(kicad_pcb
	(version 20260206)
	(generator "pcbnew")
	(generator_version "10.0")
	(general
		(thickness 1.6)
		(legacy_teardrops no)
	)
	(paper "A4")
	(layers
		(0 "F.Cu" signal "TOP")
		(4 "In1.Cu" signal "GND")
		(6 "In2.Cu" signal "IN1")
		(8 "In3.Cu" signal "GND1")
		(10 "In4.Cu" signal "IN2")
		(12 "In5.Cu" signal "GND2")
		(14 "In6.Cu" signal "IN3")
		(16 "In7.Cu" signal "GND3")
		(18 "In8.Cu" signal "VCC")
		(20 "In9.Cu" signal "VCC1")
		(22 "In10.Cu" signal "GND4")
		(24 "In11.Cu" signal "IN4")
		(26 "In12.Cu" signal "GND5")
		(28 "In13.Cu" signal "IN5")
		(30 "In14.Cu" signal "GND6")
		(32 "In15.Cu" signal "IN6")
		(34 "In16.Cu" signal "GND7")
		(2 "B.Cu" signal "BOTTOM")
		(9 "F.Adhes" user "F.Adhesive")
		(11 "B.Adhes" user "B.Adhesive")
		(13 "F.Paste" user "Package Geometry/Pastemask Top")
		(15 "B.Paste" user "Package Geometry/Pastemask Bottom")
		(5 "F.SilkS" user "Ref Des/Silkscreen Top")
		(7 "B.SilkS" user "Ref Des/Silkscreen Bottom")
		(1 "F.Mask" user "Board Geometry/Soldermask Top")
		(3 "B.Mask" user "Board Geometry/Soldermask Bottom")
		(17 "Dwgs.User" user "User.Drawings")
		(19 "Cmts.User" user "User.Comments")
		(21 "Eco1.User" user "User.Eco1")
		(23 "Eco2.User" user "User.Eco2")
		(25 "Edge.Cuts" user "Board Geometry/Outline")
		(27 "Margin" user)
		(31 "F.CrtYd" user "Package Geometry/Place Bound Top")
		(29 "B.CrtYd" user "Package Geometry/Place Bound Bottom")
		(35 "F.Fab" user "Ref Des/Assembly Top")
		(33 "B.Fab" user "Ref Des/Assembly Bottom")
	)
	(setup
		(pad_to_mask_clearance 0)
		(allow_soldermask_bridges_in_footprints no)
		(tenting
			(front yes)
			(back yes)
		)
		(covering
			(front no)
			(back no)
		)
		(plugging
			(front no)
			(back no)
		)
		(capping no)
		(filling no)
		(pcbplotparams
			(layerselection 0x00000000_00000000_55555555_5755f5ff)
			(plot_on_all_layers_selection 0x00000000_00000000_00000000_00000000)
			(disableapertmacros no)
			(usegerberextensions no)
			(usegerberattributes yes)
			(usegerberadvancedattributes yes)
			(creategerberjobfile yes)
			(dashed_line_dash_ratio 12)
			(dashed_line_gap_ratio 3)
			(svgprecision 4)
			(plotframeref no)
			(mode 1)
			(useauxorigin no)
			(pdf_front_fp_property_popups yes)
			(pdf_back_fp_property_popups yes)
			(pdf_metadata yes)
			(pdf_single_document no)
			(dxfpolygonmode yes)
			(dxfimperialunits yes)
			(dxfusepcbnewfont yes)
			(psnegative no)
			(psa4output no)
			(plot_black_and_white yes)
			(sketchpadsonfab no)
			(plotpadnumbers no)
			(hidednponfab no)
			(sketchdnponfab yes)
			(crossoutdnponfab yes)
			(subtractmaskfromsilk no)
			(outputformat 1)
			(mirror no)
			(drillshape 1)
			(scaleselection 1)
			(outputdirectory "")
		)
	)
	(segment
		(start 324.516496 -379.22073)
		(end 324.865746 -379.56998)
		(width 0.1016)
		(layer "F.Cu")
		(net "P5E_CPU0_P0_TX_C_DN<13>")
	)
	(segment
		(start 318.506856 -391.978896)
		(end 318.641222 -391.978896)
		(width 0.1016)
		(layer "F.Cu")
		(net "P5E_CPU0_P0_TX_C_DN<13>")
	)
	(segment
		(start 318.717676 -391.902442)
		(end 318.717676 -391.784586)
		(width 0.1016)
		(layer "F.Cu")
		(net "P5E_CPU0_P0_TX_C_DN<13>")
	)
	(segment
		(start 318.708278 -389.354822)
		(end 318.708278 -391.324592)
		(width 0.1016)
		(layer "F.Cu")
		(net "P5E_CPU0_P0_TX_C_DN<13>")
	)
	(arc
		(start 324.865746 -379.909578)
		(mid 324.947486 -380.321543)
		(end 325.180706 -380.670816)
		(width 0.1016)
		(layer "F.Cu")
		(net "P5E_CPU0_P0_TX_C_DN<13>")
	)
	(arc
		(start 326.53986 -382.518666)
		(mid 326.494969 -382.744257)
		(end 326.36714 -382.93548)
		(width 0.1016)
		(layer "F.Cu")
		(net "P5E_CPU0_P0_TX_C_DN<13>")
	)
	(arc
		(start 326.385428 -381.875538)
		(mid 326.499713 -382.046482)
		(end 326.53986 -382.248156)
		(width 0.1016)
		(layer "F.Cu")
		(net "P5E_CPU0_P0_TX_C_DN<13>")
	)
	(arc
		(start 325.94169 -383.36093)
		(mid 325.810951 -383.44835)
		(end 325.656702 -383.47904)
		(width 0.1016)
		(layer "F.Cu")
		(net "P5E_CPU0_P0_TX_C_DN<13>")
	)
	(arc
		(start 324.77583 -383.47904)
		(mid 324.467093 -383.540246)
		(end 324.205346 -383.715006)
		(width 0.1016)
		(layer "F.Cu")
		(net "P5E_CPU0_P0_TX_C_DN<13>")
	)
	(arc
		(start 318.808608 -389.111744)
		(mid 318.734309 -389.223313)
		(end 318.708278 -389.354822)
		(width 0.1016)
		(layer "F.Cu")
		(net "P5E_CPU0_P0_TX_C_DN<13>")
	)
	(segment
		(start 321.867276 -380.37643)
		(end 322.79844 -381.307594)
		(width 0.1016)
		(layer "F.Cu")
		(net "P5E_CPU0_P0_TX_C_DN<12>")
	)
	(segment
		(start 322.027296 -379.22073)
		(end 321.678046 -379.56998)
		(width 0.1016)
		(layer "F.Cu")
		(net "P5E_CPU0_P0_TX_C_DN<12>")
	)
	(segment
		(start 317.724282 -389.116062)
		(end 317.724282 -391.51941)
		(width 0.1016)
		(layer "F.Cu")
		(net "P5E_CPU0_P0_TX_C_DN<12>")
	)
	(segment
		(start 322.956428 -381.307594)
		(end 323.172328 -381.523494)
		(width 0.1016)
		(layer "F.Cu")
		(net "P5E_CPU0_P0_TX_C_DN<12>")
	)
	(segment
		(start 323.25183 -383.272284)
		(end 317.94831 -388.576058)
		(width 0.1016)
		(layer "F.Cu")
		(net "P5E_CPU0_P0_TX_C_DN<12>")
	)
	(segment
		(start 323.172328 -381.681482)
		(end 323.28739 -381.796544)
		(width 0.1016)
		(layer "F.Cu")
		(net "P5E_CPU0_P0_TX_C_DN<12>")
	)
	(segment
		(start 323.38772 -382.039368)
		(end 323.38772 -382.945132)
		(width 0.1016)
		(layer "F.Cu")
		(net "P5E_CPU0_P0_TX_C_DN<12>")
	)
	(segment
		(start 323.172328 -381.523494)
		(end 323.172328 -381.681482)
		(width 0.1016)
		(layer "F.Cu")
		(net "P5E_CPU0_P0_TX_C_DN<12>")
	)
	(segment
		(start 317.724282 -391.51941)
		(end 317.817754 -391.612882)
		(width 0.1016)
		(layer "F.Cu")
		(net "P5E_CPU0_P0_TX_C_DN<12>")
	)
	(segment
		(start 322.79844 -381.307594)
		(end 322.956428 -381.307594)
		(width 0.1016)
		(layer "F.Cu")
		(net "P5E_CPU0_P0_TX_C_DN<12>")
	)
	(segment
		(start 317.817754 -391.612882)
		(end 317.817754 -392.30427)
		(width 0.1016)
		(layer "F.Cu")
		(net "P5E_CPU0_P0_TX_C_DN<12>")
	)
	(segment
		(start 321.678046 -379.56998)
		(end 321.678046 -379.9205)
		(width 0.1016)
		(layer "F.Cu")
		(net "P5E_CPU0_P0_TX_C_DN<12>")
	)
	(arc
		(start 321.678046 -379.9205)
		(mid 321.727337 -380.16727)
		(end 321.867276 -380.37643)
		(width 0.1016)
		(layer "F.Cu")
		(net "P5E_CPU0_P0_TX_C_DN<12>")
	)
	(arc
		(start 323.38772 -382.945132)
		(mid 323.352292 -383.122209)
		(end 323.25183 -383.272284)
		(width 0.1016)
		(layer "F.Cu")
		(net "P5E_CPU0_P0_TX_C_DN<12>")
	)
	(arc
		(start 317.94831 -388.576058)
		(mid 317.782545 -388.82377)
		(end 317.724282 -389.116062)
		(width 0.1016)
		(layer "F.Cu")
		(net "P5E_CPU0_P0_TX_C_DN<12>")
	)
	(arc
		(start 323.28739 -381.796544)
		(mid 323.361694 -381.907982)
		(end 323.38772 -382.039368)
		(width 0.1016)
		(layer "F.Cu")
		(net "P5E_CPU0_P0_TX_C_DN<12>")
	)
	(segment
		(start 319.976246 -383.932176)
		(end 319.976246 -384.618484)
		(width 0.1016)
		(layer "F.Cu")
		(net "P5E_CPU0_P0_TX_C_DN<11>")
	)
	(segment
		(start 319.976246 -382.03378)
		(end 319.976246 -383.403856)
		(width 0.1016)
		(layer "F.Cu")
		(net "P5E_CPU0_P0_TX_C_DN<11>")
	)
	(segment
		(start 320.325496 -381.68453)
		(end 319.976246 -382.03378)
		(width 0.1016)
		(layer "F.Cu")
		(net "P5E_CPU0_P0_TX_C_DN<11>")
	)
	(segment
		(start 316.617858 -391.613136)
		(end 316.617858 -392.30427)
		(width 0.1016)
		(layer "F.Cu")
		(net "P5E_CPU0_P0_TX_C_DN<11>")
	)
	(segment
		(start 316.524132 -391.51941)
		(end 316.617858 -391.613136)
		(width 0.1016)
		(layer "F.Cu")
		(net "P5E_CPU0_P0_TX_C_DN<11>")
	)
	(segment
		(start 316.524132 -388.266178)
		(end 316.524132 -391.51941)
		(width 0.1016)
		(layer "F.Cu")
		(net "P5E_CPU0_P0_TX_C_DN<11>")
	)
	(segment
		(start 320.088006 -383.820416)
		(end 319.976246 -383.932176)
		(width 0.1016)
		(layer "F.Cu")
		(net "P5E_CPU0_P0_TX_C_DN<11>")
	)
	(segment
		(start 319.976246 -383.403856)
		(end 320.088006 -383.515616)
		(width 0.1016)
		(layer "F.Cu")
		(net "P5E_CPU0_P0_TX_C_DN<11>")
	)
	(segment
		(start 320.088006 -383.515616)
		(end 320.088006 -383.820416)
		(width 0.1016)
		(layer "F.Cu")
		(net "P5E_CPU0_P0_TX_C_DN<11>")
	)
	(segment
		(start 319.875916 -384.861562)
		(end 316.56147 -388.176008)
		(width 0.1016)
		(layer "F.Cu")
		(net "P5E_CPU0_P0_TX_C_DN<11>")
	)
	(arc
		(start 319.976246 -384.618484)
		(mid 319.950287 -384.750022)
		(end 319.875916 -384.861562)
		(width 0.1016)
		(layer "F.Cu")
		(net "P5E_CPU0_P0_TX_C_DN<11>")
	)
	(arc
		(start 316.56147 -388.176008)
		(mid 316.533827 -388.217378)
		(end 316.524132 -388.266178)
		(width 0.1016)
		(layer "F.Cu")
		(net "P5E_CPU0_P0_TX_C_DN<11>")
	)
	(segment
		(start 315.914024 -386.644388)
		(end 315.914024 -386.802122)
		(width 0.1016)
		(layer "F.Cu")
		(net "P5E_CPU0_P0_TX_C_DN<10>")
	)
	(segment
		(start 315.324236 -387.286754)
		(end 315.324236 -391.51941)
		(width 0.1016)
		(layer "F.Cu")
		(net "P5E_CPU0_P0_TX_C_DN<10>")
	)
	(segment
		(start 318.27343 -384.498596)
		(end 318.27343 -384.584702)
		(width 0.1016)
		(layer "F.Cu")
		(net "P5E_CPU0_P0_TX_C_DN<10>")
	)
	(segment
		(start 315.698378 -387.017768)
		(end 315.54039 -387.017768)
		(width 0.1016)
		(layer "F.Cu")
		(net "P5E_CPU0_P0_TX_C_DN<10>")
	)
	(segment
		(start 316.924182 -385.919472)
		(end 316.701932 -385.919472)
		(width 0.1016)
		(layer "F.Cu")
		(net "P5E_CPU0_P0_TX_C_DN<10>")
	)
	(segment
		(start 315.324236 -391.51941)
		(end 315.417708 -391.612882)
		(width 0.1016)
		(layer "F.Cu")
		(net "P5E_CPU0_P0_TX_C_DN<10>")
	)
	(segment
		(start 315.417708 -391.612882)
		(end 315.417708 -392.30427)
		(width 0.1016)
		(layer "F.Cu")
		(net "P5E_CPU0_P0_TX_C_DN<10>")
	)
	(segment
		(start 315.914024 -386.802122)
		(end 315.698378 -387.017768)
		(width 0.1016)
		(layer "F.Cu")
		(net "P5E_CPU0_P0_TX_C_DN<10>")
	)
	(segment
		(start 318.623696 -384.14833)
		(end 318.27343 -384.498596)
		(width 0.1016)
		(layer "F.Cu")
		(net "P5E_CPU0_P0_TX_C_DN<10>")
	)
	(segment
		(start 316.593728 -385.96443)
		(end 315.914024 -386.644388)
		(width 0.1016)
		(layer "F.Cu")
		(net "P5E_CPU0_P0_TX_C_DN<10>")
	)
	(segment
		(start 315.54039 -387.017768)
		(end 315.361574 -387.196584)
		(width 0.1016)
		(layer "F.Cu")
		(net "P5E_CPU0_P0_TX_C_DN<10>")
	)
	(segment
		(start 318.1731 -384.82778)
		(end 317.19139 -385.809236)
		(width 0.1016)
		(layer "F.Cu")
		(net "P5E_CPU0_P0_TX_C_DN<10>")
	)
	(arc
		(start 317.19139 -385.809236)
		(mid 317.06875 -385.890932)
		(end 316.924182 -385.919472)
		(width 0.1016)
		(layer "F.Cu")
		(net "P5E_CPU0_P0_TX_C_DN<10>")
	)
	(arc
		(start 315.361574 -387.196584)
		(mid 315.333931 -387.237954)
		(end 315.324236 -387.286754)
		(width 0.1016)
		(layer "F.Cu")
		(net "P5E_CPU0_P0_TX_C_DN<10>")
	)
	(arc
		(start 318.27343 -384.584702)
		(mid 318.247471 -384.71624)
		(end 318.1731 -384.82778)
		(width 0.1016)
		(layer "F.Cu")
		(net "P5E_CPU0_P0_TX_C_DN<10>")
	)
	(arc
		(start 316.701932 -385.919472)
		(mid 316.643348 -385.931161)
		(end 316.593728 -385.96443)
		(width 0.1016)
		(layer "F.Cu")
		(net "P5E_CPU0_P0_TX_C_DN<10>")
	)
	(segment
		(start 299.233844 -389.86206)
		(end 299.581316 -390.209532)
		(width 0.1016)
		(layer "F.Cu")
		(net "P5E_CPU0_P0_TX_C_DN<0>")
	)
	(segment
		(start 299.581316 -390.209532)
		(end 301.752508 -390.209532)
		(width 0.1016)
		(layer "F.Cu")
		(net "P5E_CPU0_P0_TX_C_DN<0>")
	)
	(segment
		(start 302.03267 -390.265158)
		(end 302.637698 -390.515094)
		(width 0.1016)
		(layer "F.Cu")
		(net "P5E_CPU0_P0_TX_C_DN<0>")
	)
	(segment
		(start 302.920146 -390.70407)
		(end 303.32426 -391.109708)
		(width 0.1016)
		(layer "F.Cu")
		(net "P5E_CPU0_P0_TX_C_DN<0>")
	)
	(segment
		(start 303.32426 -391.109708)
		(end 303.32426 -391.51941)
		(width 0.1016)
		(layer "F.Cu")
		(net "P5E_CPU0_P0_TX_C_DN<0>")
	)
	(segment
		(start 303.417732 -391.612882)
		(end 303.417732 -392.30427)
		(width 0.1016)
		(layer "F.Cu")
		(net "P5E_CPU0_P0_TX_C_DN<0>")
	)
	(segment
		(start 303.32426 -391.51941)
		(end 303.417732 -391.612882)
		(width 0.1016)
		(layer "F.Cu")
		(net "P5E_CPU0_P0_TX_C_DN<0>")
	)
	(arc
		(start 302.637698 -390.515094)
		(mid 302.78833 -390.595523)
		(end 302.920146 -390.70407)
		(width 0.1016)
		(layer "F.Cu")
		(net "P5E_CPU0_P0_TX_C_DN<0>")
	)
	(arc
		(start 301.752508 -390.209532)
		(mid 301.895327 -390.223564)
		(end 302.03267 -390.265158)
		(width 0.1016)
		(layer "F.Cu")
		(net "P5E_CPU0_P0_TX_C_DN<0>")
	)
	(segment
		(start 407.389838 -15.332456)
		(end 407.276046 -15.057882)
		(width 0.12954)
		(layer "F.Cu")
		(net "P5E_CPU0_G3_TX_C_DP<9>")
	)
	(segment
		(start 405.046942 -11.881104)
		(end 405.046942 -11.26998)
		(width 0.12954)
		(layer "F.Cu")
		(net "P5E_CPU0_G3_TX_C_DP<9>")
	)
	(segment
		(start 404.908258 -12.019788)
		(end 405.046942 -11.881104)
		(width 0.12954)
		(layer "F.Cu")
		(net "P5E_CPU0_G3_TX_C_DP<9>")
	)
	(segment
		(start 407.276046 -15.057882)
		(end 405.210772 -12.992862)
		(width 0.12954)
		(layer "F.Cu")
		(net "P5E_CPU0_G3_TX_C_DP<9>")
	)
	(segment
		(start 407.685748 -15.833598)
		(end 407.389838 -15.537688)
		(width 0.12954)
		(layer "F.Cu")
		(net "P5E_CPU0_G3_TX_C_DP<9>")
	)
	(segment
		(start 407.389838 -15.537688)
		(end 407.389838 -15.332456)
		(width 0.12954)
		(layer "F.Cu")
		(net "P5E_CPU0_G3_TX_C_DP<9>")
	)
	(segment
		(start 405.210772 -12.992862)
		(end 405.1173 -12.852908)
		(width 0.12954)
		(layer "F.Cu")
		(net "P5E_CPU0_G3_TX_C_DP<9>")
	)
	(segment
		(start 405.1173 -12.852908)
		(end 404.908258 -12.348718)
		(width 0.12954)
		(layer "F.Cu")
		(net "P5E_CPU0_G3_TX_C_DP<9>")
	)
	(segment
		(start 404.908258 -12.348718)
		(end 404.908258 -12.019788)
		(width 0.12954)
		(layer "F.Cu")
		(net "P5E_CPU0_G3_TX_C_DP<9>")
	)
	(segment
		(start 406.846786 -11.881104)
		(end 406.846786 -11.26998)
		(width 0.12954)
		(layer "F.Cu")
		(net "P5E_CPU0_G3_TX_C_DP<8>")
	)
	(segment
		(start 410.479748 -17.357598)
		(end 410.184854 -17.062704)
		(width 0.12954)
		(layer "F.Cu")
		(net "P5E_CPU0_G3_TX_C_DP<8>")
	)
	(segment
		(start 406.708102 -12.30757)
		(end 406.708102 -12.019788)
		(width 0.12954)
		(layer "F.Cu")
		(net "P5E_CPU0_G3_TX_C_DP<8>")
	)
	(segment
		(start 410.184854 -17.062704)
		(end 410.184854 -16.793972)
		(width 0.12954)
		(layer "F.Cu")
		(net "P5E_CPU0_G3_TX_C_DP<8>")
	)
	(segment
		(start 410.184854 -16.793972)
		(end 410.11348 -16.558768)
		(width 0.12954)
		(layer "F.Cu")
		(net "P5E_CPU0_G3_TX_C_DP<8>")
	)
	(segment
		(start 408.487626 -14.397228)
		(end 406.925272 -12.832842)
		(width 0.12954)
		(layer "F.Cu")
		(net "P5E_CPU0_G3_TX_C_DP<8>")
	)
	(segment
		(start 406.708102 -12.019788)
		(end 406.846786 -11.881104)
		(width 0.12954)
		(layer "F.Cu")
		(net "P5E_CPU0_G3_TX_C_DP<8>")
	)
	(segment
		(start 410.11348 -16.558768)
		(end 409.471114 -15.59687)
		(width 0.12954)
		(layer "F.Cu")
		(net "P5E_CPU0_G3_TX_C_DP<8>")
	)
	(segment
		(start 409.471114 -15.59687)
		(end 408.487626 -14.397228)
		(width 0.12954)
		(layer "F.Cu")
		(net "P5E_CPU0_G3_TX_C_DP<8>")
	)
	(segment
		(start 406.925272 -12.832842)
		(end 406.708102 -12.30757)
		(width 0.12954)
		(layer "F.Cu")
		(net "P5E_CPU0_G3_TX_C_DP<8>")
	)
	(segment
		(start 413.034226 -14.819376)
		(end 414.018222 -12.443714)
		(width 0.12954)
		(layer "F.Cu")
		(net "P5E_CPU0_G3_TX_C_DP<7>")
	)
	(segment
		(start 413.273748 -15.83182)
		(end 412.978854 -15.536926)
		(width 0.12954)
		(layer "F.Cu")
		(net "P5E_CPU0_G3_TX_C_DP<7>")
	)
	(segment
		(start 412.978854 -15.097506)
		(end 413.034226 -14.819376)
		(width 0.12954)
		(layer "F.Cu")
		(net "P5E_CPU0_G3_TX_C_DP<7>")
	)
	(segment
		(start 414.018222 -12.443714)
		(end 414.018222 -12.019788)
		(width 0.12954)
		(layer "F.Cu")
		(net "P5E_CPU0_G3_TX_C_DP<7>")
	)
	(segment
		(start 412.978854 -15.536926)
		(end 412.978854 -15.097506)
		(width 0.12954)
		(layer "F.Cu")
		(net "P5E_CPU0_G3_TX_C_DP<7>")
	)
	(segment
		(start 413.273748 -15.833598)
		(end 413.273748 -15.83182)
		(width 0.12954)
		(layer "F.Cu")
		(net "P5E_CPU0_G3_TX_C_DP<7>")
	)
	(segment
		(start 414.018222 -12.019788)
		(end 414.156906 -11.881104)
		(width 0.12954)
		(layer "F.Cu")
		(net "P5E_CPU0_G3_TX_C_DP<7>")
	)
	(segment
		(start 414.156906 -11.881104)
		(end 414.156906 -11.26998)
		(width 0.12954)
		(layer "F.Cu")
		(net "P5E_CPU0_G3_TX_C_DP<7>")
	)
	(segment
		(start 416.07867 -17.060926)
		(end 416.07867 -15.877032)
		(width 0.12954)
		(layer "F.Cu")
		(net "P5E_CPU0_G3_TX_C_DP<6>")
	)
	(segment
		(start 415.95675 -11.881104)
		(end 415.95675 -11.26998)
		(width 0.12954)
		(layer "F.Cu")
		(net "P5E_CPU0_G3_TX_C_DP<6>")
	)
	(segment
		(start 416.373564 -17.357598)
		(end 416.373564 -17.35582)
		(width 0.12954)
		(layer "F.Cu")
		(net "P5E_CPU0_G3_TX_C_DP<6>")
	)
	(segment
		(start 415.818066 -12.019788)
		(end 415.95675 -11.881104)
		(width 0.12954)
		(layer "F.Cu")
		(net "P5E_CPU0_G3_TX_C_DP<6>")
	)
	(segment
		(start 416.373564 -17.35582)
		(end 416.07867 -17.060926)
		(width 0.12954)
		(layer "F.Cu")
		(net "P5E_CPU0_G3_TX_C_DP<6>")
	)
	(segment
		(start 415.818066 -13.230352)
		(end 415.818066 -12.019788)
		(width 0.12954)
		(layer "F.Cu")
		(net "P5E_CPU0_G3_TX_C_DP<6>")
	)
	(segment
		(start 416.07867 -15.877032)
		(end 415.818066 -13.230352)
		(width 0.12954)
		(layer "F.Cu")
		(net "P5E_CPU0_G3_TX_C_DP<6>")
	)
	(segment
		(start 418.87267 -15.312644)
		(end 418.721286 -14.81328)
		(width 0.12954)
		(layer "F.Cu")
		(net "P5E_CPU0_G3_TX_C_DP<5>")
	)
	(segment
		(start 418.003482 -13.470636)
		(end 417.618164 -12.540488)
		(width 0.12954)
		(layer "F.Cu")
		(net "P5E_CPU0_G3_TX_C_DP<5>")
	)
	(segment
		(start 419.167564 -15.833598)
		(end 419.167564 -15.83182)
		(width 0.12954)
		(layer "F.Cu")
		(net "P5E_CPU0_G3_TX_C_DP<5>")
	)
	(segment
		(start 417.618164 -12.019788)
		(end 417.756848 -11.881104)
		(width 0.12954)
		(layer "F.Cu")
		(net "P5E_CPU0_G3_TX_C_DP<5>")
	)
	(segment
		(start 417.756848 -11.881104)
		(end 417.756848 -11.26998)
		(width 0.12954)
		(layer "F.Cu")
		(net "P5E_CPU0_G3_TX_C_DP<5>")
	)
	(segment
		(start 418.721286 -14.81328)
		(end 418.003482 -13.470636)
		(width 0.12954)
		(layer "F.Cu")
		(net "P5E_CPU0_G3_TX_C_DP<5>")
	)
	(segment
		(start 419.167564 -15.83182)
		(end 418.87267 -15.536926)
		(width 0.12954)
		(layer "F.Cu")
		(net "P5E_CPU0_G3_TX_C_DP<5>")
	)
	(segment
		(start 417.618164 -12.540488)
		(end 417.618164 -12.019788)
		(width 0.12954)
		(layer "F.Cu")
		(net "P5E_CPU0_G3_TX_C_DP<5>")
	)
	(segment
		(start 418.87267 -15.536926)
		(end 418.87267 -15.312644)
		(width 0.12954)
		(layer "F.Cu")
		(net "P5E_CPU0_G3_TX_C_DP<5>")
	)
	(segment
		(start 421.66667 -17.060926)
		(end 421.66667 -16.698722)
		(width 0.12954)
		(layer "F.Cu")
		(net "P5E_CPU0_G3_TX_C_DP<4>")
	)
	(segment
		(start 419.565836 -12.990576)
		(end 419.418262 -12.431014)
		(width 0.12954)
		(layer "F.Cu")
		(net "P5E_CPU0_G3_TX_C_DP<4>")
	)
	(segment
		(start 421.961564 -17.357598)
		(end 421.961564 -17.35582)
		(width 0.12954)
		(layer "F.Cu")
		(net "P5E_CPU0_G3_TX_C_DP<4>")
	)
	(segment
		(start 421.961564 -17.35582)
		(end 421.66667 -17.060926)
		(width 0.12954)
		(layer "F.Cu")
		(net "P5E_CPU0_G3_TX_C_DP<4>")
	)
	(segment
		(start 419.418262 -12.431014)
		(end 419.418262 -12.019788)
		(width 0.12954)
		(layer "F.Cu")
		(net "P5E_CPU0_G3_TX_C_DP<4>")
	)
	(segment
		(start 419.418262 -12.019788)
		(end 419.556946 -11.881104)
		(width 0.12954)
		(layer "F.Cu")
		(net "P5E_CPU0_G3_TX_C_DP<4>")
	)
	(segment
		(start 419.556946 -11.881104)
		(end 419.556946 -11.26998)
		(width 0.12954)
		(layer "F.Cu")
		(net "P5E_CPU0_G3_TX_C_DP<4>")
	)
	(segment
		(start 421.66667 -16.698722)
		(end 419.565836 -12.990576)
		(width 0.12954)
		(layer "F.Cu")
		(net "P5E_CPU0_G3_TX_C_DP<4>")
	)
	(segment
		(start 424.755564 -15.833598)
		(end 424.46067 -15.538704)
		(width 0.12954)
		(layer "F.Cu")
		(net "P5E_CPU0_G3_TX_C_DP<3>")
	)
	(segment
		(start 424.46067 -15.538704)
		(end 424.46067 -14.799056)
		(width 0.12954)
		(layer "F.Cu")
		(net "P5E_CPU0_G3_TX_C_DP<3>")
	)
	(segment
		(start 424.46067 -14.799056)
		(end 424.495976 -14.621256)
		(width 0.12954)
		(layer "F.Cu")
		(net "P5E_CPU0_G3_TX_C_DP<3>")
	)
	(segment
		(start 424.495976 -14.621256)
		(end 425.062396 -13.25372)
		(width 0.12954)
		(layer "F.Cu")
		(net "P5E_CPU0_G3_TX_C_DP<3>")
	)
	(segment
		(start 425.228258 -12.019788)
		(end 425.366942 -11.881104)
		(width 0.12954)
		(layer "F.Cu")
		(net "P5E_CPU0_G3_TX_C_DP<3>")
	)
	(segment
		(start 425.366942 -11.881104)
		(end 425.366942 -11.26998)
		(width 0.12954)
		(layer "F.Cu")
		(net "P5E_CPU0_G3_TX_C_DP<3>")
	)
	(segment
		(start 425.228258 -12.419838)
		(end 425.228258 -12.019788)
		(width 0.12954)
		(layer "F.Cu")
		(net "P5E_CPU0_G3_TX_C_DP<3>")
	)
	(segment
		(start 425.062396 -13.25372)
		(end 425.228258 -12.419838)
		(width 0.12954)
		(layer "F.Cu")
		(net "P5E_CPU0_G3_TX_C_DP<3>")
	)
	(segment
		(start 427.288706 -17.062704)
		(end 427.288706 -16.29029)
		(width 0.12954)
		(layer "F.Cu")
		(net "P5E_CPU0_G3_TX_C_DP<2>")
	)
	(segment
		(start 427.166786 -11.881104)
		(end 427.166786 -11.26998)
		(width 0.12954)
		(layer "F.Cu")
		(net "P5E_CPU0_G3_TX_C_DP<2>")
	)
	(segment
		(start 427.028102 -13.64361)
		(end 427.028102 -12.019788)
		(width 0.12954)
		(layer "F.Cu")
		(net "P5E_CPU0_G3_TX_C_DP<2>")
	)
	(segment
		(start 427.5836 -17.357598)
		(end 427.288706 -17.062704)
		(width 0.12954)
		(layer "F.Cu")
		(net "P5E_CPU0_G3_TX_C_DP<2>")
	)
	(segment
		(start 427.288706 -16.29029)
		(end 427.028102 -13.64361)
		(width 0.12954)
		(layer "F.Cu")
		(net "P5E_CPU0_G3_TX_C_DP<2>")
	)
	(segment
		(start 427.028102 -12.019788)
		(end 427.166786 -11.881104)
		(width 0.12954)
		(layer "F.Cu")
		(net "P5E_CPU0_G3_TX_C_DP<2>")
	)
	(segment
		(start 430.082706 -15.282672)
		(end 428.852584 -12.322302)
		(width 0.12954)
		(layer "F.Cu")
		(net "P5E_CPU0_G3_TX_C_DP<1>")
	)
	(segment
		(start 428.852584 -12.322302)
		(end 428.8282 -12.20089)
		(width 0.12954)
		(layer "F.Cu")
		(net "P5E_CPU0_G3_TX_C_DP<1>")
	)
	(segment
		(start 430.082706 -15.538704)
		(end 430.082706 -15.282672)
		(width 0.12954)
		(layer "F.Cu")
		(net "P5E_CPU0_G3_TX_C_DP<1>")
	)
	(segment
		(start 430.3776 -15.833598)
		(end 430.082706 -15.538704)
		(width 0.12954)
		(layer "F.Cu")
		(net "P5E_CPU0_G3_TX_C_DP<1>")
	)
	(segment
		(start 428.8282 -12.20089)
		(end 428.8282 -12.019788)
		(width 0.12954)
		(layer "F.Cu")
		(net "P5E_CPU0_G3_TX_C_DP<1>")
	)
	(segment
		(start 428.966884 -11.881104)
		(end 428.966884 -11.26998)
		(width 0.12954)
		(layer "F.Cu")
		(net "P5E_CPU0_G3_TX_C_DP<1>")
	)
	(segment
		(start 428.8282 -12.019788)
		(end 428.966884 -11.881104)
		(width 0.12954)
		(layer "F.Cu")
		(net "P5E_CPU0_G3_TX_C_DP<1>")
	)
	(segment
		(start 390.934448 -14.991334)
		(end 393.317984 -13.3985)
		(width 0.12954)
		(layer "F.Cu")
		(net "P5E_CPU0_G3_TX_C_DP<15>")
	)
	(segment
		(start 394.108178 -12.27201)
		(end 394.108178 -12.019788)
		(width 0.12954)
		(layer "F.Cu")
		(net "P5E_CPU0_G3_TX_C_DP<15>")
	)
	(segment
		(start 390.921748 -15.833598)
		(end 390.626854 -15.538704)
		(width 0.12954)
		(layer "F.Cu")
		(net "P5E_CPU0_G3_TX_C_DP<15>")
	)
	(segment
		(start 393.87018 -12.846304)
		(end 394.108178 -12.27201)
		(width 0.12954)
		(layer "F.Cu")
		(net "P5E_CPU0_G3_TX_C_DP<15>")
	)
	(segment
		(start 394.108178 -12.019788)
		(end 394.246862 -11.881104)
		(width 0.12954)
		(layer "F.Cu")
		(net "P5E_CPU0_G3_TX_C_DP<15>")
	)
	(segment
		(start 390.626854 -15.538704)
		(end 390.626854 -15.437104)
		(width 0.12954)
		(layer "F.Cu")
		(net "P5E_CPU0_G3_TX_C_DP<15>")
	)
	(segment
		(start 390.626854 -15.437104)
		(end 390.724898 -15.200884)
		(width 0.12954)
		(layer "F.Cu")
		(net "P5E_CPU0_G3_TX_C_DP<15>")
	)
	(segment
		(start 393.317984 -13.3985)
		(end 393.87018 -12.846304)
		(width 0.12954)
		(layer "F.Cu")
		(net "P5E_CPU0_G3_TX_C_DP<15>")
	)
	(segment
		(start 390.724898 -15.200884)
		(end 390.934448 -14.991334)
		(width 0.12954)
		(layer "F.Cu")
		(net "P5E_CPU0_G3_TX_C_DP<15>")
	)
	(segment
		(start 394.246862 -11.881104)
		(end 394.246862 -11.26998)
		(width 0.12954)
		(layer "F.Cu")
		(net "P5E_CPU0_G3_TX_C_DP<15>")
	)
	(segment
		(start 393.715748 -17.357598)
		(end 393.420854 -17.062704)
		(width 0.12954)
		(layer "F.Cu")
		(net "P5E_CPU0_G3_TX_C_DP<14>")
	)
	(segment
		(start 393.420854 -17.062704)
		(end 393.420854 -16.777462)
		(width 0.12954)
		(layer "F.Cu")
		(net "P5E_CPU0_G3_TX_C_DP<14>")
	)
	(segment
		(start 395.642592 -13.27531)
		(end 395.908022 -12.400534)
		(width 0.12954)
		(layer "F.Cu")
		(net "P5E_CPU0_G3_TX_C_DP<14>")
	)
	(segment
		(start 396.04696 -11.88085)
		(end 396.04696 -11.26998)
		(width 0.12954)
		(layer "F.Cu")
		(net "P5E_CPU0_G3_TX_C_DP<14>")
	)
	(segment
		(start 393.420854 -16.777462)
		(end 393.613894 -16.311118)
		(width 0.12954)
		(layer "F.Cu")
		(net "P5E_CPU0_G3_TX_C_DP<14>")
	)
	(segment
		(start 395.908022 -12.019788)
		(end 396.04696 -11.88085)
		(width 0.12954)
		(layer "F.Cu")
		(net "P5E_CPU0_G3_TX_C_DP<14>")
	)
	(segment
		(start 393.613894 -16.311118)
		(end 395.642592 -13.27531)
		(width 0.12954)
		(layer "F.Cu")
		(net "P5E_CPU0_G3_TX_C_DP<14>")
	)
	(segment
		(start 395.908022 -12.400534)
		(end 395.908022 -12.019788)
		(width 0.12954)
		(layer "F.Cu")
		(net "P5E_CPU0_G3_TX_C_DP<14>")
	)
	(segment
		(start 396.509748 -15.833598)
		(end 396.509748 -15.83182)
		(width 0.12954)
		(layer "F.Cu")
		(net "P5E_CPU0_G3_TX_C_DP<13>")
	)
	(segment
		(start 397.443452 -13.275564)
		(end 397.70812 -12.403074)
		(width 0.12954)
		(layer "F.Cu")
		(net "P5E_CPU0_G3_TX_C_DP<13>")
	)
	(segment
		(start 397.70812 -12.019788)
		(end 397.846804 -11.881104)
		(width 0.12954)
		(layer "F.Cu")
		(net "P5E_CPU0_G3_TX_C_DP<13>")
	)
	(segment
		(start 396.214854 -15.359888)
		(end 396.246858 -15.282418)
		(width 0.12954)
		(layer "F.Cu")
		(net "P5E_CPU0_G3_TX_C_DP<13>")
	)
	(segment
		(start 397.846804 -11.881104)
		(end 397.846804 -11.26998)
		(width 0.12954)
		(layer "F.Cu")
		(net "P5E_CPU0_G3_TX_C_DP<13>")
	)
	(segment
		(start 397.093694 -14.014958)
		(end 397.443452 -13.275564)
		(width 0.12954)
		(layer "F.Cu")
		(net "P5E_CPU0_G3_TX_C_DP<13>")
	)
	(segment
		(start 397.70812 -12.403074)
		(end 397.70812 -12.019788)
		(width 0.12954)
		(layer "F.Cu")
		(net "P5E_CPU0_G3_TX_C_DP<13>")
	)
	(segment
		(start 396.509748 -15.83182)
		(end 396.214854 -15.536926)
		(width 0.12954)
		(layer "F.Cu")
		(net "P5E_CPU0_G3_TX_C_DP<13>")
	)
	(segment
		(start 396.246858 -15.282418)
		(end 397.093694 -14.014958)
		(width 0.12954)
		(layer "F.Cu")
		(net "P5E_CPU0_G3_TX_C_DP<13>")
	)
	(segment
		(start 396.214854 -15.536926)
		(end 396.214854 -15.359888)
		(width 0.12954)
		(layer "F.Cu")
		(net "P5E_CPU0_G3_TX_C_DP<13>")
	)
	(segment
		(start 399.008854 -17.062704)
		(end 399.008854 -16.760698)
		(width 0.12954)
		(layer "F.Cu")
		(net "P5E_CPU0_G3_TX_C_DP<12>")
	)
	(segment
		(start 399.646902 -11.881104)
		(end 399.646902 -11.26998)
		(width 0.12954)
		(layer "F.Cu")
		(net "P5E_CPU0_G3_TX_C_DP<12>")
	)
	(segment
		(start 399.508218 -12.019788)
		(end 399.646902 -11.881104)
		(width 0.12954)
		(layer "F.Cu")
		(net "P5E_CPU0_G3_TX_C_DP<12>")
	)
	(segment
		(start 399.303748 -17.357598)
		(end 399.008854 -17.062704)
		(width 0.12954)
		(layer "F.Cu")
		(net "P5E_CPU0_G3_TX_C_DP<12>")
	)
	(segment
		(start 399.008854 -16.760698)
		(end 399.508218 -14.249654)
		(width 0.12954)
		(layer "F.Cu")
		(net "P5E_CPU0_G3_TX_C_DP<12>")
	)
	(segment
		(start 399.508218 -14.249654)
		(end 399.508218 -12.019788)
		(width 0.12954)
		(layer "F.Cu")
		(net "P5E_CPU0_G3_TX_C_DP<12>")
	)
	(segment
		(start 401.308062 -12.019788)
		(end 401.446746 -11.881104)
		(width 0.12954)
		(layer "F.Cu")
		(net "P5E_CPU0_G3_TX_C_DP<11>")
	)
	(segment
		(start 401.446746 -11.881104)
		(end 401.446746 -11.26998)
		(width 0.12954)
		(layer "F.Cu")
		(net "P5E_CPU0_G3_TX_C_DP<11>")
	)
	(segment
		(start 401.801838 -15.537688)
		(end 401.801838 -14.900402)
		(width 0.12954)
		(layer "F.Cu")
		(net "P5E_CPU0_G3_TX_C_DP<11>")
	)
	(segment
		(start 401.801838 -14.900402)
		(end 401.308062 -12.417298)
		(width 0.12954)
		(layer "F.Cu")
		(net "P5E_CPU0_G3_TX_C_DP<11>")
	)
	(segment
		(start 401.308062 -12.417298)
		(end 401.308062 -12.019788)
		(width 0.12954)
		(layer "F.Cu")
		(net "P5E_CPU0_G3_TX_C_DP<11>")
	)
	(segment
		(start 402.097748 -15.833598)
		(end 401.801838 -15.537688)
		(width 0.12954)
		(layer "F.Cu")
		(net "P5E_CPU0_G3_TX_C_DP<11>")
	)
	(segment
		(start 403.10816 -12.352528)
		(end 403.10816 -12.019788)
		(width 0.12954)
		(layer "F.Cu")
		(net "P5E_CPU0_G3_TX_C_DP<10>")
	)
	(segment
		(start 404.595838 -16.791178)
		(end 404.468838 -16.19123)
		(width 0.12954)
		(layer "F.Cu")
		(net "P5E_CPU0_G3_TX_C_DP<10>")
	)
	(segment
		(start 404.468838 -16.19123)
		(end 403.838156 -14.76629)
		(width 0.12954)
		(layer "F.Cu")
		(net "P5E_CPU0_G3_TX_C_DP<10>")
	)
	(segment
		(start 404.595838 -17.061688)
		(end 404.595838 -16.791178)
		(width 0.12954)
		(layer "F.Cu")
		(net "P5E_CPU0_G3_TX_C_DP<10>")
	)
	(segment
		(start 403.246844 -11.881104)
		(end 403.246844 -11.26998)
		(width 0.12954)
		(layer "F.Cu")
		(net "P5E_CPU0_G3_TX_C_DP<10>")
	)
	(segment
		(start 403.838156 -14.76629)
		(end 403.10816 -12.352528)
		(width 0.12954)
		(layer "F.Cu")
		(net "P5E_CPU0_G3_TX_C_DP<10>")
	)
	(segment
		(start 403.10816 -12.019788)
		(end 403.246844 -11.881104)
		(width 0.12954)
		(layer "F.Cu")
		(net "P5E_CPU0_G3_TX_C_DP<10>")
	)
	(segment
		(start 404.891748 -17.357598)
		(end 404.595838 -17.061688)
		(width 0.12954)
		(layer "F.Cu")
		(net "P5E_CPU0_G3_TX_C_DP<10>")
	)
	(segment
		(start 430.628044 -12.019788)
		(end 430.766982 -11.88085)
		(width 0.12954)
		(layer "F.Cu")
		(net "P5E_CPU0_G3_TX_C_DP<0>")
	)
	(segment
		(start 430.995328 -13.085064)
		(end 430.628044 -12.198604)
		(width 0.12954)
		(layer "F.Cu")
		(net "P5E_CPU0_G3_TX_C_DP<0>")
	)
	(segment
		(start 430.766982 -11.88085)
		(end 430.766982 -11.26998)
		(width 0.12954)
		(layer "F.Cu")
		(net "P5E_CPU0_G3_TX_C_DP<0>")
	)
	(segment
		(start 432.87569 -17.061688)
		(end 432.87569 -16.774922)
		(width 0.12954)
		(layer "F.Cu")
		(net "P5E_CPU0_G3_TX_C_DP<0>")
	)
	(segment
		(start 433.1716 -17.357598)
		(end 432.87569 -17.061688)
		(width 0.12954)
		(layer "F.Cu")
		(net "P5E_CPU0_G3_TX_C_DP<0>")
	)
	(segment
		(start 430.628044 -12.198604)
		(end 430.628044 -12.019788)
		(width 0.12954)
		(layer "F.Cu")
		(net "P5E_CPU0_G3_TX_C_DP<0>")
	)
	(segment
		(start 432.79441 -16.45031)
		(end 430.995328 -13.085064)
		(width 0.12954)
		(layer "F.Cu")
		(net "P5E_CPU0_G3_TX_C_DP<0>")
	)
	(segment
		(start 432.87569 -16.774922)
		(end 432.79441 -16.45031)
		(width 0.12954)
		(layer "F.Cu")
		(net "P5E_CPU0_G3_TX_C_DP<0>")
	)
	(segment
		(start 404.585678 -12.019788)
		(end 404.446994 -11.881104)
		(width 0.12954)
		(layer "F.Cu")
		(net "P5E_CPU0_G3_TX_C_DN<9>")
	)
	(segment
		(start 407.002488 -15.240762)
		(end 404.960074 -13.198856)
		(width 0.12954)
		(layer "F.Cu")
		(net "P5E_CPU0_G3_TX_C_DN<9>")
	)
	(segment
		(start 404.831296 -13.005816)
		(end 404.585678 -12.41298)
		(width 0.12954)
		(layer "F.Cu")
		(net "P5E_CPU0_G3_TX_C_DN<9>")
	)
	(segment
		(start 404.585678 -12.41298)
		(end 404.585678 -12.019788)
		(width 0.12954)
		(layer "F.Cu")
		(net "P5E_CPU0_G3_TX_C_DN<9>")
	)
	(segment
		(start 404.446994 -11.881104)
		(end 404.446994 -11.26998)
		(width 0.12954)
		(layer "F.Cu")
		(net "P5E_CPU0_G3_TX_C_DN<9>")
	)
	(segment
		(start 407.067258 -15.396718)
		(end 407.002488 -15.240762)
		(width 0.12954)
		(layer "F.Cu")
		(net "P5E_CPU0_G3_TX_C_DN<9>")
	)
	(segment
		(start 406.771348 -15.833598)
		(end 407.067258 -15.537688)
		(width 0.12954)
		(layer "F.Cu")
		(net "P5E_CPU0_G3_TX_C_DN<9>")
	)
	(segment
		(start 404.960074 -13.198856)
		(end 404.831296 -13.005816)
		(width 0.12954)
		(layer "F.Cu")
		(net "P5E_CPU0_G3_TX_C_DN<9>")
	)
	(segment
		(start 407.067258 -15.537688)
		(end 407.067258 -15.396718)
		(width 0.12954)
		(layer "F.Cu")
		(net "P5E_CPU0_G3_TX_C_DN<9>")
	)
	(segment
		(start 406.385522 -12.371832)
		(end 406.385522 -12.019788)
		(width 0.12954)
		(layer "F.Cu")
		(net "P5E_CPU0_G3_TX_C_DN<8>")
	)
	(segment
		(start 406.385522 -12.019788)
		(end 406.246838 -11.881104)
		(width 0.12954)
		(layer "F.Cu")
		(net "P5E_CPU0_G3_TX_C_DN<8>")
	)
	(segment
		(start 409.211526 -15.789148)
		(end 408.248104 -14.61389)
		(width 0.12954)
		(layer "F.Cu")
		(net "P5E_CPU0_G3_TX_C_DN<8>")
	)
	(segment
		(start 409.862274 -17.060672)
		(end 409.862274 -16.841978)
		(width 0.12954)
		(layer "F.Cu")
		(net "P5E_CPU0_G3_TX_C_DN<8>")
	)
	(segment
		(start 409.862274 -16.841978)
		(end 409.818586 -16.698214)
		(width 0.12954)
		(layer "F.Cu")
		(net "P5E_CPU0_G3_TX_C_DN<8>")
	)
	(segment
		(start 408.248104 -14.61389)
		(end 406.651714 -13.015468)
		(width 0.12954)
		(layer "F.Cu")
		(net "P5E_CPU0_G3_TX_C_DN<8>")
	)
	(segment
		(start 409.565348 -17.357598)
		(end 409.862274 -17.060672)
		(width 0.12954)
		(layer "F.Cu")
		(net "P5E_CPU0_G3_TX_C_DN<8>")
	)
	(segment
		(start 406.246838 -11.881104)
		(end 406.246838 -11.26998)
		(width 0.12954)
		(layer "F.Cu")
		(net "P5E_CPU0_G3_TX_C_DN<8>")
	)
	(segment
		(start 406.651714 -13.015468)
		(end 406.385522 -12.371832)
		(width 0.12954)
		(layer "F.Cu")
		(net "P5E_CPU0_G3_TX_C_DN<8>")
	)
	(segment
		(start 409.818586 -16.698214)
		(end 409.211526 -15.789148)
		(width 0.12954)
		(layer "F.Cu")
		(net "P5E_CPU0_G3_TX_C_DN<8>")
	)
	(segment
		(start 413.695642 -12.019788)
		(end 413.556958 -11.881104)
		(width 0.12954)
		(layer "F.Cu")
		(net "P5E_CPU0_G3_TX_C_DN<7>")
	)
	(segment
		(start 413.695642 -12.379452)
		(end 413.695642 -12.019788)
		(width 0.12954)
		(layer "F.Cu")
		(net "P5E_CPU0_G3_TX_C_DN<7>")
	)
	(segment
		(start 412.656274 -15.536926)
		(end 412.656274 -15.065502)
		(width 0.12954)
		(layer "F.Cu")
		(net "P5E_CPU0_G3_TX_C_DN<7>")
	)
	(segment
		(start 412.359348 -15.833598)
		(end 412.359602 -15.833598)
		(width 0.12954)
		(layer "F.Cu")
		(net "P5E_CPU0_G3_TX_C_DN<7>")
	)
	(segment
		(start 412.723838 -14.725142)
		(end 413.695642 -12.379452)
		(width 0.12954)
		(layer "F.Cu")
		(net "P5E_CPU0_G3_TX_C_DN<7>")
	)
	(segment
		(start 412.656274 -15.065502)
		(end 412.723838 -14.725142)
		(width 0.12954)
		(layer "F.Cu")
		(net "P5E_CPU0_G3_TX_C_DN<7>")
	)
	(segment
		(start 413.556958 -11.881104)
		(end 413.556958 -11.26998)
		(width 0.12954)
		(layer "F.Cu")
		(net "P5E_CPU0_G3_TX_C_DN<7>")
	)
	(segment
		(start 412.359602 -15.833598)
		(end 412.656274 -15.536926)
		(width 0.12954)
		(layer "F.Cu")
		(net "P5E_CPU0_G3_TX_C_DN<7>")
	)
	(segment
		(start 415.75609 -15.893034)
		(end 415.495486 -13.246354)
		(width 0.12954)
		(layer "F.Cu")
		(net "P5E_CPU0_G3_TX_C_DN<6>")
	)
	(segment
		(start 415.459418 -17.357598)
		(end 415.75609 -17.060926)
		(width 0.12954)
		(layer "F.Cu")
		(net "P5E_CPU0_G3_TX_C_DN<6>")
	)
	(segment
		(start 415.75609 -17.060926)
		(end 415.75609 -15.893034)
		(width 0.12954)
		(layer "F.Cu")
		(net "P5E_CPU0_G3_TX_C_DN<6>")
	)
	(segment
		(start 415.356802 -11.881104)
		(end 415.356802 -11.26998)
		(width 0.12954)
		(layer "F.Cu")
		(net "P5E_CPU0_G3_TX_C_DN<6>")
	)
	(segment
		(start 415.495486 -12.019788)
		(end 415.356802 -11.881104)
		(width 0.12954)
		(layer "F.Cu")
		(net "P5E_CPU0_G3_TX_C_DN<6>")
	)
	(segment
		(start 415.495486 -13.246354)
		(end 415.495486 -12.019788)
		(width 0.12954)
		(layer "F.Cu")
		(net "P5E_CPU0_G3_TX_C_DN<6>")
	)
	(segment
		(start 415.459164 -17.357598)
		(end 415.459418 -17.357598)
		(width 0.12954)
		(layer "F.Cu")
		(net "P5E_CPU0_G3_TX_C_DN<6>")
	)
	(segment
		(start 417.295584 -12.60475)
		(end 417.295584 -12.019788)
		(width 0.12954)
		(layer "F.Cu")
		(net "P5E_CPU0_G3_TX_C_DN<5>")
	)
	(segment
		(start 418.253164 -15.833598)
		(end 418.253418 -15.833598)
		(width 0.12954)
		(layer "F.Cu")
		(net "P5E_CPU0_G3_TX_C_DN<5>")
	)
	(segment
		(start 418.421566 -14.937486)
		(end 417.711382 -13.608812)
		(width 0.12954)
		(layer "F.Cu")
		(net "P5E_CPU0_G3_TX_C_DN<5>")
	)
	(segment
		(start 418.55009 -15.536926)
		(end 418.55009 -15.36065)
		(width 0.12954)
		(layer "F.Cu")
		(net "P5E_CPU0_G3_TX_C_DN<5>")
	)
	(segment
		(start 417.295584 -12.019788)
		(end 417.1569 -11.881104)
		(width 0.12954)
		(layer "F.Cu")
		(net "P5E_CPU0_G3_TX_C_DN<5>")
	)
	(segment
		(start 418.55009 -15.36065)
		(end 418.421566 -14.937486)
		(width 0.12954)
		(layer "F.Cu")
		(net "P5E_CPU0_G3_TX_C_DN<5>")
	)
	(segment
		(start 417.1569 -11.881104)
		(end 417.1569 -11.26998)
		(width 0.12954)
		(layer "F.Cu")
		(net "P5E_CPU0_G3_TX_C_DN<5>")
	)
	(segment
		(start 418.253418 -15.833598)
		(end 418.55009 -15.536926)
		(width 0.12954)
		(layer "F.Cu")
		(net "P5E_CPU0_G3_TX_C_DN<5>")
	)
	(segment
		(start 417.711382 -13.608812)
		(end 417.295584 -12.60475)
		(width 0.12954)
		(layer "F.Cu")
		(net "P5E_CPU0_G3_TX_C_DN<5>")
	)
	(segment
		(start 418.956998 -11.881104)
		(end 418.956998 -11.26998)
		(width 0.12954)
		(layer "F.Cu")
		(net "P5E_CPU0_G3_TX_C_DN<4>")
	)
	(segment
		(start 421.047418 -17.357598)
		(end 421.34409 -17.060926)
		(width 0.12954)
		(layer "F.Cu")
		(net "P5E_CPU0_G3_TX_C_DN<4>")
	)
	(segment
		(start 419.095682 -12.019788)
		(end 418.956998 -11.881104)
		(width 0.12954)
		(layer "F.Cu")
		(net "P5E_CPU0_G3_TX_C_DN<4>")
	)
	(segment
		(start 419.095682 -12.472924)
		(end 419.095682 -12.019788)
		(width 0.12954)
		(layer "F.Cu")
		(net "P5E_CPU0_G3_TX_C_DN<4>")
	)
	(segment
		(start 421.34409 -16.783812)
		(end 419.264338 -13.113258)
		(width 0.12954)
		(layer "F.Cu")
		(net "P5E_CPU0_G3_TX_C_DN<4>")
	)
	(segment
		(start 421.34409 -17.060926)
		(end 421.34409 -16.783812)
		(width 0.12954)
		(layer "F.Cu")
		(net "P5E_CPU0_G3_TX_C_DN<4>")
	)
	(segment
		(start 419.264338 -13.113258)
		(end 419.095682 -12.472924)
		(width 0.12954)
		(layer "F.Cu")
		(net "P5E_CPU0_G3_TX_C_DN<4>")
	)
	(segment
		(start 421.047164 -17.357598)
		(end 421.047418 -17.357598)
		(width 0.12954)
		(layer "F.Cu")
		(net "P5E_CPU0_G3_TX_C_DN<4>")
	)
	(segment
		(start 424.13809 -15.536672)
		(end 424.13809 -14.767306)
		(width 0.12954)
		(layer "F.Cu")
		(net "P5E_CPU0_G3_TX_C_DN<3>")
	)
	(segment
		(start 424.185588 -14.527022)
		(end 424.752008 -13.159486)
		(width 0.12954)
		(layer "F.Cu")
		(net "P5E_CPU0_G3_TX_C_DN<3>")
	)
	(segment
		(start 423.841164 -15.833598)
		(end 424.13809 -15.536672)
		(width 0.12954)
		(layer "F.Cu")
		(net "P5E_CPU0_G3_TX_C_DN<3>")
	)
	(segment
		(start 424.766994 -11.881104)
		(end 424.766994 -11.26998)
		(width 0.12954)
		(layer "F.Cu")
		(net "P5E_CPU0_G3_TX_C_DN<3>")
	)
	(segment
		(start 424.752008 -13.159486)
		(end 424.905678 -12.387834)
		(width 0.12954)
		(layer "F.Cu")
		(net "P5E_CPU0_G3_TX_C_DN<3>")
	)
	(segment
		(start 424.905678 -12.019788)
		(end 424.766994 -11.881104)
		(width 0.12954)
		(layer "F.Cu")
		(net "P5E_CPU0_G3_TX_C_DN<3>")
	)
	(segment
		(start 424.13809 -14.767306)
		(end 424.185588 -14.527022)
		(width 0.12954)
		(layer "F.Cu")
		(net "P5E_CPU0_G3_TX_C_DN<3>")
	)
	(segment
		(start 424.905678 -12.387834)
		(end 424.905678 -12.019788)
		(width 0.12954)
		(layer "F.Cu")
		(net "P5E_CPU0_G3_TX_C_DN<3>")
	)
	(segment
		(start 426.966126 -16.306292)
		(end 426.705522 -13.659612)
		(width 0.12954)
		(layer "F.Cu")
		(net "P5E_CPU0_G3_TX_C_DN<2>")
	)
	(segment
		(start 426.966126 -17.060672)
		(end 426.966126 -16.306292)
		(width 0.12954)
		(layer "F.Cu")
		(net "P5E_CPU0_G3_TX_C_DN<2>")
	)
	(segment
		(start 426.705522 -13.659612)
		(end 426.705522 -12.019788)
		(width 0.12954)
		(layer "F.Cu")
		(net "P5E_CPU0_G3_TX_C_DN<2>")
	)
	(segment
		(start 426.6692 -17.357598)
		(end 426.966126 -17.060672)
		(width 0.12954)
		(layer "F.Cu")
		(net "P5E_CPU0_G3_TX_C_DN<2>")
	)
	(segment
		(start 426.566838 -11.881104)
		(end 426.566838 -11.26998)
		(width 0.12954)
		(layer "F.Cu")
		(net "P5E_CPU0_G3_TX_C_DN<2>")
	)
	(segment
		(start 426.705522 -12.019788)
		(end 426.566838 -11.881104)
		(width 0.12954)
		(layer "F.Cu")
		(net "P5E_CPU0_G3_TX_C_DN<2>")
	)
	(segment
		(start 428.366936 -11.881104)
		(end 428.366936 -11.26998)
		(width 0.12954)
		(layer "F.Cu")
		(net "P5E_CPU0_G3_TX_C_DN<1>")
	)
	(segment
		(start 429.760126 -15.347188)
		(end 428.54245 -12.41679)
		(width 0.12954)
		(layer "F.Cu")
		(net "P5E_CPU0_G3_TX_C_DN<1>")
	)
	(segment
		(start 429.760126 -15.536672)
		(end 429.760126 -15.347188)
		(width 0.12954)
		(layer "F.Cu")
		(net "P5E_CPU0_G3_TX_C_DN<1>")
	)
	(segment
		(start 428.54245 -12.41679)
		(end 428.50562 -12.232894)
		(width 0.12954)
		(layer "F.Cu")
		(net "P5E_CPU0_G3_TX_C_DN<1>")
	)
	(segment
		(start 428.50562 -12.019788)
		(end 428.366936 -11.881104)
		(width 0.12954)
		(layer "F.Cu")
		(net "P5E_CPU0_G3_TX_C_DN<1>")
	)
	(segment
		(start 429.4632 -15.833598)
		(end 429.760126 -15.536672)
		(width 0.12954)
		(layer "F.Cu")
		(net "P5E_CPU0_G3_TX_C_DN<1>")
	)
	(segment
		(start 428.50562 -12.232894)
		(end 428.50562 -12.019788)
		(width 0.12954)
		(layer "F.Cu")
		(net "P5E_CPU0_G3_TX_C_DN<1>")
	)
	(segment
		(start 390.728708 -14.740636)
		(end 393.112244 -13.147802)
		(width 0.12954)
		(layer "F.Cu")
		(net "P5E_CPU0_G3_TX_C_DN<15>")
	)
	(segment
		(start 393.785598 -12.019788)
		(end 393.646914 -11.881104)
		(width 0.12954)
		(layer "F.Cu")
		(net "P5E_CPU0_G3_TX_C_DN<15>")
	)
	(segment
		(start 393.596622 -12.663424)
		(end 393.785598 -12.207748)
		(width 0.12954)
		(layer "F.Cu")
		(net "P5E_CPU0_G3_TX_C_DN<15>")
	)
	(segment
		(start 390.007348 -15.833598)
		(end 390.304274 -15.536672)
		(width 0.12954)
		(layer "F.Cu")
		(net "P5E_CPU0_G3_TX_C_DN<15>")
	)
	(segment
		(start 390.45134 -15.018004)
		(end 390.728708 -14.740636)
		(width 0.12954)
		(layer "F.Cu")
		(net "P5E_CPU0_G3_TX_C_DN<15>")
	)
	(segment
		(start 393.785598 -12.207748)
		(end 393.785598 -12.019788)
		(width 0.12954)
		(layer "F.Cu")
		(net "P5E_CPU0_G3_TX_C_DN<15>")
	)
	(segment
		(start 390.304274 -15.536672)
		(end 390.304274 -15.372842)
		(width 0.12954)
		(layer "F.Cu")
		(net "P5E_CPU0_G3_TX_C_DN<15>")
	)
	(segment
		(start 393.646914 -11.881104)
		(end 393.646914 -11.26998)
		(width 0.12954)
		(layer "F.Cu")
		(net "P5E_CPU0_G3_TX_C_DN<15>")
	)
	(segment
		(start 393.112244 -13.147802)
		(end 393.596622 -12.663424)
		(width 0.12954)
		(layer "F.Cu")
		(net "P5E_CPU0_G3_TX_C_DN<15>")
	)
	(segment
		(start 390.304274 -15.372842)
		(end 390.45134 -15.018004)
		(width 0.12954)
		(layer "F.Cu")
		(net "P5E_CPU0_G3_TX_C_DN<15>")
	)
	(segment
		(start 395.347698 -13.135864)
		(end 395.585442 -12.352528)
		(width 0.12954)
		(layer "F.Cu")
		(net "P5E_CPU0_G3_TX_C_DN<14>")
	)
	(segment
		(start 393.098274 -17.060672)
		(end 393.098274 -16.7132)
		(width 0.12954)
		(layer "F.Cu")
		(net "P5E_CPU0_G3_TX_C_DN<14>")
	)
	(segment
		(start 392.801348 -17.357598)
		(end 393.098274 -17.060672)
		(width 0.12954)
		(layer "F.Cu")
		(net "P5E_CPU0_G3_TX_C_DN<14>")
	)
	(segment
		(start 393.098274 -16.7132)
		(end 393.32789 -16.158464)
		(width 0.12954)
		(layer "F.Cu")
		(net "P5E_CPU0_G3_TX_C_DN<14>")
	)
	(segment
		(start 395.446758 -11.881104)
		(end 395.446758 -11.26998)
		(width 0.12954)
		(layer "F.Cu")
		(net "P5E_CPU0_G3_TX_C_DN<14>")
	)
	(segment
		(start 393.32789 -16.158464)
		(end 395.347698 -13.135864)
		(width 0.12954)
		(layer "F.Cu")
		(net "P5E_CPU0_G3_TX_C_DN<14>")
	)
	(segment
		(start 395.585442 -12.019788)
		(end 395.446758 -11.881104)
		(width 0.12954)
		(layer "F.Cu")
		(net "P5E_CPU0_G3_TX_C_DN<14>")
	)
	(segment
		(start 395.585442 -12.352528)
		(end 395.585442 -12.019788)
		(width 0.12954)
		(layer "F.Cu")
		(net "P5E_CPU0_G3_TX_C_DN<14>")
	)
	(segment
		(start 397.38554 -12.355068)
		(end 397.38554 -12.019788)
		(width 0.12954)
		(layer "F.Cu")
		(net "P5E_CPU0_G3_TX_C_DN<13>")
	)
	(segment
		(start 397.141446 -13.158978)
		(end 397.38554 -12.355068)
		(width 0.12954)
		(layer "F.Cu")
		(net "P5E_CPU0_G3_TX_C_DN<13>")
	)
	(segment
		(start 397.38554 -12.019788)
		(end 397.246856 -11.881104)
		(width 0.12954)
		(layer "F.Cu")
		(net "P5E_CPU0_G3_TX_C_DN<13>")
	)
	(segment
		(start 395.892274 -15.536926)
		(end 395.892274 -15.29588)
		(width 0.12954)
		(layer "F.Cu")
		(net "P5E_CPU0_G3_TX_C_DN<13>")
	)
	(segment
		(start 395.960854 -15.129764)
		(end 396.812262 -13.855446)
		(width 0.12954)
		(layer "F.Cu")
		(net "P5E_CPU0_G3_TX_C_DN<13>")
	)
	(segment
		(start 395.595602 -15.833598)
		(end 395.892274 -15.536926)
		(width 0.12954)
		(layer "F.Cu")
		(net "P5E_CPU0_G3_TX_C_DN<13>")
	)
	(segment
		(start 395.595348 -15.833598)
		(end 395.595602 -15.833598)
		(width 0.12954)
		(layer "F.Cu")
		(net "P5E_CPU0_G3_TX_C_DN<13>")
	)
	(segment
		(start 395.892274 -15.29588)
		(end 395.960854 -15.129764)
		(width 0.12954)
		(layer "F.Cu")
		(net "P5E_CPU0_G3_TX_C_DN<13>")
	)
	(segment
		(start 397.246856 -11.881104)
		(end 397.246856 -11.26998)
		(width 0.12954)
		(layer "F.Cu")
		(net "P5E_CPU0_G3_TX_C_DN<13>")
	)
	(segment
		(start 396.812262 -13.855446)
		(end 397.141446 -13.158978)
		(width 0.12954)
		(layer "F.Cu")
		(net "P5E_CPU0_G3_TX_C_DN<13>")
	)
	(segment
		(start 398.686274 -17.060926)
		(end 398.686274 -16.728694)
		(width 0.12954)
		(layer "F.Cu")
		(net "P5E_CPU0_G3_TX_C_DN<12>")
	)
	(segment
		(start 398.389348 -17.357598)
		(end 398.389602 -17.357598)
		(width 0.12954)
		(layer "F.Cu")
		(net "P5E_CPU0_G3_TX_C_DN<12>")
	)
	(segment
		(start 399.185638 -12.019788)
		(end 399.046954 -11.881104)
		(width 0.12954)
		(layer "F.Cu")
		(net "P5E_CPU0_G3_TX_C_DN<12>")
	)
	(segment
		(start 399.046954 -11.881104)
		(end 399.046954 -11.26998)
		(width 0.12954)
		(layer "F.Cu")
		(net "P5E_CPU0_G3_TX_C_DN<12>")
	)
	(segment
		(start 398.389602 -17.357598)
		(end 398.686274 -17.060926)
		(width 0.12954)
		(layer "F.Cu")
		(net "P5E_CPU0_G3_TX_C_DN<12>")
	)
	(segment
		(start 398.686274 -16.728694)
		(end 399.185638 -14.21765)
		(width 0.12954)
		(layer "F.Cu")
		(net "P5E_CPU0_G3_TX_C_DN<12>")
	)
	(segment
		(start 399.185638 -14.21765)
		(end 399.185638 -12.019788)
		(width 0.12954)
		(layer "F.Cu")
		(net "P5E_CPU0_G3_TX_C_DN<12>")
	)
	(segment
		(start 400.846798 -11.881104)
		(end 400.846798 -11.26998)
		(width 0.12954)
		(layer "F.Cu")
		(net "P5E_CPU0_G3_TX_C_DN<11>")
	)
	(segment
		(start 401.479258 -15.537688)
		(end 401.479258 -14.932406)
		(width 0.12954)
		(layer "F.Cu")
		(net "P5E_CPU0_G3_TX_C_DN<11>")
	)
	(segment
		(start 400.985482 -12.019788)
		(end 400.846798 -11.881104)
		(width 0.12954)
		(layer "F.Cu")
		(net "P5E_CPU0_G3_TX_C_DN<11>")
	)
	(segment
		(start 401.183348 -15.833598)
		(end 401.479258 -15.537688)
		(width 0.12954)
		(layer "F.Cu")
		(net "P5E_CPU0_G3_TX_C_DN<11>")
	)
	(segment
		(start 400.985482 -12.449556)
		(end 400.985482 -12.019788)
		(width 0.12954)
		(layer "F.Cu")
		(net "P5E_CPU0_G3_TX_C_DN<11>")
	)
	(segment
		(start 401.479258 -14.932406)
		(end 400.985482 -12.449556)
		(width 0.12954)
		(layer "F.Cu")
		(net "P5E_CPU0_G3_TX_C_DN<11>")
	)
	(segment
		(start 403.53488 -14.878812)
		(end 402.78558 -12.40028)
		(width 0.12954)
		(layer "F.Cu")
		(net "P5E_CPU0_G3_TX_C_DN<10>")
	)
	(segment
		(start 402.78558 -12.40028)
		(end 402.78558 -12.019788)
		(width 0.12954)
		(layer "F.Cu")
		(net "P5E_CPU0_G3_TX_C_DN<10>")
	)
	(segment
		(start 402.78558 -12.019788)
		(end 402.646896 -11.881104)
		(width 0.12954)
		(layer "F.Cu")
		(net "P5E_CPU0_G3_TX_C_DN<10>")
	)
	(segment
		(start 402.646896 -11.881104)
		(end 402.646896 -11.26998)
		(width 0.12954)
		(layer "F.Cu")
		(net "P5E_CPU0_G3_TX_C_DN<10>")
	)
	(segment
		(start 403.977348 -17.357598)
		(end 404.273258 -17.061688)
		(width 0.12954)
		(layer "F.Cu")
		(net "P5E_CPU0_G3_TX_C_DN<10>")
	)
	(segment
		(start 404.273258 -16.82496)
		(end 404.160228 -16.291052)
		(width 0.12954)
		(layer "F.Cu")
		(net "P5E_CPU0_G3_TX_C_DN<10>")
	)
	(segment
		(start 404.160228 -16.291052)
		(end 403.53488 -14.878812)
		(width 0.12954)
		(layer "F.Cu")
		(net "P5E_CPU0_G3_TX_C_DN<10>")
	)
	(segment
		(start 404.273258 -17.061688)
		(end 404.273258 -16.82496)
		(width 0.12954)
		(layer "F.Cu")
		(net "P5E_CPU0_G3_TX_C_DN<10>")
	)
	(segment
		(start 430.305464 -12.019788)
		(end 430.16678 -11.881104)
		(width 0.12954)
		(layer "F.Cu")
		(net "P5E_CPU0_G3_TX_C_DN<0>")
	)
	(segment
		(start 432.55311 -17.061688)
		(end 432.55311 -16.8148)
		(width 0.12954)
		(layer "F.Cu")
		(net "P5E_CPU0_G3_TX_C_DN<0>")
	)
	(segment
		(start 432.491134 -16.567404)
		(end 430.703228 -13.22324)
		(width 0.12954)
		(layer "F.Cu")
		(net "P5E_CPU0_G3_TX_C_DN<0>")
	)
	(segment
		(start 430.16678 -11.881104)
		(end 430.16678 -11.26998)
		(width 0.12954)
		(layer "F.Cu")
		(net "P5E_CPU0_G3_TX_C_DN<0>")
	)
	(segment
		(start 432.55311 -16.8148)
		(end 432.491134 -16.567404)
		(width 0.12954)
		(layer "F.Cu")
		(net "P5E_CPU0_G3_TX_C_DN<0>")
	)
	(segment
		(start 432.2572 -17.357598)
		(end 432.55311 -17.061688)
		(width 0.12954)
		(layer "F.Cu")
		(net "P5E_CPU0_G3_TX_C_DN<0>")
	)
	(segment
		(start 430.305464 -12.262866)
		(end 430.305464 -12.019788)
		(width 0.12954)
		(layer "F.Cu")
		(net "P5E_CPU0_G3_TX_C_DN<0>")
	)
	(segment
		(start 430.703228 -13.22324)
		(end 430.305464 -12.262866)
		(width 0.12954)
		(layer "F.Cu")
		(net "P5E_CPU0_G3_TX_C_DN<0>")
	)
	(segment
		(start 324.164452 -38.983412)
		(end 324.480936 -38.983412)
		(width 0.10668)
		(layer "F.Cu")
		(net "P3V3_PDB_AUX_ADC")
	)
	(segment
		(start 324.024244 -39.12362)
		(end 324.164452 -38.983412)
		(width 0.10668)
		(layer "F.Cu")
		(net "P3V3_PDB_AUX_ADC")
	)
	(segment
		(start 324.480936 -38.983412)
		(end 324.6247 -38.839648)
		(width 0.10668)
		(layer "F.Cu")
		(net "P3V3_PDB_AUX_ADC")
	)
	(via
		(at 273.565874 -368.680492)
		(size 0.508)
		(drill 0.254)
		(layers "F.Cu" "B.Cu")
		(net "P3V3_PDB_AUX_ADC")
	)
	(via
		(at 431.40376 -372.51386)
		(size 0.508)
		(drill 0.254)
		(layers "F.Cu" "B.Cu")
		(net "P3V3_PDB_AUX_ADC")
	)
	(via
		(at 324.6247 -38.839648)
		(size 0.508)
		(drill 0.254)
		(layers "F.Cu" "B.Cu")
		(net "P3V3_PDB_AUX_ADC")
	)
	(via
		(at 453.71004 -96.280986)
		(size 0.508)
		(drill 0.254)
		(layers "F.Cu" "B.Cu")
		(net "P3V3_PDB_AUX_ADC")
	)
	(via
		(at 448.123818 -370.86032)
		(size 0.508)
		(drill 0.254)
		(layers "F.Cu" "B.Cu")
		(net "P3V3_PDB_AUX_ADC")
	)
	(via
		(at 273.601688 -425.878244)
		(size 0.508)
		(drill 0.254)
		(layers "F.Cu" "B.Cu")
		(net "P3V3_PDB_AUX_ADC")
	)
	(segment
		(start 284.496002 -368.680492)
		(end 273.565874 -368.680492)
		(width 0.10668)
		(layer "B.Cu")
		(net "P3V3_PDB_AUX_ADC")
	)
	(segment
		(start 286.577278 -370.761768)
		(end 284.496002 -368.680492)
		(width 0.10668)
		(layer "B.Cu")
		(net "P3V3_PDB_AUX_ADC")
	)
	(segment
		(start 288.949638 -370.761768)
		(end 286.577278 -370.761768)
		(width 0.10668)
		(layer "B.Cu")
		(net "P3V3_PDB_AUX_ADC")
	)
	(segment
		(start 301.26432 -370.538248)
		(end 300.362112 -369.63604)
		(width 0.10668)
		(layer "B.Cu")
		(net "P3V3_PDB_AUX_ADC")
	)
	(segment
		(start 431.40376 -372.007892)
		(end 429.934116 -370.538248)
		(width 0.10668)
		(layer "B.Cu")
		(net "P3V3_PDB_AUX_ADC")
	)
	(segment
		(start 429.934116 -370.538248)
		(end 301.26432 -370.538248)
		(width 0.10668)
		(layer "B.Cu")
		(net "P3V3_PDB_AUX_ADC")
	)
	(segment
		(start 300.362112 -369.63604)
		(end 298.60494 -369.63604)
		(width 0.10668)
		(layer "B.Cu")
		(net "P3V3_PDB_AUX_ADC")
	)
	(segment
		(start 431.40376 -372.51386)
		(end 431.40376 -372.007892)
		(width 0.10668)
		(layer "B.Cu")
		(net "P3V3_PDB_AUX_ADC")
	)
	(segment
		(start 297.110404 -372.175786)
		(end 294.794686 -374.491504)
		(width 0.10668)
		(layer "B.Cu")
		(net "P3V3_PDB_AUX_ADC")
	)
	(segment
		(start 297.110404 -371.130576)
		(end 297.110404 -372.175786)
		(width 0.10668)
		(layer "B.Cu")
		(net "P3V3_PDB_AUX_ADC")
	)
	(segment
		(start 298.60494 -369.63604)
		(end 297.110404 -371.130576)
		(width 0.10668)
		(layer "B.Cu")
		(net "P3V3_PDB_AUX_ADC")
	)
	(segment
		(start 294.794686 -374.491504)
		(end 292.679374 -374.491504)
		(width 0.10668)
		(layer "B.Cu")
		(net "P3V3_PDB_AUX_ADC")
	)
	(segment
		(start 292.679374 -374.491504)
		(end 288.949638 -370.761768)
		(width 0.10668)
		(layer "B.Cu")
		(net "P3V3_PDB_AUX_ADC")
	)
	(segment
		(start 236.146594 -425.878244)
		(end 273.601688 -425.878244)
		(width 0.11684)
		(layer "In2.Cu")
		(net "P3V3_PDB_AUX_ADC")
	)
	(segment
		(start 402.808186 -43.18381)
		(end 399.004536 -39.38016)
		(width 0.11684)
		(layer "In2.Cu")
		(net "P3V3_PDB_AUX_ADC")
	)
	(segment
		(start 233.484166 -435.58206)
		(end 234.54233 -434.523896)
		(width 0.11684)
		(layer "In2.Cu")
		(net "P3V3_PDB_AUX_ADC")
	)
	(segment
		(start 233.37012 -435.58206)
		(end 233.484166 -435.58206)
		(width 0.11684)
		(layer "In2.Cu")
		(net "P3V3_PDB_AUX_ADC")
	)
	(segment
		(start 453.71004 -96.280986)
		(end 453.71004 -95.833946)
		(width 0.11684)
		(layer "In2.Cu")
		(net "P3V3_PDB_AUX_ADC")
	)
	(segment
		(start 234.54233 -427.482508)
		(end 236.146594 -425.878244)
		(width 0.11684)
		(layer "In2.Cu")
		(net "P3V3_PDB_AUX_ADC")
	)
	(segment
		(start 402.808186 -76.252832)
		(end 402.808186 -43.18381)
		(width 0.11684)
		(layer "In2.Cu")
		(net "P3V3_PDB_AUX_ADC")
	)
	(segment
		(start 409.754324 -83.19897)
		(end 402.808186 -76.252832)
		(width 0.11684)
		(layer "In2.Cu")
		(net "P3V3_PDB_AUX_ADC")
	)
	(segment
		(start 330.987146 -39.38016)
		(end 330.446634 -38.839648)
		(width 0.11684)
		(layer "In2.Cu")
		(net "P3V3_PDB_AUX_ADC")
	)
	(segment
		(start 453.71004 -95.833946)
		(end 441.075064 -83.19897)
		(width 0.11684)
		(layer "In2.Cu")
		(net "P3V3_PDB_AUX_ADC")
	)
	(segment
		(start 441.075064 -83.19897)
		(end 409.754324 -83.19897)
		(width 0.11684)
		(layer "In2.Cu")
		(net "P3V3_PDB_AUX_ADC")
	)
	(segment
		(start 399.004536 -39.38016)
		(end 330.987146 -39.38016)
		(width 0.11684)
		(layer "In2.Cu")
		(net "P3V3_PDB_AUX_ADC")
	)
	(segment
		(start 234.54233 -434.523896)
		(end 234.54233 -427.482508)
		(width 0.11684)
		(layer "In2.Cu")
		(net "P3V3_PDB_AUX_ADC")
	)
	(segment
		(start 330.446634 -38.839648)
		(end 324.6247 -38.839648)
		(width 0.11684)
		(layer "In2.Cu")
		(net "P3V3_PDB_AUX_ADC")
	)
	(segment
		(start 449.962524 -146.876516)
		(end 449.962524 -165.283388)
		(width 0.11684)
		(layer "In4.Cu")
		(net "P3V3_PDB_AUX_ADC")
	)
	(segment
		(start 284.483048 -410.093414)
		(end 284.397958 -410.008324)
		(width 0.11684)
		(layer "In4.Cu")
		(net "P3V3_PDB_AUX_ADC")
	)
	(segment
		(start 283.948378 -386.809996)
		(end 282.71089 -385.572508)
		(width 0.11684)
		(layer "In4.Cu")
		(net "P3V3_PDB_AUX_ADC")
	)
	(segment
		(start 445.326516 -126.501652)
		(end 442.31306 -129.515108)
		(width 0.11684)
		(layer "In4.Cu")
		(net "P3V3_PDB_AUX_ADC")
	)
	(segment
		(start 459.760066 -323.788278)
		(end 448.532758 -335.015586)
		(width 0.11684)
		(layer "In4.Cu")
		(net "P3V3_PDB_AUX_ADC")
	)
	(segment
		(start 276.286976 -422.75887)
		(end 278.603964 -422.75887)
		(width 0.11684)
		(layer "In4.Cu")
		(net "P3V3_PDB_AUX_ADC")
	)
	(segment
		(start 282.71089 -385.572508)
		(end 282.71089 -377.174252)
		(width 0.11684)
		(layer "In4.Cu")
		(net "P3V3_PDB_AUX_ADC")
	)
	(segment
		(start 284.840426 -375.044716)
		(end 284.840426 -372.557802)
		(width 0.11684)
		(layer "In4.Cu")
		(net "P3V3_PDB_AUX_ADC")
	)
	(segment
		(start 273.601688 -425.444158)
		(end 276.286976 -422.75887)
		(width 0.11684)
		(layer "In4.Cu")
		(net "P3V3_PDB_AUX_ADC")
	)
	(segment
		(start 278.603964 -422.75887)
		(end 281.146504 -420.21633)
		(width 0.11684)
		(layer "In4.Cu")
		(net "P3V3_PDB_AUX_ADC")
	)
	(segment
		(start 281.146504 -420.21633)
		(end 281.146504 -417.86048)
		(width 0.11684)
		(layer "In4.Cu")
		(net "P3V3_PDB_AUX_ADC")
	)
	(segment
		(start 442.31306 -139.227052)
		(end 449.962524 -146.876516)
		(width 0.11684)
		(layer "In4.Cu")
		(net "P3V3_PDB_AUX_ADC")
	)
	(segment
		(start 449.962524 -165.283388)
		(end 454.636124 -169.956988)
		(width 0.11684)
		(layer "In4.Cu")
		(net "P3V3_PDB_AUX_ADC")
	)
	(segment
		(start 283.948378 -389.87349)
		(end 283.948378 -386.809996)
		(width 0.11684)
		(layer "In4.Cu")
		(net "P3V3_PDB_AUX_ADC")
	)
	(segment
		(start 284.397958 -406.309576)
		(end 283.196284 -405.107902)
		(width 0.11684)
		(layer "In4.Cu")
		(net "P3V3_PDB_AUX_ADC")
	)
	(segment
		(start 453.71004 -96.280986)
		(end 445.326516 -104.66451)
		(width 0.11684)
		(layer "In4.Cu")
		(net "P3V3_PDB_AUX_ADC")
	)
	(segment
		(start 454.636124 -169.956988)
		(end 454.636124 -181.001162)
		(width 0.11684)
		(layer "In4.Cu")
		(net "P3V3_PDB_AUX_ADC")
	)
	(segment
		(start 284.325314 -396.261082)
		(end 284.325314 -396.068296)
		(width 0.11684)
		(layer "In4.Cu")
		(net "P3V3_PDB_AUX_ADC")
	)
	(segment
		(start 284.397958 -410.008324)
		(end 284.397958 -406.309576)
		(width 0.11684)
		(layer "In4.Cu")
		(net "P3V3_PDB_AUX_ADC")
	)
	(segment
		(start 448.532758 -335.015586)
		(end 448.532758 -370.45138)
		(width 0.11684)
		(layer "In4.Cu")
		(net "P3V3_PDB_AUX_ADC")
	)
	(segment
		(start 448.532758 -370.45138)
		(end 448.123818 -370.86032)
		(width 0.11684)
		(layer "In4.Cu")
		(net "P3V3_PDB_AUX_ADC")
	)
	(segment
		(start 459.760066 -186.125104)
		(end 459.760066 -323.788278)
		(width 0.11684)
		(layer "In4.Cu")
		(net "P3V3_PDB_AUX_ADC")
	)
	(segment
		(start 285.118556 -391.043668)
		(end 283.948378 -389.87349)
		(width 0.11684)
		(layer "In4.Cu")
		(net "P3V3_PDB_AUX_ADC")
	)
	(segment
		(start 284.325314 -396.068296)
		(end 285.118556 -395.275054)
		(width 0.11684)
		(layer "In4.Cu")
		(net "P3V3_PDB_AUX_ADC")
	)
	(segment
		(start 282.068778 -416.938206)
		(end 282.068778 -416.618674)
		(width 0.11684)
		(layer "In4.Cu")
		(net "P3V3_PDB_AUX_ADC")
	)
	(segment
		(start 283.478986 -371.196362)
		(end 276.081744 -371.196362)
		(width 0.11684)
		(layer "In4.Cu")
		(net "P3V3_PDB_AUX_ADC")
	)
	(segment
		(start 282.71089 -377.174252)
		(end 284.840426 -375.044716)
		(width 0.11684)
		(layer "In4.Cu")
		(net "P3V3_PDB_AUX_ADC")
	)
	(segment
		(start 284.483048 -414.204404)
		(end 284.483048 -410.093414)
		(width 0.11684)
		(layer "In4.Cu")
		(net "P3V3_PDB_AUX_ADC")
	)
	(segment
		(start 442.31306 -129.515108)
		(end 442.31306 -139.227052)
		(width 0.11684)
		(layer "In4.Cu")
		(net "P3V3_PDB_AUX_ADC")
	)
	(segment
		(start 284.840426 -372.557802)
		(end 283.478986 -371.196362)
		(width 0.11684)
		(layer "In4.Cu")
		(net "P3V3_PDB_AUX_ADC")
	)
	(segment
		(start 283.196284 -405.107902)
		(end 283.196284 -397.390112)
		(width 0.11684)
		(layer "In4.Cu")
		(net "P3V3_PDB_AUX_ADC")
	)
	(segment
		(start 282.068778 -416.618674)
		(end 284.483048 -414.204404)
		(width 0.11684)
		(layer "In4.Cu")
		(net "P3V3_PDB_AUX_ADC")
	)
	(segment
		(start 285.118556 -395.275054)
		(end 285.118556 -391.043668)
		(width 0.11684)
		(layer "In4.Cu")
		(net "P3V3_PDB_AUX_ADC")
	)
	(segment
		(start 454.636124 -181.001162)
		(end 459.760066 -186.125104)
		(width 0.11684)
		(layer "In4.Cu")
		(net "P3V3_PDB_AUX_ADC")
	)
	(segment
		(start 283.196284 -397.390112)
		(end 284.325314 -396.261082)
		(width 0.11684)
		(layer "In4.Cu")
		(net "P3V3_PDB_AUX_ADC")
	)
	(segment
		(start 276.081744 -371.196362)
		(end 273.565874 -368.680492)
		(width 0.11684)
		(layer "In4.Cu")
		(net "P3V3_PDB_AUX_ADC")
	)
	(segment
		(start 445.326516 -104.66451)
		(end 445.326516 -126.501652)
		(width 0.11684)
		(layer "In4.Cu")
		(net "P3V3_PDB_AUX_ADC")
	)
	(segment
		(start 281.146504 -417.86048)
		(end 282.068778 -416.938206)
		(width 0.11684)
		(layer "In4.Cu")
		(net "P3V3_PDB_AUX_ADC")
	)
	(segment
		(start 273.601688 -425.878244)
		(end 273.601688 -425.444158)
		(width 0.11684)
		(layer "In4.Cu")
		(net "P3V3_PDB_AUX_ADC")
	)
	(segment
		(start 431.92192 -373.03202)
		(end 433.978304 -373.03202)
		(width 0.11684)
		(layer "In11.Cu")
		(net "P3V3_PDB_AUX_ADC")
	)
	(segment
		(start 431.40376 -372.51386)
		(end 431.92192 -373.03202)
		(width 0.11684)
		(layer "In11.Cu")
		(net "P3V3_PDB_AUX_ADC")
	)
	(segment
		(start 446.523618 -369.26012)
		(end 448.123818 -370.86032)
		(width 0.11684)
		(layer "In11.Cu")
		(net "P3V3_PDB_AUX_ADC")
	)
	(segment
		(start 437.750204 -369.26012)
		(end 446.523618 -369.26012)
		(width 0.11684)
		(layer "In11.Cu")
		(net "P3V3_PDB_AUX_ADC")
	)
	(segment
		(start 433.978304 -373.03202)
		(end 437.750204 -369.26012)
		(width 0.11684)
		(layer "In11.Cu")
		(net "P3V3_PDB_AUX_ADC")
	)
	(segment
		(start 17.190974 -92.287598)
		(end 17.190974 -91.618308)
		(width 0.381)
		(layer "F.Cu")
		(net "P3V3_AUX_USB_HUB")
	)
	(segment
		(start 11.296142 -97.63633)
		(end 11.652504 -97.63633)
		(width 0.254)
		(layer "F.Cu")
		(net "P3V3_AUX_USB_HUB")
	)
	(segment
		(start 10.92708 -97.267268)
		(end 11.296142 -97.63633)
		(width 0.254)
		(layer "F.Cu")
		(net "P3V3_AUX_USB_HUB")
	)
	(segment
		(start 11.010138 -100.136452)
		(end 11.652504 -100.136452)
		(width 0.254)
		(layer "F.Cu")
		(net "P3V3_AUX_USB_HUB")
	)
	(segment
		(start 17.027144 -100.136452)
		(end 17.27708 -100.386388)
		(width 0.254)
		(layer "F.Cu")
		(net "P3V3_AUX_USB_HUB")
	)
	(segment
		(start 13.565124 -101.548946)
		(end 13.565124 -102.326948)
		(width 0.254)
		(layer "F.Cu")
		(net "P3V3_AUX_USB_HUB")
	)
	(segment
		(start 16.477488 -100.136452)
		(end 17.027144 -100.136452)
		(width 0.254)
		(layer "F.Cu")
		(net "P3V3_AUX_USB_HUB")
	)
	(segment
		(start 17.02689 -100.636578)
		(end 16.477488 -100.636578)
		(width 0.254)
		(layer "F.Cu")
		(net "P3V3_AUX_USB_HUB")
	)
	(segment
		(start 10.650982 -100.495608)
		(end 11.010138 -100.136452)
		(width 0.254)
		(layer "F.Cu")
		(net "P3V3_AUX_USB_HUB")
	)
	(segment
		(start 17.27708 -100.386388)
		(end 17.02689 -100.636578)
		(width 0.254)
		(layer "F.Cu")
		(net "P3V3_AUX_USB_HUB")
	)
	(via
		(at 10.92708 -97.267268)
		(size 0.508)
		(drill 0.254)
		(layers "F.Cu" "B.Cu")
		(net "P3V3_AUX_USB_HUB")
	)
	(via
		(at 18.161 -99.266248)
		(size 0.6604)
		(drill 0.3302)
		(layers "F.Cu" "B.Cu")
		(net "P3V3_AUX_USB_HUB")
	)
	(via
		(at 17.190974 -91.618308)
		(size 0.508)
		(drill 0.254)
		(layers "F.Cu" "B.Cu")
		(net "P3V3_AUX_USB_HUB")
	)
	(via
		(at 10.650982 -100.495608)
		(size 0.508)
		(drill 0.254)
		(layers "F.Cu" "B.Cu")
		(net "P3V3_AUX_USB_HUB")
	)
	(via
		(at 17.27708 -100.386388)
		(size 0.508)
		(drill 0.254)
		(layers "F.Cu" "B.Cu")
		(net "P3V3_AUX_USB_HUB")
	)
	(via
		(at 13.565124 -102.326948)
		(size 0.508)
		(drill 0.254)
		(layers "F.Cu" "B.Cu")
		(net "P3V3_AUX_USB_HUB")
	)
	(segment
		(start 12.37488 -94.950788)
		(end 10.92708 -96.398588)
		(width 0.381)
		(layer "B.Cu")
		(net "P3V3_AUX_USB_HUB")
	)
	(segment
		(start 17.190974 -91.618308)
		(end 17.190974 -94.554294)
		(width 0.381)
		(layer "B.Cu")
		(net "P3V3_AUX_USB_HUB")
	)
	(segment
		(start 16.79448 -94.950788)
		(end 12.37488 -94.950788)
		(width 0.381)
		(layer "B.Cu")
		(net "P3V3_AUX_USB_HUB")
	)
	(segment
		(start 17.190974 -94.554294)
		(end 16.79448 -94.950788)
		(width 0.381)
		(layer "B.Cu")
		(net "P3V3_AUX_USB_HUB")
	)
	(segment
		(start 10.92708 -96.398588)
		(end 10.92708 -97.267268)
		(width 0.381)
		(layer "B.Cu")
		(net "P3V3_AUX_USB_HUB")
	)
	(segment
		(start 108.466128 -219.184728)
		(end 98.588068 -207.034638)
		(width 0.12954)
		(layer "F.Cu")
		(net "P3E_CPU1_P5_TX_DP<1>")
	)
	(segment
		(start 98.318828 -206.906368)
		(end 98.060764 -206.906368)
		(width 0.12954)
		(layer "F.Cu")
		(net "P3E_CPU1_P5_TX_DP<1>")
	)
	(segment
		(start 109.053122 -222.070422)
		(end 109.053122 -221.78264)
		(width 0.0762)
		(layer "F.Cu")
		(net "P3E_CPU1_P5_TX_DP<1>")
	)
	(segment
		(start 109.271562 -222.410528)
		(end 109.270038 -222.409512)
		(width 0.0762)
		(layer "F.Cu")
		(net "P3E_CPU1_P5_TX_DP<1>")
	)
	(segment
		(start 109.279944 -222.415862)
		(end 109.27715 -222.41383)
		(width 0.0762)
		(layer "F.Cu")
		(net "P3E_CPU1_P5_TX_DP<1>")
	)
	(segment
		(start 109.270038 -222.409512)
		(end 109.209078 -222.374714)
		(width 0.0762)
		(layer "F.Cu")
		(net "P3E_CPU1_P5_TX_DP<1>")
	)
	(segment
		(start 109.19968 -223.392746)
		(end 109.241844 -223.367092)
		(width 0.0762)
		(layer "F.Cu")
		(net "P3E_CPU1_P5_TX_DP<1>")
	)
	(segment
		(start 109.053122 -221.78264)
		(end 109.119162 -221.7166)
		(width 0.0762)
		(layer "F.Cu")
		(net "P3E_CPU1_P5_TX_DP<1>")
	)
	(segment
		(start 109.119162 -221.69755)
		(end 109.119162 -221.022672)
		(width 0.12954)
		(layer "F.Cu")
		(net "P3E_CPU1_P5_TX_DP<1>")
	)
	(segment
		(start 109.241844 -223.367092)
		(end 109.279182 -223.345502)
		(width 0.0762)
		(layer "F.Cu")
		(net "P3E_CPU1_P5_TX_DP<1>")
	)
	(segment
		(start 98.588068 -207.034638)
		(end 98.318828 -206.906368)
		(width 0.12954)
		(layer "F.Cu")
		(net "P3E_CPU1_P5_TX_DP<1>")
	)
	(segment
		(start 109.119162 -221.022672)
		(end 108.466128 -219.184728)
		(width 0.12954)
		(layer "F.Cu")
		(net "P3E_CPU1_P5_TX_DP<1>")
	)
	(segment
		(start 109.427772 -223.690434)
		(end 109.068362 -223.690434)
		(width 0.0762)
		(layer "F.Cu")
		(net "P3E_CPU1_P5_TX_DP<1>")
	)
	(segment
		(start 109.27715 -222.41383)
		(end 109.271562 -222.410528)
		(width 0.0762)
		(layer "F.Cu")
		(net "P3E_CPU1_P5_TX_DP<1>")
	)
	(segment
		(start 109.068362 -223.690434)
		(end 109.053122 -223.675194)
		(width 0.0762)
		(layer "F.Cu")
		(net "P3E_CPU1_P5_TX_DP<1>")
	)
	(segment
		(start 98.060764 -206.906368)
		(end 97.790254 -206.635858)
		(width 0.12954)
		(layer "F.Cu")
		(net "P3E_CPU1_P5_TX_DP<1>")
	)
	(segment
		(start 109.119162 -221.7166)
		(end 109.119162 -221.69755)
		(width 0.0762)
		(layer "F.Cu")
		(net "P3E_CPU1_P5_TX_DP<1>")
	)
	(arc
		(start 109.279944 -223.344994)
		(mid 109.523271 -222.880428)
		(end 109.279944 -222.415862)
		(width 0.0762)
		(layer "F.Cu")
		(net "P3E_CPU1_P5_TX_DP<1>")
	)
	(arc
		(start 109.209078 -222.374714)
		(mid 109.094402 -222.24138)
		(end 109.053122 -222.070422)
		(width 0.0762)
		(layer "F.Cu")
		(net "P3E_CPU1_P5_TX_DP<1>")
	)
	(arc
		(start 109.279182 -223.345502)
		(mid 109.279563 -223.345248)
		(end 109.279944 -223.344994)
		(width 0.0762)
		(layer "F.Cu")
		(net "P3E_CPU1_P5_TX_DP<1>")
	)
	(arc
		(start 109.053122 -223.675194)
		(mid 109.092016 -223.516142)
		(end 109.19968 -223.392746)
		(width 0.0762)
		(layer "F.Cu")
		(net "P3E_CPU1_P5_TX_DP<1>")
	)
	(segment
		(start 39.62654 -413.17799)
		(end 42.5577 -413.17799)
		(width 0.12954)
		(layer "B.Cu")
		(net "P3E_CPU1_P5_TX_DP<1>")
	)
	(segment
		(start 42.813478 -413.433768)
		(end 43.6245 -413.433768)
		(width 0.12954)
		(layer "B.Cu")
		(net "P3E_CPU1_P5_TX_DP<1>")
	)
	(segment
		(start 42.5577 -413.17799)
		(end 42.813478 -413.433768)
		(width 0.12954)
		(layer "B.Cu")
		(net "P3E_CPU1_P5_TX_DP<1>")
	)
	(segment
		(start 39.35603 -413.4485)
		(end 39.62654 -413.17799)
		(width 0.12954)
		(layer "B.Cu")
		(net "P3E_CPU1_P5_TX_DP<1>")
	)
	(segment
		(start 43.6245 -413.433768)
		(end 43.88231 -413.691578)
		(width 0.12954)
		(layer "B.Cu")
		(net "P3E_CPU1_P5_TX_DP<1>")
	)
	(segment
		(start 39.35603 -413.4485)
		(end 39.07282 -413.16529)
		(width 0.14224)
		(layer "In6.Cu")
		(net "P3E_CPU1_P5_TX_DP<1>")
	)
	(segment
		(start 28.349194 -376.053604)
		(end 22.992842 -370.697252)
		(width 0.14224)
		(layer "In6.Cu")
		(net "P3E_CPU1_P5_TX_DP<1>")
	)
	(segment
		(start 97.502726 -206.923386)
		(end 97.790254 -206.635858)
		(width 0.14224)
		(layer "In6.Cu")
		(net "P3E_CPU1_P5_TX_DP<1>")
	)
	(segment
		(start 3.718306 -344.807032)
		(end 9.56945 -338.955888)
		(width 0.14224)
		(layer "In6.Cu")
		(net "P3E_CPU1_P5_TX_DP<1>")
	)
	(segment
		(start 22.992842 -370.697252)
		(end 18.657824 -370.697252)
		(width 0.14224)
		(layer "In6.Cu")
		(net "P3E_CPU1_P5_TX_DP<1>")
	)
	(segment
		(start 86.455758 -205.124304)
		(end 95.155512 -205.124304)
		(width 0.14224)
		(layer "In6.Cu")
		(net "P3E_CPU1_P5_TX_DP<1>")
	)
	(segment
		(start 95.155512 -205.124304)
		(end 96.954594 -206.923386)
		(width 0.14224)
		(layer "In6.Cu")
		(net "P3E_CPU1_P5_TX_DP<1>")
	)
	(segment
		(start 31.12262 -382.74625)
		(end 28.349194 -376.053604)
		(width 0.14224)
		(layer "In6.Cu")
		(net "P3E_CPU1_P5_TX_DP<1>")
	)
	(segment
		(start 58.271156 -184.923938)
		(end 68.683124 -191.880998)
		(width 0.14224)
		(layer "In6.Cu")
		(net "P3E_CPU1_P5_TX_DP<1>")
	)
	(segment
		(start 96.954594 -206.923386)
		(end 97.502726 -206.923386)
		(width 0.14224)
		(layer "In6.Cu")
		(net "P3E_CPU1_P5_TX_DP<1>")
	)
	(segment
		(start 18.657824 -370.697252)
		(end 10.773156 -362.812584)
		(width 0.14224)
		(layer "In6.Cu")
		(net "P3E_CPU1_P5_TX_DP<1>")
	)
	(segment
		(start 34.126424 -408.89047)
		(end 34.126424 -395.15415)
		(width 0.14224)
		(layer "In6.Cu")
		(net "P3E_CPU1_P5_TX_DP<1>")
	)
	(segment
		(start 39.07282 -413.16529)
		(end 38.401244 -413.16529)
		(width 0.14224)
		(layer "In6.Cu")
		(net "P3E_CPU1_P5_TX_DP<1>")
	)
	(segment
		(start 3.718306 -351.382838)
		(end 3.718306 -344.807032)
		(width 0.14224)
		(layer "In6.Cu")
		(net "P3E_CPU1_P5_TX_DP<1>")
	)
	(segment
		(start 10.773156 -362.812584)
		(end 10.773156 -358.437688)
		(width 0.14224)
		(layer "In6.Cu")
		(net "P3E_CPU1_P5_TX_DP<1>")
	)
	(segment
		(start 38.401244 -413.16529)
		(end 34.126424 -408.89047)
		(width 0.14224)
		(layer "In6.Cu")
		(net "P3E_CPU1_P5_TX_DP<1>")
	)
	(segment
		(start 9.56945 -338.955888)
		(end 9.56945 -191.459866)
		(width 0.14224)
		(layer "In6.Cu")
		(net "P3E_CPU1_P5_TX_DP<1>")
	)
	(segment
		(start 9.56945 -191.459866)
		(end 16.105378 -184.923938)
		(width 0.14224)
		(layer "In6.Cu")
		(net "P3E_CPU1_P5_TX_DP<1>")
	)
	(segment
		(start 34.126424 -395.15415)
		(end 31.12262 -392.150346)
		(width 0.14224)
		(layer "In6.Cu")
		(net "P3E_CPU1_P5_TX_DP<1>")
	)
	(segment
		(start 16.105378 -184.923938)
		(end 58.271156 -184.923938)
		(width 0.14224)
		(layer "In6.Cu")
		(net "P3E_CPU1_P5_TX_DP<1>")
	)
	(segment
		(start 68.683124 -191.880998)
		(end 78.72349 -201.921364)
		(width 0.14224)
		(layer "In6.Cu")
		(net "P3E_CPU1_P5_TX_DP<1>")
	)
	(segment
		(start 31.12262 -392.150346)
		(end 31.12262 -382.74625)
		(width 0.14224)
		(layer "In6.Cu")
		(net "P3E_CPU1_P5_TX_DP<1>")
	)
	(segment
		(start 10.773156 -358.437688)
		(end 3.718306 -351.382838)
		(width 0.14224)
		(layer "In6.Cu")
		(net "P3E_CPU1_P5_TX_DP<1>")
	)
	(segment
		(start 78.72349 -201.921364)
		(end 86.455758 -205.124304)
		(width 0.14224)
		(layer "In6.Cu")
		(net "P3E_CPU1_P5_TX_DP<1>")
	)
	(segment
		(start 104.063038 -223.198436)
		(end 104.060498 -223.197166)
		(width 0.0762)
		(layer "F.Cu")
		(net "P3E_CPU1_P5_TX_DP<0>")
	)
	(segment
		(start 106.607864 -223.690434)
		(end 106.290364 -223.690434)
		(width 0.0762)
		(layer "F.Cu")
		(net "P3E_CPU1_P5_TX_DP<0>")
	)
	(segment
		(start 104.066594 -223.200468)
		(end 104.06507 -223.199706)
		(width 0.0762)
		(layer "F.Cu")
		(net "P3E_CPU1_P5_TX_DP<0>")
	)
	(segment
		(start 95.656146 -214.542878)
		(end 95.30969 -214.399368)
		(width 0.12954)
		(layer "F.Cu")
		(net "P3E_CPU1_P5_TX_DP<0>")
	)
	(segment
		(start 103.479346 -221.303088)
		(end 103.479346 -221.151704)
		(width 0.12954)
		(layer "F.Cu")
		(net "P3E_CPU1_P5_TX_DP<0>")
	)
	(segment
		(start 104.079294 -223.207834)
		(end 104.070912 -223.203008)
		(width 0.0762)
		(layer "F.Cu")
		(net "P3E_CPU1_P5_TX_DP<0>")
	)
	(segment
		(start 103.413306 -221.388178)
		(end 103.479346 -221.322138)
		(width 0.0762)
		(layer "F.Cu")
		(net "P3E_CPU1_P5_TX_DP<0>")
	)
	(segment
		(start 103.600758 -222.393002)
		(end 103.570278 -222.375222)
		(width 0.0762)
		(layer "F.Cu")
		(net "P3E_CPU1_P5_TX_DP<0>")
	)
	(segment
		(start 103.479346 -221.322138)
		(end 103.479346 -221.303088)
		(width 0.0762)
		(layer "F.Cu")
		(net "P3E_CPU1_P5_TX_DP<0>")
	)
	(segment
		(start 95.30969 -214.399368)
		(end 94.75851 -214.399368)
		(width 0.12954)
		(layer "F.Cu")
		(net "P3E_CPU1_P5_TX_DP<0>")
	)
	(segment
		(start 103.639874 -222.415862)
		(end 103.600758 -222.393002)
		(width 0.0762)
		(layer "F.Cu")
		(net "P3E_CPU1_P5_TX_DP<0>")
	)
	(segment
		(start 104.060498 -223.197166)
		(end 104.039162 -223.18472)
		(width 0.0762)
		(layer "F.Cu")
		(net "P3E_CPU1_P5_TX_DP<0>")
	)
	(segment
		(start 104.067356 -223.200976)
		(end 104.066594 -223.200468)
		(width 0.0762)
		(layer "F.Cu")
		(net "P3E_CPU1_P5_TX_DP<0>")
	)
	(segment
		(start 104.064308 -223.199198)
		(end 104.063038 -223.198436)
		(width 0.0762)
		(layer "F.Cu")
		(net "P3E_CPU1_P5_TX_DP<0>")
	)
	(segment
		(start 104.07015 -223.2025)
		(end 104.067356 -223.200976)
		(width 0.0762)
		(layer "F.Cu")
		(net "P3E_CPU1_P5_TX_DP<0>")
	)
	(segment
		(start 94.75851 -214.399368)
		(end 94.488 -214.128858)
		(width 0.12954)
		(layer "F.Cu")
		(net "P3E_CPU1_P5_TX_DP<0>")
	)
	(segment
		(start 103.479346 -221.151704)
		(end 103.334058 -220.844872)
		(width 0.12954)
		(layer "F.Cu")
		(net "P3E_CPU1_P5_TX_DP<0>")
	)
	(segment
		(start 104.070912 -223.203008)
		(end 104.07015 -223.2025)
		(width 0.0762)
		(layer "F.Cu")
		(net "P3E_CPU1_P5_TX_DP<0>")
	)
	(segment
		(start 103.413306 -222.070422)
		(end 103.413306 -221.388178)
		(width 0.0762)
		(layer "F.Cu")
		(net "P3E_CPU1_P5_TX_DP<0>")
	)
	(segment
		(start 106.290364 -223.690434)
		(end 106.230166 -223.630236)
		(width 0.0762)
		(layer "F.Cu")
		(net "P3E_CPU1_P5_TX_DP<0>")
	)
	(segment
		(start 105.989882 -223.225868)
		(end 105.950766 -223.203008)
		(width 0.0762)
		(layer "F.Cu")
		(net "P3E_CPU1_P5_TX_DP<0>")
	)
	(segment
		(start 103.334058 -220.844872)
		(end 95.656146 -214.543132)
		(width 0.12954)
		(layer "F.Cu")
		(net "P3E_CPU1_P5_TX_DP<0>")
	)
	(segment
		(start 95.656146 -214.543132)
		(end 95.656146 -214.542878)
		(width 0.12954)
		(layer "F.Cu")
		(net "P3E_CPU1_P5_TX_DP<0>")
	)
	(segment
		(start 104.06507 -223.199706)
		(end 104.064308 -223.199198)
		(width 0.0762)
		(layer "F.Cu")
		(net "P3E_CPU1_P5_TX_DP<0>")
	)
	(arc
		(start 106.230166 -223.630236)
		(mid 106.154071 -223.40188)
		(end 105.989882 -223.225868)
		(width 0.0762)
		(layer "F.Cu")
		(net "P3E_CPU1_P5_TX_DP<0>")
	)
	(arc
		(start 104.445054 -223.203008)
		(mid 104.262803 -223.253358)
		(end 104.079294 -223.207834)
		(width 0.0762)
		(layer "F.Cu")
		(net "P3E_CPU1_P5_TX_DP<0>")
	)
	(arc
		(start 104.039162 -223.18472)
		(mid 103.924486 -223.051386)
		(end 103.883206 -222.880428)
		(width 0.0762)
		(layer "F.Cu")
		(net "P3E_CPU1_P5_TX_DP<0>")
	)
	(arc
		(start 103.570278 -222.375222)
		(mid 103.454851 -222.241846)
		(end 103.413306 -222.070422)
		(width 0.0762)
		(layer "F.Cu")
		(net "P3E_CPU1_P5_TX_DP<0>")
	)
	(arc
		(start 103.883206 -222.880428)
		(mid 103.818691 -222.618209)
		(end 103.639874 -222.415862)
		(width 0.0762)
		(layer "F.Cu")
		(net "P3E_CPU1_P5_TX_DP<0>")
	)
	(arc
		(start 105.010966 -223.203008)
		(mid 104.72801 -223.126831)
		(end 104.445054 -223.203008)
		(width 0.0762)
		(layer "F.Cu")
		(net "P3E_CPU1_P5_TX_DP<0>")
	)
	(arc
		(start 105.950766 -223.203008)
		(mid 105.66781 -223.126831)
		(end 105.384854 -223.203008)
		(width 0.0762)
		(layer "F.Cu")
		(net "P3E_CPU1_P5_TX_DP<0>")
	)
	(arc
		(start 105.384854 -223.203008)
		(mid 105.19791 -223.253263)
		(end 105.010966 -223.203008)
		(width 0.0762)
		(layer "F.Cu")
		(net "P3E_CPU1_P5_TX_DP<0>")
	)
	(segment
		(start 50.935382 -416.348926)
		(end 51.210464 -416.348926)
		(width 0.12954)
		(layer "B.Cu")
		(net "P3E_CPU1_P5_TX_DP<0>")
	)
	(segment
		(start 44.538646 -415.472626)
		(end 50.409602 -415.472626)
		(width 0.12954)
		(layer "B.Cu")
		(net "P3E_CPU1_P5_TX_DP<0>")
	)
	(segment
		(start 50.804064 -415.867088)
		(end 50.804064 -416.217608)
		(width 0.12954)
		(layer "B.Cu")
		(net "P3E_CPU1_P5_TX_DP<0>")
	)
	(segment
		(start 41.8592 -414.790636)
		(end 42.891964 -414.790636)
		(width 0.12954)
		(layer "B.Cu")
		(net "P3E_CPU1_P5_TX_DP<0>")
	)
	(segment
		(start 42.891964 -414.790636)
		(end 44.538646 -415.472626)
		(width 0.12954)
		(layer "B.Cu")
		(net "P3E_CPU1_P5_TX_DP<0>")
	)
	(segment
		(start 50.804064 -416.217608)
		(end 50.935382 -416.348926)
		(width 0.12954)
		(layer "B.Cu")
		(net "P3E_CPU1_P5_TX_DP<0>")
	)
	(segment
		(start 51.210464 -416.348926)
		(end 51.468274 -416.091116)
		(width 0.12954)
		(layer "B.Cu")
		(net "P3E_CPU1_P5_TX_DP<0>")
	)
	(segment
		(start 50.409602 -415.472626)
		(end 50.804064 -415.867088)
		(width 0.12954)
		(layer "B.Cu")
		(net "P3E_CPU1_P5_TX_DP<0>")
	)
	(segment
		(start 41.58869 -414.520126)
		(end 41.8592 -414.790636)
		(width 0.12954)
		(layer "B.Cu")
		(net "P3E_CPU1_P5_TX_DP<0>")
	)
	(segment
		(start 40.694102 -414.804098)
		(end 40.453056 -414.563052)
		(width 0.14224)
		(layer "In6.Cu")
		(net "P3E_CPU1_P5_TX_DP<0>")
	)
	(segment
		(start 94.787466 -214.428324)
		(end 94.488 -214.128858)
		(width 0.14224)
		(layer "In6.Cu")
		(net "P3E_CPU1_P5_TX_DP<0>")
	)
	(segment
		(start 23.23338 -368.626644)
		(end 18.505932 -368.626644)
		(width 0.14224)
		(layer "In6.Cu")
		(net "P3E_CPU1_P5_TX_DP<0>")
	)
	(segment
		(start 11.6205 -192.506854)
		(end 11.6205 -192.312798)
		(width 0.14224)
		(layer "In6.Cu")
		(net "P3E_CPU1_P5_TX_DP<0>")
	)
	(segment
		(start 12.41806 -191.515238)
		(end 12.719558 -191.21374)
		(width 0.14224)
		(layer "In6.Cu")
		(net "P3E_CPU1_P5_TX_DP<0>")
	)
	(segment
		(start 56.124348 -188.442346)
		(end 56.261508 -188.305186)
		(width 0.14224)
		(layer "In6.Cu")
		(net "P3E_CPU1_P5_TX_DP<0>")
	)
	(segment
		(start 37.35324 -407.54427)
		(end 37.162994 -407.50617)
		(width 0.14224)
		(layer "In6.Cu")
		(net "P3E_CPU1_P5_TX_DP<0>")
	)
	(segment
		(start 36.505134 -406.51811)
		(end 36.505134 -402.17725)
		(width 0.14224)
		(layer "In6.Cu")
		(net "P3E_CPU1_P5_TX_DP<0>")
	)
	(segment
		(start 95.339154 -213.085426)
		(end 95.339154 -213.512146)
		(width 0.14224)
		(layer "In6.Cu")
		(net "P3E_CPU1_P5_TX_DP<0>")
	)
	(segment
		(start 58.517028 -188.305186)
		(end 59.878214 -188.305186)
		(width 0.14224)
		(layer "In6.Cu")
		(net "P3E_CPU1_P5_TX_DP<0>")
	)
	(segment
		(start 95.476314 -207.691482)
		(end 95.476314 -209.989166)
		(width 0.14224)
		(layer "In6.Cu")
		(net "P3E_CPU1_P5_TX_DP<0>")
	)
	(segment
		(start 39.806626 -411.475682)
		(end 39.844726 -411.285436)
		(width 0.14224)
		(layer "In6.Cu")
		(net "P3E_CPU1_P5_TX_DP<0>")
	)
	(segment
		(start 36.705286 -401.170394)
		(end 36.86683 -401.062444)
		(width 0.14224)
		(layer "In6.Cu")
		(net "P3E_CPU1_P5_TX_DP<0>")
	)
	(segment
		(start 57.252108 -188.442346)
		(end 57.389268 -188.305186)
		(width 0.14224)
		(layer "In6.Cu")
		(net "P3E_CPU1_P5_TX_DP<0>")
	)
	(segment
		(start 41.304718 -414.804098)
		(end 40.694102 -414.804098)
		(width 0.14224)
		(layer "In6.Cu")
		(net "P3E_CPU1_P5_TX_DP<0>")
	)
	(segment
		(start 57.815988 -188.305186)
		(end 57.953148 -188.442346)
		(width 0.14224)
		(layer "In6.Cu")
		(net "P3E_CPU1_P5_TX_DP<0>")
	)
	(segment
		(start 38.668706 -388.183374)
		(end 32.316674 -381.831342)
		(width 0.14224)
		(layer "In6.Cu")
		(net "P3E_CPU1_P5_TX_DP<0>")
	)
	(segment
		(start 95.124016 -214.428324)
		(end 94.787466 -214.428324)
		(width 0.14224)
		(layer "In6.Cu")
		(net "P3E_CPU1_P5_TX_DP<0>")
	)
	(segment
		(start 41.58869 -414.520126)
		(end 41.304718 -414.804098)
		(width 0.14224)
		(layer "In6.Cu")
		(net "P3E_CPU1_P5_TX_DP<0>")
	)
	(segment
		(start 37.148262 -399.64741)
		(end 37.231574 -399.228564)
		(width 0.14224)
		(layer "In6.Cu")
		(net "P3E_CPU1_P5_TX_DP<0>")
	)
	(segment
		(start 55.560468 -188.305186)
		(end 55.697628 -188.442346)
		(width 0.14224)
		(layer "In6.Cu")
		(net "P3E_CPU1_P5_TX_DP<0>")
	)
	(segment
		(start 40.453056 -412.44647)
		(end 39.806626 -411.475682)
		(width 0.14224)
		(layer "In6.Cu")
		(net "P3E_CPU1_P5_TX_DP<0>")
	)
	(segment
		(start 36.986718 -399.755106)
		(end 37.148262 -399.64741)
		(width 0.14224)
		(layer "In6.Cu")
		(net "P3E_CPU1_P5_TX_DP<0>")
	)
	(segment
		(start 56.261508 -188.305186)
		(end 56.688228 -188.305186)
		(width 0.14224)
		(layer "In6.Cu")
		(net "P3E_CPU1_P5_TX_DP<0>")
	)
	(segment
		(start 87.830406 -207.248506)
		(end 93.009974 -207.248506)
		(width 0.14224)
		(layer "In6.Cu")
		(net "P3E_CPU1_P5_TX_DP<0>")
	)
	(segment
		(start 12.41806 -191.709294)
		(end 12.41806 -191.515238)
		(width 0.14224)
		(layer "In6.Cu")
		(net "P3E_CPU1_P5_TX_DP<0>")
	)
	(segment
		(start 57.953148 -188.442346)
		(end 58.379868 -188.442346)
		(width 0.14224)
		(layer "In6.Cu")
		(net "P3E_CPU1_P5_TX_DP<0>")
	)
	(segment
		(start 54.999128 -188.439806)
		(end 55.133748 -188.305186)
		(width 0.14224)
		(layer "In6.Cu")
		(net "P3E_CPU1_P5_TX_DP<0>")
	)
	(segment
		(start 37.551868 -408.089862)
		(end 37.589968 -407.899616)
		(width 0.14224)
		(layer "In6.Cu")
		(net "P3E_CPU1_P5_TX_DP<0>")
	)
	(segment
		(start 95.339154 -210.126326)
		(end 95.339154 -210.553046)
		(width 0.14224)
		(layer "In6.Cu")
		(net "P3E_CPU1_P5_TX_DP<0>")
	)
	(segment
		(start 14.01318 -189.920118)
		(end 15.628112 -188.305186)
		(width 0.14224)
		(layer "In6.Cu")
		(net "P3E_CPU1_P5_TX_DP<0>")
	)
	(segment
		(start 38.851078 -409.79344)
		(end 38.660832 -409.75534)
		(width 0.14224)
		(layer "In6.Cu")
		(net "P3E_CPU1_P5_TX_DP<0>")
	)
	(segment
		(start 37.123878 -399.067274)
		(end 38.668706 -391.29843)
		(width 0.14224)
		(layer "In6.Cu")
		(net "P3E_CPU1_P5_TX_DP<0>")
	)
	(segment
		(start 70.089776 -195.128388)
		(end 78.235556 -203.274168)
		(width 0.14224)
		(layer "In6.Cu")
		(net "P3E_CPU1_P5_TX_DP<0>")
	)
	(segment
		(start 37.162994 -407.505916)
		(end 36.505134 -406.51811)
		(width 0.14224)
		(layer "In6.Cu")
		(net "P3E_CPU1_P5_TX_DP<0>")
	)
	(segment
		(start 93.009974 -207.248506)
		(end 93.358208 -206.900272)
		(width 0.14224)
		(layer "In6.Cu")
		(net "P3E_CPU1_P5_TX_DP<0>")
	)
	(segment
		(start 36.950142 -400.643852)
		(end 36.842192 -400.482562)
		(width 0.14224)
		(layer "In6.Cu")
		(net "P3E_CPU1_P5_TX_DP<0>")
	)
	(segment
		(start 95.339154 -210.553046)
		(end 95.476314 -210.690206)
		(width 0.14224)
		(layer "In6.Cu")
		(net "P3E_CPU1_P5_TX_DP<0>")
	)
	(segment
		(start 56.825388 -188.442346)
		(end 57.252108 -188.442346)
		(width 0.14224)
		(layer "In6.Cu")
		(net "P3E_CPU1_P5_TX_DP<0>")
	)
	(segment
		(start 39.049706 -410.339032)
		(end 39.087806 -410.148786)
		(width 0.14224)
		(layer "In6.Cu")
		(net "P3E_CPU1_P5_TX_DP<0>")
	)
	(segment
		(start 14.01318 -190.114174)
		(end 14.01318 -189.920118)
		(width 0.14224)
		(layer "In6.Cu")
		(net "P3E_CPU1_P5_TX_DP<0>")
	)
	(segment
		(start 13.711174 -190.41618)
		(end 14.01318 -190.114174)
		(width 0.14224)
		(layer "In6.Cu")
		(net "P3E_CPU1_P5_TX_DP<0>")
	)
	(segment
		(start 12.719558 -191.21374)
		(end 12.913614 -191.21374)
		(width 0.14224)
		(layer "In6.Cu")
		(net "P3E_CPU1_P5_TX_DP<0>")
	)
	(segment
		(start 40.453056 -414.563052)
		(end 40.453056 -412.44647)
		(width 0.14224)
		(layer "In6.Cu")
		(net "P3E_CPU1_P5_TX_DP<0>")
	)
	(segment
		(start 58.379868 -188.442346)
		(end 58.517028 -188.305186)
		(width 0.14224)
		(layer "In6.Cu")
		(net "P3E_CPU1_P5_TX_DP<0>")
	)
	(segment
		(start 55.133748 -188.305186)
		(end 55.560468 -188.305186)
		(width 0.14224)
		(layer "In6.Cu")
		(net "P3E_CPU1_P5_TX_DP<0>")
	)
	(segment
		(start 95.476314 -212.948266)
		(end 95.339154 -213.085426)
		(width 0.14224)
		(layer "In6.Cu")
		(net "P3E_CPU1_P5_TX_DP<0>")
	)
	(segment
		(start 39.417752 -410.891736)
		(end 39.049706 -410.339032)
		(width 0.14224)
		(layer "In6.Cu")
		(net "P3E_CPU1_P5_TX_DP<0>")
	)
	(segment
		(start 36.505134 -402.17725)
		(end 36.705286 -401.170394)
		(width 0.14224)
		(layer "In6.Cu")
		(net "P3E_CPU1_P5_TX_DP<0>")
	)
	(segment
		(start 36.842192 -400.482562)
		(end 36.986718 -399.755106)
		(width 0.14224)
		(layer "In6.Cu")
		(net "P3E_CPU1_P5_TX_DP<0>")
	)
	(segment
		(start 15.628112 -188.305186)
		(end 54.437788 -188.305186)
		(width 0.14224)
		(layer "In6.Cu")
		(net "P3E_CPU1_P5_TX_DP<0>")
	)
	(segment
		(start 12.043918 -357.91775)
		(end 4.971796 -350.845628)
		(width 0.14224)
		(layer "In6.Cu")
		(net "P3E_CPU1_P5_TX_DP<0>")
	)
	(segment
		(start 78.235556 -203.274168)
		(end 87.830406 -207.248506)
		(width 0.14224)
		(layer "In6.Cu")
		(net "P3E_CPU1_P5_TX_DP<0>")
	)
	(segment
		(start 54.437788 -188.305186)
		(end 54.572408 -188.439806)
		(width 0.14224)
		(layer "In6.Cu")
		(net "P3E_CPU1_P5_TX_DP<0>")
	)
	(segment
		(start 37.589968 -407.899616)
		(end 37.35324 -407.54427)
		(width 0.14224)
		(layer "In6.Cu")
		(net "P3E_CPU1_P5_TX_DP<0>")
	)
	(segment
		(start 36.86683 -401.062444)
		(end 36.950142 -400.643852)
		(width 0.14224)
		(layer "In6.Cu")
		(net "P3E_CPU1_P5_TX_DP<0>")
	)
	(segment
		(start 13.517118 -190.41618)
		(end 13.711174 -190.41618)
		(width 0.14224)
		(layer "In6.Cu")
		(net "P3E_CPU1_P5_TX_DP<0>")
	)
	(segment
		(start 95.339154 -213.512146)
		(end 95.476314 -213.649306)
		(width 0.14224)
		(layer "In6.Cu")
		(net "P3E_CPU1_P5_TX_DP<0>")
	)
	(segment
		(start 11.124438 -192.80886)
		(end 11.318494 -192.80886)
		(width 0.14224)
		(layer "In6.Cu")
		(net "P3E_CPU1_P5_TX_DP<0>")
	)
	(segment
		(start 39.607998 -410.93009)
		(end 39.417752 -410.891736)
		(width 0.14224)
		(layer "In6.Cu")
		(net "P3E_CPU1_P5_TX_DP<0>")
	)
	(segment
		(start 37.978334 -408.483054)
		(end 37.788342 -408.444954)
		(width 0.14224)
		(layer "In6.Cu")
		(net "P3E_CPU1_P5_TX_DP<0>")
	)
	(segment
		(start 95.476314 -213.649306)
		(end 95.476314 -214.076026)
		(width 0.14224)
		(layer "In6.Cu")
		(net "P3E_CPU1_P5_TX_DP<0>")
	)
	(segment
		(start 37.788342 -408.444954)
		(end 37.551868 -408.089862)
		(width 0.14224)
		(layer "In6.Cu")
		(net "P3E_CPU1_P5_TX_DP<0>")
	)
	(segment
		(start 59.878214 -188.305186)
		(end 70.089776 -195.128388)
		(width 0.14224)
		(layer "In6.Cu")
		(net "P3E_CPU1_P5_TX_DP<0>")
	)
	(segment
		(start 10.82294 -339.475318)
		(end 10.82294 -193.110358)
		(width 0.14224)
		(layer "In6.Cu")
		(net "P3E_CPU1_P5_TX_DP<0>")
	)
	(segment
		(start 10.82294 -193.110358)
		(end 11.124438 -192.80886)
		(width 0.14224)
		(layer "In6.Cu")
		(net "P3E_CPU1_P5_TX_DP<0>")
	)
	(segment
		(start 11.6205 -192.312798)
		(end 11.921998 -192.0113)
		(width 0.14224)
		(layer "In6.Cu")
		(net "P3E_CPU1_P5_TX_DP<0>")
	)
	(segment
		(start 94.685104 -206.900272)
		(end 95.476314 -207.691482)
		(width 0.14224)
		(layer "In6.Cu")
		(net "P3E_CPU1_P5_TX_DP<0>")
	)
	(segment
		(start 11.921998 -192.0113)
		(end 12.116054 -192.0113)
		(width 0.14224)
		(layer "In6.Cu")
		(net "P3E_CPU1_P5_TX_DP<0>")
	)
	(segment
		(start 38.660832 -409.75534)
		(end 38.176962 -409.028646)
		(width 0.14224)
		(layer "In6.Cu")
		(net "P3E_CPU1_P5_TX_DP<0>")
	)
	(segment
		(start 4.971796 -350.845628)
		(end 4.971796 -345.326462)
		(width 0.14224)
		(layer "In6.Cu")
		(net "P3E_CPU1_P5_TX_DP<0>")
	)
	(segment
		(start 38.215316 -408.8384)
		(end 37.978334 -408.483054)
		(width 0.14224)
		(layer "In6.Cu")
		(net "P3E_CPU1_P5_TX_DP<0>")
	)
	(segment
		(start 57.389268 -188.305186)
		(end 57.815988 -188.305186)
		(width 0.14224)
		(layer "In6.Cu")
		(net "P3E_CPU1_P5_TX_DP<0>")
	)
	(segment
		(start 95.476314 -209.989166)
		(end 95.339154 -210.126326)
		(width 0.14224)
		(layer "In6.Cu")
		(net "P3E_CPU1_P5_TX_DP<0>")
	)
	(segment
		(start 37.231574 -399.228564)
		(end 37.123878 -399.067274)
		(width 0.14224)
		(layer "In6.Cu")
		(net "P3E_CPU1_P5_TX_DP<0>")
	)
	(segment
		(start 32.316674 -381.831342)
		(end 29.401008 -374.794272)
		(width 0.14224)
		(layer "In6.Cu")
		(net "P3E_CPU1_P5_TX_DP<0>")
	)
	(segment
		(start 95.476314 -210.690206)
		(end 95.476314 -212.948266)
		(width 0.14224)
		(layer "In6.Cu")
		(net "P3E_CPU1_P5_TX_DP<0>")
	)
	(segment
		(start 39.844726 -411.285436)
		(end 39.607998 -410.93009)
		(width 0.14224)
		(layer "In6.Cu")
		(net "P3E_CPU1_P5_TX_DP<0>")
	)
	(segment
		(start 11.318494 -192.80886)
		(end 11.6205 -192.506854)
		(width 0.14224)
		(layer "In6.Cu")
		(net "P3E_CPU1_P5_TX_DP<0>")
	)
	(segment
		(start 38.668706 -391.29843)
		(end 38.668706 -388.183374)
		(width 0.14224)
		(layer "In6.Cu")
		(net "P3E_CPU1_P5_TX_DP<0>")
	)
	(segment
		(start 38.176962 -409.028646)
		(end 38.215316 -408.8384)
		(width 0.14224)
		(layer "In6.Cu")
		(net "P3E_CPU1_P5_TX_DP<0>")
	)
	(segment
		(start 18.505932 -368.626644)
		(end 12.043918 -362.16463)
		(width 0.14224)
		(layer "In6.Cu")
		(net "P3E_CPU1_P5_TX_DP<0>")
	)
	(segment
		(start 55.697628 -188.442346)
		(end 56.124348 -188.442346)
		(width 0.14224)
		(layer "In6.Cu")
		(net "P3E_CPU1_P5_TX_DP<0>")
	)
	(segment
		(start 29.401008 -374.794272)
		(end 23.23338 -368.626644)
		(width 0.14224)
		(layer "In6.Cu")
		(net "P3E_CPU1_P5_TX_DP<0>")
	)
	(segment
		(start 93.358208 -206.900272)
		(end 94.685104 -206.900272)
		(width 0.14224)
		(layer "In6.Cu")
		(net "P3E_CPU1_P5_TX_DP<0>")
	)
	(segment
		(start 95.476314 -214.076026)
		(end 95.124016 -214.428324)
		(width 0.14224)
		(layer "In6.Cu")
		(net "P3E_CPU1_P5_TX_DP<0>")
	)
	(segment
		(start 37.162994 -407.50617)
		(end 37.162994 -407.505916)
		(width 0.14224)
		(layer "In6.Cu")
		(net "P3E_CPU1_P5_TX_DP<0>")
	)
	(segment
		(start 12.116054 -192.0113)
		(end 12.41806 -191.709294)
		(width 0.14224)
		(layer "In6.Cu")
		(net "P3E_CPU1_P5_TX_DP<0>")
	)
	(segment
		(start 54.572408 -188.439806)
		(end 54.999128 -188.439806)
		(width 0.14224)
		(layer "In6.Cu")
		(net "P3E_CPU1_P5_TX_DP<0>")
	)
	(segment
		(start 13.21562 -190.911734)
		(end 13.21562 -190.717678)
		(width 0.14224)
		(layer "In6.Cu")
		(net "P3E_CPU1_P5_TX_DP<0>")
	)
	(segment
		(start 13.21562 -190.717678)
		(end 13.517118 -190.41618)
		(width 0.14224)
		(layer "In6.Cu")
		(net "P3E_CPU1_P5_TX_DP<0>")
	)
	(segment
		(start 56.688228 -188.305186)
		(end 56.825388 -188.442346)
		(width 0.14224)
		(layer "In6.Cu")
		(net "P3E_CPU1_P5_TX_DP<0>")
	)
	(segment
		(start 4.971796 -345.326462)
		(end 10.82294 -339.475318)
		(width 0.14224)
		(layer "In6.Cu")
		(net "P3E_CPU1_P5_TX_DP<0>")
	)
	(segment
		(start 39.087806 -410.148786)
		(end 38.851078 -409.79344)
		(width 0.14224)
		(layer "In6.Cu")
		(net "P3E_CPU1_P5_TX_DP<0>")
	)
	(segment
		(start 12.043918 -362.16463)
		(end 12.043918 -357.91775)
		(width 0.14224)
		(layer "In6.Cu")
		(net "P3E_CPU1_P5_TX_DP<0>")
	)
	(segment
		(start 12.913614 -191.21374)
		(end 13.21562 -190.911734)
		(width 0.14224)
		(layer "In6.Cu")
		(net "P3E_CPU1_P5_TX_DP<0>")
	)
	(segment
		(start 98.060764 -207.228948)
		(end 97.790254 -207.499458)
		(width 0.12954)
		(layer "F.Cu")
		(net "P3E_CPU1_P5_TX_DN<1>")
	)
	(segment
		(start 108.862622 -221.78264)
		(end 108.796582 -221.7166)
		(width 0.0762)
		(layer "F.Cu")
		(net "P3E_CPU1_P5_TX_DN<1>")
	)
	(segment
		(start 101.128068 -210.670648)
		(end 100.8634 -210.643216)
		(width 0.12954)
		(layer "F.Cu")
		(net "P3E_CPU1_P5_TX_DN<1>")
	)
	(segment
		(start 109.095794 -223.232726)
		(end 109.144816 -223.203008)
		(width 0.0762)
		(layer "F.Cu")
		(net "P3E_CPU1_P5_TX_DN<1>")
	)
	(segment
		(start 100.8634 -210.643216)
		(end 100.622862 -210.347306)
		(width 0.12954)
		(layer "F.Cu")
		(net "P3E_CPU1_P5_TX_DN<1>")
	)
	(segment
		(start 100.41001 -209.78749)
		(end 100.145342 -209.760312)
		(width 0.12954)
		(layer "F.Cu")
		(net "P3E_CPU1_P5_TX_DN<1>")
	)
	(segment
		(start 109.144816 -222.557848)
		(end 109.108494 -222.536766)
		(width 0.0762)
		(layer "F.Cu")
		(net "P3E_CPU1_P5_TX_DN<1>")
	)
	(segment
		(start 109.144816 -223.203008)
		(end 109.176566 -223.18472)
		(width 0.0762)
		(layer "F.Cu")
		(net "P3E_CPU1_P5_TX_DN<1>")
	)
	(segment
		(start 98.245676 -207.228948)
		(end 98.060764 -207.228948)
		(width 0.12954)
		(layer "F.Cu")
		(net "P3E_CPU1_P5_TX_DN<1>")
	)
	(segment
		(start 101.846126 -211.553806)
		(end 101.581458 -211.526374)
		(width 0.12954)
		(layer "F.Cu")
		(net "P3E_CPU1_P5_TX_DN<1>")
	)
	(segment
		(start 101.581458 -211.526374)
		(end 101.34092 -211.230464)
		(width 0.12954)
		(layer "F.Cu")
		(net "P3E_CPU1_P5_TX_DN<1>")
	)
	(segment
		(start 98.383344 -207.294734)
		(end 98.245676 -207.228948)
		(width 0.12954)
		(layer "F.Cu")
		(net "P3E_CPU1_P5_TX_DN<1>")
	)
	(segment
		(start 108.796582 -221.69755)
		(end 108.796582 -221.078298)
		(width 0.12954)
		(layer "F.Cu")
		(net "P3E_CPU1_P5_TX_DN<1>")
	)
	(segment
		(start 100.145342 -209.760312)
		(end 99.905058 -209.464402)
		(width 0.12954)
		(layer "F.Cu")
		(net "P3E_CPU1_P5_TX_DN<1>")
	)
	(segment
		(start 108.180632 -219.345256)
		(end 101.846126 -211.553806)
		(width 0.12954)
		(layer "F.Cu")
		(net "P3E_CPU1_P5_TX_DN<1>")
	)
	(segment
		(start 108.796582 -221.078298)
		(end 108.180632 -219.345256)
		(width 0.12954)
		(layer "F.Cu")
		(net "P3E_CPU1_P5_TX_DN<1>")
	)
	(segment
		(start 108.847382 -223.690434)
		(end 108.862622 -223.675194)
		(width 0.0762)
		(layer "F.Cu")
		(net "P3E_CPU1_P5_TX_DN<1>")
	)
	(segment
		(start 100.650294 -210.082892)
		(end 100.41001 -209.78749)
		(width 0.12954)
		(layer "F.Cu")
		(net "P3E_CPU1_P5_TX_DN<1>")
	)
	(segment
		(start 108.487972 -223.690434)
		(end 108.847382 -223.690434)
		(width 0.0762)
		(layer "F.Cu")
		(net "P3E_CPU1_P5_TX_DN<1>")
	)
	(segment
		(start 99.905058 -209.464402)
		(end 99.932236 -209.199988)
		(width 0.12954)
		(layer "F.Cu")
		(net "P3E_CPU1_P5_TX_DN<1>")
	)
	(segment
		(start 101.34092 -211.230464)
		(end 101.368352 -210.96605)
		(width 0.12954)
		(layer "F.Cu")
		(net "P3E_CPU1_P5_TX_DN<1>")
	)
	(segment
		(start 108.796582 -221.7166)
		(end 108.796582 -221.69755)
		(width 0.0762)
		(layer "F.Cu")
		(net "P3E_CPU1_P5_TX_DN<1>")
	)
	(segment
		(start 101.368352 -210.96605)
		(end 101.128068 -210.670648)
		(width 0.12954)
		(layer "F.Cu")
		(net "P3E_CPU1_P5_TX_DN<1>")
	)
	(segment
		(start 109.17555 -222.575628)
		(end 109.144816 -222.557848)
		(width 0.0762)
		(layer "F.Cu")
		(net "P3E_CPU1_P5_TX_DN<1>")
	)
	(segment
		(start 109.176566 -222.576136)
		(end 109.17555 -222.575628)
		(width 0.0762)
		(layer "F.Cu")
		(net "P3E_CPU1_P5_TX_DN<1>")
	)
	(segment
		(start 108.862622 -222.070422)
		(end 108.862622 -221.78264)
		(width 0.0762)
		(layer "F.Cu")
		(net "P3E_CPU1_P5_TX_DN<1>")
	)
	(segment
		(start 99.932236 -209.199988)
		(end 98.383344 -207.294734)
		(width 0.12954)
		(layer "F.Cu")
		(net "P3E_CPU1_P5_TX_DN<1>")
	)
	(segment
		(start 100.622862 -210.347306)
		(end 100.650294 -210.082892)
		(width 0.12954)
		(layer "F.Cu")
		(net "P3E_CPU1_P5_TX_DN<1>")
	)
	(arc
		(start 109.108494 -222.536766)
		(mid 108.927842 -222.334021)
		(end 108.862622 -222.070422)
		(width 0.0762)
		(layer "F.Cu")
		(net "P3E_CPU1_P5_TX_DN<1>")
	)
	(arc
		(start 109.176566 -223.18472)
		(mid 109.332494 -222.880428)
		(end 109.176566 -222.576136)
		(width 0.0762)
		(layer "F.Cu")
		(net "P3E_CPU1_P5_TX_DN<1>")
	)
	(arc
		(start 108.862622 -223.675194)
		(mid 108.924478 -223.425116)
		(end 109.095794 -223.232726)
		(width 0.0762)
		(layer "F.Cu")
		(net "P3E_CPU1_P5_TX_DN<1>")
	)
	(segment
		(start 39.35603 -412.5849)
		(end 39.62654 -412.85541)
		(width 0.12954)
		(layer "B.Cu")
		(net "P3E_CPU1_P5_TX_DN<1>")
	)
	(segment
		(start 42.94759 -413.111188)
		(end 43.6245 -413.111188)
		(width 0.12954)
		(layer "B.Cu")
		(net "P3E_CPU1_P5_TX_DN<1>")
	)
	(segment
		(start 43.6245 -413.111188)
		(end 43.88231 -412.853378)
		(width 0.12954)
		(layer "B.Cu")
		(net "P3E_CPU1_P5_TX_DN<1>")
	)
	(segment
		(start 42.691812 -412.85541)
		(end 42.94759 -413.111188)
		(width 0.12954)
		(layer "B.Cu")
		(net "P3E_CPU1_P5_TX_DN<1>")
	)
	(segment
		(start 39.62654 -412.85541)
		(end 42.691812 -412.85541)
		(width 0.12954)
		(layer "B.Cu")
		(net "P3E_CPU1_P5_TX_DN<1>")
	)
	(segment
		(start 16.222218 -185.205878)
		(end 58.185558 -185.205878)
		(width 0.14224)
		(layer "In6.Cu")
		(net "P3E_CPU1_P5_TX_DN<1>")
	)
	(segment
		(start 78.563724 -202.160378)
		(end 86.399624 -205.406244)
		(width 0.14224)
		(layer "In6.Cu")
		(net "P3E_CPU1_P5_TX_DN<1>")
	)
	(segment
		(start 87.765128 -205.406244)
		(end 88.191848 -205.406244)
		(width 0.14224)
		(layer "In6.Cu")
		(net "P3E_CPU1_P5_TX_DN<1>")
	)
	(segment
		(start 97.496122 -207.205326)
		(end 97.790254 -207.499458)
		(width 0.14224)
		(layer "In6.Cu")
		(net "P3E_CPU1_P5_TX_DN<1>")
	)
	(segment
		(start 68.503292 -192.099946)
		(end 78.563724 -202.160378)
		(width 0.14224)
		(layer "In6.Cu")
		(net "P3E_CPU1_P5_TX_DN<1>")
	)
	(segment
		(start 61.769498 -187.60059)
		(end 61.807344 -187.790836)
		(width 0.14224)
		(layer "In6.Cu")
		(net "P3E_CPU1_P5_TX_DN<1>")
	)
	(segment
		(start 88.329008 -205.543404)
		(end 88.755728 -205.543404)
		(width 0.14224)
		(layer "In6.Cu")
		(net "P3E_CPU1_P5_TX_DN<1>")
	)
	(segment
		(start 62.162436 -188.028072)
		(end 62.352682 -187.990226)
		(width 0.14224)
		(layer "In6.Cu")
		(net "P3E_CPU1_P5_TX_DN<1>")
	)
	(segment
		(start 61.414914 -187.363608)
		(end 61.769498 -187.60059)
		(width 0.14224)
		(layer "In6.Cu")
		(net "P3E_CPU1_P5_TX_DN<1>")
	)
	(segment
		(start 11.093958 -190.52794)
		(end 11.093958 -190.334138)
		(width 0.14224)
		(layer "In6.Cu")
		(net "P3E_CPU1_P5_TX_DN<1>")
	)
	(segment
		(start 61.807344 -187.790836)
		(end 62.162436 -188.028072)
		(width 0.14224)
		(layer "In6.Cu")
		(net "P3E_CPU1_P5_TX_DN<1>")
	)
	(segment
		(start 88.755728 -205.543404)
		(end 88.892888 -205.406244)
		(width 0.14224)
		(layer "In6.Cu")
		(net "P3E_CPU1_P5_TX_DN<1>")
	)
	(segment
		(start 38.518084 -412.88335)
		(end 34.408364 -408.77363)
		(width 0.14224)
		(layer "In6.Cu")
		(net "P3E_CPU1_P5_TX_DN<1>")
	)
	(segment
		(start 60.869576 -187.164218)
		(end 61.224668 -187.401454)
		(width 0.14224)
		(layer "In6.Cu")
		(net "P3E_CPU1_P5_TX_DN<1>")
	)
	(segment
		(start 63.29045 -188.616844)
		(end 68.503292 -192.099946)
		(width 0.14224)
		(layer "In6.Cu")
		(net "P3E_CPU1_P5_TX_DN<1>")
	)
	(segment
		(start 23.109682 -370.415312)
		(end 18.774664 -370.415312)
		(width 0.14224)
		(layer "In6.Cu")
		(net "P3E_CPU1_P5_TX_DN<1>")
	)
	(segment
		(start 11.093958 -190.334138)
		(end 11.395456 -190.03264)
		(width 0.14224)
		(layer "In6.Cu")
		(net "P3E_CPU1_P5_TX_DN<1>")
	)
	(segment
		(start 34.408364 -395.03731)
		(end 31.40456 -392.033506)
		(width 0.14224)
		(layer "In6.Cu")
		(net "P3E_CPU1_P5_TX_DN<1>")
	)
	(segment
		(start 10.59815 -190.829946)
		(end 10.791952 -190.829946)
		(width 0.14224)
		(layer "In6.Cu")
		(net "P3E_CPU1_P5_TX_DN<1>")
	)
	(segment
		(start 18.774664 -370.415312)
		(end 11.055096 -362.695744)
		(width 0.14224)
		(layer "In6.Cu")
		(net "P3E_CPU1_P5_TX_DN<1>")
	)
	(segment
		(start 9.85139 -191.576706)
		(end 10.59815 -190.829946)
		(width 0.14224)
		(layer "In6.Cu")
		(net "P3E_CPU1_P5_TX_DN<1>")
	)
	(segment
		(start 62.352682 -187.990226)
		(end 62.707266 -188.227208)
		(width 0.14224)
		(layer "In6.Cu")
		(net "P3E_CPU1_P5_TX_DN<1>")
	)
	(segment
		(start 9.85139 -339.072728)
		(end 9.85139 -191.576706)
		(width 0.14224)
		(layer "In6.Cu")
		(net "P3E_CPU1_P5_TX_DN<1>")
	)
	(segment
		(start 58.185558 -185.205878)
		(end 60.83173 -186.973972)
		(width 0.14224)
		(layer "In6.Cu")
		(net "P3E_CPU1_P5_TX_DN<1>")
	)
	(segment
		(start 88.191848 -205.406244)
		(end 88.329008 -205.543404)
		(width 0.14224)
		(layer "In6.Cu")
		(net "P3E_CPU1_P5_TX_DN<1>")
	)
	(segment
		(start 87.064088 -205.406244)
		(end 87.201248 -205.543404)
		(width 0.14224)
		(layer "In6.Cu")
		(net "P3E_CPU1_P5_TX_DN<1>")
	)
	(segment
		(start 63.100204 -188.65469)
		(end 63.29045 -188.616844)
		(width 0.14224)
		(layer "In6.Cu")
		(net "P3E_CPU1_P5_TX_DN<1>")
	)
	(segment
		(start 31.40456 -392.033506)
		(end 31.40456 -382.690116)
		(width 0.14224)
		(layer "In6.Cu")
		(net "P3E_CPU1_P5_TX_DN<1>")
	)
	(segment
		(start 11.395456 -190.03264)
		(end 11.589512 -190.03264)
		(width 0.14224)
		(layer "In6.Cu")
		(net "P3E_CPU1_P5_TX_DN<1>")
	)
	(segment
		(start 11.891518 -189.536578)
		(end 12.193016 -189.23508)
		(width 0.14224)
		(layer "In6.Cu")
		(net "P3E_CPU1_P5_TX_DN<1>")
	)
	(segment
		(start 4.000246 -344.923872)
		(end 9.85139 -339.072728)
		(width 0.14224)
		(layer "In6.Cu")
		(net "P3E_CPU1_P5_TX_DN<1>")
	)
	(segment
		(start 31.40456 -382.690116)
		(end 28.588208 -375.893838)
		(width 0.14224)
		(layer "In6.Cu")
		(net "P3E_CPU1_P5_TX_DN<1>")
	)
	(segment
		(start 62.745112 -188.417454)
		(end 63.100204 -188.65469)
		(width 0.14224)
		(layer "In6.Cu")
		(net "P3E_CPU1_P5_TX_DN<1>")
	)
	(segment
		(start 95.038672 -205.406244)
		(end 96.837754 -207.205326)
		(width 0.14224)
		(layer "In6.Cu")
		(net "P3E_CPU1_P5_TX_DN<1>")
	)
	(segment
		(start 11.055096 -358.320848)
		(end 4.000246 -351.265998)
		(width 0.14224)
		(layer "In6.Cu")
		(net "P3E_CPU1_P5_TX_DN<1>")
	)
	(segment
		(start 11.891518 -189.730634)
		(end 11.891518 -189.536578)
		(width 0.14224)
		(layer "In6.Cu")
		(net "P3E_CPU1_P5_TX_DN<1>")
	)
	(segment
		(start 60.83173 -186.973972)
		(end 60.869576 -187.164218)
		(width 0.14224)
		(layer "In6.Cu")
		(net "P3E_CPU1_P5_TX_DN<1>")
	)
	(segment
		(start 11.589512 -190.03264)
		(end 11.891518 -189.730634)
		(width 0.14224)
		(layer "In6.Cu")
		(net "P3E_CPU1_P5_TX_DN<1>")
	)
	(segment
		(start 87.627968 -205.543404)
		(end 87.765128 -205.406244)
		(width 0.14224)
		(layer "In6.Cu")
		(net "P3E_CPU1_P5_TX_DN<1>")
	)
	(segment
		(start 86.399624 -205.406244)
		(end 87.064088 -205.406244)
		(width 0.14224)
		(layer "In6.Cu")
		(net "P3E_CPU1_P5_TX_DN<1>")
	)
	(segment
		(start 12.387072 -189.23508)
		(end 12.689078 -188.933074)
		(width 0.14224)
		(layer "In6.Cu")
		(net "P3E_CPU1_P5_TX_DN<1>")
	)
	(segment
		(start 61.224668 -187.401454)
		(end 61.414914 -187.363608)
		(width 0.14224)
		(layer "In6.Cu")
		(net "P3E_CPU1_P5_TX_DN<1>")
	)
	(segment
		(start 34.408364 -408.77363)
		(end 34.408364 -395.03731)
		(width 0.14224)
		(layer "In6.Cu")
		(net "P3E_CPU1_P5_TX_DN<1>")
	)
	(segment
		(start 96.837754 -207.205326)
		(end 97.496122 -207.205326)
		(width 0.14224)
		(layer "In6.Cu")
		(net "P3E_CPU1_P5_TX_DN<1>")
	)
	(segment
		(start 62.707266 -188.227208)
		(end 62.745112 -188.417454)
		(width 0.14224)
		(layer "In6.Cu")
		(net "P3E_CPU1_P5_TX_DN<1>")
	)
	(segment
		(start 87.201248 -205.543404)
		(end 87.627968 -205.543404)
		(width 0.14224)
		(layer "In6.Cu")
		(net "P3E_CPU1_P5_TX_DN<1>")
	)
	(segment
		(start 39.35603 -412.5849)
		(end 39.05758 -412.88335)
		(width 0.14224)
		(layer "In6.Cu")
		(net "P3E_CPU1_P5_TX_DN<1>")
	)
	(segment
		(start 28.588208 -375.893838)
		(end 23.109682 -370.415312)
		(width 0.14224)
		(layer "In6.Cu")
		(net "P3E_CPU1_P5_TX_DN<1>")
	)
	(segment
		(start 88.892888 -205.406244)
		(end 95.038672 -205.406244)
		(width 0.14224)
		(layer "In6.Cu")
		(net "P3E_CPU1_P5_TX_DN<1>")
	)
	(segment
		(start 12.689078 -188.739018)
		(end 16.222218 -185.205878)
		(width 0.14224)
		(layer "In6.Cu")
		(net "P3E_CPU1_P5_TX_DN<1>")
	)
	(segment
		(start 4.000246 -351.265998)
		(end 4.000246 -344.923872)
		(width 0.14224)
		(layer "In6.Cu")
		(net "P3E_CPU1_P5_TX_DN<1>")
	)
	(segment
		(start 12.689078 -188.933074)
		(end 12.689078 -188.739018)
		(width 0.14224)
		(layer "In6.Cu")
		(net "P3E_CPU1_P5_TX_DN<1>")
	)
	(segment
		(start 39.05758 -412.88335)
		(end 38.518084 -412.88335)
		(width 0.14224)
		(layer "In6.Cu")
		(net "P3E_CPU1_P5_TX_DN<1>")
	)
	(segment
		(start 12.193016 -189.23508)
		(end 12.387072 -189.23508)
		(width 0.14224)
		(layer "In6.Cu")
		(net "P3E_CPU1_P5_TX_DN<1>")
	)
	(segment
		(start 10.791952 -190.829946)
		(end 11.093958 -190.52794)
		(width 0.14224)
		(layer "In6.Cu")
		(net "P3E_CPU1_P5_TX_DN<1>")
	)
	(segment
		(start 11.055096 -362.695744)
		(end 11.055096 -358.320848)
		(width 0.14224)
		(layer "In6.Cu")
		(net "P3E_CPU1_P5_TX_DN<1>")
	)
	(segment
		(start 103.222806 -222.070422)
		(end 103.222806 -221.388178)
		(width 0.0762)
		(layer "F.Cu")
		(net "P3E_CPU1_P5_TX_DN<0>")
	)
	(segment
		(start 95.488506 -214.82304)
		(end 95.488252 -214.822786)
		(width 0.12954)
		(layer "F.Cu")
		(net "P3E_CPU1_P5_TX_DN<0>")
	)
	(segment
		(start 103.222806 -221.388178)
		(end 103.156766 -221.322138)
		(width 0.0762)
		(layer "F.Cu")
		(net "P3E_CPU1_P5_TX_DN<0>")
	)
	(segment
		(start 103.9749 -223.367854)
		(end 103.973884 -223.367346)
		(width 0.0762)
		(layer "F.Cu")
		(net "P3E_CPU1_P5_TX_DN<0>")
	)
	(segment
		(start 95.94342 -215.19642)
		(end 95.488506 -214.82304)
		(width 0.12954)
		(layer "F.Cu")
		(net "P3E_CPU1_P5_TX_DN<0>")
	)
	(segment
		(start 96.823276 -215.918542)
		(end 96.52889 -215.676988)
		(width 0.12954)
		(layer "F.Cu")
		(net "P3E_CPU1_P5_TX_DN<0>")
	)
	(segment
		(start 95.969582 -215.461342)
		(end 95.94342 -215.19642)
		(width 0.12954)
		(layer "F.Cu")
		(net "P3E_CPU1_P5_TX_DN<0>")
	)
	(segment
		(start 103.971344 -223.365822)
		(end 103.935784 -223.344994)
		(width 0.0762)
		(layer "F.Cu")
		(net "P3E_CPU1_P5_TX_DN<0>")
	)
	(segment
		(start 97.702878 -216.640664)
		(end 97.408492 -216.39911)
		(width 0.12954)
		(layer "F.Cu")
		(net "P3E_CPU1_P5_TX_DN<0>")
	)
	(segment
		(start 95.488252 -214.822786)
		(end 95.245428 -214.721948)
		(width 0.12954)
		(layer "F.Cu")
		(net "P3E_CPU1_P5_TX_DN<0>")
	)
	(segment
		(start 97.144078 -216.425018)
		(end 96.849438 -216.183464)
		(width 0.12954)
		(layer "F.Cu")
		(net "P3E_CPU1_P5_TX_DN<0>")
	)
	(segment
		(start 96.52889 -215.676988)
		(end 96.264222 -215.702896)
		(width 0.12954)
		(layer "F.Cu")
		(net "P3E_CPU1_P5_TX_DN<0>")
	)
	(segment
		(start 105.885488 -223.385634)
		(end 105.884726 -223.385126)
		(width 0.0762)
		(layer "F.Cu")
		(net "P3E_CPU1_P5_TX_DN<0>")
	)
	(segment
		(start 105.98531 -223.690434)
		(end 106.038396 -223.637348)
		(width 0.0762)
		(layer "F.Cu")
		(net "P3E_CPU1_P5_TX_DN<0>")
	)
	(segment
		(start 103.973884 -223.367346)
		(end 103.97236 -223.36633)
		(width 0.0762)
		(layer "F.Cu")
		(net "P3E_CPU1_P5_TX_DN<0>")
	)
	(segment
		(start 98.288348 -217.121232)
		(end 98.02368 -217.14714)
		(width 0.12954)
		(layer "F.Cu")
		(net "P3E_CPU1_P5_TX_DN<0>")
	)
	(segment
		(start 103.156766 -221.224348)
		(end 103.073454 -221.048326)
		(width 0.12954)
		(layer "F.Cu")
		(net "P3E_CPU1_P5_TX_DN<0>")
	)
	(segment
		(start 103.156766 -221.322138)
		(end 103.156766 -221.303088)
		(width 0.0762)
		(layer "F.Cu")
		(net "P3E_CPU1_P5_TX_DN<0>")
	)
	(segment
		(start 97.72904 -216.905586)
		(end 97.702878 -216.640664)
		(width 0.12954)
		(layer "F.Cu")
		(net "P3E_CPU1_P5_TX_DN<0>")
	)
	(segment
		(start 96.849438 -216.183464)
		(end 96.823276 -215.918542)
		(width 0.12954)
		(layer "F.Cu")
		(net "P3E_CPU1_P5_TX_DN<0>")
	)
	(segment
		(start 105.884726 -223.385126)
		(end 105.855008 -223.367854)
		(width 0.0762)
		(layer "F.Cu")
		(net "P3E_CPU1_P5_TX_DN<0>")
	)
	(segment
		(start 96.264222 -215.702896)
		(end 95.969582 -215.461342)
		(width 0.12954)
		(layer "F.Cu")
		(net "P3E_CPU1_P5_TX_DN<0>")
	)
	(segment
		(start 94.75851 -214.721948)
		(end 94.488 -214.992458)
		(width 0.12954)
		(layer "F.Cu")
		(net "P3E_CPU1_P5_TX_DN<0>")
	)
	(segment
		(start 103.073454 -221.048326)
		(end 98.288348 -217.121232)
		(width 0.12954)
		(layer "F.Cu")
		(net "P3E_CPU1_P5_TX_DN<0>")
	)
	(segment
		(start 98.02368 -217.14714)
		(end 97.72904 -216.905586)
		(width 0.12954)
		(layer "F.Cu")
		(net "P3E_CPU1_P5_TX_DN<0>")
	)
	(segment
		(start 103.97236 -223.36633)
		(end 103.971344 -223.365822)
		(width 0.0762)
		(layer "F.Cu")
		(net "P3E_CPU1_P5_TX_DN<0>")
	)
	(segment
		(start 95.245428 -214.721948)
		(end 94.75851 -214.721948)
		(width 0.12954)
		(layer "F.Cu")
		(net "P3E_CPU1_P5_TX_DN<0>")
	)
	(segment
		(start 103.156766 -221.303088)
		(end 103.156766 -221.224348)
		(width 0.12954)
		(layer "F.Cu")
		(net "P3E_CPU1_P5_TX_DN<0>")
	)
	(segment
		(start 104.914954 -223.367854)
		(end 104.906572 -223.363028)
		(width 0.0762)
		(layer "F.Cu")
		(net "P3E_CPU1_P5_TX_DN<0>")
	)
	(segment
		(start 97.408492 -216.39911)
		(end 97.144078 -216.425018)
		(width 0.12954)
		(layer "F.Cu")
		(net "P3E_CPU1_P5_TX_DN<0>")
	)
	(segment
		(start 105.66781 -223.690434)
		(end 105.98531 -223.690434)
		(width 0.0762)
		(layer "F.Cu")
		(net "P3E_CPU1_P5_TX_DN<0>")
	)
	(segment
		(start 105.489248 -223.363028)
		(end 105.480866 -223.367854)
		(width 0.0762)
		(layer "F.Cu")
		(net "P3E_CPU1_P5_TX_DN<0>")
	)
	(segment
		(start 103.53548 -222.575628)
		(end 103.467408 -222.536004)
		(width 0.0762)
		(layer "F.Cu")
		(net "P3E_CPU1_P5_TX_DN<0>")
	)
	(arc
		(start 105.855008 -223.367854)
		(mid 105.672757 -223.317504)
		(end 105.489248 -223.363028)
		(width 0.0762)
		(layer "F.Cu")
		(net "P3E_CPU1_P5_TX_DN<0>")
	)
	(arc
		(start 104.906572 -223.363028)
		(mid 104.723064 -223.317534)
		(end 104.540812 -223.367854)
		(width 0.0762)
		(layer "F.Cu")
		(net "P3E_CPU1_P5_TX_DN<0>")
	)
	(arc
		(start 106.038396 -223.637348)
		(mid 105.987685 -223.495862)
		(end 105.885488 -223.385634)
		(width 0.0762)
		(layer "F.Cu")
		(net "P3E_CPU1_P5_TX_DN<0>")
	)
	(arc
		(start 105.480866 -223.367854)
		(mid 105.19791 -223.444031)
		(end 104.914954 -223.367854)
		(width 0.0762)
		(layer "F.Cu")
		(net "P3E_CPU1_P5_TX_DN<0>")
	)
	(arc
		(start 104.540812 -223.367854)
		(mid 104.257856 -223.444031)
		(end 103.9749 -223.367854)
		(width 0.0762)
		(layer "F.Cu")
		(net "P3E_CPU1_P5_TX_DN<0>")
	)
	(arc
		(start 103.467408 -222.536004)
		(mid 103.287616 -222.333416)
		(end 103.222806 -222.070422)
		(width 0.0762)
		(layer "F.Cu")
		(net "P3E_CPU1_P5_TX_DN<0>")
	)
	(arc
		(start 103.692452 -222.880428)
		(mid 103.650903 -222.709006)
		(end 103.53548 -222.575628)
		(width 0.0762)
		(layer "F.Cu")
		(net "P3E_CPU1_P5_TX_DN<0>")
	)
	(arc
		(start 103.935784 -223.344994)
		(mid 103.756971 -223.142644)
		(end 103.692452 -222.880428)
		(width 0.0762)
		(layer "F.Cu")
		(net "P3E_CPU1_P5_TX_DN<0>")
	)
	(segment
		(start 50.801524 -416.671506)
		(end 51.210464 -416.671506)
		(width 0.12954)
		(layer "B.Cu")
		(net "P3E_CPU1_P5_TX_DN<0>")
	)
	(segment
		(start 50.275744 -415.795206)
		(end 50.481484 -416.000946)
		(width 0.12954)
		(layer "B.Cu")
		(net "P3E_CPU1_P5_TX_DN<0>")
	)
	(segment
		(start 44.474384 -415.795206)
		(end 50.275744 -415.795206)
		(width 0.12954)
		(layer "B.Cu")
		(net "P3E_CPU1_P5_TX_DN<0>")
	)
	(segment
		(start 41.8592 -415.113216)
		(end 42.827702 -415.113216)
		(width 0.12954)
		(layer "B.Cu")
		(net "P3E_CPU1_P5_TX_DN<0>")
	)
	(segment
		(start 41.58869 -415.383726)
		(end 41.8592 -415.113216)
		(width 0.12954)
		(layer "B.Cu")
		(net "P3E_CPU1_P5_TX_DN<0>")
	)
	(segment
		(start 51.210464 -416.671506)
		(end 51.468274 -416.929316)
		(width 0.12954)
		(layer "B.Cu")
		(net "P3E_CPU1_P5_TX_DN<0>")
	)
	(segment
		(start 42.827702 -415.113216)
		(end 44.474384 -415.795206)
		(width 0.12954)
		(layer "B.Cu")
		(net "P3E_CPU1_P5_TX_DN<0>")
	)
	(segment
		(start 50.481484 -416.351466)
		(end 50.801524 -416.671506)
		(width 0.12954)
		(layer "B.Cu")
		(net "P3E_CPU1_P5_TX_DN<0>")
	)
	(segment
		(start 50.481484 -416.000946)
		(end 50.481484 -416.351466)
		(width 0.12954)
		(layer "B.Cu")
		(net "P3E_CPU1_P5_TX_DN<0>")
	)
	(segment
		(start 36.46297 -400.943064)
		(end 38.386766 -391.27049)
		(width 0.14224)
		(layer "In6.Cu")
		(net "P3E_CPU1_P5_TX_DN<0>")
	)
	(segment
		(start 15.511272 -188.023246)
		(end 59.963812 -188.023246)
		(width 0.14224)
		(layer "In6.Cu")
		(net "P3E_CPU1_P5_TX_DN<0>")
	)
	(segment
		(start 36.223194 -406.603454)
		(end 36.223194 -402.14931)
		(width 0.14224)
		(layer "In6.Cu")
		(net "P3E_CPU1_P5_TX_DN<0>")
	)
	(segment
		(start 40.171116 -414.679892)
		(end 40.171116 -412.532068)
		(width 0.14224)
		(layer "In6.Cu")
		(net "P3E_CPU1_P5_TX_DN<0>")
	)
	(segment
		(start 29.161994 -374.954038)
		(end 23.11654 -368.908584)
		(width 0.14224)
		(layer "In6.Cu")
		(net "P3E_CPU1_P5_TX_DN<0>")
	)
	(segment
		(start 36.39439 -401.28825)
		(end 36.39439 -401.287234)
		(width 0.14224)
		(layer "In6.Cu")
		(net "P3E_CPU1_P5_TX_DN<0>")
	)
	(segment
		(start 36.39439 -401.287234)
		(end 36.428426 -401.115784)
		(width 0.14224)
		(layer "In6.Cu")
		(net "P3E_CPU1_P5_TX_DN<0>")
	)
	(segment
		(start 4.689856 -345.209622)
		(end 10.541 -339.358478)
		(width 0.14224)
		(layer "In6.Cu")
		(net "P3E_CPU1_P5_TX_DN<0>")
	)
	(segment
		(start 40.577262 -415.086038)
		(end 40.171116 -414.679892)
		(width 0.14224)
		(layer "In6.Cu")
		(net "P3E_CPU1_P5_TX_DN<0>")
	)
	(segment
		(start 11.761978 -358.03459)
		(end 4.689856 -350.962468)
		(width 0.14224)
		(layer "In6.Cu")
		(net "P3E_CPU1_P5_TX_DN<0>")
	)
	(segment
		(start 11.761978 -362.28147)
		(end 11.761978 -358.03459)
		(width 0.14224)
		(layer "In6.Cu")
		(net "P3E_CPU1_P5_TX_DN<0>")
	)
	(segment
		(start 36.428934 -401.114768)
		(end 36.46297 -400.943064)
		(width 0.14224)
		(layer "In6.Cu")
		(net "P3E_CPU1_P5_TX_DN<0>")
	)
	(segment
		(start 41.58869 -415.383726)
		(end 41.291002 -415.086038)
		(width 0.14224)
		(layer "In6.Cu")
		(net "P3E_CPU1_P5_TX_DN<0>")
	)
	(segment
		(start 10.541 -192.993518)
		(end 15.511272 -188.023246)
		(width 0.14224)
		(layer "In6.Cu")
		(net "P3E_CPU1_P5_TX_DN<0>")
	)
	(segment
		(start 40.171116 -412.532068)
		(end 36.223194 -406.603454)
		(width 0.14224)
		(layer "In6.Cu")
		(net "P3E_CPU1_P5_TX_DN<0>")
	)
	(segment
		(start 95.758254 -214.192866)
		(end 95.240856 -214.710264)
		(width 0.14224)
		(layer "In6.Cu")
		(net "P3E_CPU1_P5_TX_DN<0>")
	)
	(segment
		(start 41.291002 -415.086038)
		(end 40.577262 -415.086038)
		(width 0.14224)
		(layer "In6.Cu")
		(net "P3E_CPU1_P5_TX_DN<0>")
	)
	(segment
		(start 94.770194 -214.710264)
		(end 94.488 -214.992458)
		(width 0.14224)
		(layer "In6.Cu")
		(net "P3E_CPU1_P5_TX_DN<0>")
	)
	(segment
		(start 32.07766 -381.991108)
		(end 29.161994 -374.954038)
		(width 0.14224)
		(layer "In6.Cu")
		(net "P3E_CPU1_P5_TX_DN<0>")
	)
	(segment
		(start 87.88654 -206.966566)
		(end 92.893134 -206.966566)
		(width 0.14224)
		(layer "In6.Cu")
		(net "P3E_CPU1_P5_TX_DN<0>")
	)
	(segment
		(start 4.689856 -350.962468)
		(end 4.689856 -345.209622)
		(width 0.14224)
		(layer "In6.Cu")
		(net "P3E_CPU1_P5_TX_DN<0>")
	)
	(segment
		(start 36.428934 -401.11553)
		(end 36.428934 -401.114768)
		(width 0.14224)
		(layer "In6.Cu")
		(net "P3E_CPU1_P5_TX_DN<0>")
	)
	(segment
		(start 23.11654 -368.908584)
		(end 18.389092 -368.908584)
		(width 0.14224)
		(layer "In6.Cu")
		(net "P3E_CPU1_P5_TX_DN<0>")
	)
	(segment
		(start 38.386766 -391.27049)
		(end 38.386766 -388.300214)
		(width 0.14224)
		(layer "In6.Cu")
		(net "P3E_CPU1_P5_TX_DN<0>")
	)
	(segment
		(start 95.758254 -207.574642)
		(end 95.758254 -214.192866)
		(width 0.14224)
		(layer "In6.Cu")
		(net "P3E_CPU1_P5_TX_DN<0>")
	)
	(segment
		(start 95.240856 -214.710264)
		(end 94.770194 -214.710264)
		(width 0.14224)
		(layer "In6.Cu")
		(net "P3E_CPU1_P5_TX_DN<0>")
	)
	(segment
		(start 38.386766 -388.300214)
		(end 32.07766 -381.991108)
		(width 0.14224)
		(layer "In6.Cu")
		(net "P3E_CPU1_P5_TX_DN<0>")
	)
	(segment
		(start 93.241368 -206.618332)
		(end 94.801944 -206.618332)
		(width 0.14224)
		(layer "In6.Cu")
		(net "P3E_CPU1_P5_TX_DN<0>")
	)
	(segment
		(start 10.541 -339.358478)
		(end 10.541 -192.993518)
		(width 0.14224)
		(layer "In6.Cu")
		(net "P3E_CPU1_P5_TX_DN<0>")
	)
	(segment
		(start 92.893134 -206.966566)
		(end 93.241368 -206.618332)
		(width 0.14224)
		(layer "In6.Cu")
		(net "P3E_CPU1_P5_TX_DN<0>")
	)
	(segment
		(start 78.395322 -203.035154)
		(end 87.88654 -206.966566)
		(width 0.14224)
		(layer "In6.Cu")
		(net "P3E_CPU1_P5_TX_DN<0>")
	)
	(segment
		(start 36.42868 -401.116038)
		(end 36.428934 -401.11553)
		(width 0.14224)
		(layer "In6.Cu")
		(net "P3E_CPU1_P5_TX_DN<0>")
	)
	(segment
		(start 70.269608 -194.90944)
		(end 78.395322 -203.035154)
		(width 0.14224)
		(layer "In6.Cu")
		(net "P3E_CPU1_P5_TX_DN<0>")
	)
	(segment
		(start 94.801944 -206.618332)
		(end 95.758254 -207.574642)
		(width 0.14224)
		(layer "In6.Cu")
		(net "P3E_CPU1_P5_TX_DN<0>")
	)
	(segment
		(start 18.389092 -368.908584)
		(end 11.761978 -362.28147)
		(width 0.14224)
		(layer "In6.Cu")
		(net "P3E_CPU1_P5_TX_DN<0>")
	)
	(segment
		(start 59.963812 -188.023246)
		(end 70.269608 -194.90944)
		(width 0.14224)
		(layer "In6.Cu")
		(net "P3E_CPU1_P5_TX_DN<0>")
	)
	(segment
		(start 36.223194 -402.14931)
		(end 36.39439 -401.28825)
		(width 0.14224)
		(layer "In6.Cu")
		(net "P3E_CPU1_P5_TX_DN<0>")
	)
	(segment
		(start 36.428426 -401.115784)
		(end 36.42868 -401.116038)
		(width 0.14224)
		(layer "In6.Cu")
		(net "P3E_CPU1_P5_TX_DN<0>")
	)
	(segment
		(start 110.045754 -224.84588)
		(end 110.08233 -224.824544)
		(width 0.0762)
		(layer "F.Cu")
		(net "P3E_CPU1_P5_RX_DP<1>")
	)
	(segment
		(start 100.516182 -207.659224)
		(end 100.265484 -207.372458)
		(width 0.12954)
		(layer "F.Cu")
		(net "P3E_CPU1_P5_RX_DP<1>")
	)
	(segment
		(start 111.306356 -221.359984)
		(end 111.154718 -220.912436)
		(width 0.12954)
		(layer "F.Cu")
		(net "P3E_CPU1_P5_RX_DP<1>")
	)
	(segment
		(start 110.083854 -224.823528)
		(end 110.08487 -224.82302)
		(width 0.0762)
		(layer "F.Cu")
		(net "P3E_CPU1_P5_RX_DP<1>")
	)
	(segment
		(start 100.7491 -208.21142)
		(end 100.498402 -207.9244)
		(width 0.12954)
		(layer "F.Cu")
		(net "P3E_CPU1_P5_RX_DP<1>")
	)
	(segment
		(start 101.247702 -208.781142)
		(end 101.265482 -208.515966)
		(width 0.12954)
		(layer "F.Cu")
		(net "P3E_CPU1_P5_RX_DP<1>")
	)
	(segment
		(start 110.08233 -224.824544)
		(end 110.083854 -224.823528)
		(width 0.0762)
		(layer "F.Cu")
		(net "P3E_CPU1_P5_RX_DP<1>")
	)
	(segment
		(start 111.398304 -224.373948)
		(end 111.478822 -224.29343)
		(width 0.12954)
		(layer "F.Cu")
		(net "P3E_CPU1_P5_RX_DP<1>")
	)
	(segment
		(start 96.28124 -207.252824)
		(end 96.359472 -207.510634)
		(width 0.12954)
		(layer "F.Cu")
		(net "P3E_CPU1_P5_RX_DP<1>")
	)
	(segment
		(start 111.384842 -224.480882)
		(end 111.384842 -224.38741)
		(width 0.0762)
		(layer "F.Cu")
		(net "P3E_CPU1_P5_RX_DP<1>")
	)
	(segment
		(start 94.758256 -208.752948)
		(end 94.487746 -209.023458)
		(width 0.12954)
		(layer "F.Cu")
		(net "P3E_CPU1_P5_RX_DP<1>")
	)
	(segment
		(start 97.132648 -205.660244)
		(end 96.28124 -207.252824)
		(width 0.12954)
		(layer "F.Cu")
		(net "P3E_CPU1_P5_RX_DP<1>")
	)
	(segment
		(start 101.014784 -208.2292)
		(end 100.7491 -208.21142)
		(width 0.12954)
		(layer "F.Cu")
		(net "P3E_CPU1_P5_RX_DP<1>")
	)
	(segment
		(start 111.508794 -224.22231)
		(end 111.53013 -224.087944)
		(width 0.12954)
		(layer "F.Cu")
		(net "P3E_CPU1_P5_RX_DP<1>")
	)
	(segment
		(start 101.4984 -209.068162)
		(end 101.247702 -208.781142)
		(width 0.12954)
		(layer "F.Cu")
		(net "P3E_CPU1_P5_RX_DP<1>")
	)
	(segment
		(start 99.767136 -206.802228)
		(end 98.658172 -205.53426)
		(width 0.12954)
		(layer "F.Cu")
		(net "P3E_CPU1_P5_RX_DP<1>")
	)
	(segment
		(start 96.359472 -207.510634)
		(end 96.177354 -207.851502)
		(width 0.12954)
		(layer "F.Cu")
		(net "P3E_CPU1_P5_RX_DP<1>")
	)
	(segment
		(start 100.000054 -207.354678)
		(end 99.749356 -207.067658)
		(width 0.12954)
		(layer "F.Cu")
		(net "P3E_CPU1_P5_RX_DP<1>")
	)
	(segment
		(start 95.91929 -207.929734)
		(end 95.695262 -208.348834)
		(width 0.12954)
		(layer "F.Cu")
		(net "P3E_CPU1_P5_RX_DP<1>")
	)
	(segment
		(start 96.177354 -207.851502)
		(end 95.91929 -207.929734)
		(width 0.12954)
		(layer "F.Cu")
		(net "P3E_CPU1_P5_RX_DP<1>")
	)
	(segment
		(start 95.291148 -208.752948)
		(end 94.758256 -208.752948)
		(width 0.12954)
		(layer "F.Cu")
		(net "P3E_CPU1_P5_RX_DP<1>")
	)
	(segment
		(start 95.695262 -208.348834)
		(end 95.291148 -208.752948)
		(width 0.12954)
		(layer "F.Cu")
		(net "P3E_CPU1_P5_RX_DP<1>")
	)
	(segment
		(start 97.719134 -205.286356)
		(end 97.398586 -205.419198)
		(width 0.12954)
		(layer "F.Cu")
		(net "P3E_CPU1_P5_RX_DP<1>")
	)
	(segment
		(start 98.06051 -205.286356)
		(end 97.719134 -205.286356)
		(width 0.12954)
		(layer "F.Cu")
		(net "P3E_CPU1_P5_RX_DP<1>")
	)
	(segment
		(start 97.398586 -205.419198)
		(end 97.132648 -205.660244)
		(width 0.12954)
		(layer "F.Cu")
		(net "P3E_CPU1_P5_RX_DP<1>")
	)
	(segment
		(start 100.265484 -207.372458)
		(end 100.000054 -207.354678)
		(width 0.12954)
		(layer "F.Cu")
		(net "P3E_CPU1_P5_RX_DP<1>")
	)
	(segment
		(start 98.658172 -205.53426)
		(end 98.06051 -205.286356)
		(width 0.12954)
		(layer "F.Cu")
		(net "P3E_CPU1_P5_RX_DP<1>")
	)
	(segment
		(start 109.745272 -225.310446)
		(end 109.80547 -225.250248)
		(width 0.0762)
		(layer "F.Cu")
		(net "P3E_CPU1_P5_RX_DP<1>")
	)
	(segment
		(start 111.384842 -224.38741)
		(end 111.398304 -224.373948)
		(width 0.0762)
		(layer "F.Cu")
		(net "P3E_CPU1_P5_RX_DP<1>")
	)
	(segment
		(start 111.53013 -224.087944)
		(end 111.306356 -221.359984)
		(width 0.12954)
		(layer "F.Cu")
		(net "P3E_CPU1_P5_RX_DP<1>")
	)
	(segment
		(start 100.498402 -207.9244)
		(end 100.516182 -207.659224)
		(width 0.12954)
		(layer "F.Cu")
		(net "P3E_CPU1_P5_RX_DP<1>")
	)
	(segment
		(start 101.265482 -208.515966)
		(end 101.014784 -208.2292)
		(width 0.12954)
		(layer "F.Cu")
		(net "P3E_CPU1_P5_RX_DP<1>")
	)
	(segment
		(start 104.526588 -212.245194)
		(end 101.764084 -209.085942)
		(width 0.12954)
		(layer "F.Cu")
		(net "P3E_CPU1_P5_RX_DP<1>")
	)
	(segment
		(start 111.101632 -224.764092)
		(end 111.384842 -224.480882)
		(width 0.0762)
		(layer "F.Cu")
		(net "P3E_CPU1_P5_RX_DP<1>")
	)
	(segment
		(start 111.478822 -224.29343)
		(end 111.508794 -224.22231)
		(width 0.12954)
		(layer "F.Cu")
		(net "P3E_CPU1_P5_RX_DP<1>")
	)
	(segment
		(start 99.749356 -207.067658)
		(end 99.767136 -206.802228)
		(width 0.12954)
		(layer "F.Cu")
		(net "P3E_CPU1_P5_RX_DP<1>")
	)
	(segment
		(start 111.154718 -220.912436)
		(end 104.526588 -212.245194)
		(width 0.12954)
		(layer "F.Cu")
		(net "P3E_CPU1_P5_RX_DP<1>")
	)
	(segment
		(start 101.764084 -209.085942)
		(end 101.4984 -209.068162)
		(width 0.12954)
		(layer "F.Cu")
		(net "P3E_CPU1_P5_RX_DP<1>")
	)
	(segment
		(start 109.427772 -225.310446)
		(end 109.745272 -225.310446)
		(width 0.0762)
		(layer "F.Cu")
		(net "P3E_CPU1_P5_RX_DP<1>")
	)
	(arc
		(start 109.80547 -225.250248)
		(mid 109.881565 -225.021892)
		(end 110.045754 -224.84588)
		(width 0.0762)
		(layer "F.Cu")
		(net "P3E_CPU1_P5_RX_DP<1>")
	)
	(arc
		(start 111.025178 -224.82302)
		(mid 111.065323 -224.796044)
		(end 111.101632 -224.764092)
		(width 0.0762)
		(layer "F.Cu")
		(net "P3E_CPU1_P5_RX_DP<1>")
	)
	(arc
		(start 110.08487 -224.82302)
		(mid 110.367826 -224.746843)
		(end 110.650782 -224.82302)
		(width 0.0762)
		(layer "F.Cu")
		(net "P3E_CPU1_P5_RX_DP<1>")
	)
	(arc
		(start 110.650782 -224.82302)
		(mid 110.83798 -224.873402)
		(end 111.025178 -224.82302)
		(width 0.0762)
		(layer "F.Cu")
		(net "P3E_CPU1_P5_RX_DP<1>")
	)
	(segment
		(start 61.686694 -402.95322)
		(end 48.297592 -402.95322)
		(width 0.14224)
		(layer "In2.Cu")
		(net "P3E_CPU1_P5_RX_DP<1>")
	)
	(segment
		(start 89.486486 -403.09038)
		(end 89.349326 -402.95322)
		(width 0.14224)
		(layer "In2.Cu")
		(net "P3E_CPU1_P5_RX_DP<1>")
	)
	(segment
		(start 95.939102 -405.212296)
		(end 95.939102 -403.990302)
		(width 0.14224)
		(layer "In2.Cu")
		(net "P3E_CPU1_P5_RX_DP<1>")
	)
	(segment
		(start 61.821314 -403.08784)
		(end 61.686694 -402.95322)
		(width 0.14224)
		(layer "In2.Cu")
		(net "P3E_CPU1_P5_RX_DP<1>")
	)
	(segment
		(start 46.444662 -403.913594)
		(end 46.37532 -404.081234)
		(width 0.14224)
		(layer "In2.Cu")
		(net "P3E_CPU1_P5_RX_DP<1>")
	)
	(segment
		(start 35.83051 -407.83002)
		(end 35.499548 -407.03119)
		(width 0.14224)
		(layer "In2.Cu")
		(net "P3E_CPU1_P5_RX_DP<1>")
	)
	(segment
		(start 62.248034 -403.08784)
		(end 61.821314 -403.08784)
		(width 0.14224)
		(layer "In2.Cu")
		(net "P3E_CPU1_P5_RX_DP<1>")
	)
	(segment
		(start 33.334198 -396.144496)
		(end 31.176468 -392.107928)
		(width 0.14224)
		(layer "In2.Cu")
		(net "P3E_CPU1_P5_RX_DP<1>")
	)
	(segment
		(start 46.7741 -403.584156)
		(end 46.444662 -403.913594)
		(width 0.14224)
		(layer "In2.Cu")
		(net "P3E_CPU1_P5_RX_DP<1>")
	)
	(segment
		(start 94.43212 -414.346136)
		(end 96.44507 -412.333186)
		(width 0.14224)
		(layer "In2.Cu")
		(net "P3E_CPU1_P5_RX_DP<1>")
	)
	(segment
		(start 86.727538 -403.09038)
		(end 86.300818 -403.09038)
		(width 0.14224)
		(layer "In2.Cu")
		(net "P3E_CPU1_P5_RX_DP<1>")
	)
	(segment
		(start 86.864698 -402.95322)
		(end 86.727538 -403.09038)
		(width 0.14224)
		(layer "In2.Cu")
		(net "P3E_CPU1_P5_RX_DP<1>")
	)
	(segment
		(start 86.163658 -402.95322)
		(end 71.641208 -402.95322)
		(width 0.14224)
		(layer "In2.Cu")
		(net "P3E_CPU1_P5_RX_DP<1>")
	)
	(segment
		(start 46.37532 -404.081234)
		(end 46.37532 -406.035256)
		(width 0.14224)
		(layer "In2.Cu")
		(net "P3E_CPU1_P5_RX_DP<1>")
	)
	(segment
		(start 76.204572 -414.346136)
		(end 94.43212 -414.346136)
		(width 0.14224)
		(layer "In2.Cu")
		(net "P3E_CPU1_P5_RX_DP<1>")
	)
	(segment
		(start 31.176468 -384.76047)
		(end 30.413198 -380.923546)
		(width 0.14224)
		(layer "In2.Cu")
		(net "P3E_CPU1_P5_RX_DP<1>")
	)
	(segment
		(start 31.176468 -392.107928)
		(end 31.176468 -384.76047)
		(width 0.14224)
		(layer "In2.Cu")
		(net "P3E_CPU1_P5_RX_DP<1>")
	)
	(segment
		(start 35.499548 -407.03119)
		(end 33.334198 -396.144496)
		(width 0.14224)
		(layer "In2.Cu")
		(net "P3E_CPU1_P5_RX_DP<1>")
	)
	(segment
		(start 65.299082 -402.95322)
		(end 65.164462 -403.08784)
		(width 0.14224)
		(layer "In2.Cu")
		(net "P3E_CPU1_P5_RX_DP<1>")
	)
	(segment
		(start 66.739516 -403.08784)
		(end 66.312796 -403.08784)
		(width 0.14224)
		(layer "In2.Cu")
		(net "P3E_CPU1_P5_RX_DP<1>")
	)
	(segment
		(start 71.108824 -422.948862)
		(end 71.309992 -422.948862)
		(width 0.14224)
		(layer "In2.Cu")
		(net "P3E_CPU1_P5_RX_DP<1>")
	)
	(segment
		(start 95.939102 -403.990302)
		(end 94.90202 -402.95322)
		(width 0.14224)
		(layer "In2.Cu")
		(net "P3E_CPU1_P5_RX_DP<1>")
	)
	(segment
		(start 71.641208 -402.95322)
		(end 71.506588 -403.08784)
		(width 0.14224)
		(layer "In2.Cu")
		(net "P3E_CPU1_P5_RX_DP<1>")
	)
	(segment
		(start 90.050366 -402.95322)
		(end 89.913206 -403.09038)
		(width 0.14224)
		(layer "In2.Cu")
		(net "P3E_CPU1_P5_RX_DP<1>")
	)
	(segment
		(start 89.349326 -402.95322)
		(end 86.864698 -402.95322)
		(width 0.14224)
		(layer "In2.Cu")
		(net "P3E_CPU1_P5_RX_DP<1>")
	)
	(segment
		(start 94.90202 -402.95322)
		(end 90.050366 -402.95322)
		(width 0.14224)
		(layer "In2.Cu")
		(net "P3E_CPU1_P5_RX_DP<1>")
	)
	(segment
		(start 97.155254 -406.428448)
		(end 95.939102 -405.212296)
		(width 0.14224)
		(layer "In2.Cu")
		(net "P3E_CPU1_P5_RX_DP<1>")
	)
	(segment
		(start 71.506588 -403.08784)
		(end 71.079868 -403.08784)
		(width 0.14224)
		(layer "In2.Cu")
		(net "P3E_CPU1_P5_RX_DP<1>")
	)
	(segment
		(start 65.164462 -403.08784)
		(end 64.737742 -403.08784)
		(width 0.14224)
		(layer "In2.Cu")
		(net "P3E_CPU1_P5_RX_DP<1>")
	)
	(segment
		(start 66.312796 -403.08784)
		(end 66.178176 -402.95322)
		(width 0.14224)
		(layer "In2.Cu")
		(net "P3E_CPU1_P5_RX_DP<1>")
	)
	(segment
		(start 97.155254 -410.618686)
		(end 97.155254 -406.428448)
		(width 0.14224)
		(layer "In2.Cu")
		(net "P3E_CPU1_P5_RX_DP<1>")
	)
	(segment
		(start 72.098916 -416.540696)
		(end 76.204572 -414.346136)
		(width 0.14224)
		(layer "In2.Cu")
		(net "P3E_CPU1_P5_RX_DP<1>")
	)
	(segment
		(start 96.44507 -412.333186)
		(end 97.155254 -410.618686)
		(width 0.14224)
		(layer "In2.Cu")
		(net "P3E_CPU1_P5_RX_DP<1>")
	)
	(segment
		(start 62.382654 -402.95322)
		(end 62.248034 -403.08784)
		(width 0.14224)
		(layer "In2.Cu")
		(net "P3E_CPU1_P5_RX_DP<1>")
	)
	(segment
		(start 71.452232 -417.187634)
		(end 72.098916 -416.540696)
		(width 0.14224)
		(layer "In2.Cu")
		(net "P3E_CPU1_P5_RX_DP<1>")
	)
	(segment
		(start 66.178176 -402.95322)
		(end 65.299082 -402.95322)
		(width 0.14224)
		(layer "In2.Cu")
		(net "P3E_CPU1_P5_RX_DP<1>")
	)
	(segment
		(start 13.21435 -360.125772)
		(end 12.92352 -360.416602)
		(width 0.14224)
		(layer "In2.Cu")
		(net "P3E_CPU1_P5_RX_DP<1>")
	)
	(segment
		(start 13.854684 -360.471974)
		(end 13.508482 -360.125772)
		(width 0.14224)
		(layer "In2.Cu")
		(net "P3E_CPU1_P5_RX_DP<1>")
	)
	(segment
		(start 71.452232 -422.806622)
		(end 71.452232 -417.187634)
		(width 0.14224)
		(layer "In2.Cu")
		(net "P3E_CPU1_P5_RX_DP<1>")
	)
	(segment
		(start 14.877796 -373.888254)
		(end 13.854684 -372.865142)
		(width 0.14224)
		(layer "In2.Cu")
		(net "P3E_CPU1_P5_RX_DP<1>")
	)
	(segment
		(start 30.413198 -380.923546)
		(end 27.986228 -375.06402)
		(width 0.14224)
		(layer "In2.Cu")
		(net "P3E_CPU1_P5_RX_DP<1>")
	)
	(segment
		(start 70.649846 -422.489884)
		(end 71.108824 -422.948862)
		(width 0.14224)
		(layer "In2.Cu")
		(net "P3E_CPU1_P5_RX_DP<1>")
	)
	(segment
		(start 68.128642 -403.08784)
		(end 67.994022 -402.95322)
		(width 0.14224)
		(layer "In2.Cu")
		(net "P3E_CPU1_P5_RX_DP<1>")
	)
	(segment
		(start 44.426378 -409.555442)
		(end 37.555932 -409.555442)
		(width 0.14224)
		(layer "In2.Cu")
		(net "P3E_CPU1_P5_RX_DP<1>")
	)
	(segment
		(start 70.945248 -402.95322)
		(end 68.689982 -402.95322)
		(width 0.14224)
		(layer "In2.Cu")
		(net "P3E_CPU1_P5_RX_DP<1>")
	)
	(segment
		(start 46.37532 -406.035256)
		(end 45.26407 -408.71775)
		(width 0.14224)
		(layer "In2.Cu")
		(net "P3E_CPU1_P5_RX_DP<1>")
	)
	(segment
		(start 48.297592 -402.95322)
		(end 46.7741 -403.584156)
		(width 0.14224)
		(layer "In2.Cu")
		(net "P3E_CPU1_P5_RX_DP<1>")
	)
	(segment
		(start 67.994022 -402.95322)
		(end 66.874136 -402.95322)
		(width 0.14224)
		(layer "In2.Cu")
		(net "P3E_CPU1_P5_RX_DP<1>")
	)
	(segment
		(start 27.986228 -375.06402)
		(end 26.810462 -373.888254)
		(width 0.14224)
		(layer "In2.Cu")
		(net "P3E_CPU1_P5_RX_DP<1>")
	)
	(segment
		(start 68.555362 -403.08784)
		(end 68.128642 -403.08784)
		(width 0.14224)
		(layer "In2.Cu")
		(net "P3E_CPU1_P5_RX_DP<1>")
	)
	(segment
		(start 45.26407 -408.71775)
		(end 44.426378 -409.555442)
		(width 0.14224)
		(layer "In2.Cu")
		(net "P3E_CPU1_P5_RX_DP<1>")
	)
	(segment
		(start 68.689982 -402.95322)
		(end 68.555362 -403.08784)
		(width 0.14224)
		(layer "In2.Cu")
		(net "P3E_CPU1_P5_RX_DP<1>")
	)
	(segment
		(start 66.874136 -402.95322)
		(end 66.739516 -403.08784)
		(width 0.14224)
		(layer "In2.Cu")
		(net "P3E_CPU1_P5_RX_DP<1>")
	)
	(segment
		(start 64.737742 -403.08784)
		(end 64.603122 -402.95322)
		(width 0.14224)
		(layer "In2.Cu")
		(net "P3E_CPU1_P5_RX_DP<1>")
	)
	(segment
		(start 71.079868 -403.08784)
		(end 70.945248 -402.95322)
		(width 0.14224)
		(layer "In2.Cu")
		(net "P3E_CPU1_P5_RX_DP<1>")
	)
	(segment
		(start 86.300818 -403.09038)
		(end 86.163658 -402.95322)
		(width 0.14224)
		(layer "In2.Cu")
		(net "P3E_CPU1_P5_RX_DP<1>")
	)
	(segment
		(start 64.603122 -402.95322)
		(end 62.382654 -402.95322)
		(width 0.14224)
		(layer "In2.Cu")
		(net "P3E_CPU1_P5_RX_DP<1>")
	)
	(segment
		(start 13.508482 -360.125772)
		(end 13.21435 -360.125772)
		(width 0.14224)
		(layer "In2.Cu")
		(net "P3E_CPU1_P5_RX_DP<1>")
	)
	(segment
		(start 71.309992 -422.948862)
		(end 71.452232 -422.806622)
		(width 0.14224)
		(layer "In2.Cu")
		(net "P3E_CPU1_P5_RX_DP<1>")
	)
	(segment
		(start 13.854684 -372.865142)
		(end 13.854684 -360.471974)
		(width 0.14224)
		(layer "In2.Cu")
		(net "P3E_CPU1_P5_RX_DP<1>")
	)
	(segment
		(start 37.555932 -409.555442)
		(end 35.83051 -407.83002)
		(width 0.14224)
		(layer "In2.Cu")
		(net "P3E_CPU1_P5_RX_DP<1>")
	)
	(segment
		(start 89.913206 -403.09038)
		(end 89.486486 -403.09038)
		(width 0.14224)
		(layer "In2.Cu")
		(net "P3E_CPU1_P5_RX_DP<1>")
	)
	(segment
		(start 26.810462 -373.888254)
		(end 14.877796 -373.888254)
		(width 0.14224)
		(layer "In2.Cu")
		(net "P3E_CPU1_P5_RX_DP<1>")
	)
	(segment
		(start 77.687678 -204.769974)
		(end 87.266018 -208.737454)
		(width 0.14224)
		(layer "In6.Cu")
		(net "P3E_CPU1_P5_RX_DP<1>")
	)
	(segment
		(start 14.054074 -356.465124)
		(end 16.408654 -350.780604)
		(width 0.14224)
		(layer "In6.Cu")
		(net "P3E_CPU1_P5_RX_DP<1>")
	)
	(segment
		(start 16.408654 -350.780604)
		(end 16.408654 -345.508834)
		(width 0.14224)
		(layer "In6.Cu")
		(net "P3E_CPU1_P5_RX_DP<1>")
	)
	(segment
		(start 12.92352 -360.416602)
		(end 13.217398 -360.122724)
		(width 0.14224)
		(layer "In6.Cu")
		(net "P3E_CPU1_P5_RX_DP<1>")
	)
	(segment
		(start 14.054074 -359.730294)
		(end 14.054074 -356.465124)
		(width 0.14224)
		(layer "In6.Cu")
		(net "P3E_CPU1_P5_RX_DP<1>")
	)
	(segment
		(start 87.266018 -208.737454)
		(end 94.201742 -208.737454)
		(width 0.14224)
		(layer "In6.Cu")
		(net "P3E_CPU1_P5_RX_DP<1>")
	)
	(segment
		(start 13.661644 -360.122724)
		(end 14.054074 -359.730294)
		(width 0.14224)
		(layer "In6.Cu")
		(net "P3E_CPU1_P5_RX_DP<1>")
	)
	(segment
		(start 12.265914 -194.176904)
		(end 16.140684 -190.302134)
		(width 0.14224)
		(layer "In6.Cu")
		(net "P3E_CPU1_P5_RX_DP<1>")
	)
	(segment
		(start 13.217398 -360.122724)
		(end 13.661644 -360.122724)
		(width 0.14224)
		(layer "In6.Cu")
		(net "P3E_CPU1_P5_RX_DP<1>")
	)
	(segment
		(start 69.20357 -196.285866)
		(end 77.687678 -204.769974)
		(width 0.14224)
		(layer "In6.Cu")
		(net "P3E_CPU1_P5_RX_DP<1>")
	)
	(segment
		(start 60.248292 -190.302134)
		(end 69.20357 -196.285866)
		(width 0.14224)
		(layer "In6.Cu")
		(net "P3E_CPU1_P5_RX_DP<1>")
	)
	(segment
		(start 12.265914 -331.852778)
		(end 12.265914 -194.176904)
		(width 0.14224)
		(layer "In6.Cu")
		(net "P3E_CPU1_P5_RX_DP<1>")
	)
	(segment
		(start 94.201742 -208.737454)
		(end 94.487746 -209.023458)
		(width 0.14224)
		(layer "In6.Cu")
		(net "P3E_CPU1_P5_RX_DP<1>")
	)
	(segment
		(start 16.408654 -345.508834)
		(end 12.265914 -331.852778)
		(width 0.14224)
		(layer "In6.Cu")
		(net "P3E_CPU1_P5_RX_DP<1>")
	)
	(segment
		(start 16.140684 -190.302134)
		(end 60.248292 -190.302134)
		(width 0.14224)
		(layer "In6.Cu")
		(net "P3E_CPU1_P5_RX_DP<1>")
	)
	(segment
		(start 106.825542 -223.385634)
		(end 106.795062 -223.367854)
		(width 0.0762)
		(layer "F.Cu")
		(net "P3E_CPU1_P5_RX_DP<0>")
	)
	(segment
		(start 107.225846 -224.84588)
		(end 107.296712 -224.804732)
		(width 0.0762)
		(layer "F.Cu")
		(net "P3E_CPU1_P5_RX_DP<0>")
	)
	(segment
		(start 97.66808 -214.259668)
		(end 97.64903 -213.994238)
		(width 0.12954)
		(layer "F.Cu")
		(net "P3E_CPU1_P5_RX_DP<0>")
	)
	(segment
		(start 98.816922 -215.25357)
		(end 98.528632 -215.004396)
		(width 0.12954)
		(layer "F.Cu")
		(net "P3E_CPU1_P5_RX_DP<0>")
	)
	(segment
		(start 105.97642 -221.531688)
		(end 105.97642 -221.386146)
		(width 0.12954)
		(layer "F.Cu")
		(net "P3E_CPU1_P5_RX_DP<0>")
	)
	(segment
		(start 98.509582 -214.738966)
		(end 98.221546 -214.489792)
		(width 0.12954)
		(layer "F.Cu")
		(net "P3E_CPU1_P5_RX_DP<0>")
	)
	(segment
		(start 107.300776 -224.198942)
		(end 107.296712 -224.196148)
		(width 0.0762)
		(layer "F.Cu")
		(net "P3E_CPU1_P5_RX_DP<0>")
	)
	(segment
		(start 95.193866 -211.869528)
		(end 94.75851 -211.869528)
		(width 0.12954)
		(layer "F.Cu")
		(net "P3E_CPU1_P5_RX_DP<0>")
	)
	(segment
		(start 105.97642 -221.550738)
		(end 105.97642 -221.531688)
		(width 0.0762)
		(layer "F.Cu")
		(net "P3E_CPU1_P5_RX_DP<0>")
	)
	(segment
		(start 107.264962 -224.17786)
		(end 107.263946 -224.177352)
		(width 0.0762)
		(layer "F.Cu")
		(net "P3E_CPU1_P5_RX_DP<0>")
	)
	(segment
		(start 107.296712 -224.196148)
		(end 107.265724 -224.178368)
		(width 0.0762)
		(layer "F.Cu")
		(net "P3E_CPU1_P5_RX_DP<0>")
	)
	(segment
		(start 106.356658 -222.576136)
		(end 106.324908 -222.557848)
		(width 0.0762)
		(layer "F.Cu")
		(net "P3E_CPU1_P5_RX_DP<0>")
	)
	(segment
		(start 106.795062 -223.367854)
		(end 106.755946 -223.344994)
		(width 0.0762)
		(layer "F.Cu")
		(net "P3E_CPU1_P5_RX_DP<0>")
	)
	(segment
		(start 97.95637 -214.508842)
		(end 97.66808 -214.259668)
		(width 0.12954)
		(layer "F.Cu")
		(net "P3E_CPU1_P5_RX_DP<0>")
	)
	(segment
		(start 107.233466 -224.159572)
		(end 107.232704 -224.159064)
		(width 0.0762)
		(layer "F.Cu")
		(net "P3E_CPU1_P5_RX_DP<0>")
	)
	(segment
		(start 106.925364 -225.310446)
		(end 106.985562 -225.250248)
		(width 0.0762)
		(layer "F.Cu")
		(net "P3E_CPU1_P5_RX_DP<0>")
	)
	(segment
		(start 105.835958 -221.079314)
		(end 99.082098 -215.23452)
		(width 0.12954)
		(layer "F.Cu")
		(net "P3E_CPU1_P5_RX_DP<0>")
	)
	(segment
		(start 107.265724 -224.178368)
		(end 107.264962 -224.17786)
		(width 0.0762)
		(layer "F.Cu")
		(net "P3E_CPU1_P5_RX_DP<0>")
	)
	(segment
		(start 97.360994 -213.745064)
		(end 97.096072 -213.764114)
		(width 0.12954)
		(layer "F.Cu")
		(net "P3E_CPU1_P5_RX_DP<0>")
	)
	(segment
		(start 97.64903 -213.994238)
		(end 97.360994 -213.745064)
		(width 0.12954)
		(layer "F.Cu")
		(net "P3E_CPU1_P5_RX_DP<0>")
	)
	(segment
		(start 96.807528 -213.51494)
		(end 96.788478 -213.24951)
		(width 0.12954)
		(layer "F.Cu")
		(net "P3E_CPU1_P5_RX_DP<0>")
	)
	(segment
		(start 94.75851 -211.869528)
		(end 94.488 -212.140038)
		(width 0.12954)
		(layer "F.Cu")
		(net "P3E_CPU1_P5_RX_DP<0>")
	)
	(segment
		(start 105.97642 -221.386146)
		(end 105.835958 -221.079314)
		(width 0.12954)
		(layer "F.Cu")
		(net "P3E_CPU1_P5_RX_DP<0>")
	)
	(segment
		(start 98.528632 -215.004396)
		(end 98.509582 -214.738966)
		(width 0.12954)
		(layer "F.Cu")
		(net "P3E_CPU1_P5_RX_DP<0>")
	)
	(segment
		(start 96.788478 -213.24951)
		(end 95.193866 -211.869528)
		(width 0.12954)
		(layer "F.Cu")
		(net "P3E_CPU1_P5_RX_DP<0>")
	)
	(segment
		(start 106.04246 -222.070422)
		(end 106.04246 -221.616778)
		(width 0.0762)
		(layer "F.Cu")
		(net "P3E_CPU1_P5_RX_DP<0>")
	)
	(segment
		(start 107.296712 -224.804732)
		(end 107.300776 -224.801938)
		(width 0.0762)
		(layer "F.Cu")
		(net "P3E_CPU1_P5_RX_DP<0>")
	)
	(segment
		(start 106.607864 -225.310446)
		(end 106.925364 -225.310446)
		(width 0.0762)
		(layer "F.Cu")
		(net "P3E_CPU1_P5_RX_DP<0>")
	)
	(segment
		(start 106.04246 -221.616778)
		(end 105.97642 -221.550738)
		(width 0.0762)
		(layer "F.Cu")
		(net "P3E_CPU1_P5_RX_DP<0>")
	)
	(segment
		(start 107.232704 -224.159064)
		(end 107.225846 -224.155)
		(width 0.0762)
		(layer "F.Cu")
		(net "P3E_CPU1_P5_RX_DP<0>")
	)
	(segment
		(start 98.221546 -214.489792)
		(end 97.95637 -214.508842)
		(width 0.12954)
		(layer "F.Cu")
		(net "P3E_CPU1_P5_RX_DP<0>")
	)
	(segment
		(start 107.263946 -224.177352)
		(end 107.233466 -224.159572)
		(width 0.0762)
		(layer "F.Cu")
		(net "P3E_CPU1_P5_RX_DP<0>")
	)
	(segment
		(start 99.082098 -215.23452)
		(end 98.816922 -215.25357)
		(width 0.12954)
		(layer "F.Cu")
		(net "P3E_CPU1_P5_RX_DP<0>")
	)
	(segment
		(start 106.324908 -222.557848)
		(end 106.285792 -222.534988)
		(width 0.0762)
		(layer "F.Cu")
		(net "P3E_CPU1_P5_RX_DP<0>")
	)
	(segment
		(start 97.096072 -213.764114)
		(end 96.807528 -213.51494)
		(width 0.12954)
		(layer "F.Cu")
		(net "P3E_CPU1_P5_RX_DP<0>")
	)
	(arc
		(start 106.982514 -223.690434)
		(mid 106.940965 -223.519012)
		(end 106.825542 -223.385634)
		(width 0.0762)
		(layer "F.Cu")
		(net "P3E_CPU1_P5_RX_DP<0>")
	)
	(arc
		(start 106.755946 -223.344994)
		(mid 106.577133 -223.142644)
		(end 106.512614 -222.880428)
		(width 0.0762)
		(layer "F.Cu")
		(net "P3E_CPU1_P5_RX_DP<0>")
	)
	(arc
		(start 106.142028 -222.39097)
		(mid 106.067914 -222.238256)
		(end 106.04246 -222.070422)
		(width 0.0762)
		(layer "F.Cu")
		(net "P3E_CPU1_P5_RX_DP<0>")
	)
	(arc
		(start 106.985562 -225.250248)
		(mid 107.061657 -225.021892)
		(end 107.225846 -224.84588)
		(width 0.0762)
		(layer "F.Cu")
		(net "P3E_CPU1_P5_RX_DP<0>")
	)
	(arc
		(start 106.512614 -222.880428)
		(mid 106.471359 -222.709457)
		(end 106.356658 -222.576136)
		(width 0.0762)
		(layer "F.Cu")
		(net "P3E_CPU1_P5_RX_DP<0>")
	)
	(arc
		(start 106.285792 -222.534988)
		(mid 106.207369 -222.469507)
		(end 106.142028 -222.39097)
		(width 0.0762)
		(layer "F.Cu")
		(net "P3E_CPU1_P5_RX_DP<0>")
	)
	(arc
		(start 107.225846 -224.155)
		(mid 107.047033 -223.95265)
		(end 106.982514 -223.690434)
		(width 0.0762)
		(layer "F.Cu")
		(net "P3E_CPU1_P5_RX_DP<0>")
	)
	(arc
		(start 107.300776 -224.801938)
		(mid 107.455281 -224.50044)
		(end 107.300776 -224.198942)
		(width 0.0762)
		(layer "F.Cu")
		(net "P3E_CPU1_P5_RX_DP<0>")
	)
	(segment
		(start 89.26449 -400.435826)
		(end 89.12733 -400.572986)
		(width 0.14224)
		(layer "In2.Cu")
		(net "P3E_CPU1_P5_RX_DP<0>")
	)
	(segment
		(start 29.008324 -374.762776)
		(end 29.008578 -374.762776)
		(width 0.14224)
		(layer "In2.Cu")
		(net "P3E_CPU1_P5_RX_DP<0>")
	)
	(segment
		(start 87.57285 -400.572986)
		(end 87.43569 -400.435826)
		(width 0.14224)
		(layer "In2.Cu")
		(net "P3E_CPU1_P5_RX_DP<0>")
	)
	(segment
		(start 85.31733 -400.572986)
		(end 85.18017 -400.435826)
		(width 0.14224)
		(layer "In2.Cu")
		(net "P3E_CPU1_P5_RX_DP<0>")
	)
	(segment
		(start 88.56345 -400.435826)
		(end 88.13673 -400.435826)
		(width 0.14224)
		(layer "In2.Cu")
		(net "P3E_CPU1_P5_RX_DP<0>")
	)
	(segment
		(start 15.524988 -357.780844)
		(end 15.111476 -357.780844)
		(width 0.14224)
		(layer "In2.Cu")
		(net "P3E_CPU1_P5_RX_DP<0>")
	)
	(segment
		(start 38.308534 -391.457688)
		(end 38.308534 -389.201406)
		(width 0.14224)
		(layer "In2.Cu")
		(net "P3E_CPU1_P5_RX_DP<0>")
	)
	(segment
		(start 92.352368 -400.572986)
		(end 92.215208 -400.435826)
		(width 0.14224)
		(layer "In2.Cu")
		(net "P3E_CPU1_P5_RX_DP<0>")
	)
	(segment
		(start 15.824454 -372.112794)
		(end 15.824454 -358.08031)
		(width 0.14224)
		(layer "In2.Cu")
		(net "P3E_CPU1_P5_RX_DP<0>")
	)
	(segment
		(start 97.47123 -403.436328)
		(end 94.470728 -400.435826)
		(width 0.14224)
		(layer "In2.Cu")
		(net "P3E_CPU1_P5_RX_DP<0>")
	)
	(segment
		(start 86.30793 -400.435826)
		(end 85.88121 -400.435826)
		(width 0.14224)
		(layer "In2.Cu")
		(net "P3E_CPU1_P5_RX_DP<0>")
	)
	(segment
		(start 73.10882 -423.94886)
		(end 73.548748 -423.94886)
		(width 0.14224)
		(layer "In2.Cu")
		(net "P3E_CPU1_P5_RX_DP<0>")
	)
	(segment
		(start 97.884488 -404.433786)
		(end 97.47123 -403.436328)
		(width 0.14224)
		(layer "In2.Cu")
		(net "P3E_CPU1_P5_RX_DP<0>")
	)
	(segment
		(start 85.74405 -400.572986)
		(end 85.31733 -400.572986)
		(width 0.14224)
		(layer "In2.Cu")
		(net "P3E_CPU1_P5_RX_DP<0>")
	)
	(segment
		(start 93.480128 -400.572986)
		(end 93.342968 -400.435826)
		(width 0.14224)
		(layer "In2.Cu")
		(net "P3E_CPU1_P5_RX_DP<0>")
	)
	(segment
		(start 89.959688 -400.435826)
		(end 89.26449 -400.435826)
		(width 0.14224)
		(layer "In2.Cu")
		(net "P3E_CPU1_P5_RX_DP<0>")
	)
	(segment
		(start 91.788488 -400.435826)
		(end 91.651328 -400.572986)
		(width 0.14224)
		(layer "In2.Cu")
		(net "P3E_CPU1_P5_RX_DP<0>")
	)
	(segment
		(start 91.087448 -400.435826)
		(end 90.660728 -400.435826)
		(width 0.14224)
		(layer "In2.Cu")
		(net "P3E_CPU1_P5_RX_DP<0>")
	)
	(segment
		(start 16.641826 -372.930166)
		(end 15.824454 -372.112794)
		(width 0.14224)
		(layer "In2.Cu")
		(net "P3E_CPU1_P5_RX_DP<0>")
	)
	(segment
		(start 92.916248 -400.435826)
		(end 92.779088 -400.572986)
		(width 0.14224)
		(layer "In2.Cu")
		(net "P3E_CPU1_P5_RX_DP<0>")
	)
	(segment
		(start 29.008578 -374.762776)
		(end 27.175968 -372.930166)
		(width 0.14224)
		(layer "In2.Cu")
		(net "P3E_CPU1_P5_RX_DP<0>")
	)
	(segment
		(start 37.410898 -393.627102)
		(end 38.308534 -391.457688)
		(width 0.14224)
		(layer "In2.Cu")
		(net "P3E_CPU1_P5_RX_DP<0>")
	)
	(segment
		(start 87.43569 -400.435826)
		(end 87.00897 -400.435826)
		(width 0.14224)
		(layer "In2.Cu")
		(net "P3E_CPU1_P5_RX_DP<0>")
	)
	(segment
		(start 88.13673 -400.435826)
		(end 87.99957 -400.572986)
		(width 0.14224)
		(layer "In2.Cu")
		(net "P3E_CPU1_P5_RX_DP<0>")
	)
	(segment
		(start 90.523568 -400.572986)
		(end 90.096848 -400.572986)
		(width 0.14224)
		(layer "In2.Cu")
		(net "P3E_CPU1_P5_RX_DP<0>")
	)
	(segment
		(start 100.744782 -412.160974)
		(end 100.744782 -410.844746)
		(width 0.14224)
		(layer "In2.Cu")
		(net "P3E_CPU1_P5_RX_DP<0>")
	)
	(segment
		(start 73.82002 -423.677588)
		(end 73.82002 -418.059616)
		(width 0.14224)
		(layer "In2.Cu")
		(net "P3E_CPU1_P5_RX_DP<0>")
	)
	(segment
		(start 72.649842 -423.489882)
		(end 73.10882 -423.94886)
		(width 0.14224)
		(layer "In2.Cu")
		(net "P3E_CPU1_P5_RX_DP<0>")
	)
	(segment
		(start 15.111476 -357.780844)
		(end 14.820646 -358.071674)
		(width 0.14224)
		(layer "In2.Cu")
		(net "P3E_CPU1_P5_RX_DP<0>")
	)
	(segment
		(start 88.70061 -400.572986)
		(end 88.56345 -400.435826)
		(width 0.14224)
		(layer "In2.Cu")
		(net "P3E_CPU1_P5_RX_DP<0>")
	)
	(segment
		(start 39.46398 -399.341848)
		(end 37.410898 -397.288512)
		(width 0.14224)
		(layer "In2.Cu")
		(net "P3E_CPU1_P5_RX_DP<0>")
	)
	(segment
		(start 73.548748 -423.94886)
		(end 73.82002 -423.677588)
		(width 0.14224)
		(layer "In2.Cu")
		(net "P3E_CPU1_P5_RX_DP<0>")
	)
	(segment
		(start 93.342968 -400.435826)
		(end 92.916248 -400.435826)
		(width 0.14224)
		(layer "In2.Cu")
		(net "P3E_CPU1_P5_RX_DP<0>")
	)
	(segment
		(start 86.44509 -400.572986)
		(end 86.30793 -400.435826)
		(width 0.14224)
		(layer "In2.Cu")
		(net "P3E_CPU1_P5_RX_DP<0>")
	)
	(segment
		(start 90.096848 -400.572986)
		(end 89.959688 -400.435826)
		(width 0.14224)
		(layer "In2.Cu")
		(net "P3E_CPU1_P5_RX_DP<0>")
	)
	(segment
		(start 15.824454 -358.08031)
		(end 15.524988 -357.780844)
		(width 0.14224)
		(layer "In2.Cu")
		(net "P3E_CPU1_P5_RX_DP<0>")
	)
	(segment
		(start 37.953696 -388.344918)
		(end 31.252414 -380.17958)
		(width 0.14224)
		(layer "In2.Cu")
		(net "P3E_CPU1_P5_RX_DP<0>")
	)
	(segment
		(start 73.82002 -418.059616)
		(end 74.2315 -417.29025)
		(width 0.14224)
		(layer "In2.Cu")
		(net "P3E_CPU1_P5_RX_DP<0>")
	)
	(segment
		(start 87.00897 -400.435826)
		(end 86.87181 -400.572986)
		(width 0.14224)
		(layer "In2.Cu")
		(net "P3E_CPU1_P5_RX_DP<0>")
	)
	(segment
		(start 99.657408 -405.803354)
		(end 99.080066 -405.226012)
		(width 0.14224)
		(layer "In2.Cu")
		(net "P3E_CPU1_P5_RX_DP<0>")
	)
	(segment
		(start 91.651328 -400.572986)
		(end 91.224608 -400.572986)
		(width 0.14224)
		(layer "In2.Cu")
		(net "P3E_CPU1_P5_RX_DP<0>")
	)
	(segment
		(start 38.308534 -389.201406)
		(end 37.953696 -388.344918)
		(width 0.14224)
		(layer "In2.Cu")
		(net "P3E_CPU1_P5_RX_DP<0>")
	)
	(segment
		(start 46.756828 -401.282662)
		(end 45.860208 -401.282662)
		(width 0.14224)
		(layer "In2.Cu")
		(net "P3E_CPU1_P5_RX_DP<0>")
	)
	(segment
		(start 74.2315 -417.29025)
		(end 76.702666 -415.639504)
		(width 0.14224)
		(layer "In2.Cu")
		(net "P3E_CPU1_P5_RX_DP<0>")
	)
	(segment
		(start 92.215208 -400.435826)
		(end 91.788488 -400.435826)
		(width 0.14224)
		(layer "In2.Cu")
		(net "P3E_CPU1_P5_RX_DP<0>")
	)
	(segment
		(start 97.697544 -412.515558)
		(end 100.390198 -412.515558)
		(width 0.14224)
		(layer "In2.Cu")
		(net "P3E_CPU1_P5_RX_DP<0>")
	)
	(segment
		(start 31.252414 -380.17958)
		(end 29.008324 -374.762776)
		(width 0.14224)
		(layer "In2.Cu")
		(net "P3E_CPU1_P5_RX_DP<0>")
	)
	(segment
		(start 93.906848 -400.572986)
		(end 93.480128 -400.572986)
		(width 0.14224)
		(layer "In2.Cu")
		(net "P3E_CPU1_P5_RX_DP<0>")
	)
	(segment
		(start 85.88121 -400.435826)
		(end 85.74405 -400.572986)
		(width 0.14224)
		(layer "In2.Cu")
		(net "P3E_CPU1_P5_RX_DP<0>")
	)
	(segment
		(start 48.801528 -400.435826)
		(end 46.756828 -401.282662)
		(width 0.14224)
		(layer "In2.Cu")
		(net "P3E_CPU1_P5_RX_DP<0>")
	)
	(segment
		(start 92.779088 -400.572986)
		(end 92.352368 -400.572986)
		(width 0.14224)
		(layer "In2.Cu")
		(net "P3E_CPU1_P5_RX_DP<0>")
	)
	(segment
		(start 98.391472 -404.94077)
		(end 97.884488 -404.433786)
		(width 0.14224)
		(layer "In2.Cu")
		(net "P3E_CPU1_P5_RX_DP<0>")
	)
	(segment
		(start 100.744782 -410.844746)
		(end 99.820222 -406.196546)
		(width 0.14224)
		(layer "In2.Cu")
		(net "P3E_CPU1_P5_RX_DP<0>")
	)
	(segment
		(start 86.87181 -400.572986)
		(end 86.44509 -400.572986)
		(width 0.14224)
		(layer "In2.Cu")
		(net "P3E_CPU1_P5_RX_DP<0>")
	)
	(segment
		(start 89.12733 -400.572986)
		(end 88.70061 -400.572986)
		(width 0.14224)
		(layer "In2.Cu")
		(net "P3E_CPU1_P5_RX_DP<0>")
	)
	(segment
		(start 94.573598 -415.639504)
		(end 97.697544 -412.515558)
		(width 0.14224)
		(layer "In2.Cu")
		(net "P3E_CPU1_P5_RX_DP<0>")
	)
	(segment
		(start 99.080066 -405.226012)
		(end 98.391472 -404.94077)
		(width 0.14224)
		(layer "In2.Cu")
		(net "P3E_CPU1_P5_RX_DP<0>")
	)
	(segment
		(start 100.390198 -412.515558)
		(end 100.744782 -412.160974)
		(width 0.14224)
		(layer "In2.Cu")
		(net "P3E_CPU1_P5_RX_DP<0>")
	)
	(segment
		(start 76.702666 -415.639504)
		(end 94.573598 -415.639504)
		(width 0.14224)
		(layer "In2.Cu")
		(net "P3E_CPU1_P5_RX_DP<0>")
	)
	(segment
		(start 27.175968 -372.930166)
		(end 16.641826 -372.930166)
		(width 0.14224)
		(layer "In2.Cu")
		(net "P3E_CPU1_P5_RX_DP<0>")
	)
	(segment
		(start 99.820222 -406.196546)
		(end 99.657408 -405.803354)
		(width 0.14224)
		(layer "In2.Cu")
		(net "P3E_CPU1_P5_RX_DP<0>")
	)
	(segment
		(start 37.410898 -397.288512)
		(end 37.410898 -393.627102)
		(width 0.14224)
		(layer "In2.Cu")
		(net "P3E_CPU1_P5_RX_DP<0>")
	)
	(segment
		(start 45.860208 -401.282662)
		(end 39.46398 -399.341848)
		(width 0.14224)
		(layer "In2.Cu")
		(net "P3E_CPU1_P5_RX_DP<0>")
	)
	(segment
		(start 85.18017 -400.435826)
		(end 48.801528 -400.435826)
		(width 0.14224)
		(layer "In2.Cu")
		(net "P3E_CPU1_P5_RX_DP<0>")
	)
	(segment
		(start 87.99957 -400.572986)
		(end 87.57285 -400.572986)
		(width 0.14224)
		(layer "In2.Cu")
		(net "P3E_CPU1_P5_RX_DP<0>")
	)
	(segment
		(start 90.660728 -400.435826)
		(end 90.523568 -400.572986)
		(width 0.14224)
		(layer "In2.Cu")
		(net "P3E_CPU1_P5_RX_DP<0>")
	)
	(segment
		(start 94.044008 -400.435826)
		(end 93.906848 -400.572986)
		(width 0.14224)
		(layer "In2.Cu")
		(net "P3E_CPU1_P5_RX_DP<0>")
	)
	(segment
		(start 91.224608 -400.572986)
		(end 91.087448 -400.435826)
		(width 0.14224)
		(layer "In2.Cu")
		(net "P3E_CPU1_P5_RX_DP<0>")
	)
	(segment
		(start 94.470728 -400.435826)
		(end 94.044008 -400.435826)
		(width 0.14224)
		(layer "In2.Cu")
		(net "P3E_CPU1_P5_RX_DP<0>")
	)
	(segment
		(start 13.227812 -194.57543)
		(end 16.53921 -191.264032)
		(width 0.14224)
		(layer "In6.Cu")
		(net "P3E_CPU1_P5_RX_DP<0>")
	)
	(segment
		(start 91.678506 -211.837016)
		(end 94.184978 -211.837016)
		(width 0.14224)
		(layer "In6.Cu")
		(net "P3E_CPU1_P5_RX_DP<0>")
	)
	(segment
		(start 16.53921 -191.264032)
		(end 59.903614 -191.264032)
		(width 0.14224)
		(layer "In6.Cu")
		(net "P3E_CPU1_P5_RX_DP<0>")
	)
	(segment
		(start 68.696332 -197.139052)
		(end 77.536548 -205.979268)
		(width 0.14224)
		(layer "In6.Cu")
		(net "P3E_CPU1_P5_RX_DP<0>")
	)
	(segment
		(start 77.536548 -205.979268)
		(end 91.678506 -211.837016)
		(width 0.14224)
		(layer "In6.Cu")
		(net "P3E_CPU1_P5_RX_DP<0>")
	)
	(segment
		(start 13.227812 -330.36002)
		(end 13.227812 -194.57543)
		(width 0.14224)
		(layer "In6.Cu")
		(net "P3E_CPU1_P5_RX_DP<0>")
	)
	(segment
		(start 23.894796 -349.435928)
		(end 23.894796 -346.324428)
		(width 0.14224)
		(layer "In6.Cu")
		(net "P3E_CPU1_P5_RX_DP<0>")
	)
	(segment
		(start 14.820646 -358.071674)
		(end 15.111476 -357.780844)
		(width 0.14224)
		(layer "In6.Cu")
		(net "P3E_CPU1_P5_RX_DP<0>")
	)
	(segment
		(start 15.54988 -357.780844)
		(end 23.894796 -349.435928)
		(width 0.14224)
		(layer "In6.Cu")
		(net "P3E_CPU1_P5_RX_DP<0>")
	)
	(segment
		(start 94.184978 -211.837016)
		(end 94.488 -212.140038)
		(width 0.14224)
		(layer "In6.Cu")
		(net "P3E_CPU1_P5_RX_DP<0>")
	)
	(segment
		(start 59.903614 -191.264032)
		(end 68.696332 -197.139052)
		(width 0.14224)
		(layer "In6.Cu")
		(net "P3E_CPU1_P5_RX_DP<0>")
	)
	(segment
		(start 15.111476 -357.780844)
		(end 15.54988 -357.780844)
		(width 0.14224)
		(layer "In6.Cu")
		(net "P3E_CPU1_P5_RX_DP<0>")
	)
	(segment
		(start 23.894796 -346.324428)
		(end 13.227812 -330.36002)
		(width 0.14224)
		(layer "In6.Cu")
		(net "P3E_CPU1_P5_RX_DP<0>")
	)
	(segment
		(start 97.654872 -204.963776)
		(end 97.223326 -205.142592)
		(width 0.12954)
		(layer "F.Cu")
		(net "P3E_CPU1_P5_RX_DN<1>")
	)
	(segment
		(start 111.236506 -224.898966)
		(end 111.519716 -224.615756)
		(width 0.0762)
		(layer "F.Cu")
		(net "P3E_CPU1_P5_RX_DN<1>")
	)
	(segment
		(start 95.15729 -208.430368)
		(end 94.758256 -208.430368)
		(width 0.12954)
		(layer "F.Cu")
		(net "P3E_CPU1_P5_RX_DN<1>")
	)
	(segment
		(start 111.626396 -224.602294)
		(end 111.751872 -224.476818)
		(width 0.12954)
		(layer "F.Cu")
		(net "P3E_CPU1_P5_RX_DN<1>")
	)
	(segment
		(start 94.758256 -208.430368)
		(end 94.487746 -208.159858)
		(width 0.12954)
		(layer "F.Cu")
		(net "P3E_CPU1_P5_RX_DN<1>")
	)
	(segment
		(start 95.433134 -208.154524)
		(end 95.15729 -208.430368)
		(width 0.12954)
		(layer "F.Cu")
		(net "P3E_CPU1_P5_RX_DN<1>")
	)
	(segment
		(start 111.443516 -220.758512)
		(end 104.776524 -212.040724)
		(width 0.12954)
		(layer "F.Cu")
		(net "P3E_CPU1_P5_RX_DN<1>")
	)
	(segment
		(start 110.17885 -224.989136)
		(end 110.18012 -224.988374)
		(width 0.0762)
		(layer "F.Cu")
		(net "P3E_CPU1_P5_RX_DN<1>")
	)
	(segment
		(start 111.751872 -224.476818)
		(end 111.821214 -224.311972)
		(width 0.12954)
		(layer "F.Cu")
		(net "P3E_CPU1_P5_RX_DN<1>")
	)
	(segment
		(start 110.180882 -224.987866)
		(end 110.189264 -224.98304)
		(width 0.0762)
		(layer "F.Cu")
		(net "P3E_CPU1_P5_RX_DN<1>")
	)
	(segment
		(start 110.050326 -225.310446)
		(end 109.99724 -225.25736)
		(width 0.0762)
		(layer "F.Cu")
		(net "P3E_CPU1_P5_RX_DN<1>")
	)
	(segment
		(start 110.367826 -225.310446)
		(end 110.050326 -225.310446)
		(width 0.0762)
		(layer "F.Cu")
		(net "P3E_CPU1_P5_RX_DN<1>")
	)
	(segment
		(start 111.821214 -224.311972)
		(end 111.854996 -224.10039)
		(width 0.12954)
		(layer "F.Cu")
		(net "P3E_CPU1_P5_RX_DN<1>")
	)
	(segment
		(start 111.854996 -224.10039)
		(end 111.624872 -221.293944)
		(width 0.12954)
		(layer "F.Cu")
		(net "P3E_CPU1_P5_RX_DN<1>")
	)
	(segment
		(start 111.519716 -224.615756)
		(end 111.613188 -224.615756)
		(width 0.0762)
		(layer "F.Cu")
		(net "P3E_CPU1_P5_RX_DN<1>")
	)
	(segment
		(start 110.149132 -225.006154)
		(end 110.17885 -224.989136)
		(width 0.0762)
		(layer "F.Cu")
		(net "P3E_CPU1_P5_RX_DN<1>")
	)
	(segment
		(start 111.613188 -224.615756)
		(end 111.62665 -224.602294)
		(width 0.0762)
		(layer "F.Cu")
		(net "P3E_CPU1_P5_RX_DN<1>")
	)
	(segment
		(start 111.624872 -221.293944)
		(end 111.443516 -220.758512)
		(width 0.12954)
		(layer "F.Cu")
		(net "P3E_CPU1_P5_RX_DN<1>")
	)
	(segment
		(start 96.87433 -205.458568)
		(end 95.433134 -208.154524)
		(width 0.12954)
		(layer "F.Cu")
		(net "P3E_CPU1_P5_RX_DN<1>")
	)
	(segment
		(start 98.124772 -204.963776)
		(end 97.654872 -204.963776)
		(width 0.12954)
		(layer "F.Cu")
		(net "P3E_CPU1_P5_RX_DN<1>")
	)
	(segment
		(start 111.62665 -224.602294)
		(end 111.626396 -224.602294)
		(width 0.0762)
		(layer "F.Cu")
		(net "P3E_CPU1_P5_RX_DN<1>")
	)
	(segment
		(start 110.18012 -224.988374)
		(end 110.180882 -224.987866)
		(width 0.0762)
		(layer "F.Cu")
		(net "P3E_CPU1_P5_RX_DN<1>")
	)
	(segment
		(start 104.776524 -212.040724)
		(end 98.851466 -205.264766)
		(width 0.12954)
		(layer "F.Cu")
		(net "P3E_CPU1_P5_RX_DN<1>")
	)
	(segment
		(start 97.223326 -205.142592)
		(end 96.87433 -205.458568)
		(width 0.12954)
		(layer "F.Cu")
		(net "P3E_CPU1_P5_RX_DN<1>")
	)
	(segment
		(start 98.851466 -205.264766)
		(end 98.124772 -204.963776)
		(width 0.12954)
		(layer "F.Cu")
		(net "P3E_CPU1_P5_RX_DN<1>")
	)
	(arc
		(start 111.120936 -224.987866)
		(mid 111.181609 -224.94717)
		(end 111.236506 -224.898966)
		(width 0.0762)
		(layer "F.Cu")
		(net "P3E_CPU1_P5_RX_DN<1>")
	)
	(arc
		(start 110.189264 -224.98304)
		(mid 110.372772 -224.937546)
		(end 110.555024 -224.987866)
		(width 0.0762)
		(layer "F.Cu")
		(net "P3E_CPU1_P5_RX_DN<1>")
	)
	(arc
		(start 110.555024 -224.987866)
		(mid 110.83798 -225.064043)
		(end 111.120936 -224.987866)
		(width 0.0762)
		(layer "F.Cu")
		(net "P3E_CPU1_P5_RX_DN<1>")
	)
	(arc
		(start 109.99724 -225.25736)
		(mid 110.047588 -225.116289)
		(end 110.149132 -225.006154)
		(width 0.0762)
		(layer "F.Cu")
		(net "P3E_CPU1_P5_RX_DN<1>")
	)
	(segment
		(start 76.275438 -414.628076)
		(end 94.54896 -414.628076)
		(width 0.14224)
		(layer "In2.Cu")
		(net "P3E_CPU1_P5_RX_DN<1>")
	)
	(segment
		(start 30.68447 -380.84125)
		(end 28.225242 -374.904254)
		(width 0.14224)
		(layer "In2.Cu")
		(net "P3E_CPU1_P5_RX_DN<1>")
	)
	(segment
		(start 97.437194 -406.311608)
		(end 96.221042 -405.095456)
		(width 0.14224)
		(layer "In2.Cu")
		(net "P3E_CPU1_P5_RX_DN<1>")
	)
	(segment
		(start 45.025056 -408.557984)
		(end 44.309538 -409.273502)
		(width 0.14224)
		(layer "In2.Cu")
		(net "P3E_CPU1_P5_RX_DN<1>")
	)
	(segment
		(start 46.09338 -404.0251)
		(end 46.09338 -405.979122)
		(width 0.14224)
		(layer "In2.Cu")
		(net "P3E_CPU1_P5_RX_DN<1>")
	)
	(segment
		(start 14.994636 -373.606314)
		(end 14.136624 -372.748302)
		(width 0.14224)
		(layer "In2.Cu")
		(net "P3E_CPU1_P5_RX_DN<1>")
	)
	(segment
		(start 14.136624 -360.355134)
		(end 13.625322 -359.843832)
		(width 0.14224)
		(layer "In2.Cu")
		(net "P3E_CPU1_P5_RX_DN<1>")
	)
	(segment
		(start 96.221042 -403.873462)
		(end 95.01886 -402.67128)
		(width 0.14224)
		(layer "In2.Cu")
		(net "P3E_CPU1_P5_RX_DN<1>")
	)
	(segment
		(start 35.77082 -406.948894)
		(end 33.602676 -396.048484)
		(width 0.14224)
		(layer "In2.Cu")
		(net "P3E_CPU1_P5_RX_DN<1>")
	)
	(segment
		(start 26.927302 -373.606314)
		(end 14.994636 -373.606314)
		(width 0.14224)
		(layer "In2.Cu")
		(net "P3E_CPU1_P5_RX_DN<1>")
	)
	(segment
		(start 14.136624 -372.748302)
		(end 14.136624 -360.355134)
		(width 0.14224)
		(layer "In2.Cu")
		(net "P3E_CPU1_P5_RX_DN<1>")
	)
	(segment
		(start 13.21435 -359.843832)
		(end 12.92352 -359.553002)
		(width 0.14224)
		(layer "In2.Cu")
		(net "P3E_CPU1_P5_RX_DN<1>")
	)
	(segment
		(start 46.205394 -403.753828)
		(end 46.09338 -404.0251)
		(width 0.14224)
		(layer "In2.Cu")
		(net "P3E_CPU1_P5_RX_DN<1>")
	)
	(segment
		(start 72.268842 -416.769804)
		(end 76.275438 -414.628076)
		(width 0.14224)
		(layer "In2.Cu")
		(net "P3E_CPU1_P5_RX_DN<1>")
	)
	(segment
		(start 71.734172 -417.304474)
		(end 72.268842 -416.769804)
		(width 0.14224)
		(layer "In2.Cu")
		(net "P3E_CPU1_P5_RX_DN<1>")
	)
	(segment
		(start 71.426832 -423.230802)
		(end 71.734172 -422.923462)
		(width 0.14224)
		(layer "In2.Cu")
		(net "P3E_CPU1_P5_RX_DN<1>")
	)
	(segment
		(start 31.458408 -392.037062)
		(end 31.458408 -384.73253)
		(width 0.14224)
		(layer "In2.Cu")
		(net "P3E_CPU1_P5_RX_DN<1>")
	)
	(segment
		(start 13.625322 -359.843832)
		(end 13.21435 -359.843832)
		(width 0.14224)
		(layer "In2.Cu")
		(net "P3E_CPU1_P5_RX_DN<1>")
	)
	(segment
		(start 70.649846 -423.68978)
		(end 71.108824 -423.230802)
		(width 0.14224)
		(layer "In2.Cu")
		(net "P3E_CPU1_P5_RX_DN<1>")
	)
	(segment
		(start 44.309538 -409.273502)
		(end 37.672772 -409.273502)
		(width 0.14224)
		(layer "In2.Cu")
		(net "P3E_CPU1_P5_RX_DN<1>")
	)
	(segment
		(start 46.09338 -405.979122)
		(end 45.025056 -408.557984)
		(width 0.14224)
		(layer "In2.Cu")
		(net "P3E_CPU1_P5_RX_DN<1>")
	)
	(segment
		(start 33.602676 -396.048484)
		(end 31.458408 -392.037062)
		(width 0.14224)
		(layer "In2.Cu")
		(net "P3E_CPU1_P5_RX_DN<1>")
	)
	(segment
		(start 71.734172 -422.923462)
		(end 71.734172 -417.304474)
		(width 0.14224)
		(layer "In2.Cu")
		(net "P3E_CPU1_P5_RX_DN<1>")
	)
	(segment
		(start 95.01886 -402.67128)
		(end 48.241458 -402.67128)
		(width 0.14224)
		(layer "In2.Cu")
		(net "P3E_CPU1_P5_RX_DN<1>")
	)
	(segment
		(start 94.54896 -414.628076)
		(end 96.684084 -412.492952)
		(width 0.14224)
		(layer "In2.Cu")
		(net "P3E_CPU1_P5_RX_DN<1>")
	)
	(segment
		(start 96.221042 -405.095456)
		(end 96.221042 -403.873462)
		(width 0.14224)
		(layer "In2.Cu")
		(net "P3E_CPU1_P5_RX_DN<1>")
	)
	(segment
		(start 97.437194 -410.67482)
		(end 97.437194 -406.311608)
		(width 0.14224)
		(layer "In2.Cu")
		(net "P3E_CPU1_P5_RX_DN<1>")
	)
	(segment
		(start 28.225242 -374.904254)
		(end 26.927302 -373.606314)
		(width 0.14224)
		(layer "In2.Cu")
		(net "P3E_CPU1_P5_RX_DN<1>")
	)
	(segment
		(start 46.614334 -403.345142)
		(end 46.205394 -403.753828)
		(width 0.14224)
		(layer "In2.Cu")
		(net "P3E_CPU1_P5_RX_DN<1>")
	)
	(segment
		(start 37.672772 -409.273502)
		(end 36.069524 -407.670254)
		(width 0.14224)
		(layer "In2.Cu")
		(net "P3E_CPU1_P5_RX_DN<1>")
	)
	(segment
		(start 31.458408 -384.73253)
		(end 30.68447 -380.84125)
		(width 0.14224)
		(layer "In2.Cu")
		(net "P3E_CPU1_P5_RX_DN<1>")
	)
	(segment
		(start 71.108824 -423.230802)
		(end 71.426832 -423.230802)
		(width 0.14224)
		(layer "In2.Cu")
		(net "P3E_CPU1_P5_RX_DN<1>")
	)
	(segment
		(start 36.069524 -407.670254)
		(end 35.77082 -406.948894)
		(width 0.14224)
		(layer "In2.Cu")
		(net "P3E_CPU1_P5_RX_DN<1>")
	)
	(segment
		(start 96.684084 -412.492952)
		(end 97.437194 -410.67482)
		(width 0.14224)
		(layer "In2.Cu")
		(net "P3E_CPU1_P5_RX_DN<1>")
	)
	(segment
		(start 48.241458 -402.67128)
		(end 46.614334 -403.345142)
		(width 0.14224)
		(layer "In2.Cu")
		(net "P3E_CPU1_P5_RX_DN<1>")
	)
	(segment
		(start 13.772134 -356.40899)
		(end 16.126714 -350.72447)
		(width 0.14224)
		(layer "In6.Cu")
		(net "P3E_CPU1_P5_RX_DN<1>")
	)
	(segment
		(start 16.126714 -345.550744)
		(end 11.983974 -331.894688)
		(width 0.14224)
		(layer "In6.Cu")
		(net "P3E_CPU1_P5_RX_DN<1>")
	)
	(segment
		(start 60.33389 -190.020194)
		(end 69.383402 -196.066918)
		(width 0.14224)
		(layer "In6.Cu")
		(net "P3E_CPU1_P5_RX_DN<1>")
	)
	(segment
		(start 94.19209 -208.455514)
		(end 94.487746 -208.159858)
		(width 0.14224)
		(layer "In6.Cu")
		(net "P3E_CPU1_P5_RX_DN<1>")
	)
	(segment
		(start 16.126714 -350.72447)
		(end 16.126714 -345.550744)
		(width 0.14224)
		(layer "In6.Cu")
		(net "P3E_CPU1_P5_RX_DN<1>")
	)
	(segment
		(start 16.023844 -190.020194)
		(end 60.33389 -190.020194)
		(width 0.14224)
		(layer "In6.Cu")
		(net "P3E_CPU1_P5_RX_DN<1>")
	)
	(segment
		(start 87.322152 -208.455514)
		(end 94.19209 -208.455514)
		(width 0.14224)
		(layer "In6.Cu")
		(net "P3E_CPU1_P5_RX_DN<1>")
	)
	(segment
		(start 11.983974 -194.060064)
		(end 16.023844 -190.020194)
		(width 0.14224)
		(layer "In6.Cu")
		(net "P3E_CPU1_P5_RX_DN<1>")
	)
	(segment
		(start 13.211302 -359.840784)
		(end 13.544804 -359.840784)
		(width 0.14224)
		(layer "In6.Cu")
		(net "P3E_CPU1_P5_RX_DN<1>")
	)
	(segment
		(start 12.92352 -359.553002)
		(end 13.211302 -359.840784)
		(width 0.14224)
		(layer "In6.Cu")
		(net "P3E_CPU1_P5_RX_DN<1>")
	)
	(segment
		(start 77.847444 -204.53096)
		(end 87.322152 -208.455514)
		(width 0.14224)
		(layer "In6.Cu")
		(net "P3E_CPU1_P5_RX_DN<1>")
	)
	(segment
		(start 11.983974 -331.894688)
		(end 11.983974 -194.060064)
		(width 0.14224)
		(layer "In6.Cu")
		(net "P3E_CPU1_P5_RX_DN<1>")
	)
	(segment
		(start 13.772134 -359.613454)
		(end 13.772134 -356.40899)
		(width 0.14224)
		(layer "In6.Cu")
		(net "P3E_CPU1_P5_RX_DN<1>")
	)
	(segment
		(start 13.544804 -359.840784)
		(end 13.772134 -359.613454)
		(width 0.14224)
		(layer "In6.Cu")
		(net "P3E_CPU1_P5_RX_DN<1>")
	)
	(segment
		(start 69.383402 -196.066918)
		(end 77.847444 -204.53096)
		(width 0.14224)
		(layer "In6.Cu")
		(net "P3E_CPU1_P5_RX_DN<1>")
	)
	(segment
		(start 107.329224 -225.006154)
		(end 107.329224 -225.006662)
		(width 0.0762)
		(layer "F.Cu")
		(net "P3E_CPU1_P5_RX_DN<0>")
	)
	(segment
		(start 106.460036 -222.415862)
		(end 106.38917 -222.374714)
		(width 0.0762)
		(layer "F.Cu")
		(net "P3E_CPU1_P5_RX_DN<0>")
	)
	(segment
		(start 107.39882 -224.966022)
		(end 107.41025 -224.957894)
		(width 0.0762)
		(layer "F.Cu")
		(net "P3E_CPU1_P5_RX_DN<0>")
	)
	(segment
		(start 106.89082 -223.203008)
		(end 106.86034 -223.185228)
		(width 0.0762)
		(layer "F.Cu")
		(net "P3E_CPU1_P5_RX_DN<0>")
	)
	(segment
		(start 107.363768 -224.014792)
		(end 107.360974 -224.013014)
		(width 0.0762)
		(layer "F.Cu")
		(net "P3E_CPU1_P5_RX_DN<0>")
	)
	(segment
		(start 106.23296 -222.070422)
		(end 106.23296 -221.616778)
		(width 0.0762)
		(layer "F.Cu")
		(net "P3E_CPU1_P5_RX_DN<0>")
	)
	(segment
		(start 107.329224 -225.006662)
		(end 107.39882 -224.966022)
		(width 0.0762)
		(layer "F.Cu")
		(net "P3E_CPU1_P5_RX_DN<0>")
	)
	(segment
		(start 94.75851 -211.546948)
		(end 94.488 -211.276438)
		(width 0.12954)
		(layer "F.Cu")
		(net "P3E_CPU1_P5_RX_DN<0>")
	)
	(segment
		(start 106.299 -221.550738)
		(end 106.299 -221.531688)
		(width 0.0762)
		(layer "F.Cu")
		(net "P3E_CPU1_P5_RX_DN<0>")
	)
	(segment
		(start 106.299 -221.531688)
		(end 106.299 -221.315788)
		(width 0.12954)
		(layer "F.Cu")
		(net "P3E_CPU1_P5_RX_DN<0>")
	)
	(segment
		(start 106.23296 -221.616778)
		(end 106.299 -221.550738)
		(width 0.0762)
		(layer "F.Cu")
		(net "P3E_CPU1_P5_RX_DN<0>")
	)
	(segment
		(start 95.314262 -211.546948)
		(end 94.75851 -211.546948)
		(width 0.12954)
		(layer "F.Cu")
		(net "P3E_CPU1_P5_RX_DN<0>")
	)
	(segment
		(start 107.547918 -225.310446)
		(end 107.230418 -225.310446)
		(width 0.0762)
		(layer "F.Cu")
		(net "P3E_CPU1_P5_RX_DN<0>")
	)
	(segment
		(start 107.398312 -224.034604)
		(end 107.363768 -224.014792)
		(width 0.0762)
		(layer "F.Cu")
		(net "P3E_CPU1_P5_RX_DN<0>")
	)
	(segment
		(start 106.929936 -223.225868)
		(end 106.89082 -223.203008)
		(width 0.0762)
		(layer "F.Cu")
		(net "P3E_CPU1_P5_RX_DN<0>")
	)
	(segment
		(start 107.360212 -224.012506)
		(end 107.329224 -223.994726)
		(width 0.0762)
		(layer "F.Cu")
		(net "P3E_CPU1_P5_RX_DN<0>")
	)
	(segment
		(start 107.360974 -224.013014)
		(end 107.360212 -224.012506)
		(width 0.0762)
		(layer "F.Cu")
		(net "P3E_CPU1_P5_RX_DN<0>")
	)
	(segment
		(start 106.299 -221.315788)
		(end 106.100372 -220.881194)
		(width 0.12954)
		(layer "F.Cu")
		(net "P3E_CPU1_P5_RX_DN<0>")
	)
	(segment
		(start 106.100372 -220.881194)
		(end 106.100118 -220.881194)
		(width 0.12954)
		(layer "F.Cu")
		(net "P3E_CPU1_P5_RX_DN<0>")
	)
	(segment
		(start 107.230418 -225.310446)
		(end 107.177332 -225.25736)
		(width 0.0762)
		(layer "F.Cu")
		(net "P3E_CPU1_P5_RX_DN<0>")
	)
	(segment
		(start 107.41025 -224.042986)
		(end 107.398312 -224.034604)
		(width 0.0762)
		(layer "F.Cu")
		(net "P3E_CPU1_P5_RX_DN<0>")
	)
	(segment
		(start 106.100118 -220.881194)
		(end 95.314262 -211.546948)
		(width 0.12954)
		(layer "F.Cu")
		(net "P3E_CPU1_P5_RX_DN<0>")
	)
	(arc
		(start 107.329224 -223.994726)
		(mid 107.214548 -223.861392)
		(end 107.173268 -223.690434)
		(width 0.0762)
		(layer "F.Cu")
		(net "P3E_CPU1_P5_RX_DN<0>")
	)
	(arc
		(start 107.41025 -224.957894)
		(mid 107.645816 -224.50044)
		(end 107.41025 -224.042986)
		(width 0.0762)
		(layer "F.Cu")
		(net "P3E_CPU1_P5_RX_DN<0>")
	)
	(arc
		(start 107.177332 -225.25736)
		(mid 107.22768 -225.116289)
		(end 107.329224 -225.006154)
		(width 0.0762)
		(layer "F.Cu")
		(net "P3E_CPU1_P5_RX_DN<0>")
	)
	(arc
		(start 107.173268 -223.690434)
		(mid 107.108753 -223.428215)
		(end 106.929936 -223.225868)
		(width 0.0762)
		(layer "F.Cu")
		(net "P3E_CPU1_P5_RX_DN<0>")
	)
	(arc
		(start 106.703368 -222.880428)
		(mid 106.638853 -222.618209)
		(end 106.460036 -222.415862)
		(width 0.0762)
		(layer "F.Cu")
		(net "P3E_CPU1_P5_RX_DN<0>")
	)
	(arc
		(start 106.38917 -222.374714)
		(mid 106.340238 -222.332626)
		(end 106.299254 -222.282766)
		(width 0.0762)
		(layer "F.Cu")
		(net "P3E_CPU1_P5_RX_DN<0>")
	)
	(arc
		(start 106.299254 -222.282766)
		(mid 106.249934 -222.181637)
		(end 106.23296 -222.070422)
		(width 0.0762)
		(layer "F.Cu")
		(net "P3E_CPU1_P5_RX_DN<0>")
	)
	(arc
		(start 106.86034 -223.185228)
		(mid 106.744913 -223.051852)
		(end 106.703368 -222.880428)
		(width 0.0762)
		(layer "F.Cu")
		(net "P3E_CPU1_P5_RX_DN<0>")
	)
	(segment
		(start 98.123502 -404.27402)
		(end 97.710244 -403.276562)
		(width 0.14224)
		(layer "In2.Cu")
		(net "P3E_CPU1_P5_RX_DN<0>")
	)
	(segment
		(start 38.590474 -391.513822)
		(end 38.590474 -389.145272)
		(width 0.14224)
		(layer "In2.Cu")
		(net "P3E_CPU1_P5_RX_DN<0>")
	)
	(segment
		(start 37.692838 -397.171672)
		(end 37.692838 -393.683236)
		(width 0.14224)
		(layer "In2.Cu")
		(net "P3E_CPU1_P5_RX_DN<0>")
	)
	(segment
		(start 98.551238 -404.701756)
		(end 98.123502 -404.27402)
		(width 0.14224)
		(layer "In2.Cu")
		(net "P3E_CPU1_P5_RX_DN<0>")
	)
	(segment
		(start 74.10196 -418.130482)
		(end 74.446892 -417.485576)
		(width 0.14224)
		(layer "In2.Cu")
		(net "P3E_CPU1_P5_RX_DN<0>")
	)
	(segment
		(start 27.292808 -372.648226)
		(end 16.758666 -372.648226)
		(width 0.14224)
		(layer "In2.Cu")
		(net "P3E_CPU1_P5_RX_DN<0>")
	)
	(segment
		(start 94.690438 -415.921444)
		(end 97.814384 -412.797498)
		(width 0.14224)
		(layer "In2.Cu")
		(net "P3E_CPU1_P5_RX_DN<0>")
	)
	(segment
		(start 38.590474 -389.145272)
		(end 38.198044 -388.197852)
		(width 0.14224)
		(layer "In2.Cu")
		(net "P3E_CPU1_P5_RX_DN<0>")
	)
	(segment
		(start 101.026722 -412.277814)
		(end 101.026722 -410.816806)
		(width 0.14224)
		(layer "In2.Cu")
		(net "P3E_CPU1_P5_RX_DN<0>")
	)
	(segment
		(start 101.026722 -410.816806)
		(end 100.091494 -406.11425)
		(width 0.14224)
		(layer "In2.Cu")
		(net "P3E_CPU1_P5_RX_DN<0>")
	)
	(segment
		(start 98.551238 -404.701502)
		(end 98.551238 -404.701756)
		(width 0.14224)
		(layer "In2.Cu")
		(net "P3E_CPU1_P5_RX_DN<0>")
	)
	(segment
		(start 100.091494 -406.11425)
		(end 99.896422 -405.643588)
		(width 0.14224)
		(layer "In2.Cu")
		(net "P3E_CPU1_P5_RX_DN<0>")
	)
	(segment
		(start 97.814384 -412.797498)
		(end 100.507038 -412.797498)
		(width 0.14224)
		(layer "In2.Cu")
		(net "P3E_CPU1_P5_RX_DN<0>")
	)
	(segment
		(start 29.247592 -374.60301)
		(end 27.292808 -372.648226)
		(width 0.14224)
		(layer "In2.Cu")
		(net "P3E_CPU1_P5_RX_DN<0>")
	)
	(segment
		(start 16.758666 -372.648226)
		(end 16.106394 -371.995954)
		(width 0.14224)
		(layer "In2.Cu")
		(net "P3E_CPU1_P5_RX_DN<0>")
	)
	(segment
		(start 38.198044 -388.197852)
		(end 31.497016 -380.032768)
		(width 0.14224)
		(layer "In2.Cu")
		(net "P3E_CPU1_P5_RX_DN<0>")
	)
	(segment
		(start 15.111476 -357.498904)
		(end 14.820646 -357.208074)
		(width 0.14224)
		(layer "In2.Cu")
		(net "P3E_CPU1_P5_RX_DN<0>")
	)
	(segment
		(start 74.446892 -417.485576)
		(end 76.788264 -415.921444)
		(width 0.14224)
		(layer "In2.Cu")
		(net "P3E_CPU1_P5_RX_DN<0>")
	)
	(segment
		(start 16.106394 -371.995954)
		(end 16.106394 -357.96347)
		(width 0.14224)
		(layer "In2.Cu")
		(net "P3E_CPU1_P5_RX_DN<0>")
	)
	(segment
		(start 45.902118 -401.000722)
		(end 39.613586 -399.09242)
		(width 0.14224)
		(layer "In2.Cu")
		(net "P3E_CPU1_P5_RX_DN<0>")
	)
	(segment
		(start 37.692838 -393.683236)
		(end 38.590474 -391.513822)
		(width 0.14224)
		(layer "In2.Cu")
		(net "P3E_CPU1_P5_RX_DN<0>")
	)
	(segment
		(start 46.700694 -401.000722)
		(end 45.902118 -401.000722)
		(width 0.14224)
		(layer "In2.Cu")
		(net "P3E_CPU1_P5_RX_DN<0>")
	)
	(segment
		(start 31.497016 -380.032768)
		(end 31.497016 -380.033022)
		(width 0.14224)
		(layer "In2.Cu")
		(net "P3E_CPU1_P5_RX_DN<0>")
	)
	(segment
		(start 94.587568 -400.153886)
		(end 48.745394 -400.153886)
		(width 0.14224)
		(layer "In2.Cu")
		(net "P3E_CPU1_P5_RX_DN<0>")
	)
	(segment
		(start 99.896422 -405.643588)
		(end 99.239832 -404.986998)
		(width 0.14224)
		(layer "In2.Cu")
		(net "P3E_CPU1_P5_RX_DN<0>")
	)
	(segment
		(start 39.613586 -399.09242)
		(end 37.692838 -397.171672)
		(width 0.14224)
		(layer "In2.Cu")
		(net "P3E_CPU1_P5_RX_DN<0>")
	)
	(segment
		(start 74.10196 -423.794428)
		(end 74.10196 -418.130482)
		(width 0.14224)
		(layer "In2.Cu")
		(net "P3E_CPU1_P5_RX_DN<0>")
	)
	(segment
		(start 15.641828 -357.498904)
		(end 15.111476 -357.498904)
		(width 0.14224)
		(layer "In2.Cu")
		(net "P3E_CPU1_P5_RX_DN<0>")
	)
	(segment
		(start 16.106394 -357.96347)
		(end 15.641828 -357.498904)
		(width 0.14224)
		(layer "In2.Cu")
		(net "P3E_CPU1_P5_RX_DN<0>")
	)
	(segment
		(start 72.649842 -424.689778)
		(end 73.10882 -424.2308)
		(width 0.14224)
		(layer "In2.Cu")
		(net "P3E_CPU1_P5_RX_DN<0>")
	)
	(segment
		(start 97.710244 -403.276562)
		(end 94.587568 -400.153886)
		(width 0.14224)
		(layer "In2.Cu")
		(net "P3E_CPU1_P5_RX_DN<0>")
	)
	(segment
		(start 73.665588 -424.2308)
		(end 74.10196 -423.794428)
		(width 0.14224)
		(layer "In2.Cu")
		(net "P3E_CPU1_P5_RX_DN<0>")
	)
	(segment
		(start 76.788264 -415.921444)
		(end 94.690438 -415.921444)
		(width 0.14224)
		(layer "In2.Cu")
		(net "P3E_CPU1_P5_RX_DN<0>")
	)
	(segment
		(start 48.745394 -400.153886)
		(end 46.700694 -401.000722)
		(width 0.14224)
		(layer "In2.Cu")
		(net "P3E_CPU1_P5_RX_DN<0>")
	)
	(segment
		(start 99.239832 -404.986998)
		(end 98.551238 -404.701502)
		(width 0.14224)
		(layer "In2.Cu")
		(net "P3E_CPU1_P5_RX_DN<0>")
	)
	(segment
		(start 31.497016 -380.033022)
		(end 29.247592 -374.60301)
		(width 0.14224)
		(layer "In2.Cu")
		(net "P3E_CPU1_P5_RX_DN<0>")
	)
	(segment
		(start 100.507038 -412.797498)
		(end 101.026722 -412.277814)
		(width 0.14224)
		(layer "In2.Cu")
		(net "P3E_CPU1_P5_RX_DN<0>")
	)
	(segment
		(start 73.10882 -424.2308)
		(end 73.665588 -424.2308)
		(width 0.14224)
		(layer "In2.Cu")
		(net "P3E_CPU1_P5_RX_DN<0>")
	)
	(segment
		(start 16.42237 -190.982092)
		(end 59.989212 -190.982092)
		(width 0.14224)
		(layer "In6.Cu")
		(net "P3E_CPU1_P5_RX_DN<0>")
	)
	(segment
		(start 68.876164 -196.920104)
		(end 77.696314 -205.740254)
		(width 0.14224)
		(layer "In6.Cu")
		(net "P3E_CPU1_P5_RX_DN<0>")
	)
	(segment
		(start 15.43304 -357.498904)
		(end 23.612856 -349.319088)
		(width 0.14224)
		(layer "In6.Cu")
		(net "P3E_CPU1_P5_RX_DN<0>")
	)
	(segment
		(start 91.73464 -211.555076)
		(end 94.209362 -211.555076)
		(width 0.14224)
		(layer "In6.Cu")
		(net "P3E_CPU1_P5_RX_DN<0>")
	)
	(segment
		(start 59.989212 -190.982092)
		(end 68.876164 -196.920104)
		(width 0.14224)
		(layer "In6.Cu")
		(net "P3E_CPU1_P5_RX_DN<0>")
	)
	(segment
		(start 94.209362 -211.555076)
		(end 94.488 -211.276438)
		(width 0.14224)
		(layer "In6.Cu")
		(net "P3E_CPU1_P5_RX_DN<0>")
	)
	(segment
		(start 14.820646 -357.208074)
		(end 15.111476 -357.498904)
		(width 0.14224)
		(layer "In6.Cu")
		(net "P3E_CPU1_P5_RX_DN<0>")
	)
	(segment
		(start 77.696314 -205.740254)
		(end 91.73464 -211.555076)
		(width 0.14224)
		(layer "In6.Cu")
		(net "P3E_CPU1_P5_RX_DN<0>")
	)
	(segment
		(start 23.612856 -346.410026)
		(end 12.945872 -330.445618)
		(width 0.14224)
		(layer "In6.Cu")
		(net "P3E_CPU1_P5_RX_DN<0>")
	)
	(segment
		(start 12.945872 -194.45859)
		(end 16.42237 -190.982092)
		(width 0.14224)
		(layer "In6.Cu")
		(net "P3E_CPU1_P5_RX_DN<0>")
	)
	(segment
		(start 12.945872 -330.445618)
		(end 12.945872 -194.45859)
		(width 0.14224)
		(layer "In6.Cu")
		(net "P3E_CPU1_P5_RX_DN<0>")
	)
	(segment
		(start 23.612856 -349.319088)
		(end 23.612856 -346.410026)
		(width 0.14224)
		(layer "In6.Cu")
		(net "P3E_CPU1_P5_RX_DN<0>")
	)
	(segment
		(start 15.111476 -357.498904)
		(end 15.43304 -357.498904)
		(width 0.14224)
		(layer "In6.Cu")
		(net "P3E_CPU1_P5_RX_DN<0>")
	)
	(segment
		(start 106.907838 -292.450266)
		(end 106.440986 -292.716204)
		(width 0.12954)
		(layer "F.Cu")
		(net "P3E_CPU1_P4_TX_DP<3>")
	)
	(segment
		(start 181.084982 -53.355748)
		(end 181.777132 -53.355748)
		(width 0.12954)
		(layer "F.Cu")
		(net "P3E_CPU1_P4_TX_DP<3>")
	)
	(segment
		(start 181.777132 -53.355748)
		(end 182.041546 -53.091334)
		(width 0.12954)
		(layer "F.Cu")
		(net "P3E_CPU1_P4_TX_DP<3>")
	)
	(segment
		(start 180.795168 -53.065934)
		(end 181.084982 -53.355748)
		(width 0.12954)
		(layer "F.Cu")
		(net "P3E_CPU1_P4_TX_DP<3>")
	)
	(segment
		(start 100.869496 -313.826906)
		(end 100.567998 -314.128404)
		(width 0.14224)
		(layer "In2.Cu")
		(net "P3E_CPU1_P4_TX_DP<3>")
	)
	(segment
		(start 103.610664 -309.801514)
		(end 103.68788 -309.975504)
		(width 0.14224)
		(layer "In2.Cu")
		(net "P3E_CPU1_P4_TX_DP<3>")
	)
	(segment
		(start 99.013772 -314.43549)
		(end 98.71202 -314.133738)
		(width 0.14224)
		(layer "In2.Cu")
		(net "P3E_CPU1_P4_TX_DP<3>")
	)
	(segment
		(start 103.203502 -310.850534)
		(end 103.281988 -311.027826)
		(width 0.14224)
		(layer "In2.Cu")
		(net "P3E_CPU1_P4_TX_DP<3>")
	)
	(segment
		(start 106.440986 -292.716204)
		(end 106.738928 -292.716204)
		(width 0.1143)
		(layer "In2.Cu")
		(net "P3E_CPU1_P4_TX_DP<3>")
	)
	(segment
		(start 100.869496 -313.63285)
		(end 100.869496 -313.826906)
		(width 0.14224)
		(layer "In2.Cu")
		(net "P3E_CPU1_P4_TX_DP<3>")
	)
	(segment
		(start 107.10291 -293.206678)
		(end 107.104688 -293.207694)
		(width 0.1143)
		(layer "In2.Cu")
		(net "P3E_CPU1_P4_TX_DP<3>")
	)
	(segment
		(start 101.365558 -313.330844)
		(end 101.171502 -313.330844)
		(width 0.14224)
		(layer "In2.Cu")
		(net "P3E_CPU1_P4_TX_DP<3>")
	)
	(segment
		(start 101.849428 -312.846974)
		(end 101.365558 -313.330844)
		(width 0.14224)
		(layer "In2.Cu")
		(net "P3E_CPU1_P4_TX_DP<3>")
	)
	(segment
		(start 101.171502 -313.330844)
		(end 100.869496 -313.63285)
		(width 0.14224)
		(layer "In2.Cu")
		(net "P3E_CPU1_P4_TX_DP<3>")
	)
	(segment
		(start 107.107228 -293.209218)
		(end 107.108752 -293.210234)
		(width 0.1143)
		(layer "In2.Cu")
		(net "P3E_CPU1_P4_TX_DP<3>")
	)
	(segment
		(start 103.039418 -311.657238)
		(end 102.345236 -312.351166)
		(width 0.14224)
		(layer "In2.Cu")
		(net "P3E_CPU1_P4_TX_DP<3>")
	)
	(segment
		(start 107.149646 -300.99889)
		(end 103.938578 -309.326026)
		(width 0.14224)
		(layer "In2.Cu")
		(net "P3E_CPU1_P4_TX_DP<3>")
	)
	(segment
		(start 103.764334 -309.402988)
		(end 103.610664 -309.801514)
		(width 0.14224)
		(layer "In2.Cu")
		(net "P3E_CPU1_P4_TX_DP<3>")
	)
	(segment
		(start 102.151434 -312.351166)
		(end 101.849428 -312.653172)
		(width 0.14224)
		(layer "In2.Cu")
		(net "P3E_CPU1_P4_TX_DP<3>")
	)
	(segment
		(start 107.098846 -293.848282)
		(end 107.090972 -293.852854)
		(width 0.1143)
		(layer "In2.Cu")
		(net "P3E_CPU1_P4_TX_DP<3>")
	)
	(segment
		(start 101.849428 -312.653172)
		(end 101.849428 -312.846974)
		(width 0.14224)
		(layer "In2.Cu")
		(net "P3E_CPU1_P4_TX_DP<3>")
	)
	(segment
		(start 106.30027 -295.530524)
		(end 106.30027 -296.237406)
		(width 0.14224)
		(layer "In2.Cu")
		(net "P3E_CPU1_P4_TX_DP<3>")
	)
	(segment
		(start 106.34599 -295.17975)
		(end 106.34599 -295.456356)
		(width 0.1143)
		(layer "In2.Cu")
		(net "P3E_CPU1_P4_TX_DP<3>")
	)
	(segment
		(start 107.129834 -293.830502)
		(end 107.098846 -293.848282)
		(width 0.1143)
		(layer "In2.Cu")
		(net "P3E_CPU1_P4_TX_DP<3>")
	)
	(segment
		(start 103.68788 -309.975504)
		(end 103.534464 -310.373522)
		(width 0.14224)
		(layer "In2.Cu")
		(net "P3E_CPU1_P4_TX_DP<3>")
	)
	(segment
		(start 103.356918 -310.452262)
		(end 103.203502 -310.850534)
		(width 0.14224)
		(layer "In2.Cu")
		(net "P3E_CPU1_P4_TX_DP<3>")
	)
	(segment
		(start 106.659934 -294.638476)
		(end 106.601514 -294.68064)
		(width 0.1143)
		(layer "In2.Cu")
		(net "P3E_CPU1_P4_TX_DP<3>")
	)
	(segment
		(start 106.34599 -295.456356)
		(end 106.30027 -295.502076)
		(width 0.1143)
		(layer "In2.Cu")
		(net "P3E_CPU1_P4_TX_DP<3>")
	)
	(segment
		(start 100.567998 -314.128404)
		(end 99.826318 -314.43549)
		(width 0.14224)
		(layer "In2.Cu")
		(net "P3E_CPU1_P4_TX_DP<3>")
	)
	(segment
		(start 107.119928 -293.21633)
		(end 107.122468 -293.217854)
		(width 0.1143)
		(layer "In2.Cu")
		(net "P3E_CPU1_P4_TX_DP<3>")
	)
	(segment
		(start 107.066588 -293.185342)
		(end 107.098084 -293.20363)
		(width 0.1143)
		(layer "In2.Cu")
		(net "P3E_CPU1_P4_TX_DP<3>")
	)
	(segment
		(start 107.122468 -293.217854)
		(end 107.124754 -293.219124)
		(width 0.1143)
		(layer "In2.Cu")
		(net "P3E_CPU1_P4_TX_DP<3>")
	)
	(segment
		(start 106.30027 -295.502076)
		(end 106.30027 -295.530524)
		(width 0.1143)
		(layer "In2.Cu")
		(net "P3E_CPU1_P4_TX_DP<3>")
	)
	(segment
		(start 107.100624 -293.205154)
		(end 107.10291 -293.206678)
		(width 0.1143)
		(layer "In2.Cu")
		(net "P3E_CPU1_P4_TX_DP<3>")
	)
	(segment
		(start 107.099608 -293.204646)
		(end 107.100624 -293.205154)
		(width 0.1143)
		(layer "In2.Cu")
		(net "P3E_CPU1_P4_TX_DP<3>")
	)
	(segment
		(start 107.058968 -293.18077)
		(end 107.066588 -293.185342)
		(width 0.1143)
		(layer "In2.Cu")
		(net "P3E_CPU1_P4_TX_DP<3>")
	)
	(segment
		(start 107.119166 -293.215822)
		(end 107.119928 -293.21633)
		(width 0.1143)
		(layer "In2.Cu")
		(net "P3E_CPU1_P4_TX_DP<3>")
	)
	(segment
		(start 107.149646 -297.086782)
		(end 107.149646 -300.99889)
		(width 0.14224)
		(layer "In2.Cu")
		(net "P3E_CPU1_P4_TX_DP<3>")
	)
	(segment
		(start 107.110276 -293.210996)
		(end 107.117388 -293.214806)
		(width 0.1143)
		(layer "In2.Cu")
		(net "P3E_CPU1_P4_TX_DP<3>")
	)
	(segment
		(start 107.117388 -293.214806)
		(end 107.11815 -293.215314)
		(width 0.1143)
		(layer "In2.Cu")
		(net "P3E_CPU1_P4_TX_DP<3>")
	)
	(segment
		(start 107.126532 -293.22014)
		(end 107.129834 -293.221918)
		(width 0.1143)
		(layer "In2.Cu")
		(net "P3E_CPU1_P4_TX_DP<3>")
	)
	(segment
		(start 106.30027 -296.237406)
		(end 107.149646 -297.086782)
		(width 0.14224)
		(layer "In2.Cu")
		(net "P3E_CPU1_P4_TX_DP<3>")
	)
	(segment
		(start 107.11815 -293.215314)
		(end 107.119166 -293.215822)
		(width 0.1143)
		(layer "In2.Cu")
		(net "P3E_CPU1_P4_TX_DP<3>")
	)
	(segment
		(start 107.124754 -293.219124)
		(end 107.126532 -293.22014)
		(width 0.1143)
		(layer "In2.Cu")
		(net "P3E_CPU1_P4_TX_DP<3>")
	)
	(segment
		(start 107.108752 -293.210234)
		(end 107.110276 -293.210996)
		(width 0.1143)
		(layer "In2.Cu")
		(net "P3E_CPU1_P4_TX_DP<3>")
	)
	(segment
		(start 99.826318 -314.43549)
		(end 99.013772 -314.43549)
		(width 0.14224)
		(layer "In2.Cu")
		(net "P3E_CPU1_P4_TX_DP<3>")
	)
	(segment
		(start 102.345236 -312.351166)
		(end 102.151434 -312.351166)
		(width 0.14224)
		(layer "In2.Cu")
		(net "P3E_CPU1_P4_TX_DP<3>")
	)
	(segment
		(start 107.098084 -293.20363)
		(end 107.099608 -293.204646)
		(width 0.1143)
		(layer "In2.Cu")
		(net "P3E_CPU1_P4_TX_DP<3>")
	)
	(segment
		(start 103.534464 -310.373522)
		(end 103.356918 -310.452262)
		(width 0.14224)
		(layer "In2.Cu")
		(net "P3E_CPU1_P4_TX_DP<3>")
	)
	(segment
		(start 103.281988 -311.027826)
		(end 103.039418 -311.657238)
		(width 0.14224)
		(layer "In2.Cu")
		(net "P3E_CPU1_P4_TX_DP<3>")
	)
	(segment
		(start 106.738928 -292.716204)
		(end 106.821732 -292.799008)
		(width 0.1143)
		(layer "In2.Cu")
		(net "P3E_CPU1_P4_TX_DP<3>")
	)
	(segment
		(start 103.938578 -309.326026)
		(end 103.764334 -309.402988)
		(width 0.14224)
		(layer "In2.Cu")
		(net "P3E_CPU1_P4_TX_DP<3>")
	)
	(segment
		(start 106.660188 -294.638476)
		(end 106.659934 -294.638476)
		(width 0.1143)
		(layer "In2.Cu")
		(net "P3E_CPU1_P4_TX_DP<3>")
	)
	(segment
		(start 107.104688 -293.207694)
		(end 107.107228 -293.209218)
		(width 0.1143)
		(layer "In2.Cu")
		(net "P3E_CPU1_P4_TX_DP<3>")
	)
	(segment
		(start 107.090972 -293.852854)
		(end 107.058968 -293.87165)
		(width 0.1143)
		(layer "In2.Cu")
		(net "P3E_CPU1_P4_TX_DP<3>")
	)
	(arc
		(start 106.825542 -292.821868)
		(mid 106.906975 -293.024266)
		(end 107.058968 -293.18077)
		(width 0.1143)
		(layer "In2.Cu")
		(net "P3E_CPU1_P4_TX_DP<3>")
	)
	(arc
		(start 106.821732 -292.799008)
		(mid 106.82352 -292.810457)
		(end 106.825542 -292.821868)
		(width 0.1143)
		(layer "In2.Cu")
		(net "P3E_CPU1_P4_TX_DP<3>")
	)
	(arc
		(start 106.81589 -294.335454)
		(mid 106.774394 -294.505629)
		(end 106.660188 -294.638476)
		(width 0.1143)
		(layer "In2.Cu")
		(net "P3E_CPU1_P4_TX_DP<3>")
	)
	(arc
		(start 107.050332 -293.877746)
		(mid 106.878314 -294.078548)
		(end 106.81589 -294.335454)
		(width 0.1143)
		(layer "In2.Cu")
		(net "P3E_CPU1_P4_TX_DP<3>")
	)
	(arc
		(start 106.601514 -294.68064)
		(mid 106.413652 -294.899413)
		(end 106.34599 -295.17975)
		(width 0.1143)
		(layer "In2.Cu")
		(net "P3E_CPU1_P4_TX_DP<3>")
	)
	(arc
		(start 107.058968 -293.87165)
		(mid 107.054635 -293.874677)
		(end 107.050332 -293.877746)
		(width 0.1143)
		(layer "In2.Cu")
		(net "P3E_CPU1_P4_TX_DP<3>")
	)
	(arc
		(start 107.129834 -293.221918)
		(mid 107.281423 -293.52621)
		(end 107.129834 -293.830502)
		(width 0.1143)
		(layer "In2.Cu")
		(net "P3E_CPU1_P4_TX_DP<3>")
	)
	(segment
		(start 152.967182 -64.23152)
		(end 161.442146 -65.739264)
		(width 0.14224)
		(layer "In6.Cu")
		(net "P3E_CPU1_P4_TX_DP<3>")
	)
	(segment
		(start 161.442146 -65.739264)
		(end 168.371012 -64.51727)
		(width 0.14224)
		(layer "In6.Cu")
		(net "P3E_CPU1_P4_TX_DP<3>")
	)
	(segment
		(start 116.478558 -68.24091)
		(end 152.967182 -64.23152)
		(width 0.14224)
		(layer "In6.Cu")
		(net "P3E_CPU1_P4_TX_DP<3>")
	)
	(segment
		(start 177.223928 -57.7596)
		(end 177.223928 -53.936646)
		(width 0.14224)
		(layer "In6.Cu")
		(net "P3E_CPU1_P4_TX_DP<3>")
	)
	(segment
		(start 27.112722 -169.171874)
		(end 27.449272 -168.94683)
		(width 0.14224)
		(layer "In6.Cu")
		(net "P3E_CPU1_P4_TX_DP<3>")
	)
	(segment
		(start 177.77841 -53.382164)
		(end 181.750716 -53.382164)
		(width 0.14224)
		(layer "In6.Cu")
		(net "P3E_CPU1_P4_TX_DP<3>")
	)
	(segment
		(start 86.678516 -98.604578)
		(end 101.645974 -77.2287)
		(width 0.14224)
		(layer "In6.Cu")
		(net "P3E_CPU1_P4_TX_DP<3>")
	)
	(segment
		(start 181.750716 -53.382164)
		(end 182.041546 -53.091334)
		(width 0.14224)
		(layer "In6.Cu")
		(net "P3E_CPU1_P4_TX_DP<3>")
	)
	(segment
		(start 9.919716 -178.045618)
		(end 15.056358 -175.616108)
		(width 0.14224)
		(layer "In6.Cu")
		(net "P3E_CPU1_P4_TX_DP<3>")
	)
	(segment
		(start 27.449272 -168.94683)
		(end 40.77335 -155.622752)
		(width 0.14224)
		(layer "In6.Cu")
		(net "P3E_CPU1_P4_TX_DP<3>")
	)
	(segment
		(start 40.77335 -155.622752)
		(end 48.631348 -136.651746)
		(width 0.14224)
		(layer "In6.Cu")
		(net "P3E_CPU1_P4_TX_DP<3>")
	)
	(segment
		(start 9.106408 -177.754788)
		(end 9.397238 -178.045618)
		(width 0.14224)
		(layer "In6.Cu")
		(net "P3E_CPU1_P4_TX_DP<3>")
	)
	(segment
		(start 168.371012 -64.51727)
		(end 175.35779 -59.625738)
		(width 0.14224)
		(layer "In6.Cu")
		(net "P3E_CPU1_P4_TX_DP<3>")
	)
	(segment
		(start 113.80978 -68.711572)
		(end 116.478558 -68.24091)
		(width 0.14224)
		(layer "In6.Cu")
		(net "P3E_CPU1_P4_TX_DP<3>")
	)
	(segment
		(start 177.223928 -53.936646)
		(end 177.77841 -53.382164)
		(width 0.14224)
		(layer "In6.Cu")
		(net "P3E_CPU1_P4_TX_DP<3>")
	)
	(segment
		(start 9.397238 -178.045618)
		(end 9.919716 -178.045618)
		(width 0.14224)
		(layer "In6.Cu")
		(net "P3E_CPU1_P4_TX_DP<3>")
	)
	(segment
		(start 175.35779 -59.625738)
		(end 177.223928 -57.7596)
		(width 0.14224)
		(layer "In6.Cu")
		(net "P3E_CPU1_P4_TX_DP<3>")
	)
	(segment
		(start 15.056358 -175.616108)
		(end 27.112722 -169.171874)
		(width 0.14224)
		(layer "In6.Cu")
		(net "P3E_CPU1_P4_TX_DP<3>")
	)
	(segment
		(start 48.631348 -136.651746)
		(end 86.678516 -98.604578)
		(width 0.14224)
		(layer "In6.Cu")
		(net "P3E_CPU1_P4_TX_DP<3>")
	)
	(segment
		(start 101.645974 -77.2287)
		(end 113.80978 -68.711572)
		(width 0.14224)
		(layer "In6.Cu")
		(net "P3E_CPU1_P4_TX_DP<3>")
	)
	(segment
		(start 98.42119 -314.424568)
		(end 93.441266 -314.424568)
		(width 0.14224)
		(layer "In15.Cu")
		(net "P3E_CPU1_P4_TX_DP<3>")
	)
	(segment
		(start 87.002366 -314.741306)
		(end 71.177404 -315.518546)
		(width 0.14224)
		(layer "In15.Cu")
		(net "P3E_CPU1_P4_TX_DP<3>")
	)
	(segment
		(start 12.01039 -308.16169)
		(end 11.868404 -308.029356)
		(width 0.14224)
		(layer "In15.Cu")
		(net "P3E_CPU1_P4_TX_DP<3>")
	)
	(segment
		(start 11.906504 -309.151528)
		(end 11.89228 -308.727602)
		(width 0.14224)
		(layer "In15.Cu")
		(net "P3E_CPU1_P4_TX_DP<3>")
	)
	(segment
		(start 15.703296 -322.026026)
		(end 14.407642 -320.730372)
		(width 0.14224)
		(layer "In15.Cu")
		(net "P3E_CPU1_P4_TX_DP<3>")
	)
	(segment
		(start 11.97229 -307.039518)
		(end 11.830304 -306.907184)
		(width 0.14224)
		(layer "In15.Cu")
		(net "P3E_CPU1_P4_TX_DP<3>")
	)
	(segment
		(start 11.986768 -307.463952)
		(end 11.97229 -307.039518)
		(width 0.14224)
		(layer "In15.Cu")
		(net "P3E_CPU1_P4_TX_DP<3>")
	)
	(segment
		(start 93.441266 -314.424568)
		(end 93.441012 -314.424822)
		(width 0.14224)
		(layer "In15.Cu")
		(net "P3E_CPU1_P4_TX_DP<3>")
	)
	(segment
		(start 10.109962 -181.896258)
		(end 10.109962 -178.440334)
		(width 0.14224)
		(layer "In15.Cu")
		(net "P3E_CPU1_P4_TX_DP<3>")
	)
	(segment
		(start 12.101068 -310.830468)
		(end 12.08659 -310.406034)
		(width 0.14224)
		(layer "In15.Cu")
		(net "P3E_CPU1_P4_TX_DP<3>")
	)
	(segment
		(start 19.047206 -322.61556)
		(end 15.703296 -322.026026)
		(width 0.14224)
		(layer "In15.Cu")
		(net "P3E_CPU1_P4_TX_DP<3>")
	)
	(segment
		(start 14.407642 -320.730372)
		(end 13.314934 -318.09182)
		(width 0.14224)
		(layer "In15.Cu")
		(net "P3E_CPU1_P4_TX_DP<3>")
	)
	(segment
		(start 93.441012 -314.424822)
		(end 87.002366 -314.741052)
		(width 0.14224)
		(layer "In15.Cu")
		(net "P3E_CPU1_P4_TX_DP<3>")
	)
	(segment
		(start 11.93038 -309.849774)
		(end 12.062968 -309.708296)
		(width 0.14224)
		(layer "In15.Cu")
		(net "P3E_CPU1_P4_TX_DP<3>")
	)
	(segment
		(start 12.062968 -309.708296)
		(end 12.04849 -309.283862)
		(width 0.14224)
		(layer "In15.Cu")
		(net "P3E_CPU1_P4_TX_DP<3>")
	)
	(segment
		(start 10.109962 -178.440334)
		(end 9.715246 -178.045618)
		(width 0.14224)
		(layer "In15.Cu")
		(net "P3E_CPU1_P4_TX_DP<3>")
	)
	(segment
		(start 11.868404 -308.029356)
		(end 11.85418 -307.60543)
		(width 0.14224)
		(layer "In15.Cu")
		(net "P3E_CPU1_P4_TX_DP<3>")
	)
	(segment
		(start 60.274962 -322.803774)
		(end 58.691272 -322.803774)
		(width 0.14224)
		(layer "In15.Cu")
		(net "P3E_CPU1_P4_TX_DP<3>")
	)
	(segment
		(start 9.397238 -178.045618)
		(end 9.106408 -177.754788)
		(width 0.14224)
		(layer "In15.Cu")
		(net "P3E_CPU1_P4_TX_DP<3>")
	)
	(segment
		(start 9.715246 -178.045618)
		(end 9.397238 -178.045618)
		(width 0.14224)
		(layer "In15.Cu")
		(net "P3E_CPU1_P4_TX_DP<3>")
	)
	(segment
		(start 11.982704 -311.395872)
		(end 11.96848 -310.971946)
		(width 0.14224)
		(layer "In15.Cu")
		(net "P3E_CPU1_P4_TX_DP<3>")
	)
	(segment
		(start 8.819642 -217.82659)
		(end 10.05713 -183.36768)
		(width 0.14224)
		(layer "In15.Cu")
		(net "P3E_CPU1_P4_TX_DP<3>")
	)
	(segment
		(start 12.024868 -308.586124)
		(end 12.01039 -308.16169)
		(width 0.14224)
		(layer "In15.Cu")
		(net "P3E_CPU1_P4_TX_DP<3>")
	)
	(segment
		(start 10.05713 -183.36768)
		(end 10.109962 -181.896258)
		(width 0.14224)
		(layer "In15.Cu")
		(net "P3E_CPU1_P4_TX_DP<3>")
	)
	(segment
		(start 11.830304 -306.907184)
		(end 8.819642 -217.82659)
		(width 0.14224)
		(layer "In15.Cu")
		(net "P3E_CPU1_P4_TX_DP<3>")
	)
	(segment
		(start 71.177404 -315.518546)
		(end 60.274962 -322.803774)
		(width 0.14224)
		(layer "In15.Cu")
		(net "P3E_CPU1_P4_TX_DP<3>")
	)
	(segment
		(start 98.71202 -314.133738)
		(end 98.42119 -314.424568)
		(width 0.14224)
		(layer "In15.Cu")
		(net "P3E_CPU1_P4_TX_DP<3>")
	)
	(segment
		(start 13.314934 -318.09182)
		(end 11.982704 -311.395872)
		(width 0.14224)
		(layer "In15.Cu")
		(net "P3E_CPU1_P4_TX_DP<3>")
	)
	(segment
		(start 87.002366 -314.741052)
		(end 87.002366 -314.741306)
		(width 0.14224)
		(layer "In15.Cu")
		(net "P3E_CPU1_P4_TX_DP<3>")
	)
	(segment
		(start 11.96848 -310.971946)
		(end 12.101068 -310.830468)
		(width 0.14224)
		(layer "In15.Cu")
		(net "P3E_CPU1_P4_TX_DP<3>")
	)
	(segment
		(start 11.85418 -307.60543)
		(end 11.986768 -307.463952)
		(width 0.14224)
		(layer "In15.Cu")
		(net "P3E_CPU1_P4_TX_DP<3>")
	)
	(segment
		(start 11.944604 -310.2737)
		(end 11.93038 -309.849774)
		(width 0.14224)
		(layer "In15.Cu")
		(net "P3E_CPU1_P4_TX_DP<3>")
	)
	(segment
		(start 12.08659 -310.406034)
		(end 11.944604 -310.2737)
		(width 0.14224)
		(layer "In15.Cu")
		(net "P3E_CPU1_P4_TX_DP<3>")
	)
	(segment
		(start 12.04849 -309.283862)
		(end 11.906504 -309.151528)
		(width 0.14224)
		(layer "In15.Cu")
		(net "P3E_CPU1_P4_TX_DP<3>")
	)
	(segment
		(start 11.89228 -308.727602)
		(end 12.024868 -308.586124)
		(width 0.14224)
		(layer "In15.Cu")
		(net "P3E_CPU1_P4_TX_DP<3>")
	)
	(segment
		(start 58.691272 -322.803774)
		(end 19.047206 -322.61556)
		(width 0.14224)
		(layer "In15.Cu")
		(net "P3E_CPU1_P4_TX_DP<3>")
	)
	(segment
		(start 104.08793 -292.450266)
		(end 103.621078 -292.716204)
		(width 0.12954)
		(layer "F.Cu")
		(net "P3E_CPU1_P4_TX_DP<2>")
	)
	(segment
		(start 181.084982 -50.349912)
		(end 181.777132 -50.349912)
		(width 0.12954)
		(layer "F.Cu")
		(net "P3E_CPU1_P4_TX_DP<2>")
	)
	(segment
		(start 180.795168 -50.060098)
		(end 181.084982 -50.349912)
		(width 0.12954)
		(layer "F.Cu")
		(net "P3E_CPU1_P4_TX_DP<2>")
	)
	(segment
		(start 181.777132 -50.349912)
		(end 182.041546 -50.085498)
		(width 0.12954)
		(layer "F.Cu")
		(net "P3E_CPU1_P4_TX_DP<2>")
	)
	(segment
		(start 100.080064 -310.030876)
		(end 99.598226 -310.030876)
		(width 0.14224)
		(layer "In2.Cu")
		(net "P3E_CPU1_P4_TX_DP<2>")
	)
	(segment
		(start 103.67518 -296.700702)
		(end 103.67518 -296.72915)
		(width 0.1143)
		(layer "In2.Cu")
		(net "P3E_CPU1_P4_TX_DP<2>")
	)
	(segment
		(start 103.91902 -292.716204)
		(end 104.001824 -292.799008)
		(width 0.1143)
		(layer "In2.Cu")
		(net "P3E_CPU1_P4_TX_DP<2>")
	)
	(segment
		(start 103.525828 -295.146222)
		(end 103.525828 -295.450514)
		(width 0.1143)
		(layer "In2.Cu")
		(net "P3E_CPU1_P4_TX_DP<2>")
	)
	(segment
		(start 103.7209 -296.09161)
		(end 103.7209 -296.654982)
		(width 0.1143)
		(layer "In2.Cu")
		(net "P3E_CPU1_P4_TX_DP<2>")
	)
	(segment
		(start 103.67518 -297.733212)
		(end 104.073198 -298.694094)
		(width 0.14224)
		(layer "In2.Cu")
		(net "P3E_CPU1_P4_TX_DP<2>")
	)
	(segment
		(start 101.137212 -307.23967)
		(end 101.215698 -307.416962)
		(width 0.14224)
		(layer "In2.Cu")
		(net "P3E_CPU1_P4_TX_DP<2>")
	)
	(segment
		(start 104.241854 -293.182802)
		(end 104.277668 -293.203376)
		(width 0.1143)
		(layer "In2.Cu")
		(net "P3E_CPU1_P4_TX_DP<2>")
	)
	(segment
		(start 101.290628 -306.841144)
		(end 101.137212 -307.23967)
		(width 0.14224)
		(layer "In2.Cu")
		(net "P3E_CPU1_P4_TX_DP<2>")
	)
	(segment
		(start 101.62159 -306.36464)
		(end 101.468174 -306.762658)
		(width 0.14224)
		(layer "In2.Cu")
		(net "P3E_CPU1_P4_TX_DP<2>")
	)
	(segment
		(start 104.309926 -293.830502)
		(end 104.280208 -293.84752)
		(width 0.1143)
		(layer "In2.Cu")
		(net "P3E_CPU1_P4_TX_DP<2>")
	)
	(segment
		(start 100.24999 -309.919624)
		(end 100.242624 -309.93334)
		(width 0.14224)
		(layer "In2.Cu")
		(net "P3E_CPU1_P4_TX_DP<2>")
	)
	(segment
		(start 100.403406 -309.521606)
		(end 100.24999 -309.919624)
		(width 0.14224)
		(layer "In2.Cu")
		(net "P3E_CPU1_P4_TX_DP<2>")
	)
	(segment
		(start 101.874066 -305.710336)
		(end 101.69652 -305.788822)
		(width 0.14224)
		(layer "In2.Cu")
		(net "P3E_CPU1_P4_TX_DP<2>")
	)
	(segment
		(start 100.809552 -308.469284)
		(end 100.656136 -308.867302)
		(width 0.14224)
		(layer "In2.Cu")
		(net "P3E_CPU1_P4_TX_DP<2>")
	)
	(segment
		(start 104.279446 -293.848028)
		(end 104.278176 -293.84879)
		(width 0.1143)
		(layer "In2.Cu")
		(net "P3E_CPU1_P4_TX_DP<2>")
	)
	(segment
		(start 104.329738 -293.816278)
		(end 104.309926 -293.830502)
		(width 0.1143)
		(layer "In2.Cu")
		(net "P3E_CPU1_P4_TX_DP<2>")
	)
	(segment
		(start 103.839772 -294.640508)
		(end 103.769414 -294.681148)
		(width 0.1143)
		(layer "In2.Cu")
		(net "P3E_CPU1_P4_TX_DP<2>")
	)
	(segment
		(start 100.242624 -309.93334)
		(end 100.080064 -310.030876)
		(width 0.14224)
		(layer "In2.Cu")
		(net "P3E_CPU1_P4_TX_DP<2>")
	)
	(segment
		(start 101.468174 -306.762658)
		(end 101.290628 -306.841144)
		(width 0.14224)
		(layer "In2.Cu")
		(net "P3E_CPU1_P4_TX_DP<2>")
	)
	(segment
		(start 101.215698 -307.416962)
		(end 101.062282 -307.81498)
		(width 0.14224)
		(layer "In2.Cu")
		(net "P3E_CPU1_P4_TX_DP<2>")
	)
	(segment
		(start 104.277922 -293.849044)
		(end 104.274874 -293.850822)
		(width 0.1143)
		(layer "In2.Cu")
		(net "P3E_CPU1_P4_TX_DP<2>")
	)
	(segment
		(start 104.309926 -293.221918)
		(end 104.329738 -293.236142)
		(width 0.1143)
		(layer "In2.Cu")
		(net "P3E_CPU1_P4_TX_DP<2>")
	)
	(segment
		(start 104.23906 -293.18077)
		(end 104.241854 -293.182802)
		(width 0.1143)
		(layer "In2.Cu")
		(net "P3E_CPU1_P4_TX_DP<2>")
	)
	(segment
		(start 100.884482 -307.89372)
		(end 100.731066 -308.291992)
		(width 0.14224)
		(layer "In2.Cu")
		(net "P3E_CPU1_P4_TX_DP<2>")
	)
	(segment
		(start 101.543104 -306.187348)
		(end 101.62159 -306.36464)
		(width 0.14224)
		(layer "In2.Cu")
		(net "P3E_CPU1_P4_TX_DP<2>")
	)
	(segment
		(start 104.278176 -293.84879)
		(end 104.277922 -293.849044)
		(width 0.1143)
		(layer "In2.Cu")
		(net "P3E_CPU1_P4_TX_DP<2>")
	)
	(segment
		(start 104.280208 -293.84752)
		(end 104.279446 -293.848028)
		(width 0.1143)
		(layer "In2.Cu")
		(net "P3E_CPU1_P4_TX_DP<2>")
	)
	(segment
		(start 104.073198 -300.00956)
		(end 101.874066 -305.710336)
		(width 0.14224)
		(layer "In2.Cu")
		(net "P3E_CPU1_P4_TX_DP<2>")
	)
	(segment
		(start 103.525828 -295.450514)
		(end 103.7209 -296.09161)
		(width 0.1143)
		(layer "In2.Cu")
		(net "P3E_CPU1_P4_TX_DP<2>")
	)
	(segment
		(start 101.062282 -307.81498)
		(end 100.884482 -307.89372)
		(width 0.14224)
		(layer "In2.Cu")
		(net "P3E_CPU1_P4_TX_DP<2>")
	)
	(segment
		(start 99.598226 -310.030876)
		(end 99.307396 -309.740046)
		(width 0.14224)
		(layer "In2.Cu")
		(net "P3E_CPU1_P4_TX_DP<2>")
	)
	(segment
		(start 100.32492 -309.344314)
		(end 100.403406 -309.521606)
		(width 0.14224)
		(layer "In2.Cu")
		(net "P3E_CPU1_P4_TX_DP<2>")
	)
	(segment
		(start 104.27843 -293.203884)
		(end 104.309926 -293.221918)
		(width 0.1143)
		(layer "In2.Cu")
		(net "P3E_CPU1_P4_TX_DP<2>")
	)
	(segment
		(start 100.656136 -308.867302)
		(end 100.478336 -308.946042)
		(width 0.14224)
		(layer "In2.Cu")
		(net "P3E_CPU1_P4_TX_DP<2>")
	)
	(segment
		(start 100.478336 -308.946042)
		(end 100.32492 -309.344314)
		(width 0.14224)
		(layer "In2.Cu")
		(net "P3E_CPU1_P4_TX_DP<2>")
	)
	(segment
		(start 104.277668 -293.203376)
		(end 104.27843 -293.203884)
		(width 0.1143)
		(layer "In2.Cu")
		(net "P3E_CPU1_P4_TX_DP<2>")
	)
	(segment
		(start 101.69652 -305.788822)
		(end 101.543104 -306.187348)
		(width 0.14224)
		(layer "In2.Cu")
		(net "P3E_CPU1_P4_TX_DP<2>")
	)
	(segment
		(start 100.731066 -308.291992)
		(end 100.809552 -308.469284)
		(width 0.14224)
		(layer "In2.Cu")
		(net "P3E_CPU1_P4_TX_DP<2>")
	)
	(segment
		(start 103.621078 -292.716204)
		(end 103.91902 -292.716204)
		(width 0.1143)
		(layer "In2.Cu")
		(net "P3E_CPU1_P4_TX_DP<2>")
	)
	(segment
		(start 104.073198 -298.694094)
		(end 104.073198 -300.00956)
		(width 0.14224)
		(layer "In2.Cu")
		(net "P3E_CPU1_P4_TX_DP<2>")
	)
	(segment
		(start 103.67518 -296.72915)
		(end 103.67518 -297.733212)
		(width 0.14224)
		(layer "In2.Cu")
		(net "P3E_CPU1_P4_TX_DP<2>")
	)
	(segment
		(start 103.7209 -296.654982)
		(end 103.67518 -296.700702)
		(width 0.1143)
		(layer "In2.Cu")
		(net "P3E_CPU1_P4_TX_DP<2>")
	)
	(arc
		(start 104.001824 -292.799008)
		(mid 104.003612 -292.810457)
		(end 104.005634 -292.821868)
		(width 0.1143)
		(layer "In2.Cu")
		(net "P3E_CPU1_P4_TX_DP<2>")
	)
	(arc
		(start 103.769414 -294.681148)
		(mid 103.590313 -294.883678)
		(end 103.525828 -295.146222)
		(width 0.1143)
		(layer "In2.Cu")
		(net "P3E_CPU1_P4_TX_DP<2>")
	)
	(arc
		(start 104.274874 -293.850822)
		(mid 104.07067 -294.056311)
		(end 103.995982 -294.336216)
		(width 0.1143)
		(layer "In2.Cu")
		(net "P3E_CPU1_P4_TX_DP<2>")
	)
	(arc
		(start 103.995982 -294.336216)
		(mid 103.954588 -294.507204)
		(end 103.839772 -294.640508)
		(width 0.1143)
		(layer "In2.Cu")
		(net "P3E_CPU1_P4_TX_DP<2>")
	)
	(arc
		(start 104.329738 -293.236142)
		(mid 104.478452 -293.52621)
		(end 104.329738 -293.816278)
		(width 0.1143)
		(layer "In2.Cu")
		(net "P3E_CPU1_P4_TX_DP<2>")
	)
	(arc
		(start 104.005634 -292.821868)
		(mid 104.087067 -293.024266)
		(end 104.23906 -293.18077)
		(width 0.1143)
		(layer "In2.Cu")
		(net "P3E_CPU1_P4_TX_DP<2>")
	)
	(segment
		(start 116.893086 -67.18681)
		(end 152.958292 -63.27267)
		(width 0.14224)
		(layer "In6.Cu")
		(net "P3E_CPU1_P4_TX_DP<2>")
	)
	(segment
		(start 176.203102 -57.436512)
		(end 176.203102 -52.14493)
		(width 0.14224)
		(layer "In6.Cu")
		(net "P3E_CPU1_P4_TX_DP<2>")
	)
	(segment
		(start 152.958292 -63.27267)
		(end 161.476436 -64.774572)
		(width 0.14224)
		(layer "In6.Cu")
		(net "P3E_CPU1_P4_TX_DP<2>")
	)
	(segment
		(start 181.750716 -50.376328)
		(end 182.041546 -50.085498)
		(width 0.14224)
		(layer "In6.Cu")
		(net "P3E_CPU1_P4_TX_DP<2>")
	)
	(segment
		(start 39.997126 -154.980386)
		(end 47.814738 -136.107424)
		(width 0.14224)
		(layer "In6.Cu")
		(net "P3E_CPU1_P4_TX_DP<2>")
	)
	(segment
		(start 113.3983 -67.803014)
		(end 116.893086 -67.18681)
		(width 0.14224)
		(layer "In6.Cu")
		(net "P3E_CPU1_P4_TX_DP<2>")
	)
	(segment
		(start 9.957054 -175.275494)
		(end 26.593038 -168.384728)
		(width 0.14224)
		(layer "In6.Cu")
		(net "P3E_CPU1_P4_TX_DP<2>")
	)
	(segment
		(start 176.203102 -52.14493)
		(end 177.971704 -50.376328)
		(width 0.14224)
		(layer "In6.Cu")
		(net "P3E_CPU1_P4_TX_DP<2>")
	)
	(segment
		(start 168.001188 -63.623952)
		(end 174.72025 -58.919364)
		(width 0.14224)
		(layer "In6.Cu")
		(net "P3E_CPU1_P4_TX_DP<2>")
	)
	(segment
		(start 100.875338 -76.571602)
		(end 113.3983 -67.803014)
		(width 0.14224)
		(layer "In6.Cu")
		(net "P3E_CPU1_P4_TX_DP<2>")
	)
	(segment
		(start 161.476436 -64.774572)
		(end 168.000934 -63.623952)
		(width 0.14224)
		(layer "In6.Cu")
		(net "P3E_CPU1_P4_TX_DP<2>")
	)
	(segment
		(start 177.971704 -50.376328)
		(end 181.750716 -50.376328)
		(width 0.14224)
		(layer "In6.Cu")
		(net "P3E_CPU1_P4_TX_DP<2>")
	)
	(segment
		(start 47.814738 -136.107424)
		(end 85.753448 -98.167952)
		(width 0.14224)
		(layer "In6.Cu")
		(net "P3E_CPU1_P4_TX_DP<2>")
	)
	(segment
		(start 9.397238 -175.275494)
		(end 9.957054 -175.275494)
		(width 0.14224)
		(layer "In6.Cu")
		(net "P3E_CPU1_P4_TX_DP<2>")
	)
	(segment
		(start 174.72025 -58.919364)
		(end 176.203102 -57.436512)
		(width 0.14224)
		(layer "In6.Cu")
		(net "P3E_CPU1_P4_TX_DP<2>")
	)
	(segment
		(start 26.593038 -168.384728)
		(end 39.997126 -154.980386)
		(width 0.14224)
		(layer "In6.Cu")
		(net "P3E_CPU1_P4_TX_DP<2>")
	)
	(segment
		(start 85.753448 -98.167952)
		(end 100.875338 -76.571602)
		(width 0.14224)
		(layer "In6.Cu")
		(net "P3E_CPU1_P4_TX_DP<2>")
	)
	(segment
		(start 9.106408 -174.984664)
		(end 9.397238 -175.275494)
		(width 0.14224)
		(layer "In6.Cu")
		(net "P3E_CPU1_P4_TX_DP<2>")
	)
	(segment
		(start 168.000934 -63.623952)
		(end 168.001188 -63.623952)
		(width 0.14224)
		(layer "In6.Cu")
		(net "P3E_CPU1_P4_TX_DP<2>")
	)
	(segment
		(start 15.231872 -320.200274)
		(end 14.194028 -317.69431)
		(width 0.14224)
		(layer "In15.Cu")
		(net "P3E_CPU1_P4_TX_DP<2>")
	)
	(segment
		(start 15.699486 -320.667634)
		(end 15.699232 -320.667634)
		(width 0.14224)
		(layer "In15.Cu")
		(net "P3E_CPU1_P4_TX_DP<2>")
	)
	(segment
		(start 90.24747 -311.754266)
		(end 89.905078 -311.804558)
		(width 0.14224)
		(layer "In15.Cu")
		(net "P3E_CPU1_P4_TX_DP<2>")
	)
	(segment
		(start 15.699232 -320.667634)
		(end 15.231872 -320.200274)
		(width 0.14224)
		(layer "In15.Cu")
		(net "P3E_CPU1_P4_TX_DP<2>")
	)
	(segment
		(start 9.715246 -175.275494)
		(end 9.397238 -175.275494)
		(width 0.14224)
		(layer "In15.Cu")
		(net "P3E_CPU1_P4_TX_DP<2>")
	)
	(segment
		(start 13.22324 -310.724296)
		(end 13.208762 -310.299862)
		(width 0.14224)
		(layer "In15.Cu")
		(net "P3E_CPU1_P4_TX_DP<2>")
	)
	(segment
		(start 13.132562 -308.055518)
		(end 12.990576 -307.923184)
		(width 0.14224)
		(layer "In15.Cu")
		(net "P3E_CPU1_P4_TX_DP<2>")
	)
	(segment
		(start 13.066776 -310.167528)
		(end 13.052552 -309.743602)
		(width 0.14224)
		(layer "In15.Cu")
		(net "P3E_CPU1_P4_TX_DP<2>")
	)
	(segment
		(start 13.246862 -311.422034)
		(end 13.104876 -311.2897)
		(width 0.14224)
		(layer "In15.Cu")
		(net "P3E_CPU1_P4_TX_DP<2>")
	)
	(segment
		(start 11.030712 -183.367426)
		(end 11.082782 -181.913784)
		(width 0.14224)
		(layer "In15.Cu")
		(net "P3E_CPU1_P4_TX_DP<2>")
	)
	(segment
		(start 97.06737 -311.113424)
		(end 94.615 -311.113424)
		(width 0.14224)
		(layer "In15.Cu")
		(net "P3E_CPU1_P4_TX_DP<2>")
	)
	(segment
		(start 9.397238 -175.275494)
		(end 9.106408 -174.984664)
		(width 0.14224)
		(layer "In15.Cu")
		(net "P3E_CPU1_P4_TX_DP<2>")
	)
	(segment
		(start 11.082782 -181.913784)
		(end 11.082782 -178.056794)
		(width 0.14224)
		(layer "In15.Cu")
		(net "P3E_CPU1_P4_TX_DP<2>")
	)
	(segment
		(start 89.905078 -311.804558)
		(end 85.925406 -312.388758)
		(width 0.14224)
		(layer "In15.Cu")
		(net "P3E_CPU1_P4_TX_DP<2>")
	)
	(segment
		(start 13.128752 -311.987946)
		(end 13.26134 -311.846468)
		(width 0.14224)
		(layer "In15.Cu")
		(net "P3E_CPU1_P4_TX_DP<2>")
	)
	(segment
		(start 13.090652 -310.865774)
		(end 13.22324 -310.724296)
		(width 0.14224)
		(layer "In15.Cu")
		(net "P3E_CPU1_P4_TX_DP<2>")
	)
	(segment
		(start 13.26134 -311.846468)
		(end 13.246862 -311.422034)
		(width 0.14224)
		(layer "In15.Cu")
		(net "P3E_CPU1_P4_TX_DP<2>")
	)
	(segment
		(start 90.247724 -311.754266)
		(end 90.24747 -311.754266)
		(width 0.14224)
		(layer "In15.Cu")
		(net "P3E_CPU1_P4_TX_DP<2>")
	)
	(segment
		(start 58.686192 -321.846194)
		(end 19.133312 -321.658234)
		(width 0.14224)
		(layer "In15.Cu")
		(net "P3E_CPU1_P4_TX_DP<2>")
	)
	(segment
		(start 11.030712 -183.36895)
		(end 11.030966 -183.36768)
		(width 0.14224)
		(layer "In15.Cu")
		(net "P3E_CPU1_P4_TX_DP<2>")
	)
	(segment
		(start 13.142976 -312.411872)
		(end 13.128752 -311.987946)
		(width 0.14224)
		(layer "In15.Cu")
		(net "P3E_CPU1_P4_TX_DP<2>")
	)
	(segment
		(start 10.083038 -175.643286)
		(end 9.715246 -175.275494)
		(width 0.14224)
		(layer "In15.Cu")
		(net "P3E_CPU1_P4_TX_DP<2>")
	)
	(segment
		(start 99.016566 -310.030876)
		(end 98.149918 -310.030876)
		(width 0.14224)
		(layer "In15.Cu")
		(net "P3E_CPU1_P4_TX_DP<2>")
	)
	(segment
		(start 13.028676 -309.045356)
		(end 13.014452 -308.62143)
		(width 0.14224)
		(layer "In15.Cu")
		(net "P3E_CPU1_P4_TX_DP<2>")
	)
	(segment
		(start 99.307396 -309.740046)
		(end 99.016566 -310.030876)
		(width 0.14224)
		(layer "In15.Cu")
		(net "P3E_CPU1_P4_TX_DP<2>")
	)
	(segment
		(start 13.052552 -309.743602)
		(end 13.18514 -309.602124)
		(width 0.14224)
		(layer "In15.Cu")
		(net "P3E_CPU1_P4_TX_DP<2>")
	)
	(segment
		(start 14.194028 -317.69431)
		(end 13.142976 -312.411872)
		(width 0.14224)
		(layer "In15.Cu")
		(net "P3E_CPU1_P4_TX_DP<2>")
	)
	(segment
		(start 11.082782 -178.056794)
		(end 10.083038 -175.643286)
		(width 0.14224)
		(layer "In15.Cu")
		(net "P3E_CPU1_P4_TX_DP<2>")
	)
	(segment
		(start 85.925406 -312.389012)
		(end 70.690486 -314.624466)
		(width 0.14224)
		(layer "In15.Cu")
		(net "P3E_CPU1_P4_TX_DP<2>")
	)
	(segment
		(start 59.88304 -321.846194)
		(end 58.686192 -321.846194)
		(width 0.14224)
		(layer "In15.Cu")
		(net "P3E_CPU1_P4_TX_DP<2>")
	)
	(segment
		(start 19.133312 -321.658234)
		(end 16.1671 -321.135248)
		(width 0.14224)
		(layer "In15.Cu")
		(net "P3E_CPU1_P4_TX_DP<2>")
	)
	(segment
		(start 9.87171 -215.642698)
		(end 11.030712 -183.36895)
		(width 0.14224)
		(layer "In15.Cu")
		(net "P3E_CPU1_P4_TX_DP<2>")
	)
	(segment
		(start 11.030966 -183.36768)
		(end 11.030458 -183.367426)
		(width 0.14224)
		(layer "In15.Cu")
		(net "P3E_CPU1_P4_TX_DP<2>")
	)
	(segment
		(start 13.104876 -311.2897)
		(end 13.090652 -310.865774)
		(width 0.14224)
		(layer "In15.Cu")
		(net "P3E_CPU1_P4_TX_DP<2>")
	)
	(segment
		(start 13.18514 -309.602124)
		(end 13.170662 -309.17769)
		(width 0.14224)
		(layer "In15.Cu")
		(net "P3E_CPU1_P4_TX_DP<2>")
	)
	(segment
		(start 11.030458 -183.367426)
		(end 11.030712 -183.367426)
		(width 0.14224)
		(layer "In15.Cu")
		(net "P3E_CPU1_P4_TX_DP<2>")
	)
	(segment
		(start 13.14704 -308.479952)
		(end 13.132562 -308.055518)
		(width 0.14224)
		(layer "In15.Cu")
		(net "P3E_CPU1_P4_TX_DP<2>")
	)
	(segment
		(start 13.014452 -308.62143)
		(end 13.14704 -308.479952)
		(width 0.14224)
		(layer "In15.Cu")
		(net "P3E_CPU1_P4_TX_DP<2>")
	)
	(segment
		(start 98.149918 -310.030876)
		(end 97.06737 -311.113424)
		(width 0.14224)
		(layer "In15.Cu")
		(net "P3E_CPU1_P4_TX_DP<2>")
	)
	(segment
		(start 94.615 -311.113424)
		(end 90.247724 -311.754266)
		(width 0.14224)
		(layer "In15.Cu")
		(net "P3E_CPU1_P4_TX_DP<2>")
	)
	(segment
		(start 70.690486 -314.624466)
		(end 59.88304 -321.846194)
		(width 0.14224)
		(layer "In15.Cu")
		(net "P3E_CPU1_P4_TX_DP<2>")
	)
	(segment
		(start 13.170662 -309.17769)
		(end 13.028676 -309.045356)
		(width 0.14224)
		(layer "In15.Cu")
		(net "P3E_CPU1_P4_TX_DP<2>")
	)
	(segment
		(start 13.208762 -310.299862)
		(end 13.066776 -310.167528)
		(width 0.14224)
		(layer "In15.Cu")
		(net "P3E_CPU1_P4_TX_DP<2>")
	)
	(segment
		(start 12.990576 -307.923184)
		(end 9.87171 -215.642698)
		(width 0.14224)
		(layer "In15.Cu")
		(net "P3E_CPU1_P4_TX_DP<2>")
	)
	(segment
		(start 16.1671 -321.135248)
		(end 15.699486 -320.667634)
		(width 0.14224)
		(layer "In15.Cu")
		(net "P3E_CPU1_P4_TX_DP<2>")
	)
	(segment
		(start 85.925406 -312.388758)
		(end 85.925406 -312.389012)
		(width 0.14224)
		(layer "In15.Cu")
		(net "P3E_CPU1_P4_TX_DP<2>")
	)
	(segment
		(start 180.795168 -47.139098)
		(end 181.084982 -47.428912)
		(width 0.12954)
		(layer "F.Cu")
		(net "P3E_CPU1_P4_TX_DP<1>")
	)
	(segment
		(start 181.084982 -47.428912)
		(end 181.777132 -47.428912)
		(width 0.12954)
		(layer "F.Cu")
		(net "P3E_CPU1_P4_TX_DP<1>")
	)
	(segment
		(start 181.777132 -47.428912)
		(end 182.041546 -47.164498)
		(width 0.12954)
		(layer "F.Cu")
		(net "P3E_CPU1_P4_TX_DP<1>")
	)
	(segment
		(start 101.268022 -292.450266)
		(end 100.80117 -292.716204)
		(width 0.12954)
		(layer "F.Cu")
		(net "P3E_CPU1_P4_TX_DP<1>")
	)
	(segment
		(start 101.454712 -293.201852)
		(end 101.458014 -293.20363)
		(width 0.1143)
		(layer "In2.Cu")
		(net "P3E_CPU1_P4_TX_DP<1>")
	)
	(segment
		(start 93.947234 -307.540914)
		(end 93.947234 -308.18074)
		(width 0.14224)
		(layer "In2.Cu")
		(net "P3E_CPU1_P4_TX_DP<1>")
	)
	(segment
		(start 101.099112 -292.716204)
		(end 101.18217 -292.801548)
		(width 0.1143)
		(layer "In2.Cu")
		(net "P3E_CPU1_P4_TX_DP<1>")
	)
	(segment
		(start 100.874576 -298.708826)
		(end 100.874576 -299.244512)
		(width 0.14224)
		(layer "In2.Cu")
		(net "P3E_CPU1_P4_TX_DP<1>")
	)
	(segment
		(start 100.874576 -298.680378)
		(end 100.874576 -298.708826)
		(width 0.1143)
		(layer "In2.Cu")
		(net "P3E_CPU1_P4_TX_DP<1>")
	)
	(segment
		(start 100.920296 -298.634658)
		(end 100.874576 -298.680378)
		(width 0.1143)
		(layer "In2.Cu")
		(net "P3E_CPU1_P4_TX_DP<1>")
	)
	(segment
		(start 101.418644 -294.800782)
		(end 101.48951 -294.84193)
		(width 0.1143)
		(layer "In2.Cu")
		(net "P3E_CPU1_P4_TX_DP<1>")
	)
	(segment
		(start 101.458014 -293.20363)
		(end 101.458776 -293.204138)
		(width 0.1143)
		(layer "In2.Cu")
		(net "P3E_CPU1_P4_TX_DP<1>")
	)
	(segment
		(start 93.947234 -308.18074)
		(end 93.656404 -308.47157)
		(width 0.14224)
		(layer "In2.Cu")
		(net "P3E_CPU1_P4_TX_DP<1>")
	)
	(segment
		(start 100.874576 -299.244512)
		(end 95.122746 -305.590194)
		(width 0.14224)
		(layer "In2.Cu")
		(net "P3E_CPU1_P4_TX_DP<1>")
	)
	(segment
		(start 95.122746 -305.590194)
		(end 94.15526 -307.03774)
		(width 0.14224)
		(layer "In2.Cu")
		(net "P3E_CPU1_P4_TX_DP<1>")
	)
	(segment
		(start 94.15526 -307.03774)
		(end 93.947234 -307.540914)
		(width 0.14224)
		(layer "In2.Cu")
		(net "P3E_CPU1_P4_TX_DP<1>")
	)
	(segment
		(start 100.80117 -292.716204)
		(end 101.099112 -292.716204)
		(width 0.1143)
		(layer "In2.Cu")
		(net "P3E_CPU1_P4_TX_DP<1>")
	)
	(segment
		(start 101.175566 -296.084752)
		(end 100.920296 -296.340022)
		(width 0.1143)
		(layer "In2.Cu")
		(net "P3E_CPU1_P4_TX_DP<1>")
	)
	(segment
		(start 100.920296 -296.340022)
		(end 100.920296 -298.634658)
		(width 0.1143)
		(layer "In2.Cu")
		(net "P3E_CPU1_P4_TX_DP<1>")
	)
	(segment
		(start 101.489764 -295.450514)
		(end 101.458014 -295.468802)
		(width 0.1143)
		(layer "In2.Cu")
		(net "P3E_CPU1_P4_TX_DP<1>")
	)
	(segment
		(start 101.489764 -293.830502)
		(end 101.419152 -293.871396)
		(width 0.1143)
		(layer "In2.Cu")
		(net "P3E_CPU1_P4_TX_DP<1>")
	)
	(segment
		(start 101.397054 -294.785288)
		(end 101.418644 -294.800782)
		(width 0.1143)
		(layer "In2.Cu")
		(net "P3E_CPU1_P4_TX_DP<1>")
	)
	(segment
		(start 101.419152 -293.871396)
		(end 101.397054 -293.887144)
		(width 0.1143)
		(layer "In2.Cu")
		(net "P3E_CPU1_P4_TX_DP<1>")
	)
	(segment
		(start 101.48951 -294.84193)
		(end 101.489764 -294.84193)
		(width 0.1143)
		(layer "In2.Cu")
		(net "P3E_CPU1_P4_TX_DP<1>")
	)
	(segment
		(start 101.458014 -295.468802)
		(end 101.418898 -295.491662)
		(width 0.1143)
		(layer "In2.Cu")
		(net "P3E_CPU1_P4_TX_DP<1>")
	)
	(segment
		(start 101.175566 -295.955974)
		(end 101.175566 -296.084752)
		(width 0.1143)
		(layer "In2.Cu")
		(net "P3E_CPU1_P4_TX_DP<1>")
	)
	(segment
		(start 101.458776 -293.204138)
		(end 101.489764 -293.221918)
		(width 0.1143)
		(layer "In2.Cu")
		(net "P3E_CPU1_P4_TX_DP<1>")
	)
	(arc
		(start 101.397054 -293.887144)
		(mid 101.166711 -294.336216)
		(end 101.397054 -294.785288)
		(width 0.1143)
		(layer "In2.Cu")
		(net "P3E_CPU1_P4_TX_DP<1>")
	)
	(arc
		(start 101.275642 -295.635426)
		(mid 101.201223 -295.78809)
		(end 101.175566 -295.955974)
		(width 0.1143)
		(layer "In2.Cu")
		(net "P3E_CPU1_P4_TX_DP<1>")
	)
	(arc
		(start 101.18217 -292.801548)
		(mid 101.183874 -292.811721)
		(end 101.185726 -292.821868)
		(width 0.1143)
		(layer "In2.Cu")
		(net "P3E_CPU1_P4_TX_DP<1>")
	)
	(arc
		(start 101.489764 -293.221918)
		(mid 101.645692 -293.52621)
		(end 101.489764 -293.830502)
		(width 0.1143)
		(layer "In2.Cu")
		(net "P3E_CPU1_P4_TX_DP<1>")
	)
	(arc
		(start 101.489764 -294.84193)
		(mid 101.645692 -295.146222)
		(end 101.489764 -295.450514)
		(width 0.1143)
		(layer "In2.Cu")
		(net "P3E_CPU1_P4_TX_DP<1>")
	)
	(arc
		(start 101.418898 -295.491662)
		(mid 101.340751 -295.55705)
		(end 101.275642 -295.635426)
		(width 0.1143)
		(layer "In2.Cu")
		(net "P3E_CPU1_P4_TX_DP<1>")
	)
	(arc
		(start 101.185726 -292.821868)
		(mid 101.278868 -293.041136)
		(end 101.454712 -293.201852)
		(width 0.1143)
		(layer "In2.Cu")
		(net "P3E_CPU1_P4_TX_DP<1>")
	)
	(segment
		(start 177.974244 -47.455328)
		(end 181.750716 -47.455328)
		(width 0.14224)
		(layer "In6.Cu")
		(net "P3E_CPU1_P4_TX_DP<1>")
	)
	(segment
		(start 85.072728 -97.442528)
		(end 100.223066 -75.805792)
		(width 0.14224)
		(layer "In6.Cu")
		(net "P3E_CPU1_P4_TX_DP<1>")
	)
	(segment
		(start 46.693836 -135.822182)
		(end 85.072728 -97.442528)
		(width 0.14224)
		(layer "In6.Cu")
		(net "P3E_CPU1_P4_TX_DP<1>")
	)
	(segment
		(start 100.223066 -75.805792)
		(end 113.012982 -66.850514)
		(width 0.14224)
		(layer "In6.Cu")
		(net "P3E_CPU1_P4_TX_DP<1>")
	)
	(segment
		(start 181.750716 -47.455328)
		(end 182.041546 -47.164498)
		(width 0.14224)
		(layer "In6.Cu")
		(net "P3E_CPU1_P4_TX_DP<1>")
	)
	(segment
		(start 9.397238 -172.50537)
		(end 10.493502 -172.50537)
		(width 0.14224)
		(layer "In6.Cu")
		(net "P3E_CPU1_P4_TX_DP<1>")
	)
	(segment
		(start 9.106408 -172.21454)
		(end 9.397238 -172.50537)
		(width 0.14224)
		(layer "In6.Cu")
		(net "P3E_CPU1_P4_TX_DP<1>")
	)
	(segment
		(start 22.29993 -168.92397)
		(end 24.373586 -168.064942)
		(width 0.14224)
		(layer "In6.Cu")
		(net "P3E_CPU1_P4_TX_DP<1>")
	)
	(segment
		(start 38.836092 -154.793442)
		(end 46.693836 -135.822182)
		(width 0.14224)
		(layer "In6.Cu")
		(net "P3E_CPU1_P4_TX_DP<1>")
	)
	(segment
		(start 153.476198 -62.278514)
		(end 161.661094 -63.721742)
		(width 0.14224)
		(layer "In6.Cu")
		(net "P3E_CPU1_P4_TX_DP<1>")
	)
	(segment
		(start 174.1424 -58.172858)
		(end 175.259238 -57.05602)
		(width 0.14224)
		(layer "In6.Cu")
		(net "P3E_CPU1_P4_TX_DP<1>")
	)
	(segment
		(start 24.841708 -167.908986)
		(end 26.34234 -167.287194)
		(width 0.14224)
		(layer "In6.Cu")
		(net "P3E_CPU1_P4_TX_DP<1>")
	)
	(segment
		(start 26.34234 -167.287194)
		(end 38.836092 -154.793442)
		(width 0.14224)
		(layer "In6.Cu")
		(net "P3E_CPU1_P4_TX_DP<1>")
	)
	(segment
		(start 113.012982 -66.850514)
		(end 116.867178 -66.17081)
		(width 0.14224)
		(layer "In6.Cu")
		(net "P3E_CPU1_P4_TX_DP<1>")
	)
	(segment
		(start 161.661094 -63.721742)
		(end 167.751506 -62.647576)
		(width 0.14224)
		(layer "In6.Cu")
		(net "P3E_CPU1_P4_TX_DP<1>")
	)
	(segment
		(start 10.493502 -172.50537)
		(end 22.29993 -168.92397)
		(width 0.14224)
		(layer "In6.Cu")
		(net "P3E_CPU1_P4_TX_DP<1>")
	)
	(segment
		(start 24.373586 -168.064942)
		(end 24.841708 -167.908986)
		(width 0.14224)
		(layer "In6.Cu")
		(net "P3E_CPU1_P4_TX_DP<1>")
	)
	(segment
		(start 116.867178 -66.17081)
		(end 153.476198 -62.278514)
		(width 0.14224)
		(layer "In6.Cu")
		(net "P3E_CPU1_P4_TX_DP<1>")
	)
	(segment
		(start 175.259238 -57.05602)
		(end 175.259238 -50.170334)
		(width 0.14224)
		(layer "In6.Cu")
		(net "P3E_CPU1_P4_TX_DP<1>")
	)
	(segment
		(start 175.259238 -50.170334)
		(end 177.974244 -47.455328)
		(width 0.14224)
		(layer "In6.Cu")
		(net "P3E_CPU1_P4_TX_DP<1>")
	)
	(segment
		(start 167.751506 -62.647576)
		(end 174.1424 -58.172858)
		(width 0.14224)
		(layer "In6.Cu")
		(net "P3E_CPU1_P4_TX_DP<1>")
	)
	(segment
		(start 93.947234 -308.7624)
		(end 93.947234 -309.465218)
		(width 0.14224)
		(layer "In15.Cu")
		(net "P3E_CPU1_P4_TX_DP<1>")
	)
	(segment
		(start 14.388592 -311.302654)
		(end 14.374114 -310.87822)
		(width 0.14224)
		(layer "In15.Cu")
		(net "P3E_CPU1_P4_TX_DP<1>")
	)
	(segment
		(start 14.311122 -313.073542)
		(end 14.294104 -312.566304)
		(width 0.14224)
		(layer "In15.Cu")
		(net "P3E_CPU1_P4_TX_DP<1>")
	)
	(segment
		(start 14.294104 -312.566304)
		(end 14.426438 -312.424572)
		(width 0.14224)
		(layer "In15.Cu")
		(net "P3E_CPU1_P4_TX_DP<1>")
	)
	(segment
		(start 56.670956 -320.888614)
		(end 56.670956 -320.878962)
		(width 0.14224)
		(layer "In15.Cu")
		(net "P3E_CPU1_P4_TX_DP<1>")
	)
	(segment
		(start 14.256004 -311.444132)
		(end 14.388592 -311.302654)
		(width 0.14224)
		(layer "In15.Cu")
		(net "P3E_CPU1_P4_TX_DP<1>")
	)
	(segment
		(start 16.630904 -320.24447)
		(end 16.035274 -319.64884)
		(width 0.14224)
		(layer "In15.Cu")
		(net "P3E_CPU1_P4_TX_DP<1>")
	)
	(segment
		(start 16.035274 -319.64884)
		(end 15.233904 -317.713868)
		(width 0.14224)
		(layer "In15.Cu")
		(net "P3E_CPU1_P4_TX_DP<1>")
	)
	(segment
		(start 56.670956 -320.878962)
		(end 19.219418 -320.700908)
		(width 0.14224)
		(layer "In15.Cu")
		(net "P3E_CPU1_P4_TX_DP<1>")
	)
	(segment
		(start 14.412214 -312.000392)
		(end 14.270228 -311.868058)
		(width 0.14224)
		(layer "In15.Cu")
		(net "P3E_CPU1_P4_TX_DP<1>")
	)
	(segment
		(start 9.397238 -172.50537)
		(end 9.106408 -172.21454)
		(width 0.14224)
		(layer "In15.Cu")
		(net "P3E_CPU1_P4_TX_DP<1>")
	)
	(segment
		(start 14.270228 -311.868058)
		(end 14.256004 -311.444132)
		(width 0.14224)
		(layer "In15.Cu")
		(net "P3E_CPU1_P4_TX_DP<1>")
	)
	(segment
		(start 14.217904 -310.32196)
		(end 14.350492 -310.180482)
		(width 0.14224)
		(layer "In15.Cu")
		(net "P3E_CPU1_P4_TX_DP<1>")
	)
	(segment
		(start 14.297914 -308.633876)
		(end 14.155928 -308.501542)
		(width 0.14224)
		(layer "In15.Cu")
		(net "P3E_CPU1_P4_TX_DP<1>")
	)
	(segment
		(start 93.947234 -309.465218)
		(end 93.410024 -310.002428)
		(width 0.14224)
		(layer "In15.Cu")
		(net "P3E_CPU1_P4_TX_DP<1>")
	)
	(segment
		(start 10.943082 -213.455504)
		(end 12.074906 -181.931564)
		(width 0.14224)
		(layer "In15.Cu")
		(net "P3E_CPU1_P4_TX_DP<1>")
	)
	(segment
		(start 14.155928 -308.501542)
		(end 10.943082 -213.455504)
		(width 0.14224)
		(layer "In15.Cu")
		(net "P3E_CPU1_P4_TX_DP<1>")
	)
	(segment
		(start 15.233904 -317.713868)
		(end 14.311122 -313.073542)
		(width 0.14224)
		(layer "In15.Cu")
		(net "P3E_CPU1_P4_TX_DP<1>")
	)
	(segment
		(start 14.350492 -310.180482)
		(end 14.336014 -309.756048)
		(width 0.14224)
		(layer "In15.Cu")
		(net "P3E_CPU1_P4_TX_DP<1>")
	)
	(segment
		(start 14.194028 -309.623714)
		(end 14.179804 -309.199788)
		(width 0.14224)
		(layer "In15.Cu")
		(net "P3E_CPU1_P4_TX_DP<1>")
	)
	(segment
		(start 10.409428 -173.199552)
		(end 9.715246 -172.50537)
		(width 0.14224)
		(layer "In15.Cu")
		(net "P3E_CPU1_P4_TX_DP<1>")
	)
	(segment
		(start 19.219418 -320.700908)
		(end 16.630904 -320.24447)
		(width 0.14224)
		(layer "In15.Cu")
		(net "P3E_CPU1_P4_TX_DP<1>")
	)
	(segment
		(start 93.410024 -310.002428)
		(end 92.835476 -310.274208)
		(width 0.14224)
		(layer "In15.Cu")
		(net "P3E_CPU1_P4_TX_DP<1>")
	)
	(segment
		(start 70.384924 -313.604656)
		(end 59.483752 -320.888614)
		(width 0.14224)
		(layer "In15.Cu")
		(net "P3E_CPU1_P4_TX_DP<1>")
	)
	(segment
		(start 14.232128 -310.745886)
		(end 14.217904 -310.32196)
		(width 0.14224)
		(layer "In15.Cu")
		(net "P3E_CPU1_P4_TX_DP<1>")
	)
	(segment
		(start 12.074906 -181.931564)
		(end 12.074906 -177.220372)
		(width 0.14224)
		(layer "In15.Cu")
		(net "P3E_CPU1_P4_TX_DP<1>")
	)
	(segment
		(start 93.656404 -308.47157)
		(end 93.947234 -308.7624)
		(width 0.14224)
		(layer "In15.Cu")
		(net "P3E_CPU1_P4_TX_DP<1>")
	)
	(segment
		(start 14.426438 -312.424572)
		(end 14.412214 -312.000392)
		(width 0.14224)
		(layer "In15.Cu")
		(net "P3E_CPU1_P4_TX_DP<1>")
	)
	(segment
		(start 14.374114 -310.87822)
		(end 14.232128 -310.745886)
		(width 0.14224)
		(layer "In15.Cu")
		(net "P3E_CPU1_P4_TX_DP<1>")
	)
	(segment
		(start 14.179804 -309.199788)
		(end 14.312392 -309.05831)
		(width 0.14224)
		(layer "In15.Cu")
		(net "P3E_CPU1_P4_TX_DP<1>")
	)
	(segment
		(start 9.715246 -172.50537)
		(end 9.397238 -172.50537)
		(width 0.14224)
		(layer "In15.Cu")
		(net "P3E_CPU1_P4_TX_DP<1>")
	)
	(segment
		(start 12.074906 -177.220372)
		(end 10.409428 -173.199552)
		(width 0.14224)
		(layer "In15.Cu")
		(net "P3E_CPU1_P4_TX_DP<1>")
	)
	(segment
		(start 59.483752 -320.888614)
		(end 56.670956 -320.888614)
		(width 0.14224)
		(layer "In15.Cu")
		(net "P3E_CPU1_P4_TX_DP<1>")
	)
	(segment
		(start 14.312392 -309.05831)
		(end 14.297914 -308.633876)
		(width 0.14224)
		(layer "In15.Cu")
		(net "P3E_CPU1_P4_TX_DP<1>")
	)
	(segment
		(start 14.336014 -309.756048)
		(end 14.194028 -309.623714)
		(width 0.14224)
		(layer "In15.Cu")
		(net "P3E_CPU1_P4_TX_DP<1>")
	)
	(segment
		(start 92.835476 -310.274208)
		(end 70.384924 -313.604656)
		(width 0.14224)
		(layer "In15.Cu")
		(net "P3E_CPU1_P4_TX_DP<1>")
	)
	(segment
		(start 181.777132 -44.380912)
		(end 182.041546 -44.116498)
		(width 0.12954)
		(layer "F.Cu")
		(net "P3E_CPU1_P4_TX_DP<0>")
	)
	(segment
		(start 180.795168 -44.091098)
		(end 181.084982 -44.380912)
		(width 0.12954)
		(layer "F.Cu")
		(net "P3E_CPU1_P4_TX_DP<0>")
	)
	(segment
		(start 98.44786 -292.450266)
		(end 97.981008 -292.716204)
		(width 0.12954)
		(layer "F.Cu")
		(net "P3E_CPU1_P4_TX_DP<0>")
	)
	(segment
		(start 181.084982 -44.380912)
		(end 181.777132 -44.380912)
		(width 0.12954)
		(layer "F.Cu")
		(net "P3E_CPU1_P4_TX_DP<0>")
	)
	(segment
		(start 98.062796 -297.290236)
		(end 98.062796 -297.591226)
		(width 0.14224)
		(layer "In2.Cu")
		(net "P3E_CPU1_P4_TX_DP<0>")
	)
	(segment
		(start 85.670898 -306.13223)
		(end 85.726778 -306.318158)
		(width 0.14224)
		(layer "In2.Cu")
		(net "P3E_CPU1_P4_TX_DP<0>")
	)
	(segment
		(start 98.681794 -293.82212)
		(end 98.669856 -293.830502)
		(width 0.1143)
		(layer "In2.Cu")
		(net "P3E_CPU1_P4_TX_DP<0>")
	)
	(segment
		(start 83.354926 -308.931818)
		(end 79.864966 -308.931818)
		(width 0.14224)
		(layer "In2.Cu")
		(net "P3E_CPU1_P4_TX_DP<0>")
	)
	(segment
		(start 85.192616 -307.311552)
		(end 84.779358 -308.080156)
		(width 0.14224)
		(layer "In2.Cu")
		(net "P3E_CPU1_P4_TX_DP<0>")
	)
	(segment
		(start 86.20506 -305.138836)
		(end 86.26094 -305.324764)
		(width 0.14224)
		(layer "In2.Cu")
		(net "P3E_CPU1_P4_TX_DP<0>")
	)
	(segment
		(start 98.631502 -293.852346)
		(end 98.629216 -293.853616)
		(width 0.1143)
		(layer "In2.Cu")
		(net "P3E_CPU1_P4_TX_DP<0>")
	)
	(segment
		(start 98.062796 -297.591226)
		(end 95.744538 -299.90923)
		(width 0.14224)
		(layer "In2.Cu")
		(net "P3E_CPU1_P4_TX_DP<0>")
	)
	(segment
		(start 98.635312 -293.850314)
		(end 98.634296 -293.850822)
		(width 0.1143)
		(layer "In2.Cu")
		(net "P3E_CPU1_P4_TX_DP<0>")
	)
	(segment
		(start 98.669856 -293.221918)
		(end 98.681794 -293.2303)
		(width 0.1143)
		(layer "In2.Cu")
		(net "P3E_CPU1_P4_TX_DP<0>")
	)
	(segment
		(start 85.726778 -306.318158)
		(end 85.524848 -306.693824)
		(width 0.14224)
		(layer "In2.Cu")
		(net "P3E_CPU1_P4_TX_DP<0>")
	)
	(segment
		(start 86.82482 -304.275998)
		(end 86.593172 -304.707036)
		(width 0.14224)
		(layer "In2.Cu")
		(net "P3E_CPU1_P4_TX_DP<0>")
	)
	(segment
		(start 85.33892 -306.749704)
		(end 85.136736 -307.125624)
		(width 0.14224)
		(layer "In2.Cu")
		(net "P3E_CPU1_P4_TX_DP<0>")
	)
	(segment
		(start 98.63709 -293.849298)
		(end 98.635312 -293.850314)
		(width 0.1143)
		(layer "In2.Cu")
		(net "P3E_CPU1_P4_TX_DP<0>")
	)
	(segment
		(start 98.638106 -293.84879)
		(end 98.63709 -293.849298)
		(width 0.1143)
		(layer "In2.Cu")
		(net "P3E_CPU1_P4_TX_DP<0>")
	)
	(segment
		(start 86.26094 -305.324764)
		(end 86.05901 -305.70043)
		(width 0.14224)
		(layer "In2.Cu")
		(net "P3E_CPU1_P4_TX_DP<0>")
	)
	(segment
		(start 98.59899 -293.18077)
		(end 98.638106 -293.20363)
		(width 0.1143)
		(layer "In2.Cu")
		(net "P3E_CPU1_P4_TX_DP<0>")
	)
	(segment
		(start 97.981008 -292.716204)
		(end 98.27895 -292.716204)
		(width 0.1143)
		(layer "In2.Cu")
		(net "P3E_CPU1_P4_TX_DP<0>")
	)
	(segment
		(start 98.27895 -292.716204)
		(end 98.361754 -292.799008)
		(width 0.1143)
		(layer "In2.Cu")
		(net "P3E_CPU1_P4_TX_DP<0>")
	)
	(segment
		(start 95.744538 -299.90923)
		(end 91.392248 -301.229522)
		(width 0.14224)
		(layer "In2.Cu")
		(net "P3E_CPU1_P4_TX_DP<0>")
	)
	(segment
		(start 88.701372 -303.024286)
		(end 88.511126 -302.986186)
		(width 0.14224)
		(layer "In2.Cu")
		(net "P3E_CPU1_P4_TX_DP<0>")
	)
	(segment
		(start 85.524848 -306.693824)
		(end 85.33892 -306.749704)
		(width 0.14224)
		(layer "In2.Cu")
		(net "P3E_CPU1_P4_TX_DP<0>")
	)
	(segment
		(start 98.108516 -296.219626)
		(end 98.108516 -297.216068)
		(width 0.1143)
		(layer "In2.Cu")
		(net "P3E_CPU1_P4_TX_DP<0>")
	)
	(segment
		(start 86.593172 -304.707036)
		(end 86.407244 -304.762916)
		(width 0.14224)
		(layer "In2.Cu")
		(net "P3E_CPU1_P4_TX_DP<0>")
	)
	(segment
		(start 88.117934 -303.413414)
		(end 86.82482 -304.275998)
		(width 0.14224)
		(layer "In2.Cu")
		(net "P3E_CPU1_P4_TX_DP<0>")
	)
	(segment
		(start 98.108516 -297.216068)
		(end 98.062796 -297.261788)
		(width 0.1143)
		(layer "In2.Cu")
		(net "P3E_CPU1_P4_TX_DP<0>")
	)
	(segment
		(start 91.392248 -301.229522)
		(end 88.701372 -303.024286)
		(width 0.14224)
		(layer "In2.Cu")
		(net "P3E_CPU1_P4_TX_DP<0>")
	)
	(segment
		(start 98.629216 -293.853616)
		(end 98.627692 -293.854632)
		(width 0.1143)
		(layer "In2.Cu")
		(net "P3E_CPU1_P4_TX_DP<0>")
	)
	(segment
		(start 98.062796 -297.261788)
		(end 98.062796 -297.290236)
		(width 0.1143)
		(layer "In2.Cu")
		(net "P3E_CPU1_P4_TX_DP<0>")
	)
	(segment
		(start 86.407244 -304.762916)
		(end 86.20506 -305.138836)
		(width 0.14224)
		(layer "In2.Cu")
		(net "P3E_CPU1_P4_TX_DP<0>")
	)
	(segment
		(start 98.825812 -295.146222)
		(end 98.825812 -295.50233)
		(width 0.1143)
		(layer "In2.Cu")
		(net "P3E_CPU1_P4_TX_DP<0>")
	)
	(segment
		(start 98.638106 -293.20363)
		(end 98.638868 -293.204138)
		(width 0.1143)
		(layer "In2.Cu")
		(net "P3E_CPU1_P4_TX_DP<0>")
	)
	(segment
		(start 98.638868 -293.848282)
		(end 98.638106 -293.84879)
		(width 0.1143)
		(layer "In2.Cu")
		(net "P3E_CPU1_P4_TX_DP<0>")
	)
	(segment
		(start 88.511126 -302.986186)
		(end 88.156034 -303.223168)
		(width 0.14224)
		(layer "In2.Cu")
		(net "P3E_CPU1_P4_TX_DP<0>")
	)
	(segment
		(start 98.669856 -293.830502)
		(end 98.638868 -293.848282)
		(width 0.1143)
		(layer "In2.Cu")
		(net "P3E_CPU1_P4_TX_DP<0>")
	)
	(segment
		(start 98.638868 -293.204138)
		(end 98.669856 -293.221918)
		(width 0.1143)
		(layer "In2.Cu")
		(net "P3E_CPU1_P4_TX_DP<0>")
	)
	(segment
		(start 84.779358 -308.080156)
		(end 83.354926 -308.931818)
		(width 0.14224)
		(layer "In2.Cu")
		(net "P3E_CPU1_P4_TX_DP<0>")
	)
	(segment
		(start 85.873082 -305.75631)
		(end 85.670898 -306.13223)
		(width 0.14224)
		(layer "In2.Cu")
		(net "P3E_CPU1_P4_TX_DP<0>")
	)
	(segment
		(start 85.136736 -307.125624)
		(end 85.192616 -307.311552)
		(width 0.14224)
		(layer "In2.Cu")
		(net "P3E_CPU1_P4_TX_DP<0>")
	)
	(segment
		(start 86.05901 -305.70043)
		(end 85.873082 -305.75631)
		(width 0.14224)
		(layer "In2.Cu")
		(net "P3E_CPU1_P4_TX_DP<0>")
	)
	(segment
		(start 98.634296 -293.850822)
		(end 98.631502 -293.852346)
		(width 0.1143)
		(layer "In2.Cu")
		(net "P3E_CPU1_P4_TX_DP<0>")
	)
	(segment
		(start 98.627692 -293.854632)
		(end 98.59899 -293.87165)
		(width 0.1143)
		(layer "In2.Cu")
		(net "P3E_CPU1_P4_TX_DP<0>")
	)
	(segment
		(start 88.156034 -303.223168)
		(end 88.117934 -303.413414)
		(width 0.14224)
		(layer "In2.Cu")
		(net "P3E_CPU1_P4_TX_DP<0>")
	)
	(segment
		(start 98.59899 -294.800782)
		(end 98.669348 -294.841676)
		(width 0.1143)
		(layer "In2.Cu")
		(net "P3E_CPU1_P4_TX_DP<0>")
	)
	(segment
		(start 98.825812 -295.50233)
		(end 98.108516 -296.219626)
		(width 0.1143)
		(layer "In2.Cu")
		(net "P3E_CPU1_P4_TX_DP<0>")
	)
	(segment
		(start 79.864966 -308.931818)
		(end 79.574136 -308.640988)
		(width 0.14224)
		(layer "In2.Cu")
		(net "P3E_CPU1_P4_TX_DP<0>")
	)
	(arc
		(start 98.669348 -294.841676)
		(mid 98.784399 -294.975031)
		(end 98.825812 -295.146222)
		(width 0.1143)
		(layer "In2.Cu")
		(net "P3E_CPU1_P4_TX_DP<0>")
	)
	(arc
		(start 98.59899 -293.87165)
		(mid 98.355663 -294.336216)
		(end 98.59899 -294.800782)
		(width 0.1143)
		(layer "In2.Cu")
		(net "P3E_CPU1_P4_TX_DP<0>")
	)
	(arc
		(start 98.361754 -292.799008)
		(mid 98.440833 -293.014453)
		(end 98.59899 -293.18077)
		(width 0.1143)
		(layer "In2.Cu")
		(net "P3E_CPU1_P4_TX_DP<0>")
	)
	(arc
		(start 98.681794 -293.2303)
		(mid 98.833454 -293.52621)
		(end 98.681794 -293.82212)
		(width 0.1143)
		(layer "In2.Cu")
		(net "P3E_CPU1_P4_TX_DP<0>")
	)
	(segment
		(start 153.831798 -61.188854)
		(end 162.195256 -62.663578)
		(width 0.14224)
		(layer "In6.Cu")
		(net "P3E_CPU1_P4_TX_DP<0>")
	)
	(segment
		(start 167.235632 -61.774578)
		(end 173.600364 -57.318148)
		(width 0.14224)
		(layer "In6.Cu")
		(net "P3E_CPU1_P4_TX_DP<0>")
	)
	(segment
		(start 9.106408 -169.42943)
		(end 9.397238 -169.72026)
		(width 0.14224)
		(layer "In6.Cu")
		(net "P3E_CPU1_P4_TX_DP<0>")
	)
	(segment
		(start 116.751608 -65.215008)
		(end 153.831798 -61.188854)
		(width 0.14224)
		(layer "In6.Cu")
		(net "P3E_CPU1_P4_TX_DP<0>")
	)
	(segment
		(start 173.600364 -57.318148)
		(end 174.257716 -56.660796)
		(width 0.14224)
		(layer "In6.Cu")
		(net "P3E_CPU1_P4_TX_DP<0>")
	)
	(segment
		(start 177.96891 -44.407328)
		(end 181.750716 -44.407328)
		(width 0.14224)
		(layer "In6.Cu")
		(net "P3E_CPU1_P4_TX_DP<0>")
	)
	(segment
		(start 162.195256 -62.663578)
		(end 167.235632 -61.774578)
		(width 0.14224)
		(layer "In6.Cu")
		(net "P3E_CPU1_P4_TX_DP<0>")
	)
	(segment
		(start 174.257716 -48.118522)
		(end 177.96891 -44.407328)
		(width 0.14224)
		(layer "In6.Cu")
		(net "P3E_CPU1_P4_TX_DP<0>")
	)
	(segment
		(start 25.92705 -166.375588)
		(end 37.790882 -154.511756)
		(width 0.14224)
		(layer "In6.Cu")
		(net "P3E_CPU1_P4_TX_DP<0>")
	)
	(segment
		(start 99.533456 -75.116182)
		(end 112.638078 -65.940178)
		(width 0.14224)
		(layer "In6.Cu")
		(net "P3E_CPU1_P4_TX_DP<0>")
	)
	(segment
		(start 174.257716 -56.660796)
		(end 174.257716 -48.118522)
		(width 0.14224)
		(layer "In6.Cu")
		(net "P3E_CPU1_P4_TX_DP<0>")
	)
	(segment
		(start 45.681646 -135.46201)
		(end 84.3661 -96.777556)
		(width 0.14224)
		(layer "In6.Cu")
		(net "P3E_CPU1_P4_TX_DP<0>")
	)
	(segment
		(start 84.3661 -96.777556)
		(end 99.533456 -75.116182)
		(width 0.14224)
		(layer "In6.Cu")
		(net "P3E_CPU1_P4_TX_DP<0>")
	)
	(segment
		(start 12.658344 -169.72026)
		(end 22.65172 -167.732202)
		(width 0.14224)
		(layer "In6.Cu")
		(net "P3E_CPU1_P4_TX_DP<0>")
	)
	(segment
		(start 112.638078 -65.940178)
		(end 116.751608 -65.215008)
		(width 0.14224)
		(layer "In6.Cu")
		(net "P3E_CPU1_P4_TX_DP<0>")
	)
	(segment
		(start 9.397238 -169.72026)
		(end 12.658344 -169.72026)
		(width 0.14224)
		(layer "In6.Cu")
		(net "P3E_CPU1_P4_TX_DP<0>")
	)
	(segment
		(start 37.790882 -154.511756)
		(end 45.681646 -135.46201)
		(width 0.14224)
		(layer "In6.Cu")
		(net "P3E_CPU1_P4_TX_DP<0>")
	)
	(segment
		(start 22.65172 -167.732202)
		(end 25.92705 -166.375588)
		(width 0.14224)
		(layer "In6.Cu")
		(net "P3E_CPU1_P4_TX_DP<0>")
	)
	(segment
		(start 181.750716 -44.407328)
		(end 182.041546 -44.116498)
		(width 0.14224)
		(layer "In6.Cu")
		(net "P3E_CPU1_P4_TX_DP<0>")
	)
	(segment
		(start 15.282418 -309.385462)
		(end 11.96594 -211.271612)
		(width 0.14224)
		(layer "In15.Cu")
		(net "P3E_CPU1_P4_TX_DP<0>")
	)
	(segment
		(start 15.358618 -311.629806)
		(end 15.344394 -311.20588)
		(width 0.14224)
		(layer "In15.Cu")
		(net "P3E_CPU1_P4_TX_DP<0>")
	)
	(segment
		(start 15.382494 -312.328052)
		(end 15.515082 -312.186574)
		(width 0.14224)
		(layer "In15.Cu")
		(net "P3E_CPU1_P4_TX_DP<0>")
	)
	(segment
		(start 15.553182 -313.308746)
		(end 15.538704 -312.884312)
		(width 0.14224)
		(layer "In15.Cu")
		(net "P3E_CPU1_P4_TX_DP<0>")
	)
	(segment
		(start 12.967716 -183.367426)
		(end 13.018516 -181.948836)
		(width 0.14224)
		(layer "In15.Cu")
		(net "P3E_CPU1_P4_TX_DP<0>")
	)
	(segment
		(start 71.373492 -311.790334)
		(end 59.191144 -319.931034)
		(width 0.14224)
		(layer "In15.Cu")
		(net "P3E_CPU1_P4_TX_DP<0>")
	)
	(segment
		(start 71.931276 -311.559702)
		(end 71.373492 -311.790334)
		(width 0.14224)
		(layer "In15.Cu")
		(net "P3E_CPU1_P4_TX_DP<0>")
	)
	(segment
		(start 9.715246 -169.72026)
		(end 9.397238 -169.72026)
		(width 0.14224)
		(layer "In15.Cu")
		(net "P3E_CPU1_P4_TX_DP<0>")
	)
	(segment
		(start 16.122142 -317.328804)
		(end 15.434818 -313.87415)
		(width 0.14224)
		(layer "In15.Cu")
		(net "P3E_CPU1_P4_TX_DP<0>")
	)
	(segment
		(start 15.320518 -310.507634)
		(end 15.306294 -310.083708)
		(width 0.14224)
		(layer "In15.Cu")
		(net "P3E_CPU1_P4_TX_DP<0>")
	)
	(segment
		(start 15.515082 -312.186574)
		(end 15.500604 -311.76214)
		(width 0.14224)
		(layer "In15.Cu")
		(net "P3E_CPU1_P4_TX_DP<0>")
	)
	(segment
		(start 15.438882 -309.94223)
		(end 15.424404 -309.517796)
		(width 0.14224)
		(layer "In15.Cu")
		(net "P3E_CPU1_P4_TX_DP<0>")
	)
	(segment
		(start 57.093612 -319.923414)
		(end 19.305524 -319.743582)
		(width 0.14224)
		(layer "In15.Cu")
		(net "P3E_CPU1_P4_TX_DP<0>")
	)
	(segment
		(start 15.476982 -311.064402)
		(end 15.462504 -310.639968)
		(width 0.14224)
		(layer "In15.Cu")
		(net "P3E_CPU1_P4_TX_DP<0>")
	)
	(segment
		(start 15.434818 -313.87415)
		(end 15.420594 -313.450224)
		(width 0.14224)
		(layer "In15.Cu")
		(net "P3E_CPU1_P4_TX_DP<0>")
	)
	(segment
		(start 59.191144 -319.931034)
		(end 57.093612 -319.931034)
		(width 0.14224)
		(layer "In15.Cu")
		(net "P3E_CPU1_P4_TX_DP<0>")
	)
	(segment
		(start 15.500604 -311.76214)
		(end 15.358618 -311.629806)
		(width 0.14224)
		(layer "In15.Cu")
		(net "P3E_CPU1_P4_TX_DP<0>")
	)
	(segment
		(start 79.283306 -308.931818)
		(end 78.27645 -308.931818)
		(width 0.14224)
		(layer "In15.Cu")
		(net "P3E_CPU1_P4_TX_DP<0>")
	)
	(segment
		(start 15.344394 -311.20588)
		(end 15.476982 -311.064402)
		(width 0.14224)
		(layer "In15.Cu")
		(net "P3E_CPU1_P4_TX_DP<0>")
	)
	(segment
		(start 57.093612 -319.931034)
		(end 57.093612 -319.923414)
		(width 0.14224)
		(layer "In15.Cu")
		(net "P3E_CPU1_P4_TX_DP<0>")
	)
	(segment
		(start 79.574136 -308.640988)
		(end 79.283306 -308.931818)
		(width 0.14224)
		(layer "In15.Cu")
		(net "P3E_CPU1_P4_TX_DP<0>")
	)
	(segment
		(start 15.306294 -310.083708)
		(end 15.438882 -309.94223)
		(width 0.14224)
		(layer "In15.Cu")
		(net "P3E_CPU1_P4_TX_DP<0>")
	)
	(segment
		(start 15.538704 -312.884312)
		(end 15.396718 -312.751978)
		(width 0.14224)
		(layer "In15.Cu")
		(net "P3E_CPU1_P4_TX_DP<0>")
	)
	(segment
		(start 11.96594 -211.271612)
		(end 12.967716 -183.367426)
		(width 0.14224)
		(layer "In15.Cu")
		(net "P3E_CPU1_P4_TX_DP<0>")
	)
	(segment
		(start 19.305524 -319.743582)
		(end 17.094708 -319.353692)
		(width 0.14224)
		(layer "In15.Cu")
		(net "P3E_CPU1_P4_TX_DP<0>")
	)
	(segment
		(start 17.094708 -319.353692)
		(end 16.866108 -319.125092)
		(width 0.14224)
		(layer "In15.Cu")
		(net "P3E_CPU1_P4_TX_DP<0>")
	)
	(segment
		(start 15.420594 -313.450224)
		(end 15.553182 -313.308746)
		(width 0.14224)
		(layer "In15.Cu")
		(net "P3E_CPU1_P4_TX_DP<0>")
	)
	(segment
		(start 15.396718 -312.751978)
		(end 15.382494 -312.328052)
		(width 0.14224)
		(layer "In15.Cu")
		(net "P3E_CPU1_P4_TX_DP<0>")
	)
	(segment
		(start 78.27645 -308.931818)
		(end 71.931022 -311.559448)
		(width 0.14224)
		(layer "In15.Cu")
		(net "P3E_CPU1_P4_TX_DP<0>")
	)
	(segment
		(start 10.758424 -170.763438)
		(end 9.715246 -169.72026)
		(width 0.14224)
		(layer "In15.Cu")
		(net "P3E_CPU1_P4_TX_DP<0>")
	)
	(segment
		(start 13.018516 -181.948836)
		(end 13.018516 -176.22012)
		(width 0.14224)
		(layer "In15.Cu")
		(net "P3E_CPU1_P4_TX_DP<0>")
	)
	(segment
		(start 15.462504 -310.639968)
		(end 15.320518 -310.507634)
		(width 0.14224)
		(layer "In15.Cu")
		(net "P3E_CPU1_P4_TX_DP<0>")
	)
	(segment
		(start 71.931022 -311.559448)
		(end 71.931276 -311.559702)
		(width 0.14224)
		(layer "In15.Cu")
		(net "P3E_CPU1_P4_TX_DP<0>")
	)
	(segment
		(start 9.397238 -169.72026)
		(end 9.106408 -169.42943)
		(width 0.14224)
		(layer "In15.Cu")
		(net "P3E_CPU1_P4_TX_DP<0>")
	)
	(segment
		(start 15.424404 -309.517796)
		(end 15.282418 -309.385462)
		(width 0.14224)
		(layer "In15.Cu")
		(net "P3E_CPU1_P4_TX_DP<0>")
	)
	(segment
		(start 13.018516 -176.22012)
		(end 10.758424 -170.763438)
		(width 0.14224)
		(layer "In15.Cu")
		(net "P3E_CPU1_P4_TX_DP<0>")
	)
	(segment
		(start 16.866108 -319.125092)
		(end 16.122142 -317.328804)
		(width 0.14224)
		(layer "In15.Cu")
		(net "P3E_CPU1_P4_TX_DP<0>")
	)
	(segment
		(start 181.76494 -53.678328)
		(end 182.041546 -53.954934)
		(width 0.12954)
		(layer "F.Cu")
		(net "P3E_CPU1_P4_TX_DN<3>")
	)
	(segment
		(start 107.847892 -292.450266)
		(end 107.38104 -292.716204)
		(width 0.12954)
		(layer "F.Cu")
		(net "P3E_CPU1_P4_TX_DN<3>")
	)
	(segment
		(start 181.097174 -53.678328)
		(end 181.76494 -53.678328)
		(width 0.12954)
		(layer "F.Cu")
		(net "P3E_CPU1_P4_TX_DN<3>")
	)
	(segment
		(start 180.795168 -53.980334)
		(end 181.097174 -53.678328)
		(width 0.12954)
		(layer "F.Cu")
		(net "P3E_CPU1_P4_TX_DN<3>")
	)
	(segment
		(start 98.991928 -314.71743)
		(end 98.71202 -314.997338)
		(width 0.14224)
		(layer "In2.Cu")
		(net "P3E_CPU1_P4_TX_DN<3>")
	)
	(segment
		(start 107.200192 -293.042086)
		(end 107.208828 -293.04742)
		(width 0.1143)
		(layer "In2.Cu")
		(net "P3E_CPU1_P4_TX_DN<3>")
	)
	(segment
		(start 106.53649 -295.456356)
		(end 106.58221 -295.502076)
		(width 0.1143)
		(layer "In2.Cu")
		(net "P3E_CPU1_P4_TX_DN<3>")
	)
	(segment
		(start 106.58221 -296.120566)
		(end 107.431586 -296.969942)
		(width 0.14224)
		(layer "In2.Cu")
		(net "P3E_CPU1_P4_TX_DN<3>")
	)
	(segment
		(start 107.208828 -293.04742)
		(end 107.211114 -293.04869)
		(width 0.1143)
		(layer "In2.Cu")
		(net "P3E_CPU1_P4_TX_DN<3>")
	)
	(segment
		(start 107.197398 -293.040562)
		(end 107.200192 -293.042086)
		(width 0.1143)
		(layer "In2.Cu")
		(net "P3E_CPU1_P4_TX_DN<3>")
	)
	(segment
		(start 107.083098 -292.716204)
		(end 107.013248 -292.786054)
		(width 0.1143)
		(layer "In2.Cu")
		(net "P3E_CPU1_P4_TX_DN<3>")
	)
	(segment
		(start 106.77144 -294.793162)
		(end 106.71302 -294.835326)
		(width 0.1143)
		(layer "In2.Cu")
		(net "P3E_CPU1_P4_TX_DN<3>")
	)
	(segment
		(start 107.431586 -296.969942)
		(end 107.431586 -301.051468)
		(width 0.14224)
		(layer "In2.Cu")
		(net "P3E_CPU1_P4_TX_DN<3>")
	)
	(segment
		(start 107.188 -294.017192)
		(end 107.186984 -294.0177)
		(width 0.1143)
		(layer "In2.Cu")
		(net "P3E_CPU1_P4_TX_DN<3>")
	)
	(segment
		(start 107.193334 -294.014144)
		(end 107.19054 -294.015668)
		(width 0.1143)
		(layer "In2.Cu")
		(net "P3E_CPU1_P4_TX_DN<3>")
	)
	(segment
		(start 107.38104 -292.716204)
		(end 107.083098 -292.716204)
		(width 0.1143)
		(layer "In2.Cu")
		(net "P3E_CPU1_P4_TX_DN<3>")
	)
	(segment
		(start 103.280972 -311.814464)
		(end 100.727764 -314.367418)
		(width 0.14224)
		(layer "In2.Cu")
		(net "P3E_CPU1_P4_TX_DN<3>")
	)
	(segment
		(start 107.193588 -293.03853)
		(end 107.19435 -293.039038)
		(width 0.1143)
		(layer "In2.Cu")
		(net "P3E_CPU1_P4_TX_DN<3>")
	)
	(segment
		(start 107.21213 -293.049198)
		(end 107.212892 -293.049706)
		(width 0.1143)
		(layer "In2.Cu")
		(net "P3E_CPU1_P4_TX_DN<3>")
	)
	(segment
		(start 107.188762 -294.016684)
		(end 107.188 -294.017192)
		(width 0.1143)
		(layer "In2.Cu")
		(net "P3E_CPU1_P4_TX_DN<3>")
	)
	(segment
		(start 106.58221 -295.502076)
		(end 106.58221 -295.530524)
		(width 0.1143)
		(layer "In2.Cu")
		(net "P3E_CPU1_P4_TX_DN<3>")
	)
	(segment
		(start 107.189778 -294.016176)
		(end 107.188762 -294.016684)
		(width 0.1143)
		(layer "In2.Cu")
		(net "P3E_CPU1_P4_TX_DN<3>")
	)
	(segment
		(start 107.19435 -293.039038)
		(end 107.197398 -293.040562)
		(width 0.1143)
		(layer "In2.Cu")
		(net "P3E_CPU1_P4_TX_DN<3>")
	)
	(segment
		(start 107.216956 -293.051992)
		(end 107.230418 -293.059866)
		(width 0.1143)
		(layer "In2.Cu")
		(net "P3E_CPU1_P4_TX_DN<3>")
	)
	(segment
		(start 107.186984 -294.0177)
		(end 107.162346 -294.031924)
		(width 0.1143)
		(layer "In2.Cu")
		(net "P3E_CPU1_P4_TX_DN<3>")
	)
	(segment
		(start 100.727764 -314.367418)
		(end 99.882452 -314.71743)
		(width 0.14224)
		(layer "In2.Cu")
		(net "P3E_CPU1_P4_TX_DN<3>")
	)
	(segment
		(start 107.211114 -293.04869)
		(end 107.21213 -293.049198)
		(width 0.1143)
		(layer "In2.Cu")
		(net "P3E_CPU1_P4_TX_DN<3>")
	)
	(segment
		(start 107.19054 -294.015668)
		(end 107.189778 -294.016176)
		(width 0.1143)
		(layer "In2.Cu")
		(net "P3E_CPU1_P4_TX_DN<3>")
	)
	(segment
		(start 107.213908 -293.050214)
		(end 107.215178 -293.050976)
		(width 0.1143)
		(layer "In2.Cu")
		(net "P3E_CPU1_P4_TX_DN<3>")
	)
	(segment
		(start 107.212892 -293.049706)
		(end 107.213908 -293.050214)
		(width 0.1143)
		(layer "In2.Cu")
		(net "P3E_CPU1_P4_TX_DN<3>")
	)
	(segment
		(start 107.194096 -294.013636)
		(end 107.193334 -294.014144)
		(width 0.1143)
		(layer "In2.Cu")
		(net "P3E_CPU1_P4_TX_DN<3>")
	)
	(segment
		(start 107.431586 -301.051468)
		(end 103.280972 -311.814464)
		(width 0.14224)
		(layer "In2.Cu")
		(net "P3E_CPU1_P4_TX_DN<3>")
	)
	(segment
		(start 99.882452 -314.71743)
		(end 98.991928 -314.71743)
		(width 0.14224)
		(layer "In2.Cu")
		(net "P3E_CPU1_P4_TX_DN<3>")
	)
	(segment
		(start 106.58221 -295.530524)
		(end 106.58221 -296.120566)
		(width 0.14224)
		(layer "In2.Cu")
		(net "P3E_CPU1_P4_TX_DN<3>")
	)
	(segment
		(start 107.162346 -293.020496)
		(end 107.193588 -293.03853)
		(width 0.1143)
		(layer "In2.Cu")
		(net "P3E_CPU1_P4_TX_DN<3>")
	)
	(segment
		(start 107.216194 -293.051484)
		(end 107.216956 -293.051992)
		(width 0.1143)
		(layer "In2.Cu")
		(net "P3E_CPU1_P4_TX_DN<3>")
	)
	(segment
		(start 107.215178 -293.050976)
		(end 107.216194 -293.051484)
		(width 0.1143)
		(layer "In2.Cu")
		(net "P3E_CPU1_P4_TX_DN<3>")
	)
	(segment
		(start 107.230418 -293.992554)
		(end 107.194096 -294.013636)
		(width 0.1143)
		(layer "In2.Cu")
		(net "P3E_CPU1_P4_TX_DN<3>")
	)
	(segment
		(start 106.53649 -295.180004)
		(end 106.53649 -295.456356)
		(width 0.1143)
		(layer "In2.Cu")
		(net "P3E_CPU1_P4_TX_DN<3>")
	)
	(arc
		(start 107.00639 -294.336216)
		(mid 106.943841 -294.592937)
		(end 106.77144 -294.793162)
		(width 0.1143)
		(layer "In2.Cu")
		(net "P3E_CPU1_P4_TX_DN<3>")
	)
	(arc
		(start 107.013248 -292.786054)
		(mid 107.065297 -292.917573)
		(end 107.162346 -293.020496)
		(width 0.1143)
		(layer "In2.Cu")
		(net "P3E_CPU1_P4_TX_DN<3>")
	)
	(arc
		(start 107.244642 -293.069772)
		(mid 107.472025 -293.52621)
		(end 107.244642 -293.982648)
		(width 0.1143)
		(layer "In2.Cu")
		(net "P3E_CPU1_P4_TX_DN<3>")
	)
	(arc
		(start 107.244642 -293.982648)
		(mid 107.237568 -293.987655)
		(end 107.230418 -293.992554)
		(width 0.1143)
		(layer "In2.Cu")
		(net "P3E_CPU1_P4_TX_DN<3>")
	)
	(arc
		(start 107.162346 -294.031924)
		(mid 107.047942 -294.165407)
		(end 107.00639 -294.336216)
		(width 0.1143)
		(layer "In2.Cu")
		(net "P3E_CPU1_P4_TX_DN<3>")
	)
	(arc
		(start 107.230418 -293.059866)
		(mid 107.237567 -293.064766)
		(end 107.244642 -293.069772)
		(width 0.1143)
		(layer "In2.Cu")
		(net "P3E_CPU1_P4_TX_DN<3>")
	)
	(arc
		(start 106.71302 -294.835326)
		(mid 106.583168 -294.98637)
		(end 106.53649 -295.180004)
		(width 0.1143)
		(layer "In2.Cu")
		(net "P3E_CPU1_P4_TX_DN<3>")
	)
	(segment
		(start 41.012364 -155.782518)
		(end 48.870362 -136.811512)
		(width 0.14224)
		(layer "In6.Cu")
		(net "P3E_CPU1_P4_TX_DN<3>")
	)
	(segment
		(start 177.505868 -57.87644)
		(end 177.505868 -54.053486)
		(width 0.14224)
		(layer "In6.Cu")
		(net "P3E_CPU1_P4_TX_DN<3>")
	)
	(segment
		(start 9.983216 -178.327558)
		(end 15.183104 -175.868076)
		(width 0.14224)
		(layer "In6.Cu")
		(net "P3E_CPU1_P4_TX_DN<3>")
	)
	(segment
		(start 177.505868 -54.053486)
		(end 177.89525 -53.664104)
		(width 0.14224)
		(layer "In6.Cu")
		(net "P3E_CPU1_P4_TX_DN<3>")
	)
	(segment
		(start 152.957784 -64.516254)
		(end 161.441892 -66.025776)
		(width 0.14224)
		(layer "In6.Cu")
		(net "P3E_CPU1_P4_TX_DN<3>")
	)
	(segment
		(start 181.750716 -53.664104)
		(end 182.041546 -53.954934)
		(width 0.14224)
		(layer "In6.Cu")
		(net "P3E_CPU1_P4_TX_DN<3>")
	)
	(segment
		(start 86.895432 -98.786442)
		(end 101.848412 -77.431138)
		(width 0.14224)
		(layer "In6.Cu")
		(net "P3E_CPU1_P4_TX_DN<3>")
	)
	(segment
		(start 9.106408 -178.618388)
		(end 9.397238 -178.327558)
		(width 0.14224)
		(layer "In6.Cu")
		(net "P3E_CPU1_P4_TX_DN<3>")
	)
	(segment
		(start 161.441892 -66.025776)
		(end 168.481502 -64.784224)
		(width 0.14224)
		(layer "In6.Cu")
		(net "P3E_CPU1_P4_TX_DN<3>")
	)
	(segment
		(start 101.848412 -77.431138)
		(end 113.92027 -68.978526)
		(width 0.14224)
		(layer "In6.Cu")
		(net "P3E_CPU1_P4_TX_DN<3>")
	)
	(segment
		(start 168.481502 -64.784224)
		(end 175.539654 -59.842654)
		(width 0.14224)
		(layer "In6.Cu")
		(net "P3E_CPU1_P4_TX_DN<3>")
	)
	(segment
		(start 175.539654 -59.842654)
		(end 177.505868 -57.87644)
		(width 0.14224)
		(layer "In6.Cu")
		(net "P3E_CPU1_P4_TX_DN<3>")
	)
	(segment
		(start 27.25801 -169.413936)
		(end 27.629104 -169.165778)
		(width 0.14224)
		(layer "In6.Cu")
		(net "P3E_CPU1_P4_TX_DN<3>")
	)
	(segment
		(start 177.89525 -53.664104)
		(end 181.750716 -53.664104)
		(width 0.14224)
		(layer "In6.Cu")
		(net "P3E_CPU1_P4_TX_DN<3>")
	)
	(segment
		(start 113.92027 -68.978526)
		(end 116.518436 -68.520564)
		(width 0.14224)
		(layer "In6.Cu")
		(net "P3E_CPU1_P4_TX_DN<3>")
	)
	(segment
		(start 27.629104 -169.165778)
		(end 41.012364 -155.782518)
		(width 0.14224)
		(layer "In6.Cu")
		(net "P3E_CPU1_P4_TX_DN<3>")
	)
	(segment
		(start 48.870362 -136.811512)
		(end 86.895432 -98.786442)
		(width 0.14224)
		(layer "In6.Cu")
		(net "P3E_CPU1_P4_TX_DN<3>")
	)
	(segment
		(start 116.518436 -68.52031)
		(end 152.957784 -64.516254)
		(width 0.14224)
		(layer "In6.Cu")
		(net "P3E_CPU1_P4_TX_DN<3>")
	)
	(segment
		(start 9.397238 -178.327558)
		(end 9.983216 -178.327558)
		(width 0.14224)
		(layer "In6.Cu")
		(net "P3E_CPU1_P4_TX_DN<3>")
	)
	(segment
		(start 15.183104 -175.868076)
		(end 27.25801 -169.413936)
		(width 0.14224)
		(layer "In6.Cu")
		(net "P3E_CPU1_P4_TX_DN<3>")
	)
	(segment
		(start 116.518436 -68.520564)
		(end 116.518436 -68.52031)
		(width 0.14224)
		(layer "In6.Cu")
		(net "P3E_CPU1_P4_TX_DN<3>")
	)
	(segment
		(start 9.774936 -183.36768)
		(end 9.827768 -181.89321)
		(width 0.14224)
		(layer "In15.Cu")
		(net "P3E_CPU1_P4_TX_DN<3>")
	)
	(segment
		(start 8.537448 -217.826336)
		(end 9.774936 -183.36768)
		(width 0.14224)
		(layer "In15.Cu")
		(net "P3E_CPU1_P4_TX_DN<3>")
	)
	(segment
		(start 89.839292 -315.021722)
		(end 89.412826 -315.04255)
		(width 0.14224)
		(layer "In15.Cu")
		(net "P3E_CPU1_P4_TX_DN<3>")
	)
	(segment
		(start 11.548364 -306.916582)
		(end 8.537448 -217.826336)
		(width 0.14224)
		(layer "In15.Cu")
		(net "P3E_CPU1_P4_TX_DN<3>")
	)
	(segment
		(start 19.021806 -322.8975)
		(end 15.566644 -322.288408)
		(width 0.14224)
		(layer "In15.Cu")
		(net "P3E_CPU1_P4_TX_DN<3>")
	)
	(segment
		(start 9.827768 -181.89321)
		(end 9.828022 -181.891178)
		(width 0.14224)
		(layer "In15.Cu")
		(net "P3E_CPU1_P4_TX_DN<3>")
	)
	(segment
		(start 9.828022 -178.557174)
		(end 9.598406 -178.327558)
		(width 0.14224)
		(layer "In15.Cu")
		(net "P3E_CPU1_P4_TX_DN<3>")
	)
	(segment
		(start 91.096084 -314.822332)
		(end 90.965782 -314.96635)
		(width 0.14224)
		(layer "In15.Cu")
		(net "P3E_CPU1_P4_TX_DN<3>")
	)
	(segment
		(start 87.716614 -314.988448)
		(end 87.586312 -315.132466)
		(width 0.14224)
		(layer "In15.Cu")
		(net "P3E_CPU1_P4_TX_DN<3>")
	)
	(segment
		(start 89.412826 -315.04255)
		(end 89.269062 -314.912248)
		(width 0.14224)
		(layer "In15.Cu")
		(net "P3E_CPU1_P4_TX_DN<3>")
	)
	(segment
		(start 13.043662 -318.174116)
		(end 11.701526 -311.428384)
		(width 0.14224)
		(layer "In15.Cu")
		(net "P3E_CPU1_P4_TX_DN<3>")
	)
	(segment
		(start 93.454728 -314.706508)
		(end 91.096084 -314.822332)
		(width 0.14224)
		(layer "In15.Cu")
		(net "P3E_CPU1_P4_TX_DN<3>")
	)
	(segment
		(start 89.269062 -314.912248)
		(end 88.843104 -314.933076)
		(width 0.14224)
		(layer "In15.Cu")
		(net "P3E_CPU1_P4_TX_DN<3>")
	)
	(segment
		(start 9.397238 -178.327558)
		(end 9.106408 -178.618388)
		(width 0.14224)
		(layer "In15.Cu")
		(net "P3E_CPU1_P4_TX_DN<3>")
	)
	(segment
		(start 9.828022 -181.891178)
		(end 9.828022 -178.557174)
		(width 0.14224)
		(layer "In15.Cu")
		(net "P3E_CPU1_P4_TX_DN<3>")
	)
	(segment
		(start 90.539316 -314.987178)
		(end 90.395552 -314.856876)
		(width 0.14224)
		(layer "In15.Cu")
		(net "P3E_CPU1_P4_TX_DN<3>")
	)
	(segment
		(start 14.168628 -320.890138)
		(end 13.043662 -318.174116)
		(width 0.14224)
		(layer "In15.Cu")
		(net "P3E_CPU1_P4_TX_DN<3>")
	)
	(segment
		(start 98.42119 -314.706508)
		(end 93.454728 -314.706508)
		(width 0.14224)
		(layer "In15.Cu")
		(net "P3E_CPU1_P4_TX_DN<3>")
	)
	(segment
		(start 87.586312 -315.132466)
		(end 87.159846 -315.153294)
		(width 0.14224)
		(layer "In15.Cu")
		(net "P3E_CPU1_P4_TX_DN<3>")
	)
	(segment
		(start 87.016082 -315.022992)
		(end 71.269098 -315.796422)
		(width 0.14224)
		(layer "In15.Cu")
		(net "P3E_CPU1_P4_TX_DN<3>")
	)
	(segment
		(start 88.712802 -315.077094)
		(end 88.286336 -315.097922)
		(width 0.14224)
		(layer "In15.Cu")
		(net "P3E_CPU1_P4_TX_DN<3>")
	)
	(segment
		(start 11.701526 -311.428384)
		(end 11.548364 -306.916582)
		(width 0.14224)
		(layer "In15.Cu")
		(net "P3E_CPU1_P4_TX_DN<3>")
	)
	(segment
		(start 98.71202 -314.997338)
		(end 98.42119 -314.706508)
		(width 0.14224)
		(layer "In15.Cu")
		(net "P3E_CPU1_P4_TX_DN<3>")
	)
	(segment
		(start 60.36056 -323.085714)
		(end 58.69051 -323.085714)
		(width 0.14224)
		(layer "In15.Cu")
		(net "P3E_CPU1_P4_TX_DN<3>")
	)
	(segment
		(start 71.269098 -315.796422)
		(end 60.36056 -323.085714)
		(width 0.14224)
		(layer "In15.Cu")
		(net "P3E_CPU1_P4_TX_DN<3>")
	)
	(segment
		(start 88.142572 -314.96762)
		(end 87.716614 -314.988448)
		(width 0.14224)
		(layer "In15.Cu")
		(net "P3E_CPU1_P4_TX_DN<3>")
	)
	(segment
		(start 90.965782 -314.96635)
		(end 90.539316 -314.987178)
		(width 0.14224)
		(layer "In15.Cu")
		(net "P3E_CPU1_P4_TX_DN<3>")
	)
	(segment
		(start 15.566644 -322.288408)
		(end 14.168628 -320.890138)
		(width 0.14224)
		(layer "In15.Cu")
		(net "P3E_CPU1_P4_TX_DN<3>")
	)
	(segment
		(start 9.598406 -178.327558)
		(end 9.397238 -178.327558)
		(width 0.14224)
		(layer "In15.Cu")
		(net "P3E_CPU1_P4_TX_DN<3>")
	)
	(segment
		(start 58.69051 -323.085714)
		(end 19.021806 -322.8975)
		(width 0.14224)
		(layer "In15.Cu")
		(net "P3E_CPU1_P4_TX_DN<3>")
	)
	(segment
		(start 87.159846 -315.153294)
		(end 87.016082 -315.022992)
		(width 0.14224)
		(layer "In15.Cu")
		(net "P3E_CPU1_P4_TX_DN<3>")
	)
	(segment
		(start 88.843104 -314.933076)
		(end 88.712802 -315.077094)
		(width 0.14224)
		(layer "In15.Cu")
		(net "P3E_CPU1_P4_TX_DN<3>")
	)
	(segment
		(start 88.286336 -315.097922)
		(end 88.142572 -314.96762)
		(width 0.14224)
		(layer "In15.Cu")
		(net "P3E_CPU1_P4_TX_DN<3>")
	)
	(segment
		(start 89.969594 -314.877704)
		(end 89.839292 -315.021722)
		(width 0.14224)
		(layer "In15.Cu")
		(net "P3E_CPU1_P4_TX_DN<3>")
	)
	(segment
		(start 90.395552 -314.856876)
		(end 89.969594 -314.877704)
		(width 0.14224)
		(layer "In15.Cu")
		(net "P3E_CPU1_P4_TX_DN<3>")
	)
	(segment
		(start 181.76494 -50.672492)
		(end 182.041546 -50.949098)
		(width 0.12954)
		(layer "F.Cu")
		(net "P3E_CPU1_P4_TX_DN<2>")
	)
	(segment
		(start 105.027984 -292.450266)
		(end 104.561132 -292.716204)
		(width 0.12954)
		(layer "F.Cu")
		(net "P3E_CPU1_P4_TX_DN<2>")
	)
	(segment
		(start 180.795168 -50.974498)
		(end 181.097174 -50.672492)
		(width 0.12954)
		(layer "F.Cu")
		(net "P3E_CPU1_P4_TX_DN<2>")
	)
	(segment
		(start 181.097174 -50.672492)
		(end 181.76494 -50.672492)
		(width 0.12954)
		(layer "F.Cu")
		(net "P3E_CPU1_P4_TX_DN<2>")
	)
	(segment
		(start 104.44099 -293.970964)
		(end 104.41305 -293.99103)
		(width 0.1143)
		(layer "In2.Cu")
		(net "P3E_CPU1_P4_TX_DN<2>")
	)
	(segment
		(start 104.380284 -294.01008)
		(end 104.378506 -294.011096)
		(width 0.1143)
		(layer "In2.Cu")
		(net "P3E_CPU1_P4_TX_DN<2>")
	)
	(segment
		(start 103.95712 -297.677078)
		(end 104.355138 -298.63796)
		(width 0.14224)
		(layer "In2.Cu")
		(net "P3E_CPU1_P4_TX_DN<2>")
	)
	(segment
		(start 104.342438 -293.020496)
		(end 104.343454 -293.021258)
		(width 0.1143)
		(layer "In2.Cu")
		(net "P3E_CPU1_P4_TX_DN<2>")
	)
	(segment
		(start 103.95712 -296.700702)
		(end 103.95712 -296.72915)
		(width 0.1143)
		(layer "In2.Cu")
		(net "P3E_CPU1_P4_TX_DN<2>")
	)
	(segment
		(start 104.355138 -300.062138)
		(end 100.507038 -310.03748)
		(width 0.14224)
		(layer "In2.Cu")
		(net "P3E_CPU1_P4_TX_DN<2>")
	)
	(segment
		(start 104.378506 -294.011096)
		(end 104.377744 -294.011604)
		(width 0.1143)
		(layer "In2.Cu")
		(net "P3E_CPU1_P4_TX_DN<2>")
	)
	(segment
		(start 103.9114 -296.654982)
		(end 103.95712 -296.700702)
		(width 0.1143)
		(layer "In2.Cu")
		(net "P3E_CPU1_P4_TX_DN<2>")
	)
	(segment
		(start 103.94315 -294.800782)
		(end 103.872538 -294.84193)
		(width 0.1143)
		(layer "In2.Cu")
		(net "P3E_CPU1_P4_TX_DN<2>")
	)
	(segment
		(start 104.373426 -293.03853)
		(end 104.413304 -293.06139)
		(width 0.1143)
		(layer "In2.Cu")
		(net "P3E_CPU1_P4_TX_DN<2>")
	)
	(segment
		(start 100.507038 -310.03748)
		(end 100.454714 -310.13527)
		(width 0.14224)
		(layer "In2.Cu")
		(net "P3E_CPU1_P4_TX_DN<2>")
	)
	(segment
		(start 104.41305 -293.99103)
		(end 104.381046 -294.009572)
		(width 0.1143)
		(layer "In2.Cu")
		(net "P3E_CPU1_P4_TX_DN<2>")
	)
	(segment
		(start 103.95712 -296.72915)
		(end 103.95712 -297.677078)
		(width 0.14224)
		(layer "In2.Cu")
		(net "P3E_CPU1_P4_TX_DN<2>")
	)
	(segment
		(start 104.561132 -292.716204)
		(end 104.26319 -292.716204)
		(width 0.1143)
		(layer "In2.Cu")
		(net "P3E_CPU1_P4_TX_DN<2>")
	)
	(segment
		(start 104.343454 -293.021258)
		(end 104.372918 -293.038276)
		(width 0.1143)
		(layer "In2.Cu")
		(net "P3E_CPU1_P4_TX_DN<2>")
	)
	(segment
		(start 104.373426 -294.01389)
		(end 104.370886 -294.015414)
		(width 0.1143)
		(layer "In2.Cu")
		(net "P3E_CPU1_P4_TX_DN<2>")
	)
	(segment
		(start 100.454714 -310.13527)
		(end 100.158296 -310.312816)
		(width 0.14224)
		(layer "In2.Cu")
		(net "P3E_CPU1_P4_TX_DN<2>")
	)
	(segment
		(start 104.413304 -293.06139)
		(end 104.44099 -293.081456)
		(width 0.1143)
		(layer "In2.Cu")
		(net "P3E_CPU1_P4_TX_DN<2>")
	)
	(segment
		(start 104.381046 -294.009572)
		(end 104.380284 -294.01008)
		(width 0.1143)
		(layer "In2.Cu")
		(net "P3E_CPU1_P4_TX_DN<2>")
	)
	(segment
		(start 104.26319 -292.716204)
		(end 104.19334 -292.786054)
		(width 0.1143)
		(layer "In2.Cu")
		(net "P3E_CPU1_P4_TX_DN<2>")
	)
	(segment
		(start 103.716328 -295.146222)
		(end 103.716328 -295.422066)
		(width 0.1143)
		(layer "In2.Cu")
		(net "P3E_CPU1_P4_TX_DN<2>")
	)
	(segment
		(start 104.372918 -293.038276)
		(end 104.373426 -293.03853)
		(width 0.1143)
		(layer "In2.Cu")
		(net "P3E_CPU1_P4_TX_DN<2>")
	)
	(segment
		(start 103.716328 -295.422066)
		(end 103.9114 -296.063162)
		(width 0.1143)
		(layer "In2.Cu")
		(net "P3E_CPU1_P4_TX_DN<2>")
	)
	(segment
		(start 100.158296 -310.312816)
		(end 99.598226 -310.312816)
		(width 0.14224)
		(layer "In2.Cu")
		(net "P3E_CPU1_P4_TX_DN<2>")
	)
	(segment
		(start 99.598226 -310.312816)
		(end 99.307396 -310.603646)
		(width 0.14224)
		(layer "In2.Cu")
		(net "P3E_CPU1_P4_TX_DN<2>")
	)
	(segment
		(start 103.9114 -296.063162)
		(end 103.9114 -296.654982)
		(width 0.1143)
		(layer "In2.Cu")
		(net "P3E_CPU1_P4_TX_DN<2>")
	)
	(segment
		(start 104.355138 -298.63796)
		(end 104.355138 -300.062138)
		(width 0.14224)
		(layer "In2.Cu")
		(net "P3E_CPU1_P4_TX_DN<2>")
	)
	(segment
		(start 104.377744 -294.011604)
		(end 104.373426 -294.01389)
		(width 0.1143)
		(layer "In2.Cu")
		(net "P3E_CPU1_P4_TX_DN<2>")
	)
	(arc
		(start 104.370886 -294.015414)
		(mid 104.235903 -294.151216)
		(end 104.186482 -294.336216)
		(width 0.1143)
		(layer "In2.Cu")
		(net "P3E_CPU1_P4_TX_DN<2>")
	)
	(arc
		(start 104.186482 -294.336216)
		(mid 104.121967 -294.598435)
		(end 103.94315 -294.800782)
		(width 0.1143)
		(layer "In2.Cu")
		(net "P3E_CPU1_P4_TX_DN<2>")
	)
	(arc
		(start 104.19334 -292.786054)
		(mid 104.245389 -292.917573)
		(end 104.342438 -293.020496)
		(width 0.1143)
		(layer "In2.Cu")
		(net "P3E_CPU1_P4_TX_DN<2>")
	)
	(arc
		(start 103.872538 -294.84193)
		(mid 103.757637 -294.975191)
		(end 103.716328 -295.146222)
		(width 0.1143)
		(layer "In2.Cu")
		(net "P3E_CPU1_P4_TX_DN<2>")
	)
	(arc
		(start 104.44099 -293.081456)
		(mid 104.66899 -293.52621)
		(end 104.44099 -293.970964)
		(width 0.1143)
		(layer "In2.Cu")
		(net "P3E_CPU1_P4_TX_DN<2>")
	)
	(segment
		(start 174.902114 -59.13628)
		(end 176.485042 -57.553352)
		(width 0.14224)
		(layer "In6.Cu")
		(net "P3E_CPU1_P4_TX_DN<2>")
	)
	(segment
		(start 161.476436 -65.061084)
		(end 168.111678 -63.890906)
		(width 0.14224)
		(layer "In6.Cu")
		(net "P3E_CPU1_P4_TX_DN<2>")
	)
	(segment
		(start 176.485042 -57.553352)
		(end 176.485042 -52.26177)
		(width 0.14224)
		(layer "In6.Cu")
		(net "P3E_CPU1_P4_TX_DN<2>")
	)
	(segment
		(start 9.397238 -175.557434)
		(end 10.013188 -175.557434)
		(width 0.14224)
		(layer "In6.Cu")
		(net "P3E_CPU1_P4_TX_DN<2>")
	)
	(segment
		(start 85.970364 -98.349816)
		(end 101.077776 -76.77404)
		(width 0.14224)
		(layer "In6.Cu")
		(net "P3E_CPU1_P4_TX_DN<2>")
	)
	(segment
		(start 178.088544 -50.658268)
		(end 181.750716 -50.658268)
		(width 0.14224)
		(layer "In6.Cu")
		(net "P3E_CPU1_P4_TX_DN<2>")
	)
	(segment
		(start 176.485042 -52.26177)
		(end 178.088544 -50.658268)
		(width 0.14224)
		(layer "In6.Cu")
		(net "P3E_CPU1_P4_TX_DN<2>")
	)
	(segment
		(start 152.948894 -63.557404)
		(end 161.476436 -65.061084)
		(width 0.14224)
		(layer "In6.Cu")
		(net "P3E_CPU1_P4_TX_DN<2>")
	)
	(segment
		(start 168.111678 -63.890906)
		(end 174.902114 -59.13628)
		(width 0.14224)
		(layer "In6.Cu")
		(net "P3E_CPU1_P4_TX_DN<2>")
	)
	(segment
		(start 48.053752 -136.26719)
		(end 85.970364 -98.349816)
		(width 0.14224)
		(layer "In6.Cu")
		(net "P3E_CPU1_P4_TX_DN<2>")
	)
	(segment
		(start 10.013188 -175.557434)
		(end 26.752804 -168.623742)
		(width 0.14224)
		(layer "In6.Cu")
		(net "P3E_CPU1_P4_TX_DN<2>")
	)
	(segment
		(start 181.750716 -50.658268)
		(end 182.041546 -50.949098)
		(width 0.14224)
		(layer "In6.Cu")
		(net "P3E_CPU1_P4_TX_DN<2>")
	)
	(segment
		(start 40.23614 -155.140152)
		(end 48.053752 -136.26719)
		(width 0.14224)
		(layer "In6.Cu")
		(net "P3E_CPU1_P4_TX_DN<2>")
	)
	(segment
		(start 116.93271 -67.46621)
		(end 152.948894 -63.557404)
		(width 0.14224)
		(layer "In6.Cu")
		(net "P3E_CPU1_P4_TX_DN<2>")
	)
	(segment
		(start 26.752804 -168.623742)
		(end 40.23614 -155.140152)
		(width 0.14224)
		(layer "In6.Cu")
		(net "P3E_CPU1_P4_TX_DN<2>")
	)
	(segment
		(start 101.077776 -76.77404)
		(end 113.509044 -68.069968)
		(width 0.14224)
		(layer "In6.Cu")
		(net "P3E_CPU1_P4_TX_DN<2>")
	)
	(segment
		(start 113.509044 -68.069968)
		(end 116.93271 -67.46621)
		(width 0.14224)
		(layer "In6.Cu")
		(net "P3E_CPU1_P4_TX_DN<2>")
	)
	(segment
		(start 9.106408 -175.848264)
		(end 9.397238 -175.557434)
		(width 0.14224)
		(layer "In6.Cu")
		(net "P3E_CPU1_P4_TX_DN<2>")
	)
	(segment
		(start 87.659972 -312.558176)
		(end 87.23757 -312.620152)
		(width 0.14224)
		(layer "In15.Cu")
		(net "P3E_CPU1_P4_TX_DN<2>")
	)
	(segment
		(start 86.659974 -312.56605)
		(end 86.54415 -312.722006)
		(width 0.14224)
		(layer "In15.Cu")
		(net "P3E_CPU1_P4_TX_DN<2>")
	)
	(segment
		(start 12.708636 -307.932582)
		(end 9.589516 -215.642444)
		(width 0.14224)
		(layer "In15.Cu")
		(net "P3E_CPU1_P4_TX_DN<2>")
	)
	(segment
		(start 99.016566 -310.312816)
		(end 98.266758 -310.312816)
		(width 0.14224)
		(layer "In15.Cu")
		(net "P3E_CPU1_P4_TX_DN<2>")
	)
	(segment
		(start 94.635828 -311.395364)
		(end 90.288364 -312.033412)
		(width 0.14224)
		(layer "In15.Cu")
		(net "P3E_CPU1_P4_TX_DN<2>")
	)
	(segment
		(start 12.861798 -312.444384)
		(end 12.708636 -307.932582)
		(width 0.14224)
		(layer "In15.Cu")
		(net "P3E_CPU1_P4_TX_DN<2>")
	)
	(segment
		(start 9.844024 -175.803052)
		(end 9.598406 -175.557434)
		(width 0.14224)
		(layer "In15.Cu")
		(net "P3E_CPU1_P4_TX_DN<2>")
	)
	(segment
		(start 89.59469 -312.13552)
		(end 89.10828 -312.206894)
		(width 0.14224)
		(layer "In15.Cu")
		(net "P3E_CPU1_P4_TX_DN<2>")
	)
	(segment
		(start 97.18421 -311.395364)
		(end 94.635828 -311.395364)
		(width 0.14224)
		(layer "In15.Cu")
		(net "P3E_CPU1_P4_TX_DN<2>")
	)
	(segment
		(start 89.750138 -312.251344)
		(end 89.59469 -312.13552)
		(width 0.14224)
		(layer "In15.Cu")
		(net "P3E_CPU1_P4_TX_DN<2>")
	)
	(segment
		(start 87.23757 -312.620152)
		(end 87.082122 -312.504328)
		(width 0.14224)
		(layer "In15.Cu")
		(net "P3E_CPU1_P4_TX_DN<2>")
	)
	(segment
		(start 87.775796 -312.40222)
		(end 87.659972 -312.558176)
		(width 0.14224)
		(layer "In15.Cu")
		(net "P3E_CPU1_P4_TX_DN<2>")
	)
	(segment
		(start 88.992456 -312.362596)
		(end 88.570054 -312.424572)
		(width 0.14224)
		(layer "In15.Cu")
		(net "P3E_CPU1_P4_TX_DN<2>")
	)
	(segment
		(start 19.107912 -321.940174)
		(end 16.030448 -321.39763)
		(width 0.14224)
		(layer "In15.Cu")
		(net "P3E_CPU1_P4_TX_DN<2>")
	)
	(segment
		(start 9.598406 -175.557434)
		(end 9.397238 -175.557434)
		(width 0.14224)
		(layer "In15.Cu")
		(net "P3E_CPU1_P4_TX_DN<2>")
	)
	(segment
		(start 9.589516 -215.642444)
		(end 10.800842 -181.908704)
		(width 0.14224)
		(layer "In15.Cu")
		(net "P3E_CPU1_P4_TX_DN<2>")
	)
	(segment
		(start 13.922756 -317.776606)
		(end 12.861798 -312.444384)
		(width 0.14224)
		(layer "In15.Cu")
		(net "P3E_CPU1_P4_TX_DN<2>")
	)
	(segment
		(start 87.082122 -312.504328)
		(end 86.659974 -312.56605)
		(width 0.14224)
		(layer "In15.Cu")
		(net "P3E_CPU1_P4_TX_DN<2>")
	)
	(segment
		(start 99.307396 -310.603646)
		(end 99.016566 -310.312816)
		(width 0.14224)
		(layer "In15.Cu")
		(net "P3E_CPU1_P4_TX_DN<2>")
	)
	(segment
		(start 85.9663 -312.668158)
		(end 70.794372 -314.894214)
		(width 0.14224)
		(layer "In15.Cu")
		(net "P3E_CPU1_P4_TX_DN<2>")
	)
	(segment
		(start 88.414352 -312.308748)
		(end 87.775796 -312.40222)
		(width 0.14224)
		(layer "In15.Cu")
		(net "P3E_CPU1_P4_TX_DN<2>")
	)
	(segment
		(start 10.800842 -178.112928)
		(end 9.844024 -175.803052)
		(width 0.14224)
		(layer "In15.Cu")
		(net "P3E_CPU1_P4_TX_DN<2>")
	)
	(segment
		(start 10.800842 -181.908704)
		(end 10.800842 -178.112928)
		(width 0.14224)
		(layer "In15.Cu")
		(net "P3E_CPU1_P4_TX_DN<2>")
	)
	(segment
		(start 98.266758 -310.312816)
		(end 97.18421 -311.395364)
		(width 0.14224)
		(layer "In15.Cu")
		(net "P3E_CPU1_P4_TX_DN<2>")
	)
	(segment
		(start 86.121748 -312.783982)
		(end 85.9663 -312.668158)
		(width 0.14224)
		(layer "In15.Cu")
		(net "P3E_CPU1_P4_TX_DN<2>")
	)
	(segment
		(start 88.570054 -312.424572)
		(end 88.414352 -312.308748)
		(width 0.14224)
		(layer "In15.Cu")
		(net "P3E_CPU1_P4_TX_DN<2>")
	)
	(segment
		(start 90.172794 -312.189368)
		(end 89.750138 -312.251344)
		(width 0.14224)
		(layer "In15.Cu")
		(net "P3E_CPU1_P4_TX_DN<2>")
	)
	(segment
		(start 86.54415 -312.722006)
		(end 86.121748 -312.783982)
		(width 0.14224)
		(layer "In15.Cu")
		(net "P3E_CPU1_P4_TX_DN<2>")
	)
	(segment
		(start 58.68543 -322.128134)
		(end 19.107912 -321.940174)
		(width 0.14224)
		(layer "In15.Cu")
		(net "P3E_CPU1_P4_TX_DN<2>")
	)
	(segment
		(start 89.10828 -312.206894)
		(end 88.992456 -312.362596)
		(width 0.14224)
		(layer "In15.Cu")
		(net "P3E_CPU1_P4_TX_DN<2>")
	)
	(segment
		(start 16.030448 -321.39763)
		(end 14.992858 -320.36004)
		(width 0.14224)
		(layer "In15.Cu")
		(net "P3E_CPU1_P4_TX_DN<2>")
	)
	(segment
		(start 9.397238 -175.557434)
		(end 9.106408 -175.848264)
		(width 0.14224)
		(layer "In15.Cu")
		(net "P3E_CPU1_P4_TX_DN<2>")
	)
	(segment
		(start 59.968638 -322.128134)
		(end 58.68543 -322.128134)
		(width 0.14224)
		(layer "In15.Cu")
		(net "P3E_CPU1_P4_TX_DN<2>")
	)
	(segment
		(start 90.288364 -312.033412)
		(end 90.172794 -312.189368)
		(width 0.14224)
		(layer "In15.Cu")
		(net "P3E_CPU1_P4_TX_DN<2>")
	)
	(segment
		(start 70.794372 -314.894214)
		(end 59.968638 -322.128134)
		(width 0.14224)
		(layer "In15.Cu")
		(net "P3E_CPU1_P4_TX_DN<2>")
	)
	(segment
		(start 14.992858 -320.36004)
		(end 13.922756 -317.776606)
		(width 0.14224)
		(layer "In15.Cu")
		(net "P3E_CPU1_P4_TX_DN<2>")
	)
	(segment
		(start 181.76494 -47.751492)
		(end 182.041546 -48.028098)
		(width 0.12954)
		(layer "F.Cu")
		(net "P3E_CPU1_P4_TX_DN<1>")
	)
	(segment
		(start 180.795168 -48.053498)
		(end 181.097174 -47.751492)
		(width 0.12954)
		(layer "F.Cu")
		(net "P3E_CPU1_P4_TX_DN<1>")
	)
	(segment
		(start 181.097174 -47.751492)
		(end 181.76494 -47.751492)
		(width 0.12954)
		(layer "F.Cu")
		(net "P3E_CPU1_P4_TX_DN<1>")
	)
	(segment
		(start 102.207822 -292.450266)
		(end 101.74097 -292.716204)
		(width 0.12954)
		(layer "F.Cu")
		(net "P3E_CPU1_P4_TX_DN<1>")
	)
	(segment
		(start 101.110796 -298.634658)
		(end 101.156516 -298.680378)
		(width 0.1143)
		(layer "In2.Cu")
		(net "P3E_CPU1_P4_TX_DN<1>")
	)
	(segment
		(start 95.345758 -305.764184)
		(end 94.405958 -307.170836)
		(width 0.14224)
		(layer "In2.Cu")
		(net "P3E_CPU1_P4_TX_DN<1>")
	)
	(segment
		(start 94.404942 -307.171852)
		(end 94.229174 -307.597048)
		(width 0.14224)
		(layer "In2.Cu")
		(net "P3E_CPU1_P4_TX_DN<1>")
	)
	(segment
		(start 101.156516 -298.708826)
		(end 101.156516 -299.353478)
		(width 0.14224)
		(layer "In2.Cu")
		(net "P3E_CPU1_P4_TX_DN<1>")
	)
	(segment
		(start 101.156516 -298.680378)
		(end 101.156516 -298.708826)
		(width 0.1143)
		(layer "In2.Cu")
		(net "P3E_CPU1_P4_TX_DN<1>")
	)
	(segment
		(start 101.508052 -294.630348)
		(end 101.522276 -294.640508)
		(width 0.1143)
		(layer "In2.Cu")
		(net "P3E_CPU1_P4_TX_DN<1>")
	)
	(segment
		(start 101.593142 -295.610788)
		(end 101.522276 -295.651936)
		(width 0.1143)
		(layer "In2.Cu")
		(net "P3E_CPU1_P4_TX_DN<1>")
	)
	(segment
		(start 94.229174 -307.597048)
		(end 94.229174 -308.18074)
		(width 0.14224)
		(layer "In2.Cu")
		(net "P3E_CPU1_P4_TX_DN<1>")
	)
	(segment
		(start 101.366066 -296.163746)
		(end 101.110796 -296.419016)
		(width 0.1143)
		(layer "In2.Cu")
		(net "P3E_CPU1_P4_TX_DN<1>")
	)
	(segment
		(start 101.593142 -293.990776)
		(end 101.554026 -294.013636)
		(width 0.1143)
		(layer "In2.Cu")
		(net "P3E_CPU1_P4_TX_DN<1>")
	)
	(segment
		(start 94.405958 -307.170836)
		(end 94.404942 -307.171852)
		(width 0.14224)
		(layer "In2.Cu")
		(net "P3E_CPU1_P4_TX_DN<1>")
	)
	(segment
		(start 101.522276 -294.031924)
		(end 101.508052 -294.042084)
		(width 0.1143)
		(layer "In2.Cu")
		(net "P3E_CPU1_P4_TX_DN<1>")
	)
	(segment
		(start 101.110796 -296.419016)
		(end 101.110796 -298.634658)
		(width 0.1143)
		(layer "In2.Cu")
		(net "P3E_CPU1_P4_TX_DN<1>")
	)
	(segment
		(start 101.443028 -292.716204)
		(end 101.372924 -292.786308)
		(width 0.1143)
		(layer "In2.Cu")
		(net "P3E_CPU1_P4_TX_DN<1>")
	)
	(segment
		(start 101.156516 -299.353478)
		(end 95.345758 -305.764184)
		(width 0.14224)
		(layer "In2.Cu")
		(net "P3E_CPU1_P4_TX_DN<1>")
	)
	(segment
		(start 101.366066 -295.956228)
		(end 101.366066 -296.163746)
		(width 0.1143)
		(layer "In2.Cu")
		(net "P3E_CPU1_P4_TX_DN<1>")
	)
	(segment
		(start 101.554026 -294.013636)
		(end 101.522276 -294.031924)
		(width 0.1143)
		(layer "In2.Cu")
		(net "P3E_CPU1_P4_TX_DN<1>")
	)
	(segment
		(start 101.74097 -292.716204)
		(end 101.443028 -292.716204)
		(width 0.1143)
		(layer "In2.Cu")
		(net "P3E_CPU1_P4_TX_DN<1>")
	)
	(segment
		(start 94.229174 -308.18074)
		(end 94.520004 -308.47157)
		(width 0.14224)
		(layer "In2.Cu")
		(net "P3E_CPU1_P4_TX_DN<1>")
	)
	(segment
		(start 101.548184 -293.035482)
		(end 101.550978 -293.037006)
		(width 0.1143)
		(layer "In2.Cu")
		(net "P3E_CPU1_P4_TX_DN<1>")
	)
	(segment
		(start 101.522276 -294.640508)
		(end 101.593142 -294.681656)
		(width 0.1143)
		(layer "In2.Cu")
		(net "P3E_CPU1_P4_TX_DN<1>")
	)
	(segment
		(start 101.550978 -293.037006)
		(end 101.59238 -293.061136)
		(width 0.1143)
		(layer "In2.Cu")
		(net "P3E_CPU1_P4_TX_DN<1>")
	)
	(arc
		(start 101.593142 -293.061644)
		(mid 101.836469 -293.52621)
		(end 101.593142 -293.990776)
		(width 0.1143)
		(layer "In2.Cu")
		(net "P3E_CPU1_P4_TX_DN<1>")
	)
	(arc
		(start 101.508052 -294.042084)
		(mid 101.357307 -294.336216)
		(end 101.508052 -294.630348)
		(width 0.1143)
		(layer "In2.Cu")
		(net "P3E_CPU1_P4_TX_DN<1>")
	)
	(arc
		(start 101.59238 -293.061136)
		(mid 101.592761 -293.06139)
		(end 101.593142 -293.061644)
		(width 0.1143)
		(layer "In2.Cu")
		(net "P3E_CPU1_P4_TX_DN<1>")
	)
	(arc
		(start 101.43236 -295.743884)
		(mid 101.38304 -295.845013)
		(end 101.366066 -295.956228)
		(width 0.1143)
		(layer "In2.Cu")
		(net "P3E_CPU1_P4_TX_DN<1>")
	)
	(arc
		(start 101.593142 -294.681656)
		(mid 101.836469 -295.146222)
		(end 101.593142 -295.610788)
		(width 0.1143)
		(layer "In2.Cu")
		(net "P3E_CPU1_P4_TX_DN<1>")
	)
	(arc
		(start 101.522276 -295.651936)
		(mid 101.473344 -295.694024)
		(end 101.43236 -295.743884)
		(width 0.1143)
		(layer "In2.Cu")
		(net "P3E_CPU1_P4_TX_DN<1>")
	)
	(arc
		(start 101.372924 -292.786308)
		(mid 101.433726 -292.929757)
		(end 101.548184 -293.035482)
		(width 0.1143)
		(layer "In2.Cu")
		(net "P3E_CPU1_P4_TX_DN<1>")
	)
	(segment
		(start 175.541178 -50.287174)
		(end 178.091084 -47.737268)
		(width 0.14224)
		(layer "In6.Cu")
		(net "P3E_CPU1_P4_TX_DN<1>")
	)
	(segment
		(start 181.750716 -47.737268)
		(end 182.041546 -48.028098)
		(width 0.14224)
		(layer "In6.Cu")
		(net "P3E_CPU1_P4_TX_DN<1>")
	)
	(segment
		(start 116.906548 -66.45021)
		(end 153.466546 -62.563248)
		(width 0.14224)
		(layer "In6.Cu")
		(net "P3E_CPU1_P4_TX_DN<1>")
	)
	(segment
		(start 167.861996 -62.91453)
		(end 174.324264 -58.389774)
		(width 0.14224)
		(layer "In6.Cu")
		(net "P3E_CPU1_P4_TX_DN<1>")
	)
	(segment
		(start 10.535412 -172.78731)
		(end 22.39518 -169.189908)
		(width 0.14224)
		(layer "In6.Cu")
		(net "P3E_CPU1_P4_TX_DN<1>")
	)
	(segment
		(start 85.289644 -97.624392)
		(end 100.425504 -76.00823)
		(width 0.14224)
		(layer "In6.Cu")
		(net "P3E_CPU1_P4_TX_DN<1>")
	)
	(segment
		(start 161.661094 -64.008254)
		(end 167.861996 -62.91453)
		(width 0.14224)
		(layer "In6.Cu")
		(net "P3E_CPU1_P4_TX_DN<1>")
	)
	(segment
		(start 174.324264 -58.389774)
		(end 175.541178 -57.17286)
		(width 0.14224)
		(layer "In6.Cu")
		(net "P3E_CPU1_P4_TX_DN<1>")
	)
	(segment
		(start 153.466546 -62.563248)
		(end 161.661094 -64.008254)
		(width 0.14224)
		(layer "In6.Cu")
		(net "P3E_CPU1_P4_TX_DN<1>")
	)
	(segment
		(start 9.106408 -173.07814)
		(end 9.397238 -172.78731)
		(width 0.14224)
		(layer "In6.Cu")
		(net "P3E_CPU1_P4_TX_DN<1>")
	)
	(segment
		(start 46.93285 -135.981948)
		(end 85.289644 -97.624392)
		(width 0.14224)
		(layer "In6.Cu")
		(net "P3E_CPU1_P4_TX_DN<1>")
	)
	(segment
		(start 178.091084 -47.737268)
		(end 181.750716 -47.737268)
		(width 0.14224)
		(layer "In6.Cu")
		(net "P3E_CPU1_P4_TX_DN<1>")
	)
	(segment
		(start 113.123472 -67.117468)
		(end 116.906548 -66.45021)
		(width 0.14224)
		(layer "In6.Cu")
		(net "P3E_CPU1_P4_TX_DN<1>")
	)
	(segment
		(start 9.397238 -172.78731)
		(end 10.535412 -172.78731)
		(width 0.14224)
		(layer "In6.Cu")
		(net "P3E_CPU1_P4_TX_DN<1>")
	)
	(segment
		(start 39.075106 -154.953208)
		(end 46.93285 -135.981948)
		(width 0.14224)
		(layer "In6.Cu")
		(net "P3E_CPU1_P4_TX_DN<1>")
	)
	(segment
		(start 175.541178 -57.17286)
		(end 175.541178 -50.287174)
		(width 0.14224)
		(layer "In6.Cu")
		(net "P3E_CPU1_P4_TX_DN<1>")
	)
	(segment
		(start 24.94026 -168.1734)
		(end 26.502106 -167.526208)
		(width 0.14224)
		(layer "In6.Cu")
		(net "P3E_CPU1_P4_TX_DN<1>")
	)
	(segment
		(start 26.502106 -167.526208)
		(end 39.075106 -154.953208)
		(width 0.14224)
		(layer "In6.Cu")
		(net "P3E_CPU1_P4_TX_DN<1>")
	)
	(segment
		(start 100.425504 -76.00823)
		(end 113.123472 -67.117468)
		(width 0.14224)
		(layer "In6.Cu")
		(net "P3E_CPU1_P4_TX_DN<1>")
	)
	(segment
		(start 22.39518 -169.189908)
		(end 24.472138 -168.329356)
		(width 0.14224)
		(layer "In6.Cu")
		(net "P3E_CPU1_P4_TX_DN<1>")
	)
	(segment
		(start 24.472138 -168.329356)
		(end 24.94026 -168.1734)
		(width 0.14224)
		(layer "In6.Cu")
		(net "P3E_CPU1_P4_TX_DN<1>")
	)
	(segment
		(start 14.029944 -313.106054)
		(end 13.873988 -308.51094)
		(width 0.14224)
		(layer "In15.Cu")
		(net "P3E_CPU1_P4_TX_DN<1>")
	)
	(segment
		(start 70.489064 -313.874404)
		(end 59.56935 -321.170554)
		(width 0.14224)
		(layer "In15.Cu")
		(net "P3E_CPU1_P4_TX_DN<1>")
	)
	(segment
		(start 56.389016 -321.170554)
		(end 56.389016 -321.159632)
		(width 0.14224)
		(layer "In15.Cu")
		(net "P3E_CPU1_P4_TX_DN<1>")
	)
	(segment
		(start 13.873988 -308.51094)
		(end 10.660888 -213.45525)
		(width 0.14224)
		(layer "In15.Cu")
		(net "P3E_CPU1_P4_TX_DN<1>")
	)
	(segment
		(start 93.57487 -310.236362)
		(end 92.91828 -310.547004)
		(width 0.14224)
		(layer "In15.Cu")
		(net "P3E_CPU1_P4_TX_DN<1>")
	)
	(segment
		(start 19.194018 -320.982848)
		(end 16.494252 -320.506852)
		(width 0.14224)
		(layer "In15.Cu")
		(net "P3E_CPU1_P4_TX_DN<1>")
	)
	(segment
		(start 14.962632 -317.796164)
		(end 14.029944 -313.106054)
		(width 0.14224)
		(layer "In15.Cu")
		(net "P3E_CPU1_P4_TX_DN<1>")
	)
	(segment
		(start 94.229174 -308.7624)
		(end 94.229174 -309.582058)
		(width 0.14224)
		(layer "In15.Cu")
		(net "P3E_CPU1_P4_TX_DN<1>")
	)
	(segment
		(start 16.494252 -320.506852)
		(end 15.79626 -319.808606)
		(width 0.14224)
		(layer "In15.Cu")
		(net "P3E_CPU1_P4_TX_DN<1>")
	)
	(segment
		(start 11.792966 -181.926484)
		(end 11.792966 -177.276506)
		(width 0.14224)
		(layer "In15.Cu")
		(net "P3E_CPU1_P4_TX_DN<1>")
	)
	(segment
		(start 56.389016 -321.159632)
		(end 19.194018 -320.982848)
		(width 0.14224)
		(layer "In15.Cu")
		(net "P3E_CPU1_P4_TX_DN<1>")
	)
	(segment
		(start 94.520004 -308.47157)
		(end 94.229174 -308.7624)
		(width 0.14224)
		(layer "In15.Cu")
		(net "P3E_CPU1_P4_TX_DN<1>")
	)
	(segment
		(start 59.56935 -321.170554)
		(end 56.389016 -321.170554)
		(width 0.14224)
		(layer "In15.Cu")
		(net "P3E_CPU1_P4_TX_DN<1>")
	)
	(segment
		(start 10.170414 -173.359318)
		(end 9.598406 -172.78731)
		(width 0.14224)
		(layer "In15.Cu")
		(net "P3E_CPU1_P4_TX_DN<1>")
	)
	(segment
		(start 9.397238 -172.78731)
		(end 9.106408 -173.07814)
		(width 0.14224)
		(layer "In15.Cu")
		(net "P3E_CPU1_P4_TX_DN<1>")
	)
	(segment
		(start 11.792966 -177.276506)
		(end 10.170414 -173.359318)
		(width 0.14224)
		(layer "In15.Cu")
		(net "P3E_CPU1_P4_TX_DN<1>")
	)
	(segment
		(start 11.74115 -183.36768)
		(end 11.792966 -181.926484)
		(width 0.14224)
		(layer "In15.Cu")
		(net "P3E_CPU1_P4_TX_DN<1>")
	)
	(segment
		(start 94.229174 -309.582058)
		(end 93.57487 -310.236362)
		(width 0.14224)
		(layer "In15.Cu")
		(net "P3E_CPU1_P4_TX_DN<1>")
	)
	(segment
		(start 9.598406 -172.78731)
		(end 9.397238 -172.78731)
		(width 0.14224)
		(layer "In15.Cu")
		(net "P3E_CPU1_P4_TX_DN<1>")
	)
	(segment
		(start 10.660888 -213.45525)
		(end 11.74115 -183.36768)
		(width 0.14224)
		(layer "In15.Cu")
		(net "P3E_CPU1_P4_TX_DN<1>")
	)
	(segment
		(start 15.79626 -319.808606)
		(end 14.962632 -317.796164)
		(width 0.14224)
		(layer "In15.Cu")
		(net "P3E_CPU1_P4_TX_DN<1>")
	)
	(segment
		(start 92.91828 -310.547004)
		(end 70.489064 -313.874404)
		(width 0.14224)
		(layer "In15.Cu")
		(net "P3E_CPU1_P4_TX_DN<1>")
	)
	(segment
		(start 181.097174 -44.703492)
		(end 181.76494 -44.703492)
		(width 0.12954)
		(layer "F.Cu")
		(net "P3E_CPU1_P4_TX_DN<0>")
	)
	(segment
		(start 180.795168 -45.005498)
		(end 181.097174 -44.703492)
		(width 0.12954)
		(layer "F.Cu")
		(net "P3E_CPU1_P4_TX_DN<0>")
	)
	(segment
		(start 181.76494 -44.703492)
		(end 182.041546 -44.980098)
		(width 0.12954)
		(layer "F.Cu")
		(net "P3E_CPU1_P4_TX_DN<0>")
	)
	(segment
		(start 99.387914 -292.450266)
		(end 98.921062 -292.716204)
		(width 0.12954)
		(layer "F.Cu")
		(net "P3E_CPU1_P4_TX_DN<0>")
	)
	(segment
		(start 98.79203 -293.977568)
		(end 98.772218 -293.991538)
		(width 0.1143)
		(layer "In2.Cu")
		(net "P3E_CPU1_P4_TX_DN<0>")
	)
	(segment
		(start 91.513914 -301.487332)
		(end 87.039958 -304.471578)
		(width 0.14224)
		(layer "In2.Cu")
		(net "P3E_CPU1_P4_TX_DN<0>")
	)
	(segment
		(start 98.772218 -293.060882)
		(end 98.792284 -293.074852)
		(width 0.1143)
		(layer "In2.Cu")
		(net "P3E_CPU1_P4_TX_DN<0>")
	)
	(segment
		(start 98.771456 -294.680386)
		(end 98.772472 -294.681148)
		(width 0.1143)
		(layer "In2.Cu")
		(net "P3E_CPU1_P4_TX_DN<0>")
	)
	(segment
		(start 98.730054 -294.015922)
		(end 98.727514 -294.017192)
		(width 0.1143)
		(layer "In2.Cu")
		(net "P3E_CPU1_P4_TX_DN<0>")
	)
	(segment
		(start 98.77044 -294.679878)
		(end 98.771456 -294.680386)
		(width 0.1143)
		(layer "In2.Cu")
		(net "P3E_CPU1_P4_TX_DN<0>")
	)
	(segment
		(start 98.733356 -293.038276)
		(end 98.734118 -293.038784)
		(width 0.1143)
		(layer "In2.Cu")
		(net "P3E_CPU1_P4_TX_DN<0>")
	)
	(segment
		(start 98.731832 -294.014906)
		(end 98.730816 -294.015414)
		(width 0.1143)
		(layer "In2.Cu")
		(net "P3E_CPU1_P4_TX_DN<0>")
	)
	(segment
		(start 95.89389 -300.158658)
		(end 91.513914 -301.487332)
		(width 0.14224)
		(layer "In2.Cu")
		(net "P3E_CPU1_P4_TX_DN<0>")
	)
	(segment
		(start 99.016312 -295.146222)
		(end 99.016312 -295.581324)
		(width 0.1143)
		(layer "In2.Cu")
		(net "P3E_CPU1_P4_TX_DN<0>")
	)
	(segment
		(start 98.299016 -296.29862)
		(end 98.299016 -297.216068)
		(width 0.1143)
		(layer "In2.Cu")
		(net "P3E_CPU1_P4_TX_DN<0>")
	)
	(segment
		(start 86.841584 -304.840386)
		(end 86.841584 -304.84064)
		(width 0.14224)
		(layer "In2.Cu")
		(net "P3E_CPU1_P4_TX_DN<0>")
	)
	(segment
		(start 98.772218 -293.991538)
		(end 98.732594 -294.014398)
		(width 0.1143)
		(layer "In2.Cu")
		(net "P3E_CPU1_P4_TX_DN<0>")
	)
	(segment
		(start 98.732594 -294.014398)
		(end 98.731832 -294.014906)
		(width 0.1143)
		(layer "In2.Cu")
		(net "P3E_CPU1_P4_TX_DN<0>")
	)
	(segment
		(start 79.864966 -309.213758)
		(end 79.574136 -309.504588)
		(width 0.14224)
		(layer "In2.Cu")
		(net "P3E_CPU1_P4_TX_DN<0>")
	)
	(segment
		(start 98.730816 -294.015414)
		(end 98.730054 -294.015922)
		(width 0.1143)
		(layer "In2.Cu")
		(net "P3E_CPU1_P4_TX_DN<0>")
	)
	(segment
		(start 98.299016 -297.216068)
		(end 98.344736 -297.261788)
		(width 0.1143)
		(layer "In2.Cu")
		(net "P3E_CPU1_P4_TX_DN<0>")
	)
	(segment
		(start 98.736912 -293.040562)
		(end 98.772218 -293.060882)
		(width 0.1143)
		(layer "In2.Cu")
		(net "P3E_CPU1_P4_TX_DN<0>")
	)
	(segment
		(start 98.921062 -292.716204)
		(end 98.62312 -292.716204)
		(width 0.1143)
		(layer "In2.Cu")
		(net "P3E_CPU1_P4_TX_DN<0>")
	)
	(segment
		(start 86.841584 -304.84064)
		(end 84.99094 -308.28234)
		(width 0.14224)
		(layer "In2.Cu")
		(net "P3E_CPU1_P4_TX_DN<0>")
	)
	(segment
		(start 98.344736 -297.261788)
		(end 98.344736 -297.290236)
		(width 0.1143)
		(layer "In2.Cu")
		(net "P3E_CPU1_P4_TX_DN<0>")
	)
	(segment
		(start 99.016312 -295.581324)
		(end 98.299016 -296.29862)
		(width 0.1143)
		(layer "In2.Cu")
		(net "P3E_CPU1_P4_TX_DN<0>")
	)
	(segment
		(start 87.039958 -304.471578)
		(end 86.841584 -304.840386)
		(width 0.14224)
		(layer "In2.Cu")
		(net "P3E_CPU1_P4_TX_DN<0>")
	)
	(segment
		(start 98.727514 -294.017192)
		(end 98.726752 -294.0177)
		(width 0.1143)
		(layer "In2.Cu")
		(net "P3E_CPU1_P4_TX_DN<0>")
	)
	(segment
		(start 98.344736 -297.290236)
		(end 98.344736 -297.708066)
		(width 0.14224)
		(layer "In2.Cu")
		(net "P3E_CPU1_P4_TX_DN<0>")
	)
	(segment
		(start 98.734118 -293.038784)
		(end 98.736912 -293.040562)
		(width 0.1143)
		(layer "In2.Cu")
		(net "P3E_CPU1_P4_TX_DN<0>")
	)
	(segment
		(start 98.726752 -294.0177)
		(end 98.702368 -294.031924)
		(width 0.1143)
		(layer "In2.Cu")
		(net "P3E_CPU1_P4_TX_DN<0>")
	)
	(segment
		(start 98.344736 -297.708066)
		(end 95.89389 -300.158658)
		(width 0.14224)
		(layer "In2.Cu")
		(net "P3E_CPU1_P4_TX_DN<0>")
	)
	(segment
		(start 98.702368 -294.640508)
		(end 98.77044 -294.679878)
		(width 0.1143)
		(layer "In2.Cu")
		(net "P3E_CPU1_P4_TX_DN<0>")
	)
	(segment
		(start 98.62312 -292.716204)
		(end 98.55327 -292.786054)
		(width 0.1143)
		(layer "In2.Cu")
		(net "P3E_CPU1_P4_TX_DN<0>")
	)
	(segment
		(start 98.702368 -293.020496)
		(end 98.733356 -293.038276)
		(width 0.1143)
		(layer "In2.Cu")
		(net "P3E_CPU1_P4_TX_DN<0>")
	)
	(segment
		(start 83.432904 -309.213758)
		(end 79.864966 -309.213758)
		(width 0.14224)
		(layer "In2.Cu")
		(net "P3E_CPU1_P4_TX_DN<0>")
	)
	(segment
		(start 84.99094 -308.28234)
		(end 83.432904 -309.213758)
		(width 0.14224)
		(layer "In2.Cu")
		(net "P3E_CPU1_P4_TX_DN<0>")
	)
	(arc
		(start 98.702368 -294.031924)
		(mid 98.54644 -294.336216)
		(end 98.702368 -294.640508)
		(width 0.1143)
		(layer "In2.Cu")
		(net "P3E_CPU1_P4_TX_DN<0>")
	)
	(arc
		(start 98.772472 -294.681148)
		(mid 98.951665 -294.883658)
		(end 99.016312 -295.146222)
		(width 0.1143)
		(layer "In2.Cu")
		(net "P3E_CPU1_P4_TX_DN<0>")
	)
	(arc
		(start 98.792284 -293.074852)
		(mid 99.024166 -293.526313)
		(end 98.79203 -293.977568)
		(width 0.1143)
		(layer "In2.Cu")
		(net "P3E_CPU1_P4_TX_DN<0>")
	)
	(arc
		(start 98.55327 -292.786054)
		(mid 98.605319 -292.917573)
		(end 98.702368 -293.020496)
		(width 0.1143)
		(layer "In2.Cu")
		(net "P3E_CPU1_P4_TX_DN<0>")
	)
	(segment
		(start 153.8224 -61.473588)
		(end 162.195256 -62.95009)
		(width 0.14224)
		(layer "In6.Cu")
		(net "P3E_CPU1_P4_TX_DN<0>")
	)
	(segment
		(start 9.397238 -170.0022)
		(end 12.686284 -170.0022)
		(width 0.14224)
		(layer "In6.Cu")
		(net "P3E_CPU1_P4_TX_DN<0>")
	)
	(segment
		(start 116.791232 -65.494408)
		(end 153.8224 -61.473588)
		(width 0.14224)
		(layer "In6.Cu")
		(net "P3E_CPU1_P4_TX_DN<0>")
	)
	(segment
		(start 99.735894 -75.31862)
		(end 112.748568 -66.207132)
		(width 0.14224)
		(layer "In6.Cu")
		(net "P3E_CPU1_P4_TX_DN<0>")
	)
	(segment
		(start 174.539656 -56.777636)
		(end 174.539656 -48.235362)
		(width 0.14224)
		(layer "In6.Cu")
		(net "P3E_CPU1_P4_TX_DN<0>")
	)
	(segment
		(start 112.748568 -66.207132)
		(end 116.791232 -65.494408)
		(width 0.14224)
		(layer "In6.Cu")
		(net "P3E_CPU1_P4_TX_DN<0>")
	)
	(segment
		(start 45.92066 -135.621776)
		(end 84.583016 -96.95942)
		(width 0.14224)
		(layer "In6.Cu")
		(net "P3E_CPU1_P4_TX_DN<0>")
	)
	(segment
		(start 178.08575 -44.689268)
		(end 181.750716 -44.689268)
		(width 0.14224)
		(layer "In6.Cu")
		(net "P3E_CPU1_P4_TX_DN<0>")
	)
	(segment
		(start 12.686284 -170.0022)
		(end 22.734016 -168.003474)
		(width 0.14224)
		(layer "In6.Cu")
		(net "P3E_CPU1_P4_TX_DN<0>")
	)
	(segment
		(start 84.583016 -96.95942)
		(end 99.735894 -75.31862)
		(width 0.14224)
		(layer "In6.Cu")
		(net "P3E_CPU1_P4_TX_DN<0>")
	)
	(segment
		(start 181.750716 -44.689268)
		(end 182.041546 -44.980098)
		(width 0.14224)
		(layer "In6.Cu")
		(net "P3E_CPU1_P4_TX_DN<0>")
	)
	(segment
		(start 26.086816 -166.614602)
		(end 38.029896 -154.671522)
		(width 0.14224)
		(layer "In6.Cu")
		(net "P3E_CPU1_P4_TX_DN<0>")
	)
	(segment
		(start 162.195256 -62.95009)
		(end 167.346122 -62.041532)
		(width 0.14224)
		(layer "In6.Cu")
		(net "P3E_CPU1_P4_TX_DN<0>")
	)
	(segment
		(start 174.539656 -48.235362)
		(end 178.08575 -44.689268)
		(width 0.14224)
		(layer "In6.Cu")
		(net "P3E_CPU1_P4_TX_DN<0>")
	)
	(segment
		(start 9.106408 -170.29303)
		(end 9.397238 -170.0022)
		(width 0.14224)
		(layer "In6.Cu")
		(net "P3E_CPU1_P4_TX_DN<0>")
	)
	(segment
		(start 38.029896 -154.671522)
		(end 45.92066 -135.621776)
		(width 0.14224)
		(layer "In6.Cu")
		(net "P3E_CPU1_P4_TX_DN<0>")
	)
	(segment
		(start 167.346122 -62.041532)
		(end 173.782228 -57.535064)
		(width 0.14224)
		(layer "In6.Cu")
		(net "P3E_CPU1_P4_TX_DN<0>")
	)
	(segment
		(start 173.782228 -57.535064)
		(end 174.539656 -56.777636)
		(width 0.14224)
		(layer "In6.Cu")
		(net "P3E_CPU1_P4_TX_DN<0>")
	)
	(segment
		(start 22.734016 -168.003474)
		(end 26.086816 -166.614602)
		(width 0.14224)
		(layer "In6.Cu")
		(net "P3E_CPU1_P4_TX_DN<0>")
	)
	(segment
		(start 15.15364 -313.906662)
		(end 15.000478 -309.39486)
		(width 0.14224)
		(layer "In15.Cu")
		(net "P3E_CPU1_P4_TX_DN<0>")
	)
	(segment
		(start 12.736576 -176.276254)
		(end 10.51941 -170.923204)
		(width 0.14224)
		(layer "In15.Cu")
		(net "P3E_CPU1_P4_TX_DN<0>")
	)
	(segment
		(start 11.683746 -211.271358)
		(end 12.736576 -181.943756)
		(width 0.14224)
		(layer "In15.Cu")
		(net "P3E_CPU1_P4_TX_DN<0>")
	)
	(segment
		(start 19.280124 -320.025522)
		(end 16.958056 -319.616074)
		(width 0.14224)
		(layer "In15.Cu")
		(net "P3E_CPU1_P4_TX_DN<0>")
	)
	(segment
		(start 75.473052 -310.39816)
		(end 75.39863 -310.577484)
		(width 0.14224)
		(layer "In15.Cu")
		(net "P3E_CPU1_P4_TX_DN<0>")
	)
	(segment
		(start 74.356468 -311.009284)
		(end 73.962006 -311.172606)
		(width 0.14224)
		(layer "In15.Cu")
		(net "P3E_CPU1_P4_TX_DN<0>")
	)
	(segment
		(start 75.39863 -310.577484)
		(end 75.004168 -310.740806)
		(width 0.14224)
		(layer "In15.Cu")
		(net "P3E_CPU1_P4_TX_DN<0>")
	)
	(segment
		(start 15.000478 -309.39486)
		(end 11.683746 -211.271358)
		(width 0.14224)
		(layer "In15.Cu")
		(net "P3E_CPU1_P4_TX_DN<0>")
	)
	(segment
		(start 72.609456 -311.729882)
		(end 72.21474 -311.893204)
		(width 0.14224)
		(layer "In15.Cu")
		(net "P3E_CPU1_P4_TX_DN<0>")
	)
	(segment
		(start 10.51941 -170.923204)
		(end 9.598406 -170.0022)
		(width 0.14224)
		(layer "In15.Cu")
		(net "P3E_CPU1_P4_TX_DN<0>")
	)
	(segment
		(start 76.043028 -310.307736)
		(end 75.86726 -310.235092)
		(width 0.14224)
		(layer "In15.Cu")
		(net "P3E_CPU1_P4_TX_DN<0>")
	)
	(segment
		(start 76.43749 -310.144668)
		(end 76.043028 -310.307736)
		(width 0.14224)
		(layer "In15.Cu")
		(net "P3E_CPU1_P4_TX_DN<0>")
	)
	(segment
		(start 9.397238 -170.0022)
		(end 9.106408 -170.29303)
		(width 0.14224)
		(layer "In15.Cu")
		(net "P3E_CPU1_P4_TX_DN<0>")
	)
	(segment
		(start 79.574136 -309.504588)
		(end 79.283306 -309.213758)
		(width 0.14224)
		(layer "In15.Cu")
		(net "P3E_CPU1_P4_TX_DN<0>")
	)
	(segment
		(start 12.736576 -181.943756)
		(end 12.736576 -176.276254)
		(width 0.14224)
		(layer "In15.Cu")
		(net "P3E_CPU1_P4_TX_DN<0>")
	)
	(segment
		(start 76.510388 -309.968392)
		(end 76.43749 -310.144668)
		(width 0.14224)
		(layer "In15.Cu")
		(net "P3E_CPU1_P4_TX_DN<0>")
	)
	(segment
		(start 71.507096 -312.04027)
		(end 59.276742 -320.212974)
		(width 0.14224)
		(layer "In15.Cu")
		(net "P3E_CPU1_P4_TX_DN<0>")
	)
	(segment
		(start 56.811672 -320.212974)
		(end 56.811672 -320.204084)
		(width 0.14224)
		(layer "In15.Cu")
		(net "P3E_CPU1_P4_TX_DN<0>")
	)
	(segment
		(start 59.276742 -320.212974)
		(end 56.811672 -320.212974)
		(width 0.14224)
		(layer "In15.Cu")
		(net "P3E_CPU1_P4_TX_DN<0>")
	)
	(segment
		(start 74.43089 -310.829706)
		(end 74.356468 -311.009284)
		(width 0.14224)
		(layer "In15.Cu")
		(net "P3E_CPU1_P4_TX_DN<0>")
	)
	(segment
		(start 15.85087 -317.4111)
		(end 15.15364 -313.906662)
		(width 0.14224)
		(layer "In15.Cu")
		(net "P3E_CPU1_P4_TX_DN<0>")
	)
	(segment
		(start 79.283306 -309.213758)
		(end 78.332584 -309.213758)
		(width 0.14224)
		(layer "In15.Cu")
		(net "P3E_CPU1_P4_TX_DN<0>")
	)
	(segment
		(start 74.825098 -310.666638)
		(end 74.43089 -310.829706)
		(width 0.14224)
		(layer "In15.Cu")
		(net "P3E_CPU1_P4_TX_DN<0>")
	)
	(segment
		(start 75.86726 -310.235092)
		(end 75.473052 -310.39816)
		(width 0.14224)
		(layer "In15.Cu")
		(net "P3E_CPU1_P4_TX_DN<0>")
	)
	(segment
		(start 9.598406 -170.0022)
		(end 9.397238 -170.0022)
		(width 0.14224)
		(layer "In15.Cu")
		(net "P3E_CPU1_P4_TX_DN<0>")
	)
	(segment
		(start 16.958056 -319.616074)
		(end 16.627094 -319.284858)
		(width 0.14224)
		(layer "In15.Cu")
		(net "P3E_CPU1_P4_TX_DN<0>")
	)
	(segment
		(start 72.038972 -311.820306)
		(end 71.507096 -312.04027)
		(width 0.14224)
		(layer "In15.Cu")
		(net "P3E_CPU1_P4_TX_DN<0>")
	)
	(segment
		(start 72.682354 -311.55386)
		(end 72.609456 -311.729882)
		(width 0.14224)
		(layer "In15.Cu")
		(net "P3E_CPU1_P4_TX_DN<0>")
	)
	(segment
		(start 16.627094 -319.284858)
		(end 15.85087 -317.4111)
		(width 0.14224)
		(layer "In15.Cu")
		(net "P3E_CPU1_P4_TX_DN<0>")
	)
	(segment
		(start 73.962006 -311.172606)
		(end 73.782936 -311.098438)
		(width 0.14224)
		(layer "In15.Cu")
		(net "P3E_CPU1_P4_TX_DN<0>")
	)
	(segment
		(start 72.21474 -311.893204)
		(end 72.038972 -311.820306)
		(width 0.14224)
		(layer "In15.Cu")
		(net "P3E_CPU1_P4_TX_DN<0>")
	)
	(segment
		(start 75.004168 -310.740806)
		(end 74.825098 -310.666638)
		(width 0.14224)
		(layer "In15.Cu")
		(net "P3E_CPU1_P4_TX_DN<0>")
	)
	(segment
		(start 78.332584 -309.213758)
		(end 76.510388 -309.968392)
		(width 0.14224)
		(layer "In15.Cu")
		(net "P3E_CPU1_P4_TX_DN<0>")
	)
	(segment
		(start 56.811672 -320.204084)
		(end 19.280124 -320.025522)
		(width 0.14224)
		(layer "In15.Cu")
		(net "P3E_CPU1_P4_TX_DN<0>")
	)
	(segment
		(start 73.782936 -311.098438)
		(end 72.682354 -311.55386)
		(width 0.14224)
		(layer "In15.Cu")
		(net "P3E_CPU1_P4_TX_DN<0>")
	)
	(segment
		(start 105.967784 -294.070278)
		(end 105.500932 -294.336216)
		(width 0.12954)
		(layer "F.Cu")
		(net "P3E_CPU1_P4_RX_DP<3>")
	)
	(segment
		(start 177.796698 -54.799992)
		(end 177.885344 -54.888638)
		(width 0.12954)
		(layer "F.Cu")
		(net "P3E_CPU1_P4_RX_DP<3>")
	)
	(segment
		(start 177.885344 -54.888638)
		(end 178.741324 -54.888638)
		(width 0.12954)
		(layer "F.Cu")
		(net "P3E_CPU1_P4_RX_DP<3>")
	)
	(segment
		(start 178.741324 -54.888638)
		(end 179.011834 -54.618128)
		(width 0.12954)
		(layer "F.Cu")
		(net "P3E_CPU1_P4_RX_DP<3>")
	)
	(segment
		(start 177.108358 -54.799992)
		(end 177.796698 -54.799992)
		(width 0.12954)
		(layer "F.Cu")
		(net "P3E_CPU1_P4_RX_DP<3>")
	)
	(segment
		(start 105.685336 -294.66032)
		(end 105.68686 -294.659304)
		(width 0.1143)
		(layer "In2.Cu")
		(net "P3E_CPU1_P4_RX_DP<3>")
	)
	(segment
		(start 78.169516 -314.2615)
		(end 78.588108 -314.178188)
		(width 0.14224)
		(layer "In2.Cu")
		(net "P3E_CPU1_P4_RX_DP<3>")
	)
	(segment
		(start 105.649776 -294.680894)
		(end 105.670858 -294.668702)
		(width 0.1143)
		(layer "In2.Cu")
		(net "P3E_CPU1_P4_RX_DP<3>")
	)
	(segment
		(start 75.804014 -314.871862)
		(end 75.911964 -314.710318)
		(width 0.14224)
		(layer "In2.Cu")
		(net "P3E_CPU1_P4_RX_DP<3>")
	)
	(segment
		(start 99.841304 -75.315318)
		(end 89.330784 -90.325702)
		(width 0.14224)
		(layer "In2.Cu")
		(net "P3E_CPU1_P4_RX_DP<3>")
	)
	(segment
		(start 99.151694 -312.000646)
		(end 101.078792 -311.202578)
		(width 0.14224)
		(layer "In2.Cu")
		(net "P3E_CPU1_P4_RX_DP<3>")
	)
	(segment
		(start 171.873672 -58.701178)
		(end 162.62096 -58.960766)
		(width 0.14224)
		(layer "In2.Cu")
		(net "P3E_CPU1_P4_RX_DP<3>")
	)
	(segment
		(start 101.078792 -311.202578)
		(end 101.65715 -310.62422)
		(width 0.14224)
		(layer "In2.Cu")
		(net "P3E_CPU1_P4_RX_DP<3>")
	)
	(segment
		(start 105.116884 -296.612564)
		(end 105.116884 -296.584116)
		(width 0.1143)
		(layer "In2.Cu")
		(net "P3E_CPU1_P4_RX_DP<3>")
	)
	(segment
		(start 105.615994 -297.59656)
		(end 105.116884 -297.09745)
		(width 0.14224)
		(layer "In2.Cu")
		(net "P3E_CPU1_P4_RX_DP<3>")
	)
	(segment
		(start 83.364324 -313.555634)
		(end 85.980778 -313.298078)
		(width 0.14224)
		(layer "In2.Cu")
		(net "P3E_CPU1_P4_RX_DP<3>")
	)
	(segment
		(start 77.436726 -314.407296)
		(end 77.598016 -314.514992)
		(width 0.14224)
		(layer "In2.Cu")
		(net "P3E_CPU1_P4_RX_DP<3>")
	)
	(segment
		(start 105.162604 -295.577006)
		(end 105.273348 -295.466008)
		(width 0.1143)
		(layer "In2.Cu")
		(net "P3E_CPU1_P4_RX_DP<3>")
	)
	(segment
		(start 75.224386 -314.847224)
		(end 75.385676 -314.95492)
		(width 0.14224)
		(layer "In2.Cu")
		(net "P3E_CPU1_P4_RX_DP<3>")
	)
	(segment
		(start 105.687876 -294.658796)
		(end 105.688638 -294.658288)
		(width 0.1143)
		(layer "In2.Cu")
		(net "P3E_CPU1_P4_RX_DP<3>")
	)
	(segment
		(start 180.136546 -56.456834)
		(end 179.810664 -56.782716)
		(width 0.14224)
		(layer "In2.Cu")
		(net "P3E_CPU1_P4_RX_DP<3>")
	)
	(segment
		(start 85.980778 -313.298078)
		(end 86.103968 -313.147964)
		(width 0.14224)
		(layer "In2.Cu")
		(net "P3E_CPU1_P4_RX_DP<3>")
	)
	(segment
		(start 105.615994 -300.083474)
		(end 105.615994 -297.59656)
		(width 0.14224)
		(layer "In2.Cu")
		(net "P3E_CPU1_P4_RX_DP<3>")
	)
	(segment
		(start 105.688638 -294.658288)
		(end 105.689908 -294.657526)
		(width 0.1143)
		(layer "In2.Cu")
		(net "P3E_CPU1_P4_RX_DP<3>")
	)
	(segment
		(start 10.530078 -186.859926)
		(end 9.736836 -191.359282)
		(width 0.14224)
		(layer "In2.Cu")
		(net "P3E_CPU1_P4_RX_DP<3>")
	)
	(segment
		(start 116.702332 -65.526412)
		(end 112.851946 -66.2051)
		(width 0.14224)
		(layer "In2.Cu")
		(net "P3E_CPU1_P4_RX_DP<3>")
	)
	(segment
		(start 101.65715 -310.62422)
		(end 105.41635 -300.879256)
		(width 0.14224)
		(layer "In2.Cu")
		(net "P3E_CPU1_P4_RX_DP<3>")
	)
	(segment
		(start 44.664376 -134.990332)
		(end 34.921444 -158.51124)
		(width 0.14224)
		(layer "In2.Cu")
		(net "P3E_CPU1_P4_RX_DP<3>")
	)
	(segment
		(start 105.670858 -294.668702)
		(end 105.671874 -294.66794)
		(width 0.1143)
		(layer "In2.Cu")
		(net "P3E_CPU1_P4_RX_DP<3>")
	)
	(segment
		(start 112.851946 -66.2051)
		(end 99.841304 -75.315318)
		(width 0.14224)
		(layer "In2.Cu")
		(net "P3E_CPU1_P4_RX_DP<3>")
	)
	(segment
		(start 77.598016 -314.514992)
		(end 78.061566 -314.423044)
		(width 0.14224)
		(layer "In2.Cu")
		(net "P3E_CPU1_P4_RX_DP<3>")
	)
	(segment
		(start 34.921444 -158.51124)
		(end 33.550098 -159.882332)
		(width 0.14224)
		(layer "In2.Cu")
		(net "P3E_CPU1_P4_RX_DP<3>")
	)
	(segment
		(start 179.829206 -54.908958)
		(end 180.136546 -55.216298)
		(width 0.14224)
		(layer "In2.Cu")
		(net "P3E_CPU1_P4_RX_DP<3>")
	)
	(segment
		(start 59.3344 -322.874386)
		(end 62.310772 -322.874386)
		(width 0.14224)
		(layer "In2.Cu")
		(net "P3E_CPU1_P4_RX_DP<3>")
	)
	(segment
		(start 78.061566 -314.423044)
		(end 78.169516 -314.2615)
		(width 0.14224)
		(layer "In2.Cu")
		(net "P3E_CPU1_P4_RX_DP<3>")
	)
	(segment
		(start 179.302664 -54.908958)
		(end 179.829206 -54.908958)
		(width 0.14224)
		(layer "In2.Cu")
		(net "P3E_CPU1_P4_RX_DP<3>")
	)
	(segment
		(start 105.162604 -296.538396)
		(end 105.162604 -295.577006)
		(width 0.1143)
		(layer "In2.Cu")
		(net "P3E_CPU1_P4_RX_DP<3>")
	)
	(segment
		(start 105.868724 -294.406066)
		(end 105.798874 -294.336216)
		(width 0.1143)
		(layer "In2.Cu")
		(net "P3E_CPU1_P4_RX_DP<3>")
	)
	(segment
		(start 105.68686 -294.659304)
		(end 105.687876 -294.658796)
		(width 0.1143)
		(layer "In2.Cu")
		(net "P3E_CPU1_P4_RX_DP<3>")
	)
	(segment
		(start 74.697844 -315.09208)
		(end 74.80554 -314.930536)
		(width 0.14224)
		(layer "In2.Cu")
		(net "P3E_CPU1_P4_RX_DP<3>")
	)
	(segment
		(start 105.691432 -294.656764)
		(end 105.719626 -294.640508)
		(width 0.1143)
		(layer "In2.Cu")
		(net "P3E_CPU1_P4_RX_DP<3>")
	)
	(segment
		(start 78.749398 -314.286138)
		(end 81.501234 -313.739276)
		(width 0.14224)
		(layer "In2.Cu")
		(net "P3E_CPU1_P4_RX_DP<3>")
	)
	(segment
		(start 105.798874 -294.336216)
		(end 105.500932 -294.336216)
		(width 0.1143)
		(layer "In2.Cu")
		(net "P3E_CPU1_P4_RX_DP<3>")
	)
	(segment
		(start 12.649708 -314.004198)
		(end 13.56233 -320.051176)
		(width 0.14224)
		(layer "In2.Cu")
		(net "P3E_CPU1_P4_RX_DP<3>")
	)
	(segment
		(start 83.214464 -313.432698)
		(end 83.364324 -313.555634)
		(width 0.14224)
		(layer "In2.Cu")
		(net "P3E_CPU1_P4_RX_DP<3>")
	)
	(segment
		(start 62.310772 -322.874386)
		(end 65.128394 -321.707256)
		(width 0.14224)
		(layer "In2.Cu")
		(net "P3E_CPU1_P4_RX_DP<3>")
	)
	(segment
		(start 180.136546 -55.216298)
		(end 180.136546 -56.456834)
		(width 0.14224)
		(layer "In2.Cu")
		(net "P3E_CPU1_P4_RX_DP<3>")
	)
	(segment
		(start 86.67877 -313.22899)
		(end 99.151694 -312.000646)
		(width 0.14224)
		(layer "In2.Cu")
		(net "P3E_CPU1_P4_RX_DP<3>")
	)
	(segment
		(start 86.528656 -313.106054)
		(end 86.67877 -313.22899)
		(width 0.14224)
		(layer "In2.Cu")
		(net "P3E_CPU1_P4_RX_DP<3>")
	)
	(segment
		(start 82.789522 -313.474354)
		(end 83.214464 -313.432698)
		(width 0.14224)
		(layer "In2.Cu")
		(net "P3E_CPU1_P4_RX_DP<3>")
	)
	(segment
		(start 33.550098 -159.882332)
		(end 25.44445 -165.558216)
		(width 0.14224)
		(layer "In2.Cu")
		(net "P3E_CPU1_P4_RX_DP<3>")
	)
	(segment
		(start 179.810664 -56.782716)
		(end 177.309018 -56.782716)
		(width 0.14224)
		(layer "In2.Cu")
		(net "P3E_CPU1_P4_RX_DP<3>")
	)
	(segment
		(start 71.01078 -315.82487)
		(end 74.697844 -315.09208)
		(width 0.14224)
		(layer "In2.Cu")
		(net "P3E_CPU1_P4_RX_DP<3>")
	)
	(segment
		(start 9.736836 -191.359282)
		(end 12.649708 -314.004198)
		(width 0.14224)
		(layer "In2.Cu")
		(net "P3E_CPU1_P4_RX_DP<3>")
	)
	(segment
		(start 78.588108 -314.178188)
		(end 78.749398 -314.286138)
		(width 0.14224)
		(layer "In2.Cu")
		(net "P3E_CPU1_P4_RX_DP<3>")
	)
	(segment
		(start 162.62096 -58.960766)
		(end 161.171636 -59.359292)
		(width 0.14224)
		(layer "In2.Cu")
		(net "P3E_CPU1_P4_RX_DP<3>")
	)
	(segment
		(start 156.969714 -61.176408)
		(end 116.702332 -65.526412)
		(width 0.14224)
		(layer "In2.Cu")
		(net "P3E_CPU1_P4_RX_DP<3>")
	)
	(segment
		(start 13.56233 -320.051176)
		(end 16.070326 -322.559426)
		(width 0.14224)
		(layer "In2.Cu")
		(net "P3E_CPU1_P4_RX_DP<3>")
	)
	(segment
		(start 76.491846 -314.734956)
		(end 76.910184 -314.651898)
		(width 0.14224)
		(layer "In2.Cu")
		(net "P3E_CPU1_P4_RX_DP<3>")
	)
	(segment
		(start 77.018134 -314.490354)
		(end 77.436726 -314.407296)
		(width 0.14224)
		(layer "In2.Cu")
		(net "P3E_CPU1_P4_RX_DP<3>")
	)
	(segment
		(start 105.671874 -294.66794)
		(end 105.685336 -294.66032)
		(width 0.1143)
		(layer "In2.Cu")
		(net "P3E_CPU1_P4_RX_DP<3>")
	)
	(segment
		(start 25.44445 -165.558216)
		(end 10.530078 -186.859926)
		(width 0.14224)
		(layer "In2.Cu")
		(net "P3E_CPU1_P4_RX_DP<3>")
	)
	(segment
		(start 161.171636 -59.359292)
		(end 159.47009 -60.30849)
		(width 0.14224)
		(layer "In2.Cu")
		(net "P3E_CPU1_P4_RX_DP<3>")
	)
	(segment
		(start 105.41635 -300.879256)
		(end 105.615994 -300.083474)
		(width 0.14224)
		(layer "In2.Cu")
		(net "P3E_CPU1_P4_RX_DP<3>")
	)
	(segment
		(start 82.666332 -313.624722)
		(end 82.789522 -313.474354)
		(width 0.14224)
		(layer "In2.Cu")
		(net "P3E_CPU1_P4_RX_DP<3>")
	)
	(segment
		(start 105.116884 -297.09745)
		(end 105.116884 -296.612564)
		(width 0.14224)
		(layer "In2.Cu")
		(net "P3E_CPU1_P4_RX_DP<3>")
	)
	(segment
		(start 89.330784 -90.325702)
		(end 44.664376 -134.990332)
		(width 0.14224)
		(layer "In2.Cu")
		(net "P3E_CPU1_P4_RX_DP<3>")
	)
	(segment
		(start 75.385676 -314.95492)
		(end 75.804014 -314.871862)
		(width 0.14224)
		(layer "In2.Cu")
		(net "P3E_CPU1_P4_RX_DP<3>")
	)
	(segment
		(start 105.689908 -294.657526)
		(end 105.691432 -294.656764)
		(width 0.1143)
		(layer "In2.Cu")
		(net "P3E_CPU1_P4_RX_DP<3>")
	)
	(segment
		(start 76.330556 -314.62726)
		(end 76.491846 -314.734956)
		(width 0.14224)
		(layer "In2.Cu")
		(net "P3E_CPU1_P4_RX_DP<3>")
	)
	(segment
		(start 172.679868 -58.701178)
		(end 171.873672 -58.701178)
		(width 0.14224)
		(layer "In2.Cu")
		(net "P3E_CPU1_P4_RX_DP<3>")
	)
	(segment
		(start 76.910184 -314.651898)
		(end 77.018134 -314.490354)
		(width 0.14224)
		(layer "In2.Cu")
		(net "P3E_CPU1_P4_RX_DP<3>")
	)
	(segment
		(start 177.309018 -56.782716)
		(end 172.679868 -58.701178)
		(width 0.14224)
		(layer "In2.Cu")
		(net "P3E_CPU1_P4_RX_DP<3>")
	)
	(segment
		(start 65.128394 -321.707256)
		(end 71.01078 -315.82487)
		(width 0.14224)
		(layer "In2.Cu")
		(net "P3E_CPU1_P4_RX_DP<3>")
	)
	(segment
		(start 179.011834 -54.618128)
		(end 179.302664 -54.908958)
		(width 0.14224)
		(layer "In2.Cu")
		(net "P3E_CPU1_P4_RX_DP<3>")
	)
	(segment
		(start 86.103968 -313.147964)
		(end 86.528656 -313.106054)
		(width 0.14224)
		(layer "In2.Cu")
		(net "P3E_CPU1_P4_RX_DP<3>")
	)
	(segment
		(start 16.070326 -322.559426)
		(end 59.3344 -322.874386)
		(width 0.14224)
		(layer "In2.Cu")
		(net "P3E_CPU1_P4_RX_DP<3>")
	)
	(segment
		(start 105.116884 -296.584116)
		(end 105.162604 -296.538396)
		(width 0.1143)
		(layer "In2.Cu")
		(net "P3E_CPU1_P4_RX_DP<3>")
	)
	(segment
		(start 159.47009 -60.30849)
		(end 156.969714 -61.176408)
		(width 0.14224)
		(layer "In2.Cu")
		(net "P3E_CPU1_P4_RX_DP<3>")
	)
	(segment
		(start 75.911964 -314.710318)
		(end 76.330556 -314.62726)
		(width 0.14224)
		(layer "In2.Cu")
		(net "P3E_CPU1_P4_RX_DP<3>")
	)
	(segment
		(start 81.501234 -313.739276)
		(end 82.666332 -313.624722)
		(width 0.14224)
		(layer "In2.Cu")
		(net "P3E_CPU1_P4_RX_DP<3>")
	)
	(segment
		(start 74.80554 -314.930536)
		(end 75.224386 -314.847224)
		(width 0.14224)
		(layer "In2.Cu")
		(net "P3E_CPU1_P4_RX_DP<3>")
	)
	(arc
		(start 105.719626 -294.640508)
		(mid 105.816761 -294.537639)
		(end 105.868724 -294.406066)
		(width 0.1143)
		(layer "In2.Cu")
		(net "P3E_CPU1_P4_RX_DP<3>")
	)
	(arc
		(start 105.273348 -295.466008)
		(mid 105.371343 -295.319169)
		(end 105.405428 -295.145968)
		(width 0.1143)
		(layer "In2.Cu")
		(net "P3E_CPU1_P4_RX_DP<3>")
	)
	(arc
		(start 105.405428 -295.145968)
		(mid 105.470277 -294.883303)
		(end 105.649776 -294.680894)
		(width 0.1143)
		(layer "In2.Cu")
		(net "P3E_CPU1_P4_RX_DP<3>")
	)
	(segment
		(start 177.796698 -51.799998)
		(end 177.885344 -51.888644)
		(width 0.12954)
		(layer "F.Cu")
		(net "P3E_CPU1_P4_RX_DP<2>")
	)
	(segment
		(start 177.108358 -51.799998)
		(end 177.796698 -51.799998)
		(width 0.12954)
		(layer "F.Cu")
		(net "P3E_CPU1_P4_RX_DP<2>")
	)
	(segment
		(start 103.147876 -294.070278)
		(end 102.681024 -294.336216)
		(width 0.12954)
		(layer "F.Cu")
		(net "P3E_CPU1_P4_RX_DP<2>")
	)
	(segment
		(start 177.885344 -51.888644)
		(end 178.741324 -51.888644)
		(width 0.12954)
		(layer "F.Cu")
		(net "P3E_CPU1_P4_RX_DP<2>")
	)
	(segment
		(start 178.741324 -51.888644)
		(end 179.011834 -51.618134)
		(width 0.12954)
		(layer "F.Cu")
		(net "P3E_CPU1_P4_RX_DP<2>")
	)
	(segment
		(start 166.51605 -62.271656)
		(end 163.138612 -62.867032)
		(width 0.14224)
		(layer "In2.Cu")
		(net "P3E_CPU1_P4_RX_DP<2>")
	)
	(segment
		(start 89.080086 -311.48274)
		(end 89.50198 -311.420256)
		(width 0.14224)
		(layer "In2.Cu")
		(net "P3E_CPU1_P4_RX_DP<2>")
	)
	(segment
		(start 62.187328 -321.908424)
		(end 64.532256 -320.937128)
		(width 0.14224)
		(layer "In2.Cu")
		(net "P3E_CPU1_P4_RX_DP<2>")
	)
	(segment
		(start 97.496122 -306.28336)
		(end 97.467674 -306.09159)
		(width 0.14224)
		(layer "In2.Cu")
		(net "P3E_CPU1_P4_RX_DP<2>")
	)
	(segment
		(start 98.84029 -304.471324)
		(end 98.811842 -304.279554)
		(width 0.14224)
		(layer "In2.Cu")
		(net "P3E_CPU1_P4_RX_DP<2>")
	)
	(segment
		(start 102.265988 -297.99534)
		(end 102.311708 -297.94962)
		(width 0.1143)
		(layer "In2.Cu")
		(net "P3E_CPU1_P4_RX_DP<2>")
	)
	(segment
		(start 88.501728 -311.429908)
		(end 88.92413 -311.36717)
		(width 0.14224)
		(layer "In2.Cu")
		(net "P3E_CPU1_P4_RX_DP<2>")
	)
	(segment
		(start 97.722182 -305.748436)
		(end 97.914206 -305.719988)
		(width 0.14224)
		(layer "In2.Cu")
		(net "P3E_CPU1_P4_RX_DP<2>")
	)
	(segment
		(start 89.61755 -311.2643)
		(end 90.039698 -311.201562)
		(width 0.14224)
		(layer "In2.Cu")
		(net "P3E_CPU1_P4_RX_DP<2>")
	)
	(segment
		(start 98.139758 -305.185572)
		(end 98.394266 -304.842418)
		(width 0.14224)
		(layer "In2.Cu")
		(net "P3E_CPU1_P4_RX_DP<2>")
	)
	(segment
		(start 96.824292 -307.189378)
		(end 96.795844 -306.997354)
		(width 0.14224)
		(layer "In2.Cu")
		(net "P3E_CPU1_P4_RX_DP<2>")
	)
	(segment
		(start 102.265988 -298.023788)
		(end 102.265988 -297.99534)
		(width 0.1143)
		(layer "In2.Cu")
		(net "P3E_CPU1_P4_RX_DP<2>")
	)
	(segment
		(start 183.303672 -51.908964)
		(end 184.233566 -52.838858)
		(width 0.14224)
		(layer "In2.Cu")
		(net "P3E_CPU1_P4_RX_DP<2>")
	)
	(segment
		(start 99.06635 -303.9364)
		(end 99.25812 -303.907952)
		(width 0.14224)
		(layer "In2.Cu")
		(net "P3E_CPU1_P4_RX_DP<2>")
	)
	(segment
		(start 113.23066 -67.1195)
		(end 100.534978 -76.008992)
		(width 0.14224)
		(layer "In2.Cu")
		(net "P3E_CPU1_P4_RX_DP<2>")
	)
	(segment
		(start 96.271588 -307.93436)
		(end 96.824292 -307.189378)
		(width 0.14224)
		(layer "In2.Cu")
		(net "P3E_CPU1_P4_RX_DP<2>")
	)
	(segment
		(start 98.168206 -305.377342)
		(end 98.139758 -305.185572)
		(width 0.14224)
		(layer "In2.Cu")
		(net "P3E_CPU1_P4_RX_DP<2>")
	)
	(segment
		(start 34.065972 -160.701482)
		(end 26.138378 -166.252144)
		(width 0.14224)
		(layer "In2.Cu")
		(net "P3E_CPU1_P4_RX_DP<2>")
	)
	(segment
		(start 162.263074 -63.009526)
		(end 162.258502 -63.004954)
		(width 0.14224)
		(layer "In2.Cu")
		(net "P3E_CPU1_P4_RX_DP<2>")
	)
	(segment
		(start 90.195654 -311.317132)
		(end 90.8812 -311.215532)
		(width 0.14224)
		(layer "In2.Cu")
		(net "P3E_CPU1_P4_RX_DP<2>")
	)
	(segment
		(start 89.50198 -311.420256)
		(end 89.61755 -311.2643)
		(width 0.14224)
		(layer "In2.Cu")
		(net "P3E_CPU1_P4_RX_DP<2>")
	)
	(segment
		(start 102.287324 -298.394628)
		(end 102.265988 -298.373292)
		(width 0.14224)
		(layer "In2.Cu")
		(net "P3E_CPU1_P4_RX_DP<2>")
	)
	(segment
		(start 26.138378 -166.252144)
		(end 11.444478 -187.23864)
		(width 0.14224)
		(layer "In2.Cu")
		(net "P3E_CPU1_P4_RX_DP<2>")
	)
	(segment
		(start 13.62075 -314.186062)
		(end 14.43736 -319.600834)
		(width 0.14224)
		(layer "In2.Cu")
		(net "P3E_CPU1_P4_RX_DP<2>")
	)
	(segment
		(start 70.472046 -314.997338)
		(end 73.305924 -313.822842)
		(width 0.14224)
		(layer "In2.Cu")
		(net "P3E_CPU1_P4_RX_DP<2>")
	)
	(segment
		(start 100.534978 -76.008992)
		(end 90.061796 -90.966036)
		(width 0.14224)
		(layer "In2.Cu")
		(net "P3E_CPU1_P4_RX_DP<2>")
	)
	(segment
		(start 102.829106 -294.681656)
		(end 102.898702 -294.641016)
		(width 0.1143)
		(layer "In2.Cu")
		(net "P3E_CPU1_P4_RX_DP<2>")
	)
	(segment
		(start 116.838222 -66.483484)
		(end 113.23066 -67.1195)
		(width 0.14224)
		(layer "In2.Cu")
		(net "P3E_CPU1_P4_RX_DP<2>")
	)
	(segment
		(start 99.25812 -303.907952)
		(end 102.514908 -299.517054)
		(width 0.14224)
		(layer "In2.Cu")
		(net "P3E_CPU1_P4_RX_DP<2>")
	)
	(segment
		(start 102.514908 -298.94403)
		(end 102.287324 -298.394628)
		(width 0.14224)
		(layer "In2.Cu")
		(net "P3E_CPU1_P4_RX_DP<2>")
	)
	(segment
		(start 59.33821 -321.908424)
		(end 62.187328 -321.908424)
		(width 0.14224)
		(layer "In2.Cu")
		(net "P3E_CPU1_P4_RX_DP<2>")
	)
	(segment
		(start 179.302664 -51.908964)
		(end 183.303672 -51.908964)
		(width 0.14224)
		(layer "In2.Cu")
		(net "P3E_CPU1_P4_RX_DP<2>")
	)
	(segment
		(start 103.048816 -294.406066)
		(end 102.978966 -294.336216)
		(width 0.1143)
		(layer "In2.Cu")
		(net "P3E_CPU1_P4_RX_DP<2>")
	)
	(segment
		(start 90.039698 -311.201562)
		(end 90.195654 -311.317132)
		(width 0.14224)
		(layer "In2.Cu")
		(net "P3E_CPU1_P4_RX_DP<2>")
	)
	(segment
		(start 182.336694 -57.735216)
		(end 177.467768 -57.735216)
		(width 0.14224)
		(layer "In2.Cu")
		(net "P3E_CPU1_P4_RX_DP<2>")
	)
	(segment
		(start 97.914206 -305.719988)
		(end 98.168206 -305.377342)
		(width 0.14224)
		(layer "In2.Cu")
		(net "P3E_CPU1_P4_RX_DP<2>")
	)
	(segment
		(start 179.011834 -51.618134)
		(end 179.302664 -51.908964)
		(width 0.14224)
		(layer "In2.Cu")
		(net "P3E_CPU1_P4_RX_DP<2>")
	)
	(segment
		(start 96.795844 -306.997354)
		(end 97.050352 -306.654454)
		(width 0.14224)
		(layer "In2.Cu")
		(net "P3E_CPU1_P4_RX_DP<2>")
	)
	(segment
		(start 163.138612 -62.867032)
		(end 163.124642 -62.85738)
		(width 0.14224)
		(layer "In2.Cu")
		(net "P3E_CPU1_P4_RX_DP<2>")
	)
	(segment
		(start 97.050352 -306.654454)
		(end 97.242122 -306.626006)
		(width 0.14224)
		(layer "In2.Cu")
		(net "P3E_CPU1_P4_RX_DP<2>")
	)
	(segment
		(start 184.233566 -52.838858)
		(end 184.233566 -55.838344)
		(width 0.14224)
		(layer "In2.Cu")
		(net "P3E_CPU1_P4_RX_DP<2>")
	)
	(segment
		(start 90.8812 -311.215532)
		(end 95.149162 -309.447692)
		(width 0.14224)
		(layer "In2.Cu")
		(net "P3E_CPU1_P4_RX_DP<2>")
	)
	(segment
		(start 95.82531 -308.305708)
		(end 96.079818 -307.962808)
		(width 0.14224)
		(layer "In2.Cu")
		(net "P3E_CPU1_P4_RX_DP<2>")
	)
	(segment
		(start 35.703764 -159.06369)
		(end 34.065972 -160.701482)
		(width 0.14224)
		(layer "In2.Cu")
		(net "P3E_CPU1_P4_RX_DP<2>")
	)
	(segment
		(start 64.532256 -320.937128)
		(end 70.472046 -314.997338)
		(width 0.14224)
		(layer "In2.Cu")
		(net "P3E_CPU1_P4_RX_DP<2>")
	)
	(segment
		(start 98.394266 -304.842418)
		(end 98.58629 -304.81397)
		(width 0.14224)
		(layer "In2.Cu")
		(net "P3E_CPU1_P4_RX_DP<2>")
	)
	(segment
		(start 184.233566 -55.838344)
		(end 182.336694 -57.735216)
		(width 0.14224)
		(layer "In2.Cu")
		(net "P3E_CPU1_P4_RX_DP<2>")
	)
	(segment
		(start 73.305924 -313.822842)
		(end 88.386412 -311.585864)
		(width 0.14224)
		(layer "In2.Cu")
		(net "P3E_CPU1_P4_RX_DP<2>")
	)
	(segment
		(start 162.258502 -63.004954)
		(end 162.21964 -63.004954)
		(width 0.14224)
		(layer "In2.Cu")
		(net "P3E_CPU1_P4_RX_DP<2>")
	)
	(segment
		(start 155.526486 -62.304168)
		(end 116.838222 -66.483484)
		(width 0.14224)
		(layer "In2.Cu")
		(net "P3E_CPU1_P4_RX_DP<2>")
	)
	(segment
		(start 98.811842 -304.279554)
		(end 99.06635 -303.9364)
		(width 0.14224)
		(layer "In2.Cu")
		(net "P3E_CPU1_P4_RX_DP<2>")
	)
	(segment
		(start 14.43736 -319.600834)
		(end 16.43253 -321.596004)
		(width 0.14224)
		(layer "In2.Cu")
		(net "P3E_CPU1_P4_RX_DP<2>")
	)
	(segment
		(start 11.444478 -187.23864)
		(end 10.705084 -191.432434)
		(width 0.14224)
		(layer "In2.Cu")
		(net "P3E_CPU1_P4_RX_DP<2>")
	)
	(segment
		(start 162.21964 -63.004954)
		(end 155.526486 -62.304168)
		(width 0.14224)
		(layer "In2.Cu")
		(net "P3E_CPU1_P4_RX_DP<2>")
	)
	(segment
		(start 97.242122 -306.626006)
		(end 97.496122 -306.28336)
		(width 0.14224)
		(layer "In2.Cu")
		(net "P3E_CPU1_P4_RX_DP<2>")
	)
	(segment
		(start 102.514908 -299.517054)
		(end 102.514908 -298.94403)
		(width 0.14224)
		(layer "In2.Cu")
		(net "P3E_CPU1_P4_RX_DP<2>")
	)
	(segment
		(start 102.978966 -294.336216)
		(end 102.681024 -294.336216)
		(width 0.1143)
		(layer "In2.Cu")
		(net "P3E_CPU1_P4_RX_DP<2>")
	)
	(segment
		(start 177.467768 -57.735216)
		(end 166.51605 -62.271656)
		(width 0.14224)
		(layer "In2.Cu")
		(net "P3E_CPU1_P4_RX_DP<2>")
	)
	(segment
		(start 95.149162 -309.447692)
		(end 95.853758 -308.497732)
		(width 0.14224)
		(layer "In2.Cu")
		(net "P3E_CPU1_P4_RX_DP<2>")
	)
	(segment
		(start 16.43253 -321.596004)
		(end 59.33821 -321.908424)
		(width 0.14224)
		(layer "In2.Cu")
		(net "P3E_CPU1_P4_RX_DP<2>")
	)
	(segment
		(start 45.420026 -135.60679)
		(end 35.703764 -159.06369)
		(width 0.14224)
		(layer "In2.Cu")
		(net "P3E_CPU1_P4_RX_DP<2>")
	)
	(segment
		(start 95.853758 -308.497732)
		(end 95.82531 -308.305708)
		(width 0.14224)
		(layer "In2.Cu")
		(net "P3E_CPU1_P4_RX_DP<2>")
	)
	(segment
		(start 88.92413 -311.36717)
		(end 89.080086 -311.48274)
		(width 0.14224)
		(layer "In2.Cu")
		(net "P3E_CPU1_P4_RX_DP<2>")
	)
	(segment
		(start 88.386412 -311.585864)
		(end 88.501728 -311.429908)
		(width 0.14224)
		(layer "In2.Cu")
		(net "P3E_CPU1_P4_RX_DP<2>")
	)
	(segment
		(start 163.124642 -62.85738)
		(end 162.263074 -63.009526)
		(width 0.14224)
		(layer "In2.Cu")
		(net "P3E_CPU1_P4_RX_DP<2>")
	)
	(segment
		(start 102.265988 -298.373292)
		(end 102.265988 -298.023788)
		(width 0.14224)
		(layer "In2.Cu")
		(net "P3E_CPU1_P4_RX_DP<2>")
	)
	(segment
		(start 90.061796 -90.966036)
		(end 45.420026 -135.60679)
		(width 0.14224)
		(layer "In2.Cu")
		(net "P3E_CPU1_P4_RX_DP<2>")
	)
	(segment
		(start 98.58629 -304.81397)
		(end 98.84029 -304.471324)
		(width 0.14224)
		(layer "In2.Cu")
		(net "P3E_CPU1_P4_RX_DP<2>")
	)
	(segment
		(start 10.705084 -191.432434)
		(end 13.62075 -314.186062)
		(width 0.14224)
		(layer "In2.Cu")
		(net "P3E_CPU1_P4_RX_DP<2>")
	)
	(segment
		(start 102.311708 -297.94962)
		(end 102.311708 -295.996868)
		(width 0.1143)
		(layer "In2.Cu")
		(net "P3E_CPU1_P4_RX_DP<2>")
	)
	(segment
		(start 97.467674 -306.09159)
		(end 97.722182 -305.748436)
		(width 0.14224)
		(layer "In2.Cu")
		(net "P3E_CPU1_P4_RX_DP<2>")
	)
	(segment
		(start 96.079818 -307.962808)
		(end 96.271588 -307.93436)
		(width 0.14224)
		(layer "In2.Cu")
		(net "P3E_CPU1_P4_RX_DP<2>")
	)
	(arc
		(start 102.898702 -294.641016)
		(mid 102.996467 -294.53804)
		(end 103.048816 -294.406066)
		(width 0.1143)
		(layer "In2.Cu")
		(net "P3E_CPU1_P4_RX_DP<2>")
	)
	(arc
		(start 102.311708 -295.996868)
		(mid 102.36383 -295.665164)
		(end 102.515162 -295.365424)
		(width 0.1143)
		(layer "In2.Cu")
		(net "P3E_CPU1_P4_RX_DP<2>")
	)
	(arc
		(start 102.515162 -295.365424)
		(mid 102.567703 -295.261377)
		(end 102.585774 -295.146222)
		(width 0.1143)
		(layer "In2.Cu")
		(net "P3E_CPU1_P4_RX_DP<2>")
	)
	(arc
		(start 102.585774 -295.146222)
		(mid 102.650289 -294.884003)
		(end 102.829106 -294.681656)
		(width 0.1143)
		(layer "In2.Cu")
		(net "P3E_CPU1_P4_RX_DP<2>")
	)
	(segment
		(start 100.327968 -294.070278)
		(end 99.861116 -294.336216)
		(width 0.12954)
		(layer "F.Cu")
		(net "P3E_CPU1_P4_RX_DP<1>")
	)
	(segment
		(start 177.108358 -48.800004)
		(end 177.796698 -48.800004)
		(width 0.12954)
		(layer "F.Cu")
		(net "P3E_CPU1_P4_RX_DP<1>")
	)
	(segment
		(start 177.796698 -48.800004)
		(end 177.885344 -48.88865)
		(width 0.12954)
		(layer "F.Cu")
		(net "P3E_CPU1_P4_RX_DP<1>")
	)
	(segment
		(start 177.885344 -48.88865)
		(end 178.741324 -48.88865)
		(width 0.12954)
		(layer "F.Cu")
		(net "P3E_CPU1_P4_RX_DP<1>")
	)
	(segment
		(start 178.741324 -48.88865)
		(end 179.011834 -48.61814)
		(width 0.12954)
		(layer "F.Cu")
		(net "P3E_CPU1_P4_RX_DP<1>")
	)
	(segment
		(start 100.032058 -294.66794)
		(end 100.04552 -294.66032)
		(width 0.1143)
		(layer "In2.Cu")
		(net "P3E_CPU1_P4_RX_DP<1>")
	)
	(segment
		(start 91.960446 -302.622204)
		(end 95.903796 -301.83836)
		(width 0.14224)
		(layer "In2.Cu")
		(net "P3E_CPU1_P4_RX_DP<1>")
	)
	(segment
		(start 113.618772 -68.056506)
		(end 101.245924 -76.719938)
		(width 0.14224)
		(layer "In2.Cu")
		(net "P3E_CPU1_P4_RX_DP<1>")
	)
	(segment
		(start 179.302664 -48.90897)
		(end 183.173878 -48.90897)
		(width 0.14224)
		(layer "In2.Cu")
		(net "P3E_CPU1_P4_RX_DP<1>")
	)
	(segment
		(start 77.647546 -311.794906)
		(end 78.066138 -311.711594)
		(width 0.14224)
		(layer "In2.Cu")
		(net "P3E_CPU1_P4_RX_DP<1>")
	)
	(segment
		(start 99.482656 -297.989244)
		(end 99.482656 -297.960796)
		(width 0.1143)
		(layer "In2.Cu")
		(net "P3E_CPU1_P4_RX_DP<1>")
	)
	(segment
		(start 90.835988 -91.587066)
		(end 46.248574 -136.173464)
		(width 0.14224)
		(layer "In2.Cu")
		(net "P3E_CPU1_P4_RX_DP<1>")
	)
	(segment
		(start 166.778178 -63.172848)
		(end 162.153854 -63.988188)
		(width 0.14224)
		(layer "In2.Cu")
		(net "P3E_CPU1_P4_RX_DP<1>")
	)
	(segment
		(start 75.990958 -312.264552)
		(end 76.409296 -312.181494)
		(width 0.14224)
		(layer "In2.Cu")
		(net "P3E_CPU1_P4_RX_DP<1>")
	)
	(segment
		(start 12.381484 -187.626752)
		(end 11.655298 -191.745362)
		(width 0.14224)
		(layer "In2.Cu")
		(net "P3E_CPU1_P4_RX_DP<1>")
	)
	(segment
		(start 79.447898 -311.576466)
		(end 79.866236 -311.493408)
		(width 0.14224)
		(layer "In2.Cu")
		(net "P3E_CPU1_P4_RX_DP<1>")
	)
	(segment
		(start 46.248574 -136.173464)
		(end 36.508182 -159.688022)
		(width 0.14224)
		(layer "In2.Cu")
		(net "P3E_CPU1_P4_RX_DP<1>")
	)
	(segment
		(start 76.409296 -312.181494)
		(end 76.516992 -312.01995)
		(width 0.14224)
		(layer "In2.Cu")
		(net "P3E_CPU1_P4_RX_DP<1>")
	)
	(segment
		(start 76.935838 -311.936638)
		(end 77.097128 -312.044334)
		(width 0.14224)
		(layer "In2.Cu")
		(net "P3E_CPU1_P4_RX_DP<1>")
	)
	(segment
		(start 99.482656 -298.259754)
		(end 99.482656 -297.989244)
		(width 0.14224)
		(layer "In2.Cu")
		(net "P3E_CPU1_P4_RX_DP<1>")
	)
	(segment
		(start 177.599594 -58.690002)
		(end 166.778178 -63.172848)
		(width 0.14224)
		(layer "In2.Cu")
		(net "P3E_CPU1_P4_RX_DP<1>")
	)
	(segment
		(start 100.051616 -294.656764)
		(end 100.07981 -294.640508)
		(width 0.1143)
		(layer "In2.Cu")
		(net "P3E_CPU1_P4_RX_DP<1>")
	)
	(segment
		(start 78.760066 -311.713372)
		(end 78.867762 -311.551828)
		(width 0.14224)
		(layer "In2.Cu")
		(net "P3E_CPU1_P4_RX_DP<1>")
	)
	(segment
		(start 81.498948 -311.028588)
		(end 81.660238 -311.136538)
		(width 0.14224)
		(layer "In2.Cu")
		(net "P3E_CPU1_P4_RX_DP<1>")
	)
	(segment
		(start 100.04806 -294.658796)
		(end 100.048822 -294.658288)
		(width 0.1143)
		(layer "In2.Cu")
		(net "P3E_CPU1_P4_RX_DP<1>")
	)
	(segment
		(start 100.047044 -294.659304)
		(end 100.04806 -294.658796)
		(width 0.1143)
		(layer "In2.Cu")
		(net "P3E_CPU1_P4_RX_DP<1>")
	)
	(segment
		(start 162.10915 -63.983616)
		(end 155.3972 -63.313818)
		(width 0.14224)
		(layer "In2.Cu")
		(net "P3E_CPU1_P4_RX_DP<1>")
	)
	(segment
		(start 78.066138 -311.711594)
		(end 78.227428 -311.81929)
		(width 0.14224)
		(layer "In2.Cu")
		(net "P3E_CPU1_P4_RX_DP<1>")
	)
	(segment
		(start 185.455306 -56.009032)
		(end 182.774336 -58.690002)
		(width 0.14224)
		(layer "In2.Cu")
		(net "P3E_CPU1_P4_RX_DP<1>")
	)
	(segment
		(start 81.080356 -311.1119)
		(end 81.498948 -311.028588)
		(width 0.14224)
		(layer "In2.Cu")
		(net "P3E_CPU1_P4_RX_DP<1>")
	)
	(segment
		(start 74.196956 -312.62193)
		(end 74.304652 -312.460386)
		(width 0.14224)
		(layer "In2.Cu")
		(net "P3E_CPU1_P4_RX_DP<1>")
	)
	(segment
		(start 59.342274 -320.918586)
		(end 62.110874 -320.918586)
		(width 0.14224)
		(layer "In2.Cu")
		(net "P3E_CPU1_P4_RX_DP<1>")
	)
	(segment
		(start 80.972406 -311.273444)
		(end 81.080356 -311.1119)
		(width 0.14224)
		(layer "In2.Cu")
		(net "P3E_CPU1_P4_RX_DP<1>")
	)
	(segment
		(start 100.050092 -294.657526)
		(end 100.051616 -294.656764)
		(width 0.1143)
		(layer "In2.Cu")
		(net "P3E_CPU1_P4_RX_DP<1>")
	)
	(segment
		(start 100.228908 -294.406066)
		(end 100.159058 -294.336216)
		(width 0.1143)
		(layer "In2.Cu")
		(net "P3E_CPU1_P4_RX_DP<1>")
	)
	(segment
		(start 79.974186 -311.331864)
		(end 80.392778 -311.248552)
		(width 0.14224)
		(layer "In2.Cu")
		(net "P3E_CPU1_P4_RX_DP<1>")
	)
	(segment
		(start 99.528376 -297.915076)
		(end 99.528376 -295.917366)
		(width 0.1143)
		(layer "In2.Cu")
		(net "P3E_CPU1_P4_RX_DP<1>")
	)
	(segment
		(start 75.829668 -312.156856)
		(end 75.990958 -312.264552)
		(width 0.14224)
		(layer "In2.Cu")
		(net "P3E_CPU1_P4_RX_DP<1>")
	)
	(segment
		(start 100.009198 -294.681148)
		(end 100.031042 -294.668702)
		(width 0.1143)
		(layer "In2.Cu")
		(net "P3E_CPU1_P4_RX_DP<1>")
	)
	(segment
		(start 100.159058 -294.336216)
		(end 99.861116 -294.336216)
		(width 0.1143)
		(layer "In2.Cu")
		(net "P3E_CPU1_P4_RX_DP<1>")
	)
	(segment
		(start 77.539596 -311.95645)
		(end 77.647546 -311.794906)
		(width 0.14224)
		(layer "In2.Cu")
		(net "P3E_CPU1_P4_RX_DP<1>")
	)
	(segment
		(start 78.867762 -311.551828)
		(end 79.286608 -311.46877)
		(width 0.14224)
		(layer "In2.Cu")
		(net "P3E_CPU1_P4_RX_DP<1>")
	)
	(segment
		(start 81.660492 -311.136538)
		(end 86.598252 -310.154574)
		(width 0.14224)
		(layer "In2.Cu")
		(net "P3E_CPU1_P4_RX_DP<1>")
	)
	(segment
		(start 26.849578 -166.963344)
		(end 12.381484 -187.626752)
		(width 0.14224)
		(layer "In2.Cu")
		(net "P3E_CPU1_P4_RX_DP<1>")
	)
	(segment
		(start 77.097128 -312.044334)
		(end 77.539596 -311.95645)
		(width 0.14224)
		(layer "In2.Cu")
		(net "P3E_CPU1_P4_RX_DP<1>")
	)
	(segment
		(start 74.884788 -312.48477)
		(end 75.303126 -312.401712)
		(width 0.14224)
		(layer "In2.Cu")
		(net "P3E_CPU1_P4_RX_DP<1>")
	)
	(segment
		(start 162.149282 -63.983616)
		(end 162.10915 -63.983616)
		(width 0.14224)
		(layer "In2.Cu")
		(net "P3E_CPU1_P4_RX_DP<1>")
	)
	(segment
		(start 95.903796 -301.83836)
		(end 99.482656 -298.259754)
		(width 0.14224)
		(layer "In2.Cu")
		(net "P3E_CPU1_P4_RX_DP<1>")
	)
	(segment
		(start 101.245924 -76.719938)
		(end 90.835988 -91.587066)
		(width 0.14224)
		(layer "In2.Cu")
		(net "P3E_CPU1_P4_RX_DP<1>")
	)
	(segment
		(start 76.516992 -312.01995)
		(end 76.935838 -311.936638)
		(width 0.14224)
		(layer "In2.Cu")
		(net "P3E_CPU1_P4_RX_DP<1>")
	)
	(segment
		(start 62.110874 -320.918586)
		(end 63.973456 -320.147188)
		(width 0.14224)
		(layer "In2.Cu")
		(net "P3E_CPU1_P4_RX_DP<1>")
	)
	(segment
		(start 100.048822 -294.658288)
		(end 100.050092 -294.657526)
		(width 0.1143)
		(layer "In2.Cu")
		(net "P3E_CPU1_P4_RX_DP<1>")
	)
	(segment
		(start 87.154512 -308.88178)
		(end 87.414862 -306.24272)
		(width 0.14224)
		(layer "In2.Cu")
		(net "P3E_CPU1_P4_RX_DP<1>")
	)
	(segment
		(start 73.307448 -312.798714)
		(end 74.196956 -312.62193)
		(width 0.14224)
		(layer "In2.Cu")
		(net "P3E_CPU1_P4_RX_DP<1>")
	)
	(segment
		(start 100.04552 -294.66032)
		(end 100.047044 -294.659304)
		(width 0.1143)
		(layer "In2.Cu")
		(net "P3E_CPU1_P4_RX_DP<1>")
	)
	(segment
		(start 87.414862 -306.24272)
		(end 87.899748 -305.335686)
		(width 0.14224)
		(layer "In2.Cu")
		(net "P3E_CPU1_P4_RX_DP<1>")
	)
	(segment
		(start 75.303126 -312.401712)
		(end 75.410822 -312.240168)
		(width 0.14224)
		(layer "In2.Cu")
		(net "P3E_CPU1_P4_RX_DP<1>")
	)
	(segment
		(start 80.554068 -311.356502)
		(end 80.972406 -311.273444)
		(width 0.14224)
		(layer "In2.Cu")
		(net "P3E_CPU1_P4_RX_DP<1>")
	)
	(segment
		(start 99.482656 -297.960796)
		(end 99.528376 -297.915076)
		(width 0.1143)
		(layer "In2.Cu")
		(net "P3E_CPU1_P4_RX_DP<1>")
	)
	(segment
		(start 87.899748 -305.335686)
		(end 91.960446 -302.622204)
		(width 0.14224)
		(layer "In2.Cu")
		(net "P3E_CPU1_P4_RX_DP<1>")
	)
	(segment
		(start 75.410822 -312.240168)
		(end 75.829668 -312.156856)
		(width 0.14224)
		(layer "In2.Cu")
		(net "P3E_CPU1_P4_RX_DP<1>")
	)
	(segment
		(start 86.598252 -310.154574)
		(end 86.976966 -309.77586)
		(width 0.14224)
		(layer "In2.Cu")
		(net "P3E_CPU1_P4_RX_DP<1>")
	)
	(segment
		(start 100.031042 -294.668702)
		(end 100.032058 -294.66794)
		(width 0.1143)
		(layer "In2.Cu")
		(net "P3E_CPU1_P4_RX_DP<1>")
	)
	(segment
		(start 74.723498 -312.377074)
		(end 74.884788 -312.48477)
		(width 0.14224)
		(layer "In2.Cu")
		(net "P3E_CPU1_P4_RX_DP<1>")
	)
	(segment
		(start 81.660238 -311.136538)
		(end 81.660492 -311.136538)
		(width 0.14224)
		(layer "In2.Cu")
		(net "P3E_CPU1_P4_RX_DP<1>")
	)
	(segment
		(start 183.173878 -48.90897)
		(end 185.455306 -51.190398)
		(width 0.14224)
		(layer "In2.Cu")
		(net "P3E_CPU1_P4_RX_DP<1>")
	)
	(segment
		(start 162.153854 -63.988188)
		(end 162.149282 -63.983616)
		(width 0.14224)
		(layer "In2.Cu")
		(net "P3E_CPU1_P4_RX_DP<1>")
	)
	(segment
		(start 80.392778 -311.248552)
		(end 80.554068 -311.356502)
		(width 0.14224)
		(layer "In2.Cu")
		(net "P3E_CPU1_P4_RX_DP<1>")
	)
	(segment
		(start 155.3972 -63.313818)
		(end 116.977414 -67.464178)
		(width 0.14224)
		(layer "In2.Cu")
		(net "P3E_CPU1_P4_RX_DP<1>")
	)
	(segment
		(start 69.916802 -314.203842)
		(end 73.307448 -312.798714)
		(width 0.14224)
		(layer "In2.Cu")
		(net "P3E_CPU1_P4_RX_DP<1>")
	)
	(segment
		(start 185.455306 -51.190398)
		(end 185.455306 -56.009032)
		(width 0.14224)
		(layer "In2.Cu")
		(net "P3E_CPU1_P4_RX_DP<1>")
	)
	(segment
		(start 15.313914 -319.158366)
		(end 16.763746 -320.608452)
		(width 0.14224)
		(layer "In2.Cu")
		(net "P3E_CPU1_P4_RX_DP<1>")
	)
	(segment
		(start 74.304652 -312.460386)
		(end 74.723498 -312.377074)
		(width 0.14224)
		(layer "In2.Cu")
		(net "P3E_CPU1_P4_RX_DP<1>")
	)
	(segment
		(start 34.799778 -161.396426)
		(end 26.849578 -166.963344)
		(width 0.14224)
		(layer "In2.Cu")
		(net "P3E_CPU1_P4_RX_DP<1>")
	)
	(segment
		(start 182.774336 -58.690002)
		(end 177.599594 -58.690002)
		(width 0.14224)
		(layer "In2.Cu")
		(net "P3E_CPU1_P4_RX_DP<1>")
	)
	(segment
		(start 78.227428 -311.81929)
		(end 78.760066 -311.713372)
		(width 0.14224)
		(layer "In2.Cu")
		(net "P3E_CPU1_P4_RX_DP<1>")
	)
	(segment
		(start 79.286608 -311.46877)
		(end 79.447898 -311.576466)
		(width 0.14224)
		(layer "In2.Cu")
		(net "P3E_CPU1_P4_RX_DP<1>")
	)
	(segment
		(start 86.976966 -309.77586)
		(end 87.154512 -308.88178)
		(width 0.14224)
		(layer "In2.Cu")
		(net "P3E_CPU1_P4_RX_DP<1>")
	)
	(segment
		(start 179.011834 -48.61814)
		(end 179.302664 -48.90897)
		(width 0.14224)
		(layer "In2.Cu")
		(net "P3E_CPU1_P4_RX_DP<1>")
	)
	(segment
		(start 11.655298 -191.745362)
		(end 14.563598 -314.184538)
		(width 0.14224)
		(layer "In2.Cu")
		(net "P3E_CPU1_P4_RX_DP<1>")
	)
	(segment
		(start 79.866236 -311.493408)
		(end 79.974186 -311.331864)
		(width 0.14224)
		(layer "In2.Cu")
		(net "P3E_CPU1_P4_RX_DP<1>")
	)
	(segment
		(start 36.508182 -159.688022)
		(end 34.799778 -161.396426)
		(width 0.14224)
		(layer "In2.Cu")
		(net "P3E_CPU1_P4_RX_DP<1>")
	)
	(segment
		(start 116.977414 -67.464178)
		(end 113.618772 -68.056506)
		(width 0.14224)
		(layer "In2.Cu")
		(net "P3E_CPU1_P4_RX_DP<1>")
	)
	(segment
		(start 63.973456 -320.147188)
		(end 69.916802 -314.203842)
		(width 0.14224)
		(layer "In2.Cu")
		(net "P3E_CPU1_P4_RX_DP<1>")
	)
	(segment
		(start 14.563598 -314.184538)
		(end 15.313914 -319.158366)
		(width 0.14224)
		(layer "In2.Cu")
		(net "P3E_CPU1_P4_RX_DP<1>")
	)
	(segment
		(start 16.763746 -320.608452)
		(end 59.342274 -320.918586)
		(width 0.14224)
		(layer "In2.Cu")
		(net "P3E_CPU1_P4_RX_DP<1>")
	)
	(arc
		(start 99.765866 -295.146222)
		(mid 99.830336 -294.883772)
		(end 100.009198 -294.681148)
		(width 0.1143)
		(layer "In2.Cu")
		(net "P3E_CPU1_P4_RX_DP<1>")
	)
	(arc
		(start 99.528376 -295.917366)
		(mid 99.567155 -295.659834)
		(end 99.680014 -295.425114)
		(width 0.1143)
		(layer "In2.Cu")
		(net "P3E_CPU1_P4_RX_DP<1>")
	)
	(arc
		(start 100.07981 -294.640508)
		(mid 100.176945 -294.537639)
		(end 100.228908 -294.406066)
		(width 0.1143)
		(layer "In2.Cu")
		(net "P3E_CPU1_P4_RX_DP<1>")
	)
	(arc
		(start 99.680014 -295.425114)
		(mid 99.743992 -295.292144)
		(end 99.765866 -295.146222)
		(width 0.1143)
		(layer "In2.Cu")
		(net "P3E_CPU1_P4_RX_DP<1>")
	)
	(segment
		(start 177.885344 -45.888656)
		(end 178.741324 -45.888656)
		(width 0.12954)
		(layer "F.Cu")
		(net "P3E_CPU1_P4_RX_DP<0>")
	)
	(segment
		(start 177.796698 -45.80001)
		(end 177.885344 -45.888656)
		(width 0.12954)
		(layer "F.Cu")
		(net "P3E_CPU1_P4_RX_DP<0>")
	)
	(segment
		(start 177.108358 -45.80001)
		(end 177.796698 -45.80001)
		(width 0.12954)
		(layer "F.Cu")
		(net "P3E_CPU1_P4_RX_DP<0>")
	)
	(segment
		(start 97.507806 -294.070278)
		(end 97.040954 -294.336216)
		(width 0.12954)
		(layer "F.Cu")
		(net "P3E_CPU1_P4_RX_DP<0>")
	)
	(segment
		(start 178.741324 -45.888656)
		(end 179.011834 -45.618146)
		(width 0.12954)
		(layer "F.Cu")
		(net "P3E_CPU1_P4_RX_DP<0>")
	)
	(segment
		(start 95.570294 -297.964098)
		(end 96.656906 -296.87774)
		(width 0.14224)
		(layer "In2.Cu")
		(net "P3E_CPU1_P4_RX_DP<0>")
	)
	(segment
		(start 92.615766 -298.87545)
		(end 93.017594 -298.731686)
		(width 0.14224)
		(layer "In2.Cu")
		(net "P3E_CPU1_P4_RX_DP<0>")
	)
	(segment
		(start 179.302664 -45.908976)
		(end 183.528208 -45.908976)
		(width 0.14224)
		(layer "In2.Cu")
		(net "P3E_CPU1_P4_RX_DP<0>")
	)
	(segment
		(start 95.141796 -297.971718)
		(end 95.317056 -298.054522)
		(width 0.14224)
		(layer "In2.Cu")
		(net "P3E_CPU1_P4_RX_DP<0>")
	)
	(segment
		(start 63.398908 -319.365122)
		(end 69.414136 -313.349894)
		(width 0.14224)
		(layer "In2.Cu")
		(net "P3E_CPU1_P4_RX_DP<0>")
	)
	(segment
		(start 78.965552 -307.478684)
		(end 82.680302 -307.478684)
		(width 0.14224)
		(layer "In2.Cu")
		(net "P3E_CPU1_P4_RX_DP<0>")
	)
	(segment
		(start 71.422768 -312.518044)
		(end 78.965552 -307.478684)
		(width 0.14224)
		(layer "In2.Cu")
		(net "P3E_CPU1_P4_RX_DP<0>")
	)
	(segment
		(start 97.408746 -294.406066)
		(end 97.338896 -294.336216)
		(width 0.1143)
		(layer "In2.Cu")
		(net "P3E_CPU1_P4_RX_DP<0>")
	)
	(segment
		(start 186.41568 -56.548274)
		(end 183.240426 -59.723528)
		(width 0.14224)
		(layer "In2.Cu")
		(net "P3E_CPU1_P4_RX_DP<0>")
	)
	(segment
		(start 90.698574 -299.561504)
		(end 90.874088 -299.644562)
		(width 0.14224)
		(layer "In2.Cu")
		(net "P3E_CPU1_P4_RX_DP<0>")
	)
	(segment
		(start 96.656906 -296.612564)
		(end 96.656906 -296.584116)
		(width 0.1143)
		(layer "In2.Cu")
		(net "P3E_CPU1_P4_RX_DP<0>")
	)
	(segment
		(start 91.935808 -299.264578)
		(end 92.532708 -299.050964)
		(width 0.14224)
		(layer "In2.Cu")
		(net "P3E_CPU1_P4_RX_DP<0>")
	)
	(segment
		(start 93.017594 -298.731686)
		(end 93.193108 -298.814744)
		(width 0.14224)
		(layer "In2.Cu")
		(net "P3E_CPU1_P4_RX_DP<0>")
	)
	(segment
		(start 94.079568 -298.351702)
		(end 94.255082 -298.43476)
		(width 0.14224)
		(layer "In2.Cu")
		(net "P3E_CPU1_P4_RX_DP<0>")
	)
	(segment
		(start 84.740242 -301.839376)
		(end 88.039956 -300.65853)
		(width 0.14224)
		(layer "In2.Cu")
		(net "P3E_CPU1_P4_RX_DP<0>")
	)
	(segment
		(start 92.532708 -299.050964)
		(end 92.615766 -298.87545)
		(width 0.14224)
		(layer "In2.Cu")
		(net "P3E_CPU1_P4_RX_DP<0>")
	)
	(segment
		(start 27.519122 -167.632888)
		(end 13.26388 -187.992004)
		(width 0.14224)
		(layer "In2.Cu")
		(net "P3E_CPU1_P4_RX_DP<0>")
	)
	(segment
		(start 94.656656 -298.290996)
		(end 94.739714 -298.115482)
		(width 0.14224)
		(layer "In2.Cu")
		(net "P3E_CPU1_P4_RX_DP<0>")
	)
	(segment
		(start 69.414136 -313.349894)
		(end 71.422768 -312.518044)
		(width 0.14224)
		(layer "In2.Cu")
		(net "P3E_CPU1_P4_RX_DP<0>")
	)
	(segment
		(start 59.346084 -319.959482)
		(end 61.964062 -319.959482)
		(width 0.14224)
		(layer "In2.Cu")
		(net "P3E_CPU1_P4_RX_DP<0>")
	)
	(segment
		(start 88.039956 -300.658784)
		(end 88.12276 -300.48327)
		(width 0.14224)
		(layer "In2.Cu")
		(net "P3E_CPU1_P4_RX_DP<0>")
	)
	(segment
		(start 91.34729 -92.482416)
		(end 47.175674 -136.654032)
		(width 0.14224)
		(layer "In2.Cu")
		(net "P3E_CPU1_P4_RX_DP<0>")
	)
	(segment
		(start 35.691826 -161.910522)
		(end 27.519122 -167.632888)
		(width 0.14224)
		(layer "In2.Cu")
		(net "P3E_CPU1_P4_RX_DP<0>")
	)
	(segment
		(start 84.465922 -302.228504)
		(end 84.740242 -301.839376)
		(width 0.14224)
		(layer "In2.Cu")
		(net "P3E_CPU1_P4_RX_DP<0>")
	)
	(segment
		(start 93.67774 -298.495466)
		(end 94.079568 -298.351702)
		(width 0.14224)
		(layer "In2.Cu")
		(net "P3E_CPU1_P4_RX_DP<0>")
	)
	(segment
		(start 90.296746 -299.705268)
		(end 90.698574 -299.561504)
		(width 0.14224)
		(layer "In2.Cu")
		(net "P3E_CPU1_P4_RX_DP<0>")
	)
	(segment
		(start 15.507462 -314.186062)
		(end 16.190214 -318.715644)
		(width 0.14224)
		(layer "In2.Cu")
		(net "P3E_CPU1_P4_RX_DP<0>")
	)
	(segment
		(start 177.644806 -59.723528)
		(end 169.926 -62.92088)
		(width 0.14224)
		(layer "In2.Cu")
		(net "P3E_CPU1_P4_RX_DP<0>")
	)
	(segment
		(start 94.739714 -298.115482)
		(end 95.141796 -297.971718)
		(width 0.14224)
		(layer "In2.Cu")
		(net "P3E_CPU1_P4_RX_DP<0>")
	)
	(segment
		(start 88.12276 -300.48327)
		(end 88.524842 -300.339506)
		(width 0.14224)
		(layer "In2.Cu")
		(net "P3E_CPU1_P4_RX_DP<0>")
	)
	(segment
		(start 88.700102 -300.422564)
		(end 89.12606 -300.270164)
		(width 0.14224)
		(layer "In2.Cu")
		(net "P3E_CPU1_P4_RX_DP<0>")
	)
	(segment
		(start 90.874088 -299.644562)
		(end 91.275662 -299.500798)
		(width 0.14224)
		(layer "In2.Cu")
		(net "P3E_CPU1_P4_RX_DP<0>")
	)
	(segment
		(start 101.915468 -77.389482)
		(end 91.34729 -92.482416)
		(width 0.14224)
		(layer "In2.Cu")
		(net "P3E_CPU1_P4_RX_DP<0>")
	)
	(segment
		(start 89.208864 -300.094396)
		(end 89.610946 -299.950632)
		(width 0.14224)
		(layer "In2.Cu")
		(net "P3E_CPU1_P4_RX_DP<0>")
	)
	(segment
		(start 179.011834 -45.618146)
		(end 179.302664 -45.908976)
		(width 0.14224)
		(layer "In2.Cu")
		(net "P3E_CPU1_P4_RX_DP<0>")
	)
	(segment
		(start 96.656906 -296.87774)
		(end 96.656906 -296.612564)
		(width 0.14224)
		(layer "In2.Cu")
		(net "P3E_CPU1_P4_RX_DP<0>")
	)
	(segment
		(start 47.175674 -136.654032)
		(end 37.436806 -160.165796)
		(width 0.14224)
		(layer "In2.Cu")
		(net "P3E_CPU1_P4_RX_DP<0>")
	)
	(segment
		(start 91.358466 -299.325284)
		(end 91.760548 -299.18152)
		(width 0.14224)
		(layer "In2.Cu")
		(net "P3E_CPU1_P4_RX_DP<0>")
	)
	(segment
		(start 16.190214 -318.715644)
		(end 17.12595 -319.651634)
		(width 0.14224)
		(layer "In2.Cu")
		(net "P3E_CPU1_P4_RX_DP<0>")
	)
	(segment
		(start 97.338896 -294.336216)
		(end 97.040954 -294.336216)
		(width 0.1143)
		(layer "In2.Cu")
		(net "P3E_CPU1_P4_RX_DP<0>")
	)
	(segment
		(start 162.183318 -65.109598)
		(end 162.178746 -65.105026)
		(width 0.14224)
		(layer "In2.Cu")
		(net "P3E_CPU1_P4_RX_DP<0>")
	)
	(segment
		(start 155.041092 -64.290194)
		(end 117.108478 -68.387976)
		(width 0.14224)
		(layer "In2.Cu")
		(net "P3E_CPU1_P4_RX_DP<0>")
	)
	(segment
		(start 84.062062 -305.4858)
		(end 84.225892 -304.662586)
		(width 0.14224)
		(layer "In2.Cu")
		(net "P3E_CPU1_P4_RX_DP<0>")
	)
	(segment
		(start 13.26388 -187.992004)
		(end 12.599416 -191.760856)
		(width 0.14224)
		(layer "In2.Cu")
		(net "P3E_CPU1_P4_RX_DP<0>")
	)
	(segment
		(start 96.656906 -296.584116)
		(end 96.702626 -296.538396)
		(width 0.1143)
		(layer "In2.Cu")
		(net "P3E_CPU1_P4_RX_DP<0>")
	)
	(segment
		(start 183.240426 -59.723528)
		(end 177.644806 -59.723528)
		(width 0.14224)
		(layer "In2.Cu")
		(net "P3E_CPU1_P4_RX_DP<0>")
	)
	(segment
		(start 84.225892 -304.662586)
		(end 84.465922 -302.228504)
		(width 0.14224)
		(layer "In2.Cu")
		(net "P3E_CPU1_P4_RX_DP<0>")
	)
	(segment
		(start 89.12606 -300.270164)
		(end 89.208864 -300.094396)
		(width 0.14224)
		(layer "In2.Cu")
		(net "P3E_CPU1_P4_RX_DP<0>")
	)
	(segment
		(start 186.41568 -48.796448)
		(end 186.41568 -56.548274)
		(width 0.14224)
		(layer "In2.Cu")
		(net "P3E_CPU1_P4_RX_DP<0>")
	)
	(segment
		(start 117.108478 -68.387976)
		(end 113.984278 -68.938902)
		(width 0.14224)
		(layer "In2.Cu")
		(net "P3E_CPU1_P4_RX_DP<0>")
	)
	(segment
		(start 94.255082 -298.43476)
		(end 94.656656 -298.290996)
		(width 0.14224)
		(layer "In2.Cu")
		(net "P3E_CPU1_P4_RX_DP<0>")
	)
	(segment
		(start 88.524842 -300.339506)
		(end 88.700102 -300.422564)
		(width 0.14224)
		(layer "In2.Cu")
		(net "P3E_CPU1_P4_RX_DP<0>")
	)
	(segment
		(start 88.039956 -300.65853)
		(end 88.039956 -300.658784)
		(width 0.14224)
		(layer "In2.Cu")
		(net "P3E_CPU1_P4_RX_DP<0>")
	)
	(segment
		(start 113.984278 -68.938902)
		(end 101.915468 -77.389482)
		(width 0.14224)
		(layer "In2.Cu")
		(net "P3E_CPU1_P4_RX_DP<0>")
	)
	(segment
		(start 61.964062 -319.959482)
		(end 63.398908 -319.365122)
		(width 0.14224)
		(layer "In2.Cu")
		(net "P3E_CPU1_P4_RX_DP<0>")
	)
	(segment
		(start 89.786206 -300.03369)
		(end 90.213688 -299.880782)
		(width 0.14224)
		(layer "In2.Cu")
		(net "P3E_CPU1_P4_RX_DP<0>")
	)
	(segment
		(start 162.143948 -65.105026)
		(end 155.041092 -64.290194)
		(width 0.14224)
		(layer "In2.Cu")
		(net "P3E_CPU1_P4_RX_DP<0>")
	)
	(segment
		(start 17.12595 -319.651634)
		(end 59.346084 -319.959482)
		(width 0.14224)
		(layer "In2.Cu")
		(net "P3E_CPU1_P4_RX_DP<0>")
	)
	(segment
		(start 90.213688 -299.880782)
		(end 90.296746 -299.705268)
		(width 0.14224)
		(layer "In2.Cu")
		(net "P3E_CPU1_P4_RX_DP<0>")
	)
	(segment
		(start 91.275662 -299.500798)
		(end 91.358466 -299.325284)
		(width 0.14224)
		(layer "In2.Cu")
		(net "P3E_CPU1_P4_RX_DP<0>")
	)
	(segment
		(start 93.193108 -298.814744)
		(end 93.594682 -298.67098)
		(width 0.14224)
		(layer "In2.Cu")
		(net "P3E_CPU1_P4_RX_DP<0>")
	)
	(segment
		(start 166.464488 -64.35471)
		(end 162.183318 -65.109598)
		(width 0.14224)
		(layer "In2.Cu")
		(net "P3E_CPU1_P4_RX_DP<0>")
	)
	(segment
		(start 183.528208 -45.908976)
		(end 186.41568 -48.796448)
		(width 0.14224)
		(layer "In2.Cu")
		(net "P3E_CPU1_P4_RX_DP<0>")
	)
	(segment
		(start 91.760548 -299.18152)
		(end 91.935808 -299.264578)
		(width 0.14224)
		(layer "In2.Cu")
		(net "P3E_CPU1_P4_RX_DP<0>")
	)
	(segment
		(start 82.680302 -307.478684)
		(end 83.351624 -307.199792)
		(width 0.14224)
		(layer "In2.Cu")
		(net "P3E_CPU1_P4_RX_DP<0>")
	)
	(segment
		(start 95.317056 -298.054522)
		(end 95.570294 -297.964098)
		(width 0.14224)
		(layer "In2.Cu")
		(net "P3E_CPU1_P4_RX_DP<0>")
	)
	(segment
		(start 169.926 -62.92088)
		(end 166.464488 -64.35471)
		(width 0.14224)
		(layer "In2.Cu")
		(net "P3E_CPU1_P4_RX_DP<0>")
	)
	(segment
		(start 83.351624 -307.199792)
		(end 84.062062 -305.4858)
		(width 0.14224)
		(layer "In2.Cu")
		(net "P3E_CPU1_P4_RX_DP<0>")
	)
	(segment
		(start 93.594682 -298.67098)
		(end 93.67774 -298.495466)
		(width 0.14224)
		(layer "In2.Cu")
		(net "P3E_CPU1_P4_RX_DP<0>")
	)
	(segment
		(start 37.436806 -160.165796)
		(end 35.691826 -161.910522)
		(width 0.14224)
		(layer "In2.Cu")
		(net "P3E_CPU1_P4_RX_DP<0>")
	)
	(segment
		(start 89.610946 -299.950632)
		(end 89.786206 -300.03369)
		(width 0.14224)
		(layer "In2.Cu")
		(net "P3E_CPU1_P4_RX_DP<0>")
	)
	(segment
		(start 162.178746 -65.105026)
		(end 162.143948 -65.105026)
		(width 0.14224)
		(layer "In2.Cu")
		(net "P3E_CPU1_P4_RX_DP<0>")
	)
	(segment
		(start 96.702626 -296.538396)
		(end 96.702626 -295.846754)
		(width 0.1143)
		(layer "In2.Cu")
		(net "P3E_CPU1_P4_RX_DP<0>")
	)
	(segment
		(start 12.599416 -191.760856)
		(end 15.507462 -314.186062)
		(width 0.14224)
		(layer "In2.Cu")
		(net "P3E_CPU1_P4_RX_DP<0>")
	)
	(segment
		(start 97.189036 -294.681656)
		(end 97.258632 -294.641016)
		(width 0.1143)
		(layer "In2.Cu")
		(net "P3E_CPU1_P4_RX_DP<0>")
	)
	(arc
		(start 96.702626 -295.846754)
		(mid 96.744481 -295.59901)
		(end 96.865186 -295.378632)
		(width 0.1143)
		(layer "In2.Cu")
		(net "P3E_CPU1_P4_RX_DP<0>")
	)
	(arc
		(start 96.945704 -295.146222)
		(mid 97.010219 -294.884003)
		(end 97.189036 -294.681656)
		(width 0.1143)
		(layer "In2.Cu")
		(net "P3E_CPU1_P4_RX_DP<0>")
	)
	(arc
		(start 97.258632 -294.641016)
		(mid 97.356397 -294.53804)
		(end 97.408746 -294.406066)
		(width 0.1143)
		(layer "In2.Cu")
		(net "P3E_CPU1_P4_RX_DP<0>")
	)
	(arc
		(start 96.865186 -295.378632)
		(mid 96.925051 -295.269219)
		(end 96.945704 -295.146222)
		(width 0.1143)
		(layer "In2.Cu")
		(net "P3E_CPU1_P4_RX_DP<0>")
	)
	(segment
		(start 178.741324 -55.211218)
		(end 179.011834 -55.481728)
		(width 0.12954)
		(layer "F.Cu")
		(net "P3E_CPU1_P4_RX_DN<3>")
	)
	(segment
		(start 106.907838 -294.070278)
		(end 106.440986 -294.336216)
		(width 0.12954)
		(layer "F.Cu")
		(net "P3E_CPU1_P4_RX_DN<3>")
	)
	(segment
		(start 177.108358 -55.299864)
		(end 177.786538 -55.299864)
		(width 0.12954)
		(layer "F.Cu")
		(net "P3E_CPU1_P4_RX_DN<3>")
	)
	(segment
		(start 177.875184 -55.211218)
		(end 178.741324 -55.211218)
		(width 0.12954)
		(layer "F.Cu")
		(net "P3E_CPU1_P4_RX_DN<3>")
	)
	(segment
		(start 177.786538 -55.299864)
		(end 177.875184 -55.211218)
		(width 0.12954)
		(layer "F.Cu")
		(net "P3E_CPU1_P4_RX_DN<3>")
	)
	(segment
		(start 179.011834 -55.481728)
		(end 179.302664 -55.190898)
		(width 0.14224)
		(layer "In2.Cu")
		(net "P3E_CPU1_P4_RX_DN<3>")
	)
	(segment
		(start 161.06394 -59.096402)
		(end 159.354266 -60.050172)
		(width 0.14224)
		(layer "In2.Cu")
		(net "P3E_CPU1_P4_RX_DN<3>")
	)
	(segment
		(start 174.094394 -57.8104)
		(end 174.09414 -57.809892)
		(width 0.14224)
		(layer "In2.Cu")
		(net "P3E_CPU1_P4_RX_DN<3>")
	)
	(segment
		(start 44.425362 -134.830566)
		(end 34.68243 -158.351474)
		(width 0.14224)
		(layer "In2.Cu")
		(net "P3E_CPU1_P4_RX_DN<3>")
	)
	(segment
		(start 175.77689 -57.112408)
		(end 175.77689 -57.112662)
		(width 0.14224)
		(layer "In2.Cu")
		(net "P3E_CPU1_P4_RX_DN<3>")
	)
	(segment
		(start 34.68243 -158.351474)
		(end 33.368234 -159.665416)
		(width 0.14224)
		(layer "In2.Cu")
		(net "P3E_CPU1_P4_RX_DN<3>")
	)
	(segment
		(start 105.897934 -297.47972)
		(end 105.398824 -296.98061)
		(width 0.14224)
		(layer "In2.Cu")
		(net "P3E_CPU1_P4_RX_DN<3>")
	)
	(segment
		(start 175.13173 -57.380632)
		(end 175.131476 -57.37987)
		(width 0.14224)
		(layer "In2.Cu")
		(net "P3E_CPU1_P4_RX_DN<3>")
	)
	(segment
		(start 171.869608 -58.419238)
		(end 162.57905 -58.679842)
		(width 0.14224)
		(layer "In2.Cu")
		(net "P3E_CPU1_P4_RX_DN<3>")
	)
	(segment
		(start 105.897934 -300.118272)
		(end 105.897934 -297.47972)
		(width 0.14224)
		(layer "In2.Cu")
		(net "P3E_CPU1_P4_RX_DN<3>")
	)
	(segment
		(start 116.662708 -65.247012)
		(end 112.741456 -65.938146)
		(width 0.14224)
		(layer "In2.Cu")
		(net "P3E_CPU1_P4_RX_DN<3>")
	)
	(segment
		(start 71.149718 -316.084712)
		(end 71.149718 -316.084966)
		(width 0.14224)
		(layer "In2.Cu")
		(net "P3E_CPU1_P4_RX_DN<3>")
	)
	(segment
		(start 179.854606 -56.339994)
		(end 179.693824 -56.500776)
		(width 0.14224)
		(layer "In2.Cu")
		(net "P3E_CPU1_P4_RX_DN<3>")
	)
	(segment
		(start 89.113868 -90.143838)
		(end 44.425362 -134.830566)
		(width 0.14224)
		(layer "In2.Cu")
		(net "P3E_CPU1_P4_RX_DN<3>")
	)
	(segment
		(start 175.77689 -57.112662)
		(end 175.777398 -57.11317)
		(width 0.14224)
		(layer "In2.Cu")
		(net "P3E_CPU1_P4_RX_DN<3>")
	)
	(segment
		(start 179.712366 -55.190898)
		(end 179.854606 -55.333138)
		(width 0.14224)
		(layer "In2.Cu")
		(net "P3E_CPU1_P4_RX_DN<3>")
	)
	(segment
		(start 10.263124 -186.749436)
		(end 9.454134 -191.337946)
		(width 0.14224)
		(layer "In2.Cu")
		(net "P3E_CPU1_P4_RX_DN<3>")
	)
	(segment
		(start 105.398824 -296.98061)
		(end 105.398824 -296.612564)
		(width 0.14224)
		(layer "In2.Cu")
		(net "P3E_CPU1_P4_RX_DN<3>")
	)
	(segment
		(start 179.693824 -56.500776)
		(end 177.25263 -56.500776)
		(width 0.14224)
		(layer "In2.Cu")
		(net "P3E_CPU1_P4_RX_DN<3>")
	)
	(segment
		(start 175.205898 -57.201054)
		(end 175.13173 -57.380632)
		(width 0.14224)
		(layer "In2.Cu")
		(net "P3E_CPU1_P4_RX_DN<3>")
	)
	(segment
		(start 81.542636 -314.018676)
		(end 99.221036 -312.277252)
		(width 0.14224)
		(layer "In2.Cu")
		(net "P3E_CPU1_P4_RX_DN<3>")
	)
	(segment
		(start 179.854606 -55.333138)
		(end 179.854606 -56.339994)
		(width 0.14224)
		(layer "In2.Cu")
		(net "P3E_CPU1_P4_RX_DN<3>")
	)
	(segment
		(start 174.168562 -57.630822)
		(end 174.094394 -57.8104)
		(width 0.14224)
		(layer "In2.Cu")
		(net "P3E_CPU1_P4_RX_DN<3>")
	)
	(segment
		(start 65.28816 -321.94627)
		(end 71.149718 -316.084712)
		(width 0.14224)
		(layer "In2.Cu")
		(net "P3E_CPU1_P4_RX_DN<3>")
	)
	(segment
		(start 174.740062 -57.542684)
		(end 174.560738 -57.468516)
		(width 0.14224)
		(layer "In2.Cu")
		(net "P3E_CPU1_P4_RX_DN<3>")
	)
	(segment
		(start 105.398824 -296.584116)
		(end 105.353104 -296.538396)
		(width 0.1143)
		(layer "In2.Cu")
		(net "P3E_CPU1_P4_RX_DN<3>")
	)
	(segment
		(start 176.25949 -56.763666)
		(end 176.185322 -56.943244)
		(width 0.14224)
		(layer "In2.Cu")
		(net "P3E_CPU1_P4_RX_DN<3>")
	)
	(segment
		(start 159.354266 -60.050172)
		(end 156.907484 -60.899548)
		(width 0.14224)
		(layer "In2.Cu")
		(net "P3E_CPU1_P4_RX_DN<3>")
	)
	(segment
		(start 106.06024 -294.41902)
		(end 106.143044 -294.336216)
		(width 0.1143)
		(layer "In2.Cu")
		(net "P3E_CPU1_P4_RX_DN<3>")
	)
	(segment
		(start 33.368234 -159.665416)
		(end 25.241758 -165.355524)
		(width 0.14224)
		(layer "In2.Cu")
		(net "P3E_CPU1_P4_RX_DN<3>")
	)
	(segment
		(start 99.638866 -75.11288)
		(end 89.113868 -90.143838)
		(width 0.14224)
		(layer "In2.Cu")
		(net "P3E_CPU1_P4_RX_DN<3>")
	)
	(segment
		(start 101.238558 -311.441592)
		(end 101.898704 -310.781446)
		(width 0.14224)
		(layer "In2.Cu")
		(net "P3E_CPU1_P4_RX_DN<3>")
	)
	(segment
		(start 175.131476 -57.37987)
		(end 174.739808 -57.542176)
		(width 0.14224)
		(layer "In2.Cu")
		(net "P3E_CPU1_P4_RX_DN<3>")
	)
	(segment
		(start 9.454134 -191.337946)
		(end 12.368022 -314.028582)
		(width 0.14224)
		(layer "In2.Cu")
		(net "P3E_CPU1_P4_RX_DN<3>")
	)
	(segment
		(start 175.777398 -57.11317)
		(end 175.598074 -57.038748)
		(width 0.14224)
		(layer "In2.Cu")
		(net "P3E_CPU1_P4_RX_DN<3>")
	)
	(segment
		(start 177.25263 -56.500776)
		(end 176.830736 -56.675528)
		(width 0.14224)
		(layer "In2.Cu")
		(net "P3E_CPU1_P4_RX_DN<3>")
	)
	(segment
		(start 106.143044 -294.336216)
		(end 106.440986 -294.336216)
		(width 0.1143)
		(layer "In2.Cu")
		(net "P3E_CPU1_P4_RX_DN<3>")
	)
	(segment
		(start 174.09414 -57.809892)
		(end 174.093886 -57.809892)
		(width 0.14224)
		(layer "In2.Cu")
		(net "P3E_CPU1_P4_RX_DN<3>")
	)
	(segment
		(start 25.241758 -165.355524)
		(end 10.298938 -186.698382)
		(width 0.14224)
		(layer "In2.Cu")
		(net "P3E_CPU1_P4_RX_DN<3>")
	)
	(segment
		(start 105.353104 -296.538396)
		(end 105.353104 -295.656)
		(width 0.1143)
		(layer "In2.Cu")
		(net "P3E_CPU1_P4_RX_DN<3>")
	)
	(segment
		(start 176.185322 -56.943244)
		(end 175.77689 -57.112408)
		(width 0.14224)
		(layer "In2.Cu")
		(net "P3E_CPU1_P4_RX_DN<3>")
	)
	(segment
		(start 179.302664 -55.190898)
		(end 179.712366 -55.190898)
		(width 0.14224)
		(layer "In2.Cu")
		(net "P3E_CPU1_P4_RX_DN<3>")
	)
	(segment
		(start 12.368022 -314.028582)
		(end 13.297154 -320.185034)
		(width 0.14224)
		(layer "In2.Cu")
		(net "P3E_CPU1_P4_RX_DN<3>")
	)
	(segment
		(start 105.685844 -300.9646)
		(end 105.897934 -300.118272)
		(width 0.14224)
		(layer "In2.Cu")
		(net "P3E_CPU1_P4_RX_DN<3>")
	)
	(segment
		(start 105.780332 -294.825674)
		(end 105.783126 -294.82415)
		(width 0.1143)
		(layer "In2.Cu")
		(net "P3E_CPU1_P4_RX_DN<3>")
	)
	(segment
		(start 105.786174 -294.822372)
		(end 105.78846 -294.820848)
		(width 0.1143)
		(layer "In2.Cu")
		(net "P3E_CPU1_P4_RX_DN<3>")
	)
	(segment
		(start 174.560738 -57.468516)
		(end 174.168562 -57.630822)
		(width 0.14224)
		(layer "In2.Cu")
		(net "P3E_CPU1_P4_RX_DN<3>")
	)
	(segment
		(start 10.298938 -186.698382)
		(end 10.298684 -186.698382)
		(width 0.14224)
		(layer "In2.Cu")
		(net "P3E_CPU1_P4_RX_DN<3>")
	)
	(segment
		(start 105.398824 -296.612564)
		(end 105.398824 -296.584116)
		(width 0.1143)
		(layer "In2.Cu")
		(net "P3E_CPU1_P4_RX_DN<3>")
	)
	(segment
		(start 174.739808 -57.542176)
		(end 174.740062 -57.542684)
		(width 0.14224)
		(layer "In2.Cu")
		(net "P3E_CPU1_P4_RX_DN<3>")
	)
	(segment
		(start 172.623734 -58.419238)
		(end 171.869608 -58.419238)
		(width 0.14224)
		(layer "In2.Cu")
		(net "P3E_CPU1_P4_RX_DN<3>")
	)
	(segment
		(start 105.783888 -294.823642)
		(end 105.784904 -294.823134)
		(width 0.1143)
		(layer "In2.Cu")
		(net "P3E_CPU1_P4_RX_DN<3>")
	)
	(segment
		(start 175.598074 -57.038748)
		(end 175.205898 -57.201054)
		(width 0.14224)
		(layer "In2.Cu")
		(net "P3E_CPU1_P4_RX_DN<3>")
	)
	(segment
		(start 162.57905 -58.679842)
		(end 161.06394 -59.096402)
		(width 0.14224)
		(layer "In2.Cu")
		(net "P3E_CPU1_P4_RX_DN<3>")
	)
	(segment
		(start 156.907484 -60.899548)
		(end 116.662708 -65.247012)
		(width 0.14224)
		(layer "In2.Cu")
		(net "P3E_CPU1_P4_RX_DN<3>")
	)
	(segment
		(start 176.830736 -56.675528)
		(end 176.651412 -56.60136)
		(width 0.14224)
		(layer "In2.Cu")
		(net "P3E_CPU1_P4_RX_DN<3>")
	)
	(segment
		(start 176.651412 -56.60136)
		(end 176.25949 -56.763666)
		(width 0.14224)
		(layer "In2.Cu")
		(net "P3E_CPU1_P4_RX_DN<3>")
	)
	(segment
		(start 13.297154 -320.185034)
		(end 15.952724 -322.840604)
		(width 0.14224)
		(layer "In2.Cu")
		(net "P3E_CPU1_P4_RX_DN<3>")
	)
	(segment
		(start 105.353104 -295.656)
		(end 105.408222 -295.600882)
		(width 0.1143)
		(layer "In2.Cu")
		(net "P3E_CPU1_P4_RX_DN<3>")
	)
	(segment
		(start 15.952724 -322.840604)
		(end 59.33313 -323.156326)
		(width 0.14224)
		(layer "In2.Cu")
		(net "P3E_CPU1_P4_RX_DN<3>")
	)
	(segment
		(start 101.898704 -310.781446)
		(end 105.685844 -300.9646)
		(width 0.14224)
		(layer "In2.Cu")
		(net "P3E_CPU1_P4_RX_DN<3>")
	)
	(segment
		(start 112.741456 -65.938146)
		(end 99.638866 -75.11288)
		(width 0.14224)
		(layer "In2.Cu")
		(net "P3E_CPU1_P4_RX_DN<3>")
	)
	(segment
		(start 105.783126 -294.82415)
		(end 105.783888 -294.823642)
		(width 0.1143)
		(layer "In2.Cu")
		(net "P3E_CPU1_P4_RX_DN<3>")
	)
	(segment
		(start 10.298684 -186.698382)
		(end 10.263124 -186.749436)
		(width 0.14224)
		(layer "In2.Cu")
		(net "P3E_CPU1_P4_RX_DN<3>")
	)
	(segment
		(start 105.752138 -294.84193)
		(end 105.780332 -294.825674)
		(width 0.1143)
		(layer "In2.Cu")
		(net "P3E_CPU1_P4_RX_DN<3>")
	)
	(segment
		(start 174.093886 -57.809892)
		(end 172.623734 -58.419238)
		(width 0.14224)
		(layer "In2.Cu")
		(net "P3E_CPU1_P4_RX_DN<3>")
	)
	(segment
		(start 71.149718 -316.084966)
		(end 81.542636 -314.018676)
		(width 0.14224)
		(layer "In2.Cu")
		(net "P3E_CPU1_P4_RX_DN<3>")
	)
	(segment
		(start 99.221036 -312.277252)
		(end 101.238558 -311.441592)
		(width 0.14224)
		(layer "In2.Cu")
		(net "P3E_CPU1_P4_RX_DN<3>")
	)
	(segment
		(start 105.784904 -294.823134)
		(end 105.786174 -294.822372)
		(width 0.1143)
		(layer "In2.Cu")
		(net "P3E_CPU1_P4_RX_DN<3>")
	)
	(segment
		(start 62.366906 -323.156326)
		(end 65.28816 -321.94627)
		(width 0.14224)
		(layer "In2.Cu")
		(net "P3E_CPU1_P4_RX_DN<3>")
	)
	(segment
		(start 59.33313 -323.156326)
		(end 62.366906 -323.156326)
		(width 0.14224)
		(layer "In2.Cu")
		(net "P3E_CPU1_P4_RX_DN<3>")
	)
	(segment
		(start 105.78846 -294.820848)
		(end 105.823004 -294.800782)
		(width 0.1143)
		(layer "In2.Cu")
		(net "P3E_CPU1_P4_RX_DN<3>")
	)
	(arc
		(start 105.596182 -295.145968)
		(mid 105.637495 -294.975138)
		(end 105.752138 -294.84193)
		(width 0.1143)
		(layer "In2.Cu")
		(net "P3E_CPU1_P4_RX_DN<3>")
	)
	(arc
		(start 105.408222 -295.600882)
		(mid 105.547565 -295.392162)
		(end 105.596182 -295.145968)
		(width 0.1143)
		(layer "In2.Cu")
		(net "P3E_CPU1_P4_RX_DN<3>")
	)
	(arc
		(start 105.823004 -294.800782)
		(mid 105.974991 -294.644274)
		(end 106.05643 -294.44188)
		(width 0.1143)
		(layer "In2.Cu")
		(net "P3E_CPU1_P4_RX_DN<3>")
	)
	(arc
		(start 106.05643 -294.44188)
		(mid 106.058453 -294.43047)
		(end 106.06024 -294.41902)
		(width 0.1143)
		(layer "In2.Cu")
		(net "P3E_CPU1_P4_RX_DN<3>")
	)
	(segment
		(start 177.786538 -52.29987)
		(end 177.875184 -52.211224)
		(width 0.12954)
		(layer "F.Cu")
		(net "P3E_CPU1_P4_RX_DN<2>")
	)
	(segment
		(start 178.741324 -52.211224)
		(end 179.011834 -52.481734)
		(width 0.12954)
		(layer "F.Cu")
		(net "P3E_CPU1_P4_RX_DN<2>")
	)
	(segment
		(start 104.08793 -294.070278)
		(end 103.621078 -294.336216)
		(width 0.12954)
		(layer "F.Cu")
		(net "P3E_CPU1_P4_RX_DN<2>")
	)
	(segment
		(start 177.108358 -52.29987)
		(end 177.786538 -52.29987)
		(width 0.12954)
		(layer "F.Cu")
		(net "P3E_CPU1_P4_RX_DN<2>")
	)
	(segment
		(start 177.875184 -52.211224)
		(end 178.741324 -52.211224)
		(width 0.12954)
		(layer "F.Cu")
		(net "P3E_CPU1_P4_RX_DN<2>")
	)
	(segment
		(start 183.150002 -56.523128)
		(end 182.219854 -57.453276)
		(width 0.14224)
		(layer "In2.Cu")
		(net "P3E_CPU1_P4_RX_DN<2>")
	)
	(segment
		(start 102.502208 -297.94962)
		(end 102.502208 -295.996868)
		(width 0.1143)
		(layer "In2.Cu")
		(net "P3E_CPU1_P4_RX_DN<2>")
	)
	(segment
		(start 102.796848 -298.887896)
		(end 102.547928 -298.286932)
		(width 0.14224)
		(layer "In2.Cu")
		(net "P3E_CPU1_P4_RX_DN<2>")
	)
	(segment
		(start 35.46475 -158.903924)
		(end 33.884108 -160.484566)
		(width 0.14224)
		(layer "In2.Cu")
		(net "P3E_CPU1_P4_RX_DN<2>")
	)
	(segment
		(start 16.314928 -321.877182)
		(end 59.33694 -322.190364)
		(width 0.14224)
		(layer "In2.Cu")
		(net "P3E_CPU1_P4_RX_DN<2>")
	)
	(segment
		(start 183.814466 -53.941218)
		(end 183.951626 -54.078378)
		(width 0.14224)
		(layer "In2.Cu")
		(net "P3E_CPU1_P4_RX_DN<2>")
	)
	(segment
		(start 45.181012 -135.447024)
		(end 35.46475 -158.903924)
		(width 0.14224)
		(layer "In2.Cu")
		(net "P3E_CPU1_P4_RX_DN<2>")
	)
	(segment
		(start 179.302664 -52.190904)
		(end 183.186832 -52.190904)
		(width 0.14224)
		(layer "In2.Cu")
		(net "P3E_CPU1_P4_RX_DN<2>")
	)
	(segment
		(start 11.213338 -187.077096)
		(end 11.213084 -187.077096)
		(width 0.14224)
		(layer "In2.Cu")
		(net "P3E_CPU1_P4_RX_DN<2>")
	)
	(segment
		(start 183.644032 -56.029098)
		(end 183.45023 -56.029098)
		(width 0.14224)
		(layer "In2.Cu")
		(net "P3E_CPU1_P4_RX_DN<2>")
	)
	(segment
		(start 116.798598 -66.204084)
		(end 113.12017 -66.852546)
		(width 0.14224)
		(layer "In2.Cu")
		(net "P3E_CPU1_P4_RX_DN<2>")
	)
	(segment
		(start 102.547928 -297.99534)
		(end 102.502208 -297.94962)
		(width 0.1143)
		(layer "In2.Cu")
		(net "P3E_CPU1_P4_RX_DN<2>")
	)
	(segment
		(start 100.33254 -75.806554)
		(end 89.84488 -90.784172)
		(width 0.14224)
		(layer "In2.Cu")
		(net "P3E_CPU1_P4_RX_DN<2>")
	)
	(segment
		(start 64.692022 -321.176142)
		(end 70.631812 -315.236352)
		(width 0.14224)
		(layer "In2.Cu")
		(net "P3E_CPU1_P4_RX_DN<2>")
	)
	(segment
		(start 183.951626 -54.078378)
		(end 183.951626 -54.502558)
		(width 0.14224)
		(layer "In2.Cu")
		(net "P3E_CPU1_P4_RX_DN<2>")
	)
	(segment
		(start 162.234372 -62.723014)
		(end 155.525978 -62.02045)
		(width 0.14224)
		(layer "In2.Cu")
		(net "P3E_CPU1_P4_RX_DN<2>")
	)
	(segment
		(start 183.45023 -56.029098)
		(end 183.150002 -56.329326)
		(width 0.14224)
		(layer "In2.Cu")
		(net "P3E_CPU1_P4_RX_DN<2>")
	)
	(segment
		(start 11.213084 -187.077096)
		(end 11.177524 -187.12815)
		(width 0.14224)
		(layer "In2.Cu")
		(net "P3E_CPU1_P4_RX_DN<2>")
	)
	(segment
		(start 177.411634 -57.453276)
		(end 166.436548 -61.999114)
		(width 0.14224)
		(layer "In2.Cu")
		(net "P3E_CPU1_P4_RX_DN<2>")
	)
	(segment
		(start 183.951626 -52.955698)
		(end 183.951626 -53.379878)
		(width 0.14224)
		(layer "In2.Cu")
		(net "P3E_CPU1_P4_RX_DN<2>")
	)
	(segment
		(start 155.525978 -62.02045)
		(end 116.798598 -66.204084)
		(width 0.14224)
		(layer "In2.Cu")
		(net "P3E_CPU1_P4_RX_DN<2>")
	)
	(segment
		(start 10.422382 -191.411098)
		(end 13.339064 -314.210446)
		(width 0.14224)
		(layer "In2.Cu")
		(net "P3E_CPU1_P4_RX_DN<2>")
	)
	(segment
		(start 62.243462 -322.190364)
		(end 64.692022 -321.176142)
		(width 0.14224)
		(layer "In2.Cu")
		(net "P3E_CPU1_P4_RX_DN<2>")
	)
	(segment
		(start 102.547928 -298.023788)
		(end 102.547928 -297.99534)
		(width 0.1143)
		(layer "In2.Cu")
		(net "P3E_CPU1_P4_RX_DN<2>")
	)
	(segment
		(start 102.9335 -294.841422)
		(end 103.003096 -294.800782)
		(width 0.1143)
		(layer "In2.Cu")
		(net "P3E_CPU1_P4_RX_DN<2>")
	)
	(segment
		(start 89.84488 -90.784172)
		(end 45.181012 -135.447024)
		(width 0.14224)
		(layer "In2.Cu")
		(net "P3E_CPU1_P4_RX_DN<2>")
	)
	(segment
		(start 183.150002 -56.329326)
		(end 183.150002 -56.523128)
		(width 0.14224)
		(layer "In2.Cu")
		(net "P3E_CPU1_P4_RX_DN<2>")
	)
	(segment
		(start 95.329248 -309.678324)
		(end 102.796848 -299.610272)
		(width 0.14224)
		(layer "In2.Cu")
		(net "P3E_CPU1_P4_RX_DN<2>")
	)
	(segment
		(start 11.177524 -187.12815)
		(end 10.422382 -191.411098)
		(width 0.14224)
		(layer "In2.Cu")
		(net "P3E_CPU1_P4_RX_DN<2>")
	)
	(segment
		(start 103.323136 -294.336216)
		(end 103.621078 -294.336216)
		(width 0.1143)
		(layer "In2.Cu")
		(net "P3E_CPU1_P4_RX_DN<2>")
	)
	(segment
		(start 102.547928 -298.286932)
		(end 102.547928 -298.023788)
		(width 0.14224)
		(layer "In2.Cu")
		(net "P3E_CPU1_P4_RX_DN<2>")
	)
	(segment
		(start 183.951626 -53.379878)
		(end 183.814466 -53.517038)
		(width 0.14224)
		(layer "In2.Cu")
		(net "P3E_CPU1_P4_RX_DN<2>")
	)
	(segment
		(start 90.957146 -311.489598)
		(end 95.329248 -309.678324)
		(width 0.14224)
		(layer "In2.Cu")
		(net "P3E_CPU1_P4_RX_DN<2>")
	)
	(segment
		(start 113.12017 -66.852546)
		(end 100.33254 -75.806554)
		(width 0.14224)
		(layer "In2.Cu")
		(net "P3E_CPU1_P4_RX_DN<2>")
	)
	(segment
		(start 183.814466 -53.517038)
		(end 183.814466 -53.941218)
		(width 0.14224)
		(layer "In2.Cu")
		(net "P3E_CPU1_P4_RX_DN<2>")
	)
	(segment
		(start 25.935686 -166.049452)
		(end 11.213338 -187.077096)
		(width 0.14224)
		(layer "In2.Cu")
		(net "P3E_CPU1_P4_RX_DN<2>")
	)
	(segment
		(start 102.796848 -299.610272)
		(end 102.796848 -298.887896)
		(width 0.14224)
		(layer "In2.Cu")
		(net "P3E_CPU1_P4_RX_DN<2>")
	)
	(segment
		(start 183.951626 -55.721504)
		(end 183.644032 -56.029098)
		(width 0.14224)
		(layer "In2.Cu")
		(net "P3E_CPU1_P4_RX_DN<2>")
	)
	(segment
		(start 166.436548 -61.999114)
		(end 163.203636 -62.56909)
		(width 0.14224)
		(layer "In2.Cu")
		(net "P3E_CPU1_P4_RX_DN<2>")
	)
	(segment
		(start 103.240332 -294.41902)
		(end 103.323136 -294.336216)
		(width 0.1143)
		(layer "In2.Cu")
		(net "P3E_CPU1_P4_RX_DN<2>")
	)
	(segment
		(start 182.219854 -57.453276)
		(end 177.411634 -57.453276)
		(width 0.14224)
		(layer "In2.Cu")
		(net "P3E_CPU1_P4_RX_DN<2>")
	)
	(segment
		(start 183.814466 -55.063898)
		(end 183.951626 -55.201058)
		(width 0.14224)
		(layer "In2.Cu")
		(net "P3E_CPU1_P4_RX_DN<2>")
	)
	(segment
		(start 183.186832 -52.190904)
		(end 183.951626 -52.955698)
		(width 0.14224)
		(layer "In2.Cu")
		(net "P3E_CPU1_P4_RX_DN<2>")
	)
	(segment
		(start 13.339064 -314.210446)
		(end 14.172184 -319.734692)
		(width 0.14224)
		(layer "In2.Cu")
		(net "P3E_CPU1_P4_RX_DN<2>")
	)
	(segment
		(start 70.631812 -315.236352)
		(end 73.38187 -314.096908)
		(width 0.14224)
		(layer "In2.Cu")
		(net "P3E_CPU1_P4_RX_DN<2>")
	)
	(segment
		(start 14.172184 -319.734692)
		(end 16.314928 -321.877182)
		(width 0.14224)
		(layer "In2.Cu")
		(net "P3E_CPU1_P4_RX_DN<2>")
	)
	(segment
		(start 163.203636 -62.56909)
		(end 163.189666 -62.559438)
		(width 0.14224)
		(layer "In2.Cu")
		(net "P3E_CPU1_P4_RX_DN<2>")
	)
	(segment
		(start 183.951626 -54.502558)
		(end 183.814466 -54.639718)
		(width 0.14224)
		(layer "In2.Cu")
		(net "P3E_CPU1_P4_RX_DN<2>")
	)
	(segment
		(start 183.814466 -54.639718)
		(end 183.814466 -55.063898)
		(width 0.14224)
		(layer "In2.Cu")
		(net "P3E_CPU1_P4_RX_DN<2>")
	)
	(segment
		(start 183.951626 -55.201058)
		(end 183.951626 -55.721504)
		(width 0.14224)
		(layer "In2.Cu")
		(net "P3E_CPU1_P4_RX_DN<2>")
	)
	(segment
		(start 162.263074 -62.723014)
		(end 162.234372 -62.723014)
		(width 0.14224)
		(layer "In2.Cu")
		(net "P3E_CPU1_P4_RX_DN<2>")
	)
	(segment
		(start 59.33694 -322.190364)
		(end 62.243462 -322.190364)
		(width 0.14224)
		(layer "In2.Cu")
		(net "P3E_CPU1_P4_RX_DN<2>")
	)
	(segment
		(start 73.38187 -314.096908)
		(end 90.957146 -311.489598)
		(width 0.14224)
		(layer "In2.Cu")
		(net "P3E_CPU1_P4_RX_DN<2>")
	)
	(segment
		(start 163.189666 -62.559438)
		(end 162.263074 -62.723014)
		(width 0.14224)
		(layer "In2.Cu")
		(net "P3E_CPU1_P4_RX_DN<2>")
	)
	(segment
		(start 33.884108 -160.484566)
		(end 25.935686 -166.049452)
		(width 0.14224)
		(layer "In2.Cu")
		(net "P3E_CPU1_P4_RX_DN<2>")
	)
	(segment
		(start 179.011834 -52.481734)
		(end 179.302664 -52.190904)
		(width 0.14224)
		(layer "In2.Cu")
		(net "P3E_CPU1_P4_RX_DN<2>")
	)
	(arc
		(start 103.003096 -294.800782)
		(mid 103.155083 -294.644274)
		(end 103.236522 -294.44188)
		(width 0.1143)
		(layer "In2.Cu")
		(net "P3E_CPU1_P4_RX_DN<2>")
	)
	(arc
		(start 102.502208 -295.996868)
		(mid 102.545148 -295.723596)
		(end 102.669848 -295.476676)
		(width 0.1143)
		(layer "In2.Cu")
		(net "P3E_CPU1_P4_RX_DN<2>")
	)
	(arc
		(start 102.776528 -295.146222)
		(mid 102.818077 -294.9748)
		(end 102.9335 -294.841422)
		(width 0.1143)
		(layer "In2.Cu")
		(net "P3E_CPU1_P4_RX_DN<2>")
	)
	(arc
		(start 103.236522 -294.44188)
		(mid 103.238545 -294.43047)
		(end 103.240332 -294.41902)
		(width 0.1143)
		(layer "In2.Cu")
		(net "P3E_CPU1_P4_RX_DN<2>")
	)
	(arc
		(start 102.669848 -295.476676)
		(mid 102.749162 -295.319838)
		(end 102.776528 -295.146222)
		(width 0.1143)
		(layer "In2.Cu")
		(net "P3E_CPU1_P4_RX_DN<2>")
	)
	(segment
		(start 177.108358 -49.299876)
		(end 177.786538 -49.299876)
		(width 0.12954)
		(layer "F.Cu")
		(net "P3E_CPU1_P4_RX_DN<1>")
	)
	(segment
		(start 177.786538 -49.299876)
		(end 177.875184 -49.21123)
		(width 0.12954)
		(layer "F.Cu")
		(net "P3E_CPU1_P4_RX_DN<1>")
	)
	(segment
		(start 101.268022 -294.070278)
		(end 100.80117 -294.336216)
		(width 0.12954)
		(layer "F.Cu")
		(net "P3E_CPU1_P4_RX_DN<1>")
	)
	(segment
		(start 178.741324 -49.21123)
		(end 179.011834 -49.48174)
		(width 0.12954)
		(layer "F.Cu")
		(net "P3E_CPU1_P4_RX_DN<1>")
	)
	(segment
		(start 177.875184 -49.21123)
		(end 178.741324 -49.21123)
		(width 0.12954)
		(layer "F.Cu")
		(net "P3E_CPU1_P4_RX_DN<1>")
	)
	(segment
		(start 100.144072 -294.823642)
		(end 100.145088 -294.823134)
		(width 0.1143)
		(layer "In2.Cu")
		(net "P3E_CPU1_P4_RX_DN<1>")
	)
	(segment
		(start 166.698676 -62.900306)
		(end 162.153854 -63.701676)
		(width 0.14224)
		(layer "In2.Cu")
		(net "P3E_CPU1_P4_RX_DN<1>")
	)
	(segment
		(start 185.036206 -52.582826)
		(end 185.173366 -52.719986)
		(width 0.14224)
		(layer "In2.Cu")
		(net "P3E_CPU1_P4_RX_DN<1>")
	)
	(segment
		(start 99.764596 -297.989244)
		(end 99.764596 -297.960796)
		(width 0.1143)
		(layer "In2.Cu")
		(net "P3E_CPU1_P4_RX_DN<1>")
	)
	(segment
		(start 100.146358 -294.822372)
		(end 100.148644 -294.820848)
		(width 0.1143)
		(layer "In2.Cu")
		(net "P3E_CPU1_P4_RX_DN<1>")
	)
	(segment
		(start 70.076568 -314.442856)
		(end 73.389744 -313.069986)
		(width 0.14224)
		(layer "In2.Cu")
		(net "P3E_CPU1_P4_RX_DN<1>")
	)
	(segment
		(start 183.057038 -49.19091)
		(end 183.570118 -49.70399)
		(width 0.14224)
		(layer "In2.Cu")
		(net "P3E_CPU1_P4_RX_DN<1>")
	)
	(segment
		(start 73.389744 -313.069986)
		(end 81.715356 -311.413652)
		(width 0.14224)
		(layer "In2.Cu")
		(net "P3E_CPU1_P4_RX_DN<1>")
	)
	(segment
		(start 15.048738 -319.292224)
		(end 16.646144 -320.88963)
		(width 0.14224)
		(layer "In2.Cu")
		(net "P3E_CPU1_P4_RX_DN<1>")
	)
	(segment
		(start 113.508282 -67.789552)
		(end 101.043486 -76.5175)
		(width 0.14224)
		(layer "In2.Cu")
		(net "P3E_CPU1_P4_RX_DN<1>")
	)
	(segment
		(start 99.764596 -297.960796)
		(end 99.718876 -297.915076)
		(width 0.1143)
		(layer "In2.Cu")
		(net "P3E_CPU1_P4_RX_DN<1>")
	)
	(segment
		(start 155.39593 -63.0301)
		(end 116.93779 -67.184778)
		(width 0.14224)
		(layer "In2.Cu")
		(net "P3E_CPU1_P4_RX_DN<1>")
	)
	(segment
		(start 179.011834 -49.48174)
		(end 179.302664 -49.19091)
		(width 0.14224)
		(layer "In2.Cu")
		(net "P3E_CPU1_P4_RX_DN<1>")
	)
	(segment
		(start 100.112322 -294.84193)
		(end 100.140516 -294.825674)
		(width 0.1143)
		(layer "In2.Cu")
		(net "P3E_CPU1_P4_RX_DN<1>")
	)
	(segment
		(start 162.153854 -63.701676)
		(end 162.123374 -63.701676)
		(width 0.14224)
		(layer "In2.Cu")
		(net "P3E_CPU1_P4_RX_DN<1>")
	)
	(segment
		(start 26.64714 -166.760906)
		(end 12.11453 -187.516262)
		(width 0.14224)
		(layer "In2.Cu")
		(net "P3E_CPU1_P4_RX_DN<1>")
	)
	(segment
		(start 81.715356 -311.413144)
		(end 86.73719 -310.414416)
		(width 0.14224)
		(layer "In2.Cu")
		(net "P3E_CPU1_P4_RX_DN<1>")
	)
	(segment
		(start 177.54346 -58.408062)
		(end 166.698676 -62.900306)
		(width 0.14224)
		(layer "In2.Cu")
		(net "P3E_CPU1_P4_RX_DN<1>")
	)
	(segment
		(start 11.372596 -191.724026)
		(end 14.281912 -314.208922)
		(width 0.14224)
		(layer "In2.Cu")
		(net "P3E_CPU1_P4_RX_DN<1>")
	)
	(segment
		(start 183.570118 -49.70399)
		(end 183.570118 -49.898046)
		(width 0.14224)
		(layer "In2.Cu")
		(net "P3E_CPU1_P4_RX_DN<1>")
	)
	(segment
		(start 16.646144 -320.88963)
		(end 59.341004 -321.200526)
		(width 0.14224)
		(layer "In2.Cu")
		(net "P3E_CPU1_P4_RX_DN<1>")
	)
	(segment
		(start 96.042734 -302.098456)
		(end 99.764596 -298.376594)
		(width 0.14224)
		(layer "In2.Cu")
		(net "P3E_CPU1_P4_RX_DN<1>")
	)
	(segment
		(start 87.433912 -308.923182)
		(end 87.689944 -306.326286)
		(width 0.14224)
		(layer "In2.Cu")
		(net "P3E_CPU1_P4_RX_DN<1>")
	)
	(segment
		(start 185.036206 -52.158646)
		(end 185.036206 -52.582826)
		(width 0.14224)
		(layer "In2.Cu")
		(net "P3E_CPU1_P4_RX_DN<1>")
	)
	(segment
		(start 12.11453 -187.516262)
		(end 11.372596 -191.724026)
		(width 0.14224)
		(layer "In2.Cu")
		(net "P3E_CPU1_P4_RX_DN<1>")
	)
	(segment
		(start 184.364122 -50.497994)
		(end 184.364122 -50.69205)
		(width 0.14224)
		(layer "In2.Cu")
		(net "P3E_CPU1_P4_RX_DN<1>")
	)
	(segment
		(start 184.364122 -50.69205)
		(end 184.66435 -50.992278)
		(width 0.14224)
		(layer "In2.Cu")
		(net "P3E_CPU1_P4_RX_DN<1>")
	)
	(segment
		(start 36.269168 -159.528256)
		(end 34.617914 -161.17951)
		(width 0.14224)
		(layer "In2.Cu")
		(net "P3E_CPU1_P4_RX_DN<1>")
	)
	(segment
		(start 99.718876 -295.917112)
		(end 99.71913 -295.917366)
		(width 0.1143)
		(layer "In2.Cu")
		(net "P3E_CPU1_P4_RX_DN<1>")
	)
	(segment
		(start 183.570118 -49.898046)
		(end 183.870346 -50.198274)
		(width 0.14224)
		(layer "In2.Cu")
		(net "P3E_CPU1_P4_RX_DN<1>")
	)
	(segment
		(start 64.133222 -320.386202)
		(end 70.076568 -314.442856)
		(width 0.14224)
		(layer "In2.Cu")
		(net "P3E_CPU1_P4_RX_DN<1>")
	)
	(segment
		(start 185.173366 -52.021486)
		(end 185.036206 -52.158646)
		(width 0.14224)
		(layer "In2.Cu")
		(net "P3E_CPU1_P4_RX_DN<1>")
	)
	(segment
		(start 81.715356 -311.413652)
		(end 81.715356 -311.413144)
		(width 0.14224)
		(layer "In2.Cu")
		(net "P3E_CPU1_P4_RX_DN<1>")
	)
	(segment
		(start 100.145088 -294.823134)
		(end 100.146358 -294.822372)
		(width 0.1143)
		(layer "In2.Cu")
		(net "P3E_CPU1_P4_RX_DN<1>")
	)
	(segment
		(start 182.657496 -58.408062)
		(end 177.54346 -58.408062)
		(width 0.14224)
		(layer "In2.Cu")
		(net "P3E_CPU1_P4_RX_DN<1>")
	)
	(segment
		(start 90.619072 -91.405202)
		(end 46.00956 -136.013698)
		(width 0.14224)
		(layer "In2.Cu")
		(net "P3E_CPU1_P4_RX_DN<1>")
	)
	(segment
		(start 185.173366 -51.307238)
		(end 185.173366 -52.021486)
		(width 0.14224)
		(layer "In2.Cu")
		(net "P3E_CPU1_P4_RX_DN<1>")
	)
	(segment
		(start 99.718876 -297.915076)
		(end 99.718876 -295.917112)
		(width 0.1143)
		(layer "In2.Cu")
		(net "P3E_CPU1_P4_RX_DN<1>")
	)
	(segment
		(start 100.503228 -294.336216)
		(end 100.80117 -294.336216)
		(width 0.1143)
		(layer "In2.Cu")
		(net "P3E_CPU1_P4_RX_DN<1>")
	)
	(segment
		(start 185.173366 -55.892192)
		(end 182.657496 -58.408062)
		(width 0.14224)
		(layer "In2.Cu")
		(net "P3E_CPU1_P4_RX_DN<1>")
	)
	(segment
		(start 100.140516 -294.825674)
		(end 100.14331 -294.82415)
		(width 0.1143)
		(layer "In2.Cu")
		(net "P3E_CPU1_P4_RX_DN<1>")
	)
	(segment
		(start 100.148644 -294.820848)
		(end 100.183188 -294.800782)
		(width 0.1143)
		(layer "In2.Cu")
		(net "P3E_CPU1_P4_RX_DN<1>")
	)
	(segment
		(start 184.858406 -50.992278)
		(end 185.173366 -51.307238)
		(width 0.14224)
		(layer "In2.Cu")
		(net "P3E_CPU1_P4_RX_DN<1>")
	)
	(segment
		(start 46.00956 -136.013698)
		(end 36.269168 -159.528256)
		(width 0.14224)
		(layer "In2.Cu")
		(net "P3E_CPU1_P4_RX_DN<1>")
	)
	(segment
		(start 99.837494 -295.532556)
		(end 99.837748 -295.532556)
		(width 0.1143)
		(layer "In2.Cu")
		(net "P3E_CPU1_P4_RX_DN<1>")
	)
	(segment
		(start 88.11514 -305.531012)
		(end 92.070428 -302.887888)
		(width 0.14224)
		(layer "In2.Cu")
		(net "P3E_CPU1_P4_RX_DN<1>")
	)
	(segment
		(start 162.123374 -63.701676)
		(end 155.39593 -63.0301)
		(width 0.14224)
		(layer "In2.Cu")
		(net "P3E_CPU1_P4_RX_DN<1>")
	)
	(segment
		(start 184.064402 -50.198274)
		(end 184.364122 -50.497994)
		(width 0.14224)
		(layer "In2.Cu")
		(net "P3E_CPU1_P4_RX_DN<1>")
	)
	(segment
		(start 185.173366 -52.719986)
		(end 185.173366 -55.892192)
		(width 0.14224)
		(layer "In2.Cu")
		(net "P3E_CPU1_P4_RX_DN<1>")
	)
	(segment
		(start 86.73719 -310.414416)
		(end 87.236808 -309.914798)
		(width 0.14224)
		(layer "In2.Cu")
		(net "P3E_CPU1_P4_RX_DN<1>")
	)
	(segment
		(start 184.66435 -50.992278)
		(end 184.858406 -50.992278)
		(width 0.14224)
		(layer "In2.Cu")
		(net "P3E_CPU1_P4_RX_DN<1>")
	)
	(segment
		(start 183.870346 -50.198274)
		(end 184.064402 -50.198274)
		(width 0.14224)
		(layer "In2.Cu")
		(net "P3E_CPU1_P4_RX_DN<1>")
	)
	(segment
		(start 116.93779 -67.184778)
		(end 113.508282 -67.789552)
		(width 0.14224)
		(layer "In2.Cu")
		(net "P3E_CPU1_P4_RX_DN<1>")
	)
	(segment
		(start 179.302664 -49.19091)
		(end 183.057038 -49.19091)
		(width 0.14224)
		(layer "In2.Cu")
		(net "P3E_CPU1_P4_RX_DN<1>")
	)
	(segment
		(start 14.281912 -314.208922)
		(end 15.048738 -319.292224)
		(width 0.14224)
		(layer "In2.Cu")
		(net "P3E_CPU1_P4_RX_DN<1>")
	)
	(segment
		(start 62.167008 -321.200526)
		(end 64.133222 -320.386202)
		(width 0.14224)
		(layer "In2.Cu")
		(net "P3E_CPU1_P4_RX_DN<1>")
	)
	(segment
		(start 99.764596 -298.376594)
		(end 99.764596 -297.989244)
		(width 0.14224)
		(layer "In2.Cu")
		(net "P3E_CPU1_P4_RX_DN<1>")
	)
	(segment
		(start 87.689944 -306.326286)
		(end 88.11514 -305.531012)
		(width 0.14224)
		(layer "In2.Cu")
		(net "P3E_CPU1_P4_RX_DN<1>")
	)
	(segment
		(start 34.617914 -161.17951)
		(end 26.64714 -166.760906)
		(width 0.14224)
		(layer "In2.Cu")
		(net "P3E_CPU1_P4_RX_DN<1>")
	)
	(segment
		(start 100.420424 -294.41902)
		(end 100.503228 -294.336216)
		(width 0.1143)
		(layer "In2.Cu")
		(net "P3E_CPU1_P4_RX_DN<1>")
	)
	(segment
		(start 100.14331 -294.82415)
		(end 100.144072 -294.823642)
		(width 0.1143)
		(layer "In2.Cu")
		(net "P3E_CPU1_P4_RX_DN<1>")
	)
	(segment
		(start 59.341004 -321.200526)
		(end 62.167008 -321.200526)
		(width 0.14224)
		(layer "In2.Cu")
		(net "P3E_CPU1_P4_RX_DN<1>")
	)
	(segment
		(start 92.070428 -302.887888)
		(end 96.042734 -302.098456)
		(width 0.14224)
		(layer "In2.Cu")
		(net "P3E_CPU1_P4_RX_DN<1>")
	)
	(segment
		(start 101.043486 -76.5175)
		(end 90.619072 -91.405202)
		(width 0.14224)
		(layer "In2.Cu")
		(net "P3E_CPU1_P4_RX_DN<1>")
	)
	(segment
		(start 87.236808 -309.914798)
		(end 87.433912 -308.923182)
		(width 0.14224)
		(layer "In2.Cu")
		(net "P3E_CPU1_P4_RX_DN<1>")
	)
	(arc
		(start 99.956366 -295.145968)
		(mid 99.997679 -294.975138)
		(end 100.112322 -294.84193)
		(width 0.1143)
		(layer "In2.Cu")
		(net "P3E_CPU1_P4_RX_DN<1>")
	)
	(arc
		(start 99.837748 -295.532556)
		(mid 99.926175 -295.348202)
		(end 99.956366 -295.145968)
		(width 0.1143)
		(layer "In2.Cu")
		(net "P3E_CPU1_P4_RX_DN<1>")
	)
	(arc
		(start 100.416614 -294.44188)
		(mid 100.418637 -294.43047)
		(end 100.420424 -294.41902)
		(width 0.1143)
		(layer "In2.Cu")
		(net "P3E_CPU1_P4_RX_DN<1>")
	)
	(arc
		(start 100.183188 -294.800782)
		(mid 100.335175 -294.644274)
		(end 100.416614 -294.44188)
		(width 0.1143)
		(layer "In2.Cu")
		(net "P3E_CPU1_P4_RX_DN<1>")
	)
	(arc
		(start 99.71913 -295.917366)
		(mid 99.749357 -295.716056)
		(end 99.837494 -295.532556)
		(width 0.1143)
		(layer "In2.Cu")
		(net "P3E_CPU1_P4_RX_DN<1>")
	)
	(segment
		(start 98.44786 -294.070278)
		(end 97.981008 -294.336216)
		(width 0.12954)
		(layer "F.Cu")
		(net "P3E_CPU1_P4_RX_DN<0>")
	)
	(segment
		(start 177.786538 -46.299882)
		(end 177.875184 -46.211236)
		(width 0.12954)
		(layer "F.Cu")
		(net "P3E_CPU1_P4_RX_DN<0>")
	)
	(segment
		(start 177.875184 -46.211236)
		(end 178.741324 -46.211236)
		(width 0.12954)
		(layer "F.Cu")
		(net "P3E_CPU1_P4_RX_DN<0>")
	)
	(segment
		(start 178.741324 -46.211236)
		(end 179.011834 -46.481746)
		(width 0.12954)
		(layer "F.Cu")
		(net "P3E_CPU1_P4_RX_DN<0>")
	)
	(segment
		(start 177.108358 -46.299882)
		(end 177.786538 -46.299882)
		(width 0.12954)
		(layer "F.Cu")
		(net "P3E_CPU1_P4_RX_DN<0>")
	)
	(segment
		(start 185.99658 -50.708814)
		(end 186.13374 -50.845974)
		(width 0.14224)
		(layer "In2.Cu")
		(net "P3E_CPU1_P4_RX_DN<0>")
	)
	(segment
		(start 186.13374 -56.431434)
		(end 183.123586 -59.441588)
		(width 0.14224)
		(layer "In2.Cu")
		(net "P3E_CPU1_P4_RX_DN<0>")
	)
	(segment
		(start 84.505292 -304.703988)
		(end 84.739226 -302.330358)
		(width 0.14224)
		(layer "In2.Cu")
		(net "P3E_CPU1_P4_RX_DN<0>")
	)
	(segment
		(start 186.13374 -50.147474)
		(end 185.99658 -50.284634)
		(width 0.14224)
		(layer "In2.Cu")
		(net "P3E_CPU1_P4_RX_DN<0>")
	)
	(segment
		(start 97.683066 -294.336216)
		(end 97.981008 -294.336216)
		(width 0.1143)
		(layer "In2.Cu")
		(net "P3E_CPU1_P4_RX_DN<0>")
	)
	(segment
		(start 82.73669 -307.760624)
		(end 83.567524 -307.415438)
		(width 0.14224)
		(layer "In2.Cu")
		(net "P3E_CPU1_P4_RX_DN<0>")
	)
	(segment
		(start 113.873788 -68.671948)
		(end 101.71303 -77.187044)
		(width 0.14224)
		(layer "In2.Cu")
		(net "P3E_CPU1_P4_RX_DN<0>")
	)
	(segment
		(start 79.05115 -307.760624)
		(end 82.73669 -307.760624)
		(width 0.14224)
		(layer "In2.Cu")
		(net "P3E_CPU1_P4_RX_DN<0>")
	)
	(segment
		(start 12.996926 -187.881514)
		(end 12.316714 -191.73952)
		(width 0.14224)
		(layer "In2.Cu")
		(net "P3E_CPU1_P4_RX_DN<0>")
	)
	(segment
		(start 83.567524 -307.415438)
		(end 84.333334 -305.568096)
		(width 0.14224)
		(layer "In2.Cu")
		(net "P3E_CPU1_P4_RX_DN<0>")
	)
	(segment
		(start 91.130374 -92.300552)
		(end 46.93666 -136.494266)
		(width 0.14224)
		(layer "In2.Cu")
		(net "P3E_CPU1_P4_RX_DN<0>")
	)
	(segment
		(start 46.93666 -136.494266)
		(end 37.197792 -160.00603)
		(width 0.14224)
		(layer "In2.Cu")
		(net "P3E_CPU1_P4_RX_DN<0>")
	)
	(segment
		(start 97.600262 -294.41902)
		(end 97.683066 -294.336216)
		(width 0.1143)
		(layer "In2.Cu")
		(net "P3E_CPU1_P4_RX_DN<0>")
	)
	(segment
		(start 183.711088 -46.684692)
		(end 184.011316 -46.98492)
		(width 0.14224)
		(layer "In2.Cu")
		(net "P3E_CPU1_P4_RX_DN<0>")
	)
	(segment
		(start 84.333334 -305.568096)
		(end 84.505292 -304.703988)
		(width 0.14224)
		(layer "In2.Cu")
		(net "P3E_CPU1_P4_RX_DN<0>")
	)
	(segment
		(start 184.505092 -47.28464)
		(end 184.505092 -47.478696)
		(width 0.14224)
		(layer "In2.Cu")
		(net "P3E_CPU1_P4_RX_DN<0>")
	)
	(segment
		(start 184.999376 -47.778924)
		(end 186.13374 -48.913288)
		(width 0.14224)
		(layer "In2.Cu")
		(net "P3E_CPU1_P4_RX_DN<0>")
	)
	(segment
		(start 117.068854 -68.108576)
		(end 113.873788 -68.671948)
		(width 0.14224)
		(layer "In2.Cu")
		(net "P3E_CPU1_P4_RX_DN<0>")
	)
	(segment
		(start 96.938846 -296.612564)
		(end 96.938846 -296.584116)
		(width 0.1143)
		(layer "In2.Cu")
		(net "P3E_CPU1_P4_RX_DN<0>")
	)
	(segment
		(start 184.505092 -47.478696)
		(end 184.80532 -47.778924)
		(width 0.14224)
		(layer "In2.Cu")
		(net "P3E_CPU1_P4_RX_DN<0>")
	)
	(segment
		(start 177.588672 -59.441588)
		(end 166.384986 -64.082168)
		(width 0.14224)
		(layer "In2.Cu")
		(net "P3E_CPU1_P4_RX_DN<0>")
	)
	(segment
		(start 101.71303 -77.187044)
		(end 91.130374 -92.300552)
		(width 0.14224)
		(layer "In2.Cu")
		(net "P3E_CPU1_P4_RX_DN<0>")
	)
	(segment
		(start 69.573902 -313.588908)
		(end 71.556372 -312.76798)
		(width 0.14224)
		(layer "In2.Cu")
		(net "P3E_CPU1_P4_RX_DN<0>")
	)
	(segment
		(start 183.411368 -46.190916)
		(end 183.711088 -46.490636)
		(width 0.14224)
		(layer "In2.Cu")
		(net "P3E_CPU1_P4_RX_DN<0>")
	)
	(segment
		(start 155.042108 -64.006476)
		(end 117.068854 -68.108576)
		(width 0.14224)
		(layer "In2.Cu")
		(net "P3E_CPU1_P4_RX_DN<0>")
	)
	(segment
		(start 95.72498 -298.208446)
		(end 96.938846 -296.99458)
		(width 0.14224)
		(layer "In2.Cu")
		(net "P3E_CPU1_P4_RX_DN<0>")
	)
	(segment
		(start 27.316684 -167.43045)
		(end 12.996926 -187.881514)
		(width 0.14224)
		(layer "In2.Cu")
		(net "P3E_CPU1_P4_RX_DN<0>")
	)
	(segment
		(start 17.008348 -319.932812)
		(end 59.344814 -320.241422)
		(width 0.14224)
		(layer "In2.Cu")
		(net "P3E_CPU1_P4_RX_DN<0>")
	)
	(segment
		(start 185.99658 -50.284634)
		(end 185.99658 -50.708814)
		(width 0.14224)
		(layer "In2.Cu")
		(net "P3E_CPU1_P4_RX_DN<0>")
	)
	(segment
		(start 184.011316 -46.98492)
		(end 184.205372 -46.98492)
		(width 0.14224)
		(layer "In2.Cu")
		(net "P3E_CPU1_P4_RX_DN<0>")
	)
	(segment
		(start 183.123586 -59.441588)
		(end 177.588672 -59.441588)
		(width 0.14224)
		(layer "In2.Cu")
		(net "P3E_CPU1_P4_RX_DN<0>")
	)
	(segment
		(start 179.302664 -46.190916)
		(end 183.411368 -46.190916)
		(width 0.14224)
		(layer "In2.Cu")
		(net "P3E_CPU1_P4_RX_DN<0>")
	)
	(segment
		(start 71.556372 -312.76798)
		(end 79.05115 -307.760624)
		(width 0.14224)
		(layer "In2.Cu")
		(net "P3E_CPU1_P4_RX_DN<0>")
	)
	(segment
		(start 162.160204 -64.823086)
		(end 155.042108 -64.006476)
		(width 0.14224)
		(layer "In2.Cu")
		(net "P3E_CPU1_P4_RX_DN<0>")
	)
	(segment
		(start 12.316714 -191.73952)
		(end 15.225776 -314.210446)
		(width 0.14224)
		(layer "In2.Cu")
		(net "P3E_CPU1_P4_RX_DN<0>")
	)
	(segment
		(start 166.384986 -64.082168)
		(end 162.183318 -64.823086)
		(width 0.14224)
		(layer "In2.Cu")
		(net "P3E_CPU1_P4_RX_DN<0>")
	)
	(segment
		(start 15.225776 -314.210446)
		(end 15.925038 -318.849502)
		(width 0.14224)
		(layer "In2.Cu")
		(net "P3E_CPU1_P4_RX_DN<0>")
	)
	(segment
		(start 162.183318 -64.823086)
		(end 162.160204 -64.823086)
		(width 0.14224)
		(layer "In2.Cu")
		(net "P3E_CPU1_P4_RX_DN<0>")
	)
	(segment
		(start 184.80532 -47.778924)
		(end 184.999376 -47.778924)
		(width 0.14224)
		(layer "In2.Cu")
		(net "P3E_CPU1_P4_RX_DN<0>")
	)
	(segment
		(start 84.739226 -302.330358)
		(end 84.919312 -302.074834)
		(width 0.14224)
		(layer "In2.Cu")
		(net "P3E_CPU1_P4_RX_DN<0>")
	)
	(segment
		(start 96.938846 -296.99458)
		(end 96.938846 -296.612564)
		(width 0.14224)
		(layer "In2.Cu")
		(net "P3E_CPU1_P4_RX_DN<0>")
	)
	(segment
		(start 183.711088 -46.490636)
		(end 183.711088 -46.684692)
		(width 0.14224)
		(layer "In2.Cu")
		(net "P3E_CPU1_P4_RX_DN<0>")
	)
	(segment
		(start 35.509962 -161.693606)
		(end 27.316684 -167.43045)
		(width 0.14224)
		(layer "In2.Cu")
		(net "P3E_CPU1_P4_RX_DN<0>")
	)
	(segment
		(start 84.919312 -302.074834)
		(end 95.72498 -298.208446)
		(width 0.14224)
		(layer "In2.Cu")
		(net "P3E_CPU1_P4_RX_DN<0>")
	)
	(segment
		(start 186.13374 -50.845974)
		(end 186.13374 -56.431434)
		(width 0.14224)
		(layer "In2.Cu")
		(net "P3E_CPU1_P4_RX_DN<0>")
	)
	(segment
		(start 179.011834 -46.481746)
		(end 179.302664 -46.190916)
		(width 0.14224)
		(layer "In2.Cu")
		(net "P3E_CPU1_P4_RX_DN<0>")
	)
	(segment
		(start 62.020196 -320.241422)
		(end 63.558674 -319.604136)
		(width 0.14224)
		(layer "In2.Cu")
		(net "P3E_CPU1_P4_RX_DN<0>")
	)
	(segment
		(start 184.205372 -46.98492)
		(end 184.505092 -47.28464)
		(width 0.14224)
		(layer "In2.Cu")
		(net "P3E_CPU1_P4_RX_DN<0>")
	)
	(segment
		(start 96.938846 -296.584116)
		(end 96.893126 -296.538396)
		(width 0.1143)
		(layer "In2.Cu")
		(net "P3E_CPU1_P4_RX_DN<0>")
	)
	(segment
		(start 63.558674 -319.604136)
		(end 69.573902 -313.588908)
		(width 0.14224)
		(layer "In2.Cu")
		(net "P3E_CPU1_P4_RX_DN<0>")
	)
	(segment
		(start 15.925038 -318.849502)
		(end 17.008348 -319.932812)
		(width 0.14224)
		(layer "In2.Cu")
		(net "P3E_CPU1_P4_RX_DN<0>")
	)
	(segment
		(start 97.29343 -294.841422)
		(end 97.363026 -294.800782)
		(width 0.1143)
		(layer "In2.Cu")
		(net "P3E_CPU1_P4_RX_DN<0>")
	)
	(segment
		(start 59.344814 -320.241422)
		(end 62.020196 -320.241422)
		(width 0.14224)
		(layer "In2.Cu")
		(net "P3E_CPU1_P4_RX_DN<0>")
	)
	(segment
		(start 37.197792 -160.00603)
		(end 35.509962 -161.693606)
		(width 0.14224)
		(layer "In2.Cu")
		(net "P3E_CPU1_P4_RX_DN<0>")
	)
	(segment
		(start 186.13374 -48.913288)
		(end 186.13374 -50.147474)
		(width 0.14224)
		(layer "In2.Cu")
		(net "P3E_CPU1_P4_RX_DN<0>")
	)
	(segment
		(start 96.893126 -296.538396)
		(end 96.893126 -295.847008)
		(width 0.1143)
		(layer "In2.Cu")
		(net "P3E_CPU1_P4_RX_DN<0>")
	)
	(arc
		(start 96.893126 -295.847008)
		(mid 96.924403 -295.661606)
		(end 97.014792 -295.496742)
		(width 0.1143)
		(layer "In2.Cu")
		(net "P3E_CPU1_P4_RX_DN<0>")
	)
	(arc
		(start 97.363026 -294.800782)
		(mid 97.515013 -294.644274)
		(end 97.596452 -294.44188)
		(width 0.1143)
		(layer "In2.Cu")
		(net "P3E_CPU1_P4_RX_DN<0>")
	)
	(arc
		(start 97.136458 -295.146222)
		(mid 97.178007 -294.9748)
		(end 97.29343 -294.841422)
		(width 0.1143)
		(layer "In2.Cu")
		(net "P3E_CPU1_P4_RX_DN<0>")
	)
	(arc
		(start 97.596452 -294.44188)
		(mid 97.598475 -294.43047)
		(end 97.600262 -294.41902)
		(width 0.1143)
		(layer "In2.Cu")
		(net "P3E_CPU1_P4_RX_DN<0>")
	)
	(arc
		(start 97.014792 -295.496742)
		(mid 97.105198 -295.331749)
		(end 97.136458 -295.146222)
		(width 0.1143)
		(layer "In2.Cu")
		(net "P3E_CPU1_P4_RX_DN<0>")
	)
	(segment
		(start 240.718848 -58.561224)
		(end 241.959384 -64.79794)
		(width 0.12954)
		(layer "F.Cu")
		(net "P3E_CPU0_P4_TX_DP<3>")
	)
	(segment
		(start 239.419384 -58.32729)
		(end 239.715294 -58.03138)
		(width 0.12954)
		(layer "F.Cu")
		(net "P3E_CPU0_P4_TX_DP<3>")
	)
	(segment
		(start 245.781322 -137.855706)
		(end 247.031256 -147.926298)
		(width 0.12954)
		(layer "F.Cu")
		(net "P3E_CPU0_P4_TX_DP<3>")
	)
	(segment
		(start 254.586994 -193.436494)
		(end 255.191514 -194.041014)
		(width 0.12954)
		(layer "F.Cu")
		(net "P3E_CPU0_P4_TX_DP<3>")
	)
	(segment
		(start 354.847906 -292.450012)
		(end 354.381054 -292.71595)
		(width 0.12954)
		(layer "F.Cu")
		(net "P3E_CPU0_P4_TX_DP<3>")
	)
	(segment
		(start 239.92459 -58.03138)
		(end 240.46815 -58.256678)
		(width 0.12954)
		(layer "F.Cu")
		(net "P3E_CPU0_P4_TX_DP<3>")
	)
	(segment
		(start 247.031256 -147.926298)
		(end 252.764544 -183.36768)
		(width 0.12954)
		(layer "F.Cu")
		(net "P3E_CPU0_P4_TX_DP<3>")
	)
	(segment
		(start 240.65738 -58.445908)
		(end 240.718848 -58.561224)
		(width 0.12954)
		(layer "F.Cu")
		(net "P3E_CPU0_P4_TX_DP<3>")
	)
	(segment
		(start 254.29972 -192.856866)
		(end 254.586994 -193.436494)
		(width 0.12954)
		(layer "F.Cu")
		(net "P3E_CPU0_P4_TX_DP<3>")
	)
	(segment
		(start 255.671828 -194.041014)
		(end 255.927098 -194.296284)
		(width 0.12954)
		(layer "F.Cu")
		(net "P3E_CPU0_P4_TX_DP<3>")
	)
	(segment
		(start 240.46815 -58.256678)
		(end 240.65738 -58.445908)
		(width 0.12954)
		(layer "F.Cu")
		(net "P3E_CPU0_P4_TX_DP<3>")
	)
	(segment
		(start 239.715294 -58.03138)
		(end 239.92459 -58.03138)
		(width 0.12954)
		(layer "F.Cu")
		(net "P3E_CPU0_P4_TX_DP<3>")
	)
	(segment
		(start 252.764544 -183.36768)
		(end 254.29972 -192.856866)
		(width 0.12954)
		(layer "F.Cu")
		(net "P3E_CPU0_P4_TX_DP<3>")
	)
	(segment
		(start 241.959384 -64.79794)
		(end 245.781322 -137.855706)
		(width 0.12954)
		(layer "F.Cu")
		(net "P3E_CPU0_P4_TX_DP<3>")
	)
	(segment
		(start 255.191514 -194.041014)
		(end 255.671828 -194.041014)
		(width 0.12954)
		(layer "F.Cu")
		(net "P3E_CPU0_P4_TX_DP<3>")
	)
	(segment
		(start 350.353376 -309.043578)
		(end 350.116394 -309.398162)
		(width 0.14224)
		(layer "In2.Cu")
		(net "P3E_CPU0_P4_TX_DP<3>")
	)
	(segment
		(start 351.56394 -306.989988)
		(end 351.601024 -307.176678)
		(width 0.14224)
		(layer "In2.Cu")
		(net "P3E_CPU0_P4_TX_DP<3>")
	)
	(segment
		(start 350.940116 -307.923438)
		(end 350.9772 -308.110128)
		(width 0.14224)
		(layer "In2.Cu")
		(net "P3E_CPU0_P4_TX_DP<3>")
	)
	(segment
		(start 351.364042 -307.531262)
		(end 351.177352 -307.568346)
		(width 0.14224)
		(layer "In2.Cu")
		(net "P3E_CPU0_P4_TX_DP<3>")
	)
	(segment
		(start 354.678996 -292.71595)
		(end 354.7618 -292.798754)
		(width 0.1143)
		(layer "In2.Cu")
		(net "P3E_CPU0_P4_TX_DP<3>")
	)
	(segment
		(start 355.038152 -293.203376)
		(end 355.038914 -293.203884)
		(width 0.1143)
		(layer "In2.Cu")
		(net "P3E_CPU0_P4_TX_DP<3>")
	)
	(segment
		(start 355.069902 -293.830248)
		(end 355.038914 -293.848028)
		(width 0.1143)
		(layer "In2.Cu")
		(net "P3E_CPU0_P4_TX_DP<3>")
	)
	(segment
		(start 350.116394 -309.398162)
		(end 349.929704 -309.4355)
		(width 0.14224)
		(layer "In2.Cu")
		(net "P3E_CPU0_P4_TX_DP<3>")
	)
	(segment
		(start 355.038914 -293.848028)
		(end 355.038152 -293.848536)
		(width 0.1143)
		(layer "In2.Cu")
		(net "P3E_CPU0_P4_TX_DP<3>")
	)
	(segment
		(start 354.710746 -295.858692)
		(end 354.710746 -296.350944)
		(width 0.1143)
		(layer "In2.Cu")
		(net "P3E_CPU0_P4_TX_DP<3>")
	)
	(segment
		(start 355.63429 -301.140876)
		(end 351.987866 -306.597558)
		(width 0.14224)
		(layer "In2.Cu")
		(net "P3E_CPU0_P4_TX_DP<3>")
	)
	(segment
		(start 350.740218 -308.464712)
		(end 350.553528 -308.501796)
		(width 0.14224)
		(layer "In2.Cu")
		(net "P3E_CPU0_P4_TX_DP<3>")
	)
	(segment
		(start 350.553528 -308.501796)
		(end 350.316292 -308.856888)
		(width 0.14224)
		(layer "In2.Cu")
		(net "P3E_CPU0_P4_TX_DP<3>")
	)
	(segment
		(start 355.006656 -293.185088)
		(end 355.038152 -293.203376)
		(width 0.1143)
		(layer "In2.Cu")
		(net "P3E_CPU0_P4_TX_DP<3>")
	)
	(segment
		(start 351.601024 -307.176678)
		(end 351.364042 -307.531262)
		(width 0.14224)
		(layer "In2.Cu")
		(net "P3E_CPU0_P4_TX_DP<3>")
	)
	(segment
		(start 354.665026 -296.425112)
		(end 354.665026 -296.611802)
		(width 0.14224)
		(layer "In2.Cu")
		(net "P3E_CPU0_P4_TX_DP<3>")
	)
	(segment
		(start 354.999036 -293.180516)
		(end 355.005894 -293.18458)
		(width 0.1143)
		(layer "In2.Cu")
		(net "P3E_CPU0_P4_TX_DP<3>")
	)
	(segment
		(start 354.641404 -295.72839)
		(end 354.710746 -295.858692)
		(width 0.1143)
		(layer "In2.Cu")
		(net "P3E_CPU0_P4_TX_DP<3>")
	)
	(segment
		(start 349.02013 -310.939942)
		(end 348.443804 -310.939942)
		(width 0.14224)
		(layer "In2.Cu")
		(net "P3E_CPU0_P4_TX_DP<3>")
	)
	(segment
		(start 354.710746 -296.350944)
		(end 354.665026 -296.396664)
		(width 0.1143)
		(layer "In2.Cu")
		(net "P3E_CPU0_P4_TX_DP<3>")
	)
	(segment
		(start 355.041454 -293.205408)
		(end 355.044248 -293.206932)
		(width 0.1143)
		(layer "In2.Cu")
		(net "P3E_CPU0_P4_TX_DP<3>")
	)
	(segment
		(start 354.598732 -294.640762)
		(end 354.52939 -294.681148)
		(width 0.1143)
		(layer "In2.Cu")
		(net "P3E_CPU0_P4_TX_DP<3>")
	)
	(segment
		(start 354.665026 -296.611802)
		(end 355.63429 -297.581066)
		(width 0.14224)
		(layer "In2.Cu")
		(net "P3E_CPU0_P4_TX_DP<3>")
	)
	(segment
		(start 351.177352 -307.568346)
		(end 350.940116 -307.923438)
		(width 0.14224)
		(layer "In2.Cu")
		(net "P3E_CPU0_P4_TX_DP<3>")
	)
	(segment
		(start 349.692468 -309.790338)
		(end 349.729552 -309.977282)
		(width 0.14224)
		(layer "In2.Cu")
		(net "P3E_CPU0_P4_TX_DP<3>")
	)
	(segment
		(start 349.929704 -309.4355)
		(end 349.692468 -309.790338)
		(width 0.14224)
		(layer "In2.Cu")
		(net "P3E_CPU0_P4_TX_DP<3>")
	)
	(segment
		(start 351.987866 -306.597558)
		(end 351.801176 -306.634896)
		(width 0.14224)
		(layer "In2.Cu")
		(net "P3E_CPU0_P4_TX_DP<3>")
	)
	(segment
		(start 355.63429 -297.581066)
		(end 355.63429 -301.140876)
		(width 0.14224)
		(layer "In2.Cu")
		(net "P3E_CPU0_P4_TX_DP<3>")
	)
	(segment
		(start 355.037136 -293.849044)
		(end 354.999036 -293.871396)
		(width 0.1143)
		(layer "In2.Cu")
		(net "P3E_CPU0_P4_TX_DP<3>")
	)
	(segment
		(start 354.665026 -296.396664)
		(end 354.665026 -296.425112)
		(width 0.1143)
		(layer "In2.Cu")
		(net "P3E_CPU0_P4_TX_DP<3>")
	)
	(segment
		(start 351.801176 -306.634896)
		(end 351.56394 -306.989988)
		(width 0.14224)
		(layer "In2.Cu")
		(net "P3E_CPU0_P4_TX_DP<3>")
	)
	(segment
		(start 355.044248 -293.206932)
		(end 355.069902 -293.221664)
		(width 0.1143)
		(layer "In2.Cu")
		(net "P3E_CPU0_P4_TX_DP<3>")
	)
	(segment
		(start 355.038914 -293.203884)
		(end 355.041454 -293.205408)
		(width 0.1143)
		(layer "In2.Cu")
		(net "P3E_CPU0_P4_TX_DP<3>")
	)
	(segment
		(start 349.123254 -310.88457)
		(end 349.02013 -310.939942)
		(width 0.14224)
		(layer "In2.Cu")
		(net "P3E_CPU0_P4_TX_DP<3>")
	)
	(segment
		(start 354.381054 -292.71595)
		(end 354.678996 -292.71595)
		(width 0.1143)
		(layer "In2.Cu")
		(net "P3E_CPU0_P4_TX_DP<3>")
	)
	(segment
		(start 350.316292 -308.856888)
		(end 350.353376 -309.043578)
		(width 0.14224)
		(layer "In2.Cu")
		(net "P3E_CPU0_P4_TX_DP<3>")
	)
	(segment
		(start 349.729552 -309.977282)
		(end 349.123254 -310.88457)
		(width 0.14224)
		(layer "In2.Cu")
		(net "P3E_CPU0_P4_TX_DP<3>")
	)
	(segment
		(start 355.038152 -293.848536)
		(end 355.037136 -293.849044)
		(width 0.1143)
		(layer "In2.Cu")
		(net "P3E_CPU0_P4_TX_DP<3>")
	)
	(segment
		(start 355.005894 -293.18458)
		(end 355.006656 -293.185088)
		(width 0.1143)
		(layer "In2.Cu")
		(net "P3E_CPU0_P4_TX_DP<3>")
	)
	(segment
		(start 348.443804 -310.939942)
		(end 348.15399 -310.650128)
		(width 0.14224)
		(layer "In2.Cu")
		(net "P3E_CPU0_P4_TX_DP<3>")
	)
	(segment
		(start 350.9772 -308.110128)
		(end 350.740218 -308.464712)
		(width 0.14224)
		(layer "In2.Cu")
		(net "P3E_CPU0_P4_TX_DP<3>")
	)
	(segment
		(start 354.484686 -295.595548)
		(end 354.641404 -295.72839)
		(width 0.1143)
		(layer "In2.Cu")
		(net "P3E_CPU0_P4_TX_DP<3>")
	)
	(arc
		(start 355.069902 -293.221664)
		(mid 355.22583 -293.525956)
		(end 355.069902 -293.830248)
		(width 0.1143)
		(layer "In2.Cu")
		(net "P3E_CPU0_P4_TX_DP<3>")
	)
	(arc
		(start 354.52939 -294.681148)
		(mid 354.281456 -295.127368)
		(end 354.484686 -295.595548)
		(width 0.1143)
		(layer "In2.Cu")
		(net "P3E_CPU0_P4_TX_DP<3>")
	)
	(arc
		(start 354.755704 -294.335962)
		(mid 354.714155 -294.507384)
		(end 354.598732 -294.640762)
		(width 0.1143)
		(layer "In2.Cu")
		(net "P3E_CPU0_P4_TX_DP<3>")
	)
	(arc
		(start 354.7618 -292.798754)
		(mid 354.84083 -293.014237)
		(end 354.999036 -293.180516)
		(width 0.1143)
		(layer "In2.Cu")
		(net "P3E_CPU0_P4_TX_DP<3>")
	)
	(arc
		(start 354.999036 -293.871396)
		(mid 354.820223 -294.073746)
		(end 354.755704 -294.335962)
		(width 0.1143)
		(layer "In2.Cu")
		(net "P3E_CPU0_P4_TX_DP<3>")
	)
	(segment
		(start 251.271532 -202.700382)
		(end 251.134372 -202.563222)
		(width 0.14224)
		(layer "In15.Cu")
		(net "P3E_CPU0_P4_TX_DP<3>")
	)
	(segment
		(start 253.70917 -195.35902)
		(end 254.865378 -194.311524)
		(width 0.14224)
		(layer "In15.Cu")
		(net "P3E_CPU0_P4_TX_DP<3>")
	)
	(segment
		(start 251.271532 -209.466942)
		(end 251.134372 -209.329782)
		(width 0.14224)
		(layer "In15.Cu")
		(net "P3E_CPU0_P4_TX_DP<3>")
	)
	(segment
		(start 263.220962 -322.388992)
		(end 262.548624 -322.108576)
		(width 0.14224)
		(layer "In15.Cu")
		(net "P3E_CPU0_P4_TX_DP<3>")
	)
	(segment
		(start 259.644896 -315.689488)
		(end 258.6736 -286.94126)
		(width 0.14224)
		(layer "In15.Cu")
		(net "P3E_CPU0_P4_TX_DP<3>")
	)
	(segment
		(start 251.134372 -207.074262)
		(end 251.134372 -206.647542)
		(width 0.14224)
		(layer "In15.Cu")
		(net "P3E_CPU0_P4_TX_DP<3>")
	)
	(segment
		(start 255.44399 -194.005454)
		(end 255.636268 -194.005454)
		(width 0.14224)
		(layer "In15.Cu")
		(net "P3E_CPU0_P4_TX_DP<3>")
	)
	(segment
		(start 251.134372 -209.329782)
		(end 251.134372 -208.903062)
		(width 0.14224)
		(layer "In15.Cu")
		(net "P3E_CPU0_P4_TX_DP<3>")
	)
	(segment
		(start 255.222756 -194.072764)
		(end 255.44399 -194.005454)
		(width 0.14224)
		(layer "In15.Cu")
		(net "P3E_CPU0_P4_TX_DP<3>")
	)
	(segment
		(start 251.134372 -205.519782)
		(end 251.271532 -205.382622)
		(width 0.14224)
		(layer "In15.Cu")
		(net "P3E_CPU0_P4_TX_DP<3>")
	)
	(segment
		(start 318.394588 -316.381384)
		(end 313.153552 -321.62242)
		(width 0.14224)
		(layer "In15.Cu")
		(net "P3E_CPU0_P4_TX_DP<3>")
	)
	(segment
		(start 346.69857 -310.940958)
		(end 342.600788 -312.638186)
		(width 0.14224)
		(layer "In15.Cu")
		(net "P3E_CPU0_P4_TX_DP<3>")
	)
	(segment
		(start 251.134372 -203.264262)
		(end 251.271532 -203.127102)
		(width 0.14224)
		(layer "In15.Cu")
		(net "P3E_CPU0_P4_TX_DP<3>")
	)
	(segment
		(start 330.171552 -313.897264)
		(end 320.606166 -315.45022)
		(width 0.14224)
		(layer "In15.Cu")
		(net "P3E_CPU0_P4_TX_DP<3>")
	)
	(segment
		(start 251.271532 -208.339182)
		(end 251.134372 -208.202022)
		(width 0.14224)
		(layer "In15.Cu")
		(net "P3E_CPU0_P4_TX_DP<3>")
	)
	(segment
		(start 251.271532 -206.083662)
		(end 251.134372 -205.946502)
		(width 0.14224)
		(layer "In15.Cu")
		(net "P3E_CPU0_P4_TX_DP<3>")
	)
	(segment
		(start 264.271252 -322.60159)
		(end 263.220962 -322.388992)
		(width 0.14224)
		(layer "In15.Cu")
		(net "P3E_CPU0_P4_TX_DP<3>")
	)
	(segment
		(start 251.271532 -207.211422)
		(end 251.134372 -207.074262)
		(width 0.14224)
		(layer "In15.Cu")
		(net "P3E_CPU0_P4_TX_DP<3>")
	)
	(segment
		(start 251.134372 -218.932252)
		(end 251.134372 -210.030822)
		(width 0.14224)
		(layer "In15.Cu")
		(net "P3E_CPU0_P4_TX_DP<3>")
	)
	(segment
		(start 251.134372 -210.030822)
		(end 251.271532 -209.893662)
		(width 0.14224)
		(layer "In15.Cu")
		(net "P3E_CPU0_P4_TX_DP<3>")
	)
	(segment
		(start 251.271532 -205.382622)
		(end 251.271532 -204.955902)
		(width 0.14224)
		(layer "In15.Cu")
		(net "P3E_CPU0_P4_TX_DP<3>")
	)
	(segment
		(start 251.271532 -204.955902)
		(end 251.134372 -204.818742)
		(width 0.14224)
		(layer "In15.Cu")
		(net "P3E_CPU0_P4_TX_DP<3>")
	)
	(segment
		(start 260.544818 -319.682876)
		(end 259.644896 -315.689488)
		(width 0.14224)
		(layer "In15.Cu")
		(net "P3E_CPU0_P4_TX_DP<3>")
	)
	(segment
		(start 251.134372 -204.818742)
		(end 251.134372 -204.392022)
		(width 0.14224)
		(layer "In15.Cu")
		(net "P3E_CPU0_P4_TX_DP<3>")
	)
	(segment
		(start 251.134372 -201.008742)
		(end 252.729492 -196.552566)
		(width 0.14224)
		(layer "In15.Cu")
		(net "P3E_CPU0_P4_TX_DP<3>")
	)
	(segment
		(start 251.271532 -209.893662)
		(end 251.271532 -209.466942)
		(width 0.14224)
		(layer "In15.Cu")
		(net "P3E_CPU0_P4_TX_DP<3>")
	)
	(segment
		(start 251.134372 -204.392022)
		(end 251.271532 -204.254862)
		(width 0.14224)
		(layer "In15.Cu")
		(net "P3E_CPU0_P4_TX_DP<3>")
	)
	(segment
		(start 255.636268 -194.005454)
		(end 255.927098 -194.296284)
		(width 0.14224)
		(layer "In15.Cu")
		(net "P3E_CPU0_P4_TX_DP<3>")
	)
	(segment
		(start 313.153552 -321.62242)
		(end 311.19445 -322.433442)
		(width 0.14224)
		(layer "In15.Cu")
		(net "P3E_CPU0_P4_TX_DP<3>")
	)
	(segment
		(start 251.134372 -202.136502)
		(end 251.271532 -201.999342)
		(width 0.14224)
		(layer "In15.Cu")
		(net "P3E_CPU0_P4_TX_DP<3>")
	)
	(segment
		(start 251.271532 -201.999342)
		(end 251.271532 -201.572622)
		(width 0.14224)
		(layer "In15.Cu")
		(net "P3E_CPU0_P4_TX_DP<3>")
	)
	(segment
		(start 251.134372 -201.435462)
		(end 251.134372 -201.008742)
		(width 0.14224)
		(layer "In15.Cu")
		(net "P3E_CPU0_P4_TX_DP<3>")
	)
	(segment
		(start 251.134372 -206.647542)
		(end 251.271532 -206.510382)
		(width 0.14224)
		(layer "In15.Cu")
		(net "P3E_CPU0_P4_TX_DP<3>")
	)
	(segment
		(start 251.271532 -203.127102)
		(end 251.271532 -202.700382)
		(width 0.14224)
		(layer "In15.Cu")
		(net "P3E_CPU0_P4_TX_DP<3>")
	)
	(segment
		(start 251.134372 -208.903062)
		(end 251.271532 -208.765902)
		(width 0.14224)
		(layer "In15.Cu")
		(net "P3E_CPU0_P4_TX_DP<3>")
	)
	(segment
		(start 347.86316 -310.940958)
		(end 346.69857 -310.940958)
		(width 0.14224)
		(layer "In15.Cu")
		(net "P3E_CPU0_P4_TX_DP<3>")
	)
	(segment
		(start 309.367174 -322.798948)
		(end 264.271252 -322.60159)
		(width 0.14224)
		(layer "In15.Cu")
		(net "P3E_CPU0_P4_TX_DP<3>")
	)
	(segment
		(start 251.271532 -201.572622)
		(end 251.134372 -201.435462)
		(width 0.14224)
		(layer "In15.Cu")
		(net "P3E_CPU0_P4_TX_DP<3>")
	)
	(segment
		(start 252.729492 -196.552566)
		(end 253.70917 -195.35902)
		(width 0.14224)
		(layer "In15.Cu")
		(net "P3E_CPU0_P4_TX_DP<3>")
	)
	(segment
		(start 251.134372 -202.563222)
		(end 251.134372 -202.136502)
		(width 0.14224)
		(layer "In15.Cu")
		(net "P3E_CPU0_P4_TX_DP<3>")
	)
	(segment
		(start 251.271532 -208.765902)
		(end 251.271532 -208.339182)
		(width 0.14224)
		(layer "In15.Cu")
		(net "P3E_CPU0_P4_TX_DP<3>")
	)
	(segment
		(start 311.19445 -322.433442)
		(end 309.367174 -322.798948)
		(width 0.14224)
		(layer "In15.Cu")
		(net "P3E_CPU0_P4_TX_DP<3>")
	)
	(segment
		(start 261.11708 -321.000882)
		(end 260.544818 -319.682876)
		(width 0.14224)
		(layer "In15.Cu")
		(net "P3E_CPU0_P4_TX_DP<3>")
	)
	(segment
		(start 251.271532 -206.510382)
		(end 251.271532 -206.083662)
		(width 0.14224)
		(layer "In15.Cu")
		(net "P3E_CPU0_P4_TX_DP<3>")
	)
	(segment
		(start 342.600788 -312.638186)
		(end 330.171552 -313.897264)
		(width 0.14224)
		(layer "In15.Cu")
		(net "P3E_CPU0_P4_TX_DP<3>")
	)
	(segment
		(start 251.271532 -207.638142)
		(end 251.271532 -207.211422)
		(width 0.14224)
		(layer "In15.Cu")
		(net "P3E_CPU0_P4_TX_DP<3>")
	)
	(segment
		(start 251.271532 -204.254862)
		(end 251.271532 -203.828142)
		(width 0.14224)
		(layer "In15.Cu")
		(net "P3E_CPU0_P4_TX_DP<3>")
	)
	(segment
		(start 262.548624 -322.108576)
		(end 261.568692 -321.452494)
		(width 0.14224)
		(layer "In15.Cu")
		(net "P3E_CPU0_P4_TX_DP<3>")
	)
	(segment
		(start 251.134372 -207.775302)
		(end 251.271532 -207.638142)
		(width 0.14224)
		(layer "In15.Cu")
		(net "P3E_CPU0_P4_TX_DP<3>")
	)
	(segment
		(start 251.134372 -205.946502)
		(end 251.134372 -205.519782)
		(width 0.14224)
		(layer "In15.Cu")
		(net "P3E_CPU0_P4_TX_DP<3>")
	)
	(segment
		(start 348.15399 -310.650128)
		(end 347.86316 -310.940958)
		(width 0.14224)
		(layer "In15.Cu")
		(net "P3E_CPU0_P4_TX_DP<3>")
	)
	(segment
		(start 251.271532 -203.828142)
		(end 251.134372 -203.690982)
		(width 0.14224)
		(layer "In15.Cu")
		(net "P3E_CPU0_P4_TX_DP<3>")
	)
	(segment
		(start 261.568692 -321.452494)
		(end 261.11708 -321.000882)
		(width 0.14224)
		(layer "In15.Cu")
		(net "P3E_CPU0_P4_TX_DP<3>")
	)
	(segment
		(start 258.6736 -286.94126)
		(end 251.134372 -218.932252)
		(width 0.14224)
		(layer "In15.Cu")
		(net "P3E_CPU0_P4_TX_DP<3>")
	)
	(segment
		(start 251.134372 -208.202022)
		(end 251.134372 -207.775302)
		(width 0.14224)
		(layer "In15.Cu")
		(net "P3E_CPU0_P4_TX_DP<3>")
	)
	(segment
		(start 319.243964 -315.872876)
		(end 318.394588 -316.381384)
		(width 0.14224)
		(layer "In15.Cu")
		(net "P3E_CPU0_P4_TX_DP<3>")
	)
	(segment
		(start 254.865378 -194.311524)
		(end 255.222756 -194.072764)
		(width 0.14224)
		(layer "In15.Cu")
		(net "P3E_CPU0_P4_TX_DP<3>")
	)
	(segment
		(start 320.606166 -315.45022)
		(end 319.243964 -315.872876)
		(width 0.14224)
		(layer "In15.Cu")
		(net "P3E_CPU0_P4_TX_DP<3>")
	)
	(segment
		(start 251.134372 -203.690982)
		(end 251.134372 -203.264262)
		(width 0.14224)
		(layer "In15.Cu")
		(net "P3E_CPU0_P4_TX_DP<3>")
	)
	(segment
		(start 242.969034 -62.930024)
		(end 246.864378 -137.381488)
		(width 0.12954)
		(layer "F.Cu")
		(net "P3E_CPU0_P4_TX_DP<2>")
	)
	(segment
		(start 257.505454 -189.77356)
		(end 257.505454 -195.904358)
		(width 0.12954)
		(layer "F.Cu")
		(net "P3E_CPU0_P4_TX_DP<2>")
	)
	(segment
		(start 241.417094 -55.908702)
		(end 241.737896 -55.908702)
		(width 0.12954)
		(layer "F.Cu")
		(net "P3E_CPU0_P4_TX_DP<2>")
	)
	(segment
		(start 241.737896 -55.908702)
		(end 242.007136 -56.177942)
		(width 0.12954)
		(layer "F.Cu")
		(net "P3E_CPU0_P4_TX_DP<2>")
	)
	(segment
		(start 248.20372 -147.30222)
		(end 256.102612 -183.36768)
		(width 0.12954)
		(layer "F.Cu")
		(net "P3E_CPU0_P4_TX_DP<2>")
	)
	(segment
		(start 352.027998 -292.450012)
		(end 351.561146 -292.71595)
		(width 0.12954)
		(layer "F.Cu")
		(net "P3E_CPU0_P4_TX_DP<2>")
	)
	(segment
		(start 256.201418 -196.7992)
		(end 255.927098 -197.07352)
		(width 0.12954)
		(layer "F.Cu")
		(net "P3E_CPU0_P4_TX_DP<2>")
	)
	(segment
		(start 241.121184 -55.612792)
		(end 241.417094 -55.908702)
		(width 0.12954)
		(layer "F.Cu")
		(net "P3E_CPU0_P4_TX_DP<2>")
	)
	(segment
		(start 256.898648 -196.679058)
		(end 256.60858 -196.7992)
		(width 0.12954)
		(layer "F.Cu")
		(net "P3E_CPU0_P4_TX_DP<2>")
	)
	(segment
		(start 242.969034 -58.500518)
		(end 242.969034 -62.930024)
		(width 0.12954)
		(layer "F.Cu")
		(net "P3E_CPU0_P4_TX_DP<2>")
	)
	(segment
		(start 257.386582 -196.191124)
		(end 256.898648 -196.679058)
		(width 0.12954)
		(layer "F.Cu")
		(net "P3E_CPU0_P4_TX_DP<2>")
	)
	(segment
		(start 242.007136 -56.177942)
		(end 242.969034 -58.500518)
		(width 0.12954)
		(layer "F.Cu")
		(net "P3E_CPU0_P4_TX_DP<2>")
	)
	(segment
		(start 256.102612 -183.36768)
		(end 257.505454 -189.77356)
		(width 0.12954)
		(layer "F.Cu")
		(net "P3E_CPU0_P4_TX_DP<2>")
	)
	(segment
		(start 257.505454 -195.904358)
		(end 257.386582 -196.191124)
		(width 0.12954)
		(layer "F.Cu")
		(net "P3E_CPU0_P4_TX_DP<2>")
	)
	(segment
		(start 256.60858 -196.7992)
		(end 256.201418 -196.7992)
		(width 0.12954)
		(layer "F.Cu")
		(net "P3E_CPU0_P4_TX_DP<2>")
	)
	(segment
		(start 246.864378 -137.381488)
		(end 248.20372 -147.30222)
		(width 0.12954)
		(layer "F.Cu")
		(net "P3E_CPU0_P4_TX_DP<2>")
	)
	(segment
		(start 352.220276 -294.824404)
		(end 352.22434 -294.826944)
		(width 0.1143)
		(layer "In2.Cu")
		(net "P3E_CPU0_P4_TX_DP<2>")
	)
	(segment
		(start 352.179128 -293.180516)
		(end 352.185986 -293.18458)
		(width 0.1143)
		(layer "In2.Cu")
		(net "P3E_CPU0_P4_TX_DP<2>")
	)
	(segment
		(start 351.633536 -297.42765)
		(end 351.633536 -297.852338)
		(width 0.14224)
		(layer "In2.Cu")
		(net "P3E_CPU0_P4_TX_DP<2>")
	)
	(segment
		(start 352.218244 -294.823388)
		(end 352.220276 -294.824404)
		(width 0.1143)
		(layer "In2.Cu")
		(net "P3E_CPU0_P4_TX_DP<2>")
	)
	(segment
		(start 352.186748 -294.8051)
		(end 352.218244 -294.823388)
		(width 0.1143)
		(layer "In2.Cu")
		(net "P3E_CPU0_P4_TX_DP<2>")
	)
	(segment
		(start 351.974658 -300.931326)
		(end 351.328228 -301.898812)
		(width 0.14224)
		(layer "In2.Cu")
		(net "P3E_CPU0_P4_TX_DP<2>")
	)
	(segment
		(start 348.948756 -304.88128)
		(end 348.694248 -305.22418)
		(width 0.14224)
		(layer "In2.Cu")
		(net "P3E_CPU0_P4_TX_DP<2>")
	)
	(segment
		(start 345.533472 -308.730396)
		(end 345.398852 -308.595776)
		(width 0.14224)
		(layer "In2.Cu")
		(net "P3E_CPU0_P4_TX_DP<2>")
	)
	(segment
		(start 345.968828 -308.730396)
		(end 345.533472 -308.730396)
		(width 0.14224)
		(layer "In2.Cu")
		(net "P3E_CPU0_P4_TX_DP<2>")
	)
	(segment
		(start 352.219006 -293.203884)
		(end 352.249994 -293.221664)
		(width 0.1143)
		(layer "In2.Cu")
		(net "P3E_CPU0_P4_TX_DP<2>")
	)
	(segment
		(start 352.217228 -293.849044)
		(end 352.21545 -293.85006)
		(width 0.1143)
		(layer "In2.Cu")
		(net "P3E_CPU0_P4_TX_DP<2>")
	)
	(segment
		(start 348.032578 -306.342034)
		(end 347.769434 -306.696872)
		(width 0.14224)
		(layer "In2.Cu")
		(net "P3E_CPU0_P4_TX_DP<2>")
	)
	(segment
		(start 351.859088 -292.71595)
		(end 351.941892 -292.798754)
		(width 0.1143)
		(layer "In2.Cu")
		(net "P3E_CPU0_P4_TX_DP<2>")
	)
	(segment
		(start 352.219006 -293.848028)
		(end 352.218244 -293.848536)
		(width 0.1143)
		(layer "In2.Cu")
		(net "P3E_CPU0_P4_TX_DP<2>")
	)
	(segment
		(start 352.40595 -295.14165)
		(end 352.40595 -295.720262)
		(width 0.1143)
		(layer "In2.Cu")
		(net "P3E_CPU0_P4_TX_DP<2>")
	)
	(segment
		(start 347.354398 -307.25618)
		(end 347.100398 -307.598826)
		(width 0.14224)
		(layer "In2.Cu")
		(net "P3E_CPU0_P4_TX_DP<2>")
	)
	(segment
		(start 352.186748 -293.185088)
		(end 352.218244 -293.203376)
		(width 0.1143)
		(layer "In2.Cu")
		(net "P3E_CPU0_P4_TX_DP<2>")
	)
	(segment
		(start 344.837512 -308.730396)
		(end 342.190832 -308.730396)
		(width 0.14224)
		(layer "In2.Cu")
		(net "P3E_CPU0_P4_TX_DP<2>")
	)
	(segment
		(start 344.972132 -308.595776)
		(end 344.837512 -308.730396)
		(width 0.14224)
		(layer "In2.Cu")
		(net "P3E_CPU0_P4_TX_DP<2>")
	)
	(segment
		(start 348.447614 -305.782726)
		(end 348.259146 -305.810666)
		(width 0.14224)
		(layer "In2.Cu")
		(net "P3E_CPU0_P4_TX_DP<2>")
	)
	(segment
		(start 352.20783 -293.854378)
		(end 352.20656 -293.85514)
		(width 0.1143)
		(layer "In2.Cu")
		(net "P3E_CPU0_P4_TX_DP<2>")
	)
	(segment
		(start 352.40595 -295.720262)
		(end 351.679256 -296.446956)
		(width 0.1143)
		(layer "In2.Cu")
		(net "P3E_CPU0_P4_TX_DP<2>")
	)
	(segment
		(start 352.21545 -293.85006)
		(end 352.214434 -293.850568)
		(width 0.1143)
		(layer "In2.Cu")
		(net "P3E_CPU0_P4_TX_DP<2>")
	)
	(segment
		(start 351.974658 -298.19346)
		(end 351.974658 -300.931326)
		(width 0.14224)
		(layer "In2.Cu")
		(net "P3E_CPU0_P4_TX_DP<2>")
	)
	(segment
		(start 348.004638 -306.153566)
		(end 348.032578 -306.342034)
		(width 0.14224)
		(layer "In2.Cu")
		(net "P3E_CPU0_P4_TX_DP<2>")
	)
	(segment
		(start 349.13697 -304.85334)
		(end 348.948756 -304.88128)
		(width 0.14224)
		(layer "In2.Cu")
		(net "P3E_CPU0_P4_TX_DP<2>")
	)
	(segment
		(start 352.22434 -294.826944)
		(end 352.224594 -294.826944)
		(width 0.1143)
		(layer "In2.Cu")
		(net "P3E_CPU0_P4_TX_DP<2>")
	)
	(segment
		(start 352.185986 -294.804592)
		(end 352.186748 -294.8051)
		(width 0.1143)
		(layer "In2.Cu")
		(net "P3E_CPU0_P4_TX_DP<2>")
	)
	(segment
		(start 352.249994 -293.221664)
		(end 352.265234 -293.232586)
		(width 0.1143)
		(layer "In2.Cu")
		(net "P3E_CPU0_P4_TX_DP<2>")
	)
	(segment
		(start 352.218244 -293.203376)
		(end 352.219006 -293.203884)
		(width 0.1143)
		(layer "In2.Cu")
		(net "P3E_CPU0_P4_TX_DP<2>")
	)
	(segment
		(start 351.679256 -296.446956)
		(end 351.679256 -297.353482)
		(width 0.1143)
		(layer "In2.Cu")
		(net "P3E_CPU0_P4_TX_DP<2>")
	)
	(segment
		(start 352.21164 -293.852092)
		(end 352.209354 -293.853362)
		(width 0.1143)
		(layer "In2.Cu")
		(net "P3E_CPU0_P4_TX_DP<2>")
	)
	(segment
		(start 352.214434 -293.850568)
		(end 352.21164 -293.852092)
		(width 0.1143)
		(layer "In2.Cu")
		(net "P3E_CPU0_P4_TX_DP<2>")
	)
	(segment
		(start 352.185986 -293.18458)
		(end 352.186748 -293.185088)
		(width 0.1143)
		(layer "In2.Cu")
		(net "P3E_CPU0_P4_TX_DP<2>")
	)
	(segment
		(start 352.218244 -293.848536)
		(end 352.217228 -293.849044)
		(width 0.1143)
		(layer "In2.Cu")
		(net "P3E_CPU0_P4_TX_DP<2>")
	)
	(segment
		(start 351.561146 -292.71595)
		(end 351.859088 -292.71595)
		(width 0.1143)
		(layer "In2.Cu")
		(net "P3E_CPU0_P4_TX_DP<2>")
	)
	(segment
		(start 347.326458 -307.067966)
		(end 347.354398 -307.25618)
		(width 0.14224)
		(layer "In2.Cu")
		(net "P3E_CPU0_P4_TX_DP<2>")
	)
	(segment
		(start 347.580966 -306.724812)
		(end 347.326458 -307.067966)
		(width 0.14224)
		(layer "In2.Cu")
		(net "P3E_CPU0_P4_TX_DP<2>")
	)
	(segment
		(start 352.20656 -293.85514)
		(end 352.179128 -293.871396)
		(width 0.1143)
		(layer "In2.Cu")
		(net "P3E_CPU0_P4_TX_DP<2>")
	)
	(segment
		(start 348.259146 -305.810666)
		(end 348.004638 -306.153566)
		(width 0.14224)
		(layer "In2.Cu")
		(net "P3E_CPU0_P4_TX_DP<2>")
	)
	(segment
		(start 351.633536 -297.852338)
		(end 351.974658 -298.19346)
		(width 0.14224)
		(layer "In2.Cu")
		(net "P3E_CPU0_P4_TX_DP<2>")
	)
	(segment
		(start 352.265234 -293.819326)
		(end 352.249994 -293.830248)
		(width 0.1143)
		(layer "In2.Cu")
		(net "P3E_CPU0_P4_TX_DP<2>")
	)
	(segment
		(start 348.721934 -305.412902)
		(end 348.44736 -305.782726)
		(width 0.14224)
		(layer "In2.Cu")
		(net "P3E_CPU0_P4_TX_DP<2>")
	)
	(segment
		(start 348.694248 -305.22418)
		(end 348.722188 -305.412648)
		(width 0.14224)
		(layer "In2.Cu")
		(net "P3E_CPU0_P4_TX_DP<2>")
	)
	(segment
		(start 345.398852 -308.595776)
		(end 344.972132 -308.595776)
		(width 0.14224)
		(layer "In2.Cu")
		(net "P3E_CPU0_P4_TX_DP<2>")
	)
	(segment
		(start 351.679256 -297.353482)
		(end 351.633536 -297.399202)
		(width 0.1143)
		(layer "In2.Cu")
		(net "P3E_CPU0_P4_TX_DP<2>")
	)
	(segment
		(start 348.44736 -305.782726)
		(end 348.447614 -305.782726)
		(width 0.14224)
		(layer "In2.Cu")
		(net "P3E_CPU0_P4_TX_DP<2>")
	)
	(segment
		(start 351.328228 -301.898812)
		(end 349.13697 -304.85334)
		(width 0.14224)
		(layer "In2.Cu")
		(net "P3E_CPU0_P4_TX_DP<2>")
	)
	(segment
		(start 348.722188 -305.412648)
		(end 348.721934 -305.412902)
		(width 0.14224)
		(layer "In2.Cu")
		(net "P3E_CPU0_P4_TX_DP<2>")
	)
	(segment
		(start 342.190832 -308.730396)
		(end 341.900002 -308.439566)
		(width 0.14224)
		(layer "In2.Cu")
		(net "P3E_CPU0_P4_TX_DP<2>")
	)
	(segment
		(start 352.179128 -294.800528)
		(end 352.185986 -294.804592)
		(width 0.1143)
		(layer "In2.Cu")
		(net "P3E_CPU0_P4_TX_DP<2>")
	)
	(segment
		(start 351.633536 -297.399202)
		(end 351.633536 -297.42765)
		(width 0.1143)
		(layer "In2.Cu")
		(net "P3E_CPU0_P4_TX_DP<2>")
	)
	(segment
		(start 347.769434 -306.696872)
		(end 347.580966 -306.724812)
		(width 0.14224)
		(layer "In2.Cu")
		(net "P3E_CPU0_P4_TX_DP<2>")
	)
	(segment
		(start 352.209354 -293.853362)
		(end 352.20783 -293.854378)
		(width 0.1143)
		(layer "In2.Cu")
		(net "P3E_CPU0_P4_TX_DP<2>")
	)
	(segment
		(start 352.405696 -295.141904)
		(end 352.40595 -295.14165)
		(width 0.1143)
		(layer "In2.Cu")
		(net "P3E_CPU0_P4_TX_DP<2>")
	)
	(segment
		(start 347.100398 -307.598826)
		(end 345.968828 -308.730396)
		(width 0.14224)
		(layer "In2.Cu")
		(net "P3E_CPU0_P4_TX_DP<2>")
	)
	(segment
		(start 352.249994 -293.830248)
		(end 352.219006 -293.848028)
		(width 0.1143)
		(layer "In2.Cu")
		(net "P3E_CPU0_P4_TX_DP<2>")
	)
	(arc
		(start 352.265234 -293.232586)
		(mid 352.415571 -293.525956)
		(end 352.265234 -293.819326)
		(width 0.1143)
		(layer "In2.Cu")
		(net "P3E_CPU0_P4_TX_DP<2>")
	)
	(arc
		(start 351.941892 -292.798754)
		(mid 351.94368 -292.810203)
		(end 351.945702 -292.821614)
		(width 0.1143)
		(layer "In2.Cu")
		(net "P3E_CPU0_P4_TX_DP<2>")
	)
	(arc
		(start 352.224594 -294.826944)
		(mid 352.357254 -294.960212)
		(end 352.405696 -295.141904)
		(width 0.1143)
		(layer "In2.Cu")
		(net "P3E_CPU0_P4_TX_DP<2>")
	)
	(arc
		(start 351.945702 -292.821614)
		(mid 352.027135 -293.024012)
		(end 352.179128 -293.180516)
		(width 0.1143)
		(layer "In2.Cu")
		(net "P3E_CPU0_P4_TX_DP<2>")
	)
	(arc
		(start 352.179128 -293.871396)
		(mid 351.935801 -294.335962)
		(end 352.179128 -294.800528)
		(width 0.1143)
		(layer "In2.Cu")
		(net "P3E_CPU0_P4_TX_DP<2>")
	)
	(segment
		(start 261.594854 -319.704466)
		(end 261.489952 -319.354454)
		(width 0.14224)
		(layer "In15.Cu")
		(net "P3E_CPU0_P4_TX_DP<2>")
	)
	(segment
		(start 255.340358 -246.575072)
		(end 254.154686 -234.53852)
		(width 0.14224)
		(layer "In15.Cu")
		(net "P3E_CPU0_P4_TX_DP<2>")
	)
	(segment
		(start 252.53188 -203.535026)
		(end 252.53188 -203.108306)
		(width 0.14224)
		(layer "In15.Cu")
		(net "P3E_CPU0_P4_TX_DP<2>")
	)
	(segment
		(start 252.53188 -205.790546)
		(end 252.53188 -205.363826)
		(width 0.14224)
		(layer "In15.Cu")
		(net "P3E_CPU0_P4_TX_DP<2>")
	)
	(segment
		(start 252.53188 -210.301586)
		(end 252.53188 -209.874866)
		(width 0.14224)
		(layer "In15.Cu")
		(net "P3E_CPU0_P4_TX_DP<2>")
	)
	(segment
		(start 252.53188 -209.173826)
		(end 252.53188 -208.747106)
		(width 0.14224)
		(layer "In15.Cu")
		(net "P3E_CPU0_P4_TX_DP<2>")
	)
	(segment
		(start 330.335382 -311.72531)
		(end 330.335128 -311.72531)
		(width 0.14224)
		(layer "In15.Cu")
		(net "P3E_CPU0_P4_TX_DP<2>")
	)
	(segment
		(start 252.53188 -201.980546)
		(end 252.39472 -201.843386)
		(width 0.14224)
		(layer "In15.Cu")
		(net "P3E_CPU0_P4_TX_DP<2>")
	)
	(segment
		(start 252.39472 -210.438746)
		(end 252.53188 -210.301586)
		(width 0.14224)
		(layer "In15.Cu")
		(net "P3E_CPU0_P4_TX_DP<2>")
	)
	(segment
		(start 330.335128 -311.72531)
		(end 327.959212 -312.258456)
		(width 0.14224)
		(layer "In15.Cu")
		(net "P3E_CPU0_P4_TX_DP<2>")
	)
	(segment
		(start 254.914146 -196.951854)
		(end 255.322578 -196.78269)
		(width 0.14224)
		(layer "In15.Cu")
		(net "P3E_CPU0_P4_TX_DP<2>")
	)
	(segment
		(start 322.607178 -313.882278)
		(end 322.514976 -313.90336)
		(width 0.14224)
		(layer "In15.Cu")
		(net "P3E_CPU0_P4_TX_DP<2>")
	)
	(segment
		(start 252.39472 -202.971146)
		(end 252.39472 -202.544426)
		(width 0.14224)
		(layer "In15.Cu")
		(net "P3E_CPU0_P4_TX_DP<2>")
	)
	(segment
		(start 254.154686 -234.53852)
		(end 253.316232 -228.884734)
		(width 0.14224)
		(layer "In15.Cu")
		(net "P3E_CPU0_P4_TX_DP<2>")
	)
	(segment
		(start 252.39472 -204.799946)
		(end 252.53188 -204.662786)
		(width 0.14224)
		(layer "In15.Cu")
		(net "P3E_CPU0_P4_TX_DP<2>")
	)
	(segment
		(start 255.636268 -196.78269)
		(end 255.927098 -197.07352)
		(width 0.14224)
		(layer "In15.Cu")
		(net "P3E_CPU0_P4_TX_DP<2>")
	)
	(segment
		(start 252.53188 -204.662786)
		(end 252.53188 -204.236066)
		(width 0.14224)
		(layer "In15.Cu")
		(net "P3E_CPU0_P4_TX_DP<2>")
	)
	(segment
		(start 256.4384 -255.677924)
		(end 256.349246 -254.282956)
		(width 0.14224)
		(layer "In15.Cu")
		(net "P3E_CPU0_P4_TX_DP<2>")
	)
	(segment
		(start 252.39472 -201.416666)
		(end 253.770384 -198.095616)
		(width 0.14224)
		(layer "In15.Cu")
		(net "P3E_CPU0_P4_TX_DP<2>")
	)
	(segment
		(start 252.39472 -219.524834)
		(end 252.39472 -210.438746)
		(width 0.14224)
		(layer "In15.Cu")
		(net "P3E_CPU0_P4_TX_DP<2>")
	)
	(segment
		(start 309.353966 -321.841876)
		(end 264.946638 -321.647058)
		(width 0.14224)
		(layer "In15.Cu")
		(net "P3E_CPU0_P4_TX_DP<2>")
	)
	(segment
		(start 260.512814 -312.816494)
		(end 259.600954 -285.821882)
		(width 0.14224)
		(layer "In15.Cu")
		(net "P3E_CPU0_P4_TX_DP<2>")
	)
	(segment
		(start 252.39472 -206.354426)
		(end 252.39472 -205.927706)
		(width 0.14224)
		(layer "In15.Cu")
		(net "P3E_CPU0_P4_TX_DP<2>")
	)
	(segment
		(start 258.394454 -270.904462)
		(end 256.4384 -255.677924)
		(width 0.14224)
		(layer "In15.Cu")
		(net "P3E_CPU0_P4_TX_DP<2>")
	)
	(segment
		(start 252.53188 -208.046066)
		(end 252.53188 -207.619346)
		(width 0.14224)
		(layer "In15.Cu")
		(net "P3E_CPU0_P4_TX_DP<2>")
	)
	(segment
		(start 341.900002 -308.439566)
		(end 341.609172 -308.730396)
		(width 0.14224)
		(layer "In15.Cu")
		(net "P3E_CPU0_P4_TX_DP<2>")
	)
	(segment
		(start 252.39472 -203.672186)
		(end 252.53188 -203.535026)
		(width 0.14224)
		(layer "In15.Cu")
		(net "P3E_CPU0_P4_TX_DP<2>")
	)
	(segment
		(start 252.53188 -206.918306)
		(end 252.53188 -206.491586)
		(width 0.14224)
		(layer "In15.Cu")
		(net "P3E_CPU0_P4_TX_DP<2>")
	)
	(segment
		(start 252.53188 -202.407266)
		(end 252.53188 -201.980546)
		(width 0.14224)
		(layer "In15.Cu")
		(net "P3E_CPU0_P4_TX_DP<2>")
	)
	(segment
		(start 252.53188 -207.619346)
		(end 252.39472 -207.482186)
		(width 0.14224)
		(layer "In15.Cu")
		(net "P3E_CPU0_P4_TX_DP<2>")
	)
	(segment
		(start 259.600954 -285.821882)
		(end 258.394454 -270.904462)
		(width 0.14224)
		(layer "In15.Cu")
		(net "P3E_CPU0_P4_TX_DP<2>")
	)
	(segment
		(start 252.39472 -202.544426)
		(end 252.53188 -202.407266)
		(width 0.14224)
		(layer "In15.Cu")
		(net "P3E_CPU0_P4_TX_DP<2>")
	)
	(segment
		(start 322.514976 -313.90336)
		(end 322.513706 -313.903614)
		(width 0.14224)
		(layer "In15.Cu")
		(net "P3E_CPU0_P4_TX_DP<2>")
	)
	(segment
		(start 263.573006 -321.344036)
		(end 262.258302 -320.741294)
		(width 0.14224)
		(layer "In15.Cu")
		(net "P3E_CPU0_P4_TX_DP<2>")
	)
	(segment
		(start 261.489952 -319.354454)
		(end 261.028434 -317.127128)
		(width 0.14224)
		(layer "In15.Cu")
		(net "P3E_CPU0_P4_TX_DP<2>")
	)
	(segment
		(start 252.39472 -201.843386)
		(end 252.39472 -201.416666)
		(width 0.14224)
		(layer "In15.Cu")
		(net "P3E_CPU0_P4_TX_DP<2>")
	)
	(segment
		(start 252.53188 -204.236066)
		(end 252.39472 -204.098906)
		(width 0.14224)
		(layer "In15.Cu")
		(net "P3E_CPU0_P4_TX_DP<2>")
	)
	(segment
		(start 252.53188 -208.747106)
		(end 252.39472 -208.609946)
		(width 0.14224)
		(layer "In15.Cu")
		(net "P3E_CPU0_P4_TX_DP<2>")
	)
	(segment
		(start 252.39472 -208.609946)
		(end 252.39472 -208.183226)
		(width 0.14224)
		(layer "In15.Cu")
		(net "P3E_CPU0_P4_TX_DP<2>")
	)
	(segment
		(start 252.39472 -204.098906)
		(end 252.39472 -203.672186)
		(width 0.14224)
		(layer "In15.Cu")
		(net "P3E_CPU0_P4_TX_DP<2>")
	)
	(segment
		(start 310.945022 -321.527424)
		(end 309.353966 -321.841876)
		(width 0.14224)
		(layer "In15.Cu")
		(net "P3E_CPU0_P4_TX_DP<2>")
	)
	(segment
		(start 253.770384 -198.095616)
		(end 254.914146 -196.951854)
		(width 0.14224)
		(layer "In15.Cu")
		(net "P3E_CPU0_P4_TX_DP<2>")
	)
	(segment
		(start 255.322578 -196.78269)
		(end 255.636268 -196.78269)
		(width 0.14224)
		(layer "In15.Cu")
		(net "P3E_CPU0_P4_TX_DP<2>")
	)
	(segment
		(start 256.349246 -254.282956)
		(end 255.340358 -246.575072)
		(width 0.14224)
		(layer "In15.Cu")
		(net "P3E_CPU0_P4_TX_DP<2>")
	)
	(segment
		(start 318.073532 -315.33592)
		(end 312.54446 -320.864992)
		(width 0.14224)
		(layer "In15.Cu")
		(net "P3E_CPU0_P4_TX_DP<2>")
	)
	(segment
		(start 252.53188 -209.874866)
		(end 252.39472 -209.737706)
		(width 0.14224)
		(layer "In15.Cu")
		(net "P3E_CPU0_P4_TX_DP<2>")
	)
	(segment
		(start 252.39472 -205.927706)
		(end 252.53188 -205.790546)
		(width 0.14224)
		(layer "In15.Cu")
		(net "P3E_CPU0_P4_TX_DP<2>")
	)
	(segment
		(start 322.412868 -313.92749)
		(end 319.378838 -314.795154)
		(width 0.14224)
		(layer "In15.Cu")
		(net "P3E_CPU0_P4_TX_DP<2>")
	)
	(segment
		(start 252.39472 -208.183226)
		(end 252.53188 -208.046066)
		(width 0.14224)
		(layer "In15.Cu")
		(net "P3E_CPU0_P4_TX_DP<2>")
	)
	(segment
		(start 252.39472 -209.737706)
		(end 252.39472 -209.310986)
		(width 0.14224)
		(layer "In15.Cu")
		(net "P3E_CPU0_P4_TX_DP<2>")
	)
	(segment
		(start 334.751426 -310.734202)
		(end 330.335382 -311.72531)
		(width 0.14224)
		(layer "In15.Cu")
		(net "P3E_CPU0_P4_TX_DP<2>")
	)
	(segment
		(start 261.732014 -320.0527)
		(end 261.594854 -319.704466)
		(width 0.14224)
		(layer "In15.Cu")
		(net "P3E_CPU0_P4_TX_DP<2>")
	)
	(segment
		(start 253.316232 -228.884734)
		(end 252.39472 -219.524834)
		(width 0.14224)
		(layer "In15.Cu")
		(net "P3E_CPU0_P4_TX_DP<2>")
	)
	(segment
		(start 252.53188 -203.108306)
		(end 252.39472 -202.971146)
		(width 0.14224)
		(layer "In15.Cu")
		(net "P3E_CPU0_P4_TX_DP<2>")
	)
	(segment
		(start 338.988654 -308.730396)
		(end 334.751426 -310.734202)
		(width 0.14224)
		(layer "In15.Cu")
		(net "P3E_CPU0_P4_TX_DP<2>")
	)
	(segment
		(start 264.946638 -321.647058)
		(end 263.573006 -321.344036)
		(width 0.14224)
		(layer "In15.Cu")
		(net "P3E_CPU0_P4_TX_DP<2>")
	)
	(segment
		(start 252.53188 -206.491586)
		(end 252.39472 -206.354426)
		(width 0.14224)
		(layer "In15.Cu")
		(net "P3E_CPU0_P4_TX_DP<2>")
	)
	(segment
		(start 252.39472 -207.482186)
		(end 252.39472 -207.055466)
		(width 0.14224)
		(layer "In15.Cu")
		(net "P3E_CPU0_P4_TX_DP<2>")
	)
	(segment
		(start 312.54446 -320.864992)
		(end 310.945022 -321.527424)
		(width 0.14224)
		(layer "In15.Cu")
		(net "P3E_CPU0_P4_TX_DP<2>")
	)
	(segment
		(start 319.378838 -314.795154)
		(end 318.073532 -315.33592)
		(width 0.14224)
		(layer "In15.Cu")
		(net "P3E_CPU0_P4_TX_DP<2>")
	)
	(segment
		(start 252.39472 -207.055466)
		(end 252.53188 -206.918306)
		(width 0.14224)
		(layer "In15.Cu")
		(net "P3E_CPU0_P4_TX_DP<2>")
	)
	(segment
		(start 327.959212 -312.258456)
		(end 322.607178 -313.882278)
		(width 0.14224)
		(layer "In15.Cu")
		(net "P3E_CPU0_P4_TX_DP<2>")
	)
	(segment
		(start 261.028434 -317.127128)
		(end 260.512814 -312.816494)
		(width 0.14224)
		(layer "In15.Cu")
		(net "P3E_CPU0_P4_TX_DP<2>")
	)
	(segment
		(start 252.53188 -205.363826)
		(end 252.39472 -205.226666)
		(width 0.14224)
		(layer "In15.Cu")
		(net "P3E_CPU0_P4_TX_DP<2>")
	)
	(segment
		(start 252.39472 -205.226666)
		(end 252.39472 -204.799946)
		(width 0.14224)
		(layer "In15.Cu")
		(net "P3E_CPU0_P4_TX_DP<2>")
	)
	(segment
		(start 261.898892 -320.328036)
		(end 261.732014 -320.0527)
		(width 0.14224)
		(layer "In15.Cu")
		(net "P3E_CPU0_P4_TX_DP<2>")
	)
	(segment
		(start 262.258302 -320.741294)
		(end 261.898892 -320.328036)
		(width 0.14224)
		(layer "In15.Cu")
		(net "P3E_CPU0_P4_TX_DP<2>")
	)
	(segment
		(start 252.39472 -209.310986)
		(end 252.53188 -209.173826)
		(width 0.14224)
		(layer "In15.Cu")
		(net "P3E_CPU0_P4_TX_DP<2>")
	)
	(segment
		(start 322.513706 -313.903868)
		(end 322.412868 -313.92749)
		(width 0.14224)
		(layer "In15.Cu")
		(net "P3E_CPU0_P4_TX_DP<2>")
	)
	(segment
		(start 341.609172 -308.730396)
		(end 338.988654 -308.730396)
		(width 0.14224)
		(layer "In15.Cu")
		(net "P3E_CPU0_P4_TX_DP<2>")
	)
	(segment
		(start 322.513706 -313.903614)
		(end 322.513706 -313.903868)
		(width 0.14224)
		(layer "In15.Cu")
		(net "P3E_CPU0_P4_TX_DP<2>")
	)
	(segment
		(start 239.715294 -54.117748)
		(end 239.419384 -53.821838)
		(width 0.12954)
		(layer "F.Cu")
		(net "P3E_CPU0_P4_TX_DP<1>")
	)
	(segment
		(start 243.95176 -66.666364)
		(end 243.95176 -58.21426)
		(width 0.12954)
		(layer "F.Cu")
		(net "P3E_CPU0_P4_TX_DP<1>")
	)
	(segment
		(start 256.198878 -199.596248)
		(end 256.559304 -199.596248)
		(width 0.12954)
		(layer "F.Cu")
		(net "P3E_CPU0_P4_TX_DP<1>")
	)
	(segment
		(start 242.802918 -55.441342)
		(end 241.479324 -54.117748)
		(width 0.12954)
		(layer "F.Cu")
		(net "P3E_CPU0_P4_TX_DP<1>")
	)
	(segment
		(start 248.77395 -145.648172)
		(end 247.647968 -137.308336)
		(width 0.12954)
		(layer "F.Cu")
		(net "P3E_CPU0_P4_TX_DP<1>")
	)
	(segment
		(start 258.750308 -191.199516)
		(end 248.77395 -145.648172)
		(width 0.12954)
		(layer "F.Cu")
		(net "P3E_CPU0_P4_TX_DP<1>")
	)
	(segment
		(start 247.647968 -137.308336)
		(end 243.95176 -66.666364)
		(width 0.12954)
		(layer "F.Cu")
		(net "P3E_CPU0_P4_TX_DP<1>")
	)
	(segment
		(start 243.95176 -58.21426)
		(end 243.29771 -56.63565)
		(width 0.12954)
		(layer "F.Cu")
		(net "P3E_CPU0_P4_TX_DP<1>")
	)
	(segment
		(start 258.622038 -197.760844)
		(end 258.750308 -197.451472)
		(width 0.12954)
		(layer "F.Cu")
		(net "P3E_CPU0_P4_TX_DP<1>")
	)
	(segment
		(start 258.750308 -197.451472)
		(end 258.750308 -191.199516)
		(width 0.12954)
		(layer "F.Cu")
		(net "P3E_CPU0_P4_TX_DP<1>")
	)
	(segment
		(start 256.947416 -199.435212)
		(end 258.622038 -197.760844)
		(width 0.12954)
		(layer "F.Cu")
		(net "P3E_CPU0_P4_TX_DP<1>")
	)
	(segment
		(start 243.29771 -56.63565)
		(end 243.297456 -56.635396)
		(width 0.12954)
		(layer "F.Cu")
		(net "P3E_CPU0_P4_TX_DP<1>")
	)
	(segment
		(start 241.479324 -54.117748)
		(end 239.715294 -54.117748)
		(width 0.12954)
		(layer "F.Cu")
		(net "P3E_CPU0_P4_TX_DP<1>")
	)
	(segment
		(start 255.927098 -199.868028)
		(end 256.198878 -199.596248)
		(width 0.12954)
		(layer "F.Cu")
		(net "P3E_CPU0_P4_TX_DP<1>")
	)
	(segment
		(start 256.559304 -199.596248)
		(end 256.947416 -199.435212)
		(width 0.12954)
		(layer "F.Cu")
		(net "P3E_CPU0_P4_TX_DP<1>")
	)
	(segment
		(start 243.297456 -56.635396)
		(end 242.802918 -55.441342)
		(width 0.12954)
		(layer "F.Cu")
		(net "P3E_CPU0_P4_TX_DP<1>")
	)
	(segment
		(start 349.20809 -292.450012)
		(end 348.741238 -292.71595)
		(width 0.12954)
		(layer "F.Cu")
		(net "P3E_CPU0_P4_TX_DP<1>")
	)
	(segment
		(start 344.756486 -303.188624)
		(end 344.56624 -303.150778)
		(width 0.14224)
		(layer "In2.Cu")
		(net "P3E_CPU0_P4_TX_DP<1>")
	)
	(segment
		(start 344.211148 -303.388014)
		(end 344.173302 -303.57826)
		(width 0.14224)
		(layer "In2.Cu")
		(net "P3E_CPU0_P4_TX_DP<1>")
	)
	(segment
		(start 343.818718 -303.815242)
		(end 343.628472 -303.77765)
		(width 0.14224)
		(layer "In2.Cu")
		(net "P3E_CPU0_P4_TX_DP<1>")
	)
	(segment
		(start 341.778844 -305.54422)
		(end 341.477346 -305.845718)
		(width 0.14224)
		(layer "In2.Cu")
		(net "P3E_CPU0_P4_TX_DP<1>")
	)
	(segment
		(start 349.425514 -295.444164)
		(end 349.42526 -295.444418)
		(width 0.1143)
		(layer "In2.Cu")
		(net "P3E_CPU0_P4_TX_DP<1>")
	)
	(segment
		(start 349.360236 -293.181532)
		(end 349.38462 -293.195248)
		(width 0.1143)
		(layer "In2.Cu")
		(net "P3E_CPU0_P4_TX_DP<1>")
	)
	(segment
		(start 349.350838 -293.87673)
		(end 349.351092 -293.876984)
		(width 0.1143)
		(layer "In2.Cu")
		(net "P3E_CPU0_P4_TX_DP<1>")
	)
	(segment
		(start 349.383096 -294.814752)
		(end 349.382842 -294.814752)
		(width 0.1143)
		(layer "In2.Cu")
		(net "P3E_CPU0_P4_TX_DP<1>")
	)
	(segment
		(start 349.38462 -293.85641)
		(end 349.359728 -293.870634)
		(width 0.1143)
		(layer "In2.Cu")
		(net "P3E_CPU0_P4_TX_DP<1>")
	)
	(segment
		(start 344.173302 -303.57826)
		(end 343.818718 -303.815242)
		(width 0.14224)
		(layer "In2.Cu")
		(net "P3E_CPU0_P4_TX_DP<1>")
	)
	(segment
		(start 349.382334 -294.814244)
		(end 349.383096 -294.814752)
		(width 0.1143)
		(layer "In2.Cu")
		(net "P3E_CPU0_P4_TX_DP<1>")
	)
	(segment
		(start 349.038926 -292.71595)
		(end 349.12173 -292.798754)
		(width 0.1143)
		(layer "In2.Cu")
		(net "P3E_CPU0_P4_TX_DP<1>")
	)
	(segment
		(start 349.359982 -294.80129)
		(end 349.382334 -294.814244)
		(width 0.1143)
		(layer "In2.Cu")
		(net "P3E_CPU0_P4_TX_DP<1>")
	)
	(segment
		(start 343.27338 -304.014886)
		(end 343.235534 -304.205132)
		(width 0.14224)
		(layer "In2.Cu")
		(net "P3E_CPU0_P4_TX_DP<1>")
	)
	(segment
		(start 349.395796 -294.822118)
		(end 349.426276 -294.84066)
		(width 0.1143)
		(layer "In2.Cu")
		(net "P3E_CPU0_P4_TX_DP<1>")
	)
	(segment
		(start 348.741238 -292.71595)
		(end 349.038926 -292.71595)
		(width 0.1143)
		(layer "In2.Cu")
		(net "P3E_CPU0_P4_TX_DP<1>")
	)
	(segment
		(start 348.798896 -296.544492)
		(end 348.798896 -297.561508)
		(width 0.1143)
		(layer "In2.Cu")
		(net "P3E_CPU0_P4_TX_DP<1>")
	)
	(segment
		(start 349.12173 -292.817042)
		(end 349.126048 -292.82136)
		(width 0.1143)
		(layer "In2.Cu")
		(net "P3E_CPU0_P4_TX_DP<1>")
	)
	(segment
		(start 342.08085 -305.051714)
		(end 341.778844 -305.35372)
		(width 0.14224)
		(layer "In2.Cu")
		(net "P3E_CPU0_P4_TX_DP<1>")
	)
	(segment
		(start 341.477346 -305.845718)
		(end 341.153496 -305.845718)
		(width 0.14224)
		(layer "In2.Cu")
		(net "P3E_CPU0_P4_TX_DP<1>")
	)
	(segment
		(start 349.382842 -294.814752)
		(end 349.384366 -294.815514)
		(width 0.1143)
		(layer "In2.Cu")
		(net "P3E_CPU0_P4_TX_DP<1>")
	)
	(segment
		(start 348.753176 -297.607228)
		(end 348.753176 -297.635676)
		(width 0.1143)
		(layer "In2.Cu")
		(net "P3E_CPU0_P4_TX_DP<1>")
	)
	(segment
		(start 348.753176 -297.635676)
		(end 348.753176 -299.712126)
		(width 0.14224)
		(layer "In2.Cu")
		(net "P3E_CPU0_P4_TX_DP<1>")
	)
	(segment
		(start 349.42526 -295.444418)
		(end 349.409004 -295.454324)
		(width 0.1143)
		(layer "In2.Cu")
		(net "P3E_CPU0_P4_TX_DP<1>")
	)
	(segment
		(start 346.324428 -302.140874)
		(end 344.756486 -303.188624)
		(width 0.14224)
		(layer "In2.Cu")
		(net "P3E_CPU0_P4_TX_DP<1>")
	)
	(segment
		(start 341.153496 -305.845718)
		(end 340.877144 -305.569366)
		(width 0.14224)
		(layer "In2.Cu")
		(net "P3E_CPU0_P4_TX_DP<1>")
	)
	(segment
		(start 343.235534 -304.205132)
		(end 342.88095 -304.442114)
		(width 0.14224)
		(layer "In2.Cu")
		(net "P3E_CPU0_P4_TX_DP<1>")
	)
	(segment
		(start 342.27135 -305.051714)
		(end 342.08085 -305.051714)
		(width 0.14224)
		(layer "In2.Cu")
		(net "P3E_CPU0_P4_TX_DP<1>")
	)
	(segment
		(start 349.385128 -294.816022)
		(end 349.395796 -294.822118)
		(width 0.1143)
		(layer "In2.Cu")
		(net "P3E_CPU0_P4_TX_DP<1>")
	)
	(segment
		(start 341.778844 -305.35372)
		(end 341.778844 -305.54422)
		(width 0.14224)
		(layer "In2.Cu")
		(net "P3E_CPU0_P4_TX_DP<1>")
	)
	(segment
		(start 343.628472 -303.77765)
		(end 343.27338 -304.014886)
		(width 0.14224)
		(layer "In2.Cu")
		(net "P3E_CPU0_P4_TX_DP<1>")
	)
	(segment
		(start 342.88095 -304.442114)
		(end 342.27135 -305.051714)
		(width 0.14224)
		(layer "In2.Cu")
		(net "P3E_CPU0_P4_TX_DP<1>")
	)
	(segment
		(start 344.56624 -303.150778)
		(end 344.211148 -303.388014)
		(width 0.14224)
		(layer "In2.Cu")
		(net "P3E_CPU0_P4_TX_DP<1>")
	)
	(segment
		(start 349.384366 -294.815514)
		(end 349.385128 -294.816022)
		(width 0.1143)
		(layer "In2.Cu")
		(net "P3E_CPU0_P4_TX_DP<1>")
	)
	(segment
		(start 348.798896 -297.561508)
		(end 348.753176 -297.607228)
		(width 0.1143)
		(layer "In2.Cu")
		(net "P3E_CPU0_P4_TX_DP<1>")
	)
	(segment
		(start 348.753176 -299.712126)
		(end 346.324428 -302.140874)
		(width 0.14224)
		(layer "In2.Cu")
		(net "P3E_CPU0_P4_TX_DP<1>")
	)
	(arc
		(start 349.351092 -293.876984)
		(mid 349.115905 -294.341424)
		(end 349.359982 -294.80129)
		(width 0.1143)
		(layer "In2.Cu")
		(net "P3E_CPU0_P4_TX_DP<1>")
	)
	(arc
		(start 349.38462 -293.195248)
		(mid 349.576154 -293.525893)
		(end 349.38462 -293.85641)
		(width 0.1143)
		(layer "In2.Cu")
		(net "P3E_CPU0_P4_TX_DP<1>")
	)
	(arc
		(start 349.12173 -292.798754)
		(mid 349.121655 -292.807898)
		(end 349.12173 -292.817042)
		(width 0.1143)
		(layer "In2.Cu")
		(net "P3E_CPU0_P4_TX_DP<1>")
	)
	(arc
		(start 349.409004 -295.454324)
		(mid 348.961758 -295.919827)
		(end 348.798896 -296.544492)
		(width 0.1143)
		(layer "In2.Cu")
		(net "P3E_CPU0_P4_TX_DP<1>")
	)
	(arc
		(start 349.359728 -293.870634)
		(mid 349.355268 -293.87366)
		(end 349.350838 -293.87673)
		(width 0.1143)
		(layer "In2.Cu")
		(net "P3E_CPU0_P4_TX_DP<1>")
	)
	(arc
		(start 349.126048 -292.82136)
		(mid 349.207578 -293.024575)
		(end 349.360236 -293.181532)
		(width 0.1143)
		(layer "In2.Cu")
		(net "P3E_CPU0_P4_TX_DP<1>")
	)
	(arc
		(start 349.426276 -294.84066)
		(mid 349.594566 -295.142616)
		(end 349.425514 -295.444164)
		(width 0.1143)
		(layer "In2.Cu")
		(net "P3E_CPU0_P4_TX_DP<1>")
	)
	(segment
		(start 253.792228 -202.559412)
		(end 253.655068 -202.422252)
		(width 0.14224)
		(layer "In15.Cu")
		(net "P3E_CPU0_P4_TX_DP<1>")
	)
	(segment
		(start 253.655068 -203.550012)
		(end 253.655068 -203.123292)
		(width 0.14224)
		(layer "In15.Cu")
		(net "P3E_CPU0_P4_TX_DP<1>")
	)
	(segment
		(start 261.784338 -314.37199)
		(end 260.813296 -285.645606)
		(width 0.14224)
		(layer "In15.Cu")
		(net "P3E_CPU0_P4_TX_DP<1>")
	)
	(segment
		(start 331.212698 -308.99735)
		(end 323.803264 -312.066432)
		(width 0.14224)
		(layer "In15.Cu")
		(net "P3E_CPU0_P4_TX_DP<1>")
	)
	(segment
		(start 260.813296 -285.645606)
		(end 259.20954 -265.835892)
		(width 0.14224)
		(layer "In15.Cu")
		(net "P3E_CPU0_P4_TX_DP<1>")
	)
	(segment
		(start 253.792228 -207.070452)
		(end 253.655068 -206.933292)
		(width 0.14224)
		(layer "In15.Cu")
		(net "P3E_CPU0_P4_TX_DP<1>")
	)
	(segment
		(start 253.655068 -208.762092)
		(end 253.792228 -208.624932)
		(width 0.14224)
		(layer "In15.Cu")
		(net "P3E_CPU0_P4_TX_DP<1>")
	)
	(segment
		(start 253.792228 -209.752692)
		(end 253.792228 -209.325972)
		(width 0.14224)
		(layer "In15.Cu")
		(net "P3E_CPU0_P4_TX_DP<1>")
	)
	(segment
		(start 262.373364 -318.966596)
		(end 262.103108 -317.608712)
		(width 0.14224)
		(layer "In15.Cu")
		(net "P3E_CPU0_P4_TX_DP<1>")
	)
	(segment
		(start 253.655068 -207.634332)
		(end 253.792228 -207.497172)
		(width 0.14224)
		(layer "In15.Cu")
		(net "P3E_CPU0_P4_TX_DP<1>")
	)
	(segment
		(start 253.655068 -209.889852)
		(end 253.792228 -209.752692)
		(width 0.14224)
		(layer "In15.Cu")
		(net "P3E_CPU0_P4_TX_DP<1>")
	)
	(segment
		(start 253.792228 -202.986132)
		(end 253.792228 -202.559412)
		(width 0.14224)
		(layer "In15.Cu")
		(net "P3E_CPU0_P4_TX_DP<1>")
	)
	(segment
		(start 310.766714 -320.591942)
		(end 309.29326 -320.88455)
		(width 0.14224)
		(layer "In15.Cu")
		(net "P3E_CPU0_P4_TX_DP<1>")
	)
	(segment
		(start 253.792228 -208.624932)
		(end 253.792228 -208.198212)
		(width 0.14224)
		(layer "In15.Cu")
		(net "P3E_CPU0_P4_TX_DP<1>")
	)
	(segment
		(start 253.792228 -210.880452)
		(end 253.792228 -210.453732)
		(width 0.14224)
		(layer "In15.Cu")
		(net "P3E_CPU0_P4_TX_DP<1>")
	)
	(segment
		(start 317.602108 -314.488576)
		(end 312.015886 -320.074798)
		(width 0.14224)
		(layer "In15.Cu")
		(net "P3E_CPU0_P4_TX_DP<1>")
	)
	(segment
		(start 340.586314 -305.860196)
		(end 339.434678 -305.860196)
		(width 0.14224)
		(layer "In15.Cu")
		(net "P3E_CPU0_P4_TX_DP<1>")
	)
	(segment
		(start 253.792228 -205.241652)
		(end 253.792228 -204.814932)
		(width 0.14224)
		(layer "In15.Cu")
		(net "P3E_CPU0_P4_TX_DP<1>")
	)
	(segment
		(start 253.655068 -211.017612)
		(end 253.792228 -210.880452)
		(width 0.14224)
		(layer "In15.Cu")
		(net "P3E_CPU0_P4_TX_DP<1>")
	)
	(segment
		(start 253.792228 -203.687172)
		(end 253.655068 -203.550012)
		(width 0.14224)
		(layer "In15.Cu")
		(net "P3E_CPU0_P4_TX_DP<1>")
	)
	(segment
		(start 340.877144 -305.569366)
		(end 340.586314 -305.860196)
		(width 0.14224)
		(layer "In15.Cu")
		(net "P3E_CPU0_P4_TX_DP<1>")
	)
	(segment
		(start 253.655068 -209.188812)
		(end 253.655068 -208.762092)
		(width 0.14224)
		(layer "In15.Cu")
		(net "P3E_CPU0_P4_TX_DP<1>")
	)
	(segment
		(start 265.06551 -320.69151)
		(end 264.265156 -320.529458)
		(width 0.14224)
		(layer "In15.Cu")
		(net "P3E_CPU0_P4_TX_DP<1>")
	)
	(segment
		(start 253.792228 -208.198212)
		(end 253.655068 -208.061052)
		(width 0.14224)
		(layer "In15.Cu")
		(net "P3E_CPU0_P4_TX_DP<1>")
	)
	(segment
		(start 262.516874 -319.440306)
		(end 262.373364 -318.966596)
		(width 0.14224)
		(layer "In15.Cu")
		(net "P3E_CPU0_P4_TX_DP<1>")
	)
	(segment
		(start 322.509896 -312.52922)
		(end 321.203828 -312.99658)
		(width 0.14224)
		(layer "In15.Cu")
		(net "P3E_CPU0_P4_TX_DP<1>")
	)
	(segment
		(start 262.103108 -317.608712)
		(end 261.784338 -314.37199)
		(width 0.14224)
		(layer "In15.Cu")
		(net "P3E_CPU0_P4_TX_DP<1>")
	)
	(segment
		(start 253.792228 -209.325972)
		(end 253.655068 -209.188812)
		(width 0.14224)
		(layer "In15.Cu")
		(net "P3E_CPU0_P4_TX_DP<1>")
	)
	(segment
		(start 253.792228 -207.497172)
		(end 253.792228 -207.070452)
		(width 0.14224)
		(layer "In15.Cu")
		(net "P3E_CPU0_P4_TX_DP<1>")
	)
	(segment
		(start 309.29326 -320.88455)
		(end 265.06551 -320.69151)
		(width 0.14224)
		(layer "In15.Cu")
		(net "P3E_CPU0_P4_TX_DP<1>")
	)
	(segment
		(start 254.249174 -200.561194)
		(end 254.45974 -200.246488)
		(width 0.14224)
		(layer "In15.Cu")
		(net "P3E_CPU0_P4_TX_DP<1>")
	)
	(segment
		(start 321.203828 -312.99658)
		(end 317.602108 -314.488576)
		(width 0.14224)
		(layer "In15.Cu")
		(net "P3E_CPU0_P4_TX_DP<1>")
	)
	(segment
		(start 254.929132 -199.777096)
		(end 255.411732 -199.577198)
		(width 0.14224)
		(layer "In15.Cu")
		(net "P3E_CPU0_P4_TX_DP<1>")
	)
	(segment
		(start 255.636268 -199.577198)
		(end 255.927098 -199.868028)
		(width 0.14224)
		(layer "In15.Cu")
		(net "P3E_CPU0_P4_TX_DP<1>")
	)
	(segment
		(start 262.638286 -319.733422)
		(end 262.516874 -319.440306)
		(width 0.14224)
		(layer "In15.Cu")
		(net "P3E_CPU0_P4_TX_DP<1>")
	)
	(segment
		(start 323.803264 -312.066432)
		(end 322.509642 -312.52922)
		(width 0.14224)
		(layer "In15.Cu")
		(net "P3E_CPU0_P4_TX_DP<1>")
	)
	(segment
		(start 253.792228 -205.942692)
		(end 253.655068 -205.805532)
		(width 0.14224)
		(layer "In15.Cu")
		(net "P3E_CPU0_P4_TX_DP<1>")
	)
	(segment
		(start 339.434678 -305.860196)
		(end 338.435696 -305.44643)
		(width 0.14224)
		(layer "In15.Cu")
		(net "P3E_CPU0_P4_TX_DP<1>")
	)
	(segment
		(start 253.655068 -208.061052)
		(end 253.655068 -207.634332)
		(width 0.14224)
		(layer "In15.Cu")
		(net "P3E_CPU0_P4_TX_DP<1>")
	)
	(segment
		(start 253.655068 -202.422252)
		(end 253.655068 -201.995532)
		(width 0.14224)
		(layer "In15.Cu")
		(net "P3E_CPU0_P4_TX_DP<1>")
	)
	(segment
		(start 253.655068 -201.995532)
		(end 254.249174 -200.561194)
		(width 0.14224)
		(layer "In15.Cu")
		(net "P3E_CPU0_P4_TX_DP<1>")
	)
	(segment
		(start 253.655068 -206.933292)
		(end 253.655068 -206.506572)
		(width 0.14224)
		(layer "In15.Cu")
		(net "P3E_CPU0_P4_TX_DP<1>")
	)
	(segment
		(start 253.655068 -204.251052)
		(end 253.792228 -204.113892)
		(width 0.14224)
		(layer "In15.Cu")
		(net "P3E_CPU0_P4_TX_DP<1>")
	)
	(segment
		(start 312.015886 -320.074798)
		(end 310.766714 -320.591942)
		(width 0.14224)
		(layer "In15.Cu")
		(net "P3E_CPU0_P4_TX_DP<1>")
	)
	(segment
		(start 338.435696 -305.44643)
		(end 336.526632 -305.44643)
		(width 0.14224)
		(layer "In15.Cu")
		(net "P3E_CPU0_P4_TX_DP<1>")
	)
	(segment
		(start 254.45974 -200.246488)
		(end 254.929132 -199.777096)
		(width 0.14224)
		(layer "In15.Cu")
		(net "P3E_CPU0_P4_TX_DP<1>")
	)
	(segment
		(start 253.655068 -205.805532)
		(end 253.655068 -205.378812)
		(width 0.14224)
		(layer "In15.Cu")
		(net "P3E_CPU0_P4_TX_DP<1>")
	)
	(segment
		(start 259.20954 -265.835892)
		(end 253.655068 -222.593662)
		(width 0.14224)
		(layer "In15.Cu")
		(net "P3E_CPU0_P4_TX_DP<1>")
	)
	(segment
		(start 322.509642 -312.52922)
		(end 322.509896 -312.52922)
		(width 0.14224)
		(layer "In15.Cu")
		(net "P3E_CPU0_P4_TX_DP<1>")
	)
	(segment
		(start 253.655068 -206.506572)
		(end 253.792228 -206.369412)
		(width 0.14224)
		(layer "In15.Cu")
		(net "P3E_CPU0_P4_TX_DP<1>")
	)
	(segment
		(start 253.655068 -205.378812)
		(end 253.792228 -205.241652)
		(width 0.14224)
		(layer "In15.Cu")
		(net "P3E_CPU0_P4_TX_DP<1>")
	)
	(segment
		(start 255.411732 -199.577198)
		(end 255.636268 -199.577198)
		(width 0.14224)
		(layer "In15.Cu")
		(net "P3E_CPU0_P4_TX_DP<1>")
	)
	(segment
		(start 253.792228 -210.453732)
		(end 253.655068 -210.316572)
		(width 0.14224)
		(layer "In15.Cu")
		(net "P3E_CPU0_P4_TX_DP<1>")
	)
	(segment
		(start 253.792228 -206.369412)
		(end 253.792228 -205.942692)
		(width 0.14224)
		(layer "In15.Cu")
		(net "P3E_CPU0_P4_TX_DP<1>")
	)
	(segment
		(start 262.839454 -319.935098)
		(end 262.638286 -319.733422)
		(width 0.14224)
		(layer "In15.Cu")
		(net "P3E_CPU0_P4_TX_DP<1>")
	)
	(segment
		(start 253.655068 -203.123292)
		(end 253.792228 -202.986132)
		(width 0.14224)
		(layer "In15.Cu")
		(net "P3E_CPU0_P4_TX_DP<1>")
	)
	(segment
		(start 253.655068 -222.593662)
		(end 253.655068 -211.017612)
		(width 0.14224)
		(layer "In15.Cu")
		(net "P3E_CPU0_P4_TX_DP<1>")
	)
	(segment
		(start 253.792228 -204.113892)
		(end 253.792228 -203.687172)
		(width 0.14224)
		(layer "In15.Cu")
		(net "P3E_CPU0_P4_TX_DP<1>")
	)
	(segment
		(start 253.655068 -210.316572)
		(end 253.655068 -209.889852)
		(width 0.14224)
		(layer "In15.Cu")
		(net "P3E_CPU0_P4_TX_DP<1>")
	)
	(segment
		(start 264.265156 -320.529458)
		(end 262.839454 -319.935098)
		(width 0.14224)
		(layer "In15.Cu")
		(net "P3E_CPU0_P4_TX_DP<1>")
	)
	(segment
		(start 336.526632 -305.44643)
		(end 331.212698 -308.99735)
		(width 0.14224)
		(layer "In15.Cu")
		(net "P3E_CPU0_P4_TX_DP<1>")
	)
	(segment
		(start 253.655068 -204.677772)
		(end 253.655068 -204.251052)
		(width 0.14224)
		(layer "In15.Cu")
		(net "P3E_CPU0_P4_TX_DP<1>")
	)
	(segment
		(start 253.792228 -204.814932)
		(end 253.655068 -204.677772)
		(width 0.14224)
		(layer "In15.Cu")
		(net "P3E_CPU0_P4_TX_DP<1>")
	)
	(segment
		(start 239.419384 -52.01285)
		(end 239.715294 -52.30876)
		(width 0.12954)
		(layer "F.Cu")
		(net "P3E_CPU0_P4_TX_DP<0>")
	)
	(segment
		(start 259.724652 -191.539622)
		(end 259.724652 -199.364854)
		(width 0.12954)
		(layer "F.Cu")
		(net "P3E_CPU0_P4_TX_DP<0>")
	)
	(segment
		(start 244.69598 -64.979296)
		(end 248.476516 -137.230866)
		(width 0.12954)
		(layer "F.Cu")
		(net "P3E_CPU0_P4_TX_DP<0>")
	)
	(segment
		(start 259.724652 -199.364854)
		(end 259.569458 -199.739504)
		(width 0.12954)
		(layer "F.Cu")
		(net "P3E_CPU0_P4_TX_DP<0>")
	)
	(segment
		(start 239.715294 -52.30876)
		(end 240.872518 -52.30876)
		(width 0.12954)
		(layer "F.Cu")
		(net "P3E_CPU0_P4_TX_DP<0>")
	)
	(segment
		(start 240.872518 -52.30876)
		(end 241.313716 -52.491132)
		(width 0.12954)
		(layer "F.Cu")
		(net "P3E_CPU0_P4_TX_DP<0>")
	)
	(segment
		(start 243.522754 -54.700424)
		(end 244.69598 -57.532778)
		(width 0.12954)
		(layer "F.Cu")
		(net "P3E_CPU0_P4_TX_DP<0>")
	)
	(segment
		(start 241.798348 -52.976018)
		(end 243.522754 -54.700424)
		(width 0.12954)
		(layer "F.Cu")
		(net "P3E_CPU0_P4_TX_DP<0>")
	)
	(segment
		(start 241.313716 -52.491132)
		(end 241.798348 -52.975764)
		(width 0.12954)
		(layer "F.Cu")
		(net "P3E_CPU0_P4_TX_DP<0>")
	)
	(segment
		(start 259.569458 -199.739504)
		(end 257.069082 -202.23988)
		(width 0.12954)
		(layer "F.Cu")
		(net "P3E_CPU0_P4_TX_DP<0>")
	)
	(segment
		(start 248.476516 -137.230866)
		(end 249.514868 -144.92097)
		(width 0.12954)
		(layer "F.Cu")
		(net "P3E_CPU0_P4_TX_DP<0>")
	)
	(segment
		(start 256.71272 -202.387454)
		(end 256.20218 -202.387454)
		(width 0.12954)
		(layer "F.Cu")
		(net "P3E_CPU0_P4_TX_DP<0>")
	)
	(segment
		(start 244.69598 -57.532778)
		(end 244.69598 -64.979296)
		(width 0.12954)
		(layer "F.Cu")
		(net "P3E_CPU0_P4_TX_DP<0>")
	)
	(segment
		(start 241.798348 -52.975764)
		(end 241.798348 -52.976018)
		(width 0.12954)
		(layer "F.Cu")
		(net "P3E_CPU0_P4_TX_DP<0>")
	)
	(segment
		(start 256.20218 -202.387454)
		(end 255.927098 -202.662536)
		(width 0.12954)
		(layer "F.Cu")
		(net "P3E_CPU0_P4_TX_DP<0>")
	)
	(segment
		(start 346.387928 -292.450012)
		(end 345.921076 -292.71595)
		(width 0.12954)
		(layer "F.Cu")
		(net "P3E_CPU0_P4_TX_DP<0>")
	)
	(segment
		(start 257.069082 -202.23988)
		(end 256.71272 -202.387454)
		(width 0.12954)
		(layer "F.Cu")
		(net "P3E_CPU0_P4_TX_DP<0>")
	)
	(segment
		(start 249.514868 -144.92097)
		(end 259.724652 -191.539622)
		(width 0.12954)
		(layer "F.Cu")
		(net "P3E_CPU0_P4_TX_DP<0>")
	)
	(segment
		(start 337.96732 -302.39335)
		(end 337.78317 -302.34509)
		(width 0.14224)
		(layer "In2.Cu")
		(net "P3E_CPU0_P4_TX_DP<0>")
	)
	(segment
		(start 346.301822 -292.817042)
		(end 346.30614 -292.82136)
		(width 0.1143)
		(layer "In2.Cu")
		(net "P3E_CPU0_P4_TX_DP<0>")
	)
	(segment
		(start 338.335874 -302.178466)
		(end 337.96732 -302.39335)
		(width 0.14224)
		(layer "In2.Cu")
		(net "P3E_CPU0_P4_TX_DP<0>")
	)
	(segment
		(start 346.564458 -294.815514)
		(end 346.56522 -294.816022)
		(width 0.1143)
		(layer "In2.Cu")
		(net "P3E_CPU0_P4_TX_DP<0>")
	)
	(segment
		(start 335.425796 -303.87544)
		(end 335.026254 -304.108358)
		(width 0.14224)
		(layer "In2.Cu")
		(net "P3E_CPU0_P4_TX_DP<0>")
	)
	(segment
		(start 338.753196 -301.779432)
		(end 338.384388 -301.994316)
		(width 0.14224)
		(layer "In2.Cu")
		(net "P3E_CPU0_P4_TX_DP<0>")
	)
	(segment
		(start 336.444336 -303.125632)
		(end 336.395822 -303.309782)
		(width 0.14224)
		(layer "In2.Cu")
		(net "P3E_CPU0_P4_TX_DP<0>")
	)
	(segment
		(start 338.384388 -301.994316)
		(end 338.335874 -302.178466)
		(width 0.14224)
		(layer "In2.Cu")
		(net "P3E_CPU0_P4_TX_DP<0>")
	)
	(segment
		(start 345.905074 -297.906186)
		(end 345.859354 -297.951906)
		(width 0.1143)
		(layer "In2.Cu")
		(net "P3E_CPU0_P4_TX_DP<0>")
	)
	(segment
		(start 346.576396 -294.822372)
		(end 346.622878 -294.85082)
		(width 0.1143)
		(layer "In2.Cu")
		(net "P3E_CPU0_P4_TX_DP<0>")
	)
	(segment
		(start 335.47431 -303.691036)
		(end 335.425796 -303.87544)
		(width 0.14224)
		(layer "In2.Cu")
		(net "P3E_CPU0_P4_TX_DP<0>")
	)
	(segment
		(start 336.027268 -303.524666)
		(end 335.843118 -303.476152)
		(width 0.14224)
		(layer "In2.Cu")
		(net "P3E_CPU0_P4_TX_DP<0>")
	)
	(segment
		(start 336.813144 -302.910494)
		(end 336.444336 -303.125632)
		(width 0.14224)
		(layer "In2.Cu")
		(net "P3E_CPU0_P4_TX_DP<0>")
	)
	(segment
		(start 337.78317 -302.34509)
		(end 337.414362 -302.559974)
		(width 0.14224)
		(layer "In2.Cu")
		(net "P3E_CPU0_P4_TX_DP<0>")
	)
	(segment
		(start 346.562426 -294.814244)
		(end 346.563188 -294.814752)
		(width 0.1143)
		(layer "In2.Cu")
		(net "P3E_CPU0_P4_TX_DP<0>")
	)
	(segment
		(start 336.395822 -303.309782)
		(end 336.027268 -303.524666)
		(width 0.14224)
		(layer "In2.Cu")
		(net "P3E_CPU0_P4_TX_DP<0>")
	)
	(segment
		(start 346.540328 -293.181532)
		(end 346.564712 -293.195248)
		(width 0.1143)
		(layer "In2.Cu")
		(net "P3E_CPU0_P4_TX_DP<0>")
	)
	(segment
		(start 346.563188 -294.814752)
		(end 346.562934 -294.814752)
		(width 0.1143)
		(layer "In2.Cu")
		(net "P3E_CPU0_P4_TX_DP<0>")
	)
	(segment
		(start 335.026254 -304.108358)
		(end 334.467708 -304.108358)
		(width 0.14224)
		(layer "In2.Cu")
		(net "P3E_CPU0_P4_TX_DP<0>")
	)
	(segment
		(start 345.859354 -297.980354)
		(end 345.859354 -298.308522)
		(width 0.14224)
		(layer "In2.Cu")
		(net "P3E_CPU0_P4_TX_DP<0>")
	)
	(segment
		(start 340.613746 -300.850808)
		(end 338.937346 -301.827946)
		(width 0.14224)
		(layer "In2.Cu")
		(net "P3E_CPU0_P4_TX_DP<0>")
	)
	(segment
		(start 337.414362 -302.559974)
		(end 337.365848 -302.744124)
		(width 0.14224)
		(layer "In2.Cu")
		(net "P3E_CPU0_P4_TX_DP<0>")
	)
	(segment
		(start 345.286838 -298.880784)
		(end 340.613746 -300.850808)
		(width 0.14224)
		(layer "In2.Cu")
		(net "P3E_CPU0_P4_TX_DP<0>")
	)
	(segment
		(start 346.562934 -294.814752)
		(end 346.564458 -294.815514)
		(width 0.1143)
		(layer "In2.Cu")
		(net "P3E_CPU0_P4_TX_DP<0>")
	)
	(segment
		(start 335.843118 -303.476152)
		(end 335.47431 -303.691036)
		(width 0.14224)
		(layer "In2.Cu")
		(net "P3E_CPU0_P4_TX_DP<0>")
	)
	(segment
		(start 345.859354 -297.951906)
		(end 345.859354 -297.980354)
		(width 0.1143)
		(layer "In2.Cu")
		(net "P3E_CPU0_P4_TX_DP<0>")
	)
	(segment
		(start 345.905074 -296.516552)
		(end 345.905074 -297.906186)
		(width 0.1143)
		(layer "In2.Cu")
		(net "P3E_CPU0_P4_TX_DP<0>")
	)
	(segment
		(start 346.56522 -294.816022)
		(end 346.576396 -294.822372)
		(width 0.1143)
		(layer "In2.Cu")
		(net "P3E_CPU0_P4_TX_DP<0>")
	)
	(segment
		(start 334.467708 -304.108358)
		(end 334.176878 -303.817528)
		(width 0.14224)
		(layer "In2.Cu")
		(net "P3E_CPU0_P4_TX_DP<0>")
	)
	(segment
		(start 338.937346 -301.827946)
		(end 338.753196 -301.779432)
		(width 0.14224)
		(layer "In2.Cu")
		(net "P3E_CPU0_P4_TX_DP<0>")
	)
	(segment
		(start 337.365848 -302.744124)
		(end 336.997294 -302.959008)
		(width 0.14224)
		(layer "In2.Cu")
		(net "P3E_CPU0_P4_TX_DP<0>")
	)
	(segment
		(start 345.859354 -298.308522)
		(end 345.286838 -298.880784)
		(width 0.14224)
		(layer "In2.Cu")
		(net "P3E_CPU0_P4_TX_DP<0>")
	)
	(segment
		(start 346.76588 -295.655746)
		(end 345.905074 -296.516552)
		(width 0.1143)
		(layer "In2.Cu")
		(net "P3E_CPU0_P4_TX_DP<0>")
	)
	(segment
		(start 346.540074 -294.80129)
		(end 346.562426 -294.814244)
		(width 0.1143)
		(layer "In2.Cu")
		(net "P3E_CPU0_P4_TX_DP<0>")
	)
	(segment
		(start 346.76588 -295.125648)
		(end 346.76588 -295.655746)
		(width 0.1143)
		(layer "In2.Cu")
		(net "P3E_CPU0_P4_TX_DP<0>")
	)
	(segment
		(start 346.219018 -292.71595)
		(end 346.301822 -292.798754)
		(width 0.1143)
		(layer "In2.Cu")
		(net "P3E_CPU0_P4_TX_DP<0>")
	)
	(segment
		(start 336.997294 -302.959008)
		(end 336.813144 -302.910494)
		(width 0.14224)
		(layer "In2.Cu")
		(net "P3E_CPU0_P4_TX_DP<0>")
	)
	(segment
		(start 345.921076 -292.71595)
		(end 346.219018 -292.71595)
		(width 0.1143)
		(layer "In2.Cu")
		(net "P3E_CPU0_P4_TX_DP<0>")
	)
	(segment
		(start 346.564966 -293.85641)
		(end 346.547694 -293.866316)
		(width 0.1143)
		(layer "In2.Cu")
		(net "P3E_CPU0_P4_TX_DP<0>")
	)
	(segment
		(start 346.547694 -293.866316)
		(end 346.531184 -293.876984)
		(width 0.1143)
		(layer "In2.Cu")
		(net "P3E_CPU0_P4_TX_DP<0>")
	)
	(arc
		(start 346.622878 -294.85082)
		(mid 346.728007 -294.970739)
		(end 346.76588 -295.125648)
		(width 0.1143)
		(layer "In2.Cu")
		(net "P3E_CPU0_P4_TX_DP<0>")
	)
	(arc
		(start 346.564712 -293.195248)
		(mid 346.756246 -293.525783)
		(end 346.564966 -293.85641)
		(width 0.1143)
		(layer "In2.Cu")
		(net "P3E_CPU0_P4_TX_DP<0>")
	)
	(arc
		(start 346.301822 -292.798754)
		(mid 346.301747 -292.807898)
		(end 346.301822 -292.817042)
		(width 0.1143)
		(layer "In2.Cu")
		(net "P3E_CPU0_P4_TX_DP<0>")
	)
	(arc
		(start 346.531184 -293.876984)
		(mid 346.295997 -294.341424)
		(end 346.540074 -294.80129)
		(width 0.1143)
		(layer "In2.Cu")
		(net "P3E_CPU0_P4_TX_DP<0>")
	)
	(arc
		(start 346.30614 -292.82136)
		(mid 346.38767 -293.024575)
		(end 346.540328 -293.181532)
		(width 0.1143)
		(layer "In2.Cu")
		(net "P3E_CPU0_P4_TX_DP<0>")
	)
	(segment
		(start 330.33208 -308.095396)
		(end 324.87489 -310.04764)
		(width 0.14224)
		(layer "In15.Cu")
		(net "P3E_CPU0_P4_TX_DP<0>")
	)
	(segment
		(start 255.0541 -206.108554)
		(end 255.0541 -205.681834)
		(width 0.14224)
		(layer "In15.Cu")
		(net "P3E_CPU0_P4_TX_DP<0>")
	)
	(segment
		(start 255.0541 -209.491834)
		(end 255.0541 -209.065114)
		(width 0.14224)
		(layer "In15.Cu")
		(net "P3E_CPU0_P4_TX_DP<0>")
	)
	(segment
		(start 254.91694 -211.884514)
		(end 255.0541 -211.747354)
		(width 0.14224)
		(layer "In15.Cu")
		(net "P3E_CPU0_P4_TX_DP<0>")
	)
	(segment
		(start 309.206646 -319.927224)
		(end 268.983206 -319.75171)
		(width 0.14224)
		(layer "In15.Cu")
		(net "P3E_CPU0_P4_TX_DP<0>")
	)
	(segment
		(start 324.87489 -310.04764)
		(end 317.185802 -313.473338)
		(width 0.14224)
		(layer "In15.Cu")
		(net "P3E_CPU0_P4_TX_DP<0>")
	)
	(segment
		(start 266.450826 -319.523872)
		(end 265.392408 -319.337182)
		(width 0.14224)
		(layer "In15.Cu")
		(net "P3E_CPU0_P4_TX_DP<0>")
	)
	(segment
		(start 254.91694 -203.990194)
		(end 255.0541 -203.853034)
		(width 0.14224)
		(layer "In15.Cu")
		(net "P3E_CPU0_P4_TX_DP<0>")
	)
	(segment
		(start 254.91694 -207.800194)
		(end 254.91694 -207.373474)
		(width 0.14224)
		(layer "In15.Cu")
		(net "P3E_CPU0_P4_TX_DP<0>")
	)
	(segment
		(start 268.983206 -319.75171)
		(end 266.450826 -319.523872)
		(width 0.14224)
		(layer "In15.Cu")
		(net "P3E_CPU0_P4_TX_DP<0>")
	)
	(segment
		(start 254.91694 -202.862434)
		(end 255.068324 -202.579478)
		(width 0.14224)
		(layer "In15.Cu")
		(net "P3E_CPU0_P4_TX_DP<0>")
	)
	(segment
		(start 254.91694 -203.289154)
		(end 254.91694 -202.862434)
		(width 0.14224)
		(layer "In15.Cu")
		(net "P3E_CPU0_P4_TX_DP<0>")
	)
	(segment
		(start 254.91694 -208.501234)
		(end 255.0541 -208.364074)
		(width 0.14224)
		(layer "In15.Cu")
		(net "P3E_CPU0_P4_TX_DP<0>")
	)
	(segment
		(start 255.0541 -209.065114)
		(end 254.91694 -208.927954)
		(width 0.14224)
		(layer "In15.Cu")
		(net "P3E_CPU0_P4_TX_DP<0>")
	)
	(segment
		(start 255.0541 -207.937354)
		(end 254.91694 -207.800194)
		(width 0.14224)
		(layer "In15.Cu")
		(net "P3E_CPU0_P4_TX_DP<0>")
	)
	(segment
		(start 254.91694 -209.628994)
		(end 255.0541 -209.491834)
		(width 0.14224)
		(layer "In15.Cu")
		(net "P3E_CPU0_P4_TX_DP<0>")
	)
	(segment
		(start 254.91694 -207.373474)
		(end 255.0541 -207.236314)
		(width 0.14224)
		(layer "In15.Cu")
		(net "P3E_CPU0_P4_TX_DP<0>")
	)
	(segment
		(start 255.0541 -205.681834)
		(end 254.91694 -205.544674)
		(width 0.14224)
		(layer "In15.Cu")
		(net "P3E_CPU0_P4_TX_DP<0>")
	)
	(segment
		(start 254.91694 -211.183474)
		(end 254.91694 -210.756754)
		(width 0.14224)
		(layer "In15.Cu")
		(net "P3E_CPU0_P4_TX_DP<0>")
	)
	(segment
		(start 254.91694 -210.756754)
		(end 255.0541 -210.619594)
		(width 0.14224)
		(layer "In15.Cu")
		(net "P3E_CPU0_P4_TX_DP<0>")
	)
	(segment
		(start 254.91694 -224.674176)
		(end 254.91694 -211.884514)
		(width 0.14224)
		(layer "In15.Cu")
		(net "P3E_CPU0_P4_TX_DP<0>")
	)
	(segment
		(start 254.91694 -205.544674)
		(end 254.91694 -205.117954)
		(width 0.14224)
		(layer "In15.Cu")
		(net "P3E_CPU0_P4_TX_DP<0>")
	)
	(segment
		(start 255.0541 -211.320634)
		(end 254.91694 -211.183474)
		(width 0.14224)
		(layer "In15.Cu")
		(net "P3E_CPU0_P4_TX_DP<0>")
	)
	(segment
		(start 264.825988 -318.637666)
		(end 263.713468 -313.047126)
		(width 0.14224)
		(layer "In15.Cu")
		(net "P3E_CPU0_P4_TX_DP<0>")
	)
	(segment
		(start 311.334404 -319.32499)
		(end 310.508396 -319.666874)
		(width 0.14224)
		(layer "In15.Cu")
		(net "P3E_CPU0_P4_TX_DP<0>")
	)
	(segment
		(start 254.91694 -206.672434)
		(end 254.91694 -206.245714)
		(width 0.14224)
		(layer "In15.Cu")
		(net "P3E_CPU0_P4_TX_DP<0>")
	)
	(segment
		(start 263.195308 -308.56555)
		(end 262.881872 -299.283374)
		(width 0.14224)
		(layer "In15.Cu")
		(net "P3E_CPU0_P4_TX_DP<0>")
	)
	(segment
		(start 334.176878 -303.817528)
		(end 333.886048 -304.108358)
		(width 0.14224)
		(layer "In15.Cu")
		(net "P3E_CPU0_P4_TX_DP<0>")
	)
	(segment
		(start 255.0541 -206.809594)
		(end 254.91694 -206.672434)
		(width 0.14224)
		(layer "In15.Cu")
		(net "P3E_CPU0_P4_TX_DP<0>")
	)
	(segment
		(start 255.0541 -204.980794)
		(end 255.0541 -204.554074)
		(width 0.14224)
		(layer "In15.Cu")
		(net "P3E_CPU0_P4_TX_DP<0>")
	)
	(segment
		(start 255.068324 -202.579478)
		(end 255.326388 -202.406758)
		(width 0.14224)
		(layer "In15.Cu")
		(net "P3E_CPU0_P4_TX_DP<0>")
	)
	(segment
		(start 265.392408 -319.337182)
		(end 265.268202 -319.272666)
		(width 0.14224)
		(layer "In15.Cu")
		(net "P3E_CPU0_P4_TX_DP<0>")
	)
	(segment
		(start 255.0541 -207.236314)
		(end 255.0541 -206.809594)
		(width 0.14224)
		(layer "In15.Cu")
		(net "P3E_CPU0_P4_TX_DP<0>")
	)
	(segment
		(start 332.76159 -304.661824)
		(end 331.259434 -307.168042)
		(width 0.14224)
		(layer "In15.Cu")
		(net "P3E_CPU0_P4_TX_DP<0>")
	)
	(segment
		(start 254.91694 -210.055714)
		(end 254.91694 -209.628994)
		(width 0.14224)
		(layer "In15.Cu")
		(net "P3E_CPU0_P4_TX_DP<0>")
	)
	(segment
		(start 333.315056 -304.108358)
		(end 332.76159 -304.661824)
		(width 0.14224)
		(layer "In15.Cu")
		(net "P3E_CPU0_P4_TX_DP<0>")
	)
	(segment
		(start 265.046206 -319.050162)
		(end 264.825988 -318.637666)
		(width 0.14224)
		(layer "In15.Cu")
		(net "P3E_CPU0_P4_TX_DP<0>")
	)
	(segment
		(start 333.886048 -304.108358)
		(end 333.315056 -304.108358)
		(width 0.14224)
		(layer "In15.Cu")
		(net "P3E_CPU0_P4_TX_DP<0>")
	)
	(segment
		(start 255.0541 -210.192874)
		(end 254.91694 -210.055714)
		(width 0.14224)
		(layer "In15.Cu")
		(net "P3E_CPU0_P4_TX_DP<0>")
	)
	(segment
		(start 255.0541 -204.554074)
		(end 254.91694 -204.416914)
		(width 0.14224)
		(layer "In15.Cu")
		(net "P3E_CPU0_P4_TX_DP<0>")
	)
	(segment
		(start 255.0541 -208.364074)
		(end 255.0541 -207.937354)
		(width 0.14224)
		(layer "In15.Cu")
		(net "P3E_CPU0_P4_TX_DP<0>")
	)
	(segment
		(start 255.0541 -203.426314)
		(end 254.91694 -203.289154)
		(width 0.14224)
		(layer "In15.Cu")
		(net "P3E_CPU0_P4_TX_DP<0>")
	)
	(segment
		(start 255.0541 -211.747354)
		(end 255.0541 -211.320634)
		(width 0.14224)
		(layer "In15.Cu")
		(net "P3E_CPU0_P4_TX_DP<0>")
	)
	(segment
		(start 255.326388 -202.406758)
		(end 255.441196 -202.371706)
		(width 0.14224)
		(layer "In15.Cu")
		(net "P3E_CPU0_P4_TX_DP<0>")
	)
	(segment
		(start 254.91694 -205.117954)
		(end 255.0541 -204.980794)
		(width 0.14224)
		(layer "In15.Cu")
		(net "P3E_CPU0_P4_TX_DP<0>")
	)
	(segment
		(start 317.185802 -313.473338)
		(end 311.334404 -319.32499)
		(width 0.14224)
		(layer "In15.Cu")
		(net "P3E_CPU0_P4_TX_DP<0>")
	)
	(segment
		(start 254.91694 -204.416914)
		(end 254.91694 -203.990194)
		(width 0.14224)
		(layer "In15.Cu")
		(net "P3E_CPU0_P4_TX_DP<0>")
	)
	(segment
		(start 255.0541 -203.853034)
		(end 255.0541 -203.426314)
		(width 0.14224)
		(layer "In15.Cu")
		(net "P3E_CPU0_P4_TX_DP<0>")
	)
	(segment
		(start 254.91694 -206.245714)
		(end 255.0541 -206.108554)
		(width 0.14224)
		(layer "In15.Cu")
		(net "P3E_CPU0_P4_TX_DP<0>")
	)
	(segment
		(start 310.508396 -319.666874)
		(end 309.206646 -319.927224)
		(width 0.14224)
		(layer "In15.Cu")
		(net "P3E_CPU0_P4_TX_DP<0>")
	)
	(segment
		(start 260.122924 -265.200384)
		(end 254.91694 -224.674176)
		(width 0.14224)
		(layer "In15.Cu")
		(net "P3E_CPU0_P4_TX_DP<0>")
	)
	(segment
		(start 262.881872 -299.283374)
		(end 260.122924 -265.200384)
		(width 0.14224)
		(layer "In15.Cu")
		(net "P3E_CPU0_P4_TX_DP<0>")
	)
	(segment
		(start 254.91694 -208.927954)
		(end 254.91694 -208.501234)
		(width 0.14224)
		(layer "In15.Cu")
		(net "P3E_CPU0_P4_TX_DP<0>")
	)
	(segment
		(start 255.0541 -210.619594)
		(end 255.0541 -210.192874)
		(width 0.14224)
		(layer "In15.Cu")
		(net "P3E_CPU0_P4_TX_DP<0>")
	)
	(segment
		(start 265.268202 -319.272666)
		(end 265.046206 -319.050162)
		(width 0.14224)
		(layer "In15.Cu")
		(net "P3E_CPU0_P4_TX_DP<0>")
	)
	(segment
		(start 255.636268 -202.371706)
		(end 255.927098 -202.662536)
		(width 0.14224)
		(layer "In15.Cu")
		(net "P3E_CPU0_P4_TX_DP<0>")
	)
	(segment
		(start 263.713468 -313.047126)
		(end 263.195308 -308.56555)
		(width 0.14224)
		(layer "In15.Cu")
		(net "P3E_CPU0_P4_TX_DP<0>")
	)
	(segment
		(start 255.441196 -202.371706)
		(end 255.636268 -202.371706)
		(width 0.14224)
		(layer "In15.Cu")
		(net "P3E_CPU0_P4_TX_DP<0>")
	)
	(segment
		(start 331.259434 -307.168042)
		(end 330.33208 -308.095396)
		(width 0.14224)
		(layer "In15.Cu")
		(net "P3E_CPU0_P4_TX_DP<0>")
	)
	(segment
		(start 240.65103 -57.98312)
		(end 240.919762 -58.251598)
		(width 0.12954)
		(layer "F.Cu")
		(net "P3E_CPU0_P4_TX_DN<3>")
	)
	(segment
		(start 240.919762 -58.251598)
		(end 241.025934 -58.451496)
		(width 0.12954)
		(layer "F.Cu")
		(net "P3E_CPU0_P4_TX_DN<3>")
	)
	(segment
		(start 246.102886 -137.827258)
		(end 247.350788 -147.880578)
		(width 0.12954)
		(layer "F.Cu")
		(net "P3E_CPU0_P4_TX_DN<3>")
	)
	(segment
		(start 355.78796 -292.450012)
		(end 355.321108 -292.71595)
		(width 0.12954)
		(layer "F.Cu")
		(net "P3E_CPU0_P4_TX_DN<3>")
	)
	(segment
		(start 239.419384 -57.41289)
		(end 239.715294 -57.7088)
		(width 0.12954)
		(layer "F.Cu")
		(net "P3E_CPU0_P4_TX_DN<3>")
	)
	(segment
		(start 254.610616 -192.757298)
		(end 254.852678 -193.24574)
		(width 0.12954)
		(layer "F.Cu")
		(net "P3E_CPU0_P4_TX_DN<3>")
	)
	(segment
		(start 247.350788 -147.880578)
		(end 254.610616 -192.757298)
		(width 0.12954)
		(layer "F.Cu")
		(net "P3E_CPU0_P4_TX_DN<3>")
	)
	(segment
		(start 241.025934 -58.451496)
		(end 242.28044 -64.757808)
		(width 0.12954)
		(layer "F.Cu")
		(net "P3E_CPU0_P4_TX_DN<3>")
	)
	(segment
		(start 255.641348 -193.718434)
		(end 255.927098 -193.432684)
		(width 0.12954)
		(layer "F.Cu")
		(net "P3E_CPU0_P4_TX_DN<3>")
	)
	(segment
		(start 255.325372 -193.718434)
		(end 255.641348 -193.718434)
		(width 0.12954)
		(layer "F.Cu")
		(net "P3E_CPU0_P4_TX_DN<3>")
	)
	(segment
		(start 254.852678 -193.24574)
		(end 255.325372 -193.718434)
		(width 0.12954)
		(layer "F.Cu")
		(net "P3E_CPU0_P4_TX_DN<3>")
	)
	(segment
		(start 239.715294 -57.7088)
		(end 239.988852 -57.7088)
		(width 0.12954)
		(layer "F.Cu")
		(net "P3E_CPU0_P4_TX_DN<3>")
	)
	(segment
		(start 242.28044 -64.757808)
		(end 246.102886 -137.827258)
		(width 0.12954)
		(layer "F.Cu")
		(net "P3E_CPU0_P4_TX_DN<3>")
	)
	(segment
		(start 239.988852 -57.7088)
		(end 240.65103 -57.98312)
		(width 0.12954)
		(layer "F.Cu")
		(net "P3E_CPU0_P4_TX_DN<3>")
	)
	(segment
		(start 354.946966 -296.494962)
		(end 355.91623 -297.464226)
		(width 0.14224)
		(layer "In2.Cu")
		(net "P3E_CPU0_P4_TX_DN<3>")
	)
	(segment
		(start 354.792534 -295.60647)
		(end 354.901246 -295.811194)
		(width 0.1143)
		(layer "In2.Cu")
		(net "P3E_CPU0_P4_TX_DN<3>")
	)
	(segment
		(start 349.318834 -311.099962)
		(end 349.090996 -311.221882)
		(width 0.14224)
		(layer "In2.Cu")
		(net "P3E_CPU0_P4_TX_DN<3>")
	)
	(segment
		(start 354.946966 -296.425112)
		(end 354.946966 -296.494962)
		(width 0.14224)
		(layer "In2.Cu")
		(net "P3E_CPU0_P4_TX_DN<3>")
	)
	(segment
		(start 354.901246 -296.350944)
		(end 354.946966 -296.396664)
		(width 0.1143)
		(layer "In2.Cu")
		(net "P3E_CPU0_P4_TX_DN<3>")
	)
	(segment
		(start 354.953316 -292.7858)
		(end 354.953062 -292.7858)
		(width 0.1143)
		(layer "In2.Cu")
		(net "P3E_CPU0_P4_TX_DN<3>")
	)
	(segment
		(start 348.445836 -311.221882)
		(end 348.15399 -311.513728)
		(width 0.14224)
		(layer "In2.Cu")
		(net "P3E_CPU0_P4_TX_DN<3>")
	)
	(segment
		(start 352.222562 -306.75453)
		(end 349.318834 -311.099962)
		(width 0.14224)
		(layer "In2.Cu")
		(net "P3E_CPU0_P4_TX_DN<3>")
	)
	(segment
		(start 354.701602 -294.801544)
		(end 354.632514 -294.84193)
		(width 0.1143)
		(layer "In2.Cu")
		(net "P3E_CPU0_P4_TX_DN<3>")
	)
	(segment
		(start 355.91623 -297.464226)
		(end 355.91623 -301.226474)
		(width 0.14224)
		(layer "In2.Cu")
		(net "P3E_CPU0_P4_TX_DN<3>")
	)
	(segment
		(start 355.13899 -293.041578)
		(end 355.139498 -293.041578)
		(width 0.1143)
		(layer "In2.Cu")
		(net "P3E_CPU0_P4_TX_DN<3>")
	)
	(segment
		(start 355.321108 -292.71595)
		(end 355.023166 -292.71595)
		(width 0.1143)
		(layer "In2.Cu")
		(net "P3E_CPU0_P4_TX_DN<3>")
	)
	(segment
		(start 354.946966 -296.396664)
		(end 354.946966 -296.425112)
		(width 0.1143)
		(layer "In2.Cu")
		(net "P3E_CPU0_P4_TX_DN<3>")
	)
	(segment
		(start 355.102668 -293.020242)
		(end 355.107494 -293.023036)
		(width 0.1143)
		(layer "In2.Cu")
		(net "P3E_CPU0_P4_TX_DN<3>")
	)
	(segment
		(start 355.107494 -293.023036)
		(end 355.110034 -293.02456)
		(width 0.1143)
		(layer "In2.Cu")
		(net "P3E_CPU0_P4_TX_DN<3>")
	)
	(segment
		(start 355.126798 -294.017446)
		(end 355.102414 -294.031924)
		(width 0.1143)
		(layer "In2.Cu")
		(net "P3E_CPU0_P4_TX_DN<3>")
	)
	(segment
		(start 355.143562 -294.007794)
		(end 355.134164 -294.01389)
		(width 0.1143)
		(layer "In2.Cu")
		(net "P3E_CPU0_P4_TX_DN<3>")
	)
	(segment
		(start 354.60813 -295.450006)
		(end 354.792534 -295.60647)
		(width 0.1143)
		(layer "In2.Cu")
		(net "P3E_CPU0_P4_TX_DN<3>")
	)
	(segment
		(start 355.110034 -293.02456)
		(end 355.125528 -293.033958)
		(width 0.1143)
		(layer "In2.Cu")
		(net "P3E_CPU0_P4_TX_DN<3>")
	)
	(segment
		(start 352.222308 -306.754276)
		(end 352.222562 -306.75453)
		(width 0.14224)
		(layer "In2.Cu")
		(net "P3E_CPU0_P4_TX_DN<3>")
	)
	(segment
		(start 355.139498 -293.041578)
		(end 355.172518 -293.060628)
		(width 0.1143)
		(layer "In2.Cu")
		(net "P3E_CPU0_P4_TX_DN<3>")
	)
	(segment
		(start 355.023166 -292.71595)
		(end 354.953316 -292.7858)
		(width 0.1143)
		(layer "In2.Cu")
		(net "P3E_CPU0_P4_TX_DN<3>")
	)
	(segment
		(start 354.901246 -295.811194)
		(end 354.901246 -296.350944)
		(width 0.1143)
		(layer "In2.Cu")
		(net "P3E_CPU0_P4_TX_DN<3>")
	)
	(segment
		(start 355.125528 -293.033958)
		(end 355.13899 -293.041578)
		(width 0.1143)
		(layer "In2.Cu")
		(net "P3E_CPU0_P4_TX_DN<3>")
	)
	(segment
		(start 355.172518 -293.991284)
		(end 355.143562 -294.007794)
		(width 0.1143)
		(layer "In2.Cu")
		(net "P3E_CPU0_P4_TX_DN<3>")
	)
	(segment
		(start 355.91623 -301.226474)
		(end 352.222308 -306.754276)
		(width 0.14224)
		(layer "In2.Cu")
		(net "P3E_CPU0_P4_TX_DN<3>")
	)
	(segment
		(start 355.134164 -294.01389)
		(end 355.126798 -294.017446)
		(width 0.1143)
		(layer "In2.Cu")
		(net "P3E_CPU0_P4_TX_DN<3>")
	)
	(segment
		(start 349.090996 -311.221882)
		(end 348.445836 -311.221882)
		(width 0.14224)
		(layer "In2.Cu")
		(net "P3E_CPU0_P4_TX_DN<3>")
	)
	(arc
		(start 354.953062 -292.7858)
		(mid 355.005289 -292.917432)
		(end 355.102668 -293.020242)
		(width 0.1143)
		(layer "In2.Cu")
		(net "P3E_CPU0_P4_TX_DN<3>")
	)
	(arc
		(start 354.632514 -294.84193)
		(mid 354.472018 -295.140066)
		(end 354.60813 -295.450006)
		(width 0.1143)
		(layer "In2.Cu")
		(net "P3E_CPU0_P4_TX_DN<3>")
	)
	(arc
		(start 355.172518 -293.060628)
		(mid 355.416581 -293.525956)
		(end 355.172518 -293.991284)
		(width 0.1143)
		(layer "In2.Cu")
		(net "P3E_CPU0_P4_TX_DN<3>")
	)
	(arc
		(start 355.102414 -294.031924)
		(mid 354.987571 -294.165072)
		(end 354.946204 -294.335962)
		(width 0.1143)
		(layer "In2.Cu")
		(net "P3E_CPU0_P4_TX_DN<3>")
	)
	(arc
		(start 354.946204 -294.335962)
		(mid 354.881386 -294.598951)
		(end 354.701602 -294.801544)
		(width 0.1143)
		(layer "In2.Cu")
		(net "P3E_CPU0_P4_TX_DN<3>")
	)
	(segment
		(start 347.86316 -311.222898)
		(end 346.754704 -311.222898)
		(width 0.14224)
		(layer "In15.Cu")
		(net "P3E_CPU0_P4_TX_DN<3>")
	)
	(segment
		(start 259.363972 -315.725556)
		(end 258.392168 -286.96158)
		(width 0.14224)
		(layer "In15.Cu")
		(net "P3E_CPU0_P4_TX_DN<3>")
	)
	(segment
		(start 318.56934 -316.605412)
		(end 313.313318 -321.861434)
		(width 0.14224)
		(layer "In15.Cu")
		(net "P3E_CPU0_P4_TX_DN<3>")
	)
	(segment
		(start 253.504446 -195.163948)
		(end 254.691388 -194.088512)
		(width 0.14224)
		(layer "In15.Cu")
		(net "P3E_CPU0_P4_TX_DN<3>")
	)
	(segment
		(start 255.100836 -193.814954)
		(end 255.40208 -193.723514)
		(width 0.14224)
		(layer "In15.Cu")
		(net "P3E_CPU0_P4_TX_DN<3>")
	)
	(segment
		(start 255.40208 -193.723514)
		(end 255.636268 -193.723514)
		(width 0.14224)
		(layer "In15.Cu")
		(net "P3E_CPU0_P4_TX_DN<3>")
	)
	(segment
		(start 346.754704 -311.222898)
		(end 342.670384 -312.914538)
		(width 0.14224)
		(layer "In15.Cu")
		(net "P3E_CPU0_P4_TX_DN<3>")
	)
	(segment
		(start 250.852432 -200.95972)
		(end 252.480318 -196.411342)
		(width 0.14224)
		(layer "In15.Cu")
		(net "P3E_CPU0_P4_TX_DN<3>")
	)
	(segment
		(start 258.392168 -286.96158)
		(end 250.852432 -218.948)
		(width 0.14224)
		(layer "In15.Cu")
		(net "P3E_CPU0_P4_TX_DN<3>")
	)
	(segment
		(start 313.313318 -321.861434)
		(end 311.277 -322.704714)
		(width 0.14224)
		(layer "In15.Cu")
		(net "P3E_CPU0_P4_TX_DN<3>")
	)
	(segment
		(start 264.242296 -322.88353)
		(end 263.137904 -322.66001)
		(width 0.14224)
		(layer "In15.Cu")
		(net "P3E_CPU0_P4_TX_DN<3>")
	)
	(segment
		(start 320.670936 -315.725556)
		(end 319.359788 -316.13221)
		(width 0.14224)
		(layer "In15.Cu")
		(net "P3E_CPU0_P4_TX_DN<3>")
	)
	(segment
		(start 250.852432 -218.948)
		(end 250.852432 -200.95972)
		(width 0.14224)
		(layer "In15.Cu")
		(net "P3E_CPU0_P4_TX_DN<3>")
	)
	(segment
		(start 311.277 -322.704714)
		(end 309.394606 -323.081142)
		(width 0.14224)
		(layer "In15.Cu")
		(net "P3E_CPU0_P4_TX_DN<3>")
	)
	(segment
		(start 342.670384 -312.914538)
		(end 330.208382 -314.176918)
		(width 0.14224)
		(layer "In15.Cu")
		(net "P3E_CPU0_P4_TX_DN<3>")
	)
	(segment
		(start 262.414512 -322.358512)
		(end 261.38886 -321.671442)
		(width 0.14224)
		(layer "In15.Cu")
		(net "P3E_CPU0_P4_TX_DN<3>")
	)
	(segment
		(start 348.15399 -311.513728)
		(end 347.86316 -311.222898)
		(width 0.14224)
		(layer "In15.Cu")
		(net "P3E_CPU0_P4_TX_DN<3>")
	)
	(segment
		(start 319.359788 -316.13221)
		(end 318.56934 -316.605412)
		(width 0.14224)
		(layer "In15.Cu")
		(net "P3E_CPU0_P4_TX_DN<3>")
	)
	(segment
		(start 263.137904 -322.66001)
		(end 262.414512 -322.358512)
		(width 0.14224)
		(layer "In15.Cu")
		(net "P3E_CPU0_P4_TX_DN<3>")
	)
	(segment
		(start 260.275578 -319.77076)
		(end 259.363972 -315.725556)
		(width 0.14224)
		(layer "In15.Cu")
		(net "P3E_CPU0_P4_TX_DN<3>")
	)
	(segment
		(start 261.38886 -321.671442)
		(end 260.879844 -321.162426)
		(width 0.14224)
		(layer "In15.Cu")
		(net "P3E_CPU0_P4_TX_DN<3>")
	)
	(segment
		(start 260.879844 -321.162426)
		(end 260.275578 -319.77076)
		(width 0.14224)
		(layer "In15.Cu")
		(net "P3E_CPU0_P4_TX_DN<3>")
	)
	(segment
		(start 252.480318 -196.411342)
		(end 253.504446 -195.163948)
		(width 0.14224)
		(layer "In15.Cu")
		(net "P3E_CPU0_P4_TX_DN<3>")
	)
	(segment
		(start 255.636268 -193.723514)
		(end 255.927098 -193.432684)
		(width 0.14224)
		(layer "In15.Cu")
		(net "P3E_CPU0_P4_TX_DN<3>")
	)
	(segment
		(start 309.394606 -323.081142)
		(end 264.242296 -322.88353)
		(width 0.14224)
		(layer "In15.Cu")
		(net "P3E_CPU0_P4_TX_DN<3>")
	)
	(segment
		(start 254.691388 -194.088512)
		(end 255.100836 -193.814954)
		(width 0.14224)
		(layer "In15.Cu")
		(net "P3E_CPU0_P4_TX_DN<3>")
	)
	(segment
		(start 330.208382 -314.176918)
		(end 320.670936 -315.725556)
		(width 0.14224)
		(layer "In15.Cu")
		(net "P3E_CPU0_P4_TX_DN<3>")
	)
	(segment
		(start 241.881152 -56.717438)
		(end 241.779552 -56.963056)
		(width 0.12954)
		(layer "F.Cu")
		(net "P3E_CPU0_P4_TX_DN<2>")
	)
	(segment
		(start 257.182874 -193.245994)
		(end 257.182874 -193.632074)
		(width 0.12954)
		(layer "F.Cu")
		(net "P3E_CPU0_P4_TX_DN<2>")
	)
	(segment
		(start 242.646454 -61.105288)
		(end 242.646454 -61.491368)
		(width 0.12954)
		(layer "F.Cu")
		(net "P3E_CPU0_P4_TX_DN<2>")
	)
	(segment
		(start 241.604038 -56.231282)
		(end 241.733578 -56.360822)
		(width 0.12954)
		(layer "F.Cu")
		(net "P3E_CPU0_P4_TX_DN<2>")
	)
	(segment
		(start 242.455954 -60.914788)
		(end 242.646454 -61.105288)
		(width 0.12954)
		(layer "F.Cu")
		(net "P3E_CPU0_P4_TX_DN<2>")
	)
	(segment
		(start 257.182874 -189.808612)
		(end 257.182874 -192.478914)
		(width 0.12954)
		(layer "F.Cu")
		(net "P3E_CPU0_P4_TX_DN<2>")
	)
	(segment
		(start 242.646454 -61.491368)
		(end 242.455954 -61.681868)
		(width 0.12954)
		(layer "F.Cu")
		(net "P3E_CPU0_P4_TX_DN<2>")
	)
	(segment
		(start 257.113024 -196.008244)
		(end 256.715768 -196.4055)
		(width 0.12954)
		(layer "F.Cu")
		(net "P3E_CPU0_P4_TX_DN<2>")
	)
	(segment
		(start 242.646454 -59.952128)
		(end 242.646454 -60.338208)
		(width 0.12954)
		(layer "F.Cu")
		(net "P3E_CPU0_P4_TX_DN<2>")
	)
	(segment
		(start 256.992374 -194.975734)
		(end 256.992374 -195.361814)
		(width 0.12954)
		(layer "F.Cu")
		(net "P3E_CPU0_P4_TX_DN<2>")
	)
	(segment
		(start 257.182874 -193.632074)
		(end 256.992374 -193.822574)
		(width 0.12954)
		(layer "F.Cu")
		(net "P3E_CPU0_P4_TX_DN<2>")
	)
	(segment
		(start 257.182874 -194.399154)
		(end 257.182874 -194.785234)
		(width 0.12954)
		(layer "F.Cu")
		(net "P3E_CPU0_P4_TX_DN<2>")
	)
	(segment
		(start 256.992374 -192.669414)
		(end 256.992374 -193.055494)
		(width 0.12954)
		(layer "F.Cu")
		(net "P3E_CPU0_P4_TX_DN<2>")
	)
	(segment
		(start 241.733578 -56.360822)
		(end 241.881152 -56.717438)
		(width 0.12954)
		(layer "F.Cu")
		(net "P3E_CPU0_P4_TX_DN<2>")
	)
	(segment
		(start 242.646454 -59.185048)
		(end 242.455954 -59.375548)
		(width 0.12954)
		(layer "F.Cu")
		(net "P3E_CPU0_P4_TX_DN<2>")
	)
	(segment
		(start 257.182874 -195.552314)
		(end 257.182874 -195.840096)
		(width 0.12954)
		(layer "F.Cu")
		(net "P3E_CPU0_P4_TX_DN<2>")
	)
	(segment
		(start 242.455954 -62.067948)
		(end 242.646454 -62.258448)
		(width 0.12954)
		(layer "F.Cu")
		(net "P3E_CPU0_P4_TX_DN<2>")
	)
	(segment
		(start 246.542814 -137.41146)
		(end 247.885712 -147.358354)
		(width 0.12954)
		(layer "F.Cu")
		(net "P3E_CPU0_P4_TX_DN<2>")
	)
	(segment
		(start 242.455954 -59.761628)
		(end 242.646454 -59.952128)
		(width 0.12954)
		(layer "F.Cu")
		(net "P3E_CPU0_P4_TX_DN<2>")
	)
	(segment
		(start 242.172998 -57.421526)
		(end 242.646454 -58.56478)
		(width 0.12954)
		(layer "F.Cu")
		(net "P3E_CPU0_P4_TX_DN<2>")
	)
	(segment
		(start 256.992374 -193.822574)
		(end 256.992374 -194.208654)
		(width 0.12954)
		(layer "F.Cu")
		(net "P3E_CPU0_P4_TX_DN<2>")
	)
	(segment
		(start 257.182874 -195.840096)
		(end 257.113024 -196.008244)
		(width 0.12954)
		(layer "F.Cu")
		(net "P3E_CPU0_P4_TX_DN<2>")
	)
	(segment
		(start 256.992374 -194.208654)
		(end 257.182874 -194.399154)
		(width 0.12954)
		(layer "F.Cu")
		(net "P3E_CPU0_P4_TX_DN<2>")
	)
	(segment
		(start 256.715768 -196.4055)
		(end 256.544318 -196.47662)
		(width 0.12954)
		(layer "F.Cu")
		(net "P3E_CPU0_P4_TX_DN<2>")
	)
	(segment
		(start 242.455954 -61.681868)
		(end 242.455954 -62.067948)
		(width 0.12954)
		(layer "F.Cu")
		(net "P3E_CPU0_P4_TX_DN<2>")
	)
	(segment
		(start 241.927126 -57.319926)
		(end 242.172998 -57.421526)
		(width 0.12954)
		(layer "F.Cu")
		(net "P3E_CPU0_P4_TX_DN<2>")
	)
	(segment
		(start 242.646454 -58.56478)
		(end 242.646454 -59.185048)
		(width 0.12954)
		(layer "F.Cu")
		(net "P3E_CPU0_P4_TX_DN<2>")
	)
	(segment
		(start 256.992374 -195.361814)
		(end 257.182874 -195.552314)
		(width 0.12954)
		(layer "F.Cu")
		(net "P3E_CPU0_P4_TX_DN<2>")
	)
	(segment
		(start 257.182874 -192.478914)
		(end 256.992374 -192.669414)
		(width 0.12954)
		(layer "F.Cu")
		(net "P3E_CPU0_P4_TX_DN<2>")
	)
	(segment
		(start 256.992374 -193.055494)
		(end 257.182874 -193.245994)
		(width 0.12954)
		(layer "F.Cu")
		(net "P3E_CPU0_P4_TX_DN<2>")
	)
	(segment
		(start 241.417094 -56.231282)
		(end 241.604038 -56.231282)
		(width 0.12954)
		(layer "F.Cu")
		(net "P3E_CPU0_P4_TX_DN<2>")
	)
	(segment
		(start 247.885712 -147.358354)
		(end 257.182874 -189.808612)
		(width 0.12954)
		(layer "F.Cu")
		(net "P3E_CPU0_P4_TX_DN<2>")
	)
	(segment
		(start 242.646454 -62.258448)
		(end 242.646454 -62.93866)
		(width 0.12954)
		(layer "F.Cu")
		(net "P3E_CPU0_P4_TX_DN<2>")
	)
	(segment
		(start 256.544318 -196.47662)
		(end 256.193798 -196.47662)
		(width 0.12954)
		(layer "F.Cu")
		(net "P3E_CPU0_P4_TX_DN<2>")
	)
	(segment
		(start 242.455954 -59.375548)
		(end 242.455954 -59.761628)
		(width 0.12954)
		(layer "F.Cu")
		(net "P3E_CPU0_P4_TX_DN<2>")
	)
	(segment
		(start 242.646454 -62.93866)
		(end 246.542814 -137.41146)
		(width 0.12954)
		(layer "F.Cu")
		(net "P3E_CPU0_P4_TX_DN<2>")
	)
	(segment
		(start 352.968052 -292.450012)
		(end 352.5012 -292.71595)
		(width 0.12954)
		(layer "F.Cu")
		(net "P3E_CPU0_P4_TX_DN<2>")
	)
	(segment
		(start 241.779552 -56.963056)
		(end 241.927126 -57.319926)
		(width 0.12954)
		(layer "F.Cu")
		(net "P3E_CPU0_P4_TX_DN<2>")
	)
	(segment
		(start 256.193798 -196.47662)
		(end 255.927098 -196.20992)
		(width 0.12954)
		(layer "F.Cu")
		(net "P3E_CPU0_P4_TX_DN<2>")
	)
	(segment
		(start 257.182874 -194.785234)
		(end 256.992374 -194.975734)
		(width 0.12954)
		(layer "F.Cu")
		(net "P3E_CPU0_P4_TX_DN<2>")
	)
	(segment
		(start 242.455954 -60.528708)
		(end 242.455954 -60.914788)
		(width 0.12954)
		(layer "F.Cu")
		(net "P3E_CPU0_P4_TX_DN<2>")
	)
	(segment
		(start 241.121184 -56.527192)
		(end 241.417094 -56.231282)
		(width 0.12954)
		(layer "F.Cu")
		(net "P3E_CPU0_P4_TX_DN<2>")
	)
	(segment
		(start 242.646454 -60.338208)
		(end 242.455954 -60.528708)
		(width 0.12954)
		(layer "F.Cu")
		(net "P3E_CPU0_P4_TX_DN<2>")
	)
	(segment
		(start 352.282506 -294.640254)
		(end 352.313494 -294.658034)
		(width 0.1143)
		(layer "In2.Cu")
		(net "P3E_CPU0_P4_TX_DN<2>")
	)
	(segment
		(start 352.5012 -292.71595)
		(end 352.203258 -292.71595)
		(width 0.1143)
		(layer "In2.Cu")
		(net "P3E_CPU0_P4_TX_DN<2>")
	)
	(segment
		(start 352.256598 -298.07662)
		(end 352.256598 -301.016924)
		(width 0.14224)
		(layer "In2.Cu")
		(net "P3E_CPU0_P4_TX_DN<2>")
	)
	(segment
		(start 352.59645 -295.799256)
		(end 351.869756 -296.52595)
		(width 0.1143)
		(layer "In2.Cu")
		(net "P3E_CPU0_P4_TX_DN<2>")
	)
	(segment
		(start 347.31452 -307.783484)
		(end 346.085668 -309.012336)
		(width 0.14224)
		(layer "In2.Cu")
		(net "P3E_CPU0_P4_TX_DN<2>")
	)
	(segment
		(start 352.310954 -294.01516)
		(end 352.310192 -294.015668)
		(width 0.1143)
		(layer "In2.Cu")
		(net "P3E_CPU0_P4_TX_DN<2>")
	)
	(segment
		(start 351.915476 -297.42765)
		(end 351.915476 -297.735498)
		(width 0.14224)
		(layer "In2.Cu")
		(net "P3E_CPU0_P4_TX_DN<2>")
	)
	(segment
		(start 352.30689 -294.017446)
		(end 352.282506 -294.03167)
		(width 0.1143)
		(layer "In2.Cu")
		(net "P3E_CPU0_P4_TX_DN<2>")
	)
	(segment
		(start 352.282506 -293.020242)
		(end 352.313494 -293.038022)
		(width 0.1143)
		(layer "In2.Cu")
		(net "P3E_CPU0_P4_TX_DN<2>")
	)
	(segment
		(start 352.313494 -294.658034)
		(end 352.314256 -294.658542)
		(width 0.1143)
		(layer "In2.Cu")
		(net "P3E_CPU0_P4_TX_DN<2>")
	)
	(segment
		(start 352.313494 -293.038022)
		(end 352.314256 -293.03853)
		(width 0.1143)
		(layer "In2.Cu")
		(net "P3E_CPU0_P4_TX_DN<2>")
	)
	(segment
		(start 351.869756 -297.353482)
		(end 351.915476 -297.399202)
		(width 0.1143)
		(layer "In2.Cu")
		(net "P3E_CPU0_P4_TX_DN<2>")
	)
	(segment
		(start 352.312732 -294.014144)
		(end 352.31197 -294.014652)
		(width 0.1143)
		(layer "In2.Cu")
		(net "P3E_CPU0_P4_TX_DN<2>")
	)
	(segment
		(start 352.256598 -301.016924)
		(end 351.559114 -302.061372)
		(width 0.14224)
		(layer "In2.Cu")
		(net "P3E_CPU0_P4_TX_DN<2>")
	)
	(segment
		(start 351.559114 -302.061372)
		(end 347.31452 -307.783484)
		(width 0.14224)
		(layer "In2.Cu")
		(net "P3E_CPU0_P4_TX_DN<2>")
	)
	(segment
		(start 351.915476 -297.399202)
		(end 351.915476 -297.42765)
		(width 0.1143)
		(layer "In2.Cu")
		(net "P3E_CPU0_P4_TX_DN<2>")
	)
	(segment
		(start 351.915476 -297.735498)
		(end 352.256598 -298.07662)
		(width 0.14224)
		(layer "In2.Cu")
		(net "P3E_CPU0_P4_TX_DN<2>")
	)
	(segment
		(start 352.203258 -292.71595)
		(end 352.133408 -292.7858)
		(width 0.1143)
		(layer "In2.Cu")
		(net "P3E_CPU0_P4_TX_DN<2>")
	)
	(segment
		(start 352.59645 -295.141904)
		(end 352.59645 -295.799256)
		(width 0.1143)
		(layer "In2.Cu")
		(net "P3E_CPU0_P4_TX_DN<2>")
	)
	(segment
		(start 351.869756 -296.52595)
		(end 351.869756 -297.353482)
		(width 0.1143)
		(layer "In2.Cu")
		(net "P3E_CPU0_P4_TX_DN<2>")
	)
	(segment
		(start 342.190832 -309.012336)
		(end 341.900002 -309.303166)
		(width 0.14224)
		(layer "In2.Cu")
		(net "P3E_CPU0_P4_TX_DN<2>")
	)
	(segment
		(start 352.353118 -293.061136)
		(end 352.376486 -293.077646)
		(width 0.1143)
		(layer "In2.Cu")
		(net "P3E_CPU0_P4_TX_DN<2>")
	)
	(segment
		(start 346.085668 -309.012336)
		(end 342.190832 -309.012336)
		(width 0.14224)
		(layer "In2.Cu")
		(net "P3E_CPU0_P4_TX_DN<2>")
	)
	(segment
		(start 352.310192 -294.015668)
		(end 352.307652 -294.016938)
		(width 0.1143)
		(layer "In2.Cu")
		(net "P3E_CPU0_P4_TX_DN<2>")
	)
	(segment
		(start 352.307652 -294.016938)
		(end 352.30689 -294.017446)
		(width 0.1143)
		(layer "In2.Cu")
		(net "P3E_CPU0_P4_TX_DN<2>")
	)
	(segment
		(start 352.353118 -293.990776)
		(end 352.312732 -294.014144)
		(width 0.1143)
		(layer "In2.Cu")
		(net "P3E_CPU0_P4_TX_DN<2>")
	)
	(segment
		(start 352.314256 -293.03853)
		(end 352.31705 -293.040308)
		(width 0.1143)
		(layer "In2.Cu")
		(net "P3E_CPU0_P4_TX_DN<2>")
	)
	(segment
		(start 352.31197 -294.014652)
		(end 352.310954 -294.01516)
		(width 0.1143)
		(layer "In2.Cu")
		(net "P3E_CPU0_P4_TX_DN<2>")
	)
	(segment
		(start 352.314256 -294.658542)
		(end 352.320352 -294.662098)
		(width 0.1143)
		(layer "In2.Cu")
		(net "P3E_CPU0_P4_TX_DN<2>")
	)
	(segment
		(start 352.31705 -293.040308)
		(end 352.353118 -293.061136)
		(width 0.1143)
		(layer "In2.Cu")
		(net "P3E_CPU0_P4_TX_DN<2>")
	)
	(segment
		(start 352.376486 -293.974266)
		(end 352.353118 -293.990776)
		(width 0.1143)
		(layer "In2.Cu")
		(net "P3E_CPU0_P4_TX_DN<2>")
	)
	(arc
		(start 352.376486 -293.077646)
		(mid 352.606316 -293.525956)
		(end 352.376486 -293.974266)
		(width 0.1143)
		(layer "In2.Cu")
		(net "P3E_CPU0_P4_TX_DN<2>")
	)
	(arc
		(start 352.282506 -294.03167)
		(mid 352.126578 -294.335962)
		(end 352.282506 -294.640254)
		(width 0.1143)
		(layer "In2.Cu")
		(net "P3E_CPU0_P4_TX_DN<2>")
	)
	(arc
		(start 352.320352 -294.662098)
		(mid 352.522479 -294.865111)
		(end 352.59645 -295.141904)
		(width 0.1143)
		(layer "In2.Cu")
		(net "P3E_CPU0_P4_TX_DN<2>")
	)
	(arc
		(start 352.133408 -292.7858)
		(mid 352.185457 -292.917319)
		(end 352.282506 -293.020242)
		(width 0.1143)
		(layer "In2.Cu")
		(net "P3E_CPU0_P4_TX_DN<2>")
	)
	(segment
		(start 339.052154 -309.012336)
		(end 334.843882 -311.00268)
		(width 0.14224)
		(layer "In15.Cu")
		(net "P3E_CPU0_P4_TX_DN<2>")
	)
	(segment
		(start 262.085328 -320.972434)
		(end 261.670546 -320.495422)
		(width 0.14224)
		(layer "In15.Cu")
		(net "P3E_CPU0_P4_TX_DN<2>")
	)
	(segment
		(start 254.75438 -196.71284)
		(end 255.266444 -196.50075)
		(width 0.14224)
		(layer "In15.Cu")
		(net "P3E_CPU0_P4_TX_DN<2>")
	)
	(segment
		(start 260.749796 -317.172594)
		(end 260.231382 -312.838084)
		(width 0.14224)
		(layer "In15.Cu")
		(net "P3E_CPU0_P4_TX_DN<2>")
	)
	(segment
		(start 252.11278 -201.360532)
		(end 253.53137 -197.93585)
		(width 0.14224)
		(layer "In15.Cu")
		(net "P3E_CPU0_P4_TX_DN<2>")
	)
	(segment
		(start 334.843882 -311.00268)
		(end 328.031094 -312.531506)
		(width 0.14224)
		(layer "In15.Cu")
		(net "P3E_CPU0_P4_TX_DN<2>")
	)
	(segment
		(start 322.68033 -314.15482)
		(end 322.578984 -314.178442)
		(width 0.14224)
		(layer "In15.Cu")
		(net "P3E_CPU0_P4_TX_DN<2>")
	)
	(segment
		(start 319.471802 -315.061854)
		(end 318.233298 -315.574934)
		(width 0.14224)
		(layer "In15.Cu")
		(net "P3E_CPU0_P4_TX_DN<2>")
	)
	(segment
		(start 261.670546 -320.495422)
		(end 261.478268 -320.17843)
		(width 0.14224)
		(layer "In15.Cu")
		(net "P3E_CPU0_P4_TX_DN<2>")
	)
	(segment
		(start 252.11278 -219.538804)
		(end 252.11278 -201.360532)
		(width 0.14224)
		(layer "In15.Cu")
		(net "P3E_CPU0_P4_TX_DN<2>")
	)
	(segment
		(start 261.21614 -319.423796)
		(end 260.749796 -317.172594)
		(width 0.14224)
		(layer "In15.Cu")
		(net "P3E_CPU0_P4_TX_DN<2>")
	)
	(segment
		(start 255.060196 -246.607076)
		(end 253.874778 -234.573064)
		(width 0.14224)
		(layer "In15.Cu")
		(net "P3E_CPU0_P4_TX_DN<2>")
	)
	(segment
		(start 322.578984 -314.178442)
		(end 322.577714 -314.178696)
		(width 0.14224)
		(layer "In15.Cu")
		(net "P3E_CPU0_P4_TX_DN<2>")
	)
	(segment
		(start 258.113784 -270.933926)
		(end 256.157476 -255.704848)
		(width 0.14224)
		(layer "In15.Cu")
		(net "P3E_CPU0_P4_TX_DN<2>")
	)
	(segment
		(start 309.38089 -322.12407)
		(end 264.915396 -321.928998)
		(width 0.14224)
		(layer "In15.Cu")
		(net "P3E_CPU0_P4_TX_DN<2>")
	)
	(segment
		(start 264.915396 -321.928998)
		(end 263.482836 -321.613022)
		(width 0.14224)
		(layer "In15.Cu")
		(net "P3E_CPU0_P4_TX_DN<2>")
	)
	(segment
		(start 261.478268 -320.17843)
		(end 261.328154 -319.796668)
		(width 0.14224)
		(layer "In15.Cu")
		(net "P3E_CPU0_P4_TX_DN<2>")
	)
	(segment
		(start 341.609172 -309.012336)
		(end 339.052154 -309.012336)
		(width 0.14224)
		(layer "In15.Cu")
		(net "P3E_CPU0_P4_TX_DN<2>")
	)
	(segment
		(start 328.031094 -312.531506)
		(end 322.68033 -314.15482)
		(width 0.14224)
		(layer "In15.Cu")
		(net "P3E_CPU0_P4_TX_DN<2>")
	)
	(segment
		(start 253.53137 -197.93585)
		(end 254.75438 -196.71284)
		(width 0.14224)
		(layer "In15.Cu")
		(net "P3E_CPU0_P4_TX_DN<2>")
	)
	(segment
		(start 341.900002 -309.303166)
		(end 341.609172 -309.012336)
		(width 0.14224)
		(layer "In15.Cu")
		(net "P3E_CPU0_P4_TX_DN<2>")
	)
	(segment
		(start 263.482836 -321.613022)
		(end 262.085328 -320.972434)
		(width 0.14224)
		(layer "In15.Cu")
		(net "P3E_CPU0_P4_TX_DN<2>")
	)
	(segment
		(start 255.636268 -196.50075)
		(end 255.927098 -196.20992)
		(width 0.14224)
		(layer "In15.Cu")
		(net "P3E_CPU0_P4_TX_DN<2>")
	)
	(segment
		(start 256.157476 -255.704848)
		(end 256.068322 -254.310388)
		(width 0.14224)
		(layer "In15.Cu")
		(net "P3E_CPU0_P4_TX_DN<2>")
	)
	(segment
		(start 259.319268 -285.838138)
		(end 258.113784 -270.933926)
		(width 0.14224)
		(layer "In15.Cu")
		(net "P3E_CPU0_P4_TX_DN<2>")
	)
	(segment
		(start 261.328154 -319.796668)
		(end 261.21614 -319.423796)
		(width 0.14224)
		(layer "In15.Cu")
		(net "P3E_CPU0_P4_TX_DN<2>")
	)
	(segment
		(start 318.233298 -315.574934)
		(end 312.704226 -321.104006)
		(width 0.14224)
		(layer "In15.Cu")
		(net "P3E_CPU0_P4_TX_DN<2>")
	)
	(segment
		(start 253.036324 -228.919278)
		(end 252.11278 -219.538804)
		(width 0.14224)
		(layer "In15.Cu")
		(net "P3E_CPU0_P4_TX_DN<2>")
	)
	(segment
		(start 311.027064 -321.798696)
		(end 309.38089 -322.12407)
		(width 0.14224)
		(layer "In15.Cu")
		(net "P3E_CPU0_P4_TX_DN<2>")
	)
	(segment
		(start 312.704226 -321.104006)
		(end 311.027064 -321.798696)
		(width 0.14224)
		(layer "In15.Cu")
		(net "P3E_CPU0_P4_TX_DN<2>")
	)
	(segment
		(start 322.48348 -314.20054)
		(end 319.471802 -315.061854)
		(width 0.14224)
		(layer "In15.Cu")
		(net "P3E_CPU0_P4_TX_DN<2>")
	)
	(segment
		(start 256.068322 -254.310388)
		(end 255.060196 -246.607076)
		(width 0.14224)
		(layer "In15.Cu")
		(net "P3E_CPU0_P4_TX_DN<2>")
	)
	(segment
		(start 255.266444 -196.50075)
		(end 255.636268 -196.50075)
		(width 0.14224)
		(layer "In15.Cu")
		(net "P3E_CPU0_P4_TX_DN<2>")
	)
	(segment
		(start 260.231382 -312.838084)
		(end 259.319268 -285.838138)
		(width 0.14224)
		(layer "In15.Cu")
		(net "P3E_CPU0_P4_TX_DN<2>")
	)
	(segment
		(start 253.874778 -234.573064)
		(end 253.036324 -228.919278)
		(width 0.14224)
		(layer "In15.Cu")
		(net "P3E_CPU0_P4_TX_DN<2>")
	)
	(segment
		(start 322.577714 -314.178696)
		(end 322.48348 -314.20054)
		(width 0.14224)
		(layer "In15.Cu")
		(net "P3E_CPU0_P4_TX_DN<2>")
	)
	(segment
		(start 242.897914 -57.004712)
		(end 242.999514 -56.759094)
		(width 0.12954)
		(layer "F.Cu")
		(net "P3E_CPU0_P4_TX_DN<1>")
	)
	(segment
		(start 243.44122 -58.852562)
		(end 243.62918 -58.664602)
		(width 0.12954)
		(layer "F.Cu")
		(net "P3E_CPU0_P4_TX_DN<1>")
	)
	(segment
		(start 258.427728 -195.837556)
		(end 258.427728 -195.451476)
		(width 0.12954)
		(layer "F.Cu")
		(net "P3E_CPU0_P4_TX_DN<1>")
	)
	(segment
		(start 243.62918 -58.278522)
		(end 243.29136 -57.463436)
		(width 0.12954)
		(layer "F.Cu")
		(net "P3E_CPU0_P4_TX_DN<1>")
	)
	(segment
		(start 258.237228 -196.028056)
		(end 258.427728 -195.837556)
		(width 0.12954)
		(layer "F.Cu")
		(net "P3E_CPU0_P4_TX_DN<1>")
	)
	(segment
		(start 258.237228 -194.874896)
		(end 258.427728 -194.684396)
		(width 0.12954)
		(layer "F.Cu")
		(net "P3E_CPU0_P4_TX_DN<1>")
	)
	(segment
		(start 243.62918 -58.664602)
		(end 243.62918 -58.278522)
		(width 0.12954)
		(layer "F.Cu")
		(net "P3E_CPU0_P4_TX_DN<1>")
	)
	(segment
		(start 241.62004 -54.714902)
		(end 241.345466 -54.440328)
		(width 0.12954)
		(layer "F.Cu")
		(net "P3E_CPU0_P4_TX_DN<1>")
	)
	(segment
		(start 256.764536 -199.1614)
		(end 258.34848 -197.577964)
		(width 0.12954)
		(layer "F.Cu")
		(net "P3E_CPU0_P4_TX_DN<1>")
	)
	(segment
		(start 258.427728 -194.684396)
		(end 258.427728 -191.234568)
		(width 0.12954)
		(layer "F.Cu")
		(net "P3E_CPU0_P4_TX_DN<1>")
	)
	(segment
		(start 248.455942 -145.704306)
		(end 247.326404 -137.338308)
		(width 0.12954)
		(layer "F.Cu")
		(net "P3E_CPU0_P4_TX_DN<1>")
	)
	(segment
		(start 255.927098 -199.004428)
		(end 256.196338 -199.273668)
		(width 0.12954)
		(layer "F.Cu")
		(net "P3E_CPU0_P4_TX_DN<1>")
	)
	(segment
		(start 241.62004 -54.984396)
		(end 241.62004 -54.714902)
		(width 0.12954)
		(layer "F.Cu")
		(net "P3E_CPU0_P4_TX_DN<1>")
	)
	(segment
		(start 241.345466 -54.440328)
		(end 240.974118 -54.440328)
		(width 0.12954)
		(layer "F.Cu")
		(net "P3E_CPU0_P4_TX_DN<1>")
	)
	(segment
		(start 243.44122 -59.238642)
		(end 243.44122 -58.852562)
		(width 0.12954)
		(layer "F.Cu")
		(net "P3E_CPU0_P4_TX_DN<1>")
	)
	(segment
		(start 247.326404 -137.338308)
		(end 243.62918 -66.675)
		(width 0.12954)
		(layer "F.Cu")
		(net "P3E_CPU0_P4_TX_DN<1>")
	)
	(segment
		(start 240.786158 -54.628288)
		(end 240.400078 -54.628288)
		(width 0.12954)
		(layer "F.Cu")
		(net "P3E_CPU0_P4_TX_DN<1>")
	)
	(segment
		(start 258.237228 -195.260976)
		(end 258.237228 -194.874896)
		(width 0.12954)
		(layer "F.Cu")
		(net "P3E_CPU0_P4_TX_DN<1>")
	)
	(segment
		(start 258.427728 -195.451476)
		(end 258.237228 -195.260976)
		(width 0.12954)
		(layer "F.Cu")
		(net "P3E_CPU0_P4_TX_DN<1>")
	)
	(segment
		(start 258.427728 -191.234568)
		(end 248.455942 -145.704306)
		(width 0.12954)
		(layer "F.Cu")
		(net "P3E_CPU0_P4_TX_DN<1>")
	)
	(segment
		(start 350.14789 -292.450012)
		(end 349.681038 -292.71595)
		(width 0.12954)
		(layer "F.Cu")
		(net "P3E_CPU0_P4_TX_DN<1>")
	)
	(segment
		(start 243.29136 -57.463436)
		(end 243.045742 -57.361582)
		(width 0.12954)
		(layer "F.Cu")
		(net "P3E_CPU0_P4_TX_DN<1>")
	)
	(segment
		(start 256.494788 -199.273668)
		(end 256.764536 -199.1614)
		(width 0.12954)
		(layer "F.Cu")
		(net "P3E_CPU0_P4_TX_DN<1>")
	)
	(segment
		(start 240.974118 -54.440328)
		(end 240.786158 -54.628288)
		(width 0.12954)
		(layer "F.Cu")
		(net "P3E_CPU0_P4_TX_DN<1>")
	)
	(segment
		(start 241.895122 -55.259478)
		(end 241.62004 -54.984396)
		(width 0.12954)
		(layer "F.Cu")
		(net "P3E_CPU0_P4_TX_DN<1>")
	)
	(segment
		(start 243.045742 -57.361582)
		(end 242.897914 -57.004712)
		(width 0.12954)
		(layer "F.Cu")
		(net "P3E_CPU0_P4_TX_DN<1>")
	)
	(segment
		(start 243.62918 -66.675)
		(end 243.62918 -59.426602)
		(width 0.12954)
		(layer "F.Cu")
		(net "P3E_CPU0_P4_TX_DN<1>")
	)
	(segment
		(start 243.62918 -59.426602)
		(end 243.44122 -59.238642)
		(width 0.12954)
		(layer "F.Cu")
		(net "P3E_CPU0_P4_TX_DN<1>")
	)
	(segment
		(start 258.34848 -197.577964)
		(end 258.427474 -197.38721)
		(width 0.12954)
		(layer "F.Cu")
		(net "P3E_CPU0_P4_TX_DN<1>")
	)
	(segment
		(start 242.999514 -56.759094)
		(end 242.52936 -55.624222)
		(width 0.12954)
		(layer "F.Cu")
		(net "P3E_CPU0_P4_TX_DN<1>")
	)
	(segment
		(start 258.237228 -196.414136)
		(end 258.237228 -196.028056)
		(width 0.12954)
		(layer "F.Cu")
		(net "P3E_CPU0_P4_TX_DN<1>")
	)
	(segment
		(start 258.427474 -197.38721)
		(end 258.427728 -197.38721)
		(width 0.12954)
		(layer "F.Cu")
		(net "P3E_CPU0_P4_TX_DN<1>")
	)
	(segment
		(start 240.400078 -54.628288)
		(end 240.212118 -54.440328)
		(width 0.12954)
		(layer "F.Cu")
		(net "P3E_CPU0_P4_TX_DN<1>")
	)
	(segment
		(start 240.212118 -54.440328)
		(end 239.715294 -54.440328)
		(width 0.12954)
		(layer "F.Cu")
		(net "P3E_CPU0_P4_TX_DN<1>")
	)
	(segment
		(start 256.196338 -199.273668)
		(end 256.494788 -199.273668)
		(width 0.12954)
		(layer "F.Cu")
		(net "P3E_CPU0_P4_TX_DN<1>")
	)
	(segment
		(start 242.52936 -55.624222)
		(end 242.164616 -55.259478)
		(width 0.12954)
		(layer "F.Cu")
		(net "P3E_CPU0_P4_TX_DN<1>")
	)
	(segment
		(start 258.427728 -197.38721)
		(end 258.427728 -196.604636)
		(width 0.12954)
		(layer "F.Cu")
		(net "P3E_CPU0_P4_TX_DN<1>")
	)
	(segment
		(start 242.164616 -55.259478)
		(end 241.895122 -55.259478)
		(width 0.12954)
		(layer "F.Cu")
		(net "P3E_CPU0_P4_TX_DN<1>")
	)
	(segment
		(start 239.715294 -54.440328)
		(end 239.419384 -54.736238)
		(width 0.12954)
		(layer "F.Cu")
		(net "P3E_CPU0_P4_TX_DN<1>")
	)
	(segment
		(start 258.427728 -196.604636)
		(end 258.237228 -196.414136)
		(width 0.12954)
		(layer "F.Cu")
		(net "P3E_CPU0_P4_TX_DN<1>")
	)
	(segment
		(start 341.182452 -306.127658)
		(end 340.877144 -306.432966)
		(width 0.14224)
		(layer "In2.Cu")
		(net "P3E_CPU0_P4_TX_DN<1>")
	)
	(segment
		(start 346.50426 -302.359822)
		(end 343.060782 -304.661062)
		(width 0.14224)
		(layer "In2.Cu")
		(net "P3E_CPU0_P4_TX_DN<1>")
	)
	(segment
		(start 348.989396 -296.544492)
		(end 348.989396 -297.561508)
		(width 0.1143)
		(layer "In2.Cu")
		(net "P3E_CPU0_P4_TX_DN<1>")
	)
	(segment
		(start 349.479108 -294.649906)
		(end 349.480378 -294.650668)
		(width 0.1143)
		(layer "In2.Cu")
		(net "P3E_CPU0_P4_TX_DN<1>")
	)
	(segment
		(start 348.989396 -297.561508)
		(end 349.035116 -297.607228)
		(width 0.1143)
		(layer "In2.Cu")
		(net "P3E_CPU0_P4_TX_DN<1>")
	)
	(segment
		(start 349.525082 -295.606724)
		(end 349.50908 -295.61663)
		(width 0.1143)
		(layer "In2.Cu")
		(net "P3E_CPU0_P4_TX_DN<1>")
	)
	(segment
		(start 349.494094 -294.658542)
		(end 349.526098 -294.6781)
		(width 0.1143)
		(layer "In2.Cu")
		(net "P3E_CPU0_P4_TX_DN<1>")
	)
	(segment
		(start 341.594186 -306.127658)
		(end 341.182452 -306.127658)
		(width 0.14224)
		(layer "In2.Cu")
		(net "P3E_CPU0_P4_TX_DN<1>")
	)
	(segment
		(start 349.035116 -297.607228)
		(end 349.035116 -297.635676)
		(width 0.1143)
		(layer "In2.Cu")
		(net "P3E_CPU0_P4_TX_DN<1>")
	)
	(segment
		(start 349.681038 -292.71595)
		(end 349.383096 -292.71595)
		(width 0.1143)
		(layer "In2.Cu")
		(net "P3E_CPU0_P4_TX_DN<1>")
	)
	(segment
		(start 349.383096 -292.71595)
		(end 349.313246 -292.7858)
		(width 0.1143)
		(layer "In2.Cu")
		(net "P3E_CPU0_P4_TX_DN<1>")
	)
	(segment
		(start 349.035116 -297.635676)
		(end 349.035116 -299.828966)
		(width 0.14224)
		(layer "In2.Cu")
		(net "P3E_CPU0_P4_TX_DN<1>")
	)
	(segment
		(start 349.48114 -294.651176)
		(end 349.494094 -294.658542)
		(width 0.1143)
		(layer "In2.Cu")
		(net "P3E_CPU0_P4_TX_DN<1>")
	)
	(segment
		(start 343.060782 -304.661062)
		(end 341.594186 -306.127658)
		(width 0.14224)
		(layer "In2.Cu")
		(net "P3E_CPU0_P4_TX_DN<1>")
	)
	(segment
		(start 349.462344 -293.020242)
		(end 349.479362 -293.029894)
		(width 0.1143)
		(layer "In2.Cu")
		(net "P3E_CPU0_P4_TX_DN<1>")
	)
	(segment
		(start 349.462344 -294.640254)
		(end 349.478346 -294.649398)
		(width 0.1143)
		(layer "In2.Cu")
		(net "P3E_CPU0_P4_TX_DN<1>")
	)
	(segment
		(start 349.478346 -294.649398)
		(end 349.479108 -294.649906)
		(width 0.1143)
		(layer "In2.Cu")
		(net "P3E_CPU0_P4_TX_DN<1>")
	)
	(segment
		(start 349.480378 -294.650668)
		(end 349.48114 -294.651176)
		(width 0.1143)
		(layer "In2.Cu")
		(net "P3E_CPU0_P4_TX_DN<1>")
	)
	(segment
		(start 349.035116 -299.828966)
		(end 346.50426 -302.359822)
		(width 0.14224)
		(layer "In2.Cu")
		(net "P3E_CPU0_P4_TX_DN<1>")
	)
	(segment
		(start 349.479616 -294.021764)
		(end 349.462344 -294.03167)
		(width 0.1143)
		(layer "In2.Cu")
		(net "P3E_CPU0_P4_TX_DN<1>")
	)
	(arc
		(start 349.462344 -294.03167)
		(mid 349.306416 -294.335962)
		(end 349.462344 -294.640254)
		(width 0.1143)
		(layer "In2.Cu")
		(net "P3E_CPU0_P4_TX_DN<1>")
	)
	(arc
		(start 349.526098 -294.6781)
		(mid 349.785327 -295.142724)
		(end 349.525082 -295.606724)
		(width 0.1143)
		(layer "In2.Cu")
		(net "P3E_CPU0_P4_TX_DN<1>")
	)
	(arc
		(start 349.479362 -293.029894)
		(mid 349.766727 -293.525783)
		(end 349.479616 -294.021764)
		(width 0.1143)
		(layer "In2.Cu")
		(net "P3E_CPU0_P4_TX_DN<1>")
	)
	(arc
		(start 349.313246 -292.7858)
		(mid 349.365295 -292.917319)
		(end 349.462344 -293.020242)
		(width 0.1143)
		(layer "In2.Cu")
		(net "P3E_CPU0_P4_TX_DN<1>")
	)
	(arc
		(start 349.50908 -295.61663)
		(mid 349.128157 -296.012747)
		(end 348.989396 -296.544492)
		(width 0.1143)
		(layer "In2.Cu")
		(net "P3E_CPU0_P4_TX_DN<1>")
	)
	(segment
		(start 340.877144 -306.432966)
		(end 340.586314 -306.142136)
		(width 0.14224)
		(layer "In15.Cu")
		(net "P3E_CPU0_P4_TX_DN<1>")
	)
	(segment
		(start 253.999238 -200.42759)
		(end 254.240792 -200.066656)
		(width 0.14224)
		(layer "In15.Cu")
		(net "P3E_CPU0_P4_TX_DN<1>")
	)
	(segment
		(start 323.904864 -312.329576)
		(end 321.305428 -313.259724)
		(width 0.14224)
		(layer "In15.Cu")
		(net "P3E_CPU0_P4_TX_DN<1>")
	)
	(segment
		(start 310.84901 -320.863214)
		(end 309.320438 -321.166744)
		(width 0.14224)
		(layer "In15.Cu")
		(net "P3E_CPU0_P4_TX_DN<1>")
	)
	(segment
		(start 262.250936 -319.535302)
		(end 262.099298 -319.035176)
		(width 0.14224)
		(layer "In15.Cu")
		(net "P3E_CPU0_P4_TX_DN<1>")
	)
	(segment
		(start 340.586314 -306.142136)
		(end 339.378544 -306.142136)
		(width 0.14224)
		(layer "In15.Cu")
		(net "P3E_CPU0_P4_TX_DN<1>")
	)
	(segment
		(start 258.92887 -265.865356)
		(end 253.373128 -222.611696)
		(width 0.14224)
		(layer "In15.Cu")
		(net "P3E_CPU0_P4_TX_DN<1>")
	)
	(segment
		(start 264.182098 -320.800476)
		(end 262.679434 -320.173858)
		(width 0.14224)
		(layer "In15.Cu")
		(net "P3E_CPU0_P4_TX_DN<1>")
	)
	(segment
		(start 265.036554 -320.97345)
		(end 264.182098 -320.800476)
		(width 0.14224)
		(layer "In15.Cu")
		(net "P3E_CPU0_P4_TX_DN<1>")
	)
	(segment
		(start 253.373128 -201.939398)
		(end 253.999238 -200.42759)
		(width 0.14224)
		(layer "In15.Cu")
		(net "P3E_CPU0_P4_TX_DN<1>")
	)
	(segment
		(start 255.636268 -199.295258)
		(end 255.927098 -199.004428)
		(width 0.14224)
		(layer "In15.Cu")
		(net "P3E_CPU0_P4_TX_DN<1>")
	)
	(segment
		(start 262.399018 -319.893188)
		(end 262.250936 -319.535302)
		(width 0.14224)
		(layer "In15.Cu")
		(net "P3E_CPU0_P4_TX_DN<1>")
	)
	(segment
		(start 262.679434 -320.173858)
		(end 262.399018 -319.893188)
		(width 0.14224)
		(layer "In15.Cu")
		(net "P3E_CPU0_P4_TX_DN<1>")
	)
	(segment
		(start 338.379562 -305.72837)
		(end 336.61223 -305.72837)
		(width 0.14224)
		(layer "In15.Cu")
		(net "P3E_CPU0_P4_TX_DN<1>")
	)
	(segment
		(start 261.823708 -317.650114)
		(end 261.502652 -314.390532)
		(width 0.14224)
		(layer "In15.Cu")
		(net "P3E_CPU0_P4_TX_DN<1>")
	)
	(segment
		(start 255.355598 -199.295258)
		(end 255.636268 -199.295258)
		(width 0.14224)
		(layer "In15.Cu")
		(net "P3E_CPU0_P4_TX_DN<1>")
	)
	(segment
		(start 261.502652 -314.390532)
		(end 260.53161 -285.661862)
		(width 0.14224)
		(layer "In15.Cu")
		(net "P3E_CPU0_P4_TX_DN<1>")
	)
	(segment
		(start 260.53161 -285.661862)
		(end 258.92887 -265.865356)
		(width 0.14224)
		(layer "In15.Cu")
		(net "P3E_CPU0_P4_TX_DN<1>")
	)
	(segment
		(start 336.61223 -305.72837)
		(end 331.346302 -309.247286)
		(width 0.14224)
		(layer "In15.Cu")
		(net "P3E_CPU0_P4_TX_DN<1>")
	)
	(segment
		(start 254.769366 -199.538082)
		(end 255.355598 -199.295258)
		(width 0.14224)
		(layer "In15.Cu")
		(net "P3E_CPU0_P4_TX_DN<1>")
	)
	(segment
		(start 317.761874 -314.72759)
		(end 312.175652 -320.313812)
		(width 0.14224)
		(layer "In15.Cu")
		(net "P3E_CPU0_P4_TX_DN<1>")
	)
	(segment
		(start 339.378544 -306.142136)
		(end 338.379562 -305.72837)
		(width 0.14224)
		(layer "In15.Cu")
		(net "P3E_CPU0_P4_TX_DN<1>")
	)
	(segment
		(start 312.175652 -320.313812)
		(end 310.84901 -320.863214)
		(width 0.14224)
		(layer "In15.Cu")
		(net "P3E_CPU0_P4_TX_DN<1>")
	)
	(segment
		(start 262.099298 -319.035176)
		(end 261.823708 -317.650114)
		(width 0.14224)
		(layer "In15.Cu")
		(net "P3E_CPU0_P4_TX_DN<1>")
	)
	(segment
		(start 321.305428 -313.259724)
		(end 317.761874 -314.72759)
		(width 0.14224)
		(layer "In15.Cu")
		(net "P3E_CPU0_P4_TX_DN<1>")
	)
	(segment
		(start 331.346302 -309.247286)
		(end 323.904864 -312.329576)
		(width 0.14224)
		(layer "In15.Cu")
		(net "P3E_CPU0_P4_TX_DN<1>")
	)
	(segment
		(start 254.240792 -200.066656)
		(end 254.769366 -199.538082)
		(width 0.14224)
		(layer "In15.Cu")
		(net "P3E_CPU0_P4_TX_DN<1>")
	)
	(segment
		(start 253.373128 -222.611696)
		(end 253.373128 -201.939398)
		(width 0.14224)
		(layer "In15.Cu")
		(net "P3E_CPU0_P4_TX_DN<1>")
	)
	(segment
		(start 309.320438 -321.166744)
		(end 265.036554 -320.97345)
		(width 0.14224)
		(layer "In15.Cu")
		(net "P3E_CPU0_P4_TX_DN<1>")
	)
	(segment
		(start 241.843306 -53.746908)
		(end 242.1128 -53.746908)
		(width 0.12954)
		(layer "F.Cu")
		(net "P3E_CPU0_P4_TX_DN<0>")
	)
	(segment
		(start 259.402072 -198.297292)
		(end 259.211572 -198.487792)
		(width 0.12954)
		(layer "F.Cu")
		(net "P3E_CPU0_P4_TX_DN<0>")
	)
	(segment
		(start 243.512848 -56.011572)
		(end 243.75872 -56.113426)
		(width 0.12954)
		(layer "F.Cu")
		(net "P3E_CPU0_P4_TX_DN<0>")
	)
	(segment
		(start 256.648458 -202.064874)
		(end 256.193036 -202.064874)
		(width 0.12954)
		(layer "F.Cu")
		(net "P3E_CPU0_P4_TX_DN<0>")
	)
	(segment
		(start 248.154952 -137.260838)
		(end 249.19686 -144.977104)
		(width 0.12954)
		(layer "F.Cu")
		(net "P3E_CPU0_P4_TX_DN<0>")
	)
	(segment
		(start 259.211572 -198.873872)
		(end 259.402072 -199.064372)
		(width 0.12954)
		(layer "F.Cu")
		(net "P3E_CPU0_P4_TX_DN<0>")
	)
	(segment
		(start 259.402072 -199.064372)
		(end 259.402072 -199.300592)
		(width 0.12954)
		(layer "F.Cu")
		(net "P3E_CPU0_P4_TX_DN<0>")
	)
	(segment
		(start 244.3734 -57.59704)
		(end 244.3734 -64.987932)
		(width 0.12954)
		(layer "F.Cu")
		(net "P3E_CPU0_P4_TX_DN<0>")
	)
	(segment
		(start 257.083306 -201.769218)
		(end 256.886202 -201.966068)
		(width 0.12954)
		(layer "F.Cu")
		(net "P3E_CPU0_P4_TX_DN<0>")
	)
	(segment
		(start 249.19686 -144.977104)
		(end 259.402072 -191.574674)
		(width 0.12954)
		(layer "F.Cu")
		(net "P3E_CPU0_P4_TX_DN<0>")
	)
	(segment
		(start 244.198394 -57.17413)
		(end 244.3734 -57.59704)
		(width 0.12954)
		(layer "F.Cu")
		(net "P3E_CPU0_P4_TX_DN<0>")
	)
	(segment
		(start 241.130836 -52.764944)
		(end 241.570002 -53.20411)
		(width 0.12954)
		(layer "F.Cu")
		(net "P3E_CPU0_P4_TX_DN<0>")
	)
	(segment
		(start 239.419384 -52.92725)
		(end 239.715294 -52.63134)
		(width 0.12954)
		(layer "F.Cu")
		(net "P3E_CPU0_P4_TX_DN<0>")
	)
	(segment
		(start 256.193036 -202.064874)
		(end 255.927098 -201.798936)
		(width 0.12954)
		(layer "F.Cu")
		(net "P3E_CPU0_P4_TX_DN<0>")
	)
	(segment
		(start 241.570002 -53.20411)
		(end 241.570002 -53.473604)
		(width 0.12954)
		(layer "F.Cu")
		(net "P3E_CPU0_P4_TX_DN<0>")
	)
	(segment
		(start 259.402072 -199.300592)
		(end 259.2959 -199.556624)
		(width 0.12954)
		(layer "F.Cu")
		(net "P3E_CPU0_P4_TX_DN<0>")
	)
	(segment
		(start 257.35661 -201.22642)
		(end 257.083306 -201.499724)
		(width 0.12954)
		(layer "F.Cu")
		(net "P3E_CPU0_P4_TX_DN<0>")
	)
	(segment
		(start 241.570002 -53.473604)
		(end 241.843306 -53.746908)
		(width 0.12954)
		(layer "F.Cu")
		(net "P3E_CPU0_P4_TX_DN<0>")
	)
	(segment
		(start 242.6589 -54.562248)
		(end 242.92814 -54.562248)
		(width 0.12954)
		(layer "F.Cu")
		(net "P3E_CPU0_P4_TX_DN<0>")
	)
	(segment
		(start 257.8989 -200.953624)
		(end 257.626104 -201.22642)
		(width 0.12954)
		(layer "F.Cu")
		(net "P3E_CPU0_P4_TX_DN<0>")
	)
	(segment
		(start 258.172204 -200.410826)
		(end 257.8989 -200.68413)
		(width 0.12954)
		(layer "F.Cu")
		(net "P3E_CPU0_P4_TX_DN<0>")
	)
	(segment
		(start 257.626104 -201.22642)
		(end 257.35661 -201.22642)
		(width 0.12954)
		(layer "F.Cu")
		(net "P3E_CPU0_P4_TX_DN<0>")
	)
	(segment
		(start 347.327982 -292.450012)
		(end 346.86113 -292.71595)
		(width 0.12954)
		(layer "F.Cu")
		(net "P3E_CPU0_P4_TX_DN<0>")
	)
	(segment
		(start 257.8989 -200.68413)
		(end 257.8989 -200.953624)
		(width 0.12954)
		(layer "F.Cu")
		(net "P3E_CPU0_P4_TX_DN<0>")
	)
	(segment
		(start 242.92814 -54.562248)
		(end 243.249196 -54.883304)
		(width 0.12954)
		(layer "F.Cu")
		(net "P3E_CPU0_P4_TX_DN<0>")
	)
	(segment
		(start 243.804694 -56.71566)
		(end 243.952522 -57.07253)
		(width 0.12954)
		(layer "F.Cu")
		(net "P3E_CPU0_P4_TX_DN<0>")
	)
	(segment
		(start 242.385596 -54.288944)
		(end 242.6589 -54.562248)
		(width 0.12954)
		(layer "F.Cu")
		(net "P3E_CPU0_P4_TX_DN<0>")
	)
	(segment
		(start 239.715294 -52.63134)
		(end 240.808256 -52.63134)
		(width 0.12954)
		(layer "F.Cu")
		(net "P3E_CPU0_P4_TX_DN<0>")
	)
	(segment
		(start 257.083306 -201.499724)
		(end 257.083306 -201.769218)
		(width 0.12954)
		(layer "F.Cu")
		(net "P3E_CPU0_P4_TX_DN<0>")
	)
	(segment
		(start 258.441698 -200.410826)
		(end 258.172204 -200.410826)
		(width 0.12954)
		(layer "F.Cu")
		(net "P3E_CPU0_P4_TX_DN<0>")
	)
	(segment
		(start 256.886202 -201.966068)
		(end 256.648458 -202.064874)
		(width 0.12954)
		(layer "F.Cu")
		(net "P3E_CPU0_P4_TX_DN<0>")
	)
	(segment
		(start 243.249196 -54.883304)
		(end 243.466874 -55.409084)
		(width 0.12954)
		(layer "F.Cu")
		(net "P3E_CPU0_P4_TX_DN<0>")
	)
	(segment
		(start 240.808256 -52.63134)
		(end 241.130836 -52.764944)
		(width 0.12954)
		(layer "F.Cu")
		(net "P3E_CPU0_P4_TX_DN<0>")
	)
	(segment
		(start 259.2959 -199.556624)
		(end 258.441698 -200.410826)
		(width 0.12954)
		(layer "F.Cu")
		(net "P3E_CPU0_P4_TX_DN<0>")
	)
	(segment
		(start 243.952522 -57.07253)
		(end 244.198394 -57.17413)
		(width 0.12954)
		(layer "F.Cu")
		(net "P3E_CPU0_P4_TX_DN<0>")
	)
	(segment
		(start 242.385596 -54.019704)
		(end 242.385596 -54.288944)
		(width 0.12954)
		(layer "F.Cu")
		(net "P3E_CPU0_P4_TX_DN<0>")
	)
	(segment
		(start 243.906294 -56.470042)
		(end 243.804694 -56.71566)
		(width 0.12954)
		(layer "F.Cu")
		(net "P3E_CPU0_P4_TX_DN<0>")
	)
	(segment
		(start 243.365274 -55.654702)
		(end 243.512848 -56.011572)
		(width 0.12954)
		(layer "F.Cu")
		(net "P3E_CPU0_P4_TX_DN<0>")
	)
	(segment
		(start 243.466874 -55.409084)
		(end 243.365274 -55.654702)
		(width 0.12954)
		(layer "F.Cu")
		(net "P3E_CPU0_P4_TX_DN<0>")
	)
	(segment
		(start 259.402072 -191.574674)
		(end 259.402072 -198.297292)
		(width 0.12954)
		(layer "F.Cu")
		(net "P3E_CPU0_P4_TX_DN<0>")
	)
	(segment
		(start 244.3734 -64.987932)
		(end 248.154952 -137.260838)
		(width 0.12954)
		(layer "F.Cu")
		(net "P3E_CPU0_P4_TX_DN<0>")
	)
	(segment
		(start 242.1128 -53.746908)
		(end 242.385596 -54.019704)
		(width 0.12954)
		(layer "F.Cu")
		(net "P3E_CPU0_P4_TX_DN<0>")
	)
	(segment
		(start 243.75872 -56.113426)
		(end 243.906294 -56.470042)
		(width 0.12954)
		(layer "F.Cu")
		(net "P3E_CPU0_P4_TX_DN<0>")
	)
	(segment
		(start 259.211572 -198.487792)
		(end 259.211572 -198.873872)
		(width 0.12954)
		(layer "F.Cu")
		(net "P3E_CPU0_P4_TX_DN<0>")
	)
	(segment
		(start 346.095574 -296.595546)
		(end 346.095574 -297.906186)
		(width 0.1143)
		(layer "In2.Cu")
		(net "P3E_CPU0_P4_TX_DN<0>")
	)
	(segment
		(start 346.6592 -294.649906)
		(end 346.674186 -294.658542)
		(width 0.1143)
		(layer "In2.Cu")
		(net "P3E_CPU0_P4_TX_DN<0>")
	)
	(segment
		(start 346.642436 -294.640254)
		(end 346.658438 -294.649398)
		(width 0.1143)
		(layer "In2.Cu")
		(net "P3E_CPU0_P4_TX_DN<0>")
	)
	(segment
		(start 346.86113 -292.71595)
		(end 346.563188 -292.71595)
		(width 0.1143)
		(layer "In2.Cu")
		(net "P3E_CPU0_P4_TX_DN<0>")
	)
	(segment
		(start 346.141294 -297.980354)
		(end 346.141294 -298.425362)
		(width 0.14224)
		(layer "In2.Cu")
		(net "P3E_CPU0_P4_TX_DN<0>")
	)
	(segment
		(start 345.447366 -299.11929)
		(end 340.740238 -301.103792)
		(width 0.14224)
		(layer "In2.Cu")
		(net "P3E_CPU0_P4_TX_DN<0>")
	)
	(segment
		(start 346.141294 -298.425362)
		(end 345.447366 -299.11929)
		(width 0.14224)
		(layer "In2.Cu")
		(net "P3E_CPU0_P4_TX_DN<0>")
	)
	(segment
		(start 346.659708 -294.021764)
		(end 346.642436 -294.03167)
		(width 0.1143)
		(layer "In2.Cu")
		(net "P3E_CPU0_P4_TX_DN<0>")
	)
	(segment
		(start 346.674186 -294.658542)
		(end 346.727272 -294.691308)
		(width 0.1143)
		(layer "In2.Cu")
		(net "P3E_CPU0_P4_TX_DN<0>")
	)
	(segment
		(start 346.95638 -295.125648)
		(end 346.95638 -295.73474)
		(width 0.1143)
		(layer "In2.Cu")
		(net "P3E_CPU0_P4_TX_DN<0>")
	)
	(segment
		(start 346.642436 -293.020242)
		(end 346.659454 -293.029894)
		(width 0.1143)
		(layer "In2.Cu")
		(net "P3E_CPU0_P4_TX_DN<0>")
	)
	(segment
		(start 340.740238 -301.103792)
		(end 335.102454 -304.390298)
		(width 0.14224)
		(layer "In2.Cu")
		(net "P3E_CPU0_P4_TX_DN<0>")
	)
	(segment
		(start 346.095574 -297.906186)
		(end 346.141294 -297.951906)
		(width 0.1143)
		(layer "In2.Cu")
		(net "P3E_CPU0_P4_TX_DN<0>")
	)
	(segment
		(start 335.102454 -304.390298)
		(end 334.467708 -304.390298)
		(width 0.14224)
		(layer "In2.Cu")
		(net "P3E_CPU0_P4_TX_DN<0>")
	)
	(segment
		(start 346.95638 -295.73474)
		(end 346.095574 -296.595546)
		(width 0.1143)
		(layer "In2.Cu")
		(net "P3E_CPU0_P4_TX_DN<0>")
	)
	(segment
		(start 334.467708 -304.390298)
		(end 334.176878 -304.681128)
		(width 0.14224)
		(layer "In2.Cu")
		(net "P3E_CPU0_P4_TX_DN<0>")
	)
	(segment
		(start 346.658438 -294.649398)
		(end 346.6592 -294.649906)
		(width 0.1143)
		(layer "In2.Cu")
		(net "P3E_CPU0_P4_TX_DN<0>")
	)
	(segment
		(start 346.141294 -297.951906)
		(end 346.141294 -297.980354)
		(width 0.1143)
		(layer "In2.Cu")
		(net "P3E_CPU0_P4_TX_DN<0>")
	)
	(segment
		(start 346.563188 -292.71595)
		(end 346.493338 -292.7858)
		(width 0.1143)
		(layer "In2.Cu")
		(net "P3E_CPU0_P4_TX_DN<0>")
	)
	(arc
		(start 346.642436 -294.03167)
		(mid 346.486508 -294.335962)
		(end 346.642436 -294.640254)
		(width 0.1143)
		(layer "In2.Cu")
		(net "P3E_CPU0_P4_TX_DN<0>")
	)
	(arc
		(start 346.727272 -294.691308)
		(mid 346.895584 -294.88012)
		(end 346.95638 -295.125648)
		(width 0.1143)
		(layer "In2.Cu")
		(net "P3E_CPU0_P4_TX_DN<0>")
	)
	(arc
		(start 346.493338 -292.7858)
		(mid 346.545387 -292.917319)
		(end 346.642436 -293.020242)
		(width 0.1143)
		(layer "In2.Cu")
		(net "P3E_CPU0_P4_TX_DN<0>")
	)
	(arc
		(start 346.659454 -293.029894)
		(mid 346.946819 -293.525783)
		(end 346.659708 -294.021764)
		(width 0.1143)
		(layer "In2.Cu")
		(net "P3E_CPU0_P4_TX_DN<0>")
	)
	(segment
		(start 255.636268 -202.089766)
		(end 255.927098 -201.798936)
		(width 0.14224)
		(layer "In15.Cu")
		(net "P3E_CPU0_P4_TX_DN<0>")
	)
	(segment
		(start 317.348362 -313.709812)
		(end 311.49417 -319.564004)
		(width 0.14224)
		(layer "In15.Cu")
		(net "P3E_CPU0_P4_TX_DN<0>")
	)
	(segment
		(start 334.176878 -304.681128)
		(end 333.886048 -304.390298)
		(width 0.14224)
		(layer "In15.Cu")
		(net "P3E_CPU0_P4_TX_DN<0>")
	)
	(segment
		(start 265.300714 -319.607438)
		(end 265.099546 -319.50279)
		(width 0.14224)
		(layer "In15.Cu")
		(net "P3E_CPU0_P4_TX_DN<0>")
	)
	(segment
		(start 262.913876 -308.586632)
		(end 262.600186 -299.29963)
		(width 0.14224)
		(layer "In15.Cu")
		(net "P3E_CPU0_P4_TX_DN<0>")
	)
	(segment
		(start 331.483462 -307.342794)
		(end 330.486766 -308.339744)
		(width 0.14224)
		(layer "In15.Cu")
		(net "P3E_CPU0_P4_TX_DN<0>")
	)
	(segment
		(start 266.413488 -319.80378)
		(end 265.300714 -319.607438)
		(width 0.14224)
		(layer "In15.Cu")
		(net "P3E_CPU0_P4_TX_DN<0>")
	)
	(segment
		(start 310.590946 -319.938146)
		(end 309.234078 -320.209418)
		(width 0.14224)
		(layer "In15.Cu")
		(net "P3E_CPU0_P4_TX_DN<0>")
	)
	(segment
		(start 259.842254 -265.229848)
		(end 254.635 -224.692464)
		(width 0.14224)
		(layer "In15.Cu")
		(net "P3E_CPU0_P4_TX_DN<0>")
	)
	(segment
		(start 309.234078 -320.209418)
		(end 268.969998 -320.03365)
		(width 0.14224)
		(layer "In15.Cu")
		(net "P3E_CPU0_P4_TX_DN<0>")
	)
	(segment
		(start 263.434576 -313.090814)
		(end 262.913876 -308.586632)
		(width 0.14224)
		(layer "In15.Cu")
		(net "P3E_CPU0_P4_TX_DN<0>")
	)
	(segment
		(start 255.399286 -202.089766)
		(end 255.636268 -202.089766)
		(width 0.14224)
		(layer "In15.Cu")
		(net "P3E_CPU0_P4_TX_DN<0>")
	)
	(segment
		(start 254.852678 -202.384152)
		(end 255.204214 -202.148948)
		(width 0.14224)
		(layer "In15.Cu")
		(net "P3E_CPU0_P4_TX_DN<0>")
	)
	(segment
		(start 264.55751 -318.733678)
		(end 263.434576 -313.090814)
		(width 0.14224)
		(layer "In15.Cu")
		(net "P3E_CPU0_P4_TX_DN<0>")
	)
	(segment
		(start 333.431896 -304.390298)
		(end 332.985618 -304.836576)
		(width 0.14224)
		(layer "In15.Cu")
		(net "P3E_CPU0_P4_TX_DN<0>")
	)
	(segment
		(start 333.886048 -304.390298)
		(end 333.431896 -304.390298)
		(width 0.14224)
		(layer "In15.Cu")
		(net "P3E_CPU0_P4_TX_DN<0>")
	)
	(segment
		(start 265.099546 -319.50279)
		(end 264.817098 -319.219834)
		(width 0.14224)
		(layer "In15.Cu")
		(net "P3E_CPU0_P4_TX_DN<0>")
	)
	(segment
		(start 268.969998 -320.03365)
		(end 266.413488 -319.80378)
		(width 0.14224)
		(layer "In15.Cu")
		(net "P3E_CPU0_P4_TX_DN<0>")
	)
	(segment
		(start 332.985618 -304.836576)
		(end 331.483462 -307.342794)
		(width 0.14224)
		(layer "In15.Cu")
		(net "P3E_CPU0_P4_TX_DN<0>")
	)
	(segment
		(start 254.635 -224.692464)
		(end 254.635 -202.791568)
		(width 0.14224)
		(layer "In15.Cu")
		(net "P3E_CPU0_P4_TX_DN<0>")
	)
	(segment
		(start 262.600186 -299.29963)
		(end 259.842254 -265.229848)
		(width 0.14224)
		(layer "In15.Cu")
		(net "P3E_CPU0_P4_TX_DN<0>")
	)
	(segment
		(start 255.204214 -202.148948)
		(end 255.399286 -202.089766)
		(width 0.14224)
		(layer "In15.Cu")
		(net "P3E_CPU0_P4_TX_DN<0>")
	)
	(segment
		(start 254.635 -202.791568)
		(end 254.852678 -202.384152)
		(width 0.14224)
		(layer "In15.Cu")
		(net "P3E_CPU0_P4_TX_DN<0>")
	)
	(segment
		(start 324.980046 -310.309768)
		(end 317.348362 -313.709812)
		(width 0.14224)
		(layer "In15.Cu")
		(net "P3E_CPU0_P4_TX_DN<0>")
	)
	(segment
		(start 330.486766 -308.339744)
		(end 324.980046 -310.309768)
		(width 0.14224)
		(layer "In15.Cu")
		(net "P3E_CPU0_P4_TX_DN<0>")
	)
	(segment
		(start 264.817098 -319.219834)
		(end 264.55751 -318.733678)
		(width 0.14224)
		(layer "In15.Cu")
		(net "P3E_CPU0_P4_TX_DN<0>")
	)
	(segment
		(start 311.49417 -319.564004)
		(end 310.590946 -319.938146)
		(width 0.14224)
		(layer "In15.Cu")
		(net "P3E_CPU0_P4_TX_DN<0>")
	)
	(segment
		(start 252.661928 -201.673206)
		(end 247.151906 -155.388818)
		(width 0.12954)
		(layer "F.Cu")
		(net "P3E_CPU0_P4_RX_DP<3>")
	)
	(segment
		(start 353.907852 -294.070024)
		(end 353.441 -294.335962)
		(width 0.12954)
		(layer "F.Cu")
		(net "P3E_CPU0_P4_RX_DP<3>")
	)
	(segment
		(start 252.662182 -201.67346)
		(end 252.661928 -201.673206)
		(width 0.12954)
		(layer "F.Cu")
		(net "P3E_CPU0_P4_RX_DP<3>")
	)
	(segment
		(start 252.920754 -203.844398)
		(end 252.662182 -201.67346)
		(width 0.12954)
		(layer "F.Cu")
		(net "P3E_CPU0_P4_RX_DP<3>")
	)
	(segment
		(start 254.663448 -205.152498)
		(end 254.10414 -204.92085)
		(width 0.12954)
		(layer "F.Cu")
		(net "P3E_CPU0_P4_RX_DP<3>")
	)
	(segment
		(start 231.388666 -57.70372)
		(end 231.52735 -57.565036)
		(width 0.12954)
		(layer "F.Cu")
		(net "P3E_CPU0_P4_RX_DP<3>")
	)
	(segment
		(start 253.085854 -204.184504)
		(end 252.920754 -203.844398)
		(width 0.12954)
		(layer "F.Cu")
		(net "P3E_CPU0_P4_RX_DP<3>")
	)
	(segment
		(start 255.639824 -205.152498)
		(end 254.663448 -205.152498)
		(width 0.12954)
		(layer "F.Cu")
		(net "P3E_CPU0_P4_RX_DP<3>")
	)
	(segment
		(start 229.640638 -83.168236)
		(end 229.903528 -67.461384)
		(width 0.12954)
		(layer "F.Cu")
		(net "P3E_CPU0_P4_RX_DP<3>")
	)
	(segment
		(start 229.903528 -58.821828)
		(end 230.13416 -58.26506)
		(width 0.12954)
		(layer "F.Cu")
		(net "P3E_CPU0_P4_RX_DP<3>")
	)
	(segment
		(start 253.254256 -204.352906)
		(end 253.085854 -204.184504)
		(width 0.12954)
		(layer "F.Cu")
		(net "P3E_CPU0_P4_RX_DP<3>")
	)
	(segment
		(start 231.036876 -57.70372)
		(end 231.388666 -57.70372)
		(width 0.12954)
		(layer "F.Cu")
		(net "P3E_CPU0_P4_RX_DP<3>")
	)
	(segment
		(start 230.4542 -57.94502)
		(end 231.036876 -57.70372)
		(width 0.12954)
		(layer "F.Cu")
		(net "P3E_CPU0_P4_RX_DP<3>")
	)
	(segment
		(start 247.151906 -155.388818)
		(end 229.640638 -83.168236)
		(width 0.12954)
		(layer "F.Cu")
		(net "P3E_CPU0_P4_RX_DP<3>")
	)
	(segment
		(start 231.52735 -57.565036)
		(end 232.000044 -57.565036)
		(width 0.12954)
		(layer "F.Cu")
		(net "P3E_CPU0_P4_RX_DP<3>")
	)
	(segment
		(start 255.927098 -205.439772)
		(end 255.639824 -205.152498)
		(width 0.12954)
		(layer "F.Cu")
		(net "P3E_CPU0_P4_RX_DP<3>")
	)
	(segment
		(start 230.13416 -58.26506)
		(end 230.4542 -57.94502)
		(width 0.12954)
		(layer "F.Cu")
		(net "P3E_CPU0_P4_RX_DP<3>")
	)
	(segment
		(start 254.10414 -204.92085)
		(end 253.254256 -204.352906)
		(width 0.12954)
		(layer "F.Cu")
		(net "P3E_CPU0_P4_RX_DP<3>")
	)
	(segment
		(start 229.903528 -67.461384)
		(end 229.903528 -58.821828)
		(width 0.12954)
		(layer "F.Cu")
		(net "P3E_CPU0_P4_RX_DP<3>")
	)
	(segment
		(start 261.071868 -321.933316)
		(end 261.37743 -322.23837)
		(width 0.14224)
		(layer "In2.Cu")
		(net "P3E_CPU0_P4_RX_DP<3>")
	)
	(segment
		(start 345.940126 -310.834532)
		(end 348.204282 -308.570122)
		(width 0.14224)
		(layer "In2.Cu")
		(net "P3E_CPU0_P4_RX_DP<3>")
	)
	(segment
		(start 353.027996 -297.031918)
		(end 353.027996 -296.276014)
		(width 0.14224)
		(layer "In2.Cu")
		(net "P3E_CPU0_P4_RX_DP<3>")
	)
	(segment
		(start 353.073716 -296.201846)
		(end 353.073716 -295.764204)
		(width 0.1143)
		(layer "In2.Cu")
		(net "P3E_CPU0_P4_RX_DP<3>")
	)
	(segment
		(start 250.383294 -213.841076)
		(end 250.246134 -213.978236)
		(width 0.14224)
		(layer "In2.Cu")
		(net "P3E_CPU0_P4_RX_DP<3>")
	)
	(segment
		(start 257.165348 -267.27023)
		(end 261.071868 -321.933316)
		(width 0.14224)
		(layer "In2.Cu")
		(net "P3E_CPU0_P4_RX_DP<3>")
	)
	(segment
		(start 339.948266 -312.779918)
		(end 340.581996 -312.717688)
		(width 0.14224)
		(layer "In2.Cu")
		(net "P3E_CPU0_P4_RX_DP<3>")
	)
	(segment
		(start 338.608416 -312.77433)
		(end 338.758276 -312.897266)
		(width 0.14224)
		(layer "In2.Cu")
		(net "P3E_CPU0_P4_RX_DP<3>")
	)
	(segment
		(start 254.318008 -205.530704)
		(end 253.073916 -206.774796)
		(width 0.14224)
		(layer "In2.Cu")
		(net "P3E_CPU0_P4_RX_DP<3>")
	)
	(segment
		(start 339.798152 -312.656982)
		(end 339.948266 -312.779918)
		(width 0.14224)
		(layer "In2.Cu")
		(net "P3E_CPU0_P4_RX_DP<3>")
	)
	(segment
		(start 253.073916 -206.774796)
		(end 251.034804 -209.826352)
		(width 0.14224)
		(layer "In2.Cu")
		(net "P3E_CPU0_P4_RX_DP<3>")
	)
	(segment
		(start 262.110474 -322.545202)
		(end 262.110728 -322.545202)
		(width 0.14224)
		(layer "In2.Cu")
		(net "P3E_CPU0_P4_RX_DP<3>")
	)
	(segment
		(start 335.92897 -313.038236)
		(end 336.079084 -313.161426)
		(width 0.14224)
		(layer "In2.Cu")
		(net "P3E_CPU0_P4_RX_DP<3>")
	)
	(segment
		(start 348.204282 -308.570122)
		(end 353.755198 -301.086266)
		(width 0.14224)
		(layer "In2.Cu")
		(net "P3E_CPU0_P4_RX_DP<3>")
	)
	(segment
		(start 336.079084 -313.161426)
		(end 336.768694 -313.093608)
		(width 0.14224)
		(layer "In2.Cu")
		(net "P3E_CPU0_P4_RX_DP<3>")
	)
	(segment
		(start 332.27518 -313.53633)
		(end 332.699614 -313.494674)
		(width 0.14224)
		(layer "In2.Cu")
		(net "P3E_CPU0_P4_RX_DP<3>")
	)
	(segment
		(start 331.700124 -313.45505)
		(end 332.125066 -313.413394)
		(width 0.14224)
		(layer "In2.Cu")
		(net "P3E_CPU0_P4_RX_DP<3>")
	)
	(segment
		(start 339.37321 -312.698892)
		(end 339.798152 -312.656982)
		(width 0.14224)
		(layer "In2.Cu")
		(net "P3E_CPU0_P4_RX_DP<3>")
	)
	(segment
		(start 250.383294 -215.669876)
		(end 250.383294 -216.096596)
		(width 0.14224)
		(layer "In2.Cu")
		(net "P3E_CPU0_P4_RX_DP<3>")
	)
	(segment
		(start 251.67844 -234.631738)
		(end 257.165348 -267.27023)
		(width 0.14224)
		(layer "In2.Cu")
		(net "P3E_CPU0_P4_RX_DP<3>")
	)
	(segment
		(start 250.383294 -217.224356)
		(end 250.246134 -217.361516)
		(width 0.14224)
		(layer "In2.Cu")
		(net "P3E_CPU0_P4_RX_DP<3>")
	)
	(segment
		(start 250.383294 -216.797636)
		(end 250.383294 -217.224356)
		(width 0.14224)
		(layer "In2.Cu")
		(net "P3E_CPU0_P4_RX_DP<3>")
	)
	(segment
		(start 251.034804 -209.826352)
		(end 250.674632 -210.696302)
		(width 0.14224)
		(layer "In2.Cu")
		(net "P3E_CPU0_P4_RX_DP<3>")
	)
	(segment
		(start 333.397606 -313.425586)
		(end 333.82204 -313.38393)
		(width 0.14224)
		(layer "In2.Cu")
		(net "P3E_CPU0_P4_RX_DP<3>")
	)
	(segment
		(start 332.125066 -313.413394)
		(end 332.27518 -313.53633)
		(width 0.14224)
		(layer "In2.Cu")
		(net "P3E_CPU0_P4_RX_DP<3>")
	)
	(segment
		(start 353.755198 -301.086266)
		(end 353.755198 -297.75912)
		(width 0.14224)
		(layer "In2.Cu")
		(net "P3E_CPU0_P4_RX_DP<3>")
	)
	(segment
		(start 250.246134 -215.532716)
		(end 250.383294 -215.669876)
		(width 0.14224)
		(layer "In2.Cu")
		(net "P3E_CPU0_P4_RX_DP<3>")
	)
	(segment
		(start 255.636268 -205.148942)
		(end 255.239774 -205.148942)
		(width 0.14224)
		(layer "In2.Cu")
		(net "P3E_CPU0_P4_RX_DP<3>")
	)
	(segment
		(start 338.183474 -312.81624)
		(end 338.608416 -312.77433)
		(width 0.14224)
		(layer "In2.Cu")
		(net "P3E_CPU0_P4_RX_DP<3>")
	)
	(segment
		(start 250.383294 -214.542116)
		(end 250.383294 -214.968836)
		(width 0.14224)
		(layer "In2.Cu")
		(net "P3E_CPU0_P4_RX_DP<3>")
	)
	(segment
		(start 333.944976 -313.233816)
		(end 334.369918 -313.191906)
		(width 0.14224)
		(layer "In2.Cu")
		(net "P3E_CPU0_P4_RX_DP<3>")
	)
	(segment
		(start 331.577188 -313.605164)
		(end 331.700124 -313.45505)
		(width 0.14224)
		(layer "In2.Cu")
		(net "P3E_CPU0_P4_RX_DP<3>")
	)
	(segment
		(start 261.37743 -322.23837)
		(end 262.110474 -322.545202)
		(width 0.14224)
		(layer "In2.Cu")
		(net "P3E_CPU0_P4_RX_DP<3>")
	)
	(segment
		(start 250.383294 -213.414356)
		(end 250.383294 -213.841076)
		(width 0.14224)
		(layer "In2.Cu")
		(net "P3E_CPU0_P4_RX_DP<3>")
	)
	(segment
		(start 337.466686 -313.024774)
		(end 338.060284 -312.966354)
		(width 0.14224)
		(layer "In2.Cu")
		(net "P3E_CPU0_P4_RX_DP<3>")
	)
	(segment
		(start 250.246134 -212.850476)
		(end 250.246134 -213.277196)
		(width 0.14224)
		(layer "In2.Cu")
		(net "P3E_CPU0_P4_RX_DP<3>")
	)
	(segment
		(start 341.279734 -312.6486)
		(end 342.320372 -312.546238)
		(width 0.14224)
		(layer "In2.Cu")
		(net "P3E_CPU0_P4_RX_DP<3>")
	)
	(segment
		(start 353.808792 -294.405812)
		(end 353.738942 -294.335962)
		(width 0.1143)
		(layer "In2.Cu")
		(net "P3E_CPU0_P4_RX_DP<3>")
	)
	(segment
		(start 338.758276 -312.897266)
		(end 339.250274 -312.849006)
		(width 0.14224)
		(layer "In2.Cu")
		(net "P3E_CPU0_P4_RX_DP<3>")
	)
	(segment
		(start 250.246134 -213.277196)
		(end 250.383294 -213.414356)
		(width 0.14224)
		(layer "In2.Cu")
		(net "P3E_CPU0_P4_RX_DP<3>")
	)
	(segment
		(start 262.110728 -322.545202)
		(end 310.805576 -322.87337)
		(width 0.14224)
		(layer "In2.Cu")
		(net "P3E_CPU0_P4_RX_DP<3>")
	)
	(segment
		(start 250.246134 -214.404956)
		(end 250.383294 -214.542116)
		(width 0.14224)
		(layer "In2.Cu")
		(net "P3E_CPU0_P4_RX_DP<3>")
	)
	(segment
		(start 353.755198 -297.75912)
		(end 353.027996 -297.031918)
		(width 0.14224)
		(layer "In2.Cu")
		(net "P3E_CPU0_P4_RX_DP<3>")
	)
	(segment
		(start 332.699614 -313.494674)
		(end 332.82255 -313.344306)
		(width 0.14224)
		(layer "In2.Cu")
		(net "P3E_CPU0_P4_RX_DP<3>")
	)
	(segment
		(start 337.316572 -312.901584)
		(end 337.466686 -313.024774)
		(width 0.14224)
		(layer "In2.Cu")
		(net "P3E_CPU0_P4_RX_DP<3>")
	)
	(segment
		(start 250.246134 -213.978236)
		(end 250.246134 -214.404956)
		(width 0.14224)
		(layer "In2.Cu")
		(net "P3E_CPU0_P4_RX_DP<3>")
	)
	(segment
		(start 250.383294 -216.096596)
		(end 250.246134 -216.233756)
		(width 0.14224)
		(layer "In2.Cu")
		(net "P3E_CPU0_P4_RX_DP<3>")
	)
	(segment
		(start 335.504028 -313.080146)
		(end 335.92897 -313.038236)
		(width 0.14224)
		(layer "In2.Cu")
		(net "P3E_CPU0_P4_RX_DP<3>")
	)
	(segment
		(start 336.768694 -313.093608)
		(end 336.891884 -312.943494)
		(width 0.14224)
		(layer "In2.Cu")
		(net "P3E_CPU0_P4_RX_DP<3>")
	)
	(segment
		(start 310.805576 -322.87337)
		(end 312.67781 -322.097654)
		(width 0.14224)
		(layer "In2.Cu")
		(net "P3E_CPU0_P4_RX_DP<3>")
	)
	(segment
		(start 340.704932 -312.56732)
		(end 341.129874 -312.525664)
		(width 0.14224)
		(layer "In2.Cu")
		(net "P3E_CPU0_P4_RX_DP<3>")
	)
	(segment
		(start 333.82204 -313.38393)
		(end 333.944976 -313.233816)
		(width 0.14224)
		(layer "In2.Cu")
		(net "P3E_CPU0_P4_RX_DP<3>")
	)
	(segment
		(start 331.577188 -313.604402)
		(end 331.577188 -313.605164)
		(width 0.14224)
		(layer "In2.Cu")
		(net "P3E_CPU0_P4_RX_DP<3>")
	)
	(segment
		(start 250.246134 -216.660476)
		(end 250.383294 -216.797636)
		(width 0.14224)
		(layer "In2.Cu")
		(net "P3E_CPU0_P4_RX_DP<3>")
	)
	(segment
		(start 250.383294 -214.968836)
		(end 250.246134 -215.105996)
		(width 0.14224)
		(layer "In2.Cu")
		(net "P3E_CPU0_P4_RX_DP<3>")
	)
	(segment
		(start 338.060284 -312.966354)
		(end 338.183474 -312.81624)
		(width 0.14224)
		(layer "In2.Cu")
		(net "P3E_CPU0_P4_RX_DP<3>")
	)
	(segment
		(start 335.381092 -313.23026)
		(end 335.504028 -313.080146)
		(width 0.14224)
		(layer "In2.Cu")
		(net "P3E_CPU0_P4_RX_DP<3>")
	)
	(segment
		(start 318.776604 -315.998606)
		(end 319.4177 -315.73343)
		(width 0.14224)
		(layer "In2.Cu")
		(net "P3E_CPU0_P4_RX_DP<3>")
	)
	(segment
		(start 342.320372 -312.546238)
		(end 345.940126 -310.834532)
		(width 0.14224)
		(layer "In2.Cu")
		(net "P3E_CPU0_P4_RX_DP<3>")
	)
	(segment
		(start 250.246134 -215.105996)
		(end 250.246134 -215.532716)
		(width 0.14224)
		(layer "In2.Cu")
		(net "P3E_CPU0_P4_RX_DP<3>")
	)
	(segment
		(start 333.247492 -313.30265)
		(end 333.397606 -313.425586)
		(width 0.14224)
		(layer "In2.Cu")
		(net "P3E_CPU0_P4_RX_DP<3>")
	)
	(segment
		(start 341.129874 -312.525664)
		(end 341.279734 -312.6486)
		(width 0.14224)
		(layer "In2.Cu")
		(net "P3E_CPU0_P4_RX_DP<3>")
	)
	(segment
		(start 332.82255 -313.344306)
		(end 333.247492 -313.30265)
		(width 0.14224)
		(layer "In2.Cu")
		(net "P3E_CPU0_P4_RX_DP<3>")
	)
	(segment
		(start 353.027996 -296.276014)
		(end 353.027996 -296.247566)
		(width 0.1143)
		(layer "In2.Cu")
		(net "P3E_CPU0_P4_RX_DP<3>")
	)
	(segment
		(start 319.4177 -315.73343)
		(end 324.305168 -314.320936)
		(width 0.14224)
		(layer "In2.Cu")
		(net "P3E_CPU0_P4_RX_DP<3>")
	)
	(segment
		(start 334.519778 -313.314842)
		(end 335.381092 -313.23026)
		(width 0.14224)
		(layer "In2.Cu")
		(net "P3E_CPU0_P4_RX_DP<3>")
	)
	(segment
		(start 250.246134 -216.233756)
		(end 250.246134 -216.660476)
		(width 0.14224)
		(layer "In2.Cu")
		(net "P3E_CPU0_P4_RX_DP<3>")
	)
	(segment
		(start 324.305168 -314.320936)
		(end 331.577188 -313.604402)
		(width 0.14224)
		(layer "In2.Cu")
		(net "P3E_CPU0_P4_RX_DP<3>")
	)
	(segment
		(start 255.239774 -205.148942)
		(end 254.318008 -205.530704)
		(width 0.14224)
		(layer "In2.Cu")
		(net "P3E_CPU0_P4_RX_DP<3>")
	)
	(segment
		(start 250.246134 -221.30639)
		(end 251.67844 -234.631738)
		(width 0.14224)
		(layer "In2.Cu")
		(net "P3E_CPU0_P4_RX_DP<3>")
	)
	(segment
		(start 353.589082 -294.681402)
		(end 353.658678 -294.640762)
		(width 0.1143)
		(layer "In2.Cu")
		(net "P3E_CPU0_P4_RX_DP<3>")
	)
	(segment
		(start 353.738942 -294.335962)
		(end 353.441 -294.335962)
		(width 0.1143)
		(layer "In2.Cu")
		(net "P3E_CPU0_P4_RX_DP<3>")
	)
	(segment
		(start 312.67781 -322.097654)
		(end 318.776604 -315.998606)
		(width 0.14224)
		(layer "In2.Cu")
		(net "P3E_CPU0_P4_RX_DP<3>")
	)
	(segment
		(start 340.581996 -312.717688)
		(end 340.704932 -312.56732)
		(width 0.14224)
		(layer "In2.Cu")
		(net "P3E_CPU0_P4_RX_DP<3>")
	)
	(segment
		(start 336.891884 -312.943494)
		(end 337.316572 -312.901584)
		(width 0.14224)
		(layer "In2.Cu")
		(net "P3E_CPU0_P4_RX_DP<3>")
	)
	(segment
		(start 255.927098 -205.439772)
		(end 255.636268 -205.148942)
		(width 0.14224)
		(layer "In2.Cu")
		(net "P3E_CPU0_P4_RX_DP<3>")
	)
	(segment
		(start 353.027996 -296.247566)
		(end 353.073716 -296.201846)
		(width 0.1143)
		(layer "In2.Cu")
		(net "P3E_CPU0_P4_RX_DP<3>")
	)
	(segment
		(start 339.250274 -312.849006)
		(end 339.37321 -312.698892)
		(width 0.14224)
		(layer "In2.Cu")
		(net "P3E_CPU0_P4_RX_DP<3>")
	)
	(segment
		(start 250.246134 -217.361516)
		(end 250.246134 -221.30639)
		(width 0.14224)
		(layer "In2.Cu")
		(net "P3E_CPU0_P4_RX_DP<3>")
	)
	(segment
		(start 250.674632 -210.696302)
		(end 250.246134 -212.850476)
		(width 0.14224)
		(layer "In2.Cu")
		(net "P3E_CPU0_P4_RX_DP<3>")
	)
	(segment
		(start 334.369918 -313.191906)
		(end 334.519778 -313.314842)
		(width 0.14224)
		(layer "In2.Cu")
		(net "P3E_CPU0_P4_RX_DP<3>")
	)
	(arc
		(start 353.34575 -295.145968)
		(mid 353.410265 -294.883749)
		(end 353.589082 -294.681402)
		(width 0.1143)
		(layer "In2.Cu")
		(net "P3E_CPU0_P4_RX_DP<3>")
	)
	(arc
		(start 353.658678 -294.640762)
		(mid 353.756443 -294.537786)
		(end 353.808792 -294.405812)
		(width 0.1143)
		(layer "In2.Cu")
		(net "P3E_CPU0_P4_RX_DP<3>")
	)
	(arc
		(start 353.073716 -295.764204)
		(mid 353.113167 -295.577271)
		(end 353.224592 -295.422066)
		(width 0.1143)
		(layer "In2.Cu")
		(net "P3E_CPU0_P4_RX_DP<3>")
	)
	(arc
		(start 353.224592 -295.422066)
		(mid 353.314104 -295.296725)
		(end 353.34575 -295.145968)
		(width 0.1143)
		(layer "In2.Cu")
		(net "P3E_CPU0_P4_RX_DP<3>")
	)
	(segment
		(start 230.573834 -56.075072)
		(end 230.9876 -55.903622)
		(width 0.12954)
		(layer "F.Cu")
		(net "P3E_CPU0_P4_RX_DP<2>")
	)
	(segment
		(start 230.9876 -55.903622)
		(end 231.365806 -55.903622)
		(width 0.12954)
		(layer "F.Cu")
		(net "P3E_CPU0_P4_RX_DP<2>")
	)
	(segment
		(start 245.691152 -152.729438)
		(end 228.855016 -83.290664)
		(width 0.12954)
		(layer "F.Cu")
		(net "P3E_CPU0_P4_RX_DP<2>")
	)
	(segment
		(start 252.148086 -205.126844)
		(end 251.858526 -204.529944)
		(width 0.12954)
		(layer "F.Cu")
		(net "P3E_CPU0_P4_RX_DP<2>")
	)
	(segment
		(start 255.620012 -207.909922)
		(end 255.240536 -207.909922)
		(width 0.12954)
		(layer "F.Cu")
		(net "P3E_CPU0_P4_RX_DP<2>")
	)
	(segment
		(start 351.087944 -294.070024)
		(end 350.621092 -294.335962)
		(width 0.12954)
		(layer "F.Cu")
		(net "P3E_CPU0_P4_RX_DP<2>")
	)
	(segment
		(start 255.240536 -207.909922)
		(end 254.71247 -207.691228)
		(width 0.12954)
		(layer "F.Cu")
		(net "P3E_CPU0_P4_RX_DP<2>")
	)
	(segment
		(start 229.111302 -58.85688)
		(end 229.367334 -57.569354)
		(width 0.12954)
		(layer "F.Cu")
		(net "P3E_CPU0_P4_RX_DP<2>")
	)
	(segment
		(start 231.50449 -55.764938)
		(end 232.000044 -55.764938)
		(width 0.12954)
		(layer "F.Cu")
		(net "P3E_CPU0_P4_RX_DP<2>")
	)
	(segment
		(start 251.858526 -204.529944)
		(end 245.691152 -152.729438)
		(width 0.12954)
		(layer "F.Cu")
		(net "P3E_CPU0_P4_RX_DP<2>")
	)
	(segment
		(start 229.477062 -57.304178)
		(end 229.910894 -56.655208)
		(width 0.12954)
		(layer "F.Cu")
		(net "P3E_CPU0_P4_RX_DP<2>")
	)
	(segment
		(start 228.855016 -83.290664)
		(end 229.111302 -67.982338)
		(width 0.12954)
		(layer "F.Cu")
		(net "P3E_CPU0_P4_RX_DP<2>")
	)
	(segment
		(start 255.927098 -208.217008)
		(end 255.620012 -207.909922)
		(width 0.12954)
		(layer "F.Cu")
		(net "P3E_CPU0_P4_RX_DP<2>")
	)
	(segment
		(start 230.324406 -56.241696)
		(end 230.573834 -56.075072)
		(width 0.12954)
		(layer "F.Cu")
		(net "P3E_CPU0_P4_RX_DP<2>")
	)
	(segment
		(start 231.365806 -55.903622)
		(end 231.50449 -55.764938)
		(width 0.12954)
		(layer "F.Cu")
		(net "P3E_CPU0_P4_RX_DP<2>")
	)
	(segment
		(start 229.111302 -67.982338)
		(end 229.111302 -58.85688)
		(width 0.12954)
		(layer "F.Cu")
		(net "P3E_CPU0_P4_RX_DP<2>")
	)
	(segment
		(start 229.910894 -56.655208)
		(end 230.324406 -56.241696)
		(width 0.12954)
		(layer "F.Cu")
		(net "P3E_CPU0_P4_RX_DP<2>")
	)
	(segment
		(start 229.367334 -57.569354)
		(end 229.477062 -57.304178)
		(width 0.12954)
		(layer "F.Cu")
		(net "P3E_CPU0_P4_RX_DP<2>")
	)
	(segment
		(start 254.71247 -207.691228)
		(end 252.148086 -205.126844)
		(width 0.12954)
		(layer "F.Cu")
		(net "P3E_CPU0_P4_RX_DP<2>")
	)
	(segment
		(start 340.296246 -311.139332)
		(end 340.427818 -310.994044)
		(width 0.14224)
		(layer "In2.Cu")
		(net "P3E_CPU0_P4_RX_DP<2>")
	)
	(segment
		(start 330.799694 -312.075322)
		(end 330.799694 -312.074814)
		(width 0.14224)
		(layer "In2.Cu")
		(net "P3E_CPU0_P4_RX_DP<2>")
	)
	(segment
		(start 334.582516 -311.564528)
		(end 335.007204 -311.522618)
		(width 0.14224)
		(layer "In2.Cu")
		(net "P3E_CPU0_P4_RX_DP<2>")
	)
	(segment
		(start 263.052814 -321.586098)
		(end 263.053068 -321.586098)
		(width 0.14224)
		(layer "In2.Cu")
		(net "P3E_CPU0_P4_RX_DP<2>")
	)
	(segment
		(start 330.101702 -312.144156)
		(end 330.224892 -311.994042)
		(width 0.14224)
		(layer "In2.Cu")
		(net "P3E_CPU0_P4_RX_DP<2>")
	)
	(segment
		(start 330.101702 -312.143648)
		(end 330.101702 -312.144156)
		(width 0.14224)
		(layer "In2.Cu")
		(net "P3E_CPU0_P4_RX_DP<2>")
	)
	(segment
		(start 251.737876 -218.656662)
		(end 251.875036 -218.793822)
		(width 0.14224)
		(layer "In2.Cu")
		(net "P3E_CPU0_P4_RX_DP<2>")
	)
	(segment
		(start 331.49667 -312.006234)
		(end 331.49667 -312.006742)
		(width 0.14224)
		(layer "In2.Cu")
		(net "P3E_CPU0_P4_RX_DP<2>")
	)
	(segment
		(start 330.224892 -311.994042)
		(end 330.649834 -311.952132)
		(width 0.14224)
		(layer "In2.Cu")
		(net "P3E_CPU0_P4_RX_DP<2>")
	)
	(segment
		(start 331.49667 -312.006742)
		(end 331.619606 -311.856628)
		(width 0.14224)
		(layer "In2.Cu")
		(net "P3E_CPU0_P4_RX_DP<2>")
	)
	(segment
		(start 251.875036 -219.220542)
		(end 251.737876 -219.357702)
		(width 0.14224)
		(layer "In2.Cu")
		(net "P3E_CPU0_P4_RX_DP<2>")
	)
	(segment
		(start 332.194662 -311.937654)
		(end 332.194662 -311.9374)
		(width 0.14224)
		(layer "In2.Cu")
		(net "P3E_CPU0_P4_RX_DP<2>")
	)
	(segment
		(start 329.677268 -312.185812)
		(end 329.677268 -312.185304)
		(width 0.14224)
		(layer "In2.Cu")
		(net "P3E_CPU0_P4_RX_DP<2>")
	)
	(segment
		(start 340.427818 -310.994044)
		(end 340.427818 -308.78526)
		(width 0.14224)
		(layer "In2.Cu")
		(net "P3E_CPU0_P4_RX_DP<2>")
	)
	(segment
		(start 329.677268 -312.185304)
		(end 330.101702 -312.143648)
		(width 0.14224)
		(layer "In2.Cu")
		(net "P3E_CPU0_P4_RX_DP<2>")
	)
	(segment
		(start 350.769174 -294.681402)
		(end 350.83877 -294.640762)
		(width 0.1143)
		(layer "In2.Cu")
		(net "P3E_CPU0_P4_RX_DP<2>")
	)
	(segment
		(start 318.19469 -315.214508)
		(end 319.609724 -314.628276)
		(width 0.14224)
		(layer "In2.Cu")
		(net "P3E_CPU0_P4_RX_DP<2>")
	)
	(segment
		(start 328.979276 -312.254138)
		(end 328.979276 -312.254646)
		(width 0.14224)
		(layer "In2.Cu")
		(net "P3E_CPU0_P4_RX_DP<2>")
	)
	(segment
		(start 251.875036 -215.837262)
		(end 251.737876 -215.974422)
		(width 0.14224)
		(layer "In2.Cu")
		(net "P3E_CPU0_P4_RX_DP<2>")
	)
	(segment
		(start 328.979276 -312.254646)
		(end 329.102212 -312.104532)
		(width 0.14224)
		(layer "In2.Cu")
		(net "P3E_CPU0_P4_RX_DP<2>")
	)
	(segment
		(start 255.927098 -208.217008)
		(end 255.636268 -207.926178)
		(width 0.14224)
		(layer "In2.Cu")
		(net "P3E_CPU0_P4_RX_DP<2>")
	)
	(segment
		(start 350.988884 -294.405812)
		(end 350.919034 -294.335962)
		(width 0.1143)
		(layer "In2.Cu")
		(net "P3E_CPU0_P4_RX_DP<2>")
	)
	(segment
		(start 333.3369 -311.825386)
		(end 333.459836 -311.675018)
		(width 0.14224)
		(layer "In2.Cu")
		(net "P3E_CPU0_P4_RX_DP<2>")
	)
	(segment
		(start 333.459836 -311.675018)
		(end 333.884778 -311.633362)
		(width 0.14224)
		(layer "In2.Cu")
		(net "P3E_CPU0_P4_RX_DP<2>")
	)
	(segment
		(start 340.427818 -308.78526)
		(end 340.786212 -307.920136)
		(width 0.14224)
		(layer "In2.Cu")
		(net "P3E_CPU0_P4_RX_DP<2>")
	)
	(segment
		(start 335.672684 -311.595008)
		(end 335.79562 -311.44464)
		(width 0.14224)
		(layer "In2.Cu")
		(net "P3E_CPU0_P4_RX_DP<2>")
	)
	(segment
		(start 258.233164 -267.93825)
		(end 262.025384 -321.004692)
		(width 0.14224)
		(layer "In2.Cu")
		(net "P3E_CPU0_P4_RX_DP<2>")
	)
	(segment
		(start 312.212736 -321.196462)
		(end 318.19469 -315.214508)
		(width 0.14224)
		(layer "In2.Cu")
		(net "P3E_CPU0_P4_RX_DP<2>")
	)
	(segment
		(start 254.519938 -208.237836)
		(end 253.819406 -208.938368)
		(width 0.14224)
		(layer "In2.Cu")
		(net "P3E_CPU0_P4_RX_DP<2>")
	)
	(segment
		(start 343.187528 -306.729638)
		(end 348.888812 -302.05045)
		(width 0.14224)
		(layer "In2.Cu")
		(net "P3E_CPU0_P4_RX_DP<2>")
	)
	(segment
		(start 336.918046 -311.33415)
		(end 337.342988 -311.29224)
		(width 0.14224)
		(layer "In2.Cu")
		(net "P3E_CPU0_P4_RX_DP<2>")
	)
	(segment
		(start 253.819406 -208.938368)
		(end 253.300484 -209.7151)
		(width 0.14224)
		(layer "In2.Cu")
		(net "P3E_CPU0_P4_RX_DP<2>")
	)
	(segment
		(start 252.258068 -212.231986)
		(end 251.737876 -214.846662)
		(width 0.14224)
		(layer "In2.Cu")
		(net "P3E_CPU0_P4_RX_DP<2>")
	)
	(segment
		(start 333.3369 -311.824878)
		(end 333.3369 -311.825386)
		(width 0.14224)
		(layer "In2.Cu")
		(net "P3E_CPU0_P4_RX_DP<2>")
	)
	(segment
		(start 330.799694 -312.074814)
		(end 331.49667 -312.006234)
		(width 0.14224)
		(layer "In2.Cu")
		(net "P3E_CPU0_P4_RX_DP<2>")
	)
	(segment
		(start 350.282764 -298.149772)
		(end 350.282764 -295.698672)
		(width 0.1143)
		(layer "In2.Cu")
		(net "P3E_CPU0_P4_RX_DP<2>")
	)
	(segment
		(start 334.459326 -311.714642)
		(end 334.582516 -311.564528)
		(width 0.14224)
		(layer "In2.Cu")
		(net "P3E_CPU0_P4_RX_DP<2>")
	)
	(segment
		(start 337.342988 -311.29224)
		(end 337.493102 -311.41543)
		(width 0.14224)
		(layer "In2.Cu")
		(net "P3E_CPU0_P4_RX_DP<2>")
	)
	(segment
		(start 334.034892 -311.756298)
		(end 334.034892 -311.756044)
		(width 0.14224)
		(layer "In2.Cu")
		(net "P3E_CPU0_P4_RX_DP<2>")
	)
	(segment
		(start 337.493356 -311.41543)
		(end 340.296246 -311.139332)
		(width 0.14224)
		(layer "In2.Cu")
		(net "P3E_CPU0_P4_RX_DP<2>")
	)
	(segment
		(start 340.786212 -307.920136)
		(end 341.120222 -307.586126)
		(width 0.14224)
		(layer "In2.Cu")
		(net "P3E_CPU0_P4_RX_DP<2>")
	)
	(segment
		(start 333.884778 -311.633362)
		(end 334.034892 -311.756298)
		(width 0.14224)
		(layer "In2.Cu")
		(net "P3E_CPU0_P4_RX_DP<2>")
	)
	(segment
		(start 348.888812 -302.05045)
		(end 350.237044 -300.702472)
		(width 0.14224)
		(layer "In2.Cu")
		(net "P3E_CPU0_P4_RX_DP<2>")
	)
	(segment
		(start 330.649834 -311.952132)
		(end 330.799694 -312.075322)
		(width 0.14224)
		(layer "In2.Cu")
		(net "P3E_CPU0_P4_RX_DP<2>")
	)
	(segment
		(start 251.875036 -215.410542)
		(end 251.875036 -215.837262)
		(width 0.14224)
		(layer "In2.Cu")
		(net "P3E_CPU0_P4_RX_DP<2>")
	)
	(segment
		(start 334.459326 -311.714388)
		(end 334.459326 -311.714642)
		(width 0.14224)
		(layer "In2.Cu")
		(net "P3E_CPU0_P4_RX_DP<2>")
	)
	(segment
		(start 255.636268 -207.926178)
		(end 255.272286 -207.926178)
		(width 0.14224)
		(layer "In2.Cu")
		(net "P3E_CPU0_P4_RX_DP<2>")
	)
	(segment
		(start 325.758556 -312.762646)
		(end 326.691752 -312.47969)
		(width 0.14224)
		(layer "In2.Cu")
		(net "P3E_CPU0_P4_RX_DP<2>")
	)
	(segment
		(start 251.737876 -219.357702)
		(end 251.737876 -226.295458)
		(width 0.14224)
		(layer "In2.Cu")
		(net "P3E_CPU0_P4_RX_DP<2>")
	)
	(segment
		(start 251.875036 -216.965022)
		(end 251.737876 -217.102182)
		(width 0.14224)
		(layer "In2.Cu")
		(net "P3E_CPU0_P4_RX_DP<2>")
	)
	(segment
		(start 251.875036 -218.092782)
		(end 251.737876 -218.229942)
		(width 0.14224)
		(layer "In2.Cu")
		(net "P3E_CPU0_P4_RX_DP<2>")
	)
	(segment
		(start 335.157318 -311.645554)
		(end 335.672684 -311.594754)
		(width 0.14224)
		(layer "In2.Cu")
		(net "P3E_CPU0_P4_RX_DP<2>")
	)
	(segment
		(start 325.08698 -312.966608)
		(end 325.087488 -312.966608)
		(width 0.14224)
		(layer "In2.Cu")
		(net "P3E_CPU0_P4_RX_DP<2>")
	)
	(segment
		(start 251.737876 -226.295458)
		(end 252.635766 -234.647486)
		(width 0.14224)
		(layer "In2.Cu")
		(net "P3E_CPU0_P4_RX_DP<2>")
	)
	(segment
		(start 350.919034 -294.335962)
		(end 350.621092 -294.335962)
		(width 0.1143)
		(layer "In2.Cu")
		(net "P3E_CPU0_P4_RX_DP<2>")
	)
	(segment
		(start 251.737876 -215.273382)
		(end 251.875036 -215.410542)
		(width 0.14224)
		(layer "In2.Cu")
		(net "P3E_CPU0_P4_RX_DP<2>")
	)
	(segment
		(start 255.272286 -207.926178)
		(end 254.519938 -208.237836)
		(width 0.14224)
		(layer "In2.Cu")
		(net "P3E_CPU0_P4_RX_DP<2>")
	)
	(segment
		(start 329.527154 -312.062622)
		(end 329.677268 -312.185812)
		(width 0.14224)
		(layer "In2.Cu")
		(net "P3E_CPU0_P4_RX_DP<2>")
	)
	(segment
		(start 325.087488 -312.966608)
		(end 325.178928 -312.795158)
		(width 0.14224)
		(layer "In2.Cu")
		(net "P3E_CPU0_P4_RX_DP<2>")
	)
	(segment
		(start 251.875036 -218.793822)
		(end 251.875036 -219.220542)
		(width 0.14224)
		(layer "In2.Cu")
		(net "P3E_CPU0_P4_RX_DP<2>")
	)
	(segment
		(start 350.237044 -300.702472)
		(end 350.237044 -298.22394)
		(width 0.14224)
		(layer "In2.Cu")
		(net "P3E_CPU0_P4_RX_DP<2>")
	)
	(segment
		(start 251.737876 -215.974422)
		(end 251.737876 -216.401142)
		(width 0.14224)
		(layer "In2.Cu")
		(net "P3E_CPU0_P4_RX_DP<2>")
	)
	(segment
		(start 263.053068 -321.586098)
		(end 310.496204 -321.907154)
		(width 0.14224)
		(layer "In2.Cu")
		(net "P3E_CPU0_P4_RX_DP<2>")
	)
	(segment
		(start 252.635766 -234.647486)
		(end 258.233164 -267.93825)
		(width 0.14224)
		(layer "In2.Cu")
		(net "P3E_CPU0_P4_RX_DP<2>")
	)
	(segment
		(start 262.025384 -321.004692)
		(end 262.286496 -321.26555)
		(width 0.14224)
		(layer "In2.Cu")
		(net "P3E_CPU0_P4_RX_DP<2>")
	)
	(segment
		(start 341.120222 -307.586126)
		(end 343.187528 -306.729638)
		(width 0.14224)
		(layer "In2.Cu")
		(net "P3E_CPU0_P4_RX_DP<2>")
	)
	(segment
		(start 325.178928 -312.795158)
		(end 325.587614 -312.671206)
		(width 0.14224)
		(layer "In2.Cu")
		(net "P3E_CPU0_P4_RX_DP<2>")
	)
	(segment
		(start 337.493102 -311.41543)
		(end 337.493356 -311.41543)
		(width 0.14224)
		(layer "In2.Cu")
		(net "P3E_CPU0_P4_RX_DP<2>")
	)
	(segment
		(start 253.300484 -209.7151)
		(end 252.258068 -212.231986)
		(width 0.14224)
		(layer "In2.Cu")
		(net "P3E_CPU0_P4_RX_DP<2>")
	)
	(segment
		(start 251.875036 -216.538302)
		(end 251.875036 -216.965022)
		(width 0.14224)
		(layer "In2.Cu")
		(net "P3E_CPU0_P4_RX_DP<2>")
	)
	(segment
		(start 251.737876 -217.102182)
		(end 251.737876 -217.528902)
		(width 0.14224)
		(layer "In2.Cu")
		(net "P3E_CPU0_P4_RX_DP<2>")
	)
	(segment
		(start 350.237044 -298.195492)
		(end 350.282764 -298.149772)
		(width 0.1143)
		(layer "In2.Cu")
		(net "P3E_CPU0_P4_RX_DP<2>")
	)
	(segment
		(start 262.286496 -321.26555)
		(end 263.052814 -321.586098)
		(width 0.14224)
		(layer "In2.Cu")
		(net "P3E_CPU0_P4_RX_DP<2>")
	)
	(segment
		(start 335.672684 -311.594754)
		(end 335.672684 -311.595008)
		(width 0.14224)
		(layer "In2.Cu")
		(net "P3E_CPU0_P4_RX_DP<2>")
	)
	(segment
		(start 251.737876 -216.401142)
		(end 251.875036 -216.538302)
		(width 0.14224)
		(layer "In2.Cu")
		(net "P3E_CPU0_P4_RX_DP<2>")
	)
	(segment
		(start 251.737876 -218.229942)
		(end 251.737876 -218.656662)
		(width 0.14224)
		(layer "In2.Cu")
		(net "P3E_CPU0_P4_RX_DP<2>")
	)
	(segment
		(start 251.737876 -217.528902)
		(end 251.875036 -217.666062)
		(width 0.14224)
		(layer "In2.Cu")
		(net "P3E_CPU0_P4_RX_DP<2>")
	)
	(segment
		(start 329.102212 -312.104532)
		(end 329.527154 -312.062622)
		(width 0.14224)
		(layer "In2.Cu")
		(net "P3E_CPU0_P4_RX_DP<2>")
	)
	(segment
		(start 331.619606 -311.856628)
		(end 332.044548 -311.814718)
		(width 0.14224)
		(layer "In2.Cu")
		(net "P3E_CPU0_P4_RX_DP<2>")
	)
	(segment
		(start 251.737876 -214.846662)
		(end 251.737876 -215.273382)
		(width 0.14224)
		(layer "In2.Cu")
		(net "P3E_CPU0_P4_RX_DP<2>")
	)
	(segment
		(start 251.875036 -217.666062)
		(end 251.875036 -218.092782)
		(width 0.14224)
		(layer "In2.Cu")
		(net "P3E_CPU0_P4_RX_DP<2>")
	)
	(segment
		(start 334.034892 -311.756044)
		(end 334.459326 -311.714388)
		(width 0.14224)
		(layer "In2.Cu")
		(net "P3E_CPU0_P4_RX_DP<2>")
	)
	(segment
		(start 326.691752 -312.47969)
		(end 328.979276 -312.254138)
		(width 0.14224)
		(layer "In2.Cu")
		(net "P3E_CPU0_P4_RX_DP<2>")
	)
	(segment
		(start 325.587614 -312.671206)
		(end 325.758556 -312.762646)
		(width 0.14224)
		(layer "In2.Cu")
		(net "P3E_CPU0_P4_RX_DP<2>")
	)
	(segment
		(start 319.609724 -314.628276)
		(end 325.08698 -312.966608)
		(width 0.14224)
		(layer "In2.Cu")
		(net "P3E_CPU0_P4_RX_DP<2>")
	)
	(segment
		(start 332.044548 -311.814718)
		(end 332.194662 -311.937654)
		(width 0.14224)
		(layer "In2.Cu")
		(net "P3E_CPU0_P4_RX_DP<2>")
	)
	(segment
		(start 336.79511 -311.484264)
		(end 336.918046 -311.33415)
		(width 0.14224)
		(layer "In2.Cu")
		(net "P3E_CPU0_P4_RX_DP<2>")
	)
	(segment
		(start 332.194662 -311.9374)
		(end 333.3369 -311.824878)
		(width 0.14224)
		(layer "In2.Cu")
		(net "P3E_CPU0_P4_RX_DP<2>")
	)
	(segment
		(start 336.220562 -311.402984)
		(end 336.370676 -311.52592)
		(width 0.14224)
		(layer "In2.Cu")
		(net "P3E_CPU0_P4_RX_DP<2>")
	)
	(segment
		(start 310.496204 -321.907154)
		(end 312.212736 -321.196462)
		(width 0.14224)
		(layer "In2.Cu")
		(net "P3E_CPU0_P4_RX_DP<2>")
	)
	(segment
		(start 335.007204 -311.522618)
		(end 335.157318 -311.645554)
		(width 0.14224)
		(layer "In2.Cu")
		(net "P3E_CPU0_P4_RX_DP<2>")
	)
	(segment
		(start 336.370676 -311.52592)
		(end 336.79511 -311.484264)
		(width 0.14224)
		(layer "In2.Cu")
		(net "P3E_CPU0_P4_RX_DP<2>")
	)
	(segment
		(start 350.237044 -298.22394)
		(end 350.237044 -298.195492)
		(width 0.1143)
		(layer "In2.Cu")
		(net "P3E_CPU0_P4_RX_DP<2>")
	)
	(segment
		(start 335.79562 -311.44464)
		(end 336.220562 -311.402984)
		(width 0.14224)
		(layer "In2.Cu")
		(net "P3E_CPU0_P4_RX_DP<2>")
	)
	(arc
		(start 350.83877 -294.640762)
		(mid 350.936535 -294.537786)
		(end 350.988884 -294.405812)
		(width 0.1143)
		(layer "In2.Cu")
		(net "P3E_CPU0_P4_RX_DP<2>")
	)
	(arc
		(start 350.282764 -295.698672)
		(mid 350.314529 -295.5477)
		(end 350.40443 -295.42232)
		(width 0.1143)
		(layer "In2.Cu")
		(net "P3E_CPU0_P4_RX_DP<2>")
	)
	(arc
		(start 350.525842 -295.145968)
		(mid 350.590357 -294.883749)
		(end 350.769174 -294.681402)
		(width 0.1143)
		(layer "In2.Cu")
		(net "P3E_CPU0_P4_RX_DP<2>")
	)
	(arc
		(start 350.40443 -295.42232)
		(mid 350.494137 -295.296895)
		(end 350.525842 -295.145968)
		(width 0.1143)
		(layer "In2.Cu")
		(net "P3E_CPU0_P4_RX_DP<2>")
	)
	(segment
		(start 244.394482 -150.814786)
		(end 228.049074 -83.398868)
		(width 0.12954)
		(layer "F.Cu")
		(net "P3E_CPU0_P4_RX_DP<1>")
	)
	(segment
		(start 229.852982 -55.072788)
		(end 230.48722 -54.43855)
		(width 0.12954)
		(layer "F.Cu")
		(net "P3E_CPU0_P4_RX_DP<1>")
	)
	(segment
		(start 250.853448 -205.067662)
		(end 244.394482 -150.814786)
		(width 0.12954)
		(layer "F.Cu")
		(net "P3E_CPU0_P4_RX_DP<1>")
	)
	(segment
		(start 231.385618 -54.103778)
		(end 231.524302 -53.965094)
		(width 0.12954)
		(layer "F.Cu")
		(net "P3E_CPU0_P4_RX_DP<1>")
	)
	(segment
		(start 228.302566 -58.354214)
		(end 228.48697 -57.426098)
		(width 0.12954)
		(layer "F.Cu")
		(net "P3E_CPU0_P4_RX_DP<1>")
	)
	(segment
		(start 348.268036 -294.070024)
		(end 347.801184 -294.335962)
		(width 0.12954)
		(layer "F.Cu")
		(net "P3E_CPU0_P4_RX_DP<1>")
	)
	(segment
		(start 252.665738 -208.800446)
		(end 250.853448 -205.067662)
		(width 0.12954)
		(layer "F.Cu")
		(net "P3E_CPU0_P4_RX_DP<1>")
	)
	(segment
		(start 255.09474 -210.718146)
		(end 254.221996 -210.356704)
		(width 0.12954)
		(layer "F.Cu")
		(net "P3E_CPU0_P4_RX_DP<1>")
	)
	(segment
		(start 231.110282 -54.103778)
		(end 231.385618 -54.103778)
		(width 0.12954)
		(layer "F.Cu")
		(net "P3E_CPU0_P4_RX_DP<1>")
	)
	(segment
		(start 254.221996 -210.356704)
		(end 252.665738 -208.800446)
		(width 0.12954)
		(layer "F.Cu")
		(net "P3E_CPU0_P4_RX_DP<1>")
	)
	(segment
		(start 230.48722 -54.43855)
		(end 230.78948 -54.23662)
		(width 0.12954)
		(layer "F.Cu")
		(net "P3E_CPU0_P4_RX_DP<1>")
	)
	(segment
		(start 228.302566 -68.262246)
		(end 228.302566 -58.354214)
		(width 0.12954)
		(layer "F.Cu")
		(net "P3E_CPU0_P4_RX_DP<1>")
	)
	(segment
		(start 231.524302 -53.965094)
		(end 232.000044 -53.965094)
		(width 0.12954)
		(layer "F.Cu")
		(net "P3E_CPU0_P4_RX_DP<1>")
	)
	(segment
		(start 255.927098 -211.011516)
		(end 255.633728 -210.718146)
		(width 0.12954)
		(layer "F.Cu")
		(net "P3E_CPU0_P4_RX_DP<1>")
	)
	(segment
		(start 228.48697 -57.426098)
		(end 228.823266 -56.61406)
		(width 0.12954)
		(layer "F.Cu")
		(net "P3E_CPU0_P4_RX_DP<1>")
	)
	(segment
		(start 228.823266 -56.61406)
		(end 229.852982 -55.072788)
		(width 0.12954)
		(layer "F.Cu")
		(net "P3E_CPU0_P4_RX_DP<1>")
	)
	(segment
		(start 230.78948 -54.23662)
		(end 231.110282 -54.103778)
		(width 0.12954)
		(layer "F.Cu")
		(net "P3E_CPU0_P4_RX_DP<1>")
	)
	(segment
		(start 228.049074 -83.398868)
		(end 228.302566 -68.262246)
		(width 0.12954)
		(layer "F.Cu")
		(net "P3E_CPU0_P4_RX_DP<1>")
	)
	(segment
		(start 255.633728 -210.718146)
		(end 255.09474 -210.718146)
		(width 0.12954)
		(layer "F.Cu")
		(net "P3E_CPU0_P4_RX_DP<1>")
	)
	(segment
		(start 253.538736 -214.995506)
		(end 253.538736 -215.422226)
		(width 0.14224)
		(layer "In2.Cu")
		(net "P3E_CPU0_P4_RX_DP<1>")
	)
	(segment
		(start 342.603582 -302.133508)
		(end 342.98001 -301.93234)
		(width 0.14224)
		(layer "In2.Cu")
		(net "P3E_CPU0_P4_RX_DP<1>")
	)
	(segment
		(start 253.538736 -217.677746)
		(end 253.401576 -217.814906)
		(width 0.14224)
		(layer "In2.Cu")
		(net "P3E_CPU0_P4_RX_DP<1>")
	)
	(segment
		(start 333.331312 -307.574442)
		(end 333.52232 -307.607716)
		(width 0.14224)
		(layer "In2.Cu")
		(net "P3E_CPU0_P4_RX_DP<1>")
	)
	(segment
		(start 331.750924 -308.85384)
		(end 332.948788 -308.011322)
		(width 0.14224)
		(layer "In2.Cu")
		(net "P3E_CPU0_P4_RX_DP<1>")
	)
	(segment
		(start 263.438386 -320.599054)
		(end 310.418226 -320.917316)
		(width 0.14224)
		(layer "In2.Cu")
		(net "P3E_CPU0_P4_RX_DP<1>")
	)
	(segment
		(start 339.794596 -303.634648)
		(end 340.171024 -303.43348)
		(width 0.14224)
		(layer "In2.Cu")
		(net "P3E_CPU0_P4_RX_DP<1>")
	)
	(segment
		(start 255.172972 -210.787234)
		(end 254.949706 -210.936332)
		(width 0.14224)
		(layer "In2.Cu")
		(net "P3E_CPU0_P4_RX_DP<1>")
	)
	(segment
		(start 253.401576 -214.431626)
		(end 253.401576 -214.858346)
		(width 0.14224)
		(layer "In2.Cu")
		(net "P3E_CPU0_P4_RX_DP<1>")
	)
	(segment
		(start 347.354652 -296.797476)
		(end 347.354652 -296.069766)
		(width 0.1143)
		(layer "In2.Cu")
		(net "P3E_CPU0_P4_RX_DP<1>")
	)
	(segment
		(start 253.633986 -213.263226)
		(end 253.401576 -214.431626)
		(width 0.14224)
		(layer "In2.Cu")
		(net "P3E_CPU0_P4_RX_DP<1>")
	)
	(segment
		(start 254.23876 -211.80298)
		(end 253.633986 -213.263226)
		(width 0.14224)
		(layer "In2.Cu")
		(net "P3E_CPU0_P4_RX_DP<1>")
	)
	(segment
		(start 253.401576 -231.303068)
		(end 253.983744 -236.71657)
		(width 0.14224)
		(layer "In2.Cu")
		(net "P3E_CPU0_P4_RX_DP<1>")
	)
	(segment
		(start 347.308932 -296.843196)
		(end 347.354652 -296.797476)
		(width 0.1143)
		(layer "In2.Cu")
		(net "P3E_CPU0_P4_RX_DP<1>")
	)
	(segment
		(start 329.426824 -310.096408)
		(end 331.750924 -308.85384)
		(width 0.14224)
		(layer "In2.Cu")
		(net "P3E_CPU0_P4_RX_DP<1>")
	)
	(segment
		(start 344.182192 -301.289974)
		(end 344.36431 -301.345346)
		(width 0.14224)
		(layer "In2.Cu")
		(net "P3E_CPU0_P4_RX_DP<1>")
	)
	(segment
		(start 311.706768 -320.383662)
		(end 317.683642 -314.406788)
		(width 0.14224)
		(layer "In2.Cu")
		(net "P3E_CPU0_P4_RX_DP<1>")
	)
	(segment
		(start 337.190588 -305.026568)
		(end 337.372706 -305.08194)
		(width 0.14224)
		(layer "In2.Cu")
		(net "P3E_CPU0_P4_RX_DP<1>")
	)
	(segment
		(start 253.401576 -216.687146)
		(end 253.401576 -217.113866)
		(width 0.14224)
		(layer "In2.Cu")
		(net "P3E_CPU0_P4_RX_DP<1>")
	)
	(segment
		(start 255.391666 -210.720686)
		(end 255.172972 -210.787234)
		(width 0.14224)
		(layer "In2.Cu")
		(net "P3E_CPU0_P4_RX_DP<1>")
	)
	(segment
		(start 253.538736 -216.549986)
		(end 253.401576 -216.687146)
		(width 0.14224)
		(layer "In2.Cu")
		(net "P3E_CPU0_P4_RX_DP<1>")
	)
	(segment
		(start 348.168976 -294.405812)
		(end 348.099126 -294.335962)
		(width 0.1143)
		(layer "In2.Cu")
		(net "P3E_CPU0_P4_RX_DP<1>")
	)
	(segment
		(start 338.363052 -304.552604)
		(end 338.739226 -304.35169)
		(width 0.14224)
		(layer "In2.Cu")
		(net "P3E_CPU0_P4_RX_DP<1>")
	)
	(segment
		(start 332.982062 -307.82006)
		(end 333.331312 -307.574442)
		(width 0.14224)
		(layer "In2.Cu")
		(net "P3E_CPU0_P4_RX_DP<1>")
	)
	(segment
		(start 340.171024 -303.43348)
		(end 340.353396 -303.488852)
		(width 0.14224)
		(layer "In2.Cu")
		(net "P3E_CPU0_P4_RX_DP<1>")
	)
	(segment
		(start 317.683642 -314.406788)
		(end 319.593214 -313.615832)
		(width 0.14224)
		(layer "In2.Cu")
		(net "P3E_CPU0_P4_RX_DP<1>")
	)
	(segment
		(start 336.758534 -305.410108)
		(end 336.813906 -305.227736)
		(width 0.14224)
		(layer "In2.Cu")
		(net "P3E_CPU0_P4_RX_DP<1>")
	)
	(segment
		(start 340.353396 -303.488852)
		(end 342.54821 -302.316134)
		(width 0.14224)
		(layer "In2.Cu")
		(net "P3E_CPU0_P4_RX_DP<1>")
	)
	(segment
		(start 253.401576 -218.942666)
		(end 253.401576 -231.303068)
		(width 0.14224)
		(layer "In2.Cu")
		(net "P3E_CPU0_P4_RX_DP<1>")
	)
	(segment
		(start 343.80551 -301.491142)
		(end 344.182192 -301.289974)
		(width 0.14224)
		(layer "In2.Cu")
		(net "P3E_CPU0_P4_RX_DP<1>")
	)
	(segment
		(start 343.750138 -301.673514)
		(end 343.80551 -301.491142)
		(width 0.14224)
		(layer "In2.Cu")
		(net "P3E_CPU0_P4_RX_DP<1>")
	)
	(segment
		(start 347.308932 -296.871644)
		(end 347.308932 -296.843196)
		(width 0.1143)
		(layer "In2.Cu")
		(net "P3E_CPU0_P4_RX_DP<1>")
	)
	(segment
		(start 347.949266 -294.681402)
		(end 348.018862 -294.640762)
		(width 0.1143)
		(layer "In2.Cu")
		(net "P3E_CPU0_P4_RX_DP<1>")
	)
	(segment
		(start 347.46311 -295.807638)
		(end 347.46311 -295.698672)
		(width 0.1143)
		(layer "In2.Cu")
		(net "P3E_CPU0_P4_RX_DP<1>")
	)
	(segment
		(start 345.632532 -300.667674)
		(end 347.308932 -298.991528)
		(width 0.14224)
		(layer "In2.Cu")
		(net "P3E_CPU0_P4_RX_DP<1>")
	)
	(segment
		(start 253.538736 -215.422226)
		(end 253.401576 -215.559386)
		(width 0.14224)
		(layer "In2.Cu")
		(net "P3E_CPU0_P4_RX_DP<1>")
	)
	(segment
		(start 255.927098 -211.011516)
		(end 255.636268 -210.720686)
		(width 0.14224)
		(layer "In2.Cu")
		(net "P3E_CPU0_P4_RX_DP<1>")
	)
	(segment
		(start 339.17128 -303.96815)
		(end 339.353398 -304.023268)
		(width 0.14224)
		(layer "In2.Cu")
		(net "P3E_CPU0_P4_RX_DP<1>")
	)
	(segment
		(start 253.538736 -218.805506)
		(end 253.401576 -218.942666)
		(width 0.14224)
		(layer "In2.Cu")
		(net "P3E_CPU0_P4_RX_DP<1>")
	)
	(segment
		(start 253.401576 -218.241626)
		(end 253.538736 -218.378786)
		(width 0.14224)
		(layer "In2.Cu")
		(net "P3E_CPU0_P4_RX_DP<1>")
	)
	(segment
		(start 334.185006 -306.97678)
		(end 334.534256 -306.730908)
		(width 0.14224)
		(layer "In2.Cu")
		(net "P3E_CPU0_P4_RX_DP<1>")
	)
	(segment
		(start 342.98001 -301.93234)
		(end 343.162128 -301.987712)
		(width 0.14224)
		(layer "In2.Cu")
		(net "P3E_CPU0_P4_RX_DP<1>")
	)
	(segment
		(start 337.372706 -305.08194)
		(end 337.74888 -304.881026)
		(width 0.14224)
		(layer "In2.Cu")
		(net "P3E_CPU0_P4_RX_DP<1>")
	)
	(segment
		(start 253.538736 -218.378786)
		(end 253.538736 -218.805506)
		(width 0.14224)
		(layer "In2.Cu")
		(net "P3E_CPU0_P4_RX_DP<1>")
	)
	(segment
		(start 339.739224 -303.81702)
		(end 339.794596 -303.634648)
		(width 0.14224)
		(layer "In2.Cu")
		(net "P3E_CPU0_P4_RX_DP<1>")
	)
	(segment
		(start 348.099126 -294.335962)
		(end 347.801184 -294.335962)
		(width 0.1143)
		(layer "In2.Cu")
		(net "P3E_CPU0_P4_RX_DP<1>")
	)
	(segment
		(start 338.18068 -304.497486)
		(end 338.363052 -304.552604)
		(width 0.14224)
		(layer "In2.Cu")
		(net "P3E_CPU0_P4_RX_DP<1>")
	)
	(segment
		(start 334.721962 -306.76342)
		(end 336.28711 -305.662076)
		(width 0.14224)
		(layer "In2.Cu")
		(net "P3E_CPU0_P4_RX_DP<1>")
	)
	(segment
		(start 310.418226 -320.917316)
		(end 311.706768 -320.383662)
		(width 0.14224)
		(layer "In2.Cu")
		(net "P3E_CPU0_P4_RX_DP<1>")
	)
	(segment
		(start 262.92429 -320.383662)
		(end 263.438386 -320.599054)
		(width 0.14224)
		(layer "In2.Cu")
		(net "P3E_CPU0_P4_RX_DP<1>")
	)
	(segment
		(start 319.593214 -313.615832)
		(end 329.426824 -310.096408)
		(width 0.14224)
		(layer "In2.Cu")
		(net "P3E_CPU0_P4_RX_DP<1>")
	)
	(segment
		(start 347.308932 -298.991528)
		(end 347.308932 -296.871644)
		(width 0.14224)
		(layer "In2.Cu")
		(net "P3E_CPU0_P4_RX_DP<1>")
	)
	(segment
		(start 336.28711 -305.662076)
		(end 336.758534 -305.410108)
		(width 0.14224)
		(layer "In2.Cu")
		(net "P3E_CPU0_P4_RX_DP<1>")
	)
	(segment
		(start 253.401576 -214.858346)
		(end 253.538736 -214.995506)
		(width 0.14224)
		(layer "In2.Cu")
		(net "P3E_CPU0_P4_RX_DP<1>")
	)
	(segment
		(start 334.534256 -306.730908)
		(end 334.721962 -306.76342)
		(width 0.14224)
		(layer "In2.Cu")
		(net "P3E_CPU0_P4_RX_DP<1>")
	)
	(segment
		(start 343.162128 -301.987712)
		(end 343.750138 -301.673514)
		(width 0.14224)
		(layer "In2.Cu")
		(net "P3E_CPU0_P4_RX_DP<1>")
	)
	(segment
		(start 337.74888 -304.881026)
		(end 337.804252 -304.6984)
		(width 0.14224)
		(layer "In2.Cu")
		(net "P3E_CPU0_P4_RX_DP<1>")
	)
	(segment
		(start 253.401576 -215.986106)
		(end 253.538736 -216.123266)
		(width 0.14224)
		(layer "In2.Cu")
		(net "P3E_CPU0_P4_RX_DP<1>")
	)
	(segment
		(start 336.813906 -305.227736)
		(end 337.190588 -305.026568)
		(width 0.14224)
		(layer "In2.Cu")
		(net "P3E_CPU0_P4_RX_DP<1>")
	)
	(segment
		(start 253.983744 -236.71657)
		(end 259.13334 -267.34516)
		(width 0.14224)
		(layer "In2.Cu")
		(net "P3E_CPU0_P4_RX_DP<1>")
	)
	(segment
		(start 338.794598 -304.169064)
		(end 339.17128 -303.96815)
		(width 0.14224)
		(layer "In2.Cu")
		(net "P3E_CPU0_P4_RX_DP<1>")
	)
	(segment
		(start 337.804252 -304.6984)
		(end 338.18068 -304.497486)
		(width 0.14224)
		(layer "In2.Cu")
		(net "P3E_CPU0_P4_RX_DP<1>")
	)
	(segment
		(start 253.401576 -217.814906)
		(end 253.401576 -218.241626)
		(width 0.14224)
		(layer "In2.Cu")
		(net "P3E_CPU0_P4_RX_DP<1>")
	)
	(segment
		(start 253.401576 -217.113866)
		(end 253.538736 -217.251026)
		(width 0.14224)
		(layer "In2.Cu")
		(net "P3E_CPU0_P4_RX_DP<1>")
	)
	(segment
		(start 338.739226 -304.35169)
		(end 338.794598 -304.169064)
		(width 0.14224)
		(layer "In2.Cu")
		(net "P3E_CPU0_P4_RX_DP<1>")
	)
	(segment
		(start 254.949706 -210.936332)
		(end 254.23876 -211.80298)
		(width 0.14224)
		(layer "In2.Cu")
		(net "P3E_CPU0_P4_RX_DP<1>")
	)
	(segment
		(start 259.13334 -267.34516)
		(end 262.92429 -320.383662)
		(width 0.14224)
		(layer "In2.Cu")
		(net "P3E_CPU0_P4_RX_DP<1>")
	)
	(segment
		(start 344.36431 -301.345346)
		(end 345.632532 -300.667674)
		(width 0.14224)
		(layer "In2.Cu")
		(net "P3E_CPU0_P4_RX_DP<1>")
	)
	(segment
		(start 253.538736 -217.251026)
		(end 253.538736 -217.677746)
		(width 0.14224)
		(layer "In2.Cu")
		(net "P3E_CPU0_P4_RX_DP<1>")
	)
	(segment
		(start 255.636268 -210.720686)
		(end 255.391666 -210.720686)
		(width 0.14224)
		(layer "In2.Cu")
		(net "P3E_CPU0_P4_RX_DP<1>")
	)
	(segment
		(start 339.353398 -304.023268)
		(end 339.739224 -303.81702)
		(width 0.14224)
		(layer "In2.Cu")
		(net "P3E_CPU0_P4_RX_DP<1>")
	)
	(segment
		(start 253.401576 -215.559386)
		(end 253.401576 -215.986106)
		(width 0.14224)
		(layer "In2.Cu")
		(net "P3E_CPU0_P4_RX_DP<1>")
	)
	(segment
		(start 342.54821 -302.316134)
		(end 342.603582 -302.133508)
		(width 0.14224)
		(layer "In2.Cu")
		(net "P3E_CPU0_P4_RX_DP<1>")
	)
	(segment
		(start 332.948788 -308.011322)
		(end 332.982062 -307.82006)
		(width 0.14224)
		(layer "In2.Cu")
		(net "P3E_CPU0_P4_RX_DP<1>")
	)
	(segment
		(start 334.152494 -307.164232)
		(end 334.185006 -306.97678)
		(width 0.14224)
		(layer "In2.Cu")
		(net "P3E_CPU0_P4_RX_DP<1>")
	)
	(segment
		(start 253.538736 -216.123266)
		(end 253.538736 -216.549986)
		(width 0.14224)
		(layer "In2.Cu")
		(net "P3E_CPU0_P4_RX_DP<1>")
	)
	(segment
		(start 333.52232 -307.607716)
		(end 334.152494 -307.164232)
		(width 0.14224)
		(layer "In2.Cu")
		(net "P3E_CPU0_P4_RX_DP<1>")
	)
	(arc
		(start 347.354652 -296.069766)
		(mid 347.366914 -296.008029)
		(end 347.401896 -295.95572)
		(width 0.1143)
		(layer "In2.Cu")
		(net "P3E_CPU0_P4_RX_DP<1>")
	)
	(arc
		(start 347.584522 -295.422066)
		(mid 347.628878 -295.373509)
		(end 347.664024 -295.317926)
		(width 0.1143)
		(layer "In2.Cu")
		(net "P3E_CPU0_P4_RX_DP<1>")
	)
	(arc
		(start 348.018862 -294.640762)
		(mid 348.116627 -294.537786)
		(end 348.168976 -294.405812)
		(width 0.1143)
		(layer "In2.Cu")
		(net "P3E_CPU0_P4_RX_DP<1>")
	)
	(arc
		(start 347.46311 -295.698672)
		(mid 347.4947 -295.547589)
		(end 347.584522 -295.422066)
		(width 0.1143)
		(layer "In2.Cu")
		(net "P3E_CPU0_P4_RX_DP<1>")
	)
	(arc
		(start 347.664024 -295.317926)
		(mid 347.695265 -295.234455)
		(end 347.705934 -295.145968)
		(width 0.1143)
		(layer "In2.Cu")
		(net "P3E_CPU0_P4_RX_DP<1>")
	)
	(arc
		(start 347.705934 -295.145968)
		(mid 347.770449 -294.883749)
		(end 347.949266 -294.681402)
		(width 0.1143)
		(layer "In2.Cu")
		(net "P3E_CPU0_P4_RX_DP<1>")
	)
	(arc
		(start 347.401896 -295.95572)
		(mid 347.447209 -295.887764)
		(end 347.46311 -295.807638)
		(width 0.1143)
		(layer "In2.Cu")
		(net "P3E_CPU0_P4_RX_DP<1>")
	)
	(segment
		(start 249.901202 -205.54823)
		(end 249.298968 -200.488042)
		(width 0.12954)
		(layer "F.Cu")
		(net "P3E_CPU0_P4_RX_DP<0>")
	)
	(segment
		(start 227.42652 -58.298588)
		(end 227.661216 -57.117234)
		(width 0.12954)
		(layer "F.Cu")
		(net "P3E_CPU0_P4_RX_DP<0>")
	)
	(segment
		(start 231.49941 -52.164996)
		(end 232.000044 -52.164996)
		(width 0.12954)
		(layer "F.Cu")
		(net "P3E_CPU0_P4_RX_DP<0>")
	)
	(segment
		(start 227.42652 -68.76415)
		(end 227.42652 -58.298588)
		(width 0.12954)
		(layer "F.Cu")
		(net "P3E_CPU0_P4_RX_DP<0>")
	)
	(segment
		(start 255.927098 -213.806024)
		(end 255.61417 -213.493096)
		(width 0.12954)
		(layer "F.Cu")
		(net "P3E_CPU0_P4_RX_DP<0>")
	)
	(segment
		(start 247.260618 -183.36768)
		(end 243.280692 -149.941534)
		(width 0.12954)
		(layer "F.Cu")
		(net "P3E_CPU0_P4_RX_DP<0>")
	)
	(segment
		(start 230.467916 -52.537868)
		(end 231.033574 -52.30368)
		(width 0.12954)
		(layer "F.Cu")
		(net "P3E_CPU0_P4_RX_DP<0>")
	)
	(segment
		(start 252.264164 -211.252308)
		(end 249.901202 -205.54823)
		(width 0.12954)
		(layer "F.Cu")
		(net "P3E_CPU0_P4_RX_DP<0>")
	)
	(segment
		(start 254.357124 -213.345014)
		(end 252.264164 -211.252308)
		(width 0.12954)
		(layer "F.Cu")
		(net "P3E_CPU0_P4_RX_DP<0>")
	)
	(segment
		(start 254.714756 -213.493096)
		(end 254.357124 -213.345014)
		(width 0.12954)
		(layer "F.Cu")
		(net "P3E_CPU0_P4_RX_DP<0>")
	)
	(segment
		(start 231.360726 -52.30368)
		(end 231.49941 -52.164996)
		(width 0.12954)
		(layer "F.Cu")
		(net "P3E_CPU0_P4_RX_DP<0>")
	)
	(segment
		(start 231.033574 -52.30368)
		(end 231.360726 -52.30368)
		(width 0.12954)
		(layer "F.Cu")
		(net "P3E_CPU0_P4_RX_DP<0>")
	)
	(segment
		(start 229.611936 -53.393848)
		(end 230.467916 -52.537868)
		(width 0.12954)
		(layer "F.Cu")
		(net "P3E_CPU0_P4_RX_DP<0>")
	)
	(segment
		(start 228.538278 -55.000652)
		(end 229.611936 -53.393848)
		(width 0.12954)
		(layer "F.Cu")
		(net "P3E_CPU0_P4_RX_DP<0>")
	)
	(segment
		(start 227.17887 -83.528916)
		(end 227.42652 -68.76415)
		(width 0.12954)
		(layer "F.Cu")
		(net "P3E_CPU0_P4_RX_DP<0>")
	)
	(segment
		(start 227.661216 -57.117234)
		(end 228.538278 -55.000652)
		(width 0.12954)
		(layer "F.Cu")
		(net "P3E_CPU0_P4_RX_DP<0>")
	)
	(segment
		(start 235.23702 -116.764816)
		(end 235.23702 -116.764562)
		(width 0.12954)
		(layer "F.Cu")
		(net "P3E_CPU0_P4_RX_DP<0>")
	)
	(segment
		(start 243.280692 -149.941534)
		(end 235.23702 -116.764816)
		(width 0.12954)
		(layer "F.Cu")
		(net "P3E_CPU0_P4_RX_DP<0>")
	)
	(segment
		(start 255.61417 -213.493096)
		(end 254.714756 -213.493096)
		(width 0.12954)
		(layer "F.Cu")
		(net "P3E_CPU0_P4_RX_DP<0>")
	)
	(segment
		(start 345.447874 -294.070024)
		(end 344.981022 -294.335962)
		(width 0.12954)
		(layer "F.Cu")
		(net "P3E_CPU0_P4_RX_DP<0>")
	)
	(segment
		(start 235.23702 -116.764562)
		(end 227.17887 -83.528916)
		(width 0.12954)
		(layer "F.Cu")
		(net "P3E_CPU0_P4_RX_DP<0>")
	)
	(segment
		(start 249.298968 -200.488042)
		(end 247.260618 -183.36768)
		(width 0.12954)
		(layer "F.Cu")
		(net "P3E_CPU0_P4_RX_DP<0>")
	)
	(segment
		(start 327.257664 -309.30088)
		(end 327.332086 -309.121302)
		(width 0.14224)
		(layer "In2.Cu")
		(net "P3E_CPU0_P4_RX_DP<0>")
	)
	(segment
		(start 311.411366 -319.36055)
		(end 317.379858 -313.392058)
		(width 0.14224)
		(layer "In2.Cu")
		(net "P3E_CPU0_P4_RX_DP<0>")
	)
	(segment
		(start 254.549402 -216.692734)
		(end 254.686562 -216.829894)
		(width 0.14224)
		(layer "In2.Cu")
		(net "P3E_CPU0_P4_RX_DP<0>")
	)
	(segment
		(start 326.12965 -309.619396)
		(end 326.524112 -309.456074)
		(width 0.14224)
		(layer "In2.Cu")
		(net "P3E_CPU0_P4_RX_DP<0>")
	)
	(segment
		(start 340.175088 -298.138088)
		(end 340.59368 -298.054776)
		(width 0.14224)
		(layer "In2.Cu")
		(net "P3E_CPU0_P4_RX_DP<0>")
	)
	(segment
		(start 325.405496 -310.068214)
		(end 326.055482 -309.798974)
		(width 0.14224)
		(layer "In2.Cu")
		(net "P3E_CPU0_P4_RX_DP<0>")
	)
	(segment
		(start 327.726548 -308.95798)
		(end 327.905618 -309.032148)
		(width 0.14224)
		(layer "In2.Cu")
		(net "P3E_CPU0_P4_RX_DP<0>")
	)
	(segment
		(start 340.59368 -298.054776)
		(end 340.75497 -298.162472)
		(width 0.14224)
		(layer "In2.Cu")
		(net "P3E_CPU0_P4_RX_DP<0>")
	)
	(segment
		(start 254.686562 -216.829894)
		(end 254.686562 -217.256614)
		(width 0.14224)
		(layer "In2.Cu")
		(net "P3E_CPU0_P4_RX_DP<0>")
	)
	(segment
		(start 342.536526 -297.668442)
		(end 342.697816 -297.776138)
		(width 0.14224)
		(layer "In2.Cu")
		(net "P3E_CPU0_P4_RX_DP<0>")
	)
	(segment
		(start 254.549402 -218.521534)
		(end 254.549402 -218.948254)
		(width 0.14224)
		(layer "In2.Cu")
		(net "P3E_CPU0_P4_RX_DP<0>")
	)
	(segment
		(start 254.549402 -217.393774)
		(end 254.549402 -217.820494)
		(width 0.14224)
		(layer "In2.Cu")
		(net "P3E_CPU0_P4_RX_DP<0>")
	)
	(segment
		(start 344.47226 -297.117262)
		(end 344.47226 -296.61231)
		(width 0.14224)
		(layer "In2.Cu")
		(net "P3E_CPU0_P4_RX_DP<0>")
	)
	(segment
		(start 326.524112 -309.456074)
		(end 326.703436 -309.530242)
		(width 0.14224)
		(layer "In2.Cu")
		(net "P3E_CPU0_P4_RX_DP<0>")
	)
	(segment
		(start 254.686562 -218.384374)
		(end 254.549402 -218.521534)
		(width 0.14224)
		(layer "In2.Cu")
		(net "P3E_CPU0_P4_RX_DP<0>")
	)
	(segment
		(start 345.278964 -294.335962)
		(end 344.981022 -294.335962)
		(width 0.1143)
		(layer "In2.Cu")
		(net "P3E_CPU0_P4_RX_DP<0>")
	)
	(segment
		(start 335.788762 -299.930566)
		(end 337.115404 -299.381164)
		(width 0.14224)
		(layer "In2.Cu")
		(net "P3E_CPU0_P4_RX_DP<0>")
	)
	(segment
		(start 254.686562 -219.512134)
		(end 254.549402 -219.649294)
		(width 0.14224)
		(layer "In2.Cu")
		(net "P3E_CPU0_P4_RX_DP<0>")
	)
	(segment
		(start 254.549402 -217.820494)
		(end 254.686562 -217.957654)
		(width 0.14224)
		(layer "In2.Cu")
		(net "P3E_CPU0_P4_RX_DP<0>")
	)
	(segment
		(start 254.686562 -215.702134)
		(end 254.686562 -216.128854)
		(width 0.14224)
		(layer "In2.Cu")
		(net "P3E_CPU0_P4_RX_DP<0>")
	)
	(segment
		(start 335.788762 -299.930312)
		(end 335.788762 -299.930566)
		(width 0.14224)
		(layer "In2.Cu")
		(net "P3E_CPU0_P4_RX_DP<0>")
	)
	(segment
		(start 340.75497 -298.162472)
		(end 342.009984 -297.913044)
		(width 0.14224)
		(layer "In2.Cu")
		(net "P3E_CPU0_P4_RX_DP<0>")
	)
	(segment
		(start 254.911352 -213.86546)
		(end 254.653288 -214.488268)
		(width 0.14224)
		(layer "In2.Cu")
		(net "P3E_CPU0_P4_RX_DP<0>")
	)
	(segment
		(start 342.11768 -297.7515)
		(end 342.536526 -297.668442)
		(width 0.14224)
		(layer "In2.Cu")
		(net "P3E_CPU0_P4_RX_DP<0>")
	)
	(segment
		(start 335.788508 -299.930566)
		(end 335.788762 -299.930312)
		(width 0.14224)
		(layer "In2.Cu")
		(net "P3E_CPU0_P4_RX_DP<0>")
	)
	(segment
		(start 344.51798 -296.538142)
		(end 344.51798 -295.981374)
		(width 0.1143)
		(layer "In2.Cu")
		(net "P3E_CPU0_P4_RX_DP<0>")
	)
	(segment
		(start 342.697816 -297.776138)
		(end 344.172794 -297.483022)
		(width 0.14224)
		(layer "In2.Cu")
		(net "P3E_CPU0_P4_RX_DP<0>")
	)
	(segment
		(start 317.379858 -313.392058)
		(end 324.757542 -310.336692)
		(width 0.14224)
		(layer "In2.Cu")
		(net "P3E_CPU0_P4_RX_DP<0>")
	)
	(segment
		(start 333.430372 -301.944532)
		(end 333.758286 -301.153068)
		(width 0.14224)
		(layer "In2.Cu")
		(net "P3E_CPU0_P4_RX_DP<0>")
	)
	(segment
		(start 328.94778 -308.600602)
		(end 330.163932 -308.09692)
		(width 0.14224)
		(layer "In2.Cu")
		(net "P3E_CPU0_P4_RX_DP<0>")
	)
	(segment
		(start 333.251048 -302.018954)
		(end 333.430372 -301.944532)
		(width 0.14224)
		(layer "In2.Cu")
		(net "P3E_CPU0_P4_RX_DP<0>")
	)
	(segment
		(start 264.700258 -318.818514)
		(end 264.900156 -319.214754)
		(width 0.14224)
		(layer "In2.Cu")
		(net "P3E_CPU0_P4_RX_DP<0>")
	)
	(segment
		(start 345.129104 -294.681402)
		(end 345.1987 -294.640762)
		(width 0.1143)
		(layer "In2.Cu")
		(net "P3E_CPU0_P4_RX_DP<0>")
	)
	(segment
		(start 324.757542 -310.336692)
		(end 324.83171 -310.157114)
		(width 0.14224)
		(layer "In2.Cu")
		(net "P3E_CPU0_P4_RX_DP<0>")
	)
	(segment
		(start 254.549402 -218.948254)
		(end 254.686562 -219.085414)
		(width 0.14224)
		(layer "In2.Cu")
		(net "P3E_CPU0_P4_RX_DP<0>")
	)
	(segment
		(start 254.549402 -216.266014)
		(end 254.549402 -216.692734)
		(width 0.14224)
		(layer "In2.Cu")
		(net "P3E_CPU0_P4_RX_DP<0>")
	)
	(segment
		(start 263.342882 -309.811674)
		(end 264.700258 -318.818514)
		(width 0.14224)
		(layer "In2.Cu")
		(net "P3E_CPU0_P4_RX_DP<0>")
	)
	(segment
		(start 255.927098 -213.806024)
		(end 255.636268 -213.515194)
		(width 0.14224)
		(layer "In2.Cu")
		(net "P3E_CPU0_P4_RX_DP<0>")
	)
	(segment
		(start 337.115404 -299.381164)
		(end 337.189572 -299.201586)
		(width 0.14224)
		(layer "In2.Cu")
		(net "P3E_CPU0_P4_RX_DP<0>")
	)
	(segment
		(start 324.83171 -310.157114)
		(end 325.226172 -309.993792)
		(width 0.14224)
		(layer "In2.Cu")
		(net "P3E_CPU0_P4_RX_DP<0>")
	)
	(segment
		(start 337.584034 -299.038518)
		(end 337.763358 -299.112686)
		(width 0.14224)
		(layer "In2.Cu")
		(net "P3E_CPU0_P4_RX_DP<0>")
	)
	(segment
		(start 328.76871 -308.526434)
		(end 328.94778 -308.600602)
		(width 0.14224)
		(layer "In2.Cu")
		(net "P3E_CPU0_P4_RX_DP<0>")
	)
	(segment
		(start 265.137392 -319.45199)
		(end 265.504422 -319.605406)
		(width 0.14224)
		(layer "In2.Cu")
		(net "P3E_CPU0_P4_RX_DP<0>")
	)
	(segment
		(start 254.549402 -215.564974)
		(end 254.686562 -215.702134)
		(width 0.14224)
		(layer "In2.Cu")
		(net "P3E_CPU0_P4_RX_DP<0>")
	)
	(segment
		(start 339.412326 -298.42968)
		(end 340.067138 -298.299632)
		(width 0.14224)
		(layer "In2.Cu")
		(net "P3E_CPU0_P4_RX_DP<0>")
	)
	(segment
		(start 326.703436 -309.530242)
		(end 327.257664 -309.30088)
		(width 0.14224)
		(layer "In2.Cu")
		(net "P3E_CPU0_P4_RX_DP<0>")
	)
	(segment
		(start 334.409542 -300.501812)
		(end 335.788508 -299.930566)
		(width 0.14224)
		(layer "In2.Cu")
		(net "P3E_CPU0_P4_RX_DP<0>")
	)
	(segment
		(start 333.087726 -302.413416)
		(end 333.251048 -302.018954)
		(width 0.14224)
		(layer "In2.Cu")
		(net "P3E_CPU0_P4_RX_DP<0>")
	)
	(segment
		(start 340.067138 -298.299632)
		(end 340.175088 -298.138088)
		(width 0.14224)
		(layer "In2.Cu")
		(net "P3E_CPU0_P4_RX_DP<0>")
	)
	(segment
		(start 337.763358 -299.112686)
		(end 339.412326 -298.42968)
		(width 0.14224)
		(layer "In2.Cu")
		(net "P3E_CPU0_P4_RX_DP<0>")
	)
	(segment
		(start 345.348814 -294.405812)
		(end 345.278964 -294.335962)
		(width 0.1143)
		(layer "In2.Cu")
		(net "P3E_CPU0_P4_RX_DP<0>")
	)
	(segment
		(start 255.467358 -213.515194)
		(end 255.116076 -213.660736)
		(width 0.14224)
		(layer "In2.Cu")
		(net "P3E_CPU0_P4_RX_DP<0>")
	)
	(segment
		(start 328.373994 -308.689502)
		(end 328.76871 -308.526434)
		(width 0.14224)
		(layer "In2.Cu")
		(net "P3E_CPU0_P4_RX_DP<0>")
	)
	(segment
		(start 309.679848 -319.907412)
		(end 309.999888 -319.893696)
		(width 0.14224)
		(layer "In2.Cu")
		(net "P3E_CPU0_P4_RX_DP<0>")
	)
	(segment
		(start 331.389482 -306.87137)
		(end 333.161894 -302.592486)
		(width 0.14224)
		(layer "In2.Cu")
		(net "P3E_CPU0_P4_RX_DP<0>")
	)
	(segment
		(start 344.172794 -297.483022)
		(end 344.47226 -297.117262)
		(width 0.14224)
		(layer "In2.Cu")
		(net "P3E_CPU0_P4_RX_DP<0>")
	)
	(segment
		(start 255.116076 -213.660736)
		(end 254.911352 -213.86546)
		(width 0.14224)
		(layer "In2.Cu")
		(net "P3E_CPU0_P4_RX_DP<0>")
	)
	(segment
		(start 265.504422 -319.605406)
		(end 309.679848 -319.907412)
		(width 0.14224)
		(layer "In2.Cu")
		(net "P3E_CPU0_P4_RX_DP<0>")
	)
	(segment
		(start 254.549402 -219.649294)
		(end 254.549402 -233.219498)
		(width 0.14224)
		(layer "In2.Cu")
		(net "P3E_CPU0_P4_RX_DP<0>")
	)
	(segment
		(start 327.905618 -309.032148)
		(end 328.299826 -308.86908)
		(width 0.14224)
		(layer "In2.Cu")
		(net "P3E_CPU0_P4_RX_DP<0>")
	)
	(segment
		(start 260.323076 -267.565886)
		(end 263.342882 -309.811674)
		(width 0.14224)
		(layer "In2.Cu")
		(net "P3E_CPU0_P4_RX_DP<0>")
	)
	(segment
		(start 254.686562 -217.957654)
		(end 254.686562 -218.384374)
		(width 0.14224)
		(layer "In2.Cu")
		(net "P3E_CPU0_P4_RX_DP<0>")
	)
	(segment
		(start 326.055482 -309.798974)
		(end 326.12965 -309.619396)
		(width 0.14224)
		(layer "In2.Cu")
		(net "P3E_CPU0_P4_RX_DP<0>")
	)
	(segment
		(start 327.332086 -309.121302)
		(end 327.726548 -308.95798)
		(width 0.14224)
		(layer "In2.Cu")
		(net "P3E_CPU0_P4_RX_DP<0>")
	)
	(segment
		(start 254.686562 -217.256614)
		(end 254.549402 -217.393774)
		(width 0.14224)
		(layer "In2.Cu")
		(net "P3E_CPU0_P4_RX_DP<0>")
	)
	(segment
		(start 254.686562 -219.085414)
		(end 254.686562 -219.512134)
		(width 0.14224)
		(layer "In2.Cu")
		(net "P3E_CPU0_P4_RX_DP<0>")
	)
	(segment
		(start 309.999888 -319.893696)
		(end 310.236362 -319.847468)
		(width 0.14224)
		(layer "In2.Cu")
		(net "P3E_CPU0_P4_RX_DP<0>")
	)
	(segment
		(start 344.47226 -296.61231)
		(end 344.47226 -296.583862)
		(width 0.1143)
		(layer "In2.Cu")
		(net "P3E_CPU0_P4_RX_DP<0>")
	)
	(segment
		(start 254.549402 -215.010746)
		(end 254.549402 -215.564974)
		(width 0.14224)
		(layer "In2.Cu")
		(net "P3E_CPU0_P4_RX_DP<0>")
	)
	(segment
		(start 330.163932 -308.09692)
		(end 331.389482 -306.87137)
		(width 0.14224)
		(layer "In2.Cu")
		(net "P3E_CPU0_P4_RX_DP<0>")
	)
	(segment
		(start 310.236362 -319.847468)
		(end 311.411366 -319.36055)
		(width 0.14224)
		(layer "In2.Cu")
		(net "P3E_CPU0_P4_RX_DP<0>")
	)
	(segment
		(start 254.549402 -233.219498)
		(end 260.323076 -267.565886)
		(width 0.14224)
		(layer "In2.Cu")
		(net "P3E_CPU0_P4_RX_DP<0>")
	)
	(segment
		(start 254.686562 -216.128854)
		(end 254.549402 -216.266014)
		(width 0.14224)
		(layer "In2.Cu")
		(net "P3E_CPU0_P4_RX_DP<0>")
	)
	(segment
		(start 254.653288 -214.488268)
		(end 254.549402 -215.010746)
		(width 0.14224)
		(layer "In2.Cu")
		(net "P3E_CPU0_P4_RX_DP<0>")
	)
	(segment
		(start 333.758286 -301.153068)
		(end 334.409542 -300.501812)
		(width 0.14224)
		(layer "In2.Cu")
		(net "P3E_CPU0_P4_RX_DP<0>")
	)
	(segment
		(start 344.47226 -296.583862)
		(end 344.51798 -296.538142)
		(width 0.1143)
		(layer "In2.Cu")
		(net "P3E_CPU0_P4_RX_DP<0>")
	)
	(segment
		(start 264.900156 -319.214754)
		(end 265.137392 -319.45199)
		(width 0.14224)
		(layer "In2.Cu")
		(net "P3E_CPU0_P4_RX_DP<0>")
	)
	(segment
		(start 337.189572 -299.201586)
		(end 337.584034 -299.038518)
		(width 0.14224)
		(layer "In2.Cu")
		(net "P3E_CPU0_P4_RX_DP<0>")
	)
	(segment
		(start 255.636268 -213.515194)
		(end 255.467358 -213.515194)
		(width 0.14224)
		(layer "In2.Cu")
		(net "P3E_CPU0_P4_RX_DP<0>")
	)
	(segment
		(start 342.009984 -297.913044)
		(end 342.11768 -297.7515)
		(width 0.14224)
		(layer "In2.Cu")
		(net "P3E_CPU0_P4_RX_DP<0>")
	)
	(segment
		(start 325.226172 -309.993792)
		(end 325.405496 -310.068214)
		(width 0.14224)
		(layer "In2.Cu")
		(net "P3E_CPU0_P4_RX_DP<0>")
	)
	(segment
		(start 333.161894 -302.592486)
		(end 333.087726 -302.413416)
		(width 0.14224)
		(layer "In2.Cu")
		(net "P3E_CPU0_P4_RX_DP<0>")
	)
	(segment
		(start 328.299826 -308.86908)
		(end 328.373994 -308.689502)
		(width 0.14224)
		(layer "In2.Cu")
		(net "P3E_CPU0_P4_RX_DP<0>")
	)
	(arc
		(start 344.76436 -295.422066)
		(mid 344.854016 -295.296758)
		(end 344.885772 -295.145968)
		(width 0.1143)
		(layer "In2.Cu")
		(net "P3E_CPU0_P4_RX_DP<0>")
	)
	(arc
		(start 344.51798 -295.981374)
		(mid 344.582294 -295.675779)
		(end 344.76436 -295.422066)
		(width 0.1143)
		(layer "In2.Cu")
		(net "P3E_CPU0_P4_RX_DP<0>")
	)
	(arc
		(start 344.885772 -295.145968)
		(mid 344.950287 -294.883749)
		(end 345.129104 -294.681402)
		(width 0.1143)
		(layer "In2.Cu")
		(net "P3E_CPU0_P4_RX_DP<0>")
	)
	(arc
		(start 345.1987 -294.640762)
		(mid 345.296465 -294.537786)
		(end 345.348814 -294.405812)
		(width 0.1143)
		(layer "In2.Cu")
		(net "P3E_CPU0_P4_RX_DP<0>")
	)
	(segment
		(start 231.101138 -58.0263)
		(end 231.394762 -58.0263)
		(width 0.12954)
		(layer "F.Cu")
		(net "P3E_CPU0_P4_RX_DN<3>")
	)
	(segment
		(start 230.226108 -64.08293)
		(end 230.226108 -63.69685)
		(width 0.12954)
		(layer "F.Cu")
		(net "P3E_CPU0_P4_RX_DN<3>")
	)
	(segment
		(start 253.041658 -200.518776)
		(end 252.829568 -200.351898)
		(width 0.12954)
		(layer "F.Cu")
		(net "P3E_CPU0_P4_RX_DN<3>")
	)
	(segment
		(start 230.63708 -58.218832)
		(end 231.101138 -58.0263)
		(width 0.12954)
		(layer "F.Cu")
		(net "P3E_CPU0_P4_RX_DN<3>")
	)
	(segment
		(start 252.829568 -200.351898)
		(end 247.470168 -155.331414)
		(width 0.12954)
		(layer "F.Cu")
		(net "P3E_CPU0_P4_RX_DN<3>")
	)
	(segment
		(start 254.72771 -204.829918)
		(end 254.257048 -204.634846)
		(width 0.12954)
		(layer "F.Cu")
		(net "P3E_CPU0_P4_RX_DN<3>")
	)
	(segment
		(start 230.416608 -60.971938)
		(end 230.416608 -60.585858)
		(width 0.12954)
		(layer "F.Cu")
		(net "P3E_CPU0_P4_RX_DN<3>")
	)
	(segment
		(start 253.360682 -203.197714)
		(end 253.315216 -202.814174)
		(width 0.12954)
		(layer "F.Cu")
		(net "P3E_CPU0_P4_RX_DN<3>")
	)
	(segment
		(start 255.673352 -204.829918)
		(end 254.72771 -204.829918)
		(width 0.12954)
		(layer "F.Cu")
		(net "P3E_CPU0_P4_RX_DN<3>")
	)
	(segment
		(start 230.226108 -58.88609)
		(end 230.407718 -58.44794)
		(width 0.12954)
		(layer "F.Cu")
		(net "P3E_CPU0_P4_RX_DN<3>")
	)
	(segment
		(start 253.194058 -203.409296)
		(end 253.360682 -203.197714)
		(width 0.12954)
		(layer "F.Cu")
		(net "P3E_CPU0_P4_RX_DN<3>")
	)
	(segment
		(start 230.416608 -60.585858)
		(end 230.226108 -60.395358)
		(width 0.12954)
		(layer "F.Cu")
		(net "P3E_CPU0_P4_RX_DN<3>")
	)
	(segment
		(start 253.352554 -203.994766)
		(end 253.234698 -203.752196)
		(width 0.12954)
		(layer "F.Cu")
		(net "P3E_CPU0_P4_RX_DN<3>")
	)
	(segment
		(start 230.416608 -59.432698)
		(end 230.226108 -59.242198)
		(width 0.12954)
		(layer "F.Cu")
		(net "P3E_CPU0_P4_RX_DN<3>")
	)
	(segment
		(start 247.470168 -155.331414)
		(end 229.96398 -83.132422)
		(width 0.12954)
		(layer "F.Cu")
		(net "P3E_CPU0_P4_RX_DN<3>")
	)
	(segment
		(start 252.966728 -201.502264)
		(end 252.921008 -201.116438)
		(width 0.12954)
		(layer "F.Cu")
		(net "P3E_CPU0_P4_RX_DN<3>")
	)
	(segment
		(start 230.226108 -63.69685)
		(end 230.416608 -63.50635)
		(width 0.12954)
		(layer "F.Cu")
		(net "P3E_CPU0_P4_RX_DN<3>")
	)
	(segment
		(start 230.226108 -60.009278)
		(end 230.416608 -59.818778)
		(width 0.12954)
		(layer "F.Cu")
		(net "P3E_CPU0_P4_RX_DN<3>")
	)
	(segment
		(start 253.234698 -203.752196)
		(end 253.194058 -203.409296)
		(width 0.12954)
		(layer "F.Cu")
		(net "P3E_CPU0_P4_RX_DN<3>")
	)
	(segment
		(start 230.416608 -59.818778)
		(end 230.416608 -59.432698)
		(width 0.12954)
		(layer "F.Cu")
		(net "P3E_CPU0_P4_RX_DN<3>")
	)
	(segment
		(start 229.96398 -83.132422)
		(end 230.226108 -67.464178)
		(width 0.12954)
		(layer "F.Cu")
		(net "P3E_CPU0_P4_RX_DN<3>")
	)
	(segment
		(start 253.459996 -204.102208)
		(end 253.352554 -203.994766)
		(width 0.12954)
		(layer "F.Cu")
		(net "P3E_CPU0_P4_RX_DN<3>")
	)
	(segment
		(start 253.178564 -201.668888)
		(end 252.966728 -201.502264)
		(width 0.12954)
		(layer "F.Cu")
		(net "P3E_CPU0_P4_RX_DN<3>")
	)
	(segment
		(start 253.224284 -202.052682)
		(end 253.178564 -201.668888)
		(width 0.12954)
		(layer "F.Cu")
		(net "P3E_CPU0_P4_RX_DN<3>")
	)
	(segment
		(start 231.533446 -58.164984)
		(end 232.000044 -58.164984)
		(width 0.12954)
		(layer "F.Cu")
		(net "P3E_CPU0_P4_RX_DN<3>")
	)
	(segment
		(start 253.103126 -202.64755)
		(end 253.05766 -202.264264)
		(width 0.12954)
		(layer "F.Cu")
		(net "P3E_CPU0_P4_RX_DN<3>")
	)
	(segment
		(start 253.315216 -202.814174)
		(end 253.103126 -202.64755)
		(width 0.12954)
		(layer "F.Cu")
		(net "P3E_CPU0_P4_RX_DN<3>")
	)
	(segment
		(start 230.226108 -60.395358)
		(end 230.226108 -60.009278)
		(width 0.12954)
		(layer "F.Cu")
		(net "P3E_CPU0_P4_RX_DN<3>")
	)
	(segment
		(start 254.257048 -204.634846)
		(end 253.459996 -204.102208)
		(width 0.12954)
		(layer "F.Cu")
		(net "P3E_CPU0_P4_RX_DN<3>")
	)
	(segment
		(start 354.847906 -294.070024)
		(end 354.381054 -294.335962)
		(width 0.12954)
		(layer "F.Cu")
		(net "P3E_CPU0_P4_RX_DN<3>")
	)
	(segment
		(start 230.226108 -59.242198)
		(end 230.226108 -58.88609)
		(width 0.12954)
		(layer "F.Cu")
		(net "P3E_CPU0_P4_RX_DN<3>")
	)
	(segment
		(start 253.087632 -200.904856)
		(end 253.041658 -200.518776)
		(width 0.12954)
		(layer "F.Cu")
		(net "P3E_CPU0_P4_RX_DN<3>")
	)
	(segment
		(start 230.226108 -62.92977)
		(end 230.226108 -61.162438)
		(width 0.12954)
		(layer "F.Cu")
		(net "P3E_CPU0_P4_RX_DN<3>")
	)
	(segment
		(start 230.416608 -64.27343)
		(end 230.226108 -64.08293)
		(width 0.12954)
		(layer "F.Cu")
		(net "P3E_CPU0_P4_RX_DN<3>")
	)
	(segment
		(start 230.416608 -63.12027)
		(end 230.226108 -62.92977)
		(width 0.12954)
		(layer "F.Cu")
		(net "P3E_CPU0_P4_RX_DN<3>")
	)
	(segment
		(start 230.226108 -67.464178)
		(end 230.226108 -64.85001)
		(width 0.12954)
		(layer "F.Cu")
		(net "P3E_CPU0_P4_RX_DN<3>")
	)
	(segment
		(start 255.927098 -204.576172)
		(end 255.673352 -204.829918)
		(width 0.12954)
		(layer "F.Cu")
		(net "P3E_CPU0_P4_RX_DN<3>")
	)
	(segment
		(start 230.226108 -64.85001)
		(end 230.416608 -64.65951)
		(width 0.12954)
		(layer "F.Cu")
		(net "P3E_CPU0_P4_RX_DN<3>")
	)
	(segment
		(start 252.921008 -201.116438)
		(end 253.087632 -200.904856)
		(width 0.12954)
		(layer "F.Cu")
		(net "P3E_CPU0_P4_RX_DN<3>")
	)
	(segment
		(start 253.05766 -202.264264)
		(end 253.224284 -202.052682)
		(width 0.12954)
		(layer "F.Cu")
		(net "P3E_CPU0_P4_RX_DN<3>")
	)
	(segment
		(start 231.394762 -58.0263)
		(end 231.533446 -58.164984)
		(width 0.12954)
		(layer "F.Cu")
		(net "P3E_CPU0_P4_RX_DN<3>")
	)
	(segment
		(start 230.416608 -63.50635)
		(end 230.416608 -63.12027)
		(width 0.12954)
		(layer "F.Cu")
		(net "P3E_CPU0_P4_RX_DN<3>")
	)
	(segment
		(start 230.416608 -64.65951)
		(end 230.416608 -64.27343)
		(width 0.12954)
		(layer "F.Cu")
		(net "P3E_CPU0_P4_RX_DN<3>")
	)
	(segment
		(start 230.226108 -61.162438)
		(end 230.416608 -60.971938)
		(width 0.12954)
		(layer "F.Cu")
		(net "P3E_CPU0_P4_RX_DN<3>")
	)
	(segment
		(start 230.407718 -58.44794)
		(end 230.63708 -58.218832)
		(width 0.12954)
		(layer "F.Cu")
		(net "P3E_CPU0_P4_RX_DN<3>")
	)
	(segment
		(start 354.037138 -297.64228)
		(end 353.309936 -296.915078)
		(width 0.14224)
		(layer "In2.Cu")
		(net "P3E_CPU0_P4_RX_DN<3>")
	)
	(segment
		(start 262.10895 -322.827142)
		(end 310.860694 -323.155818)
		(width 0.14224)
		(layer "In2.Cu")
		(net "P3E_CPU0_P4_RX_DN<3>")
	)
	(segment
		(start 353.309936 -296.276014)
		(end 353.309936 -296.247566)
		(width 0.1143)
		(layer "In2.Cu")
		(net "P3E_CPU0_P4_RX_DN<3>")
	)
	(segment
		(start 262.001254 -322.805298)
		(end 262.05307 -322.826888)
		(width 0.14224)
		(layer "In2.Cu")
		(net "P3E_CPU0_P4_RX_DN<3>")
	)
	(segment
		(start 261.21741 -322.47713)
		(end 262.001508 -322.805298)
		(width 0.14224)
		(layer "In2.Cu")
		(net "P3E_CPU0_P4_RX_DN<3>")
	)
	(segment
		(start 318.93637 -316.237874)
		(end 319.511172 -316.00013)
		(width 0.14224)
		(layer "In2.Cu")
		(net "P3E_CPU0_P4_RX_DN<3>")
	)
	(segment
		(start 262.05307 -322.826888)
		(end 262.108696 -322.827142)
		(width 0.14224)
		(layer "In2.Cu")
		(net "P3E_CPU0_P4_RX_DN<3>")
	)
	(segment
		(start 255.636268 -204.867002)
		(end 255.18364 -204.867002)
		(width 0.14224)
		(layer "In2.Cu")
		(net "P3E_CPU0_P4_RX_DN<3>")
	)
	(segment
		(start 261.02564 -322.285868)
		(end 261.02564 -322.285614)
		(width 0.14224)
		(layer "In2.Cu")
		(net "P3E_CPU0_P4_RX_DN<3>")
	)
	(segment
		(start 256.884932 -267.303758)
		(end 260.798056 -322.058284)
		(width 0.14224)
		(layer "In2.Cu")
		(net "P3E_CPU0_P4_RX_DN<3>")
	)
	(segment
		(start 353.309936 -296.247566)
		(end 353.264216 -296.201846)
		(width 0.1143)
		(layer "In2.Cu")
		(net "P3E_CPU0_P4_RX_DN<3>")
	)
	(segment
		(start 255.927098 -204.576172)
		(end 255.636268 -204.867002)
		(width 0.14224)
		(layer "In2.Cu")
		(net "P3E_CPU0_P4_RX_DN<3>")
	)
	(segment
		(start 354.037138 -301.179484)
		(end 354.037138 -297.64228)
		(width 0.14224)
		(layer "In2.Cu")
		(net "P3E_CPU0_P4_RX_DN<3>")
	)
	(segment
		(start 249.964194 -221.32163)
		(end 251.398786 -234.670346)
		(width 0.14224)
		(layer "In2.Cu")
		(net "P3E_CPU0_P4_RX_DN<3>")
	)
	(segment
		(start 353.309936 -296.915078)
		(end 353.309936 -296.276014)
		(width 0.14224)
		(layer "In2.Cu")
		(net "P3E_CPU0_P4_RX_DN<3>")
	)
	(segment
		(start 353.264216 -296.201846)
		(end 353.264216 -295.764458)
		(width 0.1143)
		(layer "In2.Cu")
		(net "P3E_CPU0_P4_RX_DN<3>")
	)
	(segment
		(start 312.837576 -322.336668)
		(end 318.93637 -316.237874)
		(width 0.14224)
		(layer "In2.Cu")
		(net "P3E_CPU0_P4_RX_DN<3>")
	)
	(segment
		(start 260.798056 -322.058284)
		(end 261.02564 -322.285868)
		(width 0.14224)
		(layer "In2.Cu")
		(net "P3E_CPU0_P4_RX_DN<3>")
	)
	(segment
		(start 254.158242 -205.29169)
		(end 252.854968 -206.594964)
		(width 0.14224)
		(layer "In2.Cu")
		(net "P3E_CPU0_P4_RX_DN<3>")
	)
	(segment
		(start 250.40336 -210.614006)
		(end 249.964194 -212.822536)
		(width 0.14224)
		(layer "In2.Cu")
		(net "P3E_CPU0_P4_RX_DN<3>")
	)
	(segment
		(start 250.784868 -209.692748)
		(end 250.40336 -210.614006)
		(width 0.14224)
		(layer "In2.Cu")
		(net "P3E_CPU0_P4_RX_DN<3>")
	)
	(segment
		(start 252.854968 -206.594964)
		(end 250.784868 -209.692748)
		(width 0.14224)
		(layer "In2.Cu")
		(net "P3E_CPU0_P4_RX_DN<3>")
	)
	(segment
		(start 262.108696 -322.827142)
		(end 262.10895 -322.827142)
		(width 0.14224)
		(layer "In2.Cu")
		(net "P3E_CPU0_P4_RX_DN<3>")
	)
	(segment
		(start 354.000308 -294.418766)
		(end 354.083112 -294.335962)
		(width 0.1143)
		(layer "In2.Cu")
		(net "P3E_CPU0_P4_RX_DN<3>")
	)
	(segment
		(start 354.083112 -294.335962)
		(end 354.381054 -294.335962)
		(width 0.1143)
		(layer "In2.Cu")
		(net "P3E_CPU0_P4_RX_DN<3>")
	)
	(segment
		(start 262.001508 -322.805298)
		(end 262.001254 -322.805298)
		(width 0.14224)
		(layer "In2.Cu")
		(net "P3E_CPU0_P4_RX_DN<3>")
	)
	(segment
		(start 353.693476 -294.841168)
		(end 353.763072 -294.800528)
		(width 0.1143)
		(layer "In2.Cu")
		(net "P3E_CPU0_P4_RX_DN<3>")
	)
	(segment
		(start 249.964194 -212.822536)
		(end 249.964194 -221.32163)
		(width 0.14224)
		(layer "In2.Cu")
		(net "P3E_CPU0_P4_RX_DN<3>")
	)
	(segment
		(start 310.860694 -323.155818)
		(end 312.837576 -322.336668)
		(width 0.14224)
		(layer "In2.Cu")
		(net "P3E_CPU0_P4_RX_DN<3>")
	)
	(segment
		(start 346.104972 -311.068466)
		(end 348.418404 -308.75478)
		(width 0.14224)
		(layer "In2.Cu")
		(net "P3E_CPU0_P4_RX_DN<3>")
	)
	(segment
		(start 342.396572 -312.822082)
		(end 346.104972 -311.068466)
		(width 0.14224)
		(layer "In2.Cu")
		(net "P3E_CPU0_P4_RX_DN<3>")
	)
	(segment
		(start 251.398786 -234.670346)
		(end 256.884932 -267.303758)
		(width 0.14224)
		(layer "In2.Cu")
		(net "P3E_CPU0_P4_RX_DN<3>")
	)
	(segment
		(start 324.358508 -314.599066)
		(end 342.396572 -312.822082)
		(width 0.14224)
		(layer "In2.Cu")
		(net "P3E_CPU0_P4_RX_DN<3>")
	)
	(segment
		(start 319.511172 -316.00013)
		(end 324.358508 -314.599066)
		(width 0.14224)
		(layer "In2.Cu")
		(net "P3E_CPU0_P4_RX_DN<3>")
	)
	(segment
		(start 348.418404 -308.75478)
		(end 354.037138 -301.179484)
		(width 0.14224)
		(layer "In2.Cu")
		(net "P3E_CPU0_P4_RX_DN<3>")
	)
	(segment
		(start 255.18364 -204.867002)
		(end 254.158242 -205.29169)
		(width 0.14224)
		(layer "In2.Cu")
		(net "P3E_CPU0_P4_RX_DN<3>")
	)
	(segment
		(start 261.02564 -322.285614)
		(end 261.21741 -322.47713)
		(width 0.14224)
		(layer "In2.Cu")
		(net "P3E_CPU0_P4_RX_DN<3>")
	)
	(arc
		(start 353.353116 -295.562782)
		(mid 353.488623 -295.373653)
		(end 353.536504 -295.145968)
		(width 0.1143)
		(layer "In2.Cu")
		(net "P3E_CPU0_P4_RX_DN<3>")
	)
	(arc
		(start 353.264216 -295.764458)
		(mid 353.287421 -295.654251)
		(end 353.353116 -295.562782)
		(width 0.1143)
		(layer "In2.Cu")
		(net "P3E_CPU0_P4_RX_DN<3>")
	)
	(arc
		(start 353.996498 -294.441626)
		(mid 353.998521 -294.430216)
		(end 354.000308 -294.418766)
		(width 0.1143)
		(layer "In2.Cu")
		(net "P3E_CPU0_P4_RX_DN<3>")
	)
	(arc
		(start 353.536504 -295.145968)
		(mid 353.578053 -294.974546)
		(end 353.693476 -294.841168)
		(width 0.1143)
		(layer "In2.Cu")
		(net "P3E_CPU0_P4_RX_DN<3>")
	)
	(arc
		(start 353.763072 -294.800528)
		(mid 353.915059 -294.64402)
		(end 353.996498 -294.441626)
		(width 0.1143)
		(layer "In2.Cu")
		(net "P3E_CPU0_P4_RX_DN<3>")
	)
	(segment
		(start 247.090692 -160.141666)
		(end 247.044972 -159.757872)
		(width 0.12954)
		(layer "F.Cu")
		(net "P3E_CPU0_P4_RX_DN<2>")
	)
	(segment
		(start 246.651272 -158.062676)
		(end 246.817896 -157.851094)
		(width 0.12954)
		(layer "F.Cu")
		(net "P3E_CPU0_P4_RX_DN<2>")
	)
	(segment
		(start 255.693164 -207.587342)
		(end 255.304798 -207.587342)
		(width 0.12954)
		(layer "F.Cu")
		(net "P3E_CPU0_P4_RX_DN<2>")
	)
	(segment
		(start 251.900436 -200.540366)
		(end 251.6886 -200.373742)
		(width 0.12954)
		(layer "F.Cu")
		(net "P3E_CPU0_P4_RX_DN<2>")
	)
	(segment
		(start 252.052074 -203.426568)
		(end 252.052328 -203.426314)
		(width 0.12954)
		(layer "F.Cu")
		(net "P3E_CPU0_P4_RX_DN<2>")
	)
	(segment
		(start 251.961396 -202.664314)
		(end 251.91593 -202.281028)
		(width 0.12954)
		(layer "F.Cu")
		(net "P3E_CPU0_P4_RX_DN<2>")
	)
	(segment
		(start 229.433882 -67.985132)
		(end 229.433882 -58.888884)
		(width 0.12954)
		(layer "F.Cu")
		(net "P3E_CPU0_P4_RX_DN<2>")
	)
	(segment
		(start 246.908574 -158.612586)
		(end 246.696738 -158.445962)
		(width 0.12954)
		(layer "F.Cu")
		(net "P3E_CPU0_P4_RX_DN<2>")
	)
	(segment
		(start 252.17247 -204.437996)
		(end 252.052074 -203.426568)
		(width 0.12954)
		(layer "F.Cu")
		(net "P3E_CPU0_P4_RX_DN<2>")
	)
	(segment
		(start 231.541066 -56.364886)
		(end 232.000044 -56.364886)
		(width 0.12954)
		(layer "F.Cu")
		(net "P3E_CPU0_P4_RX_DN<2>")
	)
	(segment
		(start 246.817896 -157.851094)
		(end 246.772176 -157.4673)
		(width 0.12954)
		(layer "F.Cu")
		(net "P3E_CPU0_P4_RX_DN<2>")
	)
	(segment
		(start 231.402382 -56.226202)
		(end 231.541066 -56.364886)
		(width 0.12954)
		(layer "F.Cu")
		(net "P3E_CPU0_P4_RX_DN<2>")
	)
	(segment
		(start 246.772176 -157.4673)
		(end 246.56034 -157.300676)
		(width 0.12954)
		(layer "F.Cu")
		(net "P3E_CPU0_P4_RX_DN<2>")
	)
	(segment
		(start 246.696738 -158.445962)
		(end 246.651272 -158.062676)
		(width 0.12954)
		(layer "F.Cu")
		(net "P3E_CPU0_P4_RX_DN<2>")
	)
	(segment
		(start 246.423942 -156.15539)
		(end 246.009414 -152.672034)
		(width 0.12954)
		(layer "F.Cu")
		(net "P3E_CPU0_P4_RX_DN<2>")
	)
	(segment
		(start 246.924068 -160.353248)
		(end 247.090692 -160.141666)
		(width 0.12954)
		(layer "F.Cu")
		(net "P3E_CPU0_P4_RX_DN<2>")
	)
	(segment
		(start 249.66422 -183.36768)
		(end 246.924068 -160.353248)
		(width 0.12954)
		(layer "F.Cu")
		(net "P3E_CPU0_P4_RX_DN<2>")
	)
	(segment
		(start 251.91593 -202.281028)
		(end 252.082554 -202.069446)
		(width 0.12954)
		(layer "F.Cu")
		(net "P3E_CPU0_P4_RX_DN<2>")
	)
	(segment
		(start 251.946156 -200.92416)
		(end 251.900436 -200.540366)
		(width 0.12954)
		(layer "F.Cu")
		(net "P3E_CPU0_P4_RX_DN<2>")
	)
	(segment
		(start 246.514874 -156.91739)
		(end 246.681498 -156.705808)
		(width 0.12954)
		(layer "F.Cu")
		(net "P3E_CPU0_P4_RX_DN<2>")
	)
	(segment
		(start 229.178358 -83.25485)
		(end 229.433882 -67.985132)
		(width 0.12954)
		(layer "F.Cu")
		(net "P3E_CPU0_P4_RX_DN<2>")
	)
	(segment
		(start 246.009414 -152.672034)
		(end 229.178358 -83.25485)
		(width 0.12954)
		(layer "F.Cu")
		(net "P3E_CPU0_P4_RX_DN<2>")
	)
	(segment
		(start 230.530146 -56.492394)
		(end 230.726742 -56.361076)
		(width 0.12954)
		(layer "F.Cu")
		(net "P3E_CPU0_P4_RX_DN<2>")
	)
	(segment
		(start 246.78767 -159.207962)
		(end 246.954294 -158.99638)
		(width 0.12954)
		(layer "F.Cu")
		(net "P3E_CPU0_P4_RX_DN<2>")
	)
	(segment
		(start 229.677722 -57.663334)
		(end 229.763066 -57.457086)
		(width 0.12954)
		(layer "F.Cu")
		(net "P3E_CPU0_P4_RX_DN<2>")
	)
	(segment
		(start 252.414786 -204.937106)
		(end 252.17247 -204.437996)
		(width 0.12954)
		(layer "F.Cu")
		(net "P3E_CPU0_P4_RX_DN<2>")
	)
	(segment
		(start 247.044972 -159.757872)
		(end 246.833136 -159.591248)
		(width 0.12954)
		(layer "F.Cu")
		(net "P3E_CPU0_P4_RX_DN<2>")
	)
	(segment
		(start 229.433882 -58.888884)
		(end 229.677722 -57.663334)
		(width 0.12954)
		(layer "F.Cu")
		(net "P3E_CPU0_P4_RX_DN<2>")
	)
	(segment
		(start 229.763066 -57.457086)
		(end 230.161592 -56.860948)
		(width 0.12954)
		(layer "F.Cu")
		(net "P3E_CPU0_P4_RX_DN<2>")
	)
	(segment
		(start 252.036834 -201.685652)
		(end 251.824998 -201.519028)
		(width 0.12954)
		(layer "F.Cu")
		(net "P3E_CPU0_P4_RX_DN<2>")
	)
	(segment
		(start 231.051862 -56.226202)
		(end 231.402382 -56.226202)
		(width 0.12954)
		(layer "F.Cu")
		(net "P3E_CPU0_P4_RX_DN<2>")
	)
	(segment
		(start 230.161592 -56.860948)
		(end 230.530146 -56.492394)
		(width 0.12954)
		(layer "F.Cu")
		(net "P3E_CPU0_P4_RX_DN<2>")
	)
	(segment
		(start 230.726742 -56.361076)
		(end 231.051862 -56.226202)
		(width 0.12954)
		(layer "F.Cu")
		(net "P3E_CPU0_P4_RX_DN<2>")
	)
	(segment
		(start 255.927098 -207.353408)
		(end 255.693164 -207.587342)
		(width 0.12954)
		(layer "F.Cu")
		(net "P3E_CPU0_P4_RX_DN<2>")
	)
	(segment
		(start 246.954294 -158.99638)
		(end 246.908574 -158.612586)
		(width 0.12954)
		(layer "F.Cu")
		(net "P3E_CPU0_P4_RX_DN<2>")
	)
	(segment
		(start 246.56034 -157.300676)
		(end 246.514874 -156.91739)
		(width 0.12954)
		(layer "F.Cu")
		(net "P3E_CPU0_P4_RX_DN<2>")
	)
	(segment
		(start 246.681498 -156.705808)
		(end 246.635778 -156.322014)
		(width 0.12954)
		(layer "F.Cu")
		(net "P3E_CPU0_P4_RX_DN<2>")
	)
	(segment
		(start 254.89535 -207.417416)
		(end 252.414786 -204.937106)
		(width 0.12954)
		(layer "F.Cu")
		(net "P3E_CPU0_P4_RX_DN<2>")
	)
	(segment
		(start 251.779532 -201.135742)
		(end 251.946156 -200.92416)
		(width 0.12954)
		(layer "F.Cu")
		(net "P3E_CPU0_P4_RX_DN<2>")
	)
	(segment
		(start 251.824998 -201.519028)
		(end 251.779532 -201.135742)
		(width 0.12954)
		(layer "F.Cu")
		(net "P3E_CPU0_P4_RX_DN<2>")
	)
	(segment
		(start 246.833136 -159.591248)
		(end 246.78767 -159.207962)
		(width 0.12954)
		(layer "F.Cu")
		(net "P3E_CPU0_P4_RX_DN<2>")
	)
	(segment
		(start 255.304798 -207.587342)
		(end 254.89535 -207.417416)
		(width 0.12954)
		(layer "F.Cu")
		(net "P3E_CPU0_P4_RX_DN<2>")
	)
	(segment
		(start 252.219206 -203.214732)
		(end 252.173486 -202.831192)
		(width 0.12954)
		(layer "F.Cu")
		(net "P3E_CPU0_P4_RX_DN<2>")
	)
	(segment
		(start 352.027998 -294.070024)
		(end 351.561146 -294.335962)
		(width 0.12954)
		(layer "F.Cu")
		(net "P3E_CPU0_P4_RX_DN<2>")
	)
	(segment
		(start 252.173486 -202.831192)
		(end 251.961396 -202.664314)
		(width 0.12954)
		(layer "F.Cu")
		(net "P3E_CPU0_P4_RX_DN<2>")
	)
	(segment
		(start 246.635778 -156.322014)
		(end 246.423942 -156.15539)
		(width 0.12954)
		(layer "F.Cu")
		(net "P3E_CPU0_P4_RX_DN<2>")
	)
	(segment
		(start 251.6886 -200.371456)
		(end 249.66422 -183.36768)
		(width 0.12954)
		(layer "F.Cu")
		(net "P3E_CPU0_P4_RX_DN<2>")
	)
	(segment
		(start 252.082554 -202.069446)
		(end 252.036834 -201.685652)
		(width 0.12954)
		(layer "F.Cu")
		(net "P3E_CPU0_P4_RX_DN<2>")
	)
	(segment
		(start 251.6886 -200.373742)
		(end 251.6886 -200.371456)
		(width 0.12954)
		(layer "F.Cu")
		(net "P3E_CPU0_P4_RX_DN<2>")
	)
	(segment
		(start 252.052328 -203.426314)
		(end 252.219206 -203.214732)
		(width 0.12954)
		(layer "F.Cu")
		(net "P3E_CPU0_P4_RX_DN<2>")
	)
	(segment
		(start 350.518984 -300.819312)
		(end 350.518984 -298.22394)
		(width 0.14224)
		(layer "In2.Cu")
		(net "P3E_CPU0_P4_RX_DN<2>")
	)
	(segment
		(start 319.704974 -314.894214)
		(end 326.747124 -312.757566)
		(width 0.14224)
		(layer "In2.Cu")
		(net "P3E_CPU0_P4_RX_DN<2>")
	)
	(segment
		(start 351.263204 -294.335962)
		(end 351.561146 -294.335962)
		(width 0.1143)
		(layer "In2.Cu")
		(net "P3E_CPU0_P4_RX_DN<2>")
	)
	(segment
		(start 262.99541 -321.867784)
		(end 310.551322 -322.189602)
		(width 0.14224)
		(layer "In2.Cu")
		(net "P3E_CPU0_P4_RX_DN<2>")
	)
	(segment
		(start 253.050548 -209.581496)
		(end 251.986796 -212.14969)
		(width 0.14224)
		(layer "In2.Cu")
		(net "P3E_CPU0_P4_RX_DN<2>")
	)
	(segment
		(start 350.518984 -298.22394)
		(end 350.518984 -298.195492)
		(width 0.1143)
		(layer "In2.Cu")
		(net "P3E_CPU0_P4_RX_DN<2>")
	)
	(segment
		(start 343.334086 -306.97424)
		(end 349.07855 -302.259746)
		(width 0.14224)
		(layer "In2.Cu")
		(net "P3E_CPU0_P4_RX_DN<2>")
	)
	(segment
		(start 262.126476 -321.50431)
		(end 262.99541 -321.867784)
		(width 0.14224)
		(layer "In2.Cu")
		(net "P3E_CPU0_P4_RX_DN<2>")
	)
	(segment
		(start 340.432136 -311.409334)
		(end 340.709758 -311.10301)
		(width 0.14224)
		(layer "In2.Cu")
		(net "P3E_CPU0_P4_RX_DN<2>")
	)
	(segment
		(start 340.709758 -308.841394)
		(end 341.025226 -308.079902)
		(width 0.14224)
		(layer "In2.Cu")
		(net "P3E_CPU0_P4_RX_DN<2>")
	)
	(segment
		(start 253.600458 -208.758536)
		(end 253.050548 -209.581496)
		(width 0.14224)
		(layer "In2.Cu")
		(net "P3E_CPU0_P4_RX_DN<2>")
	)
	(segment
		(start 257.952748 -267.971778)
		(end 261.751572 -321.12966)
		(width 0.14224)
		(layer "In2.Cu")
		(net "P3E_CPU0_P4_RX_DN<2>")
	)
	(segment
		(start 251.986796 -212.14969)
		(end 251.455936 -214.818722)
		(width 0.14224)
		(layer "In2.Cu")
		(net "P3E_CPU0_P4_RX_DN<2>")
	)
	(segment
		(start 252.356112 -234.686094)
		(end 257.952748 -267.971778)
		(width 0.14224)
		(layer "In2.Cu")
		(net "P3E_CPU0_P4_RX_DN<2>")
	)
	(segment
		(start 251.455936 -226.310698)
		(end 252.356112 -234.686094)
		(width 0.14224)
		(layer "In2.Cu")
		(net "P3E_CPU0_P4_RX_DN<2>")
	)
	(segment
		(start 310.551322 -322.189602)
		(end 312.372502 -321.435476)
		(width 0.14224)
		(layer "In2.Cu")
		(net "P3E_CPU0_P4_RX_DN<2>")
	)
	(segment
		(start 349.07855 -302.259746)
		(end 350.518984 -300.819312)
		(width 0.14224)
		(layer "In2.Cu")
		(net "P3E_CPU0_P4_RX_DN<2>")
	)
	(segment
		(start 350.518984 -298.195492)
		(end 350.473264 -298.149772)
		(width 0.1143)
		(layer "In2.Cu")
		(net "P3E_CPU0_P4_RX_DN<2>")
	)
	(segment
		(start 318.354456 -315.453522)
		(end 319.704974 -314.894214)
		(width 0.14224)
		(layer "In2.Cu")
		(net "P3E_CPU0_P4_RX_DN<2>")
	)
	(segment
		(start 255.927098 -207.353408)
		(end 255.636268 -207.644238)
		(width 0.14224)
		(layer "In2.Cu")
		(net "P3E_CPU0_P4_RX_DN<2>")
	)
	(segment
		(start 255.636268 -207.644238)
		(end 255.216152 -207.644238)
		(width 0.14224)
		(layer "In2.Cu")
		(net "P3E_CPU0_P4_RX_DN<2>")
	)
	(segment
		(start 341.025226 -308.079902)
		(end 341.279988 -307.82514)
		(width 0.14224)
		(layer "In2.Cu")
		(net "P3E_CPU0_P4_RX_DN<2>")
	)
	(segment
		(start 312.372502 -321.435476)
		(end 318.354456 -315.453522)
		(width 0.14224)
		(layer "In2.Cu")
		(net "P3E_CPU0_P4_RX_DN<2>")
	)
	(segment
		(start 351.1804 -294.418766)
		(end 351.263204 -294.335962)
		(width 0.1143)
		(layer "In2.Cu")
		(net "P3E_CPU0_P4_RX_DN<2>")
	)
	(segment
		(start 254.360172 -207.998822)
		(end 253.600458 -208.758536)
		(width 0.14224)
		(layer "In2.Cu")
		(net "P3E_CPU0_P4_RX_DN<2>")
	)
	(segment
		(start 340.709758 -311.10301)
		(end 340.709758 -308.841394)
		(width 0.14224)
		(layer "In2.Cu")
		(net "P3E_CPU0_P4_RX_DN<2>")
	)
	(segment
		(start 350.873568 -294.841168)
		(end 350.943164 -294.800528)
		(width 0.1143)
		(layer "In2.Cu")
		(net "P3E_CPU0_P4_RX_DN<2>")
	)
	(segment
		(start 261.751572 -321.12966)
		(end 262.126476 -321.50431)
		(width 0.14224)
		(layer "In2.Cu")
		(net "P3E_CPU0_P4_RX_DN<2>")
	)
	(segment
		(start 341.279988 -307.82514)
		(end 343.334086 -306.97424)
		(width 0.14224)
		(layer "In2.Cu")
		(net "P3E_CPU0_P4_RX_DN<2>")
	)
	(segment
		(start 255.216152 -207.644238)
		(end 254.360172 -207.998822)
		(width 0.14224)
		(layer "In2.Cu")
		(net "P3E_CPU0_P4_RX_DN<2>")
	)
	(segment
		(start 251.455936 -214.818722)
		(end 251.455936 -226.310698)
		(width 0.14224)
		(layer "In2.Cu")
		(net "P3E_CPU0_P4_RX_DN<2>")
	)
	(segment
		(start 350.473264 -298.149772)
		(end 350.473264 -295.698926)
		(width 0.1143)
		(layer "In2.Cu")
		(net "P3E_CPU0_P4_RX_DN<2>")
	)
	(segment
		(start 326.747124 -312.757566)
		(end 340.432136 -311.409334)
		(width 0.14224)
		(layer "In2.Cu")
		(net "P3E_CPU0_P4_RX_DN<2>")
	)
	(arc
		(start 350.716596 -295.145968)
		(mid 350.758145 -294.974546)
		(end 350.873568 -294.841168)
		(width 0.1143)
		(layer "In2.Cu")
		(net "P3E_CPU0_P4_RX_DN<2>")
	)
	(arc
		(start 351.17659 -294.441626)
		(mid 351.178613 -294.430216)
		(end 351.1804 -294.418766)
		(width 0.1143)
		(layer "In2.Cu")
		(net "P3E_CPU0_P4_RX_DN<2>")
	)
	(arc
		(start 350.533208 -295.562782)
		(mid 350.668715 -295.373653)
		(end 350.716596 -295.145968)
		(width 0.1143)
		(layer "In2.Cu")
		(net "P3E_CPU0_P4_RX_DN<2>")
	)
	(arc
		(start 350.473264 -295.698926)
		(mid 350.488855 -295.624516)
		(end 350.533208 -295.562782)
		(width 0.1143)
		(layer "In2.Cu")
		(net "P3E_CPU0_P4_RX_DN<2>")
	)
	(arc
		(start 350.943164 -294.800528)
		(mid 351.095151 -294.64402)
		(end 351.17659 -294.441626)
		(width 0.1143)
		(layer "In2.Cu")
		(net "P3E_CPU0_P4_RX_DN<2>")
	)
	(segment
		(start 246.012208 -160.059116)
		(end 245.966488 -159.675576)
		(width 0.12954)
		(layer "F.Cu")
		(net "P3E_CPU0_P4_RX_DN<1>")
	)
	(segment
		(start 255.159002 -210.395566)
		(end 254.404876 -210.082892)
		(width 0.12954)
		(layer "F.Cu")
		(net "P3E_CPU0_P4_RX_DN<1>")
	)
	(segment
		(start 245.87581 -158.914084)
		(end 245.83009 -158.53029)
		(width 0.12954)
		(layer "F.Cu")
		(net "P3E_CPU0_P4_RX_DN<1>")
	)
	(segment
		(start 251.009912 -202.03922)
		(end 250.964192 -201.65568)
		(width 0.12954)
		(layer "F.Cu")
		(net "P3E_CPU0_P4_RX_DN<1>")
	)
	(segment
		(start 244.712744 -150.757382)
		(end 228.372416 -83.363054)
		(width 0.12954)
		(layer "F.Cu")
		(net "P3E_CPU0_P4_RX_DN<1>")
	)
	(segment
		(start 255.679448 -210.395566)
		(end 255.159002 -210.395566)
		(width 0.12954)
		(layer "F.Cu")
		(net "P3E_CPU0_P4_RX_DN<1>")
	)
	(segment
		(start 349.20809 -294.070024)
		(end 348.741238 -294.335962)
		(width 0.12954)
		(layer "F.Cu")
		(net "P3E_CPU0_P4_RX_DN<1>")
	)
	(segment
		(start 245.557294 -156.239718)
		(end 245.345458 -156.073094)
		(width 0.12954)
		(layer "F.Cu")
		(net "P3E_CPU0_P4_RX_DN<1>")
	)
	(segment
		(start 254.404876 -210.082892)
		(end 252.932438 -208.610708)
		(width 0.12954)
		(layer "F.Cu")
		(net "P3E_CPU0_P4_RX_DN<1>")
	)
	(segment
		(start 228.625146 -68.26504)
		(end 228.625146 -58.386218)
		(width 0.12954)
		(layer "F.Cu")
		(net "P3E_CPU0_P4_RX_DN<1>")
	)
	(segment
		(start 250.827794 -200.510394)
		(end 250.615958 -200.34377)
		(width 0.12954)
		(layer "F.Cu")
		(net "P3E_CPU0_P4_RX_DN<1>")
	)
	(segment
		(start 245.693692 -157.385004)
		(end 245.481856 -157.21838)
		(width 0.12954)
		(layer "F.Cu")
		(net "P3E_CPU0_P4_RX_DN<1>")
	)
	(segment
		(start 250.616212 -200.34377)
		(end 248.595134 -183.36768)
		(width 0.12954)
		(layer "F.Cu")
		(net "P3E_CPU0_P4_RX_DN<1>")
	)
	(segment
		(start 228.372416 -83.363054)
		(end 228.625146 -68.26504)
		(width 0.12954)
		(layer "F.Cu")
		(net "P3E_CPU0_P4_RX_DN<1>")
	)
	(segment
		(start 230.942134 -54.522624)
		(end 231.174544 -54.426358)
		(width 0.12954)
		(layer "F.Cu")
		(net "P3E_CPU0_P4_RX_DN<1>")
	)
	(segment
		(start 250.70689 -201.10577)
		(end 250.873514 -200.894188)
		(width 0.12954)
		(layer "F.Cu")
		(net "P3E_CPU0_P4_RX_DN<1>")
	)
	(segment
		(start 250.843288 -202.250802)
		(end 251.009912 -202.03922)
		(width 0.12954)
		(layer "F.Cu")
		(net "P3E_CPU0_P4_RX_DN<1>")
	)
	(segment
		(start 255.927098 -210.147916)
		(end 255.679448 -210.395566)
		(width 0.12954)
		(layer "F.Cu")
		(net "P3E_CPU0_P4_RX_DN<1>")
	)
	(segment
		(start 245.739412 -157.768798)
		(end 245.693692 -157.385004)
		(width 0.12954)
		(layer "F.Cu")
		(net "P3E_CPU0_P4_RX_DN<1>")
	)
	(segment
		(start 228.797358 -57.520332)
		(end 229.10927 -56.766714)
		(width 0.12954)
		(layer "F.Cu")
		(net "P3E_CPU0_P4_RX_DN<1>")
	)
	(segment
		(start 245.43639 -156.835094)
		(end 245.603014 -156.623512)
		(width 0.12954)
		(layer "F.Cu")
		(net "P3E_CPU0_P4_RX_DN<1>")
	)
	(segment
		(start 250.894596 -202.682856)
		(end 250.843288 -202.250802)
		(width 0.12954)
		(layer "F.Cu")
		(net "P3E_CPU0_P4_RX_DN<1>")
	)
	(segment
		(start 251.167392 -204.97546)
		(end 250.985528 -203.444856)
		(width 0.12954)
		(layer "F.Cu")
		(net "P3E_CPU0_P4_RX_DN<1>")
	)
	(segment
		(start 251.152152 -203.233274)
		(end 251.106432 -202.849734)
		(width 0.12954)
		(layer "F.Cu")
		(net "P3E_CPU0_P4_RX_DN<1>")
	)
	(segment
		(start 228.625146 -58.386218)
		(end 228.797358 -57.520332)
		(width 0.12954)
		(layer "F.Cu")
		(net "P3E_CPU0_P4_RX_DN<1>")
	)
	(segment
		(start 245.754652 -159.508952)
		(end 245.709186 -159.125666)
		(width 0.12954)
		(layer "F.Cu")
		(net "P3E_CPU0_P4_RX_DN<1>")
	)
	(segment
		(start 231.174544 -54.426358)
		(end 231.371902 -54.426358)
		(width 0.12954)
		(layer "F.Cu")
		(net "P3E_CPU0_P4_RX_DN<1>")
	)
	(segment
		(start 251.106432 -202.849734)
		(end 250.894596 -202.682856)
		(width 0.12954)
		(layer "F.Cu")
		(net "P3E_CPU0_P4_RX_DN<1>")
	)
	(segment
		(start 250.964192 -201.65568)
		(end 250.752356 -201.489056)
		(width 0.12954)
		(layer "F.Cu")
		(net "P3E_CPU0_P4_RX_DN<1>")
	)
	(segment
		(start 245.572788 -157.98038)
		(end 245.739412 -157.768798)
		(width 0.12954)
		(layer "F.Cu")
		(net "P3E_CPU0_P4_RX_DN<1>")
	)
	(segment
		(start 245.618254 -158.363666)
		(end 245.572788 -157.98038)
		(width 0.12954)
		(layer "F.Cu")
		(net "P3E_CPU0_P4_RX_DN<1>")
	)
	(segment
		(start 245.83009 -158.53029)
		(end 245.618254 -158.363666)
		(width 0.12954)
		(layer "F.Cu")
		(net "P3E_CPU0_P4_RX_DN<1>")
	)
	(segment
		(start 250.752356 -201.489056)
		(end 250.70689 -201.10577)
		(width 0.12954)
		(layer "F.Cu")
		(net "P3E_CPU0_P4_RX_DN<1>")
	)
	(segment
		(start 250.873514 -200.894188)
		(end 250.827794 -200.510394)
		(width 0.12954)
		(layer "F.Cu")
		(net "P3E_CPU0_P4_RX_DN<1>")
	)
	(segment
		(start 250.615958 -200.34377)
		(end 250.616212 -200.34377)
		(width 0.12954)
		(layer "F.Cu")
		(net "P3E_CPU0_P4_RX_DN<1>")
	)
	(segment
		(start 231.371902 -54.426358)
		(end 231.510586 -54.565042)
		(width 0.12954)
		(layer "F.Cu")
		(net "P3E_CPU0_P4_RX_DN<1>")
	)
	(segment
		(start 252.932438 -208.610708)
		(end 251.167392 -204.97546)
		(width 0.12954)
		(layer "F.Cu")
		(net "P3E_CPU0_P4_RX_DN<1>")
	)
	(segment
		(start 231.510586 -54.565042)
		(end 232.000044 -54.565042)
		(width 0.12954)
		(layer "F.Cu")
		(net "P3E_CPU0_P4_RX_DN<1>")
	)
	(segment
		(start 245.966488 -159.675576)
		(end 245.754652 -159.508952)
		(width 0.12954)
		(layer "F.Cu")
		(net "P3E_CPU0_P4_RX_DN<1>")
	)
	(segment
		(start 229.10927 -56.766714)
		(end 230.10368 -55.278528)
		(width 0.12954)
		(layer "F.Cu")
		(net "P3E_CPU0_P4_RX_DN<1>")
	)
	(segment
		(start 245.709186 -159.125666)
		(end 245.87581 -158.914084)
		(width 0.12954)
		(layer "F.Cu")
		(net "P3E_CPU0_P4_RX_DN<1>")
	)
	(segment
		(start 230.69296 -54.689248)
		(end 230.942134 -54.522624)
		(width 0.12954)
		(layer "F.Cu")
		(net "P3E_CPU0_P4_RX_DN<1>")
	)
	(segment
		(start 245.845584 -160.270952)
		(end 246.012208 -160.059116)
		(width 0.12954)
		(layer "F.Cu")
		(net "P3E_CPU0_P4_RX_DN<1>")
	)
	(segment
		(start 250.985528 -203.444856)
		(end 251.152152 -203.233274)
		(width 0.12954)
		(layer "F.Cu")
		(net "P3E_CPU0_P4_RX_DN<1>")
	)
	(segment
		(start 230.10368 -55.278528)
		(end 230.69296 -54.689248)
		(width 0.12954)
		(layer "F.Cu")
		(net "P3E_CPU0_P4_RX_DN<1>")
	)
	(segment
		(start 248.595134 -183.36768)
		(end 245.845584 -160.270952)
		(width 0.12954)
		(layer "F.Cu")
		(net "P3E_CPU0_P4_RX_DN<1>")
	)
	(segment
		(start 245.481856 -157.21838)
		(end 245.43639 -156.835094)
		(width 0.12954)
		(layer "F.Cu")
		(net "P3E_CPU0_P4_RX_DN<1>")
	)
	(segment
		(start 245.603014 -156.623512)
		(end 245.557294 -156.239718)
		(width 0.12954)
		(layer "F.Cu")
		(net "P3E_CPU0_P4_RX_DN<1>")
	)
	(segment
		(start 245.345458 -156.073094)
		(end 244.712744 -150.757382)
		(width 0.12954)
		(layer "F.Cu")
		(net "P3E_CPU0_P4_RX_DN<1>")
	)
	(segment
		(start 263.380728 -320.88074)
		(end 310.473344 -321.199764)
		(width 0.14224)
		(layer "In2.Cu")
		(net "P3E_CPU0_P4_RX_DN<1>")
	)
	(segment
		(start 347.590872 -296.843196)
		(end 347.545152 -296.797476)
		(width 0.1143)
		(layer "In2.Cu")
		(net "P3E_CPU0_P4_RX_DN<1>")
	)
	(segment
		(start 336.435446 -305.902868)
		(end 345.802458 -300.896782)
		(width 0.14224)
		(layer "In2.Cu")
		(net "P3E_CPU0_P4_RX_DN<1>")
	)
	(segment
		(start 255.349756 -210.438746)
		(end 255.051052 -210.529424)
		(width 0.14224)
		(layer "In2.Cu")
		(net "P3E_CPU0_P4_RX_DN<1>")
	)
	(segment
		(start 317.843408 -314.645802)
		(end 319.694814 -313.878976)
		(width 0.14224)
		(layer "In2.Cu")
		(net "P3E_CPU0_P4_RX_DN<1>")
	)
	(segment
		(start 347.7133 -295.562528)
		(end 347.7133 -295.562782)
		(width 0.1143)
		(layer "In2.Cu")
		(net "P3E_CPU0_P4_RX_DN<1>")
	)
	(segment
		(start 348.05366 -294.841168)
		(end 348.123256 -294.800528)
		(width 0.1143)
		(layer "In2.Cu")
		(net "P3E_CPU0_P4_RX_DN<1>")
	)
	(segment
		(start 255.051052 -210.529424)
		(end 254.75819 -210.725004)
		(width 0.14224)
		(layer "In2.Cu")
		(net "P3E_CPU0_P4_RX_DN<1>")
	)
	(segment
		(start 348.443296 -294.335962)
		(end 348.741238 -294.335962)
		(width 0.1143)
		(layer "In2.Cu")
		(net "P3E_CPU0_P4_RX_DN<1>")
	)
	(segment
		(start 255.927098 -210.147916)
		(end 255.636268 -210.438746)
		(width 0.14224)
		(layer "In2.Cu")
		(net "P3E_CPU0_P4_RX_DN<1>")
	)
	(segment
		(start 253.119636 -214.403686)
		(end 253.119636 -231.318308)
		(width 0.14224)
		(layer "In2.Cu")
		(net "P3E_CPU0_P4_RX_DN<1>")
	)
	(segment
		(start 255.636268 -210.438746)
		(end 255.349756 -210.438746)
		(width 0.14224)
		(layer "In2.Cu")
		(net "P3E_CPU0_P4_RX_DN<1>")
	)
	(segment
		(start 331.89926 -309.094632)
		(end 336.435446 -305.902868)
		(width 0.14224)
		(layer "In2.Cu")
		(net "P3E_CPU0_P4_RX_DN<1>")
	)
	(segment
		(start 262.734044 -320.609976)
		(end 263.380728 -320.88074)
		(width 0.14224)
		(layer "In2.Cu")
		(net "P3E_CPU0_P4_RX_DN<1>")
	)
	(segment
		(start 253.362714 -213.18093)
		(end 253.119636 -214.403686)
		(width 0.14224)
		(layer "In2.Cu")
		(net "P3E_CPU0_P4_RX_DN<1>")
	)
	(segment
		(start 310.473344 -321.199764)
		(end 311.866534 -320.622676)
		(width 0.14224)
		(layer "In2.Cu")
		(net "P3E_CPU0_P4_RX_DN<1>")
	)
	(segment
		(start 347.590872 -299.108368)
		(end 347.590872 -296.871644)
		(width 0.14224)
		(layer "In2.Cu")
		(net "P3E_CPU0_P4_RX_DN<1>")
	)
	(segment
		(start 253.119636 -231.318308)
		(end 253.70409 -236.755178)
		(width 0.14224)
		(layer "In2.Cu")
		(net "P3E_CPU0_P4_RX_DN<1>")
	)
	(segment
		(start 262.651748 -320.52768)
		(end 262.734044 -320.609976)
		(width 0.14224)
		(layer "In2.Cu")
		(net "P3E_CPU0_P4_RX_DN<1>")
	)
	(segment
		(start 347.65361 -295.807384)
		(end 347.65361 -295.698672)
		(width 0.1143)
		(layer "In2.Cu")
		(net "P3E_CPU0_P4_RX_DN<1>")
	)
	(segment
		(start 253.994158 -211.656422)
		(end 253.362714 -213.18093)
		(width 0.14224)
		(layer "In2.Cu")
		(net "P3E_CPU0_P4_RX_DN<1>")
	)
	(segment
		(start 348.360492 -294.418766)
		(end 348.443296 -294.335962)
		(width 0.1143)
		(layer "In2.Cu")
		(net "P3E_CPU0_P4_RX_DN<1>")
	)
	(segment
		(start 329.541632 -310.35498)
		(end 331.89926 -309.094632)
		(width 0.14224)
		(layer "In2.Cu")
		(net "P3E_CPU0_P4_RX_DN<1>")
	)
	(segment
		(start 319.694814 -313.878976)
		(end 329.541632 -310.35498)
		(width 0.14224)
		(layer "In2.Cu")
		(net "P3E_CPU0_P4_RX_DN<1>")
	)
	(segment
		(start 253.70409 -236.755178)
		(end 258.852924 -267.378688)
		(width 0.14224)
		(layer "In2.Cu")
		(net "P3E_CPU0_P4_RX_DN<1>")
	)
	(segment
		(start 258.852924 -267.378688)
		(end 262.651748 -320.52768)
		(width 0.14224)
		(layer "In2.Cu")
		(net "P3E_CPU0_P4_RX_DN<1>")
	)
	(segment
		(start 347.590872 -296.871644)
		(end 347.590872 -296.843196)
		(width 0.1143)
		(layer "In2.Cu")
		(net "P3E_CPU0_P4_RX_DN<1>")
	)
	(segment
		(start 345.802458 -300.896782)
		(end 347.590872 -299.108368)
		(width 0.14224)
		(layer "In2.Cu")
		(net "P3E_CPU0_P4_RX_DN<1>")
	)
	(segment
		(start 347.545152 -296.797476)
		(end 347.545152 -296.081958)
		(width 0.1143)
		(layer "In2.Cu")
		(net "P3E_CPU0_P4_RX_DN<1>")
	)
	(segment
		(start 311.866534 -320.622676)
		(end 317.843408 -314.645802)
		(width 0.14224)
		(layer "In2.Cu")
		(net "P3E_CPU0_P4_RX_DN<1>")
	)
	(segment
		(start 254.75819 -210.725004)
		(end 253.994158 -211.656422)
		(width 0.14224)
		(layer "In2.Cu")
		(net "P3E_CPU0_P4_RX_DN<1>")
	)
	(arc
		(start 347.896688 -295.145968)
		(mid 347.938237 -294.974546)
		(end 348.05366 -294.841168)
		(width 0.1143)
		(layer "In2.Cu")
		(net "P3E_CPU0_P4_RX_DN<1>")
	)
	(arc
		(start 347.65361 -295.698672)
		(mid 347.669077 -295.624289)
		(end 347.7133 -295.562528)
		(width 0.1143)
		(layer "In2.Cu")
		(net "P3E_CPU0_P4_RX_DN<1>")
	)
	(arc
		(start 347.545152 -296.081958)
		(mid 347.625661 -295.95505)
		(end 347.65361 -295.807384)
		(width 0.1143)
		(layer "In2.Cu")
		(net "P3E_CPU0_P4_RX_DN<1>")
	)
	(arc
		(start 348.356682 -294.441626)
		(mid 348.358705 -294.430216)
		(end 348.360492 -294.418766)
		(width 0.1143)
		(layer "In2.Cu")
		(net "P3E_CPU0_P4_RX_DN<1>")
	)
	(arc
		(start 347.7133 -295.562782)
		(mid 347.780295 -295.489461)
		(end 347.833442 -295.405556)
		(width 0.1143)
		(layer "In2.Cu")
		(net "P3E_CPU0_P4_RX_DN<1>")
	)
	(arc
		(start 347.833442 -295.405556)
		(mid 347.880618 -295.279551)
		(end 347.896688 -295.145968)
		(width 0.1143)
		(layer "In2.Cu")
		(net "P3E_CPU0_P4_RX_DN<1>")
	)
	(arc
		(start 348.123256 -294.800528)
		(mid 348.275243 -294.64402)
		(end 348.356682 -294.441626)
		(width 0.1143)
		(layer "In2.Cu")
		(net "P3E_CPU0_P4_RX_DN<1>")
	)
	(segment
		(start 243.598954 -149.88413)
		(end 227.502212 -83.493102)
		(width 0.12954)
		(layer "F.Cu")
		(net "P3E_CPU0_P4_RX_DN<0>")
	)
	(segment
		(start 249.906536 -202.864212)
		(end 249.90679 -202.864212)
		(width 0.12954)
		(layer "F.Cu")
		(net "P3E_CPU0_P4_RX_DN<0>")
	)
	(segment
		(start 250.161298 -203.412344)
		(end 250.115578 -203.028804)
		(width 0.12954)
		(layer "F.Cu")
		(net "P3E_CPU0_P4_RX_DN<0>")
	)
	(segment
		(start 253.59487 -211.856828)
		(end 253.321566 -211.583524)
		(width 0.12954)
		(layer "F.Cu")
		(net "P3E_CPU0_P4_RX_DN<0>")
	)
	(segment
		(start 249.854212 -202.42276)
		(end 250.018804 -202.213718)
		(width 0.12954)
		(layer "F.Cu")
		(net "P3E_CPU0_P4_RX_DN<0>")
	)
	(segment
		(start 251.902722 -209.044794)
		(end 251.65685 -208.943194)
		(width 0.12954)
		(layer "F.Cu")
		(net "P3E_CPU0_P4_RX_DN<0>")
	)
	(segment
		(start 249.709432 -201.206608)
		(end 249.87377 -200.99782)
		(width 0.12954)
		(layer "F.Cu")
		(net "P3E_CPU0_P4_RX_DN<0>")
	)
	(segment
		(start 227.7491 -58.330592)
		(end 227.971604 -57.211468)
		(width 0.12954)
		(layer "F.Cu")
		(net "P3E_CPU0_P4_RX_DN<0>")
	)
	(segment
		(start 249.90679 -202.864212)
		(end 249.854212 -202.42276)
		(width 0.12954)
		(layer "F.Cu")
		(net "P3E_CPU0_P4_RX_DN<0>")
	)
	(segment
		(start 249.828304 -200.614026)
		(end 249.619008 -200.449688)
		(width 0.12954)
		(layer "F.Cu")
		(net "P3E_CPU0_P4_RX_DN<0>")
	)
	(segment
		(start 249.764042 -201.66584)
		(end 249.709432 -201.206608)
		(width 0.12954)
		(layer "F.Cu")
		(net "P3E_CPU0_P4_RX_DN<0>")
	)
	(segment
		(start 252.050296 -209.401664)
		(end 251.902722 -209.044794)
		(width 0.12954)
		(layer "F.Cu")
		(net "P3E_CPU0_P4_RX_DN<0>")
	)
	(segment
		(start 252.537722 -211.069428)
		(end 252.390148 -210.712812)
		(width 0.12954)
		(layer "F.Cu")
		(net "P3E_CPU0_P4_RX_DN<0>")
	)
	(segment
		(start 253.321566 -211.583524)
		(end 253.052072 -211.583524)
		(width 0.12954)
		(layer "F.Cu")
		(net "P3E_CPU0_P4_RX_DN<0>")
	)
	(segment
		(start 346.387928 -294.070024)
		(end 345.921076 -294.335962)
		(width 0.12954)
		(layer "F.Cu")
		(net "P3E_CPU0_P4_RX_DN<0>")
	)
	(segment
		(start 229.862634 -53.599588)
		(end 230.650796 -52.811426)
		(width 0.12954)
		(layer "F.Cu")
		(net "P3E_CPU0_P4_RX_DN<0>")
	)
	(segment
		(start 251.948696 -209.647282)
		(end 252.050296 -209.401664)
		(width 0.12954)
		(layer "F.Cu")
		(net "P3E_CPU0_P4_RX_DN<0>")
	)
	(segment
		(start 255.927098 -212.942424)
		(end 255.699006 -213.170516)
		(width 0.12954)
		(layer "F.Cu")
		(net "P3E_CPU0_P4_RX_DN<0>")
	)
	(segment
		(start 254.779018 -213.170516)
		(end 254.540004 -213.071202)
		(width 0.12954)
		(layer "F.Cu")
		(net "P3E_CPU0_P4_RX_DN<0>")
	)
	(segment
		(start 253.052072 -211.583524)
		(end 252.537722 -211.069428)
		(width 0.12954)
		(layer "F.Cu")
		(net "P3E_CPU0_P4_RX_DN<0>")
	)
	(segment
		(start 254.540004 -213.071202)
		(end 254.410464 -212.941916)
		(width 0.12954)
		(layer "F.Cu")
		(net "P3E_CPU0_P4_RX_DN<0>")
	)
	(segment
		(start 254.410464 -212.941916)
		(end 254.410464 -212.672422)
		(width 0.12954)
		(layer "F.Cu")
		(net "P3E_CPU0_P4_RX_DN<0>")
	)
	(segment
		(start 227.7491 -68.766944)
		(end 227.7491 -58.330592)
		(width 0.12954)
		(layer "F.Cu")
		(net "P3E_CPU0_P4_RX_DN<0>")
	)
	(segment
		(start 254.410464 -212.672422)
		(end 254.13716 -212.399118)
		(width 0.12954)
		(layer "F.Cu")
		(net "P3E_CPU0_P4_RX_DN<0>")
	)
	(segment
		(start 231.357678 -52.62626)
		(end 231.496362 -52.764944)
		(width 0.12954)
		(layer "F.Cu")
		(net "P3E_CPU0_P4_RX_DN<0>")
	)
	(segment
		(start 252.390148 -210.712812)
		(end 252.493272 -210.463892)
		(width 0.12954)
		(layer "F.Cu")
		(net "P3E_CPU0_P4_RX_DN<0>")
	)
	(segment
		(start 249.619262 -200.449688)
		(end 243.598954 -149.88413)
		(width 0.12954)
		(layer "F.Cu")
		(net "P3E_CPU0_P4_RX_DN<0>")
	)
	(segment
		(start 251.65685 -208.943194)
		(end 250.216416 -205.465934)
		(width 0.12954)
		(layer "F.Cu")
		(net "P3E_CPU0_P4_RX_DN<0>")
	)
	(segment
		(start 255.699006 -213.170516)
		(end 254.779018 -213.170516)
		(width 0.12954)
		(layer "F.Cu")
		(net "P3E_CPU0_P4_RX_DN<0>")
	)
	(segment
		(start 252.493272 -210.463892)
		(end 252.345444 -210.107022)
		(width 0.12954)
		(layer "F.Cu")
		(net "P3E_CPU0_P4_RX_DN<0>")
	)
	(segment
		(start 252.09627 -210.003898)
		(end 251.948696 -209.647282)
		(width 0.12954)
		(layer "F.Cu")
		(net "P3E_CPU0_P4_RX_DN<0>")
	)
	(segment
		(start 227.971604 -57.211468)
		(end 228.824282 -55.15356)
		(width 0.12954)
		(layer "F.Cu")
		(net "P3E_CPU0_P4_RX_DN<0>")
	)
	(segment
		(start 250.115578 -203.028804)
		(end 249.906536 -202.864212)
		(width 0.12954)
		(layer "F.Cu")
		(net "P3E_CPU0_P4_RX_DN<0>")
	)
	(segment
		(start 231.097836 -52.62626)
		(end 231.357678 -52.62626)
		(width 0.12954)
		(layer "F.Cu")
		(net "P3E_CPU0_P4_RX_DN<0>")
	)
	(segment
		(start 250.018804 -202.213718)
		(end 249.973084 -201.830178)
		(width 0.12954)
		(layer "F.Cu")
		(net "P3E_CPU0_P4_RX_DN<0>")
	)
	(segment
		(start 250.216416 -205.465934)
		(end 249.99696 -203.621132)
		(width 0.12954)
		(layer "F.Cu")
		(net "P3E_CPU0_P4_RX_DN<0>")
	)
	(segment
		(start 252.345444 -210.107022)
		(end 252.09627 -210.003898)
		(width 0.12954)
		(layer "F.Cu")
		(net "P3E_CPU0_P4_RX_DN<0>")
	)
	(segment
		(start 254.13716 -212.399118)
		(end 253.867666 -212.399118)
		(width 0.12954)
		(layer "F.Cu")
		(net "P3E_CPU0_P4_RX_DN<0>")
	)
	(segment
		(start 228.824282 -55.15356)
		(end 229.862634 -53.599588)
		(width 0.12954)
		(layer "F.Cu")
		(net "P3E_CPU0_P4_RX_DN<0>")
	)
	(segment
		(start 249.87377 -200.99782)
		(end 249.828304 -200.614026)
		(width 0.12954)
		(layer "F.Cu")
		(net "P3E_CPU0_P4_RX_DN<0>")
	)
	(segment
		(start 249.99696 -203.621132)
		(end 250.161298 -203.412344)
		(width 0.12954)
		(layer "F.Cu")
		(net "P3E_CPU0_P4_RX_DN<0>")
	)
	(segment
		(start 249.973084 -201.830178)
		(end 249.764042 -201.66584)
		(width 0.12954)
		(layer "F.Cu")
		(net "P3E_CPU0_P4_RX_DN<0>")
	)
	(segment
		(start 253.59487 -212.126322)
		(end 253.59487 -211.856828)
		(width 0.12954)
		(layer "F.Cu")
		(net "P3E_CPU0_P4_RX_DN<0>")
	)
	(segment
		(start 253.867666 -212.399118)
		(end 253.59487 -212.126322)
		(width 0.12954)
		(layer "F.Cu")
		(net "P3E_CPU0_P4_RX_DN<0>")
	)
	(segment
		(start 231.496362 -52.764944)
		(end 232.000044 -52.764944)
		(width 0.12954)
		(layer "F.Cu")
		(net "P3E_CPU0_P4_RX_DN<0>")
	)
	(segment
		(start 249.619008 -200.449688)
		(end 249.619262 -200.449688)
		(width 0.12954)
		(layer "F.Cu")
		(net "P3E_CPU0_P4_RX_DN<0>")
	)
	(segment
		(start 227.502212 -83.493102)
		(end 227.7491 -68.766944)
		(width 0.12954)
		(layer "F.Cu")
		(net "P3E_CPU0_P4_RX_DN<0>")
	)
	(segment
		(start 230.650796 -52.811426)
		(end 231.097836 -52.62626)
		(width 0.12954)
		(layer "F.Cu")
		(net "P3E_CPU0_P4_RX_DN<0>")
	)
	(segment
		(start 264.428224 -318.90589)
		(end 264.668762 -319.38214)
		(width 0.14224)
		(layer "In2.Cu")
		(net "P3E_CPU0_P4_RX_DN<0>")
	)
	(segment
		(start 344.326972 -297.74007)
		(end 344.7542 -297.2181)
		(width 0.14224)
		(layer "In2.Cu")
		(net "P3E_CPU0_P4_RX_DN<0>")
	)
	(segment
		(start 264.977372 -319.69075)
		(end 265.446764 -319.887092)
		(width 0.14224)
		(layer "In2.Cu")
		(net "P3E_CPU0_P4_RX_DN<0>")
	)
	(segment
		(start 311.571132 -319.599564)
		(end 317.539624 -313.631072)
		(width 0.14224)
		(layer "In2.Cu")
		(net "P3E_CPU0_P4_RX_DN<0>")
	)
	(segment
		(start 324.973442 -310.552592)
		(end 324.97395 -310.55183)
		(width 0.14224)
		(layer "In2.Cu")
		(net "P3E_CPU0_P4_RX_DN<0>")
	)
	(segment
		(start 345.233498 -294.841168)
		(end 345.303094 -294.800528)
		(width 0.1143)
		(layer "In2.Cu")
		(net "P3E_CPU0_P4_RX_DN<0>")
	)
	(segment
		(start 344.7542 -296.583862)
		(end 344.70848 -296.538142)
		(width 0.1143)
		(layer "In2.Cu")
		(net "P3E_CPU0_P4_RX_DN<0>")
	)
	(segment
		(start 254.267462 -233.24312)
		(end 260.04266 -267.599414)
		(width 0.14224)
		(layer "In2.Cu")
		(net "P3E_CPU0_P4_RX_DN<0>")
	)
	(segment
		(start 264.082022 -316.608968)
		(end 264.428224 -318.90589)
		(width 0.14224)
		(layer "In2.Cu")
		(net "P3E_CPU0_P4_RX_DN<0>")
	)
	(segment
		(start 345.623134 -294.335962)
		(end 345.921076 -294.335962)
		(width 0.1143)
		(layer "In2.Cu")
		(net "P3E_CPU0_P4_RX_DN<0>")
	)
	(segment
		(start 334.569308 -300.740826)
		(end 339.494622 -298.700952)
		(width 0.14224)
		(layer "In2.Cu")
		(net "P3E_CPU0_P4_RX_DN<0>")
	)
	(segment
		(start 254.382016 -214.405972)
		(end 254.267462 -214.982806)
		(width 0.14224)
		(layer "In2.Cu")
		(net "P3E_CPU0_P4_RX_DN<0>")
	)
	(segment
		(start 255.411224 -213.233254)
		(end 254.95631 -213.421722)
		(width 0.14224)
		(layer "In2.Cu")
		(net "P3E_CPU0_P4_RX_DN<0>")
	)
	(segment
		(start 331.628496 -307.031136)
		(end 333.9973 -301.312834)
		(width 0.14224)
		(layer "In2.Cu")
		(net "P3E_CPU0_P4_RX_DN<0>")
	)
	(segment
		(start 255.927098 -212.942424)
		(end 255.636268 -213.233254)
		(width 0.14224)
		(layer "In2.Cu")
		(net "P3E_CPU0_P4_RX_DN<0>")
	)
	(segment
		(start 333.9973 -301.312834)
		(end 334.569308 -300.740826)
		(width 0.14224)
		(layer "In2.Cu")
		(net "P3E_CPU0_P4_RX_DN<0>")
	)
	(segment
		(start 260.04266 -267.599414)
		(end 263.062212 -309.842916)
		(width 0.14224)
		(layer "In2.Cu")
		(net "P3E_CPU0_P4_RX_DN<0>")
	)
	(segment
		(start 345.54033 -294.418766)
		(end 345.623134 -294.335962)
		(width 0.1143)
		(layer "In2.Cu")
		(net "P3E_CPU0_P4_RX_DN<0>")
	)
	(segment
		(start 263.062212 -309.842916)
		(end 264.082022 -316.608714)
		(width 0.14224)
		(layer "In2.Cu")
		(net "P3E_CPU0_P4_RX_DN<0>")
	)
	(segment
		(start 344.7542 -297.2181)
		(end 344.7542 -296.61231)
		(width 0.14224)
		(layer "In2.Cu")
		(net "P3E_CPU0_P4_RX_DN<0>")
	)
	(segment
		(start 254.95631 -213.421722)
		(end 254.672338 -213.705694)
		(width 0.14224)
		(layer "In2.Cu")
		(net "P3E_CPU0_P4_RX_DN<0>")
	)
	(segment
		(start 264.082022 -316.608714)
		(end 264.082022 -316.608968)
		(width 0.14224)
		(layer "In2.Cu")
		(net "P3E_CPU0_P4_RX_DN<0>")
	)
	(segment
		(start 254.267462 -214.982806)
		(end 254.267462 -233.24312)
		(width 0.14224)
		(layer "In2.Cu")
		(net "P3E_CPU0_P4_RX_DN<0>")
	)
	(segment
		(start 344.7542 -296.61231)
		(end 344.7542 -296.583862)
		(width 0.1143)
		(layer "In2.Cu")
		(net "P3E_CPU0_P4_RX_DN<0>")
	)
	(segment
		(start 339.494622 -298.700952)
		(end 344.326972 -297.74007)
		(width 0.14224)
		(layer "In2.Cu")
		(net "P3E_CPU0_P4_RX_DN<0>")
	)
	(segment
		(start 344.70848 -296.538142)
		(end 344.70848 -295.981628)
		(width 0.1143)
		(layer "In2.Cu")
		(net "P3E_CPU0_P4_RX_DN<0>")
	)
	(segment
		(start 310.31815 -320.118994)
		(end 311.571132 -319.599564)
		(width 0.14224)
		(layer "In2.Cu")
		(net "P3E_CPU0_P4_RX_DN<0>")
	)
	(segment
		(start 309.684928 -320.189606)
		(end 310.033162 -320.17462)
		(width 0.14224)
		(layer "In2.Cu")
		(net "P3E_CPU0_P4_RX_DN<0>")
	)
	(segment
		(start 317.539624 -313.631072)
		(end 324.973442 -310.552592)
		(width 0.14224)
		(layer "In2.Cu")
		(net "P3E_CPU0_P4_RX_DN<0>")
	)
	(segment
		(start 264.668762 -319.38214)
		(end 264.977372 -319.69075)
		(width 0.14224)
		(layer "In2.Cu")
		(net "P3E_CPU0_P4_RX_DN<0>")
	)
	(segment
		(start 330.323698 -308.335934)
		(end 331.628496 -307.031136)
		(width 0.14224)
		(layer "In2.Cu")
		(net "P3E_CPU0_P4_RX_DN<0>")
	)
	(segment
		(start 254.672338 -213.705694)
		(end 254.382016 -214.405972)
		(width 0.14224)
		(layer "In2.Cu")
		(net "P3E_CPU0_P4_RX_DN<0>")
	)
	(segment
		(start 324.97395 -310.55183)
		(end 330.323698 -308.335934)
		(width 0.14224)
		(layer "In2.Cu")
		(net "P3E_CPU0_P4_RX_DN<0>")
	)
	(segment
		(start 310.033162 -320.17462)
		(end 310.31815 -320.118994)
		(width 0.14224)
		(layer "In2.Cu")
		(net "P3E_CPU0_P4_RX_DN<0>")
	)
	(segment
		(start 255.636268 -213.233254)
		(end 255.411224 -213.233254)
		(width 0.14224)
		(layer "In2.Cu")
		(net "P3E_CPU0_P4_RX_DN<0>")
	)
	(segment
		(start 265.446764 -319.887092)
		(end 309.684928 -320.189606)
		(width 0.14224)
		(layer "In2.Cu")
		(net "P3E_CPU0_P4_RX_DN<0>")
	)
	(arc
		(start 345.303094 -294.800528)
		(mid 345.455081 -294.64402)
		(end 345.53652 -294.441626)
		(width 0.1143)
		(layer "In2.Cu")
		(net "P3E_CPU0_P4_RX_DN<0>")
	)
	(arc
		(start 344.893138 -295.562782)
		(mid 345.028645 -295.373653)
		(end 345.076526 -295.145968)
		(width 0.1143)
		(layer "In2.Cu")
		(net "P3E_CPU0_P4_RX_DN<0>")
	)
	(arc
		(start 345.53652 -294.441626)
		(mid 345.538543 -294.430216)
		(end 345.54033 -294.418766)
		(width 0.1143)
		(layer "In2.Cu")
		(net "P3E_CPU0_P4_RX_DN<0>")
	)
	(arc
		(start 344.70848 -295.981628)
		(mid 344.756687 -295.75275)
		(end 344.893138 -295.562782)
		(width 0.1143)
		(layer "In2.Cu")
		(net "P3E_CPU0_P4_RX_DN<0>")
	)
	(arc
		(start 345.076526 -295.145968)
		(mid 345.118075 -294.974546)
		(end 345.233498 -294.841168)
		(width 0.1143)
		(layer "In2.Cu")
		(net "P3E_CPU0_P4_RX_DN<0>")
	)
	(segment
		(start 180.207666 -35.82162)
		(end 183.295036 -38.90899)
		(width 0.12954)
		(layer "F.Cu")
		(net "P2E_CPU0_P5_RX_DP")
	)
	(segment
		(start 161.882836 -11.139424)
		(end 161.584132 -11.861546)
		(width 0.12954)
		(layer "F.Cu")
		(net "P2E_CPU0_P5_RX_DP")
	)
	(segment
		(start 213.7283 -81.594706)
		(end 216.30259 -81.820004)
		(width 0.12954)
		(layer "F.Cu")
		(net "P2E_CPU0_P5_RX_DP")
	)
	(segment
		(start 161.584132 -21.147278)
		(end 162.162998 -24.434038)
		(width 0.12954)
		(layer "F.Cu")
		(net "P2E_CPU0_P5_RX_DP")
	)
	(segment
		(start 191.437514 -77.37094)
		(end 192.088262 -78.29931)
		(width 0.12954)
		(layer "F.Cu")
		(net "P2E_CPU0_P5_RX_DP")
	)
	(segment
		(start 216.30259 -81.820004)
		(end 218.450922 -82.71002)
		(width 0.12954)
		(layer "F.Cu")
		(net "P2E_CPU0_P5_RX_DP")
	)
	(segment
		(start 186.53633 -52.13223)
		(end 188.7982 -56.983122)
		(width 0.12954)
		(layer "F.Cu")
		(net "P2E_CPU0_P5_RX_DP")
	)
	(segment
		(start 167.328342 -12.886944)
		(end 167.328342 -11.14679)
		(width 0.12954)
		(layer "F.Cu")
		(net "P2E_CPU0_P5_RX_DP")
	)
	(segment
		(start 167.6654 -32.298386)
		(end 167.859202 -32.460692)
		(width 0.12954)
		(layer "F.Cu")
		(net "P2E_CPU0_P5_RX_DP")
	)
	(segment
		(start 192.088262 -78.29931)
		(end 195.565776 -80.734154)
		(width 0.12954)
		(layer "F.Cu")
		(net "P2E_CPU0_P5_RX_DP")
	)
	(segment
		(start 191.312038 -62.295278)
		(end 191.22517 -65.814956)
		(width 0.12954)
		(layer "F.Cu")
		(net "P2E_CPU0_P5_RX_DP")
	)
	(segment
		(start 167.328342 -11.14679)
		(end 167.158162 -10.734802)
		(width 0.12954)
		(layer "F.Cu")
		(net "P2E_CPU0_P5_RX_DP")
	)
	(segment
		(start 183.295036 -38.90899)
		(end 185.207656 -42.582846)
		(width 0.12954)
		(layer "F.Cu")
		(net "P2E_CPU0_P5_RX_DP")
	)
	(segment
		(start 178.294792 -34.543492)
		(end 180.207666 -35.82162)
		(width 0.12954)
		(layer "F.Cu")
		(net "P2E_CPU0_P5_RX_DP")
	)
	(segment
		(start 190.368682 -59.225434)
		(end 191.312038 -62.295278)
		(width 0.12954)
		(layer "F.Cu")
		(net "P2E_CPU0_P5_RX_DP")
	)
	(segment
		(start 218.871546 -83.130644)
		(end 218.949778 -83.319112)
		(width 0.12954)
		(layer "F.Cu")
		(net "P2E_CPU0_P5_RX_DP")
	)
	(segment
		(start 173.582076 -34.543492)
		(end 178.294792 -34.543492)
		(width 0.12954)
		(layer "F.Cu")
		(net "P2E_CPU0_P5_RX_DP")
	)
	(segment
		(start 163.244276 -9.778238)
		(end 161.882836 -11.139424)
		(width 0.12954)
		(layer "F.Cu")
		(net "P2E_CPU0_P5_RX_DP")
	)
	(segment
		(start 195.565776 -80.734154)
		(end 198.852028 -81.313782)
		(width 0.12954)
		(layer "F.Cu")
		(net "P2E_CPU0_P5_RX_DP")
	)
	(segment
		(start 191.22517 -65.814956)
		(end 190.608966 -67.514978)
		(width 0.12954)
		(layer "F.Cu")
		(net "P2E_CPU0_P5_RX_DP")
	)
	(segment
		(start 218.949778 -83.319112)
		(end 218.949778 -83.767422)
		(width 0.12954)
		(layer "F.Cu")
		(net "P2E_CPU0_P5_RX_DP")
	)
	(segment
		(start 186.53125 -52.074064)
		(end 186.53633 -52.13223)
		(width 0.12954)
		(layer "F.Cu")
		(net "P2E_CPU0_P5_RX_DP")
	)
	(segment
		(start 163.743386 -9.571482)
		(end 163.244276 -9.778238)
		(width 0.12954)
		(layer "F.Cu")
		(net "P2E_CPU0_P5_RX_DP")
	)
	(segment
		(start 190.608966 -67.514978)
		(end 190.608966 -74.742548)
		(width 0.12954)
		(layer "F.Cu")
		(net "P2E_CPU0_P5_RX_DP")
	)
	(segment
		(start 166.325296 -9.901936)
		(end 165.525958 -9.571482)
		(width 0.12954)
		(layer "F.Cu")
		(net "P2E_CPU0_P5_RX_DP")
	)
	(segment
		(start 190.608966 -74.742548)
		(end 191.437514 -77.37094)
		(width 0.12954)
		(layer "F.Cu")
		(net "P2E_CPU0_P5_RX_DP")
	)
	(segment
		(start 218.949778 -83.767422)
		(end 218.679268 -84.037932)
		(width 0.12954)
		(layer "F.Cu")
		(net "P2E_CPU0_P5_RX_DP")
	)
	(segment
		(start 165.525958 -9.571482)
		(end 163.743386 -9.571482)
		(width 0.12954)
		(layer "F.Cu")
		(net "P2E_CPU0_P5_RX_DP")
	)
	(segment
		(start 167.467026 -13.025628)
		(end 167.328342 -12.886944)
		(width 0.12954)
		(layer "F.Cu")
		(net "P2E_CPU0_P5_RX_DP")
	)
	(segment
		(start 167.467026 -13.599922)
		(end 167.467026 -13.025628)
		(width 0.12954)
		(layer "F.Cu")
		(net "P2E_CPU0_P5_RX_DP")
	)
	(segment
		(start 185.207656 -42.582846)
		(end 186.186318 -48.133254)
		(width 0.12954)
		(layer "F.Cu")
		(net "P2E_CPU0_P5_RX_DP")
	)
	(segment
		(start 186.186318 -48.133254)
		(end 186.53125 -52.074064)
		(width 0.12954)
		(layer "F.Cu")
		(net "P2E_CPU0_P5_RX_DP")
	)
	(segment
		(start 355.487986 -225.310192)
		(end 355.021388 -225.044254)
		(width 0.12954)
		(layer "F.Cu")
		(net "P2E_CPU0_P5_RX_DP")
	)
	(segment
		(start 161.584132 -11.861546)
		(end 161.584132 -21.147278)
		(width 0.12954)
		(layer "F.Cu")
		(net "P2E_CPU0_P5_RX_DP")
	)
	(segment
		(start 218.450922 -82.71002)
		(end 218.871546 -83.130644)
		(width 0.12954)
		(layer "F.Cu")
		(net "P2E_CPU0_P5_RX_DP")
	)
	(segment
		(start 167.859202 -32.460692)
		(end 173.582076 -34.543492)
		(width 0.12954)
		(layer "F.Cu")
		(net "P2E_CPU0_P5_RX_DP")
	)
	(segment
		(start 188.7982 -56.983122)
		(end 190.368682 -59.225434)
		(width 0.12954)
		(layer "F.Cu")
		(net "P2E_CPU0_P5_RX_DP")
	)
	(segment
		(start 162.162998 -24.434038)
		(end 167.6654 -32.298386)
		(width 0.12954)
		(layer "F.Cu")
		(net "P2E_CPU0_P5_RX_DP")
	)
	(segment
		(start 198.852028 -81.313782)
		(end 213.7283 -81.594706)
		(width 0.12954)
		(layer "F.Cu")
		(net "P2E_CPU0_P5_RX_DP")
	)
	(segment
		(start 167.158162 -10.734802)
		(end 166.325296 -9.901936)
		(width 0.12954)
		(layer "F.Cu")
		(net "P2E_CPU0_P5_RX_DP")
	)
	(via
		(at 218.679268 -84.037932)
		(size 0.508)
		(drill 0.254)
		(layers "F.Cu" "B.Cu")
		(net "P2E_CPU0_P5_RX_DP")
	)
	(via
		(at 355.021388 -225.044254)
		(size 0.4064)
		(drill 0.2032)
		(layers "F.Cu" "B.Cu")
		(net "P2E_CPU0_P5_RX_DP")
	)
	(segment
		(start 271.067022 -163.973256)
		(end 290.142168 -174.168816)
		(width 0.12954)
		(layer "B.Cu")
		(net "P2E_CPU0_P5_RX_DP")
	)
	(segment
		(start 352.132392 -214.510366)
		(end 354.71227 -220.739716)
		(width 0.12954)
		(layer "B.Cu")
		(net "P2E_CPU0_P5_RX_DP")
	)
	(segment
		(start 354.818188 -222.117666)
		(end 354.819712 -222.118428)
		(width 0.0762)
		(layer "B.Cu")
		(net "P2E_CPU0_P5_RX_DP")
	)
	(segment
		(start 354.83165 -223.747076)
		(end 354.833682 -223.748092)
		(width 0.0762)
		(layer "B.Cu")
		(net "P2E_CPU0_P5_RX_DP")
	)
	(segment
		(start 354.819712 -222.118428)
		(end 354.820474 -222.118936)
		(width 0.0762)
		(layer "B.Cu")
		(net "P2E_CPU0_P5_RX_DP")
	)
	(segment
		(start 218.949778 -83.767422)
		(end 218.949778 -82.830924)
		(width 0.12954)
		(layer "B.Cu")
		(net "P2E_CPU0_P5_RX_DP")
	)
	(segment
		(start 239.521746 -132.42798)
		(end 271.067022 -163.973256)
		(width 0.12954)
		(layer "B.Cu")
		(net "P2E_CPU0_P5_RX_DP")
	)
	(segment
		(start 354.71227 -221.222316)
		(end 354.64623 -221.288356)
		(width 0.0762)
		(layer "B.Cu")
		(net "P2E_CPU0_P5_RX_DP")
	)
	(segment
		(start 354.820474 -222.118936)
		(end 354.830126 -222.124524)
		(width 0.0762)
		(layer "B.Cu")
		(net "P2E_CPU0_P5_RX_DP")
	)
	(segment
		(start 290.142168 -174.168816)
		(end 312.975244 -181.095396)
		(width 0.12954)
		(layer "B.Cu")
		(net "P2E_CPU0_P5_RX_DP")
	)
	(segment
		(start 354.833936 -223.10725)
		(end 354.800408 -223.126808)
		(width 0.0762)
		(layer "B.Cu")
		(net "P2E_CPU0_P5_RX_DP")
	)
	(segment
		(start 218.949778 -82.830924)
		(end 219.268802 -82.5119)
		(width 0.12954)
		(layer "B.Cu")
		(net "P2E_CPU0_P5_RX_DP")
	)
	(segment
		(start 354.804472 -224.738946)
		(end 354.80371 -224.739454)
		(width 0.0762)
		(layer "B.Cu")
		(net "P2E_CPU0_P5_RX_DP")
	)
	(segment
		(start 326.29094 -188.669168)
		(end 352.132392 -214.510366)
		(width 0.12954)
		(layer "B.Cu")
		(net "P2E_CPU0_P5_RX_DP")
	)
	(segment
		(start 219.268802 -82.5119)
		(end 220.16212 -82.5119)
		(width 0.12954)
		(layer "B.Cu")
		(net "P2E_CPU0_P5_RX_DP")
	)
	(segment
		(start 221.33052 -83.6803)
		(end 221.33052 -88.510618)
		(width 0.12954)
		(layer "B.Cu")
		(net "P2E_CPU0_P5_RX_DP")
	)
	(segment
		(start 354.707698 -225.044254)
		(end 355.021388 -225.044254)
		(width 0.0762)
		(layer "B.Cu")
		(net "P2E_CPU0_P5_RX_DP")
	)
	(segment
		(start 221.33052 -88.510618)
		(end 239.521746 -132.42798)
		(width 0.12954)
		(layer "B.Cu")
		(net "P2E_CPU0_P5_RX_DP")
	)
	(segment
		(start 312.975244 -181.095396)
		(end 319.480438 -184.572656)
		(width 0.12954)
		(layer "B.Cu")
		(net "P2E_CPU0_P5_RX_DP")
	)
	(segment
		(start 218.679268 -84.037932)
		(end 218.949778 -83.767422)
		(width 0.12954)
		(layer "B.Cu")
		(net "P2E_CPU0_P5_RX_DP")
	)
	(segment
		(start 354.651056 -224.987612)
		(end 354.707698 -225.044254)
		(width 0.0762)
		(layer "B.Cu")
		(net "P2E_CPU0_P5_RX_DP")
	)
	(segment
		(start 354.80244 -222.108522)
		(end 354.818188 -222.117666)
		(width 0.0762)
		(layer "B.Cu")
		(net "P2E_CPU0_P5_RX_DP")
	)
	(segment
		(start 326.085454 -188.531754)
		(end 326.29094 -188.669168)
		(width 0.12954)
		(layer "B.Cu")
		(net "P2E_CPU0_P5_RX_DP")
	)
	(segment
		(start 354.71227 -221.203266)
		(end 354.71227 -221.222316)
		(width 0.0762)
		(layer "B.Cu")
		(net "P2E_CPU0_P5_RX_DP")
	)
	(segment
		(start 354.831396 -223.746822)
		(end 354.83165 -223.747076)
		(width 0.0762)
		(layer "B.Cu")
		(net "P2E_CPU0_P5_RX_DP")
	)
	(segment
		(start 220.16212 -82.5119)
		(end 221.33052 -83.6803)
		(width 0.12954)
		(layer "B.Cu")
		(net "P2E_CPU0_P5_RX_DP")
	)
	(segment
		(start 354.871782 -224.69983)
		(end 354.804472 -224.738946)
		(width 0.0762)
		(layer "B.Cu")
		(net "P2E_CPU0_P5_RX_DP")
	)
	(segment
		(start 354.71227 -220.739716)
		(end 354.71227 -221.203266)
		(width 0.12954)
		(layer "B.Cu")
		(net "P2E_CPU0_P5_RX_DP")
	)
	(segment
		(start 354.64623 -221.288356)
		(end 354.64623 -221.80423)
		(width 0.0762)
		(layer "B.Cu")
		(net "P2E_CPU0_P5_RX_DP")
	)
	(segment
		(start 319.480438 -184.572656)
		(end 326.085454 -188.531754)
		(width 0.12954)
		(layer "B.Cu")
		(net "P2E_CPU0_P5_RX_DP")
	)
	(arc
		(start 354.830126 -222.124524)
		(mid 354.881417 -222.157734)
		(end 354.928932 -222.196152)
		(width 0.0762)
		(layer "B.Cu")
		(net "P2E_CPU0_P5_RX_DP")
	)
	(arc
		(start 355.116384 -224.234248)
		(mid 355.051566 -224.497237)
		(end 354.871782 -224.69983)
		(width 0.0762)
		(layer "B.Cu")
		(net "P2E_CPU0_P5_RX_DP")
	)
	(arc
		(start 354.781358 -223.712278)
		(mid 354.805632 -223.730629)
		(end 354.831396 -223.746822)
		(width 0.0762)
		(layer "B.Cu")
		(net "P2E_CPU0_P5_RX_DP")
	)
	(arc
		(start 354.800408 -223.126808)
		(mid 354.768922 -223.148612)
		(end 354.741226 -223.175068)
		(width 0.0762)
		(layer "B.Cu")
		(net "P2E_CPU0_P5_RX_DP")
	)
	(arc
		(start 354.928932 -222.196152)
		(mid 355.113543 -222.67595)
		(end 354.833936 -223.10725)
		(width 0.0762)
		(layer "B.Cu")
		(net "P2E_CPU0_P5_RX_DP")
	)
	(arc
		(start 354.80371 -224.739454)
		(mid 354.702239 -224.848075)
		(end 354.651056 -224.987612)
		(width 0.0762)
		(layer "B.Cu")
		(net "P2E_CPU0_P5_RX_DP")
	)
	(arc
		(start 354.712524 -222.016574)
		(mid 354.753507 -222.066436)
		(end 354.80244 -222.108522)
		(width 0.0762)
		(layer "B.Cu")
		(net "P2E_CPU0_P5_RX_DP")
	)
	(arc
		(start 354.64623 -221.80423)
		(mid 354.66328 -221.915421)
		(end 354.712524 -222.016574)
		(width 0.0762)
		(layer "B.Cu")
		(net "P2E_CPU0_P5_RX_DP")
	)
	(arc
		(start 354.833682 -223.748092)
		(mid 355.040592 -223.953052)
		(end 355.116384 -224.234248)
		(width 0.0762)
		(layer "B.Cu")
		(net "P2E_CPU0_P5_RX_DP")
	)
	(arc
		(start 354.741226 -223.175068)
		(mid 354.647428 -223.452173)
		(end 354.781358 -223.712278)
		(width 0.0762)
		(layer "B.Cu")
		(net "P2E_CPU0_P5_RX_DP")
	)
	(segment
		(start 354.547932 -225.310192)
		(end 354.081334 -225.044254)
		(width 0.12954)
		(layer "F.Cu")
		(net "P2E_CPU0_P5_RX_DN")
	)
	(segment
		(start 219.145104 -82.947764)
		(end 219.272358 -83.25485)
		(width 0.12954)
		(layer "F.Cu")
		(net "P2E_CPU0_P5_RX_DN")
	)
	(segment
		(start 168.022778 -32.17672)
		(end 173.638972 -34.220912)
		(width 0.12954)
		(layer "F.Cu")
		(net "P2E_CPU0_P5_RX_DN")
	)
	(segment
		(start 167.005762 -11.211052)
		(end 166.88435 -10.917682)
		(width 0.12954)
		(layer "F.Cu")
		(net "P2E_CPU0_P5_RX_DN")
	)
	(segment
		(start 192.31991 -78.067662)
		(end 195.692268 -80.428846)
		(width 0.12954)
		(layer "F.Cu")
		(net "P2E_CPU0_P5_RX_DN")
	)
	(segment
		(start 166.867078 -13.599922)
		(end 166.867078 -13.025628)
		(width 0.12954)
		(layer "F.Cu")
		(net "P2E_CPU0_P5_RX_DN")
	)
	(segment
		(start 190.931546 -74.692764)
		(end 191.730376 -77.226414)
		(width 0.12954)
		(layer "F.Cu")
		(net "P2E_CPU0_P5_RX_DN")
	)
	(segment
		(start 162.202368 -22.796754)
		(end 162.26917 -23.176738)
		(width 0.12954)
		(layer "F.Cu")
		(net "P2E_CPU0_P5_RX_DN")
	)
	(segment
		(start 162.094672 -20.094448)
		(end 162.094672 -20.480528)
		(width 0.12954)
		(layer "F.Cu")
		(net "P2E_CPU0_P5_RX_DN")
	)
	(segment
		(start 161.906712 -19.520408)
		(end 161.906712 -19.906488)
		(width 0.12954)
		(layer "F.Cu")
		(net "P2E_CPU0_P5_RX_DN")
	)
	(segment
		(start 161.906712 -15.719552)
		(end 161.906712 -17.610328)
		(width 0.12954)
		(layer "F.Cu")
		(net "P2E_CPU0_P5_RX_DN")
	)
	(segment
		(start 190.662052 -59.081924)
		(end 191.635888 -62.250828)
		(width 0.12954)
		(layer "F.Cu")
		(net "P2E_CPU0_P5_RX_DN")
	)
	(segment
		(start 195.692268 -80.428846)
		(end 198.88327 -80.99171)
		(width 0.12954)
		(layer "F.Cu")
		(net "P2E_CPU0_P5_RX_DN")
	)
	(segment
		(start 161.906712 -18.372328)
		(end 161.906712 -18.758408)
		(width 0.12954)
		(layer "F.Cu")
		(net "P2E_CPU0_P5_RX_DN")
	)
	(segment
		(start 161.906712 -21.119084)
		(end 162.070034 -22.045676)
		(width 0.12954)
		(layer "F.Cu")
		(net "P2E_CPU0_P5_RX_DN")
	)
	(segment
		(start 166.142416 -10.175748)
		(end 165.461696 -9.894062)
		(width 0.12954)
		(layer "F.Cu")
		(net "P2E_CPU0_P5_RX_DN")
	)
	(segment
		(start 163.036758 -24.79167)
		(end 163.258246 -25.108154)
		(width 0.12954)
		(layer "F.Cu")
		(net "P2E_CPU0_P5_RX_DN")
	)
	(segment
		(start 162.156648 -11.322304)
		(end 161.906712 -11.925808)
		(width 0.12954)
		(layer "F.Cu")
		(net "P2E_CPU0_P5_RX_DN")
	)
	(segment
		(start 163.807648 -9.894062)
		(end 163.42741 -10.051542)
		(width 0.12954)
		(layer "F.Cu")
		(net "P2E_CPU0_P5_RX_DN")
	)
	(segment
		(start 161.906712 -17.610328)
		(end 162.094672 -17.798288)
		(width 0.12954)
		(layer "F.Cu")
		(net "P2E_CPU0_P5_RX_DN")
	)
	(segment
		(start 162.094672 -19.332448)
		(end 161.906712 -19.520408)
		(width 0.12954)
		(layer "F.Cu")
		(net "P2E_CPU0_P5_RX_DN")
	)
	(segment
		(start 162.26917 -23.176738)
		(end 162.487102 -23.329138)
		(width 0.12954)
		(layer "F.Cu")
		(net "P2E_CPU0_P5_RX_DN")
	)
	(segment
		(start 198.88327 -80.99171)
		(end 213.745318 -81.27238)
		(width 0.12954)
		(layer "F.Cu")
		(net "P2E_CPU0_P5_RX_DN")
	)
	(segment
		(start 161.906712 -18.758408)
		(end 162.094672 -18.946368)
		(width 0.12954)
		(layer "F.Cu")
		(net "P2E_CPU0_P5_RX_DN")
	)
	(segment
		(start 161.906712 -14.957552)
		(end 162.094672 -15.145512)
		(width 0.12954)
		(layer "F.Cu")
		(net "P2E_CPU0_P5_RX_DN")
	)
	(segment
		(start 162.070034 -22.045676)
		(end 162.06978 -22.04593)
		(width 0.12954)
		(layer "F.Cu")
		(net "P2E_CPU0_P5_RX_DN")
	)
	(segment
		(start 162.554158 -23.70963)
		(end 162.401758 -23.927562)
		(width 0.12954)
		(layer "F.Cu")
		(net "P2E_CPU0_P5_RX_DN")
	)
	(segment
		(start 162.401758 -23.927562)
		(end 162.46856 -24.307546)
		(width 0.12954)
		(layer "F.Cu")
		(net "P2E_CPU0_P5_RX_DN")
	)
	(segment
		(start 163.212018 -25.370028)
		(end 167.90543 -32.078422)
		(width 0.12954)
		(layer "F.Cu")
		(net "P2E_CPU0_P5_RX_DN")
	)
	(segment
		(start 189.07887 -56.82107)
		(end 190.662052 -59.081924)
		(width 0.12954)
		(layer "F.Cu")
		(net "P2E_CPU0_P5_RX_DN")
	)
	(segment
		(start 163.42741 -10.051542)
		(end 162.156648 -11.322304)
		(width 0.12954)
		(layer "F.Cu")
		(net "P2E_CPU0_P5_RX_DN")
	)
	(segment
		(start 218.633802 -82.436462)
		(end 219.145104 -82.947764)
		(width 0.12954)
		(layer "F.Cu")
		(net "P2E_CPU0_P5_RX_DN")
	)
	(segment
		(start 186.506612 -48.09109)
		(end 186.852814 -52.047394)
		(width 0.12954)
		(layer "F.Cu")
		(net "P2E_CPU0_P5_RX_DN")
	)
	(segment
		(start 167.90543 -32.078422)
		(end 168.022778 -32.17672)
		(width 0.12954)
		(layer "F.Cu")
		(net "P2E_CPU0_P5_RX_DN")
	)
	(segment
		(start 191.635888 -62.250828)
		(end 191.54648 -65.875408)
		(width 0.12954)
		(layer "F.Cu")
		(net "P2E_CPU0_P5_RX_DN")
	)
	(segment
		(start 186.852814 -52.047394)
		(end 189.07887 -56.82107)
		(width 0.12954)
		(layer "F.Cu")
		(net "P2E_CPU0_P5_RX_DN")
	)
	(segment
		(start 163.258246 -25.108154)
		(end 163.212018 -25.370028)
		(width 0.12954)
		(layer "F.Cu")
		(net "P2E_CPU0_P5_RX_DN")
	)
	(segment
		(start 161.906712 -19.906488)
		(end 162.094672 -20.094448)
		(width 0.12954)
		(layer "F.Cu")
		(net "P2E_CPU0_P5_RX_DN")
	)
	(segment
		(start 167.005762 -12.886944)
		(end 167.005762 -11.211052)
		(width 0.12954)
		(layer "F.Cu")
		(net "P2E_CPU0_P5_RX_DN")
	)
	(segment
		(start 162.354768 -22.578822)
		(end 162.202368 -22.796754)
		(width 0.12954)
		(layer "F.Cu")
		(net "P2E_CPU0_P5_RX_DN")
	)
	(segment
		(start 162.487102 -23.329138)
		(end 162.554158 -23.70963)
		(width 0.12954)
		(layer "F.Cu")
		(net "P2E_CPU0_P5_RX_DN")
	)
	(segment
		(start 161.906712 -11.925808)
		(end 161.906712 -14.957552)
		(width 0.12954)
		(layer "F.Cu")
		(net "P2E_CPU0_P5_RX_DN")
	)
	(segment
		(start 178.392836 -34.220912)
		(end 180.413406 -35.570922)
		(width 0.12954)
		(layer "F.Cu")
		(net "P2E_CPU0_P5_RX_DN")
	)
	(segment
		(start 162.094672 -18.184368)
		(end 161.906712 -18.372328)
		(width 0.12954)
		(layer "F.Cu")
		(net "P2E_CPU0_P5_RX_DN")
	)
	(segment
		(start 185.516774 -42.477944)
		(end 186.506612 -48.09109)
		(width 0.12954)
		(layer "F.Cu")
		(net "P2E_CPU0_P5_RX_DN")
	)
	(segment
		(start 183.558434 -38.71595)
		(end 185.516774 -42.477944)
		(width 0.12954)
		(layer "F.Cu")
		(net "P2E_CPU0_P5_RX_DN")
	)
	(segment
		(start 162.094672 -15.145512)
		(end 162.094672 -15.531592)
		(width 0.12954)
		(layer "F.Cu")
		(net "P2E_CPU0_P5_RX_DN")
	)
	(segment
		(start 213.745318 -81.27238)
		(end 216.380314 -81.502758)
		(width 0.12954)
		(layer "F.Cu")
		(net "P2E_CPU0_P5_RX_DN")
	)
	(segment
		(start 219.272358 -83.25485)
		(end 219.272358 -83.767422)
		(width 0.12954)
		(layer "F.Cu")
		(net "P2E_CPU0_P5_RX_DN")
	)
	(segment
		(start 162.06978 -22.04593)
		(end 162.287966 -22.19833)
		(width 0.12954)
		(layer "F.Cu")
		(net "P2E_CPU0_P5_RX_DN")
	)
	(segment
		(start 161.906712 -20.668488)
		(end 161.906712 -21.119084)
		(width 0.12954)
		(layer "F.Cu")
		(net "P2E_CPU0_P5_RX_DN")
	)
	(segment
		(start 191.54648 -65.875408)
		(end 190.931546 -67.571874)
		(width 0.12954)
		(layer "F.Cu")
		(net "P2E_CPU0_P5_RX_DN")
	)
	(segment
		(start 162.094672 -18.946368)
		(end 162.094672 -19.332448)
		(width 0.12954)
		(layer "F.Cu")
		(net "P2E_CPU0_P5_RX_DN")
	)
	(segment
		(start 173.638972 -34.220912)
		(end 178.392836 -34.220912)
		(width 0.12954)
		(layer "F.Cu")
		(net "P2E_CPU0_P5_RX_DN")
	)
	(segment
		(start 219.272358 -83.767422)
		(end 219.542868 -84.037932)
		(width 0.12954)
		(layer "F.Cu")
		(net "P2E_CPU0_P5_RX_DN")
	)
	(segment
		(start 162.094672 -15.531592)
		(end 161.906712 -15.719552)
		(width 0.12954)
		(layer "F.Cu")
		(net "P2E_CPU0_P5_RX_DN")
	)
	(segment
		(start 162.46856 -24.307546)
		(end 162.774884 -24.745442)
		(width 0.12954)
		(layer "F.Cu")
		(net "P2E_CPU0_P5_RX_DN")
	)
	(segment
		(start 162.094672 -17.798288)
		(end 162.094672 -18.184368)
		(width 0.12954)
		(layer "F.Cu")
		(net "P2E_CPU0_P5_RX_DN")
	)
	(segment
		(start 166.867078 -13.025628)
		(end 167.005762 -12.886944)
		(width 0.12954)
		(layer "F.Cu")
		(net "P2E_CPU0_P5_RX_DN")
	)
	(segment
		(start 165.461696 -9.894062)
		(end 163.807648 -9.894062)
		(width 0.12954)
		(layer "F.Cu")
		(net "P2E_CPU0_P5_RX_DN")
	)
	(segment
		(start 162.287966 -22.19833)
		(end 162.354768 -22.578822)
		(width 0.12954)
		(layer "F.Cu")
		(net "P2E_CPU0_P5_RX_DN")
	)
	(segment
		(start 190.931546 -67.571874)
		(end 190.931546 -74.692764)
		(width 0.12954)
		(layer "F.Cu")
		(net "P2E_CPU0_P5_RX_DN")
	)
	(segment
		(start 216.380314 -81.502758)
		(end 218.633802 -82.436462)
		(width 0.12954)
		(layer "F.Cu")
		(net "P2E_CPU0_P5_RX_DN")
	)
	(segment
		(start 166.88435 -10.917682)
		(end 166.142416 -10.175748)
		(width 0.12954)
		(layer "F.Cu")
		(net "P2E_CPU0_P5_RX_DN")
	)
	(segment
		(start 191.730376 -77.226414)
		(end 192.31991 -78.067662)
		(width 0.12954)
		(layer "F.Cu")
		(net "P2E_CPU0_P5_RX_DN")
	)
	(segment
		(start 180.413406 -35.570922)
		(end 183.558434 -38.71595)
		(width 0.12954)
		(layer "F.Cu")
		(net "P2E_CPU0_P5_RX_DN")
	)
	(segment
		(start 162.774884 -24.745442)
		(end 163.036758 -24.79167)
		(width 0.12954)
		(layer "F.Cu")
		(net "P2E_CPU0_P5_RX_DN")
	)
	(segment
		(start 162.094672 -20.480528)
		(end 161.906712 -20.668488)
		(width 0.12954)
		(layer "F.Cu")
		(net "P2E_CPU0_P5_RX_DN")
	)
	(via
		(at 219.542868 -84.037932)
		(size 0.508)
		(drill 0.254)
		(layers "F.Cu" "B.Cu")
		(net "P2E_CPU0_P5_RX_DN")
	)
	(via
		(at 354.081334 -225.044254)
		(size 0.4064)
		(drill 0.2032)
		(layers "F.Cu" "B.Cu")
		(net "P2E_CPU0_P5_RX_DN")
	)
	(segment
		(start 221.12986 -89.36736)
		(end 221.277688 -89.72423)
		(width 0.12954)
		(layer "B.Cu")
		(net "P2E_CPU0_P5_RX_DN")
	)
	(segment
		(start 354.38969 -221.203266)
		(end 354.38969 -221.222316)
		(width 0.0762)
		(layer "B.Cu")
		(net "P2E_CPU0_P5_RX_DN")
	)
	(segment
		(start 221.96806 -90.893138)
		(end 222.115634 -91.249246)
		(width 0.12954)
		(layer "B.Cu")
		(net "P2E_CPU0_P5_RX_DN")
	)
	(segment
		(start 219.272358 -82.964782)
		(end 219.40266 -82.83448)
		(width 0.12954)
		(layer "B.Cu")
		(net "P2E_CPU0_P5_RX_DN")
	)
	(segment
		(start 351.85858 -214.693246)
		(end 354.38969 -220.803978)
		(width 0.12954)
		(layer "B.Cu")
		(net "P2E_CPU0_P5_RX_DN")
	)
	(segment
		(start 223.043496 -93.98635)
		(end 223.29267 -94.089474)
		(width 0.12954)
		(layer "B.Cu")
		(net "P2E_CPU0_P5_RX_DN")
	)
	(segment
		(start 354.38969 -220.803978)
		(end 354.38969 -221.203266)
		(width 0.12954)
		(layer "B.Cu")
		(net "P2E_CPU0_P5_RX_DN")
	)
	(segment
		(start 222.895668 -93.62948)
		(end 223.043496 -93.98635)
		(width 0.12954)
		(layer "B.Cu")
		(net "P2E_CPU0_P5_RX_DN")
	)
	(segment
		(start 222.602044 -92.92082)
		(end 222.851218 -93.023944)
		(width 0.12954)
		(layer "B.Cu")
		(net "P2E_CPU0_P5_RX_DN")
	)
	(segment
		(start 222.409258 -91.958668)
		(end 222.557086 -92.31503)
		(width 0.12954)
		(layer "B.Cu")
		(net "P2E_CPU0_P5_RX_DN")
	)
	(segment
		(start 221.674182 -90.183716)
		(end 221.674182 -90.18397)
		(width 0.12954)
		(layer "B.Cu")
		(net "P2E_CPU0_P5_RX_DN")
	)
	(segment
		(start 354.45954 -224.979738)
		(end 354.395024 -225.044254)
		(width 0.0762)
		(layer "B.Cu")
		(net "P2E_CPU0_P5_RX_DN")
	)
	(segment
		(start 326.0852 -188.919866)
		(end 351.85858 -214.693246)
		(width 0.12954)
		(layer "B.Cu")
		(net "P2E_CPU0_P5_RX_DN")
	)
	(segment
		(start 222.115634 -91.2495)
		(end 222.115888 -91.2495)
		(width 0.12954)
		(layer "B.Cu")
		(net "P2E_CPU0_P5_RX_DN")
	)
	(segment
		(start 222.454216 -92.56395)
		(end 222.602044 -92.92082)
		(width 0.12954)
		(layer "B.Cu")
		(net "P2E_CPU0_P5_RX_DN")
	)
	(segment
		(start 223.29267 -94.089474)
		(end 223.292162 -94.089728)
		(width 0.12954)
		(layer "B.Cu")
		(net "P2E_CPU0_P5_RX_DN")
	)
	(segment
		(start 222.409766 -91.958414)
		(end 222.409258 -91.958668)
		(width 0.12954)
		(layer "B.Cu")
		(net "P2E_CPU0_P5_RX_DN")
	)
	(segment
		(start 221.968314 -90.892884)
		(end 221.96806 -90.893138)
		(width 0.12954)
		(layer "B.Cu")
		(net "P2E_CPU0_P5_RX_DN")
	)
	(segment
		(start 221.00794 -85.402928)
		(end 220.87078 -85.540088)
		(width 0.12954)
		(layer "B.Cu")
		(net "P2E_CPU0_P5_RX_DN")
	)
	(segment
		(start 270.872712 -164.235384)
		(end 290.017962 -174.468536)
		(width 0.12954)
		(layer "B.Cu")
		(net "P2E_CPU0_P5_RX_DN")
	)
	(segment
		(start 220.028262 -82.83448)
		(end 221.00794 -83.814158)
		(width 0.12954)
		(layer "B.Cu")
		(net "P2E_CPU0_P5_RX_DN")
	)
	(segment
		(start 222.557086 -92.31503)
		(end 222.55734 -92.31503)
		(width 0.12954)
		(layer "B.Cu")
		(net "P2E_CPU0_P5_RX_DN")
	)
	(segment
		(start 221.277688 -89.72423)
		(end 221.526862 -89.827354)
		(width 0.12954)
		(layer "B.Cu")
		(net "P2E_CPU0_P5_RX_DN")
	)
	(segment
		(start 221.00794 -88.57488)
		(end 221.232984 -89.11844)
		(width 0.12954)
		(layer "B.Cu")
		(net "P2E_CPU0_P5_RX_DN")
	)
	(segment
		(start 221.526862 -89.827354)
		(end 221.526608 -89.827608)
		(width 0.12954)
		(layer "B.Cu")
		(net "P2E_CPU0_P5_RX_DN")
	)
	(segment
		(start 222.851218 -93.023944)
		(end 222.85071 -93.023944)
		(width 0.12954)
		(layer "B.Cu")
		(net "P2E_CPU0_P5_RX_DN")
	)
	(segment
		(start 221.71914 -90.78976)
		(end 221.968314 -90.892884)
		(width 0.12954)
		(layer "B.Cu")
		(net "P2E_CPU0_P5_RX_DN")
	)
	(segment
		(start 290.017962 -174.468536)
		(end 312.851038 -181.395116)
		(width 0.12954)
		(layer "B.Cu")
		(net "P2E_CPU0_P5_RX_DN")
	)
	(segment
		(start 223.292162 -94.089728)
		(end 239.223804 -132.551678)
		(width 0.12954)
		(layer "B.Cu")
		(net "P2E_CPU0_P5_RX_DN")
	)
	(segment
		(start 220.87078 -84.417408)
		(end 220.87078 -84.841588)
		(width 0.12954)
		(layer "B.Cu")
		(net "P2E_CPU0_P5_RX_DN")
	)
	(segment
		(start 354.736908 -223.91243)
		(end 354.73767 -223.912938)
		(width 0.0762)
		(layer "B.Cu")
		(net "P2E_CPU0_P5_RX_DN")
	)
	(segment
		(start 221.674436 -90.18397)
		(end 221.571312 -90.43289)
		(width 0.12954)
		(layer "B.Cu")
		(net "P2E_CPU0_P5_RX_DN")
	)
	(segment
		(start 354.768912 -224.539048)
		(end 354.699316 -224.579688)
		(width 0.0762)
		(layer "B.Cu")
		(net "P2E_CPU0_P5_RX_DN")
	)
	(segment
		(start 221.571312 -90.43289)
		(end 221.71914 -90.78976)
		(width 0.12954)
		(layer "B.Cu")
		(net "P2E_CPU0_P5_RX_DN")
	)
	(segment
		(start 354.38969 -221.222316)
		(end 354.45573 -221.288356)
		(width 0.0762)
		(layer "B.Cu")
		(net "P2E_CPU0_P5_RX_DN")
	)
	(segment
		(start 354.738432 -222.942404)
		(end 354.738178 -222.942404)
		(width 0.0762)
		(layer "B.Cu")
		(net "P2E_CPU0_P5_RX_DN")
	)
	(segment
		(start 222.012764 -91.49842)
		(end 222.160592 -91.85529)
		(width 0.12954)
		(layer "B.Cu")
		(net "P2E_CPU0_P5_RX_DN")
	)
	(segment
		(start 222.115634 -91.249246)
		(end 222.115634 -91.2495)
		(width 0.12954)
		(layer "B.Cu")
		(net "P2E_CPU0_P5_RX_DN")
	)
	(segment
		(start 221.526608 -89.827608)
		(end 221.674182 -90.183716)
		(width 0.12954)
		(layer "B.Cu")
		(net "P2E_CPU0_P5_RX_DN")
	)
	(segment
		(start 221.674182 -90.18397)
		(end 221.674436 -90.18397)
		(width 0.12954)
		(layer "B.Cu")
		(net "P2E_CPU0_P5_RX_DN")
	)
	(segment
		(start 239.223804 -132.551678)
		(end 239.223804 -132.586476)
		(width 0.12954)
		(layer "B.Cu")
		(net "P2E_CPU0_P5_RX_DN")
	)
	(segment
		(start 222.85071 -93.023944)
		(end 222.998284 -93.380814)
		(width 0.12954)
		(layer "B.Cu")
		(net "P2E_CPU0_P5_RX_DN")
	)
	(segment
		(start 221.00794 -86.101428)
		(end 221.00794 -88.57488)
		(width 0.12954)
		(layer "B.Cu")
		(net "P2E_CPU0_P5_RX_DN")
	)
	(segment
		(start 319.32118 -184.85358)
		(end 325.912734 -188.80455)
		(width 0.12954)
		(layer "B.Cu")
		(net "P2E_CPU0_P5_RX_DN")
	)
	(segment
		(start 219.40266 -82.83448)
		(end 220.028262 -82.83448)
		(width 0.12954)
		(layer "B.Cu")
		(net "P2E_CPU0_P5_RX_DN")
	)
	(segment
		(start 221.232984 -89.11844)
		(end 221.12986 -89.36736)
		(width 0.12954)
		(layer "B.Cu")
		(net "P2E_CPU0_P5_RX_DN")
	)
	(segment
		(start 220.87078 -84.841588)
		(end 221.00794 -84.978748)
		(width 0.12954)
		(layer "B.Cu")
		(net "P2E_CPU0_P5_RX_DN")
	)
	(segment
		(start 222.160592 -91.85529)
		(end 222.409766 -91.958414)
		(width 0.12954)
		(layer "B.Cu")
		(net "P2E_CPU0_P5_RX_DN")
	)
	(segment
		(start 354.73767 -223.912938)
		(end 354.74148 -223.91497)
		(width 0.0762)
		(layer "B.Cu")
		(net "P2E_CPU0_P5_RX_DN")
	)
	(segment
		(start 221.00794 -83.814158)
		(end 221.00794 -84.280248)
		(width 0.12954)
		(layer "B.Cu")
		(net "P2E_CPU0_P5_RX_DN")
	)
	(segment
		(start 325.912734 -188.80455)
		(end 326.0852 -188.919866)
		(width 0.12954)
		(layer "B.Cu")
		(net "P2E_CPU0_P5_RX_DN")
	)
	(segment
		(start 239.223804 -132.586476)
		(end 270.872712 -164.235384)
		(width 0.12954)
		(layer "B.Cu")
		(net "P2E_CPU0_P5_RX_DN")
	)
	(segment
		(start 354.45573 -221.288356)
		(end 354.45573 -221.80423)
		(width 0.0762)
		(layer "B.Cu")
		(net "P2E_CPU0_P5_RX_DN")
	)
	(segment
		(start 221.00794 -84.280248)
		(end 220.87078 -84.417408)
		(width 0.12954)
		(layer "B.Cu")
		(net "P2E_CPU0_P5_RX_DN")
	)
	(segment
		(start 221.00794 -84.978748)
		(end 221.00794 -85.402928)
		(width 0.12954)
		(layer "B.Cu")
		(net "P2E_CPU0_P5_RX_DN")
	)
	(segment
		(start 222.998284 -93.380814)
		(end 222.998792 -93.38056)
		(width 0.12954)
		(layer "B.Cu")
		(net "P2E_CPU0_P5_RX_DN")
	)
	(segment
		(start 222.55734 -92.31503)
		(end 222.454216 -92.56395)
		(width 0.12954)
		(layer "B.Cu")
		(net "P2E_CPU0_P5_RX_DN")
	)
	(segment
		(start 354.395024 -225.044254)
		(end 354.081334 -225.044254)
		(width 0.0762)
		(layer "B.Cu")
		(net "P2E_CPU0_P5_RX_DN")
	)
	(segment
		(start 222.115888 -91.2495)
		(end 222.012764 -91.49842)
		(width 0.12954)
		(layer "B.Cu")
		(net "P2E_CPU0_P5_RX_DN")
	)
	(segment
		(start 312.851038 -181.395116)
		(end 319.32118 -184.85358)
		(width 0.12954)
		(layer "B.Cu")
		(net "P2E_CPU0_P5_RX_DN")
	)
	(segment
		(start 222.998792 -93.38056)
		(end 222.895668 -93.62948)
		(width 0.12954)
		(layer "B.Cu")
		(net "P2E_CPU0_P5_RX_DN")
	)
	(segment
		(start 354.738178 -222.942404)
		(end 354.704396 -222.961962)
		(width 0.0762)
		(layer "B.Cu")
		(net "P2E_CPU0_P5_RX_DN")
	)
	(segment
		(start 220.87078 -85.540088)
		(end 220.87078 -85.964268)
		(width 0.12954)
		(layer "B.Cu")
		(net "P2E_CPU0_P5_RX_DN")
	)
	(segment
		(start 219.542868 -84.037932)
		(end 219.272358 -83.767422)
		(width 0.12954)
		(layer "B.Cu")
		(net "P2E_CPU0_P5_RX_DN")
	)
	(segment
		(start 219.272358 -83.767422)
		(end 219.272358 -82.964782)
		(width 0.12954)
		(layer "B.Cu")
		(net "P2E_CPU0_P5_RX_DN")
	)
	(segment
		(start 354.699316 -222.269304)
		(end 354.738432 -222.291656)
		(width 0.0762)
		(layer "B.Cu")
		(net "P2E_CPU0_P5_RX_DN")
	)
	(segment
		(start 220.87078 -85.964268)
		(end 221.00794 -86.101428)
		(width 0.12954)
		(layer "B.Cu")
		(net "P2E_CPU0_P5_RX_DN")
	)
	(arc
		(start 354.631498 -222.213932)
		(mid 354.664334 -222.242932)
		(end 354.699316 -222.269304)
		(width 0.0762)
		(layer "B.Cu")
		(net "P2E_CPU0_P5_RX_DN")
	)
	(arc
		(start 354.801424 -222.337884)
		(mid 354.923838 -222.656207)
		(end 354.738432 -222.942404)
		(width 0.0762)
		(layer "B.Cu")
		(net "P2E_CPU0_P5_RX_DN")
	)
	(arc
		(start 354.462334 -224.958656)
		(mid 354.460838 -224.969184)
		(end 354.45954 -224.979738)
		(width 0.0762)
		(layer "B.Cu")
		(net "P2E_CPU0_P5_RX_DN")
	)
	(arc
		(start 354.704396 -222.961962)
		(mid 354.648281 -223.000979)
		(end 354.598986 -223.048322)
		(width 0.0762)
		(layer "B.Cu")
		(net "P2E_CPU0_P5_RX_DN")
	)
	(arc
		(start 354.598986 -223.048322)
		(mid 354.45744 -223.466358)
		(end 354.659438 -223.858836)
		(width 0.0762)
		(layer "B.Cu")
		(net "P2E_CPU0_P5_RX_DN")
	)
	(arc
		(start 354.45573 -221.80423)
		(mid 354.501541 -222.027123)
		(end 354.631498 -222.213932)
		(width 0.0762)
		(layer "B.Cu")
		(net "P2E_CPU0_P5_RX_DN")
	)
	(arc
		(start 354.659438 -223.858836)
		(mid 354.697011 -223.887313)
		(end 354.736908 -223.91243)
		(width 0.0762)
		(layer "B.Cu")
		(net "P2E_CPU0_P5_RX_DN")
	)
	(arc
		(start 354.699316 -224.579688)
		(mid 354.541786 -224.744759)
		(end 354.462334 -224.958656)
		(width 0.0762)
		(layer "B.Cu")
		(net "P2E_CPU0_P5_RX_DN")
	)
	(arc
		(start 354.925884 -224.234248)
		(mid 354.884335 -224.40567)
		(end 354.768912 -224.539048)
		(width 0.0762)
		(layer "B.Cu")
		(net "P2E_CPU0_P5_RX_DN")
	)
	(arc
		(start 354.74148 -223.91497)
		(mid 354.876488 -224.04989)
		(end 354.925884 -224.234248)
		(width 0.0762)
		(layer "B.Cu")
		(net "P2E_CPU0_P5_RX_DN")
	)
	(arc
		(start 354.738432 -222.291656)
		(mid 354.77109 -222.313187)
		(end 354.801424 -222.337884)
		(width 0.0762)
		(layer "B.Cu")
		(net "P2E_CPU0_P5_RX_DN")
	)
	(segment
		(start 212.14842 -30.646878)
		(end 212.118956 -30.676342)
		(width 0.10668)
		(layer "F.Cu")
		(net "P12V_SCM_ADC_ALERT_R")
	)
	(segment
		(start 212.118956 -30.676342)
		(end 212.118956 -30.830266)
		(width 0.10668)
		(layer "F.Cu")
		(net "P12V_SCM_ADC_ALERT_R")
	)
	(segment
		(start 212.118956 -30.830266)
		(end 211.02193 -31.927292)
		(width 0.10668)
		(layer "F.Cu")
		(net "P12V_SCM_ADC_ALERT_R")
	)
	(segment
		(start 209.422492 -33.372044)
		(end 209.422492 -32.97301)
		(width 0.10668)
		(layer "F.Cu")
		(net "P12V_SCM_ADC_ALERT_R")
	)
	(segment
		(start 213.19744 -30.646878)
		(end 212.14842 -30.646878)
		(width 0.10668)
		(layer "F.Cu")
		(net "P12V_SCM_ADC_ALERT_R")
	)
	(segment
		(start 211.02193 -31.927292)
		(end 210.46821 -31.927292)
		(width 0.10668)
		(layer "F.Cu")
		(net "P12V_SCM_ADC_ALERT_R")
	)
	(segment
		(start 209.422492 -32.97301)
		(end 210.46821 -31.927292)
		(width 0.10668)
		(layer "F.Cu")
		(net "P12V_SCM_ADC_ALERT_R")
	)
	(via
		(at 210.46821 -31.927292)
		(size 0.762)
		(drill 0.381)
		(layers "F.Cu" "B.Cu")
		(net "P12V_SCM_ADC_ALERT_R")
	)
	(segment
		(start 184.322212 -109.852968)
		(end 183.932322 -109.463078)
		(width 0.10668)
		(layer "F.Cu")
		(net "P12V_SCM_ADC_ALERT")
	)
	(segment
		(start 212.118956 -29.266896)
		(end 212.11921 -29.266642)
		(width 0.10668)
		(layer "F.Cu")
		(net "P12V_SCM_ADC_ALERT")
	)
	(segment
		(start 212.118956 -29.876242)
		(end 212.118956 -29.266896)
		(width 0.10668)
		(layer "F.Cu")
		(net "P12V_SCM_ADC_ALERT")
	)
	(via
		(at 183.932322 -109.463078)
		(size 0.4572)
		(drill 0.254)
		(layers "F.Cu" "B.Cu")
		(net "P12V_SCM_ADC_ALERT")
	)
	(via
		(at 166.7764 -15.376398)
		(size 0.508)
		(drill 0.254)
		(layers "F.Cu" "B.Cu")
		(net "P12V_SCM_ADC_ALERT")
	)
	(via
		(at 183.515 -97.323148)
		(size 0.508)
		(drill 0.254)
		(layers "F.Cu" "B.Cu")
		(net "P12V_SCM_ADC_ALERT")
	)
	(via
		(at 212.11921 -29.266642)
		(size 0.508)
		(drill 0.254)
		(layers "F.Cu" "B.Cu")
		(net "P12V_SCM_ADC_ALERT")
	)
	(segment
		(start 183.515 -97.323148)
		(end 183.811672 -97.323148)
		(width 0.11684)
		(layer "In4.Cu")
		(net "P12V_SCM_ADC_ALERT")
	)
	(segment
		(start 184.307988 -99.770692)
		(end 183.8706 -100.20808)
		(width 0.11684)
		(layer "In4.Cu")
		(net "P12V_SCM_ADC_ALERT")
	)
	(segment
		(start 184.335928 -109.148372)
		(end 184.021222 -109.463078)
		(width 0.11684)
		(layer "In4.Cu")
		(net "P12V_SCM_ADC_ALERT")
	)
	(segment
		(start 183.8706 -100.20808)
		(end 183.8706 -103.261668)
		(width 0.11684)
		(layer "In4.Cu")
		(net "P12V_SCM_ADC_ALERT")
	)
	(segment
		(start 183.8706 -103.261668)
		(end 184.335928 -103.726996)
		(width 0.11684)
		(layer "In4.Cu")
		(net "P12V_SCM_ADC_ALERT")
	)
	(segment
		(start 184.335928 -103.726996)
		(end 184.335928 -109.148372)
		(width 0.11684)
		(layer "In4.Cu")
		(net "P12V_SCM_ADC_ALERT")
	)
	(segment
		(start 183.811672 -97.323148)
		(end 184.307988 -97.819464)
		(width 0.11684)
		(layer "In4.Cu")
		(net "P12V_SCM_ADC_ALERT")
	)
	(segment
		(start 184.307988 -97.819464)
		(end 184.307988 -99.770692)
		(width 0.11684)
		(layer "In4.Cu")
		(net "P12V_SCM_ADC_ALERT")
	)
	(segment
		(start 184.021222 -109.463078)
		(end 183.932322 -109.463078)
		(width 0.11684)
		(layer "In4.Cu")
		(net "P12V_SCM_ADC_ALERT")
	)
	(segment
		(start 193.06286 -26.035)
		(end 193.06286 -22.91588)
		(width 0.11684)
		(layer "In6.Cu")
		(net "P12V_SCM_ADC_ALERT")
	)
	(segment
		(start 204.427582 -33.553908)
		(end 193.469006 -33.553908)
		(width 0.11684)
		(layer "In6.Cu")
		(net "P12V_SCM_ADC_ALERT")
	)
	(segment
		(start 187.636658 -17.489678)
		(end 186.56808 -17.489678)
		(width 0.11684)
		(layer "In6.Cu")
		(net "P12V_SCM_ADC_ALERT")
	)
	(segment
		(start 193.06286 -29.56814)
		(end 193.06286 -27.96286)
		(width 0.11684)
		(layer "In6.Cu")
		(net "P12V_SCM_ADC_ALERT")
	)
	(segment
		(start 193.06286 -27.96286)
		(end 192.532 -27.432)
		(width 0.11684)
		(layer "In6.Cu")
		(net "P12V_SCM_ADC_ALERT")
	)
	(segment
		(start 167.03802 -16.490188)
		(end 166.7764 -16.228568)
		(width 0.11684)
		(layer "In6.Cu")
		(net "P12V_SCM_ADC_ALERT")
	)
	(segment
		(start 193.06286 -22.91588)
		(end 187.636658 -17.489678)
		(width 0.11684)
		(layer "In6.Cu")
		(net "P12V_SCM_ADC_ALERT")
	)
	(segment
		(start 212.11921 -29.266642)
		(end 211.148168 -30.237684)
		(width 0.11684)
		(layer "In6.Cu")
		(net "P12V_SCM_ADC_ALERT")
	)
	(segment
		(start 171.04106 -16.490188)
		(end 167.03802 -16.490188)
		(width 0.11684)
		(layer "In6.Cu")
		(net "P12V_SCM_ADC_ALERT")
	)
	(segment
		(start 211.148168 -30.237684)
		(end 207.743806 -30.237684)
		(width 0.11684)
		(layer "In6.Cu")
		(net "P12V_SCM_ADC_ALERT")
	)
	(segment
		(start 207.743806 -30.237684)
		(end 204.427582 -33.553908)
		(width 0.11684)
		(layer "In6.Cu")
		(net "P12V_SCM_ADC_ALERT")
	)
	(segment
		(start 192.532 -27.432)
		(end 192.532 -26.56586)
		(width 0.11684)
		(layer "In6.Cu")
		(net "P12V_SCM_ADC_ALERT")
	)
	(segment
		(start 166.7764 -16.228568)
		(end 166.7764 -15.376398)
		(width 0.11684)
		(layer "In6.Cu")
		(net "P12V_SCM_ADC_ALERT")
	)
	(segment
		(start 192.47104 -32.555942)
		(end 192.47104 -30.15996)
		(width 0.11684)
		(layer "In6.Cu")
		(net "P12V_SCM_ADC_ALERT")
	)
	(segment
		(start 192.532 -26.56586)
		(end 193.06286 -26.035)
		(width 0.11684)
		(layer "In6.Cu")
		(net "P12V_SCM_ADC_ALERT")
	)
	(segment
		(start 185.639964 -16.561562)
		(end 171.112434 -16.561562)
		(width 0.11684)
		(layer "In6.Cu")
		(net "P12V_SCM_ADC_ALERT")
	)
	(segment
		(start 192.47104 -30.15996)
		(end 193.06286 -29.56814)
		(width 0.11684)
		(layer "In6.Cu")
		(net "P12V_SCM_ADC_ALERT")
	)
	(segment
		(start 171.112434 -16.561562)
		(end 171.04106 -16.490188)
		(width 0.11684)
		(layer "In6.Cu")
		(net "P12V_SCM_ADC_ALERT")
	)
	(segment
		(start 193.469006 -33.553908)
		(end 192.47104 -32.555942)
		(width 0.11684)
		(layer "In6.Cu")
		(net "P12V_SCM_ADC_ALERT")
	)
	(segment
		(start 186.56808 -17.489678)
		(end 185.639964 -16.561562)
		(width 0.11684)
		(layer "In6.Cu")
		(net "P12V_SCM_ADC_ALERT")
	)
	(segment
		(start 184.65546 -94.595188)
		(end 184.28462 -94.224348)
		(width 0.11684)
		(layer "In11.Cu")
		(net "P12V_SCM_ADC_ALERT")
	)
	(segment
		(start 184.15762 -91.056714)
		(end 181.926484 -91.056714)
		(width 0.11684)
		(layer "In11.Cu")
		(net "P12V_SCM_ADC_ALERT")
	)
	(segment
		(start 170.343322 -78.07833)
		(end 170.343322 -50.918618)
		(width 0.11684)
		(layer "In11.Cu")
		(net "P12V_SCM_ADC_ALERT")
	)
	(segment
		(start 166.267638 -20.104354)
		(end 166.267638 -15.88516)
		(width 0.11684)
		(layer "In11.Cu")
		(net "P12V_SCM_ADC_ALERT")
	)
	(segment
		(start 169.878248 -37.463476)
		(end 169.878248 -23.714964)
		(width 0.11684)
		(layer "In11.Cu")
		(net "P12V_SCM_ADC_ALERT")
	)
	(segment
		(start 171.704762 -39.28999)
		(end 169.878248 -37.463476)
		(width 0.11684)
		(layer "In11.Cu")
		(net "P12V_SCM_ADC_ALERT")
	)
	(segment
		(start 179.824126 -88.954356)
		(end 179.824126 -87.002874)
		(width 0.11684)
		(layer "In11.Cu")
		(net "P12V_SCM_ADC_ALERT")
	)
	(segment
		(start 176.214786 -83.393534)
		(end 175.658526 -83.393534)
		(width 0.11684)
		(layer "In11.Cu")
		(net "P12V_SCM_ADC_ALERT")
	)
	(segment
		(start 184.28462 -94.224348)
		(end 184.28462 -91.183714)
		(width 0.11684)
		(layer "In11.Cu")
		(net "P12V_SCM_ADC_ALERT")
	)
	(segment
		(start 184.28462 -91.183714)
		(end 184.15762 -91.056714)
		(width 0.11684)
		(layer "In11.Cu")
		(net "P12V_SCM_ADC_ALERT")
	)
	(segment
		(start 175.658526 -83.393534)
		(end 170.343322 -78.07833)
		(width 0.11684)
		(layer "In11.Cu")
		(net "P12V_SCM_ADC_ALERT")
	)
	(segment
		(start 169.878248 -23.714964)
		(end 166.267638 -20.104354)
		(width 0.11684)
		(layer "In11.Cu")
		(net "P12V_SCM_ADC_ALERT")
	)
	(segment
		(start 184.65546 -96.182688)
		(end 184.65546 -94.595188)
		(width 0.11684)
		(layer "In11.Cu")
		(net "P12V_SCM_ADC_ALERT")
	)
	(segment
		(start 179.824126 -87.002874)
		(end 176.214786 -83.393534)
		(width 0.11684)
		(layer "In11.Cu")
		(net "P12V_SCM_ADC_ALERT")
	)
	(segment
		(start 181.926484 -91.056714)
		(end 179.824126 -88.954356)
		(width 0.11684)
		(layer "In11.Cu")
		(net "P12V_SCM_ADC_ALERT")
	)
	(segment
		(start 170.343322 -50.918618)
		(end 171.704762 -49.557178)
		(width 0.11684)
		(layer "In11.Cu")
		(net "P12V_SCM_ADC_ALERT")
	)
	(segment
		(start 171.704762 -49.557178)
		(end 171.704762 -39.28999)
		(width 0.11684)
		(layer "In11.Cu")
		(net "P12V_SCM_ADC_ALERT")
	)
	(segment
		(start 183.515 -97.323148)
		(end 184.65546 -96.182688)
		(width 0.11684)
		(layer "In11.Cu")
		(net "P12V_SCM_ADC_ALERT")
	)
	(segment
		(start 166.267638 -15.88516)
		(end 166.7764 -15.376398)
		(width 0.11684)
		(layer "In11.Cu")
		(net "P12V_SCM_ADC_ALERT")
	)
	(segment
		(start 212.0265 -142.582138)
		(end 212.0265 -143.801338)
		(width 0.10668)
		(layer "F.Cu")
		(net "P12V_AUX_BLEEDING")
	)
	(segment
		(start 212.0265 -142.582138)
		(end 210.622134 -142.582138)
		(width 0.10668)
		(layer "F.Cu")
		(net "P12V_AUX_BLEEDING")
	)
	(via
		(at 212.0265 -142.582138)
		(size 0.762)
		(drill 0.381)
		(layers "F.Cu" "B.Cu")
		(net "P12V_AUX_BLEEDING")
	)
	(segment
		(start 69.480684 -37.389562)
		(end 69.862446 -37.771324)
		(width 0.10668)
		(layer "F.Cu")
		(net "OCP_V3_2_P3V3_ADC_ALERT_R")
	)
	(segment
		(start 68.61175 -36.294568)
		(end 68.61175 -37.3888)
		(width 0.10668)
		(layer "F.Cu")
		(net "OCP_V3_2_P3V3_ADC_ALERT_R")
	)
	(segment
		(start 70.882764 -39.070026)
		(end 69.862446 -38.049708)
		(width 0.10668)
		(layer "F.Cu")
		(net "OCP_V3_2_P3V3_ADC_ALERT_R")
	)
	(segment
		(start 68.61175 -37.3888)
		(end 68.612512 -37.389562)
		(width 0.10668)
		(layer "F.Cu")
		(net "OCP_V3_2_P3V3_ADC_ALERT_R")
	)
	(segment
		(start 68.612512 -37.389562)
		(end 69.480684 -37.389562)
		(width 0.10668)
		(layer "F.Cu")
		(net "OCP_V3_2_P3V3_ADC_ALERT_R")
	)
	(segment
		(start 71.308214 -39.070026)
		(end 70.882764 -39.070026)
		(width 0.10668)
		(layer "F.Cu")
		(net "OCP_V3_2_P3V3_ADC_ALERT_R")
	)
	(segment
		(start 69.862446 -38.049708)
		(end 69.862446 -37.771324)
		(width 0.10668)
		(layer "F.Cu")
		(net "OCP_V3_2_P3V3_ADC_ALERT_R")
	)
	(via
		(at 69.862446 -37.771324)
		(size 0.762)
		(drill 0.381)
		(layers "F.Cu" "B.Cu")
		(net "OCP_V3_2_P3V3_ADC_ALERT_R")
	)
	(segment
		(start 444.79083 -94.964758)
		(end 444.79083 -94.602808)
		(width 0.10668)
		(layer "F.Cu")
		(net "OCP_SFF_P3V3_ADC_ALERT_R")
	)
	(segment
		(start 442.489844 -94.327472)
		(end 443.03696 -94.874588)
		(width 0.10668)
		(layer "F.Cu")
		(net "OCP_SFF_P3V3_ADC_ALERT_R")
	)
	(segment
		(start 443.73292 -94.602808)
		(end 443.46114 -94.874588)
		(width 0.10668)
		(layer "F.Cu")
		(net "OCP_SFF_P3V3_ADC_ALERT_R")
	)
	(segment
		(start 448.21983 -94.602808)
		(end 448.112134 -94.602808)
		(width 0.10668)
		(layer "F.Cu")
		(net "OCP_SFF_P3V3_ADC_ALERT_R")
	)
	(segment
		(start 443.03696 -94.874588)
		(end 443.46114 -94.874588)
		(width 0.10668)
		(layer "F.Cu")
		(net "OCP_SFF_P3V3_ADC_ALERT_R")
	)
	(segment
		(start 445.06388 -95.237808)
		(end 444.79083 -94.964758)
		(width 0.10668)
		(layer "F.Cu")
		(net "OCP_SFF_P3V3_ADC_ALERT_R")
	)
	(segment
		(start 447.477134 -95.237808)
		(end 445.06388 -95.237808)
		(width 0.10668)
		(layer "F.Cu")
		(net "OCP_SFF_P3V3_ADC_ALERT_R")
	)
	(segment
		(start 442.088016 -94.327472)
		(end 442.489844 -94.327472)
		(width 0.10668)
		(layer "F.Cu")
		(net "OCP_SFF_P3V3_ADC_ALERT_R")
	)
	(segment
		(start 448.112134 -94.602808)
		(end 447.477134 -95.237808)
		(width 0.10668)
		(layer "F.Cu")
		(net "OCP_SFF_P3V3_ADC_ALERT_R")
	)
	(segment
		(start 444.79083 -94.602808)
		(end 443.73292 -94.602808)
		(width 0.10668)
		(layer "F.Cu")
		(net "OCP_SFF_P3V3_ADC_ALERT_R")
	)
	(via
		(at 443.46114 -94.874588)
		(size 0.762)
		(drill 0.381)
		(layers "F.Cu" "B.Cu")
		(net "OCP_SFF_P3V3_ADC_ALERT_R")
	)
	(segment
		(start 18.15592 -101.458268)
		(end 18.15592 -100.597208)
		(width 0.10668)
		(layer "F.Cu")
		(net "NC_USB_HUB_SDA")
	)
	(segment
		(start 17.195038 -99.636326)
		(end 16.477488 -99.636326)
		(width 0.10668)
		(layer "F.Cu")
		(net "NC_USB_HUB_SDA")
	)
	(segment
		(start 18.15592 -100.597208)
		(end 17.195038 -99.636326)
		(width 0.10668)
		(layer "F.Cu")
		(net "NC_USB_HUB_SDA")
	)
	(via
		(at 18.15592 -101.458268)
		(size 0.762)
		(drill 0.381)
		(layers "F.Cu" "B.Cu")
		(net "NC_USB_HUB_SDA")
	)
	(segment
		(start 13.064998 -96.392746)
		(end 13.064998 -96.723962)
		(width 0.10668)
		(layer "F.Cu")
		(net "NC_USB_HUB_DP4")
	)
	(segment
		(start 12.0142 -95.976948)
		(end 12.6492 -95.976948)
		(width 0.10668)
		(layer "F.Cu")
		(net "NC_USB_HUB_DP4")
	)
	(segment
		(start 12.6492 -95.976948)
		(end 13.064998 -96.392746)
		(width 0.10668)
		(layer "F.Cu")
		(net "NC_USB_HUB_DP4")
	)
	(segment
		(start 11.3538 -95.316548)
		(end 12.0142 -95.976948)
		(width 0.10668)
		(layer "F.Cu")
		(net "NC_USB_HUB_DP4")
	)
	(via
		(at 11.3538 -95.316548)
		(size 0.762)
		(drill 0.381)
		(layers "F.Cu" "B.Cu")
		(net "NC_USB_HUB_DP4")
	)
	(segment
		(start 12.564872 -101.957886)
		(end 12.564872 -101.548946)
		(width 0.10668)
		(layer "F.Cu")
		(net "NC_USB_HUB_DP2")
	)
	(segment
		(start 11.402822 -102.131622)
		(end 12.391136 -102.131622)
		(width 0.10668)
		(layer "F.Cu")
		(net "NC_USB_HUB_DP2")
	)
	(segment
		(start 12.391136 -102.131622)
		(end 12.564872 -101.957886)
		(width 0.10668)
		(layer "F.Cu")
		(net "NC_USB_HUB_DP2")
	)
	(segment
		(start 9.8552 -103.266748)
		(end 10.267696 -103.266748)
		(width 0.10668)
		(layer "F.Cu")
		(net "NC_USB_HUB_DP2")
	)
	(segment
		(start 10.267696 -103.266748)
		(end 11.402822 -102.131622)
		(width 0.10668)
		(layer "F.Cu")
		(net "NC_USB_HUB_DP2")
	)
	(via
		(at 9.8552 -103.266748)
		(size 0.762)
		(drill 0.381)
		(layers "F.Cu" "B.Cu")
		(net "NC_USB_HUB_DP2")
	)
	(segment
		(start 10.0584 -96.154748)
		(end 10.2616 -96.357948)
		(width 0.10668)
		(layer "F.Cu")
		(net "NC_USB_HUB_DM4")
	)
	(segment
		(start 12.445746 -96.357948)
		(end 12.564872 -96.477074)
		(width 0.10668)
		(layer "F.Cu")
		(net "NC_USB_HUB_DM4")
	)
	(segment
		(start 10.2616 -96.357948)
		(end 12.445746 -96.357948)
		(width 0.10668)
		(layer "F.Cu")
		(net "NC_USB_HUB_DM4")
	)
	(segment
		(start 12.564872 -96.477074)
		(end 12.564872 -96.723962)
		(width 0.10668)
		(layer "F.Cu")
		(net "NC_USB_HUB_DM4")
	)
	(via
		(at 10.0584 -96.154748)
		(size 0.762)
		(drill 0.381)
		(layers "F.Cu" "B.Cu")
		(net "NC_USB_HUB_DM4")
	)
	(segment
		(start 11.2268 -103.342948)
		(end 11.938 -102.631748)
		(width 0.10668)
		(layer "F.Cu")
		(net "NC_USB_HUB_DM2")
	)
	(segment
		(start 12.5984 -102.631748)
		(end 13.064998 -102.16515)
		(width 0.10668)
		(layer "F.Cu")
		(net "NC_USB_HUB_DM2")
	)
	(segment
		(start 11.2268 -103.569262)
		(end 11.2268 -103.342948)
		(width 0.10668)
		(layer "F.Cu")
		(net "NC_USB_HUB_DM2")
	)
	(segment
		(start 11.938 -102.631748)
		(end 12.5984 -102.631748)
		(width 0.10668)
		(layer "F.Cu")
		(net "NC_USB_HUB_DM2")
	)
	(segment
		(start 11.128756 -103.667306)
		(end 11.2268 -103.569262)
		(width 0.10668)
		(layer "F.Cu")
		(net "NC_USB_HUB_DM2")
	)
	(segment
		(start 13.064998 -102.16515)
		(end 13.064998 -101.548946)
		(width 0.10668)
		(layer "F.Cu")
		(net "NC_USB_HUB_DM2")
	)
	(via
		(at 11.128756 -103.667306)
		(size 0.762)
		(drill 0.381)
		(layers "F.Cu" "B.Cu")
		(net "NC_USB_HUB_DM2")
	)
	(segment
		(start 207.346296 -34.02203)
		(end 207.772508 -34.02203)
		(width 0.10668)
		(layer "F.Cu")
		(net "NC_INA230_5_NC5")
	)
	(segment
		(start 205.902814 -32.578548)
		(end 207.346296 -34.02203)
		(width 0.10668)
		(layer "F.Cu")
		(net "NC_INA230_5_NC5")
	)
	(via
		(at 205.902814 -32.578548)
		(size 0.762)
		(drill 0.381)
		(layers "F.Cu" "B.Cu")
		(net "NC_INA230_5_NC5")
	)
	(segment
		(start 205.945994 -34.323528)
		(end 206.144622 -34.522156)
		(width 0.10668)
		(layer "F.Cu")
		(net "NC_INA230_5_NC4")
	)
	(segment
		(start 206.144622 -34.522156)
		(end 207.772508 -34.522156)
		(width 0.10668)
		(layer "F.Cu")
		(net "NC_INA230_5_NC4")
	)
	(via
		(at 205.945994 -34.323528)
		(size 0.762)
		(drill 0.381)
		(layers "F.Cu" "B.Cu")
		(net "NC_INA230_5_NC4")
	)
	(segment
		(start 205.862174 -36.007548)
		(end 205.862174 -35.707828)
		(width 0.10668)
		(layer "F.Cu")
		(net "NC_INA230_5_NC3")
	)
	(segment
		(start 206.547974 -35.022028)
		(end 207.772508 -35.022028)
		(width 0.10668)
		(layer "F.Cu")
		(net "NC_INA230_5_NC3")
	)
	(segment
		(start 205.862174 -35.707828)
		(end 206.547974 -35.022028)
		(width 0.10668)
		(layer "F.Cu")
		(net "NC_INA230_5_NC3")
	)
	(via
		(at 205.862174 -36.007548)
		(size 0.762)
		(drill 0.381)
		(layers "F.Cu" "B.Cu")
		(net "NC_INA230_5_NC3")
	)
	(segment
		(start 210.752436 -35.522154)
		(end 210.881722 -35.65144)
		(width 0.10668)
		(layer "F.Cu")
		(net "NC_INA230_5_NC2")
	)
	(segment
		(start 210.881722 -36.279836)
		(end 211.663534 -37.061648)
		(width 0.10668)
		(layer "F.Cu")
		(net "NC_INA230_5_NC2")
	)
	(segment
		(start 210.572604 -35.522154)
		(end 210.752436 -35.522154)
		(width 0.10668)
		(layer "F.Cu")
		(net "NC_INA230_5_NC2")
	)
	(segment
		(start 210.881722 -35.65144)
		(end 210.881722 -36.279836)
		(width 0.10668)
		(layer "F.Cu")
		(net "NC_INA230_5_NC2")
	)
	(via
		(at 211.663534 -37.061648)
		(size 0.762)
		(drill 0.381)
		(layers "F.Cu" "B.Cu")
		(net "NC_INA230_5_NC2")
	)
	(segment
		(start 210.572604 -35.022028)
		(end 210.907376 -35.022028)
		(width 0.10668)
		(layer "F.Cu")
		(net "NC_INA230_5_NC1")
	)
	(segment
		(start 212.037676 -36.152328)
		(end 212.280754 -36.152328)
		(width 0.10668)
		(layer "F.Cu")
		(net "NC_INA230_5_NC1")
	)
	(segment
		(start 210.907376 -35.022028)
		(end 212.037676 -36.152328)
		(width 0.10668)
		(layer "F.Cu")
		(net "NC_INA230_5_NC1")
	)
	(segment
		(start 212.280754 -36.152328)
		(end 213.223094 -37.094668)
		(width 0.10668)
		(layer "F.Cu")
		(net "NC_INA230_5_NC1")
	)
	(via
		(at 213.223094 -37.094668)
		(size 0.762)
		(drill 0.381)
		(layers "F.Cu" "B.Cu")
		(net "NC_INA230_5_NC1")
	)
	(segment
		(start 213.49462 -35.458654)
		(end 214.932514 -36.896548)
		(width 0.10668)
		(layer "F.Cu")
		(net "NC_INA230_5_NC0")
	)
	(segment
		(start 210.572604 -34.522156)
		(end 210.975956 -34.522156)
		(width 0.10668)
		(layer "F.Cu")
		(net "NC_INA230_5_NC0")
	)
	(segment
		(start 211.912454 -35.458654)
		(end 213.49462 -35.458654)
		(width 0.10668)
		(layer "F.Cu")
		(net "NC_INA230_5_NC0")
	)
	(segment
		(start 210.975956 -34.522156)
		(end 211.912454 -35.458654)
		(width 0.10668)
		(layer "F.Cu")
		(net "NC_INA230_5_NC0")
	)
	(via
		(at 214.932514 -36.896548)
		(size 0.762)
		(drill 0.381)
		(layers "F.Cu" "B.Cu")
		(net "NC_INA230_5_NC0")
	)
	(segment
		(start 153.777442 -59.136534)
		(end 154.248104 -58.665872)
		(width 0.10668)
		(layer "F.Cu")
		(net "NC_INA230_4_NC5")
	)
	(segment
		(start 152.525476 -59.136534)
		(end 153.777442 -59.136534)
		(width 0.10668)
		(layer "F.Cu")
		(net "NC_INA230_4_NC5")
	)
	(segment
		(start 154.248104 -58.665872)
		(end 154.248104 -58.518806)
		(width 0.10668)
		(layer "F.Cu")
		(net "NC_INA230_4_NC5")
	)
	(via
		(at 152.525476 -59.136534)
		(size 0.762)
		(drill 0.381)
		(layers "F.Cu" "B.Cu")
		(net "NC_INA230_4_NC5")
	)
	(segment
		(start 154.74823 -58.73496)
		(end 153.663396 -59.819794)
		(width 0.10668)
		(layer "F.Cu")
		(net "NC_INA230_4_NC4")
	)
	(segment
		(start 154.74823 -58.518806)
		(end 154.74823 -58.73496)
		(width 0.10668)
		(layer "F.Cu")
		(net "NC_INA230_4_NC4")
	)
	(via
		(at 153.663396 -59.819794)
		(size 0.762)
		(drill 0.381)
		(layers "F.Cu" "B.Cu")
		(net "NC_INA230_4_NC4")
	)
	(segment
		(start 155.248102 -58.518806)
		(end 155.248102 -59.555888)
		(width 0.10668)
		(layer "F.Cu")
		(net "NC_INA230_4_NC3")
	)
	(segment
		(start 155.248102 -59.555888)
		(end 155.017216 -59.786774)
		(width 0.10668)
		(layer "F.Cu")
		(net "NC_INA230_4_NC3")
	)
	(via
		(at 155.017216 -59.786774)
		(size 0.762)
		(drill 0.381)
		(layers "F.Cu" "B.Cu")
		(net "NC_INA230_4_NC3")
	)
	(segment
		(start 155.748228 -55.506366)
		(end 155.748228 -55.71871)
		(width 0.10668)
		(layer "F.Cu")
		(net "NC_INA230_4_NC2")
	)
	(segment
		(start 156.3497 -54.904894)
		(end 155.748228 -55.506366)
		(width 0.10668)
		(layer "F.Cu")
		(net "NC_INA230_4_NC2")
	)
	(segment
		(start 157.66669 -54.652926)
		(end 157.414722 -54.904894)
		(width 0.10668)
		(layer "F.Cu")
		(net "NC_INA230_4_NC2")
	)
	(segment
		(start 157.414722 -54.904894)
		(end 156.3497 -54.904894)
		(width 0.10668)
		(layer "F.Cu")
		(net "NC_INA230_4_NC2")
	)
	(via
		(at 157.66669 -54.652926)
		(size 0.762)
		(drill 0.381)
		(layers "F.Cu" "B.Cu")
		(net "NC_INA230_4_NC2")
	)
	(segment
		(start 155.248102 -55.377588)
		(end 156.533596 -54.092094)
		(width 0.10668)
		(layer "F.Cu")
		(net "NC_INA230_4_NC1")
	)
	(segment
		(start 155.248102 -55.71871)
		(end 155.248102 -55.377588)
		(width 0.10668)
		(layer "F.Cu")
		(net "NC_INA230_4_NC1")
	)
	(via
		(at 156.533596 -54.092094)
		(size 0.762)
		(drill 0.381)
		(layers "F.Cu" "B.Cu")
		(net "NC_INA230_4_NC1")
	)
	(segment
		(start 154.74823 -54.83606)
		(end 155.212796 -54.371494)
		(width 0.10668)
		(layer "F.Cu")
		(net "NC_INA230_4_NC0")
	)
	(segment
		(start 154.74823 -55.71871)
		(end 154.74823 -54.83606)
		(width 0.10668)
		(layer "F.Cu")
		(net "NC_INA230_4_NC0")
	)
	(via
		(at 155.212796 -54.371494)
		(size 0.762)
		(drill 0.381)
		(layers "F.Cu" "B.Cu")
		(net "NC_INA230_4_NC0")
	)
	(segment
		(start 71.9582 -41.222168)
		(end 71.245984 -41.934384)
		(width 0.10668)
		(layer "F.Cu")
		(net "NC_INA230_3_NC5")
	)
	(segment
		(start 71.9582 -40.72001)
		(end 71.9582 -41.222168)
		(width 0.10668)
		(layer "F.Cu")
		(net "NC_INA230_3_NC5")
	)
	(segment
		(start 71.245984 -41.934384)
		(end 70.789038 -41.934384)
		(width 0.10668)
		(layer "F.Cu")
		(net "NC_INA230_3_NC5")
	)
	(via
		(at 70.789038 -41.934384)
		(size 0.762)
		(drill 0.381)
		(layers "F.Cu" "B.Cu")
		(net "NC_INA230_3_NC5")
	)
	(segment
		(start 72.458326 -42.606214)
		(end 72.38746 -42.67708)
		(width 0.10668)
		(layer "F.Cu")
		(net "NC_INA230_3_NC4")
	)
	(segment
		(start 72.458326 -40.72001)
		(end 72.458326 -42.606214)
		(width 0.10668)
		(layer "F.Cu")
		(net "NC_INA230_3_NC4")
	)
	(via
		(at 72.38746 -42.67708)
		(size 0.762)
		(drill 0.381)
		(layers "F.Cu" "B.Cu")
		(net "NC_INA230_3_NC4")
	)
	(segment
		(start 72.958198 -42.285158)
		(end 73.87336 -43.20032)
		(width 0.10668)
		(layer "F.Cu")
		(net "NC_INA230_3_NC3")
	)
	(segment
		(start 72.958198 -40.72001)
		(end 72.958198 -42.285158)
		(width 0.10668)
		(layer "F.Cu")
		(net "NC_INA230_3_NC3")
	)
	(via
		(at 73.87336 -43.20032)
		(size 0.762)
		(drill 0.381)
		(layers "F.Cu" "B.Cu")
		(net "NC_INA230_3_NC3")
	)
	(segment
		(start 73.458324 -37.665152)
		(end 73.860152 -37.263324)
		(width 0.10668)
		(layer "F.Cu")
		(net "NC_INA230_3_NC2")
	)
	(segment
		(start 74.96937 -37.263324)
		(end 75.614784 -36.61791)
		(width 0.10668)
		(layer "F.Cu")
		(net "NC_INA230_3_NC2")
	)
	(segment
		(start 73.458324 -37.919914)
		(end 73.458324 -37.665152)
		(width 0.10668)
		(layer "F.Cu")
		(net "NC_INA230_3_NC2")
	)
	(segment
		(start 73.860152 -37.263324)
		(end 74.96937 -37.263324)
		(width 0.10668)
		(layer "F.Cu")
		(net "NC_INA230_3_NC2")
	)
	(via
		(at 75.614784 -36.61791)
		(size 0.762)
		(drill 0.381)
		(layers "F.Cu" "B.Cu")
		(net "NC_INA230_3_NC2")
	)
	(segment
		(start 72.958198 -37.467286)
		(end 73.84542 -36.580064)
		(width 0.10668)
		(layer "F.Cu")
		(net "NC_INA230_3_NC1")
	)
	(segment
		(start 73.84542 -36.580064)
		(end 74.293984 -36.580064)
		(width 0.10668)
		(layer "F.Cu")
		(net "NC_INA230_3_NC1")
	)
	(segment
		(start 72.958198 -37.919914)
		(end 72.958198 -37.467286)
		(width 0.10668)
		(layer "F.Cu")
		(net "NC_INA230_3_NC1")
	)
	(via
		(at 74.293984 -36.580064)
		(size 0.762)
		(drill 0.381)
		(layers "F.Cu" "B.Cu")
		(net "NC_INA230_3_NC1")
	)
	(segment
		(start 72.458326 -37.056568)
		(end 72.947784 -36.56711)
		(width 0.10668)
		(layer "F.Cu")
		(net "NC_INA230_3_NC0")
	)
	(segment
		(start 72.458326 -37.919914)
		(end 72.458326 -37.056568)
		(width 0.10668)
		(layer "F.Cu")
		(net "NC_INA230_3_NC0")
	)
	(via
		(at 72.947784 -36.56711)
		(size 0.762)
		(drill 0.381)
		(layers "F.Cu" "B.Cu")
		(net "NC_INA230_3_NC0")
	)
	(segment
		(start 214.509858 -56.069484)
		(end 213.814914 -56.764428)
		(width 0.10668)
		(layer "F.Cu")
		(net "NC_INA230_2_NC5")
	)
	(segment
		(start 213.347554 -56.764428)
		(end 213.024974 -57.087008)
		(width 0.10668)
		(layer "F.Cu")
		(net "NC_INA230_2_NC5")
	)
	(segment
		(start 213.814914 -56.764428)
		(end 213.347554 -56.764428)
		(width 0.10668)
		(layer "F.Cu")
		(net "NC_INA230_2_NC5")
	)
	(segment
		(start 214.509604 -56.06923)
		(end 214.509858 -56.069484)
		(width 0.10668)
		(layer "F.Cu")
		(net "NC_INA230_2_NC5")
	)
	(segment
		(start 214.509604 -55.855362)
		(end 214.509604 -56.06923)
		(width 0.10668)
		(layer "F.Cu")
		(net "NC_INA230_2_NC5")
	)
	(via
		(at 213.024974 -57.087008)
		(size 0.762)
		(drill 0.381)
		(layers "F.Cu" "B.Cu")
		(net "NC_INA230_2_NC5")
	)
	(segment
		(start 213.591394 -58.781188)
		(end 213.126574 -59.246008)
		(width 0.10668)
		(layer "F.Cu")
		(net "NC_INA230_2_NC4")
	)
	(segment
		(start 215.009984 -56.102758)
		(end 213.591394 -57.521348)
		(width 0.10668)
		(layer "F.Cu")
		(net "NC_INA230_2_NC4")
	)
	(segment
		(start 213.591394 -57.521348)
		(end 213.591394 -58.781188)
		(width 0.10668)
		(layer "F.Cu")
		(net "NC_INA230_2_NC4")
	)
	(segment
		(start 215.00973 -56.102504)
		(end 215.009984 -56.102758)
		(width 0.10668)
		(layer "F.Cu")
		(net "NC_INA230_2_NC4")
	)
	(segment
		(start 215.00973 -55.855362)
		(end 215.00973 -56.102504)
		(width 0.10668)
		(layer "F.Cu")
		(net "NC_INA230_2_NC4")
	)
	(via
		(at 213.126574 -59.246008)
		(size 0.762)
		(drill 0.381)
		(layers "F.Cu" "B.Cu")
		(net "NC_INA230_2_NC4")
	)
	(segment
		(start 214.251794 -58.156348)
		(end 215.509602 -56.89854)
		(width 0.10668)
		(layer "F.Cu")
		(net "NC_INA230_2_NC3")
	)
	(segment
		(start 215.509602 -56.89854)
		(end 215.509602 -55.855362)
		(width 0.10668)
		(layer "F.Cu")
		(net "NC_INA230_2_NC3")
	)
	(via
		(at 214.251794 -58.156348)
		(size 0.762)
		(drill 0.381)
		(layers "F.Cu" "B.Cu")
		(net "NC_INA230_2_NC3")
	)
	(segment
		(start 216.639394 -52.012088)
		(end 217.271854 -52.012088)
		(width 0.10668)
		(layer "F.Cu")
		(net "NC_INA230_2_NC2")
	)
	(segment
		(start 216.009728 -52.641754)
		(end 216.639394 -52.012088)
		(width 0.10668)
		(layer "F.Cu")
		(net "NC_INA230_2_NC2")
	)
	(segment
		(start 216.009728 -53.055266)
		(end 216.009728 -52.641754)
		(width 0.10668)
		(layer "F.Cu")
		(net "NC_INA230_2_NC2")
	)
	(via
		(at 217.271854 -52.012088)
		(size 0.762)
		(drill 0.381)
		(layers "F.Cu" "B.Cu")
		(net "NC_INA230_2_NC2")
	)
	(segment
		(start 216.093294 -51.438048)
		(end 216.748614 -50.782728)
		(width 0.10668)
		(layer "F.Cu")
		(net "NC_INA230_2_NC1")
	)
	(segment
		(start 215.509602 -53.055266)
		(end 215.509602 -52.43449)
		(width 0.10668)
		(layer "F.Cu")
		(net "NC_INA230_2_NC1")
	)
	(segment
		(start 215.509602 -52.43449)
		(end 216.093294 -51.850798)
		(width 0.10668)
		(layer "F.Cu")
		(net "NC_INA230_2_NC1")
	)
	(segment
		(start 216.093294 -51.850798)
		(end 216.093294 -51.438048)
		(width 0.10668)
		(layer "F.Cu")
		(net "NC_INA230_2_NC1")
	)
	(via
		(at 216.748614 -50.782728)
		(size 0.762)
		(drill 0.381)
		(layers "F.Cu" "B.Cu")
		(net "NC_INA230_2_NC1")
	)
	(segment
		(start 215.00973 -53.055266)
		(end 215.00973 -52.227226)
		(width 0.10668)
		(layer "F.Cu")
		(net "NC_INA230_2_NC0")
	)
	(segment
		(start 215.204294 -52.032662)
		(end 215.204294 -50.442368)
		(width 0.10668)
		(layer "F.Cu")
		(net "NC_INA230_2_NC0")
	)
	(segment
		(start 215.204294 -50.442368)
		(end 215.727534 -49.919128)
		(width 0.10668)
		(layer "F.Cu")
		(net "NC_INA230_2_NC0")
	)
	(segment
		(start 215.00973 -52.227226)
		(end 215.204294 -52.032662)
		(width 0.10668)
		(layer "F.Cu")
		(net "NC_INA230_2_NC0")
	)
	(via
		(at 215.727534 -49.919128)
		(size 0.762)
		(drill 0.381)
		(layers "F.Cu" "B.Cu")
		(net "NC_INA230_2_NC0")
	)
	(segment
		(start 441.43803 -92.594938)
		(end 441.43803 -92.677488)
		(width 0.10668)
		(layer "F.Cu")
		(net "NC_INA230_1_NC5")
	)
	(segment
		(start 443.35446 -90.678508)
		(end 441.43803 -92.594938)
		(width 0.10668)
		(layer "F.Cu")
		(net "NC_INA230_1_NC5")
	)
	(via
		(at 443.35446 -90.678508)
		(size 0.762)
		(drill 0.381)
		(layers "F.Cu" "B.Cu")
		(net "NC_INA230_1_NC5")
	)
	(segment
		(start 440.937904 -91.588844)
		(end 440.937904 -92.677488)
		(width 0.10668)
		(layer "F.Cu")
		(net "NC_INA230_1_NC4")
	)
	(segment
		(start 441.57392 -90.952828)
		(end 440.937904 -91.588844)
		(width 0.10668)
		(layer "F.Cu")
		(net "NC_INA230_1_NC4")
	)
	(via
		(at 441.57392 -90.952828)
		(size 0.762)
		(drill 0.381)
		(layers "F.Cu" "B.Cu")
		(net "NC_INA230_1_NC4")
	)
	(segment
		(start 440.438032 -91.58224)
		(end 440.438032 -92.677488)
		(width 0.10668)
		(layer "F.Cu")
		(net "NC_INA230_1_NC3")
	)
	(segment
		(start 439.79338 -90.937588)
		(end 440.438032 -91.58224)
		(width 0.10668)
		(layer "F.Cu")
		(net "NC_INA230_1_NC3")
	)
	(via
		(at 439.79338 -90.937588)
		(size 0.762)
		(drill 0.381)
		(layers "F.Cu" "B.Cu")
		(net "NC_INA230_1_NC3")
	)
	(segment
		(start 439.937906 -97.498662)
		(end 439.937906 -95.477584)
		(width 0.10668)
		(layer "F.Cu")
		(net "NC_INA230_1_NC2")
	)
	(segment
		(start 439.13044 -98.306128)
		(end 439.937906 -97.498662)
		(width 0.10668)
		(layer "F.Cu")
		(net "NC_INA230_1_NC2")
	)
	(via
		(at 439.13044 -98.306128)
		(size 0.762)
		(drill 0.381)
		(layers "F.Cu" "B.Cu")
		(net "NC_INA230_1_NC2")
	)
	(segment
		(start 440.91098 -98.318828)
		(end 440.438032 -97.84588)
		(width 0.10668)
		(layer "F.Cu")
		(net "NC_INA230_1_NC1")
	)
	(segment
		(start 440.438032 -97.84588)
		(end 440.438032 -95.477584)
		(width 0.10668)
		(layer "F.Cu")
		(net "NC_INA230_1_NC1")
	)
	(via
		(at 440.91098 -98.318828)
		(size 0.762)
		(drill 0.381)
		(layers "F.Cu" "B.Cu")
		(net "NC_INA230_1_NC1")
	)
	(segment
		(start 440.937904 -96.600772)
		(end 440.937904 -95.477584)
		(width 0.10668)
		(layer "F.Cu")
		(net "NC_INA230_1_NC0")
	)
	(segment
		(start 442.66358 -98.326448)
		(end 440.937904 -96.600772)
		(width 0.10668)
		(layer "F.Cu")
		(net "NC_INA230_1_NC0")
	)
	(via
		(at 442.66358 -98.326448)
		(size 0.762)
		(drill 0.381)
		(layers "F.Cu" "B.Cu")
		(net "NC_INA230_1_NC0")
	)
	(via
		(at 183.26735 -419.573202)
		(size 0.6604)
		(drill 0.3302)
		(layers "F.Cu" "B.Cu")
		(net "MB_PDB_SMB9_R_EN")
	)
	(segment
		(start 183.070754 -419.376606)
		(end 183.26735 -419.573202)
		(width 0.10668)
		(layer "B.Cu")
		(net "MB_PDB_SMB9_R_EN")
	)
	(segment
		(start 180.535834 -419.376606)
		(end 183.070754 -419.376606)
		(width 0.10668)
		(layer "B.Cu")
		(net "MB_PDB_SMB9_R_EN")
	)
	(segment
		(start 183.26735 -419.573202)
		(end 183.555386 -419.861238)
		(width 0.10668)
		(layer "B.Cu")
		(net "MB_PDB_SMB9_R_EN")
	)
	(segment
		(start 183.555386 -419.861238)
		(end 184.281064 -419.861238)
		(width 0.10668)
		(layer "B.Cu")
		(net "MB_PDB_SMB9_R_EN")
	)
	(segment
		(start 305.562508 -116.891308)
		(end 305.606704 -116.935504)
		(width 0.10668)
		(layer "F.Cu")
		(net "MB_FRU_ADDR2")
	)
	(segment
		(start 302.833278 -117.493542)
		(end 304.960274 -117.493542)
		(width 0.10668)
		(layer "F.Cu")
		(net "MB_FRU_ADDR2")
	)
	(segment
		(start 305.606704 -116.935504)
		(end 307.323998 -116.935504)
		(width 0.10668)
		(layer "F.Cu")
		(net "MB_FRU_ADDR2")
	)
	(segment
		(start 302.641508 -116.891308)
		(end 302.641508 -117.301772)
		(width 0.10668)
		(layer "F.Cu")
		(net "MB_FRU_ADDR2")
	)
	(segment
		(start 304.960274 -117.493542)
		(end 305.562508 -116.891308)
		(width 0.10668)
		(layer "F.Cu")
		(net "MB_FRU_ADDR2")
	)
	(segment
		(start 309.337964 -116.935504)
		(end 307.323998 -116.935504)
		(width 0.10668)
		(layer "F.Cu")
		(net "MB_FRU_ADDR2")
	)
	(segment
		(start 302.641508 -117.301772)
		(end 302.833278 -117.493542)
		(width 0.10668)
		(layer "F.Cu")
		(net "MB_FRU_ADDR2")
	)
	(via
		(at 307.323998 -116.935504)
		(size 0.762)
		(drill 0.381)
		(layers "F.Cu" "B.Cu")
		(net "MB_FRU_ADDR2")
	)
	(segment
		(start 309.337964 -118.205504)
		(end 307.323998 -118.205504)
		(width 0.10668)
		(layer "F.Cu")
		(net "MB_FRU_ADDR1")
	)
	(segment
		(start 302.656748 -118.179088)
		(end 302.656748 -118.647972)
		(width 0.10668)
		(layer "F.Cu")
		(net "MB_FRU_ADDR1")
	)
	(segment
		(start 302.656748 -118.647972)
		(end 302.792638 -118.783862)
		(width 0.10668)
		(layer "F.Cu")
		(net "MB_FRU_ADDR1")
	)
	(segment
		(start 304.972974 -118.783862)
		(end 305.577748 -118.179088)
		(width 0.10668)
		(layer "F.Cu")
		(net "MB_FRU_ADDR1")
	)
	(segment
		(start 305.577748 -118.179088)
		(end 305.604164 -118.205504)
		(width 0.10668)
		(layer "F.Cu")
		(net "MB_FRU_ADDR1")
	)
	(segment
		(start 305.604164 -118.205504)
		(end 307.323998 -118.205504)
		(width 0.10668)
		(layer "F.Cu")
		(net "MB_FRU_ADDR1")
	)
	(segment
		(start 302.792638 -118.783862)
		(end 304.972974 -118.783862)
		(width 0.10668)
		(layer "F.Cu")
		(net "MB_FRU_ADDR1")
	)
	(via
		(at 307.323998 -118.205504)
		(size 0.762)
		(drill 0.381)
		(layers "F.Cu" "B.Cu")
		(net "MB_FRU_ADDR1")
	)
	(segment
		(start 305.597052 -119.475504)
		(end 304.967894 -120.104662)
		(width 0.10668)
		(layer "F.Cu")
		(net "MB_FRU_ADDR0")
	)
	(segment
		(start 302.807878 -120.104662)
		(end 302.671988 -119.968772)
		(width 0.10668)
		(layer "F.Cu")
		(net "MB_FRU_ADDR0")
	)
	(segment
		(start 302.671988 -119.968772)
		(end 302.671988 -119.479568)
		(width 0.10668)
		(layer "F.Cu")
		(net "MB_FRU_ADDR0")
	)
	(segment
		(start 304.967894 -120.104662)
		(end 302.807878 -120.104662)
		(width 0.10668)
		(layer "F.Cu")
		(net "MB_FRU_ADDR0")
	)
	(segment
		(start 307.323998 -119.475504)
		(end 305.597052 -119.475504)
		(width 0.10668)
		(layer "F.Cu")
		(net "MB_FRU_ADDR0")
	)
	(segment
		(start 309.337964 -119.475504)
		(end 307.323998 -119.475504)
		(width 0.10668)
		(layer "F.Cu")
		(net "MB_FRU_ADDR0")
	)
	(via
		(at 307.323998 -119.475504)
		(size 0.762)
		(drill 0.381)
		(layers "F.Cu" "B.Cu")
		(net "MB_FRU_ADDR0")
	)
	(segment
		(start 153.598118 -56.868822)
		(end 153.19883 -56.868822)
		(width 0.10668)
		(layer "F.Cu")
		(net "M2_0_P3V3_ADC_ALERT_R")
	)
	(segment
		(start 150.900892 -53.083714)
		(end 150.900892 -54.170834)
		(width 0.10668)
		(layer "F.Cu")
		(net "M2_0_P3V3_ADC_ALERT_R")
	)
	(segment
		(start 152.15362 -55.823612)
		(end 152.15362 -55.823358)
		(width 0.10668)
		(layer "F.Cu")
		(net "M2_0_P3V3_ADC_ALERT_R")
	)
	(segment
		(start 153.19883 -56.868822)
		(end 152.15362 -55.823612)
		(width 0.10668)
		(layer "F.Cu")
		(net "M2_0_P3V3_ADC_ALERT_R")
	)
	(segment
		(start 150.902416 -54.172358)
		(end 150.902416 -54.414674)
		(width 0.10668)
		(layer "F.Cu")
		(net "M2_0_P3V3_ADC_ALERT_R")
	)
	(segment
		(start 150.902416 -54.414674)
		(end 152.15362 -55.665878)
		(width 0.10668)
		(layer "F.Cu")
		(net "M2_0_P3V3_ADC_ALERT_R")
	)
	(segment
		(start 152.15362 -55.665878)
		(end 152.15362 -55.823358)
		(width 0.10668)
		(layer "F.Cu")
		(net "M2_0_P3V3_ADC_ALERT_R")
	)
	(segment
		(start 150.900892 -54.170834)
		(end 150.902416 -54.172358)
		(width 0.10668)
		(layer "F.Cu")
		(net "M2_0_P3V3_ADC_ALERT_R")
	)
	(via
		(at 152.15362 -55.823358)
		(size 0.762)
		(drill 0.381)
		(layers "F.Cu" "B.Cu")
		(net "M2_0_P3V3_ADC_ALERT_R")
	)
	(segment
		(start 149.898608 -54.376066)
		(end 150.102316 -54.172358)
		(width 0.10668)
		(layer "F.Cu")
		(net "M2_0_P3V3_ADC_ALERT")
	)
	(segment
		(start 185.922158 -106.652822)
		(end 186.312048 -106.262932)
		(width 0.10668)
		(layer "F.Cu")
		(net "M2_0_P3V3_ADC_ALERT")
	)
	(segment
		(start 149.40661 -54.376066)
		(end 149.898608 -54.376066)
		(width 0.10668)
		(layer "F.Cu")
		(net "M2_0_P3V3_ADC_ALERT")
	)
	(via
		(at 171.284392 -55.51932)
		(size 0.508)
		(drill 0.254)
		(layers "F.Cu" "B.Cu")
		(net "M2_0_P3V3_ADC_ALERT")
	)
	(via
		(at 149.40661 -54.376066)
		(size 0.508)
		(drill 0.254)
		(layers "F.Cu" "B.Cu")
		(net "M2_0_P3V3_ADC_ALERT")
	)
	(via
		(at 186.312048 -106.262932)
		(size 0.4572)
		(drill 0.254)
		(layers "F.Cu" "B.Cu")
		(net "M2_0_P3V3_ADC_ALERT")
	)
	(segment
		(start 159.895794 -55.51932)
		(end 158.75254 -54.376066)
		(width 0.11684)
		(layer "In6.Cu")
		(net "M2_0_P3V3_ADC_ALERT")
	)
	(segment
		(start 158.75254 -54.376066)
		(end 149.40661 -54.376066)
		(width 0.11684)
		(layer "In6.Cu")
		(net "M2_0_P3V3_ADC_ALERT")
	)
	(segment
		(start 171.284392 -55.51932)
		(end 159.895794 -55.51932)
		(width 0.11684)
		(layer "In6.Cu")
		(net "M2_0_P3V3_ADC_ALERT")
	)
	(segment
		(start 186.2963 -93.490288)
		(end 184.824116 -92.018104)
		(width 0.11684)
		(layer "In11.Cu")
		(net "M2_0_P3V3_ADC_ALERT")
	)
	(segment
		(start 170.663362 -77.945742)
		(end 170.663362 -56.14035)
		(width 0.11684)
		(layer "In11.Cu")
		(net "M2_0_P3V3_ADC_ALERT")
	)
	(segment
		(start 182.092092 -90.736674)
		(end 180.144166 -88.788748)
		(width 0.11684)
		(layer "In11.Cu")
		(net "M2_0_P3V3_ADC_ALERT")
	)
	(segment
		(start 176.347374 -83.073494)
		(end 175.791114 -83.073494)
		(width 0.11684)
		(layer "In11.Cu")
		(net "M2_0_P3V3_ADC_ALERT")
	)
	(segment
		(start 186.29122 -99.65944)
		(end 186.29122 -97.658682)
		(width 0.11684)
		(layer "In11.Cu")
		(net "M2_0_P3V3_ADC_ALERT")
	)
	(segment
		(start 186.65444 -95.217488)
		(end 186.2963 -94.859348)
		(width 0.11684)
		(layer "In11.Cu")
		(net "M2_0_P3V3_ADC_ALERT")
	)
	(segment
		(start 186.65444 -97.295462)
		(end 186.65444 -95.217488)
		(width 0.11684)
		(layer "In11.Cu")
		(net "M2_0_P3V3_ADC_ALERT")
	)
	(segment
		(start 184.33161 -90.736674)
		(end 182.092092 -90.736674)
		(width 0.11684)
		(layer "In11.Cu")
		(net "M2_0_P3V3_ADC_ALERT")
	)
	(segment
		(start 185.2422 -100.70846)
		(end 186.29122 -99.65944)
		(width 0.11684)
		(layer "In11.Cu")
		(net "M2_0_P3V3_ADC_ALERT")
	)
	(segment
		(start 186.2074 -104.14254)
		(end 185.2422 -103.17734)
		(width 0.11684)
		(layer "In11.Cu")
		(net "M2_0_P3V3_ADC_ALERT")
	)
	(segment
		(start 170.663362 -56.14035)
		(end 171.284392 -55.51932)
		(width 0.11684)
		(layer "In11.Cu")
		(net "M2_0_P3V3_ADC_ALERT")
	)
	(segment
		(start 186.312048 -106.262932)
		(end 186.2074 -106.158284)
		(width 0.11684)
		(layer "In11.Cu")
		(net "M2_0_P3V3_ADC_ALERT")
	)
	(segment
		(start 186.2074 -106.158284)
		(end 186.2074 -104.14254)
		(width 0.11684)
		(layer "In11.Cu")
		(net "M2_0_P3V3_ADC_ALERT")
	)
	(segment
		(start 186.29122 -97.658682)
		(end 186.65444 -97.295462)
		(width 0.11684)
		(layer "In11.Cu")
		(net "M2_0_P3V3_ADC_ALERT")
	)
	(segment
		(start 180.144166 -88.788748)
		(end 180.144166 -86.870286)
		(width 0.11684)
		(layer "In11.Cu")
		(net "M2_0_P3V3_ADC_ALERT")
	)
	(segment
		(start 180.144166 -86.870286)
		(end 176.347374 -83.073494)
		(width 0.11684)
		(layer "In11.Cu")
		(net "M2_0_P3V3_ADC_ALERT")
	)
	(segment
		(start 175.791114 -83.073494)
		(end 170.663362 -77.945742)
		(width 0.11684)
		(layer "In11.Cu")
		(net "M2_0_P3V3_ADC_ALERT")
	)
	(segment
		(start 185.2422 -103.17734)
		(end 185.2422 -100.70846)
		(width 0.11684)
		(layer "In11.Cu")
		(net "M2_0_P3V3_ADC_ALERT")
	)
	(segment
		(start 186.2963 -94.859348)
		(end 186.2963 -93.490288)
		(width 0.11684)
		(layer "In11.Cu")
		(net "M2_0_P3V3_ADC_ALERT")
	)
	(segment
		(start 184.824116 -91.22918)
		(end 184.33161 -90.736674)
		(width 0.11684)
		(layer "In11.Cu")
		(net "M2_0_P3V3_ADC_ALERT")
	)
	(segment
		(start 184.824116 -92.018104)
		(end 184.824116 -91.22918)
		(width 0.11684)
		(layer "In11.Cu")
		(net "M2_0_P3V3_ADC_ALERT")
	)
	(segment
		(start 208.422494 -32.313626)
		(end 206.78521 -30.676342)
		(width 0.10668)
		(layer "F.Cu")
		(net "INA230_5_A1")
	)
	(segment
		(start 209.070956 -30.676342)
		(end 208.054956 -30.676342)
		(width 0.10668)
		(layer "F.Cu")
		(net "INA230_5_A1")
	)
	(segment
		(start 208.422494 -33.372044)
		(end 208.422494 -32.313626)
		(width 0.10668)
		(layer "F.Cu")
		(net "INA230_5_A1")
	)
	(segment
		(start 208.054956 -30.676342)
		(end 206.78521 -30.676342)
		(width 0.10668)
		(layer "F.Cu")
		(net "INA230_5_A1")
	)
	(via
		(at 206.78521 -30.676342)
		(size 0.762)
		(drill 0.381)
		(layers "F.Cu" "B.Cu")
		(net "INA230_5_A1")
	)
	(segment
		(start 210.086956 -30.676342)
		(end 210.086956 -30.76321)
		(width 0.10668)
		(layer "F.Cu")
		(net "INA230_5_A0")
	)
	(segment
		(start 208.92262 -33.372044)
		(end 208.92262 -31.927546)
		(width 0.10668)
		(layer "F.Cu")
		(net "INA230_5_A0")
	)
	(segment
		(start 211.102956 -30.676342)
		(end 210.086956 -30.676342)
		(width 0.10668)
		(layer "F.Cu")
		(net "INA230_5_A0")
	)
	(segment
		(start 208.92262 -31.927546)
		(end 208.922874 -31.927292)
		(width 0.10668)
		(layer "F.Cu")
		(net "INA230_5_A0")
	)
	(segment
		(start 210.086956 -30.76321)
		(end 208.922874 -31.927292)
		(width 0.10668)
		(layer "F.Cu")
		(net "INA230_5_A0")
	)
	(via
		(at 208.922874 -31.927292)
		(size 0.762)
		(drill 0.381)
		(layers "F.Cu" "B.Cu")
		(net "INA230_5_A0")
	)
	(segment
		(start 150.902416 -59.506104)
		(end 150.90267 -59.506358)
		(width 0.10668)
		(layer "F.Cu")
		(net "INA230_4_A1")
	)
	(segment
		(start 150.902416 -58.236358)
		(end 150.902416 -59.506104)
		(width 0.10668)
		(layer "F.Cu")
		(net "INA230_4_A1")
	)
	(segment
		(start 150.90267 -59.506358)
		(end 152.540208 -57.86882)
		(width 0.10668)
		(layer "F.Cu")
		(net "INA230_4_A1")
	)
	(segment
		(start 152.540208 -57.86882)
		(end 153.598118 -57.86882)
		(width 0.10668)
		(layer "F.Cu")
		(net "INA230_4_A1")
	)
	(segment
		(start 150.902416 -57.220358)
		(end 150.902416 -58.236358)
		(width 0.10668)
		(layer "F.Cu")
		(net "INA230_4_A1")
	)
	(via
		(at 150.90267 -59.506358)
		(size 0.762)
		(drill 0.381)
		(layers "F.Cu" "B.Cu")
		(net "INA230_4_A1")
	)
	(segment
		(start 150.902416 -55.188358)
		(end 150.902416 -56.204358)
		(width 0.10668)
		(layer "F.Cu")
		(net "INA230_4_A0")
	)
	(segment
		(start 153.598118 -57.368694)
		(end 152.15362 -57.368694)
		(width 0.10668)
		(layer "F.Cu")
		(net "INA230_4_A0")
	)
	(segment
		(start 150.902416 -56.204358)
		(end 150.989284 -56.204358)
		(width 0.10668)
		(layer "F.Cu")
		(net "INA230_4_A0")
	)
	(segment
		(start 150.989284 -56.204358)
		(end 152.15362 -57.368694)
		(width 0.10668)
		(layer "F.Cu")
		(net "INA230_4_A0")
	)
	(via
		(at 152.15362 -57.368694)
		(size 0.762)
		(drill 0.381)
		(layers "F.Cu" "B.Cu")
		(net "INA230_4_A0")
	)
	(segment
		(start 71.308214 -40.070024)
		(end 70.217284 -40.070024)
		(width 0.10668)
		(layer "F.Cu")
		(net "INA230_3_A1")
	)
	(segment
		(start 69.848222 -40.437562)
		(end 69.848984 -40.438324)
		(width 0.10668)
		(layer "F.Cu")
		(net "INA230_3_A1")
	)
	(segment
		(start 68.612512 -40.437562)
		(end 69.848222 -40.437562)
		(width 0.10668)
		(layer "F.Cu")
		(net "INA230_3_A1")
	)
	(segment
		(start 70.217284 -40.070024)
		(end 69.848984 -40.438324)
		(width 0.10668)
		(layer "F.Cu")
		(net "INA230_3_A1")
	)
	(via
		(at 69.848984 -40.438324)
		(size 0.762)
		(drill 0.381)
		(layers "F.Cu" "B.Cu")
		(net "INA230_3_A1")
	)
	(segment
		(start 68.612512 -39.421562)
		(end 68.612512 -38.405562)
		(width 0.10668)
		(layer "F.Cu")
		(net "INA230_3_A0")
	)
	(segment
		(start 71.308214 -39.569898)
		(end 70.815708 -39.569898)
		(width 0.10668)
		(layer "F.Cu")
		(net "INA230_3_A0")
	)
	(segment
		(start 70.815708 -39.569898)
		(end 70.32752 -39.08171)
		(width 0.10668)
		(layer "F.Cu")
		(net "INA230_3_A0")
	)
	(segment
		(start 69.23532 -39.08171)
		(end 69.848984 -39.08171)
		(width 0.10668)
		(layer "F.Cu")
		(net "INA230_3_A0")
	)
	(segment
		(start 68.895468 -39.421562)
		(end 69.23532 -39.08171)
		(width 0.10668)
		(layer "F.Cu")
		(net "INA230_3_A0")
	)
	(segment
		(start 68.612512 -39.421562)
		(end 68.895468 -39.421562)
		(width 0.10668)
		(layer "F.Cu")
		(net "INA230_3_A0")
	)
	(segment
		(start 70.32752 -39.08171)
		(end 69.848984 -39.08171)
		(width 0.10668)
		(layer "F.Cu")
		(net "INA230_3_A0")
	)
	(via
		(at 69.848984 -39.08171)
		(size 0.762)
		(drill 0.381)
		(layers "F.Cu" "B.Cu")
		(net "INA230_3_A0")
	)
	(segment
		(start 213.6394 -55.205376)
		(end 212.887814 -55.956962)
		(width 0.10668)
		(layer "F.Cu")
		(net "INA230_2_A1")
	)
	(segment
		(start 212.887814 -55.956962)
		(end 212.069934 -55.956962)
		(width 0.10668)
		(layer "F.Cu")
		(net "INA230_2_A1")
	)
	(segment
		(start 212.069934 -55.956962)
		(end 211.763864 -56.263032)
		(width 0.10668)
		(layer "F.Cu")
		(net "INA230_2_A1")
	)
	(segment
		(start 211.763864 -56.263032)
		(end 211.763864 -57.147968)
		(width 0.10668)
		(layer "F.Cu")
		(net "INA230_2_A1")
	)
	(segment
		(start 211.763864 -57.147968)
		(end 211.76361 -57.148222)
		(width 0.10668)
		(layer "F.Cu")
		(net "INA230_2_A1")
	)
	(segment
		(start 213.859618 -55.205376)
		(end 213.6394 -55.205376)
		(width 0.10668)
		(layer "F.Cu")
		(net "INA230_2_A1")
	)
	(via
		(at 212.069934 -55.956962)
		(size 0.762)
		(drill 0.381)
		(layers "F.Cu" "B.Cu")
		(net "INA230_2_A1")
	)
	(segment
		(start 212.638894 -55.425848)
		(end 213.359492 -54.70525)
		(width 0.10668)
		(layer "F.Cu")
		(net "INA230_2_A0")
	)
	(segment
		(start 213.359492 -54.70525)
		(end 213.859618 -54.70525)
		(width 0.10668)
		(layer "F.Cu")
		(net "INA230_2_A0")
	)
	(via
		(at 212.638894 -55.425848)
		(size 0.508)
		(drill 0.254)
		(layers "F.Cu" "B.Cu")
		(net "INA230_2_A0")
	)
	(segment
		(start 213.797134 -54.847998)
		(end 213.797134 -55.737252)
		(width 0.10668)
		(layer "B.Cu")
		(net "INA230_2_A0")
	)
	(segment
		(start 213.79688 -54.847998)
		(end 213.797134 -54.847998)
		(width 0.10668)
		(layer "B.Cu")
		(net "INA230_2_A0")
	)
	(segment
		(start 213.216744 -54.847998)
		(end 212.638894 -55.425848)
		(width 0.10668)
		(layer "B.Cu")
		(net "INA230_2_A0")
	)
	(segment
		(start 213.79688 -54.847998)
		(end 213.216744 -54.847998)
		(width 0.10668)
		(layer "B.Cu")
		(net "INA230_2_A0")
	)
	(segment
		(start 213.797134 -55.737252)
		(end 214.03183 -55.971948)
		(width 0.10668)
		(layer "B.Cu")
		(net "INA230_2_A0")
	)
	(segment
		(start 445.45631 -91.76893)
		(end 444.757048 -92.468192)
		(width 0.10668)
		(layer "F.Cu")
		(net "INA230_1_A1")
	)
	(segment
		(start 444.757048 -92.468192)
		(end 444.519304 -92.230448)
		(width 0.10668)
		(layer "F.Cu")
		(net "INA230_1_A1")
	)
	(segment
		(start 448.272408 -92.493592)
		(end 447.547746 -91.76893)
		(width 0.10668)
		(layer "F.Cu")
		(net "INA230_1_A1")
	)
	(segment
		(start 444.519304 -92.230448)
		(end 443.46114 -92.230448)
		(width 0.10668)
		(layer "F.Cu")
		(net "INA230_1_A1")
	)
	(segment
		(start 442.088016 -93.327474)
		(end 442.32576 -93.327474)
		(width 0.10668)
		(layer "F.Cu")
		(net "INA230_1_A1")
	)
	(segment
		(start 442.54166 -92.508324)
		(end 442.819536 -92.230448)
		(width 0.10668)
		(layer "F.Cu")
		(net "INA230_1_A1")
	)
	(segment
		(start 442.32576 -93.327474)
		(end 442.54166 -93.111574)
		(width 0.10668)
		(layer "F.Cu")
		(net "INA230_1_A1")
	)
	(segment
		(start 447.547746 -91.76893)
		(end 445.45631 -91.76893)
		(width 0.10668)
		(layer "F.Cu")
		(net "INA230_1_A1")
	)
	(segment
		(start 442.819536 -92.230448)
		(end 443.46114 -92.230448)
		(width 0.10668)
		(layer "F.Cu")
		(net "INA230_1_A1")
	)
	(segment
		(start 442.54166 -93.111574)
		(end 442.54166 -92.508324)
		(width 0.10668)
		(layer "F.Cu")
		(net "INA230_1_A1")
	)
	(via
		(at 443.46114 -92.230448)
		(size 0.762)
		(drill 0.381)
		(layers "F.Cu" "B.Cu")
		(net "INA230_1_A1")
	)
	(segment
		(start 442.8617 -93.505528)
		(end 443.51448 -93.505528)
		(width 0.10668)
		(layer "F.Cu")
		(net "INA230_1_A0")
	)
	(segment
		(start 447.722498 -94.059502)
		(end 445.332358 -94.059502)
		(width 0.10668)
		(layer "F.Cu")
		(net "INA230_1_A0")
	)
	(segment
		(start 448.272408 -93.509592)
		(end 447.722498 -94.059502)
		(width 0.10668)
		(layer "F.Cu")
		(net "INA230_1_A0")
	)
	(segment
		(start 445.332358 -94.059502)
		(end 444.757048 -93.484192)
		(width 0.10668)
		(layer "F.Cu")
		(net "INA230_1_A0")
	)
	(segment
		(start 442.088016 -93.8276)
		(end 442.539628 -93.8276)
		(width 0.10668)
		(layer "F.Cu")
		(net "INA230_1_A0")
	)
	(segment
		(start 444.757048 -93.484192)
		(end 443.535816 -93.484192)
		(width 0.10668)
		(layer "F.Cu")
		(net "INA230_1_A0")
	)
	(segment
		(start 443.535816 -93.484192)
		(end 443.51448 -93.505528)
		(width 0.10668)
		(layer "F.Cu")
		(net "INA230_1_A0")
	)
	(segment
		(start 442.539628 -93.8276)
		(end 442.8617 -93.505528)
		(width 0.10668)
		(layer "F.Cu")
		(net "INA230_1_A0")
	)
	(via
		(at 443.51448 -93.505528)
		(size 0.762)
		(drill 0.381)
		(layers "F.Cu" "B.Cu")
		(net "INA230_1_A0")
	)
	(via
		(at 234.644692 -424.417998)
		(size 0.6604)
		(drill 0.3302)
		(layers "F.Cu" "B.Cu")
		(net "HPDB_HSC_PWRGD_R")
	)
	(segment
		(start 234.644692 -424.417998)
		(end 234.644692 -423.249598)
		(width 0.10668)
		(layer "B.Cu")
		(net "HPDB_HSC_PWRGD_R")
	)
	(segment
		(start 233.37012 -430.50206)
		(end 233.369866 -430.50206)
		(width 0.10668)
		(layer "B.Cu")
		(net "HPDB_HSC_PWRGD_R")
	)
	(segment
		(start 233.369866 -430.50206)
		(end 234.64012 -429.231806)
		(width 0.10668)
		(layer "B.Cu")
		(net "HPDB_HSC_PWRGD_R")
	)
	(segment
		(start 235.660692 -423.249598)
		(end 234.644692 -423.249598)
		(width 0.10668)
		(layer "B.Cu")
		(net "HPDB_HSC_PWRGD_R")
	)
	(segment
		(start 234.64012 -429.231806)
		(end 234.64012 -424.42257)
		(width 0.10668)
		(layer "B.Cu")
		(net "HPDB_HSC_PWRGD_R")
	)
	(segment
		(start 234.64012 -424.42257)
		(end 234.644692 -424.417998)
		(width 0.10668)
		(layer "B.Cu")
		(net "HPDB_HSC_PWRGD_R")
	)
	(segment
		(start 284.317694 -437.923686)
		(end 283.083254 -437.923686)
		(width 0.10668)
		(layer "F.Cu")
		(net "HPDB_HSC_PWRGD_N")
	)
	(segment
		(start 284.317694 -436.704486)
		(end 284.317694 -437.923686)
		(width 0.10668)
		(layer "F.Cu")
		(net "HPDB_HSC_PWRGD_N")
	)
	(segment
		(start 283.083254 -437.2737)
		(end 283.083254 -437.923686)
		(width 0.10668)
		(layer "F.Cu")
		(net "HPDB_HSC_PWRGD_N")
	)
	(via
		(at 284.317694 -437.923686)
		(size 0.762)
		(drill 0.381)
		(layers "F.Cu" "B.Cu")
		(net "HPDB_HSC_PWRGD_N")
	)
	(segment
		(start 279.022556 -436.623714)
		(end 281.183334 -436.623714)
		(width 0.10668)
		(layer "F.Cu")
		(net "HPDB_HSC_PWRGD_ISO")
	)
	(segment
		(start 205.615032 -116.673376)
		(end 206.530956 -116.673376)
		(width 0.10668)
		(layer "F.Cu")
		(net "HPDB_HSC_PWRGD_ISO")
	)
	(segment
		(start 278.006556 -436.623714)
		(end 279.022556 -436.623714)
		(width 0.10668)
		(layer "F.Cu")
		(net "HPDB_HSC_PWRGD_ISO")
	)
	(segment
		(start 277.714456 -436.331614)
		(end 278.006556 -436.623714)
		(width 0.10668)
		(layer "F.Cu")
		(net "HPDB_HSC_PWRGD_ISO")
	)
	(segment
		(start 276.61362 -436.331614)
		(end 277.714456 -436.331614)
		(width 0.10668)
		(layer "F.Cu")
		(net "HPDB_HSC_PWRGD_ISO")
	)
	(via
		(at 377.03633 -123.845828)
		(size 0.508)
		(drill 0.254)
		(layers "F.Cu" "B.Cu")
		(net "HPDB_HSC_PWRGD_ISO")
	)
	(via
		(at 206.530956 -116.673376)
		(size 0.508)
		(drill 0.254)
		(layers "F.Cu" "B.Cu")
		(net "HPDB_HSC_PWRGD_ISO")
	)
	(via
		(at 276.61362 -436.331614)
		(size 0.508)
		(drill 0.254)
		(layers "F.Cu" "B.Cu")
		(net "HPDB_HSC_PWRGD_ISO")
	)
	(segment
		(start 450.534278 -342.422988)
		(end 450.534278 -363.101382)
		(width 0.11684)
		(layer "In2.Cu")
		(net "HPDB_HSC_PWRGD_ISO")
	)
	(segment
		(start 424.930824 -399.988278)
		(end 426.23359 -401.291044)
		(width 0.11684)
		(layer "In2.Cu")
		(net "HPDB_HSC_PWRGD_ISO")
	)
	(segment
		(start 427.86046 -381.284734)
		(end 425.310554 -383.83464)
		(width 0.11684)
		(layer "In2.Cu")
		(net "HPDB_HSC_PWRGD_ISO")
	)
	(segment
		(start 424.930824 -398.094454)
		(end 424.930824 -399.988278)
		(width 0.11684)
		(layer "In2.Cu")
		(net "HPDB_HSC_PWRGD_ISO")
	)
	(segment
		(start 400.777964 -122.430032)
		(end 426.017436 -122.430032)
		(width 0.11684)
		(layer "In2.Cu")
		(net "HPDB_HSC_PWRGD_ISO")
	)
	(segment
		(start 424.930824 -392.071098)
		(end 424.930824 -395.774672)
		(width 0.11684)
		(layer "In2.Cu")
		(net "HPDB_HSC_PWRGD_ISO")
	)
	(segment
		(start 426.017436 -122.430032)
		(end 451.129146 -147.541742)
		(width 0.11684)
		(layer "In2.Cu")
		(net "HPDB_HSC_PWRGD_ISO")
	)
	(segment
		(start 437.592724 -368.503962)
		(end 427.86046 -378.236226)
		(width 0.11684)
		(layer "In2.Cu")
		(net "HPDB_HSC_PWRGD_ISO")
	)
	(segment
		(start 424.087544 -391.691114)
		(end 424.55084 -391.691114)
		(width 0.11684)
		(layer "In2.Cu")
		(net "HPDB_HSC_PWRGD_ISO")
	)
	(segment
		(start 292.20541 -408.005788)
		(end 291.898578 -408.31262)
		(width 0.11684)
		(layer "In2.Cu")
		(net "HPDB_HSC_PWRGD_ISO")
	)
	(segment
		(start 451.129146 -164.428424)
		(end 462.540096 -175.839374)
		(width 0.11684)
		(layer "In2.Cu")
		(net "HPDB_HSC_PWRGD_ISO")
	)
	(segment
		(start 276.61362 -434.726334)
		(end 276.61362 -436.331614)
		(width 0.11684)
		(layer "In2.Cu")
		(net "HPDB_HSC_PWRGD_ISO")
	)
	(segment
		(start 367.025682 -405.05761)
		(end 359.325926 -405.05761)
		(width 0.11684)
		(layer "In2.Cu")
		(net "HPDB_HSC_PWRGD_ISO")
	)
	(segment
		(start 288.666174 -408.31262)
		(end 288.235136 -408.743658)
		(width 0.11684)
		(layer "In2.Cu")
		(net "HPDB_HSC_PWRGD_ISO")
	)
	(segment
		(start 280.303478 -412.945834)
		(end 279.703784 -413.545528)
		(width 0.11684)
		(layer "In2.Cu")
		(net "HPDB_HSC_PWRGD_ISO")
	)
	(segment
		(start 426.23359 -402.033994)
		(end 423.011346 -405.256238)
		(width 0.11684)
		(layer "In2.Cu")
		(net "HPDB_HSC_PWRGD_ISO")
	)
	(segment
		(start 424.55084 -391.691114)
		(end 424.930824 -392.071098)
		(width 0.11684)
		(layer "In2.Cu")
		(net "HPDB_HSC_PWRGD_ISO")
	)
	(segment
		(start 280.303478 -410.535882)
		(end 280.303478 -412.945834)
		(width 0.11684)
		(layer "In2.Cu")
		(net "HPDB_HSC_PWRGD_ISO")
	)
	(segment
		(start 462.540096 -330.41717)
		(end 450.534278 -342.422988)
		(width 0.11684)
		(layer "In2.Cu")
		(net "HPDB_HSC_PWRGD_ISO")
	)
	(segment
		(start 424.930824 -395.774672)
		(end 424.55592 -396.149576)
		(width 0.11684)
		(layer "In2.Cu")
		(net "HPDB_HSC_PWRGD_ISO")
	)
	(segment
		(start 377.03633 -123.845828)
		(end 377.721876 -124.531374)
		(width 0.11684)
		(layer "In2.Cu")
		(net "HPDB_HSC_PWRGD_ISO")
	)
	(segment
		(start 367.22431 -405.256238)
		(end 367.025682 -405.05761)
		(width 0.11684)
		(layer "In2.Cu")
		(net "HPDB_HSC_PWRGD_ISO")
	)
	(segment
		(start 451.129146 -147.541742)
		(end 451.129146 -164.428424)
		(width 0.11684)
		(layer "In2.Cu")
		(net "HPDB_HSC_PWRGD_ISO")
	)
	(segment
		(start 427.86046 -378.236226)
		(end 427.86046 -381.284734)
		(width 0.11684)
		(layer "In2.Cu")
		(net "HPDB_HSC_PWRGD_ISO")
	)
	(segment
		(start 285.997142 -408.743658)
		(end 285.179516 -409.561284)
		(width 0.11684)
		(layer "In2.Cu")
		(net "HPDB_HSC_PWRGD_ISO")
	)
	(segment
		(start 300.797976 -406.59304)
		(end 299.385228 -408.005788)
		(width 0.11684)
		(layer "In2.Cu")
		(net "HPDB_HSC_PWRGD_ISO")
	)
	(segment
		(start 279.703784 -413.545528)
		(end 279.703784 -431.63617)
		(width 0.11684)
		(layer "In2.Cu")
		(net "HPDB_HSC_PWRGD_ISO")
	)
	(segment
		(start 425.310554 -383.83464)
		(end 424.192954 -383.83464)
		(width 0.11684)
		(layer "In2.Cu")
		(net "HPDB_HSC_PWRGD_ISO")
	)
	(segment
		(start 423.055542 -384.972052)
		(end 423.055542 -390.659112)
		(width 0.11684)
		(layer "In2.Cu")
		(net "HPDB_HSC_PWRGD_ISO")
	)
	(segment
		(start 377.721876 -124.531374)
		(end 398.676622 -124.531374)
		(width 0.11684)
		(layer "In2.Cu")
		(net "HPDB_HSC_PWRGD_ISO")
	)
	(segment
		(start 299.385228 -408.005788)
		(end 292.20541 -408.005788)
		(width 0.11684)
		(layer "In2.Cu")
		(net "HPDB_HSC_PWRGD_ISO")
	)
	(segment
		(start 462.540096 -175.839374)
		(end 462.540096 -330.41717)
		(width 0.11684)
		(layer "In2.Cu")
		(net "HPDB_HSC_PWRGD_ISO")
	)
	(segment
		(start 398.676622 -124.531374)
		(end 400.777964 -122.430032)
		(width 0.11684)
		(layer "In2.Cu")
		(net "HPDB_HSC_PWRGD_ISO")
	)
	(segment
		(start 424.55592 -397.71955)
		(end 424.930824 -398.094454)
		(width 0.11684)
		(layer "In2.Cu")
		(net "HPDB_HSC_PWRGD_ISO")
	)
	(segment
		(start 424.55592 -396.149576)
		(end 424.55592 -397.71955)
		(width 0.11684)
		(layer "In2.Cu")
		(net "HPDB_HSC_PWRGD_ISO")
	)
	(segment
		(start 285.179516 -409.561284)
		(end 281.278076 -409.561284)
		(width 0.11684)
		(layer "In2.Cu")
		(net "HPDB_HSC_PWRGD_ISO")
	)
	(segment
		(start 426.23359 -401.291044)
		(end 426.23359 -402.033994)
		(width 0.11684)
		(layer "In2.Cu")
		(net "HPDB_HSC_PWRGD_ISO")
	)
	(segment
		(start 359.325926 -405.05761)
		(end 357.790496 -406.59304)
		(width 0.11684)
		(layer "In2.Cu")
		(net "HPDB_HSC_PWRGD_ISO")
	)
	(segment
		(start 288.235136 -408.743658)
		(end 285.997142 -408.743658)
		(width 0.11684)
		(layer "In2.Cu")
		(net "HPDB_HSC_PWRGD_ISO")
	)
	(segment
		(start 423.055542 -390.659112)
		(end 424.087544 -391.691114)
		(width 0.11684)
		(layer "In2.Cu")
		(net "HPDB_HSC_PWRGD_ISO")
	)
	(segment
		(start 281.278076 -409.561284)
		(end 280.303478 -410.535882)
		(width 0.11684)
		(layer "In2.Cu")
		(net "HPDB_HSC_PWRGD_ISO")
	)
	(segment
		(start 423.011346 -405.256238)
		(end 367.22431 -405.256238)
		(width 0.11684)
		(layer "In2.Cu")
		(net "HPDB_HSC_PWRGD_ISO")
	)
	(segment
		(start 424.192954 -383.83464)
		(end 423.055542 -384.972052)
		(width 0.11684)
		(layer "In2.Cu")
		(net "HPDB_HSC_PWRGD_ISO")
	)
	(segment
		(start 450.534278 -363.101382)
		(end 445.131698 -368.503962)
		(width 0.11684)
		(layer "In2.Cu")
		(net "HPDB_HSC_PWRGD_ISO")
	)
	(segment
		(start 357.790496 -406.59304)
		(end 300.797976 -406.59304)
		(width 0.11684)
		(layer "In2.Cu")
		(net "HPDB_HSC_PWRGD_ISO")
	)
	(segment
		(start 291.898578 -408.31262)
		(end 288.666174 -408.31262)
		(width 0.11684)
		(layer "In2.Cu")
		(net "HPDB_HSC_PWRGD_ISO")
	)
	(segment
		(start 279.703784 -431.63617)
		(end 276.61362 -434.726334)
		(width 0.11684)
		(layer "In2.Cu")
		(net "HPDB_HSC_PWRGD_ISO")
	)
	(segment
		(start 445.131698 -368.503962)
		(end 437.592724 -368.503962)
		(width 0.11684)
		(layer "In2.Cu")
		(net "HPDB_HSC_PWRGD_ISO")
	)
	(segment
		(start 375.444512 -122.25401)
		(end 377.03633 -123.845828)
		(width 0.11684)
		(layer "In15.Cu")
		(net "HPDB_HSC_PWRGD_ISO")
	)
	(segment
		(start 292.55593 -127.878078)
		(end 297.509184 -122.924824)
		(width 0.11684)
		(layer "In15.Cu")
		(net "HPDB_HSC_PWRGD_ISO")
	)
	(segment
		(start 206.530956 -116.673376)
		(end 207.055212 -117.197632)
		(width 0.11684)
		(layer "In15.Cu")
		(net "HPDB_HSC_PWRGD_ISO")
	)
	(segment
		(start 348.783148 -122.25401)
		(end 375.444512 -122.25401)
		(width 0.11684)
		(layer "In15.Cu")
		(net "HPDB_HSC_PWRGD_ISO")
	)
	(segment
		(start 297.509184 -122.60707)
		(end 298.28236 -121.833894)
		(width 0.11684)
		(layer "In15.Cu")
		(net "HPDB_HSC_PWRGD_ISO")
	)
	(segment
		(start 297.509184 -122.924824)
		(end 297.509184 -122.60707)
		(width 0.11684)
		(layer "In15.Cu")
		(net "HPDB_HSC_PWRGD_ISO")
	)
	(segment
		(start 274.004278 -124.94133)
		(end 286.726376 -124.94133)
		(width 0.11684)
		(layer "In15.Cu")
		(net "HPDB_HSC_PWRGD_ISO")
	)
	(segment
		(start 242.218972 -118.780814)
		(end 245.571772 -118.780814)
		(width 0.11684)
		(layer "In15.Cu")
		(net "HPDB_HSC_PWRGD_ISO")
	)
	(segment
		(start 269.286228 -122.641868)
		(end 270.679418 -122.641868)
		(width 0.11684)
		(layer "In15.Cu")
		(net "HPDB_HSC_PWRGD_ISO")
	)
	(segment
		(start 215.596724 -117.197632)
		(end 215.737186 -117.338094)
		(width 0.11684)
		(layer "In15.Cu")
		(net "HPDB_HSC_PWRGD_ISO")
	)
	(segment
		(start 272.547588 -123.48464)
		(end 274.004278 -124.94133)
		(width 0.11684)
		(layer "In15.Cu")
		(net "HPDB_HSC_PWRGD_ISO")
	)
	(segment
		(start 286.726376 -124.94133)
		(end 289.663124 -127.878078)
		(width 0.11684)
		(layer "In15.Cu")
		(net "HPDB_HSC_PWRGD_ISO")
	)
	(segment
		(start 270.679418 -122.641868)
		(end 271.52219 -123.48464)
		(width 0.11684)
		(layer "In15.Cu")
		(net "HPDB_HSC_PWRGD_ISO")
	)
	(segment
		(start 259.16636 -119.115332)
		(end 260.995414 -120.944386)
		(width 0.11684)
		(layer "In15.Cu")
		(net "HPDB_HSC_PWRGD_ISO")
	)
	(segment
		(start 207.055212 -117.197632)
		(end 215.596724 -117.197632)
		(width 0.11684)
		(layer "In15.Cu")
		(net "HPDB_HSC_PWRGD_ISO")
	)
	(segment
		(start 264.028428 -120.944386)
		(end 266.04341 -122.959368)
		(width 0.11684)
		(layer "In15.Cu")
		(net "HPDB_HSC_PWRGD_ISO")
	)
	(segment
		(start 254.055372 -117.00383)
		(end 256.166874 -119.115332)
		(width 0.11684)
		(layer "In15.Cu")
		(net "HPDB_HSC_PWRGD_ISO")
	)
	(segment
		(start 247.348756 -117.00383)
		(end 254.055372 -117.00383)
		(width 0.11684)
		(layer "In15.Cu")
		(net "HPDB_HSC_PWRGD_ISO")
	)
	(segment
		(start 298.28236 -121.833894)
		(end 303.22266 -121.833894)
		(width 0.11684)
		(layer "In15.Cu")
		(net "HPDB_HSC_PWRGD_ISO")
	)
	(segment
		(start 289.663124 -127.878078)
		(end 292.55593 -127.878078)
		(width 0.11684)
		(layer "In15.Cu")
		(net "HPDB_HSC_PWRGD_ISO")
	)
	(segment
		(start 303.22266 -121.833894)
		(end 304.687986 -123.29922)
		(width 0.11684)
		(layer "In15.Cu")
		(net "HPDB_HSC_PWRGD_ISO")
	)
	(segment
		(start 266.04341 -122.959368)
		(end 268.968728 -122.959368)
		(width 0.11684)
		(layer "In15.Cu")
		(net "HPDB_HSC_PWRGD_ISO")
	)
	(segment
		(start 347.737938 -123.29922)
		(end 348.783148 -122.25401)
		(width 0.11684)
		(layer "In15.Cu")
		(net "HPDB_HSC_PWRGD_ISO")
	)
	(segment
		(start 245.571772 -118.780814)
		(end 247.348756 -117.00383)
		(width 0.11684)
		(layer "In15.Cu")
		(net "HPDB_HSC_PWRGD_ISO")
	)
	(segment
		(start 256.166874 -119.115332)
		(end 259.16636 -119.115332)
		(width 0.11684)
		(layer "In15.Cu")
		(net "HPDB_HSC_PWRGD_ISO")
	)
	(segment
		(start 304.687986 -123.29922)
		(end 347.737938 -123.29922)
		(width 0.11684)
		(layer "In15.Cu")
		(net "HPDB_HSC_PWRGD_ISO")
	)
	(segment
		(start 215.737186 -117.338094)
		(end 240.776252 -117.338094)
		(width 0.11684)
		(layer "In15.Cu")
		(net "HPDB_HSC_PWRGD_ISO")
	)
	(segment
		(start 240.776252 -117.338094)
		(end 242.218972 -118.780814)
		(width 0.11684)
		(layer "In15.Cu")
		(net "HPDB_HSC_PWRGD_ISO")
	)
	(segment
		(start 260.995414 -120.944386)
		(end 264.028428 -120.944386)
		(width 0.11684)
		(layer "In15.Cu")
		(net "HPDB_HSC_PWRGD_ISO")
	)
	(segment
		(start 268.968728 -122.959368)
		(end 269.286228 -122.641868)
		(width 0.11684)
		(layer "In15.Cu")
		(net "HPDB_HSC_PWRGD_ISO")
	)
	(segment
		(start 271.52219 -123.48464)
		(end 272.547588 -123.48464)
		(width 0.11684)
		(layer "In15.Cu")
		(net "HPDB_HSC_PWRGD_ISO")
	)
	(segment
		(start 279.860756 -437.601614)
		(end 279.022556 -437.601614)
		(width 0.10668)
		(layer "F.Cu")
		(net "HPDB_HSC_PWRGD")
	)
	(segment
		(start 281.183334 -437.2737)
		(end 280.18867 -437.2737)
		(width 0.10668)
		(layer "F.Cu")
		(net "HPDB_HSC_PWRGD")
	)
	(segment
		(start 280.18867 -437.2737)
		(end 279.860756 -437.601614)
		(width 0.10668)
		(layer "F.Cu")
		(net "HPDB_HSC_PWRGD")
	)
	(segment
		(start 279.022556 -437.601614)
		(end 278.006556 -437.601614)
		(width 0.10668)
		(layer "F.Cu")
		(net "HPDB_HSC_PWRGD")
	)
	(segment
		(start 278.006556 -437.601614)
		(end 276.61362 -437.601614)
		(width 0.10668)
		(layer "F.Cu")
		(net "HPDB_HSC_PWRGD")
	)
	(via
		(at 276.61362 -437.601614)
		(size 0.508)
		(drill 0.254)
		(layers "F.Cu" "B.Cu")
		(net "HPDB_HSC_PWRGD")
	)
	(via
		(at 235.660692 -421.833548)
		(size 0.508)
		(drill 0.254)
		(layers "F.Cu" "B.Cu")
		(net "HPDB_HSC_PWRGD")
	)
	(segment
		(start 235.660692 -422.449498)
		(end 235.660692 -421.833548)
		(width 0.10668)
		(layer "B.Cu")
		(net "HPDB_HSC_PWRGD")
	)
	(segment
		(start 277.120604 -428.167038)
		(end 274.134072 -425.180506)
		(width 0.11684)
		(layer "In2.Cu")
		(net "HPDB_HSC_PWRGD")
	)
	(segment
		(start 239.00765 -425.180506)
		(end 235.660692 -421.833548)
		(width 0.11684)
		(layer "In2.Cu")
		(net "HPDB_HSC_PWRGD")
	)
	(segment
		(start 277.120604 -429.85309)
		(end 277.120604 -428.167038)
		(width 0.11684)
		(layer "In2.Cu")
		(net "HPDB_HSC_PWRGD")
	)
	(segment
		(start 275.538438 -431.435256)
		(end 277.120604 -429.85309)
		(width 0.11684)
		(layer "In2.Cu")
		(net "HPDB_HSC_PWRGD")
	)
	(segment
		(start 276.61362 -437.601614)
		(end 275.538438 -436.526432)
		(width 0.11684)
		(layer "In2.Cu")
		(net "HPDB_HSC_PWRGD")
	)
	(segment
		(start 274.134072 -425.180506)
		(end 239.00765 -425.180506)
		(width 0.11684)
		(layer "In2.Cu")
		(net "HPDB_HSC_PWRGD")
	)
	(segment
		(start 275.538438 -436.526432)
		(end 275.538438 -431.435256)
		(width 0.11684)
		(layer "In2.Cu")
		(net "HPDB_HSC_PWRGD")
	)
	(segment
		(start 192.47358 -415.565082)
		(end 192.47358 -416.955986)
		(width 0.10668)
		(layer "F.Cu")
		(net "GPU_PRSNT_R")
	)
	(segment
		(start 193.48958 -414.924748)
		(end 193.198242 -415.216086)
		(width 0.10668)
		(layer "F.Cu")
		(net "GPU_PRSNT_R")
	)
	(segment
		(start 193.198242 -415.216086)
		(end 192.822576 -415.216086)
		(width 0.10668)
		(layer "F.Cu")
		(net "GPU_PRSNT_R")
	)
	(segment
		(start 193.48958 -414.364932)
		(end 193.48958 -414.924748)
		(width 0.10668)
		(layer "F.Cu")
		(net "GPU_PRSNT_R")
	)
	(segment
		(start 192.822576 -415.216086)
		(end 192.47358 -415.565082)
		(width 0.10668)
		(layer "F.Cu")
		(net "GPU_PRSNT_R")
	)
	(via
		(at 192.47358 -415.565082)
		(size 0.762)
		(drill 0.381)
		(layers "F.Cu" "B.Cu")
		(net "GPU_PRSNT_R")
	)
	(segment
		(start 207.449928 -160.500568)
		(end 207.449928 -159.816292)
		(width 0.10668)
		(layer "F.Cu")
		(net "FM_THERMAL_ALERT_N")
	)
	(segment
		(start 287.393634 -13.360146)
		(end 287.380426 -13.373354)
		(width 0.10668)
		(layer "F.Cu")
		(net "FM_THERMAL_ALERT_N")
	)
	(segment
		(start 219.199968 -180.984652)
		(end 213.022688 -166.073328)
		(width 0.10668)
		(layer "F.Cu")
		(net "FM_THERMAL_ALERT_N")
	)
	(segment
		(start 219.199968 -198.274178)
		(end 219.199968 -180.984652)
		(width 0.10668)
		(layer "F.Cu")
		(net "FM_THERMAL_ALERT_N")
	)
	(segment
		(start 101.346 -412.21152)
		(end 101.69652 -411.861)
		(width 0.10668)
		(layer "F.Cu")
		(net "FM_THERMAL_ALERT_N")
	)
	(segment
		(start 219.828364 -198.902574)
		(end 219.199968 -198.274178)
		(width 0.10668)
		(layer "F.Cu")
		(net "FM_THERMAL_ALERT_N")
	)
	(segment
		(start 101.346 -412.531052)
		(end 101.346 -412.21152)
		(width 0.10668)
		(layer "F.Cu")
		(net "FM_THERMAL_ALERT_N")
	)
	(segment
		(start 213.022688 -166.073328)
		(end 207.449928 -160.500568)
		(width 0.10668)
		(layer "F.Cu")
		(net "FM_THERMAL_ALERT_N")
	)
	(segment
		(start 286.971232 -13.69822)
		(end 286.240982 -14.42847)
		(width 0.10668)
		(layer "F.Cu")
		(net "FM_THERMAL_ALERT_N")
	)
	(segment
		(start 368.427 -412.496)
		(end 368.427 -413.23895)
		(width 0.10668)
		(layer "F.Cu")
		(net "FM_THERMAL_ALERT_N")
	)
	(segment
		(start 183.769 -92.274898)
		(end 183.769 -91.658948)
		(width 0.10668)
		(layer "F.Cu")
		(net "FM_THERMAL_ALERT_N")
	)
	(segment
		(start 100.285296 -412.531052)
		(end 101.346 -412.531052)
		(width 0.10668)
		(layer "F.Cu")
		(net "FM_THERMAL_ALERT_N")
	)
	(segment
		(start 368.427 -411.62605)
		(end 368.427 -412.496)
		(width 0.10668)
		(layer "F.Cu")
		(net "FM_THERMAL_ALERT_N")
	)
	(segment
		(start 106.53395 -13.909548)
		(end 105.92435 -13.909548)
		(width 0.10668)
		(layer "F.Cu")
		(net "FM_THERMAL_ALERT_N")
	)
	(segment
		(start 286.240982 -14.42847)
		(end 285.707836 -14.42847)
		(width 0.10668)
		(layer "F.Cu")
		(net "FM_THERMAL_ALERT_N")
	)
	(segment
		(start 287.993074 -13.360146)
		(end 287.393634 -13.360146)
		(width 0.10668)
		(layer "F.Cu")
		(net "FM_THERMAL_ALERT_N")
	)
	(segment
		(start 106.532172 -13.911326)
		(end 106.53395 -13.909548)
		(width 0.10668)
		(layer "F.Cu")
		(net "FM_THERMAL_ALERT_N")
	)
	(segment
		(start 106.532172 -15.22349)
		(end 106.532172 -13.911326)
		(width 0.10668)
		(layer "F.Cu")
		(net "FM_THERMAL_ALERT_N")
	)
	(segment
		(start 287.380426 -13.373354)
		(end 286.971232 -13.373354)
		(width 0.10668)
		(layer "F.Cu")
		(net "FM_THERMAL_ALERT_N")
	)
	(segment
		(start 286.971232 -13.373354)
		(end 286.971232 -13.69822)
		(width 0.10668)
		(layer "F.Cu")
		(net "FM_THERMAL_ALERT_N")
	)
	(via
		(at 292.533578 -422.56837)
		(size 0.508)
		(drill 0.254)
		(layers "F.Cu" "B.Cu")
		(net "FM_THERMAL_ALERT_N")
	)
	(via
		(at 183.769 -91.658948)
		(size 0.508)
		(drill 0.254)
		(layers "F.Cu" "B.Cu")
		(net "FM_THERMAL_ALERT_N")
	)
	(via
		(at 207.449928 -159.816292)
		(size 0.508)
		(drill 0.254)
		(layers "F.Cu" "B.Cu")
		(net "FM_THERMAL_ALERT_N")
	)
	(via
		(at 101.69652 -411.861)
		(size 0.508)
		(drill 0.254)
		(layers "F.Cu" "B.Cu")
		(net "FM_THERMAL_ALERT_N")
	)
	(via
		(at 172.747178 -394.79982)
		(size 0.508)
		(drill 0.254)
		(layers "F.Cu" "B.Cu")
		(net "FM_THERMAL_ALERT_N")
	)
	(via
		(at 368.427 -412.496)
		(size 0.508)
		(drill 0.254)
		(layers "F.Cu" "B.Cu")
		(net "FM_THERMAL_ALERT_N")
	)
	(via
		(at 285.707836 -14.42847)
		(size 0.508)
		(drill 0.254)
		(layers "F.Cu" "B.Cu")
		(net "FM_THERMAL_ALERT_N")
	)
	(via
		(at 107.107482 -397.589248)
		(size 0.508)
		(drill 0.254)
		(layers "F.Cu" "B.Cu")
		(net "FM_THERMAL_ALERT_N")
	)
	(via
		(at 160.22574 -31.010606)
		(size 0.508)
		(drill 0.254)
		(layers "F.Cu" "B.Cu")
		(net "FM_THERMAL_ALERT_N")
	)
	(via
		(at 207.943958 -90.52687)
		(size 0.508)
		(drill 0.254)
		(layers "F.Cu" "B.Cu")
		(net "FM_THERMAL_ALERT_N")
	)
	(via
		(at 219.828364 -198.902574)
		(size 0.508)
		(drill 0.254)
		(layers "F.Cu" "B.Cu")
		(net "FM_THERMAL_ALERT_N")
	)
	(via
		(at 105.92435 -13.909548)
		(size 0.508)
		(drill 0.254)
		(layers "F.Cu" "B.Cu")
		(net "FM_THERMAL_ALERT_N")
	)
	(via
		(at 221.206568 -33.494472)
		(size 0.508)
		(drill 0.254)
		(layers "F.Cu" "B.Cu")
		(net "FM_THERMAL_ALERT_N")
	)
	(segment
		(start 284.612334 -392.719052)
		(end 284.612334 -387.121908)
		(width 0.10668)
		(layer "B.Cu")
		(net "FM_THERMAL_ALERT_N")
	)
	(segment
		(start 288.4424 -407.512012)
		(end 288.4424 -405.9555)
		(width 0.10668)
		(layer "B.Cu")
		(net "FM_THERMAL_ALERT_N")
	)
	(segment
		(start 180.761386 -394.79982)
		(end 172.747178 -394.79982)
		(width 0.10668)
		(layer "B.Cu")
		(net "FM_THERMAL_ALERT_N")
	)
	(segment
		(start 182.615586 -392.94562)
		(end 180.761386 -394.79982)
		(width 0.10668)
		(layer "B.Cu")
		(net "FM_THERMAL_ALERT_N")
	)
	(segment
		(start 281.934412 -376.614944)
		(end 279.073356 -373.753888)
		(width 0.10668)
		(layer "B.Cu")
		(net "FM_THERMAL_ALERT_N")
	)
	(segment
		(start 281.934412 -384.443986)
		(end 281.934412 -376.614944)
		(width 0.10668)
		(layer "B.Cu")
		(net "FM_THERMAL_ALERT_N")
	)
	(segment
		(start 186.870086 -381.106934)
		(end 186.870086 -383.883916)
		(width 0.10668)
		(layer "B.Cu")
		(net "FM_THERMAL_ALERT_N")
	)
	(segment
		(start 186.870086 -383.883916)
		(end 182.615586 -388.138416)
		(width 0.10668)
		(layer "B.Cu")
		(net "FM_THERMAL_ALERT_N")
	)
	(segment
		(start 194.223132 -373.753888)
		(end 186.870086 -381.106934)
		(width 0.10668)
		(layer "B.Cu")
		(net "FM_THERMAL_ALERT_N")
	)
	(segment
		(start 292.533578 -422.56837)
		(end 292.533578 -411.60319)
		(width 0.10668)
		(layer "B.Cu")
		(net "FM_THERMAL_ALERT_N")
	)
	(segment
		(start 285.955486 -394.062204)
		(end 284.612334 -392.719052)
		(width 0.10668)
		(layer "B.Cu")
		(net "FM_THERMAL_ALERT_N")
	)
	(segment
		(start 182.615586 -388.138416)
		(end 182.615586 -392.94562)
		(width 0.10668)
		(layer "B.Cu")
		(net "FM_THERMAL_ALERT_N")
	)
	(segment
		(start 285.955486 -403.468586)
		(end 285.955486 -394.062204)
		(width 0.10668)
		(layer "B.Cu")
		(net "FM_THERMAL_ALERT_N")
	)
	(segment
		(start 292.533578 -411.60319)
		(end 288.4424 -407.512012)
		(width 0.10668)
		(layer "B.Cu")
		(net "FM_THERMAL_ALERT_N")
	)
	(segment
		(start 284.612334 -387.121908)
		(end 281.934412 -384.443986)
		(width 0.10668)
		(layer "B.Cu")
		(net "FM_THERMAL_ALERT_N")
	)
	(segment
		(start 288.4424 -405.9555)
		(end 285.955486 -403.468586)
		(width 0.10668)
		(layer "B.Cu")
		(net "FM_THERMAL_ALERT_N")
	)
	(segment
		(start 279.073356 -373.753888)
		(end 194.223132 -373.753888)
		(width 0.10668)
		(layer "B.Cu")
		(net "FM_THERMAL_ALERT_N")
	)
	(segment
		(start 237.42904 -41.123108)
		(end 237.42904 -38.694868)
		(width 0.11684)
		(layer "In2.Cu")
		(net "FM_THERMAL_ALERT_N")
	)
	(segment
		(start 232.3338 -37.958268)
		(end 231.79532 -38.496748)
		(width 0.11684)
		(layer "In2.Cu")
		(net "FM_THERMAL_ALERT_N")
	)
	(segment
		(start 265.120628 -37.70884)
		(end 246.9515 -37.70884)
		(width 0.11684)
		(layer "In2.Cu")
		(net "FM_THERMAL_ALERT_N")
	)
	(segment
		(start 110.72876 -396.09776)
		(end 109.702346 -397.124174)
		(width 0.11684)
		(layer "In2.Cu")
		(net "FM_THERMAL_ALERT_N")
	)
	(segment
		(start 172.747178 -395.173708)
		(end 170.940984 -396.979902)
		(width 0.11684)
		(layer "In2.Cu")
		(net "FM_THERMAL_ALERT_N")
	)
	(segment
		(start 221.206568 -35.711892)
		(end 221.206568 -33.494472)
		(width 0.11684)
		(layer "In2.Cu")
		(net "FM_THERMAL_ALERT_N")
	)
	(segment
		(start 302.617886 -421.448484)
		(end 297.117516 -421.448484)
		(width 0.11684)
		(layer "In2.Cu")
		(net "FM_THERMAL_ALERT_N")
	)
	(segment
		(start 115.94592 -396.503398)
		(end 115.540282 -396.09776)
		(width 0.11684)
		(layer "In2.Cu")
		(net "FM_THERMAL_ALERT_N")
	)
	(segment
		(start 364.041182 -416.881818)
		(end 361.647486 -416.881818)
		(width 0.11684)
		(layer "In2.Cu")
		(net "FM_THERMAL_ALERT_N")
	)
	(segment
		(start 238.34598 -42.040048)
		(end 237.42904 -41.123108)
		(width 0.11684)
		(layer "In2.Cu")
		(net "FM_THERMAL_ALERT_N")
	)
	(segment
		(start 237.42904 -38.694868)
		(end 236.69244 -37.958268)
		(width 0.11684)
		(layer "In2.Cu")
		(net "FM_THERMAL_ALERT_N")
	)
	(segment
		(start 361.647486 -416.881818)
		(end 360.476038 -418.053266)
		(width 0.11684)
		(layer "In2.Cu")
		(net "FM_THERMAL_ALERT_N")
	)
	(segment
		(start 167.51681 -396.979902)
		(end 167.040306 -396.503398)
		(width 0.11684)
		(layer "In2.Cu")
		(net "FM_THERMAL_ALERT_N")
	)
	(segment
		(start 283.17444 -19.655028)
		(end 265.120628 -37.70884)
		(width 0.11684)
		(layer "In2.Cu")
		(net "FM_THERMAL_ALERT_N")
	)
	(segment
		(start 358.467406 -417.779962)
		(end 356.48265 -417.779962)
		(width 0.11684)
		(layer "In2.Cu")
		(net "FM_THERMAL_ALERT_N")
	)
	(segment
		(start 352.224848 -422.037764)
		(end 303.207166 -422.037764)
		(width 0.11684)
		(layer "In2.Cu")
		(net "FM_THERMAL_ALERT_N")
	)
	(segment
		(start 360.476038 -418.053266)
		(end 358.74071 -418.053266)
		(width 0.11684)
		(layer "In2.Cu")
		(net "FM_THERMAL_ALERT_N")
	)
	(segment
		(start 297.117516 -421.448484)
		(end 296.410888 -422.155112)
		(width 0.11684)
		(layer "In2.Cu")
		(net "FM_THERMAL_ALERT_N")
	)
	(segment
		(start 285.707836 -14.42847)
		(end 283.17444 -16.961866)
		(width 0.11684)
		(layer "In2.Cu")
		(net "FM_THERMAL_ALERT_N")
	)
	(segment
		(start 236.69244 -37.958268)
		(end 232.3338 -37.958268)
		(width 0.11684)
		(layer "In2.Cu")
		(net "FM_THERMAL_ALERT_N")
	)
	(segment
		(start 294.168068 -422.56837)
		(end 292.533578 -422.56837)
		(width 0.11684)
		(layer "In2.Cu")
		(net "FM_THERMAL_ALERT_N")
	)
	(segment
		(start 244.071648 -40.588692)
		(end 242.380516 -40.588692)
		(width 0.11684)
		(layer "In2.Cu")
		(net "FM_THERMAL_ALERT_N")
	)
	(segment
		(start 242.380516 -40.588692)
		(end 240.92916 -42.040048)
		(width 0.11684)
		(layer "In2.Cu")
		(net "FM_THERMAL_ALERT_N")
	)
	(segment
		(start 246.9515 -37.70884)
		(end 244.071648 -40.588692)
		(width 0.11684)
		(layer "In2.Cu")
		(net "FM_THERMAL_ALERT_N")
	)
	(segment
		(start 358.74071 -418.053266)
		(end 358.467406 -417.779962)
		(width 0.11684)
		(layer "In2.Cu")
		(net "FM_THERMAL_ALERT_N")
	)
	(segment
		(start 294.581326 -422.155112)
		(end 294.168068 -422.56837)
		(width 0.11684)
		(layer "In2.Cu")
		(net "FM_THERMAL_ALERT_N")
	)
	(segment
		(start 170.940984 -396.979902)
		(end 167.51681 -396.979902)
		(width 0.11684)
		(layer "In2.Cu")
		(net "FM_THERMAL_ALERT_N")
	)
	(segment
		(start 167.040306 -396.503398)
		(end 115.94592 -396.503398)
		(width 0.11684)
		(layer "In2.Cu")
		(net "FM_THERMAL_ALERT_N")
	)
	(segment
		(start 296.410888 -422.155112)
		(end 294.581326 -422.155112)
		(width 0.11684)
		(layer "In2.Cu")
		(net "FM_THERMAL_ALERT_N")
	)
	(segment
		(start 172.747178 -394.79982)
		(end 172.747178 -395.173708)
		(width 0.11684)
		(layer "In2.Cu")
		(net "FM_THERMAL_ALERT_N")
	)
	(segment
		(start 231.79532 -38.496748)
		(end 223.991424 -38.496748)
		(width 0.11684)
		(layer "In2.Cu")
		(net "FM_THERMAL_ALERT_N")
	)
	(segment
		(start 368.427 -412.496)
		(end 364.041182 -416.881818)
		(width 0.11684)
		(layer "In2.Cu")
		(net "FM_THERMAL_ALERT_N")
	)
	(segment
		(start 115.540282 -396.09776)
		(end 110.72876 -396.09776)
		(width 0.11684)
		(layer "In2.Cu")
		(net "FM_THERMAL_ALERT_N")
	)
	(segment
		(start 240.92916 -42.040048)
		(end 238.34598 -42.040048)
		(width 0.11684)
		(layer "In2.Cu")
		(net "FM_THERMAL_ALERT_N")
	)
	(segment
		(start 356.48265 -417.779962)
		(end 352.224848 -422.037764)
		(width 0.11684)
		(layer "In2.Cu")
		(net "FM_THERMAL_ALERT_N")
	)
	(segment
		(start 283.17444 -16.961866)
		(end 283.17444 -19.655028)
		(width 0.11684)
		(layer "In2.Cu")
		(net "FM_THERMAL_ALERT_N")
	)
	(segment
		(start 107.572556 -397.124174)
		(end 107.107482 -397.589248)
		(width 0.11684)
		(layer "In2.Cu")
		(net "FM_THERMAL_ALERT_N")
	)
	(segment
		(start 109.702346 -397.124174)
		(end 107.572556 -397.124174)
		(width 0.11684)
		(layer "In2.Cu")
		(net "FM_THERMAL_ALERT_N")
	)
	(segment
		(start 303.207166 -422.037764)
		(end 302.617886 -421.448484)
		(width 0.11684)
		(layer "In2.Cu")
		(net "FM_THERMAL_ALERT_N")
	)
	(segment
		(start 223.991424 -38.496748)
		(end 221.206568 -35.711892)
		(width 0.11684)
		(layer "In2.Cu")
		(net "FM_THERMAL_ALERT_N")
	)
	(segment
		(start 168.168066 -35.602164)
		(end 167.684704 -36.085526)
		(width 0.11684)
		(layer "In4.Cu")
		(net "FM_THERMAL_ALERT_N")
	)
	(segment
		(start 160.22574 -31.435802)
		(end 160.22574 -31.010606)
		(width 0.11684)
		(layer "In4.Cu")
		(net "FM_THERMAL_ALERT_N")
	)
	(segment
		(start 183.46166 -89.580974)
		(end 183.46166 -86.786974)
		(width 0.11684)
		(layer "In4.Cu")
		(net "FM_THERMAL_ALERT_N")
	)
	(segment
		(start 185.288682 -83.246722)
		(end 185.288682 -45.865034)
		(width 0.11684)
		(layer "In4.Cu")
		(net "FM_THERMAL_ALERT_N")
	)
	(segment
		(start 172.439584 -35.602164)
		(end 168.168066 -35.602164)
		(width 0.11684)
		(layer "In4.Cu")
		(net "FM_THERMAL_ALERT_N")
	)
	(segment
		(start 183.769 -89.888314)
		(end 183.46166 -89.580974)
		(width 0.11684)
		(layer "In4.Cu")
		(net "FM_THERMAL_ALERT_N")
	)
	(segment
		(start 175.66005 -38.084252)
		(end 174.921672 -38.084252)
		(width 0.11684)
		(layer "In4.Cu")
		(net "FM_THERMAL_ALERT_N")
	)
	(segment
		(start 183.769 -91.658948)
		(end 183.769 -89.888314)
		(width 0.11684)
		(layer "In4.Cu")
		(net "FM_THERMAL_ALERT_N")
	)
	(segment
		(start 185.288682 -45.865034)
		(end 178.814476 -39.390828)
		(width 0.11684)
		(layer "In4.Cu")
		(net "FM_THERMAL_ALERT_N")
	)
	(segment
		(start 178.814476 -39.390828)
		(end 175.66005 -38.084252)
		(width 0.11684)
		(layer "In4.Cu")
		(net "FM_THERMAL_ALERT_N")
	)
	(segment
		(start 174.921672 -38.084252)
		(end 172.439584 -35.602164)
		(width 0.11684)
		(layer "In4.Cu")
		(net "FM_THERMAL_ALERT_N")
	)
	(segment
		(start 164.875464 -36.085526)
		(end 160.22574 -31.435802)
		(width 0.11684)
		(layer "In4.Cu")
		(net "FM_THERMAL_ALERT_N")
	)
	(segment
		(start 167.684704 -36.085526)
		(end 164.875464 -36.085526)
		(width 0.11684)
		(layer "In4.Cu")
		(net "FM_THERMAL_ALERT_N")
	)
	(segment
		(start 184.49798 -84.037424)
		(end 185.288682 -83.246722)
		(width 0.11684)
		(layer "In4.Cu")
		(net "FM_THERMAL_ALERT_N")
	)
	(segment
		(start 184.49798 -85.750654)
		(end 184.49798 -84.037424)
		(width 0.11684)
		(layer "In4.Cu")
		(net "FM_THERMAL_ALERT_N")
	)
	(segment
		(start 183.46166 -86.786974)
		(end 184.49798 -85.750654)
		(width 0.11684)
		(layer "In4.Cu")
		(net "FM_THERMAL_ALERT_N")
	)
	(segment
		(start 142.18158 -21.02358)
		(end 153.741628 -32.583628)
		(width 0.11684)
		(layer "In6.Cu")
		(net "FM_THERMAL_ALERT_N")
	)
	(segment
		(start 138.15822 -19.828764)
		(end 138.15822 -20.465796)
		(width 0.11684)
		(layer "In6.Cu")
		(net "FM_THERMAL_ALERT_N")
	)
	(segment
		(start 138.716004 -21.02358)
		(end 142.18158 -21.02358)
		(width 0.11684)
		(layer "In6.Cu")
		(net "FM_THERMAL_ALERT_N")
	)
	(segment
		(start 105.92435 -13.909548)
		(end 105.92435 -16.26235)
		(width 0.11684)
		(layer "In6.Cu")
		(net "FM_THERMAL_ALERT_N")
	)
	(segment
		(start 111.82096 -18.98142)
		(end 137.310876 -18.98142)
		(width 0.11684)
		(layer "In6.Cu")
		(net "FM_THERMAL_ALERT_N")
	)
	(segment
		(start 105.92435 -16.26235)
		(end 109.0168 -19.3548)
		(width 0.11684)
		(layer "In6.Cu")
		(net "FM_THERMAL_ALERT_N")
	)
	(segment
		(start 109.0168 -19.3548)
		(end 111.44758 -19.3548)
		(width 0.11684)
		(layer "In6.Cu")
		(net "FM_THERMAL_ALERT_N")
	)
	(segment
		(start 111.44758 -19.3548)
		(end 111.82096 -18.98142)
		(width 0.11684)
		(layer "In6.Cu")
		(net "FM_THERMAL_ALERT_N")
	)
	(segment
		(start 137.310876 -18.98142)
		(end 138.15822 -19.828764)
		(width 0.11684)
		(layer "In6.Cu")
		(net "FM_THERMAL_ALERT_N")
	)
	(segment
		(start 153.741628 -32.583628)
		(end 158.206186 -32.583628)
		(width 0.11684)
		(layer "In6.Cu")
		(net "FM_THERMAL_ALERT_N")
	)
	(segment
		(start 158.206186 -32.583628)
		(end 159.779208 -31.010606)
		(width 0.11684)
		(layer "In6.Cu")
		(net "FM_THERMAL_ALERT_N")
	)
	(segment
		(start 138.15822 -20.465796)
		(end 138.716004 -21.02358)
		(width 0.11684)
		(layer "In6.Cu")
		(net "FM_THERMAL_ALERT_N")
	)
	(segment
		(start 159.779208 -31.010606)
		(end 160.22574 -31.010606)
		(width 0.11684)
		(layer "In6.Cu")
		(net "FM_THERMAL_ALERT_N")
	)
	(segment
		(start 209.624422 -92.207334)
		(end 207.943958 -90.52687)
		(width 0.11684)
		(layer "In11.Cu")
		(net "FM_THERMAL_ALERT_N")
	)
	(segment
		(start 209.643726 -92.207334)
		(end 209.624422 -92.207334)
		(width 0.11684)
		(layer "In11.Cu")
		(net "FM_THERMAL_ALERT_N")
	)
	(segment
		(start 105.431082 -403.478746)
		(end 105.431082 -398.324578)
		(width 0.11684)
		(layer "In11.Cu")
		(net "FM_THERMAL_ALERT_N")
	)
	(segment
		(start 212.243162 -105.350564)
		(end 212.243162 -103.167688)
		(width 0.11684)
		(layer "In11.Cu")
		(net "FM_THERMAL_ALERT_N")
	)
	(segment
		(start 207.411066 -136.064752)
		(end 207.411066 -132.45084)
		(width 0.11684)
		(layer "In11.Cu")
		(net "FM_THERMAL_ALERT_N")
	)
	(segment
		(start 211.25942 -109.953806)
		(end 211.25942 -106.334306)
		(width 0.11684)
		(layer "In11.Cu")
		(net "FM_THERMAL_ALERT_N")
	)
	(segment
		(start 211.453476 -100.458016)
		(end 210.741514 -99.746054)
		(width 0.11684)
		(layer "In11.Cu")
		(net "FM_THERMAL_ALERT_N")
	)
	(segment
		(start 210.378548 -97.529396)
		(end 210.378548 -92.942156)
		(width 0.11684)
		(layer "In11.Cu")
		(net "FM_THERMAL_ALERT_N")
	)
	(segment
		(start 208.876138 -126.967234)
		(end 208.876138 -114.706654)
		(width 0.11684)
		(layer "In11.Cu")
		(net "FM_THERMAL_ALERT_N")
	)
	(segment
		(start 208.110074 -131.751832)
		(end 208.110074 -127.733298)
		(width 0.11684)
		(layer "In11.Cu")
		(net "FM_THERMAL_ALERT_N")
	)
	(segment
		(start 212.243162 -103.167688)
		(end 211.453476 -102.378002)
		(width 0.11684)
		(layer "In11.Cu")
		(net "FM_THERMAL_ALERT_N")
	)
	(segment
		(start 106.997754 -397.47952)
		(end 107.107482 -397.589248)
		(width 0.11684)
		(layer "In11.Cu")
		(net "FM_THERMAL_ALERT_N")
	)
	(segment
		(start 208.876138 -114.706654)
		(end 209.848196 -113.734596)
		(width 0.11684)
		(layer "In11.Cu")
		(net "FM_THERMAL_ALERT_N")
	)
	(segment
		(start 209.848196 -113.734596)
		(end 209.848196 -111.36503)
		(width 0.11684)
		(layer "In11.Cu")
		(net "FM_THERMAL_ALERT_N")
	)
	(segment
		(start 100.514404 -408.395424)
		(end 105.431082 -403.478746)
		(width 0.11684)
		(layer "In11.Cu")
		(net "FM_THERMAL_ALERT_N")
	)
	(segment
		(start 207.411066 -132.45084)
		(end 208.110074 -131.751832)
		(width 0.11684)
		(layer "In11.Cu")
		(net "FM_THERMAL_ALERT_N")
	)
	(segment
		(start 210.378548 -92.942156)
		(end 209.643726 -92.207334)
		(width 0.11684)
		(layer "In11.Cu")
		(net "FM_THERMAL_ALERT_N")
	)
	(segment
		(start 203.303124 -149.831298)
		(end 203.303124 -140.172694)
		(width 0.11684)
		(layer "In11.Cu")
		(net "FM_THERMAL_ALERT_N")
	)
	(segment
		(start 101.69652 -411.861)
		(end 100.514404 -410.678884)
		(width 0.11684)
		(layer "In11.Cu")
		(net "FM_THERMAL_ALERT_N")
	)
	(segment
		(start 105.431082 -398.324578)
		(end 106.27614 -397.47952)
		(width 0.11684)
		(layer "In11.Cu")
		(net "FM_THERMAL_ALERT_N")
	)
	(segment
		(start 100.514404 -410.678884)
		(end 100.514404 -408.395424)
		(width 0.11684)
		(layer "In11.Cu")
		(net "FM_THERMAL_ALERT_N")
	)
	(segment
		(start 207.449928 -159.816292)
		(end 207.449928 -153.978102)
		(width 0.11684)
		(layer "In11.Cu")
		(net "FM_THERMAL_ALERT_N")
	)
	(segment
		(start 203.303124 -140.172694)
		(end 207.411066 -136.064752)
		(width 0.11684)
		(layer "In11.Cu")
		(net "FM_THERMAL_ALERT_N")
	)
	(segment
		(start 211.25942 -106.334306)
		(end 212.243162 -105.350564)
		(width 0.11684)
		(layer "In11.Cu")
		(net "FM_THERMAL_ALERT_N")
	)
	(segment
		(start 211.453476 -102.378002)
		(end 211.453476 -100.458016)
		(width 0.11684)
		(layer "In11.Cu")
		(net "FM_THERMAL_ALERT_N")
	)
	(segment
		(start 210.741514 -97.892362)
		(end 210.378548 -97.529396)
		(width 0.11684)
		(layer "In11.Cu")
		(net "FM_THERMAL_ALERT_N")
	)
	(segment
		(start 209.848196 -111.36503)
		(end 211.25942 -109.953806)
		(width 0.11684)
		(layer "In11.Cu")
		(net "FM_THERMAL_ALERT_N")
	)
	(segment
		(start 208.110074 -127.733298)
		(end 208.876138 -126.967234)
		(width 0.11684)
		(layer "In11.Cu")
		(net "FM_THERMAL_ALERT_N")
	)
	(segment
		(start 106.27614 -397.47952)
		(end 106.997754 -397.47952)
		(width 0.11684)
		(layer "In11.Cu")
		(net "FM_THERMAL_ALERT_N")
	)
	(segment
		(start 210.741514 -99.746054)
		(end 210.741514 -97.892362)
		(width 0.11684)
		(layer "In11.Cu")
		(net "FM_THERMAL_ALERT_N")
	)
	(segment
		(start 207.449928 -153.978102)
		(end 203.303124 -149.831298)
		(width 0.11684)
		(layer "In11.Cu")
		(net "FM_THERMAL_ALERT_N")
	)
	(segment
		(start 146.31797 -9.34466)
		(end 146.87804 -9.90473)
		(width 0.11684)
		(layer "In15.Cu")
		(net "FM_THERMAL_ALERT_N")
	)
	(segment
		(start 193.729356 -367.66627)
		(end 219.009214 -342.386412)
		(width 0.11684)
		(layer "In15.Cu")
		(net "FM_THERMAL_ALERT_N")
	)
	(segment
		(start 172.747178 -394.79982)
		(end 173.478444 -394.068554)
		(width 0.11684)
		(layer "In15.Cu")
		(net "FM_THERMAL_ALERT_N")
	)
	(segment
		(start 186.273186 -380.32944)
		(end 186.273186 -370.15928)
		(width 0.11684)
		(layer "In15.Cu")
		(net "FM_THERMAL_ALERT_N")
	)
	(segment
		(start 152.791922 -9.90473)
		(end 154.30373 -8.392922)
		(width 0.11684)
		(layer "In15.Cu")
		(net "FM_THERMAL_ALERT_N")
	)
	(segment
		(start 154.30373 -8.392922)
		(end 157.799278 -8.392922)
		(width 0.11684)
		(layer "In15.Cu")
		(net "FM_THERMAL_ALERT_N")
	)
	(segment
		(start 159.266128 -9.859772)
		(end 169.27957 -9.859772)
		(width 0.11684)
		(layer "In15.Cu")
		(net "FM_THERMAL_ALERT_N")
	)
	(segment
		(start 188.766196 -367.66627)
		(end 193.729356 -367.66627)
		(width 0.11684)
		(layer "In15.Cu")
		(net "FM_THERMAL_ALERT_N")
	)
	(segment
		(start 219.009214 -327.77303)
		(end 212.784182 -321.547998)
		(width 0.11684)
		(layer "In15.Cu")
		(net "FM_THERMAL_ALERT_N")
	)
	(segment
		(start 183.190642 -8.896604)
		(end 189.395608 -8.896604)
		(width 0.11684)
		(layer "In15.Cu")
		(net "FM_THERMAL_ALERT_N")
	)
	(segment
		(start 120.37187 -17.28089)
		(end 125.62459 -17.28089)
		(width 0.11684)
		(layer "In15.Cu")
		(net "FM_THERMAL_ALERT_N")
	)
	(segment
		(start 117.49786 -20.1549)
		(end 120.37187 -17.28089)
		(width 0.11684)
		(layer "In15.Cu")
		(net "FM_THERMAL_ALERT_N")
	)
	(segment
		(start 210.318604 -20.612354)
		(end 210.318604 -23.704042)
		(width 0.11684)
		(layer "In15.Cu")
		(net "FM_THERMAL_ALERT_N")
	)
	(segment
		(start 217.711274 -26.974546)
		(end 221.206568 -30.46984)
		(width 0.11684)
		(layer "In15.Cu")
		(net "FM_THERMAL_ALERT_N")
	)
	(segment
		(start 105.92435 -15.34795)
		(end 107.52582 -16.94942)
		(width 0.11684)
		(layer "In15.Cu")
		(net "FM_THERMAL_ALERT_N")
	)
	(segment
		(start 186.273186 -370.15928)
		(end 188.766196 -367.66627)
		(width 0.11684)
		(layer "In15.Cu")
		(net "FM_THERMAL_ALERT_N")
	)
	(segment
		(start 171.228258 -7.911084)
		(end 173.920404 -7.911084)
		(width 0.11684)
		(layer "In15.Cu")
		(net "FM_THERMAL_ALERT_N")
	)
	(segment
		(start 189.395608 -8.896604)
		(end 190.54064 -10.041636)
		(width 0.11684)
		(layer "In15.Cu")
		(net "FM_THERMAL_ALERT_N")
	)
	(segment
		(start 131.421632 -9.34466)
		(end 146.31797 -9.34466)
		(width 0.11684)
		(layer "In15.Cu")
		(net "FM_THERMAL_ALERT_N")
	)
	(segment
		(start 146.87804 -9.90473)
		(end 152.791922 -9.90473)
		(width 0.11684)
		(layer "In15.Cu")
		(net "FM_THERMAL_ALERT_N")
	)
	(segment
		(start 184.25414 -91.173808)
		(end 187.947046 -91.173808)
		(width 0.11684)
		(layer "In15.Cu")
		(net "FM_THERMAL_ALERT_N")
	)
	(segment
		(start 196.50837 -90.436192)
		(end 197.842632 -91.770454)
		(width 0.11684)
		(layer "In15.Cu")
		(net "FM_THERMAL_ALERT_N")
	)
	(segment
		(start 212.784182 -202.727814)
		(end 216.609422 -198.902574)
		(width 0.11684)
		(layer "In15.Cu")
		(net "FM_THERMAL_ALERT_N")
	)
	(segment
		(start 129.203704 -13.701776)
		(end 129.203704 -11.562588)
		(width 0.11684)
		(layer "In15.Cu")
		(net "FM_THERMAL_ALERT_N")
	)
	(segment
		(start 210.318604 -23.704042)
		(end 213.589108 -26.974546)
		(width 0.11684)
		(layer "In15.Cu")
		(net "FM_THERMAL_ALERT_N")
	)
	(segment
		(start 197.842632 -91.770454)
		(end 204.173582 -91.770454)
		(width 0.11684)
		(layer "In15.Cu")
		(net "FM_THERMAL_ALERT_N")
	)
	(segment
		(start 169.27957 -9.859772)
		(end 171.228258 -7.911084)
		(width 0.11684)
		(layer "In15.Cu")
		(net "FM_THERMAL_ALERT_N")
	)
	(segment
		(start 176.115726 -10.106406)
		(end 181.98084 -10.106406)
		(width 0.11684)
		(layer "In15.Cu")
		(net "FM_THERMAL_ALERT_N")
	)
	(segment
		(start 157.799278 -8.392922)
		(end 159.266128 -9.859772)
		(width 0.11684)
		(layer "In15.Cu")
		(net "FM_THERMAL_ALERT_N")
	)
	(segment
		(start 173.920404 -7.911084)
		(end 176.115726 -10.106406)
		(width 0.11684)
		(layer "In15.Cu")
		(net "FM_THERMAL_ALERT_N")
	)
	(segment
		(start 181.98084 -10.106406)
		(end 183.190642 -8.896604)
		(width 0.11684)
		(layer "In15.Cu")
		(net "FM_THERMAL_ALERT_N")
	)
	(segment
		(start 205.417166 -90.52687)
		(end 207.943958 -90.52687)
		(width 0.11684)
		(layer "In15.Cu")
		(net "FM_THERMAL_ALERT_N")
	)
	(segment
		(start 213.589108 -26.974546)
		(end 217.711274 -26.974546)
		(width 0.11684)
		(layer "In15.Cu")
		(net "FM_THERMAL_ALERT_N")
	)
	(segment
		(start 107.52582 -16.94942)
		(end 107.52582 -18.4912)
		(width 0.11684)
		(layer "In15.Cu")
		(net "FM_THERMAL_ALERT_N")
	)
	(segment
		(start 187.947046 -91.173808)
		(end 188.684662 -90.436192)
		(width 0.11684)
		(layer "In15.Cu")
		(net "FM_THERMAL_ALERT_N")
	)
	(segment
		(start 221.206568 -30.46984)
		(end 221.206568 -33.494472)
		(width 0.11684)
		(layer "In15.Cu")
		(net "FM_THERMAL_ALERT_N")
	)
	(segment
		(start 107.52582 -18.4912)
		(end 109.18952 -20.1549)
		(width 0.11684)
		(layer "In15.Cu")
		(net "FM_THERMAL_ALERT_N")
	)
	(segment
		(start 190.54064 -13.41628)
		(end 191.285114 -14.160754)
		(width 0.11684)
		(layer "In15.Cu")
		(net "FM_THERMAL_ALERT_N")
	)
	(segment
		(start 212.784182 -321.547998)
		(end 212.784182 -202.727814)
		(width 0.11684)
		(layer "In15.Cu")
		(net "FM_THERMAL_ALERT_N")
	)
	(segment
		(start 129.203704 -11.562588)
		(end 131.421632 -9.34466)
		(width 0.11684)
		(layer "In15.Cu")
		(net "FM_THERMAL_ALERT_N")
	)
	(segment
		(start 109.18952 -20.1549)
		(end 117.49786 -20.1549)
		(width 0.11684)
		(layer "In15.Cu")
		(net "FM_THERMAL_ALERT_N")
	)
	(segment
		(start 125.62459 -17.28089)
		(end 129.203704 -13.701776)
		(width 0.11684)
		(layer "In15.Cu")
		(net "FM_THERMAL_ALERT_N")
	)
	(segment
		(start 190.54064 -10.041636)
		(end 190.54064 -13.41628)
		(width 0.11684)
		(layer "In15.Cu")
		(net "FM_THERMAL_ALERT_N")
	)
	(segment
		(start 188.684662 -90.436192)
		(end 196.50837 -90.436192)
		(width 0.11684)
		(layer "In15.Cu")
		(net "FM_THERMAL_ALERT_N")
	)
	(segment
		(start 173.478444 -393.124182)
		(end 186.273186 -380.32944)
		(width 0.11684)
		(layer "In15.Cu")
		(net "FM_THERMAL_ALERT_N")
	)
	(segment
		(start 173.478444 -394.068554)
		(end 173.478444 -393.124182)
		(width 0.11684)
		(layer "In15.Cu")
		(net "FM_THERMAL_ALERT_N")
	)
	(segment
		(start 105.92435 -13.909548)
		(end 105.92435 -15.34795)
		(width 0.11684)
		(layer "In15.Cu")
		(net "FM_THERMAL_ALERT_N")
	)
	(segment
		(start 183.769 -91.658948)
		(end 184.25414 -91.173808)
		(width 0.11684)
		(layer "In15.Cu")
		(net "FM_THERMAL_ALERT_N")
	)
	(segment
		(start 204.173582 -91.770454)
		(end 205.417166 -90.52687)
		(width 0.11684)
		(layer "In15.Cu")
		(net "FM_THERMAL_ALERT_N")
	)
	(segment
		(start 203.867004 -14.160754)
		(end 210.318604 -20.612354)
		(width 0.11684)
		(layer "In15.Cu")
		(net "FM_THERMAL_ALERT_N")
	)
	(segment
		(start 216.609422 -198.902574)
		(end 219.828364 -198.902574)
		(width 0.11684)
		(layer "In15.Cu")
		(net "FM_THERMAL_ALERT_N")
	)
	(segment
		(start 191.285114 -14.160754)
		(end 203.867004 -14.160754)
		(width 0.11684)
		(layer "In15.Cu")
		(net "FM_THERMAL_ALERT_N")
	)
	(segment
		(start 219.009214 -342.386412)
		(end 219.009214 -327.77303)
		(width 0.11684)
		(layer "In15.Cu")
		(net "FM_THERMAL_ALERT_N")
	)
	(segment
		(start 189.12205 -118.652798)
		(end 189.51194 -119.042688)
		(width 0.10668)
		(layer "F.Cu")
		(net "FM_P5V_EN")
	)
	(segment
		(start 148.894292 -108.699046)
		(end 149.535642 -108.699046)
		(width 0.10668)
		(layer "F.Cu")
		(net "FM_P5V_EN")
	)
	(via
		(at 189.51194 -119.042688)
		(size 0.4572)
		(drill 0.254)
		(layers "F.Cu" "B.Cu")
		(net "FM_P5V_EN")
	)
	(via
		(at 158.592774 -127.95631)
		(size 0.508)
		(drill 0.254)
		(layers "F.Cu" "B.Cu")
		(net "FM_P5V_EN")
	)
	(via
		(at 149.535642 -108.699046)
		(size 0.508)
		(drill 0.254)
		(layers "F.Cu" "B.Cu")
		(net "FM_P5V_EN")
	)
	(via
		(at 191.173608 -128.042924)
		(size 0.508)
		(drill 0.254)
		(layers "F.Cu" "B.Cu")
		(net "FM_P5V_EN")
	)
	(segment
		(start 191.782446 -126.065026)
		(end 191.591184 -126.256288)
		(width 0.10668)
		(layer "B.Cu")
		(net "FM_P5V_EN")
	)
	(segment
		(start 189.90818 -122.502168)
		(end 190.045848 -122.639836)
		(width 0.10668)
		(layer "B.Cu")
		(net "FM_P5V_EN")
	)
	(segment
		(start 191.782446 -125.625606)
		(end 191.782446 -126.065026)
		(width 0.10668)
		(layer "B.Cu")
		(net "FM_P5V_EN")
	)
	(segment
		(start 190.713868 -122.832876)
		(end 190.713868 -123.986036)
		(width 0.10668)
		(layer "B.Cu")
		(net "FM_P5V_EN")
	)
	(segment
		(start 191.591184 -127.625348)
		(end 191.173608 -128.042924)
		(width 0.10668)
		(layer "B.Cu")
		(net "FM_P5V_EN")
	)
	(segment
		(start 190.713868 -123.986036)
		(end 190.715646 -123.987814)
		(width 0.10668)
		(layer "B.Cu")
		(net "FM_P5V_EN")
	)
	(segment
		(start 189.668658 -121.838974)
		(end 189.90818 -122.078496)
		(width 0.10668)
		(layer "B.Cu")
		(net "FM_P5V_EN")
	)
	(segment
		(start 189.1157 -121.607072)
		(end 189.347602 -121.838974)
		(width 0.10668)
		(layer "B.Cu")
		(net "FM_P5V_EN")
	)
	(segment
		(start 189.90818 -122.078496)
		(end 189.90818 -122.502168)
		(width 0.10668)
		(layer "B.Cu")
		(net "FM_P5V_EN")
	)
	(segment
		(start 189.51194 -119.042688)
		(end 189.1157 -119.438928)
		(width 0.10668)
		(layer "B.Cu")
		(net "FM_P5V_EN")
	)
	(segment
		(start 191.591184 -126.256288)
		(end 191.591184 -127.625348)
		(width 0.10668)
		(layer "B.Cu")
		(net "FM_P5V_EN")
	)
	(segment
		(start 190.866268 -124.15774)
		(end 190.866268 -124.709428)
		(width 0.10668)
		(layer "B.Cu")
		(net "FM_P5V_EN")
	)
	(segment
		(start 190.045848 -122.639836)
		(end 190.520828 -122.639836)
		(width 0.10668)
		(layer "B.Cu")
		(net "FM_P5V_EN")
	)
	(segment
		(start 190.520828 -122.639836)
		(end 190.713868 -122.832876)
		(width 0.10668)
		(layer "B.Cu")
		(net "FM_P5V_EN")
	)
	(segment
		(start 190.866268 -124.709428)
		(end 191.782446 -125.625606)
		(width 0.10668)
		(layer "B.Cu")
		(net "FM_P5V_EN")
	)
	(segment
		(start 189.347602 -121.838974)
		(end 189.668658 -121.838974)
		(width 0.10668)
		(layer "B.Cu")
		(net "FM_P5V_EN")
	)
	(segment
		(start 190.715646 -123.987814)
		(end 190.715646 -124.007118)
		(width 0.10668)
		(layer "B.Cu")
		(net "FM_P5V_EN")
	)
	(segment
		(start 189.1157 -119.438928)
		(end 189.1157 -121.607072)
		(width 0.10668)
		(layer "B.Cu")
		(net "FM_P5V_EN")
	)
	(segment
		(start 190.715646 -124.007118)
		(end 190.866268 -124.15774)
		(width 0.10668)
		(layer "B.Cu")
		(net "FM_P5V_EN")
	)
	(segment
		(start 162.315652 -127.95631)
		(end 163.046918 -127.225044)
		(width 0.11684)
		(layer "In6.Cu")
		(net "FM_P5V_EN")
	)
	(segment
		(start 174.34179 -128.042924)
		(end 191.173608 -128.042924)
		(width 0.11684)
		(layer "In6.Cu")
		(net "FM_P5V_EN")
	)
	(segment
		(start 173.907958 -127.609092)
		(end 174.34179 -128.042924)
		(width 0.11684)
		(layer "In6.Cu")
		(net "FM_P5V_EN")
	)
	(segment
		(start 165.698932 -127.851916)
		(end 165.941756 -127.609092)
		(width 0.11684)
		(layer "In6.Cu")
		(net "FM_P5V_EN")
	)
	(segment
		(start 164.731954 -127.851916)
		(end 165.698932 -127.851916)
		(width 0.11684)
		(layer "In6.Cu")
		(net "FM_P5V_EN")
	)
	(segment
		(start 165.941756 -127.609092)
		(end 173.907958 -127.609092)
		(width 0.11684)
		(layer "In6.Cu")
		(net "FM_P5V_EN")
	)
	(segment
		(start 158.592774 -127.95631)
		(end 162.315652 -127.95631)
		(width 0.11684)
		(layer "In6.Cu")
		(net "FM_P5V_EN")
	)
	(segment
		(start 163.046918 -127.225044)
		(end 164.105082 -127.225044)
		(width 0.11684)
		(layer "In6.Cu")
		(net "FM_P5V_EN")
	)
	(segment
		(start 164.105082 -127.225044)
		(end 164.731954 -127.851916)
		(width 0.11684)
		(layer "In6.Cu")
		(net "FM_P5V_EN")
	)
	(segment
		(start 154.837638 -118.85041)
		(end 154.837638 -122.927618)
		(width 0.11684)
		(layer "In11.Cu")
		(net "FM_P5V_EN")
	)
	(segment
		(start 158.563056 -127.986028)
		(end 158.592774 -127.95631)
		(width 0.11684)
		(layer "In11.Cu")
		(net "FM_P5V_EN")
	)
	(segment
		(start 154.837638 -122.927618)
		(end 155.897326 -125.485906)
		(width 0.11684)
		(layer "In11.Cu")
		(net "FM_P5V_EN")
	)
	(segment
		(start 154.134058 -113.446814)
		(end 154.134058 -118.14683)
		(width 0.11684)
		(layer "In11.Cu")
		(net "FM_P5V_EN")
	)
	(segment
		(start 154.134058 -118.14683)
		(end 154.837638 -118.85041)
		(width 0.11684)
		(layer "In11.Cu")
		(net "FM_P5V_EN")
	)
	(segment
		(start 155.897326 -125.485906)
		(end 158.397448 -127.986028)
		(width 0.11684)
		(layer "In11.Cu")
		(net "FM_P5V_EN")
	)
	(segment
		(start 158.397448 -127.986028)
		(end 158.563056 -127.986028)
		(width 0.11684)
		(layer "In11.Cu")
		(net "FM_P5V_EN")
	)
	(segment
		(start 149.535642 -108.699046)
		(end 149.535642 -108.848398)
		(width 0.11684)
		(layer "In11.Cu")
		(net "FM_P5V_EN")
	)
	(segment
		(start 149.535642 -108.848398)
		(end 154.134058 -113.446814)
		(width 0.11684)
		(layer "In11.Cu")
		(net "FM_P5V_EN")
	)
	(segment
		(start 205.712568 -143.532098)
		(end 205.693518 -143.513048)
		(width 0.10668)
		(layer "F.Cu")
		(net "FM_P12V_HSC_EN_R_N")
	)
	(segment
		(start 208.622138 -143.532098)
		(end 206.998316 -143.532098)
		(width 0.10668)
		(layer "F.Cu")
		(net "FM_P12V_HSC_EN_R_N")
	)
	(segment
		(start 206.998316 -143.532098)
		(end 205.712568 -143.532098)
		(width 0.10668)
		(layer "F.Cu")
		(net "FM_P12V_HSC_EN_R_N")
	)
	(via
		(at 206.998316 -143.532098)
		(size 0.762)
		(drill 0.381)
		(layers "F.Cu" "B.Cu")
		(net "FM_P12V_HSC_EN_R_N")
	)
	(segment
		(start 211.0613 -136.45261)
		(end 212.570822 -136.45261)
		(width 0.10668)
		(layer "F.Cu")
		(net "FM_P12V_HSC_EN_R")
	)
	(segment
		(start 212.570822 -136.45261)
		(end 213.8426 -137.724388)
		(width 0.10668)
		(layer "F.Cu")
		(net "FM_P12V_HSC_EN_R")
	)
	(segment
		(start 210.786218 -136.177528)
		(end 211.0613 -136.45261)
		(width 0.10668)
		(layer "F.Cu")
		(net "FM_P12V_HSC_EN_R")
	)
	(via
		(at 212.570822 -136.45261)
		(size 0.762)
		(drill 0.381)
		(layers "F.Cu" "B.Cu")
		(net "FM_P12V_HSC_EN_R")
	)
	(segment
		(start 207.524858 -137.127488)
		(end 207.124554 -137.527792)
		(width 0.10668)
		(layer "F.Cu")
		(net "FM_P12V_HSC_EN_N")
	)
	(segment
		(start 208.786222 -137.127488)
		(end 207.524858 -137.127488)
		(width 0.10668)
		(layer "F.Cu")
		(net "FM_P12V_HSC_EN_N")
	)
	(segment
		(start 206.065882 -137.527792)
		(end 206.065882 -139.549124)
		(width 0.10668)
		(layer "F.Cu")
		(net "FM_P12V_HSC_EN_N")
	)
	(segment
		(start 205.540864 -142.560294)
		(end 205.693518 -142.712948)
		(width 0.10668)
		(layer "F.Cu")
		(net "FM_P12V_HSC_EN_N")
	)
	(segment
		(start 205.540864 -140.074142)
		(end 205.540864 -142.560294)
		(width 0.10668)
		(layer "F.Cu")
		(net "FM_P12V_HSC_EN_N")
	)
	(segment
		(start 207.124554 -137.527792)
		(end 206.065882 -137.527792)
		(width 0.10668)
		(layer "F.Cu")
		(net "FM_P12V_HSC_EN_N")
	)
	(segment
		(start 206.065882 -139.549124)
		(end 205.540864 -140.074142)
		(width 0.10668)
		(layer "F.Cu")
		(net "FM_P12V_HSC_EN_N")
	)
	(via
		(at 205.540864 -140.074142)
		(size 0.762)
		(drill 0.381)
		(layers "F.Cu" "B.Cu")
		(net "FM_P12V_HSC_EN_N")
	)
	(segment
		(start 110.556548 -15.244064)
		(end 108.597446 -15.244064)
		(width 0.10668)
		(layer "F.Cu")
		(net "FM_LM75_3_ALERT_N")
	)
	(segment
		(start 108.597446 -15.244064)
		(end 107.352846 -15.244064)
		(width 0.10668)
		(layer "F.Cu")
		(net "FM_LM75_3_ALERT_N")
	)
	(segment
		(start 107.352846 -15.244064)
		(end 107.332272 -15.22349)
		(width 0.10668)
		(layer "F.Cu")
		(net "FM_LM75_3_ALERT_N")
	)
	(via
		(at 108.597446 -15.244064)
		(size 0.762)
		(drill 0.381)
		(layers "F.Cu" "B.Cu")
		(net "FM_LM75_3_ALERT_N")
	)
	(segment
		(start 100.285296 -415.075116)
		(end 100.285296 -413.947102)
		(width 0.10668)
		(layer "F.Cu")
		(net "FM_LM75_2_ALERT_N")
	)
	(segment
		(start 100.285296 -413.331152)
		(end 100.285296 -413.947102)
		(width 0.10668)
		(layer "F.Cu")
		(net "FM_LM75_2_ALERT_N")
	)
	(via
		(at 100.285296 -413.947102)
		(size 0.508)
		(drill 0.254)
		(layers "F.Cu" "B.Cu")
		(net "FM_LM75_2_ALERT_N")
	)
	(via
		(at 236.676692 -424.417998)
		(size 0.6604)
		(drill 0.3302)
		(layers "F.Cu" "B.Cu")
		(net "FM_GPU_HSC_EN_BUF_R1")
	)
	(segment
		(start 237.692692 -423.249598)
		(end 236.676692 -423.249598)
		(width 0.10668)
		(layer "B.Cu")
		(net "FM_GPU_HSC_EN_BUF_R1")
	)
	(segment
		(start 235.91012 -427.96206)
		(end 235.91012 -425.18457)
		(width 0.10668)
		(layer "B.Cu")
		(net "FM_GPU_HSC_EN_BUF_R1")
	)
	(segment
		(start 236.676692 -424.417998)
		(end 236.676692 -423.249598)
		(width 0.10668)
		(layer "B.Cu")
		(net "FM_GPU_HSC_EN_BUF_R1")
	)
	(segment
		(start 235.91012 -425.18457)
		(end 236.676692 -424.417998)
		(width 0.10668)
		(layer "B.Cu")
		(net "FM_GPU_HSC_EN_BUF_R1")
	)
	(segment
		(start 191.52362 -422.404032)
		(end 192.53962 -422.404032)
		(width 0.10668)
		(layer "F.Cu")
		(net "FM_GPU_HSC_EN_BUF_R")
	)
	(segment
		(start 193.42354 -420.746682)
		(end 193.42354 -419.355778)
		(width 0.10668)
		(layer "F.Cu")
		(net "FM_GPU_HSC_EN_BUF_R")
	)
	(segment
		(start 193.55562 -422.404032)
		(end 193.55562 -420.878762)
		(width 0.10668)
		(layer "F.Cu")
		(net "FM_GPU_HSC_EN_BUF_R")
	)
	(segment
		(start 192.53962 -422.404032)
		(end 193.55562 -422.404032)
		(width 0.10668)
		(layer "F.Cu")
		(net "FM_GPU_HSC_EN_BUF_R")
	)
	(segment
		(start 193.55562 -420.878762)
		(end 193.42354 -420.746682)
		(width 0.10668)
		(layer "F.Cu")
		(net "FM_GPU_HSC_EN_BUF_R")
	)
	(via
		(at 193.42354 -420.746682)
		(size 0.762)
		(drill 0.381)
		(layers "F.Cu" "B.Cu")
		(net "FM_GPU_HSC_EN_BUF_R")
	)
	(segment
		(start 191.52362 -423.204132)
		(end 191.52362 -423.991024)
		(width 0.10668)
		(layer "F.Cu")
		(net "FM_GPU_HSC_EN_BUF")
	)
	(via
		(at 232.661714 -423.501312)
		(size 0.508)
		(drill 0.254)
		(layers "F.Cu" "B.Cu")
		(net "FM_GPU_HSC_EN_BUF")
	)
	(via
		(at 191.52362 -423.991024)
		(size 0.508)
		(drill 0.254)
		(layers "F.Cu" "B.Cu")
		(net "FM_GPU_HSC_EN_BUF")
	)
	(segment
		(start 233.86923 -421.15105)
		(end 232.661714 -422.358566)
		(width 0.10668)
		(layer "B.Cu")
		(net "FM_GPU_HSC_EN_BUF")
	)
	(segment
		(start 237.692692 -422.076118)
		(end 236.767624 -421.15105)
		(width 0.10668)
		(layer "B.Cu")
		(net "FM_GPU_HSC_EN_BUF")
	)
	(segment
		(start 236.767624 -421.15105)
		(end 233.86923 -421.15105)
		(width 0.10668)
		(layer "B.Cu")
		(net "FM_GPU_HSC_EN_BUF")
	)
	(segment
		(start 232.661714 -422.358566)
		(end 232.661714 -423.501312)
		(width 0.10668)
		(layer "B.Cu")
		(net "FM_GPU_HSC_EN_BUF")
	)
	(segment
		(start 237.692692 -422.449498)
		(end 237.692692 -422.076118)
		(width 0.10668)
		(layer "B.Cu")
		(net "FM_GPU_HSC_EN_BUF")
	)
	(segment
		(start 196.457062 -434.734462)
		(end 196.457062 -428.620682)
		(width 0.11684)
		(layer "In13.Cu")
		(net "FM_GPU_HSC_EN_BUF")
	)
	(segment
		(start 191.827404 -423.991024)
		(end 191.52362 -423.991024)
		(width 0.11684)
		(layer "In13.Cu")
		(net "FM_GPU_HSC_EN_BUF")
	)
	(segment
		(start 230.484426 -436.278274)
		(end 229.46614 -437.29656)
		(width 0.11684)
		(layer "In13.Cu")
		(net "FM_GPU_HSC_EN_BUF")
	)
	(segment
		(start 232.661714 -424.715686)
		(end 230.484426 -426.892974)
		(width 0.11684)
		(layer "In13.Cu")
		(net "FM_GPU_HSC_EN_BUF")
	)
	(segment
		(start 232.661714 -423.501312)
		(end 232.661714 -424.715686)
		(width 0.11684)
		(layer "In13.Cu")
		(net "FM_GPU_HSC_EN_BUF")
	)
	(segment
		(start 199.01916 -437.29656)
		(end 196.457062 -434.734462)
		(width 0.11684)
		(layer "In13.Cu")
		(net "FM_GPU_HSC_EN_BUF")
	)
	(segment
		(start 229.46614 -437.29656)
		(end 199.01916 -437.29656)
		(width 0.11684)
		(layer "In13.Cu")
		(net "FM_GPU_HSC_EN_BUF")
	)
	(segment
		(start 196.457062 -428.620682)
		(end 191.827404 -423.991024)
		(width 0.11684)
		(layer "In13.Cu")
		(net "FM_GPU_HSC_EN_BUF")
	)
	(segment
		(start 230.484426 -426.892974)
		(end 230.484426 -436.278274)
		(width 0.11684)
		(layer "In13.Cu")
		(net "FM_GPU_HSC_EN_BUF")
	)
	(segment
		(start 228.535738 -147.918932)
		(end 226.353878 -150.100792)
		(width 0.10668)
		(layer "F.Cu")
		(net "FM_GPU_HSC_EN")
	)
	(segment
		(start 190.94958 -415.057082)
		(end 191.45758 -415.565082)
		(width 0.10668)
		(layer "F.Cu")
		(net "FM_GPU_HSC_EN")
	)
	(segment
		(start 209.294476 -116.673376)
		(end 210.502754 -116.673376)
		(width 0.10668)
		(layer "F.Cu")
		(net "FM_GPU_HSC_EN")
	)
	(segment
		(start 234.511342 -173.121574)
		(end 241.896392 -190.950596)
		(width 0.10668)
		(layer "F.Cu")
		(net "FM_GPU_HSC_EN")
	)
	(segment
		(start 226.353878 -158.737046)
		(end 234.511342 -166.89451)
		(width 0.10668)
		(layer "F.Cu")
		(net "FM_GPU_HSC_EN")
	)
	(segment
		(start 228.535738 -141.835632)
		(end 228.535738 -147.918932)
		(width 0.10668)
		(layer "F.Cu")
		(net "FM_GPU_HSC_EN")
	)
	(segment
		(start 228.572314 -119.890286)
		(end 229.997254 -121.315226)
		(width 0.10668)
		(layer "F.Cu")
		(net "FM_GPU_HSC_EN")
	)
	(segment
		(start 239.36071 -205.540102)
		(end 231.10825 -205.540102)
		(width 0.10668)
		(layer "F.Cu")
		(net "FM_GPU_HSC_EN")
	)
	(segment
		(start 191.45758 -415.565082)
		(end 191.45758 -416.889946)
		(width 0.10668)
		(layer "F.Cu")
		(net "FM_GPU_HSC_EN")
	)
	(segment
		(start 226.663504 -118.47322)
		(end 228.08057 -119.890286)
		(width 0.10668)
		(layer "F.Cu")
		(net "FM_GPU_HSC_EN")
	)
	(segment
		(start 241.896392 -203.00442)
		(end 239.36071 -205.540102)
		(width 0.10668)
		(layer "F.Cu")
		(net "FM_GPU_HSC_EN")
	)
	(segment
		(start 190.94958 -414.364932)
		(end 190.94958 -415.057082)
		(width 0.10668)
		(layer "F.Cu")
		(net "FM_GPU_HSC_EN")
	)
	(segment
		(start 229.399846 -207.248506)
		(end 229.399846 -209.573876)
		(width 0.10668)
		(layer "F.Cu")
		(net "FM_GPU_HSC_EN")
	)
	(segment
		(start 226.353878 -150.100792)
		(end 226.353878 -158.737046)
		(width 0.10668)
		(layer "F.Cu")
		(net "FM_GPU_HSC_EN")
	)
	(segment
		(start 229.997254 -121.315226)
		(end 229.997254 -140.374116)
		(width 0.10668)
		(layer "F.Cu")
		(net "FM_GPU_HSC_EN")
	)
	(segment
		(start 228.08057 -119.890286)
		(end 228.572314 -119.890286)
		(width 0.10668)
		(layer "F.Cu")
		(net "FM_GPU_HSC_EN")
	)
	(segment
		(start 234.511342 -166.89451)
		(end 234.511342 -173.121574)
		(width 0.10668)
		(layer "F.Cu")
		(net "FM_GPU_HSC_EN")
	)
	(segment
		(start 190.94958 -414.364932)
		(end 192.47358 -414.364932)
		(width 0.10668)
		(layer "F.Cu")
		(net "FM_GPU_HSC_EN")
	)
	(segment
		(start 231.10825 -205.540102)
		(end 229.399846 -207.248506)
		(width 0.10668)
		(layer "F.Cu")
		(net "FM_GPU_HSC_EN")
	)
	(segment
		(start 191.45758 -416.889946)
		(end 191.52362 -416.955986)
		(width 0.10668)
		(layer "F.Cu")
		(net "FM_GPU_HSC_EN")
	)
	(segment
		(start 241.896392 -190.950596)
		(end 241.896392 -203.00442)
		(width 0.10668)
		(layer "F.Cu")
		(net "FM_GPU_HSC_EN")
	)
	(segment
		(start 229.997254 -140.374116)
		(end 228.535738 -141.835632)
		(width 0.10668)
		(layer "F.Cu")
		(net "FM_GPU_HSC_EN")
	)
	(via
		(at 229.399846 -209.573876)
		(size 0.508)
		(drill 0.254)
		(layers "F.Cu" "B.Cu")
		(net "FM_GPU_HSC_EN")
	)
	(via
		(at 210.502754 -116.673376)
		(size 0.508)
		(drill 0.254)
		(layers "F.Cu" "B.Cu")
		(net "FM_GPU_HSC_EN")
	)
	(via
		(at 191.45758 -415.565082)
		(size 0.508)
		(drill 0.254)
		(layers "F.Cu" "B.Cu")
		(net "FM_GPU_HSC_EN")
	)
	(via
		(at 226.663504 -118.47322)
		(size 0.508)
		(drill 0.254)
		(layers "F.Cu" "B.Cu")
		(net "FM_GPU_HSC_EN")
	)
	(segment
		(start 216.806272 -117.858794)
		(end 226.049078 -117.858794)
		(width 0.11684)
		(layer "In2.Cu")
		(net "FM_GPU_HSC_EN")
	)
	(segment
		(start 210.92033 -116.2558)
		(end 215.203278 -116.2558)
		(width 0.11684)
		(layer "In2.Cu")
		(net "FM_GPU_HSC_EN")
	)
	(segment
		(start 210.502754 -116.673376)
		(end 210.92033 -116.2558)
		(width 0.11684)
		(layer "In2.Cu")
		(net "FM_GPU_HSC_EN")
	)
	(segment
		(start 226.049078 -117.858794)
		(end 226.663504 -118.47322)
		(width 0.11684)
		(layer "In2.Cu")
		(net "FM_GPU_HSC_EN")
	)
	(segment
		(start 215.203278 -116.2558)
		(end 216.806272 -117.858794)
		(width 0.11684)
		(layer "In2.Cu")
		(net "FM_GPU_HSC_EN")
	)
	(segment
		(start 171.400216 -398.244822)
		(end 173.226476 -396.418562)
		(width 0.11684)
		(layer "In4.Cu")
		(net "FM_GPU_HSC_EN")
	)
	(segment
		(start 225.954844 -332.525878)
		(end 225.954844 -331.364844)
		(width 0.11684)
		(layer "In4.Cu")
		(net "FM_GPU_HSC_EN")
	)
	(segment
		(start 174.808896 -415.133028)
		(end 170.87215 -411.196282)
		(width 0.11684)
		(layer "In4.Cu")
		(net "FM_GPU_HSC_EN")
	)
	(segment
		(start 226.751896 -343.12987)
		(end 226.751896 -333.32293)
		(width 0.11684)
		(layer "In4.Cu")
		(net "FM_GPU_HSC_EN")
	)
	(segment
		(start 219.218764 -350.663002)
		(end 226.751896 -343.12987)
		(width 0.11684)
		(layer "In4.Cu")
		(net "FM_GPU_HSC_EN")
	)
	(segment
		(start 166.102538 -400.162014)
		(end 168.01973 -398.244822)
		(width 0.11684)
		(layer "In4.Cu")
		(net "FM_GPU_HSC_EN")
	)
	(segment
		(start 190.608204 -414.715706)
		(end 182.00624 -414.715706)
		(width 0.11684)
		(layer "In4.Cu")
		(net "FM_GPU_HSC_EN")
	)
	(segment
		(start 165.405054 -401.846034)
		(end 166.102538 -400.162014)
		(width 0.11684)
		(layer "In4.Cu")
		(net "FM_GPU_HSC_EN")
	)
	(segment
		(start 222.51289 -215.845136)
		(end 228.78415 -209.573876)
		(width 0.11684)
		(layer "In4.Cu")
		(net "FM_GPU_HSC_EN")
	)
	(segment
		(start 182.00624 -414.715706)
		(end 181.417214 -414.12668)
		(width 0.11684)
		(layer "In4.Cu")
		(net "FM_GPU_HSC_EN")
	)
	(segment
		(start 228.78415 -209.573876)
		(end 229.399846 -209.573876)
		(width 0.11684)
		(layer "In4.Cu")
		(net "FM_GPU_HSC_EN")
	)
	(segment
		(start 195.685156 -369.241832)
		(end 202.632056 -369.241832)
		(width 0.11684)
		(layer "In4.Cu")
		(net "FM_GPU_HSC_EN")
	)
	(segment
		(start 219.218764 -363.461046)
		(end 219.218764 -350.663002)
		(width 0.11684)
		(layer "In4.Cu")
		(net "FM_GPU_HSC_EN")
	)
	(segment
		(start 177.883566 -414.12668)
		(end 176.877218 -415.133028)
		(width 0.11684)
		(layer "In4.Cu")
		(net "FM_GPU_HSC_EN")
	)
	(segment
		(start 222.51289 -254.37211)
		(end 222.51289 -215.845136)
		(width 0.11684)
		(layer "In4.Cu")
		(net "FM_GPU_HSC_EN")
	)
	(segment
		(start 205.292452 -366.581436)
		(end 216.098374 -366.581436)
		(width 0.11684)
		(layer "In4.Cu")
		(net "FM_GPU_HSC_EN")
	)
	(segment
		(start 225.954844 -331.364844)
		(end 215.9127 -321.3227)
		(width 0.11684)
		(layer "In4.Cu")
		(net "FM_GPU_HSC_EN")
	)
	(segment
		(start 168.01973 -398.244822)
		(end 171.400216 -398.244822)
		(width 0.11684)
		(layer "In4.Cu")
		(net "FM_GPU_HSC_EN")
	)
	(segment
		(start 202.632056 -369.241832)
		(end 205.292452 -366.581436)
		(width 0.11684)
		(layer "In4.Cu")
		(net "FM_GPU_HSC_EN")
	)
	(segment
		(start 181.417214 -414.12668)
		(end 177.883566 -414.12668)
		(width 0.11684)
		(layer "In4.Cu")
		(net "FM_GPU_HSC_EN")
	)
	(segment
		(start 176.877218 -415.133028)
		(end 174.808896 -415.133028)
		(width 0.11684)
		(layer "In4.Cu")
		(net "FM_GPU_HSC_EN")
	)
	(segment
		(start 216.098374 -366.581436)
		(end 219.218764 -363.461046)
		(width 0.11684)
		(layer "In4.Cu")
		(net "FM_GPU_HSC_EN")
	)
	(segment
		(start 173.226476 -396.418562)
		(end 173.226476 -391.700512)
		(width 0.11684)
		(layer "In4.Cu")
		(net "FM_GPU_HSC_EN")
	)
	(segment
		(start 173.226476 -391.700512)
		(end 195.685156 -369.241832)
		(width 0.11684)
		(layer "In4.Cu")
		(net "FM_GPU_HSC_EN")
	)
	(segment
		(start 215.9127 -260.9723)
		(end 222.51289 -254.37211)
		(width 0.11684)
		(layer "In4.Cu")
		(net "FM_GPU_HSC_EN")
	)
	(segment
		(start 226.751896 -333.32293)
		(end 225.954844 -332.525878)
		(width 0.11684)
		(layer "In4.Cu")
		(net "FM_GPU_HSC_EN")
	)
	(segment
		(start 191.45758 -415.565082)
		(end 190.608204 -414.715706)
		(width 0.11684)
		(layer "In4.Cu")
		(net "FM_GPU_HSC_EN")
	)
	(segment
		(start 215.9127 -321.3227)
		(end 215.9127 -260.9723)
		(width 0.11684)
		(layer "In4.Cu")
		(net "FM_GPU_HSC_EN")
	)
	(segment
		(start 165.405054 -407.25217)
		(end 165.405054 -401.846034)
		(width 0.11684)
		(layer "In4.Cu")
		(net "FM_GPU_HSC_EN")
	)
	(segment
		(start 169.349166 -411.196282)
		(end 165.405054 -407.25217)
		(width 0.11684)
		(layer "In4.Cu")
		(net "FM_GPU_HSC_EN")
	)
	(segment
		(start 170.87215 -411.196282)
		(end 169.349166 -411.196282)
		(width 0.11684)
		(layer "In4.Cu")
		(net "FM_GPU_HSC_EN")
	)
	(segment
		(start 289.14979 -14.164818)
		(end 289.14979 -13.737844)
		(width 0.10668)
		(layer "F.Cu")
		(net "FM_G751_1_ALERT_N")
	)
	(segment
		(start 288.793174 -13.381228)
		(end 288.793174 -13.360146)
		(width 0.10668)
		(layer "F.Cu")
		(net "FM_G751_1_ALERT_N")
	)
	(segment
		(start 290.042854 -14.636496)
		(end 290.042854 -14.399514)
		(width 0.10668)
		(layer "F.Cu")
		(net "FM_G751_1_ALERT_N")
	)
	(segment
		(start 289.329368 -14.344396)
		(end 289.14979 -14.164818)
		(width 0.10668)
		(layer "F.Cu")
		(net "FM_G751_1_ALERT_N")
	)
	(segment
		(start 291.715444 -14.779244)
		(end 290.185602 -14.779244)
		(width 0.10668)
		(layer "F.Cu")
		(net "FM_G751_1_ALERT_N")
	)
	(segment
		(start 289.14979 -13.737844)
		(end 288.793174 -13.381228)
		(width 0.10668)
		(layer "F.Cu")
		(net "FM_G751_1_ALERT_N")
	)
	(segment
		(start 289.987736 -14.344396)
		(end 289.329368 -14.344396)
		(width 0.10668)
		(layer "F.Cu")
		(net "FM_G751_1_ALERT_N")
	)
	(segment
		(start 290.042854 -14.399514)
		(end 289.987736 -14.344396)
		(width 0.10668)
		(layer "F.Cu")
		(net "FM_G751_1_ALERT_N")
	)
	(segment
		(start 290.185602 -14.779244)
		(end 290.042854 -14.636496)
		(width 0.10668)
		(layer "F.Cu")
		(net "FM_G751_1_ALERT_N")
	)
	(via
		(at 290.042854 -14.399514)
		(size 0.762)
		(drill 0.381)
		(layers "F.Cu" "B.Cu")
		(net "FM_G751_1_ALERT_N")
	)
	(segment
		(start 368.427 -414.03905)
		(end 368.427 -414.655)
		(width 0.10668)
		(layer "F.Cu")
		(net "FM_G751_0_ALERT_N")
	)
	(segment
		(start 368.427 -414.655)
		(end 368.681 -414.909)
		(width 0.10668)
		(layer "F.Cu")
		(net "FM_G751_0_ALERT_N")
	)
	(segment
		(start 368.447066 -416.645598)
		(end 368.447066 -415.142934)
		(width 0.10668)
		(layer "F.Cu")
		(net "FM_G751_0_ALERT_N")
	)
	(segment
		(start 368.447066 -415.142934)
		(end 368.681 -414.909)
		(width 0.10668)
		(layer "F.Cu")
		(net "FM_G751_0_ALERT_N")
	)
	(via
		(at 368.681 -414.909)
		(size 0.762)
		(drill 0.381)
		(layers "F.Cu" "B.Cu")
		(net "FM_G751_0_ALERT_N")
	)
	(via
		(at 240.740692 -424.417998)
		(size 0.6604)
		(drill 0.3302)
		(layers "F.Cu" "B.Cu")
		(net "FM_FAN_PWR_EN_R")
	)
	(segment
		(start 240.740692 -424.417998)
		(end 240.740692 -423.249598)
		(width 0.10668)
		(layer "B.Cu")
		(net "FM_FAN_PWR_EN_R")
	)
	(segment
		(start 238.45012 -426.70857)
		(end 240.740692 -424.417998)
		(width 0.10668)
		(layer "B.Cu")
		(net "FM_FAN_PWR_EN_R")
	)
	(segment
		(start 241.756692 -423.249598)
		(end 240.740692 -423.249598)
		(width 0.10668)
		(layer "B.Cu")
		(net "FM_FAN_PWR_EN_R")
	)
	(segment
		(start 238.45012 -427.96206)
		(end 238.45012 -426.70857)
		(width 0.10668)
		(layer "B.Cu")
		(net "FM_FAN_PWR_EN_R")
	)
	(segment
		(start 208.843372 -192.26149)
		(end 208.843372 -192.272666)
		(width 0.10668)
		(layer "F.Cu")
		(net "FM_FAN_PWR_EN")
	)
	(segment
		(start 208.744312 -189.381638)
		(end 208.744312 -192.16243)
		(width 0.10668)
		(layer "F.Cu")
		(net "FM_FAN_PWR_EN")
	)
	(segment
		(start 208.744312 -192.16243)
		(end 208.843372 -192.26149)
		(width 0.10668)
		(layer "F.Cu")
		(net "FM_FAN_PWR_EN")
	)
	(segment
		(start 187.575444 -172.501306)
		(end 196.962776 -181.888638)
		(width 0.10668)
		(layer "F.Cu")
		(net "FM_FAN_PWR_EN")
	)
	(segment
		(start 196.962776 -181.888638)
		(end 203.546456 -181.888638)
		(width 0.10668)
		(layer "F.Cu")
		(net "FM_FAN_PWR_EN")
	)
	(segment
		(start 203.546456 -181.888638)
		(end 207.121506 -185.463688)
		(width 0.10668)
		(layer "F.Cu")
		(net "FM_FAN_PWR_EN")
	)
	(segment
		(start 207.121506 -185.463688)
		(end 208.744312 -189.381638)
		(width 0.10668)
		(layer "F.Cu")
		(net "FM_FAN_PWR_EN")
	)
	(segment
		(start 179.52212 -115.452906)
		(end 179.13223 -115.842796)
		(width 0.10668)
		(layer "F.Cu")
		(net "FM_FAN_PWR_EN")
	)
	(via
		(at 238.524034 -367.847626)
		(size 0.508)
		(drill 0.254)
		(layers "F.Cu" "B.Cu")
		(net "FM_FAN_PWR_EN")
	)
	(via
		(at 208.843372 -192.272666)
		(size 0.508)
		(drill 0.254)
		(layers "F.Cu" "B.Cu")
		(net "FM_FAN_PWR_EN")
	)
	(via
		(at 179.13223 -115.842796)
		(size 0.4572)
		(drill 0.254)
		(layers "F.Cu" "B.Cu")
		(net "FM_FAN_PWR_EN")
	)
	(via
		(at 187.575444 -172.501306)
		(size 0.508)
		(drill 0.254)
		(layers "F.Cu" "B.Cu")
		(net "FM_FAN_PWR_EN")
	)
	(via
		(at 241.756692 -421.833548)
		(size 0.508)
		(drill 0.254)
		(layers "F.Cu" "B.Cu")
		(net "FM_FAN_PWR_EN")
	)
	(via
		(at 163.791646 -125.877828)
		(size 0.508)
		(drill 0.254)
		(layers "F.Cu" "B.Cu")
		(net "FM_FAN_PWR_EN")
	)
	(segment
		(start 163.849304 -126.907036)
		(end 163.849304 -125.935486)
		(width 0.10668)
		(layer "B.Cu")
		(net "FM_FAN_PWR_EN")
	)
	(segment
		(start 241.756692 -422.449498)
		(end 241.756692 -421.833548)
		(width 0.10668)
		(layer "B.Cu")
		(net "FM_FAN_PWR_EN")
	)
	(segment
		(start 187.575444 -169.57421)
		(end 186.431682 -168.430448)
		(width 0.10668)
		(layer "B.Cu")
		(net "FM_FAN_PWR_EN")
	)
	(segment
		(start 241.756692 -421.833548)
		(end 241.756692 -421.20693)
		(width 0.10668)
		(layer "B.Cu")
		(net "FM_FAN_PWR_EN")
	)
	(segment
		(start 177.505868 -168.430448)
		(end 176.052734 -166.977314)
		(width 0.10668)
		(layer "B.Cu")
		(net "FM_FAN_PWR_EN")
	)
	(segment
		(start 164.531802 -127.589534)
		(end 163.849304 -126.907036)
		(width 0.10668)
		(layer "B.Cu")
		(net "FM_FAN_PWR_EN")
	)
	(segment
		(start 176.052734 -157.807152)
		(end 171.477178 -153.231596)
		(width 0.10668)
		(layer "B.Cu")
		(net "FM_FAN_PWR_EN")
	)
	(segment
		(start 176.052734 -166.977314)
		(end 176.052734 -157.807152)
		(width 0.10668)
		(layer "B.Cu")
		(net "FM_FAN_PWR_EN")
	)
	(segment
		(start 187.575444 -172.501306)
		(end 187.575444 -169.57421)
		(width 0.10668)
		(layer "B.Cu")
		(net "FM_FAN_PWR_EN")
	)
	(segment
		(start 171.477178 -137.323068)
		(end 164.531802 -130.377692)
		(width 0.10668)
		(layer "B.Cu")
		(net "FM_FAN_PWR_EN")
	)
	(segment
		(start 163.849304 -125.935486)
		(end 163.791646 -125.877828)
		(width 0.10668)
		(layer "B.Cu")
		(net "FM_FAN_PWR_EN")
	)
	(segment
		(start 186.431682 -168.430448)
		(end 177.505868 -168.430448)
		(width 0.10668)
		(layer "B.Cu")
		(net "FM_FAN_PWR_EN")
	)
	(segment
		(start 171.477178 -153.231596)
		(end 171.477178 -137.323068)
		(width 0.10668)
		(layer "B.Cu")
		(net "FM_FAN_PWR_EN")
	)
	(segment
		(start 164.531802 -130.377692)
		(end 164.531802 -127.589534)
		(width 0.10668)
		(layer "B.Cu")
		(net "FM_FAN_PWR_EN")
	)
	(segment
		(start 166.81577 -119.215408)
		(end 167.208454 -118.822724)
		(width 0.11684)
		(layer "In6.Cu")
		(net "FM_FAN_PWR_EN")
	)
	(segment
		(start 235.029756 -367.847626)
		(end 238.524034 -367.847626)
		(width 0.11684)
		(layer "In6.Cu")
		(net "FM_FAN_PWR_EN")
	)
	(segment
		(start 218.443556 -200.956926)
		(end 218.443556 -319.266824)
		(width 0.11684)
		(layer "In6.Cu")
		(net "FM_FAN_PWR_EN")
	)
	(segment
		(start 230.273352 -363.091222)
		(end 235.029756 -367.847626)
		(width 0.11684)
		(layer "In6.Cu")
		(net "FM_FAN_PWR_EN")
	)
	(segment
		(start 165.681152 -119.215408)
		(end 166.81577 -119.215408)
		(width 0.11684)
		(layer "In6.Cu")
		(net "FM_FAN_PWR_EN")
	)
	(segment
		(start 167.208454 -118.822724)
		(end 168.995344 -118.822724)
		(width 0.11684)
		(layer "In6.Cu")
		(net "FM_FAN_PWR_EN")
	)
	(segment
		(start 209.759296 -192.272666)
		(end 218.443556 -200.956926)
		(width 0.11684)
		(layer "In6.Cu")
		(net "FM_FAN_PWR_EN")
	)
	(segment
		(start 164.090858 -123.21286)
		(end 164.090858 -120.805702)
		(width 0.11684)
		(layer "In6.Cu")
		(net "FM_FAN_PWR_EN")
	)
	(segment
		(start 230.273352 -331.09662)
		(end 230.273352 -363.091222)
		(width 0.11684)
		(layer "In6.Cu")
		(net "FM_FAN_PWR_EN")
	)
	(segment
		(start 164.090858 -120.805702)
		(end 165.681152 -119.215408)
		(width 0.11684)
		(layer "In6.Cu")
		(net "FM_FAN_PWR_EN")
	)
	(segment
		(start 163.791646 -123.512072)
		(end 164.090858 -123.21286)
		(width 0.11684)
		(layer "In6.Cu")
		(net "FM_FAN_PWR_EN")
	)
	(segment
		(start 170.07713 -117.740938)
		(end 173.994318 -117.740938)
		(width 0.11684)
		(layer "In6.Cu")
		(net "FM_FAN_PWR_EN")
	)
	(segment
		(start 178.729894 -116.245132)
		(end 179.13223 -115.842796)
		(width 0.11684)
		(layer "In6.Cu")
		(net "FM_FAN_PWR_EN")
	)
	(segment
		(start 163.791646 -125.877828)
		(end 163.791646 -123.512072)
		(width 0.11684)
		(layer "In6.Cu")
		(net "FM_FAN_PWR_EN")
	)
	(segment
		(start 208.843372 -192.272666)
		(end 209.759296 -192.272666)
		(width 0.11684)
		(layer "In6.Cu")
		(net "FM_FAN_PWR_EN")
	)
	(segment
		(start 173.994318 -117.740938)
		(end 175.490124 -116.245132)
		(width 0.11684)
		(layer "In6.Cu")
		(net "FM_FAN_PWR_EN")
	)
	(segment
		(start 168.995344 -118.822724)
		(end 170.07713 -117.740938)
		(width 0.11684)
		(layer "In6.Cu")
		(net "FM_FAN_PWR_EN")
	)
	(segment
		(start 218.443556 -319.266824)
		(end 230.273352 -331.09662)
		(width 0.11684)
		(layer "In6.Cu")
		(net "FM_FAN_PWR_EN")
	)
	(segment
		(start 175.490124 -116.245132)
		(end 178.729894 -116.245132)
		(width 0.11684)
		(layer "In6.Cu")
		(net "FM_FAN_PWR_EN")
	)
	(segment
		(start 254.99568 -370.143786)
		(end 259.460492 -370.143786)
		(width 0.11684)
		(layer "In13.Cu")
		(net "FM_FAN_PWR_EN")
	)
	(segment
		(start 276.310852 -420.231316)
		(end 275.679154 -420.863014)
		(width 0.11684)
		(layer "In13.Cu")
		(net "FM_FAN_PWR_EN")
	)
	(segment
		(start 242.778788 -423.601134)
		(end 241.756692 -422.579038)
		(width 0.11684)
		(layer "In13.Cu")
		(net "FM_FAN_PWR_EN")
	)
	(segment
		(start 275.468334 -370.523008)
		(end 279.175464 -374.230138)
		(width 0.11684)
		(layer "In13.Cu")
		(net "FM_FAN_PWR_EN")
	)
	(segment
		(start 241.756692 -422.579038)
		(end 241.756692 -421.833548)
		(width 0.11684)
		(layer "In13.Cu")
		(net "FM_FAN_PWR_EN")
	)
	(segment
		(start 281.62758 -392.540236)
		(end 280.976324 -393.191492)
		(width 0.11684)
		(layer "In13.Cu")
		(net "FM_FAN_PWR_EN")
	)
	(segment
		(start 281.62758 -387.261608)
		(end 281.62758 -392.540236)
		(width 0.11684)
		(layer "In13.Cu")
		(net "FM_FAN_PWR_EN")
	)
	(segment
		(start 238.524034 -367.847626)
		(end 240.335562 -366.036098)
		(width 0.11684)
		(layer "In13.Cu")
		(net "FM_FAN_PWR_EN")
	)
	(segment
		(start 265.568684 -420.863014)
		(end 262.830564 -423.601134)
		(width 0.11684)
		(layer "In13.Cu")
		(net "FM_FAN_PWR_EN")
	)
	(segment
		(start 276.310852 -414.573466)
		(end 276.310852 -420.231316)
		(width 0.11684)
		(layer "In13.Cu")
		(net "FM_FAN_PWR_EN")
	)
	(segment
		(start 279.175464 -380.004066)
		(end 280.876502 -381.705104)
		(width 0.11684)
		(layer "In13.Cu")
		(net "FM_FAN_PWR_EN")
	)
	(segment
		(start 275.679154 -420.863014)
		(end 265.568684 -420.863014)
		(width 0.11684)
		(layer "In13.Cu")
		(net "FM_FAN_PWR_EN")
	)
	(segment
		(start 240.335562 -366.036098)
		(end 250.887992 -366.036098)
		(width 0.11684)
		(layer "In13.Cu")
		(net "FM_FAN_PWR_EN")
	)
	(segment
		(start 280.876502 -381.705104)
		(end 280.876502 -386.51053)
		(width 0.11684)
		(layer "In13.Cu")
		(net "FM_FAN_PWR_EN")
	)
	(segment
		(start 280.876502 -386.51053)
		(end 281.62758 -387.261608)
		(width 0.11684)
		(layer "In13.Cu")
		(net "FM_FAN_PWR_EN")
	)
	(segment
		(start 250.887992 -366.036098)
		(end 254.99568 -370.143786)
		(width 0.11684)
		(layer "In13.Cu")
		(net "FM_FAN_PWR_EN")
	)
	(segment
		(start 259.839714 -370.523008)
		(end 275.468334 -370.523008)
		(width 0.11684)
		(layer "In13.Cu")
		(net "FM_FAN_PWR_EN")
	)
	(segment
		(start 262.830564 -423.601134)
		(end 242.778788 -423.601134)
		(width 0.11684)
		(layer "In13.Cu")
		(net "FM_FAN_PWR_EN")
	)
	(segment
		(start 279.175464 -374.230138)
		(end 279.175464 -380.004066)
		(width 0.11684)
		(layer "In13.Cu")
		(net "FM_FAN_PWR_EN")
	)
	(segment
		(start 259.460492 -370.143786)
		(end 259.839714 -370.523008)
		(width 0.11684)
		(layer "In13.Cu")
		(net "FM_FAN_PWR_EN")
	)
	(segment
		(start 280.976324 -393.191492)
		(end 280.976324 -409.907994)
		(width 0.11684)
		(layer "In13.Cu")
		(net "FM_FAN_PWR_EN")
	)
	(segment
		(start 280.976324 -409.907994)
		(end 276.310852 -414.573466)
		(width 0.11684)
		(layer "In13.Cu")
		(net "FM_FAN_PWR_EN")
	)
	(segment
		(start 212.689694 -54.205378)
		(end 213.859618 -54.205378)
		(width 0.10668)
		(layer "F.Cu")
		(net "E1S_0_P3V3_ADC_ALERT_R")
	)
	(segment
		(start 212.638894 -54.154578)
		(end 212.689694 -54.205378)
		(width 0.10668)
		(layer "F.Cu")
		(net "E1S_0_P3V3_ADC_ALERT_R")
	)
	(via
		(at 212.638894 -54.154578)
		(size 0.508)
		(drill 0.254)
		(layers "F.Cu" "B.Cu")
		(net "E1S_0_P3V3_ADC_ALERT_R")
	)
	(segment
		(start 212.396324 -54.205378)
		(end 211.695284 -54.906418)
		(width 0.10668)
		(layer "B.Cu")
		(net "E1S_0_P3V3_ADC_ALERT_R")
	)
	(segment
		(start 212.725 -56.661558)
		(end 211.711794 -56.661558)
		(width 0.10668)
		(layer "B.Cu")
		(net "E1S_0_P3V3_ADC_ALERT_R")
	)
	(segment
		(start 211.695284 -54.906418)
		(end 211.695284 -56.678068)
		(width 0.10668)
		(layer "B.Cu")
		(net "E1S_0_P3V3_ADC_ALERT_R")
	)
	(segment
		(start 212.588094 -54.205378)
		(end 212.396324 -54.205378)
		(width 0.10668)
		(layer "B.Cu")
		(net "E1S_0_P3V3_ADC_ALERT_R")
	)
	(segment
		(start 211.695284 -56.678068)
		(end 211.69503 -56.678322)
		(width 0.10668)
		(layer "B.Cu")
		(net "E1S_0_P3V3_ADC_ALERT_R")
	)
	(segment
		(start 211.711794 -56.661558)
		(end 211.695284 -56.678068)
		(width 0.10668)
		(layer "B.Cu")
		(net "E1S_0_P3V3_ADC_ALERT_R")
	)
	(segment
		(start 212.638894 -54.154578)
		(end 212.588094 -54.205378)
		(width 0.10668)
		(layer "B.Cu")
		(net "E1S_0_P3V3_ADC_ALERT_R")
	)
	(segment
		(start 132.287772 -295.69029)
		(end 132.287772 -296.510964)
		(width 0.10668)
		(layer "F.Cu")
		(net "XTAL_CPU1_X48M_X2")
	)
	(via
		(at 132.287772 -296.510964)
		(size 0.508)
		(drill 0.254)
		(layers "F.Cu" "B.Cu")
		(net "XTAL_CPU1_X48M_X2")
	)
	(segment
		(start 132.287772 -296.510964)
		(end 135.05942 -299.282612)
		(width 0.10668)
		(layer "B.Cu")
		(net "XTAL_CPU1_X48M_X2")
	)
	(segment
		(start 149.890734 -311.178702)
		(end 149.541992 -311.178702)
		(width 0.10668)
		(layer "B.Cu")
		(net "XTAL_CPU1_X48M_X2")
	)
	(segment
		(start 149.518116 -310.203342)
		(end 149.411436 -310.310022)
		(width 0.10668)
		(layer "B.Cu")
		(net "XTAL_CPU1_X48M_X2")
	)
	(segment
		(start 149.518116 -310.691022)
		(end 149.890734 -310.691022)
		(width 0.10668)
		(layer "B.Cu")
		(net "XTAL_CPU1_X48M_X2")
	)
	(segment
		(start 149.411436 -310.310022)
		(end 149.411436 -310.584342)
		(width 0.10668)
		(layer "B.Cu")
		(net "XTAL_CPU1_X48M_X2")
	)
	(segment
		(start 149.411436 -304.127154)
		(end 149.411436 -309.608982)
		(width 0.10668)
		(layer "B.Cu")
		(net "XTAL_CPU1_X48M_X2")
	)
	(segment
		(start 149.890734 -309.715662)
		(end 149.997414 -309.822342)
		(width 0.10668)
		(layer "B.Cu")
		(net "XTAL_CPU1_X48M_X2")
	)
	(segment
		(start 135.05942 -299.282612)
		(end 144.566894 -299.282612)
		(width 0.10668)
		(layer "B.Cu")
		(net "XTAL_CPU1_X48M_X2")
	)
	(segment
		(start 149.997414 -309.822342)
		(end 149.997414 -310.096662)
		(width 0.10668)
		(layer "B.Cu")
		(net "XTAL_CPU1_X48M_X2")
	)
	(segment
		(start 149.541992 -311.178702)
		(end 149.435312 -311.285382)
		(width 0.10668)
		(layer "B.Cu")
		(net "XTAL_CPU1_X48M_X2")
	)
	(segment
		(start 149.997414 -311.072022)
		(end 149.890734 -311.178702)
		(width 0.10668)
		(layer "B.Cu")
		(net "XTAL_CPU1_X48M_X2")
	)
	(segment
		(start 149.997414 -310.797702)
		(end 149.997414 -311.072022)
		(width 0.10668)
		(layer "B.Cu")
		(net "XTAL_CPU1_X48M_X2")
	)
	(segment
		(start 144.566894 -299.282612)
		(end 149.411436 -304.127154)
		(width 0.10668)
		(layer "B.Cu")
		(net "XTAL_CPU1_X48M_X2")
	)
	(segment
		(start 149.411436 -310.584342)
		(end 149.518116 -310.691022)
		(width 0.10668)
		(layer "B.Cu")
		(net "XTAL_CPU1_X48M_X2")
	)
	(segment
		(start 150.300436 -313.277504)
		(end 150.300436 -313.45505)
		(width 0.10668)
		(layer "B.Cu")
		(net "XTAL_CPU1_X48M_X2")
	)
	(segment
		(start 149.890734 -310.691022)
		(end 149.997414 -310.797702)
		(width 0.10668)
		(layer "B.Cu")
		(net "XTAL_CPU1_X48M_X2")
	)
	(segment
		(start 149.518116 -309.715662)
		(end 149.890734 -309.715662)
		(width 0.10668)
		(layer "B.Cu")
		(net "XTAL_CPU1_X48M_X2")
	)
	(segment
		(start 149.435312 -311.285382)
		(end 149.435312 -312.41238)
		(width 0.10668)
		(layer "B.Cu")
		(net "XTAL_CPU1_X48M_X2")
	)
	(segment
		(start 149.435312 -312.41238)
		(end 150.300436 -313.277504)
		(width 0.10668)
		(layer "B.Cu")
		(net "XTAL_CPU1_X48M_X2")
	)
	(segment
		(start 149.411436 -309.608982)
		(end 149.518116 -309.715662)
		(width 0.10668)
		(layer "B.Cu")
		(net "XTAL_CPU1_X48M_X2")
	)
	(segment
		(start 149.890734 -310.203342)
		(end 149.518116 -310.203342)
		(width 0.10668)
		(layer "B.Cu")
		(net "XTAL_CPU1_X48M_X2")
	)
	(segment
		(start 149.997414 -310.096662)
		(end 149.890734 -310.203342)
		(width 0.10668)
		(layer "B.Cu")
		(net "XTAL_CPU1_X48M_X2")
	)
	(segment
		(start 131.347972 -295.69029)
		(end 131.347972 -296.510964)
		(width 0.10668)
		(layer "F.Cu")
		(net "XTAL_CPU1_X48M_X1")
	)
	(via
		(at 131.347972 -296.510964)
		(size 0.508)
		(drill 0.254)
		(layers "F.Cu" "B.Cu")
		(net "XTAL_CPU1_X48M_X1")
	)
	(segment
		(start 149.000464 -316.774322)
		(end 148.090636 -317.68415)
		(width 0.10668)
		(layer "B.Cu")
		(net "XTAL_CPU1_X48M_X1")
	)
	(segment
		(start 147.722336 -313.45505)
		(end 147.722336 -313.67095)
		(width 0.10668)
		(layer "B.Cu")
		(net "XTAL_CPU1_X48M_X1")
	)
	(segment
		(start 148.036534 -304.044858)
		(end 148.036534 -313.140852)
		(width 0.10668)
		(layer "B.Cu")
		(net "XTAL_CPU1_X48M_X1")
	)
	(segment
		(start 144.209008 -300.217332)
		(end 148.036534 -304.044858)
		(width 0.10668)
		(layer "B.Cu")
		(net "XTAL_CPU1_X48M_X1")
	)
	(segment
		(start 148.036534 -313.140852)
		(end 147.722336 -313.45505)
		(width 0.10668)
		(layer "B.Cu")
		(net "XTAL_CPU1_X48M_X1")
	)
	(segment
		(start 131.347972 -296.510964)
		(end 131.347972 -297.015916)
		(width 0.10668)
		(layer "B.Cu")
		(net "XTAL_CPU1_X48M_X1")
	)
	(segment
		(start 149.000464 -315.262514)
		(end 149.000464 -316.774322)
		(width 0.10668)
		(layer "B.Cu")
		(net "XTAL_CPU1_X48M_X1")
	)
	(segment
		(start 134.549388 -300.217332)
		(end 144.209008 -300.217332)
		(width 0.10668)
		(layer "B.Cu")
		(net "XTAL_CPU1_X48M_X1")
	)
	(segment
		(start 148.090636 -317.68415)
		(end 148.027644 -317.68415)
		(width 0.10668)
		(layer "B.Cu")
		(net "XTAL_CPU1_X48M_X1")
	)
	(segment
		(start 131.347972 -297.015916)
		(end 134.549388 -300.217332)
		(width 0.10668)
		(layer "B.Cu")
		(net "XTAL_CPU1_X48M_X1")
	)
	(segment
		(start 148.522436 -314.784486)
		(end 149.000464 -315.262514)
		(width 0.10668)
		(layer "B.Cu")
		(net "XTAL_CPU1_X48M_X1")
	)
	(segment
		(start 147.722336 -313.67095)
		(end 148.522436 -314.47105)
		(width 0.10668)
		(layer "B.Cu")
		(net "XTAL_CPU1_X48M_X1")
	)
	(segment
		(start 148.522436 -314.47105)
		(end 148.522436 -314.784486)
		(width 0.10668)
		(layer "B.Cu")
		(net "XTAL_CPU1_X48M_X1")
	)
	(segment
		(start 135.107934 -295.69029)
		(end 135.107934 -296.510964)
		(width 0.10668)
		(layer "F.Cu")
		(net "XTAL_CPU1_X32K_X2")
	)
	(via
		(at 135.107934 -296.510964)
		(size 0.508)
		(drill 0.254)
		(layers "F.Cu" "B.Cu")
		(net "XTAL_CPU1_X32K_X2")
	)
	(segment
		(start 135.908542 -297.286172)
		(end 145.214594 -297.286172)
		(width 0.10668)
		(layer "B.Cu")
		(net "XTAL_CPU1_X32K_X2")
	)
	(segment
		(start 135.107934 -296.510964)
		(end 135.133334 -296.510964)
		(width 0.10668)
		(layer "B.Cu")
		(net "XTAL_CPU1_X32K_X2")
	)
	(segment
		(start 135.133334 -296.510964)
		(end 135.908542 -297.286172)
		(width 0.10668)
		(layer "B.Cu")
		(net "XTAL_CPU1_X32K_X2")
	)
	(segment
		(start 153.975054 -312.382408)
		(end 153.975054 -313.563)
		(width 0.10668)
		(layer "B.Cu")
		(net "XTAL_CPU1_X32K_X2")
	)
	(segment
		(start 145.214594 -297.286172)
		(end 152.324816 -304.396394)
		(width 0.10668)
		(layer "B.Cu")
		(net "XTAL_CPU1_X32K_X2")
	)
	(segment
		(start 152.324816 -310.73217)
		(end 153.975054 -312.382408)
		(width 0.10668)
		(layer "B.Cu")
		(net "XTAL_CPU1_X32K_X2")
	)
	(segment
		(start 152.324816 -304.396394)
		(end 152.324816 -310.73217)
		(width 0.10668)
		(layer "B.Cu")
		(net "XTAL_CPU1_X32K_X2")
	)
	(segment
		(start 146.296634 -316.134242)
		(end 146.296634 -318.992504)
		(width 0.10668)
		(layer "F.Cu")
		(net "XTAL_CPU1_X32K_X1")
	)
	(segment
		(start 163.862004 -323.261482)
		(end 165.432232 -321.691254)
		(width 0.10668)
		(layer "F.Cu")
		(net "XTAL_CPU1_X32K_X1")
	)
	(segment
		(start 134.16788 -295.69029)
		(end 134.16788 -296.510964)
		(width 0.10668)
		(layer "F.Cu")
		(net "XTAL_CPU1_X32K_X1")
	)
	(segment
		(start 151.541734 -315.052964)
		(end 147.104862 -315.052964)
		(width 0.10668)
		(layer "F.Cu")
		(net "XTAL_CPU1_X32K_X1")
	)
	(segment
		(start 150.631144 -331.283056)
		(end 157.373066 -331.283056)
		(width 0.10668)
		(layer "F.Cu")
		(net "XTAL_CPU1_X32K_X1")
	)
	(segment
		(start 147.17776 -319.87363)
		(end 147.17776 -327.829672)
		(width 0.10668)
		(layer "F.Cu")
		(net "XTAL_CPU1_X32K_X1")
	)
	(segment
		(start 146.296634 -318.992504)
		(end 147.17776 -319.87363)
		(width 0.10668)
		(layer "F.Cu")
		(net "XTAL_CPU1_X32K_X1")
	)
	(segment
		(start 163.862004 -324.794118)
		(end 163.862004 -323.261482)
		(width 0.10668)
		(layer "F.Cu")
		(net "XTAL_CPU1_X32K_X1")
	)
	(segment
		(start 146.489674 -315.668152)
		(end 146.296634 -316.134242)
		(width 0.10668)
		(layer "F.Cu")
		(net "XTAL_CPU1_X32K_X1")
	)
	(segment
		(start 147.17776 -327.829672)
		(end 150.631144 -331.283056)
		(width 0.10668)
		(layer "F.Cu")
		(net "XTAL_CPU1_X32K_X1")
	)
	(segment
		(start 147.104862 -315.052964)
		(end 146.489674 -315.668152)
		(width 0.10668)
		(layer "F.Cu")
		(net "XTAL_CPU1_X32K_X1")
	)
	(segment
		(start 165.432232 -321.691254)
		(end 210.374484 -321.691254)
		(width 0.10668)
		(layer "F.Cu")
		(net "XTAL_CPU1_X32K_X1")
	)
	(segment
		(start 157.373066 -331.283056)
		(end 163.862004 -324.794118)
		(width 0.10668)
		(layer "F.Cu")
		(net "XTAL_CPU1_X32K_X1")
	)
	(via
		(at 222.815404 -366.16259)
		(size 0.508)
		(drill 0.254)
		(layers "F.Cu" "B.Cu")
		(net "XTAL_CPU1_X32K_X1")
	)
	(via
		(at 151.541734 -315.052964)
		(size 0.508)
		(drill 0.254)
		(layers "F.Cu" "B.Cu")
		(net "XTAL_CPU1_X32K_X1")
	)
	(via
		(at 134.16788 -296.510964)
		(size 0.508)
		(drill 0.254)
		(layers "F.Cu" "B.Cu")
		(net "XTAL_CPU1_X32K_X1")
	)
	(via
		(at 390.376664 -315.174376)
		(size 0.508)
		(drill 0.254)
		(layers "F.Cu" "B.Cu")
		(net "XTAL_CPU1_X32K_X1")
	)
	(via
		(at 210.374484 -321.691254)
		(size 0.508)
		(drill 0.254)
		(layers "F.Cu" "B.Cu")
		(net "XTAL_CPU1_X32K_X1")
	)
	(segment
		(start 152.959054 -312.625232)
		(end 152.959054 -313.563)
		(width 0.10668)
		(layer "B.Cu")
		(net "XTAL_CPU1_X32K_X1")
	)
	(segment
		(start 222.20936 -365.556546)
		(end 222.815404 -366.16259)
		(width 0.10668)
		(layer "B.Cu")
		(net "XTAL_CPU1_X32K_X1")
	)
	(segment
		(start 134.16788 -296.510964)
		(end 134.16788 -296.739564)
		(width 0.10668)
		(layer "B.Cu")
		(net "XTAL_CPU1_X32K_X1")
	)
	(segment
		(start 135.666988 -298.238672)
		(end 144.881854 -298.238672)
		(width 0.10668)
		(layer "B.Cu")
		(net "XTAL_CPU1_X32K_X1")
	)
	(segment
		(start 212.773514 -347.51772)
		(end 216.126314 -350.87052)
		(width 0.10668)
		(layer "B.Cu")
		(net "XTAL_CPU1_X32K_X1")
	)
	(segment
		(start 151.285194 -304.642012)
		(end 151.285194 -310.951372)
		(width 0.10668)
		(layer "B.Cu")
		(net "XTAL_CPU1_X32K_X1")
	)
	(segment
		(start 151.541734 -314.281566)
		(end 152.2603 -313.563)
		(width 0.10668)
		(layer "B.Cu")
		(net "XTAL_CPU1_X32K_X1")
	)
	(segment
		(start 151.285194 -310.951372)
		(end 152.959054 -312.625232)
		(width 0.10668)
		(layer "B.Cu")
		(net "XTAL_CPU1_X32K_X1")
	)
	(segment
		(start 390.020048 -314.580524)
		(end 390.020048 -314.81776)
		(width 0.10668)
		(layer "B.Cu")
		(net "XTAL_CPU1_X32K_X1")
	)
	(segment
		(start 208.982056 -338.364322)
		(end 212.773514 -347.51772)
		(width 0.10668)
		(layer "B.Cu")
		(net "XTAL_CPU1_X32K_X1")
	)
	(segment
		(start 152.2603 -313.563)
		(end 152.959054 -313.563)
		(width 0.10668)
		(layer "B.Cu")
		(net "XTAL_CPU1_X32K_X1")
	)
	(segment
		(start 209.478372 -321.691254)
		(end 208.982056 -322.18757)
		(width 0.10668)
		(layer "B.Cu")
		(net "XTAL_CPU1_X32K_X1")
	)
	(segment
		(start 216.126314 -350.87052)
		(end 222.20936 -365.556546)
		(width 0.10668)
		(layer "B.Cu")
		(net "XTAL_CPU1_X32K_X1")
	)
	(segment
		(start 390.020048 -314.81776)
		(end 390.376664 -315.174376)
		(width 0.10668)
		(layer "B.Cu")
		(net "XTAL_CPU1_X32K_X1")
	)
	(segment
		(start 134.16788 -296.739564)
		(end 135.666988 -298.238672)
		(width 0.10668)
		(layer "B.Cu")
		(net "XTAL_CPU1_X32K_X1")
	)
	(segment
		(start 210.374484 -321.691254)
		(end 209.478372 -321.691254)
		(width 0.10668)
		(layer "B.Cu")
		(net "XTAL_CPU1_X32K_X1")
	)
	(segment
		(start 208.982056 -322.18757)
		(end 208.982056 -338.364322)
		(width 0.10668)
		(layer "B.Cu")
		(net "XTAL_CPU1_X32K_X1")
	)
	(segment
		(start 144.881854 -298.238672)
		(end 151.285194 -304.642012)
		(width 0.10668)
		(layer "B.Cu")
		(net "XTAL_CPU1_X32K_X1")
	)
	(segment
		(start 151.541734 -315.052964)
		(end 151.541734 -314.281566)
		(width 0.10668)
		(layer "B.Cu")
		(net "XTAL_CPU1_X32K_X1")
	)
	(segment
		(start 391.576052 -315.767212)
		(end 390.540748 -315.33846)
		(width 0.11684)
		(layer "In2.Cu")
		(net "XTAL_CPU1_X32K_X1")
	)
	(segment
		(start 282.009342 -370.369592)
		(end 287.738312 -370.369592)
		(width 0.11684)
		(layer "In2.Cu")
		(net "XTAL_CPU1_X32K_X1")
	)
	(segment
		(start 224.605088 -366.704626)
		(end 225.355404 -365.95431)
		(width 0.11684)
		(layer "In2.Cu")
		(net "XTAL_CPU1_X32K_X1")
	)
	(segment
		(start 230.727504 -366.617504)
		(end 232.367582 -366.617504)
		(width 0.11684)
		(layer "In2.Cu")
		(net "XTAL_CPU1_X32K_X1")
	)
	(segment
		(start 230.06431 -365.95431)
		(end 230.727504 -366.617504)
		(width 0.11684)
		(layer "In2.Cu")
		(net "XTAL_CPU1_X32K_X1")
	)
	(segment
		(start 353.18573 -368.13617)
		(end 384.215894 -337.106006)
		(width 0.11684)
		(layer "In2.Cu")
		(net "XTAL_CPU1_X32K_X1")
	)
	(segment
		(start 251.77369 -365.993172)
		(end 252.058424 -366.277906)
		(width 0.11684)
		(layer "In2.Cu")
		(net "XTAL_CPU1_X32K_X1")
	)
	(segment
		(start 390.285732 -317.014352)
		(end 391.062972 -317.014352)
		(width 0.11684)
		(layer "In2.Cu")
		(net "XTAL_CPU1_X32K_X1")
	)
	(segment
		(start 384.215894 -323.08419)
		(end 390.285732 -317.014352)
		(width 0.11684)
		(layer "In2.Cu")
		(net "XTAL_CPU1_X32K_X1")
	)
	(segment
		(start 322.101464 -372.946168)
		(end 353.18573 -368.13617)
		(width 0.11684)
		(layer "In2.Cu")
		(net "XTAL_CPU1_X32K_X1")
	)
	(segment
		(start 391.729722 -316.347602)
		(end 391.729722 -315.920882)
		(width 0.11684)
		(layer "In2.Cu")
		(net "XTAL_CPU1_X32K_X1")
	)
	(segment
		(start 391.062972 -317.014352)
		(end 391.729722 -316.347602)
		(width 0.11684)
		(layer "In2.Cu")
		(net "XTAL_CPU1_X32K_X1")
	)
	(segment
		(start 223.35744 -366.704626)
		(end 224.605088 -366.704626)
		(width 0.11684)
		(layer "In2.Cu")
		(net "XTAL_CPU1_X32K_X1")
	)
	(segment
		(start 232.367582 -366.617504)
		(end 232.991914 -365.993172)
		(width 0.11684)
		(layer "In2.Cu")
		(net "XTAL_CPU1_X32K_X1")
	)
	(segment
		(start 384.215894 -337.106006)
		(end 384.215894 -323.08419)
		(width 0.11684)
		(layer "In2.Cu")
		(net "XTAL_CPU1_X32K_X1")
	)
	(segment
		(start 287.738312 -370.369592)
		(end 290.314888 -372.946168)
		(width 0.11684)
		(layer "In2.Cu")
		(net "XTAL_CPU1_X32K_X1")
	)
	(segment
		(start 391.729722 -315.920882)
		(end 391.576052 -315.767212)
		(width 0.11684)
		(layer "In2.Cu")
		(net "XTAL_CPU1_X32K_X1")
	)
	(segment
		(start 271.656048 -365.275876)
		(end 276.915626 -365.275876)
		(width 0.11684)
		(layer "In2.Cu")
		(net "XTAL_CPU1_X32K_X1")
	)
	(segment
		(start 225.355404 -365.95431)
		(end 230.06431 -365.95431)
		(width 0.11684)
		(layer "In2.Cu")
		(net "XTAL_CPU1_X32K_X1")
	)
	(segment
		(start 276.915626 -365.275876)
		(end 282.009342 -370.369592)
		(width 0.11684)
		(layer "In2.Cu")
		(net "XTAL_CPU1_X32K_X1")
	)
	(segment
		(start 290.314888 -372.946168)
		(end 322.101464 -372.946168)
		(width 0.11684)
		(layer "In2.Cu")
		(net "XTAL_CPU1_X32K_X1")
	)
	(segment
		(start 252.058424 -366.277906)
		(end 269.236952 -366.277906)
		(width 0.11684)
		(layer "In2.Cu")
		(net "XTAL_CPU1_X32K_X1")
	)
	(segment
		(start 232.991914 -365.993172)
		(end 251.77369 -365.993172)
		(width 0.11684)
		(layer "In2.Cu")
		(net "XTAL_CPU1_X32K_X1")
	)
	(segment
		(start 390.540748 -315.33846)
		(end 390.376664 -315.174376)
		(width 0.11684)
		(layer "In2.Cu")
		(net "XTAL_CPU1_X32K_X1")
	)
	(segment
		(start 269.236952 -366.277906)
		(end 271.656048 -365.275876)
		(width 0.11684)
		(layer "In2.Cu")
		(net "XTAL_CPU1_X32K_X1")
	)
	(segment
		(start 222.815404 -366.16259)
		(end 223.35744 -366.704626)
		(width 0.11684)
		(layer "In2.Cu")
		(net "XTAL_CPU1_X32K_X1")
	)
	(via
		(at 154.348434 -316.506352)
		(size 0.6604)
		(drill 0.3302)
		(layers "F.Cu" "B.Cu")
		(net "XTAL_CPU1_R_X32K_X2")
	)
	(segment
		(start 154.348434 -316.506352)
		(end 154.88158 -316.506352)
		(width 0.10668)
		(layer "B.Cu")
		(net "XTAL_CPU1_R_X32K_X2")
	)
	(segment
		(start 153.975054 -314.3631)
		(end 153.975054 -315.241432)
		(width 0.10668)
		(layer "B.Cu")
		(net "XTAL_CPU1_R_X32K_X2")
	)
	(segment
		(start 154.70632 -317.234316)
		(end 155.491434 -316.449202)
		(width 0.10668)
		(layer "B.Cu")
		(net "XTAL_CPU1_R_X32K_X2")
	)
	(segment
		(start 154.93873 -316.449202)
		(end 155.491434 -316.449202)
		(width 0.10668)
		(layer "B.Cu")
		(net "XTAL_CPU1_R_X32K_X2")
	)
	(segment
		(start 154.70632 -318.53505)
		(end 154.70632 -317.234316)
		(width 0.10668)
		(layer "B.Cu")
		(net "XTAL_CPU1_R_X32K_X2")
	)
	(segment
		(start 154.348434 -315.852048)
		(end 154.348434 -316.506352)
		(width 0.10668)
		(layer "B.Cu")
		(net "XTAL_CPU1_R_X32K_X2")
	)
	(segment
		(start 154.88158 -316.506352)
		(end 154.93873 -316.449202)
		(width 0.10668)
		(layer "B.Cu")
		(net "XTAL_CPU1_R_X32K_X2")
	)
	(segment
		(start 153.856436 -315.36005)
		(end 154.348434 -315.852048)
		(width 0.10668)
		(layer "B.Cu")
		(net "XTAL_CPU1_R_X32K_X2")
	)
	(segment
		(start 153.975054 -315.241432)
		(end 153.856436 -315.36005)
		(width 0.10668)
		(layer "B.Cu")
		(net "XTAL_CPU1_R_X32K_X2")
	)
	(via
		(at 153.056336 -316.709552)
		(size 0.6604)
		(drill 0.3302)
		(layers "F.Cu" "B.Cu")
		(net "XTAL_CPU1_R_X32K_X1")
	)
	(segment
		(start 152.633934 -316.709552)
		(end 153.056336 -316.709552)
		(width 0.10668)
		(layer "B.Cu")
		(net "XTAL_CPU1_R_X32K_X1")
	)
	(segment
		(start 153.056336 -316.709552)
		(end 153.056336 -315.36005)
		(width 0.10668)
		(layer "B.Cu")
		(net "XTAL_CPU1_R_X32K_X1")
	)
	(segment
		(start 152.589484 -316.754002)
		(end 152.633934 -316.709552)
		(width 0.10668)
		(layer "B.Cu")
		(net "XTAL_CPU1_R_X32K_X1")
	)
	(segment
		(start 151.884634 -316.754002)
		(end 152.589484 -316.754002)
		(width 0.10668)
		(layer "B.Cu")
		(net "XTAL_CPU1_R_X32K_X1")
	)
	(segment
		(start 153.056336 -315.36005)
		(end 153.056336 -314.698126)
		(width 0.10668)
		(layer "B.Cu")
		(net "XTAL_CPU1_R_X32K_X1")
	)
	(segment
		(start 152.959054 -314.600844)
		(end 152.959054 -314.3631)
		(width 0.10668)
		(layer "B.Cu")
		(net "XTAL_CPU1_R_X32K_X1")
	)
	(segment
		(start 152.206452 -318.53505)
		(end 152.206452 -317.07582)
		(width 0.10668)
		(layer "B.Cu")
		(net "XTAL_CPU1_R_X32K_X1")
	)
	(segment
		(start 152.206452 -317.07582)
		(end 151.884634 -316.754002)
		(width 0.10668)
		(layer "B.Cu")
		(net "XTAL_CPU1_R_X32K_X1")
	)
	(segment
		(start 153.056336 -314.698126)
		(end 152.959054 -314.600844)
		(width 0.10668)
		(layer "B.Cu")
		(net "XTAL_CPU1_R_X32K_X1")
	)
	(segment
		(start 380.22784 -295.690036)
		(end 380.22784 -296.51706)
		(width 0.10668)
		(layer "F.Cu")
		(net "XTAL_CPU0_X48M_X2")
	)
	(via
		(at 380.22784 -296.51706)
		(size 0.508)
		(drill 0.254)
		(layers "F.Cu" "B.Cu")
		(net "XTAL_CPU0_X48M_X2")
	)
	(segment
		(start 392.93165 -311.61863)
		(end 392.65733 -311.61863)
		(width 0.10668)
		(layer "B.Cu")
		(net "XTAL_CPU0_X48M_X2")
	)
	(segment
		(start 387.718046 -311.21731)
		(end 384.78206 -308.281324)
		(width 0.10668)
		(layer "B.Cu")
		(net "XTAL_CPU0_X48M_X2")
	)
	(segment
		(start 398.336008 -313.477148)
		(end 398.336008 -312.689748)
		(width 0.10668)
		(layer "B.Cu")
		(net "XTAL_CPU0_X48M_X2")
	)
	(segment
		(start 393.14501 -311.21731)
		(end 393.03833 -311.32399)
		(width 0.10668)
		(layer "B.Cu")
		(net "XTAL_CPU0_X48M_X2")
	)
	(segment
		(start 393.90701 -311.61863)
		(end 393.63269 -311.61863)
		(width 0.10668)
		(layer "B.Cu")
		(net "XTAL_CPU0_X48M_X2")
	)
	(segment
		(start 393.03833 -311.32399)
		(end 393.03833 -311.51195)
		(width 0.10668)
		(layer "B.Cu")
		(net "XTAL_CPU0_X48M_X2")
	)
	(segment
		(start 393.52601 -311.32399)
		(end 393.41933 -311.21731)
		(width 0.10668)
		(layer "B.Cu")
		(net "XTAL_CPU0_X48M_X2")
	)
	(segment
		(start 392.55065 -311.51195)
		(end 392.55065 -311.32399)
		(width 0.10668)
		(layer "B.Cu")
		(net "XTAL_CPU0_X48M_X2")
	)
	(segment
		(start 384.78206 -308.281324)
		(end 380.22784 -297.28795)
		(width 0.10668)
		(layer "B.Cu")
		(net "XTAL_CPU0_X48M_X2")
	)
	(segment
		(start 392.44397 -311.21731)
		(end 387.718046 -311.21731)
		(width 0.10668)
		(layer "B.Cu")
		(net "XTAL_CPU0_X48M_X2")
	)
	(segment
		(start 394.12037 -311.21731)
		(end 394.01369 -311.32399)
		(width 0.10668)
		(layer "B.Cu")
		(net "XTAL_CPU0_X48M_X2")
	)
	(segment
		(start 398.336008 -312.689748)
		(end 396.86357 -311.21731)
		(width 0.10668)
		(layer "B.Cu")
		(net "XTAL_CPU0_X48M_X2")
	)
	(segment
		(start 393.63269 -311.61863)
		(end 393.52601 -311.51195)
		(width 0.10668)
		(layer "B.Cu")
		(net "XTAL_CPU0_X48M_X2")
	)
	(segment
		(start 393.41933 -311.21731)
		(end 393.14501 -311.21731)
		(width 0.10668)
		(layer "B.Cu")
		(net "XTAL_CPU0_X48M_X2")
	)
	(segment
		(start 393.52601 -311.51195)
		(end 393.52601 -311.32399)
		(width 0.10668)
		(layer "B.Cu")
		(net "XTAL_CPU0_X48M_X2")
	)
	(segment
		(start 394.01369 -311.51195)
		(end 393.90701 -311.61863)
		(width 0.10668)
		(layer "B.Cu")
		(net "XTAL_CPU0_X48M_X2")
	)
	(segment
		(start 392.65733 -311.61863)
		(end 392.55065 -311.51195)
		(width 0.10668)
		(layer "B.Cu")
		(net "XTAL_CPU0_X48M_X2")
	)
	(segment
		(start 380.22784 -297.28795)
		(end 380.22784 -296.51706)
		(width 0.10668)
		(layer "B.Cu")
		(net "XTAL_CPU0_X48M_X2")
	)
	(segment
		(start 393.03833 -311.51195)
		(end 392.93165 -311.61863)
		(width 0.10668)
		(layer "B.Cu")
		(net "XTAL_CPU0_X48M_X2")
	)
	(segment
		(start 394.01369 -311.32399)
		(end 394.01369 -311.51195)
		(width 0.10668)
		(layer "B.Cu")
		(net "XTAL_CPU0_X48M_X2")
	)
	(segment
		(start 396.86357 -311.21731)
		(end 394.12037 -311.21731)
		(width 0.10668)
		(layer "B.Cu")
		(net "XTAL_CPU0_X48M_X2")
	)
	(segment
		(start 392.55065 -311.32399)
		(end 392.44397 -311.21731)
		(width 0.10668)
		(layer "B.Cu")
		(net "XTAL_CPU0_X48M_X2")
	)
	(segment
		(start 379.28804 -295.690036)
		(end 379.28804 -296.51706)
		(width 0.10668)
		(layer "F.Cu")
		(net "XTAL_CPU0_X48M_X1")
	)
	(via
		(at 379.28804 -296.51706)
		(size 0.508)
		(drill 0.254)
		(layers "F.Cu" "B.Cu")
		(net "XTAL_CPU0_X48M_X1")
	)
	(segment
		(start 396.404846 -317.452248)
		(end 396.27302 -317.452248)
		(width 0.10668)
		(layer "B.Cu")
		(net "XTAL_CPU0_X48M_X1")
	)
	(segment
		(start 397.295878 -316.561216)
		(end 396.404846 -317.452248)
		(width 0.10668)
		(layer "B.Cu")
		(net "XTAL_CPU0_X48M_X1")
	)
	(segment
		(start 379.28804 -297.490896)
		(end 379.92812 -298.130976)
		(width 0.10668)
		(layer "B.Cu")
		(net "XTAL_CPU0_X48M_X1")
	)
	(segment
		(start 397.295878 -315.209174)
		(end 397.295878 -316.561216)
		(width 0.10668)
		(layer "B.Cu")
		(net "XTAL_CPU0_X48M_X1")
	)
	(segment
		(start 382.99517 -306.304442)
		(end 384.013456 -308.7624)
		(width 0.10668)
		(layer "B.Cu")
		(net "XTAL_CPU0_X48M_X1")
	)
	(segment
		(start 382.99517 -305.535584)
		(end 382.99517 -306.304442)
		(width 0.10668)
		(layer "B.Cu")
		(net "XTAL_CPU0_X48M_X1")
	)
	(segment
		(start 384.013456 -308.7624)
		(end 387.660388 -312.409332)
		(width 0.10668)
		(layer "B.Cu")
		(net "XTAL_CPU0_X48M_X1")
	)
	(segment
		(start 396.452852 -314.366148)
		(end 397.295878 -315.209174)
		(width 0.10668)
		(layer "B.Cu")
		(net "XTAL_CPU0_X48M_X1")
	)
	(segment
		(start 379.92812 -298.130976)
		(end 382.99517 -305.535584)
		(width 0.10668)
		(layer "B.Cu")
		(net "XTAL_CPU0_X48M_X1")
	)
	(segment
		(start 396.452852 -314.172092)
		(end 396.452852 -314.366148)
		(width 0.10668)
		(layer "B.Cu")
		(net "XTAL_CPU0_X48M_X1")
	)
	(segment
		(start 379.28804 -296.51706)
		(end 379.28804 -297.490896)
		(width 0.10668)
		(layer "B.Cu")
		(net "XTAL_CPU0_X48M_X1")
	)
	(segment
		(start 395.477492 -312.409332)
		(end 395.757908 -312.689748)
		(width 0.10668)
		(layer "B.Cu")
		(net "XTAL_CPU0_X48M_X1")
	)
	(segment
		(start 395.757908 -313.477148)
		(end 396.452852 -314.172092)
		(width 0.10668)
		(layer "B.Cu")
		(net "XTAL_CPU0_X48M_X1")
	)
	(segment
		(start 387.660388 -312.409332)
		(end 395.477492 -312.409332)
		(width 0.10668)
		(layer "B.Cu")
		(net "XTAL_CPU0_X48M_X1")
	)
	(segment
		(start 395.757908 -312.689748)
		(end 395.757908 -313.477148)
		(width 0.10668)
		(layer "B.Cu")
		(net "XTAL_CPU0_X48M_X1")
	)
	(segment
		(start 383.048002 -295.690036)
		(end 383.048002 -296.51706)
		(width 0.10668)
		(layer "F.Cu")
		(net "XTAL_CPU0_X32K_X2")
	)
	(via
		(at 383.048002 -296.51706)
		(size 0.508)
		(drill 0.254)
		(layers "F.Cu" "B.Cu")
		(net "XTAL_CPU0_X32K_X2")
	)
	(segment
		(start 392.449558 -310.148224)
		(end 388.283704 -310.148224)
		(width 0.10668)
		(layer "B.Cu")
		(net "XTAL_CPU0_X32K_X2")
	)
	(segment
		(start 401.138898 -313.60745)
		(end 401.138898 -312.97245)
		(width 0.10668)
		(layer "B.Cu")
		(net "XTAL_CPU0_X32K_X2")
	)
	(segment
		(start 383.048002 -298.104814)
		(end 383.048002 -296.51706)
		(width 0.10668)
		(layer "B.Cu")
		(net "XTAL_CPU0_X32K_X2")
	)
	(segment
		(start 401.162012 -313.782964)
		(end 401.162012 -313.630564)
		(width 0.10668)
		(layer "B.Cu")
		(net "XTAL_CPU0_X32K_X2")
	)
	(segment
		(start 383.576576 -302.269906)
		(end 383.576576 -299.380656)
		(width 0.10668)
		(layer "B.Cu")
		(net "XTAL_CPU0_X32K_X2")
	)
	(segment
		(start 402.900896 -316.371478)
		(end 402.900896 -316.917578)
		(width 0.10668)
		(layer "B.Cu")
		(net "XTAL_CPU0_X32K_X2")
	)
	(segment
		(start 402.139912 -314.760864)
		(end 402.139912 -314.925964)
		(width 0.10668)
		(layer "B.Cu")
		(net "XTAL_CPU0_X32K_X2")
	)
	(segment
		(start 402.139912 -315.610494)
		(end 402.900896 -316.371478)
		(width 0.10668)
		(layer "B.Cu")
		(net "XTAL_CPU0_X32K_X2")
	)
	(segment
		(start 401.162012 -313.630564)
		(end 401.138898 -313.60745)
		(width 0.10668)
		(layer "B.Cu")
		(net "XTAL_CPU0_X32K_X2")
	)
	(segment
		(start 402.139912 -314.925964)
		(end 402.139912 -315.610494)
		(width 0.10668)
		(layer "B.Cu")
		(net "XTAL_CPU0_X32K_X2")
	)
	(segment
		(start 397.8656 -309.699152)
		(end 392.89863 -309.699152)
		(width 0.10668)
		(layer "B.Cu")
		(net "XTAL_CPU0_X32K_X2")
	)
	(segment
		(start 385.824984 -307.689504)
		(end 383.582164 -302.275494)
		(width 0.10668)
		(layer "B.Cu")
		(net "XTAL_CPU0_X32K_X2")
	)
	(segment
		(start 401.162012 -313.782964)
		(end 402.139912 -314.760864)
		(width 0.10668)
		(layer "B.Cu")
		(net "XTAL_CPU0_X32K_X2")
	)
	(segment
		(start 392.89863 -309.699152)
		(end 392.449558 -310.148224)
		(width 0.10668)
		(layer "B.Cu")
		(net "XTAL_CPU0_X32K_X2")
	)
	(segment
		(start 388.283704 -310.148224)
		(end 385.824984 -307.689504)
		(width 0.10668)
		(layer "B.Cu")
		(net "XTAL_CPU0_X32K_X2")
	)
	(segment
		(start 383.576576 -299.380656)
		(end 383.048002 -298.104814)
		(width 0.10668)
		(layer "B.Cu")
		(net "XTAL_CPU0_X32K_X2")
	)
	(segment
		(start 401.138898 -312.97245)
		(end 397.8656 -309.699152)
		(width 0.10668)
		(layer "B.Cu")
		(net "XTAL_CPU0_X32K_X2")
	)
	(segment
		(start 383.582164 -302.275494)
		(end 383.576576 -302.269906)
		(width 0.10668)
		(layer "B.Cu")
		(net "XTAL_CPU0_X32K_X2")
	)
	(segment
		(start 382.107948 -295.690036)
		(end 382.107948 -296.51706)
		(width 0.10668)
		(layer "F.Cu")
		(net "XTAL_CPU0_X32K_X1")
	)
	(via
		(at 382.107948 -296.51706)
		(size 0.508)
		(drill 0.254)
		(layers "F.Cu" "B.Cu")
		(net "XTAL_CPU0_X32K_X1")
	)
	(segment
		(start 401.138644 -314.750196)
		(end 401.138644 -314.559696)
		(width 0.10668)
		(layer "B.Cu")
		(net "XTAL_CPU0_X32K_X1")
	)
	(segment
		(start 401.162012 -315.379608)
		(end 401.138644 -315.35624)
		(width 0.10668)
		(layer "B.Cu")
		(net "XTAL_CPU0_X32K_X1")
	)
	(segment
		(start 400.401028 -316.917578)
		(end 400.401028 -316.371478)
		(width 0.10668)
		(layer "B.Cu")
		(net "XTAL_CPU0_X32K_X1")
	)
	(segment
		(start 385.36626 -307.985414)
		(end 388.047738 -310.666892)
		(width 0.10668)
		(layer "B.Cu")
		(net "XTAL_CPU0_X32K_X1")
	)
	(segment
		(start 400.401028 -316.371478)
		(end 401.162012 -315.610494)
		(width 0.10668)
		(layer "B.Cu")
		(net "XTAL_CPU0_X32K_X1")
	)
	(segment
		(start 382.86182 -301.93869)
		(end 385.36626 -307.985414)
		(width 0.10668)
		(layer "B.Cu")
		(net "XTAL_CPU0_X32K_X1")
	)
	(segment
		(start 401.162012 -315.610494)
		(end 401.162012 -315.379608)
		(width 0.10668)
		(layer "B.Cu")
		(net "XTAL_CPU0_X32K_X1")
	)
	(segment
		(start 382.107948 -297.88104)
		(end 382.86182 -299.701458)
		(width 0.10668)
		(layer "B.Cu")
		(net "XTAL_CPU0_X32K_X1")
	)
	(segment
		(start 401.138644 -314.949332)
		(end 401.162012 -314.925964)
		(width 0.10668)
		(layer "B.Cu")
		(net "XTAL_CPU0_X32K_X1")
	)
	(segment
		(start 401.138644 -314.559696)
		(end 400.361912 -313.782964)
		(width 0.10668)
		(layer "B.Cu")
		(net "XTAL_CPU0_X32K_X1")
	)
	(segment
		(start 401.162012 -314.925964)
		(end 401.162012 -314.773564)
		(width 0.10668)
		(layer "B.Cu")
		(net "XTAL_CPU0_X32K_X1")
	)
	(segment
		(start 388.047738 -310.666892)
		(end 398.03324 -310.666892)
		(width 0.10668)
		(layer "B.Cu")
		(net "XTAL_CPU0_X32K_X1")
	)
	(segment
		(start 382.107948 -296.51706)
		(end 382.107948 -297.88104)
		(width 0.10668)
		(layer "B.Cu")
		(net "XTAL_CPU0_X32K_X1")
	)
	(segment
		(start 401.162012 -314.773564)
		(end 401.138644 -314.750196)
		(width 0.10668)
		(layer "B.Cu")
		(net "XTAL_CPU0_X32K_X1")
	)
	(segment
		(start 401.138644 -315.35624)
		(end 401.138644 -314.949332)
		(width 0.10668)
		(layer "B.Cu")
		(net "XTAL_CPU0_X32K_X1")
	)
	(segment
		(start 398.03324 -310.666892)
		(end 400.361912 -312.995564)
		(width 0.10668)
		(layer "B.Cu")
		(net "XTAL_CPU0_X32K_X1")
	)
	(segment
		(start 382.86182 -299.701458)
		(end 382.86182 -301.93869)
		(width 0.10668)
		(layer "B.Cu")
		(net "XTAL_CPU0_X32K_X1")
	)
	(segment
		(start 400.361912 -312.995564)
		(end 400.361912 -313.782964)
		(width 0.10668)
		(layer "B.Cu")
		(net "XTAL_CPU0_X32K_X1")
	)
	(segment
		(start 103.787956 -223.690434)
		(end 103.321104 -223.424496)
		(width 0.12954)
		(layer "F.Cu")
		(net "WAFL_CPU1_TX1_CPU0_RX0_DP")
	)
	(segment
		(start 349.847916 -225.310192)
		(end 349.381064 -225.044254)
		(width 0.12954)
		(layer "F.Cu")
		(net "WAFL_CPU1_TX1_CPU0_RX0_DP")
	)
	(via
		(at 103.321104 -223.424496)
		(size 0.4064)
		(drill 0.2032)
		(layers "F.Cu" "B.Cu")
		(net "WAFL_CPU1_TX1_CPU0_RX0_DP")
	)
	(via
		(at 146.445986 -189.265814)
		(size 0.4064)
		(drill 0.2032)
		(layers "F.Cu" "B.Cu")
		(net "WAFL_CPU1_TX1_CPU0_RX0_DP")
	)
	(via
		(at 349.381064 -225.044254)
		(size 0.4064)
		(drill 0.2032)
		(layers "F.Cu" "B.Cu")
		(net "WAFL_CPU1_TX1_CPU0_RX0_DP")
	)
	(segment
		(start 106.121962 -217.942414)
		(end 106.38409 -217.98661)
		(width 0.12954)
		(layer "B.Cu")
		(net "WAFL_CPU1_TX1_CPU0_RX0_DP")
	)
	(segment
		(start 349.570548 -217.569288)
		(end 349.718122 -217.925904)
		(width 0.12954)
		(layer "B.Cu")
		(net "WAFL_CPU1_TX1_CPU0_RX0_DP")
	)
	(segment
		(start 349.19412 -225.366834)
		(end 349.16237 -225.348546)
		(width 0.0762)
		(layer "B.Cu")
		(net "WAFL_CPU1_TX1_CPU0_RX0_DP")
	)
	(segment
		(start 107.602782 -217.119962)
		(end 107.913424 -216.898982)
		(width 0.12954)
		(layer "B.Cu")
		(net "WAFL_CPU1_TX1_CPU0_RX0_DP")
	)
	(segment
		(start 306.905914 -182.438294)
		(end 307.040534 -182.66791)
		(width 0.12954)
		(layer "B.Cu")
		(net "WAFL_CPU1_TX1_CPU0_RX0_DP")
	)
	(segment
		(start 307.040534 -182.66791)
		(end 307.409596 -182.763414)
		(width 0.12954)
		(layer "B.Cu")
		(net "WAFL_CPU1_TX1_CPU0_RX0_DP")
	)
	(segment
		(start 350.033844 -224.559368)
		(end 350.033082 -224.559876)
		(width 0.0762)
		(layer "B.Cu")
		(net "WAFL_CPU1_TX1_CPU0_RX0_DP")
	)
	(segment
		(start 348.393258 -214.729314)
		(end 348.290134 -214.978234)
		(width 0.12954)
		(layer "B.Cu")
		(net "WAFL_CPU1_TX1_CPU0_RX0_DP")
	)
	(segment
		(start 308.740302 -182.914798)
		(end 313.460892 -184.13984)
		(width 0.12954)
		(layer "B.Cu")
		(net "WAFL_CPU1_TX1_CPU0_RX0_DP")
	)
	(segment
		(start 103.01224 -221.193614)
		(end 103.01224 -221.174564)
		(width 0.0762)
		(layer "B.Cu")
		(net "WAFL_CPU1_TX1_CPU0_RX0_DP")
	)
	(segment
		(start 350.035622 -224.558352)
		(end 350.03486 -224.55886)
		(width 0.0762)
		(layer "B.Cu")
		(net "WAFL_CPU1_TX1_CPU0_RX0_DP")
	)
	(segment
		(start 103.007414 -223.424496)
		(end 102.950772 -223.367854)
		(width 0.0762)
		(layer "B.Cu")
		(net "WAFL_CPU1_TX1_CPU0_RX0_DP")
	)
	(segment
		(start 106.738928 -217.503502)
		(end 107.340654 -217.075512)
		(width 0.12954)
		(layer "B.Cu")
		(net "WAFL_CPU1_TX1_CPU0_RX0_DP")
	)
	(segment
		(start 104.697276 -219.543376)
		(end 104.96677 -219.273628)
		(width 0.12954)
		(layer "B.Cu")
		(net "WAFL_CPU1_TX1_CPU0_RX0_DP")
	)
	(segment
		(start 307.638704 -182.628794)
		(end 308.007258 -182.724298)
		(width 0.12954)
		(layer "B.Cu")
		(net "WAFL_CPU1_TX1_CPU0_RX0_DP")
	)
	(segment
		(start 349.321374 -217.466418)
		(end 349.570548 -217.569288)
		(width 0.12954)
		(layer "B.Cu")
		(net "WAFL_CPU1_TX1_CPU0_RX0_DP")
	)
	(segment
		(start 313.460892 -184.13984)
		(end 324.740778 -190.593472)
		(width 0.12954)
		(layer "B.Cu")
		(net "WAFL_CPU1_TX1_CPU0_RX0_DP")
	)
	(segment
		(start 349.067374 -225.044254)
		(end 349.381064 -225.044254)
		(width 0.0762)
		(layer "B.Cu")
		(net "WAFL_CPU1_TX1_CPU0_RX0_DP")
	)
	(segment
		(start 104.96677 -219.007944)
		(end 105.811574 -218.16314)
		(width 0.12954)
		(layer "B.Cu")
		(net "WAFL_CPU1_TX1_CPU0_RX0_DP")
	)
	(segment
		(start 348.879668 -216.400888)
		(end 349.128842 -216.503758)
		(width 0.12954)
		(layer "B.Cu")
		(net "WAFL_CPU1_TX1_CPU0_RX0_DP")
	)
	(segment
		(start 107.340654 -217.075512)
		(end 107.602782 -217.119962)
		(width 0.12954)
		(layer "B.Cu")
		(net "WAFL_CPU1_TX1_CPU0_RX0_DP")
	)
	(segment
		(start 163.77158 -177.866802)
		(end 165.116764 -177.488088)
		(width 0.12954)
		(layer "B.Cu")
		(net "WAFL_CPU1_TX1_CPU0_RX0_DP")
	)
	(segment
		(start 152.28443 -183.893714)
		(end 152.284176 -183.893714)
		(width 0.12954)
		(layer "B.Cu")
		(net "WAFL_CPU1_TX1_CPU0_RX0_DP")
	)
	(segment
		(start 104.431338 -219.543376)
		(end 104.697276 -219.543376)
		(width 0.12954)
		(layer "B.Cu")
		(net "WAFL_CPU1_TX1_CPU0_RX0_DP")
	)
	(segment
		(start 105.811574 -218.16314)
		(end 106.121962 -217.942414)
		(width 0.12954)
		(layer "B.Cu")
		(net "WAFL_CPU1_TX1_CPU0_RX0_DP")
	)
	(segment
		(start 104.162098 -220.0783)
		(end 104.162098 -219.812616)
		(width 0.12954)
		(layer "B.Cu")
		(net "WAFL_CPU1_TX1_CPU0_RX0_DP")
	)
	(segment
		(start 103.89235 -220.348048)
		(end 104.162098 -220.0783)
		(width 0.12954)
		(layer "B.Cu")
		(net "WAFL_CPU1_TX1_CPU0_RX0_DP")
	)
	(segment
		(start 349.615252 -218.174824)
		(end 349.76308 -218.531948)
		(width 0.12954)
		(layer "B.Cu")
		(net "WAFL_CPU1_TX1_CPU0_RX0_DP")
	)
	(segment
		(start 103.103426 -223.119696)
		(end 103.133906 -223.101916)
		(width 0.0762)
		(layer "B.Cu")
		(net "WAFL_CPU1_TX1_CPU0_RX0_DP")
	)
	(segment
		(start 165.116764 -177.488088)
		(end 305.636676 -182.10911)
		(width 0.12954)
		(layer "B.Cu")
		(net "WAFL_CPU1_TX1_CPU0_RX0_DP")
	)
	(segment
		(start 349.754952 -225.041206)
		(end 349.754952 -225.044762)
		(width 0.0762)
		(layer "B.Cu")
		(net "WAFL_CPU1_TX1_CPU0_RX0_DP")
	)
	(segment
		(start 349.276416 -216.860374)
		(end 349.173546 -217.109294)
		(width 0.12954)
		(layer "B.Cu")
		(net "WAFL_CPU1_TX1_CPU0_RX0_DP")
	)
	(segment
		(start 103.173022 -222.149924)
		(end 103.103426 -222.109284)
		(width 0.0762)
		(layer "B.Cu")
		(net "WAFL_CPU1_TX1_CPU0_RX0_DP")
	)
	(segment
		(start 350.225868 -221.343728)
		(end 350.225868 -224.234248)
		(width 0.0762)
		(layer "B.Cu")
		(net "WAFL_CPU1_TX1_CPU0_RX0_DP")
	)
	(segment
		(start 152.284176 -183.893714)
		(end 155.944062 -180.07076)
		(width 0.12954)
		(layer "B.Cu")
		(net "WAFL_CPU1_TX1_CPU0_RX0_DP")
	)
	(segment
		(start 350.03486 -224.55886)
		(end 350.033844 -224.559368)
		(width 0.0762)
		(layer "B.Cu")
		(net "WAFL_CPU1_TX1_CPU0_RX0_DP")
	)
	(segment
		(start 349.718122 -217.925904)
		(end 349.615252 -218.174824)
		(width 0.12954)
		(layer "B.Cu")
		(net "WAFL_CPU1_TX1_CPU0_RX0_DP")
	)
	(segment
		(start 348.73184 -216.043764)
		(end 348.879668 -216.400888)
		(width 0.12954)
		(layer "B.Cu")
		(net "WAFL_CPU1_TX1_CPU0_RX0_DP")
	)
	(segment
		(start 107.957874 -216.6366)
		(end 146.445986 -189.265814)
		(width 0.12954)
		(layer "B.Cu")
		(net "WAFL_CPU1_TX1_CPU0_RX0_DP")
	)
	(segment
		(start 350.159828 -218.991434)
		(end 350.159828 -221.258638)
		(width 0.12954)
		(layer "B.Cu")
		(net "WAFL_CPU1_TX1_CPU0_RX0_DP")
	)
	(segment
		(start 349.010732 -225.100896)
		(end 349.067374 -225.044254)
		(width 0.0762)
		(layer "B.Cu")
		(net "WAFL_CPU1_TX1_CPU0_RX0_DP")
	)
	(segment
		(start 103.321104 -223.424496)
		(end 103.007414 -223.424496)
		(width 0.0762)
		(layer "B.Cu")
		(net "WAFL_CPU1_TX1_CPU0_RX0_DP")
	)
	(segment
		(start 106.38409 -217.98661)
		(end 106.694732 -217.765884)
		(width 0.12954)
		(layer "B.Cu")
		(net "WAFL_CPU1_TX1_CPU0_RX0_DP")
	)
	(segment
		(start 349.56877 -225.366326)
		(end 349.568008 -225.366834)
		(width 0.0762)
		(layer "B.Cu")
		(net "WAFL_CPU1_TX1_CPU0_RX0_DP")
	)
	(segment
		(start 104.96677 -219.273628)
		(end 104.96677 -219.007944)
		(width 0.12954)
		(layer "B.Cu")
		(net "WAFL_CPU1_TX1_CPU0_RX0_DP")
	)
	(segment
		(start 350.069912 -224.53854)
		(end 350.037654 -224.557336)
		(width 0.0762)
		(layer "B.Cu")
		(net "WAFL_CPU1_TX1_CPU0_RX0_DP")
	)
	(segment
		(start 103.01224 -220.962474)
		(end 103.626666 -220.348048)
		(width 0.12954)
		(layer "B.Cu")
		(net "WAFL_CPU1_TX1_CPU0_RX0_DP")
	)
	(segment
		(start 348.83471 -215.794844)
		(end 348.73184 -216.043764)
		(width 0.12954)
		(layer "B.Cu")
		(net "WAFL_CPU1_TX1_CPU0_RX0_DP")
	)
	(segment
		(start 155.944062 -180.07076)
		(end 163.77158 -177.866802)
		(width 0.12954)
		(layer "B.Cu")
		(net "WAFL_CPU1_TX1_CPU0_RX0_DP")
	)
	(segment
		(start 308.007258 -182.724298)
		(end 308.142132 -182.95366)
		(width 0.12954)
		(layer "B.Cu")
		(net "WAFL_CPU1_TX1_CPU0_RX0_DP")
	)
	(segment
		(start 148.624036 -187.716922)
		(end 152.28443 -183.893714)
		(width 0.12954)
		(layer "B.Cu")
		(net "WAFL_CPU1_TX1_CPU0_RX0_DP")
	)
	(segment
		(start 350.012254 -218.634818)
		(end 350.159828 -218.991434)
		(width 0.12954)
		(layer "B.Cu")
		(net "WAFL_CPU1_TX1_CPU0_RX0_DP")
	)
	(segment
		(start 306.905914 -182.438548)
		(end 306.905914 -182.438294)
		(width 0.12954)
		(layer "B.Cu")
		(net "WAFL_CPU1_TX1_CPU0_RX0_DP")
	)
	(segment
		(start 307.409596 -182.763414)
		(end 307.638704 -182.628794)
		(width 0.12954)
		(layer "B.Cu")
		(net "WAFL_CPU1_TX1_CPU0_RX0_DP")
	)
	(segment
		(start 102.9462 -221.259654)
		(end 103.01224 -221.193614)
		(width 0.0762)
		(layer "B.Cu")
		(net "WAFL_CPU1_TX1_CPU0_RX0_DP")
	)
	(segment
		(start 102.9462 -221.804484)
		(end 102.9462 -221.259654)
		(width 0.0762)
		(layer "B.Cu")
		(net "WAFL_CPU1_TX1_CPU0_RX0_DP")
	)
	(segment
		(start 348.437962 -215.335104)
		(end 348.687136 -215.438228)
		(width 0.12954)
		(layer "B.Cu")
		(net "WAFL_CPU1_TX1_CPU0_RX0_DP")
	)
	(segment
		(start 350.159828 -221.258638)
		(end 350.159828 -221.277688)
		(width 0.0762)
		(layer "B.Cu")
		(net "WAFL_CPU1_TX1_CPU0_RX0_DP")
	)
	(segment
		(start 348.290134 -214.978234)
		(end 348.437962 -215.335104)
		(width 0.12954)
		(layer "B.Cu")
		(net "WAFL_CPU1_TX1_CPU0_RX0_DP")
	)
	(segment
		(start 349.128842 -216.503758)
		(end 349.276416 -216.860374)
		(width 0.12954)
		(layer "B.Cu")
		(net "WAFL_CPU1_TX1_CPU0_RX0_DP")
	)
	(segment
		(start 305.636676 -182.10911)
		(end 306.905914 -182.438548)
		(width 0.12954)
		(layer "B.Cu")
		(net "WAFL_CPU1_TX1_CPU0_RX0_DP")
	)
	(segment
		(start 308.142132 -182.95366)
		(end 308.511194 -183.049418)
		(width 0.12954)
		(layer "B.Cu")
		(net "WAFL_CPU1_TX1_CPU0_RX0_DP")
	)
	(segment
		(start 146.445986 -189.265814)
		(end 148.624036 -187.716922)
		(width 0.12954)
		(layer "B.Cu")
		(net "WAFL_CPU1_TX1_CPU0_RX0_DP")
	)
	(segment
		(start 308.511194 -183.049418)
		(end 308.740302 -182.914798)
		(width 0.12954)
		(layer "B.Cu")
		(net "WAFL_CPU1_TX1_CPU0_RX0_DP")
	)
	(segment
		(start 324.740778 -190.593472)
		(end 348.051374 -213.904322)
		(width 0.12954)
		(layer "B.Cu")
		(net "WAFL_CPU1_TX1_CPU0_RX0_DP")
	)
	(segment
		(start 103.01224 -221.174564)
		(end 103.01224 -220.962474)
		(width 0.12954)
		(layer "B.Cu")
		(net "WAFL_CPU1_TX1_CPU0_RX0_DP")
	)
	(segment
		(start 349.173546 -217.109294)
		(end 349.321374 -217.466418)
		(width 0.12954)
		(layer "B.Cu")
		(net "WAFL_CPU1_TX1_CPU0_RX0_DP")
	)
	(segment
		(start 107.913424 -216.898982)
		(end 107.957874 -216.6366)
		(width 0.12954)
		(layer "B.Cu")
		(net "WAFL_CPU1_TX1_CPU0_RX0_DP")
	)
	(segment
		(start 104.162098 -219.812616)
		(end 104.431338 -219.543376)
		(width 0.12954)
		(layer "B.Cu")
		(net "WAFL_CPU1_TX1_CPU0_RX0_DP")
	)
	(segment
		(start 103.133906 -223.101916)
		(end 103.173022 -223.079056)
		(width 0.0762)
		(layer "B.Cu")
		(net "WAFL_CPU1_TX1_CPU0_RX0_DP")
	)
	(segment
		(start 348.051374 -213.904322)
		(end 348.393258 -214.729314)
		(width 0.12954)
		(layer "B.Cu")
		(net "WAFL_CPU1_TX1_CPU0_RX0_DP")
	)
	(segment
		(start 348.687136 -215.438228)
		(end 348.83471 -215.794844)
		(width 0.12954)
		(layer "B.Cu")
		(net "WAFL_CPU1_TX1_CPU0_RX0_DP")
	)
	(segment
		(start 106.694732 -217.765884)
		(end 106.738928 -217.503502)
		(width 0.12954)
		(layer "B.Cu")
		(net "WAFL_CPU1_TX1_CPU0_RX0_DP")
	)
	(segment
		(start 350.159828 -221.277688)
		(end 350.225868 -221.343728)
		(width 0.0762)
		(layer "B.Cu")
		(net "WAFL_CPU1_TX1_CPU0_RX0_DP")
	)
	(segment
		(start 349.76308 -218.531948)
		(end 350.012254 -218.634818)
		(width 0.12954)
		(layer "B.Cu")
		(net "WAFL_CPU1_TX1_CPU0_RX0_DP")
	)
	(segment
		(start 350.037654 -224.557336)
		(end 350.035622 -224.558352)
		(width 0.0762)
		(layer "B.Cu")
		(net "WAFL_CPU1_TX1_CPU0_RX0_DP")
	)
	(segment
		(start 103.626666 -220.348048)
		(end 103.89235 -220.348048)
		(width 0.12954)
		(layer "B.Cu")
		(net "WAFL_CPU1_TX1_CPU0_RX0_DP")
	)
	(arc
		(start 349.754952 -225.044762)
		(mid 349.705053 -225.230556)
		(end 349.56877 -225.366326)
		(width 0.0762)
		(layer "B.Cu")
		(net "WAFL_CPU1_TX1_CPU0_RX0_DP")
	)
	(arc
		(start 349.16237 -225.348546)
		(mid 349.061541 -225.240024)
		(end 349.010732 -225.100896)
		(width 0.0762)
		(layer "B.Cu")
		(net "WAFL_CPU1_TX1_CPU0_RX0_DP")
	)
	(arc
		(start 103.173022 -223.079056)
		(mid 103.416349 -222.61449)
		(end 103.173022 -222.149924)
		(width 0.0762)
		(layer "B.Cu")
		(net "WAFL_CPU1_TX1_CPU0_RX0_DP")
	)
	(arc
		(start 102.950772 -223.367854)
		(mid 103.002022 -223.228358)
		(end 103.103426 -223.119696)
		(width 0.0762)
		(layer "B.Cu")
		(net "WAFL_CPU1_TX1_CPU0_RX0_DP")
	)
	(arc
		(start 349.568008 -225.366834)
		(mid 349.381064 -225.417089)
		(end 349.19412 -225.366834)
		(width 0.0762)
		(layer "B.Cu")
		(net "WAFL_CPU1_TX1_CPU0_RX0_DP")
	)
	(arc
		(start 103.103426 -222.109284)
		(mid 103.088404 -222.097966)
		(end 103.073962 -222.085916)
		(width 0.0762)
		(layer "B.Cu")
		(net "WAFL_CPU1_TX1_CPU0_RX0_DP")
	)
	(arc
		(start 350.225868 -224.234248)
		(mid 350.184613 -224.405219)
		(end 350.069912 -224.53854)
		(width 0.0762)
		(layer "B.Cu")
		(net "WAFL_CPU1_TX1_CPU0_RX0_DP")
	)
	(arc
		(start 103.073962 -222.085916)
		(mid 102.979683 -221.958999)
		(end 102.9462 -221.804484)
		(width 0.0762)
		(layer "B.Cu")
		(net "WAFL_CPU1_TX1_CPU0_RX0_DP")
	)
	(arc
		(start 350.033082 -224.559876)
		(mid 349.829463 -224.763244)
		(end 349.754952 -225.041206)
		(width 0.0762)
		(layer "B.Cu")
		(net "WAFL_CPU1_TX1_CPU0_RX0_DP")
	)
	(segment
		(start 102.847902 -223.690434)
		(end 102.38105 -223.424496)
		(width 0.12954)
		(layer "F.Cu")
		(net "WAFL_CPU1_TX1_CPU0_RX0_DN")
	)
	(segment
		(start 348.907862 -225.310192)
		(end 348.44101 -225.044254)
		(width 0.12954)
		(layer "F.Cu")
		(net "WAFL_CPU1_TX1_CPU0_RX0_DN")
	)
	(via
		(at 102.38105 -223.424496)
		(size 0.4064)
		(drill 0.2032)
		(layers "F.Cu" "B.Cu")
		(net "WAFL_CPU1_TX1_CPU0_RX0_DN")
	)
	(via
		(at 348.44101 -225.044254)
		(size 0.4064)
		(drill 0.2032)
		(layers "F.Cu" "B.Cu")
		(net "WAFL_CPU1_TX1_CPU0_RX0_DN")
	)
	(via
		(at 135.987028 -196.307456)
		(size 0.4064)
		(drill 0.2032)
		(layers "F.Cu" "B.Cu")
		(net "WAFL_CPU1_TX1_CPU0_RX0_DN")
	)
	(segment
		(start 348.7547 -225.044254)
		(end 348.819216 -225.10877)
		(width 0.0762)
		(layer "B.Cu")
		(net "WAFL_CPU1_TX1_CPU0_RX0_DN")
	)
	(segment
		(start 102.759256 -223.35998)
		(end 102.69474 -223.424496)
		(width 0.0762)
		(layer "B.Cu")
		(net "WAFL_CPU1_TX1_CPU0_RX0_DN")
	)
	(segment
		(start 348.324932 -213.721442)
		(end 324.938644 -190.334646)
		(width 0.12954)
		(layer "B.Cu")
		(net "WAFL_CPU1_TX1_CPU0_RX0_DN")
	)
	(segment
		(start 102.69474 -223.424496)
		(end 102.38105 -223.424496)
		(width 0.0762)
		(layer "B.Cu")
		(net "WAFL_CPU1_TX1_CPU0_RX0_DN")
	)
	(segment
		(start 350.482408 -221.258638)
		(end 350.482408 -218.927172)
		(width 0.12954)
		(layer "B.Cu")
		(net "WAFL_CPU1_TX1_CPU0_RX0_DN")
	)
	(segment
		(start 102.68966 -220.828616)
		(end 102.68966 -221.174564)
		(width 0.12954)
		(layer "B.Cu")
		(net "WAFL_CPU1_TX1_CPU0_RX0_DN")
	)
	(segment
		(start 350.416368 -221.343728)
		(end 350.482408 -221.277688)
		(width 0.0762)
		(layer "B.Cu")
		(net "WAFL_CPU1_TX1_CPU0_RX0_DN")
	)
	(segment
		(start 103.038148 -222.29191)
		(end 103.068628 -222.30969)
		(width 0.0762)
		(layer "B.Cu")
		(net "WAFL_CPU1_TX1_CPU0_RX0_DN")
	)
	(segment
		(start 324.938644 -190.334646)
		(end 313.583574 -183.838342)
		(width 0.12954)
		(layer "B.Cu")
		(net "WAFL_CPU1_TX1_CPU0_RX0_DN")
	)
	(segment
		(start 350.165416 -224.703386)
		(end 350.171766 -224.69983)
		(width 0.0762)
		(layer "B.Cu")
		(net "WAFL_CPU1_TX1_CPU0_RX0_DN")
	)
	(segment
		(start 350.482408 -218.927172)
		(end 348.324932 -213.721442)
		(width 0.12954)
		(layer "B.Cu")
		(net "WAFL_CPU1_TX1_CPU0_RX0_DN")
	)
	(segment
		(start 102.68966 -221.174564)
		(end 102.68966 -221.193614)
		(width 0.0762)
		(layer "B.Cu")
		(net "WAFL_CPU1_TX1_CPU0_RX0_DN")
	)
	(segment
		(start 102.999032 -222.26905)
		(end 103.038148 -222.29191)
		(width 0.0762)
		(layer "B.Cu")
		(net "WAFL_CPU1_TX1_CPU0_RX0_DN")
	)
	(segment
		(start 349.058992 -225.50882)
		(end 349.081598 -225.522028)
		(width 0.0762)
		(layer "B.Cu")
		(net "WAFL_CPU1_TX1_CPU0_RX0_DN")
	)
	(segment
		(start 313.583574 -183.838342)
		(end 305.683158 -181.7878)
		(width 0.12954)
		(layer "B.Cu")
		(net "WAFL_CPU1_TX1_CPU0_RX0_DN")
	)
	(segment
		(start 103.038148 -222.93707)
		(end 102.999032 -222.95993)
		(width 0.0762)
		(layer "B.Cu")
		(net "WAFL_CPU1_TX1_CPU0_RX0_DN")
	)
	(segment
		(start 350.128586 -224.724976)
		(end 350.130364 -224.72396)
		(width 0.0762)
		(layer "B.Cu")
		(net "WAFL_CPU1_TX1_CPU0_RX0_DN")
	)
	(segment
		(start 350.416368 -224.234248)
		(end 350.416368 -221.343728)
		(width 0.0762)
		(layer "B.Cu")
		(net "WAFL_CPU1_TX1_CPU0_RX0_DN")
	)
	(segment
		(start 350.130364 -224.72396)
		(end 350.165416 -224.703386)
		(width 0.0762)
		(layer "B.Cu")
		(net "WAFL_CPU1_TX1_CPU0_RX0_DN")
	)
	(segment
		(start 348.44101 -225.044254)
		(end 348.7547 -225.044254)
		(width 0.0762)
		(layer "B.Cu")
		(net "WAFL_CPU1_TX1_CPU0_RX0_DN")
	)
	(segment
		(start 165.077394 -177.163984)
		(end 156.87421 -179.473606)
		(width 0.12954)
		(layer "B.Cu")
		(net "WAFL_CPU1_TX1_CPU0_RX0_DN")
	)
	(segment
		(start 105.602532 -217.915744)
		(end 102.68966 -220.828616)
		(width 0.12954)
		(layer "B.Cu")
		(net "WAFL_CPU1_TX1_CPU0_RX0_DN")
	)
	(segment
		(start 155.77185 -179.783994)
		(end 148.411946 -187.471558)
		(width 0.12954)
		(layer "B.Cu")
		(net "WAFL_CPU1_TX1_CPU0_RX0_DN")
	)
	(segment
		(start 102.7557 -221.259654)
		(end 102.7557 -221.804992)
		(width 0.0762)
		(layer "B.Cu")
		(net "WAFL_CPU1_TX1_CPU0_RX0_DN")
	)
	(segment
		(start 349.669354 -225.528632)
		(end 349.669608 -225.528124)
		(width 0.0762)
		(layer "B.Cu")
		(net "WAFL_CPU1_TX1_CPU0_RX0_DN")
	)
	(segment
		(start 102.68966 -221.193614)
		(end 102.7557 -221.259654)
		(width 0.0762)
		(layer "B.Cu")
		(net "WAFL_CPU1_TX1_CPU0_RX0_DN")
	)
	(segment
		(start 135.987028 -196.307456)
		(end 105.602532 -217.915744)
		(width 0.12954)
		(layer "B.Cu")
		(net "WAFL_CPU1_TX1_CPU0_RX0_DN")
	)
	(segment
		(start 305.683158 -181.7878)
		(end 165.077394 -177.163984)
		(width 0.12954)
		(layer "B.Cu")
		(net "WAFL_CPU1_TX1_CPU0_RX0_DN")
	)
	(segment
		(start 349.083122 -225.523044)
		(end 349.098616 -225.53168)
		(width 0.0762)
		(layer "B.Cu")
		(net "WAFL_CPU1_TX1_CPU0_RX0_DN")
	)
	(segment
		(start 350.482408 -221.277688)
		(end 350.482408 -221.258638)
		(width 0.0762)
		(layer "B.Cu")
		(net "WAFL_CPU1_TX1_CPU0_RX0_DN")
	)
	(segment
		(start 156.87421 -179.473606)
		(end 155.77185 -179.783994)
		(width 0.12954)
		(layer "B.Cu")
		(net "WAFL_CPU1_TX1_CPU0_RX0_DN")
	)
	(segment
		(start 350.128332 -224.724976)
		(end 350.128586 -224.724976)
		(width 0.0762)
		(layer "B.Cu")
		(net "WAFL_CPU1_TX1_CPU0_RX0_DN")
	)
	(segment
		(start 103.068628 -222.91929)
		(end 103.038148 -222.93707)
		(width 0.0762)
		(layer "B.Cu")
		(net "WAFL_CPU1_TX1_CPU0_RX0_DN")
	)
	(segment
		(start 349.945452 -225.044762)
		(end 349.945452 -225.041206)
		(width 0.0762)
		(layer "B.Cu")
		(net "WAFL_CPU1_TX1_CPU0_RX0_DN")
	)
	(segment
		(start 349.081598 -225.522028)
		(end 349.083122 -225.523044)
		(width 0.0762)
		(layer "B.Cu")
		(net "WAFL_CPU1_TX1_CPU0_RX0_DN")
	)
	(segment
		(start 148.411946 -187.471558)
		(end 135.987028 -196.307456)
		(width 0.12954)
		(layer "B.Cu")
		(net "WAFL_CPU1_TX1_CPU0_RX0_DN")
	)
	(arc
		(start 102.7557 -221.804992)
		(mid 102.820279 -222.066954)
		(end 102.999032 -222.26905)
		(width 0.0762)
		(layer "B.Cu")
		(net "WAFL_CPU1_TX1_CPU0_RX0_DN")
	)
	(arc
		(start 348.819216 -225.10877)
		(mid 348.820514 -225.119324)
		(end 348.82201 -225.129852)
		(width 0.0762)
		(layer "B.Cu")
		(net "WAFL_CPU1_TX1_CPU0_RX0_DN")
	)
	(arc
		(start 349.669608 -225.528124)
		(mid 349.871666 -225.323038)
		(end 349.945452 -225.044762)
		(width 0.0762)
		(layer "B.Cu")
		(net "WAFL_CPU1_TX1_CPU0_RX0_DN")
	)
	(arc
		(start 103.068628 -222.30969)
		(mid 103.225605 -222.61449)
		(end 103.068628 -222.91929)
		(width 0.0762)
		(layer "B.Cu")
		(net "WAFL_CPU1_TX1_CPU0_RX0_DN")
	)
	(arc
		(start 349.098616 -225.53168)
		(mid 349.384389 -225.607721)
		(end 349.669354 -225.528632)
		(width 0.0762)
		(layer "B.Cu")
		(net "WAFL_CPU1_TX1_CPU0_RX0_DN")
	)
	(arc
		(start 349.945452 -225.041206)
		(mid 349.994473 -224.858567)
		(end 350.128332 -224.724976)
		(width 0.0762)
		(layer "B.Cu")
		(net "WAFL_CPU1_TX1_CPU0_RX0_DN")
	)
	(arc
		(start 350.171766 -224.69983)
		(mid 350.351495 -224.49721)
		(end 350.416368 -224.234248)
		(width 0.0762)
		(layer "B.Cu")
		(net "WAFL_CPU1_TX1_CPU0_RX0_DN")
	)
	(arc
		(start 102.999032 -222.95993)
		(mid 102.841502 -223.125001)
		(end 102.76205 -223.338898)
		(width 0.0762)
		(layer "B.Cu")
		(net "WAFL_CPU1_TX1_CPU0_RX0_DN")
	)
	(arc
		(start 348.82201 -225.129852)
		(mid 348.901459 -225.343751)
		(end 349.058992 -225.50882)
		(width 0.0762)
		(layer "B.Cu")
		(net "WAFL_CPU1_TX1_CPU0_RX0_DN")
	)
	(arc
		(start 102.76205 -223.338898)
		(mid 102.760554 -223.349426)
		(end 102.759256 -223.35998)
		(width 0.0762)
		(layer "B.Cu")
		(net "WAFL_CPU1_TX1_CPU0_RX0_DN")
	)
	(segment
		(start 104.72801 -225.310446)
		(end 104.261158 -225.044508)
		(width 0.12954)
		(layer "F.Cu")
		(net "WAFL_CPU0_TX0_CPU1_RX1_DP")
	)
	(segment
		(start 348.907862 -223.69018)
		(end 348.44101 -223.424242)
		(width 0.12954)
		(layer "F.Cu")
		(net "WAFL_CPU0_TX0_CPU1_RX1_DP")
	)
	(via
		(at 348.44101 -223.424242)
		(size 0.4064)
		(drill 0.2032)
		(layers "F.Cu" "B.Cu")
		(net "WAFL_CPU0_TX0_CPU1_RX1_DP")
	)
	(via
		(at 315.074046 -186.379866)
		(size 0.4064)
		(drill 0.2032)
		(layers "F.Cu" "B.Cu")
		(net "WAFL_CPU0_TX0_CPU1_RX1_DP")
	)
	(via
		(at 104.261158 -225.044508)
		(size 0.4064)
		(drill 0.2032)
		(layers "F.Cu" "B.Cu")
		(net "WAFL_CPU0_TX0_CPU1_RX1_DP")
	)
	(segment
		(start 347.05163 -216.699338)
		(end 347.297502 -216.801192)
		(width 0.12954)
		(layer "B.Cu")
		(net "WAFL_CPU0_TX0_CPU1_RX1_DP")
	)
	(segment
		(start 103.947468 -225.044508)
		(end 104.261158 -225.044508)
		(width 0.0762)
		(layer "B.Cu")
		(net "WAFL_CPU0_TX0_CPU1_RX1_DP")
	)
	(segment
		(start 108.05414 -218.532202)
		(end 107.788456 -218.487498)
		(width 0.12954)
		(layer "B.Cu")
		(net "WAFL_CPU0_TX0_CPU1_RX1_DP")
	)
	(segment
		(start 161.432748 -179.990496)
		(end 161.432748 -179.99075)
		(width 0.12954)
		(layer "B.Cu")
		(net "WAFL_CPU0_TX0_CPU1_RX1_DP")
	)
	(segment
		(start 154.811476 -183.568594)
		(end 154.544522 -183.84774)
		(width 0.12954)
		(layer "B.Cu")
		(net "WAFL_CPU0_TX0_CPU1_RX1_DP")
	)
	(segment
		(start 107.474004 -218.711018)
		(end 107.429046 -218.976956)
		(width 0.12954)
		(layer "B.Cu")
		(net "WAFL_CPU0_TX0_CPU1_RX1_DP")
	)
	(segment
		(start 349.129858 -222.918528)
		(end 349.10014 -222.935546)
		(width 0.0762)
		(layer "B.Cu")
		(net "WAFL_CPU0_TX0_CPU1_RX1_DP")
	)
	(segment
		(start 104.58323 -223.889062)
		(end 104.546654 -223.910398)
		(width 0.0762)
		(layer "B.Cu")
		(net "WAFL_CPU0_TX0_CPU1_RX1_DP")
	)
	(segment
		(start 104.892348 -221.174564)
		(end 104.892348 -221.193614)
		(width 0.0762)
		(layer "B.Cu")
		(net "WAFL_CPU0_TX0_CPU1_RX1_DP")
	)
	(segment
		(start 347.777054 -218.45016)
		(end 347.92285 -218.802458)
		(width 0.12954)
		(layer "B.Cu")
		(net "WAFL_CPU0_TX0_CPU1_RX1_DP")
	)
	(segment
		(start 106.430064 -219.45346)
		(end 104.892348 -220.991176)
		(width 0.12954)
		(layer "B.Cu")
		(net "WAFL_CPU0_TX0_CPU1_RX1_DP")
	)
	(segment
		(start 104.546654 -223.910398)
		(end 104.54513 -223.911414)
		(width 0.0762)
		(layer "B.Cu")
		(net "WAFL_CPU0_TX0_CPU1_RX1_DP")
	)
	(segment
		(start 347.733112 -217.852752)
		(end 347.878654 -218.204542)
		(width 0.12954)
		(layer "B.Cu")
		(net "WAFL_CPU0_TX0_CPU1_RX1_DP")
	)
	(segment
		(start 107.788456 -218.487498)
		(end 107.474004 -218.711018)
		(width 0.12954)
		(layer "B.Cu")
		(net "WAFL_CPU0_TX0_CPU1_RX1_DP")
	)
	(segment
		(start 348.081092 -223.548448)
		(end 348.070678 -223.481138)
		(width 0.0762)
		(layer "B.Cu")
		(net "WAFL_CPU0_TX0_CPU1_RX1_DP")
	)
	(segment
		(start 104.892348 -220.991176)
		(end 104.892348 -221.174564)
		(width 0.12954)
		(layer "B.Cu")
		(net "WAFL_CPU0_TX0_CPU1_RX1_DP")
	)
	(segment
		(start 348.12732 -223.424242)
		(end 348.44101 -223.424242)
		(width 0.0762)
		(layer "B.Cu")
		(net "WAFL_CPU0_TX0_CPU1_RX1_DP")
	)
	(segment
		(start 156.696664 -181.323996)
		(end 156.401008 -181.63286)
		(width 0.12954)
		(layer "B.Cu")
		(net "WAFL_CPU0_TX0_CPU1_RX1_DP")
	)
	(segment
		(start 315.074046 -186.379866)
		(end 324.13829 -191.56553)
		(width 0.12954)
		(layer "B.Cu")
		(net "WAFL_CPU0_TX0_CPU1_RX1_DP")
	)
	(segment
		(start 108.3691 -218.308428)
		(end 108.05414 -218.532202)
		(width 0.12954)
		(layer "B.Cu")
		(net "WAFL_CPU0_TX0_CPU1_RX1_DP")
	)
	(segment
		(start 304.210974 -183.196484)
		(end 166.16934 -178.656742)
		(width 0.12954)
		(layer "B.Cu")
		(net "WAFL_CPU0_TX0_CPU1_RX1_DP")
	)
	(segment
		(start 348.35846 -219.853764)
		(end 348.604078 -219.955618)
		(width 0.12954)
		(layer "B.Cu")
		(net "WAFL_CPU0_TX0_CPU1_RX1_DP")
	)
	(segment
		(start 108.413804 -218.042744)
		(end 108.413804 -218.04249)
		(width 0.12954)
		(layer "B.Cu")
		(net "WAFL_CPU0_TX0_CPU1_RX1_DP")
	)
	(segment
		(start 348.257114 -223.748854)
		(end 348.171262 -223.693228)
		(width 0.0762)
		(layer "B.Cu")
		(net "WAFL_CPU0_TX0_CPU1_RX1_DP")
	)
	(segment
		(start 349.058992 -222.268796)
		(end 349.129858 -222.309944)
		(width 0.0762)
		(layer "B.Cu")
		(net "WAFL_CPU0_TX0_CPU1_RX1_DP")
	)
	(segment
		(start 348.643194 -223.737678)
		(end 348.627446 -223.74733)
		(width 0.0762)
		(layer "B.Cu")
		(net "WAFL_CPU0_TX0_CPU1_RX1_DP")
	)
	(segment
		(start 313.908948 -185.71337)
		(end 304.210974 -183.196484)
		(width 0.12954)
		(layer "B.Cu")
		(net "WAFL_CPU0_TX0_CPU1_RX1_DP")
	)
	(segment
		(start 156.40685 -181.9021)
		(end 156.139896 -182.181246)
		(width 0.12954)
		(layer "B.Cu")
		(net "WAFL_CPU0_TX0_CPU1_RX1_DP")
	)
	(segment
		(start 315.074046 -186.379866)
		(end 313.908948 -185.71337)
		(width 0.12954)
		(layer "B.Cu")
		(net "WAFL_CPU0_TX0_CPU1_RX1_DP")
	)
	(segment
		(start 154.807158 -183.36768)
		(end 154.811476 -183.568594)
		(width 0.12954)
		(layer "B.Cu")
		(net "WAFL_CPU0_TX0_CPU1_RX1_DP")
	)
	(segment
		(start 156.401008 -181.63286)
		(end 156.40685 -181.9021)
		(width 0.12954)
		(layer "B.Cu")
		(net "WAFL_CPU0_TX0_CPU1_RX1_DP")
	)
	(segment
		(start 345.829128 -213.256114)
		(end 346.374212 -214.572342)
		(width 0.12954)
		(layer "B.Cu")
		(net "WAFL_CPU0_TX0_CPU1_RX1_DP")
	)
	(segment
		(start 347.443044 -217.152982)
		(end 347.341444 -217.3986)
		(width 0.12954)
		(layer "B.Cu")
		(net "WAFL_CPU0_TX0_CPU1_RX1_DP")
	)
	(segment
		(start 154.275028 -183.853582)
		(end 149.550374 -188.788802)
		(width 0.12954)
		(layer "B.Cu")
		(net "WAFL_CPU0_TX0_CPU1_RX1_DP")
	)
	(segment
		(start 349.098108 -222.936816)
		(end 349.058992 -222.959676)
		(width 0.0762)
		(layer "B.Cu")
		(net "WAFL_CPU0_TX0_CPU1_RX1_DP")
	)
	(segment
		(start 104.892348 -221.193614)
		(end 104.826308 -221.259654)
		(width 0.0762)
		(layer "B.Cu")
		(net "WAFL_CPU0_TX0_CPU1_RX1_DP")
	)
	(segment
		(start 347.48724 -217.750898)
		(end 347.733112 -217.852752)
		(width 0.12954)
		(layer "B.Cu")
		(net "WAFL_CPU0_TX0_CPU1_RX1_DP")
	)
	(segment
		(start 348.212664 -219.501466)
		(end 348.35846 -219.853764)
		(width 0.12954)
		(layer "B.Cu")
		(net "WAFL_CPU0_TX0_CPU1_RX1_DP")
	)
	(segment
		(start 156.139896 -182.181246)
		(end 155.870148 -182.187342)
		(width 0.12954)
		(layer "B.Cu")
		(net "WAFL_CPU0_TX0_CPU1_RX1_DP")
	)
	(segment
		(start 347.878654 -218.204542)
		(end 347.777054 -218.45016)
		(width 0.12954)
		(layer "B.Cu")
		(net "WAFL_CPU0_TX0_CPU1_RX1_DP")
	)
	(segment
		(start 107.114086 -219.20073)
		(end 106.848656 -219.156026)
		(width 0.12954)
		(layer "B.Cu")
		(net "WAFL_CPU0_TX0_CPU1_RX1_DP")
	)
	(segment
		(start 348.658688 -223.729042)
		(end 348.658688 -223.728788)
		(width 0.0762)
		(layer "B.Cu")
		(net "WAFL_CPU0_TX0_CPU1_RX1_DP")
	)
	(segment
		(start 346.664026 -215.272112)
		(end 347.007434 -216.101422)
		(width 0.12954)
		(layer "B.Cu")
		(net "WAFL_CPU0_TX0_CPU1_RX1_DP")
	)
	(segment
		(start 103.890826 -224.987866)
		(end 103.947468 -225.044508)
		(width 0.0762)
		(layer "B.Cu")
		(net "WAFL_CPU0_TX0_CPU1_RX1_DP")
	)
	(segment
		(start 348.815914 -221.324424)
		(end 348.815914 -221.80423)
		(width 0.0762)
		(layer "B.Cu")
		(net "WAFL_CPU0_TX0_CPU1_RX1_DP")
	)
	(segment
		(start 155.609036 -182.735474)
		(end 155.342082 -183.01462)
		(width 0.12954)
		(layer "B.Cu")
		(net "WAFL_CPU0_TX0_CPU1_RX1_DP")
	)
	(segment
		(start 348.749874 -221.258384)
		(end 348.815914 -221.324424)
		(width 0.0762)
		(layer "B.Cu")
		(net "WAFL_CPU0_TX0_CPU1_RX1_DP")
	)
	(segment
		(start 346.418154 -215.170258)
		(end 346.664026 -215.272112)
		(width 0.12954)
		(layer "B.Cu")
		(net "WAFL_CPU0_TX0_CPU1_RX1_DP")
	)
	(segment
		(start 154.805634 -183.2991)
		(end 154.807158 -183.36768)
		(width 0.12954)
		(layer "B.Cu")
		(net "WAFL_CPU0_TX0_CPU1_RX1_DP")
	)
	(segment
		(start 347.007434 -216.101422)
		(end 346.905834 -216.34704)
		(width 0.12954)
		(layer "B.Cu")
		(net "WAFL_CPU0_TX0_CPU1_RX1_DP")
	)
	(segment
		(start 349.09887 -222.936308)
		(end 349.098108 -222.936816)
		(width 0.0762)
		(layer "B.Cu")
		(net "WAFL_CPU0_TX0_CPU1_RX1_DP")
	)
	(segment
		(start 346.905834 -216.34704)
		(end 347.05163 -216.699338)
		(width 0.12954)
		(layer "B.Cu")
		(net "WAFL_CPU0_TX0_CPU1_RX1_DP")
	)
	(segment
		(start 161.432748 -179.99075)
		(end 156.696664 -181.323996)
		(width 0.12954)
		(layer "B.Cu")
		(net "WAFL_CPU0_TX0_CPU1_RX1_DP")
	)
	(segment
		(start 108.413804 -218.04249)
		(end 108.3691 -218.308428)
		(width 0.12954)
		(layer "B.Cu")
		(net "WAFL_CPU0_TX0_CPU1_RX1_DP")
	)
	(segment
		(start 154.544522 -183.84774)
		(end 154.275028 -183.853582)
		(width 0.12954)
		(layer "B.Cu")
		(net "WAFL_CPU0_TX0_CPU1_RX1_DP")
	)
	(segment
		(start 346.374212 -214.572342)
		(end 346.272358 -214.81796)
		(width 0.12954)
		(layer "B.Cu")
		(net "WAFL_CPU0_TX0_CPU1_RX1_DP")
	)
	(segment
		(start 346.272358 -214.81796)
		(end 346.418154 -215.170258)
		(width 0.12954)
		(layer "B.Cu")
		(net "WAFL_CPU0_TX0_CPU1_RX1_DP")
	)
	(segment
		(start 347.92285 -218.802458)
		(end 348.168468 -218.904312)
		(width 0.12954)
		(layer "B.Cu")
		(net "WAFL_CPU0_TX0_CPU1_RX1_DP")
	)
	(segment
		(start 348.070678 -223.480884)
		(end 348.12732 -223.424242)
		(width 0.0762)
		(layer "B.Cu")
		(net "WAFL_CPU0_TX0_CPU1_RX1_DP")
	)
	(segment
		(start 104.544114 -223.911922)
		(end 104.512364 -223.93021)
		(width 0.0762)
		(layer "B.Cu")
		(net "WAFL_CPU0_TX0_CPU1_RX1_DP")
	)
	(segment
		(start 349.10014 -222.935546)
		(end 349.09887 -222.936308)
		(width 0.0762)
		(layer "B.Cu")
		(net "WAFL_CPU0_TX0_CPU1_RX1_DP")
	)
	(segment
		(start 348.168468 -218.904312)
		(end 348.314264 -219.256102)
		(width 0.12954)
		(layer "B.Cu")
		(net "WAFL_CPU0_TX0_CPU1_RX1_DP")
	)
	(segment
		(start 105.051606 -223.080072)
		(end 104.983534 -223.119696)
		(width 0.0762)
		(layer "B.Cu")
		(net "WAFL_CPU0_TX0_CPU1_RX1_DP")
	)
	(segment
		(start 155.072588 -183.020462)
		(end 154.805634 -183.2991)
		(width 0.12954)
		(layer "B.Cu")
		(net "WAFL_CPU0_TX0_CPU1_RX1_DP")
	)
	(segment
		(start 348.070678 -223.481138)
		(end 348.070678 -223.480884)
		(width 0.0762)
		(layer "B.Cu")
		(net "WAFL_CPU0_TX0_CPU1_RX1_DP")
	)
	(segment
		(start 155.342082 -183.01462)
		(end 155.072588 -183.020462)
		(width 0.12954)
		(layer "B.Cu")
		(net "WAFL_CPU0_TX0_CPU1_RX1_DP")
	)
	(segment
		(start 106.848656 -219.156026)
		(end 106.430064 -219.45346)
		(width 0.12954)
		(layer "B.Cu")
		(net "WAFL_CPU0_TX0_CPU1_RX1_DP")
	)
	(segment
		(start 348.749874 -221.239334)
		(end 348.749874 -221.258384)
		(width 0.0762)
		(layer "B.Cu")
		(net "WAFL_CPU0_TX0_CPU1_RX1_DP")
	)
	(segment
		(start 104.54513 -223.911414)
		(end 104.544114 -223.911922)
		(width 0.0762)
		(layer "B.Cu")
		(net "WAFL_CPU0_TX0_CPU1_RX1_DP")
	)
	(segment
		(start 149.550374 -188.788802)
		(end 108.413804 -218.042744)
		(width 0.12954)
		(layer "B.Cu")
		(net "WAFL_CPU0_TX0_CPU1_RX1_DP")
	)
	(segment
		(start 347.297502 -216.801192)
		(end 347.443044 -217.152982)
		(width 0.12954)
		(layer "B.Cu")
		(net "WAFL_CPU0_TX0_CPU1_RX1_DP")
	)
	(segment
		(start 348.314264 -219.256102)
		(end 348.212664 -219.501466)
		(width 0.12954)
		(layer "B.Cu")
		(net "WAFL_CPU0_TX0_CPU1_RX1_DP")
	)
	(segment
		(start 348.749874 -220.307408)
		(end 348.749874 -221.239334)
		(width 0.12954)
		(layer "B.Cu")
		(net "WAFL_CPU0_TX0_CPU1_RX1_DP")
	)
	(segment
		(start 104.826308 -221.259654)
		(end 104.826308 -221.804484)
		(width 0.0762)
		(layer "B.Cu")
		(net "WAFL_CPU0_TX0_CPU1_RX1_DP")
	)
	(segment
		(start 107.429046 -218.976956)
		(end 107.114086 -219.20073)
		(width 0.12954)
		(layer "B.Cu")
		(net "WAFL_CPU0_TX0_CPU1_RX1_DP")
	)
	(segment
		(start 104.113076 -224.699068)
		(end 104.07396 -224.721928)
		(width 0.0762)
		(layer "B.Cu")
		(net "WAFL_CPU0_TX0_CPU1_RX1_DP")
	)
	(segment
		(start 104.07396 -224.721928)
		(end 104.04348 -224.739708)
		(width 0.0762)
		(layer "B.Cu")
		(net "WAFL_CPU0_TX0_CPU1_RX1_DP")
	)
	(segment
		(start 348.658688 -223.728788)
		(end 348.643194 -223.737678)
		(width 0.0762)
		(layer "B.Cu")
		(net "WAFL_CPU0_TX0_CPU1_RX1_DP")
	)
	(segment
		(start 324.13829 -191.56553)
		(end 345.829128 -213.256114)
		(width 0.12954)
		(layer "B.Cu")
		(net "WAFL_CPU0_TX0_CPU1_RX1_DP")
	)
	(segment
		(start 348.604078 -219.955618)
		(end 348.749874 -220.307408)
		(width 0.12954)
		(layer "B.Cu")
		(net "WAFL_CPU0_TX0_CPU1_RX1_DP")
	)
	(segment
		(start 347.341444 -217.3986)
		(end 347.48724 -217.750898)
		(width 0.12954)
		(layer "B.Cu")
		(net "WAFL_CPU0_TX0_CPU1_RX1_DP")
	)
	(segment
		(start 155.603194 -182.46598)
		(end 155.609036 -182.735474)
		(width 0.12954)
		(layer "B.Cu")
		(net "WAFL_CPU0_TX0_CPU1_RX1_DP")
	)
	(segment
		(start 166.16934 -178.656742)
		(end 161.432748 -179.990496)
		(width 0.12954)
		(layer "B.Cu")
		(net "WAFL_CPU0_TX0_CPU1_RX1_DP")
	)
	(segment
		(start 155.870148 -182.187342)
		(end 155.603194 -182.46598)
		(width 0.12954)
		(layer "B.Cu")
		(net "WAFL_CPU0_TX0_CPU1_RX1_DP")
	)
	(arc
		(start 348.815914 -221.80423)
		(mid 348.880361 -222.066382)
		(end 349.058992 -222.268796)
		(width 0.0762)
		(layer "B.Cu")
		(net "WAFL_CPU0_TX0_CPU1_RX1_DP")
	)
	(arc
		(start 104.356408 -224.234502)
		(mid 104.291893 -224.496721)
		(end 104.113076 -224.699068)
		(width 0.0762)
		(layer "B.Cu")
		(net "WAFL_CPU0_TX0_CPU1_RX1_DP")
	)
	(arc
		(start 104.826308 -221.804484)
		(mid 104.873942 -221.986441)
		(end 105.004616 -222.12173)
		(width 0.0762)
		(layer "B.Cu")
		(net "WAFL_CPU0_TX0_CPU1_RX1_DP")
	)
	(arc
		(start 105.296208 -222.61449)
		(mid 105.23139 -222.877479)
		(end 105.051606 -223.080072)
		(width 0.0762)
		(layer "B.Cu")
		(net "WAFL_CPU0_TX0_CPU1_RX1_DP")
	)
	(arc
		(start 349.129858 -222.309944)
		(mid 349.285786 -222.614236)
		(end 349.129858 -222.918528)
		(width 0.0762)
		(layer "B.Cu")
		(net "WAFL_CPU0_TX0_CPU1_RX1_DP")
	)
	(arc
		(start 104.512364 -223.93021)
		(mid 104.397688 -224.063544)
		(end 104.356408 -224.234502)
		(width 0.0762)
		(layer "B.Cu")
		(net "WAFL_CPU0_TX0_CPU1_RX1_DP")
	)
	(arc
		(start 349.058992 -222.959676)
		(mid 348.880179 -223.162026)
		(end 348.81566 -223.424242)
		(width 0.0762)
		(layer "B.Cu")
		(net "WAFL_CPU0_TX0_CPU1_RX1_DP")
	)
	(arc
		(start 104.826562 -223.424496)
		(mid 104.762047 -223.686715)
		(end 104.58323 -223.889062)
		(width 0.0762)
		(layer "B.Cu")
		(net "WAFL_CPU0_TX0_CPU1_RX1_DP")
	)
	(arc
		(start 104.04348 -224.739708)
		(mid 103.942009 -224.848329)
		(end 103.890826 -224.987866)
		(width 0.0762)
		(layer "B.Cu")
		(net "WAFL_CPU0_TX0_CPU1_RX1_DP")
	)
	(arc
		(start 348.171262 -223.693228)
		(mid 348.111356 -223.63007)
		(end 348.081092 -223.548448)
		(width 0.0762)
		(layer "B.Cu")
		(net "WAFL_CPU0_TX0_CPU1_RX1_DP")
	)
	(arc
		(start 105.004616 -222.12173)
		(mid 105.217867 -222.328198)
		(end 105.296208 -222.61449)
		(width 0.0762)
		(layer "B.Cu")
		(net "WAFL_CPU0_TX0_CPU1_RX1_DP")
	)
	(arc
		(start 348.627446 -223.74733)
		(mid 348.442491 -223.797259)
		(end 348.257114 -223.748854)
		(width 0.0762)
		(layer "B.Cu")
		(net "WAFL_CPU0_TX0_CPU1_RX1_DP")
	)
	(arc
		(start 104.983534 -223.119696)
		(mid 104.868107 -223.253072)
		(end 104.826562 -223.424496)
		(width 0.0762)
		(layer "B.Cu")
		(net "WAFL_CPU0_TX0_CPU1_RX1_DP")
	)
	(arc
		(start 348.81566 -223.424242)
		(mid 348.774111 -223.595664)
		(end 348.658688 -223.729042)
		(width 0.0762)
		(layer "B.Cu")
		(net "WAFL_CPU0_TX0_CPU1_RX1_DP")
	)
	(segment
		(start 103.787956 -225.310446)
		(end 103.321104 -225.044508)
		(width 0.12954)
		(layer "F.Cu")
		(net "WAFL_CPU0_TX0_CPU1_RX1_DN")
	)
	(segment
		(start 347.968062 -223.69018)
		(end 347.50121 -223.424242)
		(width 0.12954)
		(layer "F.Cu")
		(net "WAFL_CPU0_TX0_CPU1_RX1_DN")
	)
	(via
		(at 103.321104 -225.044508)
		(size 0.4064)
		(drill 0.2032)
		(layers "F.Cu" "B.Cu")
		(net "WAFL_CPU0_TX0_CPU1_RX1_DN")
	)
	(via
		(at 347.50121 -223.424242)
		(size 0.4064)
		(drill 0.2032)
		(layers "F.Cu" "B.Cu")
		(net "WAFL_CPU0_TX0_CPU1_RX1_DN")
	)
	(via
		(at 322.871084 -190.468758)
		(size 0.4064)
		(drill 0.2032)
		(layers "F.Cu" "B.Cu")
		(net "WAFL_CPU0_TX0_CPU1_RX1_DN")
	)
	(segment
		(start 347.8149 -223.424242)
		(end 347.879416 -223.488758)
		(width 0.0762)
		(layer "B.Cu")
		(net "WAFL_CPU0_TX0_CPU1_RX1_DN")
	)
	(segment
		(start 347.88221 -223.50984)
		(end 347.892624 -223.577404)
		(width 0.0762)
		(layer "B.Cu")
		(net "WAFL_CPU0_TX0_CPU1_RX1_DN")
	)
	(segment
		(start 348.065344 -223.851978)
		(end 348.158054 -223.911668)
		(width 0.0762)
		(layer "B.Cu")
		(net "WAFL_CPU0_TX0_CPU1_RX1_DN")
	)
	(segment
		(start 314.03163 -185.411872)
		(end 304.257456 -182.875174)
		(width 0.12954)
		(layer "B.Cu")
		(net "WAFL_CPU0_TX0_CPU1_RX1_DN")
	)
	(segment
		(start 349.19666 -223.100138)
		(end 349.233236 -223.078802)
		(width 0.0762)
		(layer "B.Cu")
		(net "WAFL_CPU0_TX0_CPU1_RX1_DN")
	)
	(segment
		(start 104.569768 -221.174564)
		(end 104.569768 -221.193614)
		(width 0.0762)
		(layer "B.Cu")
		(net "WAFL_CPU0_TX0_CPU1_RX1_DN")
	)
	(segment
		(start 166.12997 -178.332638)
		(end 156.524452 -181.03723)
		(width 0.12954)
		(layer "B.Cu")
		(net "WAFL_CPU0_TX0_CPU1_RX1_DN")
	)
	(segment
		(start 104.569768 -221.193614)
		(end 104.635808 -221.259654)
		(width 0.0762)
		(layer "B.Cu")
		(net "WAFL_CPU0_TX0_CPU1_RX1_DN")
	)
	(segment
		(start 104.448864 -223.746568)
		(end 104.448102 -223.747076)
		(width 0.0762)
		(layer "B.Cu")
		(net "WAFL_CPU0_TX0_CPU1_RX1_DN")
	)
	(segment
		(start 149.338284 -188.543438)
		(end 106.221022 -219.206064)
		(width 0.12954)
		(layer "B.Cu")
		(net "WAFL_CPU0_TX0_CPU1_RX1_DN")
	)
	(segment
		(start 349.193358 -223.10217)
		(end 349.19412 -223.101662)
		(width 0.0762)
		(layer "B.Cu")
		(net "WAFL_CPU0_TX0_CPU1_RX1_DN")
	)
	(segment
		(start 156.524452 -181.03723)
		(end 149.338284 -188.543438)
		(width 0.12954)
		(layer "B.Cu")
		(net "WAFL_CPU0_TX0_CPU1_RX1_DN")
	)
	(segment
		(start 104.91978 -222.292926)
		(end 104.920034 -222.292926)
		(width 0.0762)
		(layer "B.Cu")
		(net "WAFL_CPU0_TX0_CPU1_RX1_DN")
	)
	(segment
		(start 322.871084 -190.468758)
		(end 314.03163 -185.411872)
		(width 0.12954)
		(layer "B.Cu")
		(net "WAFL_CPU0_TX0_CPU1_RX1_DN")
	)
	(segment
		(start 103.634794 -225.044508)
		(end 103.321104 -225.044508)
		(width 0.0762)
		(layer "B.Cu")
		(net "WAFL_CPU0_TX0_CPU1_RX1_DN")
	)
	(segment
		(start 349.195136 -223.101154)
		(end 349.19666 -223.100138)
		(width 0.0762)
		(layer "B.Cu")
		(net "WAFL_CPU0_TX0_CPU1_RX1_DN")
	)
	(segment
		(start 104.448102 -223.747076)
		(end 104.447086 -223.747584)
		(width 0.0762)
		(layer "B.Cu")
		(net "WAFL_CPU0_TX0_CPU1_RX1_DN")
	)
	(segment
		(start 104.008682 -224.539302)
		(end 103.978202 -224.557082)
		(width 0.0762)
		(layer "B.Cu")
		(net "WAFL_CPU0_TX0_CPU1_RX1_DN")
	)
	(segment
		(start 349.006414 -221.80423)
		(end 349.006414 -221.324424)
		(width 0.0762)
		(layer "B.Cu")
		(net "WAFL_CPU0_TX0_CPU1_RX1_DN")
	)
	(segment
		(start 104.450134 -223.745806)
		(end 104.448864 -223.746568)
		(width 0.0762)
		(layer "B.Cu")
		(net "WAFL_CPU0_TX0_CPU1_RX1_DN")
	)
	(segment
		(start 103.978202 -224.557082)
		(end 103.939086 -224.579942)
		(width 0.0762)
		(layer "B.Cu")
		(net "WAFL_CPU0_TX0_CPU1_RX1_DN")
	)
	(segment
		(start 349.233236 -222.14967)
		(end 349.19412 -222.12681)
		(width 0.0762)
		(layer "B.Cu")
		(net "WAFL_CPU0_TX0_CPU1_RX1_DN")
	)
	(segment
		(start 104.948736 -222.91929)
		(end 104.918256 -222.93707)
		(width 0.0762)
		(layer "B.Cu")
		(net "WAFL_CPU0_TX0_CPU1_RX1_DN")
	)
	(segment
		(start 304.257456 -182.875174)
		(end 166.12997 -178.332638)
		(width 0.12954)
		(layer "B.Cu")
		(net "WAFL_CPU0_TX0_CPU1_RX1_DN")
	)
	(segment
		(start 349.006414 -221.324424)
		(end 349.072454 -221.258384)
		(width 0.0762)
		(layer "B.Cu")
		(net "WAFL_CPU0_TX0_CPU1_RX1_DN")
	)
	(segment
		(start 324.336664 -191.307212)
		(end 322.871084 -190.468758)
		(width 0.12954)
		(layer "B.Cu")
		(net "WAFL_CPU0_TX0_CPU1_RX1_DN")
	)
	(segment
		(start 347.50121 -223.424242)
		(end 347.8149 -223.424242)
		(width 0.0762)
		(layer "B.Cu")
		(net "WAFL_CPU0_TX0_CPU1_RX1_DN")
	)
	(segment
		(start 348.723966 -223.911668)
		(end 348.763082 -223.888808)
		(width 0.0762)
		(layer "B.Cu")
		(net "WAFL_CPU0_TX0_CPU1_RX1_DN")
	)
	(segment
		(start 104.915716 -222.29064)
		(end 104.91978 -222.292926)
		(width 0.0762)
		(layer "B.Cu")
		(net "WAFL_CPU0_TX0_CPU1_RX1_DN")
	)
	(segment
		(start 104.447086 -223.747584)
		(end 104.408986 -223.769936)
		(width 0.0762)
		(layer "B.Cu")
		(net "WAFL_CPU0_TX0_CPU1_RX1_DN")
	)
	(segment
		(start 349.072454 -221.239334)
		(end 349.072454 -220.243146)
		(width 0.12954)
		(layer "B.Cu")
		(net "WAFL_CPU0_TX0_CPU1_RX1_DN")
	)
	(segment
		(start 349.072454 -221.258384)
		(end 349.072454 -221.239334)
		(width 0.0762)
		(layer "B.Cu")
		(net "WAFL_CPU0_TX0_CPU1_RX1_DN")
	)
	(segment
		(start 106.221022 -219.206064)
		(end 104.569768 -220.857318)
		(width 0.12954)
		(layer "B.Cu")
		(net "WAFL_CPU0_TX0_CPU1_RX1_DN")
	)
	(segment
		(start 104.569768 -220.857318)
		(end 104.569768 -221.174564)
		(width 0.12954)
		(layer "B.Cu")
		(net "WAFL_CPU0_TX0_CPU1_RX1_DN")
	)
	(segment
		(start 104.635808 -221.259654)
		(end 104.635808 -221.804484)
		(width 0.0762)
		(layer "B.Cu")
		(net "WAFL_CPU0_TX0_CPU1_RX1_DN")
	)
	(segment
		(start 349.072454 -220.243146)
		(end 346.10294 -213.073234)
		(width 0.12954)
		(layer "B.Cu")
		(net "WAFL_CPU0_TX0_CPU1_RX1_DN")
	)
	(segment
		(start 346.10294 -213.073234)
		(end 324.336664 -191.307212)
		(width 0.12954)
		(layer "B.Cu")
		(net "WAFL_CPU0_TX0_CPU1_RX1_DN")
	)
	(segment
		(start 349.19412 -222.12681)
		(end 349.16237 -222.108522)
		(width 0.0762)
		(layer "B.Cu")
		(net "WAFL_CPU0_TX0_CPU1_RX1_DN")
	)
	(segment
		(start 349.16237 -223.11995)
		(end 349.193358 -223.10217)
		(width 0.0762)
		(layer "B.Cu")
		(net "WAFL_CPU0_TX0_CPU1_RX1_DN")
	)
	(segment
		(start 104.479852 -223.728788)
		(end 104.450134 -223.745806)
		(width 0.0762)
		(layer "B.Cu")
		(net "WAFL_CPU0_TX0_CPU1_RX1_DN")
	)
	(segment
		(start 349.19412 -223.101662)
		(end 349.195136 -223.101154)
		(width 0.0762)
		(layer "B.Cu")
		(net "WAFL_CPU0_TX0_CPU1_RX1_DN")
	)
	(segment
		(start 103.69931 -224.979992)
		(end 103.634794 -225.044508)
		(width 0.0762)
		(layer "B.Cu")
		(net "WAFL_CPU0_TX0_CPU1_RX1_DN")
	)
	(segment
		(start 104.918256 -222.93707)
		(end 104.87914 -222.95993)
		(width 0.0762)
		(layer "B.Cu")
		(net "WAFL_CPU0_TX0_CPU1_RX1_DN")
	)
	(arc
		(start 348.763082 -223.888808)
		(mid 348.941895 -223.686458)
		(end 349.006414 -223.424242)
		(width 0.0762)
		(layer "B.Cu")
		(net "WAFL_CPU0_TX0_CPU1_RX1_DN")
	)
	(arc
		(start 105.105708 -222.61449)
		(mid 105.064159 -222.785912)
		(end 104.948736 -222.91929)
		(width 0.0762)
		(layer "B.Cu")
		(net "WAFL_CPU0_TX0_CPU1_RX1_DN")
	)
	(arc
		(start 347.879416 -223.488758)
		(mid 347.880715 -223.499312)
		(end 347.88221 -223.50984)
		(width 0.0762)
		(layer "B.Cu")
		(net "WAFL_CPU0_TX0_CPU1_RX1_DN")
	)
	(arc
		(start 104.635808 -221.804484)
		(mid 104.710788 -222.084968)
		(end 104.915716 -222.29064)
		(width 0.0762)
		(layer "B.Cu")
		(net "WAFL_CPU0_TX0_CPU1_RX1_DN")
	)
	(arc
		(start 103.702104 -224.95891)
		(mid 103.700608 -224.969438)
		(end 103.69931 -224.979992)
		(width 0.0762)
		(layer "B.Cu")
		(net "WAFL_CPU0_TX0_CPU1_RX1_DN")
	)
	(arc
		(start 349.233236 -223.078802)
		(mid 349.476563 -222.614236)
		(end 349.233236 -222.14967)
		(width 0.0762)
		(layer "B.Cu")
		(net "WAFL_CPU0_TX0_CPU1_RX1_DN")
	)
	(arc
		(start 347.892624 -223.577404)
		(mid 347.950469 -223.732635)
		(end 348.065344 -223.851978)
		(width 0.0762)
		(layer "B.Cu")
		(net "WAFL_CPU0_TX0_CPU1_RX1_DN")
	)
	(arc
		(start 104.87914 -222.95993)
		(mid 104.700327 -223.16228)
		(end 104.635808 -223.424496)
		(width 0.0762)
		(layer "B.Cu")
		(net "WAFL_CPU0_TX0_CPU1_RX1_DN")
	)
	(arc
		(start 349.006414 -223.424242)
		(mid 349.047669 -223.253271)
		(end 349.16237 -223.11995)
		(width 0.0762)
		(layer "B.Cu")
		(net "WAFL_CPU0_TX0_CPU1_RX1_DN")
	)
	(arc
		(start 104.920034 -222.292926)
		(mid 105.055936 -222.428837)
		(end 105.105708 -222.61449)
		(width 0.0762)
		(layer "B.Cu")
		(net "WAFL_CPU0_TX0_CPU1_RX1_DN")
	)
	(arc
		(start 104.408986 -223.769936)
		(mid 104.230173 -223.972286)
		(end 104.165654 -224.234502)
		(width 0.0762)
		(layer "B.Cu")
		(net "WAFL_CPU0_TX0_CPU1_RX1_DN")
	)
	(arc
		(start 104.165654 -224.234502)
		(mid 104.124105 -224.405924)
		(end 104.008682 -224.539302)
		(width 0.0762)
		(layer "B.Cu")
		(net "WAFL_CPU0_TX0_CPU1_RX1_DN")
	)
	(arc
		(start 349.16237 -222.108522)
		(mid 349.047694 -221.975188)
		(end 349.006414 -221.80423)
		(width 0.0762)
		(layer "B.Cu")
		(net "WAFL_CPU0_TX0_CPU1_RX1_DN")
	)
	(arc
		(start 348.158054 -223.911668)
		(mid 348.44101 -223.987845)
		(end 348.723966 -223.911668)
		(width 0.0762)
		(layer "B.Cu")
		(net "WAFL_CPU0_TX0_CPU1_RX1_DN")
	)
	(arc
		(start 103.939086 -224.579942)
		(mid 103.781556 -224.745013)
		(end 103.702104 -224.95891)
		(width 0.0762)
		(layer "B.Cu")
		(net "WAFL_CPU0_TX0_CPU1_RX1_DN")
	)
	(arc
		(start 104.635808 -223.424496)
		(mid 104.594553 -223.595467)
		(end 104.479852 -223.728788)
		(width 0.0762)
		(layer "B.Cu")
		(net "WAFL_CPU0_TX0_CPU1_RX1_DN")
	)
	(segment
		(start 145.31975 -295.956228)
		(end 144.974818 -295.956228)
		(width 0.254)
		(layer "F.Cu")
		(net "VSENSE_VSS_SENSE_C_P1")
	)
	(segment
		(start 145.582386 -296.218864)
		(end 145.31975 -295.956228)
		(width 0.254)
		(layer "F.Cu")
		(net "VSENSE_VSS_SENSE_C_P1")
	)
	(segment
		(start 160.141158 -344.706956)
		(end 160.141158 -343.689686)
		(width 0.254)
		(layer "F.Cu")
		(net "VSENSE_VSS_SENSE_C_P1")
	)
	(segment
		(start 170.44035 -332.232508)
		(end 170.05935 -332.613508)
		(width 0.254)
		(layer "F.Cu")
		(net "VSENSE_VSS_SENSE_C_P1")
	)
	(segment
		(start 150.809198 -327.235312)
		(end 149.775926 -327.235312)
		(width 0.254)
		(layer "F.Cu")
		(net "VSENSE_VSS_SENSE_C_P1")
	)
	(segment
		(start 152.938226 -326.775572)
		(end 157.086554 -326.775572)
		(width 0.254)
		(layer "F.Cu")
		(net "VSENSE_VSS_SENSE_C_P1")
	)
	(segment
		(start 149.885146 -325.208392)
		(end 151.371046 -325.208392)
		(width 0.254)
		(layer "F.Cu")
		(net "VSENSE_VSS_SENSE_C_P1")
	)
	(segment
		(start 149.265894 -326.72528)
		(end 149.265894 -325.827644)
		(width 0.254)
		(layer "F.Cu")
		(net "VSENSE_VSS_SENSE_C_P1")
	)
	(segment
		(start 158.05658 -313.592718)
		(end 145.582386 -301.118524)
		(width 0.254)
		(layer "F.Cu")
		(net "VSENSE_VSS_SENSE_C_P1")
	)
	(segment
		(start 169.1894 -332.244192)
		(end 168.867074 -332.566518)
		(width 0.254)
		(layer "F.Cu")
		(net "VSENSE_VSS_SENSE_C_P1")
	)
	(segment
		(start 160.828482 -345.81338)
		(end 160.141158 -345.126056)
		(width 0.1778)
		(layer "F.Cu")
		(net "VSENSE_VSS_SENSE_C_P1")
	)
	(segment
		(start 169.558716 -332.613508)
		(end 169.1894 -332.244192)
		(width 0.254)
		(layer "F.Cu")
		(net "VSENSE_VSS_SENSE_C_P1")
	)
	(segment
		(start 144.974818 -295.956228)
		(end 144.507966 -295.69029)
		(width 0.350012)
		(layer "F.Cu")
		(net "VSENSE_VSS_SENSE_C_P1")
	)
	(segment
		(start 170.05935 -332.613508)
		(end 169.558716 -332.613508)
		(width 0.254)
		(layer "F.Cu")
		(net "VSENSE_VSS_SENSE_C_P1")
	)
	(segment
		(start 27.95905 -359.283)
		(end 27.95905 -358.267)
		(width 0.254)
		(layer "F.Cu")
		(net "VSENSE_VSS_SENSE_C_P1")
	)
	(segment
		(start 151.371046 -325.208392)
		(end 152.938226 -326.775572)
		(width 0.254)
		(layer "F.Cu")
		(net "VSENSE_VSS_SENSE_C_P1")
	)
	(segment
		(start 28.679902 -360.657902)
		(end 28.679902 -361.233974)
		(width 0.1778)
		(layer "F.Cu")
		(net "VSENSE_VSS_SENSE_C_P1")
	)
	(segment
		(start 160.828482 -346.153232)
		(end 160.828482 -345.81338)
		(width 0.1778)
		(layer "F.Cu")
		(net "VSENSE_VSS_SENSE_C_P1")
	)
	(segment
		(start 149.775926 -327.235312)
		(end 149.265894 -326.72528)
		(width 0.254)
		(layer "F.Cu")
		(net "VSENSE_VSS_SENSE_C_P1")
	)
	(segment
		(start 157.086554 -326.775572)
		(end 158.05658 -325.805546)
		(width 0.254)
		(layer "F.Cu")
		(net "VSENSE_VSS_SENSE_C_P1")
	)
	(segment
		(start 168.50741 -332.566518)
		(end 168.3004 -332.359508)
		(width 0.254)
		(layer "F.Cu")
		(net "VSENSE_VSS_SENSE_C_P1")
	)
	(segment
		(start 160.141158 -345.126056)
		(end 160.141158 -344.706956)
		(width 0.1778)
		(layer "F.Cu")
		(net "VSENSE_VSS_SENSE_C_P1")
	)
	(segment
		(start 151.127714 -327.553828)
		(end 150.809198 -327.235312)
		(width 0.254)
		(layer "F.Cu")
		(net "VSENSE_VSS_SENSE_C_P1")
	)
	(segment
		(start 149.265894 -325.827644)
		(end 149.885146 -325.208392)
		(width 0.254)
		(layer "F.Cu")
		(net "VSENSE_VSS_SENSE_C_P1")
	)
	(segment
		(start 28.321 -360.299)
		(end 28.679902 -360.657902)
		(width 0.1778)
		(layer "F.Cu")
		(net "VSENSE_VSS_SENSE_C_P1")
	)
	(segment
		(start 110.318804 -327.582276)
		(end 110.973362 -327.582276)
		(width 0.254)
		(layer "F.Cu")
		(net "VSENSE_VSS_SENSE_C_P1")
	)
	(segment
		(start 168.867074 -332.566518)
		(end 168.50741 -332.566518)
		(width 0.254)
		(layer "F.Cu")
		(net "VSENSE_VSS_SENSE_C_P1")
	)
	(segment
		(start 27.95905 -359.283)
		(end 27.95905 -359.93705)
		(width 0.254)
		(layer "F.Cu")
		(net "VSENSE_VSS_SENSE_C_P1")
	)
	(segment
		(start 145.582386 -301.118524)
		(end 145.582386 -296.218864)
		(width 0.254)
		(layer "F.Cu")
		(net "VSENSE_VSS_SENSE_C_P1")
	)
	(segment
		(start 158.05658 -325.805546)
		(end 158.05658 -313.592718)
		(width 0.254)
		(layer "F.Cu")
		(net "VSENSE_VSS_SENSE_C_P1")
	)
	(segment
		(start 27.95905 -359.93705)
		(end 28.321 -360.299)
		(width 0.254)
		(layer "F.Cu")
		(net "VSENSE_VSS_SENSE_C_P1")
	)
	(via
		(at 160.141158 -343.689686)
		(size 0.508)
		(drill 0.254)
		(layers "F.Cu" "B.Cu")
		(net "VSENSE_VSS_SENSE_C_P1")
	)
	(via
		(at 110.973362 -327.582276)
		(size 0.508)
		(drill 0.254)
		(layers "F.Cu" "B.Cu")
		(net "VSENSE_VSS_SENSE_C_P1")
	)
	(via
		(at 27.95905 -358.267)
		(size 0.508)
		(drill 0.254)
		(layers "F.Cu" "B.Cu")
		(net "VSENSE_VSS_SENSE_C_P1")
	)
	(via
		(at 168.3004 -332.359508)
		(size 0.508)
		(drill 0.254)
		(layers "F.Cu" "B.Cu")
		(net "VSENSE_VSS_SENSE_C_P1")
	)
	(via
		(at 151.127714 -327.553828)
		(size 0.508)
		(drill 0.254)
		(layers "F.Cu" "B.Cu")
		(net "VSENSE_VSS_SENSE_C_P1")
	)
	(via
		(at 144.974818 -295.956228)
		(size 0.4064)
		(drill 0.2032)
		(layers "F.Cu" "B.Cu")
		(net "VSENSE_VSS_SENSE_C_P1")
	)
	(segment
		(start 111.348774 -327.206864)
		(end 110.973362 -327.582276)
		(width 0.254)
		(layer "B.Cu")
		(net "VSENSE_VSS_SENSE_C_P1")
	)
	(segment
		(start 150.78075 -327.206864)
		(end 111.348774 -327.206864)
		(width 0.254)
		(layer "B.Cu")
		(net "VSENSE_VSS_SENSE_C_P1")
	)
	(segment
		(start 151.127714 -327.553828)
		(end 150.78075 -327.206864)
		(width 0.254)
		(layer "B.Cu")
		(net "VSENSE_VSS_SENSE_C_P1")
	)
	(segment
		(start 169.10812 -332.538832)
		(end 168.479724 -332.538832)
		(width 0.254)
		(layer "B.Cu")
		(net "VSENSE_VSS_SENSE_C_P1")
	)
	(segment
		(start 163.119054 -320.922142)
		(end 163.119054 -328.030332)
		(width 0.254)
		(layer "B.Cu")
		(net "VSENSE_VSS_SENSE_C_P1")
	)
	(segment
		(start 169.398188 -331.361034)
		(end 169.398188 -332.248764)
		(width 0.254)
		(layer "B.Cu")
		(net "VSENSE_VSS_SENSE_C_P1")
	)
	(segment
		(start 157.890464 -315.693552)
		(end 163.119054 -320.922142)
		(width 0.254)
		(layer "B.Cu")
		(net "VSENSE_VSS_SENSE_C_P1")
	)
	(segment
		(start 157.890464 -306.931822)
		(end 157.890464 -315.693552)
		(width 0.254)
		(layer "B.Cu")
		(net "VSENSE_VSS_SENSE_C_P1")
	)
	(segment
		(start 144.974818 -295.956228)
		(end 146.91487 -295.956228)
		(width 0.254)
		(layer "B.Cu")
		(net "VSENSE_VSS_SENSE_C_P1")
	)
	(segment
		(start 168.479724 -332.538832)
		(end 168.3004 -332.359508)
		(width 0.254)
		(layer "B.Cu")
		(net "VSENSE_VSS_SENSE_C_P1")
	)
	(segment
		(start 168.785286 -330.748132)
		(end 169.398188 -331.361034)
		(width 0.254)
		(layer "B.Cu")
		(net "VSENSE_VSS_SENSE_C_P1")
	)
	(segment
		(start 163.119054 -328.030332)
		(end 165.836854 -330.748132)
		(width 0.254)
		(layer "B.Cu")
		(net "VSENSE_VSS_SENSE_C_P1")
	)
	(segment
		(start 165.836854 -330.748132)
		(end 168.785286 -330.748132)
		(width 0.254)
		(layer "B.Cu")
		(net "VSENSE_VSS_SENSE_C_P1")
	)
	(segment
		(start 169.398188 -332.248764)
		(end 169.10812 -332.538832)
		(width 0.254)
		(layer "B.Cu")
		(net "VSENSE_VSS_SENSE_C_P1")
	)
	(segment
		(start 146.91487 -295.956228)
		(end 157.890464 -306.931822)
		(width 0.254)
		(layer "B.Cu")
		(net "VSENSE_VSS_SENSE_C_P1")
	)
	(segment
		(start 108.938822 -344.710258)
		(end 108.938822 -329.139804)
		(width 0.254)
		(layer "In2.Cu")
		(net "VSENSE_VSS_SENSE_C_P1")
	)
	(segment
		(start 27.95905 -358.267)
		(end 28.44165 -358.267)
		(width 0.254)
		(layer "In2.Cu")
		(net "VSENSE_VSS_SENSE_C_P1")
	)
	(segment
		(start 31.650686 -355.057964)
		(end 67.001136 -355.057964)
		(width 0.254)
		(layer "In2.Cu")
		(net "VSENSE_VSS_SENSE_C_P1")
	)
	(segment
		(start 67.001136 -355.057964)
		(end 79.086202 -342.972898)
		(width 0.254)
		(layer "In2.Cu")
		(net "VSENSE_VSS_SENSE_C_P1")
	)
	(segment
		(start 97.849182 -347.712538)
		(end 105.936542 -347.712538)
		(width 0.254)
		(layer "In2.Cu")
		(net "VSENSE_VSS_SENSE_C_P1")
	)
	(segment
		(start 93.109542 -342.972898)
		(end 97.849182 -347.712538)
		(width 0.254)
		(layer "In2.Cu")
		(net "VSENSE_VSS_SENSE_C_P1")
	)
	(segment
		(start 105.936542 -347.712538)
		(end 108.938822 -344.710258)
		(width 0.254)
		(layer "In2.Cu")
		(net "VSENSE_VSS_SENSE_C_P1")
	)
	(segment
		(start 168.3004 -332.359508)
		(end 168.105836 -332.554072)
		(width 0.254)
		(layer "In2.Cu")
		(net "VSENSE_VSS_SENSE_C_P1")
	)
	(segment
		(start 159.281368 -342.97747)
		(end 159.993584 -343.689686)
		(width 0.254)
		(layer "In2.Cu")
		(net "VSENSE_VSS_SENSE_C_P1")
	)
	(segment
		(start 168.105836 -332.554072)
		(end 167.482774 -332.554072)
		(width 0.254)
		(layer "In2.Cu")
		(net "VSENSE_VSS_SENSE_C_P1")
	)
	(segment
		(start 159.281368 -340.755478)
		(end 159.281368 -342.97747)
		(width 0.254)
		(layer "In2.Cu")
		(net "VSENSE_VSS_SENSE_C_P1")
	)
	(segment
		(start 110.49635 -327.582276)
		(end 110.973362 -327.582276)
		(width 0.254)
		(layer "In2.Cu")
		(net "VSENSE_VSS_SENSE_C_P1")
	)
	(segment
		(start 167.482774 -332.554072)
		(end 159.281368 -340.755478)
		(width 0.254)
		(layer "In2.Cu")
		(net "VSENSE_VSS_SENSE_C_P1")
	)
	(segment
		(start 108.938822 -329.139804)
		(end 110.49635 -327.582276)
		(width 0.254)
		(layer "In2.Cu")
		(net "VSENSE_VSS_SENSE_C_P1")
	)
	(segment
		(start 28.44165 -358.267)
		(end 31.650686 -355.057964)
		(width 0.254)
		(layer "In2.Cu")
		(net "VSENSE_VSS_SENSE_C_P1")
	)
	(segment
		(start 159.993584 -343.689686)
		(end 160.141158 -343.689686)
		(width 0.254)
		(layer "In2.Cu")
		(net "VSENSE_VSS_SENSE_C_P1")
	)
	(segment
		(start 79.086202 -342.972898)
		(end 93.109542 -342.972898)
		(width 0.254)
		(layer "In2.Cu")
		(net "VSENSE_VSS_SENSE_C_P1")
	)
	(segment
		(start 394.456158 -303.392332)
		(end 394.456158 -302.391572)
		(width 0.254)
		(layer "F.Cu")
		(net "VSENSE_VSS_SENSE_C_P0")
	)
	(segment
		(start 416.83051 -358.241092)
		(end 416.83051 -357.223822)
		(width 0.254)
		(layer "F.Cu")
		(net "VSENSE_VSS_SENSE_C_P0")
	)
	(segment
		(start 417.167822 -358.9909)
		(end 416.83051 -358.653588)
		(width 0.254)
		(layer "F.Cu")
		(net "VSENSE_VSS_SENSE_C_P0")
	)
	(segment
		(start 415.228532 -331.945996)
		(end 414.792414 -332.382114)
		(width 0.254)
		(layer "F.Cu")
		(net "VSENSE_VSS_SENSE_C_P0")
	)
	(segment
		(start 416.83051 -358.653588)
		(end 416.83051 -358.241092)
		(width 0.254)
		(layer "F.Cu")
		(net "VSENSE_VSS_SENSE_C_P0")
	)
	(segment
		(start 307.61305 -355.854)
		(end 307.61305 -354.3808)
		(width 0.254)
		(layer "F.Cu")
		(net "VSENSE_VSS_SENSE_C_P0")
	)
	(segment
		(start 392.648948 -295.690036)
		(end 392.914886 -295.955974)
		(width 0.254)
		(layer "F.Cu")
		(net "VSENSE_VSS_SENSE_C_P0")
	)
	(segment
		(start 417.517834 -359.687368)
		(end 417.517834 -359.340912)
		(width 0.1778)
		(layer "F.Cu")
		(net "VSENSE_VSS_SENSE_C_P0")
	)
	(segment
		(start 414.327594 -332.382114)
		(end 414.200594 -332.509114)
		(width 0.254)
		(layer "F.Cu")
		(net "VSENSE_VSS_SENSE_C_P0")
	)
	(segment
		(start 393.395454 -297.438572)
		(end 393.395454 -296.436542)
		(width 0.254)
		(layer "F.Cu")
		(net "VSENSE_VSS_SENSE_C_P0")
	)
	(segment
		(start 410.635958 -321.779392)
		(end 406.027128 -317.170562)
		(width 0.254)
		(layer "F.Cu")
		(net "VSENSE_VSS_SENSE_C_P0")
	)
	(segment
		(start 394.456158 -302.391572)
		(end 393.458954 -301.394368)
		(width 0.254)
		(layer "F.Cu")
		(net "VSENSE_VSS_SENSE_C_P0")
	)
	(segment
		(start 308.333902 -357.228902)
		(end 308.333902 -357.804974)
		(width 0.1778)
		(layer "F.Cu")
		(net "VSENSE_VSS_SENSE_C_P0")
	)
	(segment
		(start 359.134156 -326.62622)
		(end 358.37622 -326.62622)
		(width 0.254)
		(layer "F.Cu")
		(net "VSENSE_VSS_SENSE_C_P0")
	)
	(segment
		(start 408.538172 -338.096606)
		(end 408.686 -338.244434)
		(width 0.254)
		(layer "F.Cu")
		(net "VSENSE_VSS_SENSE_C_P0")
	)
	(segment
		(start 414.792414 -332.382114)
		(end 414.327594 -332.382114)
		(width 0.254)
		(layer "F.Cu")
		(net "VSENSE_VSS_SENSE_C_P0")
	)
	(segment
		(start 393.458954 -297.502072)
		(end 393.395454 -297.438572)
		(width 0.254)
		(layer "F.Cu")
		(net "VSENSE_VSS_SENSE_C_P0")
	)
	(segment
		(start 406.027128 -314.963302)
		(end 394.456158 -303.392332)
		(width 0.254)
		(layer "F.Cu")
		(net "VSENSE_VSS_SENSE_C_P0")
	)
	(segment
		(start 307.61305 -355.854)
		(end 307.61305 -356.50805)
		(width 0.254)
		(layer "F.Cu")
		(net "VSENSE_VSS_SENSE_C_P0")
	)
	(segment
		(start 307.975 -356.87)
		(end 308.333902 -357.228902)
		(width 0.1778)
		(layer "F.Cu")
		(net "VSENSE_VSS_SENSE_C_P0")
	)
	(segment
		(start 413.342582 -332.509114)
		(end 413.088582 -332.255114)
		(width 0.254)
		(layer "F.Cu")
		(net "VSENSE_VSS_SENSE_C_P0")
	)
	(segment
		(start 410.635958 -337.127088)
		(end 410.635958 -321.779392)
		(width 0.254)
		(layer "F.Cu")
		(net "VSENSE_VSS_SENSE_C_P0")
	)
	(segment
		(start 414.200594 -332.509114)
		(end 413.342582 -332.509114)
		(width 0.254)
		(layer "F.Cu")
		(net "VSENSE_VSS_SENSE_C_P0")
	)
	(segment
		(start 409.518612 -338.244434)
		(end 410.635958 -337.127088)
		(width 0.254)
		(layer "F.Cu")
		(net "VSENSE_VSS_SENSE_C_P0")
	)
	(segment
		(start 406.027128 -317.170562)
		(end 406.027128 -314.963302)
		(width 0.254)
		(layer "F.Cu")
		(net "VSENSE_VSS_SENSE_C_P0")
	)
	(segment
		(start 408.686 -338.244434)
		(end 409.518612 -338.244434)
		(width 0.254)
		(layer "F.Cu")
		(net "VSENSE_VSS_SENSE_C_P0")
	)
	(segment
		(start 358.37622 -326.62622)
		(end 358.33431 -326.58431)
		(width 0.254)
		(layer "F.Cu")
		(net "VSENSE_VSS_SENSE_C_P0")
	)
	(segment
		(start 358.33431 -326.58431)
		(end 358.33431 -325.360538)
		(width 0.254)
		(layer "F.Cu")
		(net "VSENSE_VSS_SENSE_C_P0")
	)
	(segment
		(start 417.517834 -359.340912)
		(end 417.167822 -358.9909)
		(width 0.1778)
		(layer "F.Cu")
		(net "VSENSE_VSS_SENSE_C_P0")
	)
	(segment
		(start 359.199688 -326.691752)
		(end 359.134156 -326.62622)
		(width 0.254)
		(layer "F.Cu")
		(net "VSENSE_VSS_SENSE_C_P0")
	)
	(segment
		(start 393.395454 -296.436542)
		(end 392.914886 -295.955974)
		(width 0.254)
		(layer "F.Cu")
		(net "VSENSE_VSS_SENSE_C_P0")
	)
	(segment
		(start 307.61305 -356.50805)
		(end 307.975 -356.87)
		(width 0.254)
		(layer "F.Cu")
		(net "VSENSE_VSS_SENSE_C_P0")
	)
	(segment
		(start 358.33431 -325.360538)
		(end 358.384094 -325.310754)
		(width 0.254)
		(layer "F.Cu")
		(net "VSENSE_VSS_SENSE_C_P0")
	)
	(segment
		(start 392.448034 -295.690036)
		(end 392.648948 -295.690036)
		(width 0.254)
		(layer "F.Cu")
		(net "VSENSE_VSS_SENSE_C_P0")
	)
	(segment
		(start 393.458954 -301.394368)
		(end 393.458954 -297.502072)
		(width 0.254)
		(layer "F.Cu")
		(net "VSENSE_VSS_SENSE_C_P0")
	)
	(via
		(at 359.199688 -326.691752)
		(size 0.508)
		(drill 0.254)
		(layers "F.Cu" "B.Cu")
		(net "VSENSE_VSS_SENSE_C_P0")
	)
	(via
		(at 392.914886 -295.955974)
		(size 0.4064)
		(drill 0.2032)
		(layers "F.Cu" "B.Cu")
		(net "VSENSE_VSS_SENSE_C_P0")
	)
	(via
		(at 307.61305 -354.3808)
		(size 0.508)
		(drill 0.254)
		(layers "F.Cu" "B.Cu")
		(net "VSENSE_VSS_SENSE_C_P0")
	)
	(via
		(at 407.450798 -322.924932)
		(size 0.508)
		(drill 0.254)
		(layers "F.Cu" "B.Cu")
		(net "VSENSE_VSS_SENSE_C_P0")
	)
	(via
		(at 413.088582 -332.255114)
		(size 0.508)
		(drill 0.254)
		(layers "F.Cu" "B.Cu")
		(net "VSENSE_VSS_SENSE_C_P0")
	)
	(via
		(at 408.538172 -338.096606)
		(size 0.508)
		(drill 0.254)
		(layers "F.Cu" "B.Cu")
		(net "VSENSE_VSS_SENSE_C_P0")
	)
	(via
		(at 416.83051 -357.223822)
		(size 0.508)
		(drill 0.254)
		(layers "F.Cu" "B.Cu")
		(net "VSENSE_VSS_SENSE_C_P0")
	)
	(segment
		(start 359.412286 -326.90435)
		(end 359.199688 -326.691752)
		(width 0.254)
		(layer "B.Cu")
		(net "VSENSE_VSS_SENSE_C_P0")
	)
	(segment
		(start 408.428444 -338.206334)
		(end 383.730754 -338.206334)
		(width 0.254)
		(layer "B.Cu")
		(net "VSENSE_VSS_SENSE_C_P0")
	)
	(segment
		(start 397.164052 -301.151544)
		(end 397.164052 -304.062638)
		(width 0.254)
		(layer "B.Cu")
		(net "VSENSE_VSS_SENSE_C_P0")
	)
	(segment
		(start 372.42877 -326.90435)
		(end 359.412286 -326.90435)
		(width 0.254)
		(layer "B.Cu")
		(net "VSENSE_VSS_SENSE_C_P0")
	)
	(segment
		(start 393.003786 -296.991278)
		(end 397.164052 -301.151544)
		(width 0.254)
		(layer "B.Cu")
		(net "VSENSE_VSS_SENSE_C_P0")
	)
	(segment
		(start 392.914886 -296.12971)
		(end 393.003786 -296.21861)
		(width 0.254)
		(layer "B.Cu")
		(net "VSENSE_VSS_SENSE_C_P0")
	)
	(segment
		(start 393.003786 -296.21861)
		(end 393.003786 -296.991278)
		(width 0.254)
		(layer "B.Cu")
		(net "VSENSE_VSS_SENSE_C_P0")
	)
	(segment
		(start 407.638758 -322.736972)
		(end 407.450798 -322.924932)
		(width 0.254)
		(layer "B.Cu")
		(net "VSENSE_VSS_SENSE_C_P0")
	)
	(segment
		(start 383.730754 -338.206334)
		(end 372.42877 -326.90435)
		(width 0.254)
		(layer "B.Cu")
		(net "VSENSE_VSS_SENSE_C_P0")
	)
	(segment
		(start 392.914886 -295.955974)
		(end 392.914886 -296.12971)
		(width 0.254)
		(layer "B.Cu")
		(net "VSENSE_VSS_SENSE_C_P0")
	)
	(segment
		(start 407.638758 -314.537344)
		(end 407.638758 -322.736972)
		(width 0.254)
		(layer "B.Cu")
		(net "VSENSE_VSS_SENSE_C_P0")
	)
	(segment
		(start 397.164052 -304.062638)
		(end 407.638758 -314.537344)
		(width 0.254)
		(layer "B.Cu")
		(net "VSENSE_VSS_SENSE_C_P0")
	)
	(segment
		(start 408.538172 -338.096606)
		(end 408.428444 -338.206334)
		(width 0.254)
		(layer "B.Cu")
		(net "VSENSE_VSS_SENSE_C_P0")
	)
	(segment
		(start 360.385106 -327.117202)
		(end 359.625138 -327.117202)
		(width 0.254)
		(layer "In2.Cu")
		(net "VSENSE_VSS_SENSE_C_P0")
	)
	(segment
		(start 314.203588 -352.7806)
		(end 315.143388 -351.8408)
		(width 0.254)
		(layer "In2.Cu")
		(net "VSENSE_VSS_SENSE_C_P0")
	)
	(segment
		(start 315.143388 -351.8408)
		(end 318.440816 -351.8408)
		(width 0.254)
		(layer "In2.Cu")
		(net "VSENSE_VSS_SENSE_C_P0")
	)
	(segment
		(start 359.469944 -332.99146)
		(end 359.469944 -331.402944)
		(width 0.254)
		(layer "In2.Cu")
		(net "VSENSE_VSS_SENSE_C_P0")
	)
	(segment
		(start 360.70286 -330.170028)
		(end 360.70286 -327.434956)
		(width 0.254)
		(layer "In2.Cu")
		(net "VSENSE_VSS_SENSE_C_P0")
	)
	(segment
		(start 356.869492 -335.591912)
		(end 359.469944 -332.99146)
		(width 0.254)
		(layer "In2.Cu")
		(net "VSENSE_VSS_SENSE_C_P0")
	)
	(segment
		(start 309.809388 -352.7806)
		(end 314.203588 -352.7806)
		(width 0.254)
		(layer "In2.Cu")
		(net "VSENSE_VSS_SENSE_C_P0")
	)
	(segment
		(start 318.440816 -351.8408)
		(end 325.825104 -344.456512)
		(width 0.254)
		(layer "In2.Cu")
		(net "VSENSE_VSS_SENSE_C_P0")
	)
	(segment
		(start 307.61305 -354.3808)
		(end 308.209188 -354.3808)
		(width 0.254)
		(layer "In2.Cu")
		(net "VSENSE_VSS_SENSE_C_P0")
	)
	(segment
		(start 308.209188 -354.3808)
		(end 309.809388 -352.7806)
		(width 0.254)
		(layer "In2.Cu")
		(net "VSENSE_VSS_SENSE_C_P0")
	)
	(segment
		(start 356.869492 -344.677492)
		(end 356.869492 -335.591912)
		(width 0.254)
		(layer "In2.Cu")
		(net "VSENSE_VSS_SENSE_C_P0")
	)
	(segment
		(start 360.70286 -327.434956)
		(end 360.385106 -327.117202)
		(width 0.254)
		(layer "In2.Cu")
		(net "VSENSE_VSS_SENSE_C_P0")
	)
	(segment
		(start 359.469944 -331.402944)
		(end 360.70286 -330.170028)
		(width 0.254)
		(layer "In2.Cu")
		(net "VSENSE_VSS_SENSE_C_P0")
	)
	(segment
		(start 359.625138 -327.117202)
		(end 359.199688 -326.691752)
		(width 0.254)
		(layer "In2.Cu")
		(net "VSENSE_VSS_SENSE_C_P0")
	)
	(segment
		(start 325.825104 -344.456512)
		(end 342.355424 -344.456512)
		(width 0.254)
		(layer "In2.Cu")
		(net "VSENSE_VSS_SENSE_C_P0")
	)
	(segment
		(start 353.303332 -348.243652)
		(end 356.869492 -344.677492)
		(width 0.254)
		(layer "In2.Cu")
		(net "VSENSE_VSS_SENSE_C_P0")
	)
	(segment
		(start 346.142564 -348.243652)
		(end 353.303332 -348.243652)
		(width 0.254)
		(layer "In2.Cu")
		(net "VSENSE_VSS_SENSE_C_P0")
	)
	(segment
		(start 342.355424 -344.456512)
		(end 346.142564 -348.243652)
		(width 0.254)
		(layer "In2.Cu")
		(net "VSENSE_VSS_SENSE_C_P0")
	)
	(segment
		(start 412.297118 -332.445614)
		(end 411.705806 -333.036926)
		(width 0.254)
		(layer "In4.Cu")
		(net "VSENSE_VSS_SENSE_C_P0")
	)
	(segment
		(start 414.356296 -332.113128)
		(end 414.02381 -332.445614)
		(width 0.254)
		(layer "In4.Cu")
		(net "VSENSE_VSS_SENSE_C_P0")
	)
	(segment
		(start 409.955492 -354.141278)
		(end 412.847536 -357.033322)
		(width 0.254)
		(layer "In4.Cu")
		(net "VSENSE_VSS_SENSE_C_P0")
	)
	(segment
		(start 412.847536 -357.033322)
		(end 416.64001 -357.033322)
		(width 0.254)
		(layer "In4.Cu")
		(net "VSENSE_VSS_SENSE_C_P0")
	)
	(segment
		(start 416.64001 -357.033322)
		(end 416.83051 -357.223822)
		(width 0.254)
		(layer "In4.Cu")
		(net "VSENSE_VSS_SENSE_C_P0")
	)
	(segment
		(start 413.279082 -332.445614)
		(end 413.088582 -332.255114)
		(width 0.254)
		(layer "In4.Cu")
		(net "VSENSE_VSS_SENSE_C_P0")
	)
	(segment
		(start 409.955492 -349.213678)
		(end 409.955492 -354.141278)
		(width 0.254)
		(layer "In4.Cu")
		(net "VSENSE_VSS_SENSE_C_P0")
	)
	(segment
		(start 413.088582 -332.255114)
		(end 412.898082 -332.445614)
		(width 0.254)
		(layer "In4.Cu")
		(net "VSENSE_VSS_SENSE_C_P0")
	)
	(segment
		(start 407.450798 -322.924932)
		(end 407.635964 -323.110098)
		(width 0.254)
		(layer "In4.Cu")
		(net "VSENSE_VSS_SENSE_C_P0")
	)
	(segment
		(start 411.705806 -333.036926)
		(end 411.705806 -347.463364)
		(width 0.254)
		(layer "In4.Cu")
		(net "VSENSE_VSS_SENSE_C_P0")
	)
	(segment
		(start 414.02381 -332.445614)
		(end 413.279082 -332.445614)
		(width 0.254)
		(layer "In4.Cu")
		(net "VSENSE_VSS_SENSE_C_P0")
	)
	(segment
		(start 411.705806 -347.463364)
		(end 409.955492 -349.213678)
		(width 0.254)
		(layer "In4.Cu")
		(net "VSENSE_VSS_SENSE_C_P0")
	)
	(segment
		(start 407.635964 -324.122034)
		(end 408.539442 -325.025512)
		(width 0.254)
		(layer "In4.Cu")
		(net "VSENSE_VSS_SENSE_C_P0")
	)
	(segment
		(start 412.898082 -332.445614)
		(end 412.297118 -332.445614)
		(width 0.254)
		(layer "In4.Cu")
		(net "VSENSE_VSS_SENSE_C_P0")
	)
	(segment
		(start 414.356296 -329.190604)
		(end 414.356296 -332.113128)
		(width 0.254)
		(layer "In4.Cu")
		(net "VSENSE_VSS_SENSE_C_P0")
	)
	(segment
		(start 407.635964 -323.110098)
		(end 407.635964 -324.122034)
		(width 0.254)
		(layer "In4.Cu")
		(net "VSENSE_VSS_SENSE_C_P0")
	)
	(segment
		(start 410.191204 -325.025512)
		(end 414.356296 -329.190604)
		(width 0.254)
		(layer "In4.Cu")
		(net "VSENSE_VSS_SENSE_C_P0")
	)
	(segment
		(start 408.539442 -325.025512)
		(end 410.191204 -325.025512)
		(width 0.254)
		(layer "In4.Cu")
		(net "VSENSE_VSS_SENSE_C_P0")
	)
	(segment
		(start 418.160454 -356.446074)
		(end 418.160454 -345.620594)
		(width 0.254)
		(layer "In6.Cu")
		(net "VSENSE_VSS_SENSE_C_P0")
	)
	(segment
		(start 414.50641 -332.46695)
		(end 413.300418 -332.46695)
		(width 0.254)
		(layer "In6.Cu")
		(net "VSENSE_VSS_SENSE_C_P0")
	)
	(segment
		(start 416.83051 -357.223822)
		(end 417.057078 -356.997254)
		(width 0.254)
		(layer "In6.Cu")
		(net "VSENSE_VSS_SENSE_C_P0")
	)
	(segment
		(start 418.160454 -345.620594)
		(end 415.026094 -342.486234)
		(width 0.254)
		(layer "In6.Cu")
		(net "VSENSE_VSS_SENSE_C_P0")
	)
	(segment
		(start 417.057078 -356.997254)
		(end 417.609274 -356.997254)
		(width 0.254)
		(layer "In6.Cu")
		(net "VSENSE_VSS_SENSE_C_P0")
	)
	(segment
		(start 413.300418 -332.46695)
		(end 413.088582 -332.255114)
		(width 0.254)
		(layer "In6.Cu")
		(net "VSENSE_VSS_SENSE_C_P0")
	)
	(segment
		(start 415.026094 -342.486234)
		(end 415.026094 -332.986634)
		(width 0.254)
		(layer "In6.Cu")
		(net "VSENSE_VSS_SENSE_C_P0")
	)
	(segment
		(start 415.026094 -332.986634)
		(end 414.50641 -332.46695)
		(width 0.254)
		(layer "In6.Cu")
		(net "VSENSE_VSS_SENSE_C_P0")
	)
	(segment
		(start 417.609274 -356.997254)
		(end 418.160454 -356.446074)
		(width 0.254)
		(layer "In6.Cu")
		(net "VSENSE_VSS_SENSE_C_P0")
	)
	(segment
		(start 17.991582 -332.071218)
		(end 18.738342 -332.817978)
		(width 0.254)
		(layer "F.Cu")
		(net "VSENSE_VSS_SENSE_B_P1")
	)
	(segment
		(start 17.991582 -328.980292)
		(end 17.991582 -332.071218)
		(width 0.254)
		(layer "F.Cu")
		(net "VSENSE_VSS_SENSE_B_P1")
	)
	(segment
		(start 35.79495 -359.55605)
		(end 36.068 -359.283)
		(width 0.254)
		(layer "F.Cu")
		(net "VSENSE_VSS_SENSE_B_P1")
	)
	(segment
		(start 18.738342 -332.817978)
		(end 19.527774 -332.817978)
		(width 0.254)
		(layer "F.Cu")
		(net "VSENSE_VSS_SENSE_B_P1")
	)
	(segment
		(start 21.087842 -333.148178)
		(end 21.411692 -332.824328)
		(width 0.254)
		(layer "F.Cu")
		(net "VSENSE_VSS_SENSE_B_P1")
	)
	(segment
		(start 21.771102 -332.824328)
		(end 22.098 -333.151226)
		(width 0.254)
		(layer "F.Cu")
		(net "VSENSE_VSS_SENSE_B_P1")
	)
	(segment
		(start 34.925 -361.696)
		(end 34.925 -360.91495)
		(width 0.254)
		(layer "F.Cu")
		(net "VSENSE_VSS_SENSE_B_P1")
	)
	(segment
		(start 20.00504 -333.295244)
		(end 20.481798 -332.818486)
		(width 0.254)
		(layer "F.Cu")
		(net "VSENSE_VSS_SENSE_B_P1")
	)
	(segment
		(start 24.758142 -322.213732)
		(end 17.991582 -328.980292)
		(width 0.254)
		(layer "F.Cu")
		(net "VSENSE_VSS_SENSE_B_P1")
	)
	(segment
		(start 33.355026 -362.708952)
		(end 33.912048 -362.708952)
		(width 0.1778)
		(layer "F.Cu")
		(net "VSENSE_VSS_SENSE_B_P1")
	)
	(segment
		(start 35.79495 -360.045)
		(end 35.79495 -359.55605)
		(width 0.254)
		(layer "F.Cu")
		(net "VSENSE_VSS_SENSE_B_P1")
	)
	(segment
		(start 53.357018 -322.213732)
		(end 24.758142 -322.213732)
		(width 0.254)
		(layer "F.Cu")
		(net "VSENSE_VSS_SENSE_B_P1")
	)
	(segment
		(start 85.541612 -302.796448)
		(end 85.681058 -302.935894)
		(width 0.254)
		(layer "F.Cu")
		(net "VSENSE_VSS_SENSE_B_P1")
	)
	(segment
		(start 34.671 -361.95)
		(end 34.925 -361.696)
		(width 0.254)
		(layer "F.Cu")
		(net "VSENSE_VSS_SENSE_B_P1")
	)
	(segment
		(start 20.481798 -332.818486)
		(end 20.75815 -332.818486)
		(width 0.254)
		(layer "F.Cu")
		(net "VSENSE_VSS_SENSE_B_P1")
	)
	(segment
		(start 62.501272 -321.395852)
		(end 54.174898 -321.395852)
		(width 0.254)
		(layer "F.Cu")
		(net "VSENSE_VSS_SENSE_B_P1")
	)
	(segment
		(start 19.527774 -332.817978)
		(end 20.00504 -333.295244)
		(width 0.254)
		(layer "F.Cu")
		(net "VSENSE_VSS_SENSE_B_P1")
	)
	(segment
		(start 34.925 -360.91495)
		(end 35.79495 -360.045)
		(width 0.254)
		(layer "F.Cu")
		(net "VSENSE_VSS_SENSE_B_P1")
	)
	(segment
		(start 85.681058 -302.935894)
		(end 85.681058 -308.282848)
		(width 0.254)
		(layer "F.Cu")
		(net "VSENSE_VSS_SENSE_B_P1")
	)
	(segment
		(start 82.96021 -311.003696)
		(end 72.893428 -311.003696)
		(width 0.254)
		(layer "F.Cu")
		(net "VSENSE_VSS_SENSE_B_P1")
	)
	(segment
		(start 72.893428 -311.003696)
		(end 62.501272 -321.395852)
		(width 0.254)
		(layer "F.Cu")
		(net "VSENSE_VSS_SENSE_B_P1")
	)
	(segment
		(start 54.174898 -321.395852)
		(end 53.357018 -322.213732)
		(width 0.254)
		(layer "F.Cu")
		(net "VSENSE_VSS_SENSE_B_P1")
	)
	(segment
		(start 20.75815 -332.818486)
		(end 21.087842 -333.148178)
		(width 0.254)
		(layer "F.Cu")
		(net "VSENSE_VSS_SENSE_B_P1")
	)
	(segment
		(start 85.681058 -308.282848)
		(end 82.96021 -311.003696)
		(width 0.254)
		(layer "F.Cu")
		(net "VSENSE_VSS_SENSE_B_P1")
	)
	(segment
		(start 97.507806 -268.15034)
		(end 97.040954 -268.416278)
		(width 0.254)
		(layer "F.Cu")
		(net "VSENSE_VSS_SENSE_B_P1")
	)
	(segment
		(start 21.411692 -332.824328)
		(end 21.771102 -332.824328)
		(width 0.254)
		(layer "F.Cu")
		(net "VSENSE_VSS_SENSE_B_P1")
	)
	(segment
		(start 33.912048 -362.708952)
		(end 34.671 -361.95)
		(width 0.1778)
		(layer "F.Cu")
		(net "VSENSE_VSS_SENSE_B_P1")
	)
	(via
		(at 97.040954 -268.416278)
		(size 0.4064)
		(drill 0.2032)
		(layers "F.Cu" "B.Cu")
		(net "VSENSE_VSS_SENSE_B_P1")
	)
	(via
		(at 85.541612 -302.796448)
		(size 0.508)
		(drill 0.254)
		(layers "F.Cu" "B.Cu")
		(net "VSENSE_VSS_SENSE_B_P1")
	)
	(via
		(at 36.068 -359.283)
		(size 0.508)
		(drill 0.254)
		(layers "F.Cu" "B.Cu")
		(net "VSENSE_VSS_SENSE_B_P1")
	)
	(via
		(at 21.087842 -333.148178)
		(size 0.508)
		(drill 0.254)
		(layers "F.Cu" "B.Cu")
		(net "VSENSE_VSS_SENSE_B_P1")
	)
	(segment
		(start 90.679778 -290.7919)
		(end 90.648028 -290.773612)
		(width 0.0762)
		(layer "B.Cu")
		(net "VSENSE_VSS_SENSE_B_P1")
	)
	(segment
		(start 90.608912 -283.341826)
		(end 90.648028 -283.318966)
		(width 0.0762)
		(layer "B.Cu")
		(net "VSENSE_VSS_SENSE_B_P1")
	)
	(segment
		(start 90.648028 -290.773612)
		(end 90.608912 -290.750752)
		(width 0.0762)
		(layer "B.Cu")
		(net "VSENSE_VSS_SENSE_B_P1")
	)
	(segment
		(start 90.679778 -282.692094)
		(end 90.648028 -282.673806)
		(width 0.0762)
		(layer "B.Cu")
		(net "VSENSE_VSS_SENSE_B_P1")
	)
	(segment
		(start 88.127078 -300.346618)
		(end 89.368884 -299.104812)
		(width 0.254)
		(layer "B.Cu")
		(net "VSENSE_VSS_SENSE_B_P1")
	)
	(segment
		(start 97.411286 -268.47292)
		(end 97.354644 -268.416278)
		(width 0.0762)
		(layer "B.Cu")
		(net "VSENSE_VSS_SENSE_B_P1")
	)
	(segment
		(start 91.079066 -292.251638)
		(end 91.118182 -292.228778)
		(width 0.0762)
		(layer "B.Cu")
		(net "VSENSE_VSS_SENSE_B_P1")
	)
	(segment
		(start 90.608912 -286.581596)
		(end 90.648028 -286.558736)
		(width 0.0762)
		(layer "B.Cu")
		(net "VSENSE_VSS_SENSE_B_P1")
	)
	(segment
		(start 93.93682 -276.026372)
		(end 93.942916 -276.022816)
		(width 0.0762)
		(layer "B.Cu")
		(net "VSENSE_VSS_SENSE_B_P1")
	)
	(segment
		(start 96.757998 -270.523716)
		(end 96.721676 -270.502634)
		(width 0.0762)
		(layer "B.Cu")
		(net "VSENSE_VSS_SENSE_B_P1")
	)
	(segment
		(start 91.118182 -291.583618)
		(end 91.079066 -291.560758)
		(width 0.0762)
		(layer "B.Cu")
		(net "VSENSE_VSS_SENSE_B_P1")
	)
	(segment
		(start 90.648028 -283.318966)
		(end 90.679778 -283.300678)
		(width 0.0762)
		(layer "B.Cu")
		(net "VSENSE_VSS_SENSE_B_P1")
	)
	(segment
		(start 96.475804 -271.656302)
		(end 96.475804 -271.62887)
		(width 0.0762)
		(layer "B.Cu")
		(net "VSENSE_VSS_SENSE_B_P1")
	)
	(segment
		(start 92.528136 -278.45893)
		(end 92.558616 -278.44115)
		(width 0.0762)
		(layer "B.Cu")
		(net "VSENSE_VSS_SENSE_B_P1")
	)
	(segment
		(start 91.118182 -288.988754)
		(end 91.148662 -288.970974)
		(width 0.0762)
		(layer "B.Cu")
		(net "VSENSE_VSS_SENSE_B_P1")
	)
	(segment
		(start 90.648028 -284.293818)
		(end 90.608912 -284.270958)
		(width 0.0762)
		(layer "B.Cu")
		(net "VSENSE_VSS_SENSE_B_P1")
	)
	(segment
		(start 88.955626 -296.472864)
		(end 88.955626 -295.91254)
		(width 0.0762)
		(layer "B.Cu")
		(net "VSENSE_VSS_SENSE_B_P1")
	)
	(segment
		(start 90.648028 -281.698954)
		(end 90.679778 -281.680666)
		(width 0.0762)
		(layer "B.Cu")
		(net "VSENSE_VSS_SENSE_B_P1")
	)
	(segment
		(start 85.541612 -302.796448)
		(end 85.66277 -302.67529)
		(width 0.254)
		(layer "B.Cu")
		(net "VSENSE_VSS_SENSE_B_P1")
	)
	(segment
		(start 85.66277 -301.637954)
		(end 86.954106 -300.346618)
		(width 0.254)
		(layer "B.Cu")
		(net "VSENSE_VSS_SENSE_B_P1")
	)
	(segment
		(start 90.679778 -284.312106)
		(end 90.648028 -284.293818)
		(width 0.0762)
		(layer "B.Cu")
		(net "VSENSE_VSS_SENSE_B_P1")
	)
	(segment
		(start 91.118182 -288.343848)
		(end 91.079066 -288.320988)
		(width 0.0762)
		(layer "B.Cu")
		(net "VSENSE_VSS_SENSE_B_P1")
	)
	(segment
		(start 90.648028 -293.038784)
		(end 90.679778 -293.020496)
		(width 0.0762)
		(layer "B.Cu")
		(net "VSENSE_VSS_SENSE_B_P1")
	)
	(segment
		(start 91.118182 -280.888948)
		(end 91.148662 -280.871168)
		(width 0.0762)
		(layer "B.Cu")
		(net "VSENSE_VSS_SENSE_B_P1")
	)
	(segment
		(start 95.779082 -272.811748)
		(end 95.818198 -272.788888)
		(width 0.0762)
		(layer "B.Cu")
		(net "VSENSE_VSS_SENSE_B_P1")
	)
	(segment
		(start 91.118182 -292.228778)
		(end 91.148662 -292.210998)
		(width 0.0762)
		(layer "B.Cu")
		(net "VSENSE_VSS_SENSE_B_P1")
	)
	(segment
		(start 95.308928 -273.621754)
		(end 95.348044 -273.598894)
		(width 0.0762)
		(layer "B.Cu")
		(net "VSENSE_VSS_SENSE_B_P1")
	)
	(segment
		(start 93.429074 -276.861778)
		(end 93.46819 -276.838918)
		(width 0.0762)
		(layer "B.Cu")
		(net "VSENSE_VSS_SENSE_B_P1")
	)
	(segment
		(start 91.148662 -291.601398)
		(end 91.118182 -291.583618)
		(width 0.0762)
		(layer "B.Cu")
		(net "VSENSE_VSS_SENSE_B_P1")
	)
	(segment
		(start 91.079066 -289.011614)
		(end 91.118182 -288.988754)
		(width 0.0762)
		(layer "B.Cu")
		(net "VSENSE_VSS_SENSE_B_P1")
	)
	(segment
		(start 90.648028 -286.558736)
		(end 90.681556 -286.539178)
		(width 0.0762)
		(layer "B.Cu")
		(net "VSENSE_VSS_SENSE_B_P1")
	)
	(segment
		(start 90.139012 -293.87165)
		(end 90.178128 -293.84879)
		(width 0.0762)
		(layer "B.Cu")
		(net "VSENSE_VSS_SENSE_B_P1")
	)
	(segment
		(start 97.354644 -268.416278)
		(end 97.040954 -268.416278)
		(width 0.0762)
		(layer "B.Cu")
		(net "VSENSE_VSS_SENSE_B_P1")
	)
	(segment
		(start 91.586812 -280.076402)
		(end 91.592908 -280.072846)
		(width 0.0762)
		(layer "B.Cu")
		(net "VSENSE_VSS_SENSE_B_P1")
	)
	(segment
		(start 90.648028 -287.533842)
		(end 90.611452 -287.512506)
		(width 0.0762)
		(layer "B.Cu")
		(net "VSENSE_VSS_SENSE_B_P1")
	)
	(segment
		(start 88.860376 -297.423586)
		(end 88.860376 -296.612564)
		(width 0.254)
		(layer "B.Cu")
		(net "VSENSE_VSS_SENSE_B_P1")
	)
	(segment
		(start 96.757998 -269.548864)
		(end 96.789748 -269.530576)
		(width 0.0762)
		(layer "B.Cu")
		(net "VSENSE_VSS_SENSE_B_P1")
	)
	(segment
		(start 90.608912 -293.061644)
		(end 90.648028 -293.038784)
		(width 0.0762)
		(layer "B.Cu")
		(net "VSENSE_VSS_SENSE_B_P1")
	)
	(segment
		(start 89.21115 -295.46804)
		(end 89.254076 -295.443402)
		(width 0.0762)
		(layer "B.Cu")
		(net "VSENSE_VSS_SENSE_B_P1")
	)
	(segment
		(start 91.150694 -288.362644)
		(end 91.118182 -288.343848)
		(width 0.0762)
		(layer "B.Cu")
		(net "VSENSE_VSS_SENSE_B_P1")
	)
	(segment
		(start 86.954106 -300.346618)
		(end 88.127078 -300.346618)
		(width 0.254)
		(layer "B.Cu")
		(net "VSENSE_VSS_SENSE_B_P1")
	)
	(segment
		(start 96.789748 -270.542004)
		(end 96.757998 -270.523716)
		(width 0.0762)
		(layer "B.Cu")
		(net "VSENSE_VSS_SENSE_B_P1")
	)
	(segment
		(start 89.368884 -299.104812)
		(end 89.368884 -297.932094)
		(width 0.254)
		(layer "B.Cu")
		(net "VSENSE_VSS_SENSE_B_P1")
	)
	(segment
		(start 94.878144 -274.4089)
		(end 94.908624 -274.39112)
		(width 0.0762)
		(layer "B.Cu")
		(net "VSENSE_VSS_SENSE_B_P1")
	)
	(segment
		(start 90.679778 -287.55213)
		(end 90.648028 -287.533842)
		(width 0.0762)
		(layer "B.Cu")
		(net "VSENSE_VSS_SENSE_B_P1")
	)
	(segment
		(start 90.608912 -284.961838)
		(end 90.648028 -284.938978)
		(width 0.0762)
		(layer "B.Cu")
		(net "VSENSE_VSS_SENSE_B_P1")
	)
	(segment
		(start 90.648028 -289.79876)
		(end 90.679778 -289.780472)
		(width 0.0762)
		(layer "B.Cu")
		(net "VSENSE_VSS_SENSE_B_P1")
	)
	(segment
		(start 89.622122 -294.71366)
		(end 89.707974 -294.658796)
		(width 0.0762)
		(layer "B.Cu")
		(net "VSENSE_VSS_SENSE_B_P1")
	)
	(segment
		(start 95.818198 -272.788888)
		(end 95.848678 -272.771108)
		(width 0.0762)
		(layer "B.Cu")
		(net "VSENSE_VSS_SENSE_B_P1")
	)
	(segment
		(start 96.724724 -271.181576)
		(end 96.754442 -271.163034)
		(width 0.0762)
		(layer "B.Cu")
		(net "VSENSE_VSS_SENSE_B_P1")
	)
	(segment
		(start 90.648028 -282.673806)
		(end 90.608912 -282.650946)
		(width 0.0762)
		(layer "B.Cu")
		(net "VSENSE_VSS_SENSE_B_P1")
	)
	(segment
		(start 94.125796 -275.706332)
		(end 94.125796 -275.702268)
		(width 0.0762)
		(layer "B.Cu")
		(net "VSENSE_VSS_SENSE_B_P1")
	)
	(segment
		(start 88.860376 -296.568114)
		(end 88.955626 -296.472864)
		(width 0.0762)
		(layer "B.Cu")
		(net "VSENSE_VSS_SENSE_B_P1")
	)
	(segment
		(start 94.839028 -274.43176)
		(end 94.878144 -274.4089)
		(width 0.0762)
		(layer "B.Cu")
		(net "VSENSE_VSS_SENSE_B_P1")
	)
	(segment
		(start 95.348044 -273.598894)
		(end 95.379794 -273.580606)
		(width 0.0762)
		(layer "B.Cu")
		(net "VSENSE_VSS_SENSE_B_P1")
	)
	(segment
		(start 91.079066 -280.911808)
		(end 91.118182 -280.888948)
		(width 0.0762)
		(layer "B.Cu")
		(net "VSENSE_VSS_SENSE_B_P1")
	)
	(segment
		(start 97.189036 -268.761718)
		(end 97.228152 -268.738858)
		(width 0.0762)
		(layer "B.Cu")
		(net "VSENSE_VSS_SENSE_B_P1")
	)
	(segment
		(start 88.860376 -296.612564)
		(end 88.860376 -296.568114)
		(width 0.0762)
		(layer "B.Cu")
		(net "VSENSE_VSS_SENSE_B_P1")
	)
	(segment
		(start 96.754442 -271.163034)
		(end 96.758506 -271.160748)
		(width 0.0762)
		(layer "B.Cu")
		(net "VSENSE_VSS_SENSE_B_P1")
	)
	(segment
		(start 89.707974 -294.658796)
		(end 89.739724 -294.640508)
		(width 0.0762)
		(layer "B.Cu")
		(net "VSENSE_VSS_SENSE_B_P1")
	)
	(segment
		(start 92.48902 -278.48179)
		(end 92.528136 -278.45893)
		(width 0.0762)
		(layer "B.Cu")
		(net "VSENSE_VSS_SENSE_B_P1")
	)
	(segment
		(start 92.95892 -277.671784)
		(end 92.998036 -277.648924)
		(width 0.0762)
		(layer "B.Cu")
		(net "VSENSE_VSS_SENSE_B_P1")
	)
	(segment
		(start 90.648028 -284.938978)
		(end 90.679778 -284.92069)
		(width 0.0762)
		(layer "B.Cu")
		(net "VSENSE_VSS_SENSE_B_P1")
	)
	(segment
		(start 85.66277 -302.67529)
		(end 85.66277 -301.637954)
		(width 0.254)
		(layer "B.Cu")
		(net "VSENSE_VSS_SENSE_B_P1")
	)
	(segment
		(start 96.721676 -269.569946)
		(end 96.757998 -269.548864)
		(width 0.0762)
		(layer "B.Cu")
		(net "VSENSE_VSS_SENSE_B_P1")
	)
	(segment
		(start 90.608912 -281.721814)
		(end 90.648028 -281.698954)
		(width 0.0762)
		(layer "B.Cu")
		(net "VSENSE_VSS_SENSE_B_P1")
	)
	(segment
		(start 90.679778 -285.932118)
		(end 90.648028 -285.91383)
		(width 0.0762)
		(layer "B.Cu")
		(net "VSENSE_VSS_SENSE_B_P1")
	)
	(segment
		(start 91.775788 -279.756362)
		(end 91.775788 -279.753822)
		(width 0.0762)
		(layer "B.Cu")
		(net "VSENSE_VSS_SENSE_B_P1")
	)
	(segment
		(start 92.998036 -277.648924)
		(end 93.029786 -277.630636)
		(width 0.0762)
		(layer "B.Cu")
		(net "VSENSE_VSS_SENSE_B_P1")
	)
	(segment
		(start 93.46819 -276.838918)
		(end 93.49867 -276.821138)
		(width 0.0762)
		(layer "B.Cu")
		(net "VSENSE_VSS_SENSE_B_P1")
	)
	(segment
		(start 97.228152 -268.738858)
		(end 97.258632 -268.721078)
		(width 0.0762)
		(layer "B.Cu")
		(net "VSENSE_VSS_SENSE_B_P1")
	)
	(segment
		(start 94.402148 -275.222208)
		(end 94.43974 -275.200618)
		(width 0.0762)
		(layer "B.Cu")
		(net "VSENSE_VSS_SENSE_B_P1")
	)
	(segment
		(start 90.608912 -289.82162)
		(end 90.648028 -289.79876)
		(width 0.0762)
		(layer "B.Cu")
		(net "VSENSE_VSS_SENSE_B_P1")
	)
	(segment
		(start 90.648028 -285.91383)
		(end 90.608912 -285.89097)
		(width 0.0762)
		(layer "B.Cu")
		(net "VSENSE_VSS_SENSE_B_P1")
	)
	(segment
		(start 89.42578 -295.146222)
		(end 89.42578 -295.086278)
		(width 0.0762)
		(layer "B.Cu")
		(net "VSENSE_VSS_SENSE_B_P1")
	)
	(segment
		(start 92.05341 -279.271476)
		(end 92.089732 -279.250648)
		(width 0.0762)
		(layer "B.Cu")
		(net "VSENSE_VSS_SENSE_B_P1")
	)
	(segment
		(start 96.286828 -271.976342)
		(end 96.292924 -271.972786)
		(width 0.0762)
		(layer "B.Cu")
		(net "VSENSE_VSS_SENSE_B_P1")
	)
	(segment
		(start 89.368884 -297.932094)
		(end 88.860376 -297.423586)
		(width 0.254)
		(layer "B.Cu")
		(net "VSENSE_VSS_SENSE_B_P1")
	)
	(segment
		(start 90.178128 -293.84879)
		(end 90.208608 -293.83101)
		(width 0.0762)
		(layer "B.Cu")
		(net "VSENSE_VSS_SENSE_B_P1")
	)
	(arc
		(start 95.065596 -274.08632)
		(mid 95.130111 -273.824101)
		(end 95.308928 -273.621754)
		(width 0.0762)
		(layer "B.Cu")
		(net "VSENSE_VSS_SENSE_B_P1")
	)
	(arc
		(start 91.148662 -292.210998)
		(mid 91.305639 -291.906198)
		(end 91.148662 -291.601398)
		(width 0.0762)
		(layer "B.Cu")
		(net "VSENSE_VSS_SENSE_B_P1")
	)
	(arc
		(start 91.305634 -288.666174)
		(mid 91.264668 -288.495768)
		(end 91.150694 -288.362644)
		(width 0.0762)
		(layer "B.Cu")
		(net "VSENSE_VSS_SENSE_B_P1")
	)
	(arc
		(start 90.608912 -290.750752)
		(mid 90.365585 -290.286186)
		(end 90.608912 -289.82162)
		(width 0.0762)
		(layer "B.Cu")
		(net "VSENSE_VSS_SENSE_B_P1")
	)
	(arc
		(start 92.245688 -278.946356)
		(mid 92.310203 -278.684137)
		(end 92.48902 -278.48179)
		(width 0.0762)
		(layer "B.Cu")
		(net "VSENSE_VSS_SENSE_B_P1")
	)
	(arc
		(start 90.681556 -286.539178)
		(mid 90.794963 -286.406289)
		(end 90.835734 -286.23641)
		(width 0.0762)
		(layer "B.Cu")
		(net "VSENSE_VSS_SENSE_B_P1")
	)
	(arc
		(start 88.955626 -295.91254)
		(mid 89.024062 -295.656188)
		(end 89.21115 -295.46804)
		(width 0.0762)
		(layer "B.Cu")
		(net "VSENSE_VSS_SENSE_B_P1")
	)
	(arc
		(start 93.942916 -276.022816)
		(mid 94.076801 -275.889098)
		(end 94.125796 -275.706332)
		(width 0.0762)
		(layer "B.Cu")
		(net "VSENSE_VSS_SENSE_B_P1")
	)
	(arc
		(start 90.835734 -291.096192)
		(mid 90.794479 -290.925221)
		(end 90.679778 -290.7919)
		(width 0.0762)
		(layer "B.Cu")
		(net "VSENSE_VSS_SENSE_B_P1")
	)
	(arc
		(start 93.029786 -277.630636)
		(mid 93.144462 -277.497302)
		(end 93.185742 -277.326344)
		(width 0.0762)
		(layer "B.Cu")
		(net "VSENSE_VSS_SENSE_B_P1")
	)
	(arc
		(start 94.908624 -274.39112)
		(mid 95.024051 -274.257744)
		(end 95.065596 -274.08632)
		(width 0.0762)
		(layer "B.Cu")
		(net "VSENSE_VSS_SENSE_B_P1")
	)
	(arc
		(start 90.208608 -293.83101)
		(mid 90.324035 -293.697634)
		(end 90.36558 -293.52621)
		(width 0.0762)
		(layer "B.Cu")
		(net "VSENSE_VSS_SENSE_B_P1")
	)
	(arc
		(start 90.835734 -281.376374)
		(mid 90.900249 -281.114155)
		(end 91.079066 -280.911808)
		(width 0.0762)
		(layer "B.Cu")
		(net "VSENSE_VSS_SENSE_B_P1")
	)
	(arc
		(start 89.739724 -294.640508)
		(mid 89.8544 -294.507174)
		(end 89.89568 -294.336216)
		(width 0.0762)
		(layer "B.Cu")
		(net "VSENSE_VSS_SENSE_B_P1")
	)
	(arc
		(start 91.592908 -280.072846)
		(mid 91.726793 -279.939128)
		(end 91.775788 -279.756362)
		(width 0.0762)
		(layer "B.Cu")
		(net "VSENSE_VSS_SENSE_B_P1")
	)
	(arc
		(start 92.558616 -278.44115)
		(mid 92.674043 -278.307774)
		(end 92.715588 -278.13635)
		(width 0.0762)
		(layer "B.Cu")
		(net "VSENSE_VSS_SENSE_B_P1")
	)
	(arc
		(start 90.835734 -286.23641)
		(mid 90.794479 -286.065439)
		(end 90.679778 -285.932118)
		(width 0.0762)
		(layer "B.Cu")
		(net "VSENSE_VSS_SENSE_B_P1")
	)
	(arc
		(start 93.655642 -276.516338)
		(mid 93.730935 -276.233887)
		(end 93.93682 -276.026372)
		(width 0.0762)
		(layer "B.Cu")
		(net "VSENSE_VSS_SENSE_B_P1")
	)
	(arc
		(start 90.679778 -281.680666)
		(mid 90.794454 -281.547332)
		(end 90.835734 -281.376374)
		(width 0.0762)
		(layer "B.Cu")
		(net "VSENSE_VSS_SENSE_B_P1")
	)
	(arc
		(start 90.835734 -289.47618)
		(mid 90.900249 -289.213961)
		(end 91.079066 -289.011614)
		(width 0.0762)
		(layer "B.Cu")
		(net "VSENSE_VSS_SENSE_B_P1")
	)
	(arc
		(start 90.36558 -293.52621)
		(mid 90.430095 -293.263991)
		(end 90.608912 -293.061644)
		(width 0.0762)
		(layer "B.Cu")
		(net "VSENSE_VSS_SENSE_B_P1")
	)
	(arc
		(start 92.089732 -279.250648)
		(mid 92.204408 -279.117314)
		(end 92.245688 -278.946356)
		(width 0.0762)
		(layer "B.Cu")
		(net "VSENSE_VSS_SENSE_B_P1")
	)
	(arc
		(start 94.595696 -274.896326)
		(mid 94.660211 -274.634107)
		(end 94.839028 -274.43176)
		(width 0.0762)
		(layer "B.Cu")
		(net "VSENSE_VSS_SENSE_B_P1")
	)
	(arc
		(start 95.848678 -272.771108)
		(mid 95.964105 -272.637732)
		(end 96.00565 -272.466308)
		(width 0.0762)
		(layer "B.Cu")
		(net "VSENSE_VSS_SENSE_B_P1")
	)
	(arc
		(start 90.679778 -289.780472)
		(mid 90.794454 -289.647138)
		(end 90.835734 -289.47618)
		(width 0.0762)
		(layer "B.Cu")
		(net "VSENSE_VSS_SENSE_B_P1")
	)
	(arc
		(start 90.835734 -292.716204)
		(mid 90.900249 -292.453985)
		(end 91.079066 -292.251638)
		(width 0.0762)
		(layer "B.Cu")
		(net "VSENSE_VSS_SENSE_B_P1")
	)
	(arc
		(start 96.758506 -271.160748)
		(mid 96.94281 -270.859854)
		(end 96.789748 -270.542004)
		(width 0.0762)
		(layer "B.Cu")
		(net "VSENSE_VSS_SENSE_B_P1")
	)
	(arc
		(start 96.789748 -269.530576)
		(mid 96.904424 -269.397242)
		(end 96.945704 -269.226284)
		(width 0.0762)
		(layer "B.Cu")
		(net "VSENSE_VSS_SENSE_B_P1")
	)
	(arc
		(start 89.42578 -295.086278)
		(mid 89.477859 -294.875675)
		(end 89.622122 -294.71366)
		(width 0.0762)
		(layer "B.Cu")
		(net "VSENSE_VSS_SENSE_B_P1")
	)
	(arc
		(start 91.148662 -280.871168)
		(mid 91.264089 -280.737792)
		(end 91.305634 -280.566368)
		(width 0.0762)
		(layer "B.Cu")
		(net "VSENSE_VSS_SENSE_B_P1")
	)
	(arc
		(start 93.185742 -277.326344)
		(mid 93.250257 -277.064125)
		(end 93.429074 -276.861778)
		(width 0.0762)
		(layer "B.Cu")
		(net "VSENSE_VSS_SENSE_B_P1")
	)
	(arc
		(start 94.125796 -275.702268)
		(mid 94.199811 -275.425295)
		(end 94.402148 -275.222208)
		(width 0.0762)
		(layer "B.Cu")
		(net "VSENSE_VSS_SENSE_B_P1")
	)
	(arc
		(start 90.679778 -293.020496)
		(mid 90.794454 -292.887162)
		(end 90.835734 -292.716204)
		(width 0.0762)
		(layer "B.Cu")
		(net "VSENSE_VSS_SENSE_B_P1")
	)
	(arc
		(start 90.679778 -284.92069)
		(mid 90.835706 -284.616398)
		(end 90.679778 -284.312106)
		(width 0.0762)
		(layer "B.Cu")
		(net "VSENSE_VSS_SENSE_B_P1")
	)
	(arc
		(start 96.475804 -271.62887)
		(mid 96.542229 -271.37293)
		(end 96.724724 -271.181576)
		(width 0.0762)
		(layer "B.Cu")
		(net "VSENSE_VSS_SENSE_B_P1")
	)
	(arc
		(start 96.00565 -272.466308)
		(mid 96.080943 -272.183857)
		(end 96.286828 -271.976342)
		(width 0.0762)
		(layer "B.Cu")
		(net "VSENSE_VSS_SENSE_B_P1")
	)
	(arc
		(start 92.715588 -278.13635)
		(mid 92.780103 -277.874131)
		(end 92.95892 -277.671784)
		(width 0.0762)
		(layer "B.Cu")
		(net "VSENSE_VSS_SENSE_B_P1")
	)
	(arc
		(start 94.43974 -275.200618)
		(mid 94.554416 -275.067284)
		(end 94.595696 -274.896326)
		(width 0.0762)
		(layer "B.Cu")
		(net "VSENSE_VSS_SENSE_B_P1")
	)
	(arc
		(start 90.608912 -282.650946)
		(mid 90.365585 -282.18638)
		(end 90.608912 -281.721814)
		(width 0.0762)
		(layer "B.Cu")
		(net "VSENSE_VSS_SENSE_B_P1")
	)
	(arc
		(start 91.148662 -288.970974)
		(mid 91.264089 -288.837598)
		(end 91.305634 -288.666174)
		(width 0.0762)
		(layer "B.Cu")
		(net "VSENSE_VSS_SENSE_B_P1")
	)
	(arc
		(start 91.079066 -288.320988)
		(mid 90.900253 -288.118638)
		(end 90.835734 -287.856422)
		(width 0.0762)
		(layer "B.Cu")
		(net "VSENSE_VSS_SENSE_B_P1")
	)
	(arc
		(start 91.079066 -291.560758)
		(mid 90.900253 -291.358408)
		(end 90.835734 -291.096192)
		(width 0.0762)
		(layer "B.Cu")
		(net "VSENSE_VSS_SENSE_B_P1")
	)
	(arc
		(start 90.608912 -284.270958)
		(mid 90.365585 -283.806392)
		(end 90.608912 -283.341826)
		(width 0.0762)
		(layer "B.Cu")
		(net "VSENSE_VSS_SENSE_B_P1")
	)
	(arc
		(start 96.292924 -271.972786)
		(mid 96.426809 -271.839068)
		(end 96.475804 -271.656302)
		(width 0.0762)
		(layer "B.Cu")
		(net "VSENSE_VSS_SENSE_B_P1")
	)
	(arc
		(start 91.305634 -280.566368)
		(mid 91.380927 -280.283917)
		(end 91.586812 -280.076402)
		(width 0.0762)
		(layer "B.Cu")
		(net "VSENSE_VSS_SENSE_B_P1")
	)
	(arc
		(start 90.679778 -283.300678)
		(mid 90.835706 -282.996386)
		(end 90.679778 -282.692094)
		(width 0.0762)
		(layer "B.Cu")
		(net "VSENSE_VSS_SENSE_B_P1")
	)
	(arc
		(start 93.49867 -276.821138)
		(mid 93.614097 -276.687762)
		(end 93.655642 -276.516338)
		(width 0.0762)
		(layer "B.Cu")
		(net "VSENSE_VSS_SENSE_B_P1")
	)
	(arc
		(start 90.36558 -287.046162)
		(mid 90.430095 -286.783943)
		(end 90.608912 -286.581596)
		(width 0.0762)
		(layer "B.Cu")
		(net "VSENSE_VSS_SENSE_B_P1")
	)
	(arc
		(start 96.945704 -269.226284)
		(mid 97.010219 -268.964065)
		(end 97.189036 -268.761718)
		(width 0.0762)
		(layer "B.Cu")
		(net "VSENSE_VSS_SENSE_B_P1")
	)
	(arc
		(start 90.608912 -285.89097)
		(mid 90.365585 -285.426404)
		(end 90.608912 -284.961838)
		(width 0.0762)
		(layer "B.Cu")
		(net "VSENSE_VSS_SENSE_B_P1")
	)
	(arc
		(start 90.835734 -287.856422)
		(mid 90.794479 -287.685451)
		(end 90.679778 -287.55213)
		(width 0.0762)
		(layer "B.Cu")
		(net "VSENSE_VSS_SENSE_B_P1")
	)
	(arc
		(start 90.611452 -287.512506)
		(mid 90.4308 -287.309761)
		(end 90.36558 -287.046162)
		(width 0.0762)
		(layer "B.Cu")
		(net "VSENSE_VSS_SENSE_B_P1")
	)
	(arc
		(start 95.53575 -273.276314)
		(mid 95.600265 -273.014095)
		(end 95.779082 -272.811748)
		(width 0.0762)
		(layer "B.Cu")
		(net "VSENSE_VSS_SENSE_B_P1")
	)
	(arc
		(start 96.721676 -270.502634)
		(mid 96.475786 -270.03629)
		(end 96.721676 -269.569946)
		(width 0.0762)
		(layer "B.Cu")
		(net "VSENSE_VSS_SENSE_B_P1")
	)
	(arc
		(start 89.89568 -294.336216)
		(mid 89.960195 -294.073997)
		(end 90.139012 -293.87165)
		(width 0.0762)
		(layer "B.Cu")
		(net "VSENSE_VSS_SENSE_B_P1")
	)
	(arc
		(start 95.379794 -273.580606)
		(mid 95.49447 -273.447272)
		(end 95.53575 -273.276314)
		(width 0.0762)
		(layer "B.Cu")
		(net "VSENSE_VSS_SENSE_B_P1")
	)
	(arc
		(start 89.254076 -295.443402)
		(mid 89.379813 -295.317847)
		(end 89.42578 -295.146222)
		(width 0.0762)
		(layer "B.Cu")
		(net "VSENSE_VSS_SENSE_B_P1")
	)
	(arc
		(start 97.258632 -268.721078)
		(mid 97.360103 -268.612457)
		(end 97.411286 -268.47292)
		(width 0.0762)
		(layer "B.Cu")
		(net "VSENSE_VSS_SENSE_B_P1")
	)
	(arc
		(start 91.775788 -279.753822)
		(mid 91.850154 -279.47556)
		(end 92.05341 -279.271476)
		(width 0.0762)
		(layer "B.Cu")
		(net "VSENSE_VSS_SENSE_B_P1")
	)
	(segment
		(start 26.501852 -355.961188)
		(end 23.305262 -352.764598)
		(width 0.254)
		(layer "In11.Cu")
		(net "VSENSE_VSS_SENSE_B_P1")
	)
	(segment
		(start 20.405598 -332.842616)
		(end 20.764754 -332.836266)
		(width 0.254)
		(layer "In11.Cu")
		(net "VSENSE_VSS_SENSE_B_P1")
	)
	(segment
		(start 23.305262 -352.764598)
		(end 23.305262 -350.505014)
		(width 0.254)
		(layer "In11.Cu")
		(net "VSENSE_VSS_SENSE_B_P1")
	)
	(segment
		(start 23.709884 -345.849194)
		(end 19.408902 -341.548212)
		(width 0.254)
		(layer "In11.Cu")
		(net "VSENSE_VSS_SENSE_B_P1")
	)
	(segment
		(start 19.408902 -341.548212)
		(end 19.408902 -333.572358)
		(width 0.254)
		(layer "In11.Cu")
		(net "VSENSE_VSS_SENSE_B_P1")
	)
	(segment
		(start 26.501852 -358.555544)
		(end 26.501852 -355.961188)
		(width 0.254)
		(layer "In11.Cu")
		(net "VSENSE_VSS_SENSE_B_P1")
	)
	(segment
		(start 28.626308 -360.68)
		(end 26.501852 -358.555544)
		(width 0.254)
		(layer "In11.Cu")
		(net "VSENSE_VSS_SENSE_B_P1")
	)
	(segment
		(start 36.068 -359.283)
		(end 34.671 -360.68)
		(width 0.254)
		(layer "In11.Cu")
		(net "VSENSE_VSS_SENSE_B_P1")
	)
	(segment
		(start 34.671 -360.68)
		(end 28.626308 -360.68)
		(width 0.254)
		(layer "In11.Cu")
		(net "VSENSE_VSS_SENSE_B_P1")
	)
	(segment
		(start 24.022812 -349.787464)
		(end 24.022812 -346.60459)
		(width 0.254)
		(layer "In11.Cu")
		(net "VSENSE_VSS_SENSE_B_P1")
	)
	(segment
		(start 19.408902 -333.572358)
		(end 20.138644 -332.842616)
		(width 0.254)
		(layer "In11.Cu")
		(net "VSENSE_VSS_SENSE_B_P1")
	)
	(segment
		(start 20.764754 -332.836266)
		(end 21.087842 -333.148178)
		(width 0.254)
		(layer "In11.Cu")
		(net "VSENSE_VSS_SENSE_B_P1")
	)
	(segment
		(start 20.138644 -332.842616)
		(end 20.405598 -332.842616)
		(width 0.254)
		(layer "In11.Cu")
		(net "VSENSE_VSS_SENSE_B_P1")
	)
	(segment
		(start 23.305262 -350.505014)
		(end 24.022812 -349.787464)
		(width 0.254)
		(layer "In11.Cu")
		(net "VSENSE_VSS_SENSE_B_P1")
	)
	(segment
		(start 24.022812 -346.60459)
		(end 23.709884 -345.849194)
		(width 0.254)
		(layer "In11.Cu")
		(net "VSENSE_VSS_SENSE_B_P1")
	)
	(segment
		(start 314.25896 -358.521)
		(end 313.500008 -359.279952)
		(width 0.1778)
		(layer "F.Cu")
		(net "VSENSE_VSS_SENSE_B_P0")
	)
	(segment
		(start 266.876022 -333.045562)
		(end 268.013434 -333.045562)
		(width 0.254)
		(layer "F.Cu")
		(net "VSENSE_VSS_SENSE_B_P0")
	)
	(segment
		(start 266.862306 -333.031846)
		(end 266.876022 -333.045562)
		(width 0.254)
		(layer "F.Cu")
		(net "VSENSE_VSS_SENSE_B_P0")
	)
	(segment
		(start 345.447874 -268.150086)
		(end 345.181936 -268.416024)
		(width 0.254)
		(layer "F.Cu")
		(net "VSENSE_VSS_SENSE_B_P0")
	)
	(segment
		(start 314.325 -358.521)
		(end 314.25896 -358.521)
		(width 0.1778)
		(layer "F.Cu")
		(net "VSENSE_VSS_SENSE_B_P0")
	)
	(segment
		(start 316.0522 -356.489)
		(end 315.214 -356.489)
		(width 0.254)
		(layer "F.Cu")
		(net "VSENSE_VSS_SENSE_B_P0")
	)
	(segment
		(start 268.013434 -333.045562)
		(end 268.623034 -333.045562)
		(width 0.254)
		(layer "F.Cu")
		(net "VSENSE_VSS_SENSE_B_P0")
	)
	(segment
		(start 313.500008 -359.279952)
		(end 313.009026 -359.279952)
		(width 0.1778)
		(layer "F.Cu")
		(net "VSENSE_VSS_SENSE_B_P0")
	)
	(segment
		(start 345.181936 -268.416024)
		(end 344.981022 -268.416024)
		(width 0.254)
		(layer "F.Cu")
		(net "VSENSE_VSS_SENSE_B_P0")
	)
	(segment
		(start 315.214 -356.489)
		(end 314.94095 -356.76205)
		(width 0.254)
		(layer "F.Cu")
		(net "VSENSE_VSS_SENSE_B_P0")
	)
	(segment
		(start 314.94095 -357.251)
		(end 314.94095 -357.90505)
		(width 0.254)
		(layer "F.Cu")
		(net "VSENSE_VSS_SENSE_B_P0")
	)
	(segment
		(start 314.94095 -357.90505)
		(end 314.325 -358.521)
		(width 0.254)
		(layer "F.Cu")
		(net "VSENSE_VSS_SENSE_B_P0")
	)
	(segment
		(start 314.94095 -356.76205)
		(end 314.94095 -357.251)
		(width 0.254)
		(layer "F.Cu")
		(net "VSENSE_VSS_SENSE_B_P0")
	)
	(via
		(at 316.0522 -356.489)
		(size 0.508)
		(drill 0.254)
		(layers "F.Cu" "B.Cu")
		(net "VSENSE_VSS_SENSE_B_P0")
	)
	(via
		(at 268.013434 -333.045562)
		(size 0.508)
		(drill 0.254)
		(layers "F.Cu" "B.Cu")
		(net "VSENSE_VSS_SENSE_B_P0")
	)
	(via
		(at 344.981022 -268.416024)
		(size 0.4064)
		(drill 0.2032)
		(layers "F.Cu" "B.Cu")
		(net "VSENSE_VSS_SENSE_B_P0")
	)
	(segment
		(start 302.824388 -368.9604)
		(end 299.420788 -365.5568)
		(width 0.254)
		(layer "In2.Cu")
		(net "VSENSE_VSS_SENSE_B_P0")
	)
	(segment
		(start 263.303258 -348.411546)
		(end 263.303258 -340.644734)
		(width 0.254)
		(layer "In2.Cu")
		(net "VSENSE_VSS_SENSE_B_P0")
	)
	(segment
		(start 267.284454 -332.6892)
		(end 267.657072 -332.6892)
		(width 0.254)
		(layer "In2.Cu")
		(net "VSENSE_VSS_SENSE_B_P0")
	)
	(segment
		(start 266.87018 -351.978468)
		(end 263.303258 -348.411546)
		(width 0.254)
		(layer "In2.Cu")
		(net "VSENSE_VSS_SENSE_B_P0")
	)
	(segment
		(start 263.303258 -340.644734)
		(end 267.0302 -336.917792)
		(width 0.254)
		(layer "In2.Cu")
		(net "VSENSE_VSS_SENSE_B_P0")
	)
	(segment
		(start 270.901668 -351.978468)
		(end 266.87018 -351.978468)
		(width 0.254)
		(layer "In2.Cu")
		(net "VSENSE_VSS_SENSE_B_P0")
	)
	(segment
		(start 299.420788 -365.5568)
		(end 284.48 -365.5568)
		(width 0.254)
		(layer "In2.Cu")
		(net "VSENSE_VSS_SENSE_B_P0")
	)
	(segment
		(start 267.657072 -332.6892)
		(end 268.013434 -333.045562)
		(width 0.254)
		(layer "In2.Cu")
		(net "VSENSE_VSS_SENSE_B_P0")
	)
	(segment
		(start 267.0302 -332.943454)
		(end 267.284454 -332.6892)
		(width 0.254)
		(layer "In2.Cu")
		(net "VSENSE_VSS_SENSE_B_P0")
	)
	(segment
		(start 316.5348 -356.9716)
		(end 316.5348 -365.144812)
		(width 0.254)
		(layer "In2.Cu")
		(net "VSENSE_VSS_SENSE_B_P0")
	)
	(segment
		(start 312.719212 -368.9604)
		(end 302.824388 -368.9604)
		(width 0.254)
		(layer "In2.Cu")
		(net "VSENSE_VSS_SENSE_B_P0")
	)
	(segment
		(start 316.5348 -365.144812)
		(end 312.719212 -368.9604)
		(width 0.254)
		(layer "In2.Cu")
		(net "VSENSE_VSS_SENSE_B_P0")
	)
	(segment
		(start 267.0302 -336.917792)
		(end 267.0302 -332.943454)
		(width 0.254)
		(layer "In2.Cu")
		(net "VSENSE_VSS_SENSE_B_P0")
	)
	(segment
		(start 316.0522 -356.489)
		(end 316.5348 -356.9716)
		(width 0.254)
		(layer "In2.Cu")
		(net "VSENSE_VSS_SENSE_B_P0")
	)
	(segment
		(start 284.48 -365.5568)
		(end 270.901668 -351.978468)
		(width 0.254)
		(layer "In2.Cu")
		(net "VSENSE_VSS_SENSE_B_P0")
	)
	(segment
		(start 339.52815 -286.558482)
		(end 339.561678 -286.538924)
		(width 0.0889)
		(layer "In6.Cu")
		(net "VSENSE_VSS_SENSE_B_P0")
	)
	(segment
		(start 339.5599 -285.931864)
		(end 339.52815 -285.913576)
		(width 0.0889)
		(layer "In6.Cu")
		(net "VSENSE_VSS_SENSE_B_P0")
	)
	(segment
		(start 339.52815 -293.03853)
		(end 339.5599 -293.020242)
		(width 0.0889)
		(layer "In6.Cu")
		(net "VSENSE_VSS_SENSE_B_P0")
	)
	(segment
		(start 339.52815 -280.078688)
		(end 339.5599 -280.0604)
		(width 0.0889)
		(layer "In6.Cu")
		(net "VSENSE_VSS_SENSE_B_P0")
	)
	(segment
		(start 343.945718 -270.846042)
		(end 343.945718 -270.805656)
		(width 0.0889)
		(layer "In6.Cu")
		(net "VSENSE_VSS_SENSE_B_P0")
	)
	(segment
		(start 342.042496 -274.12442)
		(end 342.042496 -274.098512)
		(width 0.0889)
		(layer "In6.Cu")
		(net "VSENSE_VSS_SENSE_B_P0")
	)
	(segment
		(start 343.248996 -272.001488)
		(end 343.288112 -271.978628)
		(width 0.0889)
		(layer "In6.Cu")
		(net "VSENSE_VSS_SENSE_B_P0")
	)
	(segment
		(start 339.52815 -288.178494)
		(end 339.561678 -288.158936)
		(width 0.0889)
		(layer "In6.Cu")
		(net "VSENSE_VSS_SENSE_B_P0")
	)
	(segment
		(start 339.52815 -281.6987)
		(end 339.5599 -281.680412)
		(width 0.0889)
		(layer "In6.Cu")
		(net "VSENSE_VSS_SENSE_B_P0")
	)
	(segment
		(start 340.429088 -276.861524)
		(end 340.468204 -276.838664)
		(width 0.0889)
		(layer "In6.Cu")
		(net "VSENSE_VSS_SENSE_B_P0")
	)
	(segment
		(start 339.5599 -287.551876)
		(end 339.52815 -287.533588)
		(width 0.0889)
		(layer "In6.Cu")
		(net "VSENSE_VSS_SENSE_B_P0")
	)
	(segment
		(start 339.52815 -289.153346)
		(end 339.489034 -289.130486)
		(width 0.0889)
		(layer "In6.Cu")
		(net "VSENSE_VSS_SENSE_B_P0")
	)
	(segment
		(start 344.155776 -270.40459)
		(end 344.228166 -270.358616)
		(width 0.0889)
		(layer "In6.Cu")
		(net "VSENSE_VSS_SENSE_B_P0")
	)
	(segment
		(start 309.823358 -317.923418)
		(end 330.372466 -297.37431)
		(width 0.254)
		(layer "In6.Cu")
		(net "VSENSE_VSS_SENSE_B_P0")
	)
	(segment
		(start 341.369142 -275.241512)
		(end 341.408258 -275.218652)
		(width 0.0889)
		(layer "In6.Cu")
		(net "VSENSE_VSS_SENSE_B_P0")
	)
	(segment
		(start 345.350592 -268.477238)
		(end 345.289378 -268.416024)
		(width 0.0889)
		(layer "In6.Cu")
		(net "VSENSE_VSS_SENSE_B_P0")
	)
	(segment
		(start 274.521422 -320.494152)
		(end 308.64683 -320.494152)
		(width 0.254)
		(layer "In6.Cu")
		(net "VSENSE_VSS_SENSE_B_P0")
	)
	(segment
		(start 337.315556 -297.37431)
		(end 337.672172 -297.017694)
		(width 0.254)
		(layer "In6.Cu")
		(net "VSENSE_VSS_SENSE_B_P0")
	)
	(segment
		(start 339.52815 -282.673552)
		(end 339.489034 -282.650692)
		(width 0.0889)
		(layer "In6.Cu")
		(net "VSENSE_VSS_SENSE_B_P0")
	)
	(segment
		(start 330.372466 -297.37431)
		(end 337.315556 -297.37431)
		(width 0.254)
		(layer "In6.Cu")
		(net "VSENSE_VSS_SENSE_B_P0")
	)
	(segment
		(start 339.52815 -291.418518)
		(end 339.5599 -291.40023)
		(width 0.0889)
		(layer "In6.Cu")
		(net "VSENSE_VSS_SENSE_B_P0")
	)
	(segment
		(start 339.5599 -290.791646)
		(end 339.52815 -290.773358)
		(width 0.0889)
		(layer "In6.Cu")
		(net "VSENSE_VSS_SENSE_B_P0")
	)
	(segment
		(start 339.52815 -281.05354)
		(end 339.491828 -281.032712)
		(width 0.0889)
		(layer "In6.Cu")
		(net "VSENSE_VSS_SENSE_B_P0")
	)
	(segment
		(start 265.5697 -329.445874)
		(end 274.521422 -320.494152)
		(width 0.254)
		(layer "In6.Cu")
		(net "VSENSE_VSS_SENSE_B_P0")
	)
	(segment
		(start 339.525864 -283.314394)
		(end 339.528404 -283.31287)
		(width 0.0889)
		(layer "In6.Cu")
		(net "VSENSE_VSS_SENSE_B_P0")
	)
	(segment
		(start 339.5599 -281.071828)
		(end 339.52815 -281.05354)
		(width 0.0889)
		(layer "In6.Cu")
		(net "VSENSE_VSS_SENSE_B_P0")
	)
	(segment
		(start 342.779096 -272.811494)
		(end 342.818212 -272.788634)
		(width 0.0889)
		(layer "In6.Cu")
		(net "VSENSE_VSS_SENSE_B_P0")
	)
	(segment
		(start 338.588096 -294.658542)
		(end 338.619846 -294.640254)
		(width 0.0889)
		(layer "In6.Cu")
		(net "VSENSE_VSS_SENSE_B_P0")
	)
	(segment
		(start 339.489034 -280.101548)
		(end 339.52815 -280.078688)
		(width 0.0889)
		(layer "In6.Cu")
		(net "VSENSE_VSS_SENSE_B_P0")
	)
	(segment
		(start 266.054078 -332.693772)
		(end 265.5697 -332.209394)
		(width 0.254)
		(layer "In6.Cu")
		(net "VSENSE_VSS_SENSE_B_P0")
	)
	(segment
		(start 309.823358 -319.317624)
		(end 309.823358 -317.923418)
		(width 0.254)
		(layer "In6.Cu")
		(net "VSENSE_VSS_SENSE_B_P0")
	)
	(segment
		(start 339.52815 -289.798506)
		(end 339.5599 -289.780218)
		(width 0.0889)
		(layer "In6.Cu")
		(net "VSENSE_VSS_SENSE_B_P0")
	)
	(segment
		(start 339.52815 -287.533588)
		(end 339.491574 -287.512252)
		(width 0.0889)
		(layer "In6.Cu")
		(net "VSENSE_VSS_SENSE_B_P0")
	)
	(segment
		(start 339.52815 -292.39337)
		(end 339.489034 -292.37051)
		(width 0.0889)
		(layer "In6.Cu")
		(net "VSENSE_VSS_SENSE_B_P0")
	)
	(segment
		(start 265.5697 -332.209394)
		(end 265.5697 -329.445874)
		(width 0.254)
		(layer "In6.Cu")
		(net "VSENSE_VSS_SENSE_B_P0")
	)
	(segment
		(start 339.961728 -277.669752)
		(end 339.99805 -277.64867)
		(width 0.0889)
		(layer "In6.Cu")
		(net "VSENSE_VSS_SENSE_B_P0")
	)
	(segment
		(start 339.52815 -284.938724)
		(end 339.5599 -284.920436)
		(width 0.0889)
		(layer "In6.Cu")
		(net "VSENSE_VSS_SENSE_B_P0")
	)
	(segment
		(start 339.52815 -285.913576)
		(end 339.489034 -285.890716)
		(width 0.0889)
		(layer "In6.Cu")
		(net "VSENSE_VSS_SENSE_B_P0")
	)
	(segment
		(start 344.228166 -270.358616)
		(end 344.259916 -270.340328)
		(width 0.0889)
		(layer "In6.Cu")
		(net "VSENSE_VSS_SENSE_B_P0")
	)
	(segment
		(start 339.019134 -293.871396)
		(end 339.05825 -293.848536)
		(width 0.0889)
		(layer "In6.Cu")
		(net "VSENSE_VSS_SENSE_B_P0")
	)
	(segment
		(start 343.758266 -271.168622)
		(end 343.788746 -271.150842)
		(width 0.0889)
		(layer "In6.Cu")
		(net "VSENSE_VSS_SENSE_B_P0")
	)
	(segment
		(start 337.672172 -297.017694)
		(end 337.672172 -296.71264)
		(width 0.254)
		(layer "In6.Cu")
		(net "VSENSE_VSS_SENSE_B_P0")
	)
	(segment
		(start 339.5599 -284.311852)
		(end 339.52815 -284.293564)
		(width 0.0889)
		(layer "In6.Cu")
		(net "VSENSE_VSS_SENSE_B_P0")
	)
	(segment
		(start 340.938104 -276.028658)
		(end 340.969854 -276.01037)
		(width 0.0889)
		(layer "In6.Cu")
		(net "VSENSE_VSS_SENSE_B_P0")
	)
	(segment
		(start 344.698066 -269.54861)
		(end 344.729816 -269.530322)
		(width 0.0889)
		(layer "In6.Cu")
		(net "VSENSE_VSS_SENSE_B_P0")
	)
	(segment
		(start 339.5599 -282.69184)
		(end 339.52815 -282.673552)
		(width 0.0889)
		(layer "In6.Cu")
		(net "VSENSE_VSS_SENSE_B_P0")
	)
	(segment
		(start 345.16822 -268.738604)
		(end 345.1987 -268.720824)
		(width 0.0889)
		(layer "In6.Cu")
		(net "VSENSE_VSS_SENSE_B_P0")
	)
	(segment
		(start 345.289378 -268.416024)
		(end 344.981022 -268.416024)
		(width 0.0889)
		(layer "In6.Cu")
		(net "VSENSE_VSS_SENSE_B_P0")
	)
	(segment
		(start 344.661744 -269.569692)
		(end 344.698066 -269.54861)
		(width 0.0889)
		(layer "In6.Cu")
		(net "VSENSE_VSS_SENSE_B_P0")
	)
	(segment
		(start 342.818212 -272.788634)
		(end 342.848692 -272.770854)
		(width 0.0889)
		(layer "In6.Cu")
		(net "VSENSE_VSS_SENSE_B_P0")
	)
	(segment
		(start 339.52815 -290.773358)
		(end 339.489034 -290.750498)
		(width 0.0889)
		(layer "In6.Cu")
		(net "VSENSE_VSS_SENSE_B_P0")
	)
	(segment
		(start 341.408258 -275.218652)
		(end 341.438738 -275.200872)
		(width 0.0889)
		(layer "In6.Cu")
		(net "VSENSE_VSS_SENSE_B_P0")
	)
	(segment
		(start 339.489034 -288.201354)
		(end 339.52815 -288.178494)
		(width 0.0889)
		(layer "In6.Cu")
		(net "VSENSE_VSS_SENSE_B_P0")
	)
	(segment
		(start 339.489034 -289.821366)
		(end 339.52815 -289.798506)
		(width 0.0889)
		(layer "In6.Cu")
		(net "VSENSE_VSS_SENSE_B_P0")
	)
	(segment
		(start 339.489034 -291.441378)
		(end 339.52815 -291.418518)
		(width 0.0889)
		(layer "In6.Cu")
		(net "VSENSE_VSS_SENSE_B_P0")
	)
	(segment
		(start 339.489034 -281.72156)
		(end 339.52815 -281.6987)
		(width 0.0889)
		(layer "In6.Cu")
		(net "VSENSE_VSS_SENSE_B_P0")
	)
	(segment
		(start 337.672172 -296.71264)
		(end 337.835748 -296.549064)
		(width 0.0889)
		(layer "In6.Cu")
		(net "VSENSE_VSS_SENSE_B_P0")
	)
	(segment
		(start 339.5599 -279.451816)
		(end 339.52815 -279.433528)
		(width 0.0889)
		(layer "In6.Cu")
		(net "VSENSE_VSS_SENSE_B_P0")
	)
	(segment
		(start 339.5599 -289.171634)
		(end 339.52815 -289.153346)
		(width 0.0889)
		(layer "In6.Cu")
		(net "VSENSE_VSS_SENSE_B_P0")
	)
	(segment
		(start 339.489034 -293.06139)
		(end 339.52815 -293.03853)
		(width 0.0889)
		(layer "In6.Cu")
		(net "VSENSE_VSS_SENSE_B_P0")
	)
	(segment
		(start 339.491828 -281.032712)
		(end 339.489034 -281.03068)
		(width 0.0889)
		(layer "In6.Cu")
		(net "VSENSE_VSS_SENSE_B_P0")
	)
	(segment
		(start 341.839042 -274.431506)
		(end 341.878158 -274.408646)
		(width 0.0889)
		(layer "In6.Cu")
		(net "VSENSE_VSS_SENSE_B_P0")
	)
	(segment
		(start 338.54898 -294.681402)
		(end 338.588096 -294.658542)
		(width 0.0889)
		(layer "In6.Cu")
		(net "VSENSE_VSS_SENSE_B_P0")
	)
	(segment
		(start 343.288112 -271.978628)
		(end 343.319862 -271.96034)
		(width 0.0889)
		(layer "In6.Cu")
		(net "VSENSE_VSS_SENSE_B_P0")
	)
	(segment
		(start 308.64683 -320.494152)
		(end 309.823358 -319.317624)
		(width 0.254)
		(layer "In6.Cu")
		(net "VSENSE_VSS_SENSE_B_P0")
	)
	(segment
		(start 268.013434 -333.045562)
		(end 267.661644 -332.693772)
		(width 0.254)
		(layer "In6.Cu")
		(net "VSENSE_VSS_SENSE_B_P0")
	)
	(segment
		(start 339.05825 -293.848536)
		(end 339.08873 -293.830756)
		(width 0.0889)
		(layer "In6.Cu")
		(net "VSENSE_VSS_SENSE_B_P0")
	)
	(segment
		(start 342.321388 -273.614134)
		(end 342.379808 -273.580352)
		(width 0.0889)
		(layer "In6.Cu")
		(net "VSENSE_VSS_SENSE_B_P0")
	)
	(segment
		(start 339.489034 -278.481536)
		(end 339.52815 -278.458676)
		(width 0.0889)
		(layer "In6.Cu")
		(net "VSENSE_VSS_SENSE_B_P0")
	)
	(segment
		(start 267.661644 -332.693772)
		(end 266.054078 -332.693772)
		(width 0.254)
		(layer "In6.Cu")
		(net "VSENSE_VSS_SENSE_B_P0")
	)
	(segment
		(start 339.52815 -278.458676)
		(end 339.5599 -278.440388)
		(width 0.0889)
		(layer "In6.Cu")
		(net "VSENSE_VSS_SENSE_B_P0")
	)
	(segment
		(start 339.5599 -292.411658)
		(end 339.52815 -292.39337)
		(width 0.0889)
		(layer "In6.Cu")
		(net "VSENSE_VSS_SENSE_B_P0")
	)
	(segment
		(start 338.121752 -295.457626)
		(end 338.186522 -295.41978)
		(width 0.0889)
		(layer "In6.Cu")
		(net "VSENSE_VSS_SENSE_B_P0")
	)
	(segment
		(start 339.489034 -286.581342)
		(end 339.52815 -286.558482)
		(width 0.0889)
		(layer "In6.Cu")
		(net "VSENSE_VSS_SENSE_B_P0")
	)
	(segment
		(start 339.489034 -284.961584)
		(end 339.52815 -284.938724)
		(width 0.0889)
		(layer "In6.Cu")
		(net "VSENSE_VSS_SENSE_B_P0")
	)
	(segment
		(start 337.835748 -296.549064)
		(end 337.835748 -295.955974)
		(width 0.0889)
		(layer "In6.Cu")
		(net "VSENSE_VSS_SENSE_B_P0")
	)
	(segment
		(start 340.898988 -276.051518)
		(end 340.938104 -276.028658)
		(width 0.0889)
		(layer "In6.Cu")
		(net "VSENSE_VSS_SENSE_B_P0")
	)
	(segment
		(start 339.52815 -284.293564)
		(end 339.489034 -284.270704)
		(width 0.0889)
		(layer "In6.Cu")
		(net "VSENSE_VSS_SENSE_B_P0")
	)
	(segment
		(start 343.71915 -271.191482)
		(end 343.758266 -271.168622)
		(width 0.0889)
		(layer "In6.Cu")
		(net "VSENSE_VSS_SENSE_B_P0")
	)
	(segment
		(start 339.52815 -279.433528)
		(end 339.489034 -279.410668)
		(width 0.0889)
		(layer "In6.Cu")
		(net "VSENSE_VSS_SENSE_B_P0")
	)
	(segment
		(start 345.129104 -268.761464)
		(end 345.16822 -268.738604)
		(width 0.0889)
		(layer "In6.Cu")
		(net "VSENSE_VSS_SENSE_B_P0")
	)
	(segment
		(start 340.468204 -276.838664)
		(end 340.498684 -276.820884)
		(width 0.0889)
		(layer "In6.Cu")
		(net "VSENSE_VSS_SENSE_B_P0")
	)
	(segment
		(start 339.99805 -277.64867)
		(end 340.0298 -277.630382)
		(width 0.0889)
		(layer "In6.Cu")
		(net "VSENSE_VSS_SENSE_B_P0")
	)
	(arc
		(start 340.185756 -277.32609)
		(mid 340.250271 -277.063871)
		(end 340.429088 -276.861524)
		(width 0.0889)
		(layer "In6.Cu")
		(net "VSENSE_VSS_SENSE_B_P0")
	)
	(arc
		(start 339.489034 -279.410668)
		(mid 339.245707 -278.946102)
		(end 339.489034 -278.481536)
		(width 0.0889)
		(layer "In6.Cu")
		(net "VSENSE_VSS_SENSE_B_P0")
	)
	(arc
		(start 344.729816 -269.530322)
		(mid 344.844492 -269.396988)
		(end 344.885772 -269.22603)
		(width 0.0889)
		(layer "In6.Cu")
		(net "VSENSE_VSS_SENSE_B_P0")
	)
	(arc
		(start 339.489034 -289.130486)
		(mid 339.245707 -288.66592)
		(end 339.489034 -288.201354)
		(width 0.0889)
		(layer "In6.Cu")
		(net "VSENSE_VSS_SENSE_B_P0")
	)
	(arc
		(start 339.489034 -285.890716)
		(mid 339.245707 -285.42615)
		(end 339.489034 -284.961584)
		(width 0.0889)
		(layer "In6.Cu")
		(net "VSENSE_VSS_SENSE_B_P0")
	)
	(arc
		(start 341.438738 -275.200872)
		(mid 341.554165 -275.067496)
		(end 341.59571 -274.896072)
		(width 0.0889)
		(layer "In6.Cu")
		(net "VSENSE_VSS_SENSE_B_P0")
	)
	(arc
		(start 340.655656 -276.516084)
		(mid 340.720171 -276.253865)
		(end 340.898988 -276.051518)
		(width 0.0889)
		(layer "In6.Cu")
		(net "VSENSE_VSS_SENSE_B_P0")
	)
	(arc
		(start 339.489034 -290.750498)
		(mid 339.245707 -290.285932)
		(end 339.489034 -289.821366)
		(width 0.0889)
		(layer "In6.Cu")
		(net "VSENSE_VSS_SENSE_B_P0")
	)
	(arc
		(start 342.379808 -273.580352)
		(mid 342.494484 -273.447018)
		(end 342.535764 -273.27606)
		(width 0.0889)
		(layer "In6.Cu")
		(net "VSENSE_VSS_SENSE_B_P0")
	)
	(arc
		(start 341.59571 -274.896072)
		(mid 341.660225 -274.633853)
		(end 341.839042 -274.431506)
		(width 0.0889)
		(layer "In6.Cu")
		(net "VSENSE_VSS_SENSE_B_P0")
	)
	(arc
		(start 339.5599 -293.020242)
		(mid 339.715828 -292.71595)
		(end 339.5599 -292.411658)
		(width 0.0889)
		(layer "In6.Cu")
		(net "VSENSE_VSS_SENSE_B_P0")
	)
	(arc
		(start 343.788746 -271.150842)
		(mid 343.904173 -271.017466)
		(end 343.945718 -270.846042)
		(width 0.0889)
		(layer "In6.Cu")
		(net "VSENSE_VSS_SENSE_B_P0")
	)
	(arc
		(start 338.775802 -294.335962)
		(mid 338.840317 -294.073743)
		(end 339.019134 -293.871396)
		(width 0.0889)
		(layer "In6.Cu")
		(net "VSENSE_VSS_SENSE_B_P0")
	)
	(arc
		(start 343.319862 -271.96034)
		(mid 343.434538 -271.827006)
		(end 343.475818 -271.656048)
		(width 0.0889)
		(layer "In6.Cu")
		(net "VSENSE_VSS_SENSE_B_P0")
	)
	(arc
		(start 339.489034 -282.650692)
		(mid 339.245707 -282.186126)
		(end 339.489034 -281.72156)
		(width 0.0889)
		(layer "In6.Cu")
		(net "VSENSE_VSS_SENSE_B_P0")
	)
	(arc
		(start 339.715856 -278.136096)
		(mid 339.781092 -277.872505)
		(end 339.961728 -277.669752)
		(width 0.0889)
		(layer "In6.Cu")
		(net "VSENSE_VSS_SENSE_B_P0")
	)
	(arc
		(start 344.885772 -269.22603)
		(mid 344.950287 -268.963811)
		(end 345.129104 -268.761464)
		(width 0.0889)
		(layer "In6.Cu")
		(net "VSENSE_VSS_SENSE_B_P0")
	)
	(arc
		(start 340.0298 -277.630382)
		(mid 340.144476 -277.497048)
		(end 340.185756 -277.32609)
		(width 0.0889)
		(layer "In6.Cu")
		(net "VSENSE_VSS_SENSE_B_P0")
	)
	(arc
		(start 339.245702 -293.525956)
		(mid 339.310217 -293.263737)
		(end 339.489034 -293.06139)
		(width 0.0889)
		(layer "In6.Cu")
		(net "VSENSE_VSS_SENSE_B_P0")
	)
	(arc
		(start 339.5599 -289.780218)
		(mid 339.715828 -289.475926)
		(end 339.5599 -289.171634)
		(width 0.0889)
		(layer "In6.Cu")
		(net "VSENSE_VSS_SENSE_B_P0")
	)
	(arc
		(start 341.878158 -274.408646)
		(mid 341.998469 -274.288583)
		(end 342.042496 -274.12442)
		(width 0.0889)
		(layer "In6.Cu")
		(net "VSENSE_VSS_SENSE_B_P0")
	)
	(arc
		(start 339.491574 -287.512252)
		(mid 339.310922 -287.309507)
		(end 339.245702 -287.045908)
		(width 0.0889)
		(layer "In6.Cu")
		(net "VSENSE_VSS_SENSE_B_P0")
	)
	(arc
		(start 343.945718 -270.805656)
		(mid 344.001409 -270.579281)
		(end 344.155776 -270.40459)
		(width 0.0889)
		(layer "In6.Cu")
		(net "VSENSE_VSS_SENSE_B_P0")
	)
	(arc
		(start 339.489034 -281.03068)
		(mid 339.245707 -280.566114)
		(end 339.489034 -280.101548)
		(width 0.0889)
		(layer "In6.Cu")
		(net "VSENSE_VSS_SENSE_B_P0")
	)
	(arc
		(start 338.186522 -295.41978)
		(mid 338.2746 -295.295276)
		(end 338.305648 -295.145968)
		(width 0.0889)
		(layer "In6.Cu")
		(net "VSENSE_VSS_SENSE_B_P0")
	)
	(arc
		(start 338.305648 -295.145968)
		(mid 338.370163 -294.883749)
		(end 338.54898 -294.681402)
		(width 0.0889)
		(layer "In6.Cu")
		(net "VSENSE_VSS_SENSE_B_P0")
	)
	(arc
		(start 339.245702 -287.045908)
		(mid 339.310217 -286.783689)
		(end 339.489034 -286.581342)
		(width 0.0889)
		(layer "In6.Cu")
		(net "VSENSE_VSS_SENSE_B_P0")
	)
	(arc
		(start 339.5599 -284.920436)
		(mid 339.715828 -284.616144)
		(end 339.5599 -284.311852)
		(width 0.0889)
		(layer "In6.Cu")
		(net "VSENSE_VSS_SENSE_B_P0")
	)
	(arc
		(start 345.1987 -268.720824)
		(mid 345.298879 -268.614149)
		(end 345.350592 -268.477238)
		(width 0.0889)
		(layer "In6.Cu")
		(net "VSENSE_VSS_SENSE_B_P0")
	)
	(arc
		(start 344.259916 -270.340328)
		(mid 344.374592 -270.206994)
		(end 344.415872 -270.036036)
		(width 0.0889)
		(layer "In6.Cu")
		(net "VSENSE_VSS_SENSE_B_P0")
	)
	(arc
		(start 339.561678 -286.538924)
		(mid 339.675085 -286.406035)
		(end 339.715856 -286.236156)
		(width 0.0889)
		(layer "In6.Cu")
		(net "VSENSE_VSS_SENSE_B_P0")
	)
	(arc
		(start 343.005664 -272.466054)
		(mid 343.070179 -272.203835)
		(end 343.248996 -272.001488)
		(width 0.0889)
		(layer "In6.Cu")
		(net "VSENSE_VSS_SENSE_B_P0")
	)
	(arc
		(start 339.5599 -281.680412)
		(mid 339.715828 -281.37612)
		(end 339.5599 -281.071828)
		(width 0.0889)
		(layer "In6.Cu")
		(net "VSENSE_VSS_SENSE_B_P0")
	)
	(arc
		(start 339.489034 -292.37051)
		(mid 339.245707 -291.905944)
		(end 339.489034 -291.441378)
		(width 0.0889)
		(layer "In6.Cu")
		(net "VSENSE_VSS_SENSE_B_P0")
	)
	(arc
		(start 340.498684 -276.820884)
		(mid 340.614111 -276.687508)
		(end 340.655656 -276.516084)
		(width 0.0889)
		(layer "In6.Cu")
		(net "VSENSE_VSS_SENSE_B_P0")
	)
	(arc
		(start 338.619846 -294.640254)
		(mid 338.734522 -294.50692)
		(end 338.775802 -294.335962)
		(width 0.0889)
		(layer "In6.Cu")
		(net "VSENSE_VSS_SENSE_B_P0")
	)
	(arc
		(start 337.835748 -295.955974)
		(mid 337.912337 -295.668692)
		(end 338.121752 -295.457626)
		(width 0.0889)
		(layer "In6.Cu")
		(net "VSENSE_VSS_SENSE_B_P0")
	)
	(arc
		(start 339.561678 -288.158936)
		(mid 339.675085 -288.026047)
		(end 339.715856 -287.856168)
		(width 0.0889)
		(layer "In6.Cu")
		(net "VSENSE_VSS_SENSE_B_P0")
	)
	(arc
		(start 339.5599 -291.40023)
		(mid 339.715828 -291.095938)
		(end 339.5599 -290.791646)
		(width 0.0889)
		(layer "In6.Cu")
		(net "VSENSE_VSS_SENSE_B_P0")
	)
	(arc
		(start 342.848692 -272.770854)
		(mid 342.964119 -272.637478)
		(end 343.005664 -272.466054)
		(width 0.0889)
		(layer "In6.Cu")
		(net "VSENSE_VSS_SENSE_B_P0")
	)
	(arc
		(start 339.715856 -286.236156)
		(mid 339.674601 -286.065185)
		(end 339.5599 -285.931864)
		(width 0.0889)
		(layer "In6.Cu")
		(net "VSENSE_VSS_SENSE_B_P0")
	)
	(arc
		(start 339.715856 -287.856168)
		(mid 339.674601 -287.685197)
		(end 339.5599 -287.551876)
		(width 0.0889)
		(layer "In6.Cu")
		(net "VSENSE_VSS_SENSE_B_P0")
	)
	(arc
		(start 339.08873 -293.830756)
		(mid 339.204157 -293.69738)
		(end 339.245702 -293.525956)
		(width 0.0889)
		(layer "In6.Cu")
		(net "VSENSE_VSS_SENSE_B_P0")
	)
	(arc
		(start 342.535764 -273.27606)
		(mid 342.600279 -273.013841)
		(end 342.779096 -272.811494)
		(width 0.0889)
		(layer "In6.Cu")
		(net "VSENSE_VSS_SENSE_B_P0")
	)
	(arc
		(start 339.5599 -280.0604)
		(mid 339.715828 -279.756108)
		(end 339.5599 -279.451816)
		(width 0.0889)
		(layer "In6.Cu")
		(net "VSENSE_VSS_SENSE_B_P0")
	)
	(arc
		(start 343.475818 -271.656048)
		(mid 343.540333 -271.393829)
		(end 343.71915 -271.191482)
		(width 0.0889)
		(layer "In6.Cu")
		(net "VSENSE_VSS_SENSE_B_P0")
	)
	(arc
		(start 341.12581 -275.706078)
		(mid 341.190325 -275.443859)
		(end 341.369142 -275.241512)
		(width 0.0889)
		(layer "In6.Cu")
		(net "VSENSE_VSS_SENSE_B_P0")
	)
	(arc
		(start 339.489034 -284.270704)
		(mid 339.245215 -283.782485)
		(end 339.525864 -283.314394)
		(width 0.0889)
		(layer "In6.Cu")
		(net "VSENSE_VSS_SENSE_B_P0")
	)
	(arc
		(start 342.042496 -274.098512)
		(mid 342.117202 -273.819048)
		(end 342.321388 -273.614134)
		(width 0.0889)
		(layer "In6.Cu")
		(net "VSENSE_VSS_SENSE_B_P0")
	)
	(arc
		(start 339.528404 -283.31287)
		(mid 339.713419 -283.010883)
		(end 339.5599 -282.69184)
		(width 0.0889)
		(layer "In6.Cu")
		(net "VSENSE_VSS_SENSE_B_P0")
	)
	(arc
		(start 339.5599 -278.440388)
		(mid 339.674576 -278.307054)
		(end 339.715856 -278.136096)
		(width 0.0889)
		(layer "In6.Cu")
		(net "VSENSE_VSS_SENSE_B_P0")
	)
	(arc
		(start 340.969854 -276.01037)
		(mid 341.08453 -275.877036)
		(end 341.12581 -275.706078)
		(width 0.0889)
		(layer "In6.Cu")
		(net "VSENSE_VSS_SENSE_B_P0")
	)
	(arc
		(start 344.415872 -270.036036)
		(mid 344.481108 -269.772445)
		(end 344.661744 -269.569692)
		(width 0.0889)
		(layer "In6.Cu")
		(net "VSENSE_VSS_SENSE_B_P0")
	)
	(segment
		(start 55.805324 -183.58739)
		(end 56.369966 -184.152032)
		(width 0.254)
		(layer "F.Cu")
		(net "VSENSE_VSS_SENSE_A_P1")
	)
	(segment
		(start 56.935878 -181.08041)
		(end 56.745378 -181.27091)
		(width 0.254)
		(layer "F.Cu")
		(net "VSENSE_VSS_SENSE_A_P1")
	)
	(segment
		(start 139.229084 -167.510206)
		(end 139.485878 -167.253412)
		(width 0.254)
		(layer "F.Cu")
		(net "VSENSE_VSS_SENSE_A_P1")
	)
	(segment
		(start 132.334508 -217.273378)
		(end 132.725668 -217.273378)
		(width 0.254)
		(layer "F.Cu")
		(net "VSENSE_VSS_SENSE_A_P1")
	)
	(segment
		(start 143.769842 -196.176646)
		(end 131.948936 -207.997552)
		(width 0.254)
		(layer "F.Cu")
		(net "VSENSE_VSS_SENSE_A_P1")
	)
	(segment
		(start 144.207992 -223.690434)
		(end 144.408906 -223.690434)
		(width 0.254)
		(layer "F.Cu")
		(net "VSENSE_VSS_SENSE_A_P1")
	)
	(segment
		(start 56.745378 -181.27091)
		(end 56.355996 -181.27091)
		(width 0.254)
		(layer "F.Cu")
		(net "VSENSE_VSS_SENSE_A_P1")
	)
	(segment
		(start 133.642354 -215.838278)
		(end 133.724396 -215.756236)
		(width 0.254)
		(layer "F.Cu")
		(net "VSENSE_VSS_SENSE_A_P1")
	)
	(segment
		(start 56.369966 -184.152032)
		(end 57.96407 -184.152032)
		(width 0.254)
		(layer "F.Cu")
		(net "VSENSE_VSS_SENSE_A_P1")
	)
	(segment
		(start 131.948936 -214.426292)
		(end 133.360922 -215.838278)
		(width 0.254)
		(layer "F.Cu")
		(net "VSENSE_VSS_SENSE_A_P1")
	)
	(segment
		(start 143.769842 -168.33723)
		(end 143.769842 -196.176646)
		(width 0.254)
		(layer "F.Cu")
		(net "VSENSE_VSS_SENSE_A_P1")
	)
	(segment
		(start 141.6304 -167.464232)
		(end 142.896844 -167.464232)
		(width 0.254)
		(layer "F.Cu")
		(net "VSENSE_VSS_SENSE_A_P1")
	)
	(segment
		(start 132.725668 -217.273378)
		(end 132.860796 -217.408506)
		(width 0.254)
		(layer "F.Cu")
		(net "VSENSE_VSS_SENSE_A_P1")
	)
	(segment
		(start 55.805324 -181.821582)
		(end 55.805324 -183.58739)
		(width 0.254)
		(layer "F.Cu")
		(net "VSENSE_VSS_SENSE_A_P1")
	)
	(segment
		(start 133.360922 -215.838278)
		(end 133.642354 -215.838278)
		(width 0.254)
		(layer "F.Cu")
		(net "VSENSE_VSS_SENSE_A_P1")
	)
	(segment
		(start 56.355996 -181.27091)
		(end 55.805324 -181.821582)
		(width 0.254)
		(layer "F.Cu")
		(net "VSENSE_VSS_SENSE_A_P1")
	)
	(segment
		(start 144.408906 -223.690434)
		(end 144.674844 -223.424496)
		(width 0.254)
		(layer "F.Cu")
		(net "VSENSE_VSS_SENSE_A_P1")
	)
	(segment
		(start 141.197838 -167.03167)
		(end 141.6304 -167.464232)
		(width 0.254)
		(layer "F.Cu")
		(net "VSENSE_VSS_SENSE_A_P1")
	)
	(segment
		(start 139.485878 -167.253412)
		(end 139.689078 -167.253412)
		(width 0.254)
		(layer "F.Cu")
		(net "VSENSE_VSS_SENSE_A_P1")
	)
	(segment
		(start 117.959124 -202.897994)
		(end 132.334508 -217.273378)
		(width 0.254)
		(layer "F.Cu")
		(net "VSENSE_VSS_SENSE_A_P1")
	)
	(segment
		(start 58.775092 -181.08041)
		(end 56.935878 -181.08041)
		(width 0.254)
		(layer "F.Cu")
		(net "VSENSE_VSS_SENSE_A_P1")
	)
	(segment
		(start 131.948936 -207.997552)
		(end 131.948936 -214.426292)
		(width 0.254)
		(layer "F.Cu")
		(net "VSENSE_VSS_SENSE_A_P1")
	)
	(segment
		(start 139.689078 -167.253412)
		(end 139.877038 -167.441372)
		(width 0.254)
		(layer "F.Cu")
		(net "VSENSE_VSS_SENSE_A_P1")
	)
	(segment
		(start 59.108594 -180.746908)
		(end 58.775092 -181.08041)
		(width 0.254)
		(layer "F.Cu")
		(net "VSENSE_VSS_SENSE_A_P1")
	)
	(segment
		(start 57.96407 -184.152032)
		(end 76.710032 -202.897994)
		(width 0.254)
		(layer "F.Cu")
		(net "VSENSE_VSS_SENSE_A_P1")
	)
	(segment
		(start 140.788136 -167.441372)
		(end 141.197838 -167.03167)
		(width 0.254)
		(layer "F.Cu")
		(net "VSENSE_VSS_SENSE_A_P1")
	)
	(segment
		(start 76.710032 -202.897994)
		(end 117.959124 -202.897994)
		(width 0.254)
		(layer "F.Cu")
		(net "VSENSE_VSS_SENSE_A_P1")
	)
	(segment
		(start 142.896844 -167.464232)
		(end 143.769842 -168.33723)
		(width 0.254)
		(layer "F.Cu")
		(net "VSENSE_VSS_SENSE_A_P1")
	)
	(segment
		(start 139.017248 -167.510206)
		(end 139.229084 -167.510206)
		(width 0.254)
		(layer "F.Cu")
		(net "VSENSE_VSS_SENSE_A_P1")
	)
	(segment
		(start 139.877038 -167.441372)
		(end 140.788136 -167.441372)
		(width 0.254)
		(layer "F.Cu")
		(net "VSENSE_VSS_SENSE_A_P1")
	)
	(via
		(at 56.935878 -181.08041)
		(size 0.508)
		(drill 0.254)
		(layers "F.Cu" "B.Cu")
		(net "VSENSE_VSS_SENSE_A_P1")
	)
	(via
		(at 103.515922 -147.44446)
		(size 0.508)
		(drill 0.254)
		(layers "F.Cu" "B.Cu")
		(net "VSENSE_VSS_SENSE_A_P1")
	)
	(via
		(at 133.724396 -215.756236)
		(size 0.508)
		(drill 0.254)
		(layers "F.Cu" "B.Cu")
		(net "VSENSE_VSS_SENSE_A_P1")
	)
	(via
		(at 144.674844 -223.424496)
		(size 0.4064)
		(drill 0.2032)
		(layers "F.Cu" "B.Cu")
		(net "VSENSE_VSS_SENSE_A_P1")
	)
	(via
		(at 139.689078 -167.253412)
		(size 0.508)
		(drill 0.254)
		(layers "F.Cu" "B.Cu")
		(net "VSENSE_VSS_SENSE_A_P1")
	)
	(via
		(at 132.860796 -217.408506)
		(size 0.508)
		(drill 0.254)
		(layers "F.Cu" "B.Cu")
		(net "VSENSE_VSS_SENSE_A_P1")
	)
	(via
		(at 92.750132 -150.76932)
		(size 0.508)
		(drill 0.254)
		(layers "F.Cu" "B.Cu")
		(net "VSENSE_VSS_SENSE_A_P1")
	)
	(segment
		(start 98.545904 -146.158458)
		(end 99.229926 -146.158458)
		(width 0.1778)
		(layer "B.Cu")
		(net "VSENSE_VSS_SENSE_A_P1")
	)
	(segment
		(start 144.264634 -222.721932)
		(end 143.840454 -222.297752)
		(width 0.1016)
		(layer "B.Cu")
		(net "VSENSE_VSS_SENSE_A_P1")
	)
	(segment
		(start 143.314674 -220.265752)
		(end 135.046466 -220.265752)
		(width 0.254)
		(layer "B.Cu")
		(net "VSENSE_VSS_SENSE_A_P1")
	)
	(segment
		(start 145.692114 -221.530672)
		(end 145.692114 -222.86722)
		(width 0.1016)
		(layer "B.Cu")
		(net "VSENSE_VSS_SENSE_A_P1")
	)
	(segment
		(start 93.1418 -149.589998)
		(end 93.1418 -148.821648)
		(width 0.1778)
		(layer "B.Cu")
		(net "VSENSE_VSS_SENSE_A_P1")
	)
	(segment
		(start 133.675628 -218.894914)
		(end 133.675628 -217.80119)
		(width 0.254)
		(layer "B.Cu")
		(net "VSENSE_VSS_SENSE_A_P1")
	)
	(segment
		(start 145.76425 -221.420436)
		(end 145.76425 -221.458536)
		(width 0.1016)
		(layer "B.Cu")
		(net "VSENSE_VSS_SENSE_A_P1")
	)
	(segment
		(start 144.489932 -218.631262)
		(end 145.76425 -219.90558)
		(width 0.254)
		(layer "B.Cu")
		(net "VSENSE_VSS_SENSE_A_P1")
	)
	(segment
		(start 133.80593 -215.83777)
		(end 134.439406 -215.83777)
		(width 0.254)
		(layer "B.Cu")
		(net "VSENSE_VSS_SENSE_A_P1")
	)
	(segment
		(start 133.675628 -217.80119)
		(end 133.166358 -217.29192)
		(width 0.254)
		(layer "B.Cu")
		(net "VSENSE_VSS_SENSE_A_P1")
	)
	(segment
		(start 143.757904 -221.212664)
		(end 143.757904 -221.174564)
		(width 0.1016)
		(layer "B.Cu")
		(net "VSENSE_VSS_SENSE_A_P1")
	)
	(segment
		(start 143.840454 -222.297752)
		(end 143.840454 -221.295214)
		(width 0.1016)
		(layer "B.Cu")
		(net "VSENSE_VSS_SENSE_A_P1")
	)
	(segment
		(start 146.020536 -223.195642)
		(end 146.020536 -223.576896)
		(width 0.1016)
		(layer "B.Cu")
		(net "VSENSE_VSS_SENSE_A_P1")
	)
	(segment
		(start 145.76425 -219.90558)
		(end 145.76425 -221.420436)
		(width 0.254)
		(layer "B.Cu")
		(net "VSENSE_VSS_SENSE_A_P1")
	)
	(segment
		(start 132.977382 -217.29192)
		(end 132.860796 -217.408506)
		(width 0.254)
		(layer "B.Cu")
		(net "VSENSE_VSS_SENSE_A_P1")
	)
	(segment
		(start 100.515928 -147.44446)
		(end 101.004878 -147.44446)
		(width 0.254)
		(layer "B.Cu")
		(net "VSENSE_VSS_SENSE_A_P1")
	)
	(segment
		(start 145.775172 -223.82226)
		(end 145.072608 -223.82226)
		(width 0.1016)
		(layer "B.Cu")
		(net "VSENSE_VSS_SENSE_A_P1")
	)
	(segment
		(start 136.238234 -218.631262)
		(end 144.489932 -218.631262)
		(width 0.254)
		(layer "B.Cu")
		(net "VSENSE_VSS_SENSE_A_P1")
	)
	(segment
		(start 93.87078 -148.092668)
		(end 93.87078 -147.633436)
		(width 0.1778)
		(layer "B.Cu")
		(net "VSENSE_VSS_SENSE_A_P1")
	)
	(segment
		(start 143.840454 -221.295214)
		(end 143.757904 -221.212664)
		(width 0.1016)
		(layer "B.Cu")
		(net "VSENSE_VSS_SENSE_A_P1")
	)
	(segment
		(start 101.004878 -147.44446)
		(end 103.515922 -147.44446)
		(width 0.254)
		(layer "B.Cu")
		(net "VSENSE_VSS_SENSE_A_P1")
	)
	(segment
		(start 92.750132 -149.981666)
		(end 93.1418 -149.589998)
		(width 0.1778)
		(layer "B.Cu")
		(net "VSENSE_VSS_SENSE_A_P1")
	)
	(segment
		(start 144.674844 -223.132142)
		(end 144.264634 -222.721932)
		(width 0.0762)
		(layer "B.Cu")
		(net "VSENSE_VSS_SENSE_A_P1")
	)
	(segment
		(start 134.439406 -215.83777)
		(end 135.742426 -217.14079)
		(width 0.254)
		(layer "B.Cu")
		(net "VSENSE_VSS_SENSE_A_P1")
	)
	(segment
		(start 145.072608 -223.82226)
		(end 144.674844 -223.424496)
		(width 0.1016)
		(layer "B.Cu")
		(net "VSENSE_VSS_SENSE_A_P1")
	)
	(segment
		(start 135.046466 -220.265752)
		(end 133.675628 -218.894914)
		(width 0.254)
		(layer "B.Cu")
		(net "VSENSE_VSS_SENSE_A_P1")
	)
	(segment
		(start 145.692114 -222.86722)
		(end 146.020536 -223.195642)
		(width 0.1016)
		(layer "B.Cu")
		(net "VSENSE_VSS_SENSE_A_P1")
	)
	(segment
		(start 133.166358 -217.29192)
		(end 132.977382 -217.29192)
		(width 0.254)
		(layer "B.Cu")
		(net "VSENSE_VSS_SENSE_A_P1")
	)
	(segment
		(start 146.020536 -223.576896)
		(end 145.775172 -223.82226)
		(width 0.1016)
		(layer "B.Cu")
		(net "VSENSE_VSS_SENSE_A_P1")
	)
	(segment
		(start 99.229926 -146.158458)
		(end 100.515928 -147.44446)
		(width 0.254)
		(layer "B.Cu")
		(net "VSENSE_VSS_SENSE_A_P1")
	)
	(segment
		(start 145.76425 -221.458536)
		(end 145.692114 -221.530672)
		(width 0.1016)
		(layer "B.Cu")
		(net "VSENSE_VSS_SENSE_A_P1")
	)
	(segment
		(start 92.750132 -150.76932)
		(end 92.750132 -149.981666)
		(width 0.254)
		(layer "B.Cu")
		(net "VSENSE_VSS_SENSE_A_P1")
	)
	(segment
		(start 143.757904 -220.708982)
		(end 143.314674 -220.265752)
		(width 0.254)
		(layer "B.Cu")
		(net "VSENSE_VSS_SENSE_A_P1")
	)
	(segment
		(start 135.742426 -218.135454)
		(end 136.238234 -218.631262)
		(width 0.254)
		(layer "B.Cu")
		(net "VSENSE_VSS_SENSE_A_P1")
	)
	(segment
		(start 135.742426 -217.14079)
		(end 135.742426 -218.135454)
		(width 0.254)
		(layer "B.Cu")
		(net "VSENSE_VSS_SENSE_A_P1")
	)
	(segment
		(start 133.724396 -215.756236)
		(end 133.80593 -215.83777)
		(width 0.254)
		(layer "B.Cu")
		(net "VSENSE_VSS_SENSE_A_P1")
	)
	(segment
		(start 144.674844 -223.424496)
		(end 144.674844 -223.132142)
		(width 0.0762)
		(layer "B.Cu")
		(net "VSENSE_VSS_SENSE_A_P1")
	)
	(segment
		(start 143.757904 -221.174564)
		(end 143.757904 -220.708982)
		(width 0.254)
		(layer "B.Cu")
		(net "VSENSE_VSS_SENSE_A_P1")
	)
	(segment
		(start 93.1418 -148.821648)
		(end 93.87078 -148.092668)
		(width 0.1778)
		(layer "B.Cu")
		(net "VSENSE_VSS_SENSE_A_P1")
	)
	(segment
		(start 58.590434 -169.921174)
		(end 58.590434 -163.961064)
		(width 0.254)
		(layer "In2.Cu")
		(net "VSENSE_VSS_SENSE_A_P1")
	)
	(segment
		(start 58.349388 -181.27091)
		(end 59.860434 -179.759864)
		(width 0.254)
		(layer "In2.Cu")
		(net "VSENSE_VSS_SENSE_A_P1")
	)
	(segment
		(start 64.452246 -158.099252)
		(end 77.284326 -158.099252)
		(width 0.254)
		(layer "In2.Cu")
		(net "VSENSE_VSS_SENSE_A_P1")
	)
	(segment
		(start 57.126378 -181.27091)
		(end 58.349388 -181.27091)
		(width 0.254)
		(layer "In2.Cu")
		(net "VSENSE_VSS_SENSE_A_P1")
	)
	(segment
		(start 58.590434 -163.961064)
		(end 64.452246 -158.099252)
		(width 0.254)
		(layer "In2.Cu")
		(net "VSENSE_VSS_SENSE_A_P1")
	)
	(segment
		(start 84.301076 -151.082502)
		(end 92.43695 -151.082502)
		(width 0.254)
		(layer "In2.Cu")
		(net "VSENSE_VSS_SENSE_A_P1")
	)
	(segment
		(start 59.860434 -179.759864)
		(end 59.860434 -171.191174)
		(width 0.254)
		(layer "In2.Cu")
		(net "VSENSE_VSS_SENSE_A_P1")
	)
	(segment
		(start 56.935878 -181.08041)
		(end 57.126378 -181.27091)
		(width 0.254)
		(layer "In2.Cu")
		(net "VSENSE_VSS_SENSE_A_P1")
	)
	(segment
		(start 59.860434 -171.191174)
		(end 58.590434 -169.921174)
		(width 0.254)
		(layer "In2.Cu")
		(net "VSENSE_VSS_SENSE_A_P1")
	)
	(segment
		(start 92.43695 -151.082502)
		(end 92.750132 -150.76932)
		(width 0.254)
		(layer "In2.Cu")
		(net "VSENSE_VSS_SENSE_A_P1")
	)
	(segment
		(start 77.284326 -158.099252)
		(end 84.301076 -151.082502)
		(width 0.254)
		(layer "In2.Cu")
		(net "VSENSE_VSS_SENSE_A_P1")
	)
	(segment
		(start 121.40184 -154.802332)
		(end 126.8857 -149.318472)
		(width 0.254)
		(layer "In4.Cu")
		(net "VSENSE_VSS_SENSE_A_P1")
	)
	(segment
		(start 103.515922 -147.44446)
		(end 103.126286 -147.44446)
		(width 0.254)
		(layer "In4.Cu")
		(net "VSENSE_VSS_SENSE_A_P1")
	)
	(segment
		(start 139.191238 -155.34005)
		(end 137.072878 -157.45841)
		(width 0.254)
		(layer "In4.Cu")
		(net "VSENSE_VSS_SENSE_A_P1")
	)
	(segment
		(start 139.191238 -149.20087)
		(end 139.191238 -155.34005)
		(width 0.254)
		(layer "In4.Cu")
		(net "VSENSE_VSS_SENSE_A_P1")
	)
	(segment
		(start 126.8857 -149.318472)
		(end 126.8857 -144.911318)
		(width 0.254)
		(layer "In4.Cu")
		(net "VSENSE_VSS_SENSE_A_P1")
	)
	(segment
		(start 137.199878 -147.20951)
		(end 139.191238 -149.20087)
		(width 0.254)
		(layer "In4.Cu")
		(net "VSENSE_VSS_SENSE_A_P1")
	)
	(segment
		(start 137.072878 -157.45841)
		(end 137.072878 -165.33241)
		(width 0.254)
		(layer "In4.Cu")
		(net "VSENSE_VSS_SENSE_A_P1")
	)
	(segment
		(start 108.610654 -154.802332)
		(end 121.40184 -154.802332)
		(width 0.254)
		(layer "In4.Cu")
		(net "VSENSE_VSS_SENSE_A_P1")
	)
	(segment
		(start 126.8857 -144.911318)
		(end 130.698748 -141.09827)
		(width 0.254)
		(layer "In4.Cu")
		(net "VSENSE_VSS_SENSE_A_P1")
	)
	(segment
		(start 130.698748 -141.09827)
		(end 134.918958 -141.09827)
		(width 0.254)
		(layer "In4.Cu")
		(net "VSENSE_VSS_SENSE_A_P1")
	)
	(segment
		(start 102.875334 -147.695412)
		(end 102.875334 -149.067012)
		(width 0.254)
		(layer "In4.Cu")
		(net "VSENSE_VSS_SENSE_A_P1")
	)
	(segment
		(start 139.546838 -167.395652)
		(end 139.689078 -167.253412)
		(width 0.254)
		(layer "In4.Cu")
		(net "VSENSE_VSS_SENSE_A_P1")
	)
	(segment
		(start 137.072878 -165.33241)
		(end 139.13612 -167.395652)
		(width 0.254)
		(layer "In4.Cu")
		(net "VSENSE_VSS_SENSE_A_P1")
	)
	(segment
		(start 139.13612 -167.395652)
		(end 139.546838 -167.395652)
		(width 0.254)
		(layer "In4.Cu")
		(net "VSENSE_VSS_SENSE_A_P1")
	)
	(segment
		(start 137.199878 -143.37919)
		(end 137.199878 -147.20951)
		(width 0.254)
		(layer "In4.Cu")
		(net "VSENSE_VSS_SENSE_A_P1")
	)
	(segment
		(start 102.875334 -149.067012)
		(end 108.610654 -154.802332)
		(width 0.254)
		(layer "In4.Cu")
		(net "VSENSE_VSS_SENSE_A_P1")
	)
	(segment
		(start 103.126286 -147.44446)
		(end 102.875334 -147.695412)
		(width 0.254)
		(layer "In4.Cu")
		(net "VSENSE_VSS_SENSE_A_P1")
	)
	(segment
		(start 134.918958 -141.09827)
		(end 137.199878 -143.37919)
		(width 0.254)
		(layer "In4.Cu")
		(net "VSENSE_VSS_SENSE_A_P1")
	)
	(segment
		(start 421.61587 -175.851312)
		(end 421.862758 -176.0982)
		(width 0.254)
		(layer "F.Cu")
		(net "VSENSE_VSS_SENSE_A_P0")
	)
	(segment
		(start 388.722616 -208.661762)
		(end 392.30935 -208.661762)
		(width 0.254)
		(layer "F.Cu")
		(net "VSENSE_VSS_SENSE_A_P0")
	)
	(segment
		(start 364.230158 -217.052652)
		(end 375.225818 -217.052652)
		(width 0.254)
		(layer "F.Cu")
		(net "VSENSE_VSS_SENSE_A_P0")
	)
	(segment
		(start 340.425278 -171.478194)
		(end 340.337394 -171.478194)
		(width 0.254)
		(layer "F.Cu")
		(net "VSENSE_VSS_SENSE_A_P0")
	)
	(segment
		(start 392.14806 -223.69018)
		(end 392.348974 -223.69018)
		(width 0.254)
		(layer "F.Cu")
		(net "VSENSE_VSS_SENSE_A_P0")
	)
	(segment
		(start 421.569642 -175.851312)
		(end 421.61587 -175.851312)
		(width 0.254)
		(layer "F.Cu")
		(net "VSENSE_VSS_SENSE_A_P0")
	)
	(segment
		(start 393.56665 -209.919062)
		(end 396.276576 -209.919062)
		(width 0.254)
		(layer "F.Cu")
		(net "VSENSE_VSS_SENSE_A_P0")
	)
	(segment
		(start 389.18261 -217.61831)
		(end 386.086858 -214.522558)
		(width 0.254)
		(layer "F.Cu")
		(net "VSENSE_VSS_SENSE_A_P0")
	)
	(segment
		(start 393.05484 -223.043496)
		(end 393.649454 -222.448882)
		(width 0.254)
		(layer "F.Cu")
		(net "VSENSE_VSS_SENSE_A_P0")
	)
	(segment
		(start 418.148008 -183.941212)
		(end 423.789348 -178.299872)
		(width 0.254)
		(layer "F.Cu")
		(net "VSENSE_VSS_SENSE_A_P0")
	)
	(segment
		(start 332.345538 -201.187812)
		(end 342.005158 -210.847432)
		(width 0.254)
		(layer "F.Cu")
		(net "VSENSE_VSS_SENSE_A_P0")
	)
	(segment
		(start 392.614912 -223.424242)
		(end 392.674094 -223.424242)
		(width 0.1524)
		(layer "F.Cu")
		(net "VSENSE_VSS_SENSE_A_P0")
	)
	(segment
		(start 408.481276 -197.714362)
		(end 408.481276 -190.560706)
		(width 0.254)
		(layer "F.Cu")
		(net "VSENSE_VSS_SENSE_A_P0")
	)
	(segment
		(start 391.744454 -217.61831)
		(end 389.18261 -217.61831)
		(width 0.254)
		(layer "F.Cu")
		(net "VSENSE_VSS_SENSE_A_P0")
	)
	(segment
		(start 392.674094 -223.424242)
		(end 393.05484 -223.043496)
		(width 0.1524)
		(layer "F.Cu")
		(net "VSENSE_VSS_SENSE_A_P0")
	)
	(segment
		(start 422.46169 -176.316132)
		(end 422.243758 -176.0982)
		(width 0.254)
		(layer "F.Cu")
		(net "VSENSE_VSS_SENSE_A_P0")
	)
	(segment
		(start 341.16899 -171.308522)
		(end 340.999318 -171.478194)
		(width 0.254)
		(layer "F.Cu")
		(net "VSENSE_VSS_SENSE_A_P0")
	)
	(segment
		(start 421.862758 -176.0982)
		(end 422.243758 -176.0982)
		(width 0.254)
		(layer "F.Cu")
		(net "VSENSE_VSS_SENSE_A_P0")
	)
	(segment
		(start 386.086858 -214.522558)
		(end 386.086858 -211.29752)
		(width 0.254)
		(layer "F.Cu")
		(net "VSENSE_VSS_SENSE_A_P0")
	)
	(segment
		(start 380.652528 -219.07119)
		(end 380.865126 -219.283788)
		(width 0.254)
		(layer "F.Cu")
		(net "VSENSE_VSS_SENSE_A_P0")
	)
	(segment
		(start 377.244356 -219.07119)
		(end 380.652528 -219.07119)
		(width 0.254)
		(layer "F.Cu")
		(net "VSENSE_VSS_SENSE_A_P0")
	)
	(segment
		(start 393.649454 -219.52331)
		(end 391.744454 -217.61831)
		(width 0.254)
		(layer "F.Cu")
		(net "VSENSE_VSS_SENSE_A_P0")
	)
	(segment
		(start 332.345538 -174.385478)
		(end 332.345538 -201.187812)
		(width 0.254)
		(layer "F.Cu")
		(net "VSENSE_VSS_SENSE_A_P0")
	)
	(segment
		(start 386.086858 -211.29752)
		(end 388.722616 -208.661762)
		(width 0.254)
		(layer "F.Cu")
		(net "VSENSE_VSS_SENSE_A_P0")
	)
	(segment
		(start 392.30935 -208.661762)
		(end 393.56665 -209.919062)
		(width 0.254)
		(layer "F.Cu")
		(net "VSENSE_VSS_SENSE_A_P0")
	)
	(segment
		(start 408.481276 -190.560706)
		(end 410.436822 -188.60516)
		(width 0.254)
		(layer "F.Cu")
		(net "VSENSE_VSS_SENSE_A_P0")
	)
	(segment
		(start 396.276576 -209.919062)
		(end 408.481276 -197.714362)
		(width 0.254)
		(layer "F.Cu")
		(net "VSENSE_VSS_SENSE_A_P0")
	)
	(segment
		(start 340.337394 -171.478194)
		(end 340.298278 -171.51731)
		(width 0.254)
		(layer "F.Cu")
		(net "VSENSE_VSS_SENSE_A_P0")
	)
	(segment
		(start 375.225818 -217.052652)
		(end 377.244356 -219.07119)
		(width 0.254)
		(layer "F.Cu")
		(net "VSENSE_VSS_SENSE_A_P0")
	)
	(segment
		(start 416.268408 -188.60516)
		(end 418.148008 -186.72556)
		(width 0.254)
		(layer "F.Cu")
		(net "VSENSE_VSS_SENSE_A_P0")
	)
	(segment
		(start 334.998314 -171.732702)
		(end 332.345538 -174.385478)
		(width 0.254)
		(layer "F.Cu")
		(net "VSENSE_VSS_SENSE_A_P0")
	)
	(segment
		(start 392.348974 -223.69018)
		(end 392.614912 -223.424242)
		(width 0.254)
		(layer "F.Cu")
		(net "VSENSE_VSS_SENSE_A_P0")
	)
	(segment
		(start 423.312336 -176.316132)
		(end 422.46169 -176.316132)
		(width 0.254)
		(layer "F.Cu")
		(net "VSENSE_VSS_SENSE_A_P0")
	)
	(segment
		(start 423.789348 -176.793144)
		(end 423.312336 -176.316132)
		(width 0.254)
		(layer "F.Cu")
		(net "VSENSE_VSS_SENSE_A_P0")
	)
	(segment
		(start 342.005158 -210.847432)
		(end 358.024938 -210.847432)
		(width 0.254)
		(layer "F.Cu")
		(net "VSENSE_VSS_SENSE_A_P0")
	)
	(segment
		(start 358.024938 -210.847432)
		(end 364.230158 -217.052652)
		(width 0.254)
		(layer "F.Cu")
		(net "VSENSE_VSS_SENSE_A_P0")
	)
	(segment
		(start 339.946742 -171.732702)
		(end 334.998314 -171.732702)
		(width 0.254)
		(layer "F.Cu")
		(net "VSENSE_VSS_SENSE_A_P0")
	)
	(segment
		(start 340.298278 -171.51731)
		(end 340.162134 -171.51731)
		(width 0.254)
		(layer "F.Cu")
		(net "VSENSE_VSS_SENSE_A_P0")
	)
	(segment
		(start 418.148008 -186.72556)
		(end 418.148008 -183.941212)
		(width 0.254)
		(layer "F.Cu")
		(net "VSENSE_VSS_SENSE_A_P0")
	)
	(segment
		(start 340.999318 -171.478194)
		(end 340.425278 -171.478194)
		(width 0.254)
		(layer "F.Cu")
		(net "VSENSE_VSS_SENSE_A_P0")
	)
	(segment
		(start 423.789348 -178.299872)
		(end 423.789348 -176.793144)
		(width 0.254)
		(layer "F.Cu")
		(net "VSENSE_VSS_SENSE_A_P0")
	)
	(segment
		(start 340.162134 -171.51731)
		(end 339.946742 -171.732702)
		(width 0.254)
		(layer "F.Cu")
		(net "VSENSE_VSS_SENSE_A_P0")
	)
	(segment
		(start 393.649454 -222.448882)
		(end 393.649454 -219.52331)
		(width 0.254)
		(layer "F.Cu")
		(net "VSENSE_VSS_SENSE_A_P0")
	)
	(segment
		(start 410.436822 -188.60516)
		(end 416.268408 -188.60516)
		(width 0.254)
		(layer "F.Cu")
		(net "VSENSE_VSS_SENSE_A_P0")
	)
	(via
		(at 375.477532 -148.372068)
		(size 0.508)
		(drill 0.254)
		(layers "F.Cu" "B.Cu")
		(net "VSENSE_VSS_SENSE_A_P0")
	)
	(via
		(at 340.425278 -171.478194)
		(size 0.508)
		(drill 0.254)
		(layers "F.Cu" "B.Cu")
		(net "VSENSE_VSS_SENSE_A_P0")
	)
	(via
		(at 392.614912 -223.424242)
		(size 0.4064)
		(drill 0.2032)
		(layers "F.Cu" "B.Cu")
		(net "VSENSE_VSS_SENSE_A_P0")
	)
	(via
		(at 422.243758 -176.0982)
		(size 0.508)
		(drill 0.254)
		(layers "F.Cu" "B.Cu")
		(net "VSENSE_VSS_SENSE_A_P0")
	)
	(via
		(at 380.865126 -219.283788)
		(size 0.508)
		(drill 0.254)
		(layers "F.Cu" "B.Cu")
		(net "VSENSE_VSS_SENSE_A_P0")
	)
	(segment
		(start 393.574778 -144.833086)
		(end 395.58087 -142.826994)
		(width 0.254)
		(layer "B.Cu")
		(net "VSENSE_VSS_SENSE_A_P0")
	)
	(segment
		(start 381.273304 -143.761206)
		(end 381.865886 -143.761206)
		(width 0.1778)
		(layer "B.Cu")
		(net "VSENSE_VSS_SENSE_A_P0")
	)
	(segment
		(start 395.58087 -142.826994)
		(end 395.58087 -136.81837)
		(width 0.254)
		(layer "B.Cu")
		(net "VSENSE_VSS_SENSE_A_P0")
	)
	(segment
		(start 428.291498 -144.53489)
		(end 428.291498 -172.663358)
		(width 0.254)
		(layer "B.Cu")
		(net "VSENSE_VSS_SENSE_A_P0")
	)
	(segment
		(start 421.974518 -175.029622)
		(end 421.974518 -175.82896)
		(width 0.254)
		(layer "B.Cu")
		(net "VSENSE_VSS_SENSE_A_P0")
	)
	(segment
		(start 383.151888 -145.047208)
		(end 383.732278 -145.047208)
		(width 0.254)
		(layer "B.Cu")
		(net "VSENSE_VSS_SENSE_A_P0")
	)
	(segment
		(start 421.974518 -175.82896)
		(end 422.243758 -176.0982)
		(width 0.254)
		(layer "B.Cu")
		(net "VSENSE_VSS_SENSE_A_P0")
	)
	(segment
		(start 395.58087 -136.81837)
		(end 400.888454 -131.510786)
		(width 0.254)
		(layer "B.Cu")
		(net "VSENSE_VSS_SENSE_A_P0")
	)
	(segment
		(start 386.243322 -145.047208)
		(end 386.457444 -144.833086)
		(width 0.254)
		(layer "B.Cu")
		(net "VSENSE_VSS_SENSE_A_P0")
	)
	(segment
		(start 375.731532 -147.018756)
		(end 376.59818 -146.152108)
		(width 0.1778)
		(layer "B.Cu")
		(net "VSENSE_VSS_SENSE_A_P0")
	)
	(segment
		(start 375.731532 -148.118068)
		(end 375.477532 -148.372068)
		(width 0.254)
		(layer "B.Cu")
		(net "VSENSE_VSS_SENSE_A_P0")
	)
	(segment
		(start 400.888454 -131.510786)
		(end 415.267394 -131.510786)
		(width 0.254)
		(layer "B.Cu")
		(net "VSENSE_VSS_SENSE_A_P0")
	)
	(segment
		(start 383.732278 -145.047208)
		(end 386.243322 -145.047208)
		(width 0.254)
		(layer "B.Cu")
		(net "VSENSE_VSS_SENSE_A_P0")
	)
	(segment
		(start 422.45788 -176.312322)
		(end 422.243758 -176.0982)
		(width 0.254)
		(layer "B.Cu")
		(net "VSENSE_VSS_SENSE_A_P0")
	)
	(segment
		(start 375.731532 -147.741132)
		(end 375.731532 -147.018756)
		(width 0.1778)
		(layer "B.Cu")
		(net "VSENSE_VSS_SENSE_A_P0")
	)
	(segment
		(start 415.267394 -131.510786)
		(end 428.291498 -144.53489)
		(width 0.254)
		(layer "B.Cu")
		(net "VSENSE_VSS_SENSE_A_P0")
	)
	(segment
		(start 424.642534 -176.312322)
		(end 422.45788 -176.312322)
		(width 0.254)
		(layer "B.Cu")
		(net "VSENSE_VSS_SENSE_A_P0")
	)
	(segment
		(start 381.865886 -143.761206)
		(end 383.151888 -145.047208)
		(width 0.254)
		(layer "B.Cu")
		(net "VSENSE_VSS_SENSE_A_P0")
	)
	(segment
		(start 375.731532 -147.741132)
		(end 375.731532 -148.118068)
		(width 0.254)
		(layer "B.Cu")
		(net "VSENSE_VSS_SENSE_A_P0")
	)
	(segment
		(start 428.291498 -172.663358)
		(end 424.642534 -176.312322)
		(width 0.254)
		(layer "B.Cu")
		(net "VSENSE_VSS_SENSE_A_P0")
	)
	(segment
		(start 386.457444 -144.833086)
		(end 393.574778 -144.833086)
		(width 0.254)
		(layer "B.Cu")
		(net "VSENSE_VSS_SENSE_A_P0")
	)
	(segment
		(start 376.59818 -146.152108)
		(end 376.59818 -145.236184)
		(width 0.1778)
		(layer "B.Cu")
		(net "VSENSE_VSS_SENSE_A_P0")
	)
	(segment
		(start 342.51138 -160.243012)
		(end 342.51138 -162.42538)
		(width 0.254)
		(layer "In2.Cu")
		(net "VSENSE_VSS_SENSE_A_P0")
	)
	(segment
		(start 341.518748 -157.583378)
		(end 341.518748 -159.25038)
		(width 0.254)
		(layer "In2.Cu")
		(net "VSENSE_VSS_SENSE_A_P0")
	)
	(segment
		(start 362.051854 -150.34133)
		(end 361.511596 -149.801072)
		(width 0.254)
		(layer "In2.Cu")
		(net "VSENSE_VSS_SENSE_A_P0")
	)
	(segment
		(start 351.601786 -153.713434)
		(end 345.388692 -153.713434)
		(width 0.254)
		(layer "In2.Cu")
		(net "VSENSE_VSS_SENSE_A_P0")
	)
	(segment
		(start 341.139018 -171.60367)
		(end 340.550754 -171.60367)
		(width 0.254)
		(layer "In2.Cu")
		(net "VSENSE_VSS_SENSE_A_P0")
	)
	(segment
		(start 355.514148 -149.801072)
		(end 351.601786 -153.713434)
		(width 0.254)
		(layer "In2.Cu")
		(net "VSENSE_VSS_SENSE_A_P0")
	)
	(segment
		(start 375.477532 -148.372068)
		(end 375.477532 -148.527516)
		(width 0.254)
		(layer "In2.Cu")
		(net "VSENSE_VSS_SENSE_A_P0")
	)
	(segment
		(start 341.518748 -163.418012)
		(end 341.518748 -171.22394)
		(width 0.254)
		(layer "In2.Cu")
		(net "VSENSE_VSS_SENSE_A_P0")
	)
	(segment
		(start 345.388692 -153.713434)
		(end 341.518748 -157.583378)
		(width 0.254)
		(layer "In2.Cu")
		(net "VSENSE_VSS_SENSE_A_P0")
	)
	(segment
		(start 375.477532 -148.527516)
		(end 373.663718 -150.34133)
		(width 0.254)
		(layer "In2.Cu")
		(net "VSENSE_VSS_SENSE_A_P0")
	)
	(segment
		(start 341.518748 -159.25038)
		(end 342.51138 -160.243012)
		(width 0.254)
		(layer "In2.Cu")
		(net "VSENSE_VSS_SENSE_A_P0")
	)
	(segment
		(start 341.518748 -171.22394)
		(end 341.139018 -171.60367)
		(width 0.254)
		(layer "In2.Cu")
		(net "VSENSE_VSS_SENSE_A_P0")
	)
	(segment
		(start 373.663718 -150.34133)
		(end 362.051854 -150.34133)
		(width 0.254)
		(layer "In2.Cu")
		(net "VSENSE_VSS_SENSE_A_P0")
	)
	(segment
		(start 361.511596 -149.801072)
		(end 355.514148 -149.801072)
		(width 0.254)
		(layer "In2.Cu")
		(net "VSENSE_VSS_SENSE_A_P0")
	)
	(segment
		(start 340.550754 -171.60367)
		(end 340.425278 -171.478194)
		(width 0.254)
		(layer "In2.Cu")
		(net "VSENSE_VSS_SENSE_A_P0")
	)
	(segment
		(start 342.51138 -162.42538)
		(end 341.518748 -163.418012)
		(width 0.254)
		(layer "In2.Cu")
		(net "VSENSE_VSS_SENSE_A_P0")
	)
	(segment
		(start 390.305798 -221.045532)
		(end 392.614912 -223.354646)
		(width 0.254)
		(layer "In15.Cu")
		(net "VSENSE_VSS_SENSE_A_P0")
	)
	(segment
		(start 392.614912 -223.354646)
		(end 392.614912 -223.424242)
		(width 0.254)
		(layer "In15.Cu")
		(net "VSENSE_VSS_SENSE_A_P0")
	)
	(segment
		(start 383.630932 -219.029788)
		(end 385.646676 -221.045532)
		(width 0.254)
		(layer "In15.Cu")
		(net "VSENSE_VSS_SENSE_A_P0")
	)
	(segment
		(start 381.119126 -219.029788)
		(end 383.630932 -219.029788)
		(width 0.254)
		(layer "In15.Cu")
		(net "VSENSE_VSS_SENSE_A_P0")
	)
	(segment
		(start 385.646676 -221.045532)
		(end 390.305798 -221.045532)
		(width 0.254)
		(layer "In15.Cu")
		(net "VSENSE_VSS_SENSE_A_P0")
	)
	(segment
		(start 380.865126 -219.283788)
		(end 381.119126 -219.029788)
		(width 0.254)
		(layer "In15.Cu")
		(net "VSENSE_VSS_SENSE_A_P0")
	)
	(segment
		(start 35.433 -361.061)
		(end 35.433 -361.95)
		(width 0.254)
		(layer "F.Cu")
		(net "VSENSE_PVDDIO_P1_VSEN1")
	)
	(segment
		(start 35.433 -361.95)
		(end 35.052 -362.331)
		(width 0.254)
		(layer "F.Cu")
		(net "VSENSE_PVDDIO_P1_VSEN1")
	)
	(segment
		(start 35.941 -360.553)
		(end 35.433 -361.061)
		(width 0.254)
		(layer "F.Cu")
		(net "VSENSE_PVDDIO_P1_VSEN1")
	)
	(segment
		(start 35.052 -362.331)
		(end 34.798 -362.585)
		(width 0.1778)
		(layer "F.Cu")
		(net "VSENSE_PVDDIO_P1_VSEN1")
	)
	(segment
		(start 36.448746 -360.553)
		(end 35.941 -360.553)
		(width 0.254)
		(layer "F.Cu")
		(net "VSENSE_PVDDIO_P1_VSEN1")
	)
	(segment
		(start 36.6141 -360.06405)
		(end 36.59505 -360.045)
		(width 0.254)
		(layer "F.Cu")
		(net "VSENSE_PVDDIO_P1_VSEN1")
	)
	(segment
		(start 34.019998 -363.109002)
		(end 33.355026 -363.109002)
		(width 0.1778)
		(layer "F.Cu")
		(net "VSENSE_PVDDIO_P1_VSEN1")
	)
	(segment
		(start 34.798 -362.585)
		(end 34.544 -362.585)
		(width 0.1778)
		(layer "F.Cu")
		(net "VSENSE_PVDDIO_P1_VSEN1")
	)
	(segment
		(start 37.592 -360.06405)
		(end 36.6141 -360.06405)
		(width 0.254)
		(layer "F.Cu")
		(net "VSENSE_PVDDIO_P1_VSEN1")
	)
	(segment
		(start 34.544 -362.585)
		(end 34.019998 -363.109002)
		(width 0.1778)
		(layer "F.Cu")
		(net "VSENSE_PVDDIO_P1_VSEN1")
	)
	(segment
		(start 36.59505 -360.045)
		(end 36.59505 -360.406696)
		(width 0.254)
		(layer "F.Cu")
		(net "VSENSE_PVDDIO_P1_VSEN1")
	)
	(segment
		(start 36.59505 -360.406696)
		(end 36.448746 -360.553)
		(width 0.254)
		(layer "F.Cu")
		(net "VSENSE_PVDDIO_P1_VSEN1")
	)
	(segment
		(start 73.051416 -311.384696)
		(end 62.65926 -321.776852)
		(width 0.254)
		(layer "F.Cu")
		(net "VSENSE_PVDDIO_P1_DP")
	)
	(segment
		(start 98.44786 -268.15034)
		(end 97.981008 -268.416278)
		(width 0.350012)
		(layer "F.Cu")
		(net "VSENSE_PVDDIO_P1_DP")
	)
	(segment
		(start 62.65926 -321.776852)
		(end 54.332886 -321.776852)
		(width 0.254)
		(layer "F.Cu")
		(net "VSENSE_PVDDIO_P1_DP")
	)
	(segment
		(start 21.76018 -332.437486)
		(end 22.09292 -332.104746)
		(width 0.254)
		(layer "F.Cu")
		(net "VSENSE_PVDDIO_P1_DP")
	)
	(segment
		(start 18.372582 -329.13828)
		(end 18.372582 -331.91323)
		(width 0.254)
		(layer "F.Cu")
		(net "VSENSE_PVDDIO_P1_DP")
	)
	(segment
		(start 21.37537 -332.437486)
		(end 21.76018 -332.437486)
		(width 0.254)
		(layer "F.Cu")
		(net "VSENSE_PVDDIO_P1_DP")
	)
	(segment
		(start 54.332886 -321.776852)
		(end 53.515006 -322.594732)
		(width 0.254)
		(layer "F.Cu")
		(net "VSENSE_PVDDIO_P1_DP")
	)
	(segment
		(start 83.118198 -311.384696)
		(end 73.051416 -311.384696)
		(width 0.254)
		(layer "F.Cu")
		(net "VSENSE_PVDDIO_P1_DP")
	)
	(segment
		(start 24.91613 -322.594732)
		(end 18.372582 -329.13828)
		(width 0.254)
		(layer "F.Cu")
		(net "VSENSE_PVDDIO_P1_DP")
	)
	(segment
		(start 21.070062 -332.140306)
		(end 21.070062 -332.132178)
		(width 0.254)
		(layer "F.Cu")
		(net "VSENSE_PVDDIO_P1_DP")
	)
	(segment
		(start 20.772882 -332.437486)
		(end 21.070062 -332.140306)
		(width 0.254)
		(layer "F.Cu")
		(net "VSENSE_PVDDIO_P1_DP")
	)
	(segment
		(start 53.515006 -322.594732)
		(end 24.91613 -322.594732)
		(width 0.254)
		(layer "F.Cu")
		(net "VSENSE_PVDDIO_P1_DP")
	)
	(segment
		(start 37.592 -359.26395)
		(end 36.83 -359.26395)
		(width 0.254)
		(layer "F.Cu")
		(net "VSENSE_PVDDIO_P1_DP")
	)
	(segment
		(start 20.437602 -332.437486)
		(end 20.772882 -332.437486)
		(width 0.254)
		(layer "F.Cu")
		(net "VSENSE_PVDDIO_P1_DP")
	)
	(segment
		(start 86.176612 -302.796448)
		(end 86.062058 -302.911002)
		(width 0.254)
		(layer "F.Cu")
		(net "VSENSE_PVDDIO_P1_DP")
	)
	(segment
		(start 20.00504 -332.004924)
		(end 20.437602 -332.437486)
		(width 0.254)
		(layer "F.Cu")
		(net "VSENSE_PVDDIO_P1_DP")
	)
	(segment
		(start 86.062058 -302.911002)
		(end 86.062058 -308.440836)
		(width 0.254)
		(layer "F.Cu")
		(net "VSENSE_PVDDIO_P1_DP")
	)
	(segment
		(start 19.572986 -332.436978)
		(end 20.00504 -332.004924)
		(width 0.254)
		(layer "F.Cu")
		(net "VSENSE_PVDDIO_P1_DP")
	)
	(segment
		(start 18.372582 -331.91323)
		(end 18.89633 -332.436978)
		(width 0.254)
		(layer "F.Cu")
		(net "VSENSE_PVDDIO_P1_DP")
	)
	(segment
		(start 18.89633 -332.436978)
		(end 19.572986 -332.436978)
		(width 0.254)
		(layer "F.Cu")
		(net "VSENSE_PVDDIO_P1_DP")
	)
	(segment
		(start 86.062058 -308.440836)
		(end 83.118198 -311.384696)
		(width 0.254)
		(layer "F.Cu")
		(net "VSENSE_PVDDIO_P1_DP")
	)
	(segment
		(start 21.070062 -332.132178)
		(end 21.37537 -332.437486)
		(width 0.254)
		(layer "F.Cu")
		(net "VSENSE_PVDDIO_P1_DP")
	)
	(via
		(at 36.83 -359.26395)
		(size 0.508)
		(drill 0.254)
		(layers "F.Cu" "B.Cu")
		(net "VSENSE_PVDDIO_P1_DP")
	)
	(via
		(at 97.981008 -268.416278)
		(size 0.4064)
		(drill 0.2032)
		(layers "F.Cu" "B.Cu")
		(net "VSENSE_PVDDIO_P1_DP")
	)
	(via
		(at 21.070062 -332.132178)
		(size 0.508)
		(drill 0.254)
		(layers "F.Cu" "B.Cu")
		(net "VSENSE_PVDDIO_P1_DP")
	)
	(via
		(at 86.176612 -302.796448)
		(size 0.508)
		(drill 0.254)
		(layers "F.Cu" "B.Cu")
		(net "VSENSE_PVDDIO_P1_DP")
	)
	(segment
		(start 95.444056 -273.76374)
		(end 95.483172 -273.74088)
		(width 0.0762)
		(layer "B.Cu")
		(net "VSENSE_PVDDIO_P1_DP")
	)
	(segment
		(start 89.749884 -297.774106)
		(end 89.241376 -297.265598)
		(width 0.254)
		(layer "B.Cu")
		(net "VSENSE_PVDDIO_P1_DP")
	)
	(segment
		(start 90.780616 -287.390078)
		(end 90.74404 -287.368742)
		(width 0.0762)
		(layer "B.Cu")
		(net "VSENSE_PVDDIO_P1_DP")
	)
	(segment
		(start 91.18346 -289.17138)
		(end 91.21394 -289.1536)
		(width 0.0762)
		(layer "B.Cu")
		(net "VSENSE_PVDDIO_P1_DP")
	)
	(segment
		(start 91.18346 -281.071574)
		(end 91.21394 -281.053794)
		(width 0.0762)
		(layer "B.Cu")
		(net "VSENSE_PVDDIO_P1_DP")
	)
	(segment
		(start 92.593414 -278.641556)
		(end 92.623894 -278.623776)
		(width 0.0762)
		(layer "B.Cu")
		(net "VSENSE_PVDDIO_P1_DP")
	)
	(segment
		(start 92.150184 -279.436068)
		(end 92.19311 -279.410922)
		(width 0.0762)
		(layer "B.Cu")
		(net "VSENSE_PVDDIO_P1_DP")
	)
	(segment
		(start 92.623894 -278.623776)
		(end 92.66301 -278.600916)
		(width 0.0762)
		(layer "B.Cu")
		(net "VSENSE_PVDDIO_P1_DP")
	)
	(segment
		(start 93.533468 -277.021544)
		(end 93.563948 -277.003764)
		(width 0.0762)
		(layer "B.Cu")
		(net "VSENSE_PVDDIO_P1_DP")
	)
	(segment
		(start 90.74404 -289.963606)
		(end 90.783156 -289.940746)
		(width 0.0762)
		(layer "B.Cu")
		(net "VSENSE_PVDDIO_P1_DP")
	)
	(segment
		(start 91.652344 -280.262076)
		(end 91.684094 -280.243788)
		(width 0.0762)
		(layer "B.Cu")
		(net "VSENSE_PVDDIO_P1_DP")
	)
	(segment
		(start 94.504002 -275.383752)
		(end 94.543118 -275.360892)
		(width 0.0762)
		(layer "B.Cu")
		(net "VSENSE_PVDDIO_P1_DP")
	)
	(segment
		(start 91.18346 -292.411404)
		(end 91.21394 -292.393624)
		(width 0.0762)
		(layer "B.Cu")
		(net "VSENSE_PVDDIO_P1_DP")
	)
	(segment
		(start 91.253056 -291.441632)
		(end 91.21394 -291.418772)
		(width 0.0762)
		(layer "B.Cu")
		(net "VSENSE_PVDDIO_P1_DP")
	)
	(segment
		(start 90.74404 -290.608766)
		(end 90.71229 -290.590478)
		(width 0.0762)
		(layer "B.Cu")
		(net "VSENSE_PVDDIO_P1_DP")
	)
	(segment
		(start 91.21394 -292.393624)
		(end 91.253056 -292.370764)
		(width 0.0762)
		(layer "B.Cu")
		(net "VSENSE_PVDDIO_P1_DP")
	)
	(segment
		(start 95.883476 -272.971514)
		(end 95.913956 -272.953734)
		(width 0.0762)
		(layer "B.Cu")
		(net "VSENSE_PVDDIO_P1_DP")
	)
	(segment
		(start 94.316296 -275.706332)
		(end 94.316296 -275.702776)
		(width 0.0762)
		(layer "B.Cu")
		(net "VSENSE_PVDDIO_P1_DP")
	)
	(segment
		(start 90.710512 -286.743394)
		(end 90.74404 -286.723836)
		(width 0.0762)
		(layer "B.Cu")
		(net "VSENSE_PVDDIO_P1_DP")
	)
	(segment
		(start 93.563948 -277.003764)
		(end 93.603064 -276.980904)
		(width 0.0762)
		(layer "B.Cu")
		(net "VSENSE_PVDDIO_P1_DP")
	)
	(segment
		(start 89.14638 -296.185844)
		(end 89.14638 -295.956228)
		(width 0.0762)
		(layer "B.Cu")
		(net "VSENSE_PVDDIO_P1_DP")
	)
	(segment
		(start 89.241376 -297.265598)
		(end 89.241376 -296.612564)
		(width 0.254)
		(layer "B.Cu")
		(net "VSENSE_PVDDIO_P1_DP")
	)
	(segment
		(start 90.74404 -282.50896)
		(end 90.71229 -282.490672)
		(width 0.0762)
		(layer "B.Cu")
		(net "VSENSE_PVDDIO_P1_DP")
	)
	(segment
		(start 90.74404 -286.723836)
		(end 90.783156 -286.700976)
		(width 0.0762)
		(layer "B.Cu")
		(net "VSENSE_PVDDIO_P1_DP")
	)
	(segment
		(start 97.667318 -268.416278)
		(end 97.981008 -268.416278)
		(width 0.0762)
		(layer "B.Cu")
		(net "VSENSE_PVDDIO_P1_DP")
	)
	(segment
		(start 89.241376 -296.612564)
		(end 89.241376 -296.568114)
		(width 0.0762)
		(layer "B.Cu")
		(net "VSENSE_PVDDIO_P1_DP")
	)
	(segment
		(start 94.002352 -276.212046)
		(end 94.034102 -276.193758)
		(width 0.0762)
		(layer "B.Cu")
		(net "VSENSE_PVDDIO_P1_DP")
	)
	(segment
		(start 89.799414 -294.82923)
		(end 89.805256 -294.825928)
		(width 0.0762)
		(layer "B.Cu")
		(net "VSENSE_PVDDIO_P1_DP")
	)
	(segment
		(start 89.302336 -295.651936)
		(end 89.370408 -295.612566)
		(width 0.0762)
		(layer "B.Cu")
		(net "VSENSE_PVDDIO_P1_DP")
	)
	(segment
		(start 90.71229 -289.981894)
		(end 90.74404 -289.963606)
		(width 0.0762)
		(layer "B.Cu")
		(net "VSENSE_PVDDIO_P1_DP")
	)
	(segment
		(start 88.285066 -300.727618)
		(end 89.749884 -299.2628)
		(width 0.254)
		(layer "B.Cu")
		(net "VSENSE_PVDDIO_P1_DP")
	)
	(segment
		(start 91.253056 -288.201608)
		(end 91.21394 -288.178748)
		(width 0.0762)
		(layer "B.Cu")
		(net "VSENSE_PVDDIO_P1_DP")
	)
	(segment
		(start 96.856296 -270.355314)
		(end 96.856042 -270.35506)
		(width 0.0762)
		(layer "B.Cu")
		(net "VSENSE_PVDDIO_P1_DP")
	)
	(segment
		(start 97.32391 -268.903704)
		(end 97.363026 -268.880844)
		(width 0.0762)
		(layer "B.Cu")
		(net "VSENSE_PVDDIO_P1_DP")
	)
	(segment
		(start 91.966288 -279.756362)
		(end 91.966288 -279.754076)
		(width 0.0762)
		(layer "B.Cu")
		(net "VSENSE_PVDDIO_P1_DP")
	)
	(segment
		(start 96.853756 -269.716758)
		(end 96.85528 -269.715996)
		(width 0.0762)
		(layer "B.Cu")
		(net "VSENSE_PVDDIO_P1_DP")
	)
	(segment
		(start 89.749884 -299.2628)
		(end 89.749884 -297.774106)
		(width 0.254)
		(layer "B.Cu")
		(net "VSENSE_PVDDIO_P1_DP")
	)
	(segment
		(start 86.04377 -302.663606)
		(end 86.04377 -301.795942)
		(width 0.254)
		(layer "B.Cu")
		(net "VSENSE_PVDDIO_P1_DP")
	)
	(segment
		(start 90.71229 -285.122112)
		(end 90.74404 -285.103824)
		(width 0.0762)
		(layer "B.Cu")
		(net "VSENSE_PVDDIO_P1_DP")
	)
	(segment
		(start 96.856042 -270.35506)
		(end 96.853756 -270.35379)
		(width 0.0762)
		(layer "B.Cu")
		(net "VSENSE_PVDDIO_P1_DP")
	)
	(segment
		(start 90.74404 -285.103824)
		(end 90.783156 -285.080964)
		(width 0.0762)
		(layer "B.Cu")
		(net "VSENSE_PVDDIO_P1_DP")
	)
	(segment
		(start 93.062298 -277.832058)
		(end 93.094048 -277.81377)
		(width 0.0762)
		(layer "B.Cu")
		(net "VSENSE_PVDDIO_P1_DP")
	)
	(segment
		(start 97.29343 -268.921484)
		(end 97.32391 -268.903704)
		(width 0.0762)
		(layer "B.Cu")
		(net "VSENSE_PVDDIO_P1_DP")
	)
	(segment
		(start 90.243406 -294.031416)
		(end 90.273886 -294.013636)
		(width 0.0762)
		(layer "B.Cu")
		(net "VSENSE_PVDDIO_P1_DP")
	)
	(segment
		(start 90.74404 -285.748984)
		(end 90.71229 -285.730696)
		(width 0.0762)
		(layer "B.Cu")
		(net "VSENSE_PVDDIO_P1_DP")
	)
	(segment
		(start 90.783156 -285.771844)
		(end 90.74404 -285.748984)
		(width 0.0762)
		(layer "B.Cu")
		(net "VSENSE_PVDDIO_P1_DP")
	)
	(segment
		(start 90.783156 -282.53182)
		(end 90.74404 -282.50896)
		(width 0.0762)
		(layer "B.Cu")
		(net "VSENSE_PVDDIO_P1_DP")
	)
	(segment
		(start 86.176612 -302.796448)
		(end 86.04377 -302.663606)
		(width 0.254)
		(layer "B.Cu")
		(net "VSENSE_PVDDIO_P1_DP")
	)
	(segment
		(start 94.973902 -274.573746)
		(end 95.013018 -274.550886)
		(width 0.0762)
		(layer "B.Cu")
		(net "VSENSE_PVDDIO_P1_DP")
	)
	(segment
		(start 87.112094 -300.727618)
		(end 88.285066 -300.727618)
		(width 0.254)
		(layer "B.Cu")
		(net "VSENSE_PVDDIO_P1_DP")
	)
	(segment
		(start 95.913956 -272.953734)
		(end 95.953072 -272.930874)
		(width 0.0762)
		(layer "B.Cu")
		(net "VSENSE_PVDDIO_P1_DP")
	)
	(segment
		(start 89.241376 -296.568114)
		(end 89.146126 -296.472864)
		(width 0.0762)
		(layer "B.Cu")
		(net "VSENSE_PVDDIO_P1_DP")
	)
	(segment
		(start 96.38411 -272.143728)
		(end 96.420432 -272.122646)
		(width 0.0762)
		(layer "B.Cu")
		(net "VSENSE_PVDDIO_P1_DP")
	)
	(segment
		(start 86.04377 -301.795942)
		(end 87.112094 -300.727618)
		(width 0.254)
		(layer "B.Cu")
		(net "VSENSE_PVDDIO_P1_DP")
	)
	(segment
		(start 91.21394 -291.418772)
		(end 91.18346 -291.400992)
		(width 0.0762)
		(layer "B.Cu")
		(net "VSENSE_PVDDIO_P1_DP")
	)
	(segment
		(start 91.21394 -281.053794)
		(end 91.253056 -281.030934)
		(width 0.0762)
		(layer "B.Cu")
		(net "VSENSE_PVDDIO_P1_DP")
	)
	(segment
		(start 96.35236 -272.162016)
		(end 96.38411 -272.143728)
		(width 0.0762)
		(layer "B.Cu")
		(net "VSENSE_PVDDIO_P1_DP")
	)
	(segment
		(start 89.146126 -296.186098)
		(end 89.14638 -296.185844)
		(width 0.0762)
		(layer "B.Cu")
		(net "VSENSE_PVDDIO_P1_DP")
	)
	(segment
		(start 90.74404 -284.128972)
		(end 90.71229 -284.110684)
		(width 0.0762)
		(layer "B.Cu")
		(net "VSENSE_PVDDIO_P1_DP")
	)
	(segment
		(start 94.498922 -275.386546)
		(end 94.504002 -275.383752)
		(width 0.0762)
		(layer "B.Cu")
		(net "VSENSE_PVDDIO_P1_DP")
	)
	(segment
		(start 90.71229 -281.882088)
		(end 90.74404 -281.8638)
		(width 0.0762)
		(layer "B.Cu")
		(net "VSENSE_PVDDIO_P1_DP")
	)
	(segment
		(start 97.602802 -268.480794)
		(end 97.667318 -268.416278)
		(width 0.0762)
		(layer "B.Cu")
		(net "VSENSE_PVDDIO_P1_DP")
	)
	(segment
		(start 90.71229 -283.5021)
		(end 90.74404 -283.483812)
		(width 0.0762)
		(layer "B.Cu")
		(net "VSENSE_PVDDIO_P1_DP")
	)
	(segment
		(start 90.74404 -283.483812)
		(end 90.783156 -283.460952)
		(width 0.0762)
		(layer "B.Cu")
		(net "VSENSE_PVDDIO_P1_DP")
	)
	(segment
		(start 90.71229 -293.221918)
		(end 90.74404 -293.20363)
		(width 0.0762)
		(layer "B.Cu")
		(net "VSENSE_PVDDIO_P1_DP")
	)
	(segment
		(start 96.82226 -271.35201)
		(end 96.85401 -271.333722)
		(width 0.0762)
		(layer "B.Cu")
		(net "VSENSE_PVDDIO_P1_DP")
	)
	(segment
		(start 93.094048 -277.81377)
		(end 93.133164 -277.79091)
		(width 0.0762)
		(layer "B.Cu")
		(net "VSENSE_PVDDIO_P1_DP")
	)
	(segment
		(start 94.943422 -274.591526)
		(end 94.973902 -274.573746)
		(width 0.0762)
		(layer "B.Cu")
		(net "VSENSE_PVDDIO_P1_DP")
	)
	(segment
		(start 90.74404 -281.8638)
		(end 90.783156 -281.84094)
		(width 0.0762)
		(layer "B.Cu")
		(net "VSENSE_PVDDIO_P1_DP")
	)
	(segment
		(start 96.85528 -269.715996)
		(end 96.855534 -269.715742)
		(width 0.0762)
		(layer "B.Cu")
		(net "VSENSE_PVDDIO_P1_DP")
	)
	(segment
		(start 91.684094 -280.243788)
		(end 91.720416 -280.222706)
		(width 0.0762)
		(layer "B.Cu")
		(net "VSENSE_PVDDIO_P1_DP")
	)
	(segment
		(start 89.805256 -294.825928)
		(end 89.80551 -294.825674)
		(width 0.0762)
		(layer "B.Cu")
		(net "VSENSE_PVDDIO_P1_DP")
	)
	(segment
		(start 94.034102 -276.193758)
		(end 94.070424 -276.172676)
		(width 0.0762)
		(layer "B.Cu")
		(net "VSENSE_PVDDIO_P1_DP")
	)
	(segment
		(start 90.74404 -293.20363)
		(end 90.783156 -293.18077)
		(width 0.0762)
		(layer "B.Cu")
		(net "VSENSE_PVDDIO_P1_DP")
	)
	(segment
		(start 90.74404 -287.368742)
		(end 90.71229 -287.350454)
		(width 0.0762)
		(layer "B.Cu")
		(net "VSENSE_PVDDIO_P1_DP")
	)
	(segment
		(start 95.412306 -273.782028)
		(end 95.444056 -273.76374)
		(width 0.0762)
		(layer "B.Cu")
		(net "VSENSE_PVDDIO_P1_DP")
	)
	(segment
		(start 90.783156 -290.631626)
		(end 90.74404 -290.608766)
		(width 0.0762)
		(layer "B.Cu")
		(net "VSENSE_PVDDIO_P1_DP")
	)
	(segment
		(start 90.273886 -294.013636)
		(end 90.313002 -293.990776)
		(width 0.0762)
		(layer "B.Cu")
		(net "VSENSE_PVDDIO_P1_DP")
	)
	(segment
		(start 91.21394 -288.178748)
		(end 91.181428 -288.159952)
		(width 0.0762)
		(layer "B.Cu")
		(net "VSENSE_PVDDIO_P1_DP")
	)
	(segment
		(start 96.85401 -271.333722)
		(end 96.893126 -271.310862)
		(width 0.0762)
		(layer "B.Cu")
		(net "VSENSE_PVDDIO_P1_DP")
	)
	(segment
		(start 89.146126 -296.472864)
		(end 89.146126 -296.186098)
		(width 0.0762)
		(layer "B.Cu")
		(net "VSENSE_PVDDIO_P1_DP")
	)
	(segment
		(start 90.783156 -284.151832)
		(end 90.74404 -284.128972)
		(width 0.0762)
		(layer "B.Cu")
		(net "VSENSE_PVDDIO_P1_DP")
	)
	(segment
		(start 91.21394 -289.1536)
		(end 91.253056 -289.13074)
		(width 0.0762)
		(layer "B.Cu")
		(net "VSENSE_PVDDIO_P1_DP")
	)
	(arc
		(start 90.313002 -293.990776)
		(mid 90.491815 -293.788426)
		(end 90.556334 -293.52621)
		(width 0.0762)
		(layer "B.Cu")
		(net "VSENSE_PVDDIO_P1_DP")
	)
	(arc
		(start 91.496388 -280.566368)
		(mid 91.537643 -280.395397)
		(end 91.652344 -280.262076)
		(width 0.0762)
		(layer "B.Cu")
		(net "VSENSE_PVDDIO_P1_DP")
	)
	(arc
		(start 96.853756 -270.35379)
		(mid 96.669607 -270.035274)
		(end 96.853756 -269.716758)
		(width 0.0762)
		(layer "B.Cu")
		(net "VSENSE_PVDDIO_P1_DP")
	)
	(arc
		(start 97.363026 -268.880844)
		(mid 97.526109 -268.706704)
		(end 97.602802 -268.480794)
		(width 0.0762)
		(layer "B.Cu")
		(net "VSENSE_PVDDIO_P1_DP")
	)
	(arc
		(start 92.906342 -278.13635)
		(mid 92.947597 -277.965379)
		(end 93.062298 -277.832058)
		(width 0.0762)
		(layer "B.Cu")
		(net "VSENSE_PVDDIO_P1_DP")
	)
	(arc
		(start 90.783156 -285.080964)
		(mid 91.026483 -284.616398)
		(end 90.783156 -284.151832)
		(width 0.0762)
		(layer "B.Cu")
		(net "VSENSE_PVDDIO_P1_DP")
	)
	(arc
		(start 90.783156 -289.940746)
		(mid 90.961969 -289.738396)
		(end 91.026488 -289.47618)
		(width 0.0762)
		(layer "B.Cu")
		(net "VSENSE_PVDDIO_P1_DP")
	)
	(arc
		(start 91.253056 -289.13074)
		(mid 91.496383 -288.666174)
		(end 91.253056 -288.201608)
		(width 0.0762)
		(layer "B.Cu")
		(net "VSENSE_PVDDIO_P1_DP")
	)
	(arc
		(start 96.196404 -272.466308)
		(mid 96.237659 -272.295337)
		(end 96.35236 -272.162016)
		(width 0.0762)
		(layer "B.Cu")
		(net "VSENSE_PVDDIO_P1_DP")
	)
	(arc
		(start 91.026488 -287.856422)
		(mid 90.961252 -287.592831)
		(end 90.780616 -287.390078)
		(width 0.0762)
		(layer "B.Cu")
		(net "VSENSE_PVDDIO_P1_DP")
	)
	(arc
		(start 93.846396 -276.516338)
		(mid 93.887651 -276.345367)
		(end 94.002352 -276.212046)
		(width 0.0762)
		(layer "B.Cu")
		(net "VSENSE_PVDDIO_P1_DP")
	)
	(arc
		(start 90.71229 -287.350454)
		(mid 90.597614 -287.21712)
		(end 90.556334 -287.046162)
		(width 0.0762)
		(layer "B.Cu")
		(net "VSENSE_PVDDIO_P1_DP")
	)
	(arc
		(start 91.026488 -289.47618)
		(mid 91.068037 -289.304758)
		(end 91.18346 -289.17138)
		(width 0.0762)
		(layer "B.Cu")
		(net "VSENSE_PVDDIO_P1_DP")
	)
	(arc
		(start 96.666304 -271.656302)
		(mid 96.707559 -271.485331)
		(end 96.82226 -271.35201)
		(width 0.0762)
		(layer "B.Cu")
		(net "VSENSE_PVDDIO_P1_DP")
	)
	(arc
		(start 91.026488 -292.716204)
		(mid 91.068037 -292.544782)
		(end 91.18346 -292.411404)
		(width 0.0762)
		(layer "B.Cu")
		(net "VSENSE_PVDDIO_P1_DP")
	)
	(arc
		(start 92.19311 -279.410922)
		(mid 92.371923 -279.208572)
		(end 92.436442 -278.946356)
		(width 0.0762)
		(layer "B.Cu")
		(net "VSENSE_PVDDIO_P1_DP")
	)
	(arc
		(start 94.070424 -276.172676)
		(mid 94.251076 -275.969931)
		(end 94.316296 -275.706332)
		(width 0.0762)
		(layer "B.Cu")
		(net "VSENSE_PVDDIO_P1_DP")
	)
	(arc
		(start 91.253056 -292.370764)
		(mid 91.496383 -291.906198)
		(end 91.253056 -291.441632)
		(width 0.0762)
		(layer "B.Cu")
		(net "VSENSE_PVDDIO_P1_DP")
	)
	(arc
		(start 94.543118 -275.360892)
		(mid 94.721931 -275.158542)
		(end 94.78645 -274.896326)
		(width 0.0762)
		(layer "B.Cu")
		(net "VSENSE_PVDDIO_P1_DP")
	)
	(arc
		(start 90.783156 -293.18077)
		(mid 90.961969 -292.97842)
		(end 91.026488 -292.716204)
		(width 0.0762)
		(layer "B.Cu")
		(net "VSENSE_PVDDIO_P1_DP")
	)
	(arc
		(start 89.14638 -295.956228)
		(mid 89.187635 -295.785257)
		(end 89.302336 -295.651936)
		(width 0.0762)
		(layer "B.Cu")
		(net "VSENSE_PVDDIO_P1_DP")
	)
	(arc
		(start 90.556334 -287.046162)
		(mid 90.597096 -286.876278)
		(end 90.710512 -286.743394)
		(width 0.0762)
		(layer "B.Cu")
		(net "VSENSE_PVDDIO_P1_DP")
	)
	(arc
		(start 92.436442 -278.946356)
		(mid 92.477991 -278.774934)
		(end 92.593414 -278.641556)
		(width 0.0762)
		(layer "B.Cu")
		(net "VSENSE_PVDDIO_P1_DP")
	)
	(arc
		(start 90.71229 -282.490672)
		(mid 90.556362 -282.18638)
		(end 90.71229 -281.882088)
		(width 0.0762)
		(layer "B.Cu")
		(net "VSENSE_PVDDIO_P1_DP")
	)
	(arc
		(start 91.253056 -281.030934)
		(mid 91.431869 -280.828584)
		(end 91.496388 -280.566368)
		(width 0.0762)
		(layer "B.Cu")
		(net "VSENSE_PVDDIO_P1_DP")
	)
	(arc
		(start 93.603064 -276.980904)
		(mid 93.781877 -276.778554)
		(end 93.846396 -276.516338)
		(width 0.0762)
		(layer "B.Cu")
		(net "VSENSE_PVDDIO_P1_DP")
	)
	(arc
		(start 90.71229 -284.110684)
		(mid 90.556362 -283.806392)
		(end 90.71229 -283.5021)
		(width 0.0762)
		(layer "B.Cu")
		(net "VSENSE_PVDDIO_P1_DP")
	)
	(arc
		(start 89.370408 -295.612566)
		(mid 89.55106 -295.409821)
		(end 89.61628 -295.146222)
		(width 0.0762)
		(layer "B.Cu")
		(net "VSENSE_PVDDIO_P1_DP")
	)
	(arc
		(start 91.026488 -291.096192)
		(mid 90.961973 -290.833973)
		(end 90.783156 -290.631626)
		(width 0.0762)
		(layer "B.Cu")
		(net "VSENSE_PVDDIO_P1_DP")
	)
	(arc
		(start 91.026488 -281.376374)
		(mid 91.068037 -281.204952)
		(end 91.18346 -281.071574)
		(width 0.0762)
		(layer "B.Cu")
		(net "VSENSE_PVDDIO_P1_DP")
	)
	(arc
		(start 90.556334 -293.52621)
		(mid 90.597589 -293.355239)
		(end 90.71229 -293.221918)
		(width 0.0762)
		(layer "B.Cu")
		(net "VSENSE_PVDDIO_P1_DP")
	)
	(arc
		(start 96.893126 -271.310862)
		(mid 97.136848 -270.822962)
		(end 96.856296 -270.355314)
		(width 0.0762)
		(layer "B.Cu")
		(net "VSENSE_PVDDIO_P1_DP")
	)
	(arc
		(start 90.086434 -294.336216)
		(mid 90.127983 -294.164794)
		(end 90.243406 -294.031416)
		(width 0.0762)
		(layer "B.Cu")
		(net "VSENSE_PVDDIO_P1_DP")
	)
	(arc
		(start 95.25635 -274.08632)
		(mid 95.297605 -273.915349)
		(end 95.412306 -273.782028)
		(width 0.0762)
		(layer "B.Cu")
		(net "VSENSE_PVDDIO_P1_DP")
	)
	(arc
		(start 92.66301 -278.600916)
		(mid 92.841823 -278.398566)
		(end 92.906342 -278.13635)
		(width 0.0762)
		(layer "B.Cu")
		(net "VSENSE_PVDDIO_P1_DP")
	)
	(arc
		(start 91.720416 -280.222706)
		(mid 91.901068 -280.019961)
		(end 91.966288 -279.756362)
		(width 0.0762)
		(layer "B.Cu")
		(net "VSENSE_PVDDIO_P1_DP")
	)
	(arc
		(start 97.136458 -269.226284)
		(mid 97.178007 -269.054862)
		(end 97.29343 -268.921484)
		(width 0.0762)
		(layer "B.Cu")
		(net "VSENSE_PVDDIO_P1_DP")
	)
	(arc
		(start 90.71229 -290.590478)
		(mid 90.556362 -290.286186)
		(end 90.71229 -289.981894)
		(width 0.0762)
		(layer "B.Cu")
		(net "VSENSE_PVDDIO_P1_DP")
	)
	(arc
		(start 96.855534 -269.715742)
		(mid 97.061211 -269.508449)
		(end 97.136458 -269.226284)
		(width 0.0762)
		(layer "B.Cu")
		(net "VSENSE_PVDDIO_P1_DP")
	)
	(arc
		(start 90.783156 -281.84094)
		(mid 90.961969 -281.63859)
		(end 91.026488 -281.376374)
		(width 0.0762)
		(layer "B.Cu")
		(net "VSENSE_PVDDIO_P1_DP")
	)
	(arc
		(start 95.726504 -273.276314)
		(mid 95.768053 -273.104892)
		(end 95.883476 -272.971514)
		(width 0.0762)
		(layer "B.Cu")
		(net "VSENSE_PVDDIO_P1_DP")
	)
	(arc
		(start 95.483172 -273.74088)
		(mid 95.661985 -273.53853)
		(end 95.726504 -273.276314)
		(width 0.0762)
		(layer "B.Cu")
		(net "VSENSE_PVDDIO_P1_DP")
	)
	(arc
		(start 94.316296 -275.702776)
		(mid 94.365241 -275.520201)
		(end 94.498922 -275.386546)
		(width 0.0762)
		(layer "B.Cu")
		(net "VSENSE_PVDDIO_P1_DP")
	)
	(arc
		(start 90.783156 -283.460952)
		(mid 91.026483 -282.996386)
		(end 90.783156 -282.53182)
		(width 0.0762)
		(layer "B.Cu")
		(net "VSENSE_PVDDIO_P1_DP")
	)
	(arc
		(start 94.78645 -274.896326)
		(mid 94.827999 -274.724904)
		(end 94.943422 -274.591526)
		(width 0.0762)
		(layer "B.Cu")
		(net "VSENSE_PVDDIO_P1_DP")
	)
	(arc
		(start 95.953072 -272.930874)
		(mid 96.131885 -272.728524)
		(end 96.196404 -272.466308)
		(width 0.0762)
		(layer "B.Cu")
		(net "VSENSE_PVDDIO_P1_DP")
	)
	(arc
		(start 93.133164 -277.79091)
		(mid 93.311977 -277.58856)
		(end 93.376496 -277.326344)
		(width 0.0762)
		(layer "B.Cu")
		(net "VSENSE_PVDDIO_P1_DP")
	)
	(arc
		(start 89.80551 -294.825674)
		(mid 90.011187 -294.618381)
		(end 90.086434 -294.336216)
		(width 0.0762)
		(layer "B.Cu")
		(net "VSENSE_PVDDIO_P1_DP")
	)
	(arc
		(start 91.181428 -288.159952)
		(mid 91.067499 -288.026805)
		(end 91.026488 -287.856422)
		(width 0.0762)
		(layer "B.Cu")
		(net "VSENSE_PVDDIO_P1_DP")
	)
	(arc
		(start 91.18346 -291.400992)
		(mid 91.068033 -291.267616)
		(end 91.026488 -291.096192)
		(width 0.0762)
		(layer "B.Cu")
		(net "VSENSE_PVDDIO_P1_DP")
	)
	(arc
		(start 90.71229 -285.730696)
		(mid 90.556362 -285.426404)
		(end 90.71229 -285.122112)
		(width 0.0762)
		(layer "B.Cu")
		(net "VSENSE_PVDDIO_P1_DP")
	)
	(arc
		(start 95.013018 -274.550886)
		(mid 95.191831 -274.348536)
		(end 95.25635 -274.08632)
		(width 0.0762)
		(layer "B.Cu")
		(net "VSENSE_PVDDIO_P1_DP")
	)
	(arc
		(start 89.61628 -295.146222)
		(mid 89.665346 -294.963164)
		(end 89.799414 -294.82923)
		(width 0.0762)
		(layer "B.Cu")
		(net "VSENSE_PVDDIO_P1_DP")
	)
	(arc
		(start 91.966288 -279.754076)
		(mid 92.015562 -279.570385)
		(end 92.150184 -279.436068)
		(width 0.0762)
		(layer "B.Cu")
		(net "VSENSE_PVDDIO_P1_DP")
	)
	(arc
		(start 90.783156 -286.700976)
		(mid 91.026483 -286.23641)
		(end 90.783156 -285.771844)
		(width 0.0762)
		(layer "B.Cu")
		(net "VSENSE_PVDDIO_P1_DP")
	)
	(arc
		(start 96.420432 -272.122646)
		(mid 96.601084 -271.919901)
		(end 96.666304 -271.656302)
		(width 0.0762)
		(layer "B.Cu")
		(net "VSENSE_PVDDIO_P1_DP")
	)
	(arc
		(start 93.376496 -277.326344)
		(mid 93.418045 -277.154922)
		(end 93.533468 -277.021544)
		(width 0.0762)
		(layer "B.Cu")
		(net "VSENSE_PVDDIO_P1_DP")
	)
	(segment
		(start 20.402042 -332.461616)
		(end 20.75815 -332.455266)
		(width 0.254)
		(layer "In11.Cu")
		(net "VSENSE_PVDDIO_P1_DP")
	)
	(segment
		(start 22.924262 -350.347026)
		(end 23.641812 -349.629476)
		(width 0.254)
		(layer "In11.Cu")
		(net "VSENSE_PVDDIO_P1_DP")
	)
	(segment
		(start 28.46832 -361.061)
		(end 26.118566 -358.711246)
		(width 0.254)
		(layer "In11.Cu")
		(net "VSENSE_PVDDIO_P1_DP")
	)
	(segment
		(start 19.027902 -333.41437)
		(end 19.980656 -332.461616)
		(width 0.254)
		(layer "In11.Cu")
		(net "VSENSE_PVDDIO_P1_DP")
	)
	(segment
		(start 23.641812 -346.681298)
		(end 23.386542 -346.06484)
		(width 0.254)
		(layer "In11.Cu")
		(net "VSENSE_PVDDIO_P1_DP")
	)
	(segment
		(start 35.03295 -361.061)
		(end 28.46832 -361.061)
		(width 0.254)
		(layer "In11.Cu")
		(net "VSENSE_PVDDIO_P1_DP")
	)
	(segment
		(start 22.924262 -352.988372)
		(end 22.924262 -350.347026)
		(width 0.254)
		(layer "In11.Cu")
		(net "VSENSE_PVDDIO_P1_DP")
	)
	(segment
		(start 23.386542 -346.06484)
		(end 19.027902 -341.7062)
		(width 0.254)
		(layer "In11.Cu")
		(net "VSENSE_PVDDIO_P1_DP")
	)
	(segment
		(start 19.027902 -341.7062)
		(end 19.027902 -333.41437)
		(width 0.254)
		(layer "In11.Cu")
		(net "VSENSE_PVDDIO_P1_DP")
	)
	(segment
		(start 36.83 -359.26395)
		(end 35.03295 -361.061)
		(width 0.254)
		(layer "In11.Cu")
		(net "VSENSE_PVDDIO_P1_DP")
	)
	(segment
		(start 26.118566 -356.182676)
		(end 22.924262 -352.988372)
		(width 0.254)
		(layer "In11.Cu")
		(net "VSENSE_PVDDIO_P1_DP")
	)
	(segment
		(start 20.75815 -332.455266)
		(end 21.070062 -332.132178)
		(width 0.254)
		(layer "In11.Cu")
		(net "VSENSE_PVDDIO_P1_DP")
	)
	(segment
		(start 26.118566 -358.711246)
		(end 26.118566 -356.182676)
		(width 0.254)
		(layer "In11.Cu")
		(net "VSENSE_PVDDIO_P1_DP")
	)
	(segment
		(start 19.980656 -332.461616)
		(end 20.402042 -332.461616)
		(width 0.254)
		(layer "In11.Cu")
		(net "VSENSE_PVDDIO_P1_DP")
	)
	(segment
		(start 23.641812 -349.629476)
		(end 23.641812 -346.681298)
		(width 0.254)
		(layer "In11.Cu")
		(net "VSENSE_PVDDIO_P1_DP")
	)
	(segment
		(start 313.572398 -359.680002)
		(end 313.009026 -359.680002)
		(width 0.1778)
		(layer "F.Cu")
		(net "VSENSE_PVDDIO_P0_VSEN1")
	)
	(segment
		(start 314.452 -359.156)
		(end 314.0964 -359.156)
		(width 0.1778)
		(layer "F.Cu")
		(net "VSENSE_PVDDIO_P0_VSEN1")
	)
	(segment
		(start 315.74105 -357.251)
		(end 316.31255 -357.251)
		(width 0.254)
		(layer "F.Cu")
		(net "VSENSE_PVDDIO_P0_VSEN1")
	)
	(segment
		(start 316.31255 -357.251)
		(end 316.3316 -357.27005)
		(width 0.254)
		(layer "F.Cu")
		(net "VSENSE_PVDDIO_P0_VSEN1")
	)
	(segment
		(start 316.3316 -357.27005)
		(end 316.738 -357.27005)
		(width 0.254)
		(layer "F.Cu")
		(net "VSENSE_PVDDIO_P0_VSEN1")
	)
	(segment
		(start 315.74105 -357.251)
		(end 315.74105 -357.86695)
		(width 0.254)
		(layer "F.Cu")
		(net "VSENSE_PVDDIO_P0_VSEN1")
	)
	(segment
		(start 315.74105 -357.86695)
		(end 314.706 -358.902)
		(width 0.254)
		(layer "F.Cu")
		(net "VSENSE_PVDDIO_P0_VSEN1")
	)
	(segment
		(start 314.0964 -359.156)
		(end 313.572398 -359.680002)
		(width 0.1778)
		(layer "F.Cu")
		(net "VSENSE_PVDDIO_P0_VSEN1")
	)
	(segment
		(start 314.706 -358.902)
		(end 314.452 -359.156)
		(width 0.1778)
		(layer "F.Cu")
		(net "VSENSE_PVDDIO_P0_VSEN1")
	)
	(segment
		(start 266.862306 -332.015846)
		(end 266.876022 -332.029562)
		(width 0.254)
		(layer "F.Cu")
		(net "VSENSE_PVDDIO_P0_DP")
	)
	(segment
		(start 346.12199 -268.416024)
		(end 345.921076 -268.416024)
		(width 0.254)
		(layer "F.Cu")
		(net "VSENSE_PVDDIO_P0_DP")
	)
	(segment
		(start 316.738 -356.46995)
		(end 317.3984 -356.46995)
		(width 0.254)
		(layer "F.Cu")
		(net "VSENSE_PVDDIO_P0_DP")
	)
	(segment
		(start 346.387928 -268.150086)
		(end 346.12199 -268.416024)
		(width 0.254)
		(layer "F.Cu")
		(net "VSENSE_PVDDIO_P0_DP")
	)
	(segment
		(start 268.013434 -332.029562)
		(end 268.623034 -332.029562)
		(width 0.254)
		(layer "F.Cu")
		(net "VSENSE_PVDDIO_P0_DP")
	)
	(segment
		(start 266.876022 -332.029562)
		(end 268.013434 -332.029562)
		(width 0.254)
		(layer "F.Cu")
		(net "VSENSE_PVDDIO_P0_DP")
	)
	(via
		(at 268.013434 -332.029562)
		(size 0.508)
		(drill 0.254)
		(layers "F.Cu" "B.Cu")
		(net "VSENSE_PVDDIO_P0_DP")
	)
	(via
		(at 345.921076 -268.416024)
		(size 0.4064)
		(drill 0.2032)
		(layers "F.Cu" "B.Cu")
		(net "VSENSE_PVDDIO_P0_DP")
	)
	(via
		(at 317.3984 -356.46995)
		(size 0.508)
		(drill 0.254)
		(layers "F.Cu" "B.Cu")
		(net "VSENSE_PVDDIO_P0_DP")
	)
	(segment
		(start 316.9158 -365.3028)
		(end 312.8772 -369.3414)
		(width 0.254)
		(layer "In2.Cu")
		(net "VSENSE_PVDDIO_P0_DP")
	)
	(segment
		(start 267.1064 -332.3082)
		(end 267.734796 -332.3082)
		(width 0.254)
		(layer "In2.Cu")
		(net "VSENSE_PVDDIO_P0_DP")
	)
	(segment
		(start 284.322012 -365.9378)
		(end 270.74368 -352.359468)
		(width 0.254)
		(layer "In2.Cu")
		(net "VSENSE_PVDDIO_P0_DP")
	)
	(segment
		(start 266.6492 -332.7654)
		(end 267.1064 -332.3082)
		(width 0.254)
		(layer "In2.Cu")
		(net "VSENSE_PVDDIO_P0_DP")
	)
	(segment
		(start 270.74368 -352.359468)
		(end 266.712192 -352.359468)
		(width 0.254)
		(layer "In2.Cu")
		(net "VSENSE_PVDDIO_P0_DP")
	)
	(segment
		(start 267.734796 -332.3082)
		(end 268.013434 -332.029562)
		(width 0.254)
		(layer "In2.Cu")
		(net "VSENSE_PVDDIO_P0_DP")
	)
	(segment
		(start 266.712192 -352.359468)
		(end 262.922258 -348.569534)
		(width 0.254)
		(layer "In2.Cu")
		(net "VSENSE_PVDDIO_P0_DP")
	)
	(segment
		(start 299.2628 -365.9378)
		(end 284.322012 -365.9378)
		(width 0.254)
		(layer "In2.Cu")
		(net "VSENSE_PVDDIO_P0_DP")
	)
	(segment
		(start 312.8772 -369.3414)
		(end 302.6664 -369.3414)
		(width 0.254)
		(layer "In2.Cu")
		(net "VSENSE_PVDDIO_P0_DP")
	)
	(segment
		(start 316.9158 -356.95255)
		(end 316.9158 -365.3028)
		(width 0.254)
		(layer "In2.Cu")
		(net "VSENSE_PVDDIO_P0_DP")
	)
	(segment
		(start 302.6664 -369.3414)
		(end 299.2628 -365.9378)
		(width 0.254)
		(layer "In2.Cu")
		(net "VSENSE_PVDDIO_P0_DP")
	)
	(segment
		(start 262.922258 -340.48319)
		(end 266.6492 -336.756248)
		(width 0.254)
		(layer "In2.Cu")
		(net "VSENSE_PVDDIO_P0_DP")
	)
	(segment
		(start 266.6492 -336.756248)
		(end 266.6492 -332.7654)
		(width 0.254)
		(layer "In2.Cu")
		(net "VSENSE_PVDDIO_P0_DP")
	)
	(segment
		(start 317.3984 -356.46995)
		(end 316.9158 -356.95255)
		(width 0.254)
		(layer "In2.Cu")
		(net "VSENSE_PVDDIO_P0_DP")
	)
	(segment
		(start 262.922258 -348.569534)
		(end 262.922258 -340.48319)
		(width 0.254)
		(layer "In2.Cu")
		(net "VSENSE_PVDDIO_P0_DP")
	)
	(segment
		(start 342.44407 -273.763486)
		(end 342.483186 -273.740626)
		(width 0.0889)
		(layer "In6.Cu")
		(net "VSENSE_PVDDIO_P0_DP")
	)
	(segment
		(start 339.62467 -285.10484)
		(end 339.624924 -285.104586)
		(width 0.0889)
		(layer "In6.Cu")
		(net "VSENSE_PVDDIO_P0_DP")
	)
	(segment
		(start 345.263978 -268.90345)
		(end 345.302586 -268.880844)
		(width 0.0889)
		(layer "In6.Cu")
		(net "VSENSE_PVDDIO_P0_DP")
	)
	(segment
		(start 337.473544 -297.75531)
		(end 338.035392 -297.193462)
		(width 0.254)
		(layer "In6.Cu")
		(net "VSENSE_PVDDIO_P0_DP")
	)
	(segment
		(start 340.08949 -277.819104)
		(end 340.095332 -277.815802)
		(width 0.0889)
		(layer "In6.Cu")
		(net "VSENSE_PVDDIO_P0_DP")
	)
	(segment
		(start 341.473536 -275.401278)
		(end 341.504016 -275.383498)
		(width 0.0889)
		(layer "In6.Cu")
		(net "VSENSE_PVDDIO_P0_DP")
	)
	(segment
		(start 340.095332 -277.815802)
		(end 340.095586 -277.815548)
		(width 0.0889)
		(layer "In6.Cu")
		(net "VSENSE_PVDDIO_P0_DP")
	)
	(segment
		(start 339.624924 -282.50769)
		(end 339.62467 -282.507436)
		(width 0.0889)
		(layer "In6.Cu")
		(net "VSENSE_PVDDIO_P0_DP")
	)
	(segment
		(start 310.204358 -319.475612)
		(end 310.204358 -318.081406)
		(width 0.254)
		(layer "In6.Cu")
		(net "VSENSE_PVDDIO_P0_DP")
	)
	(segment
		(start 344.795348 -269.715742)
		(end 344.795602 -269.715488)
		(width 0.0889)
		(layer "In6.Cu")
		(net "VSENSE_PVDDIO_P0_DP")
	)
	(segment
		(start 339.62467 -280.887424)
		(end 339.623908 -280.88717)
		(width 0.0889)
		(layer "In6.Cu")
		(net "VSENSE_PVDDIO_P0_DP")
	)
	(segment
		(start 338.213954 -295.633394)
		(end 338.25307 -295.610534)
		(width 0.0889)
		(layer "In6.Cu")
		(net "VSENSE_PVDDIO_P0_DP")
	)
	(segment
		(start 340.563962 -277.00351)
		(end 340.603078 -276.98065)
		(width 0.0889)
		(layer "In6.Cu")
		(net "VSENSE_PVDDIO_P0_DP")
	)
	(segment
		(start 310.204358 -318.081406)
		(end 330.530454 -297.75531)
		(width 0.254)
		(layer "In6.Cu")
		(net "VSENSE_PVDDIO_P0_DP")
	)
	(segment
		(start 265.9507 -332.051406)
		(end 265.9507 -329.603862)
		(width 0.254)
		(layer "In6.Cu")
		(net "VSENSE_PVDDIO_P0_DP")
	)
	(segment
		(start 343.352374 -272.161762)
		(end 343.384124 -272.143474)
		(width 0.0889)
		(layer "In6.Cu")
		(net "VSENSE_PVDDIO_P0_DP")
	)
	(segment
		(start 345.542108 -268.486636)
		(end 345.61272 -268.416024)
		(width 0.0889)
		(layer "In6.Cu")
		(net "VSENSE_PVDDIO_P0_DP")
	)
	(segment
		(start 344.320622 -270.527272)
		(end 344.324686 -270.524986)
		(width 0.0889)
		(layer "In6.Cu")
		(net "VSENSE_PVDDIO_P0_DP")
	)
	(segment
		(start 339.644736 -282.51912)
		(end 339.624924 -282.50769)
		(width 0.0889)
		(layer "In6.Cu")
		(net "VSENSE_PVDDIO_P0_DP")
	)
	(segment
		(start 343.384124 -272.143474)
		(end 343.42324 -272.120614)
		(width 0.0889)
		(layer "In6.Cu")
		(net "VSENSE_PVDDIO_P0_DP")
	)
	(segment
		(start 339.620606 -293.207186)
		(end 339.62467 -293.2049)
		(width 0.0889)
		(layer "In6.Cu")
		(net "VSENSE_PVDDIO_P0_DP")
	)
	(segment
		(start 339.62467 -285.747206)
		(end 339.623908 -285.746698)
		(width 0.0889)
		(layer "In6.Cu")
		(net "VSENSE_PVDDIO_P0_DP")
	)
	(segment
		(start 330.530454 -297.75531)
		(end 337.473544 -297.75531)
		(width 0.254)
		(layer "In6.Cu")
		(net "VSENSE_PVDDIO_P0_DP")
	)
	(segment
		(start 339.63864 -280.895806)
		(end 339.624924 -280.887678)
		(width 0.0889)
		(layer "In6.Cu")
		(net "VSENSE_PVDDIO_P0_DP")
	)
	(segment
		(start 339.642958 -284.135576)
		(end 339.626194 -284.125416)
		(width 0.0889)
		(layer "In6.Cu")
		(net "VSENSE_PVDDIO_P0_DP")
	)
	(segment
		(start 341.94242 -274.59178)
		(end 341.97417 -274.573492)
		(width 0.0889)
		(layer "In6.Cu")
		(net "VSENSE_PVDDIO_P0_DP")
	)
	(segment
		(start 339.624924 -285.104586)
		(end 339.635592 -285.09849)
		(width 0.0889)
		(layer "In6.Cu")
		(net "VSENSE_PVDDIO_P0_DP")
	)
	(segment
		(start 339.623908 -291.585142)
		(end 339.62467 -291.584634)
		(width 0.0889)
		(layer "In6.Cu")
		(net "VSENSE_PVDDIO_P0_DP")
	)
	(segment
		(start 341.504016 -275.383498)
		(end 341.543132 -275.360638)
		(width 0.0889)
		(layer "In6.Cu")
		(net "VSENSE_PVDDIO_P0_DP")
	)
	(segment
		(start 339.592412 -283.501846)
		(end 339.624162 -283.483558)
		(width 0.0889)
		(layer "In6.Cu")
		(net "VSENSE_PVDDIO_P0_DP")
	)
	(segment
		(start 343.854024 -271.333468)
		(end 343.89314 -271.310608)
		(width 0.0889)
		(layer "In6.Cu")
		(net "VSENSE_PVDDIO_P0_DP")
	)
	(segment
		(start 339.624162 -283.483558)
		(end 339.67928 -283.449522)
		(width 0.0889)
		(layer "In6.Cu")
		(net "VSENSE_PVDDIO_P0_DP")
	)
	(segment
		(start 274.67941 -320.875152)
		(end 308.804818 -320.875152)
		(width 0.254)
		(layer "In6.Cu")
		(net "VSENSE_PVDDIO_P0_DP")
	)
	(segment
		(start 339.624162 -288.343594)
		(end 339.660484 -288.322512)
		(width 0.0889)
		(layer "In6.Cu")
		(net "VSENSE_PVDDIO_P0_DP")
	)
	(segment
		(start 339.590634 -288.363152)
		(end 339.624162 -288.343594)
		(width 0.0889)
		(layer "In6.Cu")
		(net "VSENSE_PVDDIO_P0_DP")
	)
	(segment
		(start 339.64753 -292.23843)
		(end 339.62594 -292.225476)
		(width 0.0889)
		(layer "In6.Cu")
		(net "VSENSE_PVDDIO_P0_DP")
	)
	(segment
		(start 339.62467 -280.244804)
		(end 339.624924 -280.24455)
		(width 0.0889)
		(layer "In6.Cu")
		(net "VSENSE_PVDDIO_P0_DP")
	)
	(segment
		(start 308.804818 -320.875152)
		(end 310.204358 -319.475612)
		(width 0.254)
		(layer "In6.Cu")
		(net "VSENSE_PVDDIO_P0_DP")
	)
	(segment
		(start 339.625178 -287.36671)
		(end 339.624924 -287.366456)
		(width 0.0889)
		(layer "In6.Cu")
		(net "VSENSE_PVDDIO_P0_DP")
	)
	(segment
		(start 339.62467 -288.986722)
		(end 339.620606 -288.984436)
		(width 0.0889)
		(layer "In6.Cu")
		(net "VSENSE_PVDDIO_P0_DP")
	)
	(segment
		(start 339.624924 -281.86507)
		(end 339.63864 -281.856942)
		(width 0.0889)
		(layer "In6.Cu")
		(net "VSENSE_PVDDIO_P0_DP")
	)
	(segment
		(start 339.590634 -286.74314)
		(end 339.624162 -286.723582)
		(width 0.0889)
		(layer "In6.Cu")
		(net "VSENSE_PVDDIO_P0_DP")
	)
	(segment
		(start 341.97417 -274.573492)
		(end 342.010492 -274.55241)
		(width 0.0889)
		(layer "In6.Cu")
		(net "VSENSE_PVDDIO_P0_DP")
	)
	(segment
		(start 345.302586 -268.880844)
		(end 345.303094 -268.88059)
		(width 0.0889)
		(layer "In6.Cu")
		(net "VSENSE_PVDDIO_P0_DP")
	)
	(segment
		(start 338.035392 -297.193462)
		(end 338.035392 -296.763186)
		(width 0.254)
		(layer "In6.Cu")
		(net "VSENSE_PVDDIO_P0_DP")
	)
	(segment
		(start 339.62467 -291.584634)
		(end 339.624924 -291.58438)
		(width 0.0889)
		(layer "In6.Cu")
		(net "VSENSE_PVDDIO_P0_DP")
	)
	(segment
		(start 339.62467 -282.507436)
		(end 339.623908 -282.507182)
		(width 0.0889)
		(layer "In6.Cu")
		(net "VSENSE_PVDDIO_P0_DP")
	)
	(segment
		(start 338.181188 -295.652444)
		(end 338.213954 -295.633394)
		(width 0.0889)
		(layer "In6.Cu")
		(net "VSENSE_PVDDIO_P0_DP")
	)
	(segment
		(start 339.62467 -293.2049)
		(end 339.624924 -293.2049)
		(width 0.0889)
		(layer "In6.Cu")
		(net "VSENSE_PVDDIO_P0_DP")
	)
	(segment
		(start 266.212066 -332.312772)
		(end 265.9507 -332.051406)
		(width 0.254)
		(layer "In6.Cu")
		(net "VSENSE_PVDDIO_P0_DP")
	)
	(segment
		(start 339.623908 -289.965384)
		(end 339.62467 -289.964876)
		(width 0.0889)
		(layer "In6.Cu")
		(net "VSENSE_PVDDIO_P0_DP")
	)
	(segment
		(start 344.324686 -270.524986)
		(end 344.32494 -270.524986)
		(width 0.0889)
		(layer "In6.Cu")
		(net "VSENSE_PVDDIO_P0_DP")
	)
	(segment
		(start 265.9507 -329.603862)
		(end 274.67941 -320.875152)
		(width 0.254)
		(layer "In6.Cu")
		(net "VSENSE_PVDDIO_P0_DP")
	)
	(segment
		(start 339.626194 -284.125416)
		(end 339.623908 -284.124146)
		(width 0.0889)
		(layer "In6.Cu")
		(net "VSENSE_PVDDIO_P0_DP")
	)
	(segment
		(start 339.627718 -279.263094)
		(end 339.623908 -279.261062)
		(width 0.0889)
		(layer "In6.Cu")
		(net "VSENSE_PVDDIO_P0_DP")
	)
	(segment
		(start 340.533482 -277.02129)
		(end 340.563962 -277.00351)
		(width 0.0889)
		(layer "In6.Cu")
		(net "VSENSE_PVDDIO_P0_DP")
	)
	(segment
		(start 343.823544 -271.351248)
		(end 343.854024 -271.333468)
		(width 0.0889)
		(layer "In6.Cu")
		(net "VSENSE_PVDDIO_P0_DP")
	)
	(segment
		(start 339.123528 -294.031162)
		(end 339.193124 -293.990522)
		(width 0.0889)
		(layer "In6.Cu")
		(net "VSENSE_PVDDIO_P0_DP")
	)
	(segment
		(start 339.623908 -281.865578)
		(end 339.62467 -281.86507)
		(width 0.0889)
		(layer "In6.Cu")
		(net "VSENSE_PVDDIO_P0_DP")
	)
	(segment
		(start 339.624924 -280.24455)
		(end 339.641434 -280.234898)
		(width 0.0889)
		(layer "In6.Cu")
		(net "VSENSE_PVDDIO_P0_DP")
	)
	(segment
		(start 339.624924 -288.986976)
		(end 339.62467 -288.986722)
		(width 0.0889)
		(layer "In6.Cu")
		(net "VSENSE_PVDDIO_P0_DP")
	)
	(segment
		(start 338.026248 -296.754042)
		(end 338.026248 -295.955974)
		(width 0.0889)
		(layer "In6.Cu")
		(net "VSENSE_PVDDIO_P0_DP")
	)
	(segment
		(start 339.640672 -290.613592)
		(end 339.626194 -290.604956)
		(width 0.0889)
		(layer "In6.Cu")
		(net "VSENSE_PVDDIO_P0_DP")
	)
	(segment
		(start 339.624924 -287.366456)
		(end 339.620098 -287.363662)
		(width 0.0889)
		(layer "In6.Cu")
		(net "VSENSE_PVDDIO_P0_DP")
	)
	(segment
		(start 339.624924 -293.2049)
		(end 339.63864 -293.196772)
		(width 0.0889)
		(layer "In6.Cu")
		(net "VSENSE_PVDDIO_P0_DP")
	)
	(segment
		(start 339.62467 -281.86507)
		(end 339.624924 -281.86507)
		(width 0.0889)
		(layer "In6.Cu")
		(net "VSENSE_PVDDIO_P0_DP")
	)
	(segment
		(start 339.626194 -290.604956)
		(end 339.623908 -290.603686)
		(width 0.0889)
		(layer "In6.Cu")
		(net "VSENSE_PVDDIO_P0_DP")
	)
	(segment
		(start 339.624162 -286.723582)
		(end 339.660484 -286.7025)
		(width 0.0889)
		(layer "In6.Cu")
		(net "VSENSE_PVDDIO_P0_DP")
	)
	(segment
		(start 339.623908 -280.245312)
		(end 339.62467 -280.244804)
		(width 0.0889)
		(layer "In6.Cu")
		(net "VSENSE_PVDDIO_P0_DP")
	)
	(segment
		(start 339.623908 -278.625554)
		(end 339.62467 -278.625046)
		(width 0.0889)
		(layer "In6.Cu")
		(net "VSENSE_PVDDIO_P0_DP")
	)
	(segment
		(start 344.789506 -269.719044)
		(end 344.795348 -269.715742)
		(width 0.0889)
		(layer "In6.Cu")
		(net "VSENSE_PVDDIO_P0_DP")
	)
	(segment
		(start 342.91397 -272.95348)
		(end 342.953086 -272.93062)
		(width 0.0889)
		(layer "In6.Cu")
		(net "VSENSE_PVDDIO_P0_DP")
	)
	(segment
		(start 338.035392 -296.763186)
		(end 338.026248 -296.754042)
		(width 0.0889)
		(layer "In6.Cu")
		(net "VSENSE_PVDDIO_P0_DP")
	)
	(segment
		(start 339.623908 -285.105094)
		(end 339.62467 -285.10484)
		(width 0.0889)
		(layer "In6.Cu")
		(net "VSENSE_PVDDIO_P0_DP")
	)
	(segment
		(start 341.002366 -276.211792)
		(end 341.034116 -276.193504)
		(width 0.0889)
		(layer "In6.Cu")
		(net "VSENSE_PVDDIO_P0_DP")
	)
	(segment
		(start 338.652358 -294.841676)
		(end 338.684108 -294.823388)
		(width 0.0889)
		(layer "In6.Cu")
		(net "VSENSE_PVDDIO_P0_DP")
	)
	(segment
		(start 339.62467 -289.964876)
		(end 339.624924 -289.964876)
		(width 0.0889)
		(layer "In6.Cu")
		(net "VSENSE_PVDDIO_P0_DP")
	)
	(segment
		(start 339.624924 -291.58438)
		(end 339.634322 -291.578792)
		(width 0.0889)
		(layer "In6.Cu")
		(net "VSENSE_PVDDIO_P0_DP")
	)
	(segment
		(start 342.41232 -273.781774)
		(end 342.44407 -273.763486)
		(width 0.0889)
		(layer "In6.Cu")
		(net "VSENSE_PVDDIO_P0_DP")
	)
	(segment
		(start 339.62467 -278.625046)
		(end 339.624924 -278.625046)
		(width 0.0889)
		(layer "In6.Cu")
		(net "VSENSE_PVDDIO_P0_DP")
	)
	(segment
		(start 341.034116 -276.193504)
		(end 341.073232 -276.170644)
		(width 0.0889)
		(layer "In6.Cu")
		(net "VSENSE_PVDDIO_P0_DP")
	)
	(segment
		(start 342.88349 -272.97126)
		(end 342.91397 -272.95348)
		(width 0.0889)
		(layer "In6.Cu")
		(net "VSENSE_PVDDIO_P0_DP")
	)
	(segment
		(start 339.624924 -285.747206)
		(end 339.62467 -285.747206)
		(width 0.0889)
		(layer "In6.Cu")
		(net "VSENSE_PVDDIO_P0_DP")
	)
	(segment
		(start 339.624924 -280.887678)
		(end 339.62467 -280.887424)
		(width 0.0889)
		(layer "In6.Cu")
		(net "VSENSE_PVDDIO_P0_DP")
	)
	(segment
		(start 339.62594 -292.225476)
		(end 339.623908 -292.224206)
		(width 0.0889)
		(layer "In6.Cu")
		(net "VSENSE_PVDDIO_P0_DP")
	)
	(segment
		(start 267.730224 -332.312772)
		(end 266.212066 -332.312772)
		(width 0.254)
		(layer "In6.Cu")
		(net "VSENSE_PVDDIO_P0_DP")
	)
	(segment
		(start 338.684108 -294.823388)
		(end 338.723224 -294.800528)
		(width 0.0889)
		(layer "In6.Cu")
		(net "VSENSE_PVDDIO_P0_DP")
	)
	(segment
		(start 339.653372 -279.278842)
		(end 339.627718 -279.263094)
		(width 0.0889)
		(layer "In6.Cu")
		(net "VSENSE_PVDDIO_P0_DP")
	)
	(segment
		(start 345.61272 -268.416024)
		(end 345.921076 -268.416024)
		(width 0.0889)
		(layer "In6.Cu")
		(net "VSENSE_PVDDIO_P0_DP")
	)
	(segment
		(start 268.013434 -332.029562)
		(end 267.730224 -332.312772)
		(width 0.254)
		(layer "In6.Cu")
		(net "VSENSE_PVDDIO_P0_DP")
	)
	(segment
		(start 345.233498 -268.92123)
		(end 345.263978 -268.90345)
		(width 0.0889)
		(layer "In6.Cu")
		(net "VSENSE_PVDDIO_P0_DP")
	)
	(arc
		(start 339.906356 -287.856168)
		(mid 339.831064 -287.573922)
		(end 339.625178 -287.36671)
		(width 0.0889)
		(layer "In6.Cu")
		(net "VSENSE_PVDDIO_P0_DP")
	)
	(arc
		(start 338.026248 -295.955974)
		(mid 338.067214 -295.785568)
		(end 338.181188 -295.652444)
		(width 0.0889)
		(layer "In6.Cu")
		(net "VSENSE_PVDDIO_P0_DP")
	)
	(arc
		(start 341.543132 -275.360638)
		(mid 341.721945 -275.158288)
		(end 341.786464 -274.896072)
		(width 0.0889)
		(layer "In6.Cu")
		(net "VSENSE_PVDDIO_P0_DP")
	)
	(arc
		(start 342.726518 -273.27606)
		(mid 342.768067 -273.104638)
		(end 342.88349 -272.97126)
		(width 0.0889)
		(layer "In6.Cu")
		(net "VSENSE_PVDDIO_P0_DP")
	)
	(arc
		(start 339.906356 -278.136096)
		(mid 339.955422 -277.953038)
		(end 340.08949 -277.819104)
		(width 0.0889)
		(layer "In6.Cu")
		(net "VSENSE_PVDDIO_P0_DP")
	)
	(arc
		(start 339.436456 -287.045908)
		(mid 339.477218 -286.876024)
		(end 339.590634 -286.74314)
		(width 0.0889)
		(layer "In6.Cu")
		(net "VSENSE_PVDDIO_P0_DP")
	)
	(arc
		(start 339.623908 -284.124146)
		(mid 339.438575 -283.821577)
		(end 339.592412 -283.501846)
		(width 0.0889)
		(layer "In6.Cu")
		(net "VSENSE_PVDDIO_P0_DP")
	)
	(arc
		(start 339.193124 -293.990522)
		(mid 339.371937 -293.788172)
		(end 339.436456 -293.525956)
		(width 0.0889)
		(layer "In6.Cu")
		(net "VSENSE_PVDDIO_P0_DP")
	)
	(arc
		(start 339.624924 -289.964876)
		(mid 339.906509 -289.475926)
		(end 339.624924 -288.986976)
		(width 0.0889)
		(layer "In6.Cu")
		(net "VSENSE_PVDDIO_P0_DP")
	)
	(arc
		(start 339.67928 -283.449522)
		(mid 339.918479 -282.974745)
		(end 339.644736 -282.51912)
		(width 0.0889)
		(layer "In6.Cu")
		(net "VSENSE_PVDDIO_P0_DP")
	)
	(arc
		(start 339.620098 -287.363662)
		(mid 339.485687 -287.229404)
		(end 339.436456 -287.045908)
		(width 0.0889)
		(layer "In6.Cu")
		(net "VSENSE_PVDDIO_P0_DP")
	)
	(arc
		(start 339.620606 -288.984436)
		(mid 339.485807 -288.849879)
		(end 339.436456 -288.66592)
		(width 0.0889)
		(layer "In6.Cu")
		(net "VSENSE_PVDDIO_P0_DP")
	)
	(arc
		(start 339.635592 -285.09849)
		(mid 339.913939 -284.619143)
		(end 339.642958 -284.135576)
		(width 0.0889)
		(layer "In6.Cu")
		(net "VSENSE_PVDDIO_P0_DP")
	)
	(arc
		(start 339.623908 -285.746698)
		(mid 339.438541 -285.425896)
		(end 339.623908 -285.105094)
		(width 0.0889)
		(layer "In6.Cu")
		(net "VSENSE_PVDDIO_P0_DP")
	)
	(arc
		(start 345.303094 -268.88059)
		(mid 345.464591 -268.709081)
		(end 345.542108 -268.486636)
		(width 0.0889)
		(layer "In6.Cu")
		(net "VSENSE_PVDDIO_P0_DP")
	)
	(arc
		(start 339.623908 -279.261062)
		(mid 339.440292 -278.943308)
		(end 339.623908 -278.625554)
		(width 0.0889)
		(layer "In6.Cu")
		(net "VSENSE_PVDDIO_P0_DP")
	)
	(arc
		(start 339.660484 -286.7025)
		(mid 339.905982 -286.21509)
		(end 339.624924 -285.747206)
		(width 0.0889)
		(layer "In6.Cu")
		(net "VSENSE_PVDDIO_P0_DP")
	)
	(arc
		(start 339.623908 -290.603686)
		(mid 339.439446 -290.284599)
		(end 339.623908 -289.965384)
		(width 0.0889)
		(layer "In6.Cu")
		(net "VSENSE_PVDDIO_P0_DP")
	)
	(arc
		(start 338.966556 -294.335962)
		(mid 339.008105 -294.16454)
		(end 339.123528 -294.031162)
		(width 0.0889)
		(layer "In6.Cu")
		(net "VSENSE_PVDDIO_P0_DP")
	)
	(arc
		(start 339.436456 -288.66592)
		(mid 339.477218 -288.496036)
		(end 339.590634 -288.363152)
		(width 0.0889)
		(layer "In6.Cu")
		(net "VSENSE_PVDDIO_P0_DP")
	)
	(arc
		(start 339.63864 -281.856942)
		(mid 339.915379 -281.376374)
		(end 339.63864 -280.895806)
		(width 0.0889)
		(layer "In6.Cu")
		(net "VSENSE_PVDDIO_P0_DP")
	)
	(arc
		(start 339.660484 -288.322512)
		(mid 339.841136 -288.119767)
		(end 339.906356 -287.856168)
		(width 0.0889)
		(layer "In6.Cu")
		(net "VSENSE_PVDDIO_P0_DP")
	)
	(arc
		(start 344.795602 -269.715488)
		(mid 345.001279 -269.508195)
		(end 345.076526 -269.22603)
		(width 0.0889)
		(layer "In6.Cu")
		(net "VSENSE_PVDDIO_P0_DP")
	)
	(arc
		(start 339.623908 -292.224206)
		(mid 339.43926 -291.904674)
		(end 339.623908 -291.585142)
		(width 0.0889)
		(layer "In6.Cu")
		(net "VSENSE_PVDDIO_P0_DP")
	)
	(arc
		(start 339.63864 -293.196772)
		(mid 339.916201 -292.720118)
		(end 339.64753 -292.23843)
		(width 0.0889)
		(layer "In6.Cu")
		(net "VSENSE_PVDDIO_P0_DP")
	)
	(arc
		(start 340.37651 -277.32609)
		(mid 340.418059 -277.154668)
		(end 340.533482 -277.02129)
		(width 0.0889)
		(layer "In6.Cu")
		(net "VSENSE_PVDDIO_P0_DP")
	)
	(arc
		(start 339.436456 -293.525956)
		(mid 339.485796 -293.341878)
		(end 339.620606 -293.207186)
		(width 0.0889)
		(layer "In6.Cu")
		(net "VSENSE_PVDDIO_P0_DP")
	)
	(arc
		(start 338.25307 -295.610534)
		(mid 338.431883 -295.408184)
		(end 338.496402 -295.145968)
		(width 0.0889)
		(layer "In6.Cu")
		(net "VSENSE_PVDDIO_P0_DP")
	)
	(arc
		(start 345.076526 -269.22603)
		(mid 345.118075 -269.054608)
		(end 345.233498 -268.92123)
		(width 0.0889)
		(layer "In6.Cu")
		(net "VSENSE_PVDDIO_P0_DP")
	)
	(arc
		(start 339.624924 -278.625046)
		(mid 339.830992 -278.418183)
		(end 339.906356 -278.136096)
		(width 0.0889)
		(layer "In6.Cu")
		(net "VSENSE_PVDDIO_P0_DP")
	)
	(arc
		(start 344.606372 -270.036036)
		(mid 344.655438 -269.852978)
		(end 344.789506 -269.719044)
		(width 0.0889)
		(layer "In6.Cu")
		(net "VSENSE_PVDDIO_P0_DP")
	)
	(arc
		(start 342.483186 -273.740626)
		(mid 342.661999 -273.538276)
		(end 342.726518 -273.27606)
		(width 0.0889)
		(layer "In6.Cu")
		(net "VSENSE_PVDDIO_P0_DP")
	)
	(arc
		(start 342.256364 -274.086066)
		(mid 342.297619 -273.915095)
		(end 342.41232 -273.781774)
		(width 0.0889)
		(layer "In6.Cu")
		(net "VSENSE_PVDDIO_P0_DP")
	)
	(arc
		(start 339.634322 -291.578792)
		(mid 339.913206 -291.098052)
		(end 339.640672 -290.613592)
		(width 0.0889)
		(layer "In6.Cu")
		(net "VSENSE_PVDDIO_P0_DP")
	)
	(arc
		(start 341.786464 -274.896072)
		(mid 341.827719 -274.725101)
		(end 341.94242 -274.59178)
		(width 0.0889)
		(layer "In6.Cu")
		(net "VSENSE_PVDDIO_P0_DP")
	)
	(arc
		(start 340.603078 -276.98065)
		(mid 340.781891 -276.7783)
		(end 340.84641 -276.516084)
		(width 0.0889)
		(layer "In6.Cu")
		(net "VSENSE_PVDDIO_P0_DP")
	)
	(arc
		(start 343.42324 -272.120614)
		(mid 343.602053 -271.918264)
		(end 343.666572 -271.656048)
		(width 0.0889)
		(layer "In6.Cu")
		(net "VSENSE_PVDDIO_P0_DP")
	)
	(arc
		(start 341.316564 -275.706078)
		(mid 341.358113 -275.534656)
		(end 341.473536 -275.401278)
		(width 0.0889)
		(layer "In6.Cu")
		(net "VSENSE_PVDDIO_P0_DP")
	)
	(arc
		(start 344.32494 -270.524986)
		(mid 344.531008 -270.318123)
		(end 344.606372 -270.036036)
		(width 0.0889)
		(layer "In6.Cu")
		(net "VSENSE_PVDDIO_P0_DP")
	)
	(arc
		(start 343.666572 -271.656048)
		(mid 343.708121 -271.484626)
		(end 343.823544 -271.351248)
		(width 0.0889)
		(layer "In6.Cu")
		(net "VSENSE_PVDDIO_P0_DP")
	)
	(arc
		(start 338.723224 -294.800528)
		(mid 338.902037 -294.598178)
		(end 338.966556 -294.335962)
		(width 0.0889)
		(layer "In6.Cu")
		(net "VSENSE_PVDDIO_P0_DP")
	)
	(arc
		(start 341.073232 -276.170644)
		(mid 341.252045 -275.968294)
		(end 341.316564 -275.706078)
		(width 0.0889)
		(layer "In6.Cu")
		(net "VSENSE_PVDDIO_P0_DP")
	)
	(arc
		(start 339.623908 -280.88717)
		(mid 339.438541 -280.566305)
		(end 339.623908 -280.245312)
		(width 0.0889)
		(layer "In6.Cu")
		(net "VSENSE_PVDDIO_P0_DP")
	)
	(arc
		(start 344.136472 -270.846042)
		(mid 344.185812 -270.661964)
		(end 344.320622 -270.527272)
		(width 0.0889)
		(layer "In6.Cu")
		(net "VSENSE_PVDDIO_P0_DP")
	)
	(arc
		(start 340.095586 -277.815548)
		(mid 340.301263 -277.608255)
		(end 340.37651 -277.32609)
		(width 0.0889)
		(layer "In6.Cu")
		(net "VSENSE_PVDDIO_P0_DP")
	)
	(arc
		(start 343.89314 -271.310608)
		(mid 344.071953 -271.108258)
		(end 344.136472 -270.846042)
		(width 0.0889)
		(layer "In6.Cu")
		(net "VSENSE_PVDDIO_P0_DP")
	)
	(arc
		(start 343.196418 -272.466054)
		(mid 343.237673 -272.295083)
		(end 343.352374 -272.161762)
		(width 0.0889)
		(layer "In6.Cu")
		(net "VSENSE_PVDDIO_P0_DP")
	)
	(arc
		(start 339.641434 -280.234898)
		(mid 339.918629 -279.760262)
		(end 339.653372 -279.278842)
		(width 0.0889)
		(layer "In6.Cu")
		(net "VSENSE_PVDDIO_P0_DP")
	)
	(arc
		(start 340.84641 -276.516084)
		(mid 340.887665 -276.345113)
		(end 341.002366 -276.211792)
		(width 0.0889)
		(layer "In6.Cu")
		(net "VSENSE_PVDDIO_P0_DP")
	)
	(arc
		(start 338.496402 -295.145968)
		(mid 338.537657 -294.974997)
		(end 338.652358 -294.841676)
		(width 0.0889)
		(layer "In6.Cu")
		(net "VSENSE_PVDDIO_P0_DP")
	)
	(arc
		(start 342.953086 -272.93062)
		(mid 343.131899 -272.72827)
		(end 343.196418 -272.466054)
		(width 0.0889)
		(layer "In6.Cu")
		(net "VSENSE_PVDDIO_P0_DP")
	)
	(arc
		(start 342.010492 -274.55241)
		(mid 342.191144 -274.349665)
		(end 342.256364 -274.086066)
		(width 0.0889)
		(layer "In6.Cu")
		(net "VSENSE_PVDDIO_P0_DP")
	)
	(arc
		(start 339.623908 -282.507182)
		(mid 339.438541 -282.18638)
		(end 339.623908 -281.865578)
		(width 0.0889)
		(layer "In6.Cu")
		(net "VSENSE_PVDDIO_P0_DP")
	)
	(segment
		(start 100.350574 -146.64436)
		(end 101.004878 -146.64436)
		(width 0.254)
		(layer "B.Cu")
		(net "VSENSE_PVDDCR_SOC_P1_VSEN1")
	)
	(segment
		(start 99.464622 -145.758408)
		(end 100.350574 -146.64436)
		(width 0.254)
		(layer "B.Cu")
		(net "VSENSE_PVDDCR_SOC_P1_VSEN1")
	)
	(segment
		(start 101.004878 -146.64436)
		(end 101.023928 -146.66341)
		(width 0.254)
		(layer "B.Cu")
		(net "VSENSE_PVDDCR_SOC_P1_VSEN1")
	)
	(segment
		(start 101.023928 -146.66341)
		(end 102.001828 -146.66341)
		(width 0.254)
		(layer "B.Cu")
		(net "VSENSE_PVDDCR_SOC_P1_VSEN1")
	)
	(segment
		(start 98.545904 -145.758408)
		(end 99.464622 -145.758408)
		(width 0.1778)
		(layer "B.Cu")
		(net "VSENSE_PVDDCR_SOC_P1_VSEN1")
	)
	(segment
		(start 143.388842 -168.495472)
		(end 143.388842 -196.018404)
		(width 0.254)
		(layer "F.Cu")
		(net "VSENSE_PVDDCR_SOC_P1_DP")
	)
	(segment
		(start 131.567936 -207.83931)
		(end 131.567936 -214.58428)
		(width 0.254)
		(layer "F.Cu")
		(net "VSENSE_PVDDCR_SOC_P1_DP")
	)
	(segment
		(start 141.197838 -168.30167)
		(end 141.654276 -167.845232)
		(width 0.254)
		(layer "F.Cu")
		(net "VSENSE_PVDDCR_SOC_P1_DP")
	)
	(segment
		(start 133.580124 -216.246964)
		(end 133.724396 -216.391236)
		(width 0.254)
		(layer "F.Cu")
		(net "VSENSE_PVDDCR_SOC_P1_DP")
	)
	(segment
		(start 144.677892 -222.880428)
		(end 144.94383 -222.61449)
		(width 0.254)
		(layer "F.Cu")
		(net "VSENSE_PVDDCR_SOC_P1_DP")
	)
	(segment
		(start 133.23062 -216.246964)
		(end 133.580124 -216.246964)
		(width 0.254)
		(layer "F.Cu")
		(net "VSENSE_PVDDCR_SOC_P1_DP")
	)
	(segment
		(start 139.882118 -167.822372)
		(end 140.71854 -167.822372)
		(width 0.254)
		(layer "F.Cu")
		(net "VSENSE_PVDDCR_SOC_P1_DP")
	)
	(segment
		(start 143.388842 -196.018404)
		(end 131.567936 -207.83931)
		(width 0.254)
		(layer "F.Cu")
		(net "VSENSE_PVDDCR_SOC_P1_DP")
	)
	(segment
		(start 144.94383 -222.61449)
		(end 145.144744 -222.61449)
		(width 0.254)
		(layer "F.Cu")
		(net "VSENSE_PVDDCR_SOC_P1_DP")
	)
	(segment
		(start 139.689078 -168.015412)
		(end 139.882118 -167.822372)
		(width 0.254)
		(layer "F.Cu")
		(net "VSENSE_PVDDCR_SOC_P1_DP")
	)
	(segment
		(start 131.567936 -214.58428)
		(end 133.23062 -216.246964)
		(width 0.254)
		(layer "F.Cu")
		(net "VSENSE_PVDDCR_SOC_P1_DP")
	)
	(segment
		(start 139.017248 -168.484042)
		(end 139.485878 -168.015412)
		(width 0.254)
		(layer "F.Cu")
		(net "VSENSE_PVDDCR_SOC_P1_DP")
	)
	(segment
		(start 139.485878 -168.015412)
		(end 139.689078 -168.015412)
		(width 0.254)
		(layer "F.Cu")
		(net "VSENSE_PVDDCR_SOC_P1_DP")
	)
	(segment
		(start 140.71854 -167.822372)
		(end 141.197838 -168.30167)
		(width 0.254)
		(layer "F.Cu")
		(net "VSENSE_PVDDCR_SOC_P1_DP")
	)
	(segment
		(start 139.017248 -168.577006)
		(end 139.017248 -168.484042)
		(width 0.254)
		(layer "F.Cu")
		(net "VSENSE_PVDDCR_SOC_P1_DP")
	)
	(segment
		(start 141.654276 -167.845232)
		(end 142.738602 -167.845232)
		(width 0.254)
		(layer "F.Cu")
		(net "VSENSE_PVDDCR_SOC_P1_DP")
	)
	(segment
		(start 142.738602 -167.845232)
		(end 143.388842 -168.495472)
		(width 0.254)
		(layer "F.Cu")
		(net "VSENSE_PVDDCR_SOC_P1_DP")
	)
	(via
		(at 103.515922 -146.66341)
		(size 0.508)
		(drill 0.254)
		(layers "F.Cu" "B.Cu")
		(net "VSENSE_PVDDCR_SOC_P1_DP")
	)
	(via
		(at 145.144744 -222.61449)
		(size 0.4064)
		(drill 0.2032)
		(layers "F.Cu" "B.Cu")
		(net "VSENSE_PVDDCR_SOC_P1_DP")
	)
	(via
		(at 139.689078 -168.015412)
		(size 0.508)
		(drill 0.254)
		(layers "F.Cu" "B.Cu")
		(net "VSENSE_PVDDCR_SOC_P1_DP")
	)
	(via
		(at 133.724396 -216.391236)
		(size 0.508)
		(drill 0.254)
		(layers "F.Cu" "B.Cu")
		(net "VSENSE_PVDDCR_SOC_P1_DP")
	)
	(segment
		(start 145.38325 -220.063568)
		(end 144.331944 -219.012262)
		(width 0.254)
		(layer "B.Cu")
		(net "VSENSE_PVDDCR_SOC_P1_DP")
	)
	(segment
		(start 145.455386 -222.303848)
		(end 145.455386 -221.530672)
		(width 0.1016)
		(layer "B.Cu")
		(net "VSENSE_PVDDCR_SOC_P1_DP")
	)
	(segment
		(start 145.38325 -221.420436)
		(end 145.38325 -220.063568)
		(width 0.254)
		(layer "B.Cu")
		(net "VSENSE_PVDDCR_SOC_P1_DP")
	)
	(segment
		(start 136.080246 -219.012262)
		(end 135.361426 -218.293442)
		(width 0.254)
		(layer "B.Cu")
		(net "VSENSE_PVDDCR_SOC_P1_DP")
	)
	(segment
		(start 133.821424 -216.294208)
		(end 133.724396 -216.391236)
		(width 0.254)
		(layer "B.Cu")
		(net "VSENSE_PVDDCR_SOC_P1_DP")
	)
	(segment
		(start 135.361426 -217.353388)
		(end 134.302246 -216.294208)
		(width 0.254)
		(layer "B.Cu")
		(net "VSENSE_PVDDCR_SOC_P1_DP")
	)
	(segment
		(start 145.455386 -221.530672)
		(end 145.38325 -221.458536)
		(width 0.1016)
		(layer "B.Cu")
		(net "VSENSE_PVDDCR_SOC_P1_DP")
	)
	(segment
		(start 145.144744 -222.61449)
		(end 145.455386 -222.303848)
		(width 0.1016)
		(layer "B.Cu")
		(net "VSENSE_PVDDCR_SOC_P1_DP")
	)
	(segment
		(start 144.331944 -219.012262)
		(end 136.080246 -219.012262)
		(width 0.254)
		(layer "B.Cu")
		(net "VSENSE_PVDDCR_SOC_P1_DP")
	)
	(segment
		(start 134.302246 -216.294208)
		(end 133.821424 -216.294208)
		(width 0.254)
		(layer "B.Cu")
		(net "VSENSE_PVDDCR_SOC_P1_DP")
	)
	(segment
		(start 145.38325 -221.458536)
		(end 145.38325 -221.420436)
		(width 0.1016)
		(layer "B.Cu")
		(net "VSENSE_PVDDCR_SOC_P1_DP")
	)
	(segment
		(start 135.361426 -218.293442)
		(end 135.361426 -217.353388)
		(width 0.254)
		(layer "B.Cu")
		(net "VSENSE_PVDDCR_SOC_P1_DP")
	)
	(segment
		(start 102.801928 -146.66341)
		(end 103.515922 -146.66341)
		(width 0.254)
		(layer "B.Cu")
		(net "VSENSE_PVDDCR_SOC_P1_DP")
	)
	(segment
		(start 136.818878 -143.537178)
		(end 136.818878 -147.367498)
		(width 0.254)
		(layer "In4.Cu")
		(net "VSENSE_PVDDCR_SOC_P1_DP")
	)
	(segment
		(start 102.811834 -146.974052)
		(end 102.481634 -147.304252)
		(width 0.254)
		(layer "In4.Cu")
		(net "VSENSE_PVDDCR_SOC_P1_DP")
	)
	(segment
		(start 136.691878 -157.300422)
		(end 136.691878 -165.490398)
		(width 0.254)
		(layer "In4.Cu")
		(net "VSENSE_PVDDCR_SOC_P1_DP")
	)
	(segment
		(start 130.856736 -141.47927)
		(end 134.76097 -141.47927)
		(width 0.254)
		(layer "In4.Cu")
		(net "VSENSE_PVDDCR_SOC_P1_DP")
	)
	(segment
		(start 102.481634 -147.304252)
		(end 102.481634 -149.257512)
		(width 0.254)
		(layer "In4.Cu")
		(net "VSENSE_PVDDCR_SOC_P1_DP")
	)
	(segment
		(start 102.481634 -149.257512)
		(end 108.407454 -155.183332)
		(width 0.254)
		(layer "In4.Cu")
		(net "VSENSE_PVDDCR_SOC_P1_DP")
	)
	(segment
		(start 108.407454 -155.183332)
		(end 121.559828 -155.183332)
		(width 0.254)
		(layer "In4.Cu")
		(net "VSENSE_PVDDCR_SOC_P1_DP")
	)
	(segment
		(start 138.810238 -155.182062)
		(end 136.691878 -157.300422)
		(width 0.254)
		(layer "In4.Cu")
		(net "VSENSE_PVDDCR_SOC_P1_DP")
	)
	(segment
		(start 138.911584 -167.710104)
		(end 139.073128 -167.795956)
		(width 0.254)
		(layer "In4.Cu")
		(net "VSENSE_PVDDCR_SOC_P1_DP")
	)
	(segment
		(start 103.515922 -146.66341)
		(end 103.20528 -146.974052)
		(width 0.254)
		(layer "In4.Cu")
		(net "VSENSE_PVDDCR_SOC_P1_DP")
	)
	(segment
		(start 138.810238 -149.358858)
		(end 138.810238 -155.182062)
		(width 0.254)
		(layer "In4.Cu")
		(net "VSENSE_PVDDCR_SOC_P1_DP")
	)
	(segment
		(start 136.818878 -147.367498)
		(end 138.810238 -149.358858)
		(width 0.254)
		(layer "In4.Cu")
		(net "VSENSE_PVDDCR_SOC_P1_DP")
	)
	(segment
		(start 139.469622 -167.795956)
		(end 139.689078 -168.015412)
		(width 0.254)
		(layer "In4.Cu")
		(net "VSENSE_PVDDCR_SOC_P1_DP")
	)
	(segment
		(start 139.073128 -167.795956)
		(end 139.469622 -167.795956)
		(width 0.254)
		(layer "In4.Cu")
		(net "VSENSE_PVDDCR_SOC_P1_DP")
	)
	(segment
		(start 134.76097 -141.47927)
		(end 136.818878 -143.537178)
		(width 0.254)
		(layer "In4.Cu")
		(net "VSENSE_PVDDCR_SOC_P1_DP")
	)
	(segment
		(start 103.20528 -146.974052)
		(end 102.811834 -146.974052)
		(width 0.254)
		(layer "In4.Cu")
		(net "VSENSE_PVDDCR_SOC_P1_DP")
	)
	(segment
		(start 127.2667 -149.47646)
		(end 127.2667 -145.069306)
		(width 0.254)
		(layer "In4.Cu")
		(net "VSENSE_PVDDCR_SOC_P1_DP")
	)
	(segment
		(start 127.2667 -145.069306)
		(end 130.856736 -141.47927)
		(width 0.254)
		(layer "In4.Cu")
		(net "VSENSE_PVDDCR_SOC_P1_DP")
	)
	(segment
		(start 136.691878 -165.490398)
		(end 138.911584 -167.710104)
		(width 0.254)
		(layer "In4.Cu")
		(net "VSENSE_PVDDCR_SOC_P1_DP")
	)
	(segment
		(start 121.559828 -155.183332)
		(end 127.2667 -149.47646)
		(width 0.254)
		(layer "In4.Cu")
		(net "VSENSE_PVDDCR_SOC_P1_DP")
	)
	(segment
		(start 382.954022 -144.247108)
		(end 383.732278 -144.247108)
		(width 0.254)
		(layer "B.Cu")
		(net "VSENSE_PVDDCR_SOC_P0_VSEN1")
	)
	(segment
		(start 383.751328 -144.266158)
		(end 384.729228 -144.266158)
		(width 0.254)
		(layer "B.Cu")
		(net "VSENSE_PVDDCR_SOC_P0_VSEN1")
	)
	(segment
		(start 381.273304 -143.361156)
		(end 382.06807 -143.361156)
		(width 0.1778)
		(layer "B.Cu")
		(net "VSENSE_PVDDCR_SOC_P0_VSEN1")
	)
	(segment
		(start 382.06807 -143.361156)
		(end 382.954022 -144.247108)
		(width 0.254)
		(layer "B.Cu")
		(net "VSENSE_PVDDCR_SOC_P0_VSEN1")
	)
	(segment
		(start 383.732278 -144.247108)
		(end 383.751328 -144.266158)
		(width 0.254)
		(layer "B.Cu")
		(net "VSENSE_PVDDCR_SOC_P0_VSEN1")
	)
	(segment
		(start 416.11042 -188.22416)
		(end 417.767008 -186.567572)
		(width 0.254)
		(layer "F.Cu")
		(net "VSENSE_PVDDCR_SOC_P0_DP")
	)
	(segment
		(start 392.467338 -208.280762)
		(end 393.724638 -209.538062)
		(width 0.254)
		(layer "F.Cu")
		(net "VSENSE_PVDDCR_SOC_P0_DP")
	)
	(segment
		(start 389.024622 -217.99931)
		(end 385.705858 -214.680546)
		(width 0.254)
		(layer "F.Cu")
		(net "VSENSE_PVDDCR_SOC_P0_DP")
	)
	(segment
		(start 388.564628 -208.280762)
		(end 392.467338 -208.280762)
		(width 0.254)
		(layer "F.Cu")
		(net "VSENSE_PVDDCR_SOC_P0_DP")
	)
	(segment
		(start 423.408348 -178.141884)
		(end 423.408348 -176.951132)
		(width 0.254)
		(layer "F.Cu")
		(net "VSENSE_PVDDCR_SOC_P0_DP")
	)
	(segment
		(start 396.118588 -209.538062)
		(end 408.100276 -197.556374)
		(width 0.254)
		(layer "F.Cu")
		(net "VSENSE_PVDDCR_SOC_P0_DP")
	)
	(segment
		(start 392.61796 -222.880174)
		(end 393.268454 -222.22968)
		(width 0.254)
		(layer "F.Cu")
		(net "VSENSE_PVDDCR_SOC_P0_DP")
	)
	(segment
		(start 408.100276 -190.402718)
		(end 410.278834 -188.22416)
		(width 0.254)
		(layer "F.Cu")
		(net "VSENSE_PVDDCR_SOC_P0_DP")
	)
	(segment
		(start 393.268454 -222.22968)
		(end 393.268454 -219.681298)
		(width 0.254)
		(layer "F.Cu")
		(net "VSENSE_PVDDCR_SOC_P0_DP")
	)
	(segment
		(start 408.100276 -197.556374)
		(end 408.100276 -190.402718)
		(width 0.254)
		(layer "F.Cu")
		(net "VSENSE_PVDDCR_SOC_P0_DP")
	)
	(segment
		(start 385.705858 -211.139532)
		(end 388.564628 -208.280762)
		(width 0.254)
		(layer "F.Cu")
		(net "VSENSE_PVDDCR_SOC_P0_DP")
	)
	(segment
		(start 421.735758 -176.8602)
		(end 422.243758 -176.8602)
		(width 0.254)
		(layer "F.Cu")
		(net "VSENSE_PVDDCR_SOC_P0_DP")
	)
	(segment
		(start 385.705858 -214.680546)
		(end 385.705858 -211.139532)
		(width 0.254)
		(layer "F.Cu")
		(net "VSENSE_PVDDCR_SOC_P0_DP")
	)
	(segment
		(start 393.268454 -219.681298)
		(end 391.586466 -217.99931)
		(width 0.254)
		(layer "F.Cu")
		(net "VSENSE_PVDDCR_SOC_P0_DP")
	)
	(segment
		(start 422.406826 -176.697132)
		(end 422.243758 -176.8602)
		(width 0.254)
		(layer "F.Cu")
		(net "VSENSE_PVDDCR_SOC_P0_DP")
	)
	(segment
		(start 423.154348 -176.697132)
		(end 422.406826 -176.697132)
		(width 0.254)
		(layer "F.Cu")
		(net "VSENSE_PVDDCR_SOC_P0_DP")
	)
	(segment
		(start 421.574214 -176.864772)
		(end 421.731186 -176.864772)
		(width 0.254)
		(layer "F.Cu")
		(net "VSENSE_PVDDCR_SOC_P0_DP")
	)
	(segment
		(start 391.586466 -217.99931)
		(end 389.024622 -217.99931)
		(width 0.254)
		(layer "F.Cu")
		(net "VSENSE_PVDDCR_SOC_P0_DP")
	)
	(segment
		(start 393.724638 -209.538062)
		(end 396.118588 -209.538062)
		(width 0.254)
		(layer "F.Cu")
		(net "VSENSE_PVDDCR_SOC_P0_DP")
	)
	(segment
		(start 410.278834 -188.22416)
		(end 416.11042 -188.22416)
		(width 0.254)
		(layer "F.Cu")
		(net "VSENSE_PVDDCR_SOC_P0_DP")
	)
	(segment
		(start 417.767008 -186.567572)
		(end 417.767008 -183.783224)
		(width 0.254)
		(layer "F.Cu")
		(net "VSENSE_PVDDCR_SOC_P0_DP")
	)
	(segment
		(start 417.767008 -183.783224)
		(end 423.408348 -178.141884)
		(width 0.254)
		(layer "F.Cu")
		(net "VSENSE_PVDDCR_SOC_P0_DP")
	)
	(segment
		(start 421.731186 -176.864772)
		(end 421.735758 -176.8602)
		(width 0.254)
		(layer "F.Cu")
		(net "VSENSE_PVDDCR_SOC_P0_DP")
	)
	(segment
		(start 423.408348 -176.951132)
		(end 423.154348 -176.697132)
		(width 0.254)
		(layer "F.Cu")
		(net "VSENSE_PVDDCR_SOC_P0_DP")
	)
	(via
		(at 422.243758 -176.8602)
		(size 0.508)
		(drill 0.254)
		(layers "F.Cu" "B.Cu")
		(net "VSENSE_PVDDCR_SOC_P0_DP")
	)
	(segment
		(start 424.800522 -176.693322)
		(end 422.410636 -176.693322)
		(width 0.254)
		(layer "B.Cu")
		(net "VSENSE_PVDDCR_SOC_P0_DP")
	)
	(segment
		(start 395.19987 -136.660382)
		(end 400.730466 -131.129786)
		(width 0.254)
		(layer "B.Cu")
		(net "VSENSE_PVDDCR_SOC_P0_DP")
	)
	(segment
		(start 393.41679 -144.452086)
		(end 395.19987 -142.669006)
		(width 0.254)
		(layer "B.Cu")
		(net "VSENSE_PVDDCR_SOC_P0_DP")
	)
	(segment
		(start 421.895778 -177.20818)
		(end 422.243758 -176.8602)
		(width 0.254)
		(layer "B.Cu")
		(net "VSENSE_PVDDCR_SOC_P0_DP")
	)
	(segment
		(start 421.895778 -177.861722)
		(end 421.895778 -177.20818)
		(width 0.254)
		(layer "B.Cu")
		(net "VSENSE_PVDDCR_SOC_P0_DP")
	)
	(segment
		(start 422.410636 -176.693322)
		(end 422.243758 -176.8602)
		(width 0.254)
		(layer "B.Cu")
		(net "VSENSE_PVDDCR_SOC_P0_DP")
	)
	(segment
		(start 415.425382 -131.129786)
		(end 428.672498 -144.376902)
		(width 0.254)
		(layer "B.Cu")
		(net "VSENSE_PVDDCR_SOC_P0_DP")
	)
	(segment
		(start 395.19987 -142.669006)
		(end 395.19987 -136.660382)
		(width 0.254)
		(layer "B.Cu")
		(net "VSENSE_PVDDCR_SOC_P0_DP")
	)
	(segment
		(start 428.672498 -144.376902)
		(end 428.672498 -172.821346)
		(width 0.254)
		(layer "B.Cu")
		(net "VSENSE_PVDDCR_SOC_P0_DP")
	)
	(segment
		(start 400.730466 -131.129786)
		(end 415.425382 -131.129786)
		(width 0.254)
		(layer "B.Cu")
		(net "VSENSE_PVDDCR_SOC_P0_DP")
	)
	(segment
		(start 386.243322 -144.266158)
		(end 386.42925 -144.452086)
		(width 0.254)
		(layer "B.Cu")
		(net "VSENSE_PVDDCR_SOC_P0_DP")
	)
	(segment
		(start 386.42925 -144.452086)
		(end 393.41679 -144.452086)
		(width 0.254)
		(layer "B.Cu")
		(net "VSENSE_PVDDCR_SOC_P0_DP")
	)
	(segment
		(start 428.672498 -172.821346)
		(end 424.800522 -176.693322)
		(width 0.254)
		(layer "B.Cu")
		(net "VSENSE_PVDDCR_SOC_P0_DP")
	)
	(segment
		(start 385.529328 -144.266158)
		(end 386.243322 -144.266158)
		(width 0.254)
		(layer "B.Cu")
		(net "VSENSE_PVDDCR_SOC_P0_DP")
	)
	(segment
		(start 27.94 -360.68)
		(end 28.280106 -361.020106)
		(width 0.1778)
		(layer "F.Cu")
		(net "VSENSE_PVDDCR_CPU1_P1_VSEN0")
	)
	(segment
		(start 27.15895 -359.283)
		(end 27.15895 -359.89895)
		(width 0.254)
		(layer "F.Cu")
		(net "VSENSE_PVDDCR_CPU1_P1_VSEN0")
	)
	(segment
		(start 28.280106 -361.020106)
		(end 28.280106 -361.233974)
		(width 0.1778)
		(layer "F.Cu")
		(net "VSENSE_PVDDCR_CPU1_P1_VSEN0")
	)
	(segment
		(start 27.15895 -359.89895)
		(end 27.94 -360.68)
		(width 0.254)
		(layer "F.Cu")
		(net "VSENSE_PVDDCR_CPU1_P1_VSEN0")
	)
	(segment
		(start 27.178 -358.28605)
		(end 27.178 -359.26395)
		(width 0.254)
		(layer "F.Cu")
		(net "VSENSE_PVDDCR_CPU1_P1_VSEN0")
	)
	(segment
		(start 27.178 -359.26395)
		(end 27.15895 -359.283)
		(width 0.254)
		(layer "F.Cu")
		(net "VSENSE_PVDDCR_CPU1_P1_VSEN0")
	)
	(segment
		(start 144.507966 -294.070278)
		(end 144.974818 -294.336216)
		(width 0.254)
		(layer "F.Cu")
		(net "VSENSE_PVDDCR_CPU1_P1_DP")
	)
	(segment
		(start 149.646894 -326.567292)
		(end 149.933914 -326.854312)
		(width 0.254)
		(layer "F.Cu")
		(net "VSENSE_PVDDCR_CPU1_P1_DP")
	)
	(segment
		(start 150.81123 -326.854312)
		(end 151.127714 -326.537828)
		(width 0.254)
		(layer "F.Cu")
		(net "VSENSE_PVDDCR_CPU1_P1_DP")
	)
	(segment
		(start 27.178 -357.48595)
		(end 27.94 -357.48595)
		(width 0.254)
		(layer "F.Cu")
		(net "VSENSE_PVDDCR_CPU1_P1_DP")
	)
	(segment
		(start 149.646894 -325.985632)
		(end 149.646894 -326.567292)
		(width 0.254)
		(layer "F.Cu")
		(net "VSENSE_PVDDCR_CPU1_P1_DP")
	)
	(segment
		(start 158.43758 -313.43473)
		(end 158.43758 -325.963534)
		(width 0.254)
		(layer "F.Cu")
		(net "VSENSE_PVDDCR_CPU1_P1_DP")
	)
	(segment
		(start 110.63732 -325.720456)
		(end 110.63732 -325.116444)
		(width 0.254)
		(layer "F.Cu")
		(net "VSENSE_PVDDCR_CPU1_P1_DP")
	)
	(segment
		(start 150.043134 -325.589392)
		(end 149.646894 -325.985632)
		(width 0.254)
		(layer "F.Cu")
		(net "VSENSE_PVDDCR_CPU1_P1_DP")
	)
	(segment
		(start 158.43758 -325.963534)
		(end 157.244542 -327.156572)
		(width 0.254)
		(layer "F.Cu")
		(net "VSENSE_PVDDCR_CPU1_P1_DP")
	)
	(segment
		(start 145.784316 -294.823134)
		(end 145.963386 -295.002204)
		(width 0.254)
		(layer "F.Cu")
		(net "VSENSE_PVDDCR_CPU1_P1_DP")
	)
	(segment
		(start 152.780238 -327.156572)
		(end 151.213058 -325.589392)
		(width 0.254)
		(layer "F.Cu")
		(net "VSENSE_PVDDCR_CPU1_P1_DP")
	)
	(segment
		(start 151.213058 -325.589392)
		(end 150.043134 -325.589392)
		(width 0.254)
		(layer "F.Cu")
		(net "VSENSE_PVDDCR_CPU1_P1_DP")
	)
	(segment
		(start 110.973362 -326.566276)
		(end 110.318804 -326.566276)
		(width 0.254)
		(layer "F.Cu")
		(net "VSENSE_PVDDCR_CPU1_P1_DP")
	)
	(segment
		(start 149.933914 -326.854312)
		(end 150.81123 -326.854312)
		(width 0.254)
		(layer "F.Cu")
		(net "VSENSE_PVDDCR_CPU1_P1_DP")
	)
	(segment
		(start 145.038826 -294.400224)
		(end 145.190972 -294.463724)
		(width 0.254)
		(layer "F.Cu")
		(net "VSENSE_PVDDCR_CPU1_P1_DP")
	)
	(segment
		(start 145.190972 -294.463724)
		(end 145.470372 -294.613584)
		(width 0.254)
		(layer "F.Cu")
		(net "VSENSE_PVDDCR_CPU1_P1_DP")
	)
	(segment
		(start 144.974818 -294.336216)
		(end 145.038826 -294.400224)
		(width 0.254)
		(layer "F.Cu")
		(net "VSENSE_PVDDCR_CPU1_P1_DP")
	)
	(segment
		(start 110.318804 -326.566276)
		(end 110.295436 -326.542908)
		(width 0.254)
		(layer "F.Cu")
		(net "VSENSE_PVDDCR_CPU1_P1_DP")
	)
	(segment
		(start 157.244542 -327.156572)
		(end 152.780238 -327.156572)
		(width 0.254)
		(layer "F.Cu")
		(net "VSENSE_PVDDCR_CPU1_P1_DP")
	)
	(segment
		(start 110.295436 -326.06234)
		(end 110.63732 -325.720456)
		(width 0.254)
		(layer "F.Cu")
		(net "VSENSE_PVDDCR_CPU1_P1_DP")
	)
	(segment
		(start 145.470372 -294.613584)
		(end 145.784316 -294.823134)
		(width 0.254)
		(layer "F.Cu")
		(net "VSENSE_PVDDCR_CPU1_P1_DP")
	)
	(segment
		(start 145.963386 -295.002204)
		(end 145.963386 -300.960536)
		(width 0.254)
		(layer "F.Cu")
		(net "VSENSE_PVDDCR_CPU1_P1_DP")
	)
	(segment
		(start 145.963386 -300.960536)
		(end 158.43758 -313.43473)
		(width 0.254)
		(layer "F.Cu")
		(net "VSENSE_PVDDCR_CPU1_P1_DP")
	)
	(segment
		(start 110.295436 -326.542908)
		(end 110.295436 -326.06234)
		(width 0.254)
		(layer "F.Cu")
		(net "VSENSE_PVDDCR_CPU1_P1_DP")
	)
	(via
		(at 151.127714 -326.537828)
		(size 0.508)
		(drill 0.254)
		(layers "F.Cu" "B.Cu")
		(net "VSENSE_PVDDCR_CPU1_P1_DP")
	)
	(via
		(at 27.94 -357.48595)
		(size 0.508)
		(drill 0.254)
		(layers "F.Cu" "B.Cu")
		(net "VSENSE_PVDDCR_CPU1_P1_DP")
	)
	(via
		(at 110.973362 -326.566276)
		(size 0.508)
		(drill 0.254)
		(layers "F.Cu" "B.Cu")
		(net "VSENSE_PVDDCR_CPU1_P1_DP")
	)
	(segment
		(start 151.127714 -326.537828)
		(end 150.839678 -326.825864)
		(width 0.254)
		(layer "B.Cu")
		(net "VSENSE_PVDDCR_CPU1_P1_DP")
	)
	(segment
		(start 111.23295 -326.825864)
		(end 110.973362 -326.566276)
		(width 0.254)
		(layer "B.Cu")
		(net "VSENSE_PVDDCR_CPU1_P1_DP")
	)
	(segment
		(start 150.839678 -326.825864)
		(end 111.23295 -326.825864)
		(width 0.254)
		(layer "B.Cu")
		(net "VSENSE_PVDDCR_CPU1_P1_DP")
	)
	(segment
		(start 28.683712 -357.48595)
		(end 31.492698 -354.676964)
		(width 0.254)
		(layer "In2.Cu")
		(net "VSENSE_PVDDCR_CPU1_P1_DP")
	)
	(segment
		(start 108.557822 -344.55227)
		(end 108.557822 -328.981816)
		(width 0.254)
		(layer "In2.Cu")
		(net "VSENSE_PVDDCR_CPU1_P1_DP")
	)
	(segment
		(start 108.557822 -328.981816)
		(end 110.973362 -326.566276)
		(width 0.254)
		(layer "In2.Cu")
		(net "VSENSE_PVDDCR_CPU1_P1_DP")
	)
	(segment
		(start 93.26753 -342.591898)
		(end 98.00717 -347.331538)
		(width 0.254)
		(layer "In2.Cu")
		(net "VSENSE_PVDDCR_CPU1_P1_DP")
	)
	(segment
		(start 78.928214 -342.591898)
		(end 93.26753 -342.591898)
		(width 0.254)
		(layer "In2.Cu")
		(net "VSENSE_PVDDCR_CPU1_P1_DP")
	)
	(segment
		(start 105.778554 -347.331538)
		(end 108.557822 -344.55227)
		(width 0.254)
		(layer "In2.Cu")
		(net "VSENSE_PVDDCR_CPU1_P1_DP")
	)
	(segment
		(start 31.492698 -354.676964)
		(end 66.843148 -354.676964)
		(width 0.254)
		(layer "In2.Cu")
		(net "VSENSE_PVDDCR_CPU1_P1_DP")
	)
	(segment
		(start 27.94 -357.48595)
		(end 28.683712 -357.48595)
		(width 0.254)
		(layer "In2.Cu")
		(net "VSENSE_PVDDCR_CPU1_P1_DP")
	)
	(segment
		(start 66.843148 -354.676964)
		(end 78.928214 -342.591898)
		(width 0.254)
		(layer "In2.Cu")
		(net "VSENSE_PVDDCR_CPU1_P1_DP")
	)
	(segment
		(start 98.00717 -347.331538)
		(end 105.778554 -347.331538)
		(width 0.254)
		(layer "In2.Cu")
		(net "VSENSE_PVDDCR_CPU1_P1_DP")
	)
	(segment
		(start 306.832 -355.83495)
		(end 306.81295 -355.854)
		(width 0.254)
		(layer "F.Cu")
		(net "VSENSE_PVDDCR_CPU1_P0_VSEN0")
	)
	(segment
		(start 307.594 -357.251)
		(end 307.934106 -357.591106)
		(width 0.1778)
		(layer "F.Cu")
		(net "VSENSE_PVDDCR_CPU1_P0_VSEN0")
	)
	(segment
		(start 306.81295 -356.46995)
		(end 307.594 -357.251)
		(width 0.254)
		(layer "F.Cu")
		(net "VSENSE_PVDDCR_CPU1_P0_VSEN0")
	)
	(segment
		(start 306.832 -354.85705)
		(end 306.832 -355.83495)
		(width 0.254)
		(layer "F.Cu")
		(net "VSENSE_PVDDCR_CPU1_P0_VSEN0")
	)
	(segment
		(start 307.934106 -357.591106)
		(end 307.934106 -357.804974)
		(width 0.1778)
		(layer "F.Cu")
		(net "VSENSE_PVDDCR_CPU1_P0_VSEN0")
	)
	(segment
		(start 306.81295 -355.854)
		(end 306.81295 -356.46995)
		(width 0.254)
		(layer "F.Cu")
		(net "VSENSE_PVDDCR_CPU1_P0_VSEN0")
	)
	(segment
		(start 392.448034 -294.070024)
		(end 392.648948 -294.070024)
		(width 0.254)
		(layer "F.Cu")
		(net "VSENSE_PVDDCR_CPU1_P0_DP")
	)
	(segment
		(start 393.839954 -301.23638)
		(end 394.837158 -302.233584)
		(width 0.254)
		(layer "F.Cu")
		(net "VSENSE_PVDDCR_CPU1_P0_DP")
	)
	(segment
		(start 307.2892 -353.59975)
		(end 307.594 -353.59975)
		(width 0.254)
		(layer "F.Cu")
		(net "VSENSE_PVDDCR_CPU1_P0_DP")
	)
	(segment
		(start 411.016958 -321.621404)
		(end 411.016958 -337.285076)
		(width 0.254)
		(layer "F.Cu")
		(net "VSENSE_PVDDCR_CPU1_P0_DP")
	)
	(segment
		(start 393.903454 -297.438572)
		(end 393.839954 -297.502072)
		(width 0.254)
		(layer "F.Cu")
		(net "VSENSE_PVDDCR_CPU1_P0_DP")
	)
	(segment
		(start 393.132564 -294.462708)
		(end 393.424156 -294.618664)
		(width 0.254)
		(layer "F.Cu")
		(net "VSENSE_PVDDCR_CPU1_P0_DP")
	)
	(segment
		(start 393.839954 -297.502072)
		(end 393.839954 -301.23638)
		(width 0.254)
		(layer "F.Cu")
		(net "VSENSE_PVDDCR_CPU1_P0_DP")
	)
	(segment
		(start 393.424156 -294.618664)
		(end 393.64031 -294.76319)
		(width 0.254)
		(layer "F.Cu")
		(net "VSENSE_PVDDCR_CPU1_P0_DP")
	)
	(segment
		(start 411.016958 -337.285076)
		(end 409.6766 -338.625434)
		(width 0.254)
		(layer "F.Cu")
		(net "VSENSE_PVDDCR_CPU1_P0_DP")
	)
	(segment
		(start 408.644344 -338.625434)
		(end 408.538172 -338.731606)
		(width 0.254)
		(layer "F.Cu")
		(net "VSENSE_PVDDCR_CPU1_P0_DP")
	)
	(segment
		(start 393.903454 -295.026334)
		(end 393.903454 -297.438572)
		(width 0.254)
		(layer "F.Cu")
		(net "VSENSE_PVDDCR_CPU1_P0_DP")
	)
	(segment
		(start 394.837158 -302.233584)
		(end 394.837158 -303.234344)
		(width 0.254)
		(layer "F.Cu")
		(net "VSENSE_PVDDCR_CPU1_P0_DP")
	)
	(segment
		(start 392.648948 -294.070024)
		(end 392.97737 -294.398446)
		(width 0.254)
		(layer "F.Cu")
		(net "VSENSE_PVDDCR_CPU1_P0_DP")
	)
	(segment
		(start 306.832 -354.05695)
		(end 307.2892 -353.59975)
		(width 0.254)
		(layer "F.Cu")
		(net "VSENSE_PVDDCR_CPU1_P0_DP")
	)
	(segment
		(start 406.408128 -317.012574)
		(end 411.016958 -321.621404)
		(width 0.254)
		(layer "F.Cu")
		(net "VSENSE_PVDDCR_CPU1_P0_DP")
	)
	(segment
		(start 392.97737 -294.398446)
		(end 393.132564 -294.462708)
		(width 0.254)
		(layer "F.Cu")
		(net "VSENSE_PVDDCR_CPU1_P0_DP")
	)
	(segment
		(start 359.146856 -327.60031)
		(end 358.33431 -327.60031)
		(width 0.254)
		(layer "F.Cu")
		(net "VSENSE_PVDDCR_CPU1_P0_DP")
	)
	(segment
		(start 393.64031 -294.76319)
		(end 393.903454 -295.026334)
		(width 0.254)
		(layer "F.Cu")
		(net "VSENSE_PVDDCR_CPU1_P0_DP")
	)
	(segment
		(start 394.837158 -303.234344)
		(end 406.408128 -314.805314)
		(width 0.254)
		(layer "F.Cu")
		(net "VSENSE_PVDDCR_CPU1_P0_DP")
	)
	(segment
		(start 359.19791 -327.549256)
		(end 359.146856 -327.60031)
		(width 0.254)
		(layer "F.Cu")
		(net "VSENSE_PVDDCR_CPU1_P0_DP")
	)
	(segment
		(start 409.6766 -338.625434)
		(end 408.644344 -338.625434)
		(width 0.254)
		(layer "F.Cu")
		(net "VSENSE_PVDDCR_CPU1_P0_DP")
	)
	(segment
		(start 406.408128 -314.805314)
		(end 406.408128 -317.012574)
		(width 0.254)
		(layer "F.Cu")
		(net "VSENSE_PVDDCR_CPU1_P0_DP")
	)
	(via
		(at 359.19791 -327.549256)
		(size 0.508)
		(drill 0.254)
		(layers "F.Cu" "B.Cu")
		(net "VSENSE_PVDDCR_CPU1_P0_DP")
	)
	(via
		(at 307.594 -353.59975)
		(size 0.508)
		(drill 0.254)
		(layers "F.Cu" "B.Cu")
		(net "VSENSE_PVDDCR_CPU1_P0_DP")
	)
	(via
		(at 408.538172 -338.731606)
		(size 0.508)
		(drill 0.254)
		(layers "F.Cu" "B.Cu")
		(net "VSENSE_PVDDCR_CPU1_P0_DP")
	)
	(segment
		(start 359.19791 -327.549256)
		(end 359.19791 -327.52284)
		(width 0.254)
		(layer "B.Cu")
		(net "VSENSE_PVDDCR_CPU1_P0_DP")
	)
	(segment
		(start 372.270782 -327.28535)
		(end 383.572766 -338.587334)
		(width 0.254)
		(layer "B.Cu")
		(net "VSENSE_PVDDCR_CPU1_P0_DP")
	)
	(segment
		(start 383.572766 -338.587334)
		(end 408.3939 -338.587334)
		(width 0.254)
		(layer "B.Cu")
		(net "VSENSE_PVDDCR_CPU1_P0_DP")
	)
	(segment
		(start 307.20665 -353.59975)
		(end 307.594 -353.59975)
		(width 0.254)
		(layer "B.Cu")
		(net "VSENSE_PVDDCR_CPU1_P0_DP")
	)
	(segment
		(start 408.3939 -338.587334)
		(end 408.538172 -338.731606)
		(width 0.254)
		(layer "B.Cu")
		(net "VSENSE_PVDDCR_CPU1_P0_DP")
	)
	(segment
		(start 306.7304 -354.076)
		(end 307.20665 -353.59975)
		(width 0.254)
		(layer "B.Cu")
		(net "VSENSE_PVDDCR_CPU1_P0_DP")
	)
	(segment
		(start 359.19791 -327.52284)
		(end 359.4354 -327.28535)
		(width 0.254)
		(layer "B.Cu")
		(net "VSENSE_PVDDCR_CPU1_P0_DP")
	)
	(segment
		(start 359.4354 -327.28535)
		(end 372.270782 -327.28535)
		(width 0.254)
		(layer "B.Cu")
		(net "VSENSE_PVDDCR_CPU1_P0_DP")
	)
	(segment
		(start 318.282828 -351.4598)
		(end 325.667116 -344.075512)
		(width 0.254)
		(layer "In2.Cu")
		(net "VSENSE_PVDDCR_CPU1_P0_DP")
	)
	(segment
		(start 346.300552 -347.862652)
		(end 353.145344 -347.862652)
		(width 0.254)
		(layer "In2.Cu")
		(net "VSENSE_PVDDCR_CPU1_P0_DP")
	)
	(segment
		(start 356.488492 -335.433924)
		(end 359.088944 -332.833472)
		(width 0.254)
		(layer "In2.Cu")
		(net "VSENSE_PVDDCR_CPU1_P0_DP")
	)
	(segment
		(start 308.45125 -353.59975)
		(end 309.6514 -352.3996)
		(width 0.254)
		(layer "In2.Cu")
		(net "VSENSE_PVDDCR_CPU1_P0_DP")
	)
	(segment
		(start 353.145344 -347.862652)
		(end 356.488492 -344.519504)
		(width 0.254)
		(layer "In2.Cu")
		(net "VSENSE_PVDDCR_CPU1_P0_DP")
	)
	(segment
		(start 342.513412 -344.075512)
		(end 346.300552 -347.862652)
		(width 0.254)
		(layer "In2.Cu")
		(net "VSENSE_PVDDCR_CPU1_P0_DP")
	)
	(segment
		(start 359.088944 -331.244956)
		(end 360.32186 -330.01204)
		(width 0.254)
		(layer "In2.Cu")
		(net "VSENSE_PVDDCR_CPU1_P0_DP")
	)
	(segment
		(start 314.0456 -352.3996)
		(end 314.9854 -351.4598)
		(width 0.254)
		(layer "In2.Cu")
		(net "VSENSE_PVDDCR_CPU1_P0_DP")
	)
	(segment
		(start 360.19486 -327.549256)
		(end 359.19791 -327.549256)
		(width 0.254)
		(layer "In2.Cu")
		(net "VSENSE_PVDDCR_CPU1_P0_DP")
	)
	(segment
		(start 314.9854 -351.4598)
		(end 318.282828 -351.4598)
		(width 0.254)
		(layer "In2.Cu")
		(net "VSENSE_PVDDCR_CPU1_P0_DP")
	)
	(segment
		(start 359.088944 -332.833472)
		(end 359.088944 -331.244956)
		(width 0.254)
		(layer "In2.Cu")
		(net "VSENSE_PVDDCR_CPU1_P0_DP")
	)
	(segment
		(start 309.6514 -352.3996)
		(end 314.0456 -352.3996)
		(width 0.254)
		(layer "In2.Cu")
		(net "VSENSE_PVDDCR_CPU1_P0_DP")
	)
	(segment
		(start 307.594 -353.59975)
		(end 308.45125 -353.59975)
		(width 0.254)
		(layer "In2.Cu")
		(net "VSENSE_PVDDCR_CPU1_P0_DP")
	)
	(segment
		(start 360.32186 -330.01204)
		(end 360.32186 -327.676256)
		(width 0.254)
		(layer "In2.Cu")
		(net "VSENSE_PVDDCR_CPU1_P0_DP")
	)
	(segment
		(start 360.32186 -327.676256)
		(end 360.19486 -327.549256)
		(width 0.254)
		(layer "In2.Cu")
		(net "VSENSE_PVDDCR_CPU1_P0_DP")
	)
	(segment
		(start 356.488492 -344.519504)
		(end 356.488492 -335.433924)
		(width 0.254)
		(layer "In2.Cu")
		(net "VSENSE_PVDDCR_CPU1_P0_DP")
	)
	(segment
		(start 325.667116 -344.075512)
		(end 342.513412 -344.075512)
		(width 0.254)
		(layer "In2.Cu")
		(net "VSENSE_PVDDCR_CPU1_P0_DP")
	)
	(segment
		(start 92.7862 -149.145498)
		(end 91.950032 -149.981666)
		(width 0.1778)
		(layer "B.Cu")
		(net "VSENSE_PVDDCR_CPU0_P1_VSEN0")
	)
	(segment
		(start 91.9734 -150.005034)
		(end 91.9734 -150.485602)
		(width 0.254)
		(layer "B.Cu")
		(net "VSENSE_PVDDCR_CPU0_P1_VSEN0")
	)
	(segment
		(start 93.470984 -147.633436)
		(end 93.470984 -148.017484)
		(width 0.1778)
		(layer "B.Cu")
		(net "VSENSE_PVDDCR_CPU0_P1_VSEN0")
	)
	(segment
		(start 91.966542 -150.49246)
		(end 91.966542 -150.976584)
		(width 0.254)
		(layer "B.Cu")
		(net "VSENSE_PVDDCR_CPU0_P1_VSEN0")
	)
	(segment
		(start 91.950032 -149.981666)
		(end 91.9734 -150.005034)
		(width 0.254)
		(layer "B.Cu")
		(net "VSENSE_PVDDCR_CPU0_P1_VSEN0")
	)
	(segment
		(start 91.9734 -150.485602)
		(end 91.966542 -150.49246)
		(width 0.254)
		(layer "B.Cu")
		(net "VSENSE_PVDDCR_CPU0_P1_VSEN0")
	)
	(segment
		(start 92.7862 -148.702268)
		(end 92.7862 -149.145498)
		(width 0.1778)
		(layer "B.Cu")
		(net "VSENSE_PVDDCR_CPU0_P1_VSEN0")
	)
	(segment
		(start 93.470984 -148.017484)
		(end 92.7862 -148.702268)
		(width 0.1778)
		(layer "B.Cu")
		(net "VSENSE_PVDDCR_CPU0_P1_VSEN0")
	)
	(segment
		(start 58.122058 -183.771032)
		(end 76.86802 -202.516994)
		(width 0.254)
		(layer "F.Cu")
		(net "VSENSE_PVDDCR_CPU0_P1_DP")
	)
	(segment
		(start 145.348706 -223.690434)
		(end 145.614644 -223.424496)
		(width 0.254)
		(layer "F.Cu")
		(net "VSENSE_PVDDCR_CPU0_P1_DP")
	)
	(segment
		(start 58.74004 -181.46141)
		(end 59.097672 -181.819042)
		(width 0.254)
		(layer "F.Cu")
		(net "VSENSE_PVDDCR_CPU0_P1_DP")
	)
	(segment
		(start 56.935878 -181.84241)
		(end 56.825134 -181.731666)
		(width 0.254)
		(layer "F.Cu")
		(net "VSENSE_PVDDCR_CPU0_P1_DP")
	)
	(segment
		(start 56.211724 -181.985666)
		(end 56.211724 -183.420512)
		(width 0.254)
		(layer "F.Cu")
		(net "VSENSE_PVDDCR_CPU0_P1_DP")
	)
	(segment
		(start 57.697878 -181.84241)
		(end 58.078878 -181.46141)
		(width 0.254)
		(layer "F.Cu")
		(net "VSENSE_PVDDCR_CPU0_P1_DP")
	)
	(segment
		(start 56.825134 -181.731666)
		(end 56.465724 -181.731666)
		(width 0.254)
		(layer "F.Cu")
		(net "VSENSE_PVDDCR_CPU0_P1_DP")
	)
	(segment
		(start 76.86802 -202.516994)
		(end 118.166388 -202.516994)
		(width 0.254)
		(layer "F.Cu")
		(net "VSENSE_PVDDCR_CPU0_P1_DP")
	)
	(segment
		(start 56.465724 -181.731666)
		(end 56.211724 -181.985666)
		(width 0.254)
		(layer "F.Cu")
		(net "VSENSE_PVDDCR_CPU0_P1_DP")
	)
	(segment
		(start 132.75437 -216.879932)
		(end 132.860796 -216.773506)
		(width 0.254)
		(layer "F.Cu")
		(net "VSENSE_PVDDCR_CPU0_P1_DP")
	)
	(segment
		(start 56.211724 -183.420512)
		(end 56.562244 -183.771032)
		(width 0.254)
		(layer "F.Cu")
		(net "VSENSE_PVDDCR_CPU0_P1_DP")
	)
	(segment
		(start 145.147792 -223.690434)
		(end 145.348706 -223.690434)
		(width 0.254)
		(layer "F.Cu")
		(net "VSENSE_PVDDCR_CPU0_P1_DP")
	)
	(segment
		(start 132.529326 -216.879932)
		(end 132.75437 -216.879932)
		(width 0.254)
		(layer "F.Cu")
		(net "VSENSE_PVDDCR_CPU0_P1_DP")
	)
	(segment
		(start 118.166388 -202.516994)
		(end 132.529326 -216.879932)
		(width 0.254)
		(layer "F.Cu")
		(net "VSENSE_PVDDCR_CPU0_P1_DP")
	)
	(segment
		(start 56.562244 -183.771032)
		(end 58.122058 -183.771032)
		(width 0.254)
		(layer "F.Cu")
		(net "VSENSE_PVDDCR_CPU0_P1_DP")
	)
	(segment
		(start 58.078878 -181.46141)
		(end 58.74004 -181.46141)
		(width 0.254)
		(layer "F.Cu")
		(net "VSENSE_PVDDCR_CPU0_P1_DP")
	)
	(segment
		(start 56.935878 -181.84241)
		(end 57.697878 -181.84241)
		(width 0.254)
		(layer "F.Cu")
		(net "VSENSE_PVDDCR_CPU0_P1_DP")
	)
	(via
		(at 56.935878 -181.84241)
		(size 0.508)
		(drill 0.254)
		(layers "F.Cu" "B.Cu")
		(net "VSENSE_PVDDCR_CPU0_P1_DP")
	)
	(via
		(at 145.614644 -223.424496)
		(size 0.4064)
		(drill 0.2032)
		(layers "F.Cu" "B.Cu")
		(net "VSENSE_PVDDCR_CPU0_P1_DP")
	)
	(via
		(at 132.860796 -216.773506)
		(size 0.508)
		(drill 0.254)
		(layers "F.Cu" "B.Cu")
		(net "VSENSE_PVDDCR_CPU0_P1_DP")
	)
	(via
		(at 92.750132 -151.776684)
		(size 0.508)
		(drill 0.254)
		(layers "F.Cu" "B.Cu")
		(net "VSENSE_PVDDCR_CPU0_P1_DP")
	)
	(segment
		(start 145.27276 -223.424496)
		(end 144.480534 -222.63227)
		(width 0.0762)
		(layer "B.Cu")
		(net "VSENSE_PVDDCR_CPU0_P1_DP")
	)
	(segment
		(start 132.974588 -216.887298)
		(end 132.860796 -216.773506)
		(width 0.254)
		(layer "B.Cu")
		(net "VSENSE_PVDDCR_CPU0_P1_DP")
	)
	(segment
		(start 134.056628 -218.736926)
		(end 134.056628 -217.63101)
		(width 0.254)
		(layer "B.Cu")
		(net "VSENSE_PVDDCR_CPU0_P1_DP")
	)
	(segment
		(start 144.138904 -221.212664)
		(end 144.138904 -221.174564)
		(width 0.1016)
		(layer "B.Cu")
		(net "VSENSE_PVDDCR_CPU0_P1_DP")
	)
	(segment
		(start 144.480534 -222.63227)
		(end 144.056354 -222.20809)
		(width 0.1016)
		(layer "B.Cu")
		(net "VSENSE_PVDDCR_CPU0_P1_DP")
	)
	(segment
		(start 144.056354 -222.20809)
		(end 144.056354 -221.295214)
		(width 0.1016)
		(layer "B.Cu")
		(net "VSENSE_PVDDCR_CPU0_P1_DP")
	)
	(segment
		(start 134.056628 -217.63101)
		(end 133.312916 -216.887298)
		(width 0.254)
		(layer "B.Cu")
		(net "VSENSE_PVDDCR_CPU0_P1_DP")
	)
	(segment
		(start 145.614644 -223.424496)
		(end 145.27276 -223.424496)
		(width 0.0762)
		(layer "B.Cu")
		(net "VSENSE_PVDDCR_CPU0_P1_DP")
	)
	(segment
		(start 144.138904 -220.550994)
		(end 143.472662 -219.884752)
		(width 0.254)
		(layer "B.Cu")
		(net "VSENSE_PVDDCR_CPU0_P1_DP")
	)
	(segment
		(start 143.472662 -219.884752)
		(end 135.204454 -219.884752)
		(width 0.254)
		(layer "B.Cu")
		(net "VSENSE_PVDDCR_CPU0_P1_DP")
	)
	(segment
		(start 135.204454 -219.884752)
		(end 134.056628 -218.736926)
		(width 0.254)
		(layer "B.Cu")
		(net "VSENSE_PVDDCR_CPU0_P1_DP")
	)
	(segment
		(start 133.312916 -216.887298)
		(end 132.974588 -216.887298)
		(width 0.254)
		(layer "B.Cu")
		(net "VSENSE_PVDDCR_CPU0_P1_DP")
	)
	(segment
		(start 144.138904 -221.174564)
		(end 144.138904 -220.550994)
		(width 0.254)
		(layer "B.Cu")
		(net "VSENSE_PVDDCR_CPU0_P1_DP")
	)
	(segment
		(start 144.056354 -221.295214)
		(end 144.138904 -221.212664)
		(width 0.1016)
		(layer "B.Cu")
		(net "VSENSE_PVDDCR_CPU0_P1_DP")
	)
	(segment
		(start 91.966542 -151.776684)
		(end 92.750132 -151.776684)
		(width 0.254)
		(layer "B.Cu")
		(net "VSENSE_PVDDCR_CPU0_P1_DP")
	)
	(segment
		(start 77.442314 -158.480252)
		(end 84.459064 -151.463502)
		(width 0.254)
		(layer "In2.Cu")
		(net "VSENSE_PVDDCR_CPU0_P1_DP")
	)
	(segment
		(start 58.971434 -164.119052)
		(end 64.610234 -158.480252)
		(width 0.254)
		(layer "In2.Cu")
		(net "VSENSE_PVDDCR_CPU0_P1_DP")
	)
	(segment
		(start 64.610234 -158.480252)
		(end 77.442314 -158.480252)
		(width 0.254)
		(layer "In2.Cu")
		(net "VSENSE_PVDDCR_CPU0_P1_DP")
	)
	(segment
		(start 58.507376 -181.65191)
		(end 60.241434 -179.917852)
		(width 0.254)
		(layer "In2.Cu")
		(net "VSENSE_PVDDCR_CPU0_P1_DP")
	)
	(segment
		(start 92.43695 -151.463502)
		(end 92.750132 -151.776684)
		(width 0.254)
		(layer "In2.Cu")
		(net "VSENSE_PVDDCR_CPU0_P1_DP")
	)
	(segment
		(start 56.935878 -181.84241)
		(end 57.126378 -181.65191)
		(width 0.254)
		(layer "In2.Cu")
		(net "VSENSE_PVDDCR_CPU0_P1_DP")
	)
	(segment
		(start 60.241434 -171.033186)
		(end 58.971434 -169.763186)
		(width 0.254)
		(layer "In2.Cu")
		(net "VSENSE_PVDDCR_CPU0_P1_DP")
	)
	(segment
		(start 60.241434 -179.917852)
		(end 60.241434 -171.033186)
		(width 0.254)
		(layer "In2.Cu")
		(net "VSENSE_PVDDCR_CPU0_P1_DP")
	)
	(segment
		(start 58.971434 -169.763186)
		(end 58.971434 -164.119052)
		(width 0.254)
		(layer "In2.Cu")
		(net "VSENSE_PVDDCR_CPU0_P1_DP")
	)
	(segment
		(start 57.126378 -181.65191)
		(end 58.507376 -181.65191)
		(width 0.254)
		(layer "In2.Cu")
		(net "VSENSE_PVDDCR_CPU0_P1_DP")
	)
	(segment
		(start 84.459064 -151.463502)
		(end 92.43695 -151.463502)
		(width 0.254)
		(layer "In2.Cu")
		(net "VSENSE_PVDDCR_CPU0_P1_DP")
	)
	(segment
		(start 376.198384 -146.08937)
		(end 375.2596 -147.028154)
		(width 0.1778)
		(layer "B.Cu")
		(net "VSENSE_PVDDCR_CPU0_P0_VSEN0")
	)
	(segment
		(start 374.770142 -147.902422)
		(end 374.770142 -148.655532)
		(width 0.254)
		(layer "B.Cu")
		(net "VSENSE_PVDDCR_CPU0_P0_VSEN0")
	)
	(segment
		(start 376.198384 -145.236184)
		(end 376.198384 -146.08937)
		(width 0.1778)
		(layer "B.Cu")
		(net "VSENSE_PVDDCR_CPU0_P0_VSEN0")
	)
	(segment
		(start 375.2596 -147.412964)
		(end 374.931432 -147.741132)
		(width 0.1778)
		(layer "B.Cu")
		(net "VSENSE_PVDDCR_CPU0_P0_VSEN0")
	)
	(segment
		(start 375.2596 -147.028154)
		(end 375.2596 -147.412964)
		(width 0.1778)
		(layer "B.Cu")
		(net "VSENSE_PVDDCR_CPU0_P0_VSEN0")
	)
	(segment
		(start 374.931432 -147.741132)
		(end 374.770142 -147.902422)
		(width 0.254)
		(layer "B.Cu")
		(net "VSENSE_PVDDCR_CPU0_P0_VSEN0")
	)
	(segment
		(start 393.288774 -223.69018)
		(end 393.554712 -223.424242)
		(width 0.254)
		(layer "F.Cu")
		(net "VSENSE_PVDDCR_CPU0_P0_DP")
	)
	(segment
		(start 358.182926 -210.466432)
		(end 364.388146 -216.671652)
		(width 0.254)
		(layer "F.Cu")
		(net "VSENSE_PVDDCR_CPU0_P0_DP")
	)
	(segment
		(start 364.388146 -216.671652)
		(end 375.383806 -216.671652)
		(width 0.254)
		(layer "F.Cu")
		(net "VSENSE_PVDDCR_CPU0_P0_DP")
	)
	(segment
		(start 393.08786 -223.69018)
		(end 393.288774 -223.69018)
		(width 0.254)
		(layer "F.Cu")
		(net "VSENSE_PVDDCR_CPU0_P0_DP")
	)
	(segment
		(start 339.663278 -172.40631)
		(end 339.917278 -172.15231)
		(width 0.254)
		(layer "F.Cu")
		(net "VSENSE_PVDDCR_CPU0_P0_DP")
	)
	(segment
		(start 375.383806 -216.671652)
		(end 377.402344 -218.69019)
		(width 0.254)
		(layer "F.Cu")
		(net "VSENSE_PVDDCR_CPU0_P0_DP")
	)
	(segment
		(start 342.163146 -210.466432)
		(end 358.182926 -210.466432)
		(width 0.254)
		(layer "F.Cu")
		(net "VSENSE_PVDDCR_CPU0_P0_DP")
	)
	(segment
		(start 332.726538 -201.029824)
		(end 342.163146 -210.466432)
		(width 0.254)
		(layer "F.Cu")
		(net "VSENSE_PVDDCR_CPU0_P0_DP")
	)
	(segment
		(start 335.156302 -172.113702)
		(end 332.726538 -174.543466)
		(width 0.254)
		(layer "F.Cu")
		(net "VSENSE_PVDDCR_CPU0_P0_DP")
	)
	(segment
		(start 339.663278 -172.40631)
		(end 339.37067 -172.113702)
		(width 0.254)
		(layer "F.Cu")
		(net "VSENSE_PVDDCR_CPU0_P0_DP")
	)
	(segment
		(start 341.018622 -172.15231)
		(end 340.425278 -172.15231)
		(width 0.254)
		(layer "F.Cu")
		(net "VSENSE_PVDDCR_CPU0_P0_DP")
	)
	(segment
		(start 377.402344 -218.69019)
		(end 380.696724 -218.69019)
		(width 0.254)
		(layer "F.Cu")
		(net "VSENSE_PVDDCR_CPU0_P0_DP")
	)
	(segment
		(start 339.917278 -172.15231)
		(end 340.425278 -172.15231)
		(width 0.254)
		(layer "F.Cu")
		(net "VSENSE_PVDDCR_CPU0_P0_DP")
	)
	(segment
		(start 332.726538 -174.543466)
		(end 332.726538 -201.029824)
		(width 0.254)
		(layer "F.Cu")
		(net "VSENSE_PVDDCR_CPU0_P0_DP")
	)
	(segment
		(start 339.37067 -172.113702)
		(end 335.156302 -172.113702)
		(width 0.254)
		(layer "F.Cu")
		(net "VSENSE_PVDDCR_CPU0_P0_DP")
	)
	(segment
		(start 341.178134 -172.311822)
		(end 341.018622 -172.15231)
		(width 0.254)
		(layer "F.Cu")
		(net "VSENSE_PVDDCR_CPU0_P0_DP")
	)
	(segment
		(start 380.696724 -218.69019)
		(end 380.865126 -218.521788)
		(width 0.254)
		(layer "F.Cu")
		(net "VSENSE_PVDDCR_CPU0_P0_DP")
	)
	(via
		(at 380.865126 -218.521788)
		(size 0.508)
		(drill 0.254)
		(layers "F.Cu" "B.Cu")
		(net "VSENSE_PVDDCR_CPU0_P0_DP")
	)
	(via
		(at 375.477532 -149.379432)
		(size 0.508)
		(drill 0.254)
		(layers "F.Cu" "B.Cu")
		(net "VSENSE_PVDDCR_CPU0_P0_DP")
	)
	(via
		(at 393.554712 -223.424242)
		(size 0.4064)
		(drill 0.2032)
		(layers "F.Cu" "B.Cu")
		(net "VSENSE_PVDDCR_CPU0_P0_DP")
	)
	(via
		(at 340.425278 -172.15231)
		(size 0.508)
		(drill 0.254)
		(layers "F.Cu" "B.Cu")
		(net "VSENSE_PVDDCR_CPU0_P0_DP")
	)
	(segment
		(start 374.846342 -149.379432)
		(end 375.477532 -149.379432)
		(width 0.254)
		(layer "B.Cu")
		(net "VSENSE_PVDDCR_CPU0_P0_DP")
	)
	(segment
		(start 374.770142 -149.455632)
		(end 374.846342 -149.379432)
		(width 0.254)
		(layer "B.Cu")
		(net "VSENSE_PVDDCR_CPU0_P0_DP")
	)
	(segment
		(start 345.54668 -154.094434)
		(end 341.899748 -157.741366)
		(width 0.254)
		(layer "In2.Cu")
		(net "VSENSE_PVDDCR_CPU0_P0_DP")
	)
	(segment
		(start 361.893866 -150.72233)
		(end 361.353608 -150.182072)
		(width 0.254)
		(layer "In2.Cu")
		(net "VSENSE_PVDDCR_CPU0_P0_DP")
	)
	(segment
		(start 341.899748 -163.576)
		(end 341.899748 -171.381928)
		(width 0.254)
		(layer "In2.Cu")
		(net "VSENSE_PVDDCR_CPU0_P0_DP")
	)
	(segment
		(start 375.164604 -149.379432)
		(end 373.821706 -150.72233)
		(width 0.254)
		(layer "In2.Cu")
		(net "VSENSE_PVDDCR_CPU0_P0_DP")
	)
	(segment
		(start 342.89238 -162.583368)
		(end 341.899748 -163.576)
		(width 0.254)
		(layer "In2.Cu")
		(net "VSENSE_PVDDCR_CPU0_P0_DP")
	)
	(segment
		(start 342.89238 -160.085024)
		(end 342.89238 -162.583368)
		(width 0.254)
		(layer "In2.Cu")
		(net "VSENSE_PVDDCR_CPU0_P0_DP")
	)
	(segment
		(start 341.899748 -157.741366)
		(end 341.899748 -159.092392)
		(width 0.254)
		(layer "In2.Cu")
		(net "VSENSE_PVDDCR_CPU0_P0_DP")
	)
	(segment
		(start 340.592918 -171.98467)
		(end 340.425278 -172.15231)
		(width 0.254)
		(layer "In2.Cu")
		(net "VSENSE_PVDDCR_CPU0_P0_DP")
	)
	(segment
		(start 361.353608 -150.182072)
		(end 355.672136 -150.182072)
		(width 0.254)
		(layer "In2.Cu")
		(net "VSENSE_PVDDCR_CPU0_P0_DP")
	)
	(segment
		(start 351.759774 -154.094434)
		(end 345.54668 -154.094434)
		(width 0.254)
		(layer "In2.Cu")
		(net "VSENSE_PVDDCR_CPU0_P0_DP")
	)
	(segment
		(start 341.297006 -171.98467)
		(end 340.592918 -171.98467)
		(width 0.254)
		(layer "In2.Cu")
		(net "VSENSE_PVDDCR_CPU0_P0_DP")
	)
	(segment
		(start 355.672136 -150.182072)
		(end 351.759774 -154.094434)
		(width 0.254)
		(layer "In2.Cu")
		(net "VSENSE_PVDDCR_CPU0_P0_DP")
	)
	(segment
		(start 341.899748 -159.092392)
		(end 342.89238 -160.085024)
		(width 0.254)
		(layer "In2.Cu")
		(net "VSENSE_PVDDCR_CPU0_P0_DP")
	)
	(segment
		(start 373.821706 -150.72233)
		(end 361.893866 -150.72233)
		(width 0.254)
		(layer "In2.Cu")
		(net "VSENSE_PVDDCR_CPU0_P0_DP")
	)
	(segment
		(start 375.477532 -149.379432)
		(end 375.164604 -149.379432)
		(width 0.254)
		(layer "In2.Cu")
		(net "VSENSE_PVDDCR_CPU0_P0_DP")
	)
	(segment
		(start 341.899748 -171.381928)
		(end 341.297006 -171.98467)
		(width 0.254)
		(layer "In2.Cu")
		(net "VSENSE_PVDDCR_CPU0_P0_DP")
	)
	(segment
		(start 385.804664 -220.664532)
		(end 390.483852 -220.664532)
		(width 0.254)
		(layer "In15.Cu")
		(net "VSENSE_PVDDCR_CPU0_P0_DP")
	)
	(segment
		(start 383.78892 -218.648788)
		(end 385.804664 -220.664532)
		(width 0.254)
		(layer "In15.Cu")
		(net "VSENSE_PVDDCR_CPU0_P0_DP")
	)
	(segment
		(start 393.15263 -223.33331)
		(end 393.46378 -223.33331)
		(width 0.254)
		(layer "In15.Cu")
		(net "VSENSE_PVDDCR_CPU0_P0_DP")
	)
	(segment
		(start 380.992126 -218.648788)
		(end 383.78892 -218.648788)
		(width 0.254)
		(layer "In15.Cu")
		(net "VSENSE_PVDDCR_CPU0_P0_DP")
	)
	(segment
		(start 380.865126 -218.521788)
		(end 380.992126 -218.648788)
		(width 0.254)
		(layer "In15.Cu")
		(net "VSENSE_PVDDCR_CPU0_P0_DP")
	)
	(segment
		(start 393.46378 -223.33331)
		(end 393.554712 -223.424242)
		(width 0.254)
		(layer "In15.Cu")
		(net "VSENSE_PVDDCR_CPU0_P0_DP")
	)
	(segment
		(start 390.483852 -220.664532)
		(end 393.15263 -223.33331)
		(width 0.254)
		(layer "In15.Cu")
		(net "VSENSE_PVDDCR_CPU0_P0_DP")
	)
	(segment
		(start 77.721714 -220.849444)
		(end 77.721714 -222.874332)
		(width 0.254)
		(layer "F.Cu")
		(net "VSENSE_PVDD18_S5_P1_DP")
	)
	(segment
		(start 62.334902 -193.140076)
		(end 61.88075 -193.594228)
		(width 0.254)
		(layer "F.Cu")
		(net "VSENSE_PVDD18_S5_P1_DP")
	)
	(segment
		(start 85.478366 -212.22716)
		(end 85.478366 -214.305134)
		(width 0.254)
		(layer "F.Cu")
		(net "VSENSE_PVDD18_S5_P1_DP")
	)
	(segment
		(start 53.449982 -188.011308)
		(end 56.787288 -191.348614)
		(width 0.254)
		(layer "F.Cu")
		(net "VSENSE_PVDD18_S5_P1_DP")
	)
	(segment
		(start 61.88075 -193.594228)
		(end 62.334902 -194.04838)
		(width 0.254)
		(layer "F.Cu")
		(net "VSENSE_PVDD18_S5_P1_DP")
	)
	(segment
		(start 83.290156 -216.723214)
		(end 80.829912 -217.741246)
		(width 0.254)
		(layer "F.Cu")
		(net "VSENSE_PVDD18_S5_P1_DP")
	)
	(segment
		(start 56.787288 -191.348614)
		(end 61.054996 -191.348614)
		(width 0.254)
		(layer "F.Cu")
		(net "VSENSE_PVDD18_S5_P1_DP")
	)
	(segment
		(start 84.55533 -215.685624)
		(end 83.290156 -216.723214)
		(width 0.254)
		(layer "F.Cu")
		(net "VSENSE_PVDD18_S5_P1_DP")
	)
	(segment
		(start 61.054996 -191.348614)
		(end 62.334902 -192.62852)
		(width 0.254)
		(layer "F.Cu")
		(net "VSENSE_PVDD18_S5_P1_DP")
	)
	(segment
		(start 77.953108 -223.105726)
		(end 78.30693 -223.310958)
		(width 0.254)
		(layer "F.Cu")
		(net "VSENSE_PVDD18_S5_P1_DP")
	)
	(segment
		(start 78.951074 -208.746598)
		(end 83.153504 -208.746598)
		(width 0.254)
		(layer "F.Cu")
		(net "VSENSE_PVDD18_S5_P1_DP")
	)
	(segment
		(start 73.512934 -146.074892)
		(end 73.512934 -145.530062)
		(width 0.254)
		(layer "F.Cu")
		(net "VSENSE_PVDD18_S5_P1_DP")
	)
	(segment
		(start 80.829912 -217.741246)
		(end 77.721714 -220.849444)
		(width 0.254)
		(layer "F.Cu")
		(net "VSENSE_PVDD18_S5_P1_DP")
	)
	(segment
		(start 62.334902 -192.62852)
		(end 62.334902 -193.140076)
		(width 0.254)
		(layer "F.Cu")
		(net "VSENSE_PVDD18_S5_P1_DP")
	)
	(segment
		(start 62.334902 -194.04838)
		(end 62.334902 -194.596004)
		(width 0.254)
		(layer "F.Cu")
		(net "VSENSE_PVDD18_S5_P1_DP")
	)
	(segment
		(start 62.334902 -194.596004)
		(end 61.308234 -195.622672)
		(width 0.254)
		(layer "F.Cu")
		(net "VSENSE_PVDD18_S5_P1_DP")
	)
	(segment
		(start 85.094064 -210.687158)
		(end 85.478366 -212.22716)
		(width 0.254)
		(layer "F.Cu")
		(net "VSENSE_PVDD18_S5_P1_DP")
	)
	(segment
		(start 85.478366 -214.305134)
		(end 84.55533 -215.685624)
		(width 0.254)
		(layer "F.Cu")
		(net "VSENSE_PVDD18_S5_P1_DP")
	)
	(segment
		(start 83.153504 -208.746598)
		(end 85.094064 -210.687158)
		(width 0.254)
		(layer "F.Cu")
		(net "VSENSE_PVDD18_S5_P1_DP")
	)
	(segment
		(start 73.113646 -208.931764)
		(end 78.765908 -208.931764)
		(width 0.254)
		(layer "F.Cu")
		(net "VSENSE_PVDD18_S5_P1_DP")
	)
	(segment
		(start 52.692046 -181.692296)
		(end 52.692046 -183.130444)
		(width 0.254)
		(layer "F.Cu")
		(net "VSENSE_PVDD18_S5_P1_DP")
	)
	(segment
		(start 53.449982 -183.88838)
		(end 53.449982 -188.011308)
		(width 0.254)
		(layer "F.Cu")
		(net "VSENSE_PVDD18_S5_P1_DP")
	)
	(segment
		(start 61.308234 -195.622672)
		(end 61.308234 -197.126352)
		(width 0.254)
		(layer "F.Cu")
		(net "VSENSE_PVDD18_S5_P1_DP")
	)
	(segment
		(start 73.512934 -145.530062)
		(end 72.863964 -144.881092)
		(width 0.254)
		(layer "F.Cu")
		(net "VSENSE_PVDD18_S5_P1_DP")
	)
	(segment
		(start 52.374546 -181.374796)
		(end 52.692046 -181.692296)
		(width 0.254)
		(layer "F.Cu")
		(net "VSENSE_PVDD18_S5_P1_DP")
	)
	(segment
		(start 61.308234 -197.126352)
		(end 73.113646 -208.931764)
		(width 0.254)
		(layer "F.Cu")
		(net "VSENSE_PVDD18_S5_P1_DP")
	)
	(segment
		(start 77.721714 -222.874332)
		(end 77.953108 -223.105726)
		(width 0.254)
		(layer "F.Cu")
		(net "VSENSE_PVDD18_S5_P1_DP")
	)
	(segment
		(start 78.30693 -223.310958)
		(end 78.408022 -223.690434)
		(width 0.254)
		(layer "F.Cu")
		(net "VSENSE_PVDD18_S5_P1_DP")
	)
	(segment
		(start 78.765908 -208.931764)
		(end 78.951074 -208.746598)
		(width 0.254)
		(layer "F.Cu")
		(net "VSENSE_PVDD18_S5_P1_DP")
	)
	(segment
		(start 52.692046 -183.130444)
		(end 53.449982 -183.88838)
		(width 0.254)
		(layer "F.Cu")
		(net "VSENSE_PVDD18_S5_P1_DP")
	)
	(via
		(at 52.374546 -181.374796)
		(size 0.508)
		(drill 0.254)
		(layers "F.Cu" "B.Cu")
		(net "VSENSE_PVDD18_S5_P1_DP")
	)
	(via
		(at 73.512934 -146.074892)
		(size 0.508)
		(drill 0.254)
		(layers "F.Cu" "B.Cu")
		(net "VSENSE_PVDD18_S5_P1_DP")
	)
	(segment
		(start 71.737982 -145.725134)
		(end 71.737982 -143.865854)
		(width 0.254)
		(layer "B.Cu")
		(net "VSENSE_PVDD18_S5_P1_DP")
	)
	(segment
		(start 48.487584 -142.60068)
		(end 47.655734 -143.43253)
		(width 0.254)
		(layer "B.Cu")
		(net "VSENSE_PVDD18_S5_P1_DP")
	)
	(segment
		(start 72.08774 -146.074892)
		(end 71.737982 -145.725134)
		(width 0.254)
		(layer "B.Cu")
		(net "VSENSE_PVDD18_S5_P1_DP")
	)
	(segment
		(start 52.692046 -180.11902)
		(end 52.692046 -181.057296)
		(width 0.254)
		(layer "B.Cu")
		(net "VSENSE_PVDD18_S5_P1_DP")
	)
	(segment
		(start 73.512934 -146.074892)
		(end 72.08774 -146.074892)
		(width 0.254)
		(layer "B.Cu")
		(net "VSENSE_PVDD18_S5_P1_DP")
	)
	(segment
		(start 71.737982 -143.865854)
		(end 70.472808 -142.60068)
		(width 0.254)
		(layer "B.Cu")
		(net "VSENSE_PVDD18_S5_P1_DP")
	)
	(segment
		(start 52.692046 -181.057296)
		(end 52.374546 -181.374796)
		(width 0.254)
		(layer "B.Cu")
		(net "VSENSE_PVDD18_S5_P1_DP")
	)
	(segment
		(start 47.655734 -143.43253)
		(end 47.655734 -175.082708)
		(width 0.254)
		(layer "B.Cu")
		(net "VSENSE_PVDD18_S5_P1_DP")
	)
	(segment
		(start 47.655734 -175.082708)
		(end 52.692046 -180.11902)
		(width 0.254)
		(layer "B.Cu")
		(net "VSENSE_PVDD18_S5_P1_DP")
	)
	(segment
		(start 70.472808 -142.60068)
		(end 48.487584 -142.60068)
		(width 0.254)
		(layer "B.Cu")
		(net "VSENSE_PVDD18_S5_P1_DP")
	)
	(segment
		(start 53.830982 -183.730392)
		(end 53.830982 -187.85332)
		(width 0.254)
		(layer "F.Cu")
		(net "VSENSE_PVDD18_S5_P1_DN")
	)
	(segment
		(start 85.438234 -210.49234)
		(end 85.859366 -212.18017)
		(width 0.254)
		(layer "F.Cu")
		(net "VSENSE_PVDD18_S5_P1_DN")
	)
	(segment
		(start 78.792832 -208.365598)
		(end 83.311492 -208.365598)
		(width 0.254)
		(layer "F.Cu")
		(net "VSENSE_PVDD18_S5_P1_DN")
	)
	(segment
		(start 81.045812 -218.064588)
		(end 78.102714 -221.007432)
		(width 0.254)
		(layer "F.Cu")
		(net "VSENSE_PVDD18_S5_P1_DN")
	)
	(segment
		(start 63.15075 -193.594228)
		(end 62.715902 -194.029076)
		(width 0.254)
		(layer "F.Cu")
		(net "VSENSE_PVDD18_S5_P1_DN")
	)
	(segment
		(start 78.102714 -222.716344)
		(end 78.18755 -222.800926)
		(width 0.254)
		(layer "F.Cu")
		(net "VSENSE_PVDD18_S5_P1_DN")
	)
	(segment
		(start 78.497938 -222.981266)
		(end 78.498192 -222.981266)
		(width 0.254)
		(layer "F.Cu")
		(net "VSENSE_PVDD18_S5_P1_DN")
	)
	(segment
		(start 53.073046 -182.972456)
		(end 53.830982 -183.730392)
		(width 0.254)
		(layer "F.Cu")
		(net "VSENSE_PVDD18_S5_P1_DN")
	)
	(segment
		(start 70.320154 -144.881092)
		(end 69.620384 -145.580862)
		(width 0.254)
		(layer "F.Cu")
		(net "VSENSE_PVDD18_S5_P1_DN")
	)
	(segment
		(start 61.689234 -196.968364)
		(end 73.271634 -208.550764)
		(width 0.254)
		(layer "F.Cu")
		(net "VSENSE_PVDD18_S5_P1_DN")
	)
	(segment
		(start 78.18755 -222.800926)
		(end 78.497938 -222.981266)
		(width 0.254)
		(layer "F.Cu")
		(net "VSENSE_PVDD18_S5_P1_DN")
	)
	(segment
		(start 62.715902 -192.470532)
		(end 62.715902 -193.15938)
		(width 0.254)
		(layer "F.Cu")
		(net "VSENSE_PVDD18_S5_P1_DN")
	)
	(segment
		(start 69.620384 -145.580862)
		(end 69.620384 -145.973292)
		(width 0.254)
		(layer "F.Cu")
		(net "VSENSE_PVDD18_S5_P1_DN")
	)
	(segment
		(start 53.830982 -187.85332)
		(end 56.945276 -190.967614)
		(width 0.254)
		(layer "F.Cu")
		(net "VSENSE_PVDD18_S5_P1_DN")
	)
	(segment
		(start 83.311492 -208.365598)
		(end 85.438234 -210.49234)
		(width 0.254)
		(layer "F.Cu")
		(net "VSENSE_PVDD18_S5_P1_DN")
	)
	(segment
		(start 53.073046 -181.692296)
		(end 53.073046 -182.972456)
		(width 0.254)
		(layer "F.Cu")
		(net "VSENSE_PVDD18_S5_P1_DN")
	)
	(segment
		(start 73.271634 -208.550764)
		(end 78.607666 -208.550764)
		(width 0.254)
		(layer "F.Cu")
		(net "VSENSE_PVDD18_S5_P1_DN")
	)
	(segment
		(start 78.498192 -222.981266)
		(end 78.877922 -222.880428)
		(width 0.254)
		(layer "F.Cu")
		(net "VSENSE_PVDD18_S5_P1_DN")
	)
	(segment
		(start 84.840826 -215.94445)
		(end 83.488022 -217.053922)
		(width 0.254)
		(layer "F.Cu")
		(net "VSENSE_PVDD18_S5_P1_DN")
	)
	(segment
		(start 78.607666 -208.550764)
		(end 78.792832 -208.365598)
		(width 0.254)
		(layer "F.Cu")
		(net "VSENSE_PVDD18_S5_P1_DN")
	)
	(segment
		(start 62.715902 -194.753992)
		(end 61.689234 -195.78066)
		(width 0.254)
		(layer "F.Cu")
		(net "VSENSE_PVDD18_S5_P1_DN")
	)
	(segment
		(start 61.212984 -190.967614)
		(end 62.715902 -192.470532)
		(width 0.254)
		(layer "F.Cu")
		(net "VSENSE_PVDD18_S5_P1_DN")
	)
	(segment
		(start 56.945276 -190.967614)
		(end 61.212984 -190.967614)
		(width 0.254)
		(layer "F.Cu")
		(net "VSENSE_PVDD18_S5_P1_DN")
	)
	(segment
		(start 85.859366 -214.420958)
		(end 84.840826 -215.94445)
		(width 0.254)
		(layer "F.Cu")
		(net "VSENSE_PVDD18_S5_P1_DN")
	)
	(segment
		(start 78.102714 -221.007432)
		(end 78.102714 -222.716344)
		(width 0.254)
		(layer "F.Cu")
		(net "VSENSE_PVDD18_S5_P1_DN")
	)
	(segment
		(start 85.859366 -212.18017)
		(end 85.859366 -214.420958)
		(width 0.254)
		(layer "F.Cu")
		(net "VSENSE_PVDD18_S5_P1_DN")
	)
	(segment
		(start 53.390546 -181.374796)
		(end 53.073046 -181.692296)
		(width 0.254)
		(layer "F.Cu")
		(net "VSENSE_PVDD18_S5_P1_DN")
	)
	(segment
		(start 61.689234 -195.78066)
		(end 61.689234 -196.968364)
		(width 0.254)
		(layer "F.Cu")
		(net "VSENSE_PVDD18_S5_P1_DN")
	)
	(segment
		(start 62.715902 -194.029076)
		(end 62.715902 -194.753992)
		(width 0.254)
		(layer "F.Cu")
		(net "VSENSE_PVDD18_S5_P1_DN")
	)
	(segment
		(start 83.488022 -217.053922)
		(end 81.045812 -218.064588)
		(width 0.254)
		(layer "F.Cu")
		(net "VSENSE_PVDD18_S5_P1_DN")
	)
	(segment
		(start 62.715902 -193.15938)
		(end 63.15075 -193.594228)
		(width 0.254)
		(layer "F.Cu")
		(net "VSENSE_PVDD18_S5_P1_DN")
	)
	(via
		(at 53.390546 -181.374796)
		(size 0.508)
		(drill 0.254)
		(layers "F.Cu" "B.Cu")
		(net "VSENSE_PVDD18_S5_P1_DN")
	)
	(via
		(at 69.620384 -145.973292)
		(size 0.508)
		(drill 0.254)
		(layers "F.Cu" "B.Cu")
		(net "VSENSE_PVDD18_S5_P1_DN")
	)
	(segment
		(start 53.073046 -179.961032)
		(end 53.073046 -181.057296)
		(width 0.254)
		(layer "B.Cu")
		(net "VSENSE_PVDD18_S5_P1_DN")
	)
	(segment
		(start 69.620384 -145.973292)
		(end 71.102982 -145.973292)
		(width 0.254)
		(layer "B.Cu")
		(net "VSENSE_PVDD18_S5_P1_DN")
	)
	(segment
		(start 71.102982 -145.973292)
		(end 71.356982 -145.719292)
		(width 0.254)
		(layer "B.Cu")
		(net "VSENSE_PVDD18_S5_P1_DN")
	)
	(segment
		(start 70.31482 -142.98168)
		(end 48.645572 -142.98168)
		(width 0.254)
		(layer "B.Cu")
		(net "VSENSE_PVDD18_S5_P1_DN")
	)
	(segment
		(start 71.356982 -144.023842)
		(end 70.31482 -142.98168)
		(width 0.254)
		(layer "B.Cu")
		(net "VSENSE_PVDD18_S5_P1_DN")
	)
	(segment
		(start 71.356982 -145.719292)
		(end 71.356982 -144.023842)
		(width 0.254)
		(layer "B.Cu")
		(net "VSENSE_PVDD18_S5_P1_DN")
	)
	(segment
		(start 48.645572 -142.98168)
		(end 48.036734 -143.590518)
		(width 0.254)
		(layer "B.Cu")
		(net "VSENSE_PVDD18_S5_P1_DN")
	)
	(segment
		(start 48.036734 -174.92472)
		(end 53.073046 -179.961032)
		(width 0.254)
		(layer "B.Cu")
		(net "VSENSE_PVDD18_S5_P1_DN")
	)
	(segment
		(start 48.036734 -143.590518)
		(end 48.036734 -174.92472)
		(width 0.254)
		(layer "B.Cu")
		(net "VSENSE_PVDD18_S5_P1_DN")
	)
	(segment
		(start 53.073046 -181.057296)
		(end 53.390546 -181.374796)
		(width 0.254)
		(layer "B.Cu")
		(net "VSENSE_PVDD18_S5_P1_DN")
	)
	(segment
		(start 316.197234 -183.934608)
		(end 310.070754 -177.808128)
		(width 0.254)
		(layer "F.Cu")
		(net "VSENSE_PVDD18_S5_P0_DP")
	)
	(segment
		(start 316.197234 -194.792092)
		(end 316.197234 -183.934608)
		(width 0.254)
		(layer "F.Cu")
		(net "VSENSE_PVDD18_S5_P0_DP")
	)
	(segment
		(start 326.508872 -203.80833)
		(end 325.213472 -203.80833)
		(width 0.254)
		(layer "F.Cu")
		(net "VSENSE_PVDD18_S5_P0_DP")
	)
	(segment
		(start 333.690214 -210.989672)
		(end 326.508872 -203.80833)
		(width 0.254)
		(layer "F.Cu")
		(net "VSENSE_PVDD18_S5_P0_DP")
	)
	(segment
		(start 308.385464 -153.589736)
		(end 305.402742 -153.589736)
		(width 0.254)
		(layer "F.Cu")
		(net "VSENSE_PVDD18_S5_P0_DP")
	)
	(segment
		(start 333.690214 -214.95004)
		(end 333.690214 -210.989672)
		(width 0.254)
		(layer "F.Cu")
		(net "VSENSE_PVDD18_S5_P0_DP")
	)
	(segment
		(start 325.213472 -203.80833)
		(end 316.197234 -194.792092)
		(width 0.254)
		(layer "F.Cu")
		(net "VSENSE_PVDD18_S5_P0_DP")
	)
	(segment
		(start 328.569574 -137.849864)
		(end 328.367644 -138.051794)
		(width 0.254)
		(layer "F.Cu")
		(net "VSENSE_PVDD18_S5_P0_DP")
	)
	(segment
		(start 304.621946 -153.54554)
		(end 304.065432 -153.54554)
		(width 0.254)
		(layer "F.Cu")
		(net "VSENSE_PVDD18_S5_P0_DP")
	)
	(segment
		(start 328.679302 -219.960952)
		(end 333.690214 -214.95004)
		(width 0.254)
		(layer "F.Cu")
		(net "VSENSE_PVDD18_S5_P0_DP")
	)
	(segment
		(start 326.247252 -223.31045)
		(end 325.824596 -223.065594)
		(width 0.254)
		(layer "F.Cu")
		(net "VSENSE_PVDD18_S5_P0_DP")
	)
	(segment
		(start 325.824596 -220.749114)
		(end 326.612758 -219.960952)
		(width 0.254)
		(layer "F.Cu")
		(net "VSENSE_PVDD18_S5_P0_DP")
	)
	(segment
		(start 305.402742 -153.589736)
		(end 305.034442 -153.958036)
		(width 0.254)
		(layer "F.Cu")
		(net "VSENSE_PVDD18_S5_P0_DP")
	)
	(segment
		(start 326.612758 -219.960952)
		(end 328.679302 -219.960952)
		(width 0.254)
		(layer "F.Cu")
		(net "VSENSE_PVDD18_S5_P0_DP")
	)
	(segment
		(start 328.367644 -138.051794)
		(end 328.367644 -138.492992)
		(width 0.254)
		(layer "F.Cu")
		(net "VSENSE_PVDD18_S5_P0_DP")
	)
	(segment
		(start 310.070754 -155.275026)
		(end 308.385464 -153.589736)
		(width 0.254)
		(layer "F.Cu")
		(net "VSENSE_PVDD18_S5_P0_DP")
	)
	(segment
		(start 325.824596 -223.065594)
		(end 325.824596 -220.749114)
		(width 0.254)
		(layer "F.Cu")
		(net "VSENSE_PVDD18_S5_P0_DP")
	)
	(segment
		(start 326.34809 -223.69018)
		(end 326.247252 -223.31045)
		(width 0.254)
		(layer "F.Cu")
		(net "VSENSE_PVDD18_S5_P0_DP")
	)
	(segment
		(start 304.065432 -153.54554)
		(end 303.69383 -153.917142)
		(width 0.254)
		(layer "F.Cu")
		(net "VSENSE_PVDD18_S5_P0_DP")
	)
	(segment
		(start 310.070754 -177.808128)
		(end 310.070754 -155.275026)
		(width 0.254)
		(layer "F.Cu")
		(net "VSENSE_PVDD18_S5_P0_DP")
	)
	(segment
		(start 305.034442 -153.958036)
		(end 304.621946 -153.54554)
		(width 0.254)
		(layer "F.Cu")
		(net "VSENSE_PVDD18_S5_P0_DP")
	)
	(via
		(at 328.569574 -137.849864)
		(size 0.508)
		(drill 0.254)
		(layers "F.Cu" "B.Cu")
		(net "VSENSE_PVDD18_S5_P0_DP")
	)
	(via
		(at 305.034442 -153.958036)
		(size 0.508)
		(drill 0.254)
		(layers "F.Cu" "B.Cu")
		(net "VSENSE_PVDD18_S5_P0_DP")
	)
	(segment
		(start 316.904116 -152.354788)
		(end 315.669168 -153.589736)
		(width 0.254)
		(layer "In2.Cu")
		(net "VSENSE_PVDD18_S5_P0_DP")
	)
	(segment
		(start 328.569574 -139.949174)
		(end 329.029568 -140.409168)
		(width 0.254)
		(layer "In2.Cu")
		(net "VSENSE_PVDD18_S5_P0_DP")
	)
	(segment
		(start 321.855846 -152.354788)
		(end 316.904116 -152.354788)
		(width 0.254)
		(layer "In2.Cu")
		(net "VSENSE_PVDD18_S5_P0_DP")
	)
	(segment
		(start 305.402742 -153.589736)
		(end 305.034442 -153.958036)
		(width 0.254)
		(layer "In2.Cu")
		(net "VSENSE_PVDD18_S5_P0_DP")
	)
	(segment
		(start 330.072746 -144.137888)
		(end 321.855846 -152.354788)
		(width 0.254)
		(layer "In2.Cu")
		(net "VSENSE_PVDD18_S5_P0_DP")
	)
	(segment
		(start 329.960986 -140.751814)
		(end 329.96124 -140.751814)
		(width 0.254)
		(layer "In2.Cu")
		(net "VSENSE_PVDD18_S5_P0_DP")
	)
	(segment
		(start 330.072746 -140.863574)
		(end 330.072746 -144.137888)
		(width 0.254)
		(layer "In2.Cu")
		(net "VSENSE_PVDD18_S5_P0_DP")
	)
	(segment
		(start 329.029568 -140.409168)
		(end 329.03922 -140.399516)
		(width 0.254)
		(layer "In2.Cu")
		(net "VSENSE_PVDD18_S5_P0_DP")
	)
	(segment
		(start 329.608688 -140.399516)
		(end 329.960986 -140.751814)
		(width 0.254)
		(layer "In2.Cu")
		(net "VSENSE_PVDD18_S5_P0_DP")
	)
	(segment
		(start 329.03922 -140.399516)
		(end 329.608688 -140.399516)
		(width 0.254)
		(layer "In2.Cu")
		(net "VSENSE_PVDD18_S5_P0_DP")
	)
	(segment
		(start 315.669168 -153.589736)
		(end 305.402742 -153.589736)
		(width 0.254)
		(layer "In2.Cu")
		(net "VSENSE_PVDD18_S5_P0_DP")
	)
	(segment
		(start 328.569574 -137.849864)
		(end 328.569574 -139.949174)
		(width 0.254)
		(layer "In2.Cu")
		(net "VSENSE_PVDD18_S5_P0_DP")
	)
	(segment
		(start 329.96124 -140.751814)
		(end 330.072746 -140.863574)
		(width 0.254)
		(layer "In2.Cu")
		(net "VSENSE_PVDD18_S5_P0_DP")
	)
	(segment
		(start 326.438514 -222.980758)
		(end 326.205596 -222.84563)
		(width 0.254)
		(layer "F.Cu")
		(net "VSENSE_PVDD18_S5_P0_DN")
	)
	(segment
		(start 325.37146 -203.42733)
		(end 316.578234 -194.634104)
		(width 0.254)
		(layer "F.Cu")
		(net "VSENSE_PVDD18_S5_P0_DN")
	)
	(segment
		(start 326.66686 -203.42733)
		(end 325.37146 -203.42733)
		(width 0.254)
		(layer "F.Cu")
		(net "VSENSE_PVDD18_S5_P0_DN")
	)
	(segment
		(start 308.543452 -153.208736)
		(end 305.402742 -153.208736)
		(width 0.254)
		(layer "F.Cu")
		(net "VSENSE_PVDD18_S5_P0_DN")
	)
	(segment
		(start 310.451754 -155.117038)
		(end 308.543452 -153.208736)
		(width 0.254)
		(layer "F.Cu")
		(net "VSENSE_PVDD18_S5_P0_DN")
	)
	(segment
		(start 326.81799 -222.880174)
		(end 326.438514 -222.980758)
		(width 0.254)
		(layer "F.Cu")
		(net "VSENSE_PVDD18_S5_P0_DN")
	)
	(segment
		(start 305.402742 -153.208736)
		(end 305.034442 -152.840436)
		(width 0.254)
		(layer "F.Cu")
		(net "VSENSE_PVDD18_S5_P0_DN")
	)
	(segment
		(start 334.071214 -215.108028)
		(end 334.071214 -210.831684)
		(width 0.254)
		(layer "F.Cu")
		(net "VSENSE_PVDD18_S5_P0_DN")
	)
	(segment
		(start 334.071214 -210.831684)
		(end 326.66686 -203.42733)
		(width 0.254)
		(layer "F.Cu")
		(net "VSENSE_PVDD18_S5_P0_DN")
	)
	(segment
		(start 304.710338 -153.16454)
		(end 303.982628 -153.16454)
		(width 0.254)
		(layer "F.Cu")
		(net "VSENSE_PVDD18_S5_P0_DN")
	)
	(segment
		(start 326.205596 -220.907102)
		(end 326.770746 -220.341952)
		(width 0.254)
		(layer "F.Cu")
		(net "VSENSE_PVDD18_S5_P0_DN")
	)
	(segment
		(start 326.770746 -220.341952)
		(end 328.83729 -220.341952)
		(width 0.254)
		(layer "F.Cu")
		(net "VSENSE_PVDD18_S5_P0_DN")
	)
	(segment
		(start 329.223624 -142.268702)
		(end 329.223624 -141.991842)
		(width 0.254)
		(layer "F.Cu")
		(net "VSENSE_PVDD18_S5_P0_DN")
	)
	(segment
		(start 316.578234 -183.77662)
		(end 310.451754 -177.65014)
		(width 0.254)
		(layer "F.Cu")
		(net "VSENSE_PVDD18_S5_P0_DN")
	)
	(segment
		(start 310.451754 -177.65014)
		(end 310.451754 -155.117038)
		(width 0.254)
		(layer "F.Cu")
		(net "VSENSE_PVDD18_S5_P0_DN")
	)
	(segment
		(start 305.034442 -152.840436)
		(end 304.710338 -153.16454)
		(width 0.254)
		(layer "F.Cu")
		(net "VSENSE_PVDD18_S5_P0_DN")
	)
	(segment
		(start 328.83729 -220.341952)
		(end 334.071214 -215.108028)
		(width 0.254)
		(layer "F.Cu")
		(net "VSENSE_PVDD18_S5_P0_DN")
	)
	(segment
		(start 303.982628 -153.16454)
		(end 303.69383 -152.875742)
		(width 0.254)
		(layer "F.Cu")
		(net "VSENSE_PVDD18_S5_P0_DN")
	)
	(segment
		(start 328.914252 -142.578074)
		(end 329.223624 -142.268702)
		(width 0.254)
		(layer "F.Cu")
		(net "VSENSE_PVDD18_S5_P0_DN")
	)
	(segment
		(start 326.205596 -222.84563)
		(end 326.205596 -220.907102)
		(width 0.254)
		(layer "F.Cu")
		(net "VSENSE_PVDD18_S5_P0_DN")
	)
	(segment
		(start 316.578234 -194.634104)
		(end 316.578234 -183.77662)
		(width 0.254)
		(layer "F.Cu")
		(net "VSENSE_PVDD18_S5_P0_DN")
	)
	(via
		(at 328.914252 -142.578074)
		(size 0.508)
		(drill 0.254)
		(layers "F.Cu" "B.Cu")
		(net "VSENSE_PVDD18_S5_P0_DN")
	)
	(via
		(at 305.034442 -152.840436)
		(size 0.508)
		(drill 0.254)
		(layers "F.Cu" "B.Cu")
		(net "VSENSE_PVDD18_S5_P0_DN")
	)
	(segment
		(start 328.914252 -142.578074)
		(end 328.914252 -141.10335)
		(width 0.254)
		(layer "In2.Cu")
		(net "VSENSE_PVDD18_S5_P0_DN")
	)
	(segment
		(start 321.697858 -151.973788)
		(end 316.746128 -151.973788)
		(width 0.254)
		(layer "In2.Cu")
		(net "VSENSE_PVDD18_S5_P0_DN")
	)
	(segment
		(start 305.402742 -153.208736)
		(end 305.034442 -152.840436)
		(width 0.254)
		(layer "In2.Cu")
		(net "VSENSE_PVDD18_S5_P0_DN")
	)
	(segment
		(start 329.4507 -140.780516)
		(end 329.691746 -141.021562)
		(width 0.254)
		(layer "In2.Cu")
		(net "VSENSE_PVDD18_S5_P0_DN")
	)
	(segment
		(start 329.691746 -141.021562)
		(end 329.691746 -143.9799)
		(width 0.254)
		(layer "In2.Cu")
		(net "VSENSE_PVDD18_S5_P0_DN")
	)
	(segment
		(start 329.11542 -140.780516)
		(end 329.4507 -140.780516)
		(width 0.254)
		(layer "In2.Cu")
		(net "VSENSE_PVDD18_S5_P0_DN")
	)
	(segment
		(start 316.746128 -151.973788)
		(end 315.51118 -153.208736)
		(width 0.254)
		(layer "In2.Cu")
		(net "VSENSE_PVDD18_S5_P0_DN")
	)
	(segment
		(start 329.691746 -143.9799)
		(end 321.697858 -151.973788)
		(width 0.254)
		(layer "In2.Cu")
		(net "VSENSE_PVDD18_S5_P0_DN")
	)
	(segment
		(start 328.914252 -141.10335)
		(end 329.11542 -140.780516)
		(width 0.254)
		(layer "In2.Cu")
		(net "VSENSE_PVDD18_S5_P0_DN")
	)
	(segment
		(start 315.51118 -153.208736)
		(end 305.402742 -153.208736)
		(width 0.254)
		(layer "In2.Cu")
		(net "VSENSE_PVDD18_S5_P0_DN")
	)
	(segment
		(start 159.341058 -345.202256)
		(end 160.292034 -346.153232)
		(width 0.1778)
		(layer "F.Cu")
		(net "VSENSE_PVDD11_S3_P1_R")
	)
	(segment
		(start 159.182562 -344.54846)
		(end 159.341058 -344.706956)
		(width 0.254)
		(layer "F.Cu")
		(net "VSENSE_PVDD11_S3_P1_R")
	)
	(segment
		(start 160.292034 -346.153232)
		(end 160.428432 -346.153232)
		(width 0.1778)
		(layer "F.Cu")
		(net "VSENSE_PVDD11_S3_P1_R")
	)
	(segment
		(start 159.341058 -344.706956)
		(end 159.341058 -345.202256)
		(width 0.1778)
		(layer "F.Cu")
		(net "VSENSE_PVDD11_S3_P1_R")
	)
	(segment
		(start 159.182562 -343.727786)
		(end 159.182562 -344.54846)
		(width 0.254)
		(layer "F.Cu")
		(net "VSENSE_PVDD11_S3_P1_R")
	)
	(segment
		(start 169.5704 -332.994508)
		(end 169.1894 -333.375508)
		(width 0.254)
		(layer "F.Cu")
		(net "VSENSE_PVDD11_S3_P1_DP")
	)
	(segment
		(start 170.44035 -333.375508)
		(end 170.05935 -332.994508)
		(width 0.254)
		(layer "F.Cu")
		(net "VSENSE_PVDD11_S3_P1_DP")
	)
	(segment
		(start 168.797732 -332.98384)
		(end 168.438068 -332.98384)
		(width 0.254)
		(layer "F.Cu")
		(net "VSENSE_PVDD11_S3_P1_DP")
	)
	(segment
		(start 144.977866 -294.880284)
		(end 145.243804 -295.146222)
		(width 0.254)
		(layer "F.Cu")
		(net "VSENSE_PVDD11_S3_P1_DP")
	)
	(segment
		(start 159.182562 -342.927686)
		(end 160.141158 -342.927686)
		(width 0.254)
		(layer "F.Cu")
		(net "VSENSE_PVDD11_S3_P1_DP")
	)
	(segment
		(start 145.243804 -295.146222)
		(end 145.444718 -295.146222)
		(width 0.254)
		(layer "F.Cu")
		(net "VSENSE_PVDD11_S3_P1_DP")
	)
	(segment
		(start 169.1894 -333.375508)
		(end 168.797732 -332.98384)
		(width 0.254)
		(layer "F.Cu")
		(net "VSENSE_PVDD11_S3_P1_DP")
	)
	(segment
		(start 170.05935 -332.994508)
		(end 169.5704 -332.994508)
		(width 0.254)
		(layer "F.Cu")
		(net "VSENSE_PVDD11_S3_P1_DP")
	)
	(segment
		(start 168.438068 -332.98384)
		(end 168.3004 -333.121508)
		(width 0.254)
		(layer "F.Cu")
		(net "VSENSE_PVDD11_S3_P1_DP")
	)
	(via
		(at 145.444718 -295.146222)
		(size 0.4064)
		(drill 0.2032)
		(layers "F.Cu" "B.Cu")
		(net "VSENSE_PVDD11_S3_P1_DP")
	)
	(via
		(at 160.141158 -342.927686)
		(size 0.508)
		(drill 0.254)
		(layers "F.Cu" "B.Cu")
		(net "VSENSE_PVDD11_S3_P1_DP")
	)
	(via
		(at 168.3004 -333.121508)
		(size 0.508)
		(drill 0.254)
		(layers "F.Cu" "B.Cu")
		(net "VSENSE_PVDD11_S3_P1_DP")
	)
	(segment
		(start 163.500054 -320.764154)
		(end 163.500054 -327.872344)
		(width 0.254)
		(layer "B.Cu")
		(net "VSENSE_PVDD11_S3_P1_DP")
	)
	(segment
		(start 163.500054 -327.872344)
		(end 165.994842 -330.367132)
		(width 0.254)
		(layer "B.Cu")
		(net "VSENSE_PVDD11_S3_P1_DP")
	)
	(segment
		(start 169.266108 -332.919832)
		(end 168.502076 -332.919832)
		(width 0.254)
		(layer "B.Cu")
		(net "VSENSE_PVDD11_S3_P1_DP")
	)
	(segment
		(start 169.784014 -332.401926)
		(end 169.266108 -332.919832)
		(width 0.254)
		(layer "B.Cu")
		(net "VSENSE_PVDD11_S3_P1_DP")
	)
	(segment
		(start 168.502076 -332.919832)
		(end 168.3004 -333.121508)
		(width 0.254)
		(layer "B.Cu")
		(net "VSENSE_PVDD11_S3_P1_DP")
	)
	(segment
		(start 145.803366 -295.50487)
		(end 147.0025 -295.50487)
		(width 0.254)
		(layer "B.Cu")
		(net "VSENSE_PVDD11_S3_P1_DP")
	)
	(segment
		(start 168.943274 -330.367132)
		(end 169.784014 -331.207872)
		(width 0.254)
		(layer "B.Cu")
		(net "VSENSE_PVDD11_S3_P1_DP")
	)
	(segment
		(start 169.784014 -331.207872)
		(end 169.784014 -332.401926)
		(width 0.254)
		(layer "B.Cu")
		(net "VSENSE_PVDD11_S3_P1_DP")
	)
	(segment
		(start 147.0025 -295.50487)
		(end 158.271464 -306.773834)
		(width 0.254)
		(layer "B.Cu")
		(net "VSENSE_PVDD11_S3_P1_DP")
	)
	(segment
		(start 158.271464 -315.535564)
		(end 163.500054 -320.764154)
		(width 0.254)
		(layer "B.Cu")
		(net "VSENSE_PVDD11_S3_P1_DP")
	)
	(segment
		(start 145.444718 -295.146222)
		(end 145.803366 -295.50487)
		(width 0.254)
		(layer "B.Cu")
		(net "VSENSE_PVDD11_S3_P1_DP")
	)
	(segment
		(start 165.994842 -330.367132)
		(end 168.943274 -330.367132)
		(width 0.254)
		(layer "B.Cu")
		(net "VSENSE_PVDD11_S3_P1_DP")
	)
	(segment
		(start 158.271464 -306.773834)
		(end 158.271464 -315.535564)
		(width 0.254)
		(layer "B.Cu")
		(net "VSENSE_PVDD11_S3_P1_DP")
	)
	(segment
		(start 159.662368 -342.819482)
		(end 159.770572 -342.927686)
		(width 0.254)
		(layer "In2.Cu")
		(net "VSENSE_PVDD11_S3_P1_DP")
	)
	(segment
		(start 168.113964 -332.935072)
		(end 167.640762 -332.935072)
		(width 0.254)
		(layer "In2.Cu")
		(net "VSENSE_PVDD11_S3_P1_DP")
	)
	(segment
		(start 159.662368 -340.913466)
		(end 159.662368 -342.819482)
		(width 0.254)
		(layer "In2.Cu")
		(net "VSENSE_PVDD11_S3_P1_DP")
	)
	(segment
		(start 167.640762 -332.935072)
		(end 159.662368 -340.913466)
		(width 0.254)
		(layer "In2.Cu")
		(net "VSENSE_PVDD11_S3_P1_DP")
	)
	(segment
		(start 168.3004 -333.121508)
		(end 168.113964 -332.935072)
		(width 0.254)
		(layer "In2.Cu")
		(net "VSENSE_PVDD11_S3_P1_DP")
	)
	(segment
		(start 159.770572 -342.927686)
		(end 160.141158 -342.927686)
		(width 0.254)
		(layer "In2.Cu")
		(net "VSENSE_PVDD11_S3_P1_DP")
	)
	(segment
		(start 416.021012 -358.25049)
		(end 416.021012 -358.610154)
		(width 0.254)
		(layer "F.Cu")
		(net "VSENSE_PVDD11_S3_P0_R")
	)
	(segment
		(start 417.117784 -359.499154)
		(end 417.117784 -359.687368)
		(width 0.1778)
		(layer "F.Cu")
		(net "VSENSE_PVDD11_S3_P0_R")
	)
	(segment
		(start 415.119058 -358.01681)
		(end 415.34334 -358.241092)
		(width 0.254)
		(layer "F.Cu")
		(net "VSENSE_PVDD11_S3_P0_R")
	)
	(segment
		(start 416.687762 -359.069132)
		(end 416.823906 -359.205276)
		(width 0.254)
		(layer "F.Cu")
		(net "VSENSE_PVDD11_S3_P0_R")
	)
	(segment
		(start 415.34334 -358.241092)
		(end 416.03041 -358.241092)
		(width 0.254)
		(layer "F.Cu")
		(net "VSENSE_PVDD11_S3_P0_R")
	)
	(segment
		(start 416.021012 -358.610154)
		(end 416.47999 -359.069132)
		(width 0.254)
		(layer "F.Cu")
		(net "VSENSE_PVDD11_S3_P0_R")
	)
	(segment
		(start 416.03041 -358.241092)
		(end 416.021012 -358.25049)
		(width 0.254)
		(layer "F.Cu")
		(net "VSENSE_PVDD11_S3_P0_R")
	)
	(segment
		(start 416.823906 -359.205276)
		(end 417.117784 -359.499154)
		(width 0.1778)
		(layer "F.Cu")
		(net "VSENSE_PVDD11_S3_P0_R")
	)
	(segment
		(start 416.47999 -359.069132)
		(end 416.687762 -359.069132)
		(width 0.254)
		(layer "F.Cu")
		(net "VSENSE_PVDD11_S3_P0_R")
	)
	(segment
		(start 415.873946 -356.461822)
		(end 415.119058 -357.21671)
		(width 0.254)
		(layer "F.Cu")
		(net "VSENSE_PVDD11_S3_P0_DP")
	)
	(segment
		(start 393.183872 -295.145968)
		(end 393.384786 -295.145968)
		(width 0.254)
		(layer "F.Cu")
		(net "VSENSE_PVDD11_S3_P0_DP")
	)
	(segment
		(start 392.917934 -294.88003)
		(end 393.183872 -295.145968)
		(width 0.254)
		(layer "F.Cu")
		(net "VSENSE_PVDD11_S3_P0_DP")
	)
	(segment
		(start 415.228532 -333.215996)
		(end 414.810448 -332.797912)
		(width 0.254)
		(layer "F.Cu")
		(net "VSENSE_PVDD11_S3_P0_DP")
	)
	(segment
		(start 413.977582 -333.271114)
		(end 413.596582 -332.890114)
		(width 0.254)
		(layer "F.Cu")
		(net "VSENSE_PVDD11_S3_P0_DP")
	)
	(segment
		(start 414.450784 -332.797912)
		(end 413.977582 -333.271114)
		(width 0.254)
		(layer "F.Cu")
		(net "VSENSE_PVDD11_S3_P0_DP")
	)
	(segment
		(start 413.596582 -332.890114)
		(end 413.215582 -332.890114)
		(width 0.254)
		(layer "F.Cu")
		(net "VSENSE_PVDD11_S3_P0_DP")
	)
	(segment
		(start 414.810448 -332.797912)
		(end 414.450784 -332.797912)
		(width 0.254)
		(layer "F.Cu")
		(net "VSENSE_PVDD11_S3_P0_DP")
	)
	(segment
		(start 416.83051 -356.461822)
		(end 415.873946 -356.461822)
		(width 0.254)
		(layer "F.Cu")
		(net "VSENSE_PVDD11_S3_P0_DP")
	)
	(segment
		(start 413.215582 -332.890114)
		(end 413.088582 -333.017114)
		(width 0.254)
		(layer "F.Cu")
		(net "VSENSE_PVDD11_S3_P0_DP")
	)
	(via
		(at 408.245818 -323.082412)
		(size 0.508)
		(drill 0.254)
		(layers "F.Cu" "B.Cu")
		(net "VSENSE_PVDD11_S3_P0_DP")
	)
	(via
		(at 416.83051 -356.461822)
		(size 0.508)
		(drill 0.254)
		(layers "F.Cu" "B.Cu")
		(net "VSENSE_PVDD11_S3_P0_DP")
	)
	(via
		(at 413.088582 -333.017114)
		(size 0.508)
		(drill 0.254)
		(layers "F.Cu" "B.Cu")
		(net "VSENSE_PVDD11_S3_P0_DP")
	)
	(via
		(at 393.384786 -295.145968)
		(size 0.4064)
		(drill 0.2032)
		(layers "F.Cu" "B.Cu")
		(net "VSENSE_PVDD11_S3_P0_DP")
	)
	(segment
		(start 393.384786 -296.83329)
		(end 397.545052 -300.993556)
		(width 0.254)
		(layer "B.Cu")
		(net "VSENSE_PVDD11_S3_P0_DP")
	)
	(segment
		(start 393.384786 -295.145968)
		(end 393.384786 -296.83329)
		(width 0.254)
		(layer "B.Cu")
		(net "VSENSE_PVDD11_S3_P0_DP")
	)
	(segment
		(start 408.028902 -314.3885)
		(end 408.028902 -322.865496)
		(width 0.254)
		(layer "B.Cu")
		(net "VSENSE_PVDD11_S3_P0_DP")
	)
	(segment
		(start 397.545052 -300.993556)
		(end 397.545052 -303.90465)
		(width 0.254)
		(layer "B.Cu")
		(net "VSENSE_PVDD11_S3_P0_DP")
	)
	(segment
		(start 408.028902 -322.865496)
		(end 408.245818 -323.082412)
		(width 0.254)
		(layer "B.Cu")
		(net "VSENSE_PVDD11_S3_P0_DP")
	)
	(segment
		(start 397.545052 -303.90465)
		(end 408.028902 -314.3885)
		(width 0.254)
		(layer "B.Cu")
		(net "VSENSE_PVDD11_S3_P0_DP")
	)
	(segment
		(start 412.086806 -347.621352)
		(end 410.336492 -349.371666)
		(width 0.254)
		(layer "In4.Cu")
		(net "VSENSE_PVDD11_S3_P0_DP")
	)
	(segment
		(start 414.737296 -332.271116)
		(end 414.181798 -332.826614)
		(width 0.254)
		(layer "In4.Cu")
		(net "VSENSE_PVDD11_S3_P0_DP")
	)
	(segment
		(start 412.898082 -332.826614)
		(end 412.455106 -332.826614)
		(width 0.254)
		(layer "In4.Cu")
		(net "VSENSE_PVDD11_S3_P0_DP")
	)
	(segment
		(start 410.336492 -353.98329)
		(end 413.005524 -356.652322)
		(width 0.254)
		(layer "In4.Cu")
		(net "VSENSE_PVDD11_S3_P0_DP")
	)
	(segment
		(start 416.64001 -356.652322)
		(end 416.83051 -356.461822)
		(width 0.254)
		(layer "In4.Cu")
		(net "VSENSE_PVDD11_S3_P0_DP")
	)
	(segment
		(start 414.737296 -329.032616)
		(end 414.737296 -332.271116)
		(width 0.254)
		(layer "In4.Cu")
		(net "VSENSE_PVDD11_S3_P0_DP")
	)
	(segment
		(start 410.336492 -349.371666)
		(end 410.336492 -353.98329)
		(width 0.254)
		(layer "In4.Cu")
		(net "VSENSE_PVDD11_S3_P0_DP")
	)
	(segment
		(start 413.005524 -356.652322)
		(end 416.64001 -356.652322)
		(width 0.254)
		(layer "In4.Cu")
		(net "VSENSE_PVDD11_S3_P0_DP")
	)
	(segment
		(start 414.181798 -332.826614)
		(end 413.279082 -332.826614)
		(width 0.254)
		(layer "In4.Cu")
		(net "VSENSE_PVDD11_S3_P0_DP")
	)
	(segment
		(start 410.349192 -324.644512)
		(end 414.737296 -329.032616)
		(width 0.254)
		(layer "In4.Cu")
		(net "VSENSE_PVDD11_S3_P0_DP")
	)
	(segment
		(start 408.245818 -323.082412)
		(end 408.016964 -323.311266)
		(width 0.254)
		(layer "In4.Cu")
		(net "VSENSE_PVDD11_S3_P0_DP")
	)
	(segment
		(start 412.086806 -333.194914)
		(end 412.086806 -347.621352)
		(width 0.254)
		(layer "In4.Cu")
		(net "VSENSE_PVDD11_S3_P0_DP")
	)
	(segment
		(start 408.016964 -323.964046)
		(end 408.69743 -324.644512)
		(width 0.254)
		(layer "In4.Cu")
		(net "VSENSE_PVDD11_S3_P0_DP")
	)
	(segment
		(start 413.088582 -333.017114)
		(end 412.898082 -332.826614)
		(width 0.254)
		(layer "In4.Cu")
		(net "VSENSE_PVDD11_S3_P0_DP")
	)
	(segment
		(start 408.016964 -323.311266)
		(end 408.016964 -323.964046)
		(width 0.254)
		(layer "In4.Cu")
		(net "VSENSE_PVDD11_S3_P0_DP")
	)
	(segment
		(start 412.455106 -332.826614)
		(end 412.086806 -333.194914)
		(width 0.254)
		(layer "In4.Cu")
		(net "VSENSE_PVDD11_S3_P0_DP")
	)
	(segment
		(start 408.69743 -324.644512)
		(end 410.349192 -324.644512)
		(width 0.254)
		(layer "In4.Cu")
		(net "VSENSE_PVDD11_S3_P0_DP")
	)
	(segment
		(start 413.279082 -332.826614)
		(end 413.088582 -333.017114)
		(width 0.254)
		(layer "In4.Cu")
		(net "VSENSE_PVDD11_S3_P0_DP")
	)
	(segment
		(start 417.779454 -345.778582)
		(end 414.645094 -342.644222)
		(width 0.254)
		(layer "In6.Cu")
		(net "VSENSE_PVDD11_S3_P0_DP")
	)
	(segment
		(start 414.645094 -333.17561)
		(end 414.317434 -332.84795)
		(width 0.254)
		(layer "In6.Cu")
		(net "VSENSE_PVDD11_S3_P0_DP")
	)
	(segment
		(start 414.317434 -332.84795)
		(end 413.257746 -332.84795)
		(width 0.254)
		(layer "In6.Cu")
		(net "VSENSE_PVDD11_S3_P0_DP")
	)
	(segment
		(start 413.257746 -332.84795)
		(end 413.088582 -333.017114)
		(width 0.254)
		(layer "In6.Cu")
		(net "VSENSE_PVDD11_S3_P0_DP")
	)
	(segment
		(start 416.984942 -356.616254)
		(end 417.451286 -356.616254)
		(width 0.254)
		(layer "In6.Cu")
		(net "VSENSE_PVDD11_S3_P0_DP")
	)
	(segment
		(start 414.645094 -342.644222)
		(end 414.645094 -333.17561)
		(width 0.254)
		(layer "In6.Cu")
		(net "VSENSE_PVDD11_S3_P0_DP")
	)
	(segment
		(start 417.451286 -356.616254)
		(end 417.779454 -356.288086)
		(width 0.254)
		(layer "In6.Cu")
		(net "VSENSE_PVDD11_S3_P0_DP")
	)
	(segment
		(start 416.83051 -356.461822)
		(end 416.984942 -356.616254)
		(width 0.254)
		(layer "In6.Cu")
		(net "VSENSE_PVDD11_S3_P0_DP")
	)
	(segment
		(start 417.779454 -356.288086)
		(end 417.779454 -345.778582)
		(width 0.254)
		(layer "In6.Cu")
		(net "VSENSE_PVDD11_S3_P0_DP")
	)
	(segment
		(start 159.12592 -109.08792)
		(end 159.12592 -113.542826)
		(width 0.10668)
		(layer "F.Cu")
		(net "VIRTUAL_RESEAT_FPGA_N")
	)
	(segment
		(start 159.463486 -98.78314)
		(end 159.145224 -99.101402)
		(width 0.10668)
		(layer "F.Cu")
		(net "VIRTUAL_RESEAT_FPGA_N")
	)
	(segment
		(start 162.465766 -120.138952)
		(end 162.698684 -120.37187)
		(width 0.10668)
		(layer "F.Cu")
		(net "VIRTUAL_RESEAT_FPGA_N")
	)
	(segment
		(start 162.698684 -120.37187)
		(end 163.343844 -120.37187)
		(width 0.10668)
		(layer "F.Cu")
		(net "VIRTUAL_RESEAT_FPGA_N")
	)
	(segment
		(start 196.777356 -40.138604)
		(end 195.942458 -40.138604)
		(width 0.10668)
		(layer "F.Cu")
		(net "VIRTUAL_RESEAT_FPGA_N")
	)
	(segment
		(start 162.465766 -116.882672)
		(end 162.465766 -120.138952)
		(width 0.10668)
		(layer "F.Cu")
		(net "VIRTUAL_RESEAT_FPGA_N")
	)
	(segment
		(start 159.12592 -113.542826)
		(end 162.465766 -116.882672)
		(width 0.10668)
		(layer "F.Cu")
		(net "VIRTUAL_RESEAT_FPGA_N")
	)
	(segment
		(start 158.115 -101.727)
		(end 158.115 -108.077)
		(width 0.10668)
		(layer "F.Cu")
		(net "VIRTUAL_RESEAT_FPGA_N")
	)
	(segment
		(start 159.155384 -94.449646)
		(end 159.463486 -94.757748)
		(width 0.10668)
		(layer "F.Cu")
		(net "VIRTUAL_RESEAT_FPGA_N")
	)
	(segment
		(start 159.145224 -100.696776)
		(end 158.115 -101.727)
		(width 0.10668)
		(layer "F.Cu")
		(net "VIRTUAL_RESEAT_FPGA_N")
	)
	(segment
		(start 158.115 -108.077)
		(end 159.12592 -109.08792)
		(width 0.10668)
		(layer "F.Cu")
		(net "VIRTUAL_RESEAT_FPGA_N")
	)
	(segment
		(start 159.463486 -94.757748)
		(end 159.463486 -98.78314)
		(width 0.10668)
		(layer "F.Cu")
		(net "VIRTUAL_RESEAT_FPGA_N")
	)
	(segment
		(start 159.145224 -99.101402)
		(end 159.145224 -100.696776)
		(width 0.10668)
		(layer "F.Cu")
		(net "VIRTUAL_RESEAT_FPGA_N")
	)
	(segment
		(start 159.155384 -91.489784)
		(end 159.155384 -94.449646)
		(width 0.10668)
		(layer "F.Cu")
		(net "VIRTUAL_RESEAT_FPGA_N")
	)
	(via
		(at 195.942458 -40.138604)
		(size 0.508)
		(drill 0.254)
		(layers "F.Cu" "B.Cu")
		(net "VIRTUAL_RESEAT_FPGA_N")
	)
	(via
		(at 158.890462 -38.781482)
		(size 0.508)
		(drill 0.254)
		(layers "F.Cu" "B.Cu")
		(net "VIRTUAL_RESEAT_FPGA_N")
	)
	(via
		(at 159.155384 -91.489784)
		(size 0.508)
		(drill 0.254)
		(layers "F.Cu" "B.Cu")
		(net "VIRTUAL_RESEAT_FPGA_N")
	)
	(segment
		(start 162.075114 -89.562686)
		(end 162.075114 -65.687956)
		(width 0.11684)
		(layer "In11.Cu")
		(net "VIRTUAL_RESEAT_FPGA_N")
	)
	(segment
		(start 159.155384 -91.489784)
		(end 160.148016 -91.489784)
		(width 0.11684)
		(layer "In11.Cu")
		(net "VIRTUAL_RESEAT_FPGA_N")
	)
	(segment
		(start 160.450022 -54.345586)
		(end 160.450022 -40.341042)
		(width 0.11684)
		(layer "In11.Cu")
		(net "VIRTUAL_RESEAT_FPGA_N")
	)
	(segment
		(start 160.148016 -91.489784)
		(end 162.075114 -89.562686)
		(width 0.11684)
		(layer "In11.Cu")
		(net "VIRTUAL_RESEAT_FPGA_N")
	)
	(segment
		(start 163.69157 -64.0715)
		(end 163.69157 -57.587134)
		(width 0.11684)
		(layer "In11.Cu")
		(net "VIRTUAL_RESEAT_FPGA_N")
	)
	(segment
		(start 160.450022 -40.341042)
		(end 158.890462 -38.781482)
		(width 0.11684)
		(layer "In11.Cu")
		(net "VIRTUAL_RESEAT_FPGA_N")
	)
	(segment
		(start 163.69157 -57.587134)
		(end 160.450022 -54.345586)
		(width 0.11684)
		(layer "In11.Cu")
		(net "VIRTUAL_RESEAT_FPGA_N")
	)
	(segment
		(start 162.075114 -65.687956)
		(end 163.69157 -64.0715)
		(width 0.11684)
		(layer "In11.Cu")
		(net "VIRTUAL_RESEAT_FPGA_N")
	)
	(segment
		(start 189.795912 -41.581832)
		(end 190.376556 -42.162476)
		(width 0.11684)
		(layer "In15.Cu")
		(net "VIRTUAL_RESEAT_FPGA_N")
	)
	(segment
		(start 190.376556 -42.162476)
		(end 193.918586 -42.162476)
		(width 0.11684)
		(layer "In15.Cu")
		(net "VIRTUAL_RESEAT_FPGA_N")
	)
	(segment
		(start 163.625022 -39.580058)
		(end 184.876186 -39.580058)
		(width 0.11684)
		(layer "In15.Cu")
		(net "VIRTUAL_RESEAT_FPGA_N")
	)
	(segment
		(start 158.890462 -38.781482)
		(end 158.890716 -38.781228)
		(width 0.11684)
		(layer "In15.Cu")
		(net "VIRTUAL_RESEAT_FPGA_N")
	)
	(segment
		(start 193.918586 -42.162476)
		(end 195.942458 -40.138604)
		(width 0.11684)
		(layer "In15.Cu")
		(net "VIRTUAL_RESEAT_FPGA_N")
	)
	(segment
		(start 158.890716 -38.781228)
		(end 162.826192 -38.781228)
		(width 0.11684)
		(layer "In15.Cu")
		(net "VIRTUAL_RESEAT_FPGA_N")
	)
	(segment
		(start 186.87796 -41.581832)
		(end 189.795912 -41.581832)
		(width 0.11684)
		(layer "In15.Cu")
		(net "VIRTUAL_RESEAT_FPGA_N")
	)
	(segment
		(start 162.826192 -38.781228)
		(end 163.625022 -39.580058)
		(width 0.11684)
		(layer "In15.Cu")
		(net "VIRTUAL_RESEAT_FPGA_N")
	)
	(segment
		(start 184.876186 -39.580058)
		(end 186.87796 -41.581832)
		(width 0.11684)
		(layer "In15.Cu")
		(net "VIRTUAL_RESEAT_FPGA_N")
	)
	(segment
		(start 181.972966 -11.85418)
		(end 181.475634 -11.85418)
		(width 0.10668)
		(layer "F.Cu")
		(net "VIRTUAL_RESEAT")
	)
	(segment
		(start 181.122066 -118.652798)
		(end 180.732176 -119.042688)
		(width 0.10668)
		(layer "F.Cu")
		(net "VIRTUAL_RESEAT")
	)
	(segment
		(start 183.262016 -13.599922)
		(end 183.262016 -13.14323)
		(width 0.10668)
		(layer "F.Cu")
		(net "VIRTUAL_RESEAT")
	)
	(segment
		(start 183.262016 -13.14323)
		(end 181.972966 -11.85418)
		(width 0.10668)
		(layer "F.Cu")
		(net "VIRTUAL_RESEAT")
	)
	(via
		(at 180.732176 -119.042688)
		(size 0.4572)
		(drill 0.254)
		(layers "F.Cu" "B.Cu")
		(net "VIRTUAL_RESEAT")
	)
	(via
		(at 181.475634 -11.85418)
		(size 0.508)
		(drill 0.254)
		(layers "F.Cu" "B.Cu")
		(net "VIRTUAL_RESEAT")
	)
	(segment
		(start 182.512208 -10.879074)
		(end 183.873902 -10.879074)
		(width 0.11684)
		(layer "In11.Cu")
		(net "VIRTUAL_RESEAT")
	)
	(segment
		(start 186.061604 -15.831058)
		(end 185.760614 -16.132048)
		(width 0.11684)
		(layer "In11.Cu")
		(net "VIRTUAL_RESEAT")
	)
	(segment
		(start 182.724298 -110.836964)
		(end 182.724298 -114.781838)
		(width 0.11684)
		(layer "In11.Cu")
		(net "VIRTUAL_RESEAT")
	)
	(segment
		(start 176.153318 -90.550238)
		(end 176.153318 -100.077778)
		(width 0.11684)
		(layer "In11.Cu")
		(net "VIRTUAL_RESEAT")
	)
	(segment
		(start 167.670226 -13.824966)
		(end 165.947598 -15.547594)
		(width 0.11684)
		(layer "In11.Cu")
		(net "VIRTUAL_RESEAT")
	)
	(segment
		(start 169.558208 -35.02914)
		(end 167.794686 -36.792662)
		(width 0.11684)
		(layer "In11.Cu")
		(net "VIRTUAL_RESEAT")
	)
	(segment
		(start 169.63771 -50.65141)
		(end 169.63771 -78.452726)
		(width 0.11684)
		(layer "In11.Cu")
		(net "VIRTUAL_RESEAT")
	)
	(segment
		(start 182.724298 -114.781838)
		(end 182.358792 -115.147344)
		(width 0.11684)
		(layer "In11.Cu")
		(net "VIRTUAL_RESEAT")
	)
	(segment
		(start 181.129686 -118.645178)
		(end 180.732176 -119.042688)
		(width 0.11684)
		(layer "In11.Cu")
		(net "VIRTUAL_RESEAT")
	)
	(segment
		(start 181.475634 -11.85418)
		(end 181.537102 -11.85418)
		(width 0.11684)
		(layer "In11.Cu")
		(net "VIRTUAL_RESEAT")
	)
	(segment
		(start 177.657506 -13.824966)
		(end 167.670226 -13.824966)
		(width 0.11684)
		(layer "In11.Cu")
		(net "VIRTUAL_RESEAT")
	)
	(segment
		(start 169.558208 -23.847552)
		(end 169.558208 -35.02914)
		(width 0.11684)
		(layer "In11.Cu")
		(net "VIRTUAL_RESEAT")
	)
	(segment
		(start 165.947598 -20.236942)
		(end 169.558208 -23.847552)
		(width 0.11684)
		(layer "In11.Cu")
		(net "VIRTUAL_RESEAT")
	)
	(segment
		(start 176.648872 -90.054684)
		(end 176.153318 -90.550238)
		(width 0.11684)
		(layer "In11.Cu")
		(net "VIRTUAL_RESEAT")
	)
	(segment
		(start 176.153318 -100.077778)
		(end 178.29784 -102.2223)
		(width 0.11684)
		(layer "In11.Cu")
		(net "VIRTUAL_RESEAT")
	)
	(segment
		(start 170.3959 -41.261284)
		(end 170.3959 -49.89322)
		(width 0.11684)
		(layer "In11.Cu")
		(net "VIRTUAL_RESEAT")
	)
	(segment
		(start 183.873902 -10.879074)
		(end 186.2455 -13.250672)
		(width 0.11684)
		(layer "In11.Cu")
		(net "VIRTUAL_RESEAT")
	)
	(segment
		(start 181.129686 -115.641882)
		(end 181.129686 -118.645178)
		(width 0.11684)
		(layer "In11.Cu")
		(net "VIRTUAL_RESEAT")
	)
	(segment
		(start 185.760614 -16.132048)
		(end 179.964588 -16.132048)
		(width 0.11684)
		(layer "In11.Cu")
		(net "VIRTUAL_RESEAT")
	)
	(segment
		(start 167.794686 -38.66007)
		(end 170.3959 -41.261284)
		(width 0.11684)
		(layer "In11.Cu")
		(net "VIRTUAL_RESEAT")
	)
	(segment
		(start 179.763166 -110.664752)
		(end 182.552086 -110.664752)
		(width 0.11684)
		(layer "In11.Cu")
		(net "VIRTUAL_RESEAT")
	)
	(segment
		(start 169.63771 -78.452726)
		(end 176.648872 -85.463888)
		(width 0.11684)
		(layer "In11.Cu")
		(net "VIRTUAL_RESEAT")
	)
	(segment
		(start 181.624224 -115.147344)
		(end 181.129686 -115.641882)
		(width 0.11684)
		(layer "In11.Cu")
		(net "VIRTUAL_RESEAT")
	)
	(segment
		(start 170.3959 -49.89322)
		(end 169.63771 -50.65141)
		(width 0.11684)
		(layer "In11.Cu")
		(net "VIRTUAL_RESEAT")
	)
	(segment
		(start 165.947598 -15.547594)
		(end 165.947598 -20.236942)
		(width 0.11684)
		(layer "In11.Cu")
		(net "VIRTUAL_RESEAT")
	)
	(segment
		(start 179.534566 -106.639106)
		(end 179.534566 -110.436152)
		(width 0.11684)
		(layer "In11.Cu")
		(net "VIRTUAL_RESEAT")
	)
	(segment
		(start 181.537102 -11.85418)
		(end 182.512208 -10.879074)
		(width 0.11684)
		(layer "In11.Cu")
		(net "VIRTUAL_RESEAT")
	)
	(segment
		(start 186.2455 -14.994128)
		(end 186.061604 -15.178024)
		(width 0.11684)
		(layer "In11.Cu")
		(net "VIRTUAL_RESEAT")
	)
	(segment
		(start 178.29784 -102.2223)
		(end 178.29784 -105.40238)
		(width 0.11684)
		(layer "In11.Cu")
		(net "VIRTUAL_RESEAT")
	)
	(segment
		(start 186.061604 -15.178024)
		(end 186.061604 -15.831058)
		(width 0.11684)
		(layer "In11.Cu")
		(net "VIRTUAL_RESEAT")
	)
	(segment
		(start 182.552086 -110.664752)
		(end 182.724298 -110.836964)
		(width 0.11684)
		(layer "In11.Cu")
		(net "VIRTUAL_RESEAT")
	)
	(segment
		(start 186.2455 -13.250672)
		(end 186.2455 -14.994128)
		(width 0.11684)
		(layer "In11.Cu")
		(net "VIRTUAL_RESEAT")
	)
	(segment
		(start 179.964588 -16.132048)
		(end 177.657506 -13.824966)
		(width 0.11684)
		(layer "In11.Cu")
		(net "VIRTUAL_RESEAT")
	)
	(segment
		(start 178.29784 -105.40238)
		(end 179.534566 -106.639106)
		(width 0.11684)
		(layer "In11.Cu")
		(net "VIRTUAL_RESEAT")
	)
	(segment
		(start 182.358792 -115.147344)
		(end 181.624224 -115.147344)
		(width 0.11684)
		(layer "In11.Cu")
		(net "VIRTUAL_RESEAT")
	)
	(segment
		(start 167.794686 -36.792662)
		(end 167.794686 -38.66007)
		(width 0.11684)
		(layer "In11.Cu")
		(net "VIRTUAL_RESEAT")
	)
	(segment
		(start 176.648872 -85.463888)
		(end 176.648872 -90.054684)
		(width 0.11684)
		(layer "In11.Cu")
		(net "VIRTUAL_RESEAT")
	)
	(segment
		(start 179.534566 -110.436152)
		(end 179.763166 -110.664752)
		(width 0.11684)
		(layer "In11.Cu")
		(net "VIRTUAL_RESEAT")
	)
	(segment
		(start 164.10305 -115.280948)
		(end 164.719 -115.280948)
		(width 0.10668)
		(layer "F.Cu")
		(net "UV_ALERT_N")
	)
	(segment
		(start 177.922174 -113.85296)
		(end 177.532284 -113.46307)
		(width 0.10668)
		(layer "F.Cu")
		(net "UV_ALERT_N")
	)
	(via
		(at 177.532284 -113.46307)
		(size 0.4572)
		(drill 0.254)
		(layers "F.Cu" "B.Cu")
		(net "UV_ALERT_N")
	)
	(via
		(at 164.719 -115.280948)
		(size 0.508)
		(drill 0.254)
		(layers "F.Cu" "B.Cu")
		(net "UV_ALERT_N")
	)
	(segment
		(start 164.730684 -115.269264)
		(end 164.719 -115.280948)
		(width 0.11684)
		(layer "In2.Cu")
		(net "UV_ALERT_N")
	)
	(segment
		(start 170.857164 -114.759994)
		(end 166.422832 -114.759994)
		(width 0.11684)
		(layer "In2.Cu")
		(net "UV_ALERT_N")
	)
	(segment
		(start 177.532284 -113.46307)
		(end 177.306732 -113.688622)
		(width 0.11684)
		(layer "In2.Cu")
		(net "UV_ALERT_N")
	)
	(segment
		(start 177.306732 -113.688622)
		(end 171.928536 -113.688622)
		(width 0.11684)
		(layer "In2.Cu")
		(net "UV_ALERT_N")
	)
	(segment
		(start 171.928536 -113.688622)
		(end 170.857164 -114.759994)
		(width 0.11684)
		(layer "In2.Cu")
		(net "UV_ALERT_N")
	)
	(segment
		(start 166.422832 -114.759994)
		(end 165.913562 -115.269264)
		(width 0.11684)
		(layer "In2.Cu")
		(net "UV_ALERT_N")
	)
	(segment
		(start 165.913562 -115.269264)
		(end 164.730684 -115.269264)
		(width 0.11684)
		(layer "In2.Cu")
		(net "UV_ALERT_N")
	)
	(segment
		(start 51.91506 -419.054026)
		(end 52.191666 -418.77742)
		(width 0.12954)
		(layer "B.Cu")
		(net "USB2_HUB_BUF_SWB_DP")
	)
	(segment
		(start 51.465734 -419.054026)
		(end 51.91506 -419.054026)
		(width 0.12954)
		(layer "B.Cu")
		(net "USB2_HUB_BUF_SWB_DP")
	)
	(segment
		(start 51.119024 -418.707316)
		(end 51.465734 -419.054026)
		(width 0.12954)
		(layer "B.Cu")
		(net "USB2_HUB_BUF_SWB_DP")
	)
	(segment
		(start 52.449476 -419.03523)
		(end 54.451758 -419.03523)
		(width 0.14224)
		(layer "In2.Cu")
		(net "USB2_HUB_BUF_SWB_DP")
	)
	(segment
		(start 52.191666 -418.77742)
		(end 52.449476 -419.03523)
		(width 0.14224)
		(layer "In2.Cu")
		(net "USB2_HUB_BUF_SWB_DP")
	)
	(segment
		(start 55.209186 -419.34892)
		(end 58.190892 -419.34892)
		(width 0.14224)
		(layer "In2.Cu")
		(net "USB2_HUB_BUF_SWB_DP")
	)
	(segment
		(start 58.190892 -419.34892)
		(end 58.64987 -418.889942)
		(width 0.14224)
		(layer "In2.Cu")
		(net "USB2_HUB_BUF_SWB_DP")
	)
	(segment
		(start 54.451758 -419.03523)
		(end 55.209186 -419.34892)
		(width 0.14224)
		(layer "In2.Cu")
		(net "USB2_HUB_BUF_SWB_DP")
	)
	(segment
		(start 51.927252 -419.376606)
		(end 52.191666 -419.64102)
		(width 0.12954)
		(layer "B.Cu")
		(net "USB2_HUB_BUF_SWB_DN")
	)
	(segment
		(start 51.465734 -419.376606)
		(end 51.927252 -419.376606)
		(width 0.12954)
		(layer "B.Cu")
		(net "USB2_HUB_BUF_SWB_DN")
	)
	(segment
		(start 51.119024 -419.723316)
		(end 51.465734 -419.376606)
		(width 0.12954)
		(layer "B.Cu")
		(net "USB2_HUB_BUF_SWB_DN")
	)
	(segment
		(start 55.88127 -419.63086)
		(end 55.153052 -419.63086)
		(width 0.14224)
		(layer "In2.Cu")
		(net "USB2_HUB_BUF_SWB_DN")
	)
	(segment
		(start 56.01843 -419.76802)
		(end 55.88127 -419.63086)
		(width 0.14224)
		(layer "In2.Cu")
		(net "USB2_HUB_BUF_SWB_DN")
	)
	(segment
		(start 58.64987 -420.089838)
		(end 58.190892 -419.63086)
		(width 0.14224)
		(layer "In2.Cu")
		(net "USB2_HUB_BUF_SWB_DN")
	)
	(segment
		(start 55.153052 -419.63086)
		(end 54.395624 -419.31717)
		(width 0.14224)
		(layer "In2.Cu")
		(net "USB2_HUB_BUF_SWB_DN")
	)
	(segment
		(start 52.515516 -419.31717)
		(end 52.191666 -419.64102)
		(width 0.14224)
		(layer "In2.Cu")
		(net "USB2_HUB_BUF_SWB_DN")
	)
	(segment
		(start 58.190892 -419.63086)
		(end 56.58231 -419.63086)
		(width 0.14224)
		(layer "In2.Cu")
		(net "USB2_HUB_BUF_SWB_DN")
	)
	(segment
		(start 56.58231 -419.63086)
		(end 56.44515 -419.76802)
		(width 0.14224)
		(layer "In2.Cu")
		(net "USB2_HUB_BUF_SWB_DN")
	)
	(segment
		(start 56.44515 -419.76802)
		(end 56.01843 -419.76802)
		(width 0.14224)
		(layer "In2.Cu")
		(net "USB2_HUB_BUF_SWB_DN")
	)
	(segment
		(start 54.395624 -419.31717)
		(end 52.515516 -419.31717)
		(width 0.14224)
		(layer "In2.Cu")
		(net "USB2_HUB_BUF_SWB_DN")
	)
	(segment
		(start 141.608302 -17.874742)
		(end 141.878304 -18.144744)
		(width 0.12954)
		(layer "F.Cu")
		(net "USB2_HOST_BMC_B_DP")
	)
	(segment
		(start 15.288006 -105.13568)
		(end 15.441422 -105.13568)
		(width 0.12954)
		(layer "F.Cu")
		(net "USB2_HOST_BMC_B_DP")
	)
	(segment
		(start 15.954502 -105.64876)
		(end 15.954502 -105.664)
		(width 0.12954)
		(layer "F.Cu")
		(net "USB2_HOST_BMC_B_DP")
	)
	(segment
		(start 15.441422 -105.13568)
		(end 15.954502 -105.64876)
		(width 0.12954)
		(layer "F.Cu")
		(net "USB2_HOST_BMC_B_DP")
	)
	(segment
		(start 141.608302 -17.299686)
		(end 141.608302 -17.874742)
		(width 0.12954)
		(layer "F.Cu")
		(net "USB2_HOST_BMC_B_DP")
	)
	(segment
		(start 141.746986 -17.161002)
		(end 141.608302 -17.299686)
		(width 0.12954)
		(layer "F.Cu")
		(net "USB2_HOST_BMC_B_DP")
	)
	(segment
		(start 141.746986 -16.549878)
		(end 141.746986 -17.161002)
		(width 0.12954)
		(layer "F.Cu")
		(net "USB2_HOST_BMC_B_DP")
	)
	(segment
		(start 14.265402 -105.137712)
		(end 15.288006 -105.13568)
		(width 0.12954)
		(layer "F.Cu")
		(net "USB2_HOST_BMC_B_DP")
	)
	(segment
		(start 51.050698 -80.880458)
		(end 65.589404 -67.702938)
		(width 0.14224)
		(layer "In15.Cu")
		(net "USB2_HOST_BMC_B_DP")
	)
	(segment
		(start 71.24573 -64.390778)
		(end 82.909156 -59.559444)
		(width 0.14224)
		(layer "In15.Cu")
		(net "USB2_HOST_BMC_B_DP")
	)
	(segment
		(start 16.297402 -105.3211)
		(end 17.57045 -105.3211)
		(width 0.14224)
		(layer "In15.Cu")
		(net "USB2_HOST_BMC_B_DP")
	)
	(segment
		(start 128.166114 -36.46424)
		(end 130.969004 -32.606742)
		(width 0.14224)
		(layer "In15.Cu")
		(net "USB2_HOST_BMC_B_DP")
	)
	(segment
		(start 87.986362 -53.659786)
		(end 91.893644 -52.041298)
		(width 0.14224)
		(layer "In15.Cu")
		(net "USB2_HOST_BMC_B_DP")
	)
	(segment
		(start 82.909156 -59.559444)
		(end 83.956144 -58.512456)
		(width 0.14224)
		(layer "In15.Cu")
		(net "USB2_HOST_BMC_B_DP")
	)
	(segment
		(start 17.57045 -105.3211)
		(end 20.878038 -103.951024)
		(width 0.14224)
		(layer "In15.Cu")
		(net "USB2_HOST_BMC_B_DP")
	)
	(segment
		(start 141.587474 -18.435574)
		(end 141.878304 -18.144744)
		(width 0.14224)
		(layer "In15.Cu")
		(net "USB2_HOST_BMC_B_DP")
	)
	(segment
		(start 65.589404 -67.702938)
		(end 67.747896 -66.260472)
		(width 0.14224)
		(layer "In15.Cu")
		(net "USB2_HOST_BMC_B_DP")
	)
	(segment
		(start 91.893644 -52.041298)
		(end 99.526598 -52.041298)
		(width 0.14224)
		(layer "In15.Cu")
		(net "USB2_HOST_BMC_B_DP")
	)
	(segment
		(start 100.575364 -51.832764)
		(end 117.338856 -44.889166)
		(width 0.14224)
		(layer "In15.Cu")
		(net "USB2_HOST_BMC_B_DP")
	)
	(segment
		(start 30.583886 -97.465896)
		(end 33.06318 -95.642176)
		(width 0.14224)
		(layer "In15.Cu")
		(net "USB2_HOST_BMC_B_DP")
	)
	(segment
		(start 83.956144 -58.512456)
		(end 85.612732 -56.033416)
		(width 0.14224)
		(layer "In15.Cu")
		(net "USB2_HOST_BMC_B_DP")
	)
	(segment
		(start 20.878038 -103.951024)
		(end 30.583886 -97.465896)
		(width 0.14224)
		(layer "In15.Cu")
		(net "USB2_HOST_BMC_B_DP")
	)
	(segment
		(start 124.579126 -40.051228)
		(end 128.166114 -36.46424)
		(width 0.14224)
		(layer "In15.Cu")
		(net "USB2_HOST_BMC_B_DP")
	)
	(segment
		(start 117.338856 -44.889166)
		(end 124.579126 -40.051228)
		(width 0.14224)
		(layer "In15.Cu")
		(net "USB2_HOST_BMC_B_DP")
	)
	(segment
		(start 85.612732 -56.033416)
		(end 87.986362 -53.659786)
		(width 0.14224)
		(layer "In15.Cu")
		(net "USB2_HOST_BMC_B_DP")
	)
	(segment
		(start 141.542516 -20.242022)
		(end 141.587474 -20.0152)
		(width 0.14224)
		(layer "In15.Cu")
		(net "USB2_HOST_BMC_B_DP")
	)
	(segment
		(start 15.954502 -105.664)
		(end 16.297402 -105.3211)
		(width 0.14224)
		(layer "In15.Cu")
		(net "USB2_HOST_BMC_B_DP")
	)
	(segment
		(start 141.244828 -20.960842)
		(end 141.542516 -20.242022)
		(width 0.14224)
		(layer "In15.Cu")
		(net "USB2_HOST_BMC_B_DP")
	)
	(segment
		(start 141.587474 -20.0152)
		(end 141.587474 -18.435574)
		(width 0.14224)
		(layer "In15.Cu")
		(net "USB2_HOST_BMC_B_DP")
	)
	(segment
		(start 67.747896 -66.260472)
		(end 71.24573 -64.390778)
		(width 0.14224)
		(layer "In15.Cu")
		(net "USB2_HOST_BMC_B_DP")
	)
	(segment
		(start 132.890768 -28.832048)
		(end 141.244828 -20.960842)
		(width 0.14224)
		(layer "In15.Cu")
		(net "USB2_HOST_BMC_B_DP")
	)
	(segment
		(start 33.06318 -95.642176)
		(end 51.050698 -80.880458)
		(width 0.14224)
		(layer "In15.Cu")
		(net "USB2_HOST_BMC_B_DP")
	)
	(segment
		(start 130.969004 -32.606742)
		(end 132.890768 -28.832048)
		(width 0.14224)
		(layer "In15.Cu")
		(net "USB2_HOST_BMC_B_DP")
	)
	(segment
		(start 99.526598 -52.041298)
		(end 100.575364 -51.832764)
		(width 0.14224)
		(layer "In15.Cu")
		(net "USB2_HOST_BMC_B_DP")
	)
	(segment
		(start 16.447008 -105.16616)
		(end 15.954248 -104.6734)
		(width 0.12954)
		(layer "F.Cu")
		(net "USB2_HOST_BMC_B_DN")
	)
	(segment
		(start 16.645382 -105.16616)
		(end 16.447008 -105.16616)
		(width 0.12954)
		(layer "F.Cu")
		(net "USB2_HOST_BMC_B_DN")
	)
	(segment
		(start 17.630394 -105.16616)
		(end 17.658842 -105.137712)
		(width 0.12954)
		(layer "F.Cu")
		(net "USB2_HOST_BMC_B_DN")
	)
	(segment
		(start 141.147038 -17.161002)
		(end 141.285722 -17.299686)
		(width 0.12954)
		(layer "F.Cu")
		(net "USB2_HOST_BMC_B_DN")
	)
	(segment
		(start 16.645382 -105.16616)
		(end 17.630394 -105.16616)
		(width 0.12954)
		(layer "F.Cu")
		(net "USB2_HOST_BMC_B_DN")
	)
	(segment
		(start 141.285722 -17.873726)
		(end 141.014704 -18.144744)
		(width 0.12954)
		(layer "F.Cu")
		(net "USB2_HOST_BMC_B_DN")
	)
	(segment
		(start 141.147038 -16.549878)
		(end 141.147038 -17.161002)
		(width 0.12954)
		(layer "F.Cu")
		(net "USB2_HOST_BMC_B_DN")
	)
	(segment
		(start 141.285722 -17.299686)
		(end 141.285722 -17.873726)
		(width 0.12954)
		(layer "F.Cu")
		(net "USB2_HOST_BMC_B_DN")
	)
	(segment
		(start 141.271244 -20.159726)
		(end 141.305534 -19.98726)
		(width 0.14224)
		(layer "In15.Cu")
		(net "USB2_HOST_BMC_B_DN")
	)
	(segment
		(start 139.257278 -22.445726)
		(end 139.257532 -22.44598)
		(width 0.14224)
		(layer "In15.Cu")
		(net "USB2_HOST_BMC_B_DN")
	)
	(segment
		(start 82.74939 -59.32043)
		(end 83.737196 -58.332624)
		(width 0.14224)
		(layer "In15.Cu")
		(net "USB2_HOST_BMC_B_DN")
	)
	(segment
		(start 140.080238 -21.48205)
		(end 140.389356 -21.190966)
		(width 0.14224)
		(layer "In15.Cu")
		(net "USB2_HOST_BMC_B_DN")
	)
	(segment
		(start 140.583158 -21.196554)
		(end 141.007338 -20.797012)
		(width 0.14224)
		(layer "In15.Cu")
		(net "USB2_HOST_BMC_B_DN")
	)
	(segment
		(start 138.948668 -22.736556)
		(end 139.257278 -22.445726)
		(width 0.14224)
		(layer "In15.Cu")
		(net "USB2_HOST_BMC_B_DN")
	)
	(segment
		(start 137.62863 -23.791926)
		(end 137.937748 -23.500842)
		(width 0.14224)
		(layer "In15.Cu")
		(net "USB2_HOST_BMC_B_DN")
	)
	(segment
		(start 139.257532 -22.44598)
		(end 139.26312 -22.251924)
		(width 0.14224)
		(layer "In15.Cu")
		(net "USB2_HOST_BMC_B_DN")
	)
	(segment
		(start 130.727704 -32.458914)
		(end 132.66166 -28.660344)
		(width 0.14224)
		(layer "In15.Cu")
		(net "USB2_HOST_BMC_B_DN")
	)
	(segment
		(start 30.421834 -97.23501)
		(end 32.889952 -95.419164)
		(width 0.14224)
		(layer "In15.Cu")
		(net "USB2_HOST_BMC_B_DN")
	)
	(segment
		(start 20.744434 -103.701088)
		(end 30.421834 -97.23501)
		(width 0.14224)
		(layer "In15.Cu")
		(net "USB2_HOST_BMC_B_DN")
	)
	(segment
		(start 141.305534 -19.98726)
		(end 141.305534 -18.435574)
		(width 0.14224)
		(layer "In15.Cu")
		(net "USB2_HOST_BMC_B_DN")
	)
	(segment
		(start 32.889952 -95.419164)
		(end 50.866548 -80.666844)
		(width 0.14224)
		(layer "In15.Cu")
		(net "USB2_HOST_BMC_B_DN")
	)
	(segment
		(start 141.007338 -20.797012)
		(end 141.271244 -20.159726)
		(width 0.14224)
		(layer "In15.Cu")
		(net "USB2_HOST_BMC_B_DN")
	)
	(segment
		(start 132.66166 -28.660344)
		(end 137.622788 -23.985728)
		(width 0.14224)
		(layer "In15.Cu")
		(net "USB2_HOST_BMC_B_DN")
	)
	(segment
		(start 141.305534 -18.435574)
		(end 141.014704 -18.144744)
		(width 0.14224)
		(layer "In15.Cu")
		(net "USB2_HOST_BMC_B_DN")
	)
	(segment
		(start 138.44016 -23.215854)
		(end 138.445748 -23.021798)
		(width 0.14224)
		(layer "In15.Cu")
		(net "USB2_HOST_BMC_B_DN")
	)
	(segment
		(start 91.83751 -51.759358)
		(end 99.498658 -51.759358)
		(width 0.14224)
		(layer "In15.Cu")
		(net "USB2_HOST_BMC_B_DN")
	)
	(segment
		(start 15.954248 -104.699308)
		(end 16.2941 -105.03916)
		(width 0.14224)
		(layer "In15.Cu")
		(net "USB2_HOST_BMC_B_DN")
	)
	(segment
		(start 50.866548 -80.666844)
		(end 65.415414 -67.479926)
		(width 0.14224)
		(layer "In15.Cu")
		(net "USB2_HOST_BMC_B_DN")
	)
	(segment
		(start 140.07465 -21.675852)
		(end 140.080238 -21.48205)
		(width 0.14224)
		(layer "In15.Cu")
		(net "USB2_HOST_BMC_B_DN")
	)
	(segment
		(start 140.389356 -21.190966)
		(end 140.583158 -21.196554)
		(width 0.14224)
		(layer "In15.Cu")
		(net "USB2_HOST_BMC_B_DN")
	)
	(segment
		(start 99.498658 -51.759358)
		(end 100.493068 -51.561492)
		(width 0.14224)
		(layer "In15.Cu")
		(net "USB2_HOST_BMC_B_DN")
	)
	(segment
		(start 139.26312 -22.251924)
		(end 139.572238 -21.96084)
		(width 0.14224)
		(layer "In15.Cu")
		(net "USB2_HOST_BMC_B_DN")
	)
	(segment
		(start 138.445748 -23.021798)
		(end 138.754866 -22.730714)
		(width 0.14224)
		(layer "In15.Cu")
		(net "USB2_HOST_BMC_B_DN")
	)
	(segment
		(start 87.826596 -53.420772)
		(end 91.83751 -51.759358)
		(width 0.14224)
		(layer "In15.Cu")
		(net "USB2_HOST_BMC_B_DN")
	)
	(segment
		(start 137.623042 -23.985728)
		(end 137.62863 -23.791926)
		(width 0.14224)
		(layer "In15.Cu")
		(net "USB2_HOST_BMC_B_DN")
	)
	(segment
		(start 138.13155 -23.506684)
		(end 138.44016 -23.215854)
		(width 0.14224)
		(layer "In15.Cu")
		(net "USB2_HOST_BMC_B_DN")
	)
	(segment
		(start 65.415414 -67.479926)
		(end 67.602608 -66.018156)
		(width 0.14224)
		(layer "In15.Cu")
		(net "USB2_HOST_BMC_B_DN")
	)
	(segment
		(start 85.393784 -55.853584)
		(end 87.826596 -53.420772)
		(width 0.14224)
		(layer "In15.Cu")
		(net "USB2_HOST_BMC_B_DN")
	)
	(segment
		(start 137.622788 -23.985728)
		(end 137.623042 -23.985728)
		(width 0.14224)
		(layer "In15.Cu")
		(net "USB2_HOST_BMC_B_DN")
	)
	(segment
		(start 71.12508 -64.135508)
		(end 82.74939 -59.32043)
		(width 0.14224)
		(layer "In15.Cu")
		(net "USB2_HOST_BMC_B_DN")
	)
	(segment
		(start 15.954248 -104.6734)
		(end 15.954248 -104.699308)
		(width 0.14224)
		(layer "In15.Cu")
		(net "USB2_HOST_BMC_B_DN")
	)
	(segment
		(start 117.205252 -44.63923)
		(end 124.399294 -39.83228)
		(width 0.14224)
		(layer "In15.Cu")
		(net "USB2_HOST_BMC_B_DN")
	)
	(segment
		(start 17.514316 -105.03916)
		(end 20.744434 -103.701088)
		(width 0.14224)
		(layer "In15.Cu")
		(net "USB2_HOST_BMC_B_DN")
	)
	(segment
		(start 16.2941 -105.03916)
		(end 17.514316 -105.03916)
		(width 0.14224)
		(layer "In15.Cu")
		(net "USB2_HOST_BMC_B_DN")
	)
	(segment
		(start 127.950976 -36.280598)
		(end 130.727704 -32.458914)
		(width 0.14224)
		(layer "In15.Cu")
		(net "USB2_HOST_BMC_B_DN")
	)
	(segment
		(start 83.737196 -58.332624)
		(end 85.393784 -55.853584)
		(width 0.14224)
		(layer "In15.Cu")
		(net "USB2_HOST_BMC_B_DN")
	)
	(segment
		(start 137.937748 -23.500842)
		(end 138.13155 -23.506684)
		(width 0.14224)
		(layer "In15.Cu")
		(net "USB2_HOST_BMC_B_DN")
	)
	(segment
		(start 139.572238 -21.96084)
		(end 139.76604 -21.966682)
		(width 0.14224)
		(layer "In15.Cu")
		(net "USB2_HOST_BMC_B_DN")
	)
	(segment
		(start 139.76604 -21.966682)
		(end 140.07465 -21.675852)
		(width 0.14224)
		(layer "In15.Cu")
		(net "USB2_HOST_BMC_B_DN")
	)
	(segment
		(start 100.493068 -51.561492)
		(end 117.205252 -44.63923)
		(width 0.14224)
		(layer "In15.Cu")
		(net "USB2_HOST_BMC_B_DN")
	)
	(segment
		(start 67.602608 -66.018156)
		(end 71.12508 -64.135508)
		(width 0.14224)
		(layer "In15.Cu")
		(net "USB2_HOST_BMC_B_DN")
	)
	(segment
		(start 124.399294 -39.83228)
		(end 127.950976 -36.280598)
		(width 0.14224)
		(layer "In15.Cu")
		(net "USB2_HOST_BMC_B_DN")
	)
	(segment
		(start 138.754866 -22.730714)
		(end 138.948668 -22.736556)
		(width 0.14224)
		(layer "In15.Cu")
		(net "USB2_HOST_BMC_B_DN")
	)
	(segment
		(start 139.808204 -17.255998)
		(end 139.808204 -19.831558)
		(width 0.12954)
		(layer "F.Cu")
		(net "USB2_CPU0_P1_DP")
	)
	(segment
		(start 139.946888 -17.117314)
		(end 139.808204 -17.255998)
		(width 0.12954)
		(layer "F.Cu")
		(net "USB2_CPU0_P1_DP")
	)
	(segment
		(start 368.64798 -222.070168)
		(end 369.114832 -221.80423)
		(width 0.12954)
		(layer "F.Cu")
		(net "USB2_CPU0_P1_DP")
	)
	(segment
		(start 139.808204 -19.831558)
		(end 140.137134 -20.160488)
		(width 0.12954)
		(layer "F.Cu")
		(net "USB2_CPU0_P1_DP")
	)
	(segment
		(start 139.946888 -16.549878)
		(end 139.946888 -17.117314)
		(width 0.12954)
		(layer "F.Cu")
		(net "USB2_CPU0_P1_DP")
	)
	(via
		(at 140.137134 -20.160488)
		(size 0.508)
		(drill 0.254)
		(layers "F.Cu" "B.Cu")
		(net "USB2_CPU0_P1_DP")
	)
	(via
		(at 369.114832 -221.80423)
		(size 0.4064)
		(drill 0.2032)
		(layers "F.Cu" "B.Cu")
		(net "USB2_CPU0_P1_DP")
	)
	(segment
		(start 210.681824 -67.924934)
		(end 210.681824 -71.307706)
		(width 0.12954)
		(layer "B.Cu")
		(net "USB2_CPU0_P1_DP")
	)
	(segment
		(start 139.833096 -20.464526)
		(end 139.833096 -20.644358)
		(width 0.12954)
		(layer "B.Cu")
		(net "USB2_CPU0_P1_DP")
	)
	(segment
		(start 202.824842 -65.428368)
		(end 208.185258 -65.428368)
		(width 0.12954)
		(layer "B.Cu")
		(net "USB2_CPU0_P1_DP")
	)
	(segment
		(start 290.051744 -171.879006)
		(end 302.16729 -174.288958)
		(width 0.12954)
		(layer "B.Cu")
		(net "USB2_CPU0_P1_DP")
	)
	(segment
		(start 368.806222 -221.17812)
		(end 368.806222 -221.49562)
		(width 0.12954)
		(layer "B.Cu")
		(net "USB2_CPU0_P1_DP")
	)
	(segment
		(start 170.437302 -46.044612)
		(end 174.77232 -52.53228)
		(width 0.12954)
		(layer "B.Cu")
		(net "USB2_CPU0_P1_DP")
	)
	(segment
		(start 179.600352 -53.380894)
		(end 181.116478 -54.89702)
		(width 0.12954)
		(layer "B.Cu")
		(net "USB2_CPU0_P1_DP")
	)
	(segment
		(start 217.321384 -74.668126)
		(end 218.035124 -74.963782)
		(width 0.12954)
		(layer "B.Cu")
		(net "USB2_CPU0_P1_DP")
	)
	(segment
		(start 223.05264 -88.16721)
		(end 240.981738 -131.452112)
		(width 0.12954)
		(layer "B.Cu")
		(net "USB2_CPU0_P1_DP")
	)
	(segment
		(start 175.620934 -53.380894)
		(end 179.600352 -53.380894)
		(width 0.12954)
		(layer "B.Cu")
		(net "USB2_CPU0_P1_DP")
	)
	(segment
		(start 322.97243 -182.907178)
		(end 356.932992 -216.86774)
		(width 0.12954)
		(layer "B.Cu")
		(net "USB2_CPU0_P1_DP")
	)
	(segment
		(start 223.05264 -83.207098)
		(end 223.05264 -88.16721)
		(width 0.12954)
		(layer "B.Cu")
		(net "USB2_CPU0_P1_DP")
	)
	(segment
		(start 174.77232 -52.53228)
		(end 175.620934 -53.380894)
		(width 0.12954)
		(layer "B.Cu")
		(net "USB2_CPU0_P1_DP")
	)
	(segment
		(start 220.77172 -77.700378)
		(end 223.05264 -83.207098)
		(width 0.12954)
		(layer "B.Cu")
		(net "USB2_CPU0_P1_DP")
	)
	(segment
		(start 363.77118 -219.700348)
		(end 367.32845 -219.700348)
		(width 0.12954)
		(layer "B.Cu")
		(net "USB2_CPU0_P1_DP")
	)
	(segment
		(start 185.849514 -54.89702)
		(end 199.628252 -64.104012)
		(width 0.12954)
		(layer "B.Cu")
		(net "USB2_CPU0_P1_DP")
	)
	(segment
		(start 147.397216 -28.208478)
		(end 163.0807 -38.68801)
		(width 0.12954)
		(layer "B.Cu")
		(net "USB2_CPU0_P1_DP")
	)
	(segment
		(start 218.035124 -74.963782)
		(end 220.77172 -77.700378)
		(width 0.12954)
		(layer "B.Cu")
		(net "USB2_CPU0_P1_DP")
	)
	(segment
		(start 210.681824 -71.307706)
		(end 214.042244 -74.668126)
		(width 0.12954)
		(layer "B.Cu")
		(net "USB2_CPU0_P1_DP")
	)
	(segment
		(start 163.0807 -38.68801)
		(end 170.437302 -46.044612)
		(width 0.12954)
		(layer "B.Cu")
		(net "USB2_CPU0_P1_DP")
	)
	(segment
		(start 181.116478 -54.89702)
		(end 185.849514 -54.89702)
		(width 0.12954)
		(layer "B.Cu")
		(net "USB2_CPU0_P1_DP")
	)
	(segment
		(start 368.806222 -221.49562)
		(end 369.114832 -221.80423)
		(width 0.12954)
		(layer "B.Cu")
		(net "USB2_CPU0_P1_DP")
	)
	(segment
		(start 240.981738 -131.452112)
		(end 271.484344 -161.954718)
		(width 0.12954)
		(layer "B.Cu")
		(net "USB2_CPU0_P1_DP")
	)
	(segment
		(start 367.32845 -219.700348)
		(end 368.806222 -221.17812)
		(width 0.12954)
		(layer "B.Cu")
		(net "USB2_CPU0_P1_DP")
	)
	(segment
		(start 140.137134 -20.160488)
		(end 139.833096 -20.464526)
		(width 0.12954)
		(layer "B.Cu")
		(net "USB2_CPU0_P1_DP")
	)
	(segment
		(start 302.16729 -174.288958)
		(end 322.97243 -182.907178)
		(width 0.12954)
		(layer "B.Cu")
		(net "USB2_CPU0_P1_DP")
	)
	(segment
		(start 214.042244 -74.668126)
		(end 217.321384 -74.668126)
		(width 0.12954)
		(layer "B.Cu")
		(net "USB2_CPU0_P1_DP")
	)
	(segment
		(start 199.628252 -64.104012)
		(end 202.824842 -65.428368)
		(width 0.12954)
		(layer "B.Cu")
		(net "USB2_CPU0_P1_DP")
	)
	(segment
		(start 139.833096 -20.644358)
		(end 147.397216 -28.208478)
		(width 0.12954)
		(layer "B.Cu")
		(net "USB2_CPU0_P1_DP")
	)
	(segment
		(start 356.932992 -216.86774)
		(end 363.77118 -219.700348)
		(width 0.12954)
		(layer "B.Cu")
		(net "USB2_CPU0_P1_DP")
	)
	(segment
		(start 271.484344 -161.954718)
		(end 290.051744 -171.879006)
		(width 0.12954)
		(layer "B.Cu")
		(net "USB2_CPU0_P1_DP")
	)
	(segment
		(start 208.185258 -65.428368)
		(end 210.681824 -67.924934)
		(width 0.12954)
		(layer "B.Cu")
		(net "USB2_CPU0_P1_DP")
	)
	(segment
		(start 139.34694 -17.112234)
		(end 139.485624 -17.250918)
		(width 0.12954)
		(layer "F.Cu")
		(net "USB2_CPU0_P1_DN")
	)
	(segment
		(start 139.480544 -19.572732)
		(end 139.480544 -19.826478)
		(width 0.12954)
		(layer "F.Cu")
		(net "USB2_CPU0_P1_DN")
	)
	(segment
		(start 139.34694 -16.549878)
		(end 139.34694 -17.112234)
		(width 0.12954)
		(layer "F.Cu")
		(net "USB2_CPU0_P1_DN")
	)
	(segment
		(start 139.485624 -19.567652)
		(end 139.480544 -19.572732)
		(width 0.12954)
		(layer "F.Cu")
		(net "USB2_CPU0_P1_DN")
	)
	(segment
		(start 139.485624 -17.250918)
		(end 139.485624 -19.567652)
		(width 0.12954)
		(layer "F.Cu")
		(net "USB2_CPU0_P1_DN")
	)
	(segment
		(start 139.480544 -19.826478)
		(end 139.146534 -20.160488)
		(width 0.12954)
		(layer "F.Cu")
		(net "USB2_CPU0_P1_DN")
	)
	(segment
		(start 367.707926 -222.070168)
		(end 368.174778 -221.80423)
		(width 0.12954)
		(layer "F.Cu")
		(net "USB2_CPU0_P1_DN")
	)
	(via
		(at 368.174778 -221.80423)
		(size 0.4064)
		(drill 0.2032)
		(layers "F.Cu" "B.Cu")
		(net "USB2_CPU0_P1_DN")
	)
	(via
		(at 139.146534 -20.160488)
		(size 0.508)
		(drill 0.254)
		(layers "F.Cu" "B.Cu")
		(net "USB2_CPU0_P1_DN")
	)
	(segment
		(start 210.359244 -71.441564)
		(end 213.908386 -74.990706)
		(width 0.12954)
		(layer "B.Cu")
		(net "USB2_CPU0_P1_DN")
	)
	(segment
		(start 139.480544 -20.748244)
		(end 147.191476 -28.459176)
		(width 0.12954)
		(layer "B.Cu")
		(net "USB2_CPU0_P1_DN")
	)
	(segment
		(start 147.191476 -28.459176)
		(end 162.87496 -38.938708)
		(width 0.12954)
		(layer "B.Cu")
		(net "USB2_CPU0_P1_DN")
	)
	(segment
		(start 179.466494 -53.703474)
		(end 180.98262 -55.2196)
		(width 0.12954)
		(layer "B.Cu")
		(net "USB2_CPU0_P1_DN")
	)
	(segment
		(start 363.706918 -220.022928)
		(end 367.194592 -220.022928)
		(width 0.12954)
		(layer "B.Cu")
		(net "USB2_CPU0_P1_DN")
	)
	(segment
		(start 174.503842 -52.72024)
		(end 175.487076 -53.703474)
		(width 0.12954)
		(layer "B.Cu")
		(net "USB2_CPU0_P1_DN")
	)
	(segment
		(start 222.73006 -83.27136)
		(end 222.73006 -88.231472)
		(width 0.12954)
		(layer "B.Cu")
		(net "USB2_CPU0_P1_DN")
	)
	(segment
		(start 289.941762 -172.186092)
		(end 302.073056 -174.599346)
		(width 0.12954)
		(layer "B.Cu")
		(net "USB2_CPU0_P1_DN")
	)
	(segment
		(start 199.475344 -64.390016)
		(end 202.76058 -65.750948)
		(width 0.12954)
		(layer "B.Cu")
		(net "USB2_CPU0_P1_DN")
	)
	(segment
		(start 217.257122 -74.990706)
		(end 217.852244 -75.23734)
		(width 0.12954)
		(layer "B.Cu")
		(net "USB2_CPU0_P1_DN")
	)
	(segment
		(start 368.483642 -221.495366)
		(end 368.174778 -221.80423)
		(width 0.12954)
		(layer "B.Cu")
		(net "USB2_CPU0_P1_DN")
	)
	(segment
		(start 185.75147 -55.2196)
		(end 199.475344 -64.390016)
		(width 0.12954)
		(layer "B.Cu")
		(net "USB2_CPU0_P1_DN")
	)
	(segment
		(start 367.194592 -220.022928)
		(end 368.483642 -221.311978)
		(width 0.12954)
		(layer "B.Cu")
		(net "USB2_CPU0_P1_DN")
	)
	(segment
		(start 213.908386 -74.990706)
		(end 217.257122 -74.990706)
		(width 0.12954)
		(layer "B.Cu")
		(net "USB2_CPU0_P1_DN")
	)
	(segment
		(start 170.186604 -46.250352)
		(end 172.34535 -49.480978)
		(width 0.12954)
		(layer "B.Cu")
		(net "USB2_CPU0_P1_DN")
	)
	(segment
		(start 174.503842 -52.71135)
		(end 174.503842 -52.72024)
		(width 0.12954)
		(layer "B.Cu")
		(net "USB2_CPU0_P1_DN")
	)
	(segment
		(start 217.852244 -75.23734)
		(end 220.498162 -77.883258)
		(width 0.12954)
		(layer "B.Cu")
		(net "USB2_CPU0_P1_DN")
	)
	(segment
		(start 172.34535 -49.480978)
		(end 174.503842 -52.71135)
		(width 0.12954)
		(layer "B.Cu")
		(net "USB2_CPU0_P1_DN")
	)
	(segment
		(start 180.98262 -55.2196)
		(end 185.75147 -55.2196)
		(width 0.12954)
		(layer "B.Cu")
		(net "USB2_CPU0_P1_DN")
	)
	(segment
		(start 220.498162 -77.883258)
		(end 222.73006 -83.27136)
		(width 0.12954)
		(layer "B.Cu")
		(net "USB2_CPU0_P1_DN")
	)
	(segment
		(start 202.76058 -65.750948)
		(end 208.0514 -65.750948)
		(width 0.12954)
		(layer "B.Cu")
		(net "USB2_CPU0_P1_DN")
	)
	(segment
		(start 271.290034 -162.216846)
		(end 289.941762 -172.186092)
		(width 0.12954)
		(layer "B.Cu")
		(net "USB2_CPU0_P1_DN")
	)
	(segment
		(start 240.70818 -131.634992)
		(end 271.290034 -162.216846)
		(width 0.12954)
		(layer "B.Cu")
		(net "USB2_CPU0_P1_DN")
	)
	(segment
		(start 356.750112 -217.141298)
		(end 363.706918 -220.022928)
		(width 0.12954)
		(layer "B.Cu")
		(net "USB2_CPU0_P1_DN")
	)
	(segment
		(start 162.87496 -38.938708)
		(end 170.186604 -46.250352)
		(width 0.12954)
		(layer "B.Cu")
		(net "USB2_CPU0_P1_DN")
	)
	(segment
		(start 322.78955 -183.180736)
		(end 356.750112 -217.141298)
		(width 0.12954)
		(layer "B.Cu")
		(net "USB2_CPU0_P1_DN")
	)
	(segment
		(start 368.483642 -221.311978)
		(end 368.483642 -221.495366)
		(width 0.12954)
		(layer "B.Cu")
		(net "USB2_CPU0_P1_DN")
	)
	(segment
		(start 139.146534 -20.160488)
		(end 139.480544 -20.494498)
		(width 0.12954)
		(layer "B.Cu")
		(net "USB2_CPU0_P1_DN")
	)
	(segment
		(start 139.480544 -20.494498)
		(end 139.480544 -20.748244)
		(width 0.12954)
		(layer "B.Cu")
		(net "USB2_CPU0_P1_DN")
	)
	(segment
		(start 302.073056 -174.599346)
		(end 322.78955 -183.180736)
		(width 0.12954)
		(layer "B.Cu")
		(net "USB2_CPU0_P1_DN")
	)
	(segment
		(start 175.487076 -53.703474)
		(end 179.466494 -53.703474)
		(width 0.12954)
		(layer "B.Cu")
		(net "USB2_CPU0_P1_DN")
	)
	(segment
		(start 210.359244 -68.058792)
		(end 210.359244 -71.441564)
		(width 0.12954)
		(layer "B.Cu")
		(net "USB2_CPU0_P1_DN")
	)
	(segment
		(start 222.73006 -88.231472)
		(end 240.70818 -131.634992)
		(width 0.12954)
		(layer "B.Cu")
		(net "USB2_CPU0_P1_DN")
	)
	(segment
		(start 208.0514 -65.750948)
		(end 210.359244 -68.058792)
		(width 0.12954)
		(layer "B.Cu")
		(net "USB2_CPU0_P1_DN")
	)
	(segment
		(start 221.78645 -190.619888)
		(end 221.441264 -190.274702)
		(width 0.12954)
		(layer "F.Cu")
		(net "USB2_CPU0_P10_DP")
	)
	(segment
		(start 194.340988 -146.716242)
		(end 185.533792 -144.964404)
		(width 0.12954)
		(layer "F.Cu")
		(net "USB2_CPU0_P10_DP")
	)
	(segment
		(start 171.912534 -140.659358)
		(end 166.374572 -135.121396)
		(width 0.12954)
		(layer "F.Cu")
		(net "USB2_CPU0_P10_DP")
	)
	(segment
		(start 13.52423 -16.069564)
		(end 13.872464 -15.72133)
		(width 0.12954)
		(layer "F.Cu")
		(net "USB2_CPU0_P10_DP")
	)
	(segment
		(start 201.411332 -149.644354)
		(end 194.340988 -146.716242)
		(width 0.12954)
		(layer "F.Cu")
		(net "USB2_CPU0_P10_DP")
	)
	(segment
		(start 14.820392 -18.523204)
		(end 13.634974 -16.749014)
		(width 0.12954)
		(layer "F.Cu")
		(net "USB2_CPU0_P10_DP")
	)
	(segment
		(start 166.329106 -135.076184)
		(end 140.13053 -124.224542)
		(width 0.12954)
		(layer "F.Cu")
		(net "USB2_CPU0_P10_DP")
	)
	(segment
		(start 213.470236 -161.703766)
		(end 201.411332 -149.644354)
		(width 0.12954)
		(layer "F.Cu")
		(net "USB2_CPU0_P10_DP")
	)
	(segment
		(start 166.374318 -135.121396)
		(end 166.329106 -135.076184)
		(width 0.12954)
		(layer "F.Cu")
		(net "USB2_CPU0_P10_DP")
	)
	(segment
		(start 221.389194 -180.821838)
		(end 213.470236 -161.703766)
		(width 0.12954)
		(layer "F.Cu")
		(net "USB2_CPU0_P10_DP")
	)
	(segment
		(start 182.303674 -144.964404)
		(end 171.912534 -140.659358)
		(width 0.12954)
		(layer "F.Cu")
		(net "USB2_CPU0_P10_DP")
	)
	(segment
		(start 221.441264 -190.274702)
		(end 221.441264 -181.170072)
		(width 0.12954)
		(layer "F.Cu")
		(net "USB2_CPU0_P10_DP")
	)
	(segment
		(start 140.13053 -124.224542)
		(end 15.173198 -19.373088)
		(width 0.12954)
		(layer "F.Cu")
		(net "USB2_CPU0_P10_DP")
	)
	(segment
		(start 13.634974 -16.749014)
		(end 13.52423 -16.48206)
		(width 0.12954)
		(layer "F.Cu")
		(net "USB2_CPU0_P10_DP")
	)
	(segment
		(start 333.227934 -295.690036)
		(end 332.761082 -295.955974)
		(width 0.12954)
		(layer "F.Cu")
		(net "USB2_CPU0_P10_DP")
	)
	(segment
		(start 15.173198 -19.373088)
		(end 14.820392 -18.523204)
		(width 0.12954)
		(layer "F.Cu")
		(net "USB2_CPU0_P10_DP")
	)
	(segment
		(start 221.441264 -181.170072)
		(end 221.389194 -180.821838)
		(width 0.12954)
		(layer "F.Cu")
		(net "USB2_CPU0_P10_DP")
	)
	(segment
		(start 13.52423 -16.48206)
		(end 13.52423 -16.069564)
		(width 0.12954)
		(layer "F.Cu")
		(net "USB2_CPU0_P10_DP")
	)
	(segment
		(start 185.533792 -144.964404)
		(end 182.303674 -144.964404)
		(width 0.12954)
		(layer "F.Cu")
		(net "USB2_CPU0_P10_DP")
	)
	(segment
		(start 166.374572 -135.121396)
		(end 166.374318 -135.121396)
		(width 0.12954)
		(layer "F.Cu")
		(net "USB2_CPU0_P10_DP")
	)
	(via
		(at 332.761082 -295.955974)
		(size 0.4064)
		(drill 0.2032)
		(layers "F.Cu" "B.Cu")
		(net "USB2_CPU0_P10_DP")
	)
	(via
		(at 221.78645 -190.619888)
		(size 0.508)
		(drill 0.254)
		(layers "F.Cu" "B.Cu")
		(net "USB2_CPU0_P10_DP")
	)
	(segment
		(start 223.643444 -188.631068)
		(end 223.867472 -188.780674)
		(width 0.12954)
		(layer "B.Cu")
		(net "USB2_CPU0_P10_DP")
	)
	(segment
		(start 308.163214 -190.929768)
		(end 309.152036 -191.339216)
		(width 0.12954)
		(layer "B.Cu")
		(net "USB2_CPU0_P10_DP")
	)
	(segment
		(start 271.280128 -185.996326)
		(end 271.954752 -186.707018)
		(width 0.12954)
		(layer "B.Cu")
		(net "USB2_CPU0_P10_DP")
	)
	(segment
		(start 309.977028 -202.380088)
		(end 310.052212 -202.759056)
		(width 0.12954)
		(layer "B.Cu")
		(net "USB2_CPU0_P10_DP")
	)
	(segment
		(start 310.276494 -202.908662)
		(end 310.27624 -202.908662)
		(width 0.12954)
		(layer "B.Cu")
		(net "USB2_CPU0_P10_DP")
	)
	(segment
		(start 332.452472 -296.929556)
		(end 332.452472 -296.61231)
		(width 0.12954)
		(layer "B.Cu")
		(net "USB2_CPU0_P10_DP")
	)
	(segment
		(start 274.535392 -188.684662)
		(end 296.877994 -188.684662)
		(width 0.12954)
		(layer "B.Cu")
		(net "USB2_CPU0_P10_DP")
	)
	(segment
		(start 221.45498 -190.042292)
		(end 222.410274 -188.876178)
		(width 0.12954)
		(layer "B.Cu")
		(net "USB2_CPU0_P10_DP")
	)
	(segment
		(start 326.50684 -297.538648)
		(end 331.84338 -297.538648)
		(width 0.12954)
		(layer "B.Cu")
		(net "USB2_CPU0_P10_DP")
	)
	(segment
		(start 310.27624 -202.908662)
		(end 310.351424 -203.286614)
		(width 0.12954)
		(layer "B.Cu")
		(net "USB2_CPU0_P10_DP")
	)
	(segment
		(start 296.877994 -188.684662)
		(end 308.163214 -190.929768)
		(width 0.12954)
		(layer "B.Cu")
		(net "USB2_CPU0_P10_DP")
	)
	(segment
		(start 224.24644 -188.705236)
		(end 224.396046 -188.481208)
		(width 0.12954)
		(layer "B.Cu")
		(net "USB2_CPU0_P10_DP")
	)
	(segment
		(start 310.351678 -203.287122)
		(end 310.202072 -203.51115)
		(width 0.12954)
		(layer "B.Cu")
		(net "USB2_CPU0_P10_DP")
	)
	(segment
		(start 310.202072 -203.51115)
		(end 310.277256 -203.890118)
		(width 0.12954)
		(layer "B.Cu")
		(net "USB2_CPU0_P10_DP")
	)
	(segment
		(start 322.075302 -257.542538)
		(end 322.075302 -290.467542)
		(width 0.12954)
		(layer "B.Cu")
		(net "USB2_CPU0_P10_DP")
	)
	(segment
		(start 235.713524 -186.230006)
		(end 253.28118 -186.230006)
		(width 0.12954)
		(layer "B.Cu")
		(net "USB2_CPU0_P10_DP")
	)
	(segment
		(start 222.410274 -188.876178)
		(end 223.643444 -188.631068)
		(width 0.12954)
		(layer "B.Cu")
		(net "USB2_CPU0_P10_DP")
	)
	(segment
		(start 310.50103 -204.039724)
		(end 320.123058 -252.4125)
		(width 0.12954)
		(layer "B.Cu")
		(net "USB2_CPU0_P10_DP")
	)
	(segment
		(start 310.501538 -204.039724)
		(end 310.50103 -204.039724)
		(width 0.12954)
		(layer "B.Cu")
		(net "USB2_CPU0_P10_DP")
	)
	(segment
		(start 269.136368 -185.458862)
		(end 271.280128 -185.996326)
		(width 0.12954)
		(layer "B.Cu")
		(net "USB2_CPU0_P10_DP")
	)
	(segment
		(start 271.954752 -186.707018)
		(end 274.535392 -188.684662)
		(width 0.12954)
		(layer "B.Cu")
		(net "USB2_CPU0_P10_DP")
	)
	(segment
		(start 310.351424 -203.286868)
		(end 310.351678 -203.287122)
		(width 0.12954)
		(layer "B.Cu")
		(net "USB2_CPU0_P10_DP")
	)
	(segment
		(start 332.452472 -296.61231)
		(end 332.452472 -296.59326)
		(width 0.0762)
		(layer "B.Cu")
		(net "USB2_CPU0_P10_DP")
	)
	(segment
		(start 310.02097 -194.98183)
		(end 309.601362 -195.401438)
		(width 0.12954)
		(layer "B.Cu")
		(net "USB2_CPU0_P10_DP")
	)
	(segment
		(start 332.386432 -296.52722)
		(end 332.386432 -295.955974)
		(width 0.0762)
		(layer "B.Cu")
		(net "USB2_CPU0_P10_DP")
	)
	(segment
		(start 332.604618 -295.685972)
		(end 332.761082 -295.955974)
		(width 0.0762)
		(layer "B.Cu")
		(net "USB2_CPU0_P10_DP")
	)
	(segment
		(start 310.351424 -203.286614)
		(end 310.351424 -203.286868)
		(width 0.12954)
		(layer "B.Cu")
		(net "USB2_CPU0_P10_DP")
	)
	(segment
		(start 223.867472 -188.780674)
		(end 224.24644 -188.705236)
		(width 0.12954)
		(layer "B.Cu")
		(net "USB2_CPU0_P10_DP")
	)
	(segment
		(start 221.78645 -190.619888)
		(end 221.45498 -190.288418)
		(width 0.12954)
		(layer "B.Cu")
		(net "USB2_CPU0_P10_DP")
	)
	(segment
		(start 322.075302 -290.467542)
		(end 323.941694 -294.973502)
		(width 0.12954)
		(layer "B.Cu")
		(net "USB2_CPU0_P10_DP")
	)
	(segment
		(start 309.601362 -199.515476)
		(end 310.12638 -202.15606)
		(width 0.12954)
		(layer "B.Cu")
		(net "USB2_CPU0_P10_DP")
	)
	(segment
		(start 310.02097 -192.531746)
		(end 310.02097 -194.98183)
		(width 0.12954)
		(layer "B.Cu")
		(net "USB2_CPU0_P10_DP")
	)
	(segment
		(start 309.792116 -191.979042)
		(end 310.02097 -192.531746)
		(width 0.12954)
		(layer "B.Cu")
		(net "USB2_CPU0_P10_DP")
	)
	(segment
		(start 266.076176 -185.398918)
		(end 269.136368 -185.458862)
		(width 0.12954)
		(layer "B.Cu")
		(net "USB2_CPU0_P10_DP")
	)
	(segment
		(start 309.601362 -195.401438)
		(end 309.601362 -199.515476)
		(width 0.12954)
		(layer "B.Cu")
		(net "USB2_CPU0_P10_DP")
	)
	(segment
		(start 332.52537 -295.66489)
		(end 332.604618 -295.685972)
		(width 0.0762)
		(layer "B.Cu")
		(net "USB2_CPU0_P10_DP")
	)
	(segment
		(start 310.126634 -202.15606)
		(end 309.977028 -202.380088)
		(width 0.12954)
		(layer "B.Cu")
		(net "USB2_CPU0_P10_DP")
	)
	(segment
		(start 310.277256 -203.890118)
		(end 310.501538 -204.039724)
		(width 0.12954)
		(layer "B.Cu")
		(net "USB2_CPU0_P10_DP")
	)
	(segment
		(start 224.396046 -188.481208)
		(end 235.713524 -186.230006)
		(width 0.12954)
		(layer "B.Cu")
		(net "USB2_CPU0_P10_DP")
	)
	(segment
		(start 309.152036 -191.339216)
		(end 309.792116 -191.979042)
		(width 0.12954)
		(layer "B.Cu")
		(net "USB2_CPU0_P10_DP")
	)
	(segment
		(start 331.84338 -297.538648)
		(end 332.452472 -296.929556)
		(width 0.12954)
		(layer "B.Cu")
		(net "USB2_CPU0_P10_DP")
	)
	(segment
		(start 323.941694 -294.973502)
		(end 326.50684 -297.538648)
		(width 0.12954)
		(layer "B.Cu")
		(net "USB2_CPU0_P10_DP")
	)
	(segment
		(start 332.452472 -296.59326)
		(end 332.386432 -296.52722)
		(width 0.0762)
		(layer "B.Cu")
		(net "USB2_CPU0_P10_DP")
	)
	(segment
		(start 310.12638 -202.15606)
		(end 310.126634 -202.15606)
		(width 0.12954)
		(layer "B.Cu")
		(net "USB2_CPU0_P10_DP")
	)
	(segment
		(start 310.052212 -202.759056)
		(end 310.276494 -202.908662)
		(width 0.12954)
		(layer "B.Cu")
		(net "USB2_CPU0_P10_DP")
	)
	(segment
		(start 253.28118 -186.230006)
		(end 266.076176 -185.398918)
		(width 0.12954)
		(layer "B.Cu")
		(net "USB2_CPU0_P10_DP")
	)
	(segment
		(start 221.45498 -190.288418)
		(end 221.45498 -190.042292)
		(width 0.12954)
		(layer "B.Cu")
		(net "USB2_CPU0_P10_DP")
	)
	(segment
		(start 320.123058 -252.4125)
		(end 322.075302 -257.542538)
		(width 0.12954)
		(layer "B.Cu")
		(net "USB2_CPU0_P10_DP")
	)
	(arc
		(start 332.386432 -295.955974)
		(mid 332.422929 -295.794682)
		(end 332.52537 -295.66489)
		(width 0.0762)
		(layer "B.Cu")
		(net "USB2_CPU0_P10_DP")
	)
	(segment
		(start 13.20165 -16.546322)
		(end 13.20165 -16.145764)
		(width 0.12954)
		(layer "F.Cu")
		(net "USB2_CPU0_P10_DN")
	)
	(segment
		(start 221.076012 -180.908706)
		(end 213.196678 -161.886646)
		(width 0.12954)
		(layer "F.Cu")
		(net "USB2_CPU0_P10_DN")
	)
	(segment
		(start 13.34897 -16.901922)
		(end 13.20165 -16.546322)
		(width 0.12954)
		(layer "F.Cu")
		(net "USB2_CPU0_P10_DN")
	)
	(segment
		(start 220.79585 -190.619888)
		(end 221.118684 -190.297054)
		(width 0.12954)
		(layer "F.Cu")
		(net "USB2_CPU0_P10_DN")
	)
	(segment
		(start 14.534388 -18.676112)
		(end 13.34897 -16.901922)
		(width 0.12954)
		(layer "F.Cu")
		(net "USB2_CPU0_P10_DN")
	)
	(segment
		(start 332.758034 -294.88003)
		(end 332.291182 -295.145968)
		(width 0.12954)
		(layer "F.Cu")
		(net "USB2_CPU0_P10_DN")
	)
	(segment
		(start 201.228452 -149.918166)
		(end 194.246754 -147.02663)
		(width 0.12954)
		(layer "F.Cu")
		(net "USB2_CPU0_P10_DN")
	)
	(segment
		(start 171.729654 -140.932916)
		(end 166.146226 -135.349742)
		(width 0.12954)
		(layer "F.Cu")
		(net "USB2_CPU0_P10_DN")
	)
	(segment
		(start 166.146226 -135.349742)
		(end 139.961112 -124.503688)
		(width 0.12954)
		(layer "F.Cu")
		(net "USB2_CPU0_P10_DN")
	)
	(segment
		(start 13.20165 -16.145764)
		(end 12.777216 -15.72133)
		(width 0.12954)
		(layer "F.Cu")
		(net "USB2_CPU0_P10_DN")
	)
	(segment
		(start 221.118684 -181.194202)
		(end 221.076012 -180.908706)
		(width 0.12954)
		(layer "F.Cu")
		(net "USB2_CPU0_P10_DN")
	)
	(segment
		(start 185.501788 -145.286984)
		(end 182.239412 -145.286984)
		(width 0.12954)
		(layer "F.Cu")
		(net "USB2_CPU0_P10_DN")
	)
	(segment
		(start 221.118684 -190.297054)
		(end 221.118684 -181.194202)
		(width 0.12954)
		(layer "F.Cu")
		(net "USB2_CPU0_P10_DN")
	)
	(segment
		(start 14.905228 -19.569684)
		(end 14.534388 -18.676112)
		(width 0.12954)
		(layer "F.Cu")
		(net "USB2_CPU0_P10_DN")
	)
	(segment
		(start 213.196678 -161.886646)
		(end 201.228452 -149.918166)
		(width 0.12954)
		(layer "F.Cu")
		(net "USB2_CPU0_P10_DN")
	)
	(segment
		(start 194.246754 -147.02663)
		(end 185.501788 -145.286984)
		(width 0.12954)
		(layer "F.Cu")
		(net "USB2_CPU0_P10_DN")
	)
	(segment
		(start 182.239412 -145.286984)
		(end 171.729654 -140.932916)
		(width 0.12954)
		(layer "F.Cu")
		(net "USB2_CPU0_P10_DN")
	)
	(segment
		(start 139.961112 -124.503688)
		(end 14.905228 -19.569684)
		(width 0.12954)
		(layer "F.Cu")
		(net "USB2_CPU0_P10_DN")
	)
	(via
		(at 220.79585 -190.619888)
		(size 0.508)
		(drill 0.254)
		(layers "F.Cu" "B.Cu")
		(net "USB2_CPU0_P10_DN")
	)
	(via
		(at 332.291182 -295.145968)
		(size 0.4064)
		(drill 0.2032)
		(layers "F.Cu" "B.Cu")
		(net "USB2_CPU0_P10_DN")
	)
	(segment
		(start 222.233998 -188.5823)
		(end 235.68152 -185.907426)
		(width 0.12954)
		(layer "B.Cu")
		(net "USB2_CPU0_P10_DN")
	)
	(segment
		(start 322.8975 -291.144452)
		(end 323.046344 -291.503608)
		(width 0.12954)
		(layer "B.Cu")
		(net "USB2_CPU0_P10_DN")
	)
	(segment
		(start 308.257448 -190.61938)
		(end 309.334916 -191.065404)
		(width 0.12954)
		(layer "B.Cu")
		(net "USB2_CPU0_P10_DN")
	)
	(segment
		(start 322.397882 -290.40328)
		(end 322.664836 -291.048186)
		(width 0.12954)
		(layer "B.Cu")
		(net "USB2_CPU0_P10_DN")
	)
	(segment
		(start 322.397882 -289.449256)
		(end 322.397882 -290.40328)
		(width 0.12954)
		(layer "B.Cu")
		(net "USB2_CPU0_P10_DN")
	)
	(segment
		(start 221.1324 -189.926976)
		(end 222.233998 -188.5823)
		(width 0.12954)
		(layer "B.Cu")
		(net "USB2_CPU0_P10_DN")
	)
	(segment
		(start 332.129892 -296.59326)
		(end 332.195932 -296.52722)
		(width 0.0762)
		(layer "B.Cu")
		(net "USB2_CPU0_P10_DN")
	)
	(segment
		(start 253.270512 -185.907426)
		(end 266.06881 -185.076084)
		(width 0.12954)
		(layer "B.Cu")
		(net "USB2_CPU0_P10_DN")
	)
	(segment
		(start 322.397882 -288.705036)
		(end 322.575682 -288.882836)
		(width 0.12954)
		(layer "B.Cu")
		(net "USB2_CPU0_P10_DN")
	)
	(segment
		(start 309.334916 -191.065404)
		(end 310.065674 -191.796416)
		(width 0.12954)
		(layer "B.Cu")
		(net "USB2_CPU0_P10_DN")
	)
	(segment
		(start 309.923942 -195.535296)
		(end 309.923942 -199.483472)
		(width 0.12954)
		(layer "B.Cu")
		(net "USB2_CPU0_P10_DN")
	)
	(segment
		(start 320.434208 -252.323092)
		(end 322.397882 -257.483102)
		(width 0.12954)
		(layer "B.Cu")
		(net "USB2_CPU0_P10_DN")
	)
	(segment
		(start 332.447646 -295.41597)
		(end 332.291182 -295.145968)
		(width 0.0762)
		(layer "B.Cu")
		(net "USB2_CPU0_P10_DN")
	)
	(segment
		(start 271.449546 -185.706004)
		(end 272.171414 -186.466226)
		(width 0.12954)
		(layer "B.Cu")
		(net "USB2_CPU0_P10_DN")
	)
	(segment
		(start 310.065674 -191.796416)
		(end 310.34355 -192.467484)
		(width 0.12954)
		(layer "B.Cu")
		(net "USB2_CPU0_P10_DN")
	)
	(segment
		(start 332.195932 -296.52722)
		(end 332.195932 -295.956228)
		(width 0.0762)
		(layer "B.Cu")
		(net "USB2_CPU0_P10_DN")
	)
	(segment
		(start 332.129892 -296.61231)
		(end 332.129892 -296.59326)
		(width 0.0762)
		(layer "B.Cu")
		(net "USB2_CPU0_P10_DN")
	)
	(segment
		(start 221.1324 -190.283338)
		(end 221.1324 -189.926976)
		(width 0.12954)
		(layer "B.Cu")
		(net "USB2_CPU0_P10_DN")
	)
	(segment
		(start 332.195932 -295.956228)
		(end 332.195678 -295.955974)
		(width 0.0762)
		(layer "B.Cu")
		(net "USB2_CPU0_P10_DN")
	)
	(segment
		(start 322.664836 -291.048186)
		(end 322.8975 -291.144452)
		(width 0.12954)
		(layer "B.Cu")
		(net "USB2_CPU0_P10_DN")
	)
	(segment
		(start 235.68152 -185.907426)
		(end 253.270512 -185.907426)
		(width 0.12954)
		(layer "B.Cu")
		(net "USB2_CPU0_P10_DN")
	)
	(segment
		(start 266.06881 -185.076084)
		(end 269.179294 -185.137044)
		(width 0.12954)
		(layer "B.Cu")
		(net "USB2_CPU0_P10_DN")
	)
	(segment
		(start 310.34355 -195.115688)
		(end 309.923942 -195.535296)
		(width 0.12954)
		(layer "B.Cu")
		(net "USB2_CPU0_P10_DN")
	)
	(segment
		(start 269.179294 -185.137044)
		(end 271.449546 -185.706004)
		(width 0.12954)
		(layer "B.Cu")
		(net "USB2_CPU0_P10_DN")
	)
	(segment
		(start 274.644866 -188.362082)
		(end 296.909998 -188.362082)
		(width 0.12954)
		(layer "B.Cu")
		(net "USB2_CPU0_P10_DN")
	)
	(segment
		(start 326.640698 -297.216068)
		(end 331.709522 -297.216068)
		(width 0.12954)
		(layer "B.Cu")
		(net "USB2_CPU0_P10_DN")
	)
	(segment
		(start 322.397882 -257.483102)
		(end 322.397882 -288.705036)
		(width 0.12954)
		(layer "B.Cu")
		(net "USB2_CPU0_P10_DN")
	)
	(segment
		(start 296.909998 -188.362082)
		(end 308.257448 -190.61938)
		(width 0.12954)
		(layer "B.Cu")
		(net "USB2_CPU0_P10_DN")
	)
	(segment
		(start 309.923942 -199.483472)
		(end 320.434208 -252.323092)
		(width 0.12954)
		(layer "B.Cu")
		(net "USB2_CPU0_P10_DN")
	)
	(segment
		(start 332.424786 -295.501314)
		(end 332.447646 -295.41597)
		(width 0.0762)
		(layer "B.Cu")
		(net "USB2_CPU0_P10_DN")
	)
	(segment
		(start 323.046344 -291.503608)
		(end 322.950078 -291.736018)
		(width 0.12954)
		(layer "B.Cu")
		(net "USB2_CPU0_P10_DN")
	)
	(segment
		(start 322.950078 -291.736018)
		(end 324.215252 -294.790622)
		(width 0.12954)
		(layer "B.Cu")
		(net "USB2_CPU0_P10_DN")
	)
	(segment
		(start 322.575682 -288.882836)
		(end 322.575682 -289.271456)
		(width 0.12954)
		(layer "B.Cu")
		(net "USB2_CPU0_P10_DN")
	)
	(segment
		(start 272.171414 -186.466226)
		(end 274.644866 -188.362082)
		(width 0.12954)
		(layer "B.Cu")
		(net "USB2_CPU0_P10_DN")
	)
	(segment
		(start 220.79585 -190.619888)
		(end 221.1324 -190.283338)
		(width 0.12954)
		(layer "B.Cu")
		(net "USB2_CPU0_P10_DN")
	)
	(segment
		(start 331.709522 -297.216068)
		(end 332.129892 -296.795698)
		(width 0.12954)
		(layer "B.Cu")
		(net "USB2_CPU0_P10_DN")
	)
	(segment
		(start 310.34355 -192.467484)
		(end 310.34355 -195.115688)
		(width 0.12954)
		(layer "B.Cu")
		(net "USB2_CPU0_P10_DN")
	)
	(segment
		(start 332.129892 -296.795698)
		(end 332.129892 -296.61231)
		(width 0.12954)
		(layer "B.Cu")
		(net "USB2_CPU0_P10_DN")
	)
	(segment
		(start 324.215252 -294.790622)
		(end 326.640698 -297.216068)
		(width 0.12954)
		(layer "B.Cu")
		(net "USB2_CPU0_P10_DN")
	)
	(segment
		(start 322.575682 -289.271456)
		(end 322.397882 -289.449256)
		(width 0.12954)
		(layer "B.Cu")
		(net "USB2_CPU0_P10_DN")
	)
	(arc
		(start 332.195678 -295.955974)
		(mid 332.250754 -295.712568)
		(end 332.405228 -295.516554)
		(width 0.0762)
		(layer "B.Cu")
		(net "USB2_CPU0_P10_DN")
	)
	(arc
		(start 332.405228 -295.516554)
		(mid 332.414924 -295.508827)
		(end 332.424786 -295.501314)
		(width 0.0762)
		(layer "B.Cu")
		(net "USB2_CPU0_P10_DN")
	)
	(segment
		(start 130.49758 -27.25928)
		(end 130.6322 -27.25928)
		(width 0.12954)
		(layer "F.Cu")
		(net "USB2_CPU0_P0_DP")
	)
	(segment
		(start 370.527834 -222.070168)
		(end 370.994686 -221.80423)
		(width 0.12954)
		(layer "F.Cu")
		(net "USB2_CPU0_P0_DP")
	)
	(segment
		(start 131.06908 -27.69616)
		(end 131.06908 -27.75458)
		(width 0.12954)
		(layer "F.Cu")
		(net "USB2_CPU0_P0_DP")
	)
	(segment
		(start 130.6322 -27.25928)
		(end 131.06908 -27.69616)
		(width 0.12954)
		(layer "F.Cu")
		(net "USB2_CPU0_P0_DP")
	)
	(via
		(at 370.994686 -221.80423)
		(size 0.4064)
		(drill 0.2032)
		(layers "F.Cu" "B.Cu")
		(net "USB2_CPU0_P0_DP")
	)
	(via
		(at 131.06908 -27.75458)
		(size 0.508)
		(drill 0.254)
		(layers "F.Cu" "B.Cu")
		(net "USB2_CPU0_P0_DP")
	)
	(segment
		(start 182.782464 -52.187348)
		(end 185.9153 -53.485034)
		(width 0.12954)
		(layer "B.Cu")
		(net "USB2_CPU0_P0_DP")
	)
	(segment
		(start 142.360396 -21.810218)
		(end 142.6337 -22.083522)
		(width 0.12954)
		(layer "B.Cu")
		(net "USB2_CPU0_P0_DP")
	)
	(segment
		(start 208.8642 -64.379348)
		(end 212.78469 -65.159128)
		(width 0.12954)
		(layer "B.Cu")
		(net "USB2_CPU0_P0_DP")
	)
	(segment
		(start 142.360396 -21.540724)
		(end 142.360396 -21.810218)
		(width 0.12954)
		(layer "B.Cu")
		(net "USB2_CPU0_P0_DP")
	)
	(segment
		(start 371.30355 -221.311978)
		(end 371.30355 -221.495366)
		(width 0.12954)
		(layer "B.Cu")
		(net "USB2_CPU0_P0_DP")
	)
	(segment
		(start 136.22274 -20.057618)
		(end 136.22274 -16.91894)
		(width 0.12954)
		(layer "B.Cu")
		(net "USB2_CPU0_P0_DP")
	)
	(segment
		(start 322.899024 -181.563772)
		(end 357.423974 -216.088722)
		(width 0.12954)
		(layer "B.Cu")
		(net "USB2_CPU0_P0_DP")
	)
	(segment
		(start 367.82756 -217.835988)
		(end 371.30355 -221.311978)
		(width 0.12954)
		(layer "B.Cu")
		(net "USB2_CPU0_P0_DP")
	)
	(segment
		(start 301.757842 -172.806614)
		(end 322.899024 -181.563772)
		(width 0.12954)
		(layer "B.Cu")
		(net "USB2_CPU0_P0_DP")
	)
	(segment
		(start 139.51712 -18.462498)
		(end 140.272516 -19.217894)
		(width 0.12954)
		(layer "B.Cu")
		(net "USB2_CPU0_P0_DP")
	)
	(segment
		(start 198.498206 -61.892688)
		(end 204.50175 -64.379348)
		(width 0.12954)
		(layer "B.Cu")
		(net "USB2_CPU0_P0_DP")
	)
	(segment
		(start 366.1283 -218.021408)
		(end 366.31372 -217.835988)
		(width 0.12954)
		(layer "B.Cu")
		(net "USB2_CPU0_P0_DP")
	)
	(segment
		(start 177.086768 -50.663348)
		(end 179.324 -50.663348)
		(width 0.12954)
		(layer "B.Cu")
		(net "USB2_CPU0_P0_DP")
	)
	(segment
		(start 139.324842 -16.7894)
		(end 139.51712 -16.981678)
		(width 0.12954)
		(layer "B.Cu")
		(net "USB2_CPU0_P0_DP")
	)
	(segment
		(start 222.210122 -74.17308)
		(end 223.81718 -75.780138)
		(width 0.12954)
		(layer "B.Cu")
		(net "USB2_CPU0_P0_DP")
	)
	(segment
		(start 136.22274 -16.91894)
		(end 136.35228 -16.7894)
		(width 0.12954)
		(layer "B.Cu")
		(net "USB2_CPU0_P0_DP")
	)
	(segment
		(start 220.9165 -73.362058)
		(end 221.727522 -74.17308)
		(width 0.12954)
		(layer "B.Cu")
		(net "USB2_CPU0_P0_DP")
	)
	(segment
		(start 219.398342 -65.159128)
		(end 221.248986 -67.009772)
		(width 0.12954)
		(layer "B.Cu")
		(net "USB2_CPU0_P0_DP")
	)
	(segment
		(start 185.9153 -53.485034)
		(end 198.498206 -61.892688)
		(width 0.12954)
		(layer "B.Cu")
		(net "USB2_CPU0_P0_DP")
	)
	(segment
		(start 223.81718 -87.922354)
		(end 241.637312 -130.944112)
		(width 0.12954)
		(layer "B.Cu")
		(net "USB2_CPU0_P0_DP")
	)
	(segment
		(start 204.50175 -64.379348)
		(end 208.8642 -64.379348)
		(width 0.12954)
		(layer "B.Cu")
		(net "USB2_CPU0_P0_DP")
	)
	(segment
		(start 220.9165 -70.57644)
		(end 220.9165 -73.362058)
		(width 0.12954)
		(layer "B.Cu")
		(net "USB2_CPU0_P0_DP")
	)
	(segment
		(start 142.6337 -22.083522)
		(end 142.903194 -22.083522)
		(width 0.12954)
		(layer "B.Cu")
		(net "USB2_CPU0_P0_DP")
	)
	(segment
		(start 131.40309 -27.42057)
		(end 133.807708 -27.42057)
		(width 0.12954)
		(layer "B.Cu")
		(net "USB2_CPU0_P0_DP")
	)
	(segment
		(start 288.596324 -170.188636)
		(end 301.757842 -172.806614)
		(width 0.12954)
		(layer "B.Cu")
		(net "USB2_CPU0_P0_DP")
	)
	(segment
		(start 166.159434 -39.736014)
		(end 177.086768 -50.663348)
		(width 0.12954)
		(layer "B.Cu")
		(net "USB2_CPU0_P0_DP")
	)
	(segment
		(start 136.35228 -16.7894)
		(end 139.324842 -16.7894)
		(width 0.12954)
		(layer "B.Cu")
		(net "USB2_CPU0_P0_DP")
	)
	(segment
		(start 135.31088 -25.917398)
		(end 135.31088 -20.969478)
		(width 0.12954)
		(layer "B.Cu")
		(net "USB2_CPU0_P0_DP")
	)
	(segment
		(start 221.248986 -67.009772)
		(end 221.248986 -70.243954)
		(width 0.12954)
		(layer "B.Cu")
		(net "USB2_CPU0_P0_DP")
	)
	(segment
		(start 141.655546 -19.217894)
		(end 142.0876 -19.649948)
		(width 0.12954)
		(layer "B.Cu")
		(net "USB2_CPU0_P0_DP")
	)
	(segment
		(start 221.248986 -70.243954)
		(end 220.9165 -70.57644)
		(width 0.12954)
		(layer "B.Cu")
		(net "USB2_CPU0_P0_DP")
	)
	(segment
		(start 133.807708 -27.42057)
		(end 135.31088 -25.917398)
		(width 0.12954)
		(layer "B.Cu")
		(net "USB2_CPU0_P0_DP")
	)
	(segment
		(start 361.642406 -217.835988)
		(end 364.42904 -217.835988)
		(width 0.12954)
		(layer "B.Cu")
		(net "USB2_CPU0_P0_DP")
	)
	(segment
		(start 142.0876 -19.649948)
		(end 142.0876 -21.267928)
		(width 0.12954)
		(layer "B.Cu")
		(net "USB2_CPU0_P0_DP")
	)
	(segment
		(start 241.637312 -130.944112)
		(end 272.023586 -161.330386)
		(width 0.12954)
		(layer "B.Cu")
		(net "USB2_CPU0_P0_DP")
	)
	(segment
		(start 139.51712 -16.981678)
		(end 139.51712 -18.462498)
		(width 0.12954)
		(layer "B.Cu")
		(net "USB2_CPU0_P0_DP")
	)
	(segment
		(start 142.903194 -22.083522)
		(end 149.271228 -28.451556)
		(width 0.12954)
		(layer "B.Cu")
		(net "USB2_CPU0_P0_DP")
	)
	(segment
		(start 149.271228 -28.451556)
		(end 166.159434 -39.736014)
		(width 0.12954)
		(layer "B.Cu")
		(net "USB2_CPU0_P0_DP")
	)
	(segment
		(start 364.99546 -218.021408)
		(end 365.18088 -217.835988)
		(width 0.12954)
		(layer "B.Cu")
		(net "USB2_CPU0_P0_DP")
	)
	(segment
		(start 367.26114 -218.021408)
		(end 367.44656 -217.835988)
		(width 0.12954)
		(layer "B.Cu")
		(net "USB2_CPU0_P0_DP")
	)
	(segment
		(start 357.423974 -216.088722)
		(end 361.642406 -217.835988)
		(width 0.12954)
		(layer "B.Cu")
		(net "USB2_CPU0_P0_DP")
	)
	(segment
		(start 365.56188 -217.835988)
		(end 365.7473 -218.021408)
		(width 0.12954)
		(layer "B.Cu")
		(net "USB2_CPU0_P0_DP")
	)
	(segment
		(start 371.30355 -221.495366)
		(end 370.994686 -221.80423)
		(width 0.12954)
		(layer "B.Cu")
		(net "USB2_CPU0_P0_DP")
	)
	(segment
		(start 366.69472 -217.835988)
		(end 366.88014 -218.021408)
		(width 0.12954)
		(layer "B.Cu")
		(net "USB2_CPU0_P0_DP")
	)
	(segment
		(start 223.81718 -75.780138)
		(end 223.81718 -87.922354)
		(width 0.12954)
		(layer "B.Cu")
		(net "USB2_CPU0_P0_DP")
	)
	(segment
		(start 365.7473 -218.021408)
		(end 366.1283 -218.021408)
		(width 0.12954)
		(layer "B.Cu")
		(net "USB2_CPU0_P0_DP")
	)
	(segment
		(start 367.44656 -217.835988)
		(end 367.82756 -217.835988)
		(width 0.12954)
		(layer "B.Cu")
		(net "USB2_CPU0_P0_DP")
	)
	(segment
		(start 131.06908 -27.75458)
		(end 131.40309 -27.42057)
		(width 0.12954)
		(layer "B.Cu")
		(net "USB2_CPU0_P0_DP")
	)
	(segment
		(start 142.0876 -21.267928)
		(end 142.360396 -21.540724)
		(width 0.12954)
		(layer "B.Cu")
		(net "USB2_CPU0_P0_DP")
	)
	(segment
		(start 179.324 -50.663348)
		(end 180.848 -52.187348)
		(width 0.12954)
		(layer "B.Cu")
		(net "USB2_CPU0_P0_DP")
	)
	(segment
		(start 364.42904 -217.835988)
		(end 364.61446 -218.021408)
		(width 0.12954)
		(layer "B.Cu")
		(net "USB2_CPU0_P0_DP")
	)
	(segment
		(start 135.31088 -20.969478)
		(end 136.22274 -20.057618)
		(width 0.12954)
		(layer "B.Cu")
		(net "USB2_CPU0_P0_DP")
	)
	(segment
		(start 221.727522 -74.17308)
		(end 222.210122 -74.17308)
		(width 0.12954)
		(layer "B.Cu")
		(net "USB2_CPU0_P0_DP")
	)
	(segment
		(start 364.61446 -218.021408)
		(end 364.99546 -218.021408)
		(width 0.12954)
		(layer "B.Cu")
		(net "USB2_CPU0_P0_DP")
	)
	(segment
		(start 365.18088 -217.835988)
		(end 365.56188 -217.835988)
		(width 0.12954)
		(layer "B.Cu")
		(net "USB2_CPU0_P0_DP")
	)
	(segment
		(start 272.023586 -161.330386)
		(end 288.596324 -170.188636)
		(width 0.12954)
		(layer "B.Cu")
		(net "USB2_CPU0_P0_DP")
	)
	(segment
		(start 366.31372 -217.835988)
		(end 366.69472 -217.835988)
		(width 0.12954)
		(layer "B.Cu")
		(net "USB2_CPU0_P0_DP")
	)
	(segment
		(start 212.78469 -65.159128)
		(end 219.398342 -65.159128)
		(width 0.12954)
		(layer "B.Cu")
		(net "USB2_CPU0_P0_DP")
	)
	(segment
		(start 140.272516 -19.217894)
		(end 141.655546 -19.217894)
		(width 0.12954)
		(layer "B.Cu")
		(net "USB2_CPU0_P0_DP")
	)
	(segment
		(start 366.88014 -218.021408)
		(end 367.26114 -218.021408)
		(width 0.12954)
		(layer "B.Cu")
		(net "USB2_CPU0_P0_DP")
	)
	(segment
		(start 180.848 -52.187348)
		(end 182.782464 -52.187348)
		(width 0.12954)
		(layer "B.Cu")
		(net "USB2_CPU0_P0_DP")
	)
	(segment
		(start 131.51358 -27.25928)
		(end 131.06908 -26.81478)
		(width 0.12954)
		(layer "F.Cu")
		(net "USB2_CPU0_P0_DN")
	)
	(segment
		(start 131.06908 -26.81478)
		(end 131.06908 -26.76398)
		(width 0.12954)
		(layer "F.Cu")
		(net "USB2_CPU0_P0_DN")
	)
	(segment
		(start 131.64058 -27.25928)
		(end 131.51358 -27.25928)
		(width 0.12954)
		(layer "F.Cu")
		(net "USB2_CPU0_P0_DN")
	)
	(segment
		(start 371.467888 -222.070168)
		(end 371.93474 -221.80423)
		(width 0.12954)
		(layer "F.Cu")
		(net "USB2_CPU0_P0_DN")
	)
	(via
		(at 131.06908 -26.76398)
		(size 0.508)
		(drill 0.254)
		(layers "F.Cu" "B.Cu")
		(net "USB2_CPU0_P0_DN")
	)
	(via
		(at 371.93474 -221.80423)
		(size 0.4064)
		(drill 0.2032)
		(layers "F.Cu" "B.Cu")
		(net "USB2_CPU0_P0_DN")
	)
	(segment
		(start 139.4587 -16.46682)
		(end 136.218422 -16.46682)
		(width 0.12954)
		(layer "B.Cu")
		(net "USB2_CPU0_P0_DN")
	)
	(segment
		(start 221.86138 -73.8505)
		(end 221.23908 -73.2282)
		(width 0.12954)
		(layer "B.Cu")
		(net "USB2_CPU0_P0_DN")
	)
	(segment
		(start 182.846726 -51.864768)
		(end 180.981858 -51.864768)
		(width 0.12954)
		(layer "B.Cu")
		(net "USB2_CPU0_P0_DN")
	)
	(segment
		(start 221.571566 -66.875914)
		(end 219.5322 -64.836548)
		(width 0.12954)
		(layer "B.Cu")
		(net "USB2_CPU0_P0_DN")
	)
	(segment
		(start 140.406374 -18.895314)
		(end 139.8397 -18.32864)
		(width 0.12954)
		(layer "B.Cu")
		(net "USB2_CPU0_P0_DN")
	)
	(segment
		(start 221.23908 -70.710298)
		(end 221.571566 -70.377812)
		(width 0.12954)
		(layer "B.Cu")
		(net "USB2_CPU0_P0_DN")
	)
	(segment
		(start 142.41018 -21.13407)
		(end 142.41018 -19.51609)
		(width 0.12954)
		(layer "B.Cu")
		(net "USB2_CPU0_P0_DN")
	)
	(segment
		(start 177.220626 -50.340768)
		(end 166.365174 -39.485316)
		(width 0.12954)
		(layer "B.Cu")
		(net "USB2_CPU0_P0_DN")
	)
	(segment
		(start 134.9883 -25.78354)
		(end 133.67385 -27.09799)
		(width 0.12954)
		(layer "B.Cu")
		(net "USB2_CPU0_P0_DN")
	)
	(segment
		(start 135.90016 -16.785082)
		(end 135.90016 -19.92376)
		(width 0.12954)
		(layer "B.Cu")
		(net "USB2_CPU0_P0_DN")
	)
	(segment
		(start 371.93474 -221.80423)
		(end 371.62613 -221.49562)
		(width 0.12954)
		(layer "B.Cu")
		(net "USB2_CPU0_P0_DN")
	)
	(segment
		(start 272.217896 -161.068258)
		(end 241.91087 -130.761232)
		(width 0.12954)
		(layer "B.Cu")
		(net "USB2_CPU0_P0_DN")
	)
	(segment
		(start 224.13976 -75.64628)
		(end 222.34398 -73.8505)
		(width 0.12954)
		(layer "B.Cu")
		(net "USB2_CPU0_P0_DN")
	)
	(segment
		(start 241.91087 -130.761232)
		(end 224.13976 -87.858092)
		(width 0.12954)
		(layer "B.Cu")
		(net "USB2_CPU0_P0_DN")
	)
	(segment
		(start 142.41018 -19.51609)
		(end 141.789404 -18.895314)
		(width 0.12954)
		(layer "B.Cu")
		(net "USB2_CPU0_P0_DN")
	)
	(segment
		(start 136.218422 -16.46682)
		(end 135.90016 -16.785082)
		(width 0.12954)
		(layer "B.Cu")
		(net "USB2_CPU0_P0_DN")
	)
	(segment
		(start 221.571566 -70.377812)
		(end 221.571566 -66.875914)
		(width 0.12954)
		(layer "B.Cu")
		(net "USB2_CPU0_P0_DN")
	)
	(segment
		(start 357.606854 -215.815164)
		(end 323.081904 -181.290214)
		(width 0.12954)
		(layer "B.Cu")
		(net "USB2_CPU0_P0_DN")
	)
	(segment
		(start 180.981858 -51.864768)
		(end 179.457858 -50.340768)
		(width 0.12954)
		(layer "B.Cu")
		(net "USB2_CPU0_P0_DN")
	)
	(segment
		(start 367.961418 -217.513408)
		(end 361.706668 -217.513408)
		(width 0.12954)
		(layer "B.Cu")
		(net "USB2_CPU0_P0_DN")
	)
	(segment
		(start 198.651114 -61.606684)
		(end 186.068208 -53.19903)
		(width 0.12954)
		(layer "B.Cu")
		(net "USB2_CPU0_P0_DN")
	)
	(segment
		(start 361.706668 -217.513408)
		(end 357.606854 -215.815164)
		(width 0.12954)
		(layer "B.Cu")
		(net "USB2_CPU0_P0_DN")
	)
	(segment
		(start 301.852076 -172.496226)
		(end 288.706306 -169.88155)
		(width 0.12954)
		(layer "B.Cu")
		(net "USB2_CPU0_P0_DN")
	)
	(segment
		(start 149.476968 -28.200858)
		(end 142.41018 -21.13407)
		(width 0.12954)
		(layer "B.Cu")
		(net "USB2_CPU0_P0_DN")
	)
	(segment
		(start 204.566012 -64.056768)
		(end 198.651114 -61.606684)
		(width 0.12954)
		(layer "B.Cu")
		(net "USB2_CPU0_P0_DN")
	)
	(segment
		(start 186.068208 -53.19903)
		(end 182.846726 -51.864768)
		(width 0.12954)
		(layer "B.Cu")
		(net "USB2_CPU0_P0_DN")
	)
	(segment
		(start 179.457858 -50.340768)
		(end 177.220626 -50.340768)
		(width 0.12954)
		(layer "B.Cu")
		(net "USB2_CPU0_P0_DN")
	)
	(segment
		(start 371.62613 -221.17812)
		(end 367.961418 -217.513408)
		(width 0.12954)
		(layer "B.Cu")
		(net "USB2_CPU0_P0_DN")
	)
	(segment
		(start 221.23908 -73.2282)
		(end 221.23908 -70.710298)
		(width 0.12954)
		(layer "B.Cu")
		(net "USB2_CPU0_P0_DN")
	)
	(segment
		(start 134.9883 -20.83562)
		(end 134.9883 -25.78354)
		(width 0.12954)
		(layer "B.Cu")
		(net "USB2_CPU0_P0_DN")
	)
	(segment
		(start 141.789404 -18.895314)
		(end 140.406374 -18.895314)
		(width 0.12954)
		(layer "B.Cu")
		(net "USB2_CPU0_P0_DN")
	)
	(segment
		(start 135.90016 -19.92376)
		(end 134.9883 -20.83562)
		(width 0.12954)
		(layer "B.Cu")
		(net "USB2_CPU0_P0_DN")
	)
	(segment
		(start 323.081904 -181.290214)
		(end 301.852076 -172.496226)
		(width 0.12954)
		(layer "B.Cu")
		(net "USB2_CPU0_P0_DN")
	)
	(segment
		(start 166.365174 -39.485316)
		(end 149.476968 -28.200858)
		(width 0.12954)
		(layer "B.Cu")
		(net "USB2_CPU0_P0_DN")
	)
	(segment
		(start 212.816948 -64.836548)
		(end 212.816694 -64.836294)
		(width 0.12954)
		(layer "B.Cu")
		(net "USB2_CPU0_P0_DN")
	)
	(segment
		(start 371.62613 -221.49562)
		(end 371.62613 -221.17812)
		(width 0.12954)
		(layer "B.Cu")
		(net "USB2_CPU0_P0_DN")
	)
	(segment
		(start 139.8397 -16.84782)
		(end 139.4587 -16.46682)
		(width 0.12954)
		(layer "B.Cu")
		(net "USB2_CPU0_P0_DN")
	)
	(segment
		(start 288.706306 -169.88155)
		(end 272.217896 -161.068258)
		(width 0.12954)
		(layer "B.Cu")
		(net "USB2_CPU0_P0_DN")
	)
	(segment
		(start 212.816694 -64.836294)
		(end 208.896204 -64.056768)
		(width 0.12954)
		(layer "B.Cu")
		(net "USB2_CPU0_P0_DN")
	)
	(segment
		(start 139.8397 -18.32864)
		(end 139.8397 -16.84782)
		(width 0.12954)
		(layer "B.Cu")
		(net "USB2_CPU0_P0_DN")
	)
	(segment
		(start 133.67385 -27.09799)
		(end 131.40309 -27.09799)
		(width 0.12954)
		(layer "B.Cu")
		(net "USB2_CPU0_P0_DN")
	)
	(segment
		(start 219.5322 -64.836548)
		(end 212.816948 -64.836548)
		(width 0.12954)
		(layer "B.Cu")
		(net "USB2_CPU0_P0_DN")
	)
	(segment
		(start 224.13976 -87.858092)
		(end 224.13976 -75.64628)
		(width 0.12954)
		(layer "B.Cu")
		(net "USB2_CPU0_P0_DN")
	)
	(segment
		(start 131.40309 -27.09799)
		(end 131.06908 -26.76398)
		(width 0.12954)
		(layer "B.Cu")
		(net "USB2_CPU0_P0_DN")
	)
	(segment
		(start 208.896204 -64.056768)
		(end 204.566012 -64.056768)
		(width 0.12954)
		(layer "B.Cu")
		(net "USB2_CPU0_P0_DN")
	)
	(segment
		(start 222.34398 -73.8505)
		(end 221.86138 -73.8505)
		(width 0.12954)
		(layer "B.Cu")
		(net "USB2_CPU0_P0_DN")
	)
	(segment
		(start 186.53252 -19.035522)
		(end 187.163456 -19.035522)
		(width 0.10668)
		(layer "F.Cu")
		(net "UART_CPU0_SCM_LVC3_UART1_RX")
	)
	(segment
		(start 186.861958 -18.52295)
		(end 187.163456 -18.824448)
		(width 0.10668)
		(layer "F.Cu")
		(net "UART_CPU0_SCM_LVC3_UART1_RX")
	)
	(segment
		(start 186.861958 -16.549878)
		(end 186.861958 -18.52295)
		(width 0.10668)
		(layer "F.Cu")
		(net "UART_CPU0_SCM_LVC3_UART1_RX")
	)
	(segment
		(start 187.163456 -18.824448)
		(end 187.163456 -19.035522)
		(width 0.10668)
		(layer "F.Cu")
		(net "UART_CPU0_SCM_LVC3_UART1_RX")
	)
	(via
		(at 187.163456 -19.035522)
		(size 0.508)
		(drill 0.254)
		(layers "F.Cu" "B.Cu")
		(net "UART_CPU0_SCM_LVC3_UART1_RX")
	)
	(segment
		(start 17.215358 -6.491986)
		(end 17.485614 -6.762242)
		(width 0.12954)
		(layer "F.Cu")
		(net "USB2_P10_DP")
	)
	(segment
		(start 14.678914 -11.484356)
		(end 14.95171 -11.21156)
		(width 0.12954)
		(layer "F.Cu")
		(net "USB2_P10_DP")
	)
	(segment
		(start 14.95171 -11.21156)
		(end 14.95171 -10.224008)
		(width 0.12954)
		(layer "F.Cu")
		(net "USB2_P10_DP")
	)
	(segment
		(start 14.95171 -7.917688)
		(end 15.400274 -7.469124)
		(width 0.12954)
		(layer "F.Cu")
		(net "USB2_P10_DP")
	)
	(segment
		(start 15.942818 -6.92658)
		(end 16.377412 -6.491986)
		(width 0.12954)
		(layer "F.Cu")
		(net "USB2_P10_DP")
	)
	(segment
		(start 13.369798 -14.687804)
		(end 13.369798 -14.083538)
		(width 0.12954)
		(layer "F.Cu")
		(net "USB2_P10_DP")
	)
	(segment
		(start 15.14221 -8.880348)
		(end 15.14221 -8.494268)
		(width 0.12954)
		(layer "F.Cu")
		(net "USB2_P10_DP")
	)
	(segment
		(start 14.678914 -11.75385)
		(end 14.678914 -11.484356)
		(width 0.12954)
		(layer "F.Cu")
		(net "USB2_P10_DP")
	)
	(segment
		(start 14.95171 -9.070848)
		(end 15.14221 -8.880348)
		(width 0.12954)
		(layer "F.Cu")
		(net "USB2_P10_DP")
	)
	(segment
		(start 13.06957 -13.0937)
		(end 13.320522 -12.842748)
		(width 0.12954)
		(layer "F.Cu")
		(net "USB2_P10_DP")
	)
	(segment
		(start 13.590016 -12.842748)
		(end 13.86332 -12.569444)
		(width 0.12954)
		(layer "F.Cu")
		(net "USB2_P10_DP")
	)
	(segment
		(start 15.669514 -7.469124)
		(end 15.942818 -7.19582)
		(width 0.12954)
		(layer "F.Cu")
		(net "USB2_P10_DP")
	)
	(segment
		(start 16.377412 -6.491986)
		(end 17.215358 -6.491986)
		(width 0.12954)
		(layer "F.Cu")
		(net "USB2_P10_DP")
	)
	(segment
		(start 13.86332 -12.29995)
		(end 14.136116 -12.027154)
		(width 0.12954)
		(layer "F.Cu")
		(net "USB2_P10_DP")
	)
	(segment
		(start 13.369798 -14.083538)
		(end 13.06957 -13.78331)
		(width 0.12954)
		(layer "F.Cu")
		(net "USB2_P10_DP")
	)
	(segment
		(start 14.136116 -12.027154)
		(end 14.40561 -12.027154)
		(width 0.12954)
		(layer "F.Cu")
		(net "USB2_P10_DP")
	)
	(segment
		(start 14.95171 -8.303768)
		(end 14.95171 -7.917688)
		(width 0.12954)
		(layer "F.Cu")
		(net "USB2_P10_DP")
	)
	(segment
		(start 15.14221 -8.494268)
		(end 14.95171 -8.303768)
		(width 0.12954)
		(layer "F.Cu")
		(net "USB2_P10_DP")
	)
	(segment
		(start 14.40561 -12.027154)
		(end 14.678914 -11.75385)
		(width 0.12954)
		(layer "F.Cu")
		(net "USB2_P10_DP")
	)
	(segment
		(start 15.14221 -9.647428)
		(end 14.95171 -9.456928)
		(width 0.12954)
		(layer "F.Cu")
		(net "USB2_P10_DP")
	)
	(segment
		(start 13.872464 -14.92123)
		(end 13.603224 -14.92123)
		(width 0.12954)
		(layer "F.Cu")
		(net "USB2_P10_DP")
	)
	(segment
		(start 13.06957 -13.78331)
		(end 13.06957 -13.0937)
		(width 0.12954)
		(layer "F.Cu")
		(net "USB2_P10_DP")
	)
	(segment
		(start 17.485614 -7.60095)
		(end 17.34693 -7.739634)
		(width 0.12954)
		(layer "F.Cu")
		(net "USB2_P10_DP")
	)
	(segment
		(start 13.320522 -12.842748)
		(end 13.590016 -12.842748)
		(width 0.12954)
		(layer "F.Cu")
		(net "USB2_P10_DP")
	)
	(segment
		(start 17.485614 -6.762242)
		(end 17.485614 -7.60095)
		(width 0.12954)
		(layer "F.Cu")
		(net "USB2_P10_DP")
	)
	(segment
		(start 13.86332 -12.569444)
		(end 13.86332 -12.29995)
		(width 0.12954)
		(layer "F.Cu")
		(net "USB2_P10_DP")
	)
	(segment
		(start 14.95171 -9.456928)
		(end 14.95171 -9.070848)
		(width 0.12954)
		(layer "F.Cu")
		(net "USB2_P10_DP")
	)
	(segment
		(start 15.14221 -10.033508)
		(end 15.14221 -9.647428)
		(width 0.12954)
		(layer "F.Cu")
		(net "USB2_P10_DP")
	)
	(segment
		(start 13.603224 -14.92123)
		(end 13.369798 -14.687804)
		(width 0.12954)
		(layer "F.Cu")
		(net "USB2_P10_DP")
	)
	(segment
		(start 15.942818 -7.19582)
		(end 15.942818 -6.92658)
		(width 0.12954)
		(layer "F.Cu")
		(net "USB2_P10_DP")
	)
	(segment
		(start 17.34693 -7.739634)
		(end 17.34693 -8.320024)
		(width 0.12954)
		(layer "F.Cu")
		(net "USB2_P10_DP")
	)
	(segment
		(start 14.95171 -10.224008)
		(end 15.14221 -10.033508)
		(width 0.12954)
		(layer "F.Cu")
		(net "USB2_P10_DP")
	)
	(segment
		(start 15.400274 -7.469124)
		(end 15.669514 -7.469124)
		(width 0.12954)
		(layer "F.Cu")
		(net "USB2_P10_DP")
	)
	(segment
		(start 12.74699 -13.917168)
		(end 12.74699 -12.959842)
		(width 0.12954)
		(layer "F.Cu")
		(net "USB2_P10_DN")
	)
	(segment
		(start 13.047218 -14.651228)
		(end 13.047218 -14.217396)
		(width 0.12954)
		(layer "F.Cu")
		(net "USB2_P10_DN")
	)
	(segment
		(start 16.243554 -6.169406)
		(end 17.349216 -6.169406)
		(width 0.12954)
		(layer "F.Cu")
		(net "USB2_P10_DN")
	)
	(segment
		(start 12.777216 -14.92123)
		(end 13.047218 -14.651228)
		(width 0.12954)
		(layer "F.Cu")
		(net "USB2_P10_DN")
	)
	(segment
		(start 13.047218 -14.217396)
		(end 12.74699 -13.917168)
		(width 0.12954)
		(layer "F.Cu")
		(net "USB2_P10_DN")
	)
	(segment
		(start 14.62913 -7.78383)
		(end 16.243554 -6.169406)
		(width 0.12954)
		(layer "F.Cu")
		(net "USB2_P10_DN")
	)
	(segment
		(start 17.808194 -7.605014)
		(end 17.946878 -7.743698)
		(width 0.12954)
		(layer "F.Cu")
		(net "USB2_P10_DN")
	)
	(segment
		(start 14.62913 -11.077702)
		(end 14.62913 -7.78383)
		(width 0.12954)
		(layer "F.Cu")
		(net "USB2_P10_DN")
	)
	(segment
		(start 17.808194 -6.628384)
		(end 17.808194 -7.605014)
		(width 0.12954)
		(layer "F.Cu")
		(net "USB2_P10_DN")
	)
	(segment
		(start 12.74699 -12.959842)
		(end 14.62913 -11.077702)
		(width 0.12954)
		(layer "F.Cu")
		(net "USB2_P10_DN")
	)
	(segment
		(start 17.349216 -6.169406)
		(end 17.808194 -6.628384)
		(width 0.12954)
		(layer "F.Cu")
		(net "USB2_P10_DN")
	)
	(segment
		(start 17.946878 -7.743698)
		(end 17.946878 -8.320024)
		(width 0.12954)
		(layer "F.Cu")
		(net "USB2_P10_DN")
	)
	(segment
		(start 364.302548 -14.850618)
		(end 364.283498 -14.850618)
		(width 0.10668)
		(layer "F.Cu")
		(net "UART_VCC_J13")
	)
	(segment
		(start 363.540548 -15.593568)
		(end 363.540548 -22.18563)
		(width 0.10668)
		(layer "F.Cu")
		(net "UART_VCC_J13")
	)
	(segment
		(start 365.318548 -14.850618)
		(end 364.302548 -14.850618)
		(width 0.10668)
		(layer "F.Cu")
		(net "UART_VCC_J13")
	)
	(segment
		(start 363.540548 -22.18563)
		(end 363.51845 -22.207728)
		(width 0.10668)
		(layer "F.Cu")
		(net "UART_VCC_J13")
	)
	(segment
		(start 364.283498 -14.850618)
		(end 363.540548 -15.593568)
		(width 0.10668)
		(layer "F.Cu")
		(net "UART_VCC_J13")
	)
	(via
		(at 363.540548 -15.593568)
		(size 0.508)
		(drill 0.254)
		(layers "F.Cu" "B.Cu")
		(net "UART_VCC_J13")
	)
	(segment
		(start 362.898182 -28.673552)
		(end 363.008926 -28.673552)
		(width 0.10668)
		(layer "F.Cu")
		(net "UART_LS_EN_R_N")
	)
	(segment
		(start 361.764834 -28.663646)
		(end 360.11104 -28.663646)
		(width 0.10668)
		(layer "F.Cu")
		(net "UART_LS_EN_R_N")
	)
	(segment
		(start 363.008926 -28.673552)
		(end 363.008926 -29.549598)
		(width 0.10668)
		(layer "F.Cu")
		(net "UART_LS_EN_R_N")
	)
	(segment
		(start 362.888276 -28.663646)
		(end 362.898182 -28.673552)
		(width 0.10668)
		(layer "F.Cu")
		(net "UART_LS_EN_R_N")
	)
	(segment
		(start 360.11104 -28.663646)
		(end 360.07929 -28.695396)
		(width 0.10668)
		(layer "F.Cu")
		(net "UART_LS_EN_R_N")
	)
	(segment
		(start 363.008926 -29.549598)
		(end 363.345984 -29.886656)
		(width 0.10668)
		(layer "F.Cu")
		(net "UART_LS_EN_R_N")
	)
	(segment
		(start 363.345984 -29.886656)
		(end 363.755178 -29.886656)
		(width 0.10668)
		(layer "F.Cu")
		(net "UART_LS_EN_R_N")
	)
	(segment
		(start 361.764834 -28.663646)
		(end 362.888276 -28.663646)
		(width 0.10668)
		(layer "F.Cu")
		(net "UART_LS_EN_R_N")
	)
	(via
		(at 361.764834 -28.663646)
		(size 0.762)
		(drill 0.381)
		(layers "F.Cu" "B.Cu")
		(net "UART_LS_EN_R_N")
	)
	(segment
		(start 365.331248 -32.913574)
		(end 364.121446 -31.703772)
		(width 0.10668)
		(layer "F.Cu")
		(net "UART_LS_EN_N")
	)
	(segment
		(start 364.555278 -31.26994)
		(end 364.121446 -31.703772)
		(width 0.10668)
		(layer "F.Cu")
		(net "UART_LS_EN_N")
	)
	(segment
		(start 365.331248 -34.243772)
		(end 365.331248 -32.913574)
		(width 0.10668)
		(layer "F.Cu")
		(net "UART_LS_EN_N")
	)
	(segment
		(start 364.555278 -29.886656)
		(end 364.555278 -31.26994)
		(width 0.10668)
		(layer "F.Cu")
		(net "UART_LS_EN_N")
	)
	(via
		(at 364.121446 -31.703772)
		(size 0.762)
		(drill 0.381)
		(layers "F.Cu" "B.Cu")
		(net "UART_LS_EN_N")
	)
	(segment
		(start 205.354936 -111.665512)
		(end 205.87462 -111.665512)
		(width 0.10668)
		(layer "F.Cu")
		(net "UART_LS_EN")
	)
	(segment
		(start 206.530956 -112.321848)
		(end 206.530956 -112.609376)
		(width 0.10668)
		(layer "F.Cu")
		(net "UART_LS_EN")
	)
	(segment
		(start 357.839518 -29.695394)
		(end 356.848918 -29.695394)
		(width 0.10668)
		(layer "F.Cu")
		(net "UART_LS_EN")
	)
	(segment
		(start 205.87462 -111.665512)
		(end 206.530956 -112.321848)
		(width 0.10668)
		(layer "F.Cu")
		(net "UART_LS_EN")
	)
	(via
		(at 356.848918 -29.695394)
		(size 0.508)
		(drill 0.254)
		(layers "F.Cu" "B.Cu")
		(net "UART_LS_EN")
	)
	(via
		(at 208.852008 -78.733142)
		(size 0.508)
		(drill 0.254)
		(layers "F.Cu" "B.Cu")
		(net "UART_LS_EN")
	)
	(via
		(at 206.530956 -112.609376)
		(size 0.762)
		(drill 0.254)
		(layers "F.Cu" "B.Cu")
		(net "UART_LS_EN")
	)
	(segment
		(start 206.530956 -112.609376)
		(end 206.530956 -112.268)
		(width 0.11684)
		(layer "In4.Cu")
		(net "UART_LS_EN")
	)
	(segment
		(start 206.02448 -111.761524)
		(end 206.02448 -105.99547)
		(width 0.11684)
		(layer "In4.Cu")
		(net "UART_LS_EN")
	)
	(segment
		(start 207.463644 -97.940622)
		(end 206.82458 -97.301558)
		(width 0.11684)
		(layer "In4.Cu")
		(net "UART_LS_EN")
	)
	(segment
		(start 208.86674 -103.15321)
		(end 208.86674 -100.91547)
		(width 0.11684)
		(layer "In4.Cu")
		(net "UART_LS_EN")
	)
	(segment
		(start 206.530956 -112.268)
		(end 206.02448 -111.761524)
		(width 0.11684)
		(layer "In4.Cu")
		(net "UART_LS_EN")
	)
	(segment
		(start 208.994756 -78.87589)
		(end 208.852008 -78.733142)
		(width 0.11684)
		(layer "In4.Cu")
		(net "UART_LS_EN")
	)
	(segment
		(start 206.82458 -90.004646)
		(end 208.994756 -87.83447)
		(width 0.11684)
		(layer "In4.Cu")
		(net "UART_LS_EN")
	)
	(segment
		(start 207.463644 -99.512374)
		(end 207.463644 -97.940622)
		(width 0.11684)
		(layer "In4.Cu")
		(net "UART_LS_EN")
	)
	(segment
		(start 206.02448 -105.99547)
		(end 208.86674 -103.15321)
		(width 0.11684)
		(layer "In4.Cu")
		(net "UART_LS_EN")
	)
	(segment
		(start 208.86674 -100.91547)
		(end 207.463644 -99.512374)
		(width 0.11684)
		(layer "In4.Cu")
		(net "UART_LS_EN")
	)
	(segment
		(start 208.994756 -87.83447)
		(end 208.994756 -78.87589)
		(width 0.11684)
		(layer "In4.Cu")
		(net "UART_LS_EN")
	)
	(segment
		(start 206.82458 -97.301558)
		(end 206.82458 -90.004646)
		(width 0.11684)
		(layer "In4.Cu")
		(net "UART_LS_EN")
	)
	(segment
		(start 208.852008 -78.733142)
		(end 209.60715 -77.978)
		(width 0.11684)
		(layer "In6.Cu")
		(net "UART_LS_EN")
	)
	(segment
		(start 319.802764 -41.411652)
		(end 319.802764 -40.533066)
		(width 0.11684)
		(layer "In6.Cu")
		(net "UART_LS_EN")
	)
	(segment
		(start 271.86509 -64.791844)
		(end 291.121338 -45.535596)
		(width 0.11684)
		(layer "In6.Cu")
		(net "UART_LS_EN")
	)
	(segment
		(start 306.10175 -44.925488)
		(end 316.288928 -44.925488)
		(width 0.11684)
		(layer "In6.Cu")
		(net "UART_LS_EN")
	)
	(segment
		(start 266.553696 -64.791844)
		(end 271.86509 -64.791844)
		(width 0.11684)
		(layer "In6.Cu")
		(net "UART_LS_EN")
	)
	(segment
		(start 232.556812 -72.124316)
		(end 233.46791 -73.035414)
		(width 0.11684)
		(layer "In6.Cu")
		(net "UART_LS_EN")
	)
	(segment
		(start 258.358894 -71.770494)
		(end 259.575046 -71.770494)
		(width 0.11684)
		(layer "In6.Cu")
		(net "UART_LS_EN")
	)
	(segment
		(start 257.093974 -73.035414)
		(end 258.358894 -71.770494)
		(width 0.11684)
		(layer "In6.Cu")
		(net "UART_LS_EN")
	)
	(segment
		(start 209.60715 -77.978)
		(end 223.649794 -77.978)
		(width 0.11684)
		(layer "In6.Cu")
		(net "UART_LS_EN")
	)
	(segment
		(start 233.46791 -73.035414)
		(end 257.093974 -73.035414)
		(width 0.11684)
		(layer "In6.Cu")
		(net "UART_LS_EN")
	)
	(segment
		(start 325.48703 -34.8488)
		(end 325.48703 -34.035492)
		(width 0.11684)
		(layer "In6.Cu")
		(net "UART_LS_EN")
	)
	(segment
		(start 223.649794 -77.978)
		(end 229.503478 -72.124316)
		(width 0.11684)
		(layer "In6.Cu")
		(net "UART_LS_EN")
	)
	(segment
		(start 316.288928 -44.925488)
		(end 319.802764 -41.411652)
		(width 0.11684)
		(layer "In6.Cu")
		(net "UART_LS_EN")
	)
	(segment
		(start 305.491642 -45.535596)
		(end 306.10175 -44.925488)
		(width 0.11684)
		(layer "In6.Cu")
		(net "UART_LS_EN")
	)
	(segment
		(start 259.575046 -71.770494)
		(end 266.553696 -64.791844)
		(width 0.11684)
		(layer "In6.Cu")
		(net "UART_LS_EN")
	)
	(segment
		(start 319.802764 -40.533066)
		(end 325.48703 -34.8488)
		(width 0.11684)
		(layer "In6.Cu")
		(net "UART_LS_EN")
	)
	(segment
		(start 291.121338 -45.535596)
		(end 305.491642 -45.535596)
		(width 0.11684)
		(layer "In6.Cu")
		(net "UART_LS_EN")
	)
	(segment
		(start 229.503478 -72.124316)
		(end 232.556812 -72.124316)
		(width 0.11684)
		(layer "In6.Cu")
		(net "UART_LS_EN")
	)
	(segment
		(start 343.430352 -30.211776)
		(end 344.273632 -29.368496)
		(width 0.11684)
		(layer "In6.Cu")
		(net "UART_LS_EN")
	)
	(segment
		(start 325.48703 -34.035492)
		(end 329.310746 -30.211776)
		(width 0.11684)
		(layer "In6.Cu")
		(net "UART_LS_EN")
	)
	(segment
		(start 329.310746 -30.211776)
		(end 343.430352 -30.211776)
		(width 0.11684)
		(layer "In6.Cu")
		(net "UART_LS_EN")
	)
	(segment
		(start 344.273632 -29.368496)
		(end 356.52202 -29.368496)
		(width 0.11684)
		(layer "In6.Cu")
		(net "UART_LS_EN")
	)
	(segment
		(start 356.52202 -29.368496)
		(end 356.848918 -29.695394)
		(width 0.11684)
		(layer "In6.Cu")
		(net "UART_LS_EN")
	)
	(segment
		(start 367.281206 -41.305988)
		(end 366.971326 -41.615868)
		(width 0.10668)
		(layer "F.Cu")
		(net "UART_CPU0_UART0_TX")
	)
	(segment
		(start 275.931884 -165.711124)
		(end 275.441664 -166.201344)
		(width 0.10668)
		(layer "F.Cu")
		(net "UART_CPU0_UART0_TX")
	)
	(segment
		(start 294.971978 -144.7927)
		(end 275.931884 -163.832794)
		(width 0.10668)
		(layer "F.Cu")
		(net "UART_CPU0_UART0_TX")
	)
	(segment
		(start 367.281206 -39.843964)
		(end 367.281206 -41.305988)
		(width 0.10668)
		(layer "F.Cu")
		(net "UART_CPU0_UART0_TX")
	)
	(segment
		(start 275.931884 -163.832794)
		(end 275.931884 -165.711124)
		(width 0.10668)
		(layer "F.Cu")
		(net "UART_CPU0_UART0_TX")
	)
	(segment
		(start 295.165018 -144.7927)
		(end 294.971978 -144.7927)
		(width 0.10668)
		(layer "F.Cu")
		(net "UART_CPU0_UART0_TX")
	)
	(segment
		(start 366.971326 -41.615868)
		(end 366.971326 -42.835068)
		(width 0.10668)
		(layer "F.Cu")
		(net "UART_CPU0_UART0_TX")
	)
	(segment
		(start 274.619974 -166.201344)
		(end 271.015206 -169.806112)
		(width 0.10668)
		(layer "F.Cu")
		(net "UART_CPU0_UART0_TX")
	)
	(segment
		(start 271.015206 -169.806112)
		(end 271.015206 -186.549538)
		(width 0.10668)
		(layer "F.Cu")
		(net "UART_CPU0_UART0_TX")
	)
	(segment
		(start 271.015206 -186.549538)
		(end 270.549116 -187.015628)
		(width 0.10668)
		(layer "F.Cu")
		(net "UART_CPU0_UART0_TX")
	)
	(segment
		(start 275.441664 -166.201344)
		(end 274.619974 -166.201344)
		(width 0.10668)
		(layer "F.Cu")
		(net "UART_CPU0_UART0_TX")
	)
	(via
		(at 295.165018 -144.7927)
		(size 0.508)
		(drill 0.254)
		(layers "F.Cu" "B.Cu")
		(net "UART_CPU0_UART0_TX")
	)
	(via
		(at 270.549116 -187.015628)
		(size 0.508)
		(drill 0.254)
		(layers "F.Cu" "B.Cu")
		(net "UART_CPU0_UART0_TX")
	)
	(via
		(at 366.971326 -41.615868)
		(size 0.508)
		(drill 0.254)
		(layers "F.Cu" "B.Cu")
		(net "UART_CPU0_UART0_TX")
	)
	(segment
		(start 302.741076 -319.55613)
		(end 303.485296 -319.55613)
		(width 0.10668)
		(layer "B.Cu")
		(net "UART_CPU0_UART0_TX")
	)
	(segment
		(start 303.485296 -319.55613)
		(end 314.432696 -308.60873)
		(width 0.10668)
		(layer "B.Cu")
		(net "UART_CPU0_UART0_TX")
	)
	(segment
		(start 300.519592 -321.777614)
		(end 302.741076 -319.55613)
		(width 0.10668)
		(layer "B.Cu")
		(net "UART_CPU0_UART0_TX")
	)
	(segment
		(start 345.244674 -303.872392)
		(end 347.387926 -306.015644)
		(width 0.10668)
		(layer "B.Cu")
		(net "UART_CPU0_UART0_TX")
	)
	(segment
		(start 257.883914 -190.02502)
		(end 255.192276 -192.716658)
		(width 0.10668)
		(layer "B.Cu")
		(net "UART_CPU0_UART0_TX")
	)
	(segment
		(start 261.161276 -221.684342)
		(end 261.161276 -319.92189)
		(width 0.10668)
		(layer "B.Cu")
		(net "UART_CPU0_UART0_TX")
	)
	(segment
		(start 255.192276 -215.715342)
		(end 261.161276 -221.684342)
		(width 0.10668)
		(layer "B.Cu")
		(net "UART_CPU0_UART0_TX")
	)
	(segment
		(start 314.432696 -308.60873)
		(end 331.020674 -308.60873)
		(width 0.10668)
		(layer "B.Cu")
		(net "UART_CPU0_UART0_TX")
	)
	(segment
		(start 268.321028 -189.243716)
		(end 264.70483 -189.243716)
		(width 0.10668)
		(layer "B.Cu")
		(net "UART_CPU0_UART0_TX")
	)
	(segment
		(start 331.020674 -308.60873)
		(end 335.757012 -303.872392)
		(width 0.10668)
		(layer "B.Cu")
		(net "UART_CPU0_UART0_TX")
	)
	(segment
		(start 347.387926 -306.015644)
		(end 347.387926 -307.965856)
		(width 0.10668)
		(layer "B.Cu")
		(net "UART_CPU0_UART0_TX")
	)
	(segment
		(start 263.923526 -190.02502)
		(end 257.883914 -190.02502)
		(width 0.10668)
		(layer "B.Cu")
		(net "UART_CPU0_UART0_TX")
	)
	(segment
		(start 264.70483 -189.243716)
		(end 263.923526 -190.02502)
		(width 0.10668)
		(layer "B.Cu")
		(net "UART_CPU0_UART0_TX")
	)
	(segment
		(start 347.387926 -307.965856)
		(end 346.835984 -308.517798)
		(width 0.10668)
		(layer "B.Cu")
		(net "UART_CPU0_UART0_TX")
	)
	(segment
		(start 335.757012 -303.872392)
		(end 345.244674 -303.872392)
		(width 0.10668)
		(layer "B.Cu")
		(net "UART_CPU0_UART0_TX")
	)
	(segment
		(start 270.549116 -187.015628)
		(end 268.321028 -189.243716)
		(width 0.10668)
		(layer "B.Cu")
		(net "UART_CPU0_UART0_TX")
	)
	(segment
		(start 255.192276 -192.716658)
		(end 255.192276 -215.715342)
		(width 0.10668)
		(layer "B.Cu")
		(net "UART_CPU0_UART0_TX")
	)
	(segment
		(start 261.161276 -319.92189)
		(end 263.017 -321.777614)
		(width 0.10668)
		(layer "B.Cu")
		(net "UART_CPU0_UART0_TX")
	)
	(segment
		(start 346.835984 -308.517798)
		(end 346.427044 -308.517798)
		(width 0.10668)
		(layer "B.Cu")
		(net "UART_CPU0_UART0_TX")
	)
	(segment
		(start 263.017 -321.777614)
		(end 300.519592 -321.777614)
		(width 0.10668)
		(layer "B.Cu")
		(net "UART_CPU0_UART0_TX")
	)
	(segment
		(start 295.165018 -144.7927)
		(end 295.165018 -140.323316)
		(width 0.11684)
		(layer "In4.Cu")
		(net "UART_CPU0_UART0_TX")
	)
	(segment
		(start 313.00674 -108.61548)
		(end 317.21679 -104.40543)
		(width 0.11684)
		(layer "In4.Cu")
		(net "UART_CPU0_UART0_TX")
	)
	(segment
		(start 365.326422 -42.247312)
		(end 366.339882 -42.247312)
		(width 0.11684)
		(layer "In4.Cu")
		(net "UART_CPU0_UART0_TX")
	)
	(segment
		(start 366.339882 -42.247312)
		(end 366.971326 -41.615868)
		(width 0.11684)
		(layer "In4.Cu")
		(net "UART_CPU0_UART0_TX")
	)
	(segment
		(start 317.21679 -102.37724)
		(end 339.901022 -79.693008)
		(width 0.11684)
		(layer "In4.Cu")
		(net "UART_CPU0_UART0_TX")
	)
	(segment
		(start 313.413394 -122.07494)
		(end 313.413394 -115.575842)
		(width 0.11684)
		(layer "In4.Cu")
		(net "UART_CPU0_UART0_TX")
	)
	(segment
		(start 317.21679 -104.40543)
		(end 317.21679 -102.37724)
		(width 0.11684)
		(layer "In4.Cu")
		(net "UART_CPU0_UART0_TX")
	)
	(segment
		(start 339.901022 -67.672712)
		(end 365.326422 -42.247312)
		(width 0.11684)
		(layer "In4.Cu")
		(net "UART_CPU0_UART0_TX")
	)
	(segment
		(start 339.901022 -79.693008)
		(end 339.901022 -67.672712)
		(width 0.11684)
		(layer "In4.Cu")
		(net "UART_CPU0_UART0_TX")
	)
	(segment
		(start 313.413394 -115.575842)
		(end 313.00674 -115.169188)
		(width 0.11684)
		(layer "In4.Cu")
		(net "UART_CPU0_UART0_TX")
	)
	(segment
		(start 295.165018 -140.323316)
		(end 313.413394 -122.07494)
		(width 0.11684)
		(layer "In4.Cu")
		(net "UART_CPU0_UART0_TX")
	)
	(segment
		(start 313.00674 -115.169188)
		(end 313.00674 -108.61548)
		(width 0.11684)
		(layer "In4.Cu")
		(net "UART_CPU0_UART0_TX")
	)
	(segment
		(start 363.307884 -295.690036)
		(end 363.307884 -296.09288)
		(width 0.10668)
		(layer "F.Cu")
		(net "UART_CPU0_UART0_R_TX")
	)
	(segment
		(start 359.981246 -296.48531)
		(end 352.488246 -303.97831)
		(width 0.10668)
		(layer "F.Cu")
		(net "UART_CPU0_UART0_R_TX")
	)
	(segment
		(start 363.307884 -296.09288)
		(end 362.915454 -296.48531)
		(width 0.10668)
		(layer "F.Cu")
		(net "UART_CPU0_UART0_R_TX")
	)
	(segment
		(start 352.488246 -303.97831)
		(end 346.433394 -303.97831)
		(width 0.10668)
		(layer "F.Cu")
		(net "UART_CPU0_UART0_R_TX")
	)
	(segment
		(start 342.6587 -306.072286)
		(end 342.649048 -306.062634)
		(width 0.10668)
		(layer "F.Cu")
		(net "UART_CPU0_UART0_R_TX")
	)
	(segment
		(start 346.433394 -303.97831)
		(end 344.339418 -306.072286)
		(width 0.10668)
		(layer "F.Cu")
		(net "UART_CPU0_UART0_R_TX")
	)
	(segment
		(start 344.339418 -306.072286)
		(end 342.6587 -306.072286)
		(width 0.10668)
		(layer "F.Cu")
		(net "UART_CPU0_UART0_R_TX")
	)
	(segment
		(start 362.915454 -296.48531)
		(end 359.981246 -296.48531)
		(width 0.10668)
		(layer "F.Cu")
		(net "UART_CPU0_UART0_R_TX")
	)
	(via
		(at 342.649048 -306.062634)
		(size 0.508)
		(drill 0.254)
		(layers "F.Cu" "B.Cu")
		(net "UART_CPU0_UART0_R_TX")
	)
	(via
		(at 344.473784 -309.3085)
		(size 0.6604)
		(drill 0.3302)
		(layers "F.Cu" "B.Cu")
		(net "UART_CPU0_UART0_R_TX")
	)
	(segment
		(start 342.59774 -306.113942)
		(end 342.59774 -307.015896)
		(width 0.10668)
		(layer "B.Cu")
		(net "UART_CPU0_UART0_R_TX")
	)
	(segment
		(start 345.626944 -308.789832)
		(end 345.626944 -308.517798)
		(width 0.10668)
		(layer "B.Cu")
		(net "UART_CPU0_UART0_R_TX")
	)
	(segment
		(start 343.007442 -309.002938)
		(end 343.313004 -309.3085)
		(width 0.10668)
		(layer "B.Cu")
		(net "UART_CPU0_UART0_R_TX")
	)
	(segment
		(start 342.59774 -307.015896)
		(end 343.007442 -307.425598)
		(width 0.10668)
		(layer "B.Cu")
		(net "UART_CPU0_UART0_R_TX")
	)
	(segment
		(start 345.108276 -309.3085)
		(end 345.626944 -308.789832)
		(width 0.10668)
		(layer "B.Cu")
		(net "UART_CPU0_UART0_R_TX")
	)
	(segment
		(start 344.473784 -309.3085)
		(end 345.108276 -309.3085)
		(width 0.10668)
		(layer "B.Cu")
		(net "UART_CPU0_UART0_R_TX")
	)
	(segment
		(start 343.007442 -307.425598)
		(end 343.007442 -309.002938)
		(width 0.10668)
		(layer "B.Cu")
		(net "UART_CPU0_UART0_R_TX")
	)
	(segment
		(start 342.649048 -306.062634)
		(end 342.59774 -306.113942)
		(width 0.10668)
		(layer "B.Cu")
		(net "UART_CPU0_UART0_R_TX")
	)
	(segment
		(start 343.313004 -309.3085)
		(end 344.473784 -309.3085)
		(width 0.10668)
		(layer "B.Cu")
		(net "UART_CPU0_UART0_R_TX")
	)
	(segment
		(start 366.63122 -39.843964)
		(end 366.63122 -40.589708)
		(width 0.10668)
		(layer "F.Cu")
		(net "UART_CPU0_UART0_R_RX")
	)
	(segment
		(start 366.63122 -40.589708)
		(end 366.184688 -41.03624)
		(width 0.10668)
		(layer "F.Cu")
		(net "UART_CPU0_UART0_R_RX")
	)
	(segment
		(start 365.071406 -41.03624)
		(end 364.65383 -41.453816)
		(width 0.10668)
		(layer "F.Cu")
		(net "UART_CPU0_UART0_R_RX")
	)
	(segment
		(start 366.184688 -41.03624)
		(end 365.071406 -41.03624)
		(width 0.10668)
		(layer "F.Cu")
		(net "UART_CPU0_UART0_R_RX")
	)
	(segment
		(start 364.65383 -42.495216)
		(end 364.993682 -42.835068)
		(width 0.10668)
		(layer "F.Cu")
		(net "UART_CPU0_UART0_R_RX")
	)
	(segment
		(start 364.65383 -41.453816)
		(end 364.65383 -42.20972)
		(width 0.10668)
		(layer "F.Cu")
		(net "UART_CPU0_UART0_R_RX")
	)
	(segment
		(start 364.993682 -42.835068)
		(end 365.701326 -42.835068)
		(width 0.10668)
		(layer "F.Cu")
		(net "UART_CPU0_UART0_R_RX")
	)
	(segment
		(start 364.65383 -42.20972)
		(end 364.65383 -42.495216)
		(width 0.10668)
		(layer "F.Cu")
		(net "UART_CPU0_UART0_R_RX")
	)
	(via
		(at 364.65383 -42.20972)
		(size 0.762)
		(drill 0.381)
		(layers "F.Cu" "B.Cu")
		(net "UART_CPU0_UART0_R_RX")
	)
	(segment
		(start 362.368084 -294.070024)
		(end 362.834936 -294.335962)
		(width 0.10668)
		(layer "F.Cu")
		(net "UART_CPU0_UART0_RX")
	)
	(segment
		(start 365.701326 -44.867068)
		(end 365.701326 -44.251118)
		(width 0.10668)
		(layer "F.Cu")
		(net "UART_CPU0_UART0_RX")
	)
	(segment
		(start 365.701326 -43.635168)
		(end 365.701326 -44.251118)
		(width 0.10668)
		(layer "F.Cu")
		(net "UART_CPU0_UART0_RX")
	)
	(via
		(at 403.82063 -331.543406)
		(size 0.508)
		(drill 0.254)
		(layers "F.Cu" "B.Cu")
		(net "UART_CPU0_UART0_RX")
	)
	(via
		(at 315.643768 -122.79249)
		(size 0.508)
		(drill 0.254)
		(layers "F.Cu" "B.Cu")
		(net "UART_CPU0_UART0_RX")
	)
	(via
		(at 362.834936 -294.335962)
		(size 0.4064)
		(drill 0.2032)
		(layers "F.Cu" "B.Cu")
		(net "UART_CPU0_UART0_RX")
	)
	(via
		(at 365.701326 -44.251118)
		(size 0.508)
		(drill 0.254)
		(layers "F.Cu" "B.Cu")
		(net "UART_CPU0_UART0_RX")
	)
	(segment
		(start 363.772958 -295.576752)
		(end 363.772958 -304.564288)
		(width 0.10668)
		(layer "B.Cu")
		(net "UART_CPU0_UART0_RX")
	)
	(segment
		(start 362.834936 -294.335962)
		(end 363.192568 -294.335962)
		(width 0.0889)
		(layer "B.Cu")
		(net "UART_CPU0_UART0_RX")
	)
	(segment
		(start 371.972078 -312.798968)
		(end 371.972078 -314.578492)
		(width 0.10668)
		(layer "B.Cu")
		(net "UART_CPU0_UART0_RX")
	)
	(segment
		(start 371.923818 -312.750708)
		(end 371.972078 -312.798968)
		(width 0.10668)
		(layer "B.Cu")
		(net "UART_CPU0_UART0_RX")
	)
	(segment
		(start 363.192568 -294.335962)
		(end 363.772958 -294.916352)
		(width 0.0889)
		(layer "B.Cu")
		(net "UART_CPU0_UART0_RX")
	)
	(segment
		(start 403.315678 -332.567026)
		(end 403.82063 -332.062074)
		(width 0.10668)
		(layer "B.Cu")
		(net "UART_CPU0_UART0_RX")
	)
	(segment
		(start 371.972078 -314.578492)
		(end 391.074656 -333.68107)
		(width 0.10668)
		(layer "B.Cu")
		(net "UART_CPU0_UART0_RX")
	)
	(segment
		(start 397.38808 -333.68107)
		(end 399.935954 -333.68107)
		(width 0.10668)
		(layer "B.Cu")
		(net "UART_CPU0_UART0_RX")
	)
	(segment
		(start 401.049998 -332.567026)
		(end 403.315678 -332.567026)
		(width 0.10668)
		(layer "B.Cu")
		(net "UART_CPU0_UART0_RX")
	)
	(segment
		(start 396.874492 -333.68107)
		(end 396.874746 -333.681324)
		(width 0.10668)
		(layer "B.Cu")
		(net "UART_CPU0_UART0_RX")
	)
	(segment
		(start 396.874746 -333.681324)
		(end 397.387826 -333.681324)
		(width 0.10668)
		(layer "B.Cu")
		(net "UART_CPU0_UART0_RX")
	)
	(segment
		(start 399.935954 -333.68107)
		(end 401.049998 -332.567026)
		(width 0.10668)
		(layer "B.Cu")
		(net "UART_CPU0_UART0_RX")
	)
	(segment
		(start 391.074656 -333.68107)
		(end 396.874492 -333.68107)
		(width 0.10668)
		(layer "B.Cu")
		(net "UART_CPU0_UART0_RX")
	)
	(segment
		(start 403.82063 -332.062074)
		(end 403.82063 -331.543406)
		(width 0.10668)
		(layer "B.Cu")
		(net "UART_CPU0_UART0_RX")
	)
	(segment
		(start 363.772958 -294.916352)
		(end 363.772958 -295.576752)
		(width 0.0889)
		(layer "B.Cu")
		(net "UART_CPU0_UART0_RX")
	)
	(segment
		(start 397.387826 -333.681324)
		(end 397.38808 -333.68107)
		(width 0.10668)
		(layer "B.Cu")
		(net "UART_CPU0_UART0_RX")
	)
	(segment
		(start 363.772958 -304.564288)
		(end 371.923818 -312.715148)
		(width 0.10668)
		(layer "B.Cu")
		(net "UART_CPU0_UART0_RX")
	)
	(segment
		(start 371.923818 -312.715148)
		(end 371.923818 -312.750708)
		(width 0.10668)
		(layer "B.Cu")
		(net "UART_CPU0_UART0_RX")
	)
	(segment
		(start 425.79163 -124.961396)
		(end 403.638512 -124.961396)
		(width 0.11684)
		(layer "In2.Cu")
		(net "UART_CPU0_UART0_RX")
	)
	(segment
		(start 460.585566 -320.98107)
		(end 460.585566 -189.670436)
		(width 0.11684)
		(layer "In2.Cu")
		(net "UART_CPU0_UART0_RX")
	)
	(segment
		(start 403.82063 -331.543406)
		(end 403.82063 -331.510132)
		(width 0.11684)
		(layer "In2.Cu")
		(net "UART_CPU0_UART0_RX")
	)
	(segment
		(start 448.951858 -148.121624)
		(end 425.79163 -124.961396)
		(width 0.11684)
		(layer "In2.Cu")
		(net "UART_CPU0_UART0_RX")
	)
	(segment
		(start 318.085978 -125.2347)
		(end 315.643768 -122.79249)
		(width 0.11684)
		(layer "In2.Cu")
		(net "UART_CPU0_UART0_RX")
	)
	(segment
		(start 457.894182 -183.138064)
		(end 448.951858 -174.19574)
		(width 0.11684)
		(layer "In2.Cu")
		(net "UART_CPU0_UART0_RX")
	)
	(segment
		(start 406.656794 -330.567792)
		(end 414.739074 -327.220072)
		(width 0.11684)
		(layer "In2.Cu")
		(net "UART_CPU0_UART0_RX")
	)
	(segment
		(start 448.951858 -174.19574)
		(end 448.951858 -148.121624)
		(width 0.11684)
		(layer "In2.Cu")
		(net "UART_CPU0_UART0_RX")
	)
	(segment
		(start 346.416122 -125.2347)
		(end 318.085978 -125.2347)
		(width 0.11684)
		(layer "In2.Cu")
		(net "UART_CPU0_UART0_RX")
	)
	(segment
		(start 454.346564 -327.220072)
		(end 460.585566 -320.98107)
		(width 0.11684)
		(layer "In2.Cu")
		(net "UART_CPU0_UART0_RX")
	)
	(segment
		(start 414.739074 -327.220072)
		(end 454.346564 -327.220072)
		(width 0.11684)
		(layer "In2.Cu")
		(net "UART_CPU0_UART0_RX")
	)
	(segment
		(start 404.76297 -330.567792)
		(end 406.656794 -330.567792)
		(width 0.11684)
		(layer "In2.Cu")
		(net "UART_CPU0_UART0_RX")
	)
	(segment
		(start 457.894182 -186.979052)
		(end 457.894182 -183.138064)
		(width 0.11684)
		(layer "In2.Cu")
		(net "UART_CPU0_UART0_RX")
	)
	(segment
		(start 348.15018 -126.968758)
		(end 346.416122 -125.2347)
		(width 0.11684)
		(layer "In2.Cu")
		(net "UART_CPU0_UART0_RX")
	)
	(segment
		(start 403.638512 -124.961396)
		(end 401.63115 -126.968758)
		(width 0.11684)
		(layer "In2.Cu")
		(net "UART_CPU0_UART0_RX")
	)
	(segment
		(start 403.82063 -331.510132)
		(end 404.76297 -330.567792)
		(width 0.11684)
		(layer "In2.Cu")
		(net "UART_CPU0_UART0_RX")
	)
	(segment
		(start 460.585566 -189.670436)
		(end 457.894182 -186.979052)
		(width 0.11684)
		(layer "In2.Cu")
		(net "UART_CPU0_UART0_RX")
	)
	(segment
		(start 401.63115 -126.968758)
		(end 348.15018 -126.968758)
		(width 0.11684)
		(layer "In2.Cu")
		(net "UART_CPU0_UART0_RX")
	)
	(segment
		(start 323.204078 -101.90226)
		(end 349.518986 -75.587352)
		(width 0.11684)
		(layer "In4.Cu")
		(net "UART_CPU0_UART0_RX")
	)
	(segment
		(start 315.643768 -122.79249)
		(end 315.643768 -119.559578)
		(width 0.11684)
		(layer "In4.Cu")
		(net "UART_CPU0_UART0_RX")
	)
	(segment
		(start 316.25032 -108.294932)
		(end 317.805308 -106.739944)
		(width 0.11684)
		(layer "In4.Cu")
		(net "UART_CPU0_UART0_RX")
	)
	(segment
		(start 317.805308 -106.739944)
		(end 320.080894 -106.739944)
		(width 0.11684)
		(layer "In4.Cu")
		(net "UART_CPU0_UART0_RX")
	)
	(segment
		(start 322.07454 -104.746298)
		(end 322.07454 -104.233472)
		(width 0.11684)
		(layer "In4.Cu")
		(net "UART_CPU0_UART0_RX")
	)
	(segment
		(start 349.518986 -75.587352)
		(end 349.518986 -67.42303)
		(width 0.11684)
		(layer "In4.Cu")
		(net "UART_CPU0_UART0_RX")
	)
	(segment
		(start 349.543116 -60.409328)
		(end 365.701326 -44.251118)
		(width 0.11684)
		(layer "In4.Cu")
		(net "UART_CPU0_UART0_RX")
	)
	(segment
		(start 322.07454 -104.233472)
		(end 323.204078 -103.103934)
		(width 0.11684)
		(layer "In4.Cu")
		(net "UART_CPU0_UART0_RX")
	)
	(segment
		(start 323.204078 -103.103934)
		(end 323.204078 -101.90226)
		(width 0.11684)
		(layer "In4.Cu")
		(net "UART_CPU0_UART0_RX")
	)
	(segment
		(start 320.080894 -106.739944)
		(end 322.07454 -104.746298)
		(width 0.11684)
		(layer "In4.Cu")
		(net "UART_CPU0_UART0_RX")
	)
	(segment
		(start 315.643768 -119.559578)
		(end 316.25032 -118.953026)
		(width 0.11684)
		(layer "In4.Cu")
		(net "UART_CPU0_UART0_RX")
	)
	(segment
		(start 349.543116 -67.3989)
		(end 349.543116 -60.409328)
		(width 0.11684)
		(layer "In4.Cu")
		(net "UART_CPU0_UART0_RX")
	)
	(segment
		(start 316.25032 -118.953026)
		(end 316.25032 -108.294932)
		(width 0.11684)
		(layer "In4.Cu")
		(net "UART_CPU0_UART0_RX")
	)
	(segment
		(start 349.518986 -67.42303)
		(end 349.543116 -67.3989)
		(width 0.11684)
		(layer "In4.Cu")
		(net "UART_CPU0_UART0_RX")
	)
	(segment
		(start 265.37793 -186.991752)
		(end 265.190224 -186.991752)
		(width 0.10668)
		(layer "F.Cu")
		(net "UART_CPU0_SCM_UART1_TX")
	)
	(segment
		(start 273.938746 -164.643308)
		(end 273.938746 -165.581076)
		(width 0.10668)
		(layer "F.Cu")
		(net "UART_CPU0_SCM_UART1_TX")
	)
	(segment
		(start 273.938746 -165.581076)
		(end 265.50493 -174.014892)
		(width 0.10668)
		(layer "F.Cu")
		(net "UART_CPU0_SCM_UART1_TX")
	)
	(segment
		(start 265.50493 -186.864752)
		(end 265.37793 -186.991752)
		(width 0.10668)
		(layer "F.Cu")
		(net "UART_CPU0_SCM_UART1_TX")
	)
	(segment
		(start 369.155726 -41.615868)
		(end 369.511326 -41.615868)
		(width 0.10668)
		(layer "F.Cu")
		(net "UART_CPU0_SCM_UART1_TX")
	)
	(segment
		(start 368.581432 -41.041574)
		(end 369.155726 -41.615868)
		(width 0.10668)
		(layer "F.Cu")
		(net "UART_CPU0_SCM_UART1_TX")
	)
	(segment
		(start 265.50493 -174.014892)
		(end 265.50493 -186.864752)
		(width 0.10668)
		(layer "F.Cu")
		(net "UART_CPU0_SCM_UART1_TX")
	)
	(segment
		(start 369.511326 -41.615868)
		(end 369.511326 -42.835068)
		(width 0.10668)
		(layer "F.Cu")
		(net "UART_CPU0_SCM_UART1_TX")
	)
	(segment
		(start 368.581432 -39.843964)
		(end 368.581432 -41.041574)
		(width 0.10668)
		(layer "F.Cu")
		(net "UART_CPU0_SCM_UART1_TX")
	)
	(via
		(at 265.190224 -186.991752)
		(size 0.508)
		(drill 0.254)
		(layers "F.Cu" "B.Cu")
		(net "UART_CPU0_SCM_UART1_TX")
	)
	(via
		(at 273.938746 -164.643308)
		(size 0.508)
		(drill 0.254)
		(layers "F.Cu" "B.Cu")
		(net "UART_CPU0_SCM_UART1_TX")
	)
	(via
		(at 369.511326 -41.615868)
		(size 0.508)
		(drill 0.254)
		(layers "F.Cu" "B.Cu")
		(net "UART_CPU0_SCM_UART1_TX")
	)
	(segment
		(start 338.311744 -305.812952)
		(end 338.734908 -305.812952)
		(width 0.10668)
		(layer "B.Cu")
		(net "UART_CPU0_SCM_UART1_TX")
	)
	(segment
		(start 339.355938 -306.315872)
		(end 338.929218 -306.315872)
		(width 0.10668)
		(layer "B.Cu")
		(net "UART_CPU0_SCM_UART1_TX")
	)
	(segment
		(start 331.117956 -310.234076)
		(end 336.001106 -305.350926)
		(width 0.10668)
		(layer "B.Cu")
		(net "UART_CPU0_SCM_UART1_TX")
	)
	(segment
		(start 338.929218 -306.315872)
		(end 338.734908 -306.121562)
		(width 0.10668)
		(layer "B.Cu")
		(net "UART_CPU0_SCM_UART1_TX")
	)
	(segment
		(start 259.862828 -321.792346)
		(end 261.074154 -323.003672)
		(width 0.10668)
		(layer "B.Cu")
		(net "UART_CPU0_SCM_UART1_TX")
	)
	(segment
		(start 257.345434 -188.726572)
		(end 253.893828 -192.178178)
		(width 0.10668)
		(layer "B.Cu")
		(net "UART_CPU0_SCM_UART1_TX")
	)
	(segment
		(start 315.747908 -310.234076)
		(end 331.117956 -310.234076)
		(width 0.10668)
		(layer "B.Cu")
		(net "UART_CPU0_SCM_UART1_TX")
	)
	(segment
		(start 301.019464 -323.003672)
		(end 303.100994 -320.922142)
		(width 0.10668)
		(layer "B.Cu")
		(net "UART_CPU0_SCM_UART1_TX")
	)
	(segment
		(start 259.862828 -222.222822)
		(end 259.862828 -321.792346)
		(width 0.10668)
		(layer "B.Cu")
		(net "UART_CPU0_SCM_UART1_TX")
	)
	(segment
		(start 253.893828 -216.253822)
		(end 259.862828 -222.222822)
		(width 0.10668)
		(layer "B.Cu")
		(net "UART_CPU0_SCM_UART1_TX")
	)
	(segment
		(start 303.100994 -320.922142)
		(end 303.903888 -320.922142)
		(width 0.10668)
		(layer "B.Cu")
		(net "UART_CPU0_SCM_UART1_TX")
	)
	(segment
		(start 263.455404 -188.726572)
		(end 257.345434 -188.726572)
		(width 0.10668)
		(layer "B.Cu")
		(net "UART_CPU0_SCM_UART1_TX")
	)
	(segment
		(start 336.001106 -305.350926)
		(end 337.849718 -305.350926)
		(width 0.10668)
		(layer "B.Cu")
		(net "UART_CPU0_SCM_UART1_TX")
	)
	(segment
		(start 338.734908 -306.121562)
		(end 338.734908 -305.812952)
		(width 0.10668)
		(layer "B.Cu")
		(net "UART_CPU0_SCM_UART1_TX")
	)
	(segment
		(start 337.849718 -305.350926)
		(end 338.311744 -305.812952)
		(width 0.10668)
		(layer "B.Cu")
		(net "UART_CPU0_SCM_UART1_TX")
	)
	(segment
		(start 265.190224 -186.991752)
		(end 263.455404 -188.726572)
		(width 0.10668)
		(layer "B.Cu")
		(net "UART_CPU0_SCM_UART1_TX")
	)
	(segment
		(start 307.433726 -318.548258)
		(end 315.747908 -310.234076)
		(width 0.10668)
		(layer "B.Cu")
		(net "UART_CPU0_SCM_UART1_TX")
	)
	(segment
		(start 261.074154 -323.003672)
		(end 301.019464 -323.003672)
		(width 0.10668)
		(layer "B.Cu")
		(net "UART_CPU0_SCM_UART1_TX")
	)
	(segment
		(start 303.903888 -320.922142)
		(end 306.277772 -318.548258)
		(width 0.10668)
		(layer "B.Cu")
		(net "UART_CPU0_SCM_UART1_TX")
	)
	(segment
		(start 339.535008 -307.717952)
		(end 339.535008 -306.828952)
		(width 0.10668)
		(layer "B.Cu")
		(net "UART_CPU0_SCM_UART1_TX")
	)
	(segment
		(start 339.535008 -306.828952)
		(end 339.535008 -306.494942)
		(width 0.10668)
		(layer "B.Cu")
		(net "UART_CPU0_SCM_UART1_TX")
	)
	(segment
		(start 253.893828 -192.178178)
		(end 253.893828 -216.253822)
		(width 0.10668)
		(layer "B.Cu")
		(net "UART_CPU0_SCM_UART1_TX")
	)
	(segment
		(start 339.535008 -306.494942)
		(end 339.355938 -306.315872)
		(width 0.10668)
		(layer "B.Cu")
		(net "UART_CPU0_SCM_UART1_TX")
	)
	(segment
		(start 306.277772 -318.548258)
		(end 307.433726 -318.548258)
		(width 0.10668)
		(layer "B.Cu")
		(net "UART_CPU0_SCM_UART1_TX")
	)
	(segment
		(start 306.304442 -141.802612)
		(end 313.835034 -123.622308)
		(width 0.11684)
		(layer "In4.Cu")
		(net "UART_CPU0_SCM_UART1_TX")
	)
	(segment
		(start 298.661074 -142.846044)
		(end 305.26101 -142.846044)
		(width 0.11684)
		(layer "In4.Cu")
		(net "UART_CPU0_SCM_UART1_TX")
	)
	(segment
		(start 313.835034 -123.622308)
		(end 313.835034 -115.40109)
		(width 0.11684)
		(layer "In4.Cu")
		(net "UART_CPU0_SCM_UART1_TX")
	)
	(segment
		(start 365.509302 -42.79265)
		(end 368.334544 -42.79265)
		(width 0.11684)
		(layer "In4.Cu")
		(net "UART_CPU0_SCM_UART1_TX")
	)
	(segment
		(start 279.309068 -160.210754)
		(end 280.717752 -160.210754)
		(width 0.11684)
		(layer "In4.Cu")
		(net "UART_CPU0_SCM_UART1_TX")
	)
	(segment
		(start 275.35251 -164.167312)
		(end 279.309068 -160.210754)
		(width 0.11684)
		(layer "In4.Cu")
		(net "UART_CPU0_SCM_UART1_TX")
	)
	(segment
		(start 274.414742 -164.167312)
		(end 275.35251 -164.167312)
		(width 0.11684)
		(layer "In4.Cu")
		(net "UART_CPU0_SCM_UART1_TX")
	)
	(segment
		(start 284.492192 -152.265126)
		(end 290.279582 -146.477736)
		(width 0.11684)
		(layer "In4.Cu")
		(net "UART_CPU0_SCM_UART1_TX")
	)
	(segment
		(start 344.400378 -63.901574)
		(end 365.509302 -42.79265)
		(width 0.11684)
		(layer "In4.Cu")
		(net "UART_CPU0_SCM_UART1_TX")
	)
	(segment
		(start 317.91021 -104.47655)
		(end 317.91021 -102.280212)
		(width 0.11684)
		(layer "In4.Cu")
		(net "UART_CPU0_SCM_UART1_TX")
	)
	(segment
		(start 313.42838 -114.994436)
		(end 313.42838 -108.95838)
		(width 0.11684)
		(layer "In4.Cu")
		(net "UART_CPU0_SCM_UART1_TX")
	)
	(segment
		(start 305.26101 -142.846044)
		(end 306.304442 -141.802612)
		(width 0.11684)
		(layer "In4.Cu")
		(net "UART_CPU0_SCM_UART1_TX")
	)
	(segment
		(start 280.717752 -160.210754)
		(end 284.492192 -156.436314)
		(width 0.11684)
		(layer "In4.Cu")
		(net "UART_CPU0_SCM_UART1_TX")
	)
	(segment
		(start 313.835034 -115.40109)
		(end 313.42838 -114.994436)
		(width 0.11684)
		(layer "In4.Cu")
		(net "UART_CPU0_SCM_UART1_TX")
	)
	(segment
		(start 313.42838 -108.95838)
		(end 317.91021 -104.47655)
		(width 0.11684)
		(layer "In4.Cu")
		(net "UART_CPU0_SCM_UART1_TX")
	)
	(segment
		(start 284.492192 -156.436314)
		(end 284.492192 -152.265126)
		(width 0.11684)
		(layer "In4.Cu")
		(net "UART_CPU0_SCM_UART1_TX")
	)
	(segment
		(start 295.029382 -146.477736)
		(end 298.661074 -142.846044)
		(width 0.11684)
		(layer "In4.Cu")
		(net "UART_CPU0_SCM_UART1_TX")
	)
	(segment
		(start 317.91021 -102.280212)
		(end 344.400378 -75.790044)
		(width 0.11684)
		(layer "In4.Cu")
		(net "UART_CPU0_SCM_UART1_TX")
	)
	(segment
		(start 344.400378 -75.790044)
		(end 344.400378 -63.901574)
		(width 0.11684)
		(layer "In4.Cu")
		(net "UART_CPU0_SCM_UART1_TX")
	)
	(segment
		(start 368.334544 -42.79265)
		(end 369.511326 -41.615868)
		(width 0.11684)
		(layer "In4.Cu")
		(net "UART_CPU0_SCM_UART1_TX")
	)
	(segment
		(start 290.279582 -146.477736)
		(end 295.029382 -146.477736)
		(width 0.11684)
		(layer "In4.Cu")
		(net "UART_CPU0_SCM_UART1_TX")
	)
	(segment
		(start 273.938746 -164.643308)
		(end 274.414742 -164.167312)
		(width 0.11684)
		(layer "In4.Cu")
		(net "UART_CPU0_SCM_UART1_TX")
	)
	(segment
		(start 365.187992 -296.213276)
		(end 365.187992 -295.690036)
		(width 0.10668)
		(layer "F.Cu")
		(net "UART_CPU0_SCM_UART1_R_TX")
	)
	(segment
		(start 353.151694 -305.02225)
		(end 360.611674 -297.56227)
		(width 0.10668)
		(layer "F.Cu")
		(net "UART_CPU0_SCM_UART1_R_TX")
	)
	(segment
		(start 363.838998 -297.56227)
		(end 365.187992 -296.213276)
		(width 0.10668)
		(layer "F.Cu")
		(net "UART_CPU0_SCM_UART1_R_TX")
	)
	(segment
		(start 360.611674 -297.56227)
		(end 363.838998 -297.56227)
		(width 0.10668)
		(layer "F.Cu")
		(net "UART_CPU0_SCM_UART1_R_TX")
	)
	(segment
		(start 345.76639 -306.506372)
		(end 347.250512 -305.02225)
		(width 0.10668)
		(layer "F.Cu")
		(net "UART_CPU0_SCM_UART1_R_TX")
	)
	(segment
		(start 347.250512 -305.02225)
		(end 353.151694 -305.02225)
		(width 0.10668)
		(layer "F.Cu")
		(net "UART_CPU0_SCM_UART1_R_TX")
	)
	(via
		(at 345.76639 -306.506372)
		(size 0.508)
		(drill 0.254)
		(layers "F.Cu" "B.Cu")
		(net "UART_CPU0_SCM_UART1_R_TX")
	)
	(via
		(at 343.592658 -308.372256)
		(size 0.6604)
		(drill 0.3302)
		(layers "F.Cu" "B.Cu")
		(net "UART_CPU0_SCM_UART1_R_TX")
	)
	(segment
		(start 343.113614 -307.057552)
		(end 343.482422 -307.42636)
		(width 0.10668)
		(layer "B.Cu")
		(net "UART_CPU0_SCM_UART1_R_TX")
	)
	(segment
		(start 339.535008 -305.097942)
		(end 339.70976 -304.92319)
		(width 0.10668)
		(layer "B.Cu")
		(net "UART_CPU0_SCM_UART1_R_TX")
	)
	(segment
		(start 339.70976 -304.92319)
		(end 343.43975 -304.92319)
		(width 0.10668)
		(layer "B.Cu")
		(net "UART_CPU0_SCM_UART1_R_TX")
	)
	(segment
		(start 343.482422 -307.42636)
		(end 343.482422 -308.153562)
		(width 0.10668)
		(layer "B.Cu")
		(net "UART_CPU0_SCM_UART1_R_TX")
	)
	(segment
		(start 344.539316 -308.454552)
		(end 343.674954 -308.454552)
		(width 0.10668)
		(layer "B.Cu")
		(net "UART_CPU0_SCM_UART1_R_TX")
	)
	(segment
		(start 345.783408 -306.59197)
		(end 344.539316 -308.454552)
		(width 0.10668)
		(layer "B.Cu")
		(net "UART_CPU0_SCM_UART1_R_TX")
	)
	(segment
		(start 343.684606 -305.800252)
		(end 343.113614 -306.371244)
		(width 0.10668)
		(layer "B.Cu")
		(net "UART_CPU0_SCM_UART1_R_TX")
	)
	(segment
		(start 345.76639 -306.506372)
		(end 345.783408 -306.59197)
		(width 0.10668)
		(layer "B.Cu")
		(net "UART_CPU0_SCM_UART1_R_TX")
	)
	(segment
		(start 343.482422 -308.153562)
		(end 343.592658 -308.372256)
		(width 0.10668)
		(layer "B.Cu")
		(net "UART_CPU0_SCM_UART1_R_TX")
	)
	(segment
		(start 343.674954 -308.454552)
		(end 343.592658 -308.372256)
		(width 0.10668)
		(layer "B.Cu")
		(net "UART_CPU0_SCM_UART1_R_TX")
	)
	(segment
		(start 343.43975 -304.92319)
		(end 343.684606 -305.168046)
		(width 0.10668)
		(layer "B.Cu")
		(net "UART_CPU0_SCM_UART1_R_TX")
	)
	(segment
		(start 343.113614 -306.371244)
		(end 343.113614 -307.057552)
		(width 0.10668)
		(layer "B.Cu")
		(net "UART_CPU0_SCM_UART1_R_TX")
	)
	(segment
		(start 343.684606 -305.168046)
		(end 343.684606 -305.800252)
		(width 0.10668)
		(layer "B.Cu")
		(net "UART_CPU0_SCM_UART1_R_TX")
	)
	(segment
		(start 339.535008 -305.812952)
		(end 339.535008 -305.097942)
		(width 0.10668)
		(layer "B.Cu")
		(net "UART_CPU0_SCM_UART1_R_TX")
	)
	(segment
		(start 367.931446 -39.843964)
		(end 367.931446 -41.305988)
		(width 0.10668)
		(layer "F.Cu")
		(net "UART_CPU0_SCM_UART1_R_RX")
	)
	(segment
		(start 368.241326 -42.835068)
		(end 368.241326 -41.615868)
		(width 0.10668)
		(layer "F.Cu")
		(net "UART_CPU0_SCM_UART1_R_RX")
	)
	(segment
		(start 367.931446 -41.305988)
		(end 368.241326 -41.615868)
		(width 0.10668)
		(layer "F.Cu")
		(net "UART_CPU0_SCM_UART1_R_RX")
	)
	(via
		(at 368.241326 -41.615868)
		(size 0.762)
		(drill 0.381)
		(layers "F.Cu" "B.Cu")
		(net "UART_CPU0_SCM_UART1_R_RX")
	)
	(segment
		(start 345.113102 -306.265326)
		(end 346.704158 -304.67427)
		(width 0.10668)
		(layer "F.Cu")
		(net "UART_CPU0_SCM_UART1_RX")
	)
	(segment
		(start 368.241326 -44.251118)
		(end 368.241326 -43.635168)
		(width 0.10668)
		(layer "F.Cu")
		(net "UART_CPU0_SCM_UART1_RX")
	)
	(segment
		(start 345.113102 -306.808632)
		(end 345.113102 -306.265326)
		(width 0.10668)
		(layer "F.Cu")
		(net "UART_CPU0_SCM_UART1_RX")
	)
	(segment
		(start 345.916504 -307.612034)
		(end 345.113102 -306.808632)
		(width 0.10668)
		(layer "F.Cu")
		(net "UART_CPU0_SCM_UART1_RX")
	)
	(segment
		(start 274.338034 -165.866064)
		(end 269.608808 -170.59529)
		(width 0.10668)
		(layer "F.Cu")
		(net "UART_CPU0_SCM_UART1_RX")
	)
	(segment
		(start 346.704158 -304.67427)
		(end 353.007422 -304.67427)
		(width 0.10668)
		(layer "F.Cu")
		(net "UART_CPU0_SCM_UART1_RX")
	)
	(segment
		(start 368.241326 -44.867068)
		(end 368.241326 -44.251118)
		(width 0.10668)
		(layer "F.Cu")
		(net "UART_CPU0_SCM_UART1_RX")
	)
	(segment
		(start 346.15374 -307.612034)
		(end 345.916504 -307.612034)
		(width 0.10668)
		(layer "F.Cu")
		(net "UART_CPU0_SCM_UART1_RX")
	)
	(segment
		(start 275.153374 -165.506654)
		(end 274.793964 -165.866064)
		(width 0.10668)
		(layer "F.Cu")
		(net "UART_CPU0_SCM_UART1_RX")
	)
	(segment
		(start 269.608808 -186.943238)
		(end 269.701518 -187.035948)
		(width 0.10668)
		(layer "F.Cu")
		(net "UART_CPU0_SCM_UART1_RX")
	)
	(segment
		(start 360.467402 -297.21429)
		(end 363.694726 -297.21429)
		(width 0.10668)
		(layer "F.Cu")
		(net "UART_CPU0_SCM_UART1_RX")
	)
	(segment
		(start 269.608808 -170.59529)
		(end 269.608808 -186.943238)
		(width 0.10668)
		(layer "F.Cu")
		(net "UART_CPU0_SCM_UART1_RX")
	)
	(segment
		(start 274.793964 -165.866064)
		(end 274.338034 -165.866064)
		(width 0.10668)
		(layer "F.Cu")
		(net "UART_CPU0_SCM_UART1_RX")
	)
	(segment
		(start 364.717838 -296.191178)
		(end 364.717838 -294.88003)
		(width 0.10668)
		(layer "F.Cu")
		(net "UART_CPU0_SCM_UART1_RX")
	)
	(segment
		(start 363.694726 -297.21429)
		(end 364.717838 -296.191178)
		(width 0.10668)
		(layer "F.Cu")
		(net "UART_CPU0_SCM_UART1_RX")
	)
	(segment
		(start 353.007422 -304.67427)
		(end 360.467402 -297.21429)
		(width 0.10668)
		(layer "F.Cu")
		(net "UART_CPU0_SCM_UART1_RX")
	)
	(via
		(at 269.701518 -187.035948)
		(size 0.508)
		(drill 0.254)
		(layers "F.Cu" "B.Cu")
		(net "UART_CPU0_SCM_UART1_RX")
	)
	(via
		(at 368.241326 -44.251118)
		(size 0.508)
		(drill 0.254)
		(layers "F.Cu" "B.Cu")
		(net "UART_CPU0_SCM_UART1_RX")
	)
	(via
		(at 346.15374 -307.612034)
		(size 0.508)
		(drill 0.254)
		(layers "F.Cu" "B.Cu")
		(net "UART_CPU0_SCM_UART1_RX")
	)
	(via
		(at 275.153374 -165.506654)
		(size 0.508)
		(drill 0.254)
		(layers "F.Cu" "B.Cu")
		(net "UART_CPU0_SCM_UART1_RX")
	)
	(segment
		(start 307.48097 -316.800738)
		(end 315.168788 -309.11292)
		(width 0.10668)
		(layer "B.Cu")
		(net "UART_CPU0_SCM_UART1_RX")
	)
	(segment
		(start 302.886364 -320.019172)
		(end 303.69383 -320.019172)
		(width 0.10668)
		(layer "B.Cu")
		(net "UART_CPU0_SCM_UART1_RX")
	)
	(segment
		(start 346.446856 -307.612034)
		(end 346.15374 -307.612034)
		(width 0.10668)
		(layer "B.Cu")
		(net "UART_CPU0_SCM_UART1_RX")
	)
	(segment
		(start 267.87729 -188.860176)
		(end 264.490454 -188.860176)
		(width 0.10668)
		(layer "B.Cu")
		(net "UART_CPU0_SCM_UART1_RX")
	)
	(segment
		(start 346.9894 -306.286408)
		(end 346.9894 -307.06949)
		(width 0.10668)
		(layer "B.Cu")
		(net "UART_CPU0_SCM_UART1_RX")
	)
	(segment
		(start 261.574788 -322.20027)
		(end 300.705266 -322.20027)
		(width 0.10668)
		(layer "B.Cu")
		(net "UART_CPU0_SCM_UART1_RX")
	)
	(segment
		(start 260.73862 -221.859602)
		(end 260.73862 -320.41338)
		(width 0.10668)
		(layer "B.Cu")
		(net "UART_CPU0_SCM_UART1_RX")
	)
	(segment
		(start 346.9894 -307.06949)
		(end 346.446856 -307.612034)
		(width 0.10668)
		(layer "B.Cu")
		(net "UART_CPU0_SCM_UART1_RX")
	)
	(segment
		(start 260.731 -320.421)
		(end 260.731 -321.356482)
		(width 0.10668)
		(layer "B.Cu")
		(net "UART_CPU0_SCM_UART1_RX")
	)
	(segment
		(start 263.748266 -189.602364)
		(end 257.708654 -189.602364)
		(width 0.10668)
		(layer "B.Cu")
		(net "UART_CPU0_SCM_UART1_RX")
	)
	(segment
		(start 300.705266 -322.20027)
		(end 302.886364 -320.019172)
		(width 0.10668)
		(layer "B.Cu")
		(net "UART_CPU0_SCM_UART1_RX")
	)
	(segment
		(start 306.912264 -316.800738)
		(end 307.48097 -316.800738)
		(width 0.10668)
		(layer "B.Cu")
		(net "UART_CPU0_SCM_UART1_RX")
	)
	(segment
		(start 254.76962 -215.890602)
		(end 260.73862 -221.859602)
		(width 0.10668)
		(layer "B.Cu")
		(net "UART_CPU0_SCM_UART1_RX")
	)
	(segment
		(start 331.087222 -309.11292)
		(end 335.99247 -304.207672)
		(width 0.10668)
		(layer "B.Cu")
		(net "UART_CPU0_SCM_UART1_RX")
	)
	(segment
		(start 315.168788 -309.11292)
		(end 331.087222 -309.11292)
		(width 0.10668)
		(layer "B.Cu")
		(net "UART_CPU0_SCM_UART1_RX")
	)
	(segment
		(start 344.910664 -304.207672)
		(end 346.9894 -306.286408)
		(width 0.10668)
		(layer "B.Cu")
		(net "UART_CPU0_SCM_UART1_RX")
	)
	(segment
		(start 254.76962 -192.541398)
		(end 254.76962 -215.890602)
		(width 0.10668)
		(layer "B.Cu")
		(net "UART_CPU0_SCM_UART1_RX")
	)
	(segment
		(start 264.490454 -188.860176)
		(end 263.748266 -189.602364)
		(width 0.10668)
		(layer "B.Cu")
		(net "UART_CPU0_SCM_UART1_RX")
	)
	(segment
		(start 269.701518 -187.035948)
		(end 267.87729 -188.860176)
		(width 0.10668)
		(layer "B.Cu")
		(net "UART_CPU0_SCM_UART1_RX")
	)
	(segment
		(start 257.708654 -189.602364)
		(end 254.76962 -192.541398)
		(width 0.10668)
		(layer "B.Cu")
		(net "UART_CPU0_SCM_UART1_RX")
	)
	(segment
		(start 260.73862 -320.41338)
		(end 260.731 -320.421)
		(width 0.10668)
		(layer "B.Cu")
		(net "UART_CPU0_SCM_UART1_RX")
	)
	(segment
		(start 335.99247 -304.207672)
		(end 344.910664 -304.207672)
		(width 0.10668)
		(layer "B.Cu")
		(net "UART_CPU0_SCM_UART1_RX")
	)
	(segment
		(start 260.731 -321.356482)
		(end 261.574788 -322.20027)
		(width 0.10668)
		(layer "B.Cu")
		(net "UART_CPU0_SCM_UART1_RX")
	)
	(segment
		(start 303.69383 -320.019172)
		(end 306.912264 -316.800738)
		(width 0.10668)
		(layer "B.Cu")
		(net "UART_CPU0_SCM_UART1_RX")
	)
	(segment
		(start 275.162772 -165.506654)
		(end 279.978104 -160.691322)
		(width 0.11684)
		(layer "In4.Cu")
		(net "UART_CPU0_SCM_UART1_RX")
	)
	(segment
		(start 318.76492 -104.41178)
		(end 318.76492 -102.022148)
		(width 0.11684)
		(layer "In4.Cu")
		(net "UART_CPU0_SCM_UART1_RX")
	)
	(segment
		(start 348.430596 -60.467748)
		(end 365.684054 -43.21429)
		(width 0.11684)
		(layer "In4.Cu")
		(net "UART_CPU0_SCM_UART1_RX")
	)
	(segment
		(start 305.382168 -143.40459)
		(end 306.905406 -141.881352)
		(width 0.11684)
		(layer "In4.Cu")
		(net "UART_CPU0_SCM_UART1_RX")
	)
	(segment
		(start 298.780708 -143.40459)
		(end 305.382168 -143.40459)
		(width 0.11684)
		(layer "In4.Cu")
		(net "UART_CPU0_SCM_UART1_RX")
	)
	(segment
		(start 345.278202 -75.508866)
		(end 347.667834 -75.508866)
		(width 0.11684)
		(layer "In4.Cu")
		(net "UART_CPU0_SCM_UART1_RX")
	)
	(segment
		(start 368.241326 -43.866562)
		(end 368.241326 -44.251118)
		(width 0.11684)
		(layer "In4.Cu")
		(net "UART_CPU0_SCM_UART1_RX")
	)
	(segment
		(start 347.667834 -75.508866)
		(end 348.430596 -74.746104)
		(width 0.11684)
		(layer "In4.Cu")
		(net "UART_CPU0_SCM_UART1_RX")
	)
	(segment
		(start 284.951424 -156.615384)
		(end 284.951424 -152.524206)
		(width 0.11684)
		(layer "In4.Cu")
		(net "UART_CPU0_SCM_UART1_RX")
	)
	(segment
		(start 306.905406 -141.881352)
		(end 314.682886 -123.104656)
		(width 0.11684)
		(layer "In4.Cu")
		(net "UART_CPU0_SCM_UART1_RX")
	)
	(segment
		(start 290.51885 -146.95678)
		(end 295.228518 -146.95678)
		(width 0.11684)
		(layer "In4.Cu")
		(net "UART_CPU0_SCM_UART1_RX")
	)
	(segment
		(start 365.684054 -43.21429)
		(end 367.589054 -43.21429)
		(width 0.11684)
		(layer "In4.Cu")
		(net "UART_CPU0_SCM_UART1_RX")
	)
	(segment
		(start 295.228518 -146.95678)
		(end 298.780708 -143.40459)
		(width 0.11684)
		(layer "In4.Cu")
		(net "UART_CPU0_SCM_UART1_RX")
	)
	(segment
		(start 279.978104 -160.691322)
		(end 280.875486 -160.691322)
		(width 0.11684)
		(layer "In4.Cu")
		(net "UART_CPU0_SCM_UART1_RX")
	)
	(segment
		(start 275.153374 -165.506654)
		(end 275.162772 -165.506654)
		(width 0.11684)
		(layer "In4.Cu")
		(net "UART_CPU0_SCM_UART1_RX")
	)
	(segment
		(start 314.682886 -123.104656)
		(end 314.682886 -108.493814)
		(width 0.11684)
		(layer "In4.Cu")
		(net "UART_CPU0_SCM_UART1_RX")
	)
	(segment
		(start 284.951424 -152.524206)
		(end 290.51885 -146.95678)
		(width 0.11684)
		(layer "In4.Cu")
		(net "UART_CPU0_SCM_UART1_RX")
	)
	(segment
		(start 367.589054 -43.21429)
		(end 368.241326 -43.866562)
		(width 0.11684)
		(layer "In4.Cu")
		(net "UART_CPU0_SCM_UART1_RX")
	)
	(segment
		(start 314.682886 -108.493814)
		(end 318.76492 -104.41178)
		(width 0.11684)
		(layer "In4.Cu")
		(net "UART_CPU0_SCM_UART1_RX")
	)
	(segment
		(start 348.430596 -74.746104)
		(end 348.430596 -60.467748)
		(width 0.11684)
		(layer "In4.Cu")
		(net "UART_CPU0_SCM_UART1_RX")
	)
	(segment
		(start 318.76492 -102.022148)
		(end 345.278202 -75.508866)
		(width 0.11684)
		(layer "In4.Cu")
		(net "UART_CPU0_SCM_UART1_RX")
	)
	(segment
		(start 280.875486 -160.691322)
		(end 284.951424 -156.615384)
		(width 0.11684)
		(layer "In4.Cu")
		(net "UART_CPU0_SCM_UART1_RX")
	)
	(segment
		(start 309.103522 -21.785834)
		(end 313.284616 -17.60474)
		(width 0.10668)
		(layer "F.Cu")
		(net "UART_CPU0_SCM_LVC3_UART1_TX")
	)
	(segment
		(start 369.455446 -29.684472)
		(end 369.455446 -28.706572)
		(width 0.10668)
		(layer "F.Cu")
		(net "UART_CPU0_SCM_LVC3_UART1_TX")
	)
	(segment
		(start 306.305966 -22.065488)
		(end 306.58562 -21.785834)
		(width 0.10668)
		(layer "F.Cu")
		(net "UART_CPU0_SCM_LVC3_UART1_TX")
	)
	(segment
		(start 185.26252 -19.835622)
		(end 185.26252 -20.451572)
		(width 0.10668)
		(layer "F.Cu")
		(net "UART_CPU0_SCM_LVC3_UART1_TX")
	)
	(segment
		(start 369.455446 -28.706572)
		(end 368.81816 -28.706572)
		(width 0.10668)
		(layer "F.Cu")
		(net "UART_CPU0_SCM_LVC3_UART1_TX")
	)
	(segment
		(start 308.757574 -21.785834)
		(end 309.103522 -21.785834)
		(width 0.10668)
		(layer "F.Cu")
		(net "UART_CPU0_SCM_LVC3_UART1_TX")
	)
	(segment
		(start 306.58562 -21.785834)
		(end 308.757574 -21.785834)
		(width 0.10668)
		(layer "F.Cu")
		(net "UART_CPU0_SCM_LVC3_UART1_TX")
	)
	(segment
		(start 313.284616 -17.60474)
		(end 313.284616 -15.337536)
		(width 0.10668)
		(layer "F.Cu")
		(net "UART_CPU0_SCM_LVC3_UART1_TX")
	)
	(via
		(at 368.81816 -28.706572)
		(size 0.508)
		(drill 0.254)
		(layers "F.Cu" "B.Cu")
		(net "UART_CPU0_SCM_LVC3_UART1_TX")
	)
	(via
		(at 185.26252 -20.451572)
		(size 0.508)
		(drill 0.254)
		(layers "F.Cu" "B.Cu")
		(net "UART_CPU0_SCM_LVC3_UART1_TX")
	)
	(via
		(at 306.305966 -22.065488)
		(size 0.508)
		(drill 0.254)
		(layers "F.Cu" "B.Cu")
		(net "UART_CPU0_SCM_LVC3_UART1_TX")
	)
	(segment
		(start 337.158076 -27.736546)
		(end 349.54591 -27.736546)
		(width 0.11684)
		(layer "In2.Cu")
		(net "UART_CPU0_SCM_LVC3_UART1_TX")
	)
	(segment
		(start 309.29834 -22.065488)
		(end 311.640982 -19.722846)
		(width 0.11684)
		(layer "In2.Cu")
		(net "UART_CPU0_SCM_LVC3_UART1_TX")
	)
	(segment
		(start 329.313794 -21.966428)
		(end 331.387958 -21.966428)
		(width 0.11684)
		(layer "In2.Cu")
		(net "UART_CPU0_SCM_LVC3_UART1_TX")
	)
	(segment
		(start 351.04451 -26.237946)
		(end 367.755424 -26.237946)
		(width 0.11684)
		(layer "In2.Cu")
		(net "UART_CPU0_SCM_LVC3_UART1_TX")
	)
	(segment
		(start 327.070212 -19.722846)
		(end 329.313794 -21.966428)
		(width 0.11684)
		(layer "In2.Cu")
		(net "UART_CPU0_SCM_LVC3_UART1_TX")
	)
	(segment
		(start 306.305966 -22.065488)
		(end 309.29834 -22.065488)
		(width 0.11684)
		(layer "In2.Cu")
		(net "UART_CPU0_SCM_LVC3_UART1_TX")
	)
	(segment
		(start 349.54591 -27.736546)
		(end 351.04451 -26.237946)
		(width 0.11684)
		(layer "In2.Cu")
		(net "UART_CPU0_SCM_LVC3_UART1_TX")
	)
	(segment
		(start 367.755424 -26.237946)
		(end 368.81816 -27.300682)
		(width 0.11684)
		(layer "In2.Cu")
		(net "UART_CPU0_SCM_LVC3_UART1_TX")
	)
	(segment
		(start 331.387958 -21.966428)
		(end 337.158076 -27.736546)
		(width 0.11684)
		(layer "In2.Cu")
		(net "UART_CPU0_SCM_LVC3_UART1_TX")
	)
	(segment
		(start 368.81816 -27.300682)
		(end 368.81816 -28.706572)
		(width 0.11684)
		(layer "In2.Cu")
		(net "UART_CPU0_SCM_LVC3_UART1_TX")
	)
	(segment
		(start 311.640982 -19.722846)
		(end 327.070212 -19.722846)
		(width 0.11684)
		(layer "In2.Cu")
		(net "UART_CPU0_SCM_LVC3_UART1_TX")
	)
	(segment
		(start 262.675878 -40.923972)
		(end 274.475702 -40.923972)
		(width 0.11684)
		(layer "In6.Cu")
		(net "UART_CPU0_SCM_LVC3_UART1_TX")
	)
	(segment
		(start 222.188024 -39.095934)
		(end 230.542084 -39.095934)
		(width 0.11684)
		(layer "In6.Cu")
		(net "UART_CPU0_SCM_LVC3_UART1_TX")
	)
	(segment
		(start 192.041272 -34.922968)
		(end 204.898244 -34.922968)
		(width 0.11684)
		(layer "In6.Cu")
		(net "UART_CPU0_SCM_LVC3_UART1_TX")
	)
	(segment
		(start 242.963446 -42.4815)
		(end 247.036844 -38.408102)
		(width 0.11684)
		(layer "In6.Cu")
		(net "UART_CPU0_SCM_LVC3_UART1_TX")
	)
	(segment
		(start 185.26252 -20.451572)
		(end 185.26252 -21.54428)
		(width 0.11684)
		(layer "In6.Cu")
		(net "UART_CPU0_SCM_LVC3_UART1_TX")
	)
	(segment
		(start 219.61221 -36.52012)
		(end 222.188024 -39.095934)
		(width 0.11684)
		(layer "In6.Cu")
		(net "UART_CPU0_SCM_LVC3_UART1_TX")
	)
	(segment
		(start 204.898244 -34.922968)
		(end 208.282794 -31.538418)
		(width 0.11684)
		(layer "In6.Cu")
		(net "UART_CPU0_SCM_LVC3_UART1_TX")
	)
	(segment
		(start 294.254936 -21.144738)
		(end 305.385216 -21.144738)
		(width 0.11684)
		(layer "In6.Cu")
		(net "UART_CPU0_SCM_LVC3_UART1_TX")
	)
	(segment
		(start 235.564934 -42.4815)
		(end 242.963446 -42.4815)
		(width 0.11684)
		(layer "In6.Cu")
		(net "UART_CPU0_SCM_LVC3_UART1_TX")
	)
	(segment
		(start 187.61456 -27.88031)
		(end 187.61456 -30.496256)
		(width 0.11684)
		(layer "In6.Cu")
		(net "UART_CPU0_SCM_LVC3_UART1_TX")
	)
	(segment
		(start 256.366518 -38.408102)
		(end 257.694176 -39.73576)
		(width 0.11684)
		(layer "In6.Cu")
		(net "UART_CPU0_SCM_LVC3_UART1_TX")
	)
	(segment
		(start 218.497404 -31.538418)
		(end 219.61221 -32.653224)
		(width 0.11684)
		(layer "In6.Cu")
		(net "UART_CPU0_SCM_LVC3_UART1_TX")
	)
	(segment
		(start 261.487666 -39.73576)
		(end 262.675878 -40.923972)
		(width 0.11684)
		(layer "In6.Cu")
		(net "UART_CPU0_SCM_LVC3_UART1_TX")
	)
	(segment
		(start 305.385216 -21.144738)
		(end 306.305966 -22.065488)
		(width 0.11684)
		(layer "In6.Cu")
		(net "UART_CPU0_SCM_LVC3_UART1_TX")
	)
	(segment
		(start 208.282794 -31.538418)
		(end 218.497404 -31.538418)
		(width 0.11684)
		(layer "In6.Cu")
		(net "UART_CPU0_SCM_LVC3_UART1_TX")
	)
	(segment
		(start 186.08548 -23.83282)
		(end 186.08548 -26.35123)
		(width 0.11684)
		(layer "In6.Cu")
		(net "UART_CPU0_SCM_LVC3_UART1_TX")
	)
	(segment
		(start 219.61221 -32.653224)
		(end 219.61221 -36.52012)
		(width 0.11684)
		(layer "In6.Cu")
		(net "UART_CPU0_SCM_LVC3_UART1_TX")
	)
	(segment
		(start 257.694176 -39.73576)
		(end 261.487666 -39.73576)
		(width 0.11684)
		(layer "In6.Cu")
		(net "UART_CPU0_SCM_LVC3_UART1_TX")
	)
	(segment
		(start 186.41568 -23.50262)
		(end 186.08548 -23.83282)
		(width 0.11684)
		(layer "In6.Cu")
		(net "UART_CPU0_SCM_LVC3_UART1_TX")
	)
	(segment
		(start 247.036844 -38.408102)
		(end 256.366518 -38.408102)
		(width 0.11684)
		(layer "In6.Cu")
		(net "UART_CPU0_SCM_LVC3_UART1_TX")
	)
	(segment
		(start 233.951018 -40.867584)
		(end 235.564934 -42.4815)
		(width 0.11684)
		(layer "In6.Cu")
		(net "UART_CPU0_SCM_LVC3_UART1_TX")
	)
	(segment
		(start 187.61456 -30.496256)
		(end 192.041272 -34.922968)
		(width 0.11684)
		(layer "In6.Cu")
		(net "UART_CPU0_SCM_LVC3_UART1_TX")
	)
	(segment
		(start 230.542084 -39.095934)
		(end 232.313734 -40.867584)
		(width 0.11684)
		(layer "In6.Cu")
		(net "UART_CPU0_SCM_LVC3_UART1_TX")
	)
	(segment
		(start 185.26252 -21.54428)
		(end 186.41568 -22.69744)
		(width 0.11684)
		(layer "In6.Cu")
		(net "UART_CPU0_SCM_LVC3_UART1_TX")
	)
	(segment
		(start 274.475702 -40.923972)
		(end 294.254936 -21.144738)
		(width 0.11684)
		(layer "In6.Cu")
		(net "UART_CPU0_SCM_LVC3_UART1_TX")
	)
	(segment
		(start 186.08548 -26.35123)
		(end 187.61456 -27.88031)
		(width 0.11684)
		(layer "In6.Cu")
		(net "UART_CPU0_SCM_LVC3_UART1_TX")
	)
	(segment
		(start 186.41568 -22.69744)
		(end 186.41568 -23.50262)
		(width 0.11684)
		(layer "In6.Cu")
		(net "UART_CPU0_SCM_LVC3_UART1_TX")
	)
	(segment
		(start 232.313734 -40.867584)
		(end 233.951018 -40.867584)
		(width 0.11684)
		(layer "In6.Cu")
		(net "UART_CPU0_SCM_LVC3_UART1_TX")
	)
	(segment
		(start 368.581432 -31.71063)
		(end 368.581432 -30.759908)
		(width 0.10668)
		(layer "F.Cu")
		(net "UART_CPU0_SCM_LVC3_UART1_R_TX")
	)
	(segment
		(start 368.53241 -31.759652)
		(end 368.581432 -31.71063)
		(width 0.10668)
		(layer "F.Cu")
		(net "UART_CPU0_SCM_LVC3_UART1_R_TX")
	)
	(segment
		(start 368.856768 -30.484572)
		(end 369.455446 -30.484572)
		(width 0.10668)
		(layer "F.Cu")
		(net "UART_CPU0_SCM_LVC3_UART1_R_TX")
	)
	(segment
		(start 368.581432 -31.808674)
		(end 368.53241 -31.759652)
		(width 0.10668)
		(layer "F.Cu")
		(net "UART_CPU0_SCM_LVC3_UART1_R_TX")
	)
	(segment
		(start 368.581432 -34.243772)
		(end 368.581432 -31.808674)
		(width 0.10668)
		(layer "F.Cu")
		(net "UART_CPU0_SCM_LVC3_UART1_R_TX")
	)
	(segment
		(start 368.581432 -30.759908)
		(end 368.856768 -30.484572)
		(width 0.10668)
		(layer "F.Cu")
		(net "UART_CPU0_SCM_LVC3_UART1_R_TX")
	)
	(via
		(at 368.53241 -31.759652)
		(size 0.762)
		(drill 0.381)
		(layers "F.Cu" "B.Cu")
		(net "UART_CPU0_SCM_LVC3_UART1_R_TX")
	)
	(segment
		(start 310.75757 -21.785834)
		(end 311.992772 -21.785834)
		(width 0.10668)
		(layer "F.Cu")
		(net "UART_CPU0_SCM_LVC3_UART1_R_RX")
	)
	(segment
		(start 367.931446 -30.535372)
		(end 367.931446 -34.243772)
		(width 0.10668)
		(layer "F.Cu")
		(net "UART_CPU0_SCM_LVC3_UART1_R_RX")
	)
	(segment
		(start 311.992772 -21.785834)
		(end 314.647326 -19.13128)
		(width 0.10668)
		(layer "F.Cu")
		(net "UART_CPU0_SCM_LVC3_UART1_R_RX")
	)
	(segment
		(start 367.931446 -30.535372)
		(end 367.29416 -30.535372)
		(width 0.10668)
		(layer "F.Cu")
		(net "UART_CPU0_SCM_LVC3_UART1_R_RX")
	)
	(segment
		(start 315.284612 -18.493994)
		(end 314.647326 -19.13128)
		(width 0.10668)
		(layer "F.Cu")
		(net "UART_CPU0_SCM_LVC3_UART1_R_RX")
	)
	(segment
		(start 186.53252 -19.835622)
		(end 186.53252 -20.451572)
		(width 0.10668)
		(layer "F.Cu")
		(net "UART_CPU0_SCM_LVC3_UART1_R_RX")
	)
	(segment
		(start 315.284612 -15.337536)
		(end 315.284612 -18.493994)
		(width 0.10668)
		(layer "F.Cu")
		(net "UART_CPU0_SCM_LVC3_UART1_R_RX")
	)
	(via
		(at 314.647326 -19.13128)
		(size 0.508)
		(drill 0.254)
		(layers "F.Cu" "B.Cu")
		(net "UART_CPU0_SCM_LVC3_UART1_R_RX")
	)
	(via
		(at 367.29416 -30.535372)
		(size 0.508)
		(drill 0.254)
		(layers "F.Cu" "B.Cu")
		(net "UART_CPU0_SCM_LVC3_UART1_R_RX")
	)
	(via
		(at 186.53252 -20.451572)
		(size 0.508)
		(drill 0.254)
		(layers "F.Cu" "B.Cu")
		(net "UART_CPU0_SCM_LVC3_UART1_R_RX")
	)
	(segment
		(start 314.647326 -19.13128)
		(end 327.075038 -19.13128)
		(width 0.11684)
		(layer "In2.Cu")
		(net "UART_CPU0_SCM_LVC3_UART1_R_RX")
	)
	(segment
		(start 367.312956 -30.554168)
		(end 367.29416 -30.535372)
		(width 0.11684)
		(layer "In2.Cu")
		(net "UART_CPU0_SCM_LVC3_UART1_R_RX")
	)
	(segment
		(start 350.326706 -26.143712)
		(end 350.654112 -25.816306)
		(width 0.11684)
		(layer "In2.Cu")
		(net "UART_CPU0_SCM_LVC3_UART1_R_RX")
	)
	(segment
		(start 327.075038 -19.13128)
		(end 329.359514 -21.415756)
		(width 0.11684)
		(layer "In2.Cu")
		(net "UART_CPU0_SCM_LVC3_UART1_R_RX")
	)
	(segment
		(start 368.803682 -25.816306)
		(end 369.971066 -26.98369)
		(width 0.11684)
		(layer "In2.Cu")
		(net "UART_CPU0_SCM_LVC3_UART1_R_RX")
	)
	(segment
		(start 329.359514 -21.415756)
		(end 331.989176 -21.415756)
		(width 0.11684)
		(layer "In2.Cu")
		(net "UART_CPU0_SCM_LVC3_UART1_R_RX")
	)
	(segment
		(start 331.989176 -21.415756)
		(end 336.717132 -26.143712)
		(width 0.11684)
		(layer "In2.Cu")
		(net "UART_CPU0_SCM_LVC3_UART1_R_RX")
	)
	(segment
		(start 369.971066 -28.860496)
		(end 368.277394 -30.554168)
		(width 0.11684)
		(layer "In2.Cu")
		(net "UART_CPU0_SCM_LVC3_UART1_R_RX")
	)
	(segment
		(start 369.971066 -26.98369)
		(end 369.971066 -28.860496)
		(width 0.11684)
		(layer "In2.Cu")
		(net "UART_CPU0_SCM_LVC3_UART1_R_RX")
	)
	(segment
		(start 350.654112 -25.816306)
		(end 368.803682 -25.816306)
		(width 0.11684)
		(layer "In2.Cu")
		(net "UART_CPU0_SCM_LVC3_UART1_R_RX")
	)
	(segment
		(start 336.717132 -26.143712)
		(end 350.326706 -26.143712)
		(width 0.11684)
		(layer "In2.Cu")
		(net "UART_CPU0_SCM_LVC3_UART1_R_RX")
	)
	(segment
		(start 368.277394 -30.554168)
		(end 367.312956 -30.554168)
		(width 0.11684)
		(layer "In2.Cu")
		(net "UART_CPU0_SCM_LVC3_UART1_R_RX")
	)
	(segment
		(start 300.177962 -18.504916)
		(end 314.020962 -18.504916)
		(width 0.11684)
		(layer "In6.Cu")
		(net "UART_CPU0_SCM_LVC3_UART1_R_RX")
	)
	(segment
		(start 188.94044 -28.32608)
		(end 188.94044 -30.455362)
		(width 0.11684)
		(layer "In6.Cu")
		(net "UART_CPU0_SCM_LVC3_UART1_R_RX")
	)
	(segment
		(start 238.16437 -41.613074)
		(end 240.91138 -41.613074)
		(width 0.11684)
		(layer "In6.Cu")
		(net "UART_CPU0_SCM_LVC3_UART1_R_RX")
	)
	(segment
		(start 220.491304 -32.288988)
		(end 220.491304 -36.155884)
		(width 0.11684)
		(layer "In6.Cu")
		(net "UART_CPU0_SCM_LVC3_UART1_R_RX")
	)
	(segment
		(start 314.020962 -18.504916)
		(end 314.647326 -19.13128)
		(width 0.11684)
		(layer "In6.Cu")
		(net "UART_CPU0_SCM_LVC3_UART1_R_RX")
	)
	(segment
		(start 189.16396 -24.77135)
		(end 189.217046 -24.824436)
		(width 0.11684)
		(layer "In6.Cu")
		(net "UART_CPU0_SCM_LVC3_UART1_R_RX")
	)
	(segment
		(start 240.91138 -41.613074)
		(end 244.959632 -37.564822)
		(width 0.11684)
		(layer "In6.Cu")
		(net "UART_CPU0_SCM_LVC3_UART1_R_RX")
	)
	(segment
		(start 258.260088 -37.74948)
		(end 261.481316 -37.74948)
		(width 0.11684)
		(layer "In6.Cu")
		(net "UART_CPU0_SCM_LVC3_UART1_R_RX")
	)
	(segment
		(start 222.444564 -38.109144)
		(end 236.145832 -38.109144)
		(width 0.11684)
		(layer "In6.Cu")
		(net "UART_CPU0_SCM_LVC3_UART1_R_RX")
	)
	(segment
		(start 189.217046 -24.824436)
		(end 189.217046 -28.049474)
		(width 0.11684)
		(layer "In6.Cu")
		(net "UART_CPU0_SCM_LVC3_UART1_R_RX")
	)
	(segment
		(start 263.538462 -35.692334)
		(end 278.086566 -35.692334)
		(width 0.11684)
		(layer "In6.Cu")
		(net "UART_CPU0_SCM_LVC3_UART1_R_RX")
	)
	(segment
		(start 218.86164 -30.659324)
		(end 220.491304 -32.288988)
		(width 0.11684)
		(layer "In6.Cu")
		(net "UART_CPU0_SCM_LVC3_UART1_R_RX")
	)
	(segment
		(start 237.377224 -40.825928)
		(end 238.16437 -41.613074)
		(width 0.11684)
		(layer "In6.Cu")
		(net "UART_CPU0_SCM_LVC3_UART1_R_RX")
	)
	(segment
		(start 220.491304 -36.155884)
		(end 222.444564 -38.109144)
		(width 0.11684)
		(layer "In6.Cu")
		(net "UART_CPU0_SCM_LVC3_UART1_R_RX")
	)
	(segment
		(start 261.481316 -37.74948)
		(end 263.538462 -35.692334)
		(width 0.11684)
		(layer "In6.Cu")
		(net "UART_CPU0_SCM_LVC3_UART1_R_RX")
	)
	(segment
		(start 298.544996 -20.137882)
		(end 300.177962 -18.504916)
		(width 0.11684)
		(layer "In6.Cu")
		(net "UART_CPU0_SCM_LVC3_UART1_R_RX")
	)
	(segment
		(start 186.53252 -20.451572)
		(end 187.887864 -20.451572)
		(width 0.11684)
		(layer "In6.Cu")
		(net "UART_CPU0_SCM_LVC3_UART1_R_RX")
	)
	(segment
		(start 237.377224 -39.340536)
		(end 237.377224 -40.825928)
		(width 0.11684)
		(layer "In6.Cu")
		(net "UART_CPU0_SCM_LVC3_UART1_R_RX")
	)
	(segment
		(start 278.086566 -35.692334)
		(end 293.641018 -20.137882)
		(width 0.11684)
		(layer "In6.Cu")
		(net "UART_CPU0_SCM_LVC3_UART1_R_RX")
	)
	(segment
		(start 192.460626 -33.975548)
		(end 204.602334 -33.975548)
		(width 0.11684)
		(layer "In6.Cu")
		(net "UART_CPU0_SCM_LVC3_UART1_R_RX")
	)
	(segment
		(start 187.887864 -20.451572)
		(end 189.16396 -21.727668)
		(width 0.11684)
		(layer "In6.Cu")
		(net "UART_CPU0_SCM_LVC3_UART1_R_RX")
	)
	(segment
		(start 244.959632 -37.564822)
		(end 258.07543 -37.564822)
		(width 0.11684)
		(layer "In6.Cu")
		(net "UART_CPU0_SCM_LVC3_UART1_R_RX")
	)
	(segment
		(start 189.16396 -21.727668)
		(end 189.16396 -24.77135)
		(width 0.11684)
		(layer "In6.Cu")
		(net "UART_CPU0_SCM_LVC3_UART1_R_RX")
	)
	(segment
		(start 293.641018 -20.137882)
		(end 298.544996 -20.137882)
		(width 0.11684)
		(layer "In6.Cu")
		(net "UART_CPU0_SCM_LVC3_UART1_R_RX")
	)
	(segment
		(start 207.918558 -30.659324)
		(end 218.86164 -30.659324)
		(width 0.11684)
		(layer "In6.Cu")
		(net "UART_CPU0_SCM_LVC3_UART1_R_RX")
	)
	(segment
		(start 189.217046 -28.049474)
		(end 188.94044 -28.32608)
		(width 0.11684)
		(layer "In6.Cu")
		(net "UART_CPU0_SCM_LVC3_UART1_R_RX")
	)
	(segment
		(start 258.07543 -37.564822)
		(end 258.260088 -37.74948)
		(width 0.11684)
		(layer "In6.Cu")
		(net "UART_CPU0_SCM_LVC3_UART1_R_RX")
	)
	(segment
		(start 204.602334 -33.975548)
		(end 207.918558 -30.659324)
		(width 0.11684)
		(layer "In6.Cu")
		(net "UART_CPU0_SCM_LVC3_UART1_R_RX")
	)
	(segment
		(start 236.145832 -38.109144)
		(end 237.377224 -39.340536)
		(width 0.11684)
		(layer "In6.Cu")
		(net "UART_CPU0_SCM_LVC3_UART1_R_RX")
	)
	(segment
		(start 188.94044 -30.455362)
		(end 192.460626 -33.975548)
		(width 0.11684)
		(layer "In6.Cu")
		(net "UART_CPU0_SCM_LVC3_UART1_R_RX")
	)
	(segment
		(start 367.504726 -28.304744)
		(end 368.060478 -28.304744)
		(width 0.10668)
		(layer "F.Cu")
		(net "UART_CPU0_LVC3_UART0_TX")
	)
	(segment
		(start 366.534446 -28.706572)
		(end 367.102898 -28.706572)
		(width 0.10668)
		(layer "F.Cu")
		(net "UART_CPU0_LVC3_UART0_TX")
	)
	(segment
		(start 368.483642 -25.950672)
		(end 367.518442 -24.985472)
		(width 0.10668)
		(layer "F.Cu")
		(net "UART_CPU0_LVC3_UART0_TX")
	)
	(segment
		(start 366.534446 -29.684472)
		(end 366.534446 -28.706572)
		(width 0.10668)
		(layer "F.Cu")
		(net "UART_CPU0_LVC3_UART0_TX")
	)
	(segment
		(start 368.483642 -27.88158)
		(end 368.483642 -26.32837)
		(width 0.10668)
		(layer "F.Cu")
		(net "UART_CPU0_LVC3_UART0_TX")
	)
	(segment
		(start 367.102898 -28.706572)
		(end 367.504726 -28.304744)
		(width 0.10668)
		(layer "F.Cu")
		(net "UART_CPU0_LVC3_UART0_TX")
	)
	(segment
		(start 368.483642 -26.32837)
		(end 368.483642 -25.950672)
		(width 0.10668)
		(layer "F.Cu")
		(net "UART_CPU0_LVC3_UART0_TX")
	)
	(segment
		(start 367.518442 -24.985472)
		(end 367.518442 -22.207728)
		(width 0.10668)
		(layer "F.Cu")
		(net "UART_CPU0_LVC3_UART0_TX")
	)
	(segment
		(start 368.060478 -28.304744)
		(end 368.483642 -27.88158)
		(width 0.10668)
		(layer "F.Cu")
		(net "UART_CPU0_LVC3_UART0_TX")
	)
	(via
		(at 368.483642 -26.32837)
		(size 0.762)
		(drill 0.381)
		(layers "F.Cu" "B.Cu")
		(net "UART_CPU0_LVC3_UART0_TX")
	)
	(segment
		(start 367.281206 -32.323532)
		(end 366.661446 -31.703772)
		(width 0.10668)
		(layer "F.Cu")
		(net "UART_CPU0_LVC3_UART0_R_TX")
	)
	(segment
		(start 366.661446 -30.611572)
		(end 366.661446 -31.703772)
		(width 0.10668)
		(layer "F.Cu")
		(net "UART_CPU0_LVC3_UART0_R_TX")
	)
	(segment
		(start 366.534446 -30.484572)
		(end 366.661446 -30.611572)
		(width 0.10668)
		(layer "F.Cu")
		(net "UART_CPU0_LVC3_UART0_R_TX")
	)
	(segment
		(start 367.281206 -34.243772)
		(end 367.281206 -32.323532)
		(width 0.10668)
		(layer "F.Cu")
		(net "UART_CPU0_LVC3_UART0_R_TX")
	)
	(via
		(at 366.661446 -31.703772)
		(size 0.762)
		(drill 0.381)
		(layers "F.Cu" "B.Cu")
		(net "UART_CPU0_LVC3_UART0_R_TX")
	)
	(segment
		(start 365.391446 -30.611572)
		(end 365.391446 -31.703772)
		(width 0.10668)
		(layer "F.Cu")
		(net "UART_CPU0_LVC3_UART0_R_RX")
	)
	(segment
		(start 366.63122 -32.943546)
		(end 365.391446 -31.703772)
		(width 0.10668)
		(layer "F.Cu")
		(net "UART_CPU0_LVC3_UART0_R_RX")
	)
	(segment
		(start 366.63122 -34.243772)
		(end 366.63122 -32.943546)
		(width 0.10668)
		(layer "F.Cu")
		(net "UART_CPU0_LVC3_UART0_R_RX")
	)
	(segment
		(start 365.518446 -30.484572)
		(end 365.391446 -30.611572)
		(width 0.10668)
		(layer "F.Cu")
		(net "UART_CPU0_LVC3_UART0_R_RX")
	)
	(via
		(at 365.391446 -31.703772)
		(size 0.762)
		(drill 0.381)
		(layers "F.Cu" "B.Cu")
		(net "UART_CPU0_LVC3_UART0_R_RX")
	)
	(segment
		(start 365.518446 -28.706572)
		(end 364.377224 -28.706572)
		(width 0.10668)
		(layer "F.Cu")
		(net "UART_CPU0_LVC3_UART0_RX")
	)
	(segment
		(start 364.366302 -28.69565)
		(end 363.944662 -28.69565)
		(width 0.10668)
		(layer "F.Cu")
		(net "UART_CPU0_LVC3_UART0_RX")
	)
	(segment
		(start 363.944662 -28.69565)
		(end 363.681264 -28.432252)
		(width 0.10668)
		(layer "F.Cu")
		(net "UART_CPU0_LVC3_UART0_RX")
	)
	(segment
		(start 364.377224 -28.706572)
		(end 364.366302 -28.69565)
		(width 0.10668)
		(layer "F.Cu")
		(net "UART_CPU0_LVC3_UART0_RX")
	)
	(segment
		(start 363.681264 -28.432252)
		(end 363.681264 -26.471626)
		(width 0.10668)
		(layer "F.Cu")
		(net "UART_CPU0_LVC3_UART0_RX")
	)
	(segment
		(start 365.518446 -29.684472)
		(end 365.518446 -28.706572)
		(width 0.10668)
		(layer "F.Cu")
		(net "UART_CPU0_LVC3_UART0_RX")
	)
	(segment
		(start 363.681264 -26.471626)
		(end 363.681264 -24.04491)
		(width 0.10668)
		(layer "F.Cu")
		(net "UART_CPU0_LVC3_UART0_RX")
	)
	(segment
		(start 363.681264 -24.04491)
		(end 365.518446 -22.207728)
		(width 0.10668)
		(layer "F.Cu")
		(net "UART_CPU0_LVC3_UART0_RX")
	)
	(via
		(at 363.681264 -26.471626)
		(size 0.762)
		(drill 0.381)
		(layers "F.Cu" "B.Cu")
		(net "UART_CPU0_LVC3_UART0_RX")
	)
	(segment
		(start 186.844686 -15.645638)
		(end 186.631326 -15.432278)
		(width 0.10668)
		(layer "F.Cu")
		(net "UART_BMC_BIC_TX")
	)
	(segment
		(start 188.662056 -15.85087)
		(end 188.456824 -15.645638)
		(width 0.10668)
		(layer "F.Cu")
		(net "UART_BMC_BIC_TX")
	)
	(segment
		(start 188.662056 -16.549878)
		(end 188.662056 -15.85087)
		(width 0.10668)
		(layer "F.Cu")
		(net "UART_BMC_BIC_TX")
	)
	(segment
		(start 188.456824 -15.645638)
		(end 186.844686 -15.645638)
		(width 0.10668)
		(layer "F.Cu")
		(net "UART_BMC_BIC_TX")
	)
	(via
		(at 186.631326 -15.432278)
		(size 0.508)
		(drill 0.254)
		(layers "F.Cu" "B.Cu")
		(net "UART_BMC_BIC_TX")
	)
	(via
		(at 309.48122 -106.937048)
		(size 0.508)
		(drill 0.254)
		(layers "F.Cu" "B.Cu")
		(net "UART_BMC_BIC_TX")
	)
	(via
		(at 431.839624 -431.50282)
		(size 0.508)
		(drill 0.254)
		(layers "F.Cu" "B.Cu")
		(net "UART_BMC_BIC_TX")
	)
	(via
		(at 208.107534 -14.468094)
		(size 0.508)
		(drill 0.254)
		(layers "F.Cu" "B.Cu")
		(net "UART_BMC_BIC_TX")
	)
	(segment
		(start 396.992094 -424.689778)
		(end 398.934432 -422.74744)
		(width 0.10668)
		(layer "B.Cu")
		(net "UART_BMC_BIC_TX")
	)
	(segment
		(start 430.324768 -433.017676)
		(end 431.839624 -431.50282)
		(width 0.10668)
		(layer "B.Cu")
		(net "UART_BMC_BIC_TX")
	)
	(segment
		(start 425.37126 -432.850036)
		(end 428.548546 -432.850036)
		(width 0.10668)
		(layer "B.Cu")
		(net "UART_BMC_BIC_TX")
	)
	(segment
		(start 428.548546 -432.850036)
		(end 428.716186 -433.017676)
		(width 0.10668)
		(layer "B.Cu")
		(net "UART_BMC_BIC_TX")
	)
	(segment
		(start 416.781742 -425.691554)
		(end 416.781742 -428.638462)
		(width 0.10668)
		(layer "B.Cu")
		(net "UART_BMC_BIC_TX")
	)
	(segment
		(start 413.837628 -422.74744)
		(end 416.781742 -425.691554)
		(width 0.10668)
		(layer "B.Cu")
		(net "UART_BMC_BIC_TX")
	)
	(segment
		(start 428.716186 -433.017676)
		(end 430.324768 -433.017676)
		(width 0.10668)
		(layer "B.Cu")
		(net "UART_BMC_BIC_TX")
	)
	(segment
		(start 398.934432 -422.74744)
		(end 413.837628 -422.74744)
		(width 0.10668)
		(layer "B.Cu")
		(net "UART_BMC_BIC_TX")
	)
	(segment
		(start 416.781742 -428.638462)
		(end 418.916358 -430.773078)
		(width 0.10668)
		(layer "B.Cu")
		(net "UART_BMC_BIC_TX")
	)
	(segment
		(start 418.916358 -430.773078)
		(end 423.294302 -430.773078)
		(width 0.10668)
		(layer "B.Cu")
		(net "UART_BMC_BIC_TX")
	)
	(segment
		(start 423.294302 -430.773078)
		(end 425.37126 -432.850036)
		(width 0.10668)
		(layer "B.Cu")
		(net "UART_BMC_BIC_TX")
	)
	(segment
		(start 395.74978 -424.689778)
		(end 396.992094 -424.689778)
		(width 0.10668)
		(layer "B.Cu")
		(net "UART_BMC_BIC_TX")
	)
	(segment
		(start 453.744076 -364.544864)
		(end 453.744076 -344.020394)
		(width 0.11684)
		(layer "In2.Cu")
		(net "UART_BMC_BIC_TX")
	)
	(segment
		(start 439.234072 -387.294374)
		(end 439.234072 -375.381012)
		(width 0.11684)
		(layer "In2.Cu")
		(net "UART_BMC_BIC_TX")
	)
	(segment
		(start 186.529726 -15.330678)
		(end 186.529726 -14.106906)
		(width 0.11684)
		(layer "In2.Cu")
		(net "UART_BMC_BIC_TX")
	)
	(segment
		(start 389.586216 -119.304308)
		(end 388.515098 -118.23319)
		(width 0.11684)
		(layer "In2.Cu")
		(net "UART_BMC_BIC_TX")
	)
	(segment
		(start 434.953156 -391.57529)
		(end 439.234072 -387.294374)
		(width 0.11684)
		(layer "In2.Cu")
		(net "UART_BMC_BIC_TX")
	)
	(segment
		(start 434.15458 -424.7388)
		(end 434.15458 -411.619446)
		(width 0.11684)
		(layer "In2.Cu")
		(net "UART_BMC_BIC_TX")
	)
	(segment
		(start 446.122298 -372.166642)
		(end 453.744076 -364.544864)
		(width 0.11684)
		(layer "In2.Cu")
		(net "UART_BMC_BIC_TX")
	)
	(segment
		(start 194.295014 -12.964668)
		(end 195.79844 -14.468094)
		(width 0.11684)
		(layer "In2.Cu")
		(net "UART_BMC_BIC_TX")
	)
	(segment
		(start 465.496656 -332.267814)
		(end 465.496656 -174.449232)
		(width 0.11684)
		(layer "In2.Cu")
		(net "UART_BMC_BIC_TX")
	)
	(segment
		(start 453.744076 -344.020394)
		(end 465.496656 -332.267814)
		(width 0.11684)
		(layer "In2.Cu")
		(net "UART_BMC_BIC_TX")
	)
	(segment
		(start 431.839624 -396.583408)
		(end 434.953156 -393.469876)
		(width 0.11684)
		(layer "In2.Cu")
		(net "UART_BMC_BIC_TX")
	)
	(segment
		(start 442.448442 -372.166642)
		(end 446.122298 -372.166642)
		(width 0.11684)
		(layer "In2.Cu")
		(net "UART_BMC_BIC_TX")
	)
	(segment
		(start 314.628784 -112.084612)
		(end 309.48122 -106.937048)
		(width 0.11684)
		(layer "In2.Cu")
		(net "UART_BMC_BIC_TX")
	)
	(segment
		(start 431.839624 -427.053756)
		(end 434.15458 -424.7388)
		(width 0.11684)
		(layer "In2.Cu")
		(net "UART_BMC_BIC_TX")
	)
	(segment
		(start 190.5381 -10.65022)
		(end 191.14516 -10.04316)
		(width 0.11684)
		(layer "In2.Cu")
		(net "UART_BMC_BIC_TX")
	)
	(segment
		(start 186.529726 -14.106906)
		(end 187.62218 -13.014452)
		(width 0.11684)
		(layer "In2.Cu")
		(net "UART_BMC_BIC_TX")
	)
	(segment
		(start 374.172734 -120.777762)
		(end 325.22541 -120.777762)
		(width 0.11684)
		(layer "In2.Cu")
		(net "UART_BMC_BIC_TX")
	)
	(segment
		(start 190.5381 -12.48156)
		(end 190.5381 -10.65022)
		(width 0.11684)
		(layer "In2.Cu")
		(net "UART_BMC_BIC_TX")
	)
	(segment
		(start 431.839624 -431.50282)
		(end 431.839624 -427.053756)
		(width 0.11684)
		(layer "In2.Cu")
		(net "UART_BMC_BIC_TX")
	)
	(segment
		(start 193.539618 -10.690098)
		(end 193.74358 -11.182604)
		(width 0.11684)
		(layer "In2.Cu")
		(net "UART_BMC_BIC_TX")
	)
	(segment
		(start 428.668688 -406.133554)
		(end 428.668688 -404.240238)
		(width 0.11684)
		(layer "In2.Cu")
		(net "UART_BMC_BIC_TX")
	)
	(segment
		(start 325.22541 -120.777762)
		(end 316.53226 -112.084612)
		(width 0.11684)
		(layer "In2.Cu")
		(net "UART_BMC_BIC_TX")
	)
	(segment
		(start 190.005208 -13.014452)
		(end 190.5381 -12.48156)
		(width 0.11684)
		(layer "In2.Cu")
		(net "UART_BMC_BIC_TX")
	)
	(segment
		(start 195.79844 -14.468094)
		(end 208.107534 -14.468094)
		(width 0.11684)
		(layer "In2.Cu")
		(net "UART_BMC_BIC_TX")
	)
	(segment
		(start 376.352308 -118.598188)
		(end 374.172734 -120.777762)
		(width 0.11684)
		(layer "In2.Cu")
		(net "UART_BMC_BIC_TX")
	)
	(segment
		(start 439.234072 -375.381012)
		(end 442.448442 -372.166642)
		(width 0.11684)
		(layer "In2.Cu")
		(net "UART_BMC_BIC_TX")
	)
	(segment
		(start 191.14516 -10.04316)
		(end 192.36182 -10.04316)
		(width 0.11684)
		(layer "In2.Cu")
		(net "UART_BMC_BIC_TX")
	)
	(segment
		(start 316.53226 -112.084612)
		(end 314.628784 -112.084612)
		(width 0.11684)
		(layer "In2.Cu")
		(net "UART_BMC_BIC_TX")
	)
	(segment
		(start 456.579224 -150.669752)
		(end 456.579224 -142.316454)
		(width 0.11684)
		(layer "In2.Cu")
		(net "UART_BMC_BIC_TX")
	)
	(segment
		(start 434.15458 -411.619446)
		(end 428.668688 -406.133554)
		(width 0.11684)
		(layer "In2.Cu")
		(net "UART_BMC_BIC_TX")
	)
	(segment
		(start 431.237644 -401.671282)
		(end 431.237644 -398.03705)
		(width 0.11684)
		(layer "In2.Cu")
		(net "UART_BMC_BIC_TX")
	)
	(segment
		(start 465.496656 -174.449232)
		(end 454.510394 -163.46297)
		(width 0.11684)
		(layer "In2.Cu")
		(net "UART_BMC_BIC_TX")
	)
	(segment
		(start 434.953156 -393.469876)
		(end 434.953156 -391.57529)
		(width 0.11684)
		(layer "In2.Cu")
		(net "UART_BMC_BIC_TX")
	)
	(segment
		(start 428.668688 -404.240238)
		(end 431.237644 -401.671282)
		(width 0.11684)
		(layer "In2.Cu")
		(net "UART_BMC_BIC_TX")
	)
	(segment
		(start 192.36182 -10.04316)
		(end 193.268092 -10.418572)
		(width 0.11684)
		(layer "In2.Cu")
		(net "UART_BMC_BIC_TX")
	)
	(segment
		(start 454.510394 -152.738582)
		(end 456.579224 -150.669752)
		(width 0.11684)
		(layer "In2.Cu")
		(net "UART_BMC_BIC_TX")
	)
	(segment
		(start 193.74358 -11.6332)
		(end 194.295014 -12.964668)
		(width 0.11684)
		(layer "In2.Cu")
		(net "UART_BMC_BIC_TX")
	)
	(segment
		(start 383.120138 -118.23319)
		(end 382.75514 -118.598188)
		(width 0.11684)
		(layer "In2.Cu")
		(net "UART_BMC_BIC_TX")
	)
	(segment
		(start 456.579224 -142.316454)
		(end 433.567078 -119.304308)
		(width 0.11684)
		(layer "In2.Cu")
		(net "UART_BMC_BIC_TX")
	)
	(segment
		(start 187.62218 -13.014452)
		(end 190.005208 -13.014452)
		(width 0.11684)
		(layer "In2.Cu")
		(net "UART_BMC_BIC_TX")
	)
	(segment
		(start 186.631326 -15.432278)
		(end 186.529726 -15.330678)
		(width 0.11684)
		(layer "In2.Cu")
		(net "UART_BMC_BIC_TX")
	)
	(segment
		(start 193.74358 -11.182604)
		(end 193.74358 -11.6332)
		(width 0.11684)
		(layer "In2.Cu")
		(net "UART_BMC_BIC_TX")
	)
	(segment
		(start 382.75514 -118.598188)
		(end 376.352308 -118.598188)
		(width 0.11684)
		(layer "In2.Cu")
		(net "UART_BMC_BIC_TX")
	)
	(segment
		(start 454.510394 -163.46297)
		(end 454.510394 -152.738582)
		(width 0.11684)
		(layer "In2.Cu")
		(net "UART_BMC_BIC_TX")
	)
	(segment
		(start 431.237644 -398.03705)
		(end 431.839624 -396.583408)
		(width 0.11684)
		(layer "In2.Cu")
		(net "UART_BMC_BIC_TX")
	)
	(segment
		(start 433.567078 -119.304308)
		(end 389.586216 -119.304308)
		(width 0.11684)
		(layer "In2.Cu")
		(net "UART_BMC_BIC_TX")
	)
	(segment
		(start 388.515098 -118.23319)
		(end 383.120138 -118.23319)
		(width 0.11684)
		(layer "In2.Cu")
		(net "UART_BMC_BIC_TX")
	)
	(segment
		(start 193.268092 -10.418572)
		(end 193.539618 -10.690098)
		(width 0.11684)
		(layer "In2.Cu")
		(net "UART_BMC_BIC_TX")
	)
	(segment
		(start 231.46893 -41.494964)
		(end 229.755446 -39.78148)
		(width 0.11684)
		(layer "In4.Cu")
		(net "UART_BMC_BIC_TX")
	)
	(segment
		(start 220.541088 -35.757104)
		(end 220.541088 -22.12848)
		(width 0.11684)
		(layer "In4.Cu")
		(net "UART_BMC_BIC_TX")
	)
	(segment
		(start 245.259098 -40.838628)
		(end 243.372894 -41.620186)
		(width 0.11684)
		(layer "In4.Cu")
		(net "UART_BMC_BIC_TX")
	)
	(segment
		(start 247.748806 -38.34892)
		(end 245.259098 -40.838628)
		(width 0.11684)
		(layer "In4.Cu")
		(net "UART_BMC_BIC_TX")
	)
	(segment
		(start 220.541088 -22.12848)
		(end 216.506044 -18.093436)
		(width 0.11684)
		(layer "In4.Cu")
		(net "UART_BMC_BIC_TX")
	)
	(segment
		(start 301.969932 -51.416712)
		(end 294.967152 -44.413932)
		(width 0.11684)
		(layer "In4.Cu")
		(net "UART_BMC_BIC_TX")
	)
	(segment
		(start 216.506044 -18.093436)
		(end 211.732876 -18.093436)
		(width 0.11684)
		(layer "In4.Cu")
		(net "UART_BMC_BIC_TX")
	)
	(segment
		(start 211.732876 -18.093436)
		(end 208.107534 -14.468094)
		(width 0.11684)
		(layer "In4.Cu")
		(net "UART_BMC_BIC_TX")
	)
	(segment
		(start 301.969932 -99.42576)
		(end 301.969932 -51.416712)
		(width 0.11684)
		(layer "In4.Cu")
		(net "UART_BMC_BIC_TX")
	)
	(segment
		(start 240.815368 -42.80662)
		(end 235.328206 -42.80662)
		(width 0.11684)
		(layer "In4.Cu")
		(net "UART_BMC_BIC_TX")
	)
	(segment
		(start 263.267952 -44.413932)
		(end 257.20294 -38.34892)
		(width 0.11684)
		(layer "In4.Cu")
		(net "UART_BMC_BIC_TX")
	)
	(segment
		(start 294.967152 -44.413932)
		(end 263.267952 -44.413932)
		(width 0.11684)
		(layer "In4.Cu")
		(net "UART_BMC_BIC_TX")
	)
	(segment
		(start 257.20294 -38.34892)
		(end 247.748806 -38.34892)
		(width 0.11684)
		(layer "In4.Cu")
		(net "UART_BMC_BIC_TX")
	)
	(segment
		(start 229.755446 -39.78148)
		(end 224.565464 -39.78148)
		(width 0.11684)
		(layer "In4.Cu")
		(net "UART_BMC_BIC_TX")
	)
	(segment
		(start 242.001802 -41.620186)
		(end 240.815368 -42.80662)
		(width 0.11684)
		(layer "In4.Cu")
		(net "UART_BMC_BIC_TX")
	)
	(segment
		(start 235.328206 -42.80662)
		(end 234.01655 -41.494964)
		(width 0.11684)
		(layer "In4.Cu")
		(net "UART_BMC_BIC_TX")
	)
	(segment
		(start 224.565464 -39.78148)
		(end 220.541088 -35.757104)
		(width 0.11684)
		(layer "In4.Cu")
		(net "UART_BMC_BIC_TX")
	)
	(segment
		(start 243.372894 -41.620186)
		(end 242.001802 -41.620186)
		(width 0.11684)
		(layer "In4.Cu")
		(net "UART_BMC_BIC_TX")
	)
	(segment
		(start 234.01655 -41.494964)
		(end 231.46893 -41.494964)
		(width 0.11684)
		(layer "In4.Cu")
		(net "UART_BMC_BIC_TX")
	)
	(segment
		(start 309.48122 -106.937048)
		(end 301.969932 -99.42576)
		(width 0.11684)
		(layer "In4.Cu")
		(net "UART_BMC_BIC_TX")
	)
	(segment
		(start 359.664 -410.845)
		(end 359.664 -410.718)
		(width 0.10668)
		(layer "F.Cu")
		(net "UART_BMC_BIC_R_RX")
	)
	(segment
		(start 359.709974 -410.890974)
		(end 359.664 -410.845)
		(width 0.10668)
		(layer "F.Cu")
		(net "UART_BMC_BIC_R_RX")
	)
	(segment
		(start 359.709974 -412.909258)
		(end 359.709974 -410.890974)
		(width 0.10668)
		(layer "F.Cu")
		(net "UART_BMC_BIC_R_RX")
	)
	(segment
		(start 359.567988 -410.621988)
		(end 359.567988 -409.788868)
		(width 0.10668)
		(layer "F.Cu")
		(net "UART_BMC_BIC_R_RX")
	)
	(segment
		(start 359.664 -410.718)
		(end 359.567988 -410.621988)
		(width 0.10668)
		(layer "F.Cu")
		(net "UART_BMC_BIC_R_RX")
	)
	(via
		(at 359.664 -410.718)
		(size 0.762)
		(drill 0.381)
		(layers "F.Cu" "B.Cu")
		(net "UART_BMC_BIC_R_RX")
	)
	(segment
		(start 360.35996 -417.313618)
		(end 360.35996 -416.094418)
		(width 0.10668)
		(layer "F.Cu")
		(net "UART_BMC_BIC_R_BUF_RX")
	)
	(segment
		(start 360.35996 -418.329618)
		(end 360.35996 -417.313618)
		(width 0.10668)
		(layer "F.Cu")
		(net "UART_BMC_BIC_R_BUF_RX")
	)
	(segment
		(start 360.35996 -416.094418)
		(end 360.35996 -414.809178)
		(width 0.10668)
		(layer "F.Cu")
		(net "UART_BMC_BIC_R_BUF_RX")
	)
	(via
		(at 360.35996 -416.094418)
		(size 0.762)
		(drill 0.381)
		(layers "F.Cu" "B.Cu")
		(net "UART_BMC_BIC_R_BUF_RX")
	)
	(segment
		(start 359.567988 -408.988768)
		(end 360.583988 -408.988768)
		(width 0.10668)
		(layer "F.Cu")
		(net "UART_BMC_BIC_RX")
	)
	(segment
		(start 360.583988 -408.988768)
		(end 360.583988 -408.716988)
		(width 0.10668)
		(layer "F.Cu")
		(net "UART_BMC_BIC_RX")
	)
	(segment
		(start 360.583988 -408.716988)
		(end 360.172 -408.305)
		(width 0.10668)
		(layer "F.Cu")
		(net "UART_BMC_BIC_RX")
	)
	(via
		(at 371.611652 -428.51324)
		(size 0.508)
		(drill 0.254)
		(layers "F.Cu" "B.Cu")
		(net "UART_BMC_BIC_RX")
	)
	(via
		(at 360.172 -408.305)
		(size 0.508)
		(drill 0.254)
		(layers "F.Cu" "B.Cu")
		(net "UART_BMC_BIC_RX")
	)
	(segment
		(start 378.81306 -423.66438)
		(end 373.557546 -428.919894)
		(width 0.11684)
		(layer "In2.Cu")
		(net "UART_BMC_BIC_RX")
	)
	(segment
		(start 391.749788 -424.689778)
		(end 390.72439 -423.66438)
		(width 0.11684)
		(layer "In2.Cu")
		(net "UART_BMC_BIC_RX")
	)
	(segment
		(start 372.018306 -428.919894)
		(end 371.611652 -428.51324)
		(width 0.11684)
		(layer "In2.Cu")
		(net "UART_BMC_BIC_RX")
	)
	(segment
		(start 390.72439 -423.66438)
		(end 378.81306 -423.66438)
		(width 0.11684)
		(layer "In2.Cu")
		(net "UART_BMC_BIC_RX")
	)
	(segment
		(start 373.557546 -428.919894)
		(end 372.018306 -428.919894)
		(width 0.11684)
		(layer "In2.Cu")
		(net "UART_BMC_BIC_RX")
	)
	(segment
		(start 371.611652 -428.51324)
		(end 371.611652 -427.948852)
		(width 0.11684)
		(layer "In4.Cu")
		(net "UART_BMC_BIC_RX")
	)
	(segment
		(start 364.966758 -427.359064)
		(end 363.41304 -425.805346)
		(width 0.11684)
		(layer "In4.Cu")
		(net "UART_BMC_BIC_RX")
	)
	(segment
		(start 361.385612 -421.21328)
		(end 361.385612 -418.940742)
		(width 0.11684)
		(layer "In4.Cu")
		(net "UART_BMC_BIC_RX")
	)
	(segment
		(start 359.609136 -409.902152)
		(end 360.172 -409.339288)
		(width 0.11684)
		(layer "In4.Cu")
		(net "UART_BMC_BIC_RX")
	)
	(segment
		(start 363.41304 -425.805346)
		(end 363.41304 -423.240708)
		(width 0.11684)
		(layer "In4.Cu")
		(net "UART_BMC_BIC_RX")
	)
	(segment
		(start 368.863626 -427.359064)
		(end 364.966758 -427.359064)
		(width 0.11684)
		(layer "In4.Cu")
		(net "UART_BMC_BIC_RX")
	)
	(segment
		(start 359.609136 -414.871916)
		(end 359.609136 -409.902152)
		(width 0.11684)
		(layer "In4.Cu")
		(net "UART_BMC_BIC_RX")
	)
	(segment
		(start 361.118658 -416.381438)
		(end 359.609136 -414.871916)
		(width 0.11684)
		(layer "In4.Cu")
		(net "UART_BMC_BIC_RX")
	)
	(segment
		(start 371.21719 -427.55439)
		(end 369.058952 -427.55439)
		(width 0.11684)
		(layer "In4.Cu")
		(net "UART_BMC_BIC_RX")
	)
	(segment
		(start 361.118658 -418.673788)
		(end 361.118658 -416.381438)
		(width 0.11684)
		(layer "In4.Cu")
		(net "UART_BMC_BIC_RX")
	)
	(segment
		(start 361.385612 -418.940742)
		(end 361.118658 -418.673788)
		(width 0.11684)
		(layer "In4.Cu")
		(net "UART_BMC_BIC_RX")
	)
	(segment
		(start 371.611652 -427.948852)
		(end 371.21719 -427.55439)
		(width 0.11684)
		(layer "In4.Cu")
		(net "UART_BMC_BIC_RX")
	)
	(segment
		(start 363.41304 -423.240708)
		(end 361.385612 -421.21328)
		(width 0.11684)
		(layer "In4.Cu")
		(net "UART_BMC_BIC_RX")
	)
	(segment
		(start 369.058952 -427.55439)
		(end 368.863626 -427.359064)
		(width 0.11684)
		(layer "In4.Cu")
		(net "UART_BMC_BIC_RX")
	)
	(segment
		(start 360.172 -409.339288)
		(end 360.172 -408.305)
		(width 0.11684)
		(layer "In4.Cu")
		(net "UART_BMC_BIC_RX")
	)
	(segment
		(start 361.16006 -417.313618)
		(end 361.16006 -415.417)
		(width 0.10668)
		(layer "F.Cu")
		(net "UART_BMC_BIC_BUF_RX")
	)
	(segment
		(start 188.062108 -16.549878)
		(end 188.062108 -17.714722)
		(width 0.10668)
		(layer "F.Cu")
		(net "UART_BMC_BIC_BUF_RX")
	)
	(segment
		(start 188.062108 -17.714722)
		(end 188.096398 -17.749012)
		(width 0.10668)
		(layer "F.Cu")
		(net "UART_BMC_BIC_BUF_RX")
	)
	(segment
		(start 188.096398 -17.749012)
		(end 188.096398 -18.685256)
		(width 0.10668)
		(layer "F.Cu")
		(net "UART_BMC_BIC_BUF_RX")
	)
	(via
		(at 247.395238 -81.495392)
		(size 0.508)
		(drill 0.254)
		(layers "F.Cu" "B.Cu")
		(net "UART_BMC_BIC_BUF_RX")
	)
	(via
		(at 188.096398 -18.685256)
		(size 0.508)
		(drill 0.254)
		(layers "F.Cu" "B.Cu")
		(net "UART_BMC_BIC_BUF_RX")
	)
	(via
		(at 361.16006 -415.417)
		(size 0.508)
		(drill 0.254)
		(layers "F.Cu" "B.Cu")
		(net "UART_BMC_BIC_BUF_RX")
	)
	(via
		(at 360.658156 -407.105358)
		(size 0.508)
		(drill 0.254)
		(layers "F.Cu" "B.Cu")
		(net "UART_BMC_BIC_BUF_RX")
	)
	(segment
		(start 232.885234 -69.694806)
		(end 236.114336 -69.694806)
		(width 0.10668)
		(layer "B.Cu")
		(net "UART_BMC_BIC_BUF_RX")
	)
	(segment
		(start 230.806244 -67.615816)
		(end 232.885234 -69.694806)
		(width 0.10668)
		(layer "B.Cu")
		(net "UART_BMC_BIC_BUF_RX")
	)
	(segment
		(start 230.806244 -65.960498)
		(end 230.806244 -67.615816)
		(width 0.10668)
		(layer "B.Cu")
		(net "UART_BMC_BIC_BUF_RX")
	)
	(segment
		(start 193.188336 -20.32254)
		(end 195.69176 -22.825964)
		(width 0.10668)
		(layer "B.Cu")
		(net "UART_BMC_BIC_BUF_RX")
	)
	(segment
		(start 244.61851 -78.19898)
		(end 244.61851 -79.138526)
		(width 0.10668)
		(layer "B.Cu")
		(net "UART_BMC_BIC_BUF_RX")
	)
	(segment
		(start 215.741758 -51.447954)
		(end 216.2937 -51.447954)
		(width 0.10668)
		(layer "B.Cu")
		(net "UART_BMC_BIC_BUF_RX")
	)
	(segment
		(start 246.975376 -81.495392)
		(end 247.395238 -81.495392)
		(width 0.10668)
		(layer "B.Cu")
		(net "UART_BMC_BIC_BUF_RX")
	)
	(segment
		(start 198.281798 -40.374062)
		(end 204.667866 -40.374062)
		(width 0.10668)
		(layer "B.Cu")
		(net "UART_BMC_BIC_BUF_RX")
	)
	(segment
		(start 195.69176 -31.822136)
		(end 196.769736 -32.900112)
		(width 0.10668)
		(layer "B.Cu")
		(net "UART_BMC_BIC_BUF_RX")
	)
	(segment
		(start 189.368938 -20.32254)
		(end 193.188336 -20.32254)
		(width 0.10668)
		(layer "B.Cu")
		(net "UART_BMC_BIC_BUF_RX")
	)
	(segment
		(start 188.096398 -19.05)
		(end 189.368938 -20.32254)
		(width 0.10668)
		(layer "B.Cu")
		(net "UART_BMC_BIC_BUF_RX")
	)
	(segment
		(start 204.667866 -40.374062)
		(end 215.741758 -51.447954)
		(width 0.10668)
		(layer "B.Cu")
		(net "UART_BMC_BIC_BUF_RX")
	)
	(segment
		(start 196.769736 -32.900112)
		(end 196.769736 -38.862)
		(width 0.10668)
		(layer "B.Cu")
		(net "UART_BMC_BIC_BUF_RX")
	)
	(segment
		(start 236.114336 -69.694806)
		(end 244.61851 -78.19898)
		(width 0.10668)
		(layer "B.Cu")
		(net "UART_BMC_BIC_BUF_RX")
	)
	(segment
		(start 216.2937 -51.447954)
		(end 230.806244 -65.960498)
		(width 0.10668)
		(layer "B.Cu")
		(net "UART_BMC_BIC_BUF_RX")
	)
	(segment
		(start 188.096398 -18.685256)
		(end 188.096398 -19.05)
		(width 0.10668)
		(layer "B.Cu")
		(net "UART_BMC_BIC_BUF_RX")
	)
	(segment
		(start 244.61851 -79.138526)
		(end 246.975376 -81.495392)
		(width 0.10668)
		(layer "B.Cu")
		(net "UART_BMC_BIC_BUF_RX")
	)
	(segment
		(start 195.69176 -22.825964)
		(end 195.69176 -31.822136)
		(width 0.10668)
		(layer "B.Cu")
		(net "UART_BMC_BIC_BUF_RX")
	)
	(segment
		(start 196.769736 -38.862)
		(end 198.281798 -40.374062)
		(width 0.10668)
		(layer "B.Cu")
		(net "UART_BMC_BIC_BUF_RX")
	)
	(segment
		(start 258.943094 -81.495392)
		(end 247.395238 -81.495392)
		(width 0.11684)
		(layer "In2.Cu")
		(net "UART_BMC_BIC_BUF_RX")
	)
	(segment
		(start 382.478534 -121.404126)
		(end 375.77014 -121.404126)
		(width 0.11684)
		(layer "In2.Cu")
		(net "UART_BMC_BIC_BUF_RX")
	)
	(segment
		(start 452.863458 -163.745164)
		(end 452.863458 -146.67865)
		(width 0.11684)
		(layer "In2.Cu")
		(net "UART_BMC_BIC_BUF_RX")
	)
	(segment
		(start 437.869076 -374.504204)
		(end 441.695586 -370.677694)
		(width 0.11684)
		(layer "In2.Cu")
		(net "UART_BMC_BIC_BUF_RX")
	)
	(segment
		(start 288.30778 -108.471208)
		(end 281.040586 -101.204014)
		(width 0.11684)
		(layer "In2.Cu")
		(net "UART_BMC_BIC_BUF_RX")
	)
	(segment
		(start 274.047712 -94.12986)
		(end 271.577562 -94.12986)
		(width 0.11684)
		(layer "In2.Cu")
		(net "UART_BMC_BIC_BUF_RX")
	)
	(segment
		(start 423.5196 -407.306272)
		(end 429.966882 -400.85899)
		(width 0.11684)
		(layer "In2.Cu")
		(net "UART_BMC_BIC_BUF_RX")
	)
	(segment
		(start 375.131584 -122.042682)
		(end 320.460878 -122.042682)
		(width 0.11684)
		(layer "In2.Cu")
		(net "UART_BMC_BIC_BUF_RX")
	)
	(segment
		(start 464.231736 -331.704442)
		(end 464.231736 -175.113442)
		(width 0.11684)
		(layer "In2.Cu")
		(net "UART_BMC_BIC_BUF_RX")
	)
	(segment
		(start 271.577562 -94.12986)
		(end 258.943094 -81.495392)
		(width 0.11684)
		(layer "In2.Cu")
		(net "UART_BMC_BIC_BUF_RX")
	)
	(segment
		(start 305.837082 -108.471208)
		(end 288.30778 -108.471208)
		(width 0.11684)
		(layer "In2.Cu")
		(net "UART_BMC_BIC_BUF_RX")
	)
	(segment
		(start 320.460878 -122.042682)
		(end 317.367158 -118.948962)
		(width 0.11684)
		(layer "In2.Cu")
		(net "UART_BMC_BIC_BUF_RX")
	)
	(segment
		(start 433.520342 -390.97585)
		(end 437.869076 -386.627116)
		(width 0.11684)
		(layer "In2.Cu")
		(net "UART_BMC_BIC_BUF_RX")
	)
	(segment
		(start 452.863458 -146.67865)
		(end 426.811948 -120.62714)
		(width 0.11684)
		(layer "In2.Cu")
		(net "UART_BMC_BIC_BUF_RX")
	)
	(segment
		(start 426.811948 -120.62714)
		(end 383.25552 -120.62714)
		(width 0.11684)
		(layer "In2.Cu")
		(net "UART_BMC_BIC_BUF_RX")
	)
	(segment
		(start 280.043382 -98.95459)
		(end 278.872442 -98.95459)
		(width 0.11684)
		(layer "In2.Cu")
		(net "UART_BMC_BIC_BUF_RX")
	)
	(segment
		(start 362.044488 -407.140156)
		(end 369.060476 -407.140156)
		(width 0.11684)
		(layer "In2.Cu")
		(net "UART_BMC_BIC_BUF_RX")
	)
	(segment
		(start 383.25552 -120.62714)
		(end 382.478534 -121.404126)
		(width 0.11684)
		(layer "In2.Cu")
		(net "UART_BMC_BIC_BUF_RX")
	)
	(segment
		(start 375.77014 -121.404126)
		(end 375.131584 -122.042682)
		(width 0.11684)
		(layer "In2.Cu")
		(net "UART_BMC_BIC_BUF_RX")
	)
	(segment
		(start 278.872442 -98.95459)
		(end 274.047712 -94.12986)
		(width 0.11684)
		(layer "In2.Cu")
		(net "UART_BMC_BIC_BUF_RX")
	)
	(segment
		(start 360.658156 -407.105358)
		(end 360.95178 -407.398982)
		(width 0.11684)
		(layer "In2.Cu")
		(net "UART_BMC_BIC_BUF_RX")
	)
	(segment
		(start 441.695586 -370.677694)
		(end 445.782954 -370.677694)
		(width 0.11684)
		(layer "In2.Cu")
		(net "UART_BMC_BIC_BUF_RX")
	)
	(segment
		(start 452.479156 -343.457022)
		(end 464.231736 -331.704442)
		(width 0.11684)
		(layer "In2.Cu")
		(net "UART_BMC_BIC_BUF_RX")
	)
	(segment
		(start 281.040586 -99.951794)
		(end 280.043382 -98.95459)
		(width 0.11684)
		(layer "In2.Cu")
		(net "UART_BMC_BIC_BUF_RX")
	)
	(segment
		(start 369.060476 -407.140156)
		(end 369.226592 -407.306272)
		(width 0.11684)
		(layer "In2.Cu")
		(net "UART_BMC_BIC_BUF_RX")
	)
	(segment
		(start 361.785662 -407.398982)
		(end 362.044488 -407.140156)
		(width 0.11684)
		(layer "In2.Cu")
		(net "UART_BMC_BIC_BUF_RX")
	)
	(segment
		(start 437.869076 -386.627116)
		(end 437.869076 -374.504204)
		(width 0.11684)
		(layer "In2.Cu")
		(net "UART_BMC_BIC_BUF_RX")
	)
	(segment
		(start 445.782954 -370.677694)
		(end 452.479156 -363.981492)
		(width 0.11684)
		(layer "In2.Cu")
		(net "UART_BMC_BIC_BUF_RX")
	)
	(segment
		(start 316.314836 -118.948962)
		(end 305.837082 -108.471208)
		(width 0.11684)
		(layer "In2.Cu")
		(net "UART_BMC_BIC_BUF_RX")
	)
	(segment
		(start 360.95178 -407.398982)
		(end 361.785662 -407.398982)
		(width 0.11684)
		(layer "In2.Cu")
		(net "UART_BMC_BIC_BUF_RX")
	)
	(segment
		(start 430.592992 -395.97838)
		(end 433.520342 -393.05103)
		(width 0.11684)
		(layer "In2.Cu")
		(net "UART_BMC_BIC_BUF_RX")
	)
	(segment
		(start 369.226592 -407.306272)
		(end 423.5196 -407.306272)
		(width 0.11684)
		(layer "In2.Cu")
		(net "UART_BMC_BIC_BUF_RX")
	)
	(segment
		(start 317.367158 -118.948962)
		(end 316.314836 -118.948962)
		(width 0.11684)
		(layer "In2.Cu")
		(net "UART_BMC_BIC_BUF_RX")
	)
	(segment
		(start 429.966882 -400.85899)
		(end 429.966882 -397.490442)
		(width 0.11684)
		(layer "In2.Cu")
		(net "UART_BMC_BIC_BUF_RX")
	)
	(segment
		(start 281.040586 -101.204014)
		(end 281.040586 -99.951794)
		(width 0.11684)
		(layer "In2.Cu")
		(net "UART_BMC_BIC_BUF_RX")
	)
	(segment
		(start 429.966882 -397.490442)
		(end 430.592992 -395.97838)
		(width 0.11684)
		(layer "In2.Cu")
		(net "UART_BMC_BIC_BUF_RX")
	)
	(segment
		(start 452.479156 -363.981492)
		(end 452.479156 -343.457022)
		(width 0.11684)
		(layer "In2.Cu")
		(net "UART_BMC_BIC_BUF_RX")
	)
	(segment
		(start 464.231736 -175.113442)
		(end 452.863458 -163.745164)
		(width 0.11684)
		(layer "In2.Cu")
		(net "UART_BMC_BIC_BUF_RX")
	)
	(segment
		(start 433.520342 -393.05103)
		(end 433.520342 -390.97585)
		(width 0.11684)
		(layer "In2.Cu")
		(net "UART_BMC_BIC_BUF_RX")
	)
	(segment
		(start 359.146856 -407.452322)
		(end 358.659176 -407.940002)
		(width 0.11684)
		(layer "In6.Cu")
		(net "UART_BMC_BIC_BUF_RX")
	)
	(segment
		(start 360.658156 -407.105358)
		(end 360.311192 -407.452322)
		(width 0.11684)
		(layer "In6.Cu")
		(net "UART_BMC_BIC_BUF_RX")
	)
	(segment
		(start 358.659176 -407.940002)
		(end 358.659176 -412.916116)
		(width 0.11684)
		(layer "In6.Cu")
		(net "UART_BMC_BIC_BUF_RX")
	)
	(segment
		(start 360.311192 -407.452322)
		(end 359.146856 -407.452322)
		(width 0.11684)
		(layer "In6.Cu")
		(net "UART_BMC_BIC_BUF_RX")
	)
	(segment
		(start 358.659176 -412.916116)
		(end 361.16006 -415.417)
		(width 0.11684)
		(layer "In6.Cu")
		(net "UART_BMC_BIC_BUF_RX")
	)
	(segment
		(start 128.76403 -58.532014)
		(end 127.703326 -58.532014)
		(width 0.10668)
		(layer "F.Cu")
		(net "U212_EN_N")
	)
	(segment
		(start 127.703326 -58.532014)
		(end 127.053086 -57.881774)
		(width 0.10668)
		(layer "F.Cu")
		(net "U212_EN_N")
	)
	(via
		(at 127.053086 -57.881774)
		(size 0.508)
		(drill 0.254)
		(layers "F.Cu" "B.Cu")
		(net "U212_EN_N")
	)
	(segment
		(start 103.59136 -69.90334)
		(end 103.59136 -63.82004)
		(width 0.11684)
		(layer "In6.Cu")
		(net "U212_EN_N")
	)
	(segment
		(start 103.59136 -63.82004)
		(end 104.91978 -62.49162)
		(width 0.11684)
		(layer "In6.Cu")
		(net "U212_EN_N")
	)
	(segment
		(start 22.791166 -73.614788)
		(end 26.834338 -77.65796)
		(width 0.11684)
		(layer "In6.Cu")
		(net "U212_EN_N")
	)
	(segment
		(start 124.831856 -62.68466)
		(end 126.08052 -61.435996)
		(width 0.11684)
		(layer "In6.Cu")
		(net "U212_EN_N")
	)
	(segment
		(start 126.08052 -61.435996)
		(end 126.08052 -58.63844)
		(width 0.11684)
		(layer "In6.Cu")
		(net "U212_EN_N")
	)
	(segment
		(start 26.834338 -77.65796)
		(end 32.25292 -77.65796)
		(width 0.11684)
		(layer "In6.Cu")
		(net "U212_EN_N")
	)
	(segment
		(start 114.94262 -62.49162)
		(end 115.5192 -63.0682)
		(width 0.11684)
		(layer "In6.Cu")
		(net "U212_EN_N")
	)
	(segment
		(start 126.837186 -57.881774)
		(end 127.053086 -57.881774)
		(width 0.11684)
		(layer "In6.Cu")
		(net "U212_EN_N")
	)
	(segment
		(start 104.91978 -62.49162)
		(end 114.94262 -62.49162)
		(width 0.11684)
		(layer "In6.Cu")
		(net "U212_EN_N")
	)
	(segment
		(start 97.12452 -76.37018)
		(end 103.59136 -69.90334)
		(width 0.11684)
		(layer "In6.Cu")
		(net "U212_EN_N")
	)
	(segment
		(start 36.36518 -81.77022)
		(end 54.18074 -81.77022)
		(width 0.11684)
		(layer "In6.Cu")
		(net "U212_EN_N")
	)
	(segment
		(start 54.18074 -81.77022)
		(end 59.58078 -76.37018)
		(width 0.11684)
		(layer "In6.Cu")
		(net "U212_EN_N")
	)
	(segment
		(start 32.25292 -77.65796)
		(end 36.36518 -81.77022)
		(width 0.11684)
		(layer "In6.Cu")
		(net "U212_EN_N")
	)
	(segment
		(start 119.45366 -63.0682)
		(end 119.8372 -62.68466)
		(width 0.11684)
		(layer "In6.Cu")
		(net "U212_EN_N")
	)
	(segment
		(start 59.58078 -76.37018)
		(end 97.12452 -76.37018)
		(width 0.11684)
		(layer "In6.Cu")
		(net "U212_EN_N")
	)
	(segment
		(start 126.08052 -58.63844)
		(end 126.837186 -57.881774)
		(width 0.11684)
		(layer "In6.Cu")
		(net "U212_EN_N")
	)
	(segment
		(start 115.5192 -63.0682)
		(end 119.45366 -63.0682)
		(width 0.11684)
		(layer "In6.Cu")
		(net "U212_EN_N")
	)
	(segment
		(start 119.8372 -62.68466)
		(end 124.831856 -62.68466)
		(width 0.11684)
		(layer "In6.Cu")
		(net "U212_EN_N")
	)
	(segment
		(start 108.097828 -57.852056)
		(end 107.425744 -57.179972)
		(width 0.10668)
		(layer "F.Cu")
		(net "U160_EN_N")
	)
	(segment
		(start 107.425744 -57.179972)
		(end 107.425744 -56.769254)
		(width 0.10668)
		(layer "F.Cu")
		(net "U160_EN_N")
	)
	(segment
		(start 108.940346 -57.852056)
		(end 108.097828 -57.852056)
		(width 0.10668)
		(layer "F.Cu")
		(net "U160_EN_N")
	)
	(via
		(at 107.425744 -56.769254)
		(size 0.508)
		(drill 0.254)
		(layers "F.Cu" "B.Cu")
		(net "U160_EN_N")
	)
	(segment
		(start 52.544726 -80.327754)
		(end 54.22011 -78.65237)
		(width 0.10668)
		(layer "B.Cu")
		(net "U160_EN_N")
	)
	(segment
		(start 108.814108 -71.715376)
		(end 108.814108 -57.358026)
		(width 0.10668)
		(layer "B.Cu")
		(net "U160_EN_N")
	)
	(segment
		(start 108.225336 -56.769254)
		(end 107.425744 -56.769254)
		(width 0.10668)
		(layer "B.Cu")
		(net "U160_EN_N")
	)
	(segment
		(start 24.313896 -80.327754)
		(end 52.544726 -80.327754)
		(width 0.10668)
		(layer "B.Cu")
		(net "U160_EN_N")
	)
	(segment
		(start 101.877114 -78.65237)
		(end 108.814108 -71.715376)
		(width 0.10668)
		(layer "B.Cu")
		(net "U160_EN_N")
	)
	(segment
		(start 54.22011 -78.65237)
		(end 101.877114 -78.65237)
		(width 0.10668)
		(layer "B.Cu")
		(net "U160_EN_N")
	)
	(segment
		(start 108.814108 -57.358026)
		(end 108.225336 -56.769254)
		(width 0.10668)
		(layer "B.Cu")
		(net "U160_EN_N")
	)
	(segment
		(start 22.791166 -78.805024)
		(end 24.313896 -80.327754)
		(width 0.10668)
		(layer "B.Cu")
		(net "U160_EN_N")
	)
	(segment
		(start 130.767328 -54.374288)
		(end 132.970016 -54.374288)
		(width 0.10668)
		(layer "F.Cu")
		(net "U152_OE_N")
	)
	(segment
		(start 132.970016 -54.374288)
		(end 134.189216 -54.374288)
		(width 0.10668)
		(layer "F.Cu")
		(net "U152_OE_N")
	)
	(via
		(at 132.970016 -54.374288)
		(size 0.762)
		(drill 0.381)
		(layers "F.Cu" "B.Cu")
		(net "U152_OE_N")
	)
	(segment
		(start 97.97796 -267.340334)
		(end 97.511108 -267.606272)
		(width 0.10668)
		(layer "F.Cu")
		(net "TP_VSENSE_PVDD33_S5_P1")
	)
	(via
		(at 97.511108 -267.606272)
		(size 0.4064)
		(drill 0.2032)
		(layers "F.Cu" "B.Cu")
		(net "TP_VSENSE_PVDD33_S5_P1")
	)
	(segment
		(start 345.918028 -267.34008)
		(end 345.451176 -267.606018)
		(width 0.10668)
		(layer "F.Cu")
		(net "TP_VSENSE_PVDD33_S5_P0")
	)
	(via
		(at 345.451176 -267.606018)
		(size 0.4064)
		(drill 0.2032)
		(layers "F.Cu" "B.Cu")
		(net "TP_VSENSE_PVDD33_S5_P0")
	)
	(segment
		(start 363.778038 -293.260018)
		(end 364.24489 -293.525956)
		(width 0.10668)
		(layer "F.Cu")
		(net "TP_UART_CPU0_UART0_RTS_N")
	)
	(via
		(at 364.24489 -293.525956)
		(size 0.4064)
		(drill 0.2032)
		(layers "F.Cu" "B.Cu")
		(net "TP_UART_CPU0_UART0_RTS_N")
	)
	(segment
		(start 177.137568 -149.263862)
		(end 176.73828 -148.864574)
		(width 0.10668)
		(layer "F.Cu")
		(net "TP_U27_EN")
	)
	(segment
		(start 176.73828 -148.864574)
		(end 175.687228 -148.864574)
		(width 0.10668)
		(layer "F.Cu")
		(net "TP_U27_EN")
	)
	(segment
		(start 177.137568 -149.589236)
		(end 177.137568 -149.263862)
		(width 0.10668)
		(layer "F.Cu")
		(net "TP_U27_EN")
	)
	(via
		(at 175.687228 -148.864574)
		(size 0.762)
		(drill 0.381)
		(layers "F.Cu" "B.Cu")
		(net "TP_U27_EN")
	)
	(segment
		(start 142.947136 -16.549878)
		(end 142.947136 -19.887946)
		(width 0.10668)
		(layer "F.Cu")
		(net "TP_SPI_2_PLD_IO3")
	)
	(via
		(at 142.947136 -19.887946)
		(size 0.762)
		(drill 0.381)
		(layers "F.Cu" "B.Cu")
		(net "TP_SPI_2_PLD_IO3")
	)
	(segment
		(start 143.547084 -20.811998)
		(end 142.956534 -21.402548)
		(width 0.10668)
		(layer "F.Cu")
		(net "TP_SPI_2_PLD_IO2")
	)
	(segment
		(start 143.547084 -16.549878)
		(end 143.547084 -20.811998)
		(width 0.10668)
		(layer "F.Cu")
		(net "TP_SPI_2_PLD_IO2")
	)
	(via
		(at 142.956534 -21.402548)
		(size 0.762)
		(drill 0.381)
		(layers "F.Cu" "B.Cu")
		(net "TP_SPI_2_PLD_IO2")
	)
	(segment
		(start 144.147032 -16.549878)
		(end 144.147032 -20.586446)
		(width 0.10668)
		(layer "F.Cu")
		(net "TP_SPI_2_PLD_IO1")
	)
	(via
		(at 144.147032 -20.586446)
		(size 0.762)
		(drill 0.381)
		(layers "F.Cu" "B.Cu")
		(net "TP_SPI_2_PLD_IO1")
	)
	(segment
		(start 144.74698 -21.593302)
		(end 144.150334 -22.189948)
		(width 0.10668)
		(layer "F.Cu")
		(net "TP_SPI_2_PLD_IO0")
	)
	(segment
		(start 144.74698 -16.549878)
		(end 144.74698 -21.593302)
		(width 0.10668)
		(layer "F.Cu")
		(net "TP_SPI_2_PLD_IO0")
	)
	(via
		(at 144.150334 -22.189948)
		(size 0.762)
		(drill 0.381)
		(layers "F.Cu" "B.Cu")
		(net "TP_SPI_2_PLD_IO0")
	)
	(segment
		(start 145.346928 -16.549878)
		(end 145.346928 -19.776948)
		(width 0.10668)
		(layer "F.Cu")
		(net "TP_SPI_2_PLD_CS_N")
	)
	(via
		(at 145.346928 -19.776948)
		(size 0.762)
		(drill 0.381)
		(layers "F.Cu" "B.Cu")
		(net "TP_SPI_2_PLD_CS_N")
	)
	(segment
		(start 145.94713 -16.549878)
		(end 145.94713 -20.621752)
		(width 0.10668)
		(layer "F.Cu")
		(net "TP_SPI_2_PLD_CLK")
	)
	(segment
		(start 145.94713 -20.621752)
		(end 145.344134 -21.224748)
		(width 0.10668)
		(layer "F.Cu")
		(net "TP_SPI_2_PLD_CLK")
	)
	(via
		(at 145.344134 -21.224748)
		(size 0.762)
		(drill 0.381)
		(layers "F.Cu" "B.Cu")
		(net "TP_SPI_2_PLD_CLK")
	)
	(segment
		(start 130.946906 -20.972018)
		(end 130.946906 -19.752818)
		(width 0.10668)
		(layer "F.Cu")
		(net "TP_PCIE_TXP<3>")
	)
	(segment
		(start 130.946906 -16.549878)
		(end 130.946906 -19.752818)
		(width 0.10668)
		(layer "F.Cu")
		(net "TP_PCIE_TXP<3>")
	)
	(via
		(at 130.946906 -19.752818)
		(size 0.762)
		(drill 0.381)
		(layers "F.Cu" "B.Cu")
		(net "TP_PCIE_TXP<3>")
	)
	(segment
		(start 134.546848 -16.549878)
		(end 134.546848 -19.371818)
		(width 0.10668)
		(layer "F.Cu")
		(net "TP_PCIE_TXP<1>")
	)
	(segment
		(start 134.546848 -19.371818)
		(end 134.165848 -19.752818)
		(width 0.10668)
		(layer "F.Cu")
		(net "TP_PCIE_TXP<1>")
	)
	(segment
		(start 134.547102 -16.549878)
		(end 134.546848 -16.549878)
		(width 0.10668)
		(layer "F.Cu")
		(net "TP_PCIE_TXP<1>")
	)
	(via
		(at 134.165848 -19.752818)
		(size 0.762)
		(drill 0.381)
		(layers "F.Cu" "B.Cu")
		(net "TP_PCIE_TXP<1>")
	)
	(segment
		(start 133.9469 -18.686018)
		(end 132.8801 -19.752818)
		(width 0.10668)
		(layer "F.Cu")
		(net "TP_PCIE_TXN<1>")
	)
	(segment
		(start 133.9469 -16.549878)
		(end 133.9469 -18.686018)
		(width 0.10668)
		(layer "F.Cu")
		(net "TP_PCIE_TXN<1>")
	)
	(via
		(at 132.8801 -19.752818)
		(size 0.762)
		(drill 0.381)
		(layers "F.Cu" "B.Cu")
		(net "TP_PCIE_TXN<1>")
	)
	(segment
		(start 134.547102 -13.599922)
		(end 134.547102 -8.469884)
		(width 0.10668)
		(layer "F.Cu")
		(net "TP_PCIE_RXP<1>")
	)
	(via
		(at 134.547102 -8.469884)
		(size 0.508)
		(drill 0.254)
		(layers "F.Cu" "B.Cu")
		(net "TP_PCIE_RXP<1>")
	)
	(segment
		(start 133.9469 -9.139682)
		(end 133.277102 -8.469884)
		(width 0.10668)
		(layer "F.Cu")
		(net "TP_PCIE_RXN<1>")
	)
	(segment
		(start 133.9469 -13.599922)
		(end 133.9469 -9.139682)
		(width 0.10668)
		(layer "F.Cu")
		(net "TP_PCIE_RXN<1>")
	)
	(via
		(at 133.277102 -8.469884)
		(size 0.508)
		(drill 0.254)
		(layers "F.Cu" "B.Cu")
		(net "TP_PCIE_RXN<1>")
	)
	(segment
		(start 17.34693 -10.57275)
		(end 17.34693 -11.26998)
		(width 0.10668)
		(layer "F.Cu")
		(net "TP_OCP_V3_2_B69")
	)
	(segment
		(start 15.089124 -14.49197)
		(end 15.089124 -13.61313)
		(width 0.10668)
		(layer "F.Cu")
		(net "TP_OCP_V3_2_B69")
	)
	(segment
		(start 16.487394 -10.267696)
		(end 17.041876 -10.267696)
		(width 0.10668)
		(layer "F.Cu")
		(net "TP_OCP_V3_2_B69")
	)
	(segment
		(start 16.25219 -10.5029)
		(end 16.487394 -10.267696)
		(width 0.10668)
		(layer "F.Cu")
		(net "TP_OCP_V3_2_B69")
	)
	(segment
		(start 15.089124 -13.61313)
		(end 16.25219 -12.450064)
		(width 0.10668)
		(layer "F.Cu")
		(net "TP_OCP_V3_2_B69")
	)
	(segment
		(start 17.041876 -10.267696)
		(end 17.34693 -10.57275)
		(width 0.10668)
		(layer "F.Cu")
		(net "TP_OCP_V3_2_B69")
	)
	(segment
		(start 16.25219 -12.450064)
		(end 16.25219 -10.5029)
		(width 0.10668)
		(layer "F.Cu")
		(net "TP_OCP_V3_2_B69")
	)
	(via
		(at 15.089124 -14.49197)
		(size 0.762)
		(drill 0.381)
		(layers "F.Cu" "B.Cu")
		(net "TP_OCP_V3_2_B69")
	)
	(segment
		(start 17.946878 -10.324084)
		(end 17.946878 -11.26998)
		(width 0.10668)
		(layer "F.Cu")
		(net "TP_OCP_V3_2_B68")
	)
	(segment
		(start 17.351248 -9.728454)
		(end 17.946878 -10.324084)
		(width 0.10668)
		(layer "F.Cu")
		(net "TP_OCP_V3_2_B68")
	)
	(segment
		(start 15.833344 -10.341356)
		(end 16.446246 -9.728454)
		(width 0.10668)
		(layer "F.Cu")
		(net "TP_OCP_V3_2_B68")
	)
	(segment
		(start 14.518132 -13.600176)
		(end 15.833344 -12.284964)
		(width 0.10668)
		(layer "F.Cu")
		(net "TP_OCP_V3_2_B68")
	)
	(segment
		(start 15.833344 -12.284964)
		(end 15.833344 -10.341356)
		(width 0.10668)
		(layer "F.Cu")
		(net "TP_OCP_V3_2_B68")
	)
	(segment
		(start 14.046454 -13.600176)
		(end 14.518132 -13.600176)
		(width 0.10668)
		(layer "F.Cu")
		(net "TP_OCP_V3_2_B68")
	)
	(segment
		(start 16.446246 -9.728454)
		(end 17.351248 -9.728454)
		(width 0.10668)
		(layer "F.Cu")
		(net "TP_OCP_V3_2_B68")
	)
	(via
		(at 14.046454 -13.600176)
		(size 0.762)
		(drill 0.381)
		(layers "F.Cu" "B.Cu")
		(net "TP_OCP_V3_2_B68")
	)
	(segment
		(start 389.58901 -14.52499)
		(end 389.58901 -13.61313)
		(width 0.10668)
		(layer "F.Cu")
		(net "TP_OCP_SFF_B69")
	)
	(segment
		(start 391.562844 -10.288778)
		(end 391.846816 -10.57275)
		(width 0.10668)
		(layer "F.Cu")
		(net "TP_OCP_SFF_B69")
	)
	(segment
		(start 389.58901 -13.61313)
		(end 390.71931 -12.48283)
		(width 0.10668)
		(layer "F.Cu")
		(net "TP_OCP_SFF_B69")
	)
	(segment
		(start 391.846816 -10.57275)
		(end 391.846816 -11.26998)
		(width 0.10668)
		(layer "F.Cu")
		(net "TP_OCP_SFF_B69")
	)
	(segment
		(start 390.71931 -10.535666)
		(end 390.966198 -10.288778)
		(width 0.10668)
		(layer "F.Cu")
		(net "TP_OCP_SFF_B69")
	)
	(segment
		(start 390.71931 -12.48283)
		(end 390.71931 -10.535666)
		(width 0.10668)
		(layer "F.Cu")
		(net "TP_OCP_SFF_B69")
	)
	(segment
		(start 390.966198 -10.288778)
		(end 391.562844 -10.288778)
		(width 0.10668)
		(layer "F.Cu")
		(net "TP_OCP_SFF_B69")
	)
	(via
		(at 389.58901 -14.52499)
		(size 0.762)
		(drill 0.381)
		(layers "F.Cu" "B.Cu")
		(net "TP_OCP_SFF_B69")
	)
	(segment
		(start 390.985756 -9.68883)
		(end 391.81151 -9.68883)
		(width 0.10668)
		(layer "F.Cu")
		(net "TP_OCP_SFF_B68")
	)
	(segment
		(start 391.81151 -9.68883)
		(end 392.446764 -10.324084)
		(width 0.10668)
		(layer "F.Cu")
		(net "TP_OCP_SFF_B68")
	)
	(segment
		(start 390.33323 -12.246356)
		(end 390.33323 -10.341356)
		(width 0.10668)
		(layer "F.Cu")
		(net "TP_OCP_SFF_B68")
	)
	(segment
		(start 392.446764 -10.324084)
		(end 392.446764 -11.26998)
		(width 0.10668)
		(layer "F.Cu")
		(net "TP_OCP_SFF_B68")
	)
	(segment
		(start 388.96925 -15.767812)
		(end 388.96925 -13.610336)
		(width 0.10668)
		(layer "F.Cu")
		(net "TP_OCP_SFF_B68")
	)
	(segment
		(start 390.33323 -10.341356)
		(end 390.985756 -9.68883)
		(width 0.10668)
		(layer "F.Cu")
		(net "TP_OCP_SFF_B68")
	)
	(segment
		(start 388.844536 -15.892526)
		(end 388.96925 -15.767812)
		(width 0.10668)
		(layer "F.Cu")
		(net "TP_OCP_SFF_B68")
	)
	(segment
		(start 388.96925 -13.610336)
		(end 390.33323 -12.246356)
		(width 0.10668)
		(layer "F.Cu")
		(net "TP_OCP_SFF_B68")
	)
	(via
		(at 388.844536 -15.892526)
		(size 0.762)
		(drill 0.381)
		(layers "F.Cu" "B.Cu")
		(net "TP_OCP_SFF_B68")
	)
	(segment
		(start 137.457942 -260.860286)
		(end 137.924794 -261.126224)
		(width 0.10668)
		(layer "F.Cu")
		(net "TP_M_L_CPU1_SA_TEST39L")
	)
	(via
		(at 137.924794 -261.126224)
		(size 0.4064)
		(drill 0.2032)
		(layers "F.Cu" "B.Cu")
		(net "TP_M_L_CPU1_SA_TEST39L")
	)
	(segment
		(start 385.39801 -260.860032)
		(end 385.864862 -261.12597)
		(width 0.10668)
		(layer "F.Cu")
		(net "TP_M_L_CPU0_SA_TEST39L")
	)
	(via
		(at 385.864862 -261.12597)
		(size 0.4064)
		(drill 0.2032)
		(layers "F.Cu" "B.Cu")
		(net "TP_M_L_CPU0_SA_TEST39L")
	)
	(segment
		(start 141.217904 -260.860286)
		(end 141.684756 -261.126224)
		(width 0.10668)
		(layer "F.Cu")
		(net "TP_M_K_CPU1_SA_TEST39K")
	)
	(via
		(at 141.684756 -261.126224)
		(size 0.4064)
		(drill 0.2032)
		(layers "F.Cu" "B.Cu")
		(net "TP_M_K_CPU1_SA_TEST39K")
	)
	(segment
		(start 389.157972 -260.860032)
		(end 389.624824 -261.12597)
		(width 0.10668)
		(layer "F.Cu")
		(net "TP_M_K_CPU0_SA_TEST39K")
	)
	(via
		(at 389.624824 -261.12597)
		(size 0.4064)
		(drill 0.2032)
		(layers "F.Cu" "B.Cu")
		(net "TP_M_K_CPU0_SA_TEST39K")
	)
	(segment
		(start 130.877818 -260.860286)
		(end 131.34467 -261.126224)
		(width 0.10668)
		(layer "F.Cu")
		(net "TP_M_J_CPU1_SA_TEST39J")
	)
	(via
		(at 131.34467 -261.126224)
		(size 0.4064)
		(drill 0.2032)
		(layers "F.Cu" "B.Cu")
		(net "TP_M_J_CPU1_SA_TEST39J")
	)
	(segment
		(start 378.817886 -260.860032)
		(end 379.284738 -261.12597)
		(width 0.10668)
		(layer "F.Cu")
		(net "TP_M_J_CPU0_SA_TEST39J")
	)
	(via
		(at 379.284738 -261.12597)
		(size 0.4064)
		(drill 0.2032)
		(layers "F.Cu" "B.Cu")
		(net "TP_M_J_CPU0_SA_TEST39J")
	)
	(segment
		(start 128.05791 -260.860286)
		(end 128.524762 -261.126224)
		(width 0.10668)
		(layer "F.Cu")
		(net "TP_M_I_CPU1_SA_TEST39I")
	)
	(via
		(at 128.524762 -261.126224)
		(size 0.4064)
		(drill 0.2032)
		(layers "F.Cu" "B.Cu")
		(net "TP_M_I_CPU1_SA_TEST39I")
	)
	(segment
		(start 375.997978 -260.860032)
		(end 376.46483 -261.12597)
		(width 0.10668)
		(layer "F.Cu")
		(net "TP_M_I_CPU0_SA_TEST39I")
	)
	(via
		(at 376.46483 -261.12597)
		(size 0.4064)
		(drill 0.2032)
		(layers "F.Cu" "B.Cu")
		(net "TP_M_I_CPU0_SA_TEST39I")
	)
	(segment
		(start 134.63778 -260.860286)
		(end 135.104632 -261.126224)
		(width 0.10668)
		(layer "F.Cu")
		(net "TP_M_H_CPU1_SA_TEST39H")
	)
	(via
		(at 135.104632 -261.126224)
		(size 0.4064)
		(drill 0.2032)
		(layers "F.Cu" "B.Cu")
		(net "TP_M_H_CPU1_SA_TEST39H")
	)
	(segment
		(start 382.577848 -260.860032)
		(end 383.0447 -261.12597)
		(width 0.10668)
		(layer "F.Cu")
		(net "TP_M_H_CPU0_SA_TEST39H")
	)
	(via
		(at 383.0447 -261.12597)
		(size 0.4064)
		(drill 0.2032)
		(layers "F.Cu" "B.Cu")
		(net "TP_M_H_CPU0_SA_TEST39H")
	)
	(segment
		(start 144.037812 -260.860286)
		(end 144.504664 -261.126224)
		(width 0.10668)
		(layer "F.Cu")
		(net "TP_M_G_CPU1_SA_TEST39G")
	)
	(via
		(at 144.504664 -261.126224)
		(size 0.4064)
		(drill 0.2032)
		(layers "F.Cu" "B.Cu")
		(net "TP_M_G_CPU1_SA_TEST39G")
	)
	(segment
		(start 391.97788 -260.860032)
		(end 392.444732 -261.12597)
		(width 0.10668)
		(layer "F.Cu")
		(net "TP_M_G_CPU0_SA_TEST39G")
	)
	(via
		(at 392.444732 -261.12597)
		(size 0.4064)
		(drill 0.2032)
		(layers "F.Cu" "B.Cu")
		(net "TP_M_G_CPU0_SA_TEST39G")
	)
	(segment
		(start 86.69782 -260.860286)
		(end 86.230968 -261.126224)
		(width 0.10668)
		(layer "F.Cu")
		(net "TP_M_F_CPU1_SA_TEST39F")
	)
	(via
		(at 86.230968 -261.126224)
		(size 0.4064)
		(drill 0.2032)
		(layers "F.Cu" "B.Cu")
		(net "TP_M_F_CPU1_SA_TEST39F")
	)
	(segment
		(start 334.637888 -260.860032)
		(end 334.171036 -261.12597)
		(width 0.10668)
		(layer "F.Cu")
		(net "TP_M_F_CPU0_SA_TEST39F")
	)
	(via
		(at 334.171036 -261.12597)
		(size 0.4064)
		(drill 0.2032)
		(layers "F.Cu" "B.Cu")
		(net "TP_M_F_CPU0_SA_TEST39F")
	)
	(segment
		(start 82.937858 -260.860286)
		(end 82.471006 -261.126224)
		(width 0.10668)
		(layer "F.Cu")
		(net "TP_M_E_CPU1_SA_TEST39E")
	)
	(via
		(at 82.471006 -261.126224)
		(size 0.4064)
		(drill 0.2032)
		(layers "F.Cu" "B.Cu")
		(net "TP_M_E_CPU1_SA_TEST39E")
	)
	(segment
		(start 330.877926 -260.860032)
		(end 330.411074 -261.12597)
		(width 0.10668)
		(layer "F.Cu")
		(net "TP_M_E_CPU0_SA_TEST39E")
	)
	(via
		(at 330.411074 -261.12597)
		(size 0.4064)
		(drill 0.2032)
		(layers "F.Cu" "B.Cu")
		(net "TP_M_E_CPU0_SA_TEST39E")
	)
	(segment
		(start 93.277944 -260.860286)
		(end 92.811092 -261.126224)
		(width 0.10668)
		(layer "F.Cu")
		(net "TP_M_D_CPU1_SA_TEST39D")
	)
	(via
		(at 92.811092 -261.126224)
		(size 0.4064)
		(drill 0.2032)
		(layers "F.Cu" "B.Cu")
		(net "TP_M_D_CPU1_SA_TEST39D")
	)
	(segment
		(start 341.218012 -260.860032)
		(end 340.75116 -261.12597)
		(width 0.10668)
		(layer "F.Cu")
		(net "TP_M_D_CPU0_SA_TEST39D")
	)
	(via
		(at 340.75116 -261.12597)
		(size 0.4064)
		(drill 0.2032)
		(layers "F.Cu" "B.Cu")
		(net "TP_M_D_CPU0_SA_TEST39D")
	)
	(segment
		(start 96.097852 -260.860286)
		(end 95.631 -261.126224)
		(width 0.10668)
		(layer "F.Cu")
		(net "TP_M_C_CPU1_SA_TEST39C")
	)
	(via
		(at 95.631 -261.126224)
		(size 0.4064)
		(drill 0.2032)
		(layers "F.Cu" "B.Cu")
		(net "TP_M_C_CPU1_SA_TEST39C")
	)
	(segment
		(start 344.03792 -260.860032)
		(end 343.571068 -261.12597)
		(width 0.10668)
		(layer "F.Cu")
		(net "TP_M_C_CPU0_SA_TEST39C")
	)
	(via
		(at 343.571068 -261.12597)
		(size 0.4064)
		(drill 0.2032)
		(layers "F.Cu" "B.Cu")
		(net "TP_M_C_CPU0_SA_TEST39C")
	)
	(segment
		(start 89.517982 -260.860286)
		(end 89.05113 -261.126224)
		(width 0.10668)
		(layer "F.Cu")
		(net "TP_M_B_CPU1_SA_TEST39B")
	)
	(via
		(at 89.05113 -261.126224)
		(size 0.4064)
		(drill 0.2032)
		(layers "F.Cu" "B.Cu")
		(net "TP_M_B_CPU1_SA_TEST39B")
	)
	(segment
		(start 337.45805 -260.860032)
		(end 336.991198 -261.12597)
		(width 0.10668)
		(layer "F.Cu")
		(net "TP_M_B_CPU0_SA_TEST39B")
	)
	(via
		(at 336.991198 -261.12597)
		(size 0.4064)
		(drill 0.2032)
		(layers "F.Cu" "B.Cu")
		(net "TP_M_B_CPU0_SA_TEST39B")
	)
	(segment
		(start 91.568016 -223.690434)
		(end 91.10091 -223.424496)
		(width 0.10668)
		(layer "F.Cu")
		(net "TP_M_A_CPU1_SA_TEST40")
	)
	(via
		(at 91.10091 -223.424496)
		(size 0.4064)
		(drill 0.2032)
		(layers "F.Cu" "B.Cu")
		(net "TP_M_A_CPU1_SA_TEST40")
	)
	(segment
		(start 80.11795 -260.860286)
		(end 79.651098 -261.126224)
		(width 0.10668)
		(layer "F.Cu")
		(net "TP_M_A_CPU1_SA_TEST39A")
	)
	(via
		(at 79.651098 -261.126224)
		(size 0.4064)
		(drill 0.2032)
		(layers "F.Cu" "B.Cu")
		(net "TP_M_A_CPU1_SA_TEST39A")
	)
	(segment
		(start 339.508084 -223.69018)
		(end 339.040978 -223.424242)
		(width 0.10668)
		(layer "F.Cu")
		(net "TP_M_A_CPU0_SA_TEST40")
	)
	(via
		(at 339.040978 -223.424242)
		(size 0.4064)
		(drill 0.2032)
		(layers "F.Cu" "B.Cu")
		(net "TP_M_A_CPU0_SA_TEST40")
	)
	(segment
		(start 328.058018 -260.860032)
		(end 327.591166 -261.12597)
		(width 0.10668)
		(layer "F.Cu")
		(net "TP_M_A_CPU0_SA_TEST39A")
	)
	(via
		(at 327.591166 -261.12597)
		(size 0.4064)
		(drill 0.2032)
		(layers "F.Cu" "B.Cu")
		(net "TP_M_A_CPU0_SA_TEST39A")
	)
	(segment
		(start 107.590082 -61.799978)
		(end 107.590082 -62.450472)
		(width 0.10668)
		(layer "F.Cu")
		(net "TP_JTAG_SCM_SLOT3_R_TMS")
	)
	(segment
		(start 108.940346 -61.202062)
		(end 108.187998 -61.202062)
		(width 0.10668)
		(layer "F.Cu")
		(net "TP_JTAG_SCM_SLOT3_R_TMS")
	)
	(segment
		(start 108.187998 -61.202062)
		(end 107.590082 -61.799978)
		(width 0.10668)
		(layer "F.Cu")
		(net "TP_JTAG_SCM_SLOT3_R_TMS")
	)
	(via
		(at 107.590082 -62.450472)
		(size 0.762)
		(drill 0.381)
		(layers "F.Cu" "B.Cu")
		(net "TP_JTAG_SCM_SLOT3_R_TMS")
	)
	(segment
		(start 129.19837 -61.88202)
		(end 129.715768 -62.399418)
		(width 0.10668)
		(layer "F.Cu")
		(net "TP_JTAG_SCM_SLOT3_R_TDO")
	)
	(segment
		(start 128.76403 -61.88202)
		(end 129.19837 -61.88202)
		(width 0.10668)
		(layer "F.Cu")
		(net "TP_JTAG_SCM_SLOT3_R_TDO")
	)
	(segment
		(start 129.715768 -62.399418)
		(end 129.715768 -63.157354)
		(width 0.10668)
		(layer "F.Cu")
		(net "TP_JTAG_SCM_SLOT3_R_TDO")
	)
	(via
		(at 129.715768 -63.157354)
		(size 0.762)
		(drill 0.381)
		(layers "F.Cu" "B.Cu")
		(net "TP_JTAG_SCM_SLOT3_R_TDO")
	)
	(segment
		(start 136.807702 -59.182)
		(end 134.614158 -59.182)
		(width 0.10668)
		(layer "F.Cu")
		(net "TP_JTAG_SCM_SLOT3_R_TDI")
	)
	(via
		(at 136.807702 -59.182)
		(size 0.508)
		(drill 0.254)
		(layers "F.Cu" "B.Cu")
		(net "TP_JTAG_SCM_SLOT3_R_TDI")
	)
	(segment
		(start 116.998496 -58.502042)
		(end 114.790474 -58.502042)
		(width 0.10668)
		(layer "F.Cu")
		(net "TP_JTAG_SCM_SLOT3_R_TCK")
	)
	(via
		(at 116.998496 -58.502042)
		(size 0.508)
		(drill 0.254)
		(layers "F.Cu" "B.Cu")
		(net "TP_JTAG_SCM_SLOT3_R_TCK")
	)
	(segment
		(start 144.82318 -13.523722)
		(end 144.82318 -12.197334)
		(width 0.10668)
		(layer "F.Cu")
		(net "TP_STBY_EN")
	)
	(segment
		(start 144.74698 -13.599922)
		(end 144.82318 -13.523722)
		(width 0.10668)
		(layer "F.Cu")
		(net "TP_STBY_EN")
	)
	(segment
		(start 144.82318 -12.197334)
		(end 144.833086 -12.187428)
		(width 0.10668)
		(layer "F.Cu")
		(net "TP_STBY_EN")
	)
	(via
		(at 144.833086 -12.187428)
		(size 0.508)
		(drill 0.254)
		(layers "F.Cu" "B.Cu")
		(net "TP_STBY_EN")
	)
	(segment
		(start 234.447588 -41.780968)
		(end 232.199942 -41.780968)
		(width 0.10668)
		(layer "F.Cu")
		(net "TP_E1S_0_RFU")
	)
	(segment
		(start 234.988862 -46.233842)
		(end 234.988862 -42.322242)
		(width 0.10668)
		(layer "F.Cu")
		(net "TP_E1S_0_RFU")
	)
	(segment
		(start 228.032564 -40.113712)
		(end 227.445824 -39.526972)
		(width 0.10668)
		(layer "F.Cu")
		(net "TP_E1S_0_RFU")
	)
	(segment
		(start 232.199942 -41.780968)
		(end 230.532686 -40.113712)
		(width 0.10668)
		(layer "F.Cu")
		(net "TP_E1S_0_RFU")
	)
	(segment
		(start 234.988862 -42.322242)
		(end 234.447588 -41.780968)
		(width 0.10668)
		(layer "F.Cu")
		(net "TP_E1S_0_RFU")
	)
	(segment
		(start 236.599984 -46.764956)
		(end 235.519976 -46.764956)
		(width 0.10668)
		(layer "F.Cu")
		(net "TP_E1S_0_RFU")
	)
	(segment
		(start 235.519976 -46.764956)
		(end 234.988862 -46.233842)
		(width 0.10668)
		(layer "F.Cu")
		(net "TP_E1S_0_RFU")
	)
	(segment
		(start 230.532686 -40.113712)
		(end 228.032564 -40.113712)
		(width 0.10668)
		(layer "F.Cu")
		(net "TP_E1S_0_RFU")
	)
	(via
		(at 227.445824 -39.526972)
		(size 0.762)
		(drill 0.381)
		(layers "F.Cu" "B.Cu")
		(net "TP_E1S_0_RFU")
	)
	(segment
		(start 235.3183 -42.33545)
		(end 234.540298 -41.557448)
		(width 0.10668)
		(layer "F.Cu")
		(net "TP_E1S_0_MFG")
	)
	(segment
		(start 235.4453 -46.165008)
		(end 235.3183 -46.038008)
		(width 0.10668)
		(layer "F.Cu")
		(net "TP_E1S_0_MFG")
	)
	(segment
		(start 230.262176 -39.526972)
		(end 228.715824 -39.526972)
		(width 0.10668)
		(layer "F.Cu")
		(net "TP_E1S_0_MFG")
	)
	(segment
		(start 235.3183 -46.038008)
		(end 235.3183 -42.33545)
		(width 0.10668)
		(layer "F.Cu")
		(net "TP_E1S_0_MFG")
	)
	(segment
		(start 232.292652 -41.557448)
		(end 230.262176 -39.526972)
		(width 0.10668)
		(layer "F.Cu")
		(net "TP_E1S_0_MFG")
	)
	(segment
		(start 234.540298 -41.557448)
		(end 232.292652 -41.557448)
		(width 0.10668)
		(layer "F.Cu")
		(net "TP_E1S_0_MFG")
	)
	(segment
		(start 236.599984 -46.165008)
		(end 235.4453 -46.165008)
		(width 0.10668)
		(layer "F.Cu")
		(net "TP_E1S_0_MFG")
	)
	(via
		(at 228.715824 -39.526972)
		(size 0.762)
		(drill 0.381)
		(layers "F.Cu" "B.Cu")
		(net "TP_E1S_0_MFG")
	)
	(segment
		(start 116.77777 -294.880284)
		(end 117.244622 -295.146222)
		(width 0.10668)
		(layer "F.Cu")
		(net "TP_CPU1_UART1_RX")
	)
	(via
		(at 117.244622 -295.146222)
		(size 0.4064)
		(drill 0.2032)
		(layers "F.Cu" "B.Cu")
		(net "TP_CPU1_UART1_RX")
	)
	(segment
		(start 115.367816 -295.69029)
		(end 115.834668 -295.956228)
		(width 0.10668)
		(layer "F.Cu")
		(net "TP_CPU1_UART0_TX")
	)
	(via
		(at 115.834668 -295.956228)
		(size 0.4064)
		(drill 0.2032)
		(layers "F.Cu" "B.Cu")
		(net "TP_CPU1_UART0_TX")
	)
	(segment
		(start 114.428016 -294.070278)
		(end 114.894614 -294.336216)
		(width 0.10668)
		(layer "F.Cu")
		(net "TP_CPU1_UART0_RX")
	)
	(via
		(at 114.894614 -294.336216)
		(size 0.4064)
		(drill 0.2032)
		(layers "F.Cu" "B.Cu")
		(net "TP_CPU1_UART0_RX")
	)
	(segment
		(start 115.83797 -293.260272)
		(end 116.304822 -293.52621)
		(width 0.10668)
		(layer "F.Cu")
		(net "TP_CPU1_UART0_RTS_N")
	)
	(via
		(at 116.304822 -293.52621)
		(size 0.4064)
		(drill 0.2032)
		(layers "F.Cu" "B.Cu")
		(net "TP_CPU1_UART0_RTS_N")
	)
	(segment
		(start 115.367816 -294.070278)
		(end 115.834668 -294.336216)
		(width 0.10668)
		(layer "F.Cu")
		(net "TP_CPU1_UART0_INTR")
	)
	(via
		(at 115.834668 -294.336216)
		(size 0.4064)
		(drill 0.2032)
		(layers "F.Cu" "B.Cu")
		(net "TP_CPU1_UART0_INTR")
	)
	(segment
		(start 116.30787 -295.69029)
		(end 116.774722 -295.956228)
		(width 0.10668)
		(layer "F.Cu")
		(net "TP_CPU1_UART0_CTS_N")
	)
	(via
		(at 116.774722 -295.956228)
		(size 0.4064)
		(drill 0.2032)
		(layers "F.Cu" "B.Cu")
		(net "TP_CPU1_UART0_CTS_N")
	)
	(segment
		(start 98.44786 -279.490424)
		(end 97.981008 -279.756362)
		(width 0.10668)
		(layer "F.Cu")
		(net "TP_CPU1_TEST6_X3D5")
	)
	(via
		(at 97.981008 -279.756362)
		(size 0.4064)
		(drill 0.2032)
		(layers "F.Cu" "B.Cu")
		(net "TP_CPU1_TEST6_X3D5")
	)
	(segment
		(start 125.407928 -238.270288)
		(end 125.87478 -238.00435)
		(width 0.10668)
		(layer "F.Cu")
		(net "TP_CPU1_TEST6_X3D4")
	)
	(via
		(at 125.87478 -238.00435)
		(size 0.4064)
		(drill 0.2032)
		(layers "F.Cu" "B.Cu")
		(net "TP_CPU1_TEST6_X3D4")
	)
	(segment
		(start 99.387914 -279.490424)
		(end 98.921062 -279.756362)
		(width 0.10668)
		(layer "F.Cu")
		(net "TP_CPU1_TEST6_X3D3")
	)
	(via
		(at 98.921062 -279.756362)
		(size 0.4064)
		(drill 0.2032)
		(layers "F.Cu" "B.Cu")
		(net "TP_CPU1_TEST6_X3D3")
	)
	(segment
		(start 119.767858 -238.270288)
		(end 120.23471 -238.00435)
		(width 0.10668)
		(layer "F.Cu")
		(net "TP_CPU1_TEST6_X3D2")
	)
	(via
		(at 120.23471 -238.00435)
		(size 0.4064)
		(drill 0.2032)
		(layers "F.Cu" "B.Cu")
		(net "TP_CPU1_TEST6_X3D2")
	)
	(segment
		(start 120.067832 -279.490424)
		(end 120.534684 -279.756362)
		(width 0.10668)
		(layer "F.Cu")
		(net "TP_CPU1_TEST6_X3D1")
	)
	(via
		(at 120.534684 -279.756362)
		(size 0.4064)
		(drill 0.2032)
		(layers "F.Cu" "B.Cu")
		(net "TP_CPU1_TEST6_X3D1")
	)
	(segment
		(start 103.787956 -238.270288)
		(end 103.321104 -238.00435)
		(width 0.10668)
		(layer "F.Cu")
		(net "TP_CPU1_TEST6_X3D0")
	)
	(via
		(at 103.321104 -238.00435)
		(size 0.4064)
		(drill 0.2032)
		(layers "F.Cu" "B.Cu")
		(net "TP_CPU1_TEST6_X3D0")
	)
	(segment
		(start 101.907848 -238.270288)
		(end 101.440996 -238.00435)
		(width 0.10668)
		(layer "F.Cu")
		(net "TP_CPU1_TEST6_IOD")
	)
	(via
		(at 101.440996 -238.00435)
		(size 0.4064)
		(drill 0.2032)
		(layers "F.Cu" "B.Cu")
		(net "TP_CPU1_TEST6_IOD")
	)
	(segment
		(start 104.257856 -237.460282)
		(end 103.791004 -237.194344)
		(width 0.10668)
		(layer "F.Cu")
		(net "TP_CPU1_TEST6_CCD3")
	)
	(via
		(at 103.791004 -237.194344)
		(size 0.4064)
		(drill 0.2032)
		(layers "F.Cu" "B.Cu")
		(net "TP_CPU1_TEST6_CCD3")
	)
	(segment
		(start 105.027984 -279.490424)
		(end 104.561132 -279.756362)
		(width 0.10668)
		(layer "F.Cu")
		(net "TP_CPU1_TEST6_CCD2")
	)
	(via
		(at 104.561132 -279.756362)
		(size 0.4064)
		(drill 0.2032)
		(layers "F.Cu" "B.Cu")
		(net "TP_CPU1_TEST6_CCD2")
	)
	(segment
		(start 119.127778 -279.490424)
		(end 119.59463 -279.756362)
		(width 0.10668)
		(layer "F.Cu")
		(net "TP_CPU1_TEST6_CCD1")
	)
	(via
		(at 119.59463 -279.756362)
		(size 0.4064)
		(drill 0.2032)
		(layers "F.Cu" "B.Cu")
		(net "TP_CPU1_TEST6_CCD1")
	)
	(segment
		(start 104.72801 -238.270288)
		(end 104.261158 -238.00435)
		(width 0.10668)
		(layer "F.Cu")
		(net "TP_CPU1_TEST6_CCD0")
	)
	(via
		(at 104.261158 -238.00435)
		(size 0.4064)
		(drill 0.2032)
		(layers "F.Cu" "B.Cu")
		(net "TP_CPU1_TEST6_CCD0")
	)
	(segment
		(start 124.467874 -238.270288)
		(end 124.934726 -238.00435)
		(width 0.10668)
		(layer "F.Cu")
		(net "TP_CPU1_TEST5_IOD")
	)
	(via
		(at 124.934726 -238.00435)
		(size 0.4064)
		(drill 0.2032)
		(layers "F.Cu" "B.Cu")
		(net "TP_CPU1_TEST5_IOD")
	)
	(segment
		(start 120.537986 -280.30043)
		(end 121.004838 -280.566368)
		(width 0.10668)
		(layer "F.Cu")
		(net "TP_CPU1_TEST5_CCD9")
	)
	(via
		(at 121.004838 -280.566368)
		(size 0.4064)
		(drill 0.2032)
		(layers "F.Cu" "B.Cu")
		(net "TP_CPU1_TEST5_CCD9")
	)
	(segment
		(start 103.317802 -237.460282)
		(end 102.85095 -237.194344)
		(width 0.10668)
		(layer "F.Cu")
		(net "TP_CPU1_TEST5_CCD8")
	)
	(via
		(at 102.85095 -237.194344)
		(size 0.4064)
		(drill 0.2032)
		(layers "F.Cu" "B.Cu")
		(net "TP_CPU1_TEST5_CCD8")
	)
	(segment
		(start 122.587766 -238.270288)
		(end 123.054618 -238.00435)
		(width 0.10668)
		(layer "F.Cu")
		(net "TP_CPU1_TEST5_CCD7")
	)
	(via
		(at 123.054618 -238.00435)
		(size 0.4064)
		(drill 0.2032)
		(layers "F.Cu" "B.Cu")
		(net "TP_CPU1_TEST5_CCD7")
	)
	(segment
		(start 100.327968 -279.490424)
		(end 99.861116 -279.756362)
		(width 0.10668)
		(layer "F.Cu")
		(net "TP_CPU1_TEST5_CCD6")
	)
	(via
		(at 99.861116 -279.756362)
		(size 0.4064)
		(drill 0.2032)
		(layers "F.Cu" "B.Cu")
		(net "TP_CPU1_TEST5_CCD6")
	)
	(segment
		(start 123.827794 -279.490424)
		(end 124.294646 -279.756362)
		(width 0.10668)
		(layer "F.Cu")
		(net "TP_CPU1_TEST5_CCD5")
	)
	(via
		(at 124.294646 -279.756362)
		(size 0.4064)
		(drill 0.2032)
		(layers "F.Cu" "B.Cu")
		(net "TP_CPU1_TEST5_CCD5")
	)
	(segment
		(start 98.147886 -238.270288)
		(end 97.681034 -238.00435)
		(width 0.10668)
		(layer "F.Cu")
		(net "TP_CPU1_TEST5_CCD4")
	)
	(via
		(at 97.681034 -238.00435)
		(size 0.4064)
		(drill 0.2032)
		(layers "F.Cu" "B.Cu")
		(net "TP_CPU1_TEST5_CCD4")
	)
	(segment
		(start 119.297958 -237.460282)
		(end 119.76481 -237.194344)
		(width 0.10668)
		(layer "F.Cu")
		(net "TP_CPU1_TEST5_CCD3")
	)
	(via
		(at 119.76481 -237.194344)
		(size 0.4064)
		(drill 0.2032)
		(layers "F.Cu" "B.Cu")
		(net "TP_CPU1_TEST5_CCD3")
	)
	(segment
		(start 102.207822 -279.490424)
		(end 101.74097 -279.756362)
		(width 0.10668)
		(layer "F.Cu")
		(net "TP_CPU1_TEST5_CCD2")
	)
	(via
		(at 101.74097 -279.756362)
		(size 0.4064)
		(drill 0.2032)
		(layers "F.Cu" "B.Cu")
		(net "TP_CPU1_TEST5_CCD2")
	)
	(segment
		(start 120.238012 -237.460282)
		(end 120.70461 -237.194344)
		(width 0.10668)
		(layer "F.Cu")
		(net "TP_CPU1_TEST5_CCD11")
	)
	(via
		(at 120.70461 -237.194344)
		(size 0.4064)
		(drill 0.2032)
		(layers "F.Cu" "B.Cu")
		(net "TP_CPU1_TEST5_CCD11")
	)
	(segment
		(start 103.617776 -280.30043)
		(end 103.151178 -280.566368)
		(width 0.10668)
		(layer "F.Cu")
		(net "TP_CPU1_TEST5_CCD10")
	)
	(via
		(at 103.151178 -280.566368)
		(size 0.4064)
		(drill 0.2032)
		(layers "F.Cu" "B.Cu")
		(net "TP_CPU1_TEST5_CCD10")
	)
	(segment
		(start 121.94794 -279.490424)
		(end 122.414792 -279.756362)
		(width 0.10668)
		(layer "F.Cu")
		(net "TP_CPU1_TEST5_CCD1")
	)
	(via
		(at 122.414792 -279.756362)
		(size 0.4064)
		(drill 0.2032)
		(layers "F.Cu" "B.Cu")
		(net "TP_CPU1_TEST5_CCD1")
	)
	(segment
		(start 100.027994 -238.270288)
		(end 99.561142 -238.00435)
		(width 0.10668)
		(layer "F.Cu")
		(net "TP_CPU1_TEST5_CCD0")
	)
	(via
		(at 99.561142 -238.00435)
		(size 0.4064)
		(drill 0.2032)
		(layers "F.Cu" "B.Cu")
		(net "TP_CPU1_TEST5_CCD0")
	)
	(segment
		(start 123.52782 -238.270288)
		(end 123.994672 -238.00435)
		(width 0.10668)
		(layer "F.Cu")
		(net "TP_CPU1_TEST4_IOD")
	)
	(via
		(at 123.994672 -238.00435)
		(size 0.4064)
		(drill 0.2032)
		(layers "F.Cu" "B.Cu")
		(net "TP_CPU1_TEST4_IOD")
	)
	(segment
		(start 119.597932 -280.30043)
		(end 120.064784 -280.566368)
		(width 0.10668)
		(layer "F.Cu")
		(net "TP_CPU1_TEST4_CCD9")
	)
	(via
		(at 120.064784 -280.566368)
		(size 0.4064)
		(drill 0.2032)
		(layers "F.Cu" "B.Cu")
		(net "TP_CPU1_TEST4_CCD9")
	)
	(segment
		(start 102.847902 -238.270288)
		(end 102.38105 -238.00435)
		(width 0.10668)
		(layer "F.Cu")
		(net "TP_CPU1_TEST4_CCD8")
	)
	(via
		(at 102.38105 -238.00435)
		(size 0.4064)
		(drill 0.2032)
		(layers "F.Cu" "B.Cu")
		(net "TP_CPU1_TEST4_CCD8")
	)
	(segment
		(start 121.647966 -238.270288)
		(end 122.114818 -238.00435)
		(width 0.10668)
		(layer "F.Cu")
		(net "TP_CPU1_TEST4_CCD7")
	)
	(via
		(at 122.114818 -238.00435)
		(size 0.4064)
		(drill 0.2032)
		(layers "F.Cu" "B.Cu")
		(net "TP_CPU1_TEST4_CCD7")
	)
	(segment
		(start 101.268022 -279.490424)
		(end 100.80117 -279.756362)
		(width 0.10668)
		(layer "F.Cu")
		(net "TP_CPU1_TEST4_CCD6")
	)
	(via
		(at 100.80117 -279.756362)
		(size 0.4064)
		(drill 0.2032)
		(layers "F.Cu" "B.Cu")
		(net "TP_CPU1_TEST4_CCD6")
	)
	(segment
		(start 122.887994 -279.490424)
		(end 123.354846 -279.756362)
		(width 0.10668)
		(layer "F.Cu")
		(net "TP_CPU1_TEST4_CCD5")
	)
	(via
		(at 123.354846 -279.756362)
		(size 0.4064)
		(drill 0.2032)
		(layers "F.Cu" "B.Cu")
		(net "TP_CPU1_TEST4_CCD5")
	)
	(segment
		(start 99.08794 -238.270288)
		(end 98.621088 -238.00435)
		(width 0.10668)
		(layer "F.Cu")
		(net "TP_CPU1_TEST4_CCD4")
	)
	(via
		(at 98.621088 -238.00435)
		(size 0.4064)
		(drill 0.2032)
		(layers "F.Cu" "B.Cu")
		(net "TP_CPU1_TEST4_CCD4")
	)
	(segment
		(start 118.827804 -238.270288)
		(end 119.294656 -238.00435)
		(width 0.10668)
		(layer "F.Cu")
		(net "TP_CPU1_TEST4_CCD3")
	)
	(via
		(at 119.294656 -238.00435)
		(size 0.4064)
		(drill 0.2032)
		(layers "F.Cu" "B.Cu")
		(net "TP_CPU1_TEST4_CCD3")
	)
	(segment
		(start 103.147876 -279.490424)
		(end 102.681024 -279.756362)
		(width 0.10668)
		(layer "F.Cu")
		(net "TP_CPU1_TEST4_CCD2")
	)
	(via
		(at 102.681024 -279.756362)
		(size 0.4064)
		(drill 0.2032)
		(layers "F.Cu" "B.Cu")
		(net "TP_CPU1_TEST4_CCD2")
	)
	(segment
		(start 120.707912 -238.270288)
		(end 121.174764 -238.00435)
		(width 0.10668)
		(layer "F.Cu")
		(net "TP_CPU1_TEST4_CCD11")
	)
	(via
		(at 121.174764 -238.00435)
		(size 0.4064)
		(drill 0.2032)
		(layers "F.Cu" "B.Cu")
		(net "TP_CPU1_TEST4_CCD11")
	)
	(segment
		(start 104.08793 -279.490424)
		(end 103.621078 -279.756362)
		(width 0.10668)
		(layer "F.Cu")
		(net "TP_CPU1_TEST4_CCD10")
	)
	(via
		(at 103.621078 -279.756362)
		(size 0.4064)
		(drill 0.2032)
		(layers "F.Cu" "B.Cu")
		(net "TP_CPU1_TEST4_CCD10")
	)
	(segment
		(start 121.007886 -279.490424)
		(end 121.474738 -279.756362)
		(width 0.10668)
		(layer "F.Cu")
		(net "TP_CPU1_TEST4_CCD1")
	)
	(via
		(at 121.474738 -279.756362)
		(size 0.4064)
		(drill 0.2032)
		(layers "F.Cu" "B.Cu")
		(net "TP_CPU1_TEST4_CCD1")
	)
	(segment
		(start 100.967794 -238.270288)
		(end 100.500942 -238.00435)
		(width 0.10668)
		(layer "F.Cu")
		(net "TP_CPU1_TEST4_CCD0")
	)
	(via
		(at 100.500942 -238.00435)
		(size 0.4064)
		(drill 0.2032)
		(layers "F.Cu" "B.Cu")
		(net "TP_CPU1_TEST4_CCD0")
	)
	(segment
		(start 140.91793 -224.50044)
		(end 141.384782 -224.234502)
		(width 0.10668)
		(layer "F.Cu")
		(net "TP_CPU1_TEST47_IOD1")
	)
	(via
		(at 141.384782 -224.234502)
		(size 0.4064)
		(drill 0.2032)
		(layers "F.Cu" "B.Cu")
		(net "TP_CPU1_TEST47_IOD1")
	)
	(segment
		(start 92.97797 -222.880428)
		(end 92.511118 -222.61449)
		(width 0.10668)
		(layer "F.Cu")
		(net "TP_CPU1_TEST47_IOD0")
	)
	(via
		(at 92.511118 -222.61449)
		(size 0.4064)
		(drill 0.2032)
		(layers "F.Cu" "B.Cu")
		(net "TP_CPU1_TEST47_IOD0")
	)
	(segment
		(start 116.94795 -225.310446)
		(end 117.414802 -225.044508)
		(width 0.10668)
		(layer "F.Cu")
		(net "TP_CPU1_TEST47_CCD3")
	)
	(via
		(at 117.414802 -225.044508)
		(size 0.4064)
		(drill 0.2032)
		(layers "F.Cu" "B.Cu")
		(net "TP_CPU1_TEST47_CCD3")
	)
	(segment
		(start 104.55783 -280.30043)
		(end 104.090978 -280.566368)
		(width 0.10668)
		(layer "F.Cu")
		(net "TP_CPU1_TEST47_CCD2")
	)
	(via
		(at 104.090978 -280.566368)
		(size 0.4064)
		(drill 0.2032)
		(layers "F.Cu" "B.Cu")
		(net "TP_CPU1_TEST47_CCD2")
	)
	(segment
		(start 124.767848 -279.490424)
		(end 125.2347 -279.756362)
		(width 0.10668)
		(layer "F.Cu")
		(net "TP_CPU1_TEST47_CCD1")
	)
	(via
		(at 125.2347 -279.756362)
		(size 0.4064)
		(drill 0.2032)
		(layers "F.Cu" "B.Cu")
		(net "TP_CPU1_TEST47_CCD1")
	)
	(segment
		(start 117.888004 -236.650276)
		(end 118.354856 -236.384338)
		(width 0.10668)
		(layer "F.Cu")
		(net "TP_CPU1_TEST41_IOD")
	)
	(via
		(at 118.354856 -236.384338)
		(size 0.4064)
		(drill 0.2032)
		(layers "F.Cu" "B.Cu")
		(net "TP_CPU1_TEST41_IOD")
	)
	(segment
		(start 363.307884 -294.070024)
		(end 363.774736 -294.335962)
		(width 0.10668)
		(layer "F.Cu")
		(net "TP_CPU0_UART0_INTR")
	)
	(via
		(at 363.774736 -294.335962)
		(size 0.4064)
		(drill 0.2032)
		(layers "F.Cu" "B.Cu")
		(net "TP_CPU0_UART0_INTR")
	)
	(segment
		(start 346.387928 -279.49017)
		(end 345.921076 -279.756108)
		(width 0.10668)
		(layer "F.Cu")
		(net "TP_CPU0_TEST6_X3D5")
	)
	(via
		(at 345.921076 -279.756108)
		(size 0.4064)
		(drill 0.2032)
		(layers "F.Cu" "B.Cu")
		(net "TP_CPU0_TEST6_X3D5")
	)
	(segment
		(start 373.347996 -238.270034)
		(end 373.814848 -238.004096)
		(width 0.10668)
		(layer "F.Cu")
		(net "TP_CPU0_TEST6_X3D4")
	)
	(via
		(at 373.814848 -238.004096)
		(size 0.4064)
		(drill 0.2032)
		(layers "F.Cu" "B.Cu")
		(net "TP_CPU0_TEST6_X3D4")
	)
	(segment
		(start 347.327982 -279.49017)
		(end 346.86113 -279.756108)
		(width 0.10668)
		(layer "F.Cu")
		(net "TP_CPU0_TEST6_X3D3")
	)
	(via
		(at 346.86113 -279.756108)
		(size 0.4064)
		(drill 0.2032)
		(layers "F.Cu" "B.Cu")
		(net "TP_CPU0_TEST6_X3D3")
	)
	(segment
		(start 367.707926 -238.270034)
		(end 368.174778 -238.004096)
		(width 0.10668)
		(layer "F.Cu")
		(net "TP_CPU0_TEST6_X3D2")
	)
	(via
		(at 368.174778 -238.004096)
		(size 0.4064)
		(drill 0.2032)
		(layers "F.Cu" "B.Cu")
		(net "TP_CPU0_TEST6_X3D2")
	)
	(segment
		(start 368.0079 -279.49017)
		(end 368.474752 -279.756108)
		(width 0.10668)
		(layer "F.Cu")
		(net "TP_CPU0_TEST6_X3D1")
	)
	(via
		(at 368.474752 -279.756108)
		(size 0.4064)
		(drill 0.2032)
		(layers "F.Cu" "B.Cu")
		(net "TP_CPU0_TEST6_X3D1")
	)
	(segment
		(start 351.728024 -238.270034)
		(end 351.261172 -238.004096)
		(width 0.10668)
		(layer "F.Cu")
		(net "TP_CPU0_TEST6_X3D0")
	)
	(via
		(at 351.261172 -238.004096)
		(size 0.4064)
		(drill 0.2032)
		(layers "F.Cu" "B.Cu")
		(net "TP_CPU0_TEST6_X3D0")
	)
	(segment
		(start 349.847916 -238.270034)
		(end 349.381064 -238.004096)
		(width 0.10668)
		(layer "F.Cu")
		(net "TP_CPU0_TEST6_IOD")
	)
	(via
		(at 349.381064 -238.004096)
		(size 0.4064)
		(drill 0.2032)
		(layers "F.Cu" "B.Cu")
		(net "TP_CPU0_TEST6_IOD")
	)
	(segment
		(start 352.197924 -237.460028)
		(end 351.731072 -237.19409)
		(width 0.10668)
		(layer "F.Cu")
		(net "TP_CPU0_TEST6_CCD3")
	)
	(via
		(at 351.731072 -237.19409)
		(size 0.4064)
		(drill 0.2032)
		(layers "F.Cu" "B.Cu")
		(net "TP_CPU0_TEST6_CCD3")
	)
	(segment
		(start 352.968052 -279.49017)
		(end 352.5012 -279.756108)
		(width 0.10668)
		(layer "F.Cu")
		(net "TP_CPU0_TEST6_CCD2")
	)
	(via
		(at 352.5012 -279.756108)
		(size 0.4064)
		(drill 0.2032)
		(layers "F.Cu" "B.Cu")
		(net "TP_CPU0_TEST6_CCD2")
	)
	(segment
		(start 367.067846 -279.49017)
		(end 367.534698 -279.756108)
		(width 0.10668)
		(layer "F.Cu")
		(net "TP_CPU0_TEST6_CCD1")
	)
	(via
		(at 367.534698 -279.756108)
		(size 0.4064)
		(drill 0.2032)
		(layers "F.Cu" "B.Cu")
		(net "TP_CPU0_TEST6_CCD1")
	)
	(segment
		(start 352.668078 -238.270034)
		(end 352.201226 -238.004096)
		(width 0.10668)
		(layer "F.Cu")
		(net "TP_CPU0_TEST6_CCD0")
	)
	(via
		(at 352.201226 -238.004096)
		(size 0.4064)
		(drill 0.2032)
		(layers "F.Cu" "B.Cu")
		(net "TP_CPU0_TEST6_CCD0")
	)
	(segment
		(start 372.407942 -238.270034)
		(end 372.874794 -238.004096)
		(width 0.10668)
		(layer "F.Cu")
		(net "TP_CPU0_TEST5_IOD")
	)
	(via
		(at 372.874794 -238.004096)
		(size 0.4064)
		(drill 0.2032)
		(layers "F.Cu" "B.Cu")
		(net "TP_CPU0_TEST5_IOD")
	)
	(segment
		(start 368.478054 -280.300176)
		(end 368.944906 -280.566114)
		(width 0.10668)
		(layer "F.Cu")
		(net "TP_CPU0_TEST5_CCD9")
	)
	(via
		(at 368.944906 -280.566114)
		(size 0.4064)
		(drill 0.2032)
		(layers "F.Cu" "B.Cu")
		(net "TP_CPU0_TEST5_CCD9")
	)
	(segment
		(start 351.25787 -237.460028)
		(end 350.791018 -237.19409)
		(width 0.10668)
		(layer "F.Cu")
		(net "TP_CPU0_TEST5_CCD8")
	)
	(via
		(at 350.791018 -237.19409)
		(size 0.4064)
		(drill 0.2032)
		(layers "F.Cu" "B.Cu")
		(net "TP_CPU0_TEST5_CCD8")
	)
	(segment
		(start 370.527834 -238.270034)
		(end 370.994686 -238.004096)
		(width 0.10668)
		(layer "F.Cu")
		(net "TP_CPU0_TEST5_CCD7")
	)
	(via
		(at 370.994686 -238.004096)
		(size 0.4064)
		(drill 0.2032)
		(layers "F.Cu" "B.Cu")
		(net "TP_CPU0_TEST5_CCD7")
	)
	(segment
		(start 348.268036 -279.49017)
		(end 347.801184 -279.756108)
		(width 0.10668)
		(layer "F.Cu")
		(net "TP_CPU0_TEST5_CCD6")
	)
	(via
		(at 347.801184 -279.756108)
		(size 0.4064)
		(drill 0.2032)
		(layers "F.Cu" "B.Cu")
		(net "TP_CPU0_TEST5_CCD6")
	)
	(segment
		(start 371.767862 -279.49017)
		(end 372.234714 -279.756108)
		(width 0.10668)
		(layer "F.Cu")
		(net "TP_CPU0_TEST5_CCD5")
	)
	(via
		(at 372.234714 -279.756108)
		(size 0.4064)
		(drill 0.2032)
		(layers "F.Cu" "B.Cu")
		(net "TP_CPU0_TEST5_CCD5")
	)
	(segment
		(start 346.087954 -238.270034)
		(end 345.621102 -238.004096)
		(width 0.10668)
		(layer "F.Cu")
		(net "TP_CPU0_TEST5_CCD4")
	)
	(via
		(at 345.621102 -238.004096)
		(size 0.4064)
		(drill 0.2032)
		(layers "F.Cu" "B.Cu")
		(net "TP_CPU0_TEST5_CCD4")
	)
	(segment
		(start 367.238026 -237.460028)
		(end 367.704878 -237.19409)
		(width 0.10668)
		(layer "F.Cu")
		(net "TP_CPU0_TEST5_CCD3")
	)
	(via
		(at 367.704878 -237.19409)
		(size 0.4064)
		(drill 0.2032)
		(layers "F.Cu" "B.Cu")
		(net "TP_CPU0_TEST5_CCD3")
	)
	(segment
		(start 350.14789 -279.49017)
		(end 349.681038 -279.756108)
		(width 0.10668)
		(layer "F.Cu")
		(net "TP_CPU0_TEST5_CCD2")
	)
	(via
		(at 349.681038 -279.756108)
		(size 0.4064)
		(drill 0.2032)
		(layers "F.Cu" "B.Cu")
		(net "TP_CPU0_TEST5_CCD2")
	)
	(segment
		(start 368.17808 -237.460028)
		(end 368.644678 -237.19409)
		(width 0.10668)
		(layer "F.Cu")
		(net "TP_CPU0_TEST5_CCD11")
	)
	(via
		(at 368.644678 -237.19409)
		(size 0.4064)
		(drill 0.2032)
		(layers "F.Cu" "B.Cu")
		(net "TP_CPU0_TEST5_CCD11")
	)
	(segment
		(start 351.557844 -280.300176)
		(end 351.091246 -280.566114)
		(width 0.10668)
		(layer "F.Cu")
		(net "TP_CPU0_TEST5_CCD10")
	)
	(via
		(at 351.091246 -280.566114)
		(size 0.4064)
		(drill 0.2032)
		(layers "F.Cu" "B.Cu")
		(net "TP_CPU0_TEST5_CCD10")
	)
	(segment
		(start 369.888008 -279.49017)
		(end 370.35486 -279.756108)
		(width 0.10668)
		(layer "F.Cu")
		(net "TP_CPU0_TEST5_CCD1")
	)
	(via
		(at 370.35486 -279.756108)
		(size 0.4064)
		(drill 0.2032)
		(layers "F.Cu" "B.Cu")
		(net "TP_CPU0_TEST5_CCD1")
	)
	(segment
		(start 347.968062 -238.270034)
		(end 347.50121 -238.004096)
		(width 0.10668)
		(layer "F.Cu")
		(net "TP_CPU0_TEST5_CCD0")
	)
	(via
		(at 347.50121 -238.004096)
		(size 0.4064)
		(drill 0.2032)
		(layers "F.Cu" "B.Cu")
		(net "TP_CPU0_TEST5_CCD0")
	)
	(segment
		(start 338.097876 -222.880174)
		(end 337.631024 -222.614236)
		(width 0.10668)
		(layer "F.Cu")
		(net "TP_CPU0_TEST50_IOD")
	)
	(via
		(at 337.631024 -222.614236)
		(size 0.4064)
		(drill 0.2032)
		(layers "F.Cu" "B.Cu")
		(net "TP_CPU0_TEST50_IOD")
	)
	(segment
		(start 371.467888 -238.270034)
		(end 371.93474 -238.004096)
		(width 0.10668)
		(layer "F.Cu")
		(net "TP_CPU0_TEST4_IOD")
	)
	(via
		(at 371.93474 -238.004096)
		(size 0.4064)
		(drill 0.2032)
		(layers "F.Cu" "B.Cu")
		(net "TP_CPU0_TEST4_IOD")
	)
	(segment
		(start 367.538 -280.300176)
		(end 368.004852 -280.566114)
		(width 0.10668)
		(layer "F.Cu")
		(net "TP_CPU0_TEST4_CCD9")
	)
	(via
		(at 368.004852 -280.566114)
		(size 0.4064)
		(drill 0.2032)
		(layers "F.Cu" "B.Cu")
		(net "TP_CPU0_TEST4_CCD9")
	)
	(segment
		(start 350.78797 -238.270034)
		(end 350.321118 -238.004096)
		(width 0.10668)
		(layer "F.Cu")
		(net "TP_CPU0_TEST4_CCD8")
	)
	(via
		(at 350.321118 -238.004096)
		(size 0.4064)
		(drill 0.2032)
		(layers "F.Cu" "B.Cu")
		(net "TP_CPU0_TEST4_CCD8")
	)
	(segment
		(start 369.588034 -238.270034)
		(end 370.054886 -238.004096)
		(width 0.10668)
		(layer "F.Cu")
		(net "TP_CPU0_TEST4_CCD7")
	)
	(via
		(at 370.054886 -238.004096)
		(size 0.4064)
		(drill 0.2032)
		(layers "F.Cu" "B.Cu")
		(net "TP_CPU0_TEST4_CCD7")
	)
	(segment
		(start 349.20809 -279.49017)
		(end 348.741238 -279.756108)
		(width 0.10668)
		(layer "F.Cu")
		(net "TP_CPU0_TEST4_CCD6")
	)
	(via
		(at 348.741238 -279.756108)
		(size 0.4064)
		(drill 0.2032)
		(layers "F.Cu" "B.Cu")
		(net "TP_CPU0_TEST4_CCD6")
	)
	(segment
		(start 370.828062 -279.49017)
		(end 371.294914 -279.756108)
		(width 0.10668)
		(layer "F.Cu")
		(net "TP_CPU0_TEST4_CCD5")
	)
	(via
		(at 371.294914 -279.756108)
		(size 0.4064)
		(drill 0.2032)
		(layers "F.Cu" "B.Cu")
		(net "TP_CPU0_TEST4_CCD5")
	)
	(segment
		(start 347.028008 -238.270034)
		(end 346.561156 -238.004096)
		(width 0.10668)
		(layer "F.Cu")
		(net "TP_CPU0_TEST4_CCD4")
	)
	(via
		(at 346.561156 -238.004096)
		(size 0.4064)
		(drill 0.2032)
		(layers "F.Cu" "B.Cu")
		(net "TP_CPU0_TEST4_CCD4")
	)
	(segment
		(start 366.767872 -238.270034)
		(end 367.234724 -238.004096)
		(width 0.10668)
		(layer "F.Cu")
		(net "TP_CPU0_TEST4_CCD3")
	)
	(via
		(at 367.234724 -238.004096)
		(size 0.4064)
		(drill 0.2032)
		(layers "F.Cu" "B.Cu")
		(net "TP_CPU0_TEST4_CCD3")
	)
	(segment
		(start 351.087944 -279.49017)
		(end 350.621092 -279.756108)
		(width 0.10668)
		(layer "F.Cu")
		(net "TP_CPU0_TEST4_CCD2")
	)
	(via
		(at 350.621092 -279.756108)
		(size 0.4064)
		(drill 0.2032)
		(layers "F.Cu" "B.Cu")
		(net "TP_CPU0_TEST4_CCD2")
	)
	(segment
		(start 368.64798 -238.270034)
		(end 369.114832 -238.004096)
		(width 0.10668)
		(layer "F.Cu")
		(net "TP_CPU0_TEST4_CCD11")
	)
	(via
		(at 369.114832 -238.004096)
		(size 0.4064)
		(drill 0.2032)
		(layers "F.Cu" "B.Cu")
		(net "TP_CPU0_TEST4_CCD11")
	)
	(segment
		(start 352.027998 -279.49017)
		(end 351.561146 -279.756108)
		(width 0.10668)
		(layer "F.Cu")
		(net "TP_CPU0_TEST4_CCD10")
	)
	(via
		(at 351.561146 -279.756108)
		(size 0.4064)
		(drill 0.2032)
		(layers "F.Cu" "B.Cu")
		(net "TP_CPU0_TEST4_CCD10")
	)
	(segment
		(start 368.947954 -279.49017)
		(end 369.414806 -279.756108)
		(width 0.10668)
		(layer "F.Cu")
		(net "TP_CPU0_TEST4_CCD1")
	)
	(via
		(at 369.414806 -279.756108)
		(size 0.4064)
		(drill 0.2032)
		(layers "F.Cu" "B.Cu")
		(net "TP_CPU0_TEST4_CCD1")
	)
	(segment
		(start 348.907862 -238.270034)
		(end 348.44101 -238.004096)
		(width 0.10668)
		(layer "F.Cu")
		(net "TP_CPU0_TEST4_CCD0")
	)
	(via
		(at 348.44101 -238.004096)
		(size 0.4064)
		(drill 0.2032)
		(layers "F.Cu" "B.Cu")
		(net "TP_CPU0_TEST4_CCD0")
	)
	(segment
		(start 388.857998 -224.500186)
		(end 389.32485 -224.234248)
		(width 0.10668)
		(layer "F.Cu")
		(net "TP_CPU0_TEST47_IOD1")
	)
	(via
		(at 389.32485 -224.234248)
		(size 0.4064)
		(drill 0.2032)
		(layers "F.Cu" "B.Cu")
		(net "TP_CPU0_TEST47_IOD1")
	)
	(segment
		(start 340.918038 -222.880174)
		(end 340.451186 -222.614236)
		(width 0.10668)
		(layer "F.Cu")
		(net "TP_CPU0_TEST47_IOD0")
	)
	(via
		(at 340.451186 -222.614236)
		(size 0.4064)
		(drill 0.2032)
		(layers "F.Cu" "B.Cu")
		(net "TP_CPU0_TEST47_IOD0")
	)
	(segment
		(start 364.888018 -225.310192)
		(end 365.35487 -225.044254)
		(width 0.10668)
		(layer "F.Cu")
		(net "TP_CPU0_TEST47_CCD3")
	)
	(via
		(at 365.35487 -225.044254)
		(size 0.4064)
		(drill 0.2032)
		(layers "F.Cu" "B.Cu")
		(net "TP_CPU0_TEST47_CCD3")
	)
	(segment
		(start 352.497898 -280.300176)
		(end 352.031046 -280.566114)
		(width 0.10668)
		(layer "F.Cu")
		(net "TP_CPU0_TEST47_CCD2")
	)
	(via
		(at 352.031046 -280.566114)
		(size 0.4064)
		(drill 0.2032)
		(layers "F.Cu" "B.Cu")
		(net "TP_CPU0_TEST47_CCD2")
	)
	(segment
		(start 372.707916 -279.49017)
		(end 373.174768 -279.756108)
		(width 0.10668)
		(layer "F.Cu")
		(net "TP_CPU0_TEST47_CCD1")
	)
	(via
		(at 373.174768 -279.756108)
		(size 0.4064)
		(drill 0.2032)
		(layers "F.Cu" "B.Cu")
		(net "TP_CPU0_TEST47_CCD1")
	)
	(segment
		(start 339.03793 -222.880174)
		(end 338.571078 -222.614236)
		(width 0.10668)
		(layer "F.Cu")
		(net "TP_CPU0_TEST47_CCD0")
	)
	(via
		(at 338.571078 -222.614236)
		(size 0.4064)
		(drill 0.2032)
		(layers "F.Cu" "B.Cu")
		(net "TP_CPU0_TEST47_CCD0")
	)
	(segment
		(start 365.828072 -236.650022)
		(end 366.294924 -236.384084)
		(width 0.10668)
		(layer "F.Cu")
		(net "TP_CPU0_TEST41_IDO")
	)
	(via
		(at 366.294924 -236.384084)
		(size 0.4064)
		(drill 0.2032)
		(layers "F.Cu" "B.Cu")
		(net "TP_CPU0_TEST41_IDO")
	)
	(segment
		(start 215.31961 -14.289024)
		(end 215.666066 -13.942568)
		(width 0.10668)
		(layer "F.Cu")
		(net "TP_CLK_50M_Y3")
	)
	(segment
		(start 215.666066 -13.942568)
		(end 216.473532 -13.942568)
		(width 0.10668)
		(layer "F.Cu")
		(net "TP_CLK_50M_Y3")
	)
	(segment
		(start 215.31961 -14.845792)
		(end 215.31961 -14.289024)
		(width 0.10668)
		(layer "F.Cu")
		(net "TP_CLK_50M_Y3")
	)
	(via
		(at 216.473532 -13.942568)
		(size 0.762)
		(drill 0.381)
		(layers "F.Cu" "B.Cu")
		(net "TP_CLK_50M_Y3")
	)
	(segment
		(start 228.473254 -51.282346)
		(end 228.790754 -50.964846)
		(width 0.10668)
		(layer "F.Cu")
		(net "TP_CLK_100M_E1S_0_DP")
	)
	(segment
		(start 228.790754 -50.964846)
		(end 232.000044 -50.964846)
		(width 0.10668)
		(layer "F.Cu")
		(net "TP_CLK_100M_E1S_0_DP")
	)
	(via
		(at 228.473254 -51.282346)
		(size 0.762)
		(drill 0.381)
		(layers "F.Cu" "B.Cu")
		(net "TP_CLK_100M_E1S_0_DP")
	)
	(segment
		(start 227.000054 -51.256946)
		(end 227.892102 -50.364898)
		(width 0.10668)
		(layer "F.Cu")
		(net "TP_CLK_100M_E1S_0_DN")
	)
	(segment
		(start 227.892102 -50.364898)
		(end 232.000044 -50.364898)
		(width 0.10668)
		(layer "F.Cu")
		(net "TP_CLK_100M_E1S_0_DN")
	)
	(via
		(at 227.000054 -51.256946)
		(size 0.762)
		(drill 0.381)
		(layers "F.Cu" "B.Cu")
		(net "TP_CLK_100M_E1S_0_DN")
	)
	(segment
		(start 29.760672 -350.347026)
		(end 29.760672 -349.621094)
		(width 0.2032)
		(layer "F.Cu")
		(net "SW_PVDDIO_P1_BOOTR4")
	)
	(segment
		(start 30.386528 -350.972882)
		(end 29.760672 -350.347026)
		(width 0.2032)
		(layer "F.Cu")
		(net "SW_PVDDIO_P1_BOOTR4")
	)
	(segment
		(start 38.666928 -350.972882)
		(end 38.041072 -350.347026)
		(width 0.2032)
		(layer "F.Cu")
		(net "SW_PVDDIO_P1_BOOTR3")
	)
	(segment
		(start 38.041072 -350.347026)
		(end 38.041072 -349.621094)
		(width 0.2032)
		(layer "F.Cu")
		(net "SW_PVDDIO_P1_BOOTR3")
	)
	(segment
		(start 46.346872 -350.347026)
		(end 46.346872 -349.621094)
		(width 0.2032)
		(layer "F.Cu")
		(net "SW_PVDDIO_P1_BOOTR2")
	)
	(segment
		(start 46.972728 -350.972882)
		(end 46.346872 -350.347026)
		(width 0.2032)
		(layer "F.Cu")
		(net "SW_PVDDIO_P1_BOOTR2")
	)
	(segment
		(start 54.703472 -350.347026)
		(end 54.703472 -349.621094)
		(width 0.2032)
		(layer "F.Cu")
		(net "SW_PVDDIO_P1_BOOTR1")
	)
	(segment
		(start 55.329328 -350.972882)
		(end 54.703472 -350.347026)
		(width 0.2032)
		(layer "F.Cu")
		(net "SW_PVDDIO_P1_BOOTR1")
	)
	(segment
		(start 30.386528 -351.772982)
		(end 29.35986 -351.772982)
		(width 0.2032)
		(layer "F.Cu")
		(net "SW_PVDDIO_P1_BOOT4_R")
	)
	(segment
		(start 29.35986 -350.972882)
		(end 29.310584 -350.923606)
		(width 0.2032)
		(layer "F.Cu")
		(net "SW_PVDDIO_P1_BOOT4")
	)
	(segment
		(start 29.310584 -350.923606)
		(end 29.310584 -349.621094)
		(width 0.2032)
		(layer "F.Cu")
		(net "SW_PVDDIO_P1_BOOT4")
	)
	(segment
		(start 38.666928 -351.772982)
		(end 37.64026 -351.772982)
		(width 0.2032)
		(layer "F.Cu")
		(net "SW_PVDDIO_P1_BOOT3_R")
	)
	(segment
		(start 37.590984 -350.923606)
		(end 37.590984 -349.621094)
		(width 0.2032)
		(layer "F.Cu")
		(net "SW_PVDDIO_P1_BOOT3")
	)
	(segment
		(start 37.64026 -350.972882)
		(end 37.590984 -350.923606)
		(width 0.2032)
		(layer "F.Cu")
		(net "SW_PVDDIO_P1_BOOT3")
	)
	(segment
		(start 46.972728 -351.772982)
		(end 45.94606 -351.772982)
		(width 0.2032)
		(layer "F.Cu")
		(net "SW_PVDDIO_P1_BOOT2_R")
	)
	(segment
		(start 45.94606 -350.972882)
		(end 45.896784 -350.923606)
		(width 0.2032)
		(layer "F.Cu")
		(net "SW_PVDDIO_P1_BOOT2")
	)
	(segment
		(start 45.896784 -350.923606)
		(end 45.896784 -349.621094)
		(width 0.2032)
		(layer "F.Cu")
		(net "SW_PVDDIO_P1_BOOT2")
	)
	(segment
		(start 55.329328 -351.772982)
		(end 54.30266 -351.772982)
		(width 0.2032)
		(layer "F.Cu")
		(net "SW_PVDDIO_P1_BOOT1_R")
	)
	(segment
		(start 54.30266 -350.972882)
		(end 54.253384 -350.923606)
		(width 0.2032)
		(layer "F.Cu")
		(net "SW_PVDDIO_P1_BOOT1")
	)
	(segment
		(start 54.253384 -350.923606)
		(end 54.253384 -349.621094)
		(width 0.2032)
		(layer "F.Cu")
		(net "SW_PVDDIO_P1_BOOT1")
	)
	(segment
		(start 277.20798 -350.968056)
		(end 276.582124 -350.3422)
		(width 0.2032)
		(layer "F.Cu")
		(net "SW_PVDDIO_P0_BOOTR4")
	)
	(segment
		(start 276.582124 -350.3422)
		(end 276.582124 -349.616268)
		(width 0.2032)
		(layer "F.Cu")
		(net "SW_PVDDIO_P0_BOOTR4")
	)
	(segment
		(start 285.48838 -350.968056)
		(end 284.862524 -350.3422)
		(width 0.2032)
		(layer "F.Cu")
		(net "SW_PVDDIO_P0_BOOTR3")
	)
	(segment
		(start 284.862524 -350.3422)
		(end 284.862524 -349.616268)
		(width 0.2032)
		(layer "F.Cu")
		(net "SW_PVDDIO_P0_BOOTR3")
	)
	(segment
		(start 293.79418 -350.968056)
		(end 293.168324 -350.3422)
		(width 0.2032)
		(layer "F.Cu")
		(net "SW_PVDDIO_P0_BOOTR2")
	)
	(segment
		(start 293.168324 -350.3422)
		(end 293.168324 -349.616268)
		(width 0.2032)
		(layer "F.Cu")
		(net "SW_PVDDIO_P0_BOOTR2")
	)
	(segment
		(start 302.15078 -350.968056)
		(end 301.524924 -350.3422)
		(width 0.2032)
		(layer "F.Cu")
		(net "SW_PVDDIO_P0_BOOTR1")
	)
	(segment
		(start 301.524924 -350.3422)
		(end 301.524924 -349.616268)
		(width 0.2032)
		(layer "F.Cu")
		(net "SW_PVDDIO_P0_BOOTR1")
	)
	(segment
		(start 277.20798 -351.768156)
		(end 276.181312 -351.768156)
		(width 0.2032)
		(layer "F.Cu")
		(net "SW_PVDDIO_P0_BOOT4_R")
	)
	(segment
		(start 276.132036 -350.91878)
		(end 276.132036 -349.616268)
		(width 0.2032)
		(layer "F.Cu")
		(net "SW_PVDDIO_P0_BOOT4")
	)
	(segment
		(start 276.181312 -350.968056)
		(end 276.132036 -350.91878)
		(width 0.2032)
		(layer "F.Cu")
		(net "SW_PVDDIO_P0_BOOT4")
	)
	(segment
		(start 285.48838 -351.768156)
		(end 284.461712 -351.768156)
		(width 0.2032)
		(layer "F.Cu")
		(net "SW_PVDDIO_P0_BOOT3_R")
	)
	(segment
		(start 284.461712 -350.968056)
		(end 284.412436 -350.91878)
		(width 0.2032)
		(layer "F.Cu")
		(net "SW_PVDDIO_P0_BOOT3")
	)
	(segment
		(start 284.412436 -350.91878)
		(end 284.412436 -349.616268)
		(width 0.2032)
		(layer "F.Cu")
		(net "SW_PVDDIO_P0_BOOT3")
	)
	(segment
		(start 293.79418 -351.768156)
		(end 292.767512 -351.768156)
		(width 0.2032)
		(layer "F.Cu")
		(net "SW_PVDDIO_P0_BOOT2_R")
	)
	(segment
		(start 292.767512 -350.968056)
		(end 292.718236 -350.91878)
		(width 0.2032)
		(layer "F.Cu")
		(net "SW_PVDDIO_P0_BOOT2")
	)
	(segment
		(start 292.718236 -350.91878)
		(end 292.718236 -349.616268)
		(width 0.2032)
		(layer "F.Cu")
		(net "SW_PVDDIO_P0_BOOT2")
	)
	(segment
		(start 302.15078 -351.768156)
		(end 301.124112 -351.768156)
		(width 0.2032)
		(layer "F.Cu")
		(net "SW_PVDDIO_P0_BOOT1_R")
	)
	(segment
		(start 301.124112 -350.968056)
		(end 301.074836 -350.91878)
		(width 0.2032)
		(layer "F.Cu")
		(net "SW_PVDDIO_P0_BOOT1")
	)
	(segment
		(start 301.074836 -350.91878)
		(end 301.074836 -349.616268)
		(width 0.2032)
		(layer "F.Cu")
		(net "SW_PVDDIO_P0_BOOT1")
	)
	(segment
		(start 131.264152 -152.905206)
		(end 130.638296 -152.27935)
		(width 0.2032)
		(layer "F.Cu")
		(net "SW_PVDDCR_SOC_P1_PH3")
	)
	(segment
		(start 131.264152 -153.631138)
		(end 131.264152 -152.905206)
		(width 0.2032)
		(layer "F.Cu")
		(net "SW_PVDDCR_SOC_P1_PH3")
	)
	(segment
		(start 122.805952 -162.292538)
		(end 122.805952 -161.566606)
		(width 0.2032)
		(layer "F.Cu")
		(net "SW_PVDDCR_SOC_P1_PH2")
	)
	(segment
		(start 122.805952 -161.566606)
		(end 122.180096 -160.94075)
		(width 0.2032)
		(layer "F.Cu")
		(net "SW_PVDDCR_SOC_P1_PH2")
	)
	(segment
		(start 114.525552 -169.023538)
		(end 114.525552 -168.297606)
		(width 0.2032)
		(layer "F.Cu")
		(net "SW_PVDDCR_SOC_P1_PH1")
	)
	(segment
		(start 114.525552 -168.297606)
		(end 113.899696 -167.67175)
		(width 0.2032)
		(layer "F.Cu")
		(net "SW_PVDDCR_SOC_P1_PH1")
	)
	(segment
		(start 130.638296 -151.47925)
		(end 131.664964 -151.47925)
		(width 0.2032)
		(layer "F.Cu")
		(net "SW_PVDDCR_SOC_P1_BOOT3_RC")
	)
	(segment
		(start 131.664964 -152.27935)
		(end 131.71424 -152.328626)
		(width 0.2032)
		(layer "F.Cu")
		(net "SW_PVDDCR_SOC_P1_BOOT3")
	)
	(segment
		(start 131.71424 -152.328626)
		(end 131.71424 -153.631138)
		(width 0.2032)
		(layer "F.Cu")
		(net "SW_PVDDCR_SOC_P1_BOOT3")
	)
	(segment
		(start 123.206764 -160.14065)
		(end 122.180096 -160.14065)
		(width 0.2032)
		(layer "F.Cu")
		(net "SW_PVDDCR_SOC_P1_BOOT2_RC")
	)
	(segment
		(start 123.206764 -160.94075)
		(end 123.25604 -160.990026)
		(width 0.2032)
		(layer "F.Cu")
		(net "SW_PVDDCR_SOC_P1_BOOT2")
	)
	(segment
		(start 123.25604 -160.990026)
		(end 123.25604 -162.292538)
		(width 0.2032)
		(layer "F.Cu")
		(net "SW_PVDDCR_SOC_P1_BOOT2")
	)
	(segment
		(start 114.926364 -166.87165)
		(end 113.899696 -166.87165)
		(width 0.2032)
		(layer "F.Cu")
		(net "SW_PVDDCR_SOC_P1_BOOT1_RC")
	)
	(segment
		(start 114.926364 -167.67175)
		(end 114.97564 -167.721026)
		(width 0.2032)
		(layer "F.Cu")
		(net "SW_PVDDCR_SOC_P1_BOOT1")
	)
	(segment
		(start 114.97564 -167.721026)
		(end 114.97564 -169.023538)
		(width 0.2032)
		(layer "F.Cu")
		(net "SW_PVDDCR_SOC_P1_BOOT1")
	)
	(segment
		(start 413.36976 -160.14192)
		(end 412.743904 -159.516064)
		(width 0.2032)
		(layer "F.Cu")
		(net "SW_PVDDCR_SOC_P0_PH3")
	)
	(segment
		(start 413.36976 -160.867852)
		(end 413.36976 -160.14192)
		(width 0.2032)
		(layer "F.Cu")
		(net "SW_PVDDCR_SOC_P0_PH3")
	)
	(segment
		(start 404.98776 -165.693852)
		(end 404.98776 -164.96792)
		(width 0.2032)
		(layer "F.Cu")
		(net "SW_PVDDCR_SOC_P0_PH2")
	)
	(segment
		(start 404.98776 -164.96792)
		(end 404.361904 -164.342064)
		(width 0.2032)
		(layer "F.Cu")
		(net "SW_PVDDCR_SOC_P0_PH2")
	)
	(segment
		(start 396.66418 -173.545246)
		(end 396.038324 -172.91939)
		(width 0.2032)
		(layer "F.Cu")
		(net "SW_PVDDCR_SOC_P0_PH1")
	)
	(segment
		(start 396.66418 -174.271178)
		(end 396.66418 -173.545246)
		(width 0.2032)
		(layer "F.Cu")
		(net "SW_PVDDCR_SOC_P0_PH1")
	)
	(segment
		(start 412.743904 -158.715964)
		(end 413.770572 -158.715964)
		(width 0.2032)
		(layer "F.Cu")
		(net "SW_PVDDCR_SOC_P0_BOOT3_RC")
	)
	(segment
		(start 413.819848 -159.56534)
		(end 413.819848 -160.867852)
		(width 0.2032)
		(layer "F.Cu")
		(net "SW_PVDDCR_SOC_P0_BOOT3")
	)
	(segment
		(start 413.770572 -159.516064)
		(end 413.819848 -159.56534)
		(width 0.2032)
		(layer "F.Cu")
		(net "SW_PVDDCR_SOC_P0_BOOT3")
	)
	(segment
		(start 404.361904 -163.541964)
		(end 405.388572 -163.541964)
		(width 0.2032)
		(layer "F.Cu")
		(net "SW_PVDDCR_SOC_P0_BOOT2_RC")
	)
	(segment
		(start 405.437848 -164.39134)
		(end 405.437848 -165.693852)
		(width 0.2032)
		(layer "F.Cu")
		(net "SW_PVDDCR_SOC_P0_BOOT2")
	)
	(segment
		(start 405.388572 -164.342064)
		(end 405.437848 -164.39134)
		(width 0.2032)
		(layer "F.Cu")
		(net "SW_PVDDCR_SOC_P0_BOOT2")
	)
	(segment
		(start 396.038324 -172.11929)
		(end 397.064992 -172.11929)
		(width 0.2032)
		(layer "F.Cu")
		(net "SW_PVDDCR_SOC_P0_BOOT1_RC")
	)
	(segment
		(start 397.064992 -172.91939)
		(end 397.064992 -173.369986)
		(width 0.2032)
		(layer "F.Cu")
		(net "SW_PVDDCR_SOC_P0_BOOT1")
	)
	(segment
		(start 397.064992 -173.369986)
		(end 397.114268 -173.419262)
		(width 0.2032)
		(layer "F.Cu")
		(net "SW_PVDDCR_SOC_P0_BOOT1")
	)
	(segment
		(start 397.114268 -173.419262)
		(end 397.114268 -174.271178)
		(width 0.2032)
		(layer "F.Cu")
		(net "SW_PVDDCR_SOC_P0_BOOT1")
	)
	(segment
		(start 104.8893 -343.565226)
		(end 104.8893 -342.839294)
		(width 0.2032)
		(layer "F.Cu")
		(net "SW_PVDDCR_CPU1_P1_BOOTR6")
	)
	(segment
		(start 105.515156 -344.191082)
		(end 104.8893 -343.565226)
		(width 0.2032)
		(layer "F.Cu")
		(net "SW_PVDDCR_CPU1_P1_BOOTR6")
	)
	(segment
		(start 97.239328 -339.281008)
		(end 96.613472 -338.655152)
		(width 0.2032)
		(layer "F.Cu")
		(net "SW_PVDDCR_CPU1_P1_BOOTR5")
	)
	(segment
		(start 96.613472 -338.655152)
		(end 96.613472 -337.92922)
		(width 0.2032)
		(layer "F.Cu")
		(net "SW_PVDDCR_CPU1_P1_BOOTR5")
	)
	(segment
		(start 63.034672 -350.347026)
		(end 63.034672 -349.621094)
		(width 0.2032)
		(layer "F.Cu")
		(net "SW_PVDDCR_CPU1_P1_BOOTR4")
	)
	(segment
		(start 63.660528 -350.972882)
		(end 63.034672 -350.347026)
		(width 0.2032)
		(layer "F.Cu")
		(net "SW_PVDDCR_CPU1_P1_BOOTR4")
	)
	(segment
		(start 71.569072 -338.625942)
		(end 71.569072 -337.90001)
		(width 0.2032)
		(layer "F.Cu")
		(net "SW_PVDDCR_CPU1_P1_BOOTR3")
	)
	(segment
		(start 72.194928 -339.251798)
		(end 71.569072 -338.625942)
		(width 0.2032)
		(layer "F.Cu")
		(net "SW_PVDDCR_CPU1_P1_BOOTR3")
	)
	(segment
		(start 80.550512 -339.244686)
		(end 79.924656 -338.61883)
		(width 0.2032)
		(layer "F.Cu")
		(net "SW_PVDDCR_CPU1_P1_BOOTR2")
	)
	(segment
		(start 79.924656 -338.61883)
		(end 79.924656 -337.892898)
		(width 0.2032)
		(layer "F.Cu")
		(net "SW_PVDDCR_CPU1_P1_BOOTR2")
	)
	(segment
		(start 88.908128 -339.230208)
		(end 88.282272 -338.604352)
		(width 0.2032)
		(layer "F.Cu")
		(net "SW_PVDDCR_CPU1_P1_BOOTR1")
	)
	(segment
		(start 88.282272 -338.604352)
		(end 88.282272 -337.87842)
		(width 0.2032)
		(layer "F.Cu")
		(net "SW_PVDDCR_CPU1_P1_BOOTR1")
	)
	(segment
		(start 104.488488 -344.991182)
		(end 105.515156 -344.991182)
		(width 0.2032)
		(layer "F.Cu")
		(net "SW_PVDDCR_CPU1_P1_BOOT6_R")
	)
	(segment
		(start 104.439212 -344.141806)
		(end 104.439212 -342.839294)
		(width 0.2032)
		(layer "F.Cu")
		(net "SW_PVDDCR_CPU1_P1_BOOT6")
	)
	(segment
		(start 104.488488 -344.191082)
		(end 104.439212 -344.141806)
		(width 0.2032)
		(layer "F.Cu")
		(net "SW_PVDDCR_CPU1_P1_BOOT6")
	)
	(segment
		(start 97.239328 -340.081108)
		(end 96.21266 -340.081108)
		(width 0.2032)
		(layer "F.Cu")
		(net "SW_PVDDCR_CPU1_P1_BOOT5_R")
	)
	(segment
		(start 96.21266 -339.281008)
		(end 96.163384 -339.231732)
		(width 0.2032)
		(layer "F.Cu")
		(net "SW_PVDDCR_CPU1_P1_BOOT5")
	)
	(segment
		(start 96.163384 -339.231732)
		(end 96.163384 -337.92922)
		(width 0.2032)
		(layer "F.Cu")
		(net "SW_PVDDCR_CPU1_P1_BOOT5")
	)
	(segment
		(start 63.660528 -351.772982)
		(end 62.63386 -351.772982)
		(width 0.2032)
		(layer "F.Cu")
		(net "SW_PVDDCR_CPU1_P1_BOOT4_R")
	)
	(segment
		(start 62.63386 -350.972882)
		(end 62.584584 -350.923606)
		(width 0.2032)
		(layer "F.Cu")
		(net "SW_PVDDCR_CPU1_P1_BOOT4")
	)
	(segment
		(start 62.584584 -350.923606)
		(end 62.584584 -349.621094)
		(width 0.2032)
		(layer "F.Cu")
		(net "SW_PVDDCR_CPU1_P1_BOOT4")
	)
	(segment
		(start 72.194928 -340.051898)
		(end 71.16826 -340.051898)
		(width 0.2032)
		(layer "F.Cu")
		(net "SW_PVDDCR_CPU1_P1_BOOT3_R")
	)
	(segment
		(start 71.16826 -339.251798)
		(end 71.118984 -339.202522)
		(width 0.2032)
		(layer "F.Cu")
		(net "SW_PVDDCR_CPU1_P1_BOOT3")
	)
	(segment
		(start 71.118984 -339.202522)
		(end 71.118984 -337.90001)
		(width 0.2032)
		(layer "F.Cu")
		(net "SW_PVDDCR_CPU1_P1_BOOT3")
	)
	(segment
		(start 80.550512 -340.044786)
		(end 79.523844 -340.044786)
		(width 0.2032)
		(layer "F.Cu")
		(net "SW_PVDDCR_CPU1_P1_BOOT2_R")
	)
	(segment
		(start 79.523844 -339.244686)
		(end 79.474568 -339.19541)
		(width 0.2032)
		(layer "F.Cu")
		(net "SW_PVDDCR_CPU1_P1_BOOT2")
	)
	(segment
		(start 79.474568 -339.19541)
		(end 79.474568 -337.892898)
		(width 0.2032)
		(layer "F.Cu")
		(net "SW_PVDDCR_CPU1_P1_BOOT2")
	)
	(segment
		(start 88.908128 -340.030308)
		(end 87.88146 -340.030308)
		(width 0.2032)
		(layer "F.Cu")
		(net "SW_PVDDCR_CPU1_P1_BOOT1_R")
	)
	(segment
		(start 87.832184 -339.180932)
		(end 87.832184 -337.87842)
		(width 0.2032)
		(layer "F.Cu")
		(net "SW_PVDDCR_CPU1_P1_BOOT1")
	)
	(segment
		(start 87.88146 -339.230208)
		(end 87.832184 -339.180932)
		(width 0.2032)
		(layer "F.Cu")
		(net "SW_PVDDCR_CPU1_P1_BOOT1")
	)
	(segment
		(start 353.451922 -344.186256)
		(end 352.826066 -343.5604)
		(width 0.2032)
		(layer "F.Cu")
		(net "SW_PVDDCR_CPU1_P0_BOOTR6")
	)
	(segment
		(start 352.826066 -343.5604)
		(end 352.826066 -342.834468)
		(width 0.2032)
		(layer "F.Cu")
		(net "SW_PVDDCR_CPU1_P0_BOOTR6")
	)
	(segment
		(start 344.550238 -338.650326)
		(end 344.550238 -337.924394)
		(width 0.2032)
		(layer "F.Cu")
		(net "SW_PVDDCR_CPU1_P0_BOOTR5")
	)
	(segment
		(start 345.176094 -339.276182)
		(end 344.550238 -338.650326)
		(width 0.2032)
		(layer "F.Cu")
		(net "SW_PVDDCR_CPU1_P0_BOOTR5")
	)
	(segment
		(start 309.856124 -350.3422)
		(end 309.856124 -349.616268)
		(width 0.2032)
		(layer "F.Cu")
		(net "SW_PVDDCR_CPU1_P0_BOOTR4")
	)
	(segment
		(start 310.48198 -350.968056)
		(end 309.856124 -350.3422)
		(width 0.2032)
		(layer "F.Cu")
		(net "SW_PVDDCR_CPU1_P0_BOOTR4")
	)
	(segment
		(start 319.505838 -338.621116)
		(end 319.505838 -337.895184)
		(width 0.2032)
		(layer "F.Cu")
		(net "SW_PVDDCR_CPU1_P0_BOOTR3")
	)
	(segment
		(start 320.131694 -339.246972)
		(end 319.505838 -338.621116)
		(width 0.2032)
		(layer "F.Cu")
		(net "SW_PVDDCR_CPU1_P0_BOOTR3")
	)
	(segment
		(start 328.487278 -339.23986)
		(end 327.861422 -338.614004)
		(width 0.2032)
		(layer "F.Cu")
		(net "SW_PVDDCR_CPU1_P0_BOOTR2")
	)
	(segment
		(start 327.861422 -338.614004)
		(end 327.861422 -337.888072)
		(width 0.2032)
		(layer "F.Cu")
		(net "SW_PVDDCR_CPU1_P0_BOOTR2")
	)
	(segment
		(start 336.219038 -338.599526)
		(end 336.219038 -337.873594)
		(width 0.2032)
		(layer "F.Cu")
		(net "SW_PVDDCR_CPU1_P0_BOOTR1")
	)
	(segment
		(start 336.844894 -339.225382)
		(end 336.219038 -338.599526)
		(width 0.2032)
		(layer "F.Cu")
		(net "SW_PVDDCR_CPU1_P0_BOOTR1")
	)
	(segment
		(start 352.425254 -344.986356)
		(end 353.451922 -344.986356)
		(width 0.2032)
		(layer "F.Cu")
		(net "SW_PVDDCR_CPU1_P0_BOOT6_R")
	)
	(segment
		(start 352.425254 -344.186256)
		(end 352.375978 -344.13698)
		(width 0.2032)
		(layer "F.Cu")
		(net "SW_PVDDCR_CPU1_P0_BOOT6")
	)
	(segment
		(start 352.375978 -344.13698)
		(end 352.375978 -342.834468)
		(width 0.2032)
		(layer "F.Cu")
		(net "SW_PVDDCR_CPU1_P0_BOOT6")
	)
	(segment
		(start 345.176094 -340.076282)
		(end 344.149426 -340.076282)
		(width 0.2032)
		(layer "F.Cu")
		(net "SW_PVDDCR_CPU1_P0_BOOT5_R")
	)
	(segment
		(start 344.10015 -339.226906)
		(end 344.10015 -337.924394)
		(width 0.2032)
		(layer "F.Cu")
		(net "SW_PVDDCR_CPU1_P0_BOOT5")
	)
	(segment
		(start 344.149426 -339.276182)
		(end 344.10015 -339.226906)
		(width 0.2032)
		(layer "F.Cu")
		(net "SW_PVDDCR_CPU1_P0_BOOT5")
	)
	(segment
		(start 310.48198 -351.768156)
		(end 309.455312 -351.768156)
		(width 0.2032)
		(layer "F.Cu")
		(net "SW_PVDDCR_CPU1_P0_BOOT4_R")
	)
	(segment
		(start 309.455312 -350.968056)
		(end 309.406036 -350.91878)
		(width 0.2032)
		(layer "F.Cu")
		(net "SW_PVDDCR_CPU1_P0_BOOT4")
	)
	(segment
		(start 309.406036 -350.91878)
		(end 309.406036 -349.616268)
		(width 0.2032)
		(layer "F.Cu")
		(net "SW_PVDDCR_CPU1_P0_BOOT4")
	)
	(segment
		(start 320.131694 -340.047072)
		(end 319.105026 -340.047072)
		(width 0.2032)
		(layer "F.Cu")
		(net "SW_PVDDCR_CPU1_P0_BOOT3_R")
	)
	(segment
		(start 319.05575 -339.197696)
		(end 319.05575 -337.895184)
		(width 0.2032)
		(layer "F.Cu")
		(net "SW_PVDDCR_CPU1_P0_BOOT3")
	)
	(segment
		(start 319.105026 -339.246972)
		(end 319.05575 -339.197696)
		(width 0.2032)
		(layer "F.Cu")
		(net "SW_PVDDCR_CPU1_P0_BOOT3")
	)
	(segment
		(start 328.487278 -340.03996)
		(end 327.46061 -340.03996)
		(width 0.2032)
		(layer "F.Cu")
		(net "SW_PVDDCR_CPU1_P0_BOOT2_R")
	)
	(segment
		(start 327.46061 -339.23986)
		(end 327.411334 -339.190584)
		(width 0.2032)
		(layer "F.Cu")
		(net "SW_PVDDCR_CPU1_P0_BOOT2")
	)
	(segment
		(start 327.411334 -339.190584)
		(end 327.411334 -337.888072)
		(width 0.2032)
		(layer "F.Cu")
		(net "SW_PVDDCR_CPU1_P0_BOOT2")
	)
	(segment
		(start 336.844894 -340.025482)
		(end 335.818226 -340.025482)
		(width 0.2032)
		(layer "F.Cu")
		(net "SW_PVDDCR_CPU1_P0_BOOT1_R")
	)
	(segment
		(start 335.76895 -339.176106)
		(end 335.76895 -337.873594)
		(width 0.2032)
		(layer "F.Cu")
		(net "SW_PVDDCR_CPU1_P0_BOOT1")
	)
	(segment
		(start 335.818226 -339.225382)
		(end 335.76895 -339.176106)
		(width 0.2032)
		(layer "F.Cu")
		(net "SW_PVDDCR_CPU1_P0_BOOT1")
	)
	(segment
		(start 64.487552 -165.302692)
		(end 63.861696 -164.676836)
		(width 0.2032)
		(layer "F.Cu")
		(net "SW_PVDDCR_CPU0_P1_PH6")
	)
	(segment
		(start 64.487552 -166.028624)
		(end 64.487552 -165.302692)
		(width 0.2032)
		(layer "F.Cu")
		(net "SW_PVDDCR_CPU0_P1_PH6")
	)
	(segment
		(start 72.800972 -174.725838)
		(end 72.800972 -173.999906)
		(width 0.2032)
		(layer "F.Cu")
		(net "SW_PVDDCR_CPU0_P1_PH5")
	)
	(segment
		(start 72.800972 -173.999906)
		(end 72.175116 -173.37405)
		(width 0.2032)
		(layer "F.Cu")
		(net "SW_PVDDCR_CPU0_P1_PH5")
	)
	(segment
		(start 106.295952 -175.271938)
		(end 106.295952 -174.546006)
		(width 0.2032)
		(layer "F.Cu")
		(net "SW_PVDDCR_CPU0_P1_PH4")
	)
	(segment
		(start 106.295952 -174.546006)
		(end 105.670096 -173.92015)
		(width 0.2032)
		(layer "F.Cu")
		(net "SW_PVDDCR_CPU0_P1_PH4")
	)
	(segment
		(start 97.913952 -179.793138)
		(end 97.913952 -179.067206)
		(width 0.2032)
		(layer "F.Cu")
		(net "SW_PVDDCR_CPU0_P1_PH3")
	)
	(segment
		(start 97.913952 -179.067206)
		(end 97.288096 -178.44135)
		(width 0.2032)
		(layer "F.Cu")
		(net "SW_PVDDCR_CPU0_P1_PH3")
	)
	(segment
		(start 89.521792 -179.775866)
		(end 89.521792 -179.049934)
		(width 0.2032)
		(layer "F.Cu")
		(net "SW_PVDDCR_CPU0_P1_PH2")
	)
	(segment
		(start 89.521792 -179.049934)
		(end 88.895936 -178.424078)
		(width 0.2032)
		(layer "F.Cu")
		(net "SW_PVDDCR_CPU0_P1_PH2")
	)
	(segment
		(start 81.124552 -179.118006)
		(end 80.498696 -178.49215)
		(width 0.2032)
		(layer "F.Cu")
		(net "SW_PVDDCR_CPU0_P1_PH1")
	)
	(segment
		(start 81.124552 -179.843938)
		(end 81.124552 -179.118006)
		(width 0.2032)
		(layer "F.Cu")
		(net "SW_PVDDCR_CPU0_P1_PH1")
	)
	(segment
		(start 63.861696 -163.876736)
		(end 64.888364 -163.876736)
		(width 0.2032)
		(layer "F.Cu")
		(net "SW_PVDDCR_CPU0_P1_BOOT6_RC")
	)
	(segment
		(start 64.888364 -164.676836)
		(end 64.93764 -164.726112)
		(width 0.2032)
		(layer "F.Cu")
		(net "SW_PVDDCR_CPU0_P1_BOOT6")
	)
	(segment
		(start 64.93764 -164.726112)
		(end 64.93764 -166.028624)
		(width 0.2032)
		(layer "F.Cu")
		(net "SW_PVDDCR_CPU0_P1_BOOT6")
	)
	(segment
		(start 72.175116 -172.57395)
		(end 73.201784 -172.57395)
		(width 0.2032)
		(layer "F.Cu")
		(net "SW_PVDDCR_CPU0_P1_BOOT5_RC")
	)
	(segment
		(start 73.201784 -173.37405)
		(end 73.25106 -173.423326)
		(width 0.2032)
		(layer "F.Cu")
		(net "SW_PVDDCR_CPU0_P1_BOOT5")
	)
	(segment
		(start 73.25106 -173.423326)
		(end 73.25106 -174.725838)
		(width 0.2032)
		(layer "F.Cu")
		(net "SW_PVDDCR_CPU0_P1_BOOT5")
	)
	(segment
		(start 106.696764 -173.12005)
		(end 105.670096 -173.12005)
		(width 0.2032)
		(layer "F.Cu")
		(net "SW_PVDDCR_CPU0_P1_BOOT4_RC")
	)
	(segment
		(start 106.696764 -173.92015)
		(end 106.74604 -173.969426)
		(width 0.2032)
		(layer "F.Cu")
		(net "SW_PVDDCR_CPU0_P1_BOOT4")
	)
	(segment
		(start 106.74604 -173.969426)
		(end 106.74604 -175.271938)
		(width 0.2032)
		(layer "F.Cu")
		(net "SW_PVDDCR_CPU0_P1_BOOT4")
	)
	(segment
		(start 97.288096 -177.64125)
		(end 98.314764 -177.64125)
		(width 0.2032)
		(layer "F.Cu")
		(net "SW_PVDDCR_CPU0_P1_BOOT3_RC")
	)
	(segment
		(start 98.314764 -178.44135)
		(end 98.36404 -178.490626)
		(width 0.2032)
		(layer "F.Cu")
		(net "SW_PVDDCR_CPU0_P1_BOOT3")
	)
	(segment
		(start 98.36404 -178.490626)
		(end 98.36404 -179.793138)
		(width 0.2032)
		(layer "F.Cu")
		(net "SW_PVDDCR_CPU0_P1_BOOT3")
	)
	(segment
		(start 88.895936 -177.623978)
		(end 89.922604 -177.623978)
		(width 0.2032)
		(layer "F.Cu")
		(net "SW_PVDDCR_CPU0_P1_BOOT2_RC")
	)
	(segment
		(start 89.922604 -178.424078)
		(end 89.922604 -178.887374)
		(width 0.2032)
		(layer "F.Cu")
		(net "SW_PVDDCR_CPU0_P1_BOOT2")
	)
	(segment
		(start 89.922604 -178.887374)
		(end 89.97188 -178.93665)
		(width 0.2032)
		(layer "F.Cu")
		(net "SW_PVDDCR_CPU0_P1_BOOT2")
	)
	(segment
		(start 89.97188 -178.93665)
		(end 89.97188 -179.775866)
		(width 0.2032)
		(layer "F.Cu")
		(net "SW_PVDDCR_CPU0_P1_BOOT2")
	)
	(segment
		(start 80.498696 -177.69205)
		(end 81.525364 -177.69205)
		(width 0.2032)
		(layer "F.Cu")
		(net "SW_PVDDCR_CPU0_P1_BOOT1_RC")
	)
	(segment
		(start 81.57464 -178.541426)
		(end 81.57464 -179.843938)
		(width 0.2032)
		(layer "F.Cu")
		(net "SW_PVDDCR_CPU0_P1_BOOT1")
	)
	(segment
		(start 81.525364 -178.49215)
		(end 81.57464 -178.541426)
		(width 0.2032)
		(layer "F.Cu")
		(net "SW_PVDDCR_CPU0_P1_BOOT1")
	)
	(segment
		(start 345.941904 -156.887672)
		(end 346.56776 -157.513528)
		(width 0.2032)
		(layer "F.Cu")
		(net "SW_PVDDCR_CPU0_P0_PH6")
	)
	(segment
		(start 346.56776 -157.513528)
		(end 346.56776 -158.23946)
		(width 0.2032)
		(layer "F.Cu")
		(net "SW_PVDDCR_CPU0_P0_PH6")
	)
	(segment
		(start 354.87356 -166.59606)
		(end 354.87356 -165.870128)
		(width 0.2032)
		(layer "F.Cu")
		(net "SW_PVDDCR_CPU0_P0_PH5")
	)
	(segment
		(start 354.87356 -165.870128)
		(end 354.247704 -165.244272)
		(width 0.2032)
		(layer "F.Cu")
		(net "SW_PVDDCR_CPU0_P0_PH5")
	)
	(segment
		(start 388.24916 -179.118006)
		(end 387.623304 -178.49215)
		(width 0.2032)
		(layer "F.Cu")
		(net "SW_PVDDCR_CPU0_P0_PH4")
	)
	(segment
		(start 388.24916 -179.843938)
		(end 388.24916 -179.118006)
		(width 0.2032)
		(layer "F.Cu")
		(net "SW_PVDDCR_CPU0_P0_PH4")
	)
	(segment
		(start 379.91796 -179.88661)
		(end 379.91796 -179.118006)
		(width 0.2032)
		(layer "F.Cu")
		(net "SW_PVDDCR_CPU0_P0_PH3")
	)
	(segment
		(start 379.91796 -179.118006)
		(end 379.292104 -178.49215)
		(width 0.2032)
		(layer "F.Cu")
		(net "SW_PVDDCR_CPU0_P0_PH3")
	)
	(segment
		(start 371.515132 -179.118006)
		(end 370.889276 -178.49215)
		(width 0.2032)
		(layer "F.Cu")
		(net "SW_PVDDCR_CPU0_P0_PH2")
	)
	(segment
		(start 371.515132 -179.843938)
		(end 371.515132 -179.118006)
		(width 0.2032)
		(layer "F.Cu")
		(net "SW_PVDDCR_CPU0_P0_PH2")
	)
	(segment
		(start 363.15396 -174.145448)
		(end 362.528104 -173.519592)
		(width 0.2032)
		(layer "F.Cu")
		(net "SW_PVDDCR_CPU0_P0_PH1")
	)
	(segment
		(start 363.15396 -174.87138)
		(end 363.15396 -174.145448)
		(width 0.2032)
		(layer "F.Cu")
		(net "SW_PVDDCR_CPU0_P0_PH1")
	)
	(segment
		(start 346.968572 -156.087572)
		(end 345.941904 -156.087572)
		(width 0.2032)
		(layer "F.Cu")
		(net "SW_PVDDCR_CPU0_P0_BOOT6_RC")
	)
	(segment
		(start 346.968572 -156.887672)
		(end 346.968572 -157.207712)
		(width 0.2032)
		(layer "F.Cu")
		(net "SW_PVDDCR_CPU0_P0_BOOT6")
	)
	(segment
		(start 346.968572 -157.207712)
		(end 347.017848 -157.256988)
		(width 0.2032)
		(layer "F.Cu")
		(net "SW_PVDDCR_CPU0_P0_BOOT6")
	)
	(segment
		(start 347.017848 -157.256988)
		(end 347.017848 -158.23946)
		(width 0.2032)
		(layer "F.Cu")
		(net "SW_PVDDCR_CPU0_P0_BOOT6")
	)
	(segment
		(start 355.274372 -164.444172)
		(end 354.247704 -164.444172)
		(width 0.2032)
		(layer "F.Cu")
		(net "SW_PVDDCR_CPU0_P0_BOOT5_RC")
	)
	(segment
		(start 355.323648 -165.293548)
		(end 355.323648 -166.59606)
		(width 0.2032)
		(layer "F.Cu")
		(net "SW_PVDDCR_CPU0_P0_BOOT5")
	)
	(segment
		(start 355.274372 -165.244272)
		(end 355.323648 -165.293548)
		(width 0.2032)
		(layer "F.Cu")
		(net "SW_PVDDCR_CPU0_P0_BOOT5")
	)
	(segment
		(start 387.623304 -177.69205)
		(end 388.649972 -177.69205)
		(width 0.2032)
		(layer "F.Cu")
		(net "SW_PVDDCR_CPU0_P0_BOOT4_RC")
	)
	(segment
		(start 388.699248 -178.541426)
		(end 388.699248 -179.843938)
		(width 0.2032)
		(layer "F.Cu")
		(net "SW_PVDDCR_CPU0_P0_BOOT4")
	)
	(segment
		(start 388.649972 -178.49215)
		(end 388.699248 -178.541426)
		(width 0.2032)
		(layer "F.Cu")
		(net "SW_PVDDCR_CPU0_P0_BOOT4")
	)
	(segment
		(start 379.292104 -177.69205)
		(end 380.318772 -177.69205)
		(width 0.2032)
		(layer "F.Cu")
		(net "SW_PVDDCR_CPU0_P0_BOOT3_RC")
	)
	(segment
		(start 380.368048 -178.541426)
		(end 380.318772 -178.49215)
		(width 0.2032)
		(layer "F.Cu")
		(net "SW_PVDDCR_CPU0_P0_BOOT3")
	)
	(segment
		(start 380.368048 -179.88661)
		(end 380.368048 -178.541426)
		(width 0.2032)
		(layer "F.Cu")
		(net "SW_PVDDCR_CPU0_P0_BOOT3")
	)
	(segment
		(start 370.889276 -177.69205)
		(end 371.915944 -177.69205)
		(width 0.2032)
		(layer "F.Cu")
		(net "SW_PVDDCR_CPU0_P0_BOOT2_RC")
	)
	(segment
		(start 371.915944 -178.49215)
		(end 371.96522 -178.541426)
		(width 0.2032)
		(layer "F.Cu")
		(net "SW_PVDDCR_CPU0_P0_BOOT2")
	)
	(segment
		(start 371.96522 -178.541426)
		(end 371.96522 -179.843938)
		(width 0.2032)
		(layer "F.Cu")
		(net "SW_PVDDCR_CPU0_P0_BOOT2")
	)
	(segment
		(start 362.528104 -172.719492)
		(end 363.554772 -172.719492)
		(width 0.2032)
		(layer "F.Cu")
		(net "SW_PVDDCR_CPU0_P0_BOOT1_RC")
	)
	(segment
		(start 363.554772 -173.519592)
		(end 363.604048 -173.568868)
		(width 0.2032)
		(layer "F.Cu")
		(net "SW_PVDDCR_CPU0_P0_BOOT1")
	)
	(segment
		(start 363.604048 -173.568868)
		(end 363.604048 -174.87138)
		(width 0.2032)
		(layer "F.Cu")
		(net "SW_PVDDCR_CPU0_P0_BOOT1")
	)
	(segment
		(start 192.406524 -354.22078)
		(end 192.406524 -354.898452)
		(width 0.2032)
		(layer "F.Cu")
		(net "SW_PVDD11_S3_P1_PH2")
	)
	(segment
		(start 192.406524 -354.898452)
		(end 193.03238 -355.524308)
		(width 0.2032)
		(layer "F.Cu")
		(net "SW_PVDD11_S3_P1_PH2")
	)
	(segment
		(start 184.079896 -354.873052)
		(end 184.079896 -354.19538)
		(width 0.2032)
		(layer "F.Cu")
		(net "SW_PVDD11_S3_P1_PH1")
	)
	(segment
		(start 184.705752 -355.498908)
		(end 184.079896 -354.873052)
		(width 0.2032)
		(layer "F.Cu")
		(net "SW_PVDD11_S3_P1_PH1")
	)
	(segment
		(start 192.005712 -356.324408)
		(end 193.03238 -356.324408)
		(width 0.254)
		(layer "F.Cu")
		(net "SW_PVDD11_S3_P1_BOOT2_RC")
	)
	(segment
		(start 192.005712 -355.524308)
		(end 191.956436 -355.475032)
		(width 0.2032)
		(layer "F.Cu")
		(net "SW_PVDD11_S3_P1_BOOT2")
	)
	(segment
		(start 191.956436 -355.475032)
		(end 191.956436 -354.22078)
		(width 0.2032)
		(layer "F.Cu")
		(net "SW_PVDD11_S3_P1_BOOT2")
	)
	(segment
		(start 183.679084 -356.299008)
		(end 184.705752 -356.299008)
		(width 0.254)
		(layer "F.Cu")
		(net "SW_PVDD11_S3_P1_BOOT1_RC")
	)
	(segment
		(start 183.679084 -355.498908)
		(end 183.629808 -355.449632)
		(width 0.2032)
		(layer "F.Cu")
		(net "SW_PVDD11_S3_P1_BOOT1")
	)
	(segment
		(start 183.629808 -355.449632)
		(end 183.629808 -354.19538)
		(width 0.2032)
		(layer "F.Cu")
		(net "SW_PVDD11_S3_P1_BOOT1")
	)
	(segment
		(start 433.130706 -354.717858)
		(end 433.130706 -354.040186)
		(width 0.2032)
		(layer "F.Cu")
		(net "SW_PVDD11_S3_P0_PH2")
	)
	(segment
		(start 433.756562 -355.343714)
		(end 433.130706 -354.717858)
		(width 0.2032)
		(layer "F.Cu")
		(net "SW_PVDD11_S3_P0_PH2")
	)
	(segment
		(start 425.429934 -355.318314)
		(end 424.804078 -354.692458)
		(width 0.2032)
		(layer "F.Cu")
		(net "SW_PVDD11_S3_P0_PH1")
	)
	(segment
		(start 424.804078 -354.692458)
		(end 424.804078 -354.014786)
		(width 0.2032)
		(layer "F.Cu")
		(net "SW_PVDD11_S3_P0_PH1")
	)
	(segment
		(start 433.756562 -356.143814)
		(end 432.729894 -356.143814)
		(width 0.254)
		(layer "F.Cu")
		(net "SW_PVDD11_S3_P0_BOOT2_RC")
	)
	(segment
		(start 432.680618 -355.294438)
		(end 432.680618 -354.040186)
		(width 0.2032)
		(layer "F.Cu")
		(net "SW_PVDD11_S3_P0_BOOT2")
	)
	(segment
		(start 432.729894 -355.343714)
		(end 432.680618 -355.294438)
		(width 0.2032)
		(layer "F.Cu")
		(net "SW_PVDD11_S3_P0_BOOT2")
	)
	(segment
		(start 425.429934 -356.118414)
		(end 424.403266 -356.118414)
		(width 0.254)
		(layer "F.Cu")
		(net "SW_PVDD11_S3_P0_BOOT1_RC")
	)
	(segment
		(start 424.403266 -355.318314)
		(end 424.35399 -355.269038)
		(width 0.2032)
		(layer "F.Cu")
		(net "SW_PVDD11_S3_P0_BOOT1")
	)
	(segment
		(start 424.35399 -355.269038)
		(end 424.35399 -354.014786)
		(width 0.2032)
		(layer "F.Cu")
		(net "SW_PVDD11_S3_P0_BOOT1")
	)
	(via
		(at 413.4612 -131.890516)
		(size 0.762)
		(drill 0.381)
		(layers "F.Cu" "B.Cu")
		(net "SW_P5V_AUX_FLT")
	)
	(segment
		(start 202.014074 -127.56007)
		(end 201.971656 -127.602488)
		(width 0.10668)
		(layer "F.Cu")
		(net "SW_P3V3_EN")
	)
	(segment
		(start 204.83195 -129.032)
		(end 204.83195 -128.016)
		(width 0.10668)
		(layer "F.Cu")
		(net "SW_P3V3_EN")
	)
	(segment
		(start 203.597764 -127.59563)
		(end 203.562204 -127.56007)
		(width 0.10668)
		(layer "F.Cu")
		(net "SW_P3V3_EN")
	)
	(segment
		(start 204.41158 -127.59563)
		(end 203.597764 -127.59563)
		(width 0.10668)
		(layer "F.Cu")
		(net "SW_P3V3_EN")
	)
	(segment
		(start 201.971656 -127.602488)
		(end 200.926446 -127.602488)
		(width 0.10668)
		(layer "F.Cu")
		(net "SW_P3V3_EN")
	)
	(segment
		(start 204.83195 -128.016)
		(end 204.41158 -127.59563)
		(width 0.10668)
		(layer "F.Cu")
		(net "SW_P3V3_EN")
	)
	(segment
		(start 204.83195 -130.048)
		(end 204.83195 -129.032)
		(width 0.10668)
		(layer "F.Cu")
		(net "SW_P3V3_EN")
	)
	(segment
		(start 200.926446 -127.602488)
		(end 200.787762 -127.463804)
		(width 0.10668)
		(layer "F.Cu")
		(net "SW_P3V3_EN")
	)
	(segment
		(start 203.562204 -127.56007)
		(end 202.014074 -127.56007)
		(width 0.10668)
		(layer "F.Cu")
		(net "SW_P3V3_EN")
	)
	(segment
		(start 192.322196 -119.452898)
		(end 192.712086 -119.842788)
		(width 0.10668)
		(layer "F.Cu")
		(net "SW_P3V3_EN")
	)
	(via
		(at 192.712086 -119.842788)
		(size 0.4572)
		(drill 0.254)
		(layers "F.Cu" "B.Cu")
		(net "SW_P3V3_EN")
	)
	(via
		(at 200.787762 -127.463804)
		(size 0.508)
		(drill 0.254)
		(layers "F.Cu" "B.Cu")
		(net "SW_P3V3_EN")
	)
	(segment
		(start 200.580752 -125.290834)
		(end 196.669406 -125.290834)
		(width 0.11684)
		(layer "In15.Cu")
		(net "SW_P3V3_EN")
	)
	(segment
		(start 196.669406 -125.290834)
		(end 196.610224 -125.350016)
		(width 0.11684)
		(layer "In15.Cu")
		(net "SW_P3V3_EN")
	)
	(segment
		(start 200.852278 -127.399288)
		(end 200.852278 -125.56236)
		(width 0.11684)
		(layer "In15.Cu")
		(net "SW_P3V3_EN")
	)
	(segment
		(start 194.352164 -122.912378)
		(end 193.418968 -122.912378)
		(width 0.11684)
		(layer "In15.Cu")
		(net "SW_P3V3_EN")
	)
	(segment
		(start 192.85331 -119.842788)
		(end 192.712086 -119.842788)
		(width 0.11684)
		(layer "In15.Cu")
		(net "SW_P3V3_EN")
	)
	(segment
		(start 193.418968 -122.912378)
		(end 193.10604 -122.59945)
		(width 0.11684)
		(layer "In15.Cu")
		(net "SW_P3V3_EN")
	)
	(segment
		(start 193.10604 -120.095518)
		(end 192.85331 -119.842788)
		(width 0.11684)
		(layer "In15.Cu")
		(net "SW_P3V3_EN")
	)
	(segment
		(start 196.610224 -125.350016)
		(end 195.882006 -125.350016)
		(width 0.11684)
		(layer "In15.Cu")
		(net "SW_P3V3_EN")
	)
	(segment
		(start 195.882006 -125.350016)
		(end 195.4784 -124.94641)
		(width 0.11684)
		(layer "In15.Cu")
		(net "SW_P3V3_EN")
	)
	(segment
		(start 200.787762 -127.463804)
		(end 200.852278 -127.399288)
		(width 0.11684)
		(layer "In15.Cu")
		(net "SW_P3V3_EN")
	)
	(segment
		(start 193.10604 -122.59945)
		(end 193.10604 -120.095518)
		(width 0.11684)
		(layer "In15.Cu")
		(net "SW_P3V3_EN")
	)
	(segment
		(start 195.4784 -124.038614)
		(end 194.352164 -122.912378)
		(width 0.11684)
		(layer "In15.Cu")
		(net "SW_P3V3_EN")
	)
	(segment
		(start 195.4784 -124.94641)
		(end 195.4784 -124.038614)
		(width 0.11684)
		(layer "In15.Cu")
		(net "SW_P3V3_EN")
	)
	(segment
		(start 200.852278 -125.56236)
		(end 200.580752 -125.290834)
		(width 0.11684)
		(layer "In15.Cu")
		(net "SW_P3V3_EN")
	)
	(via
		(at 449.42887 -51.03368)
		(size 0.508)
		(drill 0.254)
		(layers "F.Cu" "B.Cu")
		(net "SW_P3V3_AUX_FLT")
	)
	(via
		(at 451.40118 -51.054508)
		(size 0.508)
		(drill 0.254)
		(layers "F.Cu" "B.Cu")
		(net "SW_P3V3_AUX_FLT")
	)
	(via
		(at 448.33286 -51.390804)
		(size 0.508)
		(drill 0.254)
		(layers "F.Cu" "B.Cu")
		(net "SW_P3V3_AUX_FLT")
	)
	(via
		(at 445.898016 -51.374802)
		(size 0.508)
		(drill 0.254)
		(layers "F.Cu" "B.Cu")
		(net "SW_P3V3_AUX_FLT")
	)
	(via
		(at 446.53962 -51.374802)
		(size 0.508)
		(drill 0.254)
		(layers "F.Cu" "B.Cu")
		(net "SW_P3V3_AUX_FLT")
	)
	(via
		(at 450.489574 -49.30648)
		(size 0.508)
		(drill 0.254)
		(layers "F.Cu" "B.Cu")
		(net "SW_P3V3_AUX_FLT")
	)
	(via
		(at 447.691256 -51.390804)
		(size 0.508)
		(drill 0.254)
		(layers "F.Cu" "B.Cu")
		(net "SW_P3V3_AUX_FLT")
	)
	(via
		(at 450.070474 -51.03368)
		(size 0.508)
		(drill 0.254)
		(layers "F.Cu" "B.Cu")
		(net "SW_P3V3_AUX_FLT")
	)
	(via
		(at 450.759576 -51.054508)
		(size 0.508)
		(drill 0.254)
		(layers "F.Cu" "B.Cu")
		(net "SW_P3V3_AUX_FLT")
	)
	(via
		(at 444.288926 -52.539646)
		(size 0.6604)
		(drill 0.3302)
		(layers "F.Cu" "B.Cu")
		(net "SW_P3V3_AUX_FLT")
	)
	(via
		(at 449.84797 -49.30648)
		(size 0.508)
		(drill 0.254)
		(layers "F.Cu" "B.Cu")
		(net "SW_P3V3_AUX_FLT")
	)
	(segment
		(start 451.739 -49.377346)
		(end 451.739 -50.239422)
		(width 0.254)
		(layer "F.Cu")
		(net "SW_P3V3_AUX_BOOT_R")
	)
	(segment
		(start 451.753224 -50.253646)
		(end 451.753224 -50.266346)
		(width 0.254)
		(layer "F.Cu")
		(net "SW_P3V3_AUX_BOOT_R")
	)
	(segment
		(start 451.739 -50.239422)
		(end 451.753224 -50.253646)
		(width 0.254)
		(layer "F.Cu")
		(net "SW_P3V3_AUX_BOOT_R")
	)
	(segment
		(start 453.13219 -50.253646)
		(end 453.195436 -50.316892)
		(width 0.254)
		(layer "F.Cu")
		(net "SW_P3V3_AUX_BOOTR")
	)
	(segment
		(start 452.566024 -50.253646)
		(end 453.13219 -50.253646)
		(width 0.254)
		(layer "F.Cu")
		(net "SW_P3V3_AUX_BOOTR")
	)
	(segment
		(start 452.553324 -50.266346)
		(end 452.566024 -50.253646)
		(width 0.254)
		(layer "F.Cu")
		(net "SW_P3V3_AUX_BOOTR")
	)
	(segment
		(start 453.195436 -50.316892)
		(end 454.150222 -50.316892)
		(width 0.254)
		(layer "F.Cu")
		(net "SW_P3V3_AUX_BOOTR")
	)
	(segment
		(start 453.483472 -49.81702)
		(end 454.150222 -49.81702)
		(width 0.254)
		(layer "F.Cu")
		(net "SW_P3V3_AUX_BOOT")
	)
	(segment
		(start 453.382126 -49.715674)
		(end 453.483472 -49.81702)
		(width 0.254)
		(layer "F.Cu")
		(net "SW_P3V3_AUX_BOOT")
	)
	(segment
		(start 452.5391 -49.377346)
		(end 452.877428 -49.715674)
		(width 0.254)
		(layer "F.Cu")
		(net "SW_P3V3_AUX_BOOT")
	)
	(segment
		(start 452.877428 -49.715674)
		(end 453.382126 -49.715674)
		(width 0.254)
		(layer "F.Cu")
		(net "SW_P3V3_AUX_BOOT")
	)
	(via
		(at 201.745342 -344.8304)
		(size 0.508)
		(drill 0.254)
		(layers "F.Cu" "B.Cu")
		(net "SW_P12V_AUX_PVDD_33_S5_FLT")
	)
	(via
		(at 201.745342 -344.0684)
		(size 0.508)
		(drill 0.254)
		(layers "F.Cu" "B.Cu")
		(net "SW_P12V_AUX_PVDD_33_S5_FLT")
	)
	(via
		(at 201.745342 -345.821)
		(size 0.508)
		(drill 0.254)
		(layers "F.Cu" "B.Cu")
		(net "SW_P12V_AUX_PVDD_33_S5_FLT")
	)
	(via
		(at 201.745342 -346.583)
		(size 0.508)
		(drill 0.254)
		(layers "F.Cu" "B.Cu")
		(net "SW_P12V_AUX_PVDD_33_S5_FLT")
	)
	(via
		(at 40.033194 -349.142558)
		(size 0.508)
		(drill 0.254)
		(layers "F.Cu" "B.Cu")
		(net "SW_P12V_AUX_PVDDIO_P1_FLT")
	)
	(via
		(at 54.234334 -348.709488)
		(size 0.49022)
		(drill 0.254)
		(layers "F.Cu" "B.Cu")
		(net "SW_P12V_AUX_PVDDIO_P1_FLT")
	)
	(via
		(at 43.993308 -359.219246)
		(size 0.508)
		(drill 0.254)
		(layers "F.Cu" "B.Cu")
		(net "SW_P12V_AUX_PVDDIO_P1_FLT")
	)
	(via
		(at 56.720994 -349.904558)
		(size 0.508)
		(drill 0.254)
		(layers "F.Cu" "B.Cu")
		(net "SW_P12V_AUX_PVDDIO_P1_FLT")
	)
	(via
		(at 38.189154 -348.709488)
		(size 0.49022)
		(drill 0.254)
		(layers "F.Cu" "B.Cu")
		(net "SW_P12V_AUX_PVDDIO_P1_FLT")
	)
	(via
		(at 39.50843 -350.318578)
		(size 0.508)
		(drill 0.254)
		(layers "F.Cu" "B.Cu")
		(net "SW_P12V_AUX_PVDDIO_P1_FLT")
	)
	(via
		(at 47.81423 -349.581978)
		(size 0.508)
		(drill 0.254)
		(layers "F.Cu" "B.Cu")
		(net "SW_P12V_AUX_PVDDIO_P1_FLT")
	)
	(via
		(at 50.03673 -357.457502)
		(size 0.508)
		(drill 0.254)
		(layers "F.Cu" "B.Cu")
		(net "SW_P12V_AUX_PVDDIO_P1_FLT")
	)
	(via
		(at 41.369742 -358.549194)
		(size 0.508)
		(drill 0.254)
		(layers "F.Cu" "B.Cu")
		(net "SW_P12V_AUX_PVDDIO_P1_FLT")
	)
	(via
		(at 30.525974 -348.709488)
		(size 0.49022)
		(drill 0.254)
		(layers "F.Cu" "B.Cu")
		(net "SW_P12V_AUX_PVDDIO_P1_FLT")
	)
	(via
		(at 50.03673 -356.822502)
		(size 0.508)
		(drill 0.254)
		(layers "F.Cu" "B.Cu")
		(net "SW_P12V_AUX_PVDDIO_P1_FLT")
	)
	(via
		(at 48.897794 -350.260158)
		(size 0.508)
		(drill 0.254)
		(layers "F.Cu" "B.Cu")
		(net "SW_P12V_AUX_PVDDIO_P1_FLT")
	)
	(via
		(at 55.727854 -347.997018)
		(size 0.508)
		(drill 0.254)
		(layers "F.Cu" "B.Cu")
		(net "SW_P12V_AUX_PVDDIO_P1_FLT")
	)
	(via
		(at 49.353978 -358.108504)
		(size 0.508)
		(drill 0.254)
		(layers "F.Cu" "B.Cu")
		(net "SW_P12V_AUX_PVDDIO_P1_FLT")
	)
	(via
		(at 30.795214 -347.966538)
		(size 0.508)
		(drill 0.254)
		(layers "F.Cu" "B.Cu")
		(net "SW_P12V_AUX_PVDDIO_P1_FLT")
	)
	(via
		(at 55.468774 -348.709488)
		(size 0.49022)
		(drill 0.254)
		(layers "F.Cu" "B.Cu")
		(net "SW_P12V_AUX_PVDDIO_P1_FLT")
	)
	(via
		(at 49.988978 -358.108504)
		(size 0.508)
		(drill 0.254)
		(layers "F.Cu" "B.Cu")
		(net "SW_P12V_AUX_PVDDIO_P1_FLT")
	)
	(via
		(at 29.291534 -348.709488)
		(size 0.49022)
		(drill 0.254)
		(layers "F.Cu" "B.Cu")
		(net "SW_P12V_AUX_PVDDIO_P1_FLT")
	)
	(via
		(at 39.50843 -349.581978)
		(size 0.508)
		(drill 0.254)
		(layers "F.Cu" "B.Cu")
		(net "SW_P12V_AUX_PVDDIO_P1_FLT")
	)
	(via
		(at 48.76673 -356.822502)
		(size 0.508)
		(drill 0.254)
		(layers "F.Cu" "B.Cu")
		(net "SW_P12V_AUX_PVDDIO_P1_FLT")
	)
	(via
		(at 43.983656 -357.224838)
		(size 0.508)
		(drill 0.254)
		(layers "F.Cu" "B.Cu")
		(net "SW_P12V_AUX_PVDDIO_P1_FLT")
	)
	(via
		(at 48.897794 -349.523558)
		(size 0.508)
		(drill 0.254)
		(layers "F.Cu" "B.Cu")
		(net "SW_P12V_AUX_PVDDIO_P1_FLT")
	)
	(via
		(at 31.22803 -350.318578)
		(size 0.508)
		(drill 0.254)
		(layers "F.Cu" "B.Cu")
		(net "SW_P12V_AUX_PVDDIO_P1_FLT")
	)
	(via
		(at 47.81423 -350.318578)
		(size 0.508)
		(drill 0.254)
		(layers "F.Cu" "B.Cu")
		(net "SW_P12V_AUX_PVDDIO_P1_FLT")
	)
	(via
		(at 37.571934 -348.709488)
		(size 0.49022)
		(drill 0.254)
		(layers "F.Cu" "B.Cu")
		(net "SW_P12V_AUX_PVDDIO_P1_FLT")
	)
	(via
		(at 56.695594 -349.142558)
		(size 0.508)
		(drill 0.254)
		(layers "F.Cu" "B.Cu")
		(net "SW_P12V_AUX_PVDDIO_P1_FLT")
	)
	(via
		(at 31.22803 -349.581978)
		(size 0.508)
		(drill 0.254)
		(layers "F.Cu" "B.Cu")
		(net "SW_P12V_AUX_PVDDIO_P1_FLT")
	)
	(via
		(at 31.778194 -349.904558)
		(size 0.508)
		(drill 0.254)
		(layers "F.Cu" "B.Cu")
		(net "SW_P12V_AUX_PVDDIO_P1_FLT")
	)
	(via
		(at 32.311594 -349.523558)
		(size 0.508)
		(drill 0.254)
		(layers "F.Cu" "B.Cu")
		(net "SW_P12V_AUX_PVDDIO_P1_FLT")
	)
	(via
		(at 38.806374 -348.709488)
		(size 0.49022)
		(drill 0.254)
		(layers "F.Cu" "B.Cu")
		(net "SW_P12V_AUX_PVDDIO_P1_FLT")
	)
	(via
		(at 48.364394 -349.904558)
		(size 0.508)
		(drill 0.254)
		(layers "F.Cu" "B.Cu")
		(net "SW_P12V_AUX_PVDDIO_P1_FLT")
	)
	(via
		(at 43.983656 -357.859838)
		(size 0.508)
		(drill 0.254)
		(layers "F.Cu" "B.Cu")
		(net "SW_P12V_AUX_PVDDIO_P1_FLT")
	)
	(via
		(at 39.050214 -347.974158)
		(size 0.508)
		(drill 0.254)
		(layers "F.Cu" "B.Cu")
		(net "SW_P12V_AUX_PVDDIO_P1_FLT")
	)
	(via
		(at 47.92853 -357.457502)
		(size 0.508)
		(drill 0.254)
		(layers "F.Cu" "B.Cu")
		(net "SW_P12V_AUX_PVDDIO_P1_FLT")
	)
	(via
		(at 40.591994 -348.786958)
		(size 0.508)
		(drill 0.254)
		(layers "F.Cu" "B.Cu")
		(net "SW_P12V_AUX_PVDDIO_P1_FLT")
	)
	(via
		(at 54.851554 -348.709488)
		(size 0.49022)
		(drill 0.254)
		(layers "F.Cu" "B.Cu")
		(net "SW_P12V_AUX_PVDDIO_P1_FLT")
	)
	(via
		(at 48.76673 -357.457502)
		(size 0.508)
		(drill 0.254)
		(layers "F.Cu" "B.Cu")
		(net "SW_P12V_AUX_PVDDIO_P1_FLT")
	)
	(via
		(at 31.752794 -349.142558)
		(size 0.508)
		(drill 0.254)
		(layers "F.Cu" "B.Cu")
		(net "SW_P12V_AUX_PVDDIO_P1_FLT")
	)
	(via
		(at 43.935904 -358.51084)
		(size 0.508)
		(drill 0.254)
		(layers "F.Cu" "B.Cu")
		(net "SW_P12V_AUX_PVDDIO_P1_FLT")
	)
	(via
		(at 40.591994 -350.260158)
		(size 0.508)
		(drill 0.254)
		(layers "F.Cu" "B.Cu")
		(net "SW_P12V_AUX_PVDDIO_P1_FLT")
	)
	(via
		(at 48.718978 -358.108504)
		(size 0.508)
		(drill 0.254)
		(layers "F.Cu" "B.Cu")
		(net "SW_P12V_AUX_PVDDIO_P1_FLT")
	)
	(via
		(at 50.67173 -357.457502)
		(size 0.508)
		(drill 0.254)
		(layers "F.Cu" "B.Cu")
		(net "SW_P12V_AUX_PVDDIO_P1_FLT")
	)
	(via
		(at 45.877734 -348.709488)
		(size 0.49022)
		(drill 0.254)
		(layers "F.Cu" "B.Cu")
		(net "SW_P12V_AUX_PVDDIO_P1_FLT")
	)
	(via
		(at 50.67173 -356.822502)
		(size 0.508)
		(drill 0.254)
		(layers "F.Cu" "B.Cu")
		(net "SW_P12V_AUX_PVDDIO_P1_FLT")
	)
	(via
		(at 41.417494 -357.263192)
		(size 0.508)
		(drill 0.254)
		(layers "F.Cu" "B.Cu")
		(net "SW_P12V_AUX_PVDDIO_P1_FLT")
	)
	(via
		(at 57.254394 -349.523558)
		(size 0.508)
		(drill 0.254)
		(layers "F.Cu" "B.Cu")
		(net "SW_P12V_AUX_PVDDIO_P1_FLT")
	)
	(via
		(at 39.050214 -347.237558)
		(size 0.508)
		(drill 0.254)
		(layers "F.Cu" "B.Cu")
		(net "SW_P12V_AUX_PVDDIO_P1_FLT")
	)
	(via
		(at 46.494954 -348.709488)
		(size 0.49022)
		(drill 0.254)
		(layers "F.Cu" "B.Cu")
		(net "SW_P12V_AUX_PVDDIO_P1_FLT")
	)
	(via
		(at 49.40173 -357.457502)
		(size 0.508)
		(drill 0.254)
		(layers "F.Cu" "B.Cu")
		(net "SW_P12V_AUX_PVDDIO_P1_FLT")
	)
	(via
		(at 32.311594 -348.786958)
		(size 0.508)
		(drill 0.254)
		(layers "F.Cu" "B.Cu")
		(net "SW_P12V_AUX_PVDDIO_P1_FLT")
	)
	(via
		(at 56.17083 -349.581978)
		(size 0.508)
		(drill 0.254)
		(layers "F.Cu" "B.Cu")
		(net "SW_P12V_AUX_PVDDIO_P1_FLT")
	)
	(via
		(at 57.254394 -348.786958)
		(size 0.508)
		(drill 0.254)
		(layers "F.Cu" "B.Cu")
		(net "SW_P12V_AUX_PVDDIO_P1_FLT")
	)
	(via
		(at 55.727854 -347.260418)
		(size 0.508)
		(drill 0.254)
		(layers "F.Cu" "B.Cu")
		(net "SW_P12V_AUX_PVDDIO_P1_FLT")
	)
	(via
		(at 47.112174 -348.709488)
		(size 0.49022)
		(drill 0.254)
		(layers "F.Cu" "B.Cu")
		(net "SW_P12V_AUX_PVDDIO_P1_FLT")
	)
	(via
		(at 56.17083 -350.318578)
		(size 0.508)
		(drill 0.254)
		(layers "F.Cu" "B.Cu")
		(net "SW_P12V_AUX_PVDDIO_P1_FLT")
	)
	(via
		(at 30.795214 -347.229938)
		(size 0.508)
		(drill 0.254)
		(layers "F.Cu" "B.Cu")
		(net "SW_P12V_AUX_PVDDIO_P1_FLT")
	)
	(via
		(at 50.623978 -358.108504)
		(size 0.508)
		(drill 0.254)
		(layers "F.Cu" "B.Cu")
		(net "SW_P12V_AUX_PVDDIO_P1_FLT")
	)
	(via
		(at 40.591994 -349.523558)
		(size 0.508)
		(drill 0.254)
		(layers "F.Cu" "B.Cu")
		(net "SW_P12V_AUX_PVDDIO_P1_FLT")
	)
	(via
		(at 32.311594 -350.260158)
		(size 0.508)
		(drill 0.254)
		(layers "F.Cu" "B.Cu")
		(net "SW_P12V_AUX_PVDDIO_P1_FLT")
	)
	(via
		(at 47.92853 -356.822502)
		(size 0.508)
		(drill 0.254)
		(layers "F.Cu" "B.Cu")
		(net "SW_P12V_AUX_PVDDIO_P1_FLT")
	)
	(via
		(at 48.338994 -349.142558)
		(size 0.508)
		(drill 0.254)
		(layers "F.Cu" "B.Cu")
		(net "SW_P12V_AUX_PVDDIO_P1_FLT")
	)
	(via
		(at 47.880778 -358.108504)
		(size 0.508)
		(drill 0.254)
		(layers "F.Cu" "B.Cu")
		(net "SW_P12V_AUX_PVDDIO_P1_FLT")
	)
	(via
		(at 57.254394 -350.260158)
		(size 0.508)
		(drill 0.254)
		(layers "F.Cu" "B.Cu")
		(net "SW_P12V_AUX_PVDDIO_P1_FLT")
	)
	(via
		(at 41.427146 -359.2576)
		(size 0.508)
		(drill 0.254)
		(layers "F.Cu" "B.Cu")
		(net "SW_P12V_AUX_PVDDIO_P1_FLT")
	)
	(via
		(at 40.058594 -349.904558)
		(size 0.508)
		(drill 0.254)
		(layers "F.Cu" "B.Cu")
		(net "SW_P12V_AUX_PVDDIO_P1_FLT")
	)
	(via
		(at 41.417494 -357.898192)
		(size 0.508)
		(drill 0.254)
		(layers "F.Cu" "B.Cu")
		(net "SW_P12V_AUX_PVDDIO_P1_FLT")
	)
	(via
		(at 29.908754 -348.709488)
		(size 0.49022)
		(drill 0.254)
		(layers "F.Cu" "B.Cu")
		(net "SW_P12V_AUX_PVDDIO_P1_FLT")
	)
	(via
		(at 48.897794 -348.786958)
		(size 0.508)
		(drill 0.254)
		(layers "F.Cu" "B.Cu")
		(net "SW_P12V_AUX_PVDDIO_P1_FLT")
	)
	(via
		(at 47.366174 -347.280738)
		(size 0.508)
		(drill 0.254)
		(layers "F.Cu" "B.Cu")
		(net "SW_P12V_AUX_PVDDIO_P1_FLT")
	)
	(via
		(at 49.40173 -356.822502)
		(size 0.508)
		(drill 0.254)
		(layers "F.Cu" "B.Cu")
		(net "SW_P12V_AUX_PVDDIO_P1_FLT")
	)
	(via
		(at 47.366174 -348.017338)
		(size 0.508)
		(drill 0.254)
		(layers "F.Cu" "B.Cu")
		(net "SW_P12V_AUX_PVDDIO_P1_FLT")
	)
	(via
		(at 303.517046 -349.137732)
		(size 0.508)
		(drill 0.254)
		(layers "F.Cu" "B.Cu")
		(net "SW_P12V_AUX_PVDDIO_P0_FLT")
	)
	(via
		(at 284.393386 -348.704662)
		(size 0.49022)
		(drill 0.254)
		(layers "F.Cu" "B.Cu")
		(net "SW_P12V_AUX_PVDDIO_P0_FLT")
	)
	(via
		(at 294.635682 -350.313752)
		(size 0.508)
		(drill 0.254)
		(layers "F.Cu" "B.Cu")
		(net "SW_P12V_AUX_PVDDIO_P0_FLT")
	)
	(via
		(at 277.593806 -348.025212)
		(size 0.508)
		(drill 0.254)
		(layers "F.Cu" "B.Cu")
		(net "SW_P12V_AUX_PVDDIO_P0_FLT")
	)
	(via
		(at 287.413446 -349.518732)
		(size 0.508)
		(drill 0.254)
		(layers "F.Cu" "B.Cu")
		(net "SW_P12V_AUX_PVDDIO_P0_FLT")
	)
	(via
		(at 278.574246 -349.137732)
		(size 0.508)
		(drill 0.254)
		(layers "F.Cu" "B.Cu")
		(net "SW_P12V_AUX_PVDDIO_P0_FLT")
	)
	(via
		(at 287.413446 -348.782132)
		(size 0.508)
		(drill 0.254)
		(layers "F.Cu" "B.Cu")
		(net "SW_P12V_AUX_PVDDIO_P0_FLT")
	)
	(via
		(at 286.854646 -349.137732)
		(size 0.508)
		(drill 0.254)
		(layers "F.Cu" "B.Cu")
		(net "SW_P12V_AUX_PVDDIO_P0_FLT")
	)
	(via
		(at 285.010606 -348.704662)
		(size 0.49022)
		(drill 0.254)
		(layers "F.Cu" "B.Cu")
		(net "SW_P12V_AUX_PVDDIO_P0_FLT")
	)
	(via
		(at 279.133046 -348.782132)
		(size 0.508)
		(drill 0.254)
		(layers "F.Cu" "B.Cu")
		(net "SW_P12V_AUX_PVDDIO_P0_FLT")
	)
	(via
		(at 286.329882 -349.577152)
		(size 0.508)
		(drill 0.254)
		(layers "F.Cu" "B.Cu")
		(net "SW_P12V_AUX_PVDDIO_P0_FLT")
	)
	(via
		(at 287.00095 -355.279198)
		(size 0.508)
		(drill 0.254)
		(layers "F.Cu" "B.Cu")
		(net "SW_P12V_AUX_PVDDIO_P0_FLT")
	)
	(via
		(at 286.36595 -355.279198)
		(size 0.508)
		(drill 0.254)
		(layers "F.Cu" "B.Cu")
		(net "SW_P12V_AUX_PVDDIO_P0_FLT")
	)
	(via
		(at 278.049482 -350.313752)
		(size 0.508)
		(drill 0.254)
		(layers "F.Cu" "B.Cu")
		(net "SW_P12V_AUX_PVDDIO_P0_FLT")
	)
	(via
		(at 301.055786 -348.704662)
		(size 0.49022)
		(drill 0.254)
		(layers "F.Cu" "B.Cu")
		(net "SW_P12V_AUX_PVDDIO_P0_FLT")
	)
	(via
		(at 304.075846 -348.782132)
		(size 0.508)
		(drill 0.254)
		(layers "F.Cu" "B.Cu")
		(net "SW_P12V_AUX_PVDDIO_P0_FLT")
	)
	(via
		(at 304.075846 -350.255332)
		(size 0.508)
		(drill 0.254)
		(layers "F.Cu" "B.Cu")
		(net "SW_P12V_AUX_PVDDIO_P0_FLT")
	)
	(via
		(at 286.37611 -356.584758)
		(size 0.508)
		(drill 0.254)
		(layers "F.Cu" "B.Cu")
		(net "SW_P12V_AUX_PVDDIO_P0_FLT")
	)
	(via
		(at 286.329882 -350.313752)
		(size 0.508)
		(drill 0.254)
		(layers "F.Cu" "B.Cu")
		(net "SW_P12V_AUX_PVDDIO_P0_FLT")
	)
	(via
		(at 301.673006 -348.704662)
		(size 0.49022)
		(drill 0.254)
		(layers "F.Cu" "B.Cu")
		(net "SW_P12V_AUX_PVDDIO_P0_FLT")
	)
	(via
		(at 278.599646 -349.899732)
		(size 0.508)
		(drill 0.254)
		(layers "F.Cu" "B.Cu")
		(net "SW_P12V_AUX_PVDDIO_P0_FLT")
	)
	(via
		(at 302.290226 -348.704662)
		(size 0.49022)
		(drill 0.254)
		(layers "F.Cu" "B.Cu")
		(net "SW_P12V_AUX_PVDDIO_P0_FLT")
	)
	(via
		(at 294.635682 -349.577152)
		(size 0.508)
		(drill 0.254)
		(layers "F.Cu" "B.Cu")
		(net "SW_P12V_AUX_PVDDIO_P0_FLT")
	)
	(via
		(at 288.27095 -355.279198)
		(size 0.508)
		(drill 0.254)
		(layers "F.Cu" "B.Cu")
		(net "SW_P12V_AUX_PVDDIO_P0_FLT")
	)
	(via
		(at 279.133046 -350.255332)
		(size 0.508)
		(drill 0.254)
		(layers "F.Cu" "B.Cu")
		(net "SW_P12V_AUX_PVDDIO_P0_FLT")
	)
	(via
		(at 302.526446 -347.265752)
		(size 0.508)
		(drill 0.254)
		(layers "F.Cu" "B.Cu")
		(net "SW_P12V_AUX_PVDDIO_P0_FLT")
	)
	(via
		(at 288.28111 -355.949758)
		(size 0.508)
		(drill 0.254)
		(layers "F.Cu" "B.Cu")
		(net "SW_P12V_AUX_PVDDIO_P0_FLT")
	)
	(via
		(at 285.627826 -348.704662)
		(size 0.49022)
		(drill 0.254)
		(layers "F.Cu" "B.Cu")
		(net "SW_P12V_AUX_PVDDIO_P0_FLT")
	)
	(via
		(at 278.049482 -349.577152)
		(size 0.508)
		(drill 0.254)
		(layers "F.Cu" "B.Cu")
		(net "SW_P12V_AUX_PVDDIO_P0_FLT")
	)
	(via
		(at 288.91611 -356.584758)
		(size 0.508)
		(drill 0.254)
		(layers "F.Cu" "B.Cu")
		(net "SW_P12V_AUX_PVDDIO_P0_FLT")
	)
	(via
		(at 285.869126 -347.982032)
		(size 0.508)
		(drill 0.254)
		(layers "F.Cu" "B.Cu")
		(net "SW_P12V_AUX_PVDDIO_P0_FLT")
	)
	(via
		(at 293.316406 -348.704662)
		(size 0.49022)
		(drill 0.254)
		(layers "F.Cu" "B.Cu")
		(net "SW_P12V_AUX_PVDDIO_P0_FLT")
	)
	(via
		(at 287.413446 -350.255332)
		(size 0.508)
		(drill 0.254)
		(layers "F.Cu" "B.Cu")
		(net "SW_P12V_AUX_PVDDIO_P0_FLT")
	)
	(via
		(at 276.730206 -348.704662)
		(size 0.49022)
		(drill 0.254)
		(layers "F.Cu" "B.Cu")
		(net "SW_P12V_AUX_PVDDIO_P0_FLT")
	)
	(via
		(at 288.90595 -355.279198)
		(size 0.508)
		(drill 0.254)
		(layers "F.Cu" "B.Cu")
		(net "SW_P12V_AUX_PVDDIO_P0_FLT")
	)
	(via
		(at 295.719246 -350.255332)
		(size 0.508)
		(drill 0.254)
		(layers "F.Cu" "B.Cu")
		(net "SW_P12V_AUX_PVDDIO_P0_FLT")
	)
	(via
		(at 302.526446 -348.002352)
		(size 0.508)
		(drill 0.254)
		(layers "F.Cu" "B.Cu")
		(net "SW_P12V_AUX_PVDDIO_P0_FLT")
	)
	(via
		(at 293.933626 -348.704662)
		(size 0.49022)
		(drill 0.254)
		(layers "F.Cu" "B.Cu")
		(net "SW_P12V_AUX_PVDDIO_P0_FLT")
	)
	(via
		(at 294.146986 -347.959172)
		(size 0.508)
		(drill 0.254)
		(layers "F.Cu" "B.Cu")
		(net "SW_P12V_AUX_PVDDIO_P0_FLT")
	)
	(via
		(at 276.112986 -348.704662)
		(size 0.49022)
		(drill 0.254)
		(layers "F.Cu" "B.Cu")
		(net "SW_P12V_AUX_PVDDIO_P0_FLT")
	)
	(via
		(at 295.719246 -348.782132)
		(size 0.508)
		(drill 0.254)
		(layers "F.Cu" "B.Cu")
		(net "SW_P12V_AUX_PVDDIO_P0_FLT")
	)
	(via
		(at 277.347426 -348.704662)
		(size 0.49022)
		(drill 0.254)
		(layers "F.Cu" "B.Cu")
		(net "SW_P12V_AUX_PVDDIO_P0_FLT")
	)
	(via
		(at 285.869126 -347.245432)
		(size 0.508)
		(drill 0.254)
		(layers "F.Cu" "B.Cu")
		(net "SW_P12V_AUX_PVDDIO_P0_FLT")
	)
	(via
		(at 302.992282 -350.313752)
		(size 0.508)
		(drill 0.254)
		(layers "F.Cu" "B.Cu")
		(net "SW_P12V_AUX_PVDDIO_P0_FLT")
	)
	(via
		(at 303.542446 -349.899732)
		(size 0.508)
		(drill 0.254)
		(layers "F.Cu" "B.Cu")
		(net "SW_P12V_AUX_PVDDIO_P0_FLT")
	)
	(via
		(at 304.075846 -349.518732)
		(size 0.508)
		(drill 0.254)
		(layers "F.Cu" "B.Cu")
		(net "SW_P12V_AUX_PVDDIO_P0_FLT")
	)
	(via
		(at 292.699186 -348.704662)
		(size 0.49022)
		(drill 0.254)
		(layers "F.Cu" "B.Cu")
		(net "SW_P12V_AUX_PVDDIO_P0_FLT")
	)
	(via
		(at 302.992282 -349.577152)
		(size 0.508)
		(drill 0.254)
		(layers "F.Cu" "B.Cu")
		(net "SW_P12V_AUX_PVDDIO_P0_FLT")
	)
	(via
		(at 287.01111 -355.949758)
		(size 0.508)
		(drill 0.254)
		(layers "F.Cu" "B.Cu")
		(net "SW_P12V_AUX_PVDDIO_P0_FLT")
	)
	(via
		(at 286.37611 -355.949758)
		(size 0.508)
		(drill 0.254)
		(layers "F.Cu" "B.Cu")
		(net "SW_P12V_AUX_PVDDIO_P0_FLT")
	)
	(via
		(at 287.64611 -355.949758)
		(size 0.508)
		(drill 0.254)
		(layers "F.Cu" "B.Cu")
		(net "SW_P12V_AUX_PVDDIO_P0_FLT")
	)
	(via
		(at 295.719246 -349.518732)
		(size 0.508)
		(drill 0.254)
		(layers "F.Cu" "B.Cu")
		(net "SW_P12V_AUX_PVDDIO_P0_FLT")
	)
	(via
		(at 279.133046 -349.518732)
		(size 0.508)
		(drill 0.254)
		(layers "F.Cu" "B.Cu")
		(net "SW_P12V_AUX_PVDDIO_P0_FLT")
	)
	(via
		(at 277.593806 -347.288612)
		(size 0.508)
		(drill 0.254)
		(layers "F.Cu" "B.Cu")
		(net "SW_P12V_AUX_PVDDIO_P0_FLT")
	)
	(via
		(at 286.880046 -349.899732)
		(size 0.508)
		(drill 0.254)
		(layers "F.Cu" "B.Cu")
		(net "SW_P12V_AUX_PVDDIO_P0_FLT")
	)
	(via
		(at 287.01111 -356.584758)
		(size 0.508)
		(drill 0.254)
		(layers "F.Cu" "B.Cu")
		(net "SW_P12V_AUX_PVDDIO_P0_FLT")
	)
	(via
		(at 288.91611 -355.949758)
		(size 0.508)
		(drill 0.254)
		(layers "F.Cu" "B.Cu")
		(net "SW_P12V_AUX_PVDDIO_P0_FLT")
	)
	(via
		(at 295.185846 -349.899732)
		(size 0.508)
		(drill 0.254)
		(layers "F.Cu" "B.Cu")
		(net "SW_P12V_AUX_PVDDIO_P0_FLT")
	)
	(via
		(at 294.146986 -347.222572)
		(size 0.508)
		(drill 0.254)
		(layers "F.Cu" "B.Cu")
		(net "SW_P12V_AUX_PVDDIO_P0_FLT")
	)
	(via
		(at 287.64611 -356.584758)
		(size 0.508)
		(drill 0.254)
		(layers "F.Cu" "B.Cu")
		(net "SW_P12V_AUX_PVDDIO_P0_FLT")
	)
	(via
		(at 288.28111 -356.584758)
		(size 0.508)
		(drill 0.254)
		(layers "F.Cu" "B.Cu")
		(net "SW_P12V_AUX_PVDDIO_P0_FLT")
	)
	(via
		(at 295.160446 -349.137732)
		(size 0.508)
		(drill 0.254)
		(layers "F.Cu" "B.Cu")
		(net "SW_P12V_AUX_PVDDIO_P0_FLT")
	)
	(via
		(at 287.63595 -355.279198)
		(size 0.508)
		(drill 0.254)
		(layers "F.Cu" "B.Cu")
		(net "SW_P12V_AUX_PVDDIO_P0_FLT")
	)
	(via
		(at 118.829074 -152.657556)
		(size 0.508)
		(drill 0.254)
		(layers "F.Cu" "B.Cu")
		(net "SW_P12V_AUX_PVDDCR_SOC_P1_FLT")
	)
	(via
		(at 116.258594 -152.022556)
		(size 0.508)
		(drill 0.254)
		(layers "F.Cu" "B.Cu")
		(net "SW_P12V_AUX_PVDDCR_SOC_P1_FLT")
	)
	(via
		(at 114.37747 -169.935144)
		(size 0.49022)
		(drill 0.254)
		(layers "F.Cu" "B.Cu")
		(net "SW_P12V_AUX_PVDDCR_SOC_P1_FLT")
	)
	(via
		(at 129.27203 -154.109674)
		(size 0.508)
		(drill 0.254)
		(layers "F.Cu" "B.Cu")
		(net "SW_P12V_AUX_PVDDCR_SOC_P1_FLT")
	)
	(via
		(at 128.71323 -152.992074)
		(size 0.508)
		(drill 0.254)
		(layers "F.Cu" "B.Cu")
		(net "SW_P12V_AUX_PVDDCR_SOC_P1_FLT")
	)
	(via
		(at 128.71323 -153.728674)
		(size 0.508)
		(drill 0.254)
		(layers "F.Cu" "B.Cu")
		(net "SW_P12V_AUX_PVDDCR_SOC_P1_FLT")
	)
	(via
		(at 130.49885 -154.542744)
		(size 0.49022)
		(drill 0.254)
		(layers "F.Cu" "B.Cu")
		(net "SW_P12V_AUX_PVDDCR_SOC_P1_FLT")
	)
	(via
		(at 111.97463 -169.121074)
		(size 0.508)
		(drill 0.254)
		(layers "F.Cu" "B.Cu")
		(net "SW_P12V_AUX_PVDDCR_SOC_P1_FLT")
	)
	(via
		(at 113.058194 -169.062654)
		(size 0.508)
		(drill 0.254)
		(layers "F.Cu" "B.Cu")
		(net "SW_P12V_AUX_PVDDCR_SOC_P1_FLT")
	)
	(via
		(at 119.464074 -152.657556)
		(size 0.508)
		(drill 0.254)
		(layers "F.Cu" "B.Cu")
		(net "SW_P12V_AUX_PVDDCR_SOC_P1_FLT")
	)
	(via
		(at 116.893594 -152.022556)
		(size 0.508)
		(drill 0.254)
		(layers "F.Cu" "B.Cu")
		(net "SW_P12V_AUX_PVDDCR_SOC_P1_FLT")
	)
	(via
		(at 121.338594 -161.595054)
		(size 0.508)
		(drill 0.254)
		(layers "F.Cu" "B.Cu")
		(net "SW_P12V_AUX_PVDDCR_SOC_P1_FLT")
	)
	(via
		(at 111.97463 -169.857674)
		(size 0.508)
		(drill 0.254)
		(layers "F.Cu" "B.Cu")
		(net "SW_P12V_AUX_PVDDCR_SOC_P1_FLT")
	)
	(via
		(at 114.99469 -169.935144)
		(size 0.49022)
		(drill 0.254)
		(layers "F.Cu" "B.Cu")
		(net "SW_P12V_AUX_PVDDCR_SOC_P1_FLT")
	)
	(via
		(at 121.872248 -163.89096)
		(size 0.508)
		(drill 0.254)
		(layers "F.Cu" "B.Cu")
		(net "SW_P12V_AUX_PVDDCR_SOC_P1_FLT")
	)
	(via
		(at 120.25503 -162.390074)
		(size 0.508)
		(drill 0.254)
		(layers "F.Cu" "B.Cu")
		(net "SW_P12V_AUX_PVDDCR_SOC_P1_FLT")
	)
	(via
		(at 121.872248 -164.62756)
		(size 0.508)
		(drill 0.254)
		(layers "F.Cu" "B.Cu")
		(net "SW_P12V_AUX_PVDDCR_SOC_P1_FLT")
	)
	(via
		(at 120.81383 -162.771074)
		(size 0.508)
		(drill 0.254)
		(layers "F.Cu" "B.Cu")
		(net "SW_P12V_AUX_PVDDCR_SOC_P1_FLT")
	)
	(via
		(at 130.305048 -155.94076)
		(size 0.508)
		(drill 0.254)
		(layers "F.Cu" "B.Cu")
		(net "SW_P12V_AUX_PVDDCR_SOC_P1_FLT")
	)
	(via
		(at 113.591848 -171.33316)
		(size 0.508)
		(drill 0.254)
		(layers "F.Cu" "B.Cu")
		(net "SW_P12V_AUX_PVDDCR_SOC_P1_FLT")
	)
	(via
		(at 116.258594 -152.657556)
		(size 0.508)
		(drill 0.254)
		(layers "F.Cu" "B.Cu")
		(net "SW_P12V_AUX_PVDDCR_SOC_P1_FLT")
	)
	(via
		(at 129.796794 -153.670254)
		(size 0.508)
		(drill 0.254)
		(layers "F.Cu" "B.Cu")
		(net "SW_P12V_AUX_PVDDCR_SOC_P1_FLT")
	)
	(via
		(at 118.829074 -152.022556)
		(size 0.508)
		(drill 0.254)
		(layers "F.Cu" "B.Cu")
		(net "SW_P12V_AUX_PVDDCR_SOC_P1_FLT")
	)
	(via
		(at 131.11607 -154.542744)
		(size 0.49022)
		(drill 0.254)
		(layers "F.Cu" "B.Cu")
		(net "SW_P12V_AUX_PVDDCR_SOC_P1_FLT")
	)
	(via
		(at 129.24663 -153.347674)
		(size 0.508)
		(drill 0.254)
		(layers "F.Cu" "B.Cu")
		(net "SW_P12V_AUX_PVDDCR_SOC_P1_FLT")
	)
	(via
		(at 123.27509 -163.204144)
		(size 0.49022)
		(drill 0.254)
		(layers "F.Cu" "B.Cu")
		(net "SW_P12V_AUX_PVDDCR_SOC_P1_FLT")
	)
	(via
		(at 111.97463 -168.384474)
		(size 0.508)
		(drill 0.254)
		(layers "F.Cu" "B.Cu")
		(net "SW_P12V_AUX_PVDDCR_SOC_P1_FLT")
	)
	(via
		(at 118.194074 -152.022556)
		(size 0.508)
		(drill 0.254)
		(layers "F.Cu" "B.Cu")
		(net "SW_P12V_AUX_PVDDCR_SOC_P1_FLT")
	)
	(via
		(at 120.25503 -161.653474)
		(size 0.508)
		(drill 0.254)
		(layers "F.Cu" "B.Cu")
		(net "SW_P12V_AUX_PVDDCR_SOC_P1_FLT")
	)
	(via
		(at 116.893594 -152.657556)
		(size 0.508)
		(drill 0.254)
		(layers "F.Cu" "B.Cu")
		(net "SW_P12V_AUX_PVDDCR_SOC_P1_FLT")
	)
	(via
		(at 117.559074 -152.657556)
		(size 0.508)
		(drill 0.254)
		(layers "F.Cu" "B.Cu")
		(net "SW_P12V_AUX_PVDDCR_SOC_P1_FLT")
	)
	(via
		(at 117.559074 -152.022556)
		(size 0.508)
		(drill 0.254)
		(layers "F.Cu" "B.Cu")
		(net "SW_P12V_AUX_PVDDCR_SOC_P1_FLT")
	)
	(via
		(at 113.76025 -169.935144)
		(size 0.49022)
		(drill 0.254)
		(layers "F.Cu" "B.Cu")
		(net "SW_P12V_AUX_PVDDCR_SOC_P1_FLT")
	)
	(via
		(at 129.796794 -152.933654)
		(size 0.508)
		(drill 0.254)
		(layers "F.Cu" "B.Cu")
		(net "SW_P12V_AUX_PVDDCR_SOC_P1_FLT")
	)
	(via
		(at 120.25503 -163.126674)
		(size 0.508)
		(drill 0.254)
		(layers "F.Cu" "B.Cu")
		(net "SW_P12V_AUX_PVDDCR_SOC_P1_FLT")
	)
	(via
		(at 122.65787 -163.204144)
		(size 0.49022)
		(drill 0.254)
		(layers "F.Cu" "B.Cu")
		(net "SW_P12V_AUX_PVDDCR_SOC_P1_FLT")
	)
	(via
		(at 112.53343 -169.502074)
		(size 0.508)
		(drill 0.254)
		(layers "F.Cu" "B.Cu")
		(net "SW_P12V_AUX_PVDDCR_SOC_P1_FLT")
	)
	(via
		(at 119.464074 -152.022556)
		(size 0.508)
		(drill 0.254)
		(layers "F.Cu" "B.Cu")
		(net "SW_P12V_AUX_PVDDCR_SOC_P1_FLT")
	)
	(via
		(at 112.50803 -168.740074)
		(size 0.508)
		(drill 0.254)
		(layers "F.Cu" "B.Cu")
		(net "SW_P12V_AUX_PVDDCR_SOC_P1_FLT")
	)
	(via
		(at 120.78843 -162.009074)
		(size 0.508)
		(drill 0.254)
		(layers "F.Cu" "B.Cu")
		(net "SW_P12V_AUX_PVDDCR_SOC_P1_FLT")
	)
	(via
		(at 131.73329 -154.542744)
		(size 0.49022)
		(drill 0.254)
		(layers "F.Cu" "B.Cu")
		(net "SW_P12V_AUX_PVDDCR_SOC_P1_FLT")
	)
	(via
		(at 113.058194 -168.326054)
		(size 0.508)
		(drill 0.254)
		(layers "F.Cu" "B.Cu")
		(net "SW_P12V_AUX_PVDDCR_SOC_P1_FLT")
	)
	(via
		(at 113.591848 -170.59656)
		(size 0.508)
		(drill 0.254)
		(layers "F.Cu" "B.Cu")
		(net "SW_P12V_AUX_PVDDCR_SOC_P1_FLT")
	)
	(via
		(at 128.71323 -154.465274)
		(size 0.508)
		(drill 0.254)
		(layers "F.Cu" "B.Cu")
		(net "SW_P12V_AUX_PVDDCR_SOC_P1_FLT")
	)
	(via
		(at 122.04065 -163.204144)
		(size 0.49022)
		(drill 0.254)
		(layers "F.Cu" "B.Cu")
		(net "SW_P12V_AUX_PVDDCR_SOC_P1_FLT")
	)
	(via
		(at 130.305048 -155.20416)
		(size 0.508)
		(drill 0.254)
		(layers "F.Cu" "B.Cu")
		(net "SW_P12V_AUX_PVDDCR_SOC_P1_FLT")
	)
	(via
		(at 121.338594 -162.331654)
		(size 0.508)
		(drill 0.254)
		(layers "F.Cu" "B.Cu")
		(net "SW_P12V_AUX_PVDDCR_SOC_P1_FLT")
	)
	(via
		(at 118.194074 -152.657556)
		(size 0.508)
		(drill 0.254)
		(layers "F.Cu" "B.Cu")
		(net "SW_P12V_AUX_PVDDCR_SOC_P1_FLT")
	)
	(via
		(at 403.520402 -164.996368)
		(size 0.508)
		(drill 0.254)
		(layers "F.Cu" "B.Cu")
		(net "SW_P12V_AUX_PVDDCR_SOC_P0_FLT")
	)
	(via
		(at 395.196822 -173.573694)
		(size 0.508)
		(drill 0.254)
		(layers "F.Cu" "B.Cu")
		(net "SW_P12V_AUX_PVDDCR_SOC_P0_FLT")
	)
	(via
		(at 402.436838 -165.054788)
		(size 0.508)
		(drill 0.254)
		(layers "F.Cu" "B.Cu")
		(net "SW_P12V_AUX_PVDDCR_SOC_P0_FLT")
	)
	(via
		(at 387.928358 -154.428952)
		(size 0.508)
		(drill 0.254)
		(layers "F.Cu" "B.Cu")
		(net "SW_P12V_AUX_PVDDCR_SOC_P0_FLT")
	)
	(via
		(at 397.133318 -175.182784)
		(size 0.49022)
		(drill 0.254)
		(layers "F.Cu" "B.Cu")
		(net "SW_P12V_AUX_PVDDCR_SOC_P0_FLT")
	)
	(via
		(at 413.221678 -161.779458)
		(size 0.49022)
		(drill 0.254)
		(layers "F.Cu" "B.Cu")
		(net "SW_P12V_AUX_PVDDCR_SOC_P0_FLT")
	)
	(via
		(at 396.516098 -175.182784)
		(size 0.49022)
		(drill 0.254)
		(layers "F.Cu" "B.Cu")
		(net "SW_P12V_AUX_PVDDCR_SOC_P0_FLT")
	)
	(via
		(at 404.839678 -166.605458)
		(size 0.49022)
		(drill 0.254)
		(layers "F.Cu" "B.Cu")
		(net "SW_P12V_AUX_PVDDCR_SOC_P0_FLT")
	)
	(via
		(at 411.902402 -160.170368)
		(size 0.508)
		(drill 0.254)
		(layers "F.Cu" "B.Cu")
		(net "SW_P12V_AUX_PVDDCR_SOC_P0_FLT")
	)
	(via
		(at 412.486856 -162.494214)
		(size 0.508)
		(drill 0.254)
		(layers "F.Cu" "B.Cu")
		(net "SW_P12V_AUX_PVDDCR_SOC_P0_FLT")
	)
	(via
		(at 395.196822 -174.310294)
		(size 0.508)
		(drill 0.254)
		(layers "F.Cu" "B.Cu")
		(net "SW_P12V_AUX_PVDDCR_SOC_P0_FLT")
	)
	(via
		(at 410.818838 -160.228788)
		(size 0.508)
		(drill 0.254)
		(layers "F.Cu" "B.Cu")
		(net "SW_P12V_AUX_PVDDCR_SOC_P0_FLT")
	)
	(via
		(at 395.898878 -175.182784)
		(size 0.49022)
		(drill 0.254)
		(layers "F.Cu" "B.Cu")
		(net "SW_P12V_AUX_PVDDCR_SOC_P0_FLT")
	)
	(via
		(at 387.293358 -154.428952)
		(size 0.508)
		(drill 0.254)
		(layers "F.Cu" "B.Cu")
		(net "SW_P12V_AUX_PVDDCR_SOC_P0_FLT")
	)
	(via
		(at 387.928358 -155.724352)
		(size 0.508)
		(drill 0.254)
		(layers "F.Cu" "B.Cu")
		(net "SW_P12V_AUX_PVDDCR_SOC_P0_FLT")
	)
	(via
		(at 412.486856 -163.256214)
		(size 0.508)
		(drill 0.254)
		(layers "F.Cu" "B.Cu")
		(net "SW_P12V_AUX_PVDDCR_SOC_P0_FLT")
	)
	(via
		(at 387.928358 -155.089352)
		(size 0.508)
		(drill 0.254)
		(layers "F.Cu" "B.Cu")
		(net "SW_P12V_AUX_PVDDCR_SOC_P0_FLT")
	)
	(via
		(at 410.818838 -161.701988)
		(size 0.508)
		(drill 0.254)
		(layers "F.Cu" "B.Cu")
		(net "SW_P12V_AUX_PVDDCR_SOC_P0_FLT")
	)
	(via
		(at 405.456898 -166.605458)
		(size 0.49022)
		(drill 0.254)
		(layers "F.Cu" "B.Cu")
		(net "SW_P12V_AUX_PVDDCR_SOC_P0_FLT")
	)
	(via
		(at 404.104856 -167.320214)
		(size 0.508)
		(drill 0.254)
		(layers "F.Cu" "B.Cu")
		(net "SW_P12V_AUX_PVDDCR_SOC_P0_FLT")
	)
	(via
		(at 387.928358 -157.001972)
		(size 0.508)
		(drill 0.254)
		(layers "F.Cu" "B.Cu")
		(net "SW_P12V_AUX_PVDDCR_SOC_P0_FLT")
	)
	(via
		(at 411.352238 -160.584388)
		(size 0.508)
		(drill 0.254)
		(layers "F.Cu" "B.Cu")
		(net "SW_P12V_AUX_PVDDCR_SOC_P0_FLT")
	)
	(via
		(at 395.230858 -172.819314)
		(size 0.508)
		(drill 0.254)
		(layers "F.Cu" "B.Cu")
		(net "SW_P12V_AUX_PVDDCR_SOC_P0_FLT")
	)
	(via
		(at 394.628878 -173.21911)
		(size 0.508)
		(drill 0.254)
		(layers "F.Cu" "B.Cu")
		(net "SW_P12V_AUX_PVDDCR_SOC_P0_FLT")
	)
	(via
		(at 394.672058 -174.749714)
		(size 0.508)
		(drill 0.254)
		(layers "F.Cu" "B.Cu")
		(net "SW_P12V_AUX_PVDDCR_SOC_P0_FLT")
	)
	(via
		(at 387.293358 -155.089352)
		(size 0.508)
		(drill 0.254)
		(layers "F.Cu" "B.Cu")
		(net "SW_P12V_AUX_PVDDCR_SOC_P0_FLT")
	)
	(via
		(at 395.781276 -175.895254)
		(size 0.508)
		(drill 0.254)
		(layers "F.Cu" "B.Cu")
		(net "SW_P12V_AUX_PVDDCR_SOC_P0_FLT")
	)
	(via
		(at 387.928358 -156.366972)
		(size 0.508)
		(drill 0.254)
		(layers "F.Cu" "B.Cu")
		(net "SW_P12V_AUX_PVDDCR_SOC_P0_FLT")
	)
	(via
		(at 403.520402 -165.732968)
		(size 0.508)
		(drill 0.254)
		(layers "F.Cu" "B.Cu")
		(net "SW_P12V_AUX_PVDDCR_SOC_P0_FLT")
	)
	(via
		(at 404.104856 -168.082214)
		(size 0.508)
		(drill 0.254)
		(layers "F.Cu" "B.Cu")
		(net "SW_P12V_AUX_PVDDCR_SOC_P0_FLT")
	)
	(via
		(at 387.293358 -153.793952)
		(size 0.508)
		(drill 0.254)
		(layers "F.Cu" "B.Cu")
		(net "SW_P12V_AUX_PVDDCR_SOC_P0_FLT")
	)
	(via
		(at 387.293358 -155.724352)
		(size 0.508)
		(drill 0.254)
		(layers "F.Cu" "B.Cu")
		(net "SW_P12V_AUX_PVDDCR_SOC_P0_FLT")
	)
	(via
		(at 395.781276 -176.657254)
		(size 0.508)
		(drill 0.254)
		(layers "F.Cu" "B.Cu")
		(net "SW_P12V_AUX_PVDDCR_SOC_P0_FLT")
	)
	(via
		(at 413.838898 -161.779458)
		(size 0.49022)
		(drill 0.254)
		(layers "F.Cu" "B.Cu")
		(net "SW_P12V_AUX_PVDDCR_SOC_P0_FLT")
	)
	(via
		(at 411.377638 -161.346388)
		(size 0.508)
		(drill 0.254)
		(layers "F.Cu" "B.Cu")
		(net "SW_P12V_AUX_PVDDCR_SOC_P0_FLT")
	)
	(via
		(at 411.902402 -160.906968)
		(size 0.508)
		(drill 0.254)
		(layers "F.Cu" "B.Cu")
		(net "SW_P12V_AUX_PVDDCR_SOC_P0_FLT")
	)
	(via
		(at 402.995638 -166.172388)
		(size 0.508)
		(drill 0.254)
		(layers "F.Cu" "B.Cu")
		(net "SW_P12V_AUX_PVDDCR_SOC_P0_FLT")
	)
	(via
		(at 387.293358 -156.366972)
		(size 0.508)
		(drill 0.254)
		(layers "F.Cu" "B.Cu")
		(net "SW_P12V_AUX_PVDDCR_SOC_P0_FLT")
	)
	(via
		(at 387.928358 -153.793952)
		(size 0.508)
		(drill 0.254)
		(layers "F.Cu" "B.Cu")
		(net "SW_P12V_AUX_PVDDCR_SOC_P0_FLT")
	)
	(via
		(at 410.818838 -160.965388)
		(size 0.508)
		(drill 0.254)
		(layers "F.Cu" "B.Cu")
		(net "SW_P12V_AUX_PVDDCR_SOC_P0_FLT")
	)
	(via
		(at 394.646658 -173.987714)
		(size 0.508)
		(drill 0.254)
		(layers "F.Cu" "B.Cu")
		(net "SW_P12V_AUX_PVDDCR_SOC_P0_FLT")
	)
	(via
		(at 402.436838 -165.791388)
		(size 0.508)
		(drill 0.254)
		(layers "F.Cu" "B.Cu")
		(net "SW_P12V_AUX_PVDDCR_SOC_P0_FLT")
	)
	(via
		(at 412.604458 -161.779458)
		(size 0.49022)
		(drill 0.254)
		(layers "F.Cu" "B.Cu")
		(net "SW_P12V_AUX_PVDDCR_SOC_P0_FLT")
	)
	(via
		(at 394.628878 -172.45711)
		(size 0.508)
		(drill 0.254)
		(layers "F.Cu" "B.Cu")
		(net "SW_P12V_AUX_PVDDCR_SOC_P0_FLT")
	)
	(via
		(at 402.436838 -166.527988)
		(size 0.508)
		(drill 0.254)
		(layers "F.Cu" "B.Cu")
		(net "SW_P12V_AUX_PVDDCR_SOC_P0_FLT")
	)
	(via
		(at 387.293358 -157.001972)
		(size 0.508)
		(drill 0.254)
		(layers "F.Cu" "B.Cu")
		(net "SW_P12V_AUX_PVDDCR_SOC_P0_FLT")
	)
	(via
		(at 402.970238 -165.410388)
		(size 0.508)
		(drill 0.254)
		(layers "F.Cu" "B.Cu")
		(net "SW_P12V_AUX_PVDDCR_SOC_P0_FLT")
	)
	(via
		(at 404.222458 -166.605458)
		(size 0.49022)
		(drill 0.254)
		(layers "F.Cu" "B.Cu")
		(net "SW_P12V_AUX_PVDDCR_SOC_P0_FLT")
	)
	(via
		(at 73.561194 -337.421474)
		(size 0.508)
		(drill 0.254)
		(layers "F.Cu" "B.Cu")
		(net "SW_P12V_AUX_PVDDCR_CPU1_P1_FLT")
	)
	(via
		(at 96.144334 -337.017614)
		(size 0.49022)
		(drill 0.254)
		(layers "F.Cu" "B.Cu")
		(net "SW_P12V_AUX_PVDDCR_CPU1_P1_FLT")
	)
	(via
		(at 74.86015 -350.929448)
		(size 0.508)
		(drill 0.254)
		(layers "F.Cu" "B.Cu")
		(net "SW_P12V_AUX_PVDDCR_CPU1_P1_FLT")
	)
	(via
		(at 82.475578 -337.795362)
		(size 0.508)
		(drill 0.254)
		(layers "F.Cu" "B.Cu")
		(net "SW_P12V_AUX_PVDDCR_CPU1_P1_FLT")
	)
	(via
		(at 74.811382 -351.637854)
		(size 0.508)
		(drill 0.254)
		(layers "F.Cu" "B.Cu")
		(net "SW_P12V_AUX_PVDDCR_CPU1_P1_FLT")
	)
	(via
		(at 77.511402 -352.978212)
		(size 0.508)
		(drill 0.254)
		(layers "F.Cu" "B.Cu")
		(net "SW_P12V_AUX_PVDDCR_CPU1_P1_FLT")
	)
	(via
		(at 106.98607 -342.540844)
		(size 0.508)
		(drill 0.254)
		(layers "F.Cu" "B.Cu")
		(net "SW_P12V_AUX_PVDDCR_CPU1_P1_FLT")
	)
	(via
		(at 89.985088 -345.96959)
		(size 0.508)
		(drill 0.254)
		(layers "F.Cu" "B.Cu")
		(net "SW_P12V_AUX_PVDDCR_CPU1_P1_FLT")
	)
	(via
		(at 97.658174 -335.582768)
		(size 0.49022)
		(drill 0.254)
		(layers "F.Cu" "B.Cu")
		(net "SW_P12V_AUX_PVDDCR_CPU1_P1_FLT")
	)
	(via
		(at 73.03643 -338.597494)
		(size 0.508)
		(drill 0.254)
		(layers "F.Cu" "B.Cu")
		(net "SW_P12V_AUX_PVDDCR_CPU1_P1_FLT")
	)
	(via
		(at 89.047574 -336.966814)
		(size 0.49022)
		(drill 0.254)
		(layers "F.Cu" "B.Cu")
		(net "SW_P12V_AUX_PVDDCR_CPU1_P1_FLT")
	)
	(via
		(at 73.586594 -338.183474)
		(size 0.508)
		(drill 0.254)
		(layers "F.Cu" "B.Cu")
		(net "SW_P12V_AUX_PVDDCR_CPU1_P1_FLT")
	)
	(via
		(at 84.884006 -350.239838)
		(size 0.508)
		(drill 0.254)
		(layers "F.Cu" "B.Cu")
		(net "SW_P12V_AUX_PVDDCR_CPU1_P1_FLT")
	)
	(via
		(at 64.50203 -350.318578)
		(size 0.508)
		(drill 0.254)
		(layers "F.Cu" "B.Cu")
		(net "SW_P12V_AUX_PVDDCR_CPU1_P1_FLT")
	)
	(via
		(at 91.293442 -346.639896)
		(size 0.508)
		(drill 0.254)
		(layers "F.Cu" "B.Cu")
		(net "SW_P12V_AUX_PVDDCR_CPU1_P1_FLT")
	)
	(via
		(at 65.585594 -348.786958)
		(size 0.508)
		(drill 0.254)
		(layers "F.Cu" "B.Cu")
		(net "SW_P12V_AUX_PVDDCR_CPU1_P1_FLT")
	)
	(via
		(at 91.255088 -345.96959)
		(size 0.508)
		(drill 0.254)
		(layers "F.Cu" "B.Cu")
		(net "SW_P12V_AUX_PVDDCR_CPU1_P1_FLT")
	)
	(via
		(at 104.420162 -341.927688)
		(size 0.49022)
		(drill 0.254)
		(layers "F.Cu" "B.Cu")
		(net "SW_P12V_AUX_PVDDCR_CPU1_P1_FLT")
	)
	(via
		(at 84.884006 -349.531432)
		(size 0.508)
		(drill 0.254)
		(layers "F.Cu" "B.Cu")
		(net "SW_P12V_AUX_PVDDCR_CPU1_P1_FLT")
	)
	(via
		(at 90.833194 -337.044284)
		(size 0.508)
		(drill 0.254)
		(layers "F.Cu" "B.Cu")
		(net "SW_P12V_AUX_PVDDCR_CPU1_P1_FLT")
	)
	(via
		(at 90.833194 -338.517484)
		(size 0.508)
		(drill 0.254)
		(layers "F.Cu" "B.Cu")
		(net "SW_P12V_AUX_PVDDCR_CPU1_P1_FLT")
	)
	(via
		(at 89.388442 -346.639896)
		(size 0.508)
		(drill 0.254)
		(layers "F.Cu" "B.Cu")
		(net "SW_P12V_AUX_PVDDCR_CPU1_P1_FLT")
	)
	(via
		(at 98.605594 -337.450684)
		(size 0.508)
		(drill 0.254)
		(layers "F.Cu" "B.Cu")
		(net "SW_P12V_AUX_PVDDCR_CPU1_P1_FLT")
	)
	(via
		(at 73.03643 -337.860894)
		(size 0.508)
		(drill 0.254)
		(layers "F.Cu" "B.Cu")
		(net "SW_P12V_AUX_PVDDCR_CPU1_P1_FLT")
	)
	(via
		(at 81.392014 -337.853782)
		(size 0.508)
		(drill 0.254)
		(layers "F.Cu" "B.Cu")
		(net "SW_P12V_AUX_PVDDCR_CPU1_P1_FLT")
	)
	(via
		(at 65.585594 -349.523558)
		(size 0.508)
		(drill 0.254)
		(layers "F.Cu" "B.Cu")
		(net "SW_P12V_AUX_PVDDCR_CPU1_P1_FLT")
	)
	(via
		(at 91.966288 -345.96959)
		(size 0.508)
		(drill 0.254)
		(layers "F.Cu" "B.Cu")
		(net "SW_P12V_AUX_PVDDCR_CPU1_P1_FLT")
	)
	(via
		(at 64.50203 -349.581978)
		(size 0.508)
		(drill 0.254)
		(layers "F.Cu" "B.Cu")
		(net "SW_P12V_AUX_PVDDCR_CPU1_P1_FLT")
	)
	(via
		(at 82.222086 -350.393)
		(size 0.508)
		(drill 0.254)
		(layers "F.Cu" "B.Cu")
		(net "SW_P12V_AUX_PVDDCR_CPU1_P1_FLT")
	)
	(via
		(at 107.01401 -343.986104)
		(size 0.508)
		(drill 0.254)
		(layers "F.Cu" "B.Cu")
		(net "SW_P12V_AUX_PVDDCR_CPU1_P1_FLT")
	)
	(via
		(at 77.473048 -351.5995)
		(size 0.508)
		(drill 0.254)
		(layers "F.Cu" "B.Cu")
		(net "SW_P12V_AUX_PVDDCR_CPU1_P1_FLT")
	)
	(via
		(at 98.630994 -338.212684)
		(size 0.508)
		(drill 0.254)
		(layers "F.Cu" "B.Cu")
		(net "SW_P12V_AUX_PVDDCR_CPU1_P1_FLT")
	)
	(via
		(at 89.319354 -335.519268)
		(size 0.49022)
		(drill 0.254)
		(layers "F.Cu" "B.Cu")
		(net "SW_P12V_AUX_PVDDCR_CPU1_P1_FLT")
	)
	(via
		(at 98.747834 -338.974684)
		(size 0.508)
		(drill 0.254)
		(layers "F.Cu" "B.Cu")
		(net "SW_P12V_AUX_PVDDCR_CPU1_P1_FLT")
	)
	(via
		(at 80.689958 -336.981292)
		(size 0.49022)
		(drill 0.254)
		(layers "F.Cu" "B.Cu")
		(net "SW_P12V_AUX_PVDDCR_CPU1_P1_FLT")
	)
	(via
		(at 77.521816 -350.891094)
		(size 0.508)
		(drill 0.254)
		(layers "F.Cu" "B.Cu")
		(net "SW_P12V_AUX_PVDDCR_CPU1_P1_FLT")
	)
	(via
		(at 89.319354 -336.255868)
		(size 0.49022)
		(drill 0.254)
		(layers "F.Cu" "B.Cu")
		(net "SW_P12V_AUX_PVDDCR_CPU1_P1_FLT")
	)
	(via
		(at 84.845652 -348.861126)
		(size 0.508)
		(drill 0.254)
		(layers "F.Cu" "B.Cu")
		(net "SW_P12V_AUX_PVDDCR_CPU1_P1_FLT")
	)
	(via
		(at 91.380056 -345.261184)
		(size 0.508)
		(drill 0.254)
		(layers "F.Cu" "B.Cu")
		(net "SW_P12V_AUX_PVDDCR_CPU1_P1_FLT")
	)
	(via
		(at 90.833194 -337.780884)
		(size 0.508)
		(drill 0.254)
		(layers "F.Cu" "B.Cu")
		(net "SW_P12V_AUX_PVDDCR_CPU1_P1_FLT")
	)
	(via
		(at 74.849482 -353.131374)
		(size 0.508)
		(drill 0.254)
		(layers "F.Cu" "B.Cu")
		(net "SW_P12V_AUX_PVDDCR_CPU1_P1_FLT")
	)
	(via
		(at 82.183986 -348.89948)
		(size 0.508)
		(drill 0.254)
		(layers "F.Cu" "B.Cu")
		(net "SW_P12V_AUX_PVDDCR_CPU1_P1_FLT")
	)
	(via
		(at 92.639642 -346.639896)
		(size 0.508)
		(drill 0.254)
		(layers "F.Cu" "B.Cu")
		(net "SW_P12V_AUX_PVDDCR_CPU1_P1_FLT")
	)
	(via
		(at 65.585594 -350.260158)
		(size 0.508)
		(drill 0.254)
		(layers "F.Cu" "B.Cu")
		(net "SW_P12V_AUX_PVDDCR_CPU1_P1_FLT")
	)
	(via
		(at 80.977994 -335.509108)
		(size 0.49022)
		(drill 0.254)
		(layers "F.Cu" "B.Cu")
		(net "SW_P12V_AUX_PVDDCR_CPU1_P1_FLT")
	)
	(via
		(at 74.119994 -337.802474)
		(size 0.508)
		(drill 0.254)
		(layers "F.Cu" "B.Cu")
		(net "SW_P12V_AUX_PVDDCR_CPU1_P1_FLT")
	)
	(via
		(at 90.618056 -345.261184)
		(size 0.508)
		(drill 0.254)
		(layers "F.Cu" "B.Cu")
		(net "SW_P12V_AUX_PVDDCR_CPU1_P1_FLT")
	)
	(via
		(at 74.119994 -337.065874)
		(size 0.508)
		(drill 0.254)
		(layers "F.Cu" "B.Cu")
		(net "SW_P12V_AUX_PVDDCR_CPU1_P1_FLT")
	)
	(via
		(at 98.747834 -339.736684)
		(size 0.508)
		(drill 0.254)
		(layers "F.Cu" "B.Cu")
		(net "SW_P12V_AUX_PVDDCR_CPU1_P1_FLT")
	)
	(via
		(at 92.004642 -346.639896)
		(size 0.508)
		(drill 0.254)
		(layers "F.Cu" "B.Cu")
		(net "SW_P12V_AUX_PVDDCR_CPU1_P1_FLT")
	)
	(via
		(at 87.813134 -336.966814)
		(size 0.49022)
		(drill 0.254)
		(layers "F.Cu" "B.Cu")
		(net "SW_P12V_AUX_PVDDCR_CPU1_P1_FLT")
	)
	(via
		(at 98.08083 -338.626704)
		(size 0.508)
		(drill 0.254)
		(layers "F.Cu" "B.Cu")
		(net "SW_P12V_AUX_PVDDCR_CPU1_P1_FLT")
	)
	(via
		(at 81.942178 -338.176362)
		(size 0.508)
		(drill 0.254)
		(layers "F.Cu" "B.Cu")
		(net "SW_P12V_AUX_PVDDCR_CPU1_P1_FLT")
	)
	(via
		(at 74.119994 -338.539074)
		(size 0.508)
		(drill 0.254)
		(layers "F.Cu" "B.Cu")
		(net "SW_P12V_AUX_PVDDCR_CPU1_P1_FLT")
	)
	(via
		(at 89.350088 -345.96959)
		(size 0.508)
		(drill 0.254)
		(layers "F.Cu" "B.Cu")
		(net "SW_P12V_AUX_PVDDCR_CPU1_P1_FLT")
	)
	(via
		(at 90.274394 -337.399884)
		(size 0.508)
		(drill 0.254)
		(layers "F.Cu" "B.Cu")
		(net "SW_P12V_AUX_PVDDCR_CPU1_P1_FLT")
	)
	(via
		(at 72.334374 -336.988404)
		(size 0.49022)
		(drill 0.254)
		(layers "F.Cu" "B.Cu")
		(net "SW_P12V_AUX_PVDDCR_CPU1_P1_FLT")
	)
	(via
		(at 90.299794 -338.161884)
		(size 0.508)
		(drill 0.254)
		(layers "F.Cu" "B.Cu")
		(net "SW_P12V_AUX_PVDDCR_CPU1_P1_FLT")
	)
	(via
		(at 89.74963 -337.839304)
		(size 0.508)
		(drill 0.254)
		(layers "F.Cu" "B.Cu")
		(net "SW_P12V_AUX_PVDDCR_CPU1_P1_FLT")
	)
	(via
		(at 98.199194 -339.358224)
		(size 0.508)
		(drill 0.254)
		(layers "F.Cu" "B.Cu")
		(net "SW_P12V_AUX_PVDDCR_CPU1_P1_FLT")
	)
	(via
		(at 72.616314 -335.519268)
		(size 0.49022)
		(drill 0.254)
		(layers "F.Cu" "B.Cu")
		(net "SW_P12V_AUX_PVDDCR_CPU1_P1_FLT")
	)
	(via
		(at 89.983056 -345.261184)
		(size 0.508)
		(drill 0.254)
		(layers "F.Cu" "B.Cu")
		(net "SW_P12V_AUX_PVDDCR_CPU1_P1_FLT")
	)
	(via
		(at 90.620088 -345.96959)
		(size 0.508)
		(drill 0.254)
		(layers "F.Cu" "B.Cu")
		(net "SW_P12V_AUX_PVDDCR_CPU1_P1_FLT")
	)
	(via
		(at 65.026794 -349.142558)
		(size 0.508)
		(drill 0.254)
		(layers "F.Cu" "B.Cu")
		(net "SW_P12V_AUX_PVDDCR_CPU1_P1_FLT")
	)
	(via
		(at 97.378774 -337.017614)
		(size 0.49022)
		(drill 0.254)
		(layers "F.Cu" "B.Cu")
		(net "SW_P12V_AUX_PVDDCR_CPU1_P1_FLT")
	)
	(via
		(at 65.052194 -349.904558)
		(size 0.508)
		(drill 0.254)
		(layers "F.Cu" "B.Cu")
		(net "SW_P12V_AUX_PVDDCR_CPU1_P1_FLT")
	)
	(via
		(at 71.099934 -336.988404)
		(size 0.49022)
		(drill 0.254)
		(layers "F.Cu" "B.Cu")
		(net "SW_P12V_AUX_PVDDCR_CPU1_P1_FLT")
	)
	(via
		(at 89.314528 -345.237562)
		(size 0.508)
		(drill 0.254)
		(layers "F.Cu" "B.Cu")
		(net "SW_P12V_AUX_PVDDCR_CPU1_P1_FLT")
	)
	(via
		(at 105.037382 -341.927688)
		(size 0.49022)
		(drill 0.254)
		(layers "F.Cu" "B.Cu")
		(net "SW_P12V_AUX_PVDDCR_CPU1_P1_FLT")
	)
	(via
		(at 107.01401 -343.249504)
		(size 0.508)
		(drill 0.254)
		(layers "F.Cu" "B.Cu")
		(net "SW_P12V_AUX_PVDDCR_CPU1_P1_FLT")
	)
	(via
		(at 72.616314 -336.255868)
		(size 0.49022)
		(drill 0.254)
		(layers "F.Cu" "B.Cu")
		(net "SW_P12V_AUX_PVDDCR_CPU1_P1_FLT")
	)
	(via
		(at 106.34345 -343.450164)
		(size 0.508)
		(drill 0.254)
		(layers "F.Cu" "B.Cu")
		(net "SW_P12V_AUX_PVDDCR_CPU1_P1_FLT")
	)
	(via
		(at 64.061594 -348.038928)
		(size 0.49022)
		(drill 0.254)
		(layers "F.Cu" "B.Cu")
		(net "SW_P12V_AUX_PVDDCR_CPU1_P1_FLT")
	)
	(via
		(at 106.34345 -342.713564)
		(size 0.508)
		(drill 0.254)
		(layers "F.Cu" "B.Cu")
		(net "SW_P12V_AUX_PVDDCR_CPU1_P1_FLT")
	)
	(via
		(at 71.717154 -336.988404)
		(size 0.49022)
		(drill 0.254)
		(layers "F.Cu" "B.Cu")
		(net "SW_P12V_AUX_PVDDCR_CPU1_P1_FLT")
	)
	(via
		(at 92.650056 -345.261184)
		(size 0.508)
		(drill 0.254)
		(layers "F.Cu" "B.Cu")
		(net "SW_P12V_AUX_PVDDCR_CPU1_P1_FLT")
	)
	(via
		(at 84.89442 -348.15272)
		(size 0.508)
		(drill 0.254)
		(layers "F.Cu" "B.Cu")
		(net "SW_P12V_AUX_PVDDCR_CPU1_P1_FLT")
	)
	(via
		(at 82.475578 -338.531962)
		(size 0.508)
		(drill 0.254)
		(layers "F.Cu" "B.Cu")
		(net "SW_P12V_AUX_PVDDCR_CPU1_P1_FLT")
	)
	(via
		(at 62.565534 -348.709488)
		(size 0.49022)
		(drill 0.254)
		(layers "F.Cu" "B.Cu")
		(net "SW_P12V_AUX_PVDDCR_CPU1_P1_FLT")
	)
	(via
		(at 89.74963 -338.575904)
		(size 0.508)
		(drill 0.254)
		(layers "F.Cu" "B.Cu")
		(net "SW_P12V_AUX_PVDDCR_CPU1_P1_FLT")
	)
	(via
		(at 82.475578 -337.058762)
		(size 0.508)
		(drill 0.254)
		(layers "F.Cu" "B.Cu")
		(net "SW_P12V_AUX_PVDDCR_CPU1_P1_FLT")
	)
	(via
		(at 81.916778 -337.414362)
		(size 0.508)
		(drill 0.254)
		(layers "F.Cu" "B.Cu")
		(net "SW_P12V_AUX_PVDDCR_CPU1_P1_FLT")
	)
	(via
		(at 105.654602 -341.927688)
		(size 0.49022)
		(drill 0.254)
		(layers "F.Cu" "B.Cu")
		(net "SW_P12V_AUX_PVDDCR_CPU1_P1_FLT")
	)
	(via
		(at 82.232754 -348.191074)
		(size 0.508)
		(drill 0.254)
		(layers "F.Cu" "B.Cu")
		(net "SW_P12V_AUX_PVDDCR_CPU1_P1_FLT")
	)
	(via
		(at 88.430354 -336.966814)
		(size 0.49022)
		(drill 0.254)
		(layers "F.Cu" "B.Cu")
		(net "SW_P12V_AUX_PVDDCR_CPU1_P1_FLT")
	)
	(via
		(at 105.934002 -341.229442)
		(size 0.49022)
		(drill 0.254)
		(layers "F.Cu" "B.Cu")
		(net "SW_P12V_AUX_PVDDCR_CPU1_P1_FLT")
	)
	(via
		(at 80.072738 -336.981292)
		(size 0.49022)
		(drill 0.254)
		(layers "F.Cu" "B.Cu")
		(net "SW_P12V_AUX_PVDDCR_CPU1_P1_FLT")
	)
	(via
		(at 92.015056 -345.261184)
		(size 0.508)
		(drill 0.254)
		(layers "F.Cu" "B.Cu")
		(net "SW_P12V_AUX_PVDDCR_CPU1_P1_FLT")
	)
	(via
		(at 77.511402 -352.269806)
		(size 0.508)
		(drill 0.254)
		(layers "F.Cu" "B.Cu")
		(net "SW_P12V_AUX_PVDDCR_CPU1_P1_FLT")
	)
	(via
		(at 82.22234 -349.569786)
		(size 0.508)
		(drill 0.254)
		(layers "F.Cu" "B.Cu")
		(net "SW_P12V_AUX_PVDDCR_CPU1_P1_FLT")
	)
	(via
		(at 81.392014 -338.590382)
		(size 0.508)
		(drill 0.254)
		(layers "F.Cu" "B.Cu")
		(net "SW_P12V_AUX_PVDDCR_CPU1_P1_FLT")
	)
	(via
		(at 80.977994 -336.245708)
		(size 0.49022)
		(drill 0.254)
		(layers "F.Cu" "B.Cu")
		(net "SW_P12V_AUX_PVDDCR_CPU1_P1_FLT")
	)
	(via
		(at 90.023442 -346.639896)
		(size 0.508)
		(drill 0.254)
		(layers "F.Cu" "B.Cu")
		(net "SW_P12V_AUX_PVDDCR_CPU1_P1_FLT")
	)
	(via
		(at 105.934002 -340.492842)
		(size 0.49022)
		(drill 0.254)
		(layers "F.Cu" "B.Cu")
		(net "SW_P12V_AUX_PVDDCR_CPU1_P1_FLT")
	)
	(via
		(at 96.761554 -337.017614)
		(size 0.49022)
		(drill 0.254)
		(layers "F.Cu" "B.Cu")
		(net "SW_P12V_AUX_PVDDCR_CPU1_P1_FLT")
	)
	(via
		(at 90.658442 -346.639896)
		(size 0.508)
		(drill 0.254)
		(layers "F.Cu" "B.Cu")
		(net "SW_P12V_AUX_PVDDCR_CPU1_P1_FLT")
	)
	(via
		(at 97.658174 -336.319368)
		(size 0.49022)
		(drill 0.254)
		(layers "F.Cu" "B.Cu")
		(net "SW_P12V_AUX_PVDDCR_CPU1_P1_FLT")
	)
	(via
		(at 98.08083 -337.890104)
		(size 0.508)
		(drill 0.254)
		(layers "F.Cu" "B.Cu")
		(net "SW_P12V_AUX_PVDDCR_CPU1_P1_FLT")
	)
	(via
		(at 106.98607 -341.804244)
		(size 0.508)
		(drill 0.254)
		(layers "F.Cu" "B.Cu")
		(net "SW_P12V_AUX_PVDDCR_CPU1_P1_FLT")
	)
	(via
		(at 63.182754 -348.709488)
		(size 0.49022)
		(drill 0.254)
		(layers "F.Cu" "B.Cu")
		(net "SW_P12V_AUX_PVDDCR_CPU1_P1_FLT")
	)
	(via
		(at 79.455518 -336.981292)
		(size 0.49022)
		(drill 0.254)
		(layers "F.Cu" "B.Cu")
		(net "SW_P12V_AUX_PVDDCR_CPU1_P1_FLT")
	)
	(via
		(at 74.849736 -352.30816)
		(size 0.508)
		(drill 0.254)
		(layers "F.Cu" "B.Cu")
		(net "SW_P12V_AUX_PVDDCR_CPU1_P1_FLT")
	)
	(via
		(at 64.061594 -347.302328)
		(size 0.49022)
		(drill 0.254)
		(layers "F.Cu" "B.Cu")
		(net "SW_P12V_AUX_PVDDCR_CPU1_P1_FLT")
	)
	(via
		(at 92.601288 -345.96959)
		(size 0.508)
		(drill 0.254)
		(layers "F.Cu" "B.Cu")
		(net "SW_P12V_AUX_PVDDCR_CPU1_P1_FLT")
	)
	(via
		(at 63.799974 -348.709488)
		(size 0.49022)
		(drill 0.254)
		(layers "F.Cu" "B.Cu")
		(net "SW_P12V_AUX_PVDDCR_CPU1_P1_FLT")
	)
	(via
		(at 339.73897 -352.973132)
		(size 0.508)
		(drill 0.254)
		(layers "F.Cu" "B.Cu")
		(net "SW_P12V_AUX_PVDDCR_CPU1_P0_FLT")
	)
	(via
		(at 346.017596 -338.621878)
		(size 0.508)
		(drill 0.254)
		(layers "F.Cu" "B.Cu")
		(net "SW_P12V_AUX_PVDDCR_CPU1_P0_FLT")
	)
	(via
		(at 354.293424 -343.531952)
		(size 0.508)
		(drill 0.254)
		(layers "F.Cu" "B.Cu")
		(net "SW_P12V_AUX_PVDDCR_CPU1_P0_FLT")
	)
	(via
		(at 353.899724 -341.22741)
		(size 0.508)
		(drill 0.254)
		(layers "F.Cu" "B.Cu")
		(net "SW_P12V_AUX_PVDDCR_CPU1_P0_FLT")
	)
	(via
		(at 341.263224 -352.215196)
		(size 0.508)
		(drill 0.254)
		(layers "F.Cu" "B.Cu")
		(net "SW_P12V_AUX_PVDDCR_CPU1_P0_FLT")
	)
	(via
		(at 320.973196 -337.856068)
		(size 0.508)
		(drill 0.254)
		(layers "F.Cu" "B.Cu")
		(net "SW_P12V_AUX_PVDDCR_CPU1_P0_FLT")
	)
	(via
		(at 352.356928 -341.922862)
		(size 0.49022)
		(drill 0.254)
		(layers "F.Cu" "B.Cu")
		(net "SW_P12V_AUX_PVDDCR_CPU1_P0_FLT")
	)
	(via
		(at 343.465404 -352.248216)
		(size 0.508)
		(drill 0.254)
		(layers "F.Cu" "B.Cu")
		(net "SW_P12V_AUX_PVDDCR_CPU1_P0_FLT")
	)
	(via
		(at 346.56776 -338.969858)
		(size 0.508)
		(drill 0.254)
		(layers "F.Cu" "B.Cu")
		(net "SW_P12V_AUX_PVDDCR_CPU1_P0_FLT")
	)
	(via
		(at 321.49796 -337.416648)
		(size 0.508)
		(drill 0.254)
		(layers "F.Cu" "B.Cu")
		(net "SW_P12V_AUX_PVDDCR_CPU1_P0_FLT")
	)
	(via
		(at 320.5607 -335.503012)
		(size 0.508)
		(drill 0.254)
		(layers "F.Cu" "B.Cu")
		(net "SW_P12V_AUX_PVDDCR_CPU1_P0_FLT")
	)
	(via
		(at 355.376988 -343.473532)
		(size 0.508)
		(drill 0.254)
		(layers "F.Cu" "B.Cu")
		(net "SW_P12V_AUX_PVDDCR_CPU1_P0_FLT")
	)
	(via
		(at 312.407046 -350.255332)
		(size 0.508)
		(drill 0.254)
		(layers "F.Cu" "B.Cu")
		(net "SW_P12V_AUX_PVDDCR_CPU1_P0_FLT")
	)
	(via
		(at 346.017596 -339.358478)
		(size 0.508)
		(drill 0.254)
		(layers "F.Cu" "B.Cu")
		(net "SW_P12V_AUX_PVDDCR_CPU1_P0_FLT")
	)
	(via
		(at 329.853544 -337.409536)
		(size 0.508)
		(drill 0.254)
		(layers "F.Cu" "B.Cu")
		(net "SW_P12V_AUX_PVDDCR_CPU1_P0_FLT")
	)
	(via
		(at 339.739224 -352.215196)
		(size 0.508)
		(drill 0.254)
		(layers "F.Cu" "B.Cu")
		(net "SW_P12V_AUX_PVDDCR_CPU1_P0_FLT")
	)
	(via
		(at 320.27114 -336.983578)
		(size 0.49022)
		(drill 0.254)
		(layers "F.Cu" "B.Cu")
		(net "SW_P12V_AUX_PVDDCR_CPU1_P0_FLT")
	)
	(via
		(at 330.412344 -337.053936)
		(size 0.508)
		(drill 0.254)
		(layers "F.Cu" "B.Cu")
		(net "SW_P12V_AUX_PVDDCR_CPU1_P0_FLT")
	)
	(via
		(at 330.412344 -337.790536)
		(size 0.508)
		(drill 0.254)
		(layers "F.Cu" "B.Cu")
		(net "SW_P12V_AUX_PVDDCR_CPU1_P0_FLT")
	)
	(via
		(at 355.376988 -342.000332)
		(size 0.508)
		(drill 0.254)
		(layers "F.Cu" "B.Cu")
		(net "SW_P12V_AUX_PVDDCR_CPU1_P0_FLT")
	)
	(via
		(at 354.293424 -342.795352)
		(size 0.508)
		(drill 0.254)
		(layers "F.Cu" "B.Cu")
		(net "SW_P12V_AUX_PVDDCR_CPU1_P0_FLT")
	)
	(via
		(at 338.76996 -338.512658)
		(size 0.508)
		(drill 0.254)
		(layers "F.Cu" "B.Cu")
		(net "SW_P12V_AUX_PVDDCR_CPU1_P0_FLT")
	)
	(via
		(at 328.918824 -335.517236)
		(size 0.508)
		(drill 0.254)
		(layers "F.Cu" "B.Cu")
		(net "SW_P12V_AUX_PVDDCR_CPU1_P0_FLT")
	)
	(via
		(at 311.848246 -349.137732)
		(size 0.508)
		(drill 0.254)
		(layers "F.Cu" "B.Cu")
		(net "SW_P12V_AUX_PVDDCR_CPU1_P0_FLT")
	)
	(via
		(at 340.667848 -353.010216)
		(size 0.508)
		(drill 0.254)
		(layers "F.Cu" "B.Cu")
		(net "SW_P12V_AUX_PVDDCR_CPU1_P0_FLT")
	)
	(via
		(at 322.05676 -337.061048)
		(size 0.508)
		(drill 0.254)
		(layers "F.Cu" "B.Cu")
		(net "SW_P12V_AUX_PVDDCR_CPU1_P0_FLT")
	)
	(via
		(at 342.025224 -351.453196)
		(size 0.508)
		(drill 0.254)
		(layers "F.Cu" "B.Cu")
		(net "SW_P12V_AUX_PVDDCR_CPU1_P0_FLT")
	)
	(via
		(at 342.025224 -352.215196)
		(size 0.508)
		(drill 0.254)
		(layers "F.Cu" "B.Cu")
		(net "SW_P12V_AUX_PVDDCR_CPU1_P0_FLT")
	)
	(via
		(at 309.386986 -348.704662)
		(size 0.49022)
		(drill 0.254)
		(layers "F.Cu" "B.Cu")
		(net "SW_P12V_AUX_PVDDCR_CPU1_P0_FLT")
	)
	(via
		(at 322.05676 -338.534248)
		(size 0.508)
		(drill 0.254)
		(layers "F.Cu" "B.Cu")
		(net "SW_P12V_AUX_PVDDCR_CPU1_P0_FLT")
	)
	(via
		(at 346.54236 -337.445858)
		(size 0.508)
		(drill 0.254)
		(layers "F.Cu" "B.Cu")
		(net "SW_P12V_AUX_PVDDCR_CPU1_P0_FLT")
	)
	(via
		(at 311.323482 -349.577152)
		(size 0.508)
		(drill 0.254)
		(layers "F.Cu" "B.Cu")
		(net "SW_P12V_AUX_PVDDCR_CPU1_P0_FLT")
	)
	(via
		(at 329.32878 -338.585556)
		(size 0.508)
		(drill 0.254)
		(layers "F.Cu" "B.Cu")
		(net "SW_P12V_AUX_PVDDCR_CPU1_P0_FLT")
	)
	(via
		(at 338.21116 -337.395058)
		(size 0.508)
		(drill 0.254)
		(layers "F.Cu" "B.Cu")
		(net "SW_P12V_AUX_PVDDCR_CPU1_P0_FLT")
	)
	(via
		(at 338.76996 -337.776058)
		(size 0.508)
		(drill 0.254)
		(layers "F.Cu" "B.Cu")
		(net "SW_P12V_AUX_PVDDCR_CPU1_P0_FLT")
	)
	(via
		(at 320.973196 -338.592668)
		(size 0.508)
		(drill 0.254)
		(layers "F.Cu" "B.Cu")
		(net "SW_P12V_AUX_PVDDCR_CPU1_P0_FLT")
	)
	(via
		(at 346.56776 -339.731858)
		(size 0.508)
		(drill 0.254)
		(layers "F.Cu" "B.Cu")
		(net "SW_P12V_AUX_PVDDCR_CPU1_P0_FLT")
	)
	(via
		(at 336.36712 -336.961988)
		(size 0.49022)
		(drill 0.254)
		(layers "F.Cu" "B.Cu")
		(net "SW_P12V_AUX_PVDDCR_CPU1_P0_FLT")
	)
	(via
		(at 342.787224 -351.453196)
		(size 0.508)
		(drill 0.254)
		(layers "F.Cu" "B.Cu")
		(net "SW_P12V_AUX_PVDDCR_CPU1_P0_FLT")
	)
	(via
		(at 336.98434 -336.961988)
		(size 0.49022)
		(drill 0.254)
		(layers "F.Cu" "B.Cu")
		(net "SW_P12V_AUX_PVDDCR_CPU1_P0_FLT")
	)
	(via
		(at 327.392284 -336.976466)
		(size 0.49022)
		(drill 0.254)
		(layers "F.Cu" "B.Cu")
		(net "SW_P12V_AUX_PVDDCR_CPU1_P0_FLT")
	)
	(via
		(at 330.412344 -338.527136)
		(size 0.508)
		(drill 0.254)
		(layers "F.Cu" "B.Cu")
		(net "SW_P12V_AUX_PVDDCR_CPU1_P0_FLT")
	)
	(via
		(at 321.52336 -338.178648)
		(size 0.508)
		(drill 0.254)
		(layers "F.Cu" "B.Cu")
		(net "SW_P12V_AUX_PVDDCR_CPU1_P0_FLT")
	)
	(via
		(at 320.5607 -336.239612)
		(size 0.508)
		(drill 0.254)
		(layers "F.Cu" "B.Cu")
		(net "SW_P12V_AUX_PVDDCR_CPU1_P0_FLT")
	)
	(via
		(at 354.818188 -342.355932)
		(size 0.508)
		(drill 0.254)
		(layers "F.Cu" "B.Cu")
		(net "SW_P12V_AUX_PVDDCR_CPU1_P0_FLT")
	)
	(via
		(at 341.302848 -353.010216)
		(size 0.508)
		(drill 0.254)
		(layers "F.Cu" "B.Cu")
		(net "SW_P12V_AUX_PVDDCR_CPU1_P0_FLT")
	)
	(via
		(at 343.465404 -351.486216)
		(size 0.508)
		(drill 0.254)
		(layers "F.Cu" "B.Cu")
		(net "SW_P12V_AUX_PVDDCR_CPU1_P0_FLT")
	)
	(via
		(at 341.263224 -351.453196)
		(size 0.508)
		(drill 0.254)
		(layers "F.Cu" "B.Cu")
		(net "SW_P12V_AUX_PVDDCR_CPU1_P0_FLT")
	)
	(via
		(at 322.05676 -337.797648)
		(size 0.508)
		(drill 0.254)
		(layers "F.Cu" "B.Cu")
		(net "SW_P12V_AUX_PVDDCR_CPU1_P0_FLT")
	)
	(via
		(at 328.626724 -336.976466)
		(size 0.49022)
		(drill 0.254)
		(layers "F.Cu" "B.Cu")
		(net "SW_P12V_AUX_PVDDCR_CPU1_P0_FLT")
	)
	(via
		(at 328.009504 -336.976466)
		(size 0.49022)
		(drill 0.254)
		(layers "F.Cu" "B.Cu")
		(net "SW_P12V_AUX_PVDDCR_CPU1_P0_FLT")
	)
	(via
		(at 345.623896 -335.580736)
		(size 0.508)
		(drill 0.254)
		(layers "F.Cu" "B.Cu")
		(net "SW_P12V_AUX_PVDDCR_CPU1_P0_FLT")
	)
	(via
		(at 312.407046 -348.782132)
		(size 0.508)
		(drill 0.254)
		(layers "F.Cu" "B.Cu")
		(net "SW_P12V_AUX_PVDDCR_CPU1_P0_FLT")
	)
	(via
		(at 340.501224 -351.453196)
		(size 0.508)
		(drill 0.254)
		(layers "F.Cu" "B.Cu")
		(net "SW_P12V_AUX_PVDDCR_CPU1_P0_FLT")
	)
	(via
		(at 335.7499 -336.961988)
		(size 0.49022)
		(drill 0.254)
		(layers "F.Cu" "B.Cu")
		(net "SW_P12V_AUX_PVDDCR_CPU1_P0_FLT")
	)
	(via
		(at 340.501224 -352.215196)
		(size 0.508)
		(drill 0.254)
		(layers "F.Cu" "B.Cu")
		(net "SW_P12V_AUX_PVDDCR_CPU1_P0_FLT")
	)
	(via
		(at 353.591368 -341.922862)
		(size 0.49022)
		(drill 0.254)
		(layers "F.Cu" "B.Cu")
		(net "SW_P12V_AUX_PVDDCR_CPU1_P0_FLT")
	)
	(via
		(at 329.32878 -337.848956)
		(size 0.508)
		(drill 0.254)
		(layers "F.Cu" "B.Cu")
		(net "SW_P12V_AUX_PVDDCR_CPU1_P0_FLT")
	)
	(via
		(at 346.56776 -338.207858)
		(size 0.508)
		(drill 0.254)
		(layers "F.Cu" "B.Cu")
		(net "SW_P12V_AUX_PVDDCR_CPU1_P0_FLT")
	)
	(via
		(at 338.76996 -337.039458)
		(size 0.508)
		(drill 0.254)
		(layers "F.Cu" "B.Cu")
		(net "SW_P12V_AUX_PVDDCR_CPU1_P0_FLT")
	)
	(via
		(at 342.787224 -352.215196)
		(size 0.508)
		(drill 0.254)
		(layers "F.Cu" "B.Cu")
		(net "SW_P12V_AUX_PVDDCR_CPU1_P0_FLT")
	)
	(via
		(at 355.376988 -342.736932)
		(size 0.508)
		(drill 0.254)
		(layers "F.Cu" "B.Cu")
		(net "SW_P12V_AUX_PVDDCR_CPU1_P0_FLT")
	)
	(via
		(at 353.899724 -340.49081)
		(size 0.508)
		(drill 0.254)
		(layers "F.Cu" "B.Cu")
		(net "SW_P12V_AUX_PVDDCR_CPU1_P0_FLT")
	)
	(via
		(at 310.621426 -348.704662)
		(size 0.49022)
		(drill 0.254)
		(layers "F.Cu" "B.Cu")
		(net "SW_P12V_AUX_PVDDCR_CPU1_P0_FLT")
	)
	(via
		(at 354.843588 -343.117932)
		(size 0.508)
		(drill 0.254)
		(layers "F.Cu" "B.Cu")
		(net "SW_P12V_AUX_PVDDCR_CPU1_P0_FLT")
	)
	(via
		(at 339.739224 -351.453196)
		(size 0.508)
		(drill 0.254)
		(layers "F.Cu" "B.Cu")
		(net "SW_P12V_AUX_PVDDCR_CPU1_P0_FLT")
	)
	(via
		(at 338.23656 -338.157058)
		(size 0.508)
		(drill 0.254)
		(layers "F.Cu" "B.Cu")
		(net "SW_P12V_AUX_PVDDCR_CPU1_P0_FLT")
	)
	(via
		(at 344.0811 -337.012788)
		(size 0.49022)
		(drill 0.254)
		(layers "F.Cu" "B.Cu")
		(net "SW_P12V_AUX_PVDDCR_CPU1_P0_FLT")
	)
	(via
		(at 342.572848 -353.010216)
		(size 0.508)
		(drill 0.254)
		(layers "F.Cu" "B.Cu")
		(net "SW_P12V_AUX_PVDDCR_CPU1_P0_FLT")
	)
	(via
		(at 310.867806 -347.265752)
		(size 0.508)
		(drill 0.254)
		(layers "F.Cu" "B.Cu")
		(net "SW_P12V_AUX_PVDDCR_CPU1_P0_FLT")
	)
	(via
		(at 345.31554 -337.012788)
		(size 0.49022)
		(drill 0.254)
		(layers "F.Cu" "B.Cu")
		(net "SW_P12V_AUX_PVDDCR_CPU1_P0_FLT")
	)
	(via
		(at 352.974148 -341.922862)
		(size 0.49022)
		(drill 0.254)
		(layers "F.Cu" "B.Cu")
		(net "SW_P12V_AUX_PVDDCR_CPU1_P0_FLT")
	)
	(via
		(at 310.867806 -348.002352)
		(size 0.508)
		(drill 0.254)
		(layers "F.Cu" "B.Cu")
		(net "SW_P12V_AUX_PVDDCR_CPU1_P0_FLT")
	)
	(via
		(at 344.69832 -337.012788)
		(size 0.49022)
		(drill 0.254)
		(layers "F.Cu" "B.Cu")
		(net "SW_P12V_AUX_PVDDCR_CPU1_P0_FLT")
	)
	(via
		(at 346.017596 -337.885278)
		(size 0.508)
		(drill 0.254)
		(layers "F.Cu" "B.Cu")
		(net "SW_P12V_AUX_PVDDCR_CPU1_P0_FLT")
	)
	(via
		(at 337.686396 -338.571078)
		(size 0.508)
		(drill 0.254)
		(layers "F.Cu" "B.Cu")
		(net "SW_P12V_AUX_PVDDCR_CPU1_P0_FLT")
	)
	(via
		(at 319.65392 -336.983578)
		(size 0.49022)
		(drill 0.254)
		(layers "F.Cu" "B.Cu")
		(net "SW_P12V_AUX_PVDDCR_CPU1_P0_FLT")
	)
	(via
		(at 319.0367 -336.983578)
		(size 0.49022)
		(drill 0.254)
		(layers "F.Cu" "B.Cu")
		(net "SW_P12V_AUX_PVDDCR_CPU1_P0_FLT")
	)
	(via
		(at 312.407046 -349.518732)
		(size 0.508)
		(drill 0.254)
		(layers "F.Cu" "B.Cu")
		(net "SW_P12V_AUX_PVDDCR_CPU1_P0_FLT")
	)
	(via
		(at 329.878944 -338.171536)
		(size 0.508)
		(drill 0.254)
		(layers "F.Cu" "B.Cu")
		(net "SW_P12V_AUX_PVDDCR_CPU1_P0_FLT")
	)
	(via
		(at 337.280504 -335.517236)
		(size 0.508)
		(drill 0.254)
		(layers "F.Cu" "B.Cu")
		(net "SW_P12V_AUX_PVDDCR_CPU1_P0_FLT")
	)
	(via
		(at 337.280504 -336.253836)
		(size 0.508)
		(drill 0.254)
		(layers "F.Cu" "B.Cu")
		(net "SW_P12V_AUX_PVDDCR_CPU1_P0_FLT")
	)
	(via
		(at 310.004206 -348.704662)
		(size 0.49022)
		(drill 0.254)
		(layers "F.Cu" "B.Cu")
		(net "SW_P12V_AUX_PVDDCR_CPU1_P0_FLT")
	)
	(via
		(at 345.623896 -336.317336)
		(size 0.508)
		(drill 0.254)
		(layers "F.Cu" "B.Cu")
		(net "SW_P12V_AUX_PVDDCR_CPU1_P0_FLT")
	)
	(via
		(at 311.323482 -350.313752)
		(size 0.508)
		(drill 0.254)
		(layers "F.Cu" "B.Cu")
		(net "SW_P12V_AUX_PVDDCR_CPU1_P0_FLT")
	)
	(via
		(at 328.918824 -336.253836)
		(size 0.508)
		(drill 0.254)
		(layers "F.Cu" "B.Cu")
		(net "SW_P12V_AUX_PVDDCR_CPU1_P0_FLT")
	)
	(via
		(at 311.873646 -349.899732)
		(size 0.508)
		(drill 0.254)
		(layers "F.Cu" "B.Cu")
		(net "SW_P12V_AUX_PVDDCR_CPU1_P0_FLT")
	)
	(via
		(at 343.46515 -353.006152)
		(size 0.508)
		(drill 0.254)
		(layers "F.Cu" "B.Cu")
		(net "SW_P12V_AUX_PVDDCR_CPU1_P0_FLT")
	)
	(via
		(at 337.686396 -337.834478)
		(size 0.508)
		(drill 0.254)
		(layers "F.Cu" "B.Cu")
		(net "SW_P12V_AUX_PVDDCR_CPU1_P0_FLT")
	)
	(via
		(at 341.937848 -353.010216)
		(size 0.508)
		(drill 0.254)
		(layers "F.Cu" "B.Cu")
		(net "SW_P12V_AUX_PVDDCR_CPU1_P0_FLT")
	)
	(via
		(at 79.13243 -180.322474)
		(size 0.508)
		(drill 0.254)
		(layers "F.Cu" "B.Cu")
		(net "SW_P12V_AUX_PVDDCR_CPU0_P1_FLT")
	)
	(via
		(at 95.36303 -180.627274)
		(size 0.508)
		(drill 0.254)
		(layers "F.Cu" "B.Cu")
		(net "SW_P12V_AUX_PVDDCR_CPU0_P1_FLT")
	)
	(via
		(at 86.97087 -179.136802)
		(size 0.508)
		(drill 0.254)
		(layers "F.Cu" "B.Cu")
		(net "SW_P12V_AUX_PVDDCR_CPU0_P1_FLT")
	)
	(via
		(at 89.55913 -164.097716)
		(size 0.508)
		(drill 0.254)
		(layers "F.Cu" "B.Cu")
		(net "SW_P12V_AUX_PVDDCR_CPU0_P1_FLT")
	)
	(via
		(at 89.57945 -162.812476)
		(size 0.508)
		(drill 0.254)
		(layers "F.Cu" "B.Cu")
		(net "SW_P12V_AUX_PVDDCR_CPU0_P1_FLT")
	)
	(via
		(at 63.579248 -167.68572)
		(size 0.508)
		(drill 0.254)
		(layers "F.Cu" "B.Cu")
		(net "SW_P12V_AUX_PVDDCR_CPU0_P1_FLT")
	)
	(via
		(at 105.336848 -176.92116)
		(size 0.508)
		(drill 0.254)
		(layers "F.Cu" "B.Cu")
		(net "SW_P12V_AUX_PVDDCR_CPU0_P1_FLT")
	)
	(via
		(at 72.65289 -175.639222)
		(size 0.49022)
		(drill 0.254)
		(layers "F.Cu" "B.Cu")
		(net "SW_P12V_AUX_PVDDCR_CPU0_P1_FLT")
	)
	(via
		(at 78.85303 -178.036474)
		(size 0.508)
		(drill 0.254)
		(layers "F.Cu" "B.Cu")
		(net "SW_P12V_AUX_PVDDCR_CPU0_P1_FLT")
	)
	(via
		(at 87.52967 -180.254402)
		(size 0.508)
		(drill 0.254)
		(layers "F.Cu" "B.Cu")
		(net "SW_P12V_AUX_PVDDCR_CPU0_P1_FLT")
	)
	(via
		(at 88.054434 -179.814982)
		(size 0.508)
		(drill 0.254)
		(layers "F.Cu" "B.Cu")
		(net "SW_P12V_AUX_PVDDCR_CPU0_P1_FLT")
	)
	(via
		(at 87.03945 -162.812476)
		(size 0.508)
		(drill 0.254)
		(layers "F.Cu" "B.Cu")
		(net "SW_P12V_AUX_PVDDCR_CPU0_P1_FLT")
	)
	(via
		(at 88.94445 -162.812476)
		(size 0.508)
		(drill 0.254)
		(layers "F.Cu" "B.Cu")
		(net "SW_P12V_AUX_PVDDCR_CPU0_P1_FLT")
	)
	(via
		(at 88.054434 -179.078382)
		(size 0.508)
		(drill 0.254)
		(layers "F.Cu" "B.Cu")
		(net "SW_P12V_AUX_PVDDCR_CPU0_P1_FLT")
	)
	(via
		(at 106.14787 -176.183544)
		(size 0.49022)
		(drill 0.254)
		(layers "F.Cu" "B.Cu")
		(net "SW_P12V_AUX_PVDDCR_CPU0_P1_FLT")
	)
	(via
		(at 90.23985 -162.822636)
		(size 0.508)
		(drill 0.254)
		(layers "F.Cu" "B.Cu")
		(net "SW_P12V_AUX_PVDDCR_CPU0_P1_FLT")
	)
	(via
		(at 96.446594 -179.095654)
		(size 0.508)
		(drill 0.254)
		(layers "F.Cu" "B.Cu")
		(net "SW_P12V_AUX_PVDDCR_CPU0_P1_FLT")
	)
	(via
		(at 98.38309 -180.704744)
		(size 0.49022)
		(drill 0.254)
		(layers "F.Cu" "B.Cu")
		(net "SW_P12V_AUX_PVDDCR_CPU0_P1_FLT")
	)
	(via
		(at 95.89643 -179.509674)
		(size 0.508)
		(drill 0.254)
		(layers "F.Cu" "B.Cu")
		(net "SW_P12V_AUX_PVDDCR_CPU0_P1_FLT")
	)
	(via
		(at 96.980248 -182.13324)
		(size 0.508)
		(drill 0.254)
		(layers "F.Cu" "B.Cu")
		(net "SW_P12V_AUX_PVDDCR_CPU0_P1_FLT")
	)
	(via
		(at 81.59369 -180.755544)
		(size 0.49022)
		(drill 0.254)
		(layers "F.Cu" "B.Cu")
		(net "SW_P12V_AUX_PVDDCR_CPU0_P1_FLT")
	)
	(via
		(at 61.93663 -166.12616)
		(size 0.508)
		(drill 0.254)
		(layers "F.Cu" "B.Cu")
		(net "SW_P12V_AUX_PVDDCR_CPU0_P1_FLT")
	)
	(via
		(at 63.020194 -166.06774)
		(size 0.508)
		(drill 0.254)
		(layers "F.Cu" "B.Cu")
		(net "SW_P12V_AUX_PVDDCR_CPU0_P1_FLT")
	)
	(via
		(at 89.37371 -180.687472)
		(size 0.49022)
		(drill 0.254)
		(layers "F.Cu" "B.Cu")
		(net "SW_P12V_AUX_PVDDCR_CPU0_P1_FLT")
	)
	(via
		(at 97.76587 -180.704744)
		(size 0.49022)
		(drill 0.254)
		(layers "F.Cu" "B.Cu")
		(net "SW_P12V_AUX_PVDDCR_CPU0_P1_FLT")
	)
	(via
		(at 64.33947 -166.94023)
		(size 0.49022)
		(drill 0.254)
		(layers "F.Cu" "B.Cu")
		(net "SW_P12V_AUX_PVDDCR_CPU0_P1_FLT")
	)
	(via
		(at 63.72225 -166.94023)
		(size 0.49022)
		(drill 0.254)
		(layers "F.Cu" "B.Cu")
		(net "SW_P12V_AUX_PVDDCR_CPU0_P1_FLT")
	)
	(via
		(at 95.36303 -179.890674)
		(size 0.508)
		(drill 0.254)
		(layers "F.Cu" "B.Cu")
		(net "SW_P12V_AUX_PVDDCR_CPU0_P1_FLT")
	)
	(via
		(at 71.333614 -174.764954)
		(size 0.508)
		(drill 0.254)
		(layers "F.Cu" "B.Cu")
		(net "SW_P12V_AUX_PVDDCR_CPU0_P1_FLT")
	)
	(via
		(at 80.241648 -182.2196)
		(size 0.508)
		(drill 0.254)
		(layers "F.Cu" "B.Cu")
		(net "SW_P12V_AUX_PVDDCR_CPU0_P1_FLT")
	)
	(via
		(at 79.10703 -179.560474)
		(size 0.508)
		(drill 0.254)
		(layers "F.Cu" "B.Cu")
		(net "SW_P12V_AUX_PVDDCR_CPU0_P1_FLT")
	)
	(via
		(at 97.14865 -180.704744)
		(size 0.49022)
		(drill 0.254)
		(layers "F.Cu" "B.Cu")
		(net "SW_P12V_AUX_PVDDCR_CPU0_P1_FLT")
	)
	(via
		(at 63.020194 -165.33114)
		(size 0.508)
		(drill 0.254)
		(layers "F.Cu" "B.Cu")
		(net "SW_P12V_AUX_PVDDCR_CPU0_P1_FLT")
	)
	(via
		(at 96.980248 -181.39664)
		(size 0.508)
		(drill 0.254)
		(layers "F.Cu" "B.Cu")
		(net "SW_P12V_AUX_PVDDCR_CPU0_P1_FLT")
	)
	(via
		(at 87.67445 -162.812476)
		(size 0.508)
		(drill 0.254)
		(layers "F.Cu" "B.Cu")
		(net "SW_P12V_AUX_PVDDCR_CPU0_P1_FLT")
	)
	(via
		(at 105.336848 -177.65776)
		(size 0.508)
		(drill 0.254)
		(layers "F.Cu" "B.Cu")
		(net "SW_P12V_AUX_PVDDCR_CPU0_P1_FLT")
	)
	(via
		(at 88.30945 -162.812476)
		(size 0.508)
		(drill 0.254)
		(layers "F.Cu" "B.Cu")
		(net "SW_P12V_AUX_PVDDCR_CPU0_P1_FLT")
	)
	(via
		(at 87.03945 -163.447476)
		(size 0.508)
		(drill 0.254)
		(layers "F.Cu" "B.Cu")
		(net "SW_P12V_AUX_PVDDCR_CPU0_P1_FLT")
	)
	(via
		(at 88.94445 -163.447476)
		(size 0.508)
		(drill 0.254)
		(layers "F.Cu" "B.Cu")
		(net "SW_P12V_AUX_PVDDCR_CPU0_P1_FLT")
	)
	(via
		(at 62.49543 -166.50716)
		(size 0.508)
		(drill 0.254)
		(layers "F.Cu" "B.Cu")
		(net "SW_P12V_AUX_PVDDCR_CPU0_P1_FLT")
	)
	(via
		(at 104.30383 -175.750474)
		(size 0.508)
		(drill 0.254)
		(layers "F.Cu" "B.Cu")
		(net "SW_P12V_AUX_PVDDCR_CPU0_P1_FLT")
	)
	(via
		(at 80.35925 -180.755544)
		(size 0.49022)
		(drill 0.254)
		(layers "F.Cu" "B.Cu")
		(net "SW_P12V_AUX_PVDDCR_CPU0_P1_FLT")
	)
	(via
		(at 90.23985 -163.457636)
		(size 0.508)
		(drill 0.254)
		(layers "F.Cu" "B.Cu")
		(net "SW_P12V_AUX_PVDDCR_CPU0_P1_FLT")
	)
	(via
		(at 79.657194 -179.146454)
		(size 0.508)
		(drill 0.254)
		(layers "F.Cu" "B.Cu")
		(net "SW_P12V_AUX_PVDDCR_CPU0_P1_FLT")
	)
	(via
		(at 61.93663 -165.38956)
		(size 0.508)
		(drill 0.254)
		(layers "F.Cu" "B.Cu")
		(net "SW_P12V_AUX_PVDDCR_CPU0_P1_FLT")
	)
	(via
		(at 70.25005 -175.559974)
		(size 0.508)
		(drill 0.254)
		(layers "F.Cu" "B.Cu")
		(net "SW_P12V_AUX_PVDDCR_CPU0_P1_FLT")
	)
	(via
		(at 95.92183 -180.271674)
		(size 0.508)
		(drill 0.254)
		(layers "F.Cu" "B.Cu")
		(net "SW_P12V_AUX_PVDDCR_CPU0_P1_FLT")
	)
	(via
		(at 87.50427 -179.492402)
		(size 0.508)
		(drill 0.254)
		(layers "F.Cu" "B.Cu")
		(net "SW_P12V_AUX_PVDDCR_CPU0_P1_FLT")
	)
	(via
		(at 70.25005 -174.086774)
		(size 0.508)
		(drill 0.254)
		(layers "F.Cu" "B.Cu")
		(net "SW_P12V_AUX_PVDDCR_CPU0_P1_FLT")
	)
	(via
		(at 70.25005 -174.823374)
		(size 0.508)
		(drill 0.254)
		(layers "F.Cu" "B.Cu")
		(net "SW_P12V_AUX_PVDDCR_CPU0_P1_FLT")
	)
	(via
		(at 103.74503 -175.369474)
		(size 0.508)
		(drill 0.254)
		(layers "F.Cu" "B.Cu")
		(net "SW_P12V_AUX_PVDDCR_CPU0_P1_FLT")
	)
	(via
		(at 61.93663 -166.86276)
		(size 0.508)
		(drill 0.254)
		(layers "F.Cu" "B.Cu")
		(net "SW_P12V_AUX_PVDDCR_CPU0_P1_FLT")
	)
	(via
		(at 86.97087 -179.873402)
		(size 0.508)
		(drill 0.254)
		(layers "F.Cu" "B.Cu")
		(net "SW_P12V_AUX_PVDDCR_CPU0_P1_FLT")
	)
	(via
		(at 88.75649 -180.687472)
		(size 0.49022)
		(drill 0.254)
		(layers "F.Cu" "B.Cu")
		(net "SW_P12V_AUX_PVDDCR_CPU0_P1_FLT")
	)
	(via
		(at 62.47003 -165.74516)
		(size 0.508)
		(drill 0.254)
		(layers "F.Cu" "B.Cu")
		(net "SW_P12V_AUX_PVDDCR_CPU0_P1_FLT")
	)
	(via
		(at 72.03567 -175.639222)
		(size 0.49022)
		(drill 0.254)
		(layers "F.Cu" "B.Cu")
		(net "SW_P12V_AUX_PVDDCR_CPU0_P1_FLT")
	)
	(via
		(at 87.67445 -163.447476)
		(size 0.508)
		(drill 0.254)
		(layers "F.Cu" "B.Cu")
		(net "SW_P12V_AUX_PVDDCR_CPU0_P1_FLT")
	)
	(via
		(at 88.92413 -164.097716)
		(size 0.508)
		(drill 0.254)
		(layers "F.Cu" "B.Cu")
		(net "SW_P12V_AUX_PVDDCR_CPU0_P1_FLT")
	)
	(via
		(at 88.49233 -181.39664)
		(size 0.508)
		(drill 0.254)
		(layers "F.Cu" "B.Cu")
		(net "SW_P12V_AUX_PVDDCR_CPU0_P1_FLT")
	)
	(via
		(at 80.241648 -181.483)
		(size 0.508)
		(drill 0.254)
		(layers "F.Cu" "B.Cu")
		(net "SW_P12V_AUX_PVDDCR_CPU0_P1_FLT")
	)
	(via
		(at 104.828594 -174.574454)
		(size 0.508)
		(drill 0.254)
		(layers "F.Cu" "B.Cu")
		(net "SW_P12V_AUX_PVDDCR_CPU0_P1_FLT")
	)
	(via
		(at 78.85303 -178.798474)
		(size 0.508)
		(drill 0.254)
		(layers "F.Cu" "B.Cu")
		(net "SW_P12V_AUX_PVDDCR_CPU0_P1_FLT")
	)
	(via
		(at 104.828594 -175.311054)
		(size 0.508)
		(drill 0.254)
		(layers "F.Cu" "B.Cu")
		(net "SW_P12V_AUX_PVDDCR_CPU0_P1_FLT")
	)
	(via
		(at 71.892668 -176.37252)
		(size 0.508)
		(drill 0.254)
		(layers "F.Cu" "B.Cu")
		(net "SW_P12V_AUX_PVDDCR_CPU0_P1_FLT")
	)
	(via
		(at 96.446594 -179.832254)
		(size 0.508)
		(drill 0.254)
		(layers "F.Cu" "B.Cu")
		(net "SW_P12V_AUX_PVDDCR_CPU0_P1_FLT")
	)
	(via
		(at 88.30945 -163.447476)
		(size 0.508)
		(drill 0.254)
		(layers "F.Cu" "B.Cu")
		(net "SW_P12V_AUX_PVDDCR_CPU0_P1_FLT")
	)
	(via
		(at 90.21953 -164.107876)
		(size 0.508)
		(drill 0.254)
		(layers "F.Cu" "B.Cu")
		(net "SW_P12V_AUX_PVDDCR_CPU0_P1_FLT")
	)
	(via
		(at 73.27011 -175.639222)
		(size 0.49022)
		(drill 0.254)
		(layers "F.Cu" "B.Cu")
		(net "SW_P12V_AUX_PVDDCR_CPU0_P1_FLT")
	)
	(via
		(at 87.65413 -164.097716)
		(size 0.508)
		(drill 0.254)
		(layers "F.Cu" "B.Cu")
		(net "SW_P12V_AUX_PVDDCR_CPU0_P1_FLT")
	)
	(via
		(at 88.28913 -164.097716)
		(size 0.508)
		(drill 0.254)
		(layers "F.Cu" "B.Cu")
		(net "SW_P12V_AUX_PVDDCR_CPU0_P1_FLT")
	)
	(via
		(at 70.78345 -174.442374)
		(size 0.508)
		(drill 0.254)
		(layers "F.Cu" "B.Cu")
		(net "SW_P12V_AUX_PVDDCR_CPU0_P1_FLT")
	)
	(via
		(at 86.97087 -180.610002)
		(size 0.508)
		(drill 0.254)
		(layers "F.Cu" "B.Cu")
		(net "SW_P12V_AUX_PVDDCR_CPU0_P1_FLT")
	)
	(via
		(at 70.80885 -175.204374)
		(size 0.508)
		(drill 0.254)
		(layers "F.Cu" "B.Cu")
		(net "SW_P12V_AUX_PVDDCR_CPU0_P1_FLT")
	)
	(via
		(at 79.657194 -179.883054)
		(size 0.508)
		(drill 0.254)
		(layers "F.Cu" "B.Cu")
		(net "SW_P12V_AUX_PVDDCR_CPU0_P1_FLT")
	)
	(via
		(at 88.49233 -182.13324)
		(size 0.508)
		(drill 0.254)
		(layers "F.Cu" "B.Cu")
		(net "SW_P12V_AUX_PVDDCR_CPU0_P1_FLT")
	)
	(via
		(at 105.53065 -176.183544)
		(size 0.49022)
		(drill 0.254)
		(layers "F.Cu" "B.Cu")
		(net "SW_P12V_AUX_PVDDCR_CPU0_P1_FLT")
	)
	(via
		(at 79.403194 -178.384454)
		(size 0.508)
		(drill 0.254)
		(layers "F.Cu" "B.Cu")
		(net "SW_P12V_AUX_PVDDCR_CPU0_P1_FLT")
	)
	(via
		(at 71.892668 -177.10912)
		(size 0.508)
		(drill 0.254)
		(layers "F.Cu" "B.Cu")
		(net "SW_P12V_AUX_PVDDCR_CPU0_P1_FLT")
	)
	(via
		(at 64.95669 -166.94023)
		(size 0.49022)
		(drill 0.254)
		(layers "F.Cu" "B.Cu")
		(net "SW_P12V_AUX_PVDDCR_CPU0_P1_FLT")
	)
	(via
		(at 71.333614 -174.028354)
		(size 0.508)
		(drill 0.254)
		(layers "F.Cu" "B.Cu")
		(net "SW_P12V_AUX_PVDDCR_CPU0_P1_FLT")
	)
	(via
		(at 63.579248 -168.42232)
		(size 0.508)
		(drill 0.254)
		(layers "F.Cu" "B.Cu")
		(net "SW_P12V_AUX_PVDDCR_CPU0_P1_FLT")
	)
	(via
		(at 106.76509 -176.183544)
		(size 0.49022)
		(drill 0.254)
		(layers "F.Cu" "B.Cu")
		(net "SW_P12V_AUX_PVDDCR_CPU0_P1_FLT")
	)
	(via
		(at 89.99093 -180.687472)
		(size 0.49022)
		(drill 0.254)
		(layers "F.Cu" "B.Cu")
		(net "SW_P12V_AUX_PVDDCR_CPU0_P1_FLT")
	)
	(via
		(at 104.27843 -174.988474)
		(size 0.508)
		(drill 0.254)
		(layers "F.Cu" "B.Cu")
		(net "SW_P12V_AUX_PVDDCR_CPU0_P1_FLT")
	)
	(via
		(at 87.01913 -164.097716)
		(size 0.508)
		(drill 0.254)
		(layers "F.Cu" "B.Cu")
		(net "SW_P12V_AUX_PVDDCR_CPU0_P1_FLT")
	)
	(via
		(at 103.74503 -176.106074)
		(size 0.508)
		(drill 0.254)
		(layers "F.Cu" "B.Cu")
		(net "SW_P12V_AUX_PVDDCR_CPU0_P1_FLT")
	)
	(via
		(at 89.57945 -163.447476)
		(size 0.508)
		(drill 0.254)
		(layers "F.Cu" "B.Cu")
		(net "SW_P12V_AUX_PVDDCR_CPU0_P1_FLT")
	)
	(via
		(at 80.97647 -180.755544)
		(size 0.49022)
		(drill 0.254)
		(layers "F.Cu" "B.Cu")
		(net "SW_P12V_AUX_PVDDCR_CPU0_P1_FLT")
	)
	(via
		(at 103.74503 -174.632874)
		(size 0.508)
		(drill 0.254)
		(layers "F.Cu" "B.Cu")
		(net "SW_P12V_AUX_PVDDCR_CPU0_P1_FLT")
	)
	(via
		(at 95.36303 -179.154074)
		(size 0.508)
		(drill 0.254)
		(layers "F.Cu" "B.Cu")
		(net "SW_P12V_AUX_PVDDCR_CPU0_P1_FLT")
	)
	(via
		(at 352.322638 -165.956996)
		(size 0.508)
		(drill 0.254)
		(layers "F.Cu" "B.Cu")
		(net "SW_P12V_AUX_PVDDCR_CPU0_P0_FLT")
	)
	(via
		(at 369.52301 -180.322474)
		(size 0.508)
		(drill 0.254)
		(layers "F.Cu" "B.Cu")
		(net "SW_P12V_AUX_PVDDCR_CPU0_P0_FLT")
	)
	(via
		(at 368.044984 -163.89858)
		(size 0.508)
		(drill 0.254)
		(layers "F.Cu" "B.Cu")
		(net "SW_P12V_AUX_PVDDCR_CPU0_P0_FLT")
	)
	(via
		(at 378.450602 -179.883054)
		(size 0.508)
		(drill 0.254)
		(layers "F.Cu" "B.Cu")
		(net "SW_P12V_AUX_PVDDCR_CPU0_P0_FLT")
	)
	(via
		(at 345.100402 -158.278576)
		(size 0.508)
		(drill 0.254)
		(layers "F.Cu" "B.Cu")
		(net "SW_P12V_AUX_PVDDCR_CPU0_P0_FLT")
	)
	(via
		(at 360.603038 -174.232316)
		(size 0.508)
		(drill 0.254)
		(layers "F.Cu" "B.Cu")
		(net "SW_P12V_AUX_PVDDCR_CPU0_P0_FLT")
	)
	(via
		(at 344.575638 -158.717996)
		(size 0.508)
		(drill 0.254)
		(layers "F.Cu" "B.Cu")
		(net "SW_P12V_AUX_PVDDCR_CPU0_P0_FLT")
	)
	(via
		(at 369.949984 -163.89858)
		(size 0.508)
		(drill 0.254)
		(layers "F.Cu" "B.Cu")
		(net "SW_P12V_AUX_PVDDCR_CPU0_P0_FLT")
	)
	(via
		(at 386.781802 -179.883054)
		(size 0.508)
		(drill 0.254)
		(layers "F.Cu" "B.Cu")
		(net "SW_P12V_AUX_PVDDCR_CPU0_P0_FLT")
	)
	(via
		(at 386.257038 -180.322474)
		(size 0.508)
		(drill 0.254)
		(layers "F.Cu" "B.Cu")
		(net "SW_P12V_AUX_PVDDCR_CPU0_P0_FLT")
	)
	(via
		(at 380.387098 -180.755544)
		(size 0.49022)
		(drill 0.254)
		(layers "F.Cu" "B.Cu")
		(net "SW_P12V_AUX_PVDDCR_CPU0_P0_FLT")
	)
	(via
		(at 371.35943 -180.803804)
		(size 0.49022)
		(drill 0.254)
		(layers "F.Cu" "B.Cu")
		(net "SW_P12V_AUX_PVDDCR_CPU0_P0_FLT")
	)
	(via
		(at 379.769878 -180.755544)
		(size 0.49022)
		(drill 0.254)
		(layers "F.Cu" "B.Cu")
		(net "SW_P12V_AUX_PVDDCR_CPU0_P0_FLT")
	)
	(via
		(at 378.450602 -179.146454)
		(size 0.508)
		(drill 0.254)
		(layers "F.Cu" "B.Cu")
		(net "SW_P12V_AUX_PVDDCR_CPU0_P0_FLT")
	)
	(via
		(at 379.035056 -182.230776)
		(size 0.508)
		(drill 0.254)
		(layers "F.Cu" "B.Cu")
		(net "SW_P12V_AUX_PVDDCR_CPU0_P0_FLT")
	)
	(via
		(at 361.686602 -174.173896)
		(size 0.508)
		(drill 0.254)
		(layers "F.Cu" "B.Cu")
		(net "SW_P12V_AUX_PVDDCR_CPU0_P0_FLT")
	)
	(via
		(at 362.271056 -177.254916)
		(size 0.508)
		(drill 0.254)
		(layers "F.Cu" "B.Cu")
		(net "SW_P12V_AUX_PVDDCR_CPU0_P0_FLT")
	)
	(via
		(at 353.406202 -166.635176)
		(size 0.508)
		(drill 0.254)
		(layers "F.Cu" "B.Cu")
		(net "SW_P12V_AUX_PVDDCR_CPU0_P0_FLT")
	)
	(via
		(at 361.686602 -174.910496)
		(size 0.508)
		(drill 0.254)
		(layers "F.Cu" "B.Cu")
		(net "SW_P12V_AUX_PVDDCR_CPU0_P0_FLT")
	)
	(via
		(at 369.949984 -164.53358)
		(size 0.508)
		(drill 0.254)
		(layers "F.Cu" "B.Cu")
		(net "SW_P12V_AUX_PVDDCR_CPU0_P0_FLT")
	)
	(via
		(at 377.367038 -179.941474)
		(size 0.508)
		(drill 0.254)
		(layers "F.Cu" "B.Cu")
		(net "SW_P12V_AUX_PVDDCR_CPU0_P0_FLT")
	)
	(via
		(at 370.74221 -180.803804)
		(size 0.49022)
		(drill 0.254)
		(layers "F.Cu" "B.Cu")
		(net "SW_P12V_AUX_PVDDCR_CPU0_P0_FLT")
	)
	(via
		(at 377.367038 -179.204874)
		(size 0.508)
		(drill 0.254)
		(layers "F.Cu" "B.Cu")
		(net "SW_P12V_AUX_PVDDCR_CPU0_P0_FLT")
	)
	(via
		(at 352.322638 -166.693596)
		(size 0.508)
		(drill 0.254)
		(layers "F.Cu" "B.Cu")
		(net "SW_P12V_AUX_PVDDCR_CPU0_P0_FLT")
	)
	(via
		(at 353.406202 -165.898576)
		(size 0.508)
		(drill 0.254)
		(layers "F.Cu" "B.Cu")
		(net "SW_P12V_AUX_PVDDCR_CPU0_P0_FLT")
	)
	(via
		(at 347.036898 -159.151066)
		(size 0.49022)
		(drill 0.254)
		(layers "F.Cu" "B.Cu")
		(net "SW_P12V_AUX_PVDDCR_CPU0_P0_FLT")
	)
	(via
		(at 369.49761 -179.560474)
		(size 0.508)
		(drill 0.254)
		(layers "F.Cu" "B.Cu")
		(net "SW_P12V_AUX_PVDDCR_CPU0_P0_FLT")
	)
	(via
		(at 370.047774 -179.146454)
		(size 0.508)
		(drill 0.254)
		(layers "F.Cu" "B.Cu")
		(net "SW_P12V_AUX_PVDDCR_CPU0_P0_FLT")
	)
	(via
		(at 352.881438 -167.074596)
		(size 0.508)
		(drill 0.254)
		(layers "F.Cu" "B.Cu")
		(net "SW_P12V_AUX_PVDDCR_CPU0_P0_FLT")
	)
	(via
		(at 354.725478 -167.507666)
		(size 0.49022)
		(drill 0.254)
		(layers "F.Cu" "B.Cu")
		(net "SW_P12V_AUX_PVDDCR_CPU0_P0_FLT")
	)
	(via
		(at 370.686584 -163.89858)
		(size 0.508)
		(drill 0.254)
		(layers "F.Cu" "B.Cu")
		(net "SW_P12V_AUX_PVDDCR_CPU0_P0_FLT")
	)
	(via
		(at 369.314984 -163.89858)
		(size 0.508)
		(drill 0.254)
		(layers "F.Cu" "B.Cu")
		(net "SW_P12V_AUX_PVDDCR_CPU0_P0_FLT")
	)
	(via
		(at 369.49761 -178.798474)
		(size 0.508)
		(drill 0.254)
		(layers "F.Cu" "B.Cu")
		(net "SW_P12V_AUX_PVDDCR_CPU0_P0_FLT")
	)
	(via
		(at 353.990656 -168.982136)
		(size 0.508)
		(drill 0.254)
		(layers "F.Cu" "B.Cu")
		(net "SW_P12V_AUX_PVDDCR_CPU0_P0_FLT")
	)
	(via
		(at 345.684856 -160.633156)
		(size 0.508)
		(drill 0.254)
		(layers "F.Cu" "B.Cu")
		(net "SW_P12V_AUX_PVDDCR_CPU0_P0_FLT")
	)
	(via
		(at 363.013498 -175.859186)
		(size 0.49022)
		(drill 0.254)
		(layers "F.Cu" "B.Cu")
		(net "SW_P12V_AUX_PVDDCR_CPU0_P0_FLT")
	)
	(via
		(at 355.342698 -167.507666)
		(size 0.49022)
		(drill 0.254)
		(layers "F.Cu" "B.Cu")
		(net "SW_P12V_AUX_PVDDCR_CPU0_P0_FLT")
	)
	(via
		(at 387.366256 -181.494176)
		(size 0.508)
		(drill 0.254)
		(layers "F.Cu" "B.Cu")
		(net "SW_P12V_AUX_PVDDCR_CPU0_P0_FLT")
	)
	(via
		(at 387.483858 -180.755544)
		(size 0.49022)
		(drill 0.254)
		(layers "F.Cu" "B.Cu")
		(net "SW_P12V_AUX_PVDDCR_CPU0_P0_FLT")
	)
	(via
		(at 385.698238 -180.678074)
		(size 0.508)
		(drill 0.254)
		(layers "F.Cu" "B.Cu")
		(net "SW_P12V_AUX_PVDDCR_CPU0_P0_FLT")
	)
	(via
		(at 344.016838 -158.336996)
		(size 0.508)
		(drill 0.254)
		(layers "F.Cu" "B.Cu")
		(net "SW_P12V_AUX_PVDDCR_CPU0_P0_FLT")
	)
	(via
		(at 360.603038 -174.968916)
		(size 0.508)
		(drill 0.254)
		(layers "F.Cu" "B.Cu")
		(net "SW_P12V_AUX_PVDDCR_CPU0_P0_FLT")
	)
	(via
		(at 370.699284 -165.19398)
		(size 0.508)
		(drill 0.254)
		(layers "F.Cu" "B.Cu")
		(net "SW_P12V_AUX_PVDDCR_CPU0_P0_FLT")
	)
	(via
		(at 388.101078 -180.755544)
		(size 0.49022)
		(drill 0.254)
		(layers "F.Cu" "B.Cu")
		(net "SW_P12V_AUX_PVDDCR_CPU0_P0_FLT")
	)
	(via
		(at 370.686584 -164.53358)
		(size 0.508)
		(drill 0.254)
		(layers "F.Cu" "B.Cu")
		(net "SW_P12V_AUX_PVDDCR_CPU0_P0_FLT")
	)
	(via
		(at 370.047774 -179.883054)
		(size 0.508)
		(drill 0.254)
		(layers "F.Cu" "B.Cu")
		(net "SW_P12V_AUX_PVDDCR_CPU0_P0_FLT")
	)
	(via
		(at 345.100402 -157.541976)
		(size 0.508)
		(drill 0.254)
		(layers "F.Cu" "B.Cu")
		(net "SW_P12V_AUX_PVDDCR_CPU0_P0_FLT")
	)
	(via
		(at 371.97665 -180.803804)
		(size 0.49022)
		(drill 0.254)
		(layers "F.Cu" "B.Cu")
		(net "SW_P12V_AUX_PVDDCR_CPU0_P0_FLT")
	)
	(via
		(at 370.529358 -181.405276)
		(size 0.508)
		(drill 0.254)
		(layers "F.Cu" "B.Cu")
		(net "SW_P12V_AUX_PVDDCR_CPU0_P0_FLT")
	)
	(via
		(at 388.718298 -180.755544)
		(size 0.49022)
		(drill 0.254)
		(layers "F.Cu" "B.Cu")
		(net "SW_P12V_AUX_PVDDCR_CPU0_P0_FLT")
	)
	(via
		(at 344.550238 -157.955996)
		(size 0.508)
		(drill 0.254)
		(layers "F.Cu" "B.Cu")
		(net "SW_P12V_AUX_PVDDCR_CPU0_P0_FLT")
	)
	(via
		(at 345.802458 -159.151066)
		(size 0.49022)
		(drill 0.254)
		(layers "F.Cu" "B.Cu")
		(net "SW_P12V_AUX_PVDDCR_CPU0_P0_FLT")
	)
	(via
		(at 385.698238 -179.204874)
		(size 0.508)
		(drill 0.254)
		(layers "F.Cu" "B.Cu")
		(net "SW_P12V_AUX_PVDDCR_CPU0_P0_FLT")
	)
	(via
		(at 368.044984 -164.53358)
		(size 0.508)
		(drill 0.254)
		(layers "F.Cu" "B.Cu")
		(net "SW_P12V_AUX_PVDDCR_CPU0_P0_FLT")
	)
	(via
		(at 370.529358 -182.141876)
		(size 0.508)
		(drill 0.254)
		(layers "F.Cu" "B.Cu")
		(net "SW_P12V_AUX_PVDDCR_CPU0_P0_FLT")
	)
	(via
		(at 366.757204 -165.19398)
		(size 0.508)
		(drill 0.254)
		(layers "F.Cu" "B.Cu")
		(net "SW_P12V_AUX_PVDDCR_CPU0_P0_FLT")
	)
	(via
		(at 379.035056 -181.494176)
		(size 0.508)
		(drill 0.254)
		(layers "F.Cu" "B.Cu")
		(net "SW_P12V_AUX_PVDDCR_CPU0_P0_FLT")
	)
	(via
		(at 362.271056 -176.518316)
		(size 0.508)
		(drill 0.254)
		(layers "F.Cu" "B.Cu")
		(net "SW_P12V_AUX_PVDDCR_CPU0_P0_FLT")
	)
	(via
		(at 385.698238 -179.941474)
		(size 0.508)
		(drill 0.254)
		(layers "F.Cu" "B.Cu")
		(net "SW_P12V_AUX_PVDDCR_CPU0_P0_FLT")
	)
	(via
		(at 386.231638 -179.560474)
		(size 0.508)
		(drill 0.254)
		(layers "F.Cu" "B.Cu")
		(net "SW_P12V_AUX_PVDDCR_CPU0_P0_FLT")
	)
	(via
		(at 377.925838 -180.322474)
		(size 0.508)
		(drill 0.254)
		(layers "F.Cu" "B.Cu")
		(net "SW_P12V_AUX_PVDDCR_CPU0_P0_FLT")
	)
	(via
		(at 369.49761 -178.036474)
		(size 0.508)
		(drill 0.254)
		(layers "F.Cu" "B.Cu")
		(net "SW_P12V_AUX_PVDDCR_CPU0_P0_FLT")
	)
	(via
		(at 352.856038 -166.312596)
		(size 0.508)
		(drill 0.254)
		(layers "F.Cu" "B.Cu")
		(net "SW_P12V_AUX_PVDDCR_CPU0_P0_FLT")
	)
	(via
		(at 368.057684 -165.19398)
		(size 0.508)
		(drill 0.254)
		(layers "F.Cu" "B.Cu")
		(net "SW_P12V_AUX_PVDDCR_CPU0_P0_FLT")
	)
	(via
		(at 366.744504 -163.89858)
		(size 0.508)
		(drill 0.254)
		(layers "F.Cu" "B.Cu")
		(net "SW_P12V_AUX_PVDDCR_CPU0_P0_FLT")
	)
	(via
		(at 369.314984 -164.53358)
		(size 0.508)
		(drill 0.254)
		(layers "F.Cu" "B.Cu")
		(net "SW_P12V_AUX_PVDDCR_CPU0_P0_FLT")
	)
	(via
		(at 368.679984 -163.89858)
		(size 0.508)
		(drill 0.254)
		(layers "F.Cu" "B.Cu")
		(net "SW_P12V_AUX_PVDDCR_CPU0_P0_FLT")
	)
	(via
		(at 379.152658 -180.755544)
		(size 0.49022)
		(drill 0.254)
		(layers "F.Cu" "B.Cu")
		(net "SW_P12V_AUX_PVDDCR_CPU0_P0_FLT")
	)
	(via
		(at 368.692684 -165.19398)
		(size 0.508)
		(drill 0.254)
		(layers "F.Cu" "B.Cu")
		(net "SW_P12V_AUX_PVDDCR_CPU0_P0_FLT")
	)
	(via
		(at 367.379504 -164.53358)
		(size 0.508)
		(drill 0.254)
		(layers "F.Cu" "B.Cu")
		(net "SW_P12V_AUX_PVDDCR_CPU0_P0_FLT")
	)
	(via
		(at 368.96421 -179.204874)
		(size 0.508)
		(drill 0.254)
		(layers "F.Cu" "B.Cu")
		(net "SW_P12V_AUX_PVDDCR_CPU0_P0_FLT")
	)
	(via
		(at 387.366256 -182.230776)
		(size 0.508)
		(drill 0.254)
		(layers "F.Cu" "B.Cu")
		(net "SW_P12V_AUX_PVDDCR_CPU0_P0_FLT")
	)
	(via
		(at 361.161838 -175.349916)
		(size 0.508)
		(drill 0.254)
		(layers "F.Cu" "B.Cu")
		(net "SW_P12V_AUX_PVDDCR_CPU0_P0_FLT")
	)
	(via
		(at 368.679984 -164.53358)
		(size 0.508)
		(drill 0.254)
		(layers "F.Cu" "B.Cu")
		(net "SW_P12V_AUX_PVDDCR_CPU0_P0_FLT")
	)
	(via
		(at 352.322638 -167.430196)
		(size 0.508)
		(drill 0.254)
		(layers "F.Cu" "B.Cu")
		(net "SW_P12V_AUX_PVDDCR_CPU0_P0_FLT")
	)
	(via
		(at 369.962684 -165.19398)
		(size 0.508)
		(drill 0.254)
		(layers "F.Cu" "B.Cu")
		(net "SW_P12V_AUX_PVDDCR_CPU0_P0_FLT")
	)
	(via
		(at 366.744504 -164.53358)
		(size 0.508)
		(drill 0.254)
		(layers "F.Cu" "B.Cu")
		(net "SW_P12V_AUX_PVDDCR_CPU0_P0_FLT")
	)
	(via
		(at 367.392204 -165.19398)
		(size 0.508)
		(drill 0.254)
		(layers "F.Cu" "B.Cu")
		(net "SW_P12V_AUX_PVDDCR_CPU0_P0_FLT")
	)
	(via
		(at 344.016838 -157.600396)
		(size 0.508)
		(drill 0.254)
		(layers "F.Cu" "B.Cu")
		(net "SW_P12V_AUX_PVDDCR_CPU0_P0_FLT")
	)
	(via
		(at 367.379504 -163.89858)
		(size 0.508)
		(drill 0.254)
		(layers "F.Cu" "B.Cu")
		(net "SW_P12V_AUX_PVDDCR_CPU0_P0_FLT")
	)
	(via
		(at 386.781802 -179.146454)
		(size 0.508)
		(drill 0.254)
		(layers "F.Cu" "B.Cu")
		(net "SW_P12V_AUX_PVDDCR_CPU0_P0_FLT")
	)
	(via
		(at 354.108258 -167.507666)
		(size 0.49022)
		(drill 0.254)
		(layers "F.Cu" "B.Cu")
		(net "SW_P12V_AUX_PVDDCR_CPU0_P0_FLT")
	)
	(via
		(at 377.900438 -179.560474)
		(size 0.508)
		(drill 0.254)
		(layers "F.Cu" "B.Cu")
		(net "SW_P12V_AUX_PVDDCR_CPU0_P0_FLT")
	)
	(via
		(at 361.136438 -174.587916)
		(size 0.508)
		(drill 0.254)
		(layers "F.Cu" "B.Cu")
		(net "SW_P12V_AUX_PVDDCR_CPU0_P0_FLT")
	)
	(via
		(at 369.327684 -165.19398)
		(size 0.508)
		(drill 0.254)
		(layers "F.Cu" "B.Cu")
		(net "SW_P12V_AUX_PVDDCR_CPU0_P0_FLT")
	)
	(via
		(at 362.396278 -175.859186)
		(size 0.49022)
		(drill 0.254)
		(layers "F.Cu" "B.Cu")
		(net "SW_P12V_AUX_PVDDCR_CPU0_P0_FLT")
	)
	(via
		(at 344.016838 -159.073596)
		(size 0.508)
		(drill 0.254)
		(layers "F.Cu" "B.Cu")
		(net "SW_P12V_AUX_PVDDCR_CPU0_P0_FLT")
	)
	(via
		(at 353.990656 -168.245536)
		(size 0.508)
		(drill 0.254)
		(layers "F.Cu" "B.Cu")
		(net "SW_P12V_AUX_PVDDCR_CPU0_P0_FLT")
	)
	(via
		(at 377.367038 -180.678074)
		(size 0.508)
		(drill 0.254)
		(layers "F.Cu" "B.Cu")
		(net "SW_P12V_AUX_PVDDCR_CPU0_P0_FLT")
	)
	(via
		(at 345.684856 -159.896556)
		(size 0.508)
		(drill 0.254)
		(layers "F.Cu" "B.Cu")
		(net "SW_P12V_AUX_PVDDCR_CPU0_P0_FLT")
	)
	(via
		(at 360.603038 -175.705516)
		(size 0.508)
		(drill 0.254)
		(layers "F.Cu" "B.Cu")
		(net "SW_P12V_AUX_PVDDCR_CPU0_P0_FLT")
	)
	(via
		(at 346.419678 -159.151066)
		(size 0.49022)
		(drill 0.254)
		(layers "F.Cu" "B.Cu")
		(net "SW_P12V_AUX_PVDDCR_CPU0_P0_FLT")
	)
	(via
		(at 363.630718 -175.859186)
		(size 0.49022)
		(drill 0.254)
		(layers "F.Cu" "B.Cu")
		(net "SW_P12V_AUX_PVDDCR_CPU0_P0_FLT")
	)
	(via
		(at 79.824834 -150.631652)
		(size 0.762)
		(drill 0.381)
		(layers "F.Cu" "B.Cu")
		(net "SW_P12V_AUX_PVDD18_S5_P1_FLT")
	)
	(via
		(at 193.28892 -352.563684)
		(size 0.508)
		(drill 0.254)
		(layers "F.Cu" "B.Cu")
		(net "SW_P12V_AUX_PVDD11_S3_P1_FLT")
	)
	(via
		(at 186.630818 -353.361244)
		(size 0.508)
		(drill 0.254)
		(layers "F.Cu" "B.Cu")
		(net "SW_P12V_AUX_PVDD11_S3_P1_FLT")
	)
	(via
		(at 186.796172 -362.234988)
		(size 0.508)
		(drill 0.254)
		(layers "F.Cu" "B.Cu")
		(net "SW_P12V_AUX_PVDD11_S3_P1_FLT")
	)
	(via
		(at 184.962292 -351.822004)
		(size 0.508)
		(drill 0.254)
		(layers "F.Cu" "B.Cu")
		(net "SW_P12V_AUX_PVDD11_S3_P1_FLT")
	)
	(via
		(at 194.957446 -354.123244)
		(size 0.508)
		(drill 0.254)
		(layers "F.Cu" "B.Cu")
		(net "SW_P12V_AUX_PVDD11_S3_P1_FLT")
	)
	(via
		(at 186.034172 -362.234988)
		(size 0.508)
		(drill 0.254)
		(layers "F.Cu" "B.Cu")
		(net "SW_P12V_AUX_PVDD11_S3_P1_FLT")
	)
	(via
		(at 185.547254 -354.156264)
		(size 0.508)
		(drill 0.254)
		(layers "F.Cu" "B.Cu")
		(net "SW_P12V_AUX_PVDD11_S3_P1_FLT")
	)
	(via
		(at 184.962292 -352.558604)
		(size 0.508)
		(drill 0.254)
		(layers "F.Cu" "B.Cu")
		(net "SW_P12V_AUX_PVDD11_S3_P1_FLT")
	)
	(via
		(at 192.554606 -353.309174)
		(size 0.49022)
		(drill 0.254)
		(layers "F.Cu" "B.Cu")
		(net "SW_P12V_AUX_PVDD11_S3_P1_FLT")
	)
	(via
		(at 186.034172 -360.710988)
		(size 0.508)
		(drill 0.254)
		(layers "F.Cu" "B.Cu")
		(net "SW_P12V_AUX_PVDD11_S3_P1_FLT")
	)
	(via
		(at 185.547254 -354.892864)
		(size 0.508)
		(drill 0.254)
		(layers "F.Cu" "B.Cu")
		(net "SW_P12V_AUX_PVDD11_S3_P1_FLT")
	)
	(via
		(at 194.957446 -354.859844)
		(size 0.508)
		(drill 0.254)
		(layers "F.Cu" "B.Cu")
		(net "SW_P12V_AUX_PVDD11_S3_P1_FLT")
	)
	(via
		(at 184.227978 -353.283774)
		(size 0.49022)
		(drill 0.254)
		(layers "F.Cu" "B.Cu")
		(net "SW_P12V_AUX_PVDD11_S3_P1_FLT")
	)
	(via
		(at 186.630818 -354.097844)
		(size 0.508)
		(drill 0.254)
		(layers "F.Cu" "B.Cu")
		(net "SW_P12V_AUX_PVDD11_S3_P1_FLT")
	)
	(via
		(at 193.28892 -351.827084)
		(size 0.508)
		(drill 0.254)
		(layers "F.Cu" "B.Cu")
		(net "SW_P12V_AUX_PVDD11_S3_P1_FLT")
	)
	(via
		(at 184.845198 -353.283774)
		(size 0.49022)
		(drill 0.254)
		(layers "F.Cu" "B.Cu")
		(net "SW_P12V_AUX_PVDD11_S3_P1_FLT")
	)
	(via
		(at 193.873882 -354.918264)
		(size 0.508)
		(drill 0.254)
		(layers "F.Cu" "B.Cu")
		(net "SW_P12V_AUX_PVDD11_S3_P1_FLT")
	)
	(via
		(at 193.873882 -354.181664)
		(size 0.508)
		(drill 0.254)
		(layers "F.Cu" "B.Cu")
		(net "SW_P12V_AUX_PVDD11_S3_P1_FLT")
	)
	(via
		(at 194.398646 -353.742244)
		(size 0.508)
		(drill 0.254)
		(layers "F.Cu" "B.Cu")
		(net "SW_P12V_AUX_PVDD11_S3_P1_FLT")
	)
	(via
		(at 186.630818 -354.834444)
		(size 0.508)
		(drill 0.254)
		(layers "F.Cu" "B.Cu")
		(net "SW_P12V_AUX_PVDD11_S3_P1_FLT")
	)
	(via
		(at 194.424046 -354.504244)
		(size 0.508)
		(drill 0.254)
		(layers "F.Cu" "B.Cu")
		(net "SW_P12V_AUX_PVDD11_S3_P1_FLT")
	)
	(via
		(at 186.796172 -361.472988)
		(size 0.508)
		(drill 0.254)
		(layers "F.Cu" "B.Cu")
		(net "SW_P12V_AUX_PVDD11_S3_P1_FLT")
	)
	(via
		(at 186.072018 -353.716844)
		(size 0.508)
		(drill 0.254)
		(layers "F.Cu" "B.Cu")
		(net "SW_P12V_AUX_PVDD11_S3_P1_FLT")
	)
	(via
		(at 186.097418 -354.478844)
		(size 0.508)
		(drill 0.254)
		(layers "F.Cu" "B.Cu")
		(net "SW_P12V_AUX_PVDD11_S3_P1_FLT")
	)
	(via
		(at 183.610758 -353.283774)
		(size 0.49022)
		(drill 0.254)
		(layers "F.Cu" "B.Cu")
		(net "SW_P12V_AUX_PVDD11_S3_P1_FLT")
	)
	(via
		(at 191.937386 -353.309174)
		(size 0.49022)
		(drill 0.254)
		(layers "F.Cu" "B.Cu")
		(net "SW_P12V_AUX_PVDD11_S3_P1_FLT")
	)
	(via
		(at 186.034172 -361.472988)
		(size 0.508)
		(drill 0.254)
		(layers "F.Cu" "B.Cu")
		(net "SW_P12V_AUX_PVDD11_S3_P1_FLT")
	)
	(via
		(at 193.171826 -353.309174)
		(size 0.49022)
		(drill 0.254)
		(layers "F.Cu" "B.Cu")
		(net "SW_P12V_AUX_PVDD11_S3_P1_FLT")
	)
	(via
		(at 194.957446 -353.386644)
		(size 0.508)
		(drill 0.254)
		(layers "F.Cu" "B.Cu")
		(net "SW_P12V_AUX_PVDD11_S3_P1_FLT")
	)
	(via
		(at 186.796172 -360.710988)
		(size 0.508)
		(drill 0.254)
		(layers "F.Cu" "B.Cu")
		(net "SW_P12V_AUX_PVDD11_S3_P1_FLT")
	)
	(via
		(at 426.8216 -354.29825)
		(size 0.508)
		(drill 0.254)
		(layers "F.Cu" "B.Cu")
		(net "SW_P12V_AUX_PVDD11_S3_P0_FLT")
	)
	(via
		(at 436.231538 -360.734102)
		(size 0.508)
		(drill 0.254)
		(layers "F.Cu" "B.Cu")
		(net "SW_P12V_AUX_PVDD11_S3_P0_FLT")
	)
	(via
		(at 435.122828 -353.56165)
		(size 0.508)
		(drill 0.254)
		(layers "F.Cu" "B.Cu")
		(net "SW_P12V_AUX_PVDD11_S3_P0_FLT")
	)
	(via
		(at 427.355 -353.18065)
		(size 0.508)
		(drill 0.254)
		(layers "F.Cu" "B.Cu")
		(net "SW_P12V_AUX_PVDD11_S3_P0_FLT")
	)
	(via
		(at 426.271436 -353.97567)
		(size 0.508)
		(drill 0.254)
		(layers "F.Cu" "B.Cu")
		(net "SW_P12V_AUX_PVDD11_S3_P0_FLT")
	)
	(via
		(at 433.278788 -353.12858)
		(size 0.49022)
		(drill 0.254)
		(layers "F.Cu" "B.Cu")
		(net "SW_P12V_AUX_PVDD11_S3_P0_FLT")
	)
	(via
		(at 435.681628 -353.20605)
		(size 0.508)
		(drill 0.254)
		(layers "F.Cu" "B.Cu")
		(net "SW_P12V_AUX_PVDD11_S3_P0_FLT")
	)
	(via
		(at 427.355 -353.91725)
		(size 0.508)
		(drill 0.254)
		(layers "F.Cu" "B.Cu")
		(net "SW_P12V_AUX_PVDD11_S3_P0_FLT")
	)
	(via
		(at 435.469538 -360.734102)
		(size 0.508)
		(drill 0.254)
		(layers "F.Cu" "B.Cu")
		(net "SW_P12V_AUX_PVDD11_S3_P0_FLT")
	)
	(via
		(at 426.7962 -353.53625)
		(size 0.508)
		(drill 0.254)
		(layers "F.Cu" "B.Cu")
		(net "SW_P12V_AUX_PVDD11_S3_P0_FLT")
	)
	(via
		(at 434.013102 -351.64649)
		(size 0.508)
		(drill 0.254)
		(layers "F.Cu" "B.Cu")
		(net "SW_P12V_AUX_PVDD11_S3_P0_FLT")
	)
	(via
		(at 433.896008 -353.12858)
		(size 0.49022)
		(drill 0.254)
		(layers "F.Cu" "B.Cu")
		(net "SW_P12V_AUX_PVDD11_S3_P0_FLT")
	)
	(via
		(at 424.95216 -353.10318)
		(size 0.49022)
		(drill 0.254)
		(layers "F.Cu" "B.Cu")
		(net "SW_P12V_AUX_PVDD11_S3_P0_FLT")
	)
	(via
		(at 434.013102 -352.38309)
		(size 0.508)
		(drill 0.254)
		(layers "F.Cu" "B.Cu")
		(net "SW_P12V_AUX_PVDD11_S3_P0_FLT")
	)
	(via
		(at 425.56938 -353.10318)
		(size 0.49022)
		(drill 0.254)
		(layers "F.Cu" "B.Cu")
		(net "SW_P12V_AUX_PVDD11_S3_P0_FLT")
	)
	(via
		(at 436.231538 -361.496102)
		(size 0.508)
		(drill 0.254)
		(layers "F.Cu" "B.Cu")
		(net "SW_P12V_AUX_PVDD11_S3_P0_FLT")
	)
	(via
		(at 434.598064 -354.00107)
		(size 0.508)
		(drill 0.254)
		(layers "F.Cu" "B.Cu")
		(net "SW_P12V_AUX_PVDD11_S3_P0_FLT")
	)
	(via
		(at 432.661568 -353.12858)
		(size 0.49022)
		(drill 0.254)
		(layers "F.Cu" "B.Cu")
		(net "SW_P12V_AUX_PVDD11_S3_P0_FLT")
	)
	(via
		(at 436.580026 -355.742494)
		(size 0.762)
		(drill 0.381)
		(layers "F.Cu" "B.Cu")
		(net "SW_P12V_AUX_PVDD11_S3_P0_FLT")
	)
	(via
		(at 427.355 -354.65385)
		(size 0.508)
		(drill 0.254)
		(layers "F.Cu" "B.Cu")
		(net "SW_P12V_AUX_PVDD11_S3_P0_FLT")
	)
	(via
		(at 435.469538 -359.972102)
		(size 0.508)
		(drill 0.254)
		(layers "F.Cu" "B.Cu")
		(net "SW_P12V_AUX_PVDD11_S3_P0_FLT")
	)
	(via
		(at 425.686474 -351.62109)
		(size 0.508)
		(drill 0.254)
		(layers "F.Cu" "B.Cu")
		(net "SW_P12V_AUX_PVDD11_S3_P0_FLT")
	)
	(via
		(at 426.271436 -354.71227)
		(size 0.508)
		(drill 0.254)
		(layers "F.Cu" "B.Cu")
		(net "SW_P12V_AUX_PVDD11_S3_P0_FLT")
	)
	(via
		(at 435.469538 -361.496102)
		(size 0.508)
		(drill 0.254)
		(layers "F.Cu" "B.Cu")
		(net "SW_P12V_AUX_PVDD11_S3_P0_FLT")
	)
	(via
		(at 435.681628 -353.94265)
		(size 0.508)
		(drill 0.254)
		(layers "F.Cu" "B.Cu")
		(net "SW_P12V_AUX_PVDD11_S3_P0_FLT")
	)
	(via
		(at 434.598064 -354.73767)
		(size 0.508)
		(drill 0.254)
		(layers "F.Cu" "B.Cu")
		(net "SW_P12V_AUX_PVDD11_S3_P0_FLT")
	)
	(via
		(at 425.686474 -352.35769)
		(size 0.508)
		(drill 0.254)
		(layers "F.Cu" "B.Cu")
		(net "SW_P12V_AUX_PVDD11_S3_P0_FLT")
	)
	(via
		(at 424.33494 -353.10318)
		(size 0.49022)
		(drill 0.254)
		(layers "F.Cu" "B.Cu")
		(net "SW_P12V_AUX_PVDD11_S3_P0_FLT")
	)
	(via
		(at 435.681628 -354.67925)
		(size 0.508)
		(drill 0.254)
		(layers "F.Cu" "B.Cu")
		(net "SW_P12V_AUX_PVDD11_S3_P0_FLT")
	)
	(via
		(at 435.148228 -354.32365)
		(size 0.508)
		(drill 0.254)
		(layers "F.Cu" "B.Cu")
		(net "SW_P12V_AUX_PVDD11_S3_P0_FLT")
	)
	(via
		(at 436.231538 -359.972102)
		(size 0.508)
		(drill 0.254)
		(layers "F.Cu" "B.Cu")
		(net "SW_P12V_AUX_PVDD11_S3_P0_FLT")
	)
	(segment
		(start 352.7044 -430.590452)
		(end 351.4852 -430.590452)
		(width 0.10668)
		(layer "F.Cu")
		(net "SWB_HSC_PWRGD_N")
	)
	(segment
		(start 352.135186 -429.356012)
		(end 351.4852 -429.356012)
		(width 0.10668)
		(layer "F.Cu")
		(net "SWB_HSC_PWRGD_N")
	)
	(segment
		(start 351.4852 -429.356012)
		(end 351.4852 -430.590452)
		(width 0.10668)
		(layer "F.Cu")
		(net "SWB_HSC_PWRGD_N")
	)
	(via
		(at 351.4852 -430.590452)
		(size 0.762)
		(drill 0.381)
		(layers "F.Cu" "B.Cu")
		(net "SWB_HSC_PWRGD_N")
	)
	(segment
		(start 352.785172 -424.279314)
		(end 352.785172 -425.295314)
		(width 0.10668)
		(layer "F.Cu")
		(net "SWB_HSC_PWRGD_ISO")
	)
	(segment
		(start 352.785172 -425.295314)
		(end 352.785172 -427.456092)
		(width 0.10668)
		(layer "F.Cu")
		(net "SWB_HSC_PWRGD_ISO")
	)
	(segment
		(start 352.785172 -423.356532)
		(end 352.785172 -424.279314)
		(width 0.10668)
		(layer "F.Cu")
		(net "SWB_HSC_PWRGD_ISO")
	)
	(segment
		(start 353.247452 -422.894252)
		(end 352.785172 -423.356532)
		(width 0.10668)
		(layer "F.Cu")
		(net "SWB_HSC_PWRGD_ISO")
	)
	(via
		(at 433.097432 -368.750596)
		(size 0.508)
		(drill 0.254)
		(layers "F.Cu" "B.Cu")
		(net "SWB_HSC_PWRGD_ISO")
	)
	(via
		(at 202.520804 -121.753376)
		(size 0.508)
		(drill 0.254)
		(layers "F.Cu" "B.Cu")
		(net "SWB_HSC_PWRGD_ISO")
	)
	(via
		(at 355.727 -116.427758)
		(size 0.508)
		(drill 0.254)
		(layers "F.Cu" "B.Cu")
		(net "SWB_HSC_PWRGD_ISO")
	)
	(via
		(at 353.247452 -422.894252)
		(size 0.508)
		(drill 0.254)
		(layers "F.Cu" "B.Cu")
		(net "SWB_HSC_PWRGD_ISO")
	)
	(via
		(at 393.077192 -386.09778)
		(size 0.508)
		(drill 0.254)
		(layers "F.Cu" "B.Cu")
		(net "SWB_HSC_PWRGD_ISO")
	)
	(segment
		(start 444.719456 -367.97488)
		(end 448.512946 -364.18139)
		(width 0.10668)
		(layer "B.Cu")
		(net "SWB_HSC_PWRGD_ISO")
	)
	(segment
		(start 201.352658 -121.753376)
		(end 202.520804 -121.753376)
		(width 0.10668)
		(layer "B.Cu")
		(net "SWB_HSC_PWRGD_ISO")
	)
	(segment
		(start 440.549792 -367.97488)
		(end 444.719456 -367.97488)
		(width 0.10668)
		(layer "B.Cu")
		(net "SWB_HSC_PWRGD_ISO")
	)
	(segment
		(start 356.26675 -115.888008)
		(end 355.727 -116.427758)
		(width 0.10668)
		(layer "B.Cu")
		(net "SWB_HSC_PWRGD_ISO")
	)
	(segment
		(start 450.722492 -145.880328)
		(end 421.779192 -116.937028)
		(width 0.10668)
		(layer "B.Cu")
		(net "SWB_HSC_PWRGD_ISO")
	)
	(segment
		(start 372.751604 -118.242334)
		(end 363.318044 -118.242334)
		(width 0.10668)
		(layer "B.Cu")
		(net "SWB_HSC_PWRGD_ISO")
	)
	(segment
		(start 421.779192 -116.937028)
		(end 374.05691 -116.937028)
		(width 0.10668)
		(layer "B.Cu")
		(net "SWB_HSC_PWRGD_ISO")
	)
	(segment
		(start 461.161384 -187.419234)
		(end 450.722492 -176.980342)
		(width 0.10668)
		(layer "B.Cu")
		(net "SWB_HSC_PWRGD_ISO")
	)
	(segment
		(start 448.512946 -364.18139)
		(end 448.512946 -342.894412)
		(width 0.10668)
		(layer "B.Cu")
		(net "SWB_HSC_PWRGD_ISO")
	)
	(segment
		(start 374.05691 -116.937028)
		(end 372.751604 -118.242334)
		(width 0.10668)
		(layer "B.Cu")
		(net "SWB_HSC_PWRGD_ISO")
	)
	(segment
		(start 439.774076 -368.750596)
		(end 440.549792 -367.97488)
		(width 0.10668)
		(layer "B.Cu")
		(net "SWB_HSC_PWRGD_ISO")
	)
	(segment
		(start 448.512946 -342.894412)
		(end 461.161384 -330.245974)
		(width 0.10668)
		(layer "B.Cu")
		(net "SWB_HSC_PWRGD_ISO")
	)
	(segment
		(start 360.963718 -115.888008)
		(end 356.26675 -115.888008)
		(width 0.10668)
		(layer "B.Cu")
		(net "SWB_HSC_PWRGD_ISO")
	)
	(segment
		(start 363.318044 -118.242334)
		(end 360.963718 -115.888008)
		(width 0.10668)
		(layer "B.Cu")
		(net "SWB_HSC_PWRGD_ISO")
	)
	(segment
		(start 461.161384 -330.245974)
		(end 461.161384 -187.419234)
		(width 0.10668)
		(layer "B.Cu")
		(net "SWB_HSC_PWRGD_ISO")
	)
	(segment
		(start 450.722492 -176.980342)
		(end 450.722492 -145.880328)
		(width 0.10668)
		(layer "B.Cu")
		(net "SWB_HSC_PWRGD_ISO")
	)
	(segment
		(start 433.097432 -368.750596)
		(end 439.774076 -368.750596)
		(width 0.10668)
		(layer "B.Cu")
		(net "SWB_HSC_PWRGD_ISO")
	)
	(segment
		(start 392.452606 -383.928366)
		(end 393.011914 -383.928366)
		(width 0.11684)
		(layer "In2.Cu")
		(net "SWB_HSC_PWRGD_ISO")
	)
	(segment
		(start 396.470632 -377.502674)
		(end 398.215866 -375.75744)
		(width 0.11684)
		(layer "In2.Cu")
		(net "SWB_HSC_PWRGD_ISO")
	)
	(segment
		(start 392.103356 -385.513326)
		(end 392.103356 -384.277616)
		(width 0.11684)
		(layer "In2.Cu")
		(net "SWB_HSC_PWRGD_ISO")
	)
	(segment
		(start 392.103356 -384.277616)
		(end 392.452606 -383.928366)
		(width 0.11684)
		(layer "In2.Cu")
		(net "SWB_HSC_PWRGD_ISO")
	)
	(segment
		(start 393.011914 -383.928366)
		(end 396.470632 -380.469648)
		(width 0.11684)
		(layer "In2.Cu")
		(net "SWB_HSC_PWRGD_ISO")
	)
	(segment
		(start 396.470632 -380.469648)
		(end 396.470632 -377.502674)
		(width 0.11684)
		(layer "In2.Cu")
		(net "SWB_HSC_PWRGD_ISO")
	)
	(segment
		(start 392.68781 -386.09778)
		(end 392.103356 -385.513326)
		(width 0.11684)
		(layer "In2.Cu")
		(net "SWB_HSC_PWRGD_ISO")
	)
	(segment
		(start 393.077192 -386.09778)
		(end 392.68781 -386.09778)
		(width 0.11684)
		(layer "In2.Cu")
		(net "SWB_HSC_PWRGD_ISO")
	)
	(segment
		(start 398.215866 -375.75744)
		(end 423.693082 -375.75744)
		(width 0.11684)
		(layer "In2.Cu")
		(net "SWB_HSC_PWRGD_ISO")
	)
	(segment
		(start 423.693082 -375.75744)
		(end 428.178214 -371.272308)
		(width 0.11684)
		(layer "In2.Cu")
		(net "SWB_HSC_PWRGD_ISO")
	)
	(segment
		(start 428.178214 -371.272308)
		(end 430.57572 -371.272308)
		(width 0.11684)
		(layer "In2.Cu")
		(net "SWB_HSC_PWRGD_ISO")
	)
	(segment
		(start 430.57572 -371.272308)
		(end 433.097432 -368.750596)
		(width 0.11684)
		(layer "In2.Cu")
		(net "SWB_HSC_PWRGD_ISO")
	)
	(segment
		(start 202.72502 -121.753376)
		(end 203.627736 -120.85066)
		(width 0.11684)
		(layer "In6.Cu")
		(net "SWB_HSC_PWRGD_ISO")
	)
	(segment
		(start 206.323438 -120.233948)
		(end 211.074 -120.233948)
		(width 0.11684)
		(layer "In6.Cu")
		(net "SWB_HSC_PWRGD_ISO")
	)
	(segment
		(start 312.05932 -114.308128)
		(end 312.856372 -115.10518)
		(width 0.11684)
		(layer "In6.Cu")
		(net "SWB_HSC_PWRGD_ISO")
	)
	(segment
		(start 223.25838 -118.133622)
		(end 224.056956 -117.335046)
		(width 0.11684)
		(layer "In6.Cu")
		(net "SWB_HSC_PWRGD_ISO")
	)
	(segment
		(start 269.021306 -113.553748)
		(end 274.468336 -113.553748)
		(width 0.11684)
		(layer "In6.Cu")
		(net "SWB_HSC_PWRGD_ISO")
	)
	(segment
		(start 318.741298 -114.308128)
		(end 320.860928 -116.427758)
		(width 0.11684)
		(layer "In6.Cu")
		(net "SWB_HSC_PWRGD_ISO")
	)
	(segment
		(start 203.627736 -120.85066)
		(end 205.706726 -120.85066)
		(width 0.11684)
		(layer "In6.Cu")
		(net "SWB_HSC_PWRGD_ISO")
	)
	(segment
		(start 274.75053 -113.835942)
		(end 286.105346 -113.835942)
		(width 0.11684)
		(layer "In6.Cu")
		(net "SWB_HSC_PWRGD_ISO")
	)
	(segment
		(start 249.21718 -112.34166)
		(end 267.809218 -112.34166)
		(width 0.11684)
		(layer "In6.Cu")
		(net "SWB_HSC_PWRGD_ISO")
	)
	(segment
		(start 286.577532 -114.308128)
		(end 312.05932 -114.308128)
		(width 0.11684)
		(layer "In6.Cu")
		(net "SWB_HSC_PWRGD_ISO")
	)
	(segment
		(start 312.856372 -115.10518)
		(end 315.51626 -115.10518)
		(width 0.11684)
		(layer "In6.Cu")
		(net "SWB_HSC_PWRGD_ISO")
	)
	(segment
		(start 224.056956 -117.335046)
		(end 244.223794 -117.335046)
		(width 0.11684)
		(layer "In6.Cu")
		(net "SWB_HSC_PWRGD_ISO")
	)
	(segment
		(start 205.706726 -120.85066)
		(end 206.323438 -120.233948)
		(width 0.11684)
		(layer "In6.Cu")
		(net "SWB_HSC_PWRGD_ISO")
	)
	(segment
		(start 315.51626 -115.10518)
		(end 316.313312 -114.308128)
		(width 0.11684)
		(layer "In6.Cu")
		(net "SWB_HSC_PWRGD_ISO")
	)
	(segment
		(start 316.313312 -114.308128)
		(end 318.741298 -114.308128)
		(width 0.11684)
		(layer "In6.Cu")
		(net "SWB_HSC_PWRGD_ISO")
	)
	(segment
		(start 244.223794 -117.335046)
		(end 249.21718 -112.34166)
		(width 0.11684)
		(layer "In6.Cu")
		(net "SWB_HSC_PWRGD_ISO")
	)
	(segment
		(start 267.809218 -112.34166)
		(end 269.021306 -113.553748)
		(width 0.11684)
		(layer "In6.Cu")
		(net "SWB_HSC_PWRGD_ISO")
	)
	(segment
		(start 213.174326 -118.133622)
		(end 223.25838 -118.133622)
		(width 0.11684)
		(layer "In6.Cu")
		(net "SWB_HSC_PWRGD_ISO")
	)
	(segment
		(start 286.105346 -113.835942)
		(end 286.577532 -114.308128)
		(width 0.11684)
		(layer "In6.Cu")
		(net "SWB_HSC_PWRGD_ISO")
	)
	(segment
		(start 320.860928 -116.427758)
		(end 355.727 -116.427758)
		(width 0.11684)
		(layer "In6.Cu")
		(net "SWB_HSC_PWRGD_ISO")
	)
	(segment
		(start 211.074 -120.233948)
		(end 213.174326 -118.133622)
		(width 0.11684)
		(layer "In6.Cu")
		(net "SWB_HSC_PWRGD_ISO")
	)
	(segment
		(start 202.520804 -121.753376)
		(end 202.72502 -121.753376)
		(width 0.11684)
		(layer "In6.Cu")
		(net "SWB_HSC_PWRGD_ISO")
	)
	(segment
		(start 274.468336 -113.553748)
		(end 274.75053 -113.835942)
		(width 0.11684)
		(layer "In6.Cu")
		(net "SWB_HSC_PWRGD_ISO")
	)
	(segment
		(start 359.17632 -410.972)
		(end 359.17632 -414.687512)
		(width 0.11684)
		(layer "In13.Cu")
		(net "SWB_HSC_PWRGD_ISO")
	)
	(segment
		(start 355.6762 -398.724374)
		(end 355.6762 -407.47188)
		(width 0.11684)
		(layer "In13.Cu")
		(net "SWB_HSC_PWRGD_ISO")
	)
	(segment
		(start 357.22052 -390.1186)
		(end 356.54234 -390.79678)
		(width 0.11684)
		(layer "In13.Cu")
		(net "SWB_HSC_PWRGD_ISO")
	)
	(segment
		(start 356.54234 -391.35812)
		(end 355.6762 -392.22426)
		(width 0.11684)
		(layer "In13.Cu")
		(net "SWB_HSC_PWRGD_ISO")
	)
	(segment
		(start 360.57332 -417.614608)
		(end 355.293676 -422.894252)
		(width 0.11684)
		(layer "In13.Cu")
		(net "SWB_HSC_PWRGD_ISO")
	)
	(segment
		(start 360.57332 -416.084512)
		(end 360.57332 -417.614608)
		(width 0.11684)
		(layer "In13.Cu")
		(net "SWB_HSC_PWRGD_ISO")
	)
	(segment
		(start 362.26242 -388.33298)
		(end 360.4768 -390.1186)
		(width 0.11684)
		(layer "In13.Cu")
		(net "SWB_HSC_PWRGD_ISO")
	)
	(segment
		(start 393.077192 -386.09778)
		(end 390.597136 -386.09778)
		(width 0.11684)
		(layer "In13.Cu")
		(net "SWB_HSC_PWRGD_ISO")
	)
	(segment
		(start 386.929376 -389.76554)
		(end 368.86388 -389.76554)
		(width 0.11684)
		(layer "In13.Cu")
		(net "SWB_HSC_PWRGD_ISO")
	)
	(segment
		(start 355.293676 -422.894252)
		(end 353.247452 -422.894252)
		(width 0.11684)
		(layer "In13.Cu")
		(net "SWB_HSC_PWRGD_ISO")
	)
	(segment
		(start 355.6762 -392.22426)
		(end 355.6762 -398.35963)
		(width 0.11684)
		(layer "In13.Cu")
		(net "SWB_HSC_PWRGD_ISO")
	)
	(segment
		(start 368.86388 -389.76554)
		(end 367.43132 -388.33298)
		(width 0.11684)
		(layer "In13.Cu")
		(net "SWB_HSC_PWRGD_ISO")
	)
	(segment
		(start 359.17632 -414.687512)
		(end 360.57332 -416.084512)
		(width 0.11684)
		(layer "In13.Cu")
		(net "SWB_HSC_PWRGD_ISO")
	)
	(segment
		(start 360.4768 -390.1186)
		(end 357.22052 -390.1186)
		(width 0.11684)
		(layer "In13.Cu")
		(net "SWB_HSC_PWRGD_ISO")
	)
	(segment
		(start 367.43132 -388.33298)
		(end 362.26242 -388.33298)
		(width 0.11684)
		(layer "In13.Cu")
		(net "SWB_HSC_PWRGD_ISO")
	)
	(segment
		(start 355.6762 -407.47188)
		(end 359.17632 -410.972)
		(width 0.11684)
		(layer "In13.Cu")
		(net "SWB_HSC_PWRGD_ISO")
	)
	(segment
		(start 356.54234 -390.79678)
		(end 356.54234 -391.35812)
		(width 0.11684)
		(layer "In13.Cu")
		(net "SWB_HSC_PWRGD_ISO")
	)
	(segment
		(start 355.686868 -398.370298)
		(end 355.686868 -398.713706)
		(width 0.11684)
		(layer "In13.Cu")
		(net "SWB_HSC_PWRGD_ISO")
	)
	(segment
		(start 355.6762 -398.35963)
		(end 355.686868 -398.370298)
		(width 0.11684)
		(layer "In13.Cu")
		(net "SWB_HSC_PWRGD_ISO")
	)
	(segment
		(start 390.597136 -386.09778)
		(end 386.929376 -389.76554)
		(width 0.11684)
		(layer "In13.Cu")
		(net "SWB_HSC_PWRGD_ISO")
	)
	(segment
		(start 355.686868 -398.713706)
		(end 355.6762 -398.724374)
		(width 0.11684)
		(layer "In13.Cu")
		(net "SWB_HSC_PWRGD_ISO")
	)
	(segment
		(start 352.135186 -426.461428)
		(end 351.807272 -426.133514)
		(width 0.10668)
		(layer "F.Cu")
		(net "SWB_HSC_PWRGD")
	)
	(segment
		(start 351.807272 -426.133514)
		(end 351.807272 -425.295314)
		(width 0.10668)
		(layer "F.Cu")
		(net "SWB_HSC_PWRGD")
	)
	(segment
		(start 352.135186 -427.456092)
		(end 352.135186 -426.461428)
		(width 0.10668)
		(layer "F.Cu")
		(net "SWB_HSC_PWRGD")
	)
	(segment
		(start 351.807272 -424.279314)
		(end 351.807272 -425.295314)
		(width 0.10668)
		(layer "F.Cu")
		(net "SWB_HSC_PWRGD")
	)
	(segment
		(start 351.807272 -424.279314)
		(end 351.807272 -422.886378)
		(width 0.10668)
		(layer "F.Cu")
		(net "SWB_HSC_PWRGD")
	)
	(via
		(at 351.807272 -422.886378)
		(size 0.508)
		(drill 0.254)
		(layers "F.Cu" "B.Cu")
		(net "SWB_HSC_PWRGD")
	)
	(segment
		(start 343.6112 -422.886378)
		(end 342.860376 -423.637202)
		(width 0.10668)
		(layer "B.Cu")
		(net "SWB_HSC_PWRGD")
	)
	(segment
		(start 351.807272 -422.886378)
		(end 343.6112 -422.886378)
		(width 0.10668)
		(layer "B.Cu")
		(net "SWB_HSC_PWRGD")
	)
	(segment
		(start 342.860376 -423.637202)
		(end 342.860376 -439.870596)
		(width 0.10668)
		(layer "B.Cu")
		(net "SWB_HSC_PWRGD")
	)
	(segment
		(start 343.479628 -440.489848)
		(end 343.649808 -440.489848)
		(width 0.10668)
		(layer "B.Cu")
		(net "SWB_HSC_PWRGD")
	)
	(segment
		(start 342.860376 -439.870596)
		(end 343.479628 -440.489848)
		(width 0.10668)
		(layer "B.Cu")
		(net "SWB_HSC_PWRGD")
	)
	(segment
		(start 353.67468 -435.406038)
		(end 353.67468 -433.841652)
		(width 0.10668)
		(layer "F.Cu")
		(net "SWB_HSC_EN_BUF_R")
	)
	(segment
		(start 352.45548 -431.809652)
		(end 352.45548 -432.825652)
		(width 0.10668)
		(layer "F.Cu")
		(net "SWB_HSC_EN_BUF_R")
	)
	(segment
		(start 353.67468 -433.841652)
		(end 352.45548 -433.841652)
		(width 0.10668)
		(layer "F.Cu")
		(net "SWB_HSC_EN_BUF_R")
	)
	(segment
		(start 352.45548 -432.825652)
		(end 352.45548 -433.841652)
		(width 0.10668)
		(layer "F.Cu")
		(net "SWB_HSC_EN_BUF_R")
	)
	(segment
		(start 353.105466 -435.975252)
		(end 353.67468 -435.406038)
		(width 0.10668)
		(layer "F.Cu")
		(net "SWB_HSC_EN_BUF_R")
	)
	(via
		(at 353.67468 -433.841652)
		(size 0.762)
		(drill 0.381)
		(layers "F.Cu" "B.Cu")
		(net "SWB_HSC_EN_BUF_R")
	)
	(segment
		(start 351.65538 -431.809652)
		(end 351.03943 -431.809652)
		(width 0.10668)
		(layer "F.Cu")
		(net "SWB_HSC_EN_BUF")
	)
	(via
		(at 351.03943 -431.809652)
		(size 0.508)
		(drill 0.254)
		(layers "F.Cu" "B.Cu")
		(net "SWB_HSC_EN_BUF")
	)
	(segment
		(start 347.389196 -424.689778)
		(end 347.792548 -425.09313)
		(width 0.10668)
		(layer "B.Cu")
		(net "SWB_HSC_EN_BUF")
	)
	(segment
		(start 347.792548 -425.09313)
		(end 347.792548 -428.56277)
		(width 0.10668)
		(layer "B.Cu")
		(net "SWB_HSC_EN_BUF")
	)
	(segment
		(start 347.792548 -428.56277)
		(end 351.03943 -431.809652)
		(width 0.10668)
		(layer "B.Cu")
		(net "SWB_HSC_EN_BUF")
	)
	(segment
		(start 345.649804 -424.689778)
		(end 347.389196 -424.689778)
		(width 0.10668)
		(layer "B.Cu")
		(net "SWB_HSC_EN_BUF")
	)
	(segment
		(start 353.105466 -440.211972)
		(end 353.105466 -438.992772)
		(width 0.10668)
		(layer "F.Cu")
		(net "SWB_HSC_EN")
	)
	(segment
		(start 353.105466 -438.992772)
		(end 353.105466 -437.875172)
		(width 0.10668)
		(layer "F.Cu")
		(net "SWB_HSC_EN")
	)
	(segment
		(start 351.886266 -440.211972)
		(end 353.105466 -440.211972)
		(width 0.10668)
		(layer "F.Cu")
		(net "SWB_HSC_EN")
	)
	(via
		(at 353.105466 -440.211972)
		(size 0.508)
		(drill 0.254)
		(layers "F.Cu" "B.Cu")
		(net "SWB_HSC_EN")
	)
	(via
		(at 432.379374 -368.249454)
		(size 0.508)
		(drill 0.254)
		(layers "F.Cu" "B.Cu")
		(net "SWB_HSC_EN")
	)
	(via
		(at 357.251 -116.423948)
		(size 0.508)
		(drill 0.254)
		(layers "F.Cu" "B.Cu")
		(net "SWB_HSC_EN")
	)
	(via
		(at 392.550142 -386.617718)
		(size 0.508)
		(drill 0.254)
		(layers "F.Cu" "B.Cu")
		(net "SWB_HSC_EN")
	)
	(via
		(at 218.005152 -118.630192)
		(size 0.508)
		(drill 0.254)
		(layers "F.Cu" "B.Cu")
		(net "SWB_HSC_EN")
	)
	(segment
		(start 450.361812 -146.030188)
		(end 450.361812 -177.130202)
		(width 0.10668)
		(layer "B.Cu")
		(net "SWB_HSC_EN")
	)
	(segment
		(start 450.361812 -177.130202)
		(end 460.715614 -187.484004)
		(width 0.10668)
		(layer "B.Cu")
		(net "SWB_HSC_EN")
	)
	(segment
		(start 206.82458 -118.22176)
		(end 217.59672 -118.22176)
		(width 0.10668)
		(layer "B.Cu")
		(net "SWB_HSC_EN")
	)
	(segment
		(start 376.591576 -117.405658)
		(end 421.737282 -117.405658)
		(width 0.10668)
		(layer "B.Cu")
		(net "SWB_HSC_EN")
	)
	(segment
		(start 448.064128 -363.995462)
		(end 444.44539 -367.6142)
		(width 0.10668)
		(layer "B.Cu")
		(net "SWB_HSC_EN")
	)
	(segment
		(start 357.27894 -116.396008)
		(end 360.52506 -116.396008)
		(width 0.10668)
		(layer "B.Cu")
		(net "SWB_HSC_EN")
	)
	(segment
		(start 421.737282 -117.405658)
		(end 450.361812 -146.030188)
		(width 0.10668)
		(layer "B.Cu")
		(net "SWB_HSC_EN")
	)
	(segment
		(start 206.050388 -118.995952)
		(end 206.82458 -118.22176)
		(width 0.10668)
		(layer "B.Cu")
		(net "SWB_HSC_EN")
	)
	(segment
		(start 439.679588 -368.249454)
		(end 432.379374 -368.249454)
		(width 0.10668)
		(layer "B.Cu")
		(net "SWB_HSC_EN")
	)
	(segment
		(start 460.715614 -330.056998)
		(end 448.064128 -342.708484)
		(width 0.10668)
		(layer "B.Cu")
		(net "SWB_HSC_EN")
	)
	(segment
		(start 444.44539 -367.6142)
		(end 440.314842 -367.6142)
		(width 0.10668)
		(layer "B.Cu")
		(net "SWB_HSC_EN")
	)
	(segment
		(start 440.314842 -367.6142)
		(end 439.679588 -368.249454)
		(width 0.10668)
		(layer "B.Cu")
		(net "SWB_HSC_EN")
	)
	(segment
		(start 360.52506 -116.396008)
		(end 362.904532 -118.77548)
		(width 0.10668)
		(layer "B.Cu")
		(net "SWB_HSC_EN")
	)
	(segment
		(start 357.251 -116.423948)
		(end 357.27894 -116.396008)
		(width 0.10668)
		(layer "B.Cu")
		(net "SWB_HSC_EN")
	)
	(segment
		(start 362.904532 -118.77548)
		(end 375.221754 -118.77548)
		(width 0.10668)
		(layer "B.Cu")
		(net "SWB_HSC_EN")
	)
	(segment
		(start 217.59672 -118.22176)
		(end 218.005152 -118.630192)
		(width 0.10668)
		(layer "B.Cu")
		(net "SWB_HSC_EN")
	)
	(segment
		(start 375.221754 -118.77548)
		(end 376.591576 -117.405658)
		(width 0.10668)
		(layer "B.Cu")
		(net "SWB_HSC_EN")
	)
	(segment
		(start 199.67956 -118.995952)
		(end 206.050388 -118.995952)
		(width 0.10668)
		(layer "B.Cu")
		(net "SWB_HSC_EN")
	)
	(segment
		(start 197.669658 -119.721376)
		(end 198.954136 -119.721376)
		(width 0.10668)
		(layer "B.Cu")
		(net "SWB_HSC_EN")
	)
	(segment
		(start 460.715614 -187.484004)
		(end 460.715614 -330.056998)
		(width 0.10668)
		(layer "B.Cu")
		(net "SWB_HSC_EN")
	)
	(segment
		(start 448.064128 -342.708484)
		(end 448.064128 -363.995462)
		(width 0.10668)
		(layer "B.Cu")
		(net "SWB_HSC_EN")
	)
	(segment
		(start 198.954136 -119.721376)
		(end 199.67956 -118.995952)
		(width 0.10668)
		(layer "B.Cu")
		(net "SWB_HSC_EN")
	)
	(segment
		(start 429.782224 -370.846604)
		(end 432.379374 -368.249454)
		(width 0.11684)
		(layer "In2.Cu")
		(net "SWB_HSC_EN")
	)
	(segment
		(start 391.64006 -384.06451)
		(end 392.237976 -383.466594)
		(width 0.11684)
		(layer "In2.Cu")
		(net "SWB_HSC_EN")
	)
	(segment
		(start 395.94917 -377.38939)
		(end 398.029938 -375.308622)
		(width 0.11684)
		(layer "In2.Cu")
		(net "SWB_HSC_EN")
	)
	(segment
		(start 427.969172 -370.846604)
		(end 429.782224 -370.846604)
		(width 0.11684)
		(layer "In2.Cu")
		(net "SWB_HSC_EN")
	)
	(segment
		(start 398.029938 -375.308622)
		(end 423.507154 -375.308622)
		(width 0.11684)
		(layer "In2.Cu")
		(net "SWB_HSC_EN")
	)
	(segment
		(start 392.237976 -383.466594)
		(end 392.48461 -383.466594)
		(width 0.11684)
		(layer "In2.Cu")
		(net "SWB_HSC_EN")
	)
	(segment
		(start 392.550142 -386.617718)
		(end 391.64006 -385.707636)
		(width 0.11684)
		(layer "In2.Cu")
		(net "SWB_HSC_EN")
	)
	(segment
		(start 392.873738 -383.47015)
		(end 395.94917 -380.394718)
		(width 0.11684)
		(layer "In2.Cu")
		(net "SWB_HSC_EN")
	)
	(segment
		(start 395.94917 -380.394718)
		(end 395.94917 -377.38939)
		(width 0.11684)
		(layer "In2.Cu")
		(net "SWB_HSC_EN")
	)
	(segment
		(start 392.488166 -383.47015)
		(end 392.873738 -383.47015)
		(width 0.11684)
		(layer "In2.Cu")
		(net "SWB_HSC_EN")
	)
	(segment
		(start 423.507154 -375.308622)
		(end 427.969172 -370.846604)
		(width 0.11684)
		(layer "In2.Cu")
		(net "SWB_HSC_EN")
	)
	(segment
		(start 391.64006 -385.707636)
		(end 391.64006 -384.06451)
		(width 0.11684)
		(layer "In2.Cu")
		(net "SWB_HSC_EN")
	)
	(segment
		(start 392.48461 -383.466594)
		(end 392.488166 -383.47015)
		(width 0.11684)
		(layer "In2.Cu")
		(net "SWB_HSC_EN")
	)
	(segment
		(start 224.281238 -117.763036)
		(end 247.21185 -117.763036)
		(width 0.11684)
		(layer "In6.Cu")
		(net "SWB_HSC_EN")
	)
	(segment
		(start 261.380732 -113.825274)
		(end 268.249908 -113.825274)
		(width 0.11684)
		(layer "In6.Cu")
		(net "SWB_HSC_EN")
	)
	(segment
		(start 253.664974 -113.352326)
		(end 260.907784 -113.352326)
		(width 0.11684)
		(layer "In6.Cu")
		(net "SWB_HSC_EN")
	)
	(segment
		(start 269.163546 -114.738912)
		(end 270.325088 -114.738912)
		(width 0.11684)
		(layer "In6.Cu")
		(net "SWB_HSC_EN")
	)
	(segment
		(start 298.618402 -117.2972)
		(end 299.284898 -117.963696)
		(width 0.11684)
		(layer "In6.Cu")
		(net "SWB_HSC_EN")
	)
	(segment
		(start 284.030674 -114.942874)
		(end 293.103808 -114.942874)
		(width 0.11684)
		(layer "In6.Cu")
		(net "SWB_HSC_EN")
	)
	(segment
		(start 270.325088 -114.738912)
		(end 270.79829 -114.26571)
		(width 0.11684)
		(layer "In6.Cu")
		(net "SWB_HSC_EN")
	)
	(segment
		(start 270.79829 -114.26571)
		(end 283.35351 -114.26571)
		(width 0.11684)
		(layer "In6.Cu")
		(net "SWB_HSC_EN")
	)
	(segment
		(start 318.782446 -117.566186)
		(end 319.456054 -116.892578)
		(width 0.11684)
		(layer "In6.Cu")
		(net "SWB_HSC_EN")
	)
	(segment
		(start 299.284898 -117.963696)
		(end 299.628814 -117.963696)
		(width 0.11684)
		(layer "In6.Cu")
		(net "SWB_HSC_EN")
	)
	(segment
		(start 283.35351 -114.26571)
		(end 284.030674 -114.942874)
		(width 0.11684)
		(layer "In6.Cu")
		(net "SWB_HSC_EN")
	)
	(segment
		(start 295.458134 -117.2972)
		(end 298.618402 -117.2972)
		(width 0.11684)
		(layer "In6.Cu")
		(net "SWB_HSC_EN")
	)
	(segment
		(start 293.103808 -114.942874)
		(end 295.458134 -117.2972)
		(width 0.11684)
		(layer "In6.Cu")
		(net "SWB_HSC_EN")
	)
	(segment
		(start 299.628814 -117.963696)
		(end 300.026324 -117.566186)
		(width 0.11684)
		(layer "In6.Cu")
		(net "SWB_HSC_EN")
	)
	(segment
		(start 218.005152 -118.630192)
		(end 223.414082 -118.630192)
		(width 0.11684)
		(layer "In6.Cu")
		(net "SWB_HSC_EN")
	)
	(segment
		(start 300.026324 -117.566186)
		(end 318.782446 -117.566186)
		(width 0.11684)
		(layer "In6.Cu")
		(net "SWB_HSC_EN")
	)
	(segment
		(start 250.842526 -114.13236)
		(end 252.88494 -114.13236)
		(width 0.11684)
		(layer "In6.Cu")
		(net "SWB_HSC_EN")
	)
	(segment
		(start 356.78237 -116.892578)
		(end 357.251 -116.423948)
		(width 0.11684)
		(layer "In6.Cu")
		(net "SWB_HSC_EN")
	)
	(segment
		(start 268.249908 -113.825274)
		(end 269.163546 -114.738912)
		(width 0.11684)
		(layer "In6.Cu")
		(net "SWB_HSC_EN")
	)
	(segment
		(start 260.907784 -113.352326)
		(end 261.380732 -113.825274)
		(width 0.11684)
		(layer "In6.Cu")
		(net "SWB_HSC_EN")
	)
	(segment
		(start 319.456054 -116.892578)
		(end 356.78237 -116.892578)
		(width 0.11684)
		(layer "In6.Cu")
		(net "SWB_HSC_EN")
	)
	(segment
		(start 247.21185 -117.763036)
		(end 250.842526 -114.13236)
		(width 0.11684)
		(layer "In6.Cu")
		(net "SWB_HSC_EN")
	)
	(segment
		(start 223.414082 -118.630192)
		(end 224.281238 -117.763036)
		(width 0.11684)
		(layer "In6.Cu")
		(net "SWB_HSC_EN")
	)
	(segment
		(start 252.88494 -114.13236)
		(end 253.664974 -113.352326)
		(width 0.11684)
		(layer "In6.Cu")
		(net "SWB_HSC_EN")
	)
	(segment
		(start 360.99496 -417.78936)
		(end 360.99496 -415.90976)
		(width 0.11684)
		(layer "In13.Cu")
		(net "SWB_HSC_EN")
	)
	(segment
		(start 368.689128 -390.18718)
		(end 387.104128 -390.18718)
		(width 0.11684)
		(layer "In13.Cu")
		(net "SWB_HSC_EN")
	)
	(segment
		(start 352.16338 -435.483)
		(end 352.16338 -426.34916)
		(width 0.11684)
		(layer "In13.Cu")
		(net "SWB_HSC_EN")
	)
	(segment
		(start 357.62946 -401.37842)
		(end 356.82555 -400.57451)
		(width 0.11684)
		(layer "In13.Cu")
		(net "SWB_HSC_EN")
	)
	(segment
		(start 357.556308 -393.700508)
		(end 357.525066 -393.669266)
		(width 0.11684)
		(layer "In13.Cu")
		(net "SWB_HSC_EN")
	)
	(segment
		(start 360.626152 -390.56564)
		(end 362.437172 -388.75462)
		(width 0.11684)
		(layer "In13.Cu")
		(net "SWB_HSC_EN")
	)
	(segment
		(start 353.105466 -436.425086)
		(end 352.16338 -435.483)
		(width 0.11684)
		(layer "In13.Cu")
		(net "SWB_HSC_EN")
	)
	(segment
		(start 360.99496 -415.90976)
		(end 359.59796 -414.51276)
		(width 0.11684)
		(layer "In13.Cu")
		(net "SWB_HSC_EN")
	)
	(segment
		(start 362.437172 -388.75462)
		(end 367.256568 -388.75462)
		(width 0.11684)
		(layer "In13.Cu")
		(net "SWB_HSC_EN")
	)
	(segment
		(start 356.09784 -404.114)
		(end 357.62946 -402.58238)
		(width 0.11684)
		(layer "In13.Cu")
		(net "SWB_HSC_EN")
	)
	(segment
		(start 355.44506 -423.33926)
		(end 360.99496 -417.78936)
		(width 0.11684)
		(layer "In13.Cu")
		(net "SWB_HSC_EN")
	)
	(segment
		(start 367.256568 -388.75462)
		(end 368.689128 -390.18718)
		(width 0.11684)
		(layer "In13.Cu")
		(net "SWB_HSC_EN")
	)
	(segment
		(start 352.16338 -426.34916)
		(end 355.17328 -423.33926)
		(width 0.11684)
		(layer "In13.Cu")
		(net "SWB_HSC_EN")
	)
	(segment
		(start 357.525066 -391.753852)
		(end 358.713278 -390.56564)
		(width 0.11684)
		(layer "In13.Cu")
		(net "SWB_HSC_EN")
	)
	(segment
		(start 359.59796 -414.51276)
		(end 359.59796 -410.797248)
		(width 0.11684)
		(layer "In13.Cu")
		(net "SWB_HSC_EN")
	)
	(segment
		(start 358.713278 -390.56564)
		(end 360.626152 -390.56564)
		(width 0.11684)
		(layer "In13.Cu")
		(net "SWB_HSC_EN")
	)
	(segment
		(start 353.105466 -440.211972)
		(end 353.105466 -436.425086)
		(width 0.11684)
		(layer "In13.Cu")
		(net "SWB_HSC_EN")
	)
	(segment
		(start 357.556308 -395.170152)
		(end 357.556308 -393.700508)
		(width 0.11684)
		(layer "In13.Cu")
		(net "SWB_HSC_EN")
	)
	(segment
		(start 357.62946 -402.58238)
		(end 357.62946 -401.37842)
		(width 0.11684)
		(layer "In13.Cu")
		(net "SWB_HSC_EN")
	)
	(segment
		(start 390.67359 -386.617718)
		(end 392.550142 -386.617718)
		(width 0.11684)
		(layer "In13.Cu")
		(net "SWB_HSC_EN")
	)
	(segment
		(start 359.59796 -410.797248)
		(end 356.09784 -407.297128)
		(width 0.11684)
		(layer "In13.Cu")
		(net "SWB_HSC_EN")
	)
	(segment
		(start 356.82555 -400.57451)
		(end 356.82555 -395.90091)
		(width 0.11684)
		(layer "In13.Cu")
		(net "SWB_HSC_EN")
	)
	(segment
		(start 356.82555 -395.90091)
		(end 357.556308 -395.170152)
		(width 0.11684)
		(layer "In13.Cu")
		(net "SWB_HSC_EN")
	)
	(segment
		(start 355.17328 -423.33926)
		(end 355.44506 -423.33926)
		(width 0.11684)
		(layer "In13.Cu")
		(net "SWB_HSC_EN")
	)
	(segment
		(start 357.525066 -393.669266)
		(end 357.525066 -391.753852)
		(width 0.11684)
		(layer "In13.Cu")
		(net "SWB_HSC_EN")
	)
	(segment
		(start 387.104128 -390.18718)
		(end 390.67359 -386.617718)
		(width 0.11684)
		(layer "In13.Cu")
		(net "SWB_HSC_EN")
	)
	(segment
		(start 356.09784 -407.297128)
		(end 356.09784 -404.114)
		(width 0.11684)
		(layer "In13.Cu")
		(net "SWB_HSC_EN")
	)
	(segment
		(start 26.156666 -360.32313)
		(end 26.742898 -360.909362)
		(width 0.10668)
		(layer "F.Cu")
		(net "SVID_PVDDCR_CPU1_P1_SVTO_R")
	)
	(segment
		(start 26.742898 -360.909362)
		(end 26.742898 -361.743498)
		(width 0.10668)
		(layer "F.Cu")
		(net "SVID_PVDDCR_CPU1_P1_SVTO_R")
	)
	(segment
		(start 27.308302 -362.308902)
		(end 27.604974 -362.308902)
		(width 0.10668)
		(layer "F.Cu")
		(net "SVID_PVDDCR_CPU1_P1_SVTO_R")
	)
	(segment
		(start 25.91689 -359.52684)
		(end 25.921716 -359.52684)
		(width 0.10668)
		(layer "F.Cu")
		(net "SVID_PVDDCR_CPU1_P1_SVTO_R")
	)
	(segment
		(start 26.156666 -359.76179)
		(end 26.156666 -360.32313)
		(width 0.10668)
		(layer "F.Cu")
		(net "SVID_PVDDCR_CPU1_P1_SVTO_R")
	)
	(segment
		(start 26.742898 -361.743498)
		(end 27.308302 -362.308902)
		(width 0.10668)
		(layer "F.Cu")
		(net "SVID_PVDDCR_CPU1_P1_SVTO_R")
	)
	(segment
		(start 26.047192 -359.652316)
		(end 26.156666 -359.76179)
		(width 0.10668)
		(layer "F.Cu")
		(net "SVID_PVDDCR_CPU1_P1_SVTO_R")
	)
	(segment
		(start 25.16505 -358.775)
		(end 25.91689 -359.52684)
		(width 0.10668)
		(layer "F.Cu")
		(net "SVID_PVDDCR_CPU1_P1_SVTO_R")
	)
	(segment
		(start 25.921716 -359.52684)
		(end 26.047192 -359.652316)
		(width 0.10668)
		(layer "F.Cu")
		(net "SVID_PVDDCR_CPU1_P1_SVTO_R")
	)
	(via
		(at 26.047192 -359.652316)
		(size 0.762)
		(drill 0.381)
		(layers "F.Cu" "B.Cu")
		(net "SVID_PVDDCR_CPU1_P1_SVTO_R")
	)
	(segment
		(start 88.358472 -307.428138)
		(end 88.358472 -308.876192)
		(width 0.10668)
		(layer "F.Cu")
		(net "SVID_PVDDCR_CPU1_P1_SVTO")
	)
	(segment
		(start 79.145384 -295.37406)
		(end 78.716632 -295.802812)
		(width 0.10668)
		(layer "F.Cu")
		(net "SVID_PVDDCR_CPU1_P1_SVTO")
	)
	(segment
		(start 96.508316 -366.803178)
		(end 42.855896 -366.803178)
		(width 0.10668)
		(layer "F.Cu")
		(net "SVID_PVDDCR_CPU1_P1_SVTO")
	)
	(segment
		(start 86.01075 -298.59097)
		(end 89.42197 -302.00219)
		(width 0.10668)
		(layer "F.Cu")
		(net "SVID_PVDDCR_CPU1_P1_SVTO")
	)
	(segment
		(start 88.358472 -308.876192)
		(end 91.509342 -312.027062)
		(width 0.10668)
		(layer "F.Cu")
		(net "SVID_PVDDCR_CPU1_P1_SVTO")
	)
	(segment
		(start 89.42197 -306.36464)
		(end 88.358472 -307.428138)
		(width 0.10668)
		(layer "F.Cu")
		(net "SVID_PVDDCR_CPU1_P1_SVTO")
	)
	(segment
		(start 78.716632 -295.802812)
		(end 78.716632 -296.428668)
		(width 0.10668)
		(layer "F.Cu")
		(net "SVID_PVDDCR_CPU1_P1_SVTO")
	)
	(segment
		(start 116.764054 -327.225914)
		(end 116.764054 -346.54744)
		(width 0.10668)
		(layer "F.Cu")
		(net "SVID_PVDDCR_CPU1_P1_SVTO")
	)
	(segment
		(start 116.764054 -346.54744)
		(end 96.508316 -366.803178)
		(width 0.10668)
		(layer "F.Cu")
		(net "SVID_PVDDCR_CPU1_P1_SVTO")
	)
	(segment
		(start 79.647796 -294.070278)
		(end 79.647796 -295.104058)
		(width 0.10668)
		(layer "F.Cu")
		(net "SVID_PVDDCR_CPU1_P1_SVTO")
	)
	(segment
		(start 41.934892 -367.724182)
		(end 39.745158 -367.724182)
		(width 0.10668)
		(layer "F.Cu")
		(net "SVID_PVDDCR_CPU1_P1_SVTO")
	)
	(segment
		(start 78.716632 -296.428668)
		(end 80.878934 -298.59097)
		(width 0.10668)
		(layer "F.Cu")
		(net "SVID_PVDDCR_CPU1_P1_SVTO")
	)
	(segment
		(start 42.855896 -366.803178)
		(end 41.934892 -367.724182)
		(width 0.10668)
		(layer "F.Cu")
		(net "SVID_PVDDCR_CPU1_P1_SVTO")
	)
	(segment
		(start 22.87905 -358.775)
		(end 23.639526 -358.775)
		(width 0.10668)
		(layer "F.Cu")
		(net "SVID_PVDDCR_CPU1_P1_SVTO")
	)
	(segment
		(start 79.647796 -295.104058)
		(end 79.377794 -295.37406)
		(width 0.10668)
		(layer "F.Cu")
		(net "SVID_PVDDCR_CPU1_P1_SVTO")
	)
	(segment
		(start 101.565202 -312.027062)
		(end 116.764054 -327.225914)
		(width 0.10668)
		(layer "F.Cu")
		(net "SVID_PVDDCR_CPU1_P1_SVTO")
	)
	(segment
		(start 89.42197 -302.00219)
		(end 89.42197 -306.36464)
		(width 0.10668)
		(layer "F.Cu")
		(net "SVID_PVDDCR_CPU1_P1_SVTO")
	)
	(segment
		(start 24.36495 -358.775)
		(end 23.639526 -358.775)
		(width 0.10668)
		(layer "F.Cu")
		(net "SVID_PVDDCR_CPU1_P1_SVTO")
	)
	(segment
		(start 79.377794 -295.37406)
		(end 79.145384 -295.37406)
		(width 0.10668)
		(layer "F.Cu")
		(net "SVID_PVDDCR_CPU1_P1_SVTO")
	)
	(segment
		(start 80.878934 -298.59097)
		(end 86.01075 -298.59097)
		(width 0.10668)
		(layer "F.Cu")
		(net "SVID_PVDDCR_CPU1_P1_SVTO")
	)
	(segment
		(start 91.509342 -312.027062)
		(end 101.565202 -312.027062)
		(width 0.10668)
		(layer "F.Cu")
		(net "SVID_PVDDCR_CPU1_P1_SVTO")
	)
	(via
		(at 23.639526 -358.775)
		(size 0.508)
		(drill 0.254)
		(layers "F.Cu" "B.Cu")
		(net "SVID_PVDDCR_CPU1_P1_SVTO")
	)
	(via
		(at 39.745158 -367.724182)
		(size 0.508)
		(drill 0.254)
		(layers "F.Cu" "B.Cu")
		(net "SVID_PVDDCR_CPU1_P1_SVTO")
	)
	(segment
		(start 23.639526 -358.775)
		(end 22.87905 -358.775)
		(width 0.10668)
		(layer "B.Cu")
		(net "SVID_PVDDCR_CPU1_P1_SVTO")
	)
	(segment
		(start 24.36495 -358.775)
		(end 23.639526 -358.775)
		(width 0.10668)
		(layer "B.Cu")
		(net "SVID_PVDDCR_CPU1_P1_SVTO")
	)
	(segment
		(start 27.701748 -361.395518)
		(end 27.701748 -366.480598)
		(width 0.11684)
		(layer "In6.Cu")
		(net "SVID_PVDDCR_CPU1_P1_SVTO")
	)
	(segment
		(start 23.639526 -358.792526)
		(end 24.287988 -359.440988)
		(width 0.11684)
		(layer "In6.Cu")
		(net "SVID_PVDDCR_CPU1_P1_SVTO")
	)
	(segment
		(start 31.539434 -366.607598)
		(end 32.830008 -367.898172)
		(width 0.11684)
		(layer "In6.Cu")
		(net "SVID_PVDDCR_CPU1_P1_SVTO")
	)
	(segment
		(start 38.74135 -367.724182)
		(end 39.745158 -367.724182)
		(width 0.11684)
		(layer "In6.Cu")
		(net "SVID_PVDDCR_CPU1_P1_SVTO")
	)
	(segment
		(start 38.56736 -367.898172)
		(end 38.74135 -367.724182)
		(width 0.11684)
		(layer "In6.Cu")
		(net "SVID_PVDDCR_CPU1_P1_SVTO")
	)
	(segment
		(start 27.828748 -366.607598)
		(end 31.539434 -366.607598)
		(width 0.11684)
		(layer "In6.Cu")
		(net "SVID_PVDDCR_CPU1_P1_SVTO")
	)
	(segment
		(start 25.747218 -359.440988)
		(end 27.701748 -361.395518)
		(width 0.11684)
		(layer "In6.Cu")
		(net "SVID_PVDDCR_CPU1_P1_SVTO")
	)
	(segment
		(start 23.639526 -358.775)
		(end 23.639526 -358.792526)
		(width 0.11684)
		(layer "In6.Cu")
		(net "SVID_PVDDCR_CPU1_P1_SVTO")
	)
	(segment
		(start 27.701748 -366.480598)
		(end 27.828748 -366.607598)
		(width 0.11684)
		(layer "In6.Cu")
		(net "SVID_PVDDCR_CPU1_P1_SVTO")
	)
	(segment
		(start 24.287988 -359.440988)
		(end 25.747218 -359.440988)
		(width 0.11684)
		(layer "In6.Cu")
		(net "SVID_PVDDCR_CPU1_P1_SVTO")
	)
	(segment
		(start 32.830008 -367.898172)
		(end 38.56736 -367.898172)
		(width 0.11684)
		(layer "In6.Cu")
		(net "SVID_PVDDCR_CPU1_P1_SVTO")
	)
	(segment
		(start 27.365706 -361.909106)
		(end 27.604974 -361.909106)
		(width 0.10668)
		(layer "F.Cu")
		(net "SVID_PVDDCR_CPU1_P1_SVTI_R")
	)
	(segment
		(start 26.003504 -357.981758)
		(end 26.62936 -358.607614)
		(width 0.10668)
		(layer "F.Cu")
		(net "SVID_PVDDCR_CPU1_P1_SVTI_R")
	)
	(segment
		(start 25.653746 -357.632)
		(end 26.003504 -357.981758)
		(width 0.10668)
		(layer "F.Cu")
		(net "SVID_PVDDCR_CPU1_P1_SVTI_R")
	)
	(segment
		(start 26.62936 -358.607614)
		(end 26.62936 -360.1339)
		(width 0.10668)
		(layer "F.Cu")
		(net "SVID_PVDDCR_CPU1_P1_SVTI_R")
	)
	(segment
		(start 27.2034 -361.7468)
		(end 27.365706 -361.909106)
		(width 0.10668)
		(layer "F.Cu")
		(net "SVID_PVDDCR_CPU1_P1_SVTI_R")
	)
	(segment
		(start 26.62936 -360.1339)
		(end 27.2034 -360.70794)
		(width 0.10668)
		(layer "F.Cu")
		(net "SVID_PVDDCR_CPU1_P1_SVTI_R")
	)
	(segment
		(start 25.16505 -357.632)
		(end 25.653746 -357.632)
		(width 0.10668)
		(layer "F.Cu")
		(net "SVID_PVDDCR_CPU1_P1_SVTI_R")
	)
	(segment
		(start 27.2034 -360.70794)
		(end 27.2034 -361.7468)
		(width 0.10668)
		(layer "F.Cu")
		(net "SVID_PVDDCR_CPU1_P1_SVTI_R")
	)
	(via
		(at 26.003504 -357.981758)
		(size 0.762)
		(drill 0.381)
		(layers "F.Cu" "B.Cu")
		(net "SVID_PVDDCR_CPU1_P1_SVTI_R")
	)
	(segment
		(start 23.622 -357.632)
		(end 22.87905 -357.632)
		(width 0.10668)
		(layer "F.Cu")
		(net "SVID_PVDDCR_CPU1_P1_SVTI")
	)
	(segment
		(start 24.36495 -357.632)
		(end 23.622 -357.632)
		(width 0.10668)
		(layer "F.Cu")
		(net "SVID_PVDDCR_CPU1_P1_SVTI")
	)
	(via
		(at 23.622 -357.632)
		(size 0.508)
		(drill 0.254)
		(layers "F.Cu" "B.Cu")
		(net "SVID_PVDDCR_CPU1_P1_SVTI")
	)
	(segment
		(start 22.87905 -357.632)
		(end 23.622 -357.632)
		(width 0.10668)
		(layer "B.Cu")
		(net "SVID_PVDDCR_CPU1_P1_SVTI")
	)
	(segment
		(start 117.693694 -346.932758)
		(end 117.693694 -326.792844)
		(width 0.10668)
		(layer "F.Cu")
		(net "SVID_PVDDCR_CPU1_P1_SVD_R")
	)
	(segment
		(start 39.19347 -369.087654)
		(end 41.86047 -369.087654)
		(width 0.10668)
		(layer "F.Cu")
		(net "SVID_PVDDCR_CPU1_P1_SVD_R")
	)
	(segment
		(start 23.622 -361.061)
		(end 22.87905 -361.061)
		(width 0.10668)
		(layer "F.Cu")
		(net "SVID_PVDDCR_CPU1_P1_SVD_R")
	)
	(segment
		(start 24.36495 -361.061)
		(end 23.622 -361.061)
		(width 0.10668)
		(layer "F.Cu")
		(net "SVID_PVDDCR_CPU1_P1_SVD_R")
	)
	(segment
		(start 96.87306 -367.753392)
		(end 117.693694 -346.932758)
		(width 0.10668)
		(layer "F.Cu")
		(net "SVID_PVDDCR_CPU1_P1_SVD_R")
	)
	(segment
		(start 43.194732 -367.753392)
		(end 96.87306 -367.753392)
		(width 0.10668)
		(layer "F.Cu")
		(net "SVID_PVDDCR_CPU1_P1_SVD_R")
	)
	(segment
		(start 41.86047 -369.087654)
		(end 43.194732 -367.753392)
		(width 0.10668)
		(layer "F.Cu")
		(net "SVID_PVDDCR_CPU1_P1_SVD_R")
	)
	(segment
		(start 102.028752 -311.127902)
		(end 93.033596 -311.127902)
		(width 0.10668)
		(layer "F.Cu")
		(net "SVID_PVDDCR_CPU1_P1_SVD_R")
	)
	(segment
		(start 117.693694 -326.792844)
		(end 102.028752 -311.127902)
		(width 0.10668)
		(layer "F.Cu")
		(net "SVID_PVDDCR_CPU1_P1_SVD_R")
	)
	(segment
		(start 93.033596 -311.127902)
		(end 89.258902 -307.353208)
		(width 0.10668)
		(layer "F.Cu")
		(net "SVID_PVDDCR_CPU1_P1_SVD_R")
	)
	(via
		(at 39.19347 -369.087654)
		(size 0.508)
		(drill 0.254)
		(layers "F.Cu" "B.Cu")
		(net "SVID_PVDDCR_CPU1_P1_SVD_R")
	)
	(via
		(at 23.622 -361.061)
		(size 0.508)
		(drill 0.254)
		(layers "F.Cu" "B.Cu")
		(net "SVID_PVDDCR_CPU1_P1_SVD_R")
	)
	(via
		(at 89.258902 -307.353208)
		(size 0.508)
		(drill 0.254)
		(layers "F.Cu" "B.Cu")
		(net "SVID_PVDDCR_CPU1_P1_SVD_R")
	)
	(segment
		(start 22.87905 -361.061)
		(end 23.622 -361.061)
		(width 0.10668)
		(layer "B.Cu")
		(net "SVID_PVDDCR_CPU1_P1_SVD_R")
	)
	(segment
		(start 90.355928 -308.450234)
		(end 89.258902 -307.353208)
		(width 0.10668)
		(layer "B.Cu")
		(net "SVID_PVDDCR_CPU1_P1_SVD_R")
	)
	(segment
		(start 90.746834 -309.007002)
		(end 90.654886 -309.007002)
		(width 0.10668)
		(layer "B.Cu")
		(net "SVID_PVDDCR_CPU1_P1_SVD_R")
	)
	(segment
		(start 90.654886 -309.007002)
		(end 90.355928 -308.708044)
		(width 0.10668)
		(layer "B.Cu")
		(net "SVID_PVDDCR_CPU1_P1_SVD_R")
	)
	(segment
		(start 90.355928 -308.708044)
		(end 90.355928 -308.450234)
		(width 0.10668)
		(layer "B.Cu")
		(net "SVID_PVDDCR_CPU1_P1_SVD_R")
	)
	(segment
		(start 24.629872 -362.068872)
		(end 26.10612 -362.068872)
		(width 0.11684)
		(layer "In6.Cu")
		(net "SVID_PVDDCR_CPU1_P1_SVD_R")
	)
	(segment
		(start 32.338518 -368.906552)
		(end 39.012368 -368.906552)
		(width 0.11684)
		(layer "In6.Cu")
		(net "SVID_PVDDCR_CPU1_P1_SVD_R")
	)
	(segment
		(start 26.524712 -366.980724)
		(end 27.021536 -367.477548)
		(width 0.11684)
		(layer "In6.Cu")
		(net "SVID_PVDDCR_CPU1_P1_SVD_R")
	)
	(segment
		(start 27.021536 -367.477548)
		(end 30.909514 -367.477548)
		(width 0.11684)
		(layer "In6.Cu")
		(net "SVID_PVDDCR_CPU1_P1_SVD_R")
	)
	(segment
		(start 26.10612 -362.068872)
		(end 26.524712 -362.487464)
		(width 0.11684)
		(layer "In6.Cu")
		(net "SVID_PVDDCR_CPU1_P1_SVD_R")
	)
	(segment
		(start 26.524712 -362.487464)
		(end 26.524712 -366.980724)
		(width 0.11684)
		(layer "In6.Cu")
		(net "SVID_PVDDCR_CPU1_P1_SVD_R")
	)
	(segment
		(start 30.909514 -367.477548)
		(end 32.338518 -368.906552)
		(width 0.11684)
		(layer "In6.Cu")
		(net "SVID_PVDDCR_CPU1_P1_SVD_R")
	)
	(segment
		(start 39.012368 -368.906552)
		(end 39.19347 -369.087654)
		(width 0.11684)
		(layer "In6.Cu")
		(net "SVID_PVDDCR_CPU1_P1_SVD_R")
	)
	(segment
		(start 23.622 -361.061)
		(end 24.629872 -362.068872)
		(width 0.11684)
		(layer "In6.Cu")
		(net "SVID_PVDDCR_CPU1_P1_SVD_R")
	)
	(segment
		(start 81.82483 -298.085764)
		(end 86.207346 -298.085764)
		(width 0.10668)
		(layer "F.Cu")
		(net "SVID_PVDDCR_CPU1_P1_SVD")
	)
	(segment
		(start 86.207346 -298.085764)
		(end 90.04808 -301.926498)
		(width 0.10668)
		(layer "F.Cu")
		(net "SVID_PVDDCR_CPU1_P1_SVD")
	)
	(segment
		(start 90.746834 -306.135024)
		(end 90.746834 -307.082952)
		(width 0.10668)
		(layer "F.Cu")
		(net "SVID_PVDDCR_CPU1_P1_SVD")
	)
	(segment
		(start 80.11795 -296.378884)
		(end 81.82483 -298.085764)
		(width 0.10668)
		(layer "F.Cu")
		(net "SVID_PVDDCR_CPU1_P1_SVD")
	)
	(segment
		(start 90.04808 -301.926498)
		(end 90.04808 -305.43627)
		(width 0.10668)
		(layer "F.Cu")
		(net "SVID_PVDDCR_CPU1_P1_SVD")
	)
	(segment
		(start 80.11795 -294.880284)
		(end 80.11795 -296.378884)
		(width 0.10668)
		(layer "F.Cu")
		(net "SVID_PVDDCR_CPU1_P1_SVD")
	)
	(segment
		(start 90.04808 -305.43627)
		(end 90.746834 -306.135024)
		(width 0.10668)
		(layer "F.Cu")
		(net "SVID_PVDDCR_CPU1_P1_SVD")
	)
	(via
		(at 90.746834 -307.082952)
		(size 0.508)
		(drill 0.254)
		(layers "F.Cu" "B.Cu")
		(net "SVID_PVDDCR_CPU1_P1_SVD")
	)
	(segment
		(start 90.746834 -307.082952)
		(end 90.746834 -308.206902)
		(width 0.10668)
		(layer "B.Cu")
		(net "SVID_PVDDCR_CPU1_P1_SVD")
	)
	(segment
		(start 41.176448 -368.304826)
		(end 39.286434 -368.304826)
		(width 0.10668)
		(layer "F.Cu")
		(net "SVID_PVDDCR_CPU1_P1_SVC_R")
	)
	(segment
		(start 42.003472 -368.304826)
		(end 41.176448 -368.304826)
		(width 0.10668)
		(layer "F.Cu")
		(net "SVID_PVDDCR_CPU1_P1_SVC_R")
	)
	(segment
		(start 117.213634 -346.733876)
		(end 96.665034 -367.282476)
		(width 0.10668)
		(layer "F.Cu")
		(net "SVID_PVDDCR_CPU1_P1_SVC_R")
	)
	(segment
		(start 117.213634 -326.949054)
		(end 117.213634 -346.733876)
		(width 0.10668)
		(layer "F.Cu")
		(net "SVID_PVDDCR_CPU1_P1_SVC_R")
	)
	(segment
		(start 101.842062 -311.577482)
		(end 117.213634 -326.949054)
		(width 0.10668)
		(layer "F.Cu")
		(net "SVID_PVDDCR_CPU1_P1_SVC_R")
	)
	(segment
		(start 23.622 -359.918)
		(end 22.87905 -359.918)
		(width 0.10668)
		(layer "F.Cu")
		(net "SVID_PVDDCR_CPU1_P1_SVC_R")
	)
	(segment
		(start 96.665034 -367.282476)
		(end 43.025822 -367.282476)
		(width 0.10668)
		(layer "F.Cu")
		(net "SVID_PVDDCR_CPU1_P1_SVC_R")
	)
	(segment
		(start 24.36495 -359.918)
		(end 23.622 -359.918)
		(width 0.10668)
		(layer "F.Cu")
		(net "SVID_PVDDCR_CPU1_P1_SVC_R")
	)
	(segment
		(start 43.025822 -367.282476)
		(end 42.003472 -368.304826)
		(width 0.10668)
		(layer "F.Cu")
		(net "SVID_PVDDCR_CPU1_P1_SVC_R")
	)
	(segment
		(start 91.962732 -311.577482)
		(end 101.842062 -311.577482)
		(width 0.10668)
		(layer "F.Cu")
		(net "SVID_PVDDCR_CPU1_P1_SVC_R")
	)
	(segment
		(start 88.884252 -308.499002)
		(end 91.962732 -311.577482)
		(width 0.10668)
		(layer "F.Cu")
		(net "SVID_PVDDCR_CPU1_P1_SVC_R")
	)
	(via
		(at 39.286434 -368.304826)
		(size 0.508)
		(drill 0.254)
		(layers "F.Cu" "B.Cu")
		(net "SVID_PVDDCR_CPU1_P1_SVC_R")
	)
	(via
		(at 23.622 -359.918)
		(size 0.508)
		(drill 0.254)
		(layers "F.Cu" "B.Cu")
		(net "SVID_PVDDCR_CPU1_P1_SVC_R")
	)
	(via
		(at 88.884252 -308.499002)
		(size 0.508)
		(drill 0.254)
		(layers "F.Cu" "B.Cu")
		(net "SVID_PVDDCR_CPU1_P1_SVC_R")
	)
	(via
		(at 41.176448 -368.304826)
		(size 0.762)
		(drill 0.381)
		(layers "F.Cu" "B.Cu")
		(net "SVID_PVDDCR_CPU1_P1_SVC_R")
	)
	(segment
		(start 89.913206 -309.527956)
		(end 88.884252 -308.499002)
		(width 0.10668)
		(layer "B.Cu")
		(net "SVID_PVDDCR_CPU1_P1_SVC_R")
	)
	(segment
		(start 22.87905 -359.918)
		(end 23.622 -359.918)
		(width 0.10668)
		(layer "B.Cu")
		(net "SVID_PVDDCR_CPU1_P1_SVC_R")
	)
	(segment
		(start 91.24188 -309.527956)
		(end 89.913206 -309.527956)
		(width 0.10668)
		(layer "B.Cu")
		(net "SVID_PVDDCR_CPU1_P1_SVC_R")
	)
	(segment
		(start 91.762834 -309.007002)
		(end 91.24188 -309.527956)
		(width 0.10668)
		(layer "B.Cu")
		(net "SVID_PVDDCR_CPU1_P1_SVC_R")
	)
	(segment
		(start 39.286434 -368.304826)
		(end 39.017956 -368.304826)
		(width 0.11684)
		(layer "In6.Cu")
		(net "SVID_PVDDCR_CPU1_P1_SVC_R")
	)
	(segment
		(start 27.108912 -362.214668)
		(end 25.885902 -360.991658)
		(width 0.11684)
		(layer "In6.Cu")
		(net "SVID_PVDDCR_CPU1_P1_SVC_R")
	)
	(segment
		(start 25.885902 -360.991658)
		(end 24.695658 -360.991658)
		(width 0.11684)
		(layer "In6.Cu")
		(net "SVID_PVDDCR_CPU1_P1_SVC_R")
	)
	(segment
		(start 31.255716 -367.029746)
		(end 27.322272 -367.029746)
		(width 0.11684)
		(layer "In6.Cu")
		(net "SVID_PVDDCR_CPU1_P1_SVC_R")
	)
	(segment
		(start 32.615886 -368.389916)
		(end 31.255716 -367.029746)
		(width 0.11684)
		(layer "In6.Cu")
		(net "SVID_PVDDCR_CPU1_P1_SVC_R")
	)
	(segment
		(start 39.017956 -368.304826)
		(end 38.932866 -368.389916)
		(width 0.11684)
		(layer "In6.Cu")
		(net "SVID_PVDDCR_CPU1_P1_SVC_R")
	)
	(segment
		(start 24.695658 -360.991658)
		(end 23.622 -359.918)
		(width 0.11684)
		(layer "In6.Cu")
		(net "SVID_PVDDCR_CPU1_P1_SVC_R")
	)
	(segment
		(start 27.322272 -367.029746)
		(end 27.108912 -366.816386)
		(width 0.11684)
		(layer "In6.Cu")
		(net "SVID_PVDDCR_CPU1_P1_SVC_R")
	)
	(segment
		(start 27.108912 -366.816386)
		(end 27.108912 -362.214668)
		(width 0.11684)
		(layer "In6.Cu")
		(net "SVID_PVDDCR_CPU1_P1_SVC_R")
	)
	(segment
		(start 38.932866 -368.389916)
		(end 32.615886 -368.389916)
		(width 0.11684)
		(layer "In6.Cu")
		(net "SVID_PVDDCR_CPU1_P1_SVC_R")
	)
	(segment
		(start 91.928188 -306.550314)
		(end 90.502994 -305.12512)
		(width 0.10668)
		(layer "F.Cu")
		(net "SVID_PVDDCR_CPU1_P1_SVC")
	)
	(segment
		(start 80.58785 -296.212768)
		(end 80.58785 -295.69029)
		(width 0.10668)
		(layer "F.Cu")
		(net "SVID_PVDDCR_CPU1_P1_SVC")
	)
	(segment
		(start 90.502994 -305.12512)
		(end 90.502994 -301.652432)
		(width 0.10668)
		(layer "F.Cu")
		(net "SVID_PVDDCR_CPU1_P1_SVC")
	)
	(segment
		(start 90.502994 -301.652432)
		(end 86.486746 -297.636184)
		(width 0.10668)
		(layer "F.Cu")
		(net "SVID_PVDDCR_CPU1_P1_SVC")
	)
	(segment
		(start 86.486746 -297.636184)
		(end 82.011266 -297.636184)
		(width 0.10668)
		(layer "F.Cu")
		(net "SVID_PVDDCR_CPU1_P1_SVC")
	)
	(segment
		(start 82.011266 -297.636184)
		(end 80.58785 -296.212768)
		(width 0.10668)
		(layer "F.Cu")
		(net "SVID_PVDDCR_CPU1_P1_SVC")
	)
	(via
		(at 91.928188 -306.550314)
		(size 0.508)
		(drill 0.254)
		(layers "F.Cu" "B.Cu")
		(net "SVID_PVDDCR_CPU1_P1_SVC")
	)
	(segment
		(start 91.762834 -308.206902)
		(end 91.928188 -308.041548)
		(width 0.10668)
		(layer "B.Cu")
		(net "SVID_PVDDCR_CPU1_P1_SVC")
	)
	(segment
		(start 91.928188 -308.041548)
		(end 91.928188 -306.550314)
		(width 0.10668)
		(layer "B.Cu")
		(net "SVID_PVDDCR_CPU1_P1_SVC")
	)
	(segment
		(start 306.4002 -358.3178)
		(end 306.4002 -357.401876)
		(width 0.10668)
		(layer "F.Cu")
		(net "SVID_PVDDCR_CPU1_P0_SVTO_R")
	)
	(segment
		(start 306.962302 -358.879902)
		(end 306.4002 -358.3178)
		(width 0.10668)
		(layer "F.Cu")
		(net "SVID_PVDDCR_CPU1_P0_SVTO_R")
	)
	(segment
		(start 307.258974 -358.879902)
		(end 306.962302 -358.879902)
		(width 0.10668)
		(layer "F.Cu")
		(net "SVID_PVDDCR_CPU1_P0_SVTO_R")
	)
	(segment
		(start 306.4002 -357.401876)
		(end 305.848766 -356.850442)
		(width 0.10668)
		(layer "F.Cu")
		(net "SVID_PVDDCR_CPU1_P0_SVTO_R")
	)
	(segment
		(start 304.81905 -356.249986)
		(end 304.81905 -355.854)
		(width 0.10668)
		(layer "F.Cu")
		(net "SVID_PVDDCR_CPU1_P0_SVTO_R")
	)
	(segment
		(start 305.848766 -356.850442)
		(end 305.419506 -356.850442)
		(width 0.10668)
		(layer "F.Cu")
		(net "SVID_PVDDCR_CPU1_P0_SVTO_R")
	)
	(segment
		(start 305.419506 -356.850442)
		(end 304.81905 -356.249986)
		(width 0.10668)
		(layer "F.Cu")
		(net "SVID_PVDDCR_CPU1_P0_SVTO_R")
	)
	(segment
		(start 327.587864 -294.070024)
		(end 327.587864 -295.080944)
		(width 0.10668)
		(layer "F.Cu")
		(net "SVID_PVDDCR_CPU1_P0_SVTO")
	)
	(segment
		(start 327.587864 -295.080944)
		(end 327.28535 -295.383458)
		(width 0.10668)
		(layer "F.Cu")
		(net "SVID_PVDDCR_CPU1_P0_SVTO")
	)
	(segment
		(start 334.68183 -309.48249)
		(end 334.969104 -309.769764)
		(width 0.10668)
		(layer "F.Cu")
		(net "SVID_PVDDCR_CPU1_P0_SVTO")
	)
	(segment
		(start 334.68183 -303.465738)
		(end 334.68183 -309.48249)
		(width 0.10668)
		(layer "F.Cu")
		(net "SVID_PVDDCR_CPU1_P0_SVTO")
	)
	(segment
		(start 326.713342 -296.077386)
		(end 327.46061 -296.824654)
		(width 0.10668)
		(layer "F.Cu")
		(net "SVID_PVDDCR_CPU1_P0_SVTO")
	)
	(segment
		(start 327.46061 -296.824654)
		(end 328.040746 -296.824654)
		(width 0.10668)
		(layer "F.Cu")
		(net "SVID_PVDDCR_CPU1_P0_SVTO")
	)
	(segment
		(start 327.28535 -295.383458)
		(end 327.033382 -295.383458)
		(width 0.10668)
		(layer "F.Cu")
		(net "SVID_PVDDCR_CPU1_P0_SVTO")
	)
	(segment
		(start 326.713342 -295.703498)
		(end 326.713342 -296.077386)
		(width 0.10668)
		(layer "F.Cu")
		(net "SVID_PVDDCR_CPU1_P0_SVTO")
	)
	(segment
		(start 303.276 -355.854)
		(end 302.53305 -355.854)
		(width 0.10668)
		(layer "F.Cu")
		(net "SVID_PVDDCR_CPU1_P0_SVTO")
	)
	(segment
		(start 304.01895 -355.854)
		(end 303.276 -355.854)
		(width 0.10668)
		(layer "F.Cu")
		(net "SVID_PVDDCR_CPU1_P0_SVTO")
	)
	(segment
		(start 327.033382 -295.383458)
		(end 326.713342 -295.703498)
		(width 0.10668)
		(layer "F.Cu")
		(net "SVID_PVDDCR_CPU1_P0_SVTO")
	)
	(segment
		(start 328.040746 -296.824654)
		(end 334.68183 -303.465738)
		(width 0.10668)
		(layer "F.Cu")
		(net "SVID_PVDDCR_CPU1_P0_SVTO")
	)
	(via
		(at 303.276 -355.854)
		(size 0.508)
		(drill 0.254)
		(layers "F.Cu" "B.Cu")
		(net "SVID_PVDDCR_CPU1_P0_SVTO")
	)
	(via
		(at 334.969104 -309.769764)
		(size 0.508)
		(drill 0.254)
		(layers "F.Cu" "B.Cu")
		(net "SVID_PVDDCR_CPU1_P0_SVTO")
	)
	(via
		(at 330.4032 -361.1372)
		(size 0.508)
		(drill 0.254)
		(layers "F.Cu" "B.Cu")
		(net "SVID_PVDDCR_CPU1_P0_SVTO")
	)
	(segment
		(start 367.157254 -358.34447)
		(end 367.157254 -334.903318)
		(width 0.10668)
		(layer "B.Cu")
		(net "SVID_PVDDCR_CPU1_P0_SVTO")
	)
	(segment
		(start 356.670102 -320.969132)
		(end 348.319344 -312.618374)
		(width 0.10668)
		(layer "B.Cu")
		(net "SVID_PVDDCR_CPU1_P0_SVTO")
	)
	(segment
		(start 332.59649 -362.489242)
		(end 352.520758 -362.489242)
		(width 0.10668)
		(layer "B.Cu")
		(net "SVID_PVDDCR_CPU1_P0_SVTO")
	)
	(segment
		(start 302.53305 -355.854)
		(end 303.276 -355.854)
		(width 0.10668)
		(layer "B.Cu")
		(net "SVID_PVDDCR_CPU1_P0_SVTO")
	)
	(segment
		(start 303.276 -355.854)
		(end 304.01895 -355.854)
		(width 0.10668)
		(layer "B.Cu")
		(net "SVID_PVDDCR_CPU1_P0_SVTO")
	)
	(segment
		(start 331.244448 -361.1372)
		(end 332.59649 -362.489242)
		(width 0.10668)
		(layer "B.Cu")
		(net "SVID_PVDDCR_CPU1_P0_SVTO")
	)
	(segment
		(start 363.936788 -361.564936)
		(end 367.157254 -358.34447)
		(width 0.10668)
		(layer "B.Cu")
		(net "SVID_PVDDCR_CPU1_P0_SVTO")
	)
	(segment
		(start 358.984042 -329.984862)
		(end 356.670102 -327.670922)
		(width 0.10668)
		(layer "B.Cu")
		(net "SVID_PVDDCR_CPU1_P0_SVTO")
	)
	(segment
		(start 336.598514 -312.618374)
		(end 334.969104 -310.988964)
		(width 0.10668)
		(layer "B.Cu")
		(net "SVID_PVDDCR_CPU1_P0_SVTO")
	)
	(segment
		(start 334.969104 -310.988964)
		(end 334.969104 -309.769764)
		(width 0.10668)
		(layer "B.Cu")
		(net "SVID_PVDDCR_CPU1_P0_SVTO")
	)
	(segment
		(start 367.157254 -334.903318)
		(end 362.238798 -329.984862)
		(width 0.10668)
		(layer "B.Cu")
		(net "SVID_PVDDCR_CPU1_P0_SVTO")
	)
	(segment
		(start 362.238798 -329.984862)
		(end 358.984042 -329.984862)
		(width 0.10668)
		(layer "B.Cu")
		(net "SVID_PVDDCR_CPU1_P0_SVTO")
	)
	(segment
		(start 348.319344 -312.618374)
		(end 336.598514 -312.618374)
		(width 0.10668)
		(layer "B.Cu")
		(net "SVID_PVDDCR_CPU1_P0_SVTO")
	)
	(segment
		(start 356.670102 -327.670922)
		(end 356.670102 -320.969132)
		(width 0.10668)
		(layer "B.Cu")
		(net "SVID_PVDDCR_CPU1_P0_SVTO")
	)
	(segment
		(start 352.520758 -362.489242)
		(end 353.445064 -361.564936)
		(width 0.10668)
		(layer "B.Cu")
		(net "SVID_PVDDCR_CPU1_P0_SVTO")
	)
	(segment
		(start 330.4032 -361.1372)
		(end 331.244448 -361.1372)
		(width 0.10668)
		(layer "B.Cu")
		(net "SVID_PVDDCR_CPU1_P0_SVTO")
	)
	(segment
		(start 353.445064 -361.564936)
		(end 363.936788 -361.564936)
		(width 0.10668)
		(layer "B.Cu")
		(net "SVID_PVDDCR_CPU1_P0_SVTO")
	)
	(segment
		(start 308.329838 -356.202234)
		(end 310.115204 -356.202234)
		(width 0.11684)
		(layer "In13.Cu")
		(net "SVID_PVDDCR_CPU1_P0_SVTO")
	)
	(segment
		(start 312.746898 -357.09352)
		(end 313.234578 -357.5812)
		(width 0.11684)
		(layer "In13.Cu")
		(net "SVID_PVDDCR_CPU1_P0_SVTO")
	)
	(segment
		(start 303.539144 -355.590856)
		(end 307.71846 -355.590856)
		(width 0.11684)
		(layer "In13.Cu")
		(net "SVID_PVDDCR_CPU1_P0_SVTO")
	)
	(segment
		(start 307.71846 -355.590856)
		(end 308.329838 -356.202234)
		(width 0.11684)
		(layer "In13.Cu")
		(net "SVID_PVDDCR_CPU1_P0_SVTO")
	)
	(segment
		(start 312.746898 -355.972364)
		(end 312.746898 -357.09352)
		(width 0.11684)
		(layer "In13.Cu")
		(net "SVID_PVDDCR_CPU1_P0_SVTO")
	)
	(segment
		(start 311.113932 -355.203506)
		(end 311.97804 -355.203506)
		(width 0.11684)
		(layer "In13.Cu")
		(net "SVID_PVDDCR_CPU1_P0_SVTO")
	)
	(segment
		(start 326.8472 -357.5812)
		(end 330.4032 -361.1372)
		(width 0.11684)
		(layer "In13.Cu")
		(net "SVID_PVDDCR_CPU1_P0_SVTO")
	)
	(segment
		(start 311.97804 -355.203506)
		(end 312.746898 -355.972364)
		(width 0.11684)
		(layer "In13.Cu")
		(net "SVID_PVDDCR_CPU1_P0_SVTO")
	)
	(segment
		(start 310.115204 -356.202234)
		(end 311.113932 -355.203506)
		(width 0.11684)
		(layer "In13.Cu")
		(net "SVID_PVDDCR_CPU1_P0_SVTO")
	)
	(segment
		(start 313.234578 -357.5812)
		(end 326.8472 -357.5812)
		(width 0.11684)
		(layer "In13.Cu")
		(net "SVID_PVDDCR_CPU1_P0_SVTO")
	)
	(segment
		(start 303.276 -355.854)
		(end 303.539144 -355.590856)
		(width 0.11684)
		(layer "In13.Cu")
		(net "SVID_PVDDCR_CPU1_P0_SVTO")
	)
	(segment
		(start 304.960528 -354.711)
		(end 305.631088 -355.38156)
		(width 0.10668)
		(layer "F.Cu")
		(net "SVID_PVDDCR_CPU1_P0_SVTI_R")
	)
	(segment
		(start 304.81905 -354.711)
		(end 304.960528 -354.711)
		(width 0.10668)
		(layer "F.Cu")
		(net "SVID_PVDDCR_CPU1_P0_SVTI_R")
	)
	(segment
		(start 306.241958 -355.99243)
		(end 306.241958 -356.72141)
		(width 0.10668)
		(layer "F.Cu")
		(net "SVID_PVDDCR_CPU1_P0_SVTI_R")
	)
	(segment
		(start 306.8574 -358.3178)
		(end 307.019706 -358.480106)
		(width 0.10668)
		(layer "F.Cu")
		(net "SVID_PVDDCR_CPU1_P0_SVTI_R")
	)
	(segment
		(start 307.019706 -358.480106)
		(end 307.258974 -358.480106)
		(width 0.10668)
		(layer "F.Cu")
		(net "SVID_PVDDCR_CPU1_P0_SVTI_R")
	)
	(segment
		(start 305.631088 -355.38156)
		(end 306.241958 -355.99243)
		(width 0.10668)
		(layer "F.Cu")
		(net "SVID_PVDDCR_CPU1_P0_SVTI_R")
	)
	(segment
		(start 306.241958 -356.72141)
		(end 306.8574 -357.336852)
		(width 0.10668)
		(layer "F.Cu")
		(net "SVID_PVDDCR_CPU1_P0_SVTI_R")
	)
	(segment
		(start 306.8574 -357.336852)
		(end 306.8574 -358.3178)
		(width 0.10668)
		(layer "F.Cu")
		(net "SVID_PVDDCR_CPU1_P0_SVTI_R")
	)
	(via
		(at 305.631088 -355.38156)
		(size 0.762)
		(drill 0.381)
		(layers "F.Cu" "B.Cu")
		(net "SVID_PVDDCR_CPU1_P0_SVTI_R")
	)
	(segment
		(start 303.351184 -354.711)
		(end 302.53305 -354.711)
		(width 0.10668)
		(layer "F.Cu")
		(net "SVID_PVDDCR_CPU1_P0_SVTI")
	)
	(segment
		(start 304.01895 -354.711)
		(end 303.351184 -354.711)
		(width 0.10668)
		(layer "F.Cu")
		(net "SVID_PVDDCR_CPU1_P0_SVTI")
	)
	(via
		(at 303.351184 -354.711)
		(size 0.508)
		(drill 0.254)
		(layers "F.Cu" "B.Cu")
		(net "SVID_PVDDCR_CPU1_P0_SVTI")
	)
	(segment
		(start 302.53305 -354.711)
		(end 303.351184 -354.711)
		(width 0.10668)
		(layer "B.Cu")
		(net "SVID_PVDDCR_CPU1_P0_SVTI")
	)
	(segment
		(start 303.257966 -358.14)
		(end 302.53305 -358.14)
		(width 0.10668)
		(layer "F.Cu")
		(net "SVID_PVDDCR_CPU1_P0_SVD_R")
	)
	(segment
		(start 304.01895 -358.14)
		(end 303.257966 -358.14)
		(width 0.10668)
		(layer "F.Cu")
		(net "SVID_PVDDCR_CPU1_P0_SVD_R")
	)
	(via
		(at 329.1078 -361.1372)
		(size 0.508)
		(drill 0.254)
		(layers "F.Cu" "B.Cu")
		(net "SVID_PVDDCR_CPU1_P0_SVD_R")
	)
	(via
		(at 303.257966 -358.14)
		(size 0.508)
		(drill 0.254)
		(layers "F.Cu" "B.Cu")
		(net "SVID_PVDDCR_CPU1_P0_SVD_R")
	)
	(segment
		(start 364.286038 -362.021628)
		(end 367.726976 -358.58069)
		(width 0.10668)
		(layer "B.Cu")
		(net "SVID_PVDDCR_CPU1_P0_SVD_R")
	)
	(segment
		(start 367.726976 -334.667098)
		(end 362.475018 -329.41514)
		(width 0.10668)
		(layer "B.Cu")
		(net "SVID_PVDDCR_CPU1_P0_SVD_R")
	)
	(segment
		(start 362.475018 -329.41514)
		(end 359.209086 -329.41514)
		(width 0.10668)
		(layer "B.Cu")
		(net "SVID_PVDDCR_CPU1_P0_SVD_R")
	)
	(segment
		(start 352.859086 -362.956856)
		(end 353.794314 -362.021628)
		(width 0.10668)
		(layer "B.Cu")
		(net "SVID_PVDDCR_CPU1_P0_SVD_R")
	)
	(segment
		(start 302.53305 -358.14)
		(end 303.257966 -358.14)
		(width 0.10668)
		(layer "B.Cu")
		(net "SVID_PVDDCR_CPU1_P0_SVD_R")
	)
	(segment
		(start 353.794314 -362.021628)
		(end 364.286038 -362.021628)
		(width 0.10668)
		(layer "B.Cu")
		(net "SVID_PVDDCR_CPU1_P0_SVD_R")
	)
	(segment
		(start 332.359 -362.956856)
		(end 352.859086 -362.956856)
		(width 0.10668)
		(layer "B.Cu")
		(net "SVID_PVDDCR_CPU1_P0_SVD_R")
	)
	(segment
		(start 329.1078 -361.1372)
		(end 329.9968 -362.0262)
		(width 0.10668)
		(layer "B.Cu")
		(net "SVID_PVDDCR_CPU1_P0_SVD_R")
	)
	(segment
		(start 329.9968 -362.0262)
		(end 331.428344 -362.0262)
		(width 0.10668)
		(layer "B.Cu")
		(net "SVID_PVDDCR_CPU1_P0_SVD_R")
	)
	(segment
		(start 367.726976 -358.58069)
		(end 367.726976 -334.667098)
		(width 0.10668)
		(layer "B.Cu")
		(net "SVID_PVDDCR_CPU1_P0_SVD_R")
	)
	(segment
		(start 359.209086 -329.41514)
		(end 357.886508 -328.092562)
		(width 0.10668)
		(layer "B.Cu")
		(net "SVID_PVDDCR_CPU1_P0_SVD_R")
	)
	(segment
		(start 357.886508 -318.94018)
		(end 348.94901 -310.002682)
		(width 0.10668)
		(layer "B.Cu")
		(net "SVID_PVDDCR_CPU1_P0_SVD_R")
	)
	(segment
		(start 348.94901 -310.002682)
		(end 346.39885 -310.002682)
		(width 0.10668)
		(layer "B.Cu")
		(net "SVID_PVDDCR_CPU1_P0_SVD_R")
	)
	(segment
		(start 331.428344 -362.0262)
		(end 332.359 -362.956856)
		(width 0.10668)
		(layer "B.Cu")
		(net "SVID_PVDDCR_CPU1_P0_SVD_R")
	)
	(segment
		(start 344.347546 -312.053986)
		(end 339.548978 -312.053986)
		(width 0.10668)
		(layer "B.Cu")
		(net "SVID_PVDDCR_CPU1_P0_SVD_R")
	)
	(segment
		(start 357.886508 -328.092562)
		(end 357.886508 -318.94018)
		(width 0.10668)
		(layer "B.Cu")
		(net "SVID_PVDDCR_CPU1_P0_SVD_R")
	)
	(segment
		(start 346.39885 -310.002682)
		(end 344.347546 -312.053986)
		(width 0.10668)
		(layer "B.Cu")
		(net "SVID_PVDDCR_CPU1_P0_SVD_R")
	)
	(segment
		(start 312.799222 -358.4956)
		(end 312.46826 -358.164638)
		(width 0.11684)
		(layer "In13.Cu")
		(net "SVID_PVDDCR_CPU1_P0_SVD_R")
	)
	(segment
		(start 312.46826 -358.164638)
		(end 303.282604 -358.164638)
		(width 0.11684)
		(layer "In13.Cu")
		(net "SVID_PVDDCR_CPU1_P0_SVD_R")
	)
	(segment
		(start 326.4662 -358.4956)
		(end 312.799222 -358.4956)
		(width 0.11684)
		(layer "In13.Cu")
		(net "SVID_PVDDCR_CPU1_P0_SVD_R")
	)
	(segment
		(start 303.282604 -358.164638)
		(end 303.257966 -358.14)
		(width 0.11684)
		(layer "In13.Cu")
		(net "SVID_PVDDCR_CPU1_P0_SVD_R")
	)
	(segment
		(start 329.1078 -361.1372)
		(end 326.4662 -358.4956)
		(width 0.11684)
		(layer "In13.Cu")
		(net "SVID_PVDDCR_CPU1_P0_SVD_R")
	)
	(segment
		(start 328.058018 -294.88003)
		(end 328.058018 -295.927272)
		(width 0.10668)
		(layer "F.Cu")
		(net "SVID_PVDDCR_CPU1_P0_SVD")
	)
	(segment
		(start 335.175606 -307.461666)
		(end 335.181194 -307.467254)
		(width 0.10668)
		(layer "F.Cu")
		(net "SVID_PVDDCR_CPU1_P0_SVD")
	)
	(segment
		(start 335.181194 -307.467254)
		(end 335.181194 -308.56809)
		(width 0.10668)
		(layer "F.Cu")
		(net "SVID_PVDDCR_CPU1_P0_SVD")
	)
	(segment
		(start 335.181194 -306.702206)
		(end 335.175606 -306.707794)
		(width 0.10668)
		(layer "F.Cu")
		(net "SVID_PVDDCR_CPU1_P0_SVD")
	)
	(segment
		(start 328.058018 -295.927272)
		(end 335.181194 -303.050448)
		(width 0.10668)
		(layer "F.Cu")
		(net "SVID_PVDDCR_CPU1_P0_SVD")
	)
	(segment
		(start 335.181194 -303.050448)
		(end 335.181194 -306.702206)
		(width 0.10668)
		(layer "F.Cu")
		(net "SVID_PVDDCR_CPU1_P0_SVD")
	)
	(segment
		(start 335.181194 -308.56809)
		(end 335.823814 -309.21071)
		(width 0.10668)
		(layer "F.Cu")
		(net "SVID_PVDDCR_CPU1_P0_SVD")
	)
	(segment
		(start 335.175606 -306.707794)
		(end 335.175606 -307.461666)
		(width 0.10668)
		(layer "F.Cu")
		(net "SVID_PVDDCR_CPU1_P0_SVD")
	)
	(via
		(at 337.694778 -312.053986)
		(size 0.6604)
		(drill 0.3302)
		(layers "F.Cu" "B.Cu")
		(net "SVID_PVDDCR_CPU1_P0_SVD")
	)
	(via
		(at 335.823814 -309.21071)
		(size 0.508)
		(drill 0.254)
		(layers "F.Cu" "B.Cu")
		(net "SVID_PVDDCR_CPU1_P0_SVD")
	)
	(segment
		(start 337.694778 -312.053986)
		(end 337.477862 -312.053986)
		(width 0.10668)
		(layer "B.Cu")
		(net "SVID_PVDDCR_CPU1_P0_SVD")
	)
	(segment
		(start 338.748878 -312.053986)
		(end 337.694778 -312.053986)
		(width 0.10668)
		(layer "B.Cu")
		(net "SVID_PVDDCR_CPU1_P0_SVD")
	)
	(segment
		(start 337.477862 -312.053986)
		(end 335.823814 -310.399938)
		(width 0.10668)
		(layer "B.Cu")
		(net "SVID_PVDDCR_CPU1_P0_SVD")
	)
	(segment
		(start 335.823814 -310.399938)
		(end 335.823814 -309.21071)
		(width 0.10668)
		(layer "B.Cu")
		(net "SVID_PVDDCR_CPU1_P0_SVD")
	)
	(segment
		(start 304.01895 -356.997)
		(end 303.368964 -356.997)
		(width 0.10668)
		(layer "F.Cu")
		(net "SVID_PVDDCR_CPU1_P0_SVC_R")
	)
	(segment
		(start 303.368964 -356.997)
		(end 302.53305 -356.997)
		(width 0.10668)
		(layer "F.Cu")
		(net "SVID_PVDDCR_CPU1_P0_SVC_R")
	)
	(via
		(at 330.6826 -362.6358)
		(size 0.508)
		(drill 0.254)
		(layers "F.Cu" "B.Cu")
		(net "SVID_PVDDCR_CPU1_P0_SVC_R")
	)
	(via
		(at 303.368964 -356.997)
		(size 0.508)
		(drill 0.254)
		(layers "F.Cu" "B.Cu")
		(net "SVID_PVDDCR_CPU1_P0_SVC_R")
	)
	(segment
		(start 302.53305 -356.997)
		(end 303.368964 -356.997)
		(width 0.10668)
		(layer "B.Cu")
		(net "SVID_PVDDCR_CPU1_P0_SVC_R")
	)
	(segment
		(start 354.108004 -362.547916)
		(end 364.599728 -362.547916)
		(width 0.10668)
		(layer "B.Cu")
		(net "SVID_PVDDCR_CPU1_P0_SVC_R")
	)
	(segment
		(start 358.35717 -317.587884)
		(end 350.10979 -309.340504)
		(width 0.10668)
		(layer "B.Cu")
		(net "SVID_PVDDCR_CPU1_P0_SVC_R")
	)
	(segment
		(start 364.599728 -362.547916)
		(end 368.320828 -358.826816)
		(width 0.10668)
		(layer "B.Cu")
		(net "SVID_PVDDCR_CPU1_P0_SVC_R")
	)
	(segment
		(start 344.167714 -310.974486)
		(end 341.875364 -310.974486)
		(width 0.10668)
		(layer "B.Cu")
		(net "SVID_PVDDCR_CPU1_P0_SVC_R")
	)
	(segment
		(start 353.214686 -363.441234)
		(end 354.108004 -362.547916)
		(width 0.10668)
		(layer "B.Cu")
		(net "SVID_PVDDCR_CPU1_P0_SVC_R")
	)
	(segment
		(start 362.721144 -328.821288)
		(end 359.274872 -328.821288)
		(width 0.10668)
		(layer "B.Cu")
		(net "SVID_PVDDCR_CPU1_P0_SVC_R")
	)
	(segment
		(start 368.320828 -358.826816)
		(end 368.320828 -334.420972)
		(width 0.10668)
		(layer "B.Cu")
		(net "SVID_PVDDCR_CPU1_P0_SVC_R")
	)
	(segment
		(start 331.346048 -362.6358)
		(end 332.151482 -363.441234)
		(width 0.10668)
		(layer "B.Cu")
		(net "SVID_PVDDCR_CPU1_P0_SVC_R")
	)
	(segment
		(start 358.35717 -327.903586)
		(end 358.35717 -317.587884)
		(width 0.10668)
		(layer "B.Cu")
		(net "SVID_PVDDCR_CPU1_P0_SVC_R")
	)
	(segment
		(start 350.10979 -309.340504)
		(end 345.801696 -309.340504)
		(width 0.10668)
		(layer "B.Cu")
		(net "SVID_PVDDCR_CPU1_P0_SVC_R")
	)
	(segment
		(start 345.801696 -309.340504)
		(end 344.167714 -310.974486)
		(width 0.10668)
		(layer "B.Cu")
		(net "SVID_PVDDCR_CPU1_P0_SVC_R")
	)
	(segment
		(start 330.6826 -362.6358)
		(end 331.346048 -362.6358)
		(width 0.10668)
		(layer "B.Cu")
		(net "SVID_PVDDCR_CPU1_P0_SVC_R")
	)
	(segment
		(start 359.274872 -328.821288)
		(end 358.35717 -327.903586)
		(width 0.10668)
		(layer "B.Cu")
		(net "SVID_PVDDCR_CPU1_P0_SVC_R")
	)
	(segment
		(start 368.320828 -334.420972)
		(end 362.721144 -328.821288)
		(width 0.10668)
		(layer "B.Cu")
		(net "SVID_PVDDCR_CPU1_P0_SVC_R")
	)
	(segment
		(start 332.151482 -363.441234)
		(end 353.214686 -363.441234)
		(width 0.10668)
		(layer "B.Cu")
		(net "SVID_PVDDCR_CPU1_P0_SVC_R")
	)
	(segment
		(start 329.6666 -361.6198)
		(end 329.6666 -361.061)
		(width 0.11684)
		(layer "In13.Cu")
		(net "SVID_PVDDCR_CPU1_P0_SVC_R")
	)
	(segment
		(start 306.581302 -357.711502)
		(end 305.8668 -356.997)
		(width 0.11684)
		(layer "In13.Cu")
		(net "SVID_PVDDCR_CPU1_P0_SVC_R")
	)
	(segment
		(start 312.611516 -357.711502)
		(end 306.581302 -357.711502)
		(width 0.11684)
		(layer "In13.Cu")
		(net "SVID_PVDDCR_CPU1_P0_SVC_R")
	)
	(segment
		(start 326.644 -358.0384)
		(end 312.938414 -358.0384)
		(width 0.11684)
		(layer "In13.Cu")
		(net "SVID_PVDDCR_CPU1_P0_SVC_R")
	)
	(segment
		(start 312.938414 -358.0384)
		(end 312.611516 -357.711502)
		(width 0.11684)
		(layer "In13.Cu")
		(net "SVID_PVDDCR_CPU1_P0_SVC_R")
	)
	(segment
		(start 305.8668 -356.997)
		(end 303.368964 -356.997)
		(width 0.11684)
		(layer "In13.Cu")
		(net "SVID_PVDDCR_CPU1_P0_SVC_R")
	)
	(segment
		(start 329.6666 -361.061)
		(end 326.644 -358.0384)
		(width 0.11684)
		(layer "In13.Cu")
		(net "SVID_PVDDCR_CPU1_P0_SVC_R")
	)
	(segment
		(start 330.6826 -362.6358)
		(end 329.6666 -361.6198)
		(width 0.11684)
		(layer "In13.Cu")
		(net "SVID_PVDDCR_CPU1_P0_SVC_R")
	)
	(segment
		(start 335.632044 -302.794162)
		(end 335.632044 -306.887372)
		(width 0.10668)
		(layer "F.Cu")
		(net "SVID_PVDDCR_CPU1_P0_SVC")
	)
	(segment
		(start 335.625186 -307.27523)
		(end 335.632044 -307.282088)
		(width 0.10668)
		(layer "F.Cu")
		(net "SVID_PVDDCR_CPU1_P0_SVC")
	)
	(segment
		(start 335.632044 -308.077616)
		(end 336.524854 -308.970426)
		(width 0.10668)
		(layer "F.Cu")
		(net "SVID_PVDDCR_CPU1_P0_SVC")
	)
	(segment
		(start 335.632044 -307.282088)
		(end 335.632044 -308.077616)
		(width 0.10668)
		(layer "F.Cu")
		(net "SVID_PVDDCR_CPU1_P0_SVC")
	)
	(segment
		(start 328.527918 -295.690036)
		(end 335.632044 -302.794162)
		(width 0.10668)
		(layer "F.Cu")
		(net "SVID_PVDDCR_CPU1_P0_SVC")
	)
	(segment
		(start 335.625186 -306.89423)
		(end 335.625186 -307.27523)
		(width 0.10668)
		(layer "F.Cu")
		(net "SVID_PVDDCR_CPU1_P0_SVC")
	)
	(segment
		(start 335.632044 -306.887372)
		(end 335.625186 -306.89423)
		(width 0.10668)
		(layer "F.Cu")
		(net "SVID_PVDDCR_CPU1_P0_SVC")
	)
	(via
		(at 336.524854 -308.970426)
		(size 0.508)
		(drill 0.254)
		(layers "F.Cu" "B.Cu")
		(net "SVID_PVDDCR_CPU1_P0_SVC")
	)
	(via
		(at 339.675216 -311.155842)
		(size 0.6604)
		(drill 0.3302)
		(layers "F.Cu" "B.Cu")
		(net "SVID_PVDDCR_CPU1_P0_SVC")
	)
	(segment
		(start 337.711542 -311.155842)
		(end 336.524854 -309.969154)
		(width 0.10668)
		(layer "B.Cu")
		(net "SVID_PVDDCR_CPU1_P0_SVC")
	)
	(segment
		(start 336.524854 -309.969154)
		(end 336.524854 -308.970426)
		(width 0.10668)
		(layer "B.Cu")
		(net "SVID_PVDDCR_CPU1_P0_SVC")
	)
	(segment
		(start 339.675216 -311.155842)
		(end 337.711542 -311.155842)
		(width 0.10668)
		(layer "B.Cu")
		(net "SVID_PVDDCR_CPU1_P0_SVC")
	)
	(segment
		(start 341.075264 -310.974486)
		(end 340.893908 -311.155842)
		(width 0.10668)
		(layer "B.Cu")
		(net "SVID_PVDDCR_CPU1_P0_SVC")
	)
	(segment
		(start 340.893908 -311.155842)
		(end 339.675216 -311.155842)
		(width 0.10668)
		(layer "B.Cu")
		(net "SVID_PVDDCR_CPU1_P0_SVC")
	)
	(via
		(at 91.558618 -147.760436)
		(size 0.6604)
		(drill 0.3302)
		(layers "F.Cu" "B.Cu")
		(net "SVID_PVDDCR_CPU0_P1_SVTO_R")
	)
	(segment
		(start 92.513912 -146.558508)
		(end 92.795852 -146.558508)
		(width 0.10668)
		(layer "B.Cu")
		(net "SVID_PVDDCR_CPU0_P1_SVTO_R")
	)
	(segment
		(start 91.558618 -147.760436)
		(end 92.12453 -147.194524)
		(width 0.10668)
		(layer "B.Cu")
		(net "SVID_PVDDCR_CPU0_P1_SVTO_R")
	)
	(segment
		(start 90.609928 -148.94941)
		(end 91.11869 -148.94941)
		(width 0.10668)
		(layer "B.Cu")
		(net "SVID_PVDDCR_CPU0_P1_SVTO_R")
	)
	(segment
		(start 91.11869 -148.94941)
		(end 91.558618 -148.509482)
		(width 0.10668)
		(layer "B.Cu")
		(net "SVID_PVDDCR_CPU0_P1_SVTO_R")
	)
	(segment
		(start 91.558618 -148.509482)
		(end 91.558618 -147.760436)
		(width 0.10668)
		(layer "B.Cu")
		(net "SVID_PVDDCR_CPU0_P1_SVTO_R")
	)
	(segment
		(start 92.12453 -147.194524)
		(end 92.12453 -146.94789)
		(width 0.10668)
		(layer "B.Cu")
		(net "SVID_PVDDCR_CPU0_P1_SVTO_R")
	)
	(segment
		(start 92.12453 -146.94789)
		(end 92.513912 -146.558508)
		(width 0.10668)
		(layer "B.Cu")
		(net "SVID_PVDDCR_CPU0_P1_SVTO_R")
	)
	(segment
		(start 88.577928 -148.94941)
		(end 89.193878 -148.94941)
		(width 0.10668)
		(layer "F.Cu")
		(net "SVID_PVDDCR_CPU0_P1_SVTO")
	)
	(segment
		(start 134.579614 -219.15882)
		(end 128.18364 -219.15882)
		(width 0.10668)
		(layer "F.Cu")
		(net "SVID_PVDDCR_CPU0_P1_SVTO")
	)
	(segment
		(start 128.18364 -219.15882)
		(end 127.757936 -219.584524)
		(width 0.10668)
		(layer "F.Cu")
		(net "SVID_PVDDCR_CPU0_P1_SVTO")
	)
	(segment
		(start 85.7885 -148.5265)
		(end 86.868 -149.606)
		(width 0.10668)
		(layer "F.Cu")
		(net "SVID_PVDDCR_CPU0_P1_SVTO")
	)
	(segment
		(start 86.868 -149.606)
		(end 87.921338 -149.606)
		(width 0.10668)
		(layer "F.Cu")
		(net "SVID_PVDDCR_CPU0_P1_SVTO")
	)
	(segment
		(start 85.471 -148.209)
		(end 85.471 -138.38174)
		(width 0.10668)
		(layer "F.Cu")
		(net "SVID_PVDDCR_CPU0_P1_SVTO")
	)
	(segment
		(start 133.853428 -211.585556)
		(end 135.58393 -215.763602)
		(width 0.10668)
		(layer "F.Cu")
		(net "SVID_PVDDCR_CPU0_P1_SVTO")
	)
	(segment
		(start 133.161278 -131.675632)
		(end 145.903696 -144.41805)
		(width 0.10668)
		(layer "F.Cu")
		(net "SVID_PVDDCR_CPU0_P1_SVTO")
	)
	(segment
		(start 146.901154 -196.9389)
		(end 133.853428 -209.986626)
		(width 0.10668)
		(layer "F.Cu")
		(net "SVID_PVDDCR_CPU0_P1_SVTO")
	)
	(segment
		(start 145.903696 -191.802766)
		(end 146.901154 -192.800224)
		(width 0.10668)
		(layer "F.Cu")
		(net "SVID_PVDDCR_CPU0_P1_SVTO")
	)
	(segment
		(start 85.471 -138.38174)
		(end 92.177108 -131.675632)
		(width 0.10668)
		(layer "F.Cu")
		(net "SVID_PVDDCR_CPU0_P1_SVTO")
	)
	(segment
		(start 92.177108 -131.675632)
		(end 133.161278 -131.675632)
		(width 0.10668)
		(layer "F.Cu")
		(net "SVID_PVDDCR_CPU0_P1_SVTO")
	)
	(segment
		(start 146.901154 -192.800224)
		(end 146.901154 -196.9389)
		(width 0.10668)
		(layer "F.Cu")
		(net "SVID_PVDDCR_CPU0_P1_SVTO")
	)
	(segment
		(start 135.58393 -215.763602)
		(end 135.58393 -218.154504)
		(width 0.10668)
		(layer "F.Cu")
		(net "SVID_PVDDCR_CPU0_P1_SVTO")
	)
	(segment
		(start 87.921338 -149.606)
		(end 88.577928 -148.94941)
		(width 0.10668)
		(layer "F.Cu")
		(net "SVID_PVDDCR_CPU0_P1_SVTO")
	)
	(segment
		(start 90.419428 -148.94941)
		(end 89.193878 -148.94941)
		(width 0.10668)
		(layer "F.Cu")
		(net "SVID_PVDDCR_CPU0_P1_SVTO")
	)
	(segment
		(start 145.903696 -144.41805)
		(end 145.903696 -191.802766)
		(width 0.10668)
		(layer "F.Cu")
		(net "SVID_PVDDCR_CPU0_P1_SVTO")
	)
	(segment
		(start 135.58393 -218.154504)
		(end 134.579614 -219.15882)
		(width 0.10668)
		(layer "F.Cu")
		(net "SVID_PVDDCR_CPU0_P1_SVTO")
	)
	(segment
		(start 85.7885 -148.5265)
		(end 85.471 -148.209)
		(width 0.10668)
		(layer "F.Cu")
		(net "SVID_PVDDCR_CPU0_P1_SVTO")
	)
	(segment
		(start 133.853428 -209.986626)
		(end 133.853428 -211.585556)
		(width 0.10668)
		(layer "F.Cu")
		(net "SVID_PVDDCR_CPU0_P1_SVTO")
	)
	(segment
		(start 127.757936 -219.584524)
		(end 127.757936 -222.880428)
		(width 0.10668)
		(layer "F.Cu")
		(net "SVID_PVDDCR_CPU0_P1_SVTO")
	)
	(via
		(at 89.193878 -148.94941)
		(size 0.508)
		(drill 0.254)
		(layers "F.Cu" "B.Cu")
		(net "SVID_PVDDCR_CPU0_P1_SVTO")
	)
	(via
		(at 85.7885 -148.5265)
		(size 0.762)
		(drill 0.381)
		(layers "F.Cu" "B.Cu")
		(net "SVID_PVDDCR_CPU0_P1_SVTO")
	)
	(segment
		(start 89.809828 -148.94941)
		(end 89.193878 -148.94941)
		(width 0.10668)
		(layer "B.Cu")
		(net "SVID_PVDDCR_CPU0_P1_SVTO")
	)
	(segment
		(start 89.193878 -148.94941)
		(end 88.577928 -148.94941)
		(width 0.10668)
		(layer "B.Cu")
		(net "SVID_PVDDCR_CPU0_P1_SVTO")
	)
	(via
		(at 92.2274 -148.83384)
		(size 0.6604)
		(drill 0.3302)
		(layers "F.Cu" "B.Cu")
		(net "SVID_PVDDCR_CPU0_P1_SVTI_R")
	)
	(segment
		(start 92.795852 -146.958304)
		(end 92.795852 -147.793202)
		(width 0.10668)
		(layer "B.Cu")
		(net "SVID_PVDDCR_CPU0_P1_SVTI_R")
	)
	(segment
		(start 92.2274 -148.361654)
		(end 92.2274 -148.83384)
		(width 0.10668)
		(layer "B.Cu")
		(net "SVID_PVDDCR_CPU0_P1_SVTI_R")
	)
	(segment
		(start 92.795852 -147.793202)
		(end 92.2274 -148.361654)
		(width 0.10668)
		(layer "B.Cu")
		(net "SVID_PVDDCR_CPU0_P1_SVTI_R")
	)
	(segment
		(start 91.09583 -149.96541)
		(end 90.609928 -149.96541)
		(width 0.10668)
		(layer "B.Cu")
		(net "SVID_PVDDCR_CPU0_P1_SVTI_R")
	)
	(segment
		(start 92.2274 -148.83384)
		(end 91.09583 -149.96541)
		(width 0.10668)
		(layer "B.Cu")
		(net "SVID_PVDDCR_CPU0_P1_SVTI_R")
	)
	(segment
		(start 90.419428 -149.96541)
		(end 89.193878 -149.96541)
		(width 0.10668)
		(layer "F.Cu")
		(net "SVID_PVDDCR_CPU0_P1_SVTI")
	)
	(via
		(at 89.193878 -149.96541)
		(size 0.762)
		(drill 0.254)
		(layers "F.Cu" "B.Cu")
		(net "SVID_PVDDCR_CPU0_P1_SVTI")
	)
	(segment
		(start 89.193878 -149.96541)
		(end 88.811608 -149.96541)
		(width 0.10668)
		(layer "B.Cu")
		(net "SVID_PVDDCR_CPU0_P1_SVTI")
	)
	(segment
		(start 89.809828 -149.96541)
		(end 89.193878 -149.96541)
		(width 0.10668)
		(layer "B.Cu")
		(net "SVID_PVDDCR_CPU0_P1_SVTI")
	)
	(segment
		(start 88.811608 -149.96541)
		(end 88.577928 -150.19909)
		(width 0.10668)
		(layer "B.Cu")
		(net "SVID_PVDDCR_CPU0_P1_SVTI")
	)
	(segment
		(start 145.401792 -192.276476)
		(end 145.401792 -144.626076)
		(width 0.10668)
		(layer "F.Cu")
		(net "SVID_PVDDCR_CPU0_P1_SVD_R")
	)
	(segment
		(start 146.104864 -192.979548)
		(end 146.104864 -194.166998)
		(width 0.10668)
		(layer "F.Cu")
		(net "SVID_PVDDCR_CPU0_P1_SVD_R")
	)
	(segment
		(start 85.95868 -138.60399)
		(end 85.95868 -145.923)
		(width 0.10668)
		(layer "F.Cu")
		(net "SVID_PVDDCR_CPU0_P1_SVD_R")
	)
	(segment
		(start 89.809828 -146.91741)
		(end 87.01659 -146.91741)
		(width 0.10668)
		(layer "F.Cu")
		(net "SVID_PVDDCR_CPU0_P1_SVD_R")
	)
	(segment
		(start 92.385134 -132.177536)
		(end 85.95868 -138.60399)
		(width 0.10668)
		(layer "F.Cu")
		(net "SVID_PVDDCR_CPU0_P1_SVD_R")
	)
	(segment
		(start 132.953252 -132.177536)
		(end 92.385134 -132.177536)
		(width 0.10668)
		(layer "F.Cu")
		(net "SVID_PVDDCR_CPU0_P1_SVD_R")
	)
	(segment
		(start 146.104864 -192.979548)
		(end 145.401792 -192.276476)
		(width 0.10668)
		(layer "F.Cu")
		(net "SVID_PVDDCR_CPU0_P1_SVD_R")
	)
	(segment
		(start 87.01659 -146.91741)
		(end 86.995 -146.939)
		(width 0.10668)
		(layer "F.Cu")
		(net "SVID_PVDDCR_CPU0_P1_SVD_R")
	)
	(segment
		(start 145.401792 -144.626076)
		(end 132.953252 -132.177536)
		(width 0.10668)
		(layer "F.Cu")
		(net "SVID_PVDDCR_CPU0_P1_SVD_R")
	)
	(via
		(at 86.995 -146.939)
		(size 0.508)
		(drill 0.254)
		(layers "F.Cu" "B.Cu")
		(net "SVID_PVDDCR_CPU0_P1_SVD_R")
	)
	(via
		(at 146.104864 -192.979548)
		(size 0.762)
		(drill 0.381)
		(layers "F.Cu" "B.Cu")
		(net "SVID_PVDDCR_CPU0_P1_SVD_R")
	)
	(via
		(at 85.95868 -145.923)
		(size 0.508)
		(drill 0.254)
		(layers "F.Cu" "B.Cu")
		(net "SVID_PVDDCR_CPU0_P1_SVD_R")
	)
	(segment
		(start 86.25205 -146.939)
		(end 86.995 -146.939)
		(width 0.10668)
		(layer "B.Cu")
		(net "SVID_PVDDCR_CPU0_P1_SVD_R")
	)
	(segment
		(start 87.73795 -146.939)
		(end 86.995 -146.939)
		(width 0.10668)
		(layer "B.Cu")
		(net "SVID_PVDDCR_CPU0_P1_SVD_R")
	)
	(segment
		(start 86.995 -146.939)
		(end 86.97468 -146.939)
		(width 0.11684)
		(layer "In6.Cu")
		(net "SVID_PVDDCR_CPU0_P1_SVD_R")
	)
	(segment
		(start 86.97468 -146.939)
		(end 85.95868 -145.923)
		(width 0.11684)
		(layer "In6.Cu")
		(net "SVID_PVDDCR_CPU0_P1_SVD_R")
	)
	(segment
		(start 146.104864 -196.154548)
		(end 146.104864 -196.615812)
		(width 0.10668)
		(layer "F.Cu")
		(net "SVID_PVDDCR_CPU0_P1_SVD")
	)
	(segment
		(start 135.04291 -215.632284)
		(end 135.04291 -217.905838)
		(width 0.10668)
		(layer "F.Cu")
		(net "SVID_PVDDCR_CPU0_P1_SVD")
	)
	(segment
		(start 133.38175 -211.621878)
		(end 135.04291 -215.632284)
		(width 0.10668)
		(layer "F.Cu")
		(net "SVID_PVDDCR_CPU0_P1_SVD")
	)
	(segment
		(start 135.04291 -217.905838)
		(end 134.239508 -218.70924)
		(width 0.10668)
		(layer "F.Cu")
		(net "SVID_PVDDCR_CPU0_P1_SVD")
	)
	(segment
		(start 127.863346 -218.70924)
		(end 126.347982 -220.224604)
		(width 0.10668)
		(layer "F.Cu")
		(net "SVID_PVDDCR_CPU0_P1_SVD")
	)
	(segment
		(start 126.347982 -220.224604)
		(end 126.347982 -222.070422)
		(width 0.10668)
		(layer "F.Cu")
		(net "SVID_PVDDCR_CPU0_P1_SVD")
	)
	(segment
		(start 146.104864 -196.154548)
		(end 146.104864 -194.967098)
		(width 0.10668)
		(layer "F.Cu")
		(net "SVID_PVDDCR_CPU0_P1_SVD")
	)
	(segment
		(start 134.239508 -218.70924)
		(end 127.863346 -218.70924)
		(width 0.10668)
		(layer "F.Cu")
		(net "SVID_PVDDCR_CPU0_P1_SVD")
	)
	(segment
		(start 133.38175 -209.338926)
		(end 133.38175 -211.621878)
		(width 0.10668)
		(layer "F.Cu")
		(net "SVID_PVDDCR_CPU0_P1_SVD")
	)
	(segment
		(start 146.104864 -196.615812)
		(end 133.38175 -209.338926)
		(width 0.10668)
		(layer "F.Cu")
		(net "SVID_PVDDCR_CPU0_P1_SVD")
	)
	(via
		(at 146.104864 -196.154548)
		(size 0.762)
		(drill 0.381)
		(layers "F.Cu" "B.Cu")
		(net "SVID_PVDDCR_CPU0_P1_SVD")
	)
	(segment
		(start 86.408768 -145.590768)
		(end 86.741 -145.923)
		(width 0.10668)
		(layer "F.Cu")
		(net "SVID_PVDDCR_CPU0_P1_SVC_R")
	)
	(segment
		(start 144.834864 -194.166998)
		(end 144.834864 -192.979548)
		(width 0.10668)
		(layer "F.Cu")
		(net "SVID_PVDDCR_CPU0_P1_SVC_R")
	)
	(segment
		(start 87.01659 -147.93341)
		(end 86.995 -147.955)
		(width 0.10668)
		(layer "F.Cu")
		(net "SVID_PVDDCR_CPU0_P1_SVC_R")
	)
	(segment
		(start 89.809828 -147.93341)
		(end 87.01659 -147.93341)
		(width 0.10668)
		(layer "F.Cu")
		(net "SVID_PVDDCR_CPU0_P1_SVC_R")
	)
	(segment
		(start 132.766816 -132.627624)
		(end 92.57157 -132.627624)
		(width 0.10668)
		(layer "F.Cu")
		(net "SVID_PVDDCR_CPU0_P1_SVC_R")
	)
	(segment
		(start 92.57157 -132.627624)
		(end 86.408768 -138.790426)
		(width 0.10668)
		(layer "F.Cu")
		(net "SVID_PVDDCR_CPU0_P1_SVC_R")
	)
	(segment
		(start 144.951704 -192.862708)
		(end 144.951704 -144.812512)
		(width 0.10668)
		(layer "F.Cu")
		(net "SVID_PVDDCR_CPU0_P1_SVC_R")
	)
	(segment
		(start 144.951704 -144.812512)
		(end 132.766816 -132.627624)
		(width 0.10668)
		(layer "F.Cu")
		(net "SVID_PVDDCR_CPU0_P1_SVC_R")
	)
	(segment
		(start 86.408768 -138.790426)
		(end 86.408768 -145.590768)
		(width 0.10668)
		(layer "F.Cu")
		(net "SVID_PVDDCR_CPU0_P1_SVC_R")
	)
	(segment
		(start 144.834864 -192.979548)
		(end 144.951704 -192.862708)
		(width 0.10668)
		(layer "F.Cu")
		(net "SVID_PVDDCR_CPU0_P1_SVC_R")
	)
	(via
		(at 86.995 -147.955)
		(size 0.508)
		(drill 0.254)
		(layers "F.Cu" "B.Cu")
		(net "SVID_PVDDCR_CPU0_P1_SVC_R")
	)
	(via
		(at 86.741 -145.923)
		(size 0.508)
		(drill 0.254)
		(layers "F.Cu" "B.Cu")
		(net "SVID_PVDDCR_CPU0_P1_SVC_R")
	)
	(via
		(at 144.834864 -192.979548)
		(size 0.762)
		(drill 0.381)
		(layers "F.Cu" "B.Cu")
		(net "SVID_PVDDCR_CPU0_P1_SVC_R")
	)
	(segment
		(start 86.25205 -147.955)
		(end 86.995 -147.955)
		(width 0.10668)
		(layer "B.Cu")
		(net "SVID_PVDDCR_CPU0_P1_SVC_R")
	)
	(segment
		(start 87.73795 -147.955)
		(end 86.995 -147.955)
		(width 0.10668)
		(layer "B.Cu")
		(net "SVID_PVDDCR_CPU0_P1_SVC_R")
	)
	(segment
		(start 87.503 -147.447)
		(end 86.995 -147.955)
		(width 0.11684)
		(layer "In6.Cu")
		(net "SVID_PVDDCR_CPU0_P1_SVC_R")
	)
	(segment
		(start 86.741 -145.923)
		(end 87.503 -146.685)
		(width 0.11684)
		(layer "In6.Cu")
		(net "SVID_PVDDCR_CPU0_P1_SVC_R")
	)
	(segment
		(start 87.503 -146.685)
		(end 87.503 -147.447)
		(width 0.11684)
		(layer "In6.Cu")
		(net "SVID_PVDDCR_CPU0_P1_SVC_R")
	)
	(segment
		(start 132.904992 -211.646262)
		(end 134.59333 -215.722454)
		(width 0.10668)
		(layer "F.Cu")
		(net "SVID_PVDDCR_CPU0_P1_SVC")
	)
	(segment
		(start 134.59333 -215.722454)
		(end 134.59333 -216.944956)
		(width 0.10668)
		(layer "F.Cu")
		(net "SVID_PVDDCR_CPU0_P1_SVC")
	)
	(segment
		(start 144.834864 -196.88429)
		(end 132.904992 -208.814162)
		(width 0.10668)
		(layer "F.Cu")
		(net "SVID_PVDDCR_CPU0_P1_SVC")
	)
	(segment
		(start 132.904992 -208.814162)
		(end 132.904992 -211.646262)
		(width 0.10668)
		(layer "F.Cu")
		(net "SVID_PVDDCR_CPU0_P1_SVC")
	)
	(segment
		(start 144.834864 -196.154548)
		(end 144.834864 -196.88429)
		(width 0.10668)
		(layer "F.Cu")
		(net "SVID_PVDDCR_CPU0_P1_SVC")
	)
	(segment
		(start 134.59333 -216.944956)
		(end 133.304026 -218.23426)
		(width 0.10668)
		(layer "F.Cu")
		(net "SVID_PVDDCR_CPU0_P1_SVC")
	)
	(segment
		(start 144.834864 -196.154548)
		(end 144.834864 -194.967098)
		(width 0.10668)
		(layer "F.Cu")
		(net "SVID_PVDDCR_CPU0_P1_SVC")
	)
	(segment
		(start 127.550926 -218.23426)
		(end 125.407928 -220.377258)
		(width 0.10668)
		(layer "F.Cu")
		(net "SVID_PVDDCR_CPU0_P1_SVC")
	)
	(segment
		(start 125.407928 -220.377258)
		(end 125.407928 -222.070422)
		(width 0.10668)
		(layer "F.Cu")
		(net "SVID_PVDDCR_CPU0_P1_SVC")
	)
	(segment
		(start 133.304026 -218.23426)
		(end 127.550926 -218.23426)
		(width 0.10668)
		(layer "F.Cu")
		(net "SVID_PVDDCR_CPU0_P1_SVC")
	)
	(via
		(at 144.834864 -196.154548)
		(size 0.762)
		(drill 0.381)
		(layers "F.Cu" "B.Cu")
		(net "SVID_PVDDCR_CPU0_P1_SVC")
	)
	(via
		(at 374.12549 -146.899376)
		(size 0.6604)
		(drill 0.3302)
		(layers "F.Cu" "B.Cu")
		(net "SVID_PVDDCR_CPU0_P0_SVTO_R")
	)
	(segment
		(start 373.337328 -146.552158)
		(end 373.684546 -146.899376)
		(width 0.10668)
		(layer "B.Cu")
		(net "SVID_PVDDCR_CPU0_P0_SVTO_R")
	)
	(segment
		(start 374.966484 -144.533874)
		(end 375.04878 -144.334992)
		(width 0.10668)
		(layer "B.Cu")
		(net "SVID_PVDDCR_CPU0_P0_SVTO_R")
	)
	(segment
		(start 374.12549 -146.899376)
		(end 374.12549 -146.51609)
		(width 0.10668)
		(layer "B.Cu")
		(net "SVID_PVDDCR_CPU0_P0_SVTO_R")
	)
	(segment
		(start 373.684546 -146.899376)
		(end 374.12549 -146.899376)
		(width 0.10668)
		(layer "B.Cu")
		(net "SVID_PVDDCR_CPU0_P0_SVTO_R")
	)
	(segment
		(start 375.222516 -144.161256)
		(end 375.523252 -144.161256)
		(width 0.10668)
		(layer "B.Cu")
		(net "SVID_PVDDCR_CPU0_P0_SVTO_R")
	)
	(segment
		(start 375.04878 -144.334992)
		(end 375.222516 -144.161256)
		(width 0.10668)
		(layer "B.Cu")
		(net "SVID_PVDDCR_CPU0_P0_SVTO_R")
	)
	(segment
		(start 374.12549 -146.51609)
		(end 374.966484 -145.675096)
		(width 0.10668)
		(layer "B.Cu")
		(net "SVID_PVDDCR_CPU0_P0_SVTO_R")
	)
	(segment
		(start 374.966484 -145.675096)
		(end 374.966484 -144.533874)
		(width 0.10668)
		(layer "B.Cu")
		(net "SVID_PVDDCR_CPU0_P0_SVTO_R")
	)
	(segment
		(start 371.921278 -146.552158)
		(end 371.305328 -146.552158)
		(width 0.10668)
		(layer "F.Cu")
		(net "SVID_PVDDCR_CPU0_P0_SVTO")
	)
	(segment
		(start 376.164856 -222.614236)
		(end 375.698004 -222.880174)
		(width 0.10668)
		(layer "F.Cu")
		(net "SVID_PVDDCR_CPU0_P0_SVTO")
	)
	(segment
		(start 372.537228 -146.552158)
		(end 371.921278 -146.552158)
		(width 0.10668)
		(layer "F.Cu")
		(net "SVID_PVDDCR_CPU0_P0_SVTO")
	)
	(via
		(at 376.164856 -222.614236)
		(size 0.4064)
		(drill 0.2032)
		(layers "F.Cu" "B.Cu")
		(net "SVID_PVDDCR_CPU0_P0_SVTO")
	)
	(via
		(at 365.941356 -213.715854)
		(size 0.6604)
		(drill 0.3302)
		(layers "F.Cu" "B.Cu")
		(net "SVID_PVDDCR_CPU0_P0_SVTO")
	)
	(via
		(at 304.407824 -169.707052)
		(size 0.508)
		(drill 0.254)
		(layers "F.Cu" "B.Cu")
		(net "SVID_PVDDCR_CPU0_P0_SVTO")
	)
	(via
		(at 371.921278 -146.552158)
		(size 0.508)
		(drill 0.254)
		(layers "F.Cu" "B.Cu")
		(net "SVID_PVDDCR_CPU0_P0_SVTO")
	)
	(segment
		(start 370.411248 -215.579198)
		(end 376.164856 -221.332806)
		(width 0.10668)
		(layer "B.Cu")
		(net "SVID_PVDDCR_CPU0_P0_SVTO")
	)
	(segment
		(start 358.12603 -213.715854)
		(end 365.941356 -213.715854)
		(width 0.10668)
		(layer "B.Cu")
		(net "SVID_PVDDCR_CPU0_P0_SVTO")
	)
	(segment
		(start 371.921278 -146.552158)
		(end 372.537228 -146.552158)
		(width 0.10668)
		(layer "B.Cu")
		(net "SVID_PVDDCR_CPU0_P0_SVTO")
	)
	(segment
		(start 365.941356 -213.715854)
		(end 369.217956 -213.715854)
		(width 0.10668)
		(layer "B.Cu")
		(net "SVID_PVDDCR_CPU0_P0_SVTO")
	)
	(segment
		(start 370.411248 -214.909146)
		(end 370.411248 -215.579198)
		(width 0.10668)
		(layer "B.Cu")
		(net "SVID_PVDDCR_CPU0_P0_SVTO")
	)
	(segment
		(start 304.407824 -169.707052)
		(end 304.407824 -169.33164)
		(width 0.10668)
		(layer "B.Cu")
		(net "SVID_PVDDCR_CPU0_P0_SVTO")
	)
	(segment
		(start 330.536804 -184.8612)
		(end 330.536804 -186.126628)
		(width 0.10668)
		(layer "B.Cu")
		(net "SVID_PVDDCR_CPU0_P0_SVTO")
	)
	(segment
		(start 305.245008 -168.494456)
		(end 314.17006 -168.494456)
		(width 0.10668)
		(layer "B.Cu")
		(net "SVID_PVDDCR_CPU0_P0_SVTO")
	)
	(segment
		(start 376.164856 -221.332806)
		(end 376.164856 -222.614236)
		(width 0.10668)
		(layer "B.Cu")
		(net "SVID_PVDDCR_CPU0_P0_SVTO")
	)
	(segment
		(start 371.305328 -146.552158)
		(end 371.921278 -146.552158)
		(width 0.10668)
		(layer "B.Cu")
		(net "SVID_PVDDCR_CPU0_P0_SVTO")
	)
	(segment
		(start 369.217956 -213.715854)
		(end 370.411248 -214.909146)
		(width 0.10668)
		(layer "B.Cu")
		(net "SVID_PVDDCR_CPU0_P0_SVTO")
	)
	(segment
		(start 304.407824 -169.33164)
		(end 305.245008 -168.494456)
		(width 0.10668)
		(layer "B.Cu")
		(net "SVID_PVDDCR_CPU0_P0_SVTO")
	)
	(segment
		(start 314.17006 -168.494456)
		(end 330.536804 -184.8612)
		(width 0.10668)
		(layer "B.Cu")
		(net "SVID_PVDDCR_CPU0_P0_SVTO")
	)
	(segment
		(start 330.536804 -186.126628)
		(end 358.12603 -213.715854)
		(width 0.10668)
		(layer "B.Cu")
		(net "SVID_PVDDCR_CPU0_P0_SVTO")
	)
	(segment
		(start 315.37529 -156.166566)
		(end 317.81369 -153.728166)
		(width 0.11684)
		(layer "In2.Cu")
		(net "SVID_PVDDCR_CPU0_P0_SVTO")
	)
	(segment
		(start 309.101744 -168.699434)
		(end 315.37529 -162.425888)
		(width 0.11684)
		(layer "In2.Cu")
		(net "SVID_PVDDCR_CPU0_P0_SVTO")
	)
	(segment
		(start 364.297468 -148.007324)
		(end 370.466112 -148.007324)
		(width 0.11684)
		(layer "In2.Cu")
		(net "SVID_PVDDCR_CPU0_P0_SVTO")
	)
	(segment
		(start 359.300018 -143.009874)
		(end 364.297468 -148.007324)
		(width 0.11684)
		(layer "In2.Cu")
		(net "SVID_PVDDCR_CPU0_P0_SVTO")
	)
	(segment
		(start 304.407824 -169.44848)
		(end 305.15687 -168.699434)
		(width 0.11684)
		(layer "In2.Cu")
		(net "SVID_PVDDCR_CPU0_P0_SVTO")
	)
	(segment
		(start 317.81369 -153.728166)
		(end 322.282312 -153.728166)
		(width 0.11684)
		(layer "In2.Cu")
		(net "SVID_PVDDCR_CPU0_P0_SVTO")
	)
	(segment
		(start 330.845668 -145.16481)
		(end 342.781128 -145.16481)
		(width 0.11684)
		(layer "In2.Cu")
		(net "SVID_PVDDCR_CPU0_P0_SVTO")
	)
	(segment
		(start 322.282312 -153.728166)
		(end 330.845668 -145.16481)
		(width 0.11684)
		(layer "In2.Cu")
		(net "SVID_PVDDCR_CPU0_P0_SVTO")
	)
	(segment
		(start 304.407824 -169.707052)
		(end 304.407824 -169.44848)
		(width 0.11684)
		(layer "In2.Cu")
		(net "SVID_PVDDCR_CPU0_P0_SVTO")
	)
	(segment
		(start 370.466112 -148.007324)
		(end 371.921278 -146.552158)
		(width 0.11684)
		(layer "In2.Cu")
		(net "SVID_PVDDCR_CPU0_P0_SVTO")
	)
	(segment
		(start 305.15687 -168.699434)
		(end 309.101744 -168.699434)
		(width 0.11684)
		(layer "In2.Cu")
		(net "SVID_PVDDCR_CPU0_P0_SVTO")
	)
	(segment
		(start 344.936064 -143.009874)
		(end 359.300018 -143.009874)
		(width 0.11684)
		(layer "In2.Cu")
		(net "SVID_PVDDCR_CPU0_P0_SVTO")
	)
	(segment
		(start 342.781128 -145.16481)
		(end 344.936064 -143.009874)
		(width 0.11684)
		(layer "In2.Cu")
		(net "SVID_PVDDCR_CPU0_P0_SVTO")
	)
	(segment
		(start 315.37529 -162.425888)
		(end 315.37529 -156.166566)
		(width 0.11684)
		(layer "In2.Cu")
		(net "SVID_PVDDCR_CPU0_P0_SVTO")
	)
	(via
		(at 375.222262 -146.240754)
		(size 0.6604)
		(drill 0.3302)
		(layers "F.Cu" "B.Cu")
		(net "SVID_PVDDCR_CPU0_P0_SVTI_R")
	)
	(segment
		(start 375.523252 -145.935954)
		(end 375.523252 -144.561052)
		(width 0.10668)
		(layer "B.Cu")
		(net "SVID_PVDDCR_CPU0_P0_SVTI_R")
	)
	(segment
		(start 374.18137 -147.568158)
		(end 374.708166 -147.041362)
		(width 0.10668)
		(layer "B.Cu")
		(net "SVID_PVDDCR_CPU0_P0_SVTI_R")
	)
	(segment
		(start 375.350532 -146.113754)
		(end 375.350532 -146.108674)
		(width 0.10668)
		(layer "B.Cu")
		(net "SVID_PVDDCR_CPU0_P0_SVTI_R")
	)
	(segment
		(start 374.708166 -147.041362)
		(end 374.708166 -146.75485)
		(width 0.10668)
		(layer "B.Cu")
		(net "SVID_PVDDCR_CPU0_P0_SVTI_R")
	)
	(segment
		(start 375.223532 -146.240754)
		(end 375.350532 -146.113754)
		(width 0.10668)
		(layer "B.Cu")
		(net "SVID_PVDDCR_CPU0_P0_SVTI_R")
	)
	(segment
		(start 374.708166 -146.75485)
		(end 375.222262 -146.240754)
		(width 0.10668)
		(layer "B.Cu")
		(net "SVID_PVDDCR_CPU0_P0_SVTI_R")
	)
	(segment
		(start 375.350532 -146.108674)
		(end 375.523252 -145.935954)
		(width 0.10668)
		(layer "B.Cu")
		(net "SVID_PVDDCR_CPU0_P0_SVTI_R")
	)
	(segment
		(start 373.337328 -147.568158)
		(end 374.18137 -147.568158)
		(width 0.10668)
		(layer "B.Cu")
		(net "SVID_PVDDCR_CPU0_P0_SVTI_R")
	)
	(segment
		(start 375.222262 -146.240754)
		(end 375.223532 -146.240754)
		(width 0.10668)
		(layer "B.Cu")
		(net "SVID_PVDDCR_CPU0_P0_SVTI_R")
	)
	(segment
		(start 372.537228 -147.568158)
		(end 371.921278 -147.568158)
		(width 0.10668)
		(layer "F.Cu")
		(net "SVID_PVDDCR_CPU0_P0_SVTI")
	)
	(via
		(at 371.305328 -148.404072)
		(size 0.6604)
		(drill 0.3302)
		(layers "F.Cu" "B.Cu")
		(net "SVID_PVDDCR_CPU0_P0_SVTI")
	)
	(via
		(at 371.921278 -147.568158)
		(size 0.508)
		(drill 0.254)
		(layers "F.Cu" "B.Cu")
		(net "SVID_PVDDCR_CPU0_P0_SVTI")
	)
	(segment
		(start 371.305328 -147.568158)
		(end 371.921278 -147.568158)
		(width 0.10668)
		(layer "B.Cu")
		(net "SVID_PVDDCR_CPU0_P0_SVTI")
	)
	(segment
		(start 371.305328 -147.568158)
		(end 371.305328 -148.404072)
		(width 0.10668)
		(layer "B.Cu")
		(net "SVID_PVDDCR_CPU0_P0_SVTI")
	)
	(segment
		(start 372.537228 -147.568158)
		(end 371.921278 -147.568158)
		(width 0.10668)
		(layer "B.Cu")
		(net "SVID_PVDDCR_CPU0_P0_SVTI")
	)
	(segment
		(start 372.537228 -144.520158)
		(end 371.921278 -144.520158)
		(width 0.10668)
		(layer "F.Cu")
		(net "SVID_PVDDCR_CPU0_P0_SVD_R")
	)
	(via
		(at 305.900836 -169.707052)
		(size 0.508)
		(drill 0.254)
		(layers "F.Cu" "B.Cu")
		(net "SVID_PVDDCR_CPU0_P0_SVD_R")
	)
	(via
		(at 371.921278 -144.520158)
		(size 0.508)
		(drill 0.254)
		(layers "F.Cu" "B.Cu")
		(net "SVID_PVDDCR_CPU0_P0_SVD_R")
	)
	(segment
		(start 368.172746 -214.345774)
		(end 368.230912 -214.287608)
		(width 0.10668)
		(layer "B.Cu")
		(net "SVID_PVDDCR_CPU0_P0_SVD_R")
	)
	(segment
		(start 313.976258 -168.961816)
		(end 330.069444 -185.055002)
		(width 0.10668)
		(layer "B.Cu")
		(net "SVID_PVDDCR_CPU0_P0_SVD_R")
	)
	(segment
		(start 305.900836 -169.707052)
		(end 305.900836 -169.382948)
		(width 0.10668)
		(layer "B.Cu")
		(net "SVID_PVDDCR_CPU0_P0_SVD_R")
	)
	(segment
		(start 330.069444 -186.32043)
		(end 358.094788 -214.345774)
		(width 0.10668)
		(layer "B.Cu")
		(net "SVID_PVDDCR_CPU0_P0_SVD_R")
	)
	(segment
		(start 372.537228 -144.520158)
		(end 371.921278 -144.520158)
		(width 0.10668)
		(layer "B.Cu")
		(net "SVID_PVDDCR_CPU0_P0_SVD_R")
	)
	(segment
		(start 330.069444 -185.055002)
		(end 330.069444 -186.32043)
		(width 0.10668)
		(layer "B.Cu")
		(net "SVID_PVDDCR_CPU0_P0_SVD_R")
	)
	(segment
		(start 305.900836 -169.382948)
		(end 306.321968 -168.961816)
		(width 0.10668)
		(layer "B.Cu")
		(net "SVID_PVDDCR_CPU0_P0_SVD_R")
	)
	(segment
		(start 371.305328 -144.520158)
		(end 371.921278 -144.520158)
		(width 0.10668)
		(layer "B.Cu")
		(net "SVID_PVDDCR_CPU0_P0_SVD_R")
	)
	(segment
		(start 306.321968 -168.961816)
		(end 313.976258 -168.961816)
		(width 0.10668)
		(layer "B.Cu")
		(net "SVID_PVDDCR_CPU0_P0_SVD_R")
	)
	(segment
		(start 358.094788 -214.345774)
		(end 368.172746 -214.345774)
		(width 0.10668)
		(layer "B.Cu")
		(net "SVID_PVDDCR_CPU0_P0_SVD_R")
	)
	(segment
		(start 372.56974 -146.162014)
		(end 372.444518 -146.036792)
		(width 0.11684)
		(layer "In2.Cu")
		(net "SVID_PVDDCR_CPU0_P0_SVD_R")
	)
	(segment
		(start 309.40248 -169.121074)
		(end 315.886084 -162.63747)
		(width 0.11684)
		(layer "In2.Cu")
		(net "SVID_PVDDCR_CPU0_P0_SVD_R")
	)
	(segment
		(start 371.26291 -144.900142)
		(end 371.642894 -144.520158)
		(width 0.11684)
		(layer "In2.Cu")
		(net "SVID_PVDDCR_CPU0_P0_SVD_R")
	)
	(segment
		(start 371.623082 -148.518118)
		(end 372.56974 -147.57146)
		(width 0.11684)
		(layer "In2.Cu")
		(net "SVID_PVDDCR_CPU0_P0_SVD_R")
	)
	(segment
		(start 306.35575 -169.121074)
		(end 309.40248 -169.121074)
		(width 0.11684)
		(layer "In2.Cu")
		(net "SVID_PVDDCR_CPU0_P0_SVD_R")
	)
	(segment
		(start 372.444518 -146.036792)
		(end 371.628416 -146.036792)
		(width 0.11684)
		(layer "In2.Cu")
		(net "SVID_PVDDCR_CPU0_P0_SVD_R")
	)
	(segment
		(start 359.088436 -143.520668)
		(end 364.085886 -148.518118)
		(width 0.11684)
		(layer "In2.Cu")
		(net "SVID_PVDDCR_CPU0_P0_SVD_R")
	)
	(segment
		(start 318.025272 -154.23896)
		(end 322.493894 -154.23896)
		(width 0.11684)
		(layer "In2.Cu")
		(net "SVID_PVDDCR_CPU0_P0_SVD_R")
	)
	(segment
		(start 315.886084 -156.378148)
		(end 318.025272 -154.23896)
		(width 0.11684)
		(layer "In2.Cu")
		(net "SVID_PVDDCR_CPU0_P0_SVD_R")
	)
	(segment
		(start 315.886084 -162.63747)
		(end 315.886084 -156.378148)
		(width 0.11684)
		(layer "In2.Cu")
		(net "SVID_PVDDCR_CPU0_P0_SVD_R")
	)
	(segment
		(start 342.99271 -145.675604)
		(end 345.147646 -143.520668)
		(width 0.11684)
		(layer "In2.Cu")
		(net "SVID_PVDDCR_CPU0_P0_SVD_R")
	)
	(segment
		(start 364.085886 -148.518118)
		(end 371.623082 -148.518118)
		(width 0.11684)
		(layer "In2.Cu")
		(net "SVID_PVDDCR_CPU0_P0_SVD_R")
	)
	(segment
		(start 322.493894 -154.23896)
		(end 331.05725 -145.675604)
		(width 0.11684)
		(layer "In2.Cu")
		(net "SVID_PVDDCR_CPU0_P0_SVD_R")
	)
	(segment
		(start 372.56974 -147.57146)
		(end 372.56974 -146.162014)
		(width 0.11684)
		(layer "In2.Cu")
		(net "SVID_PVDDCR_CPU0_P0_SVD_R")
	)
	(segment
		(start 371.628416 -146.036792)
		(end 371.26291 -145.671286)
		(width 0.11684)
		(layer "In2.Cu")
		(net "SVID_PVDDCR_CPU0_P0_SVD_R")
	)
	(segment
		(start 331.05725 -145.675604)
		(end 342.99271 -145.675604)
		(width 0.11684)
		(layer "In2.Cu")
		(net "SVID_PVDDCR_CPU0_P0_SVD_R")
	)
	(segment
		(start 371.26291 -145.671286)
		(end 371.26291 -144.900142)
		(width 0.11684)
		(layer "In2.Cu")
		(net "SVID_PVDDCR_CPU0_P0_SVD_R")
	)
	(segment
		(start 345.147646 -143.520668)
		(end 359.088436 -143.520668)
		(width 0.11684)
		(layer "In2.Cu")
		(net "SVID_PVDDCR_CPU0_P0_SVD_R")
	)
	(segment
		(start 371.642894 -144.520158)
		(end 371.921278 -144.520158)
		(width 0.11684)
		(layer "In2.Cu")
		(net "SVID_PVDDCR_CPU0_P0_SVD_R")
	)
	(segment
		(start 305.900836 -169.707052)
		(end 305.900836 -169.575988)
		(width 0.11684)
		(layer "In2.Cu")
		(net "SVID_PVDDCR_CPU0_P0_SVD_R")
	)
	(segment
		(start 305.900836 -169.575988)
		(end 306.35575 -169.121074)
		(width 0.11684)
		(layer "In2.Cu")
		(net "SVID_PVDDCR_CPU0_P0_SVD_R")
	)
	(segment
		(start 374.754902 -221.80423)
		(end 374.28805 -222.070168)
		(width 0.10668)
		(layer "F.Cu")
		(net "SVID_PVDDCR_CPU0_P0_SVD")
	)
	(via
		(at 369.913408 -215.47201)
		(size 0.6604)
		(drill 0.3302)
		(layers "F.Cu" "B.Cu")
		(net "SVID_PVDDCR_CPU0_P0_SVD")
	)
	(via
		(at 374.754902 -221.80423)
		(size 0.4064)
		(drill 0.2032)
		(layers "F.Cu" "B.Cu")
		(net "SVID_PVDDCR_CPU0_P0_SVD")
	)
	(segment
		(start 369.913408 -215.170004)
		(end 369.913408 -215.47201)
		(width 0.10668)
		(layer "B.Cu")
		(net "SVID_PVDDCR_CPU0_P0_SVD")
	)
	(segment
		(start 369.031012 -214.287608)
		(end 369.913408 -215.170004)
		(width 0.10668)
		(layer "B.Cu")
		(net "SVID_PVDDCR_CPU0_P0_SVD")
	)
	(segment
		(start 369.913408 -215.47201)
		(end 369.913408 -216.115392)
		(width 0.10668)
		(layer "B.Cu")
		(net "SVID_PVDDCR_CPU0_P0_SVD")
	)
	(segment
		(start 369.913408 -216.115392)
		(end 374.754902 -220.956886)
		(width 0.10668)
		(layer "B.Cu")
		(net "SVID_PVDDCR_CPU0_P0_SVD")
	)
	(segment
		(start 374.754902 -220.956886)
		(end 374.754902 -221.80423)
		(width 0.10668)
		(layer "B.Cu")
		(net "SVID_PVDDCR_CPU0_P0_SVD")
	)
	(segment
		(start 372.537228 -145.536158)
		(end 371.921278 -145.536158)
		(width 0.10668)
		(layer "F.Cu")
		(net "SVID_PVDDCR_CPU0_P0_SVC_R")
	)
	(via
		(at 371.921278 -145.536158)
		(size 0.508)
		(drill 0.254)
		(layers "F.Cu" "B.Cu")
		(net "SVID_PVDDCR_CPU0_P0_SVC_R")
	)
	(via
		(at 310.15305 -169.70121)
		(size 0.6604)
		(drill 0.3302)
		(layers "F.Cu" "B.Cu")
		(net "SVID_PVDDCR_CPU0_P0_SVC_R")
	)
	(via
		(at 307.288184 -169.70121)
		(size 0.508)
		(drill 0.254)
		(layers "F.Cu" "B.Cu")
		(net "SVID_PVDDCR_CPU0_P0_SVC_R")
	)
	(segment
		(start 307.288184 -169.70121)
		(end 310.15305 -169.70121)
		(width 0.10668)
		(layer "B.Cu")
		(net "SVID_PVDDCR_CPU0_P0_SVC_R")
	)
	(segment
		(start 329.616816 -186.508136)
		(end 358.412288 -215.303608)
		(width 0.10668)
		(layer "B.Cu")
		(net "SVID_PVDDCR_CPU0_P0_SVC_R")
	)
	(segment
		(start 358.412288 -215.303608)
		(end 366.702848 -215.303608)
		(width 0.10668)
		(layer "B.Cu")
		(net "SVID_PVDDCR_CPU0_P0_SVC_R")
	)
	(segment
		(start 371.305328 -145.536158)
		(end 371.921278 -145.536158)
		(width 0.10668)
		(layer "B.Cu")
		(net "SVID_PVDDCR_CPU0_P0_SVC_R")
	)
	(segment
		(start 310.15305 -169.70121)
		(end 314.075318 -169.70121)
		(width 0.10668)
		(layer "B.Cu")
		(net "SVID_PVDDCR_CPU0_P0_SVC_R")
	)
	(segment
		(start 329.616816 -185.242708)
		(end 329.616816 -186.508136)
		(width 0.10668)
		(layer "B.Cu")
		(net "SVID_PVDDCR_CPU0_P0_SVC_R")
	)
	(segment
		(start 314.075318 -169.70121)
		(end 329.616816 -185.242708)
		(width 0.10668)
		(layer "B.Cu")
		(net "SVID_PVDDCR_CPU0_P0_SVC_R")
	)
	(segment
		(start 372.537228 -145.536158)
		(end 371.921278 -145.536158)
		(width 0.10668)
		(layer "B.Cu")
		(net "SVID_PVDDCR_CPU0_P0_SVC_R")
	)
	(segment
		(start 371.931946 -148.971)
		(end 363.740954 -148.971)
		(width 0.11684)
		(layer "In2.Cu")
		(net "SVID_PVDDCR_CPU0_P0_SVC_R")
	)
	(segment
		(start 358.854756 -144.084802)
		(end 345.381326 -144.084802)
		(width 0.11684)
		(layer "In2.Cu")
		(net "SVID_PVDDCR_CPU0_P0_SVC_R")
	)
	(segment
		(start 307.44668 -169.542714)
		(end 307.288184 -169.70121)
		(width 0.11684)
		(layer "In2.Cu")
		(net "SVID_PVDDCR_CPU0_P0_SVC_R")
	)
	(segment
		(start 316.450218 -156.611828)
		(end 316.450218 -162.87115)
		(width 0.11684)
		(layer "In2.Cu")
		(net "SVID_PVDDCR_CPU0_P0_SVC_R")
	)
	(segment
		(start 322.727574 -154.803094)
		(end 318.258952 -154.803094)
		(width 0.11684)
		(layer "In2.Cu")
		(net "SVID_PVDDCR_CPU0_P0_SVC_R")
	)
	(segment
		(start 363.740954 -148.971)
		(end 358.854756 -144.084802)
		(width 0.11684)
		(layer "In2.Cu")
		(net "SVID_PVDDCR_CPU0_P0_SVC_R")
	)
	(segment
		(start 318.258952 -154.803094)
		(end 316.450218 -156.611828)
		(width 0.11684)
		(layer "In2.Cu")
		(net "SVID_PVDDCR_CPU0_P0_SVC_R")
	)
	(segment
		(start 373.076724 -147.826222)
		(end 371.931946 -148.971)
		(width 0.11684)
		(layer "In2.Cu")
		(net "SVID_PVDDCR_CPU0_P0_SVC_R")
	)
	(segment
		(start 316.450218 -162.87115)
		(end 309.778654 -169.542714)
		(width 0.11684)
		(layer "In2.Cu")
		(net "SVID_PVDDCR_CPU0_P0_SVC_R")
	)
	(segment
		(start 309.778654 -169.542714)
		(end 307.44668 -169.542714)
		(width 0.11684)
		(layer "In2.Cu")
		(net "SVID_PVDDCR_CPU0_P0_SVC_R")
	)
	(segment
		(start 345.381326 -144.084802)
		(end 343.22639 -146.239738)
		(width 0.11684)
		(layer "In2.Cu")
		(net "SVID_PVDDCR_CPU0_P0_SVC_R")
	)
	(segment
		(start 331.29093 -146.239738)
		(end 322.727574 -154.803094)
		(width 0.11684)
		(layer "In2.Cu")
		(net "SVID_PVDDCR_CPU0_P0_SVC_R")
	)
	(segment
		(start 343.22639 -146.239738)
		(end 331.29093 -146.239738)
		(width 0.11684)
		(layer "In2.Cu")
		(net "SVID_PVDDCR_CPU0_P0_SVC_R")
	)
	(segment
		(start 372.6434 -145.536158)
		(end 373.076724 -145.969482)
		(width 0.11684)
		(layer "In2.Cu")
		(net "SVID_PVDDCR_CPU0_P0_SVC_R")
	)
	(segment
		(start 371.921278 -145.536158)
		(end 372.6434 -145.536158)
		(width 0.11684)
		(layer "In2.Cu")
		(net "SVID_PVDDCR_CPU0_P0_SVC_R")
	)
	(segment
		(start 373.076724 -145.969482)
		(end 373.076724 -147.826222)
		(width 0.11684)
		(layer "In2.Cu")
		(net "SVID_PVDDCR_CPU0_P0_SVC_R")
	)
	(segment
		(start 373.347996 -222.070168)
		(end 373.814848 -221.80423)
		(width 0.10668)
		(layer "F.Cu")
		(net "SVID_PVDDCR_CPU0_P0_SVC")
	)
	(via
		(at 373.814848 -221.80423)
		(size 0.4064)
		(drill 0.2032)
		(layers "F.Cu" "B.Cu")
		(net "SVID_PVDDCR_CPU0_P0_SVC")
	)
	(via
		(at 368.643408 -215.47201)
		(size 0.6604)
		(drill 0.3302)
		(layers "F.Cu" "B.Cu")
		(net "SVID_PVDDCR_CPU0_P0_SVC")
	)
	(segment
		(start 373.814848 -221.80423)
		(end 373.814848 -221.111318)
		(width 0.10668)
		(layer "B.Cu")
		(net "SVID_PVDDCR_CPU0_P0_SVC")
	)
	(segment
		(start 368.475006 -215.303608)
		(end 367.502948 -215.303608)
		(width 0.10668)
		(layer "B.Cu")
		(net "SVID_PVDDCR_CPU0_P0_SVC")
	)
	(segment
		(start 368.643408 -215.47201)
		(end 368.475006 -215.303608)
		(width 0.10668)
		(layer "B.Cu")
		(net "SVID_PVDDCR_CPU0_P0_SVC")
	)
	(segment
		(start 373.814848 -221.111318)
		(end 368.643408 -215.939878)
		(width 0.10668)
		(layer "B.Cu")
		(net "SVID_PVDDCR_CPU0_P0_SVC")
	)
	(segment
		(start 368.643408 -215.939878)
		(end 368.643408 -215.47201)
		(width 0.10668)
		(layer "B.Cu")
		(net "SVID_PVDDCR_CPU0_P0_SVC")
	)
	(segment
		(start 121.94794 -295.69029)
		(end 122.414792 -295.956228)
		(width 0.10668)
		(layer "F.Cu")
		(net "SPI_CPU1_R_CLK")
	)
	(via
		(at 143.153384 -322.101972)
		(size 0.6604)
		(drill 0.3302)
		(layers "F.Cu" "B.Cu")
		(net "SPI_CPU1_R_CLK")
	)
	(via
		(at 122.414792 -295.956228)
		(size 0.4064)
		(drill 0.2032)
		(layers "F.Cu" "B.Cu")
		(net "SPI_CPU1_R_CLK")
	)
	(segment
		(start 143.153384 -322.101972)
		(end 144.817084 -322.101972)
		(width 0.10668)
		(layer "B.Cu")
		(net "SPI_CPU1_R_CLK")
	)
	(segment
		(start 122.171206 -296.199814)
		(end 122.171206 -301.119794)
		(width 0.10668)
		(layer "B.Cu")
		(net "SPI_CPU1_R_CLK")
	)
	(segment
		(start 122.171206 -301.119794)
		(end 143.153384 -322.101972)
		(width 0.10668)
		(layer "B.Cu")
		(net "SPI_CPU1_R_CLK")
	)
	(segment
		(start 122.414792 -295.956228)
		(end 122.171206 -296.199814)
		(width 0.10668)
		(layer "B.Cu")
		(net "SPI_CPU1_R_CLK")
	)
	(via
		(at 146.934936 -322.312792)
		(size 0.6604)
		(drill 0.3302)
		(layers "F.Cu" "B.Cu")
		(net "SPI_CPU1_CLK")
	)
	(segment
		(start 145.617184 -322.101972)
		(end 146.724116 -322.101972)
		(width 0.10668)
		(layer "B.Cu")
		(net "SPI_CPU1_CLK")
	)
	(segment
		(start 152.60447 -323.548756)
		(end 152.849834 -323.303392)
		(width 0.10668)
		(layer "B.Cu")
		(net "SPI_CPU1_CLK")
	)
	(segment
		(start 150.229316 -322.592192)
		(end 151.18588 -323.548756)
		(width 0.10668)
		(layer "B.Cu")
		(net "SPI_CPU1_CLK")
	)
	(segment
		(start 151.18588 -323.548756)
		(end 152.60447 -323.548756)
		(width 0.10668)
		(layer "B.Cu")
		(net "SPI_CPU1_CLK")
	)
	(segment
		(start 146.724116 -322.101972)
		(end 146.934936 -322.312792)
		(width 0.10668)
		(layer "B.Cu")
		(net "SPI_CPU1_CLK")
	)
	(segment
		(start 153.865834 -323.303392)
		(end 152.849834 -323.303392)
		(width 0.10668)
		(layer "B.Cu")
		(net "SPI_CPU1_CLK")
	)
	(segment
		(start 146.934936 -322.312792)
		(end 147.214336 -322.592192)
		(width 0.10668)
		(layer "B.Cu")
		(net "SPI_CPU1_CLK")
	)
	(segment
		(start 147.214336 -322.592192)
		(end 150.229316 -322.592192)
		(width 0.10668)
		(layer "B.Cu")
		(net "SPI_CPU1_CLK")
	)
	(segment
		(start 401.466558 -323.790818)
		(end 401.29206 -323.965316)
		(width 0.10668)
		(layer "F.Cu")
		(net "SPI_CPU0_TPM_CS_N")
	)
	(segment
		(start 263.381998 -135.654796)
		(end 263.149334 -135.88746)
		(width 0.10668)
		(layer "F.Cu")
		(net "SPI_CPU0_TPM_CS_N")
	)
	(segment
		(start 262.575802 -133.955282)
		(end 261.792466 -133.955282)
		(width 0.10668)
		(layer "F.Cu")
		(net "SPI_CPU0_TPM_CS_N")
	)
	(segment
		(start 263.149334 -134.528814)
		(end 262.575802 -133.955282)
		(width 0.10668)
		(layer "F.Cu")
		(net "SPI_CPU0_TPM_CS_N")
	)
	(segment
		(start 401.466558 -322.817998)
		(end 401.466558 -323.790818)
		(width 0.10668)
		(layer "F.Cu")
		(net "SPI_CPU0_TPM_CS_N")
	)
	(segment
		(start 401.29206 -323.965316)
		(end 400.88312 -323.965316)
		(width 0.10668)
		(layer "F.Cu")
		(net "SPI_CPU0_TPM_CS_N")
	)
	(segment
		(start 264.078466 -135.654796)
		(end 263.381998 -135.654796)
		(width 0.10668)
		(layer "F.Cu")
		(net "SPI_CPU0_TPM_CS_N")
	)
	(segment
		(start 263.149334 -135.88746)
		(end 263.149334 -134.528814)
		(width 0.10668)
		(layer "F.Cu")
		(net "SPI_CPU0_TPM_CS_N")
	)
	(via
		(at 263.149334 -135.88746)
		(size 0.508)
		(drill 0.254)
		(layers "F.Cu" "B.Cu")
		(net "SPI_CPU0_TPM_CS_N")
	)
	(via
		(at 401.466558 -322.817998)
		(size 0.508)
		(drill 0.254)
		(layers "F.Cu" "B.Cu")
		(net "SPI_CPU0_TPM_CS_N")
	)
	(segment
		(start 263.789668 -142.152878)
		(end 277.635462 -142.152878)
		(width 0.11684)
		(layer "In15.Cu")
		(net "SPI_CPU0_TPM_CS_N")
	)
	(segment
		(start 261.65048 -139.724892)
		(end 262.763 -140.837412)
		(width 0.11684)
		(layer "In15.Cu")
		(net "SPI_CPU0_TPM_CS_N")
	)
	(segment
		(start 335.603342 -175.722788)
		(end 373.57812 -213.697566)
		(width 0.11684)
		(layer "In15.Cu")
		(net "SPI_CPU0_TPM_CS_N")
	)
	(segment
		(start 261.790942 -135.88746)
		(end 261.65048 -136.027922)
		(width 0.11684)
		(layer "In15.Cu")
		(net "SPI_CPU0_TPM_CS_N")
	)
	(segment
		(start 294.200834 -158.71825)
		(end 307.373528 -158.71825)
		(width 0.11684)
		(layer "In15.Cu")
		(net "SPI_CPU0_TPM_CS_N")
	)
	(segment
		(start 406.404572 -312.98134)
		(end 406.404572 -320.448432)
		(width 0.11684)
		(layer "In15.Cu")
		(net "SPI_CPU0_TPM_CS_N")
	)
	(segment
		(start 405.214582 -321.638422)
		(end 402.261578 -321.638422)
		(width 0.11684)
		(layer "In15.Cu")
		(net "SPI_CPU0_TPM_CS_N")
	)
	(segment
		(start 401.466558 -322.433442)
		(end 401.466558 -322.817998)
		(width 0.11684)
		(layer "In15.Cu")
		(net "SPI_CPU0_TPM_CS_N")
	)
	(segment
		(start 396.753334 -215.572594)
		(end 402.51507 -221.33433)
		(width 0.11684)
		(layer "In15.Cu")
		(net "SPI_CPU0_TPM_CS_N")
	)
	(segment
		(start 277.635462 -142.152878)
		(end 294.200834 -158.71825)
		(width 0.11684)
		(layer "In15.Cu")
		(net "SPI_CPU0_TPM_CS_N")
	)
	(segment
		(start 402.108924 -264.565892)
		(end 402.108924 -308.685692)
		(width 0.11684)
		(layer "In15.Cu")
		(net "SPI_CPU0_TPM_CS_N")
	)
	(segment
		(start 406.404572 -320.448432)
		(end 405.214582 -321.638422)
		(width 0.11684)
		(layer "In15.Cu")
		(net "SPI_CPU0_TPM_CS_N")
	)
	(segment
		(start 316.44082 -167.785542)
		(end 335.603342 -175.722788)
		(width 0.11684)
		(layer "In15.Cu")
		(net "SPI_CPU0_TPM_CS_N")
	)
	(segment
		(start 388.124446 -215.572594)
		(end 396.753334 -215.572594)
		(width 0.11684)
		(layer "In15.Cu")
		(net "SPI_CPU0_TPM_CS_N")
	)
	(segment
		(start 402.51507 -221.33433)
		(end 402.51507 -254.63754)
		(width 0.11684)
		(layer "In15.Cu")
		(net "SPI_CPU0_TPM_CS_N")
	)
	(segment
		(start 405.40305 -261.271766)
		(end 402.108924 -264.565892)
		(width 0.11684)
		(layer "In15.Cu")
		(net "SPI_CPU0_TPM_CS_N")
	)
	(segment
		(start 405.40305 -257.52552)
		(end 405.40305 -261.271766)
		(width 0.11684)
		(layer "In15.Cu")
		(net "SPI_CPU0_TPM_CS_N")
	)
	(segment
		(start 402.51507 -254.63754)
		(end 405.40305 -257.52552)
		(width 0.11684)
		(layer "In15.Cu")
		(net "SPI_CPU0_TPM_CS_N")
	)
	(segment
		(start 307.373528 -158.71825)
		(end 316.44082 -167.785542)
		(width 0.11684)
		(layer "In15.Cu")
		(net "SPI_CPU0_TPM_CS_N")
	)
	(segment
		(start 373.57812 -213.697566)
		(end 386.249418 -213.697566)
		(width 0.11684)
		(layer "In15.Cu")
		(net "SPI_CPU0_TPM_CS_N")
	)
	(segment
		(start 402.261578 -321.638422)
		(end 401.466558 -322.433442)
		(width 0.11684)
		(layer "In15.Cu")
		(net "SPI_CPU0_TPM_CS_N")
	)
	(segment
		(start 261.65048 -136.027922)
		(end 261.65048 -139.724892)
		(width 0.11684)
		(layer "In15.Cu")
		(net "SPI_CPU0_TPM_CS_N")
	)
	(segment
		(start 386.249418 -213.697566)
		(end 388.124446 -215.572594)
		(width 0.11684)
		(layer "In15.Cu")
		(net "SPI_CPU0_TPM_CS_N")
	)
	(segment
		(start 262.763 -140.837412)
		(end 262.763 -141.12621)
		(width 0.11684)
		(layer "In15.Cu")
		(net "SPI_CPU0_TPM_CS_N")
	)
	(segment
		(start 263.149334 -135.88746)
		(end 261.790942 -135.88746)
		(width 0.11684)
		(layer "In15.Cu")
		(net "SPI_CPU0_TPM_CS_N")
	)
	(segment
		(start 402.108924 -308.685692)
		(end 406.404572 -312.98134)
		(width 0.11684)
		(layer "In15.Cu")
		(net "SPI_CPU0_TPM_CS_N")
	)
	(segment
		(start 262.763 -141.12621)
		(end 263.789668 -142.152878)
		(width 0.11684)
		(layer "In15.Cu")
		(net "SPI_CPU0_TPM_CS_N")
	)
	(segment
		(start 377.313444 -302.947324)
		(end 377.313444 -303.06518)
		(width 0.10668)
		(layer "F.Cu")
		(net "SPI_CPU0_R_TPM_CS_N")
	)
	(segment
		(start 376.307604 -302.05934)
		(end 376.42546 -302.05934)
		(width 0.10668)
		(layer "F.Cu")
		(net "SPI_CPU0_R_TPM_CS_N")
	)
	(segment
		(start 375.218452 -300.852332)
		(end 375.301764 -300.935644)
		(width 0.10668)
		(layer "F.Cu")
		(net "SPI_CPU0_R_TPM_CS_N")
	)
	(segment
		(start 375.619264 -302.345344)
		(end 375.619264 -302.4632)
		(width 0.10668)
		(layer "F.Cu")
		(net "SPI_CPU0_R_TPM_CS_N")
	)
	(segment
		(start 378.151898 -303.786032)
		(end 378.151898 -313.0423)
		(width 0.10668)
		(layer "F.Cu")
		(net "SPI_CPU0_R_TPM_CS_N")
	)
	(segment
		(start 374.814592 -301.658528)
		(end 374.897904 -301.74184)
		(width 0.10668)
		(layer "F.Cu")
		(net "SPI_CPU0_R_TPM_CS_N")
	)
	(segment
		(start 374.00992 -300.853856)
		(end 374.093232 -300.937168)
		(width 0.10668)
		(layer "F.Cu")
		(net "SPI_CPU0_R_TPM_CS_N")
	)
	(segment
		(start 389.400034 -324.787768)
		(end 389.400034 -325.907908)
		(width 0.10668)
		(layer "F.Cu")
		(net "SPI_CPU0_R_TPM_CS_N")
	)
	(segment
		(start 376.70994 -302.461676)
		(end 376.827796 -302.461676)
		(width 0.10668)
		(layer "F.Cu")
		(net "SPI_CPU0_R_TPM_CS_N")
	)
	(segment
		(start 375.216928 -302.060864)
		(end 375.30024 -302.144176)
		(width 0.10668)
		(layer "F.Cu")
		(net "SPI_CPU0_R_TPM_CS_N")
	)
	(segment
		(start 375.820432 -302.546512)
		(end 376.307604 -302.05934)
		(width 0.10668)
		(layer "F.Cu")
		(net "SPI_CPU0_R_TPM_CS_N")
	)
	(segment
		(start 376.827796 -302.461676)
		(end 376.911108 -302.544988)
		(width 0.10668)
		(layer "F.Cu")
		(net "SPI_CPU0_R_TPM_CS_N")
	)
	(segment
		(start 374.69826 -300.449996)
		(end 374.816116 -300.449996)
		(width 0.10668)
		(layer "F.Cu")
		(net "SPI_CPU0_R_TPM_CS_N")
	)
	(segment
		(start 375.620788 -301.254668)
		(end 375.7041 -301.33798)
		(width 0.10668)
		(layer "F.Cu")
		(net "SPI_CPU0_R_TPM_CS_N")
	)
	(segment
		(start 374.899428 -300.651164)
		(end 374.412256 -301.138336)
		(width 0.10668)
		(layer "F.Cu")
		(net "SPI_CPU0_R_TPM_CS_N")
	)
	(segment
		(start 375.30024 -302.144176)
		(end 375.418096 -302.144176)
		(width 0.10668)
		(layer "F.Cu")
		(net "SPI_CPU0_R_TPM_CS_N")
	)
	(segment
		(start 375.905268 -301.657004)
		(end 376.023124 -301.657004)
		(width 0.10668)
		(layer "F.Cu")
		(net "SPI_CPU0_R_TPM_CS_N")
	)
	(segment
		(start 374.412256 -301.138336)
		(end 374.412256 -301.256192)
		(width 0.10668)
		(layer "F.Cu")
		(net "SPI_CPU0_R_TPM_CS_N")
	)
	(segment
		(start 374.613424 -301.339504)
		(end 375.100596 -300.852332)
		(width 0.10668)
		(layer "F.Cu")
		(net "SPI_CPU0_R_TPM_CS_N")
	)
	(segment
		(start 378.151898 -313.0423)
		(end 386.81025 -321.700652)
		(width 0.10668)
		(layer "F.Cu")
		(net "SPI_CPU0_R_TPM_CS_N")
	)
	(segment
		(start 375.301764 -300.935644)
		(end 375.301764 -301.0535)
		(width 0.10668)
		(layer "F.Cu")
		(net "SPI_CPU0_R_TPM_CS_N")
	)
	(segment
		(start 375.100596 -300.852332)
		(end 375.218452 -300.852332)
		(width 0.10668)
		(layer "F.Cu")
		(net "SPI_CPU0_R_TPM_CS_N")
	)
	(segment
		(start 398.646904 -323.965316)
		(end 400.08302 -323.965316)
		(width 0.10668)
		(layer "F.Cu")
		(net "SPI_CPU0_R_TPM_CS_N")
	)
	(segment
		(start 374.816116 -300.449996)
		(end 374.899428 -300.533308)
		(width 0.10668)
		(layer "F.Cu")
		(net "SPI_CPU0_R_TPM_CS_N")
	)
	(segment
		(start 374.211088 -300.937168)
		(end 374.69826 -300.449996)
		(width 0.10668)
		(layer "F.Cu")
		(net "SPI_CPU0_R_TPM_CS_N")
	)
	(segment
		(start 376.104912 -302.948848)
		(end 376.222768 -302.948848)
		(width 0.10668)
		(layer "F.Cu")
		(net "SPI_CPU0_R_TPM_CS_N")
	)
	(segment
		(start 374.897904 -301.74184)
		(end 375.01576 -301.74184)
		(width 0.10668)
		(layer "F.Cu")
		(net "SPI_CPU0_R_TPM_CS_N")
	)
	(segment
		(start 375.7041 -301.33798)
		(end 375.7041 -301.455836)
		(width 0.10668)
		(layer "F.Cu")
		(net "SPI_CPU0_R_TPM_CS_N")
	)
	(segment
		(start 376.423936 -303.150016)
		(end 376.423936 -303.267872)
		(width 0.10668)
		(layer "F.Cu")
		(net "SPI_CPU0_R_TPM_CS_N")
	)
	(segment
		(start 376.508772 -302.260508)
		(end 376.0216 -302.74768)
		(width 0.10668)
		(layer "F.Cu")
		(net "SPI_CPU0_R_TPM_CS_N")
	)
	(segment
		(start 375.7041 -301.455836)
		(end 375.216928 -301.943008)
		(width 0.10668)
		(layer "F.Cu")
		(net "SPI_CPU0_R_TPM_CS_N")
	)
	(segment
		(start 375.619264 -302.4632)
		(end 375.702576 -302.546512)
		(width 0.10668)
		(layer "F.Cu")
		(net "SPI_CPU0_R_TPM_CS_N")
	)
	(segment
		(start 374.814592 -301.540672)
		(end 374.814592 -301.658528)
		(width 0.10668)
		(layer "F.Cu")
		(net "SPI_CPU0_R_TPM_CS_N")
	)
	(segment
		(start 371.767862 -295.690036)
		(end 371.767862 -297.401996)
		(width 0.10668)
		(layer "F.Cu")
		(net "SPI_CPU0_R_TPM_CS_N")
	)
	(segment
		(start 376.106436 -301.858172)
		(end 375.619264 -302.345344)
		(width 0.10668)
		(layer "F.Cu")
		(net "SPI_CPU0_R_TPM_CS_N")
	)
	(segment
		(start 376.826272 -303.552352)
		(end 376.826272 -303.670208)
		(width 0.10668)
		(layer "F.Cu")
		(net "SPI_CPU0_R_TPM_CS_N")
	)
	(segment
		(start 375.01576 -301.74184)
		(end 375.502932 -301.254668)
		(width 0.10668)
		(layer "F.Cu")
		(net "SPI_CPU0_R_TPM_CS_N")
	)
	(segment
		(start 376.423936 -303.267872)
		(end 376.507248 -303.351184)
		(width 0.10668)
		(layer "F.Cu")
		(net "SPI_CPU0_R_TPM_CS_N")
	)
	(segment
		(start 377.02744 -303.75352)
		(end 377.514866 -303.266094)
		(width 0.10668)
		(layer "F.Cu")
		(net "SPI_CPU0_R_TPM_CS_N")
	)
	(segment
		(start 377.112276 -302.864012)
		(end 377.230132 -302.864012)
		(width 0.10668)
		(layer "F.Cu")
		(net "SPI_CPU0_R_TPM_CS_N")
	)
	(segment
		(start 396.867888 -325.744332)
		(end 398.646904 -323.965316)
		(width 0.10668)
		(layer "F.Cu")
		(net "SPI_CPU0_R_TPM_CS_N")
	)
	(segment
		(start 376.508772 -302.142652)
		(end 376.508772 -302.260508)
		(width 0.10668)
		(layer "F.Cu")
		(net "SPI_CPU0_R_TPM_CS_N")
	)
	(segment
		(start 374.093232 -300.937168)
		(end 374.211088 -300.937168)
		(width 0.10668)
		(layer "F.Cu")
		(net "SPI_CPU0_R_TPM_CS_N")
	)
	(segment
		(start 374.495568 -301.339504)
		(end 374.613424 -301.339504)
		(width 0.10668)
		(layer "F.Cu")
		(net "SPI_CPU0_R_TPM_CS_N")
	)
	(segment
		(start 376.826272 -303.670208)
		(end 376.909584 -303.75352)
		(width 0.10668)
		(layer "F.Cu")
		(net "SPI_CPU0_R_TPM_CS_N")
	)
	(segment
		(start 375.418096 -302.144176)
		(end 375.905268 -301.657004)
		(width 0.10668)
		(layer "F.Cu")
		(net "SPI_CPU0_R_TPM_CS_N")
	)
	(segment
		(start 375.502932 -301.254668)
		(end 375.620788 -301.254668)
		(width 0.10668)
		(layer "F.Cu")
		(net "SPI_CPU0_R_TPM_CS_N")
	)
	(segment
		(start 374.899428 -300.533308)
		(end 374.899428 -300.651164)
		(width 0.10668)
		(layer "F.Cu")
		(net "SPI_CPU0_R_TPM_CS_N")
	)
	(segment
		(start 395.791944 -328.952098)
		(end 396.085822 -328.65822)
		(width 0.10668)
		(layer "F.Cu")
		(net "SPI_CPU0_R_TPM_CS_N")
	)
	(segment
		(start 377.632214 -303.266094)
		(end 378.151898 -303.786032)
		(width 0.10668)
		(layer "F.Cu")
		(net "SPI_CPU0_R_TPM_CS_N")
	)
	(segment
		(start 374.00992 -300.736)
		(end 374.00992 -300.853856)
		(width 0.10668)
		(layer "F.Cu")
		(net "SPI_CPU0_R_TPM_CS_N")
	)
	(segment
		(start 374.412256 -301.256192)
		(end 374.495568 -301.339504)
		(width 0.10668)
		(layer "F.Cu")
		(net "SPI_CPU0_R_TPM_CS_N")
	)
	(segment
		(start 371.767862 -297.401996)
		(end 374.497346 -300.131226)
		(width 0.10668)
		(layer "F.Cu")
		(net "SPI_CPU0_R_TPM_CS_N")
	)
	(segment
		(start 374.497346 -300.248574)
		(end 374.00992 -300.736)
		(width 0.10668)
		(layer "F.Cu")
		(net "SPI_CPU0_R_TPM_CS_N")
	)
	(segment
		(start 386.81025 -321.700652)
		(end 386.81025 -322.197984)
		(width 0.10668)
		(layer "F.Cu")
		(net "SPI_CPU0_R_TPM_CS_N")
	)
	(segment
		(start 375.702576 -302.546512)
		(end 375.820432 -302.546512)
		(width 0.10668)
		(layer "F.Cu")
		(net "SPI_CPU0_R_TPM_CS_N")
	)
	(segment
		(start 376.0216 -302.865536)
		(end 376.104912 -302.948848)
		(width 0.10668)
		(layer "F.Cu")
		(net "SPI_CPU0_R_TPM_CS_N")
	)
	(segment
		(start 376.911108 -302.544988)
		(end 376.911108 -302.662844)
		(width 0.10668)
		(layer "F.Cu")
		(net "SPI_CPU0_R_TPM_CS_N")
	)
	(segment
		(start 392.444224 -328.952098)
		(end 395.791944 -328.952098)
		(width 0.10668)
		(layer "F.Cu")
		(net "SPI_CPU0_R_TPM_CS_N")
	)
	(segment
		(start 376.023124 -301.657004)
		(end 376.106436 -301.740316)
		(width 0.10668)
		(layer "F.Cu")
		(net "SPI_CPU0_R_TPM_CS_N")
	)
	(segment
		(start 377.230132 -302.864012)
		(end 377.313444 -302.947324)
		(width 0.10668)
		(layer "F.Cu")
		(net "SPI_CPU0_R_TPM_CS_N")
	)
	(segment
		(start 375.216928 -301.943008)
		(end 375.216928 -302.060864)
		(width 0.10668)
		(layer "F.Cu")
		(net "SPI_CPU0_R_TPM_CS_N")
	)
	(segment
		(start 377.514866 -303.266094)
		(end 377.632214 -303.266094)
		(width 0.10668)
		(layer "F.Cu")
		(net "SPI_CPU0_R_TPM_CS_N")
	)
	(segment
		(start 389.400034 -325.907908)
		(end 392.444224 -328.952098)
		(width 0.10668)
		(layer "F.Cu")
		(net "SPI_CPU0_R_TPM_CS_N")
	)
	(segment
		(start 376.507248 -303.351184)
		(end 376.625104 -303.351184)
		(width 0.10668)
		(layer "F.Cu")
		(net "SPI_CPU0_R_TPM_CS_N")
	)
	(segment
		(start 374.497346 -300.131226)
		(end 374.497346 -300.248574)
		(width 0.10668)
		(layer "F.Cu")
		(net "SPI_CPU0_R_TPM_CS_N")
	)
	(segment
		(start 376.625104 -303.351184)
		(end 377.112276 -302.864012)
		(width 0.10668)
		(layer "F.Cu")
		(net "SPI_CPU0_R_TPM_CS_N")
	)
	(segment
		(start 386.81025 -322.197984)
		(end 389.400034 -324.787768)
		(width 0.10668)
		(layer "F.Cu")
		(net "SPI_CPU0_R_TPM_CS_N")
	)
	(segment
		(start 396.867888 -326.770238)
		(end 396.867888 -325.744332)
		(width 0.10668)
		(layer "F.Cu")
		(net "SPI_CPU0_R_TPM_CS_N")
	)
	(segment
		(start 376.42546 -302.05934)
		(end 376.508772 -302.142652)
		(width 0.10668)
		(layer "F.Cu")
		(net "SPI_CPU0_R_TPM_CS_N")
	)
	(segment
		(start 376.911108 -302.662844)
		(end 376.423936 -303.150016)
		(width 0.10668)
		(layer "F.Cu")
		(net "SPI_CPU0_R_TPM_CS_N")
	)
	(segment
		(start 376.0216 -302.74768)
		(end 376.0216 -302.865536)
		(width 0.10668)
		(layer "F.Cu")
		(net "SPI_CPU0_R_TPM_CS_N")
	)
	(segment
		(start 377.313444 -303.06518)
		(end 376.826272 -303.552352)
		(width 0.10668)
		(layer "F.Cu")
		(net "SPI_CPU0_R_TPM_CS_N")
	)
	(segment
		(start 375.301764 -301.0535)
		(end 374.814592 -301.540672)
		(width 0.10668)
		(layer "F.Cu")
		(net "SPI_CPU0_R_TPM_CS_N")
	)
	(segment
		(start 376.106436 -301.740316)
		(end 376.106436 -301.858172)
		(width 0.10668)
		(layer "F.Cu")
		(net "SPI_CPU0_R_TPM_CS_N")
	)
	(segment
		(start 376.222768 -302.948848)
		(end 376.70994 -302.461676)
		(width 0.10668)
		(layer "F.Cu")
		(net "SPI_CPU0_R_TPM_CS_N")
	)
	(segment
		(start 376.909584 -303.75352)
		(end 377.02744 -303.75352)
		(width 0.10668)
		(layer "F.Cu")
		(net "SPI_CPU0_R_TPM_CS_N")
	)
	(segment
		(start 396.085822 -328.65822)
		(end 396.867888 -326.770238)
		(width 0.10668)
		(layer "F.Cu")
		(net "SPI_CPU0_R_TPM_CS_N")
	)
	(via
		(at 386.81025 -322.197984)
		(size 0.762)
		(drill 0.381)
		(layers "F.Cu" "B.Cu")
		(net "SPI_CPU0_R_TPM_CS_N")
	)
	(segment
		(start 401.078446 -328.418952)
		(end 400.630644 -328.866754)
		(width 0.10668)
		(layer "F.Cu")
		(net "SPI_CPU0_R_D3")
	)
	(segment
		(start 384.313684 -326.751696)
		(end 367.504218 -309.94223)
		(width 0.10668)
		(layer "F.Cu")
		(net "SPI_CPU0_R_D3")
	)
	(segment
		(start 401.074128 -331.982064)
		(end 399.201132 -333.85506)
		(width 0.10668)
		(layer "F.Cu")
		(net "SPI_CPU0_R_D3")
	)
	(segment
		(start 401.074128 -330.070968)
		(end 401.074128 -331.982064)
		(width 0.10668)
		(layer "F.Cu")
		(net "SPI_CPU0_R_D3")
	)
	(segment
		(start 368.0079 -295.040304)
		(end 368.0079 -294.070024)
		(width 0.10668)
		(layer "F.Cu")
		(net "SPI_CPU0_R_D3")
	)
	(segment
		(start 399.201132 -333.85506)
		(end 391.417048 -333.85506)
		(width 0.10668)
		(layer "F.Cu")
		(net "SPI_CPU0_R_D3")
	)
	(segment
		(start 401.853908 -328.418952)
		(end 401.078446 -328.418952)
		(width 0.10668)
		(layer "F.Cu")
		(net "SPI_CPU0_R_D3")
	)
	(segment
		(start 400.630644 -328.866754)
		(end 400.630644 -329.627484)
		(width 0.10668)
		(layer "F.Cu")
		(net "SPI_CPU0_R_D3")
	)
	(segment
		(start 400.630644 -329.627484)
		(end 401.074128 -330.070968)
		(width 0.10668)
		(layer "F.Cu")
		(net "SPI_CPU0_R_D3")
	)
	(segment
		(start 391.417048 -333.85506)
		(end 384.313684 -326.751696)
		(width 0.10668)
		(layer "F.Cu")
		(net "SPI_CPU0_R_D3")
	)
	(segment
		(start 367.504218 -295.543986)
		(end 368.0079 -295.040304)
		(width 0.10668)
		(layer "F.Cu")
		(net "SPI_CPU0_R_D3")
	)
	(segment
		(start 367.504218 -309.94223)
		(end 367.504218 -295.543986)
		(width 0.10668)
		(layer "F.Cu")
		(net "SPI_CPU0_R_D3")
	)
	(via
		(at 384.313684 -326.751696)
		(size 0.762)
		(drill 0.381)
		(layers "F.Cu" "B.Cu")
		(net "SPI_CPU0_R_D3")
	)
	(segment
		(start 371.61978 -300.66615)
		(end 371.037612 -301.248318)
		(width 0.10668)
		(layer "F.Cu")
		(net "SPI_CPU0_R_D2")
	)
	(segment
		(start 368.947954 -297.876468)
		(end 371.61978 -300.548294)
		(width 0.10668)
		(layer "F.Cu")
		(net "SPI_CPU0_R_D2")
	)
	(segment
		(start 372.043452 -302.254158)
		(end 372.62562 -301.67199)
		(width 0.10668)
		(layer "F.Cu")
		(net "SPI_CPU0_R_D2")
	)
	(segment
		(start 371.439948 -301.650654)
		(end 371.439948 -301.76851)
		(width 0.10668)
		(layer "F.Cu")
		(net "SPI_CPU0_R_D2")
	)
	(segment
		(start 372.826788 -301.873158)
		(end 372.24462 -302.455326)
		(width 0.10668)
		(layer "F.Cu")
		(net "SPI_CPU0_R_D2")
	)
	(segment
		(start 396.51686 -331.717904)
		(end 400.007328 -328.227436)
		(width 0.10668)
		(layer "F.Cu")
		(net "SPI_CPU0_R_D2")
	)
	(segment
		(start 368.947954 -295.690036)
		(end 368.947954 -297.876468)
		(width 0.10668)
		(layer "F.Cu")
		(net "SPI_CPU0_R_D2")
	)
	(segment
		(start 371.037612 -301.248318)
		(end 371.037612 -301.366174)
		(width 0.10668)
		(layer "F.Cu")
		(net "SPI_CPU0_R_D2")
	)
	(segment
		(start 386.421884 -325.408544)
		(end 392.731244 -331.717904)
		(width 0.10668)
		(layer "F.Cu")
		(net "SPI_CPU0_R_D2")
	)
	(segment
		(start 372.022116 -301.068486)
		(end 371.439948 -301.650654)
		(width 0.10668)
		(layer "F.Cu")
		(net "SPI_CPU0_R_D2")
	)
	(segment
		(start 384.390646 -322.174362)
		(end 386.421884 -324.2056)
		(width 0.10668)
		(layer "F.Cu")
		(net "SPI_CPU0_R_D2")
	)
	(segment
		(start 371.037612 -301.366174)
		(end 371.120924 -301.449486)
		(width 0.10668)
		(layer "F.Cu")
		(net "SPI_CPU0_R_D2")
	)
	(segment
		(start 372.223284 -301.269654)
		(end 372.34114 -301.269654)
		(width 0.10668)
		(layer "F.Cu")
		(net "SPI_CPU0_R_D2")
	)
	(segment
		(start 371.61978 -300.548294)
		(end 371.61978 -300.66615)
		(width 0.10668)
		(layer "F.Cu")
		(net "SPI_CPU0_R_D2")
	)
	(segment
		(start 372.646956 -302.857662)
		(end 372.646956 -302.975518)
		(width 0.10668)
		(layer "F.Cu")
		(net "SPI_CPU0_R_D2")
	)
	(segment
		(start 371.120924 -301.449486)
		(end 371.23878 -301.449486)
		(width 0.10668)
		(layer "F.Cu")
		(net "SPI_CPU0_R_D2")
	)
	(segment
		(start 371.820948 -300.867318)
		(end 371.938804 -300.867318)
		(width 0.10668)
		(layer "F.Cu")
		(net "SPI_CPU0_R_D2")
	)
	(segment
		(start 372.24462 -302.573182)
		(end 372.327932 -302.656494)
		(width 0.10668)
		(layer "F.Cu")
		(net "SPI_CPU0_R_D2")
	)
	(segment
		(start 371.842284 -302.05299)
		(end 371.842284 -302.170846)
		(width 0.10668)
		(layer "F.Cu")
		(net "SPI_CPU0_R_D2")
	)
	(segment
		(start 372.730268 -303.05883)
		(end 372.848124 -303.05883)
		(width 0.10668)
		(layer "F.Cu")
		(net "SPI_CPU0_R_D2")
	)
	(segment
		(start 384.390646 -321.02044)
		(end 384.390646 -322.174362)
		(width 0.10668)
		(layer "F.Cu")
		(net "SPI_CPU0_R_D2")
	)
	(segment
		(start 373.229124 -302.157638)
		(end 373.229124 -302.275494)
		(width 0.10668)
		(layer "F.Cu")
		(net "SPI_CPU0_R_D2")
	)
	(segment
		(start 372.424452 -301.352966)
		(end 372.424452 -301.470822)
		(width 0.10668)
		(layer "F.Cu")
		(net "SPI_CPU0_R_D2")
	)
	(segment
		(start 376.157744 -305.086258)
		(end 376.157744 -312.787538)
		(width 0.10668)
		(layer "F.Cu")
		(net "SPI_CPU0_R_D2")
	)
	(segment
		(start 372.62562 -301.67199)
		(end 372.743476 -301.67199)
		(width 0.10668)
		(layer "F.Cu")
		(net "SPI_CPU0_R_D2")
	)
	(segment
		(start 371.641116 -301.851822)
		(end 372.223284 -301.269654)
		(width 0.10668)
		(layer "F.Cu")
		(net "SPI_CPU0_R_D2")
	)
	(segment
		(start 386.421884 -324.2056)
		(end 386.421884 -325.408544)
		(width 0.10668)
		(layer "F.Cu")
		(net "SPI_CPU0_R_D2")
	)
	(segment
		(start 371.842284 -302.170846)
		(end 371.925596 -302.254158)
		(width 0.10668)
		(layer "F.Cu")
		(net "SPI_CPU0_R_D2")
	)
	(segment
		(start 371.23878 -301.449486)
		(end 371.820948 -300.867318)
		(width 0.10668)
		(layer "F.Cu")
		(net "SPI_CPU0_R_D2")
	)
	(segment
		(start 376.157744 -312.787538)
		(end 384.390646 -321.02044)
		(width 0.10668)
		(layer "F.Cu")
		(net "SPI_CPU0_R_D2")
	)
	(segment
		(start 373.145812 -302.074326)
		(end 373.229124 -302.157638)
		(width 0.10668)
		(layer "F.Cu")
		(net "SPI_CPU0_R_D2")
	)
	(segment
		(start 372.34114 -301.269654)
		(end 372.424452 -301.352966)
		(width 0.10668)
		(layer "F.Cu")
		(net "SPI_CPU0_R_D2")
	)
	(segment
		(start 372.848124 -303.05883)
		(end 373.430292 -302.476662)
		(width 0.10668)
		(layer "F.Cu")
		(net "SPI_CPU0_R_D2")
	)
	(segment
		(start 372.424452 -301.470822)
		(end 371.842284 -302.05299)
		(width 0.10668)
		(layer "F.Cu")
		(net "SPI_CPU0_R_D2")
	)
	(segment
		(start 371.52326 -301.851822)
		(end 371.641116 -301.851822)
		(width 0.10668)
		(layer "F.Cu")
		(net "SPI_CPU0_R_D2")
	)
	(segment
		(start 373.229124 -302.275494)
		(end 372.646956 -302.857662)
		(width 0.10668)
		(layer "F.Cu")
		(net "SPI_CPU0_R_D2")
	)
	(segment
		(start 400.007328 -328.227436)
		(end 400.007328 -327.395332)
		(width 0.10668)
		(layer "F.Cu")
		(net "SPI_CPU0_R_D2")
	)
	(segment
		(start 392.731244 -331.717904)
		(end 396.51686 -331.717904)
		(width 0.10668)
		(layer "F.Cu")
		(net "SPI_CPU0_R_D2")
	)
	(segment
		(start 371.925596 -302.254158)
		(end 372.043452 -302.254158)
		(width 0.10668)
		(layer "F.Cu")
		(net "SPI_CPU0_R_D2")
	)
	(segment
		(start 373.027956 -302.074326)
		(end 373.145812 -302.074326)
		(width 0.10668)
		(layer "F.Cu")
		(net "SPI_CPU0_R_D2")
	)
	(segment
		(start 373.548148 -302.476662)
		(end 376.157744 -305.086258)
		(width 0.10668)
		(layer "F.Cu")
		(net "SPI_CPU0_R_D2")
	)
	(segment
		(start 371.439948 -301.76851)
		(end 371.52326 -301.851822)
		(width 0.10668)
		(layer "F.Cu")
		(net "SPI_CPU0_R_D2")
	)
	(segment
		(start 373.430292 -302.476662)
		(end 373.548148 -302.476662)
		(width 0.10668)
		(layer "F.Cu")
		(net "SPI_CPU0_R_D2")
	)
	(segment
		(start 372.327932 -302.656494)
		(end 372.445788 -302.656494)
		(width 0.10668)
		(layer "F.Cu")
		(net "SPI_CPU0_R_D2")
	)
	(segment
		(start 372.24462 -302.455326)
		(end 372.24462 -302.573182)
		(width 0.10668)
		(layer "F.Cu")
		(net "SPI_CPU0_R_D2")
	)
	(segment
		(start 372.743476 -301.67199)
		(end 372.826788 -301.755302)
		(width 0.10668)
		(layer "F.Cu")
		(net "SPI_CPU0_R_D2")
	)
	(segment
		(start 372.646956 -302.975518)
		(end 372.730268 -303.05883)
		(width 0.10668)
		(layer "F.Cu")
		(net "SPI_CPU0_R_D2")
	)
	(segment
		(start 371.938804 -300.867318)
		(end 372.022116 -300.95063)
		(width 0.10668)
		(layer "F.Cu")
		(net "SPI_CPU0_R_D2")
	)
	(segment
		(start 372.022116 -300.95063)
		(end 372.022116 -301.068486)
		(width 0.10668)
		(layer "F.Cu")
		(net "SPI_CPU0_R_D2")
	)
	(segment
		(start 372.445788 -302.656494)
		(end 373.027956 -302.074326)
		(width 0.10668)
		(layer "F.Cu")
		(net "SPI_CPU0_R_D2")
	)
	(segment
		(start 372.826788 -301.755302)
		(end 372.826788 -301.873158)
		(width 0.10668)
		(layer "F.Cu")
		(net "SPI_CPU0_R_D2")
	)
	(via
		(at 386.421884 -325.408544)
		(size 0.762)
		(drill 0.381)
		(layers "F.Cu" "B.Cu")
		(net "SPI_CPU0_R_D2")
	)
	(segment
		(start 398.205198 -322.938394)
		(end 398.21358 -322.930012)
		(width 0.10668)
		(layer "F.Cu")
		(net "SPI_CPU0_R_D1")
	)
	(segment
		(start 374.588024 -294.070024)
		(end 375.054876 -294.335962)
		(width 0.10668)
		(layer "F.Cu")
		(net "SPI_CPU0_R_D1")
	)
	(segment
		(start 398.21358 -322.930012)
		(end 398.962118 -322.930012)
		(width 0.10668)
		(layer "F.Cu")
		(net "SPI_CPU0_R_D1")
	)
	(via
		(at 398.205198 -322.938394)
		(size 0.508)
		(drill 0.254)
		(layers "F.Cu" "B.Cu")
		(net "SPI_CPU0_R_D1")
	)
	(via
		(at 375.054876 -294.335962)
		(size 0.4064)
		(drill 0.2032)
		(layers "F.Cu" "B.Cu")
		(net "SPI_CPU0_R_D1")
	)
	(segment
		(start 374.685052 -295.739312)
		(end 374.977152 -295.739312)
		(width 0.10668)
		(layer "B.Cu")
		(net "SPI_CPU0_R_D1")
	)
	(segment
		(start 386.043678 -316.126876)
		(end 385.960366 -316.210188)
		(width 0.10668)
		(layer "B.Cu")
		(net "SPI_CPU0_R_D1")
	)
	(segment
		(start 389.06831 -320.157348)
		(end 386.351018 -317.440056)
		(width 0.10668)
		(layer "B.Cu")
		(net "SPI_CPU0_R_D1")
	)
	(segment
		(start 378.597414 -306.766976)
		(end 378.680726 -306.683664)
		(width 0.10668)
		(layer "B.Cu")
		(net "SPI_CPU0_R_D1")
	)
	(segment
		(start 378.111766 -303.585118)
		(end 378.028454 -303.501806)
		(width 0.10668)
		(layer "B.Cu")
		(net "SPI_CPU0_R_D1")
	)
	(segment
		(start 377.827286 -303.585118)
		(end 377.827286 -306.399184)
		(width 0.10668)
		(layer "B.Cu")
		(net "SPI_CPU0_R_D1")
	)
	(segment
		(start 377.542806 -306.399184)
		(end 377.542806 -302.602138)
		(width 0.10668)
		(layer "B.Cu")
		(net "SPI_CPU0_R_D1")
	)
	(segment
		(start 378.111766 -306.399184)
		(end 378.111766 -303.585118)
		(width 0.10668)
		(layer "B.Cu")
		(net "SPI_CPU0_R_D1")
	)
	(segment
		(start 390.093708 -319.10274)
		(end 390.010396 -319.019428)
		(width 0.10668)
		(layer "B.Cu")
		(net "SPI_CPU0_R_D1")
	)
	(segment
		(start 389.840724 -319.872868)
		(end 390.010396 -319.872868)
		(width 0.10668)
		(layer "B.Cu")
		(net "SPI_CPU0_R_D1")
	)
	(segment
		(start 390.352534 -320.157348)
		(end 389.840724 -320.157348)
		(width 0.10668)
		(layer "B.Cu")
		(net "SPI_CPU0_R_D1")
	)
	(segment
		(start 398.205198 -322.938394)
		(end 398.205198 -322.48729)
		(width 0.10668)
		(layer "B.Cu")
		(net "SPI_CPU0_R_D1")
	)
	(segment
		(start 378.396246 -306.399184)
		(end 378.312934 -306.482496)
		(width 0.10668)
		(layer "B.Cu")
		(net "SPI_CPU0_R_D1")
	)
	(segment
		(start 374.415558 -296.008806)
		(end 374.685052 -295.739312)
		(width 0.10668)
		(layer "B.Cu")
		(net "SPI_CPU0_R_D1")
	)
	(segment
		(start 389.757412 -319.38722)
		(end 389.840724 -319.303908)
		(width 0.10668)
		(layer "B.Cu")
		(net "SPI_CPU0_R_D1")
	)
	(segment
		(start 390.010396 -319.019428)
		(end 389.556244 -319.019428)
		(width 0.10668)
		(layer "B.Cu")
		(net "SPI_CPU0_R_D1")
	)
	(segment
		(start 386.031994 -317.121032)
		(end 385.759198 -316.848236)
		(width 0.10668)
		(layer "B.Cu")
		(net "SPI_CPU0_R_D1")
	)
	(segment
		(start 386.244846 -316.494668)
		(end 386.328158 -316.411356)
		(width 0.10668)
		(layer "B.Cu")
		(net "SPI_CPU0_R_D1")
	)
	(segment
		(start 389.757412 -320.074036)
		(end 389.757412 -319.95618)
		(width 0.10668)
		(layer "B.Cu")
		(net "SPI_CPU0_R_D1")
	)
	(segment
		(start 389.472932 -319.10274)
		(end 389.472932 -320.074036)
		(width 0.10668)
		(layer "B.Cu")
		(net "SPI_CPU0_R_D1")
	)
	(segment
		(start 386.351018 -317.440056)
		(end 386.351018 -317.3222)
		(width 0.10668)
		(layer "B.Cu")
		(net "SPI_CPU0_R_D1")
	)
	(segment
		(start 393.04087 -319.070736)
		(end 391.926318 -319.070736)
		(width 0.10668)
		(layer "B.Cu")
		(net "SPI_CPU0_R_D1")
	)
	(segment
		(start 386.14985 -317.121032)
		(end 386.031994 -317.121032)
		(width 0.10668)
		(layer "B.Cu")
		(net "SPI_CPU0_R_D1")
	)
	(segment
		(start 386.43433 -317.238888)
		(end 386.552186 -317.238888)
		(width 0.10668)
		(layer "B.Cu")
		(net "SPI_CPU0_R_D1")
	)
	(segment
		(start 374.977152 -295.739312)
		(end 375.111772 -295.604692)
		(width 0.10668)
		(layer "B.Cu")
		(net "SPI_CPU0_R_D1")
	)
	(segment
		(start 377.910598 -303.501806)
		(end 377.827286 -303.585118)
		(width 0.10668)
		(layer "B.Cu")
		(net "SPI_CPU0_R_D1")
	)
	(segment
		(start 385.759198 -315.34862)
		(end 377.542806 -307.132228)
		(width 0.10668)
		(layer "B.Cu")
		(net "SPI_CPU0_R_D1")
	)
	(segment
		(start 378.028454 -303.501806)
		(end 377.910598 -303.501806)
		(width 0.10668)
		(layer "B.Cu")
		(net "SPI_CPU0_R_D1")
	)
	(segment
		(start 391.679176 -319.153032)
		(end 391.190988 -319.64122)
		(width 0.10668)
		(layer "B.Cu")
		(net "SPI_CPU0_R_D1")
	)
	(segment
		(start 375.990358 -295.348152)
		(end 375.990358 -295.023032)
		(width 0.10668)
		(layer "B.Cu")
		(net "SPI_CPU0_R_D1")
	)
	(segment
		(start 390.093708 -319.220596)
		(end 390.093708 -319.10274)
		(width 0.10668)
		(layer "B.Cu")
		(net "SPI_CPU0_R_D1")
	)
	(segment
		(start 385.84251 -316.494668)
		(end 386.244846 -316.494668)
		(width 0.10668)
		(layer "B.Cu")
		(net "SPI_CPU0_R_D1")
	)
	(segment
		(start 385.759198 -316.848236)
		(end 385.759198 -316.57798)
		(width 0.10668)
		(layer "B.Cu")
		(net "SPI_CPU0_R_D1")
	)
	(segment
		(start 386.328158 -316.411356)
		(end 386.328158 -315.925708)
		(width 0.10668)
		(layer "B.Cu")
		(net "SPI_CPU0_R_D1")
	)
	(segment
		(start 389.108188 -319.51041)
		(end 389.108188 -319.392554)
		(width 0.10668)
		(layer "B.Cu")
		(net "SPI_CPU0_R_D1")
	)
	(segment
		(start 391.190988 -319.64122)
		(end 390.868662 -319.64122)
		(width 0.10668)
		(layer "B.Cu")
		(net "SPI_CPU0_R_D1")
	)
	(segment
		(start 386.043678 -315.925708)
		(end 386.043678 -316.126876)
		(width 0.10668)
		(layer "B.Cu")
		(net "SPI_CPU0_R_D1")
	)
	(segment
		(start 394.3096 -320.339466)
		(end 393.04087 -319.070736)
		(width 0.10668)
		(layer "B.Cu")
		(net "SPI_CPU0_R_D1")
	)
	(segment
		(start 389.757412 -319.505076)
		(end 389.757412 -319.38722)
		(width 0.10668)
		(layer "B.Cu")
		(net "SPI_CPU0_R_D1")
	)
	(segment
		(start 377.542806 -307.132228)
		(end 377.542806 -306.850288)
		(width 0.10668)
		(layer "B.Cu")
		(net "SPI_CPU0_R_D1")
	)
	(segment
		(start 385.84251 -316.210188)
		(end 385.759198 -316.126876)
		(width 0.10668)
		(layer "B.Cu")
		(net "SPI_CPU0_R_D1")
	)
	(segment
		(start 377.827286 -306.399184)
		(end 377.743974 -306.482496)
		(width 0.10668)
		(layer "B.Cu")
		(net "SPI_CPU0_R_D1")
	)
	(segment
		(start 378.479558 -305.758596)
		(end 378.396246 -305.841908)
		(width 0.10668)
		(layer "B.Cu")
		(net "SPI_CPU0_R_D1")
	)
	(segment
		(start 377.626118 -306.482496)
		(end 377.542806 -306.399184)
		(width 0.10668)
		(layer "B.Cu")
		(net "SPI_CPU0_R_D1")
	)
	(segment
		(start 398.205198 -322.48729)
		(end 397.293592 -321.575684)
		(width 0.10668)
		(layer "B.Cu")
		(net "SPI_CPU0_R_D1")
	)
	(segment
		(start 378.680726 -306.683664)
		(end 378.680726 -305.841908)
		(width 0.10668)
		(layer "B.Cu")
		(net "SPI_CPU0_R_D1")
	)
	(segment
		(start 389.840724 -319.303908)
		(end 390.010396 -319.303908)
		(width 0.10668)
		(layer "B.Cu")
		(net "SPI_CPU0_R_D1")
	)
	(segment
		(start 375.733818 -295.604692)
		(end 375.990358 -295.348152)
		(width 0.10668)
		(layer "B.Cu")
		(net "SPI_CPU0_R_D1")
	)
	(segment
		(start 385.759198 -316.57798)
		(end 385.84251 -316.494668)
		(width 0.10668)
		(layer "B.Cu")
		(net "SPI_CPU0_R_D1")
	)
	(segment
		(start 377.743974 -306.482496)
		(end 377.626118 -306.482496)
		(width 0.10668)
		(layer "B.Cu")
		(net "SPI_CPU0_R_D1")
	)
	(segment
		(start 397.293592 -321.575684)
		(end 394.3096 -320.339466)
		(width 0.10668)
		(layer "B.Cu")
		(net "SPI_CPU0_R_D1")
	)
	(segment
		(start 391.926318 -319.070736)
		(end 391.679176 -319.153032)
		(width 0.10668)
		(layer "B.Cu")
		(net "SPI_CPU0_R_D1")
	)
	(segment
		(start 390.010396 -319.303908)
		(end 390.093708 -319.220596)
		(width 0.10668)
		(layer "B.Cu")
		(net "SPI_CPU0_R_D1")
	)
	(segment
		(start 390.010396 -319.872868)
		(end 390.093708 -319.789556)
		(width 0.10668)
		(layer "B.Cu")
		(net "SPI_CPU0_R_D1")
	)
	(segment
		(start 386.552186 -317.238888)
		(end 388.90702 -319.593722)
		(width 0.10668)
		(layer "B.Cu")
		(net "SPI_CPU0_R_D1")
	)
	(segment
		(start 375.497598 -294.530272)
		(end 375.249186 -294.530272)
		(width 0.10668)
		(layer "B.Cu")
		(net "SPI_CPU0_R_D1")
	)
	(segment
		(start 389.108188 -319.392554)
		(end 386.552186 -316.836552)
		(width 0.10668)
		(layer "B.Cu")
		(net "SPI_CPU0_R_D1")
	)
	(segment
		(start 375.249186 -294.530272)
		(end 375.054876 -294.335962)
		(width 0.10668)
		(layer "B.Cu")
		(net "SPI_CPU0_R_D1")
	)
	(segment
		(start 386.43433 -316.836552)
		(end 386.14985 -317.121032)
		(width 0.10668)
		(layer "B.Cu")
		(net "SPI_CPU0_R_D1")
	)
	(segment
		(start 390.093708 -319.789556)
		(end 390.093708 -319.6717)
		(width 0.10668)
		(layer "B.Cu")
		(net "SPI_CPU0_R_D1")
	)
	(segment
		(start 390.010396 -319.588388)
		(end 389.840724 -319.588388)
		(width 0.10668)
		(layer "B.Cu")
		(net "SPI_CPU0_R_D1")
	)
	(segment
		(start 385.759198 -316.126876)
		(end 385.759198 -315.34862)
		(width 0.10668)
		(layer "B.Cu")
		(net "SPI_CPU0_R_D1")
	)
	(segment
		(start 377.542806 -306.850288)
		(end 377.626118 -306.766976)
		(width 0.10668)
		(layer "B.Cu")
		(net "SPI_CPU0_R_D1")
	)
	(segment
		(start 377.626118 -306.766976)
		(end 378.597414 -306.766976)
		(width 0.10668)
		(layer "B.Cu")
		(net "SPI_CPU0_R_D1")
	)
	(segment
		(start 389.840724 -319.588388)
		(end 389.757412 -319.505076)
		(width 0.10668)
		(layer "B.Cu")
		(net "SPI_CPU0_R_D1")
	)
	(segment
		(start 388.90702 -319.593722)
		(end 389.024876 -319.593722)
		(width 0.10668)
		(layer "B.Cu")
		(net "SPI_CPU0_R_D1")
	)
	(segment
		(start 386.244846 -315.842396)
		(end 386.12699 -315.842396)
		(width 0.10668)
		(layer "B.Cu")
		(net "SPI_CPU0_R_D1")
	)
	(segment
		(start 386.12699 -315.842396)
		(end 386.043678 -315.925708)
		(width 0.10668)
		(layer "B.Cu")
		(net "SPI_CPU0_R_D1")
	)
	(segment
		(start 389.556244 -319.019428)
		(end 389.472932 -319.10274)
		(width 0.10668)
		(layer "B.Cu")
		(net "SPI_CPU0_R_D1")
	)
	(segment
		(start 385.960366 -316.210188)
		(end 385.84251 -316.210188)
		(width 0.10668)
		(layer "B.Cu")
		(net "SPI_CPU0_R_D1")
	)
	(segment
		(start 389.024876 -319.593722)
		(end 389.108188 -319.51041)
		(width 0.10668)
		(layer "B.Cu")
		(net "SPI_CPU0_R_D1")
	)
	(segment
		(start 377.542806 -302.602138)
		(end 375.287286 -297.15714)
		(width 0.10668)
		(layer "B.Cu")
		(net "SPI_CPU0_R_D1")
	)
	(segment
		(start 378.195078 -306.482496)
		(end 378.111766 -306.399184)
		(width 0.10668)
		(layer "B.Cu")
		(net "SPI_CPU0_R_D1")
	)
	(segment
		(start 378.680726 -305.841908)
		(end 378.597414 -305.758596)
		(width 0.10668)
		(layer "B.Cu")
		(net "SPI_CPU0_R_D1")
	)
	(segment
		(start 389.38962 -320.157348)
		(end 389.06831 -320.157348)
		(width 0.10668)
		(layer "B.Cu")
		(net "SPI_CPU0_R_D1")
	)
	(segment
		(start 378.312934 -306.482496)
		(end 378.195078 -306.482496)
		(width 0.10668)
		(layer "B.Cu")
		(net "SPI_CPU0_R_D1")
	)
	(segment
		(start 375.990358 -295.023032)
		(end 375.497598 -294.530272)
		(width 0.10668)
		(layer "B.Cu")
		(net "SPI_CPU0_R_D1")
	)
	(segment
		(start 375.111772 -295.604692)
		(end 375.733818 -295.604692)
		(width 0.10668)
		(layer "B.Cu")
		(net "SPI_CPU0_R_D1")
	)
	(segment
		(start 389.757412 -319.95618)
		(end 389.840724 -319.872868)
		(width 0.10668)
		(layer "B.Cu")
		(net "SPI_CPU0_R_D1")
	)
	(segment
		(start 390.093708 -319.6717)
		(end 390.010396 -319.588388)
		(width 0.10668)
		(layer "B.Cu")
		(net "SPI_CPU0_R_D1")
	)
	(segment
		(start 374.415558 -296.285412)
		(end 374.415558 -296.008806)
		(width 0.10668)
		(layer "B.Cu")
		(net "SPI_CPU0_R_D1")
	)
	(segment
		(start 386.351018 -317.3222)
		(end 386.43433 -317.238888)
		(width 0.10668)
		(layer "B.Cu")
		(net "SPI_CPU0_R_D1")
	)
	(segment
		(start 375.287286 -297.15714)
		(end 374.415558 -296.285412)
		(width 0.10668)
		(layer "B.Cu")
		(net "SPI_CPU0_R_D1")
	)
	(segment
		(start 386.328158 -315.925708)
		(end 386.244846 -315.842396)
		(width 0.10668)
		(layer "B.Cu")
		(net "SPI_CPU0_R_D1")
	)
	(segment
		(start 378.396246 -305.841908)
		(end 378.396246 -306.399184)
		(width 0.10668)
		(layer "B.Cu")
		(net "SPI_CPU0_R_D1")
	)
	(segment
		(start 390.868662 -319.64122)
		(end 390.352534 -320.157348)
		(width 0.10668)
		(layer "B.Cu")
		(net "SPI_CPU0_R_D1")
	)
	(segment
		(start 386.552186 -316.836552)
		(end 386.43433 -316.836552)
		(width 0.10668)
		(layer "B.Cu")
		(net "SPI_CPU0_R_D1")
	)
	(segment
		(start 389.472932 -320.074036)
		(end 389.38962 -320.157348)
		(width 0.10668)
		(layer "B.Cu")
		(net "SPI_CPU0_R_D1")
	)
	(segment
		(start 378.597414 -305.758596)
		(end 378.479558 -305.758596)
		(width 0.10668)
		(layer "B.Cu")
		(net "SPI_CPU0_R_D1")
	)
	(segment
		(start 389.840724 -320.157348)
		(end 389.757412 -320.074036)
		(width 0.10668)
		(layer "B.Cu")
		(net "SPI_CPU0_R_D1")
	)
	(segment
		(start 369.417854 -293.260018)
		(end 369.884706 -293.525956)
		(width 0.10668)
		(layer "F.Cu")
		(net "SPI_CPU0_R_D0")
	)
	(segment
		(start 395.725142 -330.862686)
		(end 395.68755 -330.900278)
		(width 0.10668)
		(layer "F.Cu")
		(net "SPI_CPU0_R_D0")
	)
	(segment
		(start 395.68755 -330.900278)
		(end 395.026388 -330.900278)
		(width 0.10668)
		(layer "F.Cu")
		(net "SPI_CPU0_R_D0")
	)
	(via
		(at 369.884706 -293.525956)
		(size 0.4064)
		(drill 0.2032)
		(layers "F.Cu" "B.Cu")
		(net "SPI_CPU0_R_D0")
	)
	(via
		(at 395.026388 -330.900278)
		(size 0.508)
		(drill 0.254)
		(layers "F.Cu" "B.Cu")
		(net "SPI_CPU0_R_D0")
	)
	(segment
		(start 368.474498 -294.184832)
		(end 368.474498 -294.809672)
		(width 0.10668)
		(layer "B.Cu")
		(net "SPI_CPU0_R_D0")
	)
	(segment
		(start 387.532626 -326.21728)
		(end 389.0137 -326.21728)
		(width 0.10668)
		(layer "B.Cu")
		(net "SPI_CPU0_R_D0")
	)
	(segment
		(start 393.226544 -330.832968)
		(end 394.959078 -330.832968)
		(width 0.10668)
		(layer "B.Cu")
		(net "SPI_CPU0_R_D0")
	)
	(segment
		(start 368.168428 -305.847242)
		(end 374.17502 -311.853834)
		(width 0.10668)
		(layer "B.Cu")
		(net "SPI_CPU0_R_D0")
	)
	(segment
		(start 394.959078 -330.832968)
		(end 395.026388 -330.900278)
		(width 0.10668)
		(layer "B.Cu")
		(net "SPI_CPU0_R_D0")
	)
	(segment
		(start 374.17502 -311.853834)
		(end 374.17502 -312.859674)
		(width 0.10668)
		(layer "B.Cu")
		(net "SPI_CPU0_R_D0")
	)
	(segment
		(start 368.168428 -297.109642)
		(end 368.168428 -305.847242)
		(width 0.10668)
		(layer "B.Cu")
		(net "SPI_CPU0_R_D0")
	)
	(segment
		(start 389.0137 -326.21728)
		(end 389.12038 -326.32396)
		(width 0.10668)
		(layer "B.Cu")
		(net "SPI_CPU0_R_D0")
	)
	(segment
		(start 374.17502 -312.859674)
		(end 387.532626 -326.21728)
		(width 0.10668)
		(layer "B.Cu")
		(net "SPI_CPU0_R_D0")
	)
	(segment
		(start 368.372898 -294.911272)
		(end 368.372898 -296.905172)
		(width 0.10668)
		(layer "B.Cu")
		(net "SPI_CPU0_R_D0")
	)
	(segment
		(start 368.372898 -296.905172)
		(end 368.168428 -297.109642)
		(width 0.10668)
		(layer "B.Cu")
		(net "SPI_CPU0_R_D0")
	)
	(segment
		(start 389.12038 -326.32396)
		(end 389.12038 -326.726804)
		(width 0.10668)
		(layer "B.Cu")
		(net "SPI_CPU0_R_D0")
	)
	(segment
		(start 368.474498 -294.809672)
		(end 368.372898 -294.911272)
		(width 0.10668)
		(layer "B.Cu")
		(net "SPI_CPU0_R_D0")
	)
	(segment
		(start 389.12038 -326.726804)
		(end 393.226544 -330.832968)
		(width 0.10668)
		(layer "B.Cu")
		(net "SPI_CPU0_R_D0")
	)
	(segment
		(start 369.133374 -293.525956)
		(end 368.474498 -294.184832)
		(width 0.10668)
		(layer "B.Cu")
		(net "SPI_CPU0_R_D0")
	)
	(segment
		(start 369.884706 -293.525956)
		(end 369.133374 -293.525956)
		(width 0.10668)
		(layer "B.Cu")
		(net "SPI_CPU0_R_D0")
	)
	(segment
		(start 370.828062 -294.070024)
		(end 371.294914 -294.335962)
		(width 0.10668)
		(layer "F.Cu")
		(net "SPI_CPU0_R_CS1_N")
	)
	(via
		(at 370.842794 -303.9745)
		(size 0.6604)
		(drill 0.3302)
		(layers "F.Cu" "B.Cu")
		(net "SPI_CPU0_R_CS1_N")
	)
	(via
		(at 371.294914 -294.335962)
		(size 0.4064)
		(drill 0.2032)
		(layers "F.Cu" "B.Cu")
		(net "SPI_CPU0_R_CS1_N")
	)
	(segment
		(start 370.842794 -303.613312)
		(end 370.74602 -303.516538)
		(width 0.10668)
		(layer "B.Cu")
		(net "SPI_CPU0_R_CS1_N")
	)
	(segment
		(start 371.294914 -295.316656)
		(end 371.294914 -294.335962)
		(width 0.10668)
		(layer "B.Cu")
		(net "SPI_CPU0_R_CS1_N")
	)
	(segment
		(start 388.068566 -324.02526)
		(end 382.401318 -318.358012)
		(width 0.10668)
		(layer "B.Cu")
		(net "SPI_CPU0_R_CS1_N")
	)
	(segment
		(start 370.74602 -303.516538)
		(end 370.74602 -295.86555)
		(width 0.10668)
		(layer "B.Cu")
		(net "SPI_CPU0_R_CS1_N")
	)
	(segment
		(start 371.071394 -306.04968)
		(end 370.842794 -305.497992)
		(width 0.10668)
		(layer "B.Cu")
		(net "SPI_CPU0_R_CS1_N")
	)
	(segment
		(start 382.401318 -318.358012)
		(end 382.401318 -317.379604)
		(width 0.10668)
		(layer "B.Cu")
		(net "SPI_CPU0_R_CS1_N")
	)
	(segment
		(start 382.401318 -317.379604)
		(end 371.071394 -306.04968)
		(width 0.10668)
		(layer "B.Cu")
		(net "SPI_CPU0_R_CS1_N")
	)
	(segment
		(start 393.040108 -327.644252)
		(end 392.164316 -326.76846)
		(width 0.10668)
		(layer "B.Cu")
		(net "SPI_CPU0_R_CS1_N")
	)
	(segment
		(start 370.74602 -295.86555)
		(end 371.294914 -295.316656)
		(width 0.10668)
		(layer "B.Cu")
		(net "SPI_CPU0_R_CS1_N")
	)
	(segment
		(start 370.842794 -305.497992)
		(end 370.842794 -303.9745)
		(width 0.10668)
		(layer "B.Cu")
		(net "SPI_CPU0_R_CS1_N")
	)
	(segment
		(start 370.842794 -303.9745)
		(end 370.842794 -303.613312)
		(width 0.10668)
		(layer "B.Cu")
		(net "SPI_CPU0_R_CS1_N")
	)
	(segment
		(start 390.08812 -324.02526)
		(end 388.068566 -324.02526)
		(width 0.10668)
		(layer "B.Cu")
		(net "SPI_CPU0_R_CS1_N")
	)
	(segment
		(start 392.164316 -326.101456)
		(end 390.08812 -324.02526)
		(width 0.10668)
		(layer "B.Cu")
		(net "SPI_CPU0_R_CS1_N")
	)
	(segment
		(start 392.164316 -326.76846)
		(end 392.164316 -326.101456)
		(width 0.10668)
		(layer "B.Cu")
		(net "SPI_CPU0_R_CS1_N")
	)
	(segment
		(start 399.420588 -330.975716)
		(end 399.393664 -331.00264)
		(width 0.10668)
		(layer "F.Cu")
		(net "SPI_CPU0_R_CS0_N")
	)
	(segment
		(start 400.22272 -330.975716)
		(end 399.420588 -330.975716)
		(width 0.10668)
		(layer "F.Cu")
		(net "SPI_CPU0_R_CS0_N")
	)
	(segment
		(start 367.538 -293.260018)
		(end 368.004852 -293.525956)
		(width 0.10668)
		(layer "F.Cu")
		(net "SPI_CPU0_R_CS0_N")
	)
	(via
		(at 399.393664 -331.00264)
		(size 0.508)
		(drill 0.254)
		(layers "F.Cu" "B.Cu")
		(net "SPI_CPU0_R_CS0_N")
	)
	(via
		(at 368.004852 -293.525956)
		(size 0.4064)
		(drill 0.2032)
		(layers "F.Cu" "B.Cu")
		(net "SPI_CPU0_R_CS0_N")
	)
	(segment
		(start 387.197346 -326.706992)
		(end 373.577358 -313.087004)
		(width 0.10668)
		(layer "B.Cu")
		(net "SPI_CPU0_R_CS0_N")
	)
	(segment
		(start 396.6591 -330.808584)
		(end 395.769592 -331.698092)
		(width 0.10668)
		(layer "B.Cu")
		(net "SPI_CPU0_R_CS0_N")
	)
	(segment
		(start 367.961418 -294.728392)
		(end 368.004852 -294.684958)
		(width 0.10668)
		(layer "B.Cu")
		(net "SPI_CPU0_R_CS0_N")
	)
	(segment
		(start 373.577358 -311.972452)
		(end 367.56594 -305.961034)
		(width 0.10668)
		(layer "B.Cu")
		(net "SPI_CPU0_R_CS0_N")
	)
	(segment
		(start 368.004852 -294.684958)
		(end 368.004852 -293.525956)
		(width 0.10668)
		(layer "B.Cu")
		(net "SPI_CPU0_R_CS0_N")
	)
	(segment
		(start 399.199608 -330.808584)
		(end 396.6591 -330.808584)
		(width 0.10668)
		(layer "B.Cu")
		(net "SPI_CPU0_R_CS0_N")
	)
	(segment
		(start 373.577358 -313.087004)
		(end 373.577358 -311.972452)
		(width 0.10668)
		(layer "B.Cu")
		(net "SPI_CPU0_R_CS0_N")
	)
	(segment
		(start 395.769592 -331.698092)
		(end 393.069572 -331.698092)
		(width 0.10668)
		(layer "B.Cu")
		(net "SPI_CPU0_R_CS0_N")
	)
	(segment
		(start 399.393664 -331.00264)
		(end 399.199608 -330.808584)
		(width 0.10668)
		(layer "B.Cu")
		(net "SPI_CPU0_R_CS0_N")
	)
	(segment
		(start 393.069572 -331.698092)
		(end 388.078472 -326.706992)
		(width 0.10668)
		(layer "B.Cu")
		(net "SPI_CPU0_R_CS0_N")
	)
	(segment
		(start 388.078472 -326.706992)
		(end 387.197346 -326.706992)
		(width 0.10668)
		(layer "B.Cu")
		(net "SPI_CPU0_R_CS0_N")
	)
	(segment
		(start 367.961418 -296.482262)
		(end 367.961418 -294.728392)
		(width 0.10668)
		(layer "B.Cu")
		(net "SPI_CPU0_R_CS0_N")
	)
	(segment
		(start 367.56594 -305.961034)
		(end 367.56594 -296.87774)
		(width 0.10668)
		(layer "B.Cu")
		(net "SPI_CPU0_R_CS0_N")
	)
	(segment
		(start 367.56594 -296.87774)
		(end 367.961418 -296.482262)
		(width 0.10668)
		(layer "B.Cu")
		(net "SPI_CPU0_R_CS0_N")
	)
	(segment
		(start 376.807984 -306.76088)
		(end 376.891296 -306.844192)
		(width 0.10668)
		(layer "F.Cu")
		(net "SPI_CPU0_R_CLK")
	)
	(segment
		(start 377.453906 -306.559712)
		(end 376.891296 -306.559712)
		(width 0.10668)
		(layer "F.Cu")
		(net "SPI_CPU0_R_CLK")
	)
	(segment
		(start 377.537218 -307.496464)
		(end 377.537218 -307.61432)
		(width 0.10668)
		(layer "F.Cu")
		(net "SPI_CPU0_R_CLK")
	)
	(segment
		(start 377.453906 -309.120032)
		(end 377.537218 -309.203344)
		(width 0.10668)
		(layer "F.Cu")
		(net "SPI_CPU0_R_CLK")
	)
	(segment
		(start 376.891296 -308.551072)
		(end 377.453906 -308.551072)
		(width 0.10668)
		(layer "F.Cu")
		(net "SPI_CPU0_R_CLK")
	)
	(segment
		(start 376.891296 -310.257952)
		(end 377.453906 -310.257952)
		(width 0.10668)
		(layer "F.Cu")
		(net "SPI_CPU0_R_CLK")
	)
	(segment
		(start 377.453906 -311.111392)
		(end 376.891296 -311.111392)
		(width 0.10668)
		(layer "F.Cu")
		(net "SPI_CPU0_R_CLK")
	)
	(segment
		(start 376.807984 -307.211984)
		(end 376.807984 -307.32984)
		(width 0.10668)
		(layer "F.Cu")
		(net "SPI_CPU0_R_CLK")
	)
	(segment
		(start 376.807984 -311.763664)
		(end 376.807984 -312.568082)
		(width 0.10668)
		(layer "F.Cu")
		(net "SPI_CPU0_R_CLK")
	)
	(segment
		(start 377.537218 -307.04536)
		(end 377.453906 -307.128672)
		(width 0.10668)
		(layer "F.Cu")
		(net "SPI_CPU0_R_CLK")
	)
	(segment
		(start 377.453906 -309.688992)
		(end 377.537218 -309.772304)
		(width 0.10668)
		(layer "F.Cu")
		(net "SPI_CPU0_R_CLK")
	)
	(segment
		(start 377.537218 -308.75224)
		(end 377.453906 -308.835552)
		(width 0.10668)
		(layer "F.Cu")
		(net "SPI_CPU0_R_CLK")
	)
	(segment
		(start 377.453906 -308.835552)
		(end 376.891296 -308.835552)
		(width 0.10668)
		(layer "F.Cu")
		(net "SPI_CPU0_R_CLK")
	)
	(segment
		(start 376.891296 -311.395872)
		(end 377.453906 -311.395872)
		(width 0.10668)
		(layer "F.Cu")
		(net "SPI_CPU0_R_CLK")
	)
	(segment
		(start 377.537218 -306.927504)
		(end 377.537218 -307.04536)
		(width 0.10668)
		(layer "F.Cu")
		(net "SPI_CPU0_R_CLK")
	)
	(segment
		(start 376.891296 -310.826912)
		(end 377.453906 -310.826912)
		(width 0.10668)
		(layer "F.Cu")
		(net "SPI_CPU0_R_CLK")
	)
	(segment
		(start 377.537218 -306.358544)
		(end 377.537218 -306.4764)
		(width 0.10668)
		(layer "F.Cu")
		(net "SPI_CPU0_R_CLK")
	)
	(segment
		(start 376.891296 -307.697632)
		(end 376.807984 -307.780944)
		(width 0.10668)
		(layer "F.Cu")
		(net "SPI_CPU0_R_CLK")
	)
	(segment
		(start 376.807984 -310.056784)
		(end 376.807984 -310.17464)
		(width 0.10668)
		(layer "F.Cu")
		(net "SPI_CPU0_R_CLK")
	)
	(segment
		(start 377.537218 -310.45912)
		(end 377.453906 -310.542432)
		(width 0.10668)
		(layer "F.Cu")
		(net "SPI_CPU0_R_CLK")
	)
	(segment
		(start 377.453906 -308.266592)
		(end 376.891296 -308.266592)
		(width 0.10668)
		(layer "F.Cu")
		(net "SPI_CPU0_R_CLK")
	)
	(segment
		(start 376.891296 -307.982112)
		(end 377.453906 -307.982112)
		(width 0.10668)
		(layer "F.Cu")
		(net "SPI_CPU0_R_CLK")
	)
	(segment
		(start 376.891296 -308.266592)
		(end 376.807984 -308.349904)
		(width 0.10668)
		(layer "F.Cu")
		(net "SPI_CPU0_R_CLK")
	)
	(segment
		(start 376.807984 -312.568082)
		(end 385.281678 -321.041776)
		(width 0.10668)
		(layer "F.Cu")
		(net "SPI_CPU0_R_CLK")
	)
	(segment
		(start 376.807984 -310.7436)
		(end 376.891296 -310.826912)
		(width 0.10668)
		(layer "F.Cu")
		(net "SPI_CPU0_R_CLK")
	)
	(segment
		(start 376.807984 -309.487824)
		(end 376.807984 -309.60568)
		(width 0.10668)
		(layer "F.Cu")
		(net "SPI_CPU0_R_CLK")
	)
	(segment
		(start 377.537218 -311.02808)
		(end 377.453906 -311.111392)
		(width 0.10668)
		(layer "F.Cu")
		(net "SPI_CPU0_R_CLK")
	)
	(segment
		(start 377.453906 -310.826912)
		(end 377.537218 -310.910224)
		(width 0.10668)
		(layer "F.Cu")
		(net "SPI_CPU0_R_CLK")
	)
	(segment
		(start 377.537218 -308.634384)
		(end 377.537218 -308.75224)
		(width 0.10668)
		(layer "F.Cu")
		(net "SPI_CPU0_R_CLK")
	)
	(segment
		(start 377.537218 -311.479184)
		(end 377.537218 -311.59704)
		(width 0.10668)
		(layer "F.Cu")
		(net "SPI_CPU0_R_CLK")
	)
	(segment
		(start 388.37743 -325.152512)
		(end 388.37743 -325.792084)
		(width 0.10668)
		(layer "F.Cu")
		(net "SPI_CPU0_R_CLK")
	)
	(segment
		(start 376.807984 -311.31256)
		(end 376.891296 -311.395872)
		(width 0.10668)
		(layer "F.Cu")
		(net "SPI_CPU0_R_CLK")
	)
	(segment
		(start 385.281678 -322.10121)
		(end 386.547868 -323.3674)
		(width 0.10668)
		(layer "F.Cu")
		(net "SPI_CPU0_R_CLK")
	)
	(segment
		(start 398.634712 -326.843898)
		(end 399.019014 -326.459596)
		(width 0.10668)
		(layer "F.Cu")
		(net "SPI_CPU0_R_CLK")
	)
	(segment
		(start 386.592318 -323.3674)
		(end 388.37743 -325.152512)
		(width 0.10668)
		(layer "F.Cu")
		(net "SPI_CPU0_R_CLK")
	)
	(segment
		(start 376.891296 -306.844192)
		(end 377.453906 -306.844192)
		(width 0.10668)
		(layer "F.Cu")
		(net "SPI_CPU0_R_CLK")
	)
	(segment
		(start 397.475202 -327.250298)
		(end 397.881602 -326.843898)
		(width 0.10668)
		(layer "F.Cu")
		(net "SPI_CPU0_R_CLK")
	)
	(segment
		(start 377.453906 -306.275232)
		(end 377.537218 -306.358544)
		(width 0.10668)
		(layer "F.Cu")
		(net "SPI_CPU0_R_CLK")
	)
	(segment
		(start 399.674334 -324.862952)
		(end 401.853908 -324.862952)
		(width 0.10668)
		(layer "F.Cu")
		(net "SPI_CPU0_R_CLK")
	)
	(segment
		(start 377.453906 -307.697632)
		(end 376.891296 -307.697632)
		(width 0.10668)
		(layer "F.Cu")
		(net "SPI_CPU0_R_CLK")
	)
	(segment
		(start 376.807984 -308.46776)
		(end 376.891296 -308.551072)
		(width 0.10668)
		(layer "F.Cu")
		(net "SPI_CPU0_R_CLK")
	)
	(segment
		(start 377.453906 -310.257952)
		(end 377.537218 -310.341264)
		(width 0.10668)
		(layer "F.Cu")
		(net "SPI_CPU0_R_CLK")
	)
	(segment
		(start 385.281678 -321.041776)
		(end 385.281678 -322.10121)
		(width 0.10668)
		(layer "F.Cu")
		(net "SPI_CPU0_R_CLK")
	)
	(segment
		(start 377.537218 -311.59704)
		(end 377.453906 -311.680352)
		(width 0.10668)
		(layer "F.Cu")
		(net "SPI_CPU0_R_CLK")
	)
	(segment
		(start 377.537218 -309.3212)
		(end 377.453906 -309.404512)
		(width 0.10668)
		(layer "F.Cu")
		(net "SPI_CPU0_R_CLK")
	)
	(segment
		(start 376.891296 -309.973472)
		(end 376.807984 -310.056784)
		(width 0.10668)
		(layer "F.Cu")
		(net "SPI_CPU0_R_CLK")
	)
	(segment
		(start 397.881602 -326.843898)
		(end 398.634712 -326.843898)
		(width 0.10668)
		(layer "F.Cu")
		(net "SPI_CPU0_R_CLK")
	)
	(segment
		(start 377.537218 -306.4764)
		(end 377.453906 -306.559712)
		(width 0.10668)
		(layer "F.Cu")
		(net "SPI_CPU0_R_CLK")
	)
	(segment
		(start 376.807984 -309.60568)
		(end 376.891296 -309.688992)
		(width 0.10668)
		(layer "F.Cu")
		(net "SPI_CPU0_R_CLK")
	)
	(segment
		(start 377.453906 -311.395872)
		(end 377.537218 -311.479184)
		(width 0.10668)
		(layer "F.Cu")
		(net "SPI_CPU0_R_CLK")
	)
	(segment
		(start 376.807984 -307.780944)
		(end 376.807984 -307.8988)
		(width 0.10668)
		(layer "F.Cu")
		(net "SPI_CPU0_R_CLK")
	)
	(segment
		(start 396.744952 -329.012804)
		(end 397.475202 -327.250298)
		(width 0.10668)
		(layer "F.Cu")
		(net "SPI_CPU0_R_CLK")
	)
	(segment
		(start 376.891296 -311.111392)
		(end 376.807984 -311.194704)
		(width 0.10668)
		(layer "F.Cu")
		(net "SPI_CPU0_R_CLK")
	)
	(segment
		(start 376.891296 -307.128672)
		(end 376.807984 -307.211984)
		(width 0.10668)
		(layer "F.Cu")
		(net "SPI_CPU0_R_CLK")
	)
	(segment
		(start 377.537218 -307.61432)
		(end 377.453906 -307.697632)
		(width 0.10668)
		(layer "F.Cu")
		(net "SPI_CPU0_R_CLK")
	)
	(segment
		(start 376.807984 -306.19192)
		(end 376.891296 -306.275232)
		(width 0.10668)
		(layer "F.Cu")
		(net "SPI_CPU0_R_CLK")
	)
	(segment
		(start 377.453906 -309.973472)
		(end 376.891296 -309.973472)
		(width 0.10668)
		(layer "F.Cu")
		(net "SPI_CPU0_R_CLK")
	)
	(segment
		(start 376.891296 -310.542432)
		(end 376.807984 -310.625744)
		(width 0.10668)
		(layer "F.Cu")
		(net "SPI_CPU0_R_CLK")
	)
	(segment
		(start 377.537218 -308.18328)
		(end 377.453906 -308.266592)
		(width 0.10668)
		(layer "F.Cu")
		(net "SPI_CPU0_R_CLK")
	)
	(segment
		(start 376.891296 -306.559712)
		(end 376.807984 -306.643024)
		(width 0.10668)
		(layer "F.Cu")
		(net "SPI_CPU0_R_CLK")
	)
	(segment
		(start 377.453906 -307.128672)
		(end 376.891296 -307.128672)
		(width 0.10668)
		(layer "F.Cu")
		(net "SPI_CPU0_R_CLK")
	)
	(segment
		(start 377.537218 -308.065424)
		(end 377.537218 -308.18328)
		(width 0.10668)
		(layer "F.Cu")
		(net "SPI_CPU0_R_CLK")
	)
	(segment
		(start 376.807984 -309.03672)
		(end 376.891296 -309.120032)
		(width 0.10668)
		(layer "F.Cu")
		(net "SPI_CPU0_R_CLK")
	)
	(segment
		(start 377.537218 -309.772304)
		(end 377.537218 -309.89016)
		(width 0.10668)
		(layer "F.Cu")
		(net "SPI_CPU0_R_CLK")
	)
	(segment
		(start 377.537218 -310.341264)
		(end 377.537218 -310.45912)
		(width 0.10668)
		(layer "F.Cu")
		(net "SPI_CPU0_R_CLK")
	)
	(segment
		(start 377.453906 -310.542432)
		(end 376.891296 -310.542432)
		(width 0.10668)
		(layer "F.Cu")
		(net "SPI_CPU0_R_CLK")
	)
	(segment
		(start 376.807984 -308.918864)
		(end 376.807984 -309.03672)
		(width 0.10668)
		(layer "F.Cu")
		(net "SPI_CPU0_R_CLK")
	)
	(segment
		(start 377.537218 -309.89016)
		(end 377.453906 -309.973472)
		(width 0.10668)
		(layer "F.Cu")
		(net "SPI_CPU0_R_CLK")
	)
	(segment
		(start 376.807984 -311.194704)
		(end 376.807984 -311.31256)
		(width 0.10668)
		(layer "F.Cu")
		(net "SPI_CPU0_R_CLK")
	)
	(segment
		(start 386.547868 -323.3674)
		(end 386.592318 -323.3674)
		(width 0.10668)
		(layer "F.Cu")
		(net "SPI_CPU0_R_CLK")
	)
	(segment
		(start 392.28649 -329.701144)
		(end 396.056612 -329.701144)
		(width 0.10668)
		(layer "F.Cu")
		(net "SPI_CPU0_R_CLK")
	)
	(segment
		(start 376.891296 -309.120032)
		(end 377.453906 -309.120032)
		(width 0.10668)
		(layer "F.Cu")
		(net "SPI_CPU0_R_CLK")
	)
	(segment
		(start 377.453906 -308.551072)
		(end 377.537218 -308.634384)
		(width 0.10668)
		(layer "F.Cu")
		(net "SPI_CPU0_R_CLK")
	)
	(segment
		(start 377.537218 -310.910224)
		(end 377.537218 -311.02808)
		(width 0.10668)
		(layer "F.Cu")
		(net "SPI_CPU0_R_CLK")
	)
	(segment
		(start 376.891296 -309.404512)
		(end 376.807984 -309.487824)
		(width 0.10668)
		(layer "F.Cu")
		(net "SPI_CPU0_R_CLK")
	)
	(segment
		(start 376.807984 -308.349904)
		(end 376.807984 -308.46776)
		(width 0.10668)
		(layer "F.Cu")
		(net "SPI_CPU0_R_CLK")
	)
	(segment
		(start 376.807984 -307.8988)
		(end 376.891296 -307.982112)
		(width 0.10668)
		(layer "F.Cu")
		(net "SPI_CPU0_R_CLK")
	)
	(segment
		(start 399.019014 -326.459596)
		(end 399.019014 -325.518272)
		(width 0.10668)
		(layer "F.Cu")
		(net "SPI_CPU0_R_CLK")
	)
	(segment
		(start 376.891296 -308.835552)
		(end 376.807984 -308.918864)
		(width 0.10668)
		(layer "F.Cu")
		(net "SPI_CPU0_R_CLK")
	)
	(segment
		(start 376.891296 -306.275232)
		(end 377.453906 -306.275232)
		(width 0.10668)
		(layer "F.Cu")
		(net "SPI_CPU0_R_CLK")
	)
	(segment
		(start 377.453906 -307.413152)
		(end 377.537218 -307.496464)
		(width 0.10668)
		(layer "F.Cu")
		(net "SPI_CPU0_R_CLK")
	)
	(segment
		(start 376.891296 -311.680352)
		(end 376.807984 -311.763664)
		(width 0.10668)
		(layer "F.Cu")
		(net "SPI_CPU0_R_CLK")
	)
	(segment
		(start 396.056612 -329.701144)
		(end 396.744952 -329.012804)
		(width 0.10668)
		(layer "F.Cu")
		(net "SPI_CPU0_R_CLK")
	)
	(segment
		(start 376.807984 -307.32984)
		(end 376.891296 -307.413152)
		(width 0.10668)
		(layer "F.Cu")
		(net "SPI_CPU0_R_CLK")
	)
	(segment
		(start 388.37743 -325.792084)
		(end 392.28649 -329.701144)
		(width 0.10668)
		(layer "F.Cu")
		(net "SPI_CPU0_R_CLK")
	)
	(segment
		(start 377.453906 -311.680352)
		(end 376.891296 -311.680352)
		(width 0.10668)
		(layer "F.Cu")
		(net "SPI_CPU0_R_CLK")
	)
	(segment
		(start 399.019014 -325.518272)
		(end 399.674334 -324.862952)
		(width 0.10668)
		(layer "F.Cu")
		(net "SPI_CPU0_R_CLK")
	)
	(segment
		(start 377.453906 -309.404512)
		(end 376.891296 -309.404512)
		(width 0.10668)
		(layer "F.Cu")
		(net "SPI_CPU0_R_CLK")
	)
	(segment
		(start 377.537218 -309.203344)
		(end 377.537218 -309.3212)
		(width 0.10668)
		(layer "F.Cu")
		(net "SPI_CPU0_R_CLK")
	)
	(segment
		(start 376.807984 -310.625744)
		(end 376.807984 -310.7436)
		(width 0.10668)
		(layer "F.Cu")
		(net "SPI_CPU0_R_CLK")
	)
	(segment
		(start 376.891296 -307.413152)
		(end 377.453906 -307.413152)
		(width 0.10668)
		(layer "F.Cu")
		(net "SPI_CPU0_R_CLK")
	)
	(segment
		(start 369.888008 -295.690036)
		(end 369.888008 -297.688762)
		(width 0.10668)
		(layer "F.Cu")
		(net "SPI_CPU0_R_CLK")
	)
	(segment
		(start 377.453906 -306.844192)
		(end 377.537218 -306.927504)
		(width 0.10668)
		(layer "F.Cu")
		(net "SPI_CPU0_R_CLK")
	)
	(segment
		(start 376.807984 -310.17464)
		(end 376.891296 -310.257952)
		(width 0.10668)
		(layer "F.Cu")
		(net "SPI_CPU0_R_CLK")
	)
	(segment
		(start 376.891296 -309.688992)
		(end 377.453906 -309.688992)
		(width 0.10668)
		(layer "F.Cu")
		(net "SPI_CPU0_R_CLK")
	)
	(segment
		(start 377.453906 -307.982112)
		(end 377.537218 -308.065424)
		(width 0.10668)
		(layer "F.Cu")
		(net "SPI_CPU0_R_CLK")
	)
	(segment
		(start 376.807984 -306.643024)
		(end 376.807984 -306.76088)
		(width 0.10668)
		(layer "F.Cu")
		(net "SPI_CPU0_R_CLK")
	)
	(segment
		(start 376.807984 -304.608738)
		(end 376.807984 -306.19192)
		(width 0.10668)
		(layer "F.Cu")
		(net "SPI_CPU0_R_CLK")
	)
	(segment
		(start 369.888008 -297.688762)
		(end 376.807984 -304.608738)
		(width 0.10668)
		(layer "F.Cu")
		(net "SPI_CPU0_R_CLK")
	)
	(via
		(at 388.37743 -325.152512)
		(size 0.762)
		(drill 0.381)
		(layers "F.Cu" "B.Cu")
		(net "SPI_CPU0_R_CLK")
	)
	(segment
		(start 184.461912 -16.549878)
		(end 184.461912 -17.596612)
		(width 0.10668)
		(layer "F.Cu")
		(net "SPI_CPU0_LVC3_TPM_CS_N")
	)
	(segment
		(start 252.490224 -134.892796)
		(end 251.874274 -134.892796)
		(width 0.10668)
		(layer "F.Cu")
		(net "SPI_CPU0_LVC3_TPM_CS_N")
	)
	(segment
		(start 184.461912 -17.596612)
		(end 184.345326 -17.713198)
		(width 0.10668)
		(layer "F.Cu")
		(net "SPI_CPU0_LVC3_TPM_CS_N")
	)
	(segment
		(start 253.106174 -134.892796)
		(end 252.490224 -134.892796)
		(width 0.10668)
		(layer "F.Cu")
		(net "SPI_CPU0_LVC3_TPM_CS_N")
	)
	(via
		(at 252.490224 -134.892796)
		(size 0.508)
		(drill 0.254)
		(layers "F.Cu" "B.Cu")
		(net "SPI_CPU0_LVC3_TPM_CS_N")
	)
	(via
		(at 184.345326 -17.713198)
		(size 0.508)
		(drill 0.254)
		(layers "F.Cu" "B.Cu")
		(net "SPI_CPU0_LVC3_TPM_CS_N")
	)
	(segment
		(start 169.138854 -26.355294)
		(end 169.138854 -29.942028)
		(width 0.10668)
		(layer "B.Cu")
		(net "SPI_CPU0_LVC3_TPM_CS_N")
	)
	(segment
		(start 251.262134 -133.345682)
		(end 251.262134 -134.488682)
		(width 0.10668)
		(layer "B.Cu")
		(net "SPI_CPU0_LVC3_TPM_CS_N")
	)
	(segment
		(start 169.9514 -21.834856)
		(end 169.9514 -25.542748)
		(width 0.10668)
		(layer "B.Cu")
		(net "SPI_CPU0_LVC3_TPM_CS_N")
	)
	(segment
		(start 175.276256 -16.99514)
		(end 173.86554 -16.41094)
		(width 0.10668)
		(layer "B.Cu")
		(net "SPI_CPU0_LVC3_TPM_CS_N")
	)
	(segment
		(start 249.658124 -133.035548)
		(end 250.952 -133.035548)
		(width 0.10668)
		(layer "B.Cu")
		(net "SPI_CPU0_LVC3_TPM_CS_N")
	)
	(segment
		(start 171.357544 -20.428712)
		(end 169.9514 -21.834856)
		(width 0.10668)
		(layer "B.Cu")
		(net "SPI_CPU0_LVC3_TPM_CS_N")
	)
	(segment
		(start 251.666248 -134.892796)
		(end 252.490224 -134.892796)
		(width 0.10668)
		(layer "B.Cu")
		(net "SPI_CPU0_LVC3_TPM_CS_N")
	)
	(segment
		(start 169.138854 -29.942028)
		(end 175.577754 -36.380928)
		(width 0.10668)
		(layer "B.Cu")
		(net "SPI_CPU0_LVC3_TPM_CS_N")
	)
	(segment
		(start 220.789754 -61.695838)
		(end 228.236018 -69.142102)
		(width 0.10668)
		(layer "B.Cu")
		(net "SPI_CPU0_LVC3_TPM_CS_N")
	)
	(segment
		(start 184.345326 -17.713198)
		(end 184.345326 -17.587722)
		(width 0.10668)
		(layer "B.Cu")
		(net "SPI_CPU0_LVC3_TPM_CS_N")
	)
	(segment
		(start 227.159566 -87.899494)
		(end 243.166392 -126.543816)
		(width 0.10668)
		(layer "B.Cu")
		(net "SPI_CPU0_LVC3_TPM_CS_N")
	)
	(segment
		(start 250.952 -133.035548)
		(end 251.262134 -133.345682)
		(width 0.10668)
		(layer "B.Cu")
		(net "SPI_CPU0_LVC3_TPM_CS_N")
	)
	(segment
		(start 227.159566 -77.79131)
		(end 227.159566 -87.899494)
		(width 0.10668)
		(layer "B.Cu")
		(net "SPI_CPU0_LVC3_TPM_CS_N")
	)
	(segment
		(start 251.262134 -134.488682)
		(end 251.666248 -134.892796)
		(width 0.10668)
		(layer "B.Cu")
		(net "SPI_CPU0_LVC3_TPM_CS_N")
	)
	(segment
		(start 202.662536 -59.152536)
		(end 215.447118 -61.695838)
		(width 0.10668)
		(layer "B.Cu")
		(net "SPI_CPU0_LVC3_TPM_CS_N")
	)
	(segment
		(start 169.9514 -25.542748)
		(end 169.138854 -26.355294)
		(width 0.10668)
		(layer "B.Cu")
		(net "SPI_CPU0_LVC3_TPM_CS_N")
	)
	(segment
		(start 180.412644 -16.636746)
		(end 180.05425 -16.99514)
		(width 0.10668)
		(layer "B.Cu")
		(net "SPI_CPU0_LVC3_TPM_CS_N")
	)
	(segment
		(start 215.447118 -61.695838)
		(end 220.789754 -61.695838)
		(width 0.10668)
		(layer "B.Cu")
		(net "SPI_CPU0_LVC3_TPM_CS_N")
	)
	(segment
		(start 228.236018 -69.142102)
		(end 228.236018 -76.714858)
		(width 0.10668)
		(layer "B.Cu")
		(net "SPI_CPU0_LVC3_TPM_CS_N")
	)
	(segment
		(start 171.88942 -16.72082)
		(end 171.88942 -18.57756)
		(width 0.10668)
		(layer "B.Cu")
		(net "SPI_CPU0_LVC3_TPM_CS_N")
	)
	(segment
		(start 243.166392 -126.543816)
		(end 249.658124 -133.035548)
		(width 0.10668)
		(layer "B.Cu")
		(net "SPI_CPU0_LVC3_TPM_CS_N")
	)
	(segment
		(start 185.21172 -44.002706)
		(end 198.734934 -57.52592)
		(width 0.10668)
		(layer "B.Cu")
		(net "SPI_CPU0_LVC3_TPM_CS_N")
	)
	(segment
		(start 185.21172 -42.718482)
		(end 185.21172 -44.002706)
		(width 0.10668)
		(layer "B.Cu")
		(net "SPI_CPU0_LVC3_TPM_CS_N")
	)
	(segment
		(start 172.085 -19.185636)
		(end 171.833794 -19.436842)
		(width 0.10668)
		(layer "B.Cu")
		(net "SPI_CPU0_LVC3_TPM_CS_N")
	)
	(segment
		(start 171.88942 -18.57756)
		(end 172.085 -18.77314)
		(width 0.10668)
		(layer "B.Cu")
		(net "SPI_CPU0_LVC3_TPM_CS_N")
	)
	(segment
		(start 228.236018 -76.714858)
		(end 227.159566 -77.79131)
		(width 0.10668)
		(layer "B.Cu")
		(net "SPI_CPU0_LVC3_TPM_CS_N")
	)
	(segment
		(start 172.085 -18.77314)
		(end 172.085 -19.185636)
		(width 0.10668)
		(layer "B.Cu")
		(net "SPI_CPU0_LVC3_TPM_CS_N")
	)
	(segment
		(start 171.833794 -20.078954)
		(end 171.484036 -20.428712)
		(width 0.10668)
		(layer "B.Cu")
		(net "SPI_CPU0_LVC3_TPM_CS_N")
	)
	(segment
		(start 183.39435 -16.636746)
		(end 180.412644 -16.636746)
		(width 0.10668)
		(layer "B.Cu")
		(net "SPI_CPU0_LVC3_TPM_CS_N")
	)
	(segment
		(start 198.734934 -57.52592)
		(end 202.662536 -59.152536)
		(width 0.10668)
		(layer "B.Cu")
		(net "SPI_CPU0_LVC3_TPM_CS_N")
	)
	(segment
		(start 178.874166 -36.380928)
		(end 185.21172 -42.718482)
		(width 0.10668)
		(layer "B.Cu")
		(net "SPI_CPU0_LVC3_TPM_CS_N")
	)
	(segment
		(start 180.05425 -16.99514)
		(end 175.276256 -16.99514)
		(width 0.10668)
		(layer "B.Cu")
		(net "SPI_CPU0_LVC3_TPM_CS_N")
	)
	(segment
		(start 184.345326 -17.587722)
		(end 183.39435 -16.636746)
		(width 0.10668)
		(layer "B.Cu")
		(net "SPI_CPU0_LVC3_TPM_CS_N")
	)
	(segment
		(start 173.86554 -16.41094)
		(end 172.1993 -16.41094)
		(width 0.10668)
		(layer "B.Cu")
		(net "SPI_CPU0_LVC3_TPM_CS_N")
	)
	(segment
		(start 171.833794 -19.436842)
		(end 171.833794 -20.078954)
		(width 0.10668)
		(layer "B.Cu")
		(net "SPI_CPU0_LVC3_TPM_CS_N")
	)
	(segment
		(start 171.484036 -20.428712)
		(end 171.357544 -20.428712)
		(width 0.10668)
		(layer "B.Cu")
		(net "SPI_CPU0_LVC3_TPM_CS_N")
	)
	(segment
		(start 172.1993 -16.41094)
		(end 171.88942 -16.72082)
		(width 0.10668)
		(layer "B.Cu")
		(net "SPI_CPU0_LVC3_TPM_CS_N")
	)
	(segment
		(start 175.577754 -36.380928)
		(end 178.874166 -36.380928)
		(width 0.10668)
		(layer "B.Cu")
		(net "SPI_CPU0_LVC3_TPM_CS_N")
	)
	(segment
		(start 169.867072 -16.549878)
		(end 169.867072 -17.820386)
		(width 0.10668)
		(layer "F.Cu")
		(net "SPI_CPU0_LVC3_SCM_D3")
	)
	(segment
		(start 168.841166 -19.322542)
		(end 168.841166 -21.181314)
		(width 0.10668)
		(layer "F.Cu")
		(net "SPI_CPU0_LVC3_SCM_D3")
	)
	(segment
		(start 256.441194 -138.448796)
		(end 255.780794 -138.448796)
		(width 0.10668)
		(layer "F.Cu")
		(net "SPI_CPU0_LVC3_SCM_D3")
	)
	(segment
		(start 169.17797 -18.509488)
		(end 168.841166 -19.322542)
		(width 0.10668)
		(layer "F.Cu")
		(net "SPI_CPU0_LVC3_SCM_D3")
	)
	(segment
		(start 257.101594 -138.448796)
		(end 256.441194 -138.448796)
		(width 0.10668)
		(layer "F.Cu")
		(net "SPI_CPU0_LVC3_SCM_D3")
	)
	(segment
		(start 169.867072 -17.820386)
		(end 169.17797 -18.509488)
		(width 0.10668)
		(layer "F.Cu")
		(net "SPI_CPU0_LVC3_SCM_D3")
	)
	(segment
		(start 168.841166 -21.181314)
		(end 169.2148 -21.554948)
		(width 0.10668)
		(layer "F.Cu")
		(net "SPI_CPU0_LVC3_SCM_D3")
	)
	(via
		(at 256.441194 -138.448796)
		(size 0.508)
		(drill 0.254)
		(layers "F.Cu" "B.Cu")
		(net "SPI_CPU0_LVC3_SCM_D3")
	)
	(via
		(at 169.2148 -21.554948)
		(size 0.508)
		(drill 0.254)
		(layers "F.Cu" "B.Cu")
		(net "SPI_CPU0_LVC3_SCM_D3")
	)
	(segment
		(start 168.478454 -26.279094)
		(end 168.478454 -30.183328)
		(width 0.10668)
		(layer "B.Cu")
		(net "SPI_CPU0_LVC3_SCM_D3")
	)
	(segment
		(start 198.439786 -57.961784)
		(end 202.831192 -59.780678)
		(width 0.10668)
		(layer "B.Cu")
		(net "SPI_CPU0_LVC3_SCM_D3")
	)
	(segment
		(start 242.901978 -127.181102)
		(end 249.936 -134.215124)
		(width 0.10668)
		(layer "B.Cu")
		(net "SPI_CPU0_LVC3_SCM_D3")
	)
	(segment
		(start 184.72404 -44.246038)
		(end 198.439786 -57.961784)
		(width 0.10668)
		(layer "B.Cu")
		(net "SPI_CPU0_LVC3_SCM_D3")
	)
	(segment
		(start 169.2148 -25.542748)
		(end 168.478454 -26.279094)
		(width 0.10668)
		(layer "B.Cu")
		(net "SPI_CPU0_LVC3_SCM_D3")
	)
	(segment
		(start 184.72404 -42.92092)
		(end 184.72404 -44.246038)
		(width 0.10668)
		(layer "B.Cu")
		(net "SPI_CPU0_LVC3_SCM_D3")
	)
	(segment
		(start 168.478454 -30.183328)
		(end 175.361854 -37.066728)
		(width 0.10668)
		(layer "B.Cu")
		(net "SPI_CPU0_LVC3_SCM_D3")
	)
	(segment
		(start 249.936 -134.215124)
		(end 249.936 -135.194548)
		(width 0.10668)
		(layer "B.Cu")
		(net "SPI_CPU0_LVC3_SCM_D3")
	)
	(segment
		(start 226.671886 -87.998046)
		(end 242.901978 -127.181102)
		(width 0.10668)
		(layer "B.Cu")
		(net "SPI_CPU0_LVC3_SCM_D3")
	)
	(segment
		(start 175.361854 -37.066728)
		(end 178.869848 -37.066728)
		(width 0.10668)
		(layer "B.Cu")
		(net "SPI_CPU0_LVC3_SCM_D3")
	)
	(segment
		(start 215.392 -62.279276)
		(end 220.683328 -62.279276)
		(width 0.10668)
		(layer "B.Cu")
		(net "SPI_CPU0_LVC3_SCM_D3")
	)
	(segment
		(start 178.869848 -37.066728)
		(end 184.72404 -42.92092)
		(width 0.10668)
		(layer "B.Cu")
		(net "SPI_CPU0_LVC3_SCM_D3")
	)
	(segment
		(start 227.748338 -76.512674)
		(end 226.671886 -77.589126)
		(width 0.10668)
		(layer "B.Cu")
		(net "SPI_CPU0_LVC3_SCM_D3")
	)
	(segment
		(start 220.683328 -62.279276)
		(end 227.748338 -69.344286)
		(width 0.10668)
		(layer "B.Cu")
		(net "SPI_CPU0_LVC3_SCM_D3")
	)
	(segment
		(start 226.671886 -77.589126)
		(end 226.671886 -87.998046)
		(width 0.10668)
		(layer "B.Cu")
		(net "SPI_CPU0_LVC3_SCM_D3")
	)
	(segment
		(start 227.748338 -69.344286)
		(end 227.748338 -76.512674)
		(width 0.10668)
		(layer "B.Cu")
		(net "SPI_CPU0_LVC3_SCM_D3")
	)
	(segment
		(start 202.831192 -59.780678)
		(end 215.392 -62.279276)
		(width 0.10668)
		(layer "B.Cu")
		(net "SPI_CPU0_LVC3_SCM_D3")
	)
	(segment
		(start 253.190248 -138.448796)
		(end 256.441194 -138.448796)
		(width 0.10668)
		(layer "B.Cu")
		(net "SPI_CPU0_LVC3_SCM_D3")
	)
	(segment
		(start 249.936 -135.194548)
		(end 253.190248 -138.448796)
		(width 0.10668)
		(layer "B.Cu")
		(net "SPI_CPU0_LVC3_SCM_D3")
	)
	(segment
		(start 169.2148 -21.554948)
		(end 169.2148 -25.542748)
		(width 0.10668)
		(layer "B.Cu")
		(net "SPI_CPU0_LVC3_SCM_D3")
	)
	(segment
		(start 170.46702 -17.94637)
		(end 169.657014 -18.756376)
		(width 0.10668)
		(layer "F.Cu")
		(net "SPI_CPU0_LVC3_SCM_D2")
	)
	(segment
		(start 257.101594 -139.718796)
		(end 256.441194 -139.718796)
		(width 0.10668)
		(layer "F.Cu")
		(net "SPI_CPU0_LVC3_SCM_D2")
	)
	(segment
		(start 169.657014 -18.756376)
		(end 169.657014 -20.356068)
		(width 0.10668)
		(layer "F.Cu")
		(net "SPI_CPU0_LVC3_SCM_D2")
	)
	(segment
		(start 256.441194 -139.718796)
		(end 255.780794 -139.718796)
		(width 0.10668)
		(layer "F.Cu")
		(net "SPI_CPU0_LVC3_SCM_D2")
	)
	(segment
		(start 170.46702 -16.549878)
		(end 170.46702 -17.94637)
		(width 0.10668)
		(layer "F.Cu")
		(net "SPI_CPU0_LVC3_SCM_D2")
	)
	(via
		(at 169.657014 -20.356068)
		(size 0.508)
		(drill 0.254)
		(layers "F.Cu" "B.Cu")
		(net "SPI_CPU0_LVC3_SCM_D2")
	)
	(via
		(at 256.441194 -139.718796)
		(size 0.508)
		(drill 0.254)
		(layers "F.Cu" "B.Cu")
		(net "SPI_CPU0_LVC3_SCM_D2")
	)
	(segment
		(start 242.51158 -127.51308)
		(end 226.184206 -88.095328)
		(width 0.10668)
		(layer "B.Cu")
		(net "SPI_CPU0_LVC3_SCM_D2")
	)
	(segment
		(start 253.596648 -139.718796)
		(end 249.0978 -135.219948)
		(width 0.10668)
		(layer "B.Cu")
		(net "SPI_CPU0_LVC3_SCM_D2")
	)
	(segment
		(start 168.45026 -25.088088)
		(end 168.45026 -21.125688)
		(width 0.10668)
		(layer "B.Cu")
		(net "SPI_CPU0_LVC3_SCM_D2")
	)
	(segment
		(start 175.274478 -37.701728)
		(end 167.945054 -30.372304)
		(width 0.10668)
		(layer "B.Cu")
		(net "SPI_CPU0_LVC3_SCM_D2")
	)
	(segment
		(start 176.595278 -37.701728)
		(end 175.274478 -37.701728)
		(width 0.10668)
		(layer "B.Cu")
		(net "SPI_CPU0_LVC3_SCM_D2")
	)
	(segment
		(start 184.23636 -43.123358)
		(end 180.384196 -39.271194)
		(width 0.10668)
		(layer "B.Cu")
		(net "SPI_CPU0_LVC3_SCM_D2")
	)
	(segment
		(start 226.184206 -88.095328)
		(end 226.184206 -77.386942)
		(width 0.10668)
		(layer "B.Cu")
		(net "SPI_CPU0_LVC3_SCM_D2")
	)
	(segment
		(start 167.945054 -25.593294)
		(end 168.45026 -25.088088)
		(width 0.10668)
		(layer "B.Cu")
		(net "SPI_CPU0_LVC3_SCM_D2")
	)
	(segment
		(start 256.441194 -139.718796)
		(end 253.596648 -139.718796)
		(width 0.10668)
		(layer "B.Cu")
		(net "SPI_CPU0_LVC3_SCM_D2")
	)
	(segment
		(start 184.23636 -44.617894)
		(end 184.23636 -43.123358)
		(width 0.10668)
		(layer "B.Cu")
		(net "SPI_CPU0_LVC3_SCM_D2")
	)
	(segment
		(start 202.875896 -60.404248)
		(end 198.005446 -58.38698)
		(width 0.10668)
		(layer "B.Cu")
		(net "SPI_CPU0_LVC3_SCM_D2")
	)
	(segment
		(start 220.597984 -62.883796)
		(end 215.3412 -62.883796)
		(width 0.10668)
		(layer "B.Cu")
		(net "SPI_CPU0_LVC3_SCM_D2")
	)
	(segment
		(start 198.005446 -58.38698)
		(end 184.23636 -44.617894)
		(width 0.10668)
		(layer "B.Cu")
		(net "SPI_CPU0_LVC3_SCM_D2")
	)
	(segment
		(start 167.945054 -30.372304)
		(end 167.945054 -25.593294)
		(width 0.10668)
		(layer "B.Cu")
		(net "SPI_CPU0_LVC3_SCM_D2")
	)
	(segment
		(start 215.3412 -62.883796)
		(end 202.875896 -60.404248)
		(width 0.10668)
		(layer "B.Cu")
		(net "SPI_CPU0_LVC3_SCM_D2")
	)
	(segment
		(start 169.21988 -20.356068)
		(end 169.657014 -20.356068)
		(width 0.10668)
		(layer "B.Cu")
		(net "SPI_CPU0_LVC3_SCM_D2")
	)
	(segment
		(start 226.184206 -77.386942)
		(end 227.252276 -76.318872)
		(width 0.10668)
		(layer "B.Cu")
		(net "SPI_CPU0_LVC3_SCM_D2")
	)
	(segment
		(start 227.252276 -76.318872)
		(end 227.252276 -69.538088)
		(width 0.10668)
		(layer "B.Cu")
		(net "SPI_CPU0_LVC3_SCM_D2")
	)
	(segment
		(start 180.384196 -39.271194)
		(end 176.595278 -37.701728)
		(width 0.10668)
		(layer "B.Cu")
		(net "SPI_CPU0_LVC3_SCM_D2")
	)
	(segment
		(start 227.252276 -69.538088)
		(end 220.597984 -62.883796)
		(width 0.10668)
		(layer "B.Cu")
		(net "SPI_CPU0_LVC3_SCM_D2")
	)
	(segment
		(start 249.0978 -135.219948)
		(end 249.0978 -134.0993)
		(width 0.10668)
		(layer "B.Cu")
		(net "SPI_CPU0_LVC3_SCM_D2")
	)
	(segment
		(start 249.0978 -134.0993)
		(end 242.51158 -127.51308)
		(width 0.10668)
		(layer "B.Cu")
		(net "SPI_CPU0_LVC3_SCM_D2")
	)
	(segment
		(start 168.45026 -21.125688)
		(end 169.21988 -20.356068)
		(width 0.10668)
		(layer "B.Cu")
		(net "SPI_CPU0_LVC3_SCM_D2")
	)
	(segment
		(start 260.24205 -143.764)
		(end 260.24205 -143.14805)
		(width 0.10668)
		(layer "F.Cu")
		(net "SPI_CPU0_LVC3_SCM_D1")
	)
	(segment
		(start 169.740834 -22.469348)
		(end 167.193722 -22.469348)
		(width 0.10668)
		(layer "F.Cu")
		(net "SPI_CPU0_LVC3_SCM_D1")
	)
	(segment
		(start 171.066968 -16.549878)
		(end 171.066968 -18.072354)
		(width 0.10668)
		(layer "F.Cu")
		(net "SPI_CPU0_LVC3_SCM_D1")
	)
	(segment
		(start 171.066968 -18.072354)
		(end 170.393614 -18.745708)
		(width 0.10668)
		(layer "F.Cu")
		(net "SPI_CPU0_LVC3_SCM_D1")
	)
	(segment
		(start 170.393614 -18.745708)
		(end 170.393614 -21.816568)
		(width 0.10668)
		(layer "F.Cu")
		(net "SPI_CPU0_LVC3_SCM_D1")
	)
	(segment
		(start 170.393614 -21.816568)
		(end 169.740834 -22.469348)
		(width 0.10668)
		(layer "F.Cu")
		(net "SPI_CPU0_LVC3_SCM_D1")
	)
	(segment
		(start 260.340094 -142.368778)
		(end 260.340094 -142.757906)
		(width 0.10668)
		(layer "F.Cu")
		(net "SPI_CPU0_LVC3_SCM_D1")
	)
	(segment
		(start 260.340094 -142.757906)
		(end 260.096 -143.002)
		(width 0.10668)
		(layer "F.Cu")
		(net "SPI_CPU0_LVC3_SCM_D1")
	)
	(segment
		(start 260.24205 -143.14805)
		(end 260.096 -143.002)
		(width 0.10668)
		(layer "F.Cu")
		(net "SPI_CPU0_LVC3_SCM_D1")
	)
	(segment
		(start 167.193722 -22.469348)
		(end 167.189912 -22.465538)
		(width 0.10668)
		(layer "F.Cu")
		(net "SPI_CPU0_LVC3_SCM_D1")
	)
	(via
		(at 167.189912 -22.465538)
		(size 0.508)
		(drill 0.254)
		(layers "F.Cu" "B.Cu")
		(net "SPI_CPU0_LVC3_SCM_D1")
	)
	(via
		(at 260.096 -143.002)
		(size 0.508)
		(drill 0.254)
		(layers "F.Cu" "B.Cu")
		(net "SPI_CPU0_LVC3_SCM_D1")
	)
	(segment
		(start 166.395654 -25.277318)
		(end 167.189912 -24.48306)
		(width 0.10668)
		(layer "B.Cu")
		(net "SPI_CPU0_LVC3_SCM_D1")
	)
	(segment
		(start 195.449444 -58.162444)
		(end 192.909444 -55.622444)
		(width 0.10668)
		(layer "B.Cu")
		(net "SPI_CPU0_LVC3_SCM_D1")
	)
	(segment
		(start 256.072386 -143.632174)
		(end 247.904 -135.463788)
		(width 0.10668)
		(layer "B.Cu")
		(net "SPI_CPU0_LVC3_SCM_D1")
	)
	(segment
		(start 170.253914 -37.523928)
		(end 170.253914 -36.088828)
		(width 0.10668)
		(layer "B.Cu")
		(net "SPI_CPU0_LVC3_SCM_D1")
	)
	(segment
		(start 247.904 -134.349236)
		(end 241.728244 -128.17348)
		(width 0.10668)
		(layer "B.Cu")
		(net "SPI_CPU0_LVC3_SCM_D1")
	)
	(segment
		(start 259.461 -143.002)
		(end 258.669282 -143.793718)
		(width 0.10668)
		(layer "B.Cu")
		(net "SPI_CPU0_LVC3_SCM_D1")
	)
	(segment
		(start 191.589914 -53.647848)
		(end 183.261 -45.318934)
		(width 0.10668)
		(layer "B.Cu")
		(net "SPI_CPU0_LVC3_SCM_D1")
	)
	(segment
		(start 225.196654 -88.261952)
		(end 225.196654 -75.324462)
		(width 0.10668)
		(layer "B.Cu")
		(net "SPI_CPU0_LVC3_SCM_D1")
	)
	(segment
		(start 222.43796 -69.998082)
		(end 222.43796 -66.355214)
		(width 0.10668)
		(layer "B.Cu")
		(net "SPI_CPU0_LVC3_SCM_D1")
	)
	(segment
		(start 202.616054 -61.627258)
		(end 197.403212 -59.468004)
		(width 0.10668)
		(layer "B.Cu")
		(net "SPI_CPU0_LVC3_SCM_D1")
	)
	(segment
		(start 192.909444 -55.622444)
		(end 191.589914 -53.647848)
		(width 0.10668)
		(layer "B.Cu")
		(net "SPI_CPU0_LVC3_SCM_D1")
	)
	(segment
		(start 257.754882 -143.793718)
		(end 257.364738 -143.632174)
		(width 0.10668)
		(layer "B.Cu")
		(net "SPI_CPU0_LVC3_SCM_D1")
	)
	(segment
		(start 167.189912 -24.48306)
		(end 167.189912 -22.465538)
		(width 0.10668)
		(layer "B.Cu")
		(net "SPI_CPU0_LVC3_SCM_D1")
	)
	(segment
		(start 222.43796 -66.355214)
		(end 220.112336 -64.02959)
		(width 0.10668)
		(layer "B.Cu")
		(net "SPI_CPU0_LVC3_SCM_D1")
	)
	(segment
		(start 173.726094 -39.430198)
		(end 172.160184 -39.430198)
		(width 0.10668)
		(layer "B.Cu")
		(net "SPI_CPU0_LVC3_SCM_D1")
	)
	(segment
		(start 224.219516 -71.779638)
		(end 222.43796 -69.998082)
		(width 0.10668)
		(layer "B.Cu")
		(net "SPI_CPU0_LVC3_SCM_D1")
	)
	(segment
		(start 247.904 -135.463788)
		(end 247.904 -134.349236)
		(width 0.10668)
		(layer "B.Cu")
		(net "SPI_CPU0_LVC3_SCM_D1")
	)
	(segment
		(start 181.597808 -43.151298)
		(end 180.811678 -42.365168)
		(width 0.10668)
		(layer "B.Cu")
		(net "SPI_CPU0_LVC3_SCM_D1")
	)
	(segment
		(start 182.884064 -43.151298)
		(end 181.597808 -43.151298)
		(width 0.10668)
		(layer "B.Cu")
		(net "SPI_CPU0_LVC3_SCM_D1")
	)
	(segment
		(start 183.261 -45.318934)
		(end 183.261 -43.528234)
		(width 0.10668)
		(layer "B.Cu")
		(net "SPI_CPU0_LVC3_SCM_D1")
	)
	(segment
		(start 225.196654 -75.324462)
		(end 224.219516 -74.347324)
		(width 0.10668)
		(layer "B.Cu")
		(net "SPI_CPU0_LVC3_SCM_D1")
	)
	(segment
		(start 260.096 -143.002)
		(end 259.461 -143.002)
		(width 0.10668)
		(layer "B.Cu")
		(net "SPI_CPU0_LVC3_SCM_D1")
	)
	(segment
		(start 220.112336 -64.02959)
		(end 214.6935 -64.02959)
		(width 0.10668)
		(layer "B.Cu")
		(net "SPI_CPU0_LVC3_SCM_D1")
	)
	(segment
		(start 257.364738 -143.632174)
		(end 256.072386 -143.632174)
		(width 0.10668)
		(layer "B.Cu")
		(net "SPI_CPU0_LVC3_SCM_D1")
	)
	(segment
		(start 241.728244 -128.17348)
		(end 225.196654 -88.261952)
		(width 0.10668)
		(layer "B.Cu")
		(net "SPI_CPU0_LVC3_SCM_D1")
	)
	(segment
		(start 166.395654 -32.230568)
		(end 166.395654 -25.277318)
		(width 0.10668)
		(layer "B.Cu")
		(net "SPI_CPU0_LVC3_SCM_D1")
	)
	(segment
		(start 170.253914 -36.088828)
		(end 166.395654 -32.230568)
		(width 0.10668)
		(layer "B.Cu")
		(net "SPI_CPU0_LVC3_SCM_D1")
	)
	(segment
		(start 258.669282 -143.793718)
		(end 257.754882 -143.793718)
		(width 0.10668)
		(layer "B.Cu")
		(net "SPI_CPU0_LVC3_SCM_D1")
	)
	(segment
		(start 224.219516 -74.347324)
		(end 224.219516 -71.779638)
		(width 0.10668)
		(layer "B.Cu")
		(net "SPI_CPU0_LVC3_SCM_D1")
	)
	(segment
		(start 183.261 -43.528234)
		(end 182.884064 -43.151298)
		(width 0.10668)
		(layer "B.Cu")
		(net "SPI_CPU0_LVC3_SCM_D1")
	)
	(segment
		(start 172.160184 -39.430198)
		(end 170.253914 -37.523928)
		(width 0.10668)
		(layer "B.Cu")
		(net "SPI_CPU0_LVC3_SCM_D1")
	)
	(segment
		(start 180.811678 -42.365168)
		(end 173.726094 -39.430198)
		(width 0.10668)
		(layer "B.Cu")
		(net "SPI_CPU0_LVC3_SCM_D1")
	)
	(segment
		(start 214.6935 -64.02959)
		(end 202.616054 -61.627258)
		(width 0.10668)
		(layer "B.Cu")
		(net "SPI_CPU0_LVC3_SCM_D1")
	)
	(segment
		(start 197.403212 -59.468004)
		(end 195.449444 -58.162444)
		(width 0.10668)
		(layer "B.Cu")
		(net "SPI_CPU0_LVC3_SCM_D1")
	)
	(segment
		(start 258.08305 -143.010128)
		(end 258.064 -143.029178)
		(width 0.10668)
		(layer "F.Cu")
		(net "SPI_CPU0_LVC3_SCM_D0")
	)
	(segment
		(start 171.666916 -18.466816)
		(end 171.205144 -18.928588)
		(width 0.10668)
		(layer "F.Cu")
		(net "SPI_CPU0_LVC3_SCM_D0")
	)
	(segment
		(start 171.666916 -16.549878)
		(end 171.666916 -18.466816)
		(width 0.10668)
		(layer "F.Cu")
		(net "SPI_CPU0_LVC3_SCM_D0")
	)
	(segment
		(start 258.08305 -142.367)
		(end 258.08305 -143.010128)
		(width 0.10668)
		(layer "F.Cu")
		(net "SPI_CPU0_LVC3_SCM_D0")
	)
	(segment
		(start 258.08305 -142.367)
		(end 259.068316 -142.367)
		(width 0.10668)
		(layer "F.Cu")
		(net "SPI_CPU0_LVC3_SCM_D0")
	)
	(segment
		(start 259.068316 -142.367)
		(end 259.070094 -142.368778)
		(width 0.10668)
		(layer "F.Cu")
		(net "SPI_CPU0_LVC3_SCM_D0")
	)
	(via
		(at 258.064 -143.029178)
		(size 0.508)
		(drill 0.254)
		(layers "F.Cu" "B.Cu")
		(net "SPI_CPU0_LVC3_SCM_D0")
	)
	(via
		(at 171.205144 -18.928588)
		(size 0.508)
		(drill 0.254)
		(layers "F.Cu" "B.Cu")
		(net "SPI_CPU0_LVC3_SCM_D0")
	)
	(segment
		(start 197.781672 -58.958988)
		(end 202.618594 -60.96254)
		(width 0.10668)
		(layer "B.Cu")
		(net "SPI_CPU0_LVC3_SCM_D0")
	)
	(segment
		(start 226.764596 -76.003404)
		(end 225.696526 -77.071474)
		(width 0.10668)
		(layer "B.Cu")
		(net "SPI_CPU0_LVC3_SCM_D0")
	)
	(segment
		(start 202.618594 -60.96254)
		(end 215.050624 -63.435484)
		(width 0.10668)
		(layer "B.Cu")
		(net "SPI_CPU0_LVC3_SCM_D0")
	)
	(segment
		(start 183.74868 -43.325796)
		(end 183.74868 -44.925996)
		(width 0.10668)
		(layer "B.Cu")
		(net "SPI_CPU0_LVC3_SCM_D0")
	)
	(segment
		(start 167.96258 -20.749768)
		(end 167.96258 -24.590756)
		(width 0.10668)
		(layer "B.Cu")
		(net "SPI_CPU0_LVC3_SCM_D0")
	)
	(segment
		(start 248.5644 -135.397748)
		(end 256.19583 -143.029178)
		(width 0.10668)
		(layer "B.Cu")
		(net "SPI_CPU0_LVC3_SCM_D0")
	)
	(segment
		(start 220.459554 -63.435484)
		(end 226.764596 -69.740526)
		(width 0.10668)
		(layer "B.Cu")
		(net "SPI_CPU0_LVC3_SCM_D0")
	)
	(segment
		(start 226.764596 -69.740526)
		(end 226.764596 -76.003404)
		(width 0.10668)
		(layer "B.Cu")
		(net "SPI_CPU0_LVC3_SCM_D0")
	)
	(segment
		(start 169.78376 -18.928588)
		(end 167.96258 -20.749768)
		(width 0.10668)
		(layer "B.Cu")
		(net "SPI_CPU0_LVC3_SCM_D0")
	)
	(segment
		(start 242.120166 -127.843534)
		(end 248.5644 -134.287768)
		(width 0.10668)
		(layer "B.Cu")
		(net "SPI_CPU0_LVC3_SCM_D0")
	)
	(segment
		(start 248.5644 -134.287768)
		(end 248.5644 -135.397748)
		(width 0.10668)
		(layer "B.Cu")
		(net "SPI_CPU0_LVC3_SCM_D0")
	)
	(segment
		(start 167.96258 -24.590756)
		(end 166.979854 -25.573482)
		(width 0.10668)
		(layer "B.Cu")
		(net "SPI_CPU0_LVC3_SCM_D0")
	)
	(segment
		(start 183.016652 -42.593768)
		(end 183.74868 -43.325796)
		(width 0.10668)
		(layer "B.Cu")
		(net "SPI_CPU0_LVC3_SCM_D0")
	)
	(segment
		(start 166.979854 -25.573482)
		(end 166.979854 -31.722568)
		(width 0.10668)
		(layer "B.Cu")
		(net "SPI_CPU0_LVC3_SCM_D0")
	)
	(segment
		(start 166.979854 -31.722568)
		(end 170.604434 -35.347148)
		(width 0.10668)
		(layer "B.Cu")
		(net "SPI_CPU0_LVC3_SCM_D0")
	)
	(segment
		(start 170.604434 -35.347148)
		(end 172.197776 -35.347148)
		(width 0.10668)
		(layer "B.Cu")
		(net "SPI_CPU0_LVC3_SCM_D0")
	)
	(segment
		(start 181.7624 -42.593768)
		(end 183.016652 -42.593768)
		(width 0.10668)
		(layer "B.Cu")
		(net "SPI_CPU0_LVC3_SCM_D0")
	)
	(segment
		(start 215.050624 -63.435484)
		(end 220.459554 -63.435484)
		(width 0.10668)
		(layer "B.Cu")
		(net "SPI_CPU0_LVC3_SCM_D0")
	)
	(segment
		(start 176.24806 -38.240208)
		(end 178.229768 -39.061136)
		(width 0.10668)
		(layer "B.Cu")
		(net "SPI_CPU0_LVC3_SCM_D0")
	)
	(segment
		(start 225.696526 -88.193118)
		(end 242.120166 -127.843534)
		(width 0.10668)
		(layer "B.Cu")
		(net "SPI_CPU0_LVC3_SCM_D0")
	)
	(segment
		(start 256.19583 -143.029178)
		(end 258.064 -143.029178)
		(width 0.10668)
		(layer "B.Cu")
		(net "SPI_CPU0_LVC3_SCM_D0")
	)
	(segment
		(start 175.090836 -38.240208)
		(end 176.24806 -38.240208)
		(width 0.10668)
		(layer "B.Cu")
		(net "SPI_CPU0_LVC3_SCM_D0")
	)
	(segment
		(start 172.197776 -35.347148)
		(end 175.090836 -38.240208)
		(width 0.10668)
		(layer "B.Cu")
		(net "SPI_CPU0_LVC3_SCM_D0")
	)
	(segment
		(start 225.696526 -77.071474)
		(end 225.696526 -88.193118)
		(width 0.10668)
		(layer "B.Cu")
		(net "SPI_CPU0_LVC3_SCM_D0")
	)
	(segment
		(start 171.205144 -18.928588)
		(end 169.78376 -18.928588)
		(width 0.10668)
		(layer "B.Cu")
		(net "SPI_CPU0_LVC3_SCM_D0")
	)
	(segment
		(start 183.74868 -44.925996)
		(end 197.781672 -58.958988)
		(width 0.10668)
		(layer "B.Cu")
		(net "SPI_CPU0_LVC3_SCM_D0")
	)
	(segment
		(start 178.229768 -39.061136)
		(end 181.7624 -42.593768)
		(width 0.10668)
		(layer "B.Cu")
		(net "SPI_CPU0_LVC3_SCM_D0")
	)
	(segment
		(start 253.106174 -133.622796)
		(end 252.490224 -133.622796)
		(width 0.10668)
		(layer "F.Cu")
		(net "SPI_CPU0_LVC3_SCM_CS1_N")
	)
	(segment
		(start 252.490224 -133.622796)
		(end 251.874274 -133.622796)
		(width 0.10668)
		(layer "F.Cu")
		(net "SPI_CPU0_LVC3_SCM_CS1_N")
	)
	(via
		(at 252.490224 -133.622796)
		(size 0.508)
		(drill 0.254)
		(layers "F.Cu" "B.Cu")
		(net "SPI_CPU0_LVC3_SCM_CS1_N")
	)
	(segment
		(start 172.207174 -18.745708)
		(end 171.930314 -19.022568)
		(width 0.10668)
		(layer "F.Cu")
		(net "SPI_CPU0_LVC3_SCM_CS0_N")
	)
	(segment
		(start 171.930314 -19.022568)
		(end 171.930314 -20.515834)
		(width 0.10668)
		(layer "F.Cu")
		(net "SPI_CPU0_LVC3_SCM_CS0_N")
	)
	(segment
		(start 252.490224 -131.067556)
		(end 251.874274 -131.067556)
		(width 0.10668)
		(layer "F.Cu")
		(net "SPI_CPU0_LVC3_SCM_CS0_N")
	)
	(segment
		(start 172.267118 -16.549878)
		(end 172.207174 -16.609822)
		(width 0.10668)
		(layer "F.Cu")
		(net "SPI_CPU0_LVC3_SCM_CS0_N")
	)
	(segment
		(start 172.207174 -16.609822)
		(end 172.207174 -18.745708)
		(width 0.10668)
		(layer "F.Cu")
		(net "SPI_CPU0_LVC3_SCM_CS0_N")
	)
	(segment
		(start 171.579286 -20.866862)
		(end 171.579286 -22.395942)
		(width 0.10668)
		(layer "F.Cu")
		(net "SPI_CPU0_LVC3_SCM_CS0_N")
	)
	(segment
		(start 171.930314 -20.515834)
		(end 171.579286 -20.866862)
		(width 0.10668)
		(layer "F.Cu")
		(net "SPI_CPU0_LVC3_SCM_CS0_N")
	)
	(segment
		(start 253.106174 -131.067556)
		(end 252.490224 -131.067556)
		(width 0.10668)
		(layer "F.Cu")
		(net "SPI_CPU0_LVC3_SCM_CS0_N")
	)
	(via
		(at 252.490224 -131.067556)
		(size 0.508)
		(drill 0.254)
		(layers "F.Cu" "B.Cu")
		(net "SPI_CPU0_LVC3_SCM_CS0_N")
	)
	(via
		(at 171.579286 -22.395942)
		(size 0.508)
		(drill 0.254)
		(layers "F.Cu" "B.Cu")
		(net "SPI_CPU0_LVC3_SCM_CS0_N")
	)
	(segment
		(start 170.515534 -29.02458)
		(end 170.869102 -29.878528)
		(width 0.10668)
		(layer "B.Cu")
		(net "SPI_CPU0_LVC3_SCM_CS0_N")
	)
	(segment
		(start 244.088158 -78.427072)
		(end 244.088158 -122.528076)
		(width 0.10668)
		(layer "B.Cu")
		(net "SPI_CPU0_LVC3_SCM_CS0_N")
	)
	(segment
		(start 175.268382 -34.277808)
		(end 177.162968 -35.062668)
		(width 0.10668)
		(layer "B.Cu")
		(net "SPI_CPU0_LVC3_SCM_CS0_N")
	)
	(segment
		(start 171.333414 -22.641814)
		(end 171.333414 -26.400252)
		(width 0.10668)
		(layer "B.Cu")
		(net "SPI_CPU0_LVC3_SCM_CS0_N")
	)
	(segment
		(start 177.162968 -35.062668)
		(end 179.533042 -35.062668)
		(width 0.10668)
		(layer "B.Cu")
		(net "SPI_CPU0_LVC3_SCM_CS0_N")
	)
	(segment
		(start 214.063326 -60.094114)
		(end 222.885508 -60.094114)
		(width 0.10668)
		(layer "B.Cu")
		(net "SPI_CPU0_LVC3_SCM_CS0_N")
	)
	(segment
		(start 251.611638 -130.037586)
		(end 252.490224 -130.916172)
		(width 0.10668)
		(layer "B.Cu")
		(net "SPI_CPU0_LVC3_SCM_CS0_N")
	)
	(segment
		(start 203.455524 -57.984136)
		(end 214.063326 -60.094114)
		(width 0.10668)
		(layer "B.Cu")
		(net "SPI_CPU0_LVC3_SCM_CS0_N")
	)
	(segment
		(start 252.490224 -130.916172)
		(end 252.490224 -131.067556)
		(width 0.10668)
		(layer "B.Cu")
		(net "SPI_CPU0_LVC3_SCM_CS0_N")
	)
	(segment
		(start 171.333414 -26.400252)
		(end 170.515534 -27.218132)
		(width 0.10668)
		(layer "B.Cu")
		(net "SPI_CPU0_LVC3_SCM_CS0_N")
	)
	(segment
		(start 244.36959 -125.819662)
		(end 248.587514 -130.037586)
		(width 0.10668)
		(layer "B.Cu")
		(net "SPI_CPU0_LVC3_SCM_CS0_N")
	)
	(segment
		(start 199.147938 -56.199786)
		(end 203.455524 -57.984136)
		(width 0.10668)
		(layer "B.Cu")
		(net "SPI_CPU0_LVC3_SCM_CS0_N")
	)
	(segment
		(start 170.869102 -29.878528)
		(end 175.268382 -34.277808)
		(width 0.10668)
		(layer "B.Cu")
		(net "SPI_CPU0_LVC3_SCM_CS0_N")
	)
	(segment
		(start 186.47283 -42.002456)
		(end 186.47283 -43.524678)
		(width 0.10668)
		(layer "B.Cu")
		(net "SPI_CPU0_LVC3_SCM_CS0_N")
	)
	(segment
		(start 228.81209 -67.870578)
		(end 233.012488 -72.070976)
		(width 0.10668)
		(layer "B.Cu")
		(net "SPI_CPU0_LVC3_SCM_CS0_N")
	)
	(segment
		(start 233.012488 -72.070976)
		(end 237.732062 -72.070976)
		(width 0.10668)
		(layer "B.Cu")
		(net "SPI_CPU0_LVC3_SCM_CS0_N")
	)
	(segment
		(start 186.47283 -43.524678)
		(end 199.147938 -56.199786)
		(width 0.10668)
		(layer "B.Cu")
		(net "SPI_CPU0_LVC3_SCM_CS0_N")
	)
	(segment
		(start 237.732062 -72.070976)
		(end 244.088158 -78.427072)
		(width 0.10668)
		(layer "B.Cu")
		(net "SPI_CPU0_LVC3_SCM_CS0_N")
	)
	(segment
		(start 171.579286 -22.395942)
		(end 171.333414 -22.641814)
		(width 0.10668)
		(layer "B.Cu")
		(net "SPI_CPU0_LVC3_SCM_CS0_N")
	)
	(segment
		(start 170.515534 -27.218132)
		(end 170.515534 -29.02458)
		(width 0.10668)
		(layer "B.Cu")
		(net "SPI_CPU0_LVC3_SCM_CS0_N")
	)
	(segment
		(start 248.587514 -130.037586)
		(end 251.611638 -130.037586)
		(width 0.10668)
		(layer "B.Cu")
		(net "SPI_CPU0_LVC3_SCM_CS0_N")
	)
	(segment
		(start 179.533042 -35.062668)
		(end 186.47283 -42.002456)
		(width 0.10668)
		(layer "B.Cu")
		(net "SPI_CPU0_LVC3_SCM_CS0_N")
	)
	(segment
		(start 228.81209 -66.020696)
		(end 228.81209 -67.870578)
		(width 0.10668)
		(layer "B.Cu")
		(net "SPI_CPU0_LVC3_SCM_CS0_N")
	)
	(segment
		(start 244.088158 -122.528076)
		(end 244.36959 -122.809508)
		(width 0.10668)
		(layer "B.Cu")
		(net "SPI_CPU0_LVC3_SCM_CS0_N")
	)
	(segment
		(start 244.36959 -122.809508)
		(end 244.36959 -125.819662)
		(width 0.10668)
		(layer "B.Cu")
		(net "SPI_CPU0_LVC3_SCM_CS0_N")
	)
	(segment
		(start 222.885508 -60.094114)
		(end 228.81209 -66.020696)
		(width 0.10668)
		(layer "B.Cu")
		(net "SPI_CPU0_LVC3_SCM_CS0_N")
	)
	(segment
		(start 172.867066 -20.124166)
		(end 172.86732 -20.12442)
		(width 0.10668)
		(layer "F.Cu")
		(net "SPI_CPU0_LVC3_SCM_CLK")
	)
	(segment
		(start 172.867066 -16.549878)
		(end 172.867066 -20.124166)
		(width 0.10668)
		(layer "F.Cu")
		(net "SPI_CPU0_LVC3_SCM_CLK")
	)
	(segment
		(start 253.106174 -132.337556)
		(end 252.490224 -132.337556)
		(width 0.10668)
		(layer "F.Cu")
		(net "SPI_CPU0_LVC3_SCM_CLK")
	)
	(segment
		(start 252.490224 -132.337556)
		(end 251.874274 -132.337556)
		(width 0.10668)
		(layer "F.Cu")
		(net "SPI_CPU0_LVC3_SCM_CLK")
	)
	(via
		(at 172.86732 -20.12442)
		(size 0.508)
		(drill 0.254)
		(layers "F.Cu" "B.Cu")
		(net "SPI_CPU0_LVC3_SCM_CLK")
	)
	(via
		(at 252.490224 -132.337556)
		(size 0.508)
		(drill 0.254)
		(layers "F.Cu" "B.Cu")
		(net "SPI_CPU0_LVC3_SCM_CLK")
	)
	(segment
		(start 175.842168 -35.743388)
		(end 179.106322 -35.743388)
		(width 0.10668)
		(layer "B.Cu")
		(net "SPI_CPU0_LVC3_SCM_CLK")
	)
	(segment
		(start 172.86732 -20.12442)
		(end 171.893992 -21.097748)
		(width 0.10668)
		(layer "B.Cu")
		(net "SPI_CPU0_LVC3_SCM_CLK")
	)
	(segment
		(start 199.018398 -56.939942)
		(end 202.842622 -58.523886)
		(width 0.10668)
		(layer "B.Cu")
		(net "SPI_CPU0_LVC3_SCM_CLK")
	)
	(segment
		(start 250.688348 -131.882896)
		(end 251.143008 -132.337556)
		(width 0.10668)
		(layer "B.Cu")
		(net "SPI_CPU0_LVC3_SCM_CLK")
	)
	(segment
		(start 179.106322 -35.743388)
		(end 185.85815 -42.495216)
		(width 0.10668)
		(layer "B.Cu")
		(net "SPI_CPU0_LVC3_SCM_CLK")
	)
	(segment
		(start 214.65794 -60.874148)
		(end 220.837506 -60.874148)
		(width 0.10668)
		(layer "B.Cu")
		(net "SPI_CPU0_LVC3_SCM_CLK")
	)
	(segment
		(start 185.85815 -42.495216)
		(end 185.85815 -43.779694)
		(width 0.10668)
		(layer "B.Cu")
		(net "SPI_CPU0_LVC3_SCM_CLK")
	)
	(segment
		(start 170.588178 -22.074886)
		(end 170.588178 -26.102564)
		(width 0.10668)
		(layer "B.Cu")
		(net "SPI_CPU0_LVC3_SCM_CLK")
	)
	(segment
		(start 227.774246 -78.046072)
		(end 227.774246 -87.77605)
		(width 0.10668)
		(layer "B.Cu")
		(net "SPI_CPU0_LVC3_SCM_CLK")
	)
	(segment
		(start 228.850698 -68.88734)
		(end 228.850698 -76.96962)
		(width 0.10668)
		(layer "B.Cu")
		(net "SPI_CPU0_LVC3_SCM_CLK")
	)
	(segment
		(start 169.801794 -29.703014)
		(end 175.842168 -35.743388)
		(width 0.10668)
		(layer "B.Cu")
		(net "SPI_CPU0_LVC3_SCM_CLK")
	)
	(segment
		(start 202.842622 -58.523886)
		(end 214.65794 -60.874148)
		(width 0.10668)
		(layer "B.Cu")
		(net "SPI_CPU0_LVC3_SCM_CLK")
	)
	(segment
		(start 171.565316 -21.097748)
		(end 170.588178 -22.074886)
		(width 0.10668)
		(layer "B.Cu")
		(net "SPI_CPU0_LVC3_SCM_CLK")
	)
	(segment
		(start 249.407172 -131.882896)
		(end 250.688348 -131.882896)
		(width 0.10668)
		(layer "B.Cu")
		(net "SPI_CPU0_LVC3_SCM_CLK")
	)
	(segment
		(start 170.588178 -26.102564)
		(end 169.801794 -26.888948)
		(width 0.10668)
		(layer "B.Cu")
		(net "SPI_CPU0_LVC3_SCM_CLK")
	)
	(segment
		(start 185.85815 -43.779694)
		(end 199.018398 -56.939942)
		(width 0.10668)
		(layer "B.Cu")
		(net "SPI_CPU0_LVC3_SCM_CLK")
	)
	(segment
		(start 251.143008 -132.337556)
		(end 252.490224 -132.337556)
		(width 0.10668)
		(layer "B.Cu")
		(net "SPI_CPU0_LVC3_SCM_CLK")
	)
	(segment
		(start 227.774246 -87.77605)
		(end 243.664994 -126.140718)
		(width 0.10668)
		(layer "B.Cu")
		(net "SPI_CPU0_LVC3_SCM_CLK")
	)
	(segment
		(start 220.837506 -60.874148)
		(end 228.850698 -68.88734)
		(width 0.10668)
		(layer "B.Cu")
		(net "SPI_CPU0_LVC3_SCM_CLK")
	)
	(segment
		(start 169.801794 -26.888948)
		(end 169.801794 -29.703014)
		(width 0.10668)
		(layer "B.Cu")
		(net "SPI_CPU0_LVC3_SCM_CLK")
	)
	(segment
		(start 171.893992 -21.097748)
		(end 171.565316 -21.097748)
		(width 0.10668)
		(layer "B.Cu")
		(net "SPI_CPU0_LVC3_SCM_CLK")
	)
	(segment
		(start 228.850698 -76.96962)
		(end 227.774246 -78.046072)
		(width 0.10668)
		(layer "B.Cu")
		(net "SPI_CPU0_LVC3_SCM_CLK")
	)
	(segment
		(start 243.664994 -126.140718)
		(end 249.407172 -131.882896)
		(width 0.10668)
		(layer "B.Cu")
		(net "SPI_CPU0_LVC3_SCM_CLK")
	)
	(segment
		(start 256.192274 -133.955282)
		(end 255.298194 -133.955282)
		(width 0.10668)
		(layer "F.Cu")
		(net "SPI_CPU0_LVC3_R_TPM_CS_N")
	)
	(segment
		(start 255.298194 -133.955282)
		(end 254.522224 -134.731252)
		(width 0.10668)
		(layer "F.Cu")
		(net "SPI_CPU0_LVC3_R_TPM_CS_N")
	)
	(segment
		(start 254.522224 -134.731252)
		(end 254.522224 -134.892796)
		(width 0.10668)
		(layer "F.Cu")
		(net "SPI_CPU0_LVC3_R_TPM_CS_N")
	)
	(segment
		(start 254.522224 -134.892796)
		(end 253.906274 -134.892796)
		(width 0.10668)
		(layer "F.Cu")
		(net "SPI_CPU0_LVC3_R_TPM_CS_N")
	)
	(via
		(at 254.522224 -134.892796)
		(size 0.508)
		(drill 0.254)
		(layers "F.Cu" "B.Cu")
		(net "SPI_CPU0_LVC3_R_TPM_CS_N")
	)
	(segment
		(start 258.562094 -138.448796)
		(end 257.901694 -138.448796)
		(width 0.10668)
		(layer "F.Cu")
		(net "SPI_CPU0_LVC3_D3")
	)
	(segment
		(start 260.340094 -138.448796)
		(end 258.562094 -138.448796)
		(width 0.10668)
		(layer "F.Cu")
		(net "SPI_CPU0_LVC3_D3")
	)
	(via
		(at 258.562094 -138.448796)
		(size 0.508)
		(drill 0.254)
		(layers "F.Cu" "B.Cu")
		(net "SPI_CPU0_LVC3_D3")
	)
	(segment
		(start 258.903724 -139.66317)
		(end 258.793488 -139.66317)
		(width 0.10668)
		(layer "F.Cu")
		(net "SPI_CPU0_LVC3_D2")
	)
	(segment
		(start 260.340094 -138.848846)
		(end 259.718048 -138.848846)
		(width 0.10668)
		(layer "F.Cu")
		(net "SPI_CPU0_LVC3_D2")
	)
	(segment
		(start 259.718048 -138.848846)
		(end 258.903724 -139.66317)
		(width 0.10668)
		(layer "F.Cu")
		(net "SPI_CPU0_LVC3_D2")
	)
	(segment
		(start 258.737862 -139.718796)
		(end 257.901694 -139.718796)
		(width 0.10668)
		(layer "F.Cu")
		(net "SPI_CPU0_LVC3_D2")
	)
	(segment
		(start 258.793488 -139.66317)
		(end 258.737862 -139.718796)
		(width 0.10668)
		(layer "F.Cu")
		(net "SPI_CPU0_LVC3_D2")
	)
	(via
		(at 258.793488 -139.66317)
		(size 0.762)
		(drill 0.381)
		(layers "F.Cu" "B.Cu")
		(net "SPI_CPU0_LVC3_D2")
	)
	(segment
		(start 260.136894 -141.365478)
		(end 260.340094 -141.568678)
		(width 0.10668)
		(layer "F.Cu")
		(net "SPI_CPU0_LVC3_D1")
	)
	(segment
		(start 260.136894 -140.908278)
		(end 260.136894 -141.365478)
		(width 0.10668)
		(layer "F.Cu")
		(net "SPI_CPU0_LVC3_D1")
	)
	(segment
		(start 260.340094 -139.648946)
		(end 260.340094 -140.705078)
		(width 0.10668)
		(layer "F.Cu")
		(net "SPI_CPU0_LVC3_D1")
	)
	(segment
		(start 260.340094 -140.705078)
		(end 260.136894 -140.908278)
		(width 0.10668)
		(layer "F.Cu")
		(net "SPI_CPU0_LVC3_D1")
	)
	(via
		(at 260.136894 -140.908278)
		(size 0.508)
		(drill 0.254)
		(layers "F.Cu" "B.Cu")
		(net "SPI_CPU0_LVC3_D1")
	)
	(segment
		(start 260.025896 -139.248896)
		(end 259.630418 -139.644374)
		(width 0.10668)
		(layer "F.Cu")
		(net "SPI_CPU0_LVC3_D0")
	)
	(segment
		(start 259.630418 -139.644374)
		(end 259.630418 -140.144754)
		(width 0.10668)
		(layer "F.Cu")
		(net "SPI_CPU0_LVC3_D0")
	)
	(segment
		(start 259.630418 -140.144754)
		(end 258.866894 -140.908278)
		(width 0.10668)
		(layer "F.Cu")
		(net "SPI_CPU0_LVC3_D0")
	)
	(segment
		(start 258.866894 -140.908278)
		(end 258.866894 -141.365478)
		(width 0.10668)
		(layer "F.Cu")
		(net "SPI_CPU0_LVC3_D0")
	)
	(segment
		(start 260.340094 -139.248896)
		(end 260.025896 -139.248896)
		(width 0.10668)
		(layer "F.Cu")
		(net "SPI_CPU0_LVC3_D0")
	)
	(segment
		(start 258.866894 -141.365478)
		(end 259.070094 -141.568678)
		(width 0.10668)
		(layer "F.Cu")
		(net "SPI_CPU0_LVC3_D0")
	)
	(via
		(at 258.866894 -140.908278)
		(size 0.508)
		(drill 0.254)
		(layers "F.Cu" "B.Cu")
		(net "SPI_CPU0_LVC3_D0")
	)
	(segment
		(start 253.906274 -133.622796)
		(end 254.522224 -133.622796)
		(width 0.10668)
		(layer "F.Cu")
		(net "SPI_CPU0_LVC3_CS1_N")
	)
	(segment
		(start 254.522224 -133.622796)
		(end 254.839724 -133.305296)
		(width 0.10668)
		(layer "F.Cu")
		(net "SPI_CPU0_LVC3_CS1_N")
	)
	(segment
		(start 254.839724 -133.305296)
		(end 256.192274 -133.305296)
		(width 0.10668)
		(layer "F.Cu")
		(net "SPI_CPU0_LVC3_CS1_N")
	)
	(via
		(at 254.522224 -133.622796)
		(size 0.508)
		(drill 0.254)
		(layers "F.Cu" "B.Cu")
		(net "SPI_CPU0_LVC3_CS1_N")
	)
	(segment
		(start 256.192274 -132.00507)
		(end 255.459738 -132.00507)
		(width 0.10668)
		(layer "F.Cu")
		(net "SPI_CPU0_LVC3_CS0_N")
	)
	(segment
		(start 254.522224 -131.067556)
		(end 253.906274 -131.067556)
		(width 0.10668)
		(layer "F.Cu")
		(net "SPI_CPU0_LVC3_CS0_N")
	)
	(segment
		(start 255.459738 -132.00507)
		(end 254.522224 -131.067556)
		(width 0.10668)
		(layer "F.Cu")
		(net "SPI_CPU0_LVC3_CS0_N")
	)
	(via
		(at 254.522224 -131.067556)
		(size 0.508)
		(drill 0.254)
		(layers "F.Cu" "B.Cu")
		(net "SPI_CPU0_LVC3_CS0_N")
	)
	(segment
		(start 256.192274 -132.655056)
		(end 254.839724 -132.655056)
		(width 0.10668)
		(layer "F.Cu")
		(net "SPI_CPU0_LVC3_CLK")
	)
	(segment
		(start 254.839724 -132.655056)
		(end 254.522224 -132.337556)
		(width 0.10668)
		(layer "F.Cu")
		(net "SPI_CPU0_LVC3_CLK")
	)
	(segment
		(start 254.522224 -132.337556)
		(end 253.906274 -132.337556)
		(width 0.10668)
		(layer "F.Cu")
		(net "SPI_CPU0_LVC3_CLK")
	)
	(via
		(at 254.522224 -132.337556)
		(size 0.508)
		(drill 0.254)
		(layers "F.Cu" "B.Cu")
		(net "SPI_CPU0_LVC3_CLK")
	)
	(segment
		(start 265.173714 -137.408666)
		(end 264.586466 -137.995914)
		(width 0.10668)
		(layer "F.Cu")
		(net "SPI_CPU0_D3")
	)
	(segment
		(start 265.57605 -137.00633)
		(end 265.173714 -137.408666)
		(width 0.10668)
		(layer "F.Cu")
		(net "SPI_CPU0_D3")
	)
	(segment
		(start 264.586466 -137.995914)
		(end 264.586466 -138.321796)
		(width 0.10668)
		(layer "F.Cu")
		(net "SPI_CPU0_D3")
	)
	(segment
		(start 402.654008 -328.418952)
		(end 402.886418 -328.651362)
		(width 0.10668)
		(layer "F.Cu")
		(net "SPI_CPU0_D3")
	)
	(segment
		(start 402.886418 -328.651362)
		(end 402.886418 -329.051412)
		(width 0.10668)
		(layer "F.Cu")
		(net "SPI_CPU0_D3")
	)
	(segment
		(start 265.57605 -136.652)
		(end 265.57605 -137.00633)
		(width 0.10668)
		(layer "F.Cu")
		(net "SPI_CPU0_D3")
	)
	(via
		(at 265.173714 -137.408666)
		(size 0.508)
		(drill 0.254)
		(layers "F.Cu" "B.Cu")
		(net "SPI_CPU0_D3")
	)
	(via
		(at 402.886418 -329.051412)
		(size 0.508)
		(drill 0.254)
		(layers "F.Cu" "B.Cu")
		(net "SPI_CPU0_D3")
	)
	(segment
		(start 409.1686 -312.383932)
		(end 409.1686 -319.761362)
		(width 0.11684)
		(layer "In15.Cu")
		(net "SPI_CPU0_D3")
	)
	(segment
		(start 409.1686 -319.761362)
		(end 411.210252 -321.803014)
		(width 0.11684)
		(layer "In15.Cu")
		(net "SPI_CPU0_D3")
	)
	(segment
		(start 409.442666 -329.5269)
		(end 403.361906 -329.5269)
		(width 0.11684)
		(layer "In15.Cu")
		(net "SPI_CPU0_D3")
	)
	(segment
		(start 404.68042 -265.393932)
		(end 404.68042 -307.895752)
		(width 0.11684)
		(layer "In15.Cu")
		(net "SPI_CPU0_D3")
	)
	(segment
		(start 393.42314 -208.137252)
		(end 404.805642 -219.519754)
		(width 0.11684)
		(layer "In15.Cu")
		(net "SPI_CPU0_D3")
	)
	(segment
		(start 295.08831 -156.04998)
		(end 308.309264 -156.04998)
		(width 0.11684)
		(layer "In15.Cu")
		(net "SPI_CPU0_D3")
	)
	(segment
		(start 407.718768 -256.316226)
		(end 407.718768 -262.355584)
		(width 0.11684)
		(layer "In15.Cu")
		(net "SPI_CPU0_D3")
	)
	(segment
		(start 265.703558 -137.08634)
		(end 276.12467 -137.08634)
		(width 0.11684)
		(layer "In15.Cu")
		(net "SPI_CPU0_D3")
	)
	(segment
		(start 407.718768 -262.355584)
		(end 404.68042 -265.393932)
		(width 0.11684)
		(layer "In15.Cu")
		(net "SPI_CPU0_D3")
	)
	(segment
		(start 317.883032 -165.623748)
		(end 336.70621 -173.420024)
		(width 0.11684)
		(layer "In15.Cu")
		(net "SPI_CPU0_D3")
	)
	(segment
		(start 374.659144 -211.372958)
		(end 383.19329 -211.372958)
		(width 0.11684)
		(layer "In15.Cu")
		(net "SPI_CPU0_D3")
	)
	(segment
		(start 411.210252 -327.759314)
		(end 409.442666 -329.5269)
		(width 0.11684)
		(layer "In15.Cu")
		(net "SPI_CPU0_D3")
	)
	(segment
		(start 404.68042 -307.895752)
		(end 409.1686 -312.383932)
		(width 0.11684)
		(layer "In15.Cu")
		(net "SPI_CPU0_D3")
	)
	(segment
		(start 411.210252 -321.803014)
		(end 411.210252 -327.759314)
		(width 0.11684)
		(layer "In15.Cu")
		(net "SPI_CPU0_D3")
	)
	(segment
		(start 386.428996 -208.137252)
		(end 393.42314 -208.137252)
		(width 0.11684)
		(layer "In15.Cu")
		(net "SPI_CPU0_D3")
	)
	(segment
		(start 308.309264 -156.04998)
		(end 317.883032 -165.623748)
		(width 0.11684)
		(layer "In15.Cu")
		(net "SPI_CPU0_D3")
	)
	(segment
		(start 265.173714 -137.408666)
		(end 265.381232 -137.408666)
		(width 0.11684)
		(layer "In15.Cu")
		(net "SPI_CPU0_D3")
	)
	(segment
		(start 383.19329 -211.372958)
		(end 386.428996 -208.137252)
		(width 0.11684)
		(layer "In15.Cu")
		(net "SPI_CPU0_D3")
	)
	(segment
		(start 276.12467 -137.08634)
		(end 295.08831 -156.04998)
		(width 0.11684)
		(layer "In15.Cu")
		(net "SPI_CPU0_D3")
	)
	(segment
		(start 404.805642 -219.519754)
		(end 404.805642 -253.4031)
		(width 0.11684)
		(layer "In15.Cu")
		(net "SPI_CPU0_D3")
	)
	(segment
		(start 265.381232 -137.408666)
		(end 265.703558 -137.08634)
		(width 0.11684)
		(layer "In15.Cu")
		(net "SPI_CPU0_D3")
	)
	(segment
		(start 403.361906 -329.5269)
		(end 402.886418 -329.051412)
		(width 0.11684)
		(layer "In15.Cu")
		(net "SPI_CPU0_D3")
	)
	(segment
		(start 336.70621 -173.420024)
		(end 374.659144 -211.372958)
		(width 0.11684)
		(layer "In15.Cu")
		(net "SPI_CPU0_D3")
	)
	(segment
		(start 404.805642 -253.4031)
		(end 407.718768 -256.316226)
		(width 0.11684)
		(layer "In15.Cu")
		(net "SPI_CPU0_D3")
	)
	(segment
		(start 401.212812 -327.395332)
		(end 401.45208 -327.6346)
		(width 0.10668)
		(layer "F.Cu")
		(net "SPI_CPU0_D2")
	)
	(segment
		(start 264.009378 -139.121642)
		(end 264.289794 -139.121642)
		(width 0.10668)
		(layer "F.Cu")
		(net "SPI_CPU0_D2")
	)
	(segment
		(start 264.289794 -139.121642)
		(end 264.586466 -139.418314)
		(width 0.10668)
		(layer "F.Cu")
		(net "SPI_CPU0_D2")
	)
	(segment
		(start 400.807428 -327.395332)
		(end 401.212812 -327.395332)
		(width 0.10668)
		(layer "F.Cu")
		(net "SPI_CPU0_D2")
	)
	(segment
		(start 265.406124 -140.624814)
		(end 265.406124 -140.411454)
		(width 0.10668)
		(layer "F.Cu")
		(net "SPI_CPU0_D2")
	)
	(segment
		(start 265.406124 -140.411454)
		(end 264.586466 -139.591796)
		(width 0.10668)
		(layer "F.Cu")
		(net "SPI_CPU0_D2")
	)
	(segment
		(start 264.586466 -139.418314)
		(end 264.586466 -139.591796)
		(width 0.10668)
		(layer "F.Cu")
		(net "SPI_CPU0_D2")
	)
	(via
		(at 401.45208 -327.6346)
		(size 0.508)
		(drill 0.254)
		(layers "F.Cu" "B.Cu")
		(net "SPI_CPU0_D2")
	)
	(via
		(at 264.009378 -139.121642)
		(size 0.508)
		(drill 0.254)
		(layers "F.Cu" "B.Cu")
		(net "SPI_CPU0_D2")
	)
	(segment
		(start 294.831262 -156.592778)
		(end 307.925216 -156.592778)
		(width 0.11684)
		(layer "In15.Cu")
		(net "SPI_CPU0_D2")
	)
	(segment
		(start 409.832556 -327.959212)
		(end 407.406348 -327.959212)
		(width 0.11684)
		(layer "In15.Cu")
		(net "SPI_CPU0_D2")
	)
	(segment
		(start 264.374376 -139.48664)
		(end 265.118088 -139.48664)
		(width 0.11684)
		(layer "In15.Cu")
		(net "SPI_CPU0_D2")
	)
	(segment
		(start 407.406348 -327.959212)
		(end 407.013156 -328.352404)
		(width 0.11684)
		(layer "In15.Cu")
		(net "SPI_CPU0_D2")
	)
	(segment
		(start 408.648408 -320.049906)
		(end 410.651706 -322.053204)
		(width 0.11684)
		(layer "In15.Cu")
		(net "SPI_CPU0_D2")
	)
	(segment
		(start 407.208736 -262.123936)
		(end 404.131526 -265.201146)
		(width 0.11684)
		(layer "In15.Cu")
		(net "SPI_CPU0_D2")
	)
	(segment
		(start 410.651706 -327.140062)
		(end 409.832556 -327.959212)
		(width 0.11684)
		(layer "In15.Cu")
		(net "SPI_CPU0_D2")
	)
	(segment
		(start 383.784602 -211.915502)
		(end 386.813044 -208.88706)
		(width 0.11684)
		(layer "In15.Cu")
		(net "SPI_CPU0_D2")
	)
	(segment
		(start 277.08479 -138.846306)
		(end 294.831262 -156.592778)
		(width 0.11684)
		(layer "In15.Cu")
		(net "SPI_CPU0_D2")
	)
	(segment
		(start 374.41632 -211.915502)
		(end 383.784602 -211.915502)
		(width 0.11684)
		(layer "In15.Cu")
		(net "SPI_CPU0_D2")
	)
	(segment
		(start 407.013156 -328.352404)
		(end 402.169884 -328.352404)
		(width 0.11684)
		(layer "In15.Cu")
		(net "SPI_CPU0_D2")
	)
	(segment
		(start 402.169884 -328.352404)
		(end 401.45208 -327.6346)
		(width 0.11684)
		(layer "In15.Cu")
		(net "SPI_CPU0_D2")
	)
	(segment
		(start 404.131526 -308.069234)
		(end 408.648408 -312.586116)
		(width 0.11684)
		(layer "In15.Cu")
		(net "SPI_CPU0_D2")
	)
	(segment
		(start 407.208736 -256.606294)
		(end 407.208736 -262.123936)
		(width 0.11684)
		(layer "In15.Cu")
		(net "SPI_CPU0_D2")
	)
	(segment
		(start 336.448146 -173.947328)
		(end 374.41632 -211.915502)
		(width 0.11684)
		(layer "In15.Cu")
		(net "SPI_CPU0_D2")
	)
	(segment
		(start 404.295102 -253.69266)
		(end 407.208736 -256.606294)
		(width 0.11684)
		(layer "In15.Cu")
		(net "SPI_CPU0_D2")
	)
	(segment
		(start 317.383414 -166.050976)
		(end 336.448146 -173.947328)
		(width 0.11684)
		(layer "In15.Cu")
		(net "SPI_CPU0_D2")
	)
	(segment
		(start 410.651706 -322.053204)
		(end 410.651706 -327.140062)
		(width 0.11684)
		(layer "In15.Cu")
		(net "SPI_CPU0_D2")
	)
	(segment
		(start 404.131526 -265.201146)
		(end 404.131526 -308.069234)
		(width 0.11684)
		(layer "In15.Cu")
		(net "SPI_CPU0_D2")
	)
	(segment
		(start 408.648408 -312.586116)
		(end 408.648408 -320.049906)
		(width 0.11684)
		(layer "In15.Cu")
		(net "SPI_CPU0_D2")
	)
	(segment
		(start 386.813044 -208.88706)
		(end 393.323064 -208.88706)
		(width 0.11684)
		(layer "In15.Cu")
		(net "SPI_CPU0_D2")
	)
	(segment
		(start 265.118088 -139.48664)
		(end 265.758422 -138.846306)
		(width 0.11684)
		(layer "In15.Cu")
		(net "SPI_CPU0_D2")
	)
	(segment
		(start 393.323064 -208.88706)
		(end 404.295102 -219.859098)
		(width 0.11684)
		(layer "In15.Cu")
		(net "SPI_CPU0_D2")
	)
	(segment
		(start 264.009378 -139.121642)
		(end 264.374376 -139.48664)
		(width 0.11684)
		(layer "In15.Cu")
		(net "SPI_CPU0_D2")
	)
	(segment
		(start 404.295102 -219.859098)
		(end 404.295102 -253.69266)
		(width 0.11684)
		(layer "In15.Cu")
		(net "SPI_CPU0_D2")
	)
	(segment
		(start 307.925216 -156.592778)
		(end 317.383414 -166.050976)
		(width 0.11684)
		(layer "In15.Cu")
		(net "SPI_CPU0_D2")
	)
	(segment
		(start 265.758422 -138.846306)
		(end 277.08479 -138.846306)
		(width 0.11684)
		(layer "In15.Cu")
		(net "SPI_CPU0_D2")
	)
	(segment
		(start 261.21995 -143.02105)
		(end 261.239 -143.002)
		(width 0.10668)
		(layer "F.Cu")
		(net "SPI_CPU0_D1")
	)
	(segment
		(start 399.874232 -322.817998)
		(end 400.577558 -322.817998)
		(width 0.10668)
		(layer "F.Cu")
		(net "SPI_CPU0_D1")
	)
	(segment
		(start 261.21995 -143.764)
		(end 261.21995 -143.02105)
		(width 0.10668)
		(layer "F.Cu")
		(net "SPI_CPU0_D1")
	)
	(segment
		(start 261.62 -142.621)
		(end 261.239 -143.002)
		(width 0.10668)
		(layer "F.Cu")
		(net "SPI_CPU0_D1")
	)
	(segment
		(start 399.762218 -322.930012)
		(end 399.874232 -322.817998)
		(width 0.10668)
		(layer "F.Cu")
		(net "SPI_CPU0_D1")
	)
	(segment
		(start 261.62 -142.38605)
		(end 261.62 -142.621)
		(width 0.10668)
		(layer "F.Cu")
		(net "SPI_CPU0_D1")
	)
	(via
		(at 400.577558 -322.817998)
		(size 0.508)
		(drill 0.254)
		(layers "F.Cu" "B.Cu")
		(net "SPI_CPU0_D1")
	)
	(via
		(at 261.239 -143.002)
		(size 0.508)
		(drill 0.254)
		(layers "F.Cu" "B.Cu")
		(net "SPI_CPU0_D1")
	)
	(segment
		(start 401.473416 -264.487152)
		(end 404.857712 -261.102856)
		(width 0.11684)
		(layer "In15.Cu")
		(net "SPI_CPU0_D1")
	)
	(segment
		(start 387.652514 -216.102438)
		(end 385.745482 -214.195406)
		(width 0.11684)
		(layer "In15.Cu")
		(net "SPI_CPU0_D1")
	)
	(segment
		(start 263.933432 -143.976598)
		(end 262.958834 -143.002)
		(width 0.11684)
		(layer "In15.Cu")
		(net "SPI_CPU0_D1")
	)
	(segment
		(start 332.683104 -175.348392)
		(end 316.10046 -168.47947)
		(width 0.11684)
		(layer "In15.Cu")
		(net "SPI_CPU0_D1")
	)
	(segment
		(start 396.378176 -216.102438)
		(end 387.652514 -216.102438)
		(width 0.11684)
		(layer "In15.Cu")
		(net "SPI_CPU0_D1")
	)
	(segment
		(start 405.903684 -320.213736)
		(end 405.903684 -313.308492)
		(width 0.11684)
		(layer "In15.Cu")
		(net "SPI_CPU0_D1")
	)
	(segment
		(start 385.745482 -214.195406)
		(end 371.530118 -214.195406)
		(width 0.11684)
		(layer "In15.Cu")
		(net "SPI_CPU0_D1")
	)
	(segment
		(start 405.02713 -321.09029)
		(end 405.903684 -320.213736)
		(width 0.11684)
		(layer "In15.Cu")
		(net "SPI_CPU0_D1")
	)
	(segment
		(start 402.009356 -255.017778)
		(end 402.009356 -221.733618)
		(width 0.11684)
		(layer "In15.Cu")
		(net "SPI_CPU0_D1")
	)
	(segment
		(start 316.10046 -168.47947)
		(end 307.295042 -159.674052)
		(width 0.11684)
		(layer "In15.Cu")
		(net "SPI_CPU0_D1")
	)
	(segment
		(start 401.473416 -308.878224)
		(end 401.473416 -264.487152)
		(width 0.11684)
		(layer "In15.Cu")
		(net "SPI_CPU0_D1")
	)
	(segment
		(start 371.530118 -214.195406)
		(end 332.683104 -175.348392)
		(width 0.11684)
		(layer "In15.Cu")
		(net "SPI_CPU0_D1")
	)
	(segment
		(start 405.903684 -313.308492)
		(end 401.473416 -308.878224)
		(width 0.11684)
		(layer "In15.Cu")
		(net "SPI_CPU0_D1")
	)
	(segment
		(start 262.958834 -143.002)
		(end 261.239 -143.002)
		(width 0.11684)
		(layer "In15.Cu")
		(net "SPI_CPU0_D1")
	)
	(segment
		(start 278.402034 -143.976598)
		(end 263.933432 -143.976598)
		(width 0.11684)
		(layer "In15.Cu")
		(net "SPI_CPU0_D1")
	)
	(segment
		(start 404.857712 -261.102856)
		(end 404.857712 -257.866134)
		(width 0.11684)
		(layer "In15.Cu")
		(net "SPI_CPU0_D1")
	)
	(segment
		(start 294.099488 -159.674052)
		(end 278.402034 -143.976598)
		(width 0.11684)
		(layer "In15.Cu")
		(net "SPI_CPU0_D1")
	)
	(segment
		(start 404.857712 -257.866134)
		(end 402.009356 -255.017778)
		(width 0.11684)
		(layer "In15.Cu")
		(net "SPI_CPU0_D1")
	)
	(segment
		(start 402.009356 -221.733618)
		(end 396.378176 -216.102438)
		(width 0.11684)
		(layer "In15.Cu")
		(net "SPI_CPU0_D1")
	)
	(segment
		(start 307.295042 -159.674052)
		(end 294.099488 -159.674052)
		(width 0.11684)
		(layer "In15.Cu")
		(net "SPI_CPU0_D1")
	)
	(segment
		(start 400.577558 -322.817998)
		(end 400.577558 -322.433442)
		(width 0.11684)
		(layer "In15.Cu")
		(net "SPI_CPU0_D1")
	)
	(segment
		(start 400.577558 -322.433442)
		(end 401.92071 -321.09029)
		(width 0.11684)
		(layer "In15.Cu")
		(net "SPI_CPU0_D1")
	)
	(segment
		(start 401.92071 -321.09029)
		(end 405.02713 -321.09029)
		(width 0.11684)
		(layer "In15.Cu")
		(net "SPI_CPU0_D1")
	)
	(segment
		(start 263.906 -142.38605)
		(end 264.827512 -141.464538)
		(width 0.10668)
		(layer "F.Cu")
		(net "SPI_CPU0_D0")
	)
	(segment
		(start 264.827512 -141.464538)
		(end 264.827512 -141.43863)
		(width 0.10668)
		(layer "F.Cu")
		(net "SPI_CPU0_D0")
	)
	(segment
		(start 397.453104 -330.081382)
		(end 399.291048 -328.243438)
		(width 0.10668)
		(layer "F.Cu")
		(net "SPI_CPU0_D0")
	)
	(segment
		(start 396.525242 -330.862686)
		(end 397.306546 -330.081382)
		(width 0.10668)
		(layer "F.Cu")
		(net "SPI_CPU0_D0")
	)
	(segment
		(start 399.291048 -328.243438)
		(end 399.291048 -327.186544)
		(width 0.10668)
		(layer "F.Cu")
		(net "SPI_CPU0_D0")
	)
	(segment
		(start 399.838672 -326.63892)
		(end 399.838672 -325.9582)
		(width 0.10668)
		(layer "F.Cu")
		(net "SPI_CPU0_D0")
	)
	(segment
		(start 397.306546 -330.081382)
		(end 397.453104 -330.081382)
		(width 0.10668)
		(layer "F.Cu")
		(net "SPI_CPU0_D0")
	)
	(segment
		(start 399.291048 -327.186544)
		(end 399.838672 -326.63892)
		(width 0.10668)
		(layer "F.Cu")
		(net "SPI_CPU0_D0")
	)
	(segment
		(start 263.906 -142.38605)
		(end 263.017 -142.38605)
		(width 0.10668)
		(layer "F.Cu")
		(net "SPI_CPU0_D0")
	)
	(via
		(at 399.838672 -325.9582)
		(size 0.508)
		(drill 0.254)
		(layers "F.Cu" "B.Cu")
		(net "SPI_CPU0_D0")
	)
	(via
		(at 264.827512 -141.43863)
		(size 0.508)
		(drill 0.254)
		(layers "F.Cu" "B.Cu")
		(net "SPI_CPU0_D0")
	)
	(segment
		(start 373.921274 -213.194138)
		(end 384.95605 -213.194138)
		(width 0.11684)
		(layer "In15.Cu")
		(net "SPI_CPU0_D0")
	)
	(segment
		(start 402.735034 -308.524402)
		(end 407.27122 -313.060588)
		(width 0.11684)
		(layer "In15.Cu")
		(net "SPI_CPU0_D0")
	)
	(segment
		(start 399.838672 -325.59752)
		(end 399.838672 -325.9582)
		(width 0.11684)
		(layer "In15.Cu")
		(net "SPI_CPU0_D0")
	)
	(segment
		(start 392.381486 -210.275678)
		(end 403.015958 -220.91015)
		(width 0.11684)
		(layer "In15.Cu")
		(net "SPI_CPU0_D0")
	)
	(segment
		(start 307.51018 -158.104332)
		(end 316.587378 -167.18153)
		(width 0.11684)
		(layer "In15.Cu")
		(net "SPI_CPU0_D0")
	)
	(segment
		(start 407.27122 -320.743326)
		(end 409.096972 -322.569078)
		(width 0.11684)
		(layer "In15.Cu")
		(net "SPI_CPU0_D0")
	)
	(segment
		(start 409.096972 -324.182232)
		(end 408.656028 -324.623176)
		(width 0.11684)
		(layer "In15.Cu")
		(net "SPI_CPU0_D0")
	)
	(segment
		(start 400.813016 -324.623176)
		(end 399.838672 -325.59752)
		(width 0.11684)
		(layer "In15.Cu")
		(net "SPI_CPU0_D0")
	)
	(segment
		(start 265.57478 -141.185392)
		(end 277.593806 -141.185392)
		(width 0.11684)
		(layer "In15.Cu")
		(net "SPI_CPU0_D0")
	)
	(segment
		(start 403.015958 -220.91015)
		(end 403.015958 -254.41656)
		(width 0.11684)
		(layer "In15.Cu")
		(net "SPI_CPU0_D0")
	)
	(segment
		(start 316.587378 -167.18153)
		(end 335.912714 -175.186086)
		(width 0.11684)
		(layer "In15.Cu")
		(net "SPI_CPU0_D0")
	)
	(segment
		(start 409.096972 -322.569078)
		(end 409.096972 -324.182232)
		(width 0.11684)
		(layer "In15.Cu")
		(net "SPI_CPU0_D0")
	)
	(segment
		(start 405.927814 -257.328416)
		(end 405.927814 -261.455154)
		(width 0.11684)
		(layer "In15.Cu")
		(net "SPI_CPU0_D0")
	)
	(segment
		(start 408.656028 -324.623176)
		(end 400.813016 -324.623176)
		(width 0.11684)
		(layer "In15.Cu")
		(net "SPI_CPU0_D0")
	)
	(segment
		(start 294.512746 -158.104332)
		(end 307.51018 -158.104332)
		(width 0.11684)
		(layer "In15.Cu")
		(net "SPI_CPU0_D0")
	)
	(segment
		(start 277.593806 -141.185392)
		(end 294.512746 -158.104332)
		(width 0.11684)
		(layer "In15.Cu")
		(net "SPI_CPU0_D0")
	)
	(segment
		(start 403.015958 -254.41656)
		(end 405.927814 -257.328416)
		(width 0.11684)
		(layer "In15.Cu")
		(net "SPI_CPU0_D0")
	)
	(segment
		(start 405.927814 -261.455154)
		(end 402.735034 -264.647934)
		(width 0.11684)
		(layer "In15.Cu")
		(net "SPI_CPU0_D0")
	)
	(segment
		(start 264.827512 -141.43863)
		(end 265.321542 -141.43863)
		(width 0.11684)
		(layer "In15.Cu")
		(net "SPI_CPU0_D0")
	)
	(segment
		(start 402.735034 -264.647934)
		(end 402.735034 -308.524402)
		(width 0.11684)
		(layer "In15.Cu")
		(net "SPI_CPU0_D0")
	)
	(segment
		(start 387.87451 -210.275678)
		(end 392.381486 -210.275678)
		(width 0.11684)
		(layer "In15.Cu")
		(net "SPI_CPU0_D0")
	)
	(segment
		(start 335.912714 -175.186086)
		(end 373.921274 -213.194138)
		(width 0.11684)
		(layer "In15.Cu")
		(net "SPI_CPU0_D0")
	)
	(segment
		(start 265.321542 -141.43863)
		(end 265.57478 -141.185392)
		(width 0.11684)
		(layer "In15.Cu")
		(net "SPI_CPU0_D0")
	)
	(segment
		(start 384.95605 -213.194138)
		(end 387.87451 -210.275678)
		(width 0.11684)
		(layer "In15.Cu")
		(net "SPI_CPU0_D0")
	)
	(segment
		(start 407.27122 -313.060588)
		(end 407.27122 -320.743326)
		(width 0.11684)
		(layer "In15.Cu")
		(net "SPI_CPU0_D0")
	)
	(segment
		(start 263.145016 -133.305296)
		(end 261.792466 -133.305296)
		(width 0.10668)
		(layer "F.Cu")
		(net "SPI_CPU0_CS1_N")
	)
	(segment
		(start 263.462516 -133.622796)
		(end 263.145016 -133.305296)
		(width 0.10668)
		(layer "F.Cu")
		(net "SPI_CPU0_CS1_N")
	)
	(segment
		(start 264.078466 -133.622796)
		(end 263.462516 -133.622796)
		(width 0.10668)
		(layer "F.Cu")
		(net "SPI_CPU0_CS1_N")
	)
	(via
		(at 263.462516 -133.622796)
		(size 0.508)
		(drill 0.254)
		(layers "F.Cu" "B.Cu")
		(net "SPI_CPU0_CS1_N")
	)
	(via
		(at 395.35481 -328.226928)
		(size 0.508)
		(drill 0.254)
		(layers "F.Cu" "B.Cu")
		(net "SPI_CPU0_CS1_N")
	)
	(segment
		(start 394.355828 -328.226928)
		(end 394.10259 -328.122026)
		(width 0.10668)
		(layer "B.Cu")
		(net "SPI_CPU0_CS1_N")
	)
	(segment
		(start 393.840208 -327.859644)
		(end 393.840208 -327.644252)
		(width 0.10668)
		(layer "B.Cu")
		(net "SPI_CPU0_CS1_N")
	)
	(segment
		(start 395.35481 -328.226928)
		(end 394.355828 -328.226928)
		(width 0.10668)
		(layer "B.Cu")
		(net "SPI_CPU0_CS1_N")
	)
	(segment
		(start 394.10259 -328.122026)
		(end 393.840208 -327.859644)
		(width 0.10668)
		(layer "B.Cu")
		(net "SPI_CPU0_CS1_N")
	)
	(segment
		(start 396.634208 -329.37831)
		(end 398.184116 -329.37831)
		(width 0.11684)
		(layer "In15.Cu")
		(net "SPI_CPU0_CS1_N")
	)
	(segment
		(start 393.80541 -207.583278)
		(end 385.866386 -207.583278)
		(width 0.11684)
		(layer "In15.Cu")
		(net "SPI_CPU0_CS1_N")
	)
	(segment
		(start 409.67152 -330.02474)
		(end 411.71114 -327.98512)
		(width 0.11684)
		(layer "In15.Cu")
		(net "SPI_CPU0_CS1_N")
	)
	(segment
		(start 385.866386 -207.583278)
		(end 384.590036 -208.859628)
		(width 0.11684)
		(layer "In15.Cu")
		(net "SPI_CPU0_CS1_N")
	)
	(segment
		(start 264.488676 -133.622796)
		(end 263.462516 -133.622796)
		(width 0.11684)
		(layer "In15.Cu")
		(net "SPI_CPU0_CS1_N")
	)
	(segment
		(start 409.669488 -312.085736)
		(end 405.23922 -307.655468)
		(width 0.11684)
		(layer "In15.Cu")
		(net "SPI_CPU0_CS1_N")
	)
	(segment
		(start 411.71114 -321.533266)
		(end 409.669488 -319.491614)
		(width 0.11684)
		(layer "In15.Cu")
		(net "SPI_CPU0_CS1_N")
	)
	(segment
		(start 395.482826 -328.226928)
		(end 396.634208 -329.37831)
		(width 0.11684)
		(layer "In15.Cu")
		(net "SPI_CPU0_CS1_N")
	)
	(segment
		(start 317.925196 -164.89426)
		(end 308.538372 -155.507436)
		(width 0.11684)
		(layer "In15.Cu")
		(net "SPI_CPU0_CS1_N")
	)
	(segment
		(start 408.23896 -262.606028)
		(end 408.23896 -256.066798)
		(width 0.11684)
		(layer "In15.Cu")
		(net "SPI_CPU0_CS1_N")
	)
	(segment
		(start 402.032724 -328.921364)
		(end 402.032724 -329.178412)
		(width 0.11684)
		(layer "In15.Cu")
		(net "SPI_CPU0_CS1_N")
	)
	(segment
		(start 372.917212 -208.859628)
		(end 336.846672 -172.789088)
		(width 0.11684)
		(layer "In15.Cu")
		(net "SPI_CPU0_CS1_N")
	)
	(segment
		(start 411.71114 -327.98512)
		(end 411.71114 -321.533266)
		(width 0.11684)
		(layer "In15.Cu")
		(net "SPI_CPU0_CS1_N")
	)
	(segment
		(start 405.315928 -253.143766)
		(end 405.315928 -219.093796)
		(width 0.11684)
		(layer "In15.Cu")
		(net "SPI_CPU0_CS1_N")
	)
	(segment
		(start 336.846672 -172.789088)
		(end 317.925196 -164.89426)
		(width 0.11684)
		(layer "In15.Cu")
		(net "SPI_CPU0_CS1_N")
	)
	(segment
		(start 409.669488 -319.491614)
		(end 409.669488 -312.085736)
		(width 0.11684)
		(layer "In15.Cu")
		(net "SPI_CPU0_CS1_N")
	)
	(segment
		(start 402.879052 -330.02474)
		(end 409.67152 -330.02474)
		(width 0.11684)
		(layer "In15.Cu")
		(net "SPI_CPU0_CS1_N")
	)
	(segment
		(start 274.25777 -134.32028)
		(end 265.18616 -134.32028)
		(width 0.11684)
		(layer "In15.Cu")
		(net "SPI_CPU0_CS1_N")
	)
	(segment
		(start 405.315928 -219.093796)
		(end 393.80541 -207.583278)
		(width 0.11684)
		(layer "In15.Cu")
		(net "SPI_CPU0_CS1_N")
	)
	(segment
		(start 408.23896 -256.066798)
		(end 405.315928 -253.143766)
		(width 0.11684)
		(layer "In15.Cu")
		(net "SPI_CPU0_CS1_N")
	)
	(segment
		(start 398.184116 -329.37831)
		(end 399.181574 -328.380852)
		(width 0.11684)
		(layer "In15.Cu")
		(net "SPI_CPU0_CS1_N")
	)
	(segment
		(start 395.35481 -328.226928)
		(end 395.482826 -328.226928)
		(width 0.11684)
		(layer "In15.Cu")
		(net "SPI_CPU0_CS1_N")
	)
	(segment
		(start 402.032724 -329.178412)
		(end 402.879052 -330.02474)
		(width 0.11684)
		(layer "In15.Cu")
		(net "SPI_CPU0_CS1_N")
	)
	(segment
		(start 265.18616 -134.32028)
		(end 264.488676 -133.622796)
		(width 0.11684)
		(layer "In15.Cu")
		(net "SPI_CPU0_CS1_N")
	)
	(segment
		(start 405.23922 -307.655468)
		(end 405.23922 -265.605768)
		(width 0.11684)
		(layer "In15.Cu")
		(net "SPI_CPU0_CS1_N")
	)
	(segment
		(start 399.181574 -328.380852)
		(end 401.492212 -328.380852)
		(width 0.11684)
		(layer "In15.Cu")
		(net "SPI_CPU0_CS1_N")
	)
	(segment
		(start 401.492212 -328.380852)
		(end 402.032724 -328.921364)
		(width 0.11684)
		(layer "In15.Cu")
		(net "SPI_CPU0_CS1_N")
	)
	(segment
		(start 295.444926 -155.507436)
		(end 274.25777 -134.32028)
		(width 0.11684)
		(layer "In15.Cu")
		(net "SPI_CPU0_CS1_N")
	)
	(segment
		(start 405.23922 -265.605768)
		(end 408.23896 -262.606028)
		(width 0.11684)
		(layer "In15.Cu")
		(net "SPI_CPU0_CS1_N")
	)
	(segment
		(start 308.538372 -155.507436)
		(end 295.444926 -155.507436)
		(width 0.11684)
		(layer "In15.Cu")
		(net "SPI_CPU0_CS1_N")
	)
	(segment
		(start 384.590036 -208.859628)
		(end 372.917212 -208.859628)
		(width 0.11684)
		(layer "In15.Cu")
		(net "SPI_CPU0_CS1_N")
	)
	(segment
		(start 263.106408 -130.997706)
		(end 263.106408 -131.506976)
		(width 0.10668)
		(layer "F.Cu")
		(net "SPI_CPU0_CS0_N")
	)
	(segment
		(start 263.323832 -130.780282)
		(end 263.106408 -130.997706)
		(width 0.10668)
		(layer "F.Cu")
		(net "SPI_CPU0_CS0_N")
	)
	(segment
		(start 400.22272 -330.175616)
		(end 399.93824 -329.891136)
		(width 0.10668)
		(layer "F.Cu")
		(net "SPI_CPU0_CS0_N")
	)
	(segment
		(start 263.611106 -131.067556)
		(end 263.323832 -130.780282)
		(width 0.10668)
		(layer "F.Cu")
		(net "SPI_CPU0_CS0_N")
	)
	(segment
		(start 264.078466 -131.067556)
		(end 263.611106 -131.067556)
		(width 0.10668)
		(layer "F.Cu")
		(net "SPI_CPU0_CS0_N")
	)
	(segment
		(start 263.106408 -131.506976)
		(end 262.608314 -132.00507)
		(width 0.10668)
		(layer "F.Cu")
		(net "SPI_CPU0_CS0_N")
	)
	(segment
		(start 399.93824 -329.891136)
		(end 399.93824 -329.28814)
		(width 0.10668)
		(layer "F.Cu")
		(net "SPI_CPU0_CS0_N")
	)
	(segment
		(start 262.608314 -132.00507)
		(end 261.792466 -132.00507)
		(width 0.10668)
		(layer "F.Cu")
		(net "SPI_CPU0_CS0_N")
	)
	(via
		(at 399.93824 -329.28814)
		(size 0.508)
		(drill 0.254)
		(layers "F.Cu" "B.Cu")
		(net "SPI_CPU0_CS0_N")
	)
	(via
		(at 263.323832 -130.780282)
		(size 0.508)
		(drill 0.254)
		(layers "F.Cu" "B.Cu")
		(net "SPI_CPU0_CS0_N")
	)
	(segment
		(start 337.418172 -172.46092)
		(end 373.259858 -208.302606)
		(width 0.11684)
		(layer "In15.Cu")
		(net "SPI_CPU0_CS0_N")
	)
	(segment
		(start 405.739854 -265.933174)
		(end 405.739854 -307.424074)
		(width 0.11684)
		(layer "In15.Cu")
		(net "SPI_CPU0_CS0_N")
	)
	(segment
		(start 407.12771 -330.61529)
		(end 401.26539 -330.61529)
		(width 0.11684)
		(layer "In15.Cu")
		(net "SPI_CPU0_CS0_N")
	)
	(segment
		(start 405.831294 -252.830584)
		(end 408.749246 -255.748536)
		(width 0.11684)
		(layer "In15.Cu")
		(net "SPI_CPU0_CS0_N")
	)
	(segment
		(start 410.34335 -319.115948)
		(end 412.24073 -321.013328)
		(width 0.11684)
		(layer "In15.Cu")
		(net "SPI_CPU0_CS0_N")
	)
	(segment
		(start 385.475226 -207.085438)
		(end 394.011658 -207.085438)
		(width 0.11684)
		(layer "In15.Cu")
		(net "SPI_CPU0_CS0_N")
	)
	(segment
		(start 405.739854 -307.424074)
		(end 410.34335 -312.02757)
		(width 0.11684)
		(layer "In15.Cu")
		(net "SPI_CPU0_CS0_N")
	)
	(segment
		(start 263.895332 -130.780282)
		(end 264.89025 -131.7752)
		(width 0.11684)
		(layer "In15.Cu")
		(net "SPI_CPU0_CS0_N")
	)
	(segment
		(start 373.259858 -208.302606)
		(end 384.258058 -208.302606)
		(width 0.11684)
		(layer "In15.Cu")
		(net "SPI_CPU0_CS0_N")
	)
	(segment
		(start 308.609492 -154.864816)
		(end 318.2112 -164.466524)
		(width 0.11684)
		(layer "In15.Cu")
		(net "SPI_CPU0_CS0_N")
	)
	(segment
		(start 268.64437 -131.7752)
		(end 269.715996 -132.846826)
		(width 0.11684)
		(layer "In15.Cu")
		(net "SPI_CPU0_CS0_N")
	)
	(segment
		(start 408.929078 -331.77226)
		(end 408.28468 -331.77226)
		(width 0.11684)
		(layer "In15.Cu")
		(net "SPI_CPU0_CS0_N")
	)
	(segment
		(start 263.323832 -130.780282)
		(end 263.895332 -130.780282)
		(width 0.11684)
		(layer "In15.Cu")
		(net "SPI_CPU0_CS0_N")
	)
	(segment
		(start 318.2112 -164.466524)
		(end 337.418172 -172.46092)
		(width 0.11684)
		(layer "In15.Cu")
		(net "SPI_CPU0_CS0_N")
	)
	(segment
		(start 408.749246 -262.923782)
		(end 405.739854 -265.933174)
		(width 0.11684)
		(layer "In15.Cu")
		(net "SPI_CPU0_CS0_N")
	)
	(segment
		(start 401.26539 -330.61529)
		(end 399.93824 -329.28814)
		(width 0.11684)
		(layer "In15.Cu")
		(net "SPI_CPU0_CS0_N")
	)
	(segment
		(start 295.68775 -154.864816)
		(end 308.609492 -154.864816)
		(width 0.11684)
		(layer "In15.Cu")
		(net "SPI_CPU0_CS0_N")
	)
	(segment
		(start 412.24073 -328.460608)
		(end 408.929078 -331.77226)
		(width 0.11684)
		(layer "In15.Cu")
		(net "SPI_CPU0_CS0_N")
	)
	(segment
		(start 408.749246 -255.748536)
		(end 408.749246 -262.923782)
		(width 0.11684)
		(layer "In15.Cu")
		(net "SPI_CPU0_CS0_N")
	)
	(segment
		(start 273.66976 -132.846826)
		(end 295.68775 -154.864816)
		(width 0.11684)
		(layer "In15.Cu")
		(net "SPI_CPU0_CS0_N")
	)
	(segment
		(start 384.258058 -208.302606)
		(end 385.475226 -207.085438)
		(width 0.11684)
		(layer "In15.Cu")
		(net "SPI_CPU0_CS0_N")
	)
	(segment
		(start 412.24073 -321.013328)
		(end 412.24073 -328.460608)
		(width 0.11684)
		(layer "In15.Cu")
		(net "SPI_CPU0_CS0_N")
	)
	(segment
		(start 394.011658 -207.085438)
		(end 405.831294 -218.905074)
		(width 0.11684)
		(layer "In15.Cu")
		(net "SPI_CPU0_CS0_N")
	)
	(segment
		(start 264.89025 -131.7752)
		(end 268.64437 -131.7752)
		(width 0.11684)
		(layer "In15.Cu")
		(net "SPI_CPU0_CS0_N")
	)
	(segment
		(start 410.34335 -312.02757)
		(end 410.34335 -319.115948)
		(width 0.11684)
		(layer "In15.Cu")
		(net "SPI_CPU0_CS0_N")
	)
	(segment
		(start 269.715996 -132.846826)
		(end 273.66976 -132.846826)
		(width 0.11684)
		(layer "In15.Cu")
		(net "SPI_CPU0_CS0_N")
	)
	(segment
		(start 408.28468 -331.77226)
		(end 407.12771 -330.61529)
		(width 0.11684)
		(layer "In15.Cu")
		(net "SPI_CPU0_CS0_N")
	)
	(segment
		(start 405.831294 -218.905074)
		(end 405.831294 -252.830584)
		(width 0.11684)
		(layer "In15.Cu")
		(net "SPI_CPU0_CS0_N")
	)
	(segment
		(start 404.438866 -326.5932)
		(end 403.504908 -325.659242)
		(width 0.10668)
		(layer "F.Cu")
		(net "SPI_CPU0_CLK")
	)
	(segment
		(start 263.145016 -132.655056)
		(end 261.792466 -132.655056)
		(width 0.10668)
		(layer "F.Cu")
		(net "SPI_CPU0_CLK")
	)
	(segment
		(start 405.476202 -326.719184)
		(end 405.350218 -326.5932)
		(width 0.10668)
		(layer "F.Cu")
		(net "SPI_CPU0_CLK")
	)
	(segment
		(start 405.350218 -326.5932)
		(end 404.438866 -326.5932)
		(width 0.10668)
		(layer "F.Cu")
		(net "SPI_CPU0_CLK")
	)
	(segment
		(start 264.078466 -132.352796)
		(end 263.477756 -132.352796)
		(width 0.10668)
		(layer "F.Cu")
		(net "SPI_CPU0_CLK")
	)
	(segment
		(start 263.477756 -132.352796)
		(end 263.462516 -132.337556)
		(width 0.10668)
		(layer "F.Cu")
		(net "SPI_CPU0_CLK")
	)
	(segment
		(start 263.462516 -132.337556)
		(end 263.145016 -132.655056)
		(width 0.10668)
		(layer "F.Cu")
		(net "SPI_CPU0_CLK")
	)
	(segment
		(start 403.504908 -324.862952)
		(end 402.654008 -324.862952)
		(width 0.10668)
		(layer "F.Cu")
		(net "SPI_CPU0_CLK")
	)
	(segment
		(start 403.504908 -325.659242)
		(end 403.504908 -324.862952)
		(width 0.10668)
		(layer "F.Cu")
		(net "SPI_CPU0_CLK")
	)
	(via
		(at 263.462516 -132.337556)
		(size 0.508)
		(drill 0.254)
		(layers "F.Cu" "B.Cu")
		(net "SPI_CPU0_CLK")
	)
	(via
		(at 405.476202 -326.719184)
		(size 0.508)
		(drill 0.254)
		(layers "F.Cu" "B.Cu")
		(net "SPI_CPU0_CLK")
	)
	(segment
		(start 263.441688 -140.124942)
		(end 264.827004 -140.124942)
		(width 0.11684)
		(layer "In15.Cu")
		(net "SPI_CPU0_CLK")
	)
	(segment
		(start 409.72994 -322.11391)
		(end 409.72994 -324.808596)
		(width 0.11684)
		(layer "In15.Cu")
		(net "SPI_CPU0_CLK")
	)
	(segment
		(start 392.961622 -209.577686)
		(end 403.656292 -220.272356)
		(width 0.11684)
		(layer "In15.Cu")
		(net "SPI_CPU0_CLK")
	)
	(segment
		(start 307.716936 -157.361636)
		(end 316.879732 -166.524432)
		(width 0.11684)
		(layer "In15.Cu")
		(net "SPI_CPU0_CLK")
	)
	(segment
		(start 403.40915 -264.912094)
		(end 403.40915 -308.31155)
		(width 0.11684)
		(layer "In15.Cu")
		(net "SPI_CPU0_CLK")
	)
	(segment
		(start 262.56107 -134.121144)
		(end 264.316972 -135.877046)
		(width 0.11684)
		(layer "In15.Cu")
		(net "SPI_CPU0_CLK")
	)
	(segment
		(start 374.15978 -212.543898)
		(end 384.278886 -212.543898)
		(width 0.11684)
		(layer "In15.Cu")
		(net "SPI_CPU0_CLK")
	)
	(segment
		(start 403.40915 -308.31155)
		(end 407.926286 -312.828686)
		(width 0.11684)
		(layer "In15.Cu")
		(net "SPI_CPU0_CLK")
	)
	(segment
		(start 403.656292 -220.272356)
		(end 403.656292 -254.045466)
		(width 0.11684)
		(layer "In15.Cu")
		(net "SPI_CPU0_CLK")
	)
	(segment
		(start 384.278886 -212.543898)
		(end 387.245098 -209.577686)
		(width 0.11684)
		(layer "In15.Cu")
		(net "SPI_CPU0_CLK")
	)
	(segment
		(start 316.879732 -166.524432)
		(end 336.102198 -174.486316)
		(width 0.11684)
		(layer "In15.Cu")
		(net "SPI_CPU0_CLK")
	)
	(segment
		(start 263.462516 -132.337556)
		(end 262.56107 -133.239002)
		(width 0.11684)
		(layer "In15.Cu")
		(net "SPI_CPU0_CLK")
	)
	(segment
		(start 409.72994 -324.808596)
		(end 408.877008 -325.661528)
		(width 0.11684)
		(layer "In15.Cu")
		(net "SPI_CPU0_CLK")
	)
	(segment
		(start 264.316972 -135.877046)
		(end 264.316972 -137.610342)
		(width 0.11684)
		(layer "In15.Cu")
		(net "SPI_CPU0_CLK")
	)
	(segment
		(start 406.572974 -256.962148)
		(end 406.572974 -261.74827)
		(width 0.11684)
		(layer "In15.Cu")
		(net "SPI_CPU0_CLK")
	)
	(segment
		(start 406.572974 -261.74827)
		(end 403.40915 -264.912094)
		(width 0.11684)
		(layer "In15.Cu")
		(net "SPI_CPU0_CLK")
	)
	(segment
		(start 407.926286 -312.828686)
		(end 407.926286 -320.310256)
		(width 0.11684)
		(layer "In15.Cu")
		(net "SPI_CPU0_CLK")
	)
	(segment
		(start 403.656292 -254.045466)
		(end 406.572974 -256.962148)
		(width 0.11684)
		(layer "In15.Cu")
		(net "SPI_CPU0_CLK")
	)
	(segment
		(start 406.971246 -325.661528)
		(end 405.91359 -326.719184)
		(width 0.11684)
		(layer "In15.Cu")
		(net "SPI_CPU0_CLK")
	)
	(segment
		(start 408.877008 -325.661528)
		(end 406.971246 -325.661528)
		(width 0.11684)
		(layer "In15.Cu")
		(net "SPI_CPU0_CLK")
	)
	(segment
		(start 405.91359 -326.719184)
		(end 405.476202 -326.719184)
		(width 0.11684)
		(layer "In15.Cu")
		(net "SPI_CPU0_CLK")
	)
	(segment
		(start 264.827004 -140.124942)
		(end 265.159998 -140.457936)
		(width 0.11684)
		(layer "In15.Cu")
		(net "SPI_CPU0_CLK")
	)
	(segment
		(start 407.926286 -320.310256)
		(end 409.72994 -322.11391)
		(width 0.11684)
		(layer "In15.Cu")
		(net "SPI_CPU0_CLK")
	)
	(segment
		(start 265.159998 -140.457936)
		(end 277.784814 -140.457936)
		(width 0.11684)
		(layer "In15.Cu")
		(net "SPI_CPU0_CLK")
	)
	(segment
		(start 294.688514 -157.361636)
		(end 307.716936 -157.361636)
		(width 0.11684)
		(layer "In15.Cu")
		(net "SPI_CPU0_CLK")
	)
	(segment
		(start 387.245098 -209.577686)
		(end 392.961622 -209.577686)
		(width 0.11684)
		(layer "In15.Cu")
		(net "SPI_CPU0_CLK")
	)
	(segment
		(start 264.316972 -137.610342)
		(end 263.13003 -138.797284)
		(width 0.11684)
		(layer "In15.Cu")
		(net "SPI_CPU0_CLK")
	)
	(segment
		(start 263.13003 -139.813284)
		(end 263.441688 -140.124942)
		(width 0.11684)
		(layer "In15.Cu")
		(net "SPI_CPU0_CLK")
	)
	(segment
		(start 262.56107 -133.239002)
		(end 262.56107 -134.121144)
		(width 0.11684)
		(layer "In15.Cu")
		(net "SPI_CPU0_CLK")
	)
	(segment
		(start 263.13003 -138.797284)
		(end 263.13003 -139.813284)
		(width 0.11684)
		(layer "In15.Cu")
		(net "SPI_CPU0_CLK")
	)
	(segment
		(start 336.102198 -174.486316)
		(end 374.15978 -212.543898)
		(width 0.11684)
		(layer "In15.Cu")
		(net "SPI_CPU0_CLK")
	)
	(segment
		(start 277.784814 -140.457936)
		(end 294.688514 -157.361636)
		(width 0.11684)
		(layer "In15.Cu")
		(net "SPI_CPU0_CLK")
	)
	(segment
		(start 342.311228 -16.928338)
		(end 341.344758 -17.894808)
		(width 0.10668)
		(layer "F.Cu")
		(net "SMERR_LED_N")
	)
	(segment
		(start 342.7349 -16.928338)
		(end 342.311228 -16.928338)
		(width 0.10668)
		(layer "F.Cu")
		(net "SMERR_LED_N")
	)
	(segment
		(start 343.3445 -20.597876)
		(end 342.526874 -19.78025)
		(width 0.10668)
		(layer "F.Cu")
		(net "SMERR_LED_N")
	)
	(segment
		(start 342.526874 -19.78025)
		(end 342.526874 -19.076924)
		(width 0.10668)
		(layer "F.Cu")
		(net "SMERR_LED_N")
	)
	(segment
		(start 343.3445 -21.03501)
		(end 343.3445 -20.597876)
		(width 0.10668)
		(layer "F.Cu")
		(net "SMERR_LED_N")
	)
	(segment
		(start 342.526874 -19.076924)
		(end 341.344758 -17.894808)
		(width 0.10668)
		(layer "F.Cu")
		(net "SMERR_LED_N")
	)
	(via
		(at 341.344758 -17.894808)
		(size 0.762)
		(drill 0.381)
		(layers "F.Cu" "B.Cu")
		(net "SMERR_LED_N")
	)
	(segment
		(start 343.994486 -19.13509)
		(end 343.994486 -18.70202)
		(width 0.10668)
		(layer "F.Cu")
		(net "SMERR_LED")
	)
	(segment
		(start 344.510106 -18.567654)
		(end 344.644472 -18.70202)
		(width 0.10668)
		(layer "F.Cu")
		(net "SMERR_LED")
	)
	(segment
		(start 344.644472 -18.70202)
		(end 344.644472 -19.13509)
		(width 0.10668)
		(layer "F.Cu")
		(net "SMERR_LED")
	)
	(segment
		(start 345.467686 -22.26945)
		(end 345.467686 -23.48865)
		(width 0.10668)
		(layer "F.Cu")
		(net "SMERR_LED")
	)
	(segment
		(start 345.467686 -20.380706)
		(end 345.467686 -22.26945)
		(width 0.10668)
		(layer "F.Cu")
		(net "SMERR_LED")
	)
	(segment
		(start 344.644472 -19.13509)
		(end 344.644472 -19.557492)
		(width 0.10668)
		(layer "F.Cu")
		(net "SMERR_LED")
	)
	(segment
		(start 344.644472 -19.557492)
		(end 345.467686 -20.380706)
		(width 0.10668)
		(layer "F.Cu")
		(net "SMERR_LED")
	)
	(segment
		(start 344.128852 -18.567654)
		(end 344.510106 -18.567654)
		(width 0.10668)
		(layer "F.Cu")
		(net "SMERR_LED")
	)
	(segment
		(start 343.994486 -18.70202)
		(end 344.128852 -18.567654)
		(width 0.10668)
		(layer "F.Cu")
		(net "SMERR_LED")
	)
	(via
		(at 345.467686 -22.26945)
		(size 0.762)
		(drill 0.381)
		(layers "F.Cu" "B.Cu")
		(net "SMERR_LED")
	)
	(segment
		(start 272.95729 -123.896628)
		(end 272.46834 -123.896628)
		(width 0.10668)
		(layer "F.Cu")
		(net "SMB_VR_SENSOR_3V3AUX_SDA")
	)
	(segment
		(start 272.21434 -124.150628)
		(end 271.928082 -123.86437)
		(width 0.10668)
		(layer "F.Cu")
		(net "SMB_VR_SENSOR_3V3AUX_SDA")
	)
	(segment
		(start 272.46834 -123.896628)
		(end 272.21434 -124.150628)
		(width 0.10668)
		(layer "F.Cu")
		(net "SMB_VR_SENSOR_3V3AUX_SDA")
	)
	(segment
		(start 271.928082 -123.86437)
		(end 271.485106 -123.86437)
		(width 0.10668)
		(layer "F.Cu")
		(net "SMB_VR_SENSOR_3V3AUX_SDA")
	)
	(via
		(at 175.886364 -9.1313)
		(size 0.508)
		(drill 0.254)
		(layers "F.Cu" "B.Cu")
		(net "SMB_VR_SENSOR_3V3AUX_SDA")
	)
	(via
		(at 272.21434 -124.150628)
		(size 0.508)
		(drill 0.254)
		(layers "F.Cu" "B.Cu")
		(net "SMB_VR_SENSOR_3V3AUX_SDA")
	)
	(segment
		(start 175.886364 -9.74725)
		(end 175.886364 -9.1313)
		(width 0.10668)
		(layer "B.Cu")
		(net "SMB_VR_SENSOR_3V3AUX_SDA")
	)
	(segment
		(start 267.036042 -63.809118)
		(end 272.686018 -63.809118)
		(width 0.11684)
		(layer "In4.Cu")
		(net "SMB_VR_SENSOR_3V3AUX_SDA")
	)
	(segment
		(start 206.24546 -30.622748)
		(end 211.5693 -35.946588)
		(width 0.11684)
		(layer "In4.Cu")
		(net "SMB_VR_SENSOR_3V3AUX_SDA")
	)
	(segment
		(start 276.721824 -119.49049)
		(end 275.754846 -119.49049)
		(width 0.11684)
		(layer "In4.Cu")
		(net "SMB_VR_SENSOR_3V3AUX_SDA")
	)
	(segment
		(start 271.743932 -123.68022)
		(end 272.21434 -124.150628)
		(width 0.11684)
		(layer "In4.Cu")
		(net "SMB_VR_SENSOR_3V3AUX_SDA")
	)
	(segment
		(start 277.072344 -112.199166)
		(end 277.072344 -119.13997)
		(width 0.11684)
		(layer "In4.Cu")
		(net "SMB_VR_SENSOR_3V3AUX_SDA")
	)
	(segment
		(start 206.24546 -27.800808)
		(end 206.24546 -30.622748)
		(width 0.11684)
		(layer "In4.Cu")
		(net "SMB_VR_SENSOR_3V3AUX_SDA")
	)
	(segment
		(start 194.942206 -14.50086)
		(end 195.17741 -14.736064)
		(width 0.11684)
		(layer "In4.Cu")
		(net "SMB_VR_SENSOR_3V3AUX_SDA")
	)
	(segment
		(start 216.872058 -47.335186)
		(end 216.872058 -50.833528)
		(width 0.11684)
		(layer "In4.Cu")
		(net "SMB_VR_SENSOR_3V3AUX_SDA")
	)
	(segment
		(start 208.8388 -25.207468)
		(end 206.24546 -27.800808)
		(width 0.11684)
		(layer "In4.Cu")
		(net "SMB_VR_SENSOR_3V3AUX_SDA")
	)
	(segment
		(start 182.570374 -10.726928)
		(end 184.25795 -12.414504)
		(width 0.11684)
		(layer "In4.Cu")
		(net "SMB_VR_SENSOR_3V3AUX_SDA")
	)
	(segment
		(start 281.252168 -72.375268)
		(end 281.252168 -108.019342)
		(width 0.11684)
		(layer "In4.Cu")
		(net "SMB_VR_SENSOR_3V3AUX_SDA")
	)
	(segment
		(start 188.998098 -13.908532)
		(end 190.406274 -13.908532)
		(width 0.11684)
		(layer "In4.Cu")
		(net "SMB_VR_SENSOR_3V3AUX_SDA")
	)
	(segment
		(start 211.5693 -35.946588)
		(end 211.5693 -38.631368)
		(width 0.11684)
		(layer "In4.Cu")
		(net "SMB_VR_SENSOR_3V3AUX_SDA")
	)
	(segment
		(start 182.006748 -10.726928)
		(end 182.570374 -10.726928)
		(width 0.11684)
		(layer "In4.Cu")
		(net "SMB_VR_SENSOR_3V3AUX_SDA")
	)
	(segment
		(start 190.406274 -13.908532)
		(end 190.998602 -14.50086)
		(width 0.11684)
		(layer "In4.Cu")
		(net "SMB_VR_SENSOR_3V3AUX_SDA")
	)
	(segment
		(start 216.872058 -50.833528)
		(end 231.80929 -65.77076)
		(width 0.11684)
		(layer "In4.Cu")
		(net "SMB_VR_SENSOR_3V3AUX_SDA")
	)
	(segment
		(start 184.25795 -12.414504)
		(end 187.50407 -12.414504)
		(width 0.11684)
		(layer "In4.Cu")
		(net "SMB_VR_SENSOR_3V3AUX_SDA")
	)
	(segment
		(start 254.155194 -67.233038)
		(end 263.612122 -67.233038)
		(width 0.11684)
		(layer "In4.Cu")
		(net "SMB_VR_SENSOR_3V3AUX_SDA")
	)
	(segment
		(start 204.707236 -14.736064)
		(end 208.8388 -18.867628)
		(width 0.11684)
		(layer "In4.Cu")
		(net "SMB_VR_SENSOR_3V3AUX_SDA")
	)
	(segment
		(start 272.686018 -63.809118)
		(end 281.252168 -72.375268)
		(width 0.11684)
		(layer "In4.Cu")
		(net "SMB_VR_SENSOR_3V3AUX_SDA")
	)
	(segment
		(start 178.741832 -11.275314)
		(end 181.458362 -11.275314)
		(width 0.11684)
		(layer "In4.Cu")
		(net "SMB_VR_SENSOR_3V3AUX_SDA")
	)
	(segment
		(start 281.252168 -108.019342)
		(end 277.072344 -112.199166)
		(width 0.11684)
		(layer "In4.Cu")
		(net "SMB_VR_SENSOR_3V3AUX_SDA")
	)
	(segment
		(start 277.072344 -119.13997)
		(end 276.721824 -119.49049)
		(width 0.11684)
		(layer "In4.Cu")
		(net "SMB_VR_SENSOR_3V3AUX_SDA")
	)
	(segment
		(start 211.5693 -38.631368)
		(end 213.7664 -40.828468)
		(width 0.11684)
		(layer "In4.Cu")
		(net "SMB_VR_SENSOR_3V3AUX_SDA")
	)
	(segment
		(start 271.743932 -122.635772)
		(end 271.743932 -123.68022)
		(width 0.11684)
		(layer "In4.Cu")
		(net "SMB_VR_SENSOR_3V3AUX_SDA")
	)
	(segment
		(start 275.754846 -119.49049)
		(end 272.903442 -122.341894)
		(width 0.11684)
		(layer "In4.Cu")
		(net "SMB_VR_SENSOR_3V3AUX_SDA")
	)
	(segment
		(start 190.998602 -14.50086)
		(end 194.942206 -14.50086)
		(width 0.11684)
		(layer "In4.Cu")
		(net "SMB_VR_SENSOR_3V3AUX_SDA")
	)
	(segment
		(start 213.7664 -40.828468)
		(end 213.7664 -44.229528)
		(width 0.11684)
		(layer "In4.Cu")
		(net "SMB_VR_SENSOR_3V3AUX_SDA")
	)
	(segment
		(start 176.597818 -9.1313)
		(end 178.741832 -11.275314)
		(width 0.11684)
		(layer "In4.Cu")
		(net "SMB_VR_SENSOR_3V3AUX_SDA")
	)
	(segment
		(start 195.17741 -14.736064)
		(end 204.707236 -14.736064)
		(width 0.11684)
		(layer "In4.Cu")
		(net "SMB_VR_SENSOR_3V3AUX_SDA")
	)
	(segment
		(start 272.903442 -122.341894)
		(end 272.03781 -122.341894)
		(width 0.11684)
		(layer "In4.Cu")
		(net "SMB_VR_SENSOR_3V3AUX_SDA")
	)
	(segment
		(start 213.7664 -44.229528)
		(end 216.872058 -47.335186)
		(width 0.11684)
		(layer "In4.Cu")
		(net "SMB_VR_SENSOR_3V3AUX_SDA")
	)
	(segment
		(start 181.458362 -11.275314)
		(end 182.006748 -10.726928)
		(width 0.11684)
		(layer "In4.Cu")
		(net "SMB_VR_SENSOR_3V3AUX_SDA")
	)
	(segment
		(start 252.692916 -65.77076)
		(end 254.155194 -67.233038)
		(width 0.11684)
		(layer "In4.Cu")
		(net "SMB_VR_SENSOR_3V3AUX_SDA")
	)
	(segment
		(start 272.03781 -122.341894)
		(end 271.743932 -122.635772)
		(width 0.11684)
		(layer "In4.Cu")
		(net "SMB_VR_SENSOR_3V3AUX_SDA")
	)
	(segment
		(start 263.612122 -67.233038)
		(end 267.036042 -63.809118)
		(width 0.11684)
		(layer "In4.Cu")
		(net "SMB_VR_SENSOR_3V3AUX_SDA")
	)
	(segment
		(start 175.886364 -9.1313)
		(end 176.597818 -9.1313)
		(width 0.11684)
		(layer "In4.Cu")
		(net "SMB_VR_SENSOR_3V3AUX_SDA")
	)
	(segment
		(start 208.8388 -18.867628)
		(end 208.8388 -25.207468)
		(width 0.11684)
		(layer "In4.Cu")
		(net "SMB_VR_SENSOR_3V3AUX_SDA")
	)
	(segment
		(start 231.80929 -65.77076)
		(end 252.692916 -65.77076)
		(width 0.11684)
		(layer "In4.Cu")
		(net "SMB_VR_SENSOR_3V3AUX_SDA")
	)
	(segment
		(start 187.50407 -12.414504)
		(end 188.998098 -13.908532)
		(width 0.11684)
		(layer "In4.Cu")
		(net "SMB_VR_SENSOR_3V3AUX_SDA")
	)
	(segment
		(start 272.246598 -122.880628)
		(end 272.95729 -122.880628)
		(width 0.10668)
		(layer "F.Cu")
		(net "SMB_VR_SENSOR_3V3AUX_SCL")
	)
	(segment
		(start 272.21434 -122.84837)
		(end 272.246598 -122.880628)
		(width 0.10668)
		(layer "F.Cu")
		(net "SMB_VR_SENSOR_3V3AUX_SCL")
	)
	(segment
		(start 271.485106 -122.84837)
		(end 272.21434 -122.84837)
		(width 0.10668)
		(layer "F.Cu")
		(net "SMB_VR_SENSOR_3V3AUX_SCL")
	)
	(via
		(at 272.21434 -122.84837)
		(size 0.508)
		(drill 0.254)
		(layers "F.Cu" "B.Cu")
		(net "SMB_VR_SENSOR_3V3AUX_SCL")
	)
	(via
		(at 177.264822 -9.1313)
		(size 0.508)
		(drill 0.254)
		(layers "F.Cu" "B.Cu")
		(net "SMB_VR_SENSOR_3V3AUX_SCL")
	)
	(segment
		(start 177.264822 -9.74725)
		(end 177.264822 -9.1313)
		(width 0.10668)
		(layer "B.Cu")
		(net "SMB_VR_SENSOR_3V3AUX_SCL")
	)
	(segment
		(start 209.26044 -25.38222)
		(end 206.6671 -27.97556)
		(width 0.11684)
		(layer "In4.Cu")
		(net "SMB_VR_SENSOR_3V3AUX_SCL")
	)
	(segment
		(start 206.6671 -27.97556)
		(end 206.6671 -30.447996)
		(width 0.11684)
		(layer "In4.Cu")
		(net "SMB_VR_SENSOR_3V3AUX_SCL")
	)
	(segment
		(start 276.491446 -120.31726)
		(end 275.633942 -120.31726)
		(width 0.11684)
		(layer "In4.Cu")
		(net "SMB_VR_SENSOR_3V3AUX_SCL")
	)
	(segment
		(start 218.033092 -47.899828)
		(end 218.033092 -51.39817)
		(width 0.11684)
		(layer "In4.Cu")
		(net "SMB_VR_SENSOR_3V3AUX_SCL")
	)
	(segment
		(start 277.493984 -115.130072)
		(end 277.493984 -119.314722)
		(width 0.11684)
		(layer "In4.Cu")
		(net "SMB_VR_SENSOR_3V3AUX_SCL")
	)
	(segment
		(start 277.493984 -112.373918)
		(end 277.493984 -113.623852)
		(width 0.11684)
		(layer "In4.Cu")
		(net "SMB_VR_SENSOR_3V3AUX_SCL")
	)
	(segment
		(start 278.38654 -113.857532)
		(end 278.38654 -114.048032)
		(width 0.11684)
		(layer "In4.Cu")
		(net "SMB_VR_SENSOR_3V3AUX_SCL")
	)
	(segment
		(start 277.493984 -114.472212)
		(end 277.610824 -114.589052)
		(width 0.11684)
		(layer "In4.Cu")
		(net "SMB_VR_SENSOR_3V3AUX_SCL")
	)
	(segment
		(start 182.745126 -10.305288)
		(end 184.404762 -11.964924)
		(width 0.11684)
		(layer "In4.Cu")
		(net "SMB_VR_SENSOR_3V3AUX_SCL")
	)
	(segment
		(start 177.264822 -9.1313)
		(end 178.987196 -10.853674)
		(width 0.11684)
		(layer "In4.Cu")
		(net "SMB_VR_SENSOR_3V3AUX_SCL")
	)
	(segment
		(start 195.348606 -14.06906)
		(end 195.59397 -14.314424)
		(width 0.11684)
		(layer "In4.Cu")
		(net "SMB_VR_SENSOR_3V3AUX_SCL")
	)
	(segment
		(start 254.50927 -66.811398)
		(end 263.296146 -66.811398)
		(width 0.11684)
		(layer "In4.Cu")
		(net "SMB_VR_SENSOR_3V3AUX_SCL")
	)
	(segment
		(start 195.59397 -14.314424)
		(end 204.881988 -14.314424)
		(width 0.11684)
		(layer "In4.Cu")
		(net "SMB_VR_SENSOR_3V3AUX_SCL")
	)
	(segment
		(start 281.673808 -72.200516)
		(end 281.673808 -108.194094)
		(width 0.11684)
		(layer "In4.Cu")
		(net "SMB_VR_SENSOR_3V3AUX_SCL")
	)
	(segment
		(start 181.831996 -10.305288)
		(end 182.745126 -10.305288)
		(width 0.11684)
		(layer "In4.Cu")
		(net "SMB_VR_SENSOR_3V3AUX_SCL")
	)
	(segment
		(start 278.2697 -114.164872)
		(end 277.610824 -114.164872)
		(width 0.11684)
		(layer "In4.Cu")
		(net "SMB_VR_SENSOR_3V3AUX_SCL")
	)
	(segment
		(start 218.033092 -51.39817)
		(end 231.984042 -65.34912)
		(width 0.11684)
		(layer "In4.Cu")
		(net "SMB_VR_SENSOR_3V3AUX_SCL")
	)
	(segment
		(start 191.205866 -14.06906)
		(end 195.348606 -14.06906)
		(width 0.11684)
		(layer "In4.Cu")
		(net "SMB_VR_SENSOR_3V3AUX_SCL")
	)
	(segment
		(start 204.881988 -14.314424)
		(end 209.26044 -18.692876)
		(width 0.11684)
		(layer "In4.Cu")
		(net "SMB_VR_SENSOR_3V3AUX_SCL")
	)
	(segment
		(start 184.404762 -11.964924)
		(end 187.650882 -11.964924)
		(width 0.11684)
		(layer "In4.Cu")
		(net "SMB_VR_SENSOR_3V3AUX_SCL")
	)
	(segment
		(start 206.6671 -30.447996)
		(end 211.99094 -35.771836)
		(width 0.11684)
		(layer "In4.Cu")
		(net "SMB_VR_SENSOR_3V3AUX_SCL")
	)
	(segment
		(start 187.650882 -11.964924)
		(end 189.17285 -13.486892)
		(width 0.11684)
		(layer "In4.Cu")
		(net "SMB_VR_SENSOR_3V3AUX_SCL")
	)
	(segment
		(start 278.38654 -114.048032)
		(end 278.2697 -114.164872)
		(width 0.11684)
		(layer "In4.Cu")
		(net "SMB_VR_SENSOR_3V3AUX_SCL")
	)
	(segment
		(start 211.99094 -38.456616)
		(end 214.18804 -40.653716)
		(width 0.11684)
		(layer "In4.Cu")
		(net "SMB_VR_SENSOR_3V3AUX_SCL")
	)
	(segment
		(start 278.2697 -115.013232)
		(end 277.610824 -115.013232)
		(width 0.11684)
		(layer "In4.Cu")
		(net "SMB_VR_SENSOR_3V3AUX_SCL")
	)
	(segment
		(start 278.38654 -114.896392)
		(end 278.2697 -115.013232)
		(width 0.11684)
		(layer "In4.Cu")
		(net "SMB_VR_SENSOR_3V3AUX_SCL")
	)
	(segment
		(start 272.86077 -63.387478)
		(end 281.673808 -72.200516)
		(width 0.11684)
		(layer "In4.Cu")
		(net "SMB_VR_SENSOR_3V3AUX_SCL")
	)
	(segment
		(start 277.493984 -119.314722)
		(end 276.491446 -120.31726)
		(width 0.11684)
		(layer "In4.Cu")
		(net "SMB_VR_SENSOR_3V3AUX_SCL")
	)
	(segment
		(start 277.610824 -115.013232)
		(end 277.493984 -115.130072)
		(width 0.11684)
		(layer "In4.Cu")
		(net "SMB_VR_SENSOR_3V3AUX_SCL")
	)
	(segment
		(start 277.493984 -113.623852)
		(end 277.610824 -113.740692)
		(width 0.11684)
		(layer "In4.Cu")
		(net "SMB_VR_SENSOR_3V3AUX_SCL")
	)
	(segment
		(start 277.493984 -114.281712)
		(end 277.493984 -114.472212)
		(width 0.11684)
		(layer "In4.Cu")
		(net "SMB_VR_SENSOR_3V3AUX_SCL")
	)
	(segment
		(start 266.720066 -63.387478)
		(end 272.86077 -63.387478)
		(width 0.11684)
		(layer "In4.Cu")
		(net "SMB_VR_SENSOR_3V3AUX_SCL")
	)
	(segment
		(start 281.673808 -108.194094)
		(end 277.493984 -112.373918)
		(width 0.11684)
		(layer "In4.Cu")
		(net "SMB_VR_SENSOR_3V3AUX_SCL")
	)
	(segment
		(start 209.26044 -18.692876)
		(end 209.26044 -25.38222)
		(width 0.11684)
		(layer "In4.Cu")
		(net "SMB_VR_SENSOR_3V3AUX_SCL")
	)
	(segment
		(start 214.18804 -44.054776)
		(end 218.033092 -47.899828)
		(width 0.11684)
		(layer "In4.Cu")
		(net "SMB_VR_SENSOR_3V3AUX_SCL")
	)
	(segment
		(start 273.102832 -122.84837)
		(end 272.21434 -122.84837)
		(width 0.11684)
		(layer "In4.Cu")
		(net "SMB_VR_SENSOR_3V3AUX_SCL")
	)
	(segment
		(start 211.99094 -35.771836)
		(end 211.99094 -38.456616)
		(width 0.11684)
		(layer "In4.Cu")
		(net "SMB_VR_SENSOR_3V3AUX_SCL")
	)
	(segment
		(start 263.296146 -66.811398)
		(end 266.720066 -63.387478)
		(width 0.11684)
		(layer "In4.Cu")
		(net "SMB_VR_SENSOR_3V3AUX_SCL")
	)
	(segment
		(start 277.610824 -114.589052)
		(end 278.2697 -114.589052)
		(width 0.11684)
		(layer "In4.Cu")
		(net "SMB_VR_SENSOR_3V3AUX_SCL")
	)
	(segment
		(start 214.18804 -40.653716)
		(end 214.18804 -44.054776)
		(width 0.11684)
		(layer "In4.Cu")
		(net "SMB_VR_SENSOR_3V3AUX_SCL")
	)
	(segment
		(start 277.610824 -114.164872)
		(end 277.493984 -114.281712)
		(width 0.11684)
		(layer "In4.Cu")
		(net "SMB_VR_SENSOR_3V3AUX_SCL")
	)
	(segment
		(start 275.633942 -120.31726)
		(end 273.102832 -122.84837)
		(width 0.11684)
		(layer "In4.Cu")
		(net "SMB_VR_SENSOR_3V3AUX_SCL")
	)
	(segment
		(start 277.610824 -113.740692)
		(end 278.2697 -113.740692)
		(width 0.11684)
		(layer "In4.Cu")
		(net "SMB_VR_SENSOR_3V3AUX_SCL")
	)
	(segment
		(start 178.987196 -10.853674)
		(end 181.28361 -10.853674)
		(width 0.11684)
		(layer "In4.Cu")
		(net "SMB_VR_SENSOR_3V3AUX_SCL")
	)
	(segment
		(start 278.2697 -114.589052)
		(end 278.38654 -114.705892)
		(width 0.11684)
		(layer "In4.Cu")
		(net "SMB_VR_SENSOR_3V3AUX_SCL")
	)
	(segment
		(start 189.17285 -13.486892)
		(end 190.623698 -13.486892)
		(width 0.11684)
		(layer "In4.Cu")
		(net "SMB_VR_SENSOR_3V3AUX_SCL")
	)
	(segment
		(start 231.984042 -65.34912)
		(end 253.046992 -65.34912)
		(width 0.11684)
		(layer "In4.Cu")
		(net "SMB_VR_SENSOR_3V3AUX_SCL")
	)
	(segment
		(start 278.2697 -113.740692)
		(end 278.38654 -113.857532)
		(width 0.11684)
		(layer "In4.Cu")
		(net "SMB_VR_SENSOR_3V3AUX_SCL")
	)
	(segment
		(start 253.046992 -65.34912)
		(end 254.50927 -66.811398)
		(width 0.11684)
		(layer "In4.Cu")
		(net "SMB_VR_SENSOR_3V3AUX_SCL")
	)
	(segment
		(start 190.623698 -13.486892)
		(end 191.205866 -14.06906)
		(width 0.11684)
		(layer "In4.Cu")
		(net "SMB_VR_SENSOR_3V3AUX_SCL")
	)
	(segment
		(start 181.28361 -10.853674)
		(end 181.831996 -10.305288)
		(width 0.11684)
		(layer "In4.Cu")
		(net "SMB_VR_SENSOR_3V3AUX_SCL")
	)
	(segment
		(start 278.38654 -114.705892)
		(end 278.38654 -114.896392)
		(width 0.11684)
		(layer "In4.Cu")
		(net "SMB_VR_SENSOR_3V3AUX_SCL")
	)
	(segment
		(start 22.07895 -367.919)
		(end 21.463 -367.919)
		(width 0.10668)
		(layer "F.Cu")
		(net "SMB_VR_3V3STBY_SDA")
	)
	(via
		(at 12.954 -340.1568)
		(size 0.508)
		(drill 0.254)
		(layers "F.Cu" "B.Cu")
		(net "SMB_VR_3V3STBY_SDA")
	)
	(via
		(at 12.12469 -402.56079)
		(size 0.508)
		(drill 0.254)
		(layers "F.Cu" "B.Cu")
		(net "SMB_VR_3V3STBY_SDA")
	)
	(via
		(at 21.463 -367.919)
		(size 0.508)
		(drill 0.254)
		(layers "F.Cu" "B.Cu")
		(net "SMB_VR_3V3STBY_SDA")
	)
	(via
		(at 93.636338 -139.807188)
		(size 0.508)
		(drill 0.254)
		(layers "F.Cu" "B.Cu")
		(net "SMB_VR_3V3STBY_SDA")
	)
	(via
		(at 21.345652 -152.967182)
		(size 0.508)
		(drill 0.254)
		(layers "F.Cu" "B.Cu")
		(net "SMB_VR_3V3STBY_SDA")
	)
	(segment
		(start 12.403074 -402.839174)
		(end 12.12469 -402.56079)
		(width 0.10668)
		(layer "B.Cu")
		(net "SMB_VR_3V3STBY_SDA")
	)
	(segment
		(start 13.2588 -402.839174)
		(end 12.403074 -402.839174)
		(width 0.10668)
		(layer "B.Cu")
		(net "SMB_VR_3V3STBY_SDA")
	)
	(segment
		(start 91.987878 -139.667742)
		(end 91.987878 -139.78636)
		(width 0.10668)
		(layer "B.Cu")
		(net "SMB_VR_3V3STBY_SDA")
	)
	(segment
		(start 93.02115 -139.192)
		(end 92.46362 -139.192)
		(width 0.10668)
		(layer "B.Cu")
		(net "SMB_VR_3V3STBY_SDA")
	)
	(segment
		(start 93.02115 -139.192)
		(end 93.636338 -139.807188)
		(width 0.10668)
		(layer "B.Cu")
		(net "SMB_VR_3V3STBY_SDA")
	)
	(segment
		(start 92.46362 -139.192)
		(end 91.987878 -139.667742)
		(width 0.10668)
		(layer "B.Cu")
		(net "SMB_VR_3V3STBY_SDA")
	)
	(segment
		(start 23.241 -353.332542)
		(end 23.241 -350.53016)
		(width 0.11684)
		(layer "In2.Cu")
		(net "SMB_VR_3V3STBY_SDA")
	)
	(segment
		(start 23.241 -350.53016)
		(end 24.0284 -348.628716)
		(width 0.11684)
		(layer "In2.Cu")
		(net "SMB_VR_3V3STBY_SDA")
	)
	(segment
		(start 17.907 -340.1568)
		(end 12.954 -340.1568)
		(width 0.11684)
		(layer "In2.Cu")
		(net "SMB_VR_3V3STBY_SDA")
	)
	(segment
		(start 22.072092 -365.441992)
		(end 19.93519 -363.30509)
		(width 0.11684)
		(layer "In2.Cu")
		(net "SMB_VR_3V3STBY_SDA")
	)
	(segment
		(start 22.072092 -367.309908)
		(end 22.072092 -365.441992)
		(width 0.11684)
		(layer "In2.Cu")
		(net "SMB_VR_3V3STBY_SDA")
	)
	(segment
		(start 24.0284 -346.2782)
		(end 17.907 -340.1568)
		(width 0.11684)
		(layer "In2.Cu")
		(net "SMB_VR_3V3STBY_SDA")
	)
	(segment
		(start 19.93519 -363.30509)
		(end 19.93519 -356.638352)
		(width 0.11684)
		(layer "In2.Cu")
		(net "SMB_VR_3V3STBY_SDA")
	)
	(segment
		(start 24.0284 -348.628716)
		(end 24.0284 -346.2782)
		(width 0.11684)
		(layer "In2.Cu")
		(net "SMB_VR_3V3STBY_SDA")
	)
	(segment
		(start 19.93519 -356.638352)
		(end 23.241 -353.332542)
		(width 0.11684)
		(layer "In2.Cu")
		(net "SMB_VR_3V3STBY_SDA")
	)
	(segment
		(start 21.463 -367.919)
		(end 22.072092 -367.309908)
		(width 0.11684)
		(layer "In2.Cu")
		(net "SMB_VR_3V3STBY_SDA")
	)
	(segment
		(start 8.155686 -168.053004)
		(end 7.306056 -168.902634)
		(width 0.11684)
		(layer "In4.Cu")
		(net "SMB_VR_3V3STBY_SDA")
	)
	(segment
		(start 21.345652 -152.967182)
		(end 19.758406 -152.967182)
		(width 0.11684)
		(layer "In4.Cu")
		(net "SMB_VR_3V3STBY_SDA")
	)
	(segment
		(start 17.886934 -163.732464)
		(end 13.566394 -168.053004)
		(width 0.11684)
		(layer "In4.Cu")
		(net "SMB_VR_3V3STBY_SDA")
	)
	(segment
		(start 17.886934 -154.838654)
		(end 17.886934 -163.732464)
		(width 0.11684)
		(layer "In4.Cu")
		(net "SMB_VR_3V3STBY_SDA")
	)
	(segment
		(start 13.566394 -168.053004)
		(end 8.155686 -168.053004)
		(width 0.11684)
		(layer "In4.Cu")
		(net "SMB_VR_3V3STBY_SDA")
	)
	(segment
		(start 7.306056 -168.902634)
		(end 7.306056 -334.508856)
		(width 0.11684)
		(layer "In4.Cu")
		(net "SMB_VR_3V3STBY_SDA")
	)
	(segment
		(start 19.758406 -152.967182)
		(end 17.886934 -154.838654)
		(width 0.11684)
		(layer "In4.Cu")
		(net "SMB_VR_3V3STBY_SDA")
	)
	(segment
		(start 7.306056 -334.508856)
		(end 12.954 -340.1568)
		(width 0.11684)
		(layer "In4.Cu")
		(net "SMB_VR_3V3STBY_SDA")
	)
	(segment
		(start 11.205972 -393.73683)
		(end 10.165334 -394.777468)
		(width 0.11684)
		(layer "In11.Cu")
		(net "SMB_VR_3V3STBY_SDA")
	)
	(segment
		(start 11.442446 -402.56079)
		(end 12.12469 -402.56079)
		(width 0.11684)
		(layer "In11.Cu")
		(net "SMB_VR_3V3STBY_SDA")
	)
	(segment
		(start 5.499862 -384.14071)
		(end 6.913372 -385.55422)
		(width 0.11684)
		(layer "In11.Cu")
		(net "SMB_VR_3V3STBY_SDA")
	)
	(segment
		(start 19.270726 -366.095026)
		(end 18.7579 -365.882682)
		(width 0.11684)
		(layer "In11.Cu")
		(net "SMB_VR_3V3STBY_SDA")
	)
	(segment
		(start 21.0947 -367.919)
		(end 19.270726 -366.095026)
		(width 0.11684)
		(layer "In11.Cu")
		(net "SMB_VR_3V3STBY_SDA")
	)
	(segment
		(start 8.87857 -365.882682)
		(end 5.499862 -369.26139)
		(width 0.11684)
		(layer "In11.Cu")
		(net "SMB_VR_3V3STBY_SDA")
	)
	(segment
		(start 6.913372 -385.55422)
		(end 8.696706 -385.55422)
		(width 0.11684)
		(layer "In11.Cu")
		(net "SMB_VR_3V3STBY_SDA")
	)
	(segment
		(start 5.499862 -369.26139)
		(end 5.499862 -384.14071)
		(width 0.11684)
		(layer "In11.Cu")
		(net "SMB_VR_3V3STBY_SDA")
	)
	(segment
		(start 11.205972 -388.063486)
		(end 11.205972 -393.73683)
		(width 0.11684)
		(layer "In11.Cu")
		(net "SMB_VR_3V3STBY_SDA")
	)
	(segment
		(start 10.165334 -401.283678)
		(end 11.442446 -402.56079)
		(width 0.11684)
		(layer "In11.Cu")
		(net "SMB_VR_3V3STBY_SDA")
	)
	(segment
		(start 18.7579 -365.882682)
		(end 8.87857 -365.882682)
		(width 0.11684)
		(layer "In11.Cu")
		(net "SMB_VR_3V3STBY_SDA")
	)
	(segment
		(start 8.696706 -385.55422)
		(end 11.205972 -388.063486)
		(width 0.11684)
		(layer "In11.Cu")
		(net "SMB_VR_3V3STBY_SDA")
	)
	(segment
		(start 10.165334 -394.777468)
		(end 10.165334 -401.283678)
		(width 0.11684)
		(layer "In11.Cu")
		(net "SMB_VR_3V3STBY_SDA")
	)
	(segment
		(start 21.463 -367.919)
		(end 21.0947 -367.919)
		(width 0.11684)
		(layer "In11.Cu")
		(net "SMB_VR_3V3STBY_SDA")
	)
	(segment
		(start 91.06662 -140.38326)
		(end 92.071444 -139.378436)
		(width 0.11684)
		(layer "In13.Cu")
		(net "SMB_VR_3V3STBY_SDA")
	)
	(segment
		(start 21.839936 -150.305516)
		(end 31.762192 -140.38326)
		(width 0.11684)
		(layer "In13.Cu")
		(net "SMB_VR_3V3STBY_SDA")
	)
	(segment
		(start 31.762192 -140.38326)
		(end 91.06662 -140.38326)
		(width 0.11684)
		(layer "In13.Cu")
		(net "SMB_VR_3V3STBY_SDA")
	)
	(segment
		(start 92.071444 -139.378436)
		(end 93.207586 -139.378436)
		(width 0.11684)
		(layer "In13.Cu")
		(net "SMB_VR_3V3STBY_SDA")
	)
	(segment
		(start 21.345652 -152.967182)
		(end 21.839936 -152.472898)
		(width 0.11684)
		(layer "In13.Cu")
		(net "SMB_VR_3V3STBY_SDA")
	)
	(segment
		(start 21.839936 -152.472898)
		(end 21.839936 -150.305516)
		(width 0.11684)
		(layer "In13.Cu")
		(net "SMB_VR_3V3STBY_SDA")
	)
	(segment
		(start 93.207586 -139.378436)
		(end 93.636338 -139.807188)
		(width 0.11684)
		(layer "In13.Cu")
		(net "SMB_VR_3V3STBY_SDA")
	)
	(segment
		(start 22.07895 -366.903)
		(end 21.463 -366.903)
		(width 0.10668)
		(layer "F.Cu")
		(net "SMB_VR_3V3STBY_SCL")
	)
	(via
		(at 21.350478 -152.240488)
		(size 0.508)
		(drill 0.254)
		(layers "F.Cu" "B.Cu")
		(net "SMB_VR_3V3STBY_SCL")
	)
	(via
		(at 21.463 -366.903)
		(size 0.508)
		(drill 0.254)
		(layers "F.Cu" "B.Cu")
		(net "SMB_VR_3V3STBY_SCL")
	)
	(via
		(at 13.6398 -340.9442)
		(size 0.508)
		(drill 0.254)
		(layers "F.Cu" "B.Cu")
		(net "SMB_VR_3V3STBY_SCL")
	)
	(via
		(at 12.185142 -403.855174)
		(size 0.508)
		(drill 0.254)
		(layers "F.Cu" "B.Cu")
		(net "SMB_VR_3V3STBY_SCL")
	)
	(via
		(at 89.043764 -137.638028)
		(size 0.508)
		(drill 0.254)
		(layers "F.Cu" "B.Cu")
		(net "SMB_VR_3V3STBY_SCL")
	)
	(segment
		(start 89.285318 -137.396474)
		(end 89.043764 -137.638028)
		(width 0.10668)
		(layer "B.Cu")
		(net "SMB_VR_3V3STBY_SCL")
	)
	(segment
		(start 93.02115 -138.176)
		(end 92.67444 -138.176)
		(width 0.10668)
		(layer "B.Cu")
		(net "SMB_VR_3V3STBY_SCL")
	)
	(segment
		(start 13.2588 -403.855174)
		(end 12.185142 -403.855174)
		(width 0.10668)
		(layer "B.Cu")
		(net "SMB_VR_3V3STBY_SCL")
	)
	(segment
		(start 91.987878 -138.00836)
		(end 91.987878 -137.7061)
		(width 0.10668)
		(layer "B.Cu")
		(net "SMB_VR_3V3STBY_SCL")
	)
	(segment
		(start 92.67444 -138.176)
		(end 92.5068 -138.00836)
		(width 0.10668)
		(layer "B.Cu")
		(net "SMB_VR_3V3STBY_SCL")
	)
	(segment
		(start 91.678252 -137.396474)
		(end 89.285318 -137.396474)
		(width 0.10668)
		(layer "B.Cu")
		(net "SMB_VR_3V3STBY_SCL")
	)
	(segment
		(start 92.5068 -138.00836)
		(end 91.987878 -138.00836)
		(width 0.10668)
		(layer "B.Cu")
		(net "SMB_VR_3V3STBY_SCL")
	)
	(segment
		(start 91.987878 -137.7061)
		(end 91.678252 -137.396474)
		(width 0.10668)
		(layer "B.Cu")
		(net "SMB_VR_3V3STBY_SCL")
	)
	(segment
		(start 22.7711 -353.192588)
		(end 22.7711 -350.50349)
		(width 0.11684)
		(layer "In2.Cu")
		(net "SMB_VR_3V3STBY_SCL")
	)
	(segment
		(start 23.597362 -346.456762)
		(end 18.0848 -340.9442)
		(width 0.11684)
		(layer "In2.Cu")
		(net "SMB_VR_3V3STBY_SCL")
	)
	(segment
		(start 22.7711 -350.50349)
		(end 23.597362 -348.508574)
		(width 0.11684)
		(layer "In2.Cu")
		(net "SMB_VR_3V3STBY_SCL")
	)
	(segment
		(start 23.597362 -348.508574)
		(end 23.597362 -346.456762)
		(width 0.11684)
		(layer "In2.Cu")
		(net "SMB_VR_3V3STBY_SCL")
	)
	(segment
		(start 21.463 -366.903)
		(end 18.91411 -364.35411)
		(width 0.11684)
		(layer "In2.Cu")
		(net "SMB_VR_3V3STBY_SCL")
	)
	(segment
		(start 18.91411 -357.049578)
		(end 22.7711 -353.192588)
		(width 0.11684)
		(layer "In2.Cu")
		(net "SMB_VR_3V3STBY_SCL")
	)
	(segment
		(start 18.91411 -364.35411)
		(end 18.91411 -357.049578)
		(width 0.11684)
		(layer "In2.Cu")
		(net "SMB_VR_3V3STBY_SCL")
	)
	(segment
		(start 18.0848 -340.9442)
		(end 13.6398 -340.9442)
		(width 0.11684)
		(layer "In2.Cu")
		(net "SMB_VR_3V3STBY_SCL")
	)
	(segment
		(start 6.865112 -168.719754)
		(end 6.865112 -334.894936)
		(width 0.11684)
		(layer "In4.Cu")
		(net "SMB_VR_3V3STBY_SCL")
	)
	(segment
		(start 19.835368 -152.240488)
		(end 17.44599 -154.629866)
		(width 0.11684)
		(layer "In4.Cu")
		(net "SMB_VR_3V3STBY_SCL")
	)
	(segment
		(start 17.44599 -163.549584)
		(end 13.383514 -167.61206)
		(width 0.11684)
		(layer "In4.Cu")
		(net "SMB_VR_3V3STBY_SCL")
	)
	(segment
		(start 13.383514 -167.61206)
		(end 7.972806 -167.61206)
		(width 0.11684)
		(layer "In4.Cu")
		(net "SMB_VR_3V3STBY_SCL")
	)
	(segment
		(start 7.972806 -167.61206)
		(end 6.865112 -168.719754)
		(width 0.11684)
		(layer "In4.Cu")
		(net "SMB_VR_3V3STBY_SCL")
	)
	(segment
		(start 21.350478 -152.240488)
		(end 19.835368 -152.240488)
		(width 0.11684)
		(layer "In4.Cu")
		(net "SMB_VR_3V3STBY_SCL")
	)
	(segment
		(start 12.914376 -340.9442)
		(end 13.6398 -340.9442)
		(width 0.11684)
		(layer "In4.Cu")
		(net "SMB_VR_3V3STBY_SCL")
	)
	(segment
		(start 17.44599 -154.629866)
		(end 17.44599 -163.549584)
		(width 0.11684)
		(layer "In4.Cu")
		(net "SMB_VR_3V3STBY_SCL")
	)
	(segment
		(start 6.865112 -334.894936)
		(end 12.914376 -340.9442)
		(width 0.11684)
		(layer "In4.Cu")
		(net "SMB_VR_3V3STBY_SCL")
	)
	(segment
		(start 19.545554 -365.74857)
		(end 18.834354 -365.45393)
		(width 0.11684)
		(layer "In11.Cu")
		(net "SMB_VR_3V3STBY_SCL")
	)
	(segment
		(start 8.228584 -385.97967)
		(end 10.766552 -388.517638)
		(width 0.11684)
		(layer "In11.Cu")
		(net "SMB_VR_3V3STBY_SCL")
	)
	(segment
		(start 10.766552 -393.569698)
		(end 9.736582 -394.599668)
		(width 0.11684)
		(layer "In11.Cu")
		(net "SMB_VR_3V3STBY_SCL")
	)
	(segment
		(start 20.699984 -366.903)
		(end 19.545554 -365.74857)
		(width 0.11684)
		(layer "In11.Cu")
		(net "SMB_VR_3V3STBY_SCL")
	)
	(segment
		(start 4.223766 -383.52222)
		(end 6.681216 -385.97967)
		(width 0.11684)
		(layer "In11.Cu")
		(net "SMB_VR_3V3STBY_SCL")
	)
	(segment
		(start 8.70077 -365.45393)
		(end 4.223766 -369.930934)
		(width 0.11684)
		(layer "In11.Cu")
		(net "SMB_VR_3V3STBY_SCL")
	)
	(segment
		(start 21.463 -366.903)
		(end 20.699984 -366.903)
		(width 0.11684)
		(layer "In11.Cu")
		(net "SMB_VR_3V3STBY_SCL")
	)
	(segment
		(start 12.060174 -403.855174)
		(end 12.185142 -403.855174)
		(width 0.11684)
		(layer "In11.Cu")
		(net "SMB_VR_3V3STBY_SCL")
	)
	(segment
		(start 4.223766 -369.930934)
		(end 4.223766 -383.52222)
		(width 0.11684)
		(layer "In11.Cu")
		(net "SMB_VR_3V3STBY_SCL")
	)
	(segment
		(start 18.834354 -365.45393)
		(end 8.70077 -365.45393)
		(width 0.11684)
		(layer "In11.Cu")
		(net "SMB_VR_3V3STBY_SCL")
	)
	(segment
		(start 9.736582 -401.531582)
		(end 12.060174 -403.855174)
		(width 0.11684)
		(layer "In11.Cu")
		(net "SMB_VR_3V3STBY_SCL")
	)
	(segment
		(start 9.736582 -394.599668)
		(end 9.736582 -401.531582)
		(width 0.11684)
		(layer "In11.Cu")
		(net "SMB_VR_3V3STBY_SCL")
	)
	(segment
		(start 6.681216 -385.97967)
		(end 8.228584 -385.97967)
		(width 0.11684)
		(layer "In11.Cu")
		(net "SMB_VR_3V3STBY_SCL")
	)
	(segment
		(start 10.766552 -388.517638)
		(end 10.766552 -393.569698)
		(width 0.11684)
		(layer "In11.Cu")
		(net "SMB_VR_3V3STBY_SCL")
	)
	(segment
		(start 86.944962 -138.678666)
		(end 87.079836 -138.543792)
		(width 0.11684)
		(layer "In13.Cu")
		(net "SMB_VR_3V3STBY_SCL")
	)
	(segment
		(start 87.708486 -138.407394)
		(end 87.54491 -138.243818)
		(width 0.11684)
		(layer "In13.Cu")
		(net "SMB_VR_3V3STBY_SCL")
	)
	(segment
		(start 31.58744 -139.96162)
		(end 86.31936 -139.96162)
		(width 0.11684)
		(layer "In13.Cu")
		(net "SMB_VR_3V3STBY_SCL")
	)
	(segment
		(start 88.17356 -138.10742)
		(end 88.642952 -137.638028)
		(width 0.11684)
		(layer "In13.Cu")
		(net "SMB_VR_3V3STBY_SCL")
	)
	(segment
		(start 87.708486 -138.572494)
		(end 87.708486 -138.407394)
		(width 0.11684)
		(layer "In13.Cu")
		(net "SMB_VR_3V3STBY_SCL")
	)
	(segment
		(start 21.350478 -150.198582)
		(end 31.58744 -139.96162)
		(width 0.11684)
		(layer "In13.Cu")
		(net "SMB_VR_3V3STBY_SCL")
	)
	(segment
		(start 87.108538 -139.007342)
		(end 86.944962 -138.843766)
		(width 0.11684)
		(layer "In13.Cu")
		(net "SMB_VR_3V3STBY_SCL")
	)
	(segment
		(start 86.944962 -138.843766)
		(end 86.944962 -138.678666)
		(width 0.11684)
		(layer "In13.Cu")
		(net "SMB_VR_3V3STBY_SCL")
	)
	(segment
		(start 87.844884 -137.943844)
		(end 88.00846 -138.10742)
		(width 0.11684)
		(layer "In13.Cu")
		(net "SMB_VR_3V3STBY_SCL")
	)
	(segment
		(start 87.54491 -138.243818)
		(end 87.54491 -138.078718)
		(width 0.11684)
		(layer "In13.Cu")
		(net "SMB_VR_3V3STBY_SCL")
	)
	(segment
		(start 88.642952 -137.638028)
		(end 89.043764 -137.638028)
		(width 0.11684)
		(layer "In13.Cu")
		(net "SMB_VR_3V3STBY_SCL")
	)
	(segment
		(start 88.00846 -138.10742)
		(end 88.17356 -138.10742)
		(width 0.11684)
		(layer "In13.Cu")
		(net "SMB_VR_3V3STBY_SCL")
	)
	(segment
		(start 87.244936 -138.543792)
		(end 87.408512 -138.707368)
		(width 0.11684)
		(layer "In13.Cu")
		(net "SMB_VR_3V3STBY_SCL")
	)
	(segment
		(start 21.350478 -152.240488)
		(end 21.350478 -150.198582)
		(width 0.11684)
		(layer "In13.Cu")
		(net "SMB_VR_3V3STBY_SCL")
	)
	(segment
		(start 87.573612 -138.707368)
		(end 87.708486 -138.572494)
		(width 0.11684)
		(layer "In13.Cu")
		(net "SMB_VR_3V3STBY_SCL")
	)
	(segment
		(start 87.408512 -138.707368)
		(end 87.573612 -138.707368)
		(width 0.11684)
		(layer "In13.Cu")
		(net "SMB_VR_3V3STBY_SCL")
	)
	(segment
		(start 86.31936 -139.96162)
		(end 87.108538 -139.172442)
		(width 0.11684)
		(layer "In13.Cu")
		(net "SMB_VR_3V3STBY_SCL")
	)
	(segment
		(start 87.108538 -139.172442)
		(end 87.108538 -139.007342)
		(width 0.11684)
		(layer "In13.Cu")
		(net "SMB_VR_3V3STBY_SCL")
	)
	(segment
		(start 87.54491 -138.078718)
		(end 87.679784 -137.943844)
		(width 0.11684)
		(layer "In13.Cu")
		(net "SMB_VR_3V3STBY_SCL")
	)
	(segment
		(start 87.679784 -137.943844)
		(end 87.844884 -137.943844)
		(width 0.11684)
		(layer "In13.Cu")
		(net "SMB_VR_3V3STBY_SCL")
	)
	(segment
		(start 87.079836 -138.543792)
		(end 87.244936 -138.543792)
		(width 0.11684)
		(layer "In13.Cu")
		(net "SMB_VR_3V3STBY_SCL")
	)
	(segment
		(start 175.86706 -11.922506)
		(end 175.86706 -13.599922)
		(width 0.10668)
		(layer "F.Cu")
		(net "SMB_VR_3V3AUX_SDA_R0")
	)
	(via
		(at 175.86706 -11.922506)
		(size 0.508)
		(drill 0.254)
		(layers "F.Cu" "B.Cu")
		(net "SMB_VR_3V3AUX_SDA_R0")
	)
	(segment
		(start 175.886364 -10.54735)
		(end 175.886364 -11.903202)
		(width 0.10668)
		(layer "B.Cu")
		(net "SMB_VR_3V3AUX_SDA_R0")
	)
	(segment
		(start 175.886364 -11.903202)
		(end 175.86706 -11.922506)
		(width 0.10668)
		(layer "B.Cu")
		(net "SMB_VR_3V3AUX_SDA_R0")
	)
	(segment
		(start 252.973586 -121.71045)
		(end 252.255528 -122.428508)
		(width 0.10668)
		(layer "F.Cu")
		(net "SMB_VR_3V3AUX_SDA")
	)
	(segment
		(start 256.842006 -121.95937)
		(end 256.140966 -121.95937)
		(width 0.10668)
		(layer "F.Cu")
		(net "SMB_VR_3V3AUX_SDA")
	)
	(segment
		(start 252.973586 -121.894854)
		(end 252.973586 -121.71045)
		(width 0.10668)
		(layer "F.Cu")
		(net "SMB_VR_3V3AUX_SDA")
	)
	(segment
		(start 251.794264 -122.428508)
		(end 250.98375 -123.239022)
		(width 0.10668)
		(layer "F.Cu")
		(net "SMB_VR_3V3AUX_SDA")
	)
	(segment
		(start 254.992886 -123.10745)
		(end 254.337566 -122.45213)
		(width 0.10668)
		(layer "F.Cu")
		(net "SMB_VR_3V3AUX_SDA")
	)
	(segment
		(start 254.337566 -122.45213)
		(end 253.530862 -122.45213)
		(width 0.10668)
		(layer "F.Cu")
		(net "SMB_VR_3V3AUX_SDA")
	)
	(segment
		(start 253.530862 -122.45213)
		(end 252.973586 -121.894854)
		(width 0.10668)
		(layer "F.Cu")
		(net "SMB_VR_3V3AUX_SDA")
	)
	(segment
		(start 252.255528 -122.428508)
		(end 251.794264 -122.428508)
		(width 0.10668)
		(layer "F.Cu")
		(net "SMB_VR_3V3AUX_SDA")
	)
	(segment
		(start 256.140966 -121.95937)
		(end 254.992886 -123.10745)
		(width 0.10668)
		(layer "F.Cu")
		(net "SMB_VR_3V3AUX_SDA")
	)
	(via
		(at 97.20707 -138.793982)
		(size 0.508)
		(drill 0.254)
		(layers "F.Cu" "B.Cu")
		(net "SMB_VR_3V3AUX_SDA")
	)
	(via
		(at 250.98375 -123.239022)
		(size 0.508)
		(drill 0.254)
		(layers "F.Cu" "B.Cu")
		(net "SMB_VR_3V3AUX_SDA")
	)
	(via
		(at 221.12986 -163.17468)
		(size 0.508)
		(drill 0.254)
		(layers "F.Cu" "B.Cu")
		(net "SMB_VR_3V3AUX_SDA")
	)
	(segment
		(start 96.636332 -139.36472)
		(end 93.99397 -139.36472)
		(width 0.10668)
		(layer "B.Cu")
		(net "SMB_VR_3V3AUX_SDA")
	)
	(segment
		(start 93.99397 -139.36472)
		(end 93.82125 -139.192)
		(width 0.10668)
		(layer "B.Cu")
		(net "SMB_VR_3V3AUX_SDA")
	)
	(segment
		(start 97.20707 -138.793982)
		(end 96.636332 -139.36472)
		(width 0.10668)
		(layer "B.Cu")
		(net "SMB_VR_3V3AUX_SDA")
	)
	(segment
		(start 248.01322 -148.46808)
		(end 244.74932 -151.73198)
		(width 0.11684)
		(layer "In4.Cu")
		(net "SMB_VR_3V3AUX_SDA")
	)
	(segment
		(start 251.765054 -127.997712)
		(end 248.01322 -131.749546)
		(width 0.11684)
		(layer "In4.Cu")
		(net "SMB_VR_3V3AUX_SDA")
	)
	(segment
		(start 240.302796 -151.73198)
		(end 238.963454 -153.071322)
		(width 0.11684)
		(layer "In4.Cu")
		(net "SMB_VR_3V3AUX_SDA")
	)
	(segment
		(start 251.765054 -127.250444)
		(end 251.765054 -127.997712)
		(width 0.11684)
		(layer "In4.Cu")
		(net "SMB_VR_3V3AUX_SDA")
	)
	(segment
		(start 235.908342 -154.420062)
		(end 233.663998 -154.420062)
		(width 0.11684)
		(layer "In4.Cu")
		(net "SMB_VR_3V3AUX_SDA")
	)
	(segment
		(start 247.09628 -145.746216)
		(end 246.97944 -145.863056)
		(width 0.11684)
		(layer "In4.Cu")
		(net "SMB_VR_3V3AUX_SDA")
	)
	(segment
		(start 247.89638 -147.018756)
		(end 248.01322 -147.135596)
		(width 0.11684)
		(layer "In4.Cu")
		(net "SMB_VR_3V3AUX_SDA")
	)
	(segment
		(start 247.89638 -146.594576)
		(end 247.09628 -146.594576)
		(width 0.11684)
		(layer "In4.Cu")
		(net "SMB_VR_3V3AUX_SDA")
	)
	(segment
		(start 247.09628 -144.897856)
		(end 246.97944 -145.014696)
		(width 0.11684)
		(layer "In4.Cu")
		(net "SMB_VR_3V3AUX_SDA")
	)
	(segment
		(start 247.89638 -145.746216)
		(end 247.09628 -145.746216)
		(width 0.11684)
		(layer "In4.Cu")
		(net "SMB_VR_3V3AUX_SDA")
	)
	(segment
		(start 248.01322 -144.781016)
		(end 247.89638 -144.897856)
		(width 0.11684)
		(layer "In4.Cu")
		(net "SMB_VR_3V3AUX_SDA")
	)
	(segment
		(start 238.963454 -153.071322)
		(end 237.257082 -153.071322)
		(width 0.11684)
		(layer "In4.Cu")
		(net "SMB_VR_3V3AUX_SDA")
	)
	(segment
		(start 244.74932 -151.73198)
		(end 240.302796 -151.73198)
		(width 0.11684)
		(layer "In4.Cu")
		(net "SMB_VR_3V3AUX_SDA")
	)
	(segment
		(start 246.97944 -144.166336)
		(end 246.97944 -144.356836)
		(width 0.11684)
		(layer "In4.Cu")
		(net "SMB_VR_3V3AUX_SDA")
	)
	(segment
		(start 248.01322 -143.932656)
		(end 247.89638 -144.049496)
		(width 0.11684)
		(layer "In4.Cu")
		(net "SMB_VR_3V3AUX_SDA")
	)
	(segment
		(start 237.257082 -153.071322)
		(end 235.908342 -154.420062)
		(width 0.11684)
		(layer "In4.Cu")
		(net "SMB_VR_3V3AUX_SDA")
	)
	(segment
		(start 248.01322 -147.135596)
		(end 248.01322 -148.46808)
		(width 0.11684)
		(layer "In4.Cu")
		(net "SMB_VR_3V3AUX_SDA")
	)
	(segment
		(start 247.09628 -146.594576)
		(end 246.97944 -146.711416)
		(width 0.11684)
		(layer "In4.Cu")
		(net "SMB_VR_3V3AUX_SDA")
	)
	(segment
		(start 246.97944 -146.053556)
		(end 247.09628 -146.170396)
		(width 0.11684)
		(layer "In4.Cu")
		(net "SMB_VR_3V3AUX_SDA")
	)
	(segment
		(start 246.97944 -144.356836)
		(end 247.09628 -144.473676)
		(width 0.11684)
		(layer "In4.Cu")
		(net "SMB_VR_3V3AUX_SDA")
	)
	(segment
		(start 248.01322 -146.477736)
		(end 247.89638 -146.594576)
		(width 0.11684)
		(layer "In4.Cu")
		(net "SMB_VR_3V3AUX_SDA")
	)
	(segment
		(start 250.799854 -126.285244)
		(end 251.765054 -127.250444)
		(width 0.11684)
		(layer "In4.Cu")
		(net "SMB_VR_3V3AUX_SDA")
	)
	(segment
		(start 247.89638 -144.049496)
		(end 247.09628 -144.049496)
		(width 0.11684)
		(layer "In4.Cu")
		(net "SMB_VR_3V3AUX_SDA")
	)
	(segment
		(start 250.98375 -124.744226)
		(end 250.799854 -124.928122)
		(width 0.11684)
		(layer "In4.Cu")
		(net "SMB_VR_3V3AUX_SDA")
	)
	(segment
		(start 247.09628 -145.322036)
		(end 247.89638 -145.322036)
		(width 0.11684)
		(layer "In4.Cu")
		(net "SMB_VR_3V3AUX_SDA")
	)
	(segment
		(start 233.663998 -154.420062)
		(end 232.48874 -155.59532)
		(width 0.11684)
		(layer "In4.Cu")
		(net "SMB_VR_3V3AUX_SDA")
	)
	(segment
		(start 247.09628 -144.473676)
		(end 247.89638 -144.473676)
		(width 0.11684)
		(layer "In4.Cu")
		(net "SMB_VR_3V3AUX_SDA")
	)
	(segment
		(start 247.89638 -144.897856)
		(end 247.09628 -144.897856)
		(width 0.11684)
		(layer "In4.Cu")
		(net "SMB_VR_3V3AUX_SDA")
	)
	(segment
		(start 248.01322 -146.287236)
		(end 248.01322 -146.477736)
		(width 0.11684)
		(layer "In4.Cu")
		(net "SMB_VR_3V3AUX_SDA")
	)
	(segment
		(start 247.09628 -147.018756)
		(end 247.89638 -147.018756)
		(width 0.11684)
		(layer "In4.Cu")
		(net "SMB_VR_3V3AUX_SDA")
	)
	(segment
		(start 250.799854 -124.928122)
		(end 250.799854 -126.285244)
		(width 0.11684)
		(layer "In4.Cu")
		(net "SMB_VR_3V3AUX_SDA")
	)
	(segment
		(start 247.09628 -144.049496)
		(end 246.97944 -144.166336)
		(width 0.11684)
		(layer "In4.Cu")
		(net "SMB_VR_3V3AUX_SDA")
	)
	(segment
		(start 225.506788 -166.623492)
		(end 222.432118 -166.623492)
		(width 0.11684)
		(layer "In4.Cu")
		(net "SMB_VR_3V3AUX_SDA")
	)
	(segment
		(start 248.01322 -145.629376)
		(end 247.89638 -145.746216)
		(width 0.11684)
		(layer "In4.Cu")
		(net "SMB_VR_3V3AUX_SDA")
	)
	(segment
		(start 232.48874 -155.59532)
		(end 232.48874 -159.64154)
		(width 0.11684)
		(layer "In4.Cu")
		(net "SMB_VR_3V3AUX_SDA")
	)
	(segment
		(start 221.12986 -165.321234)
		(end 221.12986 -163.17468)
		(width 0.11684)
		(layer "In4.Cu")
		(net "SMB_VR_3V3AUX_SDA")
	)
	(segment
		(start 232.48874 -159.64154)
		(end 225.506788 -166.623492)
		(width 0.11684)
		(layer "In4.Cu")
		(net "SMB_VR_3V3AUX_SDA")
	)
	(segment
		(start 246.97944 -145.863056)
		(end 246.97944 -146.053556)
		(width 0.11684)
		(layer "In4.Cu")
		(net "SMB_VR_3V3AUX_SDA")
	)
	(segment
		(start 248.01322 -144.590516)
		(end 248.01322 -144.781016)
		(width 0.11684)
		(layer "In4.Cu")
		(net "SMB_VR_3V3AUX_SDA")
	)
	(segment
		(start 246.97944 -146.711416)
		(end 246.97944 -146.901916)
		(width 0.11684)
		(layer "In4.Cu")
		(net "SMB_VR_3V3AUX_SDA")
	)
	(segment
		(start 248.01322 -131.749546)
		(end 248.01322 -143.932656)
		(width 0.11684)
		(layer "In4.Cu")
		(net "SMB_VR_3V3AUX_SDA")
	)
	(segment
		(start 247.09628 -146.170396)
		(end 247.89638 -146.170396)
		(width 0.11684)
		(layer "In4.Cu")
		(net "SMB_VR_3V3AUX_SDA")
	)
	(segment
		(start 250.98375 -123.239022)
		(end 250.98375 -124.744226)
		(width 0.11684)
		(layer "In4.Cu")
		(net "SMB_VR_3V3AUX_SDA")
	)
	(segment
		(start 247.89638 -146.170396)
		(end 248.01322 -146.287236)
		(width 0.11684)
		(layer "In4.Cu")
		(net "SMB_VR_3V3AUX_SDA")
	)
	(segment
		(start 246.97944 -146.901916)
		(end 247.09628 -147.018756)
		(width 0.11684)
		(layer "In4.Cu")
		(net "SMB_VR_3V3AUX_SDA")
	)
	(segment
		(start 222.432118 -166.623492)
		(end 221.12986 -165.321234)
		(width 0.11684)
		(layer "In4.Cu")
		(net "SMB_VR_3V3AUX_SDA")
	)
	(segment
		(start 247.89638 -145.322036)
		(end 248.01322 -145.438876)
		(width 0.11684)
		(layer "In4.Cu")
		(net "SMB_VR_3V3AUX_SDA")
	)
	(segment
		(start 248.01322 -145.438876)
		(end 248.01322 -145.629376)
		(width 0.11684)
		(layer "In4.Cu")
		(net "SMB_VR_3V3AUX_SDA")
	)
	(segment
		(start 247.89638 -144.473676)
		(end 248.01322 -144.590516)
		(width 0.11684)
		(layer "In4.Cu")
		(net "SMB_VR_3V3AUX_SDA")
	)
	(segment
		(start 246.97944 -145.205196)
		(end 247.09628 -145.322036)
		(width 0.11684)
		(layer "In4.Cu")
		(net "SMB_VR_3V3AUX_SDA")
	)
	(segment
		(start 246.97944 -145.014696)
		(end 246.97944 -145.205196)
		(width 0.11684)
		(layer "In4.Cu")
		(net "SMB_VR_3V3AUX_SDA")
	)
	(segment
		(start 196.393816 -168.44391)
		(end 163.450778 -168.44391)
		(width 0.11684)
		(layer "In6.Cu")
		(net "SMB_VR_3V3AUX_SDA")
	)
	(segment
		(start 208.254092 -170.33494)
		(end 198.284846 -170.33494)
		(width 0.11684)
		(layer "In6.Cu")
		(net "SMB_VR_3V3AUX_SDA")
	)
	(segment
		(start 99.197922 -136.320276)
		(end 97.493582 -138.024616)
		(width 0.11684)
		(layer "In6.Cu")
		(net "SMB_VR_3V3AUX_SDA")
	)
	(segment
		(start 159.33928 -157.870652)
		(end 138.739372 -137.270744)
		(width 0.11684)
		(layer "In6.Cu")
		(net "SMB_VR_3V3AUX_SDA")
	)
	(segment
		(start 218.88196 -163.34232)
		(end 215.246712 -163.34232)
		(width 0.11684)
		(layer "In6.Cu")
		(net "SMB_VR_3V3AUX_SDA")
	)
	(segment
		(start 138.739372 -137.270744)
		(end 104.196642 -137.270744)
		(width 0.11684)
		(layer "In6.Cu")
		(net "SMB_VR_3V3AUX_SDA")
	)
	(segment
		(start 198.284846 -170.33494)
		(end 196.393816 -168.44391)
		(width 0.11684)
		(layer "In6.Cu")
		(net "SMB_VR_3V3AUX_SDA")
	)
	(segment
		(start 220.60408 -163.70046)
		(end 219.2401 -163.70046)
		(width 0.11684)
		(layer "In6.Cu")
		(net "SMB_VR_3V3AUX_SDA")
	)
	(segment
		(start 219.2401 -163.70046)
		(end 218.88196 -163.34232)
		(width 0.11684)
		(layer "In6.Cu")
		(net "SMB_VR_3V3AUX_SDA")
	)
	(segment
		(start 215.246712 -163.34232)
		(end 208.254092 -170.33494)
		(width 0.11684)
		(layer "In6.Cu")
		(net "SMB_VR_3V3AUX_SDA")
	)
	(segment
		(start 97.493582 -138.024616)
		(end 97.493582 -138.50747)
		(width 0.11684)
		(layer "In6.Cu")
		(net "SMB_VR_3V3AUX_SDA")
	)
	(segment
		(start 159.33928 -164.332412)
		(end 159.33928 -157.870652)
		(width 0.11684)
		(layer "In6.Cu")
		(net "SMB_VR_3V3AUX_SDA")
	)
	(segment
		(start 221.12986 -163.17468)
		(end 220.60408 -163.70046)
		(width 0.11684)
		(layer "In6.Cu")
		(net "SMB_VR_3V3AUX_SDA")
	)
	(segment
		(start 103.246174 -136.320276)
		(end 99.197922 -136.320276)
		(width 0.11684)
		(layer "In6.Cu")
		(net "SMB_VR_3V3AUX_SDA")
	)
	(segment
		(start 104.196642 -137.270744)
		(end 103.246174 -136.320276)
		(width 0.11684)
		(layer "In6.Cu")
		(net "SMB_VR_3V3AUX_SDA")
	)
	(segment
		(start 163.450778 -168.44391)
		(end 159.33928 -164.332412)
		(width 0.11684)
		(layer "In6.Cu")
		(net "SMB_VR_3V3AUX_SDA")
	)
	(segment
		(start 97.493582 -138.50747)
		(end 97.20707 -138.793982)
		(width 0.11684)
		(layer "In6.Cu")
		(net "SMB_VR_3V3AUX_SDA")
	)
	(segment
		(start 176.467008 -12.714732)
		(end 177.210212 -11.971528)
		(width 0.10668)
		(layer "F.Cu")
		(net "SMB_VR_3V3AUX_SCL_R0")
	)
	(segment
		(start 176.467008 -13.599922)
		(end 176.467008 -12.714732)
		(width 0.10668)
		(layer "F.Cu")
		(net "SMB_VR_3V3AUX_SCL_R0")
	)
	(via
		(at 177.210212 -11.971528)
		(size 0.508)
		(drill 0.254)
		(layers "F.Cu" "B.Cu")
		(net "SMB_VR_3V3AUX_SCL_R0")
	)
	(segment
		(start 177.264822 -11.916918)
		(end 177.210212 -11.971528)
		(width 0.10668)
		(layer "B.Cu")
		(net "SMB_VR_3V3AUX_SCL_R0")
	)
	(segment
		(start 177.264822 -10.54735)
		(end 177.264822 -11.916918)
		(width 0.10668)
		(layer "B.Cu")
		(net "SMB_VR_3V3AUX_SCL_R0")
	)
	(segment
		(start 252.460506 -119.80037)
		(end 252.149102 -119.80037)
		(width 0.10668)
		(layer "F.Cu")
		(net "SMB_VR_3V3AUX_SCL")
	)
	(segment
		(start 252.973586 -120.497854)
		(end 252.973586 -120.31345)
		(width 0.10668)
		(layer "F.Cu")
		(net "SMB_VR_3V3AUX_SCL")
	)
	(segment
		(start 256.842006 -120.94337)
		(end 255.759966 -120.94337)
		(width 0.10668)
		(layer "F.Cu")
		(net "SMB_VR_3V3AUX_SCL")
	)
	(segment
		(start 253.530862 -121.05513)
		(end 252.973586 -120.497854)
		(width 0.10668)
		(layer "F.Cu")
		(net "SMB_VR_3V3AUX_SCL")
	)
	(segment
		(start 252.149102 -119.80037)
		(end 251.78258 -119.433848)
		(width 0.10668)
		(layer "F.Cu")
		(net "SMB_VR_3V3AUX_SCL")
	)
	(segment
		(start 252.973586 -120.31345)
		(end 252.460506 -119.80037)
		(width 0.10668)
		(layer "F.Cu")
		(net "SMB_VR_3V3AUX_SCL")
	)
	(segment
		(start 255.759966 -120.94337)
		(end 254.992886 -121.71045)
		(width 0.10668)
		(layer "F.Cu")
		(net "SMB_VR_3V3AUX_SCL")
	)
	(segment
		(start 254.992886 -121.71045)
		(end 254.337566 -121.05513)
		(width 0.10668)
		(layer "F.Cu")
		(net "SMB_VR_3V3AUX_SCL")
	)
	(segment
		(start 254.337566 -121.05513)
		(end 253.530862 -121.05513)
		(width 0.10668)
		(layer "F.Cu")
		(net "SMB_VR_3V3AUX_SCL")
	)
	(via
		(at 96.294956 -138.395964)
		(size 0.508)
		(drill 0.254)
		(layers "F.Cu" "B.Cu")
		(net "SMB_VR_3V3AUX_SCL")
	)
	(via
		(at 251.78258 -119.433848)
		(size 0.508)
		(drill 0.254)
		(layers "F.Cu" "B.Cu")
		(net "SMB_VR_3V3AUX_SCL")
	)
	(via
		(at 219.60586 -163.17468)
		(size 0.508)
		(drill 0.254)
		(layers "F.Cu" "B.Cu")
		(net "SMB_VR_3V3AUX_SCL")
	)
	(segment
		(start 96.02216 -138.66876)
		(end 94.31401 -138.66876)
		(width 0.10668)
		(layer "B.Cu")
		(net "SMB_VR_3V3AUX_SCL")
	)
	(segment
		(start 94.31401 -138.66876)
		(end 93.82125 -138.176)
		(width 0.10668)
		(layer "B.Cu")
		(net "SMB_VR_3V3AUX_SCL")
	)
	(segment
		(start 96.294956 -138.395964)
		(end 96.02216 -138.66876)
		(width 0.10668)
		(layer "B.Cu")
		(net "SMB_VR_3V3AUX_SCL")
	)
	(segment
		(start 232.91038 -155.770072)
		(end 233.732578 -154.947874)
		(width 0.11684)
		(layer "In4.Cu")
		(net "SMB_VR_3V3AUX_SCL")
	)
	(segment
		(start 244.924072 -152.15362)
		(end 248.43486 -148.642832)
		(width 0.11684)
		(layer "In4.Cu")
		(net "SMB_VR_3V3AUX_SCL")
	)
	(segment
		(start 252.72492 -126.104904)
		(end 252.72492 -121.7676)
		(width 0.11684)
		(layer "In4.Cu")
		(net "SMB_VR_3V3AUX_SCL")
	)
	(segment
		(start 235.976922 -154.947874)
		(end 237.431834 -153.492962)
		(width 0.11684)
		(layer "In4.Cu")
		(net "SMB_VR_3V3AUX_SCL")
	)
	(segment
		(start 252.72492 -121.7676)
		(end 251.78258 -120.82526)
		(width 0.11684)
		(layer "In4.Cu")
		(net "SMB_VR_3V3AUX_SCL")
	)
	(segment
		(start 239.172242 -153.492962)
		(end 240.511584 -152.15362)
		(width 0.11684)
		(layer "In4.Cu")
		(net "SMB_VR_3V3AUX_SCL")
	)
	(segment
		(start 240.511584 -152.15362)
		(end 244.924072 -152.15362)
		(width 0.11684)
		(layer "In4.Cu")
		(net "SMB_VR_3V3AUX_SCL")
	)
	(segment
		(start 225.68154 -167.045132)
		(end 232.91038 -159.816292)
		(width 0.11684)
		(layer "In4.Cu")
		(net "SMB_VR_3V3AUX_SCL")
	)
	(segment
		(start 233.732578 -154.947874)
		(end 235.976922 -154.947874)
		(width 0.11684)
		(layer "In4.Cu")
		(net "SMB_VR_3V3AUX_SCL")
	)
	(segment
		(start 248.43486 -148.642832)
		(end 248.43486 -132.253228)
		(width 0.11684)
		(layer "In4.Cu")
		(net "SMB_VR_3V3AUX_SCL")
	)
	(segment
		(start 252.275594 -128.412494)
		(end 252.275594 -126.55423)
		(width 0.11684)
		(layer "In4.Cu")
		(net "SMB_VR_3V3AUX_SCL")
	)
	(segment
		(start 232.91038 -159.816292)
		(end 232.91038 -155.770072)
		(width 0.11684)
		(layer "In4.Cu")
		(net "SMB_VR_3V3AUX_SCL")
	)
	(segment
		(start 219.60586 -163.17468)
		(end 219.60586 -165.524434)
		(width 0.11684)
		(layer "In4.Cu")
		(net "SMB_VR_3V3AUX_SCL")
	)
	(segment
		(start 237.431834 -153.492962)
		(end 239.172242 -153.492962)
		(width 0.11684)
		(layer "In4.Cu")
		(net "SMB_VR_3V3AUX_SCL")
	)
	(segment
		(start 252.275594 -126.55423)
		(end 252.72492 -126.104904)
		(width 0.11684)
		(layer "In4.Cu")
		(net "SMB_VR_3V3AUX_SCL")
	)
	(segment
		(start 221.126558 -167.045132)
		(end 225.68154 -167.045132)
		(width 0.11684)
		(layer "In4.Cu")
		(net "SMB_VR_3V3AUX_SCL")
	)
	(segment
		(start 248.43486 -132.253228)
		(end 252.275594 -128.412494)
		(width 0.11684)
		(layer "In4.Cu")
		(net "SMB_VR_3V3AUX_SCL")
	)
	(segment
		(start 251.78258 -120.82526)
		(end 251.78258 -119.433848)
		(width 0.11684)
		(layer "In4.Cu")
		(net "SMB_VR_3V3AUX_SCL")
	)
	(segment
		(start 219.60586 -165.524434)
		(end 221.126558 -167.045132)
		(width 0.11684)
		(layer "In4.Cu")
		(net "SMB_VR_3V3AUX_SCL")
	)
	(segment
		(start 96.294956 -138.395964)
		(end 96.369124 -138.321796)
		(width 0.11684)
		(layer "In6.Cu")
		(net "SMB_VR_3V3AUX_SCL")
	)
	(segment
		(start 208.07934 -169.9133)
		(end 215.07196 -162.92068)
		(width 0.11684)
		(layer "In6.Cu")
		(net "SMB_VR_3V3AUX_SCL")
	)
	(segment
		(start 159.76092 -157.6959)
		(end 159.76092 -164.15766)
		(width 0.11684)
		(layer "In6.Cu")
		(net "SMB_VR_3V3AUX_SCL")
	)
	(segment
		(start 163.62553 -168.02227)
		(end 196.568568 -168.02227)
		(width 0.11684)
		(layer "In6.Cu")
		(net "SMB_VR_3V3AUX_SCL")
	)
	(segment
		(start 196.568568 -168.02227)
		(end 198.459598 -169.9133)
		(width 0.11684)
		(layer "In6.Cu")
		(net "SMB_VR_3V3AUX_SCL")
	)
	(segment
		(start 98.373946 -135.898636)
		(end 103.420926 -135.898636)
		(width 0.11684)
		(layer "In6.Cu")
		(net "SMB_VR_3V3AUX_SCL")
	)
	(segment
		(start 96.369124 -137.903458)
		(end 98.373946 -135.898636)
		(width 0.11684)
		(layer "In6.Cu")
		(net "SMB_VR_3V3AUX_SCL")
	)
	(segment
		(start 215.07196 -162.92068)
		(end 219.35186 -162.92068)
		(width 0.11684)
		(layer "In6.Cu")
		(net "SMB_VR_3V3AUX_SCL")
	)
	(segment
		(start 103.420926 -135.898636)
		(end 104.371394 -136.849104)
		(width 0.11684)
		(layer "In6.Cu")
		(net "SMB_VR_3V3AUX_SCL")
	)
	(segment
		(start 138.914124 -136.849104)
		(end 159.76092 -157.6959)
		(width 0.11684)
		(layer "In6.Cu")
		(net "SMB_VR_3V3AUX_SCL")
	)
	(segment
		(start 104.371394 -136.849104)
		(end 138.914124 -136.849104)
		(width 0.11684)
		(layer "In6.Cu")
		(net "SMB_VR_3V3AUX_SCL")
	)
	(segment
		(start 198.459598 -169.9133)
		(end 208.07934 -169.9133)
		(width 0.11684)
		(layer "In6.Cu")
		(net "SMB_VR_3V3AUX_SCL")
	)
	(segment
		(start 159.76092 -164.15766)
		(end 163.62553 -168.02227)
		(width 0.11684)
		(layer "In6.Cu")
		(net "SMB_VR_3V3AUX_SCL")
	)
	(segment
		(start 219.35186 -162.92068)
		(end 219.60586 -163.17468)
		(width 0.11684)
		(layer "In6.Cu")
		(net "SMB_VR_3V3AUX_SCL")
	)
	(segment
		(start 96.369124 -138.321796)
		(end 96.369124 -137.903458)
		(width 0.11684)
		(layer "In6.Cu")
		(net "SMB_VR_3V3AUX_SCL")
	)
	(segment
		(start 227.834698 -147.628102)
		(end 225.652838 -149.809962)
		(width 0.10668)
		(layer "F.Cu")
		(net "SMB_SML1_PMBUS_HSC_SDA")
	)
	(segment
		(start 232.575862 -184.844182)
		(end 232.575862 -187.32119)
		(width 0.10668)
		(layer "F.Cu")
		(net "SMB_SML1_PMBUS_HSC_SDA")
	)
	(segment
		(start 232.914444 -166.289482)
		(end 232.914444 -184.5056)
		(width 0.10668)
		(layer "F.Cu")
		(net "SMB_SML1_PMBUS_HSC_SDA")
	)
	(segment
		(start 226.758246 -95.10522)
		(end 226.758246 -117.23624)
		(width 0.10668)
		(layer "F.Cu")
		(net "SMB_SML1_PMBUS_HSC_SDA")
	)
	(segment
		(start 212.927692 -88.43645)
		(end 214.073994 -88.43645)
		(width 0.10668)
		(layer "F.Cu")
		(net "SMB_SML1_PMBUS_HSC_SDA")
	)
	(segment
		(start 215.111838 -89.474294)
		(end 221.12732 -89.474294)
		(width 0.10668)
		(layer "F.Cu")
		(net "SMB_SML1_PMBUS_HSC_SDA")
	)
	(segment
		(start 232.575862 -187.32119)
		(end 230.893366 -191.383158)
		(width 0.10668)
		(layer "F.Cu")
		(net "SMB_SML1_PMBUS_HSC_SDA")
	)
	(segment
		(start 230.893366 -204.445362)
		(end 228.216714 -207.122014)
		(width 0.10668)
		(layer "F.Cu")
		(net "SMB_SML1_PMBUS_HSC_SDA")
	)
	(segment
		(start 204.753718 -83.845908)
		(end 204.753718 -84.108036)
		(width 0.10668)
		(layer "F.Cu")
		(net "SMB_SML1_PMBUS_HSC_SDA")
	)
	(segment
		(start 228.31552 -140.206476)
		(end 227.834698 -140.687298)
		(width 0.10668)
		(layer "F.Cu")
		(net "SMB_SML1_PMBUS_HSC_SDA")
	)
	(segment
		(start 228.216714 -207.122014)
		(end 228.216714 -210.685634)
		(width 0.10668)
		(layer "F.Cu")
		(net "SMB_SML1_PMBUS_HSC_SDA")
	)
	(segment
		(start 227.716842 -122.047762)
		(end 227.716842 -122.87123)
		(width 0.10668)
		(layer "F.Cu")
		(net "SMB_SML1_PMBUS_HSC_SDA")
	)
	(segment
		(start 175.913288 -411.489398)
		(end 175.821086 -411.489398)
		(width 0.10668)
		(layer "F.Cu")
		(net "SMB_SML1_PMBUS_HSC_SDA")
	)
	(segment
		(start 228.31552 -123.469908)
		(end 228.31552 -140.206476)
		(width 0.10668)
		(layer "F.Cu")
		(net "SMB_SML1_PMBUS_HSC_SDA")
	)
	(segment
		(start 208.79689 -84.305648)
		(end 212.927692 -88.43645)
		(width 0.10668)
		(layer "F.Cu")
		(net "SMB_SML1_PMBUS_HSC_SDA")
	)
	(segment
		(start 214.073994 -88.43645)
		(end 215.111838 -89.474294)
		(width 0.10668)
		(layer "F.Cu")
		(net "SMB_SML1_PMBUS_HSC_SDA")
	)
	(segment
		(start 228.216714 -210.685634)
		(end 228.661214 -211.130134)
		(width 0.10668)
		(layer "F.Cu")
		(net "SMB_SML1_PMBUS_HSC_SDA")
	)
	(segment
		(start 232.914444 -184.5056)
		(end 232.575862 -184.844182)
		(width 0.10668)
		(layer "F.Cu")
		(net "SMB_SML1_PMBUS_HSC_SDA")
	)
	(segment
		(start 225.15322 -118.841266)
		(end 225.15322 -119.48414)
		(width 0.10668)
		(layer "F.Cu")
		(net "SMB_SML1_PMBUS_HSC_SDA")
	)
	(segment
		(start 221.12732 -89.474294)
		(end 226.758246 -95.10522)
		(width 0.10668)
		(layer "F.Cu")
		(net "SMB_SML1_PMBUS_HSC_SDA")
	)
	(segment
		(start 178.451764 -410.630624)
		(end 177.889154 -411.193234)
		(width 0.10668)
		(layer "F.Cu")
		(net "SMB_SML1_PMBUS_HSC_SDA")
	)
	(segment
		(start 226.758246 -117.23624)
		(end 225.15322 -118.841266)
		(width 0.10668)
		(layer "F.Cu")
		(net "SMB_SML1_PMBUS_HSC_SDA")
	)
	(segment
		(start 230.893366 -191.383158)
		(end 230.893366 -204.445362)
		(width 0.10668)
		(layer "F.Cu")
		(net "SMB_SML1_PMBUS_HSC_SDA")
	)
	(segment
		(start 225.652838 -159.027876)
		(end 232.914444 -166.289482)
		(width 0.10668)
		(layer "F.Cu")
		(net "SMB_SML1_PMBUS_HSC_SDA")
	)
	(segment
		(start 225.652838 -149.809962)
		(end 225.652838 -159.027876)
		(width 0.10668)
		(layer "F.Cu")
		(net "SMB_SML1_PMBUS_HSC_SDA")
	)
	(segment
		(start 227.716842 -122.87123)
		(end 228.31552 -123.469908)
		(width 0.10668)
		(layer "F.Cu")
		(net "SMB_SML1_PMBUS_HSC_SDA")
	)
	(segment
		(start 176.209452 -411.193234)
		(end 175.913288 -411.489398)
		(width 0.10668)
		(layer "F.Cu")
		(net "SMB_SML1_PMBUS_HSC_SDA")
	)
	(segment
		(start 204.95133 -84.305648)
		(end 208.79689 -84.305648)
		(width 0.10668)
		(layer "F.Cu")
		(net "SMB_SML1_PMBUS_HSC_SDA")
	)
	(segment
		(start 180.09108 -408.991308)
		(end 180.09108 -408.711654)
		(width 0.10668)
		(layer "F.Cu")
		(net "SMB_SML1_PMBUS_HSC_SDA")
	)
	(segment
		(start 227.834698 -140.687298)
		(end 227.834698 -147.628102)
		(width 0.10668)
		(layer "F.Cu")
		(net "SMB_SML1_PMBUS_HSC_SDA")
	)
	(segment
		(start 178.451764 -410.630624)
		(end 180.09108 -408.991308)
		(width 0.10668)
		(layer "F.Cu")
		(net "SMB_SML1_PMBUS_HSC_SDA")
	)
	(segment
		(start 225.15322 -119.48414)
		(end 227.716842 -122.047762)
		(width 0.10668)
		(layer "F.Cu")
		(net "SMB_SML1_PMBUS_HSC_SDA")
	)
	(segment
		(start 204.753718 -84.108036)
		(end 204.95133 -84.305648)
		(width 0.10668)
		(layer "F.Cu")
		(net "SMB_SML1_PMBUS_HSC_SDA")
	)
	(segment
		(start 228.661214 -211.130134)
		(end 228.676454 -211.130134)
		(width 0.10668)
		(layer "F.Cu")
		(net "SMB_SML1_PMBUS_HSC_SDA")
	)
	(segment
		(start 177.889154 -411.193234)
		(end 176.209452 -411.193234)
		(width 0.10668)
		(layer "F.Cu")
		(net "SMB_SML1_PMBUS_HSC_SDA")
	)
	(via
		(at 175.821086 -411.489398)
		(size 0.508)
		(drill 0.254)
		(layers "F.Cu" "B.Cu")
		(net "SMB_SML1_PMBUS_HSC_SDA")
	)
	(via
		(at 228.676454 -211.130134)
		(size 0.508)
		(drill 0.254)
		(layers "F.Cu" "B.Cu")
		(net "SMB_SML1_PMBUS_HSC_SDA")
	)
	(via
		(at 204.753718 -83.845908)
		(size 0.508)
		(drill 0.254)
		(layers "F.Cu" "B.Cu")
		(net "SMB_SML1_PMBUS_HSC_SDA")
	)
	(via
		(at 234.823 -330.708)
		(size 0.508)
		(drill 0.254)
		(layers "F.Cu" "B.Cu")
		(net "SMB_SML1_PMBUS_HSC_SDA")
	)
	(via
		(at 165.357556 -15.44828)
		(size 0.508)
		(drill 0.254)
		(layers "F.Cu" "B.Cu")
		(net "SMB_SML1_PMBUS_HSC_SDA")
	)
	(via
		(at 180.09108 -408.711654)
		(size 0.508)
		(drill 0.254)
		(layers "F.Cu" "B.Cu")
		(net "SMB_SML1_PMBUS_HSC_SDA")
	)
	(via
		(at 189.479936 -381.267208)
		(size 0.508)
		(drill 0.254)
		(layers "F.Cu" "B.Cu")
		(net "SMB_SML1_PMBUS_HSC_SDA")
	)
	(segment
		(start 165.357556 -15.44828)
		(end 165.357556 -16.44523)
		(width 0.10668)
		(layer "B.Cu")
		(net "SMB_SML1_PMBUS_HSC_SDA")
	)
	(segment
		(start 181.37886 -407.318972)
		(end 180.09108 -408.606752)
		(width 0.10668)
		(layer "B.Cu")
		(net "SMB_SML1_PMBUS_HSC_SDA")
	)
	(segment
		(start 180.09108 -408.606752)
		(end 180.09108 -408.711654)
		(width 0.10668)
		(layer "B.Cu")
		(net "SMB_SML1_PMBUS_HSC_SDA")
	)
	(segment
		(start 234.08005 -330.708)
		(end 234.823 -330.708)
		(width 0.10668)
		(layer "B.Cu")
		(net "SMB_SML1_PMBUS_HSC_SDA")
	)
	(segment
		(start 189.803532 -381.267208)
		(end 191.5414 -383.005076)
		(width 0.11684)
		(layer "In2.Cu")
		(net "SMB_SML1_PMBUS_HSC_SDA")
	)
	(segment
		(start 179.551838 -397.510508)
		(end 178.993292 -398.069054)
		(width 0.11684)
		(layer "In2.Cu")
		(net "SMB_SML1_PMBUS_HSC_SDA")
	)
	(segment
		(start 180.09108 -408.246072)
		(end 180.09108 -408.711654)
		(width 0.11684)
		(layer "In2.Cu")
		(net "SMB_SML1_PMBUS_HSC_SDA")
	)
	(segment
		(start 178.993292 -398.069054)
		(end 178.993292 -407.148284)
		(width 0.11684)
		(layer "In2.Cu")
		(net "SMB_SML1_PMBUS_HSC_SDA")
	)
	(segment
		(start 178.993292 -407.148284)
		(end 180.09108 -408.246072)
		(width 0.11684)
		(layer "In2.Cu")
		(net "SMB_SML1_PMBUS_HSC_SDA")
	)
	(segment
		(start 191.5414 -385.707382)
		(end 181.27472 -395.974062)
		(width 0.11684)
		(layer "In2.Cu")
		(net "SMB_SML1_PMBUS_HSC_SDA")
	)
	(segment
		(start 180.413152 -397.510508)
		(end 179.551838 -397.510508)
		(width 0.11684)
		(layer "In2.Cu")
		(net "SMB_SML1_PMBUS_HSC_SDA")
	)
	(segment
		(start 181.27472 -395.974062)
		(end 181.27472 -396.64894)
		(width 0.11684)
		(layer "In2.Cu")
		(net "SMB_SML1_PMBUS_HSC_SDA")
	)
	(segment
		(start 191.5414 -383.005076)
		(end 191.5414 -385.707382)
		(width 0.11684)
		(layer "In2.Cu")
		(net "SMB_SML1_PMBUS_HSC_SDA")
	)
	(segment
		(start 189.479936 -381.267208)
		(end 189.803532 -381.267208)
		(width 0.11684)
		(layer "In2.Cu")
		(net "SMB_SML1_PMBUS_HSC_SDA")
	)
	(segment
		(start 181.27472 -396.64894)
		(end 180.413152 -397.510508)
		(width 0.11684)
		(layer "In2.Cu")
		(net "SMB_SML1_PMBUS_HSC_SDA")
	)
	(segment
		(start 230.845614 -331.180694)
		(end 234.350306 -331.180694)
		(width 0.11684)
		(layer "In4.Cu")
		(net "SMB_SML1_PMBUS_HSC_SDA")
	)
	(segment
		(start 206.43088 -70.209918)
		(end 206.43088 -69.139562)
		(width 0.11684)
		(layer "In4.Cu")
		(net "SMB_SML1_PMBUS_HSC_SDA")
	)
	(segment
		(start 174.215806 -391.90422)
		(end 196.034914 -370.085112)
		(width 0.11684)
		(layer "In4.Cu")
		(net "SMB_SML1_PMBUS_HSC_SDA")
	)
	(segment
		(start 204.753718 -83.845908)
		(end 204.753718 -82.816192)
		(width 0.11684)
		(layer "In4.Cu")
		(net "SMB_SML1_PMBUS_HSC_SDA")
	)
	(segment
		(start 174.540672 -410.278834)
		(end 169.636694 -410.278834)
		(width 0.11684)
		(layer "In4.Cu")
		(net "SMB_SML1_PMBUS_HSC_SDA")
	)
	(segment
		(start 166.248334 -406.890474)
		(end 166.248334 -402.607526)
		(width 0.11684)
		(layer "In4.Cu")
		(net "SMB_SML1_PMBUS_HSC_SDA")
	)
	(segment
		(start 179.573682 -23.224744)
		(end 179.573682 -18.261838)
		(width 0.11684)
		(layer "In4.Cu")
		(net "SMB_SML1_PMBUS_HSC_SDA")
	)
	(segment
		(start 174.215806 -397.486378)
		(end 174.215806 -391.90422)
		(width 0.11684)
		(layer "In4.Cu")
		(net "SMB_SML1_PMBUS_HSC_SDA")
	)
	(segment
		(start 220.335348 -363.88802)
		(end 220.335348 -351.15246)
		(width 0.11684)
		(layer "In4.Cu")
		(net "SMB_SML1_PMBUS_HSC_SDA")
	)
	(segment
		(start 189.479936 -378.831094)
		(end 197.804278 -370.506752)
		(width 0.11684)
		(layer "In4.Cu")
		(net "SMB_SML1_PMBUS_HSC_SDA")
	)
	(segment
		(start 203.830682 -370.506752)
		(end 205.292706 -369.044728)
		(width 0.11684)
		(layer "In4.Cu")
		(net "SMB_SML1_PMBUS_HSC_SDA")
	)
	(segment
		(start 205.568804 -66.999612)
		(end 197.962012 -59.39282)
		(width 0.11684)
		(layer "In4.Cu")
		(net "SMB_SML1_PMBUS_HSC_SDA")
	)
	(segment
		(start 203.365354 -370.085112)
		(end 205.883764 -367.566702)
		(width 0.11684)
		(layer "In4.Cu")
		(net "SMB_SML1_PMBUS_HSC_SDA")
	)
	(segment
		(start 178.36134 -17.049496)
		(end 171.935902 -17.049496)
		(width 0.11684)
		(layer "In4.Cu")
		(net "SMB_SML1_PMBUS_HSC_SDA")
	)
	(segment
		(start 227.963476 -343.524332)
		(end 227.963476 -332.17485)
		(width 0.11684)
		(layer "In4.Cu")
		(net "SMB_SML1_PMBUS_HSC_SDA")
	)
	(segment
		(start 166.248334 -402.607526)
		(end 169.009822 -399.846038)
		(width 0.11684)
		(layer "In4.Cu")
		(net "SMB_SML1_PMBUS_HSC_SDA")
	)
	(segment
		(start 205.292706 -369.044728)
		(end 225.811334 -369.044728)
		(width 0.11684)
		(layer "In4.Cu")
		(net "SMB_SML1_PMBUS_HSC_SDA")
	)
	(segment
		(start 189.394338 -36.251134)
		(end 188.90107 -36.251134)
		(width 0.11684)
		(layer "In4.Cu")
		(net "SMB_SML1_PMBUS_HSC_SDA")
	)
	(segment
		(start 175.821086 -411.489398)
		(end 175.751236 -411.489398)
		(width 0.11684)
		(layer "In4.Cu")
		(net "SMB_SML1_PMBUS_HSC_SDA")
	)
	(segment
		(start 223.408494 -254.74676)
		(end 223.408494 -216.398094)
		(width 0.11684)
		(layer "In4.Cu")
		(net "SMB_SML1_PMBUS_HSC_SDA")
	)
	(segment
		(start 205.883764 -367.566702)
		(end 216.656666 -367.566702)
		(width 0.11684)
		(layer "In4.Cu")
		(net "SMB_SML1_PMBUS_HSC_SDA")
	)
	(segment
		(start 187.51042 -32.374078)
		(end 182.40248 -27.266138)
		(width 0.11684)
		(layer "In4.Cu")
		(net "SMB_SML1_PMBUS_HSC_SDA")
	)
	(segment
		(start 234.350306 -331.180694)
		(end 234.823 -330.708)
		(width 0.11684)
		(layer "In4.Cu")
		(net "SMB_SML1_PMBUS_HSC_SDA")
	)
	(segment
		(start 166.26205 -16.082264)
		(end 165.628066 -15.44828)
		(width 0.11684)
		(layer "In4.Cu")
		(net "SMB_SML1_PMBUS_HSC_SDA")
	)
	(segment
		(start 191.370204 -38.227)
		(end 189.394338 -36.251134)
		(width 0.11684)
		(layer "In4.Cu")
		(net "SMB_SML1_PMBUS_HSC_SDA")
	)
	(segment
		(start 182.40248 -27.266138)
		(end 182.40248 -26.053542)
		(width 0.11684)
		(layer "In4.Cu")
		(net "SMB_SML1_PMBUS_HSC_SDA")
	)
	(segment
		(start 169.009822 -399.846038)
		(end 171.856146 -399.846038)
		(width 0.11684)
		(layer "In4.Cu")
		(net "SMB_SML1_PMBUS_HSC_SDA")
	)
	(segment
		(start 197.962012 -59.39282)
		(end 197.962012 -43.791124)
		(width 0.11684)
		(layer "In4.Cu")
		(net "SMB_SML1_PMBUS_HSC_SDA")
	)
	(segment
		(start 196.034914 -370.085112)
		(end 203.365354 -370.085112)
		(width 0.11684)
		(layer "In4.Cu")
		(net "SMB_SML1_PMBUS_HSC_SDA")
	)
	(segment
		(start 216.818972 -261.336282)
		(end 223.408494 -254.74676)
		(width 0.11684)
		(layer "In4.Cu")
		(net "SMB_SML1_PMBUS_HSC_SDA")
	)
	(segment
		(start 225.811334 -369.044728)
		(end 229.650036 -365.206026)
		(width 0.11684)
		(layer "In4.Cu")
		(net "SMB_SML1_PMBUS_HSC_SDA")
	)
	(segment
		(start 171.856146 -399.846038)
		(end 174.215806 -397.486378)
		(width 0.11684)
		(layer "In4.Cu")
		(net "SMB_SML1_PMBUS_HSC_SDA")
	)
	(segment
		(start 197.804278 -370.506752)
		(end 203.830682 -370.506752)
		(width 0.11684)
		(layer "In4.Cu")
		(net "SMB_SML1_PMBUS_HSC_SDA")
	)
	(segment
		(start 187.51042 -34.860484)
		(end 187.51042 -32.374078)
		(width 0.11684)
		(layer "In4.Cu")
		(net "SMB_SML1_PMBUS_HSC_SDA")
	)
	(segment
		(start 192.397888 -38.227)
		(end 191.370204 -38.227)
		(width 0.11684)
		(layer "In4.Cu")
		(net "SMB_SML1_PMBUS_HSC_SDA")
	)
	(segment
		(start 206.43088 -69.139562)
		(end 205.568804 -68.277486)
		(width 0.11684)
		(layer "In4.Cu")
		(net "SMB_SML1_PMBUS_HSC_SDA")
	)
	(segment
		(start 179.573682 -18.261838)
		(end 178.36134 -17.049496)
		(width 0.11684)
		(layer "In4.Cu")
		(net "SMB_SML1_PMBUS_HSC_SDA")
	)
	(segment
		(start 216.818972 -321.030346)
		(end 216.818972 -261.336282)
		(width 0.11684)
		(layer "In4.Cu")
		(net "SMB_SML1_PMBUS_HSC_SDA")
	)
	(segment
		(start 227.963476 -332.17485)
		(end 216.818972 -321.030346)
		(width 0.11684)
		(layer "In4.Cu")
		(net "SMB_SML1_PMBUS_HSC_SDA")
	)
	(segment
		(start 223.408494 -216.398094)
		(end 228.676454 -211.130134)
		(width 0.11684)
		(layer "In4.Cu")
		(net "SMB_SML1_PMBUS_HSC_SDA")
	)
	(segment
		(start 216.656666 -367.566702)
		(end 220.335348 -363.88802)
		(width 0.11684)
		(layer "In4.Cu")
		(net "SMB_SML1_PMBUS_HSC_SDA")
	)
	(segment
		(start 205.568804 -68.277486)
		(end 205.568804 -66.999612)
		(width 0.11684)
		(layer "In4.Cu")
		(net "SMB_SML1_PMBUS_HSC_SDA")
	)
	(segment
		(start 170.96867 -16.082264)
		(end 166.26205 -16.082264)
		(width 0.11684)
		(layer "In4.Cu")
		(net "SMB_SML1_PMBUS_HSC_SDA")
	)
	(segment
		(start 188.90107 -36.251134)
		(end 187.51042 -34.860484)
		(width 0.11684)
		(layer "In4.Cu")
		(net "SMB_SML1_PMBUS_HSC_SDA")
	)
	(segment
		(start 182.40248 -26.053542)
		(end 179.573682 -23.224744)
		(width 0.11684)
		(layer "In4.Cu")
		(net "SMB_SML1_PMBUS_HSC_SDA")
	)
	(segment
		(start 205.41361 -82.1563)
		(end 205.41361 -71.227188)
		(width 0.11684)
		(layer "In4.Cu")
		(net "SMB_SML1_PMBUS_HSC_SDA")
	)
	(segment
		(start 204.753718 -82.816192)
		(end 205.41361 -82.1563)
		(width 0.11684)
		(layer "In4.Cu")
		(net "SMB_SML1_PMBUS_HSC_SDA")
	)
	(segment
		(start 197.962012 -43.791124)
		(end 192.397888 -38.227)
		(width 0.11684)
		(layer "In4.Cu")
		(net "SMB_SML1_PMBUS_HSC_SDA")
	)
	(segment
		(start 220.335348 -351.15246)
		(end 227.963476 -343.524332)
		(width 0.11684)
		(layer "In4.Cu")
		(net "SMB_SML1_PMBUS_HSC_SDA")
	)
	(segment
		(start 175.751236 -411.489398)
		(end 174.540672 -410.278834)
		(width 0.11684)
		(layer "In4.Cu")
		(net "SMB_SML1_PMBUS_HSC_SDA")
	)
	(segment
		(start 205.41361 -71.227188)
		(end 206.43088 -70.209918)
		(width 0.11684)
		(layer "In4.Cu")
		(net "SMB_SML1_PMBUS_HSC_SDA")
	)
	(segment
		(start 171.935902 -17.049496)
		(end 170.96867 -16.082264)
		(width 0.11684)
		(layer "In4.Cu")
		(net "SMB_SML1_PMBUS_HSC_SDA")
	)
	(segment
		(start 189.479936 -381.267208)
		(end 189.479936 -378.831094)
		(width 0.11684)
		(layer "In4.Cu")
		(net "SMB_SML1_PMBUS_HSC_SDA")
	)
	(segment
		(start 229.650036 -365.206026)
		(end 229.650036 -332.376272)
		(width 0.11684)
		(layer "In4.Cu")
		(net "SMB_SML1_PMBUS_HSC_SDA")
	)
	(segment
		(start 165.628066 -15.44828)
		(end 165.357556 -15.44828)
		(width 0.11684)
		(layer "In4.Cu")
		(net "SMB_SML1_PMBUS_HSC_SDA")
	)
	(segment
		(start 229.650036 -332.376272)
		(end 230.845614 -331.180694)
		(width 0.11684)
		(layer "In4.Cu")
		(net "SMB_SML1_PMBUS_HSC_SDA")
	)
	(segment
		(start 169.636694 -410.278834)
		(end 166.248334 -406.890474)
		(width 0.11684)
		(layer "In4.Cu")
		(net "SMB_SML1_PMBUS_HSC_SDA")
	)
	(segment
		(start 231.233726 -204.767942)
		(end 228.676454 -207.325214)
		(width 0.10668)
		(layer "F.Cu")
		(net "SMB_SML1_PMBUS_HSC_SCL")
	)
	(segment
		(start 226.203764 -118.272306)
		(end 226.203764 -118.980204)
		(width 0.10668)
		(layer "F.Cu")
		(net "SMB_SML1_PMBUS_HSC_SCL")
	)
	(segment
		(start 176.547526 -411.683962)
		(end 176.083722 -412.147766)
		(width 0.10668)
		(layer "F.Cu")
		(net "SMB_SML1_PMBUS_HSC_SCL")
	)
	(segment
		(start 181.284372 -410.65069)
		(end 180.2511 -411.683962)
		(width 0.10668)
		(layer "F.Cu")
		(net "SMB_SML1_PMBUS_HSC_SCL")
	)
	(segment
		(start 175.44923 -412.147766)
		(end 175.233838 -411.932374)
		(width 0.10668)
		(layer "F.Cu")
		(net "SMB_SML1_PMBUS_HSC_SCL")
	)
	(segment
		(start 208.818734 -83.845908)
		(end 213.068916 -88.09609)
		(width 0.10668)
		(layer "F.Cu")
		(net "SMB_SML1_PMBUS_HSC_SCL")
	)
	(segment
		(start 227.098606 -117.377464)
		(end 226.203764 -118.272306)
		(width 0.10668)
		(layer "F.Cu")
		(net "SMB_SML1_PMBUS_HSC_SCL")
	)
	(segment
		(start 215.253062 -89.133934)
		(end 221.268544 -89.133934)
		(width 0.10668)
		(layer "F.Cu")
		(net "SMB_SML1_PMBUS_HSC_SCL")
	)
	(segment
		(start 233.261916 -184.667652)
		(end 232.916222 -185.013346)
		(width 0.10668)
		(layer "F.Cu")
		(net "SMB_SML1_PMBUS_HSC_SCL")
	)
	(segment
		(start 213.068916 -88.09609)
		(end 214.215218 -88.09609)
		(width 0.10668)
		(layer "F.Cu")
		(net "SMB_SML1_PMBUS_HSC_SCL")
	)
	(segment
		(start 225.993198 -158.886652)
		(end 233.261916 -166.15537)
		(width 0.10668)
		(layer "F.Cu")
		(net "SMB_SML1_PMBUS_HSC_SCL")
	)
	(segment
		(start 232.916222 -187.38977)
		(end 231.233726 -191.451738)
		(width 0.10668)
		(layer "F.Cu")
		(net "SMB_SML1_PMBUS_HSC_SCL")
	)
	(segment
		(start 226.203764 -118.980204)
		(end 228.8159 -121.59234)
		(width 0.10668)
		(layer "F.Cu")
		(net "SMB_SML1_PMBUS_HSC_SCL")
	)
	(segment
		(start 178.958748 -411.683962)
		(end 178.384962 -412.257748)
		(width 0.10668)
		(layer "F.Cu")
		(net "SMB_SML1_PMBUS_HSC_SCL")
	)
	(segment
		(start 225.993198 -149.951186)
		(end 225.993198 -158.886652)
		(width 0.10668)
		(layer "F.Cu")
		(net "SMB_SML1_PMBUS_HSC_SCL")
	)
	(segment
		(start 228.175058 -147.769326)
		(end 225.993198 -149.951186)
		(width 0.10668)
		(layer "F.Cu")
		(net "SMB_SML1_PMBUS_HSC_SCL")
	)
	(segment
		(start 176.083722 -412.147766)
		(end 175.44923 -412.147766)
		(width 0.10668)
		(layer "F.Cu")
		(net "SMB_SML1_PMBUS_HSC_SCL")
	)
	(segment
		(start 227.098606 -94.963996)
		(end 227.098606 -117.377464)
		(width 0.10668)
		(layer "F.Cu")
		(net "SMB_SML1_PMBUS_HSC_SCL")
	)
	(segment
		(start 228.676454 -207.325214)
		(end 228.676454 -210.374992)
		(width 0.10668)
		(layer "F.Cu")
		(net "SMB_SML1_PMBUS_HSC_SCL")
	)
	(segment
		(start 231.233726 -191.451738)
		(end 231.233726 -204.767942)
		(width 0.10668)
		(layer "F.Cu")
		(net "SMB_SML1_PMBUS_HSC_SCL")
	)
	(segment
		(start 180.2511 -411.683962)
		(end 178.958748 -411.683962)
		(width 0.10668)
		(layer "F.Cu")
		(net "SMB_SML1_PMBUS_HSC_SCL")
	)
	(segment
		(start 205.388718 -83.845908)
		(end 208.818734 -83.845908)
		(width 0.10668)
		(layer "F.Cu")
		(net "SMB_SML1_PMBUS_HSC_SCL")
	)
	(segment
		(start 178.384962 -412.257748)
		(end 177.811176 -411.683962)
		(width 0.10668)
		(layer "F.Cu")
		(net "SMB_SML1_PMBUS_HSC_SCL")
	)
	(segment
		(start 214.215218 -88.09609)
		(end 215.253062 -89.133934)
		(width 0.10668)
		(layer "F.Cu")
		(net "SMB_SML1_PMBUS_HSC_SCL")
	)
	(segment
		(start 228.175058 -141.017244)
		(end 228.175058 -147.769326)
		(width 0.10668)
		(layer "F.Cu")
		(net "SMB_SML1_PMBUS_HSC_SCL")
	)
	(segment
		(start 233.261916 -166.15537)
		(end 233.261916 -184.667652)
		(width 0.10668)
		(layer "F.Cu")
		(net "SMB_SML1_PMBUS_HSC_SCL")
	)
	(segment
		(start 177.811176 -411.683962)
		(end 176.547526 -411.683962)
		(width 0.10668)
		(layer "F.Cu")
		(net "SMB_SML1_PMBUS_HSC_SCL")
	)
	(segment
		(start 228.8159 -140.376402)
		(end 228.175058 -141.017244)
		(width 0.10668)
		(layer "F.Cu")
		(net "SMB_SML1_PMBUS_HSC_SCL")
	)
	(segment
		(start 232.916222 -185.013346)
		(end 232.916222 -187.38977)
		(width 0.10668)
		(layer "F.Cu")
		(net "SMB_SML1_PMBUS_HSC_SCL")
	)
	(segment
		(start 181.284372 -408.99969)
		(end 181.284372 -410.65069)
		(width 0.10668)
		(layer "F.Cu")
		(net "SMB_SML1_PMBUS_HSC_SCL")
	)
	(segment
		(start 228.8159 -121.59234)
		(end 228.8159 -140.376402)
		(width 0.10668)
		(layer "F.Cu")
		(net "SMB_SML1_PMBUS_HSC_SCL")
	)
	(segment
		(start 221.268544 -89.133934)
		(end 227.098606 -94.963996)
		(width 0.10668)
		(layer "F.Cu")
		(net "SMB_SML1_PMBUS_HSC_SCL")
	)
	(via
		(at 175.233838 -411.932374)
		(size 0.508)
		(drill 0.254)
		(layers "F.Cu" "B.Cu")
		(net "SMB_SML1_PMBUS_HSC_SCL")
	)
	(via
		(at 205.388718 -83.845908)
		(size 0.508)
		(drill 0.254)
		(layers "F.Cu" "B.Cu")
		(net "SMB_SML1_PMBUS_HSC_SCL")
	)
	(via
		(at 189.512194 -382.04775)
		(size 0.508)
		(drill 0.254)
		(layers "F.Cu" "B.Cu")
		(net "SMB_SML1_PMBUS_HSC_SCL")
	)
	(via
		(at 228.676454 -210.374992)
		(size 0.508)
		(drill 0.254)
		(layers "F.Cu" "B.Cu")
		(net "SMB_SML1_PMBUS_HSC_SCL")
	)
	(via
		(at 181.284372 -408.99969)
		(size 0.508)
		(drill 0.254)
		(layers "F.Cu" "B.Cu")
		(net "SMB_SML1_PMBUS_HSC_SCL")
	)
	(via
		(at 234.823 -331.724)
		(size 0.508)
		(drill 0.254)
		(layers "F.Cu" "B.Cu")
		(net "SMB_SML1_PMBUS_HSC_SCL")
	)
	(via
		(at 167.875712 -15.419578)
		(size 0.508)
		(drill 0.254)
		(layers "F.Cu" "B.Cu")
		(net "SMB_SML1_PMBUS_HSC_SCL")
	)
	(segment
		(start 182.294276 -407.619962)
		(end 182.169816 -407.619962)
		(width 0.10668)
		(layer "B.Cu")
		(net "SMB_SML1_PMBUS_HSC_SCL")
	)
	(segment
		(start 182.169816 -407.619962)
		(end 181.858158 -407.93162)
		(width 0.10668)
		(layer "B.Cu")
		(net "SMB_SML1_PMBUS_HSC_SCL")
	)
	(segment
		(start 167.31869 -14.862556)
		(end 167.875712 -15.419578)
		(width 0.10668)
		(layer "B.Cu")
		(net "SMB_SML1_PMBUS_HSC_SCL")
	)
	(segment
		(start 181.284372 -408.05862)
		(end 181.284372 -408.99969)
		(width 0.10668)
		(layer "B.Cu")
		(net "SMB_SML1_PMBUS_HSC_SCL")
	)
	(segment
		(start 181.858158 -407.93162)
		(end 181.411372 -407.93162)
		(width 0.10668)
		(layer "B.Cu")
		(net "SMB_SML1_PMBUS_HSC_SCL")
	)
	(segment
		(start 181.411372 -407.93162)
		(end 181.284372 -408.05862)
		(width 0.10668)
		(layer "B.Cu")
		(net "SMB_SML1_PMBUS_HSC_SCL")
	)
	(segment
		(start 234.08005 -331.724)
		(end 234.823 -331.724)
		(width 0.10668)
		(layer "B.Cu")
		(net "SMB_SML1_PMBUS_HSC_SCL")
	)
	(segment
		(start 179.372768 -397.078708)
		(end 178.561492 -397.889984)
		(width 0.11684)
		(layer "In2.Cu")
		(net "SMB_SML1_PMBUS_HSC_SCL")
	)
	(segment
		(start 180.84292 -395.794992)
		(end 180.84292 -396.46987)
		(width 0.11684)
		(layer "In2.Cu")
		(net "SMB_SML1_PMBUS_HSC_SCL")
	)
	(segment
		(start 180.84292 -396.46987)
		(end 180.234082 -397.078708)
		(width 0.11684)
		(layer "In2.Cu")
		(net "SMB_SML1_PMBUS_HSC_SCL")
	)
	(segment
		(start 178.561492 -397.889984)
		(end 178.561492 -407.327354)
		(width 0.11684)
		(layer "In2.Cu")
		(net "SMB_SML1_PMBUS_HSC_SCL")
	)
	(segment
		(start 191.1096 -385.528312)
		(end 180.84292 -395.794992)
		(width 0.11684)
		(layer "In2.Cu")
		(net "SMB_SML1_PMBUS_HSC_SCL")
	)
	(segment
		(start 189.512194 -382.08077)
		(end 191.1096 -383.678176)
		(width 0.11684)
		(layer "In2.Cu")
		(net "SMB_SML1_PMBUS_HSC_SCL")
	)
	(segment
		(start 179.898294 -409.176474)
		(end 181.107588 -409.176474)
		(width 0.11684)
		(layer "In2.Cu")
		(net "SMB_SML1_PMBUS_HSC_SCL")
	)
	(segment
		(start 178.89728 -407.663142)
		(end 178.89728 -408.17546)
		(width 0.11684)
		(layer "In2.Cu")
		(net "SMB_SML1_PMBUS_HSC_SCL")
	)
	(segment
		(start 178.89728 -408.17546)
		(end 179.898294 -409.176474)
		(width 0.11684)
		(layer "In2.Cu")
		(net "SMB_SML1_PMBUS_HSC_SCL")
	)
	(segment
		(start 189.512194 -382.04775)
		(end 189.512194 -382.08077)
		(width 0.11684)
		(layer "In2.Cu")
		(net "SMB_SML1_PMBUS_HSC_SCL")
	)
	(segment
		(start 178.561492 -407.327354)
		(end 178.89728 -407.663142)
		(width 0.11684)
		(layer "In2.Cu")
		(net "SMB_SML1_PMBUS_HSC_SCL")
	)
	(segment
		(start 181.107588 -409.176474)
		(end 181.284372 -408.99969)
		(width 0.11684)
		(layer "In2.Cu")
		(net "SMB_SML1_PMBUS_HSC_SCL")
	)
	(segment
		(start 191.1096 -383.678176)
		(end 191.1096 -385.528312)
		(width 0.11684)
		(layer "In2.Cu")
		(net "SMB_SML1_PMBUS_HSC_SCL")
	)
	(segment
		(start 180.234082 -397.078708)
		(end 179.372768 -397.078708)
		(width 0.11684)
		(layer "In2.Cu")
		(net "SMB_SML1_PMBUS_HSC_SCL")
	)
	(segment
		(start 227.541836 -342.965786)
		(end 219.77731 -350.730312)
		(width 0.11684)
		(layer "In4.Cu")
		(net "SMB_SML1_PMBUS_HSC_SCL")
	)
	(segment
		(start 195.860162 -369.663472)
		(end 173.707806 -391.815828)
		(width 0.11684)
		(layer "In4.Cu")
		(net "SMB_SML1_PMBUS_HSC_SCL")
	)
	(segment
		(start 168.426638 -399.60804)
		(end 165.826694 -402.207984)
		(width 0.11684)
		(layer "In4.Cu")
		(net "SMB_SML1_PMBUS_HSC_SCL")
	)
	(segment
		(start 173.707806 -391.815828)
		(end 173.707806 -397.388334)
		(width 0.11684)
		(layer "In4.Cu")
		(net "SMB_SML1_PMBUS_HSC_SCL")
	)
	(segment
		(start 172.40504 -398.6911)
		(end 168.80078 -398.6911)
		(width 0.11684)
		(layer "In4.Cu")
		(net "SMB_SML1_PMBUS_HSC_SCL")
	)
	(segment
		(start 205.802738 -369.481862)
		(end 226.043998 -369.481862)
		(width 0.11684)
		(layer "In4.Cu")
		(net "SMB_SML1_PMBUS_HSC_SCL")
	)
	(segment
		(start 207.012286 -71.212456)
		(end 205.83525 -72.389492)
		(width 0.11684)
		(layer "In4.Cu")
		(net "SMB_SML1_PMBUS_HSC_SCL")
	)
	(segment
		(start 191.499744 -37.719)
		(end 192.502028 -37.719)
		(width 0.11684)
		(layer "In4.Cu")
		(net "SMB_SML1_PMBUS_HSC_SCL")
	)
	(segment
		(start 168.80078 -398.6911)
		(end 168.426638 -399.065242)
		(width 0.11684)
		(layer "In4.Cu")
		(net "SMB_SML1_PMBUS_HSC_SCL")
	)
	(segment
		(start 180.27523 -23.291546)
		(end 182.87238 -25.888696)
		(width 0.11684)
		(layer "In4.Cu")
		(net "SMB_SML1_PMBUS_HSC_SCL")
	)
	(segment
		(start 198.383652 -59.218068)
		(end 205.994508 -66.828924)
		(width 0.11684)
		(layer "In4.Cu")
		(net "SMB_SML1_PMBUS_HSC_SCL")
	)
	(segment
		(start 219.77731 -363.756702)
		(end 216.525602 -367.00841)
		(width 0.11684)
		(layer "In4.Cu")
		(net "SMB_SML1_PMBUS_HSC_SCL")
	)
	(segment
		(start 167.89527 -15.439136)
		(end 170.922188 -15.439136)
		(width 0.11684)
		(layer "In4.Cu")
		(net "SMB_SML1_PMBUS_HSC_SCL")
	)
	(segment
		(start 180.27523 -17.425924)
		(end 180.27523 -23.291546)
		(width 0.11684)
		(layer "In4.Cu")
		(net "SMB_SML1_PMBUS_HSC_SCL")
	)
	(segment
		(start 169.526204 -410.767784)
		(end 174.069248 -410.767784)
		(width 0.11684)
		(layer "In4.Cu")
		(net "SMB_SML1_PMBUS_HSC_SCL")
	)
	(segment
		(start 190.249556 -378.7013)
		(end 191.957452 -376.993404)
		(width 0.11684)
		(layer "In4.Cu")
		(net "SMB_SML1_PMBUS_HSC_SCL")
	)
	(segment
		(start 231.145588 -331.724)
		(end 234.823 -331.724)
		(width 0.11684)
		(layer "In4.Cu")
		(net "SMB_SML1_PMBUS_HSC_SCL")
	)
	(segment
		(start 219.77731 -350.730312)
		(end 219.77731 -363.756702)
		(width 0.11684)
		(layer "In4.Cu")
		(net "SMB_SML1_PMBUS_HSC_SCL")
	)
	(segment
		(start 230.071676 -332.797912)
		(end 231.145588 -331.724)
		(width 0.11684)
		(layer "In4.Cu")
		(net "SMB_SML1_PMBUS_HSC_SCL")
	)
	(segment
		(start 216.353898 -261.166102)
		(end 216.353898 -321.161664)
		(width 0.11684)
		(layer "In4.Cu")
		(net "SMB_SML1_PMBUS_HSC_SCL")
	)
	(segment
		(start 227.541836 -332.349602)
		(end 227.541836 -342.965786)
		(width 0.11684)
		(layer "In4.Cu")
		(net "SMB_SML1_PMBUS_HSC_SCL")
	)
	(segment
		(start 165.826694 -402.207984)
		(end 165.826694 -407.068274)
		(width 0.11684)
		(layer "In4.Cu")
		(net "SMB_SML1_PMBUS_HSC_SCL")
	)
	(segment
		(start 205.388718 -82.793332)
		(end 205.388718 -83.845908)
		(width 0.11684)
		(layer "In4.Cu")
		(net "SMB_SML1_PMBUS_HSC_SCL")
	)
	(segment
		(start 199.094852 -370.928392)
		(end 204.356208 -370.928392)
		(width 0.11684)
		(layer "In4.Cu")
		(net "SMB_SML1_PMBUS_HSC_SCL")
	)
	(segment
		(start 205.83525 -82.3468)
		(end 205.388718 -82.793332)
		(width 0.11684)
		(layer "In4.Cu")
		(net "SMB_SML1_PMBUS_HSC_SCL")
	)
	(segment
		(start 168.426638 -399.065242)
		(end 168.426638 -399.60804)
		(width 0.11684)
		(layer "In4.Cu")
		(net "SMB_SML1_PMBUS_HSC_SCL")
	)
	(segment
		(start 190.249556 -381.427482)
		(end 190.249556 -378.7013)
		(width 0.11684)
		(layer "In4.Cu")
		(net "SMB_SML1_PMBUS_HSC_SCL")
	)
	(segment
		(start 189.3951 -35.614356)
		(end 191.499744 -37.719)
		(width 0.11684)
		(layer "In4.Cu")
		(net "SMB_SML1_PMBUS_HSC_SCL")
	)
	(segment
		(start 191.957452 -376.993404)
		(end 193.02984 -376.993404)
		(width 0.11684)
		(layer "In4.Cu")
		(net "SMB_SML1_PMBUS_HSC_SCL")
	)
	(segment
		(start 198.383652 -43.600624)
		(end 198.383652 -59.218068)
		(width 0.11684)
		(layer "In4.Cu")
		(net "SMB_SML1_PMBUS_HSC_SCL")
	)
	(segment
		(start 205.994508 -68.106798)
		(end 207.012286 -69.124576)
		(width 0.11684)
		(layer "In4.Cu")
		(net "SMB_SML1_PMBUS_HSC_SCL")
	)
	(segment
		(start 170.922188 -15.439136)
		(end 171.831 -16.347948)
		(width 0.11684)
		(layer "In4.Cu")
		(net "SMB_SML1_PMBUS_HSC_SCL")
	)
	(segment
		(start 189.629288 -382.04775)
		(end 190.249556 -381.427482)
		(width 0.11684)
		(layer "In4.Cu")
		(net "SMB_SML1_PMBUS_HSC_SCL")
	)
	(segment
		(start 204.356208 -370.928392)
		(end 205.802738 -369.481862)
		(width 0.11684)
		(layer "In4.Cu")
		(net "SMB_SML1_PMBUS_HSC_SCL")
	)
	(segment
		(start 222.94215 -254.57785)
		(end 216.353898 -261.166102)
		(width 0.11684)
		(layer "In4.Cu")
		(net "SMB_SML1_PMBUS_HSC_SCL")
	)
	(segment
		(start 222.94215 -216.109296)
		(end 222.94215 -254.57785)
		(width 0.11684)
		(layer "In4.Cu")
		(net "SMB_SML1_PMBUS_HSC_SCL")
	)
	(segment
		(start 207.012286 -69.124576)
		(end 207.012286 -71.212456)
		(width 0.11684)
		(layer "In4.Cu")
		(net "SMB_SML1_PMBUS_HSC_SCL")
	)
	(segment
		(start 205.555342 -367.00841)
		(end 202.90028 -369.663472)
		(width 0.11684)
		(layer "In4.Cu")
		(net "SMB_SML1_PMBUS_HSC_SCL")
	)
	(segment
		(start 216.353898 -321.161664)
		(end 227.541836 -332.349602)
		(width 0.11684)
		(layer "In4.Cu")
		(net "SMB_SML1_PMBUS_HSC_SCL")
	)
	(segment
		(start 182.87238 -27.139646)
		(end 189.3951 -33.662366)
		(width 0.11684)
		(layer "In4.Cu")
		(net "SMB_SML1_PMBUS_HSC_SCL")
	)
	(segment
		(start 202.90028 -369.663472)
		(end 195.860162 -369.663472)
		(width 0.11684)
		(layer "In4.Cu")
		(net "SMB_SML1_PMBUS_HSC_SCL")
	)
	(segment
		(start 216.525602 -367.00841)
		(end 205.555342 -367.00841)
		(width 0.11684)
		(layer "In4.Cu")
		(net "SMB_SML1_PMBUS_HSC_SCL")
	)
	(segment
		(start 205.994508 -66.828924)
		(end 205.994508 -68.106798)
		(width 0.11684)
		(layer "In4.Cu")
		(net "SMB_SML1_PMBUS_HSC_SCL")
	)
	(segment
		(start 228.676454 -210.374992)
		(end 222.94215 -216.109296)
		(width 0.11684)
		(layer "In4.Cu")
		(net "SMB_SML1_PMBUS_HSC_SCL")
	)
	(segment
		(start 189.3951 -33.662366)
		(end 189.3951 -35.614356)
		(width 0.11684)
		(layer "In4.Cu")
		(net "SMB_SML1_PMBUS_HSC_SCL")
	)
	(segment
		(start 167.875712 -15.419578)
		(end 167.89527 -15.439136)
		(width 0.11684)
		(layer "In4.Cu")
		(net "SMB_SML1_PMBUS_HSC_SCL")
	)
	(segment
		(start 192.502028 -37.719)
		(end 198.383652 -43.600624)
		(width 0.11684)
		(layer "In4.Cu")
		(net "SMB_SML1_PMBUS_HSC_SCL")
	)
	(segment
		(start 182.87238 -25.888696)
		(end 182.87238 -27.139646)
		(width 0.11684)
		(layer "In4.Cu")
		(net "SMB_SML1_PMBUS_HSC_SCL")
	)
	(segment
		(start 173.707806 -397.388334)
		(end 172.40504 -398.6911)
		(width 0.11684)
		(layer "In4.Cu")
		(net "SMB_SML1_PMBUS_HSC_SCL")
	)
	(segment
		(start 193.02984 -376.993404)
		(end 199.094852 -370.928392)
		(width 0.11684)
		(layer "In4.Cu")
		(net "SMB_SML1_PMBUS_HSC_SCL")
	)
	(segment
		(start 171.831 -16.347948)
		(end 179.197254 -16.347948)
		(width 0.11684)
		(layer "In4.Cu")
		(net "SMB_SML1_PMBUS_HSC_SCL")
	)
	(segment
		(start 230.071676 -365.454184)
		(end 230.071676 -332.797912)
		(width 0.11684)
		(layer "In4.Cu")
		(net "SMB_SML1_PMBUS_HSC_SCL")
	)
	(segment
		(start 205.83525 -72.389492)
		(end 205.83525 -82.3468)
		(width 0.11684)
		(layer "In4.Cu")
		(net "SMB_SML1_PMBUS_HSC_SCL")
	)
	(segment
		(start 189.512194 -382.04775)
		(end 189.629288 -382.04775)
		(width 0.11684)
		(layer "In4.Cu")
		(net "SMB_SML1_PMBUS_HSC_SCL")
	)
	(segment
		(start 165.826694 -407.068274)
		(end 169.526204 -410.767784)
		(width 0.11684)
		(layer "In4.Cu")
		(net "SMB_SML1_PMBUS_HSC_SCL")
	)
	(segment
		(start 179.197254 -16.347948)
		(end 180.27523 -17.425924)
		(width 0.11684)
		(layer "In4.Cu")
		(net "SMB_SML1_PMBUS_HSC_SCL")
	)
	(segment
		(start 226.043998 -369.481862)
		(end 230.071676 -365.454184)
		(width 0.11684)
		(layer "In4.Cu")
		(net "SMB_SML1_PMBUS_HSC_SCL")
	)
	(segment
		(start 174.069248 -410.767784)
		(end 175.233838 -411.932374)
		(width 0.11684)
		(layer "In4.Cu")
		(net "SMB_SML1_PMBUS_HSC_SCL")
	)
	(segment
		(start 182.747158 -404.608284)
		(end 181.91099 -404.608284)
		(width 0.10668)
		(layer "F.Cu")
		(net "SMB_SML1_PMBUS_HSC_R_SDA")
	)
	(segment
		(start 183.02859 -404.15718)
		(end 183.02859 -404.326852)
		(width 0.10668)
		(layer "F.Cu")
		(net "SMB_SML1_PMBUS_HSC_R_SDA")
	)
	(segment
		(start 183.02859 -404.326852)
		(end 182.747158 -404.608284)
		(width 0.10668)
		(layer "F.Cu")
		(net "SMB_SML1_PMBUS_HSC_R_SDA")
	)
	(segment
		(start 181.470808 -405.048466)
		(end 181.450488 -405.048466)
		(width 0.10668)
		(layer "F.Cu")
		(net "SMB_SML1_PMBUS_HSC_R_SDA")
	)
	(segment
		(start 181.91099 -404.608284)
		(end 181.470808 -405.048466)
		(width 0.10668)
		(layer "F.Cu")
		(net "SMB_SML1_PMBUS_HSC_R_SDA")
	)
	(via
		(at 181.450488 -405.048466)
		(size 0.508)
		(drill 0.254)
		(layers "F.Cu" "B.Cu")
		(net "SMB_SML1_PMBUS_HSC_R_SDA")
	)
	(segment
		(start 181.336696 -405.182578)
		(end 181.336696 -405.700992)
		(width 0.10668)
		(layer "B.Cu")
		(net "SMB_SML1_PMBUS_HSC_R_SDA")
	)
	(segment
		(start 181.450488 -405.068786)
		(end 181.336696 -405.182578)
		(width 0.10668)
		(layer "B.Cu")
		(net "SMB_SML1_PMBUS_HSC_R_SDA")
	)
	(segment
		(start 181.450488 -405.048466)
		(end 181.450488 -405.068786)
		(width 0.10668)
		(layer "B.Cu")
		(net "SMB_SML1_PMBUS_HSC_R_SDA")
	)
	(segment
		(start 181.336696 -405.700992)
		(end 181.20614 -405.831548)
		(width 0.10668)
		(layer "B.Cu")
		(net "SMB_SML1_PMBUS_HSC_R_SDA")
	)
	(segment
		(start 181.20614 -406.346152)
		(end 181.37886 -406.518872)
		(width 0.10668)
		(layer "B.Cu")
		(net "SMB_SML1_PMBUS_HSC_R_SDA")
	)
	(segment
		(start 181.20614 -405.831548)
		(end 181.20614 -406.346152)
		(width 0.10668)
		(layer "B.Cu")
		(net "SMB_SML1_PMBUS_HSC_R_SDA")
	)
	(segment
		(start 182.598568 -405.676608)
		(end 182.598568 -405.384254)
		(width 0.10668)
		(layer "F.Cu")
		(net "SMB_SML1_PMBUS_HSC_L_SCL")
	)
	(segment
		(start 183.478424 -404.504398)
		(end 183.478424 -404.15718)
		(width 0.10668)
		(layer "F.Cu")
		(net "SMB_SML1_PMBUS_HSC_L_SCL")
	)
	(segment
		(start 182.598568 -405.384254)
		(end 183.478424 -404.504398)
		(width 0.10668)
		(layer "F.Cu")
		(net "SMB_SML1_PMBUS_HSC_L_SCL")
	)
	(via
		(at 182.598568 -405.676608)
		(size 0.508)
		(drill 0.254)
		(layers "F.Cu" "B.Cu")
		(net "SMB_SML1_PMBUS_HSC_L_SCL")
	)
	(segment
		(start 182.294276 -405.9809)
		(end 182.294276 -406.819862)
		(width 0.10668)
		(layer "B.Cu")
		(net "SMB_SML1_PMBUS_HSC_L_SCL")
	)
	(segment
		(start 182.598568 -405.676608)
		(end 182.294276 -405.9809)
		(width 0.10668)
		(layer "B.Cu")
		(net "SMB_SML1_PMBUS_HSC_L_SCL")
	)
	(segment
		(start 164.094668 -11.735054)
		(end 164.094668 -10.55243)
		(width 0.10668)
		(layer "F.Cu")
		(net "SMB_PMBUS_3V3AUX_SDA_R0")
	)
	(segment
		(start 163.867084 -13.599922)
		(end 163.867084 -11.962638)
		(width 0.10668)
		(layer "F.Cu")
		(net "SMB_PMBUS_3V3AUX_SDA_R0")
	)
	(segment
		(start 163.867084 -11.962638)
		(end 164.094668 -11.735054)
		(width 0.10668)
		(layer "F.Cu")
		(net "SMB_PMBUS_3V3AUX_SDA_R0")
	)
	(via
		(at 164.094668 -10.55243)
		(size 0.508)
		(drill 0.254)
		(layers "F.Cu" "B.Cu")
		(net "SMB_PMBUS_3V3AUX_SDA_R0")
	)
	(segment
		(start 163.886388 -13.25499)
		(end 163.886388 -10.76071)
		(width 0.10668)
		(layer "B.Cu")
		(net "SMB_PMBUS_3V3AUX_SDA_R0")
	)
	(segment
		(start 163.886388 -10.76071)
		(end 164.094668 -10.55243)
		(width 0.10668)
		(layer "B.Cu")
		(net "SMB_PMBUS_3V3AUX_SDA_R0")
	)
	(segment
		(start 164.467032 -13.599922)
		(end 164.467032 -12.21359)
		(width 0.10668)
		(layer "F.Cu")
		(net "SMB_PMBUS_3V3AUX_SCL_R0")
	)
	(segment
		(start 164.467032 -12.21359)
		(end 164.588698 -12.091924)
		(width 0.10668)
		(layer "F.Cu")
		(net "SMB_PMBUS_3V3AUX_SCL_R0")
	)
	(via
		(at 164.588698 -12.091924)
		(size 0.508)
		(drill 0.254)
		(layers "F.Cu" "B.Cu")
		(net "SMB_PMBUS_3V3AUX_SCL_R0")
	)
	(segment
		(start 164.902388 -12.405614)
		(end 164.588698 -12.091924)
		(width 0.10668)
		(layer "B.Cu")
		(net "SMB_PMBUS_3V3AUX_SCL_R0")
	)
	(segment
		(start 164.902388 -13.25499)
		(end 164.902388 -12.405614)
		(width 0.10668)
		(layer "B.Cu")
		(net "SMB_PMBUS_3V3AUX_SCL_R0")
	)
	(segment
		(start 267.742162 -72.262238)
		(end 258.62788 -63.147956)
		(width 0.10668)
		(layer "F.Cu")
		(net "SMB_SENSOR_M2_P1_3V3AUX_SDA")
	)
	(segment
		(start 156.540454 -42.635424)
		(end 157.175454 -42.000424)
		(width 0.10668)
		(layer "F.Cu")
		(net "SMB_SENSOR_M2_P1_3V3AUX_SDA")
	)
	(segment
		(start 277.089362 -115.44173)
		(end 277.752302 -116.10467)
		(width 0.10668)
		(layer "F.Cu")
		(net "SMB_SENSOR_M2_P1_3V3AUX_SDA")
	)
	(segment
		(start 274.312126 -111.288322)
		(end 275.534628 -110.06582)
		(width 0.10668)
		(layer "F.Cu")
		(net "SMB_SENSOR_M2_P1_3V3AUX_SDA")
	)
	(segment
		(start 275.534628 -110.06582)
		(end 285.739586 -110.06582)
		(width 0.10668)
		(layer "F.Cu")
		(net "SMB_SENSOR_M2_P1_3V3AUX_SDA")
	)
	(segment
		(start 292.951408 -94.314772)
		(end 288.600642 -89.964006)
		(width 0.10668)
		(layer "F.Cu")
		(net "SMB_SENSOR_M2_P1_3V3AUX_SDA")
	)
	(segment
		(start 292.951408 -102.853998)
		(end 292.951408 -94.314772)
		(width 0.10668)
		(layer "F.Cu")
		(net "SMB_SENSOR_M2_P1_3V3AUX_SDA")
	)
	(segment
		(start 285.739586 -110.06582)
		(end 292.951408 -102.853998)
		(width 0.10668)
		(layer "F.Cu")
		(net "SMB_SENSOR_M2_P1_3V3AUX_SDA")
	)
	(segment
		(start 281.276044 -89.964006)
		(end 267.742162 -76.430124)
		(width 0.10668)
		(layer "F.Cu")
		(net "SMB_SENSOR_M2_P1_3V3AUX_SDA")
	)
	(segment
		(start 288.600642 -89.964006)
		(end 281.276044 -89.964006)
		(width 0.10668)
		(layer "F.Cu")
		(net "SMB_SENSOR_M2_P1_3V3AUX_SDA")
	)
	(segment
		(start 155.651454 -42.635424)
		(end 156.540454 -42.635424)
		(width 0.10668)
		(layer "F.Cu")
		(net "SMB_SENSOR_M2_P1_3V3AUX_SDA")
	)
	(segment
		(start 279.113742 -116.67617)
		(end 278.323802 -116.67617)
		(width 0.10668)
		(layer "F.Cu")
		(net "SMB_SENSOR_M2_P1_3V3AUX_SDA")
	)
	(segment
		(start 276.056852 -115.44173)
		(end 274.312126 -113.697004)
		(width 0.10668)
		(layer "F.Cu")
		(net "SMB_SENSOR_M2_P1_3V3AUX_SDA")
	)
	(segment
		(start 278.323802 -116.67617)
		(end 277.752302 -116.10467)
		(width 0.10668)
		(layer "F.Cu")
		(net "SMB_SENSOR_M2_P1_3V3AUX_SDA")
	)
	(segment
		(start 274.312126 -113.697004)
		(end 274.312126 -111.288322)
		(width 0.10668)
		(layer "F.Cu")
		(net "SMB_SENSOR_M2_P1_3V3AUX_SDA")
	)
	(segment
		(start 267.742162 -76.430124)
		(end 267.742162 -72.262238)
		(width 0.10668)
		(layer "F.Cu")
		(net "SMB_SENSOR_M2_P1_3V3AUX_SDA")
	)
	(segment
		(start 258.62788 -63.147956)
		(end 258.62788 -61.884052)
		(width 0.10668)
		(layer "F.Cu")
		(net "SMB_SENSOR_M2_P1_3V3AUX_SDA")
	)
	(segment
		(start 276.056852 -115.44173)
		(end 277.089362 -115.44173)
		(width 0.10668)
		(layer "F.Cu")
		(net "SMB_SENSOR_M2_P1_3V3AUX_SDA")
	)
	(via
		(at 258.62788 -61.884052)
		(size 0.508)
		(drill 0.254)
		(layers "F.Cu" "B.Cu")
		(net "SMB_SENSOR_M2_P1_3V3AUX_SDA")
	)
	(via
		(at 157.175454 -42.000424)
		(size 0.508)
		(drill 0.254)
		(layers "F.Cu" "B.Cu")
		(net "SMB_SENSOR_M2_P1_3V3AUX_SDA")
	)
	(segment
		(start 225.334322 -59.7916)
		(end 225.334576 -59.7916)
		(width 0.11684)
		(layer "In6.Cu")
		(net "SMB_SENSOR_M2_P1_3V3AUX_SDA")
	)
	(segment
		(start 189.895988 -42.1894)
		(end 191.91224 -42.1894)
		(width 0.11684)
		(layer "In6.Cu")
		(net "SMB_SENSOR_M2_P1_3V3AUX_SDA")
	)
	(segment
		(start 166.06139 -37.769546)
		(end 167.401748 -36.429188)
		(width 0.11684)
		(layer "In6.Cu")
		(net "SMB_SENSOR_M2_P1_3V3AUX_SDA")
	)
	(segment
		(start 214.20328 -41.072562)
		(end 219.983304 -46.852586)
		(width 0.11684)
		(layer "In6.Cu")
		(net "SMB_SENSOR_M2_P1_3V3AUX_SDA")
	)
	(segment
		(start 192.438528 -41.663112)
		(end 207.625442 -41.663112)
		(width 0.11684)
		(layer "In6.Cu")
		(net "SMB_SENSOR_M2_P1_3V3AUX_SDA")
	)
	(segment
		(start 167.401748 -36.429188)
		(end 169.066464 -36.429188)
		(width 0.11684)
		(layer "In6.Cu")
		(net "SMB_SENSOR_M2_P1_3V3AUX_SDA")
	)
	(segment
		(start 237.981998 -62.348872)
		(end 258.16306 -62.348872)
		(width 0.11684)
		(layer "In6.Cu")
		(net "SMB_SENSOR_M2_P1_3V3AUX_SDA")
	)
	(segment
		(start 174.439072 -36.878006)
		(end 176.362868 -36.878006)
		(width 0.11684)
		(layer "In6.Cu")
		(net "SMB_SENSOR_M2_P1_3V3AUX_SDA")
	)
	(segment
		(start 186.644534 -41.924478)
		(end 189.631066 -41.924478)
		(width 0.11684)
		(layer "In6.Cu")
		(net "SMB_SENSOR_M2_P1_3V3AUX_SDA")
	)
	(segment
		(start 172.69079 -35.129724)
		(end 174.439072 -36.878006)
		(width 0.11684)
		(layer "In6.Cu")
		(net "SMB_SENSOR_M2_P1_3V3AUX_SDA")
	)
	(segment
		(start 177.246534 -37.761672)
		(end 180.145182 -37.761672)
		(width 0.11684)
		(layer "In6.Cu")
		(net "SMB_SENSOR_M2_P1_3V3AUX_SDA")
	)
	(segment
		(start 157.175454 -42.000424)
		(end 157.863794 -42.000424)
		(width 0.11684)
		(layer "In6.Cu")
		(net "SMB_SENSOR_M2_P1_3V3AUX_SDA")
	)
	(segment
		(start 225.334576 -59.7916)
		(end 228.495606 -62.95263)
		(width 0.11684)
		(layer "In6.Cu")
		(net "SMB_SENSOR_M2_P1_3V3AUX_SDA")
	)
	(segment
		(start 170.365928 -35.129724)
		(end 172.69079 -35.129724)
		(width 0.11684)
		(layer "In6.Cu")
		(net "SMB_SENSOR_M2_P1_3V3AUX_SDA")
	)
	(segment
		(start 219.983304 -54.440582)
		(end 225.334322 -59.7916)
		(width 0.11684)
		(layer "In6.Cu")
		(net "SMB_SENSOR_M2_P1_3V3AUX_SDA")
	)
	(segment
		(start 207.625442 -41.663112)
		(end 208.215992 -41.072562)
		(width 0.11684)
		(layer "In6.Cu")
		(net "SMB_SENSOR_M2_P1_3V3AUX_SDA")
	)
	(segment
		(start 237.37824 -62.95263)
		(end 237.981998 -62.348872)
		(width 0.11684)
		(layer "In6.Cu")
		(net "SMB_SENSOR_M2_P1_3V3AUX_SDA")
	)
	(segment
		(start 162.094672 -37.769546)
		(end 166.06139 -37.769546)
		(width 0.11684)
		(layer "In6.Cu")
		(net "SMB_SENSOR_M2_P1_3V3AUX_SDA")
	)
	(segment
		(start 208.215992 -41.072562)
		(end 214.20328 -41.072562)
		(width 0.11684)
		(layer "In6.Cu")
		(net "SMB_SENSOR_M2_P1_3V3AUX_SDA")
	)
	(segment
		(start 180.145182 -37.761672)
		(end 181.386734 -39.003224)
		(width 0.11684)
		(layer "In6.Cu")
		(net "SMB_SENSOR_M2_P1_3V3AUX_SDA")
	)
	(segment
		(start 176.362868 -36.878006)
		(end 177.246534 -37.761672)
		(width 0.11684)
		(layer "In6.Cu")
		(net "SMB_SENSOR_M2_P1_3V3AUX_SDA")
	)
	(segment
		(start 183.72328 -39.003224)
		(end 186.644534 -41.924478)
		(width 0.11684)
		(layer "In6.Cu")
		(net "SMB_SENSOR_M2_P1_3V3AUX_SDA")
	)
	(segment
		(start 169.066464 -36.429188)
		(end 170.365928 -35.129724)
		(width 0.11684)
		(layer "In6.Cu")
		(net "SMB_SENSOR_M2_P1_3V3AUX_SDA")
	)
	(segment
		(start 219.983304 -46.852586)
		(end 219.983304 -54.440582)
		(width 0.11684)
		(layer "In6.Cu")
		(net "SMB_SENSOR_M2_P1_3V3AUX_SDA")
	)
	(segment
		(start 157.863794 -42.000424)
		(end 162.094672 -37.769546)
		(width 0.11684)
		(layer "In6.Cu")
		(net "SMB_SENSOR_M2_P1_3V3AUX_SDA")
	)
	(segment
		(start 181.386734 -39.003224)
		(end 183.72328 -39.003224)
		(width 0.11684)
		(layer "In6.Cu")
		(net "SMB_SENSOR_M2_P1_3V3AUX_SDA")
	)
	(segment
		(start 191.91224 -42.1894)
		(end 192.438528 -41.663112)
		(width 0.11684)
		(layer "In6.Cu")
		(net "SMB_SENSOR_M2_P1_3V3AUX_SDA")
	)
	(segment
		(start 228.495606 -62.95263)
		(end 237.37824 -62.95263)
		(width 0.11684)
		(layer "In6.Cu")
		(net "SMB_SENSOR_M2_P1_3V3AUX_SDA")
	)
	(segment
		(start 189.631066 -41.924478)
		(end 189.895988 -42.1894)
		(width 0.11684)
		(layer "In6.Cu")
		(net "SMB_SENSOR_M2_P1_3V3AUX_SDA")
	)
	(segment
		(start 258.16306 -62.348872)
		(end 258.62788 -61.884052)
		(width 0.11684)
		(layer "In6.Cu")
		(net "SMB_SENSOR_M2_P1_3V3AUX_SDA")
	)
	(segment
		(start 260.662166 -64.678814)
		(end 260.15188 -64.168528)
		(width 0.10668)
		(layer "F.Cu")
		(net "SMB_SENSOR_M2_P1_3V3AUX_SCL")
	)
	(segment
		(start 278.704802 -115.66017)
		(end 277.752302 -114.70767)
		(width 0.10668)
		(layer "F.Cu")
		(net "SMB_SENSOR_M2_P1_3V3AUX_SCL")
	)
	(segment
		(start 260.15188 -64.168528)
		(end 260.15188 -61.884052)
		(width 0.10668)
		(layer "F.Cu")
		(net "SMB_SENSOR_M2_P1_3V3AUX_SCL")
	)
	(segment
		(start 279.113742 -115.66017)
		(end 278.704802 -115.66017)
		(width 0.10668)
		(layer "F.Cu")
		(net "SMB_SENSOR_M2_P1_3V3AUX_SCL")
	)
	(segment
		(start 281.417268 -89.623646)
		(end 288.741866 -89.623646)
		(width 0.10668)
		(layer "F.Cu")
		(net "SMB_SENSOR_M2_P1_3V3AUX_SCL")
	)
	(segment
		(start 155.651454 -43.28541)
		(end 157.175454 -43.28541)
		(width 0.10668)
		(layer "F.Cu")
		(net "SMB_SENSOR_M2_P1_3V3AUX_SCL")
	)
	(segment
		(start 293.291768 -94.173548)
		(end 293.291768 -102.995222)
		(width 0.10668)
		(layer "F.Cu")
		(net "SMB_SENSOR_M2_P1_3V3AUX_SCL")
	)
	(segment
		(start 275.715222 -110.40618)
		(end 274.686268 -111.435134)
		(width 0.10668)
		(layer "F.Cu")
		(net "SMB_SENSOR_M2_P1_3V3AUX_SCL")
	)
	(segment
		(start 277.094442 -114.04981)
		(end 277.752302 -114.70767)
		(width 0.10668)
		(layer "F.Cu")
		(net "SMB_SENSOR_M2_P1_3V3AUX_SCL")
	)
	(segment
		(start 274.686268 -113.177828)
		(end 275.55825 -114.04981)
		(width 0.10668)
		(layer "F.Cu")
		(net "SMB_SENSOR_M2_P1_3V3AUX_SCL")
	)
	(segment
		(start 268.082522 -76.2889)
		(end 281.417268 -89.623646)
		(width 0.10668)
		(layer "F.Cu")
		(net "SMB_SENSOR_M2_P1_3V3AUX_SCL")
	)
	(segment
		(start 293.291768 -102.995222)
		(end 285.88081 -110.40618)
		(width 0.10668)
		(layer "F.Cu")
		(net "SMB_SENSOR_M2_P1_3V3AUX_SCL")
	)
	(segment
		(start 260.662166 -64.678814)
		(end 268.082522 -72.09917)
		(width 0.10668)
		(layer "F.Cu")
		(net "SMB_SENSOR_M2_P1_3V3AUX_SCL")
	)
	(segment
		(start 285.88081 -110.40618)
		(end 275.715222 -110.40618)
		(width 0.10668)
		(layer "F.Cu")
		(net "SMB_SENSOR_M2_P1_3V3AUX_SCL")
	)
	(segment
		(start 275.55825 -114.04981)
		(end 277.094442 -114.04981)
		(width 0.10668)
		(layer "F.Cu")
		(net "SMB_SENSOR_M2_P1_3V3AUX_SCL")
	)
	(segment
		(start 288.741866 -89.623646)
		(end 293.291768 -94.173548)
		(width 0.10668)
		(layer "F.Cu")
		(net "SMB_SENSOR_M2_P1_3V3AUX_SCL")
	)
	(segment
		(start 268.082522 -72.09917)
		(end 268.082522 -76.2889)
		(width 0.10668)
		(layer "F.Cu")
		(net "SMB_SENSOR_M2_P1_3V3AUX_SCL")
	)
	(segment
		(start 274.686268 -111.435134)
		(end 274.686268 -113.177828)
		(width 0.10668)
		(layer "F.Cu")
		(net "SMB_SENSOR_M2_P1_3V3AUX_SCL")
	)
	(via
		(at 157.175454 -43.28541)
		(size 0.508)
		(drill 0.254)
		(layers "F.Cu" "B.Cu")
		(net "SMB_SENSOR_M2_P1_3V3AUX_SCL")
	)
	(via
		(at 260.15188 -61.884052)
		(size 0.508)
		(drill 0.254)
		(layers "F.Cu" "B.Cu")
		(net "SMB_SENSOR_M2_P1_3V3AUX_SCL")
	)
	(segment
		(start 208.343246 -41.541954)
		(end 210.711796 -41.541954)
		(width 0.11684)
		(layer "In6.Cu")
		(net "SMB_SENSOR_M2_P1_3V3AUX_SCL")
	)
	(segment
		(start 188.431424 -44.30776)
		(end 190.57874 -44.30776)
		(width 0.11684)
		(layer "In6.Cu")
		(net "SMB_SENSOR_M2_P1_3V3AUX_SCL")
	)
	(segment
		(start 219.561664 -47.027338)
		(end 219.561664 -54.615334)
		(width 0.11684)
		(layer "In6.Cu")
		(net "SMB_SENSOR_M2_P1_3V3AUX_SCL")
	)
	(segment
		(start 166.236396 -38.191186)
		(end 167.576754 -36.850828)
		(width 0.11684)
		(layer "In6.Cu")
		(net "SMB_SENSOR_M2_P1_3V3AUX_SCL")
	)
	(segment
		(start 238.15675 -62.770512)
		(end 259.26542 -62.770512)
		(width 0.11684)
		(layer "In6.Cu")
		(net "SMB_SENSOR_M2_P1_3V3AUX_SCL")
	)
	(segment
		(start 190.57874 -44.30776)
		(end 192.801748 -42.084752)
		(width 0.11684)
		(layer "In6.Cu")
		(net "SMB_SENSOR_M2_P1_3V3AUX_SCL")
	)
	(segment
		(start 214.874348 -42.340022)
		(end 219.561664 -47.027338)
		(width 0.11684)
		(layer "In6.Cu")
		(net "SMB_SENSOR_M2_P1_3V3AUX_SCL")
	)
	(segment
		(start 167.576754 -36.850828)
		(end 169.492168 -36.850828)
		(width 0.11684)
		(layer "In6.Cu")
		(net "SMB_SENSOR_M2_P1_3V3AUX_SCL")
	)
	(segment
		(start 259.26542 -62.770512)
		(end 260.15188 -61.884052)
		(width 0.11684)
		(layer "In6.Cu")
		(net "SMB_SENSOR_M2_P1_3V3AUX_SCL")
	)
	(segment
		(start 211.509864 -42.340022)
		(end 214.874348 -42.340022)
		(width 0.11684)
		(layer "In6.Cu")
		(net "SMB_SENSOR_M2_P1_3V3AUX_SCL")
	)
	(segment
		(start 179.97043 -38.183312)
		(end 181.211982 -39.424864)
		(width 0.11684)
		(layer "In6.Cu")
		(net "SMB_SENSOR_M2_P1_3V3AUX_SCL")
	)
	(segment
		(start 192.801748 -42.084752)
		(end 207.800448 -42.084752)
		(width 0.11684)
		(layer "In6.Cu")
		(net "SMB_SENSOR_M2_P1_3V3AUX_SCL")
	)
	(segment
		(start 174.26432 -37.299646)
		(end 176.188116 -37.299646)
		(width 0.11684)
		(layer "In6.Cu")
		(net "SMB_SENSOR_M2_P1_3V3AUX_SCL")
	)
	(segment
		(start 181.211982 -39.424864)
		(end 183.548528 -39.424864)
		(width 0.11684)
		(layer "In6.Cu")
		(net "SMB_SENSOR_M2_P1_3V3AUX_SCL")
	)
	(segment
		(start 172.516038 -35.551364)
		(end 174.26432 -37.299646)
		(width 0.11684)
		(layer "In6.Cu")
		(net "SMB_SENSOR_M2_P1_3V3AUX_SCL")
	)
	(segment
		(start 157.175454 -43.28541)
		(end 162.269678 -38.191186)
		(width 0.11684)
		(layer "In6.Cu")
		(net "SMB_SENSOR_M2_P1_3V3AUX_SCL")
	)
	(segment
		(start 170.791632 -35.551364)
		(end 172.516038 -35.551364)
		(width 0.11684)
		(layer "In6.Cu")
		(net "SMB_SENSOR_M2_P1_3V3AUX_SCL")
	)
	(segment
		(start 207.800448 -42.084752)
		(end 208.343246 -41.541954)
		(width 0.11684)
		(layer "In6.Cu")
		(net "SMB_SENSOR_M2_P1_3V3AUX_SCL")
	)
	(segment
		(start 162.269678 -38.191186)
		(end 166.236396 -38.191186)
		(width 0.11684)
		(layer "In6.Cu")
		(net "SMB_SENSOR_M2_P1_3V3AUX_SCL")
	)
	(segment
		(start 237.548928 -63.378334)
		(end 238.15675 -62.770512)
		(width 0.11684)
		(layer "In6.Cu")
		(net "SMB_SENSOR_M2_P1_3V3AUX_SCL")
	)
	(segment
		(start 176.188116 -37.299646)
		(end 177.071782 -38.183312)
		(width 0.11684)
		(layer "In6.Cu")
		(net "SMB_SENSOR_M2_P1_3V3AUX_SCL")
	)
	(segment
		(start 228.324918 -63.378334)
		(end 237.548928 -63.378334)
		(width 0.11684)
		(layer "In6.Cu")
		(net "SMB_SENSOR_M2_P1_3V3AUX_SCL")
	)
	(segment
		(start 169.492168 -36.850828)
		(end 170.791632 -35.551364)
		(width 0.11684)
		(layer "In6.Cu")
		(net "SMB_SENSOR_M2_P1_3V3AUX_SCL")
	)
	(segment
		(start 225.159824 -60.21324)
		(end 228.324918 -63.378334)
		(width 0.11684)
		(layer "In6.Cu")
		(net "SMB_SENSOR_M2_P1_3V3AUX_SCL")
	)
	(segment
		(start 210.711796 -41.541954)
		(end 211.509864 -42.340022)
		(width 0.11684)
		(layer "In6.Cu")
		(net "SMB_SENSOR_M2_P1_3V3AUX_SCL")
	)
	(segment
		(start 225.15957 -60.21324)
		(end 225.159824 -60.21324)
		(width 0.11684)
		(layer "In6.Cu")
		(net "SMB_SENSOR_M2_P1_3V3AUX_SCL")
	)
	(segment
		(start 219.561664 -54.615334)
		(end 225.15957 -60.21324)
		(width 0.11684)
		(layer "In6.Cu")
		(net "SMB_SENSOR_M2_P1_3V3AUX_SCL")
	)
	(segment
		(start 183.548528 -39.424864)
		(end 188.431424 -44.30776)
		(width 0.11684)
		(layer "In6.Cu")
		(net "SMB_SENSOR_M2_P1_3V3AUX_SCL")
	)
	(segment
		(start 177.071782 -38.183312)
		(end 179.97043 -38.183312)
		(width 0.11684)
		(layer "In6.Cu")
		(net "SMB_SENSOR_M2_P1_3V3AUX_SCL")
	)
	(segment
		(start 212.146134 -42.962068)
		(end 213.247478 -44.063412)
		(width 0.10668)
		(layer "F.Cu")
		(net "SMB_SENSOR_E1S_3V3AUX_SDA")
	)
	(segment
		(start 279.085802 -114.64417)
		(end 277.752302 -113.31067)
		(width 0.10668)
		(layer "F.Cu")
		(net "SMB_SENSOR_E1S_3V3AUX_SDA")
	)
	(segment
		(start 212.146134 -41.620948)
		(end 212.146134 -42.962068)
		(width 0.10668)
		(layer "F.Cu")
		(net "SMB_SENSOR_E1S_3V3AUX_SDA")
	)
	(segment
		(start 279.113742 -114.64417)
		(end 279.085802 -114.64417)
		(width 0.10668)
		(layer "F.Cu")
		(net "SMB_SENSOR_E1S_3V3AUX_SDA")
	)
	(segment
		(start 277.094442 -112.65281)
		(end 277.752302 -113.31067)
		(width 0.10668)
		(layer "F.Cu")
		(net "SMB_SENSOR_E1S_3V3AUX_SDA")
	)
	(segment
		(start 213.247478 -44.063412)
		(end 214.010748 -44.063412)
		(width 0.10668)
		(layer "F.Cu")
		(net "SMB_SENSOR_E1S_3V3AUX_SDA")
	)
	(segment
		(start 275.54936 -112.65281)
		(end 277.094442 -112.65281)
		(width 0.10668)
		(layer "F.Cu")
		(net "SMB_SENSOR_E1S_3V3AUX_SDA")
	)
	(via
		(at 212.146134 -41.620948)
		(size 0.508)
		(drill 0.254)
		(layers "F.Cu" "B.Cu")
		(net "SMB_SENSOR_E1S_3V3AUX_SDA")
	)
	(via
		(at 275.54936 -112.65281)
		(size 0.508)
		(drill 0.254)
		(layers "F.Cu" "B.Cu")
		(net "SMB_SENSOR_E1S_3V3AUX_SDA")
	)
	(segment
		(start 280.408888 -72.724772)
		(end 280.408888 -107.128564)
		(width 0.11684)
		(layer "In4.Cu")
		(net "SMB_SENSOR_E1S_3V3AUX_SDA")
	)
	(segment
		(start 272.336514 -64.652398)
		(end 280.408888 -72.724772)
		(width 0.11684)
		(layer "In4.Cu")
		(net "SMB_SENSOR_E1S_3V3AUX_SDA")
	)
	(segment
		(start 252.757686 -68.45681)
		(end 253.922784 -69.621908)
		(width 0.11684)
		(layer "In4.Cu")
		(net "SMB_SENSOR_E1S_3V3AUX_SDA")
	)
	(segment
		(start 280.408888 -107.128564)
		(end 276.97557 -110.561882)
		(width 0.11684)
		(layer "In4.Cu")
		(net "SMB_SENSOR_E1S_3V3AUX_SDA")
	)
	(segment
		(start 276.97557 -110.561882)
		(end 275.641308 -110.561882)
		(width 0.11684)
		(layer "In4.Cu")
		(net "SMB_SENSOR_E1S_3V3AUX_SDA")
	)
	(segment
		(start 233.302302 -68.45681)
		(end 252.757686 -68.45681)
		(width 0.11684)
		(layer "In4.Cu")
		(net "SMB_SENSOR_E1S_3V3AUX_SDA")
	)
	(segment
		(start 212.787738 -47.942246)
		(end 233.302302 -68.45681)
		(width 0.11684)
		(layer "In4.Cu")
		(net "SMB_SENSOR_E1S_3V3AUX_SDA")
	)
	(segment
		(start 275.641308 -110.561882)
		(end 275.08454 -111.11865)
		(width 0.11684)
		(layer "In4.Cu")
		(net "SMB_SENSOR_E1S_3V3AUX_SDA")
	)
	(segment
		(start 212.146134 -41.620948)
		(end 212.146134 -44.70908)
		(width 0.11684)
		(layer "In4.Cu")
		(net "SMB_SENSOR_E1S_3V3AUX_SDA")
	)
	(segment
		(start 253.922784 -69.621908)
		(end 262.416036 -69.621908)
		(width 0.11684)
		(layer "In4.Cu")
		(net "SMB_SENSOR_E1S_3V3AUX_SDA")
	)
	(segment
		(start 275.08454 -112.18799)
		(end 275.54936 -112.65281)
		(width 0.11684)
		(layer "In4.Cu")
		(net "SMB_SENSOR_E1S_3V3AUX_SDA")
	)
	(segment
		(start 212.787738 -45.350684)
		(end 212.787738 -47.942246)
		(width 0.11684)
		(layer "In4.Cu")
		(net "SMB_SENSOR_E1S_3V3AUX_SDA")
	)
	(segment
		(start 267.385546 -64.652398)
		(end 272.336514 -64.652398)
		(width 0.11684)
		(layer "In4.Cu")
		(net "SMB_SENSOR_E1S_3V3AUX_SDA")
	)
	(segment
		(start 212.146134 -44.70908)
		(end 212.787738 -45.350684)
		(width 0.11684)
		(layer "In4.Cu")
		(net "SMB_SENSOR_E1S_3V3AUX_SDA")
	)
	(segment
		(start 275.08454 -111.11865)
		(end 275.08454 -112.18799)
		(width 0.11684)
		(layer "In4.Cu")
		(net "SMB_SENSOR_E1S_3V3AUX_SDA")
	)
	(segment
		(start 262.416036 -69.621908)
		(end 267.385546 -64.652398)
		(width 0.11684)
		(layer "In4.Cu")
		(net "SMB_SENSOR_E1S_3V3AUX_SDA")
	)
	(segment
		(start 277.150068 -111.311436)
		(end 277.752302 -111.91367)
		(width 0.10668)
		(layer "F.Cu")
		(net "SMB_SENSOR_E1S_3V3AUX_SCL")
	)
	(segment
		(start 213.303358 -43.413172)
		(end 214.010748 -43.413172)
		(width 0.10668)
		(layer "F.Cu")
		(net "SMB_SENSOR_E1S_3V3AUX_SCL")
	)
	(segment
		(start 279.113742 -113.62817)
		(end 277.752302 -112.26673)
		(width 0.10668)
		(layer "F.Cu")
		(net "SMB_SENSOR_E1S_3V3AUX_SCL")
	)
	(segment
		(start 275.54936 -111.311436)
		(end 277.150068 -111.311436)
		(width 0.10668)
		(layer "F.Cu")
		(net "SMB_SENSOR_E1S_3V3AUX_SCL")
	)
	(segment
		(start 277.752302 -112.26673)
		(end 277.752302 -111.91367)
		(width 0.10668)
		(layer "F.Cu")
		(net "SMB_SENSOR_E1S_3V3AUX_SCL")
	)
	(segment
		(start 212.908134 -43.017948)
		(end 213.303358 -43.413172)
		(width 0.10668)
		(layer "F.Cu")
		(net "SMB_SENSOR_E1S_3V3AUX_SCL")
	)
	(segment
		(start 212.908134 -41.620948)
		(end 212.908134 -43.017948)
		(width 0.10668)
		(layer "F.Cu")
		(net "SMB_SENSOR_E1S_3V3AUX_SCL")
	)
	(via
		(at 275.54936 -111.311436)
		(size 0.508)
		(drill 0.254)
		(layers "F.Cu" "B.Cu")
		(net "SMB_SENSOR_E1S_3V3AUX_SCL")
	)
	(via
		(at 212.908134 -41.620948)
		(size 0.508)
		(drill 0.254)
		(layers "F.Cu" "B.Cu")
		(net "SMB_SENSOR_E1S_3V3AUX_SCL")
	)
	(segment
		(start 212.908134 -41.620948)
		(end 213.209378 -41.922192)
		(width 0.11684)
		(layer "In4.Cu")
		(net "SMB_SENSOR_E1S_3V3AUX_SCL")
	)
	(segment
		(start 280.830528 -107.303316)
		(end 276.822408 -111.311436)
		(width 0.11684)
		(layer "In4.Cu")
		(net "SMB_SENSOR_E1S_3V3AUX_SCL")
	)
	(segment
		(start 276.822408 -111.311436)
		(end 275.54936 -111.311436)
		(width 0.11684)
		(layer "In4.Cu")
		(net "SMB_SENSOR_E1S_3V3AUX_SCL")
	)
	(segment
		(start 213.209378 -47.767494)
		(end 233.432096 -67.990212)
		(width 0.11684)
		(layer "In4.Cu")
		(net "SMB_SENSOR_E1S_3V3AUX_SCL")
	)
	(segment
		(start 233.432096 -67.990212)
		(end 253.00559 -67.990212)
		(width 0.11684)
		(layer "In4.Cu")
		(net "SMB_SENSOR_E1S_3V3AUX_SCL")
	)
	(segment
		(start 262.241284 -69.200268)
		(end 267.210794 -64.230758)
		(width 0.11684)
		(layer "In4.Cu")
		(net "SMB_SENSOR_E1S_3V3AUX_SCL")
	)
	(segment
		(start 267.210794 -64.230758)
		(end 272.511266 -64.230758)
		(width 0.11684)
		(layer "In4.Cu")
		(net "SMB_SENSOR_E1S_3V3AUX_SCL")
	)
	(segment
		(start 272.511266 -64.230758)
		(end 280.830528 -72.55002)
		(width 0.11684)
		(layer "In4.Cu")
		(net "SMB_SENSOR_E1S_3V3AUX_SCL")
	)
	(segment
		(start 253.00559 -67.990212)
		(end 254.215646 -69.200268)
		(width 0.11684)
		(layer "In4.Cu")
		(net "SMB_SENSOR_E1S_3V3AUX_SCL")
	)
	(segment
		(start 254.215646 -69.200268)
		(end 262.241284 -69.200268)
		(width 0.11684)
		(layer "In4.Cu")
		(net "SMB_SENSOR_E1S_3V3AUX_SCL")
	)
	(segment
		(start 213.209378 -41.922192)
		(end 213.209378 -47.767494)
		(width 0.11684)
		(layer "In4.Cu")
		(net "SMB_SENSOR_E1S_3V3AUX_SCL")
	)
	(segment
		(start 280.830528 -72.55002)
		(end 280.830528 -107.303316)
		(width 0.11684)
		(layer "In4.Cu")
		(net "SMB_SENSOR_E1S_3V3AUX_SCL")
	)
	(segment
		(start 161.505646 -353.917504)
		(end 161.29 -354.13315)
		(width 0.10668)
		(layer "F.Cu")
		(net "SMB_SCM_2_R2_SDA")
	)
	(segment
		(start 161.06013 -353.746816)
		(end 161.230818 -353.917504)
		(width 0.10668)
		(layer "F.Cu")
		(net "SMB_SCM_2_R2_SDA")
	)
	(segment
		(start 161.06013 -353.068128)
		(end 161.06013 -353.746816)
		(width 0.10668)
		(layer "F.Cu")
		(net "SMB_SCM_2_R2_SDA")
	)
	(segment
		(start 161.29 -354.13315)
		(end 161.29 -355.96195)
		(width 0.10668)
		(layer "F.Cu")
		(net "SMB_SCM_2_R2_SDA")
	)
	(segment
		(start 161.230818 -353.917504)
		(end 161.505646 -353.917504)
		(width 0.10668)
		(layer "F.Cu")
		(net "SMB_SCM_2_R2_SDA")
	)
	(via
		(at 18.734278 -367.919)
		(size 0.508)
		(drill 0.254)
		(layers "F.Cu" "B.Cu")
		(net "SMB_SCM_2_R2_SDA")
	)
	(via
		(at 161.505646 -353.917504)
		(size 0.508)
		(drill 0.254)
		(layers "F.Cu" "B.Cu")
		(net "SMB_SCM_2_R2_SDA")
	)
	(segment
		(start 19.91995 -367.919)
		(end 18.734278 -367.919)
		(width 0.10668)
		(layer "B.Cu")
		(net "SMB_SCM_2_R2_SDA")
	)
	(segment
		(start 160.598104 -354.825046)
		(end 160.598104 -358.429306)
		(width 0.11684)
		(layer "In2.Cu")
		(net "SMB_SCM_2_R2_SDA")
	)
	(segment
		(start 26.573988 -369.245134)
		(end 26.574242 -369.245134)
		(width 0.11684)
		(layer "In2.Cu")
		(net "SMB_SCM_2_R2_SDA")
	)
	(segment
		(start 28.367482 -367.45164)
		(end 26.573988 -369.245134)
		(width 0.11684)
		(layer "In2.Cu")
		(net "SMB_SCM_2_R2_SDA")
	)
	(segment
		(start 40.525446 -364.790228)
		(end 39.840154 -364.104936)
		(width 0.11684)
		(layer "In2.Cu")
		(net "SMB_SCM_2_R2_SDA")
	)
	(segment
		(start 20.184364 -369.369086)
		(end 18.734278 -367.919)
		(width 0.11684)
		(layer "In2.Cu")
		(net "SMB_SCM_2_R2_SDA")
	)
	(segment
		(start 138.09345 -363.091984)
		(end 136.395206 -364.790228)
		(width 0.11684)
		(layer "In2.Cu")
		(net "SMB_SCM_2_R2_SDA")
	)
	(segment
		(start 161.505646 -353.917504)
		(end 160.598104 -354.825046)
		(width 0.11684)
		(layer "In2.Cu")
		(net "SMB_SCM_2_R2_SDA")
	)
	(segment
		(start 39.19855 -364.104936)
		(end 38.891464 -364.412022)
		(width 0.11684)
		(layer "In2.Cu")
		(net "SMB_SCM_2_R2_SDA")
	)
	(segment
		(start 26.574242 -369.245642)
		(end 26.450798 -369.369086)
		(width 0.11684)
		(layer "In2.Cu")
		(net "SMB_SCM_2_R2_SDA")
	)
	(segment
		(start 26.450798 -369.369086)
		(end 20.184364 -369.369086)
		(width 0.11684)
		(layer "In2.Cu")
		(net "SMB_SCM_2_R2_SDA")
	)
	(segment
		(start 155.935426 -363.091984)
		(end 138.09345 -363.091984)
		(width 0.11684)
		(layer "In2.Cu")
		(net "SMB_SCM_2_R2_SDA")
	)
	(segment
		(start 26.574242 -369.245134)
		(end 26.574242 -369.245642)
		(width 0.11684)
		(layer "In2.Cu")
		(net "SMB_SCM_2_R2_SDA")
	)
	(segment
		(start 136.395206 -364.790228)
		(end 40.525446 -364.790228)
		(width 0.11684)
		(layer "In2.Cu")
		(net "SMB_SCM_2_R2_SDA")
	)
	(segment
		(start 38.281102 -366.559084)
		(end 38.281102 -367.162334)
		(width 0.11684)
		(layer "In2.Cu")
		(net "SMB_SCM_2_R2_SDA")
	)
	(segment
		(start 39.840154 -364.104936)
		(end 39.19855 -364.104936)
		(width 0.11684)
		(layer "In2.Cu")
		(net "SMB_SCM_2_R2_SDA")
	)
	(segment
		(start 38.891464 -365.085376)
		(end 38.281102 -366.559084)
		(width 0.11684)
		(layer "In2.Cu")
		(net "SMB_SCM_2_R2_SDA")
	)
	(segment
		(start 30.980634 -367.45164)
		(end 28.367482 -367.45164)
		(width 0.11684)
		(layer "In2.Cu")
		(net "SMB_SCM_2_R2_SDA")
	)
	(segment
		(start 38.281102 -367.162334)
		(end 36.786058 -368.657378)
		(width 0.11684)
		(layer "In2.Cu")
		(net "SMB_SCM_2_R2_SDA")
	)
	(segment
		(start 160.598104 -358.429306)
		(end 155.935426 -363.091984)
		(width 0.11684)
		(layer "In2.Cu")
		(net "SMB_SCM_2_R2_SDA")
	)
	(segment
		(start 36.786058 -368.657378)
		(end 32.186372 -368.657378)
		(width 0.11684)
		(layer "In2.Cu")
		(net "SMB_SCM_2_R2_SDA")
	)
	(segment
		(start 32.186372 -368.657378)
		(end 30.980634 -367.45164)
		(width 0.11684)
		(layer "In2.Cu")
		(net "SMB_SCM_2_R2_SDA")
	)
	(segment
		(start 38.891464 -364.412022)
		(end 38.891464 -365.085376)
		(width 0.11684)
		(layer "In2.Cu")
		(net "SMB_SCM_2_R2_SDA")
	)
	(segment
		(start 160.152842 -355.829108)
		(end 160.02 -355.96195)
		(width 0.10668)
		(layer "F.Cu")
		(net "SMB_SCM_2_R2_SCL")
	)
	(segment
		(start 160.152842 -353.708716)
		(end 160.152842 -355.829108)
		(width 0.10668)
		(layer "F.Cu")
		(net "SMB_SCM_2_R2_SCL")
	)
	(segment
		(start 160.06953 -353.625404)
		(end 160.152842 -353.708716)
		(width 0.10668)
		(layer "F.Cu")
		(net "SMB_SCM_2_R2_SCL")
	)
	(segment
		(start 160.06953 -353.068128)
		(end 160.06953 -353.625404)
		(width 0.10668)
		(layer "F.Cu")
		(net "SMB_SCM_2_R2_SCL")
	)
	(via
		(at 160.152842 -353.708716)
		(size 0.508)
		(drill 0.254)
		(layers "F.Cu" "B.Cu")
		(net "SMB_SCM_2_R2_SCL")
	)
	(via
		(at 18.75028 -367.27003)
		(size 0.508)
		(drill 0.254)
		(layers "F.Cu" "B.Cu")
		(net "SMB_SCM_2_R2_SCL")
	)
	(segment
		(start 19.91995 -366.903)
		(end 19.55292 -367.27003)
		(width 0.10668)
		(layer "B.Cu")
		(net "SMB_SCM_2_R2_SCL")
	)
	(segment
		(start 19.55292 -367.27003)
		(end 18.75028 -367.27003)
		(width 0.10668)
		(layer "B.Cu")
		(net "SMB_SCM_2_R2_SCL")
	)
	(segment
		(start 36.02355 -368.235738)
		(end 32.361124 -368.235738)
		(width 0.11684)
		(layer "In2.Cu")
		(net "SMB_SCM_2_R2_SCL")
	)
	(segment
		(start 160.152842 -353.708716)
		(end 160.152842 -358.278176)
		(width 0.11684)
		(layer "In2.Cu")
		(net "SMB_SCM_2_R2_SCL")
	)
	(segment
		(start 38.023546 -363.599984)
		(end 37.672264 -363.951266)
		(width 0.11684)
		(layer "In2.Cu")
		(net "SMB_SCM_2_R2_SCL")
	)
	(segment
		(start 37.672264 -364.635288)
		(end 37.81171 -364.774734)
		(width 0.11684)
		(layer "In2.Cu")
		(net "SMB_SCM_2_R2_SCL")
	)
	(segment
		(start 37.81171 -366.447578)
		(end 36.02355 -368.235738)
		(width 0.11684)
		(layer "In2.Cu")
		(net "SMB_SCM_2_R2_SCL")
	)
	(segment
		(start 20.427188 -368.946938)
		(end 18.75028 -367.27003)
		(width 0.11684)
		(layer "In2.Cu")
		(net "SMB_SCM_2_R2_SCL")
	)
	(segment
		(start 37.672264 -363.951266)
		(end 37.672264 -364.635288)
		(width 0.11684)
		(layer "In2.Cu")
		(net "SMB_SCM_2_R2_SCL")
	)
	(segment
		(start 39.995094 -363.599984)
		(end 38.023546 -363.599984)
		(width 0.11684)
		(layer "In2.Cu")
		(net "SMB_SCM_2_R2_SCL")
	)
	(segment
		(start 160.152842 -358.278176)
		(end 155.820872 -362.610146)
		(width 0.11684)
		(layer "In2.Cu")
		(net "SMB_SCM_2_R2_SCL")
	)
	(segment
		(start 37.81171 -364.774734)
		(end 37.81171 -366.447578)
		(width 0.11684)
		(layer "In2.Cu")
		(net "SMB_SCM_2_R2_SCL")
	)
	(segment
		(start 155.820872 -362.610146)
		(end 137.89025 -362.610146)
		(width 0.11684)
		(layer "In2.Cu")
		(net "SMB_SCM_2_R2_SCL")
	)
	(segment
		(start 40.758364 -364.363254)
		(end 39.995094 -363.599984)
		(width 0.11684)
		(layer "In2.Cu")
		(net "SMB_SCM_2_R2_SCL")
	)
	(segment
		(start 137.89025 -362.610146)
		(end 136.137142 -364.363254)
		(width 0.11684)
		(layer "In2.Cu")
		(net "SMB_SCM_2_R2_SCL")
	)
	(segment
		(start 31.155386 -367.03)
		(end 28.19273 -367.03)
		(width 0.11684)
		(layer "In2.Cu")
		(net "SMB_SCM_2_R2_SCL")
	)
	(segment
		(start 28.19273 -367.03)
		(end 26.275792 -368.946938)
		(width 0.11684)
		(layer "In2.Cu")
		(net "SMB_SCM_2_R2_SCL")
	)
	(segment
		(start 26.275792 -368.946938)
		(end 20.427188 -368.946938)
		(width 0.11684)
		(layer "In2.Cu")
		(net "SMB_SCM_2_R2_SCL")
	)
	(segment
		(start 32.361124 -368.235738)
		(end 31.155386 -367.03)
		(width 0.11684)
		(layer "In2.Cu")
		(net "SMB_SCM_2_R2_SCL")
	)
	(segment
		(start 136.137142 -364.363254)
		(end 40.758364 -364.363254)
		(width 0.11684)
		(layer "In2.Cu")
		(net "SMB_SCM_2_R2_SCL")
	)
	(segment
		(start 23.622 -367.919)
		(end 24.36495 -367.919)
		(width 0.10668)
		(layer "F.Cu")
		(net "SMB_SCM_2_R1_SDA")
	)
	(segment
		(start 22.87905 -367.919)
		(end 23.622 -367.919)
		(width 0.10668)
		(layer "F.Cu")
		(net "SMB_SCM_2_R1_SDA")
	)
	(via
		(at 23.622 -367.919)
		(size 0.508)
		(drill 0.254)
		(layers "F.Cu" "B.Cu")
		(net "SMB_SCM_2_R1_SDA")
	)
	(via
		(at 22.426422 -367.446052)
		(size 0.6604)
		(drill 0.3302)
		(layers "F.Cu" "B.Cu")
		(net "SMB_SCM_2_R1_SDA")
	)
	(segment
		(start 22.426422 -367.446052)
		(end 23.149052 -367.446052)
		(width 0.10668)
		(layer "B.Cu")
		(net "SMB_SCM_2_R1_SDA")
	)
	(segment
		(start 20.72005 -367.919)
		(end 21.192998 -367.446052)
		(width 0.10668)
		(layer "B.Cu")
		(net "SMB_SCM_2_R1_SDA")
	)
	(segment
		(start 21.192998 -367.446052)
		(end 22.426422 -367.446052)
		(width 0.10668)
		(layer "B.Cu")
		(net "SMB_SCM_2_R1_SDA")
	)
	(segment
		(start 23.149052 -367.446052)
		(end 23.622 -367.919)
		(width 0.10668)
		(layer "B.Cu")
		(net "SMB_SCM_2_R1_SDA")
	)
	(segment
		(start 23.622 -366.903)
		(end 22.87905 -366.903)
		(width 0.10668)
		(layer "F.Cu")
		(net "SMB_SCM_2_R1_SCL")
	)
	(segment
		(start 24.36495 -366.903)
		(end 23.622 -366.903)
		(width 0.10668)
		(layer "F.Cu")
		(net "SMB_SCM_2_R1_SCL")
	)
	(via
		(at 23.622 -366.903)
		(size 0.508)
		(drill 0.254)
		(layers "F.Cu" "B.Cu")
		(net "SMB_SCM_2_R1_SCL")
	)
	(segment
		(start 23.124922 -366.405922)
		(end 23.622 -366.903)
		(width 0.10668)
		(layer "B.Cu")
		(net "SMB_SCM_2_R1_SCL")
	)
	(segment
		(start 20.72005 -366.903)
		(end 21.217128 -366.405922)
		(width 0.10668)
		(layer "B.Cu")
		(net "SMB_SCM_2_R1_SCL")
	)
	(segment
		(start 21.217128 -366.405922)
		(end 23.124922 -366.405922)
		(width 0.10668)
		(layer "B.Cu")
		(net "SMB_SCM_2_R1_SCL")
	)
	(segment
		(start 172.7835 -118.798848)
		(end 172.06595 -118.798848)
		(width 0.10668)
		(layer "F.Cu")
		(net "SMB_2_PLD_3V3AUX_SDA_R2")
	)
	(segment
		(start 177.922174 -116.252752)
		(end 177.51679 -116.658136)
		(width 0.10668)
		(layer "F.Cu")
		(net "SMB_2_PLD_3V3AUX_SDA_R2")
	)
	(segment
		(start 177.51679 -116.658136)
		(end 175.840898 -116.658136)
		(width 0.10668)
		(layer "F.Cu")
		(net "SMB_2_PLD_3V3AUX_SDA_R2")
	)
	(segment
		(start 175.840898 -116.658136)
		(end 173.700186 -118.798848)
		(width 0.10668)
		(layer "F.Cu")
		(net "SMB_2_PLD_3V3AUX_SDA_R2")
	)
	(segment
		(start 172.06595 -118.798848)
		(end 171.59605 -118.328948)
		(width 0.10668)
		(layer "F.Cu")
		(net "SMB_2_PLD_3V3AUX_SDA_R2")
	)
	(segment
		(start 173.700186 -118.798848)
		(end 172.7835 -118.798848)
		(width 0.10668)
		(layer "F.Cu")
		(net "SMB_2_PLD_3V3AUX_SDA_R2")
	)
	(via
		(at 172.7835 -118.798848)
		(size 0.762)
		(drill 0.381)
		(layers "F.Cu" "B.Cu")
		(net "SMB_2_PLD_3V3AUX_SDA_R2")
	)
	(segment
		(start 173.783498 -117.808248)
		(end 173.5963 -117.808248)
		(width 0.10668)
		(layer "F.Cu")
		(net "SMB_2_PLD_3V3AUX_SCL_R2")
	)
	(segment
		(start 172.09135 -117.808248)
		(end 171.59605 -117.312948)
		(width 0.10668)
		(layer "F.Cu")
		(net "SMB_2_PLD_3V3AUX_SCL_R2")
	)
	(segment
		(start 173.5963 -117.808248)
		(end 172.09135 -117.808248)
		(width 0.10668)
		(layer "F.Cu")
		(net "SMB_2_PLD_3V3AUX_SCL_R2")
	)
	(segment
		(start 177.122074 -116.252752)
		(end 175.338994 -116.252752)
		(width 0.10668)
		(layer "F.Cu")
		(net "SMB_2_PLD_3V3AUX_SCL_R2")
	)
	(segment
		(start 175.338994 -116.252752)
		(end 173.783498 -117.808248)
		(width 0.10668)
		(layer "F.Cu")
		(net "SMB_2_PLD_3V3AUX_SCL_R2")
	)
	(via
		(at 173.5963 -117.808248)
		(size 0.762)
		(drill 0.381)
		(layers "F.Cu" "B.Cu")
		(net "SMB_2_PLD_3V3AUX_SCL_R2")
	)
	(via
		(at 239.395 -232.75036)
		(size 0.508)
		(drill 0.254)
		(layers "F.Cu" "B.Cu")
		(net "SMB_CPU0_CPU1_SEC_SDA_R2")
	)
	(via
		(at 237.98784 -239.496092)
		(size 0.508)
		(drill 0.254)
		(layers "F.Cu" "B.Cu")
		(net "SMB_CPU0_CPU1_SEC_SDA_R2")
	)
	(via
		(at 244.07495 -230.251)
		(size 0.508)
		(drill 0.254)
		(layers "F.Cu" "B.Cu")
		(net "SMB_CPU0_CPU1_SEC_SDA_R2")
	)
	(via
		(at 236.093 -232.791)
		(size 0.508)
		(drill 0.254)
		(layers "F.Cu" "B.Cu")
		(net "SMB_CPU0_CPU1_SEC_SDA_R2")
	)
	(segment
		(start 244.221 -228.49205)
		(end 244.221 -229.34295)
		(width 0.10668)
		(layer "B.Cu")
		(net "SMB_CPU0_CPU1_SEC_SDA_R2")
	)
	(segment
		(start 244.07495 -229.489)
		(end 244.07495 -230.251)
		(width 0.10668)
		(layer "B.Cu")
		(net "SMB_CPU0_CPU1_SEC_SDA_R2")
	)
	(segment
		(start 239.395 -233.66095)
		(end 239.395 -232.75036)
		(width 0.10668)
		(layer "B.Cu")
		(net "SMB_CPU0_CPU1_SEC_SDA_R2")
	)
	(segment
		(start 238.41964 -239.064292)
		(end 237.98784 -239.496092)
		(width 0.10668)
		(layer "B.Cu")
		(net "SMB_CPU0_CPU1_SEC_SDA_R2")
	)
	(segment
		(start 238.41964 -237.870746)
		(end 238.41964 -239.064292)
		(width 0.10668)
		(layer "B.Cu")
		(net "SMB_CPU0_CPU1_SEC_SDA_R2")
	)
	(segment
		(start 236.093 -233.66095)
		(end 236.093 -232.791)
		(width 0.10668)
		(layer "B.Cu")
		(net "SMB_CPU0_CPU1_SEC_SDA_R2")
	)
	(segment
		(start 244.221 -229.34295)
		(end 244.07495 -229.489)
		(width 0.10668)
		(layer "B.Cu")
		(net "SMB_CPU0_CPU1_SEC_SDA_R2")
	)
	(segment
		(start 239.395 -232.37444)
		(end 239.395 -232.75036)
		(width 0.11684)
		(layer "In2.Cu")
		(net "SMB_CPU0_CPU1_SEC_SDA_R2")
	)
	(segment
		(start 239.109758 -232.089198)
		(end 239.395 -232.37444)
		(width 0.11684)
		(layer "In2.Cu")
		(net "SMB_CPU0_CPU1_SEC_SDA_R2")
	)
	(segment
		(start 236.093 -232.791)
		(end 236.794802 -232.089198)
		(width 0.11684)
		(layer "In2.Cu")
		(net "SMB_CPU0_CPU1_SEC_SDA_R2")
	)
	(segment
		(start 236.794802 -232.089198)
		(end 239.109758 -232.089198)
		(width 0.11684)
		(layer "In2.Cu")
		(net "SMB_CPU0_CPU1_SEC_SDA_R2")
	)
	(segment
		(start 236.093 -232.791)
		(end 236.093 -233.672888)
		(width 0.11684)
		(layer "In4.Cu")
		(net "SMB_CPU0_CPU1_SEC_SDA_R2")
	)
	(segment
		(start 240.253266 -230.411782)
		(end 241.03965 -229.625398)
		(width 0.11684)
		(layer "In4.Cu")
		(net "SMB_CPU0_CPU1_SEC_SDA_R2")
	)
	(segment
		(start 240.253266 -231.892094)
		(end 240.253266 -230.411782)
		(width 0.11684)
		(layer "In4.Cu")
		(net "SMB_CPU0_CPU1_SEC_SDA_R2")
	)
	(segment
		(start 239.395 -232.75036)
		(end 240.253266 -231.892094)
		(width 0.11684)
		(layer "In4.Cu")
		(net "SMB_CPU0_CPU1_SEC_SDA_R2")
	)
	(segment
		(start 238.41964 -237.824518)
		(end 238.41964 -239.064292)
		(width 0.11684)
		(layer "In4.Cu")
		(net "SMB_CPU0_CPU1_SEC_SDA_R2")
	)
	(segment
		(start 237.277402 -234.85729)
		(end 237.277402 -236.68228)
		(width 0.11684)
		(layer "In4.Cu")
		(net "SMB_CPU0_CPU1_SEC_SDA_R2")
	)
	(segment
		(start 236.093 -233.672888)
		(end 237.277402 -234.85729)
		(width 0.11684)
		(layer "In4.Cu")
		(net "SMB_CPU0_CPU1_SEC_SDA_R2")
	)
	(segment
		(start 243.449348 -229.625398)
		(end 244.07495 -230.251)
		(width 0.11684)
		(layer "In4.Cu")
		(net "SMB_CPU0_CPU1_SEC_SDA_R2")
	)
	(segment
		(start 237.277402 -236.68228)
		(end 238.41964 -237.824518)
		(width 0.11684)
		(layer "In4.Cu")
		(net "SMB_CPU0_CPU1_SEC_SDA_R2")
	)
	(segment
		(start 241.03965 -229.625398)
		(end 243.449348 -229.625398)
		(width 0.11684)
		(layer "In4.Cu")
		(net "SMB_CPU0_CPU1_SEC_SDA_R2")
	)
	(segment
		(start 238.41964 -239.064292)
		(end 237.98784 -239.496092)
		(width 0.11684)
		(layer "In4.Cu")
		(net "SMB_CPU0_CPU1_SEC_SDA_R2")
	)
	(via
		(at 243.09705 -230.251)
		(size 0.508)
		(drill 0.254)
		(layers "F.Cu" "B.Cu")
		(net "SMB_CPU0_CPU1_SEC_SCL_R2")
	)
	(via
		(at 237.363 -232.791)
		(size 0.508)
		(drill 0.254)
		(layers "F.Cu" "B.Cu")
		(net "SMB_CPU0_CPU1_SEC_SCL_R2")
	)
	(via
		(at 239.428274 -239.563148)
		(size 0.508)
		(drill 0.254)
		(layers "F.Cu" "B.Cu")
		(net "SMB_CPU0_CPU1_SEC_SCL_R2")
	)
	(via
		(at 241.427 -232.7021)
		(size 0.508)
		(drill 0.254)
		(layers "F.Cu" "B.Cu")
		(net "SMB_CPU0_CPU1_SEC_SCL_R2")
	)
	(segment
		(start 237.363 -233.66095)
		(end 237.363 -232.791)
		(width 0.10668)
		(layer "B.Cu")
		(net "SMB_CPU0_CPU1_SEC_SCL_R2")
	)
	(segment
		(start 243.09705 -229.489)
		(end 243.09705 -230.251)
		(width 0.10668)
		(layer "B.Cu")
		(net "SMB_CPU0_CPU1_SEC_SCL_R2")
	)
	(segment
		(start 242.951 -229.34295)
		(end 243.09705 -229.489)
		(width 0.10668)
		(layer "B.Cu")
		(net "SMB_CPU0_CPU1_SEC_SCL_R2")
	)
	(segment
		(start 238.919512 -237.870746)
		(end 238.919512 -239.054386)
		(width 0.10668)
		(layer "B.Cu")
		(net "SMB_CPU0_CPU1_SEC_SCL_R2")
	)
	(segment
		(start 242.951 -228.49205)
		(end 242.951 -229.34295)
		(width 0.10668)
		(layer "B.Cu")
		(net "SMB_CPU0_CPU1_SEC_SCL_R2")
	)
	(segment
		(start 238.919512 -239.054386)
		(end 239.428274 -239.563148)
		(width 0.10668)
		(layer "B.Cu")
		(net "SMB_CPU0_CPU1_SEC_SCL_R2")
	)
	(segment
		(start 241.427 -233.66095)
		(end 241.427 -232.7021)
		(width 0.10668)
		(layer "B.Cu")
		(net "SMB_CPU0_CPU1_SEC_SCL_R2")
	)
	(segment
		(start 240.355882 -233.773218)
		(end 238.274098 -233.773218)
		(width 0.11684)
		(layer "In2.Cu")
		(net "SMB_CPU0_CPU1_SEC_SCL_R2")
	)
	(segment
		(start 237.363 -232.86212)
		(end 237.363 -232.791)
		(width 0.11684)
		(layer "In2.Cu")
		(net "SMB_CPU0_CPU1_SEC_SCL_R2")
	)
	(segment
		(start 238.274098 -233.773218)
		(end 237.363 -232.86212)
		(width 0.11684)
		(layer "In2.Cu")
		(net "SMB_CPU0_CPU1_SEC_SCL_R2")
	)
	(segment
		(start 241.427 -232.7021)
		(end 240.355882 -233.773218)
		(width 0.11684)
		(layer "In2.Cu")
		(net "SMB_CPU0_CPU1_SEC_SCL_R2")
	)
	(segment
		(start 240.789206 -231.948736)
		(end 240.789206 -230.590852)
		(width 0.11684)
		(layer "In4.Cu")
		(net "SMB_CPU0_CPU1_SEC_SCL_R2")
	)
	(segment
		(start 238.171482 -236.827314)
		(end 238.986822 -237.642654)
		(width 0.11684)
		(layer "In4.Cu")
		(net "SMB_CPU0_CPU1_SEC_SCL_R2")
	)
	(segment
		(start 238.986822 -239.121696)
		(end 239.428274 -239.563148)
		(width 0.11684)
		(layer "In4.Cu")
		(net "SMB_CPU0_CPU1_SEC_SCL_R2")
	)
	(segment
		(start 243.079016 -230.232966)
		(end 243.09705 -230.251)
		(width 0.11684)
		(layer "In4.Cu")
		(net "SMB_CPU0_CPU1_SEC_SCL_R2")
	)
	(segment
		(start 241.147092 -230.232966)
		(end 243.079016 -230.232966)
		(width 0.11684)
		(layer "In4.Cu")
		(net "SMB_CPU0_CPU1_SEC_SCL_R2")
	)
	(segment
		(start 238.986822 -237.642654)
		(end 238.986822 -239.121696)
		(width 0.11684)
		(layer "In4.Cu")
		(net "SMB_CPU0_CPU1_SEC_SCL_R2")
	)
	(segment
		(start 238.171482 -233.599482)
		(end 238.171482 -236.827314)
		(width 0.11684)
		(layer "In4.Cu")
		(net "SMB_CPU0_CPU1_SEC_SCL_R2")
	)
	(segment
		(start 240.789206 -230.590852)
		(end 241.147092 -230.232966)
		(width 0.11684)
		(layer "In4.Cu")
		(net "SMB_CPU0_CPU1_SEC_SCL_R2")
	)
	(segment
		(start 241.427 -232.7021)
		(end 241.427 -232.58653)
		(width 0.11684)
		(layer "In4.Cu")
		(net "SMB_CPU0_CPU1_SEC_SCL_R2")
	)
	(segment
		(start 241.427 -232.58653)
		(end 240.789206 -231.948736)
		(width 0.11684)
		(layer "In4.Cu")
		(net "SMB_CPU0_CPU1_SEC_SCL_R2")
	)
	(segment
		(start 237.363 -232.791)
		(end 238.171482 -233.599482)
		(width 0.11684)
		(layer "In4.Cu")
		(net "SMB_CPU0_CPU1_SEC_SCL_R2")
	)
	(via
		(at 244.221 -226.822)
		(size 0.6604)
		(drill 0.3302)
		(layers "F.Cu" "B.Cu")
		(net "SMB_CPU0_CPU1_SEC_SDA_R1")
	)
	(segment
		(start 244.221 -227.69195)
		(end 244.221 -226.822)
		(width 0.10668)
		(layer "B.Cu")
		(net "SMB_CPU0_CPU1_SEC_SDA_R1")
	)
	(segment
		(start 243.91112 -225.314002)
		(end 243.91112 -226.51212)
		(width 0.10668)
		(layer "B.Cu")
		(net "SMB_CPU0_CPU1_SEC_SDA_R1")
	)
	(segment
		(start 243.91112 -226.51212)
		(end 244.221 -226.822)
		(width 0.10668)
		(layer "B.Cu")
		(net "SMB_CPU0_CPU1_SEC_SDA_R1")
	)
	(via
		(at 242.951 -226.822)
		(size 0.6604)
		(drill 0.3302)
		(layers "F.Cu" "B.Cu")
		(net "SMB_CPU0_CPU1_SEC_SCL_R1")
	)
	(segment
		(start 243.26088 -225.314002)
		(end 243.26088 -226.51212)
		(width 0.10668)
		(layer "B.Cu")
		(net "SMB_CPU0_CPU1_SEC_SCL_R1")
	)
	(segment
		(start 242.951 -227.69195)
		(end 242.951 -226.822)
		(width 0.10668)
		(layer "B.Cu")
		(net "SMB_CPU0_CPU1_SEC_SCL_R1")
	)
	(segment
		(start 243.26088 -226.51212)
		(end 242.951 -226.822)
		(width 0.10668)
		(layer "B.Cu")
		(net "SMB_CPU0_CPU1_SEC_SCL_R1")
	)
	(via
		(at 231.14 -243.205)
		(size 0.508)
		(drill 0.254)
		(layers "F.Cu" "B.Cu")
		(net "SMB_CPU0_CPU1_APML_SDA_R2")
	)
	(via
		(at 235.655358 -214.227664)
		(size 0.508)
		(drill 0.254)
		(layers "F.Cu" "B.Cu")
		(net "SMB_CPU0_CPU1_APML_SDA_R2")
	)
	(segment
		(start 230.77805 -242.84305)
		(end 231.14 -243.205)
		(width 0.10668)
		(layer "B.Cu")
		(net "SMB_CPU0_CPU1_APML_SDA_R2")
	)
	(segment
		(start 230.505 -242.84305)
		(end 230.77805 -242.84305)
		(width 0.10668)
		(layer "B.Cu")
		(net "SMB_CPU0_CPU1_APML_SDA_R2")
	)
	(segment
		(start 235.655358 -214.227664)
		(end 234.686348 -213.258654)
		(width 0.10668)
		(layer "B.Cu")
		(net "SMB_CPU0_CPU1_APML_SDA_R2")
	)
	(segment
		(start 230.251 -243.205)
		(end 225.806 -238.76)
		(width 0.11684)
		(layer "In4.Cu")
		(net "SMB_CPU0_CPU1_APML_SDA_R2")
	)
	(segment
		(start 231.14 -243.205)
		(end 230.251 -243.205)
		(width 0.11684)
		(layer "In4.Cu")
		(net "SMB_CPU0_CPU1_APML_SDA_R2")
	)
	(segment
		(start 235.168694 -213.741)
		(end 235.655358 -214.227664)
		(width 0.11684)
		(layer "In4.Cu")
		(net "SMB_CPU0_CPU1_APML_SDA_R2")
	)
	(segment
		(start 225.806 -221.143576)
		(end 233.208576 -213.741)
		(width 0.11684)
		(layer "In4.Cu")
		(net "SMB_CPU0_CPU1_APML_SDA_R2")
	)
	(segment
		(start 225.806 -238.76)
		(end 225.806 -221.143576)
		(width 0.11684)
		(layer "In4.Cu")
		(net "SMB_CPU0_CPU1_APML_SDA_R2")
	)
	(segment
		(start 233.208576 -213.741)
		(end 235.168694 -213.741)
		(width 0.11684)
		(layer "In4.Cu")
		(net "SMB_CPU0_CPU1_APML_SDA_R2")
	)
	(via
		(at 231.14 -242.443)
		(size 0.508)
		(drill 0.254)
		(layers "F.Cu" "B.Cu")
		(net "SMB_CPU0_CPU1_APML_SCL_R2")
	)
	(via
		(at 233.739436 -214.210646)
		(size 0.508)
		(drill 0.254)
		(layers "F.Cu" "B.Cu")
		(net "SMB_CPU0_CPU1_APML_SCL_R2")
	)
	(segment
		(start 231.775 -242.84305)
		(end 231.54005 -242.84305)
		(width 0.10668)
		(layer "B.Cu")
		(net "SMB_CPU0_CPU1_APML_SCL_R2")
	)
	(segment
		(start 231.54005 -242.84305)
		(end 231.14 -242.443)
		(width 0.10668)
		(layer "B.Cu")
		(net "SMB_CPU0_CPU1_APML_SCL_R2")
	)
	(segment
		(start 233.998262 -214.469726)
		(end 233.998262 -214.469472)
		(width 0.10668)
		(layer "B.Cu")
		(net "SMB_CPU0_CPU1_APML_SCL_R2")
	)
	(segment
		(start 234.71505 -215.186514)
		(end 233.998262 -214.469726)
		(width 0.10668)
		(layer "B.Cu")
		(net "SMB_CPU0_CPU1_APML_SCL_R2")
	)
	(segment
		(start 233.998262 -214.469472)
		(end 233.739436 -214.210646)
		(width 0.10668)
		(layer "B.Cu")
		(net "SMB_CPU0_CPU1_APML_SCL_R2")
	)
	(segment
		(start 227.593652 -236.674406)
		(end 227.710492 -236.557566)
		(width 0.11684)
		(layer "In4.Cu")
		(net "SMB_CPU0_CPU1_APML_SCL_R2")
	)
	(segment
		(start 227.710492 -236.557566)
		(end 227.710492 -236.367066)
		(width 0.11684)
		(layer "In4.Cu")
		(net "SMB_CPU0_CPU1_APML_SCL_R2")
	)
	(segment
		(start 227.593652 -236.250226)
		(end 226.43084 -236.250226)
		(width 0.11684)
		(layer "In4.Cu")
		(net "SMB_CPU0_CPU1_APML_SCL_R2")
	)
	(segment
		(start 227.593652 -235.401866)
		(end 226.43084 -235.401866)
		(width 0.11684)
		(layer "In4.Cu")
		(net "SMB_CPU0_CPU1_APML_SCL_R2")
	)
	(segment
		(start 227.710492 -235.709206)
		(end 227.710492 -235.518706)
		(width 0.11684)
		(layer "In4.Cu")
		(net "SMB_CPU0_CPU1_APML_SCL_R2")
	)
	(segment
		(start 231.14 -242.443)
		(end 230.124 -242.443)
		(width 0.11684)
		(layer "In4.Cu")
		(net "SMB_CPU0_CPU1_APML_SCL_R2")
	)
	(segment
		(start 227.710492 -236.367066)
		(end 227.593652 -236.250226)
		(width 0.11684)
		(layer "In4.Cu")
		(net "SMB_CPU0_CPU1_APML_SCL_R2")
	)
	(segment
		(start 227.593652 -235.826046)
		(end 227.710492 -235.709206)
		(width 0.11684)
		(layer "In4.Cu")
		(net "SMB_CPU0_CPU1_APML_SCL_R2")
	)
	(segment
		(start 226.43084 -235.401866)
		(end 226.314 -235.285026)
		(width 0.11684)
		(layer "In4.Cu")
		(net "SMB_CPU0_CPU1_APML_SCL_R2")
	)
	(segment
		(start 227.710492 -235.518706)
		(end 227.593652 -235.401866)
		(width 0.11684)
		(layer "In4.Cu")
		(net "SMB_CPU0_CPU1_APML_SCL_R2")
	)
	(segment
		(start 226.314 -236.133386)
		(end 226.314 -235.942886)
		(width 0.11684)
		(layer "In4.Cu")
		(net "SMB_CPU0_CPU1_APML_SCL_R2")
	)
	(segment
		(start 233.37393 -214.210646)
		(end 233.739436 -214.210646)
		(width 0.11684)
		(layer "In4.Cu")
		(net "SMB_CPU0_CPU1_APML_SCL_R2")
	)
	(segment
		(start 226.314 -236.791246)
		(end 226.43084 -236.674406)
		(width 0.11684)
		(layer "In4.Cu")
		(net "SMB_CPU0_CPU1_APML_SCL_R2")
	)
	(segment
		(start 230.124 -242.443)
		(end 226.314 -238.633)
		(width 0.11684)
		(layer "In4.Cu")
		(net "SMB_CPU0_CPU1_APML_SCL_R2")
	)
	(segment
		(start 226.314 -235.285026)
		(end 226.314 -221.270576)
		(width 0.11684)
		(layer "In4.Cu")
		(net "SMB_CPU0_CPU1_APML_SCL_R2")
	)
	(segment
		(start 226.43084 -236.250226)
		(end 226.314 -236.133386)
		(width 0.11684)
		(layer "In4.Cu")
		(net "SMB_CPU0_CPU1_APML_SCL_R2")
	)
	(segment
		(start 226.314 -221.270576)
		(end 233.37393 -214.210646)
		(width 0.11684)
		(layer "In4.Cu")
		(net "SMB_CPU0_CPU1_APML_SCL_R2")
	)
	(segment
		(start 226.314 -238.633)
		(end 226.314 -236.791246)
		(width 0.11684)
		(layer "In4.Cu")
		(net "SMB_CPU0_CPU1_APML_SCL_R2")
	)
	(segment
		(start 226.314 -235.942886)
		(end 226.43084 -235.826046)
		(width 0.11684)
		(layer "In4.Cu")
		(net "SMB_CPU0_CPU1_APML_SCL_R2")
	)
	(segment
		(start 226.43084 -235.826046)
		(end 227.593652 -235.826046)
		(width 0.11684)
		(layer "In4.Cu")
		(net "SMB_CPU0_CPU1_APML_SCL_R2")
	)
	(segment
		(start 226.43084 -236.674406)
		(end 227.593652 -236.674406)
		(width 0.11684)
		(layer "In4.Cu")
		(net "SMB_CPU0_CPU1_APML_SCL_R2")
	)
	(via
		(at 240.04905 -226.441)
		(size 0.508)
		(drill 0.254)
		(layers "F.Cu" "B.Cu")
		(net "SMB_CPU0_CPU1_APML_BUF1_SDA_R1")
	)
	(via
		(at 239.522 -219.157042)
		(size 0.508)
		(drill 0.254)
		(layers "F.Cu" "B.Cu")
		(net "SMB_CPU0_CPU1_APML_BUF1_SDA_R1")
	)
	(segment
		(start 239.522 -219.36329)
		(end 239.522 -219.157042)
		(width 0.10668)
		(layer "B.Cu")
		(net "SMB_CPU0_CPU1_APML_BUF1_SDA_R1")
	)
	(segment
		(start 240.04905 -227.203)
		(end 240.04905 -226.441)
		(width 0.10668)
		(layer "B.Cu")
		(net "SMB_CPU0_CPU1_APML_BUF1_SDA_R1")
	)
	(segment
		(start 239.522 -219.157042)
		(end 239.522 -218.07805)
		(width 0.10668)
		(layer "B.Cu")
		(net "SMB_CPU0_CPU1_APML_BUF1_SDA_R1")
	)
	(segment
		(start 239.065562 -219.819728)
		(end 239.522 -219.36329)
		(width 0.10668)
		(layer "B.Cu")
		(net "SMB_CPU0_CPU1_APML_BUF1_SDA_R1")
	)
	(segment
		(start 239.065562 -220.927168)
		(end 239.065562 -219.819728)
		(width 0.10668)
		(layer "B.Cu")
		(net "SMB_CPU0_CPU1_APML_BUF1_SDA_R1")
	)
	(segment
		(start 239.522 -219.157042)
		(end 239.141 -219.538042)
		(width 0.11684)
		(layer "In4.Cu")
		(net "SMB_CPU0_CPU1_APML_BUF1_SDA_R1")
	)
	(segment
		(start 239.141 -219.538042)
		(end 239.141 -225.53295)
		(width 0.11684)
		(layer "In4.Cu")
		(net "SMB_CPU0_CPU1_APML_BUF1_SDA_R1")
	)
	(segment
		(start 239.141 -225.53295)
		(end 240.04905 -226.441)
		(width 0.11684)
		(layer "In4.Cu")
		(net "SMB_CPU0_CPU1_APML_BUF1_SDA_R1")
	)
	(via
		(at 237.47095 -226.42195)
		(size 0.508)
		(drill 0.254)
		(layers "F.Cu" "B.Cu")
		(net "SMB_CPU0_CPU1_APML_BUF1_SCL_R1")
	)
	(via
		(at 238.252 -219.10548)
		(size 0.508)
		(drill 0.254)
		(layers "F.Cu" "B.Cu")
		(net "SMB_CPU0_CPU1_APML_BUF1_SCL_R1")
	)
	(segment
		(start 238.415322 -219.528136)
		(end 238.252 -219.364814)
		(width 0.10668)
		(layer "B.Cu")
		(net "SMB_CPU0_CPU1_APML_BUF1_SCL_R1")
	)
	(segment
		(start 238.415322 -220.927168)
		(end 238.415322 -219.528136)
		(width 0.10668)
		(layer "B.Cu")
		(net "SMB_CPU0_CPU1_APML_BUF1_SCL_R1")
	)
	(segment
		(start 238.252 -219.364814)
		(end 238.252 -219.10548)
		(width 0.10668)
		(layer "B.Cu")
		(net "SMB_CPU0_CPU1_APML_BUF1_SCL_R1")
	)
	(segment
		(start 238.252 -219.10548)
		(end 238.252 -218.07805)
		(width 0.10668)
		(layer "B.Cu")
		(net "SMB_CPU0_CPU1_APML_BUF1_SCL_R1")
	)
	(segment
		(start 237.47095 -227.203)
		(end 237.47095 -226.42195)
		(width 0.10668)
		(layer "B.Cu")
		(net "SMB_CPU0_CPU1_APML_BUF1_SCL_R1")
	)
	(segment
		(start 238.252 -219.10548)
		(end 238.633 -219.48648)
		(width 0.11684)
		(layer "In4.Cu")
		(net "SMB_CPU0_CPU1_APML_BUF1_SCL_R1")
	)
	(segment
		(start 238.633 -225.2599)
		(end 237.47095 -226.42195)
		(width 0.11684)
		(layer "In4.Cu")
		(net "SMB_CPU0_CPU1_APML_BUF1_SCL_R1")
	)
	(segment
		(start 238.633 -219.48648)
		(end 238.633 -225.2599)
		(width 0.11684)
		(layer "In4.Cu")
		(net "SMB_CPU0_CPU1_APML_BUF1_SCL_R1")
	)
	(segment
		(start 173.5963 -115.806728)
		(end 174.40656 -115.806728)
		(width 0.10668)
		(layer "F.Cu")
		(net "SMB_1_PLD_3V3AUX_SDA_R2")
	)
	(segment
		(start 171.59605 -115.480084)
		(end 172.224446 -116.10848)
		(width 0.10668)
		(layer "F.Cu")
		(net "SMB_1_PLD_3V3AUX_SDA_R2")
	)
	(segment
		(start 172.224446 -116.10848)
		(end 173.294548 -116.10848)
		(width 0.10668)
		(layer "F.Cu")
		(net "SMB_1_PLD_3V3AUX_SDA_R2")
	)
	(segment
		(start 174.760382 -115.452906)
		(end 177.122074 -115.452906)
		(width 0.10668)
		(layer "F.Cu")
		(net "SMB_1_PLD_3V3AUX_SDA_R2")
	)
	(segment
		(start 171.59605 -115.280948)
		(end 171.59605 -115.480084)
		(width 0.10668)
		(layer "F.Cu")
		(net "SMB_1_PLD_3V3AUX_SDA_R2")
	)
	(segment
		(start 174.40656 -115.806728)
		(end 174.760382 -115.452906)
		(width 0.10668)
		(layer "F.Cu")
		(net "SMB_1_PLD_3V3AUX_SDA_R2")
	)
	(segment
		(start 173.294548 -116.10848)
		(end 173.5963 -115.806728)
		(width 0.10668)
		(layer "F.Cu")
		(net "SMB_1_PLD_3V3AUX_SDA_R2")
	)
	(via
		(at 173.5963 -115.806728)
		(size 0.762)
		(drill 0.381)
		(layers "F.Cu" "B.Cu")
		(net "SMB_1_PLD_3V3AUX_SDA_R2")
	)
	(segment
		(start 175.096678 -115.832636)
		(end 174.137066 -116.792248)
		(width 0.10668)
		(layer "F.Cu")
		(net "SMB_1_PLD_3V3AUX_SCL_R2")
	)
	(segment
		(start 172.09135 -116.792248)
		(end 171.59605 -116.296948)
		(width 0.10668)
		(layer "F.Cu")
		(net "SMB_1_PLD_3V3AUX_SCL_R2")
	)
	(segment
		(start 177.922174 -115.452906)
		(end 177.542444 -115.832636)
		(width 0.10668)
		(layer "F.Cu")
		(net "SMB_1_PLD_3V3AUX_SCL_R2")
	)
	(segment
		(start 177.542444 -115.832636)
		(end 175.096678 -115.832636)
		(width 0.10668)
		(layer "F.Cu")
		(net "SMB_1_PLD_3V3AUX_SCL_R2")
	)
	(segment
		(start 174.137066 -116.792248)
		(end 172.7835 -116.792248)
		(width 0.10668)
		(layer "F.Cu")
		(net "SMB_1_PLD_3V3AUX_SCL_R2")
	)
	(segment
		(start 172.7835 -116.792248)
		(end 172.09135 -116.792248)
		(width 0.10668)
		(layer "F.Cu")
		(net "SMB_1_PLD_3V3AUX_SCL_R2")
	)
	(via
		(at 172.7835 -116.792248)
		(size 0.762)
		(drill 0.381)
		(layers "F.Cu" "B.Cu")
		(net "SMB_1_PLD_3V3AUX_SCL_R2")
	)
	(segment
		(start 151.422354 -12.823698)
		(end 151.422354 -12.309602)
		(width 0.10668)
		(layer "F.Cu")
		(net "SMB_HOST_CLK_3V3AUX_SDA_R0")
	)
	(segment
		(start 150.874984 -11.762232)
		(end 150.352252 -11.762232)
		(width 0.10668)
		(layer "F.Cu")
		(net "SMB_HOST_CLK_3V3AUX_SDA_R0")
	)
	(segment
		(start 151.456898 -12.858242)
		(end 151.422354 -12.823698)
		(width 0.10668)
		(layer "F.Cu")
		(net "SMB_HOST_CLK_3V3AUX_SDA_R0")
	)
	(segment
		(start 151.456898 -13.599922)
		(end 151.456898 -12.858242)
		(width 0.10668)
		(layer "F.Cu")
		(net "SMB_HOST_CLK_3V3AUX_SDA_R0")
	)
	(segment
		(start 151.422354 -12.309602)
		(end 150.874984 -11.762232)
		(width 0.10668)
		(layer "F.Cu")
		(net "SMB_HOST_CLK_3V3AUX_SDA_R0")
	)
	(via
		(at 150.352252 -11.762232)
		(size 0.508)
		(drill 0.254)
		(layers "F.Cu" "B.Cu")
		(net "SMB_HOST_CLK_3V3AUX_SDA_R0")
	)
	(segment
		(start 149.884638 -12.43457)
		(end 150.352252 -11.966956)
		(width 0.10668)
		(layer "B.Cu")
		(net "SMB_HOST_CLK_3V3AUX_SDA_R0")
	)
	(segment
		(start 149.884638 -13.362178)
		(end 149.884638 -12.43457)
		(width 0.10668)
		(layer "B.Cu")
		(net "SMB_HOST_CLK_3V3AUX_SDA_R0")
	)
	(segment
		(start 150.352252 -11.966956)
		(end 150.352252 -11.762232)
		(width 0.10668)
		(layer "B.Cu")
		(net "SMB_HOST_CLK_3V3AUX_SDA_R0")
	)
	(segment
		(start 152.0571 -13.599922)
		(end 152.0571 -12.380214)
		(width 0.10668)
		(layer "F.Cu")
		(net "SMB_HOST_CLK_3V3AUX_SCL_R0")
	)
	(segment
		(start 152.0571 -12.380214)
		(end 151.880824 -12.203938)
		(width 0.10668)
		(layer "F.Cu")
		(net "SMB_HOST_CLK_3V3AUX_SCL_R0")
	)
	(via
		(at 151.880824 -12.203938)
		(size 0.508)
		(drill 0.254)
		(layers "F.Cu" "B.Cu")
		(net "SMB_HOST_CLK_3V3AUX_SCL_R0")
	)
	(segment
		(start 150.97887 -13.362178)
		(end 151.49322 -13.362178)
		(width 0.10668)
		(layer "B.Cu")
		(net "SMB_HOST_CLK_3V3AUX_SCL_R0")
	)
	(segment
		(start 151.749506 -12.335256)
		(end 151.880824 -12.203938)
		(width 0.10668)
		(layer "B.Cu")
		(net "SMB_HOST_CLK_3V3AUX_SCL_R0")
	)
	(segment
		(start 151.49322 -13.362178)
		(end 151.749506 -13.105892)
		(width 0.10668)
		(layer "B.Cu")
		(net "SMB_HOST_CLK_3V3AUX_SCL_R0")
	)
	(segment
		(start 151.749506 -13.105892)
		(end 151.749506 -12.335256)
		(width 0.10668)
		(layer "B.Cu")
		(net "SMB_HOST_CLK_3V3AUX_SCL_R0")
	)
	(segment
		(start 158.82874 -44.585636)
		(end 157.81274 -44.585636)
		(width 0.10668)
		(layer "F.Cu")
		(net "SMB_PCIE_M2_0_EN")
	)
	(segment
		(start 154.480768 -44.437554)
		(end 154.480768 -44.083732)
		(width 0.10668)
		(layer "F.Cu")
		(net "SMB_PCIE_M2_0_EN")
	)
	(segment
		(start 155.651454 -44.585636)
		(end 154.62885 -44.585636)
		(width 0.10668)
		(layer "F.Cu")
		(net "SMB_PCIE_M2_0_EN")
	)
	(segment
		(start 154.62885 -43.93565)
		(end 155.651454 -43.93565)
		(width 0.10668)
		(layer "F.Cu")
		(net "SMB_PCIE_M2_0_EN")
	)
	(segment
		(start 154.480768 -44.083732)
		(end 154.62885 -43.93565)
		(width 0.10668)
		(layer "F.Cu")
		(net "SMB_PCIE_M2_0_EN")
	)
	(segment
		(start 154.62885 -44.585636)
		(end 154.480768 -44.437554)
		(width 0.10668)
		(layer "F.Cu")
		(net "SMB_PCIE_M2_0_EN")
	)
	(segment
		(start 157.81274 -44.585636)
		(end 157.175454 -44.585636)
		(width 0.10668)
		(layer "F.Cu")
		(net "SMB_PCIE_M2_0_EN")
	)
	(segment
		(start 155.651454 -44.585636)
		(end 157.175454 -44.585636)
		(width 0.10668)
		(layer "F.Cu")
		(net "SMB_PCIE_M2_0_EN")
	)
	(via
		(at 157.175454 -44.585636)
		(size 0.508)
		(drill 0.254)
		(layers "F.Cu" "B.Cu")
		(net "SMB_PCIE_M2_0_EN")
	)
	(segment
		(start 255.312926 -73.791064)
		(end 256.06502 -73.791064)
		(width 0.10668)
		(layer "F.Cu")
		(net "SMB_PCIE_E1S_ISO_EN_R2")
	)
	(segment
		(start 256.06502 -73.791064)
		(end 256.579878 -73.276206)
		(width 0.10668)
		(layer "F.Cu")
		(net "SMB_PCIE_E1S_ISO_EN_R2")
	)
	(segment
		(start 257.875786 -72.976994)
		(end 256.87909 -72.976994)
		(width 0.10668)
		(layer "F.Cu")
		(net "SMB_PCIE_E1S_ISO_EN_R2")
	)
	(segment
		(start 256.87909 -72.976994)
		(end 256.579878 -73.276206)
		(width 0.10668)
		(layer "F.Cu")
		(net "SMB_PCIE_E1S_ISO_EN_R2")
	)
	(via
		(at 256.579878 -73.276206)
		(size 0.762)
		(drill 0.381)
		(layers "F.Cu" "B.Cu")
		(net "SMB_PCIE_E1S_ISO_EN_R2")
	)
	(segment
		(start 211.14893 -43.594274)
		(end 211.149184 -43.594528)
		(width 0.10668)
		(layer "F.Cu")
		(net "SMB_PCIE_E1S_ISO_EN_R")
	)
	(segment
		(start 214.010748 -44.788328)
		(end 213.322916 -44.788328)
		(width 0.10668)
		(layer "F.Cu")
		(net "SMB_PCIE_E1S_ISO_EN_R")
	)
	(segment
		(start 211.467954 -45.114972)
		(end 211.14893 -44.795948)
		(width 0.10668)
		(layer "F.Cu")
		(net "SMB_PCIE_E1S_ISO_EN_R")
	)
	(segment
		(start 211.14893 -44.795948)
		(end 211.14893 -43.594782)
		(width 0.10668)
		(layer "F.Cu")
		(net "SMB_PCIE_E1S_ISO_EN_R")
	)
	(segment
		(start 213.322916 -44.788328)
		(end 212.996272 -45.114972)
		(width 0.10668)
		(layer "F.Cu")
		(net "SMB_PCIE_E1S_ISO_EN_R")
	)
	(segment
		(start 211.14893 -42.382948)
		(end 211.14893 -43.594274)
		(width 0.10668)
		(layer "F.Cu")
		(net "SMB_PCIE_E1S_ISO_EN_R")
	)
	(segment
		(start 211.14893 -43.594782)
		(end 211.149184 -43.594528)
		(width 0.10668)
		(layer "F.Cu")
		(net "SMB_PCIE_E1S_ISO_EN_R")
	)
	(segment
		(start 212.996272 -45.114972)
		(end 211.467954 -45.114972)
		(width 0.10668)
		(layer "F.Cu")
		(net "SMB_PCIE_E1S_ISO_EN_R")
	)
	(via
		(at 211.149184 -43.594528)
		(size 0.762)
		(drill 0.381)
		(layers "F.Cu" "B.Cu")
		(net "SMB_PCIE_E1S_ISO_EN_R")
	)
	(segment
		(start 210.34883 -44.795948)
		(end 208.94929 -43.396408)
		(width 0.10668)
		(layer "F.Cu")
		(net "SMB_PCIE_E1S_ISO_EN")
	)
	(segment
		(start 258.675886 -72.976994)
		(end 259.86994 -72.976994)
		(width 0.10668)
		(layer "F.Cu")
		(net "SMB_PCIE_E1S_ISO_EN")
	)
	(segment
		(start 259.86994 -72.976994)
		(end 261.068566 -72.976994)
		(width 0.10668)
		(layer "F.Cu")
		(net "SMB_PCIE_E1S_ISO_EN")
	)
	(segment
		(start 208.94929 -43.396408)
		(end 208.94929 -42.028872)
		(width 0.10668)
		(layer "F.Cu")
		(net "SMB_PCIE_E1S_ISO_EN")
	)
	(via
		(at 208.94929 -42.028872)
		(size 0.508)
		(drill 0.254)
		(layers "F.Cu" "B.Cu")
		(net "SMB_PCIE_E1S_ISO_EN")
	)
	(via
		(at 259.86994 -72.976994)
		(size 0.508)
		(drill 0.254)
		(layers "F.Cu" "B.Cu")
		(net "SMB_PCIE_E1S_ISO_EN")
	)
	(segment
		(start 215.145874 -53.909214)
		(end 208.94929 -47.71263)
		(width 0.11684)
		(layer "In2.Cu")
		(net "SMB_PCIE_E1S_ISO_EN")
	)
	(segment
		(start 259.449316 -72.55637)
		(end 259.449316 -70.140322)
		(width 0.11684)
		(layer "In2.Cu")
		(net "SMB_PCIE_E1S_ISO_EN")
	)
	(segment
		(start 254.610616 -65.49263)
		(end 225.827844 -65.49263)
		(width 0.11684)
		(layer "In2.Cu")
		(net "SMB_PCIE_E1S_ISO_EN")
	)
	(segment
		(start 259.152136 -68.209414)
		(end 257.666998 -66.724276)
		(width 0.11684)
		(layer "In2.Cu")
		(net "SMB_PCIE_E1S_ISO_EN")
	)
	(segment
		(start 215.145874 -54.81066)
		(end 215.145874 -53.909214)
		(width 0.11684)
		(layer "In2.Cu")
		(net "SMB_PCIE_E1S_ISO_EN")
	)
	(segment
		(start 255.842262 -66.724276)
		(end 254.610616 -65.49263)
		(width 0.11684)
		(layer "In2.Cu")
		(net "SMB_PCIE_E1S_ISO_EN")
	)
	(segment
		(start 259.449316 -70.140322)
		(end 259.152136 -69.843142)
		(width 0.11684)
		(layer "In2.Cu")
		(net "SMB_PCIE_E1S_ISO_EN")
	)
	(segment
		(start 225.827844 -65.49263)
		(end 215.145874 -54.81066)
		(width 0.11684)
		(layer "In2.Cu")
		(net "SMB_PCIE_E1S_ISO_EN")
	)
	(segment
		(start 259.86994 -72.976994)
		(end 259.449316 -72.55637)
		(width 0.11684)
		(layer "In2.Cu")
		(net "SMB_PCIE_E1S_ISO_EN")
	)
	(segment
		(start 208.94929 -47.71263)
		(end 208.94929 -42.028872)
		(width 0.11684)
		(layer "In2.Cu")
		(net "SMB_PCIE_E1S_ISO_EN")
	)
	(segment
		(start 259.152136 -69.843142)
		(end 259.152136 -68.209414)
		(width 0.11684)
		(layer "In2.Cu")
		(net "SMB_PCIE_E1S_ISO_EN")
	)
	(segment
		(start 257.666998 -66.724276)
		(end 255.842262 -66.724276)
		(width 0.11684)
		(layer "In2.Cu")
		(net "SMB_PCIE_E1S_ISO_EN")
	)
	(segment
		(start 152.621996 -13.56487)
		(end 152.621996 -11.194034)
		(width 0.10668)
		(layer "F.Cu")
		(net "SMB_PCIE3_3V3AUX_SDA_R")
	)
	(segment
		(start 152.621996 -11.194034)
		(end 152.218136 -10.790174)
		(width 0.10668)
		(layer "F.Cu")
		(net "SMB_PCIE3_3V3AUX_SDA_R")
	)
	(segment
		(start 152.657048 -13.599922)
		(end 152.621996 -13.56487)
		(width 0.10668)
		(layer "F.Cu")
		(net "SMB_PCIE3_3V3AUX_SDA_R")
	)
	(via
		(at 152.218136 -10.790174)
		(size 0.508)
		(drill 0.254)
		(layers "F.Cu" "B.Cu")
		(net "SMB_PCIE3_3V3AUX_SDA_R")
	)
	(segment
		(start 152.940004 -13.362178)
		(end 152.461214 -12.883388)
		(width 0.10668)
		(layer "B.Cu")
		(net "SMB_PCIE3_3V3AUX_SDA_R")
	)
	(segment
		(start 152.461214 -12.883388)
		(end 152.461214 -11.033252)
		(width 0.10668)
		(layer "B.Cu")
		(net "SMB_PCIE3_3V3AUX_SDA_R")
	)
	(segment
		(start 152.9969 -13.362178)
		(end 152.940004 -13.362178)
		(width 0.10668)
		(layer "B.Cu")
		(net "SMB_PCIE3_3V3AUX_SDA_R")
	)
	(segment
		(start 152.461214 -11.033252)
		(end 152.218136 -10.790174)
		(width 0.10668)
		(layer "B.Cu")
		(net "SMB_PCIE3_3V3AUX_SDA_R")
	)
	(segment
		(start 153.256996 -13.599922)
		(end 153.256996 -12.276582)
		(width 0.10668)
		(layer "F.Cu")
		(net "SMB_PCIE3_3V3AUX_SCL_R")
	)
	(segment
		(start 153.256996 -12.276582)
		(end 153.178256 -12.197842)
		(width 0.10668)
		(layer "F.Cu")
		(net "SMB_PCIE3_3V3AUX_SCL_R")
	)
	(via
		(at 153.178256 -12.197842)
		(size 0.508)
		(drill 0.254)
		(layers "F.Cu" "B.Cu")
		(net "SMB_PCIE3_3V3AUX_SCL_R")
	)
	(segment
		(start 154.00782 -13.362178)
		(end 154.00782 -13.027406)
		(width 0.10668)
		(layer "B.Cu")
		(net "SMB_PCIE3_3V3AUX_SCL_R")
	)
	(segment
		(start 154.00782 -13.027406)
		(end 153.178256 -12.197842)
		(width 0.10668)
		(layer "B.Cu")
		(net "SMB_PCIE3_3V3AUX_SCL_R")
	)
	(segment
		(start 156.856938 -12.083034)
		(end 156.359098 -11.585194)
		(width 0.10668)
		(layer "F.Cu")
		(net "SMB_PCIE2_3V3AUX_SDA_R0")
	)
	(segment
		(start 156.856938 -13.599922)
		(end 156.856938 -12.083034)
		(width 0.10668)
		(layer "F.Cu")
		(net "SMB_PCIE2_3V3AUX_SDA_R0")
	)
	(via
		(at 156.359098 -11.585194)
		(size 0.508)
		(drill 0.254)
		(layers "F.Cu" "B.Cu")
		(net "SMB_PCIE2_3V3AUX_SDA_R0")
	)
	(segment
		(start 155.01239 -13.362178)
		(end 155.01239 -12.931902)
		(width 0.10668)
		(layer "B.Cu")
		(net "SMB_PCIE2_3V3AUX_SDA_R0")
	)
	(segment
		(start 155.01239 -12.931902)
		(end 156.359098 -11.585194)
		(width 0.10668)
		(layer "B.Cu")
		(net "SMB_PCIE2_3V3AUX_SDA_R0")
	)
	(segment
		(start 157.45714 -13.599922)
		(end 157.45714 -12.58316)
		(width 0.10668)
		(layer "F.Cu")
		(net "SMB_PCIE2_3V3AUX_SCL_R0")
	)
	(segment
		(start 157.45714 -12.58316)
		(end 157.369002 -12.495022)
		(width 0.10668)
		(layer "F.Cu")
		(net "SMB_PCIE2_3V3AUX_SCL_R0")
	)
	(via
		(at 157.369002 -12.495022)
		(size 0.508)
		(drill 0.254)
		(layers "F.Cu" "B.Cu")
		(net "SMB_PCIE2_3V3AUX_SCL_R0")
	)
	(segment
		(start 156.17063 -13.362178)
		(end 156.501846 -13.362178)
		(width 0.10668)
		(layer "B.Cu")
		(net "SMB_PCIE2_3V3AUX_SCL_R0")
	)
	(segment
		(start 156.501846 -13.362178)
		(end 157.369002 -12.495022)
		(width 0.10668)
		(layer "B.Cu")
		(net "SMB_PCIE2_3V3AUX_SCL_R0")
	)
	(segment
		(start 165.06698 -13.599922)
		(end 165.06698 -12.490958)
		(width 0.10668)
		(layer "F.Cu")
		(net "SMB_PCIE0_3V3AUX_SDA")
	)
	(segment
		(start 165.364668 -12.19327)
		(end 165.364668 -10.55243)
		(width 0.10668)
		(layer "F.Cu")
		(net "SMB_PCIE0_3V3AUX_SDA")
	)
	(segment
		(start 165.06698 -12.490958)
		(end 165.364668 -12.19327)
		(width 0.10668)
		(layer "F.Cu")
		(net "SMB_PCIE0_3V3AUX_SDA")
	)
	(via
		(at 165.364668 -10.55243)
		(size 0.508)
		(drill 0.254)
		(layers "F.Cu" "B.Cu")
		(net "SMB_PCIE0_3V3AUX_SDA")
	)
	(segment
		(start 163.359084 -9.413494)
		(end 164.508688 -9.413494)
		(width 0.10668)
		(layer "B.Cu")
		(net "SMB_PCIE0_3V3AUX_SDA")
	)
	(segment
		(start 164.508688 -9.69645)
		(end 165.364668 -10.55243)
		(width 0.10668)
		(layer "B.Cu")
		(net "SMB_PCIE0_3V3AUX_SDA")
	)
	(segment
		(start 164.508688 -9.413494)
		(end 164.508688 -9.69645)
		(width 0.10668)
		(layer "B.Cu")
		(net "SMB_PCIE0_3V3AUX_SDA")
	)
	(segment
		(start 165.666928 -13.599922)
		(end 165.666928 -12.479528)
		(width 0.10668)
		(layer "F.Cu")
		(net "SMB_PCIE0_3V3AUX_SCL")
	)
	(segment
		(start 165.666928 -12.479528)
		(end 166.263828 -11.882628)
		(width 0.10668)
		(layer "F.Cu")
		(net "SMB_PCIE0_3V3AUX_SCL")
	)
	(segment
		(start 166.263828 -11.882628)
		(end 166.263828 -11.543792)
		(width 0.10668)
		(layer "F.Cu")
		(net "SMB_PCIE0_3V3AUX_SCL")
	)
	(via
		(at 166.263828 -11.543792)
		(size 0.508)
		(drill 0.254)
		(layers "F.Cu" "B.Cu")
		(net "SMB_PCIE0_3V3AUX_SCL")
	)
	(segment
		(start 165.58514 -9.413494)
		(end 165.58514 -9.950704)
		(width 0.10668)
		(layer "B.Cu")
		(net "SMB_PCIE0_3V3AUX_SCL")
	)
	(segment
		(start 165.58514 -9.413494)
		(end 166.696644 -9.413494)
		(width 0.10668)
		(layer "B.Cu")
		(net "SMB_PCIE0_3V3AUX_SCL")
	)
	(segment
		(start 165.58514 -9.950704)
		(end 166.263828 -10.629392)
		(width 0.10668)
		(layer "B.Cu")
		(net "SMB_PCIE0_3V3AUX_SCL")
	)
	(segment
		(start 166.263828 -10.629392)
		(end 166.263828 -11.543792)
		(width 0.10668)
		(layer "B.Cu")
		(net "SMB_PCIE0_3V3AUX_SCL")
	)
	(segment
		(start 172.123354 -10.463276)
		(end 171.360338 -9.70026)
		(width 0.10668)
		(layer "F.Cu")
		(net "SMB_OCP_V3_2_3V3AUX_SDA_R0")
	)
	(segment
		(start 172.267118 -13.599922)
		(end 172.267118 -13.029946)
		(width 0.10668)
		(layer "F.Cu")
		(net "SMB_OCP_V3_2_3V3AUX_SDA_R0")
	)
	(segment
		(start 172.267118 -13.029946)
		(end 172.123354 -12.886182)
		(width 0.10668)
		(layer "F.Cu")
		(net "SMB_OCP_V3_2_3V3AUX_SDA_R0")
	)
	(segment
		(start 172.123354 -12.886182)
		(end 172.123354 -10.463276)
		(width 0.10668)
		(layer "F.Cu")
		(net "SMB_OCP_V3_2_3V3AUX_SDA_R0")
	)
	(via
		(at 171.360338 -9.70026)
		(size 0.508)
		(drill 0.254)
		(layers "F.Cu" "B.Cu")
		(net "SMB_OCP_V3_2_3V3AUX_SDA_R0")
	)
	(segment
		(start 170.424856 -8.764778)
		(end 171.360338 -9.70026)
		(width 0.10668)
		(layer "B.Cu")
		(net "SMB_OCP_V3_2_3V3AUX_SDA_R0")
	)
	(segment
		(start 170.424856 -8.462518)
		(end 170.424856 -8.764778)
		(width 0.10668)
		(layer "B.Cu")
		(net "SMB_OCP_V3_2_3V3AUX_SDA_R0")
	)
	(segment
		(start 145.363438 -38.62832)
		(end 144.117314 -38.62832)
		(width 0.10668)
		(layer "F.Cu")
		(net "SMB_OCP_V3_2_3V3AUX_SDA")
	)
	(segment
		(start 144.117314 -38.62832)
		(end 143.243554 -37.75456)
		(width 0.10668)
		(layer "F.Cu")
		(net "SMB_OCP_V3_2_3V3AUX_SDA")
	)
	(via
		(at 143.243554 -37.75456)
		(size 0.508)
		(drill 0.254)
		(layers "F.Cu" "B.Cu")
		(net "SMB_OCP_V3_2_3V3AUX_SDA")
	)
	(via
		(at 169.292524 -8.3185)
		(size 0.508)
		(drill 0.254)
		(layers "F.Cu" "B.Cu")
		(net "SMB_OCP_V3_2_3V3AUX_SDA")
	)
	(segment
		(start 170.424856 -7.662418)
		(end 169.948606 -7.662418)
		(width 0.10668)
		(layer "B.Cu")
		(net "SMB_OCP_V3_2_3V3AUX_SDA")
	)
	(segment
		(start 169.948606 -7.662418)
		(end 169.292524 -8.3185)
		(width 0.10668)
		(layer "B.Cu")
		(net "SMB_OCP_V3_2_3V3AUX_SDA")
	)
	(segment
		(start 170.424856 -7.662418)
		(end 171.440602 -7.662418)
		(width 0.10668)
		(layer "B.Cu")
		(net "SMB_OCP_V3_2_3V3AUX_SDA")
	)
	(segment
		(start 159.576008 -12.98448)
		(end 158.97733 -12.98448)
		(width 0.11684)
		(layer "In2.Cu")
		(net "SMB_OCP_V3_2_3V3AUX_SDA")
	)
	(segment
		(start 142.437612 -29.411676)
		(end 142.437612 -32.958532)
		(width 0.11684)
		(layer "In2.Cu")
		(net "SMB_OCP_V3_2_3V3AUX_SDA")
	)
	(segment
		(start 142.68196 -36.357052)
		(end 143.845026 -36.357052)
		(width 0.11684)
		(layer "In2.Cu")
		(net "SMB_OCP_V3_2_3V3AUX_SDA")
	)
	(segment
		(start 142.56512 -36.049712)
		(end 142.56512 -36.240212)
		(width 0.11684)
		(layer "In2.Cu")
		(net "SMB_OCP_V3_2_3V3AUX_SDA")
	)
	(segment
		(start 143.55572 -34.967672)
		(end 143.43888 -35.084512)
		(width 0.11684)
		(layer "In2.Cu")
		(net "SMB_OCP_V3_2_3V3AUX_SDA")
	)
	(segment
		(start 142.437612 -32.958532)
		(end 143.55572 -34.07664)
		(width 0.11684)
		(layer "In2.Cu")
		(net "SMB_OCP_V3_2_3V3AUX_SDA")
	)
	(segment
		(start 163.145978 -9.41451)
		(end 159.576008 -12.98448)
		(width 0.11684)
		(layer "In2.Cu")
		(net "SMB_OCP_V3_2_3V3AUX_SDA")
	)
	(segment
		(start 142.571216 -14.181582)
		(end 142.571216 -15.331186)
		(width 0.11684)
		(layer "In2.Cu")
		(net "SMB_OCP_V3_2_3V3AUX_SDA")
	)
	(segment
		(start 143.845026 -35.932872)
		(end 142.68196 -35.932872)
		(width 0.11684)
		(layer "In2.Cu")
		(net "SMB_OCP_V3_2_3V3AUX_SDA")
	)
	(segment
		(start 142.56512 -35.201352)
		(end 142.56512 -35.391852)
		(width 0.11684)
		(layer "In2.Cu")
		(net "SMB_OCP_V3_2_3V3AUX_SDA")
	)
	(segment
		(start 168.196514 -9.41451)
		(end 163.145978 -9.41451)
		(width 0.11684)
		(layer "In2.Cu")
		(net "SMB_OCP_V3_2_3V3AUX_SDA")
	)
	(segment
		(start 158.97733 -12.98448)
		(end 158.725362 -13.236448)
		(width 0.11684)
		(layer "In2.Cu")
		(net "SMB_OCP_V3_2_3V3AUX_SDA")
	)
	(segment
		(start 143.55572 -28.293568)
		(end 142.437612 -29.411676)
		(width 0.11684)
		(layer "In2.Cu")
		(net "SMB_OCP_V3_2_3V3AUX_SDA")
	)
	(segment
		(start 143.961866 -37.036248)
		(end 143.243554 -37.75456)
		(width 0.11684)
		(layer "In2.Cu")
		(net "SMB_OCP_V3_2_3V3AUX_SDA")
	)
	(segment
		(start 143.51635 -13.236448)
		(end 142.571216 -14.181582)
		(width 0.11684)
		(layer "In2.Cu")
		(net "SMB_OCP_V3_2_3V3AUX_SDA")
	)
	(segment
		(start 143.961866 -36.473892)
		(end 143.961866 -37.036248)
		(width 0.11684)
		(layer "In2.Cu")
		(net "SMB_OCP_V3_2_3V3AUX_SDA")
	)
	(segment
		(start 158.725362 -13.236448)
		(end 143.51635 -13.236448)
		(width 0.11684)
		(layer "In2.Cu")
		(net "SMB_OCP_V3_2_3V3AUX_SDA")
	)
	(segment
		(start 169.292524 -8.3185)
		(end 168.196514 -9.41451)
		(width 0.11684)
		(layer "In2.Cu")
		(net "SMB_OCP_V3_2_3V3AUX_SDA")
	)
	(segment
		(start 143.55572 -34.07664)
		(end 143.55572 -34.967672)
		(width 0.11684)
		(layer "In2.Cu")
		(net "SMB_OCP_V3_2_3V3AUX_SDA")
	)
	(segment
		(start 143.845026 -36.357052)
		(end 143.961866 -36.473892)
		(width 0.11684)
		(layer "In2.Cu")
		(net "SMB_OCP_V3_2_3V3AUX_SDA")
	)
	(segment
		(start 142.56512 -36.240212)
		(end 142.68196 -36.357052)
		(width 0.11684)
		(layer "In2.Cu")
		(net "SMB_OCP_V3_2_3V3AUX_SDA")
	)
	(segment
		(start 142.56512 -35.391852)
		(end 142.68196 -35.508692)
		(width 0.11684)
		(layer "In2.Cu")
		(net "SMB_OCP_V3_2_3V3AUX_SDA")
	)
	(segment
		(start 143.43888 -35.084512)
		(end 142.68196 -35.084512)
		(width 0.11684)
		(layer "In2.Cu")
		(net "SMB_OCP_V3_2_3V3AUX_SDA")
	)
	(segment
		(start 142.571216 -15.331186)
		(end 143.55572 -16.31569)
		(width 0.11684)
		(layer "In2.Cu")
		(net "SMB_OCP_V3_2_3V3AUX_SDA")
	)
	(segment
		(start 143.961866 -35.816032)
		(end 143.845026 -35.932872)
		(width 0.11684)
		(layer "In2.Cu")
		(net "SMB_OCP_V3_2_3V3AUX_SDA")
	)
	(segment
		(start 143.55572 -16.31569)
		(end 143.55572 -28.293568)
		(width 0.11684)
		(layer "In2.Cu")
		(net "SMB_OCP_V3_2_3V3AUX_SDA")
	)
	(segment
		(start 142.68196 -35.084512)
		(end 142.56512 -35.201352)
		(width 0.11684)
		(layer "In2.Cu")
		(net "SMB_OCP_V3_2_3V3AUX_SDA")
	)
	(segment
		(start 142.68196 -35.932872)
		(end 142.56512 -36.049712)
		(width 0.11684)
		(layer "In2.Cu")
		(net "SMB_OCP_V3_2_3V3AUX_SDA")
	)
	(segment
		(start 143.845026 -35.508692)
		(end 143.961866 -35.625532)
		(width 0.11684)
		(layer "In2.Cu")
		(net "SMB_OCP_V3_2_3V3AUX_SDA")
	)
	(segment
		(start 142.68196 -35.508692)
		(end 143.845026 -35.508692)
		(width 0.11684)
		(layer "In2.Cu")
		(net "SMB_OCP_V3_2_3V3AUX_SDA")
	)
	(segment
		(start 143.961866 -35.625532)
		(end 143.961866 -35.816032)
		(width 0.11684)
		(layer "In2.Cu")
		(net "SMB_OCP_V3_2_3V3AUX_SDA")
	)
	(segment
		(start 172.867066 -13.599922)
		(end 172.867066 -13.070586)
		(width 0.10668)
		(layer "F.Cu")
		(net "SMB_OCP_V3_2_3V3AUX_SCL_R0")
	)
	(segment
		(start 172.570394 -12.621768)
		(end 172.570394 -10.069322)
		(width 0.10668)
		(layer "F.Cu")
		(net "SMB_OCP_V3_2_3V3AUX_SCL_R0")
	)
	(segment
		(start 172.570394 -10.069322)
		(end 172.939456 -9.70026)
		(width 0.10668)
		(layer "F.Cu")
		(net "SMB_OCP_V3_2_3V3AUX_SCL_R0")
	)
	(segment
		(start 172.678344 -12.881864)
		(end 172.570394 -12.621768)
		(width 0.10668)
		(layer "F.Cu")
		(net "SMB_OCP_V3_2_3V3AUX_SCL_R0")
	)
	(segment
		(start 172.867066 -13.070586)
		(end 172.678344 -12.881864)
		(width 0.10668)
		(layer "F.Cu")
		(net "SMB_OCP_V3_2_3V3AUX_SCL_R0")
	)
	(via
		(at 172.939456 -9.70026)
		(size 0.508)
		(drill 0.254)
		(layers "F.Cu" "B.Cu")
		(net "SMB_OCP_V3_2_3V3AUX_SCL_R0")
	)
	(segment
		(start 173.376844 -9.70026)
		(end 172.939456 -9.70026)
		(width 0.10668)
		(layer "B.Cu")
		(net "SMB_OCP_V3_2_3V3AUX_SCL_R0")
	)
	(segment
		(start 174.202852 -8.874252)
		(end 173.376844 -9.70026)
		(width 0.10668)
		(layer "B.Cu")
		(net "SMB_OCP_V3_2_3V3AUX_SCL_R0")
	)
	(segment
		(start 174.202852 -8.45693)
		(end 174.202852 -8.874252)
		(width 0.10668)
		(layer "B.Cu")
		(net "SMB_OCP_V3_2_3V3AUX_SCL_R0")
	)
	(segment
		(start 145.363438 -39.27856)
		(end 143.497554 -39.27856)
		(width 0.10668)
		(layer "F.Cu")
		(net "SMB_OCP_V3_2_3V3AUX_SCL")
	)
	(segment
		(start 143.497554 -39.27856)
		(end 143.243554 -39.02456)
		(width 0.10668)
		(layer "F.Cu")
		(net "SMB_OCP_V3_2_3V3AUX_SCL")
	)
	(via
		(at 175.380904 -8.301736)
		(size 0.508)
		(drill 0.254)
		(layers "F.Cu" "B.Cu")
		(net "SMB_OCP_V3_2_3V3AUX_SCL")
	)
	(via
		(at 143.243554 -39.02456)
		(size 0.508)
		(drill 0.254)
		(layers "F.Cu" "B.Cu")
		(net "SMB_OCP_V3_2_3V3AUX_SCL")
	)
	(segment
		(start 174.202852 -7.65683)
		(end 174.735998 -7.65683)
		(width 0.10668)
		(layer "B.Cu")
		(net "SMB_OCP_V3_2_3V3AUX_SCL")
	)
	(segment
		(start 174.735998 -7.65683)
		(end 175.380904 -8.301736)
		(width 0.10668)
		(layer "B.Cu")
		(net "SMB_OCP_V3_2_3V3AUX_SCL")
	)
	(segment
		(start 174.197264 -7.662418)
		(end 174.202852 -7.65683)
		(width 0.10668)
		(layer "B.Cu")
		(net "SMB_OCP_V3_2_3V3AUX_SCL")
	)
	(segment
		(start 172.877734 -7.662418)
		(end 174.197264 -7.662418)
		(width 0.10668)
		(layer "B.Cu")
		(net "SMB_OCP_V3_2_3V3AUX_SCL")
	)
	(segment
		(start 143.927068 -37.667438)
		(end 145.19656 -36.397946)
		(width 0.11684)
		(layer "In2.Cu")
		(net "SMB_OCP_V3_2_3V3AUX_SCL")
	)
	(segment
		(start 163.32073 -9.83615)
		(end 169.28338 -9.83615)
		(width 0.11684)
		(layer "In2.Cu")
		(net "SMB_OCP_V3_2_3V3AUX_SCL")
	)
	(segment
		(start 143.053054 -29.849826)
		(end 145.19656 -27.70632)
		(width 0.11684)
		(layer "In2.Cu")
		(net "SMB_OCP_V3_2_3V3AUX_SCL")
	)
	(segment
		(start 159.152082 -13.40612)
		(end 159.75076 -13.40612)
		(width 0.11684)
		(layer "In2.Cu")
		(net "SMB_OCP_V3_2_3V3AUX_SCL")
	)
	(segment
		(start 143.751046 -13.658088)
		(end 158.900114 -13.658088)
		(width 0.11684)
		(layer "In2.Cu")
		(net "SMB_OCP_V3_2_3V3AUX_SCL")
	)
	(segment
		(start 142.992856 -15.156434)
		(end 142.992856 -14.416278)
		(width 0.11684)
		(layer "In2.Cu")
		(net "SMB_OCP_V3_2_3V3AUX_SCL")
	)
	(segment
		(start 145.19656 -34.70656)
		(end 143.053054 -32.563054)
		(width 0.11684)
		(layer "In2.Cu")
		(net "SMB_OCP_V3_2_3V3AUX_SCL")
	)
	(segment
		(start 171.299124 -7.820406)
		(end 174.899574 -7.820406)
		(width 0.11684)
		(layer "In2.Cu")
		(net "SMB_OCP_V3_2_3V3AUX_SCL")
	)
	(segment
		(start 158.900114 -13.658088)
		(end 159.152082 -13.40612)
		(width 0.11684)
		(layer "In2.Cu")
		(net "SMB_OCP_V3_2_3V3AUX_SCL")
	)
	(segment
		(start 145.19656 -17.360138)
		(end 142.992856 -15.156434)
		(width 0.11684)
		(layer "In2.Cu")
		(net "SMB_OCP_V3_2_3V3AUX_SCL")
	)
	(segment
		(start 169.28338 -9.83615)
		(end 171.299124 -7.820406)
		(width 0.11684)
		(layer "In2.Cu")
		(net "SMB_OCP_V3_2_3V3AUX_SCL")
	)
	(segment
		(start 145.19656 -36.397946)
		(end 145.19656 -34.70656)
		(width 0.11684)
		(layer "In2.Cu")
		(net "SMB_OCP_V3_2_3V3AUX_SCL")
	)
	(segment
		(start 145.19656 -27.70632)
		(end 145.19656 -17.360138)
		(width 0.11684)
		(layer "In2.Cu")
		(net "SMB_OCP_V3_2_3V3AUX_SCL")
	)
	(segment
		(start 159.75076 -13.40612)
		(end 163.32073 -9.83615)
		(width 0.11684)
		(layer "In2.Cu")
		(net "SMB_OCP_V3_2_3V3AUX_SCL")
	)
	(segment
		(start 143.243554 -39.02456)
		(end 143.927068 -38.341046)
		(width 0.11684)
		(layer "In2.Cu")
		(net "SMB_OCP_V3_2_3V3AUX_SCL")
	)
	(segment
		(start 143.053054 -32.563054)
		(end 143.053054 -29.849826)
		(width 0.11684)
		(layer "In2.Cu")
		(net "SMB_OCP_V3_2_3V3AUX_SCL")
	)
	(segment
		(start 143.927068 -38.341046)
		(end 143.927068 -37.667438)
		(width 0.11684)
		(layer "In2.Cu")
		(net "SMB_OCP_V3_2_3V3AUX_SCL")
	)
	(segment
		(start 142.992856 -14.416278)
		(end 143.751046 -13.658088)
		(width 0.11684)
		(layer "In2.Cu")
		(net "SMB_OCP_V3_2_3V3AUX_SCL")
	)
	(segment
		(start 174.899574 -7.820406)
		(end 175.380904 -8.301736)
		(width 0.11684)
		(layer "In2.Cu")
		(net "SMB_OCP_V3_2_3V3AUX_SCL")
	)
	(segment
		(start 150.959566 -38.62832)
		(end 151.833326 -37.75456)
		(width 0.10668)
		(layer "F.Cu")
		(net "SMB_OCP_V3_2_3V3AUX_BUF_SDA")
	)
	(segment
		(start 152.449276 -38.00856)
		(end 152.087326 -38.00856)
		(width 0.10668)
		(layer "F.Cu")
		(net "SMB_OCP_V3_2_3V3AUX_BUF_SDA")
	)
	(segment
		(start 152.087326 -38.00856)
		(end 151.833326 -37.75456)
		(width 0.10668)
		(layer "F.Cu")
		(net "SMB_OCP_V3_2_3V3AUX_BUF_SDA")
	)
	(segment
		(start 149.713442 -38.62832)
		(end 150.959566 -38.62832)
		(width 0.10668)
		(layer "F.Cu")
		(net "SMB_OCP_V3_2_3V3AUX_BUF_SDA")
	)
	(segment
		(start 152.449276 -36.99256)
		(end 152.449276 -38.00856)
		(width 0.10668)
		(layer "F.Cu")
		(net "SMB_OCP_V3_2_3V3AUX_BUF_SDA")
	)
	(via
		(at 151.833326 -37.75456)
		(size 0.508)
		(drill 0.254)
		(layers "F.Cu" "B.Cu")
		(net "SMB_OCP_V3_2_3V3AUX_BUF_SDA")
	)
	(segment
		(start 149.713442 -39.27856)
		(end 151.579326 -39.27856)
		(width 0.10668)
		(layer "F.Cu")
		(net "SMB_OCP_V3_2_3V3AUX_BUF_SCL")
	)
	(segment
		(start 152.9334 -40.04056)
		(end 152.449276 -39.556436)
		(width 0.10668)
		(layer "F.Cu")
		(net "SMB_OCP_V3_2_3V3AUX_BUF_SCL")
	)
	(segment
		(start 153.086562 -40.04056)
		(end 152.9334 -40.04056)
		(width 0.10668)
		(layer "F.Cu")
		(net "SMB_OCP_V3_2_3V3AUX_BUF_SCL")
	)
	(segment
		(start 151.833326 -39.02456)
		(end 152.449276 -39.02456)
		(width 0.10668)
		(layer "F.Cu")
		(net "SMB_OCP_V3_2_3V3AUX_BUF_SCL")
	)
	(segment
		(start 151.579326 -39.27856)
		(end 151.833326 -39.02456)
		(width 0.10668)
		(layer "F.Cu")
		(net "SMB_OCP_V3_2_3V3AUX_BUF_SCL")
	)
	(segment
		(start 152.449276 -39.556436)
		(end 152.449276 -39.02456)
		(width 0.10668)
		(layer "F.Cu")
		(net "SMB_OCP_V3_2_3V3AUX_BUF_SCL")
	)
	(via
		(at 151.833326 -39.02456)
		(size 0.508)
		(drill 0.254)
		(layers "F.Cu" "B.Cu")
		(net "SMB_OCP_V3_2_3V3AUX_BUF_SCL")
	)
	(segment
		(start 61.666882 -6.760718)
		(end 62.612524 -5.815076)
		(width 0.10668)
		(layer "F.Cu")
		(net "SMB_OCP_V3_2_3V3AUX_BUF_R_SDA")
	)
	(segment
		(start 61.666882 -8.320024)
		(end 61.666882 -6.760718)
		(width 0.10668)
		(layer "F.Cu")
		(net "SMB_OCP_V3_2_3V3AUX_BUF_R_SDA")
	)
	(segment
		(start 153.249376 -36.99256)
		(end 153.886662 -36.99256)
		(width 0.10668)
		(layer "F.Cu")
		(net "SMB_OCP_V3_2_3V3AUX_BUF_R_SDA")
	)
	(segment
		(start 62.612524 -5.815076)
		(end 62.612524 -5.17271)
		(width 0.10668)
		(layer "F.Cu")
		(net "SMB_OCP_V3_2_3V3AUX_BUF_R_SDA")
	)
	(via
		(at 62.612524 -5.17271)
		(size 0.508)
		(drill 0.254)
		(layers "F.Cu" "B.Cu")
		(net "SMB_OCP_V3_2_3V3AUX_BUF_R_SDA")
	)
	(via
		(at 63.780924 -3.20421)
		(size 0.508)
		(drill 0.254)
		(layers "F.Cu" "B.Cu")
		(net "SMB_OCP_V3_2_3V3AUX_BUF_R_SDA")
	)
	(via
		(at 153.886662 -36.99256)
		(size 0.508)
		(drill 0.254)
		(layers "F.Cu" "B.Cu")
		(net "SMB_OCP_V3_2_3V3AUX_BUF_R_SDA")
	)
	(segment
		(start 62.612524 -5.17271)
		(end 62.612524 -4.37261)
		(width 0.10668)
		(layer "B.Cu")
		(net "SMB_OCP_V3_2_3V3AUX_BUF_R_SDA")
	)
	(segment
		(start 62.612524 -4.37261)
		(end 63.780924 -3.20421)
		(width 0.10668)
		(layer "B.Cu")
		(net "SMB_OCP_V3_2_3V3AUX_BUF_R_SDA")
	)
	(segment
		(start 138.70178 -32.5628)
		(end 140.937996 -34.799016)
		(width 0.11684)
		(layer "In6.Cu")
		(net "SMB_OCP_V3_2_3V3AUX_BUF_R_SDA")
	)
	(segment
		(start 81.985866 -15.66926)
		(end 97.968308 -15.66926)
		(width 0.11684)
		(layer "In6.Cu")
		(net "SMB_OCP_V3_2_3V3AUX_BUF_R_SDA")
	)
	(segment
		(start 104.609392 -36.29914)
		(end 117.82552 -36.29914)
		(width 0.11684)
		(layer "In6.Cu")
		(net "SMB_OCP_V3_2_3V3AUX_BUF_R_SDA")
	)
	(segment
		(start 98.20148 -29.51988)
		(end 98.20148 -32.685736)
		(width 0.11684)
		(layer "In6.Cu")
		(net "SMB_OCP_V3_2_3V3AUX_BUF_R_SDA")
	)
	(segment
		(start 146.447002 -36.99256)
		(end 153.886662 -36.99256)
		(width 0.11684)
		(layer "In6.Cu")
		(net "SMB_OCP_V3_2_3V3AUX_BUF_R_SDA")
	)
	(segment
		(start 64.43853 -3.20421)
		(end 69.581268 -8.346948)
		(width 0.11684)
		(layer "In6.Cu")
		(net "SMB_OCP_V3_2_3V3AUX_BUF_R_SDA")
	)
	(segment
		(start 144.253458 -34.799016)
		(end 146.447002 -36.99256)
		(width 0.11684)
		(layer "In6.Cu")
		(net "SMB_OCP_V3_2_3V3AUX_BUF_R_SDA")
	)
	(segment
		(start 100.313744 -34.798)
		(end 103.108252 -34.798)
		(width 0.11684)
		(layer "In6.Cu")
		(net "SMB_OCP_V3_2_3V3AUX_BUF_R_SDA")
	)
	(segment
		(start 101.319076 -19.020028)
		(end 101.319076 -26.402284)
		(width 0.11684)
		(layer "In6.Cu")
		(net "SMB_OCP_V3_2_3V3AUX_BUF_R_SDA")
	)
	(segment
		(start 79.790798 -10.532364)
		(end 79.790798 -13.474192)
		(width 0.11684)
		(layer "In6.Cu")
		(net "SMB_OCP_V3_2_3V3AUX_BUF_R_SDA")
	)
	(segment
		(start 126.5428 -32.893)
		(end 129.3622 -30.0736)
		(width 0.11684)
		(layer "In6.Cu")
		(net "SMB_OCP_V3_2_3V3AUX_BUF_R_SDA")
	)
	(segment
		(start 119.8626 -35.1028)
		(end 121.760488 -37.000688)
		(width 0.11684)
		(layer "In6.Cu")
		(net "SMB_OCP_V3_2_3V3AUX_BUF_R_SDA")
	)
	(segment
		(start 101.319076 -26.402284)
		(end 98.20148 -29.51988)
		(width 0.11684)
		(layer "In6.Cu")
		(net "SMB_OCP_V3_2_3V3AUX_BUF_R_SDA")
	)
	(segment
		(start 133.95198 -30.0736)
		(end 136.44118 -32.5628)
		(width 0.11684)
		(layer "In6.Cu")
		(net "SMB_OCP_V3_2_3V3AUX_BUF_R_SDA")
	)
	(segment
		(start 69.581268 -8.346948)
		(end 77.605382 -8.346948)
		(width 0.11684)
		(layer "In6.Cu")
		(net "SMB_OCP_V3_2_3V3AUX_BUF_R_SDA")
	)
	(segment
		(start 63.780924 -3.20421)
		(end 64.43853 -3.20421)
		(width 0.11684)
		(layer "In6.Cu")
		(net "SMB_OCP_V3_2_3V3AUX_BUF_R_SDA")
	)
	(segment
		(start 123.821952 -37.000688)
		(end 126.5428 -34.27984)
		(width 0.11684)
		(layer "In6.Cu")
		(net "SMB_OCP_V3_2_3V3AUX_BUF_R_SDA")
	)
	(segment
		(start 136.44118 -32.5628)
		(end 138.70178 -32.5628)
		(width 0.11684)
		(layer "In6.Cu")
		(net "SMB_OCP_V3_2_3V3AUX_BUF_R_SDA")
	)
	(segment
		(start 77.605382 -8.346948)
		(end 79.790798 -10.532364)
		(width 0.11684)
		(layer "In6.Cu")
		(net "SMB_OCP_V3_2_3V3AUX_BUF_R_SDA")
	)
	(segment
		(start 121.760488 -37.000688)
		(end 123.821952 -37.000688)
		(width 0.11684)
		(layer "In6.Cu")
		(net "SMB_OCP_V3_2_3V3AUX_BUF_R_SDA")
	)
	(segment
		(start 97.968308 -15.66926)
		(end 101.319076 -19.020028)
		(width 0.11684)
		(layer "In6.Cu")
		(net "SMB_OCP_V3_2_3V3AUX_BUF_R_SDA")
	)
	(segment
		(start 103.108252 -34.798)
		(end 104.609392 -36.29914)
		(width 0.11684)
		(layer "In6.Cu")
		(net "SMB_OCP_V3_2_3V3AUX_BUF_R_SDA")
	)
	(segment
		(start 126.5428 -34.27984)
		(end 126.5428 -32.893)
		(width 0.11684)
		(layer "In6.Cu")
		(net "SMB_OCP_V3_2_3V3AUX_BUF_R_SDA")
	)
	(segment
		(start 119.02186 -35.1028)
		(end 119.8626 -35.1028)
		(width 0.11684)
		(layer "In6.Cu")
		(net "SMB_OCP_V3_2_3V3AUX_BUF_R_SDA")
	)
	(segment
		(start 98.20148 -32.685736)
		(end 100.313744 -34.798)
		(width 0.11684)
		(layer "In6.Cu")
		(net "SMB_OCP_V3_2_3V3AUX_BUF_R_SDA")
	)
	(segment
		(start 140.937996 -34.799016)
		(end 144.253458 -34.799016)
		(width 0.11684)
		(layer "In6.Cu")
		(net "SMB_OCP_V3_2_3V3AUX_BUF_R_SDA")
	)
	(segment
		(start 117.82552 -36.29914)
		(end 119.02186 -35.1028)
		(width 0.11684)
		(layer "In6.Cu")
		(net "SMB_OCP_V3_2_3V3AUX_BUF_R_SDA")
	)
	(segment
		(start 129.3622 -30.0736)
		(end 133.95198 -30.0736)
		(width 0.11684)
		(layer "In6.Cu")
		(net "SMB_OCP_V3_2_3V3AUX_BUF_R_SDA")
	)
	(segment
		(start 79.790798 -13.474192)
		(end 81.985866 -15.66926)
		(width 0.11684)
		(layer "In6.Cu")
		(net "SMB_OCP_V3_2_3V3AUX_BUF_R_SDA")
	)
	(segment
		(start 153.886662 -40.04056)
		(end 153.886662 -39.403274)
		(width 0.10668)
		(layer "F.Cu")
		(net "SMB_OCP_V3_2_3V3AUX_BUF_R_SCL")
	)
	(segment
		(start 62.267084 -7.12851)
		(end 62.574424 -6.82117)
		(width 0.10668)
		(layer "F.Cu")
		(net "SMB_OCP_V3_2_3V3AUX_BUF_R_SCL")
	)
	(segment
		(start 62.267084 -8.320024)
		(end 62.267084 -7.12851)
		(width 0.10668)
		(layer "F.Cu")
		(net "SMB_OCP_V3_2_3V3AUX_BUF_R_SCL")
	)
	(via
		(at 64.796924 -4.22021)
		(size 0.508)
		(drill 0.254)
		(layers "F.Cu" "B.Cu")
		(net "SMB_OCP_V3_2_3V3AUX_BUF_R_SCL")
	)
	(via
		(at 62.574424 -6.82117)
		(size 0.508)
		(drill 0.254)
		(layers "F.Cu" "B.Cu")
		(net "SMB_OCP_V3_2_3V3AUX_BUF_R_SCL")
	)
	(via
		(at 153.886662 -39.403274)
		(size 0.508)
		(drill 0.254)
		(layers "F.Cu" "B.Cu")
		(net "SMB_OCP_V3_2_3V3AUX_BUF_R_SCL")
	)
	(segment
		(start 64.796924 -4.59867)
		(end 64.796924 -4.22021)
		(width 0.10668)
		(layer "B.Cu")
		(net "SMB_OCP_V3_2_3V3AUX_BUF_R_SCL")
	)
	(segment
		(start 62.574424 -6.82117)
		(end 64.796924 -4.59867)
		(width 0.10668)
		(layer "B.Cu")
		(net "SMB_OCP_V3_2_3V3AUX_BUF_R_SCL")
	)
	(segment
		(start 144.078706 -35.220656)
		(end 140.763244 -35.220656)
		(width 0.11684)
		(layer "In6.Cu")
		(net "SMB_OCP_V3_2_3V3AUX_BUF_R_SCL")
	)
	(segment
		(start 81.811114 -16.0909)
		(end 79.369158 -13.648944)
		(width 0.11684)
		(layer "In6.Cu")
		(net "SMB_OCP_V3_2_3V3AUX_BUF_R_SCL")
	)
	(segment
		(start 127.0508 -33.0708)
		(end 127.0508 -34.417)
		(width 0.11684)
		(layer "In6.Cu")
		(net "SMB_OCP_V3_2_3V3AUX_BUF_R_SCL")
	)
	(segment
		(start 97.77984 -32.860488)
		(end 97.77984 -29.345128)
		(width 0.11684)
		(layer "In6.Cu")
		(net "SMB_OCP_V3_2_3V3AUX_BUF_R_SCL")
	)
	(segment
		(start 129.1717 -30.9499)
		(end 127.0508 -33.0708)
		(width 0.11684)
		(layer "In6.Cu")
		(net "SMB_OCP_V3_2_3V3AUX_BUF_R_SCL")
	)
	(segment
		(start 152.926288 -38.4429)
		(end 147.30095 -38.4429)
		(width 0.11684)
		(layer "In6.Cu")
		(net "SMB_OCP_V3_2_3V3AUX_BUF_R_SCL")
	)
	(segment
		(start 153.886662 -39.403274)
		(end 152.926288 -38.4429)
		(width 0.11684)
		(layer "In6.Cu")
		(net "SMB_OCP_V3_2_3V3AUX_BUF_R_SCL")
	)
	(segment
		(start 117.84838 -36.72078)
		(end 104.43464 -36.72078)
		(width 0.11684)
		(layer "In6.Cu")
		(net "SMB_OCP_V3_2_3V3AUX_BUF_R_SCL")
	)
	(segment
		(start 131.445 -31.496)
		(end 130.4544 -31.496)
		(width 0.11684)
		(layer "In6.Cu")
		(net "SMB_OCP_V3_2_3V3AUX_BUF_R_SCL")
	)
	(segment
		(start 136.4742 -34.0106)
		(end 135.3058 -32.8422)
		(width 0.11684)
		(layer "In6.Cu")
		(net "SMB_OCP_V3_2_3V3AUX_BUF_R_SCL")
	)
	(segment
		(start 137.16 -34.0106)
		(end 136.4742 -34.0106)
		(width 0.11684)
		(layer "In6.Cu")
		(net "SMB_OCP_V3_2_3V3AUX_BUF_R_SCL")
	)
	(segment
		(start 140.763244 -35.220656)
		(end 138.943588 -33.401)
		(width 0.11684)
		(layer "In6.Cu")
		(net "SMB_OCP_V3_2_3V3AUX_BUF_R_SCL")
	)
	(segment
		(start 69.345302 -8.768588)
		(end 64.796924 -4.22021)
		(width 0.11684)
		(layer "In6.Cu")
		(net "SMB_OCP_V3_2_3V3AUX_BUF_R_SCL")
	)
	(segment
		(start 132.7912 -32.8422)
		(end 131.445 -31.496)
		(width 0.11684)
		(layer "In6.Cu")
		(net "SMB_OCP_V3_2_3V3AUX_BUF_R_SCL")
	)
	(segment
		(start 102.9335 -35.21964)
		(end 100.138992 -35.21964)
		(width 0.11684)
		(layer "In6.Cu")
		(net "SMB_OCP_V3_2_3V3AUX_BUF_R_SCL")
	)
	(segment
		(start 137.7696 -33.401)
		(end 137.16 -34.0106)
		(width 0.11684)
		(layer "In6.Cu")
		(net "SMB_OCP_V3_2_3V3AUX_BUF_R_SCL")
	)
	(segment
		(start 123.55576 -37.91204)
		(end 119.03964 -37.91204)
		(width 0.11684)
		(layer "In6.Cu")
		(net "SMB_OCP_V3_2_3V3AUX_BUF_R_SCL")
	)
	(segment
		(start 97.77984 -29.345128)
		(end 100.897436 -26.227532)
		(width 0.11684)
		(layer "In6.Cu")
		(net "SMB_OCP_V3_2_3V3AUX_BUF_R_SCL")
	)
	(segment
		(start 77.43063 -8.768588)
		(end 69.345302 -8.768588)
		(width 0.11684)
		(layer "In6.Cu")
		(net "SMB_OCP_V3_2_3V3AUX_BUF_R_SCL")
	)
	(segment
		(start 129.9083 -30.9499)
		(end 129.1717 -30.9499)
		(width 0.11684)
		(layer "In6.Cu")
		(net "SMB_OCP_V3_2_3V3AUX_BUF_R_SCL")
	)
	(segment
		(start 130.4544 -31.496)
		(end 129.9083 -30.9499)
		(width 0.11684)
		(layer "In6.Cu")
		(net "SMB_OCP_V3_2_3V3AUX_BUF_R_SCL")
	)
	(segment
		(start 135.3058 -32.8422)
		(end 132.7912 -32.8422)
		(width 0.11684)
		(layer "In6.Cu")
		(net "SMB_OCP_V3_2_3V3AUX_BUF_R_SCL")
	)
	(segment
		(start 100.897436 -19.19478)
		(end 97.793556 -16.0909)
		(width 0.11684)
		(layer "In6.Cu")
		(net "SMB_OCP_V3_2_3V3AUX_BUF_R_SCL")
	)
	(segment
		(start 119.03964 -37.91204)
		(end 117.84838 -36.72078)
		(width 0.11684)
		(layer "In6.Cu")
		(net "SMB_OCP_V3_2_3V3AUX_BUF_R_SCL")
	)
	(segment
		(start 147.30095 -38.4429)
		(end 144.078706 -35.220656)
		(width 0.11684)
		(layer "In6.Cu")
		(net "SMB_OCP_V3_2_3V3AUX_BUF_R_SCL")
	)
	(segment
		(start 127.0508 -34.417)
		(end 123.55576 -37.91204)
		(width 0.11684)
		(layer "In6.Cu")
		(net "SMB_OCP_V3_2_3V3AUX_BUF_R_SCL")
	)
	(segment
		(start 97.793556 -16.0909)
		(end 81.811114 -16.0909)
		(width 0.11684)
		(layer "In6.Cu")
		(net "SMB_OCP_V3_2_3V3AUX_BUF_R_SCL")
	)
	(segment
		(start 100.138992 -35.21964)
		(end 97.77984 -32.860488)
		(width 0.11684)
		(layer "In6.Cu")
		(net "SMB_OCP_V3_2_3V3AUX_BUF_R_SCL")
	)
	(segment
		(start 100.897436 -26.227532)
		(end 100.897436 -19.19478)
		(width 0.11684)
		(layer "In6.Cu")
		(net "SMB_OCP_V3_2_3V3AUX_BUF_R_SCL")
	)
	(segment
		(start 79.369158 -13.648944)
		(end 79.369158 -10.707116)
		(width 0.11684)
		(layer "In6.Cu")
		(net "SMB_OCP_V3_2_3V3AUX_BUF_R_SCL")
	)
	(segment
		(start 138.943588 -33.401)
		(end 137.7696 -33.401)
		(width 0.11684)
		(layer "In6.Cu")
		(net "SMB_OCP_V3_2_3V3AUX_BUF_R_SCL")
	)
	(segment
		(start 79.369158 -10.707116)
		(end 77.43063 -8.768588)
		(width 0.11684)
		(layer "In6.Cu")
		(net "SMB_OCP_V3_2_3V3AUX_BUF_R_SCL")
	)
	(segment
		(start 104.43464 -36.72078)
		(end 102.9335 -35.21964)
		(width 0.11684)
		(layer "In6.Cu")
		(net "SMB_OCP_V3_2_3V3AUX_BUF_R_SCL")
	)
	(segment
		(start 182.142384 -16.375126)
		(end 182.142384 -18.215864)
		(width 0.10668)
		(layer "F.Cu")
		(net "SMB_OCP_SFF_3V3AUX_SDA_R0")
	)
	(segment
		(start 178.267106 -13.599922)
		(end 178.267106 -14.223746)
		(width 0.10668)
		(layer "F.Cu")
		(net "SMB_OCP_SFF_3V3AUX_SDA_R0")
	)
	(segment
		(start 178.267106 -14.223746)
		(end 178.844956 -14.801596)
		(width 0.10668)
		(layer "F.Cu")
		(net "SMB_OCP_SFF_3V3AUX_SDA_R0")
	)
	(segment
		(start 178.844956 -14.801596)
		(end 180.568854 -14.801596)
		(width 0.10668)
		(layer "F.Cu")
		(net "SMB_OCP_SFF_3V3AUX_SDA_R0")
	)
	(segment
		(start 182.142384 -18.215864)
		(end 182.731664 -18.805144)
		(width 0.10668)
		(layer "F.Cu")
		(net "SMB_OCP_SFF_3V3AUX_SDA_R0")
	)
	(segment
		(start 180.568854 -14.801596)
		(end 182.142384 -16.375126)
		(width 0.10668)
		(layer "F.Cu")
		(net "SMB_OCP_SFF_3V3AUX_SDA_R0")
	)
	(via
		(at 182.731664 -18.805144)
		(size 0.508)
		(drill 0.254)
		(layers "F.Cu" "B.Cu")
		(net "SMB_OCP_SFF_3V3AUX_SDA_R0")
	)
	(segment
		(start 182.88254 -19.978116)
		(end 182.88254 -18.95602)
		(width 0.10668)
		(layer "B.Cu")
		(net "SMB_OCP_SFF_3V3AUX_SDA_R0")
	)
	(segment
		(start 182.88254 -18.95602)
		(end 182.731664 -18.805144)
		(width 0.10668)
		(layer "B.Cu")
		(net "SMB_OCP_SFF_3V3AUX_SDA_R0")
	)
	(segment
		(start 405.012398 -75.738228)
		(end 404.236936 -75.738228)
		(width 0.10668)
		(layer "F.Cu")
		(net "SMB_OCP_SFF_3V3AUX_SDA")
	)
	(segment
		(start 401.95373 -49.429416)
		(end 383.577592 -49.429416)
		(width 0.10668)
		(layer "F.Cu")
		(net "SMB_OCP_SFF_3V3AUX_SDA")
	)
	(segment
		(start 383.577592 -49.429416)
		(end 383.225802 -49.781206)
		(width 0.10668)
		(layer "F.Cu")
		(net "SMB_OCP_SFF_3V3AUX_SDA")
	)
	(segment
		(start 403.679914 -74.236326)
		(end 408.268932 -69.647308)
		(width 0.10668)
		(layer "F.Cu")
		(net "SMB_OCP_SFF_3V3AUX_SDA")
	)
	(segment
		(start 280.95448 -49.781206)
		(end 273.103086 -41.929812)
		(width 0.10668)
		(layer "F.Cu")
		(net "SMB_OCP_SFF_3V3AUX_SDA")
	)
	(segment
		(start 408.268932 -69.647308)
		(end 408.268932 -55.744618)
		(width 0.10668)
		(layer "F.Cu")
		(net "SMB_OCP_SFF_3V3AUX_SDA")
	)
	(segment
		(start 408.268932 -55.744618)
		(end 401.95373 -49.429416)
		(width 0.10668)
		(layer "F.Cu")
		(net "SMB_OCP_SFF_3V3AUX_SDA")
	)
	(segment
		(start 404.236936 -75.738228)
		(end 403.679914 -75.181206)
		(width 0.10668)
		(layer "F.Cu")
		(net "SMB_OCP_SFF_3V3AUX_SDA")
	)
	(segment
		(start 273.103086 -41.929812)
		(end 270.822674 -41.929812)
		(width 0.10668)
		(layer "F.Cu")
		(net "SMB_OCP_SFF_3V3AUX_SDA")
	)
	(segment
		(start 403.679914 -75.181206)
		(end 403.679914 -74.236326)
		(width 0.10668)
		(layer "F.Cu")
		(net "SMB_OCP_SFF_3V3AUX_SDA")
	)
	(segment
		(start 383.225802 -49.781206)
		(end 280.95448 -49.781206)
		(width 0.10668)
		(layer "F.Cu")
		(net "SMB_OCP_SFF_3V3AUX_SDA")
	)
	(via
		(at 270.822674 -41.929812)
		(size 0.508)
		(drill 0.254)
		(layers "F.Cu" "B.Cu")
		(net "SMB_OCP_SFF_3V3AUX_SDA")
	)
	(via
		(at 182.884064 -22.085808)
		(size 0.508)
		(drill 0.254)
		(layers "F.Cu" "B.Cu")
		(net "SMB_OCP_SFF_3V3AUX_SDA")
	)
	(segment
		(start 182.541164 -22.428708)
		(end 182.541164 -23.255732)
		(width 0.10668)
		(layer "B.Cu")
		(net "SMB_OCP_SFF_3V3AUX_SDA")
	)
	(segment
		(start 182.88254 -20.778216)
		(end 182.884064 -20.77974)
		(width 0.10668)
		(layer "B.Cu")
		(net "SMB_OCP_SFF_3V3AUX_SDA")
	)
	(segment
		(start 182.884064 -22.085808)
		(end 182.541164 -22.428708)
		(width 0.10668)
		(layer "B.Cu")
		(net "SMB_OCP_SFF_3V3AUX_SDA")
	)
	(segment
		(start 182.884064 -20.77974)
		(end 182.884064 -22.085808)
		(width 0.10668)
		(layer "B.Cu")
		(net "SMB_OCP_SFF_3V3AUX_SDA")
	)
	(segment
		(start 242.125754 -42.90314)
		(end 235.390182 -42.90314)
		(width 0.11684)
		(layer "In6.Cu")
		(net "SMB_OCP_SFF_3V3AUX_SDA")
	)
	(segment
		(start 266.576556 -43.161458)
		(end 266.576556 -42.45102)
		(width 0.11684)
		(layer "In6.Cu")
		(net "SMB_OCP_SFF_3V3AUX_SDA")
	)
	(segment
		(start 233.809794 -41.322752)
		(end 232.131362 -41.322752)
		(width 0.11684)
		(layer "In6.Cu")
		(net "SMB_OCP_SFF_3V3AUX_SDA")
	)
	(segment
		(start 264.455656 -43.161458)
		(end 264.338816 -43.278298)
		(width 0.11684)
		(layer "In6.Cu")
		(net "SMB_OCP_SFF_3V3AUX_SDA")
	)
	(segment
		(start 266.152376 -43.161458)
		(end 266.035536 -43.278298)
		(width 0.11684)
		(layer "In6.Cu")
		(net "SMB_OCP_SFF_3V3AUX_SDA")
	)
	(segment
		(start 251.567188 -40.808656)
		(end 248.280936 -44.094908)
		(width 0.11684)
		(layer "In6.Cu")
		(net "SMB_OCP_SFF_3V3AUX_SDA")
	)
	(segment
		(start 264.879836 -42.45102)
		(end 264.762996 -42.33418)
		(width 0.11684)
		(layer "In6.Cu")
		(net "SMB_OCP_SFF_3V3AUX_SDA")
	)
	(segment
		(start 266.693396 -43.278298)
		(end 266.576556 -43.161458)
		(width 0.11684)
		(layer "In6.Cu")
		(net "SMB_OCP_SFF_3V3AUX_SDA")
	)
	(segment
		(start 265.187176 -43.278298)
		(end 264.996676 -43.278298)
		(width 0.11684)
		(layer "In6.Cu")
		(net "SMB_OCP_SFF_3V3AUX_SDA")
	)
	(segment
		(start 264.455656 -42.45102)
		(end 264.455656 -43.161458)
		(width 0.11684)
		(layer "In6.Cu")
		(net "SMB_OCP_SFF_3V3AUX_SDA")
	)
	(segment
		(start 265.611356 -42.33418)
		(end 265.420856 -42.33418)
		(width 0.11684)
		(layer "In6.Cu")
		(net "SMB_OCP_SFF_3V3AUX_SDA")
	)
	(segment
		(start 265.728196 -43.161458)
		(end 265.728196 -42.45102)
		(width 0.11684)
		(layer "In6.Cu")
		(net "SMB_OCP_SFF_3V3AUX_SDA")
	)
	(segment
		(start 268.786864 -43.278298)
		(end 266.693396 -43.278298)
		(width 0.11684)
		(layer "In6.Cu")
		(net "SMB_OCP_SFF_3V3AUX_SDA")
	)
	(segment
		(start 231.111298 -40.302688)
		(end 222.798132 -40.302688)
		(width 0.11684)
		(layer "In6.Cu")
		(net "SMB_OCP_SFF_3V3AUX_SDA")
	)
	(segment
		(start 260.960616 -40.808656)
		(end 251.567188 -40.808656)
		(width 0.11684)
		(layer "In6.Cu")
		(net "SMB_OCP_SFF_3V3AUX_SDA")
	)
	(segment
		(start 191.931544 -35.409632)
		(end 183.26608 -26.744168)
		(width 0.11684)
		(layer "In6.Cu")
		(net "SMB_OCP_SFF_3V3AUX_SDA")
	)
	(segment
		(start 265.304016 -43.161458)
		(end 265.187176 -43.278298)
		(width 0.11684)
		(layer "In6.Cu")
		(net "SMB_OCP_SFF_3V3AUX_SDA")
	)
	(segment
		(start 222.798132 -40.302688)
		(end 219.19057 -36.695126)
		(width 0.11684)
		(layer "In6.Cu")
		(net "SMB_OCP_SFF_3V3AUX_SDA")
	)
	(segment
		(start 205.098142 -35.409632)
		(end 191.931544 -35.409632)
		(width 0.11684)
		(layer "In6.Cu")
		(net "SMB_OCP_SFF_3V3AUX_SDA")
	)
	(segment
		(start 266.576556 -42.45102)
		(end 266.459716 -42.33418)
		(width 0.11684)
		(layer "In6.Cu")
		(net "SMB_OCP_SFF_3V3AUX_SDA")
	)
	(segment
		(start 270.13535 -41.929812)
		(end 268.786864 -43.278298)
		(width 0.11684)
		(layer "In6.Cu")
		(net "SMB_OCP_SFF_3V3AUX_SDA")
	)
	(segment
		(start 266.152376 -42.45102)
		(end 266.152376 -43.161458)
		(width 0.11684)
		(layer "In6.Cu")
		(net "SMB_OCP_SFF_3V3AUX_SDA")
	)
	(segment
		(start 264.996676 -43.278298)
		(end 264.879836 -43.161458)
		(width 0.11684)
		(layer "In6.Cu")
		(net "SMB_OCP_SFF_3V3AUX_SDA")
	)
	(segment
		(start 219.19057 -36.695126)
		(end 219.19057 -32.827976)
		(width 0.11684)
		(layer "In6.Cu")
		(net "SMB_OCP_SFF_3V3AUX_SDA")
	)
	(segment
		(start 264.879836 -43.161458)
		(end 264.879836 -42.45102)
		(width 0.11684)
		(layer "In6.Cu")
		(net "SMB_OCP_SFF_3V3AUX_SDA")
	)
	(segment
		(start 183.26608 -22.467824)
		(end 182.884064 -22.085808)
		(width 0.11684)
		(layer "In6.Cu")
		(net "SMB_OCP_SFF_3V3AUX_SDA")
	)
	(segment
		(start 218.322652 -31.960058)
		(end 208.547716 -31.960058)
		(width 0.11684)
		(layer "In6.Cu")
		(net "SMB_OCP_SFF_3V3AUX_SDA")
	)
	(segment
		(start 265.845036 -43.278298)
		(end 265.728196 -43.161458)
		(width 0.11684)
		(layer "In6.Cu")
		(net "SMB_OCP_SFF_3V3AUX_SDA")
	)
	(segment
		(start 183.26608 -26.744168)
		(end 183.26608 -22.467824)
		(width 0.11684)
		(layer "In6.Cu")
		(net "SMB_OCP_SFF_3V3AUX_SDA")
	)
	(segment
		(start 270.822674 -41.929812)
		(end 270.13535 -41.929812)
		(width 0.11684)
		(layer "In6.Cu")
		(net "SMB_OCP_SFF_3V3AUX_SDA")
	)
	(segment
		(start 243.317522 -44.094908)
		(end 242.125754 -42.90314)
		(width 0.11684)
		(layer "In6.Cu")
		(net "SMB_OCP_SFF_3V3AUX_SDA")
	)
	(segment
		(start 265.728196 -42.45102)
		(end 265.611356 -42.33418)
		(width 0.11684)
		(layer "In6.Cu")
		(net "SMB_OCP_SFF_3V3AUX_SDA")
	)
	(segment
		(start 266.269216 -42.33418)
		(end 266.152376 -42.45102)
		(width 0.11684)
		(layer "In6.Cu")
		(net "SMB_OCP_SFF_3V3AUX_SDA")
	)
	(segment
		(start 266.459716 -42.33418)
		(end 266.269216 -42.33418)
		(width 0.11684)
		(layer "In6.Cu")
		(net "SMB_OCP_SFF_3V3AUX_SDA")
	)
	(segment
		(start 232.131362 -41.322752)
		(end 231.111298 -40.302688)
		(width 0.11684)
		(layer "In6.Cu")
		(net "SMB_OCP_SFF_3V3AUX_SDA")
	)
	(segment
		(start 264.762996 -42.33418)
		(end 264.572496 -42.33418)
		(width 0.11684)
		(layer "In6.Cu")
		(net "SMB_OCP_SFF_3V3AUX_SDA")
	)
	(segment
		(start 248.280936 -44.094908)
		(end 243.317522 -44.094908)
		(width 0.11684)
		(layer "In6.Cu")
		(net "SMB_OCP_SFF_3V3AUX_SDA")
	)
	(segment
		(start 263.430258 -43.278298)
		(end 260.960616 -40.808656)
		(width 0.11684)
		(layer "In6.Cu")
		(net "SMB_OCP_SFF_3V3AUX_SDA")
	)
	(segment
		(start 265.304016 -42.45102)
		(end 265.304016 -43.161458)
		(width 0.11684)
		(layer "In6.Cu")
		(net "SMB_OCP_SFF_3V3AUX_SDA")
	)
	(segment
		(start 219.19057 -32.827976)
		(end 218.322652 -31.960058)
		(width 0.11684)
		(layer "In6.Cu")
		(net "SMB_OCP_SFF_3V3AUX_SDA")
	)
	(segment
		(start 208.547716 -31.960058)
		(end 205.098142 -35.409632)
		(width 0.11684)
		(layer "In6.Cu")
		(net "SMB_OCP_SFF_3V3AUX_SDA")
	)
	(segment
		(start 265.420856 -42.33418)
		(end 265.304016 -42.45102)
		(width 0.11684)
		(layer "In6.Cu")
		(net "SMB_OCP_SFF_3V3AUX_SDA")
	)
	(segment
		(start 264.338816 -43.278298)
		(end 263.430258 -43.278298)
		(width 0.11684)
		(layer "In6.Cu")
		(net "SMB_OCP_SFF_3V3AUX_SDA")
	)
	(segment
		(start 266.035536 -43.278298)
		(end 265.845036 -43.278298)
		(width 0.11684)
		(layer "In6.Cu")
		(net "SMB_OCP_SFF_3V3AUX_SDA")
	)
	(segment
		(start 264.572496 -42.33418)
		(end 264.455656 -42.45102)
		(width 0.11684)
		(layer "In6.Cu")
		(net "SMB_OCP_SFF_3V3AUX_SDA")
	)
	(segment
		(start 235.390182 -42.90314)
		(end 233.809794 -41.322752)
		(width 0.11684)
		(layer "In6.Cu")
		(net "SMB_OCP_SFF_3V3AUX_SDA")
	)
	(segment
		(start 182.665116 -16.297402)
		(end 182.665116 -17.337532)
		(width 0.10668)
		(layer "F.Cu")
		(net "SMB_OCP_SFF_3V3AUX_SCL_R0")
	)
	(segment
		(start 178.867054 -14.111986)
		(end 179.189888 -14.43482)
		(width 0.10668)
		(layer "F.Cu")
		(net "SMB_OCP_SFF_3V3AUX_SCL_R0")
	)
	(segment
		(start 182.665116 -17.337532)
		(end 182.731664 -17.40408)
		(width 0.10668)
		(layer "F.Cu")
		(net "SMB_OCP_SFF_3V3AUX_SCL_R0")
	)
	(segment
		(start 180.802534 -14.43482)
		(end 182.665116 -16.297402)
		(width 0.10668)
		(layer "F.Cu")
		(net "SMB_OCP_SFF_3V3AUX_SCL_R0")
	)
	(segment
		(start 182.731664 -17.40408)
		(end 182.731664 -17.459452)
		(width 0.10668)
		(layer "F.Cu")
		(net "SMB_OCP_SFF_3V3AUX_SCL_R0")
	)
	(segment
		(start 178.867054 -13.599922)
		(end 178.867054 -14.111986)
		(width 0.10668)
		(layer "F.Cu")
		(net "SMB_OCP_SFF_3V3AUX_SCL_R0")
	)
	(segment
		(start 179.189888 -14.43482)
		(end 180.802534 -14.43482)
		(width 0.10668)
		(layer "F.Cu")
		(net "SMB_OCP_SFF_3V3AUX_SCL_R0")
	)
	(via
		(at 182.731664 -17.459452)
		(size 0.508)
		(drill 0.254)
		(layers "F.Cu" "B.Cu")
		(net "SMB_OCP_SFF_3V3AUX_SCL_R0")
	)
	(segment
		(start 183.896 -18.568416)
		(end 182.787036 -17.459452)
		(width 0.10668)
		(layer "B.Cu")
		(net "SMB_OCP_SFF_3V3AUX_SCL_R0")
	)
	(segment
		(start 183.896 -19.978116)
		(end 183.896 -18.568416)
		(width 0.10668)
		(layer "B.Cu")
		(net "SMB_OCP_SFF_3V3AUX_SCL_R0")
	)
	(segment
		(start 182.787036 -17.459452)
		(end 182.731664 -17.459452)
		(width 0.10668)
		(layer "B.Cu")
		(net "SMB_OCP_SFF_3V3AUX_SCL_R0")
	)
	(segment
		(start 280.97099 -50.364644)
		(end 273.171158 -42.564812)
		(width 0.10668)
		(layer "F.Cu")
		(net "SMB_OCP_SFF_3V3AUX_SCL")
	)
	(segment
		(start 407.86812 -55.910734)
		(end 401.787614 -49.830228)
		(width 0.10668)
		(layer "F.Cu")
		(net "SMB_OCP_SFF_3V3AUX_SCL")
	)
	(segment
		(start 403.279102 -75.347322)
		(end 403.279102 -74.07021)
		(width 0.10668)
		(layer "F.Cu")
		(net "SMB_OCP_SFF_3V3AUX_SCL")
	)
	(segment
		(start 407.86812 -69.481192)
		(end 407.86812 -55.910734)
		(width 0.10668)
		(layer "F.Cu")
		(net "SMB_OCP_SFF_3V3AUX_SCL")
	)
	(segment
		(start 401.787614 -49.830228)
		(end 383.743708 -49.830228)
		(width 0.10668)
		(layer "F.Cu")
		(net "SMB_OCP_SFF_3V3AUX_SCL")
	)
	(segment
		(start 403.279102 -74.07021)
		(end 407.86812 -69.481192)
		(width 0.10668)
		(layer "F.Cu")
		(net "SMB_OCP_SFF_3V3AUX_SCL")
	)
	(segment
		(start 405.012398 -76.388468)
		(end 404.320248 -76.388468)
		(width 0.10668)
		(layer "F.Cu")
		(net "SMB_OCP_SFF_3V3AUX_SCL")
	)
	(segment
		(start 404.320248 -76.388468)
		(end 403.279102 -75.347322)
		(width 0.10668)
		(layer "F.Cu")
		(net "SMB_OCP_SFF_3V3AUX_SCL")
	)
	(segment
		(start 383.743708 -49.830228)
		(end 383.209292 -50.364644)
		(width 0.10668)
		(layer "F.Cu")
		(net "SMB_OCP_SFF_3V3AUX_SCL")
	)
	(segment
		(start 273.171158 -42.564812)
		(end 270.822674 -42.564812)
		(width 0.10668)
		(layer "F.Cu")
		(net "SMB_OCP_SFF_3V3AUX_SCL")
	)
	(segment
		(start 383.209292 -50.364644)
		(end 280.97099 -50.364644)
		(width 0.10668)
		(layer "F.Cu")
		(net "SMB_OCP_SFF_3V3AUX_SCL")
	)
	(via
		(at 270.822674 -42.564812)
		(size 0.508)
		(drill 0.254)
		(layers "F.Cu" "B.Cu")
		(net "SMB_OCP_SFF_3V3AUX_SCL")
	)
	(via
		(at 184.154064 -22.085808)
		(size 0.508)
		(drill 0.254)
		(layers "F.Cu" "B.Cu")
		(net "SMB_OCP_SFF_3V3AUX_SCL")
	)
	(segment
		(start 183.557164 -22.682708)
		(end 183.557164 -23.255732)
		(width 0.10668)
		(layer "B.Cu")
		(net "SMB_OCP_SFF_3V3AUX_SCL")
	)
	(segment
		(start 184.154064 -21.03628)
		(end 184.154064 -22.085808)
		(width 0.10668)
		(layer "B.Cu")
		(net "SMB_OCP_SFF_3V3AUX_SCL")
	)
	(segment
		(start 184.154064 -22.085808)
		(end 183.557164 -22.682708)
		(width 0.10668)
		(layer "B.Cu")
		(net "SMB_OCP_SFF_3V3AUX_SCL")
	)
	(segment
		(start 183.896 -20.778216)
		(end 184.154064 -21.03628)
		(width 0.10668)
		(layer "B.Cu")
		(net "SMB_OCP_SFF_3V3AUX_SCL")
	)
	(segment
		(start 230.936546 -40.724328)
		(end 222.62338 -40.724328)
		(width 0.11684)
		(layer "In6.Cu")
		(net "SMB_OCP_SFF_3V3AUX_SCL")
	)
	(segment
		(start 235.21543 -43.32478)
		(end 233.635042 -41.744392)
		(width 0.11684)
		(layer "In6.Cu")
		(net "SMB_OCP_SFF_3V3AUX_SCL")
	)
	(segment
		(start 205.272894 -35.831272)
		(end 190.875412 -35.831272)
		(width 0.11684)
		(layer "In6.Cu")
		(net "SMB_OCP_SFF_3V3AUX_SCL")
	)
	(segment
		(start 182.320438 -21.55571)
		(end 182.546752 -21.329396)
		(width 0.11684)
		(layer "In6.Cu")
		(net "SMB_OCP_SFF_3V3AUX_SCL")
	)
	(segment
		(start 218.76893 -36.869878)
		(end 218.76893 -33.002728)
		(width 0.11684)
		(layer "In6.Cu")
		(net "SMB_OCP_SFF_3V3AUX_SCL")
	)
	(segment
		(start 231.95661 -41.744392)
		(end 230.936546 -40.724328)
		(width 0.11684)
		(layer "In6.Cu")
		(net "SMB_OCP_SFF_3V3AUX_SCL")
	)
	(segment
		(start 243.14277 -44.516548)
		(end 241.951002 -43.32478)
		(width 0.11684)
		(layer "In6.Cu")
		(net "SMB_OCP_SFF_3V3AUX_SCL")
	)
	(segment
		(start 218.76893 -33.002728)
		(end 218.1479 -32.381698)
		(width 0.11684)
		(layer "In6.Cu")
		(net "SMB_OCP_SFF_3V3AUX_SCL")
	)
	(segment
		(start 270.822674 -42.564812)
		(end 270.096742 -42.564812)
		(width 0.11684)
		(layer "In6.Cu")
		(net "SMB_OCP_SFF_3V3AUX_SCL")
	)
	(segment
		(start 182.84444 -23.179024)
		(end 182.320438 -22.655022)
		(width 0.11684)
		(layer "In6.Cu")
		(net "SMB_OCP_SFF_3V3AUX_SCL")
	)
	(segment
		(start 270.096742 -42.564812)
		(end 268.961616 -43.699938)
		(width 0.11684)
		(layer "In6.Cu")
		(net "SMB_OCP_SFF_3V3AUX_SCL")
	)
	(segment
		(start 252.363732 -42.806366)
		(end 251.43714 -41.879774)
		(width 0.11684)
		(layer "In6.Cu")
		(net "SMB_OCP_SFF_3V3AUX_SCL")
	)
	(segment
		(start 190.875412 -35.831272)
		(end 182.84444 -27.8003)
		(width 0.11684)
		(layer "In6.Cu")
		(net "SMB_OCP_SFF_3V3AUX_SCL")
	)
	(segment
		(start 251.092462 -41.879774)
		(end 248.455688 -44.516548)
		(width 0.11684)
		(layer "In6.Cu")
		(net "SMB_OCP_SFF_3V3AUX_SCL")
	)
	(segment
		(start 182.320438 -22.655022)
		(end 182.320438 -21.55571)
		(width 0.11684)
		(layer "In6.Cu")
		(net "SMB_OCP_SFF_3V3AUX_SCL")
	)
	(segment
		(start 208.722468 -32.381698)
		(end 205.272894 -35.831272)
		(width 0.11684)
		(layer "In6.Cu")
		(net "SMB_OCP_SFF_3V3AUX_SCL")
	)
	(segment
		(start 233.635042 -41.744392)
		(end 231.95661 -41.744392)
		(width 0.11684)
		(layer "In6.Cu")
		(net "SMB_OCP_SFF_3V3AUX_SCL")
	)
	(segment
		(start 183.397652 -21.329396)
		(end 184.154064 -22.085808)
		(width 0.11684)
		(layer "In6.Cu")
		(net "SMB_OCP_SFF_3V3AUX_SCL")
	)
	(segment
		(start 182.546752 -21.329396)
		(end 183.397652 -21.329396)
		(width 0.11684)
		(layer "In6.Cu")
		(net "SMB_OCP_SFF_3V3AUX_SCL")
	)
	(segment
		(start 182.84444 -27.8003)
		(end 182.84444 -23.179024)
		(width 0.11684)
		(layer "In6.Cu")
		(net "SMB_OCP_SFF_3V3AUX_SCL")
	)
	(segment
		(start 268.961616 -43.699938)
		(end 263.255506 -43.699938)
		(width 0.11684)
		(layer "In6.Cu")
		(net "SMB_OCP_SFF_3V3AUX_SCL")
	)
	(segment
		(start 248.455688 -44.516548)
		(end 243.14277 -44.516548)
		(width 0.11684)
		(layer "In6.Cu")
		(net "SMB_OCP_SFF_3V3AUX_SCL")
	)
	(segment
		(start 263.255506 -43.699938)
		(end 262.361934 -42.806366)
		(width 0.11684)
		(layer "In6.Cu")
		(net "SMB_OCP_SFF_3V3AUX_SCL")
	)
	(segment
		(start 251.43714 -41.879774)
		(end 251.092462 -41.879774)
		(width 0.11684)
		(layer "In6.Cu")
		(net "SMB_OCP_SFF_3V3AUX_SCL")
	)
	(segment
		(start 241.951002 -43.32478)
		(end 235.21543 -43.32478)
		(width 0.11684)
		(layer "In6.Cu")
		(net "SMB_OCP_SFF_3V3AUX_SCL")
	)
	(segment
		(start 222.62338 -40.724328)
		(end 218.76893 -36.869878)
		(width 0.11684)
		(layer "In6.Cu")
		(net "SMB_OCP_SFF_3V3AUX_SCL")
	)
	(segment
		(start 262.361934 -42.806366)
		(end 252.363732 -42.806366)
		(width 0.11684)
		(layer "In6.Cu")
		(net "SMB_OCP_SFF_3V3AUX_SCL")
	)
	(segment
		(start 218.1479 -32.381698)
		(end 208.722468 -32.381698)
		(width 0.11684)
		(layer "In6.Cu")
		(net "SMB_OCP_SFF_3V3AUX_SCL")
	)
	(segment
		(start 410.208222 -75.738228)
		(end 409.362402 -75.738228)
		(width 0.10668)
		(layer "F.Cu")
		(net "SMB_OCP_SFF_3V3AUX_BUF_SDA")
	)
	(segment
		(start 411.456886 -74.610468)
		(end 411.335982 -74.610468)
		(width 0.10668)
		(layer "F.Cu")
		(net "SMB_OCP_SFF_3V3AUX_BUF_SDA")
	)
	(segment
		(start 412.072836 -74.864468)
		(end 411.710886 -74.864468)
		(width 0.10668)
		(layer "F.Cu")
		(net "SMB_OCP_SFF_3V3AUX_BUF_SDA")
	)
	(segment
		(start 411.710886 -74.864468)
		(end 411.456886 -74.610468)
		(width 0.10668)
		(layer "F.Cu")
		(net "SMB_OCP_SFF_3V3AUX_BUF_SDA")
	)
	(segment
		(start 412.072836 -74.864468)
		(end 412.072836 -73.848468)
		(width 0.10668)
		(layer "F.Cu")
		(net "SMB_OCP_SFF_3V3AUX_BUF_SDA")
	)
	(segment
		(start 411.335982 -74.610468)
		(end 410.208222 -75.738228)
		(width 0.10668)
		(layer "F.Cu")
		(net "SMB_OCP_SFF_3V3AUX_BUF_SDA")
	)
	(via
		(at 411.456886 -74.610468)
		(size 0.508)
		(drill 0.254)
		(layers "F.Cu" "B.Cu")
		(net "SMB_OCP_SFF_3V3AUX_BUF_SDA")
	)
	(segment
		(start 412.072836 -75.880468)
		(end 411.456886 -75.880468)
		(width 0.10668)
		(layer "F.Cu")
		(net "SMB_OCP_SFF_3V3AUX_BUF_SCL")
	)
	(segment
		(start 412.072836 -75.880468)
		(end 412.072836 -76.896468)
		(width 0.10668)
		(layer "F.Cu")
		(net "SMB_OCP_SFF_3V3AUX_BUF_SCL")
	)
	(segment
		(start 410.2735 -76.388468)
		(end 409.362402 -76.388468)
		(width 0.10668)
		(layer "F.Cu")
		(net "SMB_OCP_SFF_3V3AUX_BUF_SCL")
	)
	(segment
		(start 411.456886 -75.880468)
		(end 410.7815 -75.880468)
		(width 0.10668)
		(layer "F.Cu")
		(net "SMB_OCP_SFF_3V3AUX_BUF_SCL")
	)
	(segment
		(start 410.7815 -75.880468)
		(end 410.2735 -76.388468)
		(width 0.10668)
		(layer "F.Cu")
		(net "SMB_OCP_SFF_3V3AUX_BUF_SCL")
	)
	(via
		(at 411.456886 -75.880468)
		(size 0.508)
		(drill 0.254)
		(layers "F.Cu" "B.Cu")
		(net "SMB_OCP_SFF_3V3AUX_BUF_SCL")
	)
	(segment
		(start 436.13197 -8.285226)
		(end 436.13197 -6.580632)
		(width 0.10668)
		(layer "F.Cu")
		(net "SMB_OCP_SFF_3V3AUX_BUF_R_SDA")
	)
	(segment
		(start 436.166768 -8.320024)
		(end 436.13197 -8.285226)
		(width 0.10668)
		(layer "F.Cu")
		(net "SMB_OCP_SFF_3V3AUX_BUF_R_SDA")
	)
	(segment
		(start 412.872936 -73.848468)
		(end 413.488886 -73.848468)
		(width 0.10668)
		(layer "F.Cu")
		(net "SMB_OCP_SFF_3V3AUX_BUF_R_SDA")
	)
	(via
		(at 436.13197 -6.580632)
		(size 0.508)
		(drill 0.254)
		(layers "F.Cu" "B.Cu")
		(net "SMB_OCP_SFF_3V3AUX_BUF_R_SDA")
	)
	(via
		(at 413.488886 -73.848468)
		(size 0.508)
		(drill 0.254)
		(layers "F.Cu" "B.Cu")
		(net "SMB_OCP_SFF_3V3AUX_BUF_R_SDA")
	)
	(segment
		(start 431.225452 -24.158702)
		(end 431.225452 -42.345356)
		(width 0.11684)
		(layer "In11.Cu")
		(net "SMB_OCP_SFF_3V3AUX_BUF_R_SDA")
	)
	(segment
		(start 431.225452 -42.345356)
		(end 430.008538 -43.56227)
		(width 0.11684)
		(layer "In11.Cu")
		(net "SMB_OCP_SFF_3V3AUX_BUF_R_SDA")
	)
	(segment
		(start 425.448984 -43.56227)
		(end 411.456886 -57.554368)
		(width 0.11684)
		(layer "In11.Cu")
		(net "SMB_OCP_SFF_3V3AUX_BUF_R_SDA")
	)
	(segment
		(start 434.580284 -14.853158)
		(end 434.580284 -20.113752)
		(width 0.11684)
		(layer "In11.Cu")
		(net "SMB_OCP_SFF_3V3AUX_BUF_R_SDA")
	)
	(segment
		(start 433.935632 -20.758404)
		(end 433.935632 -21.448522)
		(width 0.11684)
		(layer "In11.Cu")
		(net "SMB_OCP_SFF_3V3AUX_BUF_R_SDA")
	)
	(segment
		(start 430.008538 -43.56227)
		(end 425.448984 -43.56227)
		(width 0.11684)
		(layer "In11.Cu")
		(net "SMB_OCP_SFF_3V3AUX_BUF_R_SDA")
	)
	(segment
		(start 411.456886 -71.816468)
		(end 413.488886 -73.848468)
		(width 0.11684)
		(layer "In11.Cu")
		(net "SMB_OCP_SFF_3V3AUX_BUF_R_SDA")
	)
	(segment
		(start 436.13197 -6.580632)
		(end 436.13197 -13.301472)
		(width 0.11684)
		(layer "In11.Cu")
		(net "SMB_OCP_SFF_3V3AUX_BUF_R_SDA")
	)
	(segment
		(start 436.13197 -13.301472)
		(end 434.580284 -14.853158)
		(width 0.11684)
		(layer "In11.Cu")
		(net "SMB_OCP_SFF_3V3AUX_BUF_R_SDA")
	)
	(segment
		(start 434.580284 -20.113752)
		(end 433.935632 -20.758404)
		(width 0.11684)
		(layer "In11.Cu")
		(net "SMB_OCP_SFF_3V3AUX_BUF_R_SDA")
	)
	(segment
		(start 433.935632 -21.448522)
		(end 431.225452 -24.158702)
		(width 0.11684)
		(layer "In11.Cu")
		(net "SMB_OCP_SFF_3V3AUX_BUF_R_SDA")
	)
	(segment
		(start 411.456886 -57.554368)
		(end 411.456886 -71.816468)
		(width 0.11684)
		(layer "In11.Cu")
		(net "SMB_OCP_SFF_3V3AUX_BUF_R_SDA")
	)
	(segment
		(start 412.872936 -76.896468)
		(end 413.488886 -76.896468)
		(width 0.10668)
		(layer "F.Cu")
		(net "SMB_OCP_SFF_3V3AUX_BUF_R_SCL")
	)
	(segment
		(start 436.76697 -8.320024)
		(end 436.76697 -7.223252)
		(width 0.10668)
		(layer "F.Cu")
		(net "SMB_OCP_SFF_3V3AUX_BUF_R_SCL")
	)
	(segment
		(start 436.76697 -7.223252)
		(end 437.40959 -6.580632)
		(width 0.10668)
		(layer "F.Cu")
		(net "SMB_OCP_SFF_3V3AUX_BUF_R_SCL")
	)
	(via
		(at 413.488886 -76.896468)
		(size 0.508)
		(drill 0.254)
		(layers "F.Cu" "B.Cu")
		(net "SMB_OCP_SFF_3V3AUX_BUF_R_SCL")
	)
	(via
		(at 437.40959 -6.580632)
		(size 0.508)
		(drill 0.254)
		(layers "F.Cu" "B.Cu")
		(net "SMB_OCP_SFF_3V3AUX_BUF_R_SCL")
	)
	(segment
		(start 435.029864 -15.000224)
		(end 435.029864 -21.073872)
		(width 0.11684)
		(layer "In11.Cu")
		(net "SMB_OCP_SFF_3V3AUX_BUF_R_SCL")
	)
	(segment
		(start 436.6514 -7.338822)
		(end 436.6514 -13.378688)
		(width 0.11684)
		(layer "In11.Cu")
		(net "SMB_OCP_SFF_3V3AUX_BUF_R_SCL")
	)
	(segment
		(start 431.734214 -42.43324)
		(end 430.096422 -44.071032)
		(width 0.11684)
		(layer "In11.Cu")
		(net "SMB_OCP_SFF_3V3AUX_BUF_R_SCL")
	)
	(segment
		(start 431.734214 -24.369522)
		(end 431.734214 -42.43324)
		(width 0.11684)
		(layer "In11.Cu")
		(net "SMB_OCP_SFF_3V3AUX_BUF_R_SCL")
	)
	(segment
		(start 437.40959 -6.580632)
		(end 436.6514 -7.338822)
		(width 0.11684)
		(layer "In11.Cu")
		(net "SMB_OCP_SFF_3V3AUX_BUF_R_SCL")
	)
	(segment
		(start 414.18002 -76.205334)
		(end 413.488886 -76.896468)
		(width 0.11684)
		(layer "In11.Cu")
		(net "SMB_OCP_SFF_3V3AUX_BUF_R_SCL")
	)
	(segment
		(start 435.029864 -21.073872)
		(end 431.734214 -24.369522)
		(width 0.11684)
		(layer "In11.Cu")
		(net "SMB_OCP_SFF_3V3AUX_BUF_R_SCL")
	)
	(segment
		(start 414.18002 -71.677276)
		(end 414.18002 -76.205334)
		(width 0.11684)
		(layer "In11.Cu")
		(net "SMB_OCP_SFF_3V3AUX_BUF_R_SCL")
	)
	(segment
		(start 411.921706 -69.418962)
		(end 414.18002 -71.677276)
		(width 0.11684)
		(layer "In11.Cu")
		(net "SMB_OCP_SFF_3V3AUX_BUF_R_SCL")
	)
	(segment
		(start 411.921706 -57.686194)
		(end 411.921706 -69.418962)
		(width 0.11684)
		(layer "In11.Cu")
		(net "SMB_OCP_SFF_3V3AUX_BUF_R_SCL")
	)
	(segment
		(start 425.536868 -44.071032)
		(end 411.921706 -57.686194)
		(width 0.11684)
		(layer "In11.Cu")
		(net "SMB_OCP_SFF_3V3AUX_BUF_R_SCL")
	)
	(segment
		(start 436.6514 -13.378688)
		(end 435.029864 -15.000224)
		(width 0.11684)
		(layer "In11.Cu")
		(net "SMB_OCP_SFF_3V3AUX_BUF_R_SCL")
	)
	(segment
		(start 430.096422 -44.071032)
		(end 425.536868 -44.071032)
		(width 0.11684)
		(layer "In11.Cu")
		(net "SMB_OCP_SFF_3V3AUX_BUF_R_SCL")
	)
	(segment
		(start 147.054316 -42.349928)
		(end 146.704812 -42.000424)
		(width 0.10668)
		(layer "F.Cu")
		(net "SMB_M2_P1_1V8AUX_SDA_R")
	)
	(segment
		(start 149.041612 -41.746424)
		(end 149.657562 -41.746424)
		(width 0.10668)
		(layer "F.Cu")
		(net "SMB_M2_P1_1V8AUX_SDA_R")
	)
	(segment
		(start 149.041612 -42.000424)
		(end 148.692108 -42.349928)
		(width 0.10668)
		(layer "F.Cu")
		(net "SMB_M2_P1_1V8AUX_SDA_R")
	)
	(segment
		(start 151.181562 -42.635424)
		(end 150.546562 -42.635424)
		(width 0.10668)
		(layer "F.Cu")
		(net "SMB_M2_P1_1V8AUX_SDA_R")
	)
	(segment
		(start 150.546562 -42.635424)
		(end 149.657562 -41.746424)
		(width 0.10668)
		(layer "F.Cu")
		(net "SMB_M2_P1_1V8AUX_SDA_R")
	)
	(segment
		(start 149.041612 -41.746424)
		(end 149.041612 -42.000424)
		(width 0.10668)
		(layer "F.Cu")
		(net "SMB_M2_P1_1V8AUX_SDA_R")
	)
	(segment
		(start 146.704812 -42.000424)
		(end 146.704812 -41.746424)
		(width 0.10668)
		(layer "F.Cu")
		(net "SMB_M2_P1_1V8AUX_SDA_R")
	)
	(segment
		(start 148.692108 -42.349928)
		(end 147.054316 -42.349928)
		(width 0.10668)
		(layer "F.Cu")
		(net "SMB_M2_P1_1V8AUX_SDA_R")
	)
	(via
		(at 149.657562 -41.746424)
		(size 0.508)
		(drill 0.254)
		(layers "F.Cu" "B.Cu")
		(net "SMB_M2_P1_1V8AUX_SDA_R")
	)
	(segment
		(start 166.0398 -45.710348)
		(end 166.238174 -45.710348)
		(width 0.10668)
		(layer "F.Cu")
		(net "SMB_M2_P1_1V8AUX_SDA")
	)
	(segment
		(start 166.577772 -46.049946)
		(end 169.558208 -46.049946)
		(width 0.10668)
		(layer "F.Cu")
		(net "SMB_M2_P1_1V8AUX_SDA")
	)
	(segment
		(start 145.904712 -41.746424)
		(end 145.288762 -41.746424)
		(width 0.10668)
		(layer "F.Cu")
		(net "SMB_M2_P1_1V8AUX_SDA")
	)
	(segment
		(start 166.238174 -45.710348)
		(end 166.577772 -46.049946)
		(width 0.10668)
		(layer "F.Cu")
		(net "SMB_M2_P1_1V8AUX_SDA")
	)
	(via
		(at 166.0398 -45.710348)
		(size 0.508)
		(drill 0.254)
		(layers "F.Cu" "B.Cu")
		(net "SMB_M2_P1_1V8AUX_SDA")
	)
	(via
		(at 145.288762 -41.746424)
		(size 0.508)
		(drill 0.254)
		(layers "F.Cu" "B.Cu")
		(net "SMB_M2_P1_1V8AUX_SDA")
	)
	(segment
		(start 151.153876 -41.230804)
		(end 153.763472 -43.8404)
		(width 0.11684)
		(layer "In2.Cu")
		(net "SMB_M2_P1_1V8AUX_SDA")
	)
	(segment
		(start 165.983412 -45.65396)
		(end 166.0398 -45.710348)
		(width 0.11684)
		(layer "In2.Cu")
		(net "SMB_M2_P1_1V8AUX_SDA")
	)
	(segment
		(start 145.288762 -41.746424)
		(end 145.557748 -41.746424)
		(width 0.11684)
		(layer "In2.Cu")
		(net "SMB_M2_P1_1V8AUX_SDA")
	)
	(segment
		(start 162.72891 -43.8404)
		(end 164.54247 -45.65396)
		(width 0.11684)
		(layer "In2.Cu")
		(net "SMB_M2_P1_1V8AUX_SDA")
	)
	(segment
		(start 145.557748 -41.746424)
		(end 146.073368 -41.230804)
		(width 0.11684)
		(layer "In2.Cu")
		(net "SMB_M2_P1_1V8AUX_SDA")
	)
	(segment
		(start 146.073368 -41.230804)
		(end 151.153876 -41.230804)
		(width 0.11684)
		(layer "In2.Cu")
		(net "SMB_M2_P1_1V8AUX_SDA")
	)
	(segment
		(start 153.763472 -43.8404)
		(end 162.72891 -43.8404)
		(width 0.11684)
		(layer "In2.Cu")
		(net "SMB_M2_P1_1V8AUX_SDA")
	)
	(segment
		(start 164.54247 -45.65396)
		(end 165.983412 -45.65396)
		(width 0.11684)
		(layer "In2.Cu")
		(net "SMB_M2_P1_1V8AUX_SDA")
	)
	(segment
		(start 149.041612 -43.03141)
		(end 149.041612 -43.28541)
		(width 0.10668)
		(layer "F.Cu")
		(net "SMB_M2_P1_1V8AUX_SCL_R")
	)
	(segment
		(start 151.181562 -43.28541)
		(end 150.536402 -43.28541)
		(width 0.10668)
		(layer "F.Cu")
		(net "SMB_M2_P1_1V8AUX_SCL_R")
	)
	(segment
		(start 149.041612 -43.28541)
		(end 148.692108 -43.634914)
		(width 0.10668)
		(layer "F.Cu")
		(net "SMB_M2_P1_1V8AUX_SCL_R")
	)
	(segment
		(start 150.282402 -43.03141)
		(end 149.657562 -43.03141)
		(width 0.10668)
		(layer "F.Cu")
		(net "SMB_M2_P1_1V8AUX_SCL_R")
	)
	(segment
		(start 148.692108 -43.634914)
		(end 147.054316 -43.634914)
		(width 0.10668)
		(layer "F.Cu")
		(net "SMB_M2_P1_1V8AUX_SCL_R")
	)
	(segment
		(start 150.536402 -43.28541)
		(end 150.282402 -43.03141)
		(width 0.10668)
		(layer "F.Cu")
		(net "SMB_M2_P1_1V8AUX_SCL_R")
	)
	(segment
		(start 149.041612 -43.03141)
		(end 149.657562 -43.03141)
		(width 0.10668)
		(layer "F.Cu")
		(net "SMB_M2_P1_1V8AUX_SCL_R")
	)
	(segment
		(start 146.704812 -43.28541)
		(end 146.704812 -43.03141)
		(width 0.10668)
		(layer "F.Cu")
		(net "SMB_M2_P1_1V8AUX_SCL_R")
	)
	(segment
		(start 147.054316 -43.634914)
		(end 146.704812 -43.28541)
		(width 0.10668)
		(layer "F.Cu")
		(net "SMB_M2_P1_1V8AUX_SCL_R")
	)
	(via
		(at 149.657562 -43.03141)
		(size 0.508)
		(drill 0.254)
		(layers "F.Cu" "B.Cu")
		(net "SMB_M2_P1_1V8AUX_SCL_R")
	)
	(segment
		(start 145.904712 -43.03141)
		(end 145.288762 -43.03141)
		(width 0.10668)
		(layer "F.Cu")
		(net "SMB_M2_P1_1V8AUX_SCL")
	)
	(segment
		(start 165.404038 -46.550072)
		(end 169.558208 -46.550072)
		(width 0.10668)
		(layer "F.Cu")
		(net "SMB_M2_P1_1V8AUX_SCL")
	)
	(segment
		(start 165.067234 -46.213268)
		(end 165.404038 -46.550072)
		(width 0.10668)
		(layer "F.Cu")
		(net "SMB_M2_P1_1V8AUX_SCL")
	)
	(via
		(at 145.288762 -43.03141)
		(size 0.508)
		(drill 0.254)
		(layers "F.Cu" "B.Cu")
		(net "SMB_M2_P1_1V8AUX_SCL")
	)
	(via
		(at 165.067234 -46.213268)
		(size 0.508)
		(drill 0.254)
		(layers "F.Cu" "B.Cu")
		(net "SMB_M2_P1_1V8AUX_SCL")
	)
	(segment
		(start 162.968686 -45.242988)
		(end 163.926774 -46.201076)
		(width 0.11684)
		(layer "In2.Cu")
		(net "SMB_M2_P1_1V8AUX_SCL")
	)
	(segment
		(start 165.055042 -46.201076)
		(end 165.067234 -46.213268)
		(width 0.11684)
		(layer "In2.Cu")
		(net "SMB_M2_P1_1V8AUX_SCL")
	)
	(segment
		(start 145.288762 -43.03141)
		(end 145.829528 -43.03141)
		(width 0.11684)
		(layer "In2.Cu")
		(net "SMB_M2_P1_1V8AUX_SCL")
	)
	(segment
		(start 145.829528 -43.03141)
		(end 146.52625 -42.334688)
		(width 0.11684)
		(layer "In2.Cu")
		(net "SMB_M2_P1_1V8AUX_SCL")
	)
	(segment
		(start 151.283416 -42.334688)
		(end 154.191716 -45.242988)
		(width 0.11684)
		(layer "In2.Cu")
		(net "SMB_M2_P1_1V8AUX_SCL")
	)
	(segment
		(start 154.191716 -45.242988)
		(end 162.968686 -45.242988)
		(width 0.11684)
		(layer "In2.Cu")
		(net "SMB_M2_P1_1V8AUX_SCL")
	)
	(segment
		(start 146.52625 -42.334688)
		(end 151.283416 -42.334688)
		(width 0.11684)
		(layer "In2.Cu")
		(net "SMB_M2_P1_1V8AUX_SCL")
	)
	(segment
		(start 163.926774 -46.201076)
		(end 165.055042 -46.201076)
		(width 0.11684)
		(layer "In2.Cu")
		(net "SMB_M2_P1_1V8AUX_SCL")
	)
	(segment
		(start 13.629132 -130.210306)
		(end 13.691108 -130.14833)
		(width 0.10668)
		(layer "F.Cu")
		(net "SMB_HOST_CLK_GEN2_3V3AUX_SDA")
	)
	(segment
		(start 13.296646 -132.164074)
		(end 13.296646 -130.542792)
		(width 0.10668)
		(layer "F.Cu")
		(net "SMB_HOST_CLK_GEN2_3V3AUX_SDA")
	)
	(segment
		(start 13.462508 -128.94564)
		(end 13.437108 -128.94564)
		(width 0.10668)
		(layer "F.Cu")
		(net "SMB_HOST_CLK_GEN2_3V3AUX_SDA")
	)
	(segment
		(start 13.691108 -129.17424)
		(end 13.462508 -128.94564)
		(width 0.10668)
		(layer "F.Cu")
		(net "SMB_HOST_CLK_GEN2_3V3AUX_SDA")
	)
	(segment
		(start 13.296646 -130.542792)
		(end 13.629132 -130.210306)
		(width 0.10668)
		(layer "F.Cu")
		(net "SMB_HOST_CLK_GEN2_3V3AUX_SDA")
	)
	(segment
		(start 13.691108 -130.14833)
		(end 13.691108 -129.17424)
		(width 0.10668)
		(layer "F.Cu")
		(net "SMB_HOST_CLK_GEN2_3V3AUX_SDA")
	)
	(via
		(at 13.629132 -130.210306)
		(size 0.762)
		(drill 0.381)
		(layers "F.Cu" "B.Cu")
		(net "SMB_HOST_CLK_GEN2_3V3AUX_SDA")
	)
	(segment
		(start 12.79652 -130.826002)
		(end 12.167108 -130.19659)
		(width 0.10668)
		(layer "F.Cu")
		(net "SMB_HOST_CLK_GEN2_3V3AUX_SCL")
	)
	(segment
		(start 12.79652 -132.164074)
		(end 12.79652 -130.826002)
		(width 0.10668)
		(layer "F.Cu")
		(net "SMB_HOST_CLK_GEN2_3V3AUX_SCL")
	)
	(segment
		(start 12.167108 -129.145538)
		(end 12.167108 -130.19659)
		(width 0.10668)
		(layer "F.Cu")
		(net "SMB_HOST_CLK_GEN2_3V3AUX_SCL")
	)
	(segment
		(start 12.319508 -128.993138)
		(end 12.167108 -129.145538)
		(width 0.10668)
		(layer "F.Cu")
		(net "SMB_HOST_CLK_GEN2_3V3AUX_SCL")
	)
	(via
		(at 12.167108 -130.19659)
		(size 0.762)
		(drill 0.381)
		(layers "F.Cu" "B.Cu")
		(net "SMB_HOST_CLK_GEN2_3V3AUX_SCL")
	)
	(segment
		(start 180.985668 -17.364964)
		(end 181.030118 -17.409414)
		(width 0.10668)
		(layer "F.Cu")
		(net "SMB_CPU0_CPU1_APML_SDA_R")
	)
	(segment
		(start 180.985668 -16.73098)
		(end 180.985668 -17.364964)
		(width 0.10668)
		(layer "F.Cu")
		(net "SMB_CPU0_CPU1_APML_SDA_R")
	)
	(segment
		(start 177.066956 -14.280134)
		(end 178.366928 -15.580106)
		(width 0.10668)
		(layer "F.Cu")
		(net "SMB_CPU0_CPU1_APML_SDA_R")
	)
	(segment
		(start 178.366928 -15.580106)
		(end 179.834794 -15.580106)
		(width 0.10668)
		(layer "F.Cu")
		(net "SMB_CPU0_CPU1_APML_SDA_R")
	)
	(segment
		(start 179.834794 -15.580106)
		(end 180.985668 -16.73098)
		(width 0.10668)
		(layer "F.Cu")
		(net "SMB_CPU0_CPU1_APML_SDA_R")
	)
	(segment
		(start 177.066956 -13.599922)
		(end 177.066956 -14.280134)
		(width 0.10668)
		(layer "F.Cu")
		(net "SMB_CPU0_CPU1_APML_SDA_R")
	)
	(via
		(at 181.030118 -17.409414)
		(size 0.508)
		(drill 0.254)
		(layers "F.Cu" "B.Cu")
		(net "SMB_CPU0_CPU1_APML_SDA_R")
	)
	(segment
		(start 181.030118 -17.604232)
		(end 181.030118 -17.409414)
		(width 0.10668)
		(layer "B.Cu")
		(net "SMB_CPU0_CPU1_APML_SDA_R")
	)
	(segment
		(start 180.824378 -19.581876)
		(end 180.824378 -17.809972)
		(width 0.10668)
		(layer "B.Cu")
		(net "SMB_CPU0_CPU1_APML_SDA_R")
	)
	(segment
		(start 180.858922 -19.61642)
		(end 180.824378 -19.581876)
		(width 0.10668)
		(layer "B.Cu")
		(net "SMB_CPU0_CPU1_APML_SDA_R")
	)
	(segment
		(start 180.858922 -19.978116)
		(end 180.858922 -19.61642)
		(width 0.10668)
		(layer "B.Cu")
		(net "SMB_CPU0_CPU1_APML_SDA_R")
	)
	(segment
		(start 180.824378 -17.809972)
		(end 181.030118 -17.604232)
		(width 0.10668)
		(layer "B.Cu")
		(net "SMB_CPU0_CPU1_APML_SDA_R")
	)
	(segment
		(start 178.572668 -15.163038)
		(end 180.107082 -15.163038)
		(width 0.10668)
		(layer "F.Cu")
		(net "SMB_CPU0_CPU1_APML_SCL_R")
	)
	(segment
		(start 181.675024 -18.421604)
		(end 181.380384 -18.716244)
		(width 0.10668)
		(layer "F.Cu")
		(net "SMB_CPU0_CPU1_APML_SCL_R")
	)
	(segment
		(start 177.666904 -14.257274)
		(end 178.572668 -15.163038)
		(width 0.10668)
		(layer "F.Cu")
		(net "SMB_CPU0_CPU1_APML_SCL_R")
	)
	(segment
		(start 180.107082 -15.163038)
		(end 181.675024 -16.73098)
		(width 0.10668)
		(layer "F.Cu")
		(net "SMB_CPU0_CPU1_APML_SCL_R")
	)
	(segment
		(start 177.666904 -13.599922)
		(end 177.666904 -14.257274)
		(width 0.10668)
		(layer "F.Cu")
		(net "SMB_CPU0_CPU1_APML_SCL_R")
	)
	(segment
		(start 181.675024 -16.73098)
		(end 181.675024 -18.421604)
		(width 0.10668)
		(layer "F.Cu")
		(net "SMB_CPU0_CPU1_APML_SCL_R")
	)
	(via
		(at 181.380384 -18.716244)
		(size 0.508)
		(drill 0.254)
		(layers "F.Cu" "B.Cu")
		(net "SMB_CPU0_CPU1_APML_SCL_R")
	)
	(segment
		(start 181.872382 -19.978116)
		(end 181.872382 -19.208242)
		(width 0.10668)
		(layer "B.Cu")
		(net "SMB_CPU0_CPU1_APML_SCL_R")
	)
	(segment
		(start 181.872382 -19.208242)
		(end 181.380384 -18.716244)
		(width 0.10668)
		(layer "B.Cu")
		(net "SMB_CPU0_CPU1_APML_SCL_R")
	)
	(segment
		(start 158.040578 -15.308072)
		(end 158.040578 -15.385542)
		(width 0.10668)
		(layer "F.Cu")
		(net "SMB_FAN_3V3AUX_SDA")
	)
	(segment
		(start 158.057088 -15.291562)
		(end 158.040578 -15.308072)
		(width 0.10668)
		(layer "F.Cu")
		(net "SMB_FAN_3V3AUX_SDA")
	)
	(segment
		(start 158.057088 -13.599922)
		(end 158.057088 -15.291562)
		(width 0.10668)
		(layer "F.Cu")
		(net "SMB_FAN_3V3AUX_SDA")
	)
	(via
		(at 158.040578 -15.385542)
		(size 0.508)
		(drill 0.254)
		(layers "F.Cu" "B.Cu")
		(net "SMB_FAN_3V3AUX_SDA")
	)
	(segment
		(start 158.040578 -16.553942)
		(end 158.040578 -15.385542)
		(width 0.10668)
		(layer "B.Cu")
		(net "SMB_FAN_3V3AUX_SDA")
	)
	(segment
		(start 157.989778 -17.569942)
		(end 158.040578 -17.519142)
		(width 0.10668)
		(layer "B.Cu")
		(net "SMB_FAN_3V3AUX_SDA")
	)
	(segment
		(start 158.040578 -17.519142)
		(end 158.040578 -16.553942)
		(width 0.10668)
		(layer "B.Cu")
		(net "SMB_FAN_3V3AUX_SDA")
	)
	(segment
		(start 158.657036 -12.218416)
		(end 158.657036 -13.599922)
		(width 0.10668)
		(layer "F.Cu")
		(net "SMB_FAN_3V3AUX_SCL")
	)
	(via
		(at 158.657036 -12.218416)
		(size 0.508)
		(drill 0.254)
		(layers "F.Cu" "B.Cu")
		(net "SMB_FAN_3V3AUX_SCL")
	)
	(segment
		(start 158.50108 -13.127228)
		(end 157.830012 -13.127228)
		(width 0.10668)
		(layer "B.Cu")
		(net "SMB_FAN_3V3AUX_SCL")
	)
	(segment
		(start 157.21838 -13.73886)
		(end 157.21838 -14.143228)
		(width 0.10668)
		(layer "B.Cu")
		(net "SMB_FAN_3V3AUX_SCL")
	)
	(segment
		(start 158.657036 -12.218416)
		(end 158.657036 -12.495022)
		(width 0.10668)
		(layer "B.Cu")
		(net "SMB_FAN_3V3AUX_SCL")
	)
	(segment
		(start 157.830012 -13.127228)
		(end 157.21838 -13.73886)
		(width 0.10668)
		(layer "B.Cu")
		(net "SMB_FAN_3V3AUX_SCL")
	)
	(segment
		(start 158.50108 -12.650978)
		(end 158.50108 -13.127228)
		(width 0.10668)
		(layer "B.Cu")
		(net "SMB_FAN_3V3AUX_SCL")
	)
	(segment
		(start 158.657036 -12.495022)
		(end 158.50108 -12.650978)
		(width 0.10668)
		(layer "B.Cu")
		(net "SMB_FAN_3V3AUX_SCL")
	)
	(segment
		(start 223.30283 -45.131228)
		(end 223.30283 -44.922948)
		(width 0.10668)
		(layer "F.Cu")
		(net "SMB_E1S_3V3AUX_ISO_SDA_R")
	)
	(segment
		(start 221.377002 -45.621702)
		(end 222.812356 -45.621702)
		(width 0.10668)
		(layer "F.Cu")
		(net "SMB_E1S_3V3AUX_ISO_SDA_R")
	)
	(segment
		(start 222.812356 -45.621702)
		(end 223.30283 -45.131228)
		(width 0.10668)
		(layer "F.Cu")
		(net "SMB_E1S_3V3AUX_ISO_SDA_R")
	)
	(segment
		(start 220.078808 -44.160948)
		(end 220.840808 -44.922948)
		(width 0.10668)
		(layer "F.Cu")
		(net "SMB_E1S_3V3AUX_ISO_SDA_R")
	)
	(segment
		(start 218.360752 -44.063412)
		(end 219.981272 -44.063412)
		(width 0.10668)
		(layer "F.Cu")
		(net "SMB_E1S_3V3AUX_ISO_SDA_R")
	)
	(segment
		(start 221.27083 -45.51553)
		(end 221.377002 -45.621702)
		(width 0.10668)
		(layer "F.Cu")
		(net "SMB_E1S_3V3AUX_ISO_SDA_R")
	)
	(segment
		(start 221.27083 -44.922948)
		(end 221.27083 -45.51553)
		(width 0.10668)
		(layer "F.Cu")
		(net "SMB_E1S_3V3AUX_ISO_SDA_R")
	)
	(segment
		(start 219.981272 -44.063412)
		(end 220.078808 -44.160948)
		(width 0.10668)
		(layer "F.Cu")
		(net "SMB_E1S_3V3AUX_ISO_SDA_R")
	)
	(segment
		(start 220.840808 -44.922948)
		(end 221.27083 -44.922948)
		(width 0.10668)
		(layer "F.Cu")
		(net "SMB_E1S_3V3AUX_ISO_SDA_R")
	)
	(via
		(at 220.078808 -44.160948)
		(size 0.762)
		(drill 0.381)
		(layers "F.Cu" "B.Cu")
		(net "SMB_E1S_3V3AUX_ISO_SDA_R")
	)
	(segment
		(start 224.10293 -44.922948)
		(end 225.430334 -44.922948)
		(width 0.10668)
		(layer "F.Cu")
		(net "SMB_E1S_3V3AUX_ISO_SDA")
	)
	(segment
		(start 232.000044 -46.764956)
		(end 233.016298 -46.764956)
		(width 0.10668)
		(layer "F.Cu")
		(net "SMB_E1S_3V3AUX_ISO_SDA")
	)
	(via
		(at 225.430334 -44.922948)
		(size 0.508)
		(drill 0.254)
		(layers "F.Cu" "B.Cu")
		(net "SMB_E1S_3V3AUX_ISO_SDA")
	)
	(via
		(at 233.016298 -46.764956)
		(size 0.508)
		(drill 0.254)
		(layers "F.Cu" "B.Cu")
		(net "SMB_E1S_3V3AUX_ISO_SDA")
	)
	(segment
		(start 225.430334 -45.82414)
		(end 225.430334 -44.922948)
		(width 0.10668)
		(layer "B.Cu")
		(net "SMB_E1S_3V3AUX_ISO_SDA")
	)
	(segment
		(start 233.016298 -46.764956)
		(end 231.164892 -46.764956)
		(width 0.10668)
		(layer "B.Cu")
		(net "SMB_E1S_3V3AUX_ISO_SDA")
	)
	(segment
		(start 227.1522 -47.546006)
		(end 225.430334 -45.82414)
		(width 0.10668)
		(layer "B.Cu")
		(net "SMB_E1S_3V3AUX_ISO_SDA")
	)
	(segment
		(start 230.383842 -47.546006)
		(end 227.1522 -47.546006)
		(width 0.10668)
		(layer "B.Cu")
		(net "SMB_E1S_3V3AUX_ISO_SDA")
	)
	(segment
		(start 231.164892 -46.764956)
		(end 230.383842 -47.546006)
		(width 0.10668)
		(layer "B.Cu")
		(net "SMB_E1S_3V3AUX_ISO_SDA")
	)
	(segment
		(start 222.94723 -44.089828)
		(end 223.30283 -43.734228)
		(width 0.10668)
		(layer "F.Cu")
		(net "SMB_E1S_3V3AUX_ISO_SCL_R")
	)
	(segment
		(start 221.27083 -43.872912)
		(end 221.487746 -44.089828)
		(width 0.10668)
		(layer "F.Cu")
		(net "SMB_E1S_3V3AUX_ISO_SCL_R")
	)
	(segment
		(start 221.487746 -44.089828)
		(end 222.94723 -44.089828)
		(width 0.10668)
		(layer "F.Cu")
		(net "SMB_E1S_3V3AUX_ISO_SCL_R")
	)
	(segment
		(start 220.63583 -42.890948)
		(end 220.078808 -42.890948)
		(width 0.10668)
		(layer "F.Cu")
		(net "SMB_E1S_3V3AUX_ISO_SCL_R")
	)
	(segment
		(start 219.556584 -43.413172)
		(end 218.360752 -43.413172)
		(width 0.10668)
		(layer "F.Cu")
		(net "SMB_E1S_3V3AUX_ISO_SCL_R")
	)
	(segment
		(start 221.27083 -43.525948)
		(end 221.27083 -43.872912)
		(width 0.10668)
		(layer "F.Cu")
		(net "SMB_E1S_3V3AUX_ISO_SCL_R")
	)
	(segment
		(start 221.27083 -43.525948)
		(end 220.63583 -42.890948)
		(width 0.10668)
		(layer "F.Cu")
		(net "SMB_E1S_3V3AUX_ISO_SCL_R")
	)
	(segment
		(start 220.078808 -42.890948)
		(end 219.556584 -43.413172)
		(width 0.10668)
		(layer "F.Cu")
		(net "SMB_E1S_3V3AUX_ISO_SCL_R")
	)
	(segment
		(start 223.30283 -43.734228)
		(end 223.30283 -43.525948)
		(width 0.10668)
		(layer "F.Cu")
		(net "SMB_E1S_3V3AUX_ISO_SCL_R")
	)
	(via
		(at 220.078808 -42.890948)
		(size 0.762)
		(drill 0.381)
		(layers "F.Cu" "B.Cu")
		(net "SMB_E1S_3V3AUX_ISO_SCL_R")
	)
	(segment
		(start 232.000044 -46.165008)
		(end 234.034076 -46.165008)
		(width 0.10668)
		(layer "F.Cu")
		(net "SMB_E1S_3V3AUX_ISO_SCL")
	)
	(segment
		(start 224.10293 -43.525948)
		(end 225.430334 -43.525948)
		(width 0.10668)
		(layer "F.Cu")
		(net "SMB_E1S_3V3AUX_ISO_SCL")
	)
	(segment
		(start 234.034076 -46.165008)
		(end 234.220512 -46.351444)
		(width 0.10668)
		(layer "F.Cu")
		(net "SMB_E1S_3V3AUX_ISO_SCL")
	)
	(via
		(at 225.430334 -43.525948)
		(size 0.508)
		(drill 0.254)
		(layers "F.Cu" "B.Cu")
		(net "SMB_E1S_3V3AUX_ISO_SCL")
	)
	(via
		(at 234.220512 -46.351444)
		(size 0.508)
		(drill 0.254)
		(layers "F.Cu" "B.Cu")
		(net "SMB_E1S_3V3AUX_ISO_SCL")
	)
	(segment
		(start 234.043982 -46.174914)
		(end 230.840788 -46.174914)
		(width 0.10668)
		(layer "B.Cu")
		(net "SMB_E1S_3V3AUX_ISO_SCL")
	)
	(segment
		(start 226.103434 -44.199048)
		(end 225.430334 -43.525948)
		(width 0.10668)
		(layer "B.Cu")
		(net "SMB_E1S_3V3AUX_ISO_SCL")
	)
	(segment
		(start 230.031036 -46.984666)
		(end 227.401628 -46.984666)
		(width 0.10668)
		(layer "B.Cu")
		(net "SMB_E1S_3V3AUX_ISO_SCL")
	)
	(segment
		(start 230.840788 -46.174914)
		(end 230.031036 -46.984666)
		(width 0.10668)
		(layer "B.Cu")
		(net "SMB_E1S_3V3AUX_ISO_SCL")
	)
	(segment
		(start 226.103434 -45.686472)
		(end 226.103434 -44.199048)
		(width 0.10668)
		(layer "B.Cu")
		(net "SMB_E1S_3V3AUX_ISO_SCL")
	)
	(segment
		(start 234.220512 -46.351444)
		(end 234.043982 -46.174914)
		(width 0.10668)
		(layer "B.Cu")
		(net "SMB_E1S_3V3AUX_ISO_SCL")
	)
	(segment
		(start 227.401628 -46.984666)
		(end 226.103434 -45.686472)
		(width 0.10668)
		(layer "B.Cu")
		(net "SMB_E1S_3V3AUX_ISO_SCL")
	)
	(segment
		(start 27.432 -366.308894)
		(end 27.604974 -366.308894)
		(width 0.10668)
		(layer "F.Cu")
		(net "SMB_DIO_PVDDCR_CPU1_P1_R")
	)
	(segment
		(start 26.520902 -367.219992)
		(end 27.432 -366.308894)
		(width 0.10668)
		(layer "F.Cu")
		(net "SMB_DIO_PVDDCR_CPU1_P1_R")
	)
	(segment
		(start 25.569926 -367.219992)
		(end 26.520902 -367.219992)
		(width 0.10668)
		(layer "F.Cu")
		(net "SMB_DIO_PVDDCR_CPU1_P1_R")
	)
	(segment
		(start 25.16505 -367.919)
		(end 25.16505 -367.624868)
		(width 0.10668)
		(layer "F.Cu")
		(net "SMB_DIO_PVDDCR_CPU1_P1_R")
	)
	(segment
		(start 25.16505 -367.624868)
		(end 25.569926 -367.219992)
		(width 0.10668)
		(layer "F.Cu")
		(net "SMB_DIO_PVDDCR_CPU1_P1_R")
	)
	(segment
		(start 306.705 -366.944656)
		(end 306.705 -363.446568)
		(width 0.10668)
		(layer "F.Cu")
		(net "SMB_DIO_PVDDCR_CPU1_P0_R")
	)
	(segment
		(start 306.836318 -363.129576)
		(end 307.086 -362.879894)
		(width 0.10668)
		(layer "F.Cu")
		(net "SMB_DIO_PVDDCR_CPU1_P0_R")
	)
	(segment
		(start 304.81905 -367.665)
		(end 305.984656 -367.665)
		(width 0.10668)
		(layer "F.Cu")
		(net "SMB_DIO_PVDDCR_CPU1_P0_R")
	)
	(segment
		(start 306.705 -363.446568)
		(end 306.836318 -363.129576)
		(width 0.10668)
		(layer "F.Cu")
		(net "SMB_DIO_PVDDCR_CPU1_P0_R")
	)
	(segment
		(start 307.086 -362.879894)
		(end 307.258974 -362.879894)
		(width 0.10668)
		(layer "F.Cu")
		(net "SMB_DIO_PVDDCR_CPU1_P0_R")
	)
	(segment
		(start 305.984656 -367.665)
		(end 306.705 -366.944656)
		(width 0.10668)
		(layer "F.Cu")
		(net "SMB_DIO_PVDDCR_CPU1_P0_R")
	)
	(via
		(at 305.984656 -367.665)
		(size 0.762)
		(drill 0.381)
		(layers "F.Cu" "B.Cu")
		(net "SMB_DIO_PVDDCR_CPU1_P0_R")
	)
	(segment
		(start 192.930272 -138.650218)
		(end 193.167 -138.41349)
		(width 0.10668)
		(layer "F.Cu")
		(net "SMB_CPU_5_SDA")
	)
	(segment
		(start 393.764008 -325.675752)
		(end 393.88923 -325.675752)
		(width 0.10668)
		(layer "F.Cu")
		(net "SMB_CPU_5_SDA")
	)
	(segment
		(start 393.88923 -325.675752)
		(end 394.601192 -326.387714)
		(width 0.10668)
		(layer "F.Cu")
		(net "SMB_CPU_5_SDA")
	)
	(segment
		(start 193.167 -138.41349)
		(end 193.167 -138.032998)
		(width 0.10668)
		(layer "F.Cu")
		(net "SMB_CPU_5_SDA")
	)
	(via
		(at 394.601192 -326.387714)
		(size 0.508)
		(drill 0.254)
		(layers "F.Cu" "B.Cu")
		(net "SMB_CPU_5_SDA")
	)
	(via
		(at 350.890078 -129.8067)
		(size 0.508)
		(drill 0.254)
		(layers "F.Cu" "B.Cu")
		(net "SMB_CPU_5_SDA")
	)
	(via
		(at 192.930272 -138.650218)
		(size 0.508)
		(drill 0.254)
		(layers "F.Cu" "B.Cu")
		(net "SMB_CPU_5_SDA")
	)
	(segment
		(start 192.930272 -139.79144)
		(end 192.930272 -138.650218)
		(width 0.10668)
		(layer "B.Cu")
		(net "SMB_CPU_5_SDA")
	)
	(segment
		(start 193.171318 -140.032486)
		(end 192.930272 -139.79144)
		(width 0.10668)
		(layer "B.Cu")
		(net "SMB_CPU_5_SDA")
	)
	(segment
		(start 459.320646 -318.603376)
		(end 459.320646 -190.362078)
		(width 0.11684)
		(layer "In2.Cu")
		(net "SMB_CPU_5_SDA")
	)
	(segment
		(start 403.765512 -325.063612)
		(end 409.857448 -325.063612)
		(width 0.11684)
		(layer "In2.Cu")
		(net "SMB_CPU_5_SDA")
	)
	(segment
		(start 447.686938 -174.854362)
		(end 447.686938 -150.875492)
		(width 0.11684)
		(layer "In2.Cu")
		(net "SMB_CPU_5_SDA")
	)
	(segment
		(start 421.380158 -126.226316)
		(end 404.162768 -126.226316)
		(width 0.11684)
		(layer "In2.Cu")
		(net "SMB_CPU_5_SDA")
	)
	(segment
		(start 447.686938 -150.875492)
		(end 443.8904 -147.078954)
		(width 0.11684)
		(layer "In2.Cu")
		(net "SMB_CPU_5_SDA")
	)
	(segment
		(start 412.112714 -322.808346)
		(end 455.115676 -322.808346)
		(width 0.11684)
		(layer "In2.Cu")
		(net "SMB_CPU_5_SDA")
	)
	(segment
		(start 402.155406 -128.233678)
		(end 353.820984 -128.233678)
		(width 0.11684)
		(layer "In2.Cu")
		(net "SMB_CPU_5_SDA")
	)
	(segment
		(start 403.531832 -326.138794)
		(end 403.648672 -326.021954)
		(width 0.11684)
		(layer "In2.Cu")
		(net "SMB_CPU_5_SDA")
	)
	(segment
		(start 404.162768 -126.226316)
		(end 402.155406 -128.233678)
		(width 0.11684)
		(layer "In2.Cu")
		(net "SMB_CPU_5_SDA")
	)
	(segment
		(start 395.837918 -326.387714)
		(end 397.16202 -325.063612)
		(width 0.11684)
		(layer "In2.Cu")
		(net "SMB_CPU_5_SDA")
	)
	(segment
		(start 442.232796 -147.078954)
		(end 421.380158 -126.226316)
		(width 0.11684)
		(layer "In2.Cu")
		(net "SMB_CPU_5_SDA")
	)
	(segment
		(start 409.857448 -325.063612)
		(end 412.112714 -322.808346)
		(width 0.11684)
		(layer "In2.Cu")
		(net "SMB_CPU_5_SDA")
	)
	(segment
		(start 352.247962 -129.8067)
		(end 350.890078 -129.8067)
		(width 0.11684)
		(layer "In2.Cu")
		(net "SMB_CPU_5_SDA")
	)
	(segment
		(start 403.224492 -326.021954)
		(end 403.341332 -326.138794)
		(width 0.11684)
		(layer "In2.Cu")
		(net "SMB_CPU_5_SDA")
	)
	(segment
		(start 394.601192 -326.387714)
		(end 395.837918 -326.387714)
		(width 0.11684)
		(layer "In2.Cu")
		(net "SMB_CPU_5_SDA")
	)
	(segment
		(start 403.341332 -326.138794)
		(end 403.531832 -326.138794)
		(width 0.11684)
		(layer "In2.Cu")
		(net "SMB_CPU_5_SDA")
	)
	(segment
		(start 353.820984 -128.233678)
		(end 352.247962 -129.8067)
		(width 0.11684)
		(layer "In2.Cu")
		(net "SMB_CPU_5_SDA")
	)
	(segment
		(start 456.560428 -187.60186)
		(end 456.560428 -183.727852)
		(width 0.11684)
		(layer "In2.Cu")
		(net "SMB_CPU_5_SDA")
	)
	(segment
		(start 443.8904 -147.078954)
		(end 442.232796 -147.078954)
		(width 0.11684)
		(layer "In2.Cu")
		(net "SMB_CPU_5_SDA")
	)
	(segment
		(start 459.320646 -190.362078)
		(end 456.560428 -187.60186)
		(width 0.11684)
		(layer "In2.Cu")
		(net "SMB_CPU_5_SDA")
	)
	(segment
		(start 455.115676 -322.808346)
		(end 459.320646 -318.603376)
		(width 0.11684)
		(layer "In2.Cu")
		(net "SMB_CPU_5_SDA")
	)
	(segment
		(start 403.107652 -325.063612)
		(end 403.224492 -325.180452)
		(width 0.11684)
		(layer "In2.Cu")
		(net "SMB_CPU_5_SDA")
	)
	(segment
		(start 403.648672 -325.180452)
		(end 403.765512 -325.063612)
		(width 0.11684)
		(layer "In2.Cu")
		(net "SMB_CPU_5_SDA")
	)
	(segment
		(start 456.560428 -183.727852)
		(end 447.686938 -174.854362)
		(width 0.11684)
		(layer "In2.Cu")
		(net "SMB_CPU_5_SDA")
	)
	(segment
		(start 403.224492 -325.180452)
		(end 403.224492 -326.021954)
		(width 0.11684)
		(layer "In2.Cu")
		(net "SMB_CPU_5_SDA")
	)
	(segment
		(start 397.16202 -325.063612)
		(end 403.107652 -325.063612)
		(width 0.11684)
		(layer "In2.Cu")
		(net "SMB_CPU_5_SDA")
	)
	(segment
		(start 403.648672 -326.021954)
		(end 403.648672 -325.180452)
		(width 0.11684)
		(layer "In2.Cu")
		(net "SMB_CPU_5_SDA")
	)
	(segment
		(start 240.595912 -138.740896)
		(end 240.505234 -138.650218)
		(width 0.11684)
		(layer "In6.Cu")
		(net "SMB_CPU_5_SDA")
	)
	(segment
		(start 207.892142 -136.95172)
		(end 205.50378 -139.340082)
		(width 0.11684)
		(layer "In6.Cu")
		(net "SMB_CPU_5_SDA")
	)
	(segment
		(start 303.045114 -127.510032)
		(end 290.689792 -139.865354)
		(width 0.11684)
		(layer "In6.Cu")
		(net "SMB_CPU_5_SDA")
	)
	(segment
		(start 240.617756 -138.740896)
		(end 240.595912 -138.740896)
		(width 0.11684)
		(layer "In6.Cu")
		(net "SMB_CPU_5_SDA")
	)
	(segment
		(start 318.851788 -127.510032)
		(end 303.045114 -127.510032)
		(width 0.11684)
		(layer "In6.Cu")
		(net "SMB_CPU_5_SDA")
	)
	(segment
		(start 345.322144 -124.54636)
		(end 321.81546 -124.54636)
		(width 0.11684)
		(layer "In6.Cu")
		(net "SMB_CPU_5_SDA")
	)
	(segment
		(start 290.689792 -139.865354)
		(end 272.098262 -139.865354)
		(width 0.11684)
		(layer "In6.Cu")
		(net "SMB_CPU_5_SDA")
	)
	(segment
		(start 245.184676 -143.307816)
		(end 240.617756 -138.740896)
		(width 0.11684)
		(layer "In6.Cu")
		(net "SMB_CPU_5_SDA")
	)
	(segment
		(start 349.807784 -129.032)
		(end 345.322144 -124.54636)
		(width 0.11684)
		(layer "In6.Cu")
		(net "SMB_CPU_5_SDA")
	)
	(segment
		(start 229.978966 -139.584176)
		(end 214.52967 -139.584176)
		(width 0.11684)
		(layer "In6.Cu")
		(net "SMB_CPU_5_SDA")
	)
	(segment
		(start 350.115378 -129.032)
		(end 349.807784 -129.032)
		(width 0.11684)
		(layer "In6.Cu")
		(net "SMB_CPU_5_SDA")
	)
	(segment
		(start 240.505234 -138.650218)
		(end 230.912924 -138.650218)
		(width 0.11684)
		(layer "In6.Cu")
		(net "SMB_CPU_5_SDA")
	)
	(segment
		(start 230.912924 -138.650218)
		(end 229.978966 -139.584176)
		(width 0.11684)
		(layer "In6.Cu")
		(net "SMB_CPU_5_SDA")
	)
	(segment
		(start 262.313928 -149.649688)
		(end 251.660914 -149.649688)
		(width 0.11684)
		(layer "In6.Cu")
		(net "SMB_CPU_5_SDA")
	)
	(segment
		(start 214.52967 -139.584176)
		(end 211.897214 -136.95172)
		(width 0.11684)
		(layer "In6.Cu")
		(net "SMB_CPU_5_SDA")
	)
	(segment
		(start 321.81546 -124.54636)
		(end 318.851788 -127.510032)
		(width 0.11684)
		(layer "In6.Cu")
		(net "SMB_CPU_5_SDA")
	)
	(segment
		(start 272.098262 -139.865354)
		(end 262.313928 -149.649688)
		(width 0.11684)
		(layer "In6.Cu")
		(net "SMB_CPU_5_SDA")
	)
	(segment
		(start 245.319042 -143.307816)
		(end 245.184676 -143.307816)
		(width 0.11684)
		(layer "In6.Cu")
		(net "SMB_CPU_5_SDA")
	)
	(segment
		(start 251.660914 -149.649688)
		(end 245.319042 -143.307816)
		(width 0.11684)
		(layer "In6.Cu")
		(net "SMB_CPU_5_SDA")
	)
	(segment
		(start 205.50378 -139.340082)
		(end 193.620136 -139.340082)
		(width 0.11684)
		(layer "In6.Cu")
		(net "SMB_CPU_5_SDA")
	)
	(segment
		(start 350.890078 -129.8067)
		(end 350.115378 -129.032)
		(width 0.11684)
		(layer "In6.Cu")
		(net "SMB_CPU_5_SDA")
	)
	(segment
		(start 211.897214 -136.95172)
		(end 207.892142 -136.95172)
		(width 0.11684)
		(layer "In6.Cu")
		(net "SMB_CPU_5_SDA")
	)
	(segment
		(start 193.620136 -139.340082)
		(end 192.930272 -138.650218)
		(width 0.11684)
		(layer "In6.Cu")
		(net "SMB_CPU_5_SDA")
	)
	(segment
		(start 393.8524 -326.691752)
		(end 394.519404 -327.358756)
		(width 0.10668)
		(layer "F.Cu")
		(net "SMB_CPU_5_SCL")
	)
	(segment
		(start 393.764008 -326.691752)
		(end 393.8524 -326.691752)
		(width 0.10668)
		(layer "F.Cu")
		(net "SMB_CPU_5_SCL")
	)
	(segment
		(start 190.119 -138.648948)
		(end 190.119 -138.032998)
		(width 0.10668)
		(layer "F.Cu")
		(net "SMB_CPU_5_SCL")
	)
	(via
		(at 394.519404 -327.358756)
		(size 0.508)
		(drill 0.254)
		(layers "F.Cu" "B.Cu")
		(net "SMB_CPU_5_SCL")
	)
	(via
		(at 190.119 -138.648948)
		(size 0.508)
		(drill 0.254)
		(layers "F.Cu" "B.Cu")
		(net "SMB_CPU_5_SCL")
	)
	(via
		(at 348.960948 -129.807208)
		(size 0.508)
		(drill 0.254)
		(layers "F.Cu" "B.Cu")
		(net "SMB_CPU_5_SCL")
	)
	(segment
		(start 190.114428 -140.06449)
		(end 190.114428 -138.65352)
		(width 0.10668)
		(layer "B.Cu")
		(net "SMB_CPU_5_SCL")
	)
	(segment
		(start 190.114428 -138.65352)
		(end 190.119 -138.648948)
		(width 0.10668)
		(layer "B.Cu")
		(net "SMB_CPU_5_SCL")
	)
	(segment
		(start 395.745716 -327.60412)
		(end 395.500352 -327.358756)
		(width 0.11684)
		(layer "In2.Cu")
		(net "SMB_CPU_5_SCL")
	)
	(segment
		(start 399.36293 -326.915272)
		(end 396.88262 -326.915272)
		(width 0.11684)
		(layer "In2.Cu")
		(net "SMB_CPU_5_SCL")
	)
	(segment
		(start 401.980654 -127.812038)
		(end 403.988016 -125.804676)
		(width 0.11684)
		(layer "In2.Cu")
		(net "SMB_CPU_5_SCL")
	)
	(segment
		(start 353.58959 -127.812038)
		(end 401.980654 -127.812038)
		(width 0.11684)
		(layer "In2.Cu")
		(net "SMB_CPU_5_SCL")
	)
	(segment
		(start 348.960948 -129.807208)
		(end 349.426276 -129.34188)
		(width 0.11684)
		(layer "In2.Cu")
		(net "SMB_CPU_5_SCL")
	)
	(segment
		(start 459.742286 -318.7954)
		(end 455.3077 -323.229986)
		(width 0.11684)
		(layer "In2.Cu")
		(net "SMB_CPU_5_SCL")
	)
	(segment
		(start 349.426276 -129.34188)
		(end 352.059748 -129.34188)
		(width 0.11684)
		(layer "In2.Cu")
		(net "SMB_CPU_5_SCL")
	)
	(segment
		(start 459.742286 -190.145162)
		(end 459.742286 -318.7954)
		(width 0.11684)
		(layer "In2.Cu")
		(net "SMB_CPU_5_SCL")
	)
	(segment
		(start 407.116788 -328.001122)
		(end 406.789128 -328.328782)
		(width 0.11684)
		(layer "In2.Cu")
		(net "SMB_CPU_5_SCL")
	)
	(segment
		(start 457.015596 -183.452516)
		(end 457.015596 -187.418472)
		(width 0.11684)
		(layer "In2.Cu")
		(net "SMB_CPU_5_SCL")
	)
	(segment
		(start 396.88262 -326.915272)
		(end 396.193772 -327.60412)
		(width 0.11684)
		(layer "In2.Cu")
		(net "SMB_CPU_5_SCL")
	)
	(segment
		(start 425.442126 -125.804676)
		(end 448.108578 -148.471128)
		(width 0.11684)
		(layer "In2.Cu")
		(net "SMB_CPU_5_SCL")
	)
	(segment
		(start 409.73883 -326.308466)
		(end 409.73883 -327.095358)
		(width 0.11684)
		(layer "In2.Cu")
		(net "SMB_CPU_5_SCL")
	)
	(segment
		(start 448.108578 -148.471128)
		(end 448.108578 -174.545498)
		(width 0.11684)
		(layer "In2.Cu")
		(net "SMB_CPU_5_SCL")
	)
	(segment
		(start 412.81731 -323.229986)
		(end 409.73883 -326.308466)
		(width 0.11684)
		(layer "In2.Cu")
		(net "SMB_CPU_5_SCL")
	)
	(segment
		(start 395.500352 -327.358756)
		(end 394.519404 -327.358756)
		(width 0.11684)
		(layer "In2.Cu")
		(net "SMB_CPU_5_SCL")
	)
	(segment
		(start 455.3077 -323.229986)
		(end 412.81731 -323.229986)
		(width 0.11684)
		(layer "In2.Cu")
		(net "SMB_CPU_5_SCL")
	)
	(segment
		(start 396.193772 -327.60412)
		(end 395.745716 -327.60412)
		(width 0.11684)
		(layer "In2.Cu")
		(net "SMB_CPU_5_SCL")
	)
	(segment
		(start 408.833066 -328.001122)
		(end 407.116788 -328.001122)
		(width 0.11684)
		(layer "In2.Cu")
		(net "SMB_CPU_5_SCL")
	)
	(segment
		(start 400.77644 -328.328782)
		(end 399.36293 -326.915272)
		(width 0.11684)
		(layer "In2.Cu")
		(net "SMB_CPU_5_SCL")
	)
	(segment
		(start 406.789128 -328.328782)
		(end 400.77644 -328.328782)
		(width 0.11684)
		(layer "In2.Cu")
		(net "SMB_CPU_5_SCL")
	)
	(segment
		(start 448.108578 -174.545498)
		(end 457.015596 -183.452516)
		(width 0.11684)
		(layer "In2.Cu")
		(net "SMB_CPU_5_SCL")
	)
	(segment
		(start 403.988016 -125.804676)
		(end 425.442126 -125.804676)
		(width 0.11684)
		(layer "In2.Cu")
		(net "SMB_CPU_5_SCL")
	)
	(segment
		(start 457.015596 -187.418472)
		(end 459.742286 -190.145162)
		(width 0.11684)
		(layer "In2.Cu")
		(net "SMB_CPU_5_SCL")
	)
	(segment
		(start 409.73883 -327.095358)
		(end 408.833066 -328.001122)
		(width 0.11684)
		(layer "In2.Cu")
		(net "SMB_CPU_5_SCL")
	)
	(segment
		(start 352.059748 -129.34188)
		(end 353.58959 -127.812038)
		(width 0.11684)
		(layer "In2.Cu")
		(net "SMB_CPU_5_SCL")
	)
	(segment
		(start 240.42116 -139.162536)
		(end 240.443004 -139.162536)
		(width 0.11684)
		(layer "In6.Cu")
		(net "SMB_CPU_5_SCL")
	)
	(segment
		(start 321.990212 -124.968)
		(end 344.12174 -124.968)
		(width 0.11684)
		(layer "In6.Cu")
		(net "SMB_CPU_5_SCL")
	)
	(segment
		(start 190.119 -138.648948)
		(end 191.390524 -139.920472)
		(width 0.11684)
		(layer "In6.Cu")
		(net "SMB_CPU_5_SCL")
	)
	(segment
		(start 205.825598 -139.920472)
		(end 208.28381 -137.46226)
		(width 0.11684)
		(layer "In6.Cu")
		(net "SMB_CPU_5_SCL")
	)
	(segment
		(start 211.696554 -137.46226)
		(end 214.24011 -140.005816)
		(width 0.11684)
		(layer "In6.Cu")
		(net "SMB_CPU_5_SCL")
	)
	(segment
		(start 290.864544 -140.286994)
		(end 303.219866 -127.931672)
		(width 0.11684)
		(layer "In6.Cu")
		(net "SMB_CPU_5_SCL")
	)
	(segment
		(start 319.02654 -127.931672)
		(end 321.990212 -124.968)
		(width 0.11684)
		(layer "In6.Cu")
		(net "SMB_CPU_5_SCL")
	)
	(segment
		(start 245.009924 -143.729456)
		(end 245.14429 -143.729456)
		(width 0.11684)
		(layer "In6.Cu")
		(net "SMB_CPU_5_SCL")
	)
	(segment
		(start 272.273014 -140.286994)
		(end 290.864544 -140.286994)
		(width 0.11684)
		(layer "In6.Cu")
		(net "SMB_CPU_5_SCL")
	)
	(segment
		(start 230.418132 -140.005816)
		(end 231.35209 -139.071858)
		(width 0.11684)
		(layer "In6.Cu")
		(net "SMB_CPU_5_SCL")
	)
	(segment
		(start 231.35209 -139.071858)
		(end 240.330482 -139.071858)
		(width 0.11684)
		(layer "In6.Cu")
		(net "SMB_CPU_5_SCL")
	)
	(segment
		(start 240.330482 -139.071858)
		(end 240.42116 -139.162536)
		(width 0.11684)
		(layer "In6.Cu")
		(net "SMB_CPU_5_SCL")
	)
	(segment
		(start 251.486162 -150.071328)
		(end 262.48868 -150.071328)
		(width 0.11684)
		(layer "In6.Cu")
		(net "SMB_CPU_5_SCL")
	)
	(segment
		(start 245.14429 -143.729456)
		(end 251.486162 -150.071328)
		(width 0.11684)
		(layer "In6.Cu")
		(net "SMB_CPU_5_SCL")
	)
	(segment
		(start 262.48868 -150.071328)
		(end 272.273014 -140.286994)
		(width 0.11684)
		(layer "In6.Cu")
		(net "SMB_CPU_5_SCL")
	)
	(segment
		(start 191.390524 -139.920472)
		(end 205.825598 -139.920472)
		(width 0.11684)
		(layer "In6.Cu")
		(net "SMB_CPU_5_SCL")
	)
	(segment
		(start 303.219866 -127.931672)
		(end 319.02654 -127.931672)
		(width 0.11684)
		(layer "In6.Cu")
		(net "SMB_CPU_5_SCL")
	)
	(segment
		(start 214.24011 -140.005816)
		(end 230.418132 -140.005816)
		(width 0.11684)
		(layer "In6.Cu")
		(net "SMB_CPU_5_SCL")
	)
	(segment
		(start 208.28381 -137.46226)
		(end 211.696554 -137.46226)
		(width 0.11684)
		(layer "In6.Cu")
		(net "SMB_CPU_5_SCL")
	)
	(segment
		(start 240.443004 -139.162536)
		(end 245.009924 -143.729456)
		(width 0.11684)
		(layer "In6.Cu")
		(net "SMB_CPU_5_SCL")
	)
	(segment
		(start 344.12174 -124.968)
		(end 348.960948 -129.807208)
		(width 0.11684)
		(layer "In6.Cu")
		(net "SMB_CPU_5_SCL")
	)
	(segment
		(start 379.582934 -309.545228)
		(end 379.641608 -309.545228)
		(width 0.10668)
		(layer "F.Cu")
		(net "SMB_CPU_5_R_SDA")
	)
	(segment
		(start 379.641608 -309.545228)
		(end 389.186166 -319.089786)
		(width 0.10668)
		(layer "F.Cu")
		(net "SMB_CPU_5_R_SDA")
	)
	(segment
		(start 389.186166 -321.46621)
		(end 389.21309 -321.493134)
		(width 0.10668)
		(layer "F.Cu")
		(net "SMB_CPU_5_R_SDA")
	)
	(segment
		(start 379.582934 -300.901354)
		(end 379.582934 -309.545228)
		(width 0.10668)
		(layer "F.Cu")
		(net "SMB_CPU_5_R_SDA")
	)
	(segment
		(start 389.186166 -319.089786)
		(end 389.186166 -321.46621)
		(width 0.10668)
		(layer "F.Cu")
		(net "SMB_CPU_5_R_SDA")
	)
	(segment
		(start 376.467878 -295.690036)
		(end 376.467878 -297.786298)
		(width 0.10668)
		(layer "F.Cu")
		(net "SMB_CPU_5_R_SDA")
	)
	(segment
		(start 392.078972 -324.359016)
		(end 392.078972 -324.790816)
		(width 0.10668)
		(layer "F.Cu")
		(net "SMB_CPU_5_R_SDA")
	)
	(segment
		(start 392.078972 -324.790816)
		(end 392.963908 -325.675752)
		(width 0.10668)
		(layer "F.Cu")
		(net "SMB_CPU_5_R_SDA")
	)
	(segment
		(start 376.467878 -297.786298)
		(end 379.582934 -300.901354)
		(width 0.10668)
		(layer "F.Cu")
		(net "SMB_CPU_5_R_SDA")
	)
	(segment
		(start 389.21309 -321.493134)
		(end 392.078972 -324.359016)
		(width 0.10668)
		(layer "F.Cu")
		(net "SMB_CPU_5_R_SDA")
	)
	(via
		(at 389.21309 -321.493134)
		(size 0.762)
		(drill 0.381)
		(layers "F.Cu" "B.Cu")
		(net "SMB_CPU_5_R_SDA")
	)
	(segment
		(start 388.329678 -321.625722)
		(end 390.47293 -323.768974)
		(width 0.10668)
		(layer "F.Cu")
		(net "SMB_CPU_5_R_SCL")
	)
	(segment
		(start 390.47293 -323.768974)
		(end 391.514076 -324.81012)
		(width 0.10668)
		(layer "F.Cu")
		(net "SMB_CPU_5_R_SCL")
	)
	(segment
		(start 391.514076 -325.24192)
		(end 392.963908 -326.691752)
		(width 0.10668)
		(layer "F.Cu")
		(net "SMB_CPU_5_R_SCL")
	)
	(segment
		(start 379.171454 -309.74792)
		(end 388.329678 -318.906144)
		(width 0.10668)
		(layer "F.Cu")
		(net "SMB_CPU_5_R_SCL")
	)
	(segment
		(start 375.528078 -295.690036)
		(end 375.528078 -297.328082)
		(width 0.10668)
		(layer "F.Cu")
		(net "SMB_CPU_5_R_SCL")
	)
	(segment
		(start 379.171454 -300.971458)
		(end 379.171454 -309.74792)
		(width 0.10668)
		(layer "F.Cu")
		(net "SMB_CPU_5_R_SCL")
	)
	(segment
		(start 391.514076 -324.81012)
		(end 391.514076 -325.24192)
		(width 0.10668)
		(layer "F.Cu")
		(net "SMB_CPU_5_R_SCL")
	)
	(segment
		(start 375.528078 -297.328082)
		(end 379.171454 -300.971458)
		(width 0.10668)
		(layer "F.Cu")
		(net "SMB_CPU_5_R_SCL")
	)
	(segment
		(start 388.329678 -318.906144)
		(end 388.329678 -321.625722)
		(width 0.10668)
		(layer "F.Cu")
		(net "SMB_CPU_5_R_SCL")
	)
	(via
		(at 390.47293 -323.768974)
		(size 0.762)
		(drill 0.381)
		(layers "F.Cu" "B.Cu")
		(net "SMB_CPU_5_R_SCL")
	)
	(segment
		(start 193.20764 -137.192258)
		(end 193.20764 -136.616948)
		(width 0.10668)
		(layer "F.Cu")
		(net "SMB_CPU_5_R1_SDA")
	)
	(segment
		(start 185.922158 -121.052844)
		(end 186.312048 -121.442734)
		(width 0.10668)
		(layer "F.Cu")
		(net "SMB_CPU_5_R1_SDA")
	)
	(segment
		(start 193.167 -137.232898)
		(end 193.20764 -137.192258)
		(width 0.10668)
		(layer "F.Cu")
		(net "SMB_CPU_5_R1_SDA")
	)
	(via
		(at 193.20764 -136.616948)
		(size 0.508)
		(drill 0.254)
		(layers "F.Cu" "B.Cu")
		(net "SMB_CPU_5_R1_SDA")
	)
	(via
		(at 186.312048 -121.442734)
		(size 0.4572)
		(drill 0.254)
		(layers "F.Cu" "B.Cu")
		(net "SMB_CPU_5_R1_SDA")
	)
	(segment
		(start 186.705494 -121.779792)
		(end 186.368436 -121.442734)
		(width 0.11684)
		(layer "In2.Cu")
		(net "SMB_CPU_5_R1_SDA")
	)
	(segment
		(start 189.1538 -131.577334)
		(end 189.872112 -130.859022)
		(width 0.11684)
		(layer "In2.Cu")
		(net "SMB_CPU_5_R1_SDA")
	)
	(segment
		(start 189.1538 -133.620764)
		(end 189.1538 -131.577334)
		(width 0.11684)
		(layer "In2.Cu")
		(net "SMB_CPU_5_R1_SDA")
	)
	(segment
		(start 193.20764 -136.616948)
		(end 192.70218 -136.111488)
		(width 0.11684)
		(layer "In2.Cu")
		(net "SMB_CPU_5_R1_SDA")
	)
	(segment
		(start 189.50559 -126.60249)
		(end 187.685426 -124.782326)
		(width 0.11684)
		(layer "In2.Cu")
		(net "SMB_CPU_5_R1_SDA")
	)
	(segment
		(start 192.70218 -136.111488)
		(end 192.70218 -134.222998)
		(width 0.11684)
		(layer "In2.Cu")
		(net "SMB_CPU_5_R1_SDA")
	)
	(segment
		(start 190.58382 -130.201162)
		(end 189.50559 -129.122932)
		(width 0.11684)
		(layer "In2.Cu")
		(net "SMB_CPU_5_R1_SDA")
	)
	(segment
		(start 192.388744 -133.909562)
		(end 189.442598 -133.909562)
		(width 0.11684)
		(layer "In2.Cu")
		(net "SMB_CPU_5_R1_SDA")
	)
	(segment
		(start 186.368436 -121.442734)
		(end 186.312048 -121.442734)
		(width 0.11684)
		(layer "In2.Cu")
		(net "SMB_CPU_5_R1_SDA")
	)
	(segment
		(start 187.685426 -124.782326)
		(end 187.106306 -124.782326)
		(width 0.11684)
		(layer "In2.Cu")
		(net "SMB_CPU_5_R1_SDA")
	)
	(segment
		(start 189.872112 -130.859022)
		(end 190.311532 -130.859022)
		(width 0.11684)
		(layer "In2.Cu")
		(net "SMB_CPU_5_R1_SDA")
	)
	(segment
		(start 192.70218 -134.222998)
		(end 192.388744 -133.909562)
		(width 0.11684)
		(layer "In2.Cu")
		(net "SMB_CPU_5_R1_SDA")
	)
	(segment
		(start 189.50559 -129.122932)
		(end 189.50559 -126.60249)
		(width 0.11684)
		(layer "In2.Cu")
		(net "SMB_CPU_5_R1_SDA")
	)
	(segment
		(start 186.705494 -124.381514)
		(end 186.705494 -121.779792)
		(width 0.11684)
		(layer "In2.Cu")
		(net "SMB_CPU_5_R1_SDA")
	)
	(segment
		(start 187.106306 -124.782326)
		(end 186.705494 -124.381514)
		(width 0.11684)
		(layer "In2.Cu")
		(net "SMB_CPU_5_R1_SDA")
	)
	(segment
		(start 190.311532 -130.859022)
		(end 190.58382 -130.586734)
		(width 0.11684)
		(layer "In2.Cu")
		(net "SMB_CPU_5_R1_SDA")
	)
	(segment
		(start 189.442598 -133.909562)
		(end 189.1538 -133.620764)
		(width 0.11684)
		(layer "In2.Cu")
		(net "SMB_CPU_5_R1_SDA")
	)
	(segment
		(start 190.58382 -130.586734)
		(end 190.58382 -130.201162)
		(width 0.11684)
		(layer "In2.Cu")
		(net "SMB_CPU_5_R1_SDA")
	)
	(segment
		(start 190.119 -136.743948)
		(end 189.992 -136.616948)
		(width 0.10668)
		(layer "F.Cu")
		(net "SMB_CPU_5_R1_SCL")
	)
	(segment
		(start 190.119 -137.232898)
		(end 190.119 -136.743948)
		(width 0.10668)
		(layer "F.Cu")
		(net "SMB_CPU_5_R1_SCL")
	)
	(segment
		(start 185.922158 -121.852944)
		(end 186.312048 -122.242834)
		(width 0.10668)
		(layer "F.Cu")
		(net "SMB_CPU_5_R1_SCL")
	)
	(via
		(at 186.312048 -122.242834)
		(size 0.4572)
		(drill 0.254)
		(layers "F.Cu" "B.Cu")
		(net "SMB_CPU_5_R1_SCL")
	)
	(via
		(at 189.992 -136.616948)
		(size 0.508)
		(drill 0.254)
		(layers "F.Cu" "B.Cu")
		(net "SMB_CPU_5_R1_SCL")
	)
	(segment
		(start 188.574934 -135.99541)
		(end 188.574934 -133.534912)
		(width 0.11684)
		(layer "In2.Cu")
		(net "SMB_CPU_5_R1_SCL")
	)
	(segment
		(start 188.709808 -131.91363)
		(end 187.46978 -130.673602)
		(width 0.11684)
		(layer "In2.Cu")
		(net "SMB_CPU_5_R1_SCL")
	)
	(segment
		(start 187.46978 -126.69901)
		(end 186.312048 -125.541278)
		(width 0.11684)
		(layer "In2.Cu")
		(net "SMB_CPU_5_R1_SCL")
	)
	(segment
		(start 189.992 -136.616948)
		(end 189.196472 -136.616948)
		(width 0.11684)
		(layer "In2.Cu")
		(net "SMB_CPU_5_R1_SCL")
	)
	(segment
		(start 187.46978 -130.673602)
		(end 187.46978 -126.69901)
		(width 0.11684)
		(layer "In2.Cu")
		(net "SMB_CPU_5_R1_SCL")
	)
	(segment
		(start 189.196472 -136.616948)
		(end 188.574934 -135.99541)
		(width 0.11684)
		(layer "In2.Cu")
		(net "SMB_CPU_5_R1_SCL")
	)
	(segment
		(start 186.312048 -125.541278)
		(end 186.312048 -122.242834)
		(width 0.11684)
		(layer "In2.Cu")
		(net "SMB_CPU_5_R1_SCL")
	)
	(segment
		(start 188.574934 -133.534912)
		(end 188.709808 -133.400038)
		(width 0.11684)
		(layer "In2.Cu")
		(net "SMB_CPU_5_R1_SCL")
	)
	(segment
		(start 188.709808 -133.400038)
		(end 188.709808 -131.91363)
		(width 0.11684)
		(layer "In2.Cu")
		(net "SMB_CPU_5_R1_SCL")
	)
	(segment
		(start 134.337806 -224.50044)
		(end 134.804658 -224.234502)
		(width 0.10668)
		(layer "F.Cu")
		(net "SMB_CPU1_SEC_SDA")
	)
	(via
		(at 134.804658 -224.234502)
		(size 0.4064)
		(drill 0.2032)
		(layers "F.Cu" "B.Cu")
		(net "SMB_CPU1_SEC_SDA")
	)
	(via
		(at 235.077 -232.791)
		(size 0.508)
		(drill 0.254)
		(layers "F.Cu" "B.Cu")
		(net "SMB_CPU1_SEC_SDA")
	)
	(via
		(at 211.221828 -229.908862)
		(size 0.508)
		(drill 0.254)
		(layers "F.Cu" "B.Cu")
		(net "SMB_CPU1_SEC_SDA")
	)
	(segment
		(start 235.077 -232.04805)
		(end 235.077 -232.791)
		(width 0.10668)
		(layer "B.Cu")
		(net "SMB_CPU1_SEC_SDA")
	)
	(segment
		(start 235.077 -232.791)
		(end 235.077 -233.66095)
		(width 0.10668)
		(layer "B.Cu")
		(net "SMB_CPU1_SEC_SDA")
	)
	(segment
		(start 135.831834 -222.221552)
		(end 135.458454 -222.221552)
		(width 0.11684)
		(layer "In6.Cu")
		(net "SMB_CPU1_SEC_SDA")
	)
	(segment
		(start 163.29025 -196.592952)
		(end 143.38681 -216.496392)
		(width 0.11684)
		(layer "In6.Cu")
		(net "SMB_CPU1_SEC_SDA")
	)
	(segment
		(start 185.308494 -195.234052)
		(end 183.970168 -195.234052)
		(width 0.11684)
		(layer "In6.Cu")
		(net "SMB_CPU1_SEC_SDA")
	)
	(segment
		(start 170.599862 -195.40982)
		(end 170.401234 -195.211192)
		(width 0.11684)
		(layer "In6.Cu")
		(net "SMB_CPU1_SEC_SDA")
	)
	(segment
		(start 168.007792 -195.43014)
		(end 166.575486 -195.43014)
		(width 0.11684)
		(layer "In6.Cu")
		(net "SMB_CPU1_SEC_SDA")
	)
	(segment
		(start 190.525146 -195.40982)
		(end 185.484262 -195.40982)
		(width 0.11684)
		(layer "In6.Cu")
		(net "SMB_CPU1_SEC_SDA")
	)
	(segment
		(start 183.792368 -195.411852)
		(end 177.869088 -195.411852)
		(width 0.11684)
		(layer "In6.Cu")
		(net "SMB_CPU1_SEC_SDA")
	)
	(segment
		(start 190.723774 -195.211192)
		(end 190.525146 -195.40982)
		(width 0.11684)
		(layer "In6.Cu")
		(net "SMB_CPU1_SEC_SDA")
	)
	(segment
		(start 207.214978 -200.418192)
		(end 206.89951 -200.102724)
		(width 0.11684)
		(layer "In6.Cu")
		(net "SMB_CPU1_SEC_SDA")
	)
	(segment
		(start 143.38681 -216.496392)
		(end 141.556994 -216.496392)
		(width 0.11684)
		(layer "In6.Cu")
		(net "SMB_CPU1_SEC_SDA")
	)
	(segment
		(start 168.22674 -195.211192)
		(end 168.007792 -195.43014)
		(width 0.11684)
		(layer "In6.Cu")
		(net "SMB_CPU1_SEC_SDA")
	)
	(segment
		(start 198.36892 -195.391532)
		(end 192.89014 -195.391532)
		(width 0.11684)
		(layer "In6.Cu")
		(net "SMB_CPU1_SEC_SDA")
	)
	(segment
		(start 135.269224 -222.410782)
		(end 135.269224 -222.784162)
		(width 0.11684)
		(layer "In6.Cu")
		(net "SMB_CPU1_SEC_SDA")
	)
	(segment
		(start 176.478946 -195.40982)
		(end 170.599862 -195.40982)
		(width 0.11684)
		(layer "In6.Cu")
		(net "SMB_CPU1_SEC_SDA")
	)
	(segment
		(start 209.700876 -228.38791)
		(end 209.700876 -209.213196)
		(width 0.11684)
		(layer "In6.Cu")
		(net "SMB_CPU1_SEC_SDA")
	)
	(segment
		(start 177.668428 -195.211192)
		(end 176.677574 -195.211192)
		(width 0.11684)
		(layer "In6.Cu")
		(net "SMB_CPU1_SEC_SDA")
	)
	(segment
		(start 183.970168 -195.234052)
		(end 183.792368 -195.411852)
		(width 0.11684)
		(layer "In6.Cu")
		(net "SMB_CPU1_SEC_SDA")
	)
	(segment
		(start 141.556994 -216.496392)
		(end 135.831834 -222.221552)
		(width 0.11684)
		(layer "In6.Cu")
		(net "SMB_CPU1_SEC_SDA")
	)
	(segment
		(start 170.401234 -195.211192)
		(end 168.22674 -195.211192)
		(width 0.11684)
		(layer "In6.Cu")
		(net "SMB_CPU1_SEC_SDA")
	)
	(segment
		(start 165.422834 -195.957952)
		(end 164.787834 -196.592952)
		(width 0.11684)
		(layer "In6.Cu")
		(net "SMB_CPU1_SEC_SDA")
	)
	(segment
		(start 176.677574 -195.211192)
		(end 176.478946 -195.40982)
		(width 0.11684)
		(layer "In6.Cu")
		(net "SMB_CPU1_SEC_SDA")
	)
	(segment
		(start 134.804658 -223.248728)
		(end 134.804658 -224.234502)
		(width 0.11684)
		(layer "In6.Cu")
		(net "SMB_CPU1_SEC_SDA")
	)
	(segment
		(start 185.484262 -195.40982)
		(end 185.308494 -195.234052)
		(width 0.11684)
		(layer "In6.Cu")
		(net "SMB_CPU1_SEC_SDA")
	)
	(segment
		(start 211.221828 -229.908862)
		(end 209.700876 -228.38791)
		(width 0.11684)
		(layer "In6.Cu")
		(net "SMB_CPU1_SEC_SDA")
	)
	(segment
		(start 207.214978 -206.727298)
		(end 207.214978 -200.418192)
		(width 0.11684)
		(layer "In6.Cu")
		(net "SMB_CPU1_SEC_SDA")
	)
	(segment
		(start 164.787834 -196.592952)
		(end 163.29025 -196.592952)
		(width 0.11684)
		(layer "In6.Cu")
		(net "SMB_CPU1_SEC_SDA")
	)
	(segment
		(start 202.663552 -196.719444)
		(end 199.696832 -196.719444)
		(width 0.11684)
		(layer "In6.Cu")
		(net "SMB_CPU1_SEC_SDA")
	)
	(segment
		(start 166.047674 -195.957952)
		(end 165.422834 -195.957952)
		(width 0.11684)
		(layer "In6.Cu")
		(net "SMB_CPU1_SEC_SDA")
	)
	(segment
		(start 209.700876 -209.213196)
		(end 207.214978 -206.727298)
		(width 0.11684)
		(layer "In6.Cu")
		(net "SMB_CPU1_SEC_SDA")
	)
	(segment
		(start 206.046832 -200.102724)
		(end 202.663552 -196.719444)
		(width 0.11684)
		(layer "In6.Cu")
		(net "SMB_CPU1_SEC_SDA")
	)
	(segment
		(start 166.575486 -195.43014)
		(end 166.047674 -195.957952)
		(width 0.11684)
		(layer "In6.Cu")
		(net "SMB_CPU1_SEC_SDA")
	)
	(segment
		(start 135.458454 -222.221552)
		(end 135.269224 -222.410782)
		(width 0.11684)
		(layer "In6.Cu")
		(net "SMB_CPU1_SEC_SDA")
	)
	(segment
		(start 135.269224 -222.784162)
		(end 134.804658 -223.248728)
		(width 0.11684)
		(layer "In6.Cu")
		(net "SMB_CPU1_SEC_SDA")
	)
	(segment
		(start 177.869088 -195.411852)
		(end 177.668428 -195.211192)
		(width 0.11684)
		(layer "In6.Cu")
		(net "SMB_CPU1_SEC_SDA")
	)
	(segment
		(start 206.89951 -200.102724)
		(end 206.046832 -200.102724)
		(width 0.11684)
		(layer "In6.Cu")
		(net "SMB_CPU1_SEC_SDA")
	)
	(segment
		(start 199.696832 -196.719444)
		(end 198.36892 -195.391532)
		(width 0.11684)
		(layer "In6.Cu")
		(net "SMB_CPU1_SEC_SDA")
	)
	(segment
		(start 192.7098 -195.211192)
		(end 190.723774 -195.211192)
		(width 0.11684)
		(layer "In6.Cu")
		(net "SMB_CPU1_SEC_SDA")
	)
	(segment
		(start 192.89014 -195.391532)
		(end 192.7098 -195.211192)
		(width 0.11684)
		(layer "In6.Cu")
		(net "SMB_CPU1_SEC_SDA")
	)
	(segment
		(start 234.561634 -232.275634)
		(end 235.077 -232.791)
		(width 0.11684)
		(layer "In11.Cu")
		(net "SMB_CPU1_SEC_SDA")
	)
	(segment
		(start 218.643708 -229.908862)
		(end 221.01048 -232.275634)
		(width 0.11684)
		(layer "In11.Cu")
		(net "SMB_CPU1_SEC_SDA")
	)
	(segment
		(start 211.221828 -229.908862)
		(end 218.643708 -229.908862)
		(width 0.11684)
		(layer "In11.Cu")
		(net "SMB_CPU1_SEC_SDA")
	)
	(segment
		(start 221.01048 -232.275634)
		(end 234.561634 -232.275634)
		(width 0.11684)
		(layer "In11.Cu")
		(net "SMB_CPU1_SEC_SDA")
	)
	(segment
		(start 134.337806 -222.880428)
		(end 134.804658 -222.61449)
		(width 0.10668)
		(layer "F.Cu")
		(net "SMB_CPU1_SEC_SCL")
	)
	(via
		(at 211.20227 -227.911914)
		(size 0.508)
		(drill 0.254)
		(layers "F.Cu" "B.Cu")
		(net "SMB_CPU1_SEC_SCL")
	)
	(via
		(at 134.804658 -222.61449)
		(size 0.4064)
		(drill 0.2032)
		(layers "F.Cu" "B.Cu")
		(net "SMB_CPU1_SEC_SCL")
	)
	(via
		(at 238.379 -232.791)
		(size 0.508)
		(drill 0.254)
		(layers "F.Cu" "B.Cu")
		(net "SMB_CPU1_SEC_SCL")
	)
	(segment
		(start 238.379 -232.791)
		(end 238.379 -233.66095)
		(width 0.10668)
		(layer "B.Cu")
		(net "SMB_CPU1_SEC_SCL")
	)
	(segment
		(start 238.379 -232.04805)
		(end 238.379 -232.791)
		(width 0.10668)
		(layer "B.Cu")
		(net "SMB_CPU1_SEC_SCL")
	)
	(segment
		(start 143.274034 -215.973152)
		(end 141.483842 -215.973152)
		(width 0.11684)
		(layer "In6.Cu")
		(net "SMB_CPU1_SEC_SCL")
	)
	(segment
		(start 190.24727 -194.339464)
		(end 190.145162 -194.441572)
		(width 0.11684)
		(layer "In6.Cu")
		(net "SMB_CPU1_SEC_SCL")
	)
	(segment
		(start 163.075874 -196.171312)
		(end 143.274034 -215.973152)
		(width 0.11684)
		(layer "In6.Cu")
		(net "SMB_CPU1_SEC_SCL")
	)
	(segment
		(start 206.222346 -199.67956)
		(end 202.726036 -196.18325)
		(width 0.11684)
		(layer "In6.Cu")
		(net "SMB_CPU1_SEC_SCL")
	)
	(segment
		(start 207.638142 -200.242678)
		(end 207.075024 -199.67956)
		(width 0.11684)
		(layer "In6.Cu")
		(net "SMB_CPU1_SEC_SCL")
	)
	(segment
		(start 210.12404 -209.037682)
		(end 207.638142 -206.551784)
		(width 0.11684)
		(layer "In6.Cu")
		(net "SMB_CPU1_SEC_SCL")
	)
	(segment
		(start 165.827202 -195.510912)
		(end 165.273482 -195.510912)
		(width 0.11684)
		(layer "In6.Cu")
		(net "SMB_CPU1_SEC_SCL")
	)
	(segment
		(start 172.366432 -194.33667)
		(end 168.29786 -194.33667)
		(width 0.11684)
		(layer "In6.Cu")
		(net "SMB_CPU1_SEC_SCL")
	)
	(segment
		(start 136.328912 -221.128082)
		(end 135.198104 -221.128082)
		(width 0.11684)
		(layer "In6.Cu")
		(net "SMB_CPU1_SEC_SCL")
	)
	(segment
		(start 179.089304 -194.441572)
		(end 178.993038 -194.345306)
		(width 0.11684)
		(layer "In6.Cu")
		(net "SMB_CPU1_SEC_SCL")
	)
	(segment
		(start 207.638142 -206.551784)
		(end 207.638142 -200.242678)
		(width 0.11684)
		(layer "In6.Cu")
		(net "SMB_CPU1_SEC_SCL")
	)
	(segment
		(start 164.613082 -196.171312)
		(end 163.075874 -196.171312)
		(width 0.11684)
		(layer "In6.Cu")
		(net "SMB_CPU1_SEC_SCL")
	)
	(segment
		(start 178.993038 -194.345306)
		(end 175.73244 -194.345306)
		(width 0.11684)
		(layer "In6.Cu")
		(net "SMB_CPU1_SEC_SCL")
	)
	(segment
		(start 134.804658 -221.521528)
		(end 134.804658 -222.61449)
		(width 0.11684)
		(layer "In6.Cu")
		(net "SMB_CPU1_SEC_SCL")
	)
	(segment
		(start 186.608974 -194.441572)
		(end 186.504072 -194.33667)
		(width 0.11684)
		(layer "In6.Cu")
		(net "SMB_CPU1_SEC_SCL")
	)
	(segment
		(start 202.726036 -196.18325)
		(end 199.790304 -196.18325)
		(width 0.11684)
		(layer "In6.Cu")
		(net "SMB_CPU1_SEC_SCL")
	)
	(segment
		(start 211.20227 -227.911914)
		(end 210.12404 -226.833684)
		(width 0.11684)
		(layer "In6.Cu")
		(net "SMB_CPU1_SEC_SCL")
	)
	(segment
		(start 210.12404 -226.833684)
		(end 210.12404 -209.037682)
		(width 0.11684)
		(layer "In6.Cu")
		(net "SMB_CPU1_SEC_SCL")
	)
	(segment
		(start 194.31 -194.339464)
		(end 190.24727 -194.339464)
		(width 0.11684)
		(layer "In6.Cu")
		(net "SMB_CPU1_SEC_SCL")
	)
	(segment
		(start 168.29786 -194.33667)
		(end 168.19499 -194.43954)
		(width 0.11684)
		(layer "In6.Cu")
		(net "SMB_CPU1_SEC_SCL")
	)
	(segment
		(start 166.898574 -194.43954)
		(end 165.827202 -195.510912)
		(width 0.11684)
		(layer "In6.Cu")
		(net "SMB_CPU1_SEC_SCL")
	)
	(segment
		(start 175.73244 -194.345306)
		(end 175.623474 -194.454272)
		(width 0.11684)
		(layer "In6.Cu")
		(net "SMB_CPU1_SEC_SCL")
	)
	(segment
		(start 182.601108 -194.441572)
		(end 179.089304 -194.441572)
		(width 0.11684)
		(layer "In6.Cu")
		(net "SMB_CPU1_SEC_SCL")
	)
	(segment
		(start 182.70601 -194.33667)
		(end 182.601108 -194.441572)
		(width 0.11684)
		(layer "In6.Cu")
		(net "SMB_CPU1_SEC_SCL")
	)
	(segment
		(start 165.273482 -195.510912)
		(end 164.613082 -196.171312)
		(width 0.11684)
		(layer "In6.Cu")
		(net "SMB_CPU1_SEC_SCL")
	)
	(segment
		(start 168.19499 -194.43954)
		(end 166.898574 -194.43954)
		(width 0.11684)
		(layer "In6.Cu")
		(net "SMB_CPU1_SEC_SCL")
	)
	(segment
		(start 199.790304 -196.18325)
		(end 198.053706 -194.446652)
		(width 0.11684)
		(layer "In6.Cu")
		(net "SMB_CPU1_SEC_SCL")
	)
	(segment
		(start 186.504072 -194.33667)
		(end 182.70601 -194.33667)
		(width 0.11684)
		(layer "In6.Cu")
		(net "SMB_CPU1_SEC_SCL")
	)
	(segment
		(start 207.075024 -199.67956)
		(end 206.222346 -199.67956)
		(width 0.11684)
		(layer "In6.Cu")
		(net "SMB_CPU1_SEC_SCL")
	)
	(segment
		(start 198.053706 -194.446652)
		(end 194.417188 -194.446652)
		(width 0.11684)
		(layer "In6.Cu")
		(net "SMB_CPU1_SEC_SCL")
	)
	(segment
		(start 172.484034 -194.454272)
		(end 172.366432 -194.33667)
		(width 0.11684)
		(layer "In6.Cu")
		(net "SMB_CPU1_SEC_SCL")
	)
	(segment
		(start 175.623474 -194.454272)
		(end 172.484034 -194.454272)
		(width 0.11684)
		(layer "In6.Cu")
		(net "SMB_CPU1_SEC_SCL")
	)
	(segment
		(start 194.417188 -194.446652)
		(end 194.31 -194.339464)
		(width 0.11684)
		(layer "In6.Cu")
		(net "SMB_CPU1_SEC_SCL")
	)
	(segment
		(start 141.483842 -215.973152)
		(end 136.328912 -221.128082)
		(width 0.11684)
		(layer "In6.Cu")
		(net "SMB_CPU1_SEC_SCL")
	)
	(segment
		(start 135.198104 -221.128082)
		(end 134.804658 -221.521528)
		(width 0.11684)
		(layer "In6.Cu")
		(net "SMB_CPU1_SEC_SCL")
	)
	(segment
		(start 190.145162 -194.441572)
		(end 186.608974 -194.441572)
		(width 0.11684)
		(layer "In6.Cu")
		(net "SMB_CPU1_SEC_SCL")
	)
	(segment
		(start 237.07725 -231.48925)
		(end 238.379 -232.791)
		(width 0.11684)
		(layer "In11.Cu")
		(net "SMB_CPU1_SEC_SCL")
	)
	(segment
		(start 220.073728 -229.163626)
		(end 222.399352 -231.48925)
		(width 0.11684)
		(layer "In11.Cu")
		(net "SMB_CPU1_SEC_SCL")
	)
	(segment
		(start 212.865462 -227.911914)
		(end 214.117174 -229.163626)
		(width 0.11684)
		(layer "In11.Cu")
		(net "SMB_CPU1_SEC_SCL")
	)
	(segment
		(start 211.20227 -227.911914)
		(end 212.865462 -227.911914)
		(width 0.11684)
		(layer "In11.Cu")
		(net "SMB_CPU1_SEC_SCL")
	)
	(segment
		(start 222.399352 -231.48925)
		(end 237.07725 -231.48925)
		(width 0.11684)
		(layer "In11.Cu")
		(net "SMB_CPU1_SEC_SCL")
	)
	(segment
		(start 214.117174 -229.163626)
		(end 220.073728 -229.163626)
		(width 0.11684)
		(layer "In11.Cu")
		(net "SMB_CPU1_SEC_SCL")
	)
	(via
		(at 236.093 -235.331)
		(size 0.6604)
		(drill 0.3302)
		(layers "F.Cu" "B.Cu")
		(net "SMB_CPU1_SEC_R_SDA")
	)
	(segment
		(start 237.744 -235.966)
		(end 236.728 -235.966)
		(width 0.10668)
		(layer "B.Cu")
		(net "SMB_CPU1_SEC_R_SDA")
	)
	(segment
		(start 237.919514 -236.590586)
		(end 237.919514 -236.141514)
		(width 0.10668)
		(layer "B.Cu")
		(net "SMB_CPU1_SEC_R_SDA")
	)
	(segment
		(start 236.728 -235.966)
		(end 236.093 -235.331)
		(width 0.10668)
		(layer "B.Cu")
		(net "SMB_CPU1_SEC_R_SDA")
	)
	(segment
		(start 236.093 -234.46105)
		(end 236.093 -235.331)
		(width 0.10668)
		(layer "B.Cu")
		(net "SMB_CPU1_SEC_R_SDA")
	)
	(segment
		(start 237.919514 -236.141514)
		(end 237.744 -235.966)
		(width 0.10668)
		(layer "B.Cu")
		(net "SMB_CPU1_SEC_R_SDA")
	)
	(segment
		(start 236.093 -234.46105)
		(end 235.077 -234.46105)
		(width 0.10668)
		(layer "B.Cu")
		(net "SMB_CPU1_SEC_R_SDA")
	)
	(via
		(at 237.363 -235.331)
		(size 0.6604)
		(drill 0.3302)
		(layers "F.Cu" "B.Cu")
		(net "SMB_CPU1_SEC_R_SCL")
	)
	(segment
		(start 238.41964 -236.590586)
		(end 238.41964 -235.966)
		(width 0.10668)
		(layer "B.Cu")
		(net "SMB_CPU1_SEC_R_SCL")
	)
	(segment
		(start 237.363 -235.331)
		(end 237.363 -234.46105)
		(width 0.10668)
		(layer "B.Cu")
		(net "SMB_CPU1_SEC_R_SCL")
	)
	(segment
		(start 238.41964 -235.966)
		(end 237.78464 -235.331)
		(width 0.10668)
		(layer "B.Cu")
		(net "SMB_CPU1_SEC_R_SCL")
	)
	(segment
		(start 237.78464 -235.331)
		(end 237.363 -235.331)
		(width 0.10668)
		(layer "B.Cu")
		(net "SMB_CPU1_SEC_R_SCL")
	)
	(segment
		(start 237.363 -234.46105)
		(end 238.379 -234.46105)
		(width 0.10668)
		(layer "B.Cu")
		(net "SMB_CPU1_SEC_R_SCL")
	)
	(segment
		(start 237.322106 -174.794164)
		(end 237.322106 -169.807382)
		(width 0.10668)
		(layer "F.Cu")
		(net "SMB_CPU0_SEC_SDA")
	)
	(segment
		(start 241.672364 -207.3656)
		(end 243.852192 -205.185772)
		(width 0.10668)
		(layer "F.Cu")
		(net "SMB_CPU0_SEC_SDA")
	)
	(segment
		(start 243.852192 -190.560452)
		(end 237.322106 -174.794164)
		(width 0.10668)
		(layer "F.Cu")
		(net "SMB_CPU0_SEC_SDA")
	)
	(segment
		(start 382.277874 -224.500186)
		(end 382.744726 -224.234248)
		(width 0.10668)
		(layer "F.Cu")
		(net "SMB_CPU0_SEC_SDA")
	)
	(segment
		(start 243.852192 -205.185772)
		(end 243.852192 -190.560452)
		(width 0.10668)
		(layer "F.Cu")
		(net "SMB_CPU0_SEC_SDA")
	)
	(via
		(at 241.672364 -207.3656)
		(size 0.508)
		(drill 0.254)
		(layers "F.Cu" "B.Cu")
		(net "SMB_CPU0_SEC_SDA")
	)
	(via
		(at 240.411 -232.660952)
		(size 0.508)
		(drill 0.254)
		(layers "F.Cu" "B.Cu")
		(net "SMB_CPU0_SEC_SDA")
	)
	(via
		(at 237.322106 -169.807382)
		(size 0.508)
		(drill 0.254)
		(layers "F.Cu" "B.Cu")
		(net "SMB_CPU0_SEC_SDA")
	)
	(via
		(at 382.744726 -224.234248)
		(size 0.4064)
		(drill 0.2032)
		(layers "F.Cu" "B.Cu")
		(net "SMB_CPU0_SEC_SDA")
	)
	(segment
		(start 240.411 -232.660952)
		(end 240.411 -232.04805)
		(width 0.10668)
		(layer "B.Cu")
		(net "SMB_CPU0_SEC_SDA")
	)
	(segment
		(start 240.411 -233.66095)
		(end 240.411 -232.660952)
		(width 0.10668)
		(layer "B.Cu")
		(net "SMB_CPU0_SEC_SDA")
	)
	(segment
		(start 240.411 -232.660952)
		(end 241.246406 -233.496358)
		(width 0.11684)
		(layer "In4.Cu")
		(net "SMB_CPU0_SEC_SDA")
	)
	(segment
		(start 246.137176 -211.830412)
		(end 241.672364 -207.3656)
		(width 0.11684)
		(layer "In4.Cu")
		(net "SMB_CPU0_SEC_SDA")
	)
	(segment
		(start 241.246406 -233.496358)
		(end 243.63934 -233.496358)
		(width 0.11684)
		(layer "In4.Cu")
		(net "SMB_CPU0_SEC_SDA")
	)
	(segment
		(start 246.137176 -230.998522)
		(end 246.137176 -211.830412)
		(width 0.11684)
		(layer "In4.Cu")
		(net "SMB_CPU0_SEC_SDA")
	)
	(segment
		(start 243.63934 -233.496358)
		(end 246.137176 -230.998522)
		(width 0.11684)
		(layer "In4.Cu")
		(net "SMB_CPU0_SEC_SDA")
	)
	(segment
		(start 238.172752 -170.658028)
		(end 254.921258 -170.658028)
		(width 0.11684)
		(layer "In6.Cu")
		(net "SMB_CPU0_SEC_SDA")
	)
	(segment
		(start 371.651276 -211.06257)
		(end 376.319542 -211.06257)
		(width 0.11684)
		(layer "In6.Cu")
		(net "SMB_CPU0_SEC_SDA")
	)
	(segment
		(start 314.392056 -172.510704)
		(end 333.09941 -172.510704)
		(width 0.11684)
		(layer "In6.Cu")
		(net "SMB_CPU0_SEC_SDA")
	)
	(segment
		(start 382.744726 -223.23298)
		(end 382.744726 -224.234248)
		(width 0.11684)
		(layer "In6.Cu")
		(net "SMB_CPU0_SEC_SDA")
	)
	(segment
		(start 382.174496 -216.917524)
		(end 382.174496 -222.66275)
		(width 0.11684)
		(layer "In6.Cu")
		(net "SMB_CPU0_SEC_SDA")
	)
	(segment
		(start 237.322106 -169.807382)
		(end 238.172752 -170.658028)
		(width 0.11684)
		(layer "In6.Cu")
		(net "SMB_CPU0_SEC_SDA")
	)
	(segment
		(start 254.921258 -170.658028)
		(end 256.749296 -168.82999)
		(width 0.11684)
		(layer "In6.Cu")
		(net "SMB_CPU0_SEC_SDA")
	)
	(segment
		(start 382.174496 -222.66275)
		(end 382.744726 -223.23298)
		(width 0.11684)
		(layer "In6.Cu")
		(net "SMB_CPU0_SEC_SDA")
	)
	(segment
		(start 333.09941 -172.510704)
		(end 371.651276 -211.06257)
		(width 0.11684)
		(layer "In6.Cu")
		(net "SMB_CPU0_SEC_SDA")
	)
	(segment
		(start 256.749296 -168.82999)
		(end 310.711342 -168.82999)
		(width 0.11684)
		(layer "In6.Cu")
		(net "SMB_CPU0_SEC_SDA")
	)
	(segment
		(start 376.319542 -211.06257)
		(end 382.174496 -216.917524)
		(width 0.11684)
		(layer "In6.Cu")
		(net "SMB_CPU0_SEC_SDA")
	)
	(segment
		(start 310.711342 -168.82999)
		(end 314.392056 -172.510704)
		(width 0.11684)
		(layer "In6.Cu")
		(net "SMB_CPU0_SEC_SDA")
	)
	(segment
		(start 243.511832 -190.628524)
		(end 243.511832 -205.044548)
		(width 0.10668)
		(layer "F.Cu")
		(net "SMB_CPU0_SEC_SCL")
	)
	(segment
		(start 241.176302 -205.821534)
		(end 240.955576 -206.04226)
		(width 0.10668)
		(layer "F.Cu")
		(net "SMB_CPU0_SEC_SCL")
	)
	(segment
		(start 382.277874 -222.880174)
		(end 382.744726 -222.614236)
		(width 0.10668)
		(layer "F.Cu")
		(net "SMB_CPU0_SEC_SCL")
	)
	(segment
		(start 242.734846 -205.821534)
		(end 241.176302 -205.821534)
		(width 0.10668)
		(layer "F.Cu")
		(net "SMB_CPU0_SEC_SCL")
	)
	(segment
		(start 237.372906 -168.820592)
		(end 236.834426 -169.359072)
		(width 0.10668)
		(layer "F.Cu")
		(net "SMB_CPU0_SEC_SCL")
	)
	(segment
		(start 236.834426 -174.50689)
		(end 243.511832 -190.628524)
		(width 0.10668)
		(layer "F.Cu")
		(net "SMB_CPU0_SEC_SCL")
	)
	(segment
		(start 236.834426 -169.359072)
		(end 236.834426 -174.50689)
		(width 0.10668)
		(layer "F.Cu")
		(net "SMB_CPU0_SEC_SCL")
	)
	(segment
		(start 243.511832 -205.044548)
		(end 242.734846 -205.821534)
		(width 0.10668)
		(layer "F.Cu")
		(net "SMB_CPU0_SEC_SCL")
	)
	(via
		(at 240.955576 -206.04226)
		(size 0.508)
		(drill 0.254)
		(layers "F.Cu" "B.Cu")
		(net "SMB_CPU0_SEC_SCL")
	)
	(via
		(at 382.744726 -222.614236)
		(size 0.4064)
		(drill 0.2032)
		(layers "F.Cu" "B.Cu")
		(net "SMB_CPU0_SEC_SCL")
	)
	(via
		(at 237.372906 -168.820592)
		(size 0.508)
		(drill 0.254)
		(layers "F.Cu" "B.Cu")
		(net "SMB_CPU0_SEC_SCL")
	)
	(via
		(at 242.443 -232.660952)
		(size 0.508)
		(drill 0.254)
		(layers "F.Cu" "B.Cu")
		(net "SMB_CPU0_SEC_SCL")
	)
	(segment
		(start 242.443 -232.660952)
		(end 242.443 -232.04805)
		(width 0.10668)
		(layer "B.Cu")
		(net "SMB_CPU0_SEC_SCL")
	)
	(segment
		(start 242.443 -233.66095)
		(end 242.443 -232.660952)
		(width 0.10668)
		(layer "B.Cu")
		(net "SMB_CPU0_SEC_SCL")
	)
	(segment
		(start 245.680992 -212.094064)
		(end 245.680992 -230.809546)
		(width 0.11684)
		(layer "In4.Cu")
		(net "SMB_CPU0_SEC_SCL")
	)
	(segment
		(start 240.955576 -206.04226)
		(end 240.955576 -207.368648)
		(width 0.11684)
		(layer "In4.Cu")
		(net "SMB_CPU0_SEC_SCL")
	)
	(segment
		(start 245.680992 -230.809546)
		(end 243.829586 -232.660952)
		(width 0.11684)
		(layer "In4.Cu")
		(net "SMB_CPU0_SEC_SCL")
	)
	(segment
		(start 243.829586 -232.660952)
		(end 242.443 -232.660952)
		(width 0.11684)
		(layer "In4.Cu")
		(net "SMB_CPU0_SEC_SCL")
	)
	(segment
		(start 240.955576 -207.368648)
		(end 245.680992 -212.094064)
		(width 0.11684)
		(layer "In4.Cu")
		(net "SMB_CPU0_SEC_SCL")
	)
	(segment
		(start 372.462806 -206.52613)
		(end 382.744726 -216.80805)
		(width 0.11684)
		(layer "In6.Cu")
		(net "SMB_CPU0_SEC_SCL")
	)
	(segment
		(start 237.912402 -169.360088)
		(end 255.289558 -169.360088)
		(width 0.11684)
		(layer "In6.Cu")
		(net "SMB_CPU0_SEC_SCL")
	)
	(segment
		(start 382.744726 -216.80805)
		(end 382.744726 -222.614236)
		(width 0.11684)
		(layer "In6.Cu")
		(net "SMB_CPU0_SEC_SCL")
	)
	(segment
		(start 310.92521 -168.40835)
		(end 314.578238 -172.061378)
		(width 0.11684)
		(layer "In6.Cu")
		(net "SMB_CPU0_SEC_SCL")
	)
	(segment
		(start 333.285592 -172.061378)
		(end 367.750344 -206.52613)
		(width 0.11684)
		(layer "In6.Cu")
		(net "SMB_CPU0_SEC_SCL")
	)
	(segment
		(start 237.372906 -168.820592)
		(end 237.912402 -169.360088)
		(width 0.11684)
		(layer "In6.Cu")
		(net "SMB_CPU0_SEC_SCL")
	)
	(segment
		(start 367.750344 -206.52613)
		(end 372.462806 -206.52613)
		(width 0.11684)
		(layer "In6.Cu")
		(net "SMB_CPU0_SEC_SCL")
	)
	(segment
		(start 255.289558 -169.360088)
		(end 256.241296 -168.40835)
		(width 0.11684)
		(layer "In6.Cu")
		(net "SMB_CPU0_SEC_SCL")
	)
	(segment
		(start 256.241296 -168.40835)
		(end 310.92521 -168.40835)
		(width 0.11684)
		(layer "In6.Cu")
		(net "SMB_CPU0_SEC_SCL")
	)
	(segment
		(start 314.578238 -172.061378)
		(end 333.285592 -172.061378)
		(width 0.11684)
		(layer "In6.Cu")
		(net "SMB_CPU0_SEC_SCL")
	)
	(via
		(at 229.87 -233.299)
		(size 0.508)
		(drill 0.254)
		(layers "F.Cu" "B.Cu")
		(net "SMB_APML_CPU1_R_SDA")
	)
	(via
		(at 234.569 -239.141)
		(size 0.508)
		(drill 0.254)
		(layers "F.Cu" "B.Cu")
		(net "SMB_APML_CPU1_R_SDA")
	)
	(segment
		(start 229.87 -232.55605)
		(end 229.87 -233.299)
		(width 0.10668)
		(layer "B.Cu")
		(net "SMB_APML_CPU1_R_SDA")
	)
	(segment
		(start 234.569 -240.01095)
		(end 234.569 -239.141)
		(width 0.10668)
		(layer "B.Cu")
		(net "SMB_APML_CPU1_R_SDA")
	)
	(segment
		(start 230.388414 -233.817414)
		(end 229.87 -233.299)
		(width 0.10668)
		(layer "B.Cu")
		(net "SMB_APML_CPU1_R_SDA")
	)
	(segment
		(start 230.388414 -234.699302)
		(end 230.388414 -233.817414)
		(width 0.10668)
		(layer "B.Cu")
		(net "SMB_APML_CPU1_R_SDA")
	)
	(segment
		(start 229.87 -232.55605)
		(end 228.854 -232.55605)
		(width 0.10668)
		(layer "B.Cu")
		(net "SMB_APML_CPU1_R_SDA")
	)
	(segment
		(start 234.569 -239.141)
		(end 234.569 -237.998)
		(width 0.11684)
		(layer "In2.Cu")
		(net "SMB_APML_CPU1_R_SDA")
	)
	(segment
		(start 234.569 -237.998)
		(end 229.87 -233.299)
		(width 0.11684)
		(layer "In2.Cu")
		(net "SMB_APML_CPU1_R_SDA")
	)
	(via
		(at 235.839 -239.141)
		(size 0.508)
		(drill 0.254)
		(layers "F.Cu" "B.Cu")
		(net "SMB_APML_CPU1_R_SCL")
	)
	(via
		(at 232.918 -233.299)
		(size 0.508)
		(drill 0.254)
		(layers "F.Cu" "B.Cu")
		(net "SMB_APML_CPU1_R_SCL")
	)
	(segment
		(start 232.918 -233.299)
		(end 232.918 -232.55605)
		(width 0.10668)
		(layer "B.Cu")
		(net "SMB_APML_CPU1_R_SCL")
	)
	(segment
		(start 232.17505 -233.299)
		(end 232.918 -233.299)
		(width 0.10668)
		(layer "B.Cu")
		(net "SMB_APML_CPU1_R_SCL")
	)
	(segment
		(start 231.388412 -234.699302)
		(end 231.388412 -234.085638)
		(width 0.10668)
		(layer "B.Cu")
		(net "SMB_APML_CPU1_R_SCL")
	)
	(segment
		(start 235.839 -240.01095)
		(end 235.839 -239.141)
		(width 0.10668)
		(layer "B.Cu")
		(net "SMB_APML_CPU1_R_SCL")
	)
	(segment
		(start 231.388412 -234.085638)
		(end 232.17505 -233.299)
		(width 0.10668)
		(layer "B.Cu")
		(net "SMB_APML_CPU1_R_SCL")
	)
	(segment
		(start 233.122724 -233.503724)
		(end 233.122724 -234.48391)
		(width 0.11684)
		(layer "In2.Cu")
		(net "SMB_APML_CPU1_R_SCL")
	)
	(segment
		(start 232.918 -233.299)
		(end 233.122724 -233.503724)
		(width 0.11684)
		(layer "In2.Cu")
		(net "SMB_APML_CPU1_R_SCL")
	)
	(segment
		(start 233.122724 -234.48391)
		(end 235.839 -237.200186)
		(width 0.11684)
		(layer "In2.Cu")
		(net "SMB_APML_CPU1_R_SCL")
	)
	(segment
		(start 235.839 -237.200186)
		(end 235.839 -239.141)
		(width 0.11684)
		(layer "In2.Cu")
		(net "SMB_APML_CPU1_R_SCL")
	)
	(segment
		(start 176.528984 -147.486624)
		(end 177.544984 -147.486624)
		(width 0.10668)
		(layer "F.Cu")
		(net "SMB_CPU0_4_XLTR_SDA")
	)
	(segment
		(start 177.862484 -149.589236)
		(end 177.862484 -149.164548)
		(width 0.10668)
		(layer "F.Cu")
		(net "SMB_CPU0_4_XLTR_SDA")
	)
	(segment
		(start 177.544984 -148.847048)
		(end 177.544984 -148.102574)
		(width 0.10668)
		(layer "F.Cu")
		(net "SMB_CPU0_4_XLTR_SDA")
	)
	(segment
		(start 177.862484 -149.164548)
		(end 177.544984 -148.847048)
		(width 0.10668)
		(layer "F.Cu")
		(net "SMB_CPU0_4_XLTR_SDA")
	)
	(segment
		(start 177.544984 -147.486624)
		(end 177.544984 -148.102574)
		(width 0.10668)
		(layer "F.Cu")
		(net "SMB_CPU0_4_XLTR_SDA")
	)
	(via
		(at 177.544984 -148.102574)
		(size 0.508)
		(drill 0.254)
		(layers "F.Cu" "B.Cu")
		(net "SMB_CPU0_4_XLTR_SDA")
	)
	(segment
		(start 178.512724 -149.152356)
		(end 178.830224 -148.834856)
		(width 0.10668)
		(layer "F.Cu")
		(net "SMB_CPU0_4_XLTR_SCL")
	)
	(segment
		(start 179.846224 -147.486624)
		(end 178.830224 -147.486624)
		(width 0.10668)
		(layer "F.Cu")
		(net "SMB_CPU0_4_XLTR_SCL")
	)
	(segment
		(start 178.830224 -148.834856)
		(end 178.830224 -148.102574)
		(width 0.10668)
		(layer "F.Cu")
		(net "SMB_CPU0_4_XLTR_SCL")
	)
	(segment
		(start 178.512724 -149.589236)
		(end 178.512724 -149.152356)
		(width 0.10668)
		(layer "F.Cu")
		(net "SMB_CPU0_4_XLTR_SCL")
	)
	(segment
		(start 178.830224 -147.486624)
		(end 178.830224 -148.102574)
		(width 0.10668)
		(layer "F.Cu")
		(net "SMB_CPU0_4_XLTR_SCL")
	)
	(via
		(at 178.830224 -148.102574)
		(size 0.508)
		(drill 0.254)
		(layers "F.Cu" "B.Cu")
		(net "SMB_CPU0_4_XLTR_SCL")
	)
	(segment
		(start 181.122066 -114.652806)
		(end 180.732176 -114.262916)
		(width 0.10668)
		(layer "F.Cu")
		(net "SMB_CPU0_4_XLTR_R_SDA")
	)
	(segment
		(start 176.528984 -146.686524)
		(end 176.528984 -146.070574)
		(width 0.10668)
		(layer "F.Cu")
		(net "SMB_CPU0_4_XLTR_R_SDA")
	)
	(via
		(at 176.528984 -146.070574)
		(size 0.508)
		(drill 0.254)
		(layers "F.Cu" "B.Cu")
		(net "SMB_CPU0_4_XLTR_R_SDA")
	)
	(via
		(at 180.732176 -114.262916)
		(size 0.4572)
		(drill 0.254)
		(layers "F.Cu" "B.Cu")
		(net "SMB_CPU0_4_XLTR_R_SDA")
	)
	(segment
		(start 180.732176 -114.262916)
		(end 180.732176 -115.065556)
		(width 0.11684)
		(layer "In4.Cu")
		(net "SMB_CPU0_4_XLTR_R_SDA")
	)
	(segment
		(start 180.332126 -124.034804)
		(end 175.394112 -128.972818)
		(width 0.11684)
		(layer "In4.Cu")
		(net "SMB_CPU0_4_XLTR_R_SDA")
	)
	(segment
		(start 176.528984 -142.006574)
		(end 176.528984 -146.070574)
		(width 0.11684)
		(layer "In4.Cu")
		(net "SMB_CPU0_4_XLTR_R_SDA")
	)
	(segment
		(start 175.394112 -140.871702)
		(end 176.528984 -142.006574)
		(width 0.11684)
		(layer "In4.Cu")
		(net "SMB_CPU0_4_XLTR_R_SDA")
	)
	(segment
		(start 180.332126 -115.465606)
		(end 180.332126 -124.034804)
		(width 0.11684)
		(layer "In4.Cu")
		(net "SMB_CPU0_4_XLTR_R_SDA")
	)
	(segment
		(start 175.394112 -128.972818)
		(end 175.394112 -140.871702)
		(width 0.11684)
		(layer "In4.Cu")
		(net "SMB_CPU0_4_XLTR_R_SDA")
	)
	(segment
		(start 180.732176 -115.065556)
		(end 180.332126 -115.465606)
		(width 0.11684)
		(layer "In4.Cu")
		(net "SMB_CPU0_4_XLTR_R_SDA")
	)
	(segment
		(start 179.846224 -146.686524)
		(end 179.846224 -146.070574)
		(width 0.10668)
		(layer "F.Cu")
		(net "SMB_CPU0_4_XLTR_R_SCL")
	)
	(segment
		(start 181.922166 -114.652806)
		(end 181.532276 -114.262916)
		(width 0.10668)
		(layer "F.Cu")
		(net "SMB_CPU0_4_XLTR_R_SCL")
	)
	(via
		(at 181.532276 -114.262916)
		(size 0.4572)
		(drill 0.254)
		(layers "F.Cu" "B.Cu")
		(net "SMB_CPU0_4_XLTR_R_SCL")
	)
	(via
		(at 179.846224 -146.070574)
		(size 0.508)
		(drill 0.254)
		(layers "F.Cu" "B.Cu")
		(net "SMB_CPU0_4_XLTR_R_SCL")
	)
	(segment
		(start 181.532276 -114.262916)
		(end 181.532276 -115.065302)
		(width 0.11684)
		(layer "In4.Cu")
		(net "SMB_CPU0_4_XLTR_R_SCL")
	)
	(segment
		(start 179.846224 -144.213326)
		(end 179.846224 -146.070574)
		(width 0.11684)
		(layer "In4.Cu")
		(net "SMB_CPU0_4_XLTR_R_SCL")
	)
	(segment
		(start 175.827182 -129.13614)
		(end 175.827182 -140.194284)
		(width 0.11684)
		(layer "In4.Cu")
		(net "SMB_CPU0_4_XLTR_R_SCL")
	)
	(segment
		(start 175.827182 -140.194284)
		(end 179.846224 -144.213326)
		(width 0.11684)
		(layer "In4.Cu")
		(net "SMB_CPU0_4_XLTR_R_SCL")
	)
	(segment
		(start 181.532276 -115.065302)
		(end 181.131972 -115.465606)
		(width 0.11684)
		(layer "In4.Cu")
		(net "SMB_CPU0_4_XLTR_R_SCL")
	)
	(segment
		(start 181.131972 -115.465606)
		(end 181.131972 -123.83135)
		(width 0.11684)
		(layer "In4.Cu")
		(net "SMB_CPU0_4_XLTR_R_SCL")
	)
	(segment
		(start 181.131972 -123.83135)
		(end 175.827182 -129.13614)
		(width 0.11684)
		(layer "In4.Cu")
		(net "SMB_CPU0_4_XLTR_R_SCL")
	)
	(segment
		(start 215.811608 -186.88177)
		(end 215.811608 -201.989436)
		(width 0.10668)
		(layer "F.Cu")
		(net "SMB_CPU0_4_SDA")
	)
	(segment
		(start 177.458116 -156.192982)
		(end 177.458116 -157.105858)
		(width 0.10668)
		(layer "F.Cu")
		(net "SMB_CPU0_4_SDA")
	)
	(segment
		(start 177.019712 -155.754578)
		(end 177.458116 -156.192982)
		(width 0.10668)
		(layer "F.Cu")
		(net "SMB_CPU0_4_SDA")
	)
	(segment
		(start 215.811608 -201.989436)
		(end 219.192602 -205.37043)
		(width 0.10668)
		(layer "F.Cu")
		(net "SMB_CPU0_4_SDA")
	)
	(segment
		(start 207.66405 -167.213026)
		(end 215.811608 -186.88177)
		(width 0.10668)
		(layer "F.Cu")
		(net "SMB_CPU0_4_SDA")
	)
	(segment
		(start 176.781206 -158.2039)
		(end 177.292254 -158.714948)
		(width 0.10668)
		(layer "F.Cu")
		(net "SMB_CPU0_4_SDA")
	)
	(segment
		(start 177.862484 -154.911806)
		(end 177.019712 -155.754578)
		(width 0.10668)
		(layer "F.Cu")
		(net "SMB_CPU0_4_SDA")
	)
	(segment
		(start 219.192602 -205.37043)
		(end 219.854526 -205.37043)
		(width 0.10668)
		(layer "F.Cu")
		(net "SMB_CPU0_4_SDA")
	)
	(segment
		(start 176.781206 -157.447488)
		(end 176.781206 -158.2039)
		(width 0.10668)
		(layer "F.Cu")
		(net "SMB_CPU0_4_SDA")
	)
	(segment
		(start 180.937408 -157.86354)
		(end 185.092848 -157.86354)
		(width 0.10668)
		(layer "F.Cu")
		(net "SMB_CPU0_4_SDA")
	)
	(segment
		(start 180.086 -158.714948)
		(end 180.937408 -157.86354)
		(width 0.10668)
		(layer "F.Cu")
		(net "SMB_CPU0_4_SDA")
	)
	(segment
		(start 185.092848 -157.86354)
		(end 207.66405 -167.213026)
		(width 0.10668)
		(layer "F.Cu")
		(net "SMB_CPU0_4_SDA")
	)
	(segment
		(start 177.45583 -157.108144)
		(end 177.12055 -157.108144)
		(width 0.10668)
		(layer "F.Cu")
		(net "SMB_CPU0_4_SDA")
	)
	(segment
		(start 177.292254 -158.714948)
		(end 180.086 -158.714948)
		(width 0.10668)
		(layer "F.Cu")
		(net "SMB_CPU0_4_SDA")
	)
	(segment
		(start 177.862484 -153.93924)
		(end 177.862484 -154.911806)
		(width 0.10668)
		(layer "F.Cu")
		(net "SMB_CPU0_4_SDA")
	)
	(segment
		(start 177.12055 -157.108144)
		(end 176.781206 -157.447488)
		(width 0.10668)
		(layer "F.Cu")
		(net "SMB_CPU0_4_SDA")
	)
	(segment
		(start 177.458116 -157.105858)
		(end 177.45583 -157.108144)
		(width 0.10668)
		(layer "F.Cu")
		(net "SMB_CPU0_4_SDA")
	)
	(via
		(at 177.019712 -155.754578)
		(size 0.508)
		(drill 0.254)
		(layers "F.Cu" "B.Cu")
		(net "SMB_CPU0_4_SDA")
	)
	(via
		(at 219.854526 -205.37043)
		(size 0.508)
		(drill 0.254)
		(layers "F.Cu" "B.Cu")
		(net "SMB_CPU0_4_SDA")
	)
	(via
		(at 404.722838 -322.950332)
		(size 0.508)
		(drill 0.254)
		(layers "F.Cu" "B.Cu")
		(net "SMB_CPU0_4_SDA")
	)
	(segment
		(start 405.086058 -320.148966)
		(end 404.722838 -320.512186)
		(width 0.10668)
		(layer "B.Cu")
		(net "SMB_CPU0_4_SDA")
	)
	(segment
		(start 404.722838 -320.512186)
		(end 404.722838 -322.950332)
		(width 0.10668)
		(layer "B.Cu")
		(net "SMB_CPU0_4_SDA")
	)
	(segment
		(start 270.679164 -362.010198)
		(end 273.33702 -362.010198)
		(width 0.11684)
		(layer "In2.Cu")
		(net "SMB_CPU0_4_SDA")
	)
	(segment
		(start 403.462744 -319.009268)
		(end 404.722838 -320.269362)
		(width 0.11684)
		(layer "In2.Cu")
		(net "SMB_CPU0_4_SDA")
	)
	(segment
		(start 296.414444 -370.607336)
		(end 297.106848 -371.29974)
		(width 0.11684)
		(layer "In2.Cu")
		(net "SMB_CPU0_4_SDA")
	)
	(segment
		(start 222.136716 -207.65262)
		(end 222.136716 -244.188234)
		(width 0.11684)
		(layer "In2.Cu")
		(net "SMB_CPU0_4_SDA")
	)
	(segment
		(start 295.651174 -370.607336)
		(end 296.414444 -370.607336)
		(width 0.11684)
		(layer "In2.Cu")
		(net "SMB_CPU0_4_SDA")
	)
	(segment
		(start 295.366186 -370.322348)
		(end 295.651174 -370.607336)
		(width 0.11684)
		(layer "In2.Cu")
		(net "SMB_CPU0_4_SDA")
	)
	(segment
		(start 391.313924 -312.94197)
		(end 394.162788 -315.790834)
		(width 0.11684)
		(layer "In2.Cu")
		(net "SMB_CPU0_4_SDA")
	)
	(segment
		(start 254.55245 -269.479522)
		(end 254.55245 -328.868786)
		(width 0.11684)
		(layer "In2.Cu")
		(net "SMB_CPU0_4_SDA")
	)
	(segment
		(start 351.652586 -365.861346)
		(end 382.129792 -335.38414)
		(width 0.11684)
		(layer "In2.Cu")
		(net "SMB_CPU0_4_SDA")
	)
	(segment
		(start 390.624314 -312.94197)
		(end 391.313924 -312.94197)
		(width 0.11684)
		(layer "In2.Cu")
		(net "SMB_CPU0_4_SDA")
	)
	(segment
		(start 388.213346 -312.836814)
		(end 390.519158 -312.836814)
		(width 0.11684)
		(layer "In2.Cu")
		(net "SMB_CPU0_4_SDA")
	)
	(segment
		(start 394.162788 -317.71082)
		(end 395.461236 -319.009268)
		(width 0.11684)
		(layer "In2.Cu")
		(net "SMB_CPU0_4_SDA")
	)
	(segment
		(start 222.136716 -244.188234)
		(end 232.475024 -254.526542)
		(width 0.11684)
		(layer "In2.Cu")
		(net "SMB_CPU0_4_SDA")
	)
	(segment
		(start 253.906274 -266.228068)
		(end 254.55245 -269.479522)
		(width 0.11684)
		(layer "In2.Cu")
		(net "SMB_CPU0_4_SDA")
	)
	(segment
		(start 251.17933 -332.241906)
		(end 251.17933 -342.510364)
		(width 0.11684)
		(layer "In2.Cu")
		(net "SMB_CPU0_4_SDA")
	)
	(segment
		(start 395.461236 -319.009268)
		(end 403.462744 -319.009268)
		(width 0.11684)
		(layer "In2.Cu")
		(net "SMB_CPU0_4_SDA")
	)
	(segment
		(start 251.17933 -342.510364)
		(end 270.679164 -362.010198)
		(width 0.11684)
		(layer "In2.Cu")
		(net "SMB_CPU0_4_SDA")
	)
	(segment
		(start 290.879022 -370.322348)
		(end 295.366186 -370.322348)
		(width 0.11684)
		(layer "In2.Cu")
		(net "SMB_CPU0_4_SDA")
	)
	(segment
		(start 242.204748 -254.526542)
		(end 253.906274 -266.228068)
		(width 0.11684)
		(layer "In2.Cu")
		(net "SMB_CPU0_4_SDA")
	)
	(segment
		(start 288.955988 -368.399314)
		(end 290.879022 -370.322348)
		(width 0.11684)
		(layer "In2.Cu")
		(net "SMB_CPU0_4_SDA")
	)
	(segment
		(start 394.162788 -315.790834)
		(end 394.162788 -317.71082)
		(width 0.11684)
		(layer "In2.Cu")
		(net "SMB_CPU0_4_SDA")
	)
	(segment
		(start 390.519158 -312.836814)
		(end 390.624314 -312.94197)
		(width 0.11684)
		(layer "In2.Cu")
		(net "SMB_CPU0_4_SDA")
	)
	(segment
		(start 274.168108 -362.841286)
		(end 276.81936 -362.841286)
		(width 0.11684)
		(layer "In2.Cu")
		(net "SMB_CPU0_4_SDA")
	)
	(segment
		(start 404.722838 -320.269362)
		(end 404.722838 -322.950332)
		(width 0.11684)
		(layer "In2.Cu")
		(net "SMB_CPU0_4_SDA")
	)
	(segment
		(start 254.55245 -328.868786)
		(end 251.17933 -332.241906)
		(width 0.11684)
		(layer "In2.Cu")
		(net "SMB_CPU0_4_SDA")
	)
	(segment
		(start 273.33702 -362.010198)
		(end 274.168108 -362.841286)
		(width 0.11684)
		(layer "In2.Cu")
		(net "SMB_CPU0_4_SDA")
	)
	(segment
		(start 282.377388 -368.399314)
		(end 288.955988 -368.399314)
		(width 0.11684)
		(layer "In2.Cu")
		(net "SMB_CPU0_4_SDA")
	)
	(segment
		(start 219.854526 -205.37043)
		(end 222.136716 -207.65262)
		(width 0.11684)
		(layer "In2.Cu")
		(net "SMB_CPU0_4_SDA")
	)
	(segment
		(start 321.175888 -371.29974)
		(end 351.652586 -365.861346)
		(width 0.11684)
		(layer "In2.Cu")
		(net "SMB_CPU0_4_SDA")
	)
	(segment
		(start 276.81936 -362.841286)
		(end 282.377388 -368.399314)
		(width 0.11684)
		(layer "In2.Cu")
		(net "SMB_CPU0_4_SDA")
	)
	(segment
		(start 382.129792 -335.38414)
		(end 382.129792 -318.920368)
		(width 0.11684)
		(layer "In2.Cu")
		(net "SMB_CPU0_4_SDA")
	)
	(segment
		(start 382.129792 -318.920368)
		(end 388.213346 -312.836814)
		(width 0.11684)
		(layer "In2.Cu")
		(net "SMB_CPU0_4_SDA")
	)
	(segment
		(start 297.106848 -371.29974)
		(end 321.175888 -371.29974)
		(width 0.11684)
		(layer "In2.Cu")
		(net "SMB_CPU0_4_SDA")
	)
	(segment
		(start 232.475024 -254.526542)
		(end 242.204748 -254.526542)
		(width 0.11684)
		(layer "In2.Cu")
		(net "SMB_CPU0_4_SDA")
	)
	(segment
		(start 185.269632 -157.43682)
		(end 207.633062 -166.700454)
		(width 0.10668)
		(layer "F.Cu")
		(net "SMB_CPU0_4_SCL")
	)
	(segment
		(start 178.47183 -157.108144)
		(end 178.512724 -157.06725)
		(width 0.10668)
		(layer "F.Cu")
		(net "SMB_CPU0_4_SCL")
	)
	(segment
		(start 207.633062 -166.700454)
		(end 207.953102 -167.020494)
		(width 0.10668)
		(layer "F.Cu")
		(net "SMB_CPU0_4_SCL")
	)
	(segment
		(start 216.151968 -201.726292)
		(end 219.161106 -204.73543)
		(width 0.10668)
		(layer "F.Cu")
		(net "SMB_CPU0_4_SCL")
	)
	(segment
		(start 219.161106 -204.73543)
		(end 219.854526 -204.73543)
		(width 0.10668)
		(layer "F.Cu")
		(net "SMB_CPU0_4_SCL")
	)
	(segment
		(start 180.459126 -157.43682)
		(end 185.269632 -157.43682)
		(width 0.10668)
		(layer "F.Cu")
		(net "SMB_CPU0_4_SCL")
	)
	(segment
		(start 207.953102 -167.020494)
		(end 216.151968 -186.81319)
		(width 0.10668)
		(layer "F.Cu")
		(net "SMB_CPU0_4_SCL")
	)
	(segment
		(start 178.512724 -153.93924)
		(end 178.512724 -155.769056)
		(width 0.10668)
		(layer "F.Cu")
		(net "SMB_CPU0_4_SCL")
	)
	(segment
		(start 180.13045 -157.108144)
		(end 180.459126 -157.43682)
		(width 0.10668)
		(layer "F.Cu")
		(net "SMB_CPU0_4_SCL")
	)
	(segment
		(start 178.512724 -157.06725)
		(end 178.512724 -155.769056)
		(width 0.10668)
		(layer "F.Cu")
		(net "SMB_CPU0_4_SCL")
	)
	(segment
		(start 216.151968 -186.81319)
		(end 216.151968 -201.726292)
		(width 0.10668)
		(layer "F.Cu")
		(net "SMB_CPU0_4_SCL")
	)
	(segment
		(start 178.47183 -157.108144)
		(end 180.13045 -157.108144)
		(width 0.10668)
		(layer "F.Cu")
		(net "SMB_CPU0_4_SCL")
	)
	(via
		(at 178.512724 -155.769056)
		(size 0.508)
		(drill 0.254)
		(layers "F.Cu" "B.Cu")
		(net "SMB_CPU0_4_SCL")
	)
	(via
		(at 404.070058 -322.930012)
		(size 0.508)
		(drill 0.254)
		(layers "F.Cu" "B.Cu")
		(net "SMB_CPU0_4_SCL")
	)
	(via
		(at 219.854526 -204.73543)
		(size 0.508)
		(drill 0.254)
		(layers "F.Cu" "B.Cu")
		(net "SMB_CPU0_4_SCL")
	)
	(segment
		(start 404.18004 -322.82003)
		(end 404.070058 -322.930012)
		(width 0.10668)
		(layer "B.Cu")
		(net "SMB_CPU0_4_SCL")
	)
	(segment
		(start 404.18004 -320.258948)
		(end 404.18004 -322.82003)
		(width 0.10668)
		(layer "B.Cu")
		(net "SMB_CPU0_4_SCL")
	)
	(segment
		(start 404.070058 -320.148966)
		(end 404.18004 -320.258948)
		(width 0.10668)
		(layer "B.Cu")
		(net "SMB_CPU0_4_SCL")
	)
	(segment
		(start 277.376128 -363.994446)
		(end 272.093944 -363.994446)
		(width 0.11684)
		(layer "In2.Cu")
		(net "SMB_CPU0_4_SCL")
	)
	(segment
		(start 404.168102 -320.311272)
		(end 403.29993 -319.4431)
		(width 0.11684)
		(layer "In2.Cu")
		(net "SMB_CPU0_4_SCL")
	)
	(segment
		(start 403.29993 -319.4431)
		(end 395.23924 -319.4431)
		(width 0.11684)
		(layer "In2.Cu")
		(net "SMB_CPU0_4_SCL")
	)
	(segment
		(start 388.244842 -314.426854)
		(end 382.551432 -320.120264)
		(width 0.11684)
		(layer "In2.Cu")
		(net "SMB_CPU0_4_SCL")
	)
	(segment
		(start 321.213988 -371.72138)
		(end 296.921174 -371.72138)
		(width 0.11684)
		(layer "In2.Cu")
		(net "SMB_CPU0_4_SCL")
	)
	(segment
		(start 271.4498 -363.350302)
		(end 271.422876 -363.350302)
		(width 0.11684)
		(layer "In2.Cu")
		(net "SMB_CPU0_4_SCL")
	)
	(segment
		(start 393.707874 -317.911734)
		(end 393.707874 -315.936122)
		(width 0.11684)
		(layer "In2.Cu")
		(net "SMB_CPU0_4_SCL")
	)
	(segment
		(start 271.422876 -363.350302)
		(end 256.025142 -347.952568)
		(width 0.11684)
		(layer "In2.Cu")
		(net "SMB_CPU0_4_SCL")
	)
	(segment
		(start 393.707874 -315.936122)
		(end 391.566908 -313.795156)
		(width 0.11684)
		(layer "In2.Cu")
		(net "SMB_CPU0_4_SCL")
	)
	(segment
		(start 221.715076 -244.362986)
		(end 221.715076 -207.900016)
		(width 0.11684)
		(layer "In2.Cu")
		(net "SMB_CPU0_4_SCL")
	)
	(segment
		(start 250.691142 -331.684884)
		(end 252.672088 -329.703938)
		(width 0.11684)
		(layer "In2.Cu")
		(net "SMB_CPU0_4_SCL")
	)
	(segment
		(start 404.168102 -322.831968)
		(end 404.168102 -320.311272)
		(width 0.11684)
		(layer "In2.Cu")
		(net "SMB_CPU0_4_SCL")
	)
	(segment
		(start 351.860358 -366.253014)
		(end 321.213988 -371.72138)
		(width 0.11684)
		(layer "In2.Cu")
		(net "SMB_CPU0_4_SCL")
	)
	(segment
		(start 390.255252 -313.795156)
		(end 389.623554 -314.426854)
		(width 0.11684)
		(layer "In2.Cu")
		(net "SMB_CPU0_4_SCL")
	)
	(segment
		(start 219.296742 -204.85227)
		(end 219.413582 -204.73543)
		(width 0.11684)
		(layer "In2.Cu")
		(net "SMB_CPU0_4_SCL")
	)
	(segment
		(start 219.413582 -204.73543)
		(end 219.854526 -204.73543)
		(width 0.11684)
		(layer "In2.Cu")
		(net "SMB_CPU0_4_SCL")
	)
	(segment
		(start 296.3672 -371.167406)
		(end 295.57345 -371.167406)
		(width 0.11684)
		(layer "In2.Cu")
		(net "SMB_CPU0_4_SCL")
	)
	(segment
		(start 282.34894 -368.967258)
		(end 277.376128 -363.994446)
		(width 0.11684)
		(layer "In2.Cu")
		(net "SMB_CPU0_4_SCL")
	)
	(segment
		(start 288.136584 -368.967258)
		(end 282.34894 -368.967258)
		(width 0.11684)
		(layer "In2.Cu")
		(net "SMB_CPU0_4_SCL")
	)
	(segment
		(start 252.672088 -320.966592)
		(end 254.13081 -319.50787)
		(width 0.11684)
		(layer "In2.Cu")
		(net "SMB_CPU0_4_SCL")
	)
	(segment
		(start 252.672088 -329.703938)
		(end 252.672088 -320.966592)
		(width 0.11684)
		(layer "In2.Cu")
		(net "SMB_CPU0_4_SCL")
	)
	(segment
		(start 242.029996 -254.948182)
		(end 232.300272 -254.948182)
		(width 0.11684)
		(layer "In2.Cu")
		(net "SMB_CPU0_4_SCL")
	)
	(segment
		(start 391.566908 -313.795156)
		(end 390.255252 -313.795156)
		(width 0.11684)
		(layer "In2.Cu")
		(net "SMB_CPU0_4_SCL")
	)
	(segment
		(start 254.13081 -269.522194)
		(end 253.517654 -266.43584)
		(width 0.11684)
		(layer "In2.Cu")
		(net "SMB_CPU0_4_SCL")
	)
	(segment
		(start 232.300272 -254.948182)
		(end 221.715076 -244.362986)
		(width 0.11684)
		(layer "In2.Cu")
		(net "SMB_CPU0_4_SCL")
	)
	(segment
		(start 382.551432 -320.120264)
		(end 382.551432 -335.56194)
		(width 0.11684)
		(layer "In2.Cu")
		(net "SMB_CPU0_4_SCL")
	)
	(segment
		(start 296.921174 -371.72138)
		(end 296.3672 -371.167406)
		(width 0.11684)
		(layer "In2.Cu")
		(net "SMB_CPU0_4_SCL")
	)
	(segment
		(start 219.296742 -205.481682)
		(end 219.296742 -204.85227)
		(width 0.11684)
		(layer "In2.Cu")
		(net "SMB_CPU0_4_SCL")
	)
	(segment
		(start 256.025142 -347.952568)
		(end 256.024888 -347.952568)
		(width 0.11684)
		(layer "In2.Cu")
		(net "SMB_CPU0_4_SCL")
	)
	(segment
		(start 295.245282 -370.839238)
		(end 290.008564 -370.839238)
		(width 0.11684)
		(layer "In2.Cu")
		(net "SMB_CPU0_4_SCL")
	)
	(segment
		(start 254.13081 -319.50787)
		(end 254.13081 -269.522194)
		(width 0.11684)
		(layer "In2.Cu")
		(net "SMB_CPU0_4_SCL")
	)
	(segment
		(start 389.623554 -314.426854)
		(end 388.244842 -314.426854)
		(width 0.11684)
		(layer "In2.Cu")
		(net "SMB_CPU0_4_SCL")
	)
	(segment
		(start 290.008564 -370.839238)
		(end 288.136584 -368.967258)
		(width 0.11684)
		(layer "In2.Cu")
		(net "SMB_CPU0_4_SCL")
	)
	(segment
		(start 295.57345 -371.167406)
		(end 295.245282 -370.839238)
		(width 0.11684)
		(layer "In2.Cu")
		(net "SMB_CPU0_4_SCL")
	)
	(segment
		(start 395.23924 -319.4431)
		(end 393.707874 -317.911734)
		(width 0.11684)
		(layer "In2.Cu")
		(net "SMB_CPU0_4_SCL")
	)
	(segment
		(start 256.024888 -347.952568)
		(end 250.691142 -342.618822)
		(width 0.11684)
		(layer "In2.Cu")
		(net "SMB_CPU0_4_SCL")
	)
	(segment
		(start 404.070058 -322.930012)
		(end 404.168102 -322.831968)
		(width 0.11684)
		(layer "In2.Cu")
		(net "SMB_CPU0_4_SCL")
	)
	(segment
		(start 221.715076 -207.900016)
		(end 219.296742 -205.481682)
		(width 0.11684)
		(layer "In2.Cu")
		(net "SMB_CPU0_4_SCL")
	)
	(segment
		(start 272.093944 -363.994446)
		(end 271.4498 -363.350302)
		(width 0.11684)
		(layer "In2.Cu")
		(net "SMB_CPU0_4_SCL")
	)
	(segment
		(start 250.691142 -342.618822)
		(end 250.691142 -331.684884)
		(width 0.11684)
		(layer "In2.Cu")
		(net "SMB_CPU0_4_SCL")
	)
	(segment
		(start 382.551432 -335.56194)
		(end 351.860358 -366.253014)
		(width 0.11684)
		(layer "In2.Cu")
		(net "SMB_CPU0_4_SCL")
	)
	(segment
		(start 253.517654 -266.43584)
		(end 242.029996 -254.948182)
		(width 0.11684)
		(layer "In2.Cu")
		(net "SMB_CPU0_4_SCL")
	)
	(segment
		(start 384.457956 -294.88003)
		(end 384.924808 -295.145968)
		(width 0.10668)
		(layer "F.Cu")
		(net "SMB_CPU0_4_R_SDA")
	)
	(via
		(at 405.340058 -318.180466)
		(size 0.6604)
		(drill 0.3302)
		(layers "F.Cu" "B.Cu")
		(net "SMB_CPU0_4_R_SDA")
	)
	(via
		(at 384.924808 -295.145968)
		(size 0.4064)
		(drill 0.2032)
		(layers "F.Cu" "B.Cu")
		(net "SMB_CPU0_4_R_SDA")
	)
	(segment
		(start 395.427454 -302.96231)
		(end 395.427454 -304.699162)
		(width 0.10668)
		(layer "B.Cu")
		(net "SMB_CPU0_4_R_SDA")
	)
	(segment
		(start 405.340058 -319.094866)
		(end 405.086058 -319.348866)
		(width 0.10668)
		(layer "B.Cu")
		(net "SMB_CPU0_4_R_SDA")
	)
	(segment
		(start 392.506454 -300.04131)
		(end 395.427454 -302.96231)
		(width 0.10668)
		(layer "B.Cu")
		(net "SMB_CPU0_4_R_SDA")
	)
	(segment
		(start 405.340058 -314.611766)
		(end 405.340058 -318.180466)
		(width 0.10668)
		(layer "B.Cu")
		(net "SMB_CPU0_4_R_SDA")
	)
	(segment
		(start 405.340058 -318.180466)
		(end 405.340058 -319.094866)
		(width 0.10668)
		(layer "B.Cu")
		(net "SMB_CPU0_4_R_SDA")
	)
	(segment
		(start 384.924808 -295.145968)
		(end 384.924808 -296.576496)
		(width 0.10668)
		(layer "B.Cu")
		(net "SMB_CPU0_4_R_SDA")
	)
	(segment
		(start 395.427454 -304.699162)
		(end 405.340058 -314.611766)
		(width 0.10668)
		(layer "B.Cu")
		(net "SMB_CPU0_4_R_SDA")
	)
	(segment
		(start 384.924808 -296.576496)
		(end 388.389622 -300.04131)
		(width 0.10668)
		(layer "B.Cu")
		(net "SMB_CPU0_4_R_SDA")
	)
	(segment
		(start 388.389622 -300.04131)
		(end 392.506454 -300.04131)
		(width 0.10668)
		(layer "B.Cu")
		(net "SMB_CPU0_4_R_SDA")
	)
	(segment
		(start 383.988056 -294.070024)
		(end 384.454908 -294.335962)
		(width 0.10668)
		(layer "F.Cu")
		(net "SMB_CPU0_4_R_SCL")
	)
	(via
		(at 404.682198 -316.022228)
		(size 0.6604)
		(drill 0.3302)
		(layers "F.Cu" "B.Cu")
		(net "SMB_CPU0_4_R_SCL")
	)
	(via
		(at 384.454908 -294.335962)
		(size 0.4064)
		(drill 0.2032)
		(layers "F.Cu" "B.Cu")
		(net "SMB_CPU0_4_R_SCL")
	)
	(segment
		(start 384.454908 -294.335962)
		(end 384.454908 -296.688764)
		(width 0.10668)
		(layer "B.Cu")
		(net "SMB_CPU0_4_R_SCL")
	)
	(segment
		(start 395.015974 -303.132998)
		(end 395.015974 -304.86985)
		(width 0.10668)
		(layer "B.Cu")
		(net "SMB_CPU0_4_R_SCL")
	)
	(segment
		(start 404.682198 -314.536074)
		(end 404.682198 -316.022228)
		(width 0.10668)
		(layer "B.Cu")
		(net "SMB_CPU0_4_R_SCL")
	)
	(segment
		(start 388.218934 -300.45279)
		(end 392.335766 -300.45279)
		(width 0.10668)
		(layer "B.Cu")
		(net "SMB_CPU0_4_R_SCL")
	)
	(segment
		(start 384.454908 -296.688764)
		(end 388.218934 -300.45279)
		(width 0.10668)
		(layer "B.Cu")
		(net "SMB_CPU0_4_R_SCL")
	)
	(segment
		(start 404.682198 -316.022228)
		(end 404.682198 -318.736726)
		(width 0.10668)
		(layer "B.Cu")
		(net "SMB_CPU0_4_R_SCL")
	)
	(segment
		(start 395.015974 -304.86985)
		(end 404.682198 -314.536074)
		(width 0.10668)
		(layer "B.Cu")
		(net "SMB_CPU0_4_R_SCL")
	)
	(segment
		(start 392.335766 -300.45279)
		(end 395.015974 -303.132998)
		(width 0.10668)
		(layer "B.Cu")
		(net "SMB_CPU0_4_R_SCL")
	)
	(segment
		(start 404.682198 -318.736726)
		(end 404.070058 -319.348866)
		(width 0.10668)
		(layer "B.Cu")
		(net "SMB_CPU0_4_R_SCL")
	)
	(via
		(at 390.106408 -203.489052)
		(size 0.6604)
		(drill 0.3302)
		(layers "F.Cu" "B.Cu")
		(net "SMB_CPU0_3_SDA")
	)
	(segment
		(start 390.118346 -203.50099)
		(end 390.106408 -203.489052)
		(width 0.10668)
		(layer "B.Cu")
		(net "SMB_CPU0_3_SDA")
	)
	(segment
		(start 390.106408 -203.489052)
		(end 390.017508 -203.577952)
		(width 0.10668)
		(layer "B.Cu")
		(net "SMB_CPU0_3_SDA")
	)
	(segment
		(start 391.236708 -203.50099)
		(end 390.118346 -203.50099)
		(width 0.10668)
		(layer "B.Cu")
		(net "SMB_CPU0_3_SDA")
	)
	(segment
		(start 390.017508 -203.577952)
		(end 388.938008 -203.577952)
		(width 0.10668)
		(layer "B.Cu")
		(net "SMB_CPU0_3_SDA")
	)
	(via
		(at 390.106408 -202.219052)
		(size 0.6604)
		(drill 0.3302)
		(layers "F.Cu" "B.Cu")
		(net "SMB_CPU0_3_SCL")
	)
	(segment
		(start 389.712708 -202.612752)
		(end 390.106408 -202.219052)
		(width 0.10668)
		(layer "B.Cu")
		(net "SMB_CPU0_3_SCL")
	)
	(segment
		(start 390.106408 -202.219052)
		(end 390.372346 -202.48499)
		(width 0.10668)
		(layer "B.Cu")
		(net "SMB_CPU0_3_SCL")
	)
	(segment
		(start 388.938008 -202.612752)
		(end 389.712708 -202.612752)
		(width 0.10668)
		(layer "B.Cu")
		(net "SMB_CPU0_3_SCL")
	)
	(segment
		(start 390.372346 -202.48499)
		(end 391.236708 -202.48499)
		(width 0.10668)
		(layer "B.Cu")
		(net "SMB_CPU0_3_SCL")
	)
	(segment
		(start 391.677906 -222.880174)
		(end 391.677906 -221.62643)
		(width 0.10668)
		(layer "F.Cu")
		(net "SMB_CPU0_3_R_SDA")
	)
	(segment
		(start 385.427474 -207.072484)
		(end 385.427474 -206.112364)
		(width 0.10668)
		(layer "F.Cu")
		(net "SMB_CPU0_3_R_SDA")
	)
	(segment
		(start 391.677906 -221.62643)
		(end 384.981958 -214.930482)
		(width 0.10668)
		(layer "F.Cu")
		(net "SMB_CPU0_3_R_SDA")
	)
	(segment
		(start 384.981958 -214.930482)
		(end 384.981958 -207.518)
		(width 0.10668)
		(layer "F.Cu")
		(net "SMB_CPU0_3_R_SDA")
	)
	(segment
		(start 384.981958 -207.518)
		(end 385.427474 -207.072484)
		(width 0.10668)
		(layer "F.Cu")
		(net "SMB_CPU0_3_R_SDA")
	)
	(via
		(at 386.886958 -203.450952)
		(size 0.6604)
		(drill 0.3302)
		(layers "F.Cu" "B.Cu")
		(net "SMB_CPU0_3_R_SDA")
	)
	(via
		(at 385.427474 -206.112364)
		(size 0.508)
		(drill 0.254)
		(layers "F.Cu" "B.Cu")
		(net "SMB_CPU0_3_R_SDA")
	)
	(segment
		(start 387.013958 -203.577952)
		(end 388.137908 -203.577952)
		(width 0.10668)
		(layer "B.Cu")
		(net "SMB_CPU0_3_R_SDA")
	)
	(segment
		(start 386.886958 -203.450952)
		(end 387.013958 -203.577952)
		(width 0.10668)
		(layer "B.Cu")
		(net "SMB_CPU0_3_R_SDA")
	)
	(segment
		(start 385.427474 -206.112364)
		(end 385.427474 -204.910436)
		(width 0.10668)
		(layer "B.Cu")
		(net "SMB_CPU0_3_R_SDA")
	)
	(segment
		(start 385.427474 -204.910436)
		(end 386.886958 -203.450952)
		(width 0.10668)
		(layer "B.Cu")
		(net "SMB_CPU0_3_R_SDA")
	)
	(segment
		(start 384.184906 -214.615268)
		(end 384.184906 -206.48168)
		(width 0.10668)
		(layer "F.Cu")
		(net "SMB_CPU0_3_R_SCL")
	)
	(segment
		(start 391.208006 -221.638368)
		(end 384.184906 -214.615268)
		(width 0.10668)
		(layer "F.Cu")
		(net "SMB_CPU0_3_R_SCL")
	)
	(segment
		(start 391.208006 -222.070168)
		(end 391.208006 -221.638368)
		(width 0.10668)
		(layer "F.Cu")
		(net "SMB_CPU0_3_R_SCL")
	)
	(via
		(at 385.743958 -202.739752)
		(size 0.6604)
		(drill 0.3302)
		(layers "F.Cu" "B.Cu")
		(net "SMB_CPU0_3_R_SCL")
	)
	(via
		(at 384.184906 -206.48168)
		(size 0.508)
		(drill 0.254)
		(layers "F.Cu" "B.Cu")
		(net "SMB_CPU0_3_R_SCL")
	)
	(segment
		(start 385.013708 -203.470002)
		(end 385.743958 -202.739752)
		(width 0.10668)
		(layer "B.Cu")
		(net "SMB_CPU0_3_R_SCL")
	)
	(segment
		(start 385.870958 -202.612752)
		(end 388.137908 -202.612752)
		(width 0.10668)
		(layer "B.Cu")
		(net "SMB_CPU0_3_R_SCL")
	)
	(segment
		(start 385.013708 -205.652878)
		(end 385.013708 -203.470002)
		(width 0.10668)
		(layer "B.Cu")
		(net "SMB_CPU0_3_R_SCL")
	)
	(segment
		(start 385.743958 -202.739752)
		(end 385.870958 -202.612752)
		(width 0.10668)
		(layer "B.Cu")
		(net "SMB_CPU0_3_R_SCL")
	)
	(segment
		(start 384.184906 -206.48168)
		(end 385.013708 -205.652878)
		(width 0.10668)
		(layer "B.Cu")
		(net "SMB_CPU0_3_R_SCL")
	)
	(via
		(at 313.734958 -200.358502)
		(size 0.6604)
		(drill 0.3302)
		(layers "F.Cu" "B.Cu")
		(net "SMB_CPU0_2_SDA")
	)
	(segment
		(start 312.436256 -200.358502)
		(end 313.734958 -200.358502)
		(width 0.10668)
		(layer "B.Cu")
		(net "SMB_CPU0_2_SDA")
	)
	(segment
		(start 313.734958 -200.358502)
		(end 313.734958 -201.526902)
		(width 0.10668)
		(layer "B.Cu")
		(net "SMB_CPU0_2_SDA")
	)
	(segment
		(start 311.387236 -199.309482)
		(end 312.436256 -200.358502)
		(width 0.10668)
		(layer "B.Cu")
		(net "SMB_CPU0_2_SDA")
	)
	(segment
		(start 311.387236 -198.236078)
		(end 311.387236 -199.309482)
		(width 0.10668)
		(layer "B.Cu")
		(net "SMB_CPU0_2_SDA")
	)
	(via
		(at 312.403236 -199.404478)
		(size 0.6604)
		(drill 0.3302)
		(layers "F.Cu" "B.Cu")
		(net "SMB_CPU0_2_SCL")
	)
	(segment
		(start 315.004958 -201.526902)
		(end 315.004958 -200.870312)
		(width 0.10668)
		(layer "B.Cu")
		(net "SMB_CPU0_2_SCL")
	)
	(segment
		(start 313.539124 -199.404478)
		(end 312.403236 -199.404478)
		(width 0.10668)
		(layer "B.Cu")
		(net "SMB_CPU0_2_SCL")
	)
	(segment
		(start 312.403236 -199.404478)
		(end 312.403236 -198.236078)
		(width 0.10668)
		(layer "B.Cu")
		(net "SMB_CPU0_2_SCL")
	)
	(segment
		(start 315.004958 -200.870312)
		(end 313.539124 -199.404478)
		(width 0.10668)
		(layer "B.Cu")
		(net "SMB_CPU0_2_SCL")
	)
	(segment
		(start 327.758044 -222.880174)
		(end 327.291446 -222.614236)
		(width 0.10668)
		(layer "F.Cu")
		(net "SMB_CPU0_2_R_SDA")
	)
	(via
		(at 313.734958 -203.495402)
		(size 0.6604)
		(drill 0.3302)
		(layers "F.Cu" "B.Cu")
		(net "SMB_CPU0_2_R_SDA")
	)
	(via
		(at 327.291446 -222.614236)
		(size 0.4064)
		(drill 0.2032)
		(layers "F.Cu" "B.Cu")
		(net "SMB_CPU0_2_R_SDA")
	)
	(segment
		(start 315.116972 -212.08111)
		(end 315.116972 -204.877416)
		(width 0.10668)
		(layer "B.Cu")
		(net "SMB_CPU0_2_R_SDA")
	)
	(segment
		(start 315.116972 -204.877416)
		(end 313.734958 -203.495402)
		(width 0.10668)
		(layer "B.Cu")
		(net "SMB_CPU0_2_R_SDA")
	)
	(segment
		(start 325.650098 -222.614236)
		(end 315.116972 -212.08111)
		(width 0.10668)
		(layer "B.Cu")
		(net "SMB_CPU0_2_R_SDA")
	)
	(segment
		(start 313.734958 -203.495402)
		(end 313.734958 -202.327002)
		(width 0.10668)
		(layer "B.Cu")
		(net "SMB_CPU0_2_R_SDA")
	)
	(segment
		(start 327.291446 -222.614236)
		(end 325.650098 -222.614236)
		(width 0.10668)
		(layer "B.Cu")
		(net "SMB_CPU0_2_R_SDA")
	)
	(segment
		(start 328.227944 -223.69018)
		(end 327.761346 -223.424242)
		(width 0.10668)
		(layer "F.Cu")
		(net "SMB_CPU0_2_R_SCL")
	)
	(via
		(at 327.761346 -223.424242)
		(size 0.4064)
		(drill 0.2032)
		(layers "F.Cu" "B.Cu")
		(net "SMB_CPU0_2_R_SCL")
	)
	(via
		(at 315.004958 -203.495402)
		(size 0.6604)
		(drill 0.3302)
		(layers "F.Cu" "B.Cu")
		(net "SMB_CPU0_2_R_SCL")
	)
	(segment
		(start 316.274958 -210.407504)
		(end 316.274958 -204.765402)
		(width 0.10668)
		(layer "B.Cu")
		(net "SMB_CPU0_2_R_SCL")
	)
	(segment
		(start 327.358502 -221.491048)
		(end 316.274958 -210.407504)
		(width 0.10668)
		(layer "B.Cu")
		(net "SMB_CPU0_2_R_SCL")
	)
	(segment
		(start 327.761346 -223.424242)
		(end 327.761346 -222.462344)
		(width 0.10668)
		(layer "B.Cu")
		(net "SMB_CPU0_2_R_SCL")
	)
	(segment
		(start 315.004958 -203.495402)
		(end 315.004958 -202.327002)
		(width 0.10668)
		(layer "B.Cu")
		(net "SMB_CPU0_2_R_SCL")
	)
	(segment
		(start 327.358502 -222.0595)
		(end 327.358502 -221.491048)
		(width 0.10668)
		(layer "B.Cu")
		(net "SMB_CPU0_2_R_SCL")
	)
	(segment
		(start 327.761346 -222.462344)
		(end 327.358502 -222.0595)
		(width 0.10668)
		(layer "B.Cu")
		(net "SMB_CPU0_2_R_SCL")
	)
	(segment
		(start 316.274958 -204.765402)
		(end 315.004958 -203.495402)
		(width 0.10668)
		(layer "B.Cu")
		(net "SMB_CPU0_2_R_SCL")
	)
	(segment
		(start 25.94864 -366.903)
		(end 25.16505 -366.903)
		(width 0.10668)
		(layer "F.Cu")
		(net "SMB_CLK_PVDDCR_CPU1_P1_R")
	)
	(segment
		(start 26.224484 -366.903)
		(end 25.94864 -366.903)
		(width 0.10668)
		(layer "F.Cu")
		(net "SMB_CLK_PVDDCR_CPU1_P1_R")
	)
	(segment
		(start 27.604974 -365.909098)
		(end 27.218386 -365.909098)
		(width 0.10668)
		(layer "F.Cu")
		(net "SMB_CLK_PVDDCR_CPU1_P1_R")
	)
	(segment
		(start 27.218386 -365.909098)
		(end 26.224484 -366.903)
		(width 0.10668)
		(layer "F.Cu")
		(net "SMB_CLK_PVDDCR_CPU1_P1_R")
	)
	(via
		(at 25.94864 -366.903)
		(size 0.4064)
		(drill 0.2032)
		(layers "F.Cu" "B.Cu")
		(net "SMB_CLK_PVDDCR_CPU1_P1_R")
	)
	(segment
		(start 306.646072 -362.770928)
		(end 306.936902 -362.480098)
		(width 0.10668)
		(layer "F.Cu")
		(net "SMB_CLK_PVDDCR_CPU1_P0_R")
	)
	(segment
		(start 305.940968 -366.395)
		(end 305.940968 -365.645954)
		(width 0.10668)
		(layer "F.Cu")
		(net "SMB_CLK_PVDDCR_CPU1_P0_R")
	)
	(segment
		(start 306.39258 -363.383068)
		(end 306.646072 -362.770928)
		(width 0.10668)
		(layer "F.Cu")
		(net "SMB_CLK_PVDDCR_CPU1_P0_R")
	)
	(segment
		(start 305.940968 -365.645954)
		(end 306.39258 -365.194342)
		(width 0.10668)
		(layer "F.Cu")
		(net "SMB_CLK_PVDDCR_CPU1_P0_R")
	)
	(segment
		(start 306.39258 -365.194342)
		(end 306.39258 -363.383068)
		(width 0.10668)
		(layer "F.Cu")
		(net "SMB_CLK_PVDDCR_CPU1_P0_R")
	)
	(segment
		(start 304.81905 -366.395)
		(end 305.940968 -366.395)
		(width 0.10668)
		(layer "F.Cu")
		(net "SMB_CLK_PVDDCR_CPU1_P0_R")
	)
	(segment
		(start 306.936902 -362.480098)
		(end 307.258974 -362.480098)
		(width 0.10668)
		(layer "F.Cu")
		(net "SMB_CLK_PVDDCR_CPU1_P0_R")
	)
	(via
		(at 305.940968 -366.395)
		(size 0.762)
		(drill 0.381)
		(layers "F.Cu" "B.Cu")
		(net "SMB_CLK_PVDDCR_CPU1_P0_R")
	)
	(segment
		(start 169.05605 -433.878736)
		(end 169.596054 -433.338732)
		(width 0.10668)
		(layer "F.Cu")
		(net "SMB_BMC_SWB_BUF_SDA")
	)
	(segment
		(start 169.596054 -433.338732)
		(end 169.596054 -433.080922)
		(width 0.10668)
		(layer "F.Cu")
		(net "SMB_BMC_SWB_BUF_SDA")
	)
	(via
		(at 169.596054 -433.080922)
		(size 0.508)
		(drill 0.254)
		(layers "F.Cu" "B.Cu")
		(net "SMB_BMC_SWB_BUF_SDA")
	)
	(segment
		(start 155.903422 -439.935366)
		(end 155.903422 -424.731942)
		(width 0.11684)
		(layer "In2.Cu")
		(net "SMB_BMC_SWB_BUF_SDA")
	)
	(segment
		(start 167.953182 -433.439824)
		(end 169.237152 -433.439824)
		(width 0.11684)
		(layer "In2.Cu")
		(net "SMB_BMC_SWB_BUF_SDA")
	)
	(segment
		(start 155.903422 -424.731942)
		(end 156.514292 -424.121072)
		(width 0.11684)
		(layer "In2.Cu")
		(net "SMB_BMC_SWB_BUF_SDA")
	)
	(segment
		(start 167.403018 -432.88966)
		(end 167.953182 -433.439824)
		(width 0.11684)
		(layer "In2.Cu")
		(net "SMB_BMC_SWB_BUF_SDA")
	)
	(segment
		(start 164.204396 -432.88966)
		(end 167.403018 -432.88966)
		(width 0.11684)
		(layer "In2.Cu")
		(net "SMB_BMC_SWB_BUF_SDA")
	)
	(segment
		(start 158.50108 -427.186344)
		(end 164.204396 -432.88966)
		(width 0.11684)
		(layer "In2.Cu")
		(net "SMB_BMC_SWB_BUF_SDA")
	)
	(segment
		(start 169.237152 -433.439824)
		(end 169.596054 -433.080922)
		(width 0.11684)
		(layer "In2.Cu")
		(net "SMB_BMC_SWB_BUF_SDA")
	)
	(segment
		(start 155.34894 -440.489848)
		(end 155.903422 -439.935366)
		(width 0.11684)
		(layer "In2.Cu")
		(net "SMB_BMC_SWB_BUF_SDA")
	)
	(segment
		(start 158.50108 -425.597574)
		(end 158.50108 -427.186344)
		(width 0.11684)
		(layer "In2.Cu")
		(net "SMB_BMC_SWB_BUF_SDA")
	)
	(segment
		(start 157.024578 -424.121072)
		(end 158.50108 -425.597574)
		(width 0.11684)
		(layer "In2.Cu")
		(net "SMB_BMC_SWB_BUF_SDA")
	)
	(segment
		(start 154.750008 -440.489848)
		(end 155.34894 -440.489848)
		(width 0.11684)
		(layer "In2.Cu")
		(net "SMB_BMC_SWB_BUF_SDA")
	)
	(segment
		(start 156.514292 -424.121072)
		(end 157.024578 -424.121072)
		(width 0.11684)
		(layer "In2.Cu")
		(net "SMB_BMC_SWB_BUF_SDA")
	)
	(segment
		(start 166.71925 -431.3936)
		(end 167.598598 -431.3936)
		(width 0.10668)
		(layer "F.Cu")
		(net "SMB_BMC_SWB_BUF_SCL")
	)
	(via
		(at 167.598598 -431.3936)
		(size 0.762)
		(drill 0.254)
		(layers "F.Cu" "B.Cu")
		(net "SMB_BMC_SWB_BUF_SCL")
	)
	(segment
		(start 158.98114 -426.880782)
		(end 158.98114 -425.451778)
		(width 0.11684)
		(layer "In2.Cu")
		(net "SMB_BMC_SWB_BUF_SCL")
	)
	(segment
		(start 163.791646 -431.691288)
		(end 158.98114 -426.880782)
		(width 0.11684)
		(layer "In2.Cu")
		(net "SMB_BMC_SWB_BUF_SCL")
	)
	(segment
		(start 167.598598 -431.3936)
		(end 167.30091 -431.691288)
		(width 0.11684)
		(layer "In2.Cu")
		(net "SMB_BMC_SWB_BUF_SCL")
	)
	(segment
		(start 158.98114 -425.451778)
		(end 157.406594 -423.877232)
		(width 0.11684)
		(layer "In2.Cu")
		(net "SMB_BMC_SWB_BUF_SCL")
	)
	(segment
		(start 151.368252 -440.489848)
		(end 150.750016 -440.489848)
		(width 0.11684)
		(layer "In2.Cu")
		(net "SMB_BMC_SWB_BUF_SCL")
	)
	(segment
		(start 157.406594 -423.877232)
		(end 152.404064 -423.877232)
		(width 0.11684)
		(layer "In2.Cu")
		(net "SMB_BMC_SWB_BUF_SCL")
	)
	(segment
		(start 167.30091 -431.691288)
		(end 163.791646 -431.691288)
		(width 0.11684)
		(layer "In2.Cu")
		(net "SMB_BMC_SWB_BUF_SCL")
	)
	(segment
		(start 151.85898 -439.99912)
		(end 151.368252 -440.489848)
		(width 0.11684)
		(layer "In2.Cu")
		(net "SMB_BMC_SWB_BUF_SCL")
	)
	(segment
		(start 151.85898 -424.422316)
		(end 151.85898 -439.99912)
		(width 0.11684)
		(layer "In2.Cu")
		(net "SMB_BMC_SWB_BUF_SCL")
	)
	(segment
		(start 152.404064 -423.877232)
		(end 151.85898 -424.422316)
		(width 0.11684)
		(layer "In2.Cu")
		(net "SMB_BMC_SWB_BUF_SCL")
	)
	(segment
		(start 82.137504 -297.113198)
		(end 81.058004 -296.033698)
		(width 0.10668)
		(layer "F.Cu")
		(net "SMB_APML_CPU1_SDA")
	)
	(segment
		(start 90.525854 -297.113198)
		(end 82.137504 -297.113198)
		(width 0.10668)
		(layer "F.Cu")
		(net "SMB_APML_CPU1_SDA")
	)
	(segment
		(start 96.322642 -309.759858)
		(end 96.322642 -307.948584)
		(width 0.10668)
		(layer "F.Cu")
		(net "SMB_APML_CPU1_SDA")
	)
	(segment
		(start 97.05467 -303.642014)
		(end 90.525854 -297.113198)
		(width 0.10668)
		(layer "F.Cu")
		(net "SMB_APML_CPU1_SDA")
	)
	(segment
		(start 97.05467 -307.216556)
		(end 97.05467 -303.642014)
		(width 0.10668)
		(layer "F.Cu")
		(net "SMB_APML_CPU1_SDA")
	)
	(segment
		(start 81.058004 -296.033698)
		(end 81.058004 -294.880284)
		(width 0.10668)
		(layer "F.Cu")
		(net "SMB_APML_CPU1_SDA")
	)
	(segment
		(start 96.322642 -307.948584)
		(end 97.05467 -307.216556)
		(width 0.10668)
		(layer "F.Cu")
		(net "SMB_APML_CPU1_SDA")
	)
	(via
		(at 235.204 -240.411)
		(size 0.508)
		(drill 0.254)
		(layers "F.Cu" "B.Cu")
		(net "SMB_APML_CPU1_SDA")
	)
	(via
		(at 225.429826 -366.93475)
		(size 0.508)
		(drill 0.254)
		(layers "F.Cu" "B.Cu")
		(net "SMB_APML_CPU1_SDA")
	)
	(via
		(at 96.322642 -309.759858)
		(size 0.508)
		(drill 0.254)
		(layers "F.Cu" "B.Cu")
		(net "SMB_APML_CPU1_SDA")
	)
	(segment
		(start 184.508394 -368.234722)
		(end 185.262774 -367.480342)
		(width 0.10668)
		(layer "B.Cu")
		(net "SMB_APML_CPU1_SDA")
	)
	(segment
		(start 139.648692 -325.281544)
		(end 152.061926 -325.281544)
		(width 0.10668)
		(layer "B.Cu")
		(net "SMB_APML_CPU1_SDA")
	)
	(segment
		(start 234.569 -240.81105)
		(end 234.80395 -240.81105)
		(width 0.10668)
		(layer "B.Cu")
		(net "SMB_APML_CPU1_SDA")
	)
	(segment
		(start 234.80395 -240.81105)
		(end 235.204 -240.411)
		(width 0.10668)
		(layer "B.Cu")
		(net "SMB_APML_CPU1_SDA")
	)
	(segment
		(start 216.047828 -368.234722)
		(end 216.488772 -367.793778)
		(width 0.10668)
		(layer "B.Cu")
		(net "SMB_APML_CPU1_SDA")
	)
	(segment
		(start 222.82912 -367.793778)
		(end 223.688148 -366.93475)
		(width 0.10668)
		(layer "B.Cu")
		(net "SMB_APML_CPU1_SDA")
	)
	(segment
		(start 223.688148 -366.93475)
		(end 225.429826 -366.93475)
		(width 0.10668)
		(layer "B.Cu")
		(net "SMB_APML_CPU1_SDA")
	)
	(segment
		(start 152.061926 -325.281544)
		(end 152.970992 -326.19061)
		(width 0.10668)
		(layer "B.Cu")
		(net "SMB_APML_CPU1_SDA")
	)
	(segment
		(start 177.14341 -364.081822)
		(end 181.29631 -368.234722)
		(width 0.10668)
		(layer "B.Cu")
		(net "SMB_APML_CPU1_SDA")
	)
	(segment
		(start 216.488772 -367.793778)
		(end 222.82912 -367.793778)
		(width 0.10668)
		(layer "B.Cu")
		(net "SMB_APML_CPU1_SDA")
	)
	(segment
		(start 174.121064 -364.081822)
		(end 177.14341 -364.081822)
		(width 0.10668)
		(layer "B.Cu")
		(net "SMB_APML_CPU1_SDA")
	)
	(segment
		(start 168.13022 -358.090978)
		(end 174.121064 -364.081822)
		(width 0.10668)
		(layer "B.Cu")
		(net "SMB_APML_CPU1_SDA")
	)
	(segment
		(start 125.577092 -311.209944)
		(end 139.648692 -325.281544)
		(width 0.10668)
		(layer "B.Cu")
		(net "SMB_APML_CPU1_SDA")
	)
	(segment
		(start 185.262774 -367.480342)
		(end 189.640972 -367.480342)
		(width 0.10668)
		(layer "B.Cu")
		(net "SMB_APML_CPU1_SDA")
	)
	(segment
		(start 233.553 -240.81105)
		(end 234.569 -240.81105)
		(width 0.10668)
		(layer "B.Cu")
		(net "SMB_APML_CPU1_SDA")
	)
	(segment
		(start 189.640972 -367.480342)
		(end 190.395352 -368.234722)
		(width 0.10668)
		(layer "B.Cu")
		(net "SMB_APML_CPU1_SDA")
	)
	(segment
		(start 190.395352 -368.234722)
		(end 216.047828 -368.234722)
		(width 0.10668)
		(layer "B.Cu")
		(net "SMB_APML_CPU1_SDA")
	)
	(segment
		(start 98.23196 -311.209944)
		(end 125.577092 -311.209944)
		(width 0.10668)
		(layer "B.Cu")
		(net "SMB_APML_CPU1_SDA")
	)
	(segment
		(start 96.781874 -309.759858)
		(end 98.23196 -311.209944)
		(width 0.10668)
		(layer "B.Cu")
		(net "SMB_APML_CPU1_SDA")
	)
	(segment
		(start 96.322642 -309.759858)
		(end 96.781874 -309.759858)
		(width 0.10668)
		(layer "B.Cu")
		(net "SMB_APML_CPU1_SDA")
	)
	(segment
		(start 152.970992 -326.19061)
		(end 152.970992 -353.924108)
		(width 0.10668)
		(layer "B.Cu")
		(net "SMB_APML_CPU1_SDA")
	)
	(segment
		(start 152.970992 -353.924108)
		(end 157.137862 -358.090978)
		(width 0.10668)
		(layer "B.Cu")
		(net "SMB_APML_CPU1_SDA")
	)
	(segment
		(start 157.137862 -358.090978)
		(end 168.13022 -358.090978)
		(width 0.10668)
		(layer "B.Cu")
		(net "SMB_APML_CPU1_SDA")
	)
	(segment
		(start 181.29631 -368.234722)
		(end 184.508394 -368.234722)
		(width 0.10668)
		(layer "B.Cu")
		(net "SMB_APML_CPU1_SDA")
	)
	(segment
		(start 235.204 -240.411)
		(end 234.179364 -241.435636)
		(width 0.11684)
		(layer "In4.Cu")
		(net "SMB_APML_CPU1_SDA")
	)
	(segment
		(start 234.179364 -241.435636)
		(end 234.179364 -247.782842)
		(width 0.11684)
		(layer "In4.Cu")
		(net "SMB_APML_CPU1_SDA")
	)
	(segment
		(start 225.429826 -366.641126)
		(end 225.429826 -366.93475)
		(width 0.11684)
		(layer "In4.Cu")
		(net "SMB_APML_CPU1_SDA")
	)
	(segment
		(start 217.662252 -320.680588)
		(end 228.806756 -331.825092)
		(width 0.11684)
		(layer "In4.Cu")
		(net "SMB_APML_CPU1_SDA")
	)
	(segment
		(start 228.806756 -363.264196)
		(end 225.429826 -366.641126)
		(width 0.11684)
		(layer "In4.Cu")
		(net "SMB_APML_CPU1_SDA")
	)
	(segment
		(start 217.662252 -264.299954)
		(end 217.662252 -320.680588)
		(width 0.11684)
		(layer "In4.Cu")
		(net "SMB_APML_CPU1_SDA")
	)
	(segment
		(start 234.179364 -247.782842)
		(end 217.662252 -264.299954)
		(width 0.11684)
		(layer "In4.Cu")
		(net "SMB_APML_CPU1_SDA")
	)
	(segment
		(start 228.806756 -331.825092)
		(end 228.806756 -363.264196)
		(width 0.11684)
		(layer "In4.Cu")
		(net "SMB_APML_CPU1_SDA")
	)
	(segment
		(start 81.527904 -296.012108)
		(end 81.527904 -295.69029)
		(width 0.10668)
		(layer "F.Cu")
		(net "SMB_APML_CPU1_SCL")
	)
	(segment
		(start 82.218022 -296.702226)
		(end 81.527904 -296.012108)
		(width 0.10668)
		(layer "F.Cu")
		(net "SMB_APML_CPU1_SCL")
	)
	(segment
		(start 96.966278 -310.100218)
		(end 96.966278 -308.23408)
		(width 0.10668)
		(layer "F.Cu")
		(net "SMB_APML_CPU1_SCL")
	)
	(segment
		(start 97.810066 -303.816004)
		(end 90.696288 -296.702226)
		(width 0.10668)
		(layer "F.Cu")
		(net "SMB_APML_CPU1_SCL")
	)
	(segment
		(start 96.966278 -308.23408)
		(end 97.810066 -307.390292)
		(width 0.10668)
		(layer "F.Cu")
		(net "SMB_APML_CPU1_SCL")
	)
	(segment
		(start 90.696288 -296.702226)
		(end 82.218022 -296.702226)
		(width 0.10668)
		(layer "F.Cu")
		(net "SMB_APML_CPU1_SCL")
	)
	(segment
		(start 97.810066 -307.390292)
		(end 97.810066 -303.816004)
		(width 0.10668)
		(layer "F.Cu")
		(net "SMB_APML_CPU1_SCL")
	)
	(segment
		(start 96.702372 -310.364124)
		(end 96.966278 -310.100218)
		(width 0.10668)
		(layer "F.Cu")
		(net "SMB_APML_CPU1_SCL")
	)
	(via
		(at 235.204 -241.173)
		(size 0.508)
		(drill 0.254)
		(layers "F.Cu" "B.Cu")
		(net "SMB_APML_CPU1_SCL")
	)
	(via
		(at 224.024698 -368.200432)
		(size 0.508)
		(drill 0.254)
		(layers "F.Cu" "B.Cu")
		(net "SMB_APML_CPU1_SCL")
	)
	(via
		(at 96.702372 -310.364124)
		(size 0.508)
		(drill 0.254)
		(layers "F.Cu" "B.Cu")
		(net "SMB_APML_CPU1_SCL")
	)
	(segment
		(start 235.839 -240.81105)
		(end 235.56595 -240.81105)
		(width 0.10668)
		(layer "B.Cu")
		(net "SMB_APML_CPU1_SCL")
	)
	(segment
		(start 189.397894 -367.944908)
		(end 190.221616 -368.76863)
		(width 0.10668)
		(layer "B.Cu")
		(net "SMB_APML_CPU1_SCL")
	)
	(segment
		(start 156.982414 -358.466136)
		(end 167.974772 -358.466136)
		(width 0.10668)
		(layer "B.Cu")
		(net "SMB_APML_CPU1_SCL")
	)
	(segment
		(start 216.731596 -368.200432)
		(end 224.024698 -368.200432)
		(width 0.10668)
		(layer "B.Cu")
		(net "SMB_APML_CPU1_SCL")
	)
	(segment
		(start 152.595834 -326.346058)
		(end 152.595834 -354.079556)
		(width 0.10668)
		(layer "B.Cu")
		(net "SMB_APML_CPU1_SCL")
	)
	(segment
		(start 236.855 -240.81105)
		(end 235.839 -240.81105)
		(width 0.10668)
		(layer "B.Cu")
		(net "SMB_APML_CPU1_SCL")
	)
	(segment
		(start 173.965616 -364.45698)
		(end 176.99101 -364.45698)
		(width 0.10668)
		(layer "B.Cu")
		(net "SMB_APML_CPU1_SCL")
	)
	(segment
		(start 216.163398 -368.76863)
		(end 216.731596 -368.200432)
		(width 0.10668)
		(layer "B.Cu")
		(net "SMB_APML_CPU1_SCL")
	)
	(segment
		(start 190.221616 -368.76863)
		(end 216.163398 -368.76863)
		(width 0.10668)
		(layer "B.Cu")
		(net "SMB_APML_CPU1_SCL")
	)
	(segment
		(start 96.7359 -310.364124)
		(end 97.92208 -311.550304)
		(width 0.10668)
		(layer "B.Cu")
		(net "SMB_APML_CPU1_SCL")
	)
	(segment
		(start 181.196234 -368.662204)
		(end 184.766712 -368.662204)
		(width 0.10668)
		(layer "B.Cu")
		(net "SMB_APML_CPU1_SCL")
	)
	(segment
		(start 97.92208 -311.550304)
		(end 125.386846 -311.550304)
		(width 0.10668)
		(layer "B.Cu")
		(net "SMB_APML_CPU1_SCL")
	)
	(segment
		(start 185.484008 -367.944908)
		(end 189.397894 -367.944908)
		(width 0.10668)
		(layer "B.Cu")
		(net "SMB_APML_CPU1_SCL")
	)
	(segment
		(start 184.766712 -368.662204)
		(end 185.484008 -367.944908)
		(width 0.10668)
		(layer "B.Cu")
		(net "SMB_APML_CPU1_SCL")
	)
	(segment
		(start 151.906478 -325.656702)
		(end 152.595834 -326.346058)
		(width 0.10668)
		(layer "B.Cu")
		(net "SMB_APML_CPU1_SCL")
	)
	(segment
		(start 235.56595 -240.81105)
		(end 235.204 -241.173)
		(width 0.10668)
		(layer "B.Cu")
		(net "SMB_APML_CPU1_SCL")
	)
	(segment
		(start 152.595834 -354.079556)
		(end 156.982414 -358.466136)
		(width 0.10668)
		(layer "B.Cu")
		(net "SMB_APML_CPU1_SCL")
	)
	(segment
		(start 176.99101 -364.45698)
		(end 181.196234 -368.662204)
		(width 0.10668)
		(layer "B.Cu")
		(net "SMB_APML_CPU1_SCL")
	)
	(segment
		(start 139.493244 -325.656702)
		(end 151.906478 -325.656702)
		(width 0.10668)
		(layer "B.Cu")
		(net "SMB_APML_CPU1_SCL")
	)
	(segment
		(start 125.386846 -311.550304)
		(end 139.493244 -325.656702)
		(width 0.10668)
		(layer "B.Cu")
		(net "SMB_APML_CPU1_SCL")
	)
	(segment
		(start 167.974772 -358.466136)
		(end 173.965616 -364.45698)
		(width 0.10668)
		(layer "B.Cu")
		(net "SMB_APML_CPU1_SCL")
	)
	(segment
		(start 96.702372 -310.364124)
		(end 96.7359 -310.364124)
		(width 0.10668)
		(layer "B.Cu")
		(net "SMB_APML_CPU1_SCL")
	)
	(segment
		(start 234.718098 -241.658902)
		(end 234.718098 -248.006108)
		(width 0.11684)
		(layer "In4.Cu")
		(net "SMB_APML_CPU1_SCL")
	)
	(segment
		(start 235.204 -241.173)
		(end 234.718098 -241.658902)
		(width 0.11684)
		(layer "In4.Cu")
		(net "SMB_APML_CPU1_SCL")
	)
	(segment
		(start 218.083892 -264.640314)
		(end 218.083892 -320.505836)
		(width 0.11684)
		(layer "In4.Cu")
		(net "SMB_APML_CPU1_SCL")
	)
	(segment
		(start 224.985326 -368.200432)
		(end 224.024698 -368.200432)
		(width 0.11684)
		(layer "In4.Cu")
		(net "SMB_APML_CPU1_SCL")
	)
	(segment
		(start 234.718098 -248.006108)
		(end 218.083892 -264.640314)
		(width 0.11684)
		(layer "In4.Cu")
		(net "SMB_APML_CPU1_SCL")
	)
	(segment
		(start 227.23348 -365.434118)
		(end 227.23348 -365.952278)
		(width 0.11684)
		(layer "In4.Cu")
		(net "SMB_APML_CPU1_SCL")
	)
	(segment
		(start 229.228396 -331.65034)
		(end 229.228396 -363.439202)
		(width 0.11684)
		(layer "In4.Cu")
		(net "SMB_APML_CPU1_SCL")
	)
	(segment
		(start 227.23348 -365.952278)
		(end 224.985326 -368.200432)
		(width 0.11684)
		(layer "In4.Cu")
		(net "SMB_APML_CPU1_SCL")
	)
	(segment
		(start 229.228396 -363.439202)
		(end 227.23348 -365.434118)
		(width 0.11684)
		(layer "In4.Cu")
		(net "SMB_APML_CPU1_SCL")
	)
	(segment
		(start 218.083892 -320.505836)
		(end 229.228396 -331.65034)
		(width 0.11684)
		(layer "In4.Cu")
		(net "SMB_APML_CPU1_SCL")
	)
	(via
		(at 241.427 -235.331)
		(size 0.6604)
		(drill 0.3302)
		(layers "F.Cu" "B.Cu")
		(net "SMB_CPU0_SEC_R_SCL")
	)
	(segment
		(start 239.419638 -236.590586)
		(end 239.419638 -236.195362)
		(width 0.10668)
		(layer "B.Cu")
		(net "SMB_CPU0_SEC_R_SCL")
	)
	(segment
		(start 241.427 -234.46105)
		(end 242.443 -234.46105)
		(width 0.10668)
		(layer "B.Cu")
		(net "SMB_CPU0_SEC_R_SCL")
	)
	(segment
		(start 241.427 -235.331)
		(end 241.427 -234.46105)
		(width 0.10668)
		(layer "B.Cu")
		(net "SMB_CPU0_SEC_R_SCL")
	)
	(segment
		(start 240.284 -235.331)
		(end 241.427 -235.331)
		(width 0.10668)
		(layer "B.Cu")
		(net "SMB_CPU0_SEC_R_SCL")
	)
	(segment
		(start 239.419638 -236.195362)
		(end 240.284 -235.331)
		(width 0.10668)
		(layer "B.Cu")
		(net "SMB_CPU0_SEC_R_SCL")
	)
	(segment
		(start 329.305158 -296.08272)
		(end 329.729592 -296.08272)
		(width 0.10668)
		(layer "F.Cu")
		(net "SMB_APML_CPU0_SDA")
	)
	(segment
		(start 328.998072 -295.775634)
		(end 329.305158 -296.08272)
		(width 0.10668)
		(layer "F.Cu")
		(net "SMB_APML_CPU0_SDA")
	)
	(segment
		(start 328.998072 -294.88003)
		(end 328.998072 -295.775634)
		(width 0.10668)
		(layer "F.Cu")
		(net "SMB_APML_CPU0_SDA")
	)
	(segment
		(start 336.084926 -302.438054)
		(end 336.084926 -307.08473)
		(width 0.10668)
		(layer "F.Cu")
		(net "SMB_APML_CPU0_SDA")
	)
	(segment
		(start 329.729592 -296.08272)
		(end 336.084926 -302.438054)
		(width 0.10668)
		(layer "F.Cu")
		(net "SMB_APML_CPU0_SDA")
	)
	(via
		(at 240.590578 -248.747788)
		(size 0.6604)
		(drill 0.3302)
		(layers "F.Cu" "B.Cu")
		(net "SMB_APML_CPU0_SDA")
	)
	(via
		(at 336.084926 -307.08473)
		(size 0.508)
		(drill 0.254)
		(layers "F.Cu" "B.Cu")
		(net "SMB_APML_CPU0_SDA")
	)
	(segment
		(start 261.7724 -326.45223)
		(end 299.766736 -326.45223)
		(width 0.10668)
		(layer "B.Cu")
		(net "SMB_APML_CPU0_SDA")
	)
	(segment
		(start 305.05654 -322.73494)
		(end 316.02934 -311.76214)
		(width 0.10668)
		(layer "B.Cu")
		(net "SMB_APML_CPU0_SDA")
	)
	(segment
		(start 333.691484 -309.478172)
		(end 336.084926 -307.08473)
		(width 0.10668)
		(layer "B.Cu")
		(net "SMB_APML_CPU0_SDA")
	)
	(segment
		(start 237.679738 -248.747788)
		(end 240.590578 -248.747788)
		(width 0.10668)
		(layer "B.Cu")
		(net "SMB_APML_CPU0_SDA")
	)
	(segment
		(start 237.21695 -248.285)
		(end 237.679738 -248.747788)
		(width 0.10668)
		(layer "B.Cu")
		(net "SMB_APML_CPU0_SDA")
	)
	(segment
		(start 316.02934 -311.76214)
		(end 332.26883 -311.76214)
		(width 0.10668)
		(layer "B.Cu")
		(net "SMB_APML_CPU0_SDA")
	)
	(segment
		(start 237.21695 -247.269)
		(end 237.21695 -248.285)
		(width 0.10668)
		(layer "B.Cu")
		(net "SMB_APML_CPU0_SDA")
	)
	(segment
		(start 303.484026 -322.73494)
		(end 305.05654 -322.73494)
		(width 0.10668)
		(layer "B.Cu")
		(net "SMB_APML_CPU0_SDA")
	)
	(segment
		(start 242.57889 -248.747788)
		(end 258.019296 -264.188194)
		(width 0.10668)
		(layer "B.Cu")
		(net "SMB_APML_CPU0_SDA")
	)
	(segment
		(start 258.019296 -264.188194)
		(end 258.019296 -322.699126)
		(width 0.10668)
		(layer "B.Cu")
		(net "SMB_APML_CPU0_SDA")
	)
	(segment
		(start 332.26883 -311.76214)
		(end 333.691484 -310.339486)
		(width 0.10668)
		(layer "B.Cu")
		(net "SMB_APML_CPU0_SDA")
	)
	(segment
		(start 258.019296 -322.699126)
		(end 261.7724 -326.45223)
		(width 0.10668)
		(layer "B.Cu")
		(net "SMB_APML_CPU0_SDA")
	)
	(segment
		(start 240.590578 -248.747788)
		(end 242.57889 -248.747788)
		(width 0.10668)
		(layer "B.Cu")
		(net "SMB_APML_CPU0_SDA")
	)
	(segment
		(start 333.691484 -310.339486)
		(end 333.691484 -309.478172)
		(width 0.10668)
		(layer "B.Cu")
		(net "SMB_APML_CPU0_SDA")
	)
	(segment
		(start 299.766736 -326.45223)
		(end 303.484026 -322.73494)
		(width 0.10668)
		(layer "B.Cu")
		(net "SMB_APML_CPU0_SDA")
	)
	(segment
		(start 329.467972 -295.690036)
		(end 329.86726 -295.690036)
		(width 0.10668)
		(layer "F.Cu")
		(net "SMB_APML_CPU0_SCL")
	)
	(segment
		(start 336.584798 -302.407574)
		(end 336.584798 -307.505862)
		(width 0.10668)
		(layer "F.Cu")
		(net "SMB_APML_CPU0_SCL")
	)
	(segment
		(start 329.86726 -295.690036)
		(end 336.584798 -302.407574)
		(width 0.10668)
		(layer "F.Cu")
		(net "SMB_APML_CPU0_SCL")
	)
	(via
		(at 242.78971 -249.889264)
		(size 0.6604)
		(drill 0.3302)
		(layers "F.Cu" "B.Cu")
		(net "SMB_APML_CPU0_SCL")
	)
	(via
		(at 336.584798 -307.505862)
		(size 0.508)
		(drill 0.254)
		(layers "F.Cu" "B.Cu")
		(net "SMB_APML_CPU0_SCL")
	)
	(segment
		(start 237.21695 -249.555)
		(end 237.683802 -249.088148)
		(width 0.10668)
		(layer "B.Cu")
		(net "SMB_APML_CPU0_SCL")
	)
	(segment
		(start 239.945672 -249.088148)
		(end 240.746788 -249.889264)
		(width 0.10668)
		(layer "B.Cu")
		(net "SMB_APML_CPU0_SCL")
	)
	(segment
		(start 336.37601 -307.505862)
		(end 336.584798 -307.505862)
		(width 0.10668)
		(layer "B.Cu")
		(net "SMB_APML_CPU0_SCL")
	)
	(segment
		(start 261.631176 -326.79259)
		(end 299.90796 -326.79259)
		(width 0.10668)
		(layer "B.Cu")
		(net "SMB_APML_CPU0_SCL")
	)
	(segment
		(start 257.678936 -264.329418)
		(end 257.678936 -322.84035)
		(width 0.10668)
		(layer "B.Cu")
		(net "SMB_APML_CPU0_SCL")
	)
	(segment
		(start 334.239108 -310.598566)
		(end 334.239108 -309.642764)
		(width 0.10668)
		(layer "B.Cu")
		(net "SMB_APML_CPU0_SCL")
	)
	(segment
		(start 334.239108 -309.642764)
		(end 336.37601 -307.505862)
		(width 0.10668)
		(layer "B.Cu")
		(net "SMB_APML_CPU0_SCL")
	)
	(segment
		(start 332.735174 -312.1025)
		(end 334.239108 -310.598566)
		(width 0.10668)
		(layer "B.Cu")
		(net "SMB_APML_CPU0_SCL")
	)
	(segment
		(start 242.78971 -249.889264)
		(end 243.238782 -249.889264)
		(width 0.10668)
		(layer "B.Cu")
		(net "SMB_APML_CPU0_SCL")
	)
	(segment
		(start 237.683802 -249.088148)
		(end 239.945672 -249.088148)
		(width 0.10668)
		(layer "B.Cu")
		(net "SMB_APML_CPU0_SCL")
	)
	(segment
		(start 299.90796 -326.79259)
		(end 303.62525 -323.0753)
		(width 0.10668)
		(layer "B.Cu")
		(net "SMB_APML_CPU0_SCL")
	)
	(segment
		(start 237.21695 -250.571)
		(end 237.21695 -249.555)
		(width 0.10668)
		(layer "B.Cu")
		(net "SMB_APML_CPU0_SCL")
	)
	(segment
		(start 257.678936 -322.84035)
		(end 261.631176 -326.79259)
		(width 0.10668)
		(layer "B.Cu")
		(net "SMB_APML_CPU0_SCL")
	)
	(segment
		(start 243.238782 -249.889264)
		(end 257.678936 -264.329418)
		(width 0.10668)
		(layer "B.Cu")
		(net "SMB_APML_CPU0_SCL")
	)
	(segment
		(start 316.170564 -312.1025)
		(end 332.735174 -312.1025)
		(width 0.10668)
		(layer "B.Cu")
		(net "SMB_APML_CPU0_SCL")
	)
	(segment
		(start 240.746788 -249.889264)
		(end 242.78971 -249.889264)
		(width 0.10668)
		(layer "B.Cu")
		(net "SMB_APML_CPU0_SCL")
	)
	(segment
		(start 305.197764 -323.0753)
		(end 316.170564 -312.1025)
		(width 0.10668)
		(layer "B.Cu")
		(net "SMB_APML_CPU0_SCL")
	)
	(segment
		(start 303.62525 -323.0753)
		(end 305.197764 -323.0753)
		(width 0.10668)
		(layer "B.Cu")
		(net "SMB_APML_CPU0_SCL")
	)
	(via
		(at 229.59695 -240.919)
		(size 0.508)
		(drill 0.254)
		(layers "F.Cu" "B.Cu")
		(net "SMB_APML_CPU0_R_SDA")
	)
	(via
		(at 238.76 -248.285)
		(size 0.508)
		(drill 0.254)
		(layers "F.Cu" "B.Cu")
		(net "SMB_APML_CPU0_R_SDA")
	)
	(segment
		(start 229.59695 -240.03)
		(end 229.59695 -240.919)
		(width 0.10668)
		(layer "B.Cu")
		(net "SMB_APML_CPU0_R_SDA")
	)
	(segment
		(start 238.01705 -248.285)
		(end 238.76 -248.285)
		(width 0.10668)
		(layer "B.Cu")
		(net "SMB_APML_CPU0_R_SDA")
	)
	(segment
		(start 229.59695 -238.906304)
		(end 230.388414 -238.11484)
		(width 0.10668)
		(layer "B.Cu")
		(net "SMB_APML_CPU0_R_SDA")
	)
	(segment
		(start 229.59695 -240.03)
		(end 229.59695 -238.906304)
		(width 0.10668)
		(layer "B.Cu")
		(net "SMB_APML_CPU0_R_SDA")
	)
	(segment
		(start 230.388414 -238.11484)
		(end 230.388414 -237.449106)
		(width 0.10668)
		(layer "B.Cu")
		(net "SMB_APML_CPU0_R_SDA")
	)
	(segment
		(start 233.229658 -242.754658)
		(end 238.76 -248.285)
		(width 0.11684)
		(layer "In2.Cu")
		(net "SMB_APML_CPU0_R_SDA")
	)
	(segment
		(start 233.229658 -240.827814)
		(end 233.229658 -242.754658)
		(width 0.11684)
		(layer "In2.Cu")
		(net "SMB_APML_CPU0_R_SDA")
	)
	(segment
		(start 229.59695 -240.919)
		(end 230.206296 -240.309654)
		(width 0.11684)
		(layer "In2.Cu")
		(net "SMB_APML_CPU0_R_SDA")
	)
	(segment
		(start 230.206296 -240.309654)
		(end 232.711498 -240.309654)
		(width 0.11684)
		(layer "In2.Cu")
		(net "SMB_APML_CPU0_R_SDA")
	)
	(segment
		(start 232.711498 -240.309654)
		(end 233.229658 -240.827814)
		(width 0.11684)
		(layer "In2.Cu")
		(net "SMB_APML_CPU0_R_SDA")
	)
	(via
		(at 232.55605 -240.919)
		(size 0.508)
		(drill 0.254)
		(layers "F.Cu" "B.Cu")
		(net "SMB_APML_CPU0_R_SCL")
	)
	(via
		(at 238.76 -249.555)
		(size 0.508)
		(drill 0.254)
		(layers "F.Cu" "B.Cu")
		(net "SMB_APML_CPU0_R_SCL")
	)
	(segment
		(start 232.55605 -240.03)
		(end 232.55605 -239.033304)
		(width 0.10668)
		(layer "B.Cu")
		(net "SMB_APML_CPU0_R_SCL")
	)
	(segment
		(start 238.01705 -249.555)
		(end 238.76 -249.555)
		(width 0.10668)
		(layer "B.Cu")
		(net "SMB_APML_CPU0_R_SCL")
	)
	(segment
		(start 231.888538 -238.365792)
		(end 231.888538 -237.449106)
		(width 0.10668)
		(layer "B.Cu")
		(net "SMB_APML_CPU0_R_SCL")
	)
	(segment
		(start 232.55605 -240.03)
		(end 232.55605 -240.919)
		(width 0.10668)
		(layer "B.Cu")
		(net "SMB_APML_CPU0_R_SCL")
	)
	(segment
		(start 232.55605 -239.033304)
		(end 231.888538 -238.365792)
		(width 0.10668)
		(layer "B.Cu")
		(net "SMB_APML_CPU0_R_SCL")
	)
	(segment
		(start 232.55605 -240.919)
		(end 232.55605 -243.35105)
		(width 0.11684)
		(layer "In2.Cu")
		(net "SMB_APML_CPU0_R_SCL")
	)
	(segment
		(start 232.55605 -243.35105)
		(end 238.76 -249.555)
		(width 0.11684)
		(layer "In2.Cu")
		(net "SMB_APML_CPU0_R_SCL")
	)
	(segment
		(start 168.148 -118.328948)
		(end 168.656 -118.836948)
		(width 0.10668)
		(layer "F.Cu")
		(net "SMB_2_PLD_3V3AUX_SDA_R1")
	)
	(segment
		(start 170.79595 -118.601744)
		(end 170.79595 -118.328948)
		(width 0.10668)
		(layer "F.Cu")
		(net "SMB_2_PLD_3V3AUX_SDA_R1")
	)
	(segment
		(start 170.560746 -118.836948)
		(end 170.79595 -118.601744)
		(width 0.10668)
		(layer "F.Cu")
		(net "SMB_2_PLD_3V3AUX_SDA_R1")
	)
	(segment
		(start 168.656 -118.836948)
		(end 170.560746 -118.836948)
		(width 0.10668)
		(layer "F.Cu")
		(net "SMB_2_PLD_3V3AUX_SDA_R1")
	)
	(via
		(at 168.148 -118.328948)
		(size 0.508)
		(drill 0.254)
		(layers "F.Cu" "B.Cu")
		(net "SMB_2_PLD_3V3AUX_SDA_R1")
	)
	(via
		(at 159.481774 -14.50848)
		(size 0.508)
		(drill 0.254)
		(layers "F.Cu" "B.Cu")
		(net "SMB_2_PLD_3V3AUX_SDA_R1")
	)
	(segment
		(start 160.29178 -16.77416)
		(end 160.29178 -15.318486)
		(width 0.10668)
		(layer "B.Cu")
		(net "SMB_2_PLD_3V3AUX_SDA_R1")
	)
	(segment
		(start 160.29178 -15.318486)
		(end 159.481774 -14.50848)
		(width 0.10668)
		(layer "B.Cu")
		(net "SMB_2_PLD_3V3AUX_SDA_R1")
	)
	(segment
		(start 163.058602 -105.463594)
		(end 161.905188 -104.31018)
		(width 0.11684)
		(layer "In11.Cu")
		(net "SMB_2_PLD_3V3AUX_SDA_R1")
	)
	(segment
		(start 164.585904 -72.06996)
		(end 164.585904 -57.288684)
		(width 0.11684)
		(layer "In11.Cu")
		(net "SMB_2_PLD_3V3AUX_SDA_R1")
	)
	(segment
		(start 165.299136 -108.230416)
		(end 163.058602 -105.989882)
		(width 0.11684)
		(layer "In11.Cu")
		(net "SMB_2_PLD_3V3AUX_SDA_R1")
	)
	(segment
		(start 163.528248 -76.092304)
		(end 163.528248 -73.127616)
		(width 0.11684)
		(layer "In11.Cu")
		(net "SMB_2_PLD_3V3AUX_SDA_R1")
	)
	(segment
		(start 160.586674 -96.232218)
		(end 164.112448 -92.706444)
		(width 0.11684)
		(layer "In11.Cu")
		(net "SMB_2_PLD_3V3AUX_SDA_R1")
	)
	(segment
		(start 166.127684 -111.630206)
		(end 166.01694 -111.362998)
		(width 0.11684)
		(layer "In11.Cu")
		(net "SMB_2_PLD_3V3AUX_SDA_R1")
	)
	(segment
		(start 159.812228 -14.585188)
		(end 159.558482 -14.585188)
		(width 0.11684)
		(layer "In11.Cu")
		(net "SMB_2_PLD_3V3AUX_SDA_R1")
	)
	(segment
		(start 163.528248 -73.127616)
		(end 164.585904 -72.06996)
		(width 0.11684)
		(layer "In11.Cu")
		(net "SMB_2_PLD_3V3AUX_SDA_R1")
	)
	(segment
		(start 165.450774 -114.42573)
		(end 165.450774 -113.967768)
		(width 0.11684)
		(layer "In11.Cu")
		(net "SMB_2_PLD_3V3AUX_SDA_R1")
	)
	(segment
		(start 165.87089 -115.26139)
		(end 165.87089 -114.845846)
		(width 0.11684)
		(layer "In11.Cu")
		(net "SMB_2_PLD_3V3AUX_SDA_R1")
	)
	(segment
		(start 164.585904 -57.288684)
		(end 161.36874 -54.07152)
		(width 0.11684)
		(layer "In11.Cu")
		(net "SMB_2_PLD_3V3AUX_SDA_R1")
	)
	(segment
		(start 166.34714 -113.071402)
		(end 166.34714 -111.849662)
		(width 0.11684)
		(layer "In11.Cu")
		(net "SMB_2_PLD_3V3AUX_SDA_R1")
	)
	(segment
		(start 165.299136 -109.275626)
		(end 165.299136 -108.230416)
		(width 0.11684)
		(layer "In11.Cu")
		(net "SMB_2_PLD_3V3AUX_SDA_R1")
	)
	(segment
		(start 168.148 -118.328948)
		(end 167.513 -118.328948)
		(width 0.11684)
		(layer "In11.Cu")
		(net "SMB_2_PLD_3V3AUX_SDA_R1")
	)
	(segment
		(start 167.513 -118.328948)
		(end 166.639494 -117.455442)
		(width 0.11684)
		(layer "In11.Cu")
		(net "SMB_2_PLD_3V3AUX_SDA_R1")
	)
	(segment
		(start 164.112448 -92.706444)
		(end 164.112448 -89.235534)
		(width 0.11684)
		(layer "In11.Cu")
		(net "SMB_2_PLD_3V3AUX_SDA_R1")
	)
	(segment
		(start 165.71214 -109.68863)
		(end 165.299136 -109.275626)
		(width 0.11684)
		(layer "In11.Cu")
		(net "SMB_2_PLD_3V3AUX_SDA_R1")
	)
	(segment
		(start 164.112448 -89.235534)
		(end 164.585904 -88.762078)
		(width 0.11684)
		(layer "In11.Cu")
		(net "SMB_2_PLD_3V3AUX_SDA_R1")
	)
	(segment
		(start 161.36874 -54.07152)
		(end 161.36874 -16.1417)
		(width 0.11684)
		(layer "In11.Cu")
		(net "SMB_2_PLD_3V3AUX_SDA_R1")
	)
	(segment
		(start 161.905188 -104.31018)
		(end 160.928812 -104.31018)
		(width 0.11684)
		(layer "In11.Cu")
		(net "SMB_2_PLD_3V3AUX_SDA_R1")
	)
	(segment
		(start 160.586674 -103.968042)
		(end 160.586674 -96.232218)
		(width 0.11684)
		(layer "In11.Cu")
		(net "SMB_2_PLD_3V3AUX_SDA_R1")
	)
	(segment
		(start 166.34714 -111.849662)
		(end 166.127684 -111.630206)
		(width 0.11684)
		(layer "In11.Cu")
		(net "SMB_2_PLD_3V3AUX_SDA_R1")
	)
	(segment
		(start 164.585904 -88.762078)
		(end 164.585904 -77.14996)
		(width 0.11684)
		(layer "In11.Cu")
		(net "SMB_2_PLD_3V3AUX_SDA_R1")
	)
	(segment
		(start 163.058602 -105.989882)
		(end 163.058602 -105.463594)
		(width 0.11684)
		(layer "In11.Cu")
		(net "SMB_2_PLD_3V3AUX_SDA_R1")
	)
	(segment
		(start 165.87089 -114.845846)
		(end 165.450774 -114.42573)
		(width 0.11684)
		(layer "In11.Cu")
		(net "SMB_2_PLD_3V3AUX_SDA_R1")
	)
	(segment
		(start 160.928812 -104.31018)
		(end 160.586674 -103.968042)
		(width 0.11684)
		(layer "In11.Cu")
		(net "SMB_2_PLD_3V3AUX_SDA_R1")
	)
	(segment
		(start 166.639494 -116.029994)
		(end 165.87089 -115.26139)
		(width 0.11684)
		(layer "In11.Cu")
		(net "SMB_2_PLD_3V3AUX_SDA_R1")
	)
	(segment
		(start 164.585904 -77.14996)
		(end 163.528248 -76.092304)
		(width 0.11684)
		(layer "In11.Cu")
		(net "SMB_2_PLD_3V3AUX_SDA_R1")
	)
	(segment
		(start 159.558482 -14.585188)
		(end 159.481774 -14.50848)
		(width 0.11684)
		(layer "In11.Cu")
		(net "SMB_2_PLD_3V3AUX_SDA_R1")
	)
	(segment
		(start 166.01694 -109.68863)
		(end 165.71214 -109.68863)
		(width 0.11684)
		(layer "In11.Cu")
		(net "SMB_2_PLD_3V3AUX_SDA_R1")
	)
	(segment
		(start 165.450774 -113.967768)
		(end 166.34714 -113.071402)
		(width 0.11684)
		(layer "In11.Cu")
		(net "SMB_2_PLD_3V3AUX_SDA_R1")
	)
	(segment
		(start 166.639494 -117.455442)
		(end 166.639494 -116.029994)
		(width 0.11684)
		(layer "In11.Cu")
		(net "SMB_2_PLD_3V3AUX_SDA_R1")
	)
	(segment
		(start 166.01694 -111.362998)
		(end 166.01694 -109.68863)
		(width 0.11684)
		(layer "In11.Cu")
		(net "SMB_2_PLD_3V3AUX_SDA_R1")
	)
	(segment
		(start 161.36874 -16.1417)
		(end 159.812228 -14.585188)
		(width 0.11684)
		(layer "In11.Cu")
		(net "SMB_2_PLD_3V3AUX_SDA_R1")
	)
	(segment
		(start 169.164 -117.312948)
		(end 169.672 -117.820948)
		(width 0.10668)
		(layer "F.Cu")
		(net "SMB_2_PLD_3V3AUX_SCL_R1")
	)
	(segment
		(start 170.79595 -117.585744)
		(end 170.79595 -117.312948)
		(width 0.10668)
		(layer "F.Cu")
		(net "SMB_2_PLD_3V3AUX_SCL_R1")
	)
	(segment
		(start 169.672 -117.820948)
		(end 170.560746 -117.820948)
		(width 0.10668)
		(layer "F.Cu")
		(net "SMB_2_PLD_3V3AUX_SCL_R1")
	)
	(segment
		(start 170.560746 -117.820948)
		(end 170.79595 -117.585744)
		(width 0.10668)
		(layer "F.Cu")
		(net "SMB_2_PLD_3V3AUX_SCL_R1")
	)
	(via
		(at 169.164 -117.312948)
		(size 0.508)
		(drill 0.254)
		(layers "F.Cu" "B.Cu")
		(net "SMB_2_PLD_3V3AUX_SCL_R1")
	)
	(via
		(at 162.725862 -14.801596)
		(size 0.508)
		(drill 0.254)
		(layers "F.Cu" "B.Cu")
		(net "SMB_2_PLD_3V3AUX_SCL_R1")
	)
	(segment
		(start 162.86988 -16.77416)
		(end 162.86988 -14.945614)
		(width 0.10668)
		(layer "B.Cu")
		(net "SMB_2_PLD_3V3AUX_SCL_R1")
	)
	(segment
		(start 162.86988 -14.945614)
		(end 162.725862 -14.801596)
		(width 0.10668)
		(layer "B.Cu")
		(net "SMB_2_PLD_3V3AUX_SCL_R1")
	)
	(segment
		(start 161.79038 -53.896768)
		(end 161.79038 -15.737078)
		(width 0.11684)
		(layer "In11.Cu")
		(net "SMB_2_PLD_3V3AUX_SCL_R1")
	)
	(segment
		(start 163.486846 -104.897936)
		(end 162.59937 -104.01046)
		(width 0.11684)
		(layer "In11.Cu")
		(net "SMB_2_PLD_3V3AUX_SCL_R1")
	)
	(segment
		(start 166.546784 -111.42599)
		(end 166.454328 -111.202724)
		(width 0.11684)
		(layer "In11.Cu")
		(net "SMB_2_PLD_3V3AUX_SCL_R1")
	)
	(segment
		(start 169.164 -117.312948)
		(end 168.609772 -116.75872)
		(width 0.11684)
		(layer "In11.Cu")
		(net "SMB_2_PLD_3V3AUX_SCL_R1")
	)
	(segment
		(start 168.609772 -116.75872)
		(end 167.5384 -116.75872)
		(width 0.11684)
		(layer "In11.Cu")
		(net "SMB_2_PLD_3V3AUX_SCL_R1")
	)
	(segment
		(start 167.5384 -116.75872)
		(end 167.253412 -116.473732)
		(width 0.11684)
		(layer "In11.Cu")
		(net "SMB_2_PLD_3V3AUX_SCL_R1")
	)
	(segment
		(start 165.732968 -108.067602)
		(end 163.486846 -105.82148)
		(width 0.11684)
		(layer "In11.Cu")
		(net "SMB_2_PLD_3V3AUX_SCL_R1")
	)
	(segment
		(start 161.387282 -100.81387)
		(end 161.387282 -96.035622)
		(width 0.11684)
		(layer "In11.Cu")
		(net "SMB_2_PLD_3V3AUX_SCL_R1")
	)
	(segment
		(start 164.592 -92.830904)
		(end 164.592 -89.426542)
		(width 0.11684)
		(layer "In11.Cu")
		(net "SMB_2_PLD_3V3AUX_SCL_R1")
	)
	(segment
		(start 165.007544 -89.010998)
		(end 165.007544 -57.113932)
		(width 0.11684)
		(layer "In11.Cu")
		(net "SMB_2_PLD_3V3AUX_SCL_R1")
	)
	(segment
		(start 166.784274 -115.489228)
		(end 166.784274 -111.66348)
		(width 0.11684)
		(layer "In11.Cu")
		(net "SMB_2_PLD_3V3AUX_SCL_R1")
	)
	(segment
		(start 167.253412 -116.473732)
		(end 167.253412 -115.958366)
		(width 0.11684)
		(layer "In11.Cu")
		(net "SMB_2_PLD_3V3AUX_SCL_R1")
	)
	(segment
		(start 164.592 -89.426542)
		(end 165.007544 -89.010998)
		(width 0.11684)
		(layer "In11.Cu")
		(net "SMB_2_PLD_3V3AUX_SCL_R1")
	)
	(segment
		(start 161.79038 -15.737078)
		(end 162.725862 -14.801596)
		(width 0.11684)
		(layer "In11.Cu")
		(net "SMB_2_PLD_3V3AUX_SCL_R1")
	)
	(segment
		(start 162.59937 -102.025958)
		(end 161.387282 -100.81387)
		(width 0.11684)
		(layer "In11.Cu")
		(net "SMB_2_PLD_3V3AUX_SCL_R1")
	)
	(segment
		(start 166.454328 -111.202724)
		(end 166.454328 -108.170726)
		(width 0.11684)
		(layer "In11.Cu")
		(net "SMB_2_PLD_3V3AUX_SCL_R1")
	)
	(segment
		(start 162.59937 -104.01046)
		(end 162.59937 -102.025958)
		(width 0.11684)
		(layer "In11.Cu")
		(net "SMB_2_PLD_3V3AUX_SCL_R1")
	)
	(segment
		(start 166.454328 -108.170726)
		(end 166.351204 -108.067602)
		(width 0.11684)
		(layer "In11.Cu")
		(net "SMB_2_PLD_3V3AUX_SCL_R1")
	)
	(segment
		(start 163.486846 -105.82148)
		(end 163.486846 -104.897936)
		(width 0.11684)
		(layer "In11.Cu")
		(net "SMB_2_PLD_3V3AUX_SCL_R1")
	)
	(segment
		(start 167.253412 -115.958366)
		(end 166.784274 -115.489228)
		(width 0.11684)
		(layer "In11.Cu")
		(net "SMB_2_PLD_3V3AUX_SCL_R1")
	)
	(segment
		(start 166.784274 -111.66348)
		(end 166.546784 -111.42599)
		(width 0.11684)
		(layer "In11.Cu")
		(net "SMB_2_PLD_3V3AUX_SCL_R1")
	)
	(segment
		(start 165.007544 -57.113932)
		(end 161.79038 -53.896768)
		(width 0.11684)
		(layer "In11.Cu")
		(net "SMB_2_PLD_3V3AUX_SCL_R1")
	)
	(segment
		(start 166.351204 -108.067602)
		(end 165.732968 -108.067602)
		(width 0.11684)
		(layer "In11.Cu")
		(net "SMB_2_PLD_3V3AUX_SCL_R1")
	)
	(segment
		(start 161.387282 -96.035622)
		(end 164.592 -92.830904)
		(width 0.11684)
		(layer "In11.Cu")
		(net "SMB_2_PLD_3V3AUX_SCL_R1")
	)
	(segment
		(start 219.296488 -211.002372)
		(end 223.5581 -206.74076)
		(width 0.10668)
		(layer "F.Cu")
		(net "SMB_2_BMC_GPU_SDA")
	)
	(segment
		(start 219.808298 -93.380814)
		(end 211.256626 -93.380814)
		(width 0.10668)
		(layer "F.Cu")
		(net "SMB_2_BMC_GPU_SDA")
	)
	(segment
		(start 208.050384 -89.091516)
		(end 203.162408 -89.091516)
		(width 0.10668)
		(layer "F.Cu")
		(net "SMB_2_BMC_GPU_SDA")
	)
	(segment
		(start 224.328482 -124.689108)
		(end 221.314772 -121.675398)
		(width 0.10668)
		(layer "F.Cu")
		(net "SMB_2_BMC_GPU_SDA")
	)
	(segment
		(start 226.84867 -165.27907)
		(end 221.868238 -160.298638)
		(width 0.10668)
		(layer "F.Cu")
		(net "SMB_2_BMC_GPU_SDA")
	)
	(segment
		(start 223.188276 -96.760792)
		(end 219.808298 -93.380814)
		(width 0.10668)
		(layer "F.Cu")
		(net "SMB_2_BMC_GPU_SDA")
	)
	(segment
		(start 21.636228 -437.980074)
		(end 20.828 -437.980074)
		(width 0.10668)
		(layer "F.Cu")
		(net "SMB_2_BMC_GPU_SDA")
	)
	(segment
		(start 199.371204 -88.783922)
		(end 199.06361 -89.091516)
		(width 0.10668)
		(layer "F.Cu")
		(net "SMB_2_BMC_GPU_SDA")
	)
	(segment
		(start 208.85785 -89.898982)
		(end 208.050384 -89.091516)
		(width 0.10668)
		(layer "F.Cu")
		(net "SMB_2_BMC_GPU_SDA")
	)
	(segment
		(start 223.5581 -206.74076)
		(end 223.5581 -204.948282)
		(width 0.10668)
		(layer "F.Cu")
		(net "SMB_2_BMC_GPU_SDA")
	)
	(segment
		(start 221.868238 -160.298638)
		(end 221.868238 -147.761452)
		(width 0.10668)
		(layer "F.Cu")
		(net "SMB_2_BMC_GPU_SDA")
	)
	(segment
		(start 221.868238 -147.761452)
		(end 223.764856 -145.864834)
		(width 0.10668)
		(layer "F.Cu")
		(net "SMB_2_BMC_GPU_SDA")
	)
	(segment
		(start 223.188276 -115.8494)
		(end 223.188276 -96.760792)
		(width 0.10668)
		(layer "F.Cu")
		(net "SMB_2_BMC_GPU_SDA")
	)
	(segment
		(start 221.314772 -121.675398)
		(end 221.314772 -117.722904)
		(width 0.10668)
		(layer "F.Cu")
		(net "SMB_2_BMC_GPU_SDA")
	)
	(segment
		(start 223.5581 -204.948282)
		(end 226.84867 -201.657712)
		(width 0.10668)
		(layer "F.Cu")
		(net "SMB_2_BMC_GPU_SDA")
	)
	(segment
		(start 226.84867 -201.657712)
		(end 226.84867 -165.27907)
		(width 0.10668)
		(layer "F.Cu")
		(net "SMB_2_BMC_GPU_SDA")
	)
	(segment
		(start 221.314772 -117.722904)
		(end 223.188276 -115.8494)
		(width 0.10668)
		(layer "F.Cu")
		(net "SMB_2_BMC_GPU_SDA")
	)
	(segment
		(start 224.328482 -137.781792)
		(end 224.328482 -124.689108)
		(width 0.10668)
		(layer "F.Cu")
		(net "SMB_2_BMC_GPU_SDA")
	)
	(segment
		(start 223.764856 -145.864834)
		(end 223.764856 -138.345418)
		(width 0.10668)
		(layer "F.Cu")
		(net "SMB_2_BMC_GPU_SDA")
	)
	(segment
		(start 202.854814 -88.783922)
		(end 199.371204 -88.783922)
		(width 0.10668)
		(layer "F.Cu")
		(net "SMB_2_BMC_GPU_SDA")
	)
	(segment
		(start 208.85785 -90.982038)
		(end 208.85785 -89.898982)
		(width 0.10668)
		(layer "F.Cu")
		(net "SMB_2_BMC_GPU_SDA")
	)
	(segment
		(start 211.256626 -93.380814)
		(end 208.85785 -90.982038)
		(width 0.10668)
		(layer "F.Cu")
		(net "SMB_2_BMC_GPU_SDA")
	)
	(segment
		(start 189.691772 -89.091516)
		(end 189.12586 -88.525604)
		(width 0.10668)
		(layer "F.Cu")
		(net "SMB_2_BMC_GPU_SDA")
	)
	(segment
		(start 189.12586 -88.525604)
		(end 187.014358 -88.525604)
		(width 0.10668)
		(layer "F.Cu")
		(net "SMB_2_BMC_GPU_SDA")
	)
	(segment
		(start 187.014358 -88.525604)
		(end 186.553602 -88.064848)
		(width 0.10668)
		(layer "F.Cu")
		(net "SMB_2_BMC_GPU_SDA")
	)
	(segment
		(start 203.162408 -89.091516)
		(end 202.854814 -88.783922)
		(width 0.10668)
		(layer "F.Cu")
		(net "SMB_2_BMC_GPU_SDA")
	)
	(segment
		(start 199.06361 -89.091516)
		(end 189.691772 -89.091516)
		(width 0.10668)
		(layer "F.Cu")
		(net "SMB_2_BMC_GPU_SDA")
	)
	(segment
		(start 223.764856 -138.345418)
		(end 224.328482 -137.781792)
		(width 0.10668)
		(layer "F.Cu")
		(net "SMB_2_BMC_GPU_SDA")
	)
	(via
		(at 219.296488 -211.002372)
		(size 0.508)
		(drill 0.254)
		(layers "F.Cu" "B.Cu")
		(net "SMB_2_BMC_GPU_SDA")
	)
	(via
		(at 186.553602 -88.064848)
		(size 0.508)
		(drill 0.254)
		(layers "F.Cu" "B.Cu")
		(net "SMB_2_BMC_GPU_SDA")
	)
	(via
		(at 41.470834 -366.163352)
		(size 0.508)
		(drill 0.254)
		(layers "F.Cu" "B.Cu")
		(net "SMB_2_BMC_GPU_SDA")
	)
	(via
		(at 155.341066 -15.310358)
		(size 0.508)
		(drill 0.254)
		(layers "F.Cu" "B.Cu")
		(net "SMB_2_BMC_GPU_SDA")
	)
	(via
		(at 20.828 -437.980074)
		(size 0.508)
		(drill 0.254)
		(layers "F.Cu" "B.Cu")
		(net "SMB_2_BMC_GPU_SDA")
	)
	(segment
		(start 155.01239 -14.162278)
		(end 155.01239 -14.950694)
		(width 0.10668)
		(layer "B.Cu")
		(net "SMB_2_BMC_GPU_SDA")
	)
	(segment
		(start 155.01239 -15.664434)
		(end 155.01239 -16.034512)
		(width 0.10668)
		(layer "B.Cu")
		(net "SMB_2_BMC_GPU_SDA")
	)
	(segment
		(start 155.01239 -14.950694)
		(end 155.341066 -15.27937)
		(width 0.10668)
		(layer "B.Cu")
		(net "SMB_2_BMC_GPU_SDA")
	)
	(segment
		(start 155.02001 -16.042132)
		(end 155.02001 -16.451072)
		(width 0.10668)
		(layer "B.Cu")
		(net "SMB_2_BMC_GPU_SDA")
	)
	(segment
		(start 155.341066 -15.335758)
		(end 155.01239 -15.664434)
		(width 0.10668)
		(layer "B.Cu")
		(net "SMB_2_BMC_GPU_SDA")
	)
	(segment
		(start 155.341066 -15.310358)
		(end 155.341066 -15.335758)
		(width 0.10668)
		(layer "B.Cu")
		(net "SMB_2_BMC_GPU_SDA")
	)
	(segment
		(start 155.01239 -16.034512)
		(end 155.02001 -16.042132)
		(width 0.10668)
		(layer "B.Cu")
		(net "SMB_2_BMC_GPU_SDA")
	)
	(segment
		(start 155.341066 -15.27937)
		(end 155.341066 -15.310358)
		(width 0.10668)
		(layer "B.Cu")
		(net "SMB_2_BMC_GPU_SDA")
	)
	(segment
		(start 204.883512 -354.437188)
		(end 191.508126 -367.812574)
		(width 0.11684)
		(layer "In2.Cu")
		(net "SMB_2_BMC_GPU_SDA")
	)
	(segment
		(start 171.400978 -366.367822)
		(end 169.456862 -364.423706)
		(width 0.11684)
		(layer "In2.Cu")
		(net "SMB_2_BMC_GPU_SDA")
	)
	(segment
		(start 181.98338 -369.07851)
		(end 180.798216 -369.07851)
		(width 0.11684)
		(layer "In2.Cu")
		(net "SMB_2_BMC_GPU_SDA")
	)
	(segment
		(start 209.474816 -338.095336)
		(end 209.268822 -338.30133)
		(width 0.11684)
		(layer "In2.Cu")
		(net "SMB_2_BMC_GPU_SDA")
	)
	(segment
		(start 183.249316 -367.812574)
		(end 181.98338 -369.07851)
		(width 0.11684)
		(layer "In2.Cu")
		(net "SMB_2_BMC_GPU_SDA")
	)
	(segment
		(start 173.596808 -366.367822)
		(end 171.400978 -366.367822)
		(width 0.11684)
		(layer "In2.Cu")
		(net "SMB_2_BMC_GPU_SDA")
	)
	(segment
		(start 191.508126 -367.812574)
		(end 183.249316 -367.812574)
		(width 0.11684)
		(layer "In2.Cu")
		(net "SMB_2_BMC_GPU_SDA")
	)
	(segment
		(start 175.363632 -368.39398)
		(end 174.949358 -367.979706)
		(width 0.11684)
		(layer "In2.Cu")
		(net "SMB_2_BMC_GPU_SDA")
	)
	(segment
		(start 138.626596 -364.423706)
		(end 136.982708 -366.067594)
		(width 0.11684)
		(layer "In2.Cu")
		(net "SMB_2_BMC_GPU_SDA")
	)
	(segment
		(start 136.982708 -366.067594)
		(end 43.437048 -366.067594)
		(width 0.11684)
		(layer "In2.Cu")
		(net "SMB_2_BMC_GPU_SDA")
	)
	(segment
		(start 219.296488 -211.002372)
		(end 214.611966 -215.686894)
		(width 0.11684)
		(layer "In2.Cu")
		(net "SMB_2_BMC_GPU_SDA")
	)
	(segment
		(start 209.474816 -323.911468)
		(end 209.474816 -338.095336)
		(width 0.11684)
		(layer "In2.Cu")
		(net "SMB_2_BMC_GPU_SDA")
	)
	(segment
		(start 43.194986 -366.309656)
		(end 41.617138 -366.309656)
		(width 0.11684)
		(layer "In2.Cu")
		(net "SMB_2_BMC_GPU_SDA")
	)
	(segment
		(start 204.883512 -350.618806)
		(end 204.883512 -354.437188)
		(width 0.11684)
		(layer "In2.Cu")
		(net "SMB_2_BMC_GPU_SDA")
	)
	(segment
		(start 174.949358 -367.720372)
		(end 173.596808 -366.367822)
		(width 0.11684)
		(layer "In2.Cu")
		(net "SMB_2_BMC_GPU_SDA")
	)
	(segment
		(start 180.113686 -368.39398)
		(end 175.363632 -368.39398)
		(width 0.11684)
		(layer "In2.Cu")
		(net "SMB_2_BMC_GPU_SDA")
	)
	(segment
		(start 211.19338 -320.159888)
		(end 211.19338 -322.192904)
		(width 0.11684)
		(layer "In2.Cu")
		(net "SMB_2_BMC_GPU_SDA")
	)
	(segment
		(start 214.611966 -215.686894)
		(end 214.611966 -316.741302)
		(width 0.11684)
		(layer "In2.Cu")
		(net "SMB_2_BMC_GPU_SDA")
	)
	(segment
		(start 214.611966 -316.741302)
		(end 211.19338 -320.159888)
		(width 0.11684)
		(layer "In2.Cu")
		(net "SMB_2_BMC_GPU_SDA")
	)
	(segment
		(start 211.19338 -322.192904)
		(end 209.474816 -323.911468)
		(width 0.11684)
		(layer "In2.Cu")
		(net "SMB_2_BMC_GPU_SDA")
	)
	(segment
		(start 169.456862 -364.423706)
		(end 138.626596 -364.423706)
		(width 0.11684)
		(layer "In2.Cu")
		(net "SMB_2_BMC_GPU_SDA")
	)
	(segment
		(start 209.268822 -346.233496)
		(end 204.883512 -350.618806)
		(width 0.11684)
		(layer "In2.Cu")
		(net "SMB_2_BMC_GPU_SDA")
	)
	(segment
		(start 180.798216 -369.07851)
		(end 180.113686 -368.39398)
		(width 0.11684)
		(layer "In2.Cu")
		(net "SMB_2_BMC_GPU_SDA")
	)
	(segment
		(start 174.949358 -367.979706)
		(end 174.949358 -367.720372)
		(width 0.11684)
		(layer "In2.Cu")
		(net "SMB_2_BMC_GPU_SDA")
	)
	(segment
		(start 43.437048 -366.067594)
		(end 43.194986 -366.309656)
		(width 0.11684)
		(layer "In2.Cu")
		(net "SMB_2_BMC_GPU_SDA")
	)
	(segment
		(start 41.617138 -366.309656)
		(end 41.470834 -366.163352)
		(width 0.11684)
		(layer "In2.Cu")
		(net "SMB_2_BMC_GPU_SDA")
	)
	(segment
		(start 209.268822 -338.30133)
		(end 209.268822 -346.233496)
		(width 0.11684)
		(layer "In2.Cu")
		(net "SMB_2_BMC_GPU_SDA")
	)
	(segment
		(start 154.92984 -15.721584)
		(end 155.341066 -15.310358)
		(width 0.11684)
		(layer "In4.Cu")
		(net "SMB_2_BMC_GPU_SDA")
	)
	(segment
		(start 154.92984 -19.482816)
		(end 154.92984 -15.721584)
		(width 0.11684)
		(layer "In4.Cu")
		(net "SMB_2_BMC_GPU_SDA")
	)
	(segment
		(start 160.852866 -21.822156)
		(end 159.44469 -20.41398)
		(width 0.11684)
		(layer "In4.Cu")
		(net "SMB_2_BMC_GPU_SDA")
	)
	(segment
		(start 155.861004 -20.41398)
		(end 154.92984 -19.482816)
		(width 0.11684)
		(layer "In4.Cu")
		(net "SMB_2_BMC_GPU_SDA")
	)
	(segment
		(start 186.553602 -88.064848)
		(end 186.553602 -45.340524)
		(width 0.11684)
		(layer "In4.Cu")
		(net "SMB_2_BMC_GPU_SDA")
	)
	(segment
		(start 175.659796 -36.705286)
		(end 175.484028 -36.705286)
		(width 0.11684)
		(layer "In4.Cu")
		(net "SMB_2_BMC_GPU_SDA")
	)
	(segment
		(start 160.852866 -28.54325)
		(end 160.852866 -21.822156)
		(width 0.11684)
		(layer "In4.Cu")
		(net "SMB_2_BMC_GPU_SDA")
	)
	(segment
		(start 186.553602 -45.340524)
		(end 179.51577 -38.302692)
		(width 0.11684)
		(layer "In4.Cu")
		(net "SMB_2_BMC_GPU_SDA")
	)
	(segment
		(start 166.520876 -34.21126)
		(end 160.852866 -28.54325)
		(width 0.11684)
		(layer "In4.Cu")
		(net "SMB_2_BMC_GPU_SDA")
	)
	(segment
		(start 175.484028 -36.705286)
		(end 172.990002 -34.21126)
		(width 0.11684)
		(layer "In4.Cu")
		(net "SMB_2_BMC_GPU_SDA")
	)
	(segment
		(start 159.44469 -20.41398)
		(end 155.861004 -20.41398)
		(width 0.11684)
		(layer "In4.Cu")
		(net "SMB_2_BMC_GPU_SDA")
	)
	(segment
		(start 179.51577 -38.302692)
		(end 175.659796 -36.705286)
		(width 0.11684)
		(layer "In4.Cu")
		(net "SMB_2_BMC_GPU_SDA")
	)
	(segment
		(start 172.990002 -34.21126)
		(end 166.520876 -34.21126)
		(width 0.11684)
		(layer "In4.Cu")
		(net "SMB_2_BMC_GPU_SDA")
	)
	(segment
		(start 39.92118 -386.120894)
		(end 39.92118 -388.414514)
		(width 0.11684)
		(layer "In11.Cu")
		(net "SMB_2_BMC_GPU_SDA")
	)
	(segment
		(start 40.78224 -389.275574)
		(end 40.78224 -393.747244)
		(width 0.11684)
		(layer "In11.Cu")
		(net "SMB_2_BMC_GPU_SDA")
	)
	(segment
		(start 44.508928 -436.958486)
		(end 41.591992 -439.875422)
		(width 0.11684)
		(layer "In11.Cu")
		(net "SMB_2_BMC_GPU_SDA")
	)
	(segment
		(start 40.1828 -399.865342)
		(end 37.128196 -402.919946)
		(width 0.11684)
		(layer "In11.Cu")
		(net "SMB_2_BMC_GPU_SDA")
	)
	(segment
		(start 32.273748 -439.081926)
		(end 21.929852 -439.081926)
		(width 0.11684)
		(layer "In11.Cu")
		(net "SMB_2_BMC_GPU_SDA")
	)
	(segment
		(start 37.128196 -406.541224)
		(end 44.508928 -413.921956)
		(width 0.11684)
		(layer "In11.Cu")
		(net "SMB_2_BMC_GPU_SDA")
	)
	(segment
		(start 43.1927 -382.849374)
		(end 39.92118 -386.120894)
		(width 0.11684)
		(layer "In11.Cu")
		(net "SMB_2_BMC_GPU_SDA")
	)
	(segment
		(start 40.1828 -394.346684)
		(end 40.1828 -399.865342)
		(width 0.11684)
		(layer "In11.Cu")
		(net "SMB_2_BMC_GPU_SDA")
	)
	(segment
		(start 40.78224 -393.747244)
		(end 40.1828 -394.346684)
		(width 0.11684)
		(layer "In11.Cu")
		(net "SMB_2_BMC_GPU_SDA")
	)
	(segment
		(start 43.1927 -374.135396)
		(end 43.1927 -382.849374)
		(width 0.11684)
		(layer "In11.Cu")
		(net "SMB_2_BMC_GPU_SDA")
	)
	(segment
		(start 33.067244 -439.875422)
		(end 32.273748 -439.081926)
		(width 0.11684)
		(layer "In11.Cu")
		(net "SMB_2_BMC_GPU_SDA")
	)
	(segment
		(start 21.929852 -439.081926)
		(end 20.828 -437.980074)
		(width 0.11684)
		(layer "In11.Cu")
		(net "SMB_2_BMC_GPU_SDA")
	)
	(segment
		(start 44.508928 -413.921956)
		(end 44.508928 -436.958486)
		(width 0.11684)
		(layer "In11.Cu")
		(net "SMB_2_BMC_GPU_SDA")
	)
	(segment
		(start 37.128196 -402.919946)
		(end 37.128196 -406.541224)
		(width 0.11684)
		(layer "In11.Cu")
		(net "SMB_2_BMC_GPU_SDA")
	)
	(segment
		(start 41.470834 -366.163352)
		(end 41.470834 -372.41353)
		(width 0.11684)
		(layer "In11.Cu")
		(net "SMB_2_BMC_GPU_SDA")
	)
	(segment
		(start 41.470834 -372.41353)
		(end 43.1927 -374.135396)
		(width 0.11684)
		(layer "In11.Cu")
		(net "SMB_2_BMC_GPU_SDA")
	)
	(segment
		(start 41.591992 -439.875422)
		(end 33.067244 -439.875422)
		(width 0.11684)
		(layer "In11.Cu")
		(net "SMB_2_BMC_GPU_SDA")
	)
	(segment
		(start 39.92118 -388.414514)
		(end 40.78224 -389.275574)
		(width 0.11684)
		(layer "In11.Cu")
		(net "SMB_2_BMC_GPU_SDA")
	)
	(segment
		(start 37.206682 -438.311544)
		(end 37.053012 -438.465214)
		(width 0.10668)
		(layer "F.Cu")
		(net "SMB_2_BMC_GPU_SCL")
	)
	(segment
		(start 224.105216 -123.931172)
		(end 224.668842 -124.494798)
		(width 0.10668)
		(layer "F.Cu")
		(net "SMB_2_BMC_GPU_SCL")
	)
	(segment
		(start 221.655132 -121.480834)
		(end 224.105216 -123.930918)
		(width 0.10668)
		(layer "F.Cu")
		(net "SMB_2_BMC_GPU_SCL")
	)
	(segment
		(start 37.053012 -438.465214)
		(end 36.281868 -438.465214)
		(width 0.10668)
		(layer "F.Cu")
		(net "SMB_2_BMC_GPU_SCL")
	)
	(segment
		(start 209.19821 -90.840814)
		(end 211.377276 -93.01988)
		(width 0.10668)
		(layer "F.Cu")
		(net "SMB_2_BMC_GPU_SCL")
	)
	(segment
		(start 224.105216 -123.930918)
		(end 224.105216 -123.931172)
		(width 0.10668)
		(layer "F.Cu")
		(net "SMB_2_BMC_GPU_SCL")
	)
	(segment
		(start 202.951588 -88.399112)
		(end 203.303632 -88.751156)
		(width 0.10668)
		(layer "F.Cu")
		(net "SMB_2_BMC_GPU_SCL")
	)
	(segment
		(start 187.648342 -88.065864)
		(end 189.147704 -88.065864)
		(width 0.10668)
		(layer "F.Cu")
		(net "SMB_2_BMC_GPU_SCL")
	)
	(segment
		(start 203.303632 -88.751156)
		(end 208.191862 -88.751156)
		(width 0.10668)
		(layer "F.Cu")
		(net "SMB_2_BMC_GPU_SCL")
	)
	(segment
		(start 219.928948 -93.01988)
		(end 223.528636 -96.619568)
		(width 0.10668)
		(layer "F.Cu")
		(net "SMB_2_BMC_GPU_SCL")
	)
	(segment
		(start 224.668842 -124.494798)
		(end 224.668842 -137.923016)
		(width 0.10668)
		(layer "F.Cu")
		(net "SMB_2_BMC_GPU_SCL")
	)
	(segment
		(start 222.208598 -147.902676)
		(end 222.208598 -160.157414)
		(width 0.10668)
		(layer "F.Cu")
		(net "SMB_2_BMC_GPU_SCL")
	)
	(segment
		(start 223.92386 -207.073754)
		(end 219.296488 -211.701126)
		(width 0.10668)
		(layer "F.Cu")
		(net "SMB_2_BMC_GPU_SCL")
	)
	(segment
		(start 227.18903 -201.798936)
		(end 223.92386 -205.064106)
		(width 0.10668)
		(layer "F.Cu")
		(net "SMB_2_BMC_GPU_SCL")
	)
	(segment
		(start 224.105216 -138.486642)
		(end 224.105216 -146.006058)
		(width 0.10668)
		(layer "F.Cu")
		(net "SMB_2_BMC_GPU_SCL")
	)
	(segment
		(start 189.832996 -88.751156)
		(end 198.922132 -88.751156)
		(width 0.10668)
		(layer "F.Cu")
		(net "SMB_2_BMC_GPU_SCL")
	)
	(segment
		(start 222.208598 -160.157414)
		(end 227.18903 -165.137846)
		(width 0.10668)
		(layer "F.Cu")
		(net "SMB_2_BMC_GPU_SCL")
	)
	(segment
		(start 189.147704 -88.065864)
		(end 189.832996 -88.751156)
		(width 0.10668)
		(layer "F.Cu")
		(net "SMB_2_BMC_GPU_SCL")
	)
	(segment
		(start 223.528636 -115.990624)
		(end 221.655132 -117.864128)
		(width 0.10668)
		(layer "F.Cu")
		(net "SMB_2_BMC_GPU_SCL")
	)
	(segment
		(start 208.191862 -88.751156)
		(end 209.19821 -89.757504)
		(width 0.10668)
		(layer "F.Cu")
		(net "SMB_2_BMC_GPU_SCL")
	)
	(segment
		(start 198.922132 -88.751156)
		(end 199.274176 -88.399112)
		(width 0.10668)
		(layer "F.Cu")
		(net "SMB_2_BMC_GPU_SCL")
	)
	(segment
		(start 221.655132 -117.864128)
		(end 221.655132 -121.480834)
		(width 0.10668)
		(layer "F.Cu")
		(net "SMB_2_BMC_GPU_SCL")
	)
	(segment
		(start 199.274176 -88.399112)
		(end 202.951588 -88.399112)
		(width 0.10668)
		(layer "F.Cu")
		(net "SMB_2_BMC_GPU_SCL")
	)
	(segment
		(start 227.18903 -165.137846)
		(end 227.18903 -201.798936)
		(width 0.10668)
		(layer "F.Cu")
		(net "SMB_2_BMC_GPU_SCL")
	)
	(segment
		(start 224.668842 -137.923016)
		(end 224.105216 -138.486642)
		(width 0.10668)
		(layer "F.Cu")
		(net "SMB_2_BMC_GPU_SCL")
	)
	(segment
		(start 211.377276 -93.01988)
		(end 219.928948 -93.01988)
		(width 0.10668)
		(layer "F.Cu")
		(net "SMB_2_BMC_GPU_SCL")
	)
	(segment
		(start 223.528636 -96.619568)
		(end 223.528636 -115.990624)
		(width 0.10668)
		(layer "F.Cu")
		(net "SMB_2_BMC_GPU_SCL")
	)
	(segment
		(start 223.92386 -205.064106)
		(end 223.92386 -207.073754)
		(width 0.10668)
		(layer "F.Cu")
		(net "SMB_2_BMC_GPU_SCL")
	)
	(segment
		(start 209.19821 -89.757504)
		(end 209.19821 -90.840814)
		(width 0.10668)
		(layer "F.Cu")
		(net "SMB_2_BMC_GPU_SCL")
	)
	(segment
		(start 224.105216 -146.006058)
		(end 222.208598 -147.902676)
		(width 0.10668)
		(layer "F.Cu")
		(net "SMB_2_BMC_GPU_SCL")
	)
	(via
		(at 219.296488 -211.701126)
		(size 0.508)
		(drill 0.254)
		(layers "F.Cu" "B.Cu")
		(net "SMB_2_BMC_GPU_SCL")
	)
	(via
		(at 37.206682 -438.311544)
		(size 0.508)
		(drill 0.254)
		(layers "F.Cu" "B.Cu")
		(net "SMB_2_BMC_GPU_SCL")
	)
	(via
		(at 156.67101 -15.310358)
		(size 0.508)
		(drill 0.254)
		(layers "F.Cu" "B.Cu")
		(net "SMB_2_BMC_GPU_SCL")
	)
	(via
		(at 40.94734 -366.659668)
		(size 0.508)
		(drill 0.254)
		(layers "F.Cu" "B.Cu")
		(net "SMB_2_BMC_GPU_SCL")
	)
	(via
		(at 187.648342 -88.065864)
		(size 0.508)
		(drill 0.254)
		(layers "F.Cu" "B.Cu")
		(net "SMB_2_BMC_GPU_SCL")
	)
	(segment
		(start 156.67101 -15.310358)
		(end 156.67101 -16.451072)
		(width 0.10668)
		(layer "B.Cu")
		(net "SMB_2_BMC_GPU_SCL")
	)
	(segment
		(start 156.17063 -14.809978)
		(end 156.67101 -15.310358)
		(width 0.10668)
		(layer "B.Cu")
		(net "SMB_2_BMC_GPU_SCL")
	)
	(segment
		(start 156.17063 -14.162278)
		(end 156.17063 -14.809978)
		(width 0.10668)
		(layer "B.Cu")
		(net "SMB_2_BMC_GPU_SCL")
	)
	(segment
		(start 215.174068 -313.732164)
		(end 215.290908 -313.615324)
		(width 0.11684)
		(layer "In2.Cu")
		(net "SMB_2_BMC_GPU_SCL")
	)
	(segment
		(start 43.366436 -366.801146)
		(end 43.678348 -366.489234)
		(width 0.11684)
		(layer "In2.Cu")
		(net "SMB_2_BMC_GPU_SCL")
	)
	(segment
		(start 215.174068 -315.530484)
		(end 215.290908 -315.413644)
		(width 0.11684)
		(layer "In2.Cu")
		(net "SMB_2_BMC_GPU_SCL")
	)
	(segment
		(start 211.750656 -322.401692)
		(end 211.750656 -320.234056)
		(width 0.11684)
		(layer "In2.Cu")
		(net "SMB_2_BMC_GPU_SCL")
	)
	(segment
		(start 191.682878 -368.234214)
		(end 205.305152 -354.61194)
		(width 0.11684)
		(layer "In2.Cu")
		(net "SMB_2_BMC_GPU_SCL")
	)
	(segment
		(start 209.738468 -338.89696)
		(end 210.125056 -338.510372)
		(width 0.11684)
		(layer "In2.Cu")
		(net "SMB_2_BMC_GPU_SCL")
	)
	(segment
		(start 215.174068 -314.847224)
		(end 215.174068 -314.631324)
		(width 0.11684)
		(layer "In2.Cu")
		(net "SMB_2_BMC_GPU_SCL")
	)
	(segment
		(start 215.290908 -314.064904)
		(end 215.174068 -313.948064)
		(width 0.11684)
		(layer "In2.Cu")
		(net "SMB_2_BMC_GPU_SCL")
	)
	(segment
		(start 173.466506 -366.833912)
		(end 174.430182 -367.797588)
		(width 0.11684)
		(layer "In2.Cu")
		(net "SMB_2_BMC_GPU_SCL")
	)
	(segment
		(start 215.290908 -310.468264)
		(end 215.174068 -310.351424)
		(width 0.11684)
		(layer "In2.Cu")
		(net "SMB_2_BMC_GPU_SCL")
	)
	(segment
		(start 210.125056 -324.027292)
		(end 211.750656 -322.401692)
		(width 0.11684)
		(layer "In2.Cu")
		(net "SMB_2_BMC_GPU_SCL")
	)
	(segment
		(start 216.134188 -314.964064)
		(end 215.290908 -314.964064)
		(width 0.11684)
		(layer "In2.Cu")
		(net "SMB_2_BMC_GPU_SCL")
	)
	(segment
		(start 40.94734 -366.659668)
		(end 41.088818 -366.801146)
		(width 0.11684)
		(layer "In2.Cu")
		(net "SMB_2_BMC_GPU_SCL")
	)
	(segment
		(start 215.290908 -311.367424)
		(end 215.174068 -311.250584)
		(width 0.11684)
		(layer "In2.Cu")
		(net "SMB_2_BMC_GPU_SCL")
	)
	(segment
		(start 215.174068 -311.034684)
		(end 215.290908 -310.917844)
		(width 0.11684)
		(layer "In2.Cu")
		(net "SMB_2_BMC_GPU_SCL")
	)
	(segment
		(start 216.251028 -314.397644)
		(end 216.251028 -314.181744)
		(width 0.11684)
		(layer "In2.Cu")
		(net "SMB_2_BMC_GPU_SCL")
	)
	(segment
		(start 215.174068 -310.351424)
		(end 215.174068 -215.823546)
		(width 0.11684)
		(layer "In2.Cu")
		(net "SMB_2_BMC_GPU_SCL")
	)
	(segment
		(start 206.660242 -349.693992)
		(end 209.738468 -346.615766)
		(width 0.11684)
		(layer "In2.Cu")
		(net "SMB_2_BMC_GPU_SCL")
	)
	(segment
		(start 216.251028 -310.585104)
		(end 216.134188 -310.468264)
		(width 0.11684)
		(layer "In2.Cu")
		(net "SMB_2_BMC_GPU_SCL")
	)
	(segment
		(start 216.251028 -315.296804)
		(end 216.251028 -315.080904)
		(width 0.11684)
		(layer "In2.Cu")
		(net "SMB_2_BMC_GPU_SCL")
	)
	(segment
		(start 210.125056 -338.510372)
		(end 210.125056 -324.027292)
		(width 0.11684)
		(layer "In2.Cu")
		(net "SMB_2_BMC_GPU_SCL")
	)
	(segment
		(start 216.134188 -313.615324)
		(end 216.251028 -313.498484)
		(width 0.11684)
		(layer "In2.Cu")
		(net "SMB_2_BMC_GPU_SCL")
	)
	(segment
		(start 215.290908 -311.817004)
		(end 216.134188 -311.817004)
		(width 0.11684)
		(layer "In2.Cu")
		(net "SMB_2_BMC_GPU_SCL")
	)
	(segment
		(start 215.290908 -310.917844)
		(end 216.134188 -310.917844)
		(width 0.11684)
		(layer "In2.Cu")
		(net "SMB_2_BMC_GPU_SCL")
	)
	(segment
		(start 174.430182 -367.797588)
		(end 174.430182 -368.08029)
		(width 0.11684)
		(layer "In2.Cu")
		(net "SMB_2_BMC_GPU_SCL")
	)
	(segment
		(start 216.251028 -312.599324)
		(end 216.251028 -312.383424)
		(width 0.11684)
		(layer "In2.Cu")
		(net "SMB_2_BMC_GPU_SCL")
	)
	(segment
		(start 183.424068 -368.234214)
		(end 191.682878 -368.234214)
		(width 0.11684)
		(layer "In2.Cu")
		(net "SMB_2_BMC_GPU_SCL")
	)
	(segment
		(start 215.290908 -313.165744)
		(end 215.174068 -313.048904)
		(width 0.11684)
		(layer "In2.Cu")
		(net "SMB_2_BMC_GPU_SCL")
	)
	(segment
		(start 216.134188 -311.817004)
		(end 216.251028 -311.700164)
		(width 0.11684)
		(layer "In2.Cu")
		(net "SMB_2_BMC_GPU_SCL")
	)
	(segment
		(start 138.82878 -364.854744)
		(end 169.291508 -364.854744)
		(width 0.11684)
		(layer "In2.Cu")
		(net "SMB_2_BMC_GPU_SCL")
	)
	(segment
		(start 215.290908 -314.964064)
		(end 215.174068 -314.847224)
		(width 0.11684)
		(layer "In2.Cu")
		(net "SMB_2_BMC_GPU_SCL")
	)
	(segment
		(start 216.134188 -310.468264)
		(end 215.290908 -310.468264)
		(width 0.11684)
		(layer "In2.Cu")
		(net "SMB_2_BMC_GPU_SCL")
	)
	(segment
		(start 206.404972 -349.693992)
		(end 206.660242 -349.693992)
		(width 0.11684)
		(layer "In2.Cu")
		(net "SMB_2_BMC_GPU_SCL")
	)
	(segment
		(start 215.174068 -311.933844)
		(end 215.290908 -311.817004)
		(width 0.11684)
		(layer "In2.Cu")
		(net "SMB_2_BMC_GPU_SCL")
	)
	(segment
		(start 216.134188 -314.064904)
		(end 215.290908 -314.064904)
		(width 0.11684)
		(layer "In2.Cu")
		(net "SMB_2_BMC_GPU_SCL")
	)
	(segment
		(start 179.791614 -368.836448)
		(end 180.5305 -369.575334)
		(width 0.11684)
		(layer "In2.Cu")
		(net "SMB_2_BMC_GPU_SCL")
	)
	(segment
		(start 211.750656 -320.234056)
		(end 215.174068 -316.810644)
		(width 0.11684)
		(layer "In2.Cu")
		(net "SMB_2_BMC_GPU_SCL")
	)
	(segment
		(start 216.251028 -312.383424)
		(end 216.134188 -312.266584)
		(width 0.11684)
		(layer "In2.Cu")
		(net "SMB_2_BMC_GPU_SCL")
	)
	(segment
		(start 216.251028 -315.080904)
		(end 216.134188 -314.964064)
		(width 0.11684)
		(layer "In2.Cu")
		(net "SMB_2_BMC_GPU_SCL")
	)
	(segment
		(start 216.134188 -310.917844)
		(end 216.251028 -310.801004)
		(width 0.11684)
		(layer "In2.Cu")
		(net "SMB_2_BMC_GPU_SCL")
	)
	(segment
		(start 216.251028 -311.484264)
		(end 216.134188 -311.367424)
		(width 0.11684)
		(layer "In2.Cu")
		(net "SMB_2_BMC_GPU_SCL")
	)
	(segment
		(start 215.290908 -312.716164)
		(end 216.134188 -312.716164)
		(width 0.11684)
		(layer "In2.Cu")
		(net "SMB_2_BMC_GPU_SCL")
	)
	(segment
		(start 216.251028 -310.801004)
		(end 216.251028 -310.585104)
		(width 0.11684)
		(layer "In2.Cu")
		(net "SMB_2_BMC_GPU_SCL")
	)
	(segment
		(start 205.305152 -354.61194)
		(end 205.305152 -350.793812)
		(width 0.11684)
		(layer "In2.Cu")
		(net "SMB_2_BMC_GPU_SCL")
	)
	(segment
		(start 215.174068 -314.631324)
		(end 215.290908 -314.514484)
		(width 0.11684)
		(layer "In2.Cu")
		(net "SMB_2_BMC_GPU_SCL")
	)
	(segment
		(start 215.174068 -316.810644)
		(end 215.174068 -315.530484)
		(width 0.11684)
		(layer "In2.Cu")
		(net "SMB_2_BMC_GPU_SCL")
	)
	(segment
		(start 216.251028 -313.282584)
		(end 216.134188 -313.165744)
		(width 0.11684)
		(layer "In2.Cu")
		(net "SMB_2_BMC_GPU_SCL")
	)
	(segment
		(start 180.5305 -369.575334)
		(end 182.082948 -369.575334)
		(width 0.11684)
		(layer "In2.Cu")
		(net "SMB_2_BMC_GPU_SCL")
	)
	(segment
		(start 216.134188 -313.165744)
		(end 215.290908 -313.165744)
		(width 0.11684)
		(layer "In2.Cu")
		(net "SMB_2_BMC_GPU_SCL")
	)
	(segment
		(start 215.290908 -312.266584)
		(end 215.174068 -312.149744)
		(width 0.11684)
		(layer "In2.Cu")
		(net "SMB_2_BMC_GPU_SCL")
	)
	(segment
		(start 43.678348 -366.489234)
		(end 137.19429 -366.489234)
		(width 0.11684)
		(layer "In2.Cu")
		(net "SMB_2_BMC_GPU_SCL")
	)
	(segment
		(start 215.174068 -312.149744)
		(end 215.174068 -311.933844)
		(width 0.11684)
		(layer "In2.Cu")
		(net "SMB_2_BMC_GPU_SCL")
	)
	(segment
		(start 216.134188 -314.514484)
		(end 216.251028 -314.397644)
		(width 0.11684)
		(layer "In2.Cu")
		(net "SMB_2_BMC_GPU_SCL")
	)
	(segment
		(start 169.291508 -364.854744)
		(end 171.270676 -366.833912)
		(width 0.11684)
		(layer "In2.Cu")
		(net "SMB_2_BMC_GPU_SCL")
	)
	(segment
		(start 174.430182 -368.08029)
		(end 175.18634 -368.836448)
		(width 0.11684)
		(layer "In2.Cu")
		(net "SMB_2_BMC_GPU_SCL")
	)
	(segment
		(start 215.290908 -313.615324)
		(end 216.134188 -313.615324)
		(width 0.11684)
		(layer "In2.Cu")
		(net "SMB_2_BMC_GPU_SCL")
	)
	(segment
		(start 215.174068 -313.948064)
		(end 215.174068 -313.732164)
		(width 0.11684)
		(layer "In2.Cu")
		(net "SMB_2_BMC_GPU_SCL")
	)
	(segment
		(start 215.174068 -313.048904)
		(end 215.174068 -312.833004)
		(width 0.11684)
		(layer "In2.Cu")
		(net "SMB_2_BMC_GPU_SCL")
	)
	(segment
		(start 216.134188 -315.413644)
		(end 216.251028 -315.296804)
		(width 0.11684)
		(layer "In2.Cu")
		(net "SMB_2_BMC_GPU_SCL")
	)
	(segment
		(start 209.738468 -346.615766)
		(end 209.738468 -338.89696)
		(width 0.11684)
		(layer "In2.Cu")
		(net "SMB_2_BMC_GPU_SCL")
	)
	(segment
		(start 41.088818 -366.801146)
		(end 43.366436 -366.801146)
		(width 0.11684)
		(layer "In2.Cu")
		(net "SMB_2_BMC_GPU_SCL")
	)
	(segment
		(start 182.082948 -369.575334)
		(end 183.424068 -368.234214)
		(width 0.11684)
		(layer "In2.Cu")
		(net "SMB_2_BMC_GPU_SCL")
	)
	(segment
		(start 171.270676 -366.833912)
		(end 173.466506 -366.833912)
		(width 0.11684)
		(layer "In2.Cu")
		(net "SMB_2_BMC_GPU_SCL")
	)
	(segment
		(start 216.251028 -314.181744)
		(end 216.134188 -314.064904)
		(width 0.11684)
		(layer "In2.Cu")
		(net "SMB_2_BMC_GPU_SCL")
	)
	(segment
		(start 215.174068 -312.833004)
		(end 215.290908 -312.716164)
		(width 0.11684)
		(layer "In2.Cu")
		(net "SMB_2_BMC_GPU_SCL")
	)
	(segment
		(start 215.290908 -314.514484)
		(end 216.134188 -314.514484)
		(width 0.11684)
		(layer "In2.Cu")
		(net "SMB_2_BMC_GPU_SCL")
	)
	(segment
		(start 216.251028 -311.700164)
		(end 216.251028 -311.484264)
		(width 0.11684)
		(layer "In2.Cu")
		(net "SMB_2_BMC_GPU_SCL")
	)
	(segment
		(start 215.174068 -311.250584)
		(end 215.174068 -311.034684)
		(width 0.11684)
		(layer "In2.Cu")
		(net "SMB_2_BMC_GPU_SCL")
	)
	(segment
		(start 216.251028 -313.498484)
		(end 216.251028 -313.282584)
		(width 0.11684)
		(layer "In2.Cu")
		(net "SMB_2_BMC_GPU_SCL")
	)
	(segment
		(start 137.19429 -366.489234)
		(end 138.82878 -364.854744)
		(width 0.11684)
		(layer "In2.Cu")
		(net "SMB_2_BMC_GPU_SCL")
	)
	(segment
		(start 215.290908 -315.413644)
		(end 216.134188 -315.413644)
		(width 0.11684)
		(layer "In2.Cu")
		(net "SMB_2_BMC_GPU_SCL")
	)
	(segment
		(start 216.134188 -312.716164)
		(end 216.251028 -312.599324)
		(width 0.11684)
		(layer "In2.Cu")
		(net "SMB_2_BMC_GPU_SCL")
	)
	(segment
		(start 205.305152 -350.793812)
		(end 206.404972 -349.693992)
		(width 0.11684)
		(layer "In2.Cu")
		(net "SMB_2_BMC_GPU_SCL")
	)
	(segment
		(start 175.18634 -368.836448)
		(end 179.791614 -368.836448)
		(width 0.11684)
		(layer "In2.Cu")
		(net "SMB_2_BMC_GPU_SCL")
	)
	(segment
		(start 216.134188 -311.367424)
		(end 215.290908 -311.367424)
		(width 0.11684)
		(layer "In2.Cu")
		(net "SMB_2_BMC_GPU_SCL")
	)
	(segment
		(start 215.174068 -215.823546)
		(end 219.296488 -211.701126)
		(width 0.11684)
		(layer "In2.Cu")
		(net "SMB_2_BMC_GPU_SCL")
	)
	(segment
		(start 216.134188 -312.266584)
		(end 215.290908 -312.266584)
		(width 0.11684)
		(layer "In2.Cu")
		(net "SMB_2_BMC_GPU_SCL")
	)
	(segment
		(start 155.35148 -19.308064)
		(end 155.35148 -16.629888)
		(width 0.11684)
		(layer "In4.Cu")
		(net "SMB_2_BMC_GPU_SCL")
	)
	(segment
		(start 186.975242 -45.165772)
		(end 179.754276 -37.944806)
		(width 0.11684)
		(layer "In4.Cu")
		(net "SMB_2_BMC_GPU_SCL")
	)
	(segment
		(start 166.695628 -33.78962)
		(end 161.274506 -28.368498)
		(width 0.11684)
		(layer "In4.Cu")
		(net "SMB_2_BMC_GPU_SCL")
	)
	(segment
		(start 186.975242 -87.392764)
		(end 186.975242 -45.165772)
		(width 0.11684)
		(layer "In4.Cu")
		(net "SMB_2_BMC_GPU_SCL")
	)
	(segment
		(start 161.274506 -21.647404)
		(end 159.619442 -19.99234)
		(width 0.11684)
		(layer "In4.Cu")
		(net "SMB_2_BMC_GPU_SCL")
	)
	(segment
		(start 175.65878 -36.283646)
		(end 173.164754 -33.78962)
		(width 0.11684)
		(layer "In4.Cu")
		(net "SMB_2_BMC_GPU_SCL")
	)
	(segment
		(start 159.619442 -19.99234)
		(end 156.035756 -19.99234)
		(width 0.11684)
		(layer "In4.Cu")
		(net "SMB_2_BMC_GPU_SCL")
	)
	(segment
		(start 161.274506 -28.368498)
		(end 161.274506 -21.647404)
		(width 0.11684)
		(layer "In4.Cu")
		(net "SMB_2_BMC_GPU_SCL")
	)
	(segment
		(start 155.35148 -16.629888)
		(end 156.67101 -15.310358)
		(width 0.11684)
		(layer "In4.Cu")
		(net "SMB_2_BMC_GPU_SCL")
	)
	(segment
		(start 187.648342 -88.065864)
		(end 186.975242 -87.392764)
		(width 0.11684)
		(layer "In4.Cu")
		(net "SMB_2_BMC_GPU_SCL")
	)
	(segment
		(start 156.035756 -19.99234)
		(end 155.35148 -19.308064)
		(width 0.11684)
		(layer "In4.Cu")
		(net "SMB_2_BMC_GPU_SCL")
	)
	(segment
		(start 175.744378 -36.283646)
		(end 175.65878 -36.283646)
		(width 0.11684)
		(layer "In4.Cu")
		(net "SMB_2_BMC_GPU_SCL")
	)
	(segment
		(start 173.164754 -33.78962)
		(end 166.695628 -33.78962)
		(width 0.11684)
		(layer "In4.Cu")
		(net "SMB_2_BMC_GPU_SCL")
	)
	(segment
		(start 179.754276 -37.944806)
		(end 175.744378 -36.283646)
		(width 0.11684)
		(layer "In4.Cu")
		(net "SMB_2_BMC_GPU_SCL")
	)
	(segment
		(start 43.122342 -432.842416)
		(end 43.122342 -437.714644)
		(width 0.11684)
		(layer "In11.Cu")
		(net "SMB_2_BMC_GPU_SCL")
	)
	(segment
		(start 43.122342 -437.714644)
		(end 42.441368 -438.395618)
		(width 0.11684)
		(layer "In11.Cu")
		(net "SMB_2_BMC_GPU_SCL")
	)
	(segment
		(start 40.947086 -366.659922)
		(end 40.947086 -372.486174)
		(width 0.11684)
		(layer "In11.Cu")
		(net "SMB_2_BMC_GPU_SCL")
	)
	(segment
		(start 36.613846 -406.680416)
		(end 44.06773 -414.1343)
		(width 0.11684)
		(layer "In11.Cu")
		(net "SMB_2_BMC_GPU_SCL")
	)
	(segment
		(start 44.06773 -431.897028)
		(end 43.122342 -432.842416)
		(width 0.11684)
		(layer "In11.Cu")
		(net "SMB_2_BMC_GPU_SCL")
	)
	(segment
		(start 44.06773 -414.1343)
		(end 44.06773 -431.897028)
		(width 0.11684)
		(layer "In11.Cu")
		(net "SMB_2_BMC_GPU_SCL")
	)
	(segment
		(start 42.66438 -382.767078)
		(end 39.49954 -385.931918)
		(width 0.11684)
		(layer "In11.Cu")
		(net "SMB_2_BMC_GPU_SCL")
	)
	(segment
		(start 40.94734 -366.659668)
		(end 40.947086 -366.659922)
		(width 0.11684)
		(layer "In11.Cu")
		(net "SMB_2_BMC_GPU_SCL")
	)
	(segment
		(start 37.290756 -438.395618)
		(end 37.206682 -438.311544)
		(width 0.11684)
		(layer "In11.Cu")
		(net "SMB_2_BMC_GPU_SCL")
	)
	(segment
		(start 42.66438 -374.203468)
		(end 42.66438 -382.767078)
		(width 0.11684)
		(layer "In11.Cu")
		(net "SMB_2_BMC_GPU_SCL")
	)
	(segment
		(start 39.49954 -385.931918)
		(end 39.49954 -388.589266)
		(width 0.11684)
		(layer "In11.Cu")
		(net "SMB_2_BMC_GPU_SCL")
	)
	(segment
		(start 36.613846 -402.812758)
		(end 36.613846 -406.680416)
		(width 0.11684)
		(layer "In11.Cu")
		(net "SMB_2_BMC_GPU_SCL")
	)
	(segment
		(start 40.947086 -372.486174)
		(end 42.66438 -374.203468)
		(width 0.11684)
		(layer "In11.Cu")
		(net "SMB_2_BMC_GPU_SCL")
	)
	(segment
		(start 39.76116 -394.162788)
		(end 39.76116 -399.665444)
		(width 0.11684)
		(layer "In11.Cu")
		(net "SMB_2_BMC_GPU_SCL")
	)
	(segment
		(start 39.49954 -388.589266)
		(end 40.343074 -389.4328)
		(width 0.11684)
		(layer "In11.Cu")
		(net "SMB_2_BMC_GPU_SCL")
	)
	(segment
		(start 39.76116 -399.665444)
		(end 36.613846 -402.812758)
		(width 0.11684)
		(layer "In11.Cu")
		(net "SMB_2_BMC_GPU_SCL")
	)
	(segment
		(start 40.343074 -393.580874)
		(end 39.76116 -394.162788)
		(width 0.11684)
		(layer "In11.Cu")
		(net "SMB_2_BMC_GPU_SCL")
	)
	(segment
		(start 42.441368 -438.395618)
		(end 37.290756 -438.395618)
		(width 0.11684)
		(layer "In11.Cu")
		(net "SMB_2_BMC_GPU_SCL")
	)
	(segment
		(start 40.343074 -389.4328)
		(end 40.343074 -393.580874)
		(width 0.11684)
		(layer "In11.Cu")
		(net "SMB_2_BMC_GPU_SCL")
	)
	(segment
		(start 21.636228 -435.948074)
		(end 20.828 -435.948074)
		(width 0.10668)
		(layer "F.Cu")
		(net "SMB_2_BMC_GPU_BUF_SDA")
	)
	(via
		(at 20.828 -435.948074)
		(size 0.508)
		(drill 0.254)
		(layers "F.Cu" "B.Cu")
		(net "SMB_2_BMC_GPU_BUF_SDA")
	)
	(segment
		(start 41.860216 -428.79645)
		(end 47.27575 -423.380916)
		(width 0.11684)
		(layer "In2.Cu")
		(net "SMB_2_BMC_GPU_BUF_SDA")
	)
	(segment
		(start 34.848292 -434.266086)
		(end 36.233608 -435.651402)
		(width 0.11684)
		(layer "In2.Cu")
		(net "SMB_2_BMC_GPU_BUF_SDA")
	)
	(segment
		(start 61.828426 -418.068506)
		(end 62.649862 -418.889942)
		(width 0.11684)
		(layer "In2.Cu")
		(net "SMB_2_BMC_GPU_BUF_SDA")
	)
	(segment
		(start 47.584106 -415.73323)
		(end 48.2473 -415.070036)
		(width 0.11684)
		(layer "In2.Cu")
		(net "SMB_2_BMC_GPU_BUF_SDA")
	)
	(segment
		(start 22.509988 -434.266086)
		(end 34.848292 -434.266086)
		(width 0.11684)
		(layer "In2.Cu")
		(net "SMB_2_BMC_GPU_BUF_SDA")
	)
	(segment
		(start 60.902342 -415.070036)
		(end 61.828426 -415.99612)
		(width 0.11684)
		(layer "In2.Cu")
		(net "SMB_2_BMC_GPU_BUF_SDA")
	)
	(segment
		(start 38.009322 -435.651402)
		(end 39.919148 -433.741576)
		(width 0.11684)
		(layer "In2.Cu")
		(net "SMB_2_BMC_GPU_BUF_SDA")
	)
	(segment
		(start 20.828 -435.948074)
		(end 22.509988 -434.266086)
		(width 0.11684)
		(layer "In2.Cu")
		(net "SMB_2_BMC_GPU_BUF_SDA")
	)
	(segment
		(start 61.828426 -415.99612)
		(end 61.828426 -418.068506)
		(width 0.11684)
		(layer "In2.Cu")
		(net "SMB_2_BMC_GPU_BUF_SDA")
	)
	(segment
		(start 36.233608 -435.651402)
		(end 38.009322 -435.651402)
		(width 0.11684)
		(layer "In2.Cu")
		(net "SMB_2_BMC_GPU_BUF_SDA")
	)
	(segment
		(start 39.919148 -433.741576)
		(end 41.452546 -433.741576)
		(width 0.11684)
		(layer "In2.Cu")
		(net "SMB_2_BMC_GPU_BUF_SDA")
	)
	(segment
		(start 47.27575 -423.380916)
		(end 47.27575 -419.11397)
		(width 0.11684)
		(layer "In2.Cu")
		(net "SMB_2_BMC_GPU_BUF_SDA")
	)
	(segment
		(start 47.584106 -418.805614)
		(end 47.584106 -415.73323)
		(width 0.11684)
		(layer "In2.Cu")
		(net "SMB_2_BMC_GPU_BUF_SDA")
	)
	(segment
		(start 48.2473 -415.070036)
		(end 60.902342 -415.070036)
		(width 0.11684)
		(layer "In2.Cu")
		(net "SMB_2_BMC_GPU_BUF_SDA")
	)
	(segment
		(start 41.860216 -433.333906)
		(end 41.860216 -428.79645)
		(width 0.11684)
		(layer "In2.Cu")
		(net "SMB_2_BMC_GPU_BUF_SDA")
	)
	(segment
		(start 41.452546 -433.741576)
		(end 41.860216 -433.333906)
		(width 0.11684)
		(layer "In2.Cu")
		(net "SMB_2_BMC_GPU_BUF_SDA")
	)
	(segment
		(start 47.27575 -419.11397)
		(end 47.584106 -418.805614)
		(width 0.11684)
		(layer "In2.Cu")
		(net "SMB_2_BMC_GPU_BUF_SDA")
	)
	(segment
		(start 36.281868 -436.433214)
		(end 37.084 -436.433214)
		(width 0.10668)
		(layer "F.Cu")
		(net "SMB_2_BMC_GPU_BUF_SCL")
	)
	(via
		(at 37.084 -436.433214)
		(size 0.508)
		(drill 0.254)
		(layers "F.Cu" "B.Cu")
		(net "SMB_2_BMC_GPU_BUF_SCL")
	)
	(segment
		(start 45.265594 -426.152564)
		(end 45.265594 -425.987464)
		(width 0.11684)
		(layer "In2.Cu")
		(net "SMB_2_BMC_GPU_BUF_SCL")
	)
	(segment
		(start 43.510454 -427.742604)
		(end 43.675554 -427.742604)
		(width 0.11684)
		(layer "In2.Cu")
		(net "SMB_2_BMC_GPU_BUF_SCL")
	)
	(segment
		(start 44.176442 -431.256948)
		(end 44.059602 -431.140108)
		(width 0.11684)
		(layer "In2.Cu")
		(net "SMB_2_BMC_GPU_BUF_SCL")
	)
	(segment
		(start 44.059602 -432.039268)
		(end 42.40276 -432.039268)
		(width 0.11684)
		(layer "In2.Cu")
		(net "SMB_2_BMC_GPU_BUF_SCL")
	)
	(segment
		(start 42.28592 -431.922428)
		(end 42.28592 -431.706528)
		(width 0.11684)
		(layer "In2.Cu")
		(net "SMB_2_BMC_GPU_BUF_SCL")
	)
	(segment
		(start 42.40276 -432.039268)
		(end 42.28592 -431.922428)
		(width 0.11684)
		(layer "In2.Cu")
		(net "SMB_2_BMC_GPU_BUF_SCL")
	)
	(segment
		(start 45.025564 -428.456344)
		(end 43.993562 -427.424596)
		(width 0.11684)
		(layer "In2.Cu")
		(net "SMB_2_BMC_GPU_BUF_SCL")
	)
	(segment
		(start 47.69739 -423.555668)
		(end 47.69739 -419.288722)
		(width 0.11684)
		(layer "In2.Cu")
		(net "SMB_2_BMC_GPU_BUF_SCL")
	)
	(segment
		(start 43.993562 -427.259496)
		(end 44.14647 -427.106588)
		(width 0.11684)
		(layer "In2.Cu")
		(net "SMB_2_BMC_GPU_BUF_SCL")
	)
	(segment
		(start 47.69739 -419.288722)
		(end 48.005746 -418.980366)
		(width 0.11684)
		(layer "In2.Cu")
		(net "SMB_2_BMC_GPU_BUF_SCL")
	)
	(segment
		(start 46.144688 -427.50232)
		(end 46.297596 -427.349412)
		(width 0.11684)
		(layer "In2.Cu")
		(net "SMB_2_BMC_GPU_BUF_SCL")
	)
	(segment
		(start 42.40276 -430.240948)
		(end 42.28592 -430.124108)
		(width 0.11684)
		(layer "In2.Cu")
		(net "SMB_2_BMC_GPU_BUF_SCL")
	)
	(segment
		(start 44.059602 -432.488848)
		(end 44.176442 -432.372008)
		(width 0.11684)
		(layer "In2.Cu")
		(net "SMB_2_BMC_GPU_BUF_SCL")
	)
	(segment
		(start 44.629578 -426.78858)
		(end 44.629578 -426.62348)
		(width 0.11684)
		(layer "In2.Cu")
		(net "SMB_2_BMC_GPU_BUF_SCL")
	)
	(segment
		(start 45.265594 -425.987464)
		(end 47.69739 -423.555668)
		(width 0.11684)
		(layer "In2.Cu")
		(net "SMB_2_BMC_GPU_BUF_SCL")
	)
	(segment
		(start 44.176442 -432.372008)
		(end 44.176442 -432.156108)
		(width 0.11684)
		(layer "In2.Cu")
		(net "SMB_2_BMC_GPU_BUF_SCL")
	)
	(segment
		(start 42.28592 -430.807368)
		(end 42.40276 -430.690528)
		(width 0.11684)
		(layer "In2.Cu")
		(net "SMB_2_BMC_GPU_BUF_SCL")
	)
	(segment
		(start 45.979588 -427.50232)
		(end 46.144688 -427.50232)
		(width 0.11684)
		(layer "In2.Cu")
		(net "SMB_2_BMC_GPU_BUF_SCL")
	)
	(segment
		(start 45.508672 -428.138336)
		(end 45.66158 -427.985428)
		(width 0.11684)
		(layer "In2.Cu")
		(net "SMB_2_BMC_GPU_BUF_SCL")
	)
	(segment
		(start 42.28592 -430.124108)
		(end 42.28592 -428.967138)
		(width 0.11684)
		(layer "In2.Cu")
		(net "SMB_2_BMC_GPU_BUF_SCL")
	)
	(segment
		(start 39.986712 -435.893718)
		(end 39.986712 -435.42331)
		(width 0.11684)
		(layer "In2.Cu")
		(net "SMB_2_BMC_GPU_BUF_SCL")
	)
	(segment
		(start 44.31157 -427.106588)
		(end 45.343572 -428.138336)
		(width 0.11684)
		(layer "In2.Cu")
		(net "SMB_2_BMC_GPU_BUF_SCL")
	)
	(segment
		(start 43.993562 -427.424596)
		(end 43.993562 -427.259496)
		(width 0.11684)
		(layer "In2.Cu")
		(net "SMB_2_BMC_GPU_BUF_SCL")
	)
	(segment
		(start 42.41292 -432.488848)
		(end 44.059602 -432.488848)
		(width 0.11684)
		(layer "In2.Cu")
		(net "SMB_2_BMC_GPU_BUF_SCL")
	)
	(segment
		(start 43.675554 -427.742604)
		(end 44.707556 -428.774352)
		(width 0.11684)
		(layer "In2.Cu")
		(net "SMB_2_BMC_GPU_BUF_SCL")
	)
	(segment
		(start 44.059602 -431.589688)
		(end 44.176442 -431.472848)
		(width 0.11684)
		(layer "In2.Cu")
		(net "SMB_2_BMC_GPU_BUF_SCL")
	)
	(segment
		(start 61.387228 -418.827204)
		(end 62.649862 -420.089838)
		(width 0.11684)
		(layer "In2.Cu")
		(net "SMB_2_BMC_GPU_BUF_SCL")
	)
	(segment
		(start 42.40276 -431.140108)
		(end 42.28592 -431.023268)
		(width 0.11684)
		(layer "In2.Cu")
		(net "SMB_2_BMC_GPU_BUF_SCL")
	)
	(segment
		(start 45.025564 -428.621444)
		(end 45.025564 -428.456344)
		(width 0.11684)
		(layer "In2.Cu")
		(net "SMB_2_BMC_GPU_BUF_SCL")
	)
	(segment
		(start 44.059602 -431.140108)
		(end 42.40276 -431.140108)
		(width 0.11684)
		(layer "In2.Cu")
		(net "SMB_2_BMC_GPU_BUF_SCL")
	)
	(segment
		(start 61.387228 -416.338258)
		(end 61.387228 -418.827204)
		(width 0.11684)
		(layer "In2.Cu")
		(net "SMB_2_BMC_GPU_BUF_SCL")
	)
	(segment
		(start 48.005746 -415.913824)
		(end 48.427894 -415.491676)
		(width 0.11684)
		(layer "In2.Cu")
		(net "SMB_2_BMC_GPU_BUF_SCL")
	)
	(segment
		(start 48.005746 -418.980366)
		(end 48.005746 -415.913824)
		(width 0.11684)
		(layer "In2.Cu")
		(net "SMB_2_BMC_GPU_BUF_SCL")
	)
	(segment
		(start 37.084 -436.433214)
		(end 39.447216 -436.433214)
		(width 0.11684)
		(layer "In2.Cu")
		(net "SMB_2_BMC_GPU_BUF_SCL")
	)
	(segment
		(start 45.66158 -427.820328)
		(end 44.629578 -426.78858)
		(width 0.11684)
		(layer "In2.Cu")
		(net "SMB_2_BMC_GPU_BUF_SCL")
	)
	(segment
		(start 44.059602 -430.690528)
		(end 44.176442 -430.573688)
		(width 0.11684)
		(layer "In2.Cu")
		(net "SMB_2_BMC_GPU_BUF_SCL")
	)
	(segment
		(start 41.117012 -434.29301)
		(end 41.762426 -434.29301)
		(width 0.11684)
		(layer "In2.Cu")
		(net "SMB_2_BMC_GPU_BUF_SCL")
	)
	(segment
		(start 44.176442 -430.357788)
		(end 44.059602 -430.240948)
		(width 0.11684)
		(layer "In2.Cu")
		(net "SMB_2_BMC_GPU_BUF_SCL")
	)
	(segment
		(start 46.297596 -427.184312)
		(end 45.265594 -426.152564)
		(width 0.11684)
		(layer "In2.Cu")
		(net "SMB_2_BMC_GPU_BUF_SCL")
	)
	(segment
		(start 44.176442 -430.573688)
		(end 44.176442 -430.357788)
		(width 0.11684)
		(layer "In2.Cu")
		(net "SMB_2_BMC_GPU_BUF_SCL")
	)
	(segment
		(start 44.14647 -427.106588)
		(end 44.31157 -427.106588)
		(width 0.11684)
		(layer "In2.Cu")
		(net "SMB_2_BMC_GPU_BUF_SCL")
	)
	(segment
		(start 42.28592 -432.615848)
		(end 42.41292 -432.488848)
		(width 0.11684)
		(layer "In2.Cu")
		(net "SMB_2_BMC_GPU_BUF_SCL")
	)
	(segment
		(start 39.986712 -435.42331)
		(end 41.117012 -434.29301)
		(width 0.11684)
		(layer "In2.Cu")
		(net "SMB_2_BMC_GPU_BUF_SCL")
	)
	(segment
		(start 60.540646 -415.491676)
		(end 61.387228 -416.338258)
		(width 0.11684)
		(layer "In2.Cu")
		(net "SMB_2_BMC_GPU_BUF_SCL")
	)
	(segment
		(start 42.28592 -431.706528)
		(end 42.40276 -431.589688)
		(width 0.11684)
		(layer "In2.Cu")
		(net "SMB_2_BMC_GPU_BUF_SCL")
	)
	(segment
		(start 45.66158 -427.985428)
		(end 45.66158 -427.820328)
		(width 0.11684)
		(layer "In2.Cu")
		(net "SMB_2_BMC_GPU_BUF_SCL")
	)
	(segment
		(start 44.059602 -430.240948)
		(end 42.40276 -430.240948)
		(width 0.11684)
		(layer "In2.Cu")
		(net "SMB_2_BMC_GPU_BUF_SCL")
	)
	(segment
		(start 44.629578 -426.62348)
		(end 44.782486 -426.470572)
		(width 0.11684)
		(layer "In2.Cu")
		(net "SMB_2_BMC_GPU_BUF_SCL")
	)
	(segment
		(start 42.40276 -431.589688)
		(end 44.059602 -431.589688)
		(width 0.11684)
		(layer "In2.Cu")
		(net "SMB_2_BMC_GPU_BUF_SCL")
	)
	(segment
		(start 44.176442 -431.472848)
		(end 44.176442 -431.256948)
		(width 0.11684)
		(layer "In2.Cu")
		(net "SMB_2_BMC_GPU_BUF_SCL")
	)
	(segment
		(start 44.707556 -428.774352)
		(end 44.872656 -428.774352)
		(width 0.11684)
		(layer "In2.Cu")
		(net "SMB_2_BMC_GPU_BUF_SCL")
	)
	(segment
		(start 42.28592 -428.967138)
		(end 43.510454 -427.742604)
		(width 0.11684)
		(layer "In2.Cu")
		(net "SMB_2_BMC_GPU_BUF_SCL")
	)
	(segment
		(start 42.40276 -430.690528)
		(end 44.059602 -430.690528)
		(width 0.11684)
		(layer "In2.Cu")
		(net "SMB_2_BMC_GPU_BUF_SCL")
	)
	(segment
		(start 46.297596 -427.349412)
		(end 46.297596 -427.184312)
		(width 0.11684)
		(layer "In2.Cu")
		(net "SMB_2_BMC_GPU_BUF_SCL")
	)
	(segment
		(start 44.872656 -428.774352)
		(end 45.025564 -428.621444)
		(width 0.11684)
		(layer "In2.Cu")
		(net "SMB_2_BMC_GPU_BUF_SCL")
	)
	(segment
		(start 42.28592 -431.023268)
		(end 42.28592 -430.807368)
		(width 0.11684)
		(layer "In2.Cu")
		(net "SMB_2_BMC_GPU_BUF_SCL")
	)
	(segment
		(start 44.176442 -432.156108)
		(end 44.059602 -432.039268)
		(width 0.11684)
		(layer "In2.Cu")
		(net "SMB_2_BMC_GPU_BUF_SCL")
	)
	(segment
		(start 39.447216 -436.433214)
		(end 39.986712 -435.893718)
		(width 0.11684)
		(layer "In2.Cu")
		(net "SMB_2_BMC_GPU_BUF_SCL")
	)
	(segment
		(start 41.762426 -434.29301)
		(end 42.28592 -433.769516)
		(width 0.11684)
		(layer "In2.Cu")
		(net "SMB_2_BMC_GPU_BUF_SCL")
	)
	(segment
		(start 45.343572 -428.138336)
		(end 45.508672 -428.138336)
		(width 0.11684)
		(layer "In2.Cu")
		(net "SMB_2_BMC_GPU_BUF_SCL")
	)
	(segment
		(start 48.427894 -415.491676)
		(end 60.540646 -415.491676)
		(width 0.11684)
		(layer "In2.Cu")
		(net "SMB_2_BMC_GPU_BUF_SCL")
	)
	(segment
		(start 42.28592 -433.769516)
		(end 42.28592 -432.615848)
		(width 0.11684)
		(layer "In2.Cu")
		(net "SMB_2_BMC_GPU_BUF_SCL")
	)
	(segment
		(start 44.947586 -426.470572)
		(end 45.979588 -427.50232)
		(width 0.11684)
		(layer "In2.Cu")
		(net "SMB_2_BMC_GPU_BUF_SCL")
	)
	(segment
		(start 44.782486 -426.470572)
		(end 44.947586 -426.470572)
		(width 0.11684)
		(layer "In2.Cu")
		(net "SMB_2_BMC_GPU_BUF_SCL")
	)
	(segment
		(start 162.666934 -12.633452)
		(end 162.528504 -12.495022)
		(width 0.10668)
		(layer "F.Cu")
		(net "SMB_1_PLD_3V3AUX_SDA_R3")
	)
	(segment
		(start 162.666934 -13.599922)
		(end 162.666934 -12.633452)
		(width 0.10668)
		(layer "F.Cu")
		(net "SMB_1_PLD_3V3AUX_SDA_R3")
	)
	(via
		(at 162.528504 -12.495022)
		(size 0.508)
		(drill 0.254)
		(layers "F.Cu" "B.Cu")
		(net "SMB_1_PLD_3V3AUX_SDA_R3")
	)
	(segment
		(start 161.09188 -12.856464)
		(end 161.453322 -12.495022)
		(width 0.10668)
		(layer "B.Cu")
		(net "SMB_1_PLD_3V3AUX_SDA_R3")
	)
	(segment
		(start 161.453322 -12.495022)
		(end 162.528504 -12.495022)
		(width 0.10668)
		(layer "B.Cu")
		(net "SMB_1_PLD_3V3AUX_SDA_R3")
	)
	(segment
		(start 161.09188 -14.95806)
		(end 161.09188 -12.856464)
		(width 0.10668)
		(layer "B.Cu")
		(net "SMB_1_PLD_3V3AUX_SDA_R3")
	)
	(segment
		(start 170.791378 -115.276376)
		(end 170.18 -115.276376)
		(width 0.10668)
		(layer "F.Cu")
		(net "SMB_1_PLD_3V3AUX_SDA_R1")
	)
	(segment
		(start 170.79595 -115.280948)
		(end 170.791378 -115.276376)
		(width 0.10668)
		(layer "F.Cu")
		(net "SMB_1_PLD_3V3AUX_SDA_R1")
	)
	(via
		(at 159.167068 -18.12671)
		(size 0.508)
		(drill 0.254)
		(layers "F.Cu" "B.Cu")
		(net "SMB_1_PLD_3V3AUX_SDA_R1")
	)
	(via
		(at 170.18 -115.276376)
		(size 0.508)
		(drill 0.254)
		(layers "F.Cu" "B.Cu")
		(net "SMB_1_PLD_3V3AUX_SDA_R1")
	)
	(segment
		(start 160.29178 -17.79016)
		(end 159.503618 -17.79016)
		(width 0.10668)
		(layer "B.Cu")
		(net "SMB_1_PLD_3V3AUX_SDA_R1")
	)
	(segment
		(start 159.503618 -17.79016)
		(end 159.167068 -18.12671)
		(width 0.10668)
		(layer "B.Cu")
		(net "SMB_1_PLD_3V3AUX_SDA_R1")
	)
	(segment
		(start 159.167068 -18.12671)
		(end 159.19577 -18.12671)
		(width 0.11684)
		(layer "In11.Cu")
		(net "SMB_1_PLD_3V3AUX_SDA_R1")
	)
	(segment
		(start 170.64482 -116.942616)
		(end 170.64482 -115.741196)
		(width 0.11684)
		(layer "In11.Cu")
		(net "SMB_1_PLD_3V3AUX_SDA_R1")
	)
	(segment
		(start 164.164264 -57.463436)
		(end 164.164264 -64.802766)
		(width 0.11684)
		(layer "In11.Cu")
		(net "SMB_1_PLD_3V3AUX_SDA_R1")
	)
	(segment
		(start 160.9471 -54.246272)
		(end 164.164264 -57.463436)
		(width 0.11684)
		(layer "In11.Cu")
		(net "SMB_1_PLD_3V3AUX_SDA_R1")
	)
	(segment
		(start 159.633158 -103.81488)
		(end 160.799018 -104.98074)
		(width 0.11684)
		(layer "In11.Cu")
		(net "SMB_1_PLD_3V3AUX_SDA_R1")
	)
	(segment
		(start 163.690808 -77.42047)
		(end 163.690808 -92.462096)
		(width 0.11684)
		(layer "In11.Cu")
		(net "SMB_1_PLD_3V3AUX_SDA_R1")
	)
	(segment
		(start 165.25494 -116.667788)
		(end 167.434006 -118.846854)
		(width 0.11684)
		(layer "In11.Cu")
		(net "SMB_1_PLD_3V3AUX_SDA_R1")
	)
	(segment
		(start 163.690808 -92.462096)
		(end 159.633158 -96.519746)
		(width 0.11684)
		(layer "In11.Cu")
		(net "SMB_1_PLD_3V3AUX_SDA_R1")
	)
	(segment
		(start 164.831776 -114.601244)
		(end 165.25494 -115.024408)
		(width 0.11684)
		(layer "In11.Cu")
		(net "SMB_1_PLD_3V3AUX_SDA_R1")
	)
	(segment
		(start 164.831776 -108.359702)
		(end 164.831776 -114.601244)
		(width 0.11684)
		(layer "In11.Cu")
		(net "SMB_1_PLD_3V3AUX_SDA_R1")
	)
	(segment
		(start 159.633158 -96.519746)
		(end 159.633158 -103.81488)
		(width 0.11684)
		(layer "In11.Cu")
		(net "SMB_1_PLD_3V3AUX_SDA_R1")
	)
	(segment
		(start 164.164264 -64.802766)
		(end 162.956748 -66.010282)
		(width 0.11684)
		(layer "In11.Cu")
		(net "SMB_1_PLD_3V3AUX_SDA_R1")
	)
	(segment
		(start 160.799018 -104.98074)
		(end 161.78276 -104.98074)
		(width 0.11684)
		(layer "In11.Cu")
		(net "SMB_1_PLD_3V3AUX_SDA_R1")
	)
	(segment
		(start 162.956748 -66.010282)
		(end 162.956748 -76.68641)
		(width 0.11684)
		(layer "In11.Cu")
		(net "SMB_1_PLD_3V3AUX_SDA_R1")
	)
	(segment
		(start 170.64482 -115.741196)
		(end 170.18 -115.276376)
		(width 0.11684)
		(layer "In11.Cu")
		(net "SMB_1_PLD_3V3AUX_SDA_R1")
	)
	(segment
		(start 162.636962 -106.164888)
		(end 164.831776 -108.359702)
		(width 0.11684)
		(layer "In11.Cu")
		(net "SMB_1_PLD_3V3AUX_SDA_R1")
	)
	(segment
		(start 168.740582 -118.846854)
		(end 170.64482 -116.942616)
		(width 0.11684)
		(layer "In11.Cu")
		(net "SMB_1_PLD_3V3AUX_SDA_R1")
	)
	(segment
		(start 160.9471 -19.87804)
		(end 160.9471 -54.246272)
		(width 0.11684)
		(layer "In11.Cu")
		(net "SMB_1_PLD_3V3AUX_SDA_R1")
	)
	(segment
		(start 159.19577 -18.12671)
		(end 160.9471 -19.87804)
		(width 0.11684)
		(layer "In11.Cu")
		(net "SMB_1_PLD_3V3AUX_SDA_R1")
	)
	(segment
		(start 162.636962 -105.834942)
		(end 162.636962 -106.164888)
		(width 0.11684)
		(layer "In11.Cu")
		(net "SMB_1_PLD_3V3AUX_SDA_R1")
	)
	(segment
		(start 165.25494 -115.024408)
		(end 165.25494 -116.667788)
		(width 0.11684)
		(layer "In11.Cu")
		(net "SMB_1_PLD_3V3AUX_SDA_R1")
	)
	(segment
		(start 167.434006 -118.846854)
		(end 168.740582 -118.846854)
		(width 0.11684)
		(layer "In11.Cu")
		(net "SMB_1_PLD_3V3AUX_SDA_R1")
	)
	(segment
		(start 161.78276 -104.98074)
		(end 162.636962 -105.834942)
		(width 0.11684)
		(layer "In11.Cu")
		(net "SMB_1_PLD_3V3AUX_SDA_R1")
	)
	(segment
		(start 162.956748 -76.68641)
		(end 163.690808 -77.42047)
		(width 0.11684)
		(layer "In11.Cu")
		(net "SMB_1_PLD_3V3AUX_SDA_R1")
	)
	(via
		(at 160.552384 -20.456144)
		(size 0.6604)
		(drill 0.3302)
		(layers "F.Cu" "B.Cu")
		(net "SMB_1_PLD_3V3AUX_SDA")
	)
	(segment
		(start 161.09188 -17.79016)
		(end 161.09188 -16.77416)
		(width 0.10668)
		(layer "B.Cu")
		(net "SMB_1_PLD_3V3AUX_SDA")
	)
	(segment
		(start 161.09188 -16.77416)
		(end 161.09188 -15.75816)
		(width 0.10668)
		(layer "B.Cu")
		(net "SMB_1_PLD_3V3AUX_SDA")
	)
	(segment
		(start 159.383984 -20.456144)
		(end 160.552384 -20.456144)
		(width 0.10668)
		(layer "B.Cu")
		(net "SMB_1_PLD_3V3AUX_SDA")
	)
	(segment
		(start 160.552384 -18.329656)
		(end 161.09188 -17.79016)
		(width 0.10668)
		(layer "B.Cu")
		(net "SMB_1_PLD_3V3AUX_SDA")
	)
	(segment
		(start 160.552384 -20.456144)
		(end 160.552384 -18.329656)
		(width 0.10668)
		(layer "B.Cu")
		(net "SMB_1_PLD_3V3AUX_SDA")
	)
	(segment
		(start 163.267136 -11.511788)
		(end 163.107878 -11.35253)
		(width 0.10668)
		(layer "F.Cu")
		(net "SMB_1_PLD_3V3AUX_SCL_R3")
	)
	(segment
		(start 163.267136 -13.599922)
		(end 163.267136 -11.511788)
		(width 0.10668)
		(layer "F.Cu")
		(net "SMB_1_PLD_3V3AUX_SCL_R3")
	)
	(via
		(at 163.107878 -11.35253)
		(size 0.508)
		(drill 0.254)
		(layers "F.Cu" "B.Cu")
		(net "SMB_1_PLD_3V3AUX_SCL_R3")
	)
	(segment
		(start 162.889438 -13.651738)
		(end 163.107878 -13.433298)
		(width 0.10668)
		(layer "B.Cu")
		(net "SMB_1_PLD_3V3AUX_SCL_R3")
	)
	(segment
		(start 163.107878 -13.433298)
		(end 163.107878 -11.35253)
		(width 0.10668)
		(layer "B.Cu")
		(net "SMB_1_PLD_3V3AUX_SCL_R3")
	)
	(segment
		(start 170.79595 -116.569744)
		(end 170.79595 -116.296948)
		(width 0.10668)
		(layer "F.Cu")
		(net "SMB_1_PLD_3V3AUX_SCL_R1")
	)
	(segment
		(start 170.560746 -116.804948)
		(end 170.79595 -116.569744)
		(width 0.10668)
		(layer "F.Cu")
		(net "SMB_1_PLD_3V3AUX_SCL_R1")
	)
	(segment
		(start 169.164 -116.296948)
		(end 169.672 -116.804948)
		(width 0.10668)
		(layer "F.Cu")
		(net "SMB_1_PLD_3V3AUX_SCL_R1")
	)
	(segment
		(start 169.672 -116.804948)
		(end 170.560746 -116.804948)
		(width 0.10668)
		(layer "F.Cu")
		(net "SMB_1_PLD_3V3AUX_SCL_R1")
	)
	(via
		(at 169.164 -116.296948)
		(size 0.508)
		(drill 0.254)
		(layers "F.Cu" "B.Cu")
		(net "SMB_1_PLD_3V3AUX_SCL_R1")
	)
	(via
		(at 163.222178 -23.905464)
		(size 0.508)
		(drill 0.254)
		(layers "F.Cu" "B.Cu")
		(net "SMB_1_PLD_3V3AUX_SCL_R1")
	)
	(segment
		(start 163.030154 -21.120608)
		(end 163.030154 -22.503384)
		(width 0.10668)
		(layer "B.Cu")
		(net "SMB_1_PLD_3V3AUX_SCL_R1")
	)
	(segment
		(start 163.615878 -18.600166)
		(end 163.615878 -20.534884)
		(width 0.10668)
		(layer "B.Cu")
		(net "SMB_1_PLD_3V3AUX_SCL_R1")
	)
	(segment
		(start 162.86988 -17.854168)
		(end 163.615878 -18.600166)
		(width 0.10668)
		(layer "B.Cu")
		(net "SMB_1_PLD_3V3AUX_SCL_R1")
	)
	(segment
		(start 162.86988 -17.79016)
		(end 162.86988 -17.854168)
		(width 0.10668)
		(layer "B.Cu")
		(net "SMB_1_PLD_3V3AUX_SCL_R1")
	)
	(segment
		(start 163.030154 -22.503384)
		(end 163.222178 -22.695408)
		(width 0.10668)
		(layer "B.Cu")
		(net "SMB_1_PLD_3V3AUX_SCL_R1")
	)
	(segment
		(start 163.222178 -22.695408)
		(end 163.222178 -23.905464)
		(width 0.10668)
		(layer "B.Cu")
		(net "SMB_1_PLD_3V3AUX_SCL_R1")
	)
	(segment
		(start 163.615878 -20.534884)
		(end 163.030154 -21.120608)
		(width 0.10668)
		(layer "B.Cu")
		(net "SMB_1_PLD_3V3AUX_SCL_R1")
	)
	(segment
		(start 167.397176 -115.344194)
		(end 167.397176 -111.589058)
		(width 0.11684)
		(layer "In11.Cu")
		(net "SMB_1_PLD_3V3AUX_SCL_R1")
	)
	(segment
		(start 165.429184 -56.93918)
		(end 162.21202 -53.722016)
		(width 0.11684)
		(layer "In11.Cu")
		(net "SMB_1_PLD_3V3AUX_SCL_R1")
	)
	(segment
		(start 169.164 -116.296948)
		(end 168.576752 -115.7097)
		(width 0.11684)
		(layer "In11.Cu")
		(net "SMB_1_PLD_3V3AUX_SCL_R1")
	)
	(segment
		(start 162.21202 -24.915622)
		(end 163.222178 -23.905464)
		(width 0.11684)
		(layer "In11.Cu")
		(net "SMB_1_PLD_3V3AUX_SCL_R1")
	)
	(segment
		(start 163.705286 -95.235014)
		(end 165.429184 -93.511116)
		(width 0.11684)
		(layer "In11.Cu")
		(net "SMB_1_PLD_3V3AUX_SCL_R1")
	)
	(segment
		(start 167.762682 -115.7097)
		(end 167.397176 -115.344194)
		(width 0.11684)
		(layer "In11.Cu")
		(net "SMB_1_PLD_3V3AUX_SCL_R1")
	)
	(segment
		(start 166.322756 -105.025444)
		(end 165.601904 -104.304592)
		(width 0.11684)
		(layer "In11.Cu")
		(net "SMB_1_PLD_3V3AUX_SCL_R1")
	)
	(segment
		(start 167.68318 -107.146344)
		(end 166.322756 -105.78592)
		(width 0.11684)
		(layer "In11.Cu")
		(net "SMB_1_PLD_3V3AUX_SCL_R1")
	)
	(segment
		(start 165.429184 -93.511116)
		(end 165.429184 -56.93918)
		(width 0.11684)
		(layer "In11.Cu")
		(net "SMB_1_PLD_3V3AUX_SCL_R1")
	)
	(segment
		(start 164.121592 -104.304592)
		(end 163.705286 -103.888286)
		(width 0.11684)
		(layer "In11.Cu")
		(net "SMB_1_PLD_3V3AUX_SCL_R1")
	)
	(segment
		(start 167.68318 -111.303054)
		(end 167.68318 -107.146344)
		(width 0.11684)
		(layer "In11.Cu")
		(net "SMB_1_PLD_3V3AUX_SCL_R1")
	)
	(segment
		(start 168.576752 -115.7097)
		(end 167.762682 -115.7097)
		(width 0.11684)
		(layer "In11.Cu")
		(net "SMB_1_PLD_3V3AUX_SCL_R1")
	)
	(segment
		(start 166.322756 -105.78592)
		(end 166.322756 -105.025444)
		(width 0.11684)
		(layer "In11.Cu")
		(net "SMB_1_PLD_3V3AUX_SCL_R1")
	)
	(segment
		(start 162.21202 -53.722016)
		(end 162.21202 -24.915622)
		(width 0.11684)
		(layer "In11.Cu")
		(net "SMB_1_PLD_3V3AUX_SCL_R1")
	)
	(segment
		(start 167.397176 -111.589058)
		(end 167.68318 -111.303054)
		(width 0.11684)
		(layer "In11.Cu")
		(net "SMB_1_PLD_3V3AUX_SCL_R1")
	)
	(segment
		(start 163.705286 -103.888286)
		(end 163.705286 -95.235014)
		(width 0.11684)
		(layer "In11.Cu")
		(net "SMB_1_PLD_3V3AUX_SCL_R1")
	)
	(segment
		(start 165.601904 -104.304592)
		(end 164.121592 -104.304592)
		(width 0.11684)
		(layer "In11.Cu")
		(net "SMB_1_PLD_3V3AUX_SCL_R1")
	)
	(via
		(at 161.56178 -19.389344)
		(size 0.6604)
		(drill 0.3302)
		(layers "F.Cu" "B.Cu")
		(net "SMB_1_PLD_3V3AUX_SCL")
	)
	(segment
		(start 161.708338 -20.456144)
		(end 161.56178 -20.309586)
		(width 0.10668)
		(layer "B.Cu")
		(net "SMB_1_PLD_3V3AUX_SCL")
	)
	(segment
		(start 162.06978 -17.79016)
		(end 162.06978 -16.77416)
		(width 0.10668)
		(layer "B.Cu")
		(net "SMB_1_PLD_3V3AUX_SCL")
	)
	(segment
		(start 161.56178 -19.389344)
		(end 162.06978 -18.881344)
		(width 0.10668)
		(layer "B.Cu")
		(net "SMB_1_PLD_3V3AUX_SCL")
	)
	(segment
		(start 162.06978 -18.881344)
		(end 162.06978 -17.79016)
		(width 0.10668)
		(layer "B.Cu")
		(net "SMB_1_PLD_3V3AUX_SCL")
	)
	(segment
		(start 162.06978 -16.77416)
		(end 162.089338 -16.754602)
		(width 0.10668)
		(layer "B.Cu")
		(net "SMB_1_PLD_3V3AUX_SCL")
	)
	(segment
		(start 161.56178 -20.309586)
		(end 161.56178 -19.389344)
		(width 0.10668)
		(layer "B.Cu")
		(net "SMB_1_PLD_3V3AUX_SCL")
	)
	(segment
		(start 162.73018 -20.456144)
		(end 161.708338 -20.456144)
		(width 0.10668)
		(layer "B.Cu")
		(net "SMB_1_PLD_3V3AUX_SCL")
	)
	(segment
		(start 162.089338 -16.754602)
		(end 162.089338 -13.651738)
		(width 0.10668)
		(layer "B.Cu")
		(net "SMB_1_PLD_3V3AUX_SCL")
	)
	(segment
		(start 188.843412 -89.206324)
		(end 189.409324 -89.772236)
		(width 0.10668)
		(layer "F.Cu")
		(net "SMB_1_BMC_GPU_SDA")
	)
	(segment
		(start 226.16795 -201.374756)
		(end 222.87738 -204.665326)
		(width 0.10668)
		(layer "F.Cu")
		(net "SMB_1_BMC_GPU_SDA")
	)
	(segment
		(start 221.187518 -147.479004)
		(end 221.187518 -160.581086)
		(width 0.10668)
		(layer "F.Cu")
		(net "SMB_1_BMC_GPU_SDA")
	)
	(segment
		(start 185.738262 -89.206324)
		(end 188.843412 -89.206324)
		(width 0.10668)
		(layer "F.Cu")
		(net "SMB_1_BMC_GPU_SDA")
	)
	(segment
		(start 222.87738 -204.665326)
		(end 222.87738 -206.061818)
		(width 0.10668)
		(layer "F.Cu")
		(net "SMB_1_BMC_GPU_SDA")
	)
	(segment
		(start 210.847178 -94.080584)
		(end 219.5449 -94.080584)
		(width 0.10668)
		(layer "F.Cu")
		(net "SMB_1_BMC_GPU_SDA")
	)
	(segment
		(start 226.16795 -165.561518)
		(end 226.16795 -201.374756)
		(width 0.10668)
		(layer "F.Cu")
		(net "SMB_1_BMC_GPU_SDA")
	)
	(segment
		(start 219.462096 -209.477102)
		(end 219.289376 -209.477102)
		(width 0.10668)
		(layer "F.Cu")
		(net "SMB_1_BMC_GPU_SDA")
	)
	(segment
		(start 184.513474 -87.981536)
		(end 185.738262 -89.206324)
		(width 0.10668)
		(layer "F.Cu")
		(net "SMB_1_BMC_GPU_SDA")
	)
	(segment
		(start 223.608138 -124.931932)
		(end 223.608138 -137.53846)
		(width 0.10668)
		(layer "F.Cu")
		(net "SMB_1_BMC_GPU_SDA")
	)
	(segment
		(start 222.507556 -115.40871)
		(end 220.634052 -117.282214)
		(width 0.10668)
		(layer "F.Cu")
		(net "SMB_1_BMC_GPU_SDA")
	)
	(segment
		(start 222.507556 -97.04324)
		(end 222.507556 -115.40871)
		(width 0.10668)
		(layer "F.Cu")
		(net "SMB_1_BMC_GPU_SDA")
	)
	(segment
		(start 223.084136 -138.062462)
		(end 223.084136 -145.582386)
		(width 0.10668)
		(layer "F.Cu")
		(net "SMB_1_BMC_GPU_SDA")
	)
	(segment
		(start 220.634052 -121.957846)
		(end 223.608138 -124.931932)
		(width 0.10668)
		(layer "F.Cu")
		(net "SMB_1_BMC_GPU_SDA")
	)
	(segment
		(start 35.55873 -432.056794)
		(end 36.322 -432.056794)
		(width 0.10668)
		(layer "F.Cu")
		(net "SMB_1_BMC_GPU_SDA")
	)
	(segment
		(start 202.6285 -89.526872)
		(end 202.873864 -89.772236)
		(width 0.10668)
		(layer "F.Cu")
		(net "SMB_1_BMC_GPU_SDA")
	)
	(segment
		(start 221.187518 -160.581086)
		(end 226.16795 -165.561518)
		(width 0.10668)
		(layer "F.Cu")
		(net "SMB_1_BMC_GPU_SDA")
	)
	(segment
		(start 189.409324 -89.772236)
		(end 199.577452 -89.772236)
		(width 0.10668)
		(layer "F.Cu")
		(net "SMB_1_BMC_GPU_SDA")
	)
	(segment
		(start 222.87738 -206.061818)
		(end 219.462096 -209.477102)
		(width 0.10668)
		(layer "F.Cu")
		(net "SMB_1_BMC_GPU_SDA")
	)
	(segment
		(start 220.634052 -117.282214)
		(end 220.634052 -121.957846)
		(width 0.10668)
		(layer "F.Cu")
		(net "SMB_1_BMC_GPU_SDA")
	)
	(segment
		(start 219.5449 -94.080584)
		(end 222.507556 -97.04324)
		(width 0.10668)
		(layer "F.Cu")
		(net "SMB_1_BMC_GPU_SDA")
	)
	(segment
		(start 202.873864 -89.772236)
		(end 206.53883 -89.772236)
		(width 0.10668)
		(layer "F.Cu")
		(net "SMB_1_BMC_GPU_SDA")
	)
	(segment
		(start 199.577452 -89.772236)
		(end 199.822816 -89.526872)
		(width 0.10668)
		(layer "F.Cu")
		(net "SMB_1_BMC_GPU_SDA")
	)
	(segment
		(start 223.608138 -137.53846)
		(end 223.084136 -138.062462)
		(width 0.10668)
		(layer "F.Cu")
		(net "SMB_1_BMC_GPU_SDA")
	)
	(segment
		(start 206.53883 -89.772236)
		(end 210.847178 -94.080584)
		(width 0.10668)
		(layer "F.Cu")
		(net "SMB_1_BMC_GPU_SDA")
	)
	(segment
		(start 199.822816 -89.526872)
		(end 202.6285 -89.526872)
		(width 0.10668)
		(layer "F.Cu")
		(net "SMB_1_BMC_GPU_SDA")
	)
	(segment
		(start 223.084136 -145.582386)
		(end 221.187518 -147.479004)
		(width 0.10668)
		(layer "F.Cu")
		(net "SMB_1_BMC_GPU_SDA")
	)
	(via
		(at 152.672542 -15.316454)
		(size 0.508)
		(drill 0.254)
		(layers "F.Cu" "B.Cu")
		(net "SMB_1_BMC_GPU_SDA")
	)
	(via
		(at 184.513474 -87.981536)
		(size 0.508)
		(drill 0.254)
		(layers "F.Cu" "B.Cu")
		(net "SMB_1_BMC_GPU_SDA")
	)
	(via
		(at 36.322 -432.056794)
		(size 0.508)
		(drill 0.254)
		(layers "F.Cu" "B.Cu")
		(net "SMB_1_BMC_GPU_SDA")
	)
	(via
		(at 40.310816 -365.610394)
		(size 0.508)
		(drill 0.254)
		(layers "F.Cu" "B.Cu")
		(net "SMB_1_BMC_GPU_SDA")
	)
	(via
		(at 219.289376 -209.477102)
		(size 0.508)
		(drill 0.254)
		(layers "F.Cu" "B.Cu")
		(net "SMB_1_BMC_GPU_SDA")
	)
	(segment
		(start 152.672542 -15.316454)
		(end 152.672542 -14.486636)
		(width 0.10668)
		(layer "B.Cu")
		(net "SMB_1_BMC_GPU_SDA")
	)
	(segment
		(start 152.992836 -16.451072)
		(end 152.992836 -15.665196)
		(width 0.10668)
		(layer "B.Cu")
		(net "SMB_1_BMC_GPU_SDA")
	)
	(segment
		(start 152.672542 -14.486636)
		(end 152.9969 -14.162278)
		(width 0.10668)
		(layer "B.Cu")
		(net "SMB_1_BMC_GPU_SDA")
	)
	(segment
		(start 152.992836 -15.665196)
		(end 152.672542 -15.344902)
		(width 0.10668)
		(layer "B.Cu")
		(net "SMB_1_BMC_GPU_SDA")
	)
	(segment
		(start 152.672542 -15.344902)
		(end 152.672542 -15.316454)
		(width 0.10668)
		(layer "B.Cu")
		(net "SMB_1_BMC_GPU_SDA")
	)
	(segment
		(start 210.555586 -317.99657)
		(end 213.674198 -314.877958)
		(width 0.11684)
		(layer "In2.Cu")
		(net "SMB_1_BMC_GPU_SDA")
	)
	(segment
		(start 171.804584 -365.502444)
		(end 174.013622 -365.502444)
		(width 0.11684)
		(layer "In2.Cu")
		(net "SMB_1_BMC_GPU_SDA")
	)
	(segment
		(start 183.025034 -366.844072)
		(end 191.283844 -366.844072)
		(width 0.11684)
		(layer "In2.Cu")
		(net "SMB_1_BMC_GPU_SDA")
	)
	(segment
		(start 208.07426 -346.23502)
		(end 208.07426 -337.158838)
		(width 0.11684)
		(layer "In2.Cu")
		(net "SMB_1_BMC_GPU_SDA")
	)
	(segment
		(start 136.621774 -365.211868)
		(end 138.297666 -363.535976)
		(width 0.11684)
		(layer "In2.Cu")
		(net "SMB_1_BMC_GPU_SDA")
	)
	(segment
		(start 210.555586 -318.76746)
		(end 210.555586 -317.99657)
		(width 0.11684)
		(layer "In2.Cu")
		(net "SMB_1_BMC_GPU_SDA")
	)
	(segment
		(start 208.07426 -337.158838)
		(end 208.383124 -336.849974)
		(width 0.11684)
		(layer "In2.Cu")
		(net "SMB_1_BMC_GPU_SDA")
	)
	(segment
		(start 208.383124 -320.939922)
		(end 210.555586 -318.76746)
		(width 0.11684)
		(layer "In2.Cu")
		(net "SMB_1_BMC_GPU_SDA")
	)
	(segment
		(start 40.709342 -365.211868)
		(end 136.621774 -365.211868)
		(width 0.11684)
		(layer "In2.Cu")
		(net "SMB_1_BMC_GPU_SDA")
	)
	(segment
		(start 181.193186 -368.168428)
		(end 181.700678 -368.168428)
		(width 0.11684)
		(layer "In2.Cu")
		(net "SMB_1_BMC_GPU_SDA")
	)
	(segment
		(start 191.283844 -366.844072)
		(end 204.040232 -354.087684)
		(width 0.11684)
		(layer "In2.Cu")
		(net "SMB_1_BMC_GPU_SDA")
	)
	(segment
		(start 204.040232 -354.087684)
		(end 204.040232 -350.269048)
		(width 0.11684)
		(layer "In2.Cu")
		(net "SMB_1_BMC_GPU_SDA")
	)
	(segment
		(start 174.013622 -365.502444)
		(end 175.17618 -366.665002)
		(width 0.11684)
		(layer "In2.Cu")
		(net "SMB_1_BMC_GPU_SDA")
	)
	(segment
		(start 181.700678 -368.168428)
		(end 183.025034 -366.844072)
		(width 0.11684)
		(layer "In2.Cu")
		(net "SMB_1_BMC_GPU_SDA")
	)
	(segment
		(start 213.674198 -314.877958)
		(end 213.674198 -215.09228)
		(width 0.11684)
		(layer "In2.Cu")
		(net "SMB_1_BMC_GPU_SDA")
	)
	(segment
		(start 169.838116 -363.535976)
		(end 171.804584 -365.502444)
		(width 0.11684)
		(layer "In2.Cu")
		(net "SMB_1_BMC_GPU_SDA")
	)
	(segment
		(start 138.297666 -363.535976)
		(end 169.838116 -363.535976)
		(width 0.11684)
		(layer "In2.Cu")
		(net "SMB_1_BMC_GPU_SDA")
	)
	(segment
		(start 208.383124 -336.849974)
		(end 208.383124 -320.939922)
		(width 0.11684)
		(layer "In2.Cu")
		(net "SMB_1_BMC_GPU_SDA")
	)
	(segment
		(start 204.040232 -350.269048)
		(end 208.07426 -346.23502)
		(width 0.11684)
		(layer "In2.Cu")
		(net "SMB_1_BMC_GPU_SDA")
	)
	(segment
		(start 213.674198 -215.09228)
		(end 219.289376 -209.477102)
		(width 0.11684)
		(layer "In2.Cu")
		(net "SMB_1_BMC_GPU_SDA")
	)
	(segment
		(start 175.17618 -366.665002)
		(end 179.68976 -366.665002)
		(width 0.11684)
		(layer "In2.Cu")
		(net "SMB_1_BMC_GPU_SDA")
	)
	(segment
		(start 40.310816 -365.610394)
		(end 40.709342 -365.211868)
		(width 0.11684)
		(layer "In2.Cu")
		(net "SMB_1_BMC_GPU_SDA")
	)
	(segment
		(start 179.68976 -366.665002)
		(end 181.193186 -368.168428)
		(width 0.11684)
		(layer "In2.Cu")
		(net "SMB_1_BMC_GPU_SDA")
	)
	(segment
		(start 154.08656 -16.730472)
		(end 152.672542 -15.316454)
		(width 0.11684)
		(layer "In4.Cu")
		(net "SMB_1_BMC_GPU_SDA")
	)
	(segment
		(start 185.710322 -45.690028)
		(end 179.03825 -39.017956)
		(width 0.11684)
		(layer "In4.Cu")
		(net "SMB_1_BMC_GPU_SDA")
	)
	(segment
		(start 185.710322 -83.421474)
		(end 185.710322 -45.690028)
		(width 0.11684)
		(layer "In4.Cu")
		(net "SMB_1_BMC_GPU_SDA")
	)
	(segment
		(start 172.552614 -35.05454)
		(end 166.083488 -35.05454)
		(width 0.11684)
		(layer "In4.Cu")
		(net "SMB_1_BMC_GPU_SDA")
	)
	(segment
		(start 184.513474 -87.981536)
		(end 184.97804 -87.51697)
		(width 0.11684)
		(layer "In4.Cu")
		(net "SMB_1_BMC_GPU_SDA")
	)
	(segment
		(start 175.108616 -37.610542)
		(end 172.552614 -35.05454)
		(width 0.11684)
		(layer "In4.Cu")
		(net "SMB_1_BMC_GPU_SDA")
	)
	(segment
		(start 155.5115 -21.25726)
		(end 154.08656 -19.83232)
		(width 0.11684)
		(layer "In4.Cu")
		(net "SMB_1_BMC_GPU_SDA")
	)
	(segment
		(start 184.97804 -84.153756)
		(end 185.710322 -83.421474)
		(width 0.11684)
		(layer "In4.Cu")
		(net "SMB_1_BMC_GPU_SDA")
	)
	(segment
		(start 159.095186 -21.25726)
		(end 155.5115 -21.25726)
		(width 0.11684)
		(layer "In4.Cu")
		(net "SMB_1_BMC_GPU_SDA")
	)
	(segment
		(start 154.08656 -19.83232)
		(end 154.08656 -16.730472)
		(width 0.11684)
		(layer "In4.Cu")
		(net "SMB_1_BMC_GPU_SDA")
	)
	(segment
		(start 179.03825 -39.017956)
		(end 175.640746 -37.610542)
		(width 0.11684)
		(layer "In4.Cu")
		(net "SMB_1_BMC_GPU_SDA")
	)
	(segment
		(start 166.083488 -35.05454)
		(end 160.009586 -28.980638)
		(width 0.11684)
		(layer "In4.Cu")
		(net "SMB_1_BMC_GPU_SDA")
	)
	(segment
		(start 184.97804 -87.51697)
		(end 184.97804 -84.153756)
		(width 0.11684)
		(layer "In4.Cu")
		(net "SMB_1_BMC_GPU_SDA")
	)
	(segment
		(start 160.009586 -28.980638)
		(end 160.009586 -22.17166)
		(width 0.11684)
		(layer "In4.Cu")
		(net "SMB_1_BMC_GPU_SDA")
	)
	(segment
		(start 175.640746 -37.610542)
		(end 175.108616 -37.610542)
		(width 0.11684)
		(layer "In4.Cu")
		(net "SMB_1_BMC_GPU_SDA")
	)
	(segment
		(start 160.009586 -22.17166)
		(end 159.095186 -21.25726)
		(width 0.11684)
		(layer "In4.Cu")
		(net "SMB_1_BMC_GPU_SDA")
	)
	(segment
		(start 36.890198 -398.012412)
		(end 37.007038 -397.895572)
		(width 0.11684)
		(layer "In11.Cu")
		(net "SMB_1_BMC_GPU_SDA")
	)
	(segment
		(start 37.007038 -399.693892)
		(end 37.007038 -399.477992)
		(width 0.11684)
		(layer "In11.Cu")
		(net "SMB_1_BMC_GPU_SDA")
	)
	(segment
		(start 36.890198 -398.461992)
		(end 35.78098 -398.461992)
		(width 0.11684)
		(layer "In11.Cu")
		(net "SMB_1_BMC_GPU_SDA")
	)
	(segment
		(start 40.23614 -365.610394)
		(end 40.310816 -365.610394)
		(width 0.11684)
		(layer "In11.Cu")
		(net "SMB_1_BMC_GPU_SDA")
	)
	(segment
		(start 36.890198 -399.361152)
		(end 35.78098 -399.361152)
		(width 0.11684)
		(layer "In11.Cu")
		(net "SMB_1_BMC_GPU_SDA")
	)
	(segment
		(start 40.175942 -365.670592)
		(end 40.23614 -365.610394)
		(width 0.11684)
		(layer "In11.Cu")
		(net "SMB_1_BMC_GPU_SDA")
	)
	(segment
		(start 36.890198 -397.562832)
		(end 35.78098 -397.562832)
		(width 0.11684)
		(layer "In11.Cu")
		(net "SMB_1_BMC_GPU_SDA")
	)
	(segment
		(start 35.284918 -407.318464)
		(end 35.284918 -402.35251)
		(width 0.11684)
		(layer "In11.Cu")
		(net "SMB_1_BMC_GPU_SDA")
	)
	(segment
		(start 37.007038 -399.477992)
		(end 36.890198 -399.361152)
		(width 0.11684)
		(layer "In11.Cu")
		(net "SMB_1_BMC_GPU_SDA")
	)
	(segment
		(start 35.78098 -398.461992)
		(end 35.66414 -398.345152)
		(width 0.11684)
		(layer "In11.Cu")
		(net "SMB_1_BMC_GPU_SDA")
	)
	(segment
		(start 42.666666 -414.700212)
		(end 35.284918 -407.318464)
		(width 0.11684)
		(layer "In11.Cu")
		(net "SMB_1_BMC_GPU_SDA")
	)
	(segment
		(start 35.284918 -402.35251)
		(end 37.007038 -400.63039)
		(width 0.11684)
		(layer "In11.Cu")
		(net "SMB_1_BMC_GPU_SDA")
	)
	(segment
		(start 35.66414 -398.345152)
		(end 35.66414 -398.129252)
		(width 0.11684)
		(layer "In11.Cu")
		(net "SMB_1_BMC_GPU_SDA")
	)
	(segment
		(start 37.007038 -398.794732)
		(end 37.007038 -398.578832)
		(width 0.11684)
		(layer "In11.Cu")
		(net "SMB_1_BMC_GPU_SDA")
	)
	(segment
		(start 37.007038 -400.377152)
		(end 36.890198 -400.260312)
		(width 0.11684)
		(layer "In11.Cu")
		(net "SMB_1_BMC_GPU_SDA")
	)
	(segment
		(start 36.890198 -397.113252)
		(end 37.007038 -396.996412)
		(width 0.11684)
		(layer "In11.Cu")
		(net "SMB_1_BMC_GPU_SDA")
	)
	(segment
		(start 35.78098 -400.260312)
		(end 35.66414 -400.143472)
		(width 0.11684)
		(layer "In11.Cu")
		(net "SMB_1_BMC_GPU_SDA")
	)
	(segment
		(start 35.66414 -400.143472)
		(end 35.66414 -399.927572)
		(width 0.11684)
		(layer "In11.Cu")
		(net "SMB_1_BMC_GPU_SDA")
	)
	(segment
		(start 37.007038 -397.895572)
		(end 37.007038 -397.679672)
		(width 0.11684)
		(layer "In11.Cu")
		(net "SMB_1_BMC_GPU_SDA")
	)
	(segment
		(start 37.007038 -395.724634)
		(end 37.835078 -394.896594)
		(width 0.11684)
		(layer "In11.Cu")
		(net "SMB_1_BMC_GPU_SDA")
	)
	(segment
		(start 37.007038 -397.679672)
		(end 36.890198 -397.562832)
		(width 0.11684)
		(layer "In11.Cu")
		(net "SMB_1_BMC_GPU_SDA")
	)
	(segment
		(start 35.78098 -398.012412)
		(end 36.890198 -398.012412)
		(width 0.11684)
		(layer "In11.Cu")
		(net "SMB_1_BMC_GPU_SDA")
	)
	(segment
		(start 35.66414 -399.927572)
		(end 35.78098 -399.810732)
		(width 0.11684)
		(layer "In11.Cu")
		(net "SMB_1_BMC_GPU_SDA")
	)
	(segment
		(start 36.890198 -400.260312)
		(end 35.78098 -400.260312)
		(width 0.11684)
		(layer "In11.Cu")
		(net "SMB_1_BMC_GPU_SDA")
	)
	(segment
		(start 37.007038 -398.578832)
		(end 36.890198 -398.461992)
		(width 0.11684)
		(layer "In11.Cu")
		(net "SMB_1_BMC_GPU_SDA")
	)
	(segment
		(start 35.78098 -398.911572)
		(end 36.890198 -398.911572)
		(width 0.11684)
		(layer "In11.Cu")
		(net "SMB_1_BMC_GPU_SDA")
	)
	(segment
		(start 37.007038 -400.63039)
		(end 37.007038 -400.377152)
		(width 0.11684)
		(layer "In11.Cu")
		(net "SMB_1_BMC_GPU_SDA")
	)
	(segment
		(start 36.890198 -398.911572)
		(end 37.007038 -398.794732)
		(width 0.11684)
		(layer "In11.Cu")
		(net "SMB_1_BMC_GPU_SDA")
	)
	(segment
		(start 42.666666 -429.678084)
		(end 42.666666 -414.700212)
		(width 0.11684)
		(layer "In11.Cu")
		(net "SMB_1_BMC_GPU_SDA")
	)
	(segment
		(start 38.249606 -367.885726)
		(end 40.175942 -365.95939)
		(width 0.11684)
		(layer "In11.Cu")
		(net "SMB_1_BMC_GPU_SDA")
	)
	(segment
		(start 38.679882 -391.44829)
		(end 39.071042 -391.057384)
		(width 0.11684)
		(layer "In11.Cu")
		(net "SMB_1_BMC_GPU_SDA")
	)
	(segment
		(start 37.835078 -393.488418)
		(end 38.679882 -391.44829)
		(width 0.11684)
		(layer "In11.Cu")
		(net "SMB_1_BMC_GPU_SDA")
	)
	(segment
		(start 35.66414 -397.445992)
		(end 35.66414 -397.230092)
		(width 0.11684)
		(layer "In11.Cu")
		(net "SMB_1_BMC_GPU_SDA")
	)
	(segment
		(start 35.78098 -399.361152)
		(end 35.66414 -399.244312)
		(width 0.11684)
		(layer "In11.Cu")
		(net "SMB_1_BMC_GPU_SDA")
	)
	(segment
		(start 39.413942 -372.046246)
		(end 38.249606 -370.88191)
		(width 0.11684)
		(layer "In11.Cu")
		(net "SMB_1_BMC_GPU_SDA")
	)
	(segment
		(start 38.23462 -389.113522)
		(end 38.23462 -385.124706)
		(width 0.11684)
		(layer "In11.Cu")
		(net "SMB_1_BMC_GPU_SDA")
	)
	(segment
		(start 36.322 -432.056794)
		(end 40.287956 -432.056794)
		(width 0.11684)
		(layer "In11.Cu")
		(net "SMB_1_BMC_GPU_SDA")
	)
	(segment
		(start 35.78098 -397.113252)
		(end 36.890198 -397.113252)
		(width 0.11684)
		(layer "In11.Cu")
		(net "SMB_1_BMC_GPU_SDA")
	)
	(segment
		(start 35.78098 -399.810732)
		(end 36.890198 -399.810732)
		(width 0.11684)
		(layer "In11.Cu")
		(net "SMB_1_BMC_GPU_SDA")
	)
	(segment
		(start 38.23462 -385.124706)
		(end 39.413942 -383.945384)
		(width 0.11684)
		(layer "In11.Cu")
		(net "SMB_1_BMC_GPU_SDA")
	)
	(segment
		(start 40.287956 -432.056794)
		(end 42.666666 -429.678084)
		(width 0.11684)
		(layer "In11.Cu")
		(net "SMB_1_BMC_GPU_SDA")
	)
	(segment
		(start 35.66414 -397.230092)
		(end 35.78098 -397.113252)
		(width 0.11684)
		(layer "In11.Cu")
		(net "SMB_1_BMC_GPU_SDA")
	)
	(segment
		(start 37.007038 -396.996412)
		(end 37.007038 -395.724634)
		(width 0.11684)
		(layer "In11.Cu")
		(net "SMB_1_BMC_GPU_SDA")
	)
	(segment
		(start 39.071042 -391.057384)
		(end 39.071042 -389.949944)
		(width 0.11684)
		(layer "In11.Cu")
		(net "SMB_1_BMC_GPU_SDA")
	)
	(segment
		(start 35.78098 -397.562832)
		(end 35.66414 -397.445992)
		(width 0.11684)
		(layer "In11.Cu")
		(net "SMB_1_BMC_GPU_SDA")
	)
	(segment
		(start 39.413942 -383.945384)
		(end 39.413942 -372.046246)
		(width 0.11684)
		(layer "In11.Cu")
		(net "SMB_1_BMC_GPU_SDA")
	)
	(segment
		(start 35.66414 -398.129252)
		(end 35.78098 -398.012412)
		(width 0.11684)
		(layer "In11.Cu")
		(net "SMB_1_BMC_GPU_SDA")
	)
	(segment
		(start 38.249606 -370.88191)
		(end 38.249606 -367.885726)
		(width 0.11684)
		(layer "In11.Cu")
		(net "SMB_1_BMC_GPU_SDA")
	)
	(segment
		(start 35.66414 -399.244312)
		(end 35.66414 -399.028412)
		(width 0.11684)
		(layer "In11.Cu")
		(net "SMB_1_BMC_GPU_SDA")
	)
	(segment
		(start 40.175942 -365.95939)
		(end 40.175942 -365.670592)
		(width 0.11684)
		(layer "In11.Cu")
		(net "SMB_1_BMC_GPU_SDA")
	)
	(segment
		(start 35.66414 -399.028412)
		(end 35.78098 -398.911572)
		(width 0.11684)
		(layer "In11.Cu")
		(net "SMB_1_BMC_GPU_SDA")
	)
	(segment
		(start 36.890198 -399.810732)
		(end 37.007038 -399.693892)
		(width 0.11684)
		(layer "In11.Cu")
		(net "SMB_1_BMC_GPU_SDA")
	)
	(segment
		(start 37.835078 -394.896594)
		(end 37.835078 -393.488418)
		(width 0.11684)
		(layer "In11.Cu")
		(net "SMB_1_BMC_GPU_SDA")
	)
	(segment
		(start 39.071042 -389.949944)
		(end 38.23462 -389.113522)
		(width 0.11684)
		(layer "In11.Cu")
		(net "SMB_1_BMC_GPU_SDA")
	)
	(segment
		(start 223.21774 -206.25308)
		(end 223.21774 -204.806804)
		(width 0.10668)
		(layer "F.Cu")
		(net "SMB_1_BMC_GPU_SCL")
	)
	(segment
		(start 203.021184 -89.431876)
		(end 202.737974 -89.148666)
		(width 0.10668)
		(layer "F.Cu")
		(net "SMB_1_BMC_GPU_SCL")
	)
	(segment
		(start 208.51749 -90.159078)
		(end 207.790288 -89.431876)
		(width 0.10668)
		(layer "F.Cu")
		(net "SMB_1_BMC_GPU_SCL")
	)
	(segment
		(start 223.21774 -204.806804)
		(end 226.50831 -201.516234)
		(width 0.10668)
		(layer "F.Cu")
		(net "SMB_1_BMC_GPU_SCL")
	)
	(segment
		(start 186.105292 -88.865964)
		(end 185.219594 -87.980266)
		(width 0.10668)
		(layer "F.Cu")
		(net "SMB_1_BMC_GPU_SCL")
	)
	(segment
		(start 189.550548 -89.431876)
		(end 188.984636 -88.865964)
		(width 0.10668)
		(layer "F.Cu")
		(net "SMB_1_BMC_GPU_SCL")
	)
	(segment
		(start 207.790288 -89.431876)
		(end 203.021184 -89.431876)
		(width 0.10668)
		(layer "F.Cu")
		(net "SMB_1_BMC_GPU_SCL")
	)
	(segment
		(start 208.51749 -91.123262)
		(end 208.51749 -90.159078)
		(width 0.10668)
		(layer "F.Cu")
		(net "SMB_1_BMC_GPU_SCL")
	)
	(segment
		(start 219.295726 -210.175094)
		(end 223.21774 -206.25308)
		(width 0.10668)
		(layer "F.Cu")
		(net "SMB_1_BMC_GPU_SCL")
	)
	(segment
		(start 21.67763 -431.421794)
		(end 20.955 -431.421794)
		(width 0.10668)
		(layer "F.Cu")
		(net "SMB_1_BMC_GPU_SCL")
	)
	(segment
		(start 199.204834 -89.431876)
		(end 189.550548 -89.431876)
		(width 0.10668)
		(layer "F.Cu")
		(net "SMB_1_BMC_GPU_SCL")
	)
	(segment
		(start 188.984636 -88.865964)
		(end 186.105292 -88.865964)
		(width 0.10668)
		(layer "F.Cu")
		(net "SMB_1_BMC_GPU_SCL")
	)
	(segment
		(start 219.676472 -93.730572)
		(end 211.1248 -93.730572)
		(width 0.10668)
		(layer "F.Cu")
		(net "SMB_1_BMC_GPU_SCL")
	)
	(segment
		(start 211.1248 -93.730572)
		(end 208.51749 -91.123262)
		(width 0.10668)
		(layer "F.Cu")
		(net "SMB_1_BMC_GPU_SCL")
	)
	(segment
		(start 223.424496 -145.72361)
		(end 223.424496 -138.20394)
		(width 0.10668)
		(layer "F.Cu")
		(net "SMB_1_BMC_GPU_SCL")
	)
	(segment
		(start 222.847916 -96.902016)
		(end 219.676472 -93.730572)
		(width 0.10668)
		(layer "F.Cu")
		(net "SMB_1_BMC_GPU_SCL")
	)
	(segment
		(start 199.488044 -89.148666)
		(end 199.204834 -89.431876)
		(width 0.10668)
		(layer "F.Cu")
		(net "SMB_1_BMC_GPU_SCL")
	)
	(segment
		(start 220.974412 -117.58168)
		(end 222.847916 -115.708176)
		(width 0.10668)
		(layer "F.Cu")
		(net "SMB_1_BMC_GPU_SCL")
	)
	(segment
		(start 221.527878 -160.439862)
		(end 221.527878 -147.620228)
		(width 0.10668)
		(layer "F.Cu")
		(net "SMB_1_BMC_GPU_SCL")
	)
	(segment
		(start 220.974412 -121.816622)
		(end 220.974412 -117.58168)
		(width 0.10668)
		(layer "F.Cu")
		(net "SMB_1_BMC_GPU_SCL")
	)
	(segment
		(start 223.424496 -138.20394)
		(end 223.948498 -137.679938)
		(width 0.10668)
		(layer "F.Cu")
		(net "SMB_1_BMC_GPU_SCL")
	)
	(segment
		(start 202.737974 -89.148666)
		(end 199.488044 -89.148666)
		(width 0.10668)
		(layer "F.Cu")
		(net "SMB_1_BMC_GPU_SCL")
	)
	(segment
		(start 222.847916 -115.708176)
		(end 222.847916 -96.902016)
		(width 0.10668)
		(layer "F.Cu")
		(net "SMB_1_BMC_GPU_SCL")
	)
	(segment
		(start 221.527878 -147.620228)
		(end 223.424496 -145.72361)
		(width 0.10668)
		(layer "F.Cu")
		(net "SMB_1_BMC_GPU_SCL")
	)
	(segment
		(start 226.50831 -165.420294)
		(end 221.527878 -160.439862)
		(width 0.10668)
		(layer "F.Cu")
		(net "SMB_1_BMC_GPU_SCL")
	)
	(segment
		(start 223.948498 -137.679938)
		(end 223.948498 -124.790708)
		(width 0.10668)
		(layer "F.Cu")
		(net "SMB_1_BMC_GPU_SCL")
	)
	(segment
		(start 223.948498 -124.790708)
		(end 220.974412 -121.816622)
		(width 0.10668)
		(layer "F.Cu")
		(net "SMB_1_BMC_GPU_SCL")
	)
	(segment
		(start 226.50831 -201.516234)
		(end 226.50831 -165.420294)
		(width 0.10668)
		(layer "F.Cu")
		(net "SMB_1_BMC_GPU_SCL")
	)
	(via
		(at 40.813736 -366.025684)
		(size 0.508)
		(drill 0.254)
		(layers "F.Cu" "B.Cu")
		(net "SMB_1_BMC_GPU_SCL")
	)
	(via
		(at 185.219594 -87.980266)
		(size 0.508)
		(drill 0.254)
		(layers "F.Cu" "B.Cu")
		(net "SMB_1_BMC_GPU_SCL")
	)
	(via
		(at 153.990802 -15.316454)
		(size 0.508)
		(drill 0.254)
		(layers "F.Cu" "B.Cu")
		(net "SMB_1_BMC_GPU_SCL")
	)
	(via
		(at 219.295726 -210.175094)
		(size 0.508)
		(drill 0.254)
		(layers "F.Cu" "B.Cu")
		(net "SMB_1_BMC_GPU_SCL")
	)
	(via
		(at 20.955 -431.421794)
		(size 0.508)
		(drill 0.254)
		(layers "F.Cu" "B.Cu")
		(net "SMB_1_BMC_GPU_SCL")
	)
	(segment
		(start 153.990802 -16.451072)
		(end 153.990802 -15.316454)
		(width 0.10668)
		(layer "B.Cu")
		(net "SMB_1_BMC_GPU_SCL")
	)
	(segment
		(start 153.990802 -15.316454)
		(end 153.990802 -14.179296)
		(width 0.10668)
		(layer "B.Cu")
		(net "SMB_1_BMC_GPU_SCL")
	)
	(segment
		(start 153.990802 -14.179296)
		(end 154.00782 -14.162278)
		(width 0.10668)
		(layer "B.Cu")
		(net "SMB_1_BMC_GPU_SCL")
	)
	(segment
		(start 174.967646 -367.142268)
		(end 173.77156 -365.946182)
		(width 0.11684)
		(layer "In2.Cu")
		(net "SMB_1_BMC_GPU_SCL")
	)
	(segment
		(start 173.77156 -365.946182)
		(end 171.65193 -365.946182)
		(width 0.11684)
		(layer "In2.Cu")
		(net "SMB_1_BMC_GPU_SCL")
	)
	(segment
		(start 181.853332 -368.612166)
		(end 180.952648 -368.612166)
		(width 0.11684)
		(layer "In2.Cu")
		(net "SMB_1_BMC_GPU_SCL")
	)
	(segment
		(start 180.952648 -368.612166)
		(end 179.48275 -367.142268)
		(width 0.11684)
		(layer "In2.Cu")
		(net "SMB_1_BMC_GPU_SCL")
	)
	(segment
		(start 208.894172 -337.417664)
		(end 208.610708 -337.701128)
		(width 0.11684)
		(layer "In2.Cu")
		(net "SMB_1_BMC_GPU_SCL")
	)
	(segment
		(start 204.461872 -350.444054)
		(end 204.461872 -354.262436)
		(width 0.11684)
		(layer "In2.Cu")
		(net "SMB_1_BMC_GPU_SCL")
	)
	(segment
		(start 219.295726 -210.175094)
		(end 214.174324 -215.296496)
		(width 0.11684)
		(layer "In2.Cu")
		(net "SMB_1_BMC_GPU_SCL")
	)
	(segment
		(start 208.610708 -337.701128)
		(end 208.610708 -346.295218)
		(width 0.11684)
		(layer "In2.Cu")
		(net "SMB_1_BMC_GPU_SCL")
	)
	(segment
		(start 214.174324 -215.296496)
		(end 214.174324 -316.062868)
		(width 0.11684)
		(layer "In2.Cu")
		(net "SMB_1_BMC_GPU_SCL")
	)
	(segment
		(start 214.174324 -316.062868)
		(end 208.894172 -321.34302)
		(width 0.11684)
		(layer "In2.Cu")
		(net "SMB_1_BMC_GPU_SCL")
	)
	(segment
		(start 191.35471 -367.369598)
		(end 183.0959 -367.369598)
		(width 0.11684)
		(layer "In2.Cu")
		(net "SMB_1_BMC_GPU_SCL")
	)
	(segment
		(start 208.894172 -321.34302)
		(end 208.894172 -337.417664)
		(width 0.11684)
		(layer "In2.Cu")
		(net "SMB_1_BMC_GPU_SCL")
	)
	(segment
		(start 41.205912 -365.633508)
		(end 40.813736 -366.025684)
		(width 0.11684)
		(layer "In2.Cu")
		(net "SMB_1_BMC_GPU_SCL")
	)
	(segment
		(start 204.461872 -354.262436)
		(end 191.35471 -367.369598)
		(width 0.11684)
		(layer "In2.Cu")
		(net "SMB_1_BMC_GPU_SCL")
	)
	(segment
		(start 183.0959 -367.369598)
		(end 181.853332 -368.612166)
		(width 0.11684)
		(layer "In2.Cu")
		(net "SMB_1_BMC_GPU_SCL")
	)
	(segment
		(start 138.461496 -363.979714)
		(end 136.807702 -365.633508)
		(width 0.11684)
		(layer "In2.Cu")
		(net "SMB_1_BMC_GPU_SCL")
	)
	(segment
		(start 208.610708 -346.295218)
		(end 204.461872 -350.444054)
		(width 0.11684)
		(layer "In2.Cu")
		(net "SMB_1_BMC_GPU_SCL")
	)
	(segment
		(start 136.807702 -365.633508)
		(end 41.205912 -365.633508)
		(width 0.11684)
		(layer "In2.Cu")
		(net "SMB_1_BMC_GPU_SCL")
	)
	(segment
		(start 171.65193 -365.946182)
		(end 169.685462 -363.979714)
		(width 0.11684)
		(layer "In2.Cu")
		(net "SMB_1_BMC_GPU_SCL")
	)
	(segment
		(start 179.48275 -367.142268)
		(end 174.967646 -367.142268)
		(width 0.11684)
		(layer "In2.Cu")
		(net "SMB_1_BMC_GPU_SCL")
	)
	(segment
		(start 169.685462 -363.979714)
		(end 138.461496 -363.979714)
		(width 0.11684)
		(layer "In2.Cu")
		(net "SMB_1_BMC_GPU_SCL")
	)
	(segment
		(start 172.76699 -34.6329)
		(end 166.297864 -34.6329)
		(width 0.11684)
		(layer "In4.Cu")
		(net "SMB_1_BMC_GPU_SCL")
	)
	(segment
		(start 175.295052 -37.160962)
		(end 172.76699 -34.6329)
		(width 0.11684)
		(layer "In4.Cu")
		(net "SMB_1_BMC_GPU_SCL")
	)
	(segment
		(start 186.131962 -45.515276)
		(end 179.27701 -38.660324)
		(width 0.11684)
		(layer "In4.Cu")
		(net "SMB_1_BMC_GPU_SCL")
	)
	(segment
		(start 179.27701 -38.660324)
		(end 175.65751 -37.160962)
		(width 0.11684)
		(layer "In4.Cu")
		(net "SMB_1_BMC_GPU_SCL")
	)
	(segment
		(start 154.5082 -19.657568)
		(end 154.5082 -15.833852)
		(width 0.11684)
		(layer "In4.Cu")
		(net "SMB_1_BMC_GPU_SCL")
	)
	(segment
		(start 185.219594 -87.980266)
		(end 185.61304 -87.58682)
		(width 0.11684)
		(layer "In4.Cu")
		(net "SMB_1_BMC_GPU_SCL")
	)
	(segment
		(start 154.5082 -15.833852)
		(end 153.990802 -15.316454)
		(width 0.11684)
		(layer "In4.Cu")
		(net "SMB_1_BMC_GPU_SCL")
	)
	(segment
		(start 185.61304 -87.58682)
		(end 185.61304 -84.115148)
		(width 0.11684)
		(layer "In4.Cu")
		(net "SMB_1_BMC_GPU_SCL")
	)
	(segment
		(start 155.686252 -20.83562)
		(end 154.5082 -19.657568)
		(width 0.11684)
		(layer "In4.Cu")
		(net "SMB_1_BMC_GPU_SCL")
	)
	(segment
		(start 166.297864 -34.6329)
		(end 160.431226 -28.766262)
		(width 0.11684)
		(layer "In4.Cu")
		(net "SMB_1_BMC_GPU_SCL")
	)
	(segment
		(start 160.431226 -28.766262)
		(end 160.431226 -21.996908)
		(width 0.11684)
		(layer "In4.Cu")
		(net "SMB_1_BMC_GPU_SCL")
	)
	(segment
		(start 186.131962 -83.596226)
		(end 186.131962 -45.515276)
		(width 0.11684)
		(layer "In4.Cu")
		(net "SMB_1_BMC_GPU_SCL")
	)
	(segment
		(start 160.431226 -21.996908)
		(end 159.269938 -20.83562)
		(width 0.11684)
		(layer "In4.Cu")
		(net "SMB_1_BMC_GPU_SCL")
	)
	(segment
		(start 175.65751 -37.160962)
		(end 175.295052 -37.160962)
		(width 0.11684)
		(layer "In4.Cu")
		(net "SMB_1_BMC_GPU_SCL")
	)
	(segment
		(start 159.269938 -20.83562)
		(end 155.686252 -20.83562)
		(width 0.11684)
		(layer "In4.Cu")
		(net "SMB_1_BMC_GPU_SCL")
	)
	(segment
		(start 185.61304 -84.115148)
		(end 186.131962 -83.596226)
		(width 0.11684)
		(layer "In4.Cu")
		(net "SMB_1_BMC_GPU_SCL")
	)
	(segment
		(start 40.612568 -433.024026)
		(end 43.112436 -430.524158)
		(width 0.11684)
		(layer "In11.Cu")
		(net "SMB_1_BMC_GPU_SCL")
	)
	(segment
		(start 43.112436 -414.49879)
		(end 35.735006 -407.12136)
		(width 0.11684)
		(layer "In11.Cu")
		(net "SMB_1_BMC_GPU_SCL")
	)
	(segment
		(start 38.65626 -385.299458)
		(end 39.835582 -384.120136)
		(width 0.11684)
		(layer "In11.Cu")
		(net "SMB_1_BMC_GPU_SCL")
	)
	(segment
		(start 35.72256 -434.830982)
		(end 36.749482 -434.830982)
		(width 0.11684)
		(layer "In11.Cu")
		(net "SMB_1_BMC_GPU_SCL")
	)
	(segment
		(start 38.256718 -395.24178)
		(end 38.256718 -393.572492)
		(width 0.11684)
		(layer "In11.Cu")
		(net "SMB_1_BMC_GPU_SCL")
	)
	(segment
		(start 37.229034 -434.35143)
		(end 39.634668 -434.35143)
		(width 0.11684)
		(layer "In11.Cu")
		(net "SMB_1_BMC_GPU_SCL")
	)
	(segment
		(start 25.775666 -431.421794)
		(end 28.588716 -434.234844)
		(width 0.11684)
		(layer "In11.Cu")
		(net "SMB_1_BMC_GPU_SCL")
	)
	(segment
		(start 38.671246 -370.707158)
		(end 38.671246 -368.122454)
		(width 0.11684)
		(layer "In11.Cu")
		(net "SMB_1_BMC_GPU_SCL")
	)
	(segment
		(start 40.612568 -433.37353)
		(end 40.612568 -433.024026)
		(width 0.11684)
		(layer "In11.Cu")
		(net "SMB_1_BMC_GPU_SCL")
	)
	(segment
		(start 35.126422 -434.234844)
		(end 35.72256 -434.830982)
		(width 0.11684)
		(layer "In11.Cu")
		(net "SMB_1_BMC_GPU_SCL")
	)
	(segment
		(start 28.588716 -434.234844)
		(end 35.126422 -434.234844)
		(width 0.11684)
		(layer "In11.Cu")
		(net "SMB_1_BMC_GPU_SCL")
	)
	(segment
		(start 39.492682 -389.775192)
		(end 38.65626 -388.93877)
		(width 0.11684)
		(layer "In11.Cu")
		(net "SMB_1_BMC_GPU_SCL")
	)
	(segment
		(start 39.037514 -391.687304)
		(end 39.492682 -391.232136)
		(width 0.11684)
		(layer "In11.Cu")
		(net "SMB_1_BMC_GPU_SCL")
	)
	(segment
		(start 43.112436 -430.524158)
		(end 43.112436 -414.49879)
		(width 0.11684)
		(layer "In11.Cu")
		(net "SMB_1_BMC_GPU_SCL")
	)
	(segment
		(start 37.48786 -396.010638)
		(end 38.256718 -395.24178)
		(width 0.11684)
		(layer "In11.Cu")
		(net "SMB_1_BMC_GPU_SCL")
	)
	(segment
		(start 39.835582 -371.871494)
		(end 38.671246 -370.707158)
		(width 0.11684)
		(layer "In11.Cu")
		(net "SMB_1_BMC_GPU_SCL")
	)
	(segment
		(start 36.749482 -434.830982)
		(end 37.229034 -434.35143)
		(width 0.11684)
		(layer "In11.Cu")
		(net "SMB_1_BMC_GPU_SCL")
	)
	(segment
		(start 39.835582 -384.120136)
		(end 39.835582 -371.871494)
		(width 0.11684)
		(layer "In11.Cu")
		(net "SMB_1_BMC_GPU_SCL")
	)
	(segment
		(start 40.768016 -366.025684)
		(end 40.813736 -366.025684)
		(width 0.11684)
		(layer "In11.Cu")
		(net "SMB_1_BMC_GPU_SCL")
	)
	(segment
		(start 37.48786 -400.74596)
		(end 37.48786 -396.010638)
		(width 0.11684)
		(layer "In11.Cu")
		(net "SMB_1_BMC_GPU_SCL")
	)
	(segment
		(start 38.671246 -368.122454)
		(end 40.768016 -366.025684)
		(width 0.11684)
		(layer "In11.Cu")
		(net "SMB_1_BMC_GPU_SCL")
	)
	(segment
		(start 39.492682 -391.232136)
		(end 39.492682 -389.775192)
		(width 0.11684)
		(layer "In11.Cu")
		(net "SMB_1_BMC_GPU_SCL")
	)
	(segment
		(start 35.735006 -407.12136)
		(end 35.735006 -402.498814)
		(width 0.11684)
		(layer "In11.Cu")
		(net "SMB_1_BMC_GPU_SCL")
	)
	(segment
		(start 39.634668 -434.35143)
		(end 40.612568 -433.37353)
		(width 0.11684)
		(layer "In11.Cu")
		(net "SMB_1_BMC_GPU_SCL")
	)
	(segment
		(start 38.65626 -388.93877)
		(end 38.65626 -385.299458)
		(width 0.11684)
		(layer "In11.Cu")
		(net "SMB_1_BMC_GPU_SCL")
	)
	(segment
		(start 20.955 -431.421794)
		(end 25.775666 -431.421794)
		(width 0.11684)
		(layer "In11.Cu")
		(net "SMB_1_BMC_GPU_SCL")
	)
	(segment
		(start 38.256718 -393.572492)
		(end 39.037514 -391.687304)
		(width 0.11684)
		(layer "In11.Cu")
		(net "SMB_1_BMC_GPU_SCL")
	)
	(segment
		(start 35.735006 -402.498814)
		(end 37.48786 -400.74596)
		(width 0.11684)
		(layer "In11.Cu")
		(net "SMB_1_BMC_GPU_SCL")
	)
	(segment
		(start 36.322 -434.128164)
		(end 35.532822 -434.128164)
		(width 0.10668)
		(layer "F.Cu")
		(net "SMB_1_BMC_GPU_BUF_SDA")
	)
	(via
		(at 36.322 -434.128164)
		(size 0.508)
		(drill 0.254)
		(layers "F.Cu" "B.Cu")
		(net "SMB_1_BMC_GPU_BUF_SDA")
	)
	(segment
		(start 55.386478 -420.35349)
		(end 56.067706 -420.35349)
		(width 0.10668)
		(layer "B.Cu")
		(net "SMB_1_BMC_GPU_BUF_SDA")
	)
	(segment
		(start 56.067706 -418.59581)
		(end 56.174386 -418.48913)
		(width 0.10668)
		(layer "B.Cu")
		(net "SMB_1_BMC_GPU_BUF_SDA")
	)
	(segment
		(start 55.279798 -430.12741)
		(end 55.386478 -430.02073)
		(width 0.10668)
		(layer "B.Cu")
		(net "SMB_1_BMC_GPU_BUF_SDA")
	)
	(segment
		(start 56.067706 -422.11117)
		(end 56.174386 -422.00449)
		(width 0.10668)
		(layer "B.Cu")
		(net "SMB_1_BMC_GPU_BUF_SDA")
	)
	(segment
		(start 55.386478 -425.62653)
		(end 56.067706 -425.62653)
		(width 0.10668)
		(layer "B.Cu")
		(net "SMB_1_BMC_GPU_BUF_SDA")
	)
	(segment
		(start 55.279798 -424.85437)
		(end 55.386478 -424.74769)
		(width 0.10668)
		(layer "B.Cu")
		(net "SMB_1_BMC_GPU_BUF_SDA")
	)
	(segment
		(start 55.386478 -424.74769)
		(end 56.067706 -424.74769)
		(width 0.10668)
		(layer "B.Cu")
		(net "SMB_1_BMC_GPU_BUF_SDA")
	)
	(segment
		(start 55.386478 -428.70247)
		(end 55.279798 -428.59579)
		(width 0.10668)
		(layer "B.Cu")
		(net "SMB_1_BMC_GPU_BUF_SDA")
	)
	(segment
		(start 56.067706 -430.46015)
		(end 55.386478 -430.46015)
		(width 0.10668)
		(layer "B.Cu")
		(net "SMB_1_BMC_GPU_BUF_SDA")
	)
	(segment
		(start 55.279798 -429.24857)
		(end 55.386478 -429.14189)
		(width 0.10668)
		(layer "B.Cu")
		(net "SMB_1_BMC_GPU_BUF_SDA")
	)
	(segment
		(start 56.174386 -423.53611)
		(end 56.067706 -423.42943)
		(width 0.10668)
		(layer "B.Cu")
		(net "SMB_1_BMC_GPU_BUF_SDA")
	)
	(segment
		(start 56.067706 -426.94479)
		(end 55.386478 -426.94479)
		(width 0.10668)
		(layer "B.Cu")
		(net "SMB_1_BMC_GPU_BUF_SDA")
	)
	(segment
		(start 56.174386 -427.27753)
		(end 56.174386 -427.05147)
		(width 0.10668)
		(layer "B.Cu")
		(net "SMB_1_BMC_GPU_BUF_SDA")
	)
	(segment
		(start 56.174386 -426.39869)
		(end 56.174386 -426.17263)
		(width 0.10668)
		(layer "B.Cu")
		(net "SMB_1_BMC_GPU_BUF_SDA")
	)
	(segment
		(start 56.174386 -423.76217)
		(end 56.174386 -423.53611)
		(width 0.10668)
		(layer "B.Cu")
		(net "SMB_1_BMC_GPU_BUF_SDA")
	)
	(segment
		(start 56.174386 -420.24681)
		(end 56.174386 -420.02075)
		(width 0.10668)
		(layer "B.Cu")
		(net "SMB_1_BMC_GPU_BUF_SDA")
	)
	(segment
		(start 56.067706 -421.67175)
		(end 55.386478 -421.67175)
		(width 0.10668)
		(layer "B.Cu")
		(net "SMB_1_BMC_GPU_BUF_SDA")
	)
	(segment
		(start 55.279798 -418.92855)
		(end 55.279798 -418.70249)
		(width 0.10668)
		(layer "B.Cu")
		(net "SMB_1_BMC_GPU_BUF_SDA")
	)
	(segment
		(start 55.386478 -430.02073)
		(end 56.067706 -430.02073)
		(width 0.10668)
		(layer "B.Cu")
		(net "SMB_1_BMC_GPU_BUF_SDA")
	)
	(segment
		(start 56.174386 -427.93031)
		(end 56.067706 -427.82363)
		(width 0.10668)
		(layer "B.Cu")
		(net "SMB_1_BMC_GPU_BUF_SDA")
	)
	(segment
		(start 63.041784 -416.339274)
		(end 63.795148 -417.092638)
		(width 0.10668)
		(layer "B.Cu")
		(net "SMB_1_BMC_GPU_BUF_SDA")
	)
	(segment
		(start 55.279798 -422.21785)
		(end 55.386478 -422.11117)
		(width 0.10668)
		(layer "B.Cu")
		(net "SMB_1_BMC_GPU_BUF_SDA")
	)
	(segment
		(start 36.322 -434.128164)
		(end 36.322 -438.997852)
		(width 0.10668)
		(layer "B.Cu")
		(net "SMB_1_BMC_GPU_BUF_SDA")
	)
	(segment
		(start 55.386478 -422.55059)
		(end 55.279798 -422.44391)
		(width 0.10668)
		(layer "B.Cu")
		(net "SMB_1_BMC_GPU_BUF_SDA")
	)
	(segment
		(start 56.174386 -435.168548)
		(end 56.174386 -430.56683)
		(width 0.10668)
		(layer "B.Cu")
		(net "SMB_1_BMC_GPU_BUF_SDA")
	)
	(segment
		(start 55.386478 -426.06595)
		(end 55.279798 -425.95927)
		(width 0.10668)
		(layer "B.Cu")
		(net "SMB_1_BMC_GPU_BUF_SDA")
	)
	(segment
		(start 56.174386 -425.51985)
		(end 56.174386 -425.29379)
		(width 0.10668)
		(layer "B.Cu")
		(net "SMB_1_BMC_GPU_BUF_SDA")
	)
	(segment
		(start 55.279798 -425.08043)
		(end 55.279798 -424.85437)
		(width 0.10668)
		(layer "B.Cu")
		(net "SMB_1_BMC_GPU_BUF_SDA")
	)
	(segment
		(start 56.174386 -429.91405)
		(end 56.174386 -429.68799)
		(width 0.10668)
		(layer "B.Cu")
		(net "SMB_1_BMC_GPU_BUF_SDA")
	)
	(segment
		(start 55.386478 -430.46015)
		(end 55.279798 -430.35347)
		(width 0.10668)
		(layer "B.Cu")
		(net "SMB_1_BMC_GPU_BUF_SDA")
	)
	(segment
		(start 56.174386 -418.48913)
		(end 56.174386 -417.6268)
		(width 0.10668)
		(layer "B.Cu")
		(net "SMB_1_BMC_GPU_BUF_SDA")
	)
	(segment
		(start 56.067706 -429.58131)
		(end 55.386478 -429.58131)
		(width 0.10668)
		(layer "B.Cu")
		(net "SMB_1_BMC_GPU_BUF_SDA")
	)
	(segment
		(start 36.322 -438.997852)
		(end 37.462206 -440.138058)
		(width 0.10668)
		(layer "B.Cu")
		(net "SMB_1_BMC_GPU_BUF_SDA")
	)
	(segment
		(start 56.174386 -427.05147)
		(end 56.067706 -426.94479)
		(width 0.10668)
		(layer "B.Cu")
		(net "SMB_1_BMC_GPU_BUF_SDA")
	)
	(segment
		(start 56.174386 -429.68799)
		(end 56.067706 -429.58131)
		(width 0.10668)
		(layer "B.Cu")
		(net "SMB_1_BMC_GPU_BUF_SDA")
	)
	(segment
		(start 44.480988 -440.138058)
		(end 45.724318 -438.894728)
		(width 0.10668)
		(layer "B.Cu")
		(net "SMB_1_BMC_GPU_BUF_SDA")
	)
	(segment
		(start 55.279798 -420.46017)
		(end 55.386478 -420.35349)
		(width 0.10668)
		(layer "B.Cu")
		(net "SMB_1_BMC_GPU_BUF_SDA")
	)
	(segment
		(start 56.067706 -422.99001)
		(end 56.174386 -422.88333)
		(width 0.10668)
		(layer "B.Cu")
		(net "SMB_1_BMC_GPU_BUF_SDA")
	)
	(segment
		(start 55.279798 -429.47463)
		(end 55.279798 -429.24857)
		(width 0.10668)
		(layer "B.Cu")
		(net "SMB_1_BMC_GPU_BUF_SDA")
	)
	(segment
		(start 56.174386 -422.65727)
		(end 56.067706 -422.55059)
		(width 0.10668)
		(layer "B.Cu")
		(net "SMB_1_BMC_GPU_BUF_SDA")
	)
	(segment
		(start 55.386478 -422.99001)
		(end 56.067706 -422.99001)
		(width 0.10668)
		(layer "B.Cu")
		(net "SMB_1_BMC_GPU_BUF_SDA")
	)
	(segment
		(start 55.386478 -424.30827)
		(end 55.279798 -424.20159)
		(width 0.10668)
		(layer "B.Cu")
		(net "SMB_1_BMC_GPU_BUF_SDA")
	)
	(segment
		(start 56.067706 -419.03523)
		(end 55.386478 -419.03523)
		(width 0.10668)
		(layer "B.Cu")
		(net "SMB_1_BMC_GPU_BUF_SDA")
	)
	(segment
		(start 55.279798 -427.49089)
		(end 55.386478 -427.38421)
		(width 0.10668)
		(layer "B.Cu")
		(net "SMB_1_BMC_GPU_BUF_SDA")
	)
	(segment
		(start 55.279798 -428.36973)
		(end 55.386478 -428.26305)
		(width 0.10668)
		(layer "B.Cu")
		(net "SMB_1_BMC_GPU_BUF_SDA")
	)
	(segment
		(start 55.386478 -418.59581)
		(end 56.067706 -418.59581)
		(width 0.10668)
		(layer "B.Cu")
		(net "SMB_1_BMC_GPU_BUF_SDA")
	)
	(segment
		(start 56.174386 -419.36797)
		(end 56.174386 -419.14191)
		(width 0.10668)
		(layer "B.Cu")
		(net "SMB_1_BMC_GPU_BUF_SDA")
	)
	(segment
		(start 55.386478 -427.82363)
		(end 55.279798 -427.71695)
		(width 0.10668)
		(layer "B.Cu")
		(net "SMB_1_BMC_GPU_BUF_SDA")
	)
	(segment
		(start 55.279798 -427.71695)
		(end 55.279798 -427.49089)
		(width 0.10668)
		(layer "B.Cu")
		(net "SMB_1_BMC_GPU_BUF_SDA")
	)
	(segment
		(start 55.279798 -419.58133)
		(end 55.386478 -419.47465)
		(width 0.10668)
		(layer "B.Cu")
		(net "SMB_1_BMC_GPU_BUF_SDA")
	)
	(segment
		(start 55.279798 -421.33901)
		(end 55.386478 -421.23233)
		(width 0.10668)
		(layer "B.Cu")
		(net "SMB_1_BMC_GPU_BUF_SDA")
	)
	(segment
		(start 56.067706 -428.26305)
		(end 56.174386 -428.15637)
		(width 0.10668)
		(layer "B.Cu")
		(net "SMB_1_BMC_GPU_BUF_SDA")
	)
	(segment
		(start 56.174386 -420.02075)
		(end 56.067706 -419.91407)
		(width 0.10668)
		(layer "B.Cu")
		(net "SMB_1_BMC_GPU_BUF_SDA")
	)
	(segment
		(start 55.279798 -425.73321)
		(end 55.386478 -425.62653)
		(width 0.10668)
		(layer "B.Cu")
		(net "SMB_1_BMC_GPU_BUF_SDA")
	)
	(segment
		(start 55.279798 -423.97553)
		(end 55.386478 -423.86885)
		(width 0.10668)
		(layer "B.Cu")
		(net "SMB_1_BMC_GPU_BUF_SDA")
	)
	(segment
		(start 55.279798 -428.59579)
		(end 55.279798 -428.36973)
		(width 0.10668)
		(layer "B.Cu")
		(net "SMB_1_BMC_GPU_BUF_SDA")
	)
	(segment
		(start 55.279798 -422.44391)
		(end 55.279798 -422.21785)
		(width 0.10668)
		(layer "B.Cu")
		(net "SMB_1_BMC_GPU_BUF_SDA")
	)
	(segment
		(start 55.279798 -423.09669)
		(end 55.386478 -422.99001)
		(width 0.10668)
		(layer "B.Cu")
		(net "SMB_1_BMC_GPU_BUF_SDA")
	)
	(segment
		(start 56.174386 -428.80915)
		(end 56.067706 -428.70247)
		(width 0.10668)
		(layer "B.Cu")
		(net "SMB_1_BMC_GPU_BUF_SDA")
	)
	(segment
		(start 56.174386 -417.6268)
		(end 57.461912 -416.339274)
		(width 0.10668)
		(layer "B.Cu")
		(net "SMB_1_BMC_GPU_BUF_SDA")
	)
	(segment
		(start 55.279798 -426.61205)
		(end 55.386478 -426.50537)
		(width 0.10668)
		(layer "B.Cu")
		(net "SMB_1_BMC_GPU_BUF_SDA")
	)
	(segment
		(start 55.279798 -421.56507)
		(end 55.279798 -421.33901)
		(width 0.10668)
		(layer "B.Cu")
		(net "SMB_1_BMC_GPU_BUF_SDA")
	)
	(segment
		(start 55.386478 -423.42943)
		(end 55.279798 -423.32275)
		(width 0.10668)
		(layer "B.Cu")
		(net "SMB_1_BMC_GPU_BUF_SDA")
	)
	(segment
		(start 56.174386 -426.17263)
		(end 56.067706 -426.06595)
		(width 0.10668)
		(layer "B.Cu")
		(net "SMB_1_BMC_GPU_BUF_SDA")
	)
	(segment
		(start 56.174386 -422.88333)
		(end 56.174386 -422.65727)
		(width 0.10668)
		(layer "B.Cu")
		(net "SMB_1_BMC_GPU_BUF_SDA")
	)
	(segment
		(start 56.067706 -423.86885)
		(end 56.174386 -423.76217)
		(width 0.10668)
		(layer "B.Cu")
		(net "SMB_1_BMC_GPU_BUF_SDA")
	)
	(segment
		(start 56.174386 -428.15637)
		(end 56.174386 -427.93031)
		(width 0.10668)
		(layer "B.Cu")
		(net "SMB_1_BMC_GPU_BUF_SDA")
	)
	(segment
		(start 55.386478 -419.47465)
		(end 56.067706 -419.47465)
		(width 0.10668)
		(layer "B.Cu")
		(net "SMB_1_BMC_GPU_BUF_SDA")
	)
	(segment
		(start 37.462206 -440.138058)
		(end 44.480988 -440.138058)
		(width 0.10668)
		(layer "B.Cu")
		(net "SMB_1_BMC_GPU_BUF_SDA")
	)
	(segment
		(start 56.174386 -420.89959)
		(end 56.067706 -420.79291)
		(width 0.10668)
		(layer "B.Cu")
		(net "SMB_1_BMC_GPU_BUF_SDA")
	)
	(segment
		(start 56.174386 -422.00449)
		(end 56.174386 -421.77843)
		(width 0.10668)
		(layer "B.Cu")
		(net "SMB_1_BMC_GPU_BUF_SDA")
	)
	(segment
		(start 63.795148 -417.092638)
		(end 63.795148 -419.03523)
		(width 0.10668)
		(layer "B.Cu")
		(net "SMB_1_BMC_GPU_BUF_SDA")
	)
	(segment
		(start 56.067706 -423.42943)
		(end 55.386478 -423.42943)
		(width 0.10668)
		(layer "B.Cu")
		(net "SMB_1_BMC_GPU_BUF_SDA")
	)
	(segment
		(start 56.174386 -424.64101)
		(end 56.174386 -424.41495)
		(width 0.10668)
		(layer "B.Cu")
		(net "SMB_1_BMC_GPU_BUF_SDA")
	)
	(segment
		(start 55.386478 -429.58131)
		(end 55.279798 -429.47463)
		(width 0.10668)
		(layer "B.Cu")
		(net "SMB_1_BMC_GPU_BUF_SDA")
	)
	(segment
		(start 55.386478 -423.86885)
		(end 56.067706 -423.86885)
		(width 0.10668)
		(layer "B.Cu")
		(net "SMB_1_BMC_GPU_BUF_SDA")
	)
	(segment
		(start 55.386478 -425.18711)
		(end 55.279798 -425.08043)
		(width 0.10668)
		(layer "B.Cu")
		(net "SMB_1_BMC_GPU_BUF_SDA")
	)
	(segment
		(start 55.386478 -421.67175)
		(end 55.279798 -421.56507)
		(width 0.10668)
		(layer "B.Cu")
		(net "SMB_1_BMC_GPU_BUF_SDA")
	)
	(segment
		(start 56.067706 -427.82363)
		(end 55.386478 -427.82363)
		(width 0.10668)
		(layer "B.Cu")
		(net "SMB_1_BMC_GPU_BUF_SDA")
	)
	(segment
		(start 55.386478 -429.14189)
		(end 56.067706 -429.14189)
		(width 0.10668)
		(layer "B.Cu")
		(net "SMB_1_BMC_GPU_BUF_SDA")
	)
	(segment
		(start 55.386478 -428.26305)
		(end 56.067706 -428.26305)
		(width 0.10668)
		(layer "B.Cu")
		(net "SMB_1_BMC_GPU_BUF_SDA")
	)
	(segment
		(start 56.174386 -429.03521)
		(end 56.174386 -428.80915)
		(width 0.10668)
		(layer "B.Cu")
		(net "SMB_1_BMC_GPU_BUF_SDA")
	)
	(segment
		(start 56.174386 -424.41495)
		(end 56.067706 -424.30827)
		(width 0.10668)
		(layer "B.Cu")
		(net "SMB_1_BMC_GPU_BUF_SDA")
	)
	(segment
		(start 55.386478 -421.23233)
		(end 56.067706 -421.23233)
		(width 0.10668)
		(layer "B.Cu")
		(net "SMB_1_BMC_GPU_BUF_SDA")
	)
	(segment
		(start 56.067706 -419.47465)
		(end 56.174386 -419.36797)
		(width 0.10668)
		(layer "B.Cu")
		(net "SMB_1_BMC_GPU_BUF_SDA")
	)
	(segment
		(start 56.067706 -426.06595)
		(end 55.386478 -426.06595)
		(width 0.10668)
		(layer "B.Cu")
		(net "SMB_1_BMC_GPU_BUF_SDA")
	)
	(segment
		(start 55.279798 -424.20159)
		(end 55.279798 -423.97553)
		(width 0.10668)
		(layer "B.Cu")
		(net "SMB_1_BMC_GPU_BUF_SDA")
	)
	(segment
		(start 56.067706 -421.23233)
		(end 56.174386 -421.12565)
		(width 0.10668)
		(layer "B.Cu")
		(net "SMB_1_BMC_GPU_BUF_SDA")
	)
	(segment
		(start 57.461912 -416.339274)
		(end 63.041784 -416.339274)
		(width 0.10668)
		(layer "B.Cu")
		(net "SMB_1_BMC_GPU_BUF_SDA")
	)
	(segment
		(start 56.067706 -424.74769)
		(end 56.174386 -424.64101)
		(width 0.10668)
		(layer "B.Cu")
		(net "SMB_1_BMC_GPU_BUF_SDA")
	)
	(segment
		(start 45.724318 -438.894728)
		(end 52.448206 -438.894728)
		(width 0.10668)
		(layer "B.Cu")
		(net "SMB_1_BMC_GPU_BUF_SDA")
	)
	(segment
		(start 56.067706 -426.50537)
		(end 56.174386 -426.39869)
		(width 0.10668)
		(layer "B.Cu")
		(net "SMB_1_BMC_GPU_BUF_SDA")
	)
	(segment
		(start 56.174386 -421.12565)
		(end 56.174386 -420.89959)
		(width 0.10668)
		(layer "B.Cu")
		(net "SMB_1_BMC_GPU_BUF_SDA")
	)
	(segment
		(start 55.386478 -426.94479)
		(end 55.279798 -426.83811)
		(width 0.10668)
		(layer "B.Cu")
		(net "SMB_1_BMC_GPU_BUF_SDA")
	)
	(segment
		(start 55.386478 -419.91407)
		(end 55.279798 -419.80739)
		(width 0.10668)
		(layer "B.Cu")
		(net "SMB_1_BMC_GPU_BUF_SDA")
	)
	(segment
		(start 56.174386 -425.29379)
		(end 56.067706 -425.18711)
		(width 0.10668)
		(layer "B.Cu")
		(net "SMB_1_BMC_GPU_BUF_SDA")
	)
	(segment
		(start 55.279798 -419.80739)
		(end 55.279798 -419.58133)
		(width 0.10668)
		(layer "B.Cu")
		(net "SMB_1_BMC_GPU_BUF_SDA")
	)
	(segment
		(start 56.067706 -429.14189)
		(end 56.174386 -429.03521)
		(width 0.10668)
		(layer "B.Cu")
		(net "SMB_1_BMC_GPU_BUF_SDA")
	)
	(segment
		(start 56.067706 -425.18711)
		(end 55.386478 -425.18711)
		(width 0.10668)
		(layer "B.Cu")
		(net "SMB_1_BMC_GPU_BUF_SDA")
	)
	(segment
		(start 56.067706 -430.02073)
		(end 56.174386 -429.91405)
		(width 0.10668)
		(layer "B.Cu")
		(net "SMB_1_BMC_GPU_BUF_SDA")
	)
	(segment
		(start 56.067706 -425.62653)
		(end 56.174386 -425.51985)
		(width 0.10668)
		(layer "B.Cu")
		(net "SMB_1_BMC_GPU_BUF_SDA")
	)
	(segment
		(start 56.067706 -422.55059)
		(end 55.386478 -422.55059)
		(width 0.10668)
		(layer "B.Cu")
		(net "SMB_1_BMC_GPU_BUF_SDA")
	)
	(segment
		(start 56.067706 -428.70247)
		(end 55.386478 -428.70247)
		(width 0.10668)
		(layer "B.Cu")
		(net "SMB_1_BMC_GPU_BUF_SDA")
	)
	(segment
		(start 56.067706 -420.35349)
		(end 56.174386 -420.24681)
		(width 0.10668)
		(layer "B.Cu")
		(net "SMB_1_BMC_GPU_BUF_SDA")
	)
	(segment
		(start 55.279798 -420.68623)
		(end 55.279798 -420.46017)
		(width 0.10668)
		(layer "B.Cu")
		(net "SMB_1_BMC_GPU_BUF_SDA")
	)
	(segment
		(start 52.448206 -438.894728)
		(end 56.174386 -435.168548)
		(width 0.10668)
		(layer "B.Cu")
		(net "SMB_1_BMC_GPU_BUF_SDA")
	)
	(segment
		(start 55.386478 -422.11117)
		(end 56.067706 -422.11117)
		(width 0.10668)
		(layer "B.Cu")
		(net "SMB_1_BMC_GPU_BUF_SDA")
	)
	(segment
		(start 56.067706 -424.30827)
		(end 55.386478 -424.30827)
		(width 0.10668)
		(layer "B.Cu")
		(net "SMB_1_BMC_GPU_BUF_SDA")
	)
	(segment
		(start 55.386478 -419.03523)
		(end 55.279798 -418.92855)
		(width 0.10668)
		(layer "B.Cu")
		(net "SMB_1_BMC_GPU_BUF_SDA")
	)
	(segment
		(start 56.174386 -419.14191)
		(end 56.067706 -419.03523)
		(width 0.10668)
		(layer "B.Cu")
		(net "SMB_1_BMC_GPU_BUF_SDA")
	)
	(segment
		(start 55.279798 -423.32275)
		(end 55.279798 -423.09669)
		(width 0.10668)
		(layer "B.Cu")
		(net "SMB_1_BMC_GPU_BUF_SDA")
	)
	(segment
		(start 56.174386 -421.77843)
		(end 56.067706 -421.67175)
		(width 0.10668)
		(layer "B.Cu")
		(net "SMB_1_BMC_GPU_BUF_SDA")
	)
	(segment
		(start 55.279798 -418.70249)
		(end 55.386478 -418.59581)
		(width 0.10668)
		(layer "B.Cu")
		(net "SMB_1_BMC_GPU_BUF_SDA")
	)
	(segment
		(start 55.386478 -426.50537)
		(end 56.067706 -426.50537)
		(width 0.10668)
		(layer "B.Cu")
		(net "SMB_1_BMC_GPU_BUF_SDA")
	)
	(segment
		(start 56.067706 -427.38421)
		(end 56.174386 -427.27753)
		(width 0.10668)
		(layer "B.Cu")
		(net "SMB_1_BMC_GPU_BUF_SDA")
	)
	(segment
		(start 55.279798 -425.95927)
		(end 55.279798 -425.73321)
		(width 0.10668)
		(layer "B.Cu")
		(net "SMB_1_BMC_GPU_BUF_SDA")
	)
	(segment
		(start 56.067706 -420.79291)
		(end 55.386478 -420.79291)
		(width 0.10668)
		(layer "B.Cu")
		(net "SMB_1_BMC_GPU_BUF_SDA")
	)
	(segment
		(start 55.386478 -427.38421)
		(end 56.067706 -427.38421)
		(width 0.10668)
		(layer "B.Cu")
		(net "SMB_1_BMC_GPU_BUF_SDA")
	)
	(segment
		(start 56.067706 -419.91407)
		(end 55.386478 -419.91407)
		(width 0.10668)
		(layer "B.Cu")
		(net "SMB_1_BMC_GPU_BUF_SDA")
	)
	(segment
		(start 55.279798 -430.35347)
		(end 55.279798 -430.12741)
		(width 0.10668)
		(layer "B.Cu")
		(net "SMB_1_BMC_GPU_BUF_SDA")
	)
	(segment
		(start 56.174386 -430.56683)
		(end 56.067706 -430.46015)
		(width 0.10668)
		(layer "B.Cu")
		(net "SMB_1_BMC_GPU_BUF_SDA")
	)
	(segment
		(start 55.386478 -420.79291)
		(end 55.279798 -420.68623)
		(width 0.10668)
		(layer "B.Cu")
		(net "SMB_1_BMC_GPU_BUF_SDA")
	)
	(segment
		(start 63.795148 -419.03523)
		(end 64.649858 -419.88994)
		(width 0.10668)
		(layer "B.Cu")
		(net "SMB_1_BMC_GPU_BUF_SDA")
	)
	(segment
		(start 55.279798 -426.83811)
		(end 55.279798 -426.61205)
		(width 0.10668)
		(layer "B.Cu")
		(net "SMB_1_BMC_GPU_BUF_SDA")
	)
	(segment
		(start 20.955 -433.453794)
		(end 21.67763 -433.453794)
		(width 0.10668)
		(layer "F.Cu")
		(net "SMB_1_BMC_GPU_BUF_SCL")
	)
	(via
		(at 20.955 -433.453794)
		(size 0.508)
		(drill 0.254)
		(layers "F.Cu" "B.Cu")
		(net "SMB_1_BMC_GPU_BUF_SCL")
	)
	(segment
		(start 63.454788 -419.894766)
		(end 63.454788 -417.598606)
		(width 0.10668)
		(layer "B.Cu")
		(net "SMB_1_BMC_GPU_BUF_SCL")
	)
	(segment
		(start 63.454788 -417.598606)
		(end 62.535816 -416.679634)
		(width 0.10668)
		(layer "B.Cu")
		(net "SMB_1_BMC_GPU_BUF_SCL")
	)
	(segment
		(start 21.48459 -433.983384)
		(end 20.955 -433.453794)
		(width 0.10668)
		(layer "B.Cu")
		(net "SMB_1_BMC_GPU_BUF_SCL")
	)
	(segment
		(start 52.589938 -439.236612)
		(end 45.86605 -439.236612)
		(width 0.10668)
		(layer "B.Cu")
		(net "SMB_1_BMC_GPU_BUF_SCL")
	)
	(segment
		(start 56.51627 -417.7665)
		(end 56.51627 -435.31028)
		(width 0.10668)
		(layer "B.Cu")
		(net "SMB_1_BMC_GPU_BUF_SCL")
	)
	(segment
		(start 37.322506 -440.479942)
		(end 35.803332 -438.960768)
		(width 0.10668)
		(layer "B.Cu")
		(net "SMB_1_BMC_GPU_BUF_SCL")
	)
	(segment
		(start 30.74162 -436.01894)
		(end 26.593292 -436.01894)
		(width 0.10668)
		(layer "B.Cu")
		(net "SMB_1_BMC_GPU_BUF_SCL")
	)
	(segment
		(start 57.603136 -416.679634)
		(end 56.51627 -417.7665)
		(width 0.10668)
		(layer "B.Cu")
		(net "SMB_1_BMC_GPU_BUF_SCL")
	)
	(segment
		(start 44.62272 -440.479942)
		(end 37.322506 -440.479942)
		(width 0.10668)
		(layer "B.Cu")
		(net "SMB_1_BMC_GPU_BUF_SCL")
	)
	(segment
		(start 35.803332 -435.261512)
		(end 34.754312 -434.212492)
		(width 0.10668)
		(layer "B.Cu")
		(net "SMB_1_BMC_GPU_BUF_SCL")
	)
	(segment
		(start 64.649858 -421.089836)
		(end 63.454788 -419.894766)
		(width 0.10668)
		(layer "B.Cu")
		(net "SMB_1_BMC_GPU_BUF_SCL")
	)
	(segment
		(start 24.557736 -433.983384)
		(end 21.48459 -433.983384)
		(width 0.10668)
		(layer "B.Cu")
		(net "SMB_1_BMC_GPU_BUF_SCL")
	)
	(segment
		(start 45.86605 -439.236612)
		(end 44.62272 -440.479942)
		(width 0.10668)
		(layer "B.Cu")
		(net "SMB_1_BMC_GPU_BUF_SCL")
	)
	(segment
		(start 32.548068 -434.212492)
		(end 30.74162 -436.01894)
		(width 0.10668)
		(layer "B.Cu")
		(net "SMB_1_BMC_GPU_BUF_SCL")
	)
	(segment
		(start 62.535816 -416.679634)
		(end 57.603136 -416.679634)
		(width 0.10668)
		(layer "B.Cu")
		(net "SMB_1_BMC_GPU_BUF_SCL")
	)
	(segment
		(start 34.754312 -434.212492)
		(end 32.548068 -434.212492)
		(width 0.10668)
		(layer "B.Cu")
		(net "SMB_1_BMC_GPU_BUF_SCL")
	)
	(segment
		(start 35.803332 -438.960768)
		(end 35.803332 -435.261512)
		(width 0.10668)
		(layer "B.Cu")
		(net "SMB_1_BMC_GPU_BUF_SCL")
	)
	(segment
		(start 56.51627 -435.31028)
		(end 52.589938 -439.236612)
		(width 0.10668)
		(layer "B.Cu")
		(net "SMB_1_BMC_GPU_BUF_SCL")
	)
	(segment
		(start 26.593292 -436.01894)
		(end 24.557736 -433.983384)
		(width 0.10668)
		(layer "B.Cu")
		(net "SMB_1_BMC_GPU_BUF_SCL")
	)
	(segment
		(start 170.8912 -95.233998)
		(end 170.8912 -97.119948)
		(width 0.10668)
		(layer "F.Cu")
		(net "SGPIO_SCM_RESET_N")
	)
	(segment
		(start 177.122074 -109.852968)
		(end 176.732184 -109.463078)
		(width 0.10668)
		(layer "F.Cu")
		(net "SGPIO_SCM_RESET_N")
	)
	(via
		(at 170.8912 -97.119948)
		(size 0.508)
		(drill 0.254)
		(layers "F.Cu" "B.Cu")
		(net "SGPIO_SCM_RESET_N")
	)
	(via
		(at 176.732184 -109.463078)
		(size 0.4572)
		(drill 0.254)
		(layers "F.Cu" "B.Cu")
		(net "SGPIO_SCM_RESET_N")
	)
	(via
		(at 170.18 -108.177076)
		(size 0.508)
		(drill 0.254)
		(layers "F.Cu" "B.Cu")
		(net "SGPIO_SCM_RESET_N")
	)
	(segment
		(start 170.307 -97.704148)
		(end 170.8912 -97.119948)
		(width 0.10668)
		(layer "B.Cu")
		(net "SGPIO_SCM_RESET_N")
	)
	(segment
		(start 170.307 -97.735898)
		(end 170.307 -97.704148)
		(width 0.10668)
		(layer "B.Cu")
		(net "SGPIO_SCM_RESET_N")
	)
	(segment
		(start 170.18 -108.177076)
		(end 175.446182 -108.177076)
		(width 0.11684)
		(layer "In2.Cu")
		(net "SGPIO_SCM_RESET_N")
	)
	(segment
		(start 175.446182 -108.177076)
		(end 176.732184 -109.463078)
		(width 0.11684)
		(layer "In2.Cu")
		(net "SGPIO_SCM_RESET_N")
	)
	(segment
		(start 169.520108 -104.060752)
		(end 169.761916 -104.30256)
		(width 0.11684)
		(layer "In4.Cu")
		(net "SGPIO_SCM_RESET_N")
	)
	(segment
		(start 170.19016 -104.30256)
		(end 170.795188 -104.907588)
		(width 0.11684)
		(layer "In4.Cu")
		(net "SGPIO_SCM_RESET_N")
	)
	(segment
		(start 170.8912 -97.119948)
		(end 169.520108 -98.49104)
		(width 0.11684)
		(layer "In4.Cu")
		(net "SGPIO_SCM_RESET_N")
	)
	(segment
		(start 169.520108 -98.49104)
		(end 169.520108 -104.060752)
		(width 0.11684)
		(layer "In4.Cu")
		(net "SGPIO_SCM_RESET_N")
	)
	(segment
		(start 170.795188 -104.907588)
		(end 170.795188 -107.708192)
		(width 0.11684)
		(layer "In4.Cu")
		(net "SGPIO_SCM_RESET_N")
	)
	(segment
		(start 170.326304 -108.177076)
		(end 170.18 -108.177076)
		(width 0.11684)
		(layer "In4.Cu")
		(net "SGPIO_SCM_RESET_N")
	)
	(segment
		(start 169.761916 -104.30256)
		(end 170.19016 -104.30256)
		(width 0.11684)
		(layer "In4.Cu")
		(net "SGPIO_SCM_RESET_N")
	)
	(segment
		(start 170.795188 -107.708192)
		(end 170.326304 -108.177076)
		(width 0.11684)
		(layer "In4.Cu")
		(net "SGPIO_SCM_RESET_N")
	)
	(segment
		(start 177.922174 -109.852968)
		(end 177.532284 -109.463078)
		(width 0.10668)
		(layer "F.Cu")
		(net "SGPIO_SCM_LD_<1>")
	)
	(segment
		(start 172.9232 -95.233998)
		(end 172.9232 -96.59112)
		(width 0.10668)
		(layer "F.Cu")
		(net "SGPIO_SCM_LD_<1>")
	)
	(via
		(at 177.532284 -109.463078)
		(size 0.4572)
		(drill 0.254)
		(layers "F.Cu" "B.Cu")
		(net "SGPIO_SCM_LD_<1>")
	)
	(via
		(at 172.9232 -96.59112)
		(size 0.508)
		(drill 0.254)
		(layers "F.Cu" "B.Cu")
		(net "SGPIO_SCM_LD_<1>")
	)
	(segment
		(start 172.593 -97.735898)
		(end 172.9232 -97.405698)
		(width 0.10668)
		(layer "B.Cu")
		(net "SGPIO_SCM_LD_<1>")
	)
	(segment
		(start 172.9232 -97.405698)
		(end 172.9232 -96.59112)
		(width 0.10668)
		(layer "B.Cu")
		(net "SGPIO_SCM_LD_<1>")
	)
	(segment
		(start 175.079152 -107.06608)
		(end 175.916336 -107.903264)
		(width 0.11684)
		(layer "In4.Cu")
		(net "SGPIO_SCM_LD_<1>")
	)
	(segment
		(start 172.9232 -97.880932)
		(end 172.055028 -98.749104)
		(width 0.11684)
		(layer "In4.Cu")
		(net "SGPIO_SCM_LD_<1>")
	)
	(segment
		(start 173.282356 -103.775764)
		(end 173.282356 -104.035352)
		(width 0.11684)
		(layer "In4.Cu")
		(net "SGPIO_SCM_LD_<1>")
	)
	(segment
		(start 175.916336 -109.586522)
		(end 176.298352 -109.968538)
		(width 0.11684)
		(layer "In4.Cu")
		(net "SGPIO_SCM_LD_<1>")
	)
	(segment
		(start 172.055028 -98.749104)
		(end 172.055028 -102.548436)
		(width 0.11684)
		(layer "In4.Cu")
		(net "SGPIO_SCM_LD_<1>")
	)
	(segment
		(start 173.282356 -104.035352)
		(end 175.079152 -105.832148)
		(width 0.11684)
		(layer "In4.Cu")
		(net "SGPIO_SCM_LD_<1>")
	)
	(segment
		(start 175.916336 -107.903264)
		(end 175.916336 -109.586522)
		(width 0.11684)
		(layer "In4.Cu")
		(net "SGPIO_SCM_LD_<1>")
	)
	(segment
		(start 175.079152 -105.832148)
		(end 175.079152 -107.06608)
		(width 0.11684)
		(layer "In4.Cu")
		(net "SGPIO_SCM_LD_<1>")
	)
	(segment
		(start 172.055028 -102.548436)
		(end 173.282356 -103.775764)
		(width 0.11684)
		(layer "In4.Cu")
		(net "SGPIO_SCM_LD_<1>")
	)
	(segment
		(start 177.026824 -109.968538)
		(end 177.532284 -109.463078)
		(width 0.11684)
		(layer "In4.Cu")
		(net "SGPIO_SCM_LD_<1>")
	)
	(segment
		(start 172.9232 -96.59112)
		(end 172.9232 -97.880932)
		(width 0.11684)
		(layer "In4.Cu")
		(net "SGPIO_SCM_LD_<1>")
	)
	(segment
		(start 176.298352 -109.968538)
		(end 177.026824 -109.968538)
		(width 0.11684)
		(layer "In4.Cu")
		(net "SGPIO_SCM_LD_<1>")
	)
	(segment
		(start 179.52212 -111.452914)
		(end 179.13223 -111.063024)
		(width 0.10668)
		(layer "F.Cu")
		(net "SGPIO_SCM_LD_<0>")
	)
	(segment
		(start 171.577 -100.694998)
		(end 171.577 -101.310948)
		(width 0.10668)
		(layer "F.Cu")
		(net "SGPIO_SCM_LD_<0>")
	)
	(via
		(at 179.13223 -111.063024)
		(size 0.4572)
		(drill 0.254)
		(layers "F.Cu" "B.Cu")
		(net "SGPIO_SCM_LD_<0>")
	)
	(via
		(at 171.577 -101.310948)
		(size 0.508)
		(drill 0.254)
		(layers "F.Cu" "B.Cu")
		(net "SGPIO_SCM_LD_<0>")
	)
	(segment
		(start 171.577 -100.694998)
		(end 171.577 -101.310948)
		(width 0.10668)
		(layer "B.Cu")
		(net "SGPIO_SCM_LD_<0>")
	)
	(segment
		(start 178.738276 -110.66907)
		(end 179.13223 -111.063024)
		(width 0.11684)
		(layer "In4.Cu")
		(net "SGPIO_SCM_LD_<0>")
	)
	(segment
		(start 172.956982 -104.506776)
		(end 173.905672 -105.455466)
		(width 0.11684)
		(layer "In4.Cu")
		(net "SGPIO_SCM_LD_<0>")
	)
	(segment
		(start 174.501556 -107.125262)
		(end 175.506888 -108.130594)
		(width 0.11684)
		(layer "In4.Cu")
		(net "SGPIO_SCM_LD_<0>")
	)
	(segment
		(start 171.62526 -101.359208)
		(end 171.62526 -102.811834)
		(width 0.11684)
		(layer "In4.Cu")
		(net "SGPIO_SCM_LD_<0>")
	)
	(segment
		(start 172.018198 -103.986076)
		(end 172.538898 -104.506776)
		(width 0.11684)
		(layer "In4.Cu")
		(net "SGPIO_SCM_LD_<0>")
	)
	(segment
		(start 174.501556 -105.851198)
		(end 174.501556 -107.125262)
		(width 0.11684)
		(layer "In4.Cu")
		(net "SGPIO_SCM_LD_<0>")
	)
	(segment
		(start 173.905672 -105.455466)
		(end 174.105824 -105.455466)
		(width 0.11684)
		(layer "In4.Cu")
		(net "SGPIO_SCM_LD_<0>")
	)
	(segment
		(start 172.538898 -104.506776)
		(end 172.956982 -104.506776)
		(width 0.11684)
		(layer "In4.Cu")
		(net "SGPIO_SCM_LD_<0>")
	)
	(segment
		(start 171.62526 -102.811834)
		(end 172.018198 -103.204772)
		(width 0.11684)
		(layer "In4.Cu")
		(net "SGPIO_SCM_LD_<0>")
	)
	(segment
		(start 174.105824 -105.455466)
		(end 174.501556 -105.851198)
		(width 0.11684)
		(layer "In4.Cu")
		(net "SGPIO_SCM_LD_<0>")
	)
	(segment
		(start 175.506888 -108.130594)
		(end 175.506888 -110.250478)
		(width 0.11684)
		(layer "In4.Cu")
		(net "SGPIO_SCM_LD_<0>")
	)
	(segment
		(start 171.577 -101.310948)
		(end 171.62526 -101.359208)
		(width 0.11684)
		(layer "In4.Cu")
		(net "SGPIO_SCM_LD_<0>")
	)
	(segment
		(start 172.018198 -103.204772)
		(end 172.018198 -103.986076)
		(width 0.11684)
		(layer "In4.Cu")
		(net "SGPIO_SCM_LD_<0>")
	)
	(segment
		(start 175.92548 -110.66907)
		(end 178.738276 -110.66907)
		(width 0.11684)
		(layer "In4.Cu")
		(net "SGPIO_SCM_LD_<0>")
	)
	(segment
		(start 175.506888 -110.250478)
		(end 175.92548 -110.66907)
		(width 0.11684)
		(layer "In4.Cu")
		(net "SGPIO_SCM_LD_<0>")
	)
	(segment
		(start 181.922166 -112.25276)
		(end 181.532276 -111.86287)
		(width 0.10668)
		(layer "F.Cu")
		(net "SGPIO_SCM_INTR_R_N")
	)
	(via
		(at 181.532276 -111.86287)
		(size 0.4572)
		(drill 0.254)
		(layers "F.Cu" "B.Cu")
		(net "SGPIO_SCM_INTR_R_N")
	)
	(via
		(at 179.114958 -114.143536)
		(size 0.6604)
		(drill 0.3302)
		(layers "F.Cu" "B.Cu")
		(net "SGPIO_SCM_INTR_R_N")
	)
	(segment
		(start 179.431696 -114.143536)
		(end 179.114958 -114.143536)
		(width 0.10668)
		(layer "B.Cu")
		(net "SGPIO_SCM_INTR_R_N")
	)
	(segment
		(start 181.12994 -113.62944)
		(end 180.8988 -113.86058)
		(width 0.10668)
		(layer "B.Cu")
		(net "SGPIO_SCM_INTR_R_N")
	)
	(segment
		(start 178.582066 -113.86058)
		(end 176.4792 -113.86058)
		(width 0.10668)
		(layer "B.Cu")
		(net "SGPIO_SCM_INTR_R_N")
	)
	(segment
		(start 173.95444 -113.60404)
		(end 173.6979 -113.86058)
		(width 0.10668)
		(layer "B.Cu")
		(net "SGPIO_SCM_INTR_R_N")
	)
	(segment
		(start 181.308756 -111.86287)
		(end 181.12994 -112.041686)
		(width 0.10668)
		(layer "B.Cu")
		(net "SGPIO_SCM_INTR_R_N")
	)
	(segment
		(start 175.77308 -114.28222)
		(end 175.0949 -113.60404)
		(width 0.10668)
		(layer "B.Cu")
		(net "SGPIO_SCM_INTR_R_N")
	)
	(segment
		(start 175.0949 -113.60404)
		(end 173.95444 -113.60404)
		(width 0.10668)
		(layer "B.Cu")
		(net "SGPIO_SCM_INTR_R_N")
	)
	(segment
		(start 179.714652 -113.86058)
		(end 179.431696 -114.143536)
		(width 0.10668)
		(layer "B.Cu")
		(net "SGPIO_SCM_INTR_R_N")
	)
	(segment
		(start 172.3898 -113.86058)
		(end 172.118528 -113.589308)
		(width 0.10668)
		(layer "B.Cu")
		(net "SGPIO_SCM_INTR_R_N")
	)
	(segment
		(start 178.865022 -114.143536)
		(end 178.582066 -113.86058)
		(width 0.10668)
		(layer "B.Cu")
		(net "SGPIO_SCM_INTR_R_N")
	)
	(segment
		(start 181.12994 -112.041686)
		(end 181.12994 -113.62944)
		(width 0.10668)
		(layer "B.Cu")
		(net "SGPIO_SCM_INTR_R_N")
	)
	(segment
		(start 173.6979 -113.86058)
		(end 172.3898 -113.86058)
		(width 0.10668)
		(layer "B.Cu")
		(net "SGPIO_SCM_INTR_R_N")
	)
	(segment
		(start 172.118528 -113.589308)
		(end 171.63415 -113.589308)
		(width 0.10668)
		(layer "B.Cu")
		(net "SGPIO_SCM_INTR_R_N")
	)
	(segment
		(start 176.05756 -114.28222)
		(end 175.77308 -114.28222)
		(width 0.10668)
		(layer "B.Cu")
		(net "SGPIO_SCM_INTR_R_N")
	)
	(segment
		(start 179.114958 -114.143536)
		(end 178.865022 -114.143536)
		(width 0.10668)
		(layer "B.Cu")
		(net "SGPIO_SCM_INTR_R_N")
	)
	(segment
		(start 176.4792 -113.86058)
		(end 176.05756 -114.28222)
		(width 0.10668)
		(layer "B.Cu")
		(net "SGPIO_SCM_INTR_R_N")
	)
	(segment
		(start 180.8988 -113.86058)
		(end 179.714652 -113.86058)
		(width 0.10668)
		(layer "B.Cu")
		(net "SGPIO_SCM_INTR_R_N")
	)
	(segment
		(start 181.532276 -111.86287)
		(end 181.308756 -111.86287)
		(width 0.10668)
		(layer "B.Cu")
		(net "SGPIO_SCM_INTR_R_N")
	)
	(segment
		(start 149.990048 -26.28773)
		(end 149.987254 -26.284936)
		(width 0.10668)
		(layer "F.Cu")
		(net "SGPIO_SCM_INTR_N")
	)
	(segment
		(start 150.319994 -25.516078)
		(end 150.319994 -24.744934)
		(width 0.10668)
		(layer "F.Cu")
		(net "SGPIO_SCM_INTR_N")
	)
	(segment
		(start 149.987254 -25.848818)
		(end 150.319994 -25.516078)
		(width 0.10668)
		(layer "F.Cu")
		(net "SGPIO_SCM_INTR_N")
	)
	(segment
		(start 149.987254 -26.284936)
		(end 149.987254 -25.848818)
		(width 0.10668)
		(layer "F.Cu")
		(net "SGPIO_SCM_INTR_N")
	)
	(segment
		(start 149.987254 -24.412194)
		(end 149.987254 -23.684992)
		(width 0.10668)
		(layer "F.Cu")
		(net "SGPIO_SCM_INTR_N")
	)
	(segment
		(start 150.319994 -24.744934)
		(end 149.987254 -24.412194)
		(width 0.10668)
		(layer "F.Cu")
		(net "SGPIO_SCM_INTR_N")
	)
	(via
		(at 169.164 -112.359948)
		(size 0.508)
		(drill 0.254)
		(layers "F.Cu" "B.Cu")
		(net "SGPIO_SCM_INTR_N")
	)
	(via
		(at 150.319994 -24.744934)
		(size 0.508)
		(drill 0.254)
		(layers "F.Cu" "B.Cu")
		(net "SGPIO_SCM_INTR_N")
	)
	(segment
		(start 169.164 -113.6015)
		(end 169.164 -112.359948)
		(width 0.10668)
		(layer "B.Cu")
		(net "SGPIO_SCM_INTR_N")
	)
	(segment
		(start 169.71518 -114.15268)
		(end 169.164 -113.6015)
		(width 0.10668)
		(layer "B.Cu")
		(net "SGPIO_SCM_INTR_N")
	)
	(segment
		(start 170.83405 -113.82883)
		(end 170.5102 -114.15268)
		(width 0.10668)
		(layer "B.Cu")
		(net "SGPIO_SCM_INTR_N")
	)
	(segment
		(start 170.83405 -113.589308)
		(end 170.83405 -113.82883)
		(width 0.10668)
		(layer "B.Cu")
		(net "SGPIO_SCM_INTR_N")
	)
	(segment
		(start 170.5102 -114.15268)
		(end 169.71518 -114.15268)
		(width 0.10668)
		(layer "B.Cu")
		(net "SGPIO_SCM_INTR_N")
	)
	(segment
		(start 153.605992 -55.958232)
		(end 153.605992 -57.244996)
		(width 0.11684)
		(layer "In4.Cu")
		(net "SGPIO_SCM_INTR_N")
	)
	(segment
		(start 167.300656 -94.222824)
		(end 167.300656 -95.9358)
		(width 0.11684)
		(layer "In4.Cu")
		(net "SGPIO_SCM_INTR_N")
	)
	(segment
		(start 167.560752 -111.76254)
		(end 167.93972 -112.141508)
		(width 0.11684)
		(layer "In4.Cu")
		(net "SGPIO_SCM_INTR_N")
	)
	(segment
		(start 154.661362 -43.47464)
		(end 153.46045 -44.675552)
		(width 0.11684)
		(layer "In4.Cu")
		(net "SGPIO_SCM_INTR_N")
	)
	(segment
		(start 161.55162 -70.114922)
		(end 161.55162 -88.473788)
		(width 0.11684)
		(layer "In4.Cu")
		(net "SGPIO_SCM_INTR_N")
	)
	(segment
		(start 154.079448 -55.484776)
		(end 153.605992 -55.958232)
		(width 0.11684)
		(layer "In4.Cu")
		(net "SGPIO_SCM_INTR_N")
	)
	(segment
		(start 167.305228 -103.894636)
		(end 167.305228 -106.027474)
		(width 0.11684)
		(layer "In4.Cu")
		(net "SGPIO_SCM_INTR_N")
	)
	(segment
		(start 167.305228 -106.027474)
		(end 167.885618 -106.607864)
		(width 0.11684)
		(layer "In4.Cu")
		(net "SGPIO_SCM_INTR_N")
	)
	(segment
		(start 168.94556 -112.141508)
		(end 169.164 -112.359948)
		(width 0.11684)
		(layer "In4.Cu")
		(net "SGPIO_SCM_INTR_N")
	)
	(segment
		(start 155.353004 -63.916306)
		(end 161.55162 -70.114922)
		(width 0.11684)
		(layer "In4.Cu")
		(net "SGPIO_SCM_INTR_N")
	)
	(segment
		(start 167.560752 -108.750608)
		(end 167.560752 -111.76254)
		(width 0.11684)
		(layer "In4.Cu")
		(net "SGPIO_SCM_INTR_N")
	)
	(segment
		(start 167.93972 -112.141508)
		(end 168.94556 -112.141508)
		(width 0.11684)
		(layer "In4.Cu")
		(net "SGPIO_SCM_INTR_N")
	)
	(segment
		(start 153.46045 -47.514256)
		(end 154.079448 -48.133254)
		(width 0.11684)
		(layer "In4.Cu")
		(net "SGPIO_SCM_INTR_N")
	)
	(segment
		(start 167.885618 -108.425742)
		(end 167.560752 -108.750608)
		(width 0.11684)
		(layer "In4.Cu")
		(net "SGPIO_SCM_INTR_N")
	)
	(segment
		(start 167.885618 -106.607864)
		(end 167.885618 -108.425742)
		(width 0.11684)
		(layer "In4.Cu")
		(net "SGPIO_SCM_INTR_N")
	)
	(segment
		(start 167.300656 -95.9358)
		(end 168.12514 -96.760284)
		(width 0.11684)
		(layer "In4.Cu")
		(net "SGPIO_SCM_INTR_N")
	)
	(segment
		(start 154.079448 -48.133254)
		(end 154.079448 -55.484776)
		(width 0.11684)
		(layer "In4.Cu")
		(net "SGPIO_SCM_INTR_N")
	)
	(segment
		(start 153.605992 -57.244996)
		(end 155.353004 -58.992008)
		(width 0.11684)
		(layer "In4.Cu")
		(net "SGPIO_SCM_INTR_N")
	)
	(segment
		(start 154.661362 -34.412174)
		(end 154.661362 -43.47464)
		(width 0.11684)
		(layer "In4.Cu")
		(net "SGPIO_SCM_INTR_N")
	)
	(segment
		(start 149.02053 -28.771342)
		(end 154.661362 -34.412174)
		(width 0.11684)
		(layer "In4.Cu")
		(net "SGPIO_SCM_INTR_N")
	)
	(segment
		(start 161.55162 -88.473788)
		(end 167.300656 -94.222824)
		(width 0.11684)
		(layer "In4.Cu")
		(net "SGPIO_SCM_INTR_N")
	)
	(segment
		(start 153.46045 -44.675552)
		(end 153.46045 -47.514256)
		(width 0.11684)
		(layer "In4.Cu")
		(net "SGPIO_SCM_INTR_N")
	)
	(segment
		(start 150.319994 -24.856948)
		(end 149.02053 -26.156412)
		(width 0.11684)
		(layer "In4.Cu")
		(net "SGPIO_SCM_INTR_N")
	)
	(segment
		(start 149.02053 -26.156412)
		(end 149.02053 -28.771342)
		(width 0.11684)
		(layer "In4.Cu")
		(net "SGPIO_SCM_INTR_N")
	)
	(segment
		(start 155.353004 -58.992008)
		(end 155.353004 -63.916306)
		(width 0.11684)
		(layer "In4.Cu")
		(net "SGPIO_SCM_INTR_N")
	)
	(segment
		(start 150.319994 -24.744934)
		(end 150.319994 -24.856948)
		(width 0.11684)
		(layer "In4.Cu")
		(net "SGPIO_SCM_INTR_N")
	)
	(segment
		(start 168.12514 -96.760284)
		(end 168.12514 -103.074724)
		(width 0.11684)
		(layer "In4.Cu")
		(net "SGPIO_SCM_INTR_N")
	)
	(segment
		(start 168.12514 -103.074724)
		(end 167.305228 -103.894636)
		(width 0.11684)
		(layer "In4.Cu")
		(net "SGPIO_SCM_INTR_N")
	)
	(segment
		(start 177.922174 -109.052868)
		(end 177.532284 -108.662978)
		(width 0.10668)
		(layer "F.Cu")
		(net "SGPIO_SCM_DO_<1>")
	)
	(segment
		(start 172.593 -100.694998)
		(end 172.593 -101.67874)
		(width 0.10668)
		(layer "F.Cu")
		(net "SGPIO_SCM_DO_<1>")
	)
	(segment
		(start 172.70476 -101.7905)
		(end 172.70476 -101.836982)
		(width 0.10668)
		(layer "F.Cu")
		(net "SGPIO_SCM_DO_<1>")
	)
	(segment
		(start 172.593 -101.67874)
		(end 172.70476 -101.7905)
		(width 0.10668)
		(layer "F.Cu")
		(net "SGPIO_SCM_DO_<1>")
	)
	(via
		(at 177.532284 -108.662978)
		(size 0.4572)
		(drill 0.254)
		(layers "F.Cu" "B.Cu")
		(net "SGPIO_SCM_DO_<1>")
	)
	(via
		(at 172.70476 -101.836982)
		(size 0.508)
		(drill 0.254)
		(layers "F.Cu" "B.Cu")
		(net "SGPIO_SCM_DO_<1>")
	)
	(segment
		(start 172.593 -101.67874)
		(end 172.70476 -101.7905)
		(width 0.10668)
		(layer "B.Cu")
		(net "SGPIO_SCM_DO_<1>")
	)
	(segment
		(start 172.70476 -101.7905)
		(end 172.70476 -101.836982)
		(width 0.10668)
		(layer "B.Cu")
		(net "SGPIO_SCM_DO_<1>")
	)
	(segment
		(start 172.593 -100.694998)
		(end 172.593 -101.67874)
		(width 0.10668)
		(layer "B.Cu")
		(net "SGPIO_SCM_DO_<1>")
	)
	(segment
		(start 172.607986 -102.41915)
		(end 173.724824 -103.535988)
		(width 0.11684)
		(layer "In4.Cu")
		(net "SGPIO_SCM_DO_<1>")
	)
	(segment
		(start 176.308766 -107.679998)
		(end 176.308766 -108.458254)
		(width 0.11684)
		(layer "In4.Cu")
		(net "SGPIO_SCM_DO_<1>")
	)
	(segment
		(start 176.308766 -108.458254)
		(end 176.465484 -108.614972)
		(width 0.11684)
		(layer "In4.Cu")
		(net "SGPIO_SCM_DO_<1>")
	)
	(segment
		(start 177.484278 -108.614972)
		(end 177.532284 -108.662978)
		(width 0.11684)
		(layer "In4.Cu")
		(net "SGPIO_SCM_DO_<1>")
	)
	(segment
		(start 175.53305 -105.689654)
		(end 175.53305 -106.904282)
		(width 0.11684)
		(layer "In4.Cu")
		(net "SGPIO_SCM_DO_<1>")
	)
	(segment
		(start 175.53305 -106.904282)
		(end 176.308766 -107.679998)
		(width 0.11684)
		(layer "In4.Cu")
		(net "SGPIO_SCM_DO_<1>")
	)
	(segment
		(start 172.70476 -101.836982)
		(end 172.607986 -101.933756)
		(width 0.11684)
		(layer "In4.Cu")
		(net "SGPIO_SCM_DO_<1>")
	)
	(segment
		(start 172.607986 -101.933756)
		(end 172.607986 -102.41915)
		(width 0.11684)
		(layer "In4.Cu")
		(net "SGPIO_SCM_DO_<1>")
	)
	(segment
		(start 173.724824 -103.535988)
		(end 173.724824 -103.881428)
		(width 0.11684)
		(layer "In4.Cu")
		(net "SGPIO_SCM_DO_<1>")
	)
	(segment
		(start 176.465484 -108.614972)
		(end 177.484278 -108.614972)
		(width 0.11684)
		(layer "In4.Cu")
		(net "SGPIO_SCM_DO_<1>")
	)
	(segment
		(start 173.724824 -103.881428)
		(end 175.53305 -105.689654)
		(width 0.11684)
		(layer "In4.Cu")
		(net "SGPIO_SCM_DO_<1>")
	)
	(segment
		(start 180.32222 -111.452914)
		(end 179.93233 -111.063024)
		(width 0.10668)
		(layer "F.Cu")
		(net "SGPIO_SCM_DO_<0>")
	)
	(segment
		(start 173.609 -100.694998)
		(end 173.609 -102.020116)
		(width 0.10668)
		(layer "F.Cu")
		(net "SGPIO_SCM_DO_<0>")
	)
	(segment
		(start 173.764956 -102.176072)
		(end 173.937676 -102.176072)
		(width 0.10668)
		(layer "F.Cu")
		(net "SGPIO_SCM_DO_<0>")
	)
	(segment
		(start 173.609 -102.020116)
		(end 173.764956 -102.176072)
		(width 0.10668)
		(layer "F.Cu")
		(net "SGPIO_SCM_DO_<0>")
	)
	(via
		(at 179.93233 -111.063024)
		(size 0.4572)
		(drill 0.254)
		(layers "F.Cu" "B.Cu")
		(net "SGPIO_SCM_DO_<0>")
	)
	(via
		(at 173.937676 -102.176072)
		(size 0.508)
		(drill 0.254)
		(layers "F.Cu" "B.Cu")
		(net "SGPIO_SCM_DO_<0>")
	)
	(segment
		(start 173.609 -100.694998)
		(end 173.609 -102.020116)
		(width 0.10668)
		(layer "B.Cu")
		(net "SGPIO_SCM_DO_<0>")
	)
	(segment
		(start 173.609 -102.020116)
		(end 173.764956 -102.176072)
		(width 0.10668)
		(layer "B.Cu")
		(net "SGPIO_SCM_DO_<0>")
	)
	(segment
		(start 173.764956 -102.176072)
		(end 173.937676 -102.176072)
		(width 0.10668)
		(layer "B.Cu")
		(net "SGPIO_SCM_DO_<0>")
	)
	(segment
		(start 179.542186 -110.67288)
		(end 179.93233 -111.063024)
		(width 0.11684)
		(layer "In4.Cu")
		(net "SGPIO_SCM_DO_<0>")
	)
	(segment
		(start 177.75428 -105.010966)
		(end 177.75428 -107.40263)
		(width 0.11684)
		(layer "In4.Cu")
		(net "SGPIO_SCM_DO_<0>")
	)
	(segment
		(start 173.937676 -102.176072)
		(end 174.04461 -102.131622)
		(width 0.11684)
		(layer "In4.Cu")
		(net "SGPIO_SCM_DO_<0>")
	)
	(segment
		(start 178.722274 -108.948474)
		(end 178.839114 -109.065314)
		(width 0.11684)
		(layer "In4.Cu")
		(net "SGPIO_SCM_DO_<0>")
	)
	(segment
		(start 179.542186 -109.19968)
		(end 179.542186 -110.67288)
		(width 0.11684)
		(layer "In4.Cu")
		(net "SGPIO_SCM_DO_<0>")
	)
	(segment
		(start 174.04461 -102.131622)
		(end 175.462946 -102.719632)
		(width 0.11684)
		(layer "In4.Cu")
		(net "SGPIO_SCM_DO_<0>")
	)
	(segment
		(start 175.462946 -102.719632)
		(end 177.75428 -105.010966)
		(width 0.11684)
		(layer "In4.Cu")
		(net "SGPIO_SCM_DO_<0>")
	)
	(segment
		(start 178.839114 -109.065314)
		(end 179.40782 -109.065314)
		(width 0.11684)
		(layer "In4.Cu")
		(net "SGPIO_SCM_DO_<0>")
	)
	(segment
		(start 177.75428 -107.40263)
		(end 178.722274 -108.370624)
		(width 0.11684)
		(layer "In4.Cu")
		(net "SGPIO_SCM_DO_<0>")
	)
	(segment
		(start 178.722274 -108.370624)
		(end 178.722274 -108.948474)
		(width 0.11684)
		(layer "In4.Cu")
		(net "SGPIO_SCM_DO_<0>")
	)
	(segment
		(start 179.40782 -109.065314)
		(end 179.542186 -109.19968)
		(width 0.11684)
		(layer "In4.Cu")
		(net "SGPIO_SCM_DO_<0>")
	)
	(segment
		(start 178.72202 -110.652814)
		(end 178.33213 -110.262924)
		(width 0.10668)
		(layer "F.Cu")
		(net "SGPIO_SCM_DI_R<1>")
	)
	(via
		(at 178.33213 -110.262924)
		(size 0.4572)
		(drill 0.254)
		(layers "F.Cu" "B.Cu")
		(net "SGPIO_SCM_DI_R<1>")
	)
	(via
		(at 173.52645 -110.200948)
		(size 0.6604)
		(drill 0.3302)
		(layers "F.Cu" "B.Cu")
		(net "SGPIO_SCM_DI_R<1>")
	)
	(segment
		(start 173.807882 -110.48238)
		(end 178.112674 -110.48238)
		(width 0.10668)
		(layer "B.Cu")
		(net "SGPIO_SCM_DI_R<1>")
	)
	(segment
		(start 173.52645 -110.200948)
		(end 173.807882 -110.48238)
		(width 0.10668)
		(layer "B.Cu")
		(net "SGPIO_SCM_DI_R<1>")
	)
	(segment
		(start 171.59605 -110.200948)
		(end 173.52645 -110.200948)
		(width 0.10668)
		(layer "B.Cu")
		(net "SGPIO_SCM_DI_R<1>")
	)
	(segment
		(start 178.112674 -110.48238)
		(end 178.33213 -110.262924)
		(width 0.10668)
		(layer "B.Cu")
		(net "SGPIO_SCM_DI_R<1>")
	)
	(segment
		(start 171.65701 -109.184948)
		(end 171.59605 -109.184948)
		(width 0.10668)
		(layer "F.Cu")
		(net "SGPIO_SCM_DI_R<0>")
	)
	(segment
		(start 175.264572 -110.315502)
		(end 172.787564 -110.315502)
		(width 0.10668)
		(layer "F.Cu")
		(net "SGPIO_SCM_DI_R<0>")
	)
	(segment
		(start 177.122074 -109.052868)
		(end 176.527206 -109.052868)
		(width 0.10668)
		(layer "F.Cu")
		(net "SGPIO_SCM_DI_R<0>")
	)
	(segment
		(start 176.527206 -109.052868)
		(end 175.264572 -110.315502)
		(width 0.10668)
		(layer "F.Cu")
		(net "SGPIO_SCM_DI_R<0>")
	)
	(segment
		(start 172.787564 -110.315502)
		(end 171.65701 -109.184948)
		(width 0.10668)
		(layer "F.Cu")
		(net "SGPIO_SCM_DI_R<0>")
	)
	(via
		(at 172.787564 -110.315502)
		(size 0.762)
		(drill 0.381)
		(layers "F.Cu" "B.Cu")
		(net "SGPIO_SCM_DI_R<0>")
	)
	(segment
		(start 152.97912 -23.684992)
		(end 152.97912 -24.831548)
		(width 0.10668)
		(layer "F.Cu")
		(net "SGPIO_SCM_DI_<1>")
	)
	(segment
		(start 152.29332 -25.589738)
		(end 152.991312 -26.28773)
		(width 0.10668)
		(layer "F.Cu")
		(net "SGPIO_SCM_DI_<1>")
	)
	(segment
		(start 152.97912 -24.831548)
		(end 152.22093 -25.589738)
		(width 0.10668)
		(layer "F.Cu")
		(net "SGPIO_SCM_DI_<1>")
	)
	(segment
		(start 152.22093 -25.589738)
		(end 152.29332 -25.589738)
		(width 0.10668)
		(layer "F.Cu")
		(net "SGPIO_SCM_DI_<1>")
	)
	(via
		(at 152.22093 -25.589738)
		(size 0.508)
		(drill 0.254)
		(layers "F.Cu" "B.Cu")
		(net "SGPIO_SCM_DI_<1>")
	)
	(via
		(at 170.18 -110.196376)
		(size 0.508)
		(drill 0.254)
		(layers "F.Cu" "B.Cu")
		(net "SGPIO_SCM_DI_<1>")
	)
	(segment
		(start 170.791378 -110.196376)
		(end 170.18 -110.196376)
		(width 0.10668)
		(layer "B.Cu")
		(net "SGPIO_SCM_DI_<1>")
	)
	(segment
		(start 170.79595 -110.200948)
		(end 170.791378 -110.196376)
		(width 0.10668)
		(layer "B.Cu")
		(net "SGPIO_SCM_DI_<1>")
	)
	(segment
		(start 171.05757 -103.545894)
		(end 171.05757 -104.553512)
		(width 0.11684)
		(layer "In4.Cu")
		(net "SGPIO_SCM_DI_<1>")
	)
	(segment
		(start 156.408628 -48.224186)
		(end 156.408628 -56.190388)
		(width 0.11684)
		(layer "In4.Cu")
		(net "SGPIO_SCM_DI_<1>")
	)
	(segment
		(start 170.882818 -93.14053)
		(end 171.357036 -93.614748)
		(width 0.11684)
		(layer "In4.Cu")
		(net "SGPIO_SCM_DI_<1>")
	)
	(segment
		(start 163.7792 -88.537542)
		(end 168.382188 -93.14053)
		(width 0.11684)
		(layer "In4.Cu")
		(net "SGPIO_SCM_DI_<1>")
	)
	(segment
		(start 169.997628 -98.79076)
		(end 169.997628 -102.485952)
		(width 0.11684)
		(layer "In4.Cu")
		(net "SGPIO_SCM_DI_<1>")
	)
	(segment
		(start 171.05757 -104.553512)
		(end 171.556426 -105.052368)
		(width 0.11684)
		(layer "In4.Cu")
		(net "SGPIO_SCM_DI_<1>")
	)
	(segment
		(start 152.22093 -29.992066)
		(end 156.06268 -33.833816)
		(width 0.11684)
		(layer "In4.Cu")
		(net "SGPIO_SCM_DI_<1>")
	)
	(segment
		(start 156.408628 -56.190388)
		(end 156.99105 -56.77281)
		(width 0.11684)
		(layer "In4.Cu")
		(net "SGPIO_SCM_DI_<1>")
	)
	(segment
		(start 156.06268 -33.833816)
		(end 156.06268 -44.439332)
		(width 0.11684)
		(layer "In4.Cu")
		(net "SGPIO_SCM_DI_<1>")
	)
	(segment
		(start 168.382188 -93.14053)
		(end 170.882818 -93.14053)
		(width 0.11684)
		(layer "In4.Cu")
		(net "SGPIO_SCM_DI_<1>")
	)
	(segment
		(start 170.9928 -96.38792)
		(end 171.357036 -96.752156)
		(width 0.11684)
		(layer "In4.Cu")
		(net "SGPIO_SCM_DI_<1>")
	)
	(segment
		(start 154.934412 -46.74997)
		(end 156.408628 -48.224186)
		(width 0.11684)
		(layer "In4.Cu")
		(net "SGPIO_SCM_DI_<1>")
	)
	(segment
		(start 156.99105 -63.764668)
		(end 162.953192 -69.72681)
		(width 0.11684)
		(layer "In4.Cu")
		(net "SGPIO_SCM_DI_<1>")
	)
	(segment
		(start 154.934412 -45.5676)
		(end 154.934412 -46.74997)
		(width 0.11684)
		(layer "In4.Cu")
		(net "SGPIO_SCM_DI_<1>")
	)
	(segment
		(start 162.953192 -77.955648)
		(end 163.7792 -78.781656)
		(width 0.11684)
		(layer "In4.Cu")
		(net "SGPIO_SCM_DI_<1>")
	)
	(segment
		(start 156.06268 -44.439332)
		(end 154.934412 -45.5676)
		(width 0.11684)
		(layer "In4.Cu")
		(net "SGPIO_SCM_DI_<1>")
	)
	(segment
		(start 171.357036 -96.752156)
		(end 171.357036 -97.431352)
		(width 0.11684)
		(layer "In4.Cu")
		(net "SGPIO_SCM_DI_<1>")
	)
	(segment
		(start 162.953192 -69.72681)
		(end 162.953192 -77.955648)
		(width 0.11684)
		(layer "In4.Cu")
		(net "SGPIO_SCM_DI_<1>")
	)
	(segment
		(start 171.357036 -97.431352)
		(end 169.997628 -98.79076)
		(width 0.11684)
		(layer "In4.Cu")
		(net "SGPIO_SCM_DI_<1>")
	)
	(segment
		(start 156.99105 -56.77281)
		(end 156.99105 -63.764668)
		(width 0.11684)
		(layer "In4.Cu")
		(net "SGPIO_SCM_DI_<1>")
	)
	(segment
		(start 171.556426 -105.052368)
		(end 171.556426 -108.81995)
		(width 0.11684)
		(layer "In4.Cu")
		(net "SGPIO_SCM_DI_<1>")
	)
	(segment
		(start 171.357036 -93.614748)
		(end 171.357036 -94.1705)
		(width 0.11684)
		(layer "In4.Cu")
		(net "SGPIO_SCM_DI_<1>")
	)
	(segment
		(start 171.357036 -94.1705)
		(end 170.9928 -94.534736)
		(width 0.11684)
		(layer "In4.Cu")
		(net "SGPIO_SCM_DI_<1>")
	)
	(segment
		(start 152.22093 -25.589738)
		(end 152.22093 -29.992066)
		(width 0.11684)
		(layer "In4.Cu")
		(net "SGPIO_SCM_DI_<1>")
	)
	(segment
		(start 171.556426 -108.81995)
		(end 170.18 -110.196376)
		(width 0.11684)
		(layer "In4.Cu")
		(net "SGPIO_SCM_DI_<1>")
	)
	(segment
		(start 163.7792 -78.781656)
		(end 163.7792 -88.537542)
		(width 0.11684)
		(layer "In4.Cu")
		(net "SGPIO_SCM_DI_<1>")
	)
	(segment
		(start 169.997628 -102.485952)
		(end 171.05757 -103.545894)
		(width 0.11684)
		(layer "In4.Cu")
		(net "SGPIO_SCM_DI_<1>")
	)
	(segment
		(start 170.9928 -94.534736)
		(end 170.9928 -96.38792)
		(width 0.11684)
		(layer "In4.Cu")
		(net "SGPIO_SCM_DI_<1>")
	)
	(segment
		(start 170.18508 -109.180376)
		(end 170.18 -109.185456)
		(width 0.10668)
		(layer "F.Cu")
		(net "SGPIO_SCM_DI_<0>")
	)
	(segment
		(start 170.79595 -109.184948)
		(end 170.791378 -109.180376)
		(width 0.10668)
		(layer "F.Cu")
		(net "SGPIO_SCM_DI_<0>")
	)
	(segment
		(start 157.018228 -23.684992)
		(end 157.018228 -25.599644)
		(width 0.10668)
		(layer "F.Cu")
		(net "SGPIO_SCM_DI_<0>")
	)
	(segment
		(start 157.018228 -26.268934)
		(end 157.037024 -26.28773)
		(width 0.10668)
		(layer "F.Cu")
		(net "SGPIO_SCM_DI_<0>")
	)
	(segment
		(start 157.018228 -25.599644)
		(end 157.018228 -26.268934)
		(width 0.10668)
		(layer "F.Cu")
		(net "SGPIO_SCM_DI_<0>")
	)
	(segment
		(start 170.791378 -109.180376)
		(end 170.18508 -109.180376)
		(width 0.10668)
		(layer "F.Cu")
		(net "SGPIO_SCM_DI_<0>")
	)
	(via
		(at 157.018228 -25.599644)
		(size 0.508)
		(drill 0.254)
		(layers "F.Cu" "B.Cu")
		(net "SGPIO_SCM_DI_<0>")
	)
	(via
		(at 170.18 -109.185456)
		(size 0.508)
		(drill 0.254)
		(layers "F.Cu" "B.Cu")
		(net "SGPIO_SCM_DI_<0>")
	)
	(segment
		(start 168.613836 -109.614208)
		(end 168.613836 -108.655866)
		(width 0.11684)
		(layer "In4.Cu")
		(net "SGPIO_SCM_DI_<0>")
	)
	(segment
		(start 154.042872 -47.11954)
		(end 154.042872 -45.19803)
		(width 0.11684)
		(layer "In4.Cu")
		(net "SGPIO_SCM_DI_<0>")
	)
	(segment
		(start 154.042872 -45.19803)
		(end 155.17114 -44.069762)
		(width 0.11684)
		(layer "In4.Cu")
		(net "SGPIO_SCM_DI_<0>")
	)
	(segment
		(start 156.09951 -57.154572)
		(end 155.517088 -56.57215)
		(width 0.11684)
		(layer "In4.Cu")
		(net "SGPIO_SCM_DI_<0>")
	)
	(segment
		(start 155.517088 -48.593756)
		(end 154.042872 -47.11954)
		(width 0.11684)
		(layer "In4.Cu")
		(net "SGPIO_SCM_DI_<0>")
	)
	(segment
		(start 150.844758 -27.50947)
		(end 150.844758 -23.883112)
		(width 0.11684)
		(layer "In4.Cu")
		(net "SGPIO_SCM_DI_<0>")
	)
	(segment
		(start 167.818562 -95.80372)
		(end 167.818562 -94.144338)
		(width 0.11684)
		(layer "In4.Cu")
		(net "SGPIO_SCM_DI_<0>")
	)
	(segment
		(start 155.517088 -56.57215)
		(end 155.517088 -48.593756)
		(width 0.11684)
		(layer "In4.Cu")
		(net "SGPIO_SCM_DI_<0>")
	)
	(segment
		(start 168.72966 -109.730032)
		(end 168.613836 -109.614208)
		(width 0.11684)
		(layer "In4.Cu")
		(net "SGPIO_SCM_DI_<0>")
	)
	(segment
		(start 151.019764 -30.093666)
		(end 151.019764 -27.932126)
		(width 0.11684)
		(layer "In4.Cu")
		(net "SGPIO_SCM_DI_<0>")
	)
	(segment
		(start 168.586658 -104.97947)
		(end 168.586658 -96.571816)
		(width 0.11684)
		(layer "In4.Cu")
		(net "SGPIO_SCM_DI_<0>")
	)
	(segment
		(start 157.018228 -23.77567)
		(end 157.018228 -25.599644)
		(width 0.11684)
		(layer "In4.Cu")
		(net "SGPIO_SCM_DI_<0>")
	)
	(segment
		(start 168.613836 -108.655866)
		(end 168.382188 -108.424218)
		(width 0.11684)
		(layer "In4.Cu")
		(net "SGPIO_SCM_DI_<0>")
	)
	(segment
		(start 168.929812 -105.322624)
		(end 168.586658 -104.97947)
		(width 0.11684)
		(layer "In4.Cu")
		(net "SGPIO_SCM_DI_<0>")
	)
	(segment
		(start 168.929812 -106.675936)
		(end 168.929812 -105.322624)
		(width 0.11684)
		(layer "In4.Cu")
		(net "SGPIO_SCM_DI_<0>")
	)
	(segment
		(start 162.011868 -88.337644)
		(end 162.011868 -69.978524)
		(width 0.11684)
		(layer "In4.Cu")
		(net "SGPIO_SCM_DI_<0>")
	)
	(segment
		(start 169.635424 -109.730032)
		(end 168.72966 -109.730032)
		(width 0.11684)
		(layer "In4.Cu")
		(net "SGPIO_SCM_DI_<0>")
	)
	(segment
		(start 167.818562 -94.144338)
		(end 162.011868 -88.337644)
		(width 0.11684)
		(layer "In4.Cu")
		(net "SGPIO_SCM_DI_<0>")
	)
	(segment
		(start 150.844758 -23.883112)
		(end 151.652478 -23.075392)
		(width 0.11684)
		(layer "In4.Cu")
		(net "SGPIO_SCM_DI_<0>")
	)
	(segment
		(start 162.011868 -69.978524)
		(end 156.09951 -64.066166)
		(width 0.11684)
		(layer "In4.Cu")
		(net "SGPIO_SCM_DI_<0>")
	)
	(segment
		(start 151.019764 -27.932126)
		(end 150.844758 -27.50947)
		(width 0.11684)
		(layer "In4.Cu")
		(net "SGPIO_SCM_DI_<0>")
	)
	(segment
		(start 155.17114 -44.069762)
		(end 155.17114 -34.245042)
		(width 0.11684)
		(layer "In4.Cu")
		(net "SGPIO_SCM_DI_<0>")
	)
	(segment
		(start 168.382188 -107.22356)
		(end 168.929812 -106.675936)
		(width 0.11684)
		(layer "In4.Cu")
		(net "SGPIO_SCM_DI_<0>")
	)
	(segment
		(start 168.382188 -108.424218)
		(end 168.382188 -107.22356)
		(width 0.11684)
		(layer "In4.Cu")
		(net "SGPIO_SCM_DI_<0>")
	)
	(segment
		(start 156.09951 -64.066166)
		(end 156.09951 -57.154572)
		(width 0.11684)
		(layer "In4.Cu")
		(net "SGPIO_SCM_DI_<0>")
	)
	(segment
		(start 170.18 -109.185456)
		(end 169.635424 -109.730032)
		(width 0.11684)
		(layer "In4.Cu")
		(net "SGPIO_SCM_DI_<0>")
	)
	(segment
		(start 151.652478 -23.075392)
		(end 156.31795 -23.075392)
		(width 0.11684)
		(layer "In4.Cu")
		(net "SGPIO_SCM_DI_<0>")
	)
	(segment
		(start 155.17114 -34.245042)
		(end 151.019764 -30.093666)
		(width 0.11684)
		(layer "In4.Cu")
		(net "SGPIO_SCM_DI_<0>")
	)
	(segment
		(start 156.31795 -23.075392)
		(end 157.018228 -23.77567)
		(width 0.11684)
		(layer "In4.Cu")
		(net "SGPIO_SCM_DI_<0>")
	)
	(segment
		(start 168.586658 -96.571816)
		(end 167.818562 -95.80372)
		(width 0.11684)
		(layer "In4.Cu")
		(net "SGPIO_SCM_DI_<0>")
	)
	(segment
		(start 176.341532 -117.052852)
		(end 175.677068 -117.717316)
		(width 0.10668)
		(layer "F.Cu")
		(net "SGPIO_OCP_V3_2_LD_N")
	)
	(segment
		(start 76.861924 -11.26998)
		(end 76.861924 -12.63777)
		(width 0.10668)
		(layer "F.Cu")
		(net "SGPIO_OCP_V3_2_LD_N")
	)
	(segment
		(start 177.122074 -117.052852)
		(end 176.341532 -117.052852)
		(width 0.10668)
		(layer "F.Cu")
		(net "SGPIO_OCP_V3_2_LD_N")
	)
	(segment
		(start 175.677068 -118.146576)
		(end 175.659288 -118.164356)
		(width 0.10668)
		(layer "F.Cu")
		(net "SGPIO_OCP_V3_2_LD_N")
	)
	(segment
		(start 175.677068 -117.717316)
		(end 175.677068 -118.146576)
		(width 0.10668)
		(layer "F.Cu")
		(net "SGPIO_OCP_V3_2_LD_N")
	)
	(segment
		(start 76.861924 -12.63777)
		(end 77.142594 -12.91844)
		(width 0.10668)
		(layer "F.Cu")
		(net "SGPIO_OCP_V3_2_LD_N")
	)
	(via
		(at 175.659288 -118.164356)
		(size 0.508)
		(drill 0.254)
		(layers "F.Cu" "B.Cu")
		(net "SGPIO_OCP_V3_2_LD_N")
	)
	(via
		(at 77.142594 -12.91844)
		(size 0.508)
		(drill 0.254)
		(layers "F.Cu" "B.Cu")
		(net "SGPIO_OCP_V3_2_LD_N")
	)
	(segment
		(start 76.20508 -12.076938)
		(end 76.20508 -11.667998)
		(width 0.10668)
		(layer "B.Cu")
		(net "SGPIO_OCP_V3_2_LD_N")
	)
	(segment
		(start 77.142594 -12.91844)
		(end 76.506578 -12.282424)
		(width 0.10668)
		(layer "B.Cu")
		(net "SGPIO_OCP_V3_2_LD_N")
	)
	(segment
		(start 76.506578 -12.282424)
		(end 76.410566 -12.282424)
		(width 0.10668)
		(layer "B.Cu")
		(net "SGPIO_OCP_V3_2_LD_N")
	)
	(segment
		(start 76.410566 -12.282424)
		(end 76.20508 -12.076938)
		(width 0.10668)
		(layer "B.Cu")
		(net "SGPIO_OCP_V3_2_LD_N")
	)
	(segment
		(start 163.670234 -123.444508)
		(end 166.277798 -123.444508)
		(width 0.11684)
		(layer "In4.Cu")
		(net "SGPIO_OCP_V3_2_LD_N")
	)
	(segment
		(start 170.434 -121.92)
		(end 170.688 -121.666)
		(width 0.11684)
		(layer "In4.Cu")
		(net "SGPIO_OCP_V3_2_LD_N")
	)
	(segment
		(start 166.277798 -123.444508)
		(end 167.802306 -121.92)
		(width 0.11684)
		(layer "In4.Cu")
		(net "SGPIO_OCP_V3_2_LD_N")
	)
	(segment
		(start 77.142594 -12.91844)
		(end 77.142594 -12.991846)
		(width 0.11684)
		(layer "In4.Cu")
		(net "SGPIO_OCP_V3_2_LD_N")
	)
	(segment
		(start 105.423462 -78.475332)
		(end 106.53903 -79.5909)
		(width 0.11684)
		(layer "In4.Cu")
		(net "SGPIO_OCP_V3_2_LD_N")
	)
	(segment
		(start 170.688 -120.904254)
		(end 171.196254 -120.396)
		(width 0.11684)
		(layer "In4.Cu")
		(net "SGPIO_OCP_V3_2_LD_N")
	)
	(segment
		(start 96.038162 -51.890422)
		(end 101.219762 -57.072022)
		(width 0.11684)
		(layer "In4.Cu")
		(net "SGPIO_OCP_V3_2_LD_N")
	)
	(segment
		(start 84.48294 -17.34439)
		(end 84.48294 -37.568632)
		(width 0.11684)
		(layer "In4.Cu")
		(net "SGPIO_OCP_V3_2_LD_N")
	)
	(segment
		(start 80.44815 -13.3096)
		(end 84.48294 -17.34439)
		(width 0.11684)
		(layer "In4.Cu")
		(net "SGPIO_OCP_V3_2_LD_N")
	)
	(segment
		(start 106.53903 -79.5909)
		(end 106.53903 -83.607656)
		(width 0.11684)
		(layer "In4.Cu")
		(net "SGPIO_OCP_V3_2_LD_N")
	)
	(segment
		(start 91.526106 -51.890422)
		(end 96.038162 -51.890422)
		(width 0.11684)
		(layer "In4.Cu")
		(net "SGPIO_OCP_V3_2_LD_N")
	)
	(segment
		(start 77.460348 -13.3096)
		(end 80.44815 -13.3096)
		(width 0.11684)
		(layer "In4.Cu")
		(net "SGPIO_OCP_V3_2_LD_N")
	)
	(segment
		(start 88.13165 -41.217342)
		(end 88.13165 -48.495966)
		(width 0.11684)
		(layer "In4.Cu")
		(net "SGPIO_OCP_V3_2_LD_N")
	)
	(segment
		(start 175.26 -118.563644)
		(end 175.659288 -118.164356)
		(width 0.11684)
		(layer "In4.Cu")
		(net "SGPIO_OCP_V3_2_LD_N")
	)
	(segment
		(start 84.48294 -37.568632)
		(end 88.13165 -41.217342)
		(width 0.11684)
		(layer "In4.Cu")
		(net "SGPIO_OCP_V3_2_LD_N")
	)
	(segment
		(start 175.26 -120.087644)
		(end 175.26 -118.563644)
		(width 0.11684)
		(layer "In4.Cu")
		(net "SGPIO_OCP_V3_2_LD_N")
	)
	(segment
		(start 146.71929 -123.787916)
		(end 163.326826 -123.787916)
		(width 0.11684)
		(layer "In4.Cu")
		(net "SGPIO_OCP_V3_2_LD_N")
	)
	(segment
		(start 88.13165 -48.495966)
		(end 91.526106 -51.890422)
		(width 0.11684)
		(layer "In4.Cu")
		(net "SGPIO_OCP_V3_2_LD_N")
	)
	(segment
		(start 101.219762 -57.072022)
		(end 101.219762 -72.289416)
		(width 0.11684)
		(layer "In4.Cu")
		(net "SGPIO_OCP_V3_2_LD_N")
	)
	(segment
		(start 105.423462 -76.493116)
		(end 105.423462 -78.475332)
		(width 0.11684)
		(layer "In4.Cu")
		(net "SGPIO_OCP_V3_2_LD_N")
	)
	(segment
		(start 101.219762 -72.289416)
		(end 105.423462 -76.493116)
		(width 0.11684)
		(layer "In4.Cu")
		(net "SGPIO_OCP_V3_2_LD_N")
	)
	(segment
		(start 106.53903 -83.607656)
		(end 146.71929 -123.787916)
		(width 0.11684)
		(layer "In4.Cu")
		(net "SGPIO_OCP_V3_2_LD_N")
	)
	(segment
		(start 171.196254 -120.396)
		(end 174.951644 -120.396)
		(width 0.11684)
		(layer "In4.Cu")
		(net "SGPIO_OCP_V3_2_LD_N")
	)
	(segment
		(start 167.802306 -121.92)
		(end 170.434 -121.92)
		(width 0.11684)
		(layer "In4.Cu")
		(net "SGPIO_OCP_V3_2_LD_N")
	)
	(segment
		(start 174.951644 -120.396)
		(end 175.26 -120.087644)
		(width 0.11684)
		(layer "In4.Cu")
		(net "SGPIO_OCP_V3_2_LD_N")
	)
	(segment
		(start 163.326826 -123.787916)
		(end 163.670234 -123.444508)
		(width 0.11684)
		(layer "In4.Cu")
		(net "SGPIO_OCP_V3_2_LD_N")
	)
	(segment
		(start 170.688 -121.666)
		(end 170.688 -120.904254)
		(width 0.11684)
		(layer "In4.Cu")
		(net "SGPIO_OCP_V3_2_LD_N")
	)
	(segment
		(start 77.142594 -12.991846)
		(end 77.460348 -13.3096)
		(width 0.11684)
		(layer "In4.Cu")
		(net "SGPIO_OCP_V3_2_LD_N")
	)
	(segment
		(start 75.662028 -12.869672)
		(end 75.768708 -12.976352)
		(width 0.10668)
		(layer "F.Cu")
		(net "SGPIO_OCP_V3_2_DATAOUT")
	)
	(segment
		(start 75.662028 -11.26998)
		(end 75.662028 -12.869672)
		(width 0.10668)
		(layer "F.Cu")
		(net "SGPIO_OCP_V3_2_DATAOUT")
	)
	(segment
		(start 75.768708 -12.976352)
		(end 75.829668 -12.976352)
		(width 0.10668)
		(layer "F.Cu")
		(net "SGPIO_OCP_V3_2_DATAOUT")
	)
	(segment
		(start 178.72202 -117.052852)
		(end 178.33213 -117.442742)
		(width 0.10668)
		(layer "F.Cu")
		(net "SGPIO_OCP_V3_2_DATAOUT")
	)
	(via
		(at 178.33213 -117.442742)
		(size 0.4572)
		(drill 0.254)
		(layers "F.Cu" "B.Cu")
		(net "SGPIO_OCP_V3_2_DATAOUT")
	)
	(via
		(at 75.829668 -12.976352)
		(size 0.508)
		(drill 0.254)
		(layers "F.Cu" "B.Cu")
		(net "SGPIO_OCP_V3_2_DATAOUT")
	)
	(segment
		(start 74.467974 -11.567922)
		(end 74.467974 -9.87679)
		(width 0.10668)
		(layer "B.Cu")
		(net "SGPIO_OCP_V3_2_DATAOUT")
	)
	(segment
		(start 75.829668 -12.929616)
		(end 74.467974 -11.567922)
		(width 0.10668)
		(layer "B.Cu")
		(net "SGPIO_OCP_V3_2_DATAOUT")
	)
	(segment
		(start 74.467974 -9.87679)
		(end 74.095864 -9.50468)
		(width 0.10668)
		(layer "B.Cu")
		(net "SGPIO_OCP_V3_2_DATAOUT")
	)
	(segment
		(start 75.829668 -12.976352)
		(end 75.829668 -12.929616)
		(width 0.10668)
		(layer "B.Cu")
		(net "SGPIO_OCP_V3_2_DATAOUT")
	)
	(segment
		(start 146.494754 -124.219716)
		(end 106.074972 -83.799934)
		(width 0.11684)
		(layer "In4.Cu")
		(net "SGPIO_OCP_V3_2_DATAOUT")
	)
	(segment
		(start 178.33213 -117.442742)
		(end 176.812956 -117.442742)
		(width 0.11684)
		(layer "In4.Cu")
		(net "SGPIO_OCP_V3_2_DATAOUT")
	)
	(segment
		(start 165.843204 -124.1044)
		(end 165.622478 -123.883674)
		(width 0.11684)
		(layer "In4.Cu")
		(net "SGPIO_OCP_V3_2_DATAOUT")
	)
	(segment
		(start 165.622478 -123.883674)
		(end 164.008816 -123.883674)
		(width 0.11684)
		(layer "In4.Cu")
		(net "SGPIO_OCP_V3_2_DATAOUT")
	)
	(segment
		(start 171.577 -120.904)
		(end 171.196 -121.285)
		(width 0.11684)
		(layer "In4.Cu")
		(net "SGPIO_OCP_V3_2_DATAOUT")
	)
	(segment
		(start 76.258928 -13.79601)
		(end 75.830684 -13.367766)
		(width 0.11684)
		(layer "In4.Cu")
		(net "SGPIO_OCP_V3_2_DATAOUT")
	)
	(segment
		(start 176.149 -118.106698)
		(end 176.149 -118.364)
		(width 0.11684)
		(layer "In4.Cu")
		(net "SGPIO_OCP_V3_2_DATAOUT")
	)
	(segment
		(start 164.008816 -123.883674)
		(end 163.672774 -124.219716)
		(width 0.11684)
		(layer "In4.Cu")
		(net "SGPIO_OCP_V3_2_DATAOUT")
	)
	(segment
		(start 171.196 -121.285)
		(end 171.196 -122.428)
		(width 0.11684)
		(layer "In4.Cu")
		(net "SGPIO_OCP_V3_2_DATAOUT")
	)
	(segment
		(start 171.196 -122.428)
		(end 171.069 -122.555)
		(width 0.11684)
		(layer "In4.Cu")
		(net "SGPIO_OCP_V3_2_DATAOUT")
	)
	(segment
		(start 87.667592 -48.688244)
		(end 87.667592 -41.40962)
		(width 0.11684)
		(layer "In4.Cu")
		(net "SGPIO_OCP_V3_2_DATAOUT")
	)
	(segment
		(start 171.069 -122.555)
		(end 171.069 -122.746008)
		(width 0.11684)
		(layer "In4.Cu")
		(net "SGPIO_OCP_V3_2_DATAOUT")
	)
	(segment
		(start 87.667592 -41.40962)
		(end 84.018882 -37.76091)
		(width 0.11684)
		(layer "In4.Cu")
		(net "SGPIO_OCP_V3_2_DATAOUT")
	)
	(segment
		(start 91.333828 -52.35448)
		(end 87.667592 -48.688244)
		(width 0.11684)
		(layer "In4.Cu")
		(net "SGPIO_OCP_V3_2_DATAOUT")
	)
	(segment
		(start 84.018882 -37.76091)
		(end 84.018882 -17.476724)
		(width 0.11684)
		(layer "In4.Cu")
		(net "SGPIO_OCP_V3_2_DATAOUT")
	)
	(segment
		(start 80.338168 -13.79601)
		(end 76.258928 -13.79601)
		(width 0.11684)
		(layer "In4.Cu")
		(net "SGPIO_OCP_V3_2_DATAOUT")
	)
	(segment
		(start 95.845884 -52.35448)
		(end 91.333828 -52.35448)
		(width 0.11684)
		(layer "In4.Cu")
		(net "SGPIO_OCP_V3_2_DATAOUT")
	)
	(segment
		(start 175.768 -118.745)
		(end 175.768 -120.325642)
		(width 0.11684)
		(layer "In4.Cu")
		(net "SGPIO_OCP_V3_2_DATAOUT")
	)
	(segment
		(start 168.1226 -124.1044)
		(end 165.843204 -124.1044)
		(width 0.11684)
		(layer "In4.Cu")
		(net "SGPIO_OCP_V3_2_DATAOUT")
	)
	(segment
		(start 104.864154 -78.521306)
		(end 104.864154 -76.64831)
		(width 0.11684)
		(layer "In4.Cu")
		(net "SGPIO_OCP_V3_2_DATAOUT")
	)
	(segment
		(start 75.830684 -13.367766)
		(end 75.830684 -12.977368)
		(width 0.11684)
		(layer "In4.Cu")
		(net "SGPIO_OCP_V3_2_DATAOUT")
	)
	(segment
		(start 106.074972 -79.732124)
		(end 104.864154 -78.521306)
		(width 0.11684)
		(layer "In4.Cu")
		(net "SGPIO_OCP_V3_2_DATAOUT")
	)
	(segment
		(start 175.189642 -120.904)
		(end 171.577 -120.904)
		(width 0.11684)
		(layer "In4.Cu")
		(net "SGPIO_OCP_V3_2_DATAOUT")
	)
	(segment
		(start 163.672774 -124.219716)
		(end 146.494754 -124.219716)
		(width 0.11684)
		(layer "In4.Cu")
		(net "SGPIO_OCP_V3_2_DATAOUT")
	)
	(segment
		(start 100.755704 -72.53986)
		(end 100.755704 -57.2643)
		(width 0.11684)
		(layer "In4.Cu")
		(net "SGPIO_OCP_V3_2_DATAOUT")
	)
	(segment
		(start 176.149 -118.364)
		(end 175.768 -118.745)
		(width 0.11684)
		(layer "In4.Cu")
		(net "SGPIO_OCP_V3_2_DATAOUT")
	)
	(segment
		(start 171.069 -122.746008)
		(end 170.117008 -123.698)
		(width 0.11684)
		(layer "In4.Cu")
		(net "SGPIO_OCP_V3_2_DATAOUT")
	)
	(segment
		(start 100.755704 -57.2643)
		(end 95.845884 -52.35448)
		(width 0.11684)
		(layer "In4.Cu")
		(net "SGPIO_OCP_V3_2_DATAOUT")
	)
	(segment
		(start 75.830684 -12.977368)
		(end 75.829668 -12.976352)
		(width 0.11684)
		(layer "In4.Cu")
		(net "SGPIO_OCP_V3_2_DATAOUT")
	)
	(segment
		(start 104.864154 -76.64831)
		(end 100.755704 -72.53986)
		(width 0.11684)
		(layer "In4.Cu")
		(net "SGPIO_OCP_V3_2_DATAOUT")
	)
	(segment
		(start 170.117008 -123.698)
		(end 168.529 -123.698)
		(width 0.11684)
		(layer "In4.Cu")
		(net "SGPIO_OCP_V3_2_DATAOUT")
	)
	(segment
		(start 175.768 -120.325642)
		(end 175.189642 -120.904)
		(width 0.11684)
		(layer "In4.Cu")
		(net "SGPIO_OCP_V3_2_DATAOUT")
	)
	(segment
		(start 106.074972 -83.799934)
		(end 106.074972 -79.732124)
		(width 0.11684)
		(layer "In4.Cu")
		(net "SGPIO_OCP_V3_2_DATAOUT")
	)
	(segment
		(start 176.812956 -117.442742)
		(end 176.149 -118.106698)
		(width 0.11684)
		(layer "In4.Cu")
		(net "SGPIO_OCP_V3_2_DATAOUT")
	)
	(segment
		(start 168.529 -123.698)
		(end 168.1226 -124.1044)
		(width 0.11684)
		(layer "In4.Cu")
		(net "SGPIO_OCP_V3_2_DATAOUT")
	)
	(segment
		(start 84.018882 -17.476724)
		(end 80.338168 -13.79601)
		(width 0.11684)
		(layer "In4.Cu")
		(net "SGPIO_OCP_V3_2_DATAOUT")
	)
	(segment
		(start 174.653448 -119.8499)
		(end 175.609758 -119.8499)
		(width 0.10668)
		(layer "F.Cu")
		(net "SGPIO_OCP_V3_2_DATAIN")
	)
	(segment
		(start 76.261976 -11.26998)
		(end 76.261976 -12.571222)
		(width 0.10668)
		(layer "F.Cu")
		(net "SGPIO_OCP_V3_2_DATAIN")
	)
	(segment
		(start 76.531724 -12.84097)
		(end 76.531724 -13.33119)
		(width 0.10668)
		(layer "F.Cu")
		(net "SGPIO_OCP_V3_2_DATAIN")
	)
	(segment
		(start 176.152048 -119.30761)
		(end 176.152048 -117.826536)
		(width 0.10668)
		(layer "F.Cu")
		(net "SGPIO_OCP_V3_2_DATAIN")
	)
	(segment
		(start 176.152048 -117.826536)
		(end 176.530508 -117.448076)
		(width 0.10668)
		(layer "F.Cu")
		(net "SGPIO_OCP_V3_2_DATAIN")
	)
	(segment
		(start 76.261976 -12.571222)
		(end 76.531724 -12.84097)
		(width 0.10668)
		(layer "F.Cu")
		(net "SGPIO_OCP_V3_2_DATAIN")
	)
	(segment
		(start 175.609758 -119.8499)
		(end 176.152048 -119.30761)
		(width 0.10668)
		(layer "F.Cu")
		(net "SGPIO_OCP_V3_2_DATAIN")
	)
	(segment
		(start 177.52695 -117.448076)
		(end 177.922174 -117.052852)
		(width 0.10668)
		(layer "F.Cu")
		(net "SGPIO_OCP_V3_2_DATAIN")
	)
	(segment
		(start 176.530508 -117.448076)
		(end 177.52695 -117.448076)
		(width 0.10668)
		(layer "F.Cu")
		(net "SGPIO_OCP_V3_2_DATAIN")
	)
	(via
		(at 75.008232 -10.979658)
		(size 0.6604)
		(drill 0.3302)
		(layers "F.Cu" "B.Cu")
		(net "SGPIO_OCP_V3_2_DATAIN")
	)
	(via
		(at 174.653448 -119.8499)
		(size 0.508)
		(drill 0.254)
		(layers "F.Cu" "B.Cu")
		(net "SGPIO_OCP_V3_2_DATAIN")
	)
	(via
		(at 76.531724 -13.33119)
		(size 0.508)
		(drill 0.254)
		(layers "F.Cu" "B.Cu")
		(net "SGPIO_OCP_V3_2_DATAIN")
	)
	(segment
		(start 75.8698 -12.258548)
		(end 76.531724 -12.920472)
		(width 0.10668)
		(layer "B.Cu")
		(net "SGPIO_OCP_V3_2_DATAIN")
	)
	(segment
		(start 75.008232 -11.625326)
		(end 75.641454 -12.258548)
		(width 0.10668)
		(layer "B.Cu")
		(net "SGPIO_OCP_V3_2_DATAIN")
	)
	(segment
		(start 75.073764 -9.50468)
		(end 75.008232 -9.570212)
		(width 0.10668)
		(layer "B.Cu")
		(net "SGPIO_OCP_V3_2_DATAIN")
	)
	(segment
		(start 75.641454 -12.258548)
		(end 75.8698 -12.258548)
		(width 0.10668)
		(layer "B.Cu")
		(net "SGPIO_OCP_V3_2_DATAIN")
	)
	(segment
		(start 76.531724 -12.920472)
		(end 76.531724 -13.33119)
		(width 0.10668)
		(layer "B.Cu")
		(net "SGPIO_OCP_V3_2_DATAIN")
	)
	(segment
		(start 75.008232 -10.979658)
		(end 75.008232 -11.625326)
		(width 0.10668)
		(layer "B.Cu")
		(net "SGPIO_OCP_V3_2_DATAIN")
	)
	(segment
		(start 75.008232 -9.570212)
		(end 75.008232 -10.979658)
		(width 0.10668)
		(layer "B.Cu")
		(net "SGPIO_OCP_V3_2_DATAIN")
	)
	(segment
		(start 163.401248 -123.022614)
		(end 163.067746 -123.356116)
		(width 0.11684)
		(layer "In4.Cu")
		(net "SGPIO_OCP_V3_2_DATAIN")
	)
	(segment
		(start 169.313352 -121.458228)
		(end 167.564562 -121.458228)
		(width 0.11684)
		(layer "In4.Cu")
		(net "SGPIO_OCP_V3_2_DATAIN")
	)
	(segment
		(start 101.656388 -72.121522)
		(end 101.656388 -56.89092)
		(width 0.11684)
		(layer "In4.Cu")
		(net "SGPIO_OCP_V3_2_DATAIN")
	)
	(segment
		(start 84.919566 -37.38753)
		(end 84.919566 -17.184624)
		(width 0.11684)
		(layer "In4.Cu")
		(net "SGPIO_OCP_V3_2_DATAIN")
	)
	(segment
		(start 167.564562 -121.458228)
		(end 166.000176 -123.022614)
		(width 0.11684)
		(layer "In4.Cu")
		(net "SGPIO_OCP_V3_2_DATAIN")
	)
	(segment
		(start 88.568276 -48.314864)
		(end 88.568276 -41.03624)
		(width 0.11684)
		(layer "In4.Cu")
		(net "SGPIO_OCP_V3_2_DATAIN")
	)
	(segment
		(start 166.000176 -123.022614)
		(end 163.401248 -123.022614)
		(width 0.11684)
		(layer "In4.Cu")
		(net "SGPIO_OCP_V3_2_DATAIN")
	)
	(segment
		(start 106.975656 -83.426554)
		(end 106.975656 -79.376016)
		(width 0.11684)
		(layer "In4.Cu")
		(net "SGPIO_OCP_V3_2_DATAIN")
	)
	(segment
		(start 170.92168 -119.8499)
		(end 169.313352 -121.458228)
		(width 0.11684)
		(layer "In4.Cu")
		(net "SGPIO_OCP_V3_2_DATAIN")
	)
	(segment
		(start 106.074972 -78.475332)
		(end 106.074972 -76.540106)
		(width 0.11684)
		(layer "In4.Cu")
		(net "SGPIO_OCP_V3_2_DATAIN")
	)
	(segment
		(start 174.653448 -119.8499)
		(end 170.92168 -119.8499)
		(width 0.11684)
		(layer "In4.Cu")
		(net "SGPIO_OCP_V3_2_DATAIN")
	)
	(segment
		(start 146.905218 -123.356116)
		(end 106.975656 -83.426554)
		(width 0.11684)
		(layer "In4.Cu")
		(net "SGPIO_OCP_V3_2_DATAIN")
	)
	(segment
		(start 101.656388 -56.89092)
		(end 96.219264 -51.453796)
		(width 0.11684)
		(layer "In4.Cu")
		(net "SGPIO_OCP_V3_2_DATAIN")
	)
	(segment
		(start 106.074972 -76.540106)
		(end 101.656388 -72.121522)
		(width 0.11684)
		(layer "In4.Cu")
		(net "SGPIO_OCP_V3_2_DATAIN")
	)
	(segment
		(start 91.707208 -51.453796)
		(end 88.568276 -48.314864)
		(width 0.11684)
		(layer "In4.Cu")
		(net "SGPIO_OCP_V3_2_DATAIN")
	)
	(segment
		(start 96.219264 -51.453796)
		(end 91.707208 -51.453796)
		(width 0.11684)
		(layer "In4.Cu")
		(net "SGPIO_OCP_V3_2_DATAIN")
	)
	(segment
		(start 80.01889 -12.283948)
		(end 76.848716 -12.283948)
		(width 0.11684)
		(layer "In4.Cu")
		(net "SGPIO_OCP_V3_2_DATAIN")
	)
	(segment
		(start 76.848716 -12.283948)
		(end 76.531724 -12.60094)
		(width 0.11684)
		(layer "In4.Cu")
		(net "SGPIO_OCP_V3_2_DATAIN")
	)
	(segment
		(start 163.067746 -123.356116)
		(end 146.905218 -123.356116)
		(width 0.11684)
		(layer "In4.Cu")
		(net "SGPIO_OCP_V3_2_DATAIN")
	)
	(segment
		(start 106.975656 -79.376016)
		(end 106.074972 -78.475332)
		(width 0.11684)
		(layer "In4.Cu")
		(net "SGPIO_OCP_V3_2_DATAIN")
	)
	(segment
		(start 88.568276 -41.03624)
		(end 84.919566 -37.38753)
		(width 0.11684)
		(layer "In4.Cu")
		(net "SGPIO_OCP_V3_2_DATAIN")
	)
	(segment
		(start 76.531724 -12.60094)
		(end 76.531724 -13.33119)
		(width 0.11684)
		(layer "In4.Cu")
		(net "SGPIO_OCP_V3_2_DATAIN")
	)
	(segment
		(start 84.919566 -17.184624)
		(end 80.01889 -12.283948)
		(width 0.11684)
		(layer "In4.Cu")
		(net "SGPIO_OCP_V3_2_DATAIN")
	)
	(segment
		(start 75.06208 -13.979652)
		(end 75.269598 -14.18717)
		(width 0.10668)
		(layer "F.Cu")
		(net "SGPIO_OCP_V3_2_CLK")
	)
	(segment
		(start 75.06208 -11.26998)
		(end 75.06208 -13.979652)
		(width 0.10668)
		(layer "F.Cu")
		(net "SGPIO_OCP_V3_2_CLK")
	)
	(segment
		(start 179.52212 -117.052852)
		(end 179.13223 -117.442742)
		(width 0.10668)
		(layer "F.Cu")
		(net "SGPIO_OCP_V3_2_CLK")
	)
	(via
		(at 75.269598 -14.18717)
		(size 0.508)
		(drill 0.254)
		(layers "F.Cu" "B.Cu")
		(net "SGPIO_OCP_V3_2_CLK")
	)
	(via
		(at 179.13223 -117.442742)
		(size 0.4572)
		(drill 0.254)
		(layers "F.Cu" "B.Cu")
		(net "SGPIO_OCP_V3_2_CLK")
	)
	(segment
		(start 73.841864 -12.034012)
		(end 73.841864 -11.66876)
		(width 0.10668)
		(layer "B.Cu")
		(net "SGPIO_OCP_V3_2_CLK")
	)
	(segment
		(start 74.670412 -12.283948)
		(end 74.0918 -12.283948)
		(width 0.10668)
		(layer "B.Cu")
		(net "SGPIO_OCP_V3_2_CLK")
	)
	(segment
		(start 74.0918 -12.283948)
		(end 73.841864 -12.034012)
		(width 0.10668)
		(layer "B.Cu")
		(net "SGPIO_OCP_V3_2_CLK")
	)
	(segment
		(start 75.06208 -12.675616)
		(end 74.670412 -12.283948)
		(width 0.10668)
		(layer "B.Cu")
		(net "SGPIO_OCP_V3_2_CLK")
	)
	(segment
		(start 75.269598 -14.18717)
		(end 75.06208 -13.979652)
		(width 0.10668)
		(layer "B.Cu")
		(net "SGPIO_OCP_V3_2_CLK")
	)
	(segment
		(start 75.06208 -13.979652)
		(end 75.06208 -12.675616)
		(width 0.10668)
		(layer "B.Cu")
		(net "SGPIO_OCP_V3_2_CLK")
	)
	(segment
		(start 80.245966 -14.3002)
		(end 83.564222 -17.618456)
		(width 0.11684)
		(layer "In4.Cu")
		(net "SGPIO_OCP_V3_2_CLK")
	)
	(segment
		(start 100.301044 -57.452768)
		(end 100.301044 -72.765412)
		(width 0.11684)
		(layer "In4.Cu")
		(net "SGPIO_OCP_V3_2_CLK")
	)
	(segment
		(start 175.180244 -122.888756)
		(end 177.927 -120.142)
		(width 0.11684)
		(layer "In4.Cu")
		(net "SGPIO_OCP_V3_2_CLK")
	)
	(segment
		(start 171.00296 -125.095)
		(end 173.209204 -122.888756)
		(width 0.11684)
		(layer "In4.Cu")
		(net "SGPIO_OCP_V3_2_CLK")
	)
	(segment
		(start 105.620312 -80.204056)
		(end 105.620312 -83.988402)
		(width 0.11684)
		(layer "In4.Cu")
		(net "SGPIO_OCP_V3_2_CLK")
	)
	(segment
		(start 91.14536 -52.80914)
		(end 95.657416 -52.80914)
		(width 0.11684)
		(layer "In4.Cu")
		(net "SGPIO_OCP_V3_2_CLK")
	)
	(segment
		(start 75.269598 -14.18717)
		(end 75.382628 -14.3002)
		(width 0.11684)
		(layer "In4.Cu")
		(net "SGPIO_OCP_V3_2_CLK")
	)
	(segment
		(start 95.657416 -52.80914)
		(end 100.301044 -57.452768)
		(width 0.11684)
		(layer "In4.Cu")
		(net "SGPIO_OCP_V3_2_CLK")
	)
	(segment
		(start 105.620312 -83.988402)
		(end 148.291042 -126.659132)
		(width 0.11684)
		(layer "In4.Cu")
		(net "SGPIO_OCP_V3_2_CLK")
	)
	(segment
		(start 103.616506 -76.080874)
		(end 103.616506 -78.20025)
		(width 0.11684)
		(layer "In4.Cu")
		(net "SGPIO_OCP_V3_2_CLK")
	)
	(segment
		(start 87.212932 -48.876712)
		(end 91.14536 -52.80914)
		(width 0.11684)
		(layer "In4.Cu")
		(net "SGPIO_OCP_V3_2_CLK")
	)
	(segment
		(start 177.927 -117.979698)
		(end 178.054 -117.852698)
		(width 0.11684)
		(layer "In4.Cu")
		(net "SGPIO_OCP_V3_2_CLK")
	)
	(segment
		(start 160.782 -125.095)
		(end 171.00296 -125.095)
		(width 0.11684)
		(layer "In4.Cu")
		(net "SGPIO_OCP_V3_2_CLK")
	)
	(segment
		(start 100.301044 -72.765412)
		(end 103.616506 -76.080874)
		(width 0.11684)
		(layer "In4.Cu")
		(net "SGPIO_OCP_V3_2_CLK")
	)
	(segment
		(start 148.291042 -126.659132)
		(end 159.217868 -126.659132)
		(width 0.11684)
		(layer "In4.Cu")
		(net "SGPIO_OCP_V3_2_CLK")
	)
	(segment
		(start 75.382628 -14.3002)
		(end 80.245966 -14.3002)
		(width 0.11684)
		(layer "In4.Cu")
		(net "SGPIO_OCP_V3_2_CLK")
	)
	(segment
		(start 83.564222 -17.618456)
		(end 83.564222 -37.949378)
		(width 0.11684)
		(layer "In4.Cu")
		(net "SGPIO_OCP_V3_2_CLK")
	)
	(segment
		(start 87.212932 -41.598088)
		(end 87.212932 -48.876712)
		(width 0.11684)
		(layer "In4.Cu")
		(net "SGPIO_OCP_V3_2_CLK")
	)
	(segment
		(start 178.054 -117.852698)
		(end 178.804824 -117.852698)
		(width 0.11684)
		(layer "In4.Cu")
		(net "SGPIO_OCP_V3_2_CLK")
	)
	(segment
		(start 159.217868 -126.659132)
		(end 160.782 -125.095)
		(width 0.11684)
		(layer "In4.Cu")
		(net "SGPIO_OCP_V3_2_CLK")
	)
	(segment
		(start 177.927 -120.142)
		(end 177.927 -117.979698)
		(width 0.11684)
		(layer "In4.Cu")
		(net "SGPIO_OCP_V3_2_CLK")
	)
	(segment
		(start 179.13223 -117.525292)
		(end 179.13223 -117.442742)
		(width 0.11684)
		(layer "In4.Cu")
		(net "SGPIO_OCP_V3_2_CLK")
	)
	(segment
		(start 83.564222 -37.949378)
		(end 87.212932 -41.598088)
		(width 0.11684)
		(layer "In4.Cu")
		(net "SGPIO_OCP_V3_2_CLK")
	)
	(segment
		(start 103.616506 -78.20025)
		(end 105.620312 -80.204056)
		(width 0.11684)
		(layer "In4.Cu")
		(net "SGPIO_OCP_V3_2_CLK")
	)
	(segment
		(start 173.209204 -122.888756)
		(end 175.180244 -122.888756)
		(width 0.11684)
		(layer "In4.Cu")
		(net "SGPIO_OCP_V3_2_CLK")
	)
	(segment
		(start 178.804824 -117.852698)
		(end 179.13223 -117.525292)
		(width 0.11684)
		(layer "In4.Cu")
		(net "SGPIO_OCP_V3_2_CLK")
	)
	(segment
		(start 451.29196 -13.16736)
		(end 451.29196 -12.428728)
		(width 0.10668)
		(layer "F.Cu")
		(net "SGPIO_OCP_SFF_LD_N")
	)
	(segment
		(start 451.29196 -12.428728)
		(end 451.36181 -12.358878)
		(width 0.10668)
		(layer "F.Cu")
		(net "SGPIO_OCP_SFF_LD_N")
	)
	(segment
		(start 451.36181 -12.358878)
		(end 451.36181 -11.26998)
		(width 0.10668)
		(layer "F.Cu")
		(net "SGPIO_OCP_SFF_LD_N")
	)
	(segment
		(start 179.52212 -112.25276)
		(end 179.13223 -111.86287)
		(width 0.10668)
		(layer "F.Cu")
		(net "SGPIO_OCP_SFF_LD_N")
	)
	(segment
		(start 452.1962 -13.8176)
		(end 451.9422 -13.8176)
		(width 0.10668)
		(layer "F.Cu")
		(net "SGPIO_OCP_SFF_LD_N")
	)
	(segment
		(start 451.9422 -13.8176)
		(end 451.29196 -13.16736)
		(width 0.10668)
		(layer "F.Cu")
		(net "SGPIO_OCP_SFF_LD_N")
	)
	(via
		(at 452.1962 -13.8176)
		(size 0.508)
		(drill 0.254)
		(layers "F.Cu" "B.Cu")
		(net "SGPIO_OCP_SFF_LD_N")
	)
	(via
		(at 179.13223 -111.86287)
		(size 0.4572)
		(drill 0.254)
		(layers "F.Cu" "B.Cu")
		(net "SGPIO_OCP_SFF_LD_N")
	)
	(via
		(at 169.164 -109.180376)
		(size 0.508)
		(drill 0.254)
		(layers "F.Cu" "B.Cu")
		(net "SGPIO_OCP_SFF_LD_N")
	)
	(segment
		(start 452.62546 -11.13917)
		(end 452.62546 -11.00582)
		(width 0.10668)
		(layer "B.Cu")
		(net "SGPIO_OCP_SFF_LD_N")
	)
	(segment
		(start 451.26656 -12.49807)
		(end 452.62546 -11.13917)
		(width 0.10668)
		(layer "B.Cu")
		(net "SGPIO_OCP_SFF_LD_N")
	)
	(segment
		(start 452.1962 -13.8176)
		(end 451.9422 -13.8176)
		(width 0.10668)
		(layer "B.Cu")
		(net "SGPIO_OCP_SFF_LD_N")
	)
	(segment
		(start 451.9422 -13.8176)
		(end 451.26656 -13.14196)
		(width 0.10668)
		(layer "B.Cu")
		(net "SGPIO_OCP_SFF_LD_N")
	)
	(segment
		(start 451.26656 -13.14196)
		(end 451.26656 -12.49807)
		(width 0.10668)
		(layer "B.Cu")
		(net "SGPIO_OCP_SFF_LD_N")
	)
	(segment
		(start 177.594768 -111.710216)
		(end 177.408586 -111.710216)
		(width 0.11684)
		(layer "In2.Cu")
		(net "SGPIO_OCP_SFF_LD_N")
	)
	(segment
		(start 175.313594 -108.965492)
		(end 170.907964 -108.965492)
		(width 0.11684)
		(layer "In2.Cu")
		(net "SGPIO_OCP_SFF_LD_N")
	)
	(segment
		(start 177.841148 -111.463836)
		(end 177.594768 -111.710216)
		(width 0.11684)
		(layer "In2.Cu")
		(net "SGPIO_OCP_SFF_LD_N")
	)
	(segment
		(start 177.408586 -111.710216)
		(end 177.126392 -111.428022)
		(width 0.11684)
		(layer "In2.Cu")
		(net "SGPIO_OCP_SFF_LD_N")
	)
	(segment
		(start 170.907964 -108.965492)
		(end 170.6372 -108.694728)
		(width 0.11684)
		(layer "In2.Cu")
		(net "SGPIO_OCP_SFF_LD_N")
	)
	(segment
		(start 177.126392 -110.77829)
		(end 175.313594 -108.965492)
		(width 0.11684)
		(layer "In2.Cu")
		(net "SGPIO_OCP_SFF_LD_N")
	)
	(segment
		(start 177.126392 -111.428022)
		(end 177.126392 -110.77829)
		(width 0.11684)
		(layer "In2.Cu")
		(net "SGPIO_OCP_SFF_LD_N")
	)
	(segment
		(start 170.6372 -108.694728)
		(end 169.649648 -108.694728)
		(width 0.11684)
		(layer "In2.Cu")
		(net "SGPIO_OCP_SFF_LD_N")
	)
	(segment
		(start 179.13223 -111.86287)
		(end 178.733196 -111.463836)
		(width 0.11684)
		(layer "In2.Cu")
		(net "SGPIO_OCP_SFF_LD_N")
	)
	(segment
		(start 178.733196 -111.463836)
		(end 177.841148 -111.463836)
		(width 0.11684)
		(layer "In2.Cu")
		(net "SGPIO_OCP_SFF_LD_N")
	)
	(segment
		(start 169.649648 -108.694728)
		(end 169.164 -109.180376)
		(width 0.11684)
		(layer "In2.Cu")
		(net "SGPIO_OCP_SFF_LD_N")
	)
	(segment
		(start 174.449994 -88.37803)
		(end 172.228764 -90.59926)
		(width 0.11684)
		(layer "In6.Cu")
		(net "SGPIO_OCP_SFF_LD_N")
	)
	(segment
		(start 194.031616 -82.74431)
		(end 192.75679 -84.019136)
		(width 0.11684)
		(layer "In6.Cu")
		(net "SGPIO_OCP_SFF_LD_N")
	)
	(segment
		(start 189.707774 -84.019136)
		(end 189.392052 -84.334858)
		(width 0.11684)
		(layer "In6.Cu")
		(net "SGPIO_OCP_SFF_LD_N")
	)
	(segment
		(start 176.088802 -84.334858)
		(end 175.99152 -84.334858)
		(width 0.11684)
		(layer "In6.Cu")
		(net "SGPIO_OCP_SFF_LD_N")
	)
	(segment
		(start 309.161942 -50.039778)
		(end 308.515766 -50.685954)
		(width 0.11684)
		(layer "In6.Cu")
		(net "SGPIO_OCP_SFF_LD_N")
	)
	(segment
		(start 168.394126 -108.410502)
		(end 169.164 -109.180376)
		(width 0.11684)
		(layer "In6.Cu")
		(net "SGPIO_OCP_SFF_LD_N")
	)
	(segment
		(start 174.449994 -87.209884)
		(end 174.449994 -88.37803)
		(width 0.11684)
		(layer "In6.Cu")
		(net "SGPIO_OCP_SFF_LD_N")
	)
	(segment
		(start 177.137314 -84.334858)
		(end 177.13706 -84.334604)
		(width 0.11684)
		(layer "In6.Cu")
		(net "SGPIO_OCP_SFF_LD_N")
	)
	(segment
		(start 176.089056 -84.334604)
		(end 176.088802 -84.334858)
		(width 0.11684)
		(layer "In6.Cu")
		(net "SGPIO_OCP_SFF_LD_N")
	)
	(segment
		(start 172.21327 -90.59926)
		(end 171.200572 -91.611958)
		(width 0.11684)
		(layer "In6.Cu")
		(net "SGPIO_OCP_SFF_LD_N")
	)
	(segment
		(start 436.772304 -22.789896)
		(end 406.072848 -22.789896)
		(width 0.11684)
		(layer "In6.Cu")
		(net "SGPIO_OCP_SFF_LD_N")
	)
	(segment
		(start 440.38266 -22.67966)
		(end 436.88254 -22.67966)
		(width 0.11684)
		(layer "In6.Cu")
		(net "SGPIO_OCP_SFF_LD_N")
	)
	(segment
		(start 164.111178 -106.073956)
		(end 165.871144 -107.833922)
		(width 0.11684)
		(layer "In6.Cu")
		(net "SGPIO_OCP_SFF_LD_N")
	)
	(segment
		(start 450.04609 -21.40331)
		(end 448.0687 -23.3807)
		(width 0.11684)
		(layer "In6.Cu")
		(net "SGPIO_OCP_SFF_LD_N")
	)
	(segment
		(start 453.136 -15.0114)
		(end 453.136 -18.8976)
		(width 0.11684)
		(layer "In6.Cu")
		(net "SGPIO_OCP_SFF_LD_N")
	)
	(segment
		(start 446.545716 -23.001732)
		(end 440.704732 -23.001732)
		(width 0.11684)
		(layer "In6.Cu")
		(net "SGPIO_OCP_SFF_LD_N")
	)
	(segment
		(start 177.13706 -84.334604)
		(end 176.089056 -84.334604)
		(width 0.11684)
		(layer "In6.Cu")
		(net "SGPIO_OCP_SFF_LD_N")
	)
	(segment
		(start 269.864332 -67.709288)
		(end 258.87045 -78.70317)
		(width 0.11684)
		(layer "In6.Cu")
		(net "SGPIO_OCP_SFF_LD_N")
	)
	(segment
		(start 452.1962 -13.8176)
		(end 452.1962 -14.0716)
		(width 0.11684)
		(layer "In6.Cu")
		(net "SGPIO_OCP_SFF_LD_N")
	)
	(segment
		(start 165.871144 -107.833922)
		(end 166.734998 -108.410502)
		(width 0.11684)
		(layer "In6.Cu")
		(net "SGPIO_OCP_SFF_LD_N")
	)
	(segment
		(start 304.976784 -49.781206)
		(end 290.597082 -49.781206)
		(width 0.11684)
		(layer "In6.Cu")
		(net "SGPIO_OCP_SFF_LD_N")
	)
	(segment
		(start 406.072848 -22.789896)
		(end 378.822966 -50.039778)
		(width 0.11684)
		(layer "In6.Cu")
		(net "SGPIO_OCP_SFF_LD_N")
	)
	(segment
		(start 450.63029 -21.40331)
		(end 450.04609 -21.40331)
		(width 0.11684)
		(layer "In6.Cu")
		(net "SGPIO_OCP_SFF_LD_N")
	)
	(segment
		(start 174.551594 -85.774784)
		(end 174.551594 -87.108284)
		(width 0.11684)
		(layer "In6.Cu")
		(net "SGPIO_OCP_SFF_LD_N")
	)
	(segment
		(start 446.924684 -23.3807)
		(end 446.545716 -23.001732)
		(width 0.11684)
		(layer "In6.Cu")
		(net "SGPIO_OCP_SFF_LD_N")
	)
	(segment
		(start 448.0687 -23.3807)
		(end 446.924684 -23.3807)
		(width 0.11684)
		(layer "In6.Cu")
		(net "SGPIO_OCP_SFF_LD_N")
	)
	(segment
		(start 233.928412 -75.74788)
		(end 226.931982 -82.74431)
		(width 0.11684)
		(layer "In6.Cu")
		(net "SGPIO_OCP_SFF_LD_N")
	)
	(segment
		(start 258.87045 -78.70317)
		(end 246.216678 -78.70317)
		(width 0.11684)
		(layer "In6.Cu")
		(net "SGPIO_OCP_SFF_LD_N")
	)
	(segment
		(start 308.515766 -50.685954)
		(end 305.881532 -50.685954)
		(width 0.11684)
		(layer "In6.Cu")
		(net "SGPIO_OCP_SFF_LD_N")
	)
	(segment
		(start 290.597082 -49.781206)
		(end 272.669 -67.709288)
		(width 0.11684)
		(layer "In6.Cu")
		(net "SGPIO_OCP_SFF_LD_N")
	)
	(segment
		(start 189.392052 -84.334858)
		(end 177.137314 -84.334858)
		(width 0.11684)
		(layer "In6.Cu")
		(net "SGPIO_OCP_SFF_LD_N")
	)
	(segment
		(start 440.704732 -23.001732)
		(end 440.38266 -22.67966)
		(width 0.11684)
		(layer "In6.Cu")
		(net "SGPIO_OCP_SFF_LD_N")
	)
	(segment
		(start 170.968924 -91.8591)
		(end 170.335956 -91.8591)
		(width 0.11684)
		(layer "In6.Cu")
		(net "SGPIO_OCP_SFF_LD_N")
	)
	(segment
		(start 164.7698 -96.69018)
		(end 164.111178 -97.348802)
		(width 0.11684)
		(layer "In6.Cu")
		(net "SGPIO_OCP_SFF_LD_N")
	)
	(segment
		(start 165.504876 -96.69018)
		(end 164.7698 -96.69018)
		(width 0.11684)
		(layer "In6.Cu")
		(net "SGPIO_OCP_SFF_LD_N")
	)
	(segment
		(start 226.931982 -82.74431)
		(end 194.031616 -82.74431)
		(width 0.11684)
		(layer "In6.Cu")
		(net "SGPIO_OCP_SFF_LD_N")
	)
	(segment
		(start 171.200572 -91.627452)
		(end 170.968924 -91.8591)
		(width 0.11684)
		(layer "In6.Cu")
		(net "SGPIO_OCP_SFF_LD_N")
	)
	(segment
		(start 378.822966 -50.039778)
		(end 309.161942 -50.039778)
		(width 0.11684)
		(layer "In6.Cu")
		(net "SGPIO_OCP_SFF_LD_N")
	)
	(segment
		(start 171.200572 -91.611958)
		(end 171.200572 -91.627452)
		(width 0.11684)
		(layer "In6.Cu")
		(net "SGPIO_OCP_SFF_LD_N")
	)
	(segment
		(start 192.75679 -84.019136)
		(end 189.707774 -84.019136)
		(width 0.11684)
		(layer "In6.Cu")
		(net "SGPIO_OCP_SFF_LD_N")
	)
	(segment
		(start 174.551594 -87.108284)
		(end 174.449994 -87.209884)
		(width 0.11684)
		(layer "In6.Cu")
		(net "SGPIO_OCP_SFF_LD_N")
	)
	(segment
		(start 436.88254 -22.67966)
		(end 436.772304 -22.789896)
		(width 0.11684)
		(layer "In6.Cu")
		(net "SGPIO_OCP_SFF_LD_N")
	)
	(segment
		(start 246.216678 -78.70317)
		(end 243.261388 -75.74788)
		(width 0.11684)
		(layer "In6.Cu")
		(net "SGPIO_OCP_SFF_LD_N")
	)
	(segment
		(start 172.228764 -90.59926)
		(end 172.21327 -90.59926)
		(width 0.11684)
		(layer "In6.Cu")
		(net "SGPIO_OCP_SFF_LD_N")
	)
	(segment
		(start 166.734998 -108.410502)
		(end 168.394126 -108.410502)
		(width 0.11684)
		(layer "In6.Cu")
		(net "SGPIO_OCP_SFF_LD_N")
	)
	(segment
		(start 452.1962 -14.0716)
		(end 453.136 -15.0114)
		(width 0.11684)
		(layer "In6.Cu")
		(net "SGPIO_OCP_SFF_LD_N")
	)
	(segment
		(start 243.261388 -75.74788)
		(end 233.928412 -75.74788)
		(width 0.11684)
		(layer "In6.Cu")
		(net "SGPIO_OCP_SFF_LD_N")
	)
	(segment
		(start 170.335956 -91.8591)
		(end 165.504876 -96.69018)
		(width 0.11684)
		(layer "In6.Cu")
		(net "SGPIO_OCP_SFF_LD_N")
	)
	(segment
		(start 164.111178 -97.348802)
		(end 164.111178 -106.073956)
		(width 0.11684)
		(layer "In6.Cu")
		(net "SGPIO_OCP_SFF_LD_N")
	)
	(segment
		(start 175.99152 -84.334858)
		(end 174.551594 -85.774784)
		(width 0.11684)
		(layer "In6.Cu")
		(net "SGPIO_OCP_SFF_LD_N")
	)
	(segment
		(start 453.136 -18.8976)
		(end 450.63029 -21.40331)
		(width 0.11684)
		(layer "In6.Cu")
		(net "SGPIO_OCP_SFF_LD_N")
	)
	(segment
		(start 305.881532 -50.685954)
		(end 304.976784 -49.781206)
		(width 0.11684)
		(layer "In6.Cu")
		(net "SGPIO_OCP_SFF_LD_N")
	)
	(segment
		(start 272.669 -67.709288)
		(end 269.864332 -67.709288)
		(width 0.11684)
		(layer "In6.Cu")
		(net "SGPIO_OCP_SFF_LD_N")
	)
	(segment
		(start 167.550338 -111.720376)
		(end 167.035988 -111.206026)
		(width 0.10668)
		(layer "F.Cu")
		(net "SGPIO_OCP_SFF_DATAOUT")
	)
	(segment
		(start 172.594524 -112.63884)
		(end 171.67606 -111.720376)
		(width 0.10668)
		(layer "F.Cu")
		(net "SGPIO_OCP_SFF_DATAOUT")
	)
	(segment
		(start 177.122074 -112.25276)
		(end 176.5427 -112.25276)
		(width 0.10668)
		(layer "F.Cu")
		(net "SGPIO_OCP_SFF_DATAOUT")
	)
	(segment
		(start 449.3768 -13.7922)
		(end 450.02196 -13.14704)
		(width 0.10668)
		(layer "F.Cu")
		(net "SGPIO_OCP_SFF_DATAOUT")
	)
	(segment
		(start 450.02196 -13.14704)
		(end 450.02196 -12.005056)
		(width 0.10668)
		(layer "F.Cu")
		(net "SGPIO_OCP_SFF_DATAOUT")
	)
	(segment
		(start 450.02196 -12.005056)
		(end 450.161914 -11.865102)
		(width 0.10668)
		(layer "F.Cu")
		(net "SGPIO_OCP_SFF_DATAOUT")
	)
	(segment
		(start 176.5427 -112.25276)
		(end 176.15662 -112.63884)
		(width 0.10668)
		(layer "F.Cu")
		(net "SGPIO_OCP_SFF_DATAOUT")
	)
	(segment
		(start 176.15662 -112.63884)
		(end 172.594524 -112.63884)
		(width 0.10668)
		(layer "F.Cu")
		(net "SGPIO_OCP_SFF_DATAOUT")
	)
	(segment
		(start 171.67606 -111.720376)
		(end 167.550338 -111.720376)
		(width 0.10668)
		(layer "F.Cu")
		(net "SGPIO_OCP_SFF_DATAOUT")
	)
	(segment
		(start 450.161914 -11.865102)
		(end 450.161914 -11.26998)
		(width 0.10668)
		(layer "F.Cu")
		(net "SGPIO_OCP_SFF_DATAOUT")
	)
	(via
		(at 167.035988 -111.206026)
		(size 0.508)
		(drill 0.254)
		(layers "F.Cu" "B.Cu")
		(net "SGPIO_OCP_SFF_DATAOUT")
	)
	(via
		(at 449.3768 -13.7922)
		(size 0.508)
		(drill 0.254)
		(layers "F.Cu" "B.Cu")
		(net "SGPIO_OCP_SFF_DATAOUT")
	)
	(segment
		(start 449.984368 -12.014962)
		(end 450.482716 -11.516614)
		(width 0.10668)
		(layer "B.Cu")
		(net "SGPIO_OCP_SFF_DATAOUT")
	)
	(segment
		(start 450.482716 -11.516614)
		(end 450.482716 -10.994136)
		(width 0.10668)
		(layer "B.Cu")
		(net "SGPIO_OCP_SFF_DATAOUT")
	)
	(segment
		(start 449.3768 -13.7922)
		(end 449.984368 -13.184632)
		(width 0.10668)
		(layer "B.Cu")
		(net "SGPIO_OCP_SFF_DATAOUT")
	)
	(segment
		(start 449.984368 -13.184632)
		(end 449.984368 -12.014962)
		(width 0.10668)
		(layer "B.Cu")
		(net "SGPIO_OCP_SFF_DATAOUT")
	)
	(segment
		(start 271.95272 -66.444368)
		(end 269.339568 -66.444368)
		(width 0.11684)
		(layer "In6.Cu")
		(net "SGPIO_OCP_SFF_DATAOUT")
	)
	(segment
		(start 259.4737 -73.47712)
		(end 259.28828 -73.2917)
		(width 0.11684)
		(layer "In6.Cu")
		(net "SGPIO_OCP_SFF_DATAOUT")
	)
	(segment
		(start 162.811968 -106.56443)
		(end 164.239448 -107.99191)
		(width 0.11684)
		(layer "In6.Cu")
		(net "SGPIO_OCP_SFF_DATAOUT")
	)
	(segment
		(start 193.47307 -81.3435)
		(end 192.17386 -82.64271)
		(width 0.11684)
		(layer "In6.Cu")
		(net "SGPIO_OCP_SFF_DATAOUT")
	)
	(segment
		(start 261.302246 -73.47712)
		(end 259.4737 -73.47712)
		(width 0.11684)
		(layer "In6.Cu")
		(net "SGPIO_OCP_SFF_DATAOUT")
	)
	(segment
		(start 257.42773 -74.34707)
		(end 233.539538 -74.34707)
		(width 0.11684)
		(layer "In6.Cu")
		(net "SGPIO_OCP_SFF_DATAOUT")
	)
	(segment
		(start 449.3768 -13.7922)
		(end 449.07962 -14.08938)
		(width 0.11684)
		(layer "In6.Cu")
		(net "SGPIO_OCP_SFF_DATAOUT")
	)
	(segment
		(start 262.317992 -72.461374)
		(end 261.302246 -73.47712)
		(width 0.11684)
		(layer "In6.Cu")
		(net "SGPIO_OCP_SFF_DATAOUT")
	)
	(segment
		(start 259.28828 -73.2917)
		(end 258.4831 -73.2917)
		(width 0.11684)
		(layer "In6.Cu")
		(net "SGPIO_OCP_SFF_DATAOUT")
	)
	(segment
		(start 228.174804 -79.711804)
		(end 221.214696 -79.711804)
		(width 0.11684)
		(layer "In6.Cu")
		(net "SGPIO_OCP_SFF_DATAOUT")
	)
	(segment
		(start 164.239448 -107.99191)
		(end 164.239448 -109.57052)
		(width 0.11684)
		(layer "In6.Cu")
		(net "SGPIO_OCP_SFF_DATAOUT")
	)
	(segment
		(start 189.222888 -82.64271)
		(end 188.79566 -83.069938)
		(width 0.11684)
		(layer "In6.Cu")
		(net "SGPIO_OCP_SFF_DATAOUT")
	)
	(segment
		(start 449.07962 -15.140432)
		(end 447.727324 -16.492728)
		(width 0.11684)
		(layer "In6.Cu")
		(net "SGPIO_OCP_SFF_DATAOUT")
	)
	(segment
		(start 447.727324 -16.492728)
		(end 445.011556 -16.492728)
		(width 0.11684)
		(layer "In6.Cu")
		(net "SGPIO_OCP_SFF_DATAOUT")
	)
	(segment
		(start 444.511684 -16.9926)
		(end 440.649614 -16.9926)
		(width 0.11684)
		(layer "In6.Cu")
		(net "SGPIO_OCP_SFF_DATAOUT")
	)
	(segment
		(start 192.17386 -82.64271)
		(end 189.222888 -82.64271)
		(width 0.11684)
		(layer "In6.Cu")
		(net "SGPIO_OCP_SFF_DATAOUT")
	)
	(segment
		(start 263.322562 -72.461374)
		(end 262.317992 -72.461374)
		(width 0.11684)
		(layer "In6.Cu")
		(net "SGPIO_OCP_SFF_DATAOUT")
	)
	(segment
		(start 161.769552 -101.040184)
		(end 162.811968 -102.0826)
		(width 0.11684)
		(layer "In6.Cu")
		(net "SGPIO_OCP_SFF_DATAOUT")
	)
	(segment
		(start 221.214696 -79.711804)
		(end 219.583 -81.3435)
		(width 0.11684)
		(layer "In6.Cu")
		(net "SGPIO_OCP_SFF_DATAOUT")
	)
	(segment
		(start 219.583 -81.3435)
		(end 193.47307 -81.3435)
		(width 0.11684)
		(layer "In6.Cu")
		(net "SGPIO_OCP_SFF_DATAOUT")
	)
	(segment
		(start 173.286674 -86.584028)
		(end 173.185074 -86.685628)
		(width 0.11684)
		(layer "In6.Cu")
		(net "SGPIO_OCP_SFF_DATAOUT")
	)
	(segment
		(start 173.185074 -87.853266)
		(end 172.1231 -88.91524)
		(width 0.11684)
		(layer "In6.Cu")
		(net "SGPIO_OCP_SFF_DATAOUT")
	)
	(segment
		(start 175.5648 -83.069684)
		(end 175.564546 -83.069938)
		(width 0.11684)
		(layer "In6.Cu")
		(net "SGPIO_OCP_SFF_DATAOUT")
	)
	(segment
		(start 378.106686 -48.774858)
		(end 308.445662 -48.774858)
		(width 0.11684)
		(layer "In6.Cu")
		(net "SGPIO_OCP_SFF_DATAOUT")
	)
	(segment
		(start 289.96513 -48.431958)
		(end 271.95272 -66.444368)
		(width 0.11684)
		(layer "In6.Cu")
		(net "SGPIO_OCP_SFF_DATAOUT")
	)
	(segment
		(start 436.253128 -21.389086)
		(end 405.492458 -21.389086)
		(width 0.11684)
		(layer "In6.Cu")
		(net "SGPIO_OCP_SFF_DATAOUT")
	)
	(segment
		(start 188.79566 -83.069938)
		(end 177.66157 -83.069938)
		(width 0.11684)
		(layer "In6.Cu")
		(net "SGPIO_OCP_SFF_DATAOUT")
	)
	(segment
		(start 269.339568 -66.444368)
		(end 263.322562 -72.461374)
		(width 0.11684)
		(layer "In6.Cu")
		(net "SGPIO_OCP_SFF_DATAOUT")
	)
	(segment
		(start 161.769552 -100.558092)
		(end 161.769552 -101.040184)
		(width 0.11684)
		(layer "In6.Cu")
		(net "SGPIO_OCP_SFF_DATAOUT")
	)
	(segment
		(start 440.649614 -16.9926)
		(end 436.253128 -21.389086)
		(width 0.11684)
		(layer "In6.Cu")
		(net "SGPIO_OCP_SFF_DATAOUT")
	)
	(segment
		(start 161.29508 -97.74428)
		(end 161.29508 -100.08362)
		(width 0.11684)
		(layer "In6.Cu")
		(net "SGPIO_OCP_SFF_DATAOUT")
	)
	(segment
		(start 175.564546 -83.069938)
		(end 175.221392 -83.069938)
		(width 0.11684)
		(layer "In6.Cu")
		(net "SGPIO_OCP_SFF_DATAOUT")
	)
	(segment
		(start 307.883814 -49.336706)
		(end 306.321714 -49.336706)
		(width 0.11684)
		(layer "In6.Cu")
		(net "SGPIO_OCP_SFF_DATAOUT")
	)
	(segment
		(start 173.185074 -86.685628)
		(end 173.185074 -87.853266)
		(width 0.11684)
		(layer "In6.Cu")
		(net "SGPIO_OCP_SFF_DATAOUT")
	)
	(segment
		(start 305.416966 -48.431958)
		(end 289.96513 -48.431958)
		(width 0.11684)
		(layer "In6.Cu")
		(net "SGPIO_OCP_SFF_DATAOUT")
	)
	(segment
		(start 405.492458 -21.389086)
		(end 378.106686 -48.774858)
		(width 0.11684)
		(layer "In6.Cu")
		(net "SGPIO_OCP_SFF_DATAOUT")
	)
	(segment
		(start 449.07962 -14.08938)
		(end 449.07962 -15.140432)
		(width 0.11684)
		(layer "In6.Cu")
		(net "SGPIO_OCP_SFF_DATAOUT")
	)
	(segment
		(start 170.12412 -88.91524)
		(end 161.29508 -97.74428)
		(width 0.11684)
		(layer "In6.Cu")
		(net "SGPIO_OCP_SFF_DATAOUT")
	)
	(segment
		(start 306.321714 -49.336706)
		(end 305.416966 -48.431958)
		(width 0.11684)
		(layer "In6.Cu")
		(net "SGPIO_OCP_SFF_DATAOUT")
	)
	(segment
		(start 172.1231 -88.91524)
		(end 170.12412 -88.91524)
		(width 0.11684)
		(layer "In6.Cu")
		(net "SGPIO_OCP_SFF_DATAOUT")
	)
	(segment
		(start 162.811968 -102.0826)
		(end 162.811968 -106.56443)
		(width 0.11684)
		(layer "In6.Cu")
		(net "SGPIO_OCP_SFF_DATAOUT")
	)
	(segment
		(start 308.445662 -48.774858)
		(end 307.883814 -49.336706)
		(width 0.11684)
		(layer "In6.Cu")
		(net "SGPIO_OCP_SFF_DATAOUT")
	)
	(segment
		(start 173.286674 -85.004656)
		(end 173.286674 -86.584028)
		(width 0.11684)
		(layer "In6.Cu")
		(net "SGPIO_OCP_SFF_DATAOUT")
	)
	(segment
		(start 177.66157 -83.069938)
		(end 177.661316 -83.069684)
		(width 0.11684)
		(layer "In6.Cu")
		(net "SGPIO_OCP_SFF_DATAOUT")
	)
	(segment
		(start 161.29508 -100.08362)
		(end 161.769552 -100.558092)
		(width 0.11684)
		(layer "In6.Cu")
		(net "SGPIO_OCP_SFF_DATAOUT")
	)
	(segment
		(start 175.221392 -83.069938)
		(end 173.286674 -85.004656)
		(width 0.11684)
		(layer "In6.Cu")
		(net "SGPIO_OCP_SFF_DATAOUT")
	)
	(segment
		(start 258.4831 -73.2917)
		(end 257.42773 -74.34707)
		(width 0.11684)
		(layer "In6.Cu")
		(net "SGPIO_OCP_SFF_DATAOUT")
	)
	(segment
		(start 445.011556 -16.492728)
		(end 444.511684 -16.9926)
		(width 0.11684)
		(layer "In6.Cu")
		(net "SGPIO_OCP_SFF_DATAOUT")
	)
	(segment
		(start 164.239448 -109.57052)
		(end 165.874954 -111.206026)
		(width 0.11684)
		(layer "In6.Cu")
		(net "SGPIO_OCP_SFF_DATAOUT")
	)
	(segment
		(start 165.874954 -111.206026)
		(end 167.035988 -111.206026)
		(width 0.11684)
		(layer "In6.Cu")
		(net "SGPIO_OCP_SFF_DATAOUT")
	)
	(segment
		(start 233.539538 -74.34707)
		(end 228.174804 -79.711804)
		(width 0.11684)
		(layer "In6.Cu")
		(net "SGPIO_OCP_SFF_DATAOUT")
	)
	(segment
		(start 177.661316 -83.069684)
		(end 175.5648 -83.069684)
		(width 0.11684)
		(layer "In6.Cu")
		(net "SGPIO_OCP_SFF_DATAOUT")
	)
	(segment
		(start 170.18 -111.212376)
		(end 171.740576 -111.212376)
		(width 0.10668)
		(layer "F.Cu")
		(net "SGPIO_OCP_SFF_DATAIN")
	)
	(segment
		(start 176.37379 -111.86287)
		(end 177.532284 -111.86287)
		(width 0.10668)
		(layer "F.Cu")
		(net "SGPIO_OCP_SFF_DATAIN")
	)
	(segment
		(start 450.639688 -12.446)
		(end 450.55282 -12.446)
		(width 0.10668)
		(layer "F.Cu")
		(net "SGPIO_OCP_SFF_DATAIN")
	)
	(segment
		(start 450.761862 -11.26998)
		(end 450.761862 -12.323826)
		(width 0.10668)
		(layer "F.Cu")
		(net "SGPIO_OCP_SFF_DATAIN")
	)
	(segment
		(start 450.761862 -12.323826)
		(end 450.639688 -12.446)
		(width 0.10668)
		(layer "F.Cu")
		(net "SGPIO_OCP_SFF_DATAIN")
	)
	(segment
		(start 172.81906 -112.29086)
		(end 175.9458 -112.29086)
		(width 0.10668)
		(layer "F.Cu")
		(net "SGPIO_OCP_SFF_DATAIN")
	)
	(segment
		(start 171.740576 -111.212376)
		(end 172.81906 -112.29086)
		(width 0.10668)
		(layer "F.Cu")
		(net "SGPIO_OCP_SFF_DATAIN")
	)
	(segment
		(start 177.532284 -111.86287)
		(end 177.922174 -112.25276)
		(width 0.10668)
		(layer "F.Cu")
		(net "SGPIO_OCP_SFF_DATAIN")
	)
	(segment
		(start 175.9458 -112.29086)
		(end 176.37379 -111.86287)
		(width 0.10668)
		(layer "F.Cu")
		(net "SGPIO_OCP_SFF_DATAIN")
	)
	(via
		(at 450.55282 -12.446)
		(size 0.508)
		(drill 0.254)
		(layers "F.Cu" "B.Cu")
		(net "SGPIO_OCP_SFF_DATAIN")
	)
	(via
		(at 170.18 -111.212376)
		(size 0.508)
		(drill 0.254)
		(layers "F.Cu" "B.Cu")
		(net "SGPIO_OCP_SFF_DATAIN")
	)
	(segment
		(start 451.549516 -11.598656)
		(end 450.702172 -12.446)
		(width 0.10668)
		(layer "B.Cu")
		(net "SGPIO_OCP_SFF_DATAIN")
	)
	(segment
		(start 451.549516 -11.034776)
		(end 451.549516 -11.598656)
		(width 0.10668)
		(layer "B.Cu")
		(net "SGPIO_OCP_SFF_DATAIN")
	)
	(segment
		(start 450.702172 -12.446)
		(end 450.55282 -12.446)
		(width 0.10668)
		(layer "B.Cu")
		(net "SGPIO_OCP_SFF_DATAIN")
	)
	(segment
		(start 436.622952 -22.316694)
		(end 436.807356 -22.13229)
		(width 0.11684)
		(layer "In6.Cu")
		(net "SGPIO_OCP_SFF_DATAIN")
	)
	(segment
		(start 177.311812 -83.912964)
		(end 177.312066 -83.913218)
		(width 0.11684)
		(layer "In6.Cu")
		(net "SGPIO_OCP_SFF_DATAIN")
	)
	(segment
		(start 163.689538 -106.248708)
		(end 163.689538 -97.173796)
		(width 0.11684)
		(layer "In6.Cu")
		(net "SGPIO_OCP_SFF_DATAIN")
	)
	(segment
		(start 449.597272 -17.132554)
		(end 451.0913 -17.132554)
		(width 0.11684)
		(layer "In6.Cu")
		(net "SGPIO_OCP_SFF_DATAIN")
	)
	(segment
		(start 440.915806 -22.57806)
		(end 443.55512 -22.57806)
		(width 0.11684)
		(layer "In6.Cu")
		(net "SGPIO_OCP_SFF_DATAIN")
	)
	(segment
		(start 175.914304 -83.912964)
		(end 177.311812 -83.912964)
		(width 0.11684)
		(layer "In6.Cu")
		(net "SGPIO_OCP_SFF_DATAIN")
	)
	(segment
		(start 272.42135 -67.287648)
		(end 290.349432 -49.359566)
		(width 0.11684)
		(layer "In6.Cu")
		(net "SGPIO_OCP_SFF_DATAIN")
	)
	(segment
		(start 436.807356 -22.13229)
		(end 440.470036 -22.13229)
		(width 0.11684)
		(layer "In6.Cu")
		(net "SGPIO_OCP_SFF_DATAIN")
	)
	(segment
		(start 378.575316 -49.618138)
		(end 405.87676 -22.316694)
		(width 0.11684)
		(layer "In6.Cu")
		(net "SGPIO_OCP_SFF_DATAIN")
	)
	(segment
		(start 451.7136 -13.60678)
		(end 450.55282 -12.446)
		(width 0.11684)
		(layer "In6.Cu")
		(net "SGPIO_OCP_SFF_DATAIN")
	)
	(segment
		(start 193.835528 -82.271108)
		(end 219.952824 -82.271108)
		(width 0.11684)
		(layer "In6.Cu")
		(net "SGPIO_OCP_SFF_DATAIN")
	)
	(segment
		(start 189.187074 -83.913218)
		(end 189.599824 -83.500468)
		(width 0.11684)
		(layer "In6.Cu")
		(net "SGPIO_OCP_SFF_DATAIN")
	)
	(segment
		(start 192.606168 -83.500468)
		(end 193.835528 -82.271108)
		(width 0.11684)
		(layer "In6.Cu")
		(net "SGPIO_OCP_SFF_DATAIN")
	)
	(segment
		(start 444.68796 -21.44522)
		(end 444.68796 -20.678648)
		(width 0.11684)
		(layer "In6.Cu")
		(net "SGPIO_OCP_SFF_DATAIN")
	)
	(segment
		(start 175.91405 -83.913218)
		(end 175.914304 -83.912964)
		(width 0.11684)
		(layer "In6.Cu")
		(net "SGPIO_OCP_SFF_DATAIN")
	)
	(segment
		(start 170.877738 -91.3384)
		(end 172.038518 -90.17762)
		(width 0.11684)
		(layer "In6.Cu")
		(net "SGPIO_OCP_SFF_DATAIN")
	)
	(segment
		(start 169.418 -109.692948)
		(end 166.558214 -109.692948)
		(width 0.11684)
		(layer "In6.Cu")
		(net "SGPIO_OCP_SFF_DATAIN")
	)
	(segment
		(start 166.558214 -109.692948)
		(end 166.012114 -109.146848)
		(width 0.11684)
		(layer "In6.Cu")
		(net "SGPIO_OCP_SFF_DATAIN")
	)
	(segment
		(start 164.594794 -96.26854)
		(end 165.330124 -96.26854)
		(width 0.11684)
		(layer "In6.Cu")
		(net "SGPIO_OCP_SFF_DATAIN")
	)
	(segment
		(start 170.260264 -91.3384)
		(end 170.877738 -91.3384)
		(width 0.11684)
		(layer "In6.Cu")
		(net "SGPIO_OCP_SFF_DATAIN")
	)
	(segment
		(start 172.053758 -90.17762)
		(end 174.028354 -88.203024)
		(width 0.11684)
		(layer "In6.Cu")
		(net "SGPIO_OCP_SFF_DATAIN")
	)
	(segment
		(start 308.268116 -50.264314)
		(end 308.914292 -49.618138)
		(width 0.11684)
		(layer "In6.Cu")
		(net "SGPIO_OCP_SFF_DATAIN")
	)
	(segment
		(start 174.028354 -87.035132)
		(end 174.129954 -86.933532)
		(width 0.11684)
		(layer "In6.Cu")
		(net "SGPIO_OCP_SFF_DATAIN")
	)
	(segment
		(start 443.55512 -22.57806)
		(end 444.68796 -21.44522)
		(width 0.11684)
		(layer "In6.Cu")
		(net "SGPIO_OCP_SFF_DATAIN")
	)
	(segment
		(start 174.028354 -88.203024)
		(end 174.028354 -87.035132)
		(width 0.11684)
		(layer "In6.Cu")
		(net "SGPIO_OCP_SFF_DATAIN")
	)
	(segment
		(start 219.952824 -82.271108)
		(end 220.835982 -81.38795)
		(width 0.11684)
		(layer "In6.Cu")
		(net "SGPIO_OCP_SFF_DATAIN")
	)
	(segment
		(start 165.48989 -109.146848)
		(end 165.166294 -108.823252)
		(width 0.11684)
		(layer "In6.Cu")
		(net "SGPIO_OCP_SFF_DATAIN")
	)
	(segment
		(start 169.672 -110.704376)
		(end 169.672 -109.946948)
		(width 0.11684)
		(layer "In6.Cu")
		(net "SGPIO_OCP_SFF_DATAIN")
	)
	(segment
		(start 233.804968 -75.274678)
		(end 243.394484 -75.274678)
		(width 0.11684)
		(layer "In6.Cu")
		(net "SGPIO_OCP_SFF_DATAIN")
	)
	(segment
		(start 306.056284 -50.264314)
		(end 308.268116 -50.264314)
		(width 0.11684)
		(layer "In6.Cu")
		(net "SGPIO_OCP_SFF_DATAIN")
	)
	(segment
		(start 172.038518 -90.17762)
		(end 172.053758 -90.17762)
		(width 0.11684)
		(layer "In6.Cu")
		(net "SGPIO_OCP_SFF_DATAIN")
	)
	(segment
		(start 246.38508 -78.265274)
		(end 258.7117 -78.265274)
		(width 0.11684)
		(layer "In6.Cu")
		(net "SGPIO_OCP_SFF_DATAIN")
	)
	(segment
		(start 444.68796 -20.678648)
		(end 445.856868 -19.50974)
		(width 0.11684)
		(layer "In6.Cu")
		(net "SGPIO_OCP_SFF_DATAIN")
	)
	(segment
		(start 174.129954 -85.536024)
		(end 175.75276 -83.913218)
		(width 0.11684)
		(layer "In6.Cu")
		(net "SGPIO_OCP_SFF_DATAIN")
	)
	(segment
		(start 220.835982 -81.38795)
		(end 227.691696 -81.38795)
		(width 0.11684)
		(layer "In6.Cu")
		(net "SGPIO_OCP_SFF_DATAIN")
	)
	(segment
		(start 305.151536 -49.359566)
		(end 306.056284 -50.264314)
		(width 0.11684)
		(layer "In6.Cu")
		(net "SGPIO_OCP_SFF_DATAIN")
	)
	(segment
		(start 177.312066 -83.913218)
		(end 189.187074 -83.913218)
		(width 0.11684)
		(layer "In6.Cu")
		(net "SGPIO_OCP_SFF_DATAIN")
	)
	(segment
		(start 165.330124 -96.26854)
		(end 170.260264 -91.3384)
		(width 0.11684)
		(layer "In6.Cu")
		(net "SGPIO_OCP_SFF_DATAIN")
	)
	(segment
		(start 227.691696 -81.38795)
		(end 233.804968 -75.274678)
		(width 0.11684)
		(layer "In6.Cu")
		(net "SGPIO_OCP_SFF_DATAIN")
	)
	(segment
		(start 243.394484 -75.274678)
		(end 246.38508 -78.265274)
		(width 0.11684)
		(layer "In6.Cu")
		(net "SGPIO_OCP_SFF_DATAIN")
	)
	(segment
		(start 169.672 -109.946948)
		(end 169.418 -109.692948)
		(width 0.11684)
		(layer "In6.Cu")
		(net "SGPIO_OCP_SFF_DATAIN")
	)
	(segment
		(start 451.0913 -17.132554)
		(end 451.7136 -16.510254)
		(width 0.11684)
		(layer "In6.Cu")
		(net "SGPIO_OCP_SFF_DATAIN")
	)
	(segment
		(start 440.470036 -22.13229)
		(end 440.915806 -22.57806)
		(width 0.11684)
		(layer "In6.Cu")
		(net "SGPIO_OCP_SFF_DATAIN")
	)
	(segment
		(start 258.7117 -78.265274)
		(end 269.689326 -67.287648)
		(width 0.11684)
		(layer "In6.Cu")
		(net "SGPIO_OCP_SFF_DATAIN")
	)
	(segment
		(start 445.856868 -19.50974)
		(end 447.220086 -19.50974)
		(width 0.11684)
		(layer "In6.Cu")
		(net "SGPIO_OCP_SFF_DATAIN")
	)
	(segment
		(start 165.166294 -107.725464)
		(end 163.689538 -106.248708)
		(width 0.11684)
		(layer "In6.Cu")
		(net "SGPIO_OCP_SFF_DATAIN")
	)
	(segment
		(start 174.129954 -86.933532)
		(end 174.129954 -85.536024)
		(width 0.11684)
		(layer "In6.Cu")
		(net "SGPIO_OCP_SFF_DATAIN")
	)
	(segment
		(start 170.18 -111.212376)
		(end 169.672 -110.704376)
		(width 0.11684)
		(layer "In6.Cu")
		(net "SGPIO_OCP_SFF_DATAIN")
	)
	(segment
		(start 290.349432 -49.359566)
		(end 305.151536 -49.359566)
		(width 0.11684)
		(layer "In6.Cu")
		(net "SGPIO_OCP_SFF_DATAIN")
	)
	(segment
		(start 175.75276 -83.913218)
		(end 175.91405 -83.913218)
		(width 0.11684)
		(layer "In6.Cu")
		(net "SGPIO_OCP_SFF_DATAIN")
	)
	(segment
		(start 308.914292 -49.618138)
		(end 378.575316 -49.618138)
		(width 0.11684)
		(layer "In6.Cu")
		(net "SGPIO_OCP_SFF_DATAIN")
	)
	(segment
		(start 166.012114 -109.146848)
		(end 165.48989 -109.146848)
		(width 0.11684)
		(layer "In6.Cu")
		(net "SGPIO_OCP_SFF_DATAIN")
	)
	(segment
		(start 269.689326 -67.287648)
		(end 272.42135 -67.287648)
		(width 0.11684)
		(layer "In6.Cu")
		(net "SGPIO_OCP_SFF_DATAIN")
	)
	(segment
		(start 405.87676 -22.316694)
		(end 436.622952 -22.316694)
		(width 0.11684)
		(layer "In6.Cu")
		(net "SGPIO_OCP_SFF_DATAIN")
	)
	(segment
		(start 163.689538 -97.173796)
		(end 164.594794 -96.26854)
		(width 0.11684)
		(layer "In6.Cu")
		(net "SGPIO_OCP_SFF_DATAIN")
	)
	(segment
		(start 189.599824 -83.500468)
		(end 192.606168 -83.500468)
		(width 0.11684)
		(layer "In6.Cu")
		(net "SGPIO_OCP_SFF_DATAIN")
	)
	(segment
		(start 451.7136 -16.510254)
		(end 451.7136 -13.60678)
		(width 0.11684)
		(layer "In6.Cu")
		(net "SGPIO_OCP_SFF_DATAIN")
	)
	(segment
		(start 165.166294 -108.823252)
		(end 165.166294 -107.725464)
		(width 0.11684)
		(layer "In6.Cu")
		(net "SGPIO_OCP_SFF_DATAIN")
	)
	(segment
		(start 447.220086 -19.50974)
		(end 449.597272 -17.132554)
		(width 0.11684)
		(layer "In6.Cu")
		(net "SGPIO_OCP_SFF_DATAIN")
	)
	(segment
		(start 449.561966 -12.253722)
		(end 449.38696 -12.428728)
		(width 0.10668)
		(layer "F.Cu")
		(net "SGPIO_OCP_SFF_CLK")
	)
	(segment
		(start 178.72202 -113.05286)
		(end 178.33213 -112.66297)
		(width 0.10668)
		(layer "F.Cu")
		(net "SGPIO_OCP_SFF_CLK")
	)
	(segment
		(start 449.561966 -11.26998)
		(end 449.561966 -12.253722)
		(width 0.10668)
		(layer "F.Cu")
		(net "SGPIO_OCP_SFF_CLK")
	)
	(segment
		(start 449.38696 -12.428728)
		(end 449.38696 -12.900152)
		(width 0.10668)
		(layer "F.Cu")
		(net "SGPIO_OCP_SFF_CLK")
	)
	(via
		(at 449.38696 -12.900152)
		(size 0.508)
		(drill 0.254)
		(layers "F.Cu" "B.Cu")
		(net "SGPIO_OCP_SFF_CLK")
	)
	(via
		(at 172.76445 -113.248948)
		(size 0.6604)
		(drill 0.3302)
		(layers "F.Cu" "B.Cu")
		(net "SGPIO_OCP_SFF_CLK")
	)
	(via
		(at 168.148 -111.212376)
		(size 0.508)
		(drill 0.254)
		(layers "F.Cu" "B.Cu")
		(net "SGPIO_OCP_SFF_CLK")
	)
	(via
		(at 178.33213 -112.66297)
		(size 0.4572)
		(drill 0.254)
		(layers "F.Cu" "B.Cu")
		(net "SGPIO_OCP_SFF_CLK")
	)
	(segment
		(start 172.76445 -113.248948)
		(end 175.020478 -113.248948)
		(width 0.10668)
		(layer "B.Cu")
		(net "SGPIO_OCP_SFF_CLK")
	)
	(segment
		(start 169.851578 -112.874298)
		(end 171.780962 -112.874298)
		(width 0.10668)
		(layer "B.Cu")
		(net "SGPIO_OCP_SFF_CLK")
	)
	(segment
		(start 169.64406 -112.15878)
		(end 169.64406 -112.66678)
		(width 0.10668)
		(layer "B.Cu")
		(net "SGPIO_OCP_SFF_CLK")
	)
	(segment
		(start 169.64406 -112.66678)
		(end 169.851578 -112.874298)
		(width 0.10668)
		(layer "B.Cu")
		(net "SGPIO_OCP_SFF_CLK")
	)
	(segment
		(start 169.385488 -111.900208)
		(end 169.64406 -112.15878)
		(width 0.10668)
		(layer "B.Cu")
		(net "SGPIO_OCP_SFF_CLK")
	)
	(segment
		(start 172.155612 -113.248948)
		(end 172.76445 -113.248948)
		(width 0.10668)
		(layer "B.Cu")
		(net "SGPIO_OCP_SFF_CLK")
	)
	(segment
		(start 449.5546 -10.994136)
		(end 449.5546 -12.732512)
		(width 0.10668)
		(layer "B.Cu")
		(net "SGPIO_OCP_SFF_CLK")
	)
	(segment
		(start 171.780962 -112.874298)
		(end 172.155612 -113.248948)
		(width 0.10668)
		(layer "B.Cu")
		(net "SGPIO_OCP_SFF_CLK")
	)
	(segment
		(start 168.148 -111.33074)
		(end 168.717468 -111.900208)
		(width 0.10668)
		(layer "B.Cu")
		(net "SGPIO_OCP_SFF_CLK")
	)
	(segment
		(start 168.148 -111.212376)
		(end 168.148 -111.33074)
		(width 0.10668)
		(layer "B.Cu")
		(net "SGPIO_OCP_SFF_CLK")
	)
	(segment
		(start 175.020478 -113.248948)
		(end 175.606456 -112.66297)
		(width 0.10668)
		(layer "B.Cu")
		(net "SGPIO_OCP_SFF_CLK")
	)
	(segment
		(start 168.717468 -111.900208)
		(end 169.385488 -111.900208)
		(width 0.10668)
		(layer "B.Cu")
		(net "SGPIO_OCP_SFF_CLK")
	)
	(segment
		(start 175.606456 -112.66297)
		(end 178.33213 -112.66297)
		(width 0.10668)
		(layer "B.Cu")
		(net "SGPIO_OCP_SFF_CLK")
	)
	(segment
		(start 449.5546 -12.732512)
		(end 449.38696 -12.900152)
		(width 0.10668)
		(layer "B.Cu")
		(net "SGPIO_OCP_SFF_CLK")
	)
	(segment
		(start 219.747592 -81.816194)
		(end 220.791786 -80.772)
		(width 0.11684)
		(layer "In6.Cu")
		(net "SGPIO_OCP_SFF_CLK")
	)
	(segment
		(start 162.2044 -100.3427)
		(end 162.3695 -100.1776)
		(width 0.11684)
		(layer "In6.Cu")
		(net "SGPIO_OCP_SFF_CLK")
	)
	(segment
		(start 166.707566 -110.592616)
		(end 165.737032 -109.622082)
		(width 0.11684)
		(layer "In6.Cu")
		(net "SGPIO_OCP_SFF_CLK")
	)
	(segment
		(start 165.26129 -109.622082)
		(end 164.699188 -109.05998)
		(width 0.11684)
		(layer "In6.Cu")
		(net "SGPIO_OCP_SFF_CLK")
	)
	(segment
		(start 163.255706 -101.866446)
		(end 162.2044 -100.81514)
		(width 0.11684)
		(layer "In6.Cu")
		(net "SGPIO_OCP_SFF_CLK")
	)
	(segment
		(start 171.878752 -89.75598)
		(end 173.606714 -88.028018)
		(width 0.11684)
		(layer "In6.Cu")
		(net "SGPIO_OCP_SFF_CLK")
	)
	(segment
		(start 162.3695 -99.81946)
		(end 162.08756 -99.53752)
		(width 0.11684)
		(layer "In6.Cu")
		(net "SGPIO_OCP_SFF_CLK")
	)
	(segment
		(start 244.6782 -75.831192)
		(end 259.124196 -75.831192)
		(width 0.11684)
		(layer "In6.Cu")
		(net "SGPIO_OCP_SFF_CLK")
	)
	(segment
		(start 162.08756 -99.53752)
		(end 162.08756 -98.179128)
		(width 0.11684)
		(layer "In6.Cu")
		(net "SGPIO_OCP_SFF_CLK")
	)
	(segment
		(start 173.606714 -88.028018)
		(end 173.606714 -86.86038)
		(width 0.11684)
		(layer "In6.Cu")
		(net "SGPIO_OCP_SFF_CLK")
	)
	(segment
		(start 308.079648 -49.8094)
		(end 308.69255 -49.196498)
		(width 0.11684)
		(layer "In6.Cu")
		(net "SGPIO_OCP_SFF_CLK")
	)
	(segment
		(start 167.52824 -110.592616)
		(end 166.707566 -110.592616)
		(width 0.11684)
		(layer "In6.Cu")
		(net "SGPIO_OCP_SFF_CLK")
	)
	(segment
		(start 290.160964 -48.904652)
		(end 305.293268 -48.904652)
		(width 0.11684)
		(layer "In6.Cu")
		(net "SGPIO_OCP_SFF_CLK")
	)
	(segment
		(start 175.739298 -83.491578)
		(end 175.739552 -83.491324)
		(width 0.11684)
		(layer "In6.Cu")
		(net "SGPIO_OCP_SFF_CLK")
	)
	(segment
		(start 272.199608 -66.866008)
		(end 290.160964 -48.904652)
		(width 0.11684)
		(layer "In6.Cu")
		(net "SGPIO_OCP_SFF_CLK")
	)
	(segment
		(start 192.387474 -83.07578)
		(end 193.64706 -81.816194)
		(width 0.11684)
		(layer "In6.Cu")
		(net "SGPIO_OCP_SFF_CLK")
	)
	(segment
		(start 308.69255 -49.196498)
		(end 378.353574 -49.196498)
		(width 0.11684)
		(layer "In6.Cu")
		(net "SGPIO_OCP_SFF_CLK")
	)
	(segment
		(start 189.390528 -83.07578)
		(end 192.387474 -83.07578)
		(width 0.11684)
		(layer "In6.Cu")
		(net "SGPIO_OCP_SFF_CLK")
	)
	(segment
		(start 220.791786 -80.772)
		(end 227.711 -80.772)
		(width 0.11684)
		(layer "In6.Cu")
		(net "SGPIO_OCP_SFF_CLK")
	)
	(segment
		(start 188.97473 -83.491578)
		(end 189.390528 -83.07578)
		(width 0.11684)
		(layer "In6.Cu")
		(net "SGPIO_OCP_SFF_CLK")
	)
	(segment
		(start 378.353574 -49.196498)
		(end 405.688292 -21.86178)
		(width 0.11684)
		(layer "In6.Cu")
		(net "SGPIO_OCP_SFF_CLK")
	)
	(segment
		(start 447.995294 -16.915384)
		(end 449.5292 -15.381478)
		(width 0.11684)
		(layer "In6.Cu")
		(net "SGPIO_OCP_SFF_CLK")
	)
	(segment
		(start 259.667248 -75.28814)
		(end 261.092188 -75.28814)
		(width 0.11684)
		(layer "In6.Cu")
		(net "SGPIO_OCP_SFF_CLK")
	)
	(segment
		(start 449.9356 -13.9192)
		(end 449.9356 -13.448792)
		(width 0.11684)
		(layer "In6.Cu")
		(net "SGPIO_OCP_SFF_CLK")
	)
	(segment
		(start 261.092188 -75.28814)
		(end 269.51432 -66.866008)
		(width 0.11684)
		(layer "In6.Cu")
		(net "SGPIO_OCP_SFF_CLK")
	)
	(segment
		(start 449.5292 -15.381478)
		(end 449.5292 -14.3256)
		(width 0.11684)
		(layer "In6.Cu")
		(net "SGPIO_OCP_SFF_CLK")
	)
	(segment
		(start 259.124196 -75.831192)
		(end 259.667248 -75.28814)
		(width 0.11684)
		(layer "In6.Cu")
		(net "SGPIO_OCP_SFF_CLK")
	)
	(segment
		(start 170.085512 -90.91676)
		(end 170.702986 -90.91676)
		(width 0.11684)
		(layer "In6.Cu")
		(net "SGPIO_OCP_SFF_CLK")
	)
	(segment
		(start 165.155372 -95.8469)
		(end 170.085512 -90.91676)
		(width 0.11684)
		(layer "In6.Cu")
		(net "SGPIO_OCP_SFF_CLK")
	)
	(segment
		(start 173.708314 -86.75878)
		(end 173.708314 -85.221572)
		(width 0.11684)
		(layer "In6.Cu")
		(net "SGPIO_OCP_SFF_CLK")
	)
	(segment
		(start 162.2044 -100.81514)
		(end 162.2044 -100.3427)
		(width 0.11684)
		(layer "In6.Cu")
		(net "SGPIO_OCP_SFF_CLK")
	)
	(segment
		(start 164.699188 -109.05998)
		(end 164.699188 -107.855004)
		(width 0.11684)
		(layer "In6.Cu")
		(net "SGPIO_OCP_SFF_CLK")
	)
	(segment
		(start 436.4355 -21.86178)
		(end 436.58663 -21.71065)
		(width 0.11684)
		(layer "In6.Cu")
		(net "SGPIO_OCP_SFF_CLK")
	)
	(segment
		(start 305.293268 -48.904652)
		(end 306.198016 -49.8094)
		(width 0.11684)
		(layer "In6.Cu")
		(net "SGPIO_OCP_SFF_CLK")
	)
	(segment
		(start 164.419788 -95.8469)
		(end 165.155372 -95.8469)
		(width 0.11684)
		(layer "In6.Cu")
		(net "SGPIO_OCP_SFF_CLK")
	)
	(segment
		(start 164.699188 -107.855004)
		(end 163.255706 -106.411522)
		(width 0.11684)
		(layer "In6.Cu")
		(net "SGPIO_OCP_SFF_CLK")
	)
	(segment
		(start 175.438308 -83.491578)
		(end 175.739298 -83.491578)
		(width 0.11684)
		(layer "In6.Cu")
		(net "SGPIO_OCP_SFF_CLK")
	)
	(segment
		(start 449.9356 -13.448792)
		(end 449.38696 -12.900152)
		(width 0.11684)
		(layer "In6.Cu")
		(net "SGPIO_OCP_SFF_CLK")
	)
	(segment
		(start 446.0494 -16.915384)
		(end 447.995294 -16.915384)
		(width 0.11684)
		(layer "In6.Cu")
		(net "SGPIO_OCP_SFF_CLK")
	)
	(segment
		(start 449.5292 -14.3256)
		(end 449.9356 -13.9192)
		(width 0.11684)
		(layer "In6.Cu")
		(net "SGPIO_OCP_SFF_CLK")
	)
	(segment
		(start 173.708314 -85.221572)
		(end 175.438308 -83.491578)
		(width 0.11684)
		(layer "In6.Cu")
		(net "SGPIO_OCP_SFF_CLK")
	)
	(segment
		(start 243.666772 -74.819764)
		(end 244.6782 -75.831192)
		(width 0.11684)
		(layer "In6.Cu")
		(net "SGPIO_OCP_SFF_CLK")
	)
	(segment
		(start 306.198016 -49.8094)
		(end 308.079648 -49.8094)
		(width 0.11684)
		(layer "In6.Cu")
		(net "SGPIO_OCP_SFF_CLK")
	)
	(segment
		(start 177.486564 -83.491324)
		(end 177.486818 -83.491578)
		(width 0.11684)
		(layer "In6.Cu")
		(net "SGPIO_OCP_SFF_CLK")
	)
	(segment
		(start 441.122054 -22.1234)
		(end 442.98108 -22.1234)
		(width 0.11684)
		(layer "In6.Cu")
		(net "SGPIO_OCP_SFF_CLK")
	)
	(segment
		(start 233.663236 -74.819764)
		(end 243.666772 -74.819764)
		(width 0.11684)
		(layer "In6.Cu")
		(net "SGPIO_OCP_SFF_CLK")
	)
	(segment
		(start 163.255706 -106.411522)
		(end 163.255706 -101.866446)
		(width 0.11684)
		(layer "In6.Cu")
		(net "SGPIO_OCP_SFF_CLK")
	)
	(segment
		(start 269.51432 -66.866008)
		(end 272.199608 -66.866008)
		(width 0.11684)
		(layer "In6.Cu")
		(net "SGPIO_OCP_SFF_CLK")
	)
	(segment
		(start 443.97168 -18.993104)
		(end 446.0494 -16.915384)
		(width 0.11684)
		(layer "In6.Cu")
		(net "SGPIO_OCP_SFF_CLK")
	)
	(segment
		(start 193.64706 -81.816194)
		(end 219.747592 -81.816194)
		(width 0.11684)
		(layer "In6.Cu")
		(net "SGPIO_OCP_SFF_CLK")
	)
	(segment
		(start 162.3695 -100.1776)
		(end 162.3695 -99.81946)
		(width 0.11684)
		(layer "In6.Cu")
		(net "SGPIO_OCP_SFF_CLK")
	)
	(segment
		(start 177.486818 -83.491578)
		(end 188.97473 -83.491578)
		(width 0.11684)
		(layer "In6.Cu")
		(net "SGPIO_OCP_SFF_CLK")
	)
	(segment
		(start 175.739552 -83.491324)
		(end 177.486564 -83.491324)
		(width 0.11684)
		(layer "In6.Cu")
		(net "SGPIO_OCP_SFF_CLK")
	)
	(segment
		(start 173.606714 -86.86038)
		(end 173.708314 -86.75878)
		(width 0.11684)
		(layer "In6.Cu")
		(net "SGPIO_OCP_SFF_CLK")
	)
	(segment
		(start 442.98108 -22.1234)
		(end 443.97168 -21.1328)
		(width 0.11684)
		(layer "In6.Cu")
		(net "SGPIO_OCP_SFF_CLK")
	)
	(segment
		(start 171.863766 -89.75598)
		(end 171.878752 -89.75598)
		(width 0.11684)
		(layer "In6.Cu")
		(net "SGPIO_OCP_SFF_CLK")
	)
	(segment
		(start 165.737032 -109.622082)
		(end 165.26129 -109.622082)
		(width 0.11684)
		(layer "In6.Cu")
		(net "SGPIO_OCP_SFF_CLK")
	)
	(segment
		(start 436.58663 -21.71065)
		(end 440.709304 -21.71065)
		(width 0.11684)
		(layer "In6.Cu")
		(net "SGPIO_OCP_SFF_CLK")
	)
	(segment
		(start 443.97168 -21.1328)
		(end 443.97168 -18.993104)
		(width 0.11684)
		(layer "In6.Cu")
		(net "SGPIO_OCP_SFF_CLK")
	)
	(segment
		(start 227.711 -80.772)
		(end 233.663236 -74.819764)
		(width 0.11684)
		(layer "In6.Cu")
		(net "SGPIO_OCP_SFF_CLK")
	)
	(segment
		(start 440.709304 -21.71065)
		(end 441.122054 -22.1234)
		(width 0.11684)
		(layer "In6.Cu")
		(net "SGPIO_OCP_SFF_CLK")
	)
	(segment
		(start 170.702986 -90.91676)
		(end 171.863766 -89.75598)
		(width 0.11684)
		(layer "In6.Cu")
		(net "SGPIO_OCP_SFF_CLK")
	)
	(segment
		(start 168.148 -111.212376)
		(end 167.52824 -110.592616)
		(width 0.11684)
		(layer "In6.Cu")
		(net "SGPIO_OCP_SFF_CLK")
	)
	(segment
		(start 405.688292 -21.86178)
		(end 436.4355 -21.86178)
		(width 0.11684)
		(layer "In6.Cu")
		(net "SGPIO_OCP_SFF_CLK")
	)
	(segment
		(start 162.08756 -98.179128)
		(end 164.419788 -95.8469)
		(width 0.11684)
		(layer "In6.Cu")
		(net "SGPIO_OCP_SFF_CLK")
	)
	(segment
		(start 191.503554 -132.581396)
		(end 191.135 -132.94995)
		(width 0.10668)
		(layer "F.Cu")
		(net "SCM_USB_OC_R_N")
	)
	(segment
		(start 191.503554 -132.537454)
		(end 191.503554 -132.581396)
		(width 0.10668)
		(layer "F.Cu")
		(net "SCM_USB_OC_R_N")
	)
	(segment
		(start 191.135 -132.94995)
		(end 191.135 -133.168898)
		(width 0.10668)
		(layer "F.Cu")
		(net "SCM_USB_OC_R_N")
	)
	(segment
		(start 188.322204 -121.052844)
		(end 188.712094 -121.442734)
		(width 0.10668)
		(layer "F.Cu")
		(net "SCM_USB_OC_R_N")
	)
	(via
		(at 191.503554 -132.537454)
		(size 0.508)
		(drill 0.254)
		(layers "F.Cu" "B.Cu")
		(net "SCM_USB_OC_R_N")
	)
	(via
		(at 188.712094 -121.442734)
		(size 0.4572)
		(drill 0.254)
		(layers "F.Cu" "B.Cu")
		(net "SCM_USB_OC_R_N")
	)
	(segment
		(start 191.756792 -131.931156)
		(end 191.756792 -130.913378)
		(width 0.11684)
		(layer "In2.Cu")
		(net "SCM_USB_OC_R_N")
	)
	(segment
		(start 188.712094 -121.636028)
		(end 188.712094 -121.442734)
		(width 0.11684)
		(layer "In2.Cu")
		(net "SCM_USB_OC_R_N")
	)
	(segment
		(start 189.106048 -122.029982)
		(end 188.712094 -121.636028)
		(width 0.11684)
		(layer "In2.Cu")
		(net "SCM_USB_OC_R_N")
	)
	(segment
		(start 191.503554 -132.537454)
		(end 191.503554 -132.184394)
		(width 0.11684)
		(layer "In2.Cu")
		(net "SCM_USB_OC_R_N")
	)
	(segment
		(start 191.756792 -130.913378)
		(end 191.639698 -130.796284)
		(width 0.11684)
		(layer "In2.Cu")
		(net "SCM_USB_OC_R_N")
	)
	(segment
		(start 191.503554 -132.184394)
		(end 191.756792 -131.931156)
		(width 0.11684)
		(layer "In2.Cu")
		(net "SCM_USB_OC_R_N")
	)
	(segment
		(start 190.693548 -126.162562)
		(end 190.693548 -125.639068)
		(width 0.11684)
		(layer "In2.Cu")
		(net "SCM_USB_OC_R_N")
	)
	(segment
		(start 191.639698 -127.108712)
		(end 190.693548 -126.162562)
		(width 0.11684)
		(layer "In2.Cu")
		(net "SCM_USB_OC_R_N")
	)
	(segment
		(start 191.639698 -130.796284)
		(end 191.639698 -127.108712)
		(width 0.11684)
		(layer "In2.Cu")
		(net "SCM_USB_OC_R_N")
	)
	(segment
		(start 190.693548 -125.639068)
		(end 189.106048 -124.051568)
		(width 0.11684)
		(layer "In2.Cu")
		(net "SCM_USB_OC_R_N")
	)
	(segment
		(start 189.106048 -124.051568)
		(end 189.106048 -122.029982)
		(width 0.11684)
		(layer "In2.Cu")
		(net "SCM_USB_OC_R_N")
	)
	(segment
		(start 191.135 -133.968998)
		(end 191.135 -134.584948)
		(width 0.10668)
		(layer "F.Cu")
		(net "SCM_USB_OC_N")
	)
	(via
		(at 197.979792 -160.654492)
		(size 0.508)
		(drill 0.254)
		(layers "F.Cu" "B.Cu")
		(net "SCM_USB_OC_N")
	)
	(via
		(at 405.1046 -198.148448)
		(size 0.508)
		(drill 0.254)
		(layers "F.Cu" "B.Cu")
		(net "SCM_USB_OC_N")
	)
	(via
		(at 191.135 -134.584948)
		(size 0.508)
		(drill 0.254)
		(layers "F.Cu" "B.Cu")
		(net "SCM_USB_OC_N")
	)
	(via
		(at 215.645746 -163.82873)
		(size 0.508)
		(drill 0.254)
		(layers "F.Cu" "B.Cu")
		(net "SCM_USB_OC_N")
	)
	(via
		(at 405.22017 -201.271886)
		(size 0.6604)
		(drill 0.3302)
		(layers "F.Cu" "B.Cu")
		(net "SCM_USB_OC_N")
	)
	(segment
		(start 405.87168 -198.915528)
		(end 405.1046 -198.148448)
		(width 0.10668)
		(layer "B.Cu")
		(net "SCM_USB_OC_N")
	)
	(segment
		(start 404.65121 -201.553572)
		(end 404.65121 -201.958194)
		(width 0.10668)
		(layer "B.Cu")
		(net "SCM_USB_OC_N")
	)
	(segment
		(start 405.22017 -201.271886)
		(end 404.932896 -201.271886)
		(width 0.10668)
		(layer "B.Cu")
		(net "SCM_USB_OC_N")
	)
	(segment
		(start 404.932896 -201.271886)
		(end 404.65121 -201.553572)
		(width 0.10668)
		(layer "B.Cu")
		(net "SCM_USB_OC_N")
	)
	(segment
		(start 404.65121 -201.958194)
		(end 404.10892 -202.500484)
		(width 0.10668)
		(layer "B.Cu")
		(net "SCM_USB_OC_N")
	)
	(segment
		(start 405.87168 -201.839576)
		(end 405.87168 -198.915528)
		(width 0.10668)
		(layer "B.Cu")
		(net "SCM_USB_OC_N")
	)
	(segment
		(start 405.22017 -202.491086)
		(end 405.87168 -201.839576)
		(width 0.10668)
		(layer "B.Cu")
		(net "SCM_USB_OC_N")
	)
	(segment
		(start 405.22017 -202.491086)
		(end 405.22017 -201.271886)
		(width 0.10668)
		(layer "B.Cu")
		(net "SCM_USB_OC_N")
	)
	(segment
		(start 404.10892 -202.500484)
		(end 403.651212 -202.500484)
		(width 0.10668)
		(layer "B.Cu")
		(net "SCM_USB_OC_N")
	)
	(segment
		(start 197.979792 -160.654492)
		(end 199.743822 -162.418522)
		(width 0.11684)
		(layer "In2.Cu")
		(net "SCM_USB_OC_N")
	)
	(segment
		(start 214.235538 -162.418522)
		(end 215.645746 -163.82873)
		(width 0.11684)
		(layer "In2.Cu")
		(net "SCM_USB_OC_N")
	)
	(segment
		(start 199.743822 -162.418522)
		(end 214.235538 -162.418522)
		(width 0.11684)
		(layer "In2.Cu")
		(net "SCM_USB_OC_N")
	)
	(segment
		(start 191.135 -135.502396)
		(end 191.135 -134.584948)
		(width 0.11684)
		(layer "In4.Cu")
		(net "SCM_USB_OC_N")
	)
	(segment
		(start 191.629538 -137.445242)
		(end 191.763396 -137.311384)
		(width 0.11684)
		(layer "In4.Cu")
		(net "SCM_USB_OC_N")
	)
	(segment
		(start 197.729348 -160.904936)
		(end 189.410848 -160.904936)
		(width 0.11684)
		(layer "In4.Cu")
		(net "SCM_USB_OC_N")
	)
	(segment
		(start 191.629538 -146.352768)
		(end 191.629538 -137.445242)
		(width 0.11684)
		(layer "In4.Cu")
		(net "SCM_USB_OC_N")
	)
	(segment
		(start 191.763396 -136.130792)
		(end 191.135 -135.502396)
		(width 0.11684)
		(layer "In4.Cu")
		(net "SCM_USB_OC_N")
	)
	(segment
		(start 187.013596 -150.96871)
		(end 191.629538 -146.352768)
		(width 0.11684)
		(layer "In4.Cu")
		(net "SCM_USB_OC_N")
	)
	(segment
		(start 187.013596 -158.507684)
		(end 187.013596 -150.96871)
		(width 0.11684)
		(layer "In4.Cu")
		(net "SCM_USB_OC_N")
	)
	(segment
		(start 197.979792 -160.654492)
		(end 197.729348 -160.904936)
		(width 0.11684)
		(layer "In4.Cu")
		(net "SCM_USB_OC_N")
	)
	(segment
		(start 191.763396 -137.311384)
		(end 191.763396 -136.130792)
		(width 0.11684)
		(layer "In4.Cu")
		(net "SCM_USB_OC_N")
	)
	(segment
		(start 189.410848 -160.904936)
		(end 187.013596 -158.507684)
		(width 0.11684)
		(layer "In4.Cu")
		(net "SCM_USB_OC_N")
	)
	(segment
		(start 216.73058 -164.913564)
		(end 219.364306 -164.913564)
		(width 0.11684)
		(layer "In6.Cu")
		(net "SCM_USB_OC_N")
	)
	(segment
		(start 219.364306 -164.913564)
		(end 219.454984 -164.822886)
		(width 0.11684)
		(layer "In6.Cu")
		(net "SCM_USB_OC_N")
	)
	(segment
		(start 244.158516 -166.507414)
		(end 244.790722 -167.13962)
		(width 0.11684)
		(layer "In6.Cu")
		(net "SCM_USB_OC_N")
	)
	(segment
		(start 244.790722 -167.13962)
		(end 313.508644 -167.13962)
		(width 0.11684)
		(layer "In6.Cu")
		(net "SCM_USB_OC_N")
	)
	(segment
		(start 401.646644 -201.606404)
		(end 405.1046 -198.148448)
		(width 0.11684)
		(layer "In6.Cu")
		(net "SCM_USB_OC_N")
	)
	(segment
		(start 335.29651 -170.815)
		(end 366.087914 -201.606404)
		(width 0.11684)
		(layer "In6.Cu")
		(net "SCM_USB_OC_N")
	)
	(segment
		(start 313.508644 -167.13962)
		(end 317.184024 -170.815)
		(width 0.11684)
		(layer "In6.Cu")
		(net "SCM_USB_OC_N")
	)
	(segment
		(start 219.454984 -164.822886)
		(end 222.404178 -164.822886)
		(width 0.11684)
		(layer "In6.Cu")
		(net "SCM_USB_OC_N")
	)
	(segment
		(start 317.184024 -170.815)
		(end 335.29651 -170.815)
		(width 0.11684)
		(layer "In6.Cu")
		(net "SCM_USB_OC_N")
	)
	(segment
		(start 224.656396 -167.075104)
		(end 241.27206 -167.075104)
		(width 0.11684)
		(layer "In6.Cu")
		(net "SCM_USB_OC_N")
	)
	(segment
		(start 222.404178 -164.822886)
		(end 224.656396 -167.075104)
		(width 0.11684)
		(layer "In6.Cu")
		(net "SCM_USB_OC_N")
	)
	(segment
		(start 241.27206 -167.075104)
		(end 241.83975 -166.507414)
		(width 0.11684)
		(layer "In6.Cu")
		(net "SCM_USB_OC_N")
	)
	(segment
		(start 366.087914 -201.606404)
		(end 401.646644 -201.606404)
		(width 0.11684)
		(layer "In6.Cu")
		(net "SCM_USB_OC_N")
	)
	(segment
		(start 215.645746 -163.82873)
		(end 216.73058 -164.913564)
		(width 0.11684)
		(layer "In6.Cu")
		(net "SCM_USB_OC_N")
	)
	(segment
		(start 241.83975 -166.507414)
		(end 244.158516 -166.507414)
		(width 0.11684)
		(layer "In6.Cu")
		(net "SCM_USB_OC_N")
	)
	(via
		(at 399.334228 -201.308208)
		(size 0.6604)
		(drill 0.3302)
		(layers "F.Cu" "B.Cu")
		(net "SCM_USB_OC_BU_R_N")
	)
	(segment
		(start 399.576544 -201.550524)
		(end 401.201128 -201.550524)
		(width 0.10668)
		(layer "B.Cu")
		(net "SCM_USB_OC_BU_R_N")
	)
	(segment
		(start 399.334228 -201.308208)
		(end 399.576544 -201.550524)
		(width 0.10668)
		(layer "B.Cu")
		(net "SCM_USB_OC_BU_R_N")
	)
	(segment
		(start 398.188942 -201.308208)
		(end 399.334228 -201.308208)
		(width 0.10668)
		(layer "B.Cu")
		(net "SCM_USB_OC_BU_R_N")
	)
	(segment
		(start 373.814848 -225.044254)
		(end 373.347996 -225.310192)
		(width 0.1524)
		(layer "F.Cu")
		(net "SCM_USB_OC_BUF_N")
	)
	(via
		(at 397.396462 -203.492608)
		(size 0.6604)
		(drill 0.3302)
		(layers "F.Cu" "B.Cu")
		(net "SCM_USB_OC_BUF_N")
	)
	(via
		(at 373.814848 -225.044254)
		(size 0.4064)
		(drill 0.2032)
		(layers "F.Cu" "B.Cu")
		(net "SCM_USB_OC_BUF_N")
	)
	(segment
		(start 374.24741 -224.611692)
		(end 394.561568 -224.611692)
		(width 0.10668)
		(layer "B.Cu")
		(net "SCM_USB_OC_BUF_N")
	)
	(segment
		(start 397.388842 -203.484988)
		(end 397.388842 -202.324208)
		(width 0.10668)
		(layer "B.Cu")
		(net "SCM_USB_OC_BUF_N")
	)
	(segment
		(start 373.814848 -225.044254)
		(end 374.24741 -224.611692)
		(width 0.10668)
		(layer "B.Cu")
		(net "SCM_USB_OC_BUF_N")
	)
	(segment
		(start 394.561568 -224.611692)
		(end 397.396462 -221.776798)
		(width 0.10668)
		(layer "B.Cu")
		(net "SCM_USB_OC_BUF_N")
	)
	(segment
		(start 397.388842 -201.308208)
		(end 397.388842 -202.324208)
		(width 0.10668)
		(layer "B.Cu")
		(net "SCM_USB_OC_BUF_N")
	)
	(segment
		(start 397.396462 -221.776798)
		(end 397.396462 -203.492608)
		(width 0.10668)
		(layer "B.Cu")
		(net "SCM_USB_OC_BUF_N")
	)
	(segment
		(start 397.396462 -203.492608)
		(end 397.388842 -203.484988)
		(width 0.10668)
		(layer "B.Cu")
		(net "SCM_USB_OC_BUF_N")
	)
	(via
		(at 165.591998 -119.272304)
		(size 0.6604)
		(drill 0.3302)
		(layers "F.Cu" "B.Cu")
		(net "SCM_SYS_PWROK_R")
	)
	(segment
		(start 165.742874 -119.340376)
		(end 166.727378 -119.340376)
		(width 0.10668)
		(layer "B.Cu")
		(net "SCM_SYS_PWROK_R")
	)
	(segment
		(start 164.923724 -119.336058)
		(end 164.954204 -119.305578)
		(width 0.10668)
		(layer "B.Cu")
		(net "SCM_SYS_PWROK_R")
	)
	(segment
		(start 164.4396 -120.331738)
		(end 164.4396 -119.359426)
		(width 0.10668)
		(layer "B.Cu")
		(net "SCM_SYS_PWROK_R")
	)
	(segment
		(start 165.674802 -119.272304)
		(end 165.742874 -119.340376)
		(width 0.10668)
		(layer "B.Cu")
		(net "SCM_SYS_PWROK_R")
	)
	(segment
		(start 165.558724 -119.305578)
		(end 165.591998 -119.272304)
		(width 0.10668)
		(layer "B.Cu")
		(net "SCM_SYS_PWROK_R")
	)
	(segment
		(start 164.462968 -119.336058)
		(end 164.923724 -119.336058)
		(width 0.10668)
		(layer "B.Cu")
		(net "SCM_SYS_PWROK_R")
	)
	(segment
		(start 166.727378 -119.340376)
		(end 166.73195 -119.344948)
		(width 0.10668)
		(layer "B.Cu")
		(net "SCM_SYS_PWROK_R")
	)
	(segment
		(start 164.4396 -119.359426)
		(end 164.462968 -119.336058)
		(width 0.10668)
		(layer "B.Cu")
		(net "SCM_SYS_PWROK_R")
	)
	(segment
		(start 165.591998 -119.272304)
		(end 165.674802 -119.272304)
		(width 0.10668)
		(layer "B.Cu")
		(net "SCM_SYS_PWROK_R")
	)
	(segment
		(start 164.47262 -120.364758)
		(end 164.4396 -120.331738)
		(width 0.10668)
		(layer "B.Cu")
		(net "SCM_SYS_PWROK_R")
	)
	(segment
		(start 164.954204 -119.305578)
		(end 165.558724 -119.305578)
		(width 0.10668)
		(layer "B.Cu")
		(net "SCM_SYS_PWROK_R")
	)
	(segment
		(start 177.122074 -117.852952)
		(end 176.732184 -118.242842)
		(width 0.10668)
		(layer "F.Cu")
		(net "SCM_SYS_PWROK")
	)
	(via
		(at 176.732184 -118.242842)
		(size 0.4572)
		(drill 0.254)
		(layers "F.Cu" "B.Cu")
		(net "SCM_SYS_PWROK")
	)
	(via
		(at 173.52645 -119.344948)
		(size 0.6604)
		(drill 0.3302)
		(layers "F.Cu" "B.Cu")
		(net "SCM_SYS_PWROK")
	)
	(segment
		(start 170.820842 -119.344948)
		(end 170.345862 -119.819928)
		(width 0.10668)
		(layer "B.Cu")
		(net "SCM_SYS_PWROK")
	)
	(segment
		(start 176.34712 -117.630956)
		(end 176.732184 -118.01602)
		(width 0.10668)
		(layer "B.Cu")
		(net "SCM_SYS_PWROK")
	)
	(segment
		(start 167.861234 -119.819928)
		(end 167.53205 -119.490744)
		(width 0.10668)
		(layer "B.Cu")
		(net "SCM_SYS_PWROK")
	)
	(segment
		(start 173.52645 -119.344948)
		(end 173.782228 -119.344948)
		(width 0.10668)
		(layer "B.Cu")
		(net "SCM_SYS_PWROK")
	)
	(segment
		(start 173.782228 -119.344948)
		(end 175.49622 -117.630956)
		(width 0.10668)
		(layer "B.Cu")
		(net "SCM_SYS_PWROK")
	)
	(segment
		(start 173.52645 -119.344948)
		(end 170.820842 -119.344948)
		(width 0.10668)
		(layer "B.Cu")
		(net "SCM_SYS_PWROK")
	)
	(segment
		(start 167.53205 -119.490744)
		(end 167.53205 -119.344948)
		(width 0.10668)
		(layer "B.Cu")
		(net "SCM_SYS_PWROK")
	)
	(segment
		(start 170.345862 -119.819928)
		(end 167.861234 -119.819928)
		(width 0.10668)
		(layer "B.Cu")
		(net "SCM_SYS_PWROK")
	)
	(segment
		(start 176.732184 -118.01602)
		(end 176.732184 -118.242842)
		(width 0.10668)
		(layer "B.Cu")
		(net "SCM_SYS_PWROK")
	)
	(segment
		(start 175.49622 -117.630956)
		(end 176.34712 -117.630956)
		(width 0.10668)
		(layer "B.Cu")
		(net "SCM_SYS_PWROK")
	)
	(segment
		(start 167.893746 -115.788948)
		(end 168.651428 -115.788948)
		(width 0.10668)
		(layer "F.Cu")
		(net "SCM_SYS_PWRBTN_N")
	)
	(segment
		(start 167.53205 -115.427252)
		(end 167.893746 -115.788948)
		(width 0.10668)
		(layer "F.Cu")
		(net "SCM_SYS_PWRBTN_N")
	)
	(segment
		(start 180.32222 -115.452906)
		(end 179.93233 -115.842796)
		(width 0.10668)
		(layer "F.Cu")
		(net "SCM_SYS_PWRBTN_N")
	)
	(segment
		(start 168.651428 -115.788948)
		(end 169.164 -115.276376)
		(width 0.10668)
		(layer "F.Cu")
		(net "SCM_SYS_PWRBTN_N")
	)
	(segment
		(start 167.53205 -115.280948)
		(end 167.53205 -115.427252)
		(width 0.10668)
		(layer "F.Cu")
		(net "SCM_SYS_PWRBTN_N")
	)
	(via
		(at 169.164 -115.276376)
		(size 0.508)
		(drill 0.254)
		(layers "F.Cu" "B.Cu")
		(net "SCM_SYS_PWRBTN_N")
	)
	(via
		(at 147.92706 -118.034054)
		(size 0.508)
		(drill 0.254)
		(layers "F.Cu" "B.Cu")
		(net "SCM_SYS_PWRBTN_N")
	)
	(via
		(at 179.93233 -115.842796)
		(size 0.4572)
		(drill 0.254)
		(layers "F.Cu" "B.Cu")
		(net "SCM_SYS_PWRBTN_N")
	)
	(via
		(at 144.271238 -14.983968)
		(size 0.508)
		(drill 0.254)
		(layers "F.Cu" "B.Cu")
		(net "SCM_SYS_PWRBTN_N")
	)
	(segment
		(start 143.3068 -14.162278)
		(end 143.5227 -14.162278)
		(width 0.10668)
		(layer "B.Cu")
		(net "SCM_SYS_PWRBTN_N")
	)
	(segment
		(start 172.011594 -115.377468)
		(end 172.011594 -115.673886)
		(width 0.10668)
		(layer "B.Cu")
		(net "SCM_SYS_PWRBTN_N")
	)
	(segment
		(start 172.011594 -115.673886)
		(end 171.852844 -115.832636)
		(width 0.10668)
		(layer "B.Cu")
		(net "SCM_SYS_PWRBTN_N")
	)
	(segment
		(start 179.515262 -115.057936)
		(end 172.331126 -115.057936)
		(width 0.10668)
		(layer "B.Cu")
		(net "SCM_SYS_PWRBTN_N")
	)
	(segment
		(start 179.93233 -115.842796)
		(end 179.93233 -115.475004)
		(width 0.10668)
		(layer "B.Cu")
		(net "SCM_SYS_PWRBTN_N")
	)
	(segment
		(start 171.852844 -115.832636)
		(end 169.72026 -115.832636)
		(width 0.10668)
		(layer "B.Cu")
		(net "SCM_SYS_PWRBTN_N")
	)
	(segment
		(start 172.331126 -115.057936)
		(end 172.011594 -115.377468)
		(width 0.10668)
		(layer "B.Cu")
		(net "SCM_SYS_PWRBTN_N")
	)
	(segment
		(start 143.5227 -14.162278)
		(end 144.271238 -14.910816)
		(width 0.10668)
		(layer "B.Cu")
		(net "SCM_SYS_PWRBTN_N")
	)
	(segment
		(start 179.93233 -115.475004)
		(end 179.515262 -115.057936)
		(width 0.10668)
		(layer "B.Cu")
		(net "SCM_SYS_PWRBTN_N")
	)
	(segment
		(start 144.271238 -14.910816)
		(end 144.271238 -14.983968)
		(width 0.10668)
		(layer "B.Cu")
		(net "SCM_SYS_PWRBTN_N")
	)
	(segment
		(start 169.72026 -115.832636)
		(end 169.164 -115.276376)
		(width 0.10668)
		(layer "B.Cu")
		(net "SCM_SYS_PWRBTN_N")
	)
	(segment
		(start 169.164 -115.276376)
		(end 168.217596 -115.276376)
		(width 0.11684)
		(layer "In2.Cu")
		(net "SCM_SYS_PWRBTN_N")
	)
	(segment
		(start 165.19652 -115.677188)
		(end 164.28466 -116.589048)
		(width 0.11684)
		(layer "In2.Cu")
		(net "SCM_SYS_PWRBTN_N")
	)
	(segment
		(start 164.28466 -116.589048)
		(end 157.635448 -116.589048)
		(width 0.11684)
		(layer "In2.Cu")
		(net "SCM_SYS_PWRBTN_N")
	)
	(segment
		(start 157.635448 -116.589048)
		(end 156.28366 -115.23726)
		(width 0.11684)
		(layer "In2.Cu")
		(net "SCM_SYS_PWRBTN_N")
	)
	(segment
		(start 149.102064 -116.85905)
		(end 147.92706 -118.034054)
		(width 0.11684)
		(layer "In2.Cu")
		(net "SCM_SYS_PWRBTN_N")
	)
	(segment
		(start 156.28366 -115.23726)
		(end 149.77618 -115.23726)
		(width 0.11684)
		(layer "In2.Cu")
		(net "SCM_SYS_PWRBTN_N")
	)
	(segment
		(start 149.102064 -115.911376)
		(end 149.102064 -116.85905)
		(width 0.11684)
		(layer "In2.Cu")
		(net "SCM_SYS_PWRBTN_N")
	)
	(segment
		(start 168.217596 -115.276376)
		(end 167.816784 -115.677188)
		(width 0.11684)
		(layer "In2.Cu")
		(net "SCM_SYS_PWRBTN_N")
	)
	(segment
		(start 149.77618 -115.23726)
		(end 149.102064 -115.911376)
		(width 0.11684)
		(layer "In2.Cu")
		(net "SCM_SYS_PWRBTN_N")
	)
	(segment
		(start 167.816784 -115.677188)
		(end 165.19652 -115.677188)
		(width 0.11684)
		(layer "In2.Cu")
		(net "SCM_SYS_PWRBTN_N")
	)
	(segment
		(start 143.926814 -16.487394)
		(end 143.926814 -15.364968)
		(width 0.11684)
		(layer "In4.Cu")
		(net "SCM_SYS_PWRBTN_N")
	)
	(segment
		(start 123.75134 -45.6438)
		(end 125.211078 -45.6438)
		(width 0.11684)
		(layer "In4.Cu")
		(net "SCM_SYS_PWRBTN_N")
	)
	(segment
		(start 145.250154 -118.982998)
		(end 141.801596 -115.53444)
		(width 0.11684)
		(layer "In4.Cu")
		(net "SCM_SYS_PWRBTN_N")
	)
	(segment
		(start 137.9728 -31.241746)
		(end 137.9728 -27.345894)
		(width 0.11684)
		(layer "In4.Cu")
		(net "SCM_SYS_PWRBTN_N")
	)
	(segment
		(start 110.48365 -75.820524)
		(end 105.537 -70.873874)
		(width 0.11684)
		(layer "In4.Cu")
		(net "SCM_SYS_PWRBTN_N")
	)
	(segment
		(start 120.49506 -89.610946)
		(end 110.48365 -79.599536)
		(width 0.11684)
		(layer "In4.Cu")
		(net "SCM_SYS_PWRBTN_N")
	)
	(segment
		(start 140.03274 -110.315756)
		(end 140.03274 -107.61218)
		(width 0.11684)
		(layer "In4.Cu")
		(net "SCM_SYS_PWRBTN_N")
	)
	(segment
		(start 118.14937 -51.24577)
		(end 123.75134 -45.6438)
		(width 0.11684)
		(layer "In4.Cu")
		(net "SCM_SYS_PWRBTN_N")
	)
	(segment
		(start 131.523232 -33.510982)
		(end 135.703564 -33.510982)
		(width 0.11684)
		(layer "In4.Cu")
		(net "SCM_SYS_PWRBTN_N")
	)
	(segment
		(start 141.801596 -115.53444)
		(end 141.801596 -112.084612)
		(width 0.11684)
		(layer "In4.Cu")
		(net "SCM_SYS_PWRBTN_N")
	)
	(segment
		(start 141.801596 -112.084612)
		(end 140.03274 -110.315756)
		(width 0.11684)
		(layer "In4.Cu")
		(net "SCM_SYS_PWRBTN_N")
	)
	(segment
		(start 129.5146 -41.340278)
		(end 129.5146 -35.519614)
		(width 0.11684)
		(layer "In4.Cu")
		(net "SCM_SYS_PWRBTN_N")
	)
	(segment
		(start 140.03274 -107.61218)
		(end 137.140696 -104.720136)
		(width 0.11684)
		(layer "In4.Cu")
		(net "SCM_SYS_PWRBTN_N")
	)
	(segment
		(start 146.978116 -118.982998)
		(end 145.250154 -118.982998)
		(width 0.11684)
		(layer "In4.Cu")
		(net "SCM_SYS_PWRBTN_N")
	)
	(segment
		(start 110.48365 -79.599536)
		(end 110.48365 -75.820524)
		(width 0.11684)
		(layer "In4.Cu")
		(net "SCM_SYS_PWRBTN_N")
	)
	(segment
		(start 147.92706 -118.034054)
		(end 146.978116 -118.982998)
		(width 0.11684)
		(layer "In4.Cu")
		(net "SCM_SYS_PWRBTN_N")
	)
	(segment
		(start 129.5146 -35.519614)
		(end 131.523232 -33.510982)
		(width 0.11684)
		(layer "In4.Cu")
		(net "SCM_SYS_PWRBTN_N")
	)
	(segment
		(start 120.49506 -90.778076)
		(end 120.49506 -89.610946)
		(width 0.11684)
		(layer "In4.Cu")
		(net "SCM_SYS_PWRBTN_N")
	)
	(segment
		(start 105.537 -70.873874)
		(end 105.537 -53.198014)
		(width 0.11684)
		(layer "In4.Cu")
		(net "SCM_SYS_PWRBTN_N")
	)
	(segment
		(start 144.271238 -15.020544)
		(end 144.271238 -14.983968)
		(width 0.11684)
		(layer "In4.Cu")
		(net "SCM_SYS_PWRBTN_N")
	)
	(segment
		(start 134.43712 -104.720136)
		(end 120.49506 -90.778076)
		(width 0.11684)
		(layer "In4.Cu")
		(net "SCM_SYS_PWRBTN_N")
	)
	(segment
		(start 135.703564 -33.510982)
		(end 137.9728 -31.241746)
		(width 0.11684)
		(layer "In4.Cu")
		(net "SCM_SYS_PWRBTN_N")
	)
	(segment
		(start 107.489244 -51.24577)
		(end 118.14937 -51.24577)
		(width 0.11684)
		(layer "In4.Cu")
		(net "SCM_SYS_PWRBTN_N")
	)
	(segment
		(start 105.537 -53.198014)
		(end 107.489244 -51.24577)
		(width 0.11684)
		(layer "In4.Cu")
		(net "SCM_SYS_PWRBTN_N")
	)
	(segment
		(start 137.9728 -27.345894)
		(end 143.68018 -21.638514)
		(width 0.11684)
		(layer "In4.Cu")
		(net "SCM_SYS_PWRBTN_N")
	)
	(segment
		(start 143.68018 -16.734028)
		(end 143.926814 -16.487394)
		(width 0.11684)
		(layer "In4.Cu")
		(net "SCM_SYS_PWRBTN_N")
	)
	(segment
		(start 125.211078 -45.6438)
		(end 129.5146 -41.340278)
		(width 0.11684)
		(layer "In4.Cu")
		(net "SCM_SYS_PWRBTN_N")
	)
	(segment
		(start 137.140696 -104.720136)
		(end 134.43712 -104.720136)
		(width 0.11684)
		(layer "In4.Cu")
		(net "SCM_SYS_PWRBTN_N")
	)
	(segment
		(start 143.926814 -15.364968)
		(end 144.271238 -15.020544)
		(width 0.11684)
		(layer "In4.Cu")
		(net "SCM_SYS_PWRBTN_N")
	)
	(segment
		(start 143.68018 -21.638514)
		(end 143.68018 -16.734028)
		(width 0.11684)
		(layer "In4.Cu")
		(net "SCM_SYS_PWRBTN_N")
	)
	(segment
		(start 181.122066 -117.052852)
		(end 180.732176 -117.442742)
		(width 0.10668)
		(layer "F.Cu")
		(net "SCM_SPARE_1")
	)
	(via
		(at 180.732176 -117.442742)
		(size 0.4572)
		(drill 0.254)
		(layers "F.Cu" "B.Cu")
		(net "SCM_SPARE_1")
	)
	(via
		(at 172.630592 -118.328948)
		(size 0.6604)
		(drill 0.3302)
		(layers "F.Cu" "B.Cu")
		(net "SCM_SPARE_1")
	)
	(segment
		(start 180.32857 -117.039136)
		(end 180.732176 -117.442742)
		(width 0.10668)
		(layer "B.Cu")
		(net "SCM_SPARE_1")
	)
	(segment
		(start 171.058332 -118.841266)
		(end 171.57065 -118.328948)
		(width 0.10668)
		(layer "B.Cu")
		(net "SCM_SPARE_1")
	)
	(segment
		(start 167.53205 -118.328948)
		(end 167.53205 -118.474744)
		(width 0.10668)
		(layer "B.Cu")
		(net "SCM_SPARE_1")
	)
	(segment
		(start 174.03191 -118.328948)
		(end 175.321722 -117.039136)
		(width 0.10668)
		(layer "B.Cu")
		(net "SCM_SPARE_1")
	)
	(segment
		(start 171.59605 -118.328948)
		(end 172.630592 -118.328948)
		(width 0.10668)
		(layer "B.Cu")
		(net "SCM_SPARE_1")
	)
	(segment
		(start 175.321722 -117.039136)
		(end 180.32857 -117.039136)
		(width 0.10668)
		(layer "B.Cu")
		(net "SCM_SPARE_1")
	)
	(segment
		(start 172.630592 -118.328948)
		(end 174.03191 -118.328948)
		(width 0.10668)
		(layer "B.Cu")
		(net "SCM_SPARE_1")
	)
	(segment
		(start 171.57065 -118.328948)
		(end 171.59605 -118.328948)
		(width 0.10668)
		(layer "B.Cu")
		(net "SCM_SPARE_1")
	)
	(segment
		(start 167.898572 -118.841266)
		(end 171.058332 -118.841266)
		(width 0.10668)
		(layer "B.Cu")
		(net "SCM_SPARE_1")
	)
	(segment
		(start 167.53205 -118.474744)
		(end 167.898572 -118.841266)
		(width 0.10668)
		(layer "B.Cu")
		(net "SCM_SPARE_1")
	)
	(segment
		(start 181.922166 -117.052852)
		(end 181.532276 -117.442742)
		(width 0.10668)
		(layer "F.Cu")
		(net "SCM_SPARE_0")
	)
	(via
		(at 172.76445 -116.550948)
		(size 0.6604)
		(drill 0.3302)
		(layers "F.Cu" "B.Cu")
		(net "SCM_SPARE_0")
	)
	(via
		(at 181.532276 -117.442742)
		(size 0.4572)
		(drill 0.254)
		(layers "F.Cu" "B.Cu")
		(net "SCM_SPARE_0")
	)
	(segment
		(start 173.45914 -116.550948)
		(end 174.586392 -115.423696)
		(width 0.10668)
		(layer "B.Cu")
		(net "SCM_SPARE_0")
	)
	(segment
		(start 172.510704 -116.297202)
		(end 172.76445 -116.550948)
		(width 0.10668)
		(layer "B.Cu")
		(net "SCM_SPARE_0")
	)
	(segment
		(start 180.962554 -116.246402)
		(end 181.132988 -116.416836)
		(width 0.10668)
		(layer "B.Cu")
		(net "SCM_SPARE_0")
	)
	(segment
		(start 171.59605 -116.531644)
		(end 171.59605 -116.296948)
		(width 0.10668)
		(layer "B.Cu")
		(net "SCM_SPARE_0")
	)
	(segment
		(start 171.354496 -116.773198)
		(end 171.59605 -116.531644)
		(width 0.10668)
		(layer "B.Cu")
		(net "SCM_SPARE_0")
	)
	(segment
		(start 172.76445 -116.550948)
		(end 173.45914 -116.550948)
		(width 0.10668)
		(layer "B.Cu")
		(net "SCM_SPARE_0")
	)
	(segment
		(start 179.535328 -115.634516)
		(end 179.535328 -116.030756)
		(width 0.10668)
		(layer "B.Cu")
		(net "SCM_SPARE_0")
	)
	(segment
		(start 174.586392 -115.423696)
		(end 179.324508 -115.423696)
		(width 0.10668)
		(layer "B.Cu")
		(net "SCM_SPARE_0")
	)
	(segment
		(start 179.535328 -116.030756)
		(end 179.750974 -116.246402)
		(width 0.10668)
		(layer "B.Cu")
		(net "SCM_SPARE_0")
	)
	(segment
		(start 171.596304 -116.297202)
		(end 172.510704 -116.297202)
		(width 0.10668)
		(layer "B.Cu")
		(net "SCM_SPARE_0")
	)
	(segment
		(start 179.750974 -116.246402)
		(end 180.962554 -116.246402)
		(width 0.10668)
		(layer "B.Cu")
		(net "SCM_SPARE_0")
	)
	(segment
		(start 181.132988 -117.043454)
		(end 181.532276 -117.442742)
		(width 0.10668)
		(layer "B.Cu")
		(net "SCM_SPARE_0")
	)
	(segment
		(start 167.53205 -116.296948)
		(end 167.53205 -116.666518)
		(width 0.10668)
		(layer "B.Cu")
		(net "SCM_SPARE_0")
	)
	(segment
		(start 181.132988 -116.416836)
		(end 181.132988 -117.043454)
		(width 0.10668)
		(layer "B.Cu")
		(net "SCM_SPARE_0")
	)
	(segment
		(start 167.53205 -116.666518)
		(end 167.63873 -116.773198)
		(width 0.10668)
		(layer "B.Cu")
		(net "SCM_SPARE_0")
	)
	(segment
		(start 179.324508 -115.423696)
		(end 179.535328 -115.634516)
		(width 0.10668)
		(layer "B.Cu")
		(net "SCM_SPARE_0")
	)
	(segment
		(start 171.59605 -116.296948)
		(end 171.596304 -116.297202)
		(width 0.10668)
		(layer "B.Cu")
		(net "SCM_SPARE_0")
	)
	(segment
		(start 167.63873 -116.773198)
		(end 171.354496 -116.773198)
		(width 0.10668)
		(layer "B.Cu")
		(net "SCM_SPARE_0")
	)
	(segment
		(start 178.72202 -116.252752)
		(end 178.33213 -116.642642)
		(width 0.10668)
		(layer "F.Cu")
		(net "SCM_ROT_CPU_RST_R_N")
	)
	(via
		(at 166.125398 -24.394414)
		(size 0.508)
		(drill 0.254)
		(layers "F.Cu" "B.Cu")
		(net "SCM_ROT_CPU_RST_R_N")
	)
	(via
		(at 178.33213 -116.642642)
		(size 0.4572)
		(drill 0.254)
		(layers "F.Cu" "B.Cu")
		(net "SCM_ROT_CPU_RST_R_N")
	)
	(via
		(at 139.679426 -7.886192)
		(size 0.508)
		(drill 0.254)
		(layers "F.Cu" "B.Cu")
		(net "SCM_ROT_CPU_RST_R_N")
	)
	(segment
		(start 139.659868 -8.63854)
		(end 139.679426 -8.658098)
		(width 0.10668)
		(layer "B.Cu")
		(net "SCM_ROT_CPU_RST_R_N")
	)
	(segment
		(start 139.679426 -8.658098)
		(end 139.679426 -7.886192)
		(width 0.10668)
		(layer "B.Cu")
		(net "SCM_ROT_CPU_RST_R_N")
	)
	(segment
		(start 137.851642 -8.636254)
		(end 138.770614 -8.636254)
		(width 0.10668)
		(layer "B.Cu")
		(net "SCM_ROT_CPU_RST_R_N")
	)
	(segment
		(start 138.7729 -8.63854)
		(end 139.659868 -8.63854)
		(width 0.10668)
		(layer "B.Cu")
		(net "SCM_ROT_CPU_RST_R_N")
	)
	(segment
		(start 138.770614 -8.636254)
		(end 138.7729 -8.63854)
		(width 0.10668)
		(layer "B.Cu")
		(net "SCM_ROT_CPU_RST_R_N")
	)
	(segment
		(start 140.192252 -7.373366)
		(end 156.421074 -7.373366)
		(width 0.11684)
		(layer "In4.Cu")
		(net "SCM_ROT_CPU_RST_R_N")
	)
	(segment
		(start 164.838634 -17.739868)
		(end 164.838634 -19.903948)
		(width 0.11684)
		(layer "In4.Cu")
		(net "SCM_ROT_CPU_RST_R_N")
	)
	(segment
		(start 161.8869 -11.674602)
		(end 161.8869 -14.788134)
		(width 0.11684)
		(layer "In4.Cu")
		(net "SCM_ROT_CPU_RST_R_N")
	)
	(segment
		(start 156.421074 -7.373366)
		(end 156.62275 -7.17169)
		(width 0.11684)
		(layer "In4.Cu")
		(net "SCM_ROT_CPU_RST_R_N")
	)
	(segment
		(start 163.186364 -10.375138)
		(end 161.8869 -11.674602)
		(width 0.11684)
		(layer "In4.Cu")
		(net "SCM_ROT_CPU_RST_R_N")
	)
	(segment
		(start 162.290252 -7.17169)
		(end 163.186364 -8.067802)
		(width 0.11684)
		(layer "In4.Cu")
		(net "SCM_ROT_CPU_RST_R_N")
	)
	(segment
		(start 161.8869 -14.788134)
		(end 164.838634 -17.739868)
		(width 0.11684)
		(layer "In4.Cu")
		(net "SCM_ROT_CPU_RST_R_N")
	)
	(segment
		(start 165.354254 -20.419568)
		(end 165.354254 -21.70938)
		(width 0.11684)
		(layer "In4.Cu")
		(net "SCM_ROT_CPU_RST_R_N")
	)
	(segment
		(start 163.186364 -8.067802)
		(end 163.186364 -10.375138)
		(width 0.11684)
		(layer "In4.Cu")
		(net "SCM_ROT_CPU_RST_R_N")
	)
	(segment
		(start 139.679426 -7.886192)
		(end 140.192252 -7.373366)
		(width 0.11684)
		(layer "In4.Cu")
		(net "SCM_ROT_CPU_RST_R_N")
	)
	(segment
		(start 156.62275 -7.17169)
		(end 162.290252 -7.17169)
		(width 0.11684)
		(layer "In4.Cu")
		(net "SCM_ROT_CPU_RST_R_N")
	)
	(segment
		(start 164.838634 -23.10765)
		(end 166.125398 -24.394414)
		(width 0.11684)
		(layer "In4.Cu")
		(net "SCM_ROT_CPU_RST_R_N")
	)
	(segment
		(start 165.354254 -21.70938)
		(end 164.838634 -22.225)
		(width 0.11684)
		(layer "In4.Cu")
		(net "SCM_ROT_CPU_RST_R_N")
	)
	(segment
		(start 164.838634 -22.225)
		(end 164.838634 -23.10765)
		(width 0.11684)
		(layer "In4.Cu")
		(net "SCM_ROT_CPU_RST_R_N")
	)
	(segment
		(start 164.838634 -19.903948)
		(end 165.354254 -20.419568)
		(width 0.11684)
		(layer "In4.Cu")
		(net "SCM_ROT_CPU_RST_R_N")
	)
	(segment
		(start 174.40783 -103.597202)
		(end 173.377606 -102.566978)
		(width 0.11684)
		(layer "In11.Cu")
		(net "SCM_ROT_CPU_RST_R_N")
	)
	(segment
		(start 173.738286 -105.22839)
		(end 174.40783 -104.558846)
		(width 0.11684)
		(layer "In11.Cu")
		(net "SCM_ROT_CPU_RST_R_N")
	)
	(segment
		(start 166.48176 -39.13632)
		(end 166.48176 -24.750776)
		(width 0.11684)
		(layer "In11.Cu")
		(net "SCM_ROT_CPU_RST_R_N")
	)
	(segment
		(start 171.61256 -97.34804)
		(end 171.61256 -96.89592)
		(width 0.11684)
		(layer "In11.Cu")
		(net "SCM_ROT_CPU_RST_R_N")
	)
	(segment
		(start 178.33213 -116.642642)
		(end 177.729642 -116.642642)
		(width 0.11684)
		(layer "In11.Cu")
		(net "SCM_ROT_CPU_RST_R_N")
	)
	(segment
		(start 167.716708 -78.917292)
		(end 167.716708 -55.452264)
		(width 0.11684)
		(layer "In11.Cu")
		(net "SCM_ROT_CPU_RST_R_N")
	)
	(segment
		(start 166.48176 -24.750776)
		(end 166.125398 -24.394414)
		(width 0.11684)
		(layer "In11.Cu")
		(net "SCM_ROT_CPU_RST_R_N")
	)
	(segment
		(start 171.235116 -95.701612)
		(end 171.433236 -95.503492)
		(width 0.11684)
		(layer "In11.Cu")
		(net "SCM_ROT_CPU_RST_R_N")
	)
	(segment
		(start 171.109132 -99.702112)
		(end 171.109132 -97.851468)
		(width 0.11684)
		(layer "In11.Cu")
		(net "SCM_ROT_CPU_RST_R_N")
	)
	(segment
		(start 172.42536 -91.16441)
		(end 172.42536 -90.264996)
		(width 0.11684)
		(layer "In11.Cu")
		(net "SCM_ROT_CPU_RST_R_N")
	)
	(segment
		(start 172.623226 -101.216206)
		(end 171.109132 -99.702112)
		(width 0.11684)
		(layer "In11.Cu")
		(net "SCM_ROT_CPU_RST_R_N")
	)
	(segment
		(start 171.433236 -95.503492)
		(end 171.433236 -92.156534)
		(width 0.11684)
		(layer "In11.Cu")
		(net "SCM_ROT_CPU_RST_R_N")
	)
	(segment
		(start 171.235116 -96.518476)
		(end 171.235116 -95.701612)
		(width 0.11684)
		(layer "In11.Cu")
		(net "SCM_ROT_CPU_RST_R_N")
	)
	(segment
		(start 169.13098 -41.78554)
		(end 166.48176 -39.13632)
		(width 0.11684)
		(layer "In11.Cu")
		(net "SCM_ROT_CPU_RST_R_N")
	)
	(segment
		(start 173.816264 -88.874092)
		(end 173.816264 -85.016848)
		(width 0.11684)
		(layer "In11.Cu")
		(net "SCM_ROT_CPU_RST_R_N")
	)
	(segment
		(start 177.729642 -116.642642)
		(end 174.628302 -113.541302)
		(width 0.11684)
		(layer "In11.Cu")
		(net "SCM_ROT_CPU_RST_R_N")
	)
	(segment
		(start 171.61256 -96.89592)
		(end 171.235116 -96.518476)
		(width 0.11684)
		(layer "In11.Cu")
		(net "SCM_ROT_CPU_RST_R_N")
	)
	(segment
		(start 169.13098 -46.064424)
		(end 169.13098 -41.78554)
		(width 0.11684)
		(layer "In11.Cu")
		(net "SCM_ROT_CPU_RST_R_N")
	)
	(segment
		(start 166.23792 -53.973476)
		(end 166.23792 -48.957484)
		(width 0.11684)
		(layer "In11.Cu")
		(net "SCM_ROT_CPU_RST_R_N")
	)
	(segment
		(start 174.628302 -113.541302)
		(end 174.628302 -107.62107)
		(width 0.11684)
		(layer "In11.Cu")
		(net "SCM_ROT_CPU_RST_R_N")
	)
	(segment
		(start 173.377606 -101.721666)
		(end 172.872146 -101.216206)
		(width 0.11684)
		(layer "In11.Cu")
		(net "SCM_ROT_CPU_RST_R_N")
	)
	(segment
		(start 174.628302 -107.62107)
		(end 173.738286 -106.731054)
		(width 0.11684)
		(layer "In11.Cu")
		(net "SCM_ROT_CPU_RST_R_N")
	)
	(segment
		(start 172.42536 -90.264996)
		(end 173.816264 -88.874092)
		(width 0.11684)
		(layer "In11.Cu")
		(net "SCM_ROT_CPU_RST_R_N")
	)
	(segment
		(start 174.40783 -104.558846)
		(end 174.40783 -103.597202)
		(width 0.11684)
		(layer "In11.Cu")
		(net "SCM_ROT_CPU_RST_R_N")
	)
	(segment
		(start 173.816264 -85.016848)
		(end 167.716708 -78.917292)
		(width 0.11684)
		(layer "In11.Cu")
		(net "SCM_ROT_CPU_RST_R_N")
	)
	(segment
		(start 173.738286 -106.731054)
		(end 173.738286 -105.22839)
		(width 0.11684)
		(layer "In11.Cu")
		(net "SCM_ROT_CPU_RST_R_N")
	)
	(segment
		(start 166.23792 -48.957484)
		(end 169.13098 -46.064424)
		(width 0.11684)
		(layer "In11.Cu")
		(net "SCM_ROT_CPU_RST_R_N")
	)
	(segment
		(start 171.433236 -92.156534)
		(end 172.42536 -91.16441)
		(width 0.11684)
		(layer "In11.Cu")
		(net "SCM_ROT_CPU_RST_R_N")
	)
	(segment
		(start 172.872146 -101.216206)
		(end 172.623226 -101.216206)
		(width 0.11684)
		(layer "In11.Cu")
		(net "SCM_ROT_CPU_RST_R_N")
	)
	(segment
		(start 167.716708 -55.452264)
		(end 166.23792 -53.973476)
		(width 0.11684)
		(layer "In11.Cu")
		(net "SCM_ROT_CPU_RST_R_N")
	)
	(segment
		(start 171.109132 -97.851468)
		(end 171.61256 -97.34804)
		(width 0.11684)
		(layer "In11.Cu")
		(net "SCM_ROT_CPU_RST_R_N")
	)
	(segment
		(start 173.377606 -102.566978)
		(end 173.377606 -101.721666)
		(width 0.11684)
		(layer "In11.Cu")
		(net "SCM_ROT_CPU_RST_R_N")
	)
	(segment
		(start 170.74134 -108.676948)
		(end 169.672 -108.676948)
		(width 0.10668)
		(layer "F.Cu")
		(net "SCM_JTAG_MUX_S1")
	)
	(segment
		(start 116.314474 -55.436262)
		(end 117.330474 -55.436262)
		(width 0.10668)
		(layer "F.Cu")
		(net "SCM_JTAG_MUX_S1")
	)
	(segment
		(start 135.706358 -57.13222)
		(end 134.614158 -57.13222)
		(width 0.10668)
		(layer "F.Cu")
		(net "SCM_JTAG_MUX_S1")
	)
	(segment
		(start 318.300608 -22.97938)
		(end 318.937894 -22.97938)
		(width 0.10668)
		(layer "F.Cu")
		(net "SCM_JTAG_MUX_S1")
	)
	(segment
		(start 117.330474 -55.436262)
		(end 117.96776 -55.436262)
		(width 0.10668)
		(layer "F.Cu")
		(net "SCM_JTAG_MUX_S1")
	)
	(segment
		(start 116.314474 -55.969916)
		(end 116.314474 -55.436262)
		(width 0.10668)
		(layer "F.Cu")
		(net "SCM_JTAG_MUX_S1")
	)
	(segment
		(start 316.62497 -22.97938)
		(end 318.300608 -22.97938)
		(width 0.10668)
		(layer "F.Cu")
		(net "SCM_JTAG_MUX_S1")
	)
	(segment
		(start 170.819064 -108.599224)
		(end 170.74134 -108.676948)
		(width 0.10668)
		(layer "F.Cu")
		(net "SCM_JTAG_MUX_S1")
	)
	(segment
		(start 169.672 -108.676948)
		(end 169.164 -108.168948)
		(width 0.10668)
		(layer "F.Cu")
		(net "SCM_JTAG_MUX_S1")
	)
	(segment
		(start 115.832128 -56.452262)
		(end 116.314474 -55.969916)
		(width 0.10668)
		(layer "F.Cu")
		(net "SCM_JTAG_MUX_S1")
	)
	(segment
		(start 170.819064 -108.192062)
		(end 170.819064 -108.599224)
		(width 0.10668)
		(layer "F.Cu")
		(net "SCM_JTAG_MUX_S1")
	)
	(segment
		(start 170.79595 -108.168948)
		(end 170.819064 -108.192062)
		(width 0.10668)
		(layer "F.Cu")
		(net "SCM_JTAG_MUX_S1")
	)
	(segment
		(start 114.790474 -56.452262)
		(end 115.832128 -56.452262)
		(width 0.10668)
		(layer "F.Cu")
		(net "SCM_JTAG_MUX_S1")
	)
	(via
		(at 318.937894 -22.97938)
		(size 0.508)
		(drill 0.254)
		(layers "F.Cu" "B.Cu")
		(net "SCM_JTAG_MUX_S1")
	)
	(via
		(at 117.96776 -55.436262)
		(size 0.508)
		(drill 0.254)
		(layers "F.Cu" "B.Cu")
		(net "SCM_JTAG_MUX_S1")
	)
	(via
		(at 169.164 -108.168948)
		(size 0.508)
		(drill 0.254)
		(layers "F.Cu" "B.Cu")
		(net "SCM_JTAG_MUX_S1")
	)
	(via
		(at 135.706358 -57.13222)
		(size 0.508)
		(drill 0.254)
		(layers "F.Cu" "B.Cu")
		(net "SCM_JTAG_MUX_S1")
	)
	(via
		(at 159.73679 -32.272478)
		(size 0.508)
		(drill 0.254)
		(layers "F.Cu" "B.Cu")
		(net "SCM_JTAG_MUX_S1")
	)
	(via
		(at 162.884104 -47.639478)
		(size 0.508)
		(drill 0.254)
		(layers "F.Cu" "B.Cu")
		(net "SCM_JTAG_MUX_S1")
	)
	(segment
		(start 129.729738 -55.0672)
		(end 130.0988 -55.436262)
		(width 0.11684)
		(layer "In2.Cu")
		(net "SCM_JTAG_MUX_S1")
	)
	(segment
		(start 150.4696 -52.08524)
		(end 151.48052 -53.09616)
		(width 0.11684)
		(layer "In2.Cu")
		(net "SCM_JTAG_MUX_S1")
	)
	(segment
		(start 162.424618 -48.098964)
		(end 162.884104 -47.639478)
		(width 0.11684)
		(layer "In2.Cu")
		(net "SCM_JTAG_MUX_S1")
	)
	(segment
		(start 145.88998 -52.08524)
		(end 150.4696 -52.08524)
		(width 0.11684)
		(layer "In2.Cu")
		(net "SCM_JTAG_MUX_S1")
	)
	(segment
		(start 134.0104 -55.436262)
		(end 135.706358 -57.13222)
		(width 0.11684)
		(layer "In2.Cu")
		(net "SCM_JTAG_MUX_S1")
	)
	(segment
		(start 128.8542 -55.0672)
		(end 129.729738 -55.0672)
		(width 0.11684)
		(layer "In2.Cu")
		(net "SCM_JTAG_MUX_S1")
	)
	(segment
		(start 123.609862 -55.436262)
		(end 123.78436 -55.61076)
		(width 0.11684)
		(layer "In2.Cu")
		(net "SCM_JTAG_MUX_S1")
	)
	(segment
		(start 117.96776 -55.436262)
		(end 123.609862 -55.436262)
		(width 0.11684)
		(layer "In2.Cu")
		(net "SCM_JTAG_MUX_S1")
	)
	(segment
		(start 159.085026 -53.09616)
		(end 162.424618 -49.756568)
		(width 0.11684)
		(layer "In2.Cu")
		(net "SCM_JTAG_MUX_S1")
	)
	(segment
		(start 151.48052 -53.09616)
		(end 159.085026 -53.09616)
		(width 0.11684)
		(layer "In2.Cu")
		(net "SCM_JTAG_MUX_S1")
	)
	(segment
		(start 162.424618 -49.756568)
		(end 162.424618 -48.098964)
		(width 0.11684)
		(layer "In2.Cu")
		(net "SCM_JTAG_MUX_S1")
	)
	(segment
		(start 123.78436 -55.61076)
		(end 128.31064 -55.61076)
		(width 0.11684)
		(layer "In2.Cu")
		(net "SCM_JTAG_MUX_S1")
	)
	(segment
		(start 140.843 -57.13222)
		(end 145.88998 -52.08524)
		(width 0.11684)
		(layer "In2.Cu")
		(net "SCM_JTAG_MUX_S1")
	)
	(segment
		(start 130.0988 -55.436262)
		(end 134.0104 -55.436262)
		(width 0.11684)
		(layer "In2.Cu")
		(net "SCM_JTAG_MUX_S1")
	)
	(segment
		(start 135.706358 -57.13222)
		(end 140.843 -57.13222)
		(width 0.11684)
		(layer "In2.Cu")
		(net "SCM_JTAG_MUX_S1")
	)
	(segment
		(start 128.31064 -55.61076)
		(end 128.8542 -55.0672)
		(width 0.11684)
		(layer "In2.Cu")
		(net "SCM_JTAG_MUX_S1")
	)
	(segment
		(start 261.76478 -57.510172)
		(end 261.76478 -51.253136)
		(width 0.11684)
		(layer "In6.Cu")
		(net "SCM_JTAG_MUX_S1")
	)
	(segment
		(start 173.244256 -32.272478)
		(end 175.523144 -34.551366)
		(width 0.11684)
		(layer "In6.Cu")
		(net "SCM_JTAG_MUX_S1")
	)
	(segment
		(start 239.31626 -59.81192)
		(end 239.94364 -60.4393)
		(width 0.11684)
		(layer "In6.Cu")
		(net "SCM_JTAG_MUX_S1")
	)
	(segment
		(start 185.078624 -36.676584)
		(end 186.771788 -38.369748)
		(width 0.11684)
		(layer "In6.Cu")
		(net "SCM_JTAG_MUX_S1")
	)
	(segment
		(start 221.248224 -53.010562)
		(end 226.889564 -58.651902)
		(width 0.11684)
		(layer "In6.Cu")
		(net "SCM_JTAG_MUX_S1")
	)
	(segment
		(start 217.438732 -39.971218)
		(end 217.438732 -41.269666)
		(width 0.11684)
		(layer "In6.Cu")
		(net "SCM_JTAG_MUX_S1")
	)
	(segment
		(start 230.553768 -57.58561)
		(end 237.635034 -57.58561)
		(width 0.11684)
		(layer "In6.Cu")
		(net "SCM_JTAG_MUX_S1")
	)
	(segment
		(start 177.327052 -34.551366)
		(end 178.210718 -35.435032)
		(width 0.11684)
		(layer "In6.Cu")
		(net "SCM_JTAG_MUX_S1")
	)
	(segment
		(start 239.94364 -60.4393)
		(end 258.835652 -60.4393)
		(width 0.11684)
		(layer "In6.Cu")
		(net "SCM_JTAG_MUX_S1")
	)
	(segment
		(start 182.351426 -36.676584)
		(end 185.078624 -36.676584)
		(width 0.11684)
		(layer "In6.Cu")
		(net "SCM_JTAG_MUX_S1")
	)
	(segment
		(start 186.771788 -38.369748)
		(end 196.352668 -38.369748)
		(width 0.11684)
		(layer "In6.Cu")
		(net "SCM_JTAG_MUX_S1")
	)
	(segment
		(start 315.07176 -26.385012)
		(end 318.477392 -22.97938)
		(width 0.11684)
		(layer "In6.Cu")
		(net "SCM_JTAG_MUX_S1")
	)
	(segment
		(start 213.594188 -39.64813)
		(end 214.417402 -38.824916)
		(width 0.11684)
		(layer "In6.Cu")
		(net "SCM_JTAG_MUX_S1")
	)
	(segment
		(start 273.771106 -46.661832)
		(end 294.047926 -26.385012)
		(width 0.11684)
		(layer "In6.Cu")
		(net "SCM_JTAG_MUX_S1")
	)
	(segment
		(start 175.523144 -34.551366)
		(end 177.327052 -34.551366)
		(width 0.11684)
		(layer "In6.Cu")
		(net "SCM_JTAG_MUX_S1")
	)
	(segment
		(start 239.31626 -59.266836)
		(end 239.31626 -59.81192)
		(width 0.11684)
		(layer "In6.Cu")
		(net "SCM_JTAG_MUX_S1")
	)
	(segment
		(start 196.352668 -38.369748)
		(end 198.35114 -40.36822)
		(width 0.11684)
		(layer "In6.Cu")
		(net "SCM_JTAG_MUX_S1")
	)
	(segment
		(start 258.835652 -60.4393)
		(end 261.76478 -57.510172)
		(width 0.11684)
		(layer "In6.Cu")
		(net "SCM_JTAG_MUX_S1")
	)
	(segment
		(start 159.73679 -32.272478)
		(end 173.244256 -32.272478)
		(width 0.11684)
		(layer "In6.Cu")
		(net "SCM_JTAG_MUX_S1")
	)
	(segment
		(start 181.109874 -35.435032)
		(end 182.351426 -36.676584)
		(width 0.11684)
		(layer "In6.Cu")
		(net "SCM_JTAG_MUX_S1")
	)
	(segment
		(start 207.85074 -39.64813)
		(end 213.594188 -39.64813)
		(width 0.11684)
		(layer "In6.Cu")
		(net "SCM_JTAG_MUX_S1")
	)
	(segment
		(start 318.477392 -22.97938)
		(end 318.937894 -22.97938)
		(width 0.11684)
		(layer "In6.Cu")
		(net "SCM_JTAG_MUX_S1")
	)
	(segment
		(start 237.635034 -57.58561)
		(end 239.31626 -59.266836)
		(width 0.11684)
		(layer "In6.Cu")
		(net "SCM_JTAG_MUX_S1")
	)
	(segment
		(start 221.248224 -45.079158)
		(end 221.248224 -53.010562)
		(width 0.11684)
		(layer "In6.Cu")
		(net "SCM_JTAG_MUX_S1")
	)
	(segment
		(start 266.356084 -46.661832)
		(end 273.771106 -46.661832)
		(width 0.11684)
		(layer "In6.Cu")
		(net "SCM_JTAG_MUX_S1")
	)
	(segment
		(start 261.76478 -51.253136)
		(end 266.356084 -46.661832)
		(width 0.11684)
		(layer "In6.Cu")
		(net "SCM_JTAG_MUX_S1")
	)
	(segment
		(start 178.210718 -35.435032)
		(end 181.109874 -35.435032)
		(width 0.11684)
		(layer "In6.Cu")
		(net "SCM_JTAG_MUX_S1")
	)
	(segment
		(start 207.13065 -40.36822)
		(end 207.85074 -39.64813)
		(width 0.11684)
		(layer "In6.Cu")
		(net "SCM_JTAG_MUX_S1")
	)
	(segment
		(start 217.438732 -41.269666)
		(end 221.248224 -45.079158)
		(width 0.11684)
		(layer "In6.Cu")
		(net "SCM_JTAG_MUX_S1")
	)
	(segment
		(start 226.889564 -58.651902)
		(end 229.487476 -58.651902)
		(width 0.11684)
		(layer "In6.Cu")
		(net "SCM_JTAG_MUX_S1")
	)
	(segment
		(start 214.417402 -38.824916)
		(end 216.29243 -38.824916)
		(width 0.11684)
		(layer "In6.Cu")
		(net "SCM_JTAG_MUX_S1")
	)
	(segment
		(start 216.29243 -38.824916)
		(end 217.438732 -39.971218)
		(width 0.11684)
		(layer "In6.Cu")
		(net "SCM_JTAG_MUX_S1")
	)
	(segment
		(start 229.487476 -58.651902)
		(end 230.553768 -57.58561)
		(width 0.11684)
		(layer "In6.Cu")
		(net "SCM_JTAG_MUX_S1")
	)
	(segment
		(start 294.047926 -26.385012)
		(end 315.07176 -26.385012)
		(width 0.11684)
		(layer "In6.Cu")
		(net "SCM_JTAG_MUX_S1")
	)
	(segment
		(start 198.35114 -40.36822)
		(end 207.13065 -40.36822)
		(width 0.11684)
		(layer "In6.Cu")
		(net "SCM_JTAG_MUX_S1")
	)
	(segment
		(start 167.298878 -89.210896)
		(end 167.298878 -93.52915)
		(width 0.11684)
		(layer "In11.Cu")
		(net "SCM_JTAG_MUX_S1")
	)
	(segment
		(start 166.837614 -105.704386)
		(end 169.164 -108.030772)
		(width 0.11684)
		(layer "In11.Cu")
		(net "SCM_JTAG_MUX_S1")
	)
	(segment
		(start 167.298878 -93.52915)
		(end 164.314632 -96.513396)
		(width 0.11684)
		(layer "In11.Cu")
		(net "SCM_JTAG_MUX_S1")
	)
	(segment
		(start 165.850824 -87.762842)
		(end 167.298878 -89.210896)
		(width 0.11684)
		(layer "In11.Cu")
		(net "SCM_JTAG_MUX_S1")
	)
	(segment
		(start 162.671252 -47.85233)
		(end 162.671252 -53.584856)
		(width 0.11684)
		(layer "In11.Cu")
		(net "SCM_JTAG_MUX_S1")
	)
	(segment
		(start 165.850824 -56.764428)
		(end 165.850824 -87.762842)
		(width 0.11684)
		(layer "In11.Cu")
		(net "SCM_JTAG_MUX_S1")
	)
	(segment
		(start 164.314632 -96.513396)
		(end 164.314632 -103.13543)
		(width 0.11684)
		(layer "In11.Cu")
		(net "SCM_JTAG_MUX_S1")
	)
	(segment
		(start 162.884104 -47.639478)
		(end 162.671252 -47.85233)
		(width 0.11684)
		(layer "In11.Cu")
		(net "SCM_JTAG_MUX_S1")
	)
	(segment
		(start 164.314632 -103.13543)
		(end 164.67328 -103.494078)
		(width 0.11684)
		(layer "In11.Cu")
		(net "SCM_JTAG_MUX_S1")
	)
	(segment
		(start 165.46957 -103.494078)
		(end 166.837614 -104.862122)
		(width 0.11684)
		(layer "In11.Cu")
		(net "SCM_JTAG_MUX_S1")
	)
	(segment
		(start 164.67328 -103.494078)
		(end 165.46957 -103.494078)
		(width 0.11684)
		(layer "In11.Cu")
		(net "SCM_JTAG_MUX_S1")
	)
	(segment
		(start 166.837614 -104.862122)
		(end 166.837614 -105.704386)
		(width 0.11684)
		(layer "In11.Cu")
		(net "SCM_JTAG_MUX_S1")
	)
	(segment
		(start 162.671252 -53.584856)
		(end 165.850824 -56.764428)
		(width 0.11684)
		(layer "In11.Cu")
		(net "SCM_JTAG_MUX_S1")
	)
	(segment
		(start 169.164 -108.030772)
		(end 169.164 -108.168948)
		(width 0.11684)
		(layer "In11.Cu")
		(net "SCM_JTAG_MUX_S1")
	)
	(segment
		(start 138.370564 -56.49468)
		(end 137.733024 -57.13222)
		(width 0.11684)
		(layer "In15.Cu")
		(net "SCM_JTAG_MUX_S1")
	)
	(segment
		(start 138.370564 -47.156878)
		(end 138.370564 -56.49468)
		(width 0.11684)
		(layer "In15.Cu")
		(net "SCM_JTAG_MUX_S1")
	)
	(segment
		(start 159.73679 -32.272478)
		(end 157.364938 -34.64433)
		(width 0.11684)
		(layer "In15.Cu")
		(net "SCM_JTAG_MUX_S1")
	)
	(segment
		(start 150.883112 -34.64433)
		(end 138.370564 -47.156878)
		(width 0.11684)
		(layer "In15.Cu")
		(net "SCM_JTAG_MUX_S1")
	)
	(segment
		(start 137.733024 -57.13222)
		(end 135.706358 -57.13222)
		(width 0.11684)
		(layer "In15.Cu")
		(net "SCM_JTAG_MUX_S1")
	)
	(segment
		(start 157.364938 -34.64433)
		(end 150.883112 -34.64433)
		(width 0.11684)
		(layer "In15.Cu")
		(net "SCM_JTAG_MUX_S1")
	)
	(segment
		(start 139.436602 -55.484014)
		(end 138.827002 -55.484014)
		(width 0.10668)
		(layer "F.Cu")
		(net "SCM_JTAG_MUX_S0")
	)
	(segment
		(start 119.728234 -56.582056)
		(end 119.118634 -56.582056)
		(width 0.10668)
		(layer "F.Cu")
		(net "SCM_JTAG_MUX_S0")
	)
	(segment
		(start 138.827002 -57.516014)
		(end 138.827002 -56.500014)
		(width 0.10668)
		(layer "F.Cu")
		(net "SCM_JTAG_MUX_S0")
	)
	(segment
		(start 166.73195 -107.646216)
		(end 167.01389 -107.364276)
		(width 0.10668)
		(layer "F.Cu")
		(net "SCM_JTAG_MUX_S0")
	)
	(segment
		(start 166.73195 -108.168948)
		(end 166.73195 -107.646216)
		(width 0.10668)
		(layer "F.Cu")
		(net "SCM_JTAG_MUX_S0")
	)
	(segment
		(start 138.827002 -56.500014)
		(end 138.827002 -55.484014)
		(width 0.10668)
		(layer "F.Cu")
		(net "SCM_JTAG_MUX_S0")
	)
	(via
		(at 167.01389 -107.364276)
		(size 0.508)
		(drill 0.254)
		(layers "F.Cu" "B.Cu")
		(net "SCM_JTAG_MUX_S0")
	)
	(via
		(at 139.436602 -55.484014)
		(size 0.508)
		(drill 0.254)
		(layers "F.Cu" "B.Cu")
		(net "SCM_JTAG_MUX_S0")
	)
	(via
		(at 119.728234 -56.582056)
		(size 0.508)
		(drill 0.254)
		(layers "F.Cu" "B.Cu")
		(net "SCM_JTAG_MUX_S0")
	)
	(segment
		(start 166.436802 -99.02825)
		(end 166.436802 -94.082108)
		(width 0.11684)
		(layer "In4.Cu")
		(net "SCM_JTAG_MUX_S0")
	)
	(segment
		(start 161.072068 -80.810608)
		(end 160.359344 -80.097884)
		(width 0.11684)
		(layer "In4.Cu")
		(net "SCM_JTAG_MUX_S0")
	)
	(segment
		(start 147.921218 -54.696614)
		(end 140.224002 -54.696614)
		(width 0.11684)
		(layer "In4.Cu")
		(net "SCM_JTAG_MUX_S0")
	)
	(segment
		(start 160.359344 -74.473054)
		(end 161.049716 -73.782682)
		(width 0.11684)
		(layer "In4.Cu")
		(net "SCM_JTAG_MUX_S0")
	)
	(segment
		(start 161.049716 -73.782682)
		(end 161.049716 -70.209664)
		(width 0.11684)
		(layer "In4.Cu")
		(net "SCM_JTAG_MUX_S0")
	)
	(segment
		(start 167.01389 -107.364276)
		(end 167.01389 -106.443018)
		(width 0.11684)
		(layer "In4.Cu")
		(net "SCM_JTAG_MUX_S0")
	)
	(segment
		(start 161.049716 -70.209664)
		(end 154.827986 -63.987934)
		(width 0.11684)
		(layer "In4.Cu")
		(net "SCM_JTAG_MUX_S0")
	)
	(segment
		(start 150.322026 -53.735478)
		(end 148.882354 -53.735478)
		(width 0.11684)
		(layer "In4.Cu")
		(net "SCM_JTAG_MUX_S0")
	)
	(segment
		(start 167.01389 -106.443018)
		(end 166.857426 -106.286554)
		(width 0.11684)
		(layer "In4.Cu")
		(net "SCM_JTAG_MUX_S0")
	)
	(segment
		(start 154.827986 -59.078114)
		(end 152.968198 -57.218326)
		(width 0.11684)
		(layer "In4.Cu")
		(net "SCM_JTAG_MUX_S0")
	)
	(segment
		(start 140.224002 -54.696614)
		(end 139.436602 -55.484014)
		(width 0.11684)
		(layer "In4.Cu")
		(net "SCM_JTAG_MUX_S0")
	)
	(segment
		(start 166.857426 -99.448874)
		(end 166.436802 -99.02825)
		(width 0.11684)
		(layer "In4.Cu")
		(net "SCM_JTAG_MUX_S0")
	)
	(segment
		(start 154.827986 -63.987934)
		(end 154.827986 -59.078114)
		(width 0.11684)
		(layer "In4.Cu")
		(net "SCM_JTAG_MUX_S0")
	)
	(segment
		(start 148.882354 -53.735478)
		(end 147.921218 -54.696614)
		(width 0.11684)
		(layer "In4.Cu")
		(net "SCM_JTAG_MUX_S0")
	)
	(segment
		(start 166.857426 -106.286554)
		(end 166.857426 -99.448874)
		(width 0.11684)
		(layer "In4.Cu")
		(net "SCM_JTAG_MUX_S0")
	)
	(segment
		(start 152.968198 -56.38165)
		(end 150.322026 -53.735478)
		(width 0.11684)
		(layer "In4.Cu")
		(net "SCM_JTAG_MUX_S0")
	)
	(segment
		(start 152.968198 -57.218326)
		(end 152.968198 -56.38165)
		(width 0.11684)
		(layer "In4.Cu")
		(net "SCM_JTAG_MUX_S0")
	)
	(segment
		(start 160.359344 -80.097884)
		(end 160.359344 -74.473054)
		(width 0.11684)
		(layer "In4.Cu")
		(net "SCM_JTAG_MUX_S0")
	)
	(segment
		(start 166.436802 -94.082108)
		(end 161.072068 -88.717374)
		(width 0.11684)
		(layer "In4.Cu")
		(net "SCM_JTAG_MUX_S0")
	)
	(segment
		(start 161.072068 -88.717374)
		(end 161.072068 -80.810608)
		(width 0.11684)
		(layer "In4.Cu")
		(net "SCM_JTAG_MUX_S0")
	)
	(segment
		(start 126.137416 -56.349646)
		(end 126.137416 -56.476138)
		(width 0.11684)
		(layer "In6.Cu")
		(net "SCM_JTAG_MUX_S0")
	)
	(segment
		(start 126.137416 -56.476138)
		(end 125.768354 -56.8452)
		(width 0.11684)
		(layer "In6.Cu")
		(net "SCM_JTAG_MUX_S0")
	)
	(segment
		(start 139.436602 -55.484014)
		(end 138.905488 -56.015128)
		(width 0.11684)
		(layer "In6.Cu")
		(net "SCM_JTAG_MUX_S0")
	)
	(segment
		(start 125.768354 -56.8452)
		(end 125.225302 -56.8452)
		(width 0.11684)
		(layer "In6.Cu")
		(net "SCM_JTAG_MUX_S0")
	)
	(segment
		(start 128.841754 -55.220362)
		(end 128.161796 -55.90032)
		(width 0.11684)
		(layer "In6.Cu")
		(net "SCM_JTAG_MUX_S0")
	)
	(segment
		(start 135.968994 -55.220362)
		(end 128.841754 -55.220362)
		(width 0.11684)
		(layer "In6.Cu")
		(net "SCM_JTAG_MUX_S0")
	)
	(segment
		(start 136.76376 -56.015128)
		(end 135.968994 -55.220362)
		(width 0.11684)
		(layer "In6.Cu")
		(net "SCM_JTAG_MUX_S0")
	)
	(segment
		(start 123.992894 -56.120538)
		(end 120.189752 -56.120538)
		(width 0.11684)
		(layer "In6.Cu")
		(net "SCM_JTAG_MUX_S0")
	)
	(segment
		(start 120.189752 -56.120538)
		(end 119.728234 -56.582056)
		(width 0.11684)
		(layer "In6.Cu")
		(net "SCM_JTAG_MUX_S0")
	)
	(segment
		(start 126.586742 -55.90032)
		(end 126.137416 -56.349646)
		(width 0.11684)
		(layer "In6.Cu")
		(net "SCM_JTAG_MUX_S0")
	)
	(segment
		(start 124.499624 -56.119522)
		(end 123.99391 -56.119522)
		(width 0.11684)
		(layer "In6.Cu")
		(net "SCM_JTAG_MUX_S0")
	)
	(segment
		(start 128.161796 -55.90032)
		(end 126.586742 -55.90032)
		(width 0.11684)
		(layer "In6.Cu")
		(net "SCM_JTAG_MUX_S0")
	)
	(segment
		(start 138.905488 -56.015128)
		(end 136.76376 -56.015128)
		(width 0.11684)
		(layer "In6.Cu")
		(net "SCM_JTAG_MUX_S0")
	)
	(segment
		(start 125.225302 -56.8452)
		(end 124.499624 -56.119522)
		(width 0.11684)
		(layer "In6.Cu")
		(net "SCM_JTAG_MUX_S0")
	)
	(segment
		(start 123.99391 -56.119522)
		(end 123.992894 -56.120538)
		(width 0.11684)
		(layer "In6.Cu")
		(net "SCM_JTAG_MUX_S0")
	)
	(segment
		(start 175.66386 -109.31144)
		(end 176.722532 -108.252768)
		(width 0.10668)
		(layer "F.Cu")
		(net "SCM_JTAG_MUX_R_S1")
	)
	(segment
		(start 171.704 -108.73232)
		(end 171.81957 -108.73232)
		(width 0.10668)
		(layer "F.Cu")
		(net "SCM_JTAG_MUX_R_S1")
	)
	(segment
		(start 173.5836 -109.31144)
		(end 175.66386 -109.31144)
		(width 0.10668)
		(layer "F.Cu")
		(net "SCM_JTAG_MUX_R_S1")
	)
	(segment
		(start 171.59605 -108.168948)
		(end 171.59605 -108.62437)
		(width 0.10668)
		(layer "F.Cu")
		(net "SCM_JTAG_MUX_R_S1")
	)
	(segment
		(start 171.81957 -108.73232)
		(end 172.39869 -109.31144)
		(width 0.10668)
		(layer "F.Cu")
		(net "SCM_JTAG_MUX_R_S1")
	)
	(segment
		(start 176.722532 -108.252768)
		(end 177.122074 -108.252768)
		(width 0.10668)
		(layer "F.Cu")
		(net "SCM_JTAG_MUX_R_S1")
	)
	(segment
		(start 172.39869 -109.31144)
		(end 173.5836 -109.31144)
		(width 0.10668)
		(layer "F.Cu")
		(net "SCM_JTAG_MUX_R_S1")
	)
	(segment
		(start 171.59605 -108.62437)
		(end 171.704 -108.73232)
		(width 0.10668)
		(layer "F.Cu")
		(net "SCM_JTAG_MUX_R_S1")
	)
	(via
		(at 173.5836 -109.31144)
		(size 0.762)
		(drill 0.381)
		(layers "F.Cu" "B.Cu")
		(net "SCM_JTAG_MUX_R_S1")
	)
	(segment
		(start 177.922174 -108.252768)
		(end 177.65776 -108.252768)
		(width 0.10668)
		(layer "F.Cu")
		(net "SCM_JTAG_MUX_R_S0")
	)
	(segment
		(start 176.495964 -107.846876)
		(end 175.77054 -108.5723)
		(width 0.10668)
		(layer "F.Cu")
		(net "SCM_JTAG_MUX_R_S0")
	)
	(segment
		(start 167.508682 -108.14558)
		(end 167.508682 -107.846368)
		(width 0.10668)
		(layer "F.Cu")
		(net "SCM_JTAG_MUX_R_S0")
	)
	(segment
		(start 167.53205 -108.168948)
		(end 167.508682 -108.14558)
		(width 0.10668)
		(layer "F.Cu")
		(net "SCM_JTAG_MUX_R_S0")
	)
	(segment
		(start 167.508682 -107.846368)
		(end 167.95877 -107.39628)
		(width 0.10668)
		(layer "F.Cu")
		(net "SCM_JTAG_MUX_R_S0")
	)
	(segment
		(start 177.251868 -107.846876)
		(end 176.495964 -107.846876)
		(width 0.10668)
		(layer "F.Cu")
		(net "SCM_JTAG_MUX_R_S0")
	)
	(segment
		(start 169.896028 -107.39628)
		(end 168.586912 -107.39628)
		(width 0.10668)
		(layer "F.Cu")
		(net "SCM_JTAG_MUX_R_S0")
	)
	(segment
		(start 172.46346 -108.76026)
		(end 172.0088 -108.3056)
		(width 0.10668)
		(layer "F.Cu")
		(net "SCM_JTAG_MUX_R_S0")
	)
	(segment
		(start 167.95877 -107.39628)
		(end 168.586912 -107.39628)
		(width 0.10668)
		(layer "F.Cu")
		(net "SCM_JTAG_MUX_R_S0")
	)
	(segment
		(start 172.0088 -108.3056)
		(end 172.0088 -107.80014)
		(width 0.10668)
		(layer "F.Cu")
		(net "SCM_JTAG_MUX_R_S0")
	)
	(segment
		(start 170.613578 -107.69346)
		(end 169.896028 -107.39628)
		(width 0.10668)
		(layer "F.Cu")
		(net "SCM_JTAG_MUX_R_S0")
	)
	(segment
		(start 175.77054 -108.5723)
		(end 173.43628 -108.5723)
		(width 0.10668)
		(layer "F.Cu")
		(net "SCM_JTAG_MUX_R_S0")
	)
	(segment
		(start 171.90212 -107.69346)
		(end 170.613578 -107.69346)
		(width 0.10668)
		(layer "F.Cu")
		(net "SCM_JTAG_MUX_R_S0")
	)
	(segment
		(start 173.43628 -108.5723)
		(end 172.982382 -108.76026)
		(width 0.10668)
		(layer "F.Cu")
		(net "SCM_JTAG_MUX_R_S0")
	)
	(segment
		(start 172.0088 -107.80014)
		(end 171.90212 -107.69346)
		(width 0.10668)
		(layer "F.Cu")
		(net "SCM_JTAG_MUX_R_S0")
	)
	(segment
		(start 177.65776 -108.252768)
		(end 177.251868 -107.846876)
		(width 0.10668)
		(layer "F.Cu")
		(net "SCM_JTAG_MUX_R_S0")
	)
	(segment
		(start 172.982382 -108.76026)
		(end 172.46346 -108.76026)
		(width 0.10668)
		(layer "F.Cu")
		(net "SCM_JTAG_MUX_R_S0")
	)
	(via
		(at 168.586912 -107.39628)
		(size 0.4064)
		(drill 0.2032)
		(layers "F.Cu" "B.Cu")
		(net "SCM_JTAG_MUX_R_S0")
	)
	(segment
		(start 152.4 -110.489746)
		(end 152.4 -113.284)
		(width 0.10668)
		(layer "F.Cu")
		(net "SCM_IRQ_R_N")
	)
	(segment
		(start 151.65705 -113.284)
		(end 151.53005 -113.157)
		(width 0.10668)
		(layer "F.Cu")
		(net "SCM_IRQ_R_N")
	)
	(segment
		(start 153.541476 -109.781086)
		(end 153.10866 -109.781086)
		(width 0.10668)
		(layer "F.Cu")
		(net "SCM_IRQ_R_N")
	)
	(segment
		(start 152.4 -113.284)
		(end 151.65705 -113.284)
		(width 0.10668)
		(layer "F.Cu")
		(net "SCM_IRQ_R_N")
	)
	(segment
		(start 153.10866 -109.781086)
		(end 152.4 -110.489746)
		(width 0.10668)
		(layer "F.Cu")
		(net "SCM_IRQ_R_N")
	)
	(via
		(at 152.4 -113.284)
		(size 0.762)
		(drill 0.381)
		(layers "F.Cu" "B.Cu")
		(net "SCM_IRQ_R_N")
	)
	(segment
		(start 150.72995 -114.173)
		(end 150.72995 -113.157)
		(width 0.10668)
		(layer "F.Cu")
		(net "SCM_IRQ_N")
	)
	(segment
		(start 136.030208 -108.575856)
		(end 135.75157 -108.854494)
		(width 0.10668)
		(layer "F.Cu")
		(net "SCM_IRQ_N")
	)
	(segment
		(start 143.8275 -112.3315)
		(end 140.071856 -108.575856)
		(width 0.10668)
		(layer "F.Cu")
		(net "SCM_IRQ_N")
	)
	(segment
		(start 140.071856 -108.575856)
		(end 136.030208 -108.575856)
		(width 0.10668)
		(layer "F.Cu")
		(net "SCM_IRQ_N")
	)
	(segment
		(start 147.687792 -112.3315)
		(end 143.8275 -112.3315)
		(width 0.10668)
		(layer "F.Cu")
		(net "SCM_IRQ_N")
	)
	(segment
		(start 149.529292 -114.173)
		(end 147.687792 -112.3315)
		(width 0.10668)
		(layer "F.Cu")
		(net "SCM_IRQ_N")
	)
	(segment
		(start 150.72995 -114.173)
		(end 149.529292 -114.173)
		(width 0.10668)
		(layer "F.Cu")
		(net "SCM_IRQ_N")
	)
	(via
		(at 135.75157 -108.854494)
		(size 0.508)
		(drill 0.254)
		(layers "F.Cu" "B.Cu")
		(net "SCM_IRQ_N")
	)
	(via
		(at 135.919718 -7.96036)
		(size 0.508)
		(drill 0.254)
		(layers "F.Cu" "B.Cu")
		(net "SCM_IRQ_N")
	)
	(segment
		(start 135.919718 -8.62584)
		(end 135.919718 -7.96036)
		(width 0.10668)
		(layer "B.Cu")
		(net "SCM_IRQ_N")
	)
	(segment
		(start 118.9482 -45.833538)
		(end 118.9482 -41.9354)
		(width 0.11684)
		(layer "In4.Cu")
		(net "SCM_IRQ_N")
	)
	(segment
		(start 107.407202 -82.60969)
		(end 107.407202 -77.198474)
		(width 0.11684)
		(layer "In4.Cu")
		(net "SCM_IRQ_N")
	)
	(segment
		(start 133.652006 -108.854494)
		(end 107.407202 -82.60969)
		(width 0.11684)
		(layer "In4.Cu")
		(net "SCM_IRQ_N")
	)
	(segment
		(start 102.11054 -51.935126)
		(end 105.907586 -48.13808)
		(width 0.11684)
		(layer "In4.Cu")
		(net "SCM_IRQ_N")
	)
	(segment
		(start 134.035038 -11.065002)
		(end 135.919718 -9.180322)
		(width 0.11684)
		(layer "In4.Cu")
		(net "SCM_IRQ_N")
	)
	(segment
		(start 135.75157 -108.854494)
		(end 133.652006 -108.854494)
		(width 0.11684)
		(layer "In4.Cu")
		(net "SCM_IRQ_N")
	)
	(segment
		(start 116.643658 -48.13808)
		(end 118.9482 -45.833538)
		(width 0.11684)
		(layer "In4.Cu")
		(net "SCM_IRQ_N")
	)
	(segment
		(start 116.84 -27.5336)
		(end 118.42242 -25.95118)
		(width 0.11684)
		(layer "In4.Cu")
		(net "SCM_IRQ_N")
	)
	(segment
		(start 107.407202 -77.198474)
		(end 102.11054 -71.901812)
		(width 0.11684)
		(layer "In4.Cu")
		(net "SCM_IRQ_N")
	)
	(segment
		(start 118.9482 -41.9354)
		(end 116.84 -39.8272)
		(width 0.11684)
		(layer "In4.Cu")
		(net "SCM_IRQ_N")
	)
	(segment
		(start 116.84 -39.8272)
		(end 116.84 -27.5336)
		(width 0.11684)
		(layer "In4.Cu")
		(net "SCM_IRQ_N")
	)
	(segment
		(start 102.11054 -71.901812)
		(end 102.11054 -51.935126)
		(width 0.11684)
		(layer "In4.Cu")
		(net "SCM_IRQ_N")
	)
	(segment
		(start 118.42242 -25.95118)
		(end 121.597674 -25.95118)
		(width 0.11684)
		(layer "In4.Cu")
		(net "SCM_IRQ_N")
	)
	(segment
		(start 135.919718 -9.180322)
		(end 135.919718 -7.96036)
		(width 0.11684)
		(layer "In4.Cu")
		(net "SCM_IRQ_N")
	)
	(segment
		(start 126.844298 -20.704556)
		(end 131.481576 -20.704556)
		(width 0.11684)
		(layer "In4.Cu")
		(net "SCM_IRQ_N")
	)
	(segment
		(start 131.481576 -20.704556)
		(end 134.035038 -18.151094)
		(width 0.11684)
		(layer "In4.Cu")
		(net "SCM_IRQ_N")
	)
	(segment
		(start 134.035038 -18.151094)
		(end 134.035038 -11.065002)
		(width 0.11684)
		(layer "In4.Cu")
		(net "SCM_IRQ_N")
	)
	(segment
		(start 105.907586 -48.13808)
		(end 116.643658 -48.13808)
		(width 0.11684)
		(layer "In4.Cu")
		(net "SCM_IRQ_N")
	)
	(segment
		(start 121.597674 -25.95118)
		(end 126.844298 -20.704556)
		(width 0.11684)
		(layer "In4.Cu")
		(net "SCM_IRQ_N")
	)
	(segment
		(start 190.119 -127.765556)
		(end 190.119 -125.822202)
		(width 0.10668)
		(layer "F.Cu")
		(net "SCM_IRQ_1V8_R_N")
	)
	(segment
		(start 190.119 -128.977898)
		(end 190.119 -127.765556)
		(width 0.10668)
		(layer "F.Cu")
		(net "SCM_IRQ_1V8_R_N")
	)
	(segment
		(start 190.119 -125.822202)
		(end 190.088774 -125.791976)
		(width 0.10668)
		(layer "F.Cu")
		(net "SCM_IRQ_1V8_R_N")
	)
	(segment
		(start 189.12205 -121.852944)
		(end 189.51194 -122.242834)
		(width 0.10668)
		(layer "F.Cu")
		(net "SCM_IRQ_1V8_R_N")
	)
	(via
		(at 190.119 -127.765556)
		(size 0.762)
		(drill 0.381)
		(layers "F.Cu" "B.Cu")
		(net "SCM_IRQ_1V8_R_N")
	)
	(via
		(at 190.088774 -125.791976)
		(size 0.508)
		(drill 0.254)
		(layers "F.Cu" "B.Cu")
		(net "SCM_IRQ_1V8_R_N")
	)
	(via
		(at 189.51194 -122.242834)
		(size 0.4572)
		(drill 0.254)
		(layers "F.Cu" "B.Cu")
		(net "SCM_IRQ_1V8_R_N")
	)
	(segment
		(start 189.90056 -122.631454)
		(end 189.51194 -122.242834)
		(width 0.11684)
		(layer "In11.Cu")
		(net "SCM_IRQ_1V8_R_N")
	)
	(segment
		(start 190.088774 -125.791976)
		(end 189.90056 -125.603762)
		(width 0.11684)
		(layer "In11.Cu")
		(net "SCM_IRQ_1V8_R_N")
	)
	(segment
		(start 189.90056 -125.603762)
		(end 189.90056 -122.631454)
		(width 0.11684)
		(layer "In11.Cu")
		(net "SCM_IRQ_1V8_R_N")
	)
	(segment
		(start 190.119 -129.777998)
		(end 190.119 -130.393948)
		(width 0.10668)
		(layer "F.Cu")
		(net "SCM_IRQ_1V8_N")
	)
	(segment
		(start 148.894292 -110.731046)
		(end 149.554692 -110.731046)
		(width 0.10668)
		(layer "F.Cu")
		(net "SCM_IRQ_1V8_N")
	)
	(segment
		(start 149.554692 -110.731046)
		(end 151.091392 -110.731046)
		(width 0.10668)
		(layer "F.Cu")
		(net "SCM_IRQ_1V8_N")
	)
	(via
		(at 149.554692 -110.731046)
		(size 0.508)
		(drill 0.254)
		(layers "F.Cu" "B.Cu")
		(net "SCM_IRQ_1V8_N")
	)
	(via
		(at 190.119 -130.393948)
		(size 0.508)
		(drill 0.254)
		(layers "F.Cu" "B.Cu")
		(net "SCM_IRQ_1V8_N")
	)
	(via
		(at 166.515288 -145.441162)
		(size 0.508)
		(drill 0.254)
		(layers "F.Cu" "B.Cu")
		(net "SCM_IRQ_1V8_N")
	)
	(via
		(at 190.939674 -141.659356)
		(size 0.508)
		(drill 0.254)
		(layers "F.Cu" "B.Cu")
		(net "SCM_IRQ_1V8_N")
	)
	(segment
		(start 180.01742 -143.763238)
		(end 168.193212 -143.763238)
		(width 0.11684)
		(layer "In2.Cu")
		(net "SCM_IRQ_1V8_N")
	)
	(segment
		(start 190.939674 -141.659356)
		(end 190.51651 -142.08252)
		(width 0.11684)
		(layer "In2.Cu")
		(net "SCM_IRQ_1V8_N")
	)
	(segment
		(start 186.572144 -142.08252)
		(end 186.14009 -142.514574)
		(width 0.11684)
		(layer "In2.Cu")
		(net "SCM_IRQ_1V8_N")
	)
	(segment
		(start 190.51651 -142.08252)
		(end 186.572144 -142.08252)
		(width 0.11684)
		(layer "In2.Cu")
		(net "SCM_IRQ_1V8_N")
	)
	(segment
		(start 168.193212 -143.763238)
		(end 166.515288 -145.441162)
		(width 0.11684)
		(layer "In2.Cu")
		(net "SCM_IRQ_1V8_N")
	)
	(segment
		(start 181.266084 -142.514574)
		(end 180.01742 -143.763238)
		(width 0.11684)
		(layer "In2.Cu")
		(net "SCM_IRQ_1V8_N")
	)
	(segment
		(start 186.14009 -142.514574)
		(end 181.266084 -142.514574)
		(width 0.11684)
		(layer "In2.Cu")
		(net "SCM_IRQ_1V8_N")
	)
	(segment
		(start 190.50508 -140.405358)
		(end 190.50508 -141.123162)
		(width 0.11684)
		(layer "In4.Cu")
		(net "SCM_IRQ_1V8_N")
	)
	(segment
		(start 190.119 -130.393948)
		(end 189.5221 -130.990848)
		(width 0.11684)
		(layer "In4.Cu")
		(net "SCM_IRQ_1V8_N")
	)
	(segment
		(start 189.5221 -130.990848)
		(end 189.5221 -132.966206)
		(width 0.11684)
		(layer "In4.Cu")
		(net "SCM_IRQ_1V8_N")
	)
	(segment
		(start 189.5221 -132.966206)
		(end 190.669418 -134.113524)
		(width 0.11684)
		(layer "In4.Cu")
		(net "SCM_IRQ_1V8_N")
	)
	(segment
		(start 190.50508 -141.123162)
		(end 190.939674 -141.557756)
		(width 0.11684)
		(layer "In4.Cu")
		(net "SCM_IRQ_1V8_N")
	)
	(segment
		(start 190.669418 -134.113524)
		(end 190.669418 -140.24102)
		(width 0.11684)
		(layer "In4.Cu")
		(net "SCM_IRQ_1V8_N")
	)
	(segment
		(start 190.939674 -141.557756)
		(end 190.939674 -141.659356)
		(width 0.11684)
		(layer "In4.Cu")
		(net "SCM_IRQ_1V8_N")
	)
	(segment
		(start 190.669418 -140.24102)
		(end 190.50508 -140.405358)
		(width 0.11684)
		(layer "In4.Cu")
		(net "SCM_IRQ_1V8_N")
	)
	(segment
		(start 148.76907 -118.25986)
		(end 148.1963 -118.83263)
		(width 0.11684)
		(layer "In15.Cu")
		(net "SCM_IRQ_1V8_N")
	)
	(segment
		(start 148.77542 -120.823228)
		(end 148.77542 -125.205998)
		(width 0.11684)
		(layer "In15.Cu")
		(net "SCM_IRQ_1V8_N")
	)
	(segment
		(start 148.20773 -112.437672)
		(end 148.20773 -115.552474)
		(width 0.11684)
		(layer "In15.Cu")
		(net "SCM_IRQ_1V8_N")
	)
	(segment
		(start 148.1963 -120.244108)
		(end 148.77542 -120.823228)
		(width 0.11684)
		(layer "In15.Cu")
		(net "SCM_IRQ_1V8_N")
	)
	(segment
		(start 149.554692 -111.09071)
		(end 148.20773 -112.437672)
		(width 0.11684)
		(layer "In15.Cu")
		(net "SCM_IRQ_1V8_N")
	)
	(segment
		(start 148.77542 -125.205998)
		(end 166.515288 -142.945866)
		(width 0.11684)
		(layer "In15.Cu")
		(net "SCM_IRQ_1V8_N")
	)
	(segment
		(start 149.554692 -110.731046)
		(end 149.554692 -111.09071)
		(width 0.11684)
		(layer "In15.Cu")
		(net "SCM_IRQ_1V8_N")
	)
	(segment
		(start 148.20773 -115.552474)
		(end 148.76907 -116.113814)
		(width 0.11684)
		(layer "In15.Cu")
		(net "SCM_IRQ_1V8_N")
	)
	(segment
		(start 148.76907 -116.113814)
		(end 148.76907 -118.25986)
		(width 0.11684)
		(layer "In15.Cu")
		(net "SCM_IRQ_1V8_N")
	)
	(segment
		(start 166.515288 -142.945866)
		(end 166.515288 -145.441162)
		(width 0.11684)
		(layer "In15.Cu")
		(net "SCM_IRQ_1V8_N")
	)
	(segment
		(start 148.1963 -118.83263)
		(end 148.1963 -120.244108)
		(width 0.11684)
		(layer "In15.Cu")
		(net "SCM_IRQ_1V8_N")
	)
	(segment
		(start 184.079642 -412.57855)
		(end 183.613806 -412.112714)
		(width 0.10668)
		(layer "F.Cu")
		(net "RST_SWB_BIC_R_N")
	)
	(segment
		(start 184.079642 -413.24403)
		(end 184.079642 -412.57855)
		(width 0.10668)
		(layer "F.Cu")
		(net "RST_SWB_BIC_R_N")
	)
	(via
		(at 183.613806 -412.112714)
		(size 0.508)
		(drill 0.254)
		(layers "F.Cu" "B.Cu")
		(net "RST_SWB_BIC_R_N")
	)
	(segment
		(start 172.856144 -417.078668)
		(end 172.856144 -415.808668)
		(width 0.10668)
		(layer "B.Cu")
		(net "RST_SWB_BIC_R_N")
	)
	(segment
		(start 174.207424 -415.08553)
		(end 173.484286 -415.808668)
		(width 0.10668)
		(layer "B.Cu")
		(net "RST_SWB_BIC_R_N")
	)
	(segment
		(start 183.613806 -412.112714)
		(end 183.097424 -411.596332)
		(width 0.10668)
		(layer "B.Cu")
		(net "RST_SWB_BIC_R_N")
	)
	(segment
		(start 176.753266 -414.51022)
		(end 176.177956 -415.08553)
		(width 0.10668)
		(layer "B.Cu")
		(net "RST_SWB_BIC_R_N")
	)
	(segment
		(start 176.753266 -413.384238)
		(end 176.753266 -414.51022)
		(width 0.10668)
		(layer "B.Cu")
		(net "RST_SWB_BIC_R_N")
	)
	(segment
		(start 176.177956 -415.08553)
		(end 175.483012 -415.08553)
		(width 0.10668)
		(layer "B.Cu")
		(net "RST_SWB_BIC_R_N")
	)
	(segment
		(start 181.538626 -411.596332)
		(end 181.061106 -412.073852)
		(width 0.10668)
		(layer "B.Cu")
		(net "RST_SWB_BIC_R_N")
	)
	(segment
		(start 181.061106 -412.073852)
		(end 178.063652 -412.073852)
		(width 0.10668)
		(layer "B.Cu")
		(net "RST_SWB_BIC_R_N")
	)
	(segment
		(start 175.483012 -415.08553)
		(end 174.207424 -415.08553)
		(width 0.10668)
		(layer "B.Cu")
		(net "RST_SWB_BIC_R_N")
	)
	(segment
		(start 173.484286 -415.808668)
		(end 172.856144 -415.808668)
		(width 0.10668)
		(layer "B.Cu")
		(net "RST_SWB_BIC_R_N")
	)
	(segment
		(start 178.063652 -412.073852)
		(end 176.753266 -413.384238)
		(width 0.10668)
		(layer "B.Cu")
		(net "RST_SWB_BIC_R_N")
	)
	(segment
		(start 183.097424 -411.596332)
		(end 181.538626 -411.596332)
		(width 0.10668)
		(layer "B.Cu")
		(net "RST_SWB_BIC_R_N")
	)
	(via
		(at 179.10302 -415.925254)
		(size 0.6604)
		(drill 0.3302)
		(layers "F.Cu" "B.Cu")
		(net "RST_SWB_BIC_BUF_R_N")
	)
	(segment
		(start 182.401718 -414.772094)
		(end 182.401718 -414.797494)
		(width 0.10668)
		(layer "B.Cu")
		(net "RST_SWB_BIC_BUF_R_N")
	)
	(segment
		(start 180.166518 -416.016694)
		(end 181.182518 -416.016694)
		(width 0.10668)
		(layer "B.Cu")
		(net "RST_SWB_BIC_BUF_R_N")
	)
	(segment
		(start 177.841656 -415.544254)
		(end 177.382932 -415.08553)
		(width 0.10668)
		(layer "B.Cu")
		(net "RST_SWB_BIC_BUF_R_N")
	)
	(segment
		(start 179.702714 -415.925254)
		(end 179.794154 -416.016694)
		(width 0.10668)
		(layer "B.Cu")
		(net "RST_SWB_BIC_BUF_R_N")
	)
	(segment
		(start 179.10302 -415.925254)
		(end 179.702714 -415.925254)
		(width 0.10668)
		(layer "B.Cu")
		(net "RST_SWB_BIC_BUF_R_N")
	)
	(segment
		(start 179.794154 -416.016694)
		(end 180.166518 -416.016694)
		(width 0.10668)
		(layer "B.Cu")
		(net "RST_SWB_BIC_BUF_R_N")
	)
	(segment
		(start 179.10302 -415.925254)
		(end 178.72202 -415.544254)
		(width 0.10668)
		(layer "B.Cu")
		(net "RST_SWB_BIC_BUF_R_N")
	)
	(segment
		(start 182.401718 -414.797494)
		(end 181.182518 -416.016694)
		(width 0.10668)
		(layer "B.Cu")
		(net "RST_SWB_BIC_BUF_R_N")
	)
	(segment
		(start 178.72202 -415.544254)
		(end 177.841656 -415.544254)
		(width 0.10668)
		(layer "B.Cu")
		(net "RST_SWB_BIC_BUF_R_N")
	)
	(via
		(at 174.50816 -368.8842)
		(size 0.508)
		(drill 0.254)
		(layers "F.Cu" "B.Cu")
		(net "RST_SWB_BIC_BUF_N")
	)
	(via
		(at 165.57498 -409.698444)
		(size 0.508)
		(drill 0.254)
		(layers "F.Cu" "B.Cu")
		(net "RST_SWB_BIC_BUF_N")
	)
	(via
		(at 286.245554 -377.100084)
		(size 0.508)
		(drill 0.254)
		(layers "F.Cu" "B.Cu")
		(net "RST_SWB_BIC_BUF_N")
	)
	(via
		(at 162.536378 -398.892522)
		(size 0.508)
		(drill 0.254)
		(layers "F.Cu" "B.Cu")
		(net "RST_SWB_BIC_BUF_N")
	)
	(via
		(at 182.402988 -415.628328)
		(size 0.508)
		(drill 0.254)
		(layers "F.Cu" "B.Cu")
		(net "RST_SWB_BIC_BUF_N")
	)
	(via
		(at 292.60419 -423.33799)
		(size 0.508)
		(drill 0.254)
		(layers "F.Cu" "B.Cu")
		(net "RST_SWB_BIC_BUF_N")
	)
	(segment
		(start 174.623222 -368.769138)
		(end 178.073304 -368.769138)
		(width 0.10668)
		(layer "B.Cu")
		(net "RST_SWB_BIC_BUF_N")
	)
	(segment
		(start 219.161614 -371.655848)
		(end 222.101156 -371.655848)
		(width 0.10668)
		(layer "B.Cu")
		(net "RST_SWB_BIC_BUF_N")
	)
	(segment
		(start 198.362316 -371.705632)
		(end 199.009254 -372.35257)
		(width 0.10668)
		(layer "B.Cu")
		(net "RST_SWB_BIC_BUF_N")
	)
	(segment
		(start 218.464892 -372.35257)
		(end 219.161614 -371.655848)
		(width 0.10668)
		(layer "B.Cu")
		(net "RST_SWB_BIC_BUF_N")
	)
	(segment
		(start 174.50816 -368.8842)
		(end 174.623222 -368.769138)
		(width 0.10668)
		(layer "B.Cu")
		(net "RST_SWB_BIC_BUF_N")
	)
	(segment
		(start 180.362352 -371.058186)
		(end 187.136024 -371.058186)
		(width 0.10668)
		(layer "B.Cu")
		(net "RST_SWB_BIC_BUF_N")
	)
	(segment
		(start 183.201818 -414.829498)
		(end 182.402988 -415.628328)
		(width 0.10668)
		(layer "B.Cu")
		(net "RST_SWB_BIC_BUF_N")
	)
	(segment
		(start 279.839928 -372.35257)
		(end 284.587442 -377.100084)
		(width 0.10668)
		(layer "B.Cu")
		(net "RST_SWB_BIC_BUF_N")
	)
	(segment
		(start 222.101156 -371.655848)
		(end 222.797878 -372.35257)
		(width 0.10668)
		(layer "B.Cu")
		(net "RST_SWB_BIC_BUF_N")
	)
	(segment
		(start 222.797878 -372.35257)
		(end 279.839928 -372.35257)
		(width 0.10668)
		(layer "B.Cu")
		(net "RST_SWB_BIC_BUF_N")
	)
	(segment
		(start 187.136024 -371.058186)
		(end 187.78347 -371.705632)
		(width 0.10668)
		(layer "B.Cu")
		(net "RST_SWB_BIC_BUF_N")
	)
	(segment
		(start 178.073304 -368.769138)
		(end 180.362352 -371.058186)
		(width 0.10668)
		(layer "B.Cu")
		(net "RST_SWB_BIC_BUF_N")
	)
	(segment
		(start 284.587442 -377.100084)
		(end 286.245554 -377.100084)
		(width 0.10668)
		(layer "B.Cu")
		(net "RST_SWB_BIC_BUF_N")
	)
	(segment
		(start 183.201818 -414.772094)
		(end 183.201818 -414.829498)
		(width 0.10668)
		(layer "B.Cu")
		(net "RST_SWB_BIC_BUF_N")
	)
	(segment
		(start 199.009254 -372.35257)
		(end 218.464892 -372.35257)
		(width 0.10668)
		(layer "B.Cu")
		(net "RST_SWB_BIC_BUF_N")
	)
	(segment
		(start 187.78347 -371.705632)
		(end 198.362316 -371.705632)
		(width 0.10668)
		(layer "B.Cu")
		(net "RST_SWB_BIC_BUF_N")
	)
	(segment
		(start 355.011736 -424.407838)
		(end 350.458278 -424.407838)
		(width 0.11684)
		(layer "In2.Cu")
		(net "RST_SWB_BIC_BUF_N")
	)
	(segment
		(start 406.384252 -422.324022)
		(end 371.780054 -422.324022)
		(width 0.11684)
		(layer "In2.Cu")
		(net "RST_SWB_BIC_BUF_N")
	)
	(segment
		(start 358.490266 -420.929308)
		(end 355.011736 -424.407838)
		(width 0.11684)
		(layer "In2.Cu")
		(net "RST_SWB_BIC_BUF_N")
	)
	(segment
		(start 350.458278 -424.407838)
		(end 348.510352 -422.459912)
		(width 0.11684)
		(layer "In2.Cu")
		(net "RST_SWB_BIC_BUF_N")
	)
	(segment
		(start 369.942618 -424.313858)
		(end 369.531138 -424.725338)
		(width 0.11684)
		(layer "In2.Cu")
		(net "RST_SWB_BIC_BUF_N")
	)
	(segment
		(start 363.941868 -425.6278)
		(end 363.941868 -422.234868)
		(width 0.11684)
		(layer "In2.Cu")
		(net "RST_SWB_BIC_BUF_N")
	)
	(segment
		(start 371.780054 -422.324022)
		(end 369.942618 -424.161458)
		(width 0.11684)
		(layer "In2.Cu")
		(net "RST_SWB_BIC_BUF_N")
	)
	(segment
		(start 295.529 -423.545)
		(end 294.005 -423.545)
		(width 0.11684)
		(layer "In2.Cu")
		(net "RST_SWB_BIC_BUF_N")
	)
	(segment
		(start 302.400208 -422.748456)
		(end 296.325544 -422.748456)
		(width 0.11684)
		(layer "In2.Cu")
		(net "RST_SWB_BIC_BUF_N")
	)
	(segment
		(start 369.531138 -424.725338)
		(end 369.531138 -425.419266)
		(width 0.11684)
		(layer "In2.Cu")
		(net "RST_SWB_BIC_BUF_N")
	)
	(segment
		(start 363.941868 -422.234868)
		(end 362.636308 -420.929308)
		(width 0.11684)
		(layer "In2.Cu")
		(net "RST_SWB_BIC_BUF_N")
	)
	(segment
		(start 294.005 -423.545)
		(end 293.79799 -423.33799)
		(width 0.11684)
		(layer "In2.Cu")
		(net "RST_SWB_BIC_BUF_N")
	)
	(segment
		(start 364.600236 -426.286168)
		(end 363.941868 -425.6278)
		(width 0.11684)
		(layer "In2.Cu")
		(net "RST_SWB_BIC_BUF_N")
	)
	(segment
		(start 293.79799 -423.33799)
		(end 292.60419 -423.33799)
		(width 0.11684)
		(layer "In2.Cu")
		(net "RST_SWB_BIC_BUF_N")
	)
	(segment
		(start 369.942618 -424.161458)
		(end 369.942618 -424.313858)
		(width 0.11684)
		(layer "In2.Cu")
		(net "RST_SWB_BIC_BUF_N")
	)
	(segment
		(start 296.325544 -422.748456)
		(end 295.529 -423.545)
		(width 0.11684)
		(layer "In2.Cu")
		(net "RST_SWB_BIC_BUF_N")
	)
	(segment
		(start 348.510352 -422.459912)
		(end 302.688752 -422.459912)
		(width 0.11684)
		(layer "In2.Cu")
		(net "RST_SWB_BIC_BUF_N")
	)
	(segment
		(start 362.636308 -420.929308)
		(end 358.490266 -420.929308)
		(width 0.11684)
		(layer "In2.Cu")
		(net "RST_SWB_BIC_BUF_N")
	)
	(segment
		(start 302.688752 -422.459912)
		(end 302.400208 -422.748456)
		(width 0.11684)
		(layer "In2.Cu")
		(net "RST_SWB_BIC_BUF_N")
	)
	(segment
		(start 368.664236 -426.286168)
		(end 364.600236 -426.286168)
		(width 0.11684)
		(layer "In2.Cu")
		(net "RST_SWB_BIC_BUF_N")
	)
	(segment
		(start 369.531138 -425.419266)
		(end 368.664236 -426.286168)
		(width 0.11684)
		(layer "In2.Cu")
		(net "RST_SWB_BIC_BUF_N")
	)
	(segment
		(start 408.750008 -424.689778)
		(end 406.384252 -422.324022)
		(width 0.11684)
		(layer "In2.Cu")
		(net "RST_SWB_BIC_BUF_N")
	)
	(segment
		(start 180.90769 -416.029648)
		(end 174.932086 -416.029648)
		(width 0.11684)
		(layer "In4.Cu")
		(net "RST_SWB_BIC_BUF_N")
	)
	(segment
		(start 287.358074 -399.688304)
		(end 288.431224 -400.761454)
		(width 0.11684)
		(layer "In4.Cu")
		(net "RST_SWB_BIC_BUF_N")
	)
	(segment
		(start 286.245554 -377.100084)
		(end 289.46729 -380.32182)
		(width 0.11684)
		(layer "In4.Cu")
		(net "RST_SWB_BIC_BUF_N")
	)
	(segment
		(start 288.049208 -418.940488)
		(end 288.127694 -419.018974)
		(width 0.11684)
		(layer "In4.Cu")
		(net "RST_SWB_BIC_BUF_N")
	)
	(segment
		(start 289.46729 -380.32182)
		(end 293.156386 -380.32182)
		(width 0.11684)
		(layer "In4.Cu")
		(net "RST_SWB_BIC_BUF_N")
	)
	(segment
		(start 287.358074 -398.153636)
		(end 287.358074 -399.688304)
		(width 0.11684)
		(layer "In4.Cu")
		(net "RST_SWB_BIC_BUF_N")
	)
	(segment
		(start 295.461944 -386.21462)
		(end 294.991282 -387.35127)
		(width 0.11684)
		(layer "In4.Cu")
		(net "RST_SWB_BIC_BUF_N")
	)
	(segment
		(start 289.558476 -396.149576)
		(end 289.362134 -396.149576)
		(width 0.11684)
		(layer "In4.Cu")
		(net "RST_SWB_BIC_BUF_N")
	)
	(segment
		(start 288.049208 -418.205412)
		(end 288.049208 -418.940488)
		(width 0.11684)
		(layer "In4.Cu")
		(net "RST_SWB_BIC_BUF_N")
	)
	(segment
		(start 293.664894 -392.043158)
		(end 293.664894 -393.065254)
		(width 0.11684)
		(layer "In4.Cu")
		(net "RST_SWB_BIC_BUF_N")
	)
	(segment
		(start 288.431224 -402.659342)
		(end 289.17773 -403.405848)
		(width 0.11684)
		(layer "In4.Cu")
		(net "RST_SWB_BIC_BUF_N")
	)
	(segment
		(start 173.847506 -416.482276)
		(end 173.279816 -415.914586)
		(width 0.11684)
		(layer "In4.Cu")
		(net "RST_SWB_BIC_BUF_N")
	)
	(segment
		(start 288.127694 -418.126926)
		(end 288.049208 -418.205412)
		(width 0.11684)
		(layer "In4.Cu")
		(net "RST_SWB_BIC_BUF_N")
	)
	(segment
		(start 294.991282 -390.71677)
		(end 293.664894 -392.043158)
		(width 0.11684)
		(layer "In4.Cu")
		(net "RST_SWB_BIC_BUF_N")
	)
	(segment
		(start 291.87902 -393.829032)
		(end 289.558476 -396.149576)
		(width 0.11684)
		(layer "In4.Cu")
		(net "RST_SWB_BIC_BUF_N")
	)
	(segment
		(start 173.279816 -415.914586)
		(end 173.279816 -414.93821)
		(width 0.11684)
		(layer "In4.Cu")
		(net "RST_SWB_BIC_BUF_N")
	)
	(segment
		(start 289.17773 -403.405848)
		(end 289.17773 -408.496008)
		(width 0.11684)
		(layer "In4.Cu")
		(net "RST_SWB_BIC_BUF_N")
	)
	(segment
		(start 174.932086 -416.029648)
		(end 174.479458 -416.482276)
		(width 0.11684)
		(layer "In4.Cu")
		(net "RST_SWB_BIC_BUF_N")
	)
	(segment
		(start 174.479458 -416.482276)
		(end 173.847506 -416.482276)
		(width 0.11684)
		(layer "In4.Cu")
		(net "RST_SWB_BIC_BUF_N")
	)
	(segment
		(start 294.991282 -387.35127)
		(end 294.991282 -390.71677)
		(width 0.11684)
		(layer "In4.Cu")
		(net "RST_SWB_BIC_BUF_N")
	)
	(segment
		(start 182.402988 -415.628328)
		(end 181.30901 -415.628328)
		(width 0.11684)
		(layer "In4.Cu")
		(net "RST_SWB_BIC_BUF_N")
	)
	(segment
		(start 289.818572 -414.471866)
		(end 288.127694 -416.162744)
		(width 0.11684)
		(layer "In4.Cu")
		(net "RST_SWB_BIC_BUF_N")
	)
	(segment
		(start 170.0911 -414.255712)
		(end 168.896792 -413.061404)
		(width 0.11684)
		(layer "In4.Cu")
		(net "RST_SWB_BIC_BUF_N")
	)
	(segment
		(start 181.30901 -415.628328)
		(end 180.90769 -416.029648)
		(width 0.11684)
		(layer "In4.Cu")
		(net "RST_SWB_BIC_BUF_N")
	)
	(segment
		(start 292.901116 -393.829032)
		(end 291.87902 -393.829032)
		(width 0.11684)
		(layer "In4.Cu")
		(net "RST_SWB_BIC_BUF_N")
	)
	(segment
		(start 293.664894 -393.065254)
		(end 292.901116 -393.829032)
		(width 0.11684)
		(layer "In4.Cu")
		(net "RST_SWB_BIC_BUF_N")
	)
	(segment
		(start 289.362134 -396.149576)
		(end 287.358074 -398.153636)
		(width 0.11684)
		(layer "In4.Cu")
		(net "RST_SWB_BIC_BUF_N")
	)
	(segment
		(start 295.461944 -382.627378)
		(end 295.461944 -386.21462)
		(width 0.11684)
		(layer "In4.Cu")
		(net "RST_SWB_BIC_BUF_N")
	)
	(segment
		(start 292.045136 -423.33799)
		(end 292.60419 -423.33799)
		(width 0.11684)
		(layer "In4.Cu")
		(net "RST_SWB_BIC_BUF_N")
	)
	(segment
		(start 165.9001 -409.698444)
		(end 165.57498 -409.698444)
		(width 0.11684)
		(layer "In4.Cu")
		(net "RST_SWB_BIC_BUF_N")
	)
	(segment
		(start 288.127694 -419.420548)
		(end 292.045136 -423.33799)
		(width 0.11684)
		(layer "In4.Cu")
		(net "RST_SWB_BIC_BUF_N")
	)
	(segment
		(start 168.896792 -412.695136)
		(end 165.9001 -409.698444)
		(width 0.11684)
		(layer "In4.Cu")
		(net "RST_SWB_BIC_BUF_N")
	)
	(segment
		(start 288.431224 -400.761454)
		(end 288.431224 -402.659342)
		(width 0.11684)
		(layer "In4.Cu")
		(net "RST_SWB_BIC_BUF_N")
	)
	(segment
		(start 168.896792 -413.061404)
		(end 168.896792 -412.695136)
		(width 0.11684)
		(layer "In4.Cu")
		(net "RST_SWB_BIC_BUF_N")
	)
	(segment
		(start 288.127694 -419.018974)
		(end 288.127694 -419.420548)
		(width 0.11684)
		(layer "In4.Cu")
		(net "RST_SWB_BIC_BUF_N")
	)
	(segment
		(start 288.127694 -416.162744)
		(end 288.127694 -418.126926)
		(width 0.11684)
		(layer "In4.Cu")
		(net "RST_SWB_BIC_BUF_N")
	)
	(segment
		(start 173.279816 -414.93821)
		(end 172.597318 -414.255712)
		(width 0.11684)
		(layer "In4.Cu")
		(net "RST_SWB_BIC_BUF_N")
	)
	(segment
		(start 289.818572 -409.13685)
		(end 289.818572 -414.471866)
		(width 0.11684)
		(layer "In4.Cu")
		(net "RST_SWB_BIC_BUF_N")
	)
	(segment
		(start 172.597318 -414.255712)
		(end 170.0911 -414.255712)
		(width 0.11684)
		(layer "In4.Cu")
		(net "RST_SWB_BIC_BUF_N")
	)
	(segment
		(start 289.17773 -408.496008)
		(end 289.818572 -409.13685)
		(width 0.11684)
		(layer "In4.Cu")
		(net "RST_SWB_BIC_BUF_N")
	)
	(segment
		(start 293.156386 -380.32182)
		(end 295.461944 -382.627378)
		(width 0.11684)
		(layer "In4.Cu")
		(net "RST_SWB_BIC_BUF_N")
	)
	(segment
		(start 166.566088 -393.992354)
		(end 162.940746 -397.617696)
		(width 0.11684)
		(layer "In6.Cu")
		(net "RST_SWB_BIC_BUF_N")
	)
	(segment
		(start 169.641266 -392.641582)
		(end 168.290494 -393.992354)
		(width 0.11684)
		(layer "In6.Cu")
		(net "RST_SWB_BIC_BUF_N")
	)
	(segment
		(start 174.33036 -369.062)
		(end 174.33036 -372.819676)
		(width 0.11684)
		(layer "In6.Cu")
		(net "RST_SWB_BIC_BUF_N")
	)
	(segment
		(start 172.137324 -380.91618)
		(end 169.641266 -383.412238)
		(width 0.11684)
		(layer "In6.Cu")
		(net "RST_SWB_BIC_BUF_N")
	)
	(segment
		(start 172.137324 -375.012712)
		(end 172.137324 -380.91618)
		(width 0.11684)
		(layer "In6.Cu")
		(net "RST_SWB_BIC_BUF_N")
	)
	(segment
		(start 162.940746 -397.617696)
		(end 162.940746 -398.488154)
		(width 0.11684)
		(layer "In6.Cu")
		(net "RST_SWB_BIC_BUF_N")
	)
	(segment
		(start 169.641266 -383.412238)
		(end 169.641266 -392.641582)
		(width 0.11684)
		(layer "In6.Cu")
		(net "RST_SWB_BIC_BUF_N")
	)
	(segment
		(start 174.50816 -368.8842)
		(end 174.33036 -369.062)
		(width 0.11684)
		(layer "In6.Cu")
		(net "RST_SWB_BIC_BUF_N")
	)
	(segment
		(start 174.33036 -372.819676)
		(end 172.137324 -375.012712)
		(width 0.11684)
		(layer "In6.Cu")
		(net "RST_SWB_BIC_BUF_N")
	)
	(segment
		(start 162.940746 -398.488154)
		(end 162.536378 -398.892522)
		(width 0.11684)
		(layer "In6.Cu")
		(net "RST_SWB_BIC_BUF_N")
	)
	(segment
		(start 168.290494 -393.992354)
		(end 166.566088 -393.992354)
		(width 0.11684)
		(layer "In6.Cu")
		(net "RST_SWB_BIC_BUF_N")
	)
	(segment
		(start 165.405054 -403.931882)
		(end 162.961066 -401.487894)
		(width 0.11684)
		(layer "In11.Cu")
		(net "RST_SWB_BIC_BUF_N")
	)
	(segment
		(start 165.405054 -409.528518)
		(end 165.405054 -403.931882)
		(width 0.11684)
		(layer "In11.Cu")
		(net "RST_SWB_BIC_BUF_N")
	)
	(segment
		(start 162.961066 -399.31721)
		(end 162.536378 -398.892522)
		(width 0.11684)
		(layer "In11.Cu")
		(net "RST_SWB_BIC_BUF_N")
	)
	(segment
		(start 162.961066 -401.487894)
		(end 162.961066 -399.31721)
		(width 0.11684)
		(layer "In11.Cu")
		(net "RST_SWB_BIC_BUF_N")
	)
	(segment
		(start 165.57498 -409.698444)
		(end 165.405054 -409.528518)
		(width 0.11684)
		(layer "In11.Cu")
		(net "RST_SWB_BIC_BUF_N")
	)
	(segment
		(start 254.992886 -124.50445)
		(end 254.992886 -123.97867)
		(width 0.10668)
		(layer "F.Cu")
		(net "RST_SMB_SWITCH_N")
	)
	(segment
		(start 256.842006 -122.97537)
		(end 256.521966 -122.97537)
		(width 0.10668)
		(layer "F.Cu")
		(net "RST_SMB_SWITCH_N")
	)
	(segment
		(start 279.113742 -121.75617)
		(end 279.085802 -121.75617)
		(width 0.10668)
		(layer "F.Cu")
		(net "RST_SMB_SWITCH_N")
	)
	(segment
		(start 457.24572 -92.090748)
		(end 457.24572 -93.246448)
		(width 0.10668)
		(layer "F.Cu")
		(net "RST_SMB_SWITCH_N")
	)
	(segment
		(start 254.992886 -123.97867)
		(end 255.797558 -123.173998)
		(width 0.10668)
		(layer "F.Cu")
		(net "RST_SMB_SWITCH_N")
	)
	(segment
		(start 275.192236 -122.301)
		(end 276.963632 -122.301)
		(width 0.10668)
		(layer "F.Cu")
		(net "RST_SMB_SWITCH_N")
	)
	(segment
		(start 56.942736 -29.414724)
		(end 52.485036 -29.414724)
		(width 0.10668)
		(layer "F.Cu")
		(net "RST_SMB_SWITCH_N")
	)
	(segment
		(start 59.737244 -28.453588)
		(end 57.903872 -28.453588)
		(width 0.10668)
		(layer "F.Cu")
		(net "RST_SMB_SWITCH_N")
	)
	(segment
		(start 457.62672 -93.627448)
		(end 458.487526 -93.627448)
		(width 0.10668)
		(layer "F.Cu")
		(net "RST_SMB_SWITCH_N")
	)
	(segment
		(start 57.903872 -28.453588)
		(end 56.942736 -29.414724)
		(width 0.10668)
		(layer "F.Cu")
		(net "RST_SMB_SWITCH_N")
	)
	(segment
		(start 256.521966 -122.97537)
		(end 255.996186 -122.97537)
		(width 0.10668)
		(layer "F.Cu")
		(net "RST_SMB_SWITCH_N")
	)
	(segment
		(start 179.52212 -119.452898)
		(end 179.13223 -119.842788)
		(width 0.10668)
		(layer "F.Cu")
		(net "RST_SMB_SWITCH_N")
	)
	(segment
		(start 181.648608 -413.386524)
		(end 182.664608 -413.386524)
		(width 0.10668)
		(layer "F.Cu")
		(net "RST_SMB_SWITCH_N")
	)
	(segment
		(start 276.963632 -122.301)
		(end 277.752302 -123.08967)
		(width 0.10668)
		(layer "F.Cu")
		(net "RST_SMB_SWITCH_N")
	)
	(segment
		(start 255.996186 -122.97537)
		(end 255.797558 -123.173998)
		(width 0.10668)
		(layer "F.Cu")
		(net "RST_SMB_SWITCH_N")
	)
	(segment
		(start 279.085802 -121.75617)
		(end 277.752302 -123.08967)
		(width 0.10668)
		(layer "F.Cu")
		(net "RST_SMB_SWITCH_N")
	)
	(segment
		(start 52.22748 -29.157168)
		(end 52.22748 -28.707588)
		(width 0.10668)
		(layer "F.Cu")
		(net "RST_SMB_SWITCH_N")
	)
	(segment
		(start 457.24064 -92.085668)
		(end 457.24572 -92.090748)
		(width 0.10668)
		(layer "F.Cu")
		(net "RST_SMB_SWITCH_N")
	)
	(segment
		(start 52.485036 -29.414724)
		(end 52.22748 -29.157168)
		(width 0.10668)
		(layer "F.Cu")
		(net "RST_SMB_SWITCH_N")
	)
	(segment
		(start 181.648608 -413.386524)
		(end 181.648608 -412.352236)
		(width 0.10668)
		(layer "F.Cu")
		(net "RST_SMB_SWITCH_N")
	)
	(segment
		(start 181.648608 -412.352236)
		(end 181.798976 -412.201868)
		(width 0.10668)
		(layer "F.Cu")
		(net "RST_SMB_SWITCH_N")
	)
	(segment
		(start 457.24572 -93.246448)
		(end 457.62672 -93.627448)
		(width 0.10668)
		(layer "F.Cu")
		(net "RST_SMB_SWITCH_N")
	)
	(via
		(at 140.654278 -40.65905)
		(size 0.508)
		(drill 0.254)
		(layers "F.Cu" "B.Cu")
		(net "RST_SMB_SWITCH_N")
	)
	(via
		(at 179.13223 -119.842788)
		(size 0.4572)
		(drill 0.254)
		(layers "F.Cu" "B.Cu")
		(net "RST_SMB_SWITCH_N")
	)
	(via
		(at 181.798976 -412.201868)
		(size 0.508)
		(drill 0.254)
		(layers "F.Cu" "B.Cu")
		(net "RST_SMB_SWITCH_N")
	)
	(via
		(at 199.305926 -371.393212)
		(size 0.508)
		(drill 0.254)
		(layers "F.Cu" "B.Cu")
		(net "RST_SMB_SWITCH_N")
	)
	(via
		(at 275.192236 -122.301)
		(size 0.508)
		(drill 0.254)
		(layers "F.Cu" "B.Cu")
		(net "RST_SMB_SWITCH_N")
	)
	(via
		(at 457.24064 -92.085668)
		(size 0.508)
		(drill 0.254)
		(layers "F.Cu" "B.Cu")
		(net "RST_SMB_SWITCH_N")
	)
	(via
		(at 431.869088 -370.978938)
		(size 0.508)
		(drill 0.254)
		(layers "F.Cu" "B.Cu")
		(net "RST_SMB_SWITCH_N")
	)
	(via
		(at 272.063718 -367.03127)
		(size 0.508)
		(drill 0.254)
		(layers "F.Cu" "B.Cu")
		(net "RST_SMB_SWITCH_N")
	)
	(via
		(at 256.946908 -144.392142)
		(size 0.508)
		(drill 0.254)
		(layers "F.Cu" "B.Cu")
		(net "RST_SMB_SWITCH_N")
	)
	(via
		(at 239.724692 -421.833548)
		(size 0.508)
		(drill 0.254)
		(layers "F.Cu" "B.Cu")
		(net "RST_SMB_SWITCH_N")
	)
	(via
		(at 59.737244 -28.453588)
		(size 0.508)
		(drill 0.254)
		(layers "F.Cu" "B.Cu")
		(net "RST_SMB_SWITCH_N")
	)
	(via
		(at 255.797558 -123.173998)
		(size 0.508)
		(drill 0.254)
		(layers "F.Cu" "B.Cu")
		(net "RST_SMB_SWITCH_N")
	)
	(via
		(at 282.194254 -91.763088)
		(size 0.508)
		(drill 0.254)
		(layers "F.Cu" "B.Cu")
		(net "RST_SMB_SWITCH_N")
	)
	(via
		(at 455.767948 -323.988684)
		(size 0.508)
		(drill 0.254)
		(layers "F.Cu" "B.Cu")
		(net "RST_SMB_SWITCH_N")
	)
	(via
		(at 275.495766 -424.942508)
		(size 0.508)
		(drill 0.254)
		(layers "F.Cu" "B.Cu")
		(net "RST_SMB_SWITCH_N")
	)
	(via
		(at 175.442372 -147.043902)
		(size 0.508)
		(drill 0.254)
		(layers "F.Cu" "B.Cu")
		(net "RST_SMB_SWITCH_N")
	)
	(via
		(at 380.937008 -124.059696)
		(size 0.508)
		(drill 0.254)
		(layers "F.Cu" "B.Cu")
		(net "RST_SMB_SWITCH_N")
	)
	(via
		(at 140.55344 -121.366788)
		(size 0.508)
		(drill 0.254)
		(layers "F.Cu" "B.Cu")
		(net "RST_SMB_SWITCH_N")
	)
	(segment
		(start 294.64508 -374.130824)
		(end 292.901624 -374.130824)
		(width 0.10668)
		(layer "B.Cu")
		(net "RST_SMB_SWITCH_N")
	)
	(segment
		(start 433.311808 -156.257752)
		(end 433.311808 -147.988782)
		(width 0.10668)
		(layer "B.Cu")
		(net "RST_SMB_SWITCH_N")
	)
	(segment
		(start 239.724692 -422.449498)
		(end 239.724692 -421.833548)
		(width 0.10668)
		(layer "B.Cu")
		(net "RST_SMB_SWITCH_N")
	)
	(segment
		(start 446.184274 -177.711608)
		(end 446.184274 -167.891968)
		(width 0.10668)
		(layer "B.Cu")
		(net "RST_SMB_SWITCH_N")
	)
	(segment
		(start 440.67476 -163.620704)
		(end 433.311808 -156.257752)
		(width 0.10668)
		(layer "B.Cu")
		(net "RST_SMB_SWITCH_N")
	)
	(segment
		(start 272.063718 -367.03127)
		(end 270.778732 -368.316256)
		(width 0.10668)
		(layer "B.Cu")
		(net "RST_SMB_SWITCH_N")
	)
	(segment
		(start 222.873062 -370.78539)
		(end 218.373452 -370.78539)
		(width 0.10668)
		(layer "B.Cu")
		(net "RST_SMB_SWITCH_N")
	)
	(segment
		(start 274.89404 -122.002804)
		(end 275.192236 -122.301)
		(width 0.10668)
		(layer "B.Cu")
		(net "RST_SMB_SWITCH_N")
	)
	(segment
		(start 457.22794 -322.528692)
		(end 457.22794 -188.755274)
		(width 0.10668)
		(layer "B.Cu")
		(net "RST_SMB_SWITCH_N")
	)
	(segment
		(start 292.901624 -374.130824)
		(end 286.963612 -368.192812)
		(width 0.10668)
		(layer "B.Cu")
		(net "RST_SMB_SWITCH_N")
	)
	(segment
		(start 433.311808 -147.988782)
		(end 415.684208 -130.361182)
		(width 0.10668)
		(layer "B.Cu")
		(net "RST_SMB_SWITCH_N")
	)
	(segment
		(start 301.62627 -370.177568)
		(end 300.690534 -369.241832)
		(width 0.10668)
		(layer "B.Cu")
		(net "RST_SMB_SWITCH_N")
	)
	(segment
		(start 265.345672 -123.637294)
		(end 268.550644 -123.637294)
		(width 0.10668)
		(layer "B.Cu")
		(net "RST_SMB_SWITCH_N")
	)
	(segment
		(start 252.393196 -368.316256)
		(end 251.220986 -367.144046)
		(width 0.10668)
		(layer "B.Cu")
		(net "RST_SMB_SWITCH_N")
	)
	(segment
		(start 273.22526 -368.192812)
		(end 272.063718 -367.03127)
		(width 0.10668)
		(layer "B.Cu")
		(net "RST_SMB_SWITCH_N")
	)
	(segment
		(start 258.860036 -123.173998)
		(end 259.990336 -122.043698)
		(width 0.10668)
		(layer "B.Cu")
		(net "RST_SMB_SWITCH_N")
	)
	(segment
		(start 268.946122 -124.032772)
		(end 270.185134 -124.032772)
		(width 0.10668)
		(layer "B.Cu")
		(net "RST_SMB_SWITCH_N")
	)
	(segment
		(start 259.990336 -122.043698)
		(end 263.752076 -122.043698)
		(width 0.10668)
		(layer "B.Cu")
		(net "RST_SMB_SWITCH_N")
	)
	(segment
		(start 218.373452 -370.78539)
		(end 217.76563 -371.393212)
		(width 0.10668)
		(layer "B.Cu")
		(net "RST_SMB_SWITCH_N")
	)
	(segment
		(start 251.220986 -367.144046)
		(end 236.038898 -367.144046)
		(width 0.10668)
		(layer "B.Cu")
		(net "RST_SMB_SWITCH_N")
	)
	(segment
		(start 298.37507 -369.241832)
		(end 296.68343 -370.933472)
		(width 0.10668)
		(layer "B.Cu")
		(net "RST_SMB_SWITCH_N")
	)
	(segment
		(start 300.690534 -369.241832)
		(end 298.37507 -369.241832)
		(width 0.10668)
		(layer "B.Cu")
		(net "RST_SMB_SWITCH_N")
	)
	(segment
		(start 272.575782 -123.488958)
		(end 274.061936 -122.002804)
		(width 0.10668)
		(layer "B.Cu")
		(net "RST_SMB_SWITCH_N")
	)
	(segment
		(start 217.76563 -371.393212)
		(end 199.305926 -371.393212)
		(width 0.10668)
		(layer "B.Cu")
		(net "RST_SMB_SWITCH_N")
	)
	(segment
		(start 268.550644 -123.637294)
		(end 268.946122 -124.032772)
		(width 0.10668)
		(layer "B.Cu")
		(net "RST_SMB_SWITCH_N")
	)
	(segment
		(start 446.184274 -167.891968)
		(end 441.91301 -163.620704)
		(width 0.10668)
		(layer "B.Cu")
		(net "RST_SMB_SWITCH_N")
	)
	(segment
		(start 236.038898 -367.144046)
		(end 231.789732 -371.393212)
		(width 0.10668)
		(layer "B.Cu")
		(net "RST_SMB_SWITCH_N")
	)
	(segment
		(start 431.869088 -370.978938)
		(end 431.067718 -370.177568)
		(width 0.10668)
		(layer "B.Cu")
		(net "RST_SMB_SWITCH_N")
	)
	(segment
		(start 296.68343 -372.092474)
		(end 294.64508 -374.130824)
		(width 0.10668)
		(layer "B.Cu")
		(net "RST_SMB_SWITCH_N")
	)
	(segment
		(start 263.752076 -122.043698)
		(end 265.345672 -123.637294)
		(width 0.10668)
		(layer "B.Cu")
		(net "RST_SMB_SWITCH_N")
	)
	(segment
		(start 441.91301 -163.620704)
		(end 440.67476 -163.620704)
		(width 0.10668)
		(layer "B.Cu")
		(net "RST_SMB_SWITCH_N")
	)
	(segment
		(start 231.789732 -371.393212)
		(end 223.480884 -371.393212)
		(width 0.10668)
		(layer "B.Cu")
		(net "RST_SMB_SWITCH_N")
	)
	(segment
		(start 223.480884 -371.393212)
		(end 222.873062 -370.78539)
		(width 0.10668)
		(layer "B.Cu")
		(net "RST_SMB_SWITCH_N")
	)
	(segment
		(start 394.671804 -136.024366)
		(end 392.901678 -136.024366)
		(width 0.10668)
		(layer "B.Cu")
		(net "RST_SMB_SWITCH_N")
	)
	(segment
		(start 274.061936 -122.002804)
		(end 274.89404 -122.002804)
		(width 0.10668)
		(layer "B.Cu")
		(net "RST_SMB_SWITCH_N")
	)
	(segment
		(start 457.22794 -188.755274)
		(end 446.184274 -177.711608)
		(width 0.10668)
		(layer "B.Cu")
		(net "RST_SMB_SWITCH_N")
	)
	(segment
		(start 270.728948 -123.488958)
		(end 272.575782 -123.488958)
		(width 0.10668)
		(layer "B.Cu")
		(net "RST_SMB_SWITCH_N")
	)
	(segment
		(start 286.963612 -368.192812)
		(end 273.22526 -368.192812)
		(width 0.10668)
		(layer "B.Cu")
		(net "RST_SMB_SWITCH_N")
	)
	(segment
		(start 255.797558 -123.173998)
		(end 258.860036 -123.173998)
		(width 0.10668)
		(layer "B.Cu")
		(net "RST_SMB_SWITCH_N")
	)
	(segment
		(start 392.901678 -136.024366)
		(end 380.937008 -124.059696)
		(width 0.10668)
		(layer "B.Cu")
		(net "RST_SMB_SWITCH_N")
	)
	(segment
		(start 270.185134 -124.032772)
		(end 270.728948 -123.488958)
		(width 0.10668)
		(layer "B.Cu")
		(net "RST_SMB_SWITCH_N")
	)
	(segment
		(start 431.067718 -370.177568)
		(end 301.62627 -370.177568)
		(width 0.10668)
		(layer "B.Cu")
		(net "RST_SMB_SWITCH_N")
	)
	(segment
		(start 400.334988 -130.361182)
		(end 394.671804 -136.024366)
		(width 0.10668)
		(layer "B.Cu")
		(net "RST_SMB_SWITCH_N")
	)
	(segment
		(start 270.778732 -368.316256)
		(end 252.393196 -368.316256)
		(width 0.10668)
		(layer "B.Cu")
		(net "RST_SMB_SWITCH_N")
	)
	(segment
		(start 296.68343 -370.933472)
		(end 296.68343 -372.092474)
		(width 0.10668)
		(layer "B.Cu")
		(net "RST_SMB_SWITCH_N")
	)
	(segment
		(start 415.684208 -130.361182)
		(end 400.334988 -130.361182)
		(width 0.10668)
		(layer "B.Cu")
		(net "RST_SMB_SWITCH_N")
	)
	(segment
		(start 455.767948 -323.988684)
		(end 457.22794 -322.528692)
		(width 0.10668)
		(layer "B.Cu")
		(net "RST_SMB_SWITCH_N")
	)
	(segment
		(start 166.822882 -124.231908)
		(end 170.049952 -124.231908)
		(width 0.11684)
		(layer "In2.Cu")
		(net "RST_SMB_SWITCH_N")
	)
	(segment
		(start 178.74107 -120.233948)
		(end 179.13223 -119.842788)
		(width 0.11684)
		(layer "In2.Cu")
		(net "RST_SMB_SWITCH_N")
	)
	(segment
		(start 171.895008 -120.439688)
		(end 175.59274 -120.439688)
		(width 0.11684)
		(layer "In2.Cu")
		(net "RST_SMB_SWITCH_N")
	)
	(segment
		(start 183.153812 -144.901666)
		(end 181.325012 -146.730466)
		(width 0.11684)
		(layer "In2.Cu")
		(net "RST_SMB_SWITCH_N")
	)
	(segment
		(start 163.471098 -123.47067)
		(end 166.061644 -123.47067)
		(width 0.11684)
		(layer "In2.Cu")
		(net "RST_SMB_SWITCH_N")
	)
	(segment
		(start 181.325012 -146.730466)
		(end 176.343818 -146.730466)
		(width 0.11684)
		(layer "In2.Cu")
		(net "RST_SMB_SWITCH_N")
	)
	(segment
		(start 256.946908 -144.392142)
		(end 256.437384 -144.392142)
		(width 0.11684)
		(layer "In2.Cu")
		(net "RST_SMB_SWITCH_N")
	)
	(segment
		(start 192.16243 -142.629128)
		(end 190.815722 -143.975836)
		(width 0.11684)
		(layer "In2.Cu")
		(net "RST_SMB_SWITCH_N")
	)
	(segment
		(start 274.915376 -424.362118)
		(end 275.495766 -424.942508)
		(width 0.11684)
		(layer "In2.Cu")
		(net "RST_SMB_SWITCH_N")
	)
	(segment
		(start 205.29931 -141.627606)
		(end 199.457818 -141.627606)
		(width 0.11684)
		(layer "In2.Cu")
		(net "RST_SMB_SWITCH_N")
	)
	(segment
		(start 175.79848 -120.233948)
		(end 178.74107 -120.233948)
		(width 0.11684)
		(layer "In2.Cu")
		(net "RST_SMB_SWITCH_N")
	)
	(segment
		(start 176.343818 -146.730466)
		(end 176.030382 -147.043902)
		(width 0.11684)
		(layer "In2.Cu")
		(net "RST_SMB_SWITCH_N")
	)
	(segment
		(start 198.456296 -142.629128)
		(end 192.16243 -142.629128)
		(width 0.11684)
		(layer "In2.Cu")
		(net "RST_SMB_SWITCH_N")
	)
	(segment
		(start 190.815722 -143.975836)
		(end 189.342522 -143.975836)
		(width 0.11684)
		(layer "In2.Cu")
		(net "RST_SMB_SWITCH_N")
	)
	(segment
		(start 239.724692 -421.833548)
		(end 241.179604 -423.28846)
		(width 0.11684)
		(layer "In2.Cu")
		(net "RST_SMB_SWITCH_N")
	)
	(segment
		(start 199.457818 -141.627606)
		(end 198.456296 -142.629128)
		(width 0.11684)
		(layer "In2.Cu")
		(net "RST_SMB_SWITCH_N")
	)
	(segment
		(start 157.42158 -124.231908)
		(end 162.70986 -124.231908)
		(width 0.11684)
		(layer "In2.Cu")
		(net "RST_SMB_SWITCH_N")
	)
	(segment
		(start 189.342522 -143.975836)
		(end 188.416692 -144.901666)
		(width 0.11684)
		(layer "In2.Cu")
		(net "RST_SMB_SWITCH_N")
	)
	(segment
		(start 162.70986 -124.231908)
		(end 163.471098 -123.47067)
		(width 0.11684)
		(layer "In2.Cu")
		(net "RST_SMB_SWITCH_N")
	)
	(segment
		(start 147.662138 -123.95581)
		(end 157.145482 -123.95581)
		(width 0.11684)
		(layer "In2.Cu")
		(net "RST_SMB_SWITCH_N")
	)
	(segment
		(start 176.030382 -147.043902)
		(end 175.442372 -147.043902)
		(width 0.11684)
		(layer "In2.Cu")
		(net "RST_SMB_SWITCH_N")
	)
	(segment
		(start 256.437384 -144.392142)
		(end 255.562354 -143.517112)
		(width 0.11684)
		(layer "In2.Cu")
		(net "RST_SMB_SWITCH_N")
	)
	(segment
		(start 140.55344 -121.366788)
		(end 145.073116 -121.366788)
		(width 0.11684)
		(layer "In2.Cu")
		(net "RST_SMB_SWITCH_N")
	)
	(segment
		(start 145.073116 -121.366788)
		(end 147.662138 -123.95581)
		(width 0.11684)
		(layer "In2.Cu")
		(net "RST_SMB_SWITCH_N")
	)
	(segment
		(start 188.416692 -144.901666)
		(end 183.153812 -144.901666)
		(width 0.11684)
		(layer "In2.Cu")
		(net "RST_SMB_SWITCH_N")
	)
	(segment
		(start 207.188816 -143.517112)
		(end 205.29931 -141.627606)
		(width 0.11684)
		(layer "In2.Cu")
		(net "RST_SMB_SWITCH_N")
	)
	(segment
		(start 263.040876 -423.28846)
		(end 264.114534 -424.362118)
		(width 0.11684)
		(layer "In2.Cu")
		(net "RST_SMB_SWITCH_N")
	)
	(segment
		(start 157.145482 -123.95581)
		(end 157.42158 -124.231908)
		(width 0.11684)
		(layer "In2.Cu")
		(net "RST_SMB_SWITCH_N")
	)
	(segment
		(start 264.114534 -424.362118)
		(end 274.915376 -424.362118)
		(width 0.11684)
		(layer "In2.Cu")
		(net "RST_SMB_SWITCH_N")
	)
	(segment
		(start 166.061644 -123.47067)
		(end 166.822882 -124.231908)
		(width 0.11684)
		(layer "In2.Cu")
		(net "RST_SMB_SWITCH_N")
	)
	(segment
		(start 175.59274 -120.439688)
		(end 175.79848 -120.233948)
		(width 0.11684)
		(layer "In2.Cu")
		(net "RST_SMB_SWITCH_N")
	)
	(segment
		(start 241.179604 -423.28846)
		(end 263.040876 -423.28846)
		(width 0.11684)
		(layer "In2.Cu")
		(net "RST_SMB_SWITCH_N")
	)
	(segment
		(start 170.049952 -124.231908)
		(end 171.32554 -122.95632)
		(width 0.11684)
		(layer "In2.Cu")
		(net "RST_SMB_SWITCH_N")
	)
	(segment
		(start 255.562354 -143.517112)
		(end 207.188816 -143.517112)
		(width 0.11684)
		(layer "In2.Cu")
		(net "RST_SMB_SWITCH_N")
	)
	(segment
		(start 171.32554 -122.95632)
		(end 171.32554 -121.009156)
		(width 0.11684)
		(layer "In2.Cu")
		(net "RST_SMB_SWITCH_N")
	)
	(segment
		(start 171.32554 -121.009156)
		(end 171.895008 -120.439688)
		(width 0.11684)
		(layer "In2.Cu")
		(net "RST_SMB_SWITCH_N")
	)
	(segment
		(start 176.322228 -408.813)
		(end 177.171858 -409.66263)
		(width 0.11684)
		(layer "In4.Cu")
		(net "RST_SMB_SWITCH_N")
	)
	(segment
		(start 280.018744 -424.22953)
		(end 280.018744 -422.46931)
		(width 0.11684)
		(layer "In4.Cu")
		(net "RST_SMB_SWITCH_N")
	)
	(segment
		(start 193.27876 -377.420378)
		(end 192.31864 -377.420378)
		(width 0.11684)
		(layer "In4.Cu")
		(net "RST_SMB_SWITCH_N")
	)
	(segment
		(start 443.055756 -370.679472)
		(end 447.676016 -366.059212)
		(width 0.11684)
		(layer "In4.Cu")
		(net "RST_SMB_SWITCH_N")
	)
	(segment
		(start 180.215286 -390.88822)
		(end 178.958494 -390.88822)
		(width 0.11684)
		(layer "In4.Cu")
		(net "RST_SMB_SWITCH_N")
	)
	(segment
		(start 284.499304 -416.05327)
		(end 284.499304 -414.842452)
		(width 0.11684)
		(layer "In4.Cu")
		(net "RST_SMB_SWITCH_N")
	)
	(segment
		(start 283.710888 -370.750592)
		(end 276.517862 -370.750592)
		(width 0.11684)
		(layer "In4.Cu")
		(net "RST_SMB_SWITCH_N")
	)
	(segment
		(start 255.751838 -131.049776)
		(end 254.58293 -129.880868)
		(width 0.11684)
		(layer "In4.Cu")
		(net "RST_SMB_SWITCH_N")
	)
	(segment
		(start 178.958494 -390.88822)
		(end 176.7586 -393.088114)
		(width 0.11684)
		(layer "In4.Cu")
		(net "RST_SMB_SWITCH_N")
	)
	(segment
		(start 280.018744 -422.46931)
		(end 281.987752 -420.500302)
		(width 0.11684)
		(layer "In4.Cu")
		(net "RST_SMB_SWITCH_N")
	)
	(segment
		(start 172.944028 -133.166866)
		(end 173.90491 -134.127748)
		(width 0.11684)
		(layer "In4.Cu")
		(net "RST_SMB_SWITCH_N")
	)
	(segment
		(start 255.751838 -134.837932)
		(end 255.751838 -131.049776)
		(width 0.11684)
		(layer "In4.Cu")
		(net "RST_SMB_SWITCH_N")
	)
	(segment
		(start 192.991232 -386.195062)
		(end 183.97474 -386.195062)
		(width 0.11684)
		(layer "In4.Cu")
		(net "RST_SMB_SWITCH_N")
	)
	(segment
		(start 173.90491 -134.127748)
		(end 173.90491 -145.50644)
		(width 0.11684)
		(layer "In4.Cu")
		(net "RST_SMB_SWITCH_N")
	)
	(segment
		(start 283.124148 -417.428426)
		(end 284.499304 -416.05327)
		(width 0.11684)
		(layer "In4.Cu")
		(net "RST_SMB_SWITCH_N")
	)
	(segment
		(start 280.57856 -109.885734)
		(end 282.194254 -108.27004)
		(width 0.11684)
		(layer "In4.Cu")
		(net "RST_SMB_SWITCH_N")
	)
	(segment
		(start 172.944028 -130.76555)
		(end 172.944028 -133.166866)
		(width 0.11684)
		(layer "In4.Cu")
		(net "RST_SMB_SWITCH_N")
	)
	(segment
		(start 283.13253 -377.570746)
		(end 285.282132 -375.421144)
		(width 0.11684)
		(layer "In4.Cu")
		(net "RST_SMB_SWITCH_N")
	)
	(segment
		(start 432.168554 -370.679472)
		(end 443.055756 -370.679472)
		(width 0.11684)
		(layer "In4.Cu")
		(net "RST_SMB_SWITCH_N")
	)
	(segment
		(start 178.733958 -124.97562)
		(end 172.944028 -130.76555)
		(width 0.11684)
		(layer "In4.Cu")
		(net "RST_SMB_SWITCH_N")
	)
	(segment
		(start 183.97474 -386.195062)
		(end 180.659532 -389.51027)
		(width 0.11684)
		(layer "In4.Cu")
		(net "RST_SMB_SWITCH_N")
	)
	(segment
		(start 193.497962 -381.54229)
		(end 193.497962 -385.688332)
		(width 0.11684)
		(layer "In4.Cu")
		(net "RST_SMB_SWITCH_N")
	)
	(segment
		(start 284.499304 -414.842452)
		(end 285.170626 -414.17113)
		(width 0.11684)
		(layer "In4.Cu")
		(net "RST_SMB_SWITCH_N")
	)
	(segment
		(start 254.58293 -129.880868)
		(end 254.58293 -124.388626)
		(width 0.11684)
		(layer "In4.Cu")
		(net "RST_SMB_SWITCH_N")
	)
	(segment
		(start 282.194254 -108.27004)
		(end 282.194254 -91.763088)
		(width 0.11684)
		(layer "In4.Cu")
		(net "RST_SMB_SWITCH_N")
	)
	(segment
		(start 178.950112 -119.842788)
		(end 178.733958 -120.058942)
		(width 0.11684)
		(layer "In4.Cu")
		(net "RST_SMB_SWITCH_N")
	)
	(segment
		(start 275.192236 -122.301)
		(end 276.798786 -122.301)
		(width 0.11684)
		(layer "In4.Cu")
		(net "RST_SMB_SWITCH_N")
	)
	(segment
		(start 275.495766 -424.942508)
		(end 279.305766 -424.942508)
		(width 0.11684)
		(layer "In4.Cu")
		(net "RST_SMB_SWITCH_N")
	)
	(segment
		(start 176.322228 -407.928318)
		(end 176.322228 -408.813)
		(width 0.11684)
		(layer "In4.Cu")
		(net "RST_SMB_SWITCH_N")
	)
	(segment
		(start 276.517862 -370.750592)
		(end 272.79854 -367.03127)
		(width 0.11684)
		(layer "In4.Cu")
		(net "RST_SMB_SWITCH_N")
	)
	(segment
		(start 285.562294 -390.832086)
		(end 284.370018 -389.63981)
		(width 0.11684)
		(layer "In4.Cu")
		(net "RST_SMB_SWITCH_N")
	)
	(segment
		(start 281.987752 -418.200078)
		(end 282.759404 -417.428426)
		(width 0.11684)
		(layer "In4.Cu")
		(net "RST_SMB_SWITCH_N")
	)
	(segment
		(start 284.370018 -386.608066)
		(end 283.13253 -385.370578)
		(width 0.11684)
		(layer "In4.Cu")
		(net "RST_SMB_SWITCH_N")
	)
	(segment
		(start 199.305926 -371.393212)
		(end 193.27876 -377.420378)
		(width 0.11684)
		(layer "In4.Cu")
		(net "RST_SMB_SWITCH_N")
	)
	(segment
		(start 179.13223 -119.842788)
		(end 178.950112 -119.842788)
		(width 0.11684)
		(layer "In4.Cu")
		(net "RST_SMB_SWITCH_N")
	)
	(segment
		(start 193.497962 -385.688332)
		(end 192.991232 -386.195062)
		(width 0.11684)
		(layer "In4.Cu")
		(net "RST_SMB_SWITCH_N")
	)
	(segment
		(start 431.869088 -370.978938)
		(end 432.168554 -370.679472)
		(width 0.11684)
		(layer "In4.Cu")
		(net "RST_SMB_SWITCH_N")
	)
	(segment
		(start 284.08503 -397.097758)
		(end 284.746954 -396.435834)
		(width 0.11684)
		(layer "In4.Cu")
		(net "RST_SMB_SWITCH_N")
	)
	(segment
		(start 283.13253 -385.370578)
		(end 283.13253 -377.570746)
		(width 0.11684)
		(layer "In4.Cu")
		(net "RST_SMB_SWITCH_N")
	)
	(segment
		(start 285.282132 -372.321836)
		(end 283.710888 -370.750592)
		(width 0.11684)
		(layer "In4.Cu")
		(net "RST_SMB_SWITCH_N")
	)
	(segment
		(start 256.946908 -144.392142)
		(end 254.474726 -141.91996)
		(width 0.11684)
		(layer "In4.Cu")
		(net "RST_SMB_SWITCH_N")
	)
	(segment
		(start 447.676016 -333.859632)
		(end 455.767948 -325.7677)
		(width 0.11684)
		(layer "In4.Cu")
		(net "RST_SMB_SWITCH_N")
	)
	(segment
		(start 177.171858 -409.66263)
		(end 179.670456 -409.66263)
		(width 0.11684)
		(layer "In4.Cu")
		(net "RST_SMB_SWITCH_N")
	)
	(segment
		(start 284.746954 -396.31874)
		(end 285.562294 -395.5034)
		(width 0.11684)
		(layer "In4.Cu")
		(net "RST_SMB_SWITCH_N")
	)
	(segment
		(start 179.670456 -409.66263)
		(end 181.798976 -411.79115)
		(width 0.11684)
		(layer "In4.Cu")
		(net "RST_SMB_SWITCH_N")
	)
	(segment
		(start 254.474726 -136.115044)
		(end 255.751838 -134.837932)
		(width 0.11684)
		(layer "In4.Cu")
		(net "RST_SMB_SWITCH_N")
	)
	(segment
		(start 178.733958 -120.058942)
		(end 178.733958 -124.97562)
		(width 0.11684)
		(layer "In4.Cu")
		(net "RST_SMB_SWITCH_N")
	)
	(segment
		(start 254.474726 -141.91996)
		(end 254.474726 -136.115044)
		(width 0.11684)
		(layer "In4.Cu")
		(net "RST_SMB_SWITCH_N")
	)
	(segment
		(start 279.305766 -424.942508)
		(end 280.018744 -424.22953)
		(width 0.11684)
		(layer "In4.Cu")
		(net "RST_SMB_SWITCH_N")
	)
	(segment
		(start 447.676016 -366.059212)
		(end 447.676016 -333.859632)
		(width 0.11684)
		(layer "In4.Cu")
		(net "RST_SMB_SWITCH_N")
	)
	(segment
		(start 193.128646 -381.172974)
		(end 193.497962 -381.54229)
		(width 0.11684)
		(layer "In4.Cu")
		(net "RST_SMB_SWITCH_N")
	)
	(segment
		(start 180.659532 -389.51027)
		(end 180.659532 -390.443974)
		(width 0.11684)
		(layer "In4.Cu")
		(net "RST_SMB_SWITCH_N")
	)
	(segment
		(start 455.767948 -325.7677)
		(end 455.767948 -323.988684)
		(width 0.11684)
		(layer "In4.Cu")
		(net "RST_SMB_SWITCH_N")
	)
	(segment
		(start 280.57856 -118.521226)
		(end 280.57856 -109.885734)
		(width 0.11684)
		(layer "In4.Cu")
		(net "RST_SMB_SWITCH_N")
	)
	(segment
		(start 191.736218 -381.172974)
		(end 193.128646 -381.172974)
		(width 0.11684)
		(layer "In4.Cu")
		(net "RST_SMB_SWITCH_N")
	)
	(segment
		(start 276.798786 -122.301)
		(end 280.57856 -118.521226)
		(width 0.11684)
		(layer "In4.Cu")
		(net "RST_SMB_SWITCH_N")
	)
	(segment
		(start 254.58293 -124.388626)
		(end 255.797558 -123.173998)
		(width 0.11684)
		(layer "In4.Cu")
		(net "RST_SMB_SWITCH_N")
	)
	(segment
		(start 181.798976 -411.79115)
		(end 181.798976 -412.201868)
		(width 0.11684)
		(layer "In4.Cu")
		(net "RST_SMB_SWITCH_N")
	)
	(segment
		(start 285.170626 -401.87626)
		(end 284.08503 -400.790664)
		(width 0.11684)
		(layer "In4.Cu")
		(net "RST_SMB_SWITCH_N")
	)
	(segment
		(start 281.987752 -420.500302)
		(end 281.987752 -418.200078)
		(width 0.11684)
		(layer "In4.Cu")
		(net "RST_SMB_SWITCH_N")
	)
	(segment
		(start 282.759404 -417.428426)
		(end 283.124148 -417.428426)
		(width 0.11684)
		(layer "In4.Cu")
		(net "RST_SMB_SWITCH_N")
	)
	(segment
		(start 284.08503 -400.790664)
		(end 284.08503 -397.097758)
		(width 0.11684)
		(layer "In4.Cu")
		(net "RST_SMB_SWITCH_N")
	)
	(segment
		(start 191.38265 -378.356368)
		(end 191.38265 -380.819406)
		(width 0.11684)
		(layer "In4.Cu")
		(net "RST_SMB_SWITCH_N")
	)
	(segment
		(start 284.746954 -396.435834)
		(end 284.746954 -396.31874)
		(width 0.11684)
		(layer "In4.Cu")
		(net "RST_SMB_SWITCH_N")
	)
	(segment
		(start 285.282132 -375.421144)
		(end 285.282132 -372.321836)
		(width 0.11684)
		(layer "In4.Cu")
		(net "RST_SMB_SWITCH_N")
	)
	(segment
		(start 176.7586 -393.088114)
		(end 176.7586 -407.491946)
		(width 0.11684)
		(layer "In4.Cu")
		(net "RST_SMB_SWITCH_N")
	)
	(segment
		(start 176.7586 -407.491946)
		(end 176.322228 -407.928318)
		(width 0.11684)
		(layer "In4.Cu")
		(net "RST_SMB_SWITCH_N")
	)
	(segment
		(start 284.370018 -389.63981)
		(end 284.370018 -386.608066)
		(width 0.11684)
		(layer "In4.Cu")
		(net "RST_SMB_SWITCH_N")
	)
	(segment
		(start 191.38265 -380.819406)
		(end 191.736218 -381.172974)
		(width 0.11684)
		(layer "In4.Cu")
		(net "RST_SMB_SWITCH_N")
	)
	(segment
		(start 272.79854 -367.03127)
		(end 272.063718 -367.03127)
		(width 0.11684)
		(layer "In4.Cu")
		(net "RST_SMB_SWITCH_N")
	)
	(segment
		(start 285.170626 -414.17113)
		(end 285.170626 -401.87626)
		(width 0.11684)
		(layer "In4.Cu")
		(net "RST_SMB_SWITCH_N")
	)
	(segment
		(start 285.562294 -395.5034)
		(end 285.562294 -390.832086)
		(width 0.11684)
		(layer "In4.Cu")
		(net "RST_SMB_SWITCH_N")
	)
	(segment
		(start 192.31864 -377.420378)
		(end 191.38265 -378.356368)
		(width 0.11684)
		(layer "In4.Cu")
		(net "RST_SMB_SWITCH_N")
	)
	(segment
		(start 173.90491 -145.50644)
		(end 175.442372 -147.043902)
		(width 0.11684)
		(layer "In4.Cu")
		(net "RST_SMB_SWITCH_N")
	)
	(segment
		(start 180.659532 -390.443974)
		(end 180.215286 -390.88822)
		(width 0.11684)
		(layer "In4.Cu")
		(net "RST_SMB_SWITCH_N")
	)
	(segment
		(start 457.24064 -92.085668)
		(end 456.930252 -91.77528)
		(width 0.11684)
		(layer "In6.Cu")
		(net "RST_SMB_SWITCH_N")
	)
	(segment
		(start 63.727584 -32.443928)
		(end 59.737244 -28.453588)
		(width 0.11684)
		(layer "In6.Cu")
		(net "RST_SMB_SWITCH_N")
	)
	(segment
		(start 129.817622 -43.43908)
		(end 129.389886 -43.011344)
		(width 0.11684)
		(layer "In6.Cu")
		(net "RST_SMB_SWITCH_N")
	)
	(segment
		(start 84.164932 -33.3248)
		(end 76.4794 -33.3248)
		(width 0.11684)
		(layer "In6.Cu")
		(net "RST_SMB_SWITCH_N")
	)
	(segment
		(start 115.303808 -43.011344)
		(end 114.304572 -44.01058)
		(width 0.11684)
		(layer "In6.Cu")
		(net "RST_SMB_SWITCH_N")
	)
	(segment
		(start 140.654278 -40.65905)
		(end 140.654278 -40.899588)
		(width 0.11684)
		(layer "In6.Cu")
		(net "RST_SMB_SWITCH_N")
	)
	(segment
		(start 104.984296 -39.378636)
		(end 103.928672 -39.378636)
		(width 0.11684)
		(layer "In6.Cu")
		(net "RST_SMB_SWITCH_N")
	)
	(segment
		(start 138.114786 -43.43908)
		(end 129.817622 -43.43908)
		(width 0.11684)
		(layer "In6.Cu")
		(net "RST_SMB_SWITCH_N")
	)
	(segment
		(start 109.61624 -44.01058)
		(end 104.984296 -39.378636)
		(width 0.11684)
		(layer "In6.Cu")
		(net "RST_SMB_SWITCH_N")
	)
	(segment
		(start 456.930252 -91.77528)
		(end 417.14928 -91.77528)
		(width 0.11684)
		(layer "In6.Cu")
		(net "RST_SMB_SWITCH_N")
	)
	(segment
		(start 317.953644 -94.625668)
		(end 314.643008 -91.315032)
		(width 0.11684)
		(layer "In6.Cu")
		(net "RST_SMB_SWITCH_N")
	)
	(segment
		(start 140.654278 -40.899588)
		(end 138.114786 -43.43908)
		(width 0.11684)
		(layer "In6.Cu")
		(net "RST_SMB_SWITCH_N")
	)
	(segment
		(start 414.298892 -94.625668)
		(end 317.953644 -94.625668)
		(width 0.11684)
		(layer "In6.Cu")
		(net "RST_SMB_SWITCH_N")
	)
	(segment
		(start 103.928672 -39.378636)
		(end 100.470462 -37.94633)
		(width 0.11684)
		(layer "In6.Cu")
		(net "RST_SMB_SWITCH_N")
	)
	(segment
		(start 114.304572 -44.01058)
		(end 109.61624 -44.01058)
		(width 0.11684)
		(layer "In6.Cu")
		(net "RST_SMB_SWITCH_N")
	)
	(segment
		(start 69.79158 -32.250888)
		(end 69.59854 -32.443928)
		(width 0.11684)
		(layer "In6.Cu")
		(net "RST_SMB_SWITCH_N")
	)
	(segment
		(start 76.4794 -33.3248)
		(end 75.405488 -32.250888)
		(width 0.11684)
		(layer "In6.Cu")
		(net "RST_SMB_SWITCH_N")
	)
	(segment
		(start 282.64231 -91.315032)
		(end 282.194254 -91.763088)
		(width 0.11684)
		(layer "In6.Cu")
		(net "RST_SMB_SWITCH_N")
	)
	(segment
		(start 69.59854 -32.443928)
		(end 63.727584 -32.443928)
		(width 0.11684)
		(layer "In6.Cu")
		(net "RST_SMB_SWITCH_N")
	)
	(segment
		(start 314.643008 -91.315032)
		(end 282.64231 -91.315032)
		(width 0.11684)
		(layer "In6.Cu")
		(net "RST_SMB_SWITCH_N")
	)
	(segment
		(start 417.14928 -91.77528)
		(end 414.298892 -94.625668)
		(width 0.11684)
		(layer "In6.Cu")
		(net "RST_SMB_SWITCH_N")
	)
	(segment
		(start 75.405488 -32.250888)
		(end 69.79158 -32.250888)
		(width 0.11684)
		(layer "In6.Cu")
		(net "RST_SMB_SWITCH_N")
	)
	(segment
		(start 100.470462 -37.94633)
		(end 88.786462 -37.94633)
		(width 0.11684)
		(layer "In6.Cu")
		(net "RST_SMB_SWITCH_N")
	)
	(segment
		(start 88.786462 -37.94633)
		(end 84.164932 -33.3248)
		(width 0.11684)
		(layer "In6.Cu")
		(net "RST_SMB_SWITCH_N")
	)
	(segment
		(start 129.389886 -43.011344)
		(end 115.303808 -43.011344)
		(width 0.11684)
		(layer "In6.Cu")
		(net "RST_SMB_SWITCH_N")
	)
	(segment
		(start 141.096746 -43.237658)
		(end 135.751824 -48.58258)
		(width 0.11684)
		(layer "In15.Cu")
		(net "RST_SMB_SWITCH_N")
	)
	(segment
		(start 135.927338 -112.081056)
		(end 136.64438 -112.798098)
		(width 0.11684)
		(layer "In15.Cu")
		(net "RST_SMB_SWITCH_N")
	)
	(segment
		(start 275.616416 -121.87682)
		(end 275.192236 -122.301)
		(width 0.11684)
		(layer "In15.Cu")
		(net "RST_SMB_SWITCH_N")
	)
	(segment
		(start 141.096746 -41.101518)
		(end 141.096746 -43.237658)
		(width 0.11684)
		(layer "In15.Cu")
		(net "RST_SMB_SWITCH_N")
	)
	(segment
		(start 134.353046 -60.48629)
		(end 137.111232 -63.244476)
		(width 0.11684)
		(layer "In15.Cu")
		(net "RST_SMB_SWITCH_N")
	)
	(segment
		(start 137.111232 -66.169032)
		(end 138.107166 -67.164966)
		(width 0.11684)
		(layer "In15.Cu")
		(net "RST_SMB_SWITCH_N")
	)
	(segment
		(start 136.64438 -114.759994)
		(end 140.55344 -118.669054)
		(width 0.11684)
		(layer "In15.Cu")
		(net "RST_SMB_SWITCH_N")
	)
	(segment
		(start 140.55344 -118.669054)
		(end 140.55344 -121.366788)
		(width 0.11684)
		(layer "In15.Cu")
		(net "RST_SMB_SWITCH_N")
	)
	(segment
		(start 136.64438 -112.798098)
		(end 136.64438 -114.759994)
		(width 0.11684)
		(layer "In15.Cu")
		(net "RST_SMB_SWITCH_N")
	)
	(segment
		(start 378.709682 -121.83237)
		(end 348.608396 -121.83237)
		(width 0.11684)
		(layer "In15.Cu")
		(net "RST_SMB_SWITCH_N")
	)
	(segment
		(start 136.64438 -108.899706)
		(end 135.927338 -109.616748)
		(width 0.11684)
		(layer "In15.Cu")
		(net "RST_SMB_SWITCH_N")
	)
	(segment
		(start 137.111232 -63.244476)
		(end 137.111232 -66.169032)
		(width 0.11684)
		(layer "In15.Cu")
		(net "RST_SMB_SWITCH_N")
	)
	(segment
		(start 138.107166 -70.642734)
		(end 135.909558 -72.840342)
		(width 0.11684)
		(layer "In15.Cu")
		(net "RST_SMB_SWITCH_N")
	)
	(segment
		(start 348.608396 -121.83237)
		(end 348.205044 -122.235722)
		(width 0.11684)
		(layer "In15.Cu")
		(net "RST_SMB_SWITCH_N")
	)
	(segment
		(start 348.205044 -122.235722)
		(end 308.601618 -122.235722)
		(width 0.11684)
		(layer "In15.Cu")
		(net "RST_SMB_SWITCH_N")
	)
	(segment
		(start 135.909558 -87.333836)
		(end 136.64438 -88.068658)
		(width 0.11684)
		(layer "In15.Cu")
		(net "RST_SMB_SWITCH_N")
	)
	(segment
		(start 136.64438 -88.068658)
		(end 136.64438 -108.899706)
		(width 0.11684)
		(layer "In15.Cu")
		(net "RST_SMB_SWITCH_N")
	)
	(segment
		(start 278.230838 -120.980962)
		(end 277.33498 -121.87682)
		(width 0.11684)
		(layer "In15.Cu")
		(net "RST_SMB_SWITCH_N")
	)
	(segment
		(start 308.601618 -122.235722)
		(end 307.346858 -120.980962)
		(width 0.11684)
		(layer "In15.Cu")
		(net "RST_SMB_SWITCH_N")
	)
	(segment
		(start 380.937008 -124.059696)
		(end 378.709682 -121.83237)
		(width 0.11684)
		(layer "In15.Cu")
		(net "RST_SMB_SWITCH_N")
	)
	(segment
		(start 140.654278 -40.65905)
		(end 141.096746 -41.101518)
		(width 0.11684)
		(layer "In15.Cu")
		(net "RST_SMB_SWITCH_N")
	)
	(segment
		(start 135.751824 -48.58258)
		(end 135.751824 -55.555642)
		(width 0.11684)
		(layer "In15.Cu")
		(net "RST_SMB_SWITCH_N")
	)
	(segment
		(start 135.909558 -72.840342)
		(end 135.909558 -87.333836)
		(width 0.11684)
		(layer "In15.Cu")
		(net "RST_SMB_SWITCH_N")
	)
	(segment
		(start 307.346858 -120.980962)
		(end 278.230838 -120.980962)
		(width 0.11684)
		(layer "In15.Cu")
		(net "RST_SMB_SWITCH_N")
	)
	(segment
		(start 138.107166 -67.164966)
		(end 138.107166 -70.642734)
		(width 0.11684)
		(layer "In15.Cu")
		(net "RST_SMB_SWITCH_N")
	)
	(segment
		(start 277.33498 -121.87682)
		(end 275.616416 -121.87682)
		(width 0.11684)
		(layer "In15.Cu")
		(net "RST_SMB_SWITCH_N")
	)
	(segment
		(start 135.751824 -55.555642)
		(end 134.353046 -56.95442)
		(width 0.11684)
		(layer "In15.Cu")
		(net "RST_SMB_SWITCH_N")
	)
	(segment
		(start 135.927338 -109.616748)
		(end 135.927338 -112.081056)
		(width 0.11684)
		(layer "In15.Cu")
		(net "RST_SMB_SWITCH_N")
	)
	(segment
		(start 134.353046 -56.95442)
		(end 134.353046 -60.48629)
		(width 0.11684)
		(layer "In15.Cu")
		(net "RST_SMB_SWITCH_N")
	)
	(segment
		(start 58.569352 -30.648148)
		(end 59.80684 -29.41066)
		(width 0.10668)
		(layer "F.Cu")
		(net "RST_SMB_OCP_V3_2_N")
	)
	(segment
		(start 61.066934 -8.320024)
		(end 61.066934 -5.38734)
		(width 0.10668)
		(layer "F.Cu")
		(net "RST_SMB_OCP_V3_2_N")
	)
	(segment
		(start 56.90997 -30.648148)
		(end 58.569352 -30.648148)
		(width 0.10668)
		(layer "F.Cu")
		(net "RST_SMB_OCP_V3_2_N")
	)
	(segment
		(start 61.066934 -5.38734)
		(end 61.291724 -5.16255)
		(width 0.10668)
		(layer "F.Cu")
		(net "RST_SMB_OCP_V3_2_N")
	)
	(via
		(at 59.80684 -29.41066)
		(size 0.508)
		(drill 0.254)
		(layers "F.Cu" "B.Cu")
		(net "RST_SMB_OCP_V3_2_N")
	)
	(via
		(at 61.291724 -5.16255)
		(size 0.508)
		(drill 0.254)
		(layers "F.Cu" "B.Cu")
		(net "RST_SMB_OCP_V3_2_N")
	)
	(segment
		(start 60.249308 -4.709668)
		(end 60.70219 -5.16255)
		(width 0.11684)
		(layer "In4.Cu")
		(net "RST_SMB_OCP_V3_2_N")
	)
	(segment
		(start 60.53836 -28.67914)
		(end 60.53836 -24.059388)
		(width 0.11684)
		(layer "In4.Cu")
		(net "RST_SMB_OCP_V3_2_N")
	)
	(segment
		(start 61.138816 -9.558274)
		(end 61.138816 -8.60171)
		(width 0.11684)
		(layer "In4.Cu")
		(net "RST_SMB_OCP_V3_2_N")
	)
	(segment
		(start 59.226196 -6.68909)
		(end 59.226196 -5.310124)
		(width 0.11684)
		(layer "In4.Cu")
		(net "RST_SMB_OCP_V3_2_N")
	)
	(segment
		(start 61.138816 -8.60171)
		(end 59.226196 -6.68909)
		(width 0.11684)
		(layer "In4.Cu")
		(net "RST_SMB_OCP_V3_2_N")
	)
	(segment
		(start 59.826652 -4.709668)
		(end 60.249308 -4.709668)
		(width 0.11684)
		(layer "In4.Cu")
		(net "RST_SMB_OCP_V3_2_N")
	)
	(segment
		(start 60.916566 -12.694158)
		(end 60.916566 -9.780524)
		(width 0.11684)
		(layer "In4.Cu")
		(net "RST_SMB_OCP_V3_2_N")
	)
	(segment
		(start 60.080144 -13.53058)
		(end 60.916566 -12.694158)
		(width 0.11684)
		(layer "In4.Cu")
		(net "RST_SMB_OCP_V3_2_N")
	)
	(segment
		(start 60.70219 -5.16255)
		(end 61.291724 -5.16255)
		(width 0.11684)
		(layer "In4.Cu")
		(net "RST_SMB_OCP_V3_2_N")
	)
	(segment
		(start 60.916566 -9.780524)
		(end 61.138816 -9.558274)
		(width 0.11684)
		(layer "In4.Cu")
		(net "RST_SMB_OCP_V3_2_N")
	)
	(segment
		(start 59.226196 -5.310124)
		(end 59.826652 -4.709668)
		(width 0.11684)
		(layer "In4.Cu")
		(net "RST_SMB_OCP_V3_2_N")
	)
	(segment
		(start 60.53836 -24.059388)
		(end 60.080144 -23.601172)
		(width 0.11684)
		(layer "In4.Cu")
		(net "RST_SMB_OCP_V3_2_N")
	)
	(segment
		(start 60.080144 -23.601172)
		(end 60.080144 -13.53058)
		(width 0.11684)
		(layer "In4.Cu")
		(net "RST_SMB_OCP_V3_2_N")
	)
	(segment
		(start 59.80684 -29.41066)
		(end 60.53836 -28.67914)
		(width 0.11684)
		(layer "In4.Cu")
		(net "RST_SMB_OCP_V3_2_N")
	)
	(segment
		(start 435.56682 -6.455156)
		(end 436.964836 -5.05714)
		(width 0.10668)
		(layer "F.Cu")
		(net "RST_SMB_OCP_SFF_N")
	)
	(segment
		(start 435.56682 -8.320024)
		(end 435.56682 -6.455156)
		(width 0.10668)
		(layer "F.Cu")
		(net "RST_SMB_OCP_SFF_N")
	)
	(segment
		(start 464.135978 -94.317566)
		(end 464.751928 -94.317566)
		(width 0.10668)
		(layer "F.Cu")
		(net "RST_SMB_OCP_SFF_N")
	)
	(segment
		(start 436.964836 -5.05714)
		(end 437.425592 -5.05714)
		(width 0.10668)
		(layer "F.Cu")
		(net "RST_SMB_OCP_SFF_N")
	)
	(via
		(at 437.425592 -5.05714)
		(size 0.508)
		(drill 0.254)
		(layers "F.Cu" "B.Cu")
		(net "RST_SMB_OCP_SFF_N")
	)
	(via
		(at 464.751928 -94.317566)
		(size 0.508)
		(drill 0.254)
		(layers "F.Cu" "B.Cu")
		(net "RST_SMB_OCP_SFF_N")
	)
	(segment
		(start 435.256686 -27.366468)
		(end 431.872898 -30.750256)
		(width 0.11684)
		(layer "In2.Cu")
		(net "RST_SMB_OCP_SFF_N")
	)
	(segment
		(start 435.256686 -6.79831)
		(end 435.256686 -27.366468)
		(width 0.11684)
		(layer "In2.Cu")
		(net "RST_SMB_OCP_SFF_N")
	)
	(segment
		(start 431.872898 -30.750256)
		(end 431.872898 -44.392088)
		(width 0.11684)
		(layer "In2.Cu")
		(net "RST_SMB_OCP_SFF_N")
	)
	(segment
		(start 427.888146 -48.37684)
		(end 427.888146 -54.550056)
		(width 0.11684)
		(layer "In2.Cu")
		(net "RST_SMB_OCP_SFF_N")
	)
	(segment
		(start 427.888146 -54.550056)
		(end 436.477156 -63.139066)
		(width 0.11684)
		(layer "In2.Cu")
		(net "RST_SMB_OCP_SFF_N")
	)
	(segment
		(start 437.425592 -5.05714)
		(end 436.997856 -5.05714)
		(width 0.11684)
		(layer "In2.Cu")
		(net "RST_SMB_OCP_SFF_N")
	)
	(segment
		(start 440.991752 -80.81772)
		(end 454.491598 -94.317566)
		(width 0.11684)
		(layer "In2.Cu")
		(net "RST_SMB_OCP_SFF_N")
	)
	(segment
		(start 437.43626 -80.81772)
		(end 440.991752 -80.81772)
		(width 0.11684)
		(layer "In2.Cu")
		(net "RST_SMB_OCP_SFF_N")
	)
	(segment
		(start 436.997856 -5.05714)
		(end 435.256686 -6.79831)
		(width 0.11684)
		(layer "In2.Cu")
		(net "RST_SMB_OCP_SFF_N")
	)
	(segment
		(start 436.477156 -79.858616)
		(end 437.43626 -80.81772)
		(width 0.11684)
		(layer "In2.Cu")
		(net "RST_SMB_OCP_SFF_N")
	)
	(segment
		(start 431.872898 -44.392088)
		(end 427.888146 -48.37684)
		(width 0.11684)
		(layer "In2.Cu")
		(net "RST_SMB_OCP_SFF_N")
	)
	(segment
		(start 436.477156 -63.139066)
		(end 436.477156 -79.858616)
		(width 0.11684)
		(layer "In2.Cu")
		(net "RST_SMB_OCP_SFF_N")
	)
	(segment
		(start 454.491598 -94.317566)
		(end 464.751928 -94.317566)
		(width 0.11684)
		(layer "In2.Cu")
		(net "RST_SMB_OCP_SFF_N")
	)
	(segment
		(start 254.00381 -73.77938)
		(end 254.148336 -73.923906)
		(width 0.10668)
		(layer "F.Cu")
		(net "RST_SMB_E1S_N")
	)
	(segment
		(start 254.148336 -73.923906)
		(end 254.148336 -74.882248)
		(width 0.10668)
		(layer "F.Cu")
		(net "RST_SMB_E1S_N")
	)
	(segment
		(start 252.095254 -75.092814)
		(end 252.097032 -75.091036)
		(width 0.10668)
		(layer "F.Cu")
		(net "RST_SMB_E1S_N")
	)
	(segment
		(start 253.939548 -75.091036)
		(end 253.413006 -75.091036)
		(width 0.10668)
		(layer "F.Cu")
		(net "RST_SMB_E1S_N")
	)
	(segment
		(start 253.42469 -73.77938)
		(end 254.00381 -73.77938)
		(width 0.10668)
		(layer "F.Cu")
		(net "RST_SMB_E1S_N")
	)
	(segment
		(start 250.865386 -75.092814)
		(end 252.095254 -75.092814)
		(width 0.10668)
		(layer "F.Cu")
		(net "RST_SMB_E1S_N")
	)
	(segment
		(start 252.097032 -75.091036)
		(end 253.413006 -75.091036)
		(width 0.10668)
		(layer "F.Cu")
		(net "RST_SMB_E1S_N")
	)
	(segment
		(start 254.148336 -74.882248)
		(end 253.939548 -75.091036)
		(width 0.10668)
		(layer "F.Cu")
		(net "RST_SMB_E1S_N")
	)
	(segment
		(start 253.413006 -73.791064)
		(end 253.42469 -73.77938)
		(width 0.10668)
		(layer "F.Cu")
		(net "RST_SMB_E1S_N")
	)
	(via
		(at 252.097032 -75.091036)
		(size 0.762)
		(drill 0.381)
		(layers "F.Cu" "B.Cu")
		(net "RST_SMB_E1S_N")
	)
	(segment
		(start 258.675886 -75.770994)
		(end 259.842 -75.770994)
		(width 0.10668)
		(layer "F.Cu")
		(net "RST_SMB_E1S_0_N")
	)
	(segment
		(start 224.60966 -46.524926)
		(end 225.33102 -46.524926)
		(width 0.10668)
		(layer "F.Cu")
		(net "RST_SMB_E1S_0_N")
	)
	(segment
		(start 226.170998 -47.364904)
		(end 232.000044 -47.364904)
		(width 0.10668)
		(layer "F.Cu")
		(net "RST_SMB_E1S_0_N")
	)
	(segment
		(start 259.842 -75.770994)
		(end 261.068566 -75.770994)
		(width 0.10668)
		(layer "F.Cu")
		(net "RST_SMB_E1S_0_N")
	)
	(segment
		(start 225.33102 -46.524926)
		(end 226.170998 -47.364904)
		(width 0.10668)
		(layer "F.Cu")
		(net "RST_SMB_E1S_0_N")
	)
	(via
		(at 261.03326 -60.427108)
		(size 0.508)
		(drill 0.254)
		(layers "F.Cu" "B.Cu")
		(net "RST_SMB_E1S_0_N")
	)
	(via
		(at 259.842 -75.770994)
		(size 0.508)
		(drill 0.254)
		(layers "F.Cu" "B.Cu")
		(net "RST_SMB_E1S_0_N")
	)
	(via
		(at 225.33102 -46.524926)
		(size 0.508)
		(drill 0.254)
		(layers "F.Cu" "B.Cu")
		(net "RST_SMB_E1S_0_N")
	)
	(segment
		(start 225.33102 -46.524926)
		(end 227.828602 -49.022508)
		(width 0.11684)
		(layer "In4.Cu")
		(net "RST_SMB_E1S_0_N")
	)
	(segment
		(start 234.22356 -56.794908)
		(end 237.852458 -60.423806)
		(width 0.11684)
		(layer "In4.Cu")
		(net "RST_SMB_E1S_0_N")
	)
	(segment
		(start 234.22356 -51.824128)
		(end 234.22356 -56.794908)
		(width 0.11684)
		(layer "In4.Cu")
		(net "RST_SMB_E1S_0_N")
	)
	(segment
		(start 237.852458 -60.423806)
		(end 261.029958 -60.423806)
		(width 0.11684)
		(layer "In4.Cu")
		(net "RST_SMB_E1S_0_N")
	)
	(segment
		(start 261.029958 -60.423806)
		(end 261.03326 -60.427108)
		(width 0.11684)
		(layer "In4.Cu")
		(net "RST_SMB_E1S_0_N")
	)
	(segment
		(start 227.828602 -49.022508)
		(end 231.42194 -49.022508)
		(width 0.11684)
		(layer "In4.Cu")
		(net "RST_SMB_E1S_0_N")
	)
	(segment
		(start 231.42194 -49.022508)
		(end 234.22356 -51.824128)
		(width 0.11684)
		(layer "In4.Cu")
		(net "RST_SMB_E1S_0_N")
	)
	(segment
		(start 259.842 -75.770994)
		(end 259.842 -74.478388)
		(width 0.11684)
		(layer "In11.Cu")
		(net "RST_SMB_E1S_0_N")
	)
	(segment
		(start 261.03326 -73.287128)
		(end 261.03326 -60.427108)
		(width 0.11684)
		(layer "In11.Cu")
		(net "RST_SMB_E1S_0_N")
	)
	(segment
		(start 259.842 -74.478388)
		(end 261.03326 -73.287128)
		(width 0.11684)
		(layer "In11.Cu")
		(net "RST_SMB_E1S_0_N")
	)
	(segment
		(start 256.6797 -75.771248)
		(end 257.875532 -75.771248)
		(width 0.10668)
		(layer "F.Cu")
		(net "RST_SMB_BUF_E1S_0_N")
	)
	(segment
		(start 255.312926 -75.091036)
		(end 255.773428 -75.091036)
		(width 0.10668)
		(layer "F.Cu")
		(net "RST_SMB_BUF_E1S_0_N")
	)
	(segment
		(start 255.773428 -75.091036)
		(end 256.45364 -75.771248)
		(width 0.10668)
		(layer "F.Cu")
		(net "RST_SMB_BUF_E1S_0_N")
	)
	(segment
		(start 257.875532 -75.771248)
		(end 257.875786 -75.770994)
		(width 0.10668)
		(layer "F.Cu")
		(net "RST_SMB_BUF_E1S_0_N")
	)
	(segment
		(start 256.45364 -75.771248)
		(end 256.6797 -75.771248)
		(width 0.10668)
		(layer "F.Cu")
		(net "RST_SMB_BUF_E1S_0_N")
	)
	(via
		(at 256.6797 -75.771248)
		(size 0.762)
		(drill 0.381)
		(layers "F.Cu" "B.Cu")
		(net "RST_SMB_BUF_E1S_0_N")
	)
	(segment
		(start 210.873848 -122.908568)
		(end 211.30895 -122.473466)
		(width 0.10668)
		(layer "F.Cu")
		(net "RST_PERST_OCP_SFF_N")
	)
	(segment
		(start 211.30895 -122.473466)
		(end 211.30895 -119.634)
		(width 0.10668)
		(layer "F.Cu")
		(net "RST_PERST_OCP_SFF_N")
	)
	(segment
		(start 191.522096 -119.452898)
		(end 191.911986 -119.842788)
		(width 0.10668)
		(layer "F.Cu")
		(net "RST_PERST_OCP_SFF_N")
	)
	(via
		(at 191.911986 -119.842788)
		(size 0.4572)
		(drill 0.254)
		(layers "F.Cu" "B.Cu")
		(net "RST_PERST_OCP_SFF_N")
	)
	(via
		(at 210.873848 -122.908568)
		(size 0.508)
		(drill 0.254)
		(layers "F.Cu" "B.Cu")
		(net "RST_PERST_OCP_SFF_N")
	)
	(segment
		(start 209.557874 -123.551188)
		(end 208.804764 -124.304298)
		(width 0.11684)
		(layer "In2.Cu")
		(net "RST_PERST_OCP_SFF_N")
	)
	(segment
		(start 192.316354 -120.482868)
		(end 191.911986 -120.0785)
		(width 0.11684)
		(layer "In2.Cu")
		(net "RST_PERST_OCP_SFF_N")
	)
	(segment
		(start 191.911986 -120.0785)
		(end 191.911986 -119.842788)
		(width 0.11684)
		(layer "In2.Cu")
		(net "RST_PERST_OCP_SFF_N")
	)
	(segment
		(start 193.291968 -121.854214)
		(end 193.111628 -121.673874)
		(width 0.11684)
		(layer "In2.Cu")
		(net "RST_PERST_OCP_SFF_N")
	)
	(segment
		(start 207.027272 -124.304298)
		(end 206.63535 -123.912376)
		(width 0.11684)
		(layer "In2.Cu")
		(net "RST_PERST_OCP_SFF_N")
	)
	(segment
		(start 202.565762 -125.314202)
		(end 201.55662 -126.323344)
		(width 0.11684)
		(layer "In2.Cu")
		(net "RST_PERST_OCP_SFF_N")
	)
	(segment
		(start 204.482954 -125.314202)
		(end 202.565762 -125.314202)
		(width 0.11684)
		(layer "In2.Cu")
		(net "RST_PERST_OCP_SFF_N")
	)
	(segment
		(start 208.804764 -124.304298)
		(end 207.027272 -124.304298)
		(width 0.11684)
		(layer "In2.Cu")
		(net "RST_PERST_OCP_SFF_N")
	)
	(segment
		(start 196.543676 -124.25299)
		(end 195.894452 -124.25299)
		(width 0.11684)
		(layer "In2.Cu")
		(net "RST_PERST_OCP_SFF_N")
	)
	(segment
		(start 192.316354 -120.871742)
		(end 192.316354 -120.482868)
		(width 0.11684)
		(layer "In2.Cu")
		(net "RST_PERST_OCP_SFF_N")
	)
	(segment
		(start 206.63535 -123.912376)
		(end 205.88478 -123.912376)
		(width 0.11684)
		(layer "In2.Cu")
		(net "RST_PERST_OCP_SFF_N")
	)
	(segment
		(start 205.88478 -123.912376)
		(end 204.482954 -125.314202)
		(width 0.11684)
		(layer "In2.Cu")
		(net "RST_PERST_OCP_SFF_N")
	)
	(segment
		(start 195.525898 -122.833384)
		(end 194.546728 -121.854214)
		(width 0.11684)
		(layer "In2.Cu")
		(net "RST_PERST_OCP_SFF_N")
	)
	(segment
		(start 193.111628 -121.673874)
		(end 193.111628 -121.202196)
		(width 0.11684)
		(layer "In2.Cu")
		(net "RST_PERST_OCP_SFF_N")
	)
	(segment
		(start 192.943988 -121.034556)
		(end 192.479168 -121.034556)
		(width 0.11684)
		(layer "In2.Cu")
		(net "RST_PERST_OCP_SFF_N")
	)
	(segment
		(start 210.231228 -123.551188)
		(end 209.557874 -123.551188)
		(width 0.11684)
		(layer "In2.Cu")
		(net "RST_PERST_OCP_SFF_N")
	)
	(segment
		(start 210.873848 -122.908568)
		(end 210.231228 -123.551188)
		(width 0.11684)
		(layer "In2.Cu")
		(net "RST_PERST_OCP_SFF_N")
	)
	(segment
		(start 201.55662 -126.323344)
		(end 198.61403 -126.323344)
		(width 0.11684)
		(layer "In2.Cu")
		(net "RST_PERST_OCP_SFF_N")
	)
	(segment
		(start 192.479168 -121.034556)
		(end 192.316354 -120.871742)
		(width 0.11684)
		(layer "In2.Cu")
		(net "RST_PERST_OCP_SFF_N")
	)
	(segment
		(start 194.546728 -121.854214)
		(end 193.291968 -121.854214)
		(width 0.11684)
		(layer "In2.Cu")
		(net "RST_PERST_OCP_SFF_N")
	)
	(segment
		(start 193.111628 -121.202196)
		(end 192.943988 -121.034556)
		(width 0.11684)
		(layer "In2.Cu")
		(net "RST_PERST_OCP_SFF_N")
	)
	(segment
		(start 195.894452 -124.25299)
		(end 195.525898 -123.884436)
		(width 0.11684)
		(layer "In2.Cu")
		(net "RST_PERST_OCP_SFF_N")
	)
	(segment
		(start 195.525898 -123.884436)
		(end 195.525898 -122.833384)
		(width 0.11684)
		(layer "In2.Cu")
		(net "RST_PERST_OCP_SFF_N")
	)
	(segment
		(start 198.61403 -126.323344)
		(end 196.543676 -124.25299)
		(width 0.11684)
		(layer "In2.Cu")
		(net "RST_PERST_OCP_SFF_N")
	)
	(segment
		(start 196.869558 -119.975376)
		(end 196.086476 -119.975376)
		(width 0.10668)
		(layer "F.Cu")
		(net "RST_PERST_M2_0_R_N")
	)
	(segment
		(start 196.086476 -119.975376)
		(end 195.72986 -119.61876)
		(width 0.10668)
		(layer "F.Cu")
		(net "RST_PERST_M2_0_R_N")
	)
	(segment
		(start 190.721996 -118.652798)
		(end 191.111886 -119.042688)
		(width 0.10668)
		(layer "F.Cu")
		(net "RST_PERST_M2_0_R_N")
	)
	(via
		(at 191.111886 -119.042688)
		(size 0.4572)
		(drill 0.254)
		(layers "F.Cu" "B.Cu")
		(net "RST_PERST_M2_0_R_N")
	)
	(via
		(at 195.72986 -119.61876)
		(size 0.508)
		(drill 0.254)
		(layers "F.Cu" "B.Cu")
		(net "RST_PERST_M2_0_R_N")
	)
	(segment
		(start 191.111886 -119.042688)
		(end 191.111886 -119.210074)
		(width 0.11684)
		(layer "In6.Cu")
		(net "RST_PERST_M2_0_R_N")
	)
	(segment
		(start 195.096638 -120.251982)
		(end 195.72986 -119.61876)
		(width 0.11684)
		(layer "In6.Cu")
		(net "RST_PERST_M2_0_R_N")
	)
	(segment
		(start 191.111886 -119.210074)
		(end 191.504316 -119.602504)
		(width 0.11684)
		(layer "In6.Cu")
		(net "RST_PERST_M2_0_R_N")
	)
	(segment
		(start 191.504316 -119.602504)
		(end 191.504316 -120.060212)
		(width 0.11684)
		(layer "In6.Cu")
		(net "RST_PERST_M2_0_R_N")
	)
	(segment
		(start 191.696086 -120.251982)
		(end 195.096638 -120.251982)
		(width 0.11684)
		(layer "In6.Cu")
		(net "RST_PERST_M2_0_R_N")
	)
	(segment
		(start 191.504316 -120.060212)
		(end 191.696086 -120.251982)
		(width 0.11684)
		(layer "In6.Cu")
		(net "RST_PERST_M2_0_R_N")
	)
	(segment
		(start 193.529966 -116.660676)
		(end 194.832986 -116.660676)
		(width 0.10668)
		(layer "F.Cu")
		(net "RST_PERST_E1S_0_R_N")
	)
	(segment
		(start 195.861686 -117.689376)
		(end 196.869558 -117.689376)
		(width 0.10668)
		(layer "F.Cu")
		(net "RST_PERST_E1S_0_R_N")
	)
	(segment
		(start 196.869558 -117.689376)
		(end 196.869558 -118.001034)
		(width 0.10668)
		(layer "F.Cu")
		(net "RST_PERST_E1S_0_R_N")
	)
	(segment
		(start 196.869558 -118.001034)
		(end 197.45579 -118.587266)
		(width 0.10668)
		(layer "F.Cu")
		(net "RST_PERST_E1S_0_R_N")
	)
	(segment
		(start 194.832986 -116.660676)
		(end 195.861686 -117.689376)
		(width 0.10668)
		(layer "F.Cu")
		(net "RST_PERST_E1S_0_R_N")
	)
	(segment
		(start 193.122042 -116.252752)
		(end 193.529966 -116.660676)
		(width 0.10668)
		(layer "F.Cu")
		(net "RST_PERST_E1S_0_R_N")
	)
	(via
		(at 197.45579 -118.587266)
		(size 0.762)
		(drill 0.381)
		(layers "F.Cu" "B.Cu")
		(net "RST_PERST_E1S_0_R_N")
	)
	(segment
		(start 41.33596 -437.148986)
		(end 41.33596 -437.867044)
		(width 0.10668)
		(layer "F.Cu")
		(net "RST_PERST_1_SWB_BUF_R_N")
	)
	(segment
		(start 41.33596 -437.867044)
		(end 41.33596 -438.531)
		(width 0.10668)
		(layer "F.Cu")
		(net "RST_PERST_1_SWB_BUF_R_N")
	)
	(segment
		(start 41.33596 -438.531)
		(end 40.35806 -438.531)
		(width 0.10668)
		(layer "F.Cu")
		(net "RST_PERST_1_SWB_BUF_R_N")
	)
	(via
		(at 41.33596 -437.867044)
		(size 0.508)
		(drill 0.254)
		(layers "F.Cu" "B.Cu")
		(net "RST_PERST_1_SWB_BUF_R_N")
	)
	(segment
		(start 53.510688 -433.172362)
		(end 53.94071 -433.172362)
		(width 0.10668)
		(layer "F.Cu")
		(net "RST_PERST_2_SWB_BUF_N")
	)
	(segment
		(start 53.10505 -433.578)
		(end 53.510688 -433.172362)
		(width 0.10668)
		(layer "F.Cu")
		(net "RST_PERST_2_SWB_BUF_N")
	)
	(via
		(at 53.94071 -433.172362)
		(size 0.508)
		(drill 0.254)
		(layers "F.Cu" "B.Cu")
		(net "RST_PERST_2_SWB_BUF_N")
	)
	(segment
		(start 58.64987 -440.489848)
		(end 57.78881 -440.489848)
		(width 0.11684)
		(layer "In11.Cu")
		(net "RST_PERST_2_SWB_BUF_N")
	)
	(segment
		(start 54.913022 -437.61406)
		(end 54.913022 -434.144674)
		(width 0.11684)
		(layer "In11.Cu")
		(net "RST_PERST_2_SWB_BUF_N")
	)
	(segment
		(start 57.78881 -440.489848)
		(end 54.913022 -437.61406)
		(width 0.11684)
		(layer "In11.Cu")
		(net "RST_PERST_2_SWB_BUF_N")
	)
	(segment
		(start 54.913022 -434.144674)
		(end 53.94071 -433.172362)
		(width 0.11684)
		(layer "In11.Cu")
		(net "RST_PERST_2_SWB_BUF_N")
	)
	(segment
		(start 51.32705 -434.595524)
		(end 51.69154 -434.960014)
		(width 0.10668)
		(layer "F.Cu")
		(net "RST_PERST_2_SWB_BUF_R_N")
	)
	(segment
		(start 51.69154 -434.960014)
		(end 52.38496 -434.960014)
		(width 0.10668)
		(layer "F.Cu")
		(net "RST_PERST_2_SWB_BUF_R_N")
	)
	(segment
		(start 51.32705 -433.578)
		(end 52.30495 -433.578)
		(width 0.10668)
		(layer "F.Cu")
		(net "RST_PERST_2_SWB_BUF_R_N")
	)
	(segment
		(start 51.32705 -433.578)
		(end 51.32705 -434.595524)
		(width 0.10668)
		(layer "F.Cu")
		(net "RST_PERST_2_SWB_BUF_R_N")
	)
	(via
		(at 51.69154 -434.960014)
		(size 0.508)
		(drill 0.254)
		(layers "F.Cu" "B.Cu")
		(net "RST_PERST_2_SWB_BUF_R_N")
	)
	(segment
		(start 42.13606 -438.531)
		(end 42.609008 -438.531)
		(width 0.10668)
		(layer "F.Cu")
		(net "RST_PERST_1_SWB_BUF_N")
	)
	(segment
		(start 42.609008 -438.531)
		(end 43.67403 -439.596022)
		(width 0.10668)
		(layer "F.Cu")
		(net "RST_PERST_1_SWB_BUF_N")
	)
	(via
		(at 43.67403 -439.596022)
		(size 0.508)
		(drill 0.254)
		(layers "F.Cu" "B.Cu")
		(net "RST_PERST_1_SWB_BUF_N")
	)
	(segment
		(start 54.903878 -418.062918)
		(end 57.002934 -415.963862)
		(width 0.10668)
		(layer "B.Cu")
		(net "RST_PERST_1_SWB_BUF_N")
	)
	(segment
		(start 43.67403 -439.596022)
		(end 45.03547 -438.234582)
		(width 0.10668)
		(layer "B.Cu")
		(net "RST_PERST_1_SWB_BUF_N")
	)
	(segment
		(start 52.486306 -438.234582)
		(end 54.903878 -435.81701)
		(width 0.10668)
		(layer "B.Cu")
		(net "RST_PERST_1_SWB_BUF_N")
	)
	(segment
		(start 54.903878 -435.81701)
		(end 54.903878 -418.062918)
		(width 0.10668)
		(layer "B.Cu")
		(net "RST_PERST_1_SWB_BUF_N")
	)
	(segment
		(start 67.771772 -440.06516)
		(end 67.347084 -440.489848)
		(width 0.10668)
		(layer "B.Cu")
		(net "RST_PERST_1_SWB_BUF_N")
	)
	(segment
		(start 66.613532 -415.963862)
		(end 67.771772 -417.122102)
		(width 0.10668)
		(layer "B.Cu")
		(net "RST_PERST_1_SWB_BUF_N")
	)
	(segment
		(start 67.347084 -440.489848)
		(end 66.649854 -440.489848)
		(width 0.10668)
		(layer "B.Cu")
		(net "RST_PERST_1_SWB_BUF_N")
	)
	(segment
		(start 57.002934 -415.963862)
		(end 66.613532 -415.963862)
		(width 0.10668)
		(layer "B.Cu")
		(net "RST_PERST_1_SWB_BUF_N")
	)
	(segment
		(start 45.03547 -438.234582)
		(end 52.486306 -438.234582)
		(width 0.10668)
		(layer "B.Cu")
		(net "RST_PERST_1_SWB_BUF_N")
	)
	(segment
		(start 67.771772 -417.122102)
		(end 67.771772 -440.06516)
		(width 0.10668)
		(layer "B.Cu")
		(net "RST_PERST_1_SWB_BUF_N")
	)
	(segment
		(start 52.38496 -437.642)
		(end 51.72837 -437.642)
		(width 0.10668)
		(layer "F.Cu")
		(net "RST_PERST_0_SWB_BUF_R_N")
	)
	(segment
		(start 51.72837 -437.642)
		(end 51.016916 -437.642)
		(width 0.10668)
		(layer "F.Cu")
		(net "RST_PERST_0_SWB_BUF_R_N")
	)
	(segment
		(start 52.38496 -436.259986)
		(end 52.38496 -437.642)
		(width 0.10668)
		(layer "F.Cu")
		(net "RST_PERST_0_SWB_BUF_R_N")
	)
	(via
		(at 51.72837 -437.642)
		(size 0.508)
		(drill 0.254)
		(layers "F.Cu" "B.Cu")
		(net "RST_PERST_0_SWB_BUF_R_N")
	)
	(segment
		(start 54.539388 -436.79872)
		(end 53.696108 -437.642)
		(width 0.10668)
		(layer "F.Cu")
		(net "RST_PERST_0_SWB_BUF_N")
	)
	(segment
		(start 53.812948 -432.0794)
		(end 54.539388 -432.80584)
		(width 0.10668)
		(layer "F.Cu")
		(net "RST_PERST_0_SWB_BUF_N")
	)
	(segment
		(start 53.696108 -437.642)
		(end 53.18506 -437.642)
		(width 0.10668)
		(layer "F.Cu")
		(net "RST_PERST_0_SWB_BUF_N")
	)
	(segment
		(start 54.539388 -432.80584)
		(end 54.539388 -436.79872)
		(width 0.10668)
		(layer "F.Cu")
		(net "RST_PERST_0_SWB_BUF_N")
	)
	(via
		(at 53.812948 -432.0794)
		(size 0.762)
		(drill 0.254)
		(layers "F.Cu" "B.Cu")
		(net "RST_PERST_0_SWB_BUF_N")
	)
	(segment
		(start 70.40245 -415.242502)
		(end 56.548782 -415.242502)
		(width 0.10668)
		(layer "B.Cu")
		(net "RST_PERST_0_SWB_BUF_N")
	)
	(segment
		(start 54.126892 -431.765456)
		(end 53.812948 -432.0794)
		(width 0.10668)
		(layer "B.Cu")
		(net "RST_PERST_0_SWB_BUF_N")
	)
	(segment
		(start 56.548782 -415.242502)
		(end 54.126892 -417.664392)
		(width 0.10668)
		(layer "B.Cu")
		(net "RST_PERST_0_SWB_BUF_N")
	)
	(segment
		(start 72.649842 -417.489894)
		(end 70.40245 -415.242502)
		(width 0.10668)
		(layer "B.Cu")
		(net "RST_PERST_0_SWB_BUF_N")
	)
	(segment
		(start 54.126892 -417.664392)
		(end 54.126892 -431.765456)
		(width 0.10668)
		(layer "B.Cu")
		(net "RST_PERST_0_SWB_BUF_N")
	)
	(segment
		(start 77.461872 -8.320024)
		(end 77.461872 -7.20471)
		(width 0.10668)
		(layer "F.Cu")
		(net "RST_PERST3_OCP_V3_2_N")
	)
	(segment
		(start 82.822034 -38.63848)
		(end 82.206084 -38.63848)
		(width 0.10668)
		(layer "F.Cu")
		(net "RST_PERST3_OCP_V3_2_N")
	)
	(via
		(at 77.461872 -7.20471)
		(size 0.508)
		(drill 0.254)
		(layers "F.Cu" "B.Cu")
		(net "RST_PERST3_OCP_V3_2_N")
	)
	(via
		(at 82.206084 -38.63848)
		(size 0.508)
		(drill 0.254)
		(layers "F.Cu" "B.Cu")
		(net "RST_PERST3_OCP_V3_2_N")
	)
	(segment
		(start 77.461872 -7.20471)
		(end 78.327504 -6.339078)
		(width 0.11684)
		(layer "In4.Cu")
		(net "RST_PERST3_OCP_V3_2_N")
	)
	(segment
		(start 77.346556 -4.2291)
		(end 70.05193 -4.2291)
		(width 0.11684)
		(layer "In4.Cu")
		(net "RST_PERST3_OCP_V3_2_N")
	)
	(segment
		(start 82.680048 -35.906202)
		(end 81.741264 -36.844986)
		(width 0.11684)
		(layer "In4.Cu")
		(net "RST_PERST3_OCP_V3_2_N")
	)
	(segment
		(start 74.292206 -16.309594)
		(end 75.45832 -15.14348)
		(width 0.11684)
		(layer "In4.Cu")
		(net "RST_PERST3_OCP_V3_2_N")
	)
	(segment
		(start 68.945506 -11.626596)
		(end 68.945506 -14.318234)
		(width 0.11684)
		(layer "In4.Cu")
		(net "RST_PERST3_OCP_V3_2_N")
	)
	(segment
		(start 69.66839 -9.791954)
		(end 69.66839 -10.903712)
		(width 0.11684)
		(layer "In4.Cu")
		(net "RST_PERST3_OCP_V3_2_N")
	)
	(segment
		(start 69.66839 -10.903712)
		(end 68.945506 -11.626596)
		(width 0.11684)
		(layer "In4.Cu")
		(net "RST_PERST3_OCP_V3_2_N")
	)
	(segment
		(start 82.680048 -17.92732)
		(end 82.680048 -35.906202)
		(width 0.11684)
		(layer "In4.Cu")
		(net "RST_PERST3_OCP_V3_2_N")
	)
	(segment
		(start 70.936866 -16.309594)
		(end 74.292206 -16.309594)
		(width 0.11684)
		(layer "In4.Cu")
		(net "RST_PERST3_OCP_V3_2_N")
	)
	(segment
		(start 78.327504 -5.210048)
		(end 77.346556 -4.2291)
		(width 0.11684)
		(layer "In4.Cu")
		(net "RST_PERST3_OCP_V3_2_N")
	)
	(segment
		(start 79.896208 -15.14348)
		(end 82.680048 -17.92732)
		(width 0.11684)
		(layer "In4.Cu")
		(net "RST_PERST3_OCP_V3_2_N")
	)
	(segment
		(start 68.945506 -14.318234)
		(end 70.936866 -16.309594)
		(width 0.11684)
		(layer "In4.Cu")
		(net "RST_PERST3_OCP_V3_2_N")
	)
	(segment
		(start 78.327504 -6.339078)
		(end 78.327504 -5.210048)
		(width 0.11684)
		(layer "In4.Cu")
		(net "RST_PERST3_OCP_V3_2_N")
	)
	(segment
		(start 70.05193 -4.2291)
		(end 68.100194 -6.180836)
		(width 0.11684)
		(layer "In4.Cu")
		(net "RST_PERST3_OCP_V3_2_N")
	)
	(segment
		(start 68.100194 -8.223758)
		(end 69.66839 -9.791954)
		(width 0.11684)
		(layer "In4.Cu")
		(net "RST_PERST3_OCP_V3_2_N")
	)
	(segment
		(start 75.45832 -15.14348)
		(end 79.896208 -15.14348)
		(width 0.11684)
		(layer "In4.Cu")
		(net "RST_PERST3_OCP_V3_2_N")
	)
	(segment
		(start 81.741264 -38.17366)
		(end 82.206084 -38.63848)
		(width 0.11684)
		(layer "In4.Cu")
		(net "RST_PERST3_OCP_V3_2_N")
	)
	(segment
		(start 81.741264 -36.844986)
		(end 81.741264 -38.17366)
		(width 0.11684)
		(layer "In4.Cu")
		(net "RST_PERST3_OCP_V3_2_N")
	)
	(segment
		(start 68.100194 -6.180836)
		(end 68.100194 -8.223758)
		(width 0.11684)
		(layer "In4.Cu")
		(net "RST_PERST3_OCP_V3_2_N")
	)
	(segment
		(start 451.961758 -5.916168)
		(end 451.641464 -5.595874)
		(width 0.10668)
		(layer "F.Cu")
		(net "RST_PERST3_OCP_SFF_N")
	)
	(segment
		(start 451.961758 -8.320024)
		(end 451.961758 -5.916168)
		(width 0.10668)
		(layer "F.Cu")
		(net "RST_PERST3_OCP_SFF_N")
	)
	(segment
		(start 214.31885 -122.460512)
		(end 214.988394 -122.460512)
		(width 0.10668)
		(layer "F.Cu")
		(net "RST_PERST3_OCP_SFF_N")
	)
	(segment
		(start 451.641464 -5.595874)
		(end 451.08368 -5.595874)
		(width 0.10668)
		(layer "F.Cu")
		(net "RST_PERST3_OCP_SFF_N")
	)
	(via
		(at 214.988394 -122.460512)
		(size 0.508)
		(drill 0.254)
		(layers "F.Cu" "B.Cu")
		(net "RST_PERST3_OCP_SFF_N")
	)
	(via
		(at 451.08368 -5.595874)
		(size 0.508)
		(drill 0.254)
		(layers "F.Cu" "B.Cu")
		(net "RST_PERST3_OCP_SFF_N")
	)
	(via
		(at 199.066404 -83.430618)
		(size 0.508)
		(drill 0.254)
		(layers "F.Cu" "B.Cu")
		(net "RST_PERST3_OCP_SFF_N")
	)
	(segment
		(start 214.988394 -122.460512)
		(end 214.131906 -121.604024)
		(width 0.11684)
		(layer "In11.Cu")
		(net "RST_PERST3_OCP_SFF_N")
	)
	(segment
		(start 213.24951 -113.912142)
		(end 215.12022 -112.041432)
		(width 0.11684)
		(layer "In11.Cu")
		(net "RST_PERST3_OCP_SFF_N")
	)
	(segment
		(start 214.943182 -93.233494)
		(end 207.202786 -85.493098)
		(width 0.11684)
		(layer "In11.Cu")
		(net "RST_PERST3_OCP_SFF_N")
	)
	(segment
		(start 214.387684 -106.160316)
		(end 214.943182 -105.604818)
		(width 0.11684)
		(layer "In11.Cu")
		(net "RST_PERST3_OCP_SFF_N")
	)
	(segment
		(start 214.943182 -105.604818)
		(end 214.943182 -93.233494)
		(width 0.11684)
		(layer "In11.Cu")
		(net "RST_PERST3_OCP_SFF_N")
	)
	(segment
		(start 215.12022 -110.85068)
		(end 214.387684 -110.118144)
		(width 0.11684)
		(layer "In11.Cu")
		(net "RST_PERST3_OCP_SFF_N")
	)
	(segment
		(start 202.381104 -84.822284)
		(end 200.45807 -84.822284)
		(width 0.11684)
		(layer "In11.Cu")
		(net "RST_PERST3_OCP_SFF_N")
	)
	(segment
		(start 207.202786 -85.493098)
		(end 203.051918 -85.493098)
		(width 0.11684)
		(layer "In11.Cu")
		(net "RST_PERST3_OCP_SFF_N")
	)
	(segment
		(start 200.45807 -84.822284)
		(end 199.066404 -83.430618)
		(width 0.11684)
		(layer "In11.Cu")
		(net "RST_PERST3_OCP_SFF_N")
	)
	(segment
		(start 215.12022 -112.041432)
		(end 215.12022 -110.85068)
		(width 0.11684)
		(layer "In11.Cu")
		(net "RST_PERST3_OCP_SFF_N")
	)
	(segment
		(start 214.131906 -121.604024)
		(end 214.131906 -118.153942)
		(width 0.11684)
		(layer "In11.Cu")
		(net "RST_PERST3_OCP_SFF_N")
	)
	(segment
		(start 203.051918 -85.493098)
		(end 202.381104 -84.822284)
		(width 0.11684)
		(layer "In11.Cu")
		(net "RST_PERST3_OCP_SFF_N")
	)
	(segment
		(start 214.131906 -118.153942)
		(end 213.24951 -117.271546)
		(width 0.11684)
		(layer "In11.Cu")
		(net "RST_PERST3_OCP_SFF_N")
	)
	(segment
		(start 213.24951 -117.271546)
		(end 213.24951 -113.912142)
		(width 0.11684)
		(layer "In11.Cu")
		(net "RST_PERST3_OCP_SFF_N")
	)
	(segment
		(start 214.387684 -110.118144)
		(end 214.387684 -106.160316)
		(width 0.11684)
		(layer "In11.Cu")
		(net "RST_PERST3_OCP_SFF_N")
	)
	(segment
		(start 422.557956 -9.091422)
		(end 423.624502 -8.024876)
		(width 0.11684)
		(layer "In15.Cu")
		(net "RST_PERST3_OCP_SFF_N")
	)
	(segment
		(start 199.066404 -83.430618)
		(end 199.601074 -82.895948)
		(width 0.11684)
		(layer "In15.Cu")
		(net "RST_PERST3_OCP_SFF_N")
	)
	(segment
		(start 378.053092 -15.178024)
		(end 420.630604 -15.178024)
		(width 0.11684)
		(layer "In15.Cu")
		(net "RST_PERST3_OCP_SFF_N")
	)
	(segment
		(start 322.956936 -24.683466)
		(end 322.956936 -19.745706)
		(width 0.11684)
		(layer "In15.Cu")
		(net "RST_PERST3_OCP_SFF_N")
	)
	(segment
		(start 201.779632 -82.895948)
		(end 202.784456 -83.900772)
		(width 0.11684)
		(layer "In15.Cu")
		(net "RST_PERST3_OCP_SFF_N")
	)
	(segment
		(start 423.624502 -8.024876)
		(end 448.654678 -8.024876)
		(width 0.11684)
		(layer "In15.Cu")
		(net "RST_PERST3_OCP_SFF_N")
	)
	(segment
		(start 221.869 -80.899)
		(end 222.25 -81.28)
		(width 0.11684)
		(layer "In15.Cu")
		(net "RST_PERST3_OCP_SFF_N")
	)
	(segment
		(start 450.569838 -6.664706)
		(end 450.569838 -6.109716)
		(width 0.11684)
		(layer "In15.Cu")
		(net "RST_PERST3_OCP_SFF_N")
	)
	(segment
		(start 275.797518 -71.100188)
		(end 282.77439 -64.123316)
		(width 0.11684)
		(layer "In15.Cu")
		(net "RST_PERST3_OCP_SFF_N")
	)
	(segment
		(start 202.784456 -83.900772)
		(end 203.269088 -83.900772)
		(width 0.11684)
		(layer "In15.Cu")
		(net "RST_PERST3_OCP_SFF_N")
	)
	(segment
		(start 260.077966 -71.100188)
		(end 275.797518 -71.100188)
		(width 0.11684)
		(layer "In15.Cu")
		(net "RST_PERST3_OCP_SFF_N")
	)
	(segment
		(start 449.761102 -6.918452)
		(end 450.316092 -6.918452)
		(width 0.11684)
		(layer "In15.Cu")
		(net "RST_PERST3_OCP_SFF_N")
	)
	(segment
		(start 450.316092 -6.918452)
		(end 450.569838 -6.664706)
		(width 0.11684)
		(layer "In15.Cu")
		(net "RST_PERST3_OCP_SFF_N")
	)
	(segment
		(start 232.465118 -73.973944)
		(end 257.20421 -73.973944)
		(width 0.11684)
		(layer "In15.Cu")
		(net "RST_PERST3_OCP_SFF_N")
	)
	(segment
		(start 319.346834 -28.293568)
		(end 322.956936 -24.683466)
		(width 0.11684)
		(layer "In15.Cu")
		(net "RST_PERST3_OCP_SFF_N")
	)
	(segment
		(start 225.159062 -81.28)
		(end 232.465118 -73.973944)
		(width 0.11684)
		(layer "In15.Cu")
		(net "RST_PERST3_OCP_SFF_N")
	)
	(segment
		(start 322.956936 -19.745706)
		(end 327.524618 -15.178024)
		(width 0.11684)
		(layer "In15.Cu")
		(net "RST_PERST3_OCP_SFF_N")
	)
	(segment
		(start 450.569838 -6.109716)
		(end 451.08368 -5.595874)
		(width 0.11684)
		(layer "In15.Cu")
		(net "RST_PERST3_OCP_SFF_N")
	)
	(segment
		(start 199.601074 -82.895948)
		(end 201.779632 -82.895948)
		(width 0.11684)
		(layer "In15.Cu")
		(net "RST_PERST3_OCP_SFF_N")
	)
	(segment
		(start 327.524618 -15.178024)
		(end 355.147626 -15.178024)
		(width 0.11684)
		(layer "In15.Cu")
		(net "RST_PERST3_OCP_SFF_N")
	)
	(segment
		(start 222.25 -81.28)
		(end 225.159062 -81.28)
		(width 0.11684)
		(layer "In15.Cu")
		(net "RST_PERST3_OCP_SFF_N")
	)
	(segment
		(start 375.134378 -18.096738)
		(end 378.053092 -15.178024)
		(width 0.11684)
		(layer "In15.Cu")
		(net "RST_PERST3_OCP_SFF_N")
	)
	(segment
		(start 206.27086 -80.899)
		(end 221.869 -80.899)
		(width 0.11684)
		(layer "In15.Cu")
		(net "RST_PERST3_OCP_SFF_N")
	)
	(segment
		(start 448.654678 -8.024876)
		(end 449.761102 -6.918452)
		(width 0.11684)
		(layer "In15.Cu")
		(net "RST_PERST3_OCP_SFF_N")
	)
	(segment
		(start 282.77439 -49.915318)
		(end 304.39614 -28.293568)
		(width 0.11684)
		(layer "In15.Cu")
		(net "RST_PERST3_OCP_SFF_N")
	)
	(segment
		(start 422.557956 -13.250672)
		(end 422.557956 -9.091422)
		(width 0.11684)
		(layer "In15.Cu")
		(net "RST_PERST3_OCP_SFF_N")
	)
	(segment
		(start 358.06634 -18.096738)
		(end 375.134378 -18.096738)
		(width 0.11684)
		(layer "In15.Cu")
		(net "RST_PERST3_OCP_SFF_N")
	)
	(segment
		(start 257.20421 -73.973944)
		(end 260.077966 -71.100188)
		(width 0.11684)
		(layer "In15.Cu")
		(net "RST_PERST3_OCP_SFF_N")
	)
	(segment
		(start 355.147626 -15.178024)
		(end 358.06634 -18.096738)
		(width 0.11684)
		(layer "In15.Cu")
		(net "RST_PERST3_OCP_SFF_N")
	)
	(segment
		(start 203.269088 -83.900772)
		(end 206.27086 -80.899)
		(width 0.11684)
		(layer "In15.Cu")
		(net "RST_PERST3_OCP_SFF_N")
	)
	(segment
		(start 420.630604 -15.178024)
		(end 422.557956 -13.250672)
		(width 0.11684)
		(layer "In15.Cu")
		(net "RST_PERST3_OCP_SFF_N")
	)
	(segment
		(start 282.77439 -64.123316)
		(end 282.77439 -49.915318)
		(width 0.11684)
		(layer "In15.Cu")
		(net "RST_PERST3_OCP_SFF_N")
	)
	(segment
		(start 304.39614 -28.293568)
		(end 319.346834 -28.293568)
		(width 0.11684)
		(layer "In15.Cu")
		(net "RST_PERST3_OCP_SFF_N")
	)
	(segment
		(start 82.822034 -37.36848)
		(end 82.206084 -37.36848)
		(width 0.10668)
		(layer "F.Cu")
		(net "RST_PERST2_OCP_V3_2_N")
	)
	(segment
		(start 78.062074 -8.320024)
		(end 78.062074 -6.87451)
		(width 0.10668)
		(layer "F.Cu")
		(net "RST_PERST2_OCP_V3_2_N")
	)
	(segment
		(start 78.062074 -6.87451)
		(end 77.450442 -6.262878)
		(width 0.10668)
		(layer "F.Cu")
		(net "RST_PERST2_OCP_V3_2_N")
	)
	(via
		(at 82.206084 -37.36848)
		(size 0.508)
		(drill 0.254)
		(layers "F.Cu" "B.Cu")
		(net "RST_PERST2_OCP_V3_2_N")
	)
	(via
		(at 77.450442 -6.262878)
		(size 0.508)
		(drill 0.254)
		(layers "F.Cu" "B.Cu")
		(net "RST_PERST2_OCP_V3_2_N")
	)
	(segment
		(start 77.653642 -5.489194)
		(end 76.815188 -4.65074)
		(width 0.11684)
		(layer "In4.Cu")
		(net "RST_PERST2_OCP_V3_2_N")
	)
	(segment
		(start 83.135978 -36.438586)
		(end 82.206084 -37.36848)
		(width 0.11684)
		(layer "In4.Cu")
		(net "RST_PERST2_OCP_V3_2_N")
	)
	(segment
		(start 70.12432 -11.092688)
		(end 69.401436 -11.815572)
		(width 0.11684)
		(layer "In4.Cu")
		(net "RST_PERST2_OCP_V3_2_N")
	)
	(segment
		(start 69.401436 -11.815572)
		(end 69.401436 -14.129258)
		(width 0.11684)
		(layer "In4.Cu")
		(net "RST_PERST2_OCP_V3_2_N")
	)
	(segment
		(start 71.125842 -15.853664)
		(end 74.138536 -15.853664)
		(width 0.11684)
		(layer "In4.Cu")
		(net "RST_PERST2_OCP_V3_2_N")
	)
	(segment
		(start 68.556124 -6.677914)
		(end 68.556124 -8.034782)
		(width 0.11684)
		(layer "In4.Cu")
		(net "RST_PERST2_OCP_V3_2_N")
	)
	(segment
		(start 75.27036 -14.72184)
		(end 80.071214 -14.72184)
		(width 0.11684)
		(layer "In4.Cu")
		(net "RST_PERST2_OCP_V3_2_N")
	)
	(segment
		(start 69.401436 -14.129258)
		(end 71.125842 -15.853664)
		(width 0.11684)
		(layer "In4.Cu")
		(net "RST_PERST2_OCP_V3_2_N")
	)
	(segment
		(start 74.138536 -15.853664)
		(end 75.27036 -14.72184)
		(width 0.11684)
		(layer "In4.Cu")
		(net "RST_PERST2_OCP_V3_2_N")
	)
	(segment
		(start 76.815188 -4.65074)
		(end 70.583298 -4.65074)
		(width 0.11684)
		(layer "In4.Cu")
		(net "RST_PERST2_OCP_V3_2_N")
	)
	(segment
		(start 70.12432 -9.602978)
		(end 70.12432 -11.092688)
		(width 0.11684)
		(layer "In4.Cu")
		(net "RST_PERST2_OCP_V3_2_N")
	)
	(segment
		(start 80.071214 -14.72184)
		(end 83.135978 -17.786604)
		(width 0.11684)
		(layer "In4.Cu")
		(net "RST_PERST2_OCP_V3_2_N")
	)
	(segment
		(start 83.135978 -17.786604)
		(end 83.135978 -36.438586)
		(width 0.11684)
		(layer "In4.Cu")
		(net "RST_PERST2_OCP_V3_2_N")
	)
	(segment
		(start 70.583298 -4.65074)
		(end 68.556124 -6.677914)
		(width 0.11684)
		(layer "In4.Cu")
		(net "RST_PERST2_OCP_V3_2_N")
	)
	(segment
		(start 68.556124 -8.034782)
		(end 70.12432 -9.602978)
		(width 0.11684)
		(layer "In4.Cu")
		(net "RST_PERST2_OCP_V3_2_N")
	)
	(segment
		(start 77.450442 -6.262878)
		(end 77.653642 -6.059678)
		(width 0.11684)
		(layer "In4.Cu")
		(net "RST_PERST2_OCP_V3_2_N")
	)
	(segment
		(start 77.653642 -6.059678)
		(end 77.653642 -5.489194)
		(width 0.11684)
		(layer "In4.Cu")
		(net "RST_PERST2_OCP_V3_2_N")
	)
	(segment
		(start 453.162924 -9.537192)
		(end 454.107804 -9.537192)
		(width 0.10668)
		(layer "F.Cu")
		(net "RST_PERST2_OCP_SFF_N")
	)
	(segment
		(start 214.319104 -124.604018)
		(end 215.18372 -124.604018)
		(width 0.10668)
		(layer "F.Cu")
		(net "RST_PERST2_OCP_SFF_N")
	)
	(segment
		(start 452.56196 -8.320024)
		(end 452.56196 -8.936228)
		(width 0.10668)
		(layer "F.Cu")
		(net "RST_PERST2_OCP_SFF_N")
	)
	(segment
		(start 452.56196 -8.936228)
		(end 453.162924 -9.537192)
		(width 0.10668)
		(layer "F.Cu")
		(net "RST_PERST2_OCP_SFF_N")
	)
	(segment
		(start 215.18372 -124.604018)
		(end 215.269572 -124.68987)
		(width 0.10668)
		(layer "F.Cu")
		(net "RST_PERST2_OCP_SFF_N")
	)
	(via
		(at 201.098404 -83.430618)
		(size 0.508)
		(drill 0.254)
		(layers "F.Cu" "B.Cu")
		(net "RST_PERST2_OCP_SFF_N")
	)
	(via
		(at 454.107804 -9.537192)
		(size 0.508)
		(drill 0.254)
		(layers "F.Cu" "B.Cu")
		(net "RST_PERST2_OCP_SFF_N")
	)
	(via
		(at 215.269572 -124.68987)
		(size 0.508)
		(drill 0.254)
		(layers "F.Cu" "B.Cu")
		(net "RST_PERST2_OCP_SFF_N")
	)
	(segment
		(start 216.513156 -93.526102)
		(end 216.513156 -102.051358)
		(width 0.11684)
		(layer "In11.Cu")
		(net "RST_PERST2_OCP_SFF_N")
	)
	(segment
		(start 207.539082 -84.552028)
		(end 216.513156 -93.526102)
		(width 0.11684)
		(layer "In11.Cu")
		(net "RST_PERST2_OCP_SFF_N")
	)
	(segment
		(start 216.513156 -102.051358)
		(end 215.786462 -102.778052)
		(width 0.11684)
		(layer "In11.Cu")
		(net "RST_PERST2_OCP_SFF_N")
	)
	(segment
		(start 216.004648 -105.53192)
		(end 216.004648 -115.32108)
		(width 0.11684)
		(layer "In11.Cu")
		(net "RST_PERST2_OCP_SFF_N")
	)
	(segment
		(start 215.786462 -105.313734)
		(end 216.004648 -105.53192)
		(width 0.11684)
		(layer "In11.Cu")
		(net "RST_PERST2_OCP_SFF_N")
	)
	(segment
		(start 201.098404 -83.430618)
		(end 202.27798 -83.430618)
		(width 0.11684)
		(layer "In11.Cu")
		(net "RST_PERST2_OCP_SFF_N")
	)
	(segment
		(start 215.409272 -115.916456)
		(end 215.409272 -120.251474)
		(width 0.11684)
		(layer "In11.Cu")
		(net "RST_PERST2_OCP_SFF_N")
	)
	(segment
		(start 216.004648 -115.32108)
		(end 215.409272 -115.916456)
		(width 0.11684)
		(layer "In11.Cu")
		(net "RST_PERST2_OCP_SFF_N")
	)
	(segment
		(start 203.39939 -84.552028)
		(end 207.539082 -84.552028)
		(width 0.11684)
		(layer "In11.Cu")
		(net "RST_PERST2_OCP_SFF_N")
	)
	(segment
		(start 216.004648 -123.954794)
		(end 215.269572 -124.68987)
		(width 0.11684)
		(layer "In11.Cu")
		(net "RST_PERST2_OCP_SFF_N")
	)
	(segment
		(start 215.409272 -120.251474)
		(end 216.004648 -120.84685)
		(width 0.11684)
		(layer "In11.Cu")
		(net "RST_PERST2_OCP_SFF_N")
	)
	(segment
		(start 202.27798 -83.430618)
		(end 203.39939 -84.552028)
		(width 0.11684)
		(layer "In11.Cu")
		(net "RST_PERST2_OCP_SFF_N")
	)
	(segment
		(start 216.004648 -120.84685)
		(end 216.004648 -123.954794)
		(width 0.11684)
		(layer "In11.Cu")
		(net "RST_PERST2_OCP_SFF_N")
	)
	(segment
		(start 215.786462 -102.778052)
		(end 215.786462 -105.313734)
		(width 0.11684)
		(layer "In11.Cu")
		(net "RST_PERST2_OCP_SFF_N")
	)
	(segment
		(start 208.556098 -81.407)
		(end 221.488 -81.407)
		(width 0.11684)
		(layer "In15.Cu")
		(net "RST_PERST2_OCP_SFF_N")
	)
	(segment
		(start 323.378576 -19.920458)
		(end 327.69937 -15.599664)
		(width 0.11684)
		(layer "In15.Cu")
		(net "RST_PERST2_OCP_SFF_N")
	)
	(segment
		(start 225.289618 -81.745836)
		(end 232.63987 -74.395584)
		(width 0.11684)
		(layer "In15.Cu")
		(net "RST_PERST2_OCP_SFF_N")
	)
	(segment
		(start 201.098404 -83.430618)
		(end 202.064366 -84.39658)
		(width 0.11684)
		(layer "In15.Cu")
		(net "RST_PERST2_OCP_SFF_N")
	)
	(segment
		(start 422.979596 -9.266174)
		(end 423.799254 -8.446516)
		(width 0.11684)
		(layer "In15.Cu")
		(net "RST_PERST2_OCP_SFF_N")
	)
	(segment
		(start 375.30913 -18.518378)
		(end 378.227844 -15.599664)
		(width 0.11684)
		(layer "In15.Cu")
		(net "RST_PERST2_OCP_SFF_N")
	)
	(segment
		(start 357.891588 -18.518378)
		(end 375.30913 -18.518378)
		(width 0.11684)
		(layer "In15.Cu")
		(net "RST_PERST2_OCP_SFF_N")
	)
	(segment
		(start 422.979596 -13.448284)
		(end 422.979596 -9.266174)
		(width 0.11684)
		(layer "In15.Cu")
		(net "RST_PERST2_OCP_SFF_N")
	)
	(segment
		(start 304.56759 -28.71851)
		(end 319.518284 -28.71851)
		(width 0.11684)
		(layer "In15.Cu")
		(net "RST_PERST2_OCP_SFF_N")
	)
	(segment
		(start 221.488 -81.407)
		(end 221.826836 -81.745836)
		(width 0.11684)
		(layer "In15.Cu")
		(net "RST_PERST2_OCP_SFF_N")
	)
	(segment
		(start 420.828216 -15.599664)
		(end 422.979596 -13.448284)
		(width 0.11684)
		(layer "In15.Cu")
		(net "RST_PERST2_OCP_SFF_N")
	)
	(segment
		(start 319.518284 -28.71851)
		(end 323.378576 -24.858218)
		(width 0.11684)
		(layer "In15.Cu")
		(net "RST_PERST2_OCP_SFF_N")
	)
	(segment
		(start 257.378962 -74.395584)
		(end 260.252718 -71.521828)
		(width 0.11684)
		(layer "In15.Cu")
		(net "RST_PERST2_OCP_SFF_N")
	)
	(segment
		(start 354.972874 -15.599664)
		(end 357.891588 -18.518378)
		(width 0.11684)
		(layer "In15.Cu")
		(net "RST_PERST2_OCP_SFF_N")
	)
	(segment
		(start 453.017128 -8.446516)
		(end 454.107804 -9.537192)
		(width 0.11684)
		(layer "In15.Cu")
		(net "RST_PERST2_OCP_SFF_N")
	)
	(segment
		(start 221.826836 -81.745836)
		(end 225.289618 -81.745836)
		(width 0.11684)
		(layer "In15.Cu")
		(net "RST_PERST2_OCP_SFF_N")
	)
	(segment
		(start 327.69937 -15.599664)
		(end 354.972874 -15.599664)
		(width 0.11684)
		(layer "In15.Cu")
		(net "RST_PERST2_OCP_SFF_N")
	)
	(segment
		(start 275.97227 -71.521828)
		(end 283.19603 -64.298068)
		(width 0.11684)
		(layer "In15.Cu")
		(net "RST_PERST2_OCP_SFF_N")
	)
	(segment
		(start 423.799254 -8.446516)
		(end 453.017128 -8.446516)
		(width 0.11684)
		(layer "In15.Cu")
		(net "RST_PERST2_OCP_SFF_N")
	)
	(segment
		(start 205.566518 -84.39658)
		(end 208.556098 -81.407)
		(width 0.11684)
		(layer "In15.Cu")
		(net "RST_PERST2_OCP_SFF_N")
	)
	(segment
		(start 323.378576 -24.858218)
		(end 323.378576 -19.920458)
		(width 0.11684)
		(layer "In15.Cu")
		(net "RST_PERST2_OCP_SFF_N")
	)
	(segment
		(start 202.064366 -84.39658)
		(end 205.566518 -84.39658)
		(width 0.11684)
		(layer "In15.Cu")
		(net "RST_PERST2_OCP_SFF_N")
	)
	(segment
		(start 283.19603 -64.298068)
		(end 283.19603 -50.09007)
		(width 0.11684)
		(layer "In15.Cu")
		(net "RST_PERST2_OCP_SFF_N")
	)
	(segment
		(start 378.227844 -15.599664)
		(end 420.828216 -15.599664)
		(width 0.11684)
		(layer "In15.Cu")
		(net "RST_PERST2_OCP_SFF_N")
	)
	(segment
		(start 283.19603 -50.09007)
		(end 304.56759 -28.71851)
		(width 0.11684)
		(layer "In15.Cu")
		(net "RST_PERST2_OCP_SFF_N")
	)
	(segment
		(start 260.252718 -71.521828)
		(end 275.97227 -71.521828)
		(width 0.11684)
		(layer "In15.Cu")
		(net "RST_PERST2_OCP_SFF_N")
	)
	(segment
		(start 232.63987 -74.395584)
		(end 257.378962 -74.395584)
		(width 0.11684)
		(layer "In15.Cu")
		(net "RST_PERST2_OCP_SFF_N")
	)
	(segment
		(start 59.867038 -8.320024)
		(end 59.867038 -5.48259)
		(width 0.10668)
		(layer "F.Cu")
		(net "RST_PERST1_OCP_V3_2_N")
	)
	(segment
		(start 82.822034 -39.65448)
		(end 82.206084 -39.65448)
		(width 0.10668)
		(layer "F.Cu")
		(net "RST_PERST1_OCP_V3_2_N")
	)
	(via
		(at 82.206084 -39.65448)
		(size 0.508)
		(drill 0.254)
		(layers "F.Cu" "B.Cu")
		(net "RST_PERST1_OCP_V3_2_N")
	)
	(via
		(at 59.867038 -5.48259)
		(size 0.508)
		(drill 0.254)
		(layers "F.Cu" "B.Cu")
		(net "RST_PERST1_OCP_V3_2_N")
	)
	(segment
		(start 62.360302 -18.0467)
		(end 62.360302 -16.457676)
		(width 0.11684)
		(layer "In4.Cu")
		(net "RST_PERST1_OCP_V3_2_N")
	)
	(segment
		(start 60.0964 -32.6644)
		(end 61.516768 -31.244032)
		(width 0.11684)
		(layer "In4.Cu")
		(net "RST_PERST1_OCP_V3_2_N")
	)
	(segment
		(start 60.630054 -34.455862)
		(end 60.630054 -33.96107)
		(width 0.11684)
		(layer "In4.Cu")
		(net "RST_PERST1_OCP_V3_2_N")
	)
	(segment
		(start 64.1604 -38.7604)
		(end 63.473076 -38.073076)
		(width 0.11684)
		(layer "In4.Cu")
		(net "RST_PERST1_OCP_V3_2_N")
	)
	(segment
		(start 61.516768 -19.188938)
		(end 61.89472 -18.810986)
		(width 0.11684)
		(layer "In4.Cu")
		(net "RST_PERST1_OCP_V3_2_N")
	)
	(segment
		(start 60.869576 -34.695384)
		(end 60.630054 -34.455862)
		(width 0.11684)
		(layer "In4.Cu")
		(net "RST_PERST1_OCP_V3_2_N")
	)
	(segment
		(start 60.630054 -33.96107)
		(end 60.0964 -33.427416)
		(width 0.11684)
		(layer "In4.Cu")
		(net "RST_PERST1_OCP_V3_2_N")
	)
	(segment
		(start 62.003432 -7.431532)
		(end 60.05449 -5.48259)
		(width 0.11684)
		(layer "In4.Cu")
		(net "RST_PERST1_OCP_V3_2_N")
	)
	(segment
		(start 62.39764 -35.410648)
		(end 61.682376 -34.695384)
		(width 0.11684)
		(layer "In4.Cu")
		(net "RST_PERST1_OCP_V3_2_N")
	)
	(segment
		(start 63.081916 -38.073076)
		(end 62.39764 -37.3888)
		(width 0.11684)
		(layer "In4.Cu")
		(net "RST_PERST1_OCP_V3_2_N")
	)
	(segment
		(start 61.516768 -14.829536)
		(end 62.003432 -14.342872)
		(width 0.11684)
		(layer "In4.Cu")
		(net "RST_PERST1_OCP_V3_2_N")
	)
	(segment
		(start 61.89472 -18.810986)
		(end 61.89472 -18.512282)
		(width 0.11684)
		(layer "In4.Cu")
		(net "RST_PERST1_OCP_V3_2_N")
	)
	(segment
		(start 79.535782 -41.529)
		(end 65.306702 -41.529)
		(width 0.11684)
		(layer "In4.Cu")
		(net "RST_PERST1_OCP_V3_2_N")
	)
	(segment
		(start 62.39764 -37.3888)
		(end 62.39764 -35.410648)
		(width 0.11684)
		(layer "In4.Cu")
		(net "RST_PERST1_OCP_V3_2_N")
	)
	(segment
		(start 60.05449 -5.48259)
		(end 59.867038 -5.48259)
		(width 0.11684)
		(layer "In4.Cu")
		(net "RST_PERST1_OCP_V3_2_N")
	)
	(segment
		(start 61.89472 -18.512282)
		(end 62.360302 -18.0467)
		(width 0.11684)
		(layer "In4.Cu")
		(net "RST_PERST1_OCP_V3_2_N")
	)
	(segment
		(start 61.516768 -15.614142)
		(end 61.516768 -14.829536)
		(width 0.11684)
		(layer "In4.Cu")
		(net "RST_PERST1_OCP_V3_2_N")
	)
	(segment
		(start 62.003432 -14.342872)
		(end 62.003432 -7.431532)
		(width 0.11684)
		(layer "In4.Cu")
		(net "RST_PERST1_OCP_V3_2_N")
	)
	(segment
		(start 61.516768 -31.244032)
		(end 61.516768 -19.188938)
		(width 0.11684)
		(layer "In4.Cu")
		(net "RST_PERST1_OCP_V3_2_N")
	)
	(segment
		(start 61.682376 -34.695384)
		(end 60.869576 -34.695384)
		(width 0.11684)
		(layer "In4.Cu")
		(net "RST_PERST1_OCP_V3_2_N")
	)
	(segment
		(start 82.206084 -39.65448)
		(end 81.410302 -39.65448)
		(width 0.11684)
		(layer "In4.Cu")
		(net "RST_PERST1_OCP_V3_2_N")
	)
	(segment
		(start 63.473076 -38.073076)
		(end 63.081916 -38.073076)
		(width 0.11684)
		(layer "In4.Cu")
		(net "RST_PERST1_OCP_V3_2_N")
	)
	(segment
		(start 60.0964 -33.427416)
		(end 60.0964 -32.6644)
		(width 0.11684)
		(layer "In4.Cu")
		(net "RST_PERST1_OCP_V3_2_N")
	)
	(segment
		(start 64.1604 -40.382698)
		(end 64.1604 -38.7604)
		(width 0.11684)
		(layer "In4.Cu")
		(net "RST_PERST1_OCP_V3_2_N")
	)
	(segment
		(start 62.360302 -16.457676)
		(end 61.516768 -15.614142)
		(width 0.11684)
		(layer "In4.Cu")
		(net "RST_PERST1_OCP_V3_2_N")
	)
	(segment
		(start 81.410302 -39.65448)
		(end 79.535782 -41.529)
		(width 0.11684)
		(layer "In4.Cu")
		(net "RST_PERST1_OCP_V3_2_N")
	)
	(segment
		(start 65.306702 -41.529)
		(end 64.1604 -40.382698)
		(width 0.11684)
		(layer "In4.Cu")
		(net "RST_PERST1_OCP_V3_2_N")
	)
	(segment
		(start 214.289894 -125.643894)
		(end 214.910416 -125.643894)
		(width 0.10668)
		(layer "F.Cu")
		(net "RST_PERST1_OCP_SFF_N")
	)
	(segment
		(start 434.366924 -5.805678)
		(end 435.096158 -5.076444)
		(width 0.10668)
		(layer "F.Cu")
		(net "RST_PERST1_OCP_SFF_N")
	)
	(segment
		(start 434.366924 -8.320024)
		(end 434.366924 -5.805678)
		(width 0.10668)
		(layer "F.Cu")
		(net "RST_PERST1_OCP_SFF_N")
	)
	(via
		(at 435.096158 -5.076444)
		(size 0.508)
		(drill 0.254)
		(layers "F.Cu" "B.Cu")
		(net "RST_PERST1_OCP_SFF_N")
	)
	(via
		(at 214.910416 -125.643894)
		(size 0.508)
		(drill 0.254)
		(layers "F.Cu" "B.Cu")
		(net "RST_PERST1_OCP_SFF_N")
	)
	(via
		(at 203.003404 -83.430618)
		(size 0.508)
		(drill 0.254)
		(layers "F.Cu" "B.Cu")
		(net "RST_PERST1_OCP_SFF_N")
	)
	(segment
		(start 214.910416 -125.643894)
		(end 215.025732 -125.643894)
		(width 0.11684)
		(layer "In11.Cu")
		(net "RST_PERST1_OCP_SFF_N")
	)
	(segment
		(start 218.010994 -96.069658)
		(end 217.54084 -95.599504)
		(width 0.11684)
		(layer "In11.Cu")
		(net "RST_PERST1_OCP_SFF_N")
	)
	(segment
		(start 217.54084 -93.871542)
		(end 206.001366 -82.332068)
		(width 0.11684)
		(layer "In11.Cu")
		(net "RST_PERST1_OCP_SFF_N")
	)
	(segment
		(start 215.85047 -116.35359)
		(end 216.426288 -115.777772)
		(width 0.11684)
		(layer "In11.Cu")
		(net "RST_PERST1_OCP_SFF_N")
	)
	(segment
		(start 217.15984 -101.94544)
		(end 217.15984 -100.805488)
		(width 0.11684)
		(layer "In11.Cu")
		(net "RST_PERST1_OCP_SFF_N")
	)
	(segment
		(start 217.462608 -105.051352)
		(end 217.462608 -102.248208)
		(width 0.11684)
		(layer "In11.Cu")
		(net "RST_PERST1_OCP_SFF_N")
	)
	(segment
		(start 217.54084 -95.599504)
		(end 217.54084 -93.871542)
		(width 0.11684)
		(layer "In11.Cu")
		(net "RST_PERST1_OCP_SFF_N")
	)
	(segment
		(start 215.85047 -119.996458)
		(end 215.85047 -116.35359)
		(width 0.11684)
		(layer "In11.Cu")
		(net "RST_PERST1_OCP_SFF_N")
	)
	(segment
		(start 216.888568 -105.625138)
		(end 217.160602 -105.353104)
		(width 0.11684)
		(layer "In11.Cu")
		(net "RST_PERST1_OCP_SFF_N")
	)
	(segment
		(start 204.101954 -82.332068)
		(end 203.003404 -83.430618)
		(width 0.11684)
		(layer "In11.Cu")
		(net "RST_PERST1_OCP_SFF_N")
	)
	(segment
		(start 217.15984 -100.805488)
		(end 218.010994 -99.954334)
		(width 0.11684)
		(layer "In11.Cu")
		(net "RST_PERST1_OCP_SFF_N")
	)
	(segment
		(start 216.426288 -115.777772)
		(end 216.426288 -106.087672)
		(width 0.11684)
		(layer "In11.Cu")
		(net "RST_PERST1_OCP_SFF_N")
	)
	(segment
		(start 217.160856 -105.353104)
		(end 217.462608 -105.051352)
		(width 0.11684)
		(layer "In11.Cu")
		(net "RST_PERST1_OCP_SFF_N")
	)
	(segment
		(start 206.001366 -82.332068)
		(end 204.101954 -82.332068)
		(width 0.11684)
		(layer "In11.Cu")
		(net "RST_PERST1_OCP_SFF_N")
	)
	(segment
		(start 216.426288 -124.243338)
		(end 216.426288 -120.572276)
		(width 0.11684)
		(layer "In11.Cu")
		(net "RST_PERST1_OCP_SFF_N")
	)
	(segment
		(start 216.426288 -120.572276)
		(end 215.85047 -119.996458)
		(width 0.11684)
		(layer "In11.Cu")
		(net "RST_PERST1_OCP_SFF_N")
	)
	(segment
		(start 216.426288 -106.087672)
		(end 216.888568 -105.625392)
		(width 0.11684)
		(layer "In11.Cu")
		(net "RST_PERST1_OCP_SFF_N")
	)
	(segment
		(start 218.010994 -99.954334)
		(end 218.010994 -96.069658)
		(width 0.11684)
		(layer "In11.Cu")
		(net "RST_PERST1_OCP_SFF_N")
	)
	(segment
		(start 216.888568 -105.625392)
		(end 216.888568 -105.625138)
		(width 0.11684)
		(layer "In11.Cu")
		(net "RST_PERST1_OCP_SFF_N")
	)
	(segment
		(start 215.025732 -125.643894)
		(end 216.426288 -124.243338)
		(width 0.11684)
		(layer "In11.Cu")
		(net "RST_PERST1_OCP_SFF_N")
	)
	(segment
		(start 217.160602 -105.353104)
		(end 217.160856 -105.353104)
		(width 0.11684)
		(layer "In11.Cu")
		(net "RST_PERST1_OCP_SFF_N")
	)
	(segment
		(start 217.462608 -102.248208)
		(end 217.15984 -101.94544)
		(width 0.11684)
		(layer "In11.Cu")
		(net "RST_PERST1_OCP_SFF_N")
	)
	(segment
		(start 374.959626 -17.675098)
		(end 377.87834 -14.756384)
		(width 0.11684)
		(layer "In15.Cu")
		(net "RST_PERST1_OCP_SFF_N")
	)
	(segment
		(start 203.003404 -83.430618)
		(end 206.043022 -80.391)
		(width 0.11684)
		(layer "In15.Cu")
		(net "RST_PERST1_OCP_SFF_N")
	)
	(segment
		(start 259.913882 -70.66788)
		(end 275.565362 -70.66788)
		(width 0.11684)
		(layer "In15.Cu")
		(net "RST_PERST1_OCP_SFF_N")
	)
	(segment
		(start 432.371246 -3.86461)
		(end 433.58308 -5.076444)
		(width 0.11684)
		(layer "In15.Cu")
		(net "RST_PERST1_OCP_SFF_N")
	)
	(segment
		(start 377.87834 -14.756384)
		(end 420.455852 -14.756384)
		(width 0.11684)
		(layer "In15.Cu")
		(net "RST_PERST1_OCP_SFF_N")
	)
	(segment
		(start 421.949372 -7.186676)
		(end 425.271438 -3.86461)
		(width 0.11684)
		(layer "In15.Cu")
		(net "RST_PERST1_OCP_SFF_N")
	)
	(segment
		(start 322.535296 -24.508714)
		(end 322.535296 -19.570954)
		(width 0.11684)
		(layer "In15.Cu")
		(net "RST_PERST1_OCP_SFF_N")
	)
	(segment
		(start 425.271438 -3.86461)
		(end 432.371246 -3.86461)
		(width 0.11684)
		(layer "In15.Cu")
		(net "RST_PERST1_OCP_SFF_N")
	)
	(segment
		(start 355.322378 -14.756384)
		(end 358.241092 -17.675098)
		(width 0.11684)
		(layer "In15.Cu")
		(net "RST_PERST1_OCP_SFF_N")
	)
	(segment
		(start 304.221388 -27.871928)
		(end 319.172082 -27.871928)
		(width 0.11684)
		(layer "In15.Cu")
		(net "RST_PERST1_OCP_SFF_N")
	)
	(segment
		(start 319.172082 -27.871928)
		(end 322.535296 -24.508714)
		(width 0.11684)
		(layer "In15.Cu")
		(net "RST_PERST1_OCP_SFF_N")
	)
	(segment
		(start 282.35275 -49.740566)
		(end 304.221388 -27.871928)
		(width 0.11684)
		(layer "In15.Cu")
		(net "RST_PERST1_OCP_SFF_N")
	)
	(segment
		(start 206.043022 -80.391)
		(end 221.996 -80.391)
		(width 0.11684)
		(layer "In15.Cu")
		(net "RST_PERST1_OCP_SFF_N")
	)
	(segment
		(start 433.58308 -5.076444)
		(end 435.096158 -5.076444)
		(width 0.11684)
		(layer "In15.Cu")
		(net "RST_PERST1_OCP_SFF_N")
	)
	(segment
		(start 327.349866 -14.756384)
		(end 355.322378 -14.756384)
		(width 0.11684)
		(layer "In15.Cu")
		(net "RST_PERST1_OCP_SFF_N")
	)
	(segment
		(start 358.241092 -17.675098)
		(end 374.959626 -17.675098)
		(width 0.11684)
		(layer "In15.Cu")
		(net "RST_PERST1_OCP_SFF_N")
	)
	(segment
		(start 222.373444 -80.768444)
		(end 223.13519 -80.768444)
		(width 0.11684)
		(layer "In15.Cu")
		(net "RST_PERST1_OCP_SFF_N")
	)
	(segment
		(start 275.565362 -70.66788)
		(end 282.35275 -63.880492)
		(width 0.11684)
		(layer "In15.Cu")
		(net "RST_PERST1_OCP_SFF_N")
	)
	(segment
		(start 282.35275 -63.880492)
		(end 282.35275 -49.740566)
		(width 0.11684)
		(layer "In15.Cu")
		(net "RST_PERST1_OCP_SFF_N")
	)
	(segment
		(start 221.996 -80.391)
		(end 222.373444 -80.768444)
		(width 0.11684)
		(layer "In15.Cu")
		(net "RST_PERST1_OCP_SFF_N")
	)
	(segment
		(start 257.029458 -73.552304)
		(end 259.913882 -70.66788)
		(width 0.11684)
		(layer "In15.Cu")
		(net "RST_PERST1_OCP_SFF_N")
	)
	(segment
		(start 322.535296 -19.570954)
		(end 327.349866 -14.756384)
		(width 0.11684)
		(layer "In15.Cu")
		(net "RST_PERST1_OCP_SFF_N")
	)
	(segment
		(start 420.455852 -14.756384)
		(end 421.949372 -13.262864)
		(width 0.11684)
		(layer "In15.Cu")
		(net "RST_PERST1_OCP_SFF_N")
	)
	(segment
		(start 421.949372 -13.262864)
		(end 421.949372 -7.186676)
		(width 0.11684)
		(layer "In15.Cu")
		(net "RST_PERST1_OCP_SFF_N")
	)
	(segment
		(start 230.35133 -73.552304)
		(end 257.029458 -73.552304)
		(width 0.11684)
		(layer "In15.Cu")
		(net "RST_PERST1_OCP_SFF_N")
	)
	(segment
		(start 223.13519 -80.768444)
		(end 230.35133 -73.552304)
		(width 0.11684)
		(layer "In15.Cu")
		(net "RST_PERST1_OCP_SFF_N")
	)
	(segment
		(start 82.822034 -40.67048)
		(end 82.206084 -40.67048)
		(width 0.10668)
		(layer "F.Cu")
		(net "RST_PERST0_OCP_V3_2_N")
	)
	(segment
		(start 60.466986 -11.26998)
		(end 60.466986 -13.362432)
		(width 0.10668)
		(layer "F.Cu")
		(net "RST_PERST0_OCP_V3_2_N")
	)
	(segment
		(start 60.466986 -13.362432)
		(end 60.913264 -13.80871)
		(width 0.10668)
		(layer "F.Cu")
		(net "RST_PERST0_OCP_V3_2_N")
	)
	(via
		(at 60.913264 -13.80871)
		(size 0.508)
		(drill 0.254)
		(layers "F.Cu" "B.Cu")
		(net "RST_PERST0_OCP_V3_2_N")
	)
	(via
		(at 82.206084 -40.67048)
		(size 0.508)
		(drill 0.254)
		(layers "F.Cu" "B.Cu")
		(net "RST_PERST0_OCP_V3_2_N")
	)
	(segment
		(start 61.976 -38.0238)
		(end 62.6364 -38.6842)
		(width 0.11684)
		(layer "In4.Cu")
		(net "RST_PERST0_OCP_V3_2_N")
	)
	(segment
		(start 62.6364 -39.767764)
		(end 65.745868 -42.877232)
		(width 0.11684)
		(layer "In4.Cu")
		(net "RST_PERST0_OCP_V3_2_N")
	)
	(segment
		(start 65.745868 -42.877232)
		(end 79.999332 -42.877232)
		(width 0.11684)
		(layer "In4.Cu")
		(net "RST_PERST0_OCP_V3_2_N")
	)
	(segment
		(start 60.1599 -34.087308)
		(end 60.1599 -34.5821)
		(width 0.11684)
		(layer "In4.Cu")
		(net "RST_PERST0_OCP_V3_2_N")
	)
	(segment
		(start 60.983114 -17.476216)
		(end 61.405516 -17.898618)
		(width 0.11684)
		(layer "In4.Cu")
		(net "RST_PERST0_OCP_V3_2_N")
	)
	(segment
		(start 60.913264 -13.80871)
		(end 60.983114 -13.87856)
		(width 0.11684)
		(layer "In4.Cu")
		(net "RST_PERST0_OCP_V3_2_N")
	)
	(segment
		(start 59.6392 -33.566608)
		(end 60.1599 -34.087308)
		(width 0.11684)
		(layer "In4.Cu")
		(net "RST_PERST0_OCP_V3_2_N")
	)
	(segment
		(start 60.1599 -34.5821)
		(end 60.694824 -35.117024)
		(width 0.11684)
		(layer "In4.Cu")
		(net "RST_PERST0_OCP_V3_2_N")
	)
	(segment
		(start 79.999332 -42.877232)
		(end 82.206084 -40.67048)
		(width 0.11684)
		(layer "In4.Cu")
		(net "RST_PERST0_OCP_V3_2_N")
	)
	(segment
		(start 61.049662 -18.944082)
		(end 61.049662 -31.101538)
		(width 0.11684)
		(layer "In4.Cu")
		(net "RST_PERST0_OCP_V3_2_N")
	)
	(segment
		(start 59.6392 -32.512)
		(end 59.6392 -33.566608)
		(width 0.11684)
		(layer "In4.Cu")
		(net "RST_PERST0_OCP_V3_2_N")
	)
	(segment
		(start 61.049662 -31.101538)
		(end 59.6392 -32.512)
		(width 0.11684)
		(layer "In4.Cu")
		(net "RST_PERST0_OCP_V3_2_N")
	)
	(segment
		(start 61.507624 -35.117024)
		(end 61.976 -35.5854)
		(width 0.11684)
		(layer "In4.Cu")
		(net "RST_PERST0_OCP_V3_2_N")
	)
	(segment
		(start 60.983114 -13.87856)
		(end 60.983114 -17.476216)
		(width 0.11684)
		(layer "In4.Cu")
		(net "RST_PERST0_OCP_V3_2_N")
	)
	(segment
		(start 61.976 -35.5854)
		(end 61.976 -38.0238)
		(width 0.11684)
		(layer "In4.Cu")
		(net "RST_PERST0_OCP_V3_2_N")
	)
	(segment
		(start 61.405516 -18.588228)
		(end 61.049662 -18.944082)
		(width 0.11684)
		(layer "In4.Cu")
		(net "RST_PERST0_OCP_V3_2_N")
	)
	(segment
		(start 60.694824 -35.117024)
		(end 61.507624 -35.117024)
		(width 0.11684)
		(layer "In4.Cu")
		(net "RST_PERST0_OCP_V3_2_N")
	)
	(segment
		(start 62.6364 -38.6842)
		(end 62.6364 -39.767764)
		(width 0.11684)
		(layer "In4.Cu")
		(net "RST_PERST0_OCP_V3_2_N")
	)
	(segment
		(start 61.405516 -17.898618)
		(end 61.405516 -18.588228)
		(width 0.11684)
		(layer "In4.Cu")
		(net "RST_PERST0_OCP_V3_2_N")
	)
	(segment
		(start 434.362606 -13.280136)
		(end 434.362606 -14.688312)
		(width 0.10668)
		(layer "F.Cu")
		(net "RST_PERST0_OCP_SFF_N")
	)
	(segment
		(start 215.039702 -123.565412)
		(end 215.214962 -123.390152)
		(width 0.10668)
		(layer "F.Cu")
		(net "RST_PERST0_OCP_SFF_N")
	)
	(segment
		(start 214.328248 -123.565412)
		(end 215.039702 -123.565412)
		(width 0.10668)
		(layer "F.Cu")
		(net "RST_PERST0_OCP_SFF_N")
	)
	(segment
		(start 434.362606 -14.688312)
		(end 435.304946 -15.630652)
		(width 0.10668)
		(layer "F.Cu")
		(net "RST_PERST0_OCP_SFF_N")
	)
	(segment
		(start 435.304946 -15.630652)
		(end 435.304946 -17.914874)
		(width 0.10668)
		(layer "F.Cu")
		(net "RST_PERST0_OCP_SFF_N")
	)
	(segment
		(start 434.966872 -11.26998)
		(end 434.966872 -12.67587)
		(width 0.10668)
		(layer "F.Cu")
		(net "RST_PERST0_OCP_SFF_N")
	)
	(segment
		(start 434.966872 -12.67587)
		(end 434.362606 -13.280136)
		(width 0.10668)
		(layer "F.Cu")
		(net "RST_PERST0_OCP_SFF_N")
	)
	(segment
		(start 435.304946 -17.914874)
		(end 435.828694 -18.438622)
		(width 0.10668)
		(layer "F.Cu")
		(net "RST_PERST0_OCP_SFF_N")
	)
	(via
		(at 200.025 -83.403948)
		(size 0.508)
		(drill 0.254)
		(layers "F.Cu" "B.Cu")
		(net "RST_PERST0_OCP_SFF_N")
	)
	(via
		(at 215.214962 -123.390152)
		(size 0.508)
		(drill 0.254)
		(layers "F.Cu" "B.Cu")
		(net "RST_PERST0_OCP_SFF_N")
	)
	(via
		(at 435.828694 -18.438622)
		(size 0.508)
		(drill 0.254)
		(layers "F.Cu" "B.Cu")
		(net "RST_PERST0_OCP_SFF_N")
	)
	(segment
		(start 203.234798 -85.062568)
		(end 207.429862 -85.062568)
		(width 0.11684)
		(layer "In11.Cu")
		(net "RST_PERST0_OCP_SFF_N")
	)
	(segment
		(start 215.555576 -105.679494)
		(end 215.555576 -113.00714)
		(width 0.11684)
		(layer "In11.Cu")
		(net "RST_PERST0_OCP_SFF_N")
	)
	(segment
		(start 200.025 -83.403948)
		(end 200.773284 -84.152232)
		(width 0.11684)
		(layer "In11.Cu")
		(net "RST_PERST0_OCP_SFF_N")
	)
	(segment
		(start 216.060274 -93.69298)
		(end 216.060274 -100.56368)
		(width 0.11684)
		(layer "In11.Cu")
		(net "RST_PERST0_OCP_SFF_N")
	)
	(segment
		(start 214.828628 -121.32818)
		(end 215.555576 -122.055128)
		(width 0.11684)
		(layer "In11.Cu")
		(net "RST_PERST0_OCP_SFF_N")
	)
	(segment
		(start 215.555576 -113.00714)
		(end 214.828628 -113.734088)
		(width 0.11684)
		(layer "In11.Cu")
		(net "RST_PERST0_OCP_SFF_N")
	)
	(segment
		(start 215.555576 -122.055128)
		(end 215.555576 -123.049538)
		(width 0.11684)
		(layer "In11.Cu")
		(net "RST_PERST0_OCP_SFF_N")
	)
	(segment
		(start 216.060274 -100.56368)
		(end 215.364822 -101.259132)
		(width 0.11684)
		(layer "In11.Cu")
		(net "RST_PERST0_OCP_SFF_N")
	)
	(segment
		(start 215.555576 -123.049538)
		(end 215.214962 -123.390152)
		(width 0.11684)
		(layer "In11.Cu")
		(net "RST_PERST0_OCP_SFF_N")
	)
	(segment
		(start 200.773284 -84.152232)
		(end 202.324462 -84.152232)
		(width 0.11684)
		(layer "In11.Cu")
		(net "RST_PERST0_OCP_SFF_N")
	)
	(segment
		(start 215.364822 -101.259132)
		(end 215.364822 -105.48874)
		(width 0.11684)
		(layer "In11.Cu")
		(net "RST_PERST0_OCP_SFF_N")
	)
	(segment
		(start 214.828628 -113.734088)
		(end 214.828628 -121.32818)
		(width 0.11684)
		(layer "In11.Cu")
		(net "RST_PERST0_OCP_SFF_N")
	)
	(segment
		(start 202.324462 -84.152232)
		(end 203.234798 -85.062568)
		(width 0.11684)
		(layer "In11.Cu")
		(net "RST_PERST0_OCP_SFF_N")
	)
	(segment
		(start 215.364822 -105.48874)
		(end 215.555576 -105.679494)
		(width 0.11684)
		(layer "In11.Cu")
		(net "RST_PERST0_OCP_SFF_N")
	)
	(segment
		(start 207.429862 -85.062568)
		(end 216.060274 -93.69298)
		(width 0.11684)
		(layer "In11.Cu")
		(net "RST_PERST0_OCP_SFF_N")
	)
	(segment
		(start 232.803192 -74.87158)
		(end 225.494596 -82.180176)
		(width 0.11684)
		(layer "In15.Cu")
		(net "RST_PERST0_OCP_SFF_N")
	)
	(segment
		(start 284.03931 -64.647572)
		(end 276.28596 -72.400922)
		(width 0.11684)
		(layer "In15.Cu")
		(net "RST_PERST0_OCP_SFF_N")
	)
	(segment
		(start 208.953608 -81.829402)
		(end 205.947264 -84.835746)
		(width 0.11684)
		(layer "In15.Cu")
		(net "RST_PERST0_OCP_SFF_N")
	)
	(segment
		(start 373.129556 -23.212806)
		(end 333.62265 -23.212806)
		(width 0.11684)
		(layer "In15.Cu")
		(net "RST_PERST0_OCP_SFF_N")
	)
	(segment
		(start 389.98525 -21.853652)
		(end 383.848356 -27.990546)
		(width 0.11684)
		(layer "In15.Cu")
		(net "RST_PERST0_OCP_SFF_N")
	)
	(segment
		(start 319.842896 -29.586936)
		(end 304.892202 -29.586936)
		(width 0.11684)
		(layer "In15.Cu")
		(net "RST_PERST0_OCP_SFF_N")
	)
	(segment
		(start 333.62265 -23.212806)
		(end 332.161642 -21.751798)
		(width 0.11684)
		(layer "In15.Cu")
		(net "RST_PERST0_OCP_SFF_N")
	)
	(segment
		(start 221.94139 -82.180176)
		(end 221.582234 -82.539332)
		(width 0.11684)
		(layer "In15.Cu")
		(net "RST_PERST0_OCP_SFF_N")
	)
	(segment
		(start 276.28596 -72.400922)
		(end 262.217916 -72.400922)
		(width 0.11684)
		(layer "In15.Cu")
		(net "RST_PERST0_OCP_SFF_N")
	)
	(segment
		(start 225.494596 -82.180176)
		(end 221.94139 -82.180176)
		(width 0.11684)
		(layer "In15.Cu")
		(net "RST_PERST0_OCP_SFF_N")
	)
	(segment
		(start 284.03931 -50.439828)
		(end 284.03931 -64.647572)
		(width 0.11684)
		(layer "In15.Cu")
		(net "RST_PERST0_OCP_SFF_N")
	)
	(segment
		(start 377.907296 -27.990546)
		(end 373.129556 -23.212806)
		(width 0.11684)
		(layer "In15.Cu")
		(net "RST_PERST0_OCP_SFF_N")
	)
	(segment
		(start 205.947264 -84.835746)
		(end 201.456798 -84.835746)
		(width 0.11684)
		(layer "In15.Cu")
		(net "RST_PERST0_OCP_SFF_N")
	)
	(segment
		(start 253.063248 -74.87158)
		(end 232.803192 -74.87158)
		(width 0.11684)
		(layer "In15.Cu")
		(net "RST_PERST0_OCP_SFF_N")
	)
	(segment
		(start 255.444498 -77.25283)
		(end 253.063248 -74.87158)
		(width 0.11684)
		(layer "In15.Cu")
		(net "RST_PERST0_OCP_SFF_N")
	)
	(segment
		(start 201.456798 -84.835746)
		(end 200.025 -83.403948)
		(width 0.11684)
		(layer "In15.Cu")
		(net "RST_PERST0_OCP_SFF_N")
	)
	(segment
		(start 220.002862 -81.829402)
		(end 208.953608 -81.829402)
		(width 0.11684)
		(layer "In15.Cu")
		(net "RST_PERST0_OCP_SFF_N")
	)
	(segment
		(start 220.712792 -82.539332)
		(end 220.002862 -81.829402)
		(width 0.11684)
		(layer "In15.Cu")
		(net "RST_PERST0_OCP_SFF_N")
	)
	(segment
		(start 327.678034 -21.751798)
		(end 319.842896 -29.586936)
		(width 0.11684)
		(layer "In15.Cu")
		(net "RST_PERST0_OCP_SFF_N")
	)
	(segment
		(start 262.217916 -72.400922)
		(end 257.366008 -77.25283)
		(width 0.11684)
		(layer "In15.Cu")
		(net "RST_PERST0_OCP_SFF_N")
	)
	(segment
		(start 221.582234 -82.539332)
		(end 220.712792 -82.539332)
		(width 0.11684)
		(layer "In15.Cu")
		(net "RST_PERST0_OCP_SFF_N")
	)
	(segment
		(start 435.828694 -20.275042)
		(end 434.250084 -21.853652)
		(width 0.11684)
		(layer "In15.Cu")
		(net "RST_PERST0_OCP_SFF_N")
	)
	(segment
		(start 434.250084 -21.853652)
		(end 389.98525 -21.853652)
		(width 0.11684)
		(layer "In15.Cu")
		(net "RST_PERST0_OCP_SFF_N")
	)
	(segment
		(start 257.366008 -77.25283)
		(end 255.444498 -77.25283)
		(width 0.11684)
		(layer "In15.Cu")
		(net "RST_PERST0_OCP_SFF_N")
	)
	(segment
		(start 332.161642 -21.751798)
		(end 327.678034 -21.751798)
		(width 0.11684)
		(layer "In15.Cu")
		(net "RST_PERST0_OCP_SFF_N")
	)
	(segment
		(start 383.848356 -27.990546)
		(end 377.907296 -27.990546)
		(width 0.11684)
		(layer "In15.Cu")
		(net "RST_PERST0_OCP_SFF_N")
	)
	(segment
		(start 435.828694 -18.438622)
		(end 435.828694 -20.275042)
		(width 0.11684)
		(layer "In15.Cu")
		(net "RST_PERST0_OCP_SFF_N")
	)
	(segment
		(start 304.892202 -29.586936)
		(end 284.03931 -50.439828)
		(width 0.11684)
		(layer "In15.Cu")
		(net "RST_PERST0_OCP_SFF_N")
	)
	(segment
		(start 239.10798 -48.019208)
		(end 238.076486 -48.019208)
		(width 0.10668)
		(layer "F.Cu")
		(net "RST_PCIE_E1S_PERST_N")
	)
	(segment
		(start 237.42396 -47.964852)
		(end 236.599984 -47.964852)
		(width 0.10668)
		(layer "F.Cu")
		(net "RST_PCIE_E1S_PERST_N")
	)
	(segment
		(start 238.076486 -48.019208)
		(end 238.065818 -48.00854)
		(width 0.10668)
		(layer "F.Cu")
		(net "RST_PCIE_E1S_PERST_N")
	)
	(segment
		(start 237.467648 -48.00854)
		(end 237.42396 -47.964852)
		(width 0.10668)
		(layer "F.Cu")
		(net "RST_PCIE_E1S_PERST_N")
	)
	(segment
		(start 238.065818 -48.00854)
		(end 237.467648 -48.00854)
		(width 0.10668)
		(layer "F.Cu")
		(net "RST_PCIE_E1S_PERST_N")
	)
	(via
		(at 238.065818 -48.00854)
		(size 0.508)
		(drill 0.254)
		(layers "F.Cu" "B.Cu")
		(net "RST_PCIE_E1S_PERST_N")
	)
	(segment
		(start 141.286992 -101.494844)
		(end 141.286992 -100.275644)
		(width 0.10668)
		(layer "F.Cu")
		(net "RST_PERST_BUF_M2_0_N")
	)
	(segment
		(start 141.286992 -102.510844)
		(end 141.286992 -101.494844)
		(width 0.10668)
		(layer "F.Cu")
		(net "RST_PERST_BUF_M2_0_N")
	)
	(segment
		(start 144.075658 -100.275644)
		(end 141.286992 -100.275644)
		(width 0.10668)
		(layer "F.Cu")
		(net "RST_PERST_BUF_M2_0_N")
	)
	(segment
		(start 145.740628 -101.244146)
		(end 145.04416 -101.244146)
		(width 0.10668)
		(layer "F.Cu")
		(net "RST_PERST_BUF_M2_0_N")
	)
	(segment
		(start 145.04416 -101.244146)
		(end 144.075658 -100.275644)
		(width 0.10668)
		(layer "F.Cu")
		(net "RST_PERST_BUF_M2_0_N")
	)
	(via
		(at 141.286992 -100.275644)
		(size 0.762)
		(drill 0.381)
		(layers "F.Cu" "B.Cu")
		(net "RST_PERST_BUF_M2_0_N")
	)
	(segment
		(start 166.455852 -44.04995)
		(end 169.558208 -44.04995)
		(width 0.10668)
		(layer "F.Cu")
		(net "RST_PERST_BUF_M2_0_R_N")
	)
	(segment
		(start 166.198804 -44.306998)
		(end 166.455852 -44.04995)
		(width 0.10668)
		(layer "F.Cu")
		(net "RST_PERST_BUF_M2_0_R_N")
	)
	(segment
		(start 140.486892 -102.510844)
		(end 139.845542 -102.510844)
		(width 0.10668)
		(layer "F.Cu")
		(net "RST_PERST_BUF_M2_0_R_N")
	)
	(via
		(at 139.845542 -102.510844)
		(size 0.508)
		(drill 0.254)
		(layers "F.Cu" "B.Cu")
		(net "RST_PERST_BUF_M2_0_R_N")
	)
	(via
		(at 159.098488 -49.131474)
		(size 0.508)
		(drill 0.254)
		(layers "F.Cu" "B.Cu")
		(net "RST_PERST_BUF_M2_0_R_N")
	)
	(via
		(at 166.198804 -44.306998)
		(size 0.762)
		(drill 0.254)
		(layers "F.Cu" "B.Cu")
		(net "RST_PERST_BUF_M2_0_R_N")
	)
	(segment
		(start 155.87345 -84.897976)
		(end 155.87345 -71.190104)
		(width 0.11684)
		(layer "In11.Cu")
		(net "RST_PERST_BUF_M2_0_R_N")
	)
	(segment
		(start 159.434276 -67.629278)
		(end 159.434276 -49.467262)
		(width 0.11684)
		(layer "In11.Cu")
		(net "RST_PERST_BUF_M2_0_R_N")
	)
	(segment
		(start 139.845542 -102.510844)
		(end 147.94103 -94.415356)
		(width 0.11684)
		(layer "In11.Cu")
		(net "RST_PERST_BUF_M2_0_R_N")
	)
	(segment
		(start 159.434276 -49.467262)
		(end 159.098488 -49.131474)
		(width 0.11684)
		(layer "In11.Cu")
		(net "RST_PERST_BUF_M2_0_R_N")
	)
	(segment
		(start 147.94103 -92.830396)
		(end 155.87345 -84.897976)
		(width 0.11684)
		(layer "In11.Cu")
		(net "RST_PERST_BUF_M2_0_R_N")
	)
	(segment
		(start 147.94103 -94.415356)
		(end 147.94103 -92.830396)
		(width 0.11684)
		(layer "In11.Cu")
		(net "RST_PERST_BUF_M2_0_R_N")
	)
	(segment
		(start 155.87345 -71.190104)
		(end 159.434276 -67.629278)
		(width 0.11684)
		(layer "In11.Cu")
		(net "RST_PERST_BUF_M2_0_R_N")
	)
	(segment
		(start 162.201352 -46.689518)
		(end 164.583872 -44.306998)
		(width 0.11684)
		(layer "In15.Cu")
		(net "RST_PERST_BUF_M2_0_R_N")
	)
	(segment
		(start 159.098488 -48.604932)
		(end 161.013902 -46.689518)
		(width 0.11684)
		(layer "In15.Cu")
		(net "RST_PERST_BUF_M2_0_R_N")
	)
	(segment
		(start 164.583872 -44.306998)
		(end 166.198804 -44.306998)
		(width 0.11684)
		(layer "In15.Cu")
		(net "RST_PERST_BUF_M2_0_R_N")
	)
	(segment
		(start 161.013902 -46.689518)
		(end 162.201352 -46.689518)
		(width 0.11684)
		(layer "In15.Cu")
		(net "RST_PERST_BUF_M2_0_R_N")
	)
	(segment
		(start 159.098488 -49.131474)
		(end 159.098488 -48.604932)
		(width 0.11684)
		(layer "In15.Cu")
		(net "RST_PERST_BUF_M2_0_R_N")
	)
	(segment
		(start 54.5846 -30.607508)
		(end 56.06923 -30.607508)
		(width 0.10668)
		(layer "F.Cu")
		(net "RST_HP_OCP_V3_2_R_N")
	)
	(segment
		(start 52.877466 -30.607508)
		(end 54.5846 -30.607508)
		(width 0.10668)
		(layer "F.Cu")
		(net "RST_HP_OCP_V3_2_R_N")
	)
	(segment
		(start 56.06923 -30.607508)
		(end 56.10987 -30.648148)
		(width 0.10668)
		(layer "F.Cu")
		(net "RST_HP_OCP_V3_2_R_N")
	)
	(segment
		(start 56.10987 -31.664148)
		(end 56.10987 -30.648148)
		(width 0.10668)
		(layer "F.Cu")
		(net "RST_HP_OCP_V3_2_R_N")
	)
	(via
		(at 54.5846 -30.607508)
		(size 0.762)
		(drill 0.381)
		(layers "F.Cu" "B.Cu")
		(net "RST_HP_OCP_V3_2_R_N")
	)
	(segment
		(start 463.335878 -94.317566)
		(end 463.335878 -93.309186)
		(width 0.10668)
		(layer "F.Cu")
		(net "RST_HP_OCP_SFF_R_N")
	)
	(segment
		(start 460.528162 -92.977208)
		(end 460.387446 -92.977462)
		(width 0.10668)
		(layer "F.Cu")
		(net "RST_HP_OCP_SFF_R_N")
	)
	(segment
		(start 461.841596 -92.977462)
		(end 463.004154 -92.977462)
		(width 0.10668)
		(layer "F.Cu")
		(net "RST_HP_OCP_SFF_R_N")
	)
	(segment
		(start 460.528416 -92.977462)
		(end 460.528162 -92.977208)
		(width 0.10668)
		(layer "F.Cu")
		(net "RST_HP_OCP_SFF_R_N")
	)
	(segment
		(start 463.004154 -92.977462)
		(end 463.335878 -93.309186)
		(width 0.10668)
		(layer "F.Cu")
		(net "RST_HP_OCP_SFF_R_N")
	)
	(segment
		(start 461.841596 -92.977462)
		(end 460.528416 -92.977462)
		(width 0.10668)
		(layer "F.Cu")
		(net "RST_HP_OCP_SFF_R_N")
	)
	(via
		(at 461.841596 -92.977462)
		(size 0.762)
		(drill 0.381)
		(layers "F.Cu" "B.Cu")
		(net "RST_HP_OCP_SFF_R_N")
	)
	(segment
		(start 369.888008 -292.450012)
		(end 370.35486 -292.71595)
		(width 0.10668)
		(layer "F.Cu")
		(net "RST_ESPI_CPU0_R_RSTOUT_N")
	)
	(via
		(at 393.330176 -329.47483)
		(size 0.6604)
		(drill 0.3302)
		(layers "F.Cu" "B.Cu")
		(net "RST_ESPI_CPU0_R_RSTOUT_N")
	)
	(via
		(at 370.35486 -292.71595)
		(size 0.4064)
		(drill 0.2032)
		(layers "F.Cu" "B.Cu")
		(net "RST_ESPI_CPU0_R_RSTOUT_N")
	)
	(segment
		(start 369.315746 -295.299638)
		(end 368.918236 -295.697148)
		(width 0.10668)
		(layer "B.Cu")
		(net "RST_ESPI_CPU0_R_RSTOUT_N")
	)
	(segment
		(start 368.918236 -305.89093)
		(end 374.893078 -311.865772)
		(width 0.10668)
		(layer "B.Cu")
		(net "RST_ESPI_CPU0_R_RSTOUT_N")
	)
	(segment
		(start 368.990118 -294.106092)
		(end 368.990118 -294.66667)
		(width 0.10668)
		(layer "B.Cu")
		(net "RST_ESPI_CPU0_R_RSTOUT_N")
	)
	(segment
		(start 369.846098 -293.951152)
		(end 369.790218 -293.895272)
		(width 0.10668)
		(layer "B.Cu")
		(net "RST_ESPI_CPU0_R_RSTOUT_N")
	)
	(segment
		(start 390.67105 -327.43902)
		(end 392.265916 -329.033886)
		(width 0.10668)
		(layer "B.Cu")
		(net "RST_ESPI_CPU0_R_RSTOUT_N")
	)
	(segment
		(start 398.121124 -329.986132)
		(end 398.225264 -330.090272)
		(width 0.10668)
		(layer "B.Cu")
		(net "RST_ESPI_CPU0_R_RSTOUT_N")
	)
	(segment
		(start 370.35486 -293.69639)
		(end 370.100098 -293.951152)
		(width 0.10668)
		(layer "B.Cu")
		(net "RST_ESPI_CPU0_R_RSTOUT_N")
	)
	(segment
		(start 392.265916 -329.033886)
		(end 393.330176 -329.47483)
		(width 0.10668)
		(layer "B.Cu")
		(net "RST_ESPI_CPU0_R_RSTOUT_N")
	)
	(segment
		(start 368.918236 -295.697148)
		(end 368.918236 -305.89093)
		(width 0.10668)
		(layer "B.Cu")
		(net "RST_ESPI_CPU0_R_RSTOUT_N")
	)
	(segment
		(start 369.315746 -294.992298)
		(end 369.315746 -295.299638)
		(width 0.10668)
		(layer "B.Cu")
		(net "RST_ESPI_CPU0_R_RSTOUT_N")
	)
	(segment
		(start 370.100098 -293.951152)
		(end 369.846098 -293.951152)
		(width 0.10668)
		(layer "B.Cu")
		(net "RST_ESPI_CPU0_R_RSTOUT_N")
	)
	(segment
		(start 387.471158 -325.45274)
		(end 389.437118 -325.45274)
		(width 0.10668)
		(layer "B.Cu")
		(net "RST_ESPI_CPU0_R_RSTOUT_N")
	)
	(segment
		(start 390.67105 -326.686672)
		(end 390.67105 -327.43902)
		(width 0.10668)
		(layer "B.Cu")
		(net "RST_ESPI_CPU0_R_RSTOUT_N")
	)
	(segment
		(start 394.564616 -329.986132)
		(end 398.121124 -329.986132)
		(width 0.10668)
		(layer "B.Cu")
		(net "RST_ESPI_CPU0_R_RSTOUT_N")
	)
	(segment
		(start 370.35486 -292.71595)
		(end 370.35486 -293.69639)
		(width 0.10668)
		(layer "B.Cu")
		(net "RST_ESPI_CPU0_R_RSTOUT_N")
	)
	(segment
		(start 389.437118 -325.45274)
		(end 390.67105 -326.686672)
		(width 0.10668)
		(layer "B.Cu")
		(net "RST_ESPI_CPU0_R_RSTOUT_N")
	)
	(segment
		(start 374.893078 -312.87466)
		(end 387.471158 -325.45274)
		(width 0.10668)
		(layer "B.Cu")
		(net "RST_ESPI_CPU0_R_RSTOUT_N")
	)
	(segment
		(start 398.225264 -330.090272)
		(end 398.634458 -330.090272)
		(width 0.10668)
		(layer "B.Cu")
		(net "RST_ESPI_CPU0_R_RSTOUT_N")
	)
	(segment
		(start 374.893078 -311.865772)
		(end 374.893078 -312.87466)
		(width 0.10668)
		(layer "B.Cu")
		(net "RST_ESPI_CPU0_R_RSTOUT_N")
	)
	(segment
		(start 369.790218 -293.895272)
		(end 369.200938 -293.895272)
		(width 0.10668)
		(layer "B.Cu")
		(net "RST_ESPI_CPU0_R_RSTOUT_N")
	)
	(segment
		(start 393.330176 -329.47483)
		(end 394.564616 -329.986132)
		(width 0.10668)
		(layer "B.Cu")
		(net "RST_ESPI_CPU0_R_RSTOUT_N")
	)
	(segment
		(start 369.200938 -293.895272)
		(end 368.990118 -294.106092)
		(width 0.10668)
		(layer "B.Cu")
		(net "RST_ESPI_CPU0_R_RSTOUT_N")
	)
	(segment
		(start 368.990118 -294.66667)
		(end 369.315746 -294.992298)
		(width 0.10668)
		(layer "B.Cu")
		(net "RST_ESPI_CPU0_R_RSTOUT_N")
	)
	(segment
		(start 189.12205 -124.067824)
		(end 188.712094 -124.47778)
		(width 0.10668)
		(layer "F.Cu")
		(net "RST_ESPI_CPU0_RSTOUT_R_N")
	)
	(segment
		(start 189.12205 -123.45289)
		(end 189.12205 -124.067824)
		(width 0.10668)
		(layer "F.Cu")
		(net "RST_ESPI_CPU0_RSTOUT_R_N")
	)
	(via
		(at 188.003688 -124.22378)
		(size 0.6604)
		(drill 0.3302)
		(layers "F.Cu" "B.Cu")
		(net "RST_ESPI_CPU0_RSTOUT_R_N")
	)
	(via
		(at 188.712094 -124.47778)
		(size 0.4572)
		(drill 0.254)
		(layers "F.Cu" "B.Cu")
		(net "RST_ESPI_CPU0_RSTOUT_R_N")
	)
	(segment
		(start 188.159644 -126.345188)
		(end 188.159644 -125.365764)
		(width 0.10668)
		(layer "B.Cu")
		(net "RST_ESPI_CPU0_RSTOUT_R_N")
	)
	(segment
		(start 188.003688 -124.22378)
		(end 188.458094 -124.22378)
		(width 0.10668)
		(layer "B.Cu")
		(net "RST_ESPI_CPU0_RSTOUT_R_N")
	)
	(segment
		(start 188.071506 -126.433326)
		(end 188.159644 -126.345188)
		(width 0.10668)
		(layer "B.Cu")
		(net "RST_ESPI_CPU0_RSTOUT_R_N")
	)
	(segment
		(start 188.458094 -124.22378)
		(end 188.712094 -124.47778)
		(width 0.10668)
		(layer "B.Cu")
		(net "RST_ESPI_CPU0_RSTOUT_R_N")
	)
	(segment
		(start 188.003688 -125.209808)
		(end 188.003688 -124.22378)
		(width 0.10668)
		(layer "B.Cu")
		(net "RST_ESPI_CPU0_RSTOUT_R_N")
	)
	(segment
		(start 188.159644 -125.365764)
		(end 188.003688 -125.209808)
		(width 0.10668)
		(layer "B.Cu")
		(net "RST_ESPI_CPU0_RSTOUT_R_N")
	)
	(segment
		(start 177.066956 -18.300446)
		(end 176.962054 -18.405348)
		(width 0.10668)
		(layer "F.Cu")
		(net "RST_ESPI_CPU0_RSTOUT_N")
	)
	(segment
		(start 177.066956 -16.549878)
		(end 177.066956 -18.300446)
		(width 0.10668)
		(layer "F.Cu")
		(net "RST_ESPI_CPU0_RSTOUT_N")
	)
	(via
		(at 176.962054 -18.405348)
		(size 0.508)
		(drill 0.254)
		(layers "F.Cu" "B.Cu")
		(net "RST_ESPI_CPU0_RSTOUT_N")
	)
	(via
		(at 402.66366 -326.414892)
		(size 0.508)
		(drill 0.254)
		(layers "F.Cu" "B.Cu")
		(net "RST_ESPI_CPU0_RSTOUT_N")
	)
	(via
		(at 189.253114 -140.605002)
		(size 0.508)
		(drill 0.254)
		(layers "F.Cu" "B.Cu")
		(net "RST_ESPI_CPU0_RSTOUT_N")
	)
	(segment
		(start 402.66366 -327.71842)
		(end 402.66366 -326.414892)
		(width 0.10668)
		(layer "B.Cu")
		(net "RST_ESPI_CPU0_RSTOUT_N")
	)
	(segment
		(start 400.75358 -329.74915)
		(end 400.75358 -328.542142)
		(width 0.10668)
		(layer "B.Cu")
		(net "RST_ESPI_CPU0_RSTOUT_N")
	)
	(segment
		(start 189.253114 -139.665964)
		(end 188.921898 -139.334748)
		(width 0.10668)
		(layer "B.Cu")
		(net "RST_ESPI_CPU0_RSTOUT_N")
	)
	(segment
		(start 402.048726 -328.333354)
		(end 402.66366 -327.71842)
		(width 0.10668)
		(layer "B.Cu")
		(net "RST_ESPI_CPU0_RSTOUT_N")
	)
	(segment
		(start 400.962368 -328.333354)
		(end 402.048726 -328.333354)
		(width 0.10668)
		(layer "B.Cu")
		(net "RST_ESPI_CPU0_RSTOUT_N")
	)
	(segment
		(start 189.253114 -140.605002)
		(end 189.253114 -139.665964)
		(width 0.10668)
		(layer "B.Cu")
		(net "RST_ESPI_CPU0_RSTOUT_N")
	)
	(segment
		(start 399.434558 -330.090272)
		(end 400.412458 -330.090272)
		(width 0.10668)
		(layer "B.Cu")
		(net "RST_ESPI_CPU0_RSTOUT_N")
	)
	(segment
		(start 188.921898 -139.334748)
		(end 188.921898 -138.191748)
		(width 0.10668)
		(layer "B.Cu")
		(net "RST_ESPI_CPU0_RSTOUT_N")
	)
	(segment
		(start 188.59119 -128.30175)
		(end 188.071506 -127.782066)
		(width 0.10668)
		(layer "B.Cu")
		(net "RST_ESPI_CPU0_RSTOUT_N")
	)
	(segment
		(start 188.59119 -135.348726)
		(end 188.59119 -128.30175)
		(width 0.10668)
		(layer "B.Cu")
		(net "RST_ESPI_CPU0_RSTOUT_N")
	)
	(segment
		(start 189.410594 -136.16813)
		(end 188.59119 -135.348726)
		(width 0.10668)
		(layer "B.Cu")
		(net "RST_ESPI_CPU0_RSTOUT_N")
	)
	(segment
		(start 188.921898 -138.191748)
		(end 189.410594 -137.703052)
		(width 0.10668)
		(layer "B.Cu")
		(net "RST_ESPI_CPU0_RSTOUT_N")
	)
	(segment
		(start 400.412458 -330.090272)
		(end 400.75358 -329.74915)
		(width 0.10668)
		(layer "B.Cu")
		(net "RST_ESPI_CPU0_RSTOUT_N")
	)
	(segment
		(start 189.410594 -137.703052)
		(end 189.410594 -136.16813)
		(width 0.10668)
		(layer "B.Cu")
		(net "RST_ESPI_CPU0_RSTOUT_N")
	)
	(segment
		(start 188.071506 -127.782066)
		(end 188.071506 -127.233426)
		(width 0.10668)
		(layer "B.Cu")
		(net "RST_ESPI_CPU0_RSTOUT_N")
	)
	(segment
		(start 400.75358 -328.542142)
		(end 400.962368 -328.333354)
		(width 0.10668)
		(layer "B.Cu")
		(net "RST_ESPI_CPU0_RSTOUT_N")
	)
	(segment
		(start 197.941438 -135.255)
		(end 196.85 -135.255)
		(width 0.11684)
		(layer "In11.Cu")
		(net "RST_ESPI_CPU0_RSTOUT_N")
	)
	(segment
		(start 203.0222 -106.131868)
		(end 203.0222 -124.15139)
		(width 0.11684)
		(layer "In11.Cu")
		(net "RST_ESPI_CPU0_RSTOUT_N")
	)
	(segment
		(start 182.935626 -28.491434)
		(end 186.871102 -32.42691)
		(width 0.11684)
		(layer "In11.Cu")
		(net "RST_ESPI_CPU0_RSTOUT_N")
	)
	(segment
		(start 192.508886 -84.459318)
		(end 193.896742 -87.056214)
		(width 0.11684)
		(layer "In11.Cu")
		(net "RST_ESPI_CPU0_RSTOUT_N")
	)
	(segment
		(start 201.70648 -103.245158)
		(end 201.911204 -103.449882)
		(width 0.11684)
		(layer "In11.Cu")
		(net "RST_ESPI_CPU0_RSTOUT_N")
	)
	(segment
		(start 201.240898 -101.83114)
		(end 201.240898 -102.120954)
		(width 0.11684)
		(layer "In11.Cu")
		(net "RST_ESPI_CPU0_RSTOUT_N")
	)
	(segment
		(start 193.896742 -87.056214)
		(end 197.216776 -90.376248)
		(width 0.11684)
		(layer "In11.Cu")
		(net "RST_ESPI_CPU0_RSTOUT_N")
	)
	(segment
		(start 201.911204 -103.449882)
		(end 203.0222 -106.131868)
		(width 0.11684)
		(layer "In11.Cu")
		(net "RST_ESPI_CPU0_RSTOUT_N")
	)
	(segment
		(start 203.0222 -124.15139)
		(end 202.59548 -124.57811)
		(width 0.11684)
		(layer "In11.Cu")
		(net "RST_ESPI_CPU0_RSTOUT_N")
	)
	(segment
		(start 188.574934 -79.190342)
		(end 189.519052 -81.469484)
		(width 0.11684)
		(layer "In11.Cu")
		(net "RST_ESPI_CPU0_RSTOUT_N")
	)
	(segment
		(start 186.182 -35.741102)
		(end 186.182 -36.83)
		(width 0.11684)
		(layer "In11.Cu")
		(net "RST_ESPI_CPU0_RSTOUT_N")
	)
	(segment
		(start 196.379592 -136.816846)
		(end 194.911726 -138.284712)
		(width 0.11684)
		(layer "In11.Cu")
		(net "RST_ESPI_CPU0_RSTOUT_N")
	)
	(segment
		(start 200.916794 -101.049074)
		(end 201.240898 -101.83114)
		(width 0.11684)
		(layer "In11.Cu")
		(net "RST_ESPI_CPU0_RSTOUT_N")
	)
	(segment
		(start 202.59548 -124.57811)
		(end 202.59548 -130.600958)
		(width 0.11684)
		(layer "In11.Cu")
		(net "RST_ESPI_CPU0_RSTOUT_N")
	)
	(segment
		(start 178.853846 -21.96973)
		(end 182.935626 -26.05151)
		(width 0.11684)
		(layer "In11.Cu")
		(net "RST_ESPI_CPU0_RSTOUT_N")
	)
	(segment
		(start 194.911726 -138.938254)
		(end 194.544696 -139.305284)
		(width 0.11684)
		(layer "In11.Cu")
		(net "RST_ESPI_CPU0_RSTOUT_N")
	)
	(segment
		(start 190.552832 -139.305284)
		(end 189.253114 -140.605002)
		(width 0.11684)
		(layer "In11.Cu")
		(net "RST_ESPI_CPU0_RSTOUT_N")
	)
	(segment
		(start 178.853846 -19.9009)
		(end 178.853846 -21.96973)
		(width 0.11684)
		(layer "In11.Cu")
		(net "RST_ESPI_CPU0_RSTOUT_N")
	)
	(segment
		(start 177.358294 -18.405348)
		(end 178.853846 -19.9009)
		(width 0.11684)
		(layer "In11.Cu")
		(net "RST_ESPI_CPU0_RSTOUT_N")
	)
	(segment
		(start 197.216776 -90.376248)
		(end 200.250806 -97.700338)
		(width 0.11684)
		(layer "In11.Cu")
		(net "RST_ESPI_CPU0_RSTOUT_N")
	)
	(segment
		(start 194.544696 -139.305284)
		(end 190.552832 -139.305284)
		(width 0.11684)
		(layer "In11.Cu")
		(net "RST_ESPI_CPU0_RSTOUT_N")
	)
	(segment
		(start 200.250806 -97.700338)
		(end 200.916794 -101.049074)
		(width 0.11684)
		(layer "In11.Cu")
		(net "RST_ESPI_CPU0_RSTOUT_N")
	)
	(segment
		(start 186.871102 -37.519102)
		(end 186.871102 -75.076812)
		(width 0.11684)
		(layer "In11.Cu")
		(net "RST_ESPI_CPU0_RSTOUT_N")
	)
	(segment
		(start 176.962054 -18.405348)
		(end 177.358294 -18.405348)
		(width 0.11684)
		(layer "In11.Cu")
		(net "RST_ESPI_CPU0_RSTOUT_N")
	)
	(segment
		(start 186.871102 -35.052)
		(end 186.182 -35.741102)
		(width 0.11684)
		(layer "In11.Cu")
		(net "RST_ESPI_CPU0_RSTOUT_N")
	)
	(segment
		(start 194.911726 -138.284712)
		(end 194.911726 -138.938254)
		(width 0.11684)
		(layer "In11.Cu")
		(net "RST_ESPI_CPU0_RSTOUT_N")
	)
	(segment
		(start 201.240898 -102.120954)
		(end 201.70648 -103.245158)
		(width 0.11684)
		(layer "In11.Cu")
		(net "RST_ESPI_CPU0_RSTOUT_N")
	)
	(segment
		(start 189.519052 -81.469484)
		(end 192.508886 -84.459318)
		(width 0.11684)
		(layer "In11.Cu")
		(net "RST_ESPI_CPU0_RSTOUT_N")
	)
	(segment
		(start 186.182 -36.83)
		(end 186.871102 -37.519102)
		(width 0.11684)
		(layer "In11.Cu")
		(net "RST_ESPI_CPU0_RSTOUT_N")
	)
	(segment
		(start 196.379592 -135.725408)
		(end 196.379592 -136.816846)
		(width 0.11684)
		(layer "In11.Cu")
		(net "RST_ESPI_CPU0_RSTOUT_N")
	)
	(segment
		(start 182.935626 -26.05151)
		(end 182.935626 -28.491434)
		(width 0.11684)
		(layer "In11.Cu")
		(net "RST_ESPI_CPU0_RSTOUT_N")
	)
	(segment
		(start 196.85 -135.255)
		(end 196.379592 -135.725408)
		(width 0.11684)
		(layer "In11.Cu")
		(net "RST_ESPI_CPU0_RSTOUT_N")
	)
	(segment
		(start 186.871102 -32.42691)
		(end 186.871102 -35.052)
		(width 0.11684)
		(layer "In11.Cu")
		(net "RST_ESPI_CPU0_RSTOUT_N")
	)
	(segment
		(start 186.871102 -75.076812)
		(end 188.574934 -79.190342)
		(width 0.11684)
		(layer "In11.Cu")
		(net "RST_ESPI_CPU0_RSTOUT_N")
	)
	(segment
		(start 202.59548 -130.600958)
		(end 197.941438 -135.255)
		(width 0.11684)
		(layer "In11.Cu")
		(net "RST_ESPI_CPU0_RSTOUT_N")
	)
	(segment
		(start 393.216384 -322.772532)
		(end 393.928854 -323.485002)
		(width 0.11684)
		(layer "In15.Cu")
		(net "RST_ESPI_CPU0_RSTOUT_N")
	)
	(segment
		(start 237.418118 -145.02384)
		(end 269.768828 -166.639748)
		(width 0.11684)
		(layer "In15.Cu")
		(net "RST_ESPI_CPU0_RSTOUT_N")
	)
	(segment
		(start 394.642086 -313.068462)
		(end 393.989306 -313.721242)
		(width 0.11684)
		(layer "In15.Cu")
		(net "RST_ESPI_CPU0_RSTOUT_N")
	)
	(segment
		(start 396.919196 -325.658734)
		(end 398.849342 -327.58888)
		(width 0.11684)
		(layer "In15.Cu")
		(net "RST_ESPI_CPU0_RSTOUT_N")
	)
	(segment
		(start 400.516852 -327.58888)
		(end 401.187412 -326.91832)
		(width 0.11684)
		(layer "In15.Cu")
		(net "RST_ESPI_CPU0_RSTOUT_N")
	)
	(segment
		(start 398.849342 -327.58888)
		(end 400.516852 -327.58888)
		(width 0.11684)
		(layer "In15.Cu")
		(net "RST_ESPI_CPU0_RSTOUT_N")
	)
	(segment
		(start 194.814698 -138.16203)
		(end 195.548504 -137.428224)
		(width 0.11684)
		(layer "In15.Cu")
		(net "RST_ESPI_CPU0_RSTOUT_N")
	)
	(segment
		(start 395.278102 -218.998292)
		(end 397.134334 -220.854524)
		(width 0.11684)
		(layer "In15.Cu")
		(net "RST_ESPI_CPU0_RSTOUT_N")
	)
	(segment
		(start 384.541522 -216.801446)
		(end 386.738368 -218.998292)
		(width 0.11684)
		(layer "In15.Cu")
		(net "RST_ESPI_CPU0_RSTOUT_N")
	)
	(segment
		(start 386.738368 -218.998292)
		(end 395.278102 -218.998292)
		(width 0.11684)
		(layer "In15.Cu")
		(net "RST_ESPI_CPU0_RSTOUT_N")
	)
	(segment
		(start 394.044424 -319.845944)
		(end 393.216384 -320.673984)
		(width 0.11684)
		(layer "In15.Cu")
		(net "RST_ESPI_CPU0_RSTOUT_N")
	)
	(segment
		(start 308.803294 -168.349168)
		(end 330.74864 -177.43932)
		(width 0.11684)
		(layer "In15.Cu")
		(net "RST_ESPI_CPU0_RSTOUT_N")
	)
	(segment
		(start 202.331574 -139.59332)
		(end 204.681836 -141.943582)
		(width 0.11684)
		(layer "In15.Cu")
		(net "RST_ESPI_CPU0_RSTOUT_N")
	)
	(segment
		(start 401.187412 -326.91832)
		(end 402.160232 -326.91832)
		(width 0.11684)
		(layer "In15.Cu")
		(net "RST_ESPI_CPU0_RSTOUT_N")
	)
	(segment
		(start 370.110766 -216.801446)
		(end 384.541522 -216.801446)
		(width 0.11684)
		(layer "In15.Cu")
		(net "RST_ESPI_CPU0_RSTOUT_N")
	)
	(segment
		(start 269.768828 -166.639748)
		(end 275.403564 -168.349168)
		(width 0.11684)
		(layer "In15.Cu")
		(net "RST_ESPI_CPU0_RSTOUT_N")
	)
	(segment
		(start 394.766292 -325.658734)
		(end 396.919196 -325.658734)
		(width 0.11684)
		(layer "In15.Cu")
		(net "RST_ESPI_CPU0_RSTOUT_N")
	)
	(segment
		(start 194.814698 -139.472924)
		(end 194.814698 -138.16203)
		(width 0.11684)
		(layer "In15.Cu")
		(net "RST_ESPI_CPU0_RSTOUT_N")
	)
	(segment
		(start 223.992694 -145.02384)
		(end 237.418118 -145.02384)
		(width 0.11684)
		(layer "In15.Cu")
		(net "RST_ESPI_CPU0_RSTOUT_N")
	)
	(segment
		(start 393.568682 -318.017906)
		(end 393.755626 -318.46901)
		(width 0.11684)
		(layer "In15.Cu")
		(net "RST_ESPI_CPU0_RSTOUT_N")
	)
	(segment
		(start 393.216384 -320.673984)
		(end 393.216384 -322.772532)
		(width 0.11684)
		(layer "In15.Cu")
		(net "RST_ESPI_CPU0_RSTOUT_N")
	)
	(segment
		(start 393.494006 -315.407548)
		(end 393.568682 -315.482224)
		(width 0.11684)
		(layer "In15.Cu")
		(net "RST_ESPI_CPU0_RSTOUT_N")
	)
	(segment
		(start 189.949582 -139.908534)
		(end 194.379088 -139.908534)
		(width 0.11684)
		(layer "In15.Cu")
		(net "RST_ESPI_CPU0_RSTOUT_N")
	)
	(segment
		(start 330.74864 -177.43932)
		(end 370.110766 -216.801446)
		(width 0.11684)
		(layer "In15.Cu")
		(net "RST_ESPI_CPU0_RSTOUT_N")
	)
	(segment
		(start 200.89368 -139.59332)
		(end 202.331574 -139.59332)
		(width 0.11684)
		(layer "In15.Cu")
		(net "RST_ESPI_CPU0_RSTOUT_N")
	)
	(segment
		(start 393.928854 -323.485002)
		(end 393.928854 -324.821296)
		(width 0.11684)
		(layer "In15.Cu")
		(net "RST_ESPI_CPU0_RSTOUT_N")
	)
	(segment
		(start 393.494006 -314.08497)
		(end 393.494006 -315.407548)
		(width 0.11684)
		(layer "In15.Cu")
		(net "RST_ESPI_CPU0_RSTOUT_N")
	)
	(segment
		(start 189.253114 -140.605002)
		(end 189.949582 -139.908534)
		(width 0.11684)
		(layer "In15.Cu")
		(net "RST_ESPI_CPU0_RSTOUT_N")
	)
	(segment
		(start 194.379088 -139.908534)
		(end 194.814698 -139.472924)
		(width 0.11684)
		(layer "In15.Cu")
		(net "RST_ESPI_CPU0_RSTOUT_N")
	)
	(segment
		(start 195.548504 -137.428224)
		(end 198.728584 -137.428224)
		(width 0.11684)
		(layer "In15.Cu")
		(net "RST_ESPI_CPU0_RSTOUT_N")
	)
	(segment
		(start 198.728584 -137.428224)
		(end 200.89368 -139.59332)
		(width 0.11684)
		(layer "In15.Cu")
		(net "RST_ESPI_CPU0_RSTOUT_N")
	)
	(segment
		(start 397.134334 -220.854524)
		(end 397.134334 -309.13705)
		(width 0.11684)
		(layer "In15.Cu")
		(net "RST_ESPI_CPU0_RSTOUT_N")
	)
	(segment
		(start 393.857734 -313.721242)
		(end 393.494006 -314.08497)
		(width 0.11684)
		(layer "In15.Cu")
		(net "RST_ESPI_CPU0_RSTOUT_N")
	)
	(segment
		(start 275.403564 -168.349168)
		(end 308.803294 -168.349168)
		(width 0.11684)
		(layer "In15.Cu")
		(net "RST_ESPI_CPU0_RSTOUT_N")
	)
	(segment
		(start 394.044424 -318.757808)
		(end 394.044424 -319.845944)
		(width 0.11684)
		(layer "In15.Cu")
		(net "RST_ESPI_CPU0_RSTOUT_N")
	)
	(segment
		(start 394.642086 -311.629298)
		(end 394.642086 -313.068462)
		(width 0.11684)
		(layer "In15.Cu")
		(net "RST_ESPI_CPU0_RSTOUT_N")
	)
	(segment
		(start 393.989306 -313.721242)
		(end 393.857734 -313.721242)
		(width 0.11684)
		(layer "In15.Cu")
		(net "RST_ESPI_CPU0_RSTOUT_N")
	)
	(segment
		(start 393.928854 -324.821296)
		(end 394.766292 -325.658734)
		(width 0.11684)
		(layer "In15.Cu")
		(net "RST_ESPI_CPU0_RSTOUT_N")
	)
	(segment
		(start 393.755626 -318.46901)
		(end 394.044424 -318.757808)
		(width 0.11684)
		(layer "In15.Cu")
		(net "RST_ESPI_CPU0_RSTOUT_N")
	)
	(segment
		(start 397.134334 -309.13705)
		(end 394.642086 -311.629298)
		(width 0.11684)
		(layer "In15.Cu")
		(net "RST_ESPI_CPU0_RSTOUT_N")
	)
	(segment
		(start 207.886808 -143.270986)
		(end 209.545174 -143.600932)
		(width 0.11684)
		(layer "In15.Cu")
		(net "RST_ESPI_CPU0_RSTOUT_N")
	)
	(segment
		(start 393.568682 -315.482224)
		(end 393.568682 -318.017906)
		(width 0.11684)
		(layer "In15.Cu")
		(net "RST_ESPI_CPU0_RSTOUT_N")
	)
	(segment
		(start 209.545174 -143.600932)
		(end 223.992694 -145.02384)
		(width 0.11684)
		(layer "In15.Cu")
		(net "RST_ESPI_CPU0_RSTOUT_N")
	)
	(segment
		(start 204.681836 -141.943582)
		(end 207.886808 -143.270986)
		(width 0.11684)
		(layer "In15.Cu")
		(net "RST_ESPI_CPU0_RSTOUT_N")
	)
	(segment
		(start 402.160232 -326.91832)
		(end 402.66366 -326.414892)
		(width 0.11684)
		(layer "In15.Cu")
		(net "RST_ESPI_CPU0_RSTOUT_N")
	)
	(segment
		(start 140.704824 -308.87162)
		(end 150.51151 -308.87162)
		(width 0.10668)
		(layer "F.Cu")
		(net "RST_CPU1_SYS_N")
	)
	(segment
		(start 142.157958 -296.765472)
		(end 138.222482 -300.700948)
		(width 0.10668)
		(layer "F.Cu")
		(net "RST_CPU1_SYS_N")
	)
	(segment
		(start 43.68419 -136.15797)
		(end 35.24377 -144.59839)
		(width 0.10668)
		(layer "F.Cu")
		(net "RST_CPU1_SYS_N")
	)
	(segment
		(start 180.67274 -129.777998)
		(end 180.975 -129.777998)
		(width 0.10668)
		(layer "F.Cu")
		(net "RST_CPU1_SYS_N")
	)
	(segment
		(start 157.48 -134.863332)
		(end 155.94838 -133.331712)
		(width 0.10668)
		(layer "F.Cu")
		(net "RST_CPU1_SYS_N")
	)
	(segment
		(start 155.94838 -133.331712)
		(end 143.400272 -133.331712)
		(width 0.10668)
		(layer "F.Cu")
		(net "RST_CPU1_SYS_N")
	)
	(segment
		(start 131.8768 -126.051818)
		(end 117.819424 -111.994442)
		(width 0.10668)
		(layer "F.Cu")
		(net "RST_CPU1_SYS_N")
	)
	(segment
		(start 117.819424 -111.994442)
		(end 98.805746 -111.994442)
		(width 0.10668)
		(layer "F.Cu")
		(net "RST_CPU1_SYS_N")
	)
	(segment
		(start 87.436452 -126.009146)
		(end 77.287628 -136.15797)
		(width 0.10668)
		(layer "F.Cu")
		(net "RST_CPU1_SYS_N")
	)
	(segment
		(start 13.538454 -329.101704)
		(end 13.980922 -329.101704)
		(width 0.10668)
		(layer "F.Cu")
		(net "RST_CPU1_SYS_N")
	)
	(segment
		(start 155.333954 -322.551552)
		(end 155.079954 -322.551552)
		(width 0.10668)
		(layer "F.Cu")
		(net "RST_CPU1_SYS_N")
	)
	(segment
		(start 35.24377 -144.59839)
		(end 24.945848 -144.59839)
		(width 0.10668)
		(layer "F.Cu")
		(net "RST_CPU1_SYS_N")
	)
	(segment
		(start 98.805746 -111.994442)
		(end 87.436452 -123.363736)
		(width 0.10668)
		(layer "F.Cu")
		(net "RST_CPU1_SYS_N")
	)
	(segment
		(start 138.222482 -306.389278)
		(end 140.704824 -308.87162)
		(width 0.10668)
		(layer "F.Cu")
		(net "RST_CPU1_SYS_N")
	)
	(segment
		(start 12.263374 -207.903064)
		(end 12.263374 -327.826624)
		(width 0.10668)
		(layer "F.Cu")
		(net "RST_CPU1_SYS_N")
	)
	(segment
		(start 180.467 -133.815582)
		(end 180.467 -131.19227)
		(width 0.10668)
		(layer "F.Cu")
		(net "RST_CPU1_SYS_N")
	)
	(segment
		(start 150.51151 -308.87162)
		(end 156.265372 -314.625482)
		(width 0.10668)
		(layer "F.Cu")
		(net "RST_CPU1_SYS_N")
	)
	(segment
		(start 156.265372 -320.140838)
		(end 155.805632 -320.600578)
		(width 0.10668)
		(layer "F.Cu")
		(net "RST_CPU1_SYS_N")
	)
	(segment
		(start 6.766306 -183.178196)
		(end 6.766306 -202.405996)
		(width 0.10668)
		(layer "F.Cu")
		(net "RST_CPU1_SYS_N")
	)
	(segment
		(start 77.287628 -136.15797)
		(end 43.68419 -136.15797)
		(width 0.10668)
		(layer "F.Cu")
		(net "RST_CPU1_SYS_N")
	)
	(segment
		(start 143.400272 -133.331712)
		(end 136.120378 -126.051818)
		(width 0.10668)
		(layer "F.Cu")
		(net "RST_CPU1_SYS_N")
	)
	(segment
		(start 163.66617 -135.947658)
		(end 162.581844 -134.863332)
		(width 0.10668)
		(layer "F.Cu")
		(net "RST_CPU1_SYS_N")
	)
	(segment
		(start 142.157958 -294.880284)
		(end 142.157958 -296.765472)
		(width 0.10668)
		(layer "F.Cu")
		(net "RST_CPU1_SYS_N")
	)
	(segment
		(start 156.265372 -314.625482)
		(end 156.265372 -320.140838)
		(width 0.10668)
		(layer "F.Cu")
		(net "RST_CPU1_SYS_N")
	)
	(segment
		(start 6.766306 -202.405996)
		(end 12.263374 -207.903064)
		(width 0.10668)
		(layer "F.Cu")
		(net "RST_CPU1_SYS_N")
	)
	(segment
		(start 180.876702 -136.600438)
		(end 180.876702 -134.225284)
		(width 0.10668)
		(layer "F.Cu")
		(net "RST_CPU1_SYS_N")
	)
	(segment
		(start 155.805632 -320.600578)
		(end 155.805632 -322.079874)
		(width 0.10668)
		(layer "F.Cu")
		(net "RST_CPU1_SYS_N")
	)
	(segment
		(start 138.222482 -300.700948)
		(end 138.222482 -306.389278)
		(width 0.10668)
		(layer "F.Cu")
		(net "RST_CPU1_SYS_N")
	)
	(segment
		(start 12.263374 -327.826624)
		(end 13.538454 -329.101704)
		(width 0.10668)
		(layer "F.Cu")
		(net "RST_CPU1_SYS_N")
	)
	(segment
		(start 136.120378 -126.051818)
		(end 131.8768 -126.051818)
		(width 0.10668)
		(layer "F.Cu")
		(net "RST_CPU1_SYS_N")
	)
	(segment
		(start 87.436452 -123.363736)
		(end 87.436452 -126.009146)
		(width 0.10668)
		(layer "F.Cu")
		(net "RST_CPU1_SYS_N")
	)
	(segment
		(start 16.839438 -152.7048)
		(end 16.839438 -173.105064)
		(width 0.10668)
		(layer "F.Cu")
		(net "RST_CPU1_SYS_N")
	)
	(segment
		(start 164.122354 -135.947658)
		(end 163.66617 -135.947658)
		(width 0.10668)
		(layer "F.Cu")
		(net "RST_CPU1_SYS_N")
	)
	(segment
		(start 162.581844 -134.863332)
		(end 157.48 -134.863332)
		(width 0.10668)
		(layer "F.Cu")
		(net "RST_CPU1_SYS_N")
	)
	(segment
		(start 180.467 -131.19227)
		(end 180.215794 -130.941064)
		(width 0.10668)
		(layer "F.Cu")
		(net "RST_CPU1_SYS_N")
	)
	(segment
		(start 180.215794 -130.941064)
		(end 180.215794 -130.234944)
		(width 0.10668)
		(layer "F.Cu")
		(net "RST_CPU1_SYS_N")
	)
	(segment
		(start 16.839438 -173.105064)
		(end 6.766306 -183.178196)
		(width 0.10668)
		(layer "F.Cu")
		(net "RST_CPU1_SYS_N")
	)
	(segment
		(start 24.945848 -144.59839)
		(end 16.839438 -152.7048)
		(width 0.10668)
		(layer "F.Cu")
		(net "RST_CPU1_SYS_N")
	)
	(segment
		(start 155.805632 -322.079874)
		(end 155.333954 -322.551552)
		(width 0.10668)
		(layer "F.Cu")
		(net "RST_CPU1_SYS_N")
	)
	(segment
		(start 180.215794 -130.234944)
		(end 180.67274 -129.777998)
		(width 0.10668)
		(layer "F.Cu")
		(net "RST_CPU1_SYS_N")
	)
	(segment
		(start 180.876702 -134.225284)
		(end 180.467 -133.815582)
		(width 0.10668)
		(layer "F.Cu")
		(net "RST_CPU1_SYS_N")
	)
	(via
		(at 155.079954 -322.551552)
		(size 0.508)
		(drill 0.254)
		(layers "F.Cu" "B.Cu")
		(net "RST_CPU1_SYS_N")
	)
	(via
		(at 13.980922 -329.101704)
		(size 0.508)
		(drill 0.254)
		(layers "F.Cu" "B.Cu")
		(net "RST_CPU1_SYS_N")
	)
	(via
		(at 180.876702 -136.600438)
		(size 0.508)
		(drill 0.254)
		(layers "F.Cu" "B.Cu")
		(net "RST_CPU1_SYS_N")
	)
	(via
		(at 108.61421 -324.590918)
		(size 0.508)
		(drill 0.254)
		(layers "F.Cu" "B.Cu")
		(net "RST_CPU1_SYS_N")
	)
	(via
		(at 164.122354 -135.947658)
		(size 0.508)
		(drill 0.254)
		(layers "F.Cu" "B.Cu")
		(net "RST_CPU1_SYS_N")
	)
	(segment
		(start 155.754324 -322.805552)
		(end 155.500324 -322.551552)
		(width 0.10668)
		(layer "B.Cu")
		(net "RST_CPU1_SYS_N")
	)
	(segment
		(start 110.470442 -315.175392)
		(end 110.470442 -323.355716)
		(width 0.10668)
		(layer "B.Cu")
		(net "RST_CPU1_SYS_N")
	)
	(segment
		(start 110.470442 -323.355716)
		(end 109.23524 -324.590918)
		(width 0.10668)
		(layer "B.Cu")
		(net "RST_CPU1_SYS_N")
	)
	(segment
		(start 16.460978 -329.101704)
		(end 18.488406 -327.074276)
		(width 0.10668)
		(layer "B.Cu")
		(net "RST_CPU1_SYS_N")
	)
	(segment
		(start 61.17717 -321.784472)
		(end 69.811138 -313.150504)
		(width 0.10668)
		(layer "B.Cu")
		(net "RST_CPU1_SYS_N")
	)
	(segment
		(start 94.093538 -312.62193)
		(end 107.91698 -312.62193)
		(width 0.10668)
		(layer "B.Cu")
		(net "RST_CPU1_SYS_N")
	)
	(segment
		(start 59.821318 -327.074276)
		(end 61.17717 -325.718424)
		(width 0.10668)
		(layer "B.Cu")
		(net "RST_CPU1_SYS_N")
	)
	(segment
		(start 18.488406 -327.074276)
		(end 59.821318 -327.074276)
		(width 0.10668)
		(layer "B.Cu")
		(net "RST_CPU1_SYS_N")
	)
	(segment
		(start 93.564964 -313.150504)
		(end 94.093538 -312.62193)
		(width 0.10668)
		(layer "B.Cu")
		(net "RST_CPU1_SYS_N")
	)
	(segment
		(start 61.17717 -325.718424)
		(end 61.17717 -321.784472)
		(width 0.10668)
		(layer "B.Cu")
		(net "RST_CPU1_SYS_N")
	)
	(segment
		(start 69.811138 -313.150504)
		(end 93.564964 -313.150504)
		(width 0.10668)
		(layer "B.Cu")
		(net "RST_CPU1_SYS_N")
	)
	(segment
		(start 155.500324 -322.551552)
		(end 155.079954 -322.551552)
		(width 0.10668)
		(layer "B.Cu")
		(net "RST_CPU1_SYS_N")
	)
	(segment
		(start 109.23524 -324.590918)
		(end 108.61421 -324.590918)
		(width 0.10668)
		(layer "B.Cu")
		(net "RST_CPU1_SYS_N")
	)
	(segment
		(start 107.91698 -312.62193)
		(end 110.470442 -315.175392)
		(width 0.10668)
		(layer "B.Cu")
		(net "RST_CPU1_SYS_N")
	)
	(segment
		(start 13.980922 -329.101704)
		(end 16.460978 -329.101704)
		(width 0.10668)
		(layer "B.Cu")
		(net "RST_CPU1_SYS_N")
	)
	(segment
		(start 152.757378 -324.874128)
		(end 146.746468 -324.874128)
		(width 0.11684)
		(layer "In2.Cu")
		(net "RST_CPU1_SYS_N")
	)
	(segment
		(start 179.439316 -138.037824)
		(end 180.876702 -136.600438)
		(width 0.11684)
		(layer "In2.Cu")
		(net "RST_CPU1_SYS_N")
	)
	(segment
		(start 176.47285 -138.037824)
		(end 179.439316 -138.037824)
		(width 0.11684)
		(layer "In2.Cu")
		(net "RST_CPU1_SYS_N")
	)
	(segment
		(start 166.382192 -139.22629)
		(end 175.284384 -139.22629)
		(width 0.11684)
		(layer "In2.Cu")
		(net "RST_CPU1_SYS_N")
	)
	(segment
		(start 146.463258 -324.590918)
		(end 108.61421 -324.590918)
		(width 0.11684)
		(layer "In2.Cu")
		(net "RST_CPU1_SYS_N")
	)
	(segment
		(start 165.61816 -136.361424)
		(end 165.61816 -138.462258)
		(width 0.11684)
		(layer "In2.Cu")
		(net "RST_CPU1_SYS_N")
	)
	(segment
		(start 175.284384 -139.22629)
		(end 176.47285 -138.037824)
		(width 0.11684)
		(layer "In2.Cu")
		(net "RST_CPU1_SYS_N")
	)
	(segment
		(start 165.204394 -135.947658)
		(end 165.61816 -136.361424)
		(width 0.11684)
		(layer "In2.Cu")
		(net "RST_CPU1_SYS_N")
	)
	(segment
		(start 146.746468 -324.874128)
		(end 146.463258 -324.590918)
		(width 0.11684)
		(layer "In2.Cu")
		(net "RST_CPU1_SYS_N")
	)
	(segment
		(start 155.079954 -322.551552)
		(end 152.757378 -324.874128)
		(width 0.11684)
		(layer "In2.Cu")
		(net "RST_CPU1_SYS_N")
	)
	(segment
		(start 165.61816 -138.462258)
		(end 166.382192 -139.22629)
		(width 0.11684)
		(layer "In2.Cu")
		(net "RST_CPU1_SYS_N")
	)
	(segment
		(start 164.122354 -135.947658)
		(end 165.204394 -135.947658)
		(width 0.11684)
		(layer "In2.Cu")
		(net "RST_CPU1_SYS_N")
	)
	(segment
		(start 152.211532 -320.699892)
		(end 151.920448 -320.990976)
		(width 0.10668)
		(layer "F.Cu")
		(net "RST_CPU1_RSMRST_N")
	)
	(segment
		(start 179.959 -129.777998)
		(end 179.660042 -129.777998)
		(width 0.10668)
		(layer "F.Cu")
		(net "RST_CPU1_RSMRST_N")
	)
	(segment
		(start 152.449784 -320.699892)
		(end 152.211532 -320.699892)
		(width 0.10668)
		(layer "F.Cu")
		(net "RST_CPU1_RSMRST_N")
	)
	(segment
		(start 25.658318 -146.842988)
		(end 36.498276 -146.842988)
		(width 0.10668)
		(layer "F.Cu")
		(net "RST_CPU1_RSMRST_N")
	)
	(segment
		(start 8.886952 -201.33945)
		(end 8.886952 -183.869838)
		(width 0.10668)
		(layer "F.Cu")
		(net "RST_CPU1_RSMRST_N")
	)
	(segment
		(start 152.449784 -321.715892)
		(end 152.449784 -320.699892)
		(width 0.10668)
		(layer "F.Cu")
		(net "RST_CPU1_RSMRST_N")
	)
	(segment
		(start 16.329152 -319.644522)
		(end 14.482572 -317.797942)
		(width 0.10668)
		(layer "F.Cu")
		(net "RST_CPU1_RSMRST_N")
	)
	(segment
		(start 75.922632 -304.783998)
		(end 75.922632 -307.512974)
		(width 0.10668)
		(layer "F.Cu")
		(net "RST_CPU1_RSMRST_N")
	)
	(segment
		(start 72.201278 -309.30469)
		(end 61.861446 -319.644522)
		(width 0.10668)
		(layer "F.Cu")
		(net "RST_CPU1_RSMRST_N")
	)
	(segment
		(start 79.47914 -299.59427)
		(end 77.077316 -301.996094)
		(width 0.10668)
		(layer "F.Cu")
		(net "RST_CPU1_RSMRST_N")
	)
	(segment
		(start 14.482572 -206.93507)
		(end 8.886952 -201.33945)
		(width 0.10668)
		(layer "F.Cu")
		(net "RST_CPU1_RSMRST_N")
	)
	(segment
		(start 91.380056 -312.533792)
		(end 87.841836 -308.995572)
		(width 0.10668)
		(layer "F.Cu")
		(net "RST_CPU1_RSMRST_N")
	)
	(segment
		(start 151.920448 -320.990976)
		(end 151.920448 -321.14871)
		(width 0.10668)
		(layer "F.Cu")
		(net "RST_CPU1_RSMRST_N")
	)
	(segment
		(start 133.609842 -128.45415)
		(end 142.970504 -137.814812)
		(width 0.10668)
		(layer "F.Cu")
		(net "RST_CPU1_RSMRST_N")
	)
	(segment
		(start 36.498276 -146.842988)
		(end 45.065188 -138.276076)
		(width 0.10668)
		(layer "F.Cu")
		(net "RST_CPU1_RSMRST_N")
	)
	(segment
		(start 179.660042 -129.777998)
		(end 179.268882 -130.169158)
		(width 0.10668)
		(layer "F.Cu")
		(net "RST_CPU1_RSMRST_N")
	)
	(segment
		(start 131.306824 -128.45415)
		(end 133.609842 -128.45415)
		(width 0.10668)
		(layer "F.Cu")
		(net "RST_CPU1_RSMRST_N")
	)
	(segment
		(start 89.724992 -124.511816)
		(end 99.609148 -114.62766)
		(width 0.10668)
		(layer "F.Cu")
		(net "RST_CPU1_RSMRST_N")
	)
	(segment
		(start 179.451 -135.23214)
		(end 179.819808 -135.600948)
		(width 0.10668)
		(layer "F.Cu")
		(net "RST_CPU1_RSMRST_N")
	)
	(segment
		(start 179.451 -132.732526)
		(end 179.451 -135.23214)
		(width 0.10668)
		(layer "F.Cu")
		(net "RST_CPU1_RSMRST_N")
	)
	(segment
		(start 179.819808 -135.600948)
		(end 179.959 -135.600948)
		(width 0.10668)
		(layer "F.Cu")
		(net "RST_CPU1_RSMRST_N")
	)
	(segment
		(start 85.768434 -299.59427)
		(end 79.47914 -299.59427)
		(width 0.10668)
		(layer "F.Cu")
		(net "RST_CPU1_RSMRST_N")
	)
	(segment
		(start 142.970504 -137.814812)
		(end 166.15918 -137.814812)
		(width 0.10668)
		(layer "F.Cu")
		(net "RST_CPU1_RSMRST_N")
	)
	(segment
		(start 179.268882 -130.169158)
		(end 179.268882 -132.550408)
		(width 0.10668)
		(layer "F.Cu")
		(net "RST_CPU1_RSMRST_N")
	)
	(segment
		(start 89.724992 -127.043942)
		(end 89.724992 -124.511816)
		(width 0.10668)
		(layer "F.Cu")
		(net "RST_CPU1_RSMRST_N")
	)
	(segment
		(start 101.265736 -312.533792)
		(end 91.380056 -312.533792)
		(width 0.10668)
		(layer "F.Cu")
		(net "RST_CPU1_RSMRST_N")
	)
	(segment
		(start 99.609148 -114.62766)
		(end 117.480334 -114.62766)
		(width 0.10668)
		(layer "F.Cu")
		(net "RST_CPU1_RSMRST_N")
	)
	(segment
		(start 74.130916 -309.30469)
		(end 72.201278 -309.30469)
		(width 0.10668)
		(layer "F.Cu")
		(net "RST_CPU1_RSMRST_N")
	)
	(segment
		(start 14.482572 -317.797942)
		(end 14.482572 -206.93507)
		(width 0.10668)
		(layer "F.Cu")
		(net "RST_CPU1_RSMRST_N")
	)
	(segment
		(start 137.927842 -294.070278)
		(end 138.394694 -294.336216)
		(width 0.10668)
		(layer "F.Cu")
		(net "RST_CPU1_RSMRST_N")
	)
	(segment
		(start 78.492858 -138.276076)
		(end 89.724992 -127.043942)
		(width 0.10668)
		(layer "F.Cu")
		(net "RST_CPU1_RSMRST_N")
	)
	(segment
		(start 117.480334 -114.62766)
		(end 131.306824 -128.45415)
		(width 0.10668)
		(layer "F.Cu")
		(net "RST_CPU1_RSMRST_N")
	)
	(segment
		(start 8.886952 -183.869838)
		(end 19.08429 -173.6725)
		(width 0.10668)
		(layer "F.Cu")
		(net "RST_CPU1_RSMRST_N")
	)
	(segment
		(start 107.718098 -323.759576)
		(end 109.214666 -322.263008)
		(width 0.10668)
		(layer "F.Cu")
		(net "RST_CPU1_RSMRST_N")
	)
	(segment
		(start 77.077316 -301.996094)
		(end 75.922632 -304.783998)
		(width 0.10668)
		(layer "F.Cu")
		(net "RST_CPU1_RSMRST_N")
	)
	(segment
		(start 87.841836 -301.667672)
		(end 85.768434 -299.59427)
		(width 0.10668)
		(layer "F.Cu")
		(net "RST_CPU1_RSMRST_N")
	)
	(segment
		(start 109.214666 -320.482722)
		(end 101.265736 -312.533792)
		(width 0.10668)
		(layer "F.Cu")
		(net "RST_CPU1_RSMRST_N")
	)
	(segment
		(start 45.065188 -138.276076)
		(end 78.492858 -138.276076)
		(width 0.10668)
		(layer "F.Cu")
		(net "RST_CPU1_RSMRST_N")
	)
	(segment
		(start 107.702096 -323.759576)
		(end 107.718098 -323.759576)
		(width 0.10668)
		(layer "F.Cu")
		(net "RST_CPU1_RSMRST_N")
	)
	(segment
		(start 19.08429 -173.6725)
		(end 19.08429 -153.417016)
		(width 0.10668)
		(layer "F.Cu")
		(net "RST_CPU1_RSMRST_N")
	)
	(segment
		(start 75.922632 -307.512974)
		(end 74.130916 -309.30469)
		(width 0.10668)
		(layer "F.Cu")
		(net "RST_CPU1_RSMRST_N")
	)
	(segment
		(start 109.214666 -322.263008)
		(end 109.214666 -320.482722)
		(width 0.10668)
		(layer "F.Cu")
		(net "RST_CPU1_RSMRST_N")
	)
	(segment
		(start 166.15918 -137.814812)
		(end 166.615618 -138.27125)
		(width 0.10668)
		(layer "F.Cu")
		(net "RST_CPU1_RSMRST_N")
	)
	(segment
		(start 19.08429 -153.417016)
		(end 25.658318 -146.842988)
		(width 0.10668)
		(layer "F.Cu")
		(net "RST_CPU1_RSMRST_N")
	)
	(segment
		(start 152.449784 -322.731892)
		(end 152.449784 -321.715892)
		(width 0.10668)
		(layer "F.Cu")
		(net "RST_CPU1_RSMRST_N")
	)
	(segment
		(start 87.841836 -308.995572)
		(end 87.841836 -301.667672)
		(width 0.10668)
		(layer "F.Cu")
		(net "RST_CPU1_RSMRST_N")
	)
	(segment
		(start 61.861446 -319.644522)
		(end 16.329152 -319.644522)
		(width 0.10668)
		(layer "F.Cu")
		(net "RST_CPU1_RSMRST_N")
	)
	(segment
		(start 179.268882 -132.550408)
		(end 179.451 -132.732526)
		(width 0.10668)
		(layer "F.Cu")
		(net "RST_CPU1_RSMRST_N")
	)
	(via
		(at 151.920448 -321.14871)
		(size 0.508)
		(drill 0.254)
		(layers "F.Cu" "B.Cu")
		(net "RST_CPU1_RSMRST_N")
	)
	(via
		(at 179.959 -135.600948)
		(size 0.508)
		(drill 0.254)
		(layers "F.Cu" "B.Cu")
		(net "RST_CPU1_RSMRST_N")
	)
	(via
		(at 107.702096 -323.759576)
		(size 0.508)
		(drill 0.254)
		(layers "F.Cu" "B.Cu")
		(net "RST_CPU1_RSMRST_N")
	)
	(via
		(at 166.615618 -138.27125)
		(size 0.508)
		(drill 0.254)
		(layers "F.Cu" "B.Cu")
		(net "RST_CPU1_RSMRST_N")
	)
	(via
		(at 138.394694 -294.336216)
		(size 0.4064)
		(drill 0.2032)
		(layers "F.Cu" "B.Cu")
		(net "RST_CPU1_RSMRST_N")
	)
	(segment
		(start 142.39494 -310.93029)
		(end 138.394694 -306.930044)
		(width 0.11684)
		(layer "In2.Cu")
		(net "RST_CPU1_RSMRST_N")
	)
	(segment
		(start 179.417726 -136.142222)
		(end 179.959 -135.600948)
		(width 0.11684)
		(layer "In2.Cu")
		(net "RST_CPU1_RSMRST_N")
	)
	(segment
		(start 143.01343 -310.93029)
		(end 142.39494 -310.93029)
		(width 0.11684)
		(layer "In2.Cu")
		(net "RST_CPU1_RSMRST_N")
	)
	(segment
		(start 151.867616 -323.145404)
		(end 152.313894 -322.699126)
		(width 0.11684)
		(layer "In2.Cu")
		(net "RST_CPU1_RSMRST_N")
	)
	(segment
		(start 134.245096 -323.451982)
		(end 138.277346 -319.419732)
		(width 0.11684)
		(layer "In2.Cu")
		(net "RST_CPU1_RSMRST_N")
	)
	(segment
		(start 138.277346 -319.419732)
		(end 145.364454 -319.419732)
		(width 0.11684)
		(layer "In2.Cu")
		(net "RST_CPU1_RSMRST_N")
	)
	(segment
		(start 166.888668 -138.5443)
		(end 175.211232 -138.5443)
		(width 0.11684)
		(layer "In2.Cu")
		(net "RST_CPU1_RSMRST_N")
	)
	(segment
		(start 107.702096 -323.759576)
		(end 108.05033 -323.759576)
		(width 0.11684)
		(layer "In2.Cu")
		(net "RST_CPU1_RSMRST_N")
	)
	(segment
		(start 145.183606 -313.100466)
		(end 143.01343 -310.93029)
		(width 0.11684)
		(layer "In2.Cu")
		(net "RST_CPU1_RSMRST_N")
	)
	(segment
		(start 151.920448 -321.14871)
		(end 151.801068 -321.26809)
		(width 0.11684)
		(layer "In2.Cu")
		(net "RST_CPU1_RSMRST_N")
	)
	(segment
		(start 147.568412 -320.417698)
		(end 145.183606 -318.032892)
		(width 0.11684)
		(layer "In2.Cu")
		(net "RST_CPU1_RSMRST_N")
	)
	(segment
		(start 148.583142 -320.417698)
		(end 147.568412 -320.417698)
		(width 0.11684)
		(layer "In2.Cu")
		(net "RST_CPU1_RSMRST_N")
	)
	(segment
		(start 145.183606 -318.032892)
		(end 145.183606 -313.100466)
		(width 0.11684)
		(layer "In2.Cu")
		(net "RST_CPU1_RSMRST_N")
	)
	(segment
		(start 149.090126 -323.145404)
		(end 151.867616 -323.145404)
		(width 0.11684)
		(layer "In2.Cu")
		(net "RST_CPU1_RSMRST_N")
	)
	(segment
		(start 108.05033 -323.759576)
		(end 108.357924 -323.451982)
		(width 0.11684)
		(layer "In2.Cu")
		(net "RST_CPU1_RSMRST_N")
	)
	(segment
		(start 152.313894 -322.699126)
		(end 152.313894 -321.542156)
		(width 0.11684)
		(layer "In2.Cu")
		(net "RST_CPU1_RSMRST_N")
	)
	(segment
		(start 138.394694 -306.930044)
		(end 138.394694 -294.336216)
		(width 0.11684)
		(layer "In2.Cu")
		(net "RST_CPU1_RSMRST_N")
	)
	(segment
		(start 175.211232 -138.5443)
		(end 176.250854 -137.504678)
		(width 0.11684)
		(layer "In2.Cu")
		(net "RST_CPU1_RSMRST_N")
	)
	(segment
		(start 149.433534 -321.26809)
		(end 148.583142 -320.417698)
		(width 0.11684)
		(layer "In2.Cu")
		(net "RST_CPU1_RSMRST_N")
	)
	(segment
		(start 179.121308 -137.504678)
		(end 179.417726 -137.20826)
		(width 0.11684)
		(layer "In2.Cu")
		(net "RST_CPU1_RSMRST_N")
	)
	(segment
		(start 151.801068 -321.26809)
		(end 149.433534 -321.26809)
		(width 0.11684)
		(layer "In2.Cu")
		(net "RST_CPU1_RSMRST_N")
	)
	(segment
		(start 108.357924 -323.451982)
		(end 134.245096 -323.451982)
		(width 0.11684)
		(layer "In2.Cu")
		(net "RST_CPU1_RSMRST_N")
	)
	(segment
		(start 152.313894 -321.542156)
		(end 151.920448 -321.14871)
		(width 0.11684)
		(layer "In2.Cu")
		(net "RST_CPU1_RSMRST_N")
	)
	(segment
		(start 166.615618 -138.27125)
		(end 166.888668 -138.5443)
		(width 0.11684)
		(layer "In2.Cu")
		(net "RST_CPU1_RSMRST_N")
	)
	(segment
		(start 176.250854 -137.504678)
		(end 179.121308 -137.504678)
		(width 0.11684)
		(layer "In2.Cu")
		(net "RST_CPU1_RSMRST_N")
	)
	(segment
		(start 145.364454 -319.419732)
		(end 149.090126 -323.145404)
		(width 0.11684)
		(layer "In2.Cu")
		(net "RST_CPU1_RSMRST_N")
	)
	(segment
		(start 179.417726 -137.20826)
		(end 179.417726 -136.142222)
		(width 0.11684)
		(layer "In2.Cu")
		(net "RST_CPU1_RSMRST_N")
	)
	(segment
		(start 84.3661 -204.803502)
		(end 89.123266 -209.560668)
		(width 0.10668)
		(layer "F.Cu")
		(net "RST_CPU1_RESETL_N")
	)
	(segment
		(start 89.123266 -209.560668)
		(end 89.123266 -216.41308)
		(width 0.10668)
		(layer "F.Cu")
		(net "RST_CPU1_RESETL_N")
	)
	(segment
		(start 89.123266 -216.41308)
		(end 84.517992 -221.018354)
		(width 0.10668)
		(layer "F.Cu")
		(net "RST_CPU1_RESETL_N")
	)
	(segment
		(start 84.517992 -221.018354)
		(end 84.517992 -222.880428)
		(width 0.10668)
		(layer "F.Cu")
		(net "RST_CPU1_RESETL_N")
	)
	(segment
		(start 182.045864 -129.832862)
		(end 182.045864 -130.395472)
		(width 0.10668)
		(layer "F.Cu")
		(net "RST_CPU1_RESETL_N")
	)
	(segment
		(start 70.636384 -199.832214)
		(end 75.607672 -204.803502)
		(width 0.10668)
		(layer "F.Cu")
		(net "RST_CPU1_RESETL_N")
	)
	(segment
		(start 69.667628 -199.832214)
		(end 70.636384 -199.832214)
		(width 0.10668)
		(layer "F.Cu")
		(net "RST_CPU1_RESETL_N")
	)
	(segment
		(start 181.991 -129.777998)
		(end 182.045864 -129.832862)
		(width 0.10668)
		(layer "F.Cu")
		(net "RST_CPU1_RESETL_N")
	)
	(segment
		(start 75.607672 -204.803502)
		(end 84.3661 -204.803502)
		(width 0.10668)
		(layer "F.Cu")
		(net "RST_CPU1_RESETL_N")
	)
	(via
		(at 182.045864 -130.395472)
		(size 0.508)
		(drill 0.254)
		(layers "F.Cu" "B.Cu")
		(net "RST_CPU1_RESETL_N")
	)
	(via
		(at 113.798096 -128.35763)
		(size 0.508)
		(drill 0.254)
		(layers "F.Cu" "B.Cu")
		(net "RST_CPU1_RESETL_N")
	)
	(via
		(at 69.667628 -199.832214)
		(size 0.508)
		(drill 0.254)
		(layers "F.Cu" "B.Cu")
		(net "RST_CPU1_RESETL_N")
	)
	(segment
		(start 69.667628 -199.832214)
		(end 69.772784 -199.93737)
		(width 0.10668)
		(layer "B.Cu")
		(net "RST_CPU1_RESETL_N")
	)
	(segment
		(start 69.42074 -199.832214)
		(end 69.667628 -199.832214)
		(width 0.10668)
		(layer "B.Cu")
		(net "RST_CPU1_RESETL_N")
	)
	(segment
		(start 69.772784 -199.93737)
		(end 69.772784 -201.672952)
		(width 0.10668)
		(layer "B.Cu")
		(net "RST_CPU1_RESETL_N")
	)
	(segment
		(start 68.547234 -201.145902)
		(end 68.547234 -200.70572)
		(width 0.10668)
		(layer "B.Cu")
		(net "RST_CPU1_RESETL_N")
	)
	(segment
		(start 68.547234 -200.70572)
		(end 69.42074 -199.832214)
		(width 0.10668)
		(layer "B.Cu")
		(net "RST_CPU1_RESETL_N")
	)
	(segment
		(start 165.99408 -130.186684)
		(end 169.913046 -130.186684)
		(width 0.11684)
		(layer "In6.Cu")
		(net "RST_CPU1_RESETL_N")
	)
	(segment
		(start 165.516306 -130.664458)
		(end 165.99408 -130.186684)
		(width 0.11684)
		(layer "In6.Cu")
		(net "RST_CPU1_RESETL_N")
	)
	(segment
		(start 169.913046 -130.186684)
		(end 170.628056 -130.901694)
		(width 0.11684)
		(layer "In6.Cu")
		(net "RST_CPU1_RESETL_N")
	)
	(segment
		(start 181.539642 -130.901694)
		(end 182.045864 -130.395472)
		(width 0.11684)
		(layer "In6.Cu")
		(net "RST_CPU1_RESETL_N")
	)
	(segment
		(start 157.443424 -129.12852)
		(end 158.979362 -130.664458)
		(width 0.11684)
		(layer "In6.Cu")
		(net "RST_CPU1_RESETL_N")
	)
	(segment
		(start 158.979362 -130.664458)
		(end 165.516306 -130.664458)
		(width 0.11684)
		(layer "In6.Cu")
		(net "RST_CPU1_RESETL_N")
	)
	(segment
		(start 170.628056 -130.901694)
		(end 181.539642 -130.901694)
		(width 0.11684)
		(layer "In6.Cu")
		(net "RST_CPU1_RESETL_N")
	)
	(segment
		(start 114.568986 -129.12852)
		(end 157.443424 -129.12852)
		(width 0.11684)
		(layer "In6.Cu")
		(net "RST_CPU1_RESETL_N")
	)
	(segment
		(start 113.798096 -128.35763)
		(end 114.568986 -129.12852)
		(width 0.11684)
		(layer "In6.Cu")
		(net "RST_CPU1_RESETL_N")
	)
	(segment
		(start 40.404796 -155.38323)
		(end 32.156908 -163.631118)
		(width 0.11684)
		(layer "In11.Cu")
		(net "RST_CPU1_RESETL_N")
	)
	(segment
		(start 40.64254 -190.279782)
		(end 59.949842 -190.279782)
		(width 0.11684)
		(layer "In11.Cu")
		(net "RST_CPU1_RESETL_N")
	)
	(segment
		(start 112.924336 -130.037586)
		(end 107.935268 -135.026654)
		(width 0.11684)
		(layer "In11.Cu")
		(net "RST_CPU1_RESETL_N")
	)
	(segment
		(start 52.627022 -135.026654)
		(end 40.404796 -147.24888)
		(width 0.11684)
		(layer "In11.Cu")
		(net "RST_CPU1_RESETL_N")
	)
	(segment
		(start 32.156908 -177.483008)
		(end 38.072822 -183.398922)
		(width 0.11684)
		(layer "In11.Cu")
		(net "RST_CPU1_RESETL_N")
	)
	(segment
		(start 59.949842 -190.279782)
		(end 67.036696 -197.366636)
		(width 0.11684)
		(layer "In11.Cu")
		(net "RST_CPU1_RESETL_N")
	)
	(segment
		(start 40.404796 -147.24888)
		(end 40.404796 -155.38323)
		(width 0.11684)
		(layer "In11.Cu")
		(net "RST_CPU1_RESETL_N")
	)
	(segment
		(start 67.036696 -197.366636)
		(end 67.036696 -198.911972)
		(width 0.11684)
		(layer "In11.Cu")
		(net "RST_CPU1_RESETL_N")
	)
	(segment
		(start 69.524626 -199.975216)
		(end 69.667628 -199.832214)
		(width 0.11684)
		(layer "In11.Cu")
		(net "RST_CPU1_RESETL_N")
	)
	(segment
		(start 112.924336 -129.23139)
		(end 112.924336 -130.037586)
		(width 0.11684)
		(layer "In11.Cu")
		(net "RST_CPU1_RESETL_N")
	)
	(segment
		(start 38.072822 -187.710064)
		(end 40.64254 -190.279782)
		(width 0.11684)
		(layer "In11.Cu")
		(net "RST_CPU1_RESETL_N")
	)
	(segment
		(start 38.072822 -183.398922)
		(end 38.072822 -187.710064)
		(width 0.11684)
		(layer "In11.Cu")
		(net "RST_CPU1_RESETL_N")
	)
	(segment
		(start 32.156908 -163.631118)
		(end 32.156908 -177.483008)
		(width 0.11684)
		(layer "In11.Cu")
		(net "RST_CPU1_RESETL_N")
	)
	(segment
		(start 113.798096 -128.35763)
		(end 112.924336 -129.23139)
		(width 0.11684)
		(layer "In11.Cu")
		(net "RST_CPU1_RESETL_N")
	)
	(segment
		(start 107.935268 -135.026654)
		(end 52.627022 -135.026654)
		(width 0.11684)
		(layer "In11.Cu")
		(net "RST_CPU1_RESETL_N")
	)
	(segment
		(start 67.036696 -198.911972)
		(end 68.09994 -199.975216)
		(width 0.11684)
		(layer "In11.Cu")
		(net "RST_CPU1_RESETL_N")
	)
	(segment
		(start 68.09994 -199.975216)
		(end 69.524626 -199.975216)
		(width 0.11684)
		(layer "In11.Cu")
		(net "RST_CPU1_RESETL_N")
	)
	(segment
		(start 181.922166 -118.652798)
		(end 181.532276 -119.042688)
		(width 0.10668)
		(layer "F.Cu")
		(net "RST_CPU1_PERST1_R_N")
	)
	(segment
		(start 178.943 -137.232898)
		(end 178.943 -136.616948)
		(width 0.10668)
		(layer "F.Cu")
		(net "RST_CPU1_PERST1_R_N")
	)
	(via
		(at 178.943 -136.616948)
		(size 0.508)
		(drill 0.254)
		(layers "F.Cu" "B.Cu")
		(net "RST_CPU1_PERST1_R_N")
	)
	(via
		(at 181.532276 -119.042688)
		(size 0.4572)
		(drill 0.254)
		(layers "F.Cu" "B.Cu")
		(net "RST_CPU1_PERST1_R_N")
	)
	(segment
		(start 181.1401 -123.567952)
		(end 179.936902 -124.77115)
		(width 0.11684)
		(layer "In2.Cu")
		(net "RST_CPU1_PERST1_R_N")
	)
	(segment
		(start 181.382162 -119.042688)
		(end 181.1401 -119.28475)
		(width 0.11684)
		(layer "In2.Cu")
		(net "RST_CPU1_PERST1_R_N")
	)
	(segment
		(start 179.46497 -128.73482)
		(end 179.46497 -129.57048)
		(width 0.11684)
		(layer "In2.Cu")
		(net "RST_CPU1_PERST1_R_N")
	)
	(segment
		(start 178.9303 -135.697976)
		(end 178.9303 -136.604248)
		(width 0.11684)
		(layer "In2.Cu")
		(net "RST_CPU1_PERST1_R_N")
	)
	(segment
		(start 178.9303 -136.604248)
		(end 178.943 -136.616948)
		(width 0.11684)
		(layer "In2.Cu")
		(net "RST_CPU1_PERST1_R_N")
	)
	(segment
		(start 179.46497 -129.57048)
		(end 179.264564 -129.770886)
		(width 0.11684)
		(layer "In2.Cu")
		(net "RST_CPU1_PERST1_R_N")
	)
	(segment
		(start 181.1401 -119.28475)
		(end 181.1401 -123.567952)
		(width 0.11684)
		(layer "In2.Cu")
		(net "RST_CPU1_PERST1_R_N")
	)
	(segment
		(start 179.264564 -131.994148)
		(end 179.46497 -132.194554)
		(width 0.11684)
		(layer "In2.Cu")
		(net "RST_CPU1_PERST1_R_N")
	)
	(segment
		(start 179.264564 -129.770886)
		(end 179.264564 -131.994148)
		(width 0.11684)
		(layer "In2.Cu")
		(net "RST_CPU1_PERST1_R_N")
	)
	(segment
		(start 179.46497 -135.163306)
		(end 178.9303 -135.697976)
		(width 0.11684)
		(layer "In2.Cu")
		(net "RST_CPU1_PERST1_R_N")
	)
	(segment
		(start 181.532276 -119.042688)
		(end 181.382162 -119.042688)
		(width 0.11684)
		(layer "In2.Cu")
		(net "RST_CPU1_PERST1_R_N")
	)
	(segment
		(start 179.936902 -124.77115)
		(end 179.936902 -128.262888)
		(width 0.11684)
		(layer "In2.Cu")
		(net "RST_CPU1_PERST1_R_N")
	)
	(segment
		(start 179.46497 -132.194554)
		(end 179.46497 -135.163306)
		(width 0.11684)
		(layer "In2.Cu")
		(net "RST_CPU1_PERST1_R_N")
	)
	(segment
		(start 179.936902 -128.262888)
		(end 179.46497 -128.73482)
		(width 0.11684)
		(layer "In2.Cu")
		(net "RST_CPU1_PERST1_R_N")
	)
	(segment
		(start 113.487962 -294.070278)
		(end 113.954814 -294.336216)
		(width 0.10668)
		(layer "F.Cu")
		(net "RST_CPU1_PERST1_N")
	)
	(segment
		(start 178.943 -139.772898)
		(end 178.943 -138.648948)
		(width 0.10668)
		(layer "F.Cu")
		(net "RST_CPU1_PERST1_N")
	)
	(segment
		(start 178.943 -138.648948)
		(end 178.943 -138.032998)
		(width 0.10668)
		(layer "F.Cu")
		(net "RST_CPU1_PERST1_N")
	)
	(via
		(at 118.304564 -133.347714)
		(size 0.508)
		(drill 0.254)
		(layers "F.Cu" "B.Cu")
		(net "RST_CPU1_PERST1_N")
	)
	(via
		(at 178.943 -138.648948)
		(size 0.508)
		(drill 0.254)
		(layers "F.Cu" "B.Cu")
		(net "RST_CPU1_PERST1_N")
	)
	(via
		(at 107.734354 -115.106196)
		(size 0.508)
		(drill 0.254)
		(layers "F.Cu" "B.Cu")
		(net "RST_CPU1_PERST1_N")
	)
	(via
		(at 113.954814 -294.336216)
		(size 0.4064)
		(drill 0.2032)
		(layers "F.Cu" "B.Cu")
		(net "RST_CPU1_PERST1_N")
	)
	(segment
		(start 39.768018 -143.80972)
		(end 39.768018 -158.000192)
		(width 0.10668)
		(layer "B.Cu")
		(net "RST_CPU1_PERST1_N")
	)
	(segment
		(start 114.826034 -295.231312)
		(end 114.826034 -294.875712)
		(width 0.10668)
		(layer "B.Cu")
		(net "RST_CPU1_PERST1_N")
	)
	(segment
		(start 13.823442 -325.654924)
		(end 59.087258 -325.654924)
		(width 0.10668)
		(layer "B.Cu")
		(net "RST_CPU1_PERST1_N")
	)
	(segment
		(start 115.339114 -298.011596)
		(end 115.339114 -295.744392)
		(width 0.10668)
		(layer "B.Cu")
		(net "RST_CPU1_PERST1_N")
	)
	(segment
		(start 68.471542 -115.106196)
		(end 39.768018 -143.80972)
		(width 0.10668)
		(layer "B.Cu")
		(net "RST_CPU1_PERST1_N")
	)
	(segment
		(start 115.339114 -295.744392)
		(end 114.826034 -295.231312)
		(width 0.10668)
		(layer "B.Cu")
		(net "RST_CPU1_PERST1_N")
	)
	(segment
		(start 114.286538 -294.336216)
		(end 113.954814 -294.336216)
		(width 0.10668)
		(layer "B.Cu")
		(net "RST_CPU1_PERST1_N")
	)
	(segment
		(start 59.087258 -325.654924)
		(end 59.539378 -325.202804)
		(width 0.10668)
		(layer "B.Cu")
		(net "RST_CPU1_PERST1_N")
	)
	(segment
		(start 59.539378 -325.202804)
		(end 59.539378 -321.477132)
		(width 0.10668)
		(layer "B.Cu")
		(net "RST_CPU1_PERST1_N")
	)
	(segment
		(start 107.734354 -115.106196)
		(end 68.471542 -115.106196)
		(width 0.10668)
		(layer "B.Cu")
		(net "RST_CPU1_PERST1_N")
	)
	(segment
		(start 96.224852 -308.59984)
		(end 104.75087 -308.59984)
		(width 0.10668)
		(layer "B.Cu")
		(net "RST_CPU1_PERST1_N")
	)
	(segment
		(start 93.022166 -311.802526)
		(end 96.224852 -308.59984)
		(width 0.10668)
		(layer "B.Cu")
		(net "RST_CPU1_PERST1_N")
	)
	(segment
		(start 11.151616 -186.616594)
		(end 11.151616 -322.983098)
		(width 0.10668)
		(layer "B.Cu")
		(net "RST_CPU1_PERST1_N")
	)
	(segment
		(start 39.768018 -158.000192)
		(end 11.151616 -186.616594)
		(width 0.10668)
		(layer "B.Cu")
		(net "RST_CPU1_PERST1_N")
	)
	(segment
		(start 104.75087 -308.59984)
		(end 115.339114 -298.011596)
		(width 0.10668)
		(layer "B.Cu")
		(net "RST_CPU1_PERST1_N")
	)
	(segment
		(start 114.826034 -294.875712)
		(end 114.286538 -294.336216)
		(width 0.10668)
		(layer "B.Cu")
		(net "RST_CPU1_PERST1_N")
	)
	(segment
		(start 11.151616 -322.983098)
		(end 13.823442 -325.654924)
		(width 0.10668)
		(layer "B.Cu")
		(net "RST_CPU1_PERST1_N")
	)
	(segment
		(start 59.539378 -321.477132)
		(end 69.213984 -311.802526)
		(width 0.10668)
		(layer "B.Cu")
		(net "RST_CPU1_PERST1_N")
	)
	(segment
		(start 69.213984 -311.802526)
		(end 93.022166 -311.802526)
		(width 0.10668)
		(layer "B.Cu")
		(net "RST_CPU1_PERST1_N")
	)
	(segment
		(start 118.304564 -125.508766)
		(end 107.901994 -115.106196)
		(width 0.11684)
		(layer "In4.Cu")
		(net "RST_CPU1_PERST1_N")
	)
	(segment
		(start 118.304564 -133.347714)
		(end 118.304564 -125.508766)
		(width 0.11684)
		(layer "In4.Cu")
		(net "RST_CPU1_PERST1_N")
	)
	(segment
		(start 107.901994 -115.106196)
		(end 107.734354 -115.106196)
		(width 0.11684)
		(layer "In4.Cu")
		(net "RST_CPU1_PERST1_N")
	)
	(segment
		(start 161.906712 -133.792722)
		(end 156.173932 -133.792722)
		(width 0.11684)
		(layer "In6.Cu")
		(net "RST_CPU1_PERST1_N")
	)
	(segment
		(start 178.411632 -138.11758)
		(end 172.223938 -138.11758)
		(width 0.11684)
		(layer "In6.Cu")
		(net "RST_CPU1_PERST1_N")
	)
	(segment
		(start 155.236672 -132.855462)
		(end 118.796816 -132.855462)
		(width 0.11684)
		(layer "In6.Cu")
		(net "RST_CPU1_PERST1_N")
	)
	(segment
		(start 169.335704 -135.229346)
		(end 163.343336 -135.229346)
		(width 0.11684)
		(layer "In6.Cu")
		(net "RST_CPU1_PERST1_N")
	)
	(segment
		(start 118.796816 -132.855462)
		(end 118.304564 -133.347714)
		(width 0.11684)
		(layer "In6.Cu")
		(net "RST_CPU1_PERST1_N")
	)
	(segment
		(start 163.343336 -135.229346)
		(end 161.906712 -133.792722)
		(width 0.11684)
		(layer "In6.Cu")
		(net "RST_CPU1_PERST1_N")
	)
	(segment
		(start 172.223938 -138.11758)
		(end 169.335704 -135.229346)
		(width 0.11684)
		(layer "In6.Cu")
		(net "RST_CPU1_PERST1_N")
	)
	(segment
		(start 156.173932 -133.792722)
		(end 155.236672 -132.855462)
		(width 0.11684)
		(layer "In6.Cu")
		(net "RST_CPU1_PERST1_N")
	)
	(segment
		(start 178.943 -138.648948)
		(end 178.411632 -138.11758)
		(width 0.11684)
		(layer "In6.Cu")
		(net "RST_CPU1_PERST1_N")
	)
	(segment
		(start 177.927 -132.70484)
		(end 177.7492 -132.52704)
		(width 0.10668)
		(layer "F.Cu")
		(net "RST_CPU1_PERST0_R_N")
	)
	(segment
		(start 180.32222 -121.052844)
		(end 179.93233 -121.442734)
		(width 0.10668)
		(layer "F.Cu")
		(net "RST_CPU1_PERST0_R_N")
	)
	(segment
		(start 177.927 -133.168898)
		(end 177.927 -132.70484)
		(width 0.10668)
		(layer "F.Cu")
		(net "RST_CPU1_PERST0_R_N")
	)
	(via
		(at 179.93233 -121.442734)
		(size 0.4572)
		(drill 0.254)
		(layers "F.Cu" "B.Cu")
		(net "RST_CPU1_PERST0_R_N")
	)
	(via
		(at 177.7492 -132.52704)
		(size 0.508)
		(drill 0.254)
		(layers "F.Cu" "B.Cu")
		(net "RST_CPU1_PERST0_R_N")
	)
	(segment
		(start 179.540408 -122.619516)
		(end 178.488848 -123.671076)
		(width 0.11684)
		(layer "In2.Cu")
		(net "RST_CPU1_PERST0_R_N")
	)
	(segment
		(start 178.447192 -128.710944)
		(end 177.14214 -130.015996)
		(width 0.11684)
		(layer "In2.Cu")
		(net "RST_CPU1_PERST0_R_N")
	)
	(segment
		(start 179.540408 -121.834656)
		(end 179.540408 -122.619516)
		(width 0.11684)
		(layer "In2.Cu")
		(net "RST_CPU1_PERST0_R_N")
	)
	(segment
		(start 178.447192 -128.025652)
		(end 178.447192 -128.710944)
		(width 0.11684)
		(layer "In2.Cu")
		(net "RST_CPU1_PERST0_R_N")
	)
	(segment
		(start 177.14214 -131.91998)
		(end 177.7492 -132.52704)
		(width 0.11684)
		(layer "In2.Cu")
		(net "RST_CPU1_PERST0_R_N")
	)
	(segment
		(start 178.488848 -127.983996)
		(end 178.447192 -128.025652)
		(width 0.11684)
		(layer "In2.Cu")
		(net "RST_CPU1_PERST0_R_N")
	)
	(segment
		(start 179.93233 -121.442734)
		(end 179.540408 -121.834656)
		(width 0.11684)
		(layer "In2.Cu")
		(net "RST_CPU1_PERST0_R_N")
	)
	(segment
		(start 177.14214 -130.015996)
		(end 177.14214 -131.91998)
		(width 0.11684)
		(layer "In2.Cu")
		(net "RST_CPU1_PERST0_R_N")
	)
	(segment
		(start 178.488848 -123.671076)
		(end 178.488848 -127.983996)
		(width 0.11684)
		(layer "In2.Cu")
		(net "RST_CPU1_PERST0_R_N")
	)
	(segment
		(start 213.286086 -187.682378)
		(end 213.286086 -200.051416)
		(width 0.10668)
		(layer "F.Cu")
		(net "RST_CPU1_PERST0_N")
	)
	(segment
		(start 178.00066 -136.583928)
		(end 178.00066 -134.042658)
		(width 0.10668)
		(layer "F.Cu")
		(net "RST_CPU1_PERST0_N")
	)
	(segment
		(start 211.357972 -183.027574)
		(end 213.286086 -187.682378)
		(width 0.10668)
		(layer "F.Cu")
		(net "RST_CPU1_PERST0_N")
	)
	(segment
		(start 130.577844 -224.50044)
		(end 131.044696 -224.234502)
		(width 0.10668)
		(layer "F.Cu")
		(net "RST_CPU1_PERST0_N")
	)
	(segment
		(start 178.00066 -134.042658)
		(end 177.927 -133.968998)
		(width 0.10668)
		(layer "F.Cu")
		(net "RST_CPU1_PERST0_N")
	)
	(segment
		(start 209.390488 -203.947014)
		(end 208.913476 -203.947014)
		(width 0.10668)
		(layer "F.Cu")
		(net "RST_CPU1_PERST0_N")
	)
	(segment
		(start 194.477894 -168.470326)
		(end 196.800724 -168.470326)
		(width 0.10668)
		(layer "F.Cu")
		(net "RST_CPU1_PERST0_N")
	)
	(segment
		(start 177.927 -137.232898)
		(end 178.00066 -137.159238)
		(width 0.10668)
		(layer "F.Cu")
		(net "RST_CPU1_PERST0_N")
	)
	(segment
		(start 178.00066 -137.159238)
		(end 178.00066 -136.583928)
		(width 0.10668)
		(layer "F.Cu")
		(net "RST_CPU1_PERST0_N")
	)
	(segment
		(start 192.46723 -166.459662)
		(end 194.477894 -168.470326)
		(width 0.10668)
		(layer "F.Cu")
		(net "RST_CPU1_PERST0_N")
	)
	(segment
		(start 196.800724 -168.470326)
		(end 211.357972 -183.027574)
		(width 0.10668)
		(layer "F.Cu")
		(net "RST_CPU1_PERST0_N")
	)
	(segment
		(start 213.286086 -200.051416)
		(end 209.390488 -203.947014)
		(width 0.10668)
		(layer "F.Cu")
		(net "RST_CPU1_PERST0_N")
	)
	(via
		(at 208.913476 -203.947014)
		(size 0.508)
		(drill 0.254)
		(layers "F.Cu" "B.Cu")
		(net "RST_CPU1_PERST0_N")
	)
	(via
		(at 192.46723 -166.459662)
		(size 0.508)
		(drill 0.254)
		(layers "F.Cu" "B.Cu")
		(net "RST_CPU1_PERST0_N")
	)
	(via
		(at 131.044696 -224.234502)
		(size 0.4064)
		(drill 0.2032)
		(layers "F.Cu" "B.Cu")
		(net "RST_CPU1_PERST0_N")
	)
	(via
		(at 161.606738 -195.879466)
		(size 0.508)
		(drill 0.254)
		(layers "F.Cu" "B.Cu")
		(net "RST_CPU1_PERST0_N")
	)
	(via
		(at 178.00066 -136.583928)
		(size 0.508)
		(drill 0.254)
		(layers "F.Cu" "B.Cu")
		(net "RST_CPU1_PERST0_N")
	)
	(segment
		(start 131.044696 -223.328992)
		(end 131.044696 -224.234502)
		(width 0.11684)
		(layer "In2.Cu")
		(net "RST_CPU1_PERST0_N")
	)
	(segment
		(start 134.853426 -216.965022)
		(end 130.566414 -221.252034)
		(width 0.11684)
		(layer "In2.Cu")
		(net "RST_CPU1_PERST0_N")
	)
	(segment
		(start 158.728156 -195.066666)
		(end 154.136852 -199.65797)
		(width 0.11684)
		(layer "In2.Cu")
		(net "RST_CPU1_PERST0_N")
	)
	(segment
		(start 130.566414 -221.252034)
		(end 130.566414 -222.85071)
		(width 0.11684)
		(layer "In2.Cu")
		(net "RST_CPU1_PERST0_N")
	)
	(segment
		(start 137.827004 -209.786474)
		(end 134.853426 -216.965022)
		(width 0.11684)
		(layer "In2.Cu")
		(net "RST_CPU1_PERST0_N")
	)
	(segment
		(start 151.85644 -200.832466)
		(end 146.781012 -200.832466)
		(width 0.11684)
		(layer "In2.Cu")
		(net "RST_CPU1_PERST0_N")
	)
	(segment
		(start 146.781012 -200.832466)
		(end 137.827004 -209.786474)
		(width 0.11684)
		(layer "In2.Cu")
		(net "RST_CPU1_PERST0_N")
	)
	(segment
		(start 160.741614 -195.066666)
		(end 158.728156 -195.066666)
		(width 0.11684)
		(layer "In2.Cu")
		(net "RST_CPU1_PERST0_N")
	)
	(segment
		(start 161.606738 -195.879466)
		(end 161.554414 -195.879466)
		(width 0.11684)
		(layer "In2.Cu")
		(net "RST_CPU1_PERST0_N")
	)
	(segment
		(start 161.554414 -195.879466)
		(end 160.741614 -195.066666)
		(width 0.11684)
		(layer "In2.Cu")
		(net "RST_CPU1_PERST0_N")
	)
	(segment
		(start 153.030936 -199.65797)
		(end 151.85644 -200.832466)
		(width 0.11684)
		(layer "In2.Cu")
		(net "RST_CPU1_PERST0_N")
	)
	(segment
		(start 130.566414 -222.85071)
		(end 131.044696 -223.328992)
		(width 0.11684)
		(layer "In2.Cu")
		(net "RST_CPU1_PERST0_N")
	)
	(segment
		(start 154.136852 -199.65797)
		(end 153.030936 -199.65797)
		(width 0.11684)
		(layer "In2.Cu")
		(net "RST_CPU1_PERST0_N")
	)
	(segment
		(start 181.910736 -165.790372)
		(end 181.540658 -165.790372)
		(width 0.11684)
		(layer "In4.Cu")
		(net "RST_CPU1_PERST0_N")
	)
	(segment
		(start 183.153812 -167.033448)
		(end 181.910736 -165.790372)
		(width 0.11684)
		(layer "In4.Cu")
		(net "RST_CPU1_PERST0_N")
	)
	(segment
		(start 179.693824 -159.231076)
		(end 180.330348 -158.594552)
		(width 0.11684)
		(layer "In4.Cu")
		(net "RST_CPU1_PERST0_N")
	)
	(segment
		(start 181.540658 -165.790372)
		(end 179.693824 -163.943538)
		(width 0.11684)
		(layer "In4.Cu")
		(net "RST_CPU1_PERST0_N")
	)
	(segment
		(start 177.44821 -140.499592)
		(end 177.44821 -137.136378)
		(width 0.11684)
		(layer "In4.Cu")
		(net "RST_CPU1_PERST0_N")
	)
	(segment
		(start 180.330348 -147.203414)
		(end 181.282848 -146.250914)
		(width 0.11684)
		(layer "In4.Cu")
		(net "RST_CPU1_PERST0_N")
	)
	(segment
		(start 179.693824 -163.943538)
		(end 179.693824 -159.231076)
		(width 0.11684)
		(layer "In4.Cu")
		(net "RST_CPU1_PERST0_N")
	)
	(segment
		(start 177.44821 -137.136378)
		(end 178.00066 -136.583928)
		(width 0.11684)
		(layer "In4.Cu")
		(net "RST_CPU1_PERST0_N")
	)
	(segment
		(start 181.282848 -144.33423)
		(end 177.44821 -140.499592)
		(width 0.11684)
		(layer "In4.Cu")
		(net "RST_CPU1_PERST0_N")
	)
	(segment
		(start 191.893444 -167.033448)
		(end 183.153812 -167.033448)
		(width 0.11684)
		(layer "In4.Cu")
		(net "RST_CPU1_PERST0_N")
	)
	(segment
		(start 192.46723 -166.459662)
		(end 191.893444 -167.033448)
		(width 0.11684)
		(layer "In4.Cu")
		(net "RST_CPU1_PERST0_N")
	)
	(segment
		(start 180.330348 -158.594552)
		(end 180.330348 -147.203414)
		(width 0.11684)
		(layer "In4.Cu")
		(net "RST_CPU1_PERST0_N")
	)
	(segment
		(start 181.282848 -146.250914)
		(end 181.282848 -144.33423)
		(width 0.11684)
		(layer "In4.Cu")
		(net "RST_CPU1_PERST0_N")
	)
	(segment
		(start 205.391766 -196.29628)
		(end 205.702916 -195.98513)
		(width 0.11684)
		(layer "In13.Cu")
		(net "RST_CPU1_PERST0_N")
	)
	(segment
		(start 190.790322 -196.01561)
		(end 191.838072 -196.01561)
		(width 0.11684)
		(layer "In13.Cu")
		(net "RST_CPU1_PERST0_N")
	)
	(segment
		(start 182.804816 -196.308472)
		(end 183.07304 -196.040248)
		(width 0.11684)
		(layer "In13.Cu")
		(net "RST_CPU1_PERST0_N")
	)
	(segment
		(start 170.346624 -195.40728)
		(end 176.255172 -195.40728)
		(width 0.11684)
		(layer "In13.Cu")
		(net "RST_CPU1_PERST0_N")
	)
	(segment
		(start 191.838072 -196.01561)
		(end 192.155572 -196.33311)
		(width 0.11684)
		(layer "In13.Cu")
		(net "RST_CPU1_PERST0_N")
	)
	(segment
		(start 162.096196 -195.390008)
		(end 167.695626 -195.390008)
		(width 0.11684)
		(layer "In13.Cu")
		(net "RST_CPU1_PERST0_N")
	)
	(segment
		(start 198.041006 -196.33311)
		(end 198.300594 -196.073522)
		(width 0.11684)
		(layer "In13.Cu")
		(net "RST_CPU1_PERST0_N")
	)
	(segment
		(start 198.300594 -196.073522)
		(end 199.234298 -196.073522)
		(width 0.11684)
		(layer "In13.Cu")
		(net "RST_CPU1_PERST0_N")
	)
	(segment
		(start 170.140122 -195.200778)
		(end 170.346624 -195.40728)
		(width 0.11684)
		(layer "In13.Cu")
		(net "RST_CPU1_PERST0_N")
	)
	(segment
		(start 183.07304 -196.040248)
		(end 184.207658 -196.040248)
		(width 0.11684)
		(layer "In13.Cu")
		(net "RST_CPU1_PERST0_N")
	)
	(segment
		(start 190.472822 -196.33311)
		(end 190.790322 -196.01561)
		(width 0.11684)
		(layer "In13.Cu")
		(net "RST_CPU1_PERST0_N")
	)
	(segment
		(start 208.315814 -203.349352)
		(end 208.913476 -203.947014)
		(width 0.11684)
		(layer "In13.Cu")
		(net "RST_CPU1_PERST0_N")
	)
	(segment
		(start 184.207658 -196.040248)
		(end 184.50052 -196.33311)
		(width 0.11684)
		(layer "In13.Cu")
		(net "RST_CPU1_PERST0_N")
	)
	(segment
		(start 205.702916 -195.98513)
		(end 206.928974 -195.98513)
		(width 0.11684)
		(layer "In13.Cu")
		(net "RST_CPU1_PERST0_N")
	)
	(segment
		(start 199.457056 -196.29628)
		(end 205.391766 -196.29628)
		(width 0.11684)
		(layer "In13.Cu")
		(net "RST_CPU1_PERST0_N")
	)
	(segment
		(start 206.928974 -195.98513)
		(end 208.315814 -197.37197)
		(width 0.11684)
		(layer "In13.Cu")
		(net "RST_CPU1_PERST0_N")
	)
	(segment
		(start 161.606738 -195.879466)
		(end 162.096196 -195.390008)
		(width 0.11684)
		(layer "In13.Cu")
		(net "RST_CPU1_PERST0_N")
	)
	(segment
		(start 192.155572 -196.33311)
		(end 198.041006 -196.33311)
		(width 0.11684)
		(layer "In13.Cu")
		(net "RST_CPU1_PERST0_N")
	)
	(segment
		(start 167.695626 -195.390008)
		(end 167.884856 -195.200778)
		(width 0.11684)
		(layer "In13.Cu")
		(net "RST_CPU1_PERST0_N")
	)
	(segment
		(start 167.884856 -195.200778)
		(end 170.140122 -195.200778)
		(width 0.11684)
		(layer "In13.Cu")
		(net "RST_CPU1_PERST0_N")
	)
	(segment
		(start 184.50052 -196.33311)
		(end 190.472822 -196.33311)
		(width 0.11684)
		(layer "In13.Cu")
		(net "RST_CPU1_PERST0_N")
	)
	(segment
		(start 177.156364 -196.308472)
		(end 182.804816 -196.308472)
		(width 0.11684)
		(layer "In13.Cu")
		(net "RST_CPU1_PERST0_N")
	)
	(segment
		(start 199.234298 -196.073522)
		(end 199.457056 -196.29628)
		(width 0.11684)
		(layer "In13.Cu")
		(net "RST_CPU1_PERST0_N")
	)
	(segment
		(start 176.255172 -195.40728)
		(end 177.156364 -196.308472)
		(width 0.11684)
		(layer "In13.Cu")
		(net "RST_CPU1_PERST0_N")
	)
	(segment
		(start 208.315814 -197.37197)
		(end 208.315814 -203.349352)
		(width 0.11684)
		(layer "In13.Cu")
		(net "RST_CPU1_PERST0_N")
	)
	(segment
		(start 293.438072 -52.02809)
		(end 295.459912 -52.02809)
		(width 0.10668)
		(layer "F.Cu")
		(net "RST_CPU0_SYS_N")
	)
	(segment
		(start 299.807884 -51.092354)
		(end 300.699932 -51.984402)
		(width 0.10668)
		(layer "F.Cu")
		(net "RST_CPU0_SYS_N")
	)
	(segment
		(start 296.395648 -51.092354)
		(end 299.807884 -51.092354)
		(width 0.10668)
		(layer "F.Cu")
		(net "RST_CPU0_SYS_N")
	)
	(segment
		(start 295.459912 -52.02809)
		(end 296.395648 -51.092354)
		(width 0.10668)
		(layer "F.Cu")
		(net "RST_CPU0_SYS_N")
	)
	(segment
		(start 178.943 -133.968998)
		(end 178.943 -134.584948)
		(width 0.10668)
		(layer "F.Cu")
		(net "RST_CPU0_SYS_N")
	)
	(segment
		(start 300.699932 -51.984402)
		(end 300.699932 -52.63007)
		(width 0.10668)
		(layer "F.Cu")
		(net "RST_CPU0_SYS_N")
	)
	(segment
		(start 390.098026 -294.88003)
		(end 390.564878 -295.145968)
		(width 0.10668)
		(layer "F.Cu")
		(net "RST_CPU0_SYS_N")
	)
	(segment
		(start 293.438072 -52.02809)
		(end 293.438072 -52.665376)
		(width 0.10668)
		(layer "F.Cu")
		(net "RST_CPU0_SYS_N")
	)
	(via
		(at 293.438072 -52.665376)
		(size 0.508)
		(drill 0.254)
		(layers "F.Cu" "B.Cu")
		(net "RST_CPU0_SYS_N")
	)
	(via
		(at 285.769558 -129.920492)
		(size 0.508)
		(drill 0.254)
		(layers "F.Cu" "B.Cu")
		(net "RST_CPU0_SYS_N")
	)
	(via
		(at 406.116282 -322.774564)
		(size 0.508)
		(drill 0.254)
		(layers "F.Cu" "B.Cu")
		(net "RST_CPU0_SYS_N")
	)
	(via
		(at 390.564878 -295.145968)
		(size 0.4064)
		(drill 0.2032)
		(layers "F.Cu" "B.Cu")
		(net "RST_CPU0_SYS_N")
	)
	(via
		(at 178.943 -134.584948)
		(size 0.508)
		(drill 0.254)
		(layers "F.Cu" "B.Cu")
		(net "RST_CPU0_SYS_N")
	)
	(via
		(at 305.630326 -122.234198)
		(size 0.508)
		(drill 0.254)
		(layers "F.Cu" "B.Cu")
		(net "RST_CPU0_SYS_N")
	)
	(segment
		(start 396.470378 -301.460154)
		(end 390.564878 -295.554654)
		(width 0.10668)
		(layer "B.Cu")
		(net "RST_CPU0_SYS_N")
	)
	(segment
		(start 406.655778 -314.62726)
		(end 396.470378 -304.44186)
		(width 0.10668)
		(layer "B.Cu")
		(net "RST_CPU0_SYS_N")
	)
	(segment
		(start 406.116282 -322.774564)
		(end 406.655778 -322.235068)
		(width 0.10668)
		(layer "B.Cu")
		(net "RST_CPU0_SYS_N")
	)
	(segment
		(start 406.655778 -322.235068)
		(end 406.655778 -314.62726)
		(width 0.10668)
		(layer "B.Cu")
		(net "RST_CPU0_SYS_N")
	)
	(segment
		(start 390.564878 -295.554654)
		(end 390.564878 -295.145968)
		(width 0.10668)
		(layer "B.Cu")
		(net "RST_CPU0_SYS_N")
	)
	(segment
		(start 396.470378 -304.44186)
		(end 396.470378 -301.460154)
		(width 0.10668)
		(layer "B.Cu")
		(net "RST_CPU0_SYS_N")
	)
	(segment
		(start 458.055726 -198.441818)
		(end 458.055726 -190.970408)
		(width 0.11684)
		(layer "In2.Cu")
		(net "RST_CPU0_SYS_N")
	)
	(segment
		(start 445.104774 -166.15283)
		(end 442.07938 -163.127436)
		(width 0.11684)
		(layer "In2.Cu")
		(net "RST_CPU0_SYS_N")
	)
	(segment
		(start 352.47707 -131.451858)
		(end 348.06255 -131.451858)
		(width 0.11684)
		(layer "In2.Cu")
		(net "RST_CPU0_SYS_N")
	)
	(segment
		(start 407.371296 -321.51955)
		(end 454.297288 -321.51955)
		(width 0.11684)
		(layer "In2.Cu")
		(net "RST_CPU0_SYS_N")
	)
	(segment
		(start 305.55946 -122.163332)
		(end 305.630326 -122.234198)
		(width 0.11684)
		(layer "In2.Cu")
		(net "RST_CPU0_SYS_N")
	)
	(segment
		(start 309.86984 -119.802148)
		(end 307.288692 -119.802148)
		(width 0.11684)
		(layer "In2.Cu")
		(net "RST_CPU0_SYS_N")
	)
	(segment
		(start 458.055726 -190.970408)
		(end 455.149458 -188.06414)
		(width 0.11684)
		(layer "In2.Cu")
		(net "RST_CPU0_SYS_N")
	)
	(segment
		(start 307.288692 -119.802148)
		(end 305.55946 -121.53138)
		(width 0.11684)
		(layer "In2.Cu")
		(net "RST_CPU0_SYS_N")
	)
	(segment
		(start 441.563506 -163.127436)
		(end 433.576984 -155.140914)
		(width 0.11684)
		(layer "In2.Cu")
		(net "RST_CPU0_SYS_N")
	)
	(segment
		(start 305.55946 -121.53138)
		(end 305.55946 -122.163332)
		(width 0.11684)
		(layer "In2.Cu")
		(net "RST_CPU0_SYS_N")
	)
	(segment
		(start 353.720146 -130.208782)
		(end 352.47707 -131.451858)
		(width 0.11684)
		(layer "In2.Cu")
		(net "RST_CPU0_SYS_N")
	)
	(segment
		(start 433.579016 -140.704824)
		(end 433.579016 -140.277596)
		(width 0.11684)
		(layer "In2.Cu")
		(net "RST_CPU0_SYS_N")
	)
	(segment
		(start 317.159132 -127.09144)
		(end 309.86984 -119.802148)
		(width 0.11684)
		(layer "In2.Cu")
		(net "RST_CPU0_SYS_N")
	)
	(segment
		(start 442.07938 -163.127436)
		(end 441.563506 -163.127436)
		(width 0.11684)
		(layer "In2.Cu")
		(net "RST_CPU0_SYS_N")
	)
	(segment
		(start 455.149458 -184.200038)
		(end 445.104774 -174.155354)
		(width 0.11684)
		(layer "In2.Cu")
		(net "RST_CPU0_SYS_N")
	)
	(segment
		(start 454.297288 -321.51955)
		(end 456.179428 -319.63741)
		(width 0.11684)
		(layer "In2.Cu")
		(net "RST_CPU0_SYS_N")
	)
	(segment
		(start 433.576984 -155.140914)
		(end 433.576984 -140.706856)
		(width 0.11684)
		(layer "In2.Cu")
		(net "RST_CPU0_SYS_N")
	)
	(segment
		(start 402.232114 -130.208782)
		(end 353.720146 -130.208782)
		(width 0.11684)
		(layer "In2.Cu")
		(net "RST_CPU0_SYS_N")
	)
	(segment
		(start 455.149458 -188.06414)
		(end 455.149458 -184.200038)
		(width 0.11684)
		(layer "In2.Cu")
		(net "RST_CPU0_SYS_N")
	)
	(segment
		(start 456.179428 -200.318116)
		(end 458.055726 -198.441818)
		(width 0.11684)
		(layer "In2.Cu")
		(net "RST_CPU0_SYS_N")
	)
	(segment
		(start 456.179428 -319.63741)
		(end 456.179428 -200.318116)
		(width 0.11684)
		(layer "In2.Cu")
		(net "RST_CPU0_SYS_N")
	)
	(segment
		(start 421.190928 -127.889508)
		(end 404.551388 -127.889508)
		(width 0.11684)
		(layer "In2.Cu")
		(net "RST_CPU0_SYS_N")
	)
	(segment
		(start 348.06255 -131.451858)
		(end 343.702132 -127.09144)
		(width 0.11684)
		(layer "In2.Cu")
		(net "RST_CPU0_SYS_N")
	)
	(segment
		(start 406.116282 -322.774564)
		(end 407.371296 -321.51955)
		(width 0.11684)
		(layer "In2.Cu")
		(net "RST_CPU0_SYS_N")
	)
	(segment
		(start 404.551388 -127.889508)
		(end 402.232114 -130.208782)
		(width 0.11684)
		(layer "In2.Cu")
		(net "RST_CPU0_SYS_N")
	)
	(segment
		(start 445.104774 -174.155354)
		(end 445.104774 -166.15283)
		(width 0.11684)
		(layer "In2.Cu")
		(net "RST_CPU0_SYS_N")
	)
	(segment
		(start 433.579016 -140.277596)
		(end 421.190928 -127.889508)
		(width 0.11684)
		(layer "In2.Cu")
		(net "RST_CPU0_SYS_N")
	)
	(segment
		(start 343.702132 -127.09144)
		(end 317.159132 -127.09144)
		(width 0.11684)
		(layer "In2.Cu")
		(net "RST_CPU0_SYS_N")
	)
	(segment
		(start 433.576984 -140.706856)
		(end 433.579016 -140.704824)
		(width 0.11684)
		(layer "In2.Cu")
		(net "RST_CPU0_SYS_N")
	)
	(segment
		(start 300.83506 -104.775)
		(end 309.555642 -113.495582)
		(width 0.11684)
		(layer "In4.Cu")
		(net "RST_CPU0_SYS_N")
	)
	(segment
		(start 293.438072 -52.665376)
		(end 292.784022 -53.319426)
		(width 0.11684)
		(layer "In4.Cu")
		(net "RST_CPU0_SYS_N")
	)
	(segment
		(start 292.784022 -56.147462)
		(end 300.83506 -64.1985)
		(width 0.11684)
		(layer "In4.Cu")
		(net "RST_CPU0_SYS_N")
	)
	(segment
		(start 309.378096 -121.518172)
		(end 306.346352 -121.518172)
		(width 0.11684)
		(layer "In4.Cu")
		(net "RST_CPU0_SYS_N")
	)
	(segment
		(start 309.555642 -121.340626)
		(end 309.378096 -121.518172)
		(width 0.11684)
		(layer "In4.Cu")
		(net "RST_CPU0_SYS_N")
	)
	(segment
		(start 300.83506 -64.1985)
		(end 300.83506 -104.775)
		(width 0.11684)
		(layer "In4.Cu")
		(net "RST_CPU0_SYS_N")
	)
	(segment
		(start 306.346352 -121.518172)
		(end 305.630326 -122.234198)
		(width 0.11684)
		(layer "In4.Cu")
		(net "RST_CPU0_SYS_N")
	)
	(segment
		(start 292.784022 -53.319426)
		(end 292.784022 -56.147462)
		(width 0.11684)
		(layer "In4.Cu")
		(net "RST_CPU0_SYS_N")
	)
	(segment
		(start 309.555642 -113.495582)
		(end 309.555642 -121.340626)
		(width 0.11684)
		(layer "In4.Cu")
		(net "RST_CPU0_SYS_N")
	)
	(segment
		(start 286.7152 -98.196908)
		(end 288.0487 -99.530408)
		(width 0.11684)
		(layer "In11.Cu")
		(net "RST_CPU0_SYS_N")
	)
	(segment
		(start 288.0487 -115.988592)
		(end 285.769558 -118.267734)
		(width 0.11684)
		(layer "In11.Cu")
		(net "RST_CPU0_SYS_N")
	)
	(segment
		(start 294.095424 -54.018434)
		(end 286.7152 -61.398658)
		(width 0.11684)
		(layer "In11.Cu")
		(net "RST_CPU0_SYS_N")
	)
	(segment
		(start 286.7152 -61.398658)
		(end 286.7152 -98.196908)
		(width 0.11684)
		(layer "In11.Cu")
		(net "RST_CPU0_SYS_N")
	)
	(segment
		(start 293.438072 -52.665376)
		(end 294.095424 -53.322728)
		(width 0.11684)
		(layer "In11.Cu")
		(net "RST_CPU0_SYS_N")
	)
	(segment
		(start 294.095424 -53.322728)
		(end 294.095424 -54.018434)
		(width 0.11684)
		(layer "In11.Cu")
		(net "RST_CPU0_SYS_N")
	)
	(segment
		(start 288.0487 -99.530408)
		(end 288.0487 -115.988592)
		(width 0.11684)
		(layer "In11.Cu")
		(net "RST_CPU0_SYS_N")
	)
	(segment
		(start 285.769558 -118.267734)
		(end 285.769558 -129.920492)
		(width 0.11684)
		(layer "In11.Cu")
		(net "RST_CPU0_SYS_N")
	)
	(segment
		(start 282.365704 -129.842768)
		(end 282.887674 -129.320798)
		(width 0.11684)
		(layer "In15.Cu")
		(net "RST_CPU0_SYS_N")
	)
	(segment
		(start 251.385578 -129.193798)
		(end 252.540008 -128.039368)
		(width 0.11684)
		(layer "In15.Cu")
		(net "RST_CPU0_SYS_N")
	)
	(segment
		(start 252.540008 -128.039368)
		(end 270.825976 -128.039368)
		(width 0.11684)
		(layer "In15.Cu")
		(net "RST_CPU0_SYS_N")
	)
	(segment
		(start 207.892142 -132.591556)
		(end 245.890034 -132.591556)
		(width 0.11684)
		(layer "In15.Cu")
		(net "RST_CPU0_SYS_N")
	)
	(segment
		(start 282.887674 -129.320798)
		(end 285.169864 -129.320798)
		(width 0.11684)
		(layer "In15.Cu")
		(net "RST_CPU0_SYS_N")
	)
	(segment
		(start 195.350892 -131.539488)
		(end 206.840074 -131.539488)
		(width 0.11684)
		(layer "In15.Cu")
		(net "RST_CPU0_SYS_N")
	)
	(segment
		(start 178.943 -134.584948)
		(end 178.943 -134.402322)
		(width 0.11684)
		(layer "In15.Cu")
		(net "RST_CPU0_SYS_N")
	)
	(segment
		(start 178.943 -134.402322)
		(end 179.452524 -133.892798)
		(width 0.11684)
		(layer "In15.Cu")
		(net "RST_CPU0_SYS_N")
	)
	(segment
		(start 194.733418 -130.922014)
		(end 195.350892 -131.539488)
		(width 0.11684)
		(layer "In15.Cu")
		(net "RST_CPU0_SYS_N")
	)
	(segment
		(start 249.287792 -129.193798)
		(end 251.385578 -129.193798)
		(width 0.11684)
		(layer "In15.Cu")
		(net "RST_CPU0_SYS_N")
	)
	(segment
		(start 206.840074 -131.539488)
		(end 207.892142 -132.591556)
		(width 0.11684)
		(layer "In15.Cu")
		(net "RST_CPU0_SYS_N")
	)
	(segment
		(start 179.452524 -131.467098)
		(end 179.264564 -131.279138)
		(width 0.11684)
		(layer "In15.Cu")
		(net "RST_CPU0_SYS_N")
	)
	(segment
		(start 270.825976 -128.039368)
		(end 272.629376 -129.842768)
		(width 0.11684)
		(layer "In15.Cu")
		(net "RST_CPU0_SYS_N")
	)
	(segment
		(start 285.169864 -129.320798)
		(end 285.769558 -129.920492)
		(width 0.11684)
		(layer "In15.Cu")
		(net "RST_CPU0_SYS_N")
	)
	(segment
		(start 179.264564 -131.279138)
		(end 179.264564 -129.98577)
		(width 0.11684)
		(layer "In15.Cu")
		(net "RST_CPU0_SYS_N")
	)
	(segment
		(start 194.733418 -130.20675)
		(end 194.733418 -130.922014)
		(width 0.11684)
		(layer "In15.Cu")
		(net "RST_CPU0_SYS_N")
	)
	(segment
		(start 245.890034 -132.591556)
		(end 249.287792 -129.193798)
		(width 0.11684)
		(layer "In15.Cu")
		(net "RST_CPU0_SYS_N")
	)
	(segment
		(start 193.822066 -129.295398)
		(end 194.733418 -130.20675)
		(width 0.11684)
		(layer "In15.Cu")
		(net "RST_CPU0_SYS_N")
	)
	(segment
		(start 272.629376 -129.842768)
		(end 282.365704 -129.842768)
		(width 0.11684)
		(layer "In15.Cu")
		(net "RST_CPU0_SYS_N")
	)
	(segment
		(start 179.954936 -129.295398)
		(end 193.822066 -129.295398)
		(width 0.11684)
		(layer "In15.Cu")
		(net "RST_CPU0_SYS_N")
	)
	(segment
		(start 179.452524 -133.892798)
		(end 179.452524 -131.467098)
		(width 0.11684)
		(layer "In15.Cu")
		(net "RST_CPU0_SYS_N")
	)
	(segment
		(start 179.264564 -129.98577)
		(end 179.954936 -129.295398)
		(width 0.11684)
		(layer "In15.Cu")
		(net "RST_CPU0_SYS_N")
	)
	(segment
		(start 306.691538 -84.845144)
		(end 305.413664 -83.56727)
		(width 0.10668)
		(layer "F.Cu")
		(net "RST_CPU0_RSMRST_N")
	)
	(segment
		(start 392.053826 -317.04407)
		(end 392.829288 -317.04407)
		(width 0.10668)
		(layer "F.Cu")
		(net "RST_CPU0_RSMRST_N")
	)
	(segment
		(start 385.457954 -297.92676)
		(end 384.975608 -297.92676)
		(width 0.10668)
		(layer "F.Cu")
		(net "RST_CPU0_RSMRST_N")
	)
	(segment
		(start 305.413664 -78.581758)
		(end 307.352192 -76.64323)
		(width 0.10668)
		(layer "F.Cu")
		(net "RST_CPU0_RSMRST_N")
	)
	(segment
		(start 382.102614 -309.266844)
		(end 389.87984 -317.04407)
		(width 0.10668)
		(layer "F.Cu")
		(net "RST_CPU0_RSMRST_N")
	)
	(segment
		(start 181.341268 -134.006336)
		(end 180.970936 -133.636004)
		(width 0.10668)
		(layer "F.Cu")
		(net "RST_CPU0_RSMRST_N")
	)
	(segment
		(start 181.341268 -140.68552)
		(end 181.341268 -134.006336)
		(width 0.10668)
		(layer "F.Cu")
		(net "RST_CPU0_RSMRST_N")
	)
	(segment
		(start 180.951886 -141.074902)
		(end 181.341268 -140.68552)
		(width 0.10668)
		(layer "F.Cu")
		(net "RST_CPU0_RSMRST_N")
	)
	(segment
		(start 311.18556 -76.64323)
		(end 311.95645 -75.87234)
		(width 0.10668)
		(layer "F.Cu")
		(net "RST_CPU0_RSMRST_N")
	)
	(segment
		(start 389.87984 -317.04407)
		(end 392.053826 -317.04407)
		(width 0.10668)
		(layer "F.Cu")
		(net "RST_CPU0_RSMRST_N")
	)
	(segment
		(start 306.691538 -86.710774)
		(end 306.691538 -84.845144)
		(width 0.10668)
		(layer "F.Cu")
		(net "RST_CPU0_RSMRST_N")
	)
	(segment
		(start 384.975608 -297.92676)
		(end 383.507996 -299.394372)
		(width 0.10668)
		(layer "F.Cu")
		(net "RST_CPU0_RSMRST_N")
	)
	(segment
		(start 385.86791 -294.070024)
		(end 386.334762 -294.335962)
		(width 0.10668)
		(layer "F.Cu")
		(net "RST_CPU0_RSMRST_N")
	)
	(segment
		(start 393.753848 -320.627756)
		(end 394.70584 -320.627756)
		(width 0.10668)
		(layer "F.Cu")
		(net "RST_CPU0_RSMRST_N")
	)
	(segment
		(start 311.95645 -73.626218)
		(end 312.443876 -73.138792)
		(width 0.10668)
		(layer "F.Cu")
		(net "RST_CPU0_RSMRST_N")
	)
	(segment
		(start 393.763246 -320.637154)
		(end 393.753848 -320.627756)
		(width 0.10668)
		(layer "F.Cu")
		(net "RST_CPU0_RSMRST_N")
	)
	(segment
		(start 382.102614 -301.215044)
		(end 382.102614 -309.266844)
		(width 0.10668)
		(layer "F.Cu")
		(net "RST_CPU0_RSMRST_N")
	)
	(segment
		(start 394.70584 -320.627756)
		(end 394.826236 -320.748152)
		(width 0.10668)
		(layer "F.Cu")
		(net "RST_CPU0_RSMRST_N")
	)
	(segment
		(start 383.507996 -299.809662)
		(end 382.102614 -301.215044)
		(width 0.10668)
		(layer "F.Cu")
		(net "RST_CPU0_RSMRST_N")
	)
	(segment
		(start 394.826236 -320.748152)
		(end 395.269212 -320.748152)
		(width 0.10668)
		(layer "F.Cu")
		(net "RST_CPU0_RSMRST_N")
	)
	(segment
		(start 383.507996 -299.394372)
		(end 383.507996 -299.809662)
		(width 0.10668)
		(layer "F.Cu")
		(net "RST_CPU0_RSMRST_N")
	)
	(segment
		(start 305.413664 -83.56727)
		(end 305.413664 -78.581758)
		(width 0.10668)
		(layer "F.Cu")
		(net "RST_CPU0_RSMRST_N")
	)
	(segment
		(start 393.753848 -317.96863)
		(end 393.753848 -320.627756)
		(width 0.10668)
		(layer "F.Cu")
		(net "RST_CPU0_RSMRST_N")
	)
	(segment
		(start 393.763246 -321.632834)
		(end 393.763246 -320.637154)
		(width 0.10668)
		(layer "F.Cu")
		(net "RST_CPU0_RSMRST_N")
	)
	(segment
		(start 386.334762 -297.049952)
		(end 385.457954 -297.92676)
		(width 0.10668)
		(layer "F.Cu")
		(net "RST_CPU0_RSMRST_N")
	)
	(segment
		(start 307.352192 -76.64323)
		(end 311.18556 -76.64323)
		(width 0.10668)
		(layer "F.Cu")
		(net "RST_CPU0_RSMRST_N")
	)
	(segment
		(start 392.829288 -317.04407)
		(end 393.753848 -317.96863)
		(width 0.10668)
		(layer "F.Cu")
		(net "RST_CPU0_RSMRST_N")
	)
	(segment
		(start 311.95645 -75.87234)
		(end 311.95645 -73.626218)
		(width 0.10668)
		(layer "F.Cu")
		(net "RST_CPU0_RSMRST_N")
	)
	(via
		(at 392.053826 -317.04407)
		(size 0.508)
		(drill 0.254)
		(layers "F.Cu" "B.Cu")
		(net "RST_CPU0_RSMRST_N")
	)
	(via
		(at 312.443876 -73.138792)
		(size 0.762)
		(drill 0.254)
		(layers "F.Cu" "B.Cu")
		(net "RST_CPU0_RSMRST_N")
	)
	(via
		(at 237.08106 -142.225522)
		(size 0.508)
		(drill 0.254)
		(layers "F.Cu" "B.Cu")
		(net "RST_CPU0_RSMRST_N")
	)
	(via
		(at 237.08106 -98.14687)
		(size 0.508)
		(drill 0.254)
		(layers "F.Cu" "B.Cu")
		(net "RST_CPU0_RSMRST_N")
	)
	(via
		(at 180.951886 -141.074902)
		(size 0.508)
		(drill 0.254)
		(layers "F.Cu" "B.Cu")
		(net "RST_CPU0_RSMRST_N")
	)
	(via
		(at 386.334762 -294.335962)
		(size 0.4064)
		(drill 0.2032)
		(layers "F.Cu" "B.Cu")
		(net "RST_CPU0_RSMRST_N")
	)
	(via
		(at 306.691538 -86.710774)
		(size 0.508)
		(drill 0.254)
		(layers "F.Cu" "B.Cu")
		(net "RST_CPU0_RSMRST_N")
	)
	(via
		(at 386.334762 -297.049952)
		(size 0.508)
		(drill 0.254)
		(layers "F.Cu" "B.Cu")
		(net "RST_CPU0_RSMRST_N")
	)
	(segment
		(start 386.334762 -294.335962)
		(end 386.334762 -297.049952)
		(width 0.10668)
		(layer "B.Cu")
		(net "RST_CPU0_RSMRST_N")
	)
	(segment
		(start 312.443876 -73.138792)
		(end 312.443876 -73.293224)
		(width 0.10668)
		(layer "B.Cu")
		(net "RST_CPU0_RSMRST_N")
	)
	(segment
		(start 312.68543 -73.534778)
		(end 313.094624 -73.534778)
		(width 0.10668)
		(layer "B.Cu")
		(net "RST_CPU0_RSMRST_N")
	)
	(segment
		(start 312.443876 -73.293224)
		(end 312.68543 -73.534778)
		(width 0.10668)
		(layer "B.Cu")
		(net "RST_CPU0_RSMRST_N")
	)
	(segment
		(start 237.08106 -98.14687)
		(end 237.08106 -142.225522)
		(width 0.11684)
		(layer "In4.Cu")
		(net "RST_CPU0_RSMRST_N")
	)
	(segment
		(start 189.634114 -141.948154)
		(end 189.79896 -142.113)
		(width 0.11684)
		(layer "In6.Cu")
		(net "RST_CPU0_RSMRST_N")
	)
	(segment
		(start 415.332164 -131.56946)
		(end 431.157126 -147.394422)
		(width 0.11684)
		(layer "In6.Cu")
		(net "RST_CPU0_RSMRST_N")
	)
	(segment
		(start 448.775582 -169.993818)
		(end 448.775582 -177.07483)
		(width 0.11684)
		(layer "In6.Cu")
		(net "RST_CPU0_RSMRST_N")
	)
	(segment
		(start 201.036174 -143.127222)
		(end 233.076242 -143.127222)
		(width 0.11684)
		(layer "In6.Cu")
		(net "RST_CPU0_RSMRST_N")
	)
	(segment
		(start 448.775582 -177.07483)
		(end 460.391256 -188.690504)
		(width 0.11684)
		(layer "In6.Cu")
		(net "RST_CPU0_RSMRST_N")
	)
	(segment
		(start 441.578492 -162.796728)
		(end 448.775582 -169.993818)
		(width 0.11684)
		(layer "In6.Cu")
		(net "RST_CPU0_RSMRST_N")
	)
	(segment
		(start 292.087808 -143.238728)
		(end 304.383694 -130.942842)
		(width 0.11684)
		(layer "In6.Cu")
		(net "RST_CPU0_RSMRST_N")
	)
	(segment
		(start 268.19987 -149.398736)
		(end 274.359878 -143.238728)
		(width 0.11684)
		(layer "In6.Cu")
		(net "RST_CPU0_RSMRST_N")
	)
	(segment
		(start 180.951886 -141.074902)
		(end 181.825138 -141.948154)
		(width 0.11684)
		(layer "In6.Cu")
		(net "RST_CPU0_RSMRST_N")
	)
	(segment
		(start 274.359878 -143.238728)
		(end 292.087808 -143.238728)
		(width 0.11684)
		(layer "In6.Cu")
		(net "RST_CPU0_RSMRST_N")
	)
	(segment
		(start 454.356978 -326.05726)
		(end 412.471108 -326.05726)
		(width 0.11684)
		(layer "In6.Cu")
		(net "RST_CPU0_RSMRST_N")
	)
	(segment
		(start 243.921026 -146.680936)
		(end 250.262898 -153.022808)
		(width 0.11684)
		(layer "In6.Cu")
		(net "RST_CPU0_RSMRST_N")
	)
	(segment
		(start 320.190622 -130.942842)
		(end 323.213984 -127.91948)
		(width 0.11684)
		(layer "In6.Cu")
		(net "RST_CPU0_RSMRST_N")
	)
	(segment
		(start 406.043384 -319.629536)
		(end 394.639292 -319.629536)
		(width 0.11684)
		(layer "In6.Cu")
		(net "RST_CPU0_RSMRST_N")
	)
	(segment
		(start 250.262898 -153.022808)
		(end 264.929874 -153.022808)
		(width 0.11684)
		(layer "In6.Cu")
		(net "RST_CPU0_RSMRST_N")
	)
	(segment
		(start 237.08106 -142.225522)
		(end 239.331246 -142.225522)
		(width 0.11684)
		(layer "In6.Cu")
		(net "RST_CPU0_RSMRST_N")
	)
	(segment
		(start 200.549764 -142.230348)
		(end 200.549764 -142.640812)
		(width 0.11684)
		(layer "In6.Cu")
		(net "RST_CPU0_RSMRST_N")
	)
	(segment
		(start 460.391256 -320.022982)
		(end 454.356978 -326.05726)
		(width 0.11684)
		(layer "In6.Cu")
		(net "RST_CPU0_RSMRST_N")
	)
	(segment
		(start 361.1245 -131.56946)
		(end 415.332164 -131.56946)
		(width 0.11684)
		(layer "In6.Cu")
		(net "RST_CPU0_RSMRST_N")
	)
	(segment
		(start 239.331246 -142.225522)
		(end 243.78666 -146.680936)
		(width 0.11684)
		(layer "In6.Cu")
		(net "RST_CPU0_RSMRST_N")
	)
	(segment
		(start 200.549764 -142.640812)
		(end 201.036174 -143.127222)
		(width 0.11684)
		(layer "In6.Cu")
		(net "RST_CPU0_RSMRST_N")
	)
	(segment
		(start 394.639292 -319.629536)
		(end 392.053826 -317.04407)
		(width 0.11684)
		(layer "In6.Cu")
		(net "RST_CPU0_RSMRST_N")
	)
	(segment
		(start 181.825138 -141.948154)
		(end 189.634114 -141.948154)
		(width 0.11684)
		(layer "In6.Cu")
		(net "RST_CPU0_RSMRST_N")
	)
	(segment
		(start 233.977942 -142.225522)
		(end 237.08106 -142.225522)
		(width 0.11684)
		(layer "In6.Cu")
		(net "RST_CPU0_RSMRST_N")
	)
	(segment
		(start 243.78666 -146.680936)
		(end 243.921026 -146.680936)
		(width 0.11684)
		(layer "In6.Cu")
		(net "RST_CPU0_RSMRST_N")
	)
	(segment
		(start 347.71965 -132.801868)
		(end 359.892092 -132.801868)
		(width 0.11684)
		(layer "In6.Cu")
		(net "RST_CPU0_RSMRST_N")
	)
	(segment
		(start 268.19987 -149.752812)
		(end 268.19987 -149.398736)
		(width 0.11684)
		(layer "In6.Cu")
		(net "RST_CPU0_RSMRST_N")
	)
	(segment
		(start 264.929874 -153.022808)
		(end 268.19987 -149.752812)
		(width 0.11684)
		(layer "In6.Cu")
		(net "RST_CPU0_RSMRST_N")
	)
	(segment
		(start 199.479916 -141.1605)
		(end 200.549764 -142.230348)
		(width 0.11684)
		(layer "In6.Cu")
		(net "RST_CPU0_RSMRST_N")
	)
	(segment
		(start 304.383694 -130.942842)
		(end 320.190622 -130.942842)
		(width 0.11684)
		(layer "In6.Cu")
		(net "RST_CPU0_RSMRST_N")
	)
	(segment
		(start 233.076242 -143.127222)
		(end 233.977942 -142.225522)
		(width 0.11684)
		(layer "In6.Cu")
		(net "RST_CPU0_RSMRST_N")
	)
	(segment
		(start 412.471108 -326.05726)
		(end 406.043384 -319.629536)
		(width 0.11684)
		(layer "In6.Cu")
		(net "RST_CPU0_RSMRST_N")
	)
	(segment
		(start 359.892092 -132.801868)
		(end 361.1245 -131.56946)
		(width 0.11684)
		(layer "In6.Cu")
		(net "RST_CPU0_RSMRST_N")
	)
	(segment
		(start 431.157126 -147.394422)
		(end 431.157126 -154.542998)
		(width 0.11684)
		(layer "In6.Cu")
		(net "RST_CPU0_RSMRST_N")
	)
	(segment
		(start 193.716656 -141.1605)
		(end 199.479916 -141.1605)
		(width 0.11684)
		(layer "In6.Cu")
		(net "RST_CPU0_RSMRST_N")
	)
	(segment
		(start 431.157126 -154.542998)
		(end 439.410856 -162.796728)
		(width 0.11684)
		(layer "In6.Cu")
		(net "RST_CPU0_RSMRST_N")
	)
	(segment
		(start 192.764156 -142.113)
		(end 193.716656 -141.1605)
		(width 0.11684)
		(layer "In6.Cu")
		(net "RST_CPU0_RSMRST_N")
	)
	(segment
		(start 342.837262 -127.91948)
		(end 347.71965 -132.801868)
		(width 0.11684)
		(layer "In6.Cu")
		(net "RST_CPU0_RSMRST_N")
	)
	(segment
		(start 460.391256 -188.690504)
		(end 460.391256 -320.022982)
		(width 0.11684)
		(layer "In6.Cu")
		(net "RST_CPU0_RSMRST_N")
	)
	(segment
		(start 439.410856 -162.796728)
		(end 441.578492 -162.796728)
		(width 0.11684)
		(layer "In6.Cu")
		(net "RST_CPU0_RSMRST_N")
	)
	(segment
		(start 323.213984 -127.91948)
		(end 342.837262 -127.91948)
		(width 0.11684)
		(layer "In6.Cu")
		(net "RST_CPU0_RSMRST_N")
	)
	(segment
		(start 189.79896 -142.113)
		(end 192.764156 -142.113)
		(width 0.11684)
		(layer "In6.Cu")
		(net "RST_CPU0_RSMRST_N")
	)
	(segment
		(start 306.1589 -87.243412)
		(end 306.691538 -86.710774)
		(width 0.11684)
		(layer "In15.Cu")
		(net "RST_CPU0_RSMRST_N")
	)
	(segment
		(start 237.08106 -98.14687)
		(end 247.984518 -87.243412)
		(width 0.11684)
		(layer "In15.Cu")
		(net "RST_CPU0_RSMRST_N")
	)
	(segment
		(start 247.984518 -87.243412)
		(end 306.1589 -87.243412)
		(width 0.11684)
		(layer "In15.Cu")
		(net "RST_CPU0_RSMRST_N")
	)
	(segment
		(start 182.994808 -129.79019)
		(end 182.994808 -130.393948)
		(width 0.10668)
		(layer "F.Cu")
		(net "RST_CPU0_RESETL_N")
	)
	(segment
		(start 320.465196 -203.513436)
		(end 321.477132 -204.525372)
		(width 0.10668)
		(layer "F.Cu")
		(net "RST_CPU0_RESETL_N")
	)
	(segment
		(start 296.820336 -172.070522)
		(end 310.870092 -186.120278)
		(width 0.10668)
		(layer "F.Cu")
		(net "RST_CPU0_RESETL_N")
	)
	(segment
		(start 280.454354 -164.40785)
		(end 280.454354 -166.616634)
		(width 0.10668)
		(layer "F.Cu")
		(net "RST_CPU0_RESETL_N")
	)
	(segment
		(start 280.454354 -166.616634)
		(end 285.908242 -172.070522)
		(width 0.10668)
		(layer "F.Cu")
		(net "RST_CPU0_RESETL_N")
	)
	(segment
		(start 322.067682 -204.525372)
		(end 322.878958 -205.336648)
		(width 0.10668)
		(layer "F.Cu")
		(net "RST_CPU0_RESETL_N")
	)
	(segment
		(start 317.833756 -203.513436)
		(end 320.465196 -203.513436)
		(width 0.10668)
		(layer "F.Cu")
		(net "RST_CPU0_RESETL_N")
	)
	(segment
		(start 321.477132 -204.525372)
		(end 322.067682 -204.525372)
		(width 0.10668)
		(layer "F.Cu")
		(net "RST_CPU0_RESETL_N")
	)
	(segment
		(start 183.007 -129.777998)
		(end 182.994808 -129.79019)
		(width 0.10668)
		(layer "F.Cu")
		(net "RST_CPU0_RESETL_N")
	)
	(segment
		(start 285.908242 -172.070522)
		(end 296.820336 -172.070522)
		(width 0.10668)
		(layer "F.Cu")
		(net "RST_CPU0_RESETL_N")
	)
	(segment
		(start 332.45806 -222.880174)
		(end 331.991208 -222.614236)
		(width 0.10668)
		(layer "F.Cu")
		(net "RST_CPU0_RESETL_N")
	)
	(segment
		(start 310.870092 -186.120278)
		(end 310.870092 -196.549772)
		(width 0.10668)
		(layer "F.Cu")
		(net "RST_CPU0_RESETL_N")
	)
	(segment
		(start 280.528522 -164.333682)
		(end 280.454354 -164.40785)
		(width 0.10668)
		(layer "F.Cu")
		(net "RST_CPU0_RESETL_N")
	)
	(segment
		(start 322.878958 -205.336648)
		(end 322.878958 -205.476602)
		(width 0.10668)
		(layer "F.Cu")
		(net "RST_CPU0_RESETL_N")
	)
	(segment
		(start 310.870092 -196.549772)
		(end 317.833756 -203.513436)
		(width 0.10668)
		(layer "F.Cu")
		(net "RST_CPU0_RESETL_N")
	)
	(via
		(at 182.994808 -130.393948)
		(size 0.508)
		(drill 0.254)
		(layers "F.Cu" "B.Cu")
		(net "RST_CPU0_RESETL_N")
	)
	(via
		(at 280.528522 -164.333682)
		(size 0.508)
		(drill 0.254)
		(layers "F.Cu" "B.Cu")
		(net "RST_CPU0_RESETL_N")
	)
	(via
		(at 322.878958 -205.476602)
		(size 0.508)
		(drill 0.254)
		(layers "F.Cu" "B.Cu")
		(net "RST_CPU0_RESETL_N")
	)
	(via
		(at 196.204586 -166.44366)
		(size 0.508)
		(drill 0.254)
		(layers "F.Cu" "B.Cu")
		(net "RST_CPU0_RESETL_N")
	)
	(via
		(at 112.695482 -127.573024)
		(size 0.508)
		(drill 0.254)
		(layers "F.Cu" "B.Cu")
		(net "RST_CPU0_RESETL_N")
	)
	(via
		(at 331.991208 -222.614236)
		(size 0.4064)
		(drill 0.2032)
		(layers "F.Cu" "B.Cu")
		(net "RST_CPU0_RESETL_N")
	)
	(via
		(at 71.710042 -201.896218)
		(size 0.508)
		(drill 0.254)
		(layers "F.Cu" "B.Cu")
		(net "RST_CPU0_RESETL_N")
	)
	(segment
		(start 322.878958 -212.52307)
		(end 322.878958 -205.476602)
		(width 0.10668)
		(layer "B.Cu")
		(net "RST_CPU0_RESETL_N")
	)
	(segment
		(start 71.2724 -201.896218)
		(end 71.710042 -201.896218)
		(width 0.10668)
		(layer "B.Cu")
		(net "RST_CPU0_RESETL_N")
	)
	(segment
		(start 71.049134 -201.672952)
		(end 71.2724 -201.896218)
		(width 0.10668)
		(layer "B.Cu")
		(net "RST_CPU0_RESETL_N")
	)
	(segment
		(start 331.991208 -222.614236)
		(end 331.991208 -221.63532)
		(width 0.10668)
		(layer "B.Cu")
		(net "RST_CPU0_RESETL_N")
	)
	(segment
		(start 331.991208 -221.63532)
		(end 322.878958 -212.52307)
		(width 0.10668)
		(layer "B.Cu")
		(net "RST_CPU0_RESETL_N")
	)
	(segment
		(start 322.878958 -204.825346)
		(end 322.370958 -204.317346)
		(width 0.10668)
		(layer "B.Cu")
		(net "RST_CPU0_RESETL_N")
	)
	(segment
		(start 70.572884 -201.672952)
		(end 71.049134 -201.672952)
		(width 0.10668)
		(layer "B.Cu")
		(net "RST_CPU0_RESETL_N")
	)
	(segment
		(start 322.878958 -205.476602)
		(end 322.878958 -204.825346)
		(width 0.10668)
		(layer "B.Cu")
		(net "RST_CPU0_RESETL_N")
	)
	(segment
		(start 114.57813 -127.262128)
		(end 115.548918 -128.232916)
		(width 0.11684)
		(layer "In6.Cu")
		(net "RST_CPU0_RESETL_N")
	)
	(segment
		(start 157.876748 -128.232916)
		(end 158.728156 -129.084324)
		(width 0.11684)
		(layer "In6.Cu")
		(net "RST_CPU0_RESETL_N")
	)
	(segment
		(start 162.812984 -129.084324)
		(end 163.072064 -129.343404)
		(width 0.11684)
		(layer "In6.Cu")
		(net "RST_CPU0_RESETL_N")
	)
	(segment
		(start 182.519828 -129.918968)
		(end 182.994808 -130.393948)
		(width 0.11684)
		(layer "In6.Cu")
		(net "RST_CPU0_RESETL_N")
	)
	(segment
		(start 115.548918 -128.232916)
		(end 157.876748 -128.232916)
		(width 0.11684)
		(layer "In6.Cu")
		(net "RST_CPU0_RESETL_N")
	)
	(segment
		(start 172.73905 -129.918968)
		(end 182.519828 -129.918968)
		(width 0.11684)
		(layer "In6.Cu")
		(net "RST_CPU0_RESETL_N")
	)
	(segment
		(start 270.899128 -164.821362)
		(end 271.542002 -164.178488)
		(width 0.11684)
		(layer "In6.Cu")
		(net "RST_CPU0_RESETL_N")
	)
	(segment
		(start 271.542002 -164.178488)
		(end 280.373328 -164.178488)
		(width 0.11684)
		(layer "In6.Cu")
		(net "RST_CPU0_RESETL_N")
	)
	(segment
		(start 280.373328 -164.178488)
		(end 280.528522 -164.333682)
		(width 0.11684)
		(layer "In6.Cu")
		(net "RST_CPU0_RESETL_N")
	)
	(segment
		(start 172.163486 -129.343404)
		(end 172.73905 -129.918968)
		(width 0.11684)
		(layer "In6.Cu")
		(net "RST_CPU0_RESETL_N")
	)
	(segment
		(start 222.76435 -161.65576)
		(end 225.929952 -164.821362)
		(width 0.11684)
		(layer "In6.Cu")
		(net "RST_CPU0_RESETL_N")
	)
	(segment
		(start 163.072064 -129.343404)
		(end 172.163486 -129.343404)
		(width 0.11684)
		(layer "In6.Cu")
		(net "RST_CPU0_RESETL_N")
	)
	(segment
		(start 112.695482 -127.573024)
		(end 113.006378 -127.262128)
		(width 0.11684)
		(layer "In6.Cu")
		(net "RST_CPU0_RESETL_N")
	)
	(segment
		(start 207.706468 -168.382442)
		(end 214.43315 -161.65576)
		(width 0.11684)
		(layer "In6.Cu")
		(net "RST_CPU0_RESETL_N")
	)
	(segment
		(start 158.728156 -129.084324)
		(end 162.812984 -129.084324)
		(width 0.11684)
		(layer "In6.Cu")
		(net "RST_CPU0_RESETL_N")
	)
	(segment
		(start 196.204586 -166.44366)
		(end 196.825362 -166.44366)
		(width 0.11684)
		(layer "In6.Cu")
		(net "RST_CPU0_RESETL_N")
	)
	(segment
		(start 113.006378 -127.262128)
		(end 114.57813 -127.262128)
		(width 0.11684)
		(layer "In6.Cu")
		(net "RST_CPU0_RESETL_N")
	)
	(segment
		(start 225.929952 -164.821362)
		(end 270.899128 -164.821362)
		(width 0.11684)
		(layer "In6.Cu")
		(net "RST_CPU0_RESETL_N")
	)
	(segment
		(start 214.43315 -161.65576)
		(end 222.76435 -161.65576)
		(width 0.11684)
		(layer "In6.Cu")
		(net "RST_CPU0_RESETL_N")
	)
	(segment
		(start 198.764144 -168.382442)
		(end 207.706468 -168.382442)
		(width 0.11684)
		(layer "In6.Cu")
		(net "RST_CPU0_RESETL_N")
	)
	(segment
		(start 196.825362 -166.44366)
		(end 198.764144 -168.382442)
		(width 0.11684)
		(layer "In6.Cu")
		(net "RST_CPU0_RESETL_N")
	)
	(segment
		(start 70.805548 -200.991724)
		(end 71.710042 -201.896218)
		(width 0.11684)
		(layer "In11.Cu")
		(net "RST_CPU0_RESETL_N")
	)
	(segment
		(start 52.277518 -134.183374)
		(end 39.561516 -146.899376)
		(width 0.11684)
		(layer "In11.Cu")
		(net "RST_CPU0_RESETL_N")
	)
	(segment
		(start 63.799974 -197.57009)
		(end 67.221608 -200.991724)
		(width 0.11684)
		(layer "In11.Cu")
		(net "RST_CPU0_RESETL_N")
	)
	(segment
		(start 60.404756 -192.636648)
		(end 60.436506 -192.636648)
		(width 0.11684)
		(layer "In11.Cu")
		(net "RST_CPU0_RESETL_N")
	)
	(segment
		(start 39.561516 -146.899376)
		(end 39.561516 -155.033726)
		(width 0.11684)
		(layer "In11.Cu")
		(net "RST_CPU0_RESETL_N")
	)
	(segment
		(start 63.799974 -196.000116)
		(end 63.799974 -197.57009)
		(width 0.11684)
		(layer "In11.Cu")
		(net "RST_CPU0_RESETL_N")
	)
	(segment
		(start 106.085132 -134.183374)
		(end 52.277518 -134.183374)
		(width 0.11684)
		(layer "In11.Cu")
		(net "RST_CPU0_RESETL_N")
	)
	(segment
		(start 67.221608 -200.991724)
		(end 70.805548 -200.991724)
		(width 0.11684)
		(layer "In11.Cu")
		(net "RST_CPU0_RESETL_N")
	)
	(segment
		(start 112.695482 -127.573024)
		(end 106.085132 -134.183374)
		(width 0.11684)
		(layer "In11.Cu")
		(net "RST_CPU0_RESETL_N")
	)
	(segment
		(start 39.561516 -155.033726)
		(end 31.313628 -163.281614)
		(width 0.11684)
		(layer "In11.Cu")
		(net "RST_CPU0_RESETL_N")
	)
	(segment
		(start 60.436506 -192.636648)
		(end 63.799974 -196.000116)
		(width 0.11684)
		(layer "In11.Cu")
		(net "RST_CPU0_RESETL_N")
	)
	(segment
		(start 58.89117 -191.123062)
		(end 60.404756 -192.636648)
		(width 0.11684)
		(layer "In11.Cu")
		(net "RST_CPU0_RESETL_N")
	)
	(segment
		(start 37.229542 -183.748426)
		(end 37.229542 -188.059568)
		(width 0.11684)
		(layer "In11.Cu")
		(net "RST_CPU0_RESETL_N")
	)
	(segment
		(start 40.293036 -191.123062)
		(end 58.89117 -191.123062)
		(width 0.11684)
		(layer "In11.Cu")
		(net "RST_CPU0_RESETL_N")
	)
	(segment
		(start 37.229542 -188.059568)
		(end 40.293036 -191.123062)
		(width 0.11684)
		(layer "In11.Cu")
		(net "RST_CPU0_RESETL_N")
	)
	(segment
		(start 31.313628 -163.281614)
		(end 31.313628 -177.832512)
		(width 0.11684)
		(layer "In11.Cu")
		(net "RST_CPU0_RESETL_N")
	)
	(segment
		(start 31.313628 -177.832512)
		(end 37.229542 -183.748426)
		(width 0.11684)
		(layer "In11.Cu")
		(net "RST_CPU0_RESETL_N")
	)
	(segment
		(start 182.462932 -130.925824)
		(end 182.994808 -130.393948)
		(width 0.11684)
		(layer "In15.Cu")
		(net "RST_CPU0_RESETL_N")
	)
	(segment
		(start 196.204586 -166.44366)
		(end 192.631822 -162.870896)
		(width 0.11684)
		(layer "In15.Cu")
		(net "RST_CPU0_RESETL_N")
	)
	(segment
		(start 180.037994 -139.692634)
		(end 181.203346 -139.692634)
		(width 0.11684)
		(layer "In15.Cu")
		(net "RST_CPU0_RESETL_N")
	)
	(segment
		(start 183.75757 -157.690312)
		(end 183.75757 -149.275038)
		(width 0.11684)
		(layer "In15.Cu")
		(net "RST_CPU0_RESETL_N")
	)
	(segment
		(start 192.631822 -162.870896)
		(end 188.938154 -162.870896)
		(width 0.11684)
		(layer "In15.Cu")
		(net "RST_CPU0_RESETL_N")
	)
	(segment
		(start 181.688994 -147.206462)
		(end 181.688994 -145.526252)
		(width 0.11684)
		(layer "In15.Cu")
		(net "RST_CPU0_RESETL_N")
	)
	(segment
		(start 182.78094 -133.446012)
		(end 182.78094 -132.19684)
		(width 0.11684)
		(layer "In15.Cu")
		(net "RST_CPU0_RESETL_N")
	)
	(segment
		(start 179.471066 -143.308324)
		(end 179.471066 -140.259562)
		(width 0.11684)
		(layer "In15.Cu")
		(net "RST_CPU0_RESETL_N")
	)
	(segment
		(start 182.462932 -131.878832)
		(end 182.462932 -130.925824)
		(width 0.11684)
		(layer "In15.Cu")
		(net "RST_CPU0_RESETL_N")
	)
	(segment
		(start 182.274718 -138.621262)
		(end 182.274718 -133.952234)
		(width 0.11684)
		(layer "In15.Cu")
		(net "RST_CPU0_RESETL_N")
	)
	(segment
		(start 183.75757 -149.275038)
		(end 181.688994 -147.206462)
		(width 0.11684)
		(layer "In15.Cu")
		(net "RST_CPU0_RESETL_N")
	)
	(segment
		(start 182.274718 -133.952234)
		(end 182.78094 -133.446012)
		(width 0.11684)
		(layer "In15.Cu")
		(net "RST_CPU0_RESETL_N")
	)
	(segment
		(start 181.688994 -145.526252)
		(end 179.471066 -143.308324)
		(width 0.11684)
		(layer "In15.Cu")
		(net "RST_CPU0_RESETL_N")
	)
	(segment
		(start 182.78094 -132.19684)
		(end 182.462932 -131.878832)
		(width 0.11684)
		(layer "In15.Cu")
		(net "RST_CPU0_RESETL_N")
	)
	(segment
		(start 188.938154 -162.870896)
		(end 183.75757 -157.690312)
		(width 0.11684)
		(layer "In15.Cu")
		(net "RST_CPU0_RESETL_N")
	)
	(segment
		(start 179.471066 -140.259562)
		(end 180.037994 -139.692634)
		(width 0.11684)
		(layer "In15.Cu")
		(net "RST_CPU0_RESETL_N")
	)
	(segment
		(start 181.203346 -139.692634)
		(end 182.274718 -138.621262)
		(width 0.11684)
		(layer "In15.Cu")
		(net "RST_CPU0_RESETL_N")
	)
	(segment
		(start 179.52212 -121.852944)
		(end 179.13223 -122.242834)
		(width 0.10668)
		(layer "F.Cu")
		(net "RST_CPU0_PERST1_R_N")
	)
	(via
		(at 176.949608 -126.350776)
		(size 0.6604)
		(drill 0.3302)
		(layers "F.Cu" "B.Cu")
		(net "RST_CPU0_PERST1_R_N")
	)
	(via
		(at 179.13223 -122.242834)
		(size 0.4572)
		(drill 0.254)
		(layers "F.Cu" "B.Cu")
		(net "RST_CPU0_PERST1_R_N")
	)
	(segment
		(start 176.949608 -126.024132)
		(end 179.13223 -123.84151)
		(width 0.10668)
		(layer "B.Cu")
		(net "RST_CPU0_PERST1_R_N")
	)
	(segment
		(start 176.943258 -126.357126)
		(end 176.949608 -126.350776)
		(width 0.10668)
		(layer "B.Cu")
		(net "RST_CPU0_PERST1_R_N")
	)
	(segment
		(start 179.13223 -123.84151)
		(end 179.13223 -122.242834)
		(width 0.10668)
		(layer "B.Cu")
		(net "RST_CPU0_PERST1_R_N")
	)
	(segment
		(start 176.949608 -126.350776)
		(end 176.949608 -126.024132)
		(width 0.10668)
		(layer "B.Cu")
		(net "RST_CPU0_PERST1_R_N")
	)
	(segment
		(start 176.943258 -127.643636)
		(end 176.943258 -126.357126)
		(width 0.10668)
		(layer "B.Cu")
		(net "RST_CPU0_PERST1_R_N")
	)
	(segment
		(start 176.911 -133.168898)
		(end 176.78908 -133.046978)
		(width 0.10668)
		(layer "F.Cu")
		(net "RST_CPU0_PERST1_N")
	)
	(segment
		(start 361.42803 -294.070024)
		(end 361.894882 -294.335962)
		(width 0.10668)
		(layer "F.Cu")
		(net "RST_CPU0_PERST1_N")
	)
	(segment
		(start 176.78908 -133.046978)
		(end 176.78908 -132.548376)
		(width 0.10668)
		(layer "F.Cu")
		(net "RST_CPU0_PERST1_N")
	)
	(via
		(at 361.894882 -294.335962)
		(size 0.4064)
		(drill 0.2032)
		(layers "F.Cu" "B.Cu")
		(net "RST_CPU0_PERST1_N")
	)
	(via
		(at 401.570698 -334.29194)
		(size 0.6604)
		(drill 0.3302)
		(layers "F.Cu" "B.Cu")
		(net "RST_CPU0_PERST1_N")
	)
	(via
		(at 406.207214 -331.881988)
		(size 0.508)
		(drill 0.254)
		(layers "F.Cu" "B.Cu")
		(net "RST_CPU0_PERST1_N")
	)
	(via
		(at 176.78908 -132.548376)
		(size 0.508)
		(drill 0.254)
		(layers "F.Cu" "B.Cu")
		(net "RST_CPU0_PERST1_N")
	)
	(via
		(at 213.121494 -141.175232)
		(size 0.508)
		(drill 0.254)
		(layers "F.Cu" "B.Cu")
		(net "RST_CPU0_PERST1_N")
	)
	(segment
		(start 370.991638 -315.007752)
		(end 370.991638 -313.205368)
		(width 0.10668)
		(layer "B.Cu")
		(net "RST_CPU0_PERST1_N")
	)
	(segment
		(start 176.143158 -131.902454)
		(end 176.78908 -132.548376)
		(width 0.10668)
		(layer "B.Cu")
		(net "RST_CPU0_PERST1_N")
	)
	(segment
		(start 400.504152 -334.66151)
		(end 397.79448 -334.66151)
		(width 0.10668)
		(layer "B.Cu")
		(net "RST_CPU0_PERST1_N")
	)
	(segment
		(start 397.794226 -334.661764)
		(end 396.468346 -334.661764)
		(width 0.10668)
		(layer "B.Cu")
		(net "RST_CPU0_PERST1_N")
	)
	(segment
		(start 390.645396 -334.66151)
		(end 370.991638 -315.007752)
		(width 0.10668)
		(layer "B.Cu")
		(net "RST_CPU0_PERST1_N")
	)
	(segment
		(start 401.570698 -334.29194)
		(end 403.797262 -334.29194)
		(width 0.10668)
		(layer "B.Cu")
		(net "RST_CPU0_PERST1_N")
	)
	(segment
		(start 403.797262 -334.29194)
		(end 406.207214 -331.881988)
		(width 0.10668)
		(layer "B.Cu")
		(net "RST_CPU0_PERST1_N")
	)
	(segment
		(start 361.894882 -304.108612)
		(end 361.894882 -294.335962)
		(width 0.10668)
		(layer "B.Cu")
		(net "RST_CPU0_PERST1_N")
	)
	(segment
		(start 396.468092 -334.66151)
		(end 390.645396 -334.66151)
		(width 0.10668)
		(layer "B.Cu")
		(net "RST_CPU0_PERST1_N")
	)
	(segment
		(start 400.873722 -334.29194)
		(end 400.504152 -334.66151)
		(width 0.10668)
		(layer "B.Cu")
		(net "RST_CPU0_PERST1_N")
	)
	(segment
		(start 396.468346 -334.661764)
		(end 396.468092 -334.66151)
		(width 0.10668)
		(layer "B.Cu")
		(net "RST_CPU0_PERST1_N")
	)
	(segment
		(start 176.143158 -127.643636)
		(end 176.143158 -131.902454)
		(width 0.10668)
		(layer "B.Cu")
		(net "RST_CPU0_PERST1_N")
	)
	(segment
		(start 370.991638 -313.205368)
		(end 361.894882 -304.108612)
		(width 0.10668)
		(layer "B.Cu")
		(net "RST_CPU0_PERST1_N")
	)
	(segment
		(start 397.79448 -334.66151)
		(end 397.794226 -334.661764)
		(width 0.10668)
		(layer "B.Cu")
		(net "RST_CPU0_PERST1_N")
	)
	(segment
		(start 401.570698 -334.29194)
		(end 400.873722 -334.29194)
		(width 0.10668)
		(layer "B.Cu")
		(net "RST_CPU0_PERST1_N")
	)
	(segment
		(start 406.207214 -331.881988)
		(end 406.580594 -332.255368)
		(width 0.11684)
		(layer "In6.Cu")
		(net "RST_CPU0_PERST1_N")
	)
	(segment
		(start 462.077816 -187.971684)
		(end 451.000622 -176.89449)
		(width 0.11684)
		(layer "In6.Cu")
		(net "RST_CPU0_PERST1_N")
	)
	(segment
		(start 359.193084 -131.115308)
		(end 348.418658 -131.115308)
		(width 0.11684)
		(layer "In6.Cu")
		(net "RST_CPU0_PERST1_N")
	)
	(segment
		(start 451.000622 -169.83329)
		(end 441.73902 -160.571688)
		(width 0.11684)
		(layer "In6.Cu")
		(net "RST_CPU0_PERST1_N")
	)
	(segment
		(start 239.987074 -140.495782)
		(end 213.800944 -140.495782)
		(width 0.11684)
		(layer "In6.Cu")
		(net "RST_CPU0_PERST1_N")
	)
	(segment
		(start 213.800944 -140.495782)
		(end 213.121494 -141.175232)
		(width 0.11684)
		(layer "In6.Cu")
		(net "RST_CPU0_PERST1_N")
	)
	(segment
		(start 244.485668 -144.994376)
		(end 239.987074 -140.495782)
		(width 0.11684)
		(layer "In6.Cu")
		(net "RST_CPU0_PERST1_N")
	)
	(segment
		(start 360.425492 -129.8829)
		(end 359.193084 -131.115308)
		(width 0.11684)
		(layer "In6.Cu")
		(net "RST_CPU0_PERST1_N")
	)
	(segment
		(start 441.73902 -160.571688)
		(end 439.571384 -160.571688)
		(width 0.11684)
		(layer "In6.Cu")
		(net "RST_CPU0_PERST1_N")
	)
	(segment
		(start 291.3888 -141.552168)
		(end 272.797016 -141.552168)
		(width 0.11684)
		(layer "In6.Cu")
		(net "RST_CPU0_PERST1_N")
	)
	(segment
		(start 303.684686 -129.256282)
		(end 291.3888 -141.552168)
		(width 0.11684)
		(layer "In6.Cu")
		(net "RST_CPU0_PERST1_N")
	)
	(segment
		(start 462.077816 -320.72199)
		(end 462.077816 -187.971684)
		(width 0.11684)
		(layer "In6.Cu")
		(net "RST_CPU0_PERST1_N")
	)
	(segment
		(start 272.797016 -141.552168)
		(end 263.012936 -151.336248)
		(width 0.11684)
		(layer "In6.Cu")
		(net "RST_CPU0_PERST1_N")
	)
	(segment
		(start 416.031172 -129.8829)
		(end 360.425492 -129.8829)
		(width 0.11684)
		(layer "In6.Cu")
		(net "RST_CPU0_PERST1_N")
	)
	(segment
		(start 319.491614 -129.256282)
		(end 303.684686 -129.256282)
		(width 0.11684)
		(layer "In6.Cu")
		(net "RST_CPU0_PERST1_N")
	)
	(segment
		(start 409.208478 -332.255368)
		(end 413.498538 -327.965308)
		(width 0.11684)
		(layer "In6.Cu")
		(net "RST_CPU0_PERST1_N")
	)
	(segment
		(start 439.571384 -160.571688)
		(end 432.843686 -153.84399)
		(width 0.11684)
		(layer "In6.Cu")
		(net "RST_CPU0_PERST1_N")
	)
	(segment
		(start 451.000622 -176.89449)
		(end 451.000622 -169.83329)
		(width 0.11684)
		(layer "In6.Cu")
		(net "RST_CPU0_PERST1_N")
	)
	(segment
		(start 343.53627 -126.23292)
		(end 322.514976 -126.23292)
		(width 0.11684)
		(layer "In6.Cu")
		(net "RST_CPU0_PERST1_N")
	)
	(segment
		(start 250.961906 -151.336248)
		(end 244.620034 -144.994376)
		(width 0.11684)
		(layer "In6.Cu")
		(net "RST_CPU0_PERST1_N")
	)
	(segment
		(start 348.418658 -131.115308)
		(end 343.53627 -126.23292)
		(width 0.11684)
		(layer "In6.Cu")
		(net "RST_CPU0_PERST1_N")
	)
	(segment
		(start 454.834498 -327.965308)
		(end 462.077816 -320.72199)
		(width 0.11684)
		(layer "In6.Cu")
		(net "RST_CPU0_PERST1_N")
	)
	(segment
		(start 322.514976 -126.23292)
		(end 319.491614 -129.256282)
		(width 0.11684)
		(layer "In6.Cu")
		(net "RST_CPU0_PERST1_N")
	)
	(segment
		(start 413.498538 -327.965308)
		(end 454.834498 -327.965308)
		(width 0.11684)
		(layer "In6.Cu")
		(net "RST_CPU0_PERST1_N")
	)
	(segment
		(start 432.843686 -153.84399)
		(end 432.843686 -146.695414)
		(width 0.11684)
		(layer "In6.Cu")
		(net "RST_CPU0_PERST1_N")
	)
	(segment
		(start 244.620034 -144.994376)
		(end 244.485668 -144.994376)
		(width 0.11684)
		(layer "In6.Cu")
		(net "RST_CPU0_PERST1_N")
	)
	(segment
		(start 406.580594 -332.255368)
		(end 409.208478 -332.255368)
		(width 0.11684)
		(layer "In6.Cu")
		(net "RST_CPU0_PERST1_N")
	)
	(segment
		(start 432.843686 -146.695414)
		(end 416.031172 -129.8829)
		(width 0.11684)
		(layer "In6.Cu")
		(net "RST_CPU0_PERST1_N")
	)
	(segment
		(start 263.012936 -151.336248)
		(end 250.961906 -151.336248)
		(width 0.11684)
		(layer "In6.Cu")
		(net "RST_CPU0_PERST1_N")
	)
	(segment
		(start 178.05527 -133.814566)
		(end 176.78908 -132.548376)
		(width 0.11684)
		(layer "In13.Cu")
		(net "RST_CPU0_PERST1_N")
	)
	(segment
		(start 184.98185 -137.555986)
		(end 184.568338 -137.142474)
		(width 0.11684)
		(layer "In13.Cu")
		(net "RST_CPU0_PERST1_N")
	)
	(segment
		(start 213.121494 -141.175232)
		(end 212.384132 -141.175232)
		(width 0.11684)
		(layer "In13.Cu")
		(net "RST_CPU0_PERST1_N")
	)
	(segment
		(start 183.973724 -133.814566)
		(end 178.05527 -133.814566)
		(width 0.11684)
		(layer "In13.Cu")
		(net "RST_CPU0_PERST1_N")
	)
	(segment
		(start 212.384132 -141.175232)
		(end 209.208624 -137.999724)
		(width 0.11684)
		(layer "In13.Cu")
		(net "RST_CPU0_PERST1_N")
	)
	(segment
		(start 209.208624 -137.999724)
		(end 199.171052 -137.999724)
		(width 0.11684)
		(layer "In13.Cu")
		(net "RST_CPU0_PERST1_N")
	)
	(segment
		(start 198.727314 -137.555986)
		(end 184.98185 -137.555986)
		(width 0.11684)
		(layer "In13.Cu")
		(net "RST_CPU0_PERST1_N")
	)
	(segment
		(start 184.568338 -134.40918)
		(end 183.973724 -133.814566)
		(width 0.11684)
		(layer "In13.Cu")
		(net "RST_CPU0_PERST1_N")
	)
	(segment
		(start 199.171052 -137.999724)
		(end 198.727314 -137.555986)
		(width 0.11684)
		(layer "In13.Cu")
		(net "RST_CPU0_PERST1_N")
	)
	(segment
		(start 184.568338 -137.142474)
		(end 184.568338 -134.40918)
		(width 0.11684)
		(layer "In13.Cu")
		(net "RST_CPU0_PERST1_N")
	)
	(segment
		(start 181.122066 -119.452898)
		(end 180.732176 -119.842788)
		(width 0.10668)
		(layer "F.Cu")
		(net "RST_CPU0_PERST0_R_N")
	)
	(via
		(at 178.550316 -125.231652)
		(size 0.6604)
		(drill 0.3302)
		(layers "F.Cu" "B.Cu")
		(net "RST_CPU0_PERST0_R_N")
	)
	(via
		(at 180.732176 -119.842788)
		(size 0.4572)
		(drill 0.254)
		(layers "F.Cu" "B.Cu")
		(net "RST_CPU0_PERST0_R_N")
	)
	(segment
		(start 180.732176 -120.073928)
		(end 180.335936 -120.470168)
		(width 0.10668)
		(layer "B.Cu")
		(net "RST_CPU0_PERST0_R_N")
	)
	(segment
		(start 177.965608 -125.81636)
		(end 177.965608 -126.433326)
		(width 0.10668)
		(layer "B.Cu")
		(net "RST_CPU0_PERST0_R_N")
	)
	(segment
		(start 180.335936 -120.470168)
		(end 180.335936 -120.841008)
		(width 0.10668)
		(layer "B.Cu")
		(net "RST_CPU0_PERST0_R_N")
	)
	(segment
		(start 179.52847 -121.202196)
		(end 179.52847 -124.253498)
		(width 0.10668)
		(layer "B.Cu")
		(net "RST_CPU0_PERST0_R_N")
	)
	(segment
		(start 179.52847 -124.253498)
		(end 178.550316 -125.231652)
		(width 0.10668)
		(layer "B.Cu")
		(net "RST_CPU0_PERST0_R_N")
	)
	(segment
		(start 180.732176 -119.842788)
		(end 180.732176 -120.073928)
		(width 0.10668)
		(layer "B.Cu")
		(net "RST_CPU0_PERST0_R_N")
	)
	(segment
		(start 178.550316 -125.231652)
		(end 177.965608 -125.81636)
		(width 0.10668)
		(layer "B.Cu")
		(net "RST_CPU0_PERST0_R_N")
	)
	(segment
		(start 180.13045 -121.046494)
		(end 179.684172 -121.046494)
		(width 0.10668)
		(layer "B.Cu")
		(net "RST_CPU0_PERST0_R_N")
	)
	(segment
		(start 179.684172 -121.046494)
		(end 179.52847 -121.202196)
		(width 0.10668)
		(layer "B.Cu")
		(net "RST_CPU0_PERST0_R_N")
	)
	(segment
		(start 180.335936 -120.841008)
		(end 180.13045 -121.046494)
		(width 0.10668)
		(layer "B.Cu")
		(net "RST_CPU0_PERST0_R_N")
	)
	(segment
		(start 378.517912 -224.500186)
		(end 378.984764 -224.234248)
		(width 0.10668)
		(layer "F.Cu")
		(net "RST_CPU0_PERST0_N")
	)
	(via
		(at 428.21606 -179.98694)
		(size 0.508)
		(drill 0.254)
		(layers "F.Cu" "B.Cu")
		(net "RST_CPU0_PERST0_N")
	)
	(via
		(at 430.14646 -157.650688)
		(size 0.508)
		(drill 0.254)
		(layers "F.Cu" "B.Cu")
		(net "RST_CPU0_PERST0_N")
	)
	(via
		(at 378.984764 -224.234248)
		(size 0.4064)
		(drill 0.2032)
		(layers "F.Cu" "B.Cu")
		(net "RST_CPU0_PERST0_N")
	)
	(via
		(at 178.762152 -132.541518)
		(size 0.508)
		(drill 0.254)
		(layers "F.Cu" "B.Cu")
		(net "RST_CPU0_PERST0_N")
	)
	(via
		(at 278.31542 -129.377948)
		(size 0.508)
		(drill 0.254)
		(layers "F.Cu" "B.Cu")
		(net "RST_CPU0_PERST0_N")
	)
	(segment
		(start 178.762152 -133.15315)
		(end 178.762152 -132.541518)
		(width 0.10668)
		(layer "B.Cu")
		(net "RST_CPU0_PERST0_N")
	)
	(segment
		(start 177.155602 -128.643888)
		(end 177.965608 -127.833882)
		(width 0.10668)
		(layer "B.Cu")
		(net "RST_CPU0_PERST0_N")
	)
	(segment
		(start 177.965608 -127.833882)
		(end 177.965608 -127.233426)
		(width 0.10668)
		(layer "B.Cu")
		(net "RST_CPU0_PERST0_N")
	)
	(segment
		(start 178.641502 -133.2738)
		(end 178.762152 -133.15315)
		(width 0.10668)
		(layer "B.Cu")
		(net "RST_CPU0_PERST0_N")
	)
	(segment
		(start 178.762152 -132.541518)
		(end 177.155602 -130.934968)
		(width 0.10668)
		(layer "B.Cu")
		(net "RST_CPU0_PERST0_N")
	)
	(segment
		(start 177.155602 -130.934968)
		(end 177.155602 -128.643888)
		(width 0.10668)
		(layer "B.Cu")
		(net "RST_CPU0_PERST0_N")
	)
	(segment
		(start 354.092764 -135.726932)
		(end 355.497892 -134.321804)
		(width 0.11684)
		(layer "In2.Cu")
		(net "RST_CPU0_PERST0_N")
	)
	(segment
		(start 310.548528 -126.548388)
		(end 315.112908 -131.112768)
		(width 0.11684)
		(layer "In2.Cu")
		(net "RST_CPU0_PERST0_N")
	)
	(segment
		(start 290.67252 -121.130568)
		(end 295.22674 -121.130568)
		(width 0.11684)
		(layer "In2.Cu")
		(net "RST_CPU0_PERST0_N")
	)
	(segment
		(start 282.42514 -129.377948)
		(end 290.67252 -121.130568)
		(width 0.11684)
		(layer "In2.Cu")
		(net "RST_CPU0_PERST0_N")
	)
	(segment
		(start 381.93218 -211.5312)
		(end 379.67412 -213.78926)
		(width 0.11684)
		(layer "In2.Cu")
		(net "RST_CPU0_PERST0_N")
	)
	(segment
		(start 428.1297 -183.64708)
		(end 422.37406 -189.40272)
		(width 0.11684)
		(layer "In2.Cu")
		(net "RST_CPU0_PERST0_N")
	)
	(segment
		(start 394.78966 -204.31506)
		(end 394.78966 -205.93558)
		(width 0.11684)
		(layer "In2.Cu")
		(net "RST_CPU0_PERST0_N")
	)
	(segment
		(start 409.702 -189.40272)
		(end 394.78966 -204.31506)
		(width 0.11684)
		(layer "In2.Cu")
		(net "RST_CPU0_PERST0_N")
	)
	(segment
		(start 315.112908 -131.112768)
		(end 341.359236 -131.112768)
		(width 0.11684)
		(layer "In2.Cu")
		(net "RST_CPU0_PERST0_N")
	)
	(segment
		(start 383.78384 -211.5312)
		(end 381.93218 -211.5312)
		(width 0.11684)
		(layer "In2.Cu")
		(net "RST_CPU0_PERST0_N")
	)
	(segment
		(start 428.387256 -144.742408)
		(end 428.387256 -155.891484)
		(width 0.11684)
		(layer "In2.Cu")
		(net "RST_CPU0_PERST0_N")
	)
	(segment
		(start 379.67412 -213.78926)
		(end 379.67412 -223.84004)
		(width 0.11684)
		(layer "In2.Cu")
		(net "RST_CPU0_PERST0_N")
	)
	(segment
		(start 428.1297 -180.0733)
		(end 428.1297 -183.64708)
		(width 0.11684)
		(layer "In2.Cu")
		(net "RST_CPU0_PERST0_N")
	)
	(segment
		(start 422.37406 -189.40272)
		(end 409.702 -189.40272)
		(width 0.11684)
		(layer "In2.Cu")
		(net "RST_CPU0_PERST0_N")
	)
	(segment
		(start 394.78966 -205.93558)
		(end 393.26566 -207.45958)
		(width 0.11684)
		(layer "In2.Cu")
		(net "RST_CPU0_PERST0_N")
	)
	(segment
		(start 393.26566 -207.45958)
		(end 387.85546 -207.45958)
		(width 0.11684)
		(layer "In2.Cu")
		(net "RST_CPU0_PERST0_N")
	)
	(segment
		(start 428.387256 -155.891484)
		(end 430.14646 -157.650688)
		(width 0.11684)
		(layer "In2.Cu")
		(net "RST_CPU0_PERST0_N")
	)
	(segment
		(start 428.21606 -179.98694)
		(end 428.1297 -180.0733)
		(width 0.11684)
		(layer "In2.Cu")
		(net "RST_CPU0_PERST0_N")
	)
	(segment
		(start 345.9734 -135.726932)
		(end 354.092764 -135.726932)
		(width 0.11684)
		(layer "In2.Cu")
		(net "RST_CPU0_PERST0_N")
	)
	(segment
		(start 406.051512 -134.321804)
		(end 408.429714 -131.943602)
		(width 0.11684)
		(layer "In2.Cu")
		(net "RST_CPU0_PERST0_N")
	)
	(segment
		(start 415.58845 -131.943602)
		(end 428.387256 -144.742408)
		(width 0.11684)
		(layer "In2.Cu")
		(net "RST_CPU0_PERST0_N")
	)
	(segment
		(start 355.497892 -134.321804)
		(end 406.051512 -134.321804)
		(width 0.11684)
		(layer "In2.Cu")
		(net "RST_CPU0_PERST0_N")
	)
	(segment
		(start 387.85546 -207.45958)
		(end 383.78384 -211.5312)
		(width 0.11684)
		(layer "In2.Cu")
		(net "RST_CPU0_PERST0_N")
	)
	(segment
		(start 379.67412 -223.84004)
		(end 379.279912 -224.234248)
		(width 0.11684)
		(layer "In2.Cu")
		(net "RST_CPU0_PERST0_N")
	)
	(segment
		(start 341.359236 -131.112768)
		(end 345.9734 -135.726932)
		(width 0.11684)
		(layer "In2.Cu")
		(net "RST_CPU0_PERST0_N")
	)
	(segment
		(start 296.13098 -124.003308)
		(end 298.67606 -126.548388)
		(width 0.11684)
		(layer "In2.Cu")
		(net "RST_CPU0_PERST0_N")
	)
	(segment
		(start 295.22674 -121.130568)
		(end 296.13098 -122.034808)
		(width 0.11684)
		(layer "In2.Cu")
		(net "RST_CPU0_PERST0_N")
	)
	(segment
		(start 408.429714 -131.943602)
		(end 415.58845 -131.943602)
		(width 0.11684)
		(layer "In2.Cu")
		(net "RST_CPU0_PERST0_N")
	)
	(segment
		(start 379.279912 -224.234248)
		(end 378.984764 -224.234248)
		(width 0.11684)
		(layer "In2.Cu")
		(net "RST_CPU0_PERST0_N")
	)
	(segment
		(start 278.31542 -129.377948)
		(end 282.42514 -129.377948)
		(width 0.11684)
		(layer "In2.Cu")
		(net "RST_CPU0_PERST0_N")
	)
	(segment
		(start 296.13098 -122.034808)
		(end 296.13098 -124.003308)
		(width 0.11684)
		(layer "In2.Cu")
		(net "RST_CPU0_PERST0_N")
	)
	(segment
		(start 298.67606 -126.548388)
		(end 310.548528 -126.548388)
		(width 0.11684)
		(layer "In2.Cu")
		(net "RST_CPU0_PERST0_N")
	)
	(segment
		(start 429.45558 -157.650688)
		(end 428.055786 -159.050482)
		(width 0.11684)
		(layer "In4.Cu")
		(net "RST_CPU0_PERST0_N")
	)
	(segment
		(start 428.055786 -179.826666)
		(end 428.21606 -179.98694)
		(width 0.11684)
		(layer "In4.Cu")
		(net "RST_CPU0_PERST0_N")
	)
	(segment
		(start 428.055786 -159.050482)
		(end 428.055786 -179.826666)
		(width 0.11684)
		(layer "In4.Cu")
		(net "RST_CPU0_PERST0_N")
	)
	(segment
		(start 430.14646 -157.650688)
		(end 429.45558 -157.650688)
		(width 0.11684)
		(layer "In4.Cu")
		(net "RST_CPU0_PERST0_N")
	)
	(segment
		(start 180.103272 -133.500368)
		(end 180.697886 -134.094982)
		(width 0.11684)
		(layer "In6.Cu")
		(net "RST_CPU0_PERST0_N")
	)
	(segment
		(start 180.697886 -134.094982)
		(end 183.092852 -134.094982)
		(width 0.11684)
		(layer "In6.Cu")
		(net "RST_CPU0_PERST0_N")
	)
	(segment
		(start 206.71663 -122.601228)
		(end 207.376776 -121.941082)
		(width 0.11684)
		(layer "In6.Cu")
		(net "RST_CPU0_PERST0_N")
	)
	(segment
		(start 213.249256 -121.941082)
		(end 215.05672 -120.133618)
		(width 0.11684)
		(layer "In6.Cu")
		(net "RST_CPU0_PERST0_N")
	)
	(segment
		(start 207.376776 -121.941082)
		(end 213.249256 -121.941082)
		(width 0.11684)
		(layer "In6.Cu")
		(net "RST_CPU0_PERST0_N")
	)
	(segment
		(start 203.7334 -123.351036)
		(end 204.483208 -122.601228)
		(width 0.11684)
		(layer "In6.Cu")
		(net "RST_CPU0_PERST0_N")
	)
	(segment
		(start 215.05672 -120.133618)
		(end 219.215462 -120.133618)
		(width 0.11684)
		(layer "In6.Cu")
		(net "RST_CPU0_PERST0_N")
	)
	(segment
		(start 204.483208 -122.601228)
		(end 206.71663 -122.601228)
		(width 0.11684)
		(layer "In6.Cu")
		(net "RST_CPU0_PERST0_N")
	)
	(segment
		(start 199.919336 -130.189732)
		(end 201.84872 -128.260348)
		(width 0.11684)
		(layer "In6.Cu")
		(net "RST_CPU0_PERST0_N")
	)
	(segment
		(start 219.215462 -120.133618)
		(end 219.965524 -120.88368)
		(width 0.11684)
		(layer "In6.Cu")
		(net "RST_CPU0_PERST0_N")
	)
	(segment
		(start 179.721002 -133.500368)
		(end 180.103272 -133.500368)
		(width 0.11684)
		(layer "In6.Cu")
		(net "RST_CPU0_PERST0_N")
	)
	(segment
		(start 195.880482 -133.500368)
		(end 199.191118 -130.189732)
		(width 0.11684)
		(layer "In6.Cu")
		(net "RST_CPU0_PERST0_N")
	)
	(segment
		(start 219.965524 -120.88368)
		(end 232.983532 -120.88368)
		(width 0.11684)
		(layer "In6.Cu")
		(net "RST_CPU0_PERST0_N")
	)
	(segment
		(start 202.348084 -123.351036)
		(end 203.7334 -123.351036)
		(width 0.11684)
		(layer "In6.Cu")
		(net "RST_CPU0_PERST0_N")
	)
	(segment
		(start 259.52196 -128.097788)
		(end 262.01878 -128.097788)
		(width 0.11684)
		(layer "In6.Cu")
		(net "RST_CPU0_PERST0_N")
	)
	(segment
		(start 262.56742 -127.549148)
		(end 276.48662 -127.549148)
		(width 0.11684)
		(layer "In6.Cu")
		(net "RST_CPU0_PERST0_N")
	)
	(segment
		(start 183.092852 -134.094982)
		(end 183.687466 -133.500368)
		(width 0.11684)
		(layer "In6.Cu")
		(net "RST_CPU0_PERST0_N")
	)
	(segment
		(start 237.031022 -124.93117)
		(end 253.924562 -124.93117)
		(width 0.11684)
		(layer "In6.Cu")
		(net "RST_CPU0_PERST0_N")
	)
	(segment
		(start 256.44094 -127.447548)
		(end 258.87172 -127.447548)
		(width 0.11684)
		(layer "In6.Cu")
		(net "RST_CPU0_PERST0_N")
	)
	(segment
		(start 262.01878 -128.097788)
		(end 262.56742 -127.549148)
		(width 0.11684)
		(layer "In6.Cu")
		(net "RST_CPU0_PERST0_N")
	)
	(segment
		(start 201.84872 -128.260348)
		(end 201.84872 -123.8504)
		(width 0.11684)
		(layer "In6.Cu")
		(net "RST_CPU0_PERST0_N")
	)
	(segment
		(start 183.687466 -133.500368)
		(end 195.880482 -133.500368)
		(width 0.11684)
		(layer "In6.Cu")
		(net "RST_CPU0_PERST0_N")
	)
	(segment
		(start 199.191118 -130.189732)
		(end 199.919336 -130.189732)
		(width 0.11684)
		(layer "In6.Cu")
		(net "RST_CPU0_PERST0_N")
	)
	(segment
		(start 232.983532 -120.88368)
		(end 237.031022 -124.93117)
		(width 0.11684)
		(layer "In6.Cu")
		(net "RST_CPU0_PERST0_N")
	)
	(segment
		(start 253.924562 -124.93117)
		(end 256.44094 -127.447548)
		(width 0.11684)
		(layer "In6.Cu")
		(net "RST_CPU0_PERST0_N")
	)
	(segment
		(start 258.87172 -127.447548)
		(end 259.52196 -128.097788)
		(width 0.11684)
		(layer "In6.Cu")
		(net "RST_CPU0_PERST0_N")
	)
	(segment
		(start 178.762152 -132.541518)
		(end 179.721002 -133.500368)
		(width 0.11684)
		(layer "In6.Cu")
		(net "RST_CPU0_PERST0_N")
	)
	(segment
		(start 201.84872 -123.8504)
		(end 202.348084 -123.351036)
		(width 0.11684)
		(layer "In6.Cu")
		(net "RST_CPU0_PERST0_N")
	)
	(segment
		(start 276.48662 -127.549148)
		(end 278.31542 -129.377948)
		(width 0.11684)
		(layer "In6.Cu")
		(net "RST_CPU0_PERST0_N")
	)
	(segment
		(start 370.828062 -295.690036)
		(end 371.294914 -295.955974)
		(width 0.10668)
		(layer "F.Cu")
		(net "RST_CPU0_KBRST_R_N")
	)
	(via
		(at 371.612414 -305.21656)
		(size 0.6604)
		(drill 0.3302)
		(layers "F.Cu" "B.Cu")
		(net "RST_CPU0_KBRST_R_N")
	)
	(via
		(at 371.294914 -295.955974)
		(size 0.4064)
		(drill 0.2032)
		(layers "F.Cu" "B.Cu")
		(net "RST_CPU0_KBRST_R_N")
	)
	(segment
		(start 392.93546 -326.653652)
		(end 392.768328 -326.48652)
		(width 0.10668)
		(layer "B.Cu")
		(net "RST_CPU0_KBRST_R_N")
	)
	(segment
		(start 392.768328 -326.48652)
		(end 392.768328 -326.000364)
		(width 0.10668)
		(layer "B.Cu")
		(net "RST_CPU0_KBRST_R_N")
	)
	(segment
		(start 395.518386 -327.372218)
		(end 395.27353 -327.372218)
		(width 0.10668)
		(layer "B.Cu")
		(net "RST_CPU0_KBRST_R_N")
	)
	(segment
		(start 395.91234 -327.766172)
		(end 395.518386 -327.372218)
		(width 0.10668)
		(layer "B.Cu")
		(net "RST_CPU0_KBRST_R_N")
	)
	(segment
		(start 395.27353 -327.372218)
		(end 394.750036 -326.848724)
		(width 0.10668)
		(layer "B.Cu")
		(net "RST_CPU0_KBRST_R_N")
	)
	(segment
		(start 382.967992 -317.227966)
		(end 371.612414 -305.872388)
		(width 0.10668)
		(layer "B.Cu")
		(net "RST_CPU0_KBRST_R_N")
	)
	(segment
		(start 389.931656 -323.163692)
		(end 388.150862 -323.163692)
		(width 0.10668)
		(layer "B.Cu")
		(net "RST_CPU0_KBRST_R_N")
	)
	(segment
		(start 371.612414 -305.21656)
		(end 371.612414 -303.409096)
		(width 0.10668)
		(layer "B.Cu")
		(net "RST_CPU0_KBRST_R_N")
	)
	(segment
		(start 371.294914 -303.091596)
		(end 371.294914 -295.955974)
		(width 0.10668)
		(layer "B.Cu")
		(net "RST_CPU0_KBRST_R_N")
	)
	(segment
		(start 388.150862 -323.163692)
		(end 382.967992 -317.980822)
		(width 0.10668)
		(layer "B.Cu")
		(net "RST_CPU0_KBRST_R_N")
	)
	(segment
		(start 371.612414 -303.409096)
		(end 371.294914 -303.091596)
		(width 0.10668)
		(layer "B.Cu")
		(net "RST_CPU0_KBRST_R_N")
	)
	(segment
		(start 393.86637 -326.848724)
		(end 393.671298 -326.653652)
		(width 0.10668)
		(layer "B.Cu")
		(net "RST_CPU0_KBRST_R_N")
	)
	(segment
		(start 394.750036 -326.848724)
		(end 393.86637 -326.848724)
		(width 0.10668)
		(layer "B.Cu")
		(net "RST_CPU0_KBRST_R_N")
	)
	(segment
		(start 396.146528 -327.766172)
		(end 396.146528 -328.655172)
		(width 0.10668)
		(layer "B.Cu")
		(net "RST_CPU0_KBRST_R_N")
	)
	(segment
		(start 392.768328 -326.000364)
		(end 389.931656 -323.163692)
		(width 0.10668)
		(layer "B.Cu")
		(net "RST_CPU0_KBRST_R_N")
	)
	(segment
		(start 396.146528 -327.766172)
		(end 395.91234 -327.766172)
		(width 0.10668)
		(layer "B.Cu")
		(net "RST_CPU0_KBRST_R_N")
	)
	(segment
		(start 382.967992 -317.980822)
		(end 382.967992 -317.227966)
		(width 0.10668)
		(layer "B.Cu")
		(net "RST_CPU0_KBRST_R_N")
	)
	(segment
		(start 393.671298 -326.653652)
		(end 392.93546 -326.653652)
		(width 0.10668)
		(layer "B.Cu")
		(net "RST_CPU0_KBRST_R_N")
	)
	(segment
		(start 371.612414 -305.872388)
		(end 371.612414 -305.21656)
		(width 0.10668)
		(layer "B.Cu")
		(net "RST_CPU0_KBRST_R_N")
	)
	(segment
		(start 181.922166 -119.452898)
		(end 181.532276 -119.842788)
		(width 0.10668)
		(layer "F.Cu")
		(net "RST_CPU0_KBRST_N")
	)
	(via
		(at 181.532276 -119.842788)
		(size 0.4572)
		(drill 0.254)
		(layers "F.Cu" "B.Cu")
		(net "RST_CPU0_KBRST_N")
	)
	(via
		(at 262.690356 -89.306654)
		(size 0.508)
		(drill 0.254)
		(layers "F.Cu" "B.Cu")
		(net "RST_CPU0_KBRST_N")
	)
	(via
		(at 398.018 -328.535284)
		(size 0.508)
		(drill 0.254)
		(layers "F.Cu" "B.Cu")
		(net "RST_CPU0_KBRST_N")
	)
	(via
		(at 183.764682 -146.02206)
		(size 0.508)
		(drill 0.254)
		(layers "F.Cu" "B.Cu")
		(net "RST_CPU0_KBRST_N")
	)
	(via
		(at 264.088372 -143.070072)
		(size 0.508)
		(drill 0.254)
		(layers "F.Cu" "B.Cu")
		(net "RST_CPU0_KBRST_N")
	)
	(segment
		(start 397.628618 -328.535284)
		(end 397.50873 -328.655172)
		(width 0.10668)
		(layer "B.Cu")
		(net "RST_CPU0_KBRST_N")
	)
	(segment
		(start 397.50873 -328.655172)
		(end 396.946628 -328.655172)
		(width 0.10668)
		(layer "B.Cu")
		(net "RST_CPU0_KBRST_N")
	)
	(segment
		(start 398.018 -328.535284)
		(end 397.628618 -328.535284)
		(width 0.10668)
		(layer "B.Cu")
		(net "RST_CPU0_KBRST_N")
	)
	(segment
		(start 279.053036 -100.513388)
		(end 273.609054 -95.069406)
		(width 0.11684)
		(layer "In2.Cu")
		(net "RST_CPU0_KBRST_N")
	)
	(segment
		(start 273.609054 -95.069406)
		(end 268.453108 -95.069406)
		(width 0.11684)
		(layer "In2.Cu")
		(net "RST_CPU0_KBRST_N")
	)
	(segment
		(start 408.747722 -329.124564)
		(end 411.681168 -326.191118)
		(width 0.11684)
		(layer "In2.Cu")
		(net "RST_CPU0_KBRST_N")
	)
	(segment
		(start 403.813264 -125.383036)
		(end 401.805902 -127.390398)
		(width 0.11684)
		(layer "In2.Cu")
		(net "RST_CPU0_KBRST_N")
	)
	(segment
		(start 448.530218 -174.370746)
		(end 448.530218 -148.296376)
		(width 0.11684)
		(layer "In2.Cu")
		(net "RST_CPU0_KBRST_N")
	)
	(segment
		(start 398.018 -328.535284)
		(end 399.716498 -330.233782)
		(width 0.11684)
		(layer "In2.Cu")
		(net "RST_CPU0_KBRST_N")
	)
	(segment
		(start 255.662938 -146.479514)
		(end 261.370826 -146.479514)
		(width 0.11684)
		(layer "In2.Cu")
		(net "RST_CPU0_KBRST_N")
	)
	(segment
		(start 401.805902 -127.390398)
		(end 347.975428 -127.390398)
		(width 0.11684)
		(layer "In2.Cu")
		(net "RST_CPU0_KBRST_N")
	)
	(segment
		(start 399.716498 -330.233782)
		(end 402.774912 -330.233782)
		(width 0.11684)
		(layer "In2.Cu")
		(net "RST_CPU0_KBRST_N")
	)
	(segment
		(start 196.432678 -144.532604)
		(end 197.266306 -143.698976)
		(width 0.11684)
		(layer "In2.Cu")
		(net "RST_CPU0_KBRST_N")
	)
	(segment
		(start 347.975428 -127.390398)
		(end 346.24137 -125.65634)
		(width 0.11684)
		(layer "In2.Cu")
		(net "RST_CPU0_KBRST_N")
	)
	(segment
		(start 403.493224 -329.51547)
		(end 407.803858 -329.51547)
		(width 0.11684)
		(layer "In2.Cu")
		(net "RST_CPU0_KBRST_N")
	)
	(segment
		(start 457.471018 -183.311546)
		(end 448.530218 -174.370746)
		(width 0.11684)
		(layer "In2.Cu")
		(net "RST_CPU0_KBRST_N")
	)
	(segment
		(start 268.453108 -95.069406)
		(end 262.690356 -89.306654)
		(width 0.11684)
		(layer "In2.Cu")
		(net "RST_CPU0_KBRST_N")
	)
	(segment
		(start 200.497694 -143.698976)
		(end 201.331322 -144.532604)
		(width 0.11684)
		(layer "In2.Cu")
		(net "RST_CPU0_KBRST_N")
	)
	(segment
		(start 460.163926 -189.845188)
		(end 457.471018 -187.15228)
		(width 0.11684)
		(layer "In2.Cu")
		(net "RST_CPU0_KBRST_N")
	)
	(segment
		(start 411.681168 -326.191118)
		(end 454.335642 -326.191118)
		(width 0.11684)
		(layer "In2.Cu")
		(net "RST_CPU0_KBRST_N")
	)
	(segment
		(start 287.744916 -109.314488)
		(end 279.053036 -100.622608)
		(width 0.11684)
		(layer "In2.Cu")
		(net "RST_CPU0_KBRST_N")
	)
	(segment
		(start 302.369474 -109.314488)
		(end 287.744916 -109.314488)
		(width 0.11684)
		(layer "In2.Cu")
		(net "RST_CPU0_KBRST_N")
	)
	(segment
		(start 192.445894 -144.532604)
		(end 196.432678 -144.532604)
		(width 0.11684)
		(layer "In2.Cu")
		(net "RST_CPU0_KBRST_N")
	)
	(segment
		(start 346.24137 -125.65634)
		(end 317.65494 -125.65634)
		(width 0.11684)
		(layer "In2.Cu")
		(net "RST_CPU0_KBRST_N")
	)
	(segment
		(start 303.56302 -110.508034)
		(end 302.369474 -109.314488)
		(width 0.11684)
		(layer "In2.Cu")
		(net "RST_CPU0_KBRST_N")
	)
	(segment
		(start 264.088372 -143.761968)
		(end 264.088372 -143.070072)
		(width 0.11684)
		(layer "In2.Cu")
		(net "RST_CPU0_KBRST_N")
	)
	(segment
		(start 317.65494 -125.65634)
		(end 303.56302 -111.56442)
		(width 0.11684)
		(layer "In2.Cu")
		(net "RST_CPU0_KBRST_N")
	)
	(segment
		(start 201.331322 -144.532604)
		(end 253.716028 -144.532604)
		(width 0.11684)
		(layer "In2.Cu")
		(net "RST_CPU0_KBRST_N")
	)
	(segment
		(start 279.053036 -100.622608)
		(end 279.053036 -100.513388)
		(width 0.11684)
		(layer "In2.Cu")
		(net "RST_CPU0_KBRST_N")
	)
	(segment
		(start 190.379858 -145.38833)
		(end 192.445894 -144.532604)
		(width 0.11684)
		(layer "In2.Cu")
		(net "RST_CPU0_KBRST_N")
	)
	(segment
		(start 261.370826 -146.479514)
		(end 264.088372 -143.761968)
		(width 0.11684)
		(layer "In2.Cu")
		(net "RST_CPU0_KBRST_N")
	)
	(segment
		(start 457.471018 -187.15228)
		(end 457.471018 -183.311546)
		(width 0.11684)
		(layer "In2.Cu")
		(net "RST_CPU0_KBRST_N")
	)
	(segment
		(start 460.163926 -320.362834)
		(end 460.163926 -189.845188)
		(width 0.11684)
		(layer "In2.Cu")
		(net "RST_CPU0_KBRST_N")
	)
	(segment
		(start 253.716028 -144.532604)
		(end 255.662938 -146.479514)
		(width 0.11684)
		(layer "In2.Cu")
		(net "RST_CPU0_KBRST_N")
	)
	(segment
		(start 454.335642 -326.191118)
		(end 460.163926 -320.362834)
		(width 0.11684)
		(layer "In2.Cu")
		(net "RST_CPU0_KBRST_N")
	)
	(segment
		(start 402.774912 -330.233782)
		(end 403.493224 -329.51547)
		(width 0.11684)
		(layer "In2.Cu")
		(net "RST_CPU0_KBRST_N")
	)
	(segment
		(start 407.803858 -329.51547)
		(end 408.747722 -329.124564)
		(width 0.11684)
		(layer "In2.Cu")
		(net "RST_CPU0_KBRST_N")
	)
	(segment
		(start 448.530218 -148.296376)
		(end 425.616878 -125.383036)
		(width 0.11684)
		(layer "In2.Cu")
		(net "RST_CPU0_KBRST_N")
	)
	(segment
		(start 303.56302 -111.56442)
		(end 303.56302 -110.508034)
		(width 0.11684)
		(layer "In2.Cu")
		(net "RST_CPU0_KBRST_N")
	)
	(segment
		(start 197.266306 -143.698976)
		(end 200.497694 -143.698976)
		(width 0.11684)
		(layer "In2.Cu")
		(net "RST_CPU0_KBRST_N")
	)
	(segment
		(start 183.764682 -146.02206)
		(end 184.398412 -145.38833)
		(width 0.11684)
		(layer "In2.Cu")
		(net "RST_CPU0_KBRST_N")
	)
	(segment
		(start 184.398412 -145.38833)
		(end 190.379858 -145.38833)
		(width 0.11684)
		(layer "In2.Cu")
		(net "RST_CPU0_KBRST_N")
	)
	(segment
		(start 425.616878 -125.383036)
		(end 403.813264 -125.383036)
		(width 0.11684)
		(layer "In2.Cu")
		(net "RST_CPU0_KBRST_N")
	)
	(segment
		(start 262.49122 -129.043684)
		(end 262.49122 -113.62309)
		(width 0.11684)
		(layer "In4.Cu")
		(net "RST_CPU0_KBRST_N")
	)
	(segment
		(start 261.932928 -103.162862)
		(end 262.690356 -102.405434)
		(width 0.11684)
		(layer "In4.Cu")
		(net "RST_CPU0_KBRST_N")
	)
	(segment
		(start 263.082532 -141.543532)
		(end 263.082532 -139.360148)
		(width 0.11684)
		(layer "In4.Cu")
		(net "RST_CPU0_KBRST_N")
	)
	(segment
		(start 262.49122 -113.62309)
		(end 261.932928 -113.064798)
		(width 0.11684)
		(layer "In4.Cu")
		(net "RST_CPU0_KBRST_N")
	)
	(segment
		(start 261.227316 -130.307588)
		(end 262.49122 -129.043684)
		(width 0.11684)
		(layer "In4.Cu")
		(net "RST_CPU0_KBRST_N")
	)
	(segment
		(start 261.227316 -137.504932)
		(end 261.227316 -130.307588)
		(width 0.11684)
		(layer "In4.Cu")
		(net "RST_CPU0_KBRST_N")
	)
	(segment
		(start 261.932928 -113.064798)
		(end 261.932928 -103.162862)
		(width 0.11684)
		(layer "In4.Cu")
		(net "RST_CPU0_KBRST_N")
	)
	(segment
		(start 264.088372 -143.070072)
		(end 264.088372 -142.549372)
		(width 0.11684)
		(layer "In4.Cu")
		(net "RST_CPU0_KBRST_N")
	)
	(segment
		(start 263.082532 -139.360148)
		(end 261.227316 -137.504932)
		(width 0.11684)
		(layer "In4.Cu")
		(net "RST_CPU0_KBRST_N")
	)
	(segment
		(start 264.088372 -142.549372)
		(end 263.082532 -141.543532)
		(width 0.11684)
		(layer "In4.Cu")
		(net "RST_CPU0_KBRST_N")
	)
	(segment
		(start 262.690356 -102.405434)
		(end 262.690356 -89.306654)
		(width 0.11684)
		(layer "In4.Cu")
		(net "RST_CPU0_KBRST_N")
	)
	(segment
		(start 180.89626 -131.23926)
		(end 181.453028 -130.682492)
		(width 0.11684)
		(layer "In11.Cu")
		(net "RST_CPU0_KBRST_N")
	)
	(segment
		(start 181.453028 -130.682492)
		(end 181.453028 -128.06045)
		(width 0.11684)
		(layer "In11.Cu")
		(net "RST_CPU0_KBRST_N")
	)
	(segment
		(start 180.394356 -133.290564)
		(end 180.394356 -132.243322)
		(width 0.11684)
		(layer "In11.Cu")
		(net "RST_CPU0_KBRST_N")
	)
	(segment
		(start 180.89626 -131.741418)
		(end 180.89626 -131.23926)
		(width 0.11684)
		(layer "In11.Cu")
		(net "RST_CPU0_KBRST_N")
	)
	(segment
		(start 182.534814 -120.234964)
		(end 181.924452 -120.234964)
		(width 0.11684)
		(layer "In11.Cu")
		(net "RST_CPU0_KBRST_N")
	)
	(segment
		(start 181.924452 -120.234964)
		(end 181.532276 -119.842788)
		(width 0.11684)
		(layer "In11.Cu")
		(net "RST_CPU0_KBRST_N")
	)
	(segment
		(start 183.764682 -146.02206)
		(end 182.21452 -144.471898)
		(width 0.11684)
		(layer "In11.Cu")
		(net "RST_CPU0_KBRST_N")
	)
	(segment
		(start 182.21452 -135.110728)
		(end 180.394356 -133.290564)
		(width 0.11684)
		(layer "In11.Cu")
		(net "RST_CPU0_KBRST_N")
	)
	(segment
		(start 182.73776 -120.43791)
		(end 182.534814 -120.234964)
		(width 0.11684)
		(layer "In11.Cu")
		(net "RST_CPU0_KBRST_N")
	)
	(segment
		(start 182.21452 -144.471898)
		(end 182.21452 -135.110728)
		(width 0.11684)
		(layer "In11.Cu")
		(net "RST_CPU0_KBRST_N")
	)
	(segment
		(start 182.73776 -126.775718)
		(end 182.73776 -120.43791)
		(width 0.11684)
		(layer "In11.Cu")
		(net "RST_CPU0_KBRST_N")
	)
	(segment
		(start 181.453028 -128.06045)
		(end 182.73776 -126.775718)
		(width 0.11684)
		(layer "In11.Cu")
		(net "RST_CPU0_KBRST_N")
	)
	(segment
		(start 180.394356 -132.243322)
		(end 180.89626 -131.741418)
		(width 0.11684)
		(layer "In11.Cu")
		(net "RST_CPU0_KBRST_N")
	)
	(segment
		(start 421.412416 -439.284872)
		(end 422.40708 -439.284872)
		(width 0.10668)
		(layer "F.Cu")
		(net "RST_BMC_FROM_SWB_N")
	)
	(segment
		(start 421.084502 -439.612786)
		(end 421.412416 -439.284872)
		(width 0.10668)
		(layer "F.Cu")
		(net "RST_BMC_FROM_SWB_N")
	)
	(segment
		(start 420.246302 -439.612786)
		(end 421.084502 -439.612786)
		(width 0.10668)
		(layer "F.Cu")
		(net "RST_BMC_FROM_SWB_N")
	)
	(segment
		(start 420.246302 -439.612786)
		(end 419.230302 -439.612786)
		(width 0.10668)
		(layer "F.Cu")
		(net "RST_BMC_FROM_SWB_N")
	)
	(segment
		(start 419.230302 -439.612786)
		(end 417.837366 -439.612786)
		(width 0.10668)
		(layer "F.Cu")
		(net "RST_BMC_FROM_SWB_N")
	)
	(via
		(at 417.837366 -439.612786)
		(size 0.508)
		(drill 0.254)
		(layers "F.Cu" "B.Cu")
		(net "RST_BMC_FROM_SWB_N")
	)
	(segment
		(start 413.269176 -424.689778)
		(end 414.490662 -425.911264)
		(width 0.10668)
		(layer "B.Cu")
		(net "RST_BMC_FROM_SWB_N")
	)
	(segment
		(start 414.490662 -425.911264)
		(end 414.490662 -436.266082)
		(width 0.10668)
		(layer "B.Cu")
		(net "RST_BMC_FROM_SWB_N")
	)
	(segment
		(start 414.490662 -436.266082)
		(end 417.837366 -439.612786)
		(width 0.10668)
		(layer "B.Cu")
		(net "RST_BMC_FROM_SWB_N")
	)
	(segment
		(start 412.75 -424.689778)
		(end 413.269176 -424.689778)
		(width 0.10668)
		(layer "B.Cu")
		(net "RST_BMC_FROM_SWB_N")
	)
	(segment
		(start 200.227184 -127.267716)
		(end 200.745598 -126.749302)
		(width 0.10668)
		(layer "F.Cu")
		(net "RST_BMC_FROM_SWB_ISO_N")
	)
	(segment
		(start 197.669658 -126.833376)
		(end 198.103998 -127.267716)
		(width 0.10668)
		(layer "F.Cu")
		(net "RST_BMC_FROM_SWB_ISO_N")
	)
	(segment
		(start 203.392786 -126.749302)
		(end 203.7715 -127.128016)
		(width 0.10668)
		(layer "F.Cu")
		(net "RST_BMC_FROM_SWB_ISO_N")
	)
	(segment
		(start 417.837366 -438.342786)
		(end 418.129466 -438.634886)
		(width 0.10668)
		(layer "F.Cu")
		(net "RST_BMC_FROM_SWB_ISO_N")
	)
	(segment
		(start 200.745598 -126.749302)
		(end 203.392786 -126.749302)
		(width 0.10668)
		(layer "F.Cu")
		(net "RST_BMC_FROM_SWB_ISO_N")
	)
	(segment
		(start 419.230302 -438.634886)
		(end 420.246302 -438.634886)
		(width 0.10668)
		(layer "F.Cu")
		(net "RST_BMC_FROM_SWB_ISO_N")
	)
	(segment
		(start 420.246302 -438.634886)
		(end 422.40708 -438.634886)
		(width 0.10668)
		(layer "F.Cu")
		(net "RST_BMC_FROM_SWB_ISO_N")
	)
	(segment
		(start 418.129466 -438.634886)
		(end 419.230302 -438.634886)
		(width 0.10668)
		(layer "F.Cu")
		(net "RST_BMC_FROM_SWB_ISO_N")
	)
	(segment
		(start 198.103998 -127.267716)
		(end 200.227184 -127.267716)
		(width 0.10668)
		(layer "F.Cu")
		(net "RST_BMC_FROM_SWB_ISO_N")
	)
	(via
		(at 417.837366 -438.342786)
		(size 0.508)
		(drill 0.254)
		(layers "F.Cu" "B.Cu")
		(net "RST_BMC_FROM_SWB_ISO_N")
	)
	(via
		(at 203.7715 -127.128016)
		(size 0.508)
		(drill 0.254)
		(layers "F.Cu" "B.Cu")
		(net "RST_BMC_FROM_SWB_ISO_N")
	)
	(segment
		(start 435.362858 -391.945368)
		(end 435.362858 -390.853422)
		(width 0.11684)
		(layer "In6.Cu")
		(net "RST_BMC_FROM_SWB_ISO_N")
	)
	(segment
		(start 432.34991 -433.34559)
		(end 434.232304 -431.463196)
		(width 0.11684)
		(layer "In6.Cu")
		(net "RST_BMC_FROM_SWB_ISO_N")
	)
	(segment
		(start 417.844986 -438.350406)
		(end 421.83431 -438.350406)
		(width 0.11684)
		(layer "In6.Cu")
		(net "RST_BMC_FROM_SWB_ISO_N")
	)
	(segment
		(start 452.08952 -342.131396)
		(end 463.764376 -330.45654)
		(width 0.11684)
		(layer "In6.Cu")
		(net "RST_BMC_FROM_SWB_ISO_N")
	)
	(segment
		(start 428.060104 -128.030478)
		(end 349.9993 -128.030478)
		(width 0.11684)
		(layer "In6.Cu")
		(net "RST_BMC_FROM_SWB_ISO_N")
	)
	(segment
		(start 430.784 -396.524226)
		(end 435.362858 -391.945368)
		(width 0.11684)
		(layer "In6.Cu")
		(net "RST_BMC_FROM_SWB_ISO_N")
	)
	(segment
		(start 216.63152 -126.271782)
		(end 208.43113 -126.271782)
		(width 0.11684)
		(layer "In6.Cu")
		(net "RST_BMC_FROM_SWB_ISO_N")
	)
	(segment
		(start 263.043924 -147.282916)
		(end 252.926342 -147.282916)
		(width 0.11684)
		(layer "In6.Cu")
		(net "RST_BMC_FROM_SWB_ISO_N")
	)
	(segment
		(start 216.934034 -125.969268)
		(end 216.63152 -126.271782)
		(width 0.11684)
		(layer "In6.Cu")
		(net "RST_BMC_FROM_SWB_ISO_N")
	)
	(segment
		(start 252.926342 -147.282916)
		(end 240.00079 -134.357364)
		(width 0.11684)
		(layer "In6.Cu")
		(net "RST_BMC_FROM_SWB_ISO_N")
	)
	(segment
		(start 345.671902 -123.70308)
		(end 321.465702 -123.70308)
		(width 0.11684)
		(layer "In6.Cu")
		(net "RST_BMC_FROM_SWB_ISO_N")
	)
	(segment
		(start 318.607948 -126.560834)
		(end 302.651414 -126.560834)
		(width 0.11684)
		(layer "In6.Cu")
		(net "RST_BMC_FROM_SWB_ISO_N")
	)
	(segment
		(start 208.43113 -126.271782)
		(end 207.574896 -127.128016)
		(width 0.11684)
		(layer "In6.Cu")
		(net "RST_BMC_FROM_SWB_ISO_N")
	)
	(segment
		(start 434.795676 -405.569674)
		(end 430.784 -401.557998)
		(width 0.11684)
		(layer "In6.Cu")
		(net "RST_BMC_FROM_SWB_ISO_N")
	)
	(segment
		(start 438.907936 -371.03304)
		(end 452.08952 -357.851456)
		(width 0.11684)
		(layer "In6.Cu")
		(net "RST_BMC_FROM_SWB_ISO_N")
	)
	(segment
		(start 227.175314 -134.357364)
		(end 218.787218 -125.969268)
		(width 0.11684)
		(layer "In6.Cu")
		(net "RST_BMC_FROM_SWB_ISO_N")
	)
	(segment
		(start 435.362858 -390.853422)
		(end 438.907936 -387.308344)
		(width 0.11684)
		(layer "In6.Cu")
		(net "RST_BMC_FROM_SWB_ISO_N")
	)
	(segment
		(start 218.787218 -125.969268)
		(end 216.934034 -125.969268)
		(width 0.11684)
		(layer "In6.Cu")
		(net "RST_BMC_FROM_SWB_ISO_N")
	)
	(segment
		(start 321.465702 -123.70308)
		(end 318.607948 -126.560834)
		(width 0.11684)
		(layer "In6.Cu")
		(net "RST_BMC_FROM_SWB_ISO_N")
	)
	(segment
		(start 450.87032 -150.840694)
		(end 428.060104 -128.030478)
		(width 0.11684)
		(layer "In6.Cu")
		(net "RST_BMC_FROM_SWB_ISO_N")
	)
	(segment
		(start 271.444466 -138.882374)
		(end 263.043924 -147.282916)
		(width 0.11684)
		(layer "In6.Cu")
		(net "RST_BMC_FROM_SWB_ISO_N")
	)
	(segment
		(start 434.232304 -416.517582)
		(end 434.787802 -415.962084)
		(width 0.11684)
		(layer "In6.Cu")
		(net "RST_BMC_FROM_SWB_ISO_N")
	)
	(segment
		(start 302.651414 -126.560834)
		(end 290.329874 -138.882374)
		(width 0.11684)
		(layer "In6.Cu")
		(net "RST_BMC_FROM_SWB_ISO_N")
	)
	(segment
		(start 452.08952 -357.851456)
		(end 452.08952 -342.131396)
		(width 0.11684)
		(layer "In6.Cu")
		(net "RST_BMC_FROM_SWB_ISO_N")
	)
	(segment
		(start 207.574896 -127.128016)
		(end 203.7715 -127.128016)
		(width 0.11684)
		(layer "In6.Cu")
		(net "RST_BMC_FROM_SWB_ISO_N")
	)
	(segment
		(start 426.839126 -433.34559)
		(end 432.34991 -433.34559)
		(width 0.11684)
		(layer "In6.Cu")
		(net "RST_BMC_FROM_SWB_ISO_N")
	)
	(segment
		(start 438.907936 -387.308344)
		(end 438.907936 -371.03304)
		(width 0.11684)
		(layer "In6.Cu")
		(net "RST_BMC_FROM_SWB_ISO_N")
	)
	(segment
		(start 434.795676 -405.955246)
		(end 434.795676 -405.569674)
		(width 0.11684)
		(layer "In6.Cu")
		(net "RST_BMC_FROM_SWB_ISO_N")
	)
	(segment
		(start 240.00079 -134.357364)
		(end 227.175314 -134.357364)
		(width 0.11684)
		(layer "In6.Cu")
		(net "RST_BMC_FROM_SWB_ISO_N")
	)
	(segment
		(start 349.9993 -128.030478)
		(end 345.671902 -123.70308)
		(width 0.11684)
		(layer "In6.Cu")
		(net "RST_BMC_FROM_SWB_ISO_N")
	)
	(segment
		(start 290.329874 -138.882374)
		(end 271.444466 -138.882374)
		(width 0.11684)
		(layer "In6.Cu")
		(net "RST_BMC_FROM_SWB_ISO_N")
	)
	(segment
		(start 421.83431 -438.350406)
		(end 426.839126 -433.34559)
		(width 0.11684)
		(layer "In6.Cu")
		(net "RST_BMC_FROM_SWB_ISO_N")
	)
	(segment
		(start 450.87032 -165.670484)
		(end 450.87032 -150.840694)
		(width 0.11684)
		(layer "In6.Cu")
		(net "RST_BMC_FROM_SWB_ISO_N")
	)
	(segment
		(start 463.764376 -178.56454)
		(end 450.87032 -165.670484)
		(width 0.11684)
		(layer "In6.Cu")
		(net "RST_BMC_FROM_SWB_ISO_N")
	)
	(segment
		(start 434.787802 -405.96312)
		(end 434.795676 -405.955246)
		(width 0.11684)
		(layer "In6.Cu")
		(net "RST_BMC_FROM_SWB_ISO_N")
	)
	(segment
		(start 434.787802 -415.962084)
		(end 434.787802 -405.96312)
		(width 0.11684)
		(layer "In6.Cu")
		(net "RST_BMC_FROM_SWB_ISO_N")
	)
	(segment
		(start 434.232304 -431.463196)
		(end 434.232304 -416.517582)
		(width 0.11684)
		(layer "In6.Cu")
		(net "RST_BMC_FROM_SWB_ISO_N")
	)
	(segment
		(start 417.837366 -438.342786)
		(end 417.844986 -438.350406)
		(width 0.11684)
		(layer "In6.Cu")
		(net "RST_BMC_FROM_SWB_ISO_N")
	)
	(segment
		(start 430.784 -401.557998)
		(end 430.784 -396.524226)
		(width 0.11684)
		(layer "In6.Cu")
		(net "RST_BMC_FROM_SWB_ISO_N")
	)
	(segment
		(start 463.764376 -330.45654)
		(end 463.764376 -178.56454)
		(width 0.11684)
		(layer "In6.Cu")
		(net "RST_BMC_FROM_SWB_ISO_N")
	)
	(segment
		(start 424.307 -439.284872)
		(end 424.307 -439.934858)
		(width 0.10668)
		(layer "F.Cu")
		(net "RST_BMC_FROM_SWB")
	)
	(segment
		(start 425.54144 -438.614058)
		(end 425.54144 -439.934858)
		(width 0.10668)
		(layer "F.Cu")
		(net "RST_BMC_FROM_SWB")
	)
	(segment
		(start 424.307 -439.934858)
		(end 425.54144 -439.934858)
		(width 0.10668)
		(layer "F.Cu")
		(net "RST_BMC_FROM_SWB")
	)
	(via
		(at 425.54144 -439.934858)
		(size 0.762)
		(drill 0.381)
		(layers "F.Cu" "B.Cu")
		(net "RST_BMC_FROM_SWB")
	)
	(segment
		(start 139.946888 -13.599922)
		(end 139.946888 -10.897108)
		(width 0.10668)
		(layer "F.Cu")
		(net "SCM_ROT_CPU_RST_N")
	)
	(via
		(at 139.946888 -10.897108)
		(size 0.508)
		(drill 0.254)
		(layers "F.Cu" "B.Cu")
		(net "SCM_ROT_CPU_RST_N")
	)
	(segment
		(start 139.679426 -10.629646)
		(end 139.946888 -10.897108)
		(width 0.10668)
		(layer "B.Cu")
		(net "SCM_ROT_CPU_RST_N")
	)
	(segment
		(start 139.679426 -9.458198)
		(end 139.679426 -10.629646)
		(width 0.10668)
		(layer "B.Cu")
		(net "SCM_ROT_CPU_RST_N")
	)
	(segment
		(start 256.192274 -135.255254)
		(end 257.379724 -135.255254)
		(width 0.10668)
		(layer "F.Cu")
		(net "ROM_SD_LS_OE")
	)
	(via
		(at 257.379724 -135.255254)
		(size 0.508)
		(drill 0.254)
		(layers "F.Cu" "B.Cu")
		(net "ROM_SD_LS_OE")
	)
	(via
		(at 194.183 -138.648948)
		(size 0.508)
		(drill 0.254)
		(layers "F.Cu" "B.Cu")
		(net "ROM_SD_LS_OE")
	)
	(segment
		(start 195.199 -138.032998)
		(end 195.199 -138.3792)
		(width 0.10668)
		(layer "B.Cu")
		(net "ROM_SD_LS_OE")
	)
	(segment
		(start 194.929252 -138.648948)
		(end 194.183 -138.648948)
		(width 0.10668)
		(layer "B.Cu")
		(net "ROM_SD_LS_OE")
	)
	(segment
		(start 195.199 -138.3792)
		(end 194.929252 -138.648948)
		(width 0.10668)
		(layer "B.Cu")
		(net "ROM_SD_LS_OE")
	)
	(segment
		(start 215.518492 -137.46607)
		(end 216.999566 -135.984996)
		(width 0.11684)
		(layer "In2.Cu")
		(net "ROM_SD_LS_OE")
	)
	(segment
		(start 203.240132 -139.333986)
		(end 204.047598 -138.52652)
		(width 0.11684)
		(layer "In2.Cu")
		(net "ROM_SD_LS_OE")
	)
	(segment
		(start 206.08671 -138.52652)
		(end 207.14716 -137.46607)
		(width 0.11684)
		(layer "In2.Cu")
		(net "ROM_SD_LS_OE")
	)
	(segment
		(start 204.047598 -138.52652)
		(end 206.08671 -138.52652)
		(width 0.11684)
		(layer "In2.Cu")
		(net "ROM_SD_LS_OE")
	)
	(segment
		(start 216.999566 -135.984996)
		(end 256.916936 -135.984996)
		(width 0.11684)
		(layer "In2.Cu")
		(net "ROM_SD_LS_OE")
	)
	(segment
		(start 194.528694 -139.333986)
		(end 203.240132 -139.333986)
		(width 0.11684)
		(layer "In2.Cu")
		(net "ROM_SD_LS_OE")
	)
	(segment
		(start 256.916936 -135.984996)
		(end 257.379724 -135.522208)
		(width 0.11684)
		(layer "In2.Cu")
		(net "ROM_SD_LS_OE")
	)
	(segment
		(start 194.183 -138.988292)
		(end 194.528694 -139.333986)
		(width 0.11684)
		(layer "In2.Cu")
		(net "ROM_SD_LS_OE")
	)
	(segment
		(start 194.183 -138.648948)
		(end 194.183 -138.988292)
		(width 0.11684)
		(layer "In2.Cu")
		(net "ROM_SD_LS_OE")
	)
	(segment
		(start 257.379724 -135.522208)
		(end 257.379724 -135.255254)
		(width 0.11684)
		(layer "In2.Cu")
		(net "ROM_SD_LS_OE")
	)
	(segment
		(start 207.14716 -137.46607)
		(end 215.518492 -137.46607)
		(width 0.11684)
		(layer "In2.Cu")
		(net "ROM_SD_LS_OE")
	)
	(segment
		(start 192.5066 -131.7879)
		(end 193.167 -131.1275)
		(width 0.10668)
		(layer "F.Cu")
		(net "ROM_LS_EN")
	)
	(segment
		(start 260.99008 -138.048746)
		(end 260.99008 -137.666222)
		(width 0.10668)
		(layer "F.Cu")
		(net "ROM_LS_EN")
	)
	(segment
		(start 192.70726 -135.35533)
		(end 192.70726 -132.779008)
		(width 0.10668)
		(layer "F.Cu")
		(net "ROM_LS_EN")
	)
	(segment
		(start 192.70726 -132.779008)
		(end 192.5066 -132.578348)
		(width 0.10668)
		(layer "F.Cu")
		(net "ROM_LS_EN")
	)
	(segment
		(start 192.151 -137.232898)
		(end 192.49644 -136.887458)
		(width 0.10668)
		(layer "F.Cu")
		(net "ROM_LS_EN")
	)
	(segment
		(start 192.49644 -136.887458)
		(end 192.49644 -136.616186)
		(width 0.10668)
		(layer "F.Cu")
		(net "ROM_LS_EN")
	)
	(segment
		(start 193.167 -131.1275)
		(end 193.167 -129.777998)
		(width 0.10668)
		(layer "F.Cu")
		(net "ROM_LS_EN")
	)
	(segment
		(start 192.49644 -135.56615)
		(end 192.70726 -135.35533)
		(width 0.10668)
		(layer "F.Cu")
		(net "ROM_LS_EN")
	)
	(segment
		(start 260.99008 -137.666222)
		(end 260.510274 -137.186416)
		(width 0.10668)
		(layer "F.Cu")
		(net "ROM_LS_EN")
	)
	(segment
		(start 192.5066 -132.578348)
		(end 192.5066 -131.7879)
		(width 0.10668)
		(layer "F.Cu")
		(net "ROM_LS_EN")
	)
	(segment
		(start 192.49644 -136.616186)
		(end 192.49644 -135.56615)
		(width 0.10668)
		(layer "F.Cu")
		(net "ROM_LS_EN")
	)
	(via
		(at 235.38942 -137.387838)
		(size 0.508)
		(drill 0.254)
		(layers "F.Cu" "B.Cu")
		(net "ROM_LS_EN")
	)
	(via
		(at 192.49644 -136.616186)
		(size 0.508)
		(drill 0.254)
		(layers "F.Cu" "B.Cu")
		(net "ROM_LS_EN")
	)
	(via
		(at 260.510274 -137.186416)
		(size 0.508)
		(drill 0.254)
		(layers "F.Cu" "B.Cu")
		(net "ROM_LS_EN")
	)
	(segment
		(start 260.348222 -137.348468)
		(end 260.510274 -137.186416)
		(width 0.11684)
		(layer "In2.Cu")
		(net "ROM_LS_EN")
	)
	(segment
		(start 253.990602 -138.275822)
		(end 255.493012 -138.275822)
		(width 0.11684)
		(layer "In2.Cu")
		(net "ROM_LS_EN")
	)
	(segment
		(start 258.157726 -136.91743)
		(end 259.150358 -136.91743)
		(width 0.11684)
		(layer "In2.Cu")
		(net "ROM_LS_EN")
	)
	(segment
		(start 257.522726 -137.55243)
		(end 258.157726 -136.91743)
		(width 0.11684)
		(layer "In2.Cu")
		(net "ROM_LS_EN")
	)
	(segment
		(start 253.102618 -137.387838)
		(end 253.990602 -138.275822)
		(width 0.11684)
		(layer "In2.Cu")
		(net "ROM_LS_EN")
	)
	(segment
		(start 259.581396 -137.348468)
		(end 260.348222 -137.348468)
		(width 0.11684)
		(layer "In2.Cu")
		(net "ROM_LS_EN")
	)
	(segment
		(start 256.216404 -137.55243)
		(end 257.522726 -137.55243)
		(width 0.11684)
		(layer "In2.Cu")
		(net "ROM_LS_EN")
	)
	(segment
		(start 235.38942 -137.387838)
		(end 253.102618 -137.387838)
		(width 0.11684)
		(layer "In2.Cu")
		(net "ROM_LS_EN")
	)
	(segment
		(start 255.493012 -138.275822)
		(end 256.216404 -137.55243)
		(width 0.11684)
		(layer "In2.Cu")
		(net "ROM_LS_EN")
	)
	(segment
		(start 259.150358 -136.91743)
		(end 259.581396 -137.348468)
		(width 0.11684)
		(layer "In2.Cu")
		(net "ROM_LS_EN")
	)
	(segment
		(start 206.2861 -136.1059)
		(end 212.14334 -136.1059)
		(width 0.11684)
		(layer "In6.Cu")
		(net "ROM_LS_EN")
	)
	(segment
		(start 192.49644 -137.027666)
		(end 192.882774 -137.414)
		(width 0.11684)
		(layer "In6.Cu")
		(net "ROM_LS_EN")
	)
	(segment
		(start 213.425278 -137.387838)
		(end 235.38942 -137.387838)
		(width 0.11684)
		(layer "In6.Cu")
		(net "ROM_LS_EN")
	)
	(segment
		(start 192.882774 -137.414)
		(end 197.358 -137.414)
		(width 0.11684)
		(layer "In6.Cu")
		(net "ROM_LS_EN")
	)
	(segment
		(start 197.993 -136.779)
		(end 205.613 -136.779)
		(width 0.11684)
		(layer "In6.Cu")
		(net "ROM_LS_EN")
	)
	(segment
		(start 205.613 -136.779)
		(end 206.2861 -136.1059)
		(width 0.11684)
		(layer "In6.Cu")
		(net "ROM_LS_EN")
	)
	(segment
		(start 197.358 -137.414)
		(end 197.993 -136.779)
		(width 0.11684)
		(layer "In6.Cu")
		(net "ROM_LS_EN")
	)
	(segment
		(start 212.14334 -136.1059)
		(end 213.425278 -137.387838)
		(width 0.11684)
		(layer "In6.Cu")
		(net "ROM_LS_EN")
	)
	(segment
		(start 192.49644 -136.616186)
		(end 192.49644 -137.027666)
		(width 0.11684)
		(layer "In6.Cu")
		(net "ROM_LS_EN")
	)
	(segment
		(start 164.3634 -18.341594)
		(end 164.3634 -20.753324)
		(width 0.10668)
		(layer "F.Cu")
		(net "RMII_OCP_BMC_RXD_1")
	)
	(segment
		(start 164.467032 -16.549878)
		(end 164.467032 -18.237962)
		(width 0.10668)
		(layer "F.Cu")
		(net "RMII_OCP_BMC_RXD_1")
	)
	(segment
		(start 199.635618 -79.221838)
		(end 199.635618 -78.42377)
		(width 0.10668)
		(layer "F.Cu")
		(net "RMII_OCP_BMC_RXD_1")
	)
	(segment
		(start 218.458034 -79.041752)
		(end 217.595704 -79.904082)
		(width 0.10668)
		(layer "F.Cu")
		(net "RMII_OCP_BMC_RXD_1")
	)
	(segment
		(start 218.458034 -77.4319)
		(end 218.458034 -79.041752)
		(width 0.10668)
		(layer "F.Cu")
		(net "RMII_OCP_BMC_RXD_1")
	)
	(segment
		(start 197.896734 -78.42377)
		(end 199.635618 -78.42377)
		(width 0.10668)
		(layer "F.Cu")
		(net "RMII_OCP_BMC_RXD_1")
	)
	(segment
		(start 164.3634 -20.753324)
		(end 163.627308 -21.489416)
		(width 0.10668)
		(layer "F.Cu")
		(net "RMII_OCP_BMC_RXD_1")
	)
	(segment
		(start 217.595704 -79.904082)
		(end 200.317862 -79.904082)
		(width 0.10668)
		(layer "F.Cu")
		(net "RMII_OCP_BMC_RXD_1")
	)
	(segment
		(start 197.108318 -78.42377)
		(end 197.896734 -78.42377)
		(width 0.10668)
		(layer "F.Cu")
		(net "RMII_OCP_BMC_RXD_1")
	)
	(segment
		(start 200.317862 -79.904082)
		(end 199.635618 -79.221838)
		(width 0.10668)
		(layer "F.Cu")
		(net "RMII_OCP_BMC_RXD_1")
	)
	(segment
		(start 164.467032 -18.237962)
		(end 164.3634 -18.341594)
		(width 0.10668)
		(layer "F.Cu")
		(net "RMII_OCP_BMC_RXD_1")
	)
	(via
		(at 218.458034 -77.4319)
		(size 0.508)
		(drill 0.254)
		(layers "F.Cu" "B.Cu")
		(net "RMII_OCP_BMC_RXD_1")
	)
	(via
		(at 163.627308 -21.489416)
		(size 0.508)
		(drill 0.254)
		(layers "F.Cu" "B.Cu")
		(net "RMII_OCP_BMC_RXD_1")
	)
	(via
		(at 197.896734 -78.42377)
		(size 0.508)
		(drill 0.254)
		(layers "F.Cu" "B.Cu")
		(net "RMII_OCP_BMC_RXD_1")
	)
	(segment
		(start 217.441526 -78.448408)
		(end 218.458034 -77.4319)
		(width 0.10668)
		(layer "B.Cu")
		(net "RMII_OCP_BMC_RXD_1")
	)
	(segment
		(start 216.65311 -78.448408)
		(end 217.441526 -78.448408)
		(width 0.10668)
		(layer "B.Cu")
		(net "RMII_OCP_BMC_RXD_1")
	)
	(segment
		(start 173.75251 -32.5247)
		(end 176.423066 -35.195256)
		(width 0.11684)
		(layer "In4.Cu")
		(net "RMII_OCP_BMC_RXD_1")
	)
	(segment
		(start 188.37656 -44.776644)
		(end 188.37656 -74.23658)
		(width 0.11684)
		(layer "In4.Cu")
		(net "RMII_OCP_BMC_RXD_1")
	)
	(segment
		(start 176.423066 -35.195256)
		(end 180.472588 -36.872672)
		(width 0.11684)
		(layer "In4.Cu")
		(net "RMII_OCP_BMC_RXD_1")
	)
	(segment
		(start 163.627308 -21.489416)
		(end 163.696142 -21.55825)
		(width 0.11684)
		(layer "In4.Cu")
		(net "RMII_OCP_BMC_RXD_1")
	)
	(segment
		(start 163.696142 -21.55825)
		(end 163.696142 -28.161742)
		(width 0.11684)
		(layer "In4.Cu")
		(net "RMII_OCP_BMC_RXD_1")
	)
	(segment
		(start 180.472588 -36.872672)
		(end 188.37656 -44.776644)
		(width 0.11684)
		(layer "In4.Cu")
		(net "RMII_OCP_BMC_RXD_1")
	)
	(segment
		(start 192.56375 -78.42377)
		(end 197.896734 -78.42377)
		(width 0.11684)
		(layer "In4.Cu")
		(net "RMII_OCP_BMC_RXD_1")
	)
	(segment
		(start 163.696142 -28.161742)
		(end 168.0591 -32.5247)
		(width 0.11684)
		(layer "In4.Cu")
		(net "RMII_OCP_BMC_RXD_1")
	)
	(segment
		(start 188.37656 -74.23658)
		(end 192.56375 -78.42377)
		(width 0.11684)
		(layer "In4.Cu")
		(net "RMII_OCP_BMC_RXD_1")
	)
	(segment
		(start 168.0591 -32.5247)
		(end 173.75251 -32.5247)
		(width 0.11684)
		(layer "In4.Cu")
		(net "RMII_OCP_BMC_RXD_1")
	)
	(segment
		(start 199.657208 -74.947272)
		(end 200.40346 -74.20102)
		(width 0.10668)
		(layer "F.Cu")
		(net "RMII_OCP_BMC_RXD_0")
	)
	(segment
		(start 164.855144 -18.558002)
		(end 164.855144 -21.005038)
		(width 0.10668)
		(layer "F.Cu")
		(net "RMII_OCP_BMC_RXD_0")
	)
	(segment
		(start 165.06698 -18.346166)
		(end 164.855144 -18.558002)
		(width 0.10668)
		(layer "F.Cu")
		(net "RMII_OCP_BMC_RXD_0")
	)
	(segment
		(start 202.531218 -74.20102)
		(end 204.784198 -76.454)
		(width 0.10668)
		(layer "F.Cu")
		(net "RMII_OCP_BMC_RXD_0")
	)
	(segment
		(start 164.855144 -21.005038)
		(end 164.576252 -21.28393)
		(width 0.10668)
		(layer "F.Cu")
		(net "RMII_OCP_BMC_RXD_0")
	)
	(segment
		(start 216.959942 -76.454)
		(end 217.292174 -76.121768)
		(width 0.10668)
		(layer "F.Cu")
		(net "RMII_OCP_BMC_RXD_0")
	)
	(segment
		(start 197.129908 -77.06614)
		(end 197.896734 -77.06614)
		(width 0.10668)
		(layer "F.Cu")
		(net "RMII_OCP_BMC_RXD_0")
	)
	(segment
		(start 165.06698 -16.549878)
		(end 165.06698 -18.346166)
		(width 0.10668)
		(layer "F.Cu")
		(net "RMII_OCP_BMC_RXD_0")
	)
	(segment
		(start 200.40346 -74.20102)
		(end 202.531218 -74.20102)
		(width 0.10668)
		(layer "F.Cu")
		(net "RMII_OCP_BMC_RXD_0")
	)
	(segment
		(start 197.896734 -77.06614)
		(end 199.657208 -77.06614)
		(width 0.10668)
		(layer "F.Cu")
		(net "RMII_OCP_BMC_RXD_0")
	)
	(segment
		(start 199.657208 -77.06614)
		(end 199.657208 -74.947272)
		(width 0.10668)
		(layer "F.Cu")
		(net "RMII_OCP_BMC_RXD_0")
	)
	(segment
		(start 204.784198 -76.454)
		(end 216.959942 -76.454)
		(width 0.10668)
		(layer "F.Cu")
		(net "RMII_OCP_BMC_RXD_0")
	)
	(via
		(at 164.576252 -21.28393)
		(size 0.508)
		(drill 0.254)
		(layers "F.Cu" "B.Cu")
		(net "RMII_OCP_BMC_RXD_0")
	)
	(via
		(at 197.896734 -77.06614)
		(size 0.508)
		(drill 0.254)
		(layers "F.Cu" "B.Cu")
		(net "RMII_OCP_BMC_RXD_0")
	)
	(via
		(at 217.292174 -76.121768)
		(size 0.508)
		(drill 0.254)
		(layers "F.Cu" "B.Cu")
		(net "RMII_OCP_BMC_RXD_0")
	)
	(segment
		(start 216.822274 -76.591668)
		(end 217.292174 -76.121768)
		(width 0.10668)
		(layer "B.Cu")
		(net "RMII_OCP_BMC_RXD_0")
	)
	(segment
		(start 216.612724 -76.591668)
		(end 216.822274 -76.591668)
		(width 0.10668)
		(layer "B.Cu")
		(net "RMII_OCP_BMC_RXD_0")
	)
	(segment
		(start 196.986652 -76.156058)
		(end 194.965574 -76.156058)
		(width 0.11684)
		(layer "In4.Cu")
		(net "RMII_OCP_BMC_RXD_0")
	)
	(segment
		(start 169.665396 -32.07766)
		(end 164.307012 -26.719276)
		(width 0.11684)
		(layer "In4.Cu")
		(net "RMII_OCP_BMC_RXD_0")
	)
	(segment
		(start 188.89472 -74.08672)
		(end 188.89472 -44.698412)
		(width 0.11684)
		(layer "In4.Cu")
		(net "RMII_OCP_BMC_RXD_0")
	)
	(segment
		(start 164.307012 -21.55317)
		(end 164.576252 -21.28393)
		(width 0.11684)
		(layer "In4.Cu")
		(net "RMII_OCP_BMC_RXD_0")
	)
	(segment
		(start 194.965574 -76.156058)
		(end 194.596766 -76.524866)
		(width 0.11684)
		(layer "In4.Cu")
		(net "RMII_OCP_BMC_RXD_0")
	)
	(segment
		(start 188.89472 -44.698412)
		(end 180.711348 -36.51504)
		(width 0.11684)
		(layer "In4.Cu")
		(net "RMII_OCP_BMC_RXD_0")
	)
	(segment
		(start 197.896734 -77.06614)
		(end 196.986652 -76.156058)
		(width 0.11684)
		(layer "In4.Cu")
		(net "RMII_OCP_BMC_RXD_0")
	)
	(segment
		(start 194.596766 -76.524866)
		(end 191.332866 -76.524866)
		(width 0.11684)
		(layer "In4.Cu")
		(net "RMII_OCP_BMC_RXD_0")
	)
	(segment
		(start 174.886366 -32.07766)
		(end 169.665396 -32.07766)
		(width 0.11684)
		(layer "In4.Cu")
		(net "RMII_OCP_BMC_RXD_0")
	)
	(segment
		(start 191.332866 -76.524866)
		(end 188.89472 -74.08672)
		(width 0.11684)
		(layer "In4.Cu")
		(net "RMII_OCP_BMC_RXD_0")
	)
	(segment
		(start 164.307012 -26.719276)
		(end 164.307012 -21.55317)
		(width 0.11684)
		(layer "In4.Cu")
		(net "RMII_OCP_BMC_RXD_0")
	)
	(segment
		(start 178.34229 -35.533584)
		(end 174.886366 -32.07766)
		(width 0.11684)
		(layer "In4.Cu")
		(net "RMII_OCP_BMC_RXD_0")
	)
	(segment
		(start 180.711348 -36.51504)
		(end 178.34229 -35.533584)
		(width 0.11684)
		(layer "In4.Cu")
		(net "RMII_OCP_BMC_RXD_0")
	)
	(segment
		(start 168.003982 -17.654778)
		(end 168.043352 -17.694148)
		(width 0.10668)
		(layer "F.Cu")
		(net "RMII_OCP_BMC_CRSDV")
	)
	(segment
		(start 168.003982 -16.61287)
		(end 168.003982 -17.654778)
		(width 0.10668)
		(layer "F.Cu")
		(net "RMII_OCP_BMC_CRSDV")
	)
	(segment
		(start 168.066974 -16.549878)
		(end 168.003982 -16.61287)
		(width 0.10668)
		(layer "F.Cu")
		(net "RMII_OCP_BMC_CRSDV")
	)
	(segment
		(start 197.476872 -75.26401)
		(end 197.476872 -76.016866)
		(width 0.10668)
		(layer "F.Cu")
		(net "RMII_OCP_BMC_CRSDV")
	)
	(segment
		(start 197.476872 -76.016866)
		(end 194.771772 -76.016866)
		(width 0.10668)
		(layer "F.Cu")
		(net "RMII_OCP_BMC_CRSDV")
	)
	(via
		(at 197.476872 -75.26401)
		(size 0.508)
		(drill 0.254)
		(layers "F.Cu" "B.Cu")
		(net "RMII_OCP_BMC_CRSDV")
	)
	(via
		(at 168.043352 -17.694148)
		(size 0.508)
		(drill 0.254)
		(layers "F.Cu" "B.Cu")
		(net "RMII_OCP_BMC_CRSDV")
	)
	(via
		(at 202.974702 -75.624182)
		(size 0.508)
		(drill 0.254)
		(layers "F.Cu" "B.Cu")
		(net "RMII_OCP_BMC_CRSDV")
	)
	(segment
		(start 202.67295 -75.472544)
		(end 202.824588 -75.624182)
		(width 0.10668)
		(layer "B.Cu")
		(net "RMII_OCP_BMC_CRSDV")
	)
	(segment
		(start 202.67295 -75.053952)
		(end 202.67295 -75.472544)
		(width 0.10668)
		(layer "B.Cu")
		(net "RMII_OCP_BMC_CRSDV")
	)
	(segment
		(start 202.824588 -75.624182)
		(end 202.974702 -75.624182)
		(width 0.10668)
		(layer "B.Cu")
		(net "RMII_OCP_BMC_CRSDV")
	)
	(segment
		(start 200.230232 -77.46746)
		(end 200.623932 -77.46746)
		(width 0.11684)
		(layer "In2.Cu")
		(net "RMII_OCP_BMC_CRSDV")
	)
	(segment
		(start 199.486012 -72.752204)
		(end 199.602852 -72.635364)
		(width 0.11684)
		(layer "In2.Cu")
		(net "RMII_OCP_BMC_CRSDV")
	)
	(segment
		(start 197.476872 -75.26401)
		(end 197.476872 -73.223882)
		(width 0.11684)
		(layer "In2.Cu")
		(net "RMII_OCP_BMC_CRSDV")
	)
	(segment
		(start 199.486012 -77.35062)
		(end 199.486012 -72.752204)
		(width 0.11684)
		(layer "In2.Cu")
		(net "RMII_OCP_BMC_CRSDV")
	)
	(segment
		(start 200.113392 -72.752204)
		(end 200.113392 -77.35062)
		(width 0.11684)
		(layer "In2.Cu")
		(net "RMII_OCP_BMC_CRSDV")
	)
	(segment
		(start 198.975472 -77.46746)
		(end 199.369172 -77.46746)
		(width 0.11684)
		(layer "In2.Cu")
		(net "RMII_OCP_BMC_CRSDV")
	)
	(segment
		(start 202.974702 -73.997058)
		(end 202.974702 -75.624182)
		(width 0.11684)
		(layer "In2.Cu")
		(net "RMII_OCP_BMC_CRSDV")
	)
	(segment
		(start 199.369172 -77.46746)
		(end 199.486012 -77.35062)
		(width 0.11684)
		(layer "In2.Cu")
		(net "RMII_OCP_BMC_CRSDV")
	)
	(segment
		(start 199.602852 -72.635364)
		(end 199.996552 -72.635364)
		(width 0.11684)
		(layer "In2.Cu")
		(net "RMII_OCP_BMC_CRSDV")
	)
	(segment
		(start 197.476872 -73.223882)
		(end 198.06539 -72.635364)
		(width 0.11684)
		(layer "In2.Cu")
		(net "RMII_OCP_BMC_CRSDV")
	)
	(segment
		(start 198.06539 -72.635364)
		(end 198.741792 -72.635364)
		(width 0.11684)
		(layer "In2.Cu")
		(net "RMII_OCP_BMC_CRSDV")
	)
	(segment
		(start 200.857612 -72.635364)
		(end 201.613008 -72.635364)
		(width 0.11684)
		(layer "In2.Cu")
		(net "RMII_OCP_BMC_CRSDV")
	)
	(segment
		(start 198.741792 -72.635364)
		(end 198.858632 -72.752204)
		(width 0.11684)
		(layer "In2.Cu")
		(net "RMII_OCP_BMC_CRSDV")
	)
	(segment
		(start 201.613008 -72.635364)
		(end 202.974702 -73.997058)
		(width 0.11684)
		(layer "In2.Cu")
		(net "RMII_OCP_BMC_CRSDV")
	)
	(segment
		(start 200.740772 -77.35062)
		(end 200.740772 -72.752204)
		(width 0.11684)
		(layer "In2.Cu")
		(net "RMII_OCP_BMC_CRSDV")
	)
	(segment
		(start 199.996552 -72.635364)
		(end 200.113392 -72.752204)
		(width 0.11684)
		(layer "In2.Cu")
		(net "RMII_OCP_BMC_CRSDV")
	)
	(segment
		(start 200.623932 -77.46746)
		(end 200.740772 -77.35062)
		(width 0.11684)
		(layer "In2.Cu")
		(net "RMII_OCP_BMC_CRSDV")
	)
	(segment
		(start 198.858632 -77.35062)
		(end 198.975472 -77.46746)
		(width 0.11684)
		(layer "In2.Cu")
		(net "RMII_OCP_BMC_CRSDV")
	)
	(segment
		(start 200.740772 -72.752204)
		(end 200.857612 -72.635364)
		(width 0.11684)
		(layer "In2.Cu")
		(net "RMII_OCP_BMC_CRSDV")
	)
	(segment
		(start 198.858632 -72.752204)
		(end 198.858632 -77.35062)
		(width 0.11684)
		(layer "In2.Cu")
		(net "RMII_OCP_BMC_CRSDV")
	)
	(segment
		(start 200.113392 -77.35062)
		(end 200.230232 -77.46746)
		(width 0.11684)
		(layer "In2.Cu")
		(net "RMII_OCP_BMC_CRSDV")
	)
	(segment
		(start 166.57574 -22.78761)
		(end 166.57574 -23.542498)
		(width 0.11684)
		(layer "In4.Cu")
		(net "RMII_OCP_BMC_CRSDV")
	)
	(segment
		(start 189.92596 -48.568356)
		(end 189.92596 -69.675248)
		(width 0.11684)
		(layer "In4.Cu")
		(net "RMII_OCP_BMC_CRSDV")
	)
	(segment
		(start 180.537866 -35.745166)
		(end 189.333124 -44.540424)
		(width 0.11684)
		(layer "In4.Cu")
		(net "RMII_OCP_BMC_CRSDV")
	)
	(segment
		(start 178.343306 -34.8361)
		(end 180.537866 -35.745166)
		(width 0.11684)
		(layer "In4.Cu")
		(net "RMII_OCP_BMC_CRSDV")
	)
	(segment
		(start 189.385956 -70.215252)
		(end 189.385956 -73.019412)
		(width 0.11684)
		(layer "In4.Cu")
		(net "RMII_OCP_BMC_CRSDV")
	)
	(segment
		(start 165.838886 -19.31924)
		(end 165.838886 -22.050756)
		(width 0.11684)
		(layer "In4.Cu")
		(net "RMII_OCP_BMC_CRSDV")
	)
	(segment
		(start 166.753032 -18.405094)
		(end 165.838886 -19.31924)
		(width 0.11684)
		(layer "In4.Cu")
		(net "RMII_OCP_BMC_CRSDV")
	)
	(segment
		(start 168.082468 -25.049226)
		(end 168.082468 -26.938986)
		(width 0.11684)
		(layer "In4.Cu")
		(net "RMII_OCP_BMC_CRSDV")
	)
	(segment
		(start 189.884304 -73.51776)
		(end 195.730622 -73.51776)
		(width 0.11684)
		(layer "In4.Cu")
		(net "RMII_OCP_BMC_CRSDV")
	)
	(segment
		(start 172.004482 -30.861)
		(end 174.368206 -30.861)
		(width 0.11684)
		(layer "In4.Cu")
		(net "RMII_OCP_BMC_CRSDV")
	)
	(segment
		(start 189.385956 -73.019412)
		(end 189.884304 -73.51776)
		(width 0.11684)
		(layer "In4.Cu")
		(net "RMII_OCP_BMC_CRSDV")
	)
	(segment
		(start 166.57574 -23.542498)
		(end 168.082468 -25.049226)
		(width 0.11684)
		(layer "In4.Cu")
		(net "RMII_OCP_BMC_CRSDV")
	)
	(segment
		(start 167.332406 -18.405094)
		(end 166.753032 -18.405094)
		(width 0.11684)
		(layer "In4.Cu")
		(net "RMII_OCP_BMC_CRSDV")
	)
	(segment
		(start 189.333124 -47.97552)
		(end 189.92596 -48.568356)
		(width 0.11684)
		(layer "In4.Cu")
		(net "RMII_OCP_BMC_CRSDV")
	)
	(segment
		(start 189.333124 -44.540424)
		(end 189.333124 -47.97552)
		(width 0.11684)
		(layer "In4.Cu")
		(net "RMII_OCP_BMC_CRSDV")
	)
	(segment
		(start 174.368206 -30.861)
		(end 178.343306 -34.8361)
		(width 0.11684)
		(layer "In4.Cu")
		(net "RMII_OCP_BMC_CRSDV")
	)
	(segment
		(start 168.082468 -26.938986)
		(end 172.004482 -30.861)
		(width 0.11684)
		(layer "In4.Cu")
		(net "RMII_OCP_BMC_CRSDV")
	)
	(segment
		(start 168.043352 -17.694148)
		(end 167.332406 -18.405094)
		(width 0.11684)
		(layer "In4.Cu")
		(net "RMII_OCP_BMC_CRSDV")
	)
	(segment
		(start 195.730622 -73.51776)
		(end 197.476872 -75.26401)
		(width 0.11684)
		(layer "In4.Cu")
		(net "RMII_OCP_BMC_CRSDV")
	)
	(segment
		(start 165.838886 -22.050756)
		(end 166.57574 -22.78761)
		(width 0.11684)
		(layer "In4.Cu")
		(net "RMII_OCP_BMC_CRSDV")
	)
	(segment
		(start 189.92596 -69.675248)
		(end 189.385956 -70.215252)
		(width 0.11684)
		(layer "In4.Cu")
		(net "RMII_OCP_BMC_CRSDV")
	)
	(segment
		(start 167.467026 -18.386044)
		(end 166.732458 -19.120612)
		(width 0.10668)
		(layer "F.Cu")
		(net "RMII_BMC_OCP_TX_EN")
	)
	(segment
		(start 166.732458 -19.120612)
		(end 166.732458 -19.159474)
		(width 0.10668)
		(layer "F.Cu")
		(net "RMII_BMC_OCP_TX_EN")
	)
	(segment
		(start 167.467026 -16.549878)
		(end 167.467026 -18.386044)
		(width 0.10668)
		(layer "F.Cu")
		(net "RMII_BMC_OCP_TX_EN")
	)
	(via
		(at 166.732458 -19.159474)
		(size 0.508)
		(drill 0.254)
		(layers "F.Cu" "B.Cu")
		(net "RMII_BMC_OCP_TX_EN")
	)
	(via
		(at 191.708786 -71.375778)
		(size 0.508)
		(drill 0.254)
		(layers "F.Cu" "B.Cu")
		(net "RMII_BMC_OCP_TX_EN")
	)
	(via
		(at 204.038708 -67.525392)
		(size 0.762)
		(drill 0.254)
		(layers "F.Cu" "B.Cu")
		(net "RMII_BMC_OCP_TX_EN")
	)
	(segment
		(start 191.592962 -69.4436)
		(end 191.592708 -69.443346)
		(width 0.10668)
		(layer "B.Cu")
		(net "RMII_BMC_OCP_TX_EN")
	)
	(segment
		(start 204.038708 -68.229734)
		(end 204.038708 -67.525392)
		(width 0.10668)
		(layer "B.Cu")
		(net "RMII_BMC_OCP_TX_EN")
	)
	(segment
		(start 191.592962 -70.459346)
		(end 191.592962 -71.259954)
		(width 0.10668)
		(layer "B.Cu")
		(net "RMII_BMC_OCP_TX_EN")
	)
	(segment
		(start 191.592962 -70.459346)
		(end 191.592962 -69.4436)
		(width 0.10668)
		(layer "B.Cu")
		(net "RMII_BMC_OCP_TX_EN")
	)
	(segment
		(start 191.592962 -71.259954)
		(end 191.708786 -71.375778)
		(width 0.10668)
		(layer "B.Cu")
		(net "RMII_BMC_OCP_TX_EN")
	)
	(segment
		(start 202.398884 -68.47078)
		(end 202.792584 -68.47078)
		(width 0.11684)
		(layer "In2.Cu")
		(net "RMII_BMC_OCP_TX_EN")
	)
	(segment
		(start 192.360042 -71.375778)
		(end 194.529964 -69.205856)
		(width 0.11684)
		(layer "In2.Cu")
		(net "RMII_BMC_OCP_TX_EN")
	)
	(segment
		(start 202.282044 -67.731894)
		(end 202.282044 -68.35394)
		(width 0.11684)
		(layer "In2.Cu")
		(net "RMII_BMC_OCP_TX_EN")
	)
	(segment
		(start 194.529964 -69.205856)
		(end 195.377562 -69.205856)
		(width 0.11684)
		(layer "In2.Cu")
		(net "RMII_BMC_OCP_TX_EN")
	)
	(segment
		(start 202.282044 -68.35394)
		(end 202.398884 -68.47078)
		(width 0.11684)
		(layer "In2.Cu")
		(net "RMII_BMC_OCP_TX_EN")
	)
	(segment
		(start 191.708786 -71.375778)
		(end 192.360042 -71.375778)
		(width 0.11684)
		(layer "In2.Cu")
		(net "RMII_BMC_OCP_TX_EN")
	)
	(segment
		(start 195.494402 -69.089016)
		(end 195.494402 -67.90944)
		(width 0.11684)
		(layer "In2.Cu")
		(net "RMII_BMC_OCP_TX_EN")
	)
	(segment
		(start 196.238622 -69.205856)
		(end 197.106794 -69.205856)
		(width 0.11684)
		(layer "In2.Cu")
		(net "RMII_BMC_OCP_TX_EN")
	)
	(segment
		(start 202.909424 -67.731894)
		(end 203.115926 -67.525392)
		(width 0.11684)
		(layer "In2.Cu")
		(net "RMII_BMC_OCP_TX_EN")
	)
	(segment
		(start 203.115926 -67.525392)
		(end 204.038708 -67.525392)
		(width 0.11684)
		(layer "In2.Cu")
		(net "RMII_BMC_OCP_TX_EN")
	)
	(segment
		(start 195.494402 -67.90944)
		(end 195.611242 -67.7926)
		(width 0.11684)
		(layer "In2.Cu")
		(net "RMII_BMC_OCP_TX_EN")
	)
	(segment
		(start 195.377562 -69.205856)
		(end 195.494402 -69.089016)
		(width 0.11684)
		(layer "In2.Cu")
		(net "RMII_BMC_OCP_TX_EN")
	)
	(segment
		(start 198.382636 -67.930014)
		(end 201.42835 -67.930014)
		(width 0.11684)
		(layer "In2.Cu")
		(net "RMII_BMC_OCP_TX_EN")
	)
	(segment
		(start 202.909424 -68.35394)
		(end 202.909424 -67.731894)
		(width 0.11684)
		(layer "In2.Cu")
		(net "RMII_BMC_OCP_TX_EN")
	)
	(segment
		(start 201.74331 -67.615054)
		(end 202.165204 -67.615054)
		(width 0.11684)
		(layer "In2.Cu")
		(net "RMII_BMC_OCP_TX_EN")
	)
	(segment
		(start 202.165204 -67.615054)
		(end 202.282044 -67.731894)
		(width 0.11684)
		(layer "In2.Cu")
		(net "RMII_BMC_OCP_TX_EN")
	)
	(segment
		(start 197.106794 -69.205856)
		(end 198.382636 -67.930014)
		(width 0.11684)
		(layer "In2.Cu")
		(net "RMII_BMC_OCP_TX_EN")
	)
	(segment
		(start 196.121782 -67.90944)
		(end 196.121782 -69.089016)
		(width 0.11684)
		(layer "In2.Cu")
		(net "RMII_BMC_OCP_TX_EN")
	)
	(segment
		(start 196.121782 -69.089016)
		(end 196.238622 -69.205856)
		(width 0.11684)
		(layer "In2.Cu")
		(net "RMII_BMC_OCP_TX_EN")
	)
	(segment
		(start 196.004942 -67.7926)
		(end 196.121782 -67.90944)
		(width 0.11684)
		(layer "In2.Cu")
		(net "RMII_BMC_OCP_TX_EN")
	)
	(segment
		(start 201.42835 -67.930014)
		(end 201.74331 -67.615054)
		(width 0.11684)
		(layer "In2.Cu")
		(net "RMII_BMC_OCP_TX_EN")
	)
	(segment
		(start 202.792584 -68.47078)
		(end 202.909424 -68.35394)
		(width 0.11684)
		(layer "In2.Cu")
		(net "RMII_BMC_OCP_TX_EN")
	)
	(segment
		(start 195.611242 -67.7926)
		(end 196.004942 -67.7926)
		(width 0.11684)
		(layer "In2.Cu")
		(net "RMII_BMC_OCP_TX_EN")
	)
	(segment
		(start 192.331086 -65.862708)
		(end 192.214246 -65.745868)
		(width 0.11684)
		(layer "In4.Cu")
		(net "RMII_BMC_OCP_TX_EN")
	)
	(segment
		(start 192.331086 -66.256408)
		(end 192.331086 -65.862708)
		(width 0.11684)
		(layer "In4.Cu")
		(net "RMII_BMC_OCP_TX_EN")
	)
	(segment
		(start 192.214246 -66.373248)
		(end 192.331086 -66.256408)
		(width 0.11684)
		(layer "In4.Cu")
		(net "RMII_BMC_OCP_TX_EN")
	)
	(segment
		(start 191.118744 -42.594784)
		(end 190.173356 -41.649396)
		(width 0.11684)
		(layer "In4.Cu")
		(net "RMII_BMC_OCP_TX_EN")
	)
	(segment
		(start 168.61917 -24.283162)
		(end 168.61917 -22.823678)
		(width 0.11684)
		(layer "In4.Cu")
		(net "RMII_BMC_OCP_TX_EN")
	)
	(segment
		(start 191.235584 -65.745868)
		(end 191.118744 -65.629028)
		(width 0.11684)
		(layer "In4.Cu")
		(net "RMII_BMC_OCP_TX_EN")
	)
	(segment
		(start 174.531782 -28.685744)
		(end 173.021752 -28.685744)
		(width 0.11684)
		(layer "In4.Cu")
		(net "RMII_BMC_OCP_TX_EN")
	)
	(segment
		(start 190.173356 -41.649396)
		(end 187.038488 -41.649396)
		(width 0.11684)
		(layer "In4.Cu")
		(net "RMII_BMC_OCP_TX_EN")
	)
	(segment
		(start 191.118744 -48.85055)
		(end 190.027052 -47.758858)
		(width 0.11684)
		(layer "In4.Cu")
		(net "RMII_BMC_OCP_TX_EN")
	)
	(segment
		(start 190.027052 -47.758858)
		(end 190.027052 -45.654976)
		(width 0.11684)
		(layer "In4.Cu")
		(net "RMII_BMC_OCP_TX_EN")
	)
	(segment
		(start 179.2224 -33.3248)
		(end 177.623978 -33.3248)
		(width 0.11684)
		(layer "In4.Cu")
		(net "RMII_BMC_OCP_TX_EN")
	)
	(segment
		(start 192.214246 -65.745868)
		(end 191.235584 -65.745868)
		(width 0.11684)
		(layer "In4.Cu")
		(net "RMII_BMC_OCP_TX_EN")
	)
	(segment
		(start 191.708786 -71.375778)
		(end 191.118744 -70.785736)
		(width 0.11684)
		(layer "In4.Cu")
		(net "RMII_BMC_OCP_TX_EN")
	)
	(segment
		(start 179.87391 -34.484818)
		(end 179.87391 -33.97631)
		(width 0.11684)
		(layer "In4.Cu")
		(net "RMII_BMC_OCP_TX_EN")
	)
	(segment
		(start 173.021752 -28.685744)
		(end 168.61917 -24.283162)
		(width 0.11684)
		(layer "In4.Cu")
		(net "RMII_BMC_OCP_TX_EN")
	)
	(segment
		(start 187.038488 -41.649396)
		(end 179.87391 -34.484818)
		(width 0.11684)
		(layer "In4.Cu")
		(net "RMII_BMC_OCP_TX_EN")
	)
	(segment
		(start 177.623978 -33.3248)
		(end 175.062134 -30.762956)
		(width 0.11684)
		(layer "In4.Cu")
		(net "RMII_BMC_OCP_TX_EN")
	)
	(segment
		(start 175.062134 -29.216096)
		(end 174.531782 -28.685744)
		(width 0.11684)
		(layer "In4.Cu")
		(net "RMII_BMC_OCP_TX_EN")
	)
	(segment
		(start 168.61917 -22.823678)
		(end 166.379652 -20.58416)
		(width 0.11684)
		(layer "In4.Cu")
		(net "RMII_BMC_OCP_TX_EN")
	)
	(segment
		(start 190.027052 -45.654976)
		(end 191.118744 -44.563284)
		(width 0.11684)
		(layer "In4.Cu")
		(net "RMII_BMC_OCP_TX_EN")
	)
	(segment
		(start 166.379652 -19.51228)
		(end 166.732458 -19.159474)
		(width 0.11684)
		(layer "In4.Cu")
		(net "RMII_BMC_OCP_TX_EN")
	)
	(segment
		(start 179.87391 -33.97631)
		(end 179.2224 -33.3248)
		(width 0.11684)
		(layer "In4.Cu")
		(net "RMII_BMC_OCP_TX_EN")
	)
	(segment
		(start 191.118744 -44.563284)
		(end 191.118744 -42.594784)
		(width 0.11684)
		(layer "In4.Cu")
		(net "RMII_BMC_OCP_TX_EN")
	)
	(segment
		(start 166.379652 -20.58416)
		(end 166.379652 -19.51228)
		(width 0.11684)
		(layer "In4.Cu")
		(net "RMII_BMC_OCP_TX_EN")
	)
	(segment
		(start 191.118744 -70.785736)
		(end 191.118744 -66.490088)
		(width 0.11684)
		(layer "In4.Cu")
		(net "RMII_BMC_OCP_TX_EN")
	)
	(segment
		(start 191.118744 -66.490088)
		(end 191.235584 -66.373248)
		(width 0.11684)
		(layer "In4.Cu")
		(net "RMII_BMC_OCP_TX_EN")
	)
	(segment
		(start 175.062134 -30.762956)
		(end 175.062134 -29.216096)
		(width 0.11684)
		(layer "In4.Cu")
		(net "RMII_BMC_OCP_TX_EN")
	)
	(segment
		(start 191.235584 -66.373248)
		(end 192.214246 -66.373248)
		(width 0.11684)
		(layer "In4.Cu")
		(net "RMII_BMC_OCP_TX_EN")
	)
	(segment
		(start 191.118744 -65.629028)
		(end 191.118744 -48.85055)
		(width 0.11684)
		(layer "In4.Cu")
		(net "RMII_BMC_OCP_TX_EN")
	)
	(segment
		(start 166.26713 -16.549878)
		(end 166.26713 -18.947384)
		(width 0.10668)
		(layer "F.Cu")
		(net "RMII_BMC_OCP_TXD_1")
	)
	(segment
		(start 213.698074 -72.031606)
		(end 214.250016 -72.583548)
		(width 0.10668)
		(layer "F.Cu")
		(net "RMII_BMC_OCP_TXD_1")
	)
	(segment
		(start 214.250016 -72.583548)
		(end 214.250016 -73.050908)
		(width 0.10668)
		(layer "F.Cu")
		(net "RMII_BMC_OCP_TXD_1")
	)
	(segment
		(start 166.26713 -18.947384)
		(end 166.116254 -19.09826)
		(width 0.10668)
		(layer "F.Cu")
		(net "RMII_BMC_OCP_TXD_1")
	)
	(segment
		(start 204.415898 -71.47052)
		(end 205.881986 -72.936608)
		(width 0.10668)
		(layer "F.Cu")
		(net "RMII_BMC_OCP_TXD_1")
	)
	(segment
		(start 204.29982 -71.47052)
		(end 204.415898 -71.47052)
		(width 0.10668)
		(layer "F.Cu")
		(net "RMII_BMC_OCP_TXD_1")
	)
	(segment
		(start 166.116254 -19.295364)
		(end 166.920164 -20.099274)
		(width 0.10668)
		(layer "F.Cu")
		(net "RMII_BMC_OCP_TXD_1")
	)
	(segment
		(start 207.54848 -72.936608)
		(end 208.453482 -72.031606)
		(width 0.10668)
		(layer "F.Cu")
		(net "RMII_BMC_OCP_TXD_1")
	)
	(segment
		(start 205.881986 -72.936608)
		(end 207.54848 -72.936608)
		(width 0.10668)
		(layer "F.Cu")
		(net "RMII_BMC_OCP_TXD_1")
	)
	(segment
		(start 208.453482 -72.031606)
		(end 213.698074 -72.031606)
		(width 0.10668)
		(layer "F.Cu")
		(net "RMII_BMC_OCP_TXD_1")
	)
	(segment
		(start 166.116254 -19.09826)
		(end 166.116254 -19.295364)
		(width 0.10668)
		(layer "F.Cu")
		(net "RMII_BMC_OCP_TXD_1")
	)
	(via
		(at 166.920164 -20.099274)
		(size 0.762)
		(drill 0.254)
		(layers "F.Cu" "B.Cu")
		(net "RMII_BMC_OCP_TXD_1")
	)
	(via
		(at 204.29982 -71.47052)
		(size 0.508)
		(drill 0.254)
		(layers "F.Cu" "B.Cu")
		(net "RMII_BMC_OCP_TXD_1")
	)
	(via
		(at 214.250016 -73.050908)
		(size 0.508)
		(drill 0.254)
		(layers "F.Cu" "B.Cu")
		(net "RMII_BMC_OCP_TXD_1")
	)
	(segment
		(start 215.121236 -73.050908)
		(end 214.250016 -73.050908)
		(width 0.10668)
		(layer "B.Cu")
		(net "RMII_BMC_OCP_TXD_1")
	)
	(segment
		(start 215.114378 -73.057766)
		(end 215.121236 -73.050908)
		(width 0.10668)
		(layer "B.Cu")
		(net "RMII_BMC_OCP_TXD_1")
	)
	(segment
		(start 205.789022 -72.214994)
		(end 205.044548 -71.47052)
		(width 0.10668)
		(layer "B.Cu")
		(net "RMII_BMC_OCP_TXD_1")
	)
	(segment
		(start 215.114378 -74.055986)
		(end 215.114378 -73.057766)
		(width 0.10668)
		(layer "B.Cu")
		(net "RMII_BMC_OCP_TXD_1")
	)
	(segment
		(start 205.044548 -71.47052)
		(end 204.29982 -71.47052)
		(width 0.10668)
		(layer "B.Cu")
		(net "RMII_BMC_OCP_TXD_1")
	)
	(segment
		(start 169.061384 -24.099774)
		(end 173.20514 -28.24353)
		(width 0.11684)
		(layer "In4.Cu")
		(net "RMII_BMC_OCP_TXD_1")
	)
	(segment
		(start 173.20514 -28.24353)
		(end 174.71517 -28.24353)
		(width 0.11684)
		(layer "In4.Cu")
		(net "RMII_BMC_OCP_TXD_1")
	)
	(segment
		(start 166.920164 -20.24126)
		(end 169.061384 -22.38248)
		(width 0.11684)
		(layer "In4.Cu")
		(net "RMII_BMC_OCP_TXD_1")
	)
	(segment
		(start 177.80762 -32.88284)
		(end 179.55641 -32.88284)
		(width 0.11684)
		(layer "In4.Cu")
		(net "RMII_BMC_OCP_TXD_1")
	)
	(segment
		(start 174.71517 -28.24353)
		(end 175.504348 -29.032708)
		(width 0.11684)
		(layer "In4.Cu")
		(net "RMII_BMC_OCP_TXD_1")
	)
	(segment
		(start 196.697092 -45.491654)
		(end 196.697092 -60.168028)
		(width 0.11684)
		(layer "In4.Cu")
		(net "RMII_BMC_OCP_TXD_1")
	)
	(segment
		(start 169.061384 -22.38248)
		(end 169.061384 -24.099774)
		(width 0.11684)
		(layer "In4.Cu")
		(net "RMII_BMC_OCP_TXD_1")
	)
	(segment
		(start 202.018138 -67.559174)
		(end 204.29982 -69.840856)
		(width 0.11684)
		(layer "In4.Cu")
		(net "RMII_BMC_OCP_TXD_1")
	)
	(segment
		(start 175.504348 -29.032708)
		(end 175.504348 -30.579568)
		(width 0.11684)
		(layer "In4.Cu")
		(net "RMII_BMC_OCP_TXD_1")
	)
	(segment
		(start 202.018138 -65.489074)
		(end 202.018138 -67.559174)
		(width 0.11684)
		(layer "In4.Cu")
		(net "RMII_BMC_OCP_TXD_1")
	)
	(segment
		(start 187.69965 -37.287708)
		(end 189.85357 -39.441628)
		(width 0.11684)
		(layer "In4.Cu")
		(net "RMII_BMC_OCP_TXD_1")
	)
	(segment
		(start 196.697092 -60.168028)
		(end 202.018138 -65.489074)
		(width 0.11684)
		(layer "In4.Cu")
		(net "RMII_BMC_OCP_TXD_1")
	)
	(segment
		(start 204.29982 -69.840856)
		(end 204.29982 -71.47052)
		(width 0.11684)
		(layer "In4.Cu")
		(net "RMII_BMC_OCP_TXD_1")
	)
	(segment
		(start 175.504348 -30.579568)
		(end 177.80762 -32.88284)
		(width 0.11684)
		(layer "In4.Cu")
		(net "RMII_BMC_OCP_TXD_1")
	)
	(segment
		(start 189.85357 -39.441628)
		(end 190.647066 -39.441628)
		(width 0.11684)
		(layer "In4.Cu")
		(net "RMII_BMC_OCP_TXD_1")
	)
	(segment
		(start 179.55641 -32.88284)
		(end 180.566568 -33.892998)
		(width 0.11684)
		(layer "In4.Cu")
		(net "RMII_BMC_OCP_TXD_1")
	)
	(segment
		(start 190.647066 -39.441628)
		(end 196.697092 -45.491654)
		(width 0.11684)
		(layer "In4.Cu")
		(net "RMII_BMC_OCP_TXD_1")
	)
	(segment
		(start 180.566568 -34.58083)
		(end 183.273446 -37.287708)
		(width 0.11684)
		(layer "In4.Cu")
		(net "RMII_BMC_OCP_TXD_1")
	)
	(segment
		(start 180.566568 -33.892998)
		(end 180.566568 -34.58083)
		(width 0.11684)
		(layer "In4.Cu")
		(net "RMII_BMC_OCP_TXD_1")
	)
	(segment
		(start 183.273446 -37.287708)
		(end 187.69965 -37.287708)
		(width 0.11684)
		(layer "In4.Cu")
		(net "RMII_BMC_OCP_TXD_1")
	)
	(segment
		(start 166.920164 -20.099274)
		(end 166.920164 -20.24126)
		(width 0.11684)
		(layer "In4.Cu")
		(net "RMII_BMC_OCP_TXD_1")
	)
	(segment
		(start 166.867078 -17.578324)
		(end 166.751254 -17.694148)
		(width 0.10668)
		(layer "F.Cu")
		(net "RMII_BMC_OCP_TXD_0")
	)
	(segment
		(start 166.867078 -16.549878)
		(end 166.867078 -17.578324)
		(width 0.10668)
		(layer "F.Cu")
		(net "RMII_BMC_OCP_TXD_0")
	)
	(via
		(at 166.751254 -17.694148)
		(size 0.508)
		(drill 0.254)
		(layers "F.Cu" "B.Cu")
		(net "RMII_BMC_OCP_TXD_0")
	)
	(via
		(at 205.775306 -69.620892)
		(size 0.762)
		(drill 0.254)
		(layers "F.Cu" "B.Cu")
		(net "RMII_BMC_OCP_TXD_0")
	)
	(via
		(at 216.872566 -66.562478)
		(size 0.508)
		(drill 0.254)
		(layers "F.Cu" "B.Cu")
		(net "RMII_BMC_OCP_TXD_0")
	)
	(segment
		(start 218.066112 -68.061078)
		(end 217.566748 -68.061078)
		(width 0.10668)
		(layer "B.Cu")
		(net "RMII_BMC_OCP_TXD_0")
	)
	(segment
		(start 217.33637 -67.8307)
		(end 217.33637 -67.026282)
		(width 0.10668)
		(layer "B.Cu")
		(net "RMII_BMC_OCP_TXD_0")
	)
	(segment
		(start 218.066112 -68.061078)
		(end 218.066112 -69.369178)
		(width 0.10668)
		(layer "B.Cu")
		(net "RMII_BMC_OCP_TXD_0")
	)
	(segment
		(start 205.775306 -70.31228)
		(end 205.775306 -69.620892)
		(width 0.10668)
		(layer "B.Cu")
		(net "RMII_BMC_OCP_TXD_0")
	)
	(segment
		(start 217.33637 -67.026282)
		(end 216.872566 -66.562478)
		(width 0.10668)
		(layer "B.Cu")
		(net "RMII_BMC_OCP_TXD_0")
	)
	(segment
		(start 217.566748 -68.061078)
		(end 217.33637 -67.8307)
		(width 0.10668)
		(layer "B.Cu")
		(net "RMII_BMC_OCP_TXD_0")
	)
	(segment
		(start 218.066112 -69.369178)
		(end 217.951812 -69.483478)
		(width 0.10668)
		(layer "B.Cu")
		(net "RMII_BMC_OCP_TXD_0")
	)
	(segment
		(start 216.872566 -66.562478)
		(end 208.83372 -66.562478)
		(width 0.11684)
		(layer "In2.Cu")
		(net "RMII_BMC_OCP_TXD_0")
	)
	(segment
		(start 208.83372 -66.562478)
		(end 205.775306 -69.620892)
		(width 0.11684)
		(layer "In2.Cu")
		(net "RMII_BMC_OCP_TXD_0")
	)
	(segment
		(start 180.565806 -24.896826)
		(end 178.78298 -23.114)
		(width 0.11684)
		(layer "In4.Cu")
		(net "RMII_BMC_OCP_TXD_0")
	)
	(segment
		(start 203.373482 -65.400936)
		(end 197.540372 -59.567826)
		(width 0.11684)
		(layer "In4.Cu")
		(net "RMII_BMC_OCP_TXD_0")
	)
	(segment
		(start 171.173902 -17.075658)
		(end 167.369744 -17.075658)
		(width 0.11684)
		(layer "In4.Cu")
		(net "RMII_BMC_OCP_TXD_0")
	)
	(segment
		(start 186.946794 -34.932366)
		(end 186.946794 -32.407098)
		(width 0.11684)
		(layer "In4.Cu")
		(net "RMII_BMC_OCP_TXD_0")
	)
	(segment
		(start 191.003428 -38.989)
		(end 186.946794 -34.932366)
		(width 0.11684)
		(layer "In4.Cu")
		(net "RMII_BMC_OCP_TXD_0")
	)
	(segment
		(start 205.476602 -69.620892)
		(end 203.373482 -67.517772)
		(width 0.11684)
		(layer "In4.Cu")
		(net "RMII_BMC_OCP_TXD_0")
	)
	(segment
		(start 175.6156 -21.62556)
		(end 175.6156 -19.7866)
		(width 0.11684)
		(layer "In4.Cu")
		(net "RMII_BMC_OCP_TXD_0")
	)
	(segment
		(start 179.9209 -27.54884)
		(end 179.9209 -26.6827)
		(width 0.11684)
		(layer "In4.Cu")
		(net "RMII_BMC_OCP_TXD_0")
	)
	(segment
		(start 180.565806 -26.037794)
		(end 180.565806 -24.896826)
		(width 0.11684)
		(layer "In4.Cu")
		(net "RMII_BMC_OCP_TXD_0")
	)
	(segment
		(start 197.540372 -44.931076)
		(end 191.598296 -38.989)
		(width 0.11684)
		(layer "In4.Cu")
		(net "RMII_BMC_OCP_TXD_0")
	)
	(segment
		(start 173.386242 -19.287998)
		(end 171.173902 -17.075658)
		(width 0.11684)
		(layer "In4.Cu")
		(net "RMII_BMC_OCP_TXD_0")
	)
	(segment
		(start 175.6156 -19.7866)
		(end 175.116998 -19.287998)
		(width 0.11684)
		(layer "In4.Cu")
		(net "RMII_BMC_OCP_TXD_0")
	)
	(segment
		(start 203.373482 -67.517772)
		(end 203.373482 -65.400936)
		(width 0.11684)
		(layer "In4.Cu")
		(net "RMII_BMC_OCP_TXD_0")
	)
	(segment
		(start 182.642256 -28.10256)
		(end 180.47462 -28.10256)
		(width 0.11684)
		(layer "In4.Cu")
		(net "RMII_BMC_OCP_TXD_0")
	)
	(segment
		(start 180.47462 -28.10256)
		(end 179.9209 -27.54884)
		(width 0.11684)
		(layer "In4.Cu")
		(net "RMII_BMC_OCP_TXD_0")
	)
	(segment
		(start 177.10404 -23.114)
		(end 175.6156 -21.62556)
		(width 0.11684)
		(layer "In4.Cu")
		(net "RMII_BMC_OCP_TXD_0")
	)
	(segment
		(start 178.78298 -23.114)
		(end 177.10404 -23.114)
		(width 0.11684)
		(layer "In4.Cu")
		(net "RMII_BMC_OCP_TXD_0")
	)
	(segment
		(start 191.598296 -38.989)
		(end 191.003428 -38.989)
		(width 0.11684)
		(layer "In4.Cu")
		(net "RMII_BMC_OCP_TXD_0")
	)
	(segment
		(start 175.116998 -19.287998)
		(end 173.386242 -19.287998)
		(width 0.11684)
		(layer "In4.Cu")
		(net "RMII_BMC_OCP_TXD_0")
	)
	(segment
		(start 179.9209 -26.6827)
		(end 180.565806 -26.037794)
		(width 0.11684)
		(layer "In4.Cu")
		(net "RMII_BMC_OCP_TXD_0")
	)
	(segment
		(start 186.946794 -32.407098)
		(end 182.642256 -28.10256)
		(width 0.11684)
		(layer "In4.Cu")
		(net "RMII_BMC_OCP_TXD_0")
	)
	(segment
		(start 167.369744 -17.075658)
		(end 166.751254 -17.694148)
		(width 0.11684)
		(layer "In4.Cu")
		(net "RMII_BMC_OCP_TXD_0")
	)
	(segment
		(start 197.540372 -59.567826)
		(end 197.540372 -44.931076)
		(width 0.11684)
		(layer "In4.Cu")
		(net "RMII_BMC_OCP_TXD_0")
	)
	(segment
		(start 205.775306 -69.620892)
		(end 205.476602 -69.620892)
		(width 0.11684)
		(layer "In4.Cu")
		(net "RMII_BMC_OCP_TXD_0")
	)
	(segment
		(start 165.404038 -18.90395)
		(end 165.404038 -19.903186)
		(width 0.10668)
		(layer "F.Cu")
		(net "RMII_BMC_OCP_RX_ER")
	)
	(segment
		(start 165.666928 -18.462752)
		(end 165.314884 -18.814796)
		(width 0.10668)
		(layer "F.Cu")
		(net "RMII_BMC_OCP_RX_ER")
	)
	(segment
		(start 165.666928 -16.549878)
		(end 165.666928 -18.462752)
		(width 0.10668)
		(layer "F.Cu")
		(net "RMII_BMC_OCP_RX_ER")
	)
	(segment
		(start 165.314884 -18.814796)
		(end 165.404038 -18.90395)
		(width 0.10668)
		(layer "F.Cu")
		(net "RMII_BMC_OCP_RX_ER")
	)
	(segment
		(start 166.070534 -20.569682)
		(end 166.070534 -21.383498)
		(width 0.10668)
		(layer "F.Cu")
		(net "RMII_BMC_OCP_RX_ER")
	)
	(segment
		(start 165.404038 -19.903186)
		(end 166.070534 -20.569682)
		(width 0.10668)
		(layer "F.Cu")
		(net "RMII_BMC_OCP_RX_ER")
	)
	(via
		(at 165.314884 -18.814796)
		(size 0.508)
		(drill 0.254)
		(layers "F.Cu" "B.Cu")
		(net "RMII_BMC_OCP_RX_ER")
	)
	(segment
		(start 25.927304 -362.669582)
		(end 26.058368 -362.669582)
		(width 0.10668)
		(layer "F.Cu")
		(net "PWRGD_PVDDIO_P1_R")
	)
	(segment
		(start 25.16505 -362.204)
		(end 25.461722 -362.204)
		(width 0.10668)
		(layer "F.Cu")
		(net "PWRGD_PVDDIO_P1_R")
	)
	(segment
		(start 25.461722 -362.204)
		(end 25.927304 -362.669582)
		(width 0.10668)
		(layer "F.Cu")
		(net "PWRGD_PVDDIO_P1_R")
	)
	(segment
		(start 26.897838 -363.509052)
		(end 27.604974 -363.509052)
		(width 0.10668)
		(layer "F.Cu")
		(net "PWRGD_PVDDIO_P1_R")
	)
	(segment
		(start 26.058368 -362.669582)
		(end 26.897838 -363.509052)
		(width 0.10668)
		(layer "F.Cu")
		(net "PWRGD_PVDDIO_P1_R")
	)
	(via
		(at 25.927304 -362.669582)
		(size 0.508)
		(drill 0.254)
		(layers "F.Cu" "B.Cu")
		(net "PWRGD_PVDDIO_P1_R")
	)
	(segment
		(start 25.16505 -362.204)
		(end 25.461722 -362.204)
		(width 0.10668)
		(layer "B.Cu")
		(net "PWRGD_PVDDIO_P1_R")
	)
	(segment
		(start 25.461722 -362.204)
		(end 25.927304 -362.669582)
		(width 0.10668)
		(layer "B.Cu")
		(net "PWRGD_PVDDIO_P1_R")
	)
	(segment
		(start 25.16505 -361.061)
		(end 25.16505 -362.204)
		(width 0.10668)
		(layer "B.Cu")
		(net "PWRGD_PVDDIO_P1_R")
	)
	(segment
		(start 197.669658 -113.625376)
		(end 198.342758 -113.625376)
		(width 0.10668)
		(layer "F.Cu")
		(net "PWRGD_PVDDIO_P1")
	)
	(via
		(at 198.19493 -102.498652)
		(size 0.508)
		(drill 0.254)
		(layers "F.Cu" "B.Cu")
		(net "PWRGD_PVDDIO_P1")
	)
	(via
		(at 20.607528 -361.74553)
		(size 0.508)
		(drill 0.254)
		(layers "F.Cu" "B.Cu")
		(net "PWRGD_PVDDIO_P1")
	)
	(via
		(at 198.342758 -113.625376)
		(size 0.508)
		(drill 0.254)
		(layers "F.Cu" "B.Cu")
		(net "PWRGD_PVDDIO_P1")
	)
	(via
		(at 202.10399 -90.804492)
		(size 0.508)
		(drill 0.254)
		(layers "F.Cu" "B.Cu")
		(net "PWRGD_PVDDIO_P1")
	)
	(via
		(at 195.62826 -79.391002)
		(size 0.508)
		(drill 0.254)
		(layers "F.Cu" "B.Cu")
		(net "PWRGD_PVDDIO_P1")
	)
	(via
		(at 96.12249 -112.620044)
		(size 0.508)
		(drill 0.254)
		(layers "F.Cu" "B.Cu")
		(net "PWRGD_PVDDIO_P1")
	)
	(via
		(at 201.941684 -92.418408)
		(size 0.6604)
		(drill 0.3302)
		(layers "F.Cu" "B.Cu")
		(net "PWRGD_PVDDIO_P1")
	)
	(segment
		(start 198.19493 -102.498652)
		(end 198.19493 -100.319586)
		(width 0.10668)
		(layer "B.Cu")
		(net "PWRGD_PVDDIO_P1")
	)
	(segment
		(start 24.23795 -361.569)
		(end 23.298658 -361.569)
		(width 0.10668)
		(layer "B.Cu")
		(net "PWRGD_PVDDIO_P1")
	)
	(segment
		(start 24.36495 -361.442)
		(end 24.23795 -361.569)
		(width 0.10668)
		(layer "B.Cu")
		(net "PWRGD_PVDDIO_P1")
	)
	(segment
		(start 24.36495 -361.061)
		(end 24.36495 -361.442)
		(width 0.10668)
		(layer "B.Cu")
		(net "PWRGD_PVDDIO_P1")
	)
	(segment
		(start 22.55139 -361.892088)
		(end 22.278086 -361.618784)
		(width 0.10668)
		(layer "B.Cu")
		(net "PWRGD_PVDDIO_P1")
	)
	(segment
		(start 22.55139 -362.077)
		(end 22.55139 -361.892088)
		(width 0.10668)
		(layer "B.Cu")
		(net "PWRGD_PVDDIO_P1")
	)
	(segment
		(start 22.87905 -362.204)
		(end 22.67839 -362.204)
		(width 0.10668)
		(layer "B.Cu")
		(net "PWRGD_PVDDIO_P1")
	)
	(segment
		(start 23.001478 -361.86618)
		(end 23.001478 -362.081572)
		(width 0.10668)
		(layer "B.Cu")
		(net "PWRGD_PVDDIO_P1")
	)
	(segment
		(start 20.734274 -361.618784)
		(end 20.607528 -361.74553)
		(width 0.10668)
		(layer "B.Cu")
		(net "PWRGD_PVDDIO_P1")
	)
	(segment
		(start 201.941684 -96.572832)
		(end 201.941684 -92.418408)
		(width 0.10668)
		(layer "B.Cu")
		(net "PWRGD_PVDDIO_P1")
	)
	(segment
		(start 201.941684 -92.418408)
		(end 201.941684 -90.966798)
		(width 0.10668)
		(layer "B.Cu")
		(net "PWRGD_PVDDIO_P1")
	)
	(segment
		(start 23.001478 -362.081572)
		(end 22.87905 -362.204)
		(width 0.10668)
		(layer "B.Cu")
		(net "PWRGD_PVDDIO_P1")
	)
	(segment
		(start 22.67839 -362.204)
		(end 22.55139 -362.077)
		(width 0.10668)
		(layer "B.Cu")
		(net "PWRGD_PVDDIO_P1")
	)
	(segment
		(start 201.941684 -90.966798)
		(end 202.10399 -90.804492)
		(width 0.10668)
		(layer "B.Cu")
		(net "PWRGD_PVDDIO_P1")
	)
	(segment
		(start 22.278086 -361.618784)
		(end 20.734274 -361.618784)
		(width 0.10668)
		(layer "B.Cu")
		(net "PWRGD_PVDDIO_P1")
	)
	(segment
		(start 23.298658 -361.569)
		(end 23.001478 -361.86618)
		(width 0.10668)
		(layer "B.Cu")
		(net "PWRGD_PVDDIO_P1")
	)
	(segment
		(start 198.19493 -100.319586)
		(end 201.941684 -96.572832)
		(width 0.10668)
		(layer "B.Cu")
		(net "PWRGD_PVDDIO_P1")
	)
	(segment
		(start 81.859374 -127.169672)
		(end 96.12249 -112.906556)
		(width 0.11684)
		(layer "In4.Cu")
		(net "PWRGD_PVDDIO_P1")
	)
	(segment
		(start 78.983078 -127.169672)
		(end 81.859374 -127.169672)
		(width 0.11684)
		(layer "In4.Cu")
		(net "PWRGD_PVDDIO_P1")
	)
	(segment
		(start 68.333112 -137.819638)
		(end 78.983078 -127.169672)
		(width 0.11684)
		(layer "In4.Cu")
		(net "PWRGD_PVDDIO_P1")
	)
	(segment
		(start 16.512286 -345.142058)
		(end 6.427724 -335.057496)
		(width 0.11684)
		(layer "In4.Cu")
		(net "PWRGD_PVDDIO_P1")
	)
	(segment
		(start 20.607528 -361.74553)
		(end 18.93697 -361.74553)
		(width 0.11684)
		(layer "In4.Cu")
		(net "PWRGD_PVDDIO_P1")
	)
	(segment
		(start 7.328916 -167.178228)
		(end 13.17371 -167.178228)
		(width 0.11684)
		(layer "In4.Cu")
		(net "PWRGD_PVDDIO_P1")
	)
	(segment
		(start 18.93697 -361.74553)
		(end 16.512286 -359.320846)
		(width 0.11684)
		(layer "In4.Cu")
		(net "PWRGD_PVDDIO_P1")
	)
	(segment
		(start 6.427724 -335.057496)
		(end 6.427724 -168.07942)
		(width 0.11684)
		(layer "In4.Cu")
		(net "PWRGD_PVDDIO_P1")
	)
	(segment
		(start 33.602676 -137.819638)
		(end 68.333112 -137.819638)
		(width 0.11684)
		(layer "In4.Cu")
		(net "PWRGD_PVDDIO_P1")
	)
	(segment
		(start 96.12249 -112.906556)
		(end 96.12249 -112.620044)
		(width 0.11684)
		(layer "In4.Cu")
		(net "PWRGD_PVDDIO_P1")
	)
	(segment
		(start 17.012158 -163.33978)
		(end 17.012158 -154.410156)
		(width 0.11684)
		(layer "In4.Cu")
		(net "PWRGD_PVDDIO_P1")
	)
	(segment
		(start 16.512286 -359.320846)
		(end 16.512286 -345.142058)
		(width 0.11684)
		(layer "In4.Cu")
		(net "PWRGD_PVDDIO_P1")
	)
	(segment
		(start 13.17371 -167.178228)
		(end 17.012158 -163.33978)
		(width 0.11684)
		(layer "In4.Cu")
		(net "PWRGD_PVDDIO_P1")
	)
	(segment
		(start 17.012158 -154.410156)
		(end 33.602676 -137.819638)
		(width 0.11684)
		(layer "In4.Cu")
		(net "PWRGD_PVDDIO_P1")
	)
	(segment
		(start 6.427724 -168.07942)
		(end 7.328916 -167.178228)
		(width 0.11684)
		(layer "In4.Cu")
		(net "PWRGD_PVDDIO_P1")
	)
	(segment
		(start 178.185572 -81.804764)
		(end 175.040544 -81.804764)
		(width 0.11684)
		(layer "In6.Cu")
		(net "PWRGD_PVDDIO_P1")
	)
	(segment
		(start 193.823082 -74.461116)
		(end 193.291714 -73.929748)
		(width 0.11684)
		(layer "In6.Cu")
		(net "PWRGD_PVDDIO_P1")
	)
	(segment
		(start 159.423862 -81.805018)
		(end 155.879546 -85.349334)
		(width 0.11684)
		(layer "In6.Cu")
		(net "PWRGD_PVDDIO_P1")
	)
	(segment
		(start 124.455936 -109.87278)
		(end 98.35896 -109.87278)
		(width 0.11684)
		(layer "In6.Cu")
		(net "PWRGD_PVDDIO_P1")
	)
	(segment
		(start 195.62826 -79.391002)
		(end 195.52412 -79.495142)
		(width 0.11684)
		(layer "In6.Cu")
		(net "PWRGD_PVDDIO_P1")
	)
	(segment
		(start 175.04029 -81.805018)
		(end 159.423862 -81.805018)
		(width 0.11684)
		(layer "In6.Cu")
		(net "PWRGD_PVDDIO_P1")
	)
	(segment
		(start 128.157224 -103.72725)
		(end 128.157224 -106.171492)
		(width 0.11684)
		(layer "In6.Cu")
		(net "PWRGD_PVDDIO_P1")
	)
	(segment
		(start 175.040544 -81.804764)
		(end 175.04029 -81.805018)
		(width 0.11684)
		(layer "In6.Cu")
		(net "PWRGD_PVDDIO_P1")
	)
	(segment
		(start 193.291714 -73.929748)
		(end 192.214246 -73.929748)
		(width 0.11684)
		(layer "In6.Cu")
		(net "PWRGD_PVDDIO_P1")
	)
	(segment
		(start 192.214246 -73.929748)
		(end 184.338976 -81.805018)
		(width 0.11684)
		(layer "In6.Cu")
		(net "PWRGD_PVDDIO_P1")
	)
	(segment
		(start 195.52412 -79.495142)
		(end 194.831716 -79.495142)
		(width 0.11684)
		(layer "In6.Cu")
		(net "PWRGD_PVDDIO_P1")
	)
	(segment
		(start 128.157224 -106.171492)
		(end 124.455936 -109.87278)
		(width 0.11684)
		(layer "In6.Cu")
		(net "PWRGD_PVDDIO_P1")
	)
	(segment
		(start 184.338976 -81.805018)
		(end 178.185826 -81.805018)
		(width 0.11684)
		(layer "In6.Cu")
		(net "PWRGD_PVDDIO_P1")
	)
	(segment
		(start 96.12249 -112.10925)
		(end 96.12249 -112.620044)
		(width 0.11684)
		(layer "In6.Cu")
		(net "PWRGD_PVDDIO_P1")
	)
	(segment
		(start 155.879546 -85.349334)
		(end 146.53514 -85.349334)
		(width 0.11684)
		(layer "In6.Cu")
		(net "PWRGD_PVDDIO_P1")
	)
	(segment
		(start 194.831716 -79.495142)
		(end 193.823082 -78.486508)
		(width 0.11684)
		(layer "In6.Cu")
		(net "PWRGD_PVDDIO_P1")
	)
	(segment
		(start 98.35896 -109.87278)
		(end 96.12249 -112.10925)
		(width 0.11684)
		(layer "In6.Cu")
		(net "PWRGD_PVDDIO_P1")
	)
	(segment
		(start 178.185826 -81.805018)
		(end 178.185572 -81.804764)
		(width 0.11684)
		(layer "In6.Cu")
		(net "PWRGD_PVDDIO_P1")
	)
	(segment
		(start 146.53514 -85.349334)
		(end 128.157224 -103.72725)
		(width 0.11684)
		(layer "In6.Cu")
		(net "PWRGD_PVDDIO_P1")
	)
	(segment
		(start 193.823082 -78.486508)
		(end 193.823082 -74.461116)
		(width 0.11684)
		(layer "In6.Cu")
		(net "PWRGD_PVDDIO_P1")
	)
	(segment
		(start 197.701916 -113.625376)
		(end 198.342758 -113.625376)
		(width 0.11684)
		(layer "In11.Cu")
		(net "PWRGD_PVDDIO_P1")
	)
	(segment
		(start 197.693026 -103.641652)
		(end 197.693026 -105.835704)
		(width 0.11684)
		(layer "In11.Cu")
		(net "PWRGD_PVDDIO_P1")
	)
	(segment
		(start 198.19493 -102.498652)
		(end 198.19493 -103.139748)
		(width 0.11684)
		(layer "In11.Cu")
		(net "PWRGD_PVDDIO_P1")
	)
	(segment
		(start 195.62826 -79.678276)
		(end 195.62826 -79.391002)
		(width 0.11684)
		(layer "In11.Cu")
		(net "PWRGD_PVDDIO_P1")
	)
	(segment
		(start 197.176136 -84.373466)
		(end 196.723254 -83.920584)
		(width 0.11684)
		(layer "In11.Cu")
		(net "PWRGD_PVDDIO_P1")
	)
	(segment
		(start 199.646286 -89.433908)
		(end 197.176136 -86.963758)
		(width 0.11684)
		(layer "In11.Cu")
		(net "PWRGD_PVDDIO_P1")
	)
	(segment
		(start 201.451972 -89.433908)
		(end 199.646286 -89.433908)
		(width 0.11684)
		(layer "In11.Cu")
		(net "PWRGD_PVDDIO_P1")
	)
	(segment
		(start 197.176136 -86.963758)
		(end 197.176136 -84.373466)
		(width 0.11684)
		(layer "In11.Cu")
		(net "PWRGD_PVDDIO_P1")
	)
	(segment
		(start 197.271894 -113.195354)
		(end 197.701916 -113.625376)
		(width 0.11684)
		(layer "In11.Cu")
		(net "PWRGD_PVDDIO_P1")
	)
	(segment
		(start 196.723254 -83.920584)
		(end 196.723254 -80.77327)
		(width 0.11684)
		(layer "In11.Cu")
		(net "PWRGD_PVDDIO_P1")
	)
	(segment
		(start 198.19493 -103.139748)
		(end 197.693026 -103.641652)
		(width 0.11684)
		(layer "In11.Cu")
		(net "PWRGD_PVDDIO_P1")
	)
	(segment
		(start 196.723254 -80.77327)
		(end 195.62826 -79.678276)
		(width 0.11684)
		(layer "In11.Cu")
		(net "PWRGD_PVDDIO_P1")
	)
	(segment
		(start 202.10399 -90.804492)
		(end 202.10399 -90.085926)
		(width 0.11684)
		(layer "In11.Cu")
		(net "PWRGD_PVDDIO_P1")
	)
	(segment
		(start 197.693026 -105.835704)
		(end 197.271894 -106.256836)
		(width 0.11684)
		(layer "In11.Cu")
		(net "PWRGD_PVDDIO_P1")
	)
	(segment
		(start 202.10399 -90.085926)
		(end 201.451972 -89.433908)
		(width 0.11684)
		(layer "In11.Cu")
		(net "PWRGD_PVDDIO_P1")
	)
	(segment
		(start 197.271894 -106.256836)
		(end 197.271894 -113.195354)
		(width 0.11684)
		(layer "In11.Cu")
		(net "PWRGD_PVDDIO_P1")
	)
	(segment
		(start 306.333906 -360.02976)
		(end 306.384198 -360.080052)
		(width 0.10668)
		(layer "F.Cu")
		(net "PWRGD_PVDDIO_P0_R")
	)
	(segment
		(start 305.623468 -360.02976)
		(end 306.333906 -360.02976)
		(width 0.10668)
		(layer "F.Cu")
		(net "PWRGD_PVDDIO_P0_R")
	)
	(segment
		(start 306.384198 -360.080052)
		(end 307.258974 -360.080052)
		(width 0.10668)
		(layer "F.Cu")
		(net "PWRGD_PVDDIO_P0_R")
	)
	(segment
		(start 304.81905 -359.283)
		(end 304.876708 -359.283)
		(width 0.10668)
		(layer "F.Cu")
		(net "PWRGD_PVDDIO_P0_R")
	)
	(segment
		(start 304.876708 -359.283)
		(end 305.623468 -360.02976)
		(width 0.10668)
		(layer "F.Cu")
		(net "PWRGD_PVDDIO_P0_R")
	)
	(via
		(at 305.623468 -360.02976)
		(size 0.508)
		(drill 0.254)
		(layers "F.Cu" "B.Cu")
		(net "PWRGD_PVDDIO_P0_R")
	)
	(segment
		(start 304.81905 -359.283)
		(end 304.876708 -359.283)
		(width 0.10668)
		(layer "B.Cu")
		(net "PWRGD_PVDDIO_P0_R")
	)
	(segment
		(start 304.876708 -359.283)
		(end 305.623468 -360.02976)
		(width 0.10668)
		(layer "B.Cu")
		(net "PWRGD_PVDDIO_P0_R")
	)
	(segment
		(start 304.81905 -358.14)
		(end 304.81905 -359.283)
		(width 0.10668)
		(layer "B.Cu")
		(net "PWRGD_PVDDIO_P0_R")
	)
	(segment
		(start 223.388682 -199.338438)
		(end 223.92767 -198.79945)
		(width 0.10668)
		(layer "F.Cu")
		(net "PWRGD_PVDDIO_P0")
	)
	(segment
		(start 252.930152 -370.25961)
		(end 248.612914 -365.942372)
		(width 0.10668)
		(layer "F.Cu")
		(net "PWRGD_PVDDIO_P0")
	)
	(segment
		(start 225.613722 -340.573614)
		(end 224.899474 -339.859366)
		(width 0.10668)
		(layer "F.Cu")
		(net "PWRGD_PVDDIO_P0")
	)
	(segment
		(start 295.7322 -371.6782)
		(end 294.851836 -372.558564)
		(width 0.10668)
		(layer "F.Cu")
		(net "PWRGD_PVDDIO_P0")
	)
	(segment
		(start 221.894908 -202.30592)
		(end 223.388682 -200.812146)
		(width 0.10668)
		(layer "F.Cu")
		(net "PWRGD_PVDDIO_P0")
	)
	(segment
		(start 284.327092 -372.558564)
		(end 282.028138 -370.25961)
		(width 0.10668)
		(layer "F.Cu")
		(net "PWRGD_PVDDIO_P0")
	)
	(segment
		(start 219.277438 -157.842712)
		(end 219.277438 -138.615674)
		(width 0.10668)
		(layer "F.Cu")
		(net "PWRGD_PVDDIO_P0")
	)
	(segment
		(start 216.510108 -104.35844)
		(end 216.285318 -104.58323)
		(width 0.10668)
		(layer "F.Cu")
		(net "PWRGD_PVDDIO_P0")
	)
	(segment
		(start 282.028138 -370.25961)
		(end 252.930152 -370.25961)
		(width 0.10668)
		(layer "F.Cu")
		(net "PWRGD_PVDDIO_P0")
	)
	(segment
		(start 222.541592 -166.879016)
		(end 222.541592 -165.304216)
		(width 0.10668)
		(layer "F.Cu")
		(net "PWRGD_PVDDIO_P0")
	)
	(segment
		(start 218.21394 -105.4481)
		(end 217.12428 -104.35844)
		(width 0.10668)
		(layer "F.Cu")
		(net "PWRGD_PVDDIO_P0")
	)
	(segment
		(start 223.92767 -168.265094)
		(end 222.541592 -166.879016)
		(width 0.10668)
		(layer "F.Cu")
		(net "PWRGD_PVDDIO_P0")
	)
	(segment
		(start 220.801438 -125.64618)
		(end 220.801438 -125.053344)
		(width 0.10668)
		(layer "F.Cu")
		(net "PWRGD_PVDDIO_P0")
	)
	(segment
		(start 224.637346 -363.602778)
		(end 225.299778 -363.602778)
		(width 0.10668)
		(layer "F.Cu")
		(net "PWRGD_PVDDIO_P0")
	)
	(segment
		(start 221.894908 -206.05242)
		(end 221.894908 -202.30592)
		(width 0.10668)
		(layer "F.Cu")
		(net "PWRGD_PVDDIO_P0")
	)
	(segment
		(start 248.612914 -365.942372)
		(end 233.190288 -365.942372)
		(width 0.10668)
		(layer "F.Cu")
		(net "PWRGD_PVDDIO_P0")
	)
	(segment
		(start 220.1291 -108.32592)
		(end 218.21394 -106.41076)
		(width 0.10668)
		(layer "F.Cu")
		(net "PWRGD_PVDDIO_P0")
	)
	(segment
		(start 219.277438 -138.615674)
		(end 221.212156 -136.680956)
		(width 0.10668)
		(layer "F.Cu")
		(net "PWRGD_PVDDIO_P0")
	)
	(segment
		(start 223.92767 -198.79945)
		(end 223.92767 -168.265094)
		(width 0.10668)
		(layer "F.Cu")
		(net "PWRGD_PVDDIO_P0")
	)
	(segment
		(start 294.851836 -372.558564)
		(end 284.327092 -372.558564)
		(width 0.10668)
		(layer "F.Cu")
		(net "PWRGD_PVDDIO_P0")
	)
	(segment
		(start 220.801438 -125.053344)
		(end 217.889836 -122.141742)
		(width 0.10668)
		(layer "F.Cu")
		(net "PWRGD_PVDDIO_P0")
	)
	(segment
		(start 219.072968 -158.047182)
		(end 219.277438 -157.842712)
		(width 0.10668)
		(layer "F.Cu")
		(net "PWRGD_PVDDIO_P0")
	)
	(segment
		(start 218.156282 -208.492598)
		(end 219.45473 -208.492598)
		(width 0.10668)
		(layer "F.Cu")
		(net "PWRGD_PVDDIO_P0")
	)
	(segment
		(start 220.1291 -113.424208)
		(end 220.1291 -108.32592)
		(width 0.10668)
		(layer "F.Cu")
		(net "PWRGD_PVDDIO_P0")
	)
	(segment
		(start 217.889836 -122.141742)
		(end 217.889836 -119.398034)
		(width 0.10668)
		(layer "F.Cu")
		(net "PWRGD_PVDDIO_P0")
	)
	(segment
		(start 217.12428 -104.35844)
		(end 216.510108 -104.35844)
		(width 0.10668)
		(layer "F.Cu")
		(net "PWRGD_PVDDIO_P0")
	)
	(segment
		(start 223.816164 -333.906114)
		(end 223.816164 -328.92111)
		(width 0.10668)
		(layer "F.Cu")
		(net "PWRGD_PVDDIO_P0")
	)
	(segment
		(start 223.816164 -328.92111)
		(end 217.499692 -322.604638)
		(width 0.10668)
		(layer "F.Cu")
		(net "PWRGD_PVDDIO_P0")
	)
	(segment
		(start 219.419932 -163.65855)
		(end 219.072968 -163.311586)
		(width 0.10668)
		(layer "F.Cu")
		(net "PWRGD_PVDDIO_P0")
	)
	(segment
		(start 225.613722 -363.288834)
		(end 225.613722 -340.573614)
		(width 0.10668)
		(layer "F.Cu")
		(net "PWRGD_PVDDIO_P0")
	)
	(segment
		(start 218.21394 -106.41076)
		(end 218.21394 -105.4481)
		(width 0.10668)
		(layer "F.Cu")
		(net "PWRGD_PVDDIO_P0")
	)
	(segment
		(start 219.072968 -163.311586)
		(end 219.072968 -158.047182)
		(width 0.10668)
		(layer "F.Cu")
		(net "PWRGD_PVDDIO_P0")
	)
	(segment
		(start 217.499692 -209.149188)
		(end 218.156282 -208.492598)
		(width 0.10668)
		(layer "F.Cu")
		(net "PWRGD_PVDDIO_P0")
	)
	(segment
		(start 217.360754 -118.868952)
		(end 217.360754 -116.192554)
		(width 0.10668)
		(layer "F.Cu")
		(net "PWRGD_PVDDIO_P0")
	)
	(segment
		(start 217.889836 -119.398034)
		(end 217.360754 -118.868952)
		(width 0.10668)
		(layer "F.Cu")
		(net "PWRGD_PVDDIO_P0")
	)
	(segment
		(start 224.899474 -339.859366)
		(end 224.899474 -334.989424)
		(width 0.10668)
		(layer "F.Cu")
		(net "PWRGD_PVDDIO_P0")
	)
	(segment
		(start 232.772458 -366.360202)
		(end 231.614472 -366.360202)
		(width 0.10668)
		(layer "F.Cu")
		(net "PWRGD_PVDDIO_P0")
	)
	(segment
		(start 221.212156 -126.056898)
		(end 220.801438 -125.64618)
		(width 0.10668)
		(layer "F.Cu")
		(net "PWRGD_PVDDIO_P0")
	)
	(segment
		(start 220.895926 -163.65855)
		(end 219.419932 -163.65855)
		(width 0.10668)
		(layer "F.Cu")
		(net "PWRGD_PVDDIO_P0")
	)
	(segment
		(start 219.45473 -208.492598)
		(end 221.894908 -206.05242)
		(width 0.10668)
		(layer "F.Cu")
		(net "PWRGD_PVDDIO_P0")
	)
	(segment
		(start 225.299778 -363.602778)
		(end 225.613722 -363.288834)
		(width 0.10668)
		(layer "F.Cu")
		(net "PWRGD_PVDDIO_P0")
	)
	(segment
		(start 222.541592 -165.304216)
		(end 220.895926 -163.65855)
		(width 0.10668)
		(layer "F.Cu")
		(net "PWRGD_PVDDIO_P0")
	)
	(segment
		(start 217.360754 -116.192554)
		(end 220.1291 -113.424208)
		(width 0.10668)
		(layer "F.Cu")
		(net "PWRGD_PVDDIO_P0")
	)
	(segment
		(start 221.212156 -136.680956)
		(end 221.212156 -126.056898)
		(width 0.10668)
		(layer "F.Cu")
		(net "PWRGD_PVDDIO_P0")
	)
	(segment
		(start 224.899474 -334.989424)
		(end 223.816164 -333.906114)
		(width 0.10668)
		(layer "F.Cu")
		(net "PWRGD_PVDDIO_P0")
	)
	(segment
		(start 231.614472 -366.360202)
		(end 231.150414 -365.896144)
		(width 0.10668)
		(layer "F.Cu")
		(net "PWRGD_PVDDIO_P0")
	)
	(segment
		(start 223.388682 -200.812146)
		(end 223.388682 -199.338438)
		(width 0.10668)
		(layer "F.Cu")
		(net "PWRGD_PVDDIO_P0")
	)
	(segment
		(start 217.499692 -322.604638)
		(end 217.499692 -209.149188)
		(width 0.10668)
		(layer "F.Cu")
		(net "PWRGD_PVDDIO_P0")
	)
	(segment
		(start 233.190288 -365.942372)
		(end 232.772458 -366.360202)
		(width 0.10668)
		(layer "F.Cu")
		(net "PWRGD_PVDDIO_P0")
	)
	(via
		(at 216.285318 -104.58323)
		(size 0.508)
		(drill 0.254)
		(layers "F.Cu" "B.Cu")
		(net "PWRGD_PVDDIO_P0")
	)
	(via
		(at 295.7322 -371.6782)
		(size 0.508)
		(drill 0.254)
		(layers "F.Cu" "B.Cu")
		(net "PWRGD_PVDDIO_P0")
	)
	(via
		(at 224.637346 -363.602778)
		(size 0.508)
		(drill 0.254)
		(layers "F.Cu" "B.Cu")
		(net "PWRGD_PVDDIO_P0")
	)
	(via
		(at 231.150414 -365.896144)
		(size 0.508)
		(drill 0.254)
		(layers "F.Cu" "B.Cu")
		(net "PWRGD_PVDDIO_P0")
	)
	(via
		(at 301.752 -360.6292)
		(size 0.508)
		(drill 0.254)
		(layers "F.Cu" "B.Cu")
		(net "PWRGD_PVDDIO_P0")
	)
	(segment
		(start 198.418958 -104.567736)
		(end 198.332598 -104.481376)
		(width 0.10668)
		(layer "B.Cu")
		(net "PWRGD_PVDDIO_P0")
	)
	(segment
		(start 216.050368 -104.81818)
		(end 213.015322 -104.81818)
		(width 0.10668)
		(layer "B.Cu")
		(net "PWRGD_PVDDIO_P0")
	)
	(segment
		(start 209.931762 -103.366824)
		(end 209.741516 -103.55707)
		(width 0.10668)
		(layer "B.Cu")
		(net "PWRGD_PVDDIO_P0")
	)
	(segment
		(start 302.697896 -358.718104)
		(end 302.53305 -358.88295)
		(width 0.10668)
		(layer "B.Cu")
		(net "PWRGD_PVDDIO_P0")
	)
	(segment
		(start 216.285318 -104.58323)
		(end 216.050368 -104.81818)
		(width 0.10668)
		(layer "B.Cu")
		(net "PWRGD_PVDDIO_P0")
	)
	(segment
		(start 302.53305 -358.88295)
		(end 302.53305 -359.283)
		(width 0.10668)
		(layer "B.Cu")
		(net "PWRGD_PVDDIO_P0")
	)
	(segment
		(start 213.015322 -104.81818)
		(end 212.14334 -103.946198)
		(width 0.10668)
		(layer "B.Cu")
		(net "PWRGD_PVDDIO_P0")
	)
	(segment
		(start 303.821846 -358.718104)
		(end 302.697896 -358.718104)
		(width 0.10668)
		(layer "B.Cu")
		(net "PWRGD_PVDDIO_P0")
	)
	(segment
		(start 212.14334 -103.946198)
		(end 212.14334 -103.696008)
		(width 0.10668)
		(layer "B.Cu")
		(net "PWRGD_PVDDIO_P0")
	)
	(segment
		(start 209.741516 -103.55707)
		(end 206.321406 -103.55707)
		(width 0.10668)
		(layer "B.Cu")
		(net "PWRGD_PVDDIO_P0")
	)
	(segment
		(start 205.697582 -102.933246)
		(end 205.697582 -102.292658)
		(width 0.10668)
		(layer "B.Cu")
		(net "PWRGD_PVDDIO_P0")
	)
	(segment
		(start 198.332598 -104.481376)
		(end 197.923658 -104.481376)
		(width 0.10668)
		(layer "B.Cu")
		(net "PWRGD_PVDDIO_P0")
	)
	(segment
		(start 202.082908 -102.12705)
		(end 199.642222 -104.567736)
		(width 0.10668)
		(layer "B.Cu")
		(net "PWRGD_PVDDIO_P0")
	)
	(segment
		(start 211.814156 -103.366824)
		(end 209.931762 -103.366824)
		(width 0.10668)
		(layer "B.Cu")
		(net "PWRGD_PVDDIO_P0")
	)
	(segment
		(start 304.01895 -358.14)
		(end 304.01895 -358.521)
		(width 0.10668)
		(layer "B.Cu")
		(net "PWRGD_PVDDIO_P0")
	)
	(segment
		(start 212.14334 -103.696008)
		(end 211.814156 -103.366824)
		(width 0.10668)
		(layer "B.Cu")
		(net "PWRGD_PVDDIO_P0")
	)
	(segment
		(start 204.987398 -101.582474)
		(end 202.94092 -101.582474)
		(width 0.10668)
		(layer "B.Cu")
		(net "PWRGD_PVDDIO_P0")
	)
	(segment
		(start 202.94092 -101.582474)
		(end 202.396344 -102.12705)
		(width 0.10668)
		(layer "B.Cu")
		(net "PWRGD_PVDDIO_P0")
	)
	(segment
		(start 304.01895 -358.521)
		(end 303.821846 -358.718104)
		(width 0.10668)
		(layer "B.Cu")
		(net "PWRGD_PVDDIO_P0")
	)
	(segment
		(start 302.53305 -359.283)
		(end 302.53305 -359.84815)
		(width 0.10668)
		(layer "B.Cu")
		(net "PWRGD_PVDDIO_P0")
	)
	(segment
		(start 205.697582 -102.292658)
		(end 204.987398 -101.582474)
		(width 0.10668)
		(layer "B.Cu")
		(net "PWRGD_PVDDIO_P0")
	)
	(segment
		(start 206.321406 -103.55707)
		(end 205.697582 -102.933246)
		(width 0.10668)
		(layer "B.Cu")
		(net "PWRGD_PVDDIO_P0")
	)
	(segment
		(start 302.53305 -359.84815)
		(end 301.752 -360.6292)
		(width 0.10668)
		(layer "B.Cu")
		(net "PWRGD_PVDDIO_P0")
	)
	(segment
		(start 202.396344 -102.12705)
		(end 202.082908 -102.12705)
		(width 0.10668)
		(layer "B.Cu")
		(net "PWRGD_PVDDIO_P0")
	)
	(segment
		(start 199.642222 -104.567736)
		(end 198.418958 -104.567736)
		(width 0.10668)
		(layer "B.Cu")
		(net "PWRGD_PVDDIO_P0")
	)
	(segment
		(start 224.637346 -363.602778)
		(end 228.857048 -363.602778)
		(width 0.11684)
		(layer "In2.Cu")
		(net "PWRGD_PVDDIO_P0")
	)
	(segment
		(start 228.857048 -363.602778)
		(end 231.150414 -365.896144)
		(width 0.11684)
		(layer "In2.Cu")
		(net "PWRGD_PVDDIO_P0")
	)
	(segment
		(start 301.752 -360.6292)
		(end 301.752 -364.3376)
		(width 0.11684)
		(layer "In11.Cu")
		(net "PWRGD_PVDDIO_P0")
	)
	(segment
		(start 297.9674 -368.1222)
		(end 297.9674 -369.443)
		(width 0.11684)
		(layer "In11.Cu")
		(net "PWRGD_PVDDIO_P0")
	)
	(segment
		(start 301.752 -364.3376)
		(end 297.9674 -368.1222)
		(width 0.11684)
		(layer "In11.Cu")
		(net "PWRGD_PVDDIO_P0")
	)
	(segment
		(start 297.9674 -369.443)
		(end 295.7322 -371.6782)
		(width 0.11684)
		(layer "In11.Cu")
		(net "PWRGD_PVDDIO_P0")
	)
	(segment
		(start 90.609928 -145.90141)
		(end 91.225878 -145.90141)
		(width 0.10668)
		(layer "F.Cu")
		(net "PWRGD_PVDDCR_SOC_P1_R")
	)
	(segment
		(start 90.609928 -144.88541)
		(end 90.609928 -145.90141)
		(width 0.10668)
		(layer "F.Cu")
		(net "PWRGD_PVDDCR_SOC_P1_R")
	)
	(via
		(at 89.735152 -146.941032)
		(size 0.6604)
		(drill 0.3302)
		(layers "F.Cu" "B.Cu")
		(net "PWRGD_PVDDCR_SOC_P1_R")
	)
	(via
		(at 91.225878 -145.90141)
		(size 0.508)
		(drill 0.254)
		(layers "F.Cu" "B.Cu")
		(net "PWRGD_PVDDCR_SOC_P1_R")
	)
	(segment
		(start 89.870788 -147.076668)
		(end 90.169492 -147.076668)
		(width 0.10668)
		(layer "B.Cu")
		(net "PWRGD_PVDDCR_SOC_P1_R")
	)
	(segment
		(start 90.609928 -145.90141)
		(end 90.609928 -146.066256)
		(width 0.10668)
		(layer "B.Cu")
		(net "PWRGD_PVDDCR_SOC_P1_R")
	)
	(segment
		(start 91.303094 -145.90141)
		(end 91.846146 -145.358358)
		(width 0.10668)
		(layer "B.Cu")
		(net "PWRGD_PVDDCR_SOC_P1_R")
	)
	(segment
		(start 91.846146 -145.358358)
		(end 92.795852 -145.358358)
		(width 0.10668)
		(layer "B.Cu")
		(net "PWRGD_PVDDCR_SOC_P1_R")
	)
	(segment
		(start 91.225878 -145.90141)
		(end 91.303094 -145.90141)
		(width 0.10668)
		(layer "B.Cu")
		(net "PWRGD_PVDDCR_SOC_P1_R")
	)
	(segment
		(start 91.225878 -146.020282)
		(end 91.225878 -145.90141)
		(width 0.10668)
		(layer "B.Cu")
		(net "PWRGD_PVDDCR_SOC_P1_R")
	)
	(segment
		(start 90.169492 -147.076668)
		(end 91.225878 -146.020282)
		(width 0.10668)
		(layer "B.Cu")
		(net "PWRGD_PVDDCR_SOC_P1_R")
	)
	(segment
		(start 89.735152 -146.941032)
		(end 89.870788 -147.076668)
		(width 0.10668)
		(layer "B.Cu")
		(net "PWRGD_PVDDCR_SOC_P1_R")
	)
	(segment
		(start 90.609928 -146.066256)
		(end 89.735152 -146.941032)
		(width 0.10668)
		(layer "B.Cu")
		(net "PWRGD_PVDDCR_SOC_P1_R")
	)
	(segment
		(start 87.859108 -145.10131)
		(end 86.946994 -144.189196)
		(width 0.10668)
		(layer "F.Cu")
		(net "PWRGD_PVDDCR_SOC_P1")
	)
	(segment
		(start 86.946994 -144.189196)
		(end 86.946994 -138.927332)
		(width 0.10668)
		(layer "F.Cu")
		(net "PWRGD_PVDDCR_SOC_P1")
	)
	(segment
		(start 89.809828 -145.503646)
		(end 89.703148 -145.396966)
		(width 0.10668)
		(layer "F.Cu")
		(net "PWRGD_PVDDCR_SOC_P1")
	)
	(segment
		(start 94.61246 -137.01014)
		(end 95.318834 -137.716514)
		(width 0.10668)
		(layer "F.Cu")
		(net "PWRGD_PVDDCR_SOC_P1")
	)
	(segment
		(start 89.703148 -145.396966)
		(end 88.727534 -145.396966)
		(width 0.10668)
		(layer "F.Cu")
		(net "PWRGD_PVDDCR_SOC_P1")
	)
	(segment
		(start 177.122074 -119.452898)
		(end 176.732184 -119.842788)
		(width 0.10668)
		(layer "F.Cu")
		(net "PWRGD_PVDDCR_SOC_P1")
	)
	(segment
		(start 88.431878 -145.10131)
		(end 87.859108 -145.10131)
		(width 0.10668)
		(layer "F.Cu")
		(net "PWRGD_PVDDCR_SOC_P1")
	)
	(segment
		(start 89.809828 -145.90141)
		(end 89.809828 -145.503646)
		(width 0.10668)
		(layer "F.Cu")
		(net "PWRGD_PVDDCR_SOC_P1")
	)
	(segment
		(start 88.727534 -145.396966)
		(end 88.431878 -145.10131)
		(width 0.10668)
		(layer "F.Cu")
		(net "PWRGD_PVDDCR_SOC_P1")
	)
	(segment
		(start 86.946994 -138.927332)
		(end 88.864186 -137.01014)
		(width 0.10668)
		(layer "F.Cu")
		(net "PWRGD_PVDDCR_SOC_P1")
	)
	(segment
		(start 88.864186 -137.01014)
		(end 94.61246 -137.01014)
		(width 0.10668)
		(layer "F.Cu")
		(net "PWRGD_PVDDCR_SOC_P1")
	)
	(via
		(at 176.732184 -119.842788)
		(size 0.4572)
		(drill 0.254)
		(layers "F.Cu" "B.Cu")
		(net "PWRGD_PVDDCR_SOC_P1")
	)
	(via
		(at 95.318834 -137.716514)
		(size 0.508)
		(drill 0.254)
		(layers "F.Cu" "B.Cu")
		(net "PWRGD_PVDDCR_SOC_P1")
	)
	(via
		(at 139.93495 -120.695212)
		(size 0.508)
		(drill 0.254)
		(layers "F.Cu" "B.Cu")
		(net "PWRGD_PVDDCR_SOC_P1")
	)
	(segment
		(start 117.503956 -125.657356)
		(end 119.090694 -125.657356)
		(width 0.10668)
		(layer "B.Cu")
		(net "PWRGD_PVDDCR_SOC_P1")
	)
	(segment
		(start 119.751094 -124.996956)
		(end 135.401304 -124.996956)
		(width 0.10668)
		(layer "B.Cu")
		(net "PWRGD_PVDDCR_SOC_P1")
	)
	(segment
		(start 105.600754 -127.0254)
		(end 107.629198 -124.996956)
		(width 0.10668)
		(layer "B.Cu")
		(net "PWRGD_PVDDCR_SOC_P1")
	)
	(segment
		(start 96.204532 -134.406894)
		(end 96.204532 -128.550924)
		(width 0.10668)
		(layer "B.Cu")
		(net "PWRGD_PVDDCR_SOC_P1")
	)
	(segment
		(start 96.204532 -128.550924)
		(end 97.730056 -127.0254)
		(width 0.10668)
		(layer "B.Cu")
		(net "PWRGD_PVDDCR_SOC_P1")
	)
	(segment
		(start 95.318834 -137.716514)
		(end 95.318834 -135.292592)
		(width 0.10668)
		(layer "B.Cu")
		(net "PWRGD_PVDDCR_SOC_P1")
	)
	(segment
		(start 139.703048 -120.695212)
		(end 139.93495 -120.695212)
		(width 0.10668)
		(layer "B.Cu")
		(net "PWRGD_PVDDCR_SOC_P1")
	)
	(segment
		(start 107.629198 -124.996956)
		(end 116.843556 -124.996956)
		(width 0.10668)
		(layer "B.Cu")
		(net "PWRGD_PVDDCR_SOC_P1")
	)
	(segment
		(start 116.843556 -124.996956)
		(end 117.503956 -125.657356)
		(width 0.10668)
		(layer "B.Cu")
		(net "PWRGD_PVDDCR_SOC_P1")
	)
	(segment
		(start 119.090694 -125.657356)
		(end 119.751094 -124.996956)
		(width 0.10668)
		(layer "B.Cu")
		(net "PWRGD_PVDDCR_SOC_P1")
	)
	(segment
		(start 97.730056 -127.0254)
		(end 105.600754 -127.0254)
		(width 0.10668)
		(layer "B.Cu")
		(net "PWRGD_PVDDCR_SOC_P1")
	)
	(segment
		(start 95.318834 -135.292592)
		(end 96.204532 -134.406894)
		(width 0.10668)
		(layer "B.Cu")
		(net "PWRGD_PVDDCR_SOC_P1")
	)
	(segment
		(start 135.401304 -124.996956)
		(end 139.703048 -120.695212)
		(width 0.10668)
		(layer "B.Cu")
		(net "PWRGD_PVDDCR_SOC_P1")
	)
	(segment
		(start 157.61081 -123.53417)
		(end 148.04517 -123.53417)
		(width 0.11684)
		(layer "In2.Cu")
		(net "PWRGD_PVDDCR_SOC_P1")
	)
	(segment
		(start 162.901376 -123.044712)
		(end 162.289744 -123.656344)
		(width 0.11684)
		(layer "In2.Cu")
		(net "PWRGD_PVDDCR_SOC_P1")
	)
	(segment
		(start 166.759382 -122.192542)
		(end 165.907212 -123.044712)
		(width 0.11684)
		(layer "In2.Cu")
		(net "PWRGD_PVDDCR_SOC_P1")
	)
	(segment
		(start 170.202098 -123.385072)
		(end 169.717212 -123.385072)
		(width 0.11684)
		(layer "In2.Cu")
		(net "PWRGD_PVDDCR_SOC_P1")
	)
	(segment
		(start 169.717212 -123.385072)
		(end 168.524682 -122.192542)
		(width 0.11684)
		(layer "In2.Cu")
		(net "PWRGD_PVDDCR_SOC_P1")
	)
	(segment
		(start 168.524682 -122.192542)
		(end 166.759382 -122.192542)
		(width 0.11684)
		(layer "In2.Cu")
		(net "PWRGD_PVDDCR_SOC_P1")
	)
	(segment
		(start 162.289744 -123.656344)
		(end 157.732984 -123.656344)
		(width 0.11684)
		(layer "In2.Cu")
		(net "PWRGD_PVDDCR_SOC_P1")
	)
	(segment
		(start 165.907212 -123.044712)
		(end 162.901376 -123.044712)
		(width 0.11684)
		(layer "In2.Cu")
		(net "PWRGD_PVDDCR_SOC_P1")
	)
	(segment
		(start 170.867578 -122.719592)
		(end 170.202098 -123.385072)
		(width 0.11684)
		(layer "In2.Cu")
		(net "PWRGD_PVDDCR_SOC_P1")
	)
	(segment
		(start 174.867824 -119.358664)
		(end 172.353478 -119.358664)
		(width 0.11684)
		(layer "In2.Cu")
		(net "PWRGD_PVDDCR_SOC_P1")
	)
	(segment
		(start 176.692052 -119.88292)
		(end 175.39208 -119.88292)
		(width 0.11684)
		(layer "In2.Cu")
		(net "PWRGD_PVDDCR_SOC_P1")
	)
	(segment
		(start 176.732184 -119.842788)
		(end 176.692052 -119.88292)
		(width 0.11684)
		(layer "In2.Cu")
		(net "PWRGD_PVDDCR_SOC_P1")
	)
	(segment
		(start 145.206212 -120.695212)
		(end 139.93495 -120.695212)
		(width 0.11684)
		(layer "In2.Cu")
		(net "PWRGD_PVDDCR_SOC_P1")
	)
	(segment
		(start 157.732984 -123.656344)
		(end 157.61081 -123.53417)
		(width 0.11684)
		(layer "In2.Cu")
		(net "PWRGD_PVDDCR_SOC_P1")
	)
	(segment
		(start 175.39208 -119.88292)
		(end 174.867824 -119.358664)
		(width 0.11684)
		(layer "In2.Cu")
		(net "PWRGD_PVDDCR_SOC_P1")
	)
	(segment
		(start 148.04517 -123.53417)
		(end 145.206212 -120.695212)
		(width 0.11684)
		(layer "In2.Cu")
		(net "PWRGD_PVDDCR_SOC_P1")
	)
	(segment
		(start 170.867578 -120.844564)
		(end 170.867578 -122.719592)
		(width 0.11684)
		(layer "In2.Cu")
		(net "PWRGD_PVDDCR_SOC_P1")
	)
	(segment
		(start 172.353478 -119.358664)
		(end 170.867578 -120.844564)
		(width 0.11684)
		(layer "In2.Cu")
		(net "PWRGD_PVDDCR_SOC_P1")
	)
	(segment
		(start 373.337328 -143.504158)
		(end 373.953278 -143.504158)
		(width 0.10668)
		(layer "F.Cu")
		(net "PWRGD_PVDDCR_SOC_P0_R")
	)
	(segment
		(start 373.337328 -142.488158)
		(end 373.337328 -142.786862)
		(width 0.10668)
		(layer "F.Cu")
		(net "PWRGD_PVDDCR_SOC_P0_R")
	)
	(segment
		(start 373.953278 -143.402812)
		(end 373.953278 -143.504158)
		(width 0.10668)
		(layer "F.Cu")
		(net "PWRGD_PVDDCR_SOC_P0_R")
	)
	(segment
		(start 373.337328 -142.786862)
		(end 373.953278 -143.402812)
		(width 0.10668)
		(layer "F.Cu")
		(net "PWRGD_PVDDCR_SOC_P0_R")
	)
	(via
		(at 374.423178 -143.034258)
		(size 0.4064)
		(drill 0.2032)
		(layers "F.Cu" "B.Cu")
		(net "PWRGD_PVDDCR_SOC_P0_R")
	)
	(via
		(at 373.953278 -143.504158)
		(size 0.508)
		(drill 0.254)
		(layers "F.Cu" "B.Cu")
		(net "PWRGD_PVDDCR_SOC_P0_R")
	)
	(segment
		(start 373.953278 -143.504158)
		(end 373.337328 -143.504158)
		(width 0.10668)
		(layer "B.Cu")
		(net "PWRGD_PVDDCR_SOC_P0_R")
	)
	(segment
		(start 375.01322 -142.961106)
		(end 374.952514 -142.9004)
		(width 0.10668)
		(layer "B.Cu")
		(net "PWRGD_PVDDCR_SOC_P0_R")
	)
	(segment
		(start 374.952514 -142.9004)
		(end 374.557036 -142.9004)
		(width 0.10668)
		(layer "B.Cu")
		(net "PWRGD_PVDDCR_SOC_P0_R")
	)
	(segment
		(start 375.523252 -142.961106)
		(end 375.01322 -142.961106)
		(width 0.10668)
		(layer "B.Cu")
		(net "PWRGD_PVDDCR_SOC_P0_R")
	)
	(segment
		(start 374.557036 -142.9004)
		(end 374.423178 -143.034258)
		(width 0.10668)
		(layer "B.Cu")
		(net "PWRGD_PVDDCR_SOC_P0_R")
	)
	(segment
		(start 374.423178 -143.034258)
		(end 373.953278 -143.504158)
		(width 0.10668)
		(layer "B.Cu")
		(net "PWRGD_PVDDCR_SOC_P0_R")
	)
	(segment
		(start 372.353078 -143.999712)
		(end 372.537228 -143.815562)
		(width 0.10668)
		(layer "F.Cu")
		(net "PWRGD_PVDDCR_SOC_P0")
	)
	(segment
		(start 369.283488 -141.40434)
		(end 371.305328 -143.42618)
		(width 0.10668)
		(layer "F.Cu")
		(net "PWRGD_PVDDCR_SOC_P0")
	)
	(segment
		(start 369.283488 -111.879888)
		(end 369.283488 -141.40434)
		(width 0.10668)
		(layer "F.Cu")
		(net "PWRGD_PVDDCR_SOC_P0")
	)
	(segment
		(start 371.305328 -143.814038)
		(end 371.491002 -143.999712)
		(width 0.10668)
		(layer "F.Cu")
		(net "PWRGD_PVDDCR_SOC_P0")
	)
	(segment
		(start 371.305328 -143.42618)
		(end 371.305328 -143.504158)
		(width 0.10668)
		(layer "F.Cu")
		(net "PWRGD_PVDDCR_SOC_P0")
	)
	(segment
		(start 370.073428 -111.089948)
		(end 369.283488 -111.879888)
		(width 0.10668)
		(layer "F.Cu")
		(net "PWRGD_PVDDCR_SOC_P0")
	)
	(segment
		(start 192.322196 -107.452922)
		(end 192.712086 -107.063032)
		(width 0.10668)
		(layer "F.Cu")
		(net "PWRGD_PVDDCR_SOC_P0")
	)
	(segment
		(start 372.537228 -143.815562)
		(end 372.537228 -143.504158)
		(width 0.10668)
		(layer "F.Cu")
		(net "PWRGD_PVDDCR_SOC_P0")
	)
	(segment
		(start 371.491002 -143.999712)
		(end 372.353078 -143.999712)
		(width 0.10668)
		(layer "F.Cu")
		(net "PWRGD_PVDDCR_SOC_P0")
	)
	(segment
		(start 371.305328 -143.504158)
		(end 371.305328 -143.814038)
		(width 0.10668)
		(layer "F.Cu")
		(net "PWRGD_PVDDCR_SOC_P0")
	)
	(via
		(at 370.073428 -111.089948)
		(size 0.508)
		(drill 0.254)
		(layers "F.Cu" "B.Cu")
		(net "PWRGD_PVDDCR_SOC_P0")
	)
	(via
		(at 192.712086 -107.063032)
		(size 0.4572)
		(drill 0.254)
		(layers "F.Cu" "B.Cu")
		(net "PWRGD_PVDDCR_SOC_P0")
	)
	(segment
		(start 322.746878 -109.22508)
		(end 321.247262 -109.22508)
		(width 0.11684)
		(layer "In6.Cu")
		(net "PWRGD_PVDDCR_SOC_P0")
	)
	(segment
		(start 202.828144 -103.928672)
		(end 201.854816 -104.902)
		(width 0.11684)
		(layer "In6.Cu")
		(net "PWRGD_PVDDCR_SOC_P0")
	)
	(segment
		(start 254.995426 -102.200202)
		(end 217.197178 -102.200202)
		(width 0.11684)
		(layer "In6.Cu")
		(net "PWRGD_PVDDCR_SOC_P0")
	)
	(segment
		(start 217.157046 -102.16007)
		(end 216.46896 -102.16007)
		(width 0.11684)
		(layer "In6.Cu")
		(net "PWRGD_PVDDCR_SOC_P0")
	)
	(segment
		(start 209.723736 -103.928672)
		(end 202.828144 -103.928672)
		(width 0.11684)
		(layer "In6.Cu")
		(net "PWRGD_PVDDCR_SOC_P0")
	)
	(segment
		(start 194.374008 -106.750612)
		(end 193.024506 -106.750612)
		(width 0.11684)
		(layer "In6.Cu")
		(net "PWRGD_PVDDCR_SOC_P0")
	)
	(segment
		(start 324.21957 -110.697772)
		(end 322.746878 -109.22508)
		(width 0.11684)
		(layer "In6.Cu")
		(net "PWRGD_PVDDCR_SOC_P0")
	)
	(segment
		(start 256.04724 -101.148388)
		(end 254.995426 -102.200202)
		(width 0.11684)
		(layer "In6.Cu")
		(net "PWRGD_PVDDCR_SOC_P0")
	)
	(segment
		(start 274.797266 -101.335586)
		(end 268.251178 -101.335586)
		(width 0.11684)
		(layer "In6.Cu")
		(net "PWRGD_PVDDCR_SOC_P0")
	)
	(segment
		(start 370.073428 -111.089948)
		(end 369.681252 -110.697772)
		(width 0.11684)
		(layer "In6.Cu")
		(net "PWRGD_PVDDCR_SOC_P0")
	)
	(segment
		(start 274.983702 -101.14915)
		(end 274.797266 -101.335586)
		(width 0.11684)
		(layer "In6.Cu")
		(net "PWRGD_PVDDCR_SOC_P0")
	)
	(segment
		(start 213.54923 -103.44277)
		(end 210.209638 -103.44277)
		(width 0.11684)
		(layer "In6.Cu")
		(net "PWRGD_PVDDCR_SOC_P0")
	)
	(segment
		(start 196.216778 -104.902)
		(end 195.3768 -105.741978)
		(width 0.11684)
		(layer "In6.Cu")
		(net "PWRGD_PVDDCR_SOC_P0")
	)
	(segment
		(start 268.251178 -101.335586)
		(end 265.85672 -98.941128)
		(width 0.11684)
		(layer "In6.Cu")
		(net "PWRGD_PVDDCR_SOC_P0")
	)
	(segment
		(start 210.209638 -103.44277)
		(end 209.723736 -103.928672)
		(width 0.11684)
		(layer "In6.Cu")
		(net "PWRGD_PVDDCR_SOC_P0")
	)
	(segment
		(start 216.18829 -102.44074)
		(end 214.55126 -102.44074)
		(width 0.11684)
		(layer "In6.Cu")
		(net "PWRGD_PVDDCR_SOC_P0")
	)
	(segment
		(start 214.55126 -102.44074)
		(end 213.54923 -103.44277)
		(width 0.11684)
		(layer "In6.Cu")
		(net "PWRGD_PVDDCR_SOC_P0")
	)
	(segment
		(start 369.681252 -110.697772)
		(end 324.21957 -110.697772)
		(width 0.11684)
		(layer "In6.Cu")
		(net "PWRGD_PVDDCR_SOC_P0")
	)
	(segment
		(start 195.3768 -105.741978)
		(end 195.3768 -105.74782)
		(width 0.11684)
		(layer "In6.Cu")
		(net "PWRGD_PVDDCR_SOC_P0")
	)
	(segment
		(start 201.854816 -104.902)
		(end 196.216778 -104.902)
		(width 0.11684)
		(layer "In6.Cu")
		(net "PWRGD_PVDDCR_SOC_P0")
	)
	(segment
		(start 217.197178 -102.200202)
		(end 217.157046 -102.16007)
		(width 0.11684)
		(layer "In6.Cu")
		(net "PWRGD_PVDDCR_SOC_P0")
	)
	(segment
		(start 195.3768 -105.74782)
		(end 194.374008 -106.750612)
		(width 0.11684)
		(layer "In6.Cu")
		(net "PWRGD_PVDDCR_SOC_P0")
	)
	(segment
		(start 193.024506 -106.750612)
		(end 192.712086 -107.063032)
		(width 0.11684)
		(layer "In6.Cu")
		(net "PWRGD_PVDDCR_SOC_P0")
	)
	(segment
		(start 313.171332 -101.14915)
		(end 274.983702 -101.14915)
		(width 0.11684)
		(layer "In6.Cu")
		(net "PWRGD_PVDDCR_SOC_P0")
	)
	(segment
		(start 265.85672 -98.941128)
		(end 260.36524 -98.941128)
		(width 0.11684)
		(layer "In6.Cu")
		(net "PWRGD_PVDDCR_SOC_P0")
	)
	(segment
		(start 258.15798 -101.148388)
		(end 256.04724 -101.148388)
		(width 0.11684)
		(layer "In6.Cu")
		(net "PWRGD_PVDDCR_SOC_P0")
	)
	(segment
		(start 216.46896 -102.16007)
		(end 216.18829 -102.44074)
		(width 0.11684)
		(layer "In6.Cu")
		(net "PWRGD_PVDDCR_SOC_P0")
	)
	(segment
		(start 321.247262 -109.22508)
		(end 313.171332 -101.14915)
		(width 0.11684)
		(layer "In6.Cu")
		(net "PWRGD_PVDDCR_SOC_P0")
	)
	(segment
		(start 260.36524 -98.941128)
		(end 258.15798 -101.148388)
		(width 0.11684)
		(layer "In6.Cu")
		(net "PWRGD_PVDDCR_SOC_P0")
	)
	(segment
		(start 26.009092 -365.76)
		(end 26.660094 -365.108998)
		(width 0.10668)
		(layer "F.Cu")
		(net "PWRGD_PVDDCR_CPU1_P1_R")
	)
	(segment
		(start 25.16505 -365.76)
		(end 26.009092 -365.76)
		(width 0.10668)
		(layer "F.Cu")
		(net "PWRGD_PVDDCR_CPU1_P1_R")
	)
	(segment
		(start 26.660094 -365.108998)
		(end 27.604974 -365.108998)
		(width 0.10668)
		(layer "F.Cu")
		(net "PWRGD_PVDDCR_CPU1_P1_R")
	)
	(via
		(at 26.009092 -365.76)
		(size 0.508)
		(drill 0.254)
		(layers "F.Cu" "B.Cu")
		(net "PWRGD_PVDDCR_CPU1_P1_R")
	)
	(segment
		(start 25.16505 -365.76)
		(end 26.009092 -365.76)
		(width 0.10668)
		(layer "B.Cu")
		(net "PWRGD_PVDDCR_CPU1_P1_R")
	)
	(segment
		(start 25.16505 -366.7379)
		(end 25.146 -366.75695)
		(width 0.10668)
		(layer "B.Cu")
		(net "PWRGD_PVDDCR_CPU1_P1_R")
	)
	(segment
		(start 25.16505 -365.76)
		(end 25.16505 -366.7379)
		(width 0.10668)
		(layer "B.Cu")
		(net "PWRGD_PVDDCR_CPU1_P1_R")
	)
	(via
		(at 95.48749 -112.620044)
		(size 0.508)
		(drill 0.254)
		(layers "F.Cu" "B.Cu")
		(net "PWRGD_PVDDCR_CPU1_P1")
	)
	(via
		(at 212.852 -107.533948)
		(size 0.508)
		(drill 0.254)
		(layers "F.Cu" "B.Cu")
		(net "PWRGD_PVDDCR_CPU1_P1")
	)
	(via
		(at 20.675854 -364.77067)
		(size 0.508)
		(drill 0.254)
		(layers "F.Cu" "B.Cu")
		(net "PWRGD_PVDDCR_CPU1_P1")
	)
	(via
		(at 210.653376 -90.480896)
		(size 0.508)
		(drill 0.254)
		(layers "F.Cu" "B.Cu")
		(net "PWRGD_PVDDCR_CPU1_P1")
	)
	(via
		(at 210.03641 -79.207868)
		(size 0.508)
		(drill 0.254)
		(layers "F.Cu" "B.Cu")
		(net "PWRGD_PVDDCR_CPU1_P1")
	)
	(segment
		(start 198.14413 -109.019848)
		(end 200.35774 -109.019848)
		(width 0.10668)
		(layer "B.Cu")
		(net "PWRGD_PVDDCR_CPU1_P1")
	)
	(segment
		(start 21.119846 -365.214662)
		(end 20.675854 -364.77067)
		(width 0.10668)
		(layer "B.Cu")
		(net "PWRGD_PVDDCR_CPU1_P1")
	)
	(segment
		(start 201.785982 -104.523032)
		(end 205.412848 -104.523032)
		(width 0.10668)
		(layer "B.Cu")
		(net "PWRGD_PVDDCR_CPU1_P1")
	)
	(segment
		(start 23.879556 -365.274606)
		(end 23.364444 -365.274606)
		(width 0.10668)
		(layer "B.Cu")
		(net "PWRGD_PVDDCR_CPU1_P1")
	)
	(segment
		(start 22.87905 -365.76)
		(end 22.87905 -365.44123)
		(width 0.10668)
		(layer "B.Cu")
		(net "PWRGD_PVDDCR_CPU1_P1")
	)
	(segment
		(start 22.87905 -365.44123)
		(end 22.652482 -365.214662)
		(width 0.10668)
		(layer "B.Cu")
		(net "PWRGD_PVDDCR_CPU1_P1")
	)
	(segment
		(start 23.364444 -365.274606)
		(end 22.87905 -365.76)
		(width 0.10668)
		(layer "B.Cu")
		(net "PWRGD_PVDDCR_CPU1_P1")
	)
	(segment
		(start 24.36495 -365.76)
		(end 23.879556 -365.274606)
		(width 0.10668)
		(layer "B.Cu")
		(net "PWRGD_PVDDCR_CPU1_P1")
	)
	(segment
		(start 212.852 -107.339638)
		(end 212.852 -107.533948)
		(width 0.10668)
		(layer "B.Cu")
		(net "PWRGD_PVDDCR_CPU1_P1")
	)
	(segment
		(start 210.459066 -104.946704)
		(end 212.852 -107.339638)
		(width 0.10668)
		(layer "B.Cu")
		(net "PWRGD_PVDDCR_CPU1_P1")
	)
	(segment
		(start 22.652482 -365.214662)
		(end 21.119846 -365.214662)
		(width 0.10668)
		(layer "B.Cu")
		(net "PWRGD_PVDDCR_CPU1_P1")
	)
	(segment
		(start 197.669658 -108.545376)
		(end 198.14413 -109.019848)
		(width 0.10668)
		(layer "B.Cu")
		(net "PWRGD_PVDDCR_CPU1_P1")
	)
	(segment
		(start 200.35774 -109.019848)
		(end 200.983088 -108.3945)
		(width 0.10668)
		(layer "B.Cu")
		(net "PWRGD_PVDDCR_CPU1_P1")
	)
	(segment
		(start 200.983088 -108.3945)
		(end 200.983088 -105.325926)
		(width 0.10668)
		(layer "B.Cu")
		(net "PWRGD_PVDDCR_CPU1_P1")
	)
	(segment
		(start 205.83652 -104.946704)
		(end 210.459066 -104.946704)
		(width 0.10668)
		(layer "B.Cu")
		(net "PWRGD_PVDDCR_CPU1_P1")
	)
	(segment
		(start 200.983088 -105.325926)
		(end 201.785982 -104.523032)
		(width 0.10668)
		(layer "B.Cu")
		(net "PWRGD_PVDDCR_CPU1_P1")
	)
	(segment
		(start 205.412848 -104.523032)
		(end 205.83652 -104.946704)
		(width 0.10668)
		(layer "B.Cu")
		(net "PWRGD_PVDDCR_CPU1_P1")
	)
	(segment
		(start 12.998704 -166.756588)
		(end 16.590518 -163.164774)
		(width 0.11684)
		(layer "In4.Cu")
		(net "PWRGD_PVDDCR_CPU1_P1")
	)
	(segment
		(start 16.090646 -359.497884)
		(end 16.090646 -345.317064)
		(width 0.11684)
		(layer "In4.Cu")
		(net "PWRGD_PVDDCR_CPU1_P1")
	)
	(segment
		(start 68.15836 -137.397998)
		(end 78.808326 -126.748032)
		(width 0.11684)
		(layer "In4.Cu")
		(net "PWRGD_PVDDCR_CPU1_P1")
	)
	(segment
		(start 210.653376 -90.480896)
		(end 211.378546 -89.755726)
		(width 0.11684)
		(layer "In4.Cu")
		(net "PWRGD_PVDDCR_CPU1_P1")
	)
	(segment
		(start 5.954776 -167.955722)
		(end 7.15391 -166.756588)
		(width 0.11684)
		(layer "In4.Cu")
		(net "PWRGD_PVDDCR_CPU1_P1")
	)
	(segment
		(start 16.090646 -345.317064)
		(end 5.954776 -335.181194)
		(width 0.11684)
		(layer "In4.Cu")
		(net "PWRGD_PVDDCR_CPU1_P1")
	)
	(segment
		(start 81.641442 -126.748032)
		(end 95.48749 -112.901984)
		(width 0.11684)
		(layer "In4.Cu")
		(net "PWRGD_PVDDCR_CPU1_P1")
	)
	(segment
		(start 5.954776 -335.181194)
		(end 5.954776 -167.955722)
		(width 0.11684)
		(layer "In4.Cu")
		(net "PWRGD_PVDDCR_CPU1_P1")
	)
	(segment
		(start 211.941156 -84.431124)
		(end 212.228684 -84.143596)
		(width 0.11684)
		(layer "In4.Cu")
		(net "PWRGD_PVDDCR_CPU1_P1")
	)
	(segment
		(start 211.378546 -89.755726)
		(end 211.378546 -85.111082)
		(width 0.11684)
		(layer "In4.Cu")
		(net "PWRGD_PVDDCR_CPU1_P1")
	)
	(segment
		(start 211.941156 -84.548472)
		(end 211.941156 -84.431124)
		(width 0.11684)
		(layer "In4.Cu")
		(net "PWRGD_PVDDCR_CPU1_P1")
	)
	(segment
		(start 33.42767 -137.397998)
		(end 68.15836 -137.397998)
		(width 0.11684)
		(layer "In4.Cu")
		(net "PWRGD_PVDDCR_CPU1_P1")
	)
	(segment
		(start 212.228684 -84.143596)
		(end 212.228684 -82.771742)
		(width 0.11684)
		(layer "In4.Cu")
		(net "PWRGD_PVDDCR_CPU1_P1")
	)
	(segment
		(start 16.590518 -163.164774)
		(end 16.590518 -154.23515)
		(width 0.11684)
		(layer "In4.Cu")
		(net "PWRGD_PVDDCR_CPU1_P1")
	)
	(segment
		(start 211.378546 -85.111082)
		(end 211.941156 -84.548472)
		(width 0.11684)
		(layer "In4.Cu")
		(net "PWRGD_PVDDCR_CPU1_P1")
	)
	(segment
		(start 211.379816 -80.701642)
		(end 210.03641 -79.358236)
		(width 0.11684)
		(layer "In4.Cu")
		(net "PWRGD_PVDDCR_CPU1_P1")
	)
	(segment
		(start 16.590518 -154.23515)
		(end 33.42767 -137.397998)
		(width 0.11684)
		(layer "In4.Cu")
		(net "PWRGD_PVDDCR_CPU1_P1")
	)
	(segment
		(start 7.15391 -166.756588)
		(end 12.998704 -166.756588)
		(width 0.11684)
		(layer "In4.Cu")
		(net "PWRGD_PVDDCR_CPU1_P1")
	)
	(segment
		(start 20.675854 -364.77067)
		(end 20.675854 -364.083092)
		(width 0.11684)
		(layer "In4.Cu")
		(net "PWRGD_PVDDCR_CPU1_P1")
	)
	(segment
		(start 210.03641 -79.358236)
		(end 210.03641 -79.207868)
		(width 0.11684)
		(layer "In4.Cu")
		(net "PWRGD_PVDDCR_CPU1_P1")
	)
	(segment
		(start 95.48749 -112.901984)
		(end 95.48749 -112.620044)
		(width 0.11684)
		(layer "In4.Cu")
		(net "PWRGD_PVDDCR_CPU1_P1")
	)
	(segment
		(start 78.808326 -126.748032)
		(end 81.641442 -126.748032)
		(width 0.11684)
		(layer "In4.Cu")
		(net "PWRGD_PVDDCR_CPU1_P1")
	)
	(segment
		(start 212.228684 -82.771742)
		(end 211.379816 -81.922874)
		(width 0.11684)
		(layer "In4.Cu")
		(net "PWRGD_PVDDCR_CPU1_P1")
	)
	(segment
		(start 211.379816 -81.922874)
		(end 211.379816 -80.701642)
		(width 0.11684)
		(layer "In4.Cu")
		(net "PWRGD_PVDDCR_CPU1_P1")
	)
	(segment
		(start 20.675854 -364.083092)
		(end 16.090646 -359.497884)
		(width 0.11684)
		(layer "In4.Cu")
		(net "PWRGD_PVDDCR_CPU1_P1")
	)
	(segment
		(start 95.48749 -112.08385)
		(end 98.33356 -109.23778)
		(width 0.11684)
		(layer "In6.Cu")
		(net "PWRGD_PVDDCR_CPU1_P1")
	)
	(segment
		(start 98.33356 -109.23778)
		(end 122.598434 -109.23778)
		(width 0.11684)
		(layer "In6.Cu")
		(net "PWRGD_PVDDCR_CPU1_P1")
	)
	(segment
		(start 198.28256 -80.440276)
		(end 208.804002 -80.440276)
		(width 0.11684)
		(layer "In6.Cu")
		(net "PWRGD_PVDDCR_CPU1_P1")
	)
	(segment
		(start 155.704794 -84.927694)
		(end 159.24911 -81.383378)
		(width 0.11684)
		(layer "In6.Cu")
		(net "PWRGD_PVDDCR_CPU1_P1")
	)
	(segment
		(start 174.865792 -81.383124)
		(end 178.360324 -81.383124)
		(width 0.11684)
		(layer "In6.Cu")
		(net "PWRGD_PVDDCR_CPU1_P1")
	)
	(segment
		(start 122.598434 -109.23778)
		(end 127.45339 -104.382824)
		(width 0.11684)
		(layer "In6.Cu")
		(net "PWRGD_PVDDCR_CPU1_P1")
	)
	(segment
		(start 127.45339 -103.53294)
		(end 146.058636 -84.927694)
		(width 0.11684)
		(layer "In6.Cu")
		(net "PWRGD_PVDDCR_CPU1_P1")
	)
	(segment
		(start 146.058636 -84.927694)
		(end 155.704794 -84.927694)
		(width 0.11684)
		(layer "In6.Cu")
		(net "PWRGD_PVDDCR_CPU1_P1")
	)
	(segment
		(start 95.48749 -112.620044)
		(end 95.48749 -112.08385)
		(width 0.11684)
		(layer "In6.Cu")
		(net "PWRGD_PVDDCR_CPU1_P1")
	)
	(segment
		(start 178.360324 -81.383124)
		(end 178.360578 -81.383378)
		(width 0.11684)
		(layer "In6.Cu")
		(net "PWRGD_PVDDCR_CPU1_P1")
	)
	(segment
		(start 174.865538 -81.383378)
		(end 174.865792 -81.383124)
		(width 0.11684)
		(layer "In6.Cu")
		(net "PWRGD_PVDDCR_CPU1_P1")
	)
	(segment
		(start 127.45339 -104.382824)
		(end 127.45339 -103.53294)
		(width 0.11684)
		(layer "In6.Cu")
		(net "PWRGD_PVDDCR_CPU1_P1")
	)
	(segment
		(start 159.24911 -81.383378)
		(end 174.865538 -81.383378)
		(width 0.11684)
		(layer "In6.Cu")
		(net "PWRGD_PVDDCR_CPU1_P1")
	)
	(segment
		(start 178.360578 -81.383378)
		(end 184.095136 -81.383378)
		(width 0.11684)
		(layer "In6.Cu")
		(net "PWRGD_PVDDCR_CPU1_P1")
	)
	(segment
		(start 194.29349 -73.903332)
		(end 194.29349 -76.451206)
		(width 0.11684)
		(layer "In6.Cu")
		(net "PWRGD_PVDDCR_CPU1_P1")
	)
	(segment
		(start 208.804002 -80.440276)
		(end 210.03641 -79.207868)
		(width 0.11684)
		(layer "In6.Cu")
		(net "PWRGD_PVDDCR_CPU1_P1")
	)
	(segment
		(start 194.29349 -76.451206)
		(end 198.28256 -80.440276)
		(width 0.11684)
		(layer "In6.Cu")
		(net "PWRGD_PVDDCR_CPU1_P1")
	)
	(segment
		(start 193.86296 -73.472802)
		(end 194.29349 -73.903332)
		(width 0.11684)
		(layer "In6.Cu")
		(net "PWRGD_PVDDCR_CPU1_P1")
	)
	(segment
		(start 184.095136 -81.383378)
		(end 192.005712 -73.472802)
		(width 0.11684)
		(layer "In6.Cu")
		(net "PWRGD_PVDDCR_CPU1_P1")
	)
	(segment
		(start 192.005712 -73.472802)
		(end 193.86296 -73.472802)
		(width 0.11684)
		(layer "In6.Cu")
		(net "PWRGD_PVDDCR_CPU1_P1")
	)
	(segment
		(start 213.985348 -100.293932)
		(end 213.112858 -99.421442)
		(width 0.11684)
		(layer "In11.Cu")
		(net "PWRGD_PVDDCR_CPU1_P1")
	)
	(segment
		(start 213.985348 -98.06686)
		(end 213.985348 -93.812868)
		(width 0.11684)
		(layer "In11.Cu")
		(net "PWRGD_PVDDCR_CPU1_P1")
	)
	(segment
		(start 213.112858 -98.93935)
		(end 213.985348 -98.06686)
		(width 0.11684)
		(layer "In11.Cu")
		(net "PWRGD_PVDDCR_CPU1_P1")
	)
	(segment
		(start 212.852 -106.318812)
		(end 213.985348 -105.185464)
		(width 0.11684)
		(layer "In11.Cu")
		(net "PWRGD_PVDDCR_CPU1_P1")
	)
	(segment
		(start 213.985348 -93.812868)
		(end 210.653376 -90.480896)
		(width 0.11684)
		(layer "In11.Cu")
		(net "PWRGD_PVDDCR_CPU1_P1")
	)
	(segment
		(start 213.112858 -99.421442)
		(end 213.112858 -98.93935)
		(width 0.11684)
		(layer "In11.Cu")
		(net "PWRGD_PVDDCR_CPU1_P1")
	)
	(segment
		(start 213.985348 -105.185464)
		(end 213.985348 -100.293932)
		(width 0.11684)
		(layer "In11.Cu")
		(net "PWRGD_PVDDCR_CPU1_P1")
	)
	(segment
		(start 212.852 -107.533948)
		(end 212.852 -106.318812)
		(width 0.11684)
		(layer "In11.Cu")
		(net "PWRGD_PVDDCR_CPU1_P1")
	)
	(segment
		(start 306.024026 -362.300774)
		(end 306.644802 -361.679998)
		(width 0.10668)
		(layer "F.Cu")
		(net "PWRGD_PVDDCR_CPU1_P0_R")
	)
	(segment
		(start 306.644802 -361.679998)
		(end 307.258974 -361.679998)
		(width 0.10668)
		(layer "F.Cu")
		(net "PWRGD_PVDDCR_CPU1_P0_R")
	)
	(segment
		(start 305.606196 -363.669326)
		(end 305.606196 -363.309154)
		(width 0.10668)
		(layer "F.Cu")
		(net "PWRGD_PVDDCR_CPU1_P0_R")
	)
	(segment
		(start 304.81905 -363.982)
		(end 304.31105 -363.474)
		(width 0.10668)
		(layer "F.Cu")
		(net "PWRGD_PVDDCR_CPU1_P0_R")
	)
	(segment
		(start 305.42865 -363.846872)
		(end 305.606196 -363.669326)
		(width 0.10668)
		(layer "F.Cu")
		(net "PWRGD_PVDDCR_CPU1_P0_R")
	)
	(segment
		(start 305.293522 -363.982)
		(end 305.42865 -363.846872)
		(width 0.10668)
		(layer "F.Cu")
		(net "PWRGD_PVDDCR_CPU1_P0_R")
	)
	(segment
		(start 302.55845 -362.839)
		(end 302.55845 -363.982)
		(width 0.10668)
		(layer "F.Cu")
		(net "PWRGD_PVDDCR_CPU1_P0_R")
	)
	(segment
		(start 303.19345 -363.474)
		(end 302.55845 -362.839)
		(width 0.10668)
		(layer "F.Cu")
		(net "PWRGD_PVDDCR_CPU1_P0_R")
	)
	(segment
		(start 304.31105 -363.474)
		(end 303.19345 -363.474)
		(width 0.10668)
		(layer "F.Cu")
		(net "PWRGD_PVDDCR_CPU1_P0_R")
	)
	(segment
		(start 305.606196 -363.309154)
		(end 306.024026 -362.300774)
		(width 0.10668)
		(layer "F.Cu")
		(net "PWRGD_PVDDCR_CPU1_P0_R")
	)
	(segment
		(start 304.81905 -363.982)
		(end 305.293522 -363.982)
		(width 0.10668)
		(layer "F.Cu")
		(net "PWRGD_PVDDCR_CPU1_P0_R")
	)
	(via
		(at 305.42865 -363.846872)
		(size 0.508)
		(drill 0.254)
		(layers "F.Cu" "B.Cu")
		(net "PWRGD_PVDDCR_CPU1_P0_R")
	)
	(segment
		(start 222.004128 -165.39972)
		(end 220.629988 -164.02558)
		(width 0.10668)
		(layer "F.Cu")
		(net "PWRGD_PVDDCR_CPU1_P0")
	)
	(segment
		(start 220.465904 -127.803148)
		(end 220.332046 -127.66929)
		(width 0.10668)
		(layer "F.Cu")
		(net "PWRGD_PVDDCR_CPU1_P0")
	)
	(segment
		(start 220.332046 -127.66929)
		(end 220.332046 -125.124718)
		(width 0.10668)
		(layer "F.Cu")
		(net "PWRGD_PVDDCR_CPU1_P0")
	)
	(segment
		(start 222.004128 -167.143938)
		(end 222.004128 -165.39972)
		(width 0.10668)
		(layer "F.Cu")
		(net "PWRGD_PVDDCR_CPU1_P0")
	)
	(segment
		(start 300.78045 -363.982)
		(end 300.78045 -364.6424)
		(width 0.10668)
		(layer "F.Cu")
		(net "PWRGD_PVDDCR_CPU1_P0")
	)
	(segment
		(start 217.000074 -116.04244)
		(end 219.76842 -113.274094)
		(width 0.10668)
		(layer "F.Cu")
		(net "PWRGD_PVDDCR_CPU1_P0")
	)
	(segment
		(start 294.346122 -372.149878)
		(end 284.491684 -372.149878)
		(width 0.10668)
		(layer "F.Cu")
		(net "PWRGD_PVDDCR_CPU1_P0")
	)
	(segment
		(start 219.76842 -108.49102)
		(end 217.83294 -106.55554)
		(width 0.10668)
		(layer "F.Cu")
		(net "PWRGD_PVDDCR_CPU1_P0")
	)
	(segment
		(start 223.455484 -329.070716)
		(end 217.139012 -322.754244)
		(width 0.10668)
		(layer "F.Cu")
		(net "PWRGD_PVDDCR_CPU1_P0")
	)
	(segment
		(start 232.262934 -365.576612)
		(end 231.97058 -365.868966)
		(width 0.10668)
		(layer "F.Cu")
		(net "PWRGD_PVDDCR_CPU1_P0")
	)
	(segment
		(start 224.404682 -335.005172)
		(end 223.455484 -334.055974)
		(width 0.10668)
		(layer "F.Cu")
		(net "PWRGD_PVDDCR_CPU1_P0")
	)
	(segment
		(start 220.629988 -164.02558)
		(end 219.239846 -164.02558)
		(width 0.10668)
		(layer "F.Cu")
		(net "PWRGD_PVDDCR_CPU1_P0")
	)
	(segment
		(start 217.069162 -104.880156)
		(end 216.977468 -104.880156)
		(width 0.10668)
		(layer "F.Cu")
		(net "PWRGD_PVDDCR_CPU1_P0")
	)
	(segment
		(start 218.712288 -157.897576)
		(end 218.916758 -157.693106)
		(width 0.10668)
		(layer "F.Cu")
		(net "PWRGD_PVDDCR_CPU1_P0")
	)
	(segment
		(start 218.916758 -157.693106)
		(end 218.916758 -138.379454)
		(width 0.10668)
		(layer "F.Cu")
		(net "PWRGD_PVDDCR_CPU1_P0")
	)
	(segment
		(start 223.455484 -334.055974)
		(end 223.455484 -329.070716)
		(width 0.10668)
		(layer "F.Cu")
		(net "PWRGD_PVDDCR_CPU1_P0")
	)
	(segment
		(start 217.83294 -105.643934)
		(end 217.069162 -104.880156)
		(width 0.10668)
		(layer "F.Cu")
		(net "PWRGD_PVDDCR_CPU1_P0")
	)
	(segment
		(start 217.51036 -119.645176)
		(end 217.000074 -119.13489)
		(width 0.10668)
		(layer "F.Cu")
		(net "PWRGD_PVDDCR_CPU1_P0")
	)
	(segment
		(start 253.092966 -369.89893)
		(end 248.770648 -365.576612)
		(width 0.10668)
		(layer "F.Cu")
		(net "PWRGD_PVDDCR_CPU1_P0")
	)
	(segment
		(start 217.000074 -119.13489)
		(end 217.000074 -116.04244)
		(width 0.10668)
		(layer "F.Cu")
		(net "PWRGD_PVDDCR_CPU1_P0")
	)
	(segment
		(start 221.513146 -202.15098)
		(end 222.85325 -200.810876)
		(width 0.10668)
		(layer "F.Cu")
		(net "PWRGD_PVDDCR_CPU1_P0")
	)
	(segment
		(start 220.83014 -129.862834)
		(end 220.465904 -129.498598)
		(width 0.10668)
		(layer "F.Cu")
		(net "PWRGD_PVDDCR_CPU1_P0")
	)
	(segment
		(start 294.8305 -371.6655)
		(end 294.346122 -372.149878)
		(width 0.10668)
		(layer "F.Cu")
		(net "PWRGD_PVDDCR_CPU1_P0")
	)
	(segment
		(start 284.491684 -372.149878)
		(end 282.240736 -369.89893)
		(width 0.10668)
		(layer "F.Cu")
		(net "PWRGD_PVDDCR_CPU1_P0")
	)
	(segment
		(start 217.83294 -106.55554)
		(end 217.83294 -105.643934)
		(width 0.10668)
		(layer "F.Cu")
		(net "PWRGD_PVDDCR_CPU1_P0")
	)
	(segment
		(start 217.981276 -208.131918)
		(end 219.232988 -208.131918)
		(width 0.10668)
		(layer "F.Cu")
		(net "PWRGD_PVDDCR_CPU1_P0")
	)
	(segment
		(start 248.770648 -365.576612)
		(end 232.262934 -365.576612)
		(width 0.10668)
		(layer "F.Cu")
		(net "PWRGD_PVDDCR_CPU1_P0")
	)
	(segment
		(start 301.75835 -363.982)
		(end 300.78045 -363.982)
		(width 0.10668)
		(layer "F.Cu")
		(net "PWRGD_PVDDCR_CPU1_P0")
	)
	(segment
		(start 282.240736 -369.89893)
		(end 253.092966 -369.89893)
		(width 0.10668)
		(layer "F.Cu")
		(net "PWRGD_PVDDCR_CPU1_P0")
	)
	(segment
		(start 217.51036 -122.303032)
		(end 217.51036 -119.645176)
		(width 0.10668)
		(layer "F.Cu")
		(net "PWRGD_PVDDCR_CPU1_P0")
	)
	(segment
		(start 216.977468 -104.880156)
		(end 216.977468 -104.879394)
		(width 0.10668)
		(layer "F.Cu")
		(net "PWRGD_PVDDCR_CPU1_P0")
	)
	(segment
		(start 220.465904 -129.498598)
		(end 220.465904 -127.803148)
		(width 0.10668)
		(layer "F.Cu")
		(net "PWRGD_PVDDCR_CPU1_P0")
	)
	(segment
		(start 218.916758 -138.379454)
		(end 220.83014 -136.466072)
		(width 0.10668)
		(layer "F.Cu")
		(net "PWRGD_PVDDCR_CPU1_P0")
	)
	(segment
		(start 220.332046 -125.124718)
		(end 217.51036 -122.303032)
		(width 0.10668)
		(layer "F.Cu")
		(net "PWRGD_PVDDCR_CPU1_P0")
	)
	(segment
		(start 219.76842 -113.274094)
		(end 219.76842 -108.49102)
		(width 0.10668)
		(layer "F.Cu")
		(net "PWRGD_PVDDCR_CPU1_P0")
	)
	(segment
		(start 223.56699 -197.553072)
		(end 223.56699 -168.7068)
		(width 0.10668)
		(layer "F.Cu")
		(net "PWRGD_PVDDCR_CPU1_P0")
	)
	(segment
		(start 223.56699 -168.7068)
		(end 222.004128 -167.143938)
		(width 0.10668)
		(layer "F.Cu")
		(net "PWRGD_PVDDCR_CPU1_P0")
	)
	(segment
		(start 225.135948 -362.959142)
		(end 225.135948 -341.02167)
		(width 0.10668)
		(layer "F.Cu")
		(net "PWRGD_PVDDCR_CPU1_P0")
	)
	(segment
		(start 221.513146 -205.85176)
		(end 221.513146 -202.15098)
		(width 0.10668)
		(layer "F.Cu")
		(net "PWRGD_PVDDCR_CPU1_P0")
	)
	(segment
		(start 220.83014 -136.466072)
		(end 220.83014 -129.862834)
		(width 0.10668)
		(layer "F.Cu")
		(net "PWRGD_PVDDCR_CPU1_P0")
	)
	(segment
		(start 222.85325 -200.810876)
		(end 222.85325 -198.266812)
		(width 0.10668)
		(layer "F.Cu")
		(net "PWRGD_PVDDCR_CPU1_P0")
	)
	(segment
		(start 216.977468 -104.879394)
		(end 216.976706 -104.879394)
		(width 0.10668)
		(layer "F.Cu")
		(net "PWRGD_PVDDCR_CPU1_P0")
	)
	(segment
		(start 217.139012 -322.754244)
		(end 217.139012 -208.974182)
		(width 0.10668)
		(layer "F.Cu")
		(net "PWRGD_PVDDCR_CPU1_P0")
	)
	(segment
		(start 219.232988 -208.131918)
		(end 221.513146 -205.85176)
		(width 0.10668)
		(layer "F.Cu")
		(net "PWRGD_PVDDCR_CPU1_P0")
	)
	(segment
		(start 224.404682 -340.290404)
		(end 224.404682 -335.005172)
		(width 0.10668)
		(layer "F.Cu")
		(net "PWRGD_PVDDCR_CPU1_P0")
	)
	(segment
		(start 217.139012 -208.974182)
		(end 217.981276 -208.131918)
		(width 0.10668)
		(layer "F.Cu")
		(net "PWRGD_PVDDCR_CPU1_P0")
	)
	(segment
		(start 222.85325 -198.266812)
		(end 223.56699 -197.553072)
		(width 0.10668)
		(layer "F.Cu")
		(net "PWRGD_PVDDCR_CPU1_P0")
	)
	(segment
		(start 219.239846 -164.02558)
		(end 218.712288 -163.498022)
		(width 0.10668)
		(layer "F.Cu")
		(net "PWRGD_PVDDCR_CPU1_P0")
	)
	(segment
		(start 225.135948 -341.02167)
		(end 224.404682 -340.290404)
		(width 0.10668)
		(layer "F.Cu")
		(net "PWRGD_PVDDCR_CPU1_P0")
	)
	(segment
		(start 218.712288 -163.498022)
		(end 218.712288 -157.897576)
		(width 0.10668)
		(layer "F.Cu")
		(net "PWRGD_PVDDCR_CPU1_P0")
	)
	(via
		(at 300.78045 -364.6424)
		(size 0.508)
		(drill 0.254)
		(layers "F.Cu" "B.Cu")
		(net "PWRGD_PVDDCR_CPU1_P0")
	)
	(via
		(at 225.135948 -362.959142)
		(size 0.508)
		(drill 0.254)
		(layers "F.Cu" "B.Cu")
		(net "PWRGD_PVDDCR_CPU1_P0")
	)
	(via
		(at 231.97058 -365.868966)
		(size 0.508)
		(drill 0.254)
		(layers "F.Cu" "B.Cu")
		(net "PWRGD_PVDDCR_CPU1_P0")
	)
	(via
		(at 294.8305 -371.6655)
		(size 0.508)
		(drill 0.254)
		(layers "F.Cu" "B.Cu")
		(net "PWRGD_PVDDCR_CPU1_P0")
	)
	(via
		(at 379.903228 -120.218708)
		(size 0.508)
		(drill 0.254)
		(layers "F.Cu" "B.Cu")
		(net "PWRGD_PVDDCR_CPU1_P0")
	)
	(via
		(at 216.976706 -104.879394)
		(size 0.508)
		(drill 0.254)
		(layers "F.Cu" "B.Cu")
		(net "PWRGD_PVDDCR_CPU1_P0")
	)
	(segment
		(start 216.977468 -104.879394)
		(end 216.976706 -104.879394)
		(width 0.10668)
		(layer "B.Cu")
		(net "PWRGD_PVDDCR_CPU1_P0")
	)
	(segment
		(start 216.354914 -103.419656)
		(end 216.977468 -104.04221)
		(width 0.10668)
		(layer "B.Cu")
		(net "PWRGD_PVDDCR_CPU1_P0")
	)
	(segment
		(start 209.218276 -102.375208)
		(end 209.748628 -102.375208)
		(width 0.10668)
		(layer "B.Cu")
		(net "PWRGD_PVDDCR_CPU1_P0")
	)
	(segment
		(start 199.129142 -102.345744)
		(end 199.686164 -101.788722)
		(width 0.10668)
		(layer "B.Cu")
		(net "PWRGD_PVDDCR_CPU1_P0")
	)
	(segment
		(start 199.129142 -102.746556)
		(end 199.129142 -102.345744)
		(width 0.10668)
		(layer "B.Cu")
		(net "PWRGD_PVDDCR_CPU1_P0")
	)
	(segment
		(start 198.410322 -103.465376)
		(end 199.129142 -102.746556)
		(width 0.10668)
		(layer "B.Cu")
		(net "PWRGD_PVDDCR_CPU1_P0")
	)
	(segment
		(start 206.072232 -102.033578)
		(end 206.072232 -102.797356)
		(width 0.10668)
		(layer "B.Cu")
		(net "PWRGD_PVDDCR_CPU1_P0")
	)
	(segment
		(start 209.748628 -102.375208)
		(end 210.348068 -102.974648)
		(width 0.10668)
		(layer "B.Cu")
		(net "PWRGD_PVDDCR_CPU1_P0")
	)
	(segment
		(start 206.344012 -103.069136)
		(end 208.524348 -103.069136)
		(width 0.10668)
		(layer "B.Cu")
		(net "PWRGD_PVDDCR_CPU1_P0")
	)
	(segment
		(start 200.086976 -101.788722)
		(end 200.697084 -101.178614)
		(width 0.10668)
		(layer "B.Cu")
		(net "PWRGD_PVDDCR_CPU1_P0")
	)
	(segment
		(start 205.217268 -101.178614)
		(end 206.072232 -102.033578)
		(width 0.10668)
		(layer "B.Cu")
		(net "PWRGD_PVDDCR_CPU1_P0")
	)
	(segment
		(start 200.697084 -101.178614)
		(end 205.217268 -101.178614)
		(width 0.10668)
		(layer "B.Cu")
		(net "PWRGD_PVDDCR_CPU1_P0")
	)
	(segment
		(start 216.977468 -104.04221)
		(end 216.977468 -104.879394)
		(width 0.10668)
		(layer "B.Cu")
		(net "PWRGD_PVDDCR_CPU1_P0")
	)
	(segment
		(start 212.085682 -102.974648)
		(end 212.53069 -103.419656)
		(width 0.10668)
		(layer "B.Cu")
		(net "PWRGD_PVDDCR_CPU1_P0")
	)
	(segment
		(start 197.923658 -103.465376)
		(end 198.410322 -103.465376)
		(width 0.10668)
		(layer "B.Cu")
		(net "PWRGD_PVDDCR_CPU1_P0")
	)
	(segment
		(start 208.524348 -103.069136)
		(end 209.218276 -102.375208)
		(width 0.10668)
		(layer "B.Cu")
		(net "PWRGD_PVDDCR_CPU1_P0")
	)
	(segment
		(start 206.072232 -102.797356)
		(end 206.344012 -103.069136)
		(width 0.10668)
		(layer "B.Cu")
		(net "PWRGD_PVDDCR_CPU1_P0")
	)
	(segment
		(start 210.348068 -102.974648)
		(end 212.085682 -102.974648)
		(width 0.10668)
		(layer "B.Cu")
		(net "PWRGD_PVDDCR_CPU1_P0")
	)
	(segment
		(start 212.53069 -103.419656)
		(end 216.354914 -103.419656)
		(width 0.10668)
		(layer "B.Cu")
		(net "PWRGD_PVDDCR_CPU1_P0")
	)
	(segment
		(start 199.686164 -101.788722)
		(end 200.086976 -101.788722)
		(width 0.10668)
		(layer "B.Cu")
		(net "PWRGD_PVDDCR_CPU1_P0")
	)
	(segment
		(start 225.135948 -362.959142)
		(end 229.060756 -362.959142)
		(width 0.11684)
		(layer "In2.Cu")
		(net "PWRGD_PVDDCR_CPU1_P0")
	)
	(segment
		(start 229.060756 -362.959142)
		(end 231.97058 -365.868966)
		(width 0.11684)
		(layer "In2.Cu")
		(net "PWRGD_PVDDCR_CPU1_P0")
	)
	(segment
		(start 368.93373 -113.29162)
		(end 372.97614 -113.29162)
		(width 0.11684)
		(layer "In6.Cu")
		(net "PWRGD_PVDDCR_CPU1_P0")
	)
	(segment
		(start 216.976706 -104.879394)
		(end 217.450416 -105.353104)
		(width 0.11684)
		(layer "In6.Cu")
		(net "PWRGD_PVDDCR_CPU1_P0")
	)
	(segment
		(start 372.97614 -113.29162)
		(end 379.903228 -120.218708)
		(width 0.11684)
		(layer "In6.Cu")
		(net "PWRGD_PVDDCR_CPU1_P0")
	)
	(segment
		(start 321.709796 -112.856264)
		(end 368.498374 -112.856264)
		(width 0.11684)
		(layer "In6.Cu")
		(net "PWRGD_PVDDCR_CPU1_P0")
	)
	(segment
		(start 314.90412 -106.050588)
		(end 321.709796 -112.856264)
		(width 0.11684)
		(layer "In6.Cu")
		(net "PWRGD_PVDDCR_CPU1_P0")
	)
	(segment
		(start 368.498374 -112.856264)
		(end 368.93373 -113.29162)
		(width 0.11684)
		(layer "In6.Cu")
		(net "PWRGD_PVDDCR_CPU1_P0")
	)
	(segment
		(start 218.215718 -106.022648)
		(end 259.931662 -106.022648)
		(width 0.11684)
		(layer "In6.Cu")
		(net "PWRGD_PVDDCR_CPU1_P0")
	)
	(segment
		(start 276.53742 -106.050588)
		(end 314.90412 -106.050588)
		(width 0.11684)
		(layer "In6.Cu")
		(net "PWRGD_PVDDCR_CPU1_P0")
	)
	(segment
		(start 217.546174 -105.353104)
		(end 218.215718 -106.022648)
		(width 0.11684)
		(layer "In6.Cu")
		(net "PWRGD_PVDDCR_CPU1_P0")
	)
	(segment
		(start 259.931662 -106.022648)
		(end 260.384036 -106.475022)
		(width 0.11684)
		(layer "In6.Cu")
		(net "PWRGD_PVDDCR_CPU1_P0")
	)
	(segment
		(start 260.384036 -106.475022)
		(end 276.112986 -106.475022)
		(width 0.11684)
		(layer "In6.Cu")
		(net "PWRGD_PVDDCR_CPU1_P0")
	)
	(segment
		(start 276.112986 -106.475022)
		(end 276.53742 -106.050588)
		(width 0.11684)
		(layer "In6.Cu")
		(net "PWRGD_PVDDCR_CPU1_P0")
	)
	(segment
		(start 217.450416 -105.353104)
		(end 217.546174 -105.353104)
		(width 0.11684)
		(layer "In6.Cu")
		(net "PWRGD_PVDDCR_CPU1_P0")
	)
	(segment
		(start 297.5102 -368.9858)
		(end 294.8305 -371.6655)
		(width 0.11684)
		(layer "In11.Cu")
		(net "PWRGD_PVDDCR_CPU1_P0")
	)
	(segment
		(start 297.5102 -367.91265)
		(end 297.5102 -368.9858)
		(width 0.11684)
		(layer "In11.Cu")
		(net "PWRGD_PVDDCR_CPU1_P0")
	)
	(segment
		(start 300.78045 -364.6424)
		(end 297.5102 -367.91265)
		(width 0.11684)
		(layer "In11.Cu")
		(net "PWRGD_PVDDCR_CPU1_P0")
	)
	(segment
		(start 89.809828 -141.82471)
		(end 90.825828 -141.82471)
		(width 0.10668)
		(layer "F.Cu")
		(net "PWRGD_PVDDCR_CPU0_P1_R")
	)
	(segment
		(start 90.825828 -141.82471)
		(end 91.506294 -142.505176)
		(width 0.10668)
		(layer "F.Cu")
		(net "PWRGD_PVDDCR_CPU0_P1_R")
	)
	(via
		(at 91.506294 -142.505176)
		(size 0.762)
		(drill 0.254)
		(layers "F.Cu" "B.Cu")
		(net "PWRGD_PVDDCR_CPU0_P1_R")
	)
	(segment
		(start 91.506294 -142.505176)
		(end 91.200478 -142.19936)
		(width 0.10668)
		(layer "B.Cu")
		(net "PWRGD_PVDDCR_CPU0_P1_R")
	)
	(segment
		(start 90.971878 -142.19936)
		(end 90.609928 -141.83741)
		(width 0.10668)
		(layer "B.Cu")
		(net "PWRGD_PVDDCR_CPU0_P1_R")
	)
	(segment
		(start 91.506294 -142.768574)
		(end 91.506294 -142.505176)
		(width 0.10668)
		(layer "B.Cu")
		(net "PWRGD_PVDDCR_CPU0_P1_R")
	)
	(segment
		(start 91.200478 -142.19936)
		(end 90.971878 -142.19936)
		(width 0.10668)
		(layer "B.Cu")
		(net "PWRGD_PVDDCR_CPU0_P1_R")
	)
	(segment
		(start 92.795852 -143.758412)
		(end 92.496132 -143.758412)
		(width 0.10668)
		(layer "B.Cu")
		(net "PWRGD_PVDDCR_CPU0_P1_R")
	)
	(segment
		(start 92.496132 -143.758412)
		(end 91.506294 -142.768574)
		(width 0.10668)
		(layer "B.Cu")
		(net "PWRGD_PVDDCR_CPU0_P1_R")
	)
	(segment
		(start 90.825828 -141.02461)
		(end 91.232228 -140.61821)
		(width 0.10668)
		(layer "F.Cu")
		(net "PWRGD_PVDDCR_CPU0_P1")
	)
	(segment
		(start 91.232228 -140.61821)
		(end 91.232228 -139.80541)
		(width 0.10668)
		(layer "F.Cu")
		(net "PWRGD_PVDDCR_CPU0_P1")
	)
	(segment
		(start 91.232228 -138.745468)
		(end 90.76182 -138.27506)
		(width 0.10668)
		(layer "F.Cu")
		(net "PWRGD_PVDDCR_CPU0_P1")
	)
	(segment
		(start 201.339958 -108.545376)
		(end 202.255882 -108.545376)
		(width 0.10668)
		(layer "F.Cu")
		(net "PWRGD_PVDDCR_CPU0_P1")
	)
	(segment
		(start 90.76182 -138.27506)
		(end 90.1954 -138.27506)
		(width 0.10668)
		(layer "F.Cu")
		(net "PWRGD_PVDDCR_CPU0_P1")
	)
	(segment
		(start 91.232228 -139.80541)
		(end 91.232228 -138.745468)
		(width 0.10668)
		(layer "F.Cu")
		(net "PWRGD_PVDDCR_CPU0_P1")
	)
	(via
		(at 202.255882 -108.545376)
		(size 0.508)
		(drill 0.254)
		(layers "F.Cu" "B.Cu")
		(net "PWRGD_PVDDCR_CPU0_P1")
	)
	(via
		(at 96.259904 -121.723404)
		(size 0.508)
		(drill 0.254)
		(layers "F.Cu" "B.Cu")
		(net "PWRGD_PVDDCR_CPU0_P1")
	)
	(via
		(at 149.942804 -113.03381)
		(size 0.508)
		(drill 0.254)
		(layers "F.Cu" "B.Cu")
		(net "PWRGD_PVDDCR_CPU0_P1")
	)
	(via
		(at 90.1954 -138.27506)
		(size 0.508)
		(drill 0.254)
		(layers "F.Cu" "B.Cu")
		(net "PWRGD_PVDDCR_CPU0_P1")
	)
	(segment
		(start 206.39278 -107.849924)
		(end 205.697328 -108.545376)
		(width 0.10668)
		(layer "B.Cu")
		(net "PWRGD_PVDDCR_CPU0_P1")
	)
	(segment
		(start 160.832292 -106.674158)
		(end 161.467292 -106.674158)
		(width 0.10668)
		(layer "B.Cu")
		(net "PWRGD_PVDDCR_CPU0_P1")
	)
	(segment
		(start 212.1281 -95.329248)
		(end 212.1281 -96.297242)
		(width 0.10668)
		(layer "B.Cu")
		(net "PWRGD_PVDDCR_CPU0_P1")
	)
	(segment
		(start 207.757268 -88.523064)
		(end 208.855818 -89.621614)
		(width 0.10668)
		(layer "B.Cu")
		(net "PWRGD_PVDDCR_CPU0_P1")
	)
	(segment
		(start 214.313262 -100.751386)
		(end 216.284302 -100.751386)
		(width 0.10668)
		(layer "B.Cu")
		(net "PWRGD_PVDDCR_CPU0_P1")
	)
	(segment
		(start 168.097708 -90.096848)
		(end 188.182504 -90.096848)
		(width 0.10668)
		(layer "B.Cu")
		(net "PWRGD_PVDDCR_CPU0_P1")
	)
	(segment
		(start 189.756288 -88.523064)
		(end 207.757268 -88.523064)
		(width 0.10668)
		(layer "B.Cu")
		(net "PWRGD_PVDDCR_CPU0_P1")
	)
	(segment
		(start 152.104852 -113.046764)
		(end 156.018484 -109.133132)
		(width 0.10668)
		(layer "B.Cu")
		(net "PWRGD_PVDDCR_CPU0_P1")
	)
	(segment
		(start 161.467292 -106.674158)
		(end 163.791646 -104.349804)
		(width 0.10668)
		(layer "B.Cu")
		(net "PWRGD_PVDDCR_CPU0_P1")
	)
	(segment
		(start 208.855818 -89.621614)
		(end 208.855818 -92.056966)
		(width 0.10668)
		(layer "B.Cu")
		(net "PWRGD_PVDDCR_CPU0_P1")
	)
	(segment
		(start 216.940892 -108.450634)
		(end 208.998312 -108.450634)
		(width 0.10668)
		(layer "B.Cu")
		(net "PWRGD_PVDDCR_CPU0_P1")
	)
	(segment
		(start 218.2876 -102.754684)
		(end 218.2876 -107.103926)
		(width 0.10668)
		(layer "B.Cu")
		(net "PWRGD_PVDDCR_CPU0_P1")
	)
	(segment
		(start 208.397602 -107.849924)
		(end 206.39278 -107.849924)
		(width 0.10668)
		(layer "B.Cu")
		(net "PWRGD_PVDDCR_CPU0_P1")
	)
	(segment
		(start 158.373318 -109.133132)
		(end 160.832292 -106.674158)
		(width 0.10668)
		(layer "B.Cu")
		(net "PWRGD_PVDDCR_CPU0_P1")
	)
	(segment
		(start 163.791646 -104.349804)
		(end 163.791646 -94.40291)
		(width 0.10668)
		(layer "B.Cu")
		(net "PWRGD_PVDDCR_CPU0_P1")
	)
	(segment
		(start 211.997798 -96.427544)
		(end 211.997798 -98.435922)
		(width 0.10668)
		(layer "B.Cu")
		(net "PWRGD_PVDDCR_CPU0_P1")
	)
	(segment
		(start 156.018484 -109.133132)
		(end 158.373318 -109.133132)
		(width 0.10668)
		(layer "B.Cu")
		(net "PWRGD_PVDDCR_CPU0_P1")
	)
	(segment
		(start 149.955758 -113.046764)
		(end 152.104852 -113.046764)
		(width 0.10668)
		(layer "B.Cu")
		(net "PWRGD_PVDDCR_CPU0_P1")
	)
	(segment
		(start 205.697328 -108.545376)
		(end 202.255882 -108.545376)
		(width 0.10668)
		(layer "B.Cu")
		(net "PWRGD_PVDDCR_CPU0_P1")
	)
	(segment
		(start 188.182504 -90.096848)
		(end 189.756288 -88.523064)
		(width 0.10668)
		(layer "B.Cu")
		(net "PWRGD_PVDDCR_CPU0_P1")
	)
	(segment
		(start 211.997798 -98.435922)
		(end 214.313262 -100.751386)
		(width 0.10668)
		(layer "B.Cu")
		(net "PWRGD_PVDDCR_CPU0_P1")
	)
	(segment
		(start 218.2876 -107.103926)
		(end 216.940892 -108.450634)
		(width 0.10668)
		(layer "B.Cu")
		(net "PWRGD_PVDDCR_CPU0_P1")
	)
	(segment
		(start 216.284302 -100.751386)
		(end 218.2876 -102.754684)
		(width 0.10668)
		(layer "B.Cu")
		(net "PWRGD_PVDDCR_CPU0_P1")
	)
	(segment
		(start 212.1281 -96.297242)
		(end 211.997798 -96.427544)
		(width 0.10668)
		(layer "B.Cu")
		(net "PWRGD_PVDDCR_CPU0_P1")
	)
	(segment
		(start 163.791646 -94.40291)
		(end 168.097708 -90.096848)
		(width 0.10668)
		(layer "B.Cu")
		(net "PWRGD_PVDDCR_CPU0_P1")
	)
	(segment
		(start 149.942804 -113.03381)
		(end 149.955758 -113.046764)
		(width 0.10668)
		(layer "B.Cu")
		(net "PWRGD_PVDDCR_CPU0_P1")
	)
	(segment
		(start 208.998312 -108.450634)
		(end 208.397602 -107.849924)
		(width 0.10668)
		(layer "B.Cu")
		(net "PWRGD_PVDDCR_CPU0_P1")
	)
	(segment
		(start 208.855818 -92.056966)
		(end 212.1281 -95.329248)
		(width 0.10668)
		(layer "B.Cu")
		(net "PWRGD_PVDDCR_CPU0_P1")
	)
	(segment
		(start 90.1954 -138.27506)
		(end 90.803222 -137.667238)
		(width 0.11684)
		(layer "In4.Cu")
		(net "PWRGD_PVDDCR_CPU0_P1")
	)
	(segment
		(start 95.590614 -130.120644)
		(end 95.590614 -122.392694)
		(width 0.11684)
		(layer "In4.Cu")
		(net "PWRGD_PVDDCR_CPU0_P1")
	)
	(segment
		(start 90.803222 -134.908036)
		(end 95.590614 -130.120644)
		(width 0.11684)
		(layer "In4.Cu")
		(net "PWRGD_PVDDCR_CPU0_P1")
	)
	(segment
		(start 90.803222 -137.667238)
		(end 90.803222 -134.908036)
		(width 0.11684)
		(layer "In4.Cu")
		(net "PWRGD_PVDDCR_CPU0_P1")
	)
	(segment
		(start 95.590614 -122.392694)
		(end 96.259904 -121.723404)
		(width 0.11684)
		(layer "In4.Cu")
		(net "PWRGD_PVDDCR_CPU0_P1")
	)
	(segment
		(start 98.988626 -117.92839)
		(end 110.81131 -117.92839)
		(width 0.11684)
		(layer "In6.Cu")
		(net "PWRGD_PVDDCR_CPU0_P1")
	)
	(segment
		(start 149.98065 -112.813084)
		(end 149.98065 -112.995964)
		(width 0.11684)
		(layer "In6.Cu")
		(net "PWRGD_PVDDCR_CPU0_P1")
	)
	(segment
		(start 136.906254 -115.168426)
		(end 140.098018 -115.168426)
		(width 0.11684)
		(layer "In6.Cu")
		(net "PWRGD_PVDDCR_CPU0_P1")
	)
	(segment
		(start 142.736824 -112.52962)
		(end 149.697186 -112.52962)
		(width 0.11684)
		(layer "In6.Cu")
		(net "PWRGD_PVDDCR_CPU0_P1")
	)
	(segment
		(start 140.098018 -115.168426)
		(end 142.736824 -112.52962)
		(width 0.11684)
		(layer "In6.Cu")
		(net "PWRGD_PVDDCR_CPU0_P1")
	)
	(segment
		(start 112.181894 -116.557806)
		(end 135.516874 -116.557806)
		(width 0.11684)
		(layer "In6.Cu")
		(net "PWRGD_PVDDCR_CPU0_P1")
	)
	(segment
		(start 135.516874 -116.557806)
		(end 136.906254 -115.168426)
		(width 0.11684)
		(layer "In6.Cu")
		(net "PWRGD_PVDDCR_CPU0_P1")
	)
	(segment
		(start 96.259904 -120.657112)
		(end 98.988626 -117.92839)
		(width 0.11684)
		(layer "In6.Cu")
		(net "PWRGD_PVDDCR_CPU0_P1")
	)
	(segment
		(start 149.98065 -112.995964)
		(end 149.942804 -113.03381)
		(width 0.11684)
		(layer "In6.Cu")
		(net "PWRGD_PVDDCR_CPU0_P1")
	)
	(segment
		(start 96.259904 -121.723404)
		(end 96.259904 -120.657112)
		(width 0.11684)
		(layer "In6.Cu")
		(net "PWRGD_PVDDCR_CPU0_P1")
	)
	(segment
		(start 110.81131 -117.92839)
		(end 112.181894 -116.557806)
		(width 0.11684)
		(layer "In6.Cu")
		(net "PWRGD_PVDDCR_CPU0_P1")
	)
	(segment
		(start 149.697186 -112.52962)
		(end 149.98065 -112.813084)
		(width 0.11684)
		(layer "In6.Cu")
		(net "PWRGD_PVDDCR_CPU0_P1")
	)
	(segment
		(start 373.337328 -138.424158)
		(end 373.337328 -139.440158)
		(width 0.10668)
		(layer "F.Cu")
		(net "PWRGD_PVDDCR_CPU0_P0_R")
	)
	(segment
		(start 373.378222 -139.440158)
		(end 373.953278 -140.015214)
		(width 0.10668)
		(layer "F.Cu")
		(net "PWRGD_PVDDCR_CPU0_P0_R")
	)
	(segment
		(start 373.337328 -139.440158)
		(end 373.378222 -139.440158)
		(width 0.10668)
		(layer "F.Cu")
		(net "PWRGD_PVDDCR_CPU0_P0_R")
	)
	(via
		(at 374.341136 -140.483844)
		(size 0.4064)
		(drill 0.2032)
		(layers "F.Cu" "B.Cu")
		(net "PWRGD_PVDDCR_CPU0_P0_R")
	)
	(via
		(at 373.953278 -140.015214)
		(size 0.508)
		(drill 0.254)
		(layers "F.Cu" "B.Cu")
		(net "PWRGD_PVDDCR_CPU0_P0_R")
	)
	(segment
		(start 375.218452 -141.36116)
		(end 375.523252 -141.36116)
		(width 0.10668)
		(layer "B.Cu")
		(net "PWRGD_PVDDCR_CPU0_P0_R")
	)
	(segment
		(start 373.337328 -139.440158)
		(end 373.378222 -139.440158)
		(width 0.10668)
		(layer "B.Cu")
		(net "PWRGD_PVDDCR_CPU0_P0_R")
	)
	(segment
		(start 373.378222 -139.440158)
		(end 373.953278 -140.015214)
		(width 0.10668)
		(layer "B.Cu")
		(net "PWRGD_PVDDCR_CPU0_P0_R")
	)
	(segment
		(start 373.953278 -140.015214)
		(end 373.953278 -140.095986)
		(width 0.10668)
		(layer "B.Cu")
		(net "PWRGD_PVDDCR_CPU0_P0_R")
	)
	(segment
		(start 374.341136 -140.483844)
		(end 375.218452 -141.36116)
		(width 0.10668)
		(layer "B.Cu")
		(net "PWRGD_PVDDCR_CPU0_P0_R")
	)
	(segment
		(start 373.953278 -140.095986)
		(end 374.341136 -140.483844)
		(width 0.10668)
		(layer "B.Cu")
		(net "PWRGD_PVDDCR_CPU0_P0_R")
	)
	(segment
		(start 371.521228 -136.608058)
		(end 371.521228 -114.394488)
		(width 0.10668)
		(layer "F.Cu")
		(net "PWRGD_PVDDCR_CPU0_P0")
	)
	(segment
		(start 192.322196 -108.252768)
		(end 192.712086 -107.862878)
		(width 0.10668)
		(layer "F.Cu")
		(net "PWRGD_PVDDCR_CPU0_P0")
	)
	(segment
		(start 371.130322 -136.998964)
		(end 371.130322 -138.989816)
		(width 0.10668)
		(layer "F.Cu")
		(net "PWRGD_PVDDCR_CPU0_P0")
	)
	(segment
		(start 371.521228 -136.608058)
		(end 371.130322 -136.998964)
		(width 0.10668)
		(layer "F.Cu")
		(net "PWRGD_PVDDCR_CPU0_P0")
	)
	(segment
		(start 371.580664 -139.440158)
		(end 372.537228 -139.440158)
		(width 0.10668)
		(layer "F.Cu")
		(net "PWRGD_PVDDCR_CPU0_P0")
	)
	(segment
		(start 371.130322 -138.989816)
		(end 371.580664 -139.440158)
		(width 0.10668)
		(layer "F.Cu")
		(net "PWRGD_PVDDCR_CPU0_P0")
	)
	(via
		(at 371.521228 -114.394488)
		(size 0.508)
		(drill 0.254)
		(layers "F.Cu" "B.Cu")
		(net "PWRGD_PVDDCR_CPU0_P0")
	)
	(via
		(at 192.712086 -107.862878)
		(size 0.4572)
		(drill 0.254)
		(layers "F.Cu" "B.Cu")
		(net "PWRGD_PVDDCR_CPU0_P0")
	)
	(segment
		(start 272.67154 -109.740192)
		(end 260.027928 -109.740192)
		(width 0.11684)
		(layer "In6.Cu")
		(net "PWRGD_PVDDCR_CPU0_P0")
	)
	(segment
		(start 195.807584 -107.994196)
		(end 195.550282 -108.251498)
		(width 0.11684)
		(layer "In6.Cu")
		(net "PWRGD_PVDDCR_CPU0_P0")
	)
	(segment
		(start 220.05925 -107.559602)
		(end 215.951308 -107.559602)
		(width 0.11684)
		(layer "In6.Cu")
		(net "PWRGD_PVDDCR_CPU0_P0")
	)
	(segment
		(start 259.44068 -109.152944)
		(end 223.450912 -109.152944)
		(width 0.11684)
		(layer "In6.Cu")
		(net "PWRGD_PVDDCR_CPU0_P0")
	)
	(segment
		(start 368.323622 -113.277904)
		(end 321.535044 -113.277904)
		(width 0.11684)
		(layer "In6.Cu")
		(net "PWRGD_PVDDCR_CPU0_P0")
	)
	(segment
		(start 193.100706 -108.251498)
		(end 192.712086 -107.862878)
		(width 0.11684)
		(layer "In6.Cu")
		(net "PWRGD_PVDDCR_CPU0_P0")
	)
	(segment
		(start 215.49614 -108.01477)
		(end 208.609692 -108.01477)
		(width 0.11684)
		(layer "In6.Cu")
		(net "PWRGD_PVDDCR_CPU0_P0")
	)
	(segment
		(start 368.758978 -113.71326)
		(end 368.323622 -113.277904)
		(width 0.11684)
		(layer "In6.Cu")
		(net "PWRGD_PVDDCR_CPU0_P0")
	)
	(segment
		(start 316.31509 -108.05795)
		(end 274.353782 -108.05795)
		(width 0.11684)
		(layer "In6.Cu")
		(net "PWRGD_PVDDCR_CPU0_P0")
	)
	(segment
		(start 195.550282 -108.251498)
		(end 193.100706 -108.251498)
		(width 0.11684)
		(layer "In6.Cu")
		(net "PWRGD_PVDDCR_CPU0_P0")
	)
	(segment
		(start 223.450912 -109.152944)
		(end 222.454978 -108.15701)
		(width 0.11684)
		(layer "In6.Cu")
		(net "PWRGD_PVDDCR_CPU0_P0")
	)
	(segment
		(start 321.535044 -113.277904)
		(end 316.31509 -108.05795)
		(width 0.11684)
		(layer "In6.Cu")
		(net "PWRGD_PVDDCR_CPU0_P0")
	)
	(segment
		(start 220.656658 -108.15701)
		(end 220.05925 -107.559602)
		(width 0.11684)
		(layer "In6.Cu")
		(net "PWRGD_PVDDCR_CPU0_P0")
	)
	(segment
		(start 274.353782 -108.05795)
		(end 272.67154 -109.740192)
		(width 0.11684)
		(layer "In6.Cu")
		(net "PWRGD_PVDDCR_CPU0_P0")
	)
	(segment
		(start 370.84 -113.71326)
		(end 368.758978 -113.71326)
		(width 0.11684)
		(layer "In6.Cu")
		(net "PWRGD_PVDDCR_CPU0_P0")
	)
	(segment
		(start 222.454978 -108.15701)
		(end 220.656658 -108.15701)
		(width 0.11684)
		(layer "In6.Cu")
		(net "PWRGD_PVDDCR_CPU0_P0")
	)
	(segment
		(start 208.609692 -108.01477)
		(end 208.589118 -107.994196)
		(width 0.11684)
		(layer "In6.Cu")
		(net "PWRGD_PVDDCR_CPU0_P0")
	)
	(segment
		(start 260.027928 -109.740192)
		(end 259.44068 -109.152944)
		(width 0.11684)
		(layer "In6.Cu")
		(net "PWRGD_PVDDCR_CPU0_P0")
	)
	(segment
		(start 215.951308 -107.559602)
		(end 215.49614 -108.01477)
		(width 0.11684)
		(layer "In6.Cu")
		(net "PWRGD_PVDDCR_CPU0_P0")
	)
	(segment
		(start 371.521228 -114.394488)
		(end 370.84 -113.71326)
		(width 0.11684)
		(layer "In6.Cu")
		(net "PWRGD_PVDDCR_CPU0_P0")
	)
	(segment
		(start 208.589118 -107.994196)
		(end 195.807584 -107.994196)
		(width 0.11684)
		(layer "In6.Cu")
		(net "PWRGD_PVDDCR_CPU0_P0")
	)
	(segment
		(start 196.676772 -128.718818)
		(end 196.676772 -127.834644)
		(width 0.10668)
		(layer "F.Cu")
		(net "PWRGD_PVDD33_S5")
	)
	(segment
		(start 206.480918 -151.777954)
		(end 206.480918 -149.816058)
		(width 0.10668)
		(layer "F.Cu")
		(net "PWRGD_PVDD33_S5")
	)
	(segment
		(start 197.151244 -128.825498)
		(end 196.783452 -128.825498)
		(width 0.10668)
		(layer "F.Cu")
		(net "PWRGD_PVDD33_S5")
	)
	(segment
		(start 217.944954 -163.24199)
		(end 206.480918 -151.777954)
		(width 0.10668)
		(layer "F.Cu")
		(net "PWRGD_PVDD33_S5")
	)
	(segment
		(start 197.669658 -107.529376)
		(end 198.342758 -107.529376)
		(width 0.10668)
		(layer "F.Cu")
		(net "PWRGD_PVDD33_S5")
	)
	(segment
		(start 202.254104 -342.35517)
		(end 202.523852 -342.35517)
		(width 0.10414)
		(layer "F.Cu")
		(net "PWRGD_PVDD33_S5")
	)
	(segment
		(start 202.964034 -342.795352)
		(end 202.964034 -342.922352)
		(width 0.10414)
		(layer "F.Cu")
		(net "PWRGD_PVDD33_S5")
	)
	(segment
		(start 196.783452 -128.825498)
		(end 196.676772 -128.718818)
		(width 0.10668)
		(layer "F.Cu")
		(net "PWRGD_PVDD33_S5")
	)
	(segment
		(start 202.438 -145.77314)
		(end 202.438 -134.112254)
		(width 0.10668)
		(layer "F.Cu")
		(net "PWRGD_PVDD33_S5")
	)
	(segment
		(start 186.770264 -187.132468)
		(end 186.770264 -179.464716)
		(width 0.10668)
		(layer "F.Cu")
		(net "PWRGD_PVDD33_S5")
	)
	(segment
		(start 219.279978 -165.287706)
		(end 217.944954 -163.952682)
		(width 0.10668)
		(layer "F.Cu")
		(net "PWRGD_PVDD33_S5")
	)
	(segment
		(start 186.770264 -179.464716)
		(end 180.87848 -173.572932)
		(width 0.10668)
		(layer "F.Cu")
		(net "PWRGD_PVDD33_S5")
	)
	(segment
		(start 196.676772 -127.834644)
		(end 196.8754 -127.636016)
		(width 0.10668)
		(layer "F.Cu")
		(net "PWRGD_PVDD33_S5")
	)
	(segment
		(start 180.87848 -173.572932)
		(end 180.87848 -172.792898)
		(width 0.10668)
		(layer "F.Cu")
		(net "PWRGD_PVDD33_S5")
	)
	(segment
		(start 202.438 -134.112254)
		(end 197.151244 -128.825498)
		(width 0.10668)
		(layer "F.Cu")
		(net "PWRGD_PVDD33_S5")
	)
	(segment
		(start 206.480918 -149.816058)
		(end 202.438 -145.77314)
		(width 0.10668)
		(layer "F.Cu")
		(net "PWRGD_PVDD33_S5")
	)
	(segment
		(start 202.523852 -342.35517)
		(end 202.964034 -342.795352)
		(width 0.10414)
		(layer "F.Cu")
		(net "PWRGD_PVDD33_S5")
	)
	(segment
		(start 217.944954 -163.952682)
		(end 217.944954 -163.24199)
		(width 0.10668)
		(layer "F.Cu")
		(net "PWRGD_PVDD33_S5")
	)
	(segment
		(start 220.148658 -165.287706)
		(end 219.279978 -165.287706)
		(width 0.10668)
		(layer "F.Cu")
		(net "PWRGD_PVDD33_S5")
	)
	(via
		(at 220.148658 -165.287706)
		(size 0.508)
		(drill 0.254)
		(layers "F.Cu" "B.Cu")
		(net "PWRGD_PVDD33_S5")
	)
	(via
		(at 196.8754 -127.636016)
		(size 0.508)
		(drill 0.254)
		(layers "F.Cu" "B.Cu")
		(net "PWRGD_PVDD33_S5")
	)
	(via
		(at 180.87848 -172.792898)
		(size 0.508)
		(drill 0.254)
		(layers "F.Cu" "B.Cu")
		(net "PWRGD_PVDD33_S5")
	)
	(via
		(at 198.342758 -107.529376)
		(size 0.508)
		(drill 0.254)
		(layers "F.Cu" "B.Cu")
		(net "PWRGD_PVDD33_S5")
	)
	(via
		(at 202.964034 -342.922352)
		(size 0.508)
		(drill 0.254)
		(layers "F.Cu" "B.Cu")
		(net "PWRGD_PVDD33_S5")
	)
	(via
		(at 186.770264 -187.132468)
		(size 0.508)
		(drill 0.254)
		(layers "F.Cu" "B.Cu")
		(net "PWRGD_PVDD33_S5")
	)
	(segment
		(start 217.898218 -166.454074)
		(end 219.064586 -165.287706)
		(width 0.10668)
		(layer "B.Cu")
		(net "PWRGD_PVDD33_S5")
	)
	(segment
		(start 180.87848 -173.692058)
		(end 182.13578 -174.949358)
		(width 0.10668)
		(layer "B.Cu")
		(net "PWRGD_PVDD33_S5")
	)
	(segment
		(start 219.064586 -165.287706)
		(end 220.148658 -165.287706)
		(width 0.10668)
		(layer "B.Cu")
		(net "PWRGD_PVDD33_S5")
	)
	(segment
		(start 207.913732 -319.600326)
		(end 207.913732 -325.90232)
		(width 0.10668)
		(layer "B.Cu")
		(net "PWRGD_PVDD33_S5")
	)
	(segment
		(start 207.098392 -342.738456)
		(end 206.914496 -342.922352)
		(width 0.10668)
		(layer "B.Cu")
		(net "PWRGD_PVDD33_S5")
	)
	(segment
		(start 212.720174 -166.454074)
		(end 217.898218 -166.454074)
		(width 0.10668)
		(layer "B.Cu")
		(net "PWRGD_PVDD33_S5")
	)
	(segment
		(start 186.770264 -187.132468)
		(end 188.762132 -189.124336)
		(width 0.10668)
		(layer "B.Cu")
		(net "PWRGD_PVDD33_S5")
	)
	(segment
		(start 180.87848 -172.792898)
		(end 180.87848 -173.692058)
		(width 0.10668)
		(layer "B.Cu")
		(net "PWRGD_PVDD33_S5")
	)
	(segment
		(start 202.5523 -341.864442)
		(end 202.5523 -342.510618)
		(width 0.10668)
		(layer "B.Cu")
		(net "PWRGD_PVDD33_S5")
	)
	(segment
		(start 208.193894 -316.869826)
		(end 208.193894 -319.320164)
		(width 0.10668)
		(layer "B.Cu")
		(net "PWRGD_PVDD33_S5")
	)
	(segment
		(start 211.940394 -313.123326)
		(end 208.193894 -316.869826)
		(width 0.10668)
		(layer "B.Cu")
		(net "PWRGD_PVDD33_S5")
	)
	(segment
		(start 207.913732 -325.90232)
		(end 207.098392 -326.71766)
		(width 0.10668)
		(layer "B.Cu")
		(net "PWRGD_PVDD33_S5")
	)
	(segment
		(start 204.22489 -174.949358)
		(end 212.720174 -166.454074)
		(width 0.10668)
		(layer "B.Cu")
		(net "PWRGD_PVDD33_S5")
	)
	(segment
		(start 211.940394 -192.445894)
		(end 211.940394 -313.123326)
		(width 0.10668)
		(layer "B.Cu")
		(net "PWRGD_PVDD33_S5")
	)
	(segment
		(start 202.5523 -342.510618)
		(end 202.964034 -342.922352)
		(width 0.10668)
		(layer "B.Cu")
		(net "PWRGD_PVDD33_S5")
	)
	(segment
		(start 182.13578 -174.949358)
		(end 204.22489 -174.949358)
		(width 0.10668)
		(layer "B.Cu")
		(net "PWRGD_PVDD33_S5")
	)
	(segment
		(start 207.098392 -326.71766)
		(end 207.098392 -342.738456)
		(width 0.10668)
		(layer "B.Cu")
		(net "PWRGD_PVDD33_S5")
	)
	(segment
		(start 206.914496 -342.922352)
		(end 202.964034 -342.922352)
		(width 0.10668)
		(layer "B.Cu")
		(net "PWRGD_PVDD33_S5")
	)
	(segment
		(start 188.762132 -189.124336)
		(end 208.618836 -189.124336)
		(width 0.10668)
		(layer "B.Cu")
		(net "PWRGD_PVDD33_S5")
	)
	(segment
		(start 208.618836 -189.124336)
		(end 211.940394 -192.445894)
		(width 0.10668)
		(layer "B.Cu")
		(net "PWRGD_PVDD33_S5")
	)
	(segment
		(start 208.193894 -319.320164)
		(end 207.913732 -319.600326)
		(width 0.10668)
		(layer "B.Cu")
		(net "PWRGD_PVDD33_S5")
	)
	(segment
		(start 198.826374 -113.887504)
		(end 198.826374 -113.260632)
		(width 0.11684)
		(layer "In11.Cu")
		(net "PWRGD_PVDD33_S5")
	)
	(segment
		(start 198.081646 -113.064544)
		(end 197.689724 -112.672622)
		(width 0.11684)
		(layer "In11.Cu")
		(net "PWRGD_PVDD33_S5")
	)
	(segment
		(start 197.689724 -108.205778)
		(end 198.342758 -107.552744)
		(width 0.11684)
		(layer "In11.Cu")
		(net "PWRGD_PVDD33_S5")
	)
	(segment
		(start 198.630286 -113.064544)
		(end 198.081646 -113.064544)
		(width 0.11684)
		(layer "In11.Cu")
		(net "PWRGD_PVDD33_S5")
	)
	(segment
		(start 197.689724 -112.672622)
		(end 197.689724 -108.205778)
		(width 0.11684)
		(layer "In11.Cu")
		(net "PWRGD_PVDD33_S5")
	)
	(segment
		(start 196.8754 -116.430806)
		(end 197.689724 -115.616482)
		(width 0.11684)
		(layer "In11.Cu")
		(net "PWRGD_PVDD33_S5")
	)
	(segment
		(start 198.342758 -107.552744)
		(end 198.342758 -107.529376)
		(width 0.11684)
		(layer "In11.Cu")
		(net "PWRGD_PVDD33_S5")
	)
	(segment
		(start 196.8754 -127.636016)
		(end 196.8754 -116.430806)
		(width 0.11684)
		(layer "In11.Cu")
		(net "PWRGD_PVDD33_S5")
	)
	(segment
		(start 197.689724 -115.616482)
		(end 197.689724 -115.024154)
		(width 0.11684)
		(layer "In11.Cu")
		(net "PWRGD_PVDD33_S5")
	)
	(segment
		(start 198.826374 -113.260632)
		(end 198.630286 -113.064544)
		(width 0.11684)
		(layer "In11.Cu")
		(net "PWRGD_PVDD33_S5")
	)
	(segment
		(start 197.689724 -115.024154)
		(end 198.826374 -113.887504)
		(width 0.11684)
		(layer "In11.Cu")
		(net "PWRGD_PVDD33_S5")
	)
	(segment
		(start 194.137788 -110.252256)
		(end 193.5226 -110.252256)
		(width 0.10668)
		(layer "F.Cu")
		(net "PWRGD_PVDD18_S5_R_P1")
	)
	(segment
		(start 194.708272 -107.846622)
		(end 194.708272 -109.681772)
		(width 0.10668)
		(layer "F.Cu")
		(net "PWRGD_PVDD18_S5_R_P1")
	)
	(segment
		(start 194.708272 -109.681772)
		(end 194.137788 -110.252256)
		(width 0.10668)
		(layer "F.Cu")
		(net "PWRGD_PVDD18_S5_R_P1")
	)
	(segment
		(start 204.851 -107.362498)
		(end 204.851 -108.535216)
		(width 0.10668)
		(layer "F.Cu")
		(net "PWRGD_PVDD18_S5_R_P1")
	)
	(segment
		(start 193.5226 -110.252256)
		(end 193.122042 -110.652814)
		(width 0.10668)
		(layer "F.Cu")
		(net "PWRGD_PVDD18_S5_R_P1")
	)
	(segment
		(start 204.851 -108.535216)
		(end 204.84084 -108.545376)
		(width 0.10668)
		(layer "F.Cu")
		(net "PWRGD_PVDD18_S5_R_P1")
	)
	(segment
		(start 203.487528 -105.999026)
		(end 196.555868 -105.999026)
		(width 0.10668)
		(layer "F.Cu")
		(net "PWRGD_PVDD18_S5_R_P1")
	)
	(segment
		(start 204.851 -107.362498)
		(end 203.75245 -106.263948)
		(width 0.10668)
		(layer "F.Cu")
		(net "PWRGD_PVDD18_S5_R_P1")
	)
	(segment
		(start 196.555868 -105.999026)
		(end 194.708272 -107.846622)
		(width 0.10668)
		(layer "F.Cu")
		(net "PWRGD_PVDD18_S5_R_P1")
	)
	(segment
		(start 203.75245 -106.263948)
		(end 203.487528 -105.999026)
		(width 0.10668)
		(layer "F.Cu")
		(net "PWRGD_PVDD18_S5_R_P1")
	)
	(via
		(at 203.75245 -106.263948)
		(size 0.762)
		(drill 0.381)
		(layers "F.Cu" "B.Cu")
		(net "PWRGD_PVDD18_S5_R_P1")
	)
	(segment
		(start 76.266294 -148.851366)
		(end 76.74102 -148.37664)
		(width 0.10668)
		(layer "F.Cu")
		(net "PWRGD_PVDD18_S5_P1")
	)
	(segment
		(start 74.95921 -149.042628)
		(end 73.61301 -150.388828)
		(width 0.10668)
		(layer "F.Cu")
		(net "PWRGD_PVDD18_S5_P1")
	)
	(segment
		(start 71.551292 -150.566374)
		(end 71.551292 -150.932642)
		(width 0.10668)
		(layer "F.Cu")
		(net "PWRGD_PVDD18_S5_P1")
	)
	(segment
		(start 73.61301 -150.388828)
		(end 71.728838 -150.388828)
		(width 0.10668)
		(layer "F.Cu")
		(net "PWRGD_PVDD18_S5_P1")
	)
	(segment
		(start 75.64501 -148.851366)
		(end 76.266294 -148.851366)
		(width 0.10668)
		(layer "F.Cu")
		(net "PWRGD_PVDD18_S5_P1")
	)
	(segment
		(start 205.64094 -108.545376)
		(end 206.493872 -108.545376)
		(width 0.10668)
		(layer "F.Cu")
		(net "PWRGD_PVDD18_S5_P1")
	)
	(segment
		(start 71.728838 -150.388828)
		(end 71.551292 -150.566374)
		(width 0.10668)
		(layer "F.Cu")
		(net "PWRGD_PVDD18_S5_P1")
	)
	(segment
		(start 75.453748 -149.042628)
		(end 74.95921 -149.042628)
		(width 0.10668)
		(layer "F.Cu")
		(net "PWRGD_PVDD18_S5_P1")
	)
	(segment
		(start 75.64501 -148.851366)
		(end 75.453748 -149.042628)
		(width 0.10668)
		(layer "F.Cu")
		(net "PWRGD_PVDD18_S5_P1")
	)
	(segment
		(start 206.493872 -108.545376)
		(end 206.566008 -108.47324)
		(width 0.10668)
		(layer "F.Cu")
		(net "PWRGD_PVDD18_S5_P1")
	)
	(via
		(at 206.566008 -108.47324)
		(size 0.508)
		(drill 0.254)
		(layers "F.Cu" "B.Cu")
		(net "PWRGD_PVDD18_S5_P1")
	)
	(via
		(at 76.74102 -148.37664)
		(size 0.508)
		(drill 0.254)
		(layers "F.Cu" "B.Cu")
		(net "PWRGD_PVDD18_S5_P1")
	)
	(via
		(at 139.965176 -94.76359)
		(size 0.508)
		(drill 0.254)
		(layers "F.Cu" "B.Cu")
		(net "PWRGD_PVDD18_S5_P1")
	)
	(via
		(at 208.963006 -77.507592)
		(size 0.508)
		(drill 0.254)
		(layers "F.Cu" "B.Cu")
		(net "PWRGD_PVDD18_S5_P1")
	)
	(via
		(at 79.184246 -111.993934)
		(size 0.508)
		(drill 0.254)
		(layers "F.Cu" "B.Cu")
		(net "PWRGD_PVDD18_S5_P1")
	)
	(segment
		(start 131.84632 -94.76359)
		(end 130.093212 -96.516698)
		(width 0.10668)
		(layer "B.Cu")
		(net "PWRGD_PVDD18_S5_P1")
	)
	(segment
		(start 139.965176 -94.76359)
		(end 131.84632 -94.76359)
		(width 0.10668)
		(layer "B.Cu")
		(net "PWRGD_PVDD18_S5_P1")
	)
	(segment
		(start 91.927426 -96.516698)
		(end 79.184246 -109.259878)
		(width 0.10668)
		(layer "B.Cu")
		(net "PWRGD_PVDD18_S5_P1")
	)
	(segment
		(start 79.184246 -109.259878)
		(end 79.184246 -111.993934)
		(width 0.10668)
		(layer "B.Cu")
		(net "PWRGD_PVDD18_S5_P1")
	)
	(segment
		(start 130.093212 -96.516698)
		(end 91.927426 -96.516698)
		(width 0.10668)
		(layer "B.Cu")
		(net "PWRGD_PVDD18_S5_P1")
	)
	(segment
		(start 210.086702 -102.531418)
		(end 209.905854 -102.35057)
		(width 0.11684)
		(layer "In4.Cu")
		(net "PWRGD_PVDD18_S5_P1")
	)
	(segment
		(start 206.566008 -108.47324)
		(end 206.59344 -108.47324)
		(width 0.11684)
		(layer "In4.Cu")
		(net "PWRGD_PVDD18_S5_P1")
	)
	(segment
		(start 208.610454 -98.820732)
		(end 208.610454 -89.760806)
		(width 0.11684)
		(layer "In4.Cu")
		(net "PWRGD_PVDD18_S5_P1")
	)
	(segment
		(start 208.476342 -106.590338)
		(end 208.476342 -104.950514)
		(width 0.11684)
		(layer "In4.Cu")
		(net "PWRGD_PVDD18_S5_P1")
	)
	(segment
		(start 206.59344 -108.47324)
		(end 208.476342 -106.590338)
		(width 0.11684)
		(layer "In4.Cu")
		(net "PWRGD_PVDD18_S5_P1")
	)
	(segment
		(start 209.838544 -86.01202)
		(end 209.459322 -85.632798)
		(width 0.11684)
		(layer "In4.Cu")
		(net "PWRGD_PVDD18_S5_P1")
	)
	(segment
		(start 208.610454 -89.760806)
		(end 209.838544 -88.532716)
		(width 0.11684)
		(layer "In4.Cu")
		(net "PWRGD_PVDD18_S5_P1")
	)
	(segment
		(start 210.086702 -103.340154)
		(end 210.086702 -102.531418)
		(width 0.11684)
		(layer "In4.Cu")
		(net "PWRGD_PVDD18_S5_P1")
	)
	(segment
		(start 209.459322 -85.632798)
		(end 209.459322 -77.66431)
		(width 0.11684)
		(layer "In4.Cu")
		(net "PWRGD_PVDD18_S5_P1")
	)
	(segment
		(start 209.838544 -88.532716)
		(end 209.838544 -86.01202)
		(width 0.11684)
		(layer "In4.Cu")
		(net "PWRGD_PVDD18_S5_P1")
	)
	(segment
		(start 209.459322 -77.66431)
		(end 209.302604 -77.507592)
		(width 0.11684)
		(layer "In4.Cu")
		(net "PWRGD_PVDD18_S5_P1")
	)
	(segment
		(start 209.905854 -102.35057)
		(end 209.905854 -100.116132)
		(width 0.11684)
		(layer "In4.Cu")
		(net "PWRGD_PVDD18_S5_P1")
	)
	(segment
		(start 208.476342 -104.950514)
		(end 210.086702 -103.340154)
		(width 0.11684)
		(layer "In4.Cu")
		(net "PWRGD_PVDD18_S5_P1")
	)
	(segment
		(start 209.302604 -77.507592)
		(end 208.963006 -77.507592)
		(width 0.11684)
		(layer "In4.Cu")
		(net "PWRGD_PVDD18_S5_P1")
	)
	(segment
		(start 209.905854 -100.116132)
		(end 208.610454 -98.820732)
		(width 0.11684)
		(layer "In4.Cu")
		(net "PWRGD_PVDD18_S5_P1")
	)
	(segment
		(start 66.256154 -132.628132)
		(end 66.256154 -134.77748)
		(width 0.11684)
		(layer "In6.Cu")
		(net "PWRGD_PVDD18_S5_P1")
	)
	(segment
		(start 72.667622 -146.631406)
		(end 74.52995 -148.493734)
		(width 0.11684)
		(layer "In6.Cu")
		(net "PWRGD_PVDD18_S5_P1")
	)
	(segment
		(start 79.184246 -119.70004)
		(end 66.256154 -132.628132)
		(width 0.11684)
		(layer "In6.Cu")
		(net "PWRGD_PVDD18_S5_P1")
	)
	(segment
		(start 79.184246 -111.993934)
		(end 79.184246 -119.70004)
		(width 0.11684)
		(layer "In6.Cu")
		(net "PWRGD_PVDD18_S5_P1")
	)
	(segment
		(start 76.623926 -148.493734)
		(end 76.74102 -148.37664)
		(width 0.11684)
		(layer "In6.Cu")
		(net "PWRGD_PVDD18_S5_P1")
	)
	(segment
		(start 66.256154 -134.77748)
		(end 72.667622 -141.188948)
		(width 0.11684)
		(layer "In6.Cu")
		(net "PWRGD_PVDD18_S5_P1")
	)
	(segment
		(start 72.667622 -141.188948)
		(end 72.667622 -146.631406)
		(width 0.11684)
		(layer "In6.Cu")
		(net "PWRGD_PVDD18_S5_P1")
	)
	(segment
		(start 74.52995 -148.493734)
		(end 76.623926 -148.493734)
		(width 0.11684)
		(layer "In6.Cu")
		(net "PWRGD_PVDD18_S5_P1")
	)
	(segment
		(start 205.653894 -77.507592)
		(end 202.88123 -74.734928)
		(width 0.11684)
		(layer "In15.Cu")
		(net "PWRGD_PVDD18_S5_P1")
	)
	(segment
		(start 208.963006 -77.507592)
		(end 205.653894 -77.507592)
		(width 0.11684)
		(layer "In15.Cu")
		(net "PWRGD_PVDD18_S5_P1")
	)
	(segment
		(start 158.049468 -89.787476)
		(end 144.94129 -89.787476)
		(width 0.11684)
		(layer "In15.Cu")
		(net "PWRGD_PVDD18_S5_P1")
	)
	(segment
		(start 165.809676 -82.027268)
		(end 158.049468 -89.787476)
		(width 0.11684)
		(layer "In15.Cu")
		(net "PWRGD_PVDD18_S5_P1")
	)
	(segment
		(start 200.938892 -75.08113)
		(end 200.938892 -79.124556)
		(width 0.11684)
		(layer "In15.Cu")
		(net "PWRGD_PVDD18_S5_P1")
	)
	(segment
		(start 202.88123 -74.734928)
		(end 201.285094 -74.734928)
		(width 0.11684)
		(layer "In15.Cu")
		(net "PWRGD_PVDD18_S5_P1")
	)
	(segment
		(start 144.94129 -89.787476)
		(end 139.965176 -94.76359)
		(width 0.11684)
		(layer "In15.Cu")
		(net "PWRGD_PVDD18_S5_P1")
	)
	(segment
		(start 200.938892 -79.124556)
		(end 198.03618 -82.027268)
		(width 0.11684)
		(layer "In15.Cu")
		(net "PWRGD_PVDD18_S5_P1")
	)
	(segment
		(start 201.285094 -74.734928)
		(end 200.938892 -75.08113)
		(width 0.11684)
		(layer "In15.Cu")
		(net "PWRGD_PVDD18_S5_P1")
	)
	(segment
		(start 198.03618 -82.027268)
		(end 165.809676 -82.027268)
		(width 0.11684)
		(layer "In15.Cu")
		(net "PWRGD_PVDD18_S5_P1")
	)
	(segment
		(start 332.878684 -138.149838)
		(end 332.878684 -137.213848)
		(width 0.10668)
		(layer "F.Cu")
		(net "PWRGD_PVDD18_S5_P0")
	)
	(segment
		(start 332.033118 -136.473946)
		(end 332.033118 -136.718802)
		(width 0.10668)
		(layer "F.Cu")
		(net "PWRGD_PVDD18_S5_P0")
	)
	(segment
		(start 332.138782 -136.473946)
		(end 332.033118 -136.473946)
		(width 0.10668)
		(layer "F.Cu")
		(net "PWRGD_PVDD18_S5_P0")
	)
	(segment
		(start 198.114158 -111.593376)
		(end 199.104758 -110.602776)
		(width 0.10668)
		(layer "F.Cu")
		(net "PWRGD_PVDD18_S5_P0")
	)
	(segment
		(start 333.89951 -139.170664)
		(end 332.878684 -138.149838)
		(width 0.10668)
		(layer "F.Cu")
		(net "PWRGD_PVDD18_S5_P0")
	)
	(segment
		(start 330.384404 -137.035286)
		(end 329.053444 -135.704326)
		(width 0.10668)
		(layer "F.Cu")
		(net "PWRGD_PVDD18_S5_P0")
	)
	(segment
		(start 332.878684 -137.213848)
		(end 332.138782 -136.473946)
		(width 0.10668)
		(layer "F.Cu")
		(net "PWRGD_PVDD18_S5_P0")
	)
	(segment
		(start 334.114394 -139.170664)
		(end 333.89951 -139.170664)
		(width 0.10668)
		(layer "F.Cu")
		(net "PWRGD_PVDD18_S5_P0")
	)
	(segment
		(start 197.669658 -111.593376)
		(end 198.114158 -111.593376)
		(width 0.10668)
		(layer "F.Cu")
		(net "PWRGD_PVDD18_S5_P0")
	)
	(segment
		(start 320.762376 -127.413258)
		(end 329.053444 -135.704326)
		(width 0.10668)
		(layer "F.Cu")
		(net "PWRGD_PVDD18_S5_P0")
	)
	(segment
		(start 292.363144 -127.413258)
		(end 320.762376 -127.413258)
		(width 0.10668)
		(layer "F.Cu")
		(net "PWRGD_PVDD18_S5_P0")
	)
	(segment
		(start 332.033118 -136.718802)
		(end 331.716634 -137.035286)
		(width 0.10668)
		(layer "F.Cu")
		(net "PWRGD_PVDD18_S5_P0")
	)
	(segment
		(start 331.716634 -137.035286)
		(end 330.384404 -137.035286)
		(width 0.10668)
		(layer "F.Cu")
		(net "PWRGD_PVDD18_S5_P0")
	)
	(via
		(at 199.104758 -110.602776)
		(size 0.508)
		(drill 0.254)
		(layers "F.Cu" "B.Cu")
		(net "PWRGD_PVDD18_S5_P0")
	)
	(via
		(at 292.363144 -127.413258)
		(size 0.762)
		(drill 0.254)
		(layers "F.Cu" "B.Cu")
		(net "PWRGD_PVDD18_S5_P0")
	)
	(segment
		(start 275.095716 -123.139708)
		(end 275.66493 -122.570494)
		(width 0.11684)
		(layer "In15.Cu")
		(net "PWRGD_PVDD18_S5_P0")
	)
	(segment
		(start 271.008602 -120.474232)
		(end 271.90192 -121.36755)
		(width 0.11684)
		(layer "In15.Cu")
		(net "PWRGD_PVDD18_S5_P0")
	)
	(segment
		(start 268.059154 -120.474232)
		(end 271.008602 -120.474232)
		(width 0.11684)
		(layer "In15.Cu")
		(net "PWRGD_PVDD18_S5_P0")
	)
	(segment
		(start 210.6676 -110.078266)
		(end 210.81365 -109.932216)
		(width 0.11684)
		(layer "In15.Cu")
		(net "PWRGD_PVDD18_S5_P0")
	)
	(segment
		(start 210.81365 -109.932216)
		(end 214.23249 -109.932216)
		(width 0.11684)
		(layer "In15.Cu")
		(net "PWRGD_PVDD18_S5_P0")
	)
	(segment
		(start 254.04953 -113.091214)
		(end 260.676136 -113.091214)
		(width 0.11684)
		(layer "In15.Cu")
		(net "PWRGD_PVDD18_S5_P0")
	)
	(segment
		(start 271.90192 -121.36755)
		(end 272.287492 -121.36755)
		(width 0.11684)
		(layer "In15.Cu")
		(net "PWRGD_PVDD18_S5_P0")
	)
	(segment
		(start 274.05965 -123.139708)
		(end 275.095716 -123.139708)
		(width 0.11684)
		(layer "In15.Cu")
		(net "PWRGD_PVDD18_S5_P0")
	)
	(segment
		(start 199.629268 -110.078266)
		(end 210.6676 -110.078266)
		(width 0.11684)
		(layer "In15.Cu")
		(net "PWRGD_PVDD18_S5_P0")
	)
	(segment
		(start 275.66493 -122.570494)
		(end 287.52038 -122.570494)
		(width 0.11684)
		(layer "In15.Cu")
		(net "PWRGD_PVDD18_S5_P0")
	)
	(segment
		(start 252.21946 -111.261144)
		(end 254.04953 -113.091214)
		(width 0.11684)
		(layer "In15.Cu")
		(net "PWRGD_PVDD18_S5_P0")
	)
	(segment
		(start 287.52038 -122.570494)
		(end 292.363144 -127.413258)
		(width 0.11684)
		(layer "In15.Cu")
		(net "PWRGD_PVDD18_S5_P0")
	)
	(segment
		(start 199.104758 -110.602776)
		(end 199.629268 -110.078266)
		(width 0.11684)
		(layer "In15.Cu")
		(net "PWRGD_PVDD18_S5_P0")
	)
	(segment
		(start 272.287492 -121.36755)
		(end 274.05965 -123.139708)
		(width 0.11684)
		(layer "In15.Cu")
		(net "PWRGD_PVDD18_S5_P0")
	)
	(segment
		(start 260.676136 -113.091214)
		(end 268.059154 -120.474232)
		(width 0.11684)
		(layer "In15.Cu")
		(net "PWRGD_PVDD18_S5_P0")
	)
	(segment
		(start 215.561418 -111.261144)
		(end 252.21946 -111.261144)
		(width 0.11684)
		(layer "In15.Cu")
		(net "PWRGD_PVDD18_S5_P0")
	)
	(segment
		(start 214.23249 -109.932216)
		(end 215.561418 -111.261144)
		(width 0.11684)
		(layer "In15.Cu")
		(net "PWRGD_PVDD18_S5_P0")
	)
	(segment
		(start 158.79953 -351.398078)
		(end 158.243524 -351.398078)
		(width 0.10668)
		(layer "F.Cu")
		(net "PWRGD_PVDD11_S3_P1_R")
	)
	(segment
		(start 158.79953 -350.68637)
		(end 158.79953 -351.398078)
		(width 0.10668)
		(layer "F.Cu")
		(net "PWRGD_PVDD11_S3_P1_R")
	)
	(segment
		(start 158.243524 -351.398078)
		(end 158.092902 -351.247456)
		(width 0.10668)
		(layer "F.Cu")
		(net "PWRGD_PVDD11_S3_P1_R")
	)
	(segment
		(start 159.28213 -350.066102)
		(end 159.28213 -350.20377)
		(width 0.10668)
		(layer "F.Cu")
		(net "PWRGD_PVDD11_S3_P1_R")
	)
	(segment
		(start 158.077408 -352.229928)
		(end 157.986476 -352.138996)
		(width 0.10668)
		(layer "F.Cu")
		(net "PWRGD_PVDD11_S3_P1_R")
	)
	(segment
		(start 157.986476 -351.353882)
		(end 158.092902 -351.247456)
		(width 0.10668)
		(layer "F.Cu")
		(net "PWRGD_PVDD11_S3_P1_R")
	)
	(segment
		(start 159.394906 -349.953326)
		(end 159.28213 -350.066102)
		(width 0.10668)
		(layer "F.Cu")
		(net "PWRGD_PVDD11_S3_P1_R")
	)
	(segment
		(start 159.28213 -350.20377)
		(end 158.79953 -350.68637)
		(width 0.10668)
		(layer "F.Cu")
		(net "PWRGD_PVDD11_S3_P1_R")
	)
	(segment
		(start 159.828484 -349.953326)
		(end 159.394906 -349.953326)
		(width 0.10668)
		(layer "F.Cu")
		(net "PWRGD_PVDD11_S3_P1_R")
	)
	(segment
		(start 157.986476 -352.138996)
		(end 157.986476 -351.353882)
		(width 0.10668)
		(layer "F.Cu")
		(net "PWRGD_PVDD11_S3_P1_R")
	)
	(via
		(at 158.79953 -351.398078)
		(size 0.508)
		(drill 0.254)
		(layers "F.Cu" "B.Cu")
		(net "PWRGD_PVDD11_S3_P1_R")
	)
	(segment
		(start 158.79953 -352.566478)
		(end 158.79953 -351.398078)
		(width 0.10668)
		(layer "B.Cu")
		(net "PWRGD_PVDD11_S3_P1_R")
	)
	(segment
		(start 197.870572 -109.005116)
		(end 198.645018 -109.005116)
		(width 0.10668)
		(layer "F.Cu")
		(net "PWRGD_PVDD11_S3_P1")
	)
	(segment
		(start 202.677014 -86.104476)
		(end 203.921614 -87.349076)
		(width 0.10668)
		(layer "F.Cu")
		(net "PWRGD_PVDD11_S3_P1")
	)
	(segment
		(start 225.32594 -215.659208)
		(end 218.581732 -222.403416)
		(width 0.10668)
		(layer "F.Cu")
		(net "PWRGD_PVDD11_S3_P1")
	)
	(segment
		(start 174.796704 -364.84306)
		(end 173.047406 -363.093762)
		(width 0.10668)
		(layer "F.Cu")
		(net "PWRGD_PVDD11_S3_P1")
	)
	(segment
		(start 223.570546 -365.82604)
		(end 223.570546 -366.564926)
		(width 0.10668)
		(layer "F.Cu")
		(net "PWRGD_PVDD11_S3_P1")
	)
	(segment
		(start 223.610678 -159.575754)
		(end 228.59111 -164.556186)
		(width 0.10668)
		(layer "F.Cu")
		(net "PWRGD_PVDD11_S3_P1")
	)
	(segment
		(start 201.055986 -370.974874)
		(end 199.899016 -369.817904)
		(width 0.10668)
		(layer "F.Cu")
		(net "PWRGD_PVDD11_S3_P1")
	)
	(segment
		(start 197.669658 -109.561376)
		(end 197.669658 -109.20603)
		(width 0.10668)
		(layer "F.Cu")
		(net "PWRGD_PVDD11_S3_P1")
	)
	(segment
		(start 174.796704 -366.751108)
		(end 174.796704 -364.84306)
		(width 0.10668)
		(layer "F.Cu")
		(net "PWRGD_PVDD11_S3_P1")
	)
	(segment
		(start 222.667068 -367.468404)
		(end 221.928182 -367.468404)
		(width 0.10668)
		(layer "F.Cu")
		(net "PWRGD_PVDD11_S3_P1")
	)
	(segment
		(start 226.117912 -139.99591)
		(end 226.03333 -140.080492)
		(width 0.10668)
		(layer "F.Cu")
		(net "PWRGD_PVDD11_S3_P1")
	)
	(segment
		(start 197.895972 -86.804246)
		(end 198.595742 -86.104476)
		(width 0.10668)
		(layer "F.Cu")
		(net "PWRGD_PVDD11_S3_P1")
	)
	(segment
		(start 209.230214 -87.349076)
		(end 213.330282 -91.449144)
		(width 0.10668)
		(layer "F.Cu")
		(net "PWRGD_PVDD11_S3_P1")
	)
	(segment
		(start 226.00666 -329.580494)
		(end 226.00666 -334.15224)
		(width 0.10668)
		(layer "F.Cu")
		(net "PWRGD_PVDD11_S3_P1")
	)
	(segment
		(start 219.325698 -322.899532)
		(end 226.00666 -329.580494)
		(width 0.10668)
		(layer "F.Cu")
		(net "PWRGD_PVDD11_S3_P1")
	)
	(segment
		(start 224.76968 -365.267494)
		(end 224.129092 -365.267494)
		(width 0.10668)
		(layer "F.Cu")
		(net "PWRGD_PVDD11_S3_P1")
	)
	(segment
		(start 228.59111 -164.556186)
		(end 228.59111 -202.381358)
		(width 0.10668)
		(layer "F.Cu")
		(net "PWRGD_PVDD11_S3_P1")
	)
	(segment
		(start 219.551758 -317.047626)
		(end 219.551758 -318.221614)
		(width 0.10668)
		(layer "F.Cu")
		(net "PWRGD_PVDD11_S3_P1")
	)
	(segment
		(start 175.45558 -367.409984)
		(end 174.796704 -366.751108)
		(width 0.10668)
		(layer "F.Cu")
		(net "PWRGD_PVDD11_S3_P1")
	)
	(segment
		(start 227.39858 -335.54416)
		(end 227.39858 -364.149132)
		(width 0.10668)
		(layer "F.Cu")
		(net "PWRGD_PVDD11_S3_P1")
	)
	(segment
		(start 218.421712 -370.974874)
		(end 201.055986 -370.974874)
		(width 0.10668)
		(layer "F.Cu")
		(net "PWRGD_PVDD11_S3_P1")
	)
	(segment
		(start 224.129092 -365.267494)
		(end 223.570546 -365.82604)
		(width 0.10668)
		(layer "F.Cu")
		(net "PWRGD_PVDD11_S3_P1")
	)
	(segment
		(start 173.047406 -363.093762)
		(end 173.047406 -360.245914)
		(width 0.10668)
		(layer "F.Cu")
		(net "PWRGD_PVDD11_S3_P1")
	)
	(segment
		(start 227.39858 -364.149132)
		(end 226.11588 -365.431832)
		(width 0.10668)
		(layer "F.Cu")
		(net "PWRGD_PVDD11_S3_P1")
	)
	(segment
		(start 178.406298 -367.409984)
		(end 175.45558 -367.409984)
		(width 0.10668)
		(layer "F.Cu")
		(net "PWRGD_PVDD11_S3_P1")
	)
	(segment
		(start 219.325698 -318.447674)
		(end 219.325698 -322.899532)
		(width 0.10668)
		(layer "F.Cu")
		(net "PWRGD_PVDD11_S3_P1")
	)
	(segment
		(start 226.00666 -334.15224)
		(end 227.39858 -335.54416)
		(width 0.10668)
		(layer "F.Cu")
		(net "PWRGD_PVDD11_S3_P1")
	)
	(segment
		(start 220.341952 -91.449144)
		(end 224.966276 -96.073468)
		(width 0.10668)
		(layer "F.Cu")
		(net "PWRGD_PVDD11_S3_P1")
	)
	(segment
		(start 213.330282 -91.449144)
		(end 220.341952 -91.449144)
		(width 0.10668)
		(layer "F.Cu")
		(net "PWRGD_PVDD11_S3_P1")
	)
	(segment
		(start 198.595742 -86.104476)
		(end 202.677014 -86.104476)
		(width 0.10668)
		(layer "F.Cu")
		(net "PWRGD_PVDD11_S3_P1")
	)
	(segment
		(start 223.570546 -366.564926)
		(end 222.667068 -367.468404)
		(width 0.10668)
		(layer "F.Cu")
		(net "PWRGD_PVDD11_S3_P1")
	)
	(segment
		(start 225.32594 -205.646528)
		(end 225.32594 -215.659208)
		(width 0.10668)
		(layer "F.Cu")
		(net "PWRGD_PVDD11_S3_P1")
	)
	(segment
		(start 198.645018 -109.005116)
		(end 199.104758 -108.545376)
		(width 0.10668)
		(layer "F.Cu")
		(net "PWRGD_PVDD11_S3_P1")
	)
	(segment
		(start 228.59111 -202.381358)
		(end 225.32594 -205.646528)
		(width 0.10668)
		(layer "F.Cu")
		(net "PWRGD_PVDD11_S3_P1")
	)
	(segment
		(start 226.03333 -146.25828)
		(end 223.610678 -148.680932)
		(width 0.10668)
		(layer "F.Cu")
		(net "PWRGD_PVDD11_S3_P1")
	)
	(segment
		(start 219.551758 -318.221614)
		(end 219.325698 -318.447674)
		(width 0.10668)
		(layer "F.Cu")
		(net "PWRGD_PVDD11_S3_P1")
	)
	(segment
		(start 226.11588 -365.431832)
		(end 224.934018 -365.431832)
		(width 0.10668)
		(layer "F.Cu")
		(net "PWRGD_PVDD11_S3_P1")
	)
	(segment
		(start 203.921614 -87.349076)
		(end 209.230214 -87.349076)
		(width 0.10668)
		(layer "F.Cu")
		(net "PWRGD_PVDD11_S3_P1")
	)
	(segment
		(start 226.117912 -123.78055)
		(end 226.117912 -139.99591)
		(width 0.10668)
		(layer "F.Cu")
		(net "PWRGD_PVDD11_S3_P1")
	)
	(segment
		(start 218.581732 -222.403416)
		(end 218.581732 -316.0776)
		(width 0.10668)
		(layer "F.Cu")
		(net "PWRGD_PVDD11_S3_P1")
	)
	(segment
		(start 224.934018 -365.431832)
		(end 224.76968 -365.267494)
		(width 0.10668)
		(layer "F.Cu")
		(net "PWRGD_PVDD11_S3_P1")
	)
	(segment
		(start 197.669658 -109.20603)
		(end 197.870572 -109.005116)
		(width 0.10668)
		(layer "F.Cu")
		(net "PWRGD_PVDD11_S3_P1")
	)
	(segment
		(start 224.966276 -116.571268)
		(end 223.075246 -118.462298)
		(width 0.10668)
		(layer "F.Cu")
		(net "PWRGD_PVDD11_S3_P1")
	)
	(segment
		(start 223.610678 -148.680932)
		(end 223.610678 -159.575754)
		(width 0.10668)
		(layer "F.Cu")
		(net "PWRGD_PVDD11_S3_P1")
	)
	(segment
		(start 218.581732 -316.0776)
		(end 219.551758 -317.047626)
		(width 0.10668)
		(layer "F.Cu")
		(net "PWRGD_PVDD11_S3_P1")
	)
	(segment
		(start 180.814218 -369.817904)
		(end 178.406298 -367.409984)
		(width 0.10668)
		(layer "F.Cu")
		(net "PWRGD_PVDD11_S3_P1")
	)
	(segment
		(start 223.075246 -118.462298)
		(end 223.075246 -120.737884)
		(width 0.10668)
		(layer "F.Cu")
		(net "PWRGD_PVDD11_S3_P1")
	)
	(segment
		(start 199.899016 -369.817904)
		(end 180.814218 -369.817904)
		(width 0.10668)
		(layer "F.Cu")
		(net "PWRGD_PVDD11_S3_P1")
	)
	(segment
		(start 221.928182 -367.468404)
		(end 218.421712 -370.974874)
		(width 0.10668)
		(layer "F.Cu")
		(net "PWRGD_PVDD11_S3_P1")
	)
	(segment
		(start 223.075246 -120.737884)
		(end 226.117912 -123.78055)
		(width 0.10668)
		(layer "F.Cu")
		(net "PWRGD_PVDD11_S3_P1")
	)
	(segment
		(start 224.966276 -96.073468)
		(end 224.966276 -116.571268)
		(width 0.10668)
		(layer "F.Cu")
		(net "PWRGD_PVDD11_S3_P1")
	)
	(segment
		(start 226.03333 -140.080492)
		(end 226.03333 -146.25828)
		(width 0.10668)
		(layer "F.Cu")
		(net "PWRGD_PVDD11_S3_P1")
	)
	(via
		(at 154.747214 -352.692208)
		(size 0.6604)
		(drill 0.3302)
		(layers "F.Cu" "B.Cu")
		(net "PWRGD_PVDD11_S3_P1")
	)
	(via
		(at 199.104758 -108.545376)
		(size 0.508)
		(drill 0.254)
		(layers "F.Cu" "B.Cu")
		(net "PWRGD_PVDD11_S3_P1")
	)
	(via
		(at 197.895972 -86.804246)
		(size 0.508)
		(drill 0.254)
		(layers "F.Cu" "B.Cu")
		(net "PWRGD_PVDD11_S3_P1")
	)
	(via
		(at 173.047406 -360.245914)
		(size 0.508)
		(drill 0.254)
		(layers "F.Cu" "B.Cu")
		(net "PWRGD_PVDD11_S3_P1")
	)
	(segment
		(start 154.747214 -352.692208)
		(end 157.8737 -352.692208)
		(width 0.10668)
		(layer "B.Cu")
		(net "PWRGD_PVDD11_S3_P1")
	)
	(segment
		(start 169.004996 -356.888542)
		(end 172.362368 -360.245914)
		(width 0.10668)
		(layer "B.Cu")
		(net "PWRGD_PVDD11_S3_P1")
	)
	(segment
		(start 157.8737 -352.692208)
		(end 157.99943 -352.566478)
		(width 0.10668)
		(layer "B.Cu")
		(net "PWRGD_PVDD11_S3_P1")
	)
	(segment
		(start 154.747214 -353.637088)
		(end 157.998668 -356.888542)
		(width 0.10668)
		(layer "B.Cu")
		(net "PWRGD_PVDD11_S3_P1")
	)
	(segment
		(start 157.998668 -356.888542)
		(end 169.004996 -356.888542)
		(width 0.10668)
		(layer "B.Cu")
		(net "PWRGD_PVDD11_S3_P1")
	)
	(segment
		(start 154.747214 -352.692208)
		(end 154.747214 -353.637088)
		(width 0.10668)
		(layer "B.Cu")
		(net "PWRGD_PVDD11_S3_P1")
	)
	(segment
		(start 172.362368 -360.245914)
		(end 173.047406 -360.245914)
		(width 0.10668)
		(layer "B.Cu")
		(net "PWRGD_PVDD11_S3_P1")
	)
	(segment
		(start 199.063864 -90.974418)
		(end 199.063864 -86.626954)
		(width 0.11684)
		(layer "In4.Cu")
		(net "PWRGD_PVDD11_S3_P1")
	)
	(segment
		(start 198.332598 -86.36762)
		(end 197.895972 -86.804246)
		(width 0.11684)
		(layer "In4.Cu")
		(net "PWRGD_PVDD11_S3_P1")
	)
	(segment
		(start 199.104758 -108.667042)
		(end 199.447912 -109.010196)
		(width 0.11684)
		(layer "In4.Cu")
		(net "PWRGD_PVDD11_S3_P1")
	)
	(segment
		(start 199.447912 -109.010196)
		(end 200.059544 -109.010196)
		(width 0.11684)
		(layer "In4.Cu")
		(net "PWRGD_PVDD11_S3_P1")
	)
	(segment
		(start 200.753218 -108.316522)
		(end 200.753218 -92.663772)
		(width 0.11684)
		(layer "In4.Cu")
		(net "PWRGD_PVDD11_S3_P1")
	)
	(segment
		(start 198.80453 -86.36762)
		(end 198.332598 -86.36762)
		(width 0.11684)
		(layer "In4.Cu")
		(net "PWRGD_PVDD11_S3_P1")
	)
	(segment
		(start 200.059544 -109.010196)
		(end 200.753218 -108.316522)
		(width 0.11684)
		(layer "In4.Cu")
		(net "PWRGD_PVDD11_S3_P1")
	)
	(segment
		(start 200.753218 -92.663772)
		(end 199.063864 -90.974418)
		(width 0.11684)
		(layer "In4.Cu")
		(net "PWRGD_PVDD11_S3_P1")
	)
	(segment
		(start 199.104758 -108.545376)
		(end 199.104758 -108.667042)
		(width 0.11684)
		(layer "In4.Cu")
		(net "PWRGD_PVDD11_S3_P1")
	)
	(segment
		(start 199.063864 -86.626954)
		(end 198.80453 -86.36762)
		(width 0.11684)
		(layer "In4.Cu")
		(net "PWRGD_PVDD11_S3_P1")
	)
	(segment
		(start 414.716468 -365.764064)
		(end 414.716468 -366.780064)
		(width 0.10668)
		(layer "F.Cu")
		(net "PWRGD_PVDD11_S3_P0_R")
	)
	(segment
		(start 415.017458 -364.781592)
		(end 415.113978 -364.878112)
		(width 0.10668)
		(layer "F.Cu")
		(net "PWRGD_PVDD11_S3_P0_R")
	)
	(segment
		(start 416.163506 -363.487462)
		(end 416.517836 -363.487462)
		(width 0.10668)
		(layer "F.Cu")
		(net "PWRGD_PVDD11_S3_P0_R")
	)
	(segment
		(start 414.716468 -365.764064)
		(end 414.716468 -364.797086)
		(width 0.10668)
		(layer "F.Cu")
		(net "PWRGD_PVDD11_S3_P0_R")
	)
	(segment
		(start 415.113978 -364.878112)
		(end 415.347658 -364.878112)
		(width 0.10668)
		(layer "F.Cu")
		(net "PWRGD_PVDD11_S3_P0_R")
	)
	(segment
		(start 414.731962 -364.781592)
		(end 415.017458 -364.781592)
		(width 0.10668)
		(layer "F.Cu")
		(net "PWRGD_PVDD11_S3_P0_R")
	)
	(segment
		(start 415.347658 -364.30331)
		(end 416.163506 -363.487462)
		(width 0.10668)
		(layer "F.Cu")
		(net "PWRGD_PVDD11_S3_P0_R")
	)
	(segment
		(start 415.347658 -364.878112)
		(end 415.347658 -364.30331)
		(width 0.10668)
		(layer "F.Cu")
		(net "PWRGD_PVDD11_S3_P0_R")
	)
	(segment
		(start 414.716468 -364.797086)
		(end 414.731962 -364.781592)
		(width 0.10668)
		(layer "F.Cu")
		(net "PWRGD_PVDD11_S3_P0_R")
	)
	(via
		(at 415.347658 -364.878112)
		(size 0.508)
		(drill 0.254)
		(layers "F.Cu" "B.Cu")
		(net "PWRGD_PVDD11_S3_P0_R")
	)
	(segment
		(start 201.339958 -106.513376)
		(end 202.255882 -106.513376)
		(width 0.10668)
		(layer "F.Cu")
		(net "PWRGD_PVDD11_S3_P0")
	)
	(segment
		(start 413.916368 -366.780064)
		(end 412.79318 -366.780064)
		(width 0.10668)
		(layer "F.Cu")
		(net "PWRGD_PVDD11_S3_P0")
	)
	(via
		(at 202.255882 -106.513376)
		(size 0.508)
		(drill 0.254)
		(layers "F.Cu" "B.Cu")
		(net "PWRGD_PVDD11_S3_P0")
	)
	(via
		(at 380.336044 -118.10492)
		(size 0.508)
		(drill 0.254)
		(layers "F.Cu" "B.Cu")
		(net "PWRGD_PVDD11_S3_P0")
	)
	(via
		(at 412.79318 -366.780064)
		(size 0.508)
		(drill 0.254)
		(layers "F.Cu" "B.Cu")
		(net "PWRGD_PVDD11_S3_P0")
	)
	(segment
		(start 412.99638 -366.576864)
		(end 412.79318 -366.780064)
		(width 0.10668)
		(layer "B.Cu")
		(net "PWRGD_PVDD11_S3_P0")
	)
	(segment
		(start 422.125648 -369.222528)
		(end 420.153338 -367.250218)
		(width 0.10668)
		(layer "B.Cu")
		(net "PWRGD_PVDD11_S3_P0")
	)
	(segment
		(start 382.74625 -118.389908)
		(end 388.056628 -118.389908)
		(width 0.10668)
		(layer "B.Cu")
		(net "PWRGD_PVDD11_S3_P0")
	)
	(segment
		(start 431.396902 -367.068862)
		(end 429.243236 -369.222528)
		(width 0.10668)
		(layer "B.Cu")
		(net "PWRGD_PVDD11_S3_P0")
	)
	(segment
		(start 420.153338 -367.250218)
		(end 420.153338 -366.911382)
		(width 0.10668)
		(layer "B.Cu")
		(net "PWRGD_PVDD11_S3_P0")
	)
	(segment
		(start 448.99961 -177.230532)
		(end 459.664308 -187.89523)
		(width 0.10668)
		(layer "B.Cu")
		(net "PWRGD_PVDD11_S3_P0")
	)
	(segment
		(start 382.359916 -118.776242)
		(end 382.74625 -118.389908)
		(width 0.10668)
		(layer "B.Cu")
		(net "PWRGD_PVDD11_S3_P0")
	)
	(segment
		(start 454.692766 -333.30007)
		(end 446.60947 -341.383366)
		(width 0.10668)
		(layer "B.Cu")
		(net "PWRGD_PVDD11_S3_P0")
	)
	(segment
		(start 389.349742 -119.683022)
		(end 422.237662 -119.683022)
		(width 0.10668)
		(layer "B.Cu")
		(net "PWRGD_PVDD11_S3_P0")
	)
	(segment
		(start 439.414412 -366.271048)
		(end 438.616598 -367.068862)
		(width 0.10668)
		(layer "B.Cu")
		(net "PWRGD_PVDD11_S3_P0")
	)
	(segment
		(start 454.692766 -328.81697)
		(end 454.692766 -333.30007)
		(width 0.10668)
		(layer "B.Cu")
		(net "PWRGD_PVDD11_S3_P0")
	)
	(segment
		(start 380.336044 -118.10492)
		(end 381.007366 -118.776242)
		(width 0.10668)
		(layer "B.Cu")
		(net "PWRGD_PVDD11_S3_P0")
	)
	(segment
		(start 419.81882 -366.576864)
		(end 412.99638 -366.576864)
		(width 0.10668)
		(layer "B.Cu")
		(net "PWRGD_PVDD11_S3_P0")
	)
	(segment
		(start 444.113666 -366.271048)
		(end 439.414412 -366.271048)
		(width 0.10668)
		(layer "B.Cu")
		(net "PWRGD_PVDD11_S3_P0")
	)
	(segment
		(start 422.237662 -119.683022)
		(end 448.99961 -146.44497)
		(width 0.10668)
		(layer "B.Cu")
		(net "PWRGD_PVDD11_S3_P0")
	)
	(segment
		(start 459.664308 -323.845428)
		(end 454.692766 -328.81697)
		(width 0.10668)
		(layer "B.Cu")
		(net "PWRGD_PVDD11_S3_P0")
	)
	(segment
		(start 429.243236 -369.222528)
		(end 422.125648 -369.222528)
		(width 0.10668)
		(layer "B.Cu")
		(net "PWRGD_PVDD11_S3_P0")
	)
	(segment
		(start 446.60947 -341.383366)
		(end 446.60947 -363.775244)
		(width 0.10668)
		(layer "B.Cu")
		(net "PWRGD_PVDD11_S3_P0")
	)
	(segment
		(start 438.616598 -367.068862)
		(end 431.396902 -367.068862)
		(width 0.10668)
		(layer "B.Cu")
		(net "PWRGD_PVDD11_S3_P0")
	)
	(segment
		(start 446.60947 -363.775244)
		(end 444.113666 -366.271048)
		(width 0.10668)
		(layer "B.Cu")
		(net "PWRGD_PVDD11_S3_P0")
	)
	(segment
		(start 381.007366 -118.776242)
		(end 382.359916 -118.776242)
		(width 0.10668)
		(layer "B.Cu")
		(net "PWRGD_PVDD11_S3_P0")
	)
	(segment
		(start 459.664308 -187.89523)
		(end 459.664308 -323.845428)
		(width 0.10668)
		(layer "B.Cu")
		(net "PWRGD_PVDD11_S3_P0")
	)
	(segment
		(start 388.056628 -118.389908)
		(end 389.349742 -119.683022)
		(width 0.10668)
		(layer "B.Cu")
		(net "PWRGD_PVDD11_S3_P0")
	)
	(segment
		(start 420.153338 -366.911382)
		(end 419.81882 -366.576864)
		(width 0.10668)
		(layer "B.Cu")
		(net "PWRGD_PVDD11_S3_P0")
	)
	(segment
		(start 448.99961 -146.44497)
		(end 448.99961 -177.230532)
		(width 0.10668)
		(layer "B.Cu")
		(net "PWRGD_PVDD11_S3_P0")
	)
	(segment
		(start 369.028472 -111.541052)
		(end 369.463828 -111.976408)
		(width 0.11684)
		(layer "In6.Cu")
		(net "PWRGD_PVDD11_S3_P0")
	)
	(segment
		(start 261.08787 -104.26954)
		(end 263.024366 -102.333044)
		(width 0.11684)
		(layer "In6.Cu")
		(net "PWRGD_PVDD11_S3_P0")
	)
	(segment
		(start 214.340948 -105.032556)
		(end 215.80221 -103.571294)
		(width 0.11684)
		(layer "In6.Cu")
		(net "PWRGD_PVDD11_S3_P0")
	)
	(segment
		(start 215.80221 -103.571294)
		(end 221.519242 -103.571294)
		(width 0.11684)
		(layer "In6.Cu")
		(net "PWRGD_PVDD11_S3_P0")
	)
	(segment
		(start 369.463828 -111.976408)
		(end 374.207532 -111.976408)
		(width 0.11684)
		(layer "In6.Cu")
		(net "PWRGD_PVDD11_S3_P0")
	)
	(segment
		(start 202.255882 -106.513376)
		(end 203.736702 -105.032556)
		(width 0.11684)
		(layer "In6.Cu")
		(net "PWRGD_PVDD11_S3_P0")
	)
	(segment
		(start 322.293488 -111.541052)
		(end 369.028472 -111.541052)
		(width 0.11684)
		(layer "In6.Cu")
		(net "PWRGD_PVDD11_S3_P0")
	)
	(segment
		(start 275.194522 -103.398828)
		(end 314.151264 -103.398828)
		(width 0.11684)
		(layer "In6.Cu")
		(net "PWRGD_PVDD11_S3_P0")
	)
	(segment
		(start 314.151264 -103.398828)
		(end 322.293488 -111.541052)
		(width 0.11684)
		(layer "In6.Cu")
		(net "PWRGD_PVDD11_S3_P0")
	)
	(segment
		(start 274.128738 -102.333044)
		(end 275.194522 -103.398828)
		(width 0.11684)
		(layer "In6.Cu")
		(net "PWRGD_PVDD11_S3_P0")
	)
	(segment
		(start 222.217488 -104.26954)
		(end 261.08787 -104.26954)
		(width 0.11684)
		(layer "In6.Cu")
		(net "PWRGD_PVDD11_S3_P0")
	)
	(segment
		(start 374.207532 -111.976408)
		(end 380.336044 -118.10492)
		(width 0.11684)
		(layer "In6.Cu")
		(net "PWRGD_PVDD11_S3_P0")
	)
	(segment
		(start 221.519242 -103.571294)
		(end 222.217488 -104.26954)
		(width 0.11684)
		(layer "In6.Cu")
		(net "PWRGD_PVDD11_S3_P0")
	)
	(segment
		(start 263.024366 -102.333044)
		(end 274.128738 -102.333044)
		(width 0.11684)
		(layer "In6.Cu")
		(net "PWRGD_PVDD11_S3_P0")
	)
	(segment
		(start 203.736702 -105.032556)
		(end 214.340948 -105.032556)
		(width 0.11684)
		(layer "In6.Cu")
		(net "PWRGD_PVDD11_S3_P0")
	)
	(segment
		(start 145.346928 -11.143234)
		(end 145.590514 -10.899648)
		(width 0.10668)
		(layer "F.Cu")
		(net "PWRGD_PS_PWROK_R")
	)
	(segment
		(start 145.346928 -13.599922)
		(end 145.346928 -11.143234)
		(width 0.10668)
		(layer "F.Cu")
		(net "PWRGD_PS_PWROK_R")
	)
	(via
		(at 145.590514 -10.899648)
		(size 0.508)
		(drill 0.254)
		(layers "F.Cu" "B.Cu")
		(net "PWRGD_PS_PWROK_R")
	)
	(segment
		(start 145.590514 -10.899648)
		(end 145.590514 -12.640564)
		(width 0.10668)
		(layer "B.Cu")
		(net "PWRGD_PS_PWROK_R")
	)
	(segment
		(start 145.3388 -12.892278)
		(end 145.3388 -13.362178)
		(width 0.10668)
		(layer "B.Cu")
		(net "PWRGD_PS_PWROK_R")
	)
	(segment
		(start 145.590514 -12.640564)
		(end 145.3388 -12.892278)
		(width 0.10668)
		(layer "B.Cu")
		(net "PWRGD_PS_PWROK_R")
	)
	(segment
		(start 411.562296 -139.083034)
		(end 411.190186 -138.710924)
		(width 0.10668)
		(layer "F.Cu")
		(net "PWRGD_P5V_AUX_R")
	)
	(segment
		(start 411.190186 -138.710924)
		(end 411.190186 -137.87628)
		(width 0.10668)
		(layer "F.Cu")
		(net "PWRGD_P5V_AUX_R")
	)
	(segment
		(start 411.190186 -137.87628)
		(end 410.149548 -136.835642)
		(width 0.10668)
		(layer "F.Cu")
		(net "PWRGD_P5V_AUX_R")
	)
	(segment
		(start 411.870144 -139.083034)
		(end 411.562296 -139.083034)
		(width 0.10668)
		(layer "F.Cu")
		(net "PWRGD_P5V_AUX_R")
	)
	(segment
		(start 410.149548 -136.835642)
		(end 409.86456 -136.835642)
		(width 0.10668)
		(layer "F.Cu")
		(net "PWRGD_P5V_AUX_R")
	)
	(via
		(at 411.190186 -137.87628)
		(size 0.508)
		(drill 0.254)
		(layers "F.Cu" "B.Cu")
		(net "PWRGD_P5V_AUX_R")
	)
	(segment
		(start 411.190186 -138.64336)
		(end 411.190186 -137.87628)
		(width 0.10668)
		(layer "B.Cu")
		(net "PWRGD_P5V_AUX_R")
	)
	(segment
		(start 411.576266 -139.02944)
		(end 411.190186 -138.64336)
		(width 0.10668)
		(layer "B.Cu")
		(net "PWRGD_P5V_AUX_R")
	)
	(segment
		(start 409.06446 -136.835642)
		(end 409.06446 -136.493758)
		(width 0.10668)
		(layer "F.Cu")
		(net "PWRGD_P5V_AUX")
	)
	(segment
		(start 451.26148 -45.75556)
		(end 451.34022 -45.67682)
		(width 0.10668)
		(layer "F.Cu")
		(net "PWRGD_P5V_AUX")
	)
	(segment
		(start 451.26148 -47.780194)
		(end 451.26148 -45.75556)
		(width 0.10668)
		(layer "F.Cu")
		(net "PWRGD_P5V_AUX")
	)
	(segment
		(start 406.075896 -134.931404)
		(end 405.459946 -134.931404)
		(width 0.10668)
		(layer "F.Cu")
		(net "PWRGD_P5V_AUX")
	)
	(segment
		(start 451.34022 -45.67682)
		(end 451.34022 -45.478954)
		(width 0.10668)
		(layer "F.Cu")
		(net "PWRGD_P5V_AUX")
	)
	(segment
		(start 451.739 -48.462946)
		(end 451.739 -48.257714)
		(width 0.10668)
		(layer "F.Cu")
		(net "PWRGD_P5V_AUX")
	)
	(segment
		(start 406.075896 -135.27659)
		(end 406.075896 -134.931404)
		(width 0.10668)
		(layer "F.Cu")
		(net "PWRGD_P5V_AUX")
	)
	(segment
		(start 404.80996 -135.58139)
		(end 403.963378 -135.58139)
		(width 0.10668)
		(layer "F.Cu")
		(net "PWRGD_P5V_AUX")
	)
	(segment
		(start 403.001734 -135.240014)
		(end 403.34311 -135.58139)
		(width 0.10668)
		(layer "F.Cu")
		(net "PWRGD_P5V_AUX")
	)
	(segment
		(start 451.739 -48.257714)
		(end 451.26148 -47.780194)
		(width 0.10668)
		(layer "F.Cu")
		(net "PWRGD_P5V_AUX")
	)
	(segment
		(start 409.06446 -136.493758)
		(end 408.234134 -135.663432)
		(width 0.10668)
		(layer "F.Cu")
		(net "PWRGD_P5V_AUX")
	)
	(segment
		(start 405.459946 -134.931404)
		(end 404.80996 -135.58139)
		(width 0.10668)
		(layer "F.Cu")
		(net "PWRGD_P5V_AUX")
	)
	(segment
		(start 408.234134 -135.663432)
		(end 406.462738 -135.663432)
		(width 0.10668)
		(layer "F.Cu")
		(net "PWRGD_P5V_AUX")
	)
	(segment
		(start 403.34311 -135.58139)
		(end 403.963378 -135.58139)
		(width 0.10668)
		(layer "F.Cu")
		(net "PWRGD_P5V_AUX")
	)
	(segment
		(start 406.462738 -135.663432)
		(end 406.075896 -135.27659)
		(width 0.10668)
		(layer "F.Cu")
		(net "PWRGD_P5V_AUX")
	)
	(segment
		(start 403.001734 -123.013216)
		(end 403.001734 -135.240014)
		(width 0.10668)
		(layer "F.Cu")
		(net "PWRGD_P5V_AUX")
	)
	(via
		(at 403.001734 -123.013216)
		(size 0.508)
		(drill 0.254)
		(layers "F.Cu" "B.Cu")
		(net "PWRGD_P5V_AUX")
	)
	(via
		(at 442.569092 -123.013216)
		(size 0.508)
		(drill 0.254)
		(layers "F.Cu" "B.Cu")
		(net "PWRGD_P5V_AUX")
	)
	(via
		(at 451.34022 -45.478954)
		(size 0.508)
		(drill 0.254)
		(layers "F.Cu" "B.Cu")
		(net "PWRGD_P5V_AUX")
	)
	(segment
		(start 443.55131 -52.578)
		(end 445.782192 -50.347118)
		(width 0.11684)
		(layer "In4.Cu")
		(net "PWRGD_P5V_AUX")
	)
	(segment
		(start 442.577982 -123.004326)
		(end 442.577982 -77.806804)
		(width 0.11684)
		(layer "In4.Cu")
		(net "PWRGD_P5V_AUX")
	)
	(segment
		(start 442.577982 -77.806804)
		(end 444.04534 -76.339446)
		(width 0.11684)
		(layer "In4.Cu")
		(net "PWRGD_P5V_AUX")
	)
	(segment
		(start 446.850262 -50.347118)
		(end 451.34022 -45.85716)
		(width 0.11684)
		(layer "In4.Cu")
		(net "PWRGD_P5V_AUX")
	)
	(segment
		(start 442.569092 -123.013216)
		(end 442.577982 -123.004326)
		(width 0.11684)
		(layer "In4.Cu")
		(net "PWRGD_P5V_AUX")
	)
	(segment
		(start 443.55131 -72.60717)
		(end 443.55131 -52.578)
		(width 0.11684)
		(layer "In4.Cu")
		(net "PWRGD_P5V_AUX")
	)
	(segment
		(start 451.34022 -45.85716)
		(end 451.34022 -45.478954)
		(width 0.11684)
		(layer "In4.Cu")
		(net "PWRGD_P5V_AUX")
	)
	(segment
		(start 444.04534 -76.339446)
		(end 444.04534 -73.1012)
		(width 0.11684)
		(layer "In4.Cu")
		(net "PWRGD_P5V_AUX")
	)
	(segment
		(start 444.04534 -73.1012)
		(end 443.55131 -72.60717)
		(width 0.11684)
		(layer "In4.Cu")
		(net "PWRGD_P5V_AUX")
	)
	(segment
		(start 445.782192 -50.347118)
		(end 446.850262 -50.347118)
		(width 0.11684)
		(layer "In4.Cu")
		(net "PWRGD_P5V_AUX")
	)
	(segment
		(start 403.001734 -123.013216)
		(end 442.569092 -123.013216)
		(width 0.11684)
		(layer "In15.Cu")
		(net "PWRGD_P5V_AUX")
	)
	(segment
		(start 460.174594 -45.077126)
		(end 461.4164 -45.077126)
		(width 0.10668)
		(layer "F.Cu")
		(net "PWRGD_P3V3_AUX")
	)
	(segment
		(start 202.265788 -109.571282)
		(end 204.793088 -109.571282)
		(width 0.10668)
		(layer "F.Cu")
		(net "PWRGD_P3V3_AUX")
	)
	(segment
		(start 201.339958 -109.561376)
		(end 202.255882 -109.561376)
		(width 0.10668)
		(layer "F.Cu")
		(net "PWRGD_P3V3_AUX")
	)
	(segment
		(start 202.255882 -109.561376)
		(end 202.265788 -109.571282)
		(width 0.10668)
		(layer "F.Cu")
		(net "PWRGD_P3V3_AUX")
	)
	(segment
		(start 217.382598 -133.200902)
		(end 217.382598 -132.007102)
		(width 0.10668)
		(layer "F.Cu")
		(net "PWRGD_P3V3_AUX")
	)
	(segment
		(start 204.793088 -109.571282)
		(end 204.802994 -109.561376)
		(width 0.10668)
		(layer "F.Cu")
		(net "PWRGD_P3V3_AUX")
	)
	(segment
		(start 461.4164 -45.077126)
		(end 461.982312 -44.511214)
		(width 0.10668)
		(layer "F.Cu")
		(net "PWRGD_P3V3_AUX")
	)
	(via
		(at 461.982312 -44.511214)
		(size 0.508)
		(drill 0.254)
		(layers "F.Cu" "B.Cu")
		(net "PWRGD_P3V3_AUX")
	)
	(via
		(at 202.255882 -109.561376)
		(size 0.508)
		(drill 0.254)
		(layers "F.Cu" "B.Cu")
		(net "PWRGD_P3V3_AUX")
	)
	(via
		(at 261.149084 -90.41384)
		(size 0.508)
		(drill 0.254)
		(layers "F.Cu" "B.Cu")
		(net "PWRGD_P3V3_AUX")
	)
	(via
		(at 244.35689 -131.822952)
		(size 0.508)
		(drill 0.254)
		(layers "F.Cu" "B.Cu")
		(net "PWRGD_P3V3_AUX")
	)
	(via
		(at 217.382598 -132.007102)
		(size 0.508)
		(drill 0.254)
		(layers "F.Cu" "B.Cu")
		(net "PWRGD_P3V3_AUX")
	)
	(segment
		(start 460.806038 -44.416726)
		(end 461.887824 -44.416726)
		(width 0.10668)
		(layer "B.Cu")
		(net "PWRGD_P3V3_AUX")
	)
	(segment
		(start 461.887824 -44.416726)
		(end 461.982312 -44.511214)
		(width 0.10668)
		(layer "B.Cu")
		(net "PWRGD_P3V3_AUX")
	)
	(segment
		(start 295.173908 -82.854038)
		(end 287.614106 -90.41384)
		(width 0.11684)
		(layer "In6.Cu")
		(net "PWRGD_P3V3_AUX")
	)
	(segment
		(start 262.312912 -90.41384)
		(end 261.149084 -90.41384)
		(width 0.11684)
		(layer "In6.Cu")
		(net "PWRGD_P3V3_AUX")
	)
	(segment
		(start 262.811514 -89.915238)
		(end 262.312912 -90.41384)
		(width 0.11684)
		(layer "In6.Cu")
		(net "PWRGD_P3V3_AUX")
	)
	(segment
		(start 274.382484 -89.915238)
		(end 262.811514 -89.915238)
		(width 0.11684)
		(layer "In6.Cu")
		(net "PWRGD_P3V3_AUX")
	)
	(segment
		(start 287.614106 -90.41384)
		(end 274.881086 -90.41384)
		(width 0.11684)
		(layer "In6.Cu")
		(net "PWRGD_P3V3_AUX")
	)
	(segment
		(start 274.881086 -90.41384)
		(end 274.382484 -89.915238)
		(width 0.11684)
		(layer "In6.Cu")
		(net "PWRGD_P3V3_AUX")
	)
	(segment
		(start 470.113614 -53.058314)
		(end 468.324184 -54.847744)
		(width 0.11684)
		(layer "In6.Cu")
		(net "PWRGD_P3V3_AUX")
	)
	(segment
		(start 468.324184 -73.118218)
		(end 458.588364 -82.854038)
		(width 0.11684)
		(layer "In6.Cu")
		(net "PWRGD_P3V3_AUX")
	)
	(segment
		(start 461.982312 -44.511214)
		(end 462.548224 -45.077126)
		(width 0.11684)
		(layer "In6.Cu")
		(net "PWRGD_P3V3_AUX")
	)
	(segment
		(start 466.013038 -45.077126)
		(end 470.113614 -49.177702)
		(width 0.11684)
		(layer "In6.Cu")
		(net "PWRGD_P3V3_AUX")
	)
	(segment
		(start 470.113614 -49.177702)
		(end 470.113614 -53.058314)
		(width 0.11684)
		(layer "In6.Cu")
		(net "PWRGD_P3V3_AUX")
	)
	(segment
		(start 462.548224 -45.077126)
		(end 466.013038 -45.077126)
		(width 0.11684)
		(layer "In6.Cu")
		(net "PWRGD_P3V3_AUX")
	)
	(segment
		(start 458.588364 -82.854038)
		(end 295.173908 -82.854038)
		(width 0.11684)
		(layer "In6.Cu")
		(net "PWRGD_P3V3_AUX")
	)
	(segment
		(start 468.324184 -54.847744)
		(end 468.324184 -73.118218)
		(width 0.11684)
		(layer "In6.Cu")
		(net "PWRGD_P3V3_AUX")
	)
	(segment
		(start 244.948202 -131.111498)
		(end 249.215656 -131.111498)
		(width 0.11684)
		(layer "In11.Cu")
		(net "PWRGD_P3V3_AUX")
	)
	(segment
		(start 251.247402 -129.079752)
		(end 252.710442 -129.079752)
		(width 0.11684)
		(layer "In11.Cu")
		(net "PWRGD_P3V3_AUX")
	)
	(segment
		(start 261.253224 -108.414312)
		(end 262.272272 -107.395264)
		(width 0.11684)
		(layer "In11.Cu")
		(net "PWRGD_P3V3_AUX")
	)
	(segment
		(start 252.710442 -129.079752)
		(end 254.356362 -127.433832)
		(width 0.11684)
		(layer "In11.Cu")
		(net "PWRGD_P3V3_AUX")
	)
	(segment
		(start 249.215656 -131.111498)
		(end 251.247402 -129.079752)
		(width 0.11684)
		(layer "In11.Cu")
		(net "PWRGD_P3V3_AUX")
	)
	(segment
		(start 262.272272 -107.395264)
		(end 262.272272 -100.916232)
		(width 0.11684)
		(layer "In11.Cu")
		(net "PWRGD_P3V3_AUX")
	)
	(segment
		(start 262.768842 -92.033598)
		(end 261.149084 -90.41384)
		(width 0.11684)
		(layer "In11.Cu")
		(net "PWRGD_P3V3_AUX")
	)
	(segment
		(start 244.35689 -131.822952)
		(end 244.35689 -131.70281)
		(width 0.11684)
		(layer "In11.Cu")
		(net "PWRGD_P3V3_AUX")
	)
	(segment
		(start 260.809486 -108.414312)
		(end 261.253224 -108.414312)
		(width 0.11684)
		(layer "In11.Cu")
		(net "PWRGD_P3V3_AUX")
	)
	(segment
		(start 254.356362 -127.433832)
		(end 254.356362 -114.867436)
		(width 0.11684)
		(layer "In11.Cu")
		(net "PWRGD_P3V3_AUX")
	)
	(segment
		(start 262.768842 -100.419662)
		(end 262.768842 -92.033598)
		(width 0.11684)
		(layer "In11.Cu")
		(net "PWRGD_P3V3_AUX")
	)
	(segment
		(start 244.35689 -131.70281)
		(end 244.948202 -131.111498)
		(width 0.11684)
		(layer "In11.Cu")
		(net "PWRGD_P3V3_AUX")
	)
	(segment
		(start 262.272272 -100.916232)
		(end 262.768842 -100.419662)
		(width 0.11684)
		(layer "In11.Cu")
		(net "PWRGD_P3V3_AUX")
	)
	(segment
		(start 254.356362 -114.867436)
		(end 260.809486 -108.414312)
		(width 0.11684)
		(layer "In11.Cu")
		(net "PWRGD_P3V3_AUX")
	)
	(segment
		(start 255.166114 -93.88348)
		(end 257.679444 -93.88348)
		(width 0.11684)
		(layer "In15.Cu")
		(net "PWRGD_P3V3_AUX")
	)
	(segment
		(start 217.382598 -132.007102)
		(end 217.502232 -132.126736)
		(width 0.11684)
		(layer "In15.Cu")
		(net "PWRGD_P3V3_AUX")
	)
	(segment
		(start 202.255882 -109.561376)
		(end 204.498194 -109.561376)
		(width 0.11684)
		(layer "In15.Cu")
		(net "PWRGD_P3V3_AUX")
	)
	(segment
		(start 223.384618 -109.381036)
		(end 233.351832 -109.381036)
		(width 0.11684)
		(layer "In15.Cu")
		(net "PWRGD_P3V3_AUX")
	)
	(segment
		(start 254.449326 -93.166692)
		(end 255.166114 -93.88348)
		(width 0.11684)
		(layer "In15.Cu")
		(net "PWRGD_P3V3_AUX")
	)
	(segment
		(start 221.92615 -110.839504)
		(end 223.384618 -109.381036)
		(width 0.11684)
		(layer "In15.Cu")
		(net "PWRGD_P3V3_AUX")
	)
	(segment
		(start 233.351832 -109.381036)
		(end 249.566176 -93.166692)
		(width 0.11684)
		(layer "In15.Cu")
		(net "PWRGD_P3V3_AUX")
	)
	(segment
		(start 215.820498 -110.839504)
		(end 221.92615 -110.839504)
		(width 0.11684)
		(layer "In15.Cu")
		(net "PWRGD_P3V3_AUX")
	)
	(segment
		(start 244.053106 -132.126736)
		(end 244.35689 -131.822952)
		(width 0.11684)
		(layer "In15.Cu")
		(net "PWRGD_P3V3_AUX")
	)
	(segment
		(start 257.679444 -93.88348)
		(end 261.149084 -90.41384)
		(width 0.11684)
		(layer "In15.Cu")
		(net "PWRGD_P3V3_AUX")
	)
	(segment
		(start 249.566176 -93.166692)
		(end 254.449326 -93.166692)
		(width 0.11684)
		(layer "In15.Cu")
		(net "PWRGD_P3V3_AUX")
	)
	(segment
		(start 205.044294 -109.015276)
		(end 213.99627 -109.015276)
		(width 0.11684)
		(layer "In15.Cu")
		(net "PWRGD_P3V3_AUX")
	)
	(segment
		(start 204.498194 -109.561376)
		(end 205.044294 -109.015276)
		(width 0.11684)
		(layer "In15.Cu")
		(net "PWRGD_P3V3_AUX")
	)
	(segment
		(start 213.99627 -109.015276)
		(end 215.820498 -110.839504)
		(width 0.11684)
		(layer "In15.Cu")
		(net "PWRGD_P3V3_AUX")
	)
	(segment
		(start 217.502232 -132.126736)
		(end 244.053106 -132.126736)
		(width 0.11684)
		(layer "In15.Cu")
		(net "PWRGD_P3V3_AUX")
	)
	(segment
		(start 145.823178 -75.64374)
		(end 145.401538 -76.06538)
		(width 0.10668)
		(layer "F.Cu")
		(net "PWRGD_P1V8_AUX")
	)
	(segment
		(start 214.930228 -128.804924)
		(end 214.372952 -128.804924)
		(width 0.10668)
		(layer "F.Cu")
		(net "PWRGD_P1V8_AUX")
	)
	(segment
		(start 145.377916 -76.089002)
		(end 145.377916 -76.301092)
		(width 0.10668)
		(layer "F.Cu")
		(net "PWRGD_P1V8_AUX")
	)
	(segment
		(start 145.204942 -76.474066)
		(end 145.204942 -77.302614)
		(width 0.10668)
		(layer "F.Cu")
		(net "PWRGD_P1V8_AUX")
	)
	(segment
		(start 214.372952 -128.804924)
		(end 213.830916 -128.262888)
		(width 0.10668)
		(layer "F.Cu")
		(net "PWRGD_P1V8_AUX")
	)
	(segment
		(start 145.377916 -76.301092)
		(end 145.204942 -76.474066)
		(width 0.10668)
		(layer "F.Cu")
		(net "PWRGD_P1V8_AUX")
	)
	(segment
		(start 145.204942 -77.302614)
		(end 144.719802 -77.787754)
		(width 0.10668)
		(layer "F.Cu")
		(net "PWRGD_P1V8_AUX")
	)
	(segment
		(start 145.401538 -76.06538)
		(end 145.377916 -76.089002)
		(width 0.10668)
		(layer "F.Cu")
		(net "PWRGD_P1V8_AUX")
	)
	(segment
		(start 145.823178 -75.515216)
		(end 145.823178 -75.64374)
		(width 0.10668)
		(layer "F.Cu")
		(net "PWRGD_P1V8_AUX")
	)
	(segment
		(start 144.719802 -77.787754)
		(end 144.311624 -77.787754)
		(width 0.10668)
		(layer "F.Cu")
		(net "PWRGD_P1V8_AUX")
	)
	(via
		(at 213.830916 -128.262888)
		(size 0.762)
		(drill 0.254)
		(layers "F.Cu" "B.Cu")
		(net "PWRGD_P1V8_AUX")
	)
	(via
		(at 145.401538 -76.06538)
		(size 0.508)
		(drill 0.254)
		(layers "F.Cu" "B.Cu")
		(net "PWRGD_P1V8_AUX")
	)
	(segment
		(start 207.82534 -86.13648)
		(end 212.10778 -90.41892)
		(width 0.10668)
		(layer "B.Cu")
		(net "PWRGD_P1V8_AUX")
	)
	(segment
		(start 186.533536 -84.02574)
		(end 192.99174 -84.02574)
		(width 0.10668)
		(layer "B.Cu")
		(net "PWRGD_P1V8_AUX")
	)
	(segment
		(start 192.99174 -84.02574)
		(end 194.64147 -85.67547)
		(width 0.10668)
		(layer "B.Cu")
		(net "PWRGD_P1V8_AUX")
	)
	(segment
		(start 221.144338 -126.143258)
		(end 217.9447 -129.342896)
		(width 0.10668)
		(layer "B.Cu")
		(net "PWRGD_P1V8_AUX")
	)
	(segment
		(start 154.837384 -72.6948)
		(end 156.70276 -74.560176)
		(width 0.10668)
		(layer "B.Cu")
		(net "PWRGD_P1V8_AUX")
	)
	(segment
		(start 197.54596 -86.13648)
		(end 207.82534 -86.13648)
		(width 0.10668)
		(layer "B.Cu")
		(net "PWRGD_P1V8_AUX")
	)
	(segment
		(start 194.64147 -85.67547)
		(end 197.08495 -85.67547)
		(width 0.10668)
		(layer "B.Cu")
		(net "PWRGD_P1V8_AUX")
	)
	(segment
		(start 221.144338 -111.065818)
		(end 221.144338 -126.143258)
		(width 0.10668)
		(layer "B.Cu")
		(net "PWRGD_P1V8_AUX")
	)
	(segment
		(start 214.209122 -128.641094)
		(end 213.830916 -128.262888)
		(width 0.10668)
		(layer "B.Cu")
		(net "PWRGD_P1V8_AUX")
	)
	(segment
		(start 212.10778 -90.41892)
		(end 212.10778 -93.548708)
		(width 0.10668)
		(layer "B.Cu")
		(net "PWRGD_P1V8_AUX")
	)
	(segment
		(start 156.70276 -74.560176)
		(end 156.70276 -79.45374)
		(width 0.10668)
		(layer "B.Cu")
		(net "PWRGD_P1V8_AUX")
	)
	(segment
		(start 161.457386 -84.208366)
		(end 168.032176 -84.208366)
		(width 0.10668)
		(layer "B.Cu")
		(net "PWRGD_P1V8_AUX")
	)
	(segment
		(start 156.70276 -79.45374)
		(end 161.457386 -84.208366)
		(width 0.10668)
		(layer "B.Cu")
		(net "PWRGD_P1V8_AUX")
	)
	(segment
		(start 168.032176 -84.208366)
		(end 168.859962 -83.38058)
		(width 0.10668)
		(layer "B.Cu")
		(net "PWRGD_P1V8_AUX")
	)
	(segment
		(start 145.401538 -76.06538)
		(end 145.683732 -75.783186)
		(width 0.10668)
		(layer "B.Cu")
		(net "PWRGD_P1V8_AUX")
	)
	(segment
		(start 212.10778 -93.548708)
		(end 215.053418 -96.494346)
		(width 0.10668)
		(layer "B.Cu")
		(net "PWRGD_P1V8_AUX")
	)
	(segment
		(start 145.683732 -75.783186)
		(end 145.683732 -73.279508)
		(width 0.10668)
		(layer "B.Cu")
		(net "PWRGD_P1V8_AUX")
	)
	(segment
		(start 146.26844 -72.6948)
		(end 154.837384 -72.6948)
		(width 0.10668)
		(layer "B.Cu")
		(net "PWRGD_P1V8_AUX")
	)
	(segment
		(start 145.683732 -73.279508)
		(end 146.26844 -72.6948)
		(width 0.10668)
		(layer "B.Cu")
		(net "PWRGD_P1V8_AUX")
	)
	(segment
		(start 197.08495 -85.67547)
		(end 197.54596 -86.13648)
		(width 0.10668)
		(layer "B.Cu")
		(net "PWRGD_P1V8_AUX")
	)
	(segment
		(start 168.859962 -83.38058)
		(end 185.888376 -83.38058)
		(width 0.10668)
		(layer "B.Cu")
		(net "PWRGD_P1V8_AUX")
	)
	(segment
		(start 217.9447 -129.342896)
		(end 215.705436 -129.342896)
		(width 0.10668)
		(layer "B.Cu")
		(net "PWRGD_P1V8_AUX")
	)
	(segment
		(start 185.888376 -83.38058)
		(end 186.533536 -84.02574)
		(width 0.10668)
		(layer "B.Cu")
		(net "PWRGD_P1V8_AUX")
	)
	(segment
		(start 220.496892 -101.597714)
		(end 220.496892 -110.418372)
		(width 0.10668)
		(layer "B.Cu")
		(net "PWRGD_P1V8_AUX")
	)
	(segment
		(start 215.003634 -128.641094)
		(end 214.209122 -128.641094)
		(width 0.10668)
		(layer "B.Cu")
		(net "PWRGD_P1V8_AUX")
	)
	(segment
		(start 215.053418 -96.494346)
		(end 215.393524 -96.494346)
		(width 0.10668)
		(layer "B.Cu")
		(net "PWRGD_P1V8_AUX")
	)
	(segment
		(start 215.393524 -96.494346)
		(end 220.496892 -101.597714)
		(width 0.10668)
		(layer "B.Cu")
		(net "PWRGD_P1V8_AUX")
	)
	(segment
		(start 220.496892 -110.418372)
		(end 221.144338 -111.065818)
		(width 0.10668)
		(layer "B.Cu")
		(net "PWRGD_P1V8_AUX")
	)
	(segment
		(start 215.705436 -129.342896)
		(end 215.003634 -128.641094)
		(width 0.10668)
		(layer "B.Cu")
		(net "PWRGD_P1V8_AUX")
	)
	(segment
		(start 186.722004 -121.852944)
		(end 187.111894 -122.242834)
		(width 0.10668)
		(layer "F.Cu")
		(net "TP_PWRGD_P12V_FAN_DR_R")
	)
	(via
		(at 187.111894 -122.242834)
		(size 0.4572)
		(drill 0.254)
		(layers "F.Cu" "B.Cu")
		(net "TP_PWRGD_P12V_FAN_DR_R")
	)
	(via
		(at 187.35294 -128.899666)
		(size 0.6604)
		(drill 0.3302)
		(layers "F.Cu" "B.Cu")
		(net "TP_PWRGD_P12V_FAN_DR_R")
	)
	(segment
		(start 186.604148 -125.535436)
		(end 186.604148 -128.150874)
		(width 0.10668)
		(layer "B.Cu")
		(net "TP_PWRGD_P12V_FAN_DR_R")
	)
	(segment
		(start 187.111894 -122.242834)
		(end 186.936126 -122.242834)
		(width 0.10668)
		(layer "B.Cu")
		(net "TP_PWRGD_P12V_FAN_DR_R")
	)
	(segment
		(start 186.578748 -124.933964)
		(end 186.49696 -125.015752)
		(width 0.10668)
		(layer "B.Cu")
		(net "TP_PWRGD_P12V_FAN_DR_R")
	)
	(segment
		(start 186.604148 -128.150874)
		(end 187.35294 -128.899666)
		(width 0.10668)
		(layer "B.Cu")
		(net "TP_PWRGD_P12V_FAN_DR_R")
	)
	(segment
		(start 186.578748 -122.600212)
		(end 186.578748 -124.933964)
		(width 0.10668)
		(layer "B.Cu")
		(net "TP_PWRGD_P12V_FAN_DR_R")
	)
	(segment
		(start 186.49696 -125.015752)
		(end 186.49696 -125.428248)
		(width 0.10668)
		(layer "B.Cu")
		(net "TP_PWRGD_P12V_FAN_DR_R")
	)
	(segment
		(start 186.49696 -125.428248)
		(end 186.604148 -125.535436)
		(width 0.10668)
		(layer "B.Cu")
		(net "TP_PWRGD_P12V_FAN_DR_R")
	)
	(segment
		(start 186.936126 -122.242834)
		(end 186.578748 -122.600212)
		(width 0.10668)
		(layer "B.Cu")
		(net "TP_PWRGD_P12V_FAN_DR_R")
	)
	(segment
		(start 82.879946 -141.247368)
		(end 82.757264 -141.124686)
		(width 0.10668)
		(layer "F.Cu")
		(net "PWRGD_CPU1_PWROK")
	)
	(segment
		(start 84.057236 -141.124686)
		(end 83.934554 -141.247368)
		(width 0.10668)
		(layer "F.Cu")
		(net "PWRGD_CPU1_PWROK")
	)
	(segment
		(start 82.757264 -140.308838)
		(end 82.757264 -138.562334)
		(width 0.10668)
		(layer "F.Cu")
		(net "PWRGD_CPU1_PWROK")
	)
	(segment
		(start 82.757264 -141.124686)
		(end 82.757264 -140.308838)
		(width 0.10668)
		(layer "F.Cu")
		(net "PWRGD_CPU1_PWROK")
	)
	(segment
		(start 82.637884 -224.50044)
		(end 82.171032 -224.234502)
		(width 0.10668)
		(layer "F.Cu")
		(net "PWRGD_CPU1_PWROK")
	)
	(segment
		(start 82.757264 -137.925048)
		(end 82.757264 -138.562334)
		(width 0.10668)
		(layer "F.Cu")
		(net "PWRGD_CPU1_PWROK")
	)
	(segment
		(start 83.934554 -141.247368)
		(end 82.879946 -141.247368)
		(width 0.10668)
		(layer "F.Cu")
		(net "PWRGD_CPU1_PWROK")
	)
	(segment
		(start 84.057236 -140.308838)
		(end 84.057236 -141.124686)
		(width 0.10668)
		(layer "F.Cu")
		(net "PWRGD_CPU1_PWROK")
	)
	(via
		(at 179.959 -134.584948)
		(size 0.508)
		(drill 0.254)
		(layers "F.Cu" "B.Cu")
		(net "PWRGD_CPU1_PWROK")
	)
	(via
		(at 82.757264 -137.925048)
		(size 0.508)
		(drill 0.254)
		(layers "F.Cu" "B.Cu")
		(net "PWRGD_CPU1_PWROK")
	)
	(via
		(at 82.171032 -224.234502)
		(size 0.4064)
		(drill 0.2032)
		(layers "F.Cu" "B.Cu")
		(net "PWRGD_CPU1_PWROK")
	)
	(via
		(at 72.132698 -206.080868)
		(size 0.508)
		(drill 0.254)
		(layers "F.Cu" "B.Cu")
		(net "PWRGD_CPU1_PWROK")
	)
	(via
		(at 116.099336 -130.01498)
		(size 0.508)
		(drill 0.254)
		(layers "F.Cu" "B.Cu")
		(net "PWRGD_CPU1_PWROK")
	)
	(segment
		(start 179.7812 -133.511798)
		(end 179.83962 -133.453378)
		(width 0.10668)
		(layer "B.Cu")
		(net "PWRGD_CPU1_PWROK")
	)
	(segment
		(start 179.7812 -133.511798)
		(end 179.7812 -133.920992)
		(width 0.10668)
		(layer "B.Cu")
		(net "PWRGD_CPU1_PWROK")
	)
	(segment
		(start 72.472804 -204.228192)
		(end 72.472804 -204.955902)
		(width 0.10668)
		(layer "B.Cu")
		(net "PWRGD_CPU1_PWROK")
	)
	(segment
		(start 179.7812 -133.920992)
		(end 179.959 -134.098792)
		(width 0.10668)
		(layer "B.Cu")
		(net "PWRGD_CPU1_PWROK")
	)
	(segment
		(start 72.132698 -205.296008)
		(end 72.132698 -206.080868)
		(width 0.10668)
		(layer "B.Cu")
		(net "PWRGD_CPU1_PWROK")
	)
	(segment
		(start 179.83962 -133.453378)
		(end 180.681376 -133.453378)
		(width 0.10668)
		(layer "B.Cu")
		(net "PWRGD_CPU1_PWROK")
	)
	(segment
		(start 179.959 -134.098792)
		(end 179.959 -134.584948)
		(width 0.10668)
		(layer "B.Cu")
		(net "PWRGD_CPU1_PWROK")
	)
	(segment
		(start 72.472804 -204.955902)
		(end 72.132698 -205.296008)
		(width 0.10668)
		(layer "B.Cu")
		(net "PWRGD_CPU1_PWROK")
	)
	(segment
		(start 157.079442 -132.089652)
		(end 155.00477 -130.01498)
		(width 0.11684)
		(layer "In6.Cu")
		(net "PWRGD_CPU1_PWROK")
	)
	(segment
		(start 170.791632 -133.352794)
		(end 163.953698 -133.352794)
		(width 0.11684)
		(layer "In6.Cu")
		(net "PWRGD_CPU1_PWROK")
	)
	(segment
		(start 163.953698 -133.352794)
		(end 162.690556 -132.089652)
		(width 0.11684)
		(layer "In6.Cu")
		(net "PWRGD_CPU1_PWROK")
	)
	(segment
		(start 172.488606 -135.049768)
		(end 170.791632 -133.352794)
		(width 0.11684)
		(layer "In6.Cu")
		(net "PWRGD_CPU1_PWROK")
	)
	(segment
		(start 162.690556 -132.089652)
		(end 157.079442 -132.089652)
		(width 0.11684)
		(layer "In6.Cu")
		(net "PWRGD_CPU1_PWROK")
	)
	(segment
		(start 179.49418 -135.049768)
		(end 172.488606 -135.049768)
		(width 0.11684)
		(layer "In6.Cu")
		(net "PWRGD_CPU1_PWROK")
	)
	(segment
		(start 155.00477 -130.01498)
		(end 116.099336 -130.01498)
		(width 0.11684)
		(layer "In6.Cu")
		(net "PWRGD_CPU1_PWROK")
	)
	(segment
		(start 179.959 -134.584948)
		(end 179.49418 -135.049768)
		(width 0.11684)
		(layer "In6.Cu")
		(net "PWRGD_CPU1_PWROK")
	)
	(segment
		(start 78.244954 -214.25789)
		(end 78.244954 -217.924126)
		(width 0.11684)
		(layer "In11.Cu")
		(net "PWRGD_CPU1_PWROK")
	)
	(segment
		(start 42.091356 -156.082238)
		(end 37.130228 -161.043366)
		(width 0.11684)
		(layer "In11.Cu")
		(net "PWRGD_CPU1_PWROK")
	)
	(segment
		(start 72.132698 -206.080868)
		(end 72.132698 -206.382366)
		(width 0.11684)
		(layer "In11.Cu")
		(net "PWRGD_CPU1_PWROK")
	)
	(segment
		(start 42.091356 -147.947888)
		(end 42.091356 -156.082238)
		(width 0.11684)
		(layer "In11.Cu")
		(net "PWRGD_CPU1_PWROK")
	)
	(segment
		(start 37.130228 -161.043366)
		(end 37.130228 -180.07076)
		(width 0.11684)
		(layer "In11.Cu")
		(net "PWRGD_CPU1_PWROK")
	)
	(segment
		(start 78.244954 -217.924126)
		(end 82.171032 -221.850204)
		(width 0.11684)
		(layer "In11.Cu")
		(net "PWRGD_CPU1_PWROK")
	)
	(segment
		(start 41.255188 -188.506862)
		(end 60.148216 -188.506862)
		(width 0.11684)
		(layer "In11.Cu")
		(net "PWRGD_CPU1_PWROK")
	)
	(segment
		(start 81.807812 -136.975596)
		(end 53.063648 -136.975596)
		(width 0.11684)
		(layer "In11.Cu")
		(net "PWRGD_CPU1_PWROK")
	)
	(segment
		(start 72.920352 -201.278998)
		(end 72.920352 -205.293214)
		(width 0.11684)
		(layer "In11.Cu")
		(net "PWRGD_CPU1_PWROK")
	)
	(segment
		(start 82.757264 -137.925048)
		(end 81.807812 -136.975596)
		(width 0.11684)
		(layer "In11.Cu")
		(net "PWRGD_CPU1_PWROK")
	)
	(segment
		(start 39.759382 -182.699914)
		(end 39.759382 -187.011056)
		(width 0.11684)
		(layer "In11.Cu")
		(net "PWRGD_CPU1_PWROK")
	)
	(segment
		(start 84.08797 -136.713214)
		(end 82.876136 -137.925048)
		(width 0.11684)
		(layer "In11.Cu")
		(net "PWRGD_CPU1_PWROK")
	)
	(segment
		(start 72.132698 -206.382366)
		(end 72.814434 -207.064102)
		(width 0.11684)
		(layer "In11.Cu")
		(net "PWRGD_CPU1_PWROK")
	)
	(segment
		(start 72.920352 -205.293214)
		(end 72.132698 -206.080868)
		(width 0.11684)
		(layer "In11.Cu")
		(net "PWRGD_CPU1_PWROK")
	)
	(segment
		(start 82.876136 -137.925048)
		(end 82.757264 -137.925048)
		(width 0.11684)
		(layer "In11.Cu")
		(net "PWRGD_CPU1_PWROK")
	)
	(segment
		(start 60.148216 -188.506862)
		(end 72.920352 -201.278998)
		(width 0.11684)
		(layer "In11.Cu")
		(net "PWRGD_CPU1_PWROK")
	)
	(segment
		(start 116.099336 -130.564382)
		(end 109.950504 -136.713214)
		(width 0.11684)
		(layer "In11.Cu")
		(net "PWRGD_CPU1_PWROK")
	)
	(segment
		(start 116.099336 -130.01498)
		(end 116.099336 -130.564382)
		(width 0.11684)
		(layer "In11.Cu")
		(net "PWRGD_CPU1_PWROK")
	)
	(segment
		(start 39.759382 -187.011056)
		(end 41.255188 -188.506862)
		(width 0.11684)
		(layer "In11.Cu")
		(net "PWRGD_CPU1_PWROK")
	)
	(segment
		(start 72.814434 -207.064102)
		(end 72.814434 -208.82737)
		(width 0.11684)
		(layer "In11.Cu")
		(net "PWRGD_CPU1_PWROK")
	)
	(segment
		(start 37.130228 -180.07076)
		(end 39.759382 -182.699914)
		(width 0.11684)
		(layer "In11.Cu")
		(net "PWRGD_CPU1_PWROK")
	)
	(segment
		(start 72.814434 -208.82737)
		(end 78.244954 -214.25789)
		(width 0.11684)
		(layer "In11.Cu")
		(net "PWRGD_CPU1_PWROK")
	)
	(segment
		(start 82.171032 -221.850204)
		(end 82.171032 -224.234502)
		(width 0.11684)
		(layer "In11.Cu")
		(net "PWRGD_CPU1_PWROK")
	)
	(segment
		(start 53.063648 -136.975596)
		(end 42.091356 -147.947888)
		(width 0.11684)
		(layer "In11.Cu")
		(net "PWRGD_CPU1_PWROK")
	)
	(segment
		(start 109.950504 -136.713214)
		(end 84.08797 -136.713214)
		(width 0.11684)
		(layer "In11.Cu")
		(net "PWRGD_CPU1_PWROK")
	)
	(segment
		(start 288.388298 -156.377132)
		(end 288.388298 -156.554424)
		(width 0.10668)
		(layer "F.Cu")
		(net "PWRGD_CPU0_PWROK")
	)
	(segment
		(start 391.189464 -138.185144)
		(end 391.189464 -139.024614)
		(width 0.10668)
		(layer "F.Cu")
		(net "PWRGD_CPU0_PWROK")
	)
	(segment
		(start 391.189464 -139.79906)
		(end 391.189464 -139.024614)
		(width 0.10668)
		(layer "F.Cu")
		(net "PWRGD_CPU0_PWROK")
	)
	(segment
		(start 283.430726 -160.136332)
		(end 279.419304 -164.147754)
		(width 0.10668)
		(layer "F.Cu")
		(net "PWRGD_CPU0_PWROK")
	)
	(segment
		(start 279.419304 -166.760652)
		(end 285.562802 -172.90415)
		(width 0.10668)
		(layer "F.Cu")
		(net "PWRGD_CPU0_PWROK")
	)
	(segment
		(start 392.489436 -139.79906)
		(end 392.33221 -139.956286)
		(width 0.10668)
		(layer "F.Cu")
		(net "PWRGD_CPU0_PWROK")
	)
	(segment
		(start 296.474896 -172.90415)
		(end 310.036464 -186.465718)
		(width 0.10668)
		(layer "F.Cu")
		(net "PWRGD_CPU0_PWROK")
	)
	(segment
		(start 313.896502 -200.756012)
		(end 317.487808 -204.347318)
		(width 0.10668)
		(layer "F.Cu")
		(net "PWRGD_CPU0_PWROK")
	)
	(segment
		(start 320.966338 -205.388464)
		(end 320.966338 -205.515972)
		(width 0.10668)
		(layer "F.Cu")
		(net "PWRGD_CPU0_PWROK")
	)
	(segment
		(start 310.036464 -186.465718)
		(end 310.036464 -196.895212)
		(width 0.10668)
		(layer "F.Cu")
		(net "PWRGD_CPU0_PWROK")
	)
	(segment
		(start 319.925192 -204.347318)
		(end 320.966338 -205.388464)
		(width 0.10668)
		(layer "F.Cu")
		(net "PWRGD_CPU0_PWROK")
	)
	(segment
		(start 330.577952 -224.500186)
		(end 330.1111 -224.234248)
		(width 0.10668)
		(layer "F.Cu")
		(net "PWRGD_CPU0_PWROK")
	)
	(segment
		(start 279.419304 -164.147754)
		(end 279.419304 -166.760652)
		(width 0.10668)
		(layer "F.Cu")
		(net "PWRGD_CPU0_PWROK")
	)
	(segment
		(start 310.036464 -196.895212)
		(end 313.896502 -200.75525)
		(width 0.10668)
		(layer "F.Cu")
		(net "PWRGD_CPU0_PWROK")
	)
	(segment
		(start 391.082022 -138.077702)
		(end 391.189464 -138.185144)
		(width 0.10668)
		(layer "F.Cu")
		(net "PWRGD_CPU0_PWROK")
	)
	(segment
		(start 313.896502 -200.75525)
		(end 313.896502 -200.756012)
		(width 0.10668)
		(layer "F.Cu")
		(net "PWRGD_CPU0_PWROK")
	)
	(segment
		(start 317.487808 -204.347318)
		(end 319.925192 -204.347318)
		(width 0.10668)
		(layer "F.Cu")
		(net "PWRGD_CPU0_PWROK")
	)
	(segment
		(start 391.34669 -139.956286)
		(end 391.189464 -139.79906)
		(width 0.10668)
		(layer "F.Cu")
		(net "PWRGD_CPU0_PWROK")
	)
	(segment
		(start 391.082022 -137.461752)
		(end 391.082022 -138.077702)
		(width 0.10668)
		(layer "F.Cu")
		(net "PWRGD_CPU0_PWROK")
	)
	(segment
		(start 288.388298 -156.554424)
		(end 284.80639 -160.136332)
		(width 0.10668)
		(layer "F.Cu")
		(net "PWRGD_CPU0_PWROK")
	)
	(segment
		(start 392.489436 -139.024614)
		(end 392.489436 -139.79906)
		(width 0.10668)
		(layer "F.Cu")
		(net "PWRGD_CPU0_PWROK")
	)
	(segment
		(start 285.562802 -172.90415)
		(end 296.474896 -172.90415)
		(width 0.10668)
		(layer "F.Cu")
		(net "PWRGD_CPU0_PWROK")
	)
	(segment
		(start 392.33221 -139.956286)
		(end 391.34669 -139.956286)
		(width 0.10668)
		(layer "F.Cu")
		(net "PWRGD_CPU0_PWROK")
	)
	(segment
		(start 284.80639 -160.136332)
		(end 283.430726 -160.136332)
		(width 0.10668)
		(layer "F.Cu")
		(net "PWRGD_CPU0_PWROK")
	)
	(via
		(at 262.14197 -149.16404)
		(size 0.508)
		(drill 0.254)
		(layers "F.Cu" "B.Cu")
		(net "PWRGD_CPU0_PWROK")
	)
	(via
		(at 330.1111 -224.234248)
		(size 0.4064)
		(drill 0.2032)
		(layers "F.Cu" "B.Cu")
		(net "PWRGD_CPU0_PWROK")
	)
	(via
		(at 320.966338 -205.515972)
		(size 0.508)
		(drill 0.254)
		(layers "F.Cu" "B.Cu")
		(net "PWRGD_CPU0_PWROK")
	)
	(via
		(at 181.909974 -148.732748)
		(size 0.508)
		(drill 0.254)
		(layers "F.Cu" "B.Cu")
		(net "PWRGD_CPU0_PWROK")
	)
	(via
		(at 179.746656 -130.39725)
		(size 0.508)
		(drill 0.254)
		(layers "F.Cu" "B.Cu")
		(net "PWRGD_CPU0_PWROK")
	)
	(via
		(at 288.388298 -156.377132)
		(size 0.508)
		(drill 0.254)
		(layers "F.Cu" "B.Cu")
		(net "PWRGD_CPU0_PWROK")
	)
	(via
		(at 391.082022 -138.077702)
		(size 0.508)
		(drill 0.254)
		(layers "F.Cu" "B.Cu")
		(net "PWRGD_CPU0_PWROK")
	)
	(segment
		(start 179.36337 -130.780536)
		(end 179.746656 -130.39725)
		(width 0.10668)
		(layer "B.Cu")
		(net "PWRGD_CPU0_PWROK")
	)
	(segment
		(start 179.997608 -129.388362)
		(end 179.997608 -127.233426)
		(width 0.10668)
		(layer "B.Cu")
		(net "PWRGD_CPU0_PWROK")
	)
	(segment
		(start 330.600558 -222.754952)
		(end 330.600558 -221.83852)
		(width 0.10668)
		(layer "B.Cu")
		(net "PWRGD_CPU0_PWROK")
	)
	(segment
		(start 179.7812 -132.711698)
		(end 179.7812 -132.114798)
		(width 0.10668)
		(layer "B.Cu")
		(net "PWRGD_CPU0_PWROK")
	)
	(segment
		(start 320.966338 -205.515972)
		(end 320.719958 -205.269592)
		(width 0.10668)
		(layer "B.Cu")
		(net "PWRGD_CPU0_PWROK")
	)
	(segment
		(start 320.719958 -204.825346)
		(end 320.211958 -204.317346)
		(width 0.10668)
		(layer "B.Cu")
		(net "PWRGD_CPU0_PWROK")
	)
	(segment
		(start 330.1111 -223.24441)
		(end 330.600558 -222.754952)
		(width 0.10668)
		(layer "B.Cu")
		(net "PWRGD_CPU0_PWROK")
	)
	(segment
		(start 179.7812 -132.114798)
		(end 179.36337 -131.696968)
		(width 0.10668)
		(layer "B.Cu")
		(net "PWRGD_CPU0_PWROK")
	)
	(segment
		(start 179.746656 -129.639314)
		(end 179.997608 -129.388362)
		(width 0.10668)
		(layer "B.Cu")
		(net "PWRGD_CPU0_PWROK")
	)
	(segment
		(start 330.600558 -221.83852)
		(end 320.966338 -212.2043)
		(width 0.10668)
		(layer "B.Cu")
		(net "PWRGD_CPU0_PWROK")
	)
	(segment
		(start 179.36337 -131.696968)
		(end 179.36337 -130.780536)
		(width 0.10668)
		(layer "B.Cu")
		(net "PWRGD_CPU0_PWROK")
	)
	(segment
		(start 330.1111 -224.234248)
		(end 330.1111 -223.24441)
		(width 0.10668)
		(layer "B.Cu")
		(net "PWRGD_CPU0_PWROK")
	)
	(segment
		(start 320.719958 -205.269592)
		(end 320.719958 -204.825346)
		(width 0.10668)
		(layer "B.Cu")
		(net "PWRGD_CPU0_PWROK")
	)
	(segment
		(start 179.746656 -130.39725)
		(end 179.746656 -129.639314)
		(width 0.10668)
		(layer "B.Cu")
		(net "PWRGD_CPU0_PWROK")
	)
	(segment
		(start 320.966338 -212.2043)
		(end 320.966338 -205.515972)
		(width 0.10668)
		(layer "B.Cu")
		(net "PWRGD_CPU0_PWROK")
	)
	(segment
		(start 315.85916 -154.861768)
		(end 289.903662 -154.861768)
		(width 0.11684)
		(layer "In2.Cu")
		(net "PWRGD_CPU0_PWROK")
	)
	(segment
		(start 199.980042 -144.16659)
		(end 197.3961 -144.16659)
		(width 0.11684)
		(layer "In2.Cu")
		(net "PWRGD_CPU0_PWROK")
	)
	(segment
		(start 391.082022 -138.077702)
		(end 387.934454 -134.930134)
		(width 0.11684)
		(layer "In2.Cu")
		(net "PWRGD_CPU0_PWROK")
	)
	(segment
		(start 192.549018 -144.954244)
		(end 190.23965 -145.910808)
		(width 0.11684)
		(layer "In2.Cu")
		(net "PWRGD_CPU0_PWROK")
	)
	(segment
		(start 371.696996 -135.41502)
		(end 364.566708 -142.545308)
		(width 0.11684)
		(layer "In2.Cu")
		(net "PWRGD_CPU0_PWROK")
	)
	(segment
		(start 197.3961 -144.16659)
		(end 196.608446 -144.954244)
		(width 0.11684)
		(layer "In2.Cu")
		(net "PWRGD_CPU0_PWROK")
	)
	(segment
		(start 289.903662 -154.861768)
		(end 288.388298 -156.377132)
		(width 0.11684)
		(layer "In2.Cu")
		(net "PWRGD_CPU0_PWROK")
	)
	(segment
		(start 262.14197 -149.06625)
		(end 260.247638 -147.171918)
		(width 0.11684)
		(layer "In2.Cu")
		(net "PWRGD_CPU0_PWROK")
	)
	(segment
		(start 254.800608 -147.171918)
		(end 252.582934 -144.954244)
		(width 0.11684)
		(layer "In2.Cu")
		(net "PWRGD_CPU0_PWROK")
	)
	(segment
		(start 322.10756 -153.306526)
		(end 317.414402 -153.306526)
		(width 0.11684)
		(layer "In2.Cu")
		(net "PWRGD_CPU0_PWROK")
	)
	(segment
		(start 200.767696 -144.954244)
		(end 199.980042 -144.16659)
		(width 0.11684)
		(layer "In2.Cu")
		(net "PWRGD_CPU0_PWROK")
	)
	(segment
		(start 252.582934 -144.954244)
		(end 200.767696 -144.954244)
		(width 0.11684)
		(layer "In2.Cu")
		(net "PWRGD_CPU0_PWROK")
	)
	(segment
		(start 387.934454 -134.930134)
		(end 375.830846 -134.930134)
		(width 0.11684)
		(layer "In2.Cu")
		(net "PWRGD_CPU0_PWROK")
	)
	(segment
		(start 375.34596 -135.41502)
		(end 371.696996 -135.41502)
		(width 0.11684)
		(layer "In2.Cu")
		(net "PWRGD_CPU0_PWROK")
	)
	(segment
		(start 330.722478 -144.691608)
		(end 322.10756 -153.306526)
		(width 0.11684)
		(layer "In2.Cu")
		(net "PWRGD_CPU0_PWROK")
	)
	(segment
		(start 190.23965 -145.910808)
		(end 186.213242 -145.910808)
		(width 0.11684)
		(layer "In2.Cu")
		(net "PWRGD_CPU0_PWROK")
	)
	(segment
		(start 375.830846 -134.930134)
		(end 375.34596 -135.41502)
		(width 0.11684)
		(layer "In2.Cu")
		(net "PWRGD_CPU0_PWROK")
	)
	(segment
		(start 196.608446 -144.954244)
		(end 192.549018 -144.954244)
		(width 0.11684)
		(layer "In2.Cu")
		(net "PWRGD_CPU0_PWROK")
	)
	(segment
		(start 186.213242 -145.910808)
		(end 183.391302 -148.732748)
		(width 0.11684)
		(layer "In2.Cu")
		(net "PWRGD_CPU0_PWROK")
	)
	(segment
		(start 364.566708 -142.545308)
		(end 344.804238 -142.545308)
		(width 0.11684)
		(layer "In2.Cu")
		(net "PWRGD_CPU0_PWROK")
	)
	(segment
		(start 260.247638 -147.171918)
		(end 254.800608 -147.171918)
		(width 0.11684)
		(layer "In2.Cu")
		(net "PWRGD_CPU0_PWROK")
	)
	(segment
		(start 317.414402 -153.306526)
		(end 315.85916 -154.861768)
		(width 0.11684)
		(layer "In2.Cu")
		(net "PWRGD_CPU0_PWROK")
	)
	(segment
		(start 183.391302 -148.732748)
		(end 181.909974 -148.732748)
		(width 0.11684)
		(layer "In2.Cu")
		(net "PWRGD_CPU0_PWROK")
	)
	(segment
		(start 342.657938 -144.691608)
		(end 330.722478 -144.691608)
		(width 0.11684)
		(layer "In2.Cu")
		(net "PWRGD_CPU0_PWROK")
	)
	(segment
		(start 262.14197 -149.16404)
		(end 262.14197 -149.06625)
		(width 0.11684)
		(layer "In2.Cu")
		(net "PWRGD_CPU0_PWROK")
	)
	(segment
		(start 344.804238 -142.545308)
		(end 342.657938 -144.691608)
		(width 0.11684)
		(layer "In2.Cu")
		(net "PWRGD_CPU0_PWROK")
	)
	(segment
		(start 181.114954 -133.296914)
		(end 181.114954 -136.144254)
		(width 0.11684)
		(layer "In4.Cu")
		(net "PWRGD_CPU0_PWROK")
	)
	(segment
		(start 179.746656 -130.39725)
		(end 180.833776 -131.48437)
		(width 0.11684)
		(layer "In4.Cu")
		(net "PWRGD_CPU0_PWROK")
	)
	(segment
		(start 181.704488 -136.733788)
		(end 181.704488 -148.527262)
		(width 0.11684)
		(layer "In4.Cu")
		(net "PWRGD_CPU0_PWROK")
	)
	(segment
		(start 180.833776 -131.48437)
		(end 180.833776 -133.015736)
		(width 0.11684)
		(layer "In4.Cu")
		(net "PWRGD_CPU0_PWROK")
	)
	(segment
		(start 181.114954 -136.144254)
		(end 181.704488 -136.733788)
		(width 0.11684)
		(layer "In4.Cu")
		(net "PWRGD_CPU0_PWROK")
	)
	(segment
		(start 180.833776 -133.015736)
		(end 181.114954 -133.296914)
		(width 0.11684)
		(layer "In4.Cu")
		(net "PWRGD_CPU0_PWROK")
	)
	(segment
		(start 181.704488 -148.527262)
		(end 181.909974 -148.732748)
		(width 0.11684)
		(layer "In4.Cu")
		(net "PWRGD_CPU0_PWROK")
	)
	(segment
		(start 286.948118 -153.677366)
		(end 286.948118 -155.192476)
		(width 0.11684)
		(layer "In15.Cu")
		(net "PWRGD_CPU0_PWROK")
	)
	(segment
		(start 287.647888 -155.636722)
		(end 288.388298 -156.377132)
		(width 0.11684)
		(layer "In15.Cu")
		(net "PWRGD_CPU0_PWROK")
	)
	(segment
		(start 287.392364 -155.636722)
		(end 287.647888 -155.636722)
		(width 0.11684)
		(layer "In15.Cu")
		(net "PWRGD_CPU0_PWROK")
	)
	(segment
		(start 279.920446 -146.649694)
		(end 286.948118 -153.677366)
		(width 0.11684)
		(layer "In15.Cu")
		(net "PWRGD_CPU0_PWROK")
	)
	(segment
		(start 272.15465 -149.16404)
		(end 274.668996 -146.649694)
		(width 0.11684)
		(layer "In15.Cu")
		(net "PWRGD_CPU0_PWROK")
	)
	(segment
		(start 274.668996 -146.649694)
		(end 279.920446 -146.649694)
		(width 0.11684)
		(layer "In15.Cu")
		(net "PWRGD_CPU0_PWROK")
	)
	(segment
		(start 262.14197 -149.16404)
		(end 272.15465 -149.16404)
		(width 0.11684)
		(layer "In15.Cu")
		(net "PWRGD_CPU0_PWROK")
	)
	(segment
		(start 286.948118 -155.192476)
		(end 287.392364 -155.636722)
		(width 0.11684)
		(layer "In15.Cu")
		(net "PWRGD_CPU0_PWROK")
	)
	(segment
		(start 202.147932 -193.93535)
		(end 200.992232 -193.93535)
		(width 0.10668)
		(layer "F.Cu")
		(net "PWRGD_CHL_CPU1_DIMM")
	)
	(via
		(at 200.63333 -191.07531)
		(size 0.6604)
		(drill 0.3302)
		(layers "F.Cu" "B.Cu")
		(net "PWRGD_CHL_CPU1_DIMM")
	)
	(via
		(at 200.992232 -193.93535)
		(size 0.4826)
		(drill 0.254)
		(layers "F.Cu" "B.Cu")
		(net "PWRGD_CHL_CPU1_DIMM")
	)
	(segment
		(start 200.76033 -190.94831)
		(end 200.63333 -191.07531)
		(width 0.10668)
		(layer "B.Cu")
		(net "PWRGD_CHL_CPU1_DIMM")
	)
	(segment
		(start 201.413872 -193.93535)
		(end 201.474832 -193.99631)
		(width 0.10668)
		(layer "B.Cu")
		(net "PWRGD_CHL_CPU1_DIMM")
	)
	(segment
		(start 201.75728 -190.94831)
		(end 200.76033 -190.94831)
		(width 0.10668)
		(layer "B.Cu")
		(net "PWRGD_CHL_CPU1_DIMM")
	)
	(segment
		(start 200.992232 -193.93535)
		(end 201.413872 -193.93535)
		(width 0.10668)
		(layer "B.Cu")
		(net "PWRGD_CHL_CPU1_DIMM")
	)
	(segment
		(start 200.391014 -193.334132)
		(end 200.992232 -193.93535)
		(width 0.10668)
		(layer "B.Cu")
		(net "PWRGD_CHL_CPU1_DIMM")
	)
	(segment
		(start 200.391014 -191.317626)
		(end 200.391014 -193.334132)
		(width 0.10668)
		(layer "B.Cu")
		(net "PWRGD_CHL_CPU1_DIMM")
	)
	(segment
		(start 200.63333 -191.07531)
		(end 200.391014 -191.317626)
		(width 0.10668)
		(layer "B.Cu")
		(net "PWRGD_CHL_CPU1_DIMM")
	)
	(segment
		(start 201.474832 -193.99631)
		(end 202.503786 -193.99631)
		(width 0.10668)
		(layer "B.Cu")
		(net "PWRGD_CHL_CPU1_DIMM")
	)
	(segment
		(start 450.088 -193.935096)
		(end 448.9323 -193.935096)
		(width 0.10668)
		(layer "F.Cu")
		(net "PWRGD_CHL_CPU0_DIMM")
	)
	(via
		(at 448.386454 -191.07531)
		(size 0.6604)
		(drill 0.3302)
		(layers "F.Cu" "B.Cu")
		(net "PWRGD_CHL_CPU0_DIMM")
	)
	(via
		(at 448.9323 -193.935096)
		(size 0.4826)
		(drill 0.254)
		(layers "F.Cu" "B.Cu")
		(net "PWRGD_CHL_CPU0_DIMM")
	)
	(segment
		(start 449.35394 -193.935096)
		(end 449.415154 -193.99631)
		(width 0.10668)
		(layer "B.Cu")
		(net "PWRGD_CHL_CPU0_DIMM")
	)
	(segment
		(start 448.9323 -193.935096)
		(end 449.35394 -193.935096)
		(width 0.10668)
		(layer "B.Cu")
		(net "PWRGD_CHL_CPU0_DIMM")
	)
	(segment
		(start 448.894454 -191.32931)
		(end 448.640454 -191.07531)
		(width 0.10668)
		(layer "B.Cu")
		(net "PWRGD_CHL_CPU0_DIMM")
	)
	(segment
		(start 449.415154 -193.99631)
		(end 450.4436 -193.99631)
		(width 0.10668)
		(layer "B.Cu")
		(net "PWRGD_CHL_CPU0_DIMM")
	)
	(segment
		(start 448.386454 -193.38925)
		(end 448.9323 -193.935096)
		(width 0.10668)
		(layer "B.Cu")
		(net "PWRGD_CHL_CPU0_DIMM")
	)
	(segment
		(start 448.640454 -191.07531)
		(end 448.386454 -191.07531)
		(width 0.10668)
		(layer "B.Cu")
		(net "PWRGD_CHL_CPU0_DIMM")
	)
	(segment
		(start 448.386454 -191.07531)
		(end 448.386454 -193.38925)
		(width 0.10668)
		(layer "B.Cu")
		(net "PWRGD_CHL_CPU0_DIMM")
	)
	(segment
		(start 449.510404 -191.32931)
		(end 448.894454 -191.32931)
		(width 0.10668)
		(layer "B.Cu")
		(net "PWRGD_CHL_CPU0_DIMM")
	)
	(segment
		(start 194.604132 -193.93535)
		(end 193.448432 -193.93535)
		(width 0.10668)
		(layer "F.Cu")
		(net "PWRGD_CHK_CPU1_DIMM")
	)
	(via
		(at 193.448432 -193.93535)
		(size 0.4826)
		(drill 0.254)
		(layers "F.Cu" "B.Cu")
		(net "PWRGD_CHK_CPU1_DIMM")
	)
	(via
		(at 193.16446 -191.075564)
		(size 0.6604)
		(drill 0.3302)
		(layers "F.Cu" "B.Cu")
		(net "PWRGD_CHK_CPU1_DIMM")
	)
	(segment
		(start 193.448432 -193.93535)
		(end 193.870072 -193.93535)
		(width 0.10668)
		(layer "B.Cu")
		(net "PWRGD_CHK_CPU1_DIMM")
	)
	(segment
		(start 192.04051 -190.821564)
		(end 192.91046 -190.821564)
		(width 0.10668)
		(layer "B.Cu")
		(net "PWRGD_CHK_CPU1_DIMM")
	)
	(segment
		(start 192.91046 -190.821564)
		(end 193.16446 -191.075564)
		(width 0.10668)
		(layer "B.Cu")
		(net "PWRGD_CHK_CPU1_DIMM")
	)
	(segment
		(start 193.16446 -191.075564)
		(end 192.91935 -191.320674)
		(width 0.10668)
		(layer "B.Cu")
		(net "PWRGD_CHK_CPU1_DIMM")
	)
	(segment
		(start 193.931286 -193.996564)
		(end 194.959732 -193.996564)
		(width 0.10668)
		(layer "B.Cu")
		(net "PWRGD_CHK_CPU1_DIMM")
	)
	(segment
		(start 193.12128 -193.93535)
		(end 193.448432 -193.93535)
		(width 0.10668)
		(layer "B.Cu")
		(net "PWRGD_CHK_CPU1_DIMM")
	)
	(segment
		(start 193.870072 -193.93535)
		(end 193.931286 -193.996564)
		(width 0.10668)
		(layer "B.Cu")
		(net "PWRGD_CHK_CPU1_DIMM")
	)
	(segment
		(start 192.91935 -191.320674)
		(end 192.91935 -193.73342)
		(width 0.10668)
		(layer "B.Cu")
		(net "PWRGD_CHK_CPU1_DIMM")
	)
	(segment
		(start 192.91935 -193.73342)
		(end 193.12128 -193.93535)
		(width 0.10668)
		(layer "B.Cu")
		(net "PWRGD_CHK_CPU1_DIMM")
	)
	(segment
		(start 442.5442 -193.935096)
		(end 441.3885 -193.935096)
		(width 0.10668)
		(layer "F.Cu")
		(net "PWRGD_CHK_CPU0_DIMM")
	)
	(via
		(at 440.639454 -191.07531)
		(size 0.6604)
		(drill 0.3302)
		(layers "F.Cu" "B.Cu")
		(net "PWRGD_CHK_CPU0_DIMM")
	)
	(via
		(at 441.3885 -193.935096)
		(size 0.4826)
		(drill 0.254)
		(layers "F.Cu" "B.Cu")
		(net "PWRGD_CHK_CPU0_DIMM")
	)
	(segment
		(start 441.763404 -191.07531)
		(end 440.639454 -191.07531)
		(width 0.10668)
		(layer "B.Cu")
		(net "PWRGD_CHK_CPU0_DIMM")
	)
	(segment
		(start 441.81014 -193.935096)
		(end 441.871354 -193.99631)
		(width 0.10668)
		(layer "B.Cu")
		(net "PWRGD_CHK_CPU0_DIMM")
	)
	(segment
		(start 440.639454 -191.58331)
		(end 440.893454 -191.83731)
		(width 0.10668)
		(layer "B.Cu")
		(net "PWRGD_CHK_CPU0_DIMM")
	)
	(segment
		(start 440.893454 -191.83731)
		(end 440.893454 -193.44005)
		(width 0.10668)
		(layer "B.Cu")
		(net "PWRGD_CHK_CPU0_DIMM")
	)
	(segment
		(start 441.871354 -193.99631)
		(end 442.8998 -193.99631)
		(width 0.10668)
		(layer "B.Cu")
		(net "PWRGD_CHK_CPU0_DIMM")
	)
	(segment
		(start 440.893454 -193.44005)
		(end 441.3885 -193.935096)
		(width 0.10668)
		(layer "B.Cu")
		(net "PWRGD_CHK_CPU0_DIMM")
	)
	(segment
		(start 441.890404 -191.20231)
		(end 441.763404 -191.07531)
		(width 0.10668)
		(layer "B.Cu")
		(net "PWRGD_CHK_CPU0_DIMM")
	)
	(segment
		(start 440.639454 -191.07531)
		(end 440.639454 -191.58331)
		(width 0.10668)
		(layer "B.Cu")
		(net "PWRGD_CHK_CPU0_DIMM")
	)
	(segment
		(start 441.3885 -193.935096)
		(end 441.81014 -193.935096)
		(width 0.10668)
		(layer "B.Cu")
		(net "PWRGD_CHK_CPU0_DIMM")
	)
	(segment
		(start 187.060078 -193.93535)
		(end 185.904378 -193.93535)
		(width 0.10668)
		(layer "F.Cu")
		(net "PWRGD_CHJ_CPU1_DIMM")
	)
	(via
		(at 185.29046 -191.075564)
		(size 0.6604)
		(drill 0.3302)
		(layers "F.Cu" "B.Cu")
		(net "PWRGD_CHJ_CPU1_DIMM")
	)
	(via
		(at 185.904378 -193.93535)
		(size 0.4826)
		(drill 0.254)
		(layers "F.Cu" "B.Cu")
		(net "PWRGD_CHJ_CPU1_DIMM")
	)
	(segment
		(start 186.326018 -193.93535)
		(end 186.387232 -193.996564)
		(width 0.10668)
		(layer "B.Cu")
		(net "PWRGD_CHJ_CPU1_DIMM")
	)
	(segment
		(start 186.387232 -193.996564)
		(end 187.415678 -193.996564)
		(width 0.10668)
		(layer "B.Cu")
		(net "PWRGD_CHJ_CPU1_DIMM")
	)
	(segment
		(start 185.29046 -193.321432)
		(end 185.904378 -193.93535)
		(width 0.10668)
		(layer "B.Cu")
		(net "PWRGD_CHJ_CPU1_DIMM")
	)
	(segment
		(start 186.41441 -190.948564)
		(end 185.41746 -190.948564)
		(width 0.10668)
		(layer "B.Cu")
		(net "PWRGD_CHJ_CPU1_DIMM")
	)
	(segment
		(start 185.41746 -190.948564)
		(end 185.29046 -191.075564)
		(width 0.10668)
		(layer "B.Cu")
		(net "PWRGD_CHJ_CPU1_DIMM")
	)
	(segment
		(start 185.29046 -191.075564)
		(end 185.29046 -193.321432)
		(width 0.10668)
		(layer "B.Cu")
		(net "PWRGD_CHJ_CPU1_DIMM")
	)
	(segment
		(start 185.904378 -193.93535)
		(end 186.326018 -193.93535)
		(width 0.10668)
		(layer "B.Cu")
		(net "PWRGD_CHJ_CPU1_DIMM")
	)
	(segment
		(start 435.000146 -193.935096)
		(end 433.844446 -193.935096)
		(width 0.10668)
		(layer "F.Cu")
		(net "PWRGD_CHJ_CPU0_DIMM")
	)
	(via
		(at 433.273454 -191.07531)
		(size 0.6604)
		(drill 0.3302)
		(layers "F.Cu" "B.Cu")
		(net "PWRGD_CHJ_CPU0_DIMM")
	)
	(via
		(at 433.844446 -193.935096)
		(size 0.4826)
		(drill 0.254)
		(layers "F.Cu" "B.Cu")
		(net "PWRGD_CHJ_CPU0_DIMM")
	)
	(segment
		(start 434.266086 -193.935096)
		(end 434.3273 -193.99631)
		(width 0.10668)
		(layer "B.Cu")
		(net "PWRGD_CHJ_CPU0_DIMM")
	)
	(segment
		(start 434.270404 -191.07531)
		(end 433.273454 -191.07531)
		(width 0.10668)
		(layer "B.Cu")
		(net "PWRGD_CHJ_CPU0_DIMM")
	)
	(segment
		(start 433.28844 -191.090296)
		(end 433.28844 -193.37909)
		(width 0.10668)
		(layer "B.Cu")
		(net "PWRGD_CHJ_CPU0_DIMM")
	)
	(segment
		(start 433.273454 -191.07531)
		(end 433.28844 -191.090296)
		(width 0.10668)
		(layer "B.Cu")
		(net "PWRGD_CHJ_CPU0_DIMM")
	)
	(segment
		(start 433.28844 -193.37909)
		(end 433.844446 -193.935096)
		(width 0.10668)
		(layer "B.Cu")
		(net "PWRGD_CHJ_CPU0_DIMM")
	)
	(segment
		(start 433.844446 -193.935096)
		(end 434.266086 -193.935096)
		(width 0.10668)
		(layer "B.Cu")
		(net "PWRGD_CHJ_CPU0_DIMM")
	)
	(segment
		(start 434.3273 -193.99631)
		(end 435.355746 -193.99631)
		(width 0.10668)
		(layer "B.Cu")
		(net "PWRGD_CHJ_CPU0_DIMM")
	)
	(segment
		(start 434.397404 -191.20231)
		(end 434.270404 -191.07531)
		(width 0.10668)
		(layer "B.Cu")
		(net "PWRGD_CHJ_CPU0_DIMM")
	)
	(segment
		(start 179.516024 -193.93535)
		(end 178.360324 -193.93535)
		(width 0.10668)
		(layer "F.Cu")
		(net "PWRGD_CHI_CPU1_DIMM")
	)
	(via
		(at 177.79746 -191.075564)
		(size 0.6604)
		(drill 0.3302)
		(layers "F.Cu" "B.Cu")
		(net "PWRGD_CHI_CPU1_DIMM")
	)
	(via
		(at 178.360324 -193.93535)
		(size 0.4826)
		(drill 0.254)
		(layers "F.Cu" "B.Cu")
		(net "PWRGD_CHI_CPU1_DIMM")
	)
	(segment
		(start 177.804572 -191.082676)
		(end 177.804572 -193.379598)
		(width 0.10668)
		(layer "B.Cu")
		(net "PWRGD_CHI_CPU1_DIMM")
	)
	(segment
		(start 177.79746 -191.075564)
		(end 177.804572 -191.082676)
		(width 0.10668)
		(layer "B.Cu")
		(net "PWRGD_CHI_CPU1_DIMM")
	)
	(segment
		(start 178.843178 -193.996564)
		(end 179.871878 -193.996564)
		(width 0.10668)
		(layer "B.Cu")
		(net "PWRGD_CHI_CPU1_DIMM")
	)
	(segment
		(start 177.804572 -193.379598)
		(end 178.360324 -193.93535)
		(width 0.10668)
		(layer "B.Cu")
		(net "PWRGD_CHI_CPU1_DIMM")
	)
	(segment
		(start 178.360324 -193.93535)
		(end 178.781964 -193.93535)
		(width 0.10668)
		(layer "B.Cu")
		(net "PWRGD_CHI_CPU1_DIMM")
	)
	(segment
		(start 178.781964 -193.93535)
		(end 178.843178 -193.996564)
		(width 0.10668)
		(layer "B.Cu")
		(net "PWRGD_CHI_CPU1_DIMM")
	)
	(segment
		(start 178.92141 -190.948564)
		(end 177.92446 -190.948564)
		(width 0.10668)
		(layer "B.Cu")
		(net "PWRGD_CHI_CPU1_DIMM")
	)
	(segment
		(start 177.92446 -190.948564)
		(end 177.79746 -191.075564)
		(width 0.10668)
		(layer "B.Cu")
		(net "PWRGD_CHI_CPU1_DIMM")
	)
	(segment
		(start 427.456092 -193.935096)
		(end 426.300392 -193.935096)
		(width 0.10668)
		(layer "F.Cu")
		(net "PWRGD_CHI_CPU0_DIMM")
	)
	(via
		(at 425.907454 -191.07531)
		(size 0.6604)
		(drill 0.3302)
		(layers "F.Cu" "B.Cu")
		(net "PWRGD_CHI_CPU0_DIMM")
	)
	(via
		(at 426.300392 -193.935096)
		(size 0.4826)
		(drill 0.254)
		(layers "F.Cu" "B.Cu")
		(net "PWRGD_CHI_CPU0_DIMM")
	)
	(segment
		(start 425.744386 -193.37909)
		(end 426.300392 -193.935096)
		(width 0.10668)
		(layer "B.Cu")
		(net "PWRGD_CHI_CPU0_DIMM")
	)
	(segment
		(start 425.907454 -191.07531)
		(end 425.744386 -191.238378)
		(width 0.10668)
		(layer "B.Cu")
		(net "PWRGD_CHI_CPU0_DIMM")
	)
	(segment
		(start 427.158404 -191.32931)
		(end 426.904404 -191.07531)
		(width 0.10668)
		(layer "B.Cu")
		(net "PWRGD_CHI_CPU0_DIMM")
	)
	(segment
		(start 425.744386 -191.238378)
		(end 425.744386 -193.37909)
		(width 0.10668)
		(layer "B.Cu")
		(net "PWRGD_CHI_CPU0_DIMM")
	)
	(segment
		(start 426.904404 -191.07531)
		(end 425.907454 -191.07531)
		(width 0.10668)
		(layer "B.Cu")
		(net "PWRGD_CHI_CPU0_DIMM")
	)
	(segment
		(start 426.300392 -193.935096)
		(end 427.750478 -193.935096)
		(width 0.10668)
		(layer "B.Cu")
		(net "PWRGD_CHI_CPU0_DIMM")
	)
	(segment
		(start 427.750478 -193.935096)
		(end 427.811692 -193.99631)
		(width 0.10668)
		(layer "B.Cu")
		(net "PWRGD_CHI_CPU0_DIMM")
	)
	(segment
		(start 171.97197 -193.93535)
		(end 170.81627 -193.93535)
		(width 0.10668)
		(layer "F.Cu")
		(net "PWRGD_CHH_CPU1_DIMM")
	)
	(via
		(at 170.30446 -191.075564)
		(size 0.6604)
		(drill 0.3302)
		(layers "F.Cu" "B.Cu")
		(net "PWRGD_CHH_CPU1_DIMM")
	)
	(via
		(at 170.81627 -193.93535)
		(size 0.4826)
		(drill 0.254)
		(layers "F.Cu" "B.Cu")
		(net "PWRGD_CHH_CPU1_DIMM")
	)
	(segment
		(start 171.42841 -190.948564)
		(end 170.43146 -190.948564)
		(width 0.10668)
		(layer "B.Cu")
		(net "PWRGD_CHH_CPU1_DIMM")
	)
	(segment
		(start 171.23791 -193.93535)
		(end 171.299124 -193.996564)
		(width 0.10668)
		(layer "B.Cu")
		(net "PWRGD_CHH_CPU1_DIMM")
	)
	(segment
		(start 170.260518 -193.379598)
		(end 170.81627 -193.93535)
		(width 0.10668)
		(layer "B.Cu")
		(net "PWRGD_CHH_CPU1_DIMM")
	)
	(segment
		(start 170.43146 -190.948564)
		(end 170.30446 -191.075564)
		(width 0.10668)
		(layer "B.Cu")
		(net "PWRGD_CHH_CPU1_DIMM")
	)
	(segment
		(start 171.299124 -193.996564)
		(end 172.327824 -193.996564)
		(width 0.10668)
		(layer "B.Cu")
		(net "PWRGD_CHH_CPU1_DIMM")
	)
	(segment
		(start 170.30446 -191.075564)
		(end 170.260518 -191.119506)
		(width 0.10668)
		(layer "B.Cu")
		(net "PWRGD_CHH_CPU1_DIMM")
	)
	(segment
		(start 170.260518 -191.119506)
		(end 170.260518 -193.379598)
		(width 0.10668)
		(layer "B.Cu")
		(net "PWRGD_CHH_CPU1_DIMM")
	)
	(segment
		(start 170.81627 -193.93535)
		(end 171.23791 -193.93535)
		(width 0.10668)
		(layer "B.Cu")
		(net "PWRGD_CHH_CPU1_DIMM")
	)
	(segment
		(start 419.912038 -193.935096)
		(end 418.756338 -193.935096)
		(width 0.10668)
		(layer "F.Cu")
		(net "PWRGD_CHH_CPU0_DIMM")
	)
	(via
		(at 418.160454 -191.07531)
		(size 0.6604)
		(drill 0.3302)
		(layers "F.Cu" "B.Cu")
		(net "PWRGD_CHH_CPU0_DIMM")
	)
	(via
		(at 418.756338 -193.935096)
		(size 0.4826)
		(drill 0.254)
		(layers "F.Cu" "B.Cu")
		(net "PWRGD_CHH_CPU0_DIMM")
	)
	(segment
		(start 418.160454 -191.07531)
		(end 418.160454 -193.339212)
		(width 0.10668)
		(layer "B.Cu")
		(net "PWRGD_CHH_CPU0_DIMM")
	)
	(segment
		(start 418.756338 -193.935096)
		(end 420.206424 -193.935096)
		(width 0.10668)
		(layer "B.Cu")
		(net "PWRGD_CHH_CPU0_DIMM")
	)
	(segment
		(start 419.284404 -191.32931)
		(end 419.030404 -191.07531)
		(width 0.10668)
		(layer "B.Cu")
		(net "PWRGD_CHH_CPU0_DIMM")
	)
	(segment
		(start 420.206424 -193.935096)
		(end 420.267638 -193.99631)
		(width 0.10668)
		(layer "B.Cu")
		(net "PWRGD_CHH_CPU0_DIMM")
	)
	(segment
		(start 419.030404 -191.07531)
		(end 418.160454 -191.07531)
		(width 0.10668)
		(layer "B.Cu")
		(net "PWRGD_CHH_CPU0_DIMM")
	)
	(segment
		(start 418.160454 -193.339212)
		(end 418.756338 -193.935096)
		(width 0.10668)
		(layer "B.Cu")
		(net "PWRGD_CHH_CPU0_DIMM")
	)
	(segment
		(start 164.427916 -193.93535)
		(end 163.272216 -193.93535)
		(width 0.10668)
		(layer "F.Cu")
		(net "PWRGD_CHG_CPU1_DIMM0")
	)
	(via
		(at 162.81146 -190.694564)
		(size 0.6604)
		(drill 0.3302)
		(layers "F.Cu" "B.Cu")
		(net "PWRGD_CHG_CPU1_DIMM0")
	)
	(via
		(at 163.272216 -193.93535)
		(size 0.4826)
		(drill 0.254)
		(layers "F.Cu" "B.Cu")
		(net "PWRGD_CHG_CPU1_DIMM0")
	)
	(segment
		(start 163.80841 -190.694564)
		(end 162.81146 -190.694564)
		(width 0.10668)
		(layer "B.Cu")
		(net "PWRGD_CHG_CPU1_DIMM0")
	)
	(segment
		(start 162.81146 -190.694564)
		(end 162.7759 -190.730124)
		(width 0.10668)
		(layer "B.Cu")
		(net "PWRGD_CHG_CPU1_DIMM0")
	)
	(segment
		(start 163.75507 -193.996564)
		(end 164.78377 -193.996564)
		(width 0.10668)
		(layer "B.Cu")
		(net "PWRGD_CHG_CPU1_DIMM0")
	)
	(segment
		(start 163.272216 -193.807334)
		(end 163.272216 -193.93535)
		(width 0.10668)
		(layer "B.Cu")
		(net "PWRGD_CHG_CPU1_DIMM0")
	)
	(segment
		(start 163.93541 -190.821564)
		(end 163.80841 -190.694564)
		(width 0.10668)
		(layer "B.Cu")
		(net "PWRGD_CHG_CPU1_DIMM0")
	)
	(segment
		(start 163.693856 -193.93535)
		(end 163.75507 -193.996564)
		(width 0.10668)
		(layer "B.Cu")
		(net "PWRGD_CHG_CPU1_DIMM0")
	)
	(segment
		(start 163.272216 -193.93535)
		(end 163.693856 -193.93535)
		(width 0.10668)
		(layer "B.Cu")
		(net "PWRGD_CHG_CPU1_DIMM0")
	)
	(segment
		(start 162.7759 -193.311018)
		(end 163.272216 -193.807334)
		(width 0.10668)
		(layer "B.Cu")
		(net "PWRGD_CHG_CPU1_DIMM0")
	)
	(segment
		(start 162.7759 -190.730124)
		(end 162.7759 -193.311018)
		(width 0.10668)
		(layer "B.Cu")
		(net "PWRGD_CHG_CPU1_DIMM0")
	)
	(segment
		(start 412.367984 -193.935096)
		(end 411.212284 -193.935096)
		(width 0.10668)
		(layer "F.Cu")
		(net "PWRGD_CHG_CPU0_DIMM0")
	)
	(via
		(at 411.212284 -193.935096)
		(size 0.4826)
		(drill 0.254)
		(layers "F.Cu" "B.Cu")
		(net "PWRGD_CHG_CPU0_DIMM0")
	)
	(via
		(at 410.667454 -191.07531)
		(size 0.6604)
		(drill 0.3302)
		(layers "F.Cu" "B.Cu")
		(net "PWRGD_CHG_CPU0_DIMM0")
	)
	(segment
		(start 411.791404 -191.20231)
		(end 411.664404 -191.07531)
		(width 0.10668)
		(layer "B.Cu")
		(net "PWRGD_CHG_CPU0_DIMM0")
	)
	(segment
		(start 410.538676 -191.204088)
		(end 410.538676 -193.261488)
		(width 0.10668)
		(layer "B.Cu")
		(net "PWRGD_CHG_CPU0_DIMM0")
	)
	(segment
		(start 411.664404 -191.07531)
		(end 410.667454 -191.07531)
		(width 0.10668)
		(layer "B.Cu")
		(net "PWRGD_CHG_CPU0_DIMM0")
	)
	(segment
		(start 411.633924 -193.935096)
		(end 411.695138 -193.99631)
		(width 0.10668)
		(layer "B.Cu")
		(net "PWRGD_CHG_CPU0_DIMM0")
	)
	(segment
		(start 410.667454 -191.07531)
		(end 410.538676 -191.204088)
		(width 0.10668)
		(layer "B.Cu")
		(net "PWRGD_CHG_CPU0_DIMM0")
	)
	(segment
		(start 411.212284 -193.935096)
		(end 411.633924 -193.935096)
		(width 0.10668)
		(layer "B.Cu")
		(net "PWRGD_CHG_CPU0_DIMM0")
	)
	(segment
		(start 410.538676 -193.261488)
		(end 411.212284 -193.935096)
		(width 0.10668)
		(layer "B.Cu")
		(net "PWRGD_CHG_CPU0_DIMM0")
	)
	(segment
		(start 411.695138 -193.99631)
		(end 412.723584 -193.99631)
		(width 0.10668)
		(layer "B.Cu")
		(net "PWRGD_CHG_CPU0_DIMM0")
	)
	(segment
		(start 196.86905 -91.96705)
		(end 195.834 -90.932)
		(width 0.10668)
		(layer "F.Cu")
		(net "PWRGD_CHGL_CPU1")
	)
	(segment
		(start 158.529782 -94.857824)
		(end 159.097472 -95.425514)
		(width 0.10668)
		(layer "F.Cu")
		(net "PWRGD_CHGL_CPU1")
	)
	(segment
		(start 158.738062 -109.335062)
		(end 158.738062 -113.676684)
		(width 0.10668)
		(layer "F.Cu")
		(net "PWRGD_CHGL_CPU1")
	)
	(segment
		(start 158.529782 -88.01608)
		(end 158.529782 -94.857824)
		(width 0.10668)
		(layer "F.Cu")
		(net "PWRGD_CHGL_CPU1")
	)
	(segment
		(start 174.373286 -172.06976)
		(end 174.907956 -172.60443)
		(width 0.10668)
		(layer "F.Cu")
		(net "PWRGD_CHGL_CPU1")
	)
	(segment
		(start 158.741872 -100.465128)
		(end 157.734 -101.473)
		(width 0.10668)
		(layer "F.Cu")
		(net "PWRGD_CHGL_CPU1")
	)
	(segment
		(start 196.86905 -92.456)
		(end 196.86905 -91.96705)
		(width 0.10668)
		(layer "F.Cu")
		(net "PWRGD_CHGL_CPU1")
	)
	(segment
		(start 162.037522 -118.369842)
		(end 161.622486 -118.784878)
		(width 0.10668)
		(layer "F.Cu")
		(net "PWRGD_CHGL_CPU1")
	)
	(segment
		(start 157.734 -101.473)
		(end 157.734 -108.331)
		(width 0.10668)
		(layer "F.Cu")
		(net "PWRGD_CHGL_CPU1")
	)
	(segment
		(start 158.741872 -98.890074)
		(end 158.741872 -100.465128)
		(width 0.10668)
		(layer "F.Cu")
		(net "PWRGD_CHGL_CPU1")
	)
	(segment
		(start 190.979806 -90.932)
		(end 190.344806 -91.567)
		(width 0.10668)
		(layer "F.Cu")
		(net "PWRGD_CHGL_CPU1")
	)
	(segment
		(start 159.097472 -95.425514)
		(end 159.097472 -98.534474)
		(width 0.10668)
		(layer "F.Cu")
		(net "PWRGD_CHGL_CPU1")
	)
	(segment
		(start 170.380914 -178.892708)
		(end 170.380914 -185.58764)
		(width 0.10668)
		(layer "F.Cu")
		(net "PWRGD_CHGL_CPU1")
	)
	(segment
		(start 157.734 -108.331)
		(end 158.738062 -109.335062)
		(width 0.10668)
		(layer "F.Cu")
		(net "PWRGD_CHGL_CPU1")
	)
	(segment
		(start 158.738062 -113.676684)
		(end 162.037522 -116.976144)
		(width 0.10668)
		(layer "F.Cu")
		(net "PWRGD_CHGL_CPU1")
	)
	(segment
		(start 162.037522 -116.976144)
		(end 162.037522 -118.369842)
		(width 0.10668)
		(layer "F.Cu")
		(net "PWRGD_CHGL_CPU1")
	)
	(segment
		(start 195.834 -90.932)
		(end 190.979806 -90.932)
		(width 0.10668)
		(layer "F.Cu")
		(net "PWRGD_CHGL_CPU1")
	)
	(segment
		(start 161.622486 -118.784878)
		(end 161.622486 -126.380494)
		(width 0.10668)
		(layer "F.Cu")
		(net "PWRGD_CHGL_CPU1")
	)
	(segment
		(start 174.907956 -174.365666)
		(end 170.380914 -178.892708)
		(width 0.10668)
		(layer "F.Cu")
		(net "PWRGD_CHGL_CPU1")
	)
	(segment
		(start 190.344806 -91.567)
		(end 190.344806 -91.647264)
		(width 0.10668)
		(layer "F.Cu")
		(net "PWRGD_CHGL_CPU1")
	)
	(segment
		(start 174.907956 -172.60443)
		(end 174.907956 -174.365666)
		(width 0.10668)
		(layer "F.Cu")
		(net "PWRGD_CHGL_CPU1")
	)
	(segment
		(start 197.84695 -92.456)
		(end 196.86905 -92.456)
		(width 0.10668)
		(layer "F.Cu")
		(net "PWRGD_CHGL_CPU1")
	)
	(segment
		(start 159.097472 -98.534474)
		(end 158.741872 -98.890074)
		(width 0.10668)
		(layer "F.Cu")
		(net "PWRGD_CHGL_CPU1")
	)
	(segment
		(start 170.380914 -185.58764)
		(end 171.014898 -186.221624)
		(width 0.10668)
		(layer "F.Cu")
		(net "PWRGD_CHGL_CPU1")
	)
	(segment
		(start 161.622486 -126.380494)
		(end 161.520124 -126.482856)
		(width 0.10668)
		(layer "F.Cu")
		(net "PWRGD_CHGL_CPU1")
	)
	(via
		(at 161.520124 -126.482856)
		(size 0.508)
		(drill 0.254)
		(layers "F.Cu" "B.Cu")
		(net "PWRGD_CHGL_CPU1")
	)
	(via
		(at 190.839598 -87.337646)
		(size 0.508)
		(drill 0.254)
		(layers "F.Cu" "B.Cu")
		(net "PWRGD_CHGL_CPU1")
	)
	(via
		(at 174.373286 -172.06976)
		(size 0.508)
		(drill 0.254)
		(layers "F.Cu" "B.Cu")
		(net "PWRGD_CHGL_CPU1")
	)
	(via
		(at 190.344806 -91.647264)
		(size 0.508)
		(drill 0.254)
		(layers "F.Cu" "B.Cu")
		(net "PWRGD_CHGL_CPU1")
	)
	(via
		(at 181.844442 -190.782448)
		(size 0.6604)
		(drill 0.3302)
		(layers "F.Cu" "B.Cu")
		(net "PWRGD_CHGL_CPU1")
	)
	(via
		(at 158.529782 -88.01608)
		(size 0.508)
		(drill 0.254)
		(layers "F.Cu" "B.Cu")
		(net "PWRGD_CHGL_CPU1")
	)
	(via
		(at 171.014898 -186.221624)
		(size 0.508)
		(drill 0.254)
		(layers "F.Cu" "B.Cu")
		(net "PWRGD_CHGL_CPU1")
	)
	(segment
		(start 181.22646 -190.948564)
		(end 179.72151 -190.948564)
		(width 0.10668)
		(layer "B.Cu")
		(net "PWRGD_CHGL_CPU1")
	)
	(segment
		(start 166.11346 -190.039244)
		(end 167.191436 -190.039244)
		(width 0.10668)
		(layer "B.Cu")
		(net "PWRGD_CHGL_CPU1")
	)
	(segment
		(start 187.21451 -190.948564)
		(end 187.21451 -190.597282)
		(width 0.10668)
		(layer "B.Cu")
		(net "PWRGD_CHGL_CPU1")
	)
	(segment
		(start 173.990508 -169.216578)
		(end 173.990508 -171.686982)
		(width 0.10668)
		(layer "B.Cu")
		(net "PWRGD_CHGL_CPU1")
	)
	(segment
		(start 179.72151 -190.420244)
		(end 179.72151 -190.948564)
		(width 0.10668)
		(layer "B.Cu")
		(net "PWRGD_CHGL_CPU1")
	)
	(segment
		(start 172.22851 -190.948564)
		(end 173.606206 -190.948564)
		(width 0.10668)
		(layer "B.Cu")
		(net "PWRGD_CHGL_CPU1")
	)
	(segment
		(start 187.798456 -190.948564)
		(end 187.21451 -190.948564)
		(width 0.10668)
		(layer "B.Cu")
		(net "PWRGD_CHGL_CPU1")
	)
	(segment
		(start 174.241206 -190.313564)
		(end 179.61483 -190.313564)
		(width 0.10668)
		(layer "B.Cu")
		(net "PWRGD_CHGL_CPU1")
	)
	(segment
		(start 173.606206 -190.948564)
		(end 174.241206 -190.313564)
		(width 0.10668)
		(layer "B.Cu")
		(net "PWRGD_CHGL_CPU1")
	)
	(segment
		(start 165.84041 -190.821564)
		(end 164.73551 -190.821564)
		(width 0.10668)
		(layer "B.Cu")
		(net "PWRGD_CHGL_CPU1")
	)
	(segment
		(start 172.22851 -190.439294)
		(end 172.22851 -190.948564)
		(width 0.10668)
		(layer "B.Cu")
		(net "PWRGD_CHGL_CPU1")
	)
	(segment
		(start 171.41825 -186.221624)
		(end 171.920408 -186.723782)
		(width 0.10668)
		(layer "B.Cu")
		(net "PWRGD_CHGL_CPU1")
	)
	(segment
		(start 165.84041 -190.312294)
		(end 166.11346 -190.039244)
		(width 0.10668)
		(layer "B.Cu")
		(net "PWRGD_CHGL_CPU1")
	)
	(segment
		(start 171.920408 -190.131192)
		(end 172.22851 -190.439294)
		(width 0.10668)
		(layer "B.Cu")
		(net "PWRGD_CHGL_CPU1")
	)
	(segment
		(start 171.014898 -186.221624)
		(end 171.41825 -186.221624)
		(width 0.10668)
		(layer "B.Cu")
		(net "PWRGD_CHGL_CPU1")
	)
	(segment
		(start 174.750476 -158.42488)
		(end 174.750476 -168.45661)
		(width 0.10668)
		(layer "B.Cu")
		(net "PWRGD_CHGL_CPU1")
	)
	(segment
		(start 191.710818 -190.351156)
		(end 201.960226 -190.351156)
		(width 0.10668)
		(layer "B.Cu")
		(net "PWRGD_CHGL_CPU1")
	)
	(segment
		(start 174.750476 -168.45661)
		(end 173.990508 -169.216578)
		(width 0.10668)
		(layer "B.Cu")
		(net "PWRGD_CHGL_CPU1")
	)
	(segment
		(start 179.61483 -190.313564)
		(end 179.72151 -190.420244)
		(width 0.10668)
		(layer "B.Cu")
		(net "PWRGD_CHGL_CPU1")
	)
	(segment
		(start 191.24041 -190.821564)
		(end 187.925456 -190.821564)
		(width 0.10668)
		(layer "B.Cu")
		(net "PWRGD_CHGL_CPU1")
	)
	(segment
		(start 181.844442 -190.782448)
		(end 181.392576 -190.782448)
		(width 0.10668)
		(layer "B.Cu")
		(net "PWRGD_CHGL_CPU1")
	)
	(segment
		(start 201.960226 -190.351156)
		(end 202.55738 -190.94831)
		(width 0.10668)
		(layer "B.Cu")
		(net "PWRGD_CHGL_CPU1")
	)
	(segment
		(start 187.21451 -190.597282)
		(end 187.10783 -190.490602)
		(width 0.10668)
		(layer "B.Cu")
		(net "PWRGD_CHGL_CPU1")
	)
	(segment
		(start 182.136288 -190.490602)
		(end 181.844442 -190.782448)
		(width 0.10668)
		(layer "B.Cu")
		(net "PWRGD_CHGL_CPU1")
	)
	(segment
		(start 170.688508 -186.548014)
		(end 171.014898 -186.221624)
		(width 0.10668)
		(layer "B.Cu")
		(net "PWRGD_CHGL_CPU1")
	)
	(segment
		(start 187.925456 -190.821564)
		(end 187.798456 -190.948564)
		(width 0.10668)
		(layer "B.Cu")
		(net "PWRGD_CHGL_CPU1")
	)
	(segment
		(start 167.191436 -190.039244)
		(end 170.682666 -186.548014)
		(width 0.10668)
		(layer "B.Cu")
		(net "PWRGD_CHGL_CPU1")
	)
	(segment
		(start 171.920408 -186.723782)
		(end 171.920408 -190.131192)
		(width 0.10668)
		(layer "B.Cu")
		(net "PWRGD_CHGL_CPU1")
	)
	(segment
		(start 165.84041 -190.821564)
		(end 165.84041 -190.312294)
		(width 0.10668)
		(layer "B.Cu")
		(net "PWRGD_CHGL_CPU1")
	)
	(segment
		(start 170.281854 -139.420854)
		(end 170.281854 -153.956258)
		(width 0.10668)
		(layer "B.Cu")
		(net "PWRGD_CHGL_CPU1")
	)
	(segment
		(start 170.682666 -186.548014)
		(end 170.688508 -186.548014)
		(width 0.10668)
		(layer "B.Cu")
		(net "PWRGD_CHGL_CPU1")
	)
	(segment
		(start 181.392576 -190.782448)
		(end 181.22646 -190.948564)
		(width 0.10668)
		(layer "B.Cu")
		(net "PWRGD_CHGL_CPU1")
	)
	(segment
		(start 163.123372 -132.262372)
		(end 170.281854 -139.420854)
		(width 0.10668)
		(layer "B.Cu")
		(net "PWRGD_CHGL_CPU1")
	)
	(segment
		(start 191.24041 -190.821564)
		(end 191.710818 -190.351156)
		(width 0.10668)
		(layer "B.Cu")
		(net "PWRGD_CHGL_CPU1")
	)
	(segment
		(start 173.990508 -171.686982)
		(end 174.373286 -172.06976)
		(width 0.10668)
		(layer "B.Cu")
		(net "PWRGD_CHGL_CPU1")
	)
	(segment
		(start 170.281854 -153.956258)
		(end 174.750476 -158.42488)
		(width 0.10668)
		(layer "B.Cu")
		(net "PWRGD_CHGL_CPU1")
	)
	(segment
		(start 161.520124 -126.482856)
		(end 161.520124 -128.459484)
		(width 0.10668)
		(layer "B.Cu")
		(net "PWRGD_CHGL_CPU1")
	)
	(segment
		(start 163.123372 -130.062732)
		(end 163.123372 -132.262372)
		(width 0.10668)
		(layer "B.Cu")
		(net "PWRGD_CHGL_CPU1")
	)
	(segment
		(start 161.520124 -128.459484)
		(end 163.123372 -130.062732)
		(width 0.10668)
		(layer "B.Cu")
		(net "PWRGD_CHGL_CPU1")
	)
	(segment
		(start 187.10783 -190.490602)
		(end 182.136288 -190.490602)
		(width 0.10668)
		(layer "B.Cu")
		(net "PWRGD_CHGL_CPU1")
	)
	(segment
		(start 181.47919 -86.067646)
		(end 182.195724 -86.78418)
		(width 0.11684)
		(layer "In2.Cu")
		(net "PWRGD_CHGL_CPU1")
	)
	(segment
		(start 166.253668 -86.067646)
		(end 181.47919 -86.067646)
		(width 0.11684)
		(layer "In2.Cu")
		(net "PWRGD_CHGL_CPU1")
	)
	(segment
		(start 190.514732 -86.78418)
		(end 190.839598 -87.109046)
		(width 0.11684)
		(layer "In2.Cu")
		(net "PWRGD_CHGL_CPU1")
	)
	(segment
		(start 158.529782 -88.01608)
		(end 164.305234 -88.01608)
		(width 0.11684)
		(layer "In2.Cu")
		(net "PWRGD_CHGL_CPU1")
	)
	(segment
		(start 164.305234 -88.01608)
		(end 166.253668 -86.067646)
		(width 0.11684)
		(layer "In2.Cu")
		(net "PWRGD_CHGL_CPU1")
	)
	(segment
		(start 190.839598 -87.109046)
		(end 190.839598 -87.337646)
		(width 0.11684)
		(layer "In2.Cu")
		(net "PWRGD_CHGL_CPU1")
	)
	(segment
		(start 182.195724 -86.78418)
		(end 190.514732 -86.78418)
		(width 0.11684)
		(layer "In2.Cu")
		(net "PWRGD_CHGL_CPU1")
	)
	(segment
		(start 190.839598 -87.337646)
		(end 190.839598 -91.152472)
		(width 0.11684)
		(layer "In4.Cu")
		(net "PWRGD_CHGL_CPU1")
	)
	(segment
		(start 190.839598 -91.152472)
		(end 190.344806 -91.647264)
		(width 0.11684)
		(layer "In4.Cu")
		(net "PWRGD_CHGL_CPU1")
	)
	(segment
		(start 213.819486 -101.805486)
		(end 213.106 -101.092)
		(width 0.10668)
		(layer "F.Cu")
		(net "PWRGD_CHGL_CPU0")
	)
	(segment
		(start 205.37805 -99.695)
		(end 206.35595 -99.695)
		(width 0.10668)
		(layer "F.Cu")
		(net "PWRGD_CHGL_CPU0")
	)
	(segment
		(start 213.819486 -107.497626)
		(end 213.819486 -101.805486)
		(width 0.10668)
		(layer "F.Cu")
		(net "PWRGD_CHGL_CPU0")
	)
	(segment
		(start 206.35595 -100.056696)
		(end 206.35595 -99.695)
		(width 0.10668)
		(layer "F.Cu")
		(net "PWRGD_CHGL_CPU0")
	)
	(segment
		(start 207.391254 -101.092)
		(end 206.35595 -100.056696)
		(width 0.10668)
		(layer "F.Cu")
		(net "PWRGD_CHGL_CPU0")
	)
	(segment
		(start 213.106 -101.092)
		(end 207.391254 -101.092)
		(width 0.10668)
		(layer "F.Cu")
		(net "PWRGD_CHGL_CPU0")
	)
	(via
		(at 429.232568 -190.925196)
		(size 0.6604)
		(drill 0.3302)
		(layers "F.Cu" "B.Cu")
		(net "PWRGD_CHGL_CPU0")
	)
	(via
		(at 274.75942 -129.329688)
		(size 0.508)
		(drill 0.254)
		(layers "F.Cu" "B.Cu")
		(net "PWRGD_CHGL_CPU0")
	)
	(via
		(at 213.819486 -107.497626)
		(size 0.508)
		(drill 0.254)
		(layers "F.Cu" "B.Cu")
		(net "PWRGD_CHGL_CPU0")
	)
	(via
		(at 451.354444 -190.251842)
		(size 0.508)
		(drill 0.254)
		(layers "F.Cu" "B.Cu")
		(net "PWRGD_CHGL_CPU0")
	)
	(via
		(at 268.5923 -129.347468)
		(size 0.508)
		(drill 0.254)
		(layers "F.Cu" "B.Cu")
		(net "PWRGD_CHGL_CPU0")
	)
	(segment
		(start 450.310504 -191.32931)
		(end 450.56806 -191.32931)
		(width 0.10668)
		(layer "B.Cu")
		(net "PWRGD_CHGL_CPU0")
	)
	(segment
		(start 444.957454 -191.20231)
		(end 445.705738 -190.454026)
		(width 0.10668)
		(layer "B.Cu")
		(net "PWRGD_CHGL_CPU0")
	)
	(segment
		(start 448.916298 -190.766954)
		(end 449.769992 -190.766954)
		(width 0.10668)
		(layer "B.Cu")
		(net "PWRGD_CHGL_CPU0")
	)
	(segment
		(start 420.084504 -190.82004)
		(end 420.084504 -191.32931)
		(width 0.10668)
		(layer "B.Cu")
		(net "PWRGD_CHGL_CPU0")
	)
	(segment
		(start 420.084504 -191.32931)
		(end 421.716454 -191.32931)
		(width 0.10668)
		(layer "B.Cu")
		(net "PWRGD_CHGL_CPU0")
	)
	(segment
		(start 450.310504 -191.058292)
		(end 450.310504 -191.32931)
		(width 0.10668)
		(layer "B.Cu")
		(net "PWRGD_CHGL_CPU0")
	)
	(segment
		(start 427.597824 -190.44031)
		(end 427.958504 -190.80099)
		(width 0.10668)
		(layer "B.Cu")
		(net "PWRGD_CHGL_CPU0")
	)
	(segment
		(start 434.772054 -190.49111)
		(end 435.197504 -190.91656)
		(width 0.10668)
		(layer "B.Cu")
		(net "PWRGD_CHGL_CPU0")
	)
	(segment
		(start 419.761924 -190.49746)
		(end 420.084504 -190.82004)
		(width 0.10668)
		(layer "B.Cu")
		(net "PWRGD_CHGL_CPU0")
	)
	(segment
		(start 413.696404 -190.69304)
		(end 413.891984 -190.49746)
		(width 0.10668)
		(layer "B.Cu")
		(net "PWRGD_CHGL_CPU0")
	)
	(segment
		(start 449.769992 -190.766954)
		(end 450.119242 -190.86703)
		(width 0.10668)
		(layer "B.Cu")
		(net "PWRGD_CHGL_CPU0")
	)
	(segment
		(start 440.766454 -190.44031)
		(end 441.020454 -190.69431)
		(width 0.10668)
		(layer "B.Cu")
		(net "PWRGD_CHGL_CPU0")
	)
	(segment
		(start 413.891984 -190.49746)
		(end 419.761924 -190.49746)
		(width 0.10668)
		(layer "B.Cu")
		(net "PWRGD_CHGL_CPU0")
	)
	(segment
		(start 421.716454 -191.32931)
		(end 422.605454 -190.44031)
		(width 0.10668)
		(layer "B.Cu")
		(net "PWRGD_CHGL_CPU0")
	)
	(segment
		(start 427.958504 -191.32931)
		(end 428.828454 -191.32931)
		(width 0.10668)
		(layer "B.Cu")
		(net "PWRGD_CHGL_CPU0")
	)
	(segment
		(start 429.666654 -190.49111)
		(end 434.772054 -190.49111)
		(width 0.10668)
		(layer "B.Cu")
		(net "PWRGD_CHGL_CPU0")
	)
	(segment
		(start 451.354444 -190.542926)
		(end 451.354444 -190.251842)
		(width 0.10668)
		(layer "B.Cu")
		(net "PWRGD_CHGL_CPU0")
	)
	(segment
		(start 445.705738 -190.454026)
		(end 448.60337 -190.454026)
		(width 0.10668)
		(layer "B.Cu")
		(net "PWRGD_CHGL_CPU0")
	)
	(segment
		(start 413.696404 -191.20231)
		(end 413.696404 -190.69304)
		(width 0.10668)
		(layer "B.Cu")
		(net "PWRGD_CHGL_CPU0")
	)
	(segment
		(start 428.828454 -191.32931)
		(end 429.232568 -190.925196)
		(width 0.10668)
		(layer "B.Cu")
		(net "PWRGD_CHGL_CPU0")
	)
	(segment
		(start 438.836054 -191.20231)
		(end 439.598054 -190.44031)
		(width 0.10668)
		(layer "B.Cu")
		(net "PWRGD_CHGL_CPU0")
	)
	(segment
		(start 450.56806 -191.32931)
		(end 451.354444 -190.542926)
		(width 0.10668)
		(layer "B.Cu")
		(net "PWRGD_CHGL_CPU0")
	)
	(segment
		(start 429.232568 -190.925196)
		(end 429.666654 -190.49111)
		(width 0.10668)
		(layer "B.Cu")
		(net "PWRGD_CHGL_CPU0")
	)
	(segment
		(start 435.197504 -190.91656)
		(end 435.197504 -191.20231)
		(width 0.10668)
		(layer "B.Cu")
		(net "PWRGD_CHGL_CPU0")
	)
	(segment
		(start 427.958504 -190.80099)
		(end 427.958504 -191.32931)
		(width 0.10668)
		(layer "B.Cu")
		(net "PWRGD_CHGL_CPU0")
	)
	(segment
		(start 448.60337 -190.454026)
		(end 448.916298 -190.766954)
		(width 0.10668)
		(layer "B.Cu")
		(net "PWRGD_CHGL_CPU0")
	)
	(segment
		(start 422.605454 -190.44031)
		(end 427.597824 -190.44031)
		(width 0.10668)
		(layer "B.Cu")
		(net "PWRGD_CHGL_CPU0")
	)
	(segment
		(start 450.119242 -190.86703)
		(end 450.310504 -191.058292)
		(width 0.10668)
		(layer "B.Cu")
		(net "PWRGD_CHGL_CPU0")
	)
	(segment
		(start 442.583824 -190.69431)
		(end 442.690504 -190.80099)
		(width 0.10668)
		(layer "B.Cu")
		(net "PWRGD_CHGL_CPU0")
	)
	(segment
		(start 442.690504 -191.20231)
		(end 444.957454 -191.20231)
		(width 0.10668)
		(layer "B.Cu")
		(net "PWRGD_CHGL_CPU0")
	)
	(segment
		(start 412.591504 -191.20231)
		(end 413.696404 -191.20231)
		(width 0.10668)
		(layer "B.Cu")
		(net "PWRGD_CHGL_CPU0")
	)
	(segment
		(start 435.197504 -191.20231)
		(end 438.836054 -191.20231)
		(width 0.10668)
		(layer "B.Cu")
		(net "PWRGD_CHGL_CPU0")
	)
	(segment
		(start 439.598054 -190.44031)
		(end 440.766454 -190.44031)
		(width 0.10668)
		(layer "B.Cu")
		(net "PWRGD_CHGL_CPU0")
	)
	(segment
		(start 441.020454 -190.69431)
		(end 442.583824 -190.69431)
		(width 0.10668)
		(layer "B.Cu")
		(net "PWRGD_CHGL_CPU0")
	)
	(segment
		(start 442.690504 -190.80099)
		(end 442.690504 -191.20231)
		(width 0.10668)
		(layer "B.Cu")
		(net "PWRGD_CHGL_CPU0")
	)
	(segment
		(start 440.3979 -165.11016)
		(end 430.423574 -155.135834)
		(width 0.11684)
		(layer "In2.Cu")
		(net "PWRGD_CHGL_CPU0")
	)
	(segment
		(start 436.938928 -173.612556)
		(end 435.76748 -172.441108)
		(width 0.11684)
		(layer "In2.Cu")
		(net "PWRGD_CHGL_CPU0")
	)
	(segment
		(start 268.5923 -129.347468)
		(end 263.742424 -124.497592)
		(width 0.11684)
		(layer "In2.Cu")
		(net "PWRGD_CHGL_CPU0")
	)
	(segment
		(start 430.423574 -155.135834)
		(end 430.423574 -144.21358)
		(width 0.11684)
		(layer "In2.Cu")
		(net "PWRGD_CHGL_CPU0")
	)
	(segment
		(start 448.26174 -180.608224)
		(end 441.266072 -173.612556)
		(width 0.11684)
		(layer "In2.Cu")
		(net "PWRGD_CHGL_CPU0")
	)
	(segment
		(start 439.95594 -170.934888)
		(end 439.95594 -168.979088)
		(width 0.11684)
		(layer "In2.Cu")
		(net "PWRGD_CHGL_CPU0")
	)
	(segment
		(start 342.452452 -129.314448)
		(end 315.858144 -129.314448)
		(width 0.11684)
		(layer "In2.Cu")
		(net "PWRGD_CHGL_CPU0")
	)
	(segment
		(start 440.94146 -166.060628)
		(end 440.3979 -165.517068)
		(width 0.11684)
		(layer "In2.Cu")
		(net "PWRGD_CHGL_CPU0")
	)
	(segment
		(start 281.756104 -127.503428)
		(end 276.58568 -127.503428)
		(width 0.11684)
		(layer "In2.Cu")
		(net "PWRGD_CHGL_CPU0")
	)
	(segment
		(start 213.819486 -108.87837)
		(end 213.819486 -107.497626)
		(width 0.11684)
		(layer "In2.Cu")
		(net "PWRGD_CHGL_CPU0")
	)
	(segment
		(start 437.050688 -171.003468)
		(end 437.490108 -171.442888)
		(width 0.11684)
		(layer "In2.Cu")
		(net "PWRGD_CHGL_CPU0")
	)
	(segment
		(start 448.26174 -187.159138)
		(end 448.26174 -180.608224)
		(width 0.11684)
		(layer "In2.Cu")
		(net "PWRGD_CHGL_CPU0")
	)
	(segment
		(start 289.927284 -119.332248)
		(end 281.756104 -127.503428)
		(width 0.11684)
		(layer "In2.Cu")
		(net "PWRGD_CHGL_CPU0")
	)
	(segment
		(start 437.490108 -171.442888)
		(end 439.44794 -171.442888)
		(width 0.11684)
		(layer "In2.Cu")
		(net "PWRGD_CHGL_CPU0")
	)
	(segment
		(start 311.293764 -124.750068)
		(end 299.421296 -124.750068)
		(width 0.11684)
		(layer "In2.Cu")
		(net "PWRGD_CHGL_CPU0")
	)
	(segment
		(start 263.742424 -124.497592)
		(end 263.742424 -116.390674)
		(width 0.11684)
		(layer "In2.Cu")
		(net "PWRGD_CHGL_CPU0")
	)
	(segment
		(start 276.58568 -127.503428)
		(end 274.75942 -129.329688)
		(width 0.11684)
		(layer "In2.Cu")
		(net "PWRGD_CHGL_CPU0")
	)
	(segment
		(start 416.355276 -130.145282)
		(end 405.724106 -130.145282)
		(width 0.11684)
		(layer "In2.Cu")
		(net "PWRGD_CHGL_CPU0")
	)
	(segment
		(start 440.94146 -167.993568)
		(end 440.94146 -166.060628)
		(width 0.11684)
		(layer "In2.Cu")
		(net "PWRGD_CHGL_CPU0")
	)
	(segment
		(start 439.44794 -171.442888)
		(end 439.95594 -170.934888)
		(width 0.11684)
		(layer "In2.Cu")
		(net "PWRGD_CHGL_CPU0")
	)
	(segment
		(start 297.9293 -123.258072)
		(end 297.9293 -121.289572)
		(width 0.11684)
		(layer "In2.Cu")
		(net "PWRGD_CHGL_CPU0")
	)
	(segment
		(start 435.76748 -171.293028)
		(end 436.05704 -171.003468)
		(width 0.11684)
		(layer "In2.Cu")
		(net "PWRGD_CHGL_CPU0")
	)
	(segment
		(start 403.440646 -132.428742)
		(end 354.776278 -132.428742)
		(width 0.11684)
		(layer "In2.Cu")
		(net "PWRGD_CHGL_CPU0")
	)
	(segment
		(start 440.3979 -165.517068)
		(end 440.3979 -165.11016)
		(width 0.11684)
		(layer "In2.Cu")
		(net "PWRGD_CHGL_CPU0")
	)
	(segment
		(start 295.971976 -119.332248)
		(end 289.927284 -119.332248)
		(width 0.11684)
		(layer "In2.Cu")
		(net "PWRGD_CHGL_CPU0")
	)
	(segment
		(start 353.276408 -133.928612)
		(end 347.066616 -133.928612)
		(width 0.11684)
		(layer "In2.Cu")
		(net "PWRGD_CHGL_CPU0")
	)
	(segment
		(start 254.51943 -113.281714)
		(end 252.669548 -111.431832)
		(width 0.11684)
		(layer "In2.Cu")
		(net "PWRGD_CHGL_CPU0")
	)
	(segment
		(start 430.423574 -144.21358)
		(end 416.355276 -130.145282)
		(width 0.11684)
		(layer "In2.Cu")
		(net "PWRGD_CHGL_CPU0")
	)
	(segment
		(start 347.066616 -133.928612)
		(end 342.452452 -129.314448)
		(width 0.11684)
		(layer "In2.Cu")
		(net "PWRGD_CHGL_CPU0")
	)
	(segment
		(start 252.669548 -111.431832)
		(end 216.372948 -111.431832)
		(width 0.11684)
		(layer "In2.Cu")
		(net "PWRGD_CHGL_CPU0")
	)
	(segment
		(start 435.76748 -172.441108)
		(end 435.76748 -171.293028)
		(width 0.11684)
		(layer "In2.Cu")
		(net "PWRGD_CHGL_CPU0")
	)
	(segment
		(start 436.05704 -171.003468)
		(end 437.050688 -171.003468)
		(width 0.11684)
		(layer "In2.Cu")
		(net "PWRGD_CHGL_CPU0")
	)
	(segment
		(start 263.742424 -116.390674)
		(end 260.633464 -113.281714)
		(width 0.11684)
		(layer "In2.Cu")
		(net "PWRGD_CHGL_CPU0")
	)
	(segment
		(start 451.354444 -190.251842)
		(end 448.26174 -187.159138)
		(width 0.11684)
		(layer "In2.Cu")
		(net "PWRGD_CHGL_CPU0")
	)
	(segment
		(start 216.372948 -111.431832)
		(end 213.819486 -108.87837)
		(width 0.11684)
		(layer "In2.Cu")
		(net "PWRGD_CHGL_CPU0")
	)
	(segment
		(start 405.724106 -130.145282)
		(end 403.440646 -132.428742)
		(width 0.11684)
		(layer "In2.Cu")
		(net "PWRGD_CHGL_CPU0")
	)
	(segment
		(start 441.266072 -173.612556)
		(end 436.938928 -173.612556)
		(width 0.11684)
		(layer "In2.Cu")
		(net "PWRGD_CHGL_CPU0")
	)
	(segment
		(start 354.776278 -132.428742)
		(end 353.276408 -133.928612)
		(width 0.11684)
		(layer "In2.Cu")
		(net "PWRGD_CHGL_CPU0")
	)
	(segment
		(start 260.633464 -113.281714)
		(end 254.51943 -113.281714)
		(width 0.11684)
		(layer "In2.Cu")
		(net "PWRGD_CHGL_CPU0")
	)
	(segment
		(start 299.421296 -124.750068)
		(end 297.9293 -123.258072)
		(width 0.11684)
		(layer "In2.Cu")
		(net "PWRGD_CHGL_CPU0")
	)
	(segment
		(start 315.858144 -129.314448)
		(end 311.293764 -124.750068)
		(width 0.11684)
		(layer "In2.Cu")
		(net "PWRGD_CHGL_CPU0")
	)
	(segment
		(start 297.9293 -121.289572)
		(end 295.971976 -119.332248)
		(width 0.11684)
		(layer "In2.Cu")
		(net "PWRGD_CHGL_CPU0")
	)
	(segment
		(start 439.95594 -168.979088)
		(end 440.94146 -167.993568)
		(width 0.11684)
		(layer "In2.Cu")
		(net "PWRGD_CHGL_CPU0")
	)
	(segment
		(start 268.5923 -129.347468)
		(end 274.74164 -129.347468)
		(width 0.11684)
		(layer "In6.Cu")
		(net "PWRGD_CHGL_CPU0")
	)
	(segment
		(start 274.74164 -129.347468)
		(end 274.75942 -129.329688)
		(width 0.11684)
		(layer "In6.Cu")
		(net "PWRGD_CHGL_CPU0")
	)
	(segment
		(start 15.250668 -194.60972)
		(end 14.33576 -194.60972)
		(width 0.10668)
		(layer "F.Cu")
		(net "PWRGD_CHF_CPU1_DIMM")
	)
	(segment
		(start 17.608042 -193.93535)
		(end 15.925038 -193.93535)
		(width 0.10668)
		(layer "F.Cu")
		(net "PWRGD_CHF_CPU1_DIMM")
	)
	(segment
		(start 15.925038 -193.93535)
		(end 15.250668 -194.60972)
		(width 0.10668)
		(layer "F.Cu")
		(net "PWRGD_CHF_CPU1_DIMM")
	)
	(via
		(at 14.33576 -194.60972)
		(size 0.508)
		(drill 0.254)
		(layers "F.Cu" "B.Cu")
		(net "PWRGD_CHF_CPU1_DIMM")
	)
	(segment
		(start 15.113762 -193.212466)
		(end 14.33576 -193.990468)
		(width 0.10668)
		(layer "B.Cu")
		(net "PWRGD_CHF_CPU1_DIMM")
	)
	(segment
		(start 14.33576 -193.990468)
		(end 14.33576 -194.60972)
		(width 0.10668)
		(layer "B.Cu")
		(net "PWRGD_CHF_CPU1_DIMM")
	)
	(segment
		(start 15.113762 -192.762378)
		(end 15.113762 -193.212466)
		(width 0.10668)
		(layer "B.Cu")
		(net "PWRGD_CHF_CPU1_DIMM")
	)
	(segment
		(start 14.097762 -192.762378)
		(end 15.113762 -192.762378)
		(width 0.10668)
		(layer "B.Cu")
		(net "PWRGD_CHF_CPU1_DIMM")
	)
	(segment
		(start 265.54811 -193.935096)
		(end 264.39241 -193.935096)
		(width 0.10668)
		(layer "F.Cu")
		(net "PWRGD_CHF_CPU0_DIMM")
	)
	(via
		(at 263.855454 -190.94831)
		(size 0.6604)
		(drill 0.3302)
		(layers "F.Cu" "B.Cu")
		(net "PWRGD_CHF_CPU0_DIMM")
	)
	(via
		(at 264.39241 -193.935096)
		(size 0.4826)
		(drill 0.254)
		(layers "F.Cu" "B.Cu")
		(net "PWRGD_CHF_CPU0_DIMM")
	)
	(segment
		(start 264.875264 -193.99631)
		(end 264.81405 -193.935096)
		(width 0.10668)
		(layer "B.Cu")
		(net "PWRGD_CHF_CPU0_DIMM")
	)
	(segment
		(start 264.81405 -193.935096)
		(end 264.39241 -193.935096)
		(width 0.10668)
		(layer "B.Cu")
		(net "PWRGD_CHF_CPU0_DIMM")
	)
	(segment
		(start 263.855454 -190.94831)
		(end 263.982454 -190.82131)
		(width 0.10668)
		(layer "B.Cu")
		(net "PWRGD_CHF_CPU0_DIMM")
	)
	(segment
		(start 263.855454 -193.39814)
		(end 263.855454 -190.94831)
		(width 0.10668)
		(layer "B.Cu")
		(net "PWRGD_CHF_CPU0_DIMM")
	)
	(segment
		(start 265.90371 -193.99631)
		(end 264.875264 -193.99631)
		(width 0.10668)
		(layer "B.Cu")
		(net "PWRGD_CHF_CPU0_DIMM")
	)
	(segment
		(start 264.39241 -193.935096)
		(end 263.855454 -193.39814)
		(width 0.10668)
		(layer "B.Cu")
		(net "PWRGD_CHF_CPU0_DIMM")
	)
	(segment
		(start 263.982454 -190.82131)
		(end 265.106404 -190.82131)
		(width 0.10668)
		(layer "B.Cu")
		(net "PWRGD_CHF_CPU0_DIMM")
	)
	(segment
		(start 25.152096 -193.93535)
		(end 23.996396 -193.93535)
		(width 0.10668)
		(layer "F.Cu")
		(net "PWRGD_CHE_CPU1_DIMM")
	)
	(via
		(at 23.996396 -193.93535)
		(size 0.4826)
		(drill 0.254)
		(layers "F.Cu" "B.Cu")
		(net "PWRGD_CHE_CPU1_DIMM")
	)
	(via
		(at 23.408386 -190.627)
		(size 0.6604)
		(drill 0.3302)
		(layers "F.Cu" "B.Cu")
		(net "PWRGD_CHE_CPU1_DIMM")
	)
	(segment
		(start 24.418036 -193.93535)
		(end 24.47925 -193.996564)
		(width 0.10668)
		(layer "B.Cu")
		(net "PWRGD_CHE_CPU1_DIMM")
	)
	(segment
		(start 23.408386 -193.34734)
		(end 23.996396 -193.93535)
		(width 0.10668)
		(layer "B.Cu")
		(net "PWRGD_CHE_CPU1_DIMM")
	)
	(segment
		(start 24.591772 -190.627)
		(end 23.408386 -190.627)
		(width 0.10668)
		(layer "B.Cu")
		(net "PWRGD_CHE_CPU1_DIMM")
	)
	(segment
		(start 24.47925 -193.996564)
		(end 25.52319 -193.996564)
		(width 0.10668)
		(layer "B.Cu")
		(net "PWRGD_CHE_CPU1_DIMM")
	)
	(segment
		(start 23.408386 -190.627)
		(end 23.408386 -193.34734)
		(width 0.10668)
		(layer "B.Cu")
		(net "PWRGD_CHE_CPU1_DIMM")
	)
	(segment
		(start 24.913336 -190.948564)
		(end 24.591772 -190.627)
		(width 0.10668)
		(layer "B.Cu")
		(net "PWRGD_CHE_CPU1_DIMM")
	)
	(segment
		(start 23.996396 -193.93535)
		(end 24.418036 -193.93535)
		(width 0.10668)
		(layer "B.Cu")
		(net "PWRGD_CHE_CPU1_DIMM")
	)
	(segment
		(start 273.092164 -193.935096)
		(end 271.936464 -193.935096)
		(width 0.10668)
		(layer "F.Cu")
		(net "PWRGD_CHE_CPU0_DIMM")
	)
	(via
		(at 271.936464 -193.935096)
		(size 0.4826)
		(drill 0.254)
		(layers "F.Cu" "B.Cu")
		(net "PWRGD_CHE_CPU0_DIMM")
	)
	(via
		(at 271.475454 -190.94831)
		(size 0.6604)
		(drill 0.3302)
		(layers "F.Cu" "B.Cu")
		(net "PWRGD_CHE_CPU0_DIMM")
	)
	(segment
		(start 272.419318 -193.99631)
		(end 273.447764 -193.99631)
		(width 0.10668)
		(layer "B.Cu")
		(net "PWRGD_CHE_CPU0_DIMM")
	)
	(segment
		(start 272.358104 -193.935096)
		(end 272.419318 -193.99631)
		(width 0.10668)
		(layer "B.Cu")
		(net "PWRGD_CHE_CPU0_DIMM")
	)
	(segment
		(start 271.475454 -190.94831)
		(end 271.348454 -191.07531)
		(width 0.10668)
		(layer "B.Cu")
		(net "PWRGD_CHE_CPU0_DIMM")
	)
	(segment
		(start 271.348454 -193.347086)
		(end 271.936464 -193.935096)
		(width 0.10668)
		(layer "B.Cu")
		(net "PWRGD_CHE_CPU0_DIMM")
	)
	(segment
		(start 271.348454 -191.07531)
		(end 271.348454 -193.347086)
		(width 0.10668)
		(layer "B.Cu")
		(net "PWRGD_CHE_CPU0_DIMM")
	)
	(segment
		(start 272.853404 -190.94831)
		(end 271.475454 -190.94831)
		(width 0.10668)
		(layer "B.Cu")
		(net "PWRGD_CHE_CPU0_DIMM")
	)
	(segment
		(start 271.936464 -193.935096)
		(end 272.358104 -193.935096)
		(width 0.10668)
		(layer "B.Cu")
		(net "PWRGD_CHE_CPU0_DIMM")
	)
	(segment
		(start 32.695896 -193.93535)
		(end 31.540196 -193.93535)
		(width 0.10668)
		(layer "F.Cu")
		(net "PWRGD_CHD_CPU1_DIMM")
	)
	(via
		(at 31.540196 -193.93535)
		(size 0.4826)
		(drill 0.254)
		(layers "F.Cu" "B.Cu")
		(net "PWRGD_CHD_CPU1_DIMM")
	)
	(via
		(at 31.028386 -190.567564)
		(size 0.6604)
		(drill 0.3302)
		(layers "F.Cu" "B.Cu")
		(net "PWRGD_CHD_CPU1_DIMM")
	)
	(segment
		(start 30.984444 -190.611506)
		(end 30.984444 -193.379598)
		(width 0.10668)
		(layer "B.Cu")
		(net "PWRGD_CHD_CPU1_DIMM")
	)
	(segment
		(start 32.152336 -190.948564)
		(end 31.771336 -190.567564)
		(width 0.10668)
		(layer "B.Cu")
		(net "PWRGD_CHD_CPU1_DIMM")
	)
	(segment
		(start 31.540196 -193.93535)
		(end 31.961836 -193.93535)
		(width 0.10668)
		(layer "B.Cu")
		(net "PWRGD_CHD_CPU1_DIMM")
	)
	(segment
		(start 31.771336 -190.567564)
		(end 31.028386 -190.567564)
		(width 0.10668)
		(layer "B.Cu")
		(net "PWRGD_CHD_CPU1_DIMM")
	)
	(segment
		(start 31.961836 -193.93535)
		(end 32.02305 -193.996564)
		(width 0.10668)
		(layer "B.Cu")
		(net "PWRGD_CHD_CPU1_DIMM")
	)
	(segment
		(start 32.02305 -193.996564)
		(end 33.067244 -193.996564)
		(width 0.10668)
		(layer "B.Cu")
		(net "PWRGD_CHD_CPU1_DIMM")
	)
	(segment
		(start 31.028386 -190.567564)
		(end 30.984444 -190.611506)
		(width 0.10668)
		(layer "B.Cu")
		(net "PWRGD_CHD_CPU1_DIMM")
	)
	(segment
		(start 30.984444 -193.379598)
		(end 31.540196 -193.93535)
		(width 0.10668)
		(layer "B.Cu")
		(net "PWRGD_CHD_CPU1_DIMM")
	)
	(segment
		(start 280.635964 -193.935096)
		(end 279.480264 -193.935096)
		(width 0.10668)
		(layer "F.Cu")
		(net "PWRGD_CHD_CPU0_DIMM")
	)
	(via
		(at 278.968454 -191.07531)
		(size 0.6604)
		(drill 0.3302)
		(layers "F.Cu" "B.Cu")
		(net "PWRGD_CHD_CPU0_DIMM")
	)
	(via
		(at 279.480264 -193.935096)
		(size 0.4826)
		(drill 0.254)
		(layers "F.Cu" "B.Cu")
		(net "PWRGD_CHD_CPU0_DIMM")
	)
	(segment
		(start 278.936958 -193.39179)
		(end 279.480264 -193.935096)
		(width 0.10668)
		(layer "B.Cu")
		(net "PWRGD_CHD_CPU0_DIMM")
	)
	(segment
		(start 280.092404 -190.94831)
		(end 279.095454 -190.94831)
		(width 0.10668)
		(layer "B.Cu")
		(net "PWRGD_CHD_CPU0_DIMM")
	)
	(segment
		(start 278.936958 -191.106806)
		(end 278.936958 -193.39179)
		(width 0.10668)
		(layer "B.Cu")
		(net "PWRGD_CHD_CPU0_DIMM")
	)
	(segment
		(start 279.963118 -193.99631)
		(end 280.991564 -193.99631)
		(width 0.10668)
		(layer "B.Cu")
		(net "PWRGD_CHD_CPU0_DIMM")
	)
	(segment
		(start 279.095454 -190.94831)
		(end 278.968454 -191.07531)
		(width 0.10668)
		(layer "B.Cu")
		(net "PWRGD_CHD_CPU0_DIMM")
	)
	(segment
		(start 279.480264 -193.935096)
		(end 279.901904 -193.935096)
		(width 0.10668)
		(layer "B.Cu")
		(net "PWRGD_CHD_CPU0_DIMM")
	)
	(segment
		(start 279.901904 -193.935096)
		(end 279.963118 -193.99631)
		(width 0.10668)
		(layer "B.Cu")
		(net "PWRGD_CHD_CPU0_DIMM")
	)
	(segment
		(start 278.968454 -191.07531)
		(end 278.936958 -191.106806)
		(width 0.10668)
		(layer "B.Cu")
		(net "PWRGD_CHD_CPU0_DIMM")
	)
	(segment
		(start 40.23995 -193.93535)
		(end 39.08425 -193.93535)
		(width 0.10668)
		(layer "F.Cu")
		(net "PWRGD_CHC_CPU1_DIMM")
	)
	(via
		(at 39.08425 -193.93535)
		(size 0.4826)
		(drill 0.254)
		(layers "F.Cu" "B.Cu")
		(net "PWRGD_CHC_CPU1_DIMM")
	)
	(via
		(at 38.521386 -190.440564)
		(size 0.6604)
		(drill 0.3302)
		(layers "F.Cu" "B.Cu")
		(net "PWRGD_CHC_CPU1_DIMM")
	)
	(segment
		(start 38.528498 -190.447676)
		(end 38.528498 -193.379598)
		(width 0.10668)
		(layer "B.Cu")
		(net "PWRGD_CHC_CPU1_DIMM")
	)
	(segment
		(start 39.50589 -193.93535)
		(end 39.567104 -193.996564)
		(width 0.10668)
		(layer "B.Cu")
		(net "PWRGD_CHC_CPU1_DIMM")
	)
	(segment
		(start 39.08425 -193.93535)
		(end 39.50589 -193.93535)
		(width 0.10668)
		(layer "B.Cu")
		(net "PWRGD_CHC_CPU1_DIMM")
	)
	(segment
		(start 39.645336 -190.948564)
		(end 39.137336 -190.440564)
		(width 0.10668)
		(layer "B.Cu")
		(net "PWRGD_CHC_CPU1_DIMM")
	)
	(segment
		(start 38.528498 -193.379598)
		(end 39.08425 -193.93535)
		(width 0.10668)
		(layer "B.Cu")
		(net "PWRGD_CHC_CPU1_DIMM")
	)
	(segment
		(start 38.521386 -190.440564)
		(end 38.528498 -190.447676)
		(width 0.10668)
		(layer "B.Cu")
		(net "PWRGD_CHC_CPU1_DIMM")
	)
	(segment
		(start 39.137336 -190.440564)
		(end 38.521386 -190.440564)
		(width 0.10668)
		(layer "B.Cu")
		(net "PWRGD_CHC_CPU1_DIMM")
	)
	(segment
		(start 39.567104 -193.996564)
		(end 40.59555 -193.996564)
		(width 0.10668)
		(layer "B.Cu")
		(net "PWRGD_CHC_CPU1_DIMM")
	)
	(segment
		(start 288.180018 -193.935096)
		(end 287.024318 -193.935096)
		(width 0.10668)
		(layer "F.Cu")
		(net "PWRGD_CHC_CPU0_DIMM")
	)
	(via
		(at 286.461454 -191.07531)
		(size 0.6604)
		(drill 0.3302)
		(layers "F.Cu" "B.Cu")
		(net "PWRGD_CHC_CPU0_DIMM")
	)
	(via
		(at 287.024318 -193.935096)
		(size 0.4826)
		(drill 0.254)
		(layers "F.Cu" "B.Cu")
		(net "PWRGD_CHC_CPU0_DIMM")
	)
	(segment
		(start 286.461454 -191.07531)
		(end 286.588454 -190.94831)
		(width 0.10668)
		(layer "B.Cu")
		(net "PWRGD_CHC_CPU0_DIMM")
	)
	(segment
		(start 287.445958 -193.935096)
		(end 287.024318 -193.935096)
		(width 0.10668)
		(layer "B.Cu")
		(net "PWRGD_CHC_CPU0_DIMM")
	)
	(segment
		(start 286.588454 -190.94831)
		(end 287.585404 -190.94831)
		(width 0.10668)
		(layer "B.Cu")
		(net "PWRGD_CHC_CPU0_DIMM")
	)
	(segment
		(start 287.507172 -193.99631)
		(end 287.445958 -193.935096)
		(width 0.10668)
		(layer "B.Cu")
		(net "PWRGD_CHC_CPU0_DIMM")
	)
	(segment
		(start 288.535618 -193.99631)
		(end 287.507172 -193.99631)
		(width 0.10668)
		(layer "B.Cu")
		(net "PWRGD_CHC_CPU0_DIMM")
	)
	(segment
		(start 287.024318 -193.935096)
		(end 286.468566 -193.379344)
		(width 0.10668)
		(layer "B.Cu")
		(net "PWRGD_CHC_CPU0_DIMM")
	)
	(segment
		(start 286.468566 -193.379344)
		(end 286.468566 -191.082422)
		(width 0.10668)
		(layer "B.Cu")
		(net "PWRGD_CHC_CPU0_DIMM")
	)
	(segment
		(start 286.468566 -191.082422)
		(end 286.461454 -191.07531)
		(width 0.10668)
		(layer "B.Cu")
		(net "PWRGD_CHC_CPU0_DIMM")
	)
	(segment
		(start 47.784004 -193.93535)
		(end 46.628304 -193.93535)
		(width 0.10668)
		(layer "F.Cu")
		(net "PWRGD_CHB_CPU1_DIMM")
	)
	(via
		(at 46.628304 -193.93535)
		(size 0.4826)
		(drill 0.254)
		(layers "F.Cu" "B.Cu")
		(net "PWRGD_CHB_CPU1_DIMM")
	)
	(via
		(at 46.014386 -190.694564)
		(size 0.6604)
		(drill 0.3302)
		(layers "F.Cu" "B.Cu")
		(net "PWRGD_CHB_CPU1_DIMM")
	)
	(segment
		(start 46.757336 -190.567564)
		(end 46.141386 -190.567564)
		(width 0.10668)
		(layer "B.Cu")
		(net "PWRGD_CHB_CPU1_DIMM")
	)
	(segment
		(start 47.049944 -193.93535)
		(end 47.111158 -193.996564)
		(width 0.10668)
		(layer "B.Cu")
		(net "PWRGD_CHB_CPU1_DIMM")
	)
	(segment
		(start 46.014386 -193.321432)
		(end 46.628304 -193.93535)
		(width 0.10668)
		(layer "B.Cu")
		(net "PWRGD_CHB_CPU1_DIMM")
	)
	(segment
		(start 46.628304 -193.93535)
		(end 47.049944 -193.93535)
		(width 0.10668)
		(layer "B.Cu")
		(net "PWRGD_CHB_CPU1_DIMM")
	)
	(segment
		(start 46.014386 -190.694564)
		(end 46.014386 -193.321432)
		(width 0.10668)
		(layer "B.Cu")
		(net "PWRGD_CHB_CPU1_DIMM")
	)
	(segment
		(start 47.138336 -190.948564)
		(end 46.757336 -190.567564)
		(width 0.10668)
		(layer "B.Cu")
		(net "PWRGD_CHB_CPU1_DIMM")
	)
	(segment
		(start 47.111158 -193.996564)
		(end 48.155098 -193.996564)
		(width 0.10668)
		(layer "B.Cu")
		(net "PWRGD_CHB_CPU1_DIMM")
	)
	(segment
		(start 46.141386 -190.567564)
		(end 46.014386 -190.694564)
		(width 0.10668)
		(layer "B.Cu")
		(net "PWRGD_CHB_CPU1_DIMM")
	)
	(segment
		(start 295.724072 -193.935096)
		(end 294.568372 -193.935096)
		(width 0.10668)
		(layer "F.Cu")
		(net "PWRGD_CHB_CPU0_DIMM")
	)
	(via
		(at 294.568372 -193.935096)
		(size 0.4826)
		(drill 0.254)
		(layers "F.Cu" "B.Cu")
		(net "PWRGD_CHB_CPU0_DIMM")
	)
	(via
		(at 293.954454 -191.07531)
		(size 0.6604)
		(drill 0.3302)
		(layers "F.Cu" "B.Cu")
		(net "PWRGD_CHB_CPU0_DIMM")
	)
	(segment
		(start 295.078404 -190.94831)
		(end 294.081454 -190.94831)
		(width 0.10668)
		(layer "B.Cu")
		(net "PWRGD_CHB_CPU0_DIMM")
	)
	(segment
		(start 293.954454 -191.07531)
		(end 293.954454 -193.321178)
		(width 0.10668)
		(layer "B.Cu")
		(net "PWRGD_CHB_CPU0_DIMM")
	)
	(segment
		(start 295.051226 -193.99631)
		(end 296.079672 -193.99631)
		(width 0.10668)
		(layer "B.Cu")
		(net "PWRGD_CHB_CPU0_DIMM")
	)
	(segment
		(start 294.990012 -193.935096)
		(end 295.051226 -193.99631)
		(width 0.10668)
		(layer "B.Cu")
		(net "PWRGD_CHB_CPU0_DIMM")
	)
	(segment
		(start 294.081454 -190.94831)
		(end 293.954454 -191.07531)
		(width 0.10668)
		(layer "B.Cu")
		(net "PWRGD_CHB_CPU0_DIMM")
	)
	(segment
		(start 293.954454 -193.321178)
		(end 294.568372 -193.935096)
		(width 0.10668)
		(layer "B.Cu")
		(net "PWRGD_CHB_CPU0_DIMM")
	)
	(segment
		(start 294.568372 -193.935096)
		(end 294.990012 -193.935096)
		(width 0.10668)
		(layer "B.Cu")
		(net "PWRGD_CHB_CPU0_DIMM")
	)
	(segment
		(start 55.328058 -193.93535)
		(end 54.172358 -193.93535)
		(width 0.10668)
		(layer "F.Cu")
		(net "PWRGD_CHA_CPU1_DIMM0")
	)
	(via
		(at 53.9496 -190.5508)
		(size 0.6604)
		(drill 0.3302)
		(layers "F.Cu" "B.Cu")
		(net "PWRGD_CHA_CPU1_DIMM0")
	)
	(via
		(at 54.172358 -193.93535)
		(size 0.4826)
		(drill 0.254)
		(layers "F.Cu" "B.Cu")
		(net "PWRGD_CHA_CPU1_DIMM0")
	)
	(segment
		(start 54.593998 -193.93535)
		(end 54.655212 -193.996564)
		(width 0.10668)
		(layer "B.Cu")
		(net "PWRGD_CHA_CPU1_DIMM0")
	)
	(segment
		(start 53.643276 -193.73342)
		(end 53.845206 -193.93535)
		(width 0.10668)
		(layer "B.Cu")
		(net "PWRGD_CHA_CPU1_DIMM0")
	)
	(segment
		(start 53.9496 -191.186054)
		(end 53.643276 -191.492378)
		(width 0.10668)
		(layer "B.Cu")
		(net "PWRGD_CHA_CPU1_DIMM0")
	)
	(segment
		(start 54.172358 -193.93535)
		(end 54.593998 -193.93535)
		(width 0.10668)
		(layer "B.Cu")
		(net "PWRGD_CHA_CPU1_DIMM0")
	)
	(segment
		(start 54.655212 -193.996564)
		(end 55.673752 -193.996564)
		(width 0.10668)
		(layer "B.Cu")
		(net "PWRGD_CHA_CPU1_DIMM0")
	)
	(segment
		(start 53.643276 -191.492378)
		(end 53.643276 -193.73342)
		(width 0.10668)
		(layer "B.Cu")
		(net "PWRGD_CHA_CPU1_DIMM0")
	)
	(segment
		(start 52.764436 -190.821564)
		(end 53.678836 -190.821564)
		(width 0.10668)
		(layer "B.Cu")
		(net "PWRGD_CHA_CPU1_DIMM0")
	)
	(segment
		(start 53.678836 -190.821564)
		(end 53.9496 -190.5508)
		(width 0.10668)
		(layer "B.Cu")
		(net "PWRGD_CHA_CPU1_DIMM0")
	)
	(segment
		(start 53.845206 -193.93535)
		(end 54.172358 -193.93535)
		(width 0.10668)
		(layer "B.Cu")
		(net "PWRGD_CHA_CPU1_DIMM0")
	)
	(segment
		(start 53.9496 -190.5508)
		(end 53.9496 -191.186054)
		(width 0.10668)
		(layer "B.Cu")
		(net "PWRGD_CHA_CPU1_DIMM0")
	)
	(segment
		(start 303.268126 -193.935096)
		(end 302.112426 -193.935096)
		(width 0.10668)
		(layer "F.Cu")
		(net "PWRGD_CHA_CPU0_DIMM0")
	)
	(via
		(at 301.828454 -191.07531)
		(size 0.6604)
		(drill 0.3302)
		(layers "F.Cu" "B.Cu")
		(net "PWRGD_CHA_CPU0_DIMM0")
	)
	(via
		(at 302.112426 -193.935096)
		(size 0.4826)
		(drill 0.254)
		(layers "F.Cu" "B.Cu")
		(net "PWRGD_CHA_CPU0_DIMM0")
	)
	(segment
		(start 301.785274 -193.935096)
		(end 302.112426 -193.935096)
		(width 0.10668)
		(layer "B.Cu")
		(net "PWRGD_CHA_CPU0_DIMM0")
	)
	(segment
		(start 301.828454 -191.07531)
		(end 301.583344 -191.32042)
		(width 0.10668)
		(layer "B.Cu")
		(net "PWRGD_CHA_CPU0_DIMM0")
	)
	(segment
		(start 302.59528 -193.99631)
		(end 303.623726 -193.99631)
		(width 0.10668)
		(layer "B.Cu")
		(net "PWRGD_CHA_CPU0_DIMM0")
	)
	(segment
		(start 301.574454 -190.82131)
		(end 301.828454 -191.07531)
		(width 0.10668)
		(layer "B.Cu")
		(net "PWRGD_CHA_CPU0_DIMM0")
	)
	(segment
		(start 302.112426 -193.935096)
		(end 302.534066 -193.935096)
		(width 0.10668)
		(layer "B.Cu")
		(net "PWRGD_CHA_CPU0_DIMM0")
	)
	(segment
		(start 302.534066 -193.935096)
		(end 302.59528 -193.99631)
		(width 0.10668)
		(layer "B.Cu")
		(net "PWRGD_CHA_CPU0_DIMM0")
	)
	(segment
		(start 301.583344 -193.733166)
		(end 301.785274 -193.935096)
		(width 0.10668)
		(layer "B.Cu")
		(net "PWRGD_CHA_CPU0_DIMM0")
	)
	(segment
		(start 301.583344 -191.32042)
		(end 301.583344 -193.733166)
		(width 0.10668)
		(layer "B.Cu")
		(net "PWRGD_CHA_CPU0_DIMM0")
	)
	(segment
		(start 300.704504 -190.82131)
		(end 301.574454 -190.82131)
		(width 0.10668)
		(layer "B.Cu")
		(net "PWRGD_CHA_CPU0_DIMM0")
	)
	(segment
		(start 142.832328 -122.738388)
		(end 142.46606 -123.104656)
		(width 0.10668)
		(layer "F.Cu")
		(net "PWRGD_CHAF_CPU1")
	)
	(segment
		(start 146.53895 -120.777)
		(end 145.56105 -120.777)
		(width 0.10668)
		(layer "F.Cu")
		(net "PWRGD_CHAF_CPU1")
	)
	(segment
		(start 145.56105 -120.777)
		(end 143.599662 -122.738388)
		(width 0.10668)
		(layer "F.Cu")
		(net "PWRGD_CHAF_CPU1")
	)
	(segment
		(start 143.599662 -122.738388)
		(end 142.832328 -122.738388)
		(width 0.10668)
		(layer "F.Cu")
		(net "PWRGD_CHAF_CPU1")
	)
	(via
		(at 86.445598 -126.101348)
		(size 0.508)
		(drill 0.254)
		(layers "F.Cu" "B.Cu")
		(net "PWRGD_CHAF_CPU1")
	)
	(via
		(at 16.480282 -190.186564)
		(size 0.6604)
		(drill 0.3302)
		(layers "F.Cu" "B.Cu")
		(net "PWRGD_CHAF_CPU1")
	)
	(via
		(at 52.388516 -186.064398)
		(size 0.508)
		(drill 0.254)
		(layers "F.Cu" "B.Cu")
		(net "PWRGD_CHAF_CPU1")
	)
	(via
		(at 142.46606 -123.104656)
		(size 0.508)
		(drill 0.254)
		(layers "F.Cu" "B.Cu")
		(net "PWRGD_CHAF_CPU1")
	)
	(segment
		(start 16.607282 -190.059564)
		(end 25.479756 -190.059564)
		(width 0.10668)
		(layer "B.Cu")
		(net "PWRGD_CHAF_CPU1")
	)
	(segment
		(start 40.445436 -190.420244)
		(end 40.445436 -190.948564)
		(width 0.10668)
		(layer "B.Cu")
		(net "PWRGD_CHAF_CPU1")
	)
	(segment
		(start 25.713436 -190.948564)
		(end 26.456386 -190.948564)
		(width 0.10668)
		(layer "B.Cu")
		(net "PWRGD_CHAF_CPU1")
	)
	(segment
		(start 26.456386 -190.948564)
		(end 27.726386 -189.678564)
		(width 0.10668)
		(layer "B.Cu")
		(net "PWRGD_CHAF_CPU1")
	)
	(segment
		(start 15.113762 -191.553084)
		(end 16.480282 -190.186564)
		(width 0.10668)
		(layer "B.Cu")
		(net "PWRGD_CHAF_CPU1")
	)
	(segment
		(start 40.445436 -190.948564)
		(end 41.950386 -190.948564)
		(width 0.10668)
		(layer "B.Cu")
		(net "PWRGD_CHAF_CPU1")
	)
	(segment
		(start 15.113762 -191.962278)
		(end 15.113762 -191.553084)
		(width 0.10668)
		(layer "B.Cu")
		(net "PWRGD_CHAF_CPU1")
	)
	(segment
		(start 31.682436 -189.678564)
		(end 32.952436 -190.948564)
		(width 0.10668)
		(layer "B.Cu")
		(net "PWRGD_CHAF_CPU1")
	)
	(segment
		(start 50.380646 -191.427354)
		(end 50.986436 -190.821564)
		(width 0.10668)
		(layer "B.Cu")
		(net "PWRGD_CHAF_CPU1")
	)
	(segment
		(start 49.001172 -191.427354)
		(end 50.380646 -191.427354)
		(width 0.10668)
		(layer "B.Cu")
		(net "PWRGD_CHAF_CPU1")
	)
	(segment
		(start 25.713436 -190.293244)
		(end 25.713436 -190.948564)
		(width 0.10668)
		(layer "B.Cu")
		(net "PWRGD_CHAF_CPU1")
	)
	(segment
		(start 25.479756 -190.059564)
		(end 25.713436 -190.293244)
		(width 0.10668)
		(layer "B.Cu")
		(net "PWRGD_CHAF_CPU1")
	)
	(segment
		(start 32.952436 -190.948564)
		(end 34.330132 -190.948564)
		(width 0.10668)
		(layer "B.Cu")
		(net "PWRGD_CHAF_CPU1")
	)
	(segment
		(start 27.726386 -189.678564)
		(end 31.682436 -189.678564)
		(width 0.10668)
		(layer "B.Cu")
		(net "PWRGD_CHAF_CPU1")
	)
	(segment
		(start 50.986436 -190.821564)
		(end 51.964336 -190.821564)
		(width 0.10668)
		(layer "B.Cu")
		(net "PWRGD_CHAF_CPU1")
	)
	(segment
		(start 47.938436 -190.420244)
		(end 47.938436 -190.948564)
		(width 0.10668)
		(layer "B.Cu")
		(net "PWRGD_CHAF_CPU1")
	)
	(segment
		(start 35.473132 -189.805564)
		(end 39.830756 -189.805564)
		(width 0.10668)
		(layer "B.Cu")
		(net "PWRGD_CHAF_CPU1")
	)
	(segment
		(start 34.330132 -190.948564)
		(end 35.473132 -189.805564)
		(width 0.10668)
		(layer "B.Cu")
		(net "PWRGD_CHAF_CPU1")
	)
	(segment
		(start 51.964336 -190.821564)
		(end 51.964336 -186.488578)
		(width 0.10668)
		(layer "B.Cu")
		(net "PWRGD_CHAF_CPU1")
	)
	(segment
		(start 41.950386 -190.948564)
		(end 42.966386 -189.932564)
		(width 0.10668)
		(layer "B.Cu")
		(net "PWRGD_CHAF_CPU1")
	)
	(segment
		(start 47.938436 -190.948564)
		(end 48.522382 -190.948564)
		(width 0.10668)
		(layer "B.Cu")
		(net "PWRGD_CHAF_CPU1")
	)
	(segment
		(start 42.966386 -189.932564)
		(end 47.450756 -189.932564)
		(width 0.10668)
		(layer "B.Cu")
		(net "PWRGD_CHAF_CPU1")
	)
	(segment
		(start 39.830756 -189.805564)
		(end 40.445436 -190.420244)
		(width 0.10668)
		(layer "B.Cu")
		(net "PWRGD_CHAF_CPU1")
	)
	(segment
		(start 16.480282 -190.186564)
		(end 16.607282 -190.059564)
		(width 0.10668)
		(layer "B.Cu")
		(net "PWRGD_CHAF_CPU1")
	)
	(segment
		(start 47.450756 -189.932564)
		(end 47.938436 -190.420244)
		(width 0.10668)
		(layer "B.Cu")
		(net "PWRGD_CHAF_CPU1")
	)
	(segment
		(start 48.522382 -190.948564)
		(end 49.001172 -191.427354)
		(width 0.10668)
		(layer "B.Cu")
		(net "PWRGD_CHAF_CPU1")
	)
	(segment
		(start 51.964336 -186.488578)
		(end 52.388516 -186.064398)
		(width 0.10668)
		(layer "B.Cu")
		(net "PWRGD_CHAF_CPU1")
	)
	(segment
		(start 51.055524 -184.731406)
		(end 52.388516 -186.064398)
		(width 0.11684)
		(layer "In4.Cu")
		(net "PWRGD_CHAF_CPU1")
	)
	(segment
		(start 79.728568 -128.967992)
		(end 69.032882 -139.663678)
		(width 0.11684)
		(layer "In4.Cu")
		(net "PWRGD_CHAF_CPU1")
	)
	(segment
		(start 69.032882 -139.663678)
		(end 46.498002 -139.663678)
		(width 0.11684)
		(layer "In4.Cu")
		(net "PWRGD_CHAF_CPU1")
	)
	(segment
		(start 42.40149 -143.76019)
		(end 42.40149 -152.671272)
		(width 0.11684)
		(layer "In4.Cu")
		(net "PWRGD_CHAF_CPU1")
	)
	(segment
		(start 43.719242 -184.731406)
		(end 51.055524 -184.731406)
		(width 0.11684)
		(layer "In4.Cu")
		(net "PWRGD_CHAF_CPU1")
	)
	(segment
		(start 36.449 -177.461164)
		(end 43.719242 -184.731406)
		(width 0.11684)
		(layer "In4.Cu")
		(net "PWRGD_CHAF_CPU1")
	)
	(segment
		(start 83.578954 -128.967992)
		(end 79.728568 -128.967992)
		(width 0.11684)
		(layer "In4.Cu")
		(net "PWRGD_CHAF_CPU1")
	)
	(segment
		(start 46.498002 -139.663678)
		(end 42.40149 -143.76019)
		(width 0.11684)
		(layer "In4.Cu")
		(net "PWRGD_CHAF_CPU1")
	)
	(segment
		(start 86.445598 -126.101348)
		(end 83.578954 -128.967992)
		(width 0.11684)
		(layer "In4.Cu")
		(net "PWRGD_CHAF_CPU1")
	)
	(segment
		(start 36.449 -168.88968)
		(end 36.449 -177.461164)
		(width 0.11684)
		(layer "In4.Cu")
		(net "PWRGD_CHAF_CPU1")
	)
	(segment
		(start 42.40149 -152.671272)
		(end 35.45332 -159.619442)
		(width 0.11684)
		(layer "In4.Cu")
		(net "PWRGD_CHAF_CPU1")
	)
	(segment
		(start 35.45332 -167.894)
		(end 36.449 -168.88968)
		(width 0.11684)
		(layer "In4.Cu")
		(net "PWRGD_CHAF_CPU1")
	)
	(segment
		(start 35.45332 -159.619442)
		(end 35.45332 -167.894)
		(width 0.11684)
		(layer "In4.Cu")
		(net "PWRGD_CHAF_CPU1")
	)
	(segment
		(start 97.898712 -125.086618)
		(end 110.076234 -125.086618)
		(width 0.11684)
		(layer "In6.Cu")
		(net "PWRGD_CHAF_CPU1")
	)
	(segment
		(start 86.445598 -126.101348)
		(end 96.883982 -126.101348)
		(width 0.11684)
		(layer "In6.Cu")
		(net "PWRGD_CHAF_CPU1")
	)
	(segment
		(start 116.066824 -125.4125)
		(end 116.140738 -125.338586)
		(width 0.11684)
		(layer "In6.Cu")
		(net "PWRGD_CHAF_CPU1")
	)
	(segment
		(start 140.23213 -125.338586)
		(end 142.46606 -123.104656)
		(width 0.11684)
		(layer "In6.Cu")
		(net "PWRGD_CHAF_CPU1")
	)
	(segment
		(start 96.883982 -126.101348)
		(end 97.898712 -125.086618)
		(width 0.11684)
		(layer "In6.Cu")
		(net "PWRGD_CHAF_CPU1")
	)
	(segment
		(start 110.402116 -125.4125)
		(end 116.066824 -125.4125)
		(width 0.11684)
		(layer "In6.Cu")
		(net "PWRGD_CHAF_CPU1")
	)
	(segment
		(start 110.076234 -125.086618)
		(end 110.402116 -125.4125)
		(width 0.11684)
		(layer "In6.Cu")
		(net "PWRGD_CHAF_CPU1")
	)
	(segment
		(start 116.140738 -125.338586)
		(end 140.23213 -125.338586)
		(width 0.11684)
		(layer "In6.Cu")
		(net "PWRGD_CHAF_CPU1")
	)
	(segment
		(start 210.439 -104.648)
		(end 212.344 -104.648)
		(width 0.10668)
		(layer "F.Cu")
		(net "PWRGD_CHAF_CPU0")
	)
	(segment
		(start 210.03895 -104.24795)
		(end 210.439 -104.648)
		(width 0.10668)
		(layer "F.Cu")
		(net "PWRGD_CHAF_CPU0")
	)
	(segment
		(start 210.03895 -104.013)
		(end 210.03895 -104.24795)
		(width 0.10668)
		(layer "F.Cu")
		(net "PWRGD_CHAF_CPU0")
	)
	(segment
		(start 271.646904 -186.867038)
		(end 271.368012 -187.14593)
		(width 0.10668)
		(layer "F.Cu")
		(net "PWRGD_CHAF_CPU0")
	)
	(segment
		(start 209.06105 -104.013)
		(end 210.03895 -104.013)
		(width 0.10668)
		(layer "F.Cu")
		(net "PWRGD_CHAF_CPU0")
	)
	(segment
		(start 212.344 -104.648)
		(end 212.979 -104.013)
		(width 0.10668)
		(layer "F.Cu")
		(net "PWRGD_CHAF_CPU0")
	)
	(segment
		(start 272.346928 -169.608246)
		(end 271.646904 -170.30827)
		(width 0.10668)
		(layer "F.Cu")
		(net "PWRGD_CHAF_CPU0")
	)
	(segment
		(start 271.646904 -170.30827)
		(end 271.646904 -186.867038)
		(width 0.10668)
		(layer "F.Cu")
		(net "PWRGD_CHAF_CPU0")
	)
	(via
		(at 212.979 -104.013)
		(size 0.508)
		(drill 0.254)
		(layers "F.Cu" "B.Cu")
		(net "PWRGD_CHAF_CPU0")
	)
	(via
		(at 271.368012 -187.14593)
		(size 0.508)
		(drill 0.254)
		(layers "F.Cu" "B.Cu")
		(net "PWRGD_CHAF_CPU0")
	)
	(via
		(at 272.346928 -169.608246)
		(size 0.508)
		(drill 0.254)
		(layers "F.Cu" "B.Cu")
		(net "PWRGD_CHAF_CPU0")
	)
	(segment
		(start 290.525454 -190.31331)
		(end 295.771824 -190.31331)
		(width 0.10668)
		(layer "B.Cu")
		(net "PWRGD_CHAF_CPU0")
	)
	(segment
		(start 296.46245 -190.94831)
		(end 297.22445 -190.18631)
		(width 0.10668)
		(layer "B.Cu")
		(net "PWRGD_CHAF_CPU0")
	)
	(segment
		(start 280.892504 -190.94831)
		(end 281.733244 -190.10757)
		(width 0.10668)
		(layer "B.Cu")
		(net "PWRGD_CHAF_CPU0")
	)
	(segment
		(start 288.385504 -190.94831)
		(end 289.890454 -190.94831)
		(width 0.10668)
		(layer "B.Cu")
		(net "PWRGD_CHAF_CPU0")
	)
	(segment
		(start 281.733244 -190.10757)
		(end 287.544764 -190.10757)
		(width 0.10668)
		(layer "B.Cu")
		(net "PWRGD_CHAF_CPU0")
	)
	(segment
		(start 269.797784 -190.82131)
		(end 270.604742 -190.014352)
		(width 0.10668)
		(layer "B.Cu")
		(net "PWRGD_CHAF_CPU0")
	)
	(segment
		(start 280.090626 -190.146432)
		(end 280.892504 -190.94831)
		(width 0.10668)
		(layer "B.Cu")
		(net "PWRGD_CHAF_CPU0")
	)
	(segment
		(start 271.311624 -187.427108)
		(end 271.311624 -187.246514)
		(width 0.10668)
		(layer "B.Cu")
		(net "PWRGD_CHAF_CPU0")
	)
	(segment
		(start 297.22445 -190.18631)
		(end 298.653454 -190.18631)
		(width 0.10668)
		(layer "B.Cu")
		(net "PWRGD_CHAF_CPU0")
	)
	(segment
		(start 298.926504 -190.45936)
		(end 298.926504 -190.82131)
		(width 0.10668)
		(layer "B.Cu")
		(net "PWRGD_CHAF_CPU0")
	)
	(segment
		(start 274.455382 -190.146432)
		(end 280.090626 -190.146432)
		(width 0.10668)
		(layer "B.Cu")
		(net "PWRGD_CHAF_CPU0")
	)
	(segment
		(start 298.926504 -190.82131)
		(end 299.904404 -190.82131)
		(width 0.10668)
		(layer "B.Cu")
		(net "PWRGD_CHAF_CPU0")
	)
	(segment
		(start 295.771824 -190.31331)
		(end 295.878504 -190.41999)
		(width 0.10668)
		(layer "B.Cu")
		(net "PWRGD_CHAF_CPU0")
	)
	(segment
		(start 265.906504 -190.00724)
		(end 266.063476 -189.850268)
		(width 0.10668)
		(layer "B.Cu")
		(net "PWRGD_CHAF_CPU0")
	)
	(segment
		(start 265.906504 -190.82131)
		(end 265.906504 -190.00724)
		(width 0.10668)
		(layer "B.Cu")
		(net "PWRGD_CHAF_CPU0")
	)
	(segment
		(start 295.878504 -190.41999)
		(end 295.878504 -190.94831)
		(width 0.10668)
		(layer "B.Cu")
		(net "PWRGD_CHAF_CPU0")
	)
	(segment
		(start 271.311624 -187.246514)
		(end 271.336008 -187.22213)
		(width 0.10668)
		(layer "B.Cu")
		(net "PWRGD_CHAF_CPU0")
	)
	(segment
		(start 268.888464 -189.850268)
		(end 271.311624 -187.427108)
		(width 0.10668)
		(layer "B.Cu")
		(net "PWRGD_CHAF_CPU0")
	)
	(segment
		(start 271.336008 -187.177934)
		(end 271.368012 -187.14593)
		(width 0.10668)
		(layer "B.Cu")
		(net "PWRGD_CHAF_CPU0")
	)
	(segment
		(start 266.063476 -189.850268)
		(end 268.888464 -189.850268)
		(width 0.10668)
		(layer "B.Cu")
		(net "PWRGD_CHAF_CPU0")
	)
	(segment
		(start 289.890454 -190.94831)
		(end 290.525454 -190.31331)
		(width 0.10668)
		(layer "B.Cu")
		(net "PWRGD_CHAF_CPU0")
	)
	(segment
		(start 273.653504 -190.94831)
		(end 274.455382 -190.146432)
		(width 0.10668)
		(layer "B.Cu")
		(net "PWRGD_CHAF_CPU0")
	)
	(segment
		(start 298.653454 -190.18631)
		(end 298.926504 -190.45936)
		(width 0.10668)
		(layer "B.Cu")
		(net "PWRGD_CHAF_CPU0")
	)
	(segment
		(start 287.544764 -190.10757)
		(end 288.385504 -190.94831)
		(width 0.10668)
		(layer "B.Cu")
		(net "PWRGD_CHAF_CPU0")
	)
	(segment
		(start 271.336008 -187.22213)
		(end 271.336008 -187.177934)
		(width 0.10668)
		(layer "B.Cu")
		(net "PWRGD_CHAF_CPU0")
	)
	(segment
		(start 272.719546 -190.014352)
		(end 273.653504 -190.94831)
		(width 0.10668)
		(layer "B.Cu")
		(net "PWRGD_CHAF_CPU0")
	)
	(segment
		(start 295.878504 -190.94831)
		(end 296.46245 -190.94831)
		(width 0.10668)
		(layer "B.Cu")
		(net "PWRGD_CHAF_CPU0")
	)
	(segment
		(start 265.906504 -190.82131)
		(end 269.797784 -190.82131)
		(width 0.10668)
		(layer "B.Cu")
		(net "PWRGD_CHAF_CPU0")
	)
	(segment
		(start 270.604742 -190.014352)
		(end 272.719546 -190.014352)
		(width 0.10668)
		(layer "B.Cu")
		(net "PWRGD_CHAF_CPU0")
	)
	(segment
		(start 213.208616 -104.013)
		(end 212.979 -104.013)
		(width 0.11684)
		(layer "In2.Cu")
		(net "PWRGD_CHAF_CPU0")
	)
	(segment
		(start 260.827266 -112.847374)
		(end 254.70612 -112.847374)
		(width 0.11684)
		(layer "In2.Cu")
		(net "PWRGD_CHAF_CPU0")
	)
	(segment
		(start 267.705078 -137.659364)
		(end 270.39951 -134.964932)
		(width 0.11684)
		(layer "In2.Cu")
		(net "PWRGD_CHAF_CPU0")
	)
	(segment
		(start 215.419178 -108.48975)
		(end 215.419178 -106.223562)
		(width 0.11684)
		(layer "In2.Cu")
		(net "PWRGD_CHAF_CPU0")
	)
	(segment
		(start 252.85954 -111.000794)
		(end 217.930222 -111.000794)
		(width 0.11684)
		(layer "In2.Cu")
		(net "PWRGD_CHAF_CPU0")
	)
	(segment
		(start 272.346928 -169.608246)
		(end 267.705078 -164.966396)
		(width 0.11684)
		(layer "In2.Cu")
		(net "PWRGD_CHAF_CPU0")
	)
	(segment
		(start 217.930222 -111.000794)
		(end 215.419178 -108.48975)
		(width 0.11684)
		(layer "In2.Cu")
		(net "PWRGD_CHAF_CPU0")
	)
	(segment
		(start 264.564114 -123.458478)
		(end 264.564114 -116.584222)
		(width 0.11684)
		(layer "In2.Cu")
		(net "PWRGD_CHAF_CPU0")
	)
	(segment
		(start 270.39951 -129.293874)
		(end 264.564114 -123.458478)
		(width 0.11684)
		(layer "In2.Cu")
		(net "PWRGD_CHAF_CPU0")
	)
	(segment
		(start 264.564114 -116.584222)
		(end 260.827266 -112.847374)
		(width 0.11684)
		(layer "In2.Cu")
		(net "PWRGD_CHAF_CPU0")
	)
	(segment
		(start 270.39951 -134.964932)
		(end 270.39951 -129.293874)
		(width 0.11684)
		(layer "In2.Cu")
		(net "PWRGD_CHAF_CPU0")
	)
	(segment
		(start 254.70612 -112.847374)
		(end 252.85954 -111.000794)
		(width 0.11684)
		(layer "In2.Cu")
		(net "PWRGD_CHAF_CPU0")
	)
	(segment
		(start 215.419178 -106.223562)
		(end 213.208616 -104.013)
		(width 0.11684)
		(layer "In2.Cu")
		(net "PWRGD_CHAF_CPU0")
	)
	(segment
		(start 267.705078 -164.966396)
		(end 267.705078 -137.659364)
		(width 0.11684)
		(layer "In2.Cu")
		(net "PWRGD_CHAF_CPU0")
	)
	(segment
		(start 199.454008 -338.955126)
		(end 198.732394 -338.955126)
		(width 0.254)
		(layer "F.Cu")
		(net "PVDD_33_S5_VCC")
	)
	(segment
		(start 198.655178 -338.881974)
		(end 197.979538 -338.881974)
		(width 0.254)
		(layer "F.Cu")
		(net "PVDD_33_S5_VCC")
	)
	(segment
		(start 198.65721 -338.879942)
		(end 198.655178 -338.881974)
		(width 0.254)
		(layer "F.Cu")
		(net "PVDD_33_S5_VCC")
	)
	(segment
		(start 198.732394 -338.955126)
		(end 198.65721 -338.879942)
		(width 0.254)
		(layer "F.Cu")
		(net "PVDD_33_S5_VCC")
	)
	(via
		(at 198.65721 -338.879942)
		(size 0.508)
		(drill 0.254)
		(layers "F.Cu" "B.Cu")
		(net "PVDD_33_S5_VCC")
	)
	(segment
		(start 199.894698 -338.879942)
		(end 201.118978 -340.104222)
		(width 0.254)
		(layer "B.Cu")
		(net "PVDD_33_S5_VCC")
	)
	(segment
		(start 201.118978 -340.104222)
		(end 201.118978 -341.23122)
		(width 0.254)
		(layer "B.Cu")
		(net "PVDD_33_S5_VCC")
	)
	(segment
		(start 201.118978 -341.23122)
		(end 201.7522 -341.864442)
		(width 0.254)
		(layer "B.Cu")
		(net "PVDD_33_S5_VCC")
	)
	(segment
		(start 198.65721 -338.879942)
		(end 199.894698 -338.879942)
		(width 0.254)
		(layer "B.Cu")
		(net "PVDD_33_S5_VCC")
	)
	(segment
		(start 204.289406 -340.553548)
		(end 203.881482 -340.553548)
		(width 0.1778)
		(layer "F.Cu")
		(net "PVDD_33_S5_REF")
	)
	(segment
		(start 203.779882 -340.655148)
		(end 202.254104 -340.655148)
		(width 0.1778)
		(layer "F.Cu")
		(net "PVDD_33_S5_REF")
	)
	(segment
		(start 203.881482 -340.553548)
		(end 203.779882 -340.655148)
		(width 0.1778)
		(layer "F.Cu")
		(net "PVDD_33_S5_REF")
	)
	(segment
		(start 202.800458 -341.455248)
		(end 202.254104 -341.455248)
		(width 0.1778)
		(layer "F.Cu")
		(net "PVDD_33_S5_FB")
	)
	(segment
		(start 204.332078 -342.475312)
		(end 203.251054 -341.728552)
		(width 0.254)
		(layer "F.Cu")
		(net "PVDD_33_S5_FB")
	)
	(segment
		(start 203.251054 -341.728552)
		(end 202.800458 -341.455248)
		(width 0.1778)
		(layer "F.Cu")
		(net "PVDD_33_S5_FB")
	)
	(segment
		(start 206.381604 -342.475312)
		(end 205.365604 -342.475312)
		(width 0.254)
		(layer "F.Cu")
		(net "PVDD_33_S5_FB")
	)
	(segment
		(start 205.365604 -342.475312)
		(end 204.332078 -342.475312)
		(width 0.254)
		(layer "F.Cu")
		(net "PVDD_33_S5_FB")
	)
	(segment
		(start 202.851766 -339.855048)
		(end 202.254104 -339.855048)
		(width 0.1778)
		(layer "F.Cu")
		(net "PVDD_33_S5_CS")
	)
	(segment
		(start 204.289406 -339.428836)
		(end 203.687172 -339.428836)
		(width 0.1778)
		(layer "F.Cu")
		(net "PVDD_33_S5_CS")
	)
	(segment
		(start 203.687172 -339.428836)
		(end 202.851766 -339.855048)
		(width 0.1778)
		(layer "F.Cu")
		(net "PVDD_33_S5_CS")
	)
	(segment
		(start 99.387914 -266.530328)
		(end 98.921062 -266.796266)
		(width 0.350012)
		(layer "F.Cu")
		(net "PVDD_33_S5")
	)
	(segment
		(start 347.797882 -267.34008)
		(end 347.33103 -267.606018)
		(width 0.350012)
		(layer "F.Cu")
		(net "PVDD_33_S5")
	)
	(segment
		(start 347.327982 -266.530074)
		(end 346.86113 -266.796012)
		(width 0.350012)
		(layer "F.Cu")
		(net "PVDD_33_S5")
	)
	(segment
		(start 206.381604 -341.675212)
		(end 206.381604 -331.125322)
		(width 0.254)
		(layer "F.Cu")
		(net "PVDD_33_S5")
	)
	(segment
		(start 205.365604 -341.675212)
		(end 206.381604 -341.675212)
		(width 0.254)
		(layer "F.Cu")
		(net "PVDD_33_S5")
	)
	(segment
		(start 206.381604 -331.125322)
		(end 205.910434 -330.654152)
		(width 0.254)
		(layer "F.Cu")
		(net "PVDD_33_S5")
	)
	(segment
		(start 99.857814 -267.340334)
		(end 99.390962 -267.606272)
		(width 0.350012)
		(layer "F.Cu")
		(net "PVDD_33_S5")
	)
	(segment
		(start 205.910434 -330.654152)
		(end 205.167992 -330.654152)
		(width 0.254)
		(layer "F.Cu")
		(net "PVDD_33_S5")
	)
	(via
		(at 198.95312 -330.456286)
		(size 0.508)
		(drill 0.254)
		(layers "F.Cu" "B.Cu")
		(net "PVDD_33_S5")
	)
	(via
		(at 197.61962 -329.249786)
		(size 0.508)
		(drill 0.254)
		(layers "F.Cu" "B.Cu")
		(net "PVDD_33_S5")
	)
	(via
		(at 203.01712 -330.456286)
		(size 0.508)
		(drill 0.254)
		(layers "F.Cu" "B.Cu")
		(net "PVDD_33_S5")
	)
	(via
		(at 203.01712 -329.186286)
		(size 0.508)
		(drill 0.254)
		(layers "F.Cu" "B.Cu")
		(net "PVDD_33_S5")
	)
	(via
		(at 203.01712 -329.821286)
		(size 0.508)
		(drill 0.254)
		(layers "F.Cu" "B.Cu")
		(net "PVDD_33_S5")
	)
	(via
		(at 204.35062 -329.249786)
		(size 0.508)
		(drill 0.254)
		(layers "F.Cu" "B.Cu")
		(net "PVDD_33_S5")
	)
	(via
		(at 198.25462 -329.249786)
		(size 0.508)
		(drill 0.254)
		(layers "F.Cu" "B.Cu")
		(net "PVDD_33_S5")
	)
	(via
		(at 199.52208 -328.20864)
		(size 0.508)
		(drill 0.254)
		(layers "F.Cu" "B.Cu")
		(net "PVDD_33_S5")
	)
	(via
		(at 263.248394 -324.017132)
		(size 0.508)
		(drill 0.254)
		(layers "F.Cu" "B.Cu")
		(net "PVDD_33_S5")
	)
	(via
		(at 264.88517 -323.990208)
		(size 0.508)
		(drill 0.254)
		(layers "F.Cu" "B.Cu")
		(net "PVDD_33_S5")
	)
	(via
		(at 263.261602 -324.853046)
		(size 0.508)
		(drill 0.254)
		(layers "F.Cu" "B.Cu")
		(net "PVDD_33_S5")
	)
	(via
		(at 201.30008 -328.20864)
		(size 0.508)
		(drill 0.254)
		(layers "F.Cu" "B.Cu")
		(net "PVDD_33_S5")
	)
	(via
		(at 264.044684 -323.970396)
		(size 0.508)
		(drill 0.254)
		(layers "F.Cu" "B.Cu")
		(net "PVDD_33_S5")
	)
	(via
		(at 347.33103 -267.606018)
		(size 0.4064)
		(drill 0.2032)
		(layers "F.Cu" "B.Cu")
		(net "PVDD_33_S5")
	)
	(via
		(at 202.18908 -328.20864)
		(size 0.508)
		(drill 0.254)
		(layers "F.Cu" "B.Cu")
		(net "PVDD_33_S5")
	)
	(via
		(at 239.035082 -326.683624)
		(size 0.508)
		(drill 0.254)
		(layers "F.Cu" "B.Cu")
		(net "PVDD_33_S5")
	)
	(via
		(at 264.057892 -324.80631)
		(size 0.508)
		(drill 0.254)
		(layers "F.Cu" "B.Cu")
		(net "PVDD_33_S5")
	)
	(via
		(at 98.921062 -266.796266)
		(size 0.4064)
		(drill 0.2032)
		(layers "F.Cu" "B.Cu")
		(net "PVDD_33_S5")
	)
	(via
		(at 205.130654 -330.007214)
		(size 0.508)
		(drill 0.254)
		(layers "F.Cu" "B.Cu")
		(net "PVDD_33_S5")
	)
	(via
		(at 198.95312 -329.821286)
		(size 0.508)
		(drill 0.254)
		(layers "F.Cu" "B.Cu")
		(net "PVDD_33_S5")
	)
	(via
		(at 346.86113 -266.796012)
		(size 0.4064)
		(drill 0.2032)
		(layers "F.Cu" "B.Cu")
		(net "PVDD_33_S5")
	)
	(via
		(at 218.959176 -317.420498)
		(size 0.508)
		(drill 0.254)
		(layers "F.Cu" "B.Cu")
		(net "PVDD_33_S5")
	)
	(via
		(at 99.390962 -267.606272)
		(size 0.4064)
		(drill 0.2032)
		(layers "F.Cu" "B.Cu")
		(net "PVDD_33_S5")
	)
	(via
		(at 262.428736 -324.102984)
		(size 0.508)
		(drill 0.254)
		(layers "F.Cu" "B.Cu")
		(net "PVDD_33_S5")
	)
	(via
		(at 200.41108 -328.20864)
		(size 0.508)
		(drill 0.254)
		(layers "F.Cu" "B.Cu")
		(net "PVDD_33_S5")
	)
	(via
		(at 264.832846 -324.904608)
		(size 0.508)
		(drill 0.254)
		(layers "F.Cu" "B.Cu")
		(net "PVDD_33_S5")
	)
	(via
		(at 203.71562 -329.249786)
		(size 0.508)
		(drill 0.254)
		(layers "F.Cu" "B.Cu")
		(net "PVDD_33_S5")
	)
	(via
		(at 198.95312 -329.186286)
		(size 0.508)
		(drill 0.254)
		(layers "F.Cu" "B.Cu")
		(net "PVDD_33_S5")
	)
	(via
		(at 262.441944 -324.938898)
		(size 0.508)
		(drill 0.254)
		(layers "F.Cu" "B.Cu")
		(net "PVDD_33_S5")
	)
	(segment
		(start 238.310674 -326.683624)
		(end 239.035082 -326.683624)
		(width 0.508)
		(layer "B.Cu")
		(net "PVDD_33_S5")
	)
	(segment
		(start 239.035082 -326.683624)
		(end 237.85068 -326.683624)
		(width 0.508)
		(layer "In4.Cu")
		(net "PVDD_33_S5")
	)
	(segment
		(start 237.447836 -321.452494)
		(end 236.725206 -320.729864)
		(width 0.508)
		(layer "In4.Cu")
		(net "PVDD_33_S5")
	)
	(segment
		(start 237.85068 -326.683624)
		(end 237.447836 -326.28078)
		(width 0.508)
		(layer "In4.Cu")
		(net "PVDD_33_S5")
	)
	(segment
		(start 236.725206 -320.729864)
		(end 223.422972 -320.729864)
		(width 0.508)
		(layer "In4.Cu")
		(net "PVDD_33_S5")
	)
	(segment
		(start 223.422972 -320.729864)
		(end 220.113606 -317.420498)
		(width 0.508)
		(layer "In4.Cu")
		(net "PVDD_33_S5")
	)
	(segment
		(start 237.447836 -326.28078)
		(end 237.447836 -321.452494)
		(width 0.508)
		(layer "In4.Cu")
		(net "PVDD_33_S5")
	)
	(segment
		(start 220.113606 -317.420498)
		(end 218.959176 -317.420498)
		(width 0.508)
		(layer "In4.Cu")
		(net "PVDD_33_S5")
	)
	(segment
		(start 26.200608 -349.28302)
		(end 25.875996 -349.607632)
		(width 0.2032)
		(layer "F.Cu")
		(net "PVDDIO_P1_VOS4")
	)
	(segment
		(start 26.200608 -348.996254)
		(end 26.200608 -349.28302)
		(width 0.2032)
		(layer "F.Cu")
		(net "PVDDIO_P1_VOS4")
	)
	(via
		(at 25.875996 -349.607632)
		(size 0.508)
		(drill 0.254)
		(layers "F.Cu" "B.Cu")
		(net "PVDDIO_P1_VOS4")
	)
	(segment
		(start 25.254712 -348.986348)
		(end 25.875996 -349.607632)
		(width 0.2286)
		(layer "B.Cu")
		(net "PVDDIO_P1_VOS4")
	)
	(segment
		(start 24.939244 -348.986348)
		(end 25.254712 -348.986348)
		(width 0.2286)
		(layer "B.Cu")
		(net "PVDDIO_P1_VOS4")
	)
	(segment
		(start 34.481008 -349.28302)
		(end 34.156396 -349.607632)
		(width 0.2032)
		(layer "F.Cu")
		(net "PVDDIO_P1_VOS3")
	)
	(segment
		(start 34.481008 -348.996254)
		(end 34.481008 -349.28302)
		(width 0.2032)
		(layer "F.Cu")
		(net "PVDDIO_P1_VOS3")
	)
	(via
		(at 34.156396 -349.607632)
		(size 0.508)
		(drill 0.254)
		(layers "F.Cu" "B.Cu")
		(net "PVDDIO_P1_VOS3")
	)
	(segment
		(start 33.535112 -348.986348)
		(end 34.156396 -349.607632)
		(width 0.2286)
		(layer "B.Cu")
		(net "PVDDIO_P1_VOS3")
	)
	(segment
		(start 33.219644 -348.986348)
		(end 33.535112 -348.986348)
		(width 0.2286)
		(layer "B.Cu")
		(net "PVDDIO_P1_VOS3")
	)
	(segment
		(start 42.786808 -349.28302)
		(end 42.462196 -349.607632)
		(width 0.2032)
		(layer "F.Cu")
		(net "PVDDIO_P1_VOS2")
	)
	(segment
		(start 42.786808 -348.996254)
		(end 42.786808 -349.28302)
		(width 0.2032)
		(layer "F.Cu")
		(net "PVDDIO_P1_VOS2")
	)
	(via
		(at 42.462196 -349.607632)
		(size 0.508)
		(drill 0.254)
		(layers "F.Cu" "B.Cu")
		(net "PVDDIO_P1_VOS2")
	)
	(segment
		(start 41.840912 -348.986348)
		(end 42.462196 -349.607632)
		(width 0.2286)
		(layer "B.Cu")
		(net "PVDDIO_P1_VOS2")
	)
	(segment
		(start 41.525444 -348.986348)
		(end 41.840912 -348.986348)
		(width 0.2286)
		(layer "B.Cu")
		(net "PVDDIO_P1_VOS2")
	)
	(segment
		(start 51.143408 -348.996254)
		(end 51.143408 -349.28302)
		(width 0.2032)
		(layer "F.Cu")
		(net "PVDDIO_P1_VOS1")
	)
	(segment
		(start 51.143408 -349.28302)
		(end 50.818796 -349.607632)
		(width 0.2032)
		(layer "F.Cu")
		(net "PVDDIO_P1_VOS1")
	)
	(via
		(at 50.818796 -349.607632)
		(size 0.508)
		(drill 0.254)
		(layers "F.Cu" "B.Cu")
		(net "PVDDIO_P1_VOS1")
	)
	(segment
		(start 50.197512 -348.986348)
		(end 50.818796 -349.607632)
		(width 0.2286)
		(layer "B.Cu")
		(net "PVDDIO_P1_VOS1")
	)
	(segment
		(start 49.882044 -348.986348)
		(end 50.197512 -348.986348)
		(width 0.2286)
		(layer "B.Cu")
		(net "PVDDIO_P1_VOS1")
	)
	(segment
		(start 28.410662 -350.333056)
		(end 28.410662 -349.621094)
		(width 0.2286)
		(layer "F.Cu")
		(net "PVDDIO_P1_VCC4")
	)
	(segment
		(start 24.917654 -348.375986)
		(end 24.917654 -348.986348)
		(width 0.4572)
		(layer "F.Cu")
		(net "PVDDIO_P1_VCC4")
	)
	(segment
		(start 25.269952 -348.375986)
		(end 24.917654 -348.375986)
		(width 0.2286)
		(layer "F.Cu")
		(net "PVDDIO_P1_VCC4")
	)
	(segment
		(start 25.54986 -348.096078)
		(end 25.269952 -348.375986)
		(width 0.2286)
		(layer "F.Cu")
		(net "PVDDIO_P1_VCC4")
	)
	(segment
		(start 28.33497 -350.408748)
		(end 28.410662 -350.333056)
		(width 0.2286)
		(layer "F.Cu")
		(net "PVDDIO_P1_VCC4")
	)
	(segment
		(start 26.200608 -348.096078)
		(end 25.54986 -348.096078)
		(width 0.2286)
		(layer "F.Cu")
		(net "PVDDIO_P1_VCC4")
	)
	(via
		(at 26.745184 -349.490284)
		(size 0.6604)
		(drill 0.3302)
		(layers "F.Cu" "B.Cu")
		(net "PVDDIO_P1_VCC4")
	)
	(via
		(at 28.33497 -350.408748)
		(size 0.508)
		(drill 0.254)
		(layers "F.Cu" "B.Cu")
		(net "PVDDIO_P1_VCC4")
	)
	(via
		(at 24.917654 -348.375986)
		(size 0.508)
		(drill 0.254)
		(layers "F.Cu" "B.Cu")
		(net "PVDDIO_P1_VCC4")
	)
	(segment
		(start 26.289762 -349.034862)
		(end 26.289762 -348.180406)
		(width 0.381)
		(layer "B.Cu")
		(net "PVDDIO_P1_VCC4")
	)
	(segment
		(start 25.779984 -348.180406)
		(end 26.289762 -348.180406)
		(width 0.381)
		(layer "B.Cu")
		(net "PVDDIO_P1_VCC4")
	)
	(segment
		(start 24.917654 -348.375986)
		(end 25.584404 -348.375986)
		(width 0.381)
		(layer "B.Cu")
		(net "PVDDIO_P1_VCC4")
	)
	(segment
		(start 26.745184 -349.490284)
		(end 26.289762 -349.034862)
		(width 0.381)
		(layer "B.Cu")
		(net "PVDDIO_P1_VCC4")
	)
	(segment
		(start 25.584404 -348.375986)
		(end 25.779984 -348.180406)
		(width 0.381)
		(layer "B.Cu")
		(net "PVDDIO_P1_VCC4")
	)
	(segment
		(start 27.05862 -349.909384)
		(end 26.745184 -349.595948)
		(width 0.508)
		(layer "B.Cu")
		(net "PVDDIO_P1_VCC4")
	)
	(segment
		(start 27.835606 -349.909384)
		(end 27.05862 -349.909384)
		(width 0.508)
		(layer "B.Cu")
		(net "PVDDIO_P1_VCC4")
	)
	(segment
		(start 28.33497 -350.408748)
		(end 27.835606 -349.909384)
		(width 0.508)
		(layer "B.Cu")
		(net "PVDDIO_P1_VCC4")
	)
	(segment
		(start 26.745184 -349.595948)
		(end 26.745184 -349.490284)
		(width 0.381)
		(layer "B.Cu")
		(net "PVDDIO_P1_VCC4")
	)
	(segment
		(start 33.550352 -348.375986)
		(end 33.198054 -348.375986)
		(width 0.2286)
		(layer "F.Cu")
		(net "PVDDIO_P1_VCC3")
	)
	(segment
		(start 36.61537 -350.408748)
		(end 36.691062 -350.333056)
		(width 0.2286)
		(layer "F.Cu")
		(net "PVDDIO_P1_VCC3")
	)
	(segment
		(start 33.198054 -348.375986)
		(end 33.198054 -348.986348)
		(width 0.4572)
		(layer "F.Cu")
		(net "PVDDIO_P1_VCC3")
	)
	(segment
		(start 34.481008 -348.096078)
		(end 33.83026 -348.096078)
		(width 0.2286)
		(layer "F.Cu")
		(net "PVDDIO_P1_VCC3")
	)
	(segment
		(start 33.83026 -348.096078)
		(end 33.550352 -348.375986)
		(width 0.2286)
		(layer "F.Cu")
		(net "PVDDIO_P1_VCC3")
	)
	(segment
		(start 36.691062 -350.333056)
		(end 36.691062 -349.621094)
		(width 0.2286)
		(layer "F.Cu")
		(net "PVDDIO_P1_VCC3")
	)
	(via
		(at 35.025584 -349.490284)
		(size 0.6604)
		(drill 0.3302)
		(layers "F.Cu" "B.Cu")
		(net "PVDDIO_P1_VCC3")
	)
	(via
		(at 33.198054 -348.375986)
		(size 0.508)
		(drill 0.254)
		(layers "F.Cu" "B.Cu")
		(net "PVDDIO_P1_VCC3")
	)
	(via
		(at 36.61537 -350.408748)
		(size 0.508)
		(drill 0.254)
		(layers "F.Cu" "B.Cu")
		(net "PVDDIO_P1_VCC3")
	)
	(segment
		(start 35.025584 -349.595948)
		(end 35.025584 -349.490284)
		(width 0.381)
		(layer "B.Cu")
		(net "PVDDIO_P1_VCC3")
	)
	(segment
		(start 33.864804 -348.375986)
		(end 34.060384 -348.180406)
		(width 0.381)
		(layer "B.Cu")
		(net "PVDDIO_P1_VCC3")
	)
	(segment
		(start 35.025584 -349.490284)
		(end 34.570162 -349.034862)
		(width 0.381)
		(layer "B.Cu")
		(net "PVDDIO_P1_VCC3")
	)
	(segment
		(start 33.198054 -348.375986)
		(end 33.864804 -348.375986)
		(width 0.381)
		(layer "B.Cu")
		(net "PVDDIO_P1_VCC3")
	)
	(segment
		(start 34.060384 -348.180406)
		(end 34.570162 -348.180406)
		(width 0.381)
		(layer "B.Cu")
		(net "PVDDIO_P1_VCC3")
	)
	(segment
		(start 36.61537 -350.408748)
		(end 36.116006 -349.909384)
		(width 0.508)
		(layer "B.Cu")
		(net "PVDDIO_P1_VCC3")
	)
	(segment
		(start 35.33902 -349.909384)
		(end 35.025584 -349.595948)
		(width 0.508)
		(layer "B.Cu")
		(net "PVDDIO_P1_VCC3")
	)
	(segment
		(start 36.116006 -349.909384)
		(end 35.33902 -349.909384)
		(width 0.508)
		(layer "B.Cu")
		(net "PVDDIO_P1_VCC3")
	)
	(segment
		(start 34.570162 -349.034862)
		(end 34.570162 -348.180406)
		(width 0.381)
		(layer "B.Cu")
		(net "PVDDIO_P1_VCC3")
	)
	(segment
		(start 41.503854 -348.986348)
		(end 41.503854 -348.375986)
		(width 0.4572)
		(layer "F.Cu")
		(net "PVDDIO_P1_VCC2")
	)
	(segment
		(start 41.856152 -348.375986)
		(end 42.13606 -348.096078)
		(width 0.2286)
		(layer "F.Cu")
		(net "PVDDIO_P1_VCC2")
	)
	(segment
		(start 41.503854 -348.375986)
		(end 41.856152 -348.375986)
		(width 0.2286)
		(layer "F.Cu")
		(net "PVDDIO_P1_VCC2")
	)
	(segment
		(start 44.92117 -350.408748)
		(end 44.996862 -350.333056)
		(width 0.2286)
		(layer "F.Cu")
		(net "PVDDIO_P1_VCC2")
	)
	(segment
		(start 42.13606 -348.096078)
		(end 42.786808 -348.096078)
		(width 0.2286)
		(layer "F.Cu")
		(net "PVDDIO_P1_VCC2")
	)
	(segment
		(start 44.996862 -350.333056)
		(end 44.996862 -349.621094)
		(width 0.2286)
		(layer "F.Cu")
		(net "PVDDIO_P1_VCC2")
	)
	(via
		(at 43.331384 -349.490284)
		(size 0.6604)
		(drill 0.3302)
		(layers "F.Cu" "B.Cu")
		(net "PVDDIO_P1_VCC2")
	)
	(via
		(at 41.503854 -348.375986)
		(size 0.508)
		(drill 0.254)
		(layers "F.Cu" "B.Cu")
		(net "PVDDIO_P1_VCC2")
	)
	(via
		(at 44.92117 -350.408748)
		(size 0.508)
		(drill 0.254)
		(layers "F.Cu" "B.Cu")
		(net "PVDDIO_P1_VCC2")
	)
	(segment
		(start 44.421806 -349.909384)
		(end 43.64482 -349.909384)
		(width 0.508)
		(layer "B.Cu")
		(net "PVDDIO_P1_VCC2")
	)
	(segment
		(start 43.331384 -349.595948)
		(end 43.331384 -349.490284)
		(width 0.381)
		(layer "B.Cu")
		(net "PVDDIO_P1_VCC2")
	)
	(segment
		(start 42.170604 -348.375986)
		(end 42.366184 -348.180406)
		(width 0.381)
		(layer "B.Cu")
		(net "PVDDIO_P1_VCC2")
	)
	(segment
		(start 43.64482 -349.909384)
		(end 43.331384 -349.595948)
		(width 0.508)
		(layer "B.Cu")
		(net "PVDDIO_P1_VCC2")
	)
	(segment
		(start 43.331384 -349.490284)
		(end 42.875962 -349.034862)
		(width 0.381)
		(layer "B.Cu")
		(net "PVDDIO_P1_VCC2")
	)
	(segment
		(start 42.366184 -348.180406)
		(end 42.875962 -348.180406)
		(width 0.381)
		(layer "B.Cu")
		(net "PVDDIO_P1_VCC2")
	)
	(segment
		(start 44.92117 -350.408748)
		(end 44.421806 -349.909384)
		(width 0.508)
		(layer "B.Cu")
		(net "PVDDIO_P1_VCC2")
	)
	(segment
		(start 42.875962 -349.034862)
		(end 42.875962 -348.180406)
		(width 0.381)
		(layer "B.Cu")
		(net "PVDDIO_P1_VCC2")
	)
	(segment
		(start 41.503854 -348.375986)
		(end 42.170604 -348.375986)
		(width 0.381)
		(layer "B.Cu")
		(net "PVDDIO_P1_VCC2")
	)
	(segment
		(start 50.49266 -348.096078)
		(end 51.143408 -348.096078)
		(width 0.2286)
		(layer "F.Cu")
		(net "PVDDIO_P1_VCC1")
	)
	(segment
		(start 49.860454 -348.375986)
		(end 50.212752 -348.375986)
		(width 0.2286)
		(layer "F.Cu")
		(net "PVDDIO_P1_VCC1")
	)
	(segment
		(start 53.353462 -350.333056)
		(end 53.353462 -349.621094)
		(width 0.2286)
		(layer "F.Cu")
		(net "PVDDIO_P1_VCC1")
	)
	(segment
		(start 53.27777 -350.408748)
		(end 53.353462 -350.333056)
		(width 0.2286)
		(layer "F.Cu")
		(net "PVDDIO_P1_VCC1")
	)
	(segment
		(start 50.212752 -348.375986)
		(end 50.49266 -348.096078)
		(width 0.2286)
		(layer "F.Cu")
		(net "PVDDIO_P1_VCC1")
	)
	(segment
		(start 49.860454 -348.986348)
		(end 49.860454 -348.375986)
		(width 0.4572)
		(layer "F.Cu")
		(net "PVDDIO_P1_VCC1")
	)
	(via
		(at 51.687984 -349.490284)
		(size 0.6604)
		(drill 0.3302)
		(layers "F.Cu" "B.Cu")
		(net "PVDDIO_P1_VCC1")
	)
	(via
		(at 49.860454 -348.375986)
		(size 0.508)
		(drill 0.254)
		(layers "F.Cu" "B.Cu")
		(net "PVDDIO_P1_VCC1")
	)
	(via
		(at 53.27777 -350.408748)
		(size 0.508)
		(drill 0.254)
		(layers "F.Cu" "B.Cu")
		(net "PVDDIO_P1_VCC1")
	)
	(segment
		(start 50.527204 -348.375986)
		(end 50.722784 -348.180406)
		(width 0.381)
		(layer "B.Cu")
		(net "PVDDIO_P1_VCC1")
	)
	(segment
		(start 51.687984 -349.490284)
		(end 51.687984 -349.595948)
		(width 0.381)
		(layer "B.Cu")
		(net "PVDDIO_P1_VCC1")
	)
	(segment
		(start 51.232562 -349.034862)
		(end 51.687984 -349.490284)
		(width 0.381)
		(layer "B.Cu")
		(net "PVDDIO_P1_VCC1")
	)
	(segment
		(start 52.778406 -349.909384)
		(end 53.27777 -350.408748)
		(width 0.508)
		(layer "B.Cu")
		(net "PVDDIO_P1_VCC1")
	)
	(segment
		(start 51.687984 -349.595948)
		(end 52.00142 -349.909384)
		(width 0.508)
		(layer "B.Cu")
		(net "PVDDIO_P1_VCC1")
	)
	(segment
		(start 49.860454 -348.375986)
		(end 50.527204 -348.375986)
		(width 0.381)
		(layer "B.Cu")
		(net "PVDDIO_P1_VCC1")
	)
	(segment
		(start 50.722784 -348.180406)
		(end 51.232562 -348.180406)
		(width 0.381)
		(layer "B.Cu")
		(net "PVDDIO_P1_VCC1")
	)
	(segment
		(start 52.00142 -349.909384)
		(end 52.778406 -349.909384)
		(width 0.508)
		(layer "B.Cu")
		(net "PVDDIO_P1_VCC1")
	)
	(segment
		(start 51.232562 -348.180406)
		(end 51.232562 -349.034862)
		(width 0.381)
		(layer "B.Cu")
		(net "PVDDIO_P1_VCC1")
	)
	(segment
		(start 36.240974 -349.968058)
		(end 36.240974 -349.621094)
		(width 0.2286)
		(layer "F.Cu")
		(net "PVDDIO_P1_TEMP1")
	)
	(segment
		(start 36.81095 -363.093)
		(end 35.941 -363.093)
		(width 0.254)
		(layer "F.Cu")
		(net "PVDDIO_P1_TEMP1")
	)
	(segment
		(start 27.841956 -350.181164)
		(end 27.960574 -349.894652)
		(width 0.2286)
		(layer "F.Cu")
		(net "PVDDIO_P1_TEMP1")
	)
	(segment
		(start 35.941 -363.093)
		(end 34.725102 -364.308898)
		(width 0.1778)
		(layer "F.Cu")
		(net "PVDDIO_P1_TEMP1")
	)
	(segment
		(start 36.174172 -350.129348)
		(end 36.240974 -349.968058)
		(width 0.2286)
		(layer "F.Cu")
		(net "PVDDIO_P1_TEMP1")
	)
	(segment
		(start 35.919918 -350.383602)
		(end 36.174172 -350.129348)
		(width 0.2286)
		(layer "F.Cu")
		(net "PVDDIO_P1_TEMP1")
	)
	(segment
		(start 52.797202 -350.168718)
		(end 52.903374 -349.912178)
		(width 0.2286)
		(layer "F.Cu")
		(net "PVDDIO_P1_TEMP1")
	)
	(segment
		(start 34.725102 -364.308898)
		(end 33.355026 -364.308898)
		(width 0.1778)
		(layer "F.Cu")
		(net "PVDDIO_P1_TEMP1")
	)
	(segment
		(start 44.225718 -350.383602)
		(end 44.46397 -350.14535)
		(width 0.2286)
		(layer "F.Cu")
		(net "PVDDIO_P1_TEMP1")
	)
	(segment
		(start 27.639518 -350.383602)
		(end 27.841956 -350.181164)
		(width 0.2286)
		(layer "F.Cu")
		(net "PVDDIO_P1_TEMP1")
	)
	(segment
		(start 44.546774 -349.945452)
		(end 44.546774 -349.621094)
		(width 0.2286)
		(layer "F.Cu")
		(net "PVDDIO_P1_TEMP1")
	)
	(segment
		(start 35.919918 -350.65462)
		(end 35.919918 -350.383602)
		(width 0.2286)
		(layer "F.Cu")
		(net "PVDDIO_P1_TEMP1")
	)
	(segment
		(start 27.639518 -350.65462)
		(end 27.639518 -350.383602)
		(width 0.2286)
		(layer "F.Cu")
		(net "PVDDIO_P1_TEMP1")
	)
	(segment
		(start 52.582318 -350.65462)
		(end 52.582318 -350.383602)
		(width 0.2286)
		(layer "F.Cu")
		(net "PVDDIO_P1_TEMP1")
	)
	(segment
		(start 27.960574 -349.894652)
		(end 27.960574 -349.621094)
		(width 0.2286)
		(layer "F.Cu")
		(net "PVDDIO_P1_TEMP1")
	)
	(segment
		(start 44.46397 -350.14535)
		(end 44.546774 -349.945452)
		(width 0.2286)
		(layer "F.Cu")
		(net "PVDDIO_P1_TEMP1")
	)
	(segment
		(start 44.225718 -350.65462)
		(end 44.225718 -350.383602)
		(width 0.2286)
		(layer "F.Cu")
		(net "PVDDIO_P1_TEMP1")
	)
	(segment
		(start 52.582318 -350.383602)
		(end 52.797202 -350.168718)
		(width 0.2286)
		(layer "F.Cu")
		(net "PVDDIO_P1_TEMP1")
	)
	(segment
		(start 52.903374 -349.912178)
		(end 52.903374 -349.621094)
		(width 0.2286)
		(layer "F.Cu")
		(net "PVDDIO_P1_TEMP1")
	)
	(via
		(at 35.919918 -350.65462)
		(size 0.508)
		(drill 0.254)
		(layers "F.Cu" "B.Cu")
		(net "PVDDIO_P1_TEMP1")
	)
	(via
		(at 52.582318 -350.65462)
		(size 0.508)
		(drill 0.254)
		(layers "F.Cu" "B.Cu")
		(net "PVDDIO_P1_TEMP1")
	)
	(via
		(at 35.941 -363.093)
		(size 0.508)
		(drill 0.254)
		(layers "F.Cu" "B.Cu")
		(net "PVDDIO_P1_TEMP1")
	)
	(via
		(at 27.639518 -350.65462)
		(size 0.508)
		(drill 0.254)
		(layers "F.Cu" "B.Cu")
		(net "PVDDIO_P1_TEMP1")
	)
	(via
		(at 44.225718 -350.65462)
		(size 0.508)
		(drill 0.254)
		(layers "F.Cu" "B.Cu")
		(net "PVDDIO_P1_TEMP1")
	)
	(segment
		(start 27.639518 -352.28276)
		(end 26.1112 -353.811078)
		(width 0.254)
		(layer "In2.Cu")
		(net "PVDDIO_P1_TEMP1")
	)
	(segment
		(start 52.582318 -350.65462)
		(end 52.582318 -351.986088)
		(width 0.254)
		(layer "In2.Cu")
		(net "PVDDIO_P1_TEMP1")
	)
	(segment
		(start 35.17519 -352.82124)
		(end 35.931094 -352.065336)
		(width 0.254)
		(layer "In2.Cu")
		(net "PVDDIO_P1_TEMP1")
	)
	(segment
		(start 26.1112 -358.723946)
		(end 28.981654 -361.5944)
		(width 0.254)
		(layer "In2.Cu")
		(net "PVDDIO_P1_TEMP1")
	)
	(segment
		(start 26.1112 -353.811078)
		(end 26.1112 -358.723946)
		(width 0.254)
		(layer "In2.Cu")
		(net "PVDDIO_P1_TEMP1")
	)
	(segment
		(start 44.225718 -350.65462)
		(end 44.225718 -352.127312)
		(width 0.254)
		(layer "In2.Cu")
		(net "PVDDIO_P1_TEMP1")
	)
	(segment
		(start 34.4424 -361.5944)
		(end 35.941 -363.093)
		(width 0.254)
		(layer "In2.Cu")
		(net "PVDDIO_P1_TEMP1")
	)
	(segment
		(start 27.639518 -352.28276)
		(end 28.177998 -352.82124)
		(width 0.254)
		(layer "In2.Cu")
		(net "PVDDIO_P1_TEMP1")
	)
	(segment
		(start 36.648898 -352.78314)
		(end 35.931094 -352.065336)
		(width 0.254)
		(layer "In2.Cu")
		(net "PVDDIO_P1_TEMP1")
	)
	(segment
		(start 51.827176 -352.74123)
		(end 44.839636 -352.74123)
		(width 0.254)
		(layer "In2.Cu")
		(net "PVDDIO_P1_TEMP1")
	)
	(segment
		(start 44.839636 -352.74123)
		(end 44.225718 -352.127312)
		(width 0.254)
		(layer "In2.Cu")
		(net "PVDDIO_P1_TEMP1")
	)
	(segment
		(start 28.981654 -361.5944)
		(end 34.4424 -361.5944)
		(width 0.254)
		(layer "In2.Cu")
		(net "PVDDIO_P1_TEMP1")
	)
	(segment
		(start 28.177998 -352.82124)
		(end 35.17519 -352.82124)
		(width 0.254)
		(layer "In2.Cu")
		(net "PVDDIO_P1_TEMP1")
	)
	(segment
		(start 35.931094 -350.665796)
		(end 35.919918 -350.65462)
		(width 0.254)
		(layer "In2.Cu")
		(net "PVDDIO_P1_TEMP1")
	)
	(segment
		(start 52.582318 -351.986088)
		(end 51.827176 -352.74123)
		(width 0.254)
		(layer "In2.Cu")
		(net "PVDDIO_P1_TEMP1")
	)
	(segment
		(start 27.639518 -350.65462)
		(end 27.639518 -352.28276)
		(width 0.254)
		(layer "In2.Cu")
		(net "PVDDIO_P1_TEMP1")
	)
	(segment
		(start 44.225718 -352.127312)
		(end 43.56989 -352.78314)
		(width 0.254)
		(layer "In2.Cu")
		(net "PVDDIO_P1_TEMP1")
	)
	(segment
		(start 43.56989 -352.78314)
		(end 36.648898 -352.78314)
		(width 0.254)
		(layer "In2.Cu")
		(net "PVDDIO_P1_TEMP1")
	)
	(segment
		(start 35.931094 -352.065336)
		(end 35.931094 -350.665796)
		(width 0.254)
		(layer "In2.Cu")
		(net "PVDDIO_P1_TEMP1")
	)
	(segment
		(start 31.479998 -370.627402)
		(end 31.479998 -366.984026)
		(width 0.1524)
		(layer "F.Cu")
		(net "PVDDIO_P1_PWM4")
	)
	(segment
		(start 28.4734 -372.745)
		(end 29.3624 -372.745)
		(width 0.1524)
		(layer "F.Cu")
		(net "PVDDIO_P1_PWM4")
	)
	(segment
		(start 29.3624 -372.745)
		(end 31.479998 -370.627402)
		(width 0.1524)
		(layer "F.Cu")
		(net "PVDDIO_P1_PWM4")
	)
	(segment
		(start 28.86075 -350.72574)
		(end 28.86075 -349.621094)
		(width 0.1778)
		(layer "F.Cu")
		(net "PVDDIO_P1_PWM4")
	)
	(segment
		(start 28.52547 -351.06102)
		(end 28.86075 -350.72574)
		(width 0.1778)
		(layer "F.Cu")
		(net "PVDDIO_P1_PWM4")
	)
	(via
		(at 28.52547 -351.06102)
		(size 0.508)
		(drill 0.254)
		(layers "F.Cu" "B.Cu")
		(net "PVDDIO_P1_PWM4")
	)
	(via
		(at 28.4734 -372.745)
		(size 0.508)
		(drill 0.254)
		(layers "F.Cu" "B.Cu")
		(net "PVDDIO_P1_PWM4")
	)
	(segment
		(start 25.180798 -366.350804)
		(end 25.180798 -365.410242)
		(width 0.1524)
		(layer "In4.Cu")
		(net "PVDDIO_P1_PWM4")
	)
	(segment
		(start 28.199842 -351.06102)
		(end 28.52547 -351.06102)
		(width 0.1524)
		(layer "In4.Cu")
		(net "PVDDIO_P1_PWM4")
	)
	(segment
		(start 26.500328 -367.670334)
		(end 25.180798 -366.350804)
		(width 0.1524)
		(layer "In4.Cu")
		(net "PVDDIO_P1_PWM4")
	)
	(segment
		(start 25.180798 -365.410242)
		(end 24.2316 -364.461044)
		(width 0.1524)
		(layer "In4.Cu")
		(net "PVDDIO_P1_PWM4")
	)
	(segment
		(start 26.500328 -370.771928)
		(end 26.500328 -367.670334)
		(width 0.1524)
		(layer "In4.Cu")
		(net "PVDDIO_P1_PWM4")
	)
	(segment
		(start 24.2316 -364.461044)
		(end 24.2316 -355.029262)
		(width 0.1524)
		(layer "In4.Cu")
		(net "PVDDIO_P1_PWM4")
	)
	(segment
		(start 24.2316 -355.029262)
		(end 28.199842 -351.06102)
		(width 0.1524)
		(layer "In4.Cu")
		(net "PVDDIO_P1_PWM4")
	)
	(segment
		(start 28.4734 -372.745)
		(end 26.500328 -370.771928)
		(width 0.1524)
		(layer "In4.Cu")
		(net "PVDDIO_P1_PWM4")
	)
	(segment
		(start 31.880048 -370.862352)
		(end 31.880048 -366.984026)
		(width 0.1524)
		(layer "F.Cu")
		(net "PVDDIO_P1_PWM3")
	)
	(segment
		(start 30.861 -371.8814)
		(end 31.880048 -370.862352)
		(width 0.1524)
		(layer "F.Cu")
		(net "PVDDIO_P1_PWM3")
	)
	(segment
		(start 30.861 -372.7196)
		(end 30.861 -371.8814)
		(width 0.1524)
		(layer "F.Cu")
		(net "PVDDIO_P1_PWM3")
	)
	(segment
		(start 36.80587 -351.06102)
		(end 37.14115 -350.72574)
		(width 0.1778)
		(layer "F.Cu")
		(net "PVDDIO_P1_PWM3")
	)
	(segment
		(start 37.14115 -350.72574)
		(end 37.14115 -349.621094)
		(width 0.1778)
		(layer "F.Cu")
		(net "PVDDIO_P1_PWM3")
	)
	(via
		(at 36.80587 -351.06102)
		(size 0.508)
		(drill 0.254)
		(layers "F.Cu" "B.Cu")
		(net "PVDDIO_P1_PWM3")
	)
	(via
		(at 30.861 -372.7196)
		(size 0.762)
		(drill 0.254)
		(layers "F.Cu" "B.Cu")
		(net "PVDDIO_P1_PWM3")
	)
	(segment
		(start 26.530554 -354.443792)
		(end 26.530554 -365.294164)
		(width 0.1524)
		(layer "In4.Cu")
		(net "PVDDIO_P1_PWM3")
	)
	(segment
		(start 26.908252 -365.671862)
		(end 26.908252 -370.163852)
		(width 0.1524)
		(layer "In4.Cu")
		(net "PVDDIO_P1_PWM3")
	)
	(segment
		(start 28.147772 -352.826574)
		(end 26.530554 -354.443792)
		(width 0.1524)
		(layer "In4.Cu")
		(net "PVDDIO_P1_PWM3")
	)
	(segment
		(start 29.464 -372.7196)
		(end 30.861 -372.7196)
		(width 0.1524)
		(layer "In4.Cu")
		(net "PVDDIO_P1_PWM3")
	)
	(segment
		(start 36.404042 -351.06102)
		(end 34.638488 -352.826574)
		(width 0.1524)
		(layer "In4.Cu")
		(net "PVDDIO_P1_PWM3")
	)
	(segment
		(start 36.80587 -351.06102)
		(end 36.404042 -351.06102)
		(width 0.1524)
		(layer "In4.Cu")
		(net "PVDDIO_P1_PWM3")
	)
	(segment
		(start 26.530554 -365.294164)
		(end 26.908252 -365.671862)
		(width 0.1524)
		(layer "In4.Cu")
		(net "PVDDIO_P1_PWM3")
	)
	(segment
		(start 34.638488 -352.826574)
		(end 28.147772 -352.826574)
		(width 0.1524)
		(layer "In4.Cu")
		(net "PVDDIO_P1_PWM3")
	)
	(segment
		(start 26.908252 -370.163852)
		(end 29.464 -372.7196)
		(width 0.1524)
		(layer "In4.Cu")
		(net "PVDDIO_P1_PWM3")
	)
	(segment
		(start 45.44695 -350.72574)
		(end 45.11167 -351.06102)
		(width 0.1778)
		(layer "F.Cu")
		(net "PVDDIO_P1_PWM2")
	)
	(segment
		(start 32.280098 -370.970302)
		(end 32.280098 -366.984026)
		(width 0.1524)
		(layer "F.Cu")
		(net "PVDDIO_P1_PWM2")
	)
	(segment
		(start 31.6484 -372.1354)
		(end 31.6484 -371.602)
		(width 0.1524)
		(layer "F.Cu")
		(net "PVDDIO_P1_PWM2")
	)
	(segment
		(start 31.6484 -371.602)
		(end 32.280098 -370.970302)
		(width 0.1524)
		(layer "F.Cu")
		(net "PVDDIO_P1_PWM2")
	)
	(segment
		(start 45.44695 -349.621094)
		(end 45.44695 -350.72574)
		(width 0.1778)
		(layer "F.Cu")
		(net "PVDDIO_P1_PWM2")
	)
	(via
		(at 31.6484 -372.1354)
		(size 0.508)
		(drill 0.254)
		(layers "F.Cu" "B.Cu")
		(net "PVDDIO_P1_PWM2")
	)
	(via
		(at 45.11167 -351.06102)
		(size 0.508)
		(drill 0.254)
		(layers "F.Cu" "B.Cu")
		(net "PVDDIO_P1_PWM2")
	)
	(segment
		(start 27.407616 -360.69778)
		(end 27.407616 -369.901216)
		(width 0.1524)
		(layer "In4.Cu")
		(net "PVDDIO_P1_PWM2")
	)
	(segment
		(start 38.12413 -353.682808)
		(end 32.1818 -353.682808)
		(width 0.1524)
		(layer "In4.Cu")
		(net "PVDDIO_P1_PWM2")
	)
	(segment
		(start 29.6418 -372.1354)
		(end 31.6484 -372.1354)
		(width 0.1524)
		(layer "In4.Cu")
		(net "PVDDIO_P1_PWM2")
	)
	(segment
		(start 29.750004 -356.555294)
		(end 28.800298 -357.505)
		(width 0.1524)
		(layer "In4.Cu")
		(net "PVDDIO_P1_PWM2")
	)
	(segment
		(start 27.407616 -369.901216)
		(end 29.6418 -372.1354)
		(width 0.1524)
		(layer "In4.Cu")
		(net "PVDDIO_P1_PWM2")
	)
	(segment
		(start 32.1818 -353.682808)
		(end 29.750004 -356.114604)
		(width 0.1524)
		(layer "In4.Cu")
		(net "PVDDIO_P1_PWM2")
	)
	(segment
		(start 28.800298 -359.305098)
		(end 27.407616 -360.69778)
		(width 0.1524)
		(layer "In4.Cu")
		(net "PVDDIO_P1_PWM2")
	)
	(segment
		(start 44.482766 -351.06102)
		(end 42.725848 -352.817938)
		(width 0.1524)
		(layer "In4.Cu")
		(net "PVDDIO_P1_PWM2")
	)
	(segment
		(start 29.750004 -356.114604)
		(end 29.750004 -356.555294)
		(width 0.1524)
		(layer "In4.Cu")
		(net "PVDDIO_P1_PWM2")
	)
	(segment
		(start 28.800298 -357.505)
		(end 28.800298 -359.305098)
		(width 0.1524)
		(layer "In4.Cu")
		(net "PVDDIO_P1_PWM2")
	)
	(segment
		(start 42.725848 -352.817938)
		(end 38.989 -352.817938)
		(width 0.1524)
		(layer "In4.Cu")
		(net "PVDDIO_P1_PWM2")
	)
	(segment
		(start 38.989 -352.817938)
		(end 38.12413 -353.682808)
		(width 0.1524)
		(layer "In4.Cu")
		(net "PVDDIO_P1_PWM2")
	)
	(segment
		(start 45.11167 -351.06102)
		(end 44.482766 -351.06102)
		(width 0.1524)
		(layer "In4.Cu")
		(net "PVDDIO_P1_PWM2")
	)
	(segment
		(start 53.80355 -349.621094)
		(end 53.80355 -350.72574)
		(width 0.1778)
		(layer "F.Cu")
		(net "PVDDIO_P1_PWM1")
	)
	(segment
		(start 32.679894 -371.856)
		(end 32.679894 -366.984026)
		(width 0.1524)
		(layer "F.Cu")
		(net "PVDDIO_P1_PWM1")
	)
	(segment
		(start 53.80355 -350.72574)
		(end 53.46827 -351.06102)
		(width 0.1778)
		(layer "F.Cu")
		(net "PVDDIO_P1_PWM1")
	)
	(via
		(at 32.679894 -371.856)
		(size 0.508)
		(drill 0.254)
		(layers "F.Cu" "B.Cu")
		(net "PVDDIO_P1_PWM1")
	)
	(via
		(at 53.46827 -351.06102)
		(size 0.508)
		(drill 0.254)
		(layers "F.Cu" "B.Cu")
		(net "PVDDIO_P1_PWM1")
	)
	(segment
		(start 30.965648 -358.690672)
		(end 32.584644 -357.071676)
		(width 0.1524)
		(layer "In4.Cu")
		(net "PVDDIO_P1_PWM1")
	)
	(segment
		(start 28.194 -361.4928)
		(end 28.201366 -361.4928)
		(width 0.1524)
		(layer "In4.Cu")
		(net "PVDDIO_P1_PWM1")
	)
	(segment
		(start 42.893234 -353.727766)
		(end 43.854624 -352.766376)
		(width 0.1524)
		(layer "In4.Cu")
		(net "PVDDIO_P1_PWM1")
	)
	(segment
		(start 29.961078 -360.652568)
		(end 30.965648 -359.647998)
		(width 0.1524)
		(layer "In4.Cu")
		(net "PVDDIO_P1_PWM1")
	)
	(segment
		(start 27.9146 -361.7722)
		(end 28.194 -361.4928)
		(width 0.1524)
		(layer "In4.Cu")
		(net "PVDDIO_P1_PWM1")
	)
	(segment
		(start 32.938212 -357.071676)
		(end 33.714182 -356.295706)
		(width 0.1524)
		(layer "In4.Cu")
		(net "PVDDIO_P1_PWM1")
	)
	(segment
		(start 34.30778 -354.639626)
		(end 38.453822 -354.639626)
		(width 0.1524)
		(layer "In4.Cu")
		(net "PVDDIO_P1_PWM1")
	)
	(segment
		(start 43.854624 -352.766376)
		(end 51.656234 -352.766376)
		(width 0.1524)
		(layer "In4.Cu")
		(net "PVDDIO_P1_PWM1")
	)
	(segment
		(start 29.041598 -360.652568)
		(end 29.961078 -360.652568)
		(width 0.1524)
		(layer "In4.Cu")
		(net "PVDDIO_P1_PWM1")
	)
	(segment
		(start 51.656234 -352.766376)
		(end 53.36159 -351.06102)
		(width 0.1524)
		(layer "In4.Cu")
		(net "PVDDIO_P1_PWM1")
	)
	(segment
		(start 28.201366 -361.4928)
		(end 29.041598 -360.652568)
		(width 0.1524)
		(layer "In4.Cu")
		(net "PVDDIO_P1_PWM1")
	)
	(segment
		(start 27.9146 -369.6462)
		(end 27.9146 -361.7722)
		(width 0.1524)
		(layer "In4.Cu")
		(net "PVDDIO_P1_PWM1")
	)
	(segment
		(start 29.8196 -371.5512)
		(end 27.9146 -369.6462)
		(width 0.1524)
		(layer "In4.Cu")
		(net "PVDDIO_P1_PWM1")
	)
	(segment
		(start 32.679894 -371.856)
		(end 32.375094 -371.5512)
		(width 0.1524)
		(layer "In4.Cu")
		(net "PVDDIO_P1_PWM1")
	)
	(segment
		(start 33.714182 -355.233224)
		(end 34.30778 -354.639626)
		(width 0.1524)
		(layer "In4.Cu")
		(net "PVDDIO_P1_PWM1")
	)
	(segment
		(start 39.365682 -353.727766)
		(end 42.893234 -353.727766)
		(width 0.1524)
		(layer "In4.Cu")
		(net "PVDDIO_P1_PWM1")
	)
	(segment
		(start 32.375094 -371.5512)
		(end 29.8196 -371.5512)
		(width 0.1524)
		(layer "In4.Cu")
		(net "PVDDIO_P1_PWM1")
	)
	(segment
		(start 30.965648 -359.647998)
		(end 30.965648 -358.690672)
		(width 0.1524)
		(layer "In4.Cu")
		(net "PVDDIO_P1_PWM1")
	)
	(segment
		(start 38.453822 -354.639626)
		(end 39.365682 -353.727766)
		(width 0.1524)
		(layer "In4.Cu")
		(net "PVDDIO_P1_PWM1")
	)
	(segment
		(start 33.714182 -356.295706)
		(end 33.714182 -355.233224)
		(width 0.1524)
		(layer "In4.Cu")
		(net "PVDDIO_P1_PWM1")
	)
	(segment
		(start 32.584644 -357.071676)
		(end 32.938212 -357.071676)
		(width 0.1524)
		(layer "In4.Cu")
		(net "PVDDIO_P1_PWM1")
	)
	(segment
		(start 53.36159 -351.06102)
		(end 53.46827 -351.06102)
		(width 0.1524)
		(layer "In4.Cu")
		(net "PVDDIO_P1_PWM1")
	)
	(segment
		(start 26.89606 -351.932748)
		(end 27.138122 -351.690686)
		(width 0.127)
		(layer "F.Cu")
		(net "PVDDIO_P1_LSET4")
	)
	(segment
		(start 27.138122 -350.399604)
		(end 27.51074 -350.026986)
		(width 0.127)
		(layer "F.Cu")
		(net "PVDDIO_P1_LSET4")
	)
	(segment
		(start 27.51074 -350.026986)
		(end 27.51074 -349.621094)
		(width 0.127)
		(layer "F.Cu")
		(net "PVDDIO_P1_LSET4")
	)
	(segment
		(start 27.138122 -351.690686)
		(end 27.138122 -350.808798)
		(width 0.127)
		(layer "F.Cu")
		(net "PVDDIO_P1_LSET4")
	)
	(segment
		(start 27.138122 -350.808798)
		(end 27.138122 -350.399604)
		(width 0.127)
		(layer "F.Cu")
		(net "PVDDIO_P1_LSET4")
	)
	(via
		(at 27.138122 -350.808798)
		(size 0.4064)
		(drill 0.2032)
		(layers "F.Cu" "B.Cu")
		(net "PVDDIO_P1_LSET4")
	)
	(segment
		(start 35.79114 -349.621094)
		(end 35.79114 -350.026986)
		(width 0.127)
		(layer "F.Cu")
		(net "PVDDIO_P1_LSET3")
	)
	(segment
		(start 35.418522 -350.399604)
		(end 35.418522 -350.808798)
		(width 0.127)
		(layer "F.Cu")
		(net "PVDDIO_P1_LSET3")
	)
	(segment
		(start 35.418522 -350.808798)
		(end 35.418522 -351.690686)
		(width 0.127)
		(layer "F.Cu")
		(net "PVDDIO_P1_LSET3")
	)
	(segment
		(start 35.79114 -350.026986)
		(end 35.418522 -350.399604)
		(width 0.127)
		(layer "F.Cu")
		(net "PVDDIO_P1_LSET3")
	)
	(segment
		(start 35.418522 -351.690686)
		(end 35.17646 -351.932748)
		(width 0.127)
		(layer "F.Cu")
		(net "PVDDIO_P1_LSET3")
	)
	(via
		(at 35.418522 -350.808798)
		(size 0.4064)
		(drill 0.2032)
		(layers "F.Cu" "B.Cu")
		(net "PVDDIO_P1_LSET3")
	)
	(segment
		(start 43.724322 -350.399604)
		(end 44.09694 -350.026986)
		(width 0.127)
		(layer "F.Cu")
		(net "PVDDIO_P1_LSET2")
	)
	(segment
		(start 43.724322 -351.690686)
		(end 43.724322 -350.837246)
		(width 0.127)
		(layer "F.Cu")
		(net "PVDDIO_P1_LSET2")
	)
	(segment
		(start 44.09694 -350.026986)
		(end 44.09694 -349.621094)
		(width 0.127)
		(layer "F.Cu")
		(net "PVDDIO_P1_LSET2")
	)
	(segment
		(start 43.724322 -350.837246)
		(end 43.724322 -350.399604)
		(width 0.127)
		(layer "F.Cu")
		(net "PVDDIO_P1_LSET2")
	)
	(segment
		(start 43.48226 -351.932748)
		(end 43.724322 -351.690686)
		(width 0.127)
		(layer "F.Cu")
		(net "PVDDIO_P1_LSET2")
	)
	(via
		(at 43.724322 -350.837246)
		(size 0.4064)
		(drill 0.2032)
		(layers "F.Cu" "B.Cu")
		(net "PVDDIO_P1_LSET2")
	)
	(segment
		(start 52.080922 -351.690686)
		(end 51.83886 -351.932748)
		(width 0.127)
		(layer "F.Cu")
		(net "PVDDIO_P1_LSET1")
	)
	(segment
		(start 52.080922 -350.810576)
		(end 52.080922 -351.690686)
		(width 0.127)
		(layer "F.Cu")
		(net "PVDDIO_P1_LSET1")
	)
	(segment
		(start 52.45354 -350.026986)
		(end 52.080922 -350.399604)
		(width 0.127)
		(layer "F.Cu")
		(net "PVDDIO_P1_LSET1")
	)
	(segment
		(start 52.080922 -350.399604)
		(end 52.080922 -350.810576)
		(width 0.127)
		(layer "F.Cu")
		(net "PVDDIO_P1_LSET1")
	)
	(segment
		(start 52.45354 -349.621094)
		(end 52.45354 -350.026986)
		(width 0.127)
		(layer "F.Cu")
		(net "PVDDIO_P1_LSET1")
	)
	(via
		(at 52.080922 -350.810576)
		(size 0.4064)
		(drill 0.2032)
		(layers "F.Cu" "B.Cu")
		(net "PVDDIO_P1_LSET1")
	)
	(segment
		(start 31.6738 -355.854)
		(end 31.6738 -357.495602)
		(width 0.1778)
		(layer "F.Cu")
		(net "PVDDIO_P1_IMON4")
	)
	(segment
		(start 32.280098 -360.657902)
		(end 32.280098 -361.233974)
		(width 0.1778)
		(layer "F.Cu")
		(net "PVDDIO_P1_IMON4")
	)
	(segment
		(start 32.893 -360.045)
		(end 32.280098 -360.657902)
		(width 0.1778)
		(layer "F.Cu")
		(net "PVDDIO_P1_IMON4")
	)
	(segment
		(start 26.635202 -350.54159)
		(end 26.635202 -350.422464)
		(width 0.2286)
		(layer "F.Cu")
		(net "PVDDIO_P1_IMON4")
	)
	(segment
		(start 26.635202 -350.422464)
		(end 27.060652 -349.997014)
		(width 0.2286)
		(layer "F.Cu")
		(net "PVDDIO_P1_IMON4")
	)
	(segment
		(start 31.6738 -357.495602)
		(end 32.893 -358.714802)
		(width 0.1778)
		(layer "F.Cu")
		(net "PVDDIO_P1_IMON4")
	)
	(segment
		(start 27.060652 -349.997014)
		(end 27.060652 -349.621094)
		(width 0.2286)
		(layer "F.Cu")
		(net "PVDDIO_P1_IMON4")
	)
	(segment
		(start 32.893 -358.714802)
		(end 32.893 -360.045)
		(width 0.1778)
		(layer "F.Cu")
		(net "PVDDIO_P1_IMON4")
	)
	(via
		(at 26.635202 -350.54159)
		(size 0.508)
		(drill 0.254)
		(layers "F.Cu" "B.Cu")
		(net "PVDDIO_P1_IMON4")
	)
	(via
		(at 31.6738 -355.854)
		(size 0.762)
		(drill 0.254)
		(layers "F.Cu" "B.Cu")
		(net "PVDDIO_P1_IMON4")
	)
	(segment
		(start 31.877 -354.335588)
		(end 30.398212 -352.8568)
		(width 0.254)
		(layer "In6.Cu")
		(net "PVDDIO_P1_IMON4")
	)
	(segment
		(start 26.49601 -350.54159)
		(end 26.635202 -350.54159)
		(width 0.254)
		(layer "In6.Cu")
		(net "PVDDIO_P1_IMON4")
	)
	(segment
		(start 31.877 -355.6508)
		(end 31.877 -354.335588)
		(width 0.254)
		(layer "In6.Cu")
		(net "PVDDIO_P1_IMON4")
	)
	(segment
		(start 26.1112 -351.933002)
		(end 26.1112 -350.9264)
		(width 0.254)
		(layer "In6.Cu")
		(net "PVDDIO_P1_IMON4")
	)
	(segment
		(start 26.1112 -350.9264)
		(end 26.49601 -350.54159)
		(width 0.254)
		(layer "In6.Cu")
		(net "PVDDIO_P1_IMON4")
	)
	(segment
		(start 27.034998 -352.8568)
		(end 26.1112 -351.933002)
		(width 0.254)
		(layer "In6.Cu")
		(net "PVDDIO_P1_IMON4")
	)
	(segment
		(start 30.398212 -352.8568)
		(end 27.034998 -352.8568)
		(width 0.254)
		(layer "In6.Cu")
		(net "PVDDIO_P1_IMON4")
	)
	(segment
		(start 31.6738 -355.854)
		(end 31.877 -355.6508)
		(width 0.254)
		(layer "In6.Cu")
		(net "PVDDIO_P1_IMON4")
	)
	(segment
		(start 34.903918 -350.434148)
		(end 34.903918 -350.54159)
		(width 0.2286)
		(layer "F.Cu")
		(net "PVDDIO_P1_IMON3")
	)
	(segment
		(start 32.8168 -355.854)
		(end 33.2994 -356.3366)
		(width 0.1778)
		(layer "F.Cu")
		(net "PVDDIO_P1_IMON3")
	)
	(segment
		(start 33.2994 -360.1466)
		(end 32.679894 -360.766106)
		(width 0.1778)
		(layer "F.Cu")
		(net "PVDDIO_P1_IMON3")
	)
	(segment
		(start 35.341052 -349.997014)
		(end 34.903918 -350.434148)
		(width 0.2286)
		(layer "F.Cu")
		(net "PVDDIO_P1_IMON3")
	)
	(segment
		(start 32.679894 -360.766106)
		(end 32.679894 -361.233974)
		(width 0.1778)
		(layer "F.Cu")
		(net "PVDDIO_P1_IMON3")
	)
	(segment
		(start 33.2994 -356.3366)
		(end 33.2994 -360.1466)
		(width 0.1778)
		(layer "F.Cu")
		(net "PVDDIO_P1_IMON3")
	)
	(segment
		(start 34.903918 -350.54159)
		(end 34.915602 -350.54159)
		(width 0.2286)
		(layer "F.Cu")
		(net "PVDDIO_P1_IMON3")
	)
	(segment
		(start 35.341052 -349.621094)
		(end 35.341052 -349.997014)
		(width 0.2286)
		(layer "F.Cu")
		(net "PVDDIO_P1_IMON3")
	)
	(via
		(at 34.915602 -350.54159)
		(size 0.508)
		(drill 0.254)
		(layers "F.Cu" "B.Cu")
		(net "PVDDIO_P1_IMON3")
	)
	(via
		(at 32.8168 -355.854)
		(size 0.508)
		(drill 0.254)
		(layers "F.Cu" "B.Cu")
		(net "PVDDIO_P1_IMON3")
	)
	(segment
		(start 34.331402 -350.82607)
		(end 34.615882 -350.54159)
		(width 0.254)
		(layer "In6.Cu")
		(net "PVDDIO_P1_IMON3")
	)
	(segment
		(start 34.331402 -354.71481)
		(end 34.331402 -350.82607)
		(width 0.254)
		(layer "In6.Cu")
		(net "PVDDIO_P1_IMON3")
	)
	(segment
		(start 33.192212 -355.854)
		(end 34.331402 -354.71481)
		(width 0.254)
		(layer "In6.Cu")
		(net "PVDDIO_P1_IMON3")
	)
	(segment
		(start 32.8168 -355.854)
		(end 33.192212 -355.854)
		(width 0.254)
		(layer "In6.Cu")
		(net "PVDDIO_P1_IMON3")
	)
	(segment
		(start 34.615882 -350.54159)
		(end 34.915602 -350.54159)
		(width 0.254)
		(layer "In6.Cu")
		(net "PVDDIO_P1_IMON3")
	)
	(segment
		(start 43.646852 -349.621094)
		(end 43.646852 -349.997014)
		(width 0.2286)
		(layer "F.Cu")
		(net "PVDDIO_P1_IMON2")
	)
	(segment
		(start 43.209718 -350.54159)
		(end 43.221402 -350.54159)
		(width 0.2286)
		(layer "F.Cu")
		(net "PVDDIO_P1_IMON2")
	)
	(segment
		(start 43.209718 -350.434148)
		(end 43.209718 -350.54159)
		(width 0.2286)
		(layer "F.Cu")
		(net "PVDDIO_P1_IMON2")
	)
	(segment
		(start 33.695894 -361.909106)
		(end 33.355026 -361.909106)
		(width 0.1778)
		(layer "F.Cu")
		(net "PVDDIO_P1_IMON2")
	)
	(segment
		(start 33.8328 -361.7722)
		(end 33.695894 -361.909106)
		(width 0.1778)
		(layer "F.Cu")
		(net "PVDDIO_P1_IMON2")
	)
	(segment
		(start 33.8328 -358.0638)
		(end 33.8328 -361.7722)
		(width 0.1778)
		(layer "F.Cu")
		(net "PVDDIO_P1_IMON2")
	)
	(segment
		(start 43.646852 -349.997014)
		(end 43.209718 -350.434148)
		(width 0.2286)
		(layer "F.Cu")
		(net "PVDDIO_P1_IMON2")
	)
	(segment
		(start 34.2392 -357.6574)
		(end 33.8328 -358.0638)
		(width 0.1778)
		(layer "F.Cu")
		(net "PVDDIO_P1_IMON2")
	)
	(via
		(at 43.221402 -350.54159)
		(size 0.508)
		(drill 0.254)
		(layers "F.Cu" "B.Cu")
		(net "PVDDIO_P1_IMON2")
	)
	(via
		(at 34.2392 -357.6574)
		(size 0.508)
		(drill 0.254)
		(layers "F.Cu" "B.Cu")
		(net "PVDDIO_P1_IMON2")
	)
	(segment
		(start 34.2392 -357.6574)
		(end 34.436812 -357.6574)
		(width 0.254)
		(layer "In6.Cu")
		(net "PVDDIO_P1_IMON2")
	)
	(segment
		(start 42.665142 -350.821498)
		(end 42.94505 -350.54159)
		(width 0.254)
		(layer "In6.Cu")
		(net "PVDDIO_P1_IMON2")
	)
	(segment
		(start 42.665142 -352.267266)
		(end 42.665142 -350.821498)
		(width 0.254)
		(layer "In6.Cu")
		(net "PVDDIO_P1_IMON2")
	)
	(segment
		(start 34.436812 -357.6574)
		(end 39.296848 -352.797364)
		(width 0.254)
		(layer "In6.Cu")
		(net "PVDDIO_P1_IMON2")
	)
	(segment
		(start 42.94505 -350.54159)
		(end 43.221402 -350.54159)
		(width 0.254)
		(layer "In6.Cu")
		(net "PVDDIO_P1_IMON2")
	)
	(segment
		(start 42.135044 -352.797364)
		(end 42.665142 -352.267266)
		(width 0.254)
		(layer "In6.Cu")
		(net "PVDDIO_P1_IMON2")
	)
	(segment
		(start 39.296848 -352.797364)
		(end 42.135044 -352.797364)
		(width 0.254)
		(layer "In6.Cu")
		(net "PVDDIO_P1_IMON2")
	)
	(segment
		(start 34.798 -358.3432)
		(end 34.2392 -358.902)
		(width 0.1778)
		(layer "F.Cu")
		(net "PVDDIO_P1_IMON1")
	)
	(segment
		(start 52.003452 -349.621094)
		(end 52.003452 -349.997014)
		(width 0.2286)
		(layer "F.Cu")
		(net "PVDDIO_P1_IMON1")
	)
	(segment
		(start 34.2392 -361.8738)
		(end 33.804098 -362.308902)
		(width 0.1778)
		(layer "F.Cu")
		(net "PVDDIO_P1_IMON1")
	)
	(segment
		(start 35.052 -355.7524)
		(end 34.798 -356.0064)
		(width 0.1778)
		(layer "F.Cu")
		(net "PVDDIO_P1_IMON1")
	)
	(segment
		(start 33.804098 -362.308902)
		(end 33.355026 -362.308902)
		(width 0.1778)
		(layer "F.Cu")
		(net "PVDDIO_P1_IMON1")
	)
	(segment
		(start 51.566318 -350.54159)
		(end 51.578002 -350.54159)
		(width 0.2286)
		(layer "F.Cu")
		(net "PVDDIO_P1_IMON1")
	)
	(segment
		(start 34.798 -356.0064)
		(end 34.798 -358.3432)
		(width 0.1778)
		(layer "F.Cu")
		(net "PVDDIO_P1_IMON1")
	)
	(segment
		(start 34.2392 -358.902)
		(end 34.2392 -361.8738)
		(width 0.1778)
		(layer "F.Cu")
		(net "PVDDIO_P1_IMON1")
	)
	(segment
		(start 51.566318 -350.434148)
		(end 51.566318 -350.54159)
		(width 0.2286)
		(layer "F.Cu")
		(net "PVDDIO_P1_IMON1")
	)
	(segment
		(start 52.003452 -349.997014)
		(end 51.566318 -350.434148)
		(width 0.2286)
		(layer "F.Cu")
		(net "PVDDIO_P1_IMON1")
	)
	(via
		(at 35.052 -355.7524)
		(size 0.508)
		(drill 0.254)
		(layers "F.Cu" "B.Cu")
		(net "PVDDIO_P1_IMON1")
	)
	(via
		(at 51.578002 -350.54159)
		(size 0.508)
		(drill 0.254)
		(layers "F.Cu" "B.Cu")
		(net "PVDDIO_P1_IMON1")
	)
	(segment
		(start 51.021742 -352.181414)
		(end 51.021742 -350.821498)
		(width 0.254)
		(layer "In13.Cu")
		(net "PVDDIO_P1_IMON1")
	)
	(segment
		(start 35.052 -355.7524)
		(end 35.2806 -355.7524)
		(width 0.254)
		(layer "In13.Cu")
		(net "PVDDIO_P1_IMON1")
	)
	(segment
		(start 51.021742 -350.821498)
		(end 51.30165 -350.54159)
		(width 0.254)
		(layer "In13.Cu")
		(net "PVDDIO_P1_IMON1")
	)
	(segment
		(start 51.30165 -350.54159)
		(end 51.578002 -350.54159)
		(width 0.254)
		(layer "In13.Cu")
		(net "PVDDIO_P1_IMON1")
	)
	(segment
		(start 50.452274 -352.750882)
		(end 51.021742 -352.181414)
		(width 0.254)
		(layer "In13.Cu")
		(net "PVDDIO_P1_IMON1")
	)
	(segment
		(start 35.2806 -355.7524)
		(end 38.282118 -352.750882)
		(width 0.254)
		(layer "In13.Cu")
		(net "PVDDIO_P1_IMON1")
	)
	(segment
		(start 38.282118 -352.750882)
		(end 50.452274 -352.750882)
		(width 0.254)
		(layer "In13.Cu")
		(net "PVDDIO_P1_IMON1")
	)
	(segment
		(start 19.400012 -358.70642)
		(end 18.384012 -358.70642)
		(width 0.10668)
		(layer "F.Cu")
		(net "PVDDIO_P1_EN_R")
	)
	(segment
		(start 17.135856 -359.21061)
		(end 16.8275 -358.902254)
		(width 0.10668)
		(layer "F.Cu")
		(net "PVDDIO_P1_EN_R")
	)
	(segment
		(start 18.35404 -360.341926)
		(end 18.35404 -359.767378)
		(width 0.10668)
		(layer "F.Cu")
		(net "PVDDIO_P1_EN_R")
	)
	(segment
		(start 16.8275 -358.876346)
		(end 16.8275 -358.751378)
		(width 0.10668)
		(layer "F.Cu")
		(net "PVDDIO_P1_EN_R")
	)
	(segment
		(start 16.8275 -358.751378)
		(end 16.991584 -358.587294)
		(width 0.10668)
		(layer "F.Cu")
		(net "PVDDIO_P1_EN_R")
	)
	(segment
		(start 17.797272 -359.21061)
		(end 17.135856 -359.21061)
		(width 0.10668)
		(layer "F.Cu")
		(net "PVDDIO_P1_EN_R")
	)
	(segment
		(start 18.264886 -358.587294)
		(end 18.384012 -358.70642)
		(width 0.10668)
		(layer "F.Cu")
		(net "PVDDIO_P1_EN_R")
	)
	(segment
		(start 16.8275 -358.902254)
		(end 16.8275 -358.876346)
		(width 0.10668)
		(layer "F.Cu")
		(net "PVDDIO_P1_EN_R")
	)
	(segment
		(start 18.35404 -359.767378)
		(end 17.797272 -359.21061)
		(width 0.10668)
		(layer "F.Cu")
		(net "PVDDIO_P1_EN_R")
	)
	(segment
		(start 16.991584 -358.587294)
		(end 18.264886 -358.587294)
		(width 0.10668)
		(layer "F.Cu")
		(net "PVDDIO_P1_EN_R")
	)
	(segment
		(start 20.416012 -358.70642)
		(end 19.400012 -358.70642)
		(width 0.10668)
		(layer "F.Cu")
		(net "PVDDIO_P1_EN_R")
	)
	(via
		(at 16.8275 -358.876346)
		(size 0.762)
		(drill 0.381)
		(layers "F.Cu" "B.Cu")
		(net "PVDDIO_P1_EN_R")
	)
	(segment
		(start 18.64995 -365.607092)
		(end 18.60804 -365.649002)
		(width 0.10668)
		(layer "F.Cu")
		(net "PVDDIO_P1_EN_G")
	)
	(segment
		(start 17.371568 -363.731302)
		(end 17.371568 -363.982)
		(width 0.10668)
		(layer "F.Cu")
		(net "PVDDIO_P1_EN_G")
	)
	(segment
		(start 17.571212 -364.181644)
		(end 18.595594 -364.181644)
		(width 0.10668)
		(layer "F.Cu")
		(net "PVDDIO_P1_EN_G")
	)
	(segment
		(start 17.371568 -363.982)
		(end 17.571212 -364.181644)
		(width 0.10668)
		(layer "F.Cu")
		(net "PVDDIO_P1_EN_G")
	)
	(segment
		(start 18.036286 -362.542074)
		(end 17.371568 -363.206792)
		(width 0.10668)
		(layer "F.Cu")
		(net "PVDDIO_P1_EN_G")
	)
	(segment
		(start 18.595594 -364.181644)
		(end 18.64995 -364.236)
		(width 0.10668)
		(layer "F.Cu")
		(net "PVDDIO_P1_EN_G")
	)
	(segment
		(start 17.371568 -363.206792)
		(end 17.371568 -363.731302)
		(width 0.10668)
		(layer "F.Cu")
		(net "PVDDIO_P1_EN_G")
	)
	(segment
		(start 18.64995 -364.236)
		(end 18.64995 -365.607092)
		(width 0.10668)
		(layer "F.Cu")
		(net "PVDDIO_P1_EN_G")
	)
	(segment
		(start 19.304 -362.542074)
		(end 18.036286 -362.542074)
		(width 0.10668)
		(layer "F.Cu")
		(net "PVDDIO_P1_EN_G")
	)
	(via
		(at 17.371568 -363.731302)
		(size 0.762)
		(drill 0.381)
		(layers "F.Cu" "B.Cu")
		(net "PVDDIO_P1_EN_G")
	)
	(segment
		(start 197.669658 -112.609376)
		(end 198.342758 -112.609376)
		(width 0.10668)
		(layer "F.Cu")
		(net "PVDDIO_P1_EN")
	)
	(segment
		(start 20.416012 -357.90632)
		(end 20.416012 -357.295704)
		(width 0.10668)
		(layer "F.Cu")
		(net "PVDDIO_P1_EN")
	)
	(via
		(at 113.422938 -121.951242)
		(size 0.508)
		(drill 0.254)
		(layers "F.Cu" "B.Cu")
		(net "PVDDIO_P1_EN")
	)
	(via
		(at 167.898826 -87.587074)
		(size 0.508)
		(drill 0.254)
		(layers "F.Cu" "B.Cu")
		(net "PVDDIO_P1_EN")
	)
	(via
		(at 200.356724 -86.927944)
		(size 0.508)
		(drill 0.254)
		(layers "F.Cu" "B.Cu")
		(net "PVDDIO_P1_EN")
	)
	(via
		(at 198.342758 -112.609376)
		(size 0.508)
		(drill 0.254)
		(layers "F.Cu" "B.Cu")
		(net "PVDDIO_P1_EN")
	)
	(via
		(at 20.416012 -357.295704)
		(size 0.508)
		(drill 0.254)
		(layers "F.Cu" "B.Cu")
		(net "PVDDIO_P1_EN")
	)
	(segment
		(start 202.795378 -93.798136)
		(end 202.795378 -89.732866)
		(width 0.11684)
		(layer "In4.Cu")
		(net "PVDDIO_P1_EN")
	)
	(segment
		(start 199.699118 -111.534956)
		(end 200.888092 -110.345982)
		(width 0.11684)
		(layer "In4.Cu")
		(net "PVDDIO_P1_EN")
	)
	(segment
		(start 201.596498 -96.969072)
		(end 203.3143 -95.25127)
		(width 0.11684)
		(layer "In4.Cu")
		(net "PVDDIO_P1_EN")
	)
	(segment
		(start 202.795378 -89.732866)
		(end 200.356724 -87.294212)
		(width 0.11684)
		(layer "In4.Cu")
		(net "PVDDIO_P1_EN")
	)
	(segment
		(start 198.342758 -112.609376)
		(end 199.417178 -111.534956)
		(width 0.11684)
		(layer "In4.Cu")
		(net "PVDDIO_P1_EN")
	)
	(segment
		(start 200.356724 -87.294212)
		(end 200.356724 -86.927944)
		(width 0.11684)
		(layer "In4.Cu")
		(net "PVDDIO_P1_EN")
	)
	(segment
		(start 200.888092 -109.374686)
		(end 201.596498 -108.66628)
		(width 0.11684)
		(layer "In4.Cu")
		(net "PVDDIO_P1_EN")
	)
	(segment
		(start 200.888092 -110.345982)
		(end 200.888092 -109.374686)
		(width 0.11684)
		(layer "In4.Cu")
		(net "PVDDIO_P1_EN")
	)
	(segment
		(start 199.417178 -111.534956)
		(end 199.699118 -111.534956)
		(width 0.11684)
		(layer "In4.Cu")
		(net "PVDDIO_P1_EN")
	)
	(segment
		(start 203.3143 -95.25127)
		(end 203.3143 -94.317058)
		(width 0.11684)
		(layer "In4.Cu")
		(net "PVDDIO_P1_EN")
	)
	(segment
		(start 201.596498 -108.66628)
		(end 201.596498 -96.969072)
		(width 0.11684)
		(layer "In4.Cu")
		(net "PVDDIO_P1_EN")
	)
	(segment
		(start 203.3143 -94.317058)
		(end 202.795378 -93.798136)
		(width 0.11684)
		(layer "In4.Cu")
		(net "PVDDIO_P1_EN")
	)
	(segment
		(start 149.176232 -116.35232)
		(end 155.55722 -116.35232)
		(width 0.11684)
		(layer "In6.Cu")
		(net "PVDDIO_P1_EN")
	)
	(segment
		(start 159.665162 -97.284794)
		(end 167.73398 -89.215976)
		(width 0.11684)
		(layer "In6.Cu")
		(net "PVDDIO_P1_EN")
	)
	(segment
		(start 160.553654 -108.153454)
		(end 160.553654 -106.812842)
		(width 0.11684)
		(layer "In6.Cu")
		(net "PVDDIO_P1_EN")
	)
	(segment
		(start 147.29206 -118.589552)
		(end 147.29206 -117.342412)
		(width 0.11684)
		(layer "In6.Cu")
		(net "PVDDIO_P1_EN")
	)
	(segment
		(start 167.73398 -87.75192)
		(end 167.898826 -87.587074)
		(width 0.11684)
		(layer "In6.Cu")
		(net "PVDDIO_P1_EN")
	)
	(segment
		(start 159.665162 -112.244378)
		(end 159.665162 -109.041946)
		(width 0.11684)
		(layer "In6.Cu")
		(net "PVDDIO_P1_EN")
	)
	(segment
		(start 147.836382 -116.79809)
		(end 148.730462 -116.79809)
		(width 0.11684)
		(layer "In6.Cu")
		(net "PVDDIO_P1_EN")
	)
	(segment
		(start 147.29206 -117.342412)
		(end 147.836382 -116.79809)
		(width 0.11684)
		(layer "In6.Cu")
		(net "PVDDIO_P1_EN")
	)
	(segment
		(start 160.553654 -106.812842)
		(end 159.665162 -105.92435)
		(width 0.11684)
		(layer "In6.Cu")
		(net "PVDDIO_P1_EN")
	)
	(segment
		(start 113.422938 -121.951242)
		(end 116.218208 -119.155972)
		(width 0.11684)
		(layer "In6.Cu")
		(net "PVDDIO_P1_EN")
	)
	(segment
		(start 148.730462 -116.79809)
		(end 149.176232 -116.35232)
		(width 0.11684)
		(layer "In6.Cu")
		(net "PVDDIO_P1_EN")
	)
	(segment
		(start 116.218208 -119.155972)
		(end 146.72564 -119.155972)
		(width 0.11684)
		(layer "In6.Cu")
		(net "PVDDIO_P1_EN")
	)
	(segment
		(start 159.665162 -109.041946)
		(end 160.553654 -108.153454)
		(width 0.11684)
		(layer "In6.Cu")
		(net "PVDDIO_P1_EN")
	)
	(segment
		(start 159.665162 -105.92435)
		(end 159.665162 -97.284794)
		(width 0.11684)
		(layer "In6.Cu")
		(net "PVDDIO_P1_EN")
	)
	(segment
		(start 155.55722 -116.35232)
		(end 159.665162 -112.244378)
		(width 0.11684)
		(layer "In6.Cu")
		(net "PVDDIO_P1_EN")
	)
	(segment
		(start 146.72564 -119.155972)
		(end 147.29206 -118.589552)
		(width 0.11684)
		(layer "In6.Cu")
		(net "PVDDIO_P1_EN")
	)
	(segment
		(start 167.73398 -89.215976)
		(end 167.73398 -87.75192)
		(width 0.11684)
		(layer "In6.Cu")
		(net "PVDDIO_P1_EN")
	)
	(segment
		(start 14.395704 -167.51935)
		(end 18.636234 -163.27882)
		(width 0.11684)
		(layer "In11.Cu")
		(net "PVDDIO_P1_EN")
	)
	(segment
		(start 87.067136 -132.075174)
		(end 88.359996 -132.075174)
		(width 0.11684)
		(layer "In11.Cu")
		(net "PVDDIO_P1_EN")
	)
	(segment
		(start 95.941642 -124.493528)
		(end 111.4679 -124.493528)
		(width 0.11684)
		(layer "In11.Cu")
		(net "PVDDIO_P1_EN")
	)
	(segment
		(start 51.778662 -131.0259)
		(end 86.017862 -131.0259)
		(width 0.11684)
		(layer "In11.Cu")
		(net "PVDDIO_P1_EN")
	)
	(segment
		(start 26.761948 -138.126724)
		(end 44.677838 -138.126724)
		(width 0.11684)
		(layer "In11.Cu")
		(net "PVDDIO_P1_EN")
	)
	(segment
		(start 44.677838 -138.126724)
		(end 51.778662 -131.0259)
		(width 0.11684)
		(layer "In11.Cu")
		(net "PVDDIO_P1_EN")
	)
	(segment
		(start 7.801864 -167.51935)
		(end 14.395704 -167.51935)
		(width 0.11684)
		(layer "In11.Cu")
		(net "PVDDIO_P1_EN")
	)
	(segment
		(start 6.473952 -168.847262)
		(end 7.801864 -167.51935)
		(width 0.11684)
		(layer "In11.Cu")
		(net "PVDDIO_P1_EN")
	)
	(segment
		(start 20.416012 -357.295704)
		(end 16.20266 -353.082352)
		(width 0.11684)
		(layer "In11.Cu")
		(net "PVDDIO_P1_EN")
	)
	(segment
		(start 18.636234 -163.27882)
		(end 18.636234 -146.252438)
		(width 0.11684)
		(layer "In11.Cu")
		(net "PVDDIO_P1_EN")
	)
	(segment
		(start 18.636234 -146.252438)
		(end 26.761948 -138.126724)
		(width 0.11684)
		(layer "In11.Cu")
		(net "PVDDIO_P1_EN")
	)
	(segment
		(start 6.473952 -335.479898)
		(end 6.473952 -168.847262)
		(width 0.11684)
		(layer "In11.Cu")
		(net "PVDDIO_P1_EN")
	)
	(segment
		(start 86.017862 -131.0259)
		(end 87.067136 -132.075174)
		(width 0.11684)
		(layer "In11.Cu")
		(net "PVDDIO_P1_EN")
	)
	(segment
		(start 88.359996 -132.075174)
		(end 95.941642 -124.493528)
		(width 0.11684)
		(layer "In11.Cu")
		(net "PVDDIO_P1_EN")
	)
	(segment
		(start 16.20266 -353.082352)
		(end 16.20266 -345.208606)
		(width 0.11684)
		(layer "In11.Cu")
		(net "PVDDIO_P1_EN")
	)
	(segment
		(start 113.422938 -122.53849)
		(end 113.422938 -121.951242)
		(width 0.11684)
		(layer "In11.Cu")
		(net "PVDDIO_P1_EN")
	)
	(segment
		(start 16.20266 -345.208606)
		(end 6.473952 -335.479898)
		(width 0.11684)
		(layer "In11.Cu")
		(net "PVDDIO_P1_EN")
	)
	(segment
		(start 111.4679 -124.493528)
		(end 113.422938 -122.53849)
		(width 0.11684)
		(layer "In11.Cu")
		(net "PVDDIO_P1_EN")
	)
	(segment
		(start 175.434498 -88.52281)
		(end 183.445912 -88.52281)
		(width 0.11684)
		(layer "In15.Cu")
		(net "PVDDIO_P1_EN")
	)
	(segment
		(start 187.985146 -88.749632)
		(end 198.535036 -88.749632)
		(width 0.11684)
		(layer "In15.Cu")
		(net "PVDDIO_P1_EN")
	)
	(segment
		(start 169.447972 -86.037928)
		(end 172.949616 -86.037928)
		(width 0.11684)
		(layer "In15.Cu")
		(net "PVDDIO_P1_EN")
	)
	(segment
		(start 183.445912 -88.52281)
		(end 184.41035 -89.487248)
		(width 0.11684)
		(layer "In15.Cu")
		(net "PVDDIO_P1_EN")
	)
	(segment
		(start 198.535036 -88.749632)
		(end 200.356724 -86.927944)
		(width 0.11684)
		(layer "In15.Cu")
		(net "PVDDIO_P1_EN")
	)
	(segment
		(start 187.24753 -89.487248)
		(end 187.985146 -88.749632)
		(width 0.11684)
		(layer "In15.Cu")
		(net "PVDDIO_P1_EN")
	)
	(segment
		(start 172.949616 -86.037928)
		(end 175.434498 -88.52281)
		(width 0.11684)
		(layer "In15.Cu")
		(net "PVDDIO_P1_EN")
	)
	(segment
		(start 184.41035 -89.487248)
		(end 187.24753 -89.487248)
		(width 0.11684)
		(layer "In15.Cu")
		(net "PVDDIO_P1_EN")
	)
	(segment
		(start 167.898826 -87.587074)
		(end 169.447972 -86.037928)
		(width 0.11684)
		(layer "In15.Cu")
		(net "PVDDIO_P1_EN")
	)
	(segment
		(start 87.637874 -270.580358)
		(end 87.171022 -270.846296)
		(width 0.350012)
		(layer "F.Cu")
		(net "PVDDIO_P1")
	)
	(segment
		(start 101.268022 -261.670292)
		(end 100.80117 -261.93623)
		(width 0.350012)
		(layer "F.Cu")
		(net "PVDDIO_P1")
	)
	(segment
		(start 97.97796 -265.720322)
		(end 97.511108 -265.98626)
		(width 0.350012)
		(layer "F.Cu")
		(net "PVDDIO_P1")
	)
	(segment
		(start 80.287876 -244.750336)
		(end 79.821024 -244.484398)
		(width 0.350012)
		(layer "F.Cu")
		(net "PVDDIO_P1")
	)
	(segment
		(start 93.747844 -268.15034)
		(end 93.280992 -268.416278)
		(width 0.350012)
		(layer "F.Cu")
		(net "PVDDIO_P1")
	)
	(segment
		(start 80.757776 -242.320318)
		(end 80.291178 -242.05438)
		(width 0.350012)
		(layer "F.Cu")
		(net "PVDDIO_P1")
	)
	(segment
		(start 93.747844 -263.290304)
		(end 93.280992 -263.556242)
		(width 0.350012)
		(layer "F.Cu")
		(net "PVDDIO_P1")
	)
	(segment
		(start 80.287876 -254.470408)
		(end 79.821024 -254.20447)
		(width 0.350012)
		(layer "F.Cu")
		(net "PVDDIO_P1")
	)
	(segment
		(start 87.167974 -292.450266)
		(end 86.701122 -292.716204)
		(width 0.350012)
		(layer "F.Cu")
		(net "PVDDIO_P1")
	)
	(segment
		(start 97.507806 -264.910316)
		(end 97.040954 -265.176254)
		(width 0.350012)
		(layer "F.Cu")
		(net "PVDDIO_P1")
	)
	(segment
		(start 87.3379 -227.740464)
		(end 86.871048 -227.474526)
		(width 0.350012)
		(layer "F.Cu")
		(net "PVDDIO_P1")
	)
	(segment
		(start 81.058004 -270.580358)
		(end 80.591152 -270.846296)
		(width 0.350012)
		(layer "F.Cu")
		(net "PVDDIO_P1")
	)
	(segment
		(start 80.757776 -247.180354)
		(end 80.291178 -246.914416)
		(width 0.350012)
		(layer "F.Cu")
		(net "PVDDIO_P1")
	)
	(segment
		(start 93.44787 -239.8903)
		(end 92.981018 -239.624362)
		(width 0.350012)
		(layer "F.Cu")
		(net "PVDDIO_P1")
	)
	(segment
		(start 97.507806 -263.290304)
		(end 97.040954 -263.556242)
		(width 0.350012)
		(layer "F.Cu")
		(net "PVDDIO_P1")
	)
	(segment
		(start 80.58785 -273.010376)
		(end 80.120998 -273.276314)
		(width 0.350012)
		(layer "F.Cu")
		(net "PVDDIO_P1")
	)
	(segment
		(start 97.97796 -262.480298)
		(end 97.511108 -262.746236)
		(width 0.350012)
		(layer "F.Cu")
		(net "PVDDIO_P1")
	)
	(segment
		(start 96.737932 -235.84027)
		(end 96.27108 -235.574332)
		(width 0.350012)
		(layer "F.Cu")
		(net "PVDDIO_P1")
	)
	(segment
		(start 97.037906 -273.820382)
		(end 96.571054 -274.08632)
		(width 0.350012)
		(layer "F.Cu")
		(net "PVDDIO_P1")
	)
	(segment
		(start 93.91777 -252.04039)
		(end 93.450918 -251.774452)
		(width 0.350012)
		(layer "F.Cu")
		(net "PVDDIO_P1")
	)
	(segment
		(start 98.617786 -256.900426)
		(end 98.150934 -256.634488)
		(width 0.350012)
		(layer "F.Cu")
		(net "PVDDIO_P1")
	)
	(segment
		(start 87.167974 -277.870412)
		(end 86.701122 -278.13635)
		(width 0.350012)
		(layer "F.Cu")
		(net "PVDDIO_P1")
	)
	(segment
		(start 99.387914 -264.910316)
		(end 98.921062 -265.176254)
		(width 0.350012)
		(layer "F.Cu")
		(net "PVDDIO_P1")
	)
	(segment
		(start 93.91777 -237.460282)
		(end 93.450918 -237.194344)
		(width 0.350012)
		(layer "F.Cu")
		(net "PVDDIO_P1")
	)
	(segment
		(start 87.167974 -268.15034)
		(end 86.701122 -268.416278)
		(width 0.350012)
		(layer "F.Cu")
		(net "PVDDIO_P1")
	)
	(segment
		(start 87.167974 -282.730448)
		(end 86.701122 -282.996386)
		(width 0.350012)
		(layer "F.Cu")
		(net "PVDDIO_P1")
	)
	(segment
		(start 93.44787 -244.750336)
		(end 92.981018 -244.484398)
		(width 0.350012)
		(layer "F.Cu")
		(net "PVDDIO_P1")
	)
	(segment
		(start 80.757776 -252.04039)
		(end 80.291178 -251.774452)
		(width 0.350012)
		(layer "F.Cu")
		(net "PVDDIO_P1")
	)
	(segment
		(start 80.287876 -249.610372)
		(end 79.821024 -249.344434)
		(width 0.350012)
		(layer "F.Cu")
		(net "PVDDIO_P1")
	)
	(segment
		(start 80.58785 -268.15034)
		(end 80.120998 -268.416278)
		(width 0.350012)
		(layer "F.Cu")
		(net "PVDDIO_P1")
	)
	(segment
		(start 94.217998 -280.30043)
		(end 93.751146 -280.566368)
		(width 0.350012)
		(layer "F.Cu")
		(net "PVDDIO_P1")
	)
	(segment
		(start 93.91777 -227.740464)
		(end 93.450918 -227.474526)
		(width 0.350012)
		(layer "F.Cu")
		(net "PVDDIO_P1")
	)
	(segment
		(start 87.3379 -252.04039)
		(end 86.871048 -251.774452)
		(width 0.350012)
		(layer "F.Cu")
		(net "PVDDIO_P1")
	)
	(segment
		(start 97.507806 -261.670292)
		(end 97.040954 -261.93623)
		(width 0.350012)
		(layer "F.Cu")
		(net "PVDDIO_P1")
	)
	(segment
		(start 93.91777 -242.320318)
		(end 93.450918 -242.05438)
		(width 0.350012)
		(layer "F.Cu")
		(net "PVDDIO_P1")
	)
	(segment
		(start 97.97796 -260.860286)
		(end 97.511108 -261.126224)
		(width 0.350012)
		(layer "F.Cu")
		(net "PVDDIO_P1")
	)
	(segment
		(start 81.058004 -290.020248)
		(end 80.591152 -290.286186)
		(width 0.350012)
		(layer "F.Cu")
		(net "PVDDIO_P1")
	)
	(segment
		(start 87.637874 -280.30043)
		(end 87.171022 -280.566368)
		(width 0.350012)
		(layer "F.Cu")
		(net "PVDDIO_P1")
	)
	(segment
		(start 87.167974 -263.290304)
		(end 86.701122 -263.556242)
		(width 0.350012)
		(layer "F.Cu")
		(net "PVDDIO_P1")
	)
	(segment
		(start 97.037906 -277.060406)
		(end 96.571054 -277.326344)
		(width 0.350012)
		(layer "F.Cu")
		(net "PVDDIO_P1")
	)
	(segment
		(start 101.268022 -263.290304)
		(end 100.80117 -263.556242)
		(width 0.350012)
		(layer "F.Cu")
		(net "PVDDIO_P1")
	)
	(segment
		(start 96.737932 -243.94033)
		(end 96.27108 -243.674392)
		(width 0.350012)
		(layer "F.Cu")
		(net "PVDDIO_P1")
	)
	(segment
		(start 80.58785 -282.730448)
		(end 80.120998 -282.996386)
		(width 0.350012)
		(layer "F.Cu")
		(net "PVDDIO_P1")
	)
	(segment
		(start 93.747844 -292.450266)
		(end 93.280992 -292.716204)
		(width 0.350012)
		(layer "F.Cu")
		(net "PVDDIO_P1")
	)
	(segment
		(start 99.857814 -262.480298)
		(end 99.390962 -262.746236)
		(width 0.350012)
		(layer "F.Cu")
		(net "PVDDIO_P1")
	)
	(segment
		(start 80.58785 -263.290304)
		(end 80.120998 -263.556242)
		(width 0.350012)
		(layer "F.Cu")
		(net "PVDDIO_P1")
	)
	(segment
		(start 93.747844 -282.730448)
		(end 93.280992 -282.996386)
		(width 0.350012)
		(layer "F.Cu")
		(net "PVDDIO_P1")
	)
	(segment
		(start 81.527904 -294.070278)
		(end 81.061052 -294.336216)
		(width 0.350012)
		(layer "F.Cu")
		(net "PVDDIO_P1")
	)
	(segment
		(start 87.637874 -285.160466)
		(end 87.171022 -285.426404)
		(width 0.350012)
		(layer "F.Cu")
		(net "PVDDIO_P1")
	)
	(segment
		(start 101.268022 -264.910316)
		(end 100.80117 -265.176254)
		(width 0.350012)
		(layer "F.Cu")
		(net "PVDDIO_P1")
	)
	(segment
		(start 87.3379 -232.600246)
		(end 86.871048 -232.334308)
		(width 0.350012)
		(layer "F.Cu")
		(net "PVDDIO_P1")
	)
	(segment
		(start 96.737932 -232.600246)
		(end 96.27108 -232.334308)
		(width 0.350012)
		(layer "F.Cu")
		(net "PVDDIO_P1")
	)
	(segment
		(start 99.857814 -265.720322)
		(end 99.390962 -265.98626)
		(width 0.350012)
		(layer "F.Cu")
		(net "PVDDIO_P1")
	)
	(segment
		(start 80.757776 -227.740464)
		(end 80.291178 -227.474526)
		(width 0.350012)
		(layer "F.Cu")
		(net "PVDDIO_P1")
	)
	(segment
		(start 80.287876 -235.030264)
		(end 79.821024 -234.764326)
		(width 0.350012)
		(layer "F.Cu")
		(net "PVDDIO_P1")
	)
	(segment
		(start 93.747844 -287.590484)
		(end 93.280992 -287.856422)
		(width 0.350012)
		(layer "F.Cu")
		(net "PVDDIO_P1")
	)
	(segment
		(start 93.44787 -249.610372)
		(end 92.981018 -249.344434)
		(width 0.350012)
		(layer "F.Cu")
		(net "PVDDIO_P1")
	)
	(segment
		(start 94.217998 -290.020248)
		(end 93.751146 -290.286186)
		(width 0.350012)
		(layer "F.Cu")
		(net "PVDDIO_P1")
	)
	(segment
		(start 97.507806 -279.490424)
		(end 97.040954 -279.756362)
		(width 0.350012)
		(layer "F.Cu")
		(net "PVDDIO_P1")
	)
	(segment
		(start 80.287876 -230.170228)
		(end 79.821024 -229.90429)
		(width 0.350012)
		(layer "F.Cu")
		(net "PVDDIO_P1")
	)
	(segment
		(start 80.58785 -277.870412)
		(end 80.120998 -278.13635)
		(width 0.350012)
		(layer "F.Cu")
		(net "PVDDIO_P1")
	)
	(segment
		(start 94.217998 -260.860286)
		(end 93.751146 -261.126224)
		(width 0.350012)
		(layer "F.Cu")
		(net "PVDDIO_P1")
	)
	(segment
		(start 99.857814 -264.10031)
		(end 99.390962 -264.366248)
		(width 0.350012)
		(layer "F.Cu")
		(net "PVDDIO_P1")
	)
	(segment
		(start 99.387914 -263.290304)
		(end 98.921062 -263.556242)
		(width 0.350012)
		(layer "F.Cu")
		(net "PVDDIO_P1")
	)
	(segment
		(start 81.058004 -275.440394)
		(end 80.591152 -275.706332)
		(width 0.350012)
		(layer "F.Cu")
		(net "PVDDIO_P1")
	)
	(segment
		(start 81.058004 -285.160466)
		(end 80.591152 -285.426404)
		(width 0.350012)
		(layer "F.Cu")
		(net "PVDDIO_P1")
	)
	(segment
		(start 81.058004 -265.720322)
		(end 80.591152 -265.98626)
		(width 0.350012)
		(layer "F.Cu")
		(net "PVDDIO_P1")
	)
	(segment
		(start 86.868 -254.470408)
		(end 86.401148 -254.20447)
		(width 0.350012)
		(layer "F.Cu")
		(net "PVDDIO_P1")
	)
	(segment
		(start 87.167974 -273.010376)
		(end 86.701122 -273.276314)
		(width 0.350012)
		(layer "F.Cu")
		(net "PVDDIO_P1")
	)
	(segment
		(start 97.207832 -238.270288)
		(end 96.74098 -238.00435)
		(width 0.350012)
		(layer "F.Cu")
		(net "PVDDIO_P1")
	)
	(segment
		(start 96.737932 -256.900426)
		(end 96.27108 -256.634488)
		(width 0.350012)
		(layer "F.Cu")
		(net "PVDDIO_P1")
	)
	(segment
		(start 93.44787 -254.470408)
		(end 92.981018 -254.20447)
		(width 0.350012)
		(layer "F.Cu")
		(net "PVDDIO_P1")
	)
	(segment
		(start 97.507806 -266.530328)
		(end 97.040954 -266.796266)
		(width 0.350012)
		(layer "F.Cu")
		(net "PVDDIO_P1")
	)
	(segment
		(start 93.44787 -230.170228)
		(end 92.981018 -229.90429)
		(width 0.350012)
		(layer "F.Cu")
		(net "PVDDIO_P1")
	)
	(segment
		(start 88.107774 -294.070278)
		(end 87.640922 -294.336216)
		(width 0.350012)
		(layer "F.Cu")
		(net "PVDDIO_P1")
	)
	(segment
		(start 93.44787 -235.030264)
		(end 92.981018 -234.764326)
		(width 0.350012)
		(layer "F.Cu")
		(net "PVDDIO_P1")
	)
	(segment
		(start 87.3379 -242.320318)
		(end 86.871048 -242.05438)
		(width 0.350012)
		(layer "F.Cu")
		(net "PVDDIO_P1")
	)
	(segment
		(start 93.91777 -247.180354)
		(end 93.450918 -246.914416)
		(width 0.350012)
		(layer "F.Cu")
		(net "PVDDIO_P1")
	)
	(segment
		(start 99.387914 -261.670292)
		(end 98.921062 -261.93623)
		(width 0.350012)
		(layer "F.Cu")
		(net "PVDDIO_P1")
	)
	(segment
		(start 97.037906 -288.400236)
		(end 96.571054 -288.666174)
		(width 0.350012)
		(layer "F.Cu")
		(net "PVDDIO_P1")
	)
	(segment
		(start 87.637874 -265.720322)
		(end 87.171022 -265.98626)
		(width 0.350012)
		(layer "F.Cu")
		(net "PVDDIO_P1")
	)
	(segment
		(start 99.857814 -260.860286)
		(end 99.390962 -261.126224)
		(width 0.350012)
		(layer "F.Cu")
		(net "PVDDIO_P1")
	)
	(segment
		(start 87.637874 -290.020248)
		(end 87.171022 -290.286186)
		(width 0.350012)
		(layer "F.Cu")
		(net "PVDDIO_P1")
	)
	(segment
		(start 81.058004 -260.860286)
		(end 80.591152 -261.126224)
		(width 0.350012)
		(layer "F.Cu")
		(net "PVDDIO_P1")
	)
	(segment
		(start 86.868 -249.610372)
		(end 86.401148 -249.344434)
		(width 0.350012)
		(layer "F.Cu")
		(net "PVDDIO_P1")
	)
	(segment
		(start 97.97796 -264.10031)
		(end 97.511108 -264.366248)
		(width 0.350012)
		(layer "F.Cu")
		(net "PVDDIO_P1")
	)
	(segment
		(start 80.757776 -237.460282)
		(end 80.291178 -237.194344)
		(width 0.350012)
		(layer "F.Cu")
		(net "PVDDIO_P1")
	)
	(segment
		(start 86.868 -239.8903)
		(end 86.401148 -239.624362)
		(width 0.350012)
		(layer "F.Cu")
		(net "PVDDIO_P1")
	)
	(segment
		(start 86.868 -235.030264)
		(end 86.401148 -234.764326)
		(width 0.350012)
		(layer "F.Cu")
		(net "PVDDIO_P1")
	)
	(segment
		(start 93.747844 -277.870412)
		(end 93.280992 -278.13635)
		(width 0.350012)
		(layer "F.Cu")
		(net "PVDDIO_P1")
	)
	(segment
		(start 87.637874 -275.440394)
		(end 87.171022 -275.706332)
		(width 0.350012)
		(layer "F.Cu")
		(net "PVDDIO_P1")
	)
	(segment
		(start 80.287876 -239.8903)
		(end 79.821024 -239.624362)
		(width 0.350012)
		(layer "F.Cu")
		(net "PVDDIO_P1")
	)
	(segment
		(start 94.217998 -285.160466)
		(end 93.751146 -285.426404)
		(width 0.350012)
		(layer "F.Cu")
		(net "PVDDIO_P1")
	)
	(segment
		(start 80.757776 -232.600246)
		(end 80.291178 -232.334308)
		(width 0.350012)
		(layer "F.Cu")
		(net "PVDDIO_P1")
	)
	(segment
		(start 97.037906 -285.160466)
		(end 96.571054 -285.426404)
		(width 0.350012)
		(layer "F.Cu")
		(net "PVDDIO_P1")
	)
	(segment
		(start 87.3379 -237.460282)
		(end 86.871048 -237.194344)
		(width 0.350012)
		(layer "F.Cu")
		(net "PVDDIO_P1")
	)
	(segment
		(start 87.637874 -260.860286)
		(end 87.171022 -261.126224)
		(width 0.350012)
		(layer "F.Cu")
		(net "PVDDIO_P1")
	)
	(segment
		(start 94.217998 -265.720322)
		(end 93.751146 -265.98626)
		(width 0.350012)
		(layer "F.Cu")
		(net "PVDDIO_P1")
	)
	(segment
		(start 81.058004 -280.30043)
		(end 80.591152 -280.566368)
		(width 0.350012)
		(layer "F.Cu")
		(net "PVDDIO_P1")
	)
	(segment
		(start 93.91777 -232.600246)
		(end 93.450918 -232.334308)
		(width 0.350012)
		(layer "F.Cu")
		(net "PVDDIO_P1")
	)
	(segment
		(start 93.747844 -273.010376)
		(end 93.280992 -273.276314)
		(width 0.350012)
		(layer "F.Cu")
		(net "PVDDIO_P1")
	)
	(segment
		(start 100.497894 -256.900426)
		(end 100.031042 -256.634488)
		(width 0.350012)
		(layer "F.Cu")
		(net "PVDDIO_P1")
	)
	(segment
		(start 80.58785 -287.590484)
		(end 80.120998 -287.856422)
		(width 0.350012)
		(layer "F.Cu")
		(net "PVDDIO_P1")
	)
	(segment
		(start 87.3379 -247.180354)
		(end 86.871048 -246.914416)
		(width 0.350012)
		(layer "F.Cu")
		(net "PVDDIO_P1")
	)
	(segment
		(start 96.737932 -247.180354)
		(end 96.27108 -246.914416)
		(width 0.350012)
		(layer "F.Cu")
		(net "PVDDIO_P1")
	)
	(segment
		(start 97.037906 -281.920442)
		(end 96.571054 -282.18638)
		(width 0.350012)
		(layer "F.Cu")
		(net "PVDDIO_P1")
	)
	(segment
		(start 96.737932 -229.360476)
		(end 96.27108 -229.094538)
		(width 0.350012)
		(layer "F.Cu")
		(net "PVDDIO_P1")
	)
	(segment
		(start 96.737932 -240.700306)
		(end 96.27108 -240.434368)
		(width 0.350012)
		(layer "F.Cu")
		(net "PVDDIO_P1")
	)
	(segment
		(start 86.868 -244.750336)
		(end 86.401148 -244.484398)
		(width 0.350012)
		(layer "F.Cu")
		(net "PVDDIO_P1")
	)
	(segment
		(start 94.217998 -270.580358)
		(end 93.751146 -270.846296)
		(width 0.350012)
		(layer "F.Cu")
		(net "PVDDIO_P1")
	)
	(segment
		(start 86.868 -230.170228)
		(end 86.401148 -229.90429)
		(width 0.350012)
		(layer "F.Cu")
		(net "PVDDIO_P1")
	)
	(segment
		(start 80.58785 -292.450266)
		(end 80.120998 -292.716204)
		(width 0.350012)
		(layer "F.Cu")
		(net "PVDDIO_P1")
	)
	(segment
		(start 87.167974 -287.590484)
		(end 86.701122 -287.856422)
		(width 0.350012)
		(layer "F.Cu")
		(net "PVDDIO_P1")
	)
	(segment
		(start 97.037906 -270.580358)
		(end 96.571054 -270.846296)
		(width 0.350012)
		(layer "F.Cu")
		(net "PVDDIO_P1")
	)
	(segment
		(start 94.217998 -275.440394)
		(end 93.751146 -275.706332)
		(width 0.350012)
		(layer "F.Cu")
		(net "PVDDIO_P1")
	)
	(via
		(at 47.26051 -330.29652)
		(size 0.508)
		(drill 0.254)
		(layers "F.Cu" "B.Cu")
		(net "PVDDIO_P1")
	)
	(via
		(at 56.17591 -331.56652)
		(size 0.508)
		(drill 0.254)
		(layers "F.Cu" "B.Cu")
		(net "PVDDIO_P1")
	)
	(via
		(at 39.64051 -330.93152)
		(size 0.508)
		(drill 0.254)
		(layers "F.Cu" "B.Cu")
		(net "PVDDIO_P1")
	)
	(via
		(at 54.90591 -334.10652)
		(size 0.508)
		(drill 0.254)
		(layers "F.Cu" "B.Cu")
		(net "PVDDIO_P1")
	)
	(via
		(at 47.89551 -330.29652)
		(size 0.508)
		(drill 0.254)
		(layers "F.Cu" "B.Cu")
		(net "PVDDIO_P1")
	)
	(via
		(at 86.701122 -282.996386)
		(size 0.4064)
		(drill 0.2032)
		(layers "F.Cu" "B.Cu")
		(net "PVDDIO_P1")
	)
	(via
		(at 51.52771 -331.56652)
		(size 0.508)
		(drill 0.254)
		(layers "F.Cu" "B.Cu")
		(net "PVDDIO_P1")
	)
	(via
		(at 38.37051 -333.47152)
		(size 0.508)
		(drill 0.254)
		(layers "F.Cu" "B.Cu")
		(net "PVDDIO_P1")
	)
	(via
		(at 26.71191 -330.93152)
		(size 0.508)
		(drill 0.254)
		(layers "F.Cu" "B.Cu")
		(net "PVDDIO_P1")
	)
	(via
		(at 99.390962 -264.366248)
		(size 0.4064)
		(drill 0.2032)
		(layers "F.Cu" "B.Cu")
		(net "PVDDIO_P1")
	)
	(via
		(at 30.09011 -330.29652)
		(size 0.508)
		(drill 0.254)
		(layers "F.Cu" "B.Cu")
		(net "PVDDIO_P1")
	)
	(via
		(at 30.72511 -334.74152)
		(size 0.508)
		(drill 0.254)
		(layers "F.Cu" "B.Cu")
		(net "PVDDIO_P1")
	)
	(via
		(at 31.36011 -332.83652)
		(size 0.508)
		(drill 0.254)
		(layers "F.Cu" "B.Cu")
		(net "PVDDIO_P1")
	)
	(via
		(at 54.90591 -331.56652)
		(size 0.508)
		(drill 0.254)
		(layers "F.Cu" "B.Cu")
		(net "PVDDIO_P1")
	)
	(via
		(at 25.296876 -350.502982)
		(size 0.508)
		(drill 0.254)
		(layers "F.Cu" "B.Cu")
		(net "PVDDIO_P1")
	)
	(via
		(at 92.981018 -229.90429)
		(size 0.4064)
		(drill 0.2032)
		(layers "F.Cu" "B.Cu")
		(net "PVDDIO_P1")
	)
	(via
		(at 26.71191 -333.47152)
		(size 0.508)
		(drill 0.254)
		(layers "F.Cu" "B.Cu")
		(net "PVDDIO_P1")
	)
	(via
		(at 43.24731 -330.93152)
		(size 0.508)
		(drill 0.254)
		(layers "F.Cu" "B.Cu")
		(net "PVDDIO_P1")
	)
	(via
		(at 47.26051 -333.47152)
		(size 0.508)
		(drill 0.254)
		(layers "F.Cu" "B.Cu")
		(net "PVDDIO_P1")
	)
	(via
		(at 80.120998 -282.996386)
		(size 0.4064)
		(drill 0.2032)
		(layers "F.Cu" "B.Cu")
		(net "PVDDIO_P1")
	)
	(via
		(at 34.35731 -330.93152)
		(size 0.508)
		(drill 0.254)
		(layers "F.Cu" "B.Cu")
		(net "PVDDIO_P1")
	)
	(via
		(at 93.751146 -290.286186)
		(size 0.4064)
		(drill 0.2032)
		(layers "F.Cu" "B.Cu")
		(net "PVDDIO_P1")
	)
	(via
		(at 52.16271 -330.29652)
		(size 0.508)
		(drill 0.254)
		(layers "F.Cu" "B.Cu")
		(net "PVDDIO_P1")
	)
	(via
		(at 87.171022 -285.426404)
		(size 0.4064)
		(drill 0.2032)
		(layers "F.Cu" "B.Cu")
		(net "PVDDIO_P1")
	)
	(via
		(at 55.54091 -330.93152)
		(size 0.508)
		(drill 0.254)
		(layers "F.Cu" "B.Cu")
		(net "PVDDIO_P1")
	)
	(via
		(at 80.591152 -285.426404)
		(size 0.4064)
		(drill 0.2032)
		(layers "F.Cu" "B.Cu")
		(net "PVDDIO_P1")
	)
	(via
		(at 30.72511 -334.10652)
		(size 0.508)
		(drill 0.254)
		(layers "F.Cu" "B.Cu")
		(net "PVDDIO_P1")
	)
	(via
		(at 47.89551 -333.47152)
		(size 0.508)
		(drill 0.254)
		(layers "F.Cu" "B.Cu")
		(net "PVDDIO_P1")
	)
	(via
		(at 79.821024 -249.344434)
		(size 0.4064)
		(drill 0.2032)
		(layers "F.Cu" "B.Cu")
		(net "PVDDIO_P1")
	)
	(via
		(at 101.940614 -259.73024)
		(size 0.4826)
		(drill 0.254)
		(layers "F.Cu" "B.Cu")
		(net "PVDDIO_P1")
	)
	(via
		(at 80.291178 -246.914416)
		(size 0.4064)
		(drill 0.2032)
		(layers "F.Cu" "B.Cu")
		(net "PVDDIO_P1")
	)
	(via
		(at 96.27108 -256.634488)
		(size 0.4064)
		(drill 0.2032)
		(layers "F.Cu" "B.Cu")
		(net "PVDDIO_P1")
	)
	(via
		(at 97.511108 -264.366248)
		(size 0.4064)
		(drill 0.2032)
		(layers "F.Cu" "B.Cu")
		(net "PVDDIO_P1")
	)
	(via
		(at 41.883076 -350.502982)
		(size 0.508)
		(drill 0.254)
		(layers "F.Cu" "B.Cu")
		(net "PVDDIO_P1")
	)
	(via
		(at 92.981018 -239.624362)
		(size 0.4064)
		(drill 0.2032)
		(layers "F.Cu" "B.Cu")
		(net "PVDDIO_P1")
	)
	(via
		(at 39.00551 -333.47152)
		(size 0.508)
		(drill 0.254)
		(layers "F.Cu" "B.Cu")
		(net "PVDDIO_P1")
	)
	(via
		(at 86.871048 -246.914416)
		(size 0.4064)
		(drill 0.2032)
		(layers "F.Cu" "B.Cu")
		(net "PVDDIO_P1")
	)
	(via
		(at 97.040954 -266.796266)
		(size 0.4064)
		(drill 0.2032)
		(layers "F.Cu" "B.Cu")
		(net "PVDDIO_P1")
	)
	(via
		(at 27.34691 -330.93152)
		(size 0.508)
		(drill 0.254)
		(layers "F.Cu" "B.Cu")
		(net "PVDDIO_P1")
	)
	(via
		(at 93.280992 -278.13635)
		(size 0.4064)
		(drill 0.2032)
		(layers "F.Cu" "B.Cu")
		(net "PVDDIO_P1")
	)
	(via
		(at 80.291178 -232.334308)
		(size 0.4064)
		(drill 0.2032)
		(layers "F.Cu" "B.Cu")
		(net "PVDDIO_P1")
	)
	(via
		(at 43.24731 -334.74152)
		(size 0.508)
		(drill 0.254)
		(layers "F.Cu" "B.Cu")
		(net "PVDDIO_P1")
	)
	(via
		(at 50.89271 -333.47152)
		(size 0.508)
		(drill 0.254)
		(layers "F.Cu" "B.Cu")
		(net "PVDDIO_P1")
	)
	(via
		(at 98.140774 -257.930396)
		(size 0.4826)
		(drill 0.254)
		(layers "F.Cu" "B.Cu")
		(net "PVDDIO_P1")
	)
	(via
		(at 79.821024 -234.764326)
		(size 0.4064)
		(drill 0.2032)
		(layers "F.Cu" "B.Cu")
		(net "PVDDIO_P1")
	)
	(via
		(at 80.120998 -287.856422)
		(size 0.4064)
		(drill 0.2032)
		(layers "F.Cu" "B.Cu")
		(net "PVDDIO_P1")
	)
	(via
		(at 52.16271 -332.83652)
		(size 0.508)
		(drill 0.254)
		(layers "F.Cu" "B.Cu")
		(net "PVDDIO_P1")
	)
	(via
		(at 93.280992 -268.416278)
		(size 0.4064)
		(drill 0.2032)
		(layers "F.Cu" "B.Cu")
		(net "PVDDIO_P1")
	)
	(via
		(at 96.571054 -282.18638)
		(size 0.4064)
		(drill 0.2032)
		(layers "F.Cu" "B.Cu")
		(net "PVDDIO_P1")
	)
	(via
		(at 55.54091 -333.47152)
		(size 0.508)
		(drill 0.254)
		(layers "F.Cu" "B.Cu")
		(net "PVDDIO_P1")
	)
	(via
		(at 96.27108 -240.434368)
		(size 0.4064)
		(drill 0.2032)
		(layers "F.Cu" "B.Cu")
		(net "PVDDIO_P1")
	)
	(via
		(at 39.00551 -332.20152)
		(size 0.508)
		(drill 0.254)
		(layers "F.Cu" "B.Cu")
		(net "PVDDIO_P1")
	)
	(via
		(at 26.07691 -330.29652)
		(size 0.508)
		(drill 0.254)
		(layers "F.Cu" "B.Cu")
		(net "PVDDIO_P1")
	)
	(via
		(at 87.171022 -275.706332)
		(size 0.4064)
		(drill 0.2032)
		(layers "F.Cu" "B.Cu")
		(net "PVDDIO_P1")
	)
	(via
		(at 43.93311 -329.53452)
		(size 0.6604)
		(drill 0.3302)
		(layers "F.Cu" "B.Cu")
		(net "PVDDIO_P1")
	)
	(via
		(at 35.62731 -329.53452)
		(size 0.6604)
		(drill 0.3302)
		(layers "F.Cu" "B.Cu")
		(net "PVDDIO_P1")
	)
	(via
		(at 87.640922 -294.336216)
		(size 0.4064)
		(drill 0.2032)
		(layers "F.Cu" "B.Cu")
		(net "PVDDIO_P1")
	)
	(via
		(at 100.80117 -263.556242)
		(size 0.4064)
		(drill 0.2032)
		(layers "F.Cu" "B.Cu")
		(net "PVDDIO_P1")
	)
	(via
		(at 50.89271 -332.83652)
		(size 0.508)
		(drill 0.254)
		(layers "F.Cu" "B.Cu")
		(net "PVDDIO_P1")
	)
	(via
		(at 87.171022 -280.566368)
		(size 0.4064)
		(drill 0.2032)
		(layers "F.Cu" "B.Cu")
		(net "PVDDIO_P1")
	)
	(via
		(at 86.701122 -278.13635)
		(size 0.4064)
		(drill 0.2032)
		(layers "F.Cu" "B.Cu")
		(net "PVDDIO_P1")
	)
	(via
		(at 96.571054 -288.666174)
		(size 0.4064)
		(drill 0.2032)
		(layers "F.Cu" "B.Cu")
		(net "PVDDIO_P1")
	)
	(via
		(at 38.37051 -330.93152)
		(size 0.508)
		(drill 0.254)
		(layers "F.Cu" "B.Cu")
		(net "PVDDIO_P1")
	)
	(via
		(at 86.401148 -234.764326)
		(size 0.4064)
		(drill 0.2032)
		(layers "F.Cu" "B.Cu")
		(net "PVDDIO_P1")
	)
	(via
		(at 96.27108 -246.914416)
		(size 0.4064)
		(drill 0.2032)
		(layers "F.Cu" "B.Cu")
		(net "PVDDIO_P1")
	)
	(via
		(at 26.71191 -334.10652)
		(size 0.508)
		(drill 0.254)
		(layers "F.Cu" "B.Cu")
		(net "PVDDIO_P1")
	)
	(via
		(at 56.17591 -330.93152)
		(size 0.508)
		(drill 0.254)
		(layers "F.Cu" "B.Cu")
		(net "PVDDIO_P1")
	)
	(via
		(at 42.61231 -331.56652)
		(size 0.508)
		(drill 0.254)
		(layers "F.Cu" "B.Cu")
		(net "PVDDIO_P1")
	)
	(via
		(at 43.88231 -330.29652)
		(size 0.508)
		(drill 0.254)
		(layers "F.Cu" "B.Cu")
		(net "PVDDIO_P1")
	)
	(via
		(at 34.99231 -334.10652)
		(size 0.508)
		(drill 0.254)
		(layers "F.Cu" "B.Cu")
		(net "PVDDIO_P1")
	)
	(via
		(at 101.940614 -258.830318)
		(size 0.4826)
		(drill 0.254)
		(layers "F.Cu" "B.Cu")
		(net "PVDDIO_P1")
	)
	(via
		(at 105.490772 -261.230364)
		(size 0.4826)
		(drill 0.254)
		(layers "F.Cu" "B.Cu")
		(net "PVDDIO_P1")
	)
	(via
		(at 86.401148 -239.624362)
		(size 0.4064)
		(drill 0.2032)
		(layers "F.Cu" "B.Cu")
		(net "PVDDIO_P1")
	)
	(via
		(at 50.89271 -334.10652)
		(size 0.508)
		(drill 0.254)
		(layers "F.Cu" "B.Cu")
		(net "PVDDIO_P1")
	)
	(via
		(at 51.52771 -334.74152)
		(size 0.508)
		(drill 0.254)
		(layers "F.Cu" "B.Cu")
		(net "PVDDIO_P1")
	)
	(via
		(at 56.17591 -330.29652)
		(size 0.508)
		(drill 0.254)
		(layers "F.Cu" "B.Cu")
		(net "PVDDIO_P1")
	)
	(via
		(at 93.751146 -270.846296)
		(size 0.4064)
		(drill 0.2032)
		(layers "F.Cu" "B.Cu")
		(net "PVDDIO_P1")
	)
	(via
		(at 52.16271 -332.20152)
		(size 0.508)
		(drill 0.254)
		(layers "F.Cu" "B.Cu")
		(net "PVDDIO_P1")
	)
	(via
		(at 39.00551 -330.93152)
		(size 0.508)
		(drill 0.254)
		(layers "F.Cu" "B.Cu")
		(net "PVDDIO_P1")
	)
	(via
		(at 54.90591 -334.74152)
		(size 0.508)
		(drill 0.254)
		(layers "F.Cu" "B.Cu")
		(net "PVDDIO_P1")
	)
	(via
		(at 51.52771 -332.20152)
		(size 0.508)
		(drill 0.254)
		(layers "F.Cu" "B.Cu")
		(net "PVDDIO_P1")
	)
	(via
		(at 39.64051 -334.10652)
		(size 0.508)
		(drill 0.254)
		(layers "F.Cu" "B.Cu")
		(net "PVDDIO_P1")
	)
	(via
		(at 26.07691 -334.74152)
		(size 0.508)
		(drill 0.254)
		(layers "F.Cu" "B.Cu")
		(net "PVDDIO_P1")
	)
	(via
		(at 30.09011 -331.56652)
		(size 0.508)
		(drill 0.254)
		(layers "F.Cu" "B.Cu")
		(net "PVDDIO_P1")
	)
	(via
		(at 43.24731 -332.83652)
		(size 0.508)
		(drill 0.254)
		(layers "F.Cu" "B.Cu")
		(net "PVDDIO_P1")
	)
	(via
		(at 46.62551 -332.20152)
		(size 0.508)
		(drill 0.254)
		(layers "F.Cu" "B.Cu")
		(net "PVDDIO_P1")
	)
	(via
		(at 86.401148 -244.484398)
		(size 0.4064)
		(drill 0.2032)
		(layers "F.Cu" "B.Cu")
		(net "PVDDIO_P1")
	)
	(via
		(at 34.35731 -334.10652)
		(size 0.508)
		(drill 0.254)
		(layers "F.Cu" "B.Cu")
		(net "PVDDIO_P1")
	)
	(via
		(at 55.54091 -332.83652)
		(size 0.508)
		(drill 0.254)
		(layers "F.Cu" "B.Cu")
		(net "PVDDIO_P1")
	)
	(via
		(at 93.280992 -292.716204)
		(size 0.4064)
		(drill 0.2032)
		(layers "F.Cu" "B.Cu")
		(net "PVDDIO_P1")
	)
	(via
		(at 38.37051 -332.20152)
		(size 0.508)
		(drill 0.254)
		(layers "F.Cu" "B.Cu")
		(net "PVDDIO_P1")
	)
	(via
		(at 26.07691 -330.93152)
		(size 0.508)
		(drill 0.254)
		(layers "F.Cu" "B.Cu")
		(net "PVDDIO_P1")
	)
	(via
		(at 47.89551 -332.20152)
		(size 0.508)
		(drill 0.254)
		(layers "F.Cu" "B.Cu")
		(net "PVDDIO_P1")
	)
	(via
		(at 96.27108 -229.094538)
		(size 0.4064)
		(drill 0.2032)
		(layers "F.Cu" "B.Cu")
		(net "PVDDIO_P1")
	)
	(via
		(at 34.35731 -330.29652)
		(size 0.508)
		(drill 0.254)
		(layers "F.Cu" "B.Cu")
		(net "PVDDIO_P1")
	)
	(via
		(at 107.917742 -259.845302)
		(size 0.4826)
		(drill 0.254)
		(layers "F.Cu" "B.Cu")
		(net "PVDDIO_P1")
	)
	(via
		(at 80.291178 -242.05438)
		(size 0.4064)
		(drill 0.2032)
		(layers "F.Cu" "B.Cu")
		(net "PVDDIO_P1")
	)
	(via
		(at 50.89271 -332.20152)
		(size 0.508)
		(drill 0.254)
		(layers "F.Cu" "B.Cu")
		(net "PVDDIO_P1")
	)
	(via
		(at 26.71191 -334.74152)
		(size 0.508)
		(drill 0.254)
		(layers "F.Cu" "B.Cu")
		(net "PVDDIO_P1")
	)
	(via
		(at 30.09011 -332.83652)
		(size 0.508)
		(drill 0.254)
		(layers "F.Cu" "B.Cu")
		(net "PVDDIO_P1")
	)
	(via
		(at 80.120998 -268.416278)
		(size 0.4064)
		(drill 0.2032)
		(layers "F.Cu" "B.Cu")
		(net "PVDDIO_P1")
	)
	(via
		(at 39.00551 -334.74152)
		(size 0.508)
		(drill 0.254)
		(layers "F.Cu" "B.Cu")
		(net "PVDDIO_P1")
	)
	(via
		(at 86.401148 -229.90429)
		(size 0.4064)
		(drill 0.2032)
		(layers "F.Cu" "B.Cu")
		(net "PVDDIO_P1")
	)
	(via
		(at 50.239676 -350.502982)
		(size 0.508)
		(drill 0.254)
		(layers "F.Cu" "B.Cu")
		(net "PVDDIO_P1")
	)
	(via
		(at 30.72511 -330.93152)
		(size 0.508)
		(drill 0.254)
		(layers "F.Cu" "B.Cu")
		(net "PVDDIO_P1")
	)
	(via
		(at 80.120998 -278.13635)
		(size 0.4064)
		(drill 0.2032)
		(layers "F.Cu" "B.Cu")
		(net "PVDDIO_P1")
	)
	(via
		(at 31.36011 -330.93152)
		(size 0.508)
		(drill 0.254)
		(layers "F.Cu" "B.Cu")
		(net "PVDDIO_P1")
	)
	(via
		(at 31.36011 -332.20152)
		(size 0.508)
		(drill 0.254)
		(layers "F.Cu" "B.Cu")
		(net "PVDDIO_P1")
	)
	(via
		(at 39.64051 -330.29652)
		(size 0.508)
		(drill 0.254)
		(layers "F.Cu" "B.Cu")
		(net "PVDDIO_P1")
	)
	(via
		(at 92.981018 -254.20447)
		(size 0.4064)
		(drill 0.2032)
		(layers "F.Cu" "B.Cu")
		(net "PVDDIO_P1")
	)
	(via
		(at 34.99231 -330.29652)
		(size 0.508)
		(drill 0.254)
		(layers "F.Cu" "B.Cu")
		(net "PVDDIO_P1")
	)
	(via
		(at 30.72511 -332.20152)
		(size 0.508)
		(drill 0.254)
		(layers "F.Cu" "B.Cu")
		(net "PVDDIO_P1")
	)
	(via
		(at 97.511108 -261.126224)
		(size 0.4064)
		(drill 0.2032)
		(layers "F.Cu" "B.Cu")
		(net "PVDDIO_P1")
	)
	(via
		(at 98.140774 -259.73024)
		(size 0.4826)
		(drill 0.254)
		(layers "F.Cu" "B.Cu")
		(net "PVDDIO_P1")
	)
	(via
		(at 47.26051 -332.20152)
		(size 0.508)
		(drill 0.254)
		(layers "F.Cu" "B.Cu")
		(net "PVDDIO_P1")
	)
	(via
		(at 35.62731 -330.93152)
		(size 0.508)
		(drill 0.254)
		(layers "F.Cu" "B.Cu")
		(net "PVDDIO_P1")
	)
	(via
		(at 30.72511 -333.47152)
		(size 0.508)
		(drill 0.254)
		(layers "F.Cu" "B.Cu")
		(net "PVDDIO_P1")
	)
	(via
		(at 27.34691 -331.56652)
		(size 0.508)
		(drill 0.254)
		(layers "F.Cu" "B.Cu")
		(net "PVDDIO_P1")
	)
	(via
		(at 100.031042 -256.634488)
		(size 0.4064)
		(drill 0.2032)
		(layers "F.Cu" "B.Cu")
		(net "PVDDIO_P1")
	)
	(via
		(at 55.54091 -334.74152)
		(size 0.508)
		(drill 0.254)
		(layers "F.Cu" "B.Cu")
		(net "PVDDIO_P1")
	)
	(via
		(at 46.62551 -330.29652)
		(size 0.508)
		(drill 0.254)
		(layers "F.Cu" "B.Cu")
		(net "PVDDIO_P1")
	)
	(via
		(at 26.07691 -334.10652)
		(size 0.508)
		(drill 0.254)
		(layers "F.Cu" "B.Cu")
		(net "PVDDIO_P1")
	)
	(via
		(at 93.280992 -282.996386)
		(size 0.4064)
		(drill 0.2032)
		(layers "F.Cu" "B.Cu")
		(net "PVDDIO_P1")
	)
	(via
		(at 43.24731 -331.56652)
		(size 0.508)
		(drill 0.254)
		(layers "F.Cu" "B.Cu")
		(net "PVDDIO_P1")
	)
	(via
		(at 55.54091 -331.56652)
		(size 0.508)
		(drill 0.254)
		(layers "F.Cu" "B.Cu")
		(net "PVDDIO_P1")
	)
	(via
		(at 87.171022 -261.126224)
		(size 0.4064)
		(drill 0.2032)
		(layers "F.Cu" "B.Cu")
		(net "PVDDIO_P1")
	)
	(via
		(at 46.62551 -331.56652)
		(size 0.508)
		(drill 0.254)
		(layers "F.Cu" "B.Cu")
		(net "PVDDIO_P1")
	)
	(via
		(at 79.821024 -254.20447)
		(size 0.4064)
		(drill 0.2032)
		(layers "F.Cu" "B.Cu")
		(net "PVDDIO_P1")
	)
	(via
		(at 47.89551 -331.56652)
		(size 0.508)
		(drill 0.254)
		(layers "F.Cu" "B.Cu")
		(net "PVDDIO_P1")
	)
	(via
		(at 39.64051 -331.56652)
		(size 0.508)
		(drill 0.254)
		(layers "F.Cu" "B.Cu")
		(net "PVDDIO_P1")
	)
	(via
		(at 39.64051 -332.20152)
		(size 0.508)
		(drill 0.254)
		(layers "F.Cu" "B.Cu")
		(net "PVDDIO_P1")
	)
	(via
		(at 34.35731 -331.56652)
		(size 0.508)
		(drill 0.254)
		(layers "F.Cu" "B.Cu")
		(net "PVDDIO_P1")
	)
	(via
		(at 98.140774 -258.830318)
		(size 0.4826)
		(drill 0.254)
		(layers "F.Cu" "B.Cu")
		(net "PVDDIO_P1")
	)
	(via
		(at 47.26051 -331.56652)
		(size 0.508)
		(drill 0.254)
		(layers "F.Cu" "B.Cu")
		(net "PVDDIO_P1")
	)
	(via
		(at 26.07691 -332.20152)
		(size 0.508)
		(drill 0.254)
		(layers "F.Cu" "B.Cu")
		(net "PVDDIO_P1")
	)
	(via
		(at 100.040694 -259.73024)
		(size 0.4826)
		(drill 0.254)
		(layers "F.Cu" "B.Cu")
		(net "PVDDIO_P1")
	)
	(via
		(at 93.450918 -242.05438)
		(size 0.4064)
		(drill 0.2032)
		(layers "F.Cu" "B.Cu")
		(net "PVDDIO_P1")
	)
	(via
		(at 46.62551 -334.10652)
		(size 0.508)
		(drill 0.254)
		(layers "F.Cu" "B.Cu")
		(net "PVDDIO_P1")
	)
	(via
		(at 80.291178 -251.774452)
		(size 0.4064)
		(drill 0.2032)
		(layers "F.Cu" "B.Cu")
		(net "PVDDIO_P1")
	)
	(via
		(at 55.54091 -332.20152)
		(size 0.508)
		(drill 0.254)
		(layers "F.Cu" "B.Cu")
		(net "PVDDIO_P1")
	)
	(via
		(at 87.171022 -265.98626)
		(size 0.4064)
		(drill 0.2032)
		(layers "F.Cu" "B.Cu")
		(net "PVDDIO_P1")
	)
	(via
		(at 39.00551 -331.56652)
		(size 0.508)
		(drill 0.254)
		(layers "F.Cu" "B.Cu")
		(net "PVDDIO_P1")
	)
	(via
		(at 27.34691 -332.83652)
		(size 0.508)
		(drill 0.254)
		(layers "F.Cu" "B.Cu")
		(net "PVDDIO_P1")
	)
	(via
		(at 96.571054 -285.426404)
		(size 0.4064)
		(drill 0.2032)
		(layers "F.Cu" "B.Cu")
		(net "PVDDIO_P1")
	)
	(via
		(at 34.99231 -332.20152)
		(size 0.508)
		(drill 0.254)
		(layers "F.Cu" "B.Cu")
		(net "PVDDIO_P1")
	)
	(via
		(at 46.62551 -330.93152)
		(size 0.508)
		(drill 0.254)
		(layers "F.Cu" "B.Cu")
		(net "PVDDIO_P1")
	)
	(via
		(at 97.040954 -263.556242)
		(size 0.4064)
		(drill 0.2032)
		(layers "F.Cu" "B.Cu")
		(net "PVDDIO_P1")
	)
	(via
		(at 35.62731 -333.47152)
		(size 0.508)
		(drill 0.254)
		(layers "F.Cu" "B.Cu")
		(net "PVDDIO_P1")
	)
	(via
		(at 34.99231 -334.74152)
		(size 0.508)
		(drill 0.254)
		(layers "F.Cu" "B.Cu")
		(net "PVDDIO_P1")
	)
	(via
		(at 35.62731 -332.83652)
		(size 0.508)
		(drill 0.254)
		(layers "F.Cu" "B.Cu")
		(net "PVDDIO_P1")
	)
	(via
		(at 86.701122 -268.416278)
		(size 0.4064)
		(drill 0.2032)
		(layers "F.Cu" "B.Cu")
		(net "PVDDIO_P1")
	)
	(via
		(at 31.36011 -330.29652)
		(size 0.508)
		(drill 0.254)
		(layers "F.Cu" "B.Cu")
		(net "PVDDIO_P1")
	)
	(via
		(at 34.35731 -334.74152)
		(size 0.508)
		(drill 0.254)
		(layers "F.Cu" "B.Cu")
		(net "PVDDIO_P1")
	)
	(via
		(at 34.35731 -333.47152)
		(size 0.508)
		(drill 0.254)
		(layers "F.Cu" "B.Cu")
		(net "PVDDIO_P1")
	)
	(via
		(at 39.64051 -334.74152)
		(size 0.508)
		(drill 0.254)
		(layers "F.Cu" "B.Cu")
		(net "PVDDIO_P1")
	)
	(via
		(at 97.511108 -265.98626)
		(size 0.4064)
		(drill 0.2032)
		(layers "F.Cu" "B.Cu")
		(net "PVDDIO_P1")
	)
	(via
		(at 42.61231 -332.83652)
		(size 0.508)
		(drill 0.254)
		(layers "F.Cu" "B.Cu")
		(net "PVDDIO_P1")
	)
	(via
		(at 26.07691 -333.47152)
		(size 0.508)
		(drill 0.254)
		(layers "F.Cu" "B.Cu")
		(net "PVDDIO_P1")
	)
	(via
		(at 35.62731 -334.10652)
		(size 0.508)
		(drill 0.254)
		(layers "F.Cu" "B.Cu")
		(net "PVDDIO_P1")
	)
	(via
		(at 86.401148 -249.344434)
		(size 0.4064)
		(drill 0.2032)
		(layers "F.Cu" "B.Cu")
		(net "PVDDIO_P1")
	)
	(via
		(at 79.821024 -239.624362)
		(size 0.4064)
		(drill 0.2032)
		(layers "F.Cu" "B.Cu")
		(net "PVDDIO_P1")
	)
	(via
		(at 30.72511 -330.29652)
		(size 0.508)
		(drill 0.254)
		(layers "F.Cu" "B.Cu")
		(net "PVDDIO_P1")
	)
	(via
		(at 86.701122 -273.276314)
		(size 0.4064)
		(drill 0.2032)
		(layers "F.Cu" "B.Cu")
		(net "PVDDIO_P1")
	)
	(via
		(at 86.871048 -242.05438)
		(size 0.4064)
		(drill 0.2032)
		(layers "F.Cu" "B.Cu")
		(net "PVDDIO_P1")
	)
	(via
		(at 107.917742 -258.795266)
		(size 0.4826)
		(drill 0.254)
		(layers "F.Cu" "B.Cu")
		(net "PVDDIO_P1")
	)
	(via
		(at 98.921062 -261.93623)
		(size 0.4064)
		(drill 0.2032)
		(layers "F.Cu" "B.Cu")
		(net "PVDDIO_P1")
	)
	(via
		(at 98.921062 -265.176254)
		(size 0.4064)
		(drill 0.2032)
		(layers "F.Cu" "B.Cu")
		(net "PVDDIO_P1")
	)
	(via
		(at 96.27108 -232.334308)
		(size 0.4064)
		(drill 0.2032)
		(layers "F.Cu" "B.Cu")
		(net "PVDDIO_P1")
	)
	(via
		(at 43.88231 -330.93152)
		(size 0.508)
		(drill 0.254)
		(layers "F.Cu" "B.Cu")
		(net "PVDDIO_P1")
	)
	(via
		(at 96.27108 -235.574332)
		(size 0.4064)
		(drill 0.2032)
		(layers "F.Cu" "B.Cu")
		(net "PVDDIO_P1")
	)
	(via
		(at 51.52771 -330.29652)
		(size 0.508)
		(drill 0.254)
		(layers "F.Cu" "B.Cu")
		(net "PVDDIO_P1")
	)
	(via
		(at 26.07691 -332.83652)
		(size 0.508)
		(drill 0.254)
		(layers "F.Cu" "B.Cu")
		(net "PVDDIO_P1")
	)
	(via
		(at 47.89551 -334.74152)
		(size 0.508)
		(drill 0.254)
		(layers "F.Cu" "B.Cu")
		(net "PVDDIO_P1")
	)
	(via
		(at 54.90591 -332.83652)
		(size 0.508)
		(drill 0.254)
		(layers "F.Cu" "B.Cu")
		(net "PVDDIO_P1")
	)
	(via
		(at 39.00551 -330.29652)
		(size 0.508)
		(drill 0.254)
		(layers "F.Cu" "B.Cu")
		(net "PVDDIO_P1")
	)
	(via
		(at 96.571054 -274.08632)
		(size 0.4064)
		(drill 0.2032)
		(layers "F.Cu" "B.Cu")
		(net "PVDDIO_P1")
	)
	(via
		(at 52.16271 -334.10652)
		(size 0.508)
		(drill 0.254)
		(layers "F.Cu" "B.Cu")
		(net "PVDDIO_P1")
	)
	(via
		(at 97.511108 -262.746236)
		(size 0.4064)
		(drill 0.2032)
		(layers "F.Cu" "B.Cu")
		(net "PVDDIO_P1")
	)
	(via
		(at 87.171022 -290.286186)
		(size 0.4064)
		(drill 0.2032)
		(layers "F.Cu" "B.Cu")
		(net "PVDDIO_P1")
	)
	(via
		(at 86.871048 -251.774452)
		(size 0.4064)
		(drill 0.2032)
		(layers "F.Cu" "B.Cu")
		(net "PVDDIO_P1")
	)
	(via
		(at 27.34691 -330.29652)
		(size 0.508)
		(drill 0.254)
		(layers "F.Cu" "B.Cu")
		(net "PVDDIO_P1")
	)
	(via
		(at 100.040694 -257.930396)
		(size 0.4826)
		(drill 0.254)
		(layers "F.Cu" "B.Cu")
		(net "PVDDIO_P1")
	)
	(via
		(at 80.591152 -265.98626)
		(size 0.4064)
		(drill 0.2032)
		(layers "F.Cu" "B.Cu")
		(net "PVDDIO_P1")
	)
	(via
		(at 34.35731 -332.20152)
		(size 0.508)
		(drill 0.254)
		(layers "F.Cu" "B.Cu")
		(net "PVDDIO_P1")
	)
	(via
		(at 86.871048 -232.334308)
		(size 0.4064)
		(drill 0.2032)
		(layers "F.Cu" "B.Cu")
		(net "PVDDIO_P1")
	)
	(via
		(at 80.591152 -280.566368)
		(size 0.4064)
		(drill 0.2032)
		(layers "F.Cu" "B.Cu")
		(net "PVDDIO_P1")
	)
	(via
		(at 93.751146 -285.426404)
		(size 0.4064)
		(drill 0.2032)
		(layers "F.Cu" "B.Cu")
		(net "PVDDIO_P1")
	)
	(via
		(at 80.120998 -263.556242)
		(size 0.4064)
		(drill 0.2032)
		(layers "F.Cu" "B.Cu")
		(net "PVDDIO_P1")
	)
	(via
		(at 96.27108 -243.674392)
		(size 0.4064)
		(drill 0.2032)
		(layers "F.Cu" "B.Cu")
		(net "PVDDIO_P1")
	)
	(via
		(at 86.701122 -263.556242)
		(size 0.4064)
		(drill 0.2032)
		(layers "F.Cu" "B.Cu")
		(net "PVDDIO_P1")
	)
	(via
		(at 92.981018 -249.344434)
		(size 0.4064)
		(drill 0.2032)
		(layers "F.Cu" "B.Cu")
		(net "PVDDIO_P1")
	)
	(via
		(at 105.490772 -258.38023)
		(size 0.4826)
		(drill 0.254)
		(layers "F.Cu" "B.Cu")
		(net "PVDDIO_P1")
	)
	(via
		(at 39.00551 -334.10652)
		(size 0.508)
		(drill 0.254)
		(layers "F.Cu" "B.Cu")
		(net "PVDDIO_P1")
	)
	(via
		(at 86.701122 -292.716204)
		(size 0.4064)
		(drill 0.2032)
		(layers "F.Cu" "B.Cu")
		(net "PVDDIO_P1")
	)
	(via
		(at 80.591152 -275.706332)
		(size 0.4064)
		(drill 0.2032)
		(layers "F.Cu" "B.Cu")
		(net "PVDDIO_P1")
	)
	(via
		(at 54.90591 -333.47152)
		(size 0.508)
		(drill 0.254)
		(layers "F.Cu" "B.Cu")
		(net "PVDDIO_P1")
	)
	(via
		(at 46.62551 -332.83652)
		(size 0.508)
		(drill 0.254)
		(layers "F.Cu" "B.Cu")
		(net "PVDDIO_P1")
	)
	(via
		(at 34.99231 -331.56652)
		(size 0.508)
		(drill 0.254)
		(layers "F.Cu" "B.Cu")
		(net "PVDDIO_P1")
	)
	(via
		(at 34.99231 -330.93152)
		(size 0.508)
		(drill 0.254)
		(layers "F.Cu" "B.Cu")
		(net "PVDDIO_P1")
	)
	(via
		(at 43.88231 -332.20152)
		(size 0.508)
		(drill 0.254)
		(layers "F.Cu" "B.Cu")
		(net "PVDDIO_P1")
	)
	(via
		(at 81.061052 -294.336216)
		(size 0.4064)
		(drill 0.2032)
		(layers "F.Cu" "B.Cu")
		(net "PVDDIO_P1")
	)
	(via
		(at 92.981018 -244.484398)
		(size 0.4064)
		(drill 0.2032)
		(layers "F.Cu" "B.Cu")
		(net "PVDDIO_P1")
	)
	(via
		(at 47.26051 -334.10652)
		(size 0.508)
		(drill 0.254)
		(layers "F.Cu" "B.Cu")
		(net "PVDDIO_P1")
	)
	(via
		(at 27.34691 -334.74152)
		(size 0.508)
		(drill 0.254)
		(layers "F.Cu" "B.Cu")
		(net "PVDDIO_P1")
	)
	(via
		(at 98.150934 -256.634488)
		(size 0.4064)
		(drill 0.2032)
		(layers "F.Cu" "B.Cu")
		(net "PVDDIO_P1")
	)
	(via
		(at 30.09011 -334.74152)
		(size 0.508)
		(drill 0.254)
		(layers "F.Cu" "B.Cu")
		(net "PVDDIO_P1")
	)
	(via
		(at 34.35731 -332.83652)
		(size 0.508)
		(drill 0.254)
		(layers "F.Cu" "B.Cu")
		(net "PVDDIO_P1")
	)
	(via
		(at 33.577276 -350.502982)
		(size 0.508)
		(drill 0.254)
		(layers "F.Cu" "B.Cu")
		(net "PVDDIO_P1")
	)
	(via
		(at 31.36011 -334.74152)
		(size 0.508)
		(drill 0.254)
		(layers "F.Cu" "B.Cu")
		(net "PVDDIO_P1")
	)
	(via
		(at 43.24731 -332.20152)
		(size 0.508)
		(drill 0.254)
		(layers "F.Cu" "B.Cu")
		(net "PVDDIO_P1")
	)
	(via
		(at 35.62731 -331.56652)
		(size 0.508)
		(drill 0.254)
		(layers "F.Cu" "B.Cu")
		(net "PVDDIO_P1")
	)
	(via
		(at 96.571054 -270.846296)
		(size 0.4064)
		(drill 0.2032)
		(layers "F.Cu" "B.Cu")
		(net "PVDDIO_P1")
	)
	(via
		(at 30.09011 -332.20152)
		(size 0.508)
		(drill 0.254)
		(layers "F.Cu" "B.Cu")
		(net "PVDDIO_P1")
	)
	(via
		(at 38.37051 -334.74152)
		(size 0.508)
		(drill 0.254)
		(layers "F.Cu" "B.Cu")
		(net "PVDDIO_P1")
	)
	(via
		(at 56.17591 -334.10652)
		(size 0.508)
		(drill 0.254)
		(layers "F.Cu" "B.Cu")
		(net "PVDDIO_P1")
	)
	(via
		(at 99.390962 -261.126224)
		(size 0.4064)
		(drill 0.2032)
		(layers "F.Cu" "B.Cu")
		(net "PVDDIO_P1")
	)
	(via
		(at 30.09011 -330.93152)
		(size 0.508)
		(drill 0.254)
		(layers "F.Cu" "B.Cu")
		(net "PVDDIO_P1")
	)
	(via
		(at 50.89271 -330.29652)
		(size 0.508)
		(drill 0.254)
		(layers "F.Cu" "B.Cu")
		(net "PVDDIO_P1")
	)
	(via
		(at 100.040694 -258.830318)
		(size 0.4826)
		(drill 0.254)
		(layers "F.Cu" "B.Cu")
		(net "PVDDIO_P1")
	)
	(via
		(at 86.871048 -227.474526)
		(size 0.4064)
		(drill 0.2032)
		(layers "F.Cu" "B.Cu")
		(net "PVDDIO_P1")
	)
	(via
		(at 38.37051 -330.29652)
		(size 0.508)
		(drill 0.254)
		(layers "F.Cu" "B.Cu")
		(net "PVDDIO_P1")
	)
	(via
		(at 26.07691 -331.56652)
		(size 0.508)
		(drill 0.254)
		(layers "F.Cu" "B.Cu")
		(net "PVDDIO_P1")
	)
	(via
		(at 30.72511 -331.56652)
		(size 0.508)
		(drill 0.254)
		(layers "F.Cu" "B.Cu")
		(net "PVDDIO_P1")
	)
	(via
		(at 93.450918 -237.194344)
		(size 0.4064)
		(drill 0.2032)
		(layers "F.Cu" "B.Cu")
		(net "PVDDIO_P1")
	)
	(via
		(at 93.280992 -287.856422)
		(size 0.4064)
		(drill 0.2032)
		(layers "F.Cu" "B.Cu")
		(net "PVDDIO_P1")
	)
	(via
		(at 35.62731 -330.29652)
		(size 0.508)
		(drill 0.254)
		(layers "F.Cu" "B.Cu")
		(net "PVDDIO_P1")
	)
	(via
		(at 93.450918 -232.334308)
		(size 0.4064)
		(drill 0.2032)
		(layers "F.Cu" "B.Cu")
		(net "PVDDIO_P1")
	)
	(via
		(at 26.71191 -332.83652)
		(size 0.508)
		(drill 0.254)
		(layers "F.Cu" "B.Cu")
		(net "PVDDIO_P1")
	)
	(via
		(at 51.52771 -334.10652)
		(size 0.508)
		(drill 0.254)
		(layers "F.Cu" "B.Cu")
		(net "PVDDIO_P1")
	)
	(via
		(at 35.62731 -332.20152)
		(size 0.508)
		(drill 0.254)
		(layers "F.Cu" "B.Cu")
		(net "PVDDIO_P1")
	)
	(via
		(at 27.34691 -332.20152)
		(size 0.508)
		(drill 0.254)
		(layers "F.Cu" "B.Cu")
		(net "PVDDIO_P1")
	)
	(via
		(at 52.16271 -331.56652)
		(size 0.508)
		(drill 0.254)
		(layers "F.Cu" "B.Cu")
		(net "PVDDIO_P1")
	)
	(via
		(at 93.450918 -227.474526)
		(size 0.4064)
		(drill 0.2032)
		(layers "F.Cu" "B.Cu")
		(net "PVDDIO_P1")
	)
	(via
		(at 97.040954 -279.756362)
		(size 0.4064)
		(drill 0.2032)
		(layers "F.Cu" "B.Cu")
		(net "PVDDIO_P1")
	)
	(via
		(at 55.54091 -334.10652)
		(size 0.508)
		(drill 0.254)
		(layers "F.Cu" "B.Cu")
		(net "PVDDIO_P1")
	)
	(via
		(at 43.24731 -330.29652)
		(size 0.508)
		(drill 0.254)
		(layers "F.Cu" "B.Cu")
		(net "PVDDIO_P1")
	)
	(via
		(at 93.751146 -265.98626)
		(size 0.4064)
		(drill 0.2032)
		(layers "F.Cu" "B.Cu")
		(net "PVDDIO_P1")
	)
	(via
		(at 31.36011 -334.10652)
		(size 0.508)
		(drill 0.254)
		(layers "F.Cu" "B.Cu")
		(net "PVDDIO_P1")
	)
	(via
		(at 56.17591 -333.47152)
		(size 0.508)
		(drill 0.254)
		(layers "F.Cu" "B.Cu")
		(net "PVDDIO_P1")
	)
	(via
		(at 42.61231 -330.29652)
		(size 0.508)
		(drill 0.254)
		(layers "F.Cu" "B.Cu")
		(net "PVDDIO_P1")
	)
	(via
		(at 38.37051 -334.10652)
		(size 0.508)
		(drill 0.254)
		(layers "F.Cu" "B.Cu")
		(net "PVDDIO_P1")
	)
	(via
		(at 80.591152 -290.286186)
		(size 0.4064)
		(drill 0.2032)
		(layers "F.Cu" "B.Cu")
		(net "PVDDIO_P1")
	)
	(via
		(at 47.89551 -332.83652)
		(size 0.508)
		(drill 0.254)
		(layers "F.Cu" "B.Cu")
		(net "PVDDIO_P1")
	)
	(via
		(at 47.89551 -330.93152)
		(size 0.508)
		(drill 0.254)
		(layers "F.Cu" "B.Cu")
		(net "PVDDIO_P1")
	)
	(via
		(at 98.921062 -263.556242)
		(size 0.4064)
		(drill 0.2032)
		(layers "F.Cu" "B.Cu")
		(net "PVDDIO_P1")
	)
	(via
		(at 34.99231 -332.83652)
		(size 0.508)
		(drill 0.254)
		(layers "F.Cu" "B.Cu")
		(net "PVDDIO_P1")
	)
	(via
		(at 46.62551 -333.47152)
		(size 0.508)
		(drill 0.254)
		(layers "F.Cu" "B.Cu")
		(net "PVDDIO_P1")
	)
	(via
		(at 80.120998 -273.276314)
		(size 0.4064)
		(drill 0.2032)
		(layers "F.Cu" "B.Cu")
		(net "PVDDIO_P1")
	)
	(via
		(at 93.751146 -280.566368)
		(size 0.4064)
		(drill 0.2032)
		(layers "F.Cu" "B.Cu")
		(net "PVDDIO_P1")
	)
	(via
		(at 38.37051 -331.56652)
		(size 0.508)
		(drill 0.254)
		(layers "F.Cu" "B.Cu")
		(net "PVDDIO_P1")
	)
	(via
		(at 79.821024 -229.90429)
		(size 0.4064)
		(drill 0.2032)
		(layers "F.Cu" "B.Cu")
		(net "PVDDIO_P1")
	)
	(via
		(at 34.99231 -333.47152)
		(size 0.508)
		(drill 0.254)
		(layers "F.Cu" "B.Cu")
		(net "PVDDIO_P1")
	)
	(via
		(at 43.88231 -334.74152)
		(size 0.508)
		(drill 0.254)
		(layers "F.Cu" "B.Cu")
		(net "PVDDIO_P1")
	)
	(via
		(at 47.26051 -332.83652)
		(size 0.508)
		(drill 0.254)
		(layers "F.Cu" "B.Cu")
		(net "PVDDIO_P1")
	)
	(via
		(at 43.88231 -334.10652)
		(size 0.508)
		(drill 0.254)
		(layers "F.Cu" "B.Cu")
		(net "PVDDIO_P1")
	)
	(via
		(at 93.751146 -261.126224)
		(size 0.4064)
		(drill 0.2032)
		(layers "F.Cu" "B.Cu")
		(net "PVDDIO_P1")
	)
	(via
		(at 27.34691 -334.10652)
		(size 0.508)
		(drill 0.254)
		(layers "F.Cu" "B.Cu")
		(net "PVDDIO_P1")
	)
	(via
		(at 97.040954 -265.176254)
		(size 0.4064)
		(drill 0.2032)
		(layers "F.Cu" "B.Cu")
		(net "PVDDIO_P1")
	)
	(via
		(at 47.89551 -334.10652)
		(size 0.508)
		(drill 0.254)
		(layers "F.Cu" "B.Cu")
		(net "PVDDIO_P1")
	)
	(via
		(at 43.88231 -332.83652)
		(size 0.508)
		(drill 0.254)
		(layers "F.Cu" "B.Cu")
		(net "PVDDIO_P1")
	)
	(via
		(at 96.571054 -277.326344)
		(size 0.4064)
		(drill 0.2032)
		(layers "F.Cu" "B.Cu")
		(net "PVDDIO_P1")
	)
	(via
		(at 86.701122 -287.856422)
		(size 0.4064)
		(drill 0.2032)
		(layers "F.Cu" "B.Cu")
		(net "PVDDIO_P1")
	)
	(via
		(at 31.36011 -331.56652)
		(size 0.508)
		(drill 0.254)
		(layers "F.Cu" "B.Cu")
		(net "PVDDIO_P1")
	)
	(via
		(at 47.26051 -330.93152)
		(size 0.508)
		(drill 0.254)
		(layers "F.Cu" "B.Cu")
		(net "PVDDIO_P1")
	)
	(via
		(at 54.90591 -330.29652)
		(size 0.508)
		(drill 0.254)
		(layers "F.Cu" "B.Cu")
		(net "PVDDIO_P1")
	)
	(via
		(at 52.16271 -330.93152)
		(size 0.508)
		(drill 0.254)
		(layers "F.Cu" "B.Cu")
		(net "PVDDIO_P1")
	)
	(via
		(at 27.34691 -333.47152)
		(size 0.508)
		(drill 0.254)
		(layers "F.Cu" "B.Cu")
		(net "PVDDIO_P1")
	)
	(via
		(at 93.751146 -275.706332)
		(size 0.4064)
		(drill 0.2032)
		(layers "F.Cu" "B.Cu")
		(net "PVDDIO_P1")
	)
	(via
		(at 80.291178 -237.194344)
		(size 0.4064)
		(drill 0.2032)
		(layers "F.Cu" "B.Cu")
		(net "PVDDIO_P1")
	)
	(via
		(at 39.64051 -332.83652)
		(size 0.508)
		(drill 0.254)
		(layers "F.Cu" "B.Cu")
		(net "PVDDIO_P1")
	)
	(via
		(at 92.981018 -234.764326)
		(size 0.4064)
		(drill 0.2032)
		(layers "F.Cu" "B.Cu")
		(net "PVDDIO_P1")
	)
	(via
		(at 47.26051 -334.74152)
		(size 0.508)
		(drill 0.254)
		(layers "F.Cu" "B.Cu")
		(net "PVDDIO_P1")
	)
	(via
		(at 99.390962 -262.746236)
		(size 0.4064)
		(drill 0.2032)
		(layers "F.Cu" "B.Cu")
		(net "PVDDIO_P1")
	)
	(via
		(at 26.71191 -331.56652)
		(size 0.508)
		(drill 0.254)
		(layers "F.Cu" "B.Cu")
		(net "PVDDIO_P1")
	)
	(via
		(at 42.61231 -330.93152)
		(size 0.508)
		(drill 0.254)
		(layers "F.Cu" "B.Cu")
		(net "PVDDIO_P1")
	)
	(via
		(at 105.490772 -257.43027)
		(size 0.4826)
		(drill 0.254)
		(layers "F.Cu" "B.Cu")
		(net "PVDDIO_P1")
	)
	(via
		(at 30.09011 -334.10652)
		(size 0.508)
		(drill 0.254)
		(layers "F.Cu" "B.Cu")
		(net "PVDDIO_P1")
	)
	(via
		(at 46.62551 -334.74152)
		(size 0.508)
		(drill 0.254)
		(layers "F.Cu" "B.Cu")
		(net "PVDDIO_P1")
	)
	(via
		(at 51.52771 -332.83652)
		(size 0.508)
		(drill 0.254)
		(layers "F.Cu" "B.Cu")
		(net "PVDDIO_P1")
	)
	(via
		(at 52.16271 -333.47152)
		(size 0.508)
		(drill 0.254)
		(layers "F.Cu" "B.Cu")
		(net "PVDDIO_P1")
	)
	(via
		(at 30.72511 -332.83652)
		(size 0.508)
		(drill 0.254)
		(layers "F.Cu" "B.Cu")
		(net "PVDDIO_P1")
	)
	(via
		(at 43.24731 -333.47152)
		(size 0.508)
		(drill 0.254)
		(layers "F.Cu" "B.Cu")
		(net "PVDDIO_P1")
	)
	(via
		(at 50.89271 -334.74152)
		(size 0.508)
		(drill 0.254)
		(layers "F.Cu" "B.Cu")
		(net "PVDDIO_P1")
	)
	(via
		(at 54.90591 -332.20152)
		(size 0.508)
		(drill 0.254)
		(layers "F.Cu" "B.Cu")
		(net "PVDDIO_P1")
	)
	(via
		(at 51.52771 -333.47152)
		(size 0.508)
		(drill 0.254)
		(layers "F.Cu" "B.Cu")
		(net "PVDDIO_P1")
	)
	(via
		(at 101.940614 -257.930396)
		(size 0.4826)
		(drill 0.254)
		(layers "F.Cu" "B.Cu")
		(net "PVDDIO_P1")
	)
	(via
		(at 30.09011 -333.47152)
		(size 0.508)
		(drill 0.254)
		(layers "F.Cu" "B.Cu")
		(net "PVDDIO_P1")
	)
	(via
		(at 80.291178 -227.474526)
		(size 0.4064)
		(drill 0.2032)
		(layers "F.Cu" "B.Cu")
		(net "PVDDIO_P1")
	)
	(via
		(at 56.17591 -332.20152)
		(size 0.508)
		(drill 0.254)
		(layers "F.Cu" "B.Cu")
		(net "PVDDIO_P1")
	)
	(via
		(at 43.88231 -331.56652)
		(size 0.508)
		(drill 0.254)
		(layers "F.Cu" "B.Cu")
		(net "PVDDIO_P1")
	)
	(via
		(at 79.821024 -244.484398)
		(size 0.4064)
		(drill 0.2032)
		(layers "F.Cu" "B.Cu")
		(net "PVDDIO_P1")
	)
	(via
		(at 31.36011 -333.47152)
		(size 0.508)
		(drill 0.254)
		(layers "F.Cu" "B.Cu")
		(net "PVDDIO_P1")
	)
	(via
		(at 42.61231 -334.10652)
		(size 0.508)
		(drill 0.254)
		(layers "F.Cu" "B.Cu")
		(net "PVDDIO_P1")
	)
	(via
		(at 35.62731 -334.74152)
		(size 0.508)
		(drill 0.254)
		(layers "F.Cu" "B.Cu")
		(net "PVDDIO_P1")
	)
	(via
		(at 87.171022 -270.846296)
		(size 0.4064)
		(drill 0.2032)
		(layers "F.Cu" "B.Cu")
		(net "PVDDIO_P1")
	)
	(via
		(at 86.401148 -254.20447)
		(size 0.4064)
		(drill 0.2032)
		(layers "F.Cu" "B.Cu")
		(net "PVDDIO_P1")
	)
	(via
		(at 105.490772 -259.330444)
		(size 0.4826)
		(drill 0.254)
		(layers "F.Cu" "B.Cu")
		(net "PVDDIO_P1")
	)
	(via
		(at 93.280992 -263.556242)
		(size 0.4064)
		(drill 0.2032)
		(layers "F.Cu" "B.Cu")
		(net "PVDDIO_P1")
	)
	(via
		(at 97.040954 -261.93623)
		(size 0.4064)
		(drill 0.2032)
		(layers "F.Cu" "B.Cu")
		(net "PVDDIO_P1")
	)
	(via
		(at 100.80117 -261.93623)
		(size 0.4064)
		(drill 0.2032)
		(layers "F.Cu" "B.Cu")
		(net "PVDDIO_P1")
	)
	(via
		(at 56.17591 -334.74152)
		(size 0.508)
		(drill 0.254)
		(layers "F.Cu" "B.Cu")
		(net "PVDDIO_P1")
	)
	(via
		(at 55.54091 -330.29652)
		(size 0.508)
		(drill 0.254)
		(layers "F.Cu" "B.Cu")
		(net "PVDDIO_P1")
	)
	(via
		(at 93.450918 -251.774452)
		(size 0.4064)
		(drill 0.2032)
		(layers "F.Cu" "B.Cu")
		(net "PVDDIO_P1")
	)
	(via
		(at 80.591152 -270.846296)
		(size 0.4064)
		(drill 0.2032)
		(layers "F.Cu" "B.Cu")
		(net "PVDDIO_P1")
	)
	(via
		(at 52.28971 -329.53452)
		(size 0.6604)
		(drill 0.3302)
		(layers "F.Cu" "B.Cu")
		(net "PVDDIO_P1")
	)
	(via
		(at 42.61231 -333.47152)
		(size 0.508)
		(drill 0.254)
		(layers "F.Cu" "B.Cu")
		(net "PVDDIO_P1")
	)
	(via
		(at 50.89271 -331.56652)
		(size 0.508)
		(drill 0.254)
		(layers "F.Cu" "B.Cu")
		(net "PVDDIO_P1")
	)
	(via
		(at 100.80117 -265.176254)
		(size 0.4064)
		(drill 0.2032)
		(layers "F.Cu" "B.Cu")
		(net "PVDDIO_P1")
	)
	(via
		(at 51.52771 -330.93152)
		(size 0.508)
		(drill 0.254)
		(layers "F.Cu" "B.Cu")
		(net "PVDDIO_P1")
	)
	(via
		(at 26.71191 -332.20152)
		(size 0.508)
		(drill 0.254)
		(layers "F.Cu" "B.Cu")
		(net "PVDDIO_P1")
	)
	(via
		(at 52.16271 -334.74152)
		(size 0.508)
		(drill 0.254)
		(layers "F.Cu" "B.Cu")
		(net "PVDDIO_P1")
	)
	(via
		(at 26.71191 -330.29652)
		(size 0.508)
		(drill 0.254)
		(layers "F.Cu" "B.Cu")
		(net "PVDDIO_P1")
	)
	(via
		(at 105.490772 -260.280404)
		(size 0.4826)
		(drill 0.254)
		(layers "F.Cu" "B.Cu")
		(net "PVDDIO_P1")
	)
	(via
		(at 42.61231 -334.74152)
		(size 0.508)
		(drill 0.254)
		(layers "F.Cu" "B.Cu")
		(net "PVDDIO_P1")
	)
	(via
		(at 96.74098 -238.00435)
		(size 0.4064)
		(drill 0.2032)
		(layers "F.Cu" "B.Cu")
		(net "PVDDIO_P1")
	)
	(via
		(at 42.61231 -332.20152)
		(size 0.508)
		(drill 0.254)
		(layers "F.Cu" "B.Cu")
		(net "PVDDIO_P1")
	)
	(via
		(at 54.90591 -330.93152)
		(size 0.508)
		(drill 0.254)
		(layers "F.Cu" "B.Cu")
		(net "PVDDIO_P1")
	)
	(via
		(at 86.871048 -237.194344)
		(size 0.4064)
		(drill 0.2032)
		(layers "F.Cu" "B.Cu")
		(net "PVDDIO_P1")
	)
	(via
		(at 99.390962 -265.98626)
		(size 0.4064)
		(drill 0.2032)
		(layers "F.Cu" "B.Cu")
		(net "PVDDIO_P1")
	)
	(via
		(at 39.64051 -333.47152)
		(size 0.508)
		(drill 0.254)
		(layers "F.Cu" "B.Cu")
		(net "PVDDIO_P1")
	)
	(via
		(at 80.591152 -261.126224)
		(size 0.4064)
		(drill 0.2032)
		(layers "F.Cu" "B.Cu")
		(net "PVDDIO_P1")
	)
	(via
		(at 39.00551 -332.83652)
		(size 0.508)
		(drill 0.254)
		(layers "F.Cu" "B.Cu")
		(net "PVDDIO_P1")
	)
	(via
		(at 50.89271 -330.93152)
		(size 0.508)
		(drill 0.254)
		(layers "F.Cu" "B.Cu")
		(net "PVDDIO_P1")
	)
	(via
		(at 43.24731 -334.10652)
		(size 0.508)
		(drill 0.254)
		(layers "F.Cu" "B.Cu")
		(net "PVDDIO_P1")
	)
	(via
		(at 80.120998 -292.716204)
		(size 0.4064)
		(drill 0.2032)
		(layers "F.Cu" "B.Cu")
		(net "PVDDIO_P1")
	)
	(via
		(at 56.17591 -332.83652)
		(size 0.508)
		(drill 0.254)
		(layers "F.Cu" "B.Cu")
		(net "PVDDIO_P1")
	)
	(via
		(at 38.37051 -332.83652)
		(size 0.508)
		(drill 0.254)
		(layers "F.Cu" "B.Cu")
		(net "PVDDIO_P1")
	)
	(via
		(at 93.280992 -273.276314)
		(size 0.4064)
		(drill 0.2032)
		(layers "F.Cu" "B.Cu")
		(net "PVDDIO_P1")
	)
	(via
		(at 43.88231 -333.47152)
		(size 0.508)
		(drill 0.254)
		(layers "F.Cu" "B.Cu")
		(net "PVDDIO_P1")
	)
	(via
		(at 93.450918 -246.914416)
		(size 0.4064)
		(drill 0.2032)
		(layers "F.Cu" "B.Cu")
		(net "PVDDIO_P1")
	)
	(segment
		(start 41.525444 -349.786448)
		(end 41.525444 -350.14535)
		(width 0.381)
		(layer "B.Cu")
		(net "PVDDIO_P1")
	)
	(segment
		(start 49.882044 -349.786448)
		(end 49.882044 -350.14535)
		(width 0.381)
		(layer "B.Cu")
		(net "PVDDIO_P1")
	)
	(segment
		(start 24.939244 -349.786448)
		(end 24.939244 -350.14535)
		(width 0.381)
		(layer "B.Cu")
		(net "PVDDIO_P1")
	)
	(segment
		(start 33.219644 -349.786448)
		(end 33.219644 -350.14535)
		(width 0.381)
		(layer "B.Cu")
		(net "PVDDIO_P1")
	)
	(segment
		(start 49.882044 -350.14535)
		(end 50.239676 -350.502982)
		(width 0.381)
		(layer "B.Cu")
		(net "PVDDIO_P1")
	)
	(segment
		(start 33.219644 -350.14535)
		(end 33.577276 -350.502982)
		(width 0.381)
		(layer "B.Cu")
		(net "PVDDIO_P1")
	)
	(segment
		(start 41.525444 -350.14535)
		(end 41.883076 -350.502982)
		(width 0.381)
		(layer "B.Cu")
		(net "PVDDIO_P1")
	)
	(segment
		(start 24.939244 -350.14535)
		(end 25.296876 -350.502982)
		(width 0.381)
		(layer "B.Cu")
		(net "PVDDIO_P1")
	)
	(segment
		(start 49.948338 -349.37192)
		(end 49.948338 -350.211644)
		(width 0.381)
		(layer "In2.Cu")
		(net "PVDDIO_P1")
	)
	(segment
		(start 49.948338 -350.211644)
		(end 50.239676 -350.502982)
		(width 0.381)
		(layer "In2.Cu")
		(net "PVDDIO_P1")
	)
	(segment
		(start 34.356294 -348.276164)
		(end 33.300162 -349.332296)
		(width 0.381)
		(layer "In2.Cu")
		(net "PVDDIO_P1")
	)
	(segment
		(start 50.89271 -334.74152)
		(end 50.89271 -335.250536)
		(width 0.381)
		(layer "In2.Cu")
		(net "PVDDIO_P1")
	)
	(segment
		(start 42.662094 -348.326964)
		(end 41.591738 -349.39732)
		(width 0.381)
		(layer "In2.Cu")
		(net "PVDDIO_P1")
	)
	(segment
		(start 26.07691 -334.74152)
		(end 26.075894 -334.742536)
		(width 0.381)
		(layer "In2.Cu")
		(net "PVDDIO_P1")
	)
	(segment
		(start 50.89271 -335.250536)
		(end 51.018694 -335.37652)
		(width 0.381)
		(layer "In2.Cu")
		(net "PVDDIO_P1")
	)
	(segment
		(start 51.018694 -348.301564)
		(end 49.948338 -349.37192)
		(width 0.381)
		(layer "In2.Cu")
		(net "PVDDIO_P1")
	)
	(segment
		(start 26.075894 -334.742536)
		(end 26.075894 -348.301564)
		(width 0.381)
		(layer "In2.Cu")
		(net "PVDDIO_P1")
	)
	(segment
		(start 42.662094 -334.791304)
		(end 42.662094 -348.326964)
		(width 0.381)
		(layer "In2.Cu")
		(net "PVDDIO_P1")
	)
	(segment
		(start 51.018694 -335.37652)
		(end 51.018694 -348.301564)
		(width 0.381)
		(layer "In2.Cu")
		(net "PVDDIO_P1")
	)
	(segment
		(start 24.980138 -350.186244)
		(end 25.296876 -350.502982)
		(width 0.381)
		(layer "In2.Cu")
		(net "PVDDIO_P1")
	)
	(segment
		(start 26.075894 -348.301564)
		(end 24.980138 -349.39732)
		(width 0.381)
		(layer "In2.Cu")
		(net "PVDDIO_P1")
	)
	(segment
		(start 33.300162 -349.332296)
		(end 33.300162 -350.225868)
		(width 0.381)
		(layer "In2.Cu")
		(net "PVDDIO_P1")
	)
	(segment
		(start 24.980138 -349.39732)
		(end 24.980138 -350.186244)
		(width 0.381)
		(layer "In2.Cu")
		(net "PVDDIO_P1")
	)
	(segment
		(start 41.591738 -350.211644)
		(end 41.883076 -350.502982)
		(width 0.381)
		(layer "In2.Cu")
		(net "PVDDIO_P1")
	)
	(segment
		(start 33.300162 -350.225868)
		(end 33.577276 -350.502982)
		(width 0.381)
		(layer "In2.Cu")
		(net "PVDDIO_P1")
	)
	(segment
		(start 34.356294 -334.742536)
		(end 34.356294 -348.276164)
		(width 0.381)
		(layer "In2.Cu")
		(net "PVDDIO_P1")
	)
	(segment
		(start 41.591738 -349.39732)
		(end 41.591738 -350.211644)
		(width 0.381)
		(layer "In2.Cu")
		(net "PVDDIO_P1")
	)
	(segment
		(start 42.61231 -334.74152)
		(end 42.662094 -334.791304)
		(width 0.381)
		(layer "In2.Cu")
		(net "PVDDIO_P1")
	)
	(segment
		(start 34.35731 -334.74152)
		(end 34.356294 -334.742536)
		(width 0.381)
		(layer "In2.Cu")
		(net "PVDDIO_P1")
	)
	(segment
		(start 273.02206 -349.278194)
		(end 273.02206 -348.991428)
		(width 0.2032)
		(layer "F.Cu")
		(net "PVDDIO_P0_VOS4")
	)
	(segment
		(start 272.697448 -349.602806)
		(end 273.02206 -349.278194)
		(width 0.2032)
		(layer "F.Cu")
		(net "PVDDIO_P0_VOS4")
	)
	(via
		(at 272.697448 -349.602806)
		(size 0.508)
		(drill 0.254)
		(layers "F.Cu" "B.Cu")
		(net "PVDDIO_P0_VOS4")
	)
	(segment
		(start 271.760696 -348.981522)
		(end 272.076164 -348.981522)
		(width 0.2286)
		(layer "B.Cu")
		(net "PVDDIO_P0_VOS4")
	)
	(segment
		(start 272.076164 -348.981522)
		(end 272.697448 -349.602806)
		(width 0.2286)
		(layer "B.Cu")
		(net "PVDDIO_P0_VOS4")
	)
	(segment
		(start 281.30246 -349.278194)
		(end 281.30246 -348.991428)
		(width 0.2032)
		(layer "F.Cu")
		(net "PVDDIO_P0_VOS3")
	)
	(segment
		(start 280.977848 -349.602806)
		(end 281.30246 -349.278194)
		(width 0.2032)
		(layer "F.Cu")
		(net "PVDDIO_P0_VOS3")
	)
	(via
		(at 280.977848 -349.602806)
		(size 0.508)
		(drill 0.254)
		(layers "F.Cu" "B.Cu")
		(net "PVDDIO_P0_VOS3")
	)
	(segment
		(start 280.041096 -348.981522)
		(end 280.356564 -348.981522)
		(width 0.2286)
		(layer "B.Cu")
		(net "PVDDIO_P0_VOS3")
	)
	(segment
		(start 280.356564 -348.981522)
		(end 280.977848 -349.602806)
		(width 0.2286)
		(layer "B.Cu")
		(net "PVDDIO_P0_VOS3")
	)
	(segment
		(start 289.283648 -349.602806)
		(end 289.60826 -349.278194)
		(width 0.2032)
		(layer "F.Cu")
		(net "PVDDIO_P0_VOS2")
	)
	(segment
		(start 289.60826 -349.278194)
		(end 289.60826 -348.991428)
		(width 0.2032)
		(layer "F.Cu")
		(net "PVDDIO_P0_VOS2")
	)
	(via
		(at 289.283648 -349.602806)
		(size 0.508)
		(drill 0.254)
		(layers "F.Cu" "B.Cu")
		(net "PVDDIO_P0_VOS2")
	)
	(segment
		(start 288.662364 -348.981522)
		(end 289.283648 -349.602806)
		(width 0.2286)
		(layer "B.Cu")
		(net "PVDDIO_P0_VOS2")
	)
	(segment
		(start 288.346896 -348.981522)
		(end 288.662364 -348.981522)
		(width 0.2286)
		(layer "B.Cu")
		(net "PVDDIO_P0_VOS2")
	)
	(segment
		(start 297.640248 -349.602806)
		(end 297.96486 -349.278194)
		(width 0.2032)
		(layer "F.Cu")
		(net "PVDDIO_P0_VOS1")
	)
	(segment
		(start 297.96486 -349.278194)
		(end 297.96486 -348.991428)
		(width 0.2032)
		(layer "F.Cu")
		(net "PVDDIO_P0_VOS1")
	)
	(via
		(at 297.640248 -349.602806)
		(size 0.508)
		(drill 0.254)
		(layers "F.Cu" "B.Cu")
		(net "PVDDIO_P0_VOS1")
	)
	(segment
		(start 296.703496 -348.981522)
		(end 297.018964 -348.981522)
		(width 0.2286)
		(layer "B.Cu")
		(net "PVDDIO_P0_VOS1")
	)
	(segment
		(start 297.018964 -348.981522)
		(end 297.640248 -349.602806)
		(width 0.2286)
		(layer "B.Cu")
		(net "PVDDIO_P0_VOS1")
	)
	(segment
		(start 275.156422 -350.403922)
		(end 275.232114 -350.32823)
		(width 0.2286)
		(layer "F.Cu")
		(net "PVDDIO_P0_VCC4")
	)
	(segment
		(start 272.091404 -348.37116)
		(end 272.371312 -348.091252)
		(width 0.2286)
		(layer "F.Cu")
		(net "PVDDIO_P0_VCC4")
	)
	(segment
		(start 275.232114 -350.32823)
		(end 275.232114 -349.616268)
		(width 0.2286)
		(layer "F.Cu")
		(net "PVDDIO_P0_VCC4")
	)
	(segment
		(start 272.371312 -348.091252)
		(end 273.02206 -348.091252)
		(width 0.2286)
		(layer "F.Cu")
		(net "PVDDIO_P0_VCC4")
	)
	(segment
		(start 271.739106 -348.37116)
		(end 272.091404 -348.37116)
		(width 0.2286)
		(layer "F.Cu")
		(net "PVDDIO_P0_VCC4")
	)
	(segment
		(start 271.739106 -348.981522)
		(end 271.739106 -348.37116)
		(width 0.4572)
		(layer "F.Cu")
		(net "PVDDIO_P0_VCC4")
	)
	(via
		(at 273.566636 -349.485458)
		(size 0.6604)
		(drill 0.3302)
		(layers "F.Cu" "B.Cu")
		(net "PVDDIO_P0_VCC4")
	)
	(via
		(at 275.156422 -350.403922)
		(size 0.508)
		(drill 0.254)
		(layers "F.Cu" "B.Cu")
		(net "PVDDIO_P0_VCC4")
	)
	(via
		(at 271.739106 -348.37116)
		(size 0.508)
		(drill 0.254)
		(layers "F.Cu" "B.Cu")
		(net "PVDDIO_P0_VCC4")
	)
	(segment
		(start 275.156422 -350.403922)
		(end 274.657058 -349.904558)
		(width 0.4572)
		(layer "B.Cu")
		(net "PVDDIO_P0_VCC4")
	)
	(segment
		(start 273.111214 -349.030036)
		(end 273.111214 -348.17558)
		(width 0.381)
		(layer "B.Cu")
		(net "PVDDIO_P0_VCC4")
	)
	(segment
		(start 273.566636 -349.485458)
		(end 273.111214 -349.030036)
		(width 0.381)
		(layer "B.Cu")
		(net "PVDDIO_P0_VCC4")
	)
	(segment
		(start 272.405856 -348.37116)
		(end 272.601436 -348.17558)
		(width 0.381)
		(layer "B.Cu")
		(net "PVDDIO_P0_VCC4")
	)
	(segment
		(start 273.566636 -349.591122)
		(end 273.566636 -349.485458)
		(width 0.381)
		(layer "B.Cu")
		(net "PVDDIO_P0_VCC4")
	)
	(segment
		(start 273.880072 -349.904558)
		(end 273.566636 -349.591122)
		(width 0.4572)
		(layer "B.Cu")
		(net "PVDDIO_P0_VCC4")
	)
	(segment
		(start 274.657058 -349.904558)
		(end 273.880072 -349.904558)
		(width 0.4572)
		(layer "B.Cu")
		(net "PVDDIO_P0_VCC4")
	)
	(segment
		(start 271.739106 -348.37116)
		(end 272.405856 -348.37116)
		(width 0.381)
		(layer "B.Cu")
		(net "PVDDIO_P0_VCC4")
	)
	(segment
		(start 272.601436 -348.17558)
		(end 273.111214 -348.17558)
		(width 0.381)
		(layer "B.Cu")
		(net "PVDDIO_P0_VCC4")
	)
	(segment
		(start 283.436822 -350.403922)
		(end 283.512514 -350.32823)
		(width 0.2286)
		(layer "F.Cu")
		(net "PVDDIO_P0_VCC3")
	)
	(segment
		(start 280.651712 -348.091252)
		(end 281.30246 -348.091252)
		(width 0.2286)
		(layer "F.Cu")
		(net "PVDDIO_P0_VCC3")
	)
	(segment
		(start 283.512514 -350.32823)
		(end 283.512514 -349.616268)
		(width 0.2286)
		(layer "F.Cu")
		(net "PVDDIO_P0_VCC3")
	)
	(segment
		(start 280.371804 -348.37116)
		(end 280.651712 -348.091252)
		(width 0.2286)
		(layer "F.Cu")
		(net "PVDDIO_P0_VCC3")
	)
	(segment
		(start 280.019506 -348.981522)
		(end 280.019506 -348.37116)
		(width 0.4572)
		(layer "F.Cu")
		(net "PVDDIO_P0_VCC3")
	)
	(segment
		(start 280.019506 -348.37116)
		(end 280.371804 -348.37116)
		(width 0.2286)
		(layer "F.Cu")
		(net "PVDDIO_P0_VCC3")
	)
	(via
		(at 280.019506 -348.37116)
		(size 0.508)
		(drill 0.254)
		(layers "F.Cu" "B.Cu")
		(net "PVDDIO_P0_VCC3")
	)
	(via
		(at 283.436822 -350.403922)
		(size 0.508)
		(drill 0.254)
		(layers "F.Cu" "B.Cu")
		(net "PVDDIO_P0_VCC3")
	)
	(via
		(at 281.847036 -349.485458)
		(size 0.6604)
		(drill 0.3302)
		(layers "F.Cu" "B.Cu")
		(net "PVDDIO_P0_VCC3")
	)
	(segment
		(start 281.847036 -349.591122)
		(end 281.847036 -349.485458)
		(width 0.381)
		(layer "B.Cu")
		(net "PVDDIO_P0_VCC3")
	)
	(segment
		(start 282.160472 -349.904558)
		(end 281.847036 -349.591122)
		(width 0.4572)
		(layer "B.Cu")
		(net "PVDDIO_P0_VCC3")
	)
	(segment
		(start 282.937458 -349.904558)
		(end 282.160472 -349.904558)
		(width 0.4572)
		(layer "B.Cu")
		(net "PVDDIO_P0_VCC3")
	)
	(segment
		(start 281.847036 -349.485458)
		(end 281.391614 -349.030036)
		(width 0.381)
		(layer "B.Cu")
		(net "PVDDIO_P0_VCC3")
	)
	(segment
		(start 280.686256 -348.37116)
		(end 280.881836 -348.17558)
		(width 0.381)
		(layer "B.Cu")
		(net "PVDDIO_P0_VCC3")
	)
	(segment
		(start 283.436822 -350.403922)
		(end 282.937458 -349.904558)
		(width 0.4572)
		(layer "B.Cu")
		(net "PVDDIO_P0_VCC3")
	)
	(segment
		(start 281.391614 -349.030036)
		(end 281.391614 -348.17558)
		(width 0.381)
		(layer "B.Cu")
		(net "PVDDIO_P0_VCC3")
	)
	(segment
		(start 280.881836 -348.17558)
		(end 281.391614 -348.17558)
		(width 0.381)
		(layer "B.Cu")
		(net "PVDDIO_P0_VCC3")
	)
	(segment
		(start 280.019506 -348.37116)
		(end 280.686256 -348.37116)
		(width 0.381)
		(layer "B.Cu")
		(net "PVDDIO_P0_VCC3")
	)
	(segment
		(start 288.957512 -348.091252)
		(end 289.60826 -348.091252)
		(width 0.2286)
		(layer "F.Cu")
		(net "PVDDIO_P0_VCC2")
	)
	(segment
		(start 288.325306 -348.37116)
		(end 288.677604 -348.37116)
		(width 0.2286)
		(layer "F.Cu")
		(net "PVDDIO_P0_VCC2")
	)
	(segment
		(start 291.818314 -350.32823)
		(end 291.818314 -349.616268)
		(width 0.2286)
		(layer "F.Cu")
		(net "PVDDIO_P0_VCC2")
	)
	(segment
		(start 288.325306 -348.981522)
		(end 288.325306 -348.37116)
		(width 0.4572)
		(layer "F.Cu")
		(net "PVDDIO_P0_VCC2")
	)
	(segment
		(start 291.742622 -350.403922)
		(end 291.818314 -350.32823)
		(width 0.2286)
		(layer "F.Cu")
		(net "PVDDIO_P0_VCC2")
	)
	(segment
		(start 288.677604 -348.37116)
		(end 288.957512 -348.091252)
		(width 0.2286)
		(layer "F.Cu")
		(net "PVDDIO_P0_VCC2")
	)
	(via
		(at 290.152836 -349.485458)
		(size 0.6604)
		(drill 0.3302)
		(layers "F.Cu" "B.Cu")
		(net "PVDDIO_P0_VCC2")
	)
	(via
		(at 288.325306 -348.37116)
		(size 0.508)
		(drill 0.254)
		(layers "F.Cu" "B.Cu")
		(net "PVDDIO_P0_VCC2")
	)
	(via
		(at 291.742622 -350.403922)
		(size 0.508)
		(drill 0.254)
		(layers "F.Cu" "B.Cu")
		(net "PVDDIO_P0_VCC2")
	)
	(segment
		(start 290.152836 -349.591122)
		(end 290.466272 -349.904558)
		(width 0.4572)
		(layer "B.Cu")
		(net "PVDDIO_P0_VCC2")
	)
	(segment
		(start 288.325306 -348.37116)
		(end 288.992056 -348.37116)
		(width 0.381)
		(layer "B.Cu")
		(net "PVDDIO_P0_VCC2")
	)
	(segment
		(start 290.152836 -349.485458)
		(end 290.152836 -349.591122)
		(width 0.381)
		(layer "B.Cu")
		(net "PVDDIO_P0_VCC2")
	)
	(segment
		(start 288.992056 -348.37116)
		(end 289.187636 -348.17558)
		(width 0.381)
		(layer "B.Cu")
		(net "PVDDIO_P0_VCC2")
	)
	(segment
		(start 289.697414 -349.030036)
		(end 290.152836 -349.485458)
		(width 0.381)
		(layer "B.Cu")
		(net "PVDDIO_P0_VCC2")
	)
	(segment
		(start 289.697414 -348.17558)
		(end 289.697414 -349.030036)
		(width 0.381)
		(layer "B.Cu")
		(net "PVDDIO_P0_VCC2")
	)
	(segment
		(start 290.466272 -349.904558)
		(end 291.243258 -349.904558)
		(width 0.4572)
		(layer "B.Cu")
		(net "PVDDIO_P0_VCC2")
	)
	(segment
		(start 289.187636 -348.17558)
		(end 289.697414 -348.17558)
		(width 0.381)
		(layer "B.Cu")
		(net "PVDDIO_P0_VCC2")
	)
	(segment
		(start 291.243258 -349.904558)
		(end 291.742622 -350.403922)
		(width 0.4572)
		(layer "B.Cu")
		(net "PVDDIO_P0_VCC2")
	)
	(segment
		(start 300.099222 -350.403922)
		(end 300.174914 -350.32823)
		(width 0.2286)
		(layer "F.Cu")
		(net "PVDDIO_P0_VCC1")
	)
	(segment
		(start 296.681906 -348.37116)
		(end 297.034204 -348.37116)
		(width 0.2286)
		(layer "F.Cu")
		(net "PVDDIO_P0_VCC1")
	)
	(segment
		(start 296.681906 -348.981522)
		(end 296.681906 -348.37116)
		(width 0.4572)
		(layer "F.Cu")
		(net "PVDDIO_P0_VCC1")
	)
	(segment
		(start 297.314112 -348.091252)
		(end 297.96486 -348.091252)
		(width 0.2286)
		(layer "F.Cu")
		(net "PVDDIO_P0_VCC1")
	)
	(segment
		(start 300.174914 -350.32823)
		(end 300.174914 -349.616268)
		(width 0.2286)
		(layer "F.Cu")
		(net "PVDDIO_P0_VCC1")
	)
	(segment
		(start 297.034204 -348.37116)
		(end 297.314112 -348.091252)
		(width 0.2286)
		(layer "F.Cu")
		(net "PVDDIO_P0_VCC1")
	)
	(via
		(at 296.681906 -348.37116)
		(size 0.508)
		(drill 0.254)
		(layers "F.Cu" "B.Cu")
		(net "PVDDIO_P0_VCC1")
	)
	(via
		(at 300.099222 -350.403922)
		(size 0.508)
		(drill 0.254)
		(layers "F.Cu" "B.Cu")
		(net "PVDDIO_P0_VCC1")
	)
	(via
		(at 298.509436 -349.485458)
		(size 0.6604)
		(drill 0.3302)
		(layers "F.Cu" "B.Cu")
		(net "PVDDIO_P0_VCC1")
	)
	(segment
		(start 297.348656 -348.37116)
		(end 297.544236 -348.17558)
		(width 0.381)
		(layer "B.Cu")
		(net "PVDDIO_P0_VCC1")
	)
	(segment
		(start 298.054014 -349.030036)
		(end 298.509436 -349.485458)
		(width 0.381)
		(layer "B.Cu")
		(net "PVDDIO_P0_VCC1")
	)
	(segment
		(start 298.509436 -349.591122)
		(end 298.822872 -349.904558)
		(width 0.4572)
		(layer "B.Cu")
		(net "PVDDIO_P0_VCC1")
	)
	(segment
		(start 296.681906 -348.37116)
		(end 297.348656 -348.37116)
		(width 0.381)
		(layer "B.Cu")
		(net "PVDDIO_P0_VCC1")
	)
	(segment
		(start 297.544236 -348.17558)
		(end 298.054014 -348.17558)
		(width 0.381)
		(layer "B.Cu")
		(net "PVDDIO_P0_VCC1")
	)
	(segment
		(start 299.599858 -349.904558)
		(end 300.099222 -350.403922)
		(width 0.4572)
		(layer "B.Cu")
		(net "PVDDIO_P0_VCC1")
	)
	(segment
		(start 298.054014 -348.17558)
		(end 298.054014 -349.030036)
		(width 0.381)
		(layer "B.Cu")
		(net "PVDDIO_P0_VCC1")
	)
	(segment
		(start 298.822872 -349.904558)
		(end 299.599858 -349.904558)
		(width 0.4572)
		(layer "B.Cu")
		(net "PVDDIO_P0_VCC1")
	)
	(segment
		(start 298.509436 -349.485458)
		(end 298.509436 -349.591122)
		(width 0.381)
		(layer "B.Cu")
		(net "PVDDIO_P0_VCC1")
	)
	(segment
		(start 283.062426 -350.025208)
		(end 283.062426 -349.616268)
		(width 0.2286)
		(layer "F.Cu")
		(net "PVDDIO_P0_TEMP1")
	)
	(segment
		(start 314.176918 -360.879898)
		(end 313.009026 -360.879898)
		(width 0.1778)
		(layer "F.Cu")
		(net "PVDDIO_P0_TEMP1")
	)
	(segment
		(start 315.402468 -360.289348)
		(end 314.767468 -360.289348)
		(width 0.1778)
		(layer "F.Cu")
		(net "PVDDIO_P0_TEMP1")
	)
	(segment
		(start 274.782026 -349.616268)
		(end 274.782026 -350.035876)
		(width 0.2286)
		(layer "F.Cu")
		(net "PVDDIO_P0_TEMP1")
	)
	(segment
		(start 274.46097 -350.356932)
		(end 274.46097 -350.649794)
		(width 0.2286)
		(layer "F.Cu")
		(net "PVDDIO_P0_TEMP1")
	)
	(segment
		(start 299.724826 -350.03232)
		(end 299.724826 -349.616268)
		(width 0.2286)
		(layer "F.Cu")
		(net "PVDDIO_P0_TEMP1")
	)
	(segment
		(start 299.40377 -350.649794)
		(end 299.40377 -350.353376)
		(width 0.2286)
		(layer "F.Cu")
		(net "PVDDIO_P0_TEMP1")
	)
	(segment
		(start 291.04717 -350.649794)
		(end 291.04717 -350.355408)
		(width 0.2286)
		(layer "F.Cu")
		(net "PVDDIO_P0_TEMP1")
	)
	(segment
		(start 282.74137 -350.346264)
		(end 283.062426 -350.025208)
		(width 0.2286)
		(layer "F.Cu")
		(net "PVDDIO_P0_TEMP1")
	)
	(segment
		(start 291.04717 -350.355408)
		(end 291.368226 -350.034352)
		(width 0.2286)
		(layer "F.Cu")
		(net "PVDDIO_P0_TEMP1")
	)
	(segment
		(start 314.767468 -360.289348)
		(end 314.176918 -360.879898)
		(width 0.1778)
		(layer "F.Cu")
		(net "PVDDIO_P0_TEMP1")
	)
	(segment
		(start 274.782026 -350.035876)
		(end 274.46097 -350.356932)
		(width 0.2286)
		(layer "F.Cu")
		(net "PVDDIO_P0_TEMP1")
	)
	(segment
		(start 282.74137 -350.649794)
		(end 282.74137 -350.346264)
		(width 0.2286)
		(layer "F.Cu")
		(net "PVDDIO_P0_TEMP1")
	)
	(segment
		(start 299.40377 -350.353376)
		(end 299.724826 -350.03232)
		(width 0.2286)
		(layer "F.Cu")
		(net "PVDDIO_P0_TEMP1")
	)
	(segment
		(start 291.368226 -350.034352)
		(end 291.368226 -349.616268)
		(width 0.2286)
		(layer "F.Cu")
		(net "PVDDIO_P0_TEMP1")
	)
	(via
		(at 291.04717 -350.649794)
		(size 0.508)
		(drill 0.254)
		(layers "F.Cu" "B.Cu")
		(net "PVDDIO_P0_TEMP1")
	)
	(via
		(at 314.767468 -360.289348)
		(size 0.508)
		(drill 0.254)
		(layers "F.Cu" "B.Cu")
		(net "PVDDIO_P0_TEMP1")
	)
	(via
		(at 299.40377 -350.649794)
		(size 0.508)
		(drill 0.254)
		(layers "F.Cu" "B.Cu")
		(net "PVDDIO_P0_TEMP1")
	)
	(via
		(at 274.46097 -350.649794)
		(size 0.508)
		(drill 0.254)
		(layers "F.Cu" "B.Cu")
		(net "PVDDIO_P0_TEMP1")
	)
	(via
		(at 282.74137 -350.649794)
		(size 0.508)
		(drill 0.254)
		(layers "F.Cu" "B.Cu")
		(net "PVDDIO_P0_TEMP1")
	)
	(segment
		(start 282.74137 -350.649794)
		(end 282.74137 -352.049334)
		(width 0.254)
		(layer "In2.Cu")
		(net "PVDDIO_P0_TEMP1")
	)
	(segment
		(start 308.1528 -358.1908)
		(end 313.220608 -358.1908)
		(width 0.254)
		(layer "In2.Cu")
		(net "PVDDIO_P0_TEMP1")
	)
	(segment
		(start 275.068538 -352.7679)
		(end 274.46097 -352.160332)
		(width 0.254)
		(layer "In2.Cu")
		(net "PVDDIO_P0_TEMP1")
	)
	(segment
		(start 299.40377 -351.95383)
		(end 298.6151 -352.7425)
		(width 0.254)
		(layer "In2.Cu")
		(net "PVDDIO_P0_TEMP1")
	)
	(segment
		(start 282.022804 -352.7679)
		(end 275.068538 -352.7679)
		(width 0.254)
		(layer "In2.Cu")
		(net "PVDDIO_P0_TEMP1")
	)
	(segment
		(start 274.46097 -352.160332)
		(end 274.46097 -350.649794)
		(width 0.254)
		(layer "In2.Cu")
		(net "PVDDIO_P0_TEMP1")
	)
	(segment
		(start 299.40377 -350.649794)
		(end 299.40377 -351.95383)
		(width 0.254)
		(layer "In2.Cu")
		(net "PVDDIO_P0_TEMP1")
	)
	(segment
		(start 298.6151 -352.7425)
		(end 291.667184 -352.7425)
		(width 0.254)
		(layer "In2.Cu")
		(net "PVDDIO_P0_TEMP1")
	)
	(segment
		(start 291.04717 -352.122486)
		(end 291.04717 -350.649794)
		(width 0.254)
		(layer "In2.Cu")
		(net "PVDDIO_P0_TEMP1")
	)
	(segment
		(start 282.74137 -352.049334)
		(end 282.022804 -352.7679)
		(width 0.254)
		(layer "In2.Cu")
		(net "PVDDIO_P0_TEMP1")
	)
	(segment
		(start 299.40377 -351.95383)
		(end 300.02734 -352.5774)
		(width 0.254)
		(layer "In2.Cu")
		(net "PVDDIO_P0_TEMP1")
	)
	(segment
		(start 291.04717 -352.122486)
		(end 290.401756 -352.7679)
		(width 0.254)
		(layer "In2.Cu")
		(net "PVDDIO_P0_TEMP1")
	)
	(segment
		(start 313.220608 -358.1908)
		(end 314.767468 -359.73766)
		(width 0.254)
		(layer "In2.Cu")
		(net "PVDDIO_P0_TEMP1")
	)
	(segment
		(start 314.767468 -359.73766)
		(end 314.767468 -360.289348)
		(width 0.254)
		(layer "In2.Cu")
		(net "PVDDIO_P0_TEMP1")
	)
	(segment
		(start 290.401756 -352.7679)
		(end 283.459936 -352.7679)
		(width 0.254)
		(layer "In2.Cu")
		(net "PVDDIO_P0_TEMP1")
	)
	(segment
		(start 291.667184 -352.7425)
		(end 291.04717 -352.122486)
		(width 0.254)
		(layer "In2.Cu")
		(net "PVDDIO_P0_TEMP1")
	)
	(segment
		(start 302.5394 -352.5774)
		(end 308.1528 -358.1908)
		(width 0.254)
		(layer "In2.Cu")
		(net "PVDDIO_P0_TEMP1")
	)
	(segment
		(start 300.02734 -352.5774)
		(end 302.5394 -352.5774)
		(width 0.254)
		(layer "In2.Cu")
		(net "PVDDIO_P0_TEMP1")
	)
	(segment
		(start 283.459936 -352.7679)
		(end 282.74137 -352.049334)
		(width 0.254)
		(layer "In2.Cu")
		(net "PVDDIO_P0_TEMP1")
	)
	(segment
		(start 309.9308 -368.0714)
		(end 309.9308 -366.88268)
		(width 0.1524)
		(layer "F.Cu")
		(net "PVDDIO_P0_PWM4")
	)
	(segment
		(start 275.346922 -351.056194)
		(end 275.682202 -350.720914)
		(width 0.1778)
		(layer "F.Cu")
		(net "PVDDIO_P0_PWM4")
	)
	(segment
		(start 310.95442 -365.85906)
		(end 311.133998 -365.425228)
		(width 0.1524)
		(layer "F.Cu")
		(net "PVDDIO_P0_PWM4")
	)
	(segment
		(start 275.682202 -350.720914)
		(end 275.682202 -349.616268)
		(width 0.1778)
		(layer "F.Cu")
		(net "PVDDIO_P0_PWM4")
	)
	(segment
		(start 311.133998 -365.425228)
		(end 311.133998 -363.555026)
		(width 0.1524)
		(layer "F.Cu")
		(net "PVDDIO_P0_PWM4")
	)
	(segment
		(start 309.9308 -366.88268)
		(end 310.95442 -365.85906)
		(width 0.1524)
		(layer "F.Cu")
		(net "PVDDIO_P0_PWM4")
	)
	(via
		(at 275.346922 -351.056194)
		(size 0.508)
		(drill 0.254)
		(layers "F.Cu" "B.Cu")
		(net "PVDDIO_P0_PWM4")
	)
	(via
		(at 309.9308 -368.0714)
		(size 0.508)
		(drill 0.254)
		(layers "F.Cu" "B.Cu")
		(net "PVDDIO_P0_PWM4")
	)
	(segment
		(start 309.2704 -368.7318)
		(end 305.5366 -368.7318)
		(width 0.1524)
		(layer "In4.Cu")
		(net "PVDDIO_P0_PWM4")
	)
	(segment
		(start 309.9308 -368.0714)
		(end 309.2704 -368.7318)
		(width 0.1524)
		(layer "In4.Cu")
		(net "PVDDIO_P0_PWM4")
	)
	(segment
		(start 301.371254 -369.951)
		(end 297.939206 -366.518952)
		(width 0.1524)
		(layer "In4.Cu")
		(net "PVDDIO_P0_PWM4")
	)
	(segment
		(start 304.3174 -369.951)
		(end 301.371254 -369.951)
		(width 0.1524)
		(layer "In4.Cu")
		(net "PVDDIO_P0_PWM4")
	)
	(segment
		(start 276.11197 -351.821242)
		(end 275.346922 -351.056194)
		(width 0.1524)
		(layer "In4.Cu")
		(net "PVDDIO_P0_PWM4")
	)
	(segment
		(start 297.939206 -366.518952)
		(end 284.36189 -366.518952)
		(width 0.1524)
		(layer "In4.Cu")
		(net "PVDDIO_P0_PWM4")
	)
	(segment
		(start 284.36189 -366.518952)
		(end 276.11197 -358.269032)
		(width 0.1524)
		(layer "In4.Cu")
		(net "PVDDIO_P0_PWM4")
	)
	(segment
		(start 276.11197 -358.269032)
		(end 276.11197 -351.821242)
		(width 0.1524)
		(layer "In4.Cu")
		(net "PVDDIO_P0_PWM4")
	)
	(segment
		(start 305.5366 -368.7318)
		(end 304.3174 -369.951)
		(width 0.1524)
		(layer "In4.Cu")
		(net "PVDDIO_P0_PWM4")
	)
	(segment
		(start 311.534048 -365.584486)
		(end 311.534048 -363.555026)
		(width 0.1524)
		(layer "F.Cu")
		(net "PVDDIO_P0_PWM3")
	)
	(segment
		(start 310.5658 -366.810036)
		(end 311.352184 -366.023652)
		(width 0.1524)
		(layer "F.Cu")
		(net "PVDDIO_P0_PWM3")
	)
	(segment
		(start 311.352184 -366.023652)
		(end 311.534048 -365.584486)
		(width 0.1524)
		(layer "F.Cu")
		(net "PVDDIO_P0_PWM3")
	)
	(segment
		(start 283.962602 -350.720914)
		(end 283.962602 -349.616268)
		(width 0.1778)
		(layer "F.Cu")
		(net "PVDDIO_P0_PWM3")
	)
	(segment
		(start 310.5658 -367.3602)
		(end 310.5658 -366.810036)
		(width 0.1524)
		(layer "F.Cu")
		(net "PVDDIO_P0_PWM3")
	)
	(segment
		(start 283.627322 -351.056194)
		(end 283.962602 -350.720914)
		(width 0.1778)
		(layer "F.Cu")
		(net "PVDDIO_P0_PWM3")
	)
	(via
		(at 283.627322 -351.056194)
		(size 0.508)
		(drill 0.254)
		(layers "F.Cu" "B.Cu")
		(net "PVDDIO_P0_PWM3")
	)
	(via
		(at 310.5658 -367.3602)
		(size 0.508)
		(drill 0.254)
		(layers "F.Cu" "B.Cu")
		(net "PVDDIO_P0_PWM3")
	)
	(segment
		(start 284.09519 -364.288832)
		(end 284.09519 -351.524062)
		(width 0.1524)
		(layer "In4.Cu")
		(net "PVDDIO_P0_PWM3")
	)
	(segment
		(start 308.9148 -368.0968)
		(end 305.1302 -368.0968)
		(width 0.1524)
		(layer "In4.Cu")
		(net "PVDDIO_P0_PWM3")
	)
	(segment
		(start 309.6514 -367.3602)
		(end 308.9148 -368.0968)
		(width 0.1524)
		(layer "In4.Cu")
		(net "PVDDIO_P0_PWM3")
	)
	(segment
		(start 284.09519 -351.524062)
		(end 283.627322 -351.056194)
		(width 0.1524)
		(layer "In4.Cu")
		(net "PVDDIO_P0_PWM3")
	)
	(segment
		(start 310.5658 -367.3602)
		(end 309.6514 -367.3602)
		(width 0.1524)
		(layer "In4.Cu")
		(net "PVDDIO_P0_PWM3")
	)
	(segment
		(start 304.038 -369.189)
		(end 302.2092 -369.189)
		(width 0.1524)
		(layer "In4.Cu")
		(net "PVDDIO_P0_PWM3")
	)
	(segment
		(start 302.2092 -369.189)
		(end 298.419012 -365.398812)
		(width 0.1524)
		(layer "In4.Cu")
		(net "PVDDIO_P0_PWM3")
	)
	(segment
		(start 285.20517 -365.398812)
		(end 284.09519 -364.288832)
		(width 0.1524)
		(layer "In4.Cu")
		(net "PVDDIO_P0_PWM3")
	)
	(segment
		(start 298.419012 -365.398812)
		(end 285.20517 -365.398812)
		(width 0.1524)
		(layer "In4.Cu")
		(net "PVDDIO_P0_PWM3")
	)
	(segment
		(start 305.1302 -368.0968)
		(end 304.038 -369.189)
		(width 0.1524)
		(layer "In4.Cu")
		(net "PVDDIO_P0_PWM3")
	)
	(segment
		(start 292.268402 -349.616268)
		(end 292.268402 -350.720914)
		(width 0.1778)
		(layer "F.Cu")
		(net "PVDDIO_P0_PWM2")
	)
	(segment
		(start 311.4548 -366.8522)
		(end 311.934098 -365.694722)
		(width 0.1524)
		(layer "F.Cu")
		(net "PVDDIO_P0_PWM2")
	)
	(segment
		(start 292.268402 -350.720914)
		(end 291.933122 -351.056194)
		(width 0.1778)
		(layer "F.Cu")
		(net "PVDDIO_P0_PWM2")
	)
	(segment
		(start 311.934098 -365.694722)
		(end 311.934098 -363.555026)
		(width 0.1524)
		(layer "F.Cu")
		(net "PVDDIO_P0_PWM2")
	)
	(via
		(at 311.4548 -366.8522)
		(size 0.508)
		(drill 0.254)
		(layers "F.Cu" "B.Cu")
		(net "PVDDIO_P0_PWM2")
	)
	(via
		(at 291.933122 -351.056194)
		(size 0.508)
		(drill 0.254)
		(layers "F.Cu" "B.Cu")
		(net "PVDDIO_P0_PWM2")
	)
	(segment
		(start 299.847 -365.4044)
		(end 302.8188 -368.3762)
		(width 0.1524)
		(layer "In4.Cu")
		(net "PVDDIO_P0_PWM2")
	)
	(segment
		(start 299.847 -358.970072)
		(end 299.847 -365.4044)
		(width 0.1524)
		(layer "In4.Cu")
		(net "PVDDIO_P0_PWM2")
	)
	(segment
		(start 309.5244 -366.649)
		(end 310.964326 -366.649)
		(width 0.1524)
		(layer "In4.Cu")
		(net "PVDDIO_P0_PWM2")
	)
	(segment
		(start 303.8348 -368.3762)
		(end 304.673 -367.538)
		(width 0.1524)
		(layer "In4.Cu")
		(net "PVDDIO_P0_PWM2")
	)
	(segment
		(start 291.933122 -351.056194)
		(end 299.847 -358.970072)
		(width 0.1524)
		(layer "In4.Cu")
		(net "PVDDIO_P0_PWM2")
	)
	(segment
		(start 304.673 -367.538)
		(end 308.6354 -367.538)
		(width 0.1524)
		(layer "In4.Cu")
		(net "PVDDIO_P0_PWM2")
	)
	(segment
		(start 302.8188 -368.3762)
		(end 303.8348 -368.3762)
		(width 0.1524)
		(layer "In4.Cu")
		(net "PVDDIO_P0_PWM2")
	)
	(segment
		(start 310.964326 -366.649)
		(end 311.4548 -366.8522)
		(width 0.1524)
		(layer "In4.Cu")
		(net "PVDDIO_P0_PWM2")
	)
	(segment
		(start 308.6354 -367.538)
		(end 309.5244 -366.649)
		(width 0.1524)
		(layer "In4.Cu")
		(net "PVDDIO_P0_PWM2")
	)
	(segment
		(start 312.333894 -363.555026)
		(end 312.333894 -366.268)
		(width 0.1524)
		(layer "F.Cu")
		(net "PVDDIO_P0_PWM1")
	)
	(segment
		(start 300.625002 -350.720914)
		(end 300.289722 -351.056194)
		(width 0.1778)
		(layer "F.Cu")
		(net "PVDDIO_P0_PWM1")
	)
	(segment
		(start 300.625002 -349.616268)
		(end 300.625002 -350.720914)
		(width 0.1778)
		(layer "F.Cu")
		(net "PVDDIO_P0_PWM1")
	)
	(via
		(at 312.333894 -366.268)
		(size 0.508)
		(drill 0.254)
		(layers "F.Cu" "B.Cu")
		(net "PVDDIO_P0_PWM1")
	)
	(via
		(at 300.289722 -351.056194)
		(size 0.508)
		(drill 0.254)
		(layers "F.Cu" "B.Cu")
		(net "PVDDIO_P0_PWM1")
	)
	(segment
		(start 301.5996 -352.366072)
		(end 301.5996 -358.7496)
		(width 0.1524)
		(layer "In4.Cu")
		(net "PVDDIO_P0_PWM1")
	)
	(segment
		(start 311.904634 -366.0902)
		(end 312.333894 -366.268)
		(width 0.1524)
		(layer "In4.Cu")
		(net "PVDDIO_P0_PWM1")
	)
	(segment
		(start 308.3814 -366.9284)
		(end 309.2196 -366.0902)
		(width 0.1524)
		(layer "In4.Cu")
		(net "PVDDIO_P0_PWM1")
	)
	(segment
		(start 309.2196 -366.0902)
		(end 311.904634 -366.0902)
		(width 0.1524)
		(layer "In4.Cu")
		(net "PVDDIO_P0_PWM1")
	)
	(segment
		(start 301.1678 -361.7722)
		(end 301.752 -362.3564)
		(width 0.1524)
		(layer "In4.Cu")
		(net "PVDDIO_P0_PWM1")
	)
	(segment
		(start 301.1678 -359.1814)
		(end 301.1678 -361.7722)
		(width 0.1524)
		(layer "In4.Cu")
		(net "PVDDIO_P0_PWM1")
	)
	(segment
		(start 301.5996 -358.7496)
		(end 301.1678 -359.1814)
		(width 0.1524)
		(layer "In4.Cu")
		(net "PVDDIO_P0_PWM1")
	)
	(segment
		(start 301.752 -362.3564)
		(end 301.752 -363.4994)
		(width 0.1524)
		(layer "In4.Cu")
		(net "PVDDIO_P0_PWM1")
	)
	(segment
		(start 302.6918 -364.4392)
		(end 303.4284 -364.4392)
		(width 0.1524)
		(layer "In4.Cu")
		(net "PVDDIO_P0_PWM1")
	)
	(segment
		(start 305.9176 -366.9284)
		(end 308.3814 -366.9284)
		(width 0.1524)
		(layer "In4.Cu")
		(net "PVDDIO_P0_PWM1")
	)
	(segment
		(start 301.752 -363.4994)
		(end 302.6918 -364.4392)
		(width 0.1524)
		(layer "In4.Cu")
		(net "PVDDIO_P0_PWM1")
	)
	(segment
		(start 303.4284 -364.4392)
		(end 305.9176 -366.9284)
		(width 0.1524)
		(layer "In4.Cu")
		(net "PVDDIO_P0_PWM1")
	)
	(segment
		(start 300.289722 -351.056194)
		(end 301.5996 -352.366072)
		(width 0.1524)
		(layer "In4.Cu")
		(net "PVDDIO_P0_PWM1")
	)
	(segment
		(start 273.959574 -350.799908)
		(end 273.959574 -351.68586)
		(width 0.127)
		(layer "F.Cu")
		(net "PVDDIO_P0_LSET4")
	)
	(segment
		(start 274.332192 -349.616268)
		(end 274.332192 -350.02216)
		(width 0.127)
		(layer "F.Cu")
		(net "PVDDIO_P0_LSET4")
	)
	(segment
		(start 273.959574 -350.394778)
		(end 273.959574 -350.799908)
		(width 0.127)
		(layer "F.Cu")
		(net "PVDDIO_P0_LSET4")
	)
	(segment
		(start 274.332192 -350.02216)
		(end 273.959574 -350.394778)
		(width 0.127)
		(layer "F.Cu")
		(net "PVDDIO_P0_LSET4")
	)
	(segment
		(start 273.959574 -351.68586)
		(end 273.717512 -351.927922)
		(width 0.127)
		(layer "F.Cu")
		(net "PVDDIO_P0_LSET4")
	)
	(via
		(at 273.959574 -350.799908)
		(size 0.4064)
		(drill 0.2032)
		(layers "F.Cu" "B.Cu")
		(net "PVDDIO_P0_LSET4")
	)
	(segment
		(start 282.239974 -351.68586)
		(end 281.997912 -351.927922)
		(width 0.127)
		(layer "F.Cu")
		(net "PVDDIO_P0_LSET3")
	)
	(segment
		(start 282.239974 -350.394778)
		(end 282.239974 -350.792796)
		(width 0.127)
		(layer "F.Cu")
		(net "PVDDIO_P0_LSET3")
	)
	(segment
		(start 282.612592 -349.616268)
		(end 282.612592 -350.02216)
		(width 0.127)
		(layer "F.Cu")
		(net "PVDDIO_P0_LSET3")
	)
	(segment
		(start 282.239974 -350.792796)
		(end 282.239974 -351.68586)
		(width 0.127)
		(layer "F.Cu")
		(net "PVDDIO_P0_LSET3")
	)
	(segment
		(start 282.612592 -350.02216)
		(end 282.239974 -350.394778)
		(width 0.127)
		(layer "F.Cu")
		(net "PVDDIO_P0_LSET3")
	)
	(via
		(at 282.239974 -350.792796)
		(size 0.4064)
		(drill 0.2032)
		(layers "F.Cu" "B.Cu")
		(net "PVDDIO_P0_LSET3")
	)
	(segment
		(start 290.545774 -350.764602)
		(end 290.545774 -350.394778)
		(width 0.127)
		(layer "F.Cu")
		(net "PVDDIO_P0_LSET2")
	)
	(segment
		(start 290.303712 -351.927922)
		(end 290.545774 -351.68586)
		(width 0.127)
		(layer "F.Cu")
		(net "PVDDIO_P0_LSET2")
	)
	(segment
		(start 290.545774 -351.68586)
		(end 290.545774 -350.764602)
		(width 0.127)
		(layer "F.Cu")
		(net "PVDDIO_P0_LSET2")
	)
	(segment
		(start 290.918392 -350.02216)
		(end 290.918392 -349.616268)
		(width 0.127)
		(layer "F.Cu")
		(net "PVDDIO_P0_LSET2")
	)
	(segment
		(start 290.545774 -350.394778)
		(end 290.918392 -350.02216)
		(width 0.127)
		(layer "F.Cu")
		(net "PVDDIO_P0_LSET2")
	)
	(via
		(at 290.545774 -350.764602)
		(size 0.4064)
		(drill 0.2032)
		(layers "F.Cu" "B.Cu")
		(net "PVDDIO_P0_LSET2")
	)
	(segment
		(start 299.274992 -350.02216)
		(end 298.902374 -350.394778)
		(width 0.127)
		(layer "F.Cu")
		(net "PVDDIO_P0_LSET1")
	)
	(segment
		(start 298.902374 -350.764602)
		(end 298.902374 -351.68586)
		(width 0.127)
		(layer "F.Cu")
		(net "PVDDIO_P0_LSET1")
	)
	(segment
		(start 299.274992 -349.616268)
		(end 299.274992 -350.02216)
		(width 0.127)
		(layer "F.Cu")
		(net "PVDDIO_P0_LSET1")
	)
	(segment
		(start 298.902374 -351.68586)
		(end 298.660312 -351.927922)
		(width 0.127)
		(layer "F.Cu")
		(net "PVDDIO_P0_LSET1")
	)
	(segment
		(start 298.902374 -350.394778)
		(end 298.902374 -350.764602)
		(width 0.127)
		(layer "F.Cu")
		(net "PVDDIO_P0_LSET1")
	)
	(via
		(at 298.902374 -350.764602)
		(size 0.4064)
		(drill 0.2032)
		(layers "F.Cu" "B.Cu")
		(net "PVDDIO_P0_LSET1")
	)
	(segment
		(start 273.882104 -349.616268)
		(end 273.882104 -349.992188)
		(width 0.2286)
		(layer "F.Cu")
		(net "PVDDIO_P0_IMON4")
	)
	(segment
		(start 313.11215 -353.845622)
		(end 312.5216 -354.436172)
		(width 0.1778)
		(layer "F.Cu")
		(net "PVDDIO_P0_IMON4")
	)
	(segment
		(start 273.882104 -349.992188)
		(end 273.44497 -350.429322)
		(width 0.2286)
		(layer "F.Cu")
		(net "PVDDIO_P0_IMON4")
	)
	(segment
		(start 312.5216 -356.6414)
		(end 311.934098 -357.228902)
		(width 0.1778)
		(layer "F.Cu")
		(net "PVDDIO_P0_IMON4")
	)
	(segment
		(start 313.891422 -353.845622)
		(end 313.11215 -353.845622)
		(width 0.1778)
		(layer "F.Cu")
		(net "PVDDIO_P0_IMON4")
	)
	(segment
		(start 311.934098 -357.228902)
		(end 311.934098 -357.804974)
		(width 0.1778)
		(layer "F.Cu")
		(net "PVDDIO_P0_IMON4")
	)
	(segment
		(start 273.44497 -350.429322)
		(end 273.44497 -350.536764)
		(width 0.2286)
		(layer "F.Cu")
		(net "PVDDIO_P0_IMON4")
	)
	(segment
		(start 273.44497 -350.536764)
		(end 273.456654 -350.536764)
		(width 0.2286)
		(layer "F.Cu")
		(net "PVDDIO_P0_IMON4")
	)
	(segment
		(start 312.5216 -354.436172)
		(end 312.5216 -356.6414)
		(width 0.1778)
		(layer "F.Cu")
		(net "PVDDIO_P0_IMON4")
	)
	(segment
		(start 314.5028 -354.457)
		(end 313.891422 -353.845622)
		(width 0.1778)
		(layer "F.Cu")
		(net "PVDDIO_P0_IMON4")
	)
	(via
		(at 314.5028 -354.457)
		(size 0.508)
		(drill 0.254)
		(layers "F.Cu" "B.Cu")
		(net "PVDDIO_P0_IMON4")
	)
	(via
		(at 273.456654 -350.536764)
		(size 0.508)
		(drill 0.254)
		(layers "F.Cu" "B.Cu")
		(net "PVDDIO_P0_IMON4")
	)
	(segment
		(start 272.936462 -350.877632)
		(end 273.27733 -350.536764)
		(width 0.254)
		(layer "In6.Cu")
		(net "PVDDIO_P0_IMON4")
	)
	(segment
		(start 303.746408 -353.77882)
		(end 301.168816 -353.77882)
		(width 0.254)
		(layer "In6.Cu")
		(net "PVDDIO_P0_IMON4")
	)
	(segment
		(start 272.936462 -351.536508)
		(end 272.936462 -350.877632)
		(width 0.254)
		(layer "In6.Cu")
		(net "PVDDIO_P0_IMON4")
	)
	(segment
		(start 301.168816 -353.77882)
		(end 300.698408 -354.249228)
		(width 0.254)
		(layer "In6.Cu")
		(net "PVDDIO_P0_IMON4")
	)
	(segment
		(start 314.5028 -354.6094)
		(end 313.055 -356.0572)
		(width 0.254)
		(layer "In6.Cu")
		(net "PVDDIO_P0_IMON4")
	)
	(segment
		(start 314.5028 -354.457)
		(end 314.5028 -354.6094)
		(width 0.254)
		(layer "In6.Cu")
		(net "PVDDIO_P0_IMON4")
	)
	(segment
		(start 313.055 -356.0572)
		(end 313.055 -356.977188)
		(width 0.254)
		(layer "In6.Cu")
		(net "PVDDIO_P0_IMON4")
	)
	(segment
		(start 312.400188 -357.632)
		(end 307.599588 -357.632)
		(width 0.254)
		(layer "In6.Cu")
		(net "PVDDIO_P0_IMON4")
	)
	(segment
		(start 273.27733 -350.536764)
		(end 273.456654 -350.536764)
		(width 0.254)
		(layer "In6.Cu")
		(net "PVDDIO_P0_IMON4")
	)
	(segment
		(start 275.649182 -354.249228)
		(end 272.936462 -351.536508)
		(width 0.254)
		(layer "In6.Cu")
		(net "PVDDIO_P0_IMON4")
	)
	(segment
		(start 300.698408 -354.249228)
		(end 275.649182 -354.249228)
		(width 0.254)
		(layer "In6.Cu")
		(net "PVDDIO_P0_IMON4")
	)
	(segment
		(start 313.055 -356.977188)
		(end 312.400188 -357.632)
		(width 0.254)
		(layer "In6.Cu")
		(net "PVDDIO_P0_IMON4")
	)
	(segment
		(start 307.599588 -357.632)
		(end 303.746408 -353.77882)
		(width 0.254)
		(layer "In6.Cu")
		(net "PVDDIO_P0_IMON4")
	)
	(segment
		(start 282.162504 -349.616268)
		(end 282.162504 -349.992188)
		(width 0.2286)
		(layer "F.Cu")
		(net "PVDDIO_P0_IMON3")
	)
	(segment
		(start 281.72537 -350.536764)
		(end 281.737054 -350.536764)
		(width 0.2286)
		(layer "F.Cu")
		(net "PVDDIO_P0_IMON3")
	)
	(segment
		(start 282.162504 -349.992188)
		(end 281.72537 -350.429322)
		(width 0.2286)
		(layer "F.Cu")
		(net "PVDDIO_P0_IMON3")
	)
	(segment
		(start 312.333894 -357.337106)
		(end 312.333894 -357.804974)
		(width 0.1778)
		(layer "F.Cu")
		(net "PVDDIO_P0_IMON3")
	)
	(segment
		(start 313.3598 -354.4824)
		(end 312.9534 -354.8888)
		(width 0.1778)
		(layer "F.Cu")
		(net "PVDDIO_P0_IMON3")
	)
	(segment
		(start 281.72537 -350.429322)
		(end 281.72537 -350.536764)
		(width 0.2286)
		(layer "F.Cu")
		(net "PVDDIO_P0_IMON3")
	)
	(segment
		(start 312.9534 -356.7176)
		(end 312.333894 -357.337106)
		(width 0.1778)
		(layer "F.Cu")
		(net "PVDDIO_P0_IMON3")
	)
	(segment
		(start 312.9534 -354.8888)
		(end 312.9534 -356.7176)
		(width 0.1778)
		(layer "F.Cu")
		(net "PVDDIO_P0_IMON3")
	)
	(via
		(at 313.3598 -354.4824)
		(size 0.762)
		(drill 0.254)
		(layers "F.Cu" "B.Cu")
		(net "PVDDIO_P0_IMON3")
	)
	(via
		(at 281.737054 -350.536764)
		(size 0.508)
		(drill 0.254)
		(layers "F.Cu" "B.Cu")
		(net "PVDDIO_P0_IMON3")
	)
	(segment
		(start 281.55773 -350.536764)
		(end 281.737054 -350.536764)
		(width 0.254)
		(layer "In6.Cu")
		(net "PVDDIO_P0_IMON3")
	)
	(segment
		(start 310.088788 -356.2604)
		(end 308.071012 -356.2604)
		(width 0.254)
		(layer "In6.Cu")
		(net "PVDDIO_P0_IMON3")
	)
	(segment
		(start 308.071012 -356.2604)
		(end 304.286412 -352.4758)
		(width 0.254)
		(layer "In6.Cu")
		(net "PVDDIO_P0_IMON3")
	)
	(segment
		(start 313.3598 -354.4824)
		(end 312.801 -355.0412)
		(width 0.254)
		(layer "In6.Cu")
		(net "PVDDIO_P0_IMON3")
	)
	(segment
		(start 300.131988 -353.1362)
		(end 282.118054 -353.1362)
		(width 0.254)
		(layer "In6.Cu")
		(net "PVDDIO_P0_IMON3")
	)
	(segment
		(start 300.792388 -352.4758)
		(end 300.131988 -353.1362)
		(width 0.254)
		(layer "In6.Cu")
		(net "PVDDIO_P0_IMON3")
	)
	(segment
		(start 282.118054 -353.1362)
		(end 281.027886 -352.046032)
		(width 0.254)
		(layer "In6.Cu")
		(net "PVDDIO_P0_IMON3")
	)
	(segment
		(start 281.027886 -351.066608)
		(end 281.55773 -350.536764)
		(width 0.254)
		(layer "In6.Cu")
		(net "PVDDIO_P0_IMON3")
	)
	(segment
		(start 304.286412 -352.4758)
		(end 300.792388 -352.4758)
		(width 0.254)
		(layer "In6.Cu")
		(net "PVDDIO_P0_IMON3")
	)
	(segment
		(start 312.801 -355.0412)
		(end 311.307988 -355.0412)
		(width 0.254)
		(layer "In6.Cu")
		(net "PVDDIO_P0_IMON3")
	)
	(segment
		(start 281.027886 -352.046032)
		(end 281.027886 -351.066608)
		(width 0.254)
		(layer "In6.Cu")
		(net "PVDDIO_P0_IMON3")
	)
	(segment
		(start 311.307988 -355.0412)
		(end 310.088788 -356.2604)
		(width 0.254)
		(layer "In6.Cu")
		(net "PVDDIO_P0_IMON3")
	)
	(segment
		(start 290.468304 -349.992188)
		(end 290.03117 -350.429322)
		(width 0.2286)
		(layer "F.Cu")
		(net "PVDDIO_P0_IMON2")
	)
	(segment
		(start 313.349894 -358.480106)
		(end 313.009026 -358.480106)
		(width 0.1778)
		(layer "F.Cu")
		(net "PVDDIO_P0_IMON2")
	)
	(segment
		(start 290.468304 -349.616268)
		(end 290.468304 -349.992188)
		(width 0.2286)
		(layer "F.Cu")
		(net "PVDDIO_P0_IMON2")
	)
	(segment
		(start 313.4868 -358.3432)
		(end 313.349894 -358.480106)
		(width 0.1778)
		(layer "F.Cu")
		(net "PVDDIO_P0_IMON2")
	)
	(segment
		(start 313.6646 -357.505)
		(end 313.4868 -357.6828)
		(width 0.1778)
		(layer "F.Cu")
		(net "PVDDIO_P0_IMON2")
	)
	(segment
		(start 313.6646 -356.7176)
		(end 313.6646 -357.505)
		(width 0.1778)
		(layer "F.Cu")
		(net "PVDDIO_P0_IMON2")
	)
	(segment
		(start 313.4868 -357.6828)
		(end 313.4868 -358.3432)
		(width 0.1778)
		(layer "F.Cu")
		(net "PVDDIO_P0_IMON2")
	)
	(segment
		(start 290.03117 -350.536764)
		(end 290.042854 -350.536764)
		(width 0.2286)
		(layer "F.Cu")
		(net "PVDDIO_P0_IMON2")
	)
	(segment
		(start 290.03117 -350.429322)
		(end 290.03117 -350.536764)
		(width 0.2286)
		(layer "F.Cu")
		(net "PVDDIO_P0_IMON2")
	)
	(via
		(at 290.042854 -350.536764)
		(size 0.508)
		(drill 0.254)
		(layers "F.Cu" "B.Cu")
		(net "PVDDIO_P0_IMON2")
	)
	(via
		(at 313.6646 -356.7176)
		(size 0.508)
		(drill 0.254)
		(layers "F.Cu" "B.Cu")
		(net "PVDDIO_P0_IMON2")
	)
	(segment
		(start 308.096412 -358.1654)
		(end 303.753012 -353.822)
		(width 0.254)
		(layer "In11.Cu")
		(net "PVDDIO_P0_IMON2")
	)
	(segment
		(start 289.86353 -350.536764)
		(end 290.042854 -350.536764)
		(width 0.254)
		(layer "In11.Cu")
		(net "PVDDIO_P0_IMON2")
	)
	(segment
		(start 303.753012 -353.822)
		(end 291.13099 -353.822)
		(width 0.254)
		(layer "In11.Cu")
		(net "PVDDIO_P0_IMON2")
	)
	(segment
		(start 313.6646 -356.7176)
		(end 313.2328 -356.7176)
		(width 0.254)
		(layer "In11.Cu")
		(net "PVDDIO_P0_IMON2")
	)
	(segment
		(start 313.2328 -356.7176)
		(end 311.785 -358.1654)
		(width 0.254)
		(layer "In11.Cu")
		(net "PVDDIO_P0_IMON2")
	)
	(segment
		(start 291.13099 -353.822)
		(end 289.333686 -352.024696)
		(width 0.254)
		(layer "In11.Cu")
		(net "PVDDIO_P0_IMON2")
	)
	(segment
		(start 311.785 -358.1654)
		(end 308.096412 -358.1654)
		(width 0.254)
		(layer "In11.Cu")
		(net "PVDDIO_P0_IMON2")
	)
	(segment
		(start 289.333686 -351.066608)
		(end 289.86353 -350.536764)
		(width 0.254)
		(layer "In11.Cu")
		(net "PVDDIO_P0_IMON2")
	)
	(segment
		(start 289.333686 -352.024696)
		(end 289.333686 -351.066608)
		(width 0.254)
		(layer "In11.Cu")
		(net "PVDDIO_P0_IMON2")
	)
	(segment
		(start 298.824904 -349.616268)
		(end 298.824904 -349.992188)
		(width 0.2286)
		(layer "F.Cu")
		(net "PVDDIO_P0_IMON1")
	)
	(segment
		(start 314.1726 -357.759)
		(end 313.8932 -358.0384)
		(width 0.1778)
		(layer "F.Cu")
		(net "PVDDIO_P0_IMON1")
	)
	(segment
		(start 313.8932 -358.0384)
		(end 313.8932 -358.4448)
		(width 0.1778)
		(layer "F.Cu")
		(net "PVDDIO_P0_IMON1")
	)
	(segment
		(start 298.824904 -349.992188)
		(end 298.38777 -350.429322)
		(width 0.2286)
		(layer "F.Cu")
		(net "PVDDIO_P0_IMON1")
	)
	(segment
		(start 314.1726 -356.235)
		(end 314.1726 -357.759)
		(width 0.1778)
		(layer "F.Cu")
		(net "PVDDIO_P0_IMON1")
	)
	(segment
		(start 298.38777 -350.536764)
		(end 298.399454 -350.536764)
		(width 0.2286)
		(layer "F.Cu")
		(net "PVDDIO_P0_IMON1")
	)
	(segment
		(start 298.38777 -350.429322)
		(end 298.38777 -350.536764)
		(width 0.2286)
		(layer "F.Cu")
		(net "PVDDIO_P0_IMON1")
	)
	(segment
		(start 313.458098 -358.879902)
		(end 313.009026 -358.879902)
		(width 0.1778)
		(layer "F.Cu")
		(net "PVDDIO_P0_IMON1")
	)
	(segment
		(start 314.579 -355.8286)
		(end 314.1726 -356.235)
		(width 0.1778)
		(layer "F.Cu")
		(net "PVDDIO_P0_IMON1")
	)
	(segment
		(start 313.8932 -358.4448)
		(end 313.458098 -358.879902)
		(width 0.1778)
		(layer "F.Cu")
		(net "PVDDIO_P0_IMON1")
	)
	(via
		(at 298.399454 -350.536764)
		(size 0.508)
		(drill 0.254)
		(layers "F.Cu" "B.Cu")
		(net "PVDDIO_P0_IMON1")
	)
	(via
		(at 314.579 -355.8286)
		(size 0.508)
		(drill 0.254)
		(layers "F.Cu" "B.Cu")
		(net "PVDDIO_P0_IMON1")
	)
	(segment
		(start 310.342788 -356.3112)
		(end 307.969412 -356.3112)
		(width 0.254)
		(layer "In11.Cu")
		(net "PVDDIO_P0_IMON1")
	)
	(segment
		(start 307.969412 -356.3112)
		(end 304.43424 -352.776028)
		(width 0.254)
		(layer "In11.Cu")
		(net "PVDDIO_P0_IMON1")
	)
	(segment
		(start 314.579 -355.8286)
		(end 314.579 -355.6254)
		(width 0.254)
		(layer "In11.Cu")
		(net "PVDDIO_P0_IMON1")
	)
	(segment
		(start 298.487338 -352.776028)
		(end 297.690286 -351.978976)
		(width 0.254)
		(layer "In11.Cu")
		(net "PVDDIO_P0_IMON1")
	)
	(segment
		(start 304.43424 -352.776028)
		(end 298.487338 -352.776028)
		(width 0.254)
		(layer "In11.Cu")
		(net "PVDDIO_P0_IMON1")
	)
	(segment
		(start 314.4012 -355.4476)
		(end 312.5216 -355.4476)
		(width 0.254)
		(layer "In11.Cu")
		(net "PVDDIO_P0_IMON1")
	)
	(segment
		(start 297.690286 -351.066608)
		(end 298.22013 -350.536764)
		(width 0.254)
		(layer "In11.Cu")
		(net "PVDDIO_P0_IMON1")
	)
	(segment
		(start 314.579 -355.6254)
		(end 314.4012 -355.4476)
		(width 0.254)
		(layer "In11.Cu")
		(net "PVDDIO_P0_IMON1")
	)
	(segment
		(start 298.22013 -350.536764)
		(end 298.399454 -350.536764)
		(width 0.254)
		(layer "In11.Cu")
		(net "PVDDIO_P0_IMON1")
	)
	(segment
		(start 311.587388 -355.0666)
		(end 310.342788 -356.3112)
		(width 0.254)
		(layer "In11.Cu")
		(net "PVDDIO_P0_IMON1")
	)
	(segment
		(start 312.5216 -355.4476)
		(end 312.1406 -355.0666)
		(width 0.254)
		(layer "In11.Cu")
		(net "PVDDIO_P0_IMON1")
	)
	(segment
		(start 297.690286 -351.978976)
		(end 297.690286 -351.066608)
		(width 0.254)
		(layer "In11.Cu")
		(net "PVDDIO_P0_IMON1")
	)
	(segment
		(start 312.1406 -355.0666)
		(end 311.587388 -355.0666)
		(width 0.254)
		(layer "In11.Cu")
		(net "PVDDIO_P0_IMON1")
	)
	(segment
		(start 289.012884 -370.718842)
		(end 290.34613 -370.718842)
		(width 0.10668)
		(layer "F.Cu")
		(net "PVDDIO_P0_EN_R")
	)
	(segment
		(start 286.980884 -370.718842)
		(end 287.996884 -370.718842)
		(width 0.10668)
		(layer "F.Cu")
		(net "PVDDIO_P0_EN_R")
	)
	(segment
		(start 290.605972 -370.459)
		(end 290.34613 -370.718842)
		(width 0.10668)
		(layer "F.Cu")
		(net "PVDDIO_P0_EN_R")
	)
	(segment
		(start 290.605972 -369.180618)
		(end 290.605972 -370.459)
		(width 0.10668)
		(layer "F.Cu")
		(net "PVDDIO_P0_EN_R")
	)
	(segment
		(start 287.996884 -370.718842)
		(end 289.012884 -370.718842)
		(width 0.10668)
		(layer "F.Cu")
		(net "PVDDIO_P0_EN_R")
	)
	(via
		(at 290.34613 -370.718842)
		(size 0.762)
		(drill 0.381)
		(layers "F.Cu" "B.Cu")
		(net "PVDDIO_P0_EN_R")
	)
	(segment
		(start 294.681402 -369.366038)
		(end 294.6908 -369.375436)
		(width 0.10668)
		(layer "F.Cu")
		(net "PVDDIO_P0_EN_G")
	)
	(segment
		(start 294.6908 -369.375436)
		(end 294.167306 -369.89893)
		(width 0.10668)
		(layer "F.Cu")
		(net "PVDDIO_P0_EN_G")
	)
	(segment
		(start 292.80612 -369.307364)
		(end 292.80612 -368.230658)
		(width 0.10668)
		(layer "F.Cu")
		(net "PVDDIO_P0_EN_G")
	)
	(segment
		(start 294.167306 -369.89893)
		(end 293.397686 -369.89893)
		(width 0.10668)
		(layer "F.Cu")
		(net "PVDDIO_P0_EN_G")
	)
	(segment
		(start 293.397686 -369.89893)
		(end 292.80612 -369.307364)
		(width 0.10668)
		(layer "F.Cu")
		(net "PVDDIO_P0_EN_G")
	)
	(segment
		(start 294.681402 -367.97996)
		(end 294.681402 -369.366038)
		(width 0.10668)
		(layer "F.Cu")
		(net "PVDDIO_P0_EN_G")
	)
	(via
		(at 293.397686 -369.89893)
		(size 0.762)
		(drill 0.381)
		(layers "F.Cu" "B.Cu")
		(net "PVDDIO_P0_EN_G")
	)
	(segment
		(start 239.607598 -169.191686)
		(end 238.72444 -168.308528)
		(width 0.10668)
		(layer "F.Cu")
		(net "PVDDIO_P0_EN")
	)
	(segment
		(start 238.72444 -168.308528)
		(end 238.4552 -168.308528)
		(width 0.10668)
		(layer "F.Cu")
		(net "PVDDIO_P0_EN")
	)
	(segment
		(start 228.915214 -365.850424)
		(end 224.424748 -365.850424)
		(width 0.10668)
		(layer "F.Cu")
		(net "PVDDIO_P0_EN")
	)
	(segment
		(start 283.980636 -369.918742)
		(end 281.865832 -367.803938)
		(width 0.10668)
		(layer "F.Cu")
		(net "PVDDIO_P0_EN")
	)
	(segment
		(start 285.449264 -369.918742)
		(end 283.980636 -369.918742)
		(width 0.10668)
		(layer "F.Cu")
		(net "PVDDIO_P0_EN")
	)
	(segment
		(start 244.8941 -190.351156)
		(end 239.607598 -177.588926)
		(width 0.10668)
		(layer "F.Cu")
		(net "PVDDIO_P0_EN")
	)
	(segment
		(start 241.886486 -209.57413)
		(end 244.8941 -206.566516)
		(width 0.10668)
		(layer "F.Cu")
		(net "PVDDIO_P0_EN")
	)
	(segment
		(start 231.776524 -362.989114)
		(end 228.915214 -365.850424)
		(width 0.10668)
		(layer "F.Cu")
		(net "PVDDIO_P0_EN")
	)
	(segment
		(start 285.449264 -369.918742)
		(end 286.980884 -369.918742)
		(width 0.10668)
		(layer "F.Cu")
		(net "PVDDIO_P0_EN")
	)
	(segment
		(start 270.444722 -368.83721)
		(end 253.782068 -368.83721)
		(width 0.10668)
		(layer "F.Cu")
		(net "PVDDIO_P0_EN")
	)
	(segment
		(start 239.607598 -177.588926)
		(end 239.607598 -169.191686)
		(width 0.10668)
		(layer "F.Cu")
		(net "PVDDIO_P0_EN")
	)
	(segment
		(start 281.865832 -367.803938)
		(end 271.477994 -367.803938)
		(width 0.10668)
		(layer "F.Cu")
		(net "PVDDIO_P0_EN")
	)
	(segment
		(start 247.933972 -362.989114)
		(end 231.776524 -362.989114)
		(width 0.10668)
		(layer "F.Cu")
		(net "PVDDIO_P0_EN")
	)
	(segment
		(start 253.782068 -368.83721)
		(end 247.933972 -362.989114)
		(width 0.10668)
		(layer "F.Cu")
		(net "PVDDIO_P0_EN")
	)
	(segment
		(start 238.4552 -168.308528)
		(end 232.494836 -162.348164)
		(width 0.10668)
		(layer "F.Cu")
		(net "PVDDIO_P0_EN")
	)
	(segment
		(start 271.477994 -367.803938)
		(end 270.444722 -368.83721)
		(width 0.10668)
		(layer "F.Cu")
		(net "PVDDIO_P0_EN")
	)
	(segment
		(start 244.8941 -206.566516)
		(end 244.8941 -190.351156)
		(width 0.10668)
		(layer "F.Cu")
		(net "PVDDIO_P0_EN")
	)
	(segment
		(start 230.203502 -209.57413)
		(end 241.886486 -209.57413)
		(width 0.10668)
		(layer "F.Cu")
		(net "PVDDIO_P0_EN")
	)
	(via
		(at 214.884 -106.390948)
		(size 0.508)
		(drill 0.254)
		(layers "F.Cu" "B.Cu")
		(net "PVDDIO_P0_EN")
	)
	(via
		(at 230.203502 -209.57413)
		(size 0.508)
		(drill 0.254)
		(layers "F.Cu" "B.Cu")
		(net "PVDDIO_P0_EN")
	)
	(via
		(at 224.424748 -365.850424)
		(size 0.508)
		(drill 0.254)
		(layers "F.Cu" "B.Cu")
		(net "PVDDIO_P0_EN")
	)
	(via
		(at 260.208522 -107.708954)
		(size 0.508)
		(drill 0.254)
		(layers "F.Cu" "B.Cu")
		(net "PVDDIO_P0_EN")
	)
	(via
		(at 285.449264 -369.918742)
		(size 0.762)
		(drill 0.381)
		(layers "F.Cu" "B.Cu")
		(net "PVDDIO_P0_EN")
	)
	(via
		(at 232.494836 -162.348164)
		(size 0.508)
		(drill 0.254)
		(layers "F.Cu" "B.Cu")
		(net "PVDDIO_P0_EN")
	)
	(segment
		(start 203.818236 -102.124764)
		(end 204.37856 -102.124764)
		(width 0.10668)
		(layer "B.Cu")
		(net "PVDDIO_P0_EN")
	)
	(segment
		(start 214.559134 -106.066082)
		(end 214.884 -106.390948)
		(width 0.10668)
		(layer "B.Cu")
		(net "PVDDIO_P0_EN")
	)
	(segment
		(start 205.014322 -103.698548)
		(end 205.743302 -103.698548)
		(width 0.10668)
		(layer "B.Cu")
		(net "PVDDIO_P0_EN")
	)
	(segment
		(start 197.923658 -105.497376)
		(end 197.923658 -105.47604)
		(width 0.10668)
		(layer "B.Cu")
		(net "PVDDIO_P0_EN")
	)
	(segment
		(start 204.559662 -102.305866)
		(end 204.559662 -103.243888)
		(width 0.10668)
		(layer "B.Cu")
		(net "PVDDIO_P0_EN")
	)
	(segment
		(start 205.743302 -103.698548)
		(end 206.145892 -104.101138)
		(width 0.10668)
		(layer "B.Cu")
		(net "PVDDIO_P0_EN")
	)
	(segment
		(start 199.785732 -104.93756)
		(end 201.360786 -103.362506)
		(width 0.10668)
		(layer "B.Cu")
		(net "PVDDIO_P0_EN")
	)
	(segment
		(start 198.462138 -104.93756)
		(end 199.785732 -104.93756)
		(width 0.10668)
		(layer "B.Cu")
		(net "PVDDIO_P0_EN")
	)
	(segment
		(start 201.360786 -103.362506)
		(end 202.580494 -103.362506)
		(width 0.10668)
		(layer "B.Cu")
		(net "PVDDIO_P0_EN")
	)
	(segment
		(start 197.923658 -105.47604)
		(end 198.462138 -104.93756)
		(width 0.10668)
		(layer "B.Cu")
		(net "PVDDIO_P0_EN")
	)
	(segment
		(start 204.37856 -102.124764)
		(end 204.559662 -102.305866)
		(width 0.10668)
		(layer "B.Cu")
		(net "PVDDIO_P0_EN")
	)
	(segment
		(start 206.145892 -104.101138)
		(end 210.8327 -104.101138)
		(width 0.10668)
		(layer "B.Cu")
		(net "PVDDIO_P0_EN")
	)
	(segment
		(start 212.797644 -106.066082)
		(end 214.559134 -106.066082)
		(width 0.10668)
		(layer "B.Cu")
		(net "PVDDIO_P0_EN")
	)
	(segment
		(start 210.8327 -104.101138)
		(end 212.797644 -106.066082)
		(width 0.10668)
		(layer "B.Cu")
		(net "PVDDIO_P0_EN")
	)
	(segment
		(start 204.559662 -103.243888)
		(end 205.014322 -103.698548)
		(width 0.10668)
		(layer "B.Cu")
		(net "PVDDIO_P0_EN")
	)
	(segment
		(start 202.580494 -103.362506)
		(end 203.818236 -102.124764)
		(width 0.10668)
		(layer "B.Cu")
		(net "PVDDIO_P0_EN")
	)
	(segment
		(start 259.712206 -134.060946)
		(end 255.651 -138.122152)
		(width 0.11684)
		(layer "In4.Cu")
		(net "PVDDIO_P0_EN")
	)
	(segment
		(start 217.240612 -320.85534)
		(end 217.240612 -261.676388)
		(width 0.11684)
		(layer "In4.Cu")
		(net "PVDDIO_P0_EN")
	)
	(segment
		(start 256.329434 -142.596616)
		(end 257.876802 -144.143984)
		(width 0.11684)
		(layer "In4.Cu")
		(net "PVDDIO_P0_EN")
	)
	(segment
		(start 254.798068 -148.806154)
		(end 248.961402 -148.806154)
		(width 0.11684)
		(layer "In4.Cu")
		(net "PVDDIO_P0_EN")
	)
	(segment
		(start 223.851724 -216.689686)
		(end 230.203502 -210.337908)
		(width 0.11684)
		(layer "In4.Cu")
		(net "PVDDIO_P0_EN")
	)
	(segment
		(start 261.580376 -127.8255)
		(end 259.712206 -129.69367)
		(width 0.11684)
		(layer "In4.Cu")
		(net "PVDDIO_P0_EN")
	)
	(segment
		(start 224.424748 -365.850424)
		(end 224.424748 -365.15294)
		(width 0.11684)
		(layer "In4.Cu")
		(net "PVDDIO_P0_EN")
	)
	(segment
		(start 224.424748 -365.15294)
		(end 220.860874 -361.589066)
		(width 0.11684)
		(layer "In4.Cu")
		(net "PVDDIO_P0_EN")
	)
	(segment
		(start 241.049048 -152.968706)
		(end 232.494836 -161.522918)
		(width 0.11684)
		(layer "In4.Cu")
		(net "PVDDIO_P0_EN")
	)
	(segment
		(start 228.385116 -331.999844)
		(end 217.240612 -320.85534)
		(width 0.11684)
		(layer "In4.Cu")
		(net "PVDDIO_P0_EN")
	)
	(segment
		(start 255.651 -140.208)
		(end 256.329434 -140.886434)
		(width 0.11684)
		(layer "In4.Cu")
		(net "PVDDIO_P0_EN")
	)
	(segment
		(start 220.860874 -351.373948)
		(end 228.385116 -343.849706)
		(width 0.11684)
		(layer "In4.Cu")
		(net "PVDDIO_P0_EN")
	)
	(segment
		(start 260.208522 -107.708954)
		(end 260.208522 -112.921288)
		(width 0.11684)
		(layer "In4.Cu")
		(net "PVDDIO_P0_EN")
	)
	(segment
		(start 257.876802 -144.143984)
		(end 257.876802 -145.72742)
		(width 0.11684)
		(layer "In4.Cu")
		(net "PVDDIO_P0_EN")
	)
	(segment
		(start 220.860874 -361.589066)
		(end 220.860874 -351.373948)
		(width 0.11684)
		(layer "In4.Cu")
		(net "PVDDIO_P0_EN")
	)
	(segment
		(start 257.876802 -145.72742)
		(end 254.798068 -148.806154)
		(width 0.11684)
		(layer "In4.Cu")
		(net "PVDDIO_P0_EN")
	)
	(segment
		(start 230.203502 -210.337908)
		(end 230.203502 -209.57413)
		(width 0.11684)
		(layer "In4.Cu")
		(net "PVDDIO_P0_EN")
	)
	(segment
		(start 223.851724 -255.065276)
		(end 223.851724 -216.689686)
		(width 0.11684)
		(layer "In4.Cu")
		(net "PVDDIO_P0_EN")
	)
	(segment
		(start 244.79885 -152.968706)
		(end 241.049048 -152.968706)
		(width 0.11684)
		(layer "In4.Cu")
		(net "PVDDIO_P0_EN")
	)
	(segment
		(start 256.329434 -140.886434)
		(end 256.329434 -142.596616)
		(width 0.11684)
		(layer "In4.Cu")
		(net "PVDDIO_P0_EN")
	)
	(segment
		(start 260.208522 -112.921288)
		(end 261.580376 -114.293142)
		(width 0.11684)
		(layer "In4.Cu")
		(net "PVDDIO_P0_EN")
	)
	(segment
		(start 255.651 -138.122152)
		(end 255.651 -140.208)
		(width 0.11684)
		(layer "In4.Cu")
		(net "PVDDIO_P0_EN")
	)
	(segment
		(start 259.712206 -129.69367)
		(end 259.712206 -134.060946)
		(width 0.11684)
		(layer "In4.Cu")
		(net "PVDDIO_P0_EN")
	)
	(segment
		(start 248.961402 -148.806154)
		(end 244.79885 -152.968706)
		(width 0.11684)
		(layer "In4.Cu")
		(net "PVDDIO_P0_EN")
	)
	(segment
		(start 232.494836 -161.522918)
		(end 232.494836 -162.348164)
		(width 0.11684)
		(layer "In4.Cu")
		(net "PVDDIO_P0_EN")
	)
	(segment
		(start 228.385116 -343.849706)
		(end 228.385116 -331.999844)
		(width 0.11684)
		(layer "In4.Cu")
		(net "PVDDIO_P0_EN")
	)
	(segment
		(start 217.240612 -261.676388)
		(end 223.851724 -255.065276)
		(width 0.11684)
		(layer "In4.Cu")
		(net "PVDDIO_P0_EN")
	)
	(segment
		(start 261.580376 -114.293142)
		(end 261.580376 -127.8255)
		(width 0.11684)
		(layer "In4.Cu")
		(net "PVDDIO_P0_EN")
	)
	(segment
		(start 215.534748 -107.041696)
		(end 221.93631 -107.041696)
		(width 0.11684)
		(layer "In6.Cu")
		(net "PVDDIO_P0_EN")
	)
	(segment
		(start 258.399788 -108.319824)
		(end 259.056124 -107.663488)
		(width 0.11684)
		(layer "In6.Cu")
		(net "PVDDIO_P0_EN")
	)
	(segment
		(start 221.93631 -107.041696)
		(end 223.214438 -108.319824)
		(width 0.11684)
		(layer "In6.Cu")
		(net "PVDDIO_P0_EN")
	)
	(segment
		(start 214.884 -106.390948)
		(end 215.534748 -107.041696)
		(width 0.11684)
		(layer "In6.Cu")
		(net "PVDDIO_P0_EN")
	)
	(segment
		(start 260.163056 -107.663488)
		(end 260.208522 -107.708954)
		(width 0.11684)
		(layer "In6.Cu")
		(net "PVDDIO_P0_EN")
	)
	(segment
		(start 259.056124 -107.663488)
		(end 260.163056 -107.663488)
		(width 0.11684)
		(layer "In6.Cu")
		(net "PVDDIO_P0_EN")
	)
	(segment
		(start 223.214438 -108.319824)
		(end 258.399788 -108.319824)
		(width 0.11684)
		(layer "In6.Cu")
		(net "PVDDIO_P0_EN")
	)
	(segment
		(start 335.577942 -280.300176)
		(end 335.11109 -280.566114)
		(width 0.350012)
		(layer "F.Cu")
		(net "PVDDIO_P0")
	)
	(segment
		(start 328.998072 -260.860032)
		(end 328.53122 -261.12597)
		(width 0.350012)
		(layer "F.Cu")
		(net "PVDDIO_P0")
	)
	(segment
		(start 345.447874 -263.29005)
		(end 344.981022 -263.555988)
		(width 0.350012)
		(layer "F.Cu")
		(net "PVDDIO_P0")
	)
	(segment
		(start 335.577942 -265.720068)
		(end 335.11109 -265.986006)
		(width 0.350012)
		(layer "F.Cu")
		(net "PVDDIO_P0")
	)
	(segment
		(start 344.678 -243.940076)
		(end 344.211148 -243.674138)
		(width 0.350012)
		(layer "F.Cu")
		(net "PVDDIO_P0")
	)
	(segment
		(start 335.108042 -268.150086)
		(end 334.64119 -268.416024)
		(width 0.350012)
		(layer "F.Cu")
		(net "PVDDIO_P0")
	)
	(segment
		(start 335.277968 -237.460028)
		(end 334.811116 -237.19409)
		(width 0.350012)
		(layer "F.Cu")
		(net "PVDDIO_P0")
	)
	(segment
		(start 347.797882 -264.100056)
		(end 347.33103 -264.365994)
		(width 0.350012)
		(layer "F.Cu")
		(net "PVDDIO_P0")
	)
	(segment
		(start 342.158066 -270.580104)
		(end 341.691214 -270.846042)
		(width 0.350012)
		(layer "F.Cu")
		(net "PVDDIO_P0")
	)
	(segment
		(start 341.857838 -247.1801)
		(end 341.390986 -246.914162)
		(width 0.350012)
		(layer "F.Cu")
		(net "PVDDIO_P0")
	)
	(segment
		(start 328.527918 -263.29005)
		(end 328.061066 -263.555988)
		(width 0.350012)
		(layer "F.Cu")
		(net "PVDDIO_P0")
	)
	(segment
		(start 328.227944 -254.470154)
		(end 327.761092 -254.204216)
		(width 0.350012)
		(layer "F.Cu")
		(net "PVDDIO_P0")
	)
	(segment
		(start 328.998072 -265.720068)
		(end 328.53122 -265.986006)
		(width 0.350012)
		(layer "F.Cu")
		(net "PVDDIO_P0")
	)
	(segment
		(start 341.687912 -268.150086)
		(end 341.22106 -268.416024)
		(width 0.350012)
		(layer "F.Cu")
		(net "PVDDIO_P0")
	)
	(segment
		(start 341.687912 -282.730194)
		(end 341.22106 -282.996132)
		(width 0.350012)
		(layer "F.Cu")
		(net "PVDDIO_P0")
	)
	(segment
		(start 345.447874 -279.49017)
		(end 344.981022 -279.756108)
		(width 0.350012)
		(layer "F.Cu")
		(net "PVDDIO_P0")
	)
	(segment
		(start 344.678 -240.700052)
		(end 344.211148 -240.434114)
		(width 0.350012)
		(layer "F.Cu")
		(net "PVDDIO_P0")
	)
	(segment
		(start 344.678 -232.599992)
		(end 344.211148 -232.334054)
		(width 0.350012)
		(layer "F.Cu")
		(net "PVDDIO_P0")
	)
	(segment
		(start 347.797882 -260.860032)
		(end 347.33103 -261.12597)
		(width 0.350012)
		(layer "F.Cu")
		(net "PVDDIO_P0")
	)
	(segment
		(start 344.977974 -273.820128)
		(end 344.511122 -274.086066)
		(width 0.350012)
		(layer "F.Cu")
		(net "PVDDIO_P0")
	)
	(segment
		(start 335.277968 -247.1801)
		(end 334.811116 -246.914162)
		(width 0.350012)
		(layer "F.Cu")
		(net "PVDDIO_P0")
	)
	(segment
		(start 335.277968 -252.040136)
		(end 334.811116 -251.774198)
		(width 0.350012)
		(layer "F.Cu")
		(net "PVDDIO_P0")
	)
	(segment
		(start 328.527918 -268.150086)
		(end 328.061066 -268.416024)
		(width 0.350012)
		(layer "F.Cu")
		(net "PVDDIO_P0")
	)
	(segment
		(start 334.808068 -235.03001)
		(end 334.341216 -234.764072)
		(width 0.350012)
		(layer "F.Cu")
		(net "PVDDIO_P0")
	)
	(segment
		(start 345.918028 -260.860032)
		(end 345.451176 -261.12597)
		(width 0.350012)
		(layer "F.Cu")
		(net "PVDDIO_P0")
	)
	(segment
		(start 347.327982 -263.29005)
		(end 346.86113 -263.555988)
		(width 0.350012)
		(layer "F.Cu")
		(net "PVDDIO_P0")
	)
	(segment
		(start 335.108042 -287.59023)
		(end 334.64119 -287.856168)
		(width 0.350012)
		(layer "F.Cu")
		(net "PVDDIO_P0")
	)
	(segment
		(start 328.998072 -275.44014)
		(end 328.53122 -275.706078)
		(width 0.350012)
		(layer "F.Cu")
		(net "PVDDIO_P0")
	)
	(segment
		(start 345.918028 -262.480044)
		(end 345.451176 -262.745982)
		(width 0.350012)
		(layer "F.Cu")
		(net "PVDDIO_P0")
	)
	(segment
		(start 328.527918 -282.730194)
		(end 328.061066 -282.996132)
		(width 0.350012)
		(layer "F.Cu")
		(net "PVDDIO_P0")
	)
	(segment
		(start 341.387938 -249.610118)
		(end 340.921086 -249.34418)
		(width 0.350012)
		(layer "F.Cu")
		(net "PVDDIO_P0")
	)
	(segment
		(start 345.447874 -261.670038)
		(end 344.981022 -261.935976)
		(width 0.350012)
		(layer "F.Cu")
		(net "PVDDIO_P0")
	)
	(segment
		(start 341.857838 -232.599992)
		(end 341.390986 -232.334054)
		(width 0.350012)
		(layer "F.Cu")
		(net "PVDDIO_P0")
	)
	(segment
		(start 342.158066 -265.720068)
		(end 341.691214 -265.986006)
		(width 0.350012)
		(layer "F.Cu")
		(net "PVDDIO_P0")
	)
	(segment
		(start 341.857838 -252.040136)
		(end 341.390986 -251.774198)
		(width 0.350012)
		(layer "F.Cu")
		(net "PVDDIO_P0")
	)
	(segment
		(start 328.697844 -252.040136)
		(end 328.231246 -251.774198)
		(width 0.350012)
		(layer "F.Cu")
		(net "PVDDIO_P0")
	)
	(segment
		(start 328.227944 -230.169974)
		(end 327.761092 -229.904036)
		(width 0.350012)
		(layer "F.Cu")
		(net "PVDDIO_P0")
	)
	(segment
		(start 344.977974 -277.060152)
		(end 344.511122 -277.32609)
		(width 0.350012)
		(layer "F.Cu")
		(net "PVDDIO_P0")
	)
	(segment
		(start 349.20809 -261.670038)
		(end 348.741238 -261.935976)
		(width 0.350012)
		(layer "F.Cu")
		(net "PVDDIO_P0")
	)
	(segment
		(start 328.998072 -270.580104)
		(end 328.53122 -270.846042)
		(width 0.350012)
		(layer "F.Cu")
		(net "PVDDIO_P0")
	)
	(segment
		(start 342.158066 -285.160212)
		(end 341.691214 -285.42615)
		(width 0.350012)
		(layer "F.Cu")
		(net "PVDDIO_P0")
	)
	(segment
		(start 335.277968 -227.74021)
		(end 334.811116 -227.474272)
		(width 0.350012)
		(layer "F.Cu")
		(net "PVDDIO_P0")
	)
	(segment
		(start 328.227944 -244.750082)
		(end 327.761092 -244.484144)
		(width 0.350012)
		(layer "F.Cu")
		(net "PVDDIO_P0")
	)
	(segment
		(start 341.687912 -277.870158)
		(end 341.22106 -278.136096)
		(width 0.350012)
		(layer "F.Cu")
		(net "PVDDIO_P0")
	)
	(segment
		(start 341.857838 -227.74021)
		(end 341.390986 -227.474272)
		(width 0.350012)
		(layer "F.Cu")
		(net "PVDDIO_P0")
	)
	(segment
		(start 345.918028 -264.100056)
		(end 345.451176 -264.365994)
		(width 0.350012)
		(layer "F.Cu")
		(net "PVDDIO_P0")
	)
	(segment
		(start 328.697844 -232.599992)
		(end 328.231246 -232.334054)
		(width 0.350012)
		(layer "F.Cu")
		(net "PVDDIO_P0")
	)
	(segment
		(start 346.557854 -256.900172)
		(end 346.091002 -256.634234)
		(width 0.350012)
		(layer "F.Cu")
		(net "PVDDIO_P0")
	)
	(segment
		(start 345.918028 -265.720068)
		(end 345.451176 -265.986006)
		(width 0.350012)
		(layer "F.Cu")
		(net "PVDDIO_P0")
	)
	(segment
		(start 348.437962 -256.900172)
		(end 347.97111 -256.634234)
		(width 0.350012)
		(layer "F.Cu")
		(net "PVDDIO_P0")
	)
	(segment
		(start 342.158066 -280.300176)
		(end 341.691214 -280.566114)
		(width 0.350012)
		(layer "F.Cu")
		(net "PVDDIO_P0")
	)
	(segment
		(start 328.697844 -247.1801)
		(end 328.231246 -246.914162)
		(width 0.350012)
		(layer "F.Cu")
		(net "PVDDIO_P0")
	)
	(segment
		(start 344.977974 -285.160212)
		(end 344.511122 -285.42615)
		(width 0.350012)
		(layer "F.Cu")
		(net "PVDDIO_P0")
	)
	(segment
		(start 335.277968 -232.599992)
		(end 334.811116 -232.334054)
		(width 0.350012)
		(layer "F.Cu")
		(net "PVDDIO_P0")
	)
	(segment
		(start 344.977974 -270.580104)
		(end 344.511122 -270.846042)
		(width 0.350012)
		(layer "F.Cu")
		(net "PVDDIO_P0")
	)
	(segment
		(start 342.158066 -260.860032)
		(end 341.691214 -261.12597)
		(width 0.350012)
		(layer "F.Cu")
		(net "PVDDIO_P0")
	)
	(segment
		(start 341.687912 -292.450012)
		(end 341.22106 -292.71595)
		(width 0.350012)
		(layer "F.Cu")
		(net "PVDDIO_P0")
	)
	(segment
		(start 335.108042 -273.010122)
		(end 334.64119 -273.27606)
		(width 0.350012)
		(layer "F.Cu")
		(net "PVDDIO_P0")
	)
	(segment
		(start 349.20809 -263.29005)
		(end 348.741238 -263.555988)
		(width 0.350012)
		(layer "F.Cu")
		(net "PVDDIO_P0")
	)
	(segment
		(start 335.108042 -292.450012)
		(end 334.64119 -292.71595)
		(width 0.350012)
		(layer "F.Cu")
		(net "PVDDIO_P0")
	)
	(segment
		(start 341.387938 -235.03001)
		(end 340.921086 -234.764072)
		(width 0.350012)
		(layer "F.Cu")
		(net "PVDDIO_P0")
	)
	(segment
		(start 347.327982 -264.910062)
		(end 346.86113 -265.176)
		(width 0.350012)
		(layer "F.Cu")
		(net "PVDDIO_P0")
	)
	(segment
		(start 329.467972 -294.070024)
		(end 329.00112 -294.335962)
		(width 0.350012)
		(layer "F.Cu")
		(net "PVDDIO_P0")
	)
	(segment
		(start 341.857838 -237.460028)
		(end 341.390986 -237.19409)
		(width 0.350012)
		(layer "F.Cu")
		(net "PVDDIO_P0")
	)
	(segment
		(start 328.227944 -239.890046)
		(end 327.761092 -239.624108)
		(width 0.350012)
		(layer "F.Cu")
		(net "PVDDIO_P0")
	)
	(segment
		(start 328.227944 -249.610118)
		(end 327.761092 -249.34418)
		(width 0.350012)
		(layer "F.Cu")
		(net "PVDDIO_P0")
	)
	(segment
		(start 328.227944 -235.03001)
		(end 327.761092 -234.764072)
		(width 0.350012)
		(layer "F.Cu")
		(net "PVDDIO_P0")
	)
	(segment
		(start 341.687912 -287.59023)
		(end 341.22106 -287.856168)
		(width 0.350012)
		(layer "F.Cu")
		(net "PVDDIO_P0")
	)
	(segment
		(start 344.678 -235.840016)
		(end 344.211148 -235.574078)
		(width 0.350012)
		(layer "F.Cu")
		(net "PVDDIO_P0")
	)
	(segment
		(start 336.047842 -294.070024)
		(end 335.58099 -294.335962)
		(width 0.350012)
		(layer "F.Cu")
		(net "PVDDIO_P0")
	)
	(segment
		(start 334.808068 -249.610118)
		(end 334.341216 -249.34418)
		(width 0.350012)
		(layer "F.Cu")
		(net "PVDDIO_P0")
	)
	(segment
		(start 335.577942 -260.860032)
		(end 335.11109 -261.12597)
		(width 0.350012)
		(layer "F.Cu")
		(net "PVDDIO_P0")
	)
	(segment
		(start 335.108042 -263.29005)
		(end 334.64119 -263.555988)
		(width 0.350012)
		(layer "F.Cu")
		(net "PVDDIO_P0")
	)
	(segment
		(start 347.797882 -262.480044)
		(end 347.33103 -262.745982)
		(width 0.350012)
		(layer "F.Cu")
		(net "PVDDIO_P0")
	)
	(segment
		(start 344.678 -229.360222)
		(end 344.211148 -229.094284)
		(width 0.350012)
		(layer "F.Cu")
		(net "PVDDIO_P0")
	)
	(segment
		(start 344.678 -247.1801)
		(end 344.211148 -246.914162)
		(width 0.350012)
		(layer "F.Cu")
		(net "PVDDIO_P0")
	)
	(segment
		(start 328.697844 -227.74021)
		(end 328.231246 -227.474272)
		(width 0.350012)
		(layer "F.Cu")
		(net "PVDDIO_P0")
	)
	(segment
		(start 342.158066 -275.44014)
		(end 341.691214 -275.706078)
		(width 0.350012)
		(layer "F.Cu")
		(net "PVDDIO_P0")
	)
	(segment
		(start 341.387938 -230.169974)
		(end 340.921086 -229.904036)
		(width 0.350012)
		(layer "F.Cu")
		(net "PVDDIO_P0")
	)
	(segment
		(start 345.447874 -266.530074)
		(end 344.981022 -266.796012)
		(width 0.350012)
		(layer "F.Cu")
		(net "PVDDIO_P0")
	)
	(segment
		(start 347.797882 -265.720068)
		(end 347.33103 -265.986006)
		(width 0.350012)
		(layer "F.Cu")
		(net "PVDDIO_P0")
	)
	(segment
		(start 341.387938 -244.750082)
		(end 340.921086 -244.484144)
		(width 0.350012)
		(layer "F.Cu")
		(net "PVDDIO_P0")
	)
	(segment
		(start 328.527918 -273.010122)
		(end 328.061066 -273.27606)
		(width 0.350012)
		(layer "F.Cu")
		(net "PVDDIO_P0")
	)
	(segment
		(start 344.678 -256.900172)
		(end 344.211148 -256.634234)
		(width 0.350012)
		(layer "F.Cu")
		(net "PVDDIO_P0")
	)
	(segment
		(start 334.808068 -239.890046)
		(end 334.341216 -239.624108)
		(width 0.350012)
		(layer "F.Cu")
		(net "PVDDIO_P0")
	)
	(segment
		(start 328.998072 -285.160212)
		(end 328.53122 -285.42615)
		(width 0.350012)
		(layer "F.Cu")
		(net "PVDDIO_P0")
	)
	(segment
		(start 328.527918 -277.870158)
		(end 328.061066 -278.136096)
		(width 0.350012)
		(layer "F.Cu")
		(net "PVDDIO_P0")
	)
	(segment
		(start 328.527918 -292.450012)
		(end 328.061066 -292.71595)
		(width 0.350012)
		(layer "F.Cu")
		(net "PVDDIO_P0")
	)
	(segment
		(start 328.527918 -287.59023)
		(end 328.061066 -287.856168)
		(width 0.350012)
		(layer "F.Cu")
		(net "PVDDIO_P0")
	)
	(segment
		(start 334.808068 -244.750082)
		(end 334.341216 -244.484144)
		(width 0.350012)
		(layer "F.Cu")
		(net "PVDDIO_P0")
	)
	(segment
		(start 334.808068 -230.169974)
		(end 334.341216 -229.904036)
		(width 0.350012)
		(layer "F.Cu")
		(net "PVDDIO_P0")
	)
	(segment
		(start 335.577942 -270.580104)
		(end 335.11109 -270.846042)
		(width 0.350012)
		(layer "F.Cu")
		(net "PVDDIO_P0")
	)
	(segment
		(start 335.577942 -290.019994)
		(end 335.11109 -290.285932)
		(width 0.350012)
		(layer "F.Cu")
		(net "PVDDIO_P0")
	)
	(segment
		(start 328.998072 -280.300176)
		(end 328.53122 -280.566114)
		(width 0.350012)
		(layer "F.Cu")
		(net "PVDDIO_P0")
	)
	(segment
		(start 345.1479 -238.270034)
		(end 344.681048 -238.004096)
		(width 0.350012)
		(layer "F.Cu")
		(net "PVDDIO_P0")
	)
	(segment
		(start 335.108042 -277.870158)
		(end 334.64119 -278.136096)
		(width 0.350012)
		(layer "F.Cu")
		(net "PVDDIO_P0")
	)
	(segment
		(start 334.808068 -254.470154)
		(end 334.341216 -254.204216)
		(width 0.350012)
		(layer "F.Cu")
		(net "PVDDIO_P0")
	)
	(segment
		(start 347.327982 -261.670038)
		(end 346.86113 -261.935976)
		(width 0.350012)
		(layer "F.Cu")
		(net "PVDDIO_P0")
	)
	(segment
		(start 345.447874 -264.910062)
		(end 344.981022 -265.176)
		(width 0.350012)
		(layer "F.Cu")
		(net "PVDDIO_P0")
	)
	(segment
		(start 328.697844 -242.320064)
		(end 328.231246 -242.054126)
		(width 0.350012)
		(layer "F.Cu")
		(net "PVDDIO_P0")
	)
	(segment
		(start 328.998072 -290.019994)
		(end 328.53122 -290.285932)
		(width 0.350012)
		(layer "F.Cu")
		(net "PVDDIO_P0")
	)
	(segment
		(start 342.158066 -290.019994)
		(end 341.691214 -290.285932)
		(width 0.350012)
		(layer "F.Cu")
		(net "PVDDIO_P0")
	)
	(segment
		(start 335.277968 -242.320064)
		(end 334.811116 -242.054126)
		(width 0.350012)
		(layer "F.Cu")
		(net "PVDDIO_P0")
	)
	(segment
		(start 335.108042 -282.730194)
		(end 334.64119 -282.996132)
		(width 0.350012)
		(layer "F.Cu")
		(net "PVDDIO_P0")
	)
	(segment
		(start 341.387938 -254.470154)
		(end 340.921086 -254.204216)
		(width 0.350012)
		(layer "F.Cu")
		(net "PVDDIO_P0")
	)
	(segment
		(start 341.857838 -242.320064)
		(end 341.390986 -242.054126)
		(width 0.350012)
		(layer "F.Cu")
		(net "PVDDIO_P0")
	)
	(segment
		(start 344.977974 -281.920188)
		(end 344.511122 -282.186126)
		(width 0.350012)
		(layer "F.Cu")
		(net "PVDDIO_P0")
	)
	(segment
		(start 335.577942 -285.160212)
		(end 335.11109 -285.42615)
		(width 0.350012)
		(layer "F.Cu")
		(net "PVDDIO_P0")
	)
	(segment
		(start 341.387938 -239.890046)
		(end 340.921086 -239.624108)
		(width 0.350012)
		(layer "F.Cu")
		(net "PVDDIO_P0")
	)
	(segment
		(start 349.20809 -264.910062)
		(end 348.741238 -265.176)
		(width 0.350012)
		(layer "F.Cu")
		(net "PVDDIO_P0")
	)
	(segment
		(start 341.687912 -273.010122)
		(end 341.22106 -273.27606)
		(width 0.350012)
		(layer "F.Cu")
		(net "PVDDIO_P0")
	)
	(segment
		(start 328.697844 -237.460028)
		(end 328.231246 -237.19409)
		(width 0.350012)
		(layer "F.Cu")
		(net "PVDDIO_P0")
	)
	(segment
		(start 344.977974 -288.399982)
		(end 344.511122 -288.66592)
		(width 0.350012)
		(layer "F.Cu")
		(net "PVDDIO_P0")
	)
	(segment
		(start 335.577942 -275.44014)
		(end 335.11109 -275.706078)
		(width 0.350012)
		(layer "F.Cu")
		(net "PVDDIO_P0")
	)
	(segment
		(start 341.687912 -263.29005)
		(end 341.22106 -263.555988)
		(width 0.350012)
		(layer "F.Cu")
		(net "PVDDIO_P0")
	)
	(via
		(at 290.754562 -333.466694)
		(size 0.508)
		(drill 0.254)
		(layers "F.Cu" "B.Cu")
		(net "PVDDIO_P0")
	)
	(via
		(at 273.533362 -332.831694)
		(size 0.508)
		(drill 0.254)
		(layers "F.Cu" "B.Cu")
		(net "PVDDIO_P0")
	)
	(via
		(at 334.64119 -282.996132)
		(size 0.4064)
		(drill 0.2032)
		(layers "F.Cu" "B.Cu")
		(net "PVDDIO_P0")
	)
	(via
		(at 276.047454 -329.535028)
		(size 0.6604)
		(drill 0.3302)
		(layers "F.Cu" "B.Cu")
		(net "PVDDIO_P0")
	)
	(via
		(at 334.811116 -232.334054)
		(size 0.4064)
		(drill 0.2032)
		(layers "F.Cu" "B.Cu")
		(net "PVDDIO_P0")
	)
	(via
		(at 341.390986 -237.19409)
		(size 0.4064)
		(drill 0.2032)
		(layers "F.Cu" "B.Cu")
		(net "PVDDIO_P0")
	)
	(via
		(at 301.854362 -334.736694)
		(size 0.508)
		(drill 0.254)
		(layers "F.Cu" "B.Cu")
		(net "PVDDIO_P0")
	)
	(via
		(at 278.181562 -332.196694)
		(size 0.508)
		(drill 0.254)
		(layers "F.Cu" "B.Cu")
		(net "PVDDIO_P0")
	)
	(via
		(at 353.43084 -257.430016)
		(size 0.4826)
		(drill 0.254)
		(layers "F.Cu" "B.Cu")
		(net "PVDDIO_P0")
	)
	(via
		(at 344.211148 -235.574078)
		(size 0.4064)
		(drill 0.2032)
		(layers "F.Cu" "B.Cu")
		(net "PVDDIO_P0")
	)
	(via
		(at 340.921086 -239.624108)
		(size 0.4064)
		(drill 0.2032)
		(layers "F.Cu" "B.Cu")
		(net "PVDDIO_P0")
	)
	(via
		(at 274.168362 -332.831694)
		(size 0.508)
		(drill 0.254)
		(layers "F.Cu" "B.Cu")
		(net "PVDDIO_P0")
	)
	(via
		(at 345.451176 -265.986006)
		(size 0.4064)
		(drill 0.2032)
		(layers "F.Cu" "B.Cu")
		(net "PVDDIO_P0")
	)
	(via
		(at 290.754562 -334.101694)
		(size 0.508)
		(drill 0.254)
		(layers "F.Cu" "B.Cu")
		(net "PVDDIO_P0")
	)
	(via
		(at 353.43084 -260.28015)
		(size 0.4826)
		(drill 0.254)
		(layers "F.Cu" "B.Cu")
		(net "PVDDIO_P0")
	)
	(via
		(at 290.754562 -330.291694)
		(size 0.508)
		(drill 0.254)
		(layers "F.Cu" "B.Cu")
		(net "PVDDIO_P0")
	)
	(via
		(at 274.168362 -331.561694)
		(size 0.508)
		(drill 0.254)
		(layers "F.Cu" "B.Cu")
		(net "PVDDIO_P0")
	)
	(via
		(at 328.53122 -275.706078)
		(size 0.4064)
		(drill 0.2032)
		(layers "F.Cu" "B.Cu")
		(net "PVDDIO_P0")
	)
	(via
		(at 289.484562 -330.926694)
		(size 0.508)
		(drill 0.254)
		(layers "F.Cu" "B.Cu")
		(net "PVDDIO_P0")
	)
	(via
		(at 278.181562 -331.561694)
		(size 0.508)
		(drill 0.254)
		(layers "F.Cu" "B.Cu")
		(net "PVDDIO_P0")
	)
	(via
		(at 341.22106 -273.27606)
		(size 0.4064)
		(drill 0.2032)
		(layers "F.Cu" "B.Cu")
		(net "PVDDIO_P0")
	)
	(via
		(at 294.767762 -332.196694)
		(size 0.508)
		(drill 0.254)
		(layers "F.Cu" "B.Cu")
		(net "PVDDIO_P0")
	)
	(via
		(at 294.767762 -332.831694)
		(size 0.508)
		(drill 0.254)
		(layers "F.Cu" "B.Cu")
		(net "PVDDIO_P0")
	)
	(via
		(at 301.854362 -330.291694)
		(size 0.508)
		(drill 0.254)
		(layers "F.Cu" "B.Cu")
		(net "PVDDIO_P0")
	)
	(via
		(at 334.341216 -229.904036)
		(size 0.4064)
		(drill 0.2032)
		(layers "F.Cu" "B.Cu")
		(net "PVDDIO_P0")
	)
	(via
		(at 289.484562 -331.561694)
		(size 0.508)
		(drill 0.254)
		(layers "F.Cu" "B.Cu")
		(net "PVDDIO_P0")
	)
	(via
		(at 282.448762 -332.196694)
		(size 0.508)
		(drill 0.254)
		(layers "F.Cu" "B.Cu")
		(net "PVDDIO_P0")
	)
	(via
		(at 303.124362 -332.196694)
		(size 0.508)
		(drill 0.254)
		(layers "F.Cu" "B.Cu")
		(net "PVDDIO_P0")
	)
	(via
		(at 328.53122 -265.986006)
		(size 0.4064)
		(drill 0.2032)
		(layers "F.Cu" "B.Cu")
		(net "PVDDIO_P0")
	)
	(via
		(at 335.11109 -275.706078)
		(size 0.4064)
		(drill 0.2032)
		(layers "F.Cu" "B.Cu")
		(net "PVDDIO_P0")
	)
	(via
		(at 293.497762 -330.926694)
		(size 0.508)
		(drill 0.254)
		(layers "F.Cu" "B.Cu")
		(net "PVDDIO_P0")
	)
	(via
		(at 285.191962 -334.736694)
		(size 0.508)
		(drill 0.254)
		(layers "F.Cu" "B.Cu")
		(net "PVDDIO_P0")
	)
	(via
		(at 341.390986 -232.334054)
		(size 0.4064)
		(drill 0.2032)
		(layers "F.Cu" "B.Cu")
		(net "PVDDIO_P0")
	)
	(via
		(at 302.489362 -332.831694)
		(size 0.508)
		(drill 0.254)
		(layers "F.Cu" "B.Cu")
		(net "PVDDIO_P0")
	)
	(via
		(at 281.178762 -334.736694)
		(size 0.508)
		(drill 0.254)
		(layers "F.Cu" "B.Cu")
		(net "PVDDIO_P0")
	)
	(via
		(at 294.132762 -330.291694)
		(size 0.508)
		(drill 0.254)
		(layers "F.Cu" "B.Cu")
		(net "PVDDIO_P0")
	)
	(via
		(at 346.86113 -263.555988)
		(size 0.4064)
		(drill 0.2032)
		(layers "F.Cu" "B.Cu")
		(net "PVDDIO_P0")
	)
	(via
		(at 274.168362 -330.291694)
		(size 0.508)
		(drill 0.254)
		(layers "F.Cu" "B.Cu")
		(net "PVDDIO_P0")
	)
	(via
		(at 344.211148 -229.094284)
		(size 0.4064)
		(drill 0.2032)
		(layers "F.Cu" "B.Cu")
		(net "PVDDIO_P0")
	)
	(via
		(at 301.854362 -331.561694)
		(size 0.508)
		(drill 0.254)
		(layers "F.Cu" "B.Cu")
		(net "PVDDIO_P0")
	)
	(via
		(at 344.211148 -232.334054)
		(size 0.4064)
		(drill 0.2032)
		(layers "F.Cu" "B.Cu")
		(net "PVDDIO_P0")
	)
	(via
		(at 328.53122 -290.285932)
		(size 0.4064)
		(drill 0.2032)
		(layers "F.Cu" "B.Cu")
		(net "PVDDIO_P0")
	)
	(via
		(at 327.761092 -249.34418)
		(size 0.4064)
		(drill 0.2032)
		(layers "F.Cu" "B.Cu")
		(net "PVDDIO_P0")
	)
	(via
		(at 281.178762 -332.196694)
		(size 0.508)
		(drill 0.254)
		(layers "F.Cu" "B.Cu")
		(net "PVDDIO_P0")
	)
	(via
		(at 277.546562 -334.736694)
		(size 0.508)
		(drill 0.254)
		(layers "F.Cu" "B.Cu")
		(net "PVDDIO_P0")
	)
	(via
		(at 346.86113 -261.935976)
		(size 0.4064)
		(drill 0.2032)
		(layers "F.Cu" "B.Cu")
		(net "PVDDIO_P0")
	)
	(via
		(at 277.546562 -331.561694)
		(size 0.508)
		(drill 0.254)
		(layers "F.Cu" "B.Cu")
		(net "PVDDIO_P0")
	)
	(via
		(at 277.546562 -334.101694)
		(size 0.508)
		(drill 0.254)
		(layers "F.Cu" "B.Cu")
		(net "PVDDIO_P0")
	)
	(via
		(at 341.390986 -227.474272)
		(size 0.4064)
		(drill 0.2032)
		(layers "F.Cu" "B.Cu")
		(net "PVDDIO_P0")
	)
	(via
		(at 289.484562 -334.736694)
		(size 0.508)
		(drill 0.254)
		(layers "F.Cu" "B.Cu")
		(net "PVDDIO_P0")
	)
	(via
		(at 294.132762 -334.736694)
		(size 0.508)
		(drill 0.254)
		(layers "F.Cu" "B.Cu")
		(net "PVDDIO_P0")
	)
	(via
		(at 353.43084 -259.33019)
		(size 0.4826)
		(drill 0.254)
		(layers "F.Cu" "B.Cu")
		(net "PVDDIO_P0")
	)
	(via
		(at 328.231246 -246.914162)
		(size 0.4064)
		(drill 0.2032)
		(layers "F.Cu" "B.Cu")
		(net "PVDDIO_P0")
	)
	(via
		(at 345.451176 -264.365994)
		(size 0.4064)
		(drill 0.2032)
		(layers "F.Cu" "B.Cu")
		(net "PVDDIO_P0")
	)
	(via
		(at 272.898362 -330.291694)
		(size 0.508)
		(drill 0.254)
		(layers "F.Cu" "B.Cu")
		(net "PVDDIO_P0")
	)
	(via
		(at 286.461962 -330.926694)
		(size 0.508)
		(drill 0.254)
		(layers "F.Cu" "B.Cu")
		(net "PVDDIO_P0")
	)
	(via
		(at 290.119562 -333.466694)
		(size 0.508)
		(drill 0.254)
		(layers "F.Cu" "B.Cu")
		(net "PVDDIO_P0")
	)
	(via
		(at 328.061066 -292.71595)
		(size 0.4064)
		(drill 0.2032)
		(layers "F.Cu" "B.Cu")
		(net "PVDDIO_P0")
	)
	(via
		(at 294.132762 -334.101694)
		(size 0.508)
		(drill 0.254)
		(layers "F.Cu" "B.Cu")
		(net "PVDDIO_P0")
	)
	(via
		(at 297.061128 -350.498156)
		(size 0.508)
		(drill 0.254)
		(layers "F.Cu" "B.Cu")
		(net "PVDDIO_P0")
	)
	(via
		(at 290.119562 -334.101694)
		(size 0.508)
		(drill 0.254)
		(layers "F.Cu" "B.Cu")
		(net "PVDDIO_P0")
	)
	(via
		(at 298.476162 -330.291694)
		(size 0.508)
		(drill 0.254)
		(layers "F.Cu" "B.Cu")
		(net "PVDDIO_P0")
	)
	(via
		(at 285.826962 -334.736694)
		(size 0.508)
		(drill 0.254)
		(layers "F.Cu" "B.Cu")
		(net "PVDDIO_P0")
	)
	(via
		(at 282.448762 -331.561694)
		(size 0.508)
		(drill 0.254)
		(layers "F.Cu" "B.Cu")
		(net "PVDDIO_P0")
	)
	(via
		(at 327.761092 -239.624108)
		(size 0.4064)
		(drill 0.2032)
		(layers "F.Cu" "B.Cu")
		(net "PVDDIO_P0")
	)
	(via
		(at 348.741238 -265.176)
		(size 0.4064)
		(drill 0.2032)
		(layers "F.Cu" "B.Cu")
		(net "PVDDIO_P0")
	)
	(via
		(at 344.981022 -279.756108)
		(size 0.4064)
		(drill 0.2032)
		(layers "F.Cu" "B.Cu")
		(net "PVDDIO_P0")
	)
	(via
		(at 290.119562 -334.736694)
		(size 0.508)
		(drill 0.254)
		(layers "F.Cu" "B.Cu")
		(net "PVDDIO_P0")
	)
	(via
		(at 281.178762 -330.291694)
		(size 0.508)
		(drill 0.254)
		(layers "F.Cu" "B.Cu")
		(net "PVDDIO_P0")
	)
	(via
		(at 346.080842 -258.830064)
		(size 0.4826)
		(drill 0.254)
		(layers "F.Cu" "B.Cu")
		(net "PVDDIO_P0")
	)
	(via
		(at 274.168362 -330.926694)
		(size 0.508)
		(drill 0.254)
		(layers "F.Cu" "B.Cu")
		(net "PVDDIO_P0")
	)
	(via
		(at 294.132762 -330.926694)
		(size 0.508)
		(drill 0.254)
		(layers "F.Cu" "B.Cu")
		(net "PVDDIO_P0")
	)
	(via
		(at 285.826962 -331.561694)
		(size 0.508)
		(drill 0.254)
		(layers "F.Cu" "B.Cu")
		(net "PVDDIO_P0")
	)
	(via
		(at 272.118328 -350.498156)
		(size 0.508)
		(drill 0.254)
		(layers "F.Cu" "B.Cu")
		(net "PVDDIO_P0")
	)
	(via
		(at 341.691214 -275.706078)
		(size 0.4064)
		(drill 0.2032)
		(layers "F.Cu" "B.Cu")
		(net "PVDDIO_P0")
	)
	(via
		(at 285.191962 -332.196694)
		(size 0.508)
		(drill 0.254)
		(layers "F.Cu" "B.Cu")
		(net "PVDDIO_P0")
	)
	(via
		(at 344.511122 -277.32609)
		(size 0.4064)
		(drill 0.2032)
		(layers "F.Cu" "B.Cu")
		(net "PVDDIO_P0")
	)
	(via
		(at 298.476162 -333.466694)
		(size 0.508)
		(drill 0.254)
		(layers "F.Cu" "B.Cu")
		(net "PVDDIO_P0")
	)
	(via
		(at 285.826962 -330.291694)
		(size 0.508)
		(drill 0.254)
		(layers "F.Cu" "B.Cu")
		(net "PVDDIO_P0")
	)
	(via
		(at 340.921086 -234.764072)
		(size 0.4064)
		(drill 0.2032)
		(layers "F.Cu" "B.Cu")
		(net "PVDDIO_P0")
	)
	(via
		(at 344.511122 -274.086066)
		(size 0.4064)
		(drill 0.2032)
		(layers "F.Cu" "B.Cu")
		(net "PVDDIO_P0")
	)
	(via
		(at 290.754562 -331.561694)
		(size 0.508)
		(drill 0.254)
		(layers "F.Cu" "B.Cu")
		(net "PVDDIO_P0")
	)
	(via
		(at 347.33103 -265.986006)
		(size 0.4064)
		(drill 0.2032)
		(layers "F.Cu" "B.Cu")
		(net "PVDDIO_P0")
	)
	(via
		(at 353.43084 -258.379976)
		(size 0.4826)
		(drill 0.254)
		(layers "F.Cu" "B.Cu")
		(net "PVDDIO_P0")
	)
	(via
		(at 293.497762 -332.831694)
		(size 0.508)
		(drill 0.254)
		(layers "F.Cu" "B.Cu")
		(net "PVDDIO_P0")
	)
	(via
		(at 341.390986 -246.914162)
		(size 0.4064)
		(drill 0.2032)
		(layers "F.Cu" "B.Cu")
		(net "PVDDIO_P0")
	)
	(via
		(at 299.111162 -332.196694)
		(size 0.508)
		(drill 0.254)
		(layers "F.Cu" "B.Cu")
		(net "PVDDIO_P0")
	)
	(via
		(at 293.497762 -334.101694)
		(size 0.508)
		(drill 0.254)
		(layers "F.Cu" "B.Cu")
		(net "PVDDIO_P0")
	)
	(via
		(at 289.484562 -333.466694)
		(size 0.508)
		(drill 0.254)
		(layers "F.Cu" "B.Cu")
		(net "PVDDIO_P0")
	)
	(via
		(at 293.497762 -331.561694)
		(size 0.508)
		(drill 0.254)
		(layers "F.Cu" "B.Cu")
		(net "PVDDIO_P0")
	)
	(via
		(at 347.33103 -264.365994)
		(size 0.4064)
		(drill 0.2032)
		(layers "F.Cu" "B.Cu")
		(net "PVDDIO_P0")
	)
	(via
		(at 281.178762 -332.831694)
		(size 0.508)
		(drill 0.254)
		(layers "F.Cu" "B.Cu")
		(net "PVDDIO_P0")
	)
	(via
		(at 340.921086 -254.204216)
		(size 0.4064)
		(drill 0.2032)
		(layers "F.Cu" "B.Cu")
		(net "PVDDIO_P0")
	)
	(via
		(at 274.168362 -334.101694)
		(size 0.508)
		(drill 0.254)
		(layers "F.Cu" "B.Cu")
		(net "PVDDIO_P0")
	)
	(via
		(at 349.880682 -259.729986)
		(size 0.4826)
		(drill 0.254)
		(layers "F.Cu" "B.Cu")
		(net "PVDDIO_P0")
	)
	(via
		(at 355.85781 -258.795012)
		(size 0.4826)
		(drill 0.254)
		(layers "F.Cu" "B.Cu")
		(net "PVDDIO_P0")
	)
	(via
		(at 285.191962 -330.291694)
		(size 0.508)
		(drill 0.254)
		(layers "F.Cu" "B.Cu")
		(net "PVDDIO_P0")
	)
	(via
		(at 344.981022 -263.555988)
		(size 0.4064)
		(drill 0.2032)
		(layers "F.Cu" "B.Cu")
		(net "PVDDIO_P0")
	)
	(via
		(at 297.841162 -332.831694)
		(size 0.508)
		(drill 0.254)
		(layers "F.Cu" "B.Cu")
		(net "PVDDIO_P0")
	)
	(via
		(at 282.448762 -330.926694)
		(size 0.508)
		(drill 0.254)
		(layers "F.Cu" "B.Cu")
		(net "PVDDIO_P0")
	)
	(via
		(at 273.533362 -331.561694)
		(size 0.508)
		(drill 0.254)
		(layers "F.Cu" "B.Cu")
		(net "PVDDIO_P0")
	)
	(via
		(at 334.811116 -242.054126)
		(size 0.4064)
		(drill 0.2032)
		(layers "F.Cu" "B.Cu")
		(net "PVDDIO_P0")
	)
	(via
		(at 272.898362 -331.561694)
		(size 0.508)
		(drill 0.254)
		(layers "F.Cu" "B.Cu")
		(net "PVDDIO_P0")
	)
	(via
		(at 344.981022 -261.935976)
		(size 0.4064)
		(drill 0.2032)
		(layers "F.Cu" "B.Cu")
		(net "PVDDIO_P0")
	)
	(via
		(at 282.448762 -334.736694)
		(size 0.508)
		(drill 0.254)
		(layers "F.Cu" "B.Cu")
		(net "PVDDIO_P0")
	)
	(via
		(at 281.813762 -330.291694)
		(size 0.508)
		(drill 0.254)
		(layers "F.Cu" "B.Cu")
		(net "PVDDIO_P0")
	)
	(via
		(at 289.484562 -332.831694)
		(size 0.508)
		(drill 0.254)
		(layers "F.Cu" "B.Cu")
		(net "PVDDIO_P0")
	)
	(via
		(at 278.181562 -334.101694)
		(size 0.508)
		(drill 0.254)
		(layers "F.Cu" "B.Cu")
		(net "PVDDIO_P0")
	)
	(via
		(at 294.132762 -331.561694)
		(size 0.508)
		(drill 0.254)
		(layers "F.Cu" "B.Cu")
		(net "PVDDIO_P0")
	)
	(via
		(at 328.231246 -251.774198)
		(size 0.4064)
		(drill 0.2032)
		(layers "F.Cu" "B.Cu")
		(net "PVDDIO_P0")
	)
	(via
		(at 346.091002 -256.634234)
		(size 0.4064)
		(drill 0.2032)
		(layers "F.Cu" "B.Cu")
		(net "PVDDIO_P0")
	)
	(via
		(at 282.448762 -332.831694)
		(size 0.508)
		(drill 0.254)
		(layers "F.Cu" "B.Cu")
		(net "PVDDIO_P0")
	)
	(via
		(at 286.461962 -331.561694)
		(size 0.508)
		(drill 0.254)
		(layers "F.Cu" "B.Cu")
		(net "PVDDIO_P0")
	)
	(via
		(at 272.898362 -334.101694)
		(size 0.508)
		(drill 0.254)
		(layers "F.Cu" "B.Cu")
		(net "PVDDIO_P0")
	)
	(via
		(at 290.754562 -330.926694)
		(size 0.508)
		(drill 0.254)
		(layers "F.Cu" "B.Cu")
		(net "PVDDIO_P0")
	)
	(via
		(at 297.841162 -330.291694)
		(size 0.508)
		(drill 0.254)
		(layers "F.Cu" "B.Cu")
		(net "PVDDIO_P0")
	)
	(via
		(at 328.231246 -232.334054)
		(size 0.4064)
		(drill 0.2032)
		(layers "F.Cu" "B.Cu")
		(net "PVDDIO_P0")
	)
	(via
		(at 347.97111 -256.634234)
		(size 0.4064)
		(drill 0.2032)
		(layers "F.Cu" "B.Cu")
		(net "PVDDIO_P0")
	)
	(via
		(at 293.497762 -330.291694)
		(size 0.508)
		(drill 0.254)
		(layers "F.Cu" "B.Cu")
		(net "PVDDIO_P0")
	)
	(via
		(at 301.854362 -332.831694)
		(size 0.508)
		(drill 0.254)
		(layers "F.Cu" "B.Cu")
		(net "PVDDIO_P0")
	)
	(via
		(at 341.691214 -285.42615)
		(size 0.4064)
		(drill 0.2032)
		(layers "F.Cu" "B.Cu")
		(net "PVDDIO_P0")
	)
	(via
		(at 328.061066 -263.555988)
		(size 0.4064)
		(drill 0.2032)
		(layers "F.Cu" "B.Cu")
		(net "PVDDIO_P0")
	)
	(via
		(at 285.826962 -330.926694)
		(size 0.508)
		(drill 0.254)
		(layers "F.Cu" "B.Cu")
		(net "PVDDIO_P0")
	)
	(via
		(at 278.181562 -332.831694)
		(size 0.508)
		(drill 0.254)
		(layers "F.Cu" "B.Cu")
		(net "PVDDIO_P0")
	)
	(via
		(at 285.191962 -332.831694)
		(size 0.508)
		(drill 0.254)
		(layers "F.Cu" "B.Cu")
		(net "PVDDIO_P0")
	)
	(via
		(at 334.811116 -237.19409)
		(size 0.4064)
		(drill 0.2032)
		(layers "F.Cu" "B.Cu")
		(net "PVDDIO_P0")
	)
	(via
		(at 281.813762 -331.561694)
		(size 0.508)
		(drill 0.254)
		(layers "F.Cu" "B.Cu")
		(net "PVDDIO_P0")
	)
	(via
		(at 290.754562 -332.831694)
		(size 0.508)
		(drill 0.254)
		(layers "F.Cu" "B.Cu")
		(net "PVDDIO_P0")
	)
	(via
		(at 282.448762 -334.101694)
		(size 0.508)
		(drill 0.254)
		(layers "F.Cu" "B.Cu")
		(net "PVDDIO_P0")
	)
	(via
		(at 327.761092 -244.484144)
		(size 0.4064)
		(drill 0.2032)
		(layers "F.Cu" "B.Cu")
		(net "PVDDIO_P0")
	)
	(via
		(at 301.854362 -332.196694)
		(size 0.508)
		(drill 0.254)
		(layers "F.Cu" "B.Cu")
		(net "PVDDIO_P0")
	)
	(via
		(at 328.53122 -280.566114)
		(size 0.4064)
		(drill 0.2032)
		(layers "F.Cu" "B.Cu")
		(net "PVDDIO_P0")
	)
	(via
		(at 282.448762 -333.466694)
		(size 0.508)
		(drill 0.254)
		(layers "F.Cu" "B.Cu")
		(net "PVDDIO_P0")
	)
	(via
		(at 294.132762 -332.831694)
		(size 0.508)
		(drill 0.254)
		(layers "F.Cu" "B.Cu")
		(net "PVDDIO_P0")
	)
	(via
		(at 272.898362 -332.831694)
		(size 0.508)
		(drill 0.254)
		(layers "F.Cu" "B.Cu")
		(net "PVDDIO_P0")
	)
	(via
		(at 341.22106 -278.136096)
		(size 0.4064)
		(drill 0.2032)
		(layers "F.Cu" "B.Cu")
		(net "PVDDIO_P0")
	)
	(via
		(at 347.33103 -262.745982)
		(size 0.4064)
		(drill 0.2032)
		(layers "F.Cu" "B.Cu")
		(net "PVDDIO_P0")
	)
	(via
		(at 344.681048 -238.004096)
		(size 0.4064)
		(drill 0.2032)
		(layers "F.Cu" "B.Cu")
		(net "PVDDIO_P0")
	)
	(via
		(at 348.741238 -263.555988)
		(size 0.4064)
		(drill 0.2032)
		(layers "F.Cu" "B.Cu")
		(net "PVDDIO_P0")
	)
	(via
		(at 281.813762 -332.196694)
		(size 0.508)
		(drill 0.254)
		(layers "F.Cu" "B.Cu")
		(net "PVDDIO_P0")
	)
	(via
		(at 293.497762 -332.196694)
		(size 0.508)
		(drill 0.254)
		(layers "F.Cu" "B.Cu")
		(net "PVDDIO_P0")
	)
	(via
		(at 301.854362 -334.101694)
		(size 0.508)
		(drill 0.254)
		(layers "F.Cu" "B.Cu")
		(net "PVDDIO_P0")
	)
	(via
		(at 276.911562 -332.831694)
		(size 0.508)
		(drill 0.254)
		(layers "F.Cu" "B.Cu")
		(net "PVDDIO_P0")
	)
	(via
		(at 278.181562 -334.736694)
		(size 0.508)
		(drill 0.254)
		(layers "F.Cu" "B.Cu")
		(net "PVDDIO_P0")
	)
	(via
		(at 335.11109 -285.42615)
		(size 0.4064)
		(drill 0.2032)
		(layers "F.Cu" "B.Cu")
		(net "PVDDIO_P0")
	)
	(via
		(at 290.119562 -332.196694)
		(size 0.508)
		(drill 0.254)
		(layers "F.Cu" "B.Cu")
		(net "PVDDIO_P0")
	)
	(via
		(at 303.124362 -333.466694)
		(size 0.508)
		(drill 0.254)
		(layers "F.Cu" "B.Cu")
		(net "PVDDIO_P0")
	)
	(via
		(at 277.546562 -332.196694)
		(size 0.508)
		(drill 0.254)
		(layers "F.Cu" "B.Cu")
		(net "PVDDIO_P0")
	)
	(via
		(at 276.911562 -334.101694)
		(size 0.508)
		(drill 0.254)
		(layers "F.Cu" "B.Cu")
		(net "PVDDIO_P0")
	)
	(via
		(at 297.841162 -334.736694)
		(size 0.508)
		(drill 0.254)
		(layers "F.Cu" "B.Cu")
		(net "PVDDIO_P0")
	)
	(via
		(at 286.461962 -333.466694)
		(size 0.508)
		(drill 0.254)
		(layers "F.Cu" "B.Cu")
		(net "PVDDIO_P0")
	)
	(via
		(at 294.767762 -330.926694)
		(size 0.508)
		(drill 0.254)
		(layers "F.Cu" "B.Cu")
		(net "PVDDIO_P0")
	)
	(via
		(at 335.11109 -265.986006)
		(size 0.4064)
		(drill 0.2032)
		(layers "F.Cu" "B.Cu")
		(net "PVDDIO_P0")
	)
	(via
		(at 285.191962 -334.101694)
		(size 0.508)
		(drill 0.254)
		(layers "F.Cu" "B.Cu")
		(net "PVDDIO_P0")
	)
	(via
		(at 299.111162 -331.561694)
		(size 0.508)
		(drill 0.254)
		(layers "F.Cu" "B.Cu")
		(net "PVDDIO_P0")
	)
	(via
		(at 286.461962 -332.196694)
		(size 0.508)
		(drill 0.254)
		(layers "F.Cu" "B.Cu")
		(net "PVDDIO_P0")
	)
	(via
		(at 294.767762 -331.561694)
		(size 0.508)
		(drill 0.254)
		(layers "F.Cu" "B.Cu")
		(net "PVDDIO_P0")
	)
	(via
		(at 345.451176 -261.12597)
		(size 0.4064)
		(drill 0.2032)
		(layers "F.Cu" "B.Cu")
		(net "PVDDIO_P0")
	)
	(via
		(at 285.826962 -332.196694)
		(size 0.508)
		(drill 0.254)
		(layers "F.Cu" "B.Cu")
		(net "PVDDIO_P0")
	)
	(via
		(at 294.132762 -333.466694)
		(size 0.508)
		(drill 0.254)
		(layers "F.Cu" "B.Cu")
		(net "PVDDIO_P0")
	)
	(via
		(at 294.767762 -330.291694)
		(size 0.508)
		(drill 0.254)
		(layers "F.Cu" "B.Cu")
		(net "PVDDIO_P0")
	)
	(via
		(at 297.841162 -333.466694)
		(size 0.508)
		(drill 0.254)
		(layers "F.Cu" "B.Cu")
		(net "PVDDIO_P0")
	)
	(via
		(at 298.476162 -334.736694)
		(size 0.508)
		(drill 0.254)
		(layers "F.Cu" "B.Cu")
		(net "PVDDIO_P0")
	)
	(via
		(at 273.533362 -333.466694)
		(size 0.508)
		(drill 0.254)
		(layers "F.Cu" "B.Cu")
		(net "PVDDIO_P0")
	)
	(via
		(at 303.124362 -331.561694)
		(size 0.508)
		(drill 0.254)
		(layers "F.Cu" "B.Cu")
		(net "PVDDIO_P0")
	)
	(via
		(at 334.341216 -244.484144)
		(size 0.4064)
		(drill 0.2032)
		(layers "F.Cu" "B.Cu")
		(net "PVDDIO_P0")
	)
	(via
		(at 288.704528 -350.498156)
		(size 0.508)
		(drill 0.254)
		(layers "F.Cu" "B.Cu")
		(net "PVDDIO_P0")
	)
	(via
		(at 278.181562 -330.291694)
		(size 0.508)
		(drill 0.254)
		(layers "F.Cu" "B.Cu")
		(net "PVDDIO_P0")
	)
	(via
		(at 344.511122 -282.186126)
		(size 0.4064)
		(drill 0.2032)
		(layers "F.Cu" "B.Cu")
		(net "PVDDIO_P0")
	)
	(via
		(at 301.854362 -333.466694)
		(size 0.508)
		(drill 0.254)
		(layers "F.Cu" "B.Cu")
		(net "PVDDIO_P0")
	)
	(via
		(at 303.124362 -334.101694)
		(size 0.508)
		(drill 0.254)
		(layers "F.Cu" "B.Cu")
		(net "PVDDIO_P0")
	)
	(via
		(at 344.511122 -288.66592)
		(size 0.4064)
		(drill 0.2032)
		(layers "F.Cu" "B.Cu")
		(net "PVDDIO_P0")
	)
	(via
		(at 347.980762 -258.830064)
		(size 0.4826)
		(drill 0.254)
		(layers "F.Cu" "B.Cu")
		(net "PVDDIO_P0")
	)
	(via
		(at 277.546562 -333.466694)
		(size 0.508)
		(drill 0.254)
		(layers "F.Cu" "B.Cu")
		(net "PVDDIO_P0")
	)
	(via
		(at 278.181562 -330.926694)
		(size 0.508)
		(drill 0.254)
		(layers "F.Cu" "B.Cu")
		(net "PVDDIO_P0")
	)
	(via
		(at 301.854362 -330.926694)
		(size 0.508)
		(drill 0.254)
		(layers "F.Cu" "B.Cu")
		(net "PVDDIO_P0")
	)
	(via
		(at 344.511122 -285.42615)
		(size 0.4064)
		(drill 0.2032)
		(layers "F.Cu" "B.Cu")
		(net "PVDDIO_P0")
	)
	(via
		(at 340.921086 -249.34418)
		(size 0.4064)
		(drill 0.2032)
		(layers "F.Cu" "B.Cu")
		(net "PVDDIO_P0")
	)
	(via
		(at 341.390986 -242.054126)
		(size 0.4064)
		(drill 0.2032)
		(layers "F.Cu" "B.Cu")
		(net "PVDDIO_P0")
	)
	(via
		(at 334.811116 -246.914162)
		(size 0.4064)
		(drill 0.2032)
		(layers "F.Cu" "B.Cu")
		(net "PVDDIO_P0")
	)
	(via
		(at 302.489362 -332.196694)
		(size 0.508)
		(drill 0.254)
		(layers "F.Cu" "B.Cu")
		(net "PVDDIO_P0")
	)
	(via
		(at 290.119562 -331.561694)
		(size 0.508)
		(drill 0.254)
		(layers "F.Cu" "B.Cu")
		(net "PVDDIO_P0")
	)
	(via
		(at 344.211148 -243.674138)
		(size 0.4064)
		(drill 0.2032)
		(layers "F.Cu" "B.Cu")
		(net "PVDDIO_P0")
	)
	(via
		(at 272.898362 -333.466694)
		(size 0.508)
		(drill 0.254)
		(layers "F.Cu" "B.Cu")
		(net "PVDDIO_P0")
	)
	(via
		(at 277.546562 -332.831694)
		(size 0.508)
		(drill 0.254)
		(layers "F.Cu" "B.Cu")
		(net "PVDDIO_P0")
	)
	(via
		(at 298.476162 -332.196694)
		(size 0.508)
		(drill 0.254)
		(layers "F.Cu" "B.Cu")
		(net "PVDDIO_P0")
	)
	(via
		(at 341.691214 -270.846042)
		(size 0.4064)
		(drill 0.2032)
		(layers "F.Cu" "B.Cu")
		(net "PVDDIO_P0")
	)
	(via
		(at 329.00112 -294.335962)
		(size 0.4064)
		(drill 0.2032)
		(layers "F.Cu" "B.Cu")
		(net "PVDDIO_P0")
	)
	(via
		(at 327.761092 -229.904036)
		(size 0.4064)
		(drill 0.2032)
		(layers "F.Cu" "B.Cu")
		(net "PVDDIO_P0")
	)
	(via
		(at 276.911562 -333.466694)
		(size 0.508)
		(drill 0.254)
		(layers "F.Cu" "B.Cu")
		(net "PVDDIO_P0")
	)
	(via
		(at 347.980762 -257.930142)
		(size 0.4826)
		(drill 0.254)
		(layers "F.Cu" "B.Cu")
		(net "PVDDIO_P0")
	)
	(via
		(at 272.898362 -334.736694)
		(size 0.508)
		(drill 0.254)
		(layers "F.Cu" "B.Cu")
		(net "PVDDIO_P0")
	)
	(via
		(at 274.168362 -333.466694)
		(size 0.508)
		(drill 0.254)
		(layers "F.Cu" "B.Cu")
		(net "PVDDIO_P0")
	)
	(via
		(at 341.691214 -290.285932)
		(size 0.4064)
		(drill 0.2032)
		(layers "F.Cu" "B.Cu")
		(net "PVDDIO_P0")
	)
	(via
		(at 285.826962 -334.101694)
		(size 0.508)
		(drill 0.254)
		(layers "F.Cu" "B.Cu")
		(net "PVDDIO_P0")
	)
	(via
		(at 286.461962 -334.736694)
		(size 0.508)
		(drill 0.254)
		(layers "F.Cu" "B.Cu")
		(net "PVDDIO_P0")
	)
	(via
		(at 344.211148 -256.634234)
		(size 0.4064)
		(drill 0.2032)
		(layers "F.Cu" "B.Cu")
		(net "PVDDIO_P0")
	)
	(via
		(at 289.484562 -334.101694)
		(size 0.508)
		(drill 0.254)
		(layers "F.Cu" "B.Cu")
		(net "PVDDIO_P0")
	)
	(via
		(at 298.476162 -331.561694)
		(size 0.508)
		(drill 0.254)
		(layers "F.Cu" "B.Cu")
		(net "PVDDIO_P0")
	)
	(via
		(at 294.132762 -332.196694)
		(size 0.508)
		(drill 0.254)
		(layers "F.Cu" "B.Cu")
		(net "PVDDIO_P0")
	)
	(via
		(at 272.898362 -330.926694)
		(size 0.508)
		(drill 0.254)
		(layers "F.Cu" "B.Cu")
		(net "PVDDIO_P0")
	)
	(via
		(at 335.11109 -270.846042)
		(size 0.4064)
		(drill 0.2032)
		(layers "F.Cu" "B.Cu")
		(net "PVDDIO_P0")
	)
	(via
		(at 272.898362 -332.196694)
		(size 0.508)
		(drill 0.254)
		(layers "F.Cu" "B.Cu")
		(net "PVDDIO_P0")
	)
	(via
		(at 334.64119 -273.27606)
		(size 0.4064)
		(drill 0.2032)
		(layers "F.Cu" "B.Cu")
		(net "PVDDIO_P0")
	)
	(via
		(at 340.921086 -229.904036)
		(size 0.4064)
		(drill 0.2032)
		(layers "F.Cu" "B.Cu")
		(net "PVDDIO_P0")
	)
	(via
		(at 335.11109 -290.285932)
		(size 0.4064)
		(drill 0.2032)
		(layers "F.Cu" "B.Cu")
		(net "PVDDIO_P0")
	)
	(via
		(at 334.64119 -287.856168)
		(size 0.4064)
		(drill 0.2032)
		(layers "F.Cu" "B.Cu")
		(net "PVDDIO_P0")
	)
	(via
		(at 344.211148 -240.434114)
		(size 0.4064)
		(drill 0.2032)
		(layers "F.Cu" "B.Cu")
		(net "PVDDIO_P0")
	)
	(via
		(at 328.231246 -242.054126)
		(size 0.4064)
		(drill 0.2032)
		(layers "F.Cu" "B.Cu")
		(net "PVDDIO_P0")
	)
	(via
		(at 335.11109 -280.566114)
		(size 0.4064)
		(drill 0.2032)
		(layers "F.Cu" "B.Cu")
		(net "PVDDIO_P0")
	)
	(via
		(at 347.980762 -259.729986)
		(size 0.4826)
		(drill 0.254)
		(layers "F.Cu" "B.Cu")
		(net "PVDDIO_P0")
	)
	(via
		(at 277.546562 -330.291694)
		(size 0.508)
		(drill 0.254)
		(layers "F.Cu" "B.Cu")
		(net "PVDDIO_P0")
	)
	(via
		(at 288.620454 -329.535028)
		(size 0.6604)
		(drill 0.3302)
		(layers "F.Cu" "B.Cu")
		(net "PVDDIO_P0")
	)
	(via
		(at 328.53122 -261.12597)
		(size 0.4064)
		(drill 0.2032)
		(layers "F.Cu" "B.Cu")
		(net "PVDDIO_P0")
	)
	(via
		(at 303.124362 -330.291694)
		(size 0.508)
		(drill 0.254)
		(layers "F.Cu" "B.Cu")
		(net "PVDDIO_P0")
	)
	(via
		(at 344.981022 -265.176)
		(size 0.4064)
		(drill 0.2032)
		(layers "F.Cu" "B.Cu")
		(net "PVDDIO_P0")
	)
	(via
		(at 334.64119 -268.416024)
		(size 0.4064)
		(drill 0.2032)
		(layers "F.Cu" "B.Cu")
		(net "PVDDIO_P0")
	)
	(via
		(at 290.754562 -332.196694)
		(size 0.508)
		(drill 0.254)
		(layers "F.Cu" "B.Cu")
		(net "PVDDIO_P0")
	)
	(via
		(at 281.178762 -334.101694)
		(size 0.508)
		(drill 0.254)
		(layers "F.Cu" "B.Cu")
		(net "PVDDIO_P0")
	)
	(via
		(at 341.691214 -265.986006)
		(size 0.4064)
		(drill 0.2032)
		(layers "F.Cu" "B.Cu")
		(net "PVDDIO_P0")
	)
	(via
		(at 341.691214 -261.12597)
		(size 0.4064)
		(drill 0.2032)
		(layers "F.Cu" "B.Cu")
		(net "PVDDIO_P0")
	)
	(via
		(at 290.119562 -330.926694)
		(size 0.508)
		(drill 0.254)
		(layers "F.Cu" "B.Cu")
		(net "PVDDIO_P0")
	)
	(via
		(at 297.841162 -332.196694)
		(size 0.508)
		(drill 0.254)
		(layers "F.Cu" "B.Cu")
		(net "PVDDIO_P0")
	)
	(via
		(at 281.178762 -333.466694)
		(size 0.508)
		(drill 0.254)
		(layers "F.Cu" "B.Cu")
		(net "PVDDIO_P0")
	)
	(via
		(at 289.484562 -332.196694)
		(size 0.508)
		(drill 0.254)
		(layers "F.Cu" "B.Cu")
		(net "PVDDIO_P0")
	)
	(via
		(at 277.546562 -330.926694)
		(size 0.508)
		(drill 0.254)
		(layers "F.Cu" "B.Cu")
		(net "PVDDIO_P0")
	)
	(via
		(at 346.86113 -265.176)
		(size 0.4064)
		(drill 0.2032)
		(layers "F.Cu" "B.Cu")
		(net "PVDDIO_P0")
	)
	(via
		(at 302.489362 -330.926694)
		(size 0.508)
		(drill 0.254)
		(layers "F.Cu" "B.Cu")
		(net "PVDDIO_P0")
	)
	(via
		(at 341.22106 -282.996132)
		(size 0.4064)
		(drill 0.2032)
		(layers "F.Cu" "B.Cu")
		(net "PVDDIO_P0")
	)
	(via
		(at 273.533362 -334.736694)
		(size 0.508)
		(drill 0.254)
		(layers "F.Cu" "B.Cu")
		(net "PVDDIO_P0")
	)
	(via
		(at 347.33103 -261.12597)
		(size 0.4064)
		(drill 0.2032)
		(layers "F.Cu" "B.Cu")
		(net "PVDDIO_P0")
	)
	(via
		(at 334.341216 -249.34418)
		(size 0.4064)
		(drill 0.2032)
		(layers "F.Cu" "B.Cu")
		(net "PVDDIO_P0")
	)
	(via
		(at 290.119562 -330.291694)
		(size 0.508)
		(drill 0.254)
		(layers "F.Cu" "B.Cu")
		(net "PVDDIO_P0")
	)
	(via
		(at 302.489362 -333.466694)
		(size 0.508)
		(drill 0.254)
		(layers "F.Cu" "B.Cu")
		(net "PVDDIO_P0")
	)
	(via
		(at 334.811116 -227.474272)
		(size 0.4064)
		(drill 0.2032)
		(layers "F.Cu" "B.Cu")
		(net "PVDDIO_P0")
	)
	(via
		(at 285.826962 -333.466694)
		(size 0.508)
		(drill 0.254)
		(layers "F.Cu" "B.Cu")
		(net "PVDDIO_P0")
	)
	(via
		(at 341.691214 -280.566114)
		(size 0.4064)
		(drill 0.2032)
		(layers "F.Cu" "B.Cu")
		(net "PVDDIO_P0")
	)
	(via
		(at 341.22106 -292.71595)
		(size 0.4064)
		(drill 0.2032)
		(layers "F.Cu" "B.Cu")
		(net "PVDDIO_P0")
	)
	(via
		(at 276.911562 -332.196694)
		(size 0.508)
		(drill 0.254)
		(layers "F.Cu" "B.Cu")
		(net "PVDDIO_P0")
	)
	(via
		(at 285.191962 -333.466694)
		(size 0.508)
		(drill 0.254)
		(layers "F.Cu" "B.Cu")
		(net "PVDDIO_P0")
	)
	(via
		(at 302.489362 -331.561694)
		(size 0.508)
		(drill 0.254)
		(layers "F.Cu" "B.Cu")
		(net "PVDDIO_P0")
	)
	(via
		(at 334.341216 -234.764072)
		(size 0.4064)
		(drill 0.2032)
		(layers "F.Cu" "B.Cu")
		(net "PVDDIO_P0")
	)
	(via
		(at 294.767762 -334.101694)
		(size 0.508)
		(drill 0.254)
		(layers "F.Cu" "B.Cu")
		(net "PVDDIO_P0")
	)
	(via
		(at 298.476162 -330.926694)
		(size 0.508)
		(drill 0.254)
		(layers "F.Cu" "B.Cu")
		(net "PVDDIO_P0")
	)
	(via
		(at 281.813762 -334.736694)
		(size 0.508)
		(drill 0.254)
		(layers "F.Cu" "B.Cu")
		(net "PVDDIO_P0")
	)
	(via
		(at 273.533362 -330.291694)
		(size 0.508)
		(drill 0.254)
		(layers "F.Cu" "B.Cu")
		(net "PVDDIO_P0")
	)
	(via
		(at 281.178762 -330.926694)
		(size 0.508)
		(drill 0.254)
		(layers "F.Cu" "B.Cu")
		(net "PVDDIO_P0")
	)
	(via
		(at 327.761092 -254.204216)
		(size 0.4064)
		(drill 0.2032)
		(layers "F.Cu" "B.Cu")
		(net "PVDDIO_P0")
	)
	(via
		(at 346.080842 -257.930142)
		(size 0.4826)
		(drill 0.254)
		(layers "F.Cu" "B.Cu")
		(net "PVDDIO_P0")
	)
	(via
		(at 346.080842 -259.729986)
		(size 0.4826)
		(drill 0.254)
		(layers "F.Cu" "B.Cu")
		(net "PVDDIO_P0")
	)
	(via
		(at 328.061066 -287.856168)
		(size 0.4064)
		(drill 0.2032)
		(layers "F.Cu" "B.Cu")
		(net "PVDDIO_P0")
	)
	(via
		(at 340.921086 -244.484144)
		(size 0.4064)
		(drill 0.2032)
		(layers "F.Cu" "B.Cu")
		(net "PVDDIO_P0")
	)
	(via
		(at 285.826962 -332.831694)
		(size 0.508)
		(drill 0.254)
		(layers "F.Cu" "B.Cu")
		(net "PVDDIO_P0")
	)
	(via
		(at 285.191962 -330.926694)
		(size 0.508)
		(drill 0.254)
		(layers "F.Cu" "B.Cu")
		(net "PVDDIO_P0")
	)
	(via
		(at 289.484562 -330.291694)
		(size 0.508)
		(drill 0.254)
		(layers "F.Cu" "B.Cu")
		(net "PVDDIO_P0")
	)
	(via
		(at 334.64119 -263.555988)
		(size 0.4064)
		(drill 0.2032)
		(layers "F.Cu" "B.Cu")
		(net "PVDDIO_P0")
	)
	(via
		(at 276.911562 -331.561694)
		(size 0.508)
		(drill 0.254)
		(layers "F.Cu" "B.Cu")
		(net "PVDDIO_P0")
	)
	(via
		(at 297.841162 -331.561694)
		(size 0.508)
		(drill 0.254)
		(layers "F.Cu" "B.Cu")
		(net "PVDDIO_P0")
	)
	(via
		(at 273.533362 -334.101694)
		(size 0.508)
		(drill 0.254)
		(layers "F.Cu" "B.Cu")
		(net "PVDDIO_P0")
	)
	(via
		(at 297.841162 -330.926694)
		(size 0.508)
		(drill 0.254)
		(layers "F.Cu" "B.Cu")
		(net "PVDDIO_P0")
	)
	(via
		(at 273.533362 -330.926694)
		(size 0.508)
		(drill 0.254)
		(layers "F.Cu" "B.Cu")
		(net "PVDDIO_P0")
	)
	(via
		(at 334.64119 -278.136096)
		(size 0.4064)
		(drill 0.2032)
		(layers "F.Cu" "B.Cu")
		(net "PVDDIO_P0")
	)
	(via
		(at 299.111162 -332.831694)
		(size 0.508)
		(drill 0.254)
		(layers "F.Cu" "B.Cu")
		(net "PVDDIO_P0")
	)
	(via
		(at 273.533362 -332.196694)
		(size 0.508)
		(drill 0.254)
		(layers "F.Cu" "B.Cu")
		(net "PVDDIO_P0")
	)
	(via
		(at 327.761092 -234.764072)
		(size 0.4064)
		(drill 0.2032)
		(layers "F.Cu" "B.Cu")
		(net "PVDDIO_P0")
	)
	(via
		(at 299.111162 -330.926694)
		(size 0.508)
		(drill 0.254)
		(layers "F.Cu" "B.Cu")
		(net "PVDDIO_P0")
	)
	(via
		(at 281.813762 -333.466694)
		(size 0.508)
		(drill 0.254)
		(layers "F.Cu" "B.Cu")
		(net "PVDDIO_P0")
	)
	(via
		(at 345.451176 -262.745982)
		(size 0.4064)
		(drill 0.2032)
		(layers "F.Cu" "B.Cu")
		(net "PVDDIO_P0")
	)
	(via
		(at 297.841162 -334.101694)
		(size 0.508)
		(drill 0.254)
		(layers "F.Cu" "B.Cu")
		(net "PVDDIO_P0")
	)
	(via
		(at 328.231246 -227.474272)
		(size 0.4064)
		(drill 0.2032)
		(layers "F.Cu" "B.Cu")
		(net "PVDDIO_P0")
	)
	(via
		(at 293.497762 -333.466694)
		(size 0.508)
		(drill 0.254)
		(layers "F.Cu" "B.Cu")
		(net "PVDDIO_P0")
	)
	(via
		(at 298.476162 -334.101694)
		(size 0.508)
		(drill 0.254)
		(layers "F.Cu" "B.Cu")
		(net "PVDDIO_P0")
	)
	(via
		(at 328.061066 -278.136096)
		(size 0.4064)
		(drill 0.2032)
		(layers "F.Cu" "B.Cu")
		(net "PVDDIO_P0")
	)
	(via
		(at 302.489362 -330.291694)
		(size 0.508)
		(drill 0.254)
		(layers "F.Cu" "B.Cu")
		(net "PVDDIO_P0")
	)
	(via
		(at 286.461962 -334.101694)
		(size 0.508)
		(drill 0.254)
		(layers "F.Cu" "B.Cu")
		(net "PVDDIO_P0")
	)
	(via
		(at 290.119562 -332.831694)
		(size 0.508)
		(drill 0.254)
		(layers "F.Cu" "B.Cu")
		(net "PVDDIO_P0")
	)
	(via
		(at 328.061066 -273.27606)
		(size 0.4064)
		(drill 0.2032)
		(layers "F.Cu" "B.Cu")
		(net "PVDDIO_P0")
	)
	(via
		(at 281.813762 -332.831694)
		(size 0.508)
		(drill 0.254)
		(layers "F.Cu" "B.Cu")
		(net "PVDDIO_P0")
	)
	(via
		(at 341.22106 -268.416024)
		(size 0.4064)
		(drill 0.2032)
		(layers "F.Cu" "B.Cu")
		(net "PVDDIO_P0")
	)
	(via
		(at 344.211148 -246.914162)
		(size 0.4064)
		(drill 0.2032)
		(layers "F.Cu" "B.Cu")
		(net "PVDDIO_P0")
	)
	(via
		(at 281.813762 -334.101694)
		(size 0.508)
		(drill 0.254)
		(layers "F.Cu" "B.Cu")
		(net "PVDDIO_P0")
	)
	(via
		(at 302.489362 -334.736694)
		(size 0.508)
		(drill 0.254)
		(layers "F.Cu" "B.Cu")
		(net "PVDDIO_P0")
	)
	(via
		(at 353.43084 -261.23011)
		(size 0.4826)
		(drill 0.254)
		(layers "F.Cu" "B.Cu")
		(net "PVDDIO_P0")
	)
	(via
		(at 299.111162 -330.291694)
		(size 0.508)
		(drill 0.254)
		(layers "F.Cu" "B.Cu")
		(net "PVDDIO_P0")
	)
	(via
		(at 303.124362 -332.831694)
		(size 0.508)
		(drill 0.254)
		(layers "F.Cu" "B.Cu")
		(net "PVDDIO_P0")
	)
	(via
		(at 278.181562 -333.466694)
		(size 0.508)
		(drill 0.254)
		(layers "F.Cu" "B.Cu")
		(net "PVDDIO_P0")
	)
	(via
		(at 303.124362 -330.926694)
		(size 0.508)
		(drill 0.254)
		(layers "F.Cu" "B.Cu")
		(net "PVDDIO_P0")
	)
	(via
		(at 286.461962 -330.291694)
		(size 0.508)
		(drill 0.254)
		(layers "F.Cu" "B.Cu")
		(net "PVDDIO_P0")
	)
	(via
		(at 276.911562 -334.736694)
		(size 0.508)
		(drill 0.254)
		(layers "F.Cu" "B.Cu")
		(net "PVDDIO_P0")
	)
	(via
		(at 300.990254 -329.535028)
		(size 0.6604)
		(drill 0.3302)
		(layers "F.Cu" "B.Cu")
		(net "PVDDIO_P0")
	)
	(via
		(at 349.880682 -257.930142)
		(size 0.4826)
		(drill 0.254)
		(layers "F.Cu" "B.Cu")
		(net "PVDDIO_P0")
	)
	(via
		(at 294.767762 -333.466694)
		(size 0.508)
		(drill 0.254)
		(layers "F.Cu" "B.Cu")
		(net "PVDDIO_P0")
	)
	(via
		(at 294.767762 -334.736694)
		(size 0.508)
		(drill 0.254)
		(layers "F.Cu" "B.Cu")
		(net "PVDDIO_P0")
	)
	(via
		(at 335.58099 -294.335962)
		(size 0.4064)
		(drill 0.2032)
		(layers "F.Cu" "B.Cu")
		(net "PVDDIO_P0")
	)
	(via
		(at 274.168362 -332.196694)
		(size 0.508)
		(drill 0.254)
		(layers "F.Cu" "B.Cu")
		(net "PVDDIO_P0")
	)
	(via
		(at 274.168362 -334.736694)
		(size 0.508)
		(drill 0.254)
		(layers "F.Cu" "B.Cu")
		(net "PVDDIO_P0")
	)
	(via
		(at 286.461962 -332.831694)
		(size 0.508)
		(drill 0.254)
		(layers "F.Cu" "B.Cu")
		(net "PVDDIO_P0")
	)
	(via
		(at 335.11109 -261.12597)
		(size 0.4064)
		(drill 0.2032)
		(layers "F.Cu" "B.Cu")
		(net "PVDDIO_P0")
	)
	(via
		(at 341.22106 -263.555988)
		(size 0.4064)
		(drill 0.2032)
		(layers "F.Cu" "B.Cu")
		(net "PVDDIO_P0")
	)
	(via
		(at 341.390986 -251.774198)
		(size 0.4064)
		(drill 0.2032)
		(layers "F.Cu" "B.Cu")
		(net "PVDDIO_P0")
	)
	(via
		(at 328.53122 -270.846042)
		(size 0.4064)
		(drill 0.2032)
		(layers "F.Cu" "B.Cu")
		(net "PVDDIO_P0")
	)
	(via
		(at 334.811116 -251.774198)
		(size 0.4064)
		(drill 0.2032)
		(layers "F.Cu" "B.Cu")
		(net "PVDDIO_P0")
	)
	(via
		(at 298.476162 -332.831694)
		(size 0.508)
		(drill 0.254)
		(layers "F.Cu" "B.Cu")
		(net "PVDDIO_P0")
	)
	(via
		(at 328.231246 -237.19409)
		(size 0.4064)
		(drill 0.2032)
		(layers "F.Cu" "B.Cu")
		(net "PVDDIO_P0")
	)
	(via
		(at 349.880682 -258.830064)
		(size 0.4826)
		(drill 0.254)
		(layers "F.Cu" "B.Cu")
		(net "PVDDIO_P0")
	)
	(via
		(at 303.124362 -334.736694)
		(size 0.508)
		(drill 0.254)
		(layers "F.Cu" "B.Cu")
		(net "PVDDIO_P0")
	)
	(via
		(at 282.448762 -330.291694)
		(size 0.508)
		(drill 0.254)
		(layers "F.Cu" "B.Cu")
		(net "PVDDIO_P0")
	)
	(via
		(at 341.22106 -287.856168)
		(size 0.4064)
		(drill 0.2032)
		(layers "F.Cu" "B.Cu")
		(net "PVDDIO_P0")
	)
	(via
		(at 299.111162 -334.736694)
		(size 0.508)
		(drill 0.254)
		(layers "F.Cu" "B.Cu")
		(net "PVDDIO_P0")
	)
	(via
		(at 328.061066 -282.996132)
		(size 0.4064)
		(drill 0.2032)
		(layers "F.Cu" "B.Cu")
		(net "PVDDIO_P0")
	)
	(via
		(at 276.911562 -330.291694)
		(size 0.508)
		(drill 0.254)
		(layers "F.Cu" "B.Cu")
		(net "PVDDIO_P0")
	)
	(via
		(at 285.191962 -331.561694)
		(size 0.508)
		(drill 0.254)
		(layers "F.Cu" "B.Cu")
		(net "PVDDIO_P0")
	)
	(via
		(at 299.111162 -334.101694)
		(size 0.508)
		(drill 0.254)
		(layers "F.Cu" "B.Cu")
		(net "PVDDIO_P0")
	)
	(via
		(at 328.061066 -268.416024)
		(size 0.4064)
		(drill 0.2032)
		(layers "F.Cu" "B.Cu")
		(net "PVDDIO_P0")
	)
	(via
		(at 280.398728 -350.498156)
		(size 0.508)
		(drill 0.254)
		(layers "F.Cu" "B.Cu")
		(net "PVDDIO_P0")
	)
	(via
		(at 355.85781 -259.845048)
		(size 0.4826)
		(drill 0.254)
		(layers "F.Cu" "B.Cu")
		(net "PVDDIO_P0")
	)
	(via
		(at 328.53122 -285.42615)
		(size 0.4064)
		(drill 0.2032)
		(layers "F.Cu" "B.Cu")
		(net "PVDDIO_P0")
	)
	(via
		(at 299.111162 -333.466694)
		(size 0.508)
		(drill 0.254)
		(layers "F.Cu" "B.Cu")
		(net "PVDDIO_P0")
	)
	(via
		(at 334.341216 -239.624108)
		(size 0.4064)
		(drill 0.2032)
		(layers "F.Cu" "B.Cu")
		(net "PVDDIO_P0")
	)
	(via
		(at 348.741238 -261.935976)
		(size 0.4064)
		(drill 0.2032)
		(layers "F.Cu" "B.Cu")
		(net "PVDDIO_P0")
	)
	(via
		(at 302.489362 -334.101694)
		(size 0.508)
		(drill 0.254)
		(layers "F.Cu" "B.Cu")
		(net "PVDDIO_P0")
	)
	(via
		(at 293.497762 -334.736694)
		(size 0.508)
		(drill 0.254)
		(layers "F.Cu" "B.Cu")
		(net "PVDDIO_P0")
	)
	(via
		(at 276.911562 -330.926694)
		(size 0.508)
		(drill 0.254)
		(layers "F.Cu" "B.Cu")
		(net "PVDDIO_P0")
	)
	(via
		(at 281.178762 -331.561694)
		(size 0.508)
		(drill 0.254)
		(layers "F.Cu" "B.Cu")
		(net "PVDDIO_P0")
	)
	(via
		(at 334.64119 -292.71595)
		(size 0.4064)
		(drill 0.2032)
		(layers "F.Cu" "B.Cu")
		(net "PVDDIO_P0")
	)
	(via
		(at 344.981022 -266.796012)
		(size 0.4064)
		(drill 0.2032)
		(layers "F.Cu" "B.Cu")
		(net "PVDDIO_P0")
	)
	(via
		(at 290.754562 -334.736694)
		(size 0.508)
		(drill 0.254)
		(layers "F.Cu" "B.Cu")
		(net "PVDDIO_P0")
	)
	(via
		(at 334.341216 -254.204216)
		(size 0.4064)
		(drill 0.2032)
		(layers "F.Cu" "B.Cu")
		(net "PVDDIO_P0")
	)
	(via
		(at 344.511122 -270.846042)
		(size 0.4064)
		(drill 0.2032)
		(layers "F.Cu" "B.Cu")
		(net "PVDDIO_P0")
	)
	(via
		(at 281.813762 -330.926694)
		(size 0.508)
		(drill 0.254)
		(layers "F.Cu" "B.Cu")
		(net "PVDDIO_P0")
	)
	(segment
		(start 271.760696 -349.781622)
		(end 271.760696 -350.140524)
		(width 0.381)
		(layer "B.Cu")
		(net "PVDDIO_P0")
	)
	(segment
		(start 288.346896 -349.781622)
		(end 288.346896 -350.140524)
		(width 0.381)
		(layer "B.Cu")
		(net "PVDDIO_P0")
	)
	(segment
		(start 280.041096 -350.140524)
		(end 280.398728 -350.498156)
		(width 0.381)
		(layer "B.Cu")
		(net "PVDDIO_P0")
	)
	(segment
		(start 296.703496 -349.781622)
		(end 296.703496 -350.140524)
		(width 0.381)
		(layer "B.Cu")
		(net "PVDDIO_P0")
	)
	(segment
		(start 288.346896 -350.140524)
		(end 288.704528 -350.498156)
		(width 0.381)
		(layer "B.Cu")
		(net "PVDDIO_P0")
	)
	(segment
		(start 271.760696 -350.140524)
		(end 272.118328 -350.498156)
		(width 0.381)
		(layer "B.Cu")
		(net "PVDDIO_P0")
	)
	(segment
		(start 296.703496 -350.140524)
		(end 297.061128 -350.498156)
		(width 0.381)
		(layer "B.Cu")
		(net "PVDDIO_P0")
	)
	(segment
		(start 280.041096 -349.781622)
		(end 280.041096 -350.140524)
		(width 0.381)
		(layer "B.Cu")
		(net "PVDDIO_P0")
	)
	(segment
		(start 271.80159 -349.392494)
		(end 271.80159 -350.181418)
		(width 0.381)
		(layer "In2.Cu")
		(net "PVDDIO_P0")
	)
	(segment
		(start 288.52241 -350.316038)
		(end 288.704528 -350.498156)
		(width 0.381)
		(layer "In2.Cu")
		(net "PVDDIO_P0")
	)
	(segment
		(start 280.23439 -350.333818)
		(end 280.398728 -350.498156)
		(width 0.381)
		(layer "In2.Cu")
		(net "PVDDIO_P0")
	)
	(segment
		(start 296.85869 -350.295718)
		(end 296.85869 -349.278194)
		(width 0.381)
		(layer "In2.Cu")
		(net "PVDDIO_P0")
	)
	(segment
		(start 288.52241 -349.283274)
		(end 288.52241 -350.316038)
		(width 0.381)
		(layer "In2.Cu")
		(net "PVDDIO_P0")
	)
	(segment
		(start 296.85869 -349.278194)
		(end 297.840146 -348.296738)
		(width 0.381)
		(layer "In2.Cu")
		(net "PVDDIO_P0")
	)
	(segment
		(start 297.840146 -334.73771)
		(end 297.841162 -334.736694)
		(width 0.381)
		(layer "In2.Cu")
		(net "PVDDIO_P0")
	)
	(segment
		(start 289.484562 -334.736694)
		(end 289.419792 -334.801464)
		(width 0.381)
		(layer "In2.Cu")
		(net "PVDDIO_P0")
	)
	(segment
		(start 280.23439 -349.214694)
		(end 280.23439 -350.333818)
		(width 0.381)
		(layer "In2.Cu")
		(net "PVDDIO_P0")
	)
	(segment
		(start 272.898362 -334.736694)
		(end 272.871946 -334.76311)
		(width 0.381)
		(layer "In2.Cu")
		(net "PVDDIO_P0")
	)
	(segment
		(start 289.419792 -334.801464)
		(end 289.419792 -348.385892)
		(width 0.381)
		(layer "In2.Cu")
		(net "PVDDIO_P0")
	)
	(segment
		(start 272.871946 -348.322138)
		(end 271.80159 -349.392494)
		(width 0.381)
		(layer "In2.Cu")
		(net "PVDDIO_P0")
	)
	(segment
		(start 281.152346 -334.76311)
		(end 281.152346 -348.296738)
		(width 0.381)
		(layer "In2.Cu")
		(net "PVDDIO_P0")
	)
	(segment
		(start 271.80159 -350.181418)
		(end 272.118328 -350.498156)
		(width 0.381)
		(layer "In2.Cu")
		(net "PVDDIO_P0")
	)
	(segment
		(start 297.061128 -350.498156)
		(end 296.85869 -350.295718)
		(width 0.381)
		(layer "In2.Cu")
		(net "PVDDIO_P0")
	)
	(segment
		(start 289.419792 -348.385892)
		(end 288.52241 -349.283274)
		(width 0.381)
		(layer "In2.Cu")
		(net "PVDDIO_P0")
	)
	(segment
		(start 281.152346 -348.296738)
		(end 280.23439 -349.214694)
		(width 0.381)
		(layer "In2.Cu")
		(net "PVDDIO_P0")
	)
	(segment
		(start 272.871946 -334.76311)
		(end 272.871946 -348.322138)
		(width 0.381)
		(layer "In2.Cu")
		(net "PVDDIO_P0")
	)
	(segment
		(start 281.178762 -334.736694)
		(end 281.152346 -334.76311)
		(width 0.381)
		(layer "In2.Cu")
		(net "PVDDIO_P0")
	)
	(segment
		(start 297.840146 -348.296738)
		(end 297.840146 -334.73771)
		(width 0.381)
		(layer "In2.Cu")
		(net "PVDDIO_P0")
	)
	(segment
		(start 134.824216 -153.969212)
		(end 135.148828 -153.6446)
		(width 0.2032)
		(layer "F.Cu")
		(net "PVDDCR_SOC_P1_VOS3")
	)
	(segment
		(start 134.824216 -154.255978)
		(end 134.824216 -153.969212)
		(width 0.2032)
		(layer "F.Cu")
		(net "PVDDCR_SOC_P1_VOS3")
	)
	(via
		(at 135.148828 -153.6446)
		(size 0.508)
		(drill 0.254)
		(layers "F.Cu" "B.Cu")
		(net "PVDDCR_SOC_P1_VOS3")
	)
	(segment
		(start 135.770112 -154.265884)
		(end 135.148828 -153.6446)
		(width 0.2286)
		(layer "B.Cu")
		(net "PVDDCR_SOC_P1_VOS3")
	)
	(segment
		(start 136.08558 -154.265884)
		(end 135.770112 -154.265884)
		(width 0.2286)
		(layer "B.Cu")
		(net "PVDDCR_SOC_P1_VOS3")
	)
	(segment
		(start 126.366016 -162.630612)
		(end 126.366016 -162.917378)
		(width 0.2032)
		(layer "F.Cu")
		(net "PVDDCR_SOC_P1_VOS2")
	)
	(segment
		(start 126.690628 -162.306)
		(end 126.366016 -162.630612)
		(width 0.2032)
		(layer "F.Cu")
		(net "PVDDCR_SOC_P1_VOS2")
	)
	(via
		(at 126.690628 -162.306)
		(size 0.508)
		(drill 0.254)
		(layers "F.Cu" "B.Cu")
		(net "PVDDCR_SOC_P1_VOS2")
	)
	(segment
		(start 127.311912 -162.927284)
		(end 126.690628 -162.306)
		(width 0.2286)
		(layer "B.Cu")
		(net "PVDDCR_SOC_P1_VOS2")
	)
	(segment
		(start 127.62738 -162.927284)
		(end 127.311912 -162.927284)
		(width 0.2286)
		(layer "B.Cu")
		(net "PVDDCR_SOC_P1_VOS2")
	)
	(segment
		(start 118.410228 -169.037)
		(end 118.085616 -169.361612)
		(width 0.2032)
		(layer "F.Cu")
		(net "PVDDCR_SOC_P1_VOS1")
	)
	(segment
		(start 118.085616 -169.361612)
		(end 118.085616 -169.648378)
		(width 0.2032)
		(layer "F.Cu")
		(net "PVDDCR_SOC_P1_VOS1")
	)
	(via
		(at 118.410228 -169.037)
		(size 0.508)
		(drill 0.254)
		(layers "F.Cu" "B.Cu")
		(net "PVDDCR_SOC_P1_VOS1")
	)
	(segment
		(start 119.031512 -169.658284)
		(end 118.410228 -169.037)
		(width 0.2286)
		(layer "B.Cu")
		(net "PVDDCR_SOC_P1_VOS1")
	)
	(segment
		(start 119.34698 -169.658284)
		(end 119.031512 -169.658284)
		(width 0.2286)
		(layer "B.Cu")
		(net "PVDDCR_SOC_P1_VOS1")
	)
	(segment
		(start 132.614162 -152.919176)
		(end 132.614162 -153.631138)
		(width 0.2286)
		(layer "F.Cu")
		(net "PVDDCR_SOC_P1_VCC3")
	)
	(segment
		(start 136.10717 -154.876246)
		(end 136.10717 -154.265884)
		(width 0.381)
		(layer "F.Cu")
		(net "PVDDCR_SOC_P1_VCC3")
	)
	(segment
		(start 134.824216 -155.156154)
		(end 135.474964 -155.156154)
		(width 0.2286)
		(layer "F.Cu")
		(net "PVDDCR_SOC_P1_VCC3")
	)
	(segment
		(start 135.754872 -154.876246)
		(end 136.10717 -154.876246)
		(width 0.254)
		(layer "F.Cu")
		(net "PVDDCR_SOC_P1_VCC3")
	)
	(segment
		(start 135.474964 -155.156154)
		(end 135.754872 -154.876246)
		(width 0.254)
		(layer "F.Cu")
		(net "PVDDCR_SOC_P1_VCC3")
	)
	(segment
		(start 132.689854 -152.843484)
		(end 132.614162 -152.919176)
		(width 0.2286)
		(layer "F.Cu")
		(net "PVDDCR_SOC_P1_VCC3")
	)
	(via
		(at 133.287008 -153.653744)
		(size 0.6604)
		(drill 0.3302)
		(layers "F.Cu" "B.Cu")
		(net "PVDDCR_SOC_P1_VCC3")
	)
	(via
		(at 136.10717 -154.876246)
		(size 0.508)
		(drill 0.254)
		(layers "F.Cu" "B.Cu")
		(net "PVDDCR_SOC_P1_VCC3")
	)
	(via
		(at 132.689854 -152.843484)
		(size 0.508)
		(drill 0.254)
		(layers "F.Cu" "B.Cu")
		(net "PVDDCR_SOC_P1_VCC3")
	)
	(segment
		(start 132.689854 -153.436574)
		(end 132.907024 -153.653744)
		(width 0.508)
		(layer "B.Cu")
		(net "PVDDCR_SOC_P1_VCC3")
	)
	(segment
		(start 132.689854 -152.843484)
		(end 132.689854 -153.436574)
		(width 0.508)
		(layer "B.Cu")
		(net "PVDDCR_SOC_P1_VCC3")
	)
	(segment
		(start 135.24484 -155.071826)
		(end 135.44042 -154.876246)
		(width 0.381)
		(layer "B.Cu")
		(net "PVDDCR_SOC_P1_VCC3")
	)
	(segment
		(start 133.287008 -153.653744)
		(end 134.2771 -153.653744)
		(width 0.381)
		(layer "B.Cu")
		(net "PVDDCR_SOC_P1_VCC3")
	)
	(segment
		(start 135.44042 -154.876246)
		(end 136.10717 -154.876246)
		(width 0.381)
		(layer "B.Cu")
		(net "PVDDCR_SOC_P1_VCC3")
	)
	(segment
		(start 134.735062 -155.071826)
		(end 135.24484 -155.071826)
		(width 0.381)
		(layer "B.Cu")
		(net "PVDDCR_SOC_P1_VCC3")
	)
	(segment
		(start 134.2771 -153.653744)
		(end 134.735062 -154.111706)
		(width 0.381)
		(layer "B.Cu")
		(net "PVDDCR_SOC_P1_VCC3")
	)
	(segment
		(start 134.735062 -154.111706)
		(end 134.735062 -155.071826)
		(width 0.381)
		(layer "B.Cu")
		(net "PVDDCR_SOC_P1_VCC3")
	)
	(segment
		(start 132.907024 -153.653744)
		(end 133.287008 -153.653744)
		(width 0.381)
		(layer "B.Cu")
		(net "PVDDCR_SOC_P1_VCC3")
	)
	(segment
		(start 127.64897 -162.927284)
		(end 127.64897 -163.537646)
		(width 0.381)
		(layer "F.Cu")
		(net "PVDDCR_SOC_P1_VCC2")
	)
	(segment
		(start 124.231654 -161.504884)
		(end 124.155962 -161.580576)
		(width 0.2286)
		(layer "F.Cu")
		(net "PVDDCR_SOC_P1_VCC2")
	)
	(segment
		(start 124.155962 -161.580576)
		(end 124.155962 -162.292538)
		(width 0.2286)
		(layer "F.Cu")
		(net "PVDDCR_SOC_P1_VCC2")
	)
	(segment
		(start 127.296672 -163.537646)
		(end 127.016764 -163.817554)
		(width 0.2286)
		(layer "F.Cu")
		(net "PVDDCR_SOC_P1_VCC2")
	)
	(segment
		(start 127.016764 -163.817554)
		(end 126.366016 -163.817554)
		(width 0.2286)
		(layer "F.Cu")
		(net "PVDDCR_SOC_P1_VCC2")
	)
	(segment
		(start 127.64897 -163.537646)
		(end 127.296672 -163.537646)
		(width 0.2286)
		(layer "F.Cu")
		(net "PVDDCR_SOC_P1_VCC2")
	)
	(via
		(at 124.707904 -162.315144)
		(size 0.6604)
		(drill 0.3302)
		(layers "F.Cu" "B.Cu")
		(net "PVDDCR_SOC_P1_VCC2")
	)
	(via
		(at 124.231654 -161.504884)
		(size 0.508)
		(drill 0.254)
		(layers "F.Cu" "B.Cu")
		(net "PVDDCR_SOC_P1_VCC2")
	)
	(via
		(at 127.64897 -163.537646)
		(size 0.508)
		(drill 0.254)
		(layers "F.Cu" "B.Cu")
		(net "PVDDCR_SOC_P1_VCC2")
	)
	(segment
		(start 124.231654 -161.504884)
		(end 124.231654 -162.097974)
		(width 0.508)
		(layer "B.Cu")
		(net "PVDDCR_SOC_P1_VCC2")
	)
	(segment
		(start 126.78664 -163.733226)
		(end 126.276862 -163.733226)
		(width 0.381)
		(layer "B.Cu")
		(net "PVDDCR_SOC_P1_VCC2")
	)
	(segment
		(start 126.98222 -163.537646)
		(end 126.78664 -163.733226)
		(width 0.381)
		(layer "B.Cu")
		(net "PVDDCR_SOC_P1_VCC2")
	)
	(segment
		(start 124.231654 -162.097974)
		(end 124.448824 -162.315144)
		(width 0.508)
		(layer "B.Cu")
		(net "PVDDCR_SOC_P1_VCC2")
	)
	(segment
		(start 125.8189 -162.315144)
		(end 126.276862 -162.773106)
		(width 0.381)
		(layer "B.Cu")
		(net "PVDDCR_SOC_P1_VCC2")
	)
	(segment
		(start 126.276862 -162.773106)
		(end 126.276862 -163.733226)
		(width 0.381)
		(layer "B.Cu")
		(net "PVDDCR_SOC_P1_VCC2")
	)
	(segment
		(start 127.64897 -163.537646)
		(end 126.98222 -163.537646)
		(width 0.381)
		(layer "B.Cu")
		(net "PVDDCR_SOC_P1_VCC2")
	)
	(segment
		(start 124.707904 -162.315144)
		(end 125.8189 -162.315144)
		(width 0.381)
		(layer "B.Cu")
		(net "PVDDCR_SOC_P1_VCC2")
	)
	(segment
		(start 124.448824 -162.315144)
		(end 124.707904 -162.315144)
		(width 0.381)
		(layer "B.Cu")
		(net "PVDDCR_SOC_P1_VCC2")
	)
	(segment
		(start 119.016272 -170.268646)
		(end 118.736364 -170.548554)
		(width 0.2286)
		(layer "F.Cu")
		(net "PVDDCR_SOC_P1_VCC1")
	)
	(segment
		(start 115.875562 -169.023538)
		(end 115.875562 -168.311576)
		(width 0.2286)
		(layer "F.Cu")
		(net "PVDDCR_SOC_P1_VCC1")
	)
	(segment
		(start 119.36857 -170.268646)
		(end 119.016272 -170.268646)
		(width 0.2286)
		(layer "F.Cu")
		(net "PVDDCR_SOC_P1_VCC1")
	)
	(segment
		(start 115.875562 -168.311576)
		(end 115.951254 -168.235884)
		(width 0.2286)
		(layer "F.Cu")
		(net "PVDDCR_SOC_P1_VCC1")
	)
	(segment
		(start 118.736364 -170.548554)
		(end 118.085616 -170.548554)
		(width 0.2286)
		(layer "F.Cu")
		(net "PVDDCR_SOC_P1_VCC1")
	)
	(segment
		(start 119.36857 -169.658284)
		(end 119.36857 -170.268646)
		(width 0.381)
		(layer "F.Cu")
		(net "PVDDCR_SOC_P1_VCC1")
	)
	(via
		(at 119.36857 -170.268646)
		(size 0.508)
		(drill 0.254)
		(layers "F.Cu" "B.Cu")
		(net "PVDDCR_SOC_P1_VCC1")
	)
	(via
		(at 115.951254 -168.235884)
		(size 0.508)
		(drill 0.254)
		(layers "F.Cu" "B.Cu")
		(net "PVDDCR_SOC_P1_VCC1")
	)
	(via
		(at 116.168424 -169.046144)
		(size 0.6604)
		(drill 0.3302)
		(layers "F.Cu" "B.Cu")
		(net "PVDDCR_SOC_P1_VCC1")
	)
	(segment
		(start 115.951254 -168.828974)
		(end 116.168424 -169.046144)
		(width 0.508)
		(layer "B.Cu")
		(net "PVDDCR_SOC_P1_VCC1")
	)
	(segment
		(start 115.951254 -168.235884)
		(end 115.951254 -168.828974)
		(width 0.508)
		(layer "B.Cu")
		(net "PVDDCR_SOC_P1_VCC1")
	)
	(segment
		(start 116.168424 -169.046144)
		(end 117.5385 -169.046144)
		(width 0.381)
		(layer "B.Cu")
		(net "PVDDCR_SOC_P1_VCC1")
	)
	(segment
		(start 117.996462 -170.464226)
		(end 118.50624 -170.464226)
		(width 0.381)
		(layer "B.Cu")
		(net "PVDDCR_SOC_P1_VCC1")
	)
	(segment
		(start 117.5385 -169.046144)
		(end 117.996462 -169.504106)
		(width 0.381)
		(layer "B.Cu")
		(net "PVDDCR_SOC_P1_VCC1")
	)
	(segment
		(start 117.996462 -169.504106)
		(end 117.996462 -170.464226)
		(width 0.381)
		(layer "B.Cu")
		(net "PVDDCR_SOC_P1_VCC1")
	)
	(segment
		(start 118.70182 -170.268646)
		(end 119.36857 -170.268646)
		(width 0.381)
		(layer "B.Cu")
		(net "PVDDCR_SOC_P1_VCC1")
	)
	(segment
		(start 118.50624 -170.464226)
		(end 118.70182 -170.268646)
		(width 0.381)
		(layer "B.Cu")
		(net "PVDDCR_SOC_P1_VCC1")
	)
	(segment
		(start 124.60605 -162.004756)
		(end 124.60605 -162.292538)
		(width 0.2286)
		(layer "F.Cu")
		(net "PVDDCR_SOC_P1_TEMP1")
	)
	(segment
		(start 116.646706 -168.26103)
		(end 116.423694 -168.484042)
		(width 0.2286)
		(layer "F.Cu")
		(net "PVDDCR_SOC_P1_TEMP1")
	)
	(segment
		(start 133.154674 -153.120598)
		(end 133.154674 -153.171398)
		(width 0.2286)
		(layer "F.Cu")
		(net "PVDDCR_SOC_P1_TEMP1")
	)
	(segment
		(start 124.927106 -161.259012)
		(end 124.927106 -161.53003)
		(width 0.2286)
		(layer "F.Cu")
		(net "PVDDCR_SOC_P1_TEMP1")
	)
	(segment
		(start 116.646706 -167.990012)
		(end 116.646706 -168.26103)
		(width 0.2286)
		(layer "F.Cu")
		(net "PVDDCR_SOC_P1_TEMP1")
	)
	(segment
		(start 133.06425 -153.261822)
		(end 133.06425 -153.631138)
		(width 0.2286)
		(layer "F.Cu")
		(net "PVDDCR_SOC_P1_TEMP1")
	)
	(segment
		(start 124.927106 -161.53003)
		(end 124.714762 -161.742374)
		(width 0.2286)
		(layer "F.Cu")
		(net "PVDDCR_SOC_P1_TEMP1")
	)
	(segment
		(start 133.385306 -152.889966)
		(end 133.154674 -153.120598)
		(width 0.254)
		(layer "F.Cu")
		(net "PVDDCR_SOC_P1_TEMP1")
	)
	(segment
		(start 133.385306 -152.597612)
		(end 133.385306 -152.889966)
		(width 0.254)
		(layer "F.Cu")
		(net "PVDDCR_SOC_P1_TEMP1")
	)
	(segment
		(start 124.714762 -161.742374)
		(end 124.60605 -162.004756)
		(width 0.2286)
		(layer "F.Cu")
		(net "PVDDCR_SOC_P1_TEMP1")
	)
	(segment
		(start 116.32565 -168.72077)
		(end 116.32565 -169.023538)
		(width 0.2286)
		(layer "F.Cu")
		(net "PVDDCR_SOC_P1_TEMP1")
	)
	(segment
		(start 133.154674 -153.171398)
		(end 133.06425 -153.261822)
		(width 0.2286)
		(layer "F.Cu")
		(net "PVDDCR_SOC_P1_TEMP1")
	)
	(segment
		(start 116.423694 -168.484042)
		(end 116.32565 -168.72077)
		(width 0.2286)
		(layer "F.Cu")
		(net "PVDDCR_SOC_P1_TEMP1")
	)
	(via
		(at 133.385306 -152.597612)
		(size 0.508)
		(drill 0.254)
		(layers "F.Cu" "B.Cu")
		(net "PVDDCR_SOC_P1_TEMP1")
	)
	(via
		(at 116.646706 -167.990012)
		(size 0.508)
		(drill 0.254)
		(layers "F.Cu" "B.Cu")
		(net "PVDDCR_SOC_P1_TEMP1")
	)
	(via
		(at 100.118672 -144.394428)
		(size 0.508)
		(drill 0.254)
		(layers "F.Cu" "B.Cu")
		(net "PVDDCR_SOC_P1_TEMP1")
	)
	(via
		(at 124.927106 -161.259012)
		(size 0.508)
		(drill 0.254)
		(layers "F.Cu" "B.Cu")
		(net "PVDDCR_SOC_P1_TEMP1")
	)
	(segment
		(start 100.206556 -144.482312)
		(end 100.83673 -144.482312)
		(width 0.1524)
		(layer "B.Cu")
		(net "PVDDCR_SOC_P1_TEMP1")
	)
	(segment
		(start 98.545904 -144.558512)
		(end 99.721924 -144.558512)
		(width 0.1524)
		(layer "B.Cu")
		(net "PVDDCR_SOC_P1_TEMP1")
	)
	(segment
		(start 99.886008 -144.394428)
		(end 100.118672 -144.394428)
		(width 0.1524)
		(layer "B.Cu")
		(net "PVDDCR_SOC_P1_TEMP1")
	)
	(segment
		(start 100.118672 -144.394428)
		(end 100.206556 -144.482312)
		(width 0.1524)
		(layer "B.Cu")
		(net "PVDDCR_SOC_P1_TEMP1")
	)
	(segment
		(start 99.721924 -144.558512)
		(end 99.886008 -144.394428)
		(width 0.1524)
		(layer "B.Cu")
		(net "PVDDCR_SOC_P1_TEMP1")
	)
	(segment
		(start 100.83673 -144.482312)
		(end 100.985828 -144.63141)
		(width 0.1524)
		(layer "B.Cu")
		(net "PVDDCR_SOC_P1_TEMP1")
	)
	(segment
		(start 126.404878 -153.26741)
		(end 126.404878 -158.34741)
		(width 0.254)
		(layer "In2.Cu")
		(net "PVDDCR_SOC_P1_TEMP1")
	)
	(segment
		(start 116.646706 -165.819582)
		(end 117.641878 -164.82441)
		(width 0.254)
		(layer "In2.Cu")
		(net "PVDDCR_SOC_P1_TEMP1")
	)
	(segment
		(start 124.927106 -161.259012)
		(end 124.927106 -159.825182)
		(width 0.254)
		(layer "In2.Cu")
		(net "PVDDCR_SOC_P1_TEMP1")
	)
	(segment
		(start 117.641878 -164.82441)
		(end 117.641878 -161.14141)
		(width 0.254)
		(layer "In2.Cu")
		(net "PVDDCR_SOC_P1_TEMP1")
	)
	(segment
		(start 101.440234 -146.466052)
		(end 116.115592 -161.14141)
		(width 0.254)
		(layer "In2.Cu")
		(net "PVDDCR_SOC_P1_TEMP1")
	)
	(segment
		(start 133.385306 -152.597612)
		(end 133.385306 -150.976838)
		(width 0.254)
		(layer "In2.Cu")
		(net "PVDDCR_SOC_P1_TEMP1")
	)
	(segment
		(start 133.008878 -150.60041)
		(end 129.071878 -150.60041)
		(width 0.254)
		(layer "In2.Cu")
		(net "PVDDCR_SOC_P1_TEMP1")
	)
	(segment
		(start 116.115592 -161.14141)
		(end 117.641878 -161.14141)
		(width 0.254)
		(layer "In2.Cu")
		(net "PVDDCR_SOC_P1_TEMP1")
	)
	(segment
		(start 129.071878 -150.60041)
		(end 126.404878 -153.26741)
		(width 0.254)
		(layer "In2.Cu")
		(net "PVDDCR_SOC_P1_TEMP1")
	)
	(segment
		(start 116.646706 -167.990012)
		(end 116.646706 -165.819582)
		(width 0.254)
		(layer "In2.Cu")
		(net "PVDDCR_SOC_P1_TEMP1")
	)
	(segment
		(start 119.419878 -159.36341)
		(end 124.465334 -159.36341)
		(width 0.254)
		(layer "In2.Cu")
		(net "PVDDCR_SOC_P1_TEMP1")
	)
	(segment
		(start 126.404878 -158.34741)
		(end 124.927106 -159.825182)
		(width 0.254)
		(layer "In2.Cu")
		(net "PVDDCR_SOC_P1_TEMP1")
	)
	(segment
		(start 100.118672 -144.394428)
		(end 100.206556 -144.482312)
		(width 0.254)
		(layer "In2.Cu")
		(net "PVDDCR_SOC_P1_TEMP1")
	)
	(segment
		(start 101.440234 -145.546572)
		(end 101.440234 -146.466052)
		(width 0.254)
		(layer "In2.Cu")
		(net "PVDDCR_SOC_P1_TEMP1")
	)
	(segment
		(start 100.206556 -144.482312)
		(end 100.375974 -144.482312)
		(width 0.254)
		(layer "In2.Cu")
		(net "PVDDCR_SOC_P1_TEMP1")
	)
	(segment
		(start 117.641878 -161.14141)
		(end 119.419878 -159.36341)
		(width 0.254)
		(layer "In2.Cu")
		(net "PVDDCR_SOC_P1_TEMP1")
	)
	(segment
		(start 124.465334 -159.36341)
		(end 124.927106 -159.825182)
		(width 0.254)
		(layer "In2.Cu")
		(net "PVDDCR_SOC_P1_TEMP1")
	)
	(segment
		(start 100.375974 -144.482312)
		(end 101.440234 -145.546572)
		(width 0.254)
		(layer "In2.Cu")
		(net "PVDDCR_SOC_P1_TEMP1")
	)
	(segment
		(start 133.385306 -150.976838)
		(end 133.008878 -150.60041)
		(width 0.254)
		(layer "In2.Cu")
		(net "PVDDCR_SOC_P1_TEMP1")
	)
	(segment
		(start 132.164074 -153.631138)
		(end 132.164074 -153.120598)
		(width 0.1778)
		(layer "F.Cu")
		(net "PVDDCR_SOC_P1_PWM3")
	)
	(segment
		(start 132.164074 -153.120598)
		(end 132.174234 -153.110438)
		(width 0.1778)
		(layer "F.Cu")
		(net "PVDDCR_SOC_P1_PWM3")
	)
	(segment
		(start 132.174234 -153.110438)
		(end 132.174234 -152.516332)
		(width 0.1778)
		(layer "F.Cu")
		(net "PVDDCR_SOC_P1_PWM3")
	)
	(segment
		(start 132.174234 -152.516332)
		(end 132.499354 -152.191212)
		(width 0.1778)
		(layer "F.Cu")
		(net "PVDDCR_SOC_P1_PWM3")
	)
	(via
		(at 96.559878 -140.48486)
		(size 0.508)
		(drill 0.254)
		(layers "F.Cu" "B.Cu")
		(net "PVDDCR_SOC_P1_PWM3")
	)
	(via
		(at 132.499354 -152.191212)
		(size 0.508)
		(drill 0.254)
		(layers "F.Cu" "B.Cu")
		(net "PVDDCR_SOC_P1_PWM3")
	)
	(segment
		(start 96.559878 -140.956538)
		(end 97.070926 -141.467586)
		(width 0.1524)
		(layer "B.Cu")
		(net "PVDDCR_SOC_P1_PWM3")
	)
	(segment
		(start 97.070926 -141.467586)
		(end 97.070926 -141.883384)
		(width 0.1524)
		(layer "B.Cu")
		(net "PVDDCR_SOC_P1_PWM3")
	)
	(segment
		(start 96.559878 -140.48486)
		(end 96.559878 -140.956538)
		(width 0.1524)
		(layer "B.Cu")
		(net "PVDDCR_SOC_P1_PWM3")
	)
	(segment
		(start 96.559878 -140.48486)
		(end 97.544128 -139.50061)
		(width 0.1524)
		(layer "In6.Cu")
		(net "PVDDCR_SOC_P1_PWM3")
	)
	(segment
		(start 107.104434 -141.773148)
		(end 107.104434 -152.349454)
		(width 0.1524)
		(layer "In6.Cu")
		(net "PVDDCR_SOC_P1_PWM3")
	)
	(segment
		(start 104.831896 -139.50061)
		(end 107.104434 -141.773148)
		(width 0.1524)
		(layer "In6.Cu")
		(net "PVDDCR_SOC_P1_PWM3")
	)
	(segment
		(start 109.72546 -154.97048)
		(end 122.09653 -154.97048)
		(width 0.1524)
		(layer "In6.Cu")
		(net "PVDDCR_SOC_P1_PWM3")
	)
	(segment
		(start 122.09653 -154.97048)
		(end 126.3142 -150.75281)
		(width 0.1524)
		(layer "In6.Cu")
		(net "PVDDCR_SOC_P1_PWM3")
	)
	(segment
		(start 126.3142 -150.75281)
		(end 131.060952 -150.75281)
		(width 0.1524)
		(layer "In6.Cu")
		(net "PVDDCR_SOC_P1_PWM3")
	)
	(segment
		(start 97.544128 -139.50061)
		(end 104.831896 -139.50061)
		(width 0.1524)
		(layer "In6.Cu")
		(net "PVDDCR_SOC_P1_PWM3")
	)
	(segment
		(start 107.104434 -152.349454)
		(end 109.72546 -154.97048)
		(width 0.1524)
		(layer "In6.Cu")
		(net "PVDDCR_SOC_P1_PWM3")
	)
	(segment
		(start 131.060952 -150.75281)
		(end 132.499354 -152.191212)
		(width 0.1524)
		(layer "In6.Cu")
		(net "PVDDCR_SOC_P1_PWM3")
	)
	(segment
		(start 123.705874 -162.292538)
		(end 123.705874 -161.187892)
		(width 0.1778)
		(layer "F.Cu")
		(net "PVDDCR_SOC_P1_PWM2")
	)
	(segment
		(start 123.705874 -161.187892)
		(end 124.041154 -160.852612)
		(width 0.1778)
		(layer "F.Cu")
		(net "PVDDCR_SOC_P1_PWM2")
	)
	(via
		(at 97.300034 -140.649452)
		(size 0.508)
		(drill 0.254)
		(layers "F.Cu" "B.Cu")
		(net "PVDDCR_SOC_P1_PWM2")
	)
	(via
		(at 124.041154 -160.852612)
		(size 0.508)
		(drill 0.254)
		(layers "F.Cu" "B.Cu")
		(net "PVDDCR_SOC_P1_PWM2")
	)
	(segment
		(start 97.300034 -140.649452)
		(end 97.300034 -141.157452)
		(width 0.1524)
		(layer "B.Cu")
		(net "PVDDCR_SOC_P1_PWM2")
	)
	(segment
		(start 97.300034 -141.157452)
		(end 97.470976 -141.328394)
		(width 0.1524)
		(layer "B.Cu")
		(net "PVDDCR_SOC_P1_PWM2")
	)
	(segment
		(start 97.470976 -141.328394)
		(end 97.470976 -141.883384)
		(width 0.1524)
		(layer "B.Cu")
		(net "PVDDCR_SOC_P1_PWM2")
	)
	(segment
		(start 106.037634 -156.52623)
		(end 106.037634 -141.696948)
		(width 0.1524)
		(layer "In6.Cu")
		(net "PVDDCR_SOC_P1_PWM2")
	)
	(segment
		(start 109.739176 -160.227772)
		(end 106.037634 -156.52623)
		(width 0.1524)
		(layer "In6.Cu")
		(net "PVDDCR_SOC_P1_PWM2")
	)
	(segment
		(start 106.037634 -141.696948)
		(end 104.247696 -139.90701)
		(width 0.1524)
		(layer "In6.Cu")
		(net "PVDDCR_SOC_P1_PWM2")
	)
	(segment
		(start 123.416314 -160.227772)
		(end 109.739176 -160.227772)
		(width 0.1524)
		(layer "In6.Cu")
		(net "PVDDCR_SOC_P1_PWM2")
	)
	(segment
		(start 104.247696 -139.90701)
		(end 98.042476 -139.90701)
		(width 0.1524)
		(layer "In6.Cu")
		(net "PVDDCR_SOC_P1_PWM2")
	)
	(segment
		(start 124.041154 -160.852612)
		(end 123.416314 -160.227772)
		(width 0.1524)
		(layer "In6.Cu")
		(net "PVDDCR_SOC_P1_PWM2")
	)
	(segment
		(start 98.042476 -139.90701)
		(end 97.300034 -140.649452)
		(width 0.1524)
		(layer "In6.Cu")
		(net "PVDDCR_SOC_P1_PWM2")
	)
	(segment
		(start 115.425474 -169.023538)
		(end 115.425474 -167.918892)
		(width 0.1778)
		(layer "F.Cu")
		(net "PVDDCR_SOC_P1_PWM1")
	)
	(segment
		(start 115.425474 -167.918892)
		(end 115.760754 -167.583612)
		(width 0.1778)
		(layer "F.Cu")
		(net "PVDDCR_SOC_P1_PWM1")
	)
	(via
		(at 115.760754 -167.583612)
		(size 0.508)
		(drill 0.254)
		(layers "F.Cu" "B.Cu")
		(net "PVDDCR_SOC_P1_PWM1")
	)
	(via
		(at 97.870772 -141.030452)
		(size 0.508)
		(drill 0.254)
		(layers "F.Cu" "B.Cu")
		(net "PVDDCR_SOC_P1_PWM1")
	)
	(segment
		(start 97.870772 -141.883384)
		(end 97.870772 -141.030452)
		(width 0.1524)
		(layer "B.Cu")
		(net "PVDDCR_SOC_P1_PWM1")
	)
	(segment
		(start 98.39198 -141.7955)
		(end 99.32924 -141.7955)
		(width 0.1524)
		(layer "In6.Cu")
		(net "PVDDCR_SOC_P1_PWM1")
	)
	(segment
		(start 103.942134 -140.32992)
		(end 104.920034 -141.30782)
		(width 0.1524)
		(layer "In6.Cu")
		(net "PVDDCR_SOC_P1_PWM1")
	)
	(segment
		(start 104.920034 -158.124652)
		(end 114.378994 -167.583612)
		(width 0.1524)
		(layer "In6.Cu")
		(net "PVDDCR_SOC_P1_PWM1")
	)
	(segment
		(start 97.870772 -141.030452)
		(end 97.870772 -141.274292)
		(width 0.1524)
		(layer "In6.Cu")
		(net "PVDDCR_SOC_P1_PWM1")
	)
	(segment
		(start 99.32924 -141.7955)
		(end 100.79482 -140.32992)
		(width 0.1524)
		(layer "In6.Cu")
		(net "PVDDCR_SOC_P1_PWM1")
	)
	(segment
		(start 104.920034 -141.30782)
		(end 104.920034 -158.124652)
		(width 0.1524)
		(layer "In6.Cu")
		(net "PVDDCR_SOC_P1_PWM1")
	)
	(segment
		(start 114.378994 -167.583612)
		(end 115.760754 -167.583612)
		(width 0.1524)
		(layer "In6.Cu")
		(net "PVDDCR_SOC_P1_PWM1")
	)
	(segment
		(start 100.79482 -140.32992)
		(end 103.942134 -140.32992)
		(width 0.1524)
		(layer "In6.Cu")
		(net "PVDDCR_SOC_P1_PWM1")
	)
	(segment
		(start 97.870772 -141.274292)
		(end 98.39198 -141.7955)
		(width 0.1524)
		(layer "In6.Cu")
		(net "PVDDCR_SOC_P1_PWM1")
	)
	(segment
		(start 133.886702 -152.42159)
		(end 133.886702 -152.871424)
		(width 0.127)
		(layer "F.Cu")
		(net "PVDDCR_SOC_P1_LSET3")
	)
	(segment
		(start 133.514084 -153.244042)
		(end 133.514084 -153.631138)
		(width 0.127)
		(layer "F.Cu")
		(net "PVDDCR_SOC_P1_LSET3")
	)
	(segment
		(start 133.886702 -152.871424)
		(end 133.514084 -153.244042)
		(width 0.127)
		(layer "F.Cu")
		(net "PVDDCR_SOC_P1_LSET3")
	)
	(segment
		(start 134.128764 -151.319484)
		(end 133.886702 -151.561546)
		(width 0.127)
		(layer "F.Cu")
		(net "PVDDCR_SOC_P1_LSET3")
	)
	(segment
		(start 133.886702 -151.561546)
		(end 133.886702 -152.42159)
		(width 0.127)
		(layer "F.Cu")
		(net "PVDDCR_SOC_P1_LSET3")
	)
	(via
		(at 133.886702 -152.42159)
		(size 0.4064)
		(drill 0.2032)
		(layers "F.Cu" "B.Cu")
		(net "PVDDCR_SOC_P1_LSET3")
	)
	(segment
		(start 125.428502 -161.118804)
		(end 125.428502 -161.514028)
		(width 0.127)
		(layer "F.Cu")
		(net "PVDDCR_SOC_P1_LSET2")
	)
	(segment
		(start 125.055884 -161.886646)
		(end 125.055884 -162.292538)
		(width 0.127)
		(layer "F.Cu")
		(net "PVDDCR_SOC_P1_LSET2")
	)
	(segment
		(start 125.670564 -159.980884)
		(end 125.428502 -160.222946)
		(width 0.127)
		(layer "F.Cu")
		(net "PVDDCR_SOC_P1_LSET2")
	)
	(segment
		(start 125.428502 -160.222946)
		(end 125.428502 -161.118804)
		(width 0.127)
		(layer "F.Cu")
		(net "PVDDCR_SOC_P1_LSET2")
	)
	(segment
		(start 125.428502 -161.514028)
		(end 125.055884 -161.886646)
		(width 0.127)
		(layer "F.Cu")
		(net "PVDDCR_SOC_P1_LSET2")
	)
	(via
		(at 125.428502 -161.118804)
		(size 0.4064)
		(drill 0.2032)
		(layers "F.Cu" "B.Cu")
		(net "PVDDCR_SOC_P1_LSET2")
	)
	(segment
		(start 117.390164 -166.711884)
		(end 117.148102 -166.953946)
		(width 0.127)
		(layer "F.Cu")
		(net "PVDDCR_SOC_P1_LSET1")
	)
	(segment
		(start 117.148102 -166.953946)
		(end 117.148102 -167.832786)
		(width 0.127)
		(layer "F.Cu")
		(net "PVDDCR_SOC_P1_LSET1")
	)
	(segment
		(start 117.148102 -167.832786)
		(end 117.148102 -168.245028)
		(width 0.127)
		(layer "F.Cu")
		(net "PVDDCR_SOC_P1_LSET1")
	)
	(segment
		(start 116.775484 -168.617646)
		(end 116.775484 -169.023538)
		(width 0.127)
		(layer "F.Cu")
		(net "PVDDCR_SOC_P1_LSET1")
	)
	(segment
		(start 117.148102 -168.245028)
		(end 116.775484 -168.617646)
		(width 0.127)
		(layer "F.Cu")
		(net "PVDDCR_SOC_P1_LSET1")
	)
	(via
		(at 117.148102 -167.832786)
		(size 0.4064)
		(drill 0.2032)
		(layers "F.Cu" "B.Cu")
		(net "PVDDCR_SOC_P1_LSET1")
	)
	(segment
		(start 134.401306 -152.816306)
		(end 134.401306 -152.818084)
		(width 0.254)
		(layer "F.Cu")
		(net "PVDDCR_SOC_P1_IMON3")
	)
	(segment
		(start 133.964172 -153.255218)
		(end 133.964172 -153.631138)
		(width 0.2286)
		(layer "F.Cu")
		(net "PVDDCR_SOC_P1_IMON3")
	)
	(segment
		(start 134.401306 -152.818084)
		(end 134.12216 -153.09723)
		(width 0.254)
		(layer "F.Cu")
		(net "PVDDCR_SOC_P1_IMON3")
	)
	(segment
		(start 134.12216 -153.09723)
		(end 133.964172 -153.255218)
		(width 0.2286)
		(layer "F.Cu")
		(net "PVDDCR_SOC_P1_IMON3")
	)
	(segment
		(start 134.42569 -152.791922)
		(end 134.401306 -152.816306)
		(width 0.254)
		(layer "F.Cu")
		(net "PVDDCR_SOC_P1_IMON3")
	)
	(via
		(at 98.324162 -148.464524)
		(size 0.762)
		(drill 0.254)
		(layers "F.Cu" "B.Cu")
		(net "PVDDCR_SOC_P1_IMON3")
	)
	(via
		(at 134.42569 -152.791922)
		(size 0.508)
		(drill 0.254)
		(layers "F.Cu" "B.Cu")
		(net "PVDDCR_SOC_P1_IMON3")
	)
	(segment
		(start 97.912174 -148.052536)
		(end 97.870772 -147.95246)
		(width 0.1778)
		(layer "B.Cu")
		(net "PVDDCR_SOC_P1_IMON3")
	)
	(segment
		(start 97.870772 -147.95246)
		(end 97.870772 -147.633436)
		(width 0.1778)
		(layer "B.Cu")
		(net "PVDDCR_SOC_P1_IMON3")
	)
	(segment
		(start 98.324162 -148.464524)
		(end 97.912174 -148.052536)
		(width 0.254)
		(layer "B.Cu")
		(net "PVDDCR_SOC_P1_IMON3")
	)
	(segment
		(start 122.33783 -156.16047)
		(end 107.807252 -156.16047)
		(width 0.254)
		(layer "In4.Cu")
		(net "PVDDCR_SOC_P1_IMON3")
	)
	(segment
		(start 134.42569 -152.791922)
		(end 134.472426 -152.791922)
		(width 0.254)
		(layer "In4.Cu")
		(net "PVDDCR_SOC_P1_IMON3")
	)
	(segment
		(start 128.15189 -150.34641)
		(end 122.33783 -156.16047)
		(width 0.254)
		(layer "In4.Cu")
		(net "PVDDCR_SOC_P1_IMON3")
	)
	(segment
		(start 134.990078 -152.27427)
		(end 134.990078 -151.153622)
		(width 0.254)
		(layer "In4.Cu")
		(net "PVDDCR_SOC_P1_IMON3")
	)
	(segment
		(start 107.807252 -156.16047)
		(end 100.111306 -148.464524)
		(width 0.254)
		(layer "In4.Cu")
		(net "PVDDCR_SOC_P1_IMON3")
	)
	(segment
		(start 134.182866 -150.34641)
		(end 128.15189 -150.34641)
		(width 0.254)
		(layer "In4.Cu")
		(net "PVDDCR_SOC_P1_IMON3")
	)
	(segment
		(start 134.472426 -152.791922)
		(end 134.990078 -152.27427)
		(width 0.254)
		(layer "In4.Cu")
		(net "PVDDCR_SOC_P1_IMON3")
	)
	(segment
		(start 100.111306 -148.464524)
		(end 98.324162 -148.464524)
		(width 0.254)
		(layer "In4.Cu")
		(net "PVDDCR_SOC_P1_IMON3")
	)
	(segment
		(start 134.990078 -151.153622)
		(end 134.182866 -150.34641)
		(width 0.254)
		(layer "In4.Cu")
		(net "PVDDCR_SOC_P1_IMON3")
	)
	(segment
		(start 125.943106 -161.479484)
		(end 125.505972 -161.916618)
		(width 0.2286)
		(layer "F.Cu")
		(net "PVDDCR_SOC_P1_IMON2")
	)
	(segment
		(start 125.943106 -161.372042)
		(end 125.943106 -161.479484)
		(width 0.2286)
		(layer "F.Cu")
		(net "PVDDCR_SOC_P1_IMON2")
	)
	(segment
		(start 125.505972 -161.916618)
		(end 125.505972 -162.292538)
		(width 0.2286)
		(layer "F.Cu")
		(net "PVDDCR_SOC_P1_IMON2")
	)
	(via
		(at 125.943106 -161.372042)
		(size 0.508)
		(drill 0.254)
		(layers "F.Cu" "B.Cu")
		(net "PVDDCR_SOC_P1_IMON2")
	)
	(via
		(at 99.319334 -149.552152)
		(size 0.508)
		(drill 0.254)
		(layers "F.Cu" "B.Cu")
		(net "PVDDCR_SOC_P1_IMON2")
	)
	(segment
		(start 98.697034 -146.958304)
		(end 98.781362 -147.042632)
		(width 0.1778)
		(layer "B.Cu")
		(net "PVDDCR_SOC_P1_IMON2")
	)
	(segment
		(start 98.545904 -146.958304)
		(end 98.697034 -146.958304)
		(width 0.1778)
		(layer "B.Cu")
		(net "PVDDCR_SOC_P1_IMON2")
	)
	(segment
		(start 99.319334 -148.341588)
		(end 99.319334 -149.552152)
		(width 0.254)
		(layer "B.Cu")
		(net "PVDDCR_SOC_P1_IMON2")
	)
	(segment
		(start 98.781362 -147.042632)
		(end 99.319334 -148.341588)
		(width 0.1778)
		(layer "B.Cu")
		(net "PVDDCR_SOC_P1_IMON2")
	)
	(segment
		(start 124.683266 -157.96641)
		(end 107.733592 -157.96641)
		(width 0.254)
		(layer "In4.Cu")
		(net "PVDDCR_SOC_P1_IMON2")
	)
	(segment
		(start 126.04877 -161.372042)
		(end 126.531878 -160.888934)
		(width 0.254)
		(layer "In4.Cu")
		(net "PVDDCR_SOC_P1_IMON2")
	)
	(segment
		(start 107.733592 -157.96641)
		(end 99.319334 -149.552152)
		(width 0.254)
		(layer "In4.Cu")
		(net "PVDDCR_SOC_P1_IMON2")
	)
	(segment
		(start 126.531878 -160.888934)
		(end 126.531878 -159.815022)
		(width 0.254)
		(layer "In4.Cu")
		(net "PVDDCR_SOC_P1_IMON2")
	)
	(segment
		(start 126.531878 -159.815022)
		(end 124.683266 -157.96641)
		(width 0.254)
		(layer "In4.Cu")
		(net "PVDDCR_SOC_P1_IMON2")
	)
	(segment
		(start 125.943106 -161.372042)
		(end 126.04877 -161.372042)
		(width 0.254)
		(layer "In4.Cu")
		(net "PVDDCR_SOC_P1_IMON2")
	)
	(segment
		(start 117.651022 -168.244266)
		(end 117.225572 -168.669716)
		(width 0.2286)
		(layer "F.Cu")
		(net "PVDDCR_SOC_P1_IMON1")
	)
	(segment
		(start 117.225572 -168.669716)
		(end 117.225572 -169.023538)
		(width 0.2286)
		(layer "F.Cu")
		(net "PVDDCR_SOC_P1_IMON1")
	)
	(segment
		(start 117.651022 -168.103042)
		(end 117.651022 -168.244266)
		(width 0.2286)
		(layer "F.Cu")
		(net "PVDDCR_SOC_P1_IMON1")
	)
	(via
		(at 99.687634 -151.634952)
		(size 0.508)
		(drill 0.254)
		(layers "F.Cu" "B.Cu")
		(net "PVDDCR_SOC_P1_IMON1")
	)
	(via
		(at 117.651022 -168.103042)
		(size 0.508)
		(drill 0.254)
		(layers "F.Cu" "B.Cu")
		(net "PVDDCR_SOC_P1_IMON1")
	)
	(segment
		(start 99.244404 -146.807936)
		(end 99.941634 -148.491194)
		(width 0.1778)
		(layer "B.Cu")
		(net "PVDDCR_SOC_P1_IMON1")
	)
	(segment
		(start 99.941634 -148.491194)
		(end 99.941634 -151.380952)
		(width 0.1778)
		(layer "B.Cu")
		(net "PVDDCR_SOC_P1_IMON1")
	)
	(segment
		(start 98.994976 -146.558508)
		(end 99.244404 -146.807936)
		(width 0.1778)
		(layer "B.Cu")
		(net "PVDDCR_SOC_P1_IMON1")
	)
	(segment
		(start 99.941634 -151.380952)
		(end 99.687634 -151.634952)
		(width 0.1778)
		(layer "B.Cu")
		(net "PVDDCR_SOC_P1_IMON1")
	)
	(segment
		(start 98.545904 -146.558508)
		(end 98.994976 -146.558508)
		(width 0.1778)
		(layer "B.Cu")
		(net "PVDDCR_SOC_P1_IMON1")
	)
	(segment
		(start 117.651022 -168.103042)
		(end 117.76837 -168.103042)
		(width 0.254)
		(layer "In4.Cu")
		(net "PVDDCR_SOC_P1_IMON1")
	)
	(segment
		(start 118.251478 -166.546022)
		(end 113.227866 -161.52241)
		(width 0.254)
		(layer "In4.Cu")
		(net "PVDDCR_SOC_P1_IMON1")
	)
	(segment
		(start 117.76837 -168.103042)
		(end 118.251478 -167.619934)
		(width 0.254)
		(layer "In4.Cu")
		(net "PVDDCR_SOC_P1_IMON1")
	)
	(segment
		(start 108.114592 -161.52241)
		(end 99.687634 -153.095452)
		(width 0.254)
		(layer "In4.Cu")
		(net "PVDDCR_SOC_P1_IMON1")
	)
	(segment
		(start 99.687634 -153.095452)
		(end 99.687634 -151.634952)
		(width 0.254)
		(layer "In4.Cu")
		(net "PVDDCR_SOC_P1_IMON1")
	)
	(segment
		(start 118.251478 -167.619934)
		(end 118.251478 -166.546022)
		(width 0.254)
		(layer "In4.Cu")
		(net "PVDDCR_SOC_P1_IMON1")
	)
	(segment
		(start 113.227866 -161.52241)
		(end 108.114592 -161.52241)
		(width 0.254)
		(layer "In4.Cu")
		(net "PVDDCR_SOC_P1_IMON1")
	)
	(segment
		(start 96.701102 -136.466834)
		(end 96.715834 -136.452102)
		(width 0.10668)
		(layer "F.Cu")
		(net "PVDDCR_SOC_P1_EN_RC")
	)
	(segment
		(start 95.482156 -136.459468)
		(end 95.489522 -136.466834)
		(width 0.10668)
		(layer "F.Cu")
		(net "PVDDCR_SOC_P1_EN_RC")
	)
	(segment
		(start 96.969834 -137.703052)
		(end 96.715834 -137.703052)
		(width 0.10668)
		(layer "F.Cu")
		(net "PVDDCR_SOC_P1_EN_RC")
	)
	(segment
		(start 96.715834 -136.452102)
		(end 96.715834 -137.703052)
		(width 0.10668)
		(layer "F.Cu")
		(net "PVDDCR_SOC_P1_EN_RC")
	)
	(segment
		(start 98.40976 -137.129012)
		(end 97.543874 -137.129012)
		(width 0.10668)
		(layer "F.Cu")
		(net "PVDDCR_SOC_P1_EN_RC")
	)
	(segment
		(start 95.489522 -136.466834)
		(end 96.701102 -136.466834)
		(width 0.10668)
		(layer "F.Cu")
		(net "PVDDCR_SOC_P1_EN_RC")
	)
	(segment
		(start 94.478348 -136.459468)
		(end 95.482156 -136.459468)
		(width 0.10668)
		(layer "F.Cu")
		(net "PVDDCR_SOC_P1_EN_RC")
	)
	(segment
		(start 97.543874 -137.129012)
		(end 96.969834 -137.703052)
		(width 0.10668)
		(layer "F.Cu")
		(net "PVDDCR_SOC_P1_EN_RC")
	)
	(via
		(at 96.715834 -137.703052)
		(size 0.762)
		(drill 0.381)
		(layers "F.Cu" "B.Cu")
		(net "PVDDCR_SOC_P1_EN_RC")
	)
	(segment
		(start 105.332784 -135.690102)
		(end 105.716832 -135.306054)
		(width 0.10668)
		(layer "F.Cu")
		(net "PVDDCR_SOC_P1_EN_GD")
	)
	(segment
		(start 105.716832 -135.306054)
		(end 106.306874 -135.306054)
		(width 0.10668)
		(layer "F.Cu")
		(net "PVDDCR_SOC_P1_EN_GD")
	)
	(segment
		(start 104.843834 -135.690102)
		(end 105.332784 -135.690102)
		(width 0.10668)
		(layer "F.Cu")
		(net "PVDDCR_SOC_P1_EN_GD")
	)
	(segment
		(start 102.792784 -135.690102)
		(end 102.303834 -136.179052)
		(width 0.10668)
		(layer "F.Cu")
		(net "PVDDCR_SOC_P1_EN_GD")
	)
	(segment
		(start 102.303834 -136.179052)
		(end 100.609908 -136.179052)
		(width 0.10668)
		(layer "F.Cu")
		(net "PVDDCR_SOC_P1_EN_GD")
	)
	(segment
		(start 103.254048 -135.690102)
		(end 102.792784 -135.690102)
		(width 0.10668)
		(layer "F.Cu")
		(net "PVDDCR_SOC_P1_EN_GD")
	)
	(segment
		(start 103.254048 -135.690102)
		(end 104.843834 -135.690102)
		(width 0.10668)
		(layer "F.Cu")
		(net "PVDDCR_SOC_P1_EN_GD")
	)
	(via
		(at 103.254048 -135.690102)
		(size 0.762)
		(drill 0.381)
		(layers "F.Cu" "B.Cu")
		(net "PVDDCR_SOC_P1_EN_GD")
	)
	(segment
		(start 99.912678 -145.06321)
		(end 99.944174 -145.094706)
		(width 0.10668)
		(layer "F.Cu")
		(net "PVDDCR_SOC_P1_EN//ADDR_CFG")
	)
	(segment
		(start 105.885996 -139.455144)
		(end 107.256834 -138.084306)
		(width 0.10668)
		(layer "F.Cu")
		(net "PVDDCR_SOC_P1_EN//ADDR_CFG")
	)
	(segment
		(start 99.921822 -147.186142)
		(end 99.975416 -147.186142)
		(width 0.10668)
		(layer "F.Cu")
		(net "PVDDCR_SOC_P1_EN//ADDR_CFG")
	)
	(segment
		(start 99.195128 -145.06321)
		(end 99.912678 -145.06321)
		(width 0.10668)
		(layer "F.Cu")
		(net "PVDDCR_SOC_P1_EN//ADDR_CFG")
	)
	(segment
		(start 101.828092 -147.186142)
		(end 103.260144 -145.75409)
		(width 0.10668)
		(layer "F.Cu")
		(net "PVDDCR_SOC_P1_EN//ADDR_CFG")
	)
	(segment
		(start 103.260144 -145.663158)
		(end 105.885996 -143.037306)
		(width 0.10668)
		(layer "F.Cu")
		(net "PVDDCR_SOC_P1_EN//ADDR_CFG")
	)
	(segment
		(start 99.195128 -145.06321)
		(end 99.195128 -146.459448)
		(width 0.10668)
		(layer "F.Cu")
		(net "PVDDCR_SOC_P1_EN//ADDR_CFG")
	)
	(segment
		(start 99.975416 -147.186142)
		(end 101.828092 -147.186142)
		(width 0.10668)
		(layer "F.Cu")
		(net "PVDDCR_SOC_P1_EN//ADDR_CFG")
	)
	(segment
		(start 99.195128 -146.459448)
		(end 99.921822 -147.186142)
		(width 0.10668)
		(layer "F.Cu")
		(net "PVDDCR_SOC_P1_EN//ADDR_CFG")
	)
	(segment
		(start 107.256834 -138.084306)
		(end 107.256834 -137.30605)
		(width 0.10668)
		(layer "F.Cu")
		(net "PVDDCR_SOC_P1_EN//ADDR_CFG")
	)
	(segment
		(start 105.885996 -143.037306)
		(end 105.885996 -139.455144)
		(width 0.10668)
		(layer "F.Cu")
		(net "PVDDCR_SOC_P1_EN//ADDR_CFG")
	)
	(segment
		(start 103.260144 -145.75409)
		(end 103.260144 -145.663158)
		(width 0.10668)
		(layer "F.Cu")
		(net "PVDDCR_SOC_P1_EN//ADDR_CFG")
	)
	(via
		(at 99.975416 -147.186142)
		(size 0.762)
		(drill 0.381)
		(layers "F.Cu" "B.Cu")
		(net "PVDDCR_SOC_P1_EN//ADDR_CFG")
	)
	(via
		(at 99.944174 -145.094706)
		(size 0.508)
		(drill 0.254)
		(layers "F.Cu" "B.Cu")
		(net "PVDDCR_SOC_P1_EN//ADDR_CFG")
	)
	(segment
		(start 99.807776 -144.958308)
		(end 99.944174 -145.094706)
		(width 0.10668)
		(layer "B.Cu")
		(net "PVDDCR_SOC_P1_EN//ADDR_CFG")
	)
	(segment
		(start 98.545904 -144.958308)
		(end 99.807776 -144.958308)
		(width 0.10668)
		(layer "B.Cu")
		(net "PVDDCR_SOC_P1_EN//ADDR_CFG")
	)
	(segment
		(start 94.478348 -135.659368)
		(end 94.478348 -133.338316)
		(width 0.10668)
		(layer "F.Cu")
		(net "PVDDCR_SOC_P1_EN")
	)
	(segment
		(start 178.72202 -117.852952)
		(end 178.33213 -118.242842)
		(width 0.10668)
		(layer "F.Cu")
		(net "PVDDCR_SOC_P1_EN")
	)
	(via
		(at 139.128754 -120.060212)
		(size 0.508)
		(drill 0.254)
		(layers "F.Cu" "B.Cu")
		(net "PVDDCR_SOC_P1_EN")
	)
	(via
		(at 94.478348 -133.338316)
		(size 0.762)
		(drill 0.254)
		(layers "F.Cu" "B.Cu")
		(net "PVDDCR_SOC_P1_EN")
	)
	(via
		(at 178.33213 -118.242842)
		(size 0.4572)
		(drill 0.254)
		(layers "F.Cu" "B.Cu")
		(net "PVDDCR_SOC_P1_EN")
	)
	(segment
		(start 118.724172 -125.254004)
		(end 119.4054 -124.572776)
		(width 0.10668)
		(layer "B.Cu")
		(net "PVDDCR_SOC_P1_EN")
	)
	(segment
		(start 94.478348 -133.338316)
		(end 94.478348 -125.524768)
		(width 0.10668)
		(layer "B.Cu")
		(net "PVDDCR_SOC_P1_EN")
	)
	(segment
		(start 117.811296 -125.254004)
		(end 118.724172 -125.254004)
		(width 0.10668)
		(layer "B.Cu")
		(net "PVDDCR_SOC_P1_EN")
	)
	(segment
		(start 134.61619 -124.572776)
		(end 139.128754 -120.060212)
		(width 0.10668)
		(layer "B.Cu")
		(net "PVDDCR_SOC_P1_EN")
	)
	(segment
		(start 117.130068 -124.572776)
		(end 117.811296 -125.254004)
		(width 0.10668)
		(layer "B.Cu")
		(net "PVDDCR_SOC_P1_EN")
	)
	(segment
		(start 95.43034 -124.572776)
		(end 117.130068 -124.572776)
		(width 0.10668)
		(layer "B.Cu")
		(net "PVDDCR_SOC_P1_EN")
	)
	(segment
		(start 94.478348 -125.524768)
		(end 95.43034 -124.572776)
		(width 0.10668)
		(layer "B.Cu")
		(net "PVDDCR_SOC_P1_EN")
	)
	(segment
		(start 119.4054 -124.572776)
		(end 134.61619 -124.572776)
		(width 0.10668)
		(layer "B.Cu")
		(net "PVDDCR_SOC_P1_EN")
	)
	(segment
		(start 170.387264 -119.841518)
		(end 163.397692 -119.841518)
		(width 0.11684)
		(layer "In2.Cu")
		(net "PVDDCR_SOC_P1_EN")
	)
	(segment
		(start 161.05505 -122.18416)
		(end 151.084026 -122.18416)
		(width 0.11684)
		(layer "In2.Cu")
		(net "PVDDCR_SOC_P1_EN")
	)
	(segment
		(start 175.428148 -118.646448)
		(end 175.159162 -118.377462)
		(width 0.11684)
		(layer "In2.Cu")
		(net "PVDDCR_SOC_P1_EN")
	)
	(segment
		(start 150.155656 -123.11253)
		(end 148.219922 -123.11253)
		(width 0.11684)
		(layer "In2.Cu")
		(net "PVDDCR_SOC_P1_EN")
	)
	(segment
		(start 163.397692 -119.841518)
		(end 161.05505 -122.18416)
		(width 0.11684)
		(layer "In2.Cu")
		(net "PVDDCR_SOC_P1_EN")
	)
	(segment
		(start 171.85132 -118.377462)
		(end 170.387264 -119.841518)
		(width 0.11684)
		(layer "In2.Cu")
		(net "PVDDCR_SOC_P1_EN")
	)
	(segment
		(start 178.33213 -118.242842)
		(end 177.928524 -118.646448)
		(width 0.11684)
		(layer "In2.Cu")
		(net "PVDDCR_SOC_P1_EN")
	)
	(segment
		(start 177.928524 -118.646448)
		(end 175.428148 -118.646448)
		(width 0.11684)
		(layer "In2.Cu")
		(net "PVDDCR_SOC_P1_EN")
	)
	(segment
		(start 175.159162 -118.377462)
		(end 171.85132 -118.377462)
		(width 0.11684)
		(layer "In2.Cu")
		(net "PVDDCR_SOC_P1_EN")
	)
	(segment
		(start 145.167604 -120.060212)
		(end 139.128754 -120.060212)
		(width 0.11684)
		(layer "In2.Cu")
		(net "PVDDCR_SOC_P1_EN")
	)
	(segment
		(start 151.084026 -122.18416)
		(end 150.155656 -123.11253)
		(width 0.11684)
		(layer "In2.Cu")
		(net "PVDDCR_SOC_P1_EN")
	)
	(segment
		(start 148.219922 -123.11253)
		(end 145.167604 -120.060212)
		(width 0.11684)
		(layer "In2.Cu")
		(net "PVDDCR_SOC_P1_EN")
	)
	(segment
		(start 101.437948 -255.280414)
		(end 100.971096 -255.014476)
		(width 0.350012)
		(layer "F.Cu")
		(net "PVDDCR_SOC_P1")
	)
	(segment
		(start 115.537996 -252.04039)
		(end 116.004848 -251.774452)
		(width 0.350012)
		(layer "F.Cu")
		(net "PVDDCR_SOC_P1")
	)
	(segment
		(start 126.817882 -256.900426)
		(end 127.284734 -256.634488)
		(width 0.350012)
		(layer "F.Cu")
		(net "PVDDCR_SOC_P1")
	)
	(segment
		(start 117.888004 -251.230384)
		(end 118.354856 -250.964446)
		(width 0.350012)
		(layer "F.Cu")
		(net "PVDDCR_SOC_P1")
	)
	(segment
		(start 142.797784 -242.320318)
		(end 143.264636 -242.05438)
		(width 0.350012)
		(layer "F.Cu")
		(net "PVDDCR_SOC_P1")
	)
	(segment
		(start 126.817882 -250.420378)
		(end 127.284734 -250.15444)
		(width 0.350012)
		(layer "F.Cu")
		(net "PVDDCR_SOC_P1")
	)
	(segment
		(start 143.567912 -263.290304)
		(end 144.034764 -263.556242)
		(width 0.350012)
		(layer "F.Cu")
		(net "PVDDCR_SOC_P1")
	)
	(segment
		(start 126.817882 -229.360476)
		(end 127.284734 -229.094538)
		(width 0.350012)
		(layer "F.Cu")
		(net "PVDDCR_SOC_P1")
	)
	(segment
		(start 126.647956 -261.670292)
		(end 127.114808 -261.93623)
		(width 0.350012)
		(layer "F.Cu")
		(net "PVDDCR_SOC_P1")
	)
	(segment
		(start 130.107944 -230.170228)
		(end 130.574796 -229.90429)
		(width 0.350012)
		(layer "F.Cu")
		(net "PVDDCR_SOC_P1")
	)
	(segment
		(start 136.687814 -230.170228)
		(end 137.154666 -229.90429)
		(width 0.350012)
		(layer "F.Cu")
		(net "PVDDCR_SOC_P1")
	)
	(segment
		(start 136.687814 -235.030264)
		(end 137.154666 -234.764326)
		(width 0.350012)
		(layer "F.Cu")
		(net "PVDDCR_SOC_P1")
	)
	(segment
		(start 126.817882 -235.84027)
		(end 127.284734 -235.574332)
		(width 0.350012)
		(layer "F.Cu")
		(net "PVDDCR_SOC_P1")
	)
	(segment
		(start 125.407928 -252.850396)
		(end 125.87478 -252.584458)
		(width 0.350012)
		(layer "F.Cu")
		(net "PVDDCR_SOC_P1")
	)
	(segment
		(start 101.437948 -253.660402)
		(end 100.971096 -253.394464)
		(width 0.350012)
		(layer "F.Cu")
		(net "PVDDCR_SOC_P1")
	)
	(segment
		(start 126.177802 -260.860286)
		(end 126.644654 -261.126224)
		(width 0.350012)
		(layer "F.Cu")
		(net "PVDDCR_SOC_P1")
	)
	(segment
		(start 143.267938 -225.310446)
		(end 143.73479 -225.044508)
		(width 0.350012)
		(layer "F.Cu")
		(net "PVDDCR_SOC_P1")
	)
	(segment
		(start 125.407928 -254.470408)
		(end 125.87478 -254.20447)
		(width 0.350012)
		(layer "F.Cu")
		(net "PVDDCR_SOC_P1")
	)
	(segment
		(start 121.647966 -251.230384)
		(end 122.114818 -250.964446)
		(width 0.350012)
		(layer "F.Cu")
		(net "PVDDCR_SOC_P1")
	)
	(segment
		(start 129.63779 -256.900426)
		(end 130.104642 -256.634488)
		(width 0.350012)
		(layer "F.Cu")
		(net "PVDDCR_SOC_P1")
	)
	(segment
		(start 136.687814 -254.470408)
		(end 137.154666 -254.20447)
		(width 0.350012)
		(layer "F.Cu")
		(net "PVDDCR_SOC_P1")
	)
	(segment
		(start 108.957872 -252.04039)
		(end 108.49102 -251.774452)
		(width 0.350012)
		(layer "F.Cu")
		(net "PVDDCR_SOC_P1")
	)
	(segment
		(start 121.177812 -253.660402)
		(end 121.644664 -253.394464)
		(width 0.350012)
		(layer "F.Cu")
		(net "PVDDCR_SOC_P1")
	)
	(segment
		(start 142.797784 -252.04039)
		(end 143.264636 -251.774452)
		(width 0.350012)
		(layer "F.Cu")
		(net "PVDDCR_SOC_P1")
	)
	(segment
		(start 130.107944 -244.750336)
		(end 130.574796 -244.484398)
		(width 0.350012)
		(layer "F.Cu")
		(net "PVDDCR_SOC_P1")
	)
	(segment
		(start 102.677976 -260.860286)
		(end 102.211124 -261.126224)
		(width 0.350012)
		(layer "F.Cu")
		(net "PVDDCR_SOC_P1")
	)
	(segment
		(start 136.987788 -263.290304)
		(end 137.45464 -263.556242)
		(width 0.350012)
		(layer "F.Cu")
		(net "PVDDCR_SOC_P1")
	)
	(segment
		(start 103.147876 -261.670292)
		(end 102.681024 -261.93623)
		(width 0.350012)
		(layer "F.Cu")
		(net "PVDDCR_SOC_P1")
	)
	(segment
		(start 130.107944 -249.610372)
		(end 130.574796 -249.344434)
		(width 0.350012)
		(layer "F.Cu")
		(net "PVDDCR_SOC_P1")
	)
	(segment
		(start 124.937774 -253.660402)
		(end 125.404626 -253.394464)
		(width 0.350012)
		(layer "F.Cu")
		(net "PVDDCR_SOC_P1")
	)
	(segment
		(start 123.05792 -255.280414)
		(end 123.524772 -255.014476)
		(width 0.350012)
		(layer "F.Cu")
		(net "PVDDCR_SOC_P1")
	)
	(segment
		(start 126.817882 -232.600246)
		(end 127.284734 -232.334308)
		(width 0.350012)
		(layer "F.Cu")
		(net "PVDDCR_SOC_P1")
	)
	(segment
		(start 142.797784 -222.880428)
		(end 143.264636 -222.61449)
		(width 0.350012)
		(layer "F.Cu")
		(net "PVDDCR_SOC_P1")
	)
	(segment
		(start 143.267938 -249.610372)
		(end 143.73479 -249.344434)
		(width 0.350012)
		(layer "F.Cu")
		(net "PVDDCR_SOC_P1")
	)
	(segment
		(start 124.937774 -252.04039)
		(end 125.404626 -251.774452)
		(width 0.350012)
		(layer "F.Cu")
		(net "PVDDCR_SOC_P1")
	)
	(segment
		(start 123.05792 -253.660402)
		(end 123.524772 -253.394464)
		(width 0.350012)
		(layer "F.Cu")
		(net "PVDDCR_SOC_P1")
	)
	(segment
		(start 121.177812 -252.04039)
		(end 121.644664 -251.774452)
		(width 0.350012)
		(layer "F.Cu")
		(net "PVDDCR_SOC_P1")
	)
	(segment
		(start 130.107944 -239.8903)
		(end 130.574796 -239.624362)
		(width 0.350012)
		(layer "F.Cu")
		(net "PVDDCR_SOC_P1")
	)
	(segment
		(start 130.107944 -235.030264)
		(end 130.574796 -234.764326)
		(width 0.350012)
		(layer "F.Cu")
		(net "PVDDCR_SOC_P1")
	)
	(segment
		(start 103.317802 -252.04039)
		(end 102.85095 -251.774452)
		(width 0.350012)
		(layer "F.Cu")
		(net "PVDDCR_SOC_P1")
	)
	(segment
		(start 143.267938 -230.170228)
		(end 143.73479 -229.90429)
		(width 0.350012)
		(layer "F.Cu")
		(net "PVDDCR_SOC_P1")
	)
	(segment
		(start 102.847902 -254.470408)
		(end 102.38105 -254.20447)
		(width 0.350012)
		(layer "F.Cu")
		(net "PVDDCR_SOC_P1")
	)
	(segment
		(start 142.797784 -232.600246)
		(end 143.264636 -232.334308)
		(width 0.350012)
		(layer "F.Cu")
		(net "PVDDCR_SOC_P1")
	)
	(segment
		(start 143.267938 -254.470408)
		(end 143.73479 -254.20447)
		(width 0.350012)
		(layer "F.Cu")
		(net "PVDDCR_SOC_P1")
	)
	(segment
		(start 123.52782 -254.470408)
		(end 123.994672 -254.20447)
		(width 0.350012)
		(layer "F.Cu")
		(net "PVDDCR_SOC_P1")
	)
	(segment
		(start 136.217914 -237.460282)
		(end 136.684766 -237.194344)
		(width 0.350012)
		(layer "F.Cu")
		(net "PVDDCR_SOC_P1")
	)
	(segment
		(start 123.05792 -256.900426)
		(end 123.524772 -256.634488)
		(width 0.350012)
		(layer "F.Cu")
		(net "PVDDCR_SOC_P1")
	)
	(segment
		(start 125.407928 -251.230384)
		(end 125.87478 -250.964446)
		(width 0.350012)
		(layer "F.Cu")
		(net "PVDDCR_SOC_P1")
	)
	(segment
		(start 121.647966 -256.09042)
		(end 122.114818 -255.824482)
		(width 0.350012)
		(layer "F.Cu")
		(net "PVDDCR_SOC_P1")
	)
	(segment
		(start 102.847902 -252.850396)
		(end 102.38105 -252.584458)
		(width 0.350012)
		(layer "F.Cu")
		(net "PVDDCR_SOC_P1")
	)
	(segment
		(start 126.817882 -243.94033)
		(end 127.284734 -243.674392)
		(width 0.350012)
		(layer "F.Cu")
		(net "PVDDCR_SOC_P1")
	)
	(segment
		(start 136.687814 -225.310446)
		(end 137.154666 -225.044508)
		(width 0.350012)
		(layer "F.Cu")
		(net "PVDDCR_SOC_P1")
	)
	(segment
		(start 129.63779 -237.460282)
		(end 130.104642 -237.194344)
		(width 0.350012)
		(layer "F.Cu")
		(net "PVDDCR_SOC_P1")
	)
	(segment
		(start 136.687814 -249.610372)
		(end 137.154666 -249.344434)
		(width 0.350012)
		(layer "F.Cu")
		(net "PVDDCR_SOC_P1")
	)
	(segment
		(start 129.63779 -247.180354)
		(end 130.104642 -246.914416)
		(width 0.350012)
		(layer "F.Cu")
		(net "PVDDCR_SOC_P1")
	)
	(segment
		(start 122.41784 -260.860286)
		(end 122.884692 -261.126224)
		(width 0.350012)
		(layer "F.Cu")
		(net "PVDDCR_SOC_P1")
	)
	(segment
		(start 142.797784 -227.740464)
		(end 143.264636 -227.474526)
		(width 0.350012)
		(layer "F.Cu")
		(net "PVDDCR_SOC_P1")
	)
	(segment
		(start 121.647966 -254.470408)
		(end 122.114818 -254.20447)
		(width 0.350012)
		(layer "F.Cu")
		(net "PVDDCR_SOC_P1")
	)
	(segment
		(start 121.007886 -261.670292)
		(end 121.474738 -261.93623)
		(width 0.350012)
		(layer "F.Cu")
		(net "PVDDCR_SOC_P1")
	)
	(segment
		(start 123.52782 -256.09042)
		(end 123.994672 -255.824482)
		(width 0.350012)
		(layer "F.Cu")
		(net "PVDDCR_SOC_P1")
	)
	(segment
		(start 126.817882 -255.280414)
		(end 127.284734 -255.014476)
		(width 0.350012)
		(layer "F.Cu")
		(net "PVDDCR_SOC_P1")
	)
	(segment
		(start 136.687814 -244.750336)
		(end 137.154666 -244.484398)
		(width 0.350012)
		(layer "F.Cu")
		(net "PVDDCR_SOC_P1")
	)
	(segment
		(start 102.677976 -262.480298)
		(end 102.211124 -262.746236)
		(width 0.350012)
		(layer "F.Cu")
		(net "PVDDCR_SOC_P1")
	)
	(segment
		(start 129.63779 -252.04039)
		(end 130.104642 -251.774452)
		(width 0.350012)
		(layer "F.Cu")
		(net "PVDDCR_SOC_P1")
	)
	(segment
		(start 124.297948 -260.860286)
		(end 124.7648 -261.126224)
		(width 0.350012)
		(layer "F.Cu")
		(net "PVDDCR_SOC_P1")
	)
	(segment
		(start 121.647966 -252.850396)
		(end 122.114818 -252.584458)
		(width 0.350012)
		(layer "F.Cu")
		(net "PVDDCR_SOC_P1")
	)
	(segment
		(start 126.817882 -253.660402)
		(end 127.284734 -253.394464)
		(width 0.350012)
		(layer "F.Cu")
		(net "PVDDCR_SOC_P1")
	)
	(segment
		(start 136.217914 -252.04039)
		(end 136.684766 -251.774452)
		(width 0.350012)
		(layer "F.Cu")
		(net "PVDDCR_SOC_P1")
	)
	(segment
		(start 114.127788 -251.230384)
		(end 114.59464 -250.964446)
		(width 0.350012)
		(layer "F.Cu")
		(net "PVDDCR_SOC_P1")
	)
	(segment
		(start 123.52782 -252.850396)
		(end 123.994672 -252.584458)
		(width 0.350012)
		(layer "F.Cu")
		(net "PVDDCR_SOC_P1")
	)
	(segment
		(start 136.217914 -247.180354)
		(end 136.684766 -246.914416)
		(width 0.350012)
		(layer "F.Cu")
		(net "PVDDCR_SOC_P1")
	)
	(segment
		(start 143.267938 -239.8903)
		(end 143.73479 -239.624362)
		(width 0.350012)
		(layer "F.Cu")
		(net "PVDDCR_SOC_P1")
	)
	(segment
		(start 130.107944 -254.470408)
		(end 130.574796 -254.20447)
		(width 0.350012)
		(layer "F.Cu")
		(net "PVDDCR_SOC_P1")
	)
	(segment
		(start 113.657888 -252.04039)
		(end 114.12474 -251.774452)
		(width 0.350012)
		(layer "F.Cu")
		(net "PVDDCR_SOC_P1")
	)
	(segment
		(start 102.847902 -256.09042)
		(end 102.38105 -255.824482)
		(width 0.350012)
		(layer "F.Cu")
		(net "PVDDCR_SOC_P1")
	)
	(segment
		(start 124.297948 -262.480298)
		(end 124.7648 -262.746236)
		(width 0.350012)
		(layer "F.Cu")
		(net "PVDDCR_SOC_P1")
	)
	(segment
		(start 105.19791 -252.04039)
		(end 104.731058 -251.774452)
		(width 0.350012)
		(layer "F.Cu")
		(net "PVDDCR_SOC_P1")
	)
	(segment
		(start 110.83798 -252.04039)
		(end 110.371128 -251.774452)
		(width 0.350012)
		(layer "F.Cu")
		(net "PVDDCR_SOC_P1")
	)
	(segment
		(start 102.378002 -256.900426)
		(end 101.91115 -256.634488)
		(width 0.350012)
		(layer "F.Cu")
		(net "PVDDCR_SOC_P1")
	)
	(segment
		(start 143.098012 -265.720322)
		(end 143.56461 -265.98626)
		(width 0.350012)
		(layer "F.Cu")
		(net "PVDDCR_SOC_P1")
	)
	(segment
		(start 129.63779 -242.320318)
		(end 130.104642 -242.05438)
		(width 0.350012)
		(layer "F.Cu")
		(net "PVDDCR_SOC_P1")
	)
	(segment
		(start 124.937774 -256.900426)
		(end 125.404626 -256.634488)
		(width 0.350012)
		(layer "F.Cu")
		(net "PVDDCR_SOC_P1")
	)
	(segment
		(start 129.63779 -227.740464)
		(end 130.104642 -227.474526)
		(width 0.350012)
		(layer "F.Cu")
		(net "PVDDCR_SOC_P1")
	)
	(segment
		(start 121.177812 -255.280414)
		(end 121.644664 -255.014476)
		(width 0.350012)
		(layer "F.Cu")
		(net "PVDDCR_SOC_P1")
	)
	(segment
		(start 143.267938 -244.750336)
		(end 143.73479 -244.484398)
		(width 0.350012)
		(layer "F.Cu")
		(net "PVDDCR_SOC_P1")
	)
	(segment
		(start 121.177812 -256.900426)
		(end 121.644664 -256.634488)
		(width 0.350012)
		(layer "F.Cu")
		(net "PVDDCR_SOC_P1")
	)
	(segment
		(start 143.267938 -223.690434)
		(end 143.73479 -223.424496)
		(width 0.350012)
		(layer "F.Cu")
		(net "PVDDCR_SOC_P1")
	)
	(segment
		(start 136.217914 -242.320318)
		(end 136.684766 -242.05438)
		(width 0.350012)
		(layer "F.Cu")
		(net "PVDDCR_SOC_P1")
	)
	(segment
		(start 124.937774 -255.280414)
		(end 125.404626 -255.014476)
		(width 0.350012)
		(layer "F.Cu")
		(net "PVDDCR_SOC_P1")
	)
	(segment
		(start 110.367826 -251.230384)
		(end 109.900974 -250.964446)
		(width 0.350012)
		(layer "F.Cu")
		(net "PVDDCR_SOC_P1")
	)
	(segment
		(start 142.797784 -247.180354)
		(end 143.264636 -246.914416)
		(width 0.350012)
		(layer "F.Cu")
		(net "PVDDCR_SOC_P1")
	)
	(segment
		(start 103.147876 -263.290304)
		(end 102.681024 -263.556242)
		(width 0.350012)
		(layer "F.Cu")
		(net "PVDDCR_SOC_P1")
	)
	(segment
		(start 126.177802 -262.480298)
		(end 126.644654 -262.746236)
		(width 0.350012)
		(layer "F.Cu")
		(net "PVDDCR_SOC_P1")
	)
	(segment
		(start 126.817882 -252.04039)
		(end 127.284734 -251.774452)
		(width 0.350012)
		(layer "F.Cu")
		(net "PVDDCR_SOC_P1")
	)
	(segment
		(start 142.797784 -237.460282)
		(end 143.264636 -237.194344)
		(width 0.350012)
		(layer "F.Cu")
		(net "PVDDCR_SOC_P1")
	)
	(segment
		(start 122.887994 -261.670292)
		(end 123.354846 -261.93623)
		(width 0.350012)
		(layer "F.Cu")
		(net "PVDDCR_SOC_P1")
	)
	(segment
		(start 123.05792 -252.04039)
		(end 123.524772 -251.774452)
		(width 0.350012)
		(layer "F.Cu")
		(net "PVDDCR_SOC_P1")
	)
	(segment
		(start 117.41785 -252.04039)
		(end 117.884702 -251.774452)
		(width 0.350012)
		(layer "F.Cu")
		(net "PVDDCR_SOC_P1")
	)
	(segment
		(start 126.817882 -247.180354)
		(end 127.284734 -246.914416)
		(width 0.350012)
		(layer "F.Cu")
		(net "PVDDCR_SOC_P1")
	)
	(segment
		(start 136.217914 -232.600246)
		(end 136.684766 -232.334308)
		(width 0.350012)
		(layer "F.Cu")
		(net "PVDDCR_SOC_P1")
	)
	(segment
		(start 126.817882 -240.700306)
		(end 127.284734 -240.434368)
		(width 0.350012)
		(layer "F.Cu")
		(net "PVDDCR_SOC_P1")
	)
	(segment
		(start 126.347982 -238.270288)
		(end 126.814834 -238.00435)
		(width 0.350012)
		(layer "F.Cu")
		(net "PVDDCR_SOC_P1")
	)
	(segment
		(start 136.217914 -256.900426)
		(end 136.684766 -256.634488)
		(width 0.350012)
		(layer "F.Cu")
		(net "PVDDCR_SOC_P1")
	)
	(segment
		(start 119.297958 -252.04039)
		(end 119.76481 -251.774452)
		(width 0.350012)
		(layer "F.Cu")
		(net "PVDDCR_SOC_P1")
	)
	(segment
		(start 107.078018 -252.04039)
		(end 106.611166 -251.774452)
		(width 0.350012)
		(layer "F.Cu")
		(net "PVDDCR_SOC_P1")
	)
	(segment
		(start 142.797784 -256.900426)
		(end 143.264636 -256.634488)
		(width 0.350012)
		(layer "F.Cu")
		(net "PVDDCR_SOC_P1")
	)
	(segment
		(start 136.687814 -239.8903)
		(end 137.154666 -239.624362)
		(width 0.350012)
		(layer "F.Cu")
		(net "PVDDCR_SOC_P1")
	)
	(segment
		(start 124.767848 -261.670292)
		(end 125.2347 -261.93623)
		(width 0.350012)
		(layer "F.Cu")
		(net "PVDDCR_SOC_P1")
	)
	(segment
		(start 125.407928 -256.09042)
		(end 125.87478 -255.824482)
		(width 0.350012)
		(layer "F.Cu")
		(net "PVDDCR_SOC_P1")
	)
	(segment
		(start 136.217914 -227.740464)
		(end 136.684766 -227.474526)
		(width 0.350012)
		(layer "F.Cu")
		(net "PVDDCR_SOC_P1")
	)
	(segment
		(start 143.267938 -235.030264)
		(end 143.73479 -234.764326)
		(width 0.350012)
		(layer "F.Cu")
		(net "PVDDCR_SOC_P1")
	)
	(segment
		(start 129.63779 -232.600246)
		(end 130.104642 -232.334308)
		(width 0.350012)
		(layer "F.Cu")
		(net "PVDDCR_SOC_P1")
	)
	(via
		(at 118.106444 -183.903112)
		(size 0.508)
		(drill 0.254)
		(layers "F.Cu" "B.Cu")
		(net "PVDDCR_SOC_P1")
	)
	(via
		(at 127.284734 -235.574332)
		(size 0.4064)
		(drill 0.2032)
		(layers "F.Cu" "B.Cu")
		(net "PVDDCR_SOC_P1")
	)
	(via
		(at 114.128042 -253.392432)
		(size 0.4064)
		(drill 0.2032)
		(layers "F.Cu" "B.Cu")
		(net "PVDDCR_SOC_P1")
	)
	(via
		(at 122.114818 -254.20447)
		(size 0.4064)
		(drill 0.2032)
		(layers "F.Cu" "B.Cu")
		(net "PVDDCR_SOC_P1")
	)
	(via
		(at 118.35511 -258.38023)
		(size 0.4826)
		(drill 0.254)
		(layers "F.Cu" "B.Cu")
		(net "PVDDCR_SOC_P1")
	)
	(via
		(at 130.104642 -237.194344)
		(size 0.4064)
		(drill 0.2032)
		(layers "F.Cu" "B.Cu")
		(net "PVDDCR_SOC_P1")
	)
	(via
		(at 108.597954 -255.4732)
		(size 0.4826)
		(drill 0.254)
		(layers "F.Cu" "B.Cu")
		(net "PVDDCR_SOC_P1")
	)
	(via
		(at 135.245348 -170.42384)
		(size 0.508)
		(drill 0.254)
		(layers "F.Cu" "B.Cu")
		(net "PVDDCR_SOC_P1")
	)
	(via
		(at 114.728244 -188.38164)
		(size 0.508)
		(drill 0.254)
		(layers "F.Cu" "B.Cu")
		(net "PVDDCR_SOC_P1")
	)
	(via
		(at 126.963932 -177.172112)
		(size 0.508)
		(drill 0.254)
		(layers "F.Cu" "B.Cu")
		(net "PVDDCR_SOC_P1")
	)
	(via
		(at 122.950732 -181.65064)
		(size 0.508)
		(drill 0.254)
		(layers "F.Cu" "B.Cu")
		(net "PVDDCR_SOC_P1")
	)
	(via
		(at 114.728244 -187.11164)
		(size 0.508)
		(drill 0.254)
		(layers "F.Cu" "B.Cu")
		(net "PVDDCR_SOC_P1")
	)
	(via
		(at 112.667796 -257.74523)
		(size 0.4826)
		(drill 0.254)
		(layers "F.Cu" "B.Cu")
		(net "PVDDCR_SOC_P1")
	)
	(via
		(at 103.147876 -262.748268)
		(size 0.4064)
		(drill 0.2032)
		(layers "F.Cu" "B.Cu")
		(net "PVDDCR_SOC_P1")
	)
	(via
		(at 131.231132 -172.32884)
		(size 0.508)
		(drill 0.254)
		(layers "F.Cu" "B.Cu")
		(net "PVDDCR_SOC_P1")
	)
	(via
		(at 110.497874 -255.4732)
		(size 0.4826)
		(drill 0.254)
		(layers "F.Cu" "B.Cu")
		(net "PVDDCR_SOC_P1")
	)
	(via
		(at 122.950732 -181.01564)
		(size 0.508)
		(drill 0.254)
		(layers "F.Cu" "B.Cu")
		(net "PVDDCR_SOC_P1")
	)
	(via
		(at 113.348008 -255.4732)
		(size 0.4826)
		(drill 0.254)
		(layers "F.Cu" "B.Cu")
		(net "PVDDCR_SOC_P1")
	)
	(via
		(at 130.597148 -169.780712)
		(size 0.508)
		(drill 0.254)
		(layers "F.Cu" "B.Cu")
		(net "PVDDCR_SOC_P1")
	)
	(via
		(at 121.680732 -179.74564)
		(size 0.508)
		(drill 0.254)
		(layers "F.Cu" "B.Cu")
		(net "PVDDCR_SOC_P1")
	)
	(via
		(at 127.284734 -250.15444)
		(size 0.4064)
		(drill 0.2032)
		(layers "F.Cu" "B.Cu")
		(net "PVDDCR_SOC_P1")
	)
	(via
		(at 125.404626 -255.014476)
		(size 0.4064)
		(drill 0.2032)
		(layers "F.Cu" "B.Cu")
		(net "PVDDCR_SOC_P1")
	)
	(via
		(at 125.954536 -259.73024)
		(size 0.4826)
		(drill 0.254)
		(layers "F.Cu" "B.Cu")
		(net "PVDDCR_SOC_P1")
	)
	(via
		(at 137.154666 -229.90429)
		(size 0.4064)
		(drill 0.2032)
		(layers "F.Cu" "B.Cu")
		(net "PVDDCR_SOC_P1")
	)
	(via
		(at 127.284734 -243.674392)
		(size 0.4064)
		(drill 0.2032)
		(layers "F.Cu" "B.Cu")
		(net "PVDDCR_SOC_P1")
	)
	(via
		(at 127.284734 -232.334308)
		(size 0.4064)
		(drill 0.2032)
		(layers "F.Cu" "B.Cu")
		(net "PVDDCR_SOC_P1")
	)
	(via
		(at 125.694948 -178.442112)
		(size 0.508)
		(drill 0.254)
		(layers "F.Cu" "B.Cu")
		(net "PVDDCR_SOC_P1")
	)
	(via
		(at 131.231132 -171.69384)
		(size 0.508)
		(drill 0.254)
		(layers "F.Cu" "B.Cu")
		(net "PVDDCR_SOC_P1")
	)
	(via
		(at 118.35511 -259.330444)
		(size 0.4826)
		(drill 0.254)
		(layers "F.Cu" "B.Cu")
		(net "PVDDCR_SOC_P1")
	)
	(via
		(at 131.231132 -172.96384)
		(size 0.508)
		(drill 0.254)
		(layers "F.Cu" "B.Cu")
		(net "PVDDCR_SOC_P1")
	)
	(via
		(at 133.975348 -171.050712)
		(size 0.508)
		(drill 0.254)
		(layers "F.Cu" "B.Cu")
		(net "PVDDCR_SOC_P1")
	)
	(via
		(at 121.680732 -183.04764)
		(size 0.6604)
		(drill 0.3302)
		(layers "F.Cu" "B.Cu")
		(net "PVDDCR_SOC_P1")
	)
	(via
		(at 110.371128 -251.774452)
		(size 0.4064)
		(drill 0.2032)
		(layers "F.Cu" "B.Cu")
		(net "PVDDCR_SOC_P1")
	)
	(via
		(at 133.974332 -173.09084)
		(size 0.6604)
		(drill 0.3302)
		(layers "F.Cu" "B.Cu")
		(net "PVDDCR_SOC_P1")
	)
	(via
		(at 118.989348 -168.14165)
		(size 0.508)
		(drill 0.254)
		(layers "F.Cu" "B.Cu")
		(net "PVDDCR_SOC_P1")
	)
	(via
		(at 114.093244 -187.74664)
		(size 0.508)
		(drill 0.254)
		(layers "F.Cu" "B.Cu")
		(net "PVDDCR_SOC_P1")
	)
	(via
		(at 108.49102 -251.774452)
		(size 0.4064)
		(drill 0.2032)
		(layers "F.Cu" "B.Cu")
		(net "PVDDCR_SOC_P1")
	)
	(via
		(at 131.232148 -169.145712)
		(size 0.508)
		(drill 0.254)
		(layers "F.Cu" "B.Cu")
		(net "PVDDCR_SOC_P1")
	)
	(via
		(at 137.154666 -249.344434)
		(size 0.4064)
		(drill 0.2032)
		(layers "F.Cu" "B.Cu")
		(net "PVDDCR_SOC_P1")
	)
	(via
		(at 135.245348 -168.51884)
		(size 0.508)
		(drill 0.254)
		(layers "F.Cu" "B.Cu")
		(net "PVDDCR_SOC_P1")
	)
	(via
		(at 137.154666 -244.484398)
		(size 0.4064)
		(drill 0.2032)
		(layers "F.Cu" "B.Cu")
		(net "PVDDCR_SOC_P1")
	)
	(via
		(at 121.680732 -180.38064)
		(size 0.508)
		(drill 0.254)
		(layers "F.Cu" "B.Cu")
		(net "PVDDCR_SOC_P1")
	)
	(via
		(at 127.284734 -229.094538)
		(size 0.4064)
		(drill 0.2032)
		(layers "F.Cu" "B.Cu")
		(net "PVDDCR_SOC_P1")
	)
	(via
		(at 103.317802 -255.82245)
		(size 0.4064)
		(drill 0.2032)
		(layers "F.Cu" "B.Cu")
		(net "PVDDCR_SOC_P1")
	)
	(via
		(at 110.417864 -257.74523)
		(size 0.4826)
		(drill 0.254)
		(layers "F.Cu" "B.Cu")
		(net "PVDDCR_SOC_P1")
	)
	(via
		(at 143.73479 -229.90429)
		(size 0.4064)
		(drill 0.2032)
		(layers "F.Cu" "B.Cu")
		(net "PVDDCR_SOC_P1")
	)
	(via
		(at 122.884692 -261.126224)
		(size 0.4064)
		(drill 0.2032)
		(layers "F.Cu" "B.Cu")
		(net "PVDDCR_SOC_P1")
	)
	(via
		(at 114.59464 -250.964446)
		(size 0.4064)
		(drill 0.2032)
		(layers "F.Cu" "B.Cu")
		(net "PVDDCR_SOC_P1")
	)
	(via
		(at 131.232148 -169.780712)
		(size 0.508)
		(drill 0.254)
		(layers "F.Cu" "B.Cu")
		(net "PVDDCR_SOC_P1")
	)
	(via
		(at 130.104642 -227.474526)
		(size 0.4064)
		(drill 0.2032)
		(layers "F.Cu" "B.Cu")
		(net "PVDDCR_SOC_P1")
	)
	(via
		(at 115.26774 -257.74523)
		(size 0.4826)
		(drill 0.254)
		(layers "F.Cu" "B.Cu")
		(net "PVDDCR_SOC_P1")
	)
	(via
		(at 126.328932 -177.172112)
		(size 0.508)
		(drill 0.254)
		(layers "F.Cu" "B.Cu")
		(net "PVDDCR_SOC_P1")
	)
	(via
		(at 135.880348 -169.15384)
		(size 0.508)
		(drill 0.254)
		(layers "F.Cu" "B.Cu")
		(net "PVDDCR_SOC_P1")
	)
	(via
		(at 143.264636 -256.634488)
		(size 0.4064)
		(drill 0.2032)
		(layers "F.Cu" "B.Cu")
		(net "PVDDCR_SOC_P1")
	)
	(via
		(at 123.994672 -252.584458)
		(size 0.4064)
		(drill 0.2032)
		(layers "F.Cu" "B.Cu")
		(net "PVDDCR_SOC_P1")
	)
	(via
		(at 122.123962 -258.830318)
		(size 0.4826)
		(drill 0.254)
		(layers "F.Cu" "B.Cu")
		(net "PVDDCR_SOC_P1")
	)
	(via
		(at 131.231132 -173.59884)
		(size 0.508)
		(drill 0.254)
		(layers "F.Cu" "B.Cu")
		(net "PVDDCR_SOC_P1")
	)
	(via
		(at 126.814834 -238.00435)
		(size 0.4064)
		(drill 0.2032)
		(layers "F.Cu" "B.Cu")
		(net "PVDDCR_SOC_P1")
	)
	(via
		(at 119.767858 -253.392432)
		(size 0.4064)
		(drill 0.2032)
		(layers "F.Cu" "B.Cu")
		(net "PVDDCR_SOC_P1")
	)
	(via
		(at 112.667796 -258.795266)
		(size 0.4826)
		(drill 0.254)
		(layers "F.Cu" "B.Cu")
		(net "PVDDCR_SOC_P1")
	)
	(via
		(at 122.114818 -252.584458)
		(size 0.4064)
		(drill 0.2032)
		(layers "F.Cu" "B.Cu")
		(net "PVDDCR_SOC_P1")
	)
	(via
		(at 135.880348 -170.42384)
		(size 0.508)
		(drill 0.254)
		(layers "F.Cu" "B.Cu")
		(net "PVDDCR_SOC_P1")
	)
	(via
		(at 137.154666 -234.764326)
		(size 0.4064)
		(drill 0.2032)
		(layers "F.Cu" "B.Cu")
		(net "PVDDCR_SOC_P1")
	)
	(via
		(at 121.680732 -178.47564)
		(size 0.508)
		(drill 0.254)
		(layers "F.Cu" "B.Cu")
		(net "PVDDCR_SOC_P1")
	)
	(via
		(at 114.09426 -186.443112)
		(size 0.508)
		(drill 0.254)
		(layers "F.Cu" "B.Cu")
		(net "PVDDCR_SOC_P1")
	)
	(via
		(at 111.343186 -254.448564)
		(size 0.4826)
		(drill 0.254)
		(layers "F.Cu" "B.Cu")
		(net "PVDDCR_SOC_P1")
	)
	(via
		(at 125.2347 -261.93623)
		(size 0.4064)
		(drill 0.2032)
		(layers "F.Cu" "B.Cu")
		(net "PVDDCR_SOC_P1")
	)
	(via
		(at 118.35511 -260.280404)
		(size 0.4826)
		(drill 0.254)
		(layers "F.Cu" "B.Cu")
		(net "PVDDCR_SOC_P1")
	)
	(via
		(at 123.524772 -251.774452)
		(size 0.4064)
		(drill 0.2032)
		(layers "F.Cu" "B.Cu")
		(net "PVDDCR_SOC_P1")
	)
	(via
		(at 114.297968 -255.4732)
		(size 0.4826)
		(drill 0.254)
		(layers "F.Cu" "B.Cu")
		(net "PVDDCR_SOC_P1")
	)
	(via
		(at 125.694948 -179.839112)
		(size 0.6604)
		(drill 0.3302)
		(layers "F.Cu" "B.Cu")
		(net "PVDDCR_SOC_P1")
	)
	(via
		(at 130.574796 -249.344434)
		(size 0.4064)
		(drill 0.2032)
		(layers "F.Cu" "B.Cu")
		(net "PVDDCR_SOC_P1")
	)
	(via
		(at 126.644654 -261.126224)
		(size 0.4064)
		(drill 0.2032)
		(layers "F.Cu" "B.Cu")
		(net "PVDDCR_SOC_P1")
	)
	(via
		(at 136.684766 -227.474526)
		(size 0.4064)
		(drill 0.2032)
		(layers "F.Cu" "B.Cu")
		(net "PVDDCR_SOC_P1")
	)
	(via
		(at 136.684766 -256.634488)
		(size 0.4064)
		(drill 0.2032)
		(layers "F.Cu" "B.Cu")
		(net "PVDDCR_SOC_P1")
	)
	(via
		(at 114.09426 -185.808112)
		(size 0.508)
		(drill 0.254)
		(layers "F.Cu" "B.Cu")
		(net "PVDDCR_SOC_P1")
	)
	(via
		(at 135.245348 -171.69384)
		(size 0.508)
		(drill 0.254)
		(layers "F.Cu" "B.Cu")
		(net "PVDDCR_SOC_P1")
	)
	(via
		(at 108.487972 -253.392432)
		(size 0.4064)
		(drill 0.2032)
		(layers "F.Cu" "B.Cu")
		(net "PVDDCR_SOC_P1")
	)
	(via
		(at 114.12474 -251.774452)
		(size 0.4064)
		(drill 0.2032)
		(layers "F.Cu" "B.Cu")
		(net "PVDDCR_SOC_P1")
	)
	(via
		(at 135.880348 -171.05884)
		(size 0.508)
		(drill 0.254)
		(layers "F.Cu" "B.Cu")
		(net "PVDDCR_SOC_P1")
	)
	(via
		(at 130.597148 -170.415712)
		(size 0.508)
		(drill 0.254)
		(layers "F.Cu" "B.Cu")
		(net "PVDDCR_SOC_P1")
	)
	(via
		(at 106.611166 -251.774452)
		(size 0.4064)
		(drill 0.2032)
		(layers "F.Cu" "B.Cu")
		(net "PVDDCR_SOC_P1")
	)
	(via
		(at 118.10746 -184.538112)
		(size 0.508)
		(drill 0.254)
		(layers "F.Cu" "B.Cu")
		(net "PVDDCR_SOC_P1")
	)
	(via
		(at 125.694948 -179.077112)
		(size 0.508)
		(drill 0.254)
		(layers "F.Cu" "B.Cu")
		(net "PVDDCR_SOC_P1")
	)
	(via
		(at 130.104642 -256.634488)
		(size 0.4064)
		(drill 0.2032)
		(layers "F.Cu" "B.Cu")
		(net "PVDDCR_SOC_P1")
	)
	(via
		(at 114.72926 -185.173112)
		(size 0.508)
		(drill 0.254)
		(layers "F.Cu" "B.Cu")
		(net "PVDDCR_SOC_P1")
	)
	(via
		(at 127.284734 -255.014476)
		(size 0.4064)
		(drill 0.2032)
		(layers "F.Cu" "B.Cu")
		(net "PVDDCR_SOC_P1")
	)
	(via
		(at 136.684766 -232.334308)
		(size 0.4064)
		(drill 0.2032)
		(layers "F.Cu" "B.Cu")
		(net "PVDDCR_SOC_P1")
	)
	(via
		(at 112.397794 -255.4732)
		(size 0.4826)
		(drill 0.254)
		(layers "F.Cu" "B.Cu")
		(net "PVDDCR_SOC_P1")
	)
	(via
		(at 121.474738 -261.93623)
		(size 0.4064)
		(drill 0.2032)
		(layers "F.Cu" "B.Cu")
		(net "PVDDCR_SOC_P1")
	)
	(via
		(at 114.72926 -186.443112)
		(size 0.508)
		(drill 0.254)
		(layers "F.Cu" "B.Cu")
		(net "PVDDCR_SOC_P1")
	)
	(via
		(at 116.007896 -253.392432)
		(size 0.4064)
		(drill 0.2032)
		(layers "F.Cu" "B.Cu")
		(net "PVDDCR_SOC_P1")
	)
	(via
		(at 143.264636 -227.474526)
		(size 0.4064)
		(drill 0.2032)
		(layers "F.Cu" "B.Cu")
		(net "PVDDCR_SOC_P1")
	)
	(via
		(at 102.211124 -261.126224)
		(size 0.4064)
		(drill 0.2032)
		(layers "F.Cu" "B.Cu")
		(net "PVDDCR_SOC_P1")
	)
	(via
		(at 121.644664 -253.394464)
		(size 0.4064)
		(drill 0.2032)
		(layers "F.Cu" "B.Cu")
		(net "PVDDCR_SOC_P1")
	)
	(via
		(at 122.316748 -178.442112)
		(size 0.508)
		(drill 0.254)
		(layers "F.Cu" "B.Cu")
		(net "PVDDCR_SOC_P1")
	)
	(via
		(at 117.471444 -183.903112)
		(size 0.508)
		(drill 0.254)
		(layers "F.Cu" "B.Cu")
		(net "PVDDCR_SOC_P1")
	)
	(via
		(at 122.315732 -177.172112)
		(size 0.508)
		(drill 0.254)
		(layers "F.Cu" "B.Cu")
		(net "PVDDCR_SOC_P1")
	)
	(via
		(at 135.727948 -152.74925)
		(size 0.508)
		(drill 0.254)
		(layers "F.Cu" "B.Cu")
		(net "PVDDCR_SOC_P1")
	)
	(via
		(at 102.85095 -251.774452)
		(size 0.4064)
		(drill 0.2032)
		(layers "F.Cu" "B.Cu")
		(net "PVDDCR_SOC_P1")
	)
	(via
		(at 135.880348 -171.69384)
		(size 0.508)
		(drill 0.254)
		(layers "F.Cu" "B.Cu")
		(net "PVDDCR_SOC_P1")
	)
	(via
		(at 123.354846 -261.93623)
		(size 0.4064)
		(drill 0.2032)
		(layers "F.Cu" "B.Cu")
		(net "PVDDCR_SOC_P1")
	)
	(via
		(at 103.147876 -261.128256)
		(size 0.4064)
		(drill 0.2032)
		(layers "F.Cu" "B.Cu")
		(net "PVDDCR_SOC_P1")
	)
	(via
		(at 113.458244 -188.38164)
		(size 0.508)
		(drill 0.254)
		(layers "F.Cu" "B.Cu")
		(net "PVDDCR_SOC_P1")
	)
	(via
		(at 113.458244 -183.903112)
		(size 0.508)
		(drill 0.254)
		(layers "F.Cu" "B.Cu")
		(net "PVDDCR_SOC_P1")
	)
	(via
		(at 100.971096 -253.394464)
		(size 0.4064)
		(drill 0.2032)
		(layers "F.Cu" "B.Cu")
		(net "PVDDCR_SOC_P1")
	)
	(via
		(at 121.680732 -179.11064)
		(size 0.508)
		(drill 0.254)
		(layers "F.Cu" "B.Cu")
		(net "PVDDCR_SOC_P1")
	)
	(via
		(at 143.73479 -225.044508)
		(size 0.4064)
		(drill 0.2032)
		(layers "F.Cu" "B.Cu")
		(net "PVDDCR_SOC_P1")
	)
	(via
		(at 102.38105 -252.584458)
		(size 0.4064)
		(drill 0.2032)
		(layers "F.Cu" "B.Cu")
		(net "PVDDCR_SOC_P1")
	)
	(via
		(at 114.09426 -184.538112)
		(size 0.508)
		(drill 0.254)
		(layers "F.Cu" "B.Cu")
		(net "PVDDCR_SOC_P1")
	)
	(via
		(at 104.72801 -253.392432)
		(size 0.4064)
		(drill 0.2032)
		(layers "F.Cu" "B.Cu")
		(net "PVDDCR_SOC_P1")
	)
	(via
		(at 127.284734 -251.774452)
		(size 0.4064)
		(drill 0.2032)
		(layers "F.Cu" "B.Cu")
		(net "PVDDCR_SOC_P1")
	)
	(via
		(at 137.154666 -254.20447)
		(size 0.4064)
		(drill 0.2032)
		(layers "F.Cu" "B.Cu")
		(net "PVDDCR_SOC_P1")
	)
	(via
		(at 113.458244 -187.11164)
		(size 0.508)
		(drill 0.254)
		(layers "F.Cu" "B.Cu")
		(net "PVDDCR_SOC_P1")
	)
	(via
		(at 114.093244 -183.903112)
		(size 0.508)
		(drill 0.254)
		(layers "F.Cu" "B.Cu")
		(net "PVDDCR_SOC_P1")
	)
	(via
		(at 133.974332 -171.69384)
		(size 0.508)
		(drill 0.254)
		(layers "F.Cu" "B.Cu")
		(net "PVDDCR_SOC_P1")
	)
	(via
		(at 121.680732 -181.65064)
		(size 0.508)
		(drill 0.254)
		(layers "F.Cu" "B.Cu")
		(net "PVDDCR_SOC_P1")
	)
	(via
		(at 125.693932 -177.172112)
		(size 0.508)
		(drill 0.254)
		(layers "F.Cu" "B.Cu")
		(net "PVDDCR_SOC_P1")
	)
	(via
		(at 143.73479 -249.344434)
		(size 0.4064)
		(drill 0.2032)
		(layers "F.Cu" "B.Cu")
		(net "PVDDCR_SOC_P1")
	)
	(via
		(at 111.447834 -255.4732)
		(size 0.4826)
		(drill 0.254)
		(layers "F.Cu" "B.Cu")
		(net "PVDDCR_SOC_P1")
	)
	(via
		(at 121.680732 -177.84064)
		(size 0.508)
		(drill 0.254)
		(layers "F.Cu" "B.Cu")
		(net "PVDDCR_SOC_P1")
	)
	(via
		(at 104.731058 -251.774452)
		(size 0.4064)
		(drill 0.2032)
		(layers "F.Cu" "B.Cu")
		(net "PVDDCR_SOC_P1")
	)
	(via
		(at 121.680732 -182.28564)
		(size 0.508)
		(drill 0.254)
		(layers "F.Cu" "B.Cu")
		(net "PVDDCR_SOC_P1")
	)
	(via
		(at 124.049536 -257.930396)
		(size 0.4826)
		(drill 0.254)
		(layers "F.Cu" "B.Cu")
		(net "PVDDCR_SOC_P1")
	)
	(via
		(at 113.458244 -185.20664)
		(size 0.508)
		(drill 0.254)
		(layers "F.Cu" "B.Cu")
		(net "PVDDCR_SOC_P1")
	)
	(via
		(at 137.154666 -225.044508)
		(size 0.4064)
		(drill 0.2032)
		(layers "F.Cu" "B.Cu")
		(net "PVDDCR_SOC_P1")
	)
	(via
		(at 117.888004 -253.392432)
		(size 0.4064)
		(drill 0.2032)
		(layers "F.Cu" "B.Cu")
		(net "PVDDCR_SOC_P1")
	)
	(via
		(at 121.644664 -251.774452)
		(size 0.4064)
		(drill 0.2032)
		(layers "F.Cu" "B.Cu")
		(net "PVDDCR_SOC_P1")
	)
	(via
		(at 122.316748 -177.807112)
		(size 0.508)
		(drill 0.254)
		(layers "F.Cu" "B.Cu")
		(net "PVDDCR_SOC_P1")
	)
	(via
		(at 134.609332 -172.32884)
		(size 0.508)
		(drill 0.254)
		(layers "F.Cu" "B.Cu")
		(net "PVDDCR_SOC_P1")
	)
	(via
		(at 143.73479 -254.20447)
		(size 0.4064)
		(drill 0.2032)
		(layers "F.Cu" "B.Cu")
		(net "PVDDCR_SOC_P1")
	)
	(via
		(at 102.38105 -255.824482)
		(size 0.4064)
		(drill 0.2032)
		(layers "F.Cu" "B.Cu")
		(net "PVDDCR_SOC_P1")
	)
	(via
		(at 122.123962 -257.930396)
		(size 0.4826)
		(drill 0.254)
		(layers "F.Cu" "B.Cu")
		(net "PVDDCR_SOC_P1")
	)
	(via
		(at 113.458244 -186.47664)
		(size 0.508)
		(drill 0.254)
		(layers "F.Cu" "B.Cu")
		(net "PVDDCR_SOC_P1")
	)
	(via
		(at 124.049536 -259.73024)
		(size 0.4826)
		(drill 0.254)
		(layers "F.Cu" "B.Cu")
		(net "PVDDCR_SOC_P1")
	)
	(via
		(at 117.47246 -185.173112)
		(size 0.508)
		(drill 0.254)
		(layers "F.Cu" "B.Cu")
		(net "PVDDCR_SOC_P1")
	)
	(via
		(at 101.91115 -256.634488)
		(size 0.4064)
		(drill 0.2032)
		(layers "F.Cu" "B.Cu")
		(net "PVDDCR_SOC_P1")
	)
	(via
		(at 135.880348 -169.78884)
		(size 0.508)
		(drill 0.254)
		(layers "F.Cu" "B.Cu")
		(net "PVDDCR_SOC_P1")
	)
	(via
		(at 114.09426 -185.173112)
		(size 0.508)
		(drill 0.254)
		(layers "F.Cu" "B.Cu")
		(net "PVDDCR_SOC_P1")
	)
	(via
		(at 122.114818 -255.824482)
		(size 0.4064)
		(drill 0.2032)
		(layers "F.Cu" "B.Cu")
		(net "PVDDCR_SOC_P1")
	)
	(via
		(at 136.684766 -246.914416)
		(size 0.4064)
		(drill 0.2032)
		(layers "F.Cu" "B.Cu")
		(net "PVDDCR_SOC_P1")
	)
	(via
		(at 125.954536 -258.830318)
		(size 0.4826)
		(drill 0.254)
		(layers "F.Cu" "B.Cu")
		(net "PVDDCR_SOC_P1")
	)
	(via
		(at 111.343186 -253.432564)
		(size 0.4826)
		(drill 0.254)
		(layers "F.Cu" "B.Cu")
		(net "PVDDCR_SOC_P1")
	)
	(via
		(at 143.56461 -265.98626)
		(size 0.4064)
		(drill 0.2032)
		(layers "F.Cu" "B.Cu")
		(net "PVDDCR_SOC_P1")
	)
	(via
		(at 114.093244 -187.11164)
		(size 0.508)
		(drill 0.254)
		(layers "F.Cu" "B.Cu")
		(net "PVDDCR_SOC_P1")
	)
	(via
		(at 114.728244 -187.74664)
		(size 0.508)
		(drill 0.254)
		(layers "F.Cu" "B.Cu")
		(net "PVDDCR_SOC_P1")
	)
	(via
		(at 117.47246 -185.808112)
		(size 0.508)
		(drill 0.254)
		(layers "F.Cu" "B.Cu")
		(net "PVDDCR_SOC_P1")
	)
	(via
		(at 130.574796 -229.90429)
		(size 0.4064)
		(drill 0.2032)
		(layers "F.Cu" "B.Cu")
		(net "PVDDCR_SOC_P1")
	)
	(via
		(at 126.644654 -262.746236)
		(size 0.4064)
		(drill 0.2032)
		(layers "F.Cu" "B.Cu")
		(net "PVDDCR_SOC_P1")
	)
	(via
		(at 135.245348 -169.15384)
		(size 0.508)
		(drill 0.254)
		(layers "F.Cu" "B.Cu")
		(net "PVDDCR_SOC_P1")
	)
	(via
		(at 119.76481 -251.774452)
		(size 0.4064)
		(drill 0.2032)
		(layers "F.Cu" "B.Cu")
		(net "PVDDCR_SOC_P1")
	)
	(via
		(at 118.35511 -255.53035)
		(size 0.4826)
		(drill 0.254)
		(layers "F.Cu" "B.Cu")
		(net "PVDDCR_SOC_P1")
	)
	(via
		(at 123.994672 -254.20447)
		(size 0.4064)
		(drill 0.2032)
		(layers "F.Cu" "B.Cu")
		(net "PVDDCR_SOC_P1")
	)
	(via
		(at 125.954536 -257.930396)
		(size 0.4826)
		(drill 0.254)
		(layers "F.Cu" "B.Cu")
		(net "PVDDCR_SOC_P1")
	)
	(via
		(at 130.104642 -246.914416)
		(size 0.4064)
		(drill 0.2032)
		(layers "F.Cu" "B.Cu")
		(net "PVDDCR_SOC_P1")
	)
	(via
		(at 127.284734 -246.914416)
		(size 0.4064)
		(drill 0.2032)
		(layers "F.Cu" "B.Cu")
		(net "PVDDCR_SOC_P1")
	)
	(via
		(at 143.264636 -242.05438)
		(size 0.4064)
		(drill 0.2032)
		(layers "F.Cu" "B.Cu")
		(net "PVDDCR_SOC_P1")
	)
	(via
		(at 117.884702 -251.774452)
		(size 0.4064)
		(drill 0.2032)
		(layers "F.Cu" "B.Cu")
		(net "PVDDCR_SOC_P1")
	)
	(via
		(at 113.458244 -184.57164)
		(size 0.508)
		(drill 0.254)
		(layers "F.Cu" "B.Cu")
		(net "PVDDCR_SOC_P1")
	)
	(via
		(at 130.574796 -244.484398)
		(size 0.4064)
		(drill 0.2032)
		(layers "F.Cu" "B.Cu")
		(net "PVDDCR_SOC_P1")
	)
	(via
		(at 102.681024 -261.93623)
		(size 0.4064)
		(drill 0.2032)
		(layers "F.Cu" "B.Cu")
		(net "PVDDCR_SOC_P1")
	)
	(via
		(at 114.093244 -188.38164)
		(size 0.508)
		(drill 0.254)
		(layers "F.Cu" "B.Cu")
		(net "PVDDCR_SOC_P1")
	)
	(via
		(at 143.264636 -232.334308)
		(size 0.4064)
		(drill 0.2032)
		(layers "F.Cu" "B.Cu")
		(net "PVDDCR_SOC_P1")
	)
	(via
		(at 126.329948 -179.077112)
		(size 0.508)
		(drill 0.254)
		(layers "F.Cu" "B.Cu")
		(net "PVDDCR_SOC_P1")
	)
	(via
		(at 100.971096 -255.014476)
		(size 0.4064)
		(drill 0.2032)
		(layers "F.Cu" "B.Cu")
		(net "PVDDCR_SOC_P1")
	)
	(via
		(at 113.458244 -185.84164)
		(size 0.508)
		(drill 0.254)
		(layers "F.Cu" "B.Cu")
		(net "PVDDCR_SOC_P1")
	)
	(via
		(at 111.343186 -252.416564)
		(size 0.4826)
		(drill 0.254)
		(layers "F.Cu" "B.Cu")
		(net "PVDDCR_SOC_P1")
	)
	(via
		(at 130.574796 -239.624362)
		(size 0.4064)
		(drill 0.2032)
		(layers "F.Cu" "B.Cu")
		(net "PVDDCR_SOC_P1")
	)
	(via
		(at 125.404626 -251.774452)
		(size 0.4064)
		(drill 0.2032)
		(layers "F.Cu" "B.Cu")
		(net "PVDDCR_SOC_P1")
	)
	(via
		(at 118.741444 -183.903112)
		(size 0.508)
		(drill 0.254)
		(layers "F.Cu" "B.Cu")
		(net "PVDDCR_SOC_P1")
	)
	(via
		(at 127.114808 -261.93623)
		(size 0.4064)
		(drill 0.2032)
		(layers "F.Cu" "B.Cu")
		(net "PVDDCR_SOC_P1")
	)
	(via
		(at 133.975348 -170.415712)
		(size 0.508)
		(drill 0.254)
		(layers "F.Cu" "B.Cu")
		(net "PVDDCR_SOC_P1")
	)
	(via
		(at 122.950732 -180.38064)
		(size 0.508)
		(drill 0.254)
		(layers "F.Cu" "B.Cu")
		(net "PVDDCR_SOC_P1")
	)
	(via
		(at 121.644664 -255.014476)
		(size 0.4064)
		(drill 0.2032)
		(layers "F.Cu" "B.Cu")
		(net "PVDDCR_SOC_P1")
	)
	(via
		(at 126.964948 -178.47564)
		(size 0.508)
		(drill 0.254)
		(layers "F.Cu" "B.Cu")
		(net "PVDDCR_SOC_P1")
	)
	(via
		(at 134.610348 -169.780712)
		(size 0.508)
		(drill 0.254)
		(layers "F.Cu" "B.Cu")
		(net "PVDDCR_SOC_P1")
	)
	(via
		(at 102.211124 -262.746236)
		(size 0.4064)
		(drill 0.2032)
		(layers "F.Cu" "B.Cu")
		(net "PVDDCR_SOC_P1")
	)
	(via
		(at 135.245348 -169.78884)
		(size 0.508)
		(drill 0.254)
		(layers "F.Cu" "B.Cu")
		(net "PVDDCR_SOC_P1")
	)
	(via
		(at 130.596132 -168.510712)
		(size 0.508)
		(drill 0.254)
		(layers "F.Cu" "B.Cu")
		(net "PVDDCR_SOC_P1")
	)
	(via
		(at 125.87478 -254.20447)
		(size 0.4064)
		(drill 0.2032)
		(layers "F.Cu" "B.Cu")
		(net "PVDDCR_SOC_P1")
	)
	(via
		(at 130.597148 -169.145712)
		(size 0.508)
		(drill 0.254)
		(layers "F.Cu" "B.Cu")
		(net "PVDDCR_SOC_P1")
	)
	(via
		(at 130.574796 -234.764326)
		(size 0.4064)
		(drill 0.2032)
		(layers "F.Cu" "B.Cu")
		(net "PVDDCR_SOC_P1")
	)
	(via
		(at 135.880348 -168.51884)
		(size 0.508)
		(drill 0.254)
		(layers "F.Cu" "B.Cu")
		(net "PVDDCR_SOC_P1")
	)
	(via
		(at 122.123962 -259.73024)
		(size 0.4826)
		(drill 0.254)
		(layers "F.Cu" "B.Cu")
		(net "PVDDCR_SOC_P1")
	)
	(via
		(at 115.247928 -255.4732)
		(size 0.4826)
		(drill 0.254)
		(layers "F.Cu" "B.Cu")
		(net "PVDDCR_SOC_P1")
	)
	(via
		(at 130.596132 -172.32884)
		(size 0.508)
		(drill 0.254)
		(layers "F.Cu" "B.Cu")
		(net "PVDDCR_SOC_P1")
	)
	(via
		(at 136.684766 -242.05438)
		(size 0.4064)
		(drill 0.2032)
		(layers "F.Cu" "B.Cu")
		(net "PVDDCR_SOC_P1")
	)
	(via
		(at 143.264636 -246.914416)
		(size 0.4064)
		(drill 0.2032)
		(layers "F.Cu" "B.Cu")
		(net "PVDDCR_SOC_P1")
	)
	(via
		(at 118.354856 -250.964446)
		(size 0.4064)
		(drill 0.2032)
		(layers "F.Cu" "B.Cu")
		(net "PVDDCR_SOC_P1")
	)
	(via
		(at 118.35511 -261.230364)
		(size 0.4826)
		(drill 0.254)
		(layers "F.Cu" "B.Cu")
		(net "PVDDCR_SOC_P1")
	)
	(via
		(at 121.680732 -177.172112)
		(size 0.508)
		(drill 0.254)
		(layers "F.Cu" "B.Cu")
		(net "PVDDCR_SOC_P1")
	)
	(via
		(at 115.26774 -258.795266)
		(size 0.4826)
		(drill 0.254)
		(layers "F.Cu" "B.Cu")
		(net "PVDDCR_SOC_P1")
	)
	(via
		(at 133.975348 -169.145712)
		(size 0.508)
		(drill 0.254)
		(layers "F.Cu" "B.Cu")
		(net "PVDDCR_SOC_P1")
	)
	(via
		(at 122.315732 -181.01564)
		(size 0.508)
		(drill 0.254)
		(layers "F.Cu" "B.Cu")
		(net "PVDDCR_SOC_P1")
	)
	(via
		(at 116.004848 -251.774452)
		(size 0.4064)
		(drill 0.2032)
		(layers "F.Cu" "B.Cu")
		(net "PVDDCR_SOC_P1")
	)
	(via
		(at 131.231132 -168.510712)
		(size 0.508)
		(drill 0.254)
		(layers "F.Cu" "B.Cu")
		(net "PVDDCR_SOC_P1")
	)
	(via
		(at 134.609332 -171.69384)
		(size 0.508)
		(drill 0.254)
		(layers "F.Cu" "B.Cu")
		(net "PVDDCR_SOC_P1")
	)
	(via
		(at 127.284734 -253.394464)
		(size 0.4064)
		(drill 0.2032)
		(layers "F.Cu" "B.Cu")
		(net "PVDDCR_SOC_P1")
	)
	(via
		(at 130.574796 -254.20447)
		(size 0.4064)
		(drill 0.2032)
		(layers "F.Cu" "B.Cu")
		(net "PVDDCR_SOC_P1")
	)
	(via
		(at 137.154666 -239.624362)
		(size 0.4064)
		(drill 0.2032)
		(layers "F.Cu" "B.Cu")
		(net "PVDDCR_SOC_P1")
	)
	(via
		(at 123.524772 -255.014476)
		(size 0.4064)
		(drill 0.2032)
		(layers "F.Cu" "B.Cu")
		(net "PVDDCR_SOC_P1")
	)
	(via
		(at 106.607864 -253.392432)
		(size 0.4064)
		(drill 0.2032)
		(layers "F.Cu" "B.Cu")
		(net "PVDDCR_SOC_P1")
	)
	(via
		(at 143.73479 -244.484398)
		(size 0.4064)
		(drill 0.2032)
		(layers "F.Cu" "B.Cu")
		(net "PVDDCR_SOC_P1")
	)
	(via
		(at 118.10746 -185.173112)
		(size 0.508)
		(drill 0.254)
		(layers "F.Cu" "B.Cu")
		(net "PVDDCR_SOC_P1")
	)
	(via
		(at 143.73479 -234.764326)
		(size 0.4064)
		(drill 0.2032)
		(layers "F.Cu" "B.Cu")
		(net "PVDDCR_SOC_P1")
	)
	(via
		(at 123.524772 -253.394464)
		(size 0.4064)
		(drill 0.2032)
		(layers "F.Cu" "B.Cu")
		(net "PVDDCR_SOC_P1")
	)
	(via
		(at 134.609332 -168.510712)
		(size 0.508)
		(drill 0.254)
		(layers "F.Cu" "B.Cu")
		(net "PVDDCR_SOC_P1")
	)
	(via
		(at 114.72926 -184.538112)
		(size 0.508)
		(drill 0.254)
		(layers "F.Cu" "B.Cu")
		(net "PVDDCR_SOC_P1")
	)
	(via
		(at 134.610348 -171.050712)
		(size 0.508)
		(drill 0.254)
		(layers "F.Cu" "B.Cu")
		(net "PVDDCR_SOC_P1")
	)
	(via
		(at 122.951748 -179.077112)
		(size 0.508)
		(drill 0.254)
		(layers "F.Cu" "B.Cu")
		(net "PVDDCR_SOC_P1")
	)
	(via
		(at 126.964948 -179.11064)
		(size 0.508)
		(drill 0.254)
		(layers "F.Cu" "B.Cu")
		(net "PVDDCR_SOC_P1")
	)
	(via
		(at 143.73479 -223.424496)
		(size 0.4064)
		(drill 0.2032)
		(layers "F.Cu" "B.Cu")
		(net "PVDDCR_SOC_P1")
	)
	(via
		(at 109.900974 -250.964446)
		(size 0.4064)
		(drill 0.2032)
		(layers "F.Cu" "B.Cu")
		(net "PVDDCR_SOC_P1")
	)
	(via
		(at 127.284734 -256.634488)
		(size 0.4064)
		(drill 0.2032)
		(layers "F.Cu" "B.Cu")
		(net "PVDDCR_SOC_P1")
	)
	(via
		(at 130.104642 -251.774452)
		(size 0.4064)
		(drill 0.2032)
		(layers "F.Cu" "B.Cu")
		(net "PVDDCR_SOC_P1")
	)
	(via
		(at 122.316748 -179.077112)
		(size 0.508)
		(drill 0.254)
		(layers "F.Cu" "B.Cu")
		(net "PVDDCR_SOC_P1")
	)
	(via
		(at 122.315732 -180.38064)
		(size 0.508)
		(drill 0.254)
		(layers "F.Cu" "B.Cu")
		(net "PVDDCR_SOC_P1")
	)
	(via
		(at 133.974332 -172.32884)
		(size 0.508)
		(drill 0.254)
		(layers "F.Cu" "B.Cu")
		(net "PVDDCR_SOC_P1")
	)
	(via
		(at 122.951748 -179.712112)
		(size 0.508)
		(drill 0.254)
		(layers "F.Cu" "B.Cu")
		(net "PVDDCR_SOC_P1")
	)
	(via
		(at 117.47246 -186.570112)
		(size 0.6604)
		(drill 0.3302)
		(layers "F.Cu" "B.Cu")
		(net "PVDDCR_SOC_P1")
	)
	(via
		(at 122.316748 -179.712112)
		(size 0.508)
		(drill 0.254)
		(layers "F.Cu" "B.Cu")
		(net "PVDDCR_SOC_P1")
	)
	(via
		(at 133.974332 -168.510712)
		(size 0.508)
		(drill 0.254)
		(layers "F.Cu" "B.Cu")
		(net "PVDDCR_SOC_P1")
	)
	(via
		(at 126.329948 -178.442112)
		(size 0.508)
		(drill 0.254)
		(layers "F.Cu" "B.Cu")
		(net "PVDDCR_SOC_P1")
	)
	(via
		(at 130.104642 -232.334308)
		(size 0.4064)
		(drill 0.2032)
		(layers "F.Cu" "B.Cu")
		(net "PVDDCR_SOC_P1")
	)
	(via
		(at 118.35511 -257.43027)
		(size 0.4826)
		(drill 0.254)
		(layers "F.Cu" "B.Cu")
		(net "PVDDCR_SOC_P1")
	)
	(via
		(at 134.610348 -170.415712)
		(size 0.508)
		(drill 0.254)
		(layers "F.Cu" "B.Cu")
		(net "PVDDCR_SOC_P1")
	)
	(via
		(at 136.684766 -251.774452)
		(size 0.4064)
		(drill 0.2032)
		(layers "F.Cu" "B.Cu")
		(net "PVDDCR_SOC_P1")
	)
	(via
		(at 134.610348 -169.145712)
		(size 0.508)
		(drill 0.254)
		(layers "F.Cu" "B.Cu")
		(net "PVDDCR_SOC_P1")
	)
	(via
		(at 123.524772 -256.634488)
		(size 0.4064)
		(drill 0.2032)
		(layers "F.Cu" "B.Cu")
		(net "PVDDCR_SOC_P1")
	)
	(via
		(at 144.034764 -263.556242)
		(size 0.4064)
		(drill 0.2032)
		(layers "F.Cu" "B.Cu")
		(net "PVDDCR_SOC_P1")
	)
	(via
		(at 127.269748 -161.41065)
		(size 0.508)
		(drill 0.254)
		(layers "F.Cu" "B.Cu")
		(net "PVDDCR_SOC_P1")
	)
	(via
		(at 125.87478 -252.584458)
		(size 0.4064)
		(drill 0.2032)
		(layers "F.Cu" "B.Cu")
		(net "PVDDCR_SOC_P1")
	)
	(via
		(at 124.049536 -258.830318)
		(size 0.4826)
		(drill 0.254)
		(layers "F.Cu" "B.Cu")
		(net "PVDDCR_SOC_P1")
	)
	(via
		(at 130.596132 -172.96384)
		(size 0.508)
		(drill 0.254)
		(layers "F.Cu" "B.Cu")
		(net "PVDDCR_SOC_P1")
	)
	(via
		(at 143.73479 -239.624362)
		(size 0.4064)
		(drill 0.2032)
		(layers "F.Cu" "B.Cu")
		(net "PVDDCR_SOC_P1")
	)
	(via
		(at 121.680732 -181.01564)
		(size 0.508)
		(drill 0.254)
		(layers "F.Cu" "B.Cu")
		(net "PVDDCR_SOC_P1")
	)
	(via
		(at 125.404626 -256.634488)
		(size 0.4064)
		(drill 0.2032)
		(layers "F.Cu" "B.Cu")
		(net "PVDDCR_SOC_P1")
	)
	(via
		(at 137.45464 -263.556242)
		(size 0.4064)
		(drill 0.2032)
		(layers "F.Cu" "B.Cu")
		(net "PVDDCR_SOC_P1")
	)
	(via
		(at 122.114818 -250.964446)
		(size 0.4064)
		(drill 0.2032)
		(layers "F.Cu" "B.Cu")
		(net "PVDDCR_SOC_P1")
	)
	(via
		(at 102.38105 -254.20447)
		(size 0.4064)
		(drill 0.2032)
		(layers "F.Cu" "B.Cu")
		(net "PVDDCR_SOC_P1")
	)
	(via
		(at 126.964948 -177.84064)
		(size 0.508)
		(drill 0.254)
		(layers "F.Cu" "B.Cu")
		(net "PVDDCR_SOC_P1")
	)
	(via
		(at 111.362236 -251.400564)
		(size 0.4826)
		(drill 0.254)
		(layers "F.Cu" "B.Cu")
		(net "PVDDCR_SOC_P1")
	)
	(via
		(at 130.596132 -173.59884)
		(size 0.508)
		(drill 0.254)
		(layers "F.Cu" "B.Cu")
		(net "PVDDCR_SOC_P1")
	)
	(via
		(at 127.284734 -240.434368)
		(size 0.4064)
		(drill 0.2032)
		(layers "F.Cu" "B.Cu")
		(net "PVDDCR_SOC_P1")
	)
	(via
		(at 125.87478 -250.964446)
		(size 0.4064)
		(drill 0.2032)
		(layers "F.Cu" "B.Cu")
		(net "PVDDCR_SOC_P1")
	)
	(via
		(at 118.74246 -184.57164)
		(size 0.508)
		(drill 0.254)
		(layers "F.Cu" "B.Cu")
		(net "PVDDCR_SOC_P1")
	)
	(via
		(at 143.264636 -237.194344)
		(size 0.4064)
		(drill 0.2032)
		(layers "F.Cu" "B.Cu")
		(net "PVDDCR_SOC_P1")
	)
	(via
		(at 131.232148 -170.415712)
		(size 0.508)
		(drill 0.254)
		(layers "F.Cu" "B.Cu")
		(net "PVDDCR_SOC_P1")
	)
	(via
		(at 118.35511 -256.48031)
		(size 0.4826)
		(drill 0.254)
		(layers "F.Cu" "B.Cu")
		(net "PVDDCR_SOC_P1")
	)
	(via
		(at 113.458244 -187.74664)
		(size 0.508)
		(drill 0.254)
		(layers "F.Cu" "B.Cu")
		(net "PVDDCR_SOC_P1")
	)
	(via
		(at 123.994672 -255.824482)
		(size 0.4064)
		(drill 0.2032)
		(layers "F.Cu" "B.Cu")
		(net "PVDDCR_SOC_P1")
	)
	(via
		(at 131.232148 -171.050712)
		(size 0.508)
		(drill 0.254)
		(layers "F.Cu" "B.Cu")
		(net "PVDDCR_SOC_P1")
	)
	(via
		(at 143.264636 -251.774452)
		(size 0.4064)
		(drill 0.2032)
		(layers "F.Cu" "B.Cu")
		(net "PVDDCR_SOC_P1")
	)
	(via
		(at 114.72926 -185.808112)
		(size 0.508)
		(drill 0.254)
		(layers "F.Cu" "B.Cu")
		(net "PVDDCR_SOC_P1")
	)
	(via
		(at 124.7648 -261.126224)
		(size 0.4064)
		(drill 0.2032)
		(layers "F.Cu" "B.Cu")
		(net "PVDDCR_SOC_P1")
	)
	(via
		(at 122.951748 -177.807112)
		(size 0.508)
		(drill 0.254)
		(layers "F.Cu" "B.Cu")
		(net "PVDDCR_SOC_P1")
	)
	(via
		(at 126.329948 -177.807112)
		(size 0.508)
		(drill 0.254)
		(layers "F.Cu" "B.Cu")
		(net "PVDDCR_SOC_P1")
	)
	(via
		(at 110.367826 -253.392432)
		(size 0.4064)
		(drill 0.2032)
		(layers "F.Cu" "B.Cu")
		(net "PVDDCR_SOC_P1")
	)
	(via
		(at 107.647994 -255.4732)
		(size 0.4826)
		(drill 0.254)
		(layers "F.Cu" "B.Cu")
		(net "PVDDCR_SOC_P1")
	)
	(via
		(at 133.975348 -169.780712)
		(size 0.508)
		(drill 0.254)
		(layers "F.Cu" "B.Cu")
		(net "PVDDCR_SOC_P1")
	)
	(via
		(at 113.458244 -189.14364)
		(size 0.6604)
		(drill 0.3302)
		(layers "F.Cu" "B.Cu")
		(net "PVDDCR_SOC_P1")
	)
	(via
		(at 124.7648 -262.746236)
		(size 0.4064)
		(drill 0.2032)
		(layers "F.Cu" "B.Cu")
		(net "PVDDCR_SOC_P1")
	)
	(via
		(at 130.596132 -171.69384)
		(size 0.508)
		(drill 0.254)
		(layers "F.Cu" "B.Cu")
		(net "PVDDCR_SOC_P1")
	)
	(via
		(at 125.694948 -177.807112)
		(size 0.508)
		(drill 0.254)
		(layers "F.Cu" "B.Cu")
		(net "PVDDCR_SOC_P1")
	)
	(via
		(at 122.951748 -178.442112)
		(size 0.508)
		(drill 0.254)
		(layers "F.Cu" "B.Cu")
		(net "PVDDCR_SOC_P1")
	)
	(via
		(at 130.104642 -242.05438)
		(size 0.4064)
		(drill 0.2032)
		(layers "F.Cu" "B.Cu")
		(net "PVDDCR_SOC_P1")
	)
	(via
		(at 130.597148 -171.050712)
		(size 0.508)
		(drill 0.254)
		(layers "F.Cu" "B.Cu")
		(net "PVDDCR_SOC_P1")
	)
	(via
		(at 136.684766 -237.194344)
		(size 0.4064)
		(drill 0.2032)
		(layers "F.Cu" "B.Cu")
		(net "PVDDCR_SOC_P1")
	)
	(via
		(at 122.315732 -181.65064)
		(size 0.508)
		(drill 0.254)
		(layers "F.Cu" "B.Cu")
		(net "PVDDCR_SOC_P1")
	)
	(via
		(at 143.264636 -222.61449)
		(size 0.4064)
		(drill 0.2032)
		(layers "F.Cu" "B.Cu")
		(net "PVDDCR_SOC_P1")
	)
	(via
		(at 117.47246 -184.538112)
		(size 0.508)
		(drill 0.254)
		(layers "F.Cu" "B.Cu")
		(net "PVDDCR_SOC_P1")
	)
	(via
		(at 122.950732 -177.172112)
		(size 0.508)
		(drill 0.254)
		(layers "F.Cu" "B.Cu")
		(net "PVDDCR_SOC_P1")
	)
	(via
		(at 135.245348 -171.05884)
		(size 0.508)
		(drill 0.254)
		(layers "F.Cu" "B.Cu")
		(net "PVDDCR_SOC_P1")
	)
	(via
		(at 102.681024 -263.556242)
		(size 0.4064)
		(drill 0.2032)
		(layers "F.Cu" "B.Cu")
		(net "PVDDCR_SOC_P1")
	)
	(via
		(at 116.197888 -255.4732)
		(size 0.4826)
		(drill 0.254)
		(layers "F.Cu" "B.Cu")
		(net "PVDDCR_SOC_P1")
	)
	(via
		(at 125.87478 -255.824482)
		(size 0.4064)
		(drill 0.2032)
		(layers "F.Cu" "B.Cu")
		(net "PVDDCR_SOC_P1")
	)
	(via
		(at 125.404626 -253.394464)
		(size 0.4064)
		(drill 0.2032)
		(layers "F.Cu" "B.Cu")
		(net "PVDDCR_SOC_P1")
	)
	(via
		(at 114.728244 -183.903112)
		(size 0.508)
		(drill 0.254)
		(layers "F.Cu" "B.Cu")
		(net "PVDDCR_SOC_P1")
	)
	(via
		(at 121.644664 -256.634488)
		(size 0.4064)
		(drill 0.2032)
		(layers "F.Cu" "B.Cu")
		(net "PVDDCR_SOC_P1")
	)
	(via
		(at 109.547914 -255.4732)
		(size 0.4826)
		(drill 0.254)
		(layers "F.Cu" "B.Cu")
		(net "PVDDCR_SOC_P1")
	)
	(segment
		(start 119.34698 -168.499282)
		(end 118.989348 -168.14165)
		(width 0.381)
		(layer "B.Cu")
		(net "PVDDCR_SOC_P1")
	)
	(segment
		(start 136.08558 -153.106882)
		(end 135.727948 -152.74925)
		(width 0.381)
		(layer "B.Cu")
		(net "PVDDCR_SOC_P1")
	)
	(segment
		(start 136.08558 -153.465784)
		(end 136.08558 -153.106882)
		(width 0.381)
		(layer "B.Cu")
		(net "PVDDCR_SOC_P1")
	)
	(segment
		(start 127.62738 -161.768282)
		(end 127.269748 -161.41065)
		(width 0.381)
		(layer "B.Cu")
		(net "PVDDCR_SOC_P1")
	)
	(segment
		(start 127.62738 -162.127184)
		(end 127.62738 -161.768282)
		(width 0.381)
		(layer "B.Cu")
		(net "PVDDCR_SOC_P1")
	)
	(segment
		(start 119.34698 -168.858184)
		(end 119.34698 -168.499282)
		(width 0.381)
		(layer "B.Cu")
		(net "PVDDCR_SOC_P1")
	)
	(segment
		(start 136.019286 -153.880312)
		(end 134.988554 -154.911044)
		(width 0.381)
		(layer "In2.Cu")
		(net "PVDDCR_SOC_P1")
	)
	(segment
		(start 126.963932 -176.11344)
		(end 126.963932 -177.172112)
		(width 0.381)
		(layer "In2.Cu")
		(net "PVDDCR_SOC_P1")
	)
	(segment
		(start 135.245348 -167.980106)
		(end 135.245348 -168.51884)
		(width 0.381)
		(layer "In2.Cu")
		(net "PVDDCR_SOC_P1")
	)
	(segment
		(start 134.988554 -154.911044)
		(end 134.988554 -167.723312)
		(width 0.381)
		(layer "In2.Cu")
		(net "PVDDCR_SOC_P1")
	)
	(segment
		(start 118.247414 -170.305984)
		(end 118.247414 -182.797704)
		(width 0.381)
		(layer "In2.Cu")
		(net "PVDDCR_SOC_P1")
	)
	(segment
		(start 128.420114 -174.657258)
		(end 126.963932 -176.11344)
		(width 0.381)
		(layer "In2.Cu")
		(net "PVDDCR_SOC_P1")
	)
	(segment
		(start 119.280686 -168.432988)
		(end 119.280686 -169.272712)
		(width 0.381)
		(layer "In2.Cu")
		(net "PVDDCR_SOC_P1")
	)
	(segment
		(start 136.019286 -153.040588)
		(end 136.019286 -153.880312)
		(width 0.381)
		(layer "In2.Cu")
		(net "PVDDCR_SOC_P1")
	)
	(segment
		(start 118.247414 -182.797704)
		(end 118.741444 -183.291734)
		(width 0.381)
		(layer "In2.Cu")
		(net "PVDDCR_SOC_P1")
	)
	(segment
		(start 135.727948 -152.74925)
		(end 136.019286 -153.040588)
		(width 0.381)
		(layer "In2.Cu")
		(net "PVDDCR_SOC_P1")
	)
	(segment
		(start 134.988554 -167.723312)
		(end 135.245348 -167.980106)
		(width 0.381)
		(layer "In2.Cu")
		(net "PVDDCR_SOC_P1")
	)
	(segment
		(start 119.280686 -169.272712)
		(end 118.247414 -170.305984)
		(width 0.381)
		(layer "In2.Cu")
		(net "PVDDCR_SOC_P1")
	)
	(segment
		(start 118.989348 -168.14165)
		(end 119.280686 -168.432988)
		(width 0.381)
		(layer "In2.Cu")
		(net "PVDDCR_SOC_P1")
	)
	(segment
		(start 128.420114 -162.561016)
		(end 128.420114 -174.657258)
		(width 0.381)
		(layer "In2.Cu")
		(net "PVDDCR_SOC_P1")
	)
	(segment
		(start 127.269748 -161.41065)
		(end 128.420114 -162.561016)
		(width 0.381)
		(layer "In2.Cu")
		(net "PVDDCR_SOC_P1")
	)
	(segment
		(start 118.741444 -183.291734)
		(end 118.741444 -183.903112)
		(width 0.381)
		(layer "In2.Cu")
		(net "PVDDCR_SOC_P1")
	)
	(segment
		(start 416.929824 -161.492692)
		(end 416.979862 -161.442654)
		(width 0.2032)
		(layer "F.Cu")
		(net "PVDDCR_SOC_P0_VOS3")
	)
	(segment
		(start 416.979862 -161.442654)
		(end 416.979862 -161.155888)
		(width 0.2032)
		(layer "F.Cu")
		(net "PVDDCR_SOC_P0_VOS3")
	)
	(segment
		(start 416.979862 -161.155888)
		(end 417.254436 -160.881314)
		(width 0.2032)
		(layer "F.Cu")
		(net "PVDDCR_SOC_P0_VOS3")
	)
	(via
		(at 417.254436 -160.881314)
		(size 0.508)
		(drill 0.254)
		(layers "F.Cu" "B.Cu")
		(net "PVDDCR_SOC_P0_VOS3")
	)
	(segment
		(start 417.87572 -161.502598)
		(end 417.254436 -160.881314)
		(width 0.2286)
		(layer "B.Cu")
		(net "PVDDCR_SOC_P0_VOS3")
	)
	(segment
		(start 418.191188 -161.502598)
		(end 417.87572 -161.502598)
		(width 0.2286)
		(layer "B.Cu")
		(net "PVDDCR_SOC_P0_VOS3")
	)
	(segment
		(start 408.547824 -166.318692)
		(end 408.675078 -166.191438)
		(width 0.2286)
		(layer "F.Cu")
		(net "PVDDCR_SOC_P0_VOS2")
	)
	(segment
		(start 408.675078 -165.904672)
		(end 408.872436 -165.707314)
		(width 0.2286)
		(layer "F.Cu")
		(net "PVDDCR_SOC_P0_VOS2")
	)
	(segment
		(start 408.675078 -166.191438)
		(end 408.675078 -165.904672)
		(width 0.2286)
		(layer "F.Cu")
		(net "PVDDCR_SOC_P0_VOS2")
	)
	(via
		(at 408.872436 -165.707314)
		(size 0.508)
		(drill 0.254)
		(layers "F.Cu" "B.Cu")
		(net "PVDDCR_SOC_P0_VOS2")
	)
	(segment
		(start 409.809188 -166.328598)
		(end 409.49372 -166.328598)
		(width 0.2286)
		(layer "B.Cu")
		(net "PVDDCR_SOC_P0_VOS2")
	)
	(segment
		(start 409.49372 -166.328598)
		(end 408.872436 -165.707314)
		(width 0.2286)
		(layer "B.Cu")
		(net "PVDDCR_SOC_P0_VOS2")
	)
	(segment
		(start 400.548856 -174.28464)
		(end 400.224244 -174.609252)
		(width 0.2032)
		(layer "F.Cu")
		(net "PVDDCR_SOC_P0_VOS1")
	)
	(segment
		(start 400.224244 -174.609252)
		(end 400.224244 -174.896018)
		(width 0.2032)
		(layer "F.Cu")
		(net "PVDDCR_SOC_P0_VOS1")
	)
	(via
		(at 400.548856 -174.28464)
		(size 0.508)
		(drill 0.254)
		(layers "F.Cu" "B.Cu")
		(net "PVDDCR_SOC_P0_VOS1")
	)
	(segment
		(start 401.485608 -174.905924)
		(end 401.17014 -174.905924)
		(width 0.2286)
		(layer "B.Cu")
		(net "PVDDCR_SOC_P0_VOS1")
	)
	(segment
		(start 401.17014 -174.905924)
		(end 400.548856 -174.28464)
		(width 0.2286)
		(layer "B.Cu")
		(net "PVDDCR_SOC_P0_VOS1")
	)
	(segment
		(start 416.929824 -162.392868)
		(end 417.580572 -162.392868)
		(width 0.2286)
		(layer "F.Cu")
		(net "PVDDCR_SOC_P0_VCC3")
	)
	(segment
		(start 414.71977 -160.867852)
		(end 414.71977 -160.15589)
		(width 0.2286)
		(layer "F.Cu")
		(net "PVDDCR_SOC_P0_VCC3")
	)
	(segment
		(start 417.86048 -162.11296)
		(end 418.212778 -162.11296)
		(width 0.2286)
		(layer "F.Cu")
		(net "PVDDCR_SOC_P0_VCC3")
	)
	(segment
		(start 417.580572 -162.392868)
		(end 417.86048 -162.11296)
		(width 0.2286)
		(layer "F.Cu")
		(net "PVDDCR_SOC_P0_VCC3")
	)
	(segment
		(start 418.212778 -162.11296)
		(end 418.212778 -161.502598)
		(width 0.381)
		(layer "F.Cu")
		(net "PVDDCR_SOC_P0_VCC3")
	)
	(segment
		(start 414.71977 -160.15589)
		(end 414.795462 -160.080198)
		(width 0.2286)
		(layer "F.Cu")
		(net "PVDDCR_SOC_P0_VCC3")
	)
	(via
		(at 418.212778 -162.11296)
		(size 0.508)
		(drill 0.254)
		(layers "F.Cu" "B.Cu")
		(net "PVDDCR_SOC_P0_VCC3")
	)
	(via
		(at 414.795462 -160.080198)
		(size 0.508)
		(drill 0.254)
		(layers "F.Cu" "B.Cu")
		(net "PVDDCR_SOC_P0_VCC3")
	)
	(via
		(at 416.385248 -160.998662)
		(size 0.6604)
		(drill 0.3302)
		(layers "F.Cu" "B.Cu")
		(net "PVDDCR_SOC_P0_VCC3")
	)
	(segment
		(start 416.268662 -160.776412)
		(end 415.491676 -160.776412)
		(width 0.508)
		(layer "B.Cu")
		(net "PVDDCR_SOC_P0_VCC3")
	)
	(segment
		(start 416.385248 -160.892998)
		(end 416.268662 -160.776412)
		(width 0.508)
		(layer "B.Cu")
		(net "PVDDCR_SOC_P0_VCC3")
	)
	(segment
		(start 416.84067 -162.30854)
		(end 416.84067 -161.454084)
		(width 0.381)
		(layer "B.Cu")
		(net "PVDDCR_SOC_P0_VCC3")
	)
	(segment
		(start 415.491676 -160.776412)
		(end 414.795462 -160.080198)
		(width 0.508)
		(layer "B.Cu")
		(net "PVDDCR_SOC_P0_VCC3")
	)
	(segment
		(start 416.385248 -160.998662)
		(end 416.385248 -160.892998)
		(width 0.381)
		(layer "B.Cu")
		(net "PVDDCR_SOC_P0_VCC3")
	)
	(segment
		(start 417.350448 -162.30854)
		(end 416.84067 -162.30854)
		(width 0.381)
		(layer "B.Cu")
		(net "PVDDCR_SOC_P0_VCC3")
	)
	(segment
		(start 416.84067 -161.454084)
		(end 416.385248 -160.998662)
		(width 0.381)
		(layer "B.Cu")
		(net "PVDDCR_SOC_P0_VCC3")
	)
	(segment
		(start 418.212778 -162.11296)
		(end 417.546028 -162.11296)
		(width 0.381)
		(layer "B.Cu")
		(net "PVDDCR_SOC_P0_VCC3")
	)
	(segment
		(start 417.546028 -162.11296)
		(end 417.350448 -162.30854)
		(width 0.381)
		(layer "B.Cu")
		(net "PVDDCR_SOC_P0_VCC3")
	)
	(segment
		(start 406.33777 -164.98189)
		(end 406.33777 -165.693852)
		(width 0.2286)
		(layer "F.Cu")
		(net "PVDDCR_SOC_P0_VCC2")
	)
	(segment
		(start 408.547824 -167.218868)
		(end 409.198572 -167.218868)
		(width 0.2286)
		(layer "F.Cu")
		(net "PVDDCR_SOC_P0_VCC2")
	)
	(segment
		(start 409.198572 -167.218868)
		(end 409.47848 -166.93896)
		(width 0.2286)
		(layer "F.Cu")
		(net "PVDDCR_SOC_P0_VCC2")
	)
	(segment
		(start 409.47848 -166.93896)
		(end 409.830778 -166.93896)
		(width 0.2286)
		(layer "F.Cu")
		(net "PVDDCR_SOC_P0_VCC2")
	)
	(segment
		(start 406.413462 -164.906198)
		(end 406.33777 -164.98189)
		(width 0.2286)
		(layer "F.Cu")
		(net "PVDDCR_SOC_P0_VCC2")
	)
	(segment
		(start 409.830778 -166.93896)
		(end 409.830778 -166.328598)
		(width 0.381)
		(layer "F.Cu")
		(net "PVDDCR_SOC_P0_VCC2")
	)
	(via
		(at 408.003248 -165.824662)
		(size 0.6604)
		(drill 0.3302)
		(layers "F.Cu" "B.Cu")
		(net "PVDDCR_SOC_P0_VCC2")
	)
	(via
		(at 406.413462 -164.906198)
		(size 0.508)
		(drill 0.254)
		(layers "F.Cu" "B.Cu")
		(net "PVDDCR_SOC_P0_VCC2")
	)
	(via
		(at 409.830778 -166.93896)
		(size 0.508)
		(drill 0.254)
		(layers "F.Cu" "B.Cu")
		(net "PVDDCR_SOC_P0_VCC2")
	)
	(segment
		(start 408.003248 -165.892734)
		(end 408.003248 -165.824662)
		(width 0.381)
		(layer "B.Cu")
		(net "PVDDCR_SOC_P0_VCC2")
	)
	(segment
		(start 409.830778 -166.93896)
		(end 409.164028 -166.93896)
		(width 0.381)
		(layer "B.Cu")
		(net "PVDDCR_SOC_P0_VCC2")
	)
	(segment
		(start 407.84018 -165.55593)
		(end 407.063194 -165.55593)
		(width 0.508)
		(layer "B.Cu")
		(net "PVDDCR_SOC_P0_VCC2")
	)
	(segment
		(start 408.003248 -165.824662)
		(end 408.003248 -165.718998)
		(width 0.381)
		(layer "B.Cu")
		(net "PVDDCR_SOC_P0_VCC2")
	)
	(segment
		(start 407.063194 -165.55593)
		(end 406.413462 -164.906198)
		(width 0.508)
		(layer "B.Cu")
		(net "PVDDCR_SOC_P0_VCC2")
	)
	(segment
		(start 408.968448 -167.13454)
		(end 408.45867 -167.13454)
		(width 0.381)
		(layer "B.Cu")
		(net "PVDDCR_SOC_P0_VCC2")
	)
	(segment
		(start 408.003248 -165.718998)
		(end 407.84018 -165.55593)
		(width 0.508)
		(layer "B.Cu")
		(net "PVDDCR_SOC_P0_VCC2")
	)
	(segment
		(start 408.45867 -167.13454)
		(end 408.45867 -166.348156)
		(width 0.381)
		(layer "B.Cu")
		(net "PVDDCR_SOC_P0_VCC2")
	)
	(segment
		(start 408.45867 -166.348156)
		(end 408.003248 -165.892734)
		(width 0.381)
		(layer "B.Cu")
		(net "PVDDCR_SOC_P0_VCC2")
	)
	(segment
		(start 409.164028 -166.93896)
		(end 408.968448 -167.13454)
		(width 0.381)
		(layer "B.Cu")
		(net "PVDDCR_SOC_P0_VCC2")
	)
	(segment
		(start 401.507198 -175.516286)
		(end 401.507198 -174.905924)
		(width 0.2286)
		(layer "F.Cu")
		(net "PVDDCR_SOC_P0_VCC1")
	)
	(segment
		(start 400.86915 -175.796194)
		(end 401.149058 -175.516286)
		(width 0.2286)
		(layer "F.Cu")
		(net "PVDDCR_SOC_P0_VCC1")
	)
	(segment
		(start 400.224244 -175.796194)
		(end 400.86915 -175.796194)
		(width 0.2286)
		(layer "F.Cu")
		(net "PVDDCR_SOC_P0_VCC1")
	)
	(segment
		(start 401.149058 -175.516286)
		(end 401.507198 -175.516286)
		(width 0.2286)
		(layer "F.Cu")
		(net "PVDDCR_SOC_P0_VCC1")
	)
	(segment
		(start 398.01419 -174.271178)
		(end 398.01419 -173.559216)
		(width 0.2286)
		(layer "F.Cu")
		(net "PVDDCR_SOC_P0_VCC1")
	)
	(segment
		(start 398.01419 -173.559216)
		(end 398.089882 -173.483524)
		(width 0.2286)
		(layer "F.Cu")
		(net "PVDDCR_SOC_P0_VCC1")
	)
	(via
		(at 401.507198 -175.516286)
		(size 0.508)
		(drill 0.254)
		(layers "F.Cu" "B.Cu")
		(net "PVDDCR_SOC_P0_VCC1")
	)
	(via
		(at 398.089882 -173.483524)
		(size 0.508)
		(drill 0.254)
		(layers "F.Cu" "B.Cu")
		(net "PVDDCR_SOC_P0_VCC1")
	)
	(via
		(at 399.732246 -174.454566)
		(size 0.6604)
		(drill 0.3302)
		(layers "F.Cu" "B.Cu")
		(net "PVDDCR_SOC_P0_VCC1")
	)
	(segment
		(start 399.732246 -174.454566)
		(end 399.679668 -174.401988)
		(width 0.381)
		(layer "B.Cu")
		(net "PVDDCR_SOC_P0_VCC1")
	)
	(segment
		(start 399.679668 -174.401988)
		(end 399.679668 -174.296324)
		(width 0.381)
		(layer "B.Cu")
		(net "PVDDCR_SOC_P0_VCC1")
	)
	(segment
		(start 400.13509 -174.85741)
		(end 399.732246 -174.454566)
		(width 0.381)
		(layer "B.Cu")
		(net "PVDDCR_SOC_P0_VCC1")
	)
	(segment
		(start 399.366232 -173.982888)
		(end 398.589246 -173.982888)
		(width 0.508)
		(layer "B.Cu")
		(net "PVDDCR_SOC_P0_VCC1")
	)
	(segment
		(start 400.644868 -175.711866)
		(end 400.13509 -175.711866)
		(width 0.381)
		(layer "B.Cu")
		(net "PVDDCR_SOC_P0_VCC1")
	)
	(segment
		(start 398.589246 -173.982888)
		(end 398.089882 -173.483524)
		(width 0.508)
		(layer "B.Cu")
		(net "PVDDCR_SOC_P0_VCC1")
	)
	(segment
		(start 399.679668 -174.296324)
		(end 399.366232 -173.982888)
		(width 0.508)
		(layer "B.Cu")
		(net "PVDDCR_SOC_P0_VCC1")
	)
	(segment
		(start 400.840448 -175.516286)
		(end 400.644868 -175.711866)
		(width 0.381)
		(layer "B.Cu")
		(net "PVDDCR_SOC_P0_VCC1")
	)
	(segment
		(start 400.13509 -175.711866)
		(end 400.13509 -174.85741)
		(width 0.381)
		(layer "B.Cu")
		(net "PVDDCR_SOC_P0_VCC1")
	)
	(segment
		(start 401.507198 -175.516286)
		(end 400.840448 -175.516286)
		(width 0.381)
		(layer "B.Cu")
		(net "PVDDCR_SOC_P0_VCC1")
	)
	(segment
		(start 406.886664 -165.153594)
		(end 407.108914 -164.931344)
		(width 0.2286)
		(layer "F.Cu")
		(net "PVDDCR_SOC_P0_TEMP1")
	)
	(segment
		(start 415.169858 -160.867852)
		(end 415.169858 -160.577276)
		(width 0.2286)
		(layer "F.Cu")
		(net "PVDDCR_SOC_P0_TEMP1")
	)
	(segment
		(start 407.108914 -164.931344)
		(end 407.108914 -164.660326)
		(width 0.2286)
		(layer "F.Cu")
		(net "PVDDCR_SOC_P0_TEMP1")
	)
	(segment
		(start 398.785334 -173.50867)
		(end 398.785334 -173.237652)
		(width 0.2286)
		(layer "F.Cu")
		(net "PVDDCR_SOC_P0_TEMP1")
	)
	(segment
		(start 415.169858 -160.577276)
		(end 415.276538 -160.31972)
		(width 0.2286)
		(layer "F.Cu")
		(net "PVDDCR_SOC_P0_TEMP1")
	)
	(segment
		(start 415.490914 -160.105344)
		(end 415.490914 -159.834326)
		(width 0.2286)
		(layer "F.Cu")
		(net "PVDDCR_SOC_P0_TEMP1")
	)
	(segment
		(start 398.464278 -174.271178)
		(end 398.464278 -173.990254)
		(width 0.2286)
		(layer "F.Cu")
		(net "PVDDCR_SOC_P0_TEMP1")
	)
	(segment
		(start 406.787858 -165.693852)
		(end 406.787858 -165.3921)
		(width 0.2286)
		(layer "F.Cu")
		(net "PVDDCR_SOC_P0_TEMP1")
	)
	(segment
		(start 406.787858 -165.3921)
		(end 406.886664 -165.153594)
		(width 0.2286)
		(layer "F.Cu")
		(net "PVDDCR_SOC_P0_TEMP1")
	)
	(segment
		(start 398.577816 -173.716188)
		(end 398.785334 -173.50867)
		(width 0.2286)
		(layer "F.Cu")
		(net "PVDDCR_SOC_P0_TEMP1")
	)
	(segment
		(start 398.464278 -173.990254)
		(end 398.577816 -173.716188)
		(width 0.2286)
		(layer "F.Cu")
		(net "PVDDCR_SOC_P0_TEMP1")
	)
	(segment
		(start 415.276538 -160.31972)
		(end 415.490914 -160.105344)
		(width 0.2286)
		(layer "F.Cu")
		(net "PVDDCR_SOC_P0_TEMP1")
	)
	(via
		(at 415.490914 -159.834326)
		(size 0.508)
		(drill 0.254)
		(layers "F.Cu" "B.Cu")
		(net "PVDDCR_SOC_P0_TEMP1")
	)
	(via
		(at 398.785334 -173.237652)
		(size 0.508)
		(drill 0.254)
		(layers "F.Cu" "B.Cu")
		(net "PVDDCR_SOC_P0_TEMP1")
	)
	(via
		(at 407.108914 -164.660326)
		(size 0.508)
		(drill 0.254)
		(layers "F.Cu" "B.Cu")
		(net "PVDDCR_SOC_P0_TEMP1")
	)
	(via
		(at 383.103374 -142.08506)
		(size 0.508)
		(drill 0.254)
		(layers "F.Cu" "B.Cu")
		(net "PVDDCR_SOC_P0_TEMP1")
	)
	(segment
		(start 383.56413 -142.08506)
		(end 383.103374 -142.08506)
		(width 0.1524)
		(layer "B.Cu")
		(net "PVDDCR_SOC_P0_TEMP1")
	)
	(segment
		(start 383.713228 -142.234158)
		(end 383.56413 -142.08506)
		(width 0.1524)
		(layer "B.Cu")
		(net "PVDDCR_SOC_P0_TEMP1")
	)
	(segment
		(start 383.103374 -142.08506)
		(end 383.027174 -142.16126)
		(width 0.1524)
		(layer "B.Cu")
		(net "PVDDCR_SOC_P0_TEMP1")
	)
	(segment
		(start 383.027174 -142.16126)
		(end 381.273304 -142.16126)
		(width 0.1524)
		(layer "B.Cu")
		(net "PVDDCR_SOC_P0_TEMP1")
	)
	(segment
		(start 408.858212 -158.735776)
		(end 412.751016 -158.735776)
		(width 0.254)
		(layer "In2.Cu")
		(net "PVDDCR_SOC_P0_TEMP1")
	)
	(segment
		(start 415.490914 -160.315402)
		(end 415.490914 -159.834326)
		(width 0.254)
		(layer "In2.Cu")
		(net "PVDDCR_SOC_P0_TEMP1")
	)
	(segment
		(start 407.108914 -160.485074)
		(end 407.108914 -164.660326)
		(width 0.254)
		(layer "In2.Cu")
		(net "PVDDCR_SOC_P0_TEMP1")
	)
	(segment
		(start 400.247358 -167.992552)
		(end 400.247358 -162.328352)
		(width 0.254)
		(layer "In2.Cu")
		(net "PVDDCR_SOC_P0_TEMP1")
	)
	(segment
		(start 413.856678 -160.065974)
		(end 414.447228 -160.656524)
		(width 0.254)
		(layer "In2.Cu")
		(net "PVDDCR_SOC_P0_TEMP1")
	)
	(segment
		(start 398.785334 -168.790366)
		(end 398.821148 -168.754552)
		(width 0.254)
		(layer "In2.Cu")
		(net "PVDDCR_SOC_P0_TEMP1")
	)
	(segment
		(start 398.785334 -173.237652)
		(end 398.785334 -168.790366)
		(width 0.254)
		(layer "In2.Cu")
		(net "PVDDCR_SOC_P0_TEMP1")
	)
	(segment
		(start 383.316734 -142.08506)
		(end 384.320034 -143.08836)
		(width 0.254)
		(layer "In2.Cu")
		(net "PVDDCR_SOC_P0_TEMP1")
	)
	(segment
		(start 412.751016 -158.735776)
		(end 413.856678 -159.841438)
		(width 0.254)
		(layer "In2.Cu")
		(net "PVDDCR_SOC_P0_TEMP1")
	)
	(segment
		(start 394.583158 -157.469586)
		(end 394.583158 -164.58819)
		(width 0.254)
		(layer "In2.Cu")
		(net "PVDDCR_SOC_P0_TEMP1")
	)
	(segment
		(start 399.485358 -168.754552)
		(end 400.247358 -167.992552)
		(width 0.254)
		(layer "In2.Cu")
		(net "PVDDCR_SOC_P0_TEMP1")
	)
	(segment
		(start 384.320034 -147.206462)
		(end 394.583158 -157.469586)
		(width 0.254)
		(layer "In2.Cu")
		(net "PVDDCR_SOC_P0_TEMP1")
	)
	(segment
		(start 407.108914 -160.485074)
		(end 408.858212 -158.735776)
		(width 0.254)
		(layer "In2.Cu")
		(net "PVDDCR_SOC_P0_TEMP1")
	)
	(segment
		(start 400.247358 -162.328352)
		(end 402.090636 -160.485074)
		(width 0.254)
		(layer "In2.Cu")
		(net "PVDDCR_SOC_P0_TEMP1")
	)
	(segment
		(start 394.583158 -164.58819)
		(end 398.785334 -168.790366)
		(width 0.254)
		(layer "In2.Cu")
		(net "PVDDCR_SOC_P0_TEMP1")
	)
	(segment
		(start 384.320034 -143.08836)
		(end 384.320034 -147.206462)
		(width 0.254)
		(layer "In2.Cu")
		(net "PVDDCR_SOC_P0_TEMP1")
	)
	(segment
		(start 414.447228 -160.656524)
		(end 415.149792 -160.656524)
		(width 0.254)
		(layer "In2.Cu")
		(net "PVDDCR_SOC_P0_TEMP1")
	)
	(segment
		(start 398.821148 -168.754552)
		(end 399.485358 -168.754552)
		(width 0.254)
		(layer "In2.Cu")
		(net "PVDDCR_SOC_P0_TEMP1")
	)
	(segment
		(start 402.090636 -160.485074)
		(end 407.108914 -160.485074)
		(width 0.254)
		(layer "In2.Cu")
		(net "PVDDCR_SOC_P0_TEMP1")
	)
	(segment
		(start 383.103374 -142.08506)
		(end 383.316734 -142.08506)
		(width 0.254)
		(layer "In2.Cu")
		(net "PVDDCR_SOC_P0_TEMP1")
	)
	(segment
		(start 415.149792 -160.656524)
		(end 415.490914 -160.315402)
		(width 0.254)
		(layer "In2.Cu")
		(net "PVDDCR_SOC_P0_TEMP1")
	)
	(segment
		(start 413.856678 -159.841438)
		(end 413.856678 -160.065974)
		(width 0.254)
		(layer "In2.Cu")
		(net "PVDDCR_SOC_P0_TEMP1")
	)
	(segment
		(start 414.269682 -159.763206)
		(end 414.269682 -160.867852)
		(width 0.1778)
		(layer "F.Cu")
		(net "PVDDCR_SOC_P0_PWM3")
	)
	(segment
		(start 414.604962 -159.427926)
		(end 414.269682 -159.763206)
		(width 0.1778)
		(layer "F.Cu")
		(net "PVDDCR_SOC_P0_PWM3")
	)
	(via
		(at 414.604962 -159.427926)
		(size 0.508)
		(drill 0.254)
		(layers "F.Cu" "B.Cu")
		(net "PVDDCR_SOC_P0_PWM3")
	)
	(via
		(at 379.098556 -137.072878)
		(size 0.508)
		(drill 0.254)
		(layers "F.Cu" "B.Cu")
		(net "PVDDCR_SOC_P0_PWM3")
	)
	(segment
		(start 379.798326 -139.148566)
		(end 379.798326 -139.486132)
		(width 0.1524)
		(layer "B.Cu")
		(net "PVDDCR_SOC_P0_PWM3")
	)
	(segment
		(start 379.098556 -137.072878)
		(end 379.098556 -138.448796)
		(width 0.1524)
		(layer "B.Cu")
		(net "PVDDCR_SOC_P0_PWM3")
	)
	(segment
		(start 379.098556 -138.448796)
		(end 379.798326 -139.148566)
		(width 0.1524)
		(layer "B.Cu")
		(net "PVDDCR_SOC_P0_PWM3")
	)
	(segment
		(start 413.064198 -159.427926)
		(end 412.46044 -158.824168)
		(width 0.1524)
		(layer "In6.Cu")
		(net "PVDDCR_SOC_P0_PWM3")
	)
	(segment
		(start 390.469628 -144.031462)
		(end 390.469628 -138.760962)
		(width 0.1524)
		(layer "In6.Cu")
		(net "PVDDCR_SOC_P0_PWM3")
	)
	(segment
		(start 390.469628 -138.760962)
		(end 387.563614 -135.854948)
		(width 0.1524)
		(layer "In6.Cu")
		(net "PVDDCR_SOC_P0_PWM3")
	)
	(segment
		(start 405.262334 -158.824168)
		(end 397.095218 -150.657052)
		(width 0.1524)
		(layer "In6.Cu")
		(net "PVDDCR_SOC_P0_PWM3")
	)
	(segment
		(start 414.604962 -159.427926)
		(end 413.064198 -159.427926)
		(width 0.1524)
		(layer "In6.Cu")
		(net "PVDDCR_SOC_P0_PWM3")
	)
	(segment
		(start 392.561064 -148.92655)
		(end 392.561064 -146.122898)
		(width 0.1524)
		(layer "In6.Cu")
		(net "PVDDCR_SOC_P0_PWM3")
	)
	(segment
		(start 380.316486 -135.854948)
		(end 379.098556 -137.072878)
		(width 0.1524)
		(layer "In6.Cu")
		(net "PVDDCR_SOC_P0_PWM3")
	)
	(segment
		(start 412.46044 -158.824168)
		(end 405.262334 -158.824168)
		(width 0.1524)
		(layer "In6.Cu")
		(net "PVDDCR_SOC_P0_PWM3")
	)
	(segment
		(start 392.561064 -146.122898)
		(end 390.469628 -144.031462)
		(width 0.1524)
		(layer "In6.Cu")
		(net "PVDDCR_SOC_P0_PWM3")
	)
	(segment
		(start 387.563614 -135.854948)
		(end 380.316486 -135.854948)
		(width 0.1524)
		(layer "In6.Cu")
		(net "PVDDCR_SOC_P0_PWM3")
	)
	(segment
		(start 394.291566 -150.657052)
		(end 392.561064 -148.92655)
		(width 0.1524)
		(layer "In6.Cu")
		(net "PVDDCR_SOC_P0_PWM3")
	)
	(segment
		(start 397.095218 -150.657052)
		(end 394.291566 -150.657052)
		(width 0.1524)
		(layer "In6.Cu")
		(net "PVDDCR_SOC_P0_PWM3")
	)
	(segment
		(start 406.222962 -164.253926)
		(end 405.887682 -164.589206)
		(width 0.1778)
		(layer "F.Cu")
		(net "PVDDCR_SOC_P0_PWM2")
	)
	(segment
		(start 405.887682 -164.589206)
		(end 405.887682 -165.693852)
		(width 0.1778)
		(layer "F.Cu")
		(net "PVDDCR_SOC_P0_PWM2")
	)
	(via
		(at 406.222962 -164.253926)
		(size 0.508)
		(drill 0.254)
		(layers "F.Cu" "B.Cu")
		(net "PVDDCR_SOC_P0_PWM2")
	)
	(via
		(at 379.721618 -137.642092)
		(size 0.508)
		(drill 0.254)
		(layers "F.Cu" "B.Cu")
		(net "PVDDCR_SOC_P0_PWM2")
	)
	(segment
		(start 380.198376 -139.027662)
		(end 380.198376 -139.486132)
		(width 0.1524)
		(layer "B.Cu")
		(net "PVDDCR_SOC_P0_PWM2")
	)
	(segment
		(start 379.721618 -137.642092)
		(end 379.721618 -138.550904)
		(width 0.1524)
		(layer "B.Cu")
		(net "PVDDCR_SOC_P0_PWM2")
	)
	(segment
		(start 379.721618 -138.550904)
		(end 380.198376 -139.027662)
		(width 0.1524)
		(layer "B.Cu")
		(net "PVDDCR_SOC_P0_PWM2")
	)
	(segment
		(start 386.014214 -137.122408)
		(end 388.667498 -139.775692)
		(width 0.1524)
		(layer "In6.Cu")
		(net "PVDDCR_SOC_P0_PWM2")
	)
	(segment
		(start 405.881078 -161.626042)
		(end 405.881078 -163.912042)
		(width 0.1524)
		(layer "In6.Cu")
		(net "PVDDCR_SOC_P0_PWM2")
	)
	(segment
		(start 390.089644 -149.273006)
		(end 392.498326 -151.681688)
		(width 0.1524)
		(layer "In6.Cu")
		(net "PVDDCR_SOC_P0_PWM2")
	)
	(segment
		(start 392.498326 -151.681688)
		(end 395.936724 -151.681688)
		(width 0.1524)
		(layer "In6.Cu")
		(net "PVDDCR_SOC_P0_PWM2")
	)
	(segment
		(start 390.089644 -145.834608)
		(end 390.089644 -149.273006)
		(width 0.1524)
		(layer "In6.Cu")
		(net "PVDDCR_SOC_P0_PWM2")
	)
	(segment
		(start 379.721618 -137.642092)
		(end 380.241302 -137.122408)
		(width 0.1524)
		(layer "In6.Cu")
		(net "PVDDCR_SOC_P0_PWM2")
	)
	(segment
		(start 388.667498 -139.775692)
		(end 388.667498 -144.412462)
		(width 0.1524)
		(layer "In6.Cu")
		(net "PVDDCR_SOC_P0_PWM2")
	)
	(segment
		(start 405.881078 -163.912042)
		(end 406.222962 -164.253926)
		(width 0.1524)
		(layer "In6.Cu")
		(net "PVDDCR_SOC_P0_PWM2")
	)
	(segment
		(start 388.667498 -144.412462)
		(end 390.089644 -145.834608)
		(width 0.1524)
		(layer "In6.Cu")
		(net "PVDDCR_SOC_P0_PWM2")
	)
	(segment
		(start 380.241302 -137.122408)
		(end 386.014214 -137.122408)
		(width 0.1524)
		(layer "In6.Cu")
		(net "PVDDCR_SOC_P0_PWM2")
	)
	(segment
		(start 395.936724 -151.681688)
		(end 405.881078 -161.626042)
		(width 0.1524)
		(layer "In6.Cu")
		(net "PVDDCR_SOC_P0_PWM2")
	)
	(segment
		(start 397.899382 -172.831252)
		(end 397.564102 -173.166532)
		(width 0.1778)
		(layer "F.Cu")
		(net "PVDDCR_SOC_P0_PWM1")
	)
	(segment
		(start 397.564102 -173.166532)
		(end 397.564102 -174.271178)
		(width 0.1778)
		(layer "F.Cu")
		(net "PVDDCR_SOC_P0_PWM1")
	)
	(via
		(at 380.31674 -138.16584)
		(size 0.508)
		(drill 0.254)
		(layers "F.Cu" "B.Cu")
		(net "PVDDCR_SOC_P0_PWM1")
	)
	(via
		(at 397.899382 -172.831252)
		(size 0.508)
		(drill 0.254)
		(layers "F.Cu" "B.Cu")
		(net "PVDDCR_SOC_P0_PWM1")
	)
	(segment
		(start 380.31674 -138.16584)
		(end 380.598172 -138.447272)
		(width 0.1524)
		(layer "B.Cu")
		(net "PVDDCR_SOC_P0_PWM1")
	)
	(segment
		(start 380.598172 -138.447272)
		(end 380.598172 -139.486132)
		(width 0.1524)
		(layer "B.Cu")
		(net "PVDDCR_SOC_P0_PWM1")
	)
	(segment
		(start 387.25856 -147.769326)
		(end 392.474958 -152.985724)
		(width 0.1524)
		(layer "In6.Cu")
		(net "PVDDCR_SOC_P0_PWM1")
	)
	(segment
		(start 392.474958 -152.985724)
		(end 392.474958 -168.167558)
		(width 0.1524)
		(layer "In6.Cu")
		(net "PVDDCR_SOC_P0_PWM1")
	)
	(segment
		(start 380.819152 -137.663428)
		(end 385.009898 -137.663428)
		(width 0.1524)
		(layer "In6.Cu")
		(net "PVDDCR_SOC_P0_PWM1")
	)
	(segment
		(start 396.654528 -172.347128)
		(end 397.415258 -172.347128)
		(width 0.1524)
		(layer "In6.Cu")
		(net "PVDDCR_SOC_P0_PWM1")
	)
	(segment
		(start 397.415258 -172.347128)
		(end 397.899382 -172.831252)
		(width 0.1524)
		(layer "In6.Cu")
		(net "PVDDCR_SOC_P0_PWM1")
	)
	(segment
		(start 385.009898 -137.663428)
		(end 387.25856 -139.91209)
		(width 0.1524)
		(layer "In6.Cu")
		(net "PVDDCR_SOC_P0_PWM1")
	)
	(segment
		(start 387.25856 -139.91209)
		(end 387.25856 -147.769326)
		(width 0.1524)
		(layer "In6.Cu")
		(net "PVDDCR_SOC_P0_PWM1")
	)
	(segment
		(start 380.31674 -138.16584)
		(end 380.819152 -137.663428)
		(width 0.1524)
		(layer "In6.Cu")
		(net "PVDDCR_SOC_P0_PWM1")
	)
	(segment
		(start 392.474958 -168.167558)
		(end 396.654528 -172.347128)
		(width 0.1524)
		(layer "In6.Cu")
		(net "PVDDCR_SOC_P0_PWM1")
	)
	(segment
		(start 415.99231 -158.79826)
		(end 415.99231 -159.69361)
		(width 0.127)
		(layer "F.Cu")
		(net "PVDDCR_SOC_P0_LSET3")
	)
	(segment
		(start 415.99231 -160.089342)
		(end 415.619692 -160.46196)
		(width 0.127)
		(layer "F.Cu")
		(net "PVDDCR_SOC_P0_LSET3")
	)
	(segment
		(start 415.99231 -159.69361)
		(end 415.99231 -160.089342)
		(width 0.127)
		(layer "F.Cu")
		(net "PVDDCR_SOC_P0_LSET3")
	)
	(segment
		(start 416.234372 -158.556198)
		(end 415.99231 -158.79826)
		(width 0.127)
		(layer "F.Cu")
		(net "PVDDCR_SOC_P0_LSET3")
	)
	(segment
		(start 415.619692 -160.46196)
		(end 415.619692 -160.867852)
		(width 0.127)
		(layer "F.Cu")
		(net "PVDDCR_SOC_P0_LSET3")
	)
	(via
		(at 415.99231 -159.69361)
		(size 0.4064)
		(drill 0.2032)
		(layers "F.Cu" "B.Cu")
		(net "PVDDCR_SOC_P0_LSET3")
	)
	(segment
		(start 407.61031 -163.62426)
		(end 407.61031 -164.490654)
		(width 0.127)
		(layer "F.Cu")
		(net "PVDDCR_SOC_P0_LSET2")
	)
	(segment
		(start 407.237692 -165.693852)
		(end 407.237692 -165.28796)
		(width 0.127)
		(layer "F.Cu")
		(net "PVDDCR_SOC_P0_LSET2")
	)
	(segment
		(start 407.237692 -165.28796)
		(end 407.61031 -164.915342)
		(width 0.127)
		(layer "F.Cu")
		(net "PVDDCR_SOC_P0_LSET2")
	)
	(segment
		(start 407.852372 -163.382198)
		(end 407.61031 -163.62426)
		(width 0.127)
		(layer "F.Cu")
		(net "PVDDCR_SOC_P0_LSET2")
	)
	(segment
		(start 407.61031 -164.915342)
		(end 407.61031 -164.490654)
		(width 0.127)
		(layer "F.Cu")
		(net "PVDDCR_SOC_P0_LSET2")
	)
	(via
		(at 407.61031 -164.490654)
		(size 0.4064)
		(drill 0.2032)
		(layers "F.Cu" "B.Cu")
		(net "PVDDCR_SOC_P0_LSET2")
	)
	(segment
		(start 399.28673 -173.492668)
		(end 398.914112 -173.865286)
		(width 0.127)
		(layer "F.Cu")
		(net "PVDDCR_SOC_P0_LSET1")
	)
	(segment
		(start 399.28673 -172.201586)
		(end 399.28673 -173.101254)
		(width 0.127)
		(layer "F.Cu")
		(net "PVDDCR_SOC_P0_LSET1")
	)
	(segment
		(start 399.28673 -173.101254)
		(end 399.28673 -173.492668)
		(width 0.127)
		(layer "F.Cu")
		(net "PVDDCR_SOC_P0_LSET1")
	)
	(segment
		(start 398.914112 -173.865286)
		(end 398.914112 -174.271178)
		(width 0.127)
		(layer "F.Cu")
		(net "PVDDCR_SOC_P0_LSET1")
	)
	(segment
		(start 399.528792 -171.959524)
		(end 399.28673 -172.201586)
		(width 0.127)
		(layer "F.Cu")
		(net "PVDDCR_SOC_P0_LSET1")
	)
	(via
		(at 399.28673 -173.101254)
		(size 0.4064)
		(drill 0.2032)
		(layers "F.Cu" "B.Cu")
		(net "PVDDCR_SOC_P0_LSET1")
	)
	(segment
		(start 416.06978 -160.867852)
		(end 416.06978 -160.490916)
		(width 0.2286)
		(layer "F.Cu")
		(net "PVDDCR_SOC_P0_IMON3")
	)
	(segment
		(start 416.49523 -160.065466)
		(end 416.49523 -159.947356)
		(width 0.2286)
		(layer "F.Cu")
		(net "PVDDCR_SOC_P0_IMON3")
	)
	(segment
		(start 416.06978 -160.490916)
		(end 416.49523 -160.065466)
		(width 0.2286)
		(layer "F.Cu")
		(net "PVDDCR_SOC_P0_IMON3")
	)
	(via
		(at 416.49523 -159.947356)
		(size 0.508)
		(drill 0.254)
		(layers "F.Cu" "B.Cu")
		(net "PVDDCR_SOC_P0_IMON3")
	)
	(via
		(at 381.462534 -146.726656)
		(size 0.508)
		(drill 0.254)
		(layers "F.Cu" "B.Cu")
		(net "PVDDCR_SOC_P0_IMON3")
	)
	(segment
		(start 380.815342 -146.079464)
		(end 380.598172 -145.555208)
		(width 0.1778)
		(layer "B.Cu")
		(net "PVDDCR_SOC_P0_IMON3")
	)
	(segment
		(start 380.598172 -145.555208)
		(end 380.598172 -145.236184)
		(width 0.1778)
		(layer "B.Cu")
		(net "PVDDCR_SOC_P0_IMON3")
	)
	(segment
		(start 381.462534 -146.726656)
		(end 380.815342 -146.079464)
		(width 0.254)
		(layer "B.Cu")
		(net "PVDDCR_SOC_P0_IMON3")
	)
	(segment
		(start 395.762734 -157.685232)
		(end 385.066794 -146.989292)
		(width 0.254)
		(layer "In11.Cu")
		(net "PVDDCR_SOC_P0_IMON3")
	)
	(segment
		(start 416.105848 -157.685232)
		(end 395.762734 -157.685232)
		(width 0.254)
		(layer "In11.Cu")
		(net "PVDDCR_SOC_P0_IMON3")
	)
	(segment
		(start 385.066794 -146.989292)
		(end 381.72517 -146.989292)
		(width 0.254)
		(layer "In11.Cu")
		(net "PVDDCR_SOC_P0_IMON3")
	)
	(segment
		(start 416.644074 -159.947356)
		(end 417.036758 -159.554672)
		(width 0.254)
		(layer "In11.Cu")
		(net "PVDDCR_SOC_P0_IMON3")
	)
	(segment
		(start 417.036758 -158.616142)
		(end 416.105848 -157.685232)
		(width 0.254)
		(layer "In11.Cu")
		(net "PVDDCR_SOC_P0_IMON3")
	)
	(segment
		(start 417.036758 -159.554672)
		(end 417.036758 -158.616142)
		(width 0.254)
		(layer "In11.Cu")
		(net "PVDDCR_SOC_P0_IMON3")
	)
	(segment
		(start 416.49523 -159.947356)
		(end 416.644074 -159.947356)
		(width 0.254)
		(layer "In11.Cu")
		(net "PVDDCR_SOC_P0_IMON3")
	)
	(segment
		(start 381.72517 -146.989292)
		(end 381.462534 -146.726656)
		(width 0.254)
		(layer "In11.Cu")
		(net "PVDDCR_SOC_P0_IMON3")
	)
	(segment
		(start 407.68778 -165.317932)
		(end 408.124914 -164.880798)
		(width 0.2286)
		(layer "F.Cu")
		(net "PVDDCR_SOC_P0_IMON2")
	)
	(segment
		(start 407.68778 -165.693852)
		(end 407.68778 -165.317932)
		(width 0.2286)
		(layer "F.Cu")
		(net "PVDDCR_SOC_P0_IMON2")
	)
	(segment
		(start 408.124914 -164.773356)
		(end 408.11323 -164.773356)
		(width 0.2286)
		(layer "F.Cu")
		(net "PVDDCR_SOC_P0_IMON2")
	)
	(segment
		(start 408.124914 -164.880798)
		(end 408.124914 -164.773356)
		(width 0.2286)
		(layer "F.Cu")
		(net "PVDDCR_SOC_P0_IMON2")
	)
	(via
		(at 381.700278 -145.028158)
		(size 0.762)
		(drill 0.254)
		(layers "F.Cu" "B.Cu")
		(net "PVDDCR_SOC_P0_IMON2")
	)
	(via
		(at 408.11323 -164.773356)
		(size 0.508)
		(drill 0.254)
		(layers "F.Cu" "B.Cu")
		(net "PVDDCR_SOC_P0_IMON2")
	)
	(segment
		(start 381.522478 -144.561052)
		(end 381.273304 -144.561052)
		(width 0.1778)
		(layer "B.Cu")
		(net "PVDDCR_SOC_P0_IMON2")
	)
	(segment
		(start 381.700278 -145.028158)
		(end 381.700278 -144.738852)
		(width 0.254)
		(layer "B.Cu")
		(net "PVDDCR_SOC_P0_IMON2")
	)
	(segment
		(start 381.700278 -144.738852)
		(end 381.522478 -144.561052)
		(width 0.1778)
		(layer "B.Cu")
		(net "PVDDCR_SOC_P0_IMON2")
	)
	(segment
		(start 408.702764 -164.30117)
		(end 408.2415 -164.762434)
		(width 0.254)
		(layer "In4.Cu")
		(net "PVDDCR_SOC_P0_IMON2")
	)
	(segment
		(start 408.713686 -163.72205)
		(end 408.713686 -164.27577)
		(width 0.254)
		(layer "In4.Cu")
		(net "PVDDCR_SOC_P0_IMON2")
	)
	(segment
		(start 395.453108 -146.97075)
		(end 395.453108 -150.461472)
		(width 0.254)
		(layer "In4.Cu")
		(net "PVDDCR_SOC_P0_IMON2")
	)
	(segment
		(start 395.453108 -150.461472)
		(end 408.713686 -163.72205)
		(width 0.254)
		(layer "In4.Cu")
		(net "PVDDCR_SOC_P0_IMON2")
	)
	(segment
		(start 381.709422 -145.019014)
		(end 385.224782 -145.019014)
		(width 0.254)
		(layer "In4.Cu")
		(net "PVDDCR_SOC_P0_IMON2")
	)
	(segment
		(start 381.700278 -145.028158)
		(end 381.709422 -145.019014)
		(width 0.254)
		(layer "In4.Cu")
		(net "PVDDCR_SOC_P0_IMON2")
	)
	(segment
		(start 385.224782 -145.019014)
		(end 386.171948 -145.96618)
		(width 0.254)
		(layer "In4.Cu")
		(net "PVDDCR_SOC_P0_IMON2")
	)
	(segment
		(start 408.713686 -164.27577)
		(end 408.712162 -164.289486)
		(width 0.254)
		(layer "In4.Cu")
		(net "PVDDCR_SOC_P0_IMON2")
	)
	(segment
		(start 386.171948 -145.96618)
		(end 394.448538 -145.96618)
		(width 0.254)
		(layer "In4.Cu")
		(net "PVDDCR_SOC_P0_IMON2")
	)
	(segment
		(start 408.712162 -164.289486)
		(end 408.702764 -164.30117)
		(width 0.254)
		(layer "In4.Cu")
		(net "PVDDCR_SOC_P0_IMON2")
	)
	(segment
		(start 394.448538 -145.96618)
		(end 395.453108 -146.97075)
		(width 0.254)
		(layer "In4.Cu")
		(net "PVDDCR_SOC_P0_IMON2")
	)
	(segment
		(start 408.2415 -164.762434)
		(end 408.229816 -164.771832)
		(width 0.254)
		(layer "In4.Cu")
		(net "PVDDCR_SOC_P0_IMON2")
	)
	(segment
		(start 408.214576 -164.773356)
		(end 408.11323 -164.773356)
		(width 0.254)
		(layer "In4.Cu")
		(net "PVDDCR_SOC_P0_IMON2")
	)
	(segment
		(start 408.229816 -164.771832)
		(end 408.214576 -164.773356)
		(width 0.254)
		(layer "In4.Cu")
		(net "PVDDCR_SOC_P0_IMON2")
	)
	(segment
		(start 399.3642 -174.271178)
		(end 399.3642 -173.895258)
		(width 0.2286)
		(layer "F.Cu")
		(net "PVDDCR_SOC_P0_IMON1")
	)
	(segment
		(start 399.3642 -173.895258)
		(end 399.801334 -173.458124)
		(width 0.2286)
		(layer "F.Cu")
		(net "PVDDCR_SOC_P0_IMON1")
	)
	(segment
		(start 399.801334 -173.458124)
		(end 399.801334 -173.350682)
		(width 0.2286)
		(layer "F.Cu")
		(net "PVDDCR_SOC_P0_IMON1")
	)
	(segment
		(start 399.801334 -173.350682)
		(end 399.78965 -173.350682)
		(width 0.2286)
		(layer "F.Cu")
		(net "PVDDCR_SOC_P0_IMON1")
	)
	(via
		(at 399.78965 -173.350682)
		(size 0.508)
		(drill 0.254)
		(layers "F.Cu" "B.Cu")
		(net "PVDDCR_SOC_P0_IMON1")
	)
	(via
		(at 383.478278 -146.171158)
		(size 0.508)
		(drill 0.254)
		(layers "F.Cu" "B.Cu")
		(net "PVDDCR_SOC_P0_IMON1")
	)
	(segment
		(start 381.722376 -144.161256)
		(end 381.273304 -144.161256)
		(width 0.1778)
		(layer "B.Cu")
		(net "PVDDCR_SOC_P0_IMON1")
	)
	(segment
		(start 382.566418 -145.005298)
		(end 381.722376 -144.161256)
		(width 0.1778)
		(layer "B.Cu")
		(net "PVDDCR_SOC_P0_IMON1")
	)
	(segment
		(start 382.566418 -145.739612)
		(end 382.566418 -145.005298)
		(width 0.1778)
		(layer "B.Cu")
		(net "PVDDCR_SOC_P0_IMON1")
	)
	(segment
		(start 383.478278 -146.171158)
		(end 382.997964 -146.171158)
		(width 0.1778)
		(layer "B.Cu")
		(net "PVDDCR_SOC_P0_IMON1")
	)
	(segment
		(start 382.997964 -146.171158)
		(end 382.566418 -145.739612)
		(width 0.1778)
		(layer "B.Cu")
		(net "PVDDCR_SOC_P0_IMON1")
	)
	(segment
		(start 399.906998 -173.350682)
		(end 400.390106 -172.867574)
		(width 0.254)
		(layer "In4.Cu")
		(net "PVDDCR_SOC_P0_IMON1")
	)
	(segment
		(start 384.037078 -146.171158)
		(end 383.478278 -146.171158)
		(width 0.254)
		(layer "In4.Cu")
		(net "PVDDCR_SOC_P0_IMON1")
	)
	(segment
		(start 399.87982 -158.216346)
		(end 390.63168 -148.968206)
		(width 0.254)
		(layer "In4.Cu")
		(net "PVDDCR_SOC_P0_IMON1")
	)
	(segment
		(start 399.87982 -171.46651)
		(end 399.87982 -158.216346)
		(width 0.254)
		(layer "In4.Cu")
		(net "PVDDCR_SOC_P0_IMON1")
	)
	(segment
		(start 390.63168 -148.968206)
		(end 386.834126 -148.968206)
		(width 0.254)
		(layer "In4.Cu")
		(net "PVDDCR_SOC_P0_IMON1")
	)
	(segment
		(start 400.390106 -171.976796)
		(end 399.87982 -171.46651)
		(width 0.254)
		(layer "In4.Cu")
		(net "PVDDCR_SOC_P0_IMON1")
	)
	(segment
		(start 399.78965 -173.350682)
		(end 399.906998 -173.350682)
		(width 0.254)
		(layer "In4.Cu")
		(net "PVDDCR_SOC_P0_IMON1")
	)
	(segment
		(start 400.390106 -172.867574)
		(end 400.390106 -171.976796)
		(width 0.254)
		(layer "In4.Cu")
		(net "PVDDCR_SOC_P0_IMON1")
	)
	(segment
		(start 386.834126 -148.968206)
		(end 384.037078 -146.171158)
		(width 0.254)
		(layer "In4.Cu")
		(net "PVDDCR_SOC_P0_IMON1")
	)
	(via
		(at 369.205256 -136.615424)
		(size 0.6604)
		(drill 0.3302)
		(layers "F.Cu" "B.Cu")
		(net "PVDDCR_SOC_P0_EN_RC")
	)
	(segment
		(start 368.071908 -135.970772)
		(end 369.040156 -135.970772)
		(width 0.10668)
		(layer "B.Cu")
		(net "PVDDCR_SOC_P0_EN_RC")
	)
	(segment
		(start 368.545618 -138.680698)
		(end 368.071908 -138.206988)
		(width 0.10668)
		(layer "B.Cu")
		(net "PVDDCR_SOC_P0_EN_RC")
	)
	(segment
		(start 369.040156 -135.970772)
		(end 369.205256 -136.135872)
		(width 0.10668)
		(layer "B.Cu")
		(net "PVDDCR_SOC_P0_EN_RC")
	)
	(segment
		(start 368.071908 -138.206988)
		(end 368.071908 -136.986772)
		(width 0.10668)
		(layer "B.Cu")
		(net "PVDDCR_SOC_P0_EN_RC")
	)
	(segment
		(start 368.084862 -136.973818)
		(end 368.846862 -136.973818)
		(width 0.10668)
		(layer "B.Cu")
		(net "PVDDCR_SOC_P0_EN_RC")
	)
	(segment
		(start 369.205256 -136.135872)
		(end 369.205256 -136.615424)
		(width 0.10668)
		(layer "B.Cu")
		(net "PVDDCR_SOC_P0_EN_RC")
	)
	(segment
		(start 368.846862 -136.973818)
		(end 369.205256 -136.615424)
		(width 0.10668)
		(layer "B.Cu")
		(net "PVDDCR_SOC_P0_EN_RC")
	)
	(segment
		(start 368.071908 -136.986772)
		(end 368.084862 -136.973818)
		(width 0.10668)
		(layer "B.Cu")
		(net "PVDDCR_SOC_P0_EN_RC")
	)
	(segment
		(start 368.071908 -134.954772)
		(end 368.071908 -135.970772)
		(width 0.10668)
		(layer "B.Cu")
		(net "PVDDCR_SOC_P0_EN_RC")
	)
	(via
		(at 369.106958 -143.047212)
		(size 0.6604)
		(drill 0.3302)
		(layers "F.Cu" "B.Cu")
		(net "PVDDCR_SOC_P0_EN_GD")
	)
	(segment
		(start 367.944908 -141.230096)
		(end 367.944908 -142.574772)
		(width 0.10668)
		(layer "B.Cu")
		(net "PVDDCR_SOC_P0_EN_GD")
	)
	(segment
		(start 367.595658 -140.880846)
		(end 367.944908 -141.230096)
		(width 0.10668)
		(layer "B.Cu")
		(net "PVDDCR_SOC_P0_EN_GD")
	)
	(segment
		(start 369.106958 -143.934434)
		(end 368.545618 -144.495774)
		(width 0.10668)
		(layer "B.Cu")
		(net "PVDDCR_SOC_P0_EN_GD")
	)
	(segment
		(start 369.000278 -142.574772)
		(end 369.106958 -142.681452)
		(width 0.10668)
		(layer "B.Cu")
		(net "PVDDCR_SOC_P0_EN_GD")
	)
	(segment
		(start 369.106958 -142.681452)
		(end 369.106958 -143.047212)
		(width 0.10668)
		(layer "B.Cu")
		(net "PVDDCR_SOC_P0_EN_GD")
	)
	(segment
		(start 369.106958 -143.047212)
		(end 369.106958 -143.934434)
		(width 0.10668)
		(layer "B.Cu")
		(net "PVDDCR_SOC_P0_EN_GD")
	)
	(segment
		(start 367.944908 -142.574772)
		(end 369.000278 -142.574772)
		(width 0.10668)
		(layer "B.Cu")
		(net "PVDDCR_SOC_P0_EN_GD")
	)
	(segment
		(start 381.998728 -142.665958)
		(end 382.609598 -142.665958)
		(width 0.10668)
		(layer "F.Cu")
		(net "PVDDCR_SOC_P0_EN//ADDR_CFG")
	)
	(via
		(at 366.242092 -146.49577)
		(size 0.762)
		(drill 0.254)
		(layers "F.Cu" "B.Cu")
		(net "PVDDCR_SOC_P0_EN//ADDR_CFG")
	)
	(via
		(at 382.609598 -142.665958)
		(size 0.508)
		(drill 0.254)
		(layers "F.Cu" "B.Cu")
		(net "PVDDCR_SOC_P0_EN//ADDR_CFG")
	)
	(segment
		(start 367.595658 -146.49577)
		(end 366.242092 -146.49577)
		(width 0.10668)
		(layer "B.Cu")
		(net "PVDDCR_SOC_P0_EN//ADDR_CFG")
	)
	(segment
		(start 381.273304 -142.561056)
		(end 382.504696 -142.561056)
		(width 0.10668)
		(layer "B.Cu")
		(net "PVDDCR_SOC_P0_EN//ADDR_CFG")
	)
	(segment
		(start 382.504696 -142.561056)
		(end 382.609598 -142.665958)
		(width 0.10668)
		(layer "B.Cu")
		(net "PVDDCR_SOC_P0_EN//ADDR_CFG")
	)
	(segment
		(start 381.466598 -150.230586)
		(end 369.976908 -150.230586)
		(width 0.11684)
		(layer "In15.Cu")
		(net "PVDDCR_SOC_P0_EN//ADDR_CFG")
	)
	(segment
		(start 382.609598 -144.68856)
		(end 382.609598 -149.087586)
		(width 0.11684)
		(layer "In15.Cu")
		(net "PVDDCR_SOC_P0_EN//ADDR_CFG")
	)
	(segment
		(start 369.976908 -150.230586)
		(end 366.242092 -146.49577)
		(width 0.11684)
		(layer "In15.Cu")
		(net "PVDDCR_SOC_P0_EN//ADDR_CFG")
	)
	(segment
		(start 382.609598 -142.665958)
		(end 382.1176 -143.157956)
		(width 0.11684)
		(layer "In15.Cu")
		(net "PVDDCR_SOC_P0_EN//ADDR_CFG")
	)
	(segment
		(start 382.1176 -144.196562)
		(end 382.609598 -144.68856)
		(width 0.11684)
		(layer "In15.Cu")
		(net "PVDDCR_SOC_P0_EN//ADDR_CFG")
	)
	(segment
		(start 382.609598 -149.087586)
		(end 381.466598 -150.230586)
		(width 0.11684)
		(layer "In15.Cu")
		(net "PVDDCR_SOC_P0_EN//ADDR_CFG")
	)
	(segment
		(start 382.1176 -143.157956)
		(end 382.1176 -144.196562)
		(width 0.11684)
		(layer "In15.Cu")
		(net "PVDDCR_SOC_P0_EN//ADDR_CFG")
	)
	(segment
		(start 191.522096 -108.252768)
		(end 191.911986 -107.862878)
		(width 0.10668)
		(layer "F.Cu")
		(net "PVDDCR_SOC_P0_EN")
	)
	(via
		(at 260.56082 -114.051588)
		(size 0.508)
		(drill 0.254)
		(layers "F.Cu" "B.Cu")
		(net "PVDDCR_SOC_P0_EN")
	)
	(via
		(at 191.911986 -107.862878)
		(size 0.4572)
		(drill 0.254)
		(layers "F.Cu" "B.Cu")
		(net "PVDDCR_SOC_P0_EN")
	)
	(via
		(at 358.394 -116.931948)
		(size 0.508)
		(drill 0.254)
		(layers "F.Cu" "B.Cu")
		(net "PVDDCR_SOC_P0_EN")
	)
	(segment
		(start 367.271808 -125.809756)
		(end 358.394 -116.931948)
		(width 0.10668)
		(layer "B.Cu")
		(net "PVDDCR_SOC_P0_EN")
	)
	(segment
		(start 367.271808 -134.954772)
		(end 367.271808 -125.809756)
		(width 0.10668)
		(layer "B.Cu")
		(net "PVDDCR_SOC_P0_EN")
	)
	(segment
		(start 192.319656 -107.455208)
		(end 192.97904 -107.455208)
		(width 0.11684)
		(layer "In2.Cu")
		(net "PVDDCR_SOC_P0_EN")
	)
	(segment
		(start 198.172578 -104.905048)
		(end 204.216 -104.905048)
		(width 0.11684)
		(layer "In2.Cu")
		(net "PVDDCR_SOC_P0_EN")
	)
	(segment
		(start 195.223384 -105.997756)
		(end 197.07987 -105.997756)
		(width 0.11684)
		(layer "In2.Cu")
		(net "PVDDCR_SOC_P0_EN")
	)
	(segment
		(start 252.54331 -111.90224)
		(end 254.692658 -114.051588)
		(width 0.11684)
		(layer "In2.Cu")
		(net "PVDDCR_SOC_P0_EN")
	)
	(segment
		(start 204.216 -104.905048)
		(end 205.494636 -106.183684)
		(width 0.11684)
		(layer "In2.Cu")
		(net "PVDDCR_SOC_P0_EN")
	)
	(segment
		(start 208.886044 -108.579412)
		(end 212.874098 -108.579412)
		(width 0.11684)
		(layer "In2.Cu")
		(net "PVDDCR_SOC_P0_EN")
	)
	(segment
		(start 205.494636 -106.183684)
		(end 206.490316 -106.183684)
		(width 0.11684)
		(layer "In2.Cu")
		(net "PVDDCR_SOC_P0_EN")
	)
	(segment
		(start 197.07987 -105.997756)
		(end 198.172578 -104.905048)
		(width 0.11684)
		(layer "In2.Cu")
		(net "PVDDCR_SOC_P0_EN")
	)
	(segment
		(start 192.97904 -107.455208)
		(end 193.433954 -107.000294)
		(width 0.11684)
		(layer "In2.Cu")
		(net "PVDDCR_SOC_P0_EN")
	)
	(segment
		(start 206.490316 -106.183684)
		(end 208.886044 -108.579412)
		(width 0.11684)
		(layer "In2.Cu")
		(net "PVDDCR_SOC_P0_EN")
	)
	(segment
		(start 193.433954 -107.000294)
		(end 194.220846 -107.000294)
		(width 0.11684)
		(layer "In2.Cu")
		(net "PVDDCR_SOC_P0_EN")
	)
	(segment
		(start 191.911986 -107.862878)
		(end 192.319656 -107.455208)
		(width 0.11684)
		(layer "In2.Cu")
		(net "PVDDCR_SOC_P0_EN")
	)
	(segment
		(start 254.692658 -114.051588)
		(end 260.56082 -114.051588)
		(width 0.11684)
		(layer "In2.Cu")
		(net "PVDDCR_SOC_P0_EN")
	)
	(segment
		(start 216.196926 -111.90224)
		(end 252.54331 -111.90224)
		(width 0.11684)
		(layer "In2.Cu")
		(net "PVDDCR_SOC_P0_EN")
	)
	(segment
		(start 194.220846 -107.000294)
		(end 195.223384 -105.997756)
		(width 0.11684)
		(layer "In2.Cu")
		(net "PVDDCR_SOC_P0_EN")
	)
	(segment
		(start 212.874098 -108.579412)
		(end 216.196926 -111.90224)
		(width 0.11684)
		(layer "In2.Cu")
		(net "PVDDCR_SOC_P0_EN")
	)
	(segment
		(start 305.34102 -120.023128)
		(end 307.303424 -118.060724)
		(width 0.11684)
		(layer "In6.Cu")
		(net "PVDDCR_SOC_P0_EN")
	)
	(segment
		(start 319.630806 -117.314218)
		(end 358.01173 -117.314218)
		(width 0.11684)
		(layer "In6.Cu")
		(net "PVDDCR_SOC_P0_EN")
	)
	(segment
		(start 307.303424 -118.060724)
		(end 318.8843 -118.060724)
		(width 0.11684)
		(layer "In6.Cu")
		(net "PVDDCR_SOC_P0_EN")
	)
	(segment
		(start 318.8843 -118.060724)
		(end 319.630806 -117.314218)
		(width 0.11684)
		(layer "In6.Cu")
		(net "PVDDCR_SOC_P0_EN")
	)
	(segment
		(start 260.796786 -114.287554)
		(end 268.037564 -114.287554)
		(width 0.11684)
		(layer "In6.Cu")
		(net "PVDDCR_SOC_P0_EN")
	)
	(segment
		(start 279.817322 -115.372388)
		(end 280.096722 -115.092988)
		(width 0.11684)
		(layer "In6.Cu")
		(net "PVDDCR_SOC_P0_EN")
	)
	(segment
		(start 269.122398 -115.372388)
		(end 279.817322 -115.372388)
		(width 0.11684)
		(layer "In6.Cu")
		(net "PVDDCR_SOC_P0_EN")
	)
	(segment
		(start 268.037564 -114.287554)
		(end 269.122398 -115.372388)
		(width 0.11684)
		(layer "In6.Cu")
		(net "PVDDCR_SOC_P0_EN")
	)
	(segment
		(start 282.66136 -115.545108)
		(end 293.04488 -115.545108)
		(width 0.11684)
		(layer "In6.Cu")
		(net "PVDDCR_SOC_P0_EN")
	)
	(segment
		(start 297.5229 -120.023128)
		(end 305.34102 -120.023128)
		(width 0.11684)
		(layer "In6.Cu")
		(net "PVDDCR_SOC_P0_EN")
	)
	(segment
		(start 293.04488 -115.545108)
		(end 297.5229 -120.023128)
		(width 0.11684)
		(layer "In6.Cu")
		(net "PVDDCR_SOC_P0_EN")
	)
	(segment
		(start 260.56082 -114.051588)
		(end 260.796786 -114.287554)
		(width 0.11684)
		(layer "In6.Cu")
		(net "PVDDCR_SOC_P0_EN")
	)
	(segment
		(start 282.20924 -115.092988)
		(end 282.66136 -115.545108)
		(width 0.11684)
		(layer "In6.Cu")
		(net "PVDDCR_SOC_P0_EN")
	)
	(segment
		(start 358.01173 -117.314218)
		(end 358.394 -116.931948)
		(width 0.11684)
		(layer "In6.Cu")
		(net "PVDDCR_SOC_P0_EN")
	)
	(segment
		(start 280.096722 -115.092988)
		(end 282.20924 -115.092988)
		(width 0.11684)
		(layer "In6.Cu")
		(net "PVDDCR_SOC_P0_EN")
	)
	(segment
		(start 374.28805 -238.270034)
		(end 374.754902 -238.004096)
		(width 0.350012)
		(layer "F.Cu")
		(net "PVDDCR_SOC_P0")
	)
	(segment
		(start 372.238016 -260.860032)
		(end 372.704868 -261.12597)
		(width 0.350012)
		(layer "F.Cu")
		(net "PVDDCR_SOC_P0")
	)
	(segment
		(start 384.627882 -235.03001)
		(end 385.094734 -234.764072)
		(width 0.350012)
		(layer "F.Cu")
		(net "PVDDCR_SOC_P0")
	)
	(segment
		(start 384.157982 -256.900172)
		(end 384.624834 -256.634234)
		(width 0.350012)
		(layer "F.Cu")
		(net "PVDDCR_SOC_P0")
	)
	(segment
		(start 374.588024 -261.670038)
		(end 375.054876 -261.935976)
		(width 0.350012)
		(layer "F.Cu")
		(net "PVDDCR_SOC_P0")
	)
	(segment
		(start 377.577858 -256.900172)
		(end 378.04471 -256.634234)
		(width 0.350012)
		(layer "F.Cu")
		(net "PVDDCR_SOC_P0")
	)
	(segment
		(start 378.048012 -249.610118)
		(end 378.514864 -249.34418)
		(width 0.350012)
		(layer "F.Cu")
		(net "PVDDCR_SOC_P0")
	)
	(segment
		(start 384.157982 -237.460028)
		(end 384.624834 -237.19409)
		(width 0.350012)
		(layer "F.Cu")
		(net "PVDDCR_SOC_P0")
	)
	(segment
		(start 384.157982 -232.599992)
		(end 384.624834 -232.334054)
		(width 0.350012)
		(layer "F.Cu")
		(net "PVDDCR_SOC_P0")
	)
	(segment
		(start 374.75795 -240.700052)
		(end 375.224802 -240.434114)
		(width 0.350012)
		(layer "F.Cu")
		(net "PVDDCR_SOC_P0")
	)
	(segment
		(start 373.347996 -251.23013)
		(end 373.814848 -250.964192)
		(width 0.350012)
		(layer "F.Cu")
		(net "PVDDCR_SOC_P0")
	)
	(segment
		(start 356.89794 -252.040136)
		(end 356.431088 -251.774198)
		(width 0.350012)
		(layer "F.Cu")
		(net "PVDDCR_SOC_P0")
	)
	(segment
		(start 391.208006 -254.470154)
		(end 391.674858 -254.204216)
		(width 0.350012)
		(layer "F.Cu")
		(net "PVDDCR_SOC_P0")
	)
	(segment
		(start 369.11788 -252.040136)
		(end 369.584732 -251.774198)
		(width 0.350012)
		(layer "F.Cu")
		(net "PVDDCR_SOC_P0")
	)
	(segment
		(start 419.597586 -176.738788)
		(end 420.64813 -176.738788)
		(width 0.254)
		(layer "F.Cu")
		(net "PVDDCR_SOC_P0")
	)
	(segment
		(start 377.577858 -232.599992)
		(end 378.04471 -232.334054)
		(width 0.350012)
		(layer "F.Cu")
		(net "PVDDCR_SOC_P0")
	)
	(segment
		(start 384.627882 -244.750082)
		(end 385.094734 -244.484144)
		(width 0.350012)
		(layer "F.Cu")
		(net "PVDDCR_SOC_P0")
	)
	(segment
		(start 362.067856 -251.23013)
		(end 362.534708 -250.964192)
		(width 0.350012)
		(layer "F.Cu")
		(net "PVDDCR_SOC_P0")
	)
	(segment
		(start 372.877842 -253.660148)
		(end 373.344694 -253.39421)
		(width 0.350012)
		(layer "F.Cu")
		(net "PVDDCR_SOC_P0")
	)
	(segment
		(start 369.588034 -251.23013)
		(end 370.054886 -250.964192)
		(width 0.350012)
		(layer "F.Cu")
		(net "PVDDCR_SOC_P0")
	)
	(segment
		(start 390.737852 -247.1801)
		(end 391.204704 -246.914162)
		(width 0.350012)
		(layer "F.Cu")
		(net "PVDDCR_SOC_P0")
	)
	(segment
		(start 390.737852 -237.460028)
		(end 391.204704 -237.19409)
		(width 0.350012)
		(layer "F.Cu")
		(net "PVDDCR_SOC_P0")
	)
	(segment
		(start 391.208006 -225.310192)
		(end 391.674858 -225.044254)
		(width 0.350012)
		(layer "F.Cu")
		(net "PVDDCR_SOC_P0")
	)
	(segment
		(start 365.357918 -252.040136)
		(end 365.82477 -251.774198)
		(width 0.350012)
		(layer "F.Cu")
		(net "PVDDCR_SOC_P0")
	)
	(segment
		(start 372.238016 -262.480044)
		(end 372.704868 -262.745982)
		(width 0.350012)
		(layer "F.Cu")
		(net "PVDDCR_SOC_P0")
	)
	(segment
		(start 391.208006 -223.69018)
		(end 391.674858 -223.424242)
		(width 0.350012)
		(layer "F.Cu")
		(net "PVDDCR_SOC_P0")
	)
	(segment
		(start 384.627882 -254.470154)
		(end 385.094734 -254.204216)
		(width 0.350012)
		(layer "F.Cu")
		(net "PVDDCR_SOC_P0")
	)
	(segment
		(start 378.048012 -230.169974)
		(end 378.514864 -229.904036)
		(width 0.350012)
		(layer "F.Cu")
		(net "PVDDCR_SOC_P0")
	)
	(segment
		(start 390.737852 -227.74021)
		(end 391.204704 -227.474272)
		(width 0.350012)
		(layer "F.Cu")
		(net "PVDDCR_SOC_P0")
	)
	(segment
		(start 365.828072 -251.23013)
		(end 366.294924 -250.964192)
		(width 0.350012)
		(layer "F.Cu")
		(net "PVDDCR_SOC_P0")
	)
	(segment
		(start 373.347996 -252.850142)
		(end 373.814848 -252.584204)
		(width 0.350012)
		(layer "F.Cu")
		(net "PVDDCR_SOC_P0")
	)
	(segment
		(start 349.378016 -253.660148)
		(end 348.911164 -253.39421)
		(width 0.350012)
		(layer "F.Cu")
		(net "PVDDCR_SOC_P0")
	)
	(segment
		(start 374.75795 -247.1801)
		(end 375.224802 -246.914162)
		(width 0.350012)
		(layer "F.Cu")
		(net "PVDDCR_SOC_P0")
	)
	(segment
		(start 391.50798 -263.29005)
		(end 391.974832 -263.555988)
		(width 0.350012)
		(layer "F.Cu")
		(net "PVDDCR_SOC_P0")
	)
	(segment
		(start 350.78797 -256.090166)
		(end 350.321118 -255.824228)
		(width 0.350012)
		(layer "F.Cu")
		(net "PVDDCR_SOC_P0")
	)
	(segment
		(start 351.087944 -261.670038)
		(end 350.621092 -261.935976)
		(width 0.350012)
		(layer "F.Cu")
		(net "PVDDCR_SOC_P0")
	)
	(segment
		(start 390.737852 -242.320064)
		(end 391.204704 -242.054126)
		(width 0.350012)
		(layer "F.Cu")
		(net "PVDDCR_SOC_P0")
	)
	(segment
		(start 384.627882 -249.610118)
		(end 385.094734 -249.34418)
		(width 0.350012)
		(layer "F.Cu")
		(net "PVDDCR_SOC_P0")
	)
	(segment
		(start 378.048012 -235.03001)
		(end 378.514864 -234.764072)
		(width 0.350012)
		(layer "F.Cu")
		(net "PVDDCR_SOC_P0")
	)
	(segment
		(start 369.11788 -256.900172)
		(end 369.584732 -256.634234)
		(width 0.350012)
		(layer "F.Cu")
		(net "PVDDCR_SOC_P0")
	)
	(segment
		(start 378.048012 -254.470154)
		(end 378.514864 -254.204216)
		(width 0.350012)
		(layer "F.Cu")
		(net "PVDDCR_SOC_P0")
	)
	(segment
		(start 351.087944 -263.29005)
		(end 350.621092 -263.555988)
		(width 0.350012)
		(layer "F.Cu")
		(net "PVDDCR_SOC_P0")
	)
	(segment
		(start 374.11787 -260.860032)
		(end 374.584722 -261.12597)
		(width 0.350012)
		(layer "F.Cu")
		(net "PVDDCR_SOC_P0")
	)
	(segment
		(start 369.588034 -254.470154)
		(end 370.054886 -254.204216)
		(width 0.350012)
		(layer "F.Cu")
		(net "PVDDCR_SOC_P0")
	)
	(segment
		(start 374.75795 -243.940076)
		(end 375.224802 -243.674138)
		(width 0.350012)
		(layer "F.Cu")
		(net "PVDDCR_SOC_P0")
	)
	(segment
		(start 374.75795 -232.599992)
		(end 375.224802 -232.334054)
		(width 0.350012)
		(layer "F.Cu")
		(net "PVDDCR_SOC_P0")
	)
	(segment
		(start 374.11787 -262.480044)
		(end 374.584722 -262.745982)
		(width 0.350012)
		(layer "F.Cu")
		(net "PVDDCR_SOC_P0")
	)
	(segment
		(start 369.588034 -252.850142)
		(end 370.054886 -252.584204)
		(width 0.350012)
		(layer "F.Cu")
		(net "PVDDCR_SOC_P0")
	)
	(segment
		(start 374.75795 -255.28016)
		(end 375.224802 -255.014222)
		(width 0.350012)
		(layer "F.Cu")
		(net "PVDDCR_SOC_P0")
	)
	(segment
		(start 384.927856 -263.29005)
		(end 385.394708 -263.555988)
		(width 0.350012)
		(layer "F.Cu")
		(net "PVDDCR_SOC_P0")
	)
	(segment
		(start 384.627882 -230.169974)
		(end 385.094734 -229.904036)
		(width 0.350012)
		(layer "F.Cu")
		(net "PVDDCR_SOC_P0")
	)
	(segment
		(start 377.577858 -247.1801)
		(end 378.04471 -246.914162)
		(width 0.350012)
		(layer "F.Cu")
		(net "PVDDCR_SOC_P0")
	)
	(segment
		(start 374.75795 -250.420124)
		(end 375.224802 -250.154186)
		(width 0.350012)
		(layer "F.Cu")
		(net "PVDDCR_SOC_P0")
	)
	(segment
		(start 384.157982 -252.040136)
		(end 384.624834 -251.774198)
		(width 0.350012)
		(layer "F.Cu")
		(net "PVDDCR_SOC_P0")
	)
	(segment
		(start 350.618044 -260.860032)
		(end 350.151192 -261.12597)
		(width 0.350012)
		(layer "F.Cu")
		(net "PVDDCR_SOC_P0")
	)
	(segment
		(start 420.64813 -176.738788)
		(end 420.774114 -176.864772)
		(width 0.254)
		(layer "F.Cu")
		(net "PVDDCR_SOC_P0")
	)
	(segment
		(start 377.577858 -227.74021)
		(end 378.04471 -227.474272)
		(width 0.350012)
		(layer "F.Cu")
		(net "PVDDCR_SOC_P0")
	)
	(segment
		(start 391.208006 -244.750082)
		(end 391.674858 -244.484144)
		(width 0.350012)
		(layer "F.Cu")
		(net "PVDDCR_SOC_P0")
	)
	(segment
		(start 384.157982 -247.1801)
		(end 384.624834 -246.914162)
		(width 0.350012)
		(layer "F.Cu")
		(net "PVDDCR_SOC_P0")
	)
	(segment
		(start 369.11788 -253.660148)
		(end 369.584732 -253.39421)
		(width 0.350012)
		(layer "F.Cu")
		(net "PVDDCR_SOC_P0")
	)
	(segment
		(start 391.03808 -265.720068)
		(end 391.504678 -265.986006)
		(width 0.350012)
		(layer "F.Cu")
		(net "PVDDCR_SOC_P0")
	)
	(segment
		(start 370.357908 -260.860032)
		(end 370.82476 -261.12597)
		(width 0.350012)
		(layer "F.Cu")
		(net "PVDDCR_SOC_P0")
	)
	(segment
		(start 378.048012 -244.750082)
		(end 378.514864 -244.484144)
		(width 0.350012)
		(layer "F.Cu")
		(net "PVDDCR_SOC_P0")
	)
	(segment
		(start 378.048012 -239.890046)
		(end 378.514864 -239.624108)
		(width 0.350012)
		(layer "F.Cu")
		(net "PVDDCR_SOC_P0")
	)
	(segment
		(start 374.75795 -253.660148)
		(end 375.224802 -253.39421)
		(width 0.350012)
		(layer "F.Cu")
		(net "PVDDCR_SOC_P0")
	)
	(segment
		(start 372.707916 -261.670038)
		(end 373.174768 -261.935976)
		(width 0.350012)
		(layer "F.Cu")
		(net "PVDDCR_SOC_P0")
	)
	(segment
		(start 350.618044 -262.480044)
		(end 350.151192 -262.745982)
		(width 0.350012)
		(layer "F.Cu")
		(net "PVDDCR_SOC_P0")
	)
	(segment
		(start 390.737852 -252.040136)
		(end 391.204704 -251.774198)
		(width 0.350012)
		(layer "F.Cu")
		(net "PVDDCR_SOC_P0")
	)
	(segment
		(start 372.877842 -252.040136)
		(end 373.344694 -251.774198)
		(width 0.350012)
		(layer "F.Cu")
		(net "PVDDCR_SOC_P0")
	)
	(segment
		(start 349.378016 -255.28016)
		(end 348.911164 -255.014222)
		(width 0.350012)
		(layer "F.Cu")
		(net "PVDDCR_SOC_P0")
	)
	(segment
		(start 372.877842 -256.900172)
		(end 373.344694 -256.634234)
		(width 0.350012)
		(layer "F.Cu")
		(net "PVDDCR_SOC_P0")
	)
	(segment
		(start 418.263832 -176.738788)
		(end 419.597586 -176.738788)
		(width 0.254)
		(layer "F.Cu")
		(net "PVDDCR_SOC_P0")
	)
	(segment
		(start 377.577858 -242.320064)
		(end 378.04471 -242.054126)
		(width 0.350012)
		(layer "F.Cu")
		(net "PVDDCR_SOC_P0")
	)
	(segment
		(start 361.597956 -252.040136)
		(end 362.064808 -251.774198)
		(width 0.350012)
		(layer "F.Cu")
		(net "PVDDCR_SOC_P0")
	)
	(segment
		(start 371.467888 -254.470154)
		(end 371.93474 -254.204216)
		(width 0.350012)
		(layer "F.Cu")
		(net "PVDDCR_SOC_P0")
	)
	(segment
		(start 369.11788 -255.28016)
		(end 369.584732 -255.014222)
		(width 0.350012)
		(layer "F.Cu")
		(net "PVDDCR_SOC_P0")
	)
	(segment
		(start 373.347996 -256.090166)
		(end 373.814848 -255.824228)
		(width 0.350012)
		(layer "F.Cu")
		(net "PVDDCR_SOC_P0")
	)
	(segment
		(start 370.828062 -261.670038)
		(end 371.294914 -261.935976)
		(width 0.350012)
		(layer "F.Cu")
		(net "PVDDCR_SOC_P0")
	)
	(segment
		(start 351.25787 -252.040136)
		(end 350.791018 -251.774198)
		(width 0.350012)
		(layer "F.Cu")
		(net "PVDDCR_SOC_P0")
	)
	(segment
		(start 391.208006 -249.610118)
		(end 391.674858 -249.34418)
		(width 0.350012)
		(layer "F.Cu")
		(net "PVDDCR_SOC_P0")
	)
	(segment
		(start 371.467888 -252.850142)
		(end 371.93474 -252.584204)
		(width 0.350012)
		(layer "F.Cu")
		(net "PVDDCR_SOC_P0")
	)
	(segment
		(start 377.577858 -252.040136)
		(end 378.04471 -251.774198)
		(width 0.350012)
		(layer "F.Cu")
		(net "PVDDCR_SOC_P0")
	)
	(segment
		(start 353.137978 -252.040136)
		(end 352.671126 -251.774198)
		(width 0.350012)
		(layer "F.Cu")
		(net "PVDDCR_SOC_P0")
	)
	(segment
		(start 391.208006 -230.169974)
		(end 391.674858 -229.904036)
		(width 0.350012)
		(layer "F.Cu")
		(net "PVDDCR_SOC_P0")
	)
	(segment
		(start 367.238026 -252.040136)
		(end 367.704878 -251.774198)
		(width 0.350012)
		(layer "F.Cu")
		(net "PVDDCR_SOC_P0")
	)
	(segment
		(start 373.347996 -254.470154)
		(end 373.814848 -254.204216)
		(width 0.350012)
		(layer "F.Cu")
		(net "PVDDCR_SOC_P0")
	)
	(segment
		(start 371.467888 -256.090166)
		(end 371.93474 -255.824228)
		(width 0.350012)
		(layer "F.Cu")
		(net "PVDDCR_SOC_P0")
	)
	(segment
		(start 384.157982 -242.320064)
		(end 384.624834 -242.054126)
		(width 0.350012)
		(layer "F.Cu")
		(net "PVDDCR_SOC_P0")
	)
	(segment
		(start 390.737852 -256.900172)
		(end 391.204704 -256.634234)
		(width 0.350012)
		(layer "F.Cu")
		(net "PVDDCR_SOC_P0")
	)
	(segment
		(start 374.75795 -235.840016)
		(end 375.224802 -235.574078)
		(width 0.350012)
		(layer "F.Cu")
		(net "PVDDCR_SOC_P0")
	)
	(segment
		(start 374.75795 -256.900172)
		(end 375.224802 -256.634234)
		(width 0.350012)
		(layer "F.Cu")
		(net "PVDDCR_SOC_P0")
	)
	(segment
		(start 391.208006 -235.03001)
		(end 391.674858 -234.764072)
		(width 0.350012)
		(layer "F.Cu")
		(net "PVDDCR_SOC_P0")
	)
	(segment
		(start 358.778048 -252.040136)
		(end 358.311196 -251.774198)
		(width 0.350012)
		(layer "F.Cu")
		(net "PVDDCR_SOC_P0")
	)
	(segment
		(start 355.018086 -252.040136)
		(end 354.551234 -251.774198)
		(width 0.350012)
		(layer "F.Cu")
		(net "PVDDCR_SOC_P0")
	)
	(segment
		(start 390.737852 -222.880174)
		(end 391.204704 -222.614236)
		(width 0.350012)
		(layer "F.Cu")
		(net "PVDDCR_SOC_P0")
	)
	(segment
		(start 391.208006 -239.890046)
		(end 391.674858 -239.624108)
		(width 0.350012)
		(layer "F.Cu")
		(net "PVDDCR_SOC_P0")
	)
	(segment
		(start 358.307894 -251.23013)
		(end 357.841042 -250.964192)
		(width 0.350012)
		(layer "F.Cu")
		(net "PVDDCR_SOC_P0")
	)
	(segment
		(start 390.737852 -232.599992)
		(end 391.204704 -232.334054)
		(width 0.350012)
		(layer "F.Cu")
		(net "PVDDCR_SOC_P0")
	)
	(segment
		(start 368.947954 -261.670038)
		(end 369.414806 -261.935976)
		(width 0.350012)
		(layer "F.Cu")
		(net "PVDDCR_SOC_P0")
	)
	(segment
		(start 350.78797 -252.850142)
		(end 350.321118 -252.584204)
		(width 0.350012)
		(layer "F.Cu")
		(net "PVDDCR_SOC_P0")
	)
	(segment
		(start 384.627882 -239.890046)
		(end 385.094734 -239.624108)
		(width 0.350012)
		(layer "F.Cu")
		(net "PVDDCR_SOC_P0")
	)
	(segment
		(start 384.157982 -227.74021)
		(end 384.624834 -227.474272)
		(width 0.350012)
		(layer "F.Cu")
		(net "PVDDCR_SOC_P0")
	)
	(segment
		(start 377.577858 -237.460028)
		(end 378.04471 -237.19409)
		(width 0.350012)
		(layer "F.Cu")
		(net "PVDDCR_SOC_P0")
	)
	(segment
		(start 372.877842 -255.28016)
		(end 373.344694 -255.014222)
		(width 0.350012)
		(layer "F.Cu")
		(net "PVDDCR_SOC_P0")
	)
	(segment
		(start 370.997988 -256.900172)
		(end 371.46484 -256.634234)
		(width 0.350012)
		(layer "F.Cu")
		(net "PVDDCR_SOC_P0")
	)
	(segment
		(start 370.997988 -255.28016)
		(end 371.46484 -255.014222)
		(width 0.350012)
		(layer "F.Cu")
		(net "PVDDCR_SOC_P0")
	)
	(segment
		(start 350.31807 -256.900172)
		(end 349.851218 -256.634234)
		(width 0.350012)
		(layer "F.Cu")
		(net "PVDDCR_SOC_P0")
	)
	(segment
		(start 350.78797 -254.470154)
		(end 350.321118 -254.204216)
		(width 0.350012)
		(layer "F.Cu")
		(net "PVDDCR_SOC_P0")
	)
	(segment
		(start 370.997988 -253.660148)
		(end 371.46484 -253.39421)
		(width 0.350012)
		(layer "F.Cu")
		(net "PVDDCR_SOC_P0")
	)
	(segment
		(start 374.75795 -229.360222)
		(end 375.224802 -229.094284)
		(width 0.350012)
		(layer "F.Cu")
		(net "PVDDCR_SOC_P0")
	)
	(segment
		(start 370.997988 -252.040136)
		(end 371.46484 -251.774198)
		(width 0.350012)
		(layer "F.Cu")
		(net "PVDDCR_SOC_P0")
	)
	(segment
		(start 369.588034 -256.090166)
		(end 370.054886 -255.824228)
		(width 0.350012)
		(layer "F.Cu")
		(net "PVDDCR_SOC_P0")
	)
	(segment
		(start 384.627882 -225.310192)
		(end 385.094734 -225.044254)
		(width 0.350012)
		(layer "F.Cu")
		(net "PVDDCR_SOC_P0")
	)
	(segment
		(start 374.75795 -252.040136)
		(end 375.224802 -251.774198)
		(width 0.350012)
		(layer "F.Cu")
		(net "PVDDCR_SOC_P0")
	)
	(segment
		(start 363.478064 -252.040136)
		(end 363.944916 -251.774198)
		(width 0.350012)
		(layer "F.Cu")
		(net "PVDDCR_SOC_P0")
	)
	(via
		(at 396.038832 -192.984628)
		(size 0.508)
		(drill 0.254)
		(layers "F.Cu" "B.Cu")
		(net "PVDDCR_SOC_P0")
	)
	(via
		(at 359.283254 -253.43231)
		(size 0.4826)
		(drill 0.254)
		(layers "F.Cu" "B.Cu")
		(net "PVDDCR_SOC_P0")
	)
	(via
		(at 370.82476 -261.12597)
		(size 0.4064)
		(drill 0.2032)
		(layers "F.Cu" "B.Cu")
		(net "PVDDCR_SOC_P0")
	)
	(via
		(at 360.607864 -258.795012)
		(size 0.4826)
		(drill 0.254)
		(layers "F.Cu" "B.Cu")
		(net "PVDDCR_SOC_P0")
	)
	(via
		(at 400.707352 -190.444628)
		(size 0.508)
		(drill 0.254)
		(layers "F.Cu" "B.Cu")
		(net "PVDDCR_SOC_P0")
	)
	(via
		(at 375.224802 -250.154186)
		(size 0.4064)
		(drill 0.2032)
		(layers "F.Cu" "B.Cu")
		(net "PVDDCR_SOC_P0")
	)
	(via
		(at 416.164522 -177.017426)
		(size 0.508)
		(drill 0.254)
		(layers "F.Cu" "B.Cu")
		(net "PVDDCR_SOC_P0")
	)
	(via
		(at 373.344694 -253.39421)
		(size 0.4064)
		(drill 0.2032)
		(layers "F.Cu" "B.Cu")
		(net "PVDDCR_SOC_P0")
	)
	(via
		(at 371.46484 -255.014222)
		(size 0.4064)
		(drill 0.2032)
		(layers "F.Cu" "B.Cu")
		(net "PVDDCR_SOC_P0")
	)
	(via
		(at 366.295178 -259.33019)
		(size 0.4826)
		(drill 0.254)
		(layers "F.Cu" "B.Cu")
		(net "PVDDCR_SOC_P0")
	)
	(via
		(at 399.418556 -191.055752)
		(size 0.508)
		(drill 0.254)
		(layers "F.Cu" "B.Cu")
		(net "PVDDCR_SOC_P0")
	)
	(via
		(at 404.455376 -183.113426)
		(size 0.508)
		(drill 0.254)
		(layers "F.Cu" "B.Cu")
		(net "PVDDCR_SOC_P0")
	)
	(via
		(at 370.054886 -252.584204)
		(size 0.4064)
		(drill 0.2032)
		(layers "F.Cu" "B.Cu")
		(net "PVDDCR_SOC_P0")
	)
	(via
		(at 404.415752 -185.042048)
		(size 0.508)
		(drill 0.254)
		(layers "F.Cu" "B.Cu")
		(net "PVDDCR_SOC_P0")
	)
	(via
		(at 391.204704 -227.474272)
		(size 0.4064)
		(drill 0.2032)
		(layers "F.Cu" "B.Cu")
		(net "PVDDCR_SOC_P0")
	)
	(via
		(at 407.826972 -185.804048)
		(size 0.6604)
		(drill 0.3302)
		(layers "F.Cu" "B.Cu")
		(net "PVDDCR_SOC_P0")
	)
	(via
		(at 366.295178 -260.28015)
		(size 0.4826)
		(drill 0.254)
		(layers "F.Cu" "B.Cu")
		(net "PVDDCR_SOC_P0")
	)
	(via
		(at 396.675356 -190.420752)
		(size 0.508)
		(drill 0.254)
		(layers "F.Cu" "B.Cu")
		(net "PVDDCR_SOC_P0")
	)
	(via
		(at 396.033752 -189.150752)
		(size 0.508)
		(drill 0.254)
		(layers "F.Cu" "B.Cu")
		(net "PVDDCR_SOC_P0")
	)
	(via
		(at 370.054886 -250.964192)
		(size 0.4064)
		(drill 0.2032)
		(layers "F.Cu" "B.Cu")
		(net "PVDDCR_SOC_P0")
	)
	(via
		(at 366.295178 -258.379976)
		(size 0.4826)
		(drill 0.254)
		(layers "F.Cu" "B.Cu")
		(net "PVDDCR_SOC_P0")
	)
	(via
		(at 351.25787 -255.822196)
		(size 0.4064)
		(drill 0.2032)
		(layers "F.Cu" "B.Cu")
		(net "PVDDCR_SOC_P0")
	)
	(via
		(at 400.049492 -189.150752)
		(size 0.508)
		(drill 0.254)
		(layers "F.Cu" "B.Cu")
		(net "PVDDCR_SOC_P0")
	)
	(via
		(at 405.090376 -183.113426)
		(size 0.508)
		(drill 0.254)
		(layers "F.Cu" "B.Cu")
		(net "PVDDCR_SOC_P0")
	)
	(via
		(at 367.704878 -251.774198)
		(size 0.4064)
		(drill 0.2032)
		(layers "F.Cu" "B.Cu")
		(net "PVDDCR_SOC_P0")
	)
	(via
		(at 404.415752 -187.709048)
		(size 0.6604)
		(drill 0.3302)
		(layers "F.Cu" "B.Cu")
		(net "PVDDCR_SOC_P0")
	)
	(via
		(at 370.054886 -254.204216)
		(size 0.4064)
		(drill 0.2032)
		(layers "F.Cu" "B.Cu")
		(net "PVDDCR_SOC_P0")
	)
	(via
		(at 408.468576 -183.113426)
		(size 0.508)
		(drill 0.254)
		(layers "F.Cu" "B.Cu")
		(net "PVDDCR_SOC_P0")
	)
	(via
		(at 362.534708 -250.964192)
		(size 0.4064)
		(drill 0.2032)
		(layers "F.Cu" "B.Cu")
		(net "PVDDCR_SOC_P0")
	)
	(via
		(at 366.294924 -250.964192)
		(size 0.4064)
		(drill 0.2032)
		(layers "F.Cu" "B.Cu")
		(net "PVDDCR_SOC_P0")
	)
	(via
		(at 399.418556 -189.785752)
		(size 0.508)
		(drill 0.254)
		(layers "F.Cu" "B.Cu")
		(net "PVDDCR_SOC_P0")
	)
	(via
		(at 369.584732 -256.634234)
		(size 0.4064)
		(drill 0.2032)
		(layers "F.Cu" "B.Cu")
		(net "PVDDCR_SOC_P0")
	)
	(via
		(at 378.04471 -232.334054)
		(size 0.4064)
		(drill 0.2032)
		(layers "F.Cu" "B.Cu")
		(net "PVDDCR_SOC_P0")
	)
	(via
		(at 417.453318 -177.041302)
		(size 0.508)
		(drill 0.254)
		(layers "F.Cu" "B.Cu")
		(net "PVDDCR_SOC_P0")
	)
	(via
		(at 391.674858 -229.904036)
		(size 0.4064)
		(drill 0.2032)
		(layers "F.Cu" "B.Cu")
		(net "PVDDCR_SOC_P0")
	)
	(via
		(at 416.799522 -176.382426)
		(size 0.508)
		(drill 0.254)
		(layers "F.Cu" "B.Cu")
		(net "PVDDCR_SOC_P0")
	)
	(via
		(at 404.455376 -182.478426)
		(size 0.508)
		(drill 0.254)
		(layers "F.Cu" "B.Cu")
		(net "PVDDCR_SOC_P0")
	)
	(via
		(at 391.204704 -256.634234)
		(size 0.4064)
		(drill 0.2032)
		(layers "F.Cu" "B.Cu")
		(net "PVDDCR_SOC_P0")
	)
	(via
		(at 395.403832 -192.984628)
		(size 0.508)
		(drill 0.254)
		(layers "F.Cu" "B.Cu")
		(net "PVDDCR_SOC_P0")
	)
	(via
		(at 375.224802 -235.574078)
		(size 0.4064)
		(drill 0.2032)
		(layers "F.Cu" "B.Cu")
		(net "PVDDCR_SOC_P0")
	)
	(via
		(at 416.147758 -180.840888)
		(size 0.508)
		(drill 0.254)
		(layers "F.Cu" "B.Cu")
		(net "PVDDCR_SOC_P0")
	)
	(via
		(at 371.989604 -259.729986)
		(size 0.4826)
		(drill 0.254)
		(layers "F.Cu" "B.Cu")
		(net "PVDDCR_SOC_P0")
	)
	(via
		(at 409.122372 -181.232302)
		(size 0.508)
		(drill 0.254)
		(layers "F.Cu" "B.Cu")
		(net "PVDDCR_SOC_P0")
	)
	(via
		(at 375.224802 -246.914162)
		(size 0.4064)
		(drill 0.2032)
		(layers "F.Cu" "B.Cu")
		(net "PVDDCR_SOC_P0")
	)
	(via
		(at 412.779718 -178.946048)
		(size 0.508)
		(drill 0.254)
		(layers "F.Cu" "B.Cu")
		(net "PVDDCR_SOC_P0")
	)
	(via
		(at 405.090376 -181.843426)
		(size 0.508)
		(drill 0.254)
		(layers "F.Cu" "B.Cu")
		(net "PVDDCR_SOC_P0")
	)
	(via
		(at 372.704868 -261.12597)
		(size 0.4064)
		(drill 0.2032)
		(layers "F.Cu" "B.Cu")
		(net "PVDDCR_SOC_P0")
	)
	(via
		(at 371.46484 -251.774198)
		(size 0.4064)
		(drill 0.2032)
		(layers "F.Cu" "B.Cu")
		(net "PVDDCR_SOC_P0")
	)
	(via
		(at 412.786322 -177.652426)
		(size 0.508)
		(drill 0.254)
		(layers "F.Cu" "B.Cu")
		(net "PVDDCR_SOC_P0")
	)
	(via
		(at 413.421322 -176.382426)
		(size 0.508)
		(drill 0.254)
		(layers "F.Cu" "B.Cu")
		(net "PVDDCR_SOC_P0")
	)
	(via
		(at 413.414718 -180.216048)
		(size 0.508)
		(drill 0.254)
		(layers "F.Cu" "B.Cu")
		(net "PVDDCR_SOC_P0")
	)
	(via
		(at 352.671126 -251.774198)
		(size 0.4064)
		(drill 0.2032)
		(layers "F.Cu" "B.Cu")
		(net "PVDDCR_SOC_P0")
	)
	(via
		(at 396.038832 -194.254628)
		(size 0.508)
		(drill 0.254)
		(layers "F.Cu" "B.Cu")
		(net "PVDDCR_SOC_P0")
	)
	(via
		(at 391.674858 -223.424242)
		(size 0.4064)
		(drill 0.2032)
		(layers "F.Cu" "B.Cu")
		(net "PVDDCR_SOC_P0")
	)
	(via
		(at 374.754902 -238.004096)
		(size 0.4064)
		(drill 0.2032)
		(layers "F.Cu" "B.Cu")
		(net "PVDDCR_SOC_P0")
	)
	(via
		(at 408.468576 -181.208426)
		(size 0.508)
		(drill 0.254)
		(layers "F.Cu" "B.Cu")
		(net "PVDDCR_SOC_P0")
	)
	(via
		(at 396.038832 -194.889628)
		(size 0.508)
		(drill 0.254)
		(layers "F.Cu" "B.Cu")
		(net "PVDDCR_SOC_P0")
	)
	(via
		(at 391.674858 -225.044254)
		(size 0.4064)
		(drill 0.2032)
		(layers "F.Cu" "B.Cu")
		(net "PVDDCR_SOC_P0")
	)
	(via
		(at 366.295178 -255.530096)
		(size 0.4826)
		(drill 0.254)
		(layers "F.Cu" "B.Cu")
		(net "PVDDCR_SOC_P0")
	)
	(via
		(at 363.947964 -253.392178)
		(size 0.4064)
		(drill 0.2032)
		(layers "F.Cu" "B.Cu")
		(net "PVDDCR_SOC_P0")
	)
	(via
		(at 352.668078 -253.392178)
		(size 0.4064)
		(drill 0.2032)
		(layers "F.Cu" "B.Cu")
		(net "PVDDCR_SOC_P0")
	)
	(via
		(at 361.288076 -255.472946)
		(size 0.4826)
		(drill 0.254)
		(layers "F.Cu" "B.Cu")
		(net "PVDDCR_SOC_P0")
	)
	(via
		(at 359.283254 -254.44831)
		(size 0.4826)
		(drill 0.254)
		(layers "F.Cu" "B.Cu")
		(net "PVDDCR_SOC_P0")
	)
	(via
		(at 395.403832 -192.349628)
		(size 0.508)
		(drill 0.254)
		(layers "F.Cu" "B.Cu")
		(net "PVDDCR_SOC_P0")
	)
	(via
		(at 416.782758 -180.840888)
		(size 0.508)
		(drill 0.254)
		(layers "F.Cu" "B.Cu")
		(net "PVDDCR_SOC_P0")
	)
	(via
		(at 396.038832 -193.619628)
		(size 0.508)
		(drill 0.254)
		(layers "F.Cu" "B.Cu")
		(net "PVDDCR_SOC_P0")
	)
	(via
		(at 378.514864 -229.904036)
		(size 0.4064)
		(drill 0.2032)
		(layers "F.Cu" "B.Cu")
		(net "PVDDCR_SOC_P0")
	)
	(via
		(at 416.782758 -179.570888)
		(size 0.508)
		(drill 0.254)
		(layers "F.Cu" "B.Cu")
		(net "PVDDCR_SOC_P0")
	)
	(via
		(at 363.187996 -255.472946)
		(size 0.4826)
		(drill 0.254)
		(layers "F.Cu" "B.Cu")
		(net "PVDDCR_SOC_P0")
	)
	(via
		(at 413.421322 -178.287426)
		(size 0.508)
		(drill 0.254)
		(layers "F.Cu" "B.Cu")
		(net "PVDDCR_SOC_P0")
	)
	(via
		(at 385.094734 -244.484144)
		(size 0.4064)
		(drill 0.2032)
		(layers "F.Cu" "B.Cu")
		(net "PVDDCR_SOC_P0")
	)
	(via
		(at 401.127976 -173.38929)
		(size 0.508)
		(drill 0.254)
		(layers "F.Cu" "B.Cu")
		(net "PVDDCR_SOC_P0")
	)
	(via
		(at 350.321118 -254.204216)
		(size 0.4064)
		(drill 0.2032)
		(layers "F.Cu" "B.Cu")
		(net "PVDDCR_SOC_P0")
	)
	(via
		(at 405.050752 -183.772048)
		(size 0.508)
		(drill 0.254)
		(layers "F.Cu" "B.Cu")
		(net "PVDDCR_SOC_P0")
	)
	(via
		(at 408.468576 -182.478426)
		(size 0.508)
		(drill 0.254)
		(layers "F.Cu" "B.Cu")
		(net "PVDDCR_SOC_P0")
	)
	(via
		(at 370.06403 -257.930142)
		(size 0.4826)
		(drill 0.254)
		(layers "F.Cu" "B.Cu")
		(net "PVDDCR_SOC_P0")
	)
	(via
		(at 396.675356 -191.690752)
		(size 0.508)
		(drill 0.254)
		(layers "F.Cu" "B.Cu")
		(net "PVDDCR_SOC_P0")
	)
	(via
		(at 371.93474 -254.204216)
		(size 0.4064)
		(drill 0.2032)
		(layers "F.Cu" "B.Cu")
		(net "PVDDCR_SOC_P0")
	)
	(via
		(at 375.224802 -253.39421)
		(size 0.4064)
		(drill 0.2032)
		(layers "F.Cu" "B.Cu")
		(net "PVDDCR_SOC_P0")
	)
	(via
		(at 391.204704 -251.774198)
		(size 0.4064)
		(drill 0.2032)
		(layers "F.Cu" "B.Cu")
		(net "PVDDCR_SOC_P0")
	)
	(via
		(at 395.403832 -193.619628)
		(size 0.508)
		(drill 0.254)
		(layers "F.Cu" "B.Cu")
		(net "PVDDCR_SOC_P0")
	)
	(via
		(at 400.053556 -191.055752)
		(size 0.508)
		(drill 0.254)
		(layers "F.Cu" "B.Cu")
		(net "PVDDCR_SOC_P0")
	)
	(via
		(at 375.224802 -251.774198)
		(size 0.4064)
		(drill 0.2032)
		(layers "F.Cu" "B.Cu")
		(net "PVDDCR_SOC_P0")
	)
	(via
		(at 396.038832 -195.524628)
		(size 0.508)
		(drill 0.254)
		(layers "F.Cu" "B.Cu")
		(net "PVDDCR_SOC_P0")
	)
	(via
		(at 370.06403 -259.729986)
		(size 0.4826)
		(drill 0.254)
		(layers "F.Cu" "B.Cu")
		(net "PVDDCR_SOC_P0")
	)
	(via
		(at 400.707352 -191.079628)
		(size 0.508)
		(drill 0.254)
		(layers "F.Cu" "B.Cu")
		(net "PVDDCR_SOC_P0")
	)
	(via
		(at 409.122372 -181.867302)
		(size 0.508)
		(drill 0.254)
		(layers "F.Cu" "B.Cu")
		(net "PVDDCR_SOC_P0")
	)
	(via
		(at 373.814848 -252.584204)
		(size 0.4064)
		(drill 0.2032)
		(layers "F.Cu" "B.Cu")
		(net "PVDDCR_SOC_P0")
	)
	(via
		(at 373.344694 -256.634234)
		(size 0.4064)
		(drill 0.2032)
		(layers "F.Cu" "B.Cu")
		(net "PVDDCR_SOC_P0")
	)
	(via
		(at 405.050752 -185.042048)
		(size 0.508)
		(drill 0.254)
		(layers "F.Cu" "B.Cu")
		(net "PVDDCR_SOC_P0")
	)
	(via
		(at 404.415752 -185.677048)
		(size 0.508)
		(drill 0.254)
		(layers "F.Cu" "B.Cu")
		(net "PVDDCR_SOC_P0")
	)
	(via
		(at 399.437352 -192.984628)
		(size 0.508)
		(drill 0.254)
		(layers "F.Cu" "B.Cu")
		(net "PVDDCR_SOC_P0")
	)
	(via
		(at 396.675356 -189.785752)
		(size 0.508)
		(drill 0.254)
		(layers "F.Cu" "B.Cu")
		(net "PVDDCR_SOC_P0")
	)
	(via
		(at 356.42804 -253.392178)
		(size 0.4064)
		(drill 0.2032)
		(layers "F.Cu" "B.Cu")
		(net "PVDDCR_SOC_P0")
	)
	(via
		(at 373.767604 -258.830064)
		(size 0.4826)
		(drill 0.254)
		(layers "F.Cu" "B.Cu")
		(net "PVDDCR_SOC_P0")
	)
	(via
		(at 384.624834 -237.19409)
		(size 0.4064)
		(drill 0.2032)
		(layers "F.Cu" "B.Cu")
		(net "PVDDCR_SOC_P0")
	)
	(via
		(at 405.050752 -184.407048)
		(size 0.508)
		(drill 0.254)
		(layers "F.Cu" "B.Cu")
		(net "PVDDCR_SOC_P0")
	)
	(via
		(at 399.418556 -191.690752)
		(size 0.508)
		(drill 0.254)
		(layers "F.Cu" "B.Cu")
		(net "PVDDCR_SOC_P0")
	)
	(via
		(at 378.04471 -242.054126)
		(size 0.4064)
		(drill 0.2032)
		(layers "F.Cu" "B.Cu")
		(net "PVDDCR_SOC_P0")
	)
	(via
		(at 378.514864 -234.764072)
		(size 0.4064)
		(drill 0.2032)
		(layers "F.Cu" "B.Cu")
		(net "PVDDCR_SOC_P0")
	)
	(via
		(at 367.707926 -253.392178)
		(size 0.4064)
		(drill 0.2032)
		(layers "F.Cu" "B.Cu")
		(net "PVDDCR_SOC_P0")
	)
	(via
		(at 396.668752 -189.150752)
		(size 0.508)
		(drill 0.254)
		(layers "F.Cu" "B.Cu")
		(net "PVDDCR_SOC_P0")
	)
	(via
		(at 396.675356 -191.055752)
		(size 0.508)
		(drill 0.254)
		(layers "F.Cu" "B.Cu")
		(net "PVDDCR_SOC_P0")
	)
	(via
		(at 409.122372 -182.502302)
		(size 0.508)
		(drill 0.254)
		(layers "F.Cu" "B.Cu")
		(net "PVDDCR_SOC_P0")
	)
	(via
		(at 400.053556 -190.420752)
		(size 0.508)
		(drill 0.254)
		(layers "F.Cu" "B.Cu")
		(net "PVDDCR_SOC_P0")
	)
	(via
		(at 405.050752 -185.677048)
		(size 0.508)
		(drill 0.254)
		(layers "F.Cu" "B.Cu")
		(net "PVDDCR_SOC_P0")
	)
	(via
		(at 351.087944 -261.128002)
		(size 0.4064)
		(drill 0.2032)
		(layers "F.Cu" "B.Cu")
		(net "PVDDCR_SOC_P0")
	)
	(via
		(at 408.464512 -180.573426)
		(size 0.508)
		(drill 0.254)
		(layers "F.Cu" "B.Cu")
		(net "PVDDCR_SOC_P0")
	)
	(via
		(at 370.06403 -258.830064)
		(size 0.4826)
		(drill 0.254)
		(layers "F.Cu" "B.Cu")
		(net "PVDDCR_SOC_P0")
	)
	(via
		(at 363.207808 -258.795012)
		(size 0.4826)
		(drill 0.254)
		(layers "F.Cu" "B.Cu")
		(net "PVDDCR_SOC_P0")
	)
	(via
		(at 405.050752 -186.947048)
		(size 0.508)
		(drill 0.254)
		(layers "F.Cu" "B.Cu")
		(net "PVDDCR_SOC_P0")
	)
	(via
		(at 399.414492 -189.150752)
		(size 0.508)
		(drill 0.254)
		(layers "F.Cu" "B.Cu")
		(net "PVDDCR_SOC_P0")
	)
	(via
		(at 359.283254 -252.41631)
		(size 0.4826)
		(drill 0.254)
		(layers "F.Cu" "B.Cu")
		(net "PVDDCR_SOC_P0")
	)
	(via
		(at 373.344694 -251.774198)
		(size 0.4064)
		(drill 0.2032)
		(layers "F.Cu" "B.Cu")
		(net "PVDDCR_SOC_P0")
	)
	(via
		(at 350.321118 -255.824228)
		(size 0.4064)
		(drill 0.2032)
		(layers "F.Cu" "B.Cu")
		(net "PVDDCR_SOC_P0")
	)
	(via
		(at 417.417758 -178.94554)
		(size 0.508)
		(drill 0.254)
		(layers "F.Cu" "B.Cu")
		(net "PVDDCR_SOC_P0")
	)
	(via
		(at 417.417758 -179.58054)
		(size 0.508)
		(drill 0.254)
		(layers "F.Cu" "B.Cu")
		(net "PVDDCR_SOC_P0")
	)
	(via
		(at 365.828072 -253.392178)
		(size 0.4064)
		(drill 0.2032)
		(layers "F.Cu" "B.Cu")
		(net "PVDDCR_SOC_P0")
	)
	(via
		(at 373.767604 -259.729986)
		(size 0.4826)
		(drill 0.254)
		(layers "F.Cu" "B.Cu")
		(net "PVDDCR_SOC_P0")
	)
	(via
		(at 408.461972 -184.407048)
		(size 0.508)
		(drill 0.254)
		(layers "F.Cu" "B.Cu")
		(net "PVDDCR_SOC_P0")
	)
	(via
		(at 416.799522 -178.287426)
		(size 0.508)
		(drill 0.254)
		(layers "F.Cu" "B.Cu")
		(net "PVDDCR_SOC_P0")
	)
	(via
		(at 354.547932 -253.392178)
		(size 0.4064)
		(drill 0.2032)
		(layers "F.Cu" "B.Cu")
		(net "PVDDCR_SOC_P0")
	)
	(via
		(at 395.403832 -195.524628)
		(size 0.508)
		(drill 0.254)
		(layers "F.Cu" "B.Cu")
		(net "PVDDCR_SOC_P0")
	)
	(via
		(at 385.094734 -225.044254)
		(size 0.4064)
		(drill 0.2032)
		(layers "F.Cu" "B.Cu")
		(net "PVDDCR_SOC_P0")
	)
	(via
		(at 366.295178 -256.480056)
		(size 0.4826)
		(drill 0.254)
		(layers "F.Cu" "B.Cu")
		(net "PVDDCR_SOC_P0")
	)
	(via
		(at 384.624834 -246.914162)
		(size 0.4064)
		(drill 0.2032)
		(layers "F.Cu" "B.Cu")
		(net "PVDDCR_SOC_P0")
	)
	(via
		(at 416.164522 -178.287426)
		(size 0.508)
		(drill 0.254)
		(layers "F.Cu" "B.Cu")
		(net "PVDDCR_SOC_P0")
	)
	(via
		(at 417.453318 -177.676302)
		(size 0.508)
		(drill 0.254)
		(layers "F.Cu" "B.Cu")
		(net "PVDDCR_SOC_P0")
	)
	(via
		(at 396.040356 -191.690752)
		(size 0.508)
		(drill 0.254)
		(layers "F.Cu" "B.Cu")
		(net "PVDDCR_SOC_P0")
	)
	(via
		(at 375.054876 -261.935976)
		(size 0.4064)
		(drill 0.2032)
		(layers "F.Cu" "B.Cu")
		(net "PVDDCR_SOC_P0")
	)
	(via
		(at 395.398752 -189.150752)
		(size 0.508)
		(drill 0.254)
		(layers "F.Cu" "B.Cu")
		(net "PVDDCR_SOC_P0")
	)
	(via
		(at 396.040356 -191.055752)
		(size 0.508)
		(drill 0.254)
		(layers "F.Cu" "B.Cu")
		(net "PVDDCR_SOC_P0")
	)
	(via
		(at 416.799522 -177.652426)
		(size 0.508)
		(drill 0.254)
		(layers "F.Cu" "B.Cu")
		(net "PVDDCR_SOC_P0")
	)
	(via
		(at 375.224802 -256.634234)
		(size 0.4064)
		(drill 0.2032)
		(layers "F.Cu" "B.Cu")
		(net "PVDDCR_SOC_P0")
	)
	(via
		(at 400.707352 -189.809628)
		(size 0.508)
		(drill 0.254)
		(layers "F.Cu" "B.Cu")
		(net "PVDDCR_SOC_P0")
	)
	(via
		(at 417.417758 -180.85054)
		(size 0.508)
		(drill 0.254)
		(layers "F.Cu" "B.Cu")
		(net "PVDDCR_SOC_P0")
	)
	(via
		(at 396.038832 -192.349628)
		(size 0.508)
		(drill 0.254)
		(layers "F.Cu" "B.Cu")
		(net "PVDDCR_SOC_P0")
	)
	(via
		(at 391.674858 -239.624108)
		(size 0.4064)
		(drill 0.2032)
		(layers "F.Cu" "B.Cu")
		(net "PVDDCR_SOC_P0")
	)
	(via
		(at 407.833576 -183.113426)
		(size 0.508)
		(drill 0.254)
		(layers "F.Cu" "B.Cu")
		(net "PVDDCR_SOC_P0")
	)
	(via
		(at 369.414806 -261.935976)
		(size 0.4064)
		(drill 0.2032)
		(layers "F.Cu" "B.Cu")
		(net "PVDDCR_SOC_P0")
	)
	(via
		(at 373.174768 -261.935976)
		(size 0.4064)
		(drill 0.2032)
		(layers "F.Cu" "B.Cu")
		(net "PVDDCR_SOC_P0")
	)
	(via
		(at 350.621092 -261.935976)
		(size 0.4064)
		(drill 0.2032)
		(layers "F.Cu" "B.Cu")
		(net "PVDDCR_SOC_P0")
	)
	(via
		(at 395.403832 -194.254628)
		(size 0.508)
		(drill 0.254)
		(layers "F.Cu" "B.Cu")
		(net "PVDDCR_SOC_P0")
	)
	(via
		(at 407.833576 -181.843426)
		(size 0.508)
		(drill 0.254)
		(layers "F.Cu" "B.Cu")
		(net "PVDDCR_SOC_P0")
	)
	(via
		(at 349.851218 -256.634234)
		(size 0.4064)
		(drill 0.2032)
		(layers "F.Cu" "B.Cu")
		(net "PVDDCR_SOC_P0")
	)
	(via
		(at 375.224802 -243.674138)
		(size 0.4064)
		(drill 0.2032)
		(layers "F.Cu" "B.Cu")
		(net "PVDDCR_SOC_P0")
	)
	(via
		(at 358.357932 -257.744976)
		(size 0.4826)
		(drill 0.254)
		(layers "F.Cu" "B.Cu")
		(net "PVDDCR_SOC_P0")
	)
	(via
		(at 407.829512 -180.573426)
		(size 0.508)
		(drill 0.254)
		(layers "F.Cu" "B.Cu")
		(net "PVDDCR_SOC_P0")
	)
	(via
		(at 359.302304 -251.40031)
		(size 0.4826)
		(drill 0.254)
		(layers "F.Cu" "B.Cu")
		(net "PVDDCR_SOC_P0")
	)
	(via
		(at 370.054886 -255.824228)
		(size 0.4064)
		(drill 0.2032)
		(layers "F.Cu" "B.Cu")
		(net "PVDDCR_SOC_P0")
	)
	(via
		(at 350.791018 -251.774198)
		(size 0.4064)
		(drill 0.2032)
		(layers "F.Cu" "B.Cu")
		(net "PVDDCR_SOC_P0")
	)
	(via
		(at 416.147758 -181.602888)
		(size 0.6604)
		(drill 0.3302)
		(layers "F.Cu" "B.Cu")
		(net "PVDDCR_SOC_P0")
	)
	(via
		(at 378.04471 -251.774198)
		(size 0.4064)
		(drill 0.2032)
		(layers "F.Cu" "B.Cu")
		(net "PVDDCR_SOC_P0")
	)
	(via
		(at 375.224802 -232.334054)
		(size 0.4064)
		(drill 0.2032)
		(layers "F.Cu" "B.Cu")
		(net "PVDDCR_SOC_P0")
	)
	(via
		(at 378.514864 -249.34418)
		(size 0.4064)
		(drill 0.2032)
		(layers "F.Cu" "B.Cu")
		(net "PVDDCR_SOC_P0")
	)
	(via
		(at 373.767604 -257.930142)
		(size 0.4826)
		(drill 0.254)
		(layers "F.Cu" "B.Cu")
		(net "PVDDCR_SOC_P0")
	)
	(via
		(at 384.624834 -256.634234)
		(size 0.4064)
		(drill 0.2032)
		(layers "F.Cu" "B.Cu")
		(net "PVDDCR_SOC_P0")
	)
	(via
		(at 375.224802 -255.014222)
		(size 0.4064)
		(drill 0.2032)
		(layers "F.Cu" "B.Cu")
		(net "PVDDCR_SOC_P0")
	)
	(via
		(at 351.087944 -262.748014)
		(size 0.4064)
		(drill 0.2032)
		(layers "F.Cu" "B.Cu")
		(net "PVDDCR_SOC_P0")
	)
	(via
		(at 417.430458 -175.747426)
		(size 0.508)
		(drill 0.254)
		(layers "F.Cu" "B.Cu")
		(net "PVDDCR_SOC_P0")
	)
	(via
		(at 404.415752 -184.407048)
		(size 0.508)
		(drill 0.254)
		(layers "F.Cu" "B.Cu")
		(net "PVDDCR_SOC_P0")
	)
	(via
		(at 371.93474 -252.584204)
		(size 0.4064)
		(drill 0.2032)
		(layers "F.Cu" "B.Cu")
		(net "PVDDCR_SOC_P0")
	)
	(via
		(at 373.814848 -255.824228)
		(size 0.4064)
		(drill 0.2032)
		(layers "F.Cu" "B.Cu")
		(net "PVDDCR_SOC_P0")
	)
	(via
		(at 395.403832 -191.079628)
		(size 0.508)
		(drill 0.254)
		(layers "F.Cu" "B.Cu")
		(net "PVDDCR_SOC_P0")
	)
	(via
		(at 357.487982 -255.472946)
		(size 0.4826)
		(drill 0.254)
		(layers "F.Cu" "B.Cu")
		(net "PVDDCR_SOC_P0")
	)
	(via
		(at 391.204704 -232.334054)
		(size 0.4064)
		(drill 0.2032)
		(layers "F.Cu" "B.Cu")
		(net "PVDDCR_SOC_P0")
	)
	(via
		(at 371.46484 -253.39421)
		(size 0.4064)
		(drill 0.2032)
		(layers "F.Cu" "B.Cu")
		(net "PVDDCR_SOC_P0")
	)
	(via
		(at 378.514864 -244.484144)
		(size 0.4064)
		(drill 0.2032)
		(layers "F.Cu" "B.Cu")
		(net "PVDDCR_SOC_P0")
	)
	(via
		(at 416.795458 -175.747426)
		(size 0.508)
		(drill 0.254)
		(layers "F.Cu" "B.Cu")
		(net "PVDDCR_SOC_P0")
	)
	(via
		(at 354.551234 -251.774198)
		(size 0.4064)
		(drill 0.2032)
		(layers "F.Cu" "B.Cu")
		(net "PVDDCR_SOC_P0")
	)
	(via
		(at 416.164522 -176.382426)
		(size 0.508)
		(drill 0.254)
		(layers "F.Cu" "B.Cu")
		(net "PVDDCR_SOC_P0")
	)
	(via
		(at 384.624834 -242.054126)
		(size 0.4064)
		(drill 0.2032)
		(layers "F.Cu" "B.Cu")
		(net "PVDDCR_SOC_P0")
	)
	(via
		(at 350.151192 -262.745982)
		(size 0.4064)
		(drill 0.2032)
		(layers "F.Cu" "B.Cu")
		(net "PVDDCR_SOC_P0")
	)
	(via
		(at 362.064808 -251.774198)
		(size 0.4064)
		(drill 0.2032)
		(layers "F.Cu" "B.Cu")
		(net "PVDDCR_SOC_P0")
	)
	(via
		(at 404.415752 -183.772048)
		(size 0.508)
		(drill 0.254)
		(layers "F.Cu" "B.Cu")
		(net "PVDDCR_SOC_P0")
	)
	(via
		(at 358.307894 -253.392178)
		(size 0.4064)
		(drill 0.2032)
		(layers "F.Cu" "B.Cu")
		(net "PVDDCR_SOC_P0")
	)
	(via
		(at 378.04471 -256.634234)
		(size 0.4064)
		(drill 0.2032)
		(layers "F.Cu" "B.Cu")
		(net "PVDDCR_SOC_P0")
	)
	(via
		(at 395.403832 -189.809628)
		(size 0.508)
		(drill 0.254)
		(layers "F.Cu" "B.Cu")
		(net "PVDDCR_SOC_P0")
	)
	(via
		(at 405.090376 -182.478426)
		(size 0.508)
		(drill 0.254)
		(layers "F.Cu" "B.Cu")
		(net "PVDDCR_SOC_P0")
	)
	(via
		(at 396.673832 -194.889628)
		(size 0.508)
		(drill 0.254)
		(layers "F.Cu" "B.Cu")
		(net "PVDDCR_SOC_P0")
	)
	(via
		(at 400.072352 -192.349628)
		(size 0.508)
		(drill 0.254)
		(layers "F.Cu" "B.Cu")
		(net "PVDDCR_SOC_P0")
	)
	(via
		(at 364.137956 -255.472946)
		(size 0.4826)
		(drill 0.254)
		(layers "F.Cu" "B.Cu")
		(net "PVDDCR_SOC_P0")
	)
	(via
		(at 412.779718 -180.216048)
		(size 0.508)
		(drill 0.254)
		(layers "F.Cu" "B.Cu")
		(net "PVDDCR_SOC_P0")
	)
	(via
		(at 416.799522 -177.017426)
		(size 0.508)
		(drill 0.254)
		(layers "F.Cu" "B.Cu")
		(net "PVDDCR_SOC_P0")
	)
	(via
		(at 396.673832 -192.984628)
		(size 0.508)
		(drill 0.254)
		(layers "F.Cu" "B.Cu")
		(net "PVDDCR_SOC_P0")
	)
	(via
		(at 369.584732 -251.774198)
		(size 0.4064)
		(drill 0.2032)
		(layers "F.Cu" "B.Cu")
		(net "PVDDCR_SOC_P0")
	)
	(via
		(at 400.707352 -191.714628)
		(size 0.508)
		(drill 0.254)
		(layers "F.Cu" "B.Cu")
		(net "PVDDCR_SOC_P0")
	)
	(via
		(at 378.514864 -239.624108)
		(size 0.4064)
		(drill 0.2032)
		(layers "F.Cu" "B.Cu")
		(net "PVDDCR_SOC_P0")
	)
	(via
		(at 391.204704 -222.614236)
		(size 0.4064)
		(drill 0.2032)
		(layers "F.Cu" "B.Cu")
		(net "PVDDCR_SOC_P0")
	)
	(via
		(at 413.414718 -178.946048)
		(size 0.508)
		(drill 0.254)
		(layers "F.Cu" "B.Cu")
		(net "PVDDCR_SOC_P0")
	)
	(via
		(at 416.782758 -178.935888)
		(size 0.508)
		(drill 0.254)
		(layers "F.Cu" "B.Cu")
		(net "PVDDCR_SOC_P0")
	)
	(via
		(at 396.673832 -195.524628)
		(size 0.508)
		(drill 0.254)
		(layers "F.Cu" "B.Cu")
		(net "PVDDCR_SOC_P0")
	)
	(via
		(at 404.455376 -181.208426)
		(size 0.508)
		(drill 0.254)
		(layers "F.Cu" "B.Cu")
		(net "PVDDCR_SOC_P0")
	)
	(via
		(at 413.414718 -179.581048)
		(size 0.508)
		(drill 0.254)
		(layers "F.Cu" "B.Cu")
		(net "PVDDCR_SOC_P0")
	)
	(via
		(at 404.455376 -181.843426)
		(size 0.508)
		(drill 0.254)
		(layers "F.Cu" "B.Cu")
		(net "PVDDCR_SOC_P0")
	)
	(via
		(at 407.833576 -182.478426)
		(size 0.508)
		(drill 0.254)
		(layers "F.Cu" "B.Cu")
		(net "PVDDCR_SOC_P0")
	)
	(via
		(at 408.461972 -183.772048)
		(size 0.508)
		(drill 0.254)
		(layers "F.Cu" "B.Cu")
		(net "PVDDCR_SOC_P0")
	)
	(via
		(at 399.418556 -190.420752)
		(size 0.508)
		(drill 0.254)
		(layers "F.Cu" "B.Cu")
		(net "PVDDCR_SOC_P0")
	)
	(via
		(at 405.090376 -181.208426)
		(size 0.508)
		(drill 0.254)
		(layers "F.Cu" "B.Cu")
		(net "PVDDCR_SOC_P0")
	)
	(via
		(at 374.584722 -262.745982)
		(size 0.4064)
		(drill 0.2032)
		(layers "F.Cu" "B.Cu")
		(net "PVDDCR_SOC_P0")
	)
	(via
		(at 366.295178 -257.430016)
		(size 0.4826)
		(drill 0.254)
		(layers "F.Cu" "B.Cu")
		(net "PVDDCR_SOC_P0")
	)
	(via
		(at 412.779718 -175.747426)
		(size 0.508)
		(drill 0.254)
		(layers "F.Cu" "B.Cu")
		(net "PVDDCR_SOC_P0")
	)
	(via
		(at 362.06811 -253.392178)
		(size 0.4064)
		(drill 0.2032)
		(layers "F.Cu" "B.Cu")
		(net "PVDDCR_SOC_P0")
	)
	(via
		(at 375.224802 -229.094284)
		(size 0.4064)
		(drill 0.2032)
		(layers "F.Cu" "B.Cu")
		(net "PVDDCR_SOC_P0")
	)
	(via
		(at 385.094734 -229.904036)
		(size 0.4064)
		(drill 0.2032)
		(layers "F.Cu" "B.Cu")
		(net "PVDDCR_SOC_P0")
	)
	(via
		(at 384.624834 -227.474272)
		(size 0.4064)
		(drill 0.2032)
		(layers "F.Cu" "B.Cu")
		(net "PVDDCR_SOC_P0")
	)
	(via
		(at 385.094734 -254.204216)
		(size 0.4064)
		(drill 0.2032)
		(layers "F.Cu" "B.Cu")
		(net "PVDDCR_SOC_P0")
	)
	(via
		(at 371.93474 -255.824228)
		(size 0.4064)
		(drill 0.2032)
		(layers "F.Cu" "B.Cu")
		(net "PVDDCR_SOC_P0")
	)
	(via
		(at 405.050752 -186.312048)
		(size 0.508)
		(drill 0.254)
		(layers "F.Cu" "B.Cu")
		(net "PVDDCR_SOC_P0")
	)
	(via
		(at 371.989604 -257.930142)
		(size 0.4826)
		(drill 0.254)
		(layers "F.Cu" "B.Cu")
		(net "PVDDCR_SOC_P0")
	)
	(via
		(at 413.421322 -177.017426)
		(size 0.508)
		(drill 0.254)
		(layers "F.Cu" "B.Cu")
		(net "PVDDCR_SOC_P0")
	)
	(via
		(at 409.096972 -183.772048)
		(size 0.508)
		(drill 0.254)
		(layers "F.Cu" "B.Cu")
		(net "PVDDCR_SOC_P0")
	)
	(via
		(at 409.099512 -180.573426)
		(size 0.508)
		(drill 0.254)
		(layers "F.Cu" "B.Cu")
		(net "PVDDCR_SOC_P0")
	)
	(via
		(at 396.673832 -194.254628)
		(size 0.508)
		(drill 0.254)
		(layers "F.Cu" "B.Cu")
		(net "PVDDCR_SOC_P0")
	)
	(via
		(at 391.204704 -242.054126)
		(size 0.4064)
		(drill 0.2032)
		(layers "F.Cu" "B.Cu")
		(net "PVDDCR_SOC_P0")
	)
	(via
		(at 413.421322 -177.652426)
		(size 0.508)
		(drill 0.254)
		(layers "F.Cu" "B.Cu")
		(net "PVDDCR_SOC_P0")
	)
	(via
		(at 391.204704 -246.914162)
		(size 0.4064)
		(drill 0.2032)
		(layers "F.Cu" "B.Cu")
		(net "PVDDCR_SOC_P0")
	)
	(via
		(at 391.674858 -254.204216)
		(size 0.4064)
		(drill 0.2032)
		(layers "F.Cu" "B.Cu")
		(net "PVDDCR_SOC_P0")
	)
	(via
		(at 395.403832 -190.444628)
		(size 0.508)
		(drill 0.254)
		(layers "F.Cu" "B.Cu")
		(net "PVDDCR_SOC_P0")
	)
	(via
		(at 385.094734 -234.764072)
		(size 0.4064)
		(drill 0.2032)
		(layers "F.Cu" "B.Cu")
		(net "PVDDCR_SOC_P0")
	)
	(via
		(at 371.46484 -256.634234)
		(size 0.4064)
		(drill 0.2032)
		(layers "F.Cu" "B.Cu")
		(net "PVDDCR_SOC_P0")
	)
	(via
		(at 395.403832 -196.286628)
		(size 0.6604)
		(drill 0.3302)
		(layers "F.Cu" "B.Cu")
		(net "PVDDCR_SOC_P0")
	)
	(via
		(at 365.82477 -251.774198)
		(size 0.4064)
		(drill 0.2032)
		(layers "F.Cu" "B.Cu")
		(net "PVDDCR_SOC_P0")
	)
	(via
		(at 385.094734 -249.34418)
		(size 0.4064)
		(drill 0.2032)
		(layers "F.Cu" "B.Cu")
		(net "PVDDCR_SOC_P0")
	)
	(via
		(at 359.387902 -255.472946)
		(size 0.4826)
		(drill 0.254)
		(layers "F.Cu" "B.Cu")
		(net "PVDDCR_SOC_P0")
	)
	(via
		(at 399.437352 -193.746628)
		(size 0.6604)
		(drill 0.3302)
		(layers "F.Cu" "B.Cu")
		(net "PVDDCR_SOC_P0")
	)
	(via
		(at 391.204704 -237.19409)
		(size 0.4064)
		(drill 0.2032)
		(layers "F.Cu" "B.Cu")
		(net "PVDDCR_SOC_P0")
	)
	(via
		(at 395.403832 -194.889628)
		(size 0.508)
		(drill 0.254)
		(layers "F.Cu" "B.Cu")
		(net "PVDDCR_SOC_P0")
	)
	(via
		(at 348.911164 -253.39421)
		(size 0.4064)
		(drill 0.2032)
		(layers "F.Cu" "B.Cu")
		(net "PVDDCR_SOC_P0")
	)
	(via
		(at 378.04471 -237.19409)
		(size 0.4064)
		(drill 0.2032)
		(layers "F.Cu" "B.Cu")
		(net "PVDDCR_SOC_P0")
	)
	(via
		(at 360.607864 -257.744976)
		(size 0.4826)
		(drill 0.254)
		(layers "F.Cu" "B.Cu")
		(net "PVDDCR_SOC_P0")
	)
	(via
		(at 369.584732 -255.014222)
		(size 0.4064)
		(drill 0.2032)
		(layers "F.Cu" "B.Cu")
		(net "PVDDCR_SOC_P0")
	)
	(via
		(at 407.833576 -181.208426)
		(size 0.508)
		(drill 0.254)
		(layers "F.Cu" "B.Cu")
		(net "PVDDCR_SOC_P0")
	)
	(via
		(at 358.311196 -251.774198)
		(size 0.4064)
		(drill 0.2032)
		(layers "F.Cu" "B.Cu")
		(net "PVDDCR_SOC_P0")
	)
	(via
		(at 391.504678 -265.986006)
		(size 0.4064)
		(drill 0.2032)
		(layers "F.Cu" "B.Cu")
		(net "PVDDCR_SOC_P0")
	)
	(via
		(at 396.040356 -189.785752)
		(size 0.508)
		(drill 0.254)
		(layers "F.Cu" "B.Cu")
		(net "PVDDCR_SOC_P0")
	)
	(via
		(at 350.621092 -263.555988)
		(size 0.4064)
		(drill 0.2032)
		(layers "F.Cu" "B.Cu")
		(net "PVDDCR_SOC_P0")
	)
	(via
		(at 417.417758 -180.21554)
		(size 0.508)
		(drill 0.254)
		(layers "F.Cu" "B.Cu")
		(net "PVDDCR_SOC_P0")
	)
	(via
		(at 413.414718 -175.747426)
		(size 0.508)
		(drill 0.254)
		(layers "F.Cu" "B.Cu")
		(net "PVDDCR_SOC_P0")
	)
	(via
		(at 412.779718 -180.851048)
		(size 0.508)
		(drill 0.254)
		(layers "F.Cu" "B.Cu")
		(net "PVDDCR_SOC_P0")
	)
	(via
		(at 416.160458 -175.747426)
		(size 0.508)
		(drill 0.254)
		(layers "F.Cu" "B.Cu")
		(net "PVDDCR_SOC_P0")
	)
	(via
		(at 373.814848 -254.204216)
		(size 0.4064)
		(drill 0.2032)
		(layers "F.Cu" "B.Cu")
		(net "PVDDCR_SOC_P0")
	)
	(via
		(at 400.053556 -189.785752)
		(size 0.508)
		(drill 0.254)
		(layers "F.Cu" "B.Cu")
		(net "PVDDCR_SOC_P0")
	)
	(via
		(at 417.453318 -178.311302)
		(size 0.508)
		(drill 0.254)
		(layers "F.Cu" "B.Cu")
		(net "PVDDCR_SOC_P0")
	)
	(via
		(at 356.538022 -255.472946)
		(size 0.4826)
		(drill 0.254)
		(layers "F.Cu" "B.Cu")
		(net "PVDDCR_SOC_P0")
	)
	(via
		(at 363.207808 -257.744976)
		(size 0.4826)
		(drill 0.254)
		(layers "F.Cu" "B.Cu")
		(net "PVDDCR_SOC_P0")
	)
	(via
		(at 369.584732 -253.39421)
		(size 0.4064)
		(drill 0.2032)
		(layers "F.Cu" "B.Cu")
		(net "PVDDCR_SOC_P0")
	)
	(via
		(at 412.786322 -176.382426)
		(size 0.508)
		(drill 0.254)
		(layers "F.Cu" "B.Cu")
		(net "PVDDCR_SOC_P0")
	)
	(via
		(at 378.04471 -246.914162)
		(size 0.4064)
		(drill 0.2032)
		(layers "F.Cu" "B.Cu")
		(net "PVDDCR_SOC_P0")
	)
	(via
		(at 366.295178 -261.23011)
		(size 0.4826)
		(drill 0.254)
		(layers "F.Cu" "B.Cu")
		(net "PVDDCR_SOC_P0")
	)
	(via
		(at 385.394708 -263.555988)
		(size 0.4064)
		(drill 0.2032)
		(layers "F.Cu" "B.Cu")
		(net "PVDDCR_SOC_P0")
	)
	(via
		(at 374.584722 -261.12597)
		(size 0.4064)
		(drill 0.2032)
		(layers "F.Cu" "B.Cu")
		(net "PVDDCR_SOC_P0")
	)
	(via
		(at 417.453318 -176.406302)
		(size 0.508)
		(drill 0.254)
		(layers "F.Cu" "B.Cu")
		(net "PVDDCR_SOC_P0")
	)
	(via
		(at 375.224802 -240.434114)
		(size 0.4064)
		(drill 0.2032)
		(layers "F.Cu" "B.Cu")
		(net "PVDDCR_SOC_P0")
	)
	(via
		(at 416.147758 -178.935888)
		(size 0.508)
		(drill 0.254)
		(layers "F.Cu" "B.Cu")
		(net "PVDDCR_SOC_P0")
	)
	(via
		(at 360.337862 -255.472946)
		(size 0.4826)
		(drill 0.254)
		(layers "F.Cu" "B.Cu")
		(net "PVDDCR_SOC_P0")
	)
	(via
		(at 400.053556 -191.690752)
		(size 0.508)
		(drill 0.254)
		(layers "F.Cu" "B.Cu")
		(net "PVDDCR_SOC_P0")
	)
	(via
		(at 409.122372 -183.137302)
		(size 0.508)
		(drill 0.254)
		(layers "F.Cu" "B.Cu")
		(net "PVDDCR_SOC_P0")
	)
	(via
		(at 400.684492 -189.150752)
		(size 0.508)
		(drill 0.254)
		(layers "F.Cu" "B.Cu")
		(net "PVDDCR_SOC_P0")
	)
	(via
		(at 407.826972 -185.042048)
		(size 0.508)
		(drill 0.254)
		(layers "F.Cu" "B.Cu")
		(net "PVDDCR_SOC_P0")
	)
	(via
		(at 413.414718 -180.851048)
		(size 0.508)
		(drill 0.254)
		(layers "F.Cu" "B.Cu")
		(net "PVDDCR_SOC_P0")
	)
	(via
		(at 417.833556 -159.985964)
		(size 0.508)
		(drill 0.254)
		(layers "F.Cu" "B.Cu")
		(net "PVDDCR_SOC_P0")
	)
	(via
		(at 412.786322 -178.287426)
		(size 0.508)
		(drill 0.254)
		(layers "F.Cu" "B.Cu")
		(net "PVDDCR_SOC_P0")
	)
	(via
		(at 373.344694 -255.014222)
		(size 0.4064)
		(drill 0.2032)
		(layers "F.Cu" "B.Cu")
		(net "PVDDCR_SOC_P0")
	)
	(via
		(at 356.431088 -251.774198)
		(size 0.4064)
		(drill 0.2032)
		(layers "F.Cu" "B.Cu")
		(net "PVDDCR_SOC_P0")
	)
	(via
		(at 404.415752 -186.312048)
		(size 0.508)
		(drill 0.254)
		(layers "F.Cu" "B.Cu")
		(net "PVDDCR_SOC_P0")
	)
	(via
		(at 396.673832 -192.349628)
		(size 0.508)
		(drill 0.254)
		(layers "F.Cu" "B.Cu")
		(net "PVDDCR_SOC_P0")
	)
	(via
		(at 358.437942 -255.472946)
		(size 0.4826)
		(drill 0.254)
		(layers "F.Cu" "B.Cu")
		(net "PVDDCR_SOC_P0")
	)
	(via
		(at 412.786322 -177.017426)
		(size 0.508)
		(drill 0.254)
		(layers "F.Cu" "B.Cu")
		(net "PVDDCR_SOC_P0")
	)
	(via
		(at 408.468576 -181.843426)
		(size 0.508)
		(drill 0.254)
		(layers "F.Cu" "B.Cu")
		(net "PVDDCR_SOC_P0")
	)
	(via
		(at 391.674858 -244.484144)
		(size 0.4064)
		(drill 0.2032)
		(layers "F.Cu" "B.Cu")
		(net "PVDDCR_SOC_P0")
	)
	(via
		(at 416.147758 -179.570888)
		(size 0.508)
		(drill 0.254)
		(layers "F.Cu" "B.Cu")
		(net "PVDDCR_SOC_P0")
	)
	(via
		(at 395.403832 -191.714628)
		(size 0.508)
		(drill 0.254)
		(layers "F.Cu" "B.Cu")
		(net "PVDDCR_SOC_P0")
	)
	(via
		(at 416.164522 -177.652426)
		(size 0.508)
		(drill 0.254)
		(layers "F.Cu" "B.Cu")
		(net "PVDDCR_SOC_P0")
	)
	(via
		(at 399.437352 -192.349628)
		(size 0.508)
		(drill 0.254)
		(layers "F.Cu" "B.Cu")
		(net "PVDDCR_SOC_P0")
	)
	(via
		(at 384.624834 -251.774198)
		(size 0.4064)
		(drill 0.2032)
		(layers "F.Cu" "B.Cu")
		(net "PVDDCR_SOC_P0")
	)
	(via
		(at 416.782758 -180.205888)
		(size 0.508)
		(drill 0.254)
		(layers "F.Cu" "B.Cu")
		(net "PVDDCR_SOC_P0")
	)
	(via
		(at 350.151192 -261.12597)
		(size 0.4064)
		(drill 0.2032)
		(layers "F.Cu" "B.Cu")
		(net "PVDDCR_SOC_P0")
	)
	(via
		(at 391.674858 -234.764072)
		(size 0.4064)
		(drill 0.2032)
		(layers "F.Cu" "B.Cu")
		(net "PVDDCR_SOC_P0")
	)
	(via
		(at 373.814848 -250.964192)
		(size 0.4064)
		(drill 0.2032)
		(layers "F.Cu" "B.Cu")
		(net "PVDDCR_SOC_P0")
	)
	(via
		(at 372.704868 -262.745982)
		(size 0.4064)
		(drill 0.2032)
		(layers "F.Cu" "B.Cu")
		(net "PVDDCR_SOC_P0")
	)
	(via
		(at 407.826972 -183.772048)
		(size 0.508)
		(drill 0.254)
		(layers "F.Cu" "B.Cu")
		(net "PVDDCR_SOC_P0")
	)
	(via
		(at 416.147758 -180.205888)
		(size 0.508)
		(drill 0.254)
		(layers "F.Cu" "B.Cu")
		(net "PVDDCR_SOC_P0")
	)
	(via
		(at 371.989604 -258.830064)
		(size 0.4826)
		(drill 0.254)
		(layers "F.Cu" "B.Cu")
		(net "PVDDCR_SOC_P0")
	)
	(via
		(at 391.674858 -249.34418)
		(size 0.4064)
		(drill 0.2032)
		(layers "F.Cu" "B.Cu")
		(net "PVDDCR_SOC_P0")
	)
	(via
		(at 385.094734 -239.624108)
		(size 0.4064)
		(drill 0.2032)
		(layers "F.Cu" "B.Cu")
		(net "PVDDCR_SOC_P0")
	)
	(via
		(at 407.826972 -184.407048)
		(size 0.508)
		(drill 0.254)
		(layers "F.Cu" "B.Cu")
		(net "PVDDCR_SOC_P0")
	)
	(via
		(at 412.779718 -179.581048)
		(size 0.508)
		(drill 0.254)
		(layers "F.Cu" "B.Cu")
		(net "PVDDCR_SOC_P0")
	)
	(via
		(at 371.294914 -261.935976)
		(size 0.4064)
		(drill 0.2032)
		(layers "F.Cu" "B.Cu")
		(net "PVDDCR_SOC_P0")
	)
	(via
		(at 378.514864 -254.204216)
		(size 0.4064)
		(drill 0.2032)
		(layers "F.Cu" "B.Cu")
		(net "PVDDCR_SOC_P0")
	)
	(via
		(at 391.974832 -263.555988)
		(size 0.4064)
		(drill 0.2032)
		(layers "F.Cu" "B.Cu")
		(net "PVDDCR_SOC_P0")
	)
	(via
		(at 357.841042 -250.964192)
		(size 0.4064)
		(drill 0.2032)
		(layers "F.Cu" "B.Cu")
		(net "PVDDCR_SOC_P0")
	)
	(via
		(at 396.040356 -190.420752)
		(size 0.508)
		(drill 0.254)
		(layers "F.Cu" "B.Cu")
		(net "PVDDCR_SOC_P0")
	)
	(via
		(at 362.238036 -255.472946)
		(size 0.4826)
		(drill 0.254)
		(layers "F.Cu" "B.Cu")
		(net "PVDDCR_SOC_P0")
	)
	(via
		(at 363.944916 -251.774198)
		(size 0.4064)
		(drill 0.2032)
		(layers "F.Cu" "B.Cu")
		(net "PVDDCR_SOC_P0")
	)
	(via
		(at 396.673832 -193.619628)
		(size 0.508)
		(drill 0.254)
		(layers "F.Cu" "B.Cu")
		(net "PVDDCR_SOC_P0")
	)
	(via
		(at 404.415752 -186.947048)
		(size 0.508)
		(drill 0.254)
		(layers "F.Cu" "B.Cu")
		(net "PVDDCR_SOC_P0")
	)
	(via
		(at 384.624834 -232.334054)
		(size 0.4064)
		(drill 0.2032)
		(layers "F.Cu" "B.Cu")
		(net "PVDDCR_SOC_P0")
	)
	(via
		(at 350.321118 -252.584204)
		(size 0.4064)
		(drill 0.2032)
		(layers "F.Cu" "B.Cu")
		(net "PVDDCR_SOC_P0")
	)
	(via
		(at 409.451556 -164.811964)
		(size 0.508)
		(drill 0.254)
		(layers "F.Cu" "B.Cu")
		(net "PVDDCR_SOC_P0")
	)
	(via
		(at 355.588062 -255.472946)
		(size 0.4826)
		(drill 0.254)
		(layers "F.Cu" "B.Cu")
		(net "PVDDCR_SOC_P0")
	)
	(via
		(at 348.911164 -255.014222)
		(size 0.4064)
		(drill 0.2032)
		(layers "F.Cu" "B.Cu")
		(net "PVDDCR_SOC_P0")
	)
	(via
		(at 378.04471 -227.474272)
		(size 0.4064)
		(drill 0.2032)
		(layers "F.Cu" "B.Cu")
		(net "PVDDCR_SOC_P0")
	)
	(via
		(at 405.083772 -180.573426)
		(size 0.508)
		(drill 0.254)
		(layers "F.Cu" "B.Cu")
		(net "PVDDCR_SOC_P0")
	)
	(segment
		(start 401.485608 -173.746922)
		(end 401.127976 -173.38929)
		(width 0.381)
		(layer "B.Cu")
		(net "PVDDCR_SOC_P0")
	)
	(segment
		(start 401.485608 -174.105824)
		(end 401.485608 -173.746922)
		(width 0.381)
		(layer "B.Cu")
		(net "PVDDCR_SOC_P0")
	)
	(segment
		(start 418.191188 -160.343596)
		(end 417.833556 -159.985964)
		(width 0.381)
		(layer "B.Cu")
		(net "PVDDCR_SOC_P0")
	)
	(segment
		(start 409.809188 -165.169596)
		(end 409.451556 -164.811964)
		(width 0.381)
		(layer "B.Cu")
		(net "PVDDCR_SOC_P0")
	)
	(segment
		(start 418.191188 -160.702498)
		(end 418.191188 -160.343596)
		(width 0.381)
		(layer "B.Cu")
		(net "PVDDCR_SOC_P0")
	)
	(segment
		(start 409.809188 -165.528498)
		(end 409.809188 -165.169596)
		(width 0.381)
		(layer "B.Cu")
		(net "PVDDCR_SOC_P0")
	)
	(segment
		(start 401.127976 -173.38929)
		(end 401.419314 -173.680628)
		(width 0.381)
		(layer "In2.Cu")
		(net "PVDDCR_SOC_P0")
	)
	(segment
		(start 409.099512 -180.573426)
		(end 409.099512 -180.103272)
		(width 0.381)
		(layer "In2.Cu")
		(net "PVDDCR_SOC_P0")
	)
	(segment
		(start 401.419314 -174.520352)
		(end 400.394678 -175.544988)
		(width 0.381)
		(layer "In2.Cu")
		(net "PVDDCR_SOC_P0")
	)
	(segment
		(start 408.725878 -179.729638)
		(end 408.725878 -166.960042)
		(width 0.381)
		(layer "In2.Cu")
		(net "PVDDCR_SOC_P0")
	)
	(segment
		(start 417.833556 -159.985964)
		(end 418.124894 -160.277302)
		(width 0.381)
		(layer "In2.Cu")
		(net "PVDDCR_SOC_P0")
	)
	(segment
		(start 408.725878 -166.960042)
		(end 409.742894 -165.943026)
		(width 0.381)
		(layer "In2.Cu")
		(net "PVDDCR_SOC_P0")
	)
	(segment
		(start 418.124894 -161.117026)
		(end 417.082478 -162.159442)
		(width 0.381)
		(layer "In2.Cu")
		(net "PVDDCR_SOC_P0")
	)
	(segment
		(start 400.394678 -180.649118)
		(end 400.049492 -180.994304)
		(width 0.381)
		(layer "In2.Cu")
		(net "PVDDCR_SOC_P0")
	)
	(segment
		(start 417.082478 -166.41191)
		(end 417.430458 -166.75989)
		(width 0.381)
		(layer "In2.Cu")
		(net "PVDDCR_SOC_P0")
	)
	(segment
		(start 409.742894 -165.943026)
		(end 409.742894 -165.103302)
		(width 0.381)
		(layer "In2.Cu")
		(net "PVDDCR_SOC_P0")
	)
	(segment
		(start 400.049492 -180.994304)
		(end 400.049492 -189.150752)
		(width 0.381)
		(layer "In2.Cu")
		(net "PVDDCR_SOC_P0")
	)
	(segment
		(start 409.099512 -180.103272)
		(end 408.725878 -179.729638)
		(width 0.381)
		(layer "In2.Cu")
		(net "PVDDCR_SOC_P0")
	)
	(segment
		(start 401.419314 -173.680628)
		(end 401.419314 -174.520352)
		(width 0.381)
		(layer "In2.Cu")
		(net "PVDDCR_SOC_P0")
	)
	(segment
		(start 418.124894 -160.277302)
		(end 418.124894 -161.117026)
		(width 0.381)
		(layer "In2.Cu")
		(net "PVDDCR_SOC_P0")
	)
	(segment
		(start 417.430458 -166.75989)
		(end 417.430458 -175.747426)
		(width 0.381)
		(layer "In2.Cu")
		(net "PVDDCR_SOC_P0")
	)
	(segment
		(start 409.742894 -165.103302)
		(end 409.451556 -164.811964)
		(width 0.381)
		(layer "In2.Cu")
		(net "PVDDCR_SOC_P0")
	)
	(segment
		(start 417.082478 -162.159442)
		(end 417.082478 -166.41191)
		(width 0.381)
		(layer "In2.Cu")
		(net "PVDDCR_SOC_P0")
	)
	(segment
		(start 400.394678 -175.544988)
		(end 400.394678 -180.649118)
		(width 0.381)
		(layer "In2.Cu")
		(net "PVDDCR_SOC_P0")
	)
	(segment
		(start 101.329236 -342.50122)
		(end 101.004624 -342.825832)
		(width 0.2032)
		(layer "F.Cu")
		(net "PVDDCR_CPU1_P1_VOS6")
	)
	(segment
		(start 101.329236 -342.214454)
		(end 101.329236 -342.50122)
		(width 0.2032)
		(layer "F.Cu")
		(net "PVDDCR_CPU1_P1_VOS6")
	)
	(via
		(at 101.004624 -342.825832)
		(size 0.508)
		(drill 0.254)
		(layers "F.Cu" "B.Cu")
		(net "PVDDCR_CPU1_P1_VOS6")
	)
	(segment
		(start 100.38334 -342.204548)
		(end 101.004624 -342.825832)
		(width 0.254)
		(layer "B.Cu")
		(net "PVDDCR_CPU1_P1_VOS6")
	)
	(segment
		(start 100.067872 -342.204548)
		(end 100.38334 -342.204548)
		(width 0.254)
		(layer "B.Cu")
		(net "PVDDCR_CPU1_P1_VOS6")
	)
	(segment
		(start 93.053408 -337.591146)
		(end 93.053408 -337.30438)
		(width 0.2032)
		(layer "F.Cu")
		(net "PVDDCR_CPU1_P1_VOS5")
	)
	(segment
		(start 92.728796 -337.915758)
		(end 93.053408 -337.591146)
		(width 0.2032)
		(layer "F.Cu")
		(net "PVDDCR_CPU1_P1_VOS5")
	)
	(via
		(at 92.728796 -337.915758)
		(size 0.508)
		(drill 0.254)
		(layers "F.Cu" "B.Cu")
		(net "PVDDCR_CPU1_P1_VOS5")
	)
	(segment
		(start 92.107512 -337.294474)
		(end 92.728796 -337.915758)
		(width 0.254)
		(layer "B.Cu")
		(net "PVDDCR_CPU1_P1_VOS5")
	)
	(segment
		(start 91.792044 -337.294474)
		(end 92.107512 -337.294474)
		(width 0.254)
		(layer "B.Cu")
		(net "PVDDCR_CPU1_P1_VOS5")
	)
	(segment
		(start 59.474608 -348.996254)
		(end 59.474608 -349.28302)
		(width 0.2032)
		(layer "F.Cu")
		(net "PVDDCR_CPU1_P1_VOS4")
	)
	(segment
		(start 59.474608 -349.28302)
		(end 59.149996 -349.607632)
		(width 0.2032)
		(layer "F.Cu")
		(net "PVDDCR_CPU1_P1_VOS4")
	)
	(via
		(at 59.149996 -349.607632)
		(size 0.508)
		(drill 0.254)
		(layers "F.Cu" "B.Cu")
		(net "PVDDCR_CPU1_P1_VOS4")
	)
	(segment
		(start 58.213244 -348.986348)
		(end 58.528712 -348.986348)
		(width 0.2286)
		(layer "B.Cu")
		(net "PVDDCR_CPU1_P1_VOS4")
	)
	(segment
		(start 58.528712 -348.986348)
		(end 59.149996 -349.607632)
		(width 0.2286)
		(layer "B.Cu")
		(net "PVDDCR_CPU1_P1_VOS4")
	)
	(segment
		(start 68.009008 -337.561936)
		(end 67.684396 -337.886548)
		(width 0.2032)
		(layer "F.Cu")
		(net "PVDDCR_CPU1_P1_VOS3")
	)
	(segment
		(start 68.009008 -337.27517)
		(end 68.009008 -337.561936)
		(width 0.2032)
		(layer "F.Cu")
		(net "PVDDCR_CPU1_P1_VOS3")
	)
	(via
		(at 67.684396 -337.886548)
		(size 0.508)
		(drill 0.254)
		(layers "F.Cu" "B.Cu")
		(net "PVDDCR_CPU1_P1_VOS3")
	)
	(segment
		(start 66.747644 -337.265264)
		(end 67.063112 -337.265264)
		(width 0.254)
		(layer "B.Cu")
		(net "PVDDCR_CPU1_P1_VOS3")
	)
	(segment
		(start 67.063112 -337.265264)
		(end 67.684396 -337.886548)
		(width 0.254)
		(layer "B.Cu")
		(net "PVDDCR_CPU1_P1_VOS3")
	)
	(segment
		(start 76.364592 -337.554824)
		(end 76.03998 -337.879436)
		(width 0.2032)
		(layer "F.Cu")
		(net "PVDDCR_CPU1_P1_VOS2")
	)
	(segment
		(start 76.364592 -337.268058)
		(end 76.364592 -337.554824)
		(width 0.2032)
		(layer "F.Cu")
		(net "PVDDCR_CPU1_P1_VOS2")
	)
	(via
		(at 76.03998 -337.879436)
		(size 0.508)
		(drill 0.254)
		(layers "F.Cu" "B.Cu")
		(net "PVDDCR_CPU1_P1_VOS2")
	)
	(segment
		(start 75.418696 -337.258152)
		(end 76.03998 -337.879436)
		(width 0.254)
		(layer "B.Cu")
		(net "PVDDCR_CPU1_P1_VOS2")
	)
	(segment
		(start 75.103228 -337.258152)
		(end 75.418696 -337.258152)
		(width 0.254)
		(layer "B.Cu")
		(net "PVDDCR_CPU1_P1_VOS2")
	)
	(segment
		(start 84.722208 -337.540346)
		(end 84.397596 -337.864958)
		(width 0.2032)
		(layer "F.Cu")
		(net "PVDDCR_CPU1_P1_VOS1")
	)
	(segment
		(start 84.722208 -337.25358)
		(end 84.722208 -337.540346)
		(width 0.2032)
		(layer "F.Cu")
		(net "PVDDCR_CPU1_P1_VOS1")
	)
	(via
		(at 84.397596 -337.864958)
		(size 0.508)
		(drill 0.254)
		(layers "F.Cu" "B.Cu")
		(net "PVDDCR_CPU1_P1_VOS1")
	)
	(segment
		(start 83.776312 -337.243674)
		(end 84.397596 -337.864958)
		(width 0.254)
		(layer "B.Cu")
		(net "PVDDCR_CPU1_P1_VOS1")
	)
	(segment
		(start 83.460844 -337.243674)
		(end 83.776312 -337.243674)
		(width 0.254)
		(layer "B.Cu")
		(net "PVDDCR_CPU1_P1_VOS1")
	)
	(segment
		(start 34.527744 -365.108998)
		(end 34.530792 -365.10595)
		(width 0.1778)
		(layer "F.Cu")
		(net "PVDDCR_CPU1_P1_VMON")
	)
	(segment
		(start 34.530792 -365.10595)
		(end 35.45205 -365.10595)
		(width 0.254)
		(layer "F.Cu")
		(net "PVDDCR_CPU1_P1_VMON")
	)
	(segment
		(start 35.45205 -365.10595)
		(end 35.687 -364.871)
		(width 0.254)
		(layer "F.Cu")
		(net "PVDDCR_CPU1_P1_VMON")
	)
	(segment
		(start 33.355026 -365.108998)
		(end 34.527744 -365.108998)
		(width 0.1778)
		(layer "F.Cu")
		(net "PVDDCR_CPU1_P1_VMON")
	)
	(segment
		(start 35.687 -364.871)
		(end 35.944556 -364.871)
		(width 0.254)
		(layer "F.Cu")
		(net "PVDDCR_CPU1_P1_VMON")
	)
	(segment
		(start 35.944556 -364.871)
		(end 36.55695 -364.871)
		(width 0.254)
		(layer "F.Cu")
		(net "PVDDCR_CPU1_P1_VMON")
	)
	(segment
		(start 36.55695 -364.871)
		(end 36.81095 -365.125)
		(width 0.254)
		(layer "F.Cu")
		(net "PVDDCR_CPU1_P1_VMON")
	)
	(via
		(at 35.944556 -364.871)
		(size 0.762)
		(drill 0.254)
		(layers "F.Cu" "B.Cu")
		(net "PVDDCR_CPU1_P1_VMON")
	)
	(segment
		(start 35.56 -364.871)
		(end 35.944556 -364.871)
		(width 0.254)
		(layer "B.Cu")
		(net "PVDDCR_CPU1_P1_VMON")
	)
	(segment
		(start 34.94405 -362.966)
		(end 35.179 -363.20095)
		(width 0.254)
		(layer "B.Cu")
		(net "PVDDCR_CPU1_P1_VMON")
	)
	(segment
		(start 35.179 -364.49)
		(end 35.56 -364.871)
		(width 0.254)
		(layer "B.Cu")
		(net "PVDDCR_CPU1_P1_VMON")
	)
	(segment
		(start 34.90595 -362.9279)
		(end 34.94405 -362.966)
		(width 0.254)
		(layer "B.Cu")
		(net "PVDDCR_CPU1_P1_VMON")
	)
	(segment
		(start 34.90595 -361.95)
		(end 34.90595 -362.9279)
		(width 0.254)
		(layer "B.Cu")
		(net "PVDDCR_CPU1_P1_VMON")
	)
	(segment
		(start 35.179 -363.20095)
		(end 35.179 -364.49)
		(width 0.254)
		(layer "B.Cu")
		(net "PVDDCR_CPU1_P1_VMON")
	)
	(segment
		(start 34.804604 -365.633)
		(end 34.417 -365.633)
		(width 0.1778)
		(layer "F.Cu")
		(net "PVDDCR_CPU1_P1_VINSEN")
	)
	(segment
		(start 38.354 -367.17605)
		(end 37.338 -367.17605)
		(width 0.254)
		(layer "F.Cu")
		(net "PVDDCR_CPU1_P1_VINSEN")
	)
	(segment
		(start 34.417 -365.633)
		(end 34.293048 -365.509048)
		(width 0.1778)
		(layer "F.Cu")
		(net "PVDDCR_CPU1_P1_VINSEN")
	)
	(segment
		(start 37.338 -367.17605)
		(end 36.449 -367.17605)
		(width 0.254)
		(layer "F.Cu")
		(net "PVDDCR_CPU1_P1_VINSEN")
	)
	(segment
		(start 35.055302 -365.883698)
		(end 34.804604 -365.633)
		(width 0.254)
		(layer "F.Cu")
		(net "PVDDCR_CPU1_P1_VINSEN")
	)
	(segment
		(start 36.338764 -367.175542)
		(end 35.055302 -365.883698)
		(width 0.254)
		(layer "F.Cu")
		(net "PVDDCR_CPU1_P1_VINSEN")
	)
	(segment
		(start 34.293048 -365.509048)
		(end 33.355026 -365.509048)
		(width 0.1778)
		(layer "F.Cu")
		(net "PVDDCR_CPU1_P1_VINSEN")
	)
	(segment
		(start 36.449 -367.17605)
		(end 36.338764 -367.175542)
		(width 0.254)
		(layer "F.Cu")
		(net "PVDDCR_CPU1_P1_VINSEN")
	)
	(via
		(at 35.055302 -365.883698)
		(size 0.508)
		(drill 0.254)
		(layers "F.Cu" "B.Cu")
		(net "PVDDCR_CPU1_P1_VINSEN")
	)
	(segment
		(start 25.90673 -350.515682)
		(end 25.90673 -351.178622)
		(width 0.2286)
		(layer "F.Cu")
		(net "PVDDCR_CPU1_P1_VCCS")
	)
	(segment
		(start 50.84953 -351.178622)
		(end 51.578002 -351.178622)
		(width 0.254)
		(layer "F.Cu")
		(net "PVDDCR_CPU1_P1_VCCS")
	)
	(segment
		(start 34.18713 -351.178622)
		(end 34.915602 -351.178622)
		(width 0.254)
		(layer "F.Cu")
		(net "PVDDCR_CPU1_P1_VCCS")
	)
	(segment
		(start 34.890964 -349.621094)
		(end 34.890964 -349.811848)
		(width 0.2286)
		(layer "F.Cu")
		(net "PVDDCR_CPU1_P1_VCCS")
	)
	(segment
		(start 67.71513 -339.457538)
		(end 67.71513 -338.794598)
		(width 0.2286)
		(layer "F.Cu")
		(net "PVDDCR_CPU1_P1_VCCS")
	)
	(segment
		(start 25.90673 -351.178622)
		(end 26.635202 -351.178622)
		(width 0.254)
		(layer "F.Cu")
		(net "PVDDCR_CPU1_P1_VCCS")
	)
	(segment
		(start 92.75953 -339.486748)
		(end 92.75953 -338.823808)
		(width 0.2286)
		(layer "F.Cu")
		(net "PVDDCR_CPU1_P1_VCCS")
	)
	(segment
		(start 51.553364 -349.621094)
		(end 51.553364 -349.811848)
		(width 0.2286)
		(layer "F.Cu")
		(net "PVDDCR_CPU1_P1_VCCS")
	)
	(segment
		(start 59.18073 -351.178622)
		(end 59.909202 -351.178622)
		(width 0.254)
		(layer "F.Cu")
		(net "PVDDCR_CPU1_P1_VCCS")
	)
	(segment
		(start 67.71513 -338.794598)
		(end 68.418964 -338.090764)
		(width 0.2286)
		(layer "F.Cu")
		(net "PVDDCR_CPU1_P1_VCCS")
	)
	(segment
		(start 43.196764 -349.811848)
		(end 42.49293 -350.515682)
		(width 0.2286)
		(layer "F.Cu")
		(net "PVDDCR_CPU1_P1_VCCS")
	)
	(segment
		(start 42.49293 -351.178622)
		(end 43.221402 -351.178622)
		(width 0.254)
		(layer "F.Cu")
		(net "PVDDCR_CPU1_P1_VCCS")
	)
	(segment
		(start 76.070714 -338.787486)
		(end 76.774548 -338.083652)
		(width 0.2286)
		(layer "F.Cu")
		(net "PVDDCR_CPU1_P1_VCCS")
	)
	(segment
		(start 76.774548 -338.083652)
		(end 76.774548 -337.892898)
		(width 0.2286)
		(layer "F.Cu")
		(net "PVDDCR_CPU1_P1_VCCS")
	)
	(segment
		(start 101.739192 -343.030048)
		(end 101.739192 -342.839294)
		(width 0.2286)
		(layer "F.Cu")
		(net "PVDDCR_CPU1_P1_VCCS")
	)
	(segment
		(start 59.884564 -349.811848)
		(end 59.18073 -350.515682)
		(width 0.2286)
		(layer "F.Cu")
		(net "PVDDCR_CPU1_P1_VCCS")
	)
	(segment
		(start 76.070714 -339.450426)
		(end 76.070714 -338.787486)
		(width 0.2286)
		(layer "F.Cu")
		(net "PVDDCR_CPU1_P1_VCCS")
	)
	(segment
		(start 42.49293 -350.515682)
		(end 42.49293 -351.178622)
		(width 0.2286)
		(layer "F.Cu")
		(net "PVDDCR_CPU1_P1_VCCS")
	)
	(segment
		(start 43.196764 -349.621094)
		(end 43.196764 -349.811848)
		(width 0.2286)
		(layer "F.Cu")
		(net "PVDDCR_CPU1_P1_VCCS")
	)
	(segment
		(start 68.418964 -338.090764)
		(end 68.418964 -337.90001)
		(width 0.2286)
		(layer "F.Cu")
		(net "PVDDCR_CPU1_P1_VCCS")
	)
	(segment
		(start 85.132164 -338.069174)
		(end 85.132164 -337.87842)
		(width 0.2286)
		(layer "F.Cu")
		(net "PVDDCR_CPU1_P1_VCCS")
	)
	(segment
		(start 101.76383 -344.396822)
		(end 101.035358 -344.396822)
		(width 0.254)
		(layer "F.Cu")
		(net "PVDDCR_CPU1_P1_VCCS")
	)
	(segment
		(start 59.18073 -350.515682)
		(end 59.18073 -351.178622)
		(width 0.2286)
		(layer "F.Cu")
		(net "PVDDCR_CPU1_P1_VCCS")
	)
	(segment
		(start 84.42833 -339.435948)
		(end 84.42833 -338.773008)
		(width 0.2286)
		(layer "F.Cu")
		(net "PVDDCR_CPU1_P1_VCCS")
	)
	(segment
		(start 26.610564 -349.811848)
		(end 25.90673 -350.515682)
		(width 0.2286)
		(layer "F.Cu")
		(net "PVDDCR_CPU1_P1_VCCS")
	)
	(segment
		(start 34.890964 -349.811848)
		(end 34.18713 -350.515682)
		(width 0.2286)
		(layer "F.Cu")
		(net "PVDDCR_CPU1_P1_VCCS")
	)
	(segment
		(start 92.75953 -338.823808)
		(end 93.463364 -338.119974)
		(width 0.2286)
		(layer "F.Cu")
		(net "PVDDCR_CPU1_P1_VCCS")
	)
	(segment
		(start 34.18713 -350.515682)
		(end 34.18713 -351.178622)
		(width 0.2286)
		(layer "F.Cu")
		(net "PVDDCR_CPU1_P1_VCCS")
	)
	(segment
		(start 101.035358 -344.396822)
		(end 101.035358 -343.733882)
		(width 0.2286)
		(layer "F.Cu")
		(net "PVDDCR_CPU1_P1_VCCS")
	)
	(segment
		(start 51.553364 -349.811848)
		(end 50.84953 -350.515682)
		(width 0.2286)
		(layer "F.Cu")
		(net "PVDDCR_CPU1_P1_VCCS")
	)
	(segment
		(start 50.84953 -350.515682)
		(end 50.84953 -351.178622)
		(width 0.2286)
		(layer "F.Cu")
		(net "PVDDCR_CPU1_P1_VCCS")
	)
	(segment
		(start 93.463364 -338.119974)
		(end 93.463364 -337.92922)
		(width 0.2286)
		(layer "F.Cu")
		(net "PVDDCR_CPU1_P1_VCCS")
	)
	(segment
		(start 68.443602 -339.457538)
		(end 67.71513 -339.457538)
		(width 0.254)
		(layer "F.Cu")
		(net "PVDDCR_CPU1_P1_VCCS")
	)
	(segment
		(start 84.42833 -338.773008)
		(end 85.132164 -338.069174)
		(width 0.2286)
		(layer "F.Cu")
		(net "PVDDCR_CPU1_P1_VCCS")
	)
	(segment
		(start 26.610564 -349.621094)
		(end 26.610564 -349.811848)
		(width 0.2286)
		(layer "F.Cu")
		(net "PVDDCR_CPU1_P1_VCCS")
	)
	(segment
		(start 93.488002 -339.486748)
		(end 92.75953 -339.486748)
		(width 0.254)
		(layer "F.Cu")
		(net "PVDDCR_CPU1_P1_VCCS")
	)
	(segment
		(start 59.884564 -349.621094)
		(end 59.884564 -349.811848)
		(width 0.2286)
		(layer "F.Cu")
		(net "PVDDCR_CPU1_P1_VCCS")
	)
	(segment
		(start 85.156802 -339.435948)
		(end 84.42833 -339.435948)
		(width 0.254)
		(layer "F.Cu")
		(net "PVDDCR_CPU1_P1_VCCS")
	)
	(segment
		(start 101.035358 -343.733882)
		(end 101.739192 -343.030048)
		(width 0.2286)
		(layer "F.Cu")
		(net "PVDDCR_CPU1_P1_VCCS")
	)
	(segment
		(start 76.799186 -339.450426)
		(end 76.070714 -339.450426)
		(width 0.254)
		(layer "F.Cu")
		(net "PVDDCR_CPU1_P1_VCCS")
	)
	(via
		(at 85.156802 -339.435948)
		(size 0.508)
		(drill 0.254)
		(layers "F.Cu" "B.Cu")
		(net "PVDDCR_CPU1_P1_VCCS")
	)
	(via
		(at 93.488002 -339.486748)
		(size 0.508)
		(drill 0.254)
		(layers "F.Cu" "B.Cu")
		(net "PVDDCR_CPU1_P1_VCCS")
	)
	(via
		(at 51.578002 -351.178622)
		(size 0.508)
		(drill 0.254)
		(layers "F.Cu" "B.Cu")
		(net "PVDDCR_CPU1_P1_VCCS")
	)
	(via
		(at 101.76383 -344.396822)
		(size 0.508)
		(drill 0.254)
		(layers "F.Cu" "B.Cu")
		(net "PVDDCR_CPU1_P1_VCCS")
	)
	(via
		(at 43.221402 -351.178622)
		(size 0.508)
		(drill 0.254)
		(layers "F.Cu" "B.Cu")
		(net "PVDDCR_CPU1_P1_VCCS")
	)
	(via
		(at 59.909202 -351.178622)
		(size 0.508)
		(drill 0.254)
		(layers "F.Cu" "B.Cu")
		(net "PVDDCR_CPU1_P1_VCCS")
	)
	(via
		(at 34.915602 -351.178622)
		(size 0.508)
		(drill 0.254)
		(layers "F.Cu" "B.Cu")
		(net "PVDDCR_CPU1_P1_VCCS")
	)
	(via
		(at 68.443602 -339.457538)
		(size 0.508)
		(drill 0.254)
		(layers "F.Cu" "B.Cu")
		(net "PVDDCR_CPU1_P1_VCCS")
	)
	(via
		(at 26.635202 -351.178622)
		(size 0.508)
		(drill 0.254)
		(layers "F.Cu" "B.Cu")
		(net "PVDDCR_CPU1_P1_VCCS")
	)
	(via
		(at 33.8074 -366.8014)
		(size 0.508)
		(drill 0.254)
		(layers "F.Cu" "B.Cu")
		(net "PVDDCR_CPU1_P1_VCCS")
	)
	(via
		(at 76.799186 -339.450426)
		(size 0.508)
		(drill 0.254)
		(layers "F.Cu" "B.Cu")
		(net "PVDDCR_CPU1_P1_VCCS")
	)
	(segment
		(start 30.5562 -352.4758)
		(end 32.258 -354.1776)
		(width 0.254)
		(layer "In6.Cu")
		(net "PVDDCR_CPU1_P1_VCCS")
	)
	(segment
		(start 58.80735 -353.259898)
		(end 59.733942 -352.333306)
		(width 0.254)
		(layer "In6.Cu")
		(net "PVDDCR_CPU1_P1_VCCS")
	)
	(segment
		(start 46.736 -353.259898)
		(end 58.80735 -353.259898)
		(width 0.254)
		(layer "In6.Cu")
		(net "PVDDCR_CPU1_P1_VCCS")
	)
	(segment
		(start 30.475174 -361.157774)
		(end 36.549838 -361.157774)
		(width 0.254)
		(layer "In6.Cu")
		(net "PVDDCR_CPU1_P1_VCCS")
	)
	(segment
		(start 66.353182 -346.72905)
		(end 66.353182 -342.491314)
		(width 0.254)
		(layer "In6.Cu")
		(net "PVDDCR_CPU1_P1_VCCS")
	)
	(segment
		(start 39.454836 -353.178364)
		(end 34.4551 -358.1781)
		(width 0.254)
		(layer "In6.Cu")
		(net "PVDDCR_CPU1_P1_VCCS")
	)
	(segment
		(start 43.046142 -351.353882)
		(end 43.046142 -352.425254)
		(width 0.254)
		(layer "In6.Cu")
		(net "PVDDCR_CPU1_P1_VCCS")
	)
	(segment
		(start 45.215556 -354.780342)
		(end 46.736 -353.259898)
		(width 0.254)
		(layer "In6.Cu")
		(net "PVDDCR_CPU1_P1_VCCS")
	)
	(segment
		(start 34.4551 -358.1781)
		(end 34.0233 -358.1781)
		(width 0.254)
		(layer "In6.Cu")
		(net "PVDDCR_CPU1_P1_VCCS")
	)
	(segment
		(start 34.915602 -351.178622)
		(end 34.712402 -351.381822)
		(width 0.254)
		(layer "In6.Cu")
		(net "PVDDCR_CPU1_P1_VCCS")
	)
	(segment
		(start 47.519844 -354.524056)
		(end 63.31458 -354.524056)
		(width 0.254)
		(layer "In6.Cu")
		(net "PVDDCR_CPU1_P1_VCCS")
	)
	(segment
		(start 34.712402 -351.381822)
		(end 34.712402 -354.872798)
		(width 0.254)
		(layer "In6.Cu")
		(net "PVDDCR_CPU1_P1_VCCS")
	)
	(segment
		(start 32.3342 -357.251)
		(end 31.8008 -357.251)
		(width 0.254)
		(layer "In6.Cu")
		(net "PVDDCR_CPU1_P1_VCCS")
	)
	(segment
		(start 39.742364 -357.965248)
		(end 39.742364 -357.467408)
		(width 0.254)
		(layer "In6.Cu")
		(net "PVDDCR_CPU1_P1_VCCS")
	)
	(segment
		(start 33.443672 -359.314496)
		(end 35.173158 -359.314496)
		(width 0.254)
		(layer "In6.Cu")
		(net "PVDDCR_CPU1_P1_VCCS")
	)
	(segment
		(start 67.39509 -347.770958)
		(end 66.353182 -346.72905)
		(width 0.254)
		(layer "In6.Cu")
		(net "PVDDCR_CPU1_P1_VCCS")
	)
	(segment
		(start 34.712402 -354.872798)
		(end 32.3342 -357.251)
		(width 0.254)
		(layer "In6.Cu")
		(net "PVDDCR_CPU1_P1_VCCS")
	)
	(segment
		(start 29.1084 -359.035096)
		(end 29.2608 -358.882696)
		(width 0.254)
		(layer "In6.Cu")
		(net "PVDDCR_CPU1_P1_VCCS")
	)
	(segment
		(start 34.0233 -358.1781)
		(end 33.2359 -357.3907)
		(width 0.254)
		(layer "In6.Cu")
		(net "PVDDCR_CPU1_P1_VCCS")
	)
	(segment
		(start 36.549838 -361.157774)
		(end 39.742364 -357.965248)
		(width 0.254)
		(layer "In6.Cu")
		(net "PVDDCR_CPU1_P1_VCCS")
	)
	(segment
		(start 32.258 -354.1776)
		(end 32.258 -356.3874)
		(width 0.254)
		(layer "In6.Cu")
		(net "PVDDCR_CPU1_P1_VCCS")
	)
	(segment
		(start 67.39509 -350.443546)
		(end 67.39509 -347.770958)
		(width 0.254)
		(layer "In6.Cu")
		(net "PVDDCR_CPU1_P1_VCCS")
	)
	(segment
		(start 41.005506 -356.204266)
		(end 45.839634 -356.204266)
		(width 0.254)
		(layer "In6.Cu")
		(net "PVDDCR_CPU1_P1_VCCS")
	)
	(segment
		(start 68.443602 -340.400894)
		(end 68.443602 -339.457538)
		(width 0.254)
		(layer "In6.Cu")
		(net "PVDDCR_CPU1_P1_VCCS")
	)
	(segment
		(start 33.2359 -357.3907)
		(end 32.8041 -357.3907)
		(width 0.254)
		(layer "In6.Cu")
		(net "PVDDCR_CPU1_P1_VCCS")
	)
	(segment
		(start 45.839634 -356.204266)
		(end 47.519844 -354.524056)
		(width 0.254)
		(layer "In6.Cu")
		(net "PVDDCR_CPU1_P1_VCCS")
	)
	(segment
		(start 42.293032 -353.178364)
		(end 39.454836 -353.178364)
		(width 0.254)
		(layer "In6.Cu")
		(net "PVDDCR_CPU1_P1_VCCS")
	)
	(segment
		(start 39.707312 -354.780342)
		(end 45.215556 -354.780342)
		(width 0.254)
		(layer "In6.Cu")
		(net "PVDDCR_CPU1_P1_VCCS")
	)
	(segment
		(start 43.221402 -351.178622)
		(end 43.046142 -351.353882)
		(width 0.254)
		(layer "In6.Cu")
		(net "PVDDCR_CPU1_P1_VCCS")
	)
	(segment
		(start 59.733942 -352.333306)
		(end 59.733942 -351.353882)
		(width 0.254)
		(layer "In6.Cu")
		(net "PVDDCR_CPU1_P1_VCCS")
	)
	(segment
		(start 26.635202 -351.178622)
		(end 26.635202 -351.895664)
		(width 0.254)
		(layer "In6.Cu")
		(net "PVDDCR_CPU1_P1_VCCS")
	)
	(segment
		(start 39.742364 -357.467408)
		(end 41.005506 -356.204266)
		(width 0.254)
		(layer "In6.Cu")
		(net "PVDDCR_CPU1_P1_VCCS")
	)
	(segment
		(start 26.635202 -351.895664)
		(end 27.215338 -352.4758)
		(width 0.254)
		(layer "In6.Cu")
		(net "PVDDCR_CPU1_P1_VCCS")
	)
	(segment
		(start 31.8008 -356.8446)
		(end 31.5214 -356.8446)
		(width 0.254)
		(layer "In6.Cu")
		(net "PVDDCR_CPU1_P1_VCCS")
	)
	(segment
		(start 66.353182 -342.491314)
		(end 68.443602 -340.400894)
		(width 0.254)
		(layer "In6.Cu")
		(net "PVDDCR_CPU1_P1_VCCS")
	)
	(segment
		(start 43.046142 -352.425254)
		(end 42.293032 -353.178364)
		(width 0.254)
		(layer "In6.Cu")
		(net "PVDDCR_CPU1_P1_VCCS")
	)
	(segment
		(start 35.173158 -359.314496)
		(end 39.707312 -354.780342)
		(width 0.254)
		(layer "In6.Cu")
		(net "PVDDCR_CPU1_P1_VCCS")
	)
	(segment
		(start 63.31458 -354.524056)
		(end 67.39509 -350.443546)
		(width 0.254)
		(layer "In6.Cu")
		(net "PVDDCR_CPU1_P1_VCCS")
	)
	(segment
		(start 32.376872 -358.247696)
		(end 33.443672 -359.314496)
		(width 0.254)
		(layer "In6.Cu")
		(net "PVDDCR_CPU1_P1_VCCS")
	)
	(segment
		(start 59.733942 -351.353882)
		(end 59.909202 -351.178622)
		(width 0.254)
		(layer "In6.Cu")
		(net "PVDDCR_CPU1_P1_VCCS")
	)
	(segment
		(start 29.2608 -358.882696)
		(end 30.970728 -358.882696)
		(width 0.254)
		(layer "In6.Cu")
		(net "PVDDCR_CPU1_P1_VCCS")
	)
	(segment
		(start 29.0322 -359.7148)
		(end 30.475174 -361.157774)
		(width 0.254)
		(layer "In6.Cu")
		(net "PVDDCR_CPU1_P1_VCCS")
	)
	(segment
		(start 27.215338 -352.4758)
		(end 30.5562 -352.4758)
		(width 0.254)
		(layer "In6.Cu")
		(net "PVDDCR_CPU1_P1_VCCS")
	)
	(segment
		(start 30.970728 -358.882696)
		(end 31.605728 -358.247696)
		(width 0.254)
		(layer "In6.Cu")
		(net "PVDDCR_CPU1_P1_VCCS")
	)
	(segment
		(start 32.258 -356.3874)
		(end 31.8008 -356.8446)
		(width 0.254)
		(layer "In6.Cu")
		(net "PVDDCR_CPU1_P1_VCCS")
	)
	(segment
		(start 31.605728 -358.247696)
		(end 32.376872 -358.247696)
		(width 0.254)
		(layer "In6.Cu")
		(net "PVDDCR_CPU1_P1_VCCS")
	)
	(segment
		(start 84.981542 -340.712552)
		(end 84.981542 -339.611208)
		(width 0.254)
		(layer "In11.Cu")
		(net "PVDDCR_CPU1_P1_VCCS")
	)
	(segment
		(start 28.6766 -355.9048)
		(end 28.4607 -355.6889)
		(width 0.254)
		(layer "In11.Cu")
		(net "PVDDCR_CPU1_P1_VCCS")
	)
	(segment
		(start 69.386196 -354.547932)
		(end 81.95183 -341.982298)
		(width 0.254)
		(layer "In11.Cu")
		(net "PVDDCR_CPU1_P1_VCCS")
	)
	(segment
		(start 81.95183 -341.982298)
		(end 83.711796 -341.982298)
		(width 0.254)
		(layer "In11.Cu")
		(net "PVDDCR_CPU1_P1_VCCS")
	)
	(segment
		(start 29.698188 -357.0732)
		(end 32.223456 -354.547932)
		(width 0.254)
		(layer "In11.Cu")
		(net "PVDDCR_CPU1_P1_VCCS")
	)
	(segment
		(start 76.799186 -339.450426)
		(end 76.623926 -339.625686)
		(width 0.254)
		(layer "In11.Cu")
		(net "PVDDCR_CPU1_P1_VCCS")
	)
	(segment
		(start 32.223456 -354.547932)
		(end 69.386196 -354.547932)
		(width 0.254)
		(layer "In11.Cu")
		(net "PVDDCR_CPU1_P1_VCCS")
	)
	(segment
		(start 29.698188 -357.0732)
		(end 28.2702 -357.0732)
		(width 0.254)
		(layer "In11.Cu")
		(net "PVDDCR_CPU1_P1_VCCS")
	)
	(segment
		(start 84.981542 -339.611208)
		(end 85.156802 -339.435948)
		(width 0.254)
		(layer "In11.Cu")
		(net "PVDDCR_CPU1_P1_VCCS")
	)
	(segment
		(start 83.711796 -341.982298)
		(end 84.981542 -340.712552)
		(width 0.254)
		(layer "In11.Cu")
		(net "PVDDCR_CPU1_P1_VCCS")
	)
	(segment
		(start 68.164456 -353.128072)
		(end 31.808928 -353.128072)
		(width 0.254)
		(layer "In11.Cu")
		(net "PVDDCR_CPU1_P1_VCCS")
	)
	(segment
		(start 28.2702 -357.0732)
		(end 27.5844 -356.3874)
		(width 0.254)
		(layer "In11.Cu")
		(net "PVDDCR_CPU1_P1_VCCS")
	)
	(segment
		(start 31.808928 -353.128072)
		(end 29.0322 -355.9048)
		(width 0.254)
		(layer "In11.Cu")
		(net "PVDDCR_CPU1_P1_VCCS")
	)
	(segment
		(start 76.623926 -339.625686)
		(end 76.623926 -344.668602)
		(width 0.254)
		(layer "In11.Cu")
		(net "PVDDCR_CPU1_P1_VCCS")
	)
	(segment
		(start 29.0322 -355.9048)
		(end 28.6766 -355.9048)
		(width 0.254)
		(layer "In11.Cu")
		(net "PVDDCR_CPU1_P1_VCCS")
	)
	(segment
		(start 76.623926 -344.668602)
		(end 68.164456 -353.128072)
		(width 0.254)
		(layer "In11.Cu")
		(net "PVDDCR_CPU1_P1_VCCS")
	)
	(segment
		(start 99.586034 -346.267278)
		(end 96.360234 -343.041478)
		(width 0.254)
		(layer "In13.Cu")
		(net "PVDDCR_CPU1_P1_VCCS")
	)
	(segment
		(start 101.76383 -345.340178)
		(end 100.83673 -346.267278)
		(width 0.254)
		(layer "In13.Cu")
		(net "PVDDCR_CPU1_P1_VCCS")
	)
	(segment
		(start 50.610262 -353.131882)
		(end 51.402742 -352.339402)
		(width 0.254)
		(layer "In13.Cu")
		(net "PVDDCR_CPU1_P1_VCCS")
	)
	(segment
		(start 92.517722 -341.476838)
		(end 93.284802 -340.709758)
		(width 0.254)
		(layer "In13.Cu")
		(net "PVDDCR_CPU1_P1_VCCS")
	)
	(segment
		(start 51.402742 -352.339402)
		(end 51.402742 -351.353882)
		(width 0.254)
		(layer "In13.Cu")
		(net "PVDDCR_CPU1_P1_VCCS")
	)
	(segment
		(start 100.83673 -346.267278)
		(end 99.586034 -346.267278)
		(width 0.254)
		(layer "In13.Cu")
		(net "PVDDCR_CPU1_P1_VCCS")
	)
	(segment
		(start 29.9974 -357.759)
		(end 30.4546 -358.2162)
		(width 0.254)
		(layer "In13.Cu")
		(net "PVDDCR_CPU1_P1_VCCS")
	)
	(segment
		(start 34.8742 -356.2604)
		(end 35.311588 -356.2604)
		(width 0.254)
		(layer "In13.Cu")
		(net "PVDDCR_CPU1_P1_VCCS")
	)
	(segment
		(start 66.40449 -355.533198)
		(end 40.122602 -355.533198)
		(width 0.254)
		(layer "In13.Cu")
		(net "PVDDCR_CPU1_P1_VCCS")
	)
	(segment
		(start 78.528672 -341.476838)
		(end 92.517722 -341.476838)
		(width 0.254)
		(layer "In13.Cu")
		(net "PVDDCR_CPU1_P1_VCCS")
	)
	(segment
		(start 96.360234 -343.041478)
		(end 78.89621 -343.041478)
		(width 0.254)
		(layer "In13.Cu")
		(net "PVDDCR_CPU1_P1_VCCS")
	)
	(segment
		(start 78.89621 -343.041478)
		(end 66.40449 -355.533198)
		(width 0.254)
		(layer "In13.Cu")
		(net "PVDDCR_CPU1_P1_VCCS")
	)
	(segment
		(start 39.299896 -354.253292)
		(end 65.752218 -354.253292)
		(width 0.254)
		(layer "In13.Cu")
		(net "PVDDCR_CPU1_P1_VCCS")
	)
	(segment
		(start 40.122602 -355.533198)
		(end 37.1094 -358.5464)
		(width 0.254)
		(layer "In13.Cu")
		(net "PVDDCR_CPU1_P1_VCCS")
	)
	(segment
		(start 101.76383 -344.396822)
		(end 101.76383 -345.340178)
		(width 0.254)
		(layer "In13.Cu")
		(net "PVDDCR_CPU1_P1_VCCS")
	)
	(segment
		(start 35.311588 -356.2604)
		(end 38.440106 -353.131882)
		(width 0.254)
		(layer "In13.Cu")
		(net "PVDDCR_CPU1_P1_VCCS")
	)
	(segment
		(start 32.385 -358.2162)
		(end 32.7152 -358.5464)
		(width 0.254)
		(layer "In13.Cu")
		(net "PVDDCR_CPU1_P1_VCCS")
	)
	(segment
		(start 36.454588 -357.0986)
		(end 39.299896 -354.253292)
		(width 0.254)
		(layer "In13.Cu")
		(net "PVDDCR_CPU1_P1_VCCS")
	)
	(segment
		(start 51.402742 -351.353882)
		(end 51.578002 -351.178622)
		(width 0.254)
		(layer "In13.Cu")
		(net "PVDDCR_CPU1_P1_VCCS")
	)
	(segment
		(start 37.1094 -358.5464)
		(end 32.7152 -358.5464)
		(width 0.254)
		(layer "In13.Cu")
		(net "PVDDCR_CPU1_P1_VCCS")
	)
	(segment
		(start 30.4292 -357.0986)
		(end 36.454588 -357.0986)
		(width 0.254)
		(layer "In13.Cu")
		(net "PVDDCR_CPU1_P1_VCCS")
	)
	(segment
		(start 93.284802 -339.689948)
		(end 93.488002 -339.486748)
		(width 0.254)
		(layer "In13.Cu")
		(net "PVDDCR_CPU1_P1_VCCS")
	)
	(segment
		(start 93.284802 -340.709758)
		(end 93.284802 -339.689948)
		(width 0.254)
		(layer "In13.Cu")
		(net "PVDDCR_CPU1_P1_VCCS")
	)
	(segment
		(start 30.4546 -358.2162)
		(end 32.385 -358.2162)
		(width 0.254)
		(layer "In13.Cu")
		(net "PVDDCR_CPU1_P1_VCCS")
	)
	(segment
		(start 65.752218 -354.253292)
		(end 78.528672 -341.476838)
		(width 0.254)
		(layer "In13.Cu")
		(net "PVDDCR_CPU1_P1_VCCS")
	)
	(segment
		(start 38.440106 -353.131882)
		(end 50.610262 -353.131882)
		(width 0.254)
		(layer "In13.Cu")
		(net "PVDDCR_CPU1_P1_VCCS")
	)
	(segment
		(start 100.678488 -341.314278)
		(end 101.329236 -341.314278)
		(width 0.2286)
		(layer "F.Cu")
		(net "PVDDCR_CPU1_P1_VCC6")
	)
	(segment
		(start 100.046282 -341.594186)
		(end 100.39858 -341.594186)
		(width 0.2286)
		(layer "F.Cu")
		(net "PVDDCR_CPU1_P1_VCC6")
	)
	(segment
		(start 100.39858 -341.594186)
		(end 100.678488 -341.314278)
		(width 0.2286)
		(layer "F.Cu")
		(net "PVDDCR_CPU1_P1_VCC6")
	)
	(segment
		(start 100.046282 -342.204548)
		(end 100.046282 -341.594186)
		(width 0.4572)
		(layer "F.Cu")
		(net "PVDDCR_CPU1_P1_VCC6")
	)
	(segment
		(start 103.53929 -342.839294)
		(end 103.53929 -343.551256)
		(width 0.2286)
		(layer "F.Cu")
		(net "PVDDCR_CPU1_P1_VCC6")
	)
	(segment
		(start 103.53929 -343.551256)
		(end 103.463598 -343.626948)
		(width 0.2286)
		(layer "F.Cu")
		(net "PVDDCR_CPU1_P1_VCC6")
	)
	(via
		(at 102.508558 -342.671908)
		(size 0.6604)
		(drill 0.3302)
		(layers "F.Cu" "B.Cu")
		(net "PVDDCR_CPU1_P1_VCC6")
	)
	(via
		(at 100.046282 -341.594186)
		(size 0.508)
		(drill 0.254)
		(layers "F.Cu" "B.Cu")
		(net "PVDDCR_CPU1_P1_VCC6")
	)
	(via
		(at 103.463598 -343.626948)
		(size 0.508)
		(drill 0.254)
		(layers "F.Cu" "B.Cu")
		(net "PVDDCR_CPU1_P1_VCC6")
	)
	(segment
		(start 101.41839 -341.398606)
		(end 100.955348 -341.398606)
		(width 0.254)
		(layer "B.Cu")
		(net "PVDDCR_CPU1_P1_VCC6")
	)
	(segment
		(start 101.386894 -341.430102)
		(end 101.386894 -342.247982)
		(width 0.254)
		(layer "B.Cu")
		(net "PVDDCR_CPU1_P1_VCC6")
	)
	(segment
		(start 100.054918 -341.602822)
		(end 100.046282 -341.594186)
		(width 0.254)
		(layer "B.Cu")
		(net "PVDDCR_CPU1_P1_VCC6")
	)
	(segment
		(start 102.508558 -342.671908)
		(end 103.463598 -343.626948)
		(width 0.254)
		(layer "B.Cu")
		(net "PVDDCR_CPU1_P1_VCC6")
	)
	(segment
		(start 101.41839 -341.398606)
		(end 101.386894 -341.430102)
		(width 0.254)
		(layer "B.Cu")
		(net "PVDDCR_CPU1_P1_VCC6")
	)
	(segment
		(start 101.386894 -342.247982)
		(end 101.81082 -342.671908)
		(width 0.254)
		(layer "B.Cu")
		(net "PVDDCR_CPU1_P1_VCC6")
	)
	(segment
		(start 101.81082 -342.671908)
		(end 102.508558 -342.671908)
		(width 0.254)
		(layer "B.Cu")
		(net "PVDDCR_CPU1_P1_VCC6")
	)
	(segment
		(start 100.955348 -341.398606)
		(end 100.751132 -341.602822)
		(width 0.254)
		(layer "B.Cu")
		(net "PVDDCR_CPU1_P1_VCC6")
	)
	(segment
		(start 100.751132 -341.602822)
		(end 100.054918 -341.602822)
		(width 0.254)
		(layer "B.Cu")
		(net "PVDDCR_CPU1_P1_VCC6")
	)
	(segment
		(start 92.40266 -336.404204)
		(end 93.053408 -336.404204)
		(width 0.2286)
		(layer "F.Cu")
		(net "PVDDCR_CPU1_P1_VCC5")
	)
	(segment
		(start 95.263462 -338.641182)
		(end 95.18777 -338.716874)
		(width 0.2286)
		(layer "F.Cu")
		(net "PVDDCR_CPU1_P1_VCC5")
	)
	(segment
		(start 91.770454 -336.684112)
		(end 92.122752 -336.684112)
		(width 0.2286)
		(layer "F.Cu")
		(net "PVDDCR_CPU1_P1_VCC5")
	)
	(segment
		(start 92.122752 -336.684112)
		(end 92.40266 -336.404204)
		(width 0.2286)
		(layer "F.Cu")
		(net "PVDDCR_CPU1_P1_VCC5")
	)
	(segment
		(start 95.263462 -337.92922)
		(end 95.263462 -338.641182)
		(width 0.2286)
		(layer "F.Cu")
		(net "PVDDCR_CPU1_P1_VCC5")
	)
	(segment
		(start 91.770454 -337.294474)
		(end 91.770454 -336.684112)
		(width 0.4572)
		(layer "F.Cu")
		(net "PVDDCR_CPU1_P1_VCC5")
	)
	(via
		(at 91.770454 -336.684112)
		(size 0.508)
		(drill 0.254)
		(layers "F.Cu" "B.Cu")
		(net "PVDDCR_CPU1_P1_VCC5")
	)
	(via
		(at 95.18777 -338.716874)
		(size 0.508)
		(drill 0.254)
		(layers "F.Cu" "B.Cu")
		(net "PVDDCR_CPU1_P1_VCC5")
	)
	(via
		(at 94.256606 -337.78571)
		(size 0.6604)
		(drill 0.3302)
		(layers "F.Cu" "B.Cu")
		(net "PVDDCR_CPU1_P1_VCC5")
	)
	(segment
		(start 93.111066 -337.337908)
		(end 93.558868 -337.78571)
		(width 0.254)
		(layer "B.Cu")
		(net "PVDDCR_CPU1_P1_VCC5")
	)
	(segment
		(start 93.558868 -337.78571)
		(end 94.256606 -337.78571)
		(width 0.254)
		(layer "B.Cu")
		(net "PVDDCR_CPU1_P1_VCC5")
	)
	(segment
		(start 93.111066 -336.520028)
		(end 93.111066 -337.337908)
		(width 0.254)
		(layer "B.Cu")
		(net "PVDDCR_CPU1_P1_VCC5")
	)
	(segment
		(start 91.77909 -336.692748)
		(end 91.770454 -336.684112)
		(width 0.254)
		(layer "B.Cu")
		(net "PVDDCR_CPU1_P1_VCC5")
	)
	(segment
		(start 92.67952 -336.488532)
		(end 92.475304 -336.692748)
		(width 0.254)
		(layer "B.Cu")
		(net "PVDDCR_CPU1_P1_VCC5")
	)
	(segment
		(start 92.475304 -336.692748)
		(end 91.77909 -336.692748)
		(width 0.254)
		(layer "B.Cu")
		(net "PVDDCR_CPU1_P1_VCC5")
	)
	(segment
		(start 93.142562 -336.488532)
		(end 93.111066 -336.520028)
		(width 0.254)
		(layer "B.Cu")
		(net "PVDDCR_CPU1_P1_VCC5")
	)
	(segment
		(start 93.142562 -336.488532)
		(end 92.67952 -336.488532)
		(width 0.254)
		(layer "B.Cu")
		(net "PVDDCR_CPU1_P1_VCC5")
	)
	(segment
		(start 94.256606 -337.78571)
		(end 95.18777 -338.716874)
		(width 0.254)
		(layer "B.Cu")
		(net "PVDDCR_CPU1_P1_VCC5")
	)
	(segment
		(start 58.543952 -348.375986)
		(end 58.82386 -348.096078)
		(width 0.2286)
		(layer "F.Cu")
		(net "PVDDCR_CPU1_P1_VCC4")
	)
	(segment
		(start 61.684662 -350.333056)
		(end 61.60897 -350.408748)
		(width 0.2286)
		(layer "F.Cu")
		(net "PVDDCR_CPU1_P1_VCC4")
	)
	(segment
		(start 61.684662 -349.621094)
		(end 61.684662 -350.333056)
		(width 0.2286)
		(layer "F.Cu")
		(net "PVDDCR_CPU1_P1_VCC4")
	)
	(segment
		(start 58.82386 -348.096078)
		(end 59.474608 -348.096078)
		(width 0.2286)
		(layer "F.Cu")
		(net "PVDDCR_CPU1_P1_VCC4")
	)
	(segment
		(start 58.191654 -348.986348)
		(end 58.191654 -348.375986)
		(width 0.4572)
		(layer "F.Cu")
		(net "PVDDCR_CPU1_P1_VCC4")
	)
	(segment
		(start 58.191654 -348.375986)
		(end 58.543952 -348.375986)
		(width 0.2286)
		(layer "F.Cu")
		(net "PVDDCR_CPU1_P1_VCC4")
	)
	(via
		(at 61.60897 -350.408748)
		(size 0.508)
		(drill 0.254)
		(layers "F.Cu" "B.Cu")
		(net "PVDDCR_CPU1_P1_VCC4")
	)
	(via
		(at 58.191654 -348.375986)
		(size 0.508)
		(drill 0.254)
		(layers "F.Cu" "B.Cu")
		(net "PVDDCR_CPU1_P1_VCC4")
	)
	(via
		(at 60.019184 -349.490284)
		(size 0.6604)
		(drill 0.3302)
		(layers "F.Cu" "B.Cu")
		(net "PVDDCR_CPU1_P1_VCC4")
	)
	(segment
		(start 61.109606 -349.909384)
		(end 60.33262 -349.909384)
		(width 0.508)
		(layer "B.Cu")
		(net "PVDDCR_CPU1_P1_VCC4")
	)
	(segment
		(start 58.858404 -348.375986)
		(end 59.053984 -348.180406)
		(width 0.381)
		(layer "B.Cu")
		(net "PVDDCR_CPU1_P1_VCC4")
	)
	(segment
		(start 59.563762 -349.034862)
		(end 59.563762 -348.180406)
		(width 0.381)
		(layer "B.Cu")
		(net "PVDDCR_CPU1_P1_VCC4")
	)
	(segment
		(start 60.019184 -349.490284)
		(end 59.563762 -349.034862)
		(width 0.381)
		(layer "B.Cu")
		(net "PVDDCR_CPU1_P1_VCC4")
	)
	(segment
		(start 58.191654 -348.375986)
		(end 58.858404 -348.375986)
		(width 0.381)
		(layer "B.Cu")
		(net "PVDDCR_CPU1_P1_VCC4")
	)
	(segment
		(start 61.60897 -350.408748)
		(end 61.109606 -349.909384)
		(width 0.508)
		(layer "B.Cu")
		(net "PVDDCR_CPU1_P1_VCC4")
	)
	(segment
		(start 60.33262 -349.909384)
		(end 60.019184 -349.595948)
		(width 0.508)
		(layer "B.Cu")
		(net "PVDDCR_CPU1_P1_VCC4")
	)
	(segment
		(start 60.019184 -349.595948)
		(end 60.019184 -349.490284)
		(width 0.381)
		(layer "B.Cu")
		(net "PVDDCR_CPU1_P1_VCC4")
	)
	(segment
		(start 59.053984 -348.180406)
		(end 59.563762 -348.180406)
		(width 0.381)
		(layer "B.Cu")
		(net "PVDDCR_CPU1_P1_VCC4")
	)
	(segment
		(start 66.726054 -337.265264)
		(end 66.726054 -336.654902)
		(width 0.4572)
		(layer "F.Cu")
		(net "PVDDCR_CPU1_P1_VCC3")
	)
	(segment
		(start 70.219062 -338.611972)
		(end 70.14337 -338.687664)
		(width 0.2286)
		(layer "F.Cu")
		(net "PVDDCR_CPU1_P1_VCC3")
	)
	(segment
		(start 67.35826 -336.374994)
		(end 68.009008 -336.374994)
		(width 0.2286)
		(layer "F.Cu")
		(net "PVDDCR_CPU1_P1_VCC3")
	)
	(segment
		(start 66.726054 -336.654902)
		(end 67.078352 -336.654902)
		(width 0.2286)
		(layer "F.Cu")
		(net "PVDDCR_CPU1_P1_VCC3")
	)
	(segment
		(start 70.219062 -337.90001)
		(end 70.219062 -338.611972)
		(width 0.2286)
		(layer "F.Cu")
		(net "PVDDCR_CPU1_P1_VCC3")
	)
	(segment
		(start 67.078352 -336.654902)
		(end 67.35826 -336.374994)
		(width 0.2286)
		(layer "F.Cu")
		(net "PVDDCR_CPU1_P1_VCC3")
	)
	(via
		(at 66.726054 -336.654902)
		(size 0.508)
		(drill 0.254)
		(layers "F.Cu" "B.Cu")
		(net "PVDDCR_CPU1_P1_VCC3")
	)
	(via
		(at 69.18833 -337.732624)
		(size 0.6604)
		(drill 0.3302)
		(layers "F.Cu" "B.Cu")
		(net "PVDDCR_CPU1_P1_VCC3")
	)
	(via
		(at 70.14337 -338.687664)
		(size 0.508)
		(drill 0.254)
		(layers "F.Cu" "B.Cu")
		(net "PVDDCR_CPU1_P1_VCC3")
	)
	(segment
		(start 68.098162 -336.459322)
		(end 67.63512 -336.459322)
		(width 0.254)
		(layer "B.Cu")
		(net "PVDDCR_CPU1_P1_VCC3")
	)
	(segment
		(start 66.73469 -336.663538)
		(end 66.726054 -336.654902)
		(width 0.254)
		(layer "B.Cu")
		(net "PVDDCR_CPU1_P1_VCC3")
	)
	(segment
		(start 69.18833 -337.732624)
		(end 68.490592 -337.732624)
		(width 0.254)
		(layer "B.Cu")
		(net "PVDDCR_CPU1_P1_VCC3")
	)
	(segment
		(start 68.066666 -336.490818)
		(end 68.098162 -336.459322)
		(width 0.254)
		(layer "B.Cu")
		(net "PVDDCR_CPU1_P1_VCC3")
	)
	(segment
		(start 67.63512 -336.459322)
		(end 67.430904 -336.663538)
		(width 0.254)
		(layer "B.Cu")
		(net "PVDDCR_CPU1_P1_VCC3")
	)
	(segment
		(start 67.430904 -336.663538)
		(end 66.73469 -336.663538)
		(width 0.254)
		(layer "B.Cu")
		(net "PVDDCR_CPU1_P1_VCC3")
	)
	(segment
		(start 68.066666 -337.308698)
		(end 68.066666 -336.490818)
		(width 0.254)
		(layer "B.Cu")
		(net "PVDDCR_CPU1_P1_VCC3")
	)
	(segment
		(start 68.490592 -337.732624)
		(end 68.066666 -337.308698)
		(width 0.254)
		(layer "B.Cu")
		(net "PVDDCR_CPU1_P1_VCC3")
	)
	(segment
		(start 70.14337 -338.687664)
		(end 69.18833 -337.732624)
		(width 0.254)
		(layer "B.Cu")
		(net "PVDDCR_CPU1_P1_VCC3")
	)
	(segment
		(start 75.081638 -336.64779)
		(end 75.081638 -337.258152)
		(width 0.4572)
		(layer "F.Cu")
		(net "PVDDCR_CPU1_P1_VCC2")
	)
	(segment
		(start 78.574646 -337.892898)
		(end 78.574646 -338.60486)
		(width 0.2286)
		(layer "F.Cu")
		(net "PVDDCR_CPU1_P1_VCC2")
	)
	(segment
		(start 75.433936 -336.64779)
		(end 75.081638 -336.64779)
		(width 0.2286)
		(layer "F.Cu")
		(net "PVDDCR_CPU1_P1_VCC2")
	)
	(segment
		(start 76.364592 -336.367882)
		(end 75.713844 -336.367882)
		(width 0.2286)
		(layer "F.Cu")
		(net "PVDDCR_CPU1_P1_VCC2")
	)
	(segment
		(start 78.574646 -338.60486)
		(end 78.498954 -338.680552)
		(width 0.2286)
		(layer "F.Cu")
		(net "PVDDCR_CPU1_P1_VCC2")
	)
	(segment
		(start 75.713844 -336.367882)
		(end 75.433936 -336.64779)
		(width 0.2286)
		(layer "F.Cu")
		(net "PVDDCR_CPU1_P1_VCC2")
	)
	(via
		(at 78.498954 -338.680552)
		(size 0.508)
		(drill 0.254)
		(layers "F.Cu" "B.Cu")
		(net "PVDDCR_CPU1_P1_VCC2")
	)
	(via
		(at 75.081638 -336.64779)
		(size 0.508)
		(drill 0.254)
		(layers "F.Cu" "B.Cu")
		(net "PVDDCR_CPU1_P1_VCC2")
	)
	(via
		(at 77.543914 -337.725512)
		(size 0.6604)
		(drill 0.3302)
		(layers "F.Cu" "B.Cu")
		(net "PVDDCR_CPU1_P1_VCC2")
	)
	(segment
		(start 76.42225 -337.301586)
		(end 76.42225 -336.483706)
		(width 0.254)
		(layer "B.Cu")
		(net "PVDDCR_CPU1_P1_VCC2")
	)
	(segment
		(start 75.090274 -336.656426)
		(end 75.081638 -336.64779)
		(width 0.254)
		(layer "B.Cu")
		(net "PVDDCR_CPU1_P1_VCC2")
	)
	(segment
		(start 77.543914 -337.725512)
		(end 76.846176 -337.725512)
		(width 0.254)
		(layer "B.Cu")
		(net "PVDDCR_CPU1_P1_VCC2")
	)
	(segment
		(start 78.498954 -338.680552)
		(end 77.543914 -337.725512)
		(width 0.254)
		(layer "B.Cu")
		(net "PVDDCR_CPU1_P1_VCC2")
	)
	(segment
		(start 76.846176 -337.725512)
		(end 76.42225 -337.301586)
		(width 0.254)
		(layer "B.Cu")
		(net "PVDDCR_CPU1_P1_VCC2")
	)
	(segment
		(start 75.990704 -336.45221)
		(end 75.786488 -336.656426)
		(width 0.254)
		(layer "B.Cu")
		(net "PVDDCR_CPU1_P1_VCC2")
	)
	(segment
		(start 76.42225 -336.483706)
		(end 76.453746 -336.45221)
		(width 0.254)
		(layer "B.Cu")
		(net "PVDDCR_CPU1_P1_VCC2")
	)
	(segment
		(start 76.453746 -336.45221)
		(end 75.990704 -336.45221)
		(width 0.254)
		(layer "B.Cu")
		(net "PVDDCR_CPU1_P1_VCC2")
	)
	(segment
		(start 75.786488 -336.656426)
		(end 75.090274 -336.656426)
		(width 0.254)
		(layer "B.Cu")
		(net "PVDDCR_CPU1_P1_VCC2")
	)
	(segment
		(start 83.791552 -336.633312)
		(end 84.07146 -336.353404)
		(width 0.2286)
		(layer "F.Cu")
		(net "PVDDCR_CPU1_P1_VCC1")
	)
	(segment
		(start 86.932262 -338.590382)
		(end 86.85657 -338.666074)
		(width 0.2286)
		(layer "F.Cu")
		(net "PVDDCR_CPU1_P1_VCC1")
	)
	(segment
		(start 83.439254 -337.243674)
		(end 83.439254 -336.633312)
		(width 0.4572)
		(layer "F.Cu")
		(net "PVDDCR_CPU1_P1_VCC1")
	)
	(segment
		(start 86.932262 -337.87842)
		(end 86.932262 -338.590382)
		(width 0.2286)
		(layer "F.Cu")
		(net "PVDDCR_CPU1_P1_VCC1")
	)
	(segment
		(start 83.439254 -336.633312)
		(end 83.791552 -336.633312)
		(width 0.2286)
		(layer "F.Cu")
		(net "PVDDCR_CPU1_P1_VCC1")
	)
	(segment
		(start 84.07146 -336.353404)
		(end 84.722208 -336.353404)
		(width 0.2286)
		(layer "F.Cu")
		(net "PVDDCR_CPU1_P1_VCC1")
	)
	(via
		(at 86.85657 -338.666074)
		(size 0.508)
		(drill 0.254)
		(layers "F.Cu" "B.Cu")
		(net "PVDDCR_CPU1_P1_VCC1")
	)
	(via
		(at 83.439254 -336.633312)
		(size 0.508)
		(drill 0.254)
		(layers "F.Cu" "B.Cu")
		(net "PVDDCR_CPU1_P1_VCC1")
	)
	(via
		(at 85.90153 -337.711034)
		(size 0.6604)
		(drill 0.3302)
		(layers "F.Cu" "B.Cu")
		(net "PVDDCR_CPU1_P1_VCC1")
	)
	(segment
		(start 85.90153 -337.711034)
		(end 86.85657 -338.666074)
		(width 0.254)
		(layer "B.Cu")
		(net "PVDDCR_CPU1_P1_VCC1")
	)
	(segment
		(start 84.779866 -336.469228)
		(end 84.779866 -337.287108)
		(width 0.254)
		(layer "B.Cu")
		(net "PVDDCR_CPU1_P1_VCC1")
	)
	(segment
		(start 84.811362 -336.437732)
		(end 84.779866 -336.469228)
		(width 0.254)
		(layer "B.Cu")
		(net "PVDDCR_CPU1_P1_VCC1")
	)
	(segment
		(start 84.779866 -337.287108)
		(end 85.203792 -337.711034)
		(width 0.254)
		(layer "B.Cu")
		(net "PVDDCR_CPU1_P1_VCC1")
	)
	(segment
		(start 84.34832 -336.437732)
		(end 84.144104 -336.641948)
		(width 0.254)
		(layer "B.Cu")
		(net "PVDDCR_CPU1_P1_VCC1")
	)
	(segment
		(start 85.203792 -337.711034)
		(end 85.90153 -337.711034)
		(width 0.254)
		(layer "B.Cu")
		(net "PVDDCR_CPU1_P1_VCC1")
	)
	(segment
		(start 84.144104 -336.641948)
		(end 83.44789 -336.641948)
		(width 0.254)
		(layer "B.Cu")
		(net "PVDDCR_CPU1_P1_VCC1")
	)
	(segment
		(start 84.811362 -336.437732)
		(end 84.34832 -336.437732)
		(width 0.254)
		(layer "B.Cu")
		(net "PVDDCR_CPU1_P1_VCC1")
	)
	(segment
		(start 83.44789 -336.641948)
		(end 83.439254 -336.633312)
		(width 0.254)
		(layer "B.Cu")
		(net "PVDDCR_CPU1_P1_VCC1")
	)
	(segment
		(start 34.058098 -365.909098)
		(end 33.355026 -365.909098)
		(width 0.1778)
		(layer "F.Cu")
		(net "PVDDCR_CPU1_P1_VCC")
	)
	(segment
		(start 36.837112 -368.055398)
		(end 37.853112 -368.055398)
		(width 0.254)
		(layer "F.Cu")
		(net "PVDDCR_CPU1_P1_VCC")
	)
	(segment
		(start 35.821112 -368.055398)
		(end 36.837112 -368.055398)
		(width 0.254)
		(layer "F.Cu")
		(net "PVDDCR_CPU1_P1_VCC")
	)
	(segment
		(start 35.821112 -368.055398)
		(end 35.821112 -367.672112)
		(width 0.254)
		(layer "F.Cu")
		(net "PVDDCR_CPU1_P1_VCC")
	)
	(segment
		(start 35.821112 -367.672112)
		(end 35.433 -367.284)
		(width 0.254)
		(layer "F.Cu")
		(net "PVDDCR_CPU1_P1_VCC")
	)
	(segment
		(start 35.433 -367.284)
		(end 34.5694 -366.4204)
		(width 0.254)
		(layer "F.Cu")
		(net "PVDDCR_CPU1_P1_VCC")
	)
	(segment
		(start 34.5694 -366.4204)
		(end 34.058098 -365.909098)
		(width 0.1778)
		(layer "F.Cu")
		(net "PVDDCR_CPU1_P1_VCC")
	)
	(via
		(at 35.433 -367.284)
		(size 0.508)
		(drill 0.254)
		(layers "F.Cu" "B.Cu")
		(net "PVDDCR_CPU1_P1_VCC")
	)
	(segment
		(start 102.768146 -343.87282)
		(end 102.768146 -343.601802)
		(width 0.2286)
		(layer "F.Cu")
		(net "PVDDCR_CPU1_P1_TEMP0")
	)
	(segment
		(start 78.124558 -338.179918)
		(end 78.124558 -337.892898)
		(width 0.2286)
		(layer "F.Cu")
		(net "PVDDCR_CPU1_P1_TEMP0")
	)
	(segment
		(start 103.089202 -343.12733)
		(end 103.089202 -342.839294)
		(width 0.2286)
		(layer "F.Cu")
		(net "PVDDCR_CPU1_P1_TEMP0")
	)
	(segment
		(start 61.130434 -350.166686)
		(end 61.234574 -349.915226)
		(width 0.2286)
		(layer "F.Cu")
		(net "PVDDCR_CPU1_P1_TEMP0")
	)
	(segment
		(start 69.768974 -338.198206)
		(end 69.768974 -337.90001)
		(width 0.2286)
		(layer "F.Cu")
		(net "PVDDCR_CPU1_P1_TEMP0")
	)
	(segment
		(start 102.980744 -343.389204)
		(end 103.089202 -343.12733)
		(width 0.2286)
		(layer "F.Cu")
		(net "PVDDCR_CPU1_P1_TEMP0")
	)
	(segment
		(start 102.768146 -343.601802)
		(end 102.980744 -343.389204)
		(width 0.2286)
		(layer "F.Cu")
		(net "PVDDCR_CPU1_P1_TEMP0")
	)
	(segment
		(start 60.913518 -350.65462)
		(end 60.913518 -350.383602)
		(width 0.2286)
		(layer "F.Cu")
		(net "PVDDCR_CPU1_P1_TEMP0")
	)
	(segment
		(start 60.913518 -350.383602)
		(end 61.130434 -350.166686)
		(width 0.2286)
		(layer "F.Cu")
		(net "PVDDCR_CPU1_P1_TEMP0")
	)
	(segment
		(start 36.81095 -364.109)
		(end 35.941 -364.109)
		(width 0.1778)
		(layer "F.Cu")
		(net "PVDDCR_CPU1_P1_TEMP0")
	)
	(segment
		(start 94.492318 -338.691728)
		(end 94.706186 -338.47786)
		(width 0.2286)
		(layer "F.Cu")
		(net "PVDDCR_CPU1_P1_TEMP0")
	)
	(segment
		(start 77.803502 -338.926424)
		(end 77.803502 -338.655406)
		(width 0.2286)
		(layer "F.Cu")
		(net "PVDDCR_CPU1_P1_TEMP0")
	)
	(segment
		(start 86.482174 -338.174076)
		(end 86.482174 -337.87842)
		(width 0.2286)
		(layer "F.Cu")
		(net "PVDDCR_CPU1_P1_TEMP0")
	)
	(segment
		(start 69.667628 -338.442808)
		(end 69.768974 -338.198206)
		(width 0.2286)
		(layer "F.Cu")
		(net "PVDDCR_CPU1_P1_TEMP0")
	)
	(segment
		(start 94.492318 -338.962746)
		(end 94.492318 -338.691728)
		(width 0.2286)
		(layer "F.Cu")
		(net "PVDDCR_CPU1_P1_TEMP0")
	)
	(segment
		(start 34.960052 -364.708948)
		(end 33.355026 -364.708948)
		(width 0.1778)
		(layer "F.Cu")
		(net "PVDDCR_CPU1_P1_TEMP0")
	)
	(segment
		(start 94.813374 -338.219034)
		(end 94.813374 -337.92922)
		(width 0.2286)
		(layer "F.Cu")
		(net "PVDDCR_CPU1_P1_TEMP0")
	)
	(segment
		(start 69.447918 -338.662518)
		(end 69.667628 -338.442808)
		(width 0.2286)
		(layer "F.Cu")
		(net "PVDDCR_CPU1_P1_TEMP0")
	)
	(segment
		(start 35.56 -364.109)
		(end 34.960052 -364.708948)
		(width 0.1778)
		(layer "F.Cu")
		(net "PVDDCR_CPU1_P1_TEMP0")
	)
	(segment
		(start 86.161118 -338.640928)
		(end 86.37905 -338.422996)
		(width 0.2286)
		(layer "F.Cu")
		(net "PVDDCR_CPU1_P1_TEMP0")
	)
	(segment
		(start 35.941 -364.109)
		(end 35.56 -364.109)
		(width 0.1778)
		(layer "F.Cu")
		(net "PVDDCR_CPU1_P1_TEMP0")
	)
	(segment
		(start 94.706186 -338.47786)
		(end 94.813374 -338.219034)
		(width 0.2286)
		(layer "F.Cu")
		(net "PVDDCR_CPU1_P1_TEMP0")
	)
	(segment
		(start 78.015338 -338.44357)
		(end 78.124558 -338.179918)
		(width 0.2286)
		(layer "F.Cu")
		(net "PVDDCR_CPU1_P1_TEMP0")
	)
	(segment
		(start 86.161118 -338.911946)
		(end 86.161118 -338.640928)
		(width 0.2286)
		(layer "F.Cu")
		(net "PVDDCR_CPU1_P1_TEMP0")
	)
	(segment
		(start 61.234574 -349.915226)
		(end 61.234574 -349.621094)
		(width 0.2286)
		(layer "F.Cu")
		(net "PVDDCR_CPU1_P1_TEMP0")
	)
	(segment
		(start 77.803502 -338.655406)
		(end 78.015338 -338.44357)
		(width 0.2286)
		(layer "F.Cu")
		(net "PVDDCR_CPU1_P1_TEMP0")
	)
	(segment
		(start 86.37905 -338.422996)
		(end 86.482174 -338.174076)
		(width 0.2286)
		(layer "F.Cu")
		(net "PVDDCR_CPU1_P1_TEMP0")
	)
	(segment
		(start 69.447918 -338.933536)
		(end 69.447918 -338.662518)
		(width 0.2286)
		(layer "F.Cu")
		(net "PVDDCR_CPU1_P1_TEMP0")
	)
	(via
		(at 77.803502 -338.926424)
		(size 0.508)
		(drill 0.254)
		(layers "F.Cu" "B.Cu")
		(net "PVDDCR_CPU1_P1_TEMP0")
	)
	(via
		(at 69.447918 -338.933536)
		(size 0.508)
		(drill 0.254)
		(layers "F.Cu" "B.Cu")
		(net "PVDDCR_CPU1_P1_TEMP0")
	)
	(via
		(at 102.768146 -343.87282)
		(size 0.508)
		(drill 0.254)
		(layers "F.Cu" "B.Cu")
		(net "PVDDCR_CPU1_P1_TEMP0")
	)
	(via
		(at 94.492318 -338.962746)
		(size 0.508)
		(drill 0.254)
		(layers "F.Cu" "B.Cu")
		(net "PVDDCR_CPU1_P1_TEMP0")
	)
	(via
		(at 35.941 -364.109)
		(size 0.508)
		(drill 0.254)
		(layers "F.Cu" "B.Cu")
		(net "PVDDCR_CPU1_P1_TEMP0")
	)
	(via
		(at 86.161118 -338.911946)
		(size 0.508)
		(drill 0.254)
		(layers "F.Cu" "B.Cu")
		(net "PVDDCR_CPU1_P1_TEMP0")
	)
	(via
		(at 60.913518 -350.65462)
		(size 0.508)
		(drill 0.254)
		(layers "F.Cu" "B.Cu")
		(net "PVDDCR_CPU1_P1_TEMP0")
	)
	(segment
		(start 67.122294 -351.557336)
		(end 67.122294 -347.391736)
		(width 0.254)
		(layer "In2.Cu")
		(net "PVDDCR_CPU1_P1_TEMP0")
	)
	(segment
		(start 60.913518 -352.528886)
		(end 61.407294 -353.022662)
		(width 0.254)
		(layer "In2.Cu")
		(net "PVDDCR_CPU1_P1_TEMP0")
	)
	(segment
		(start 70.119494 -340.940136)
		(end 70.622922 -340.940136)
		(width 0.254)
		(layer "In2.Cu")
		(net "PVDDCR_CPU1_P1_TEMP0")
	)
	(segment
		(start 86.835742 -341.067136)
		(end 93.995494 -341.067136)
		(width 0.254)
		(layer "In2.Cu")
		(net "PVDDCR_CPU1_P1_TEMP0")
	)
	(segment
		(start 77.803502 -340.496144)
		(end 77.803502 -340.495128)
		(width 0.254)
		(layer "In2.Cu")
		(net "PVDDCR_CPU1_P1_TEMP0")
	)
	(segment
		(start 60.913518 -352.528886)
		(end 60.473844 -352.96856)
		(width 0.254)
		(layer "In2.Cu")
		(net "PVDDCR_CPU1_P1_TEMP0")
	)
	(segment
		(start 60.473844 -352.96856)
		(end 53.488336 -352.96856)
		(width 0.254)
		(layer "In2.Cu")
		(net "PVDDCR_CPU1_P1_TEMP0")
	)
	(segment
		(start 78.374494 -341.067136)
		(end 77.803502 -340.496144)
		(width 0.254)
		(layer "In2.Cu")
		(net "PVDDCR_CPU1_P1_TEMP0")
	)
	(segment
		(start 102.631494 -344.009472)
		(end 102.768146 -343.87282)
		(width 0.254)
		(layer "In2.Cu")
		(net "PVDDCR_CPU1_P1_TEMP0")
	)
	(segment
		(start 85.486494 -341.067136)
		(end 78.374494 -341.067136)
		(width 0.254)
		(layer "In2.Cu")
		(net "PVDDCR_CPU1_P1_TEMP0")
	)
	(segment
		(start 94.503494 -340.559136)
		(end 97.424494 -343.480136)
		(width 0.254)
		(layer "In2.Cu")
		(net "PVDDCR_CPU1_P1_TEMP0")
	)
	(segment
		(start 36.5252 -362.5342)
		(end 36.5252 -363.5248)
		(width 0.254)
		(layer "In2.Cu")
		(net "PVDDCR_CPU1_P1_TEMP0")
	)
	(segment
		(start 93.995494 -341.067136)
		(end 94.503494 -340.559136)
		(width 0.254)
		(layer "In2.Cu")
		(net "PVDDCR_CPU1_P1_TEMP0")
	)
	(segment
		(start 71.1327 -340.430358)
		(end 72.319642 -340.430358)
		(width 0.254)
		(layer "In2.Cu")
		(net "PVDDCR_CPU1_P1_TEMP0")
	)
	(segment
		(start 65.656968 -353.022662)
		(end 67.122294 -351.557336)
		(width 0.254)
		(layer "In2.Cu")
		(net "PVDDCR_CPU1_P1_TEMP0")
	)
	(segment
		(start 66.512694 -342.557862)
		(end 68.48983 -340.580726)
		(width 0.254)
		(layer "In2.Cu")
		(net "PVDDCR_CPU1_P1_TEMP0")
	)
	(segment
		(start 70.622922 -340.940136)
		(end 71.1327 -340.430358)
		(width 0.254)
		(layer "In2.Cu")
		(net "PVDDCR_CPU1_P1_TEMP0")
	)
	(segment
		(start 97.424494 -344.877136)
		(end 98.694494 -346.147136)
		(width 0.254)
		(layer "In2.Cu")
		(net "PVDDCR_CPU1_P1_TEMP0")
	)
	(segment
		(start 86.161118 -340.392512)
		(end 86.835742 -341.067136)
		(width 0.254)
		(layer "In2.Cu")
		(net "PVDDCR_CPU1_P1_TEMP0")
	)
	(segment
		(start 29.21 -360.7562)
		(end 34.7472 -360.7562)
		(width 0.254)
		(layer "In2.Cu")
		(net "PVDDCR_CPU1_P1_TEMP0")
	)
	(segment
		(start 27.0764 -358.6226)
		(end 29.21 -360.7562)
		(width 0.254)
		(layer "In2.Cu")
		(net "PVDDCR_CPU1_P1_TEMP0")
	)
	(segment
		(start 94.492318 -340.54796)
		(end 94.503494 -340.559136)
		(width 0.254)
		(layer "In2.Cu")
		(net "PVDDCR_CPU1_P1_TEMP0")
	)
	(segment
		(start 97.424494 -343.480136)
		(end 97.424494 -344.877136)
		(width 0.254)
		(layer "In2.Cu")
		(net "PVDDCR_CPU1_P1_TEMP0")
	)
	(segment
		(start 67.122294 -347.391736)
		(end 66.512694 -346.782136)
		(width 0.254)
		(layer "In2.Cu")
		(net "PVDDCR_CPU1_P1_TEMP0")
	)
	(segment
		(start 77.12837 -341.17026)
		(end 77.803502 -340.495128)
		(width 0.254)
		(layer "In2.Cu")
		(net "PVDDCR_CPU1_P1_TEMP0")
	)
	(segment
		(start 73.059544 -341.17026)
		(end 77.12837 -341.17026)
		(width 0.254)
		(layer "In2.Cu")
		(net "PVDDCR_CPU1_P1_TEMP0")
	)
	(segment
		(start 52.994814 -353.462082)
		(end 28.071318 -353.462082)
		(width 0.254)
		(layer "In2.Cu")
		(net "PVDDCR_CPU1_P1_TEMP0")
	)
	(segment
		(start 72.319642 -340.430358)
		(end 73.059544 -341.17026)
		(width 0.254)
		(layer "In2.Cu")
		(net "PVDDCR_CPU1_P1_TEMP0")
	)
	(segment
		(start 98.694494 -346.147136)
		(end 101.869494 -346.147136)
		(width 0.254)
		(layer "In2.Cu")
		(net "PVDDCR_CPU1_P1_TEMP0")
	)
	(segment
		(start 69.135752 -340.580726)
		(end 69.447918 -340.26856)
		(width 0.254)
		(layer "In2.Cu")
		(net "PVDDCR_CPU1_P1_TEMP0")
	)
	(segment
		(start 69.447918 -338.933536)
		(end 69.447918 -340.26856)
		(width 0.254)
		(layer "In2.Cu")
		(net "PVDDCR_CPU1_P1_TEMP0")
	)
	(segment
		(start 61.407294 -353.022662)
		(end 65.656968 -353.022662)
		(width 0.254)
		(layer "In2.Cu")
		(net "PVDDCR_CPU1_P1_TEMP0")
	)
	(segment
		(start 68.48983 -340.580726)
		(end 69.135752 -340.580726)
		(width 0.254)
		(layer "In2.Cu")
		(net "PVDDCR_CPU1_P1_TEMP0")
	)
	(segment
		(start 86.161118 -338.911946)
		(end 86.161118 -340.392512)
		(width 0.254)
		(layer "In2.Cu")
		(net "PVDDCR_CPU1_P1_TEMP0")
	)
	(segment
		(start 60.913518 -350.65462)
		(end 60.913518 -352.528886)
		(width 0.254)
		(layer "In2.Cu")
		(net "PVDDCR_CPU1_P1_TEMP0")
	)
	(segment
		(start 101.869494 -346.147136)
		(end 102.631494 -345.385136)
		(width 0.254)
		(layer "In2.Cu")
		(net "PVDDCR_CPU1_P1_TEMP0")
	)
	(segment
		(start 34.7472 -360.7562)
		(end 36.5252 -362.5342)
		(width 0.254)
		(layer "In2.Cu")
		(net "PVDDCR_CPU1_P1_TEMP0")
	)
	(segment
		(start 69.447918 -340.26856)
		(end 70.119494 -340.940136)
		(width 0.254)
		(layer "In2.Cu")
		(net "PVDDCR_CPU1_P1_TEMP0")
	)
	(segment
		(start 86.161118 -340.392512)
		(end 85.486494 -341.067136)
		(width 0.254)
		(layer "In2.Cu")
		(net "PVDDCR_CPU1_P1_TEMP0")
	)
	(segment
		(start 27.0764 -354.457)
		(end 27.0764 -358.6226)
		(width 0.254)
		(layer "In2.Cu")
		(net "PVDDCR_CPU1_P1_TEMP0")
	)
	(segment
		(start 36.5252 -363.5248)
		(end 35.941 -364.109)
		(width 0.254)
		(layer "In2.Cu")
		(net "PVDDCR_CPU1_P1_TEMP0")
	)
	(segment
		(start 77.803502 -340.495128)
		(end 77.803502 -338.926424)
		(width 0.254)
		(layer "In2.Cu")
		(net "PVDDCR_CPU1_P1_TEMP0")
	)
	(segment
		(start 53.488336 -352.96856)
		(end 52.994814 -353.462082)
		(width 0.254)
		(layer "In2.Cu")
		(net "PVDDCR_CPU1_P1_TEMP0")
	)
	(segment
		(start 28.071318 -353.462082)
		(end 27.0764 -354.457)
		(width 0.254)
		(layer "In2.Cu")
		(net "PVDDCR_CPU1_P1_TEMP0")
	)
	(segment
		(start 102.631494 -345.385136)
		(end 102.631494 -344.009472)
		(width 0.254)
		(layer "In2.Cu")
		(net "PVDDCR_CPU1_P1_TEMP0")
	)
	(segment
		(start 66.512694 -346.782136)
		(end 66.512694 -342.557862)
		(width 0.254)
		(layer "In2.Cu")
		(net "PVDDCR_CPU1_P1_TEMP0")
	)
	(segment
		(start 94.492318 -338.962746)
		(end 94.492318 -340.54796)
		(width 0.254)
		(layer "In2.Cu")
		(net "PVDDCR_CPU1_P1_TEMP0")
	)
	(segment
		(start 23.455376 -366.336326)
		(end 26.24201 -366.336326)
		(width 0.10668)
		(layer "F.Cu")
		(net "PVDDCR_CPU1_P1_SMB_ALERT_R")
	)
	(segment
		(start 27.069288 -365.509048)
		(end 27.604974 -365.509048)
		(width 0.10668)
		(layer "F.Cu")
		(net "PVDDCR_CPU1_P1_SMB_ALERT_R")
	)
	(segment
		(start 22.87905 -365.76)
		(end 23.455376 -366.336326)
		(width 0.10668)
		(layer "F.Cu")
		(net "PVDDCR_CPU1_P1_SMB_ALERT_R")
	)
	(segment
		(start 26.24201 -366.336326)
		(end 27.069288 -365.509048)
		(width 0.10668)
		(layer "F.Cu")
		(net "PVDDCR_CPU1_P1_SMB_ALERT_R")
	)
	(segment
		(start 184.785 -105.204768)
		(end 185.522362 -105.94213)
		(width 0.10668)
		(layer "F.Cu")
		(net "PVDDCR_CPU1_P1_SMB_ALERT")
	)
	(segment
		(start 184.785 -100.694998)
		(end 184.785 -105.204768)
		(width 0.10668)
		(layer "F.Cu")
		(net "PVDDCR_CPU1_P1_SMB_ALERT")
	)
	(segment
		(start 185.122058 -110.652814)
		(end 184.732168 -110.262924)
		(width 0.10668)
		(layer "F.Cu")
		(net "PVDDCR_CPU1_P1_SMB_ALERT")
	)
	(segment
		(start 21.455634 -362.752132)
		(end 20.7772 -362.752132)
		(width 0.10668)
		(layer "F.Cu")
		(net "PVDDCR_CPU1_P1_SMB_ALERT")
	)
	(segment
		(start 20.7772 -362.752132)
		(end 20.587208 -362.56214)
		(width 0.10668)
		(layer "F.Cu")
		(net "PVDDCR_CPU1_P1_SMB_ALERT")
	)
	(segment
		(start 185.522362 -105.94213)
		(end 185.522362 -110.25251)
		(width 0.10668)
		(layer "F.Cu")
		(net "PVDDCR_CPU1_P1_SMB_ALERT")
	)
	(segment
		(start 185.522362 -110.25251)
		(end 185.122058 -110.652814)
		(width 0.10668)
		(layer "F.Cu")
		(net "PVDDCR_CPU1_P1_SMB_ALERT")
	)
	(segment
		(start 22.07895 -365.76)
		(end 22.07895 -364.617)
		(width 0.10668)
		(layer "F.Cu")
		(net "PVDDCR_CPU1_P1_SMB_ALERT")
	)
	(segment
		(start 22.256242 -364.439708)
		(end 22.256242 -363.55274)
		(width 0.10668)
		(layer "F.Cu")
		(net "PVDDCR_CPU1_P1_SMB_ALERT")
	)
	(segment
		(start 22.256242 -363.55274)
		(end 21.455634 -362.752132)
		(width 0.10668)
		(layer "F.Cu")
		(net "PVDDCR_CPU1_P1_SMB_ALERT")
	)
	(segment
		(start 22.07895 -364.617)
		(end 22.256242 -364.439708)
		(width 0.10668)
		(layer "F.Cu")
		(net "PVDDCR_CPU1_P1_SMB_ALERT")
	)
	(via
		(at 20.587208 -362.56214)
		(size 0.508)
		(drill 0.254)
		(layers "F.Cu" "B.Cu")
		(net "PVDDCR_CPU1_P1_SMB_ALERT")
	)
	(via
		(at 182.298848 -87.910162)
		(size 0.508)
		(drill 0.254)
		(layers "F.Cu" "B.Cu")
		(net "PVDDCR_CPU1_P1_SMB_ALERT")
	)
	(via
		(at 114.171984 -120.398286)
		(size 0.508)
		(drill 0.254)
		(layers "F.Cu" "B.Cu")
		(net "PVDDCR_CPU1_P1_SMB_ALERT")
	)
	(via
		(at 167.36187 -86.83879)
		(size 0.508)
		(drill 0.254)
		(layers "F.Cu" "B.Cu")
		(net "PVDDCR_CPU1_P1_SMB_ALERT")
	)
	(via
		(at 184.732168 -110.262924)
		(size 0.4572)
		(drill 0.254)
		(layers "F.Cu" "B.Cu")
		(net "PVDDCR_CPU1_P1_SMB_ALERT")
	)
	(segment
		(start 182.298848 -87.910162)
		(end 182.298848 -87.521034)
		(width 0.11684)
		(layer "In2.Cu")
		(net "PVDDCR_CPU1_P1_SMB_ALERT")
	)
	(segment
		(start 181.393846 -86.616032)
		(end 167.584628 -86.616032)
		(width 0.11684)
		(layer "In2.Cu")
		(net "PVDDCR_CPU1_P1_SMB_ALERT")
	)
	(segment
		(start 167.584628 -86.616032)
		(end 167.36187 -86.83879)
		(width 0.11684)
		(layer "In2.Cu")
		(net "PVDDCR_CPU1_P1_SMB_ALERT")
	)
	(segment
		(start 182.298848 -87.521034)
		(end 181.393846 -86.616032)
		(width 0.11684)
		(layer "In2.Cu")
		(net "PVDDCR_CPU1_P1_SMB_ALERT")
	)
	(segment
		(start 182.298848 -89.189814)
		(end 182.298848 -87.910162)
		(width 0.11684)
		(layer "In4.Cu")
		(net "PVDDCR_CPU1_P1_SMB_ALERT")
	)
	(segment
		(start 185.0644 -100.68814)
		(end 186.2836 -99.46894)
		(width 0.11684)
		(layer "In4.Cu")
		(net "PVDDCR_CPU1_P1_SMB_ALERT")
	)
	(segment
		(start 184.300622 -93.235272)
		(end 183.201056 -92.135706)
		(width 0.11684)
		(layer "In4.Cu")
		(net "PVDDCR_CPU1_P1_SMB_ALERT")
	)
	(segment
		(start 186.2836 -96.449388)
		(end 184.300622 -94.46641)
		(width 0.11684)
		(layer "In4.Cu")
		(net "PVDDCR_CPU1_P1_SMB_ALERT")
	)
	(segment
		(start 185.736484 -103.430324)
		(end 185.0644 -102.75824)
		(width 0.11684)
		(layer "In4.Cu")
		(net "PVDDCR_CPU1_P1_SMB_ALERT")
	)
	(segment
		(start 185.736484 -105.739184)
		(end 185.736484 -103.430324)
		(width 0.11684)
		(layer "In4.Cu")
		(net "PVDDCR_CPU1_P1_SMB_ALERT")
	)
	(segment
		(start 182.196232 -89.29243)
		(end 182.298848 -89.189814)
		(width 0.11684)
		(layer "In4.Cu")
		(net "PVDDCR_CPU1_P1_SMB_ALERT")
	)
	(segment
		(start 183.201056 -92.135706)
		(end 183.201056 -91.143074)
		(width 0.11684)
		(layer "In4.Cu")
		(net "PVDDCR_CPU1_P1_SMB_ALERT")
	)
	(segment
		(start 184.300622 -94.46641)
		(end 184.300622 -93.235272)
		(width 0.11684)
		(layer "In4.Cu")
		(net "PVDDCR_CPU1_P1_SMB_ALERT")
	)
	(segment
		(start 185.5089 -105.966768)
		(end 185.736484 -105.739184)
		(width 0.11684)
		(layer "In4.Cu")
		(net "PVDDCR_CPU1_P1_SMB_ALERT")
	)
	(segment
		(start 185.0644 -102.75824)
		(end 185.0644 -100.68814)
		(width 0.11684)
		(layer "In4.Cu")
		(net "PVDDCR_CPU1_P1_SMB_ALERT")
	)
	(segment
		(start 183.201056 -91.143074)
		(end 182.196232 -90.13825)
		(width 0.11684)
		(layer "In4.Cu")
		(net "PVDDCR_CPU1_P1_SMB_ALERT")
	)
	(segment
		(start 184.732168 -110.262924)
		(end 185.5089 -109.486192)
		(width 0.11684)
		(layer "In4.Cu")
		(net "PVDDCR_CPU1_P1_SMB_ALERT")
	)
	(segment
		(start 182.196232 -90.13825)
		(end 182.196232 -89.29243)
		(width 0.11684)
		(layer "In4.Cu")
		(net "PVDDCR_CPU1_P1_SMB_ALERT")
	)
	(segment
		(start 185.5089 -109.486192)
		(end 185.5089 -105.966768)
		(width 0.11684)
		(layer "In4.Cu")
		(net "PVDDCR_CPU1_P1_SMB_ALERT")
	)
	(segment
		(start 186.2836 -99.46894)
		(end 186.2836 -96.449388)
		(width 0.11684)
		(layer "In4.Cu")
		(net "PVDDCR_CPU1_P1_SMB_ALERT")
	)
	(segment
		(start 159.225742 -97.127568)
		(end 167.033702 -89.319608)
		(width 0.11684)
		(layer "In6.Cu")
		(net "PVDDCR_CPU1_P1_SMB_ALERT")
	)
	(segment
		(start 160.070292 -107.826556)
		(end 160.070292 -106.94543)
		(width 0.11684)
		(layer "In6.Cu")
		(net "PVDDCR_CPU1_P1_SMB_ALERT")
	)
	(segment
		(start 115.853718 -118.716552)
		(end 145.179034 -118.716552)
		(width 0.11684)
		(layer "In6.Cu")
		(net "PVDDCR_CPU1_P1_SMB_ALERT")
	)
	(segment
		(start 159.225742 -108.671106)
		(end 160.070292 -107.826556)
		(width 0.11684)
		(layer "In6.Cu")
		(net "PVDDCR_CPU1_P1_SMB_ALERT")
	)
	(segment
		(start 167.033702 -87.166958)
		(end 167.36187 -86.83879)
		(width 0.11684)
		(layer "In6.Cu")
		(net "PVDDCR_CPU1_P1_SMB_ALERT")
	)
	(segment
		(start 145.179034 -118.716552)
		(end 148.022056 -115.87353)
		(width 0.11684)
		(layer "In6.Cu")
		(net "PVDDCR_CPU1_P1_SMB_ALERT")
	)
	(segment
		(start 159.225742 -106.10088)
		(end 159.225742 -97.127568)
		(width 0.11684)
		(layer "In6.Cu")
		(net "PVDDCR_CPU1_P1_SMB_ALERT")
	)
	(segment
		(start 155.414472 -115.87353)
		(end 159.225742 -112.06226)
		(width 0.11684)
		(layer "In6.Cu")
		(net "PVDDCR_CPU1_P1_SMB_ALERT")
	)
	(segment
		(start 148.022056 -115.87353)
		(end 155.414472 -115.87353)
		(width 0.11684)
		(layer "In6.Cu")
		(net "PVDDCR_CPU1_P1_SMB_ALERT")
	)
	(segment
		(start 159.225742 -112.06226)
		(end 159.225742 -108.671106)
		(width 0.11684)
		(layer "In6.Cu")
		(net "PVDDCR_CPU1_P1_SMB_ALERT")
	)
	(segment
		(start 114.171984 -120.398286)
		(end 115.853718 -118.716552)
		(width 0.11684)
		(layer "In6.Cu")
		(net "PVDDCR_CPU1_P1_SMB_ALERT")
	)
	(segment
		(start 160.070292 -106.94543)
		(end 159.225742 -106.10088)
		(width 0.11684)
		(layer "In6.Cu")
		(net "PVDDCR_CPU1_P1_SMB_ALERT")
	)
	(segment
		(start 167.033702 -89.319608)
		(end 167.033702 -87.166958)
		(width 0.11684)
		(layer "In6.Cu")
		(net "PVDDCR_CPU1_P1_SMB_ALERT")
	)
	(segment
		(start 18.862548 -356.438962)
		(end 15.75308 -353.329494)
		(width 0.11684)
		(layer "In11.Cu")
		(net "PVDDCR_CPU1_P1_SMB_ALERT")
	)
	(segment
		(start 26.595832 -137.671048)
		(end 44.469304 -137.671048)
		(width 0.11684)
		(layer "In11.Cu")
		(net "PVDDCR_CPU1_P1_SMB_ALERT")
	)
	(segment
		(start 20.587208 -362.56214)
		(end 18.862548 -360.83748)
		(width 0.11684)
		(layer "In11.Cu")
		(net "PVDDCR_CPU1_P1_SMB_ALERT")
	)
	(segment
		(start 88.160098 -131.653534)
		(end 95.759524 -124.054108)
		(width 0.11684)
		(layer "In11.Cu")
		(net "PVDDCR_CPU1_P1_SMB_ALERT")
	)
	(segment
		(start 51.572922 -130.56743)
		(end 86.190836 -130.56743)
		(width 0.11684)
		(layer "In11.Cu")
		(net "PVDDCR_CPU1_P1_SMB_ALERT")
	)
	(segment
		(start 5.979668 -335.655412)
		(end 5.979668 -168.314624)
		(width 0.11684)
		(layer "In11.Cu")
		(net "PVDDCR_CPU1_P1_SMB_ALERT")
	)
	(segment
		(start 18.862548 -360.83748)
		(end 18.862548 -356.438962)
		(width 0.11684)
		(layer "In11.Cu")
		(net "PVDDCR_CPU1_P1_SMB_ALERT")
	)
	(segment
		(start 113.424208 -120.398286)
		(end 114.171984 -120.398286)
		(width 0.11684)
		(layer "In11.Cu")
		(net "PVDDCR_CPU1_P1_SMB_ALERT")
	)
	(segment
		(start 95.759524 -124.054108)
		(end 109.768386 -124.054108)
		(width 0.11684)
		(layer "In11.Cu")
		(net "PVDDCR_CPU1_P1_SMB_ALERT")
	)
	(segment
		(start 109.768386 -124.054108)
		(end 113.424208 -120.398286)
		(width 0.11684)
		(layer "In11.Cu")
		(net "PVDDCR_CPU1_P1_SMB_ALERT")
	)
	(segment
		(start 87.27694 -131.653534)
		(end 88.160098 -131.653534)
		(width 0.11684)
		(layer "In11.Cu")
		(net "PVDDCR_CPU1_P1_SMB_ALERT")
	)
	(segment
		(start 44.469304 -137.671048)
		(end 51.572922 -130.56743)
		(width 0.11684)
		(layer "In11.Cu")
		(net "PVDDCR_CPU1_P1_SMB_ALERT")
	)
	(segment
		(start 15.75308 -353.329494)
		(end 15.75308 -345.428824)
		(width 0.11684)
		(layer "In11.Cu")
		(net "PVDDCR_CPU1_P1_SMB_ALERT")
	)
	(segment
		(start 14.172184 -166.996364)
		(end 18.04543 -163.123118)
		(width 0.11684)
		(layer "In11.Cu")
		(net "PVDDCR_CPU1_P1_SMB_ALERT")
	)
	(segment
		(start 7.297928 -166.996364)
		(end 14.172184 -166.996364)
		(width 0.11684)
		(layer "In11.Cu")
		(net "PVDDCR_CPU1_P1_SMB_ALERT")
	)
	(segment
		(start 15.75308 -345.428824)
		(end 5.979668 -335.655412)
		(width 0.11684)
		(layer "In11.Cu")
		(net "PVDDCR_CPU1_P1_SMB_ALERT")
	)
	(segment
		(start 18.04543 -146.22145)
		(end 26.595832 -137.671048)
		(width 0.11684)
		(layer "In11.Cu")
		(net "PVDDCR_CPU1_P1_SMB_ALERT")
	)
	(segment
		(start 86.190836 -130.56743)
		(end 87.27694 -131.653534)
		(width 0.11684)
		(layer "In11.Cu")
		(net "PVDDCR_CPU1_P1_SMB_ALERT")
	)
	(segment
		(start 5.979668 -168.314624)
		(end 7.297928 -166.996364)
		(width 0.11684)
		(layer "In11.Cu")
		(net "PVDDCR_CPU1_P1_SMB_ALERT")
	)
	(segment
		(start 18.04543 -163.123118)
		(end 18.04543 -146.22145)
		(width 0.11684)
		(layer "In11.Cu")
		(net "PVDDCR_CPU1_P1_SMB_ALERT")
	)
	(segment
		(start 25.815798 -363.966252)
		(end 26.158444 -364.308898)
		(width 0.10668)
		(layer "F.Cu")
		(net "PVDDCR_CPU1_P1_RESET_N_R")
	)
	(segment
		(start 26.158444 -364.308898)
		(end 27.604974 -364.308898)
		(width 0.10668)
		(layer "F.Cu")
		(net "PVDDCR_CPU1_P1_RESET_N_R")
	)
	(via
		(at 25.815798 -363.966252)
		(size 0.508)
		(drill 0.254)
		(layers "F.Cu" "B.Cu")
		(net "PVDDCR_CPU1_P1_RESET_N_R")
	)
	(segment
		(start 25.196546 -363.347)
		(end 25.815798 -363.966252)
		(width 0.10668)
		(layer "B.Cu")
		(net "PVDDCR_CPU1_P1_RESET_N_R")
	)
	(segment
		(start 25.16505 -363.347)
		(end 25.196546 -363.347)
		(width 0.10668)
		(layer "B.Cu")
		(net "PVDDCR_CPU1_P1_RESET_N_R")
	)
	(segment
		(start 25.16505 -362.985304)
		(end 25.16505 -363.347)
		(width 0.10668)
		(layer "B.Cu")
		(net "PVDDCR_CPU1_P1_RESET_N_R")
	)
	(segment
		(start 23.38705 -362.839)
		(end 25.018746 -362.839)
		(width 0.10668)
		(layer "B.Cu")
		(net "PVDDCR_CPU1_P1_RESET_N_R")
	)
	(segment
		(start 25.018746 -362.839)
		(end 25.16505 -362.985304)
		(width 0.10668)
		(layer "B.Cu")
		(net "PVDDCR_CPU1_P1_RESET_N_R")
	)
	(segment
		(start 22.87905 -363.347)
		(end 23.38705 -362.839)
		(width 0.10668)
		(layer "B.Cu")
		(net "PVDDCR_CPU1_P1_RESET_N_R")
	)
	(segment
		(start 84.057236 -142.308834)
		(end 84.057236 -142.03299)
		(width 0.10668)
		(layer "F.Cu")
		(net "PVDDCR_CPU1_P1_RESET_N")
	)
	(segment
		(start 84.805266 -141.28496)
		(end 84.805266 -134.174992)
		(width 0.10668)
		(layer "F.Cu")
		(net "PVDDCR_CPU1_P1_RESET_N")
	)
	(segment
		(start 84.057236 -142.03299)
		(end 84.805266 -141.28496)
		(width 0.10668)
		(layer "F.Cu")
		(net "PVDDCR_CPU1_P1_RESET_N")
	)
	(segment
		(start 84.805266 -134.174992)
		(end 88.074754 -130.905504)
		(width 0.10668)
		(layer "F.Cu")
		(net "PVDDCR_CPU1_P1_RESET_N")
	)
	(via
		(at 88.074754 -130.905504)
		(size 0.508)
		(drill 0.254)
		(layers "F.Cu" "B.Cu")
		(net "PVDDCR_CPU1_P1_RESET_N")
	)
	(via
		(at 21.194014 -363.347)
		(size 0.508)
		(drill 0.254)
		(layers "F.Cu" "B.Cu")
		(net "PVDDCR_CPU1_P1_RESET_N")
	)
	(segment
		(start 22.07895 -363.347)
		(end 21.194014 -363.347)
		(width 0.10668)
		(layer "B.Cu")
		(net "PVDDCR_CPU1_P1_RESET_N")
	)
	(segment
		(start 5.608828 -168.113456)
		(end 5.608828 -344.072972)
		(width 0.11684)
		(layer "In11.Cu")
		(net "PVDDCR_CPU1_P1_RESET_N")
	)
	(segment
		(start 26.445972 -137.2489)
		(end 17.516602 -146.17827)
		(width 0.11684)
		(layer "In11.Cu")
		(net "PVDDCR_CPU1_P1_RESET_N")
	)
	(segment
		(start 17.516602 -162.915346)
		(end 13.839952 -166.591996)
		(width 0.11684)
		(layer "In11.Cu")
		(net "PVDDCR_CPU1_P1_RESET_N")
	)
	(segment
		(start 44.33697 -137.2489)
		(end 26.445972 -137.2489)
		(width 0.11684)
		(layer "In11.Cu")
		(net "PVDDCR_CPU1_P1_RESET_N")
	)
	(segment
		(start 88.074754 -130.905504)
		(end 87.314532 -130.145282)
		(width 0.11684)
		(layer "In11.Cu")
		(net "PVDDCR_CPU1_P1_RESET_N")
	)
	(segment
		(start 20.559776 -363.347)
		(end 21.194014 -363.347)
		(width 0.11684)
		(layer "In11.Cu")
		(net "PVDDCR_CPU1_P1_RESET_N")
	)
	(segment
		(start 17.516602 -146.17827)
		(end 17.516602 -162.915346)
		(width 0.11684)
		(layer "In11.Cu")
		(net "PVDDCR_CPU1_P1_RESET_N")
	)
	(segment
		(start 4.93522 -344.74658)
		(end 4.93522 -349.961454)
		(width 0.11684)
		(layer "In11.Cu")
		(net "PVDDCR_CPU1_P1_RESET_N")
	)
	(segment
		(start 8.249666 -353.2759)
		(end 15.02283 -353.2759)
		(width 0.11684)
		(layer "In11.Cu")
		(net "PVDDCR_CPU1_P1_RESET_N")
	)
	(segment
		(start 7.130288 -166.591996)
		(end 5.608828 -168.113456)
		(width 0.11684)
		(layer "In11.Cu")
		(net "PVDDCR_CPU1_P1_RESET_N")
	)
	(segment
		(start 87.314532 -130.145282)
		(end 51.440588 -130.145282)
		(width 0.11684)
		(layer "In11.Cu")
		(net "PVDDCR_CPU1_P1_RESET_N")
	)
	(segment
		(start 51.440588 -130.145282)
		(end 44.33697 -137.2489)
		(width 0.11684)
		(layer "In11.Cu")
		(net "PVDDCR_CPU1_P1_RESET_N")
	)
	(segment
		(start 15.02283 -353.2759)
		(end 18.410174 -356.663244)
		(width 0.11684)
		(layer "In11.Cu")
		(net "PVDDCR_CPU1_P1_RESET_N")
	)
	(segment
		(start 18.410174 -361.197398)
		(end 20.559776 -363.347)
		(width 0.11684)
		(layer "In11.Cu")
		(net "PVDDCR_CPU1_P1_RESET_N")
	)
	(segment
		(start 4.93522 -349.961454)
		(end 8.249666 -353.2759)
		(width 0.11684)
		(layer "In11.Cu")
		(net "PVDDCR_CPU1_P1_RESET_N")
	)
	(segment
		(start 13.839952 -166.591996)
		(end 7.130288 -166.591996)
		(width 0.11684)
		(layer "In11.Cu")
		(net "PVDDCR_CPU1_P1_RESET_N")
	)
	(segment
		(start 5.608828 -344.072972)
		(end 4.93522 -344.74658)
		(width 0.11684)
		(layer "In11.Cu")
		(net "PVDDCR_CPU1_P1_RESET_N")
	)
	(segment
		(start 18.410174 -356.663244)
		(end 18.410174 -361.197398)
		(width 0.11684)
		(layer "In11.Cu")
		(net "PVDDCR_CPU1_P1_RESET_N")
	)
	(segment
		(start 30.861 -370.3066)
		(end 30.861 -367.87709)
		(width 0.1524)
		(layer "F.Cu")
		(net "PVDDCR_CPU1_P1_PWM6")
	)
	(segment
		(start 103.989378 -343.94394)
		(end 103.654098 -344.27922)
		(width 0.1778)
		(layer "F.Cu")
		(net "PVDDCR_CPU1_P1_PWM6")
	)
	(segment
		(start 103.989378 -342.839294)
		(end 103.989378 -343.94394)
		(width 0.1778)
		(layer "F.Cu")
		(net "PVDDCR_CPU1_P1_PWM6")
	)
	(segment
		(start 30.280102 -367.296192)
		(end 30.280102 -366.984026)
		(width 0.1524)
		(layer "F.Cu")
		(net "PVDDCR_CPU1_P1_PWM6")
	)
	(segment
		(start 30.861 -367.87709)
		(end 30.280102 -367.296192)
		(width 0.1524)
		(layer "F.Cu")
		(net "PVDDCR_CPU1_P1_PWM6")
	)
	(segment
		(start 30.2514 -370.9162)
		(end 30.861 -370.3066)
		(width 0.1524)
		(layer "F.Cu")
		(net "PVDDCR_CPU1_P1_PWM6")
	)
	(via
		(at 103.654098 -344.27922)
		(size 0.508)
		(drill 0.254)
		(layers "F.Cu" "B.Cu")
		(net "PVDDCR_CPU1_P1_PWM6")
	)
	(via
		(at 30.2514 -370.9162)
		(size 0.508)
		(drill 0.254)
		(layers "F.Cu" "B.Cu")
		(net "PVDDCR_CPU1_P1_PWM6")
	)
	(segment
		(start 97.141538 -343.198958)
		(end 99.72294 -345.78036)
		(width 0.1524)
		(layer "In4.Cu")
		(net "PVDDCR_CPU1_P1_PWM6")
	)
	(segment
		(start 99.72294 -345.78036)
		(end 101.81336 -345.78036)
		(width 0.1524)
		(layer "In4.Cu")
		(net "PVDDCR_CPU1_P1_PWM6")
	)
	(segment
		(start 103.3145 -344.27922)
		(end 103.654098 -344.27922)
		(width 0.1524)
		(layer "In4.Cu")
		(net "PVDDCR_CPU1_P1_PWM6")
	)
	(segment
		(start 81.0641 -343.198958)
		(end 97.141538 -343.198958)
		(width 0.1524)
		(layer "In4.Cu")
		(net "PVDDCR_CPU1_P1_PWM6")
	)
	(segment
		(start 33.409128 -371.74043)
		(end 40.320214 -371.74043)
		(width 0.1524)
		(layer "In4.Cu")
		(net "PVDDCR_CPU1_P1_PWM6")
	)
	(segment
		(start 41.52392 -369.23599)
		(end 44.999656 -365.760254)
		(width 0.1524)
		(layer "In4.Cu")
		(net "PVDDCR_CPU1_P1_PWM6")
	)
	(segment
		(start 101.81336 -345.78036)
		(end 103.3145 -344.27922)
		(width 0.1524)
		(layer "In4.Cu")
		(net "PVDDCR_CPU1_P1_PWM6")
	)
	(segment
		(start 30.2514 -370.9162)
		(end 32.584898 -370.9162)
		(width 0.1524)
		(layer "In4.Cu")
		(net "PVDDCR_CPU1_P1_PWM6")
	)
	(segment
		(start 40.320214 -371.74043)
		(end 41.52392 -370.536724)
		(width 0.1524)
		(layer "In4.Cu")
		(net "PVDDCR_CPU1_P1_PWM6")
	)
	(segment
		(start 58.502804 -365.760254)
		(end 81.0641 -343.198958)
		(width 0.1524)
		(layer "In4.Cu")
		(net "PVDDCR_CPU1_P1_PWM6")
	)
	(segment
		(start 32.584898 -370.9162)
		(end 33.409128 -371.74043)
		(width 0.1524)
		(layer "In4.Cu")
		(net "PVDDCR_CPU1_P1_PWM6")
	)
	(segment
		(start 44.999656 -365.760254)
		(end 58.502804 -365.760254)
		(width 0.1524)
		(layer "In4.Cu")
		(net "PVDDCR_CPU1_P1_PWM6")
	)
	(segment
		(start 41.52392 -370.536724)
		(end 41.52392 -369.23599)
		(width 0.1524)
		(layer "In4.Cu")
		(net "PVDDCR_CPU1_P1_PWM6")
	)
	(segment
		(start 30.3784 -367.899188)
		(end 29.880052 -367.40084)
		(width 0.1524)
		(layer "F.Cu")
		(net "PVDDCR_CPU1_P1_PWM5")
	)
	(segment
		(start 95.71355 -339.033866)
		(end 95.37827 -339.369146)
		(width 0.1778)
		(layer "F.Cu")
		(net "PVDDCR_CPU1_P1_PWM5")
	)
	(segment
		(start 95.71355 -337.92922)
		(end 95.71355 -339.033866)
		(width 0.1778)
		(layer "F.Cu")
		(net "PVDDCR_CPU1_P1_PWM5")
	)
	(segment
		(start 29.494988 -370.332)
		(end 30.139132 -369.687856)
		(width 0.1524)
		(layer "F.Cu")
		(net "PVDDCR_CPU1_P1_PWM5")
	)
	(segment
		(start 29.880052 -367.40084)
		(end 29.880052 -366.984026)
		(width 0.1524)
		(layer "F.Cu")
		(net "PVDDCR_CPU1_P1_PWM5")
	)
	(segment
		(start 30.3784 -369.448588)
		(end 30.3784 -367.899188)
		(width 0.1524)
		(layer "F.Cu")
		(net "PVDDCR_CPU1_P1_PWM5")
	)
	(segment
		(start 30.139132 -369.687856)
		(end 30.3784 -369.448588)
		(width 0.1524)
		(layer "F.Cu")
		(net "PVDDCR_CPU1_P1_PWM5")
	)
	(via
		(at 95.37827 -339.369146)
		(size 0.508)
		(drill 0.254)
		(layers "F.Cu" "B.Cu")
		(net "PVDDCR_CPU1_P1_PWM5")
	)
	(via
		(at 30.139132 -369.687856)
		(size 0.762)
		(drill 0.381)
		(layers "F.Cu" "B.Cu")
		(net "PVDDCR_CPU1_P1_PWM5")
	)
	(via
		(at 29.494988 -370.332)
		(size 0.508)
		(drill 0.254)
		(layers "F.Cu" "B.Cu")
		(net "PVDDCR_CPU1_P1_PWM5")
	)
	(segment
		(start 57.896506 -364.993936)
		(end 44.903644 -364.993936)
		(width 0.1524)
		(layer "In4.Cu")
		(net "PVDDCR_CPU1_P1_PWM5")
	)
	(segment
		(start 33.36925 -371.108478)
		(end 32.592772 -370.332)
		(width 0.1524)
		(layer "In4.Cu")
		(net "PVDDCR_CPU1_P1_PWM5")
	)
	(segment
		(start 92.413582 -341.893398)
		(end 80.997044 -341.893398)
		(width 0.1524)
		(layer "In4.Cu")
		(net "PVDDCR_CPU1_P1_PWM5")
	)
	(segment
		(start 32.592772 -370.332)
		(end 29.494988 -370.332)
		(width 0.1524)
		(layer "In4.Cu")
		(net "PVDDCR_CPU1_P1_PWM5")
	)
	(segment
		(start 40.972232 -368.925348)
		(end 40.972232 -370.132356)
		(width 0.1524)
		(layer "In4.Cu")
		(net "PVDDCR_CPU1_P1_PWM5")
	)
	(segment
		(start 80.997044 -341.893398)
		(end 57.896506 -364.993936)
		(width 0.1524)
		(layer "In4.Cu")
		(net "PVDDCR_CPU1_P1_PWM5")
	)
	(segment
		(start 95.37827 -339.369146)
		(end 94.937834 -339.369146)
		(width 0.1524)
		(layer "In4.Cu")
		(net "PVDDCR_CPU1_P1_PWM5")
	)
	(segment
		(start 94.937834 -339.369146)
		(end 92.413582 -341.893398)
		(width 0.1524)
		(layer "In4.Cu")
		(net "PVDDCR_CPU1_P1_PWM5")
	)
	(segment
		(start 44.903644 -364.993936)
		(end 40.972232 -368.925348)
		(width 0.1524)
		(layer "In4.Cu")
		(net "PVDDCR_CPU1_P1_PWM5")
	)
	(segment
		(start 39.99611 -371.108478)
		(end 33.36925 -371.108478)
		(width 0.1524)
		(layer "In4.Cu")
		(net "PVDDCR_CPU1_P1_PWM5")
	)
	(segment
		(start 40.972232 -370.132356)
		(end 39.99611 -371.108478)
		(width 0.1524)
		(layer "In4.Cu")
		(net "PVDDCR_CPU1_P1_PWM5")
	)
	(segment
		(start 29.480002 -367.833402)
		(end 29.6926 -368.046)
		(width 0.1524)
		(layer "F.Cu")
		(net "PVDDCR_CPU1_P1_PWM4")
	)
	(segment
		(start 61.79947 -351.06102)
		(end 62.13475 -350.72574)
		(width 0.1778)
		(layer "F.Cu")
		(net "PVDDCR_CPU1_P1_PWM4")
	)
	(segment
		(start 29.480002 -366.984026)
		(end 29.480002 -367.833402)
		(width 0.1524)
		(layer "F.Cu")
		(net "PVDDCR_CPU1_P1_PWM4")
	)
	(segment
		(start 62.13475 -350.72574)
		(end 62.13475 -349.621094)
		(width 0.1778)
		(layer "F.Cu")
		(net "PVDDCR_CPU1_P1_PWM4")
	)
	(via
		(at 61.79947 -351.06102)
		(size 0.508)
		(drill 0.254)
		(layers "F.Cu" "B.Cu")
		(net "PVDDCR_CPU1_P1_PWM4")
	)
	(via
		(at 29.6926 -368.046)
		(size 0.508)
		(drill 0.254)
		(layers "F.Cu" "B.Cu")
		(net "PVDDCR_CPU1_P1_PWM4")
	)
	(segment
		(start 39.569644 -354.8634)
		(end 42.940224 -354.8634)
		(width 0.1524)
		(layer "In4.Cu")
		(net "PVDDCR_CPU1_P1_PWM4")
	)
	(segment
		(start 30.343856 -361.14101)
		(end 32.526732 -361.14101)
		(width 0.1524)
		(layer "In4.Cu")
		(net "PVDDCR_CPU1_P1_PWM4")
	)
	(segment
		(start 44.286424 -353.5172)
		(end 58.989722 -353.5172)
		(width 0.1524)
		(layer "In4.Cu")
		(net "PVDDCR_CPU1_P1_PWM4")
	)
	(segment
		(start 29.338016 -367.691416)
		(end 29.338016 -362.14685)
		(width 0.1524)
		(layer "In4.Cu")
		(net "PVDDCR_CPU1_P1_PWM4")
	)
	(segment
		(start 37.71646 -356.716584)
		(end 39.569644 -354.8634)
		(width 0.1524)
		(layer "In4.Cu")
		(net "PVDDCR_CPU1_P1_PWM4")
	)
	(segment
		(start 61.44641 -351.41408)
		(end 61.79947 -351.06102)
		(width 0.1524)
		(layer "In4.Cu")
		(net "PVDDCR_CPU1_P1_PWM4")
	)
	(segment
		(start 32.526732 -361.14101)
		(end 36.951158 -356.716584)
		(width 0.1524)
		(layer "In4.Cu")
		(net "PVDDCR_CPU1_P1_PWM4")
	)
	(segment
		(start 58.989722 -353.5172)
		(end 61.092842 -351.41408)
		(width 0.1524)
		(layer "In4.Cu")
		(net "PVDDCR_CPU1_P1_PWM4")
	)
	(segment
		(start 61.092842 -351.41408)
		(end 61.44641 -351.41408)
		(width 0.1524)
		(layer "In4.Cu")
		(net "PVDDCR_CPU1_P1_PWM4")
	)
	(segment
		(start 29.338016 -362.14685)
		(end 30.343856 -361.14101)
		(width 0.1524)
		(layer "In4.Cu")
		(net "PVDDCR_CPU1_P1_PWM4")
	)
	(segment
		(start 29.6926 -368.046)
		(end 29.338016 -367.691416)
		(width 0.1524)
		(layer "In4.Cu")
		(net "PVDDCR_CPU1_P1_PWM4")
	)
	(segment
		(start 42.940224 -354.8634)
		(end 44.286424 -353.5172)
		(width 0.1524)
		(layer "In4.Cu")
		(net "PVDDCR_CPU1_P1_PWM4")
	)
	(segment
		(start 36.951158 -356.716584)
		(end 37.71646 -356.716584)
		(width 0.1524)
		(layer "In4.Cu")
		(net "PVDDCR_CPU1_P1_PWM4")
	)
	(segment
		(start 28.8544 -368.0714)
		(end 29.079952 -367.845848)
		(width 0.1524)
		(layer "F.Cu")
		(net "PVDDCR_CPU1_P1_PWM3")
	)
	(segment
		(start 70.66915 -339.004656)
		(end 70.33387 -339.339936)
		(width 0.1778)
		(layer "F.Cu")
		(net "PVDDCR_CPU1_P1_PWM3")
	)
	(segment
		(start 70.66915 -337.90001)
		(end 70.66915 -339.004656)
		(width 0.1778)
		(layer "F.Cu")
		(net "PVDDCR_CPU1_P1_PWM3")
	)
	(segment
		(start 29.079952 -367.845848)
		(end 29.079952 -366.984026)
		(width 0.1524)
		(layer "F.Cu")
		(net "PVDDCR_CPU1_P1_PWM3")
	)
	(via
		(at 70.33387 -339.339936)
		(size 0.508)
		(drill 0.254)
		(layers "F.Cu" "B.Cu")
		(net "PVDDCR_CPU1_P1_PWM3")
	)
	(via
		(at 28.8544 -368.0714)
		(size 0.508)
		(drill 0.254)
		(layers "F.Cu" "B.Cu")
		(net "PVDDCR_CPU1_P1_PWM3")
	)
	(segment
		(start 63.198502 -354.486718)
		(end 66.9417 -350.74352)
		(width 0.1524)
		(layer "In4.Cu")
		(net "PVDDCR_CPU1_P1_PWM3")
	)
	(segment
		(start 44.236386 -354.486718)
		(end 63.198502 -354.486718)
		(width 0.1524)
		(layer "In4.Cu")
		(net "PVDDCR_CPU1_P1_PWM3")
	)
	(segment
		(start 30.563566 -366.876584)
		(end 31.052516 -366.387634)
		(width 0.1524)
		(layer "In4.Cu")
		(net "PVDDCR_CPU1_P1_PWM3")
	)
	(segment
		(start 31.052516 -366.387634)
		(end 31.052516 -364.530386)
		(width 0.1524)
		(layer "In4.Cu")
		(net "PVDDCR_CPU1_P1_PWM3")
	)
	(segment
		(start 38.507416 -358.923844)
		(end 38.507416 -357.42245)
		(width 0.1524)
		(layer "In4.Cu")
		(net "PVDDCR_CPU1_P1_PWM3")
	)
	(segment
		(start 40.484552 -355.445314)
		(end 43.27779 -355.445314)
		(width 0.1524)
		(layer "In4.Cu")
		(net "PVDDCR_CPU1_P1_PWM3")
	)
	(segment
		(start 66.9417 -342.27516)
		(end 69.545962 -339.670898)
		(width 0.1524)
		(layer "In4.Cu")
		(net "PVDDCR_CPU1_P1_PWM3")
	)
	(segment
		(start 43.27779 -355.445314)
		(end 44.236386 -354.486718)
		(width 0.1524)
		(layer "In4.Cu")
		(net "PVDDCR_CPU1_P1_PWM3")
	)
	(segment
		(start 31.052516 -364.530386)
		(end 35.350958 -360.231944)
		(width 0.1524)
		(layer "In4.Cu")
		(net "PVDDCR_CPU1_P1_PWM3")
	)
	(segment
		(start 69.545962 -339.670898)
		(end 69.716142 -339.670898)
		(width 0.1524)
		(layer "In4.Cu")
		(net "PVDDCR_CPU1_P1_PWM3")
	)
	(segment
		(start 35.350958 -360.231944)
		(end 37.199316 -360.231944)
		(width 0.1524)
		(layer "In4.Cu")
		(net "PVDDCR_CPU1_P1_PWM3")
	)
	(segment
		(start 37.199316 -360.231944)
		(end 38.507416 -358.923844)
		(width 0.1524)
		(layer "In4.Cu")
		(net "PVDDCR_CPU1_P1_PWM3")
	)
	(segment
		(start 30.563566 -368.245644)
		(end 30.563566 -366.876584)
		(width 0.1524)
		(layer "In4.Cu")
		(net "PVDDCR_CPU1_P1_PWM3")
	)
	(segment
		(start 69.716142 -339.670898)
		(end 70.047104 -339.339936)
		(width 0.1524)
		(layer "In4.Cu")
		(net "PVDDCR_CPU1_P1_PWM3")
	)
	(segment
		(start 30.17901 -368.6302)
		(end 30.563566 -368.245644)
		(width 0.1524)
		(layer "In4.Cu")
		(net "PVDDCR_CPU1_P1_PWM3")
	)
	(segment
		(start 28.8544 -368.0714)
		(end 29.4132 -368.6302)
		(width 0.1524)
		(layer "In4.Cu")
		(net "PVDDCR_CPU1_P1_PWM3")
	)
	(segment
		(start 29.4132 -368.6302)
		(end 30.17901 -368.6302)
		(width 0.1524)
		(layer "In4.Cu")
		(net "PVDDCR_CPU1_P1_PWM3")
	)
	(segment
		(start 38.507416 -357.42245)
		(end 40.484552 -355.445314)
		(width 0.1524)
		(layer "In4.Cu")
		(net "PVDDCR_CPU1_P1_PWM3")
	)
	(segment
		(start 70.047104 -339.339936)
		(end 70.33387 -339.339936)
		(width 0.1524)
		(layer "In4.Cu")
		(net "PVDDCR_CPU1_P1_PWM3")
	)
	(segment
		(start 66.9417 -350.74352)
		(end 66.9417 -342.27516)
		(width 0.1524)
		(layer "In4.Cu")
		(net "PVDDCR_CPU1_P1_PWM3")
	)
	(segment
		(start 79.024734 -337.892898)
		(end 79.024734 -338.997544)
		(width 0.1778)
		(layer "F.Cu")
		(net "PVDDCR_CPU1_P1_PWM2")
	)
	(segment
		(start 79.024734 -338.997544)
		(end 78.689454 -339.332824)
		(width 0.1778)
		(layer "F.Cu")
		(net "PVDDCR_CPU1_P1_PWM2")
	)
	(segment
		(start 28.570174 -368.915696)
		(end 28.2702 -368.615722)
		(width 0.1524)
		(layer "F.Cu")
		(net "PVDDCR_CPU1_P1_PWM2")
	)
	(segment
		(start 28.2702 -367.792)
		(end 28.679902 -367.382298)
		(width 0.1524)
		(layer "F.Cu")
		(net "PVDDCR_CPU1_P1_PWM2")
	)
	(segment
		(start 28.2702 -368.615722)
		(end 28.2702 -367.792)
		(width 0.1524)
		(layer "F.Cu")
		(net "PVDDCR_CPU1_P1_PWM2")
	)
	(segment
		(start 28.679902 -367.382298)
		(end 28.679902 -366.984026)
		(width 0.1524)
		(layer "F.Cu")
		(net "PVDDCR_CPU1_P1_PWM2")
	)
	(via
		(at 78.689454 -339.332824)
		(size 0.508)
		(drill 0.254)
		(layers "F.Cu" "B.Cu")
		(net "PVDDCR_CPU1_P1_PWM2")
	)
	(via
		(at 28.570174 -368.915696)
		(size 0.508)
		(drill 0.254)
		(layers "F.Cu" "B.Cu")
		(net "PVDDCR_CPU1_P1_PWM2")
	)
	(segment
		(start 39.484808 -357.55453)
		(end 39.484808 -359.340404)
		(width 0.1524)
		(layer "In4.Cu")
		(net "PVDDCR_CPU1_P1_PWM2")
	)
	(segment
		(start 35.781234 -361.189524)
		(end 33.273746 -363.697012)
		(width 0.1524)
		(layer "In4.Cu")
		(net "PVDDCR_CPU1_P1_PWM2")
	)
	(segment
		(start 40.927528 -356.11181)
		(end 39.484808 -357.55453)
		(width 0.1524)
		(layer "In4.Cu")
		(net "PVDDCR_CPU1_P1_PWM2")
	)
	(segment
		(start 44.791376 -355.463602)
		(end 44.143168 -356.11181)
		(width 0.1524)
		(layer "In4.Cu")
		(net "PVDDCR_CPU1_P1_PWM2")
	)
	(segment
		(start 33.273746 -363.697012)
		(end 33.273746 -366.005364)
		(width 0.1524)
		(layer "In4.Cu")
		(net "PVDDCR_CPU1_P1_PWM2")
	)
	(segment
		(start 64.337438 -355.463602)
		(end 44.791376 -355.463602)
		(width 0.1524)
		(layer "In4.Cu")
		(net "PVDDCR_CPU1_P1_PWM2")
	)
	(segment
		(start 78.316836 -339.332824)
		(end 76.589382 -341.060278)
		(width 0.1524)
		(layer "In4.Cu")
		(net "PVDDCR_CPU1_P1_PWM2")
	)
	(segment
		(start 32.105346 -369.198398)
		(end 29.280358 -369.198398)
		(width 0.1524)
		(layer "In4.Cu")
		(net "PVDDCR_CPU1_P1_PWM2")
	)
	(segment
		(start 32.105346 -367.173764)
		(end 32.105346 -369.198398)
		(width 0.1524)
		(layer "In4.Cu")
		(net "PVDDCR_CPU1_P1_PWM2")
	)
	(segment
		(start 29.280358 -369.198398)
		(end 28.997656 -368.915696)
		(width 0.1524)
		(layer "In4.Cu")
		(net "PVDDCR_CPU1_P1_PWM2")
	)
	(segment
		(start 76.589382 -343.211658)
		(end 64.337438 -355.463602)
		(width 0.1524)
		(layer "In4.Cu")
		(net "PVDDCR_CPU1_P1_PWM2")
	)
	(segment
		(start 37.635688 -361.189524)
		(end 35.781234 -361.189524)
		(width 0.1524)
		(layer "In4.Cu")
		(net "PVDDCR_CPU1_P1_PWM2")
	)
	(segment
		(start 76.589382 -341.060278)
		(end 76.589382 -343.211658)
		(width 0.1524)
		(layer "In4.Cu")
		(net "PVDDCR_CPU1_P1_PWM2")
	)
	(segment
		(start 33.273746 -366.005364)
		(end 32.105346 -367.173764)
		(width 0.1524)
		(layer "In4.Cu")
		(net "PVDDCR_CPU1_P1_PWM2")
	)
	(segment
		(start 28.997656 -368.915696)
		(end 28.570174 -368.915696)
		(width 0.1524)
		(layer "In4.Cu")
		(net "PVDDCR_CPU1_P1_PWM2")
	)
	(segment
		(start 39.484808 -359.340404)
		(end 37.635688 -361.189524)
		(width 0.1524)
		(layer "In4.Cu")
		(net "PVDDCR_CPU1_P1_PWM2")
	)
	(segment
		(start 78.689454 -339.332824)
		(end 78.316836 -339.332824)
		(width 0.1524)
		(layer "In4.Cu")
		(net "PVDDCR_CPU1_P1_PWM2")
	)
	(segment
		(start 44.143168 -356.11181)
		(end 40.927528 -356.11181)
		(width 0.1524)
		(layer "In4.Cu")
		(net "PVDDCR_CPU1_P1_PWM2")
	)
	(segment
		(start 87.38235 -337.87842)
		(end 87.38235 -338.983066)
		(width 0.1778)
		(layer "F.Cu")
		(net "PVDDCR_CPU1_P1_PWM1")
	)
	(segment
		(start 27.9146 -367.6142)
		(end 28.280106 -367.248694)
		(width 0.1524)
		(layer "F.Cu")
		(net "PVDDCR_CPU1_P1_PWM1")
	)
	(segment
		(start 28.829 -369.7224)
		(end 28.527248 -369.7224)
		(width 0.1524)
		(layer "F.Cu")
		(net "PVDDCR_CPU1_P1_PWM1")
	)
	(segment
		(start 87.38235 -338.983066)
		(end 87.04707 -339.318346)
		(width 0.1778)
		(layer "F.Cu")
		(net "PVDDCR_CPU1_P1_PWM1")
	)
	(segment
		(start 28.527248 -369.7224)
		(end 27.9146 -369.109752)
		(width 0.1524)
		(layer "F.Cu")
		(net "PVDDCR_CPU1_P1_PWM1")
	)
	(segment
		(start 28.280106 -367.248694)
		(end 28.280106 -366.984026)
		(width 0.1524)
		(layer "F.Cu")
		(net "PVDDCR_CPU1_P1_PWM1")
	)
	(segment
		(start 27.9146 -369.109752)
		(end 27.9146 -367.6142)
		(width 0.1524)
		(layer "F.Cu")
		(net "PVDDCR_CPU1_P1_PWM1")
	)
	(via
		(at 28.829 -369.7224)
		(size 0.508)
		(drill 0.254)
		(layers "F.Cu" "B.Cu")
		(net "PVDDCR_CPU1_P1_PWM1")
	)
	(via
		(at 87.04707 -339.318346)
		(size 0.508)
		(drill 0.254)
		(layers "F.Cu" "B.Cu")
		(net "PVDDCR_CPU1_P1_PWM1")
	)
	(segment
		(start 80.262984 -341.04834)
		(end 84.89696 -341.04834)
		(width 0.1524)
		(layer "In4.Cu")
		(net "PVDDCR_CPU1_P1_PWM1")
	)
	(segment
		(start 84.89696 -341.04834)
		(end 86.626954 -339.318346)
		(width 0.1524)
		(layer "In4.Cu")
		(net "PVDDCR_CPU1_P1_PWM1")
	)
	(segment
		(start 86.626954 -339.318346)
		(end 87.04707 -339.318346)
		(width 0.1524)
		(layer "In4.Cu")
		(net "PVDDCR_CPU1_P1_PWM1")
	)
	(segment
		(start 28.829 -369.7224)
		(end 32.691578 -369.7224)
		(width 0.1524)
		(layer "In4.Cu")
		(net "PVDDCR_CPU1_P1_PWM1")
	)
	(segment
		(start 40.455596 -369.786916)
		(end 40.455596 -368.56162)
		(width 0.1524)
		(layer "In4.Cu")
		(net "PVDDCR_CPU1_P1_PWM1")
	)
	(segment
		(start 44.859448 -364.157768)
		(end 57.153556 -364.157768)
		(width 0.1524)
		(layer "In4.Cu")
		(net "PVDDCR_CPU1_P1_PWM1")
	)
	(segment
		(start 32.691578 -369.7224)
		(end 33.465008 -370.49583)
		(width 0.1524)
		(layer "In4.Cu")
		(net "PVDDCR_CPU1_P1_PWM1")
	)
	(segment
		(start 39.746682 -370.49583)
		(end 40.455596 -369.786916)
		(width 0.1524)
		(layer "In4.Cu")
		(net "PVDDCR_CPU1_P1_PWM1")
	)
	(segment
		(start 33.465008 -370.49583)
		(end 39.746682 -370.49583)
		(width 0.1524)
		(layer "In4.Cu")
		(net "PVDDCR_CPU1_P1_PWM1")
	)
	(segment
		(start 57.153556 -364.157768)
		(end 80.262984 -341.04834)
		(width 0.1524)
		(layer "In4.Cu")
		(net "PVDDCR_CPU1_P1_PWM1")
	)
	(segment
		(start 40.455596 -368.56162)
		(end 44.859448 -364.157768)
		(width 0.1524)
		(layer "In4.Cu")
		(net "PVDDCR_CPU1_P1_PWM1")
	)
	(segment
		(start 76.364592 -335.918048)
		(end 75.828906 -335.918048)
		(width 0.2286)
		(layer "F.Cu")
		(net "PVDDCR_CPU1_P1_PVCC")
	)
	(segment
		(start 67.473322 -335.92516)
		(end 68.009008 -335.92516)
		(width 0.2286)
		(layer "F.Cu")
		(net "PVDDCR_CPU1_P1_PVCC")
	)
	(segment
		(start 83.659726 -335.376774)
		(end 83.439254 -335.376774)
		(width 0.2286)
		(layer "F.Cu")
		(net "PVDDCR_CPU1_P1_PVCC")
	)
	(segment
		(start 58.938922 -347.646244)
		(end 59.474608 -347.646244)
		(width 0.2286)
		(layer "F.Cu")
		(net "PVDDCR_CPU1_P1_PVCC")
	)
	(segment
		(start 91.770454 -335.427574)
		(end 91.770454 -336.038698)
		(width 0.4572)
		(layer "F.Cu")
		(net "PVDDCR_CPU1_P1_PVCC")
	)
	(segment
		(start 33.198054 -347.119448)
		(end 33.198054 -347.730572)
		(width 0.4572)
		(layer "F.Cu")
		(net "PVDDCR_CPU1_P1_PVCC")
	)
	(segment
		(start 49.860454 -347.730572)
		(end 49.860454 -347.119448)
		(width 0.4572)
		(layer "F.Cu")
		(net "PVDDCR_CPU1_P1_PVCC")
	)
	(segment
		(start 58.412126 -347.119448)
		(end 58.938922 -347.646244)
		(width 0.2286)
		(layer "F.Cu")
		(net "PVDDCR_CPU1_P1_PVCC")
	)
	(segment
		(start 33.418526 -347.119448)
		(end 33.198054 -347.119448)
		(width 0.2286)
		(layer "F.Cu")
		(net "PVDDCR_CPU1_P1_PVCC")
	)
	(segment
		(start 101.329236 -340.864444)
		(end 100.79355 -340.864444)
		(width 0.2286)
		(layer "F.Cu")
		(net "PVDDCR_CPU1_P1_PVCC")
	)
	(segment
		(start 33.945322 -347.646244)
		(end 33.418526 -347.119448)
		(width 0.2286)
		(layer "F.Cu")
		(net "PVDDCR_CPU1_P1_PVCC")
	)
	(segment
		(start 58.191654 -347.730572)
		(end 58.191654 -347.119448)
		(width 0.4572)
		(layer "F.Cu")
		(net "PVDDCR_CPU1_P1_PVCC")
	)
	(segment
		(start 50.607722 -347.646244)
		(end 51.143408 -347.646244)
		(width 0.2286)
		(layer "F.Cu")
		(net "PVDDCR_CPU1_P1_PVCC")
	)
	(segment
		(start 41.503854 -347.119448)
		(end 41.724326 -347.119448)
		(width 0.2286)
		(layer "F.Cu")
		(net "PVDDCR_CPU1_P1_PVCC")
	)
	(segment
		(start 84.722208 -335.90357)
		(end 84.186522 -335.90357)
		(width 0.2286)
		(layer "F.Cu")
		(net "PVDDCR_CPU1_P1_PVCC")
	)
	(segment
		(start 58.191654 -347.119448)
		(end 58.412126 -347.119448)
		(width 0.2286)
		(layer "F.Cu")
		(net "PVDDCR_CPU1_P1_PVCC")
	)
	(segment
		(start 100.266754 -340.337648)
		(end 100.046282 -340.337648)
		(width 0.2286)
		(layer "F.Cu")
		(net "PVDDCR_CPU1_P1_PVCC")
	)
	(segment
		(start 83.439254 -335.376774)
		(end 83.439254 -335.987898)
		(width 0.4572)
		(layer "F.Cu")
		(net "PVDDCR_CPU1_P1_PVCC")
	)
	(segment
		(start 49.860454 -347.119448)
		(end 50.080926 -347.119448)
		(width 0.2286)
		(layer "F.Cu")
		(net "PVDDCR_CPU1_P1_PVCC")
	)
	(segment
		(start 75.081638 -335.391252)
		(end 75.081638 -336.002376)
		(width 0.4572)
		(layer "F.Cu")
		(net "PVDDCR_CPU1_P1_PVCC")
	)
	(segment
		(start 42.251122 -347.646244)
		(end 42.786808 -347.646244)
		(width 0.2286)
		(layer "F.Cu")
		(net "PVDDCR_CPU1_P1_PVCC")
	)
	(segment
		(start 25.315926 -347.119448)
		(end 24.917654 -347.119448)
		(width 0.2286)
		(layer "F.Cu")
		(net "PVDDCR_CPU1_P1_PVCC")
	)
	(segment
		(start 41.724326 -347.119448)
		(end 42.251122 -347.646244)
		(width 0.2286)
		(layer "F.Cu")
		(net "PVDDCR_CPU1_P1_PVCC")
	)
	(segment
		(start 66.726054 -336.009488)
		(end 66.726054 -335.398364)
		(width 0.4572)
		(layer "F.Cu")
		(net "PVDDCR_CPU1_P1_PVCC")
	)
	(segment
		(start 66.946526 -335.398364)
		(end 67.473322 -335.92516)
		(width 0.2286)
		(layer "F.Cu")
		(net "PVDDCR_CPU1_P1_PVCC")
	)
	(segment
		(start 100.79355 -340.864444)
		(end 100.266754 -340.337648)
		(width 0.2286)
		(layer "F.Cu")
		(net "PVDDCR_CPU1_P1_PVCC")
	)
	(segment
		(start 100.046282 -340.337648)
		(end 100.046282 -340.948772)
		(width 0.4572)
		(layer "F.Cu")
		(net "PVDDCR_CPU1_P1_PVCC")
	)
	(segment
		(start 92.517722 -335.95437)
		(end 91.990926 -335.427574)
		(width 0.2286)
		(layer "F.Cu")
		(net "PVDDCR_CPU1_P1_PVCC")
	)
	(segment
		(start 34.481008 -347.646244)
		(end 33.945322 -347.646244)
		(width 0.2286)
		(layer "F.Cu")
		(net "PVDDCR_CPU1_P1_PVCC")
	)
	(segment
		(start 66.726054 -335.398364)
		(end 66.946526 -335.398364)
		(width 0.2286)
		(layer "F.Cu")
		(net "PVDDCR_CPU1_P1_PVCC")
	)
	(segment
		(start 50.080926 -347.119448)
		(end 50.607722 -347.646244)
		(width 0.2286)
		(layer "F.Cu")
		(net "PVDDCR_CPU1_P1_PVCC")
	)
	(segment
		(start 26.200608 -347.646244)
		(end 25.842722 -347.646244)
		(width 0.2286)
		(layer "F.Cu")
		(net "PVDDCR_CPU1_P1_PVCC")
	)
	(segment
		(start 41.503854 -347.730572)
		(end 41.503854 -347.119448)
		(width 0.4572)
		(layer "F.Cu")
		(net "PVDDCR_CPU1_P1_PVCC")
	)
	(segment
		(start 93.053408 -335.95437)
		(end 92.517722 -335.95437)
		(width 0.2286)
		(layer "F.Cu")
		(net "PVDDCR_CPU1_P1_PVCC")
	)
	(segment
		(start 91.990926 -335.427574)
		(end 91.770454 -335.427574)
		(width 0.2286)
		(layer "F.Cu")
		(net "PVDDCR_CPU1_P1_PVCC")
	)
	(segment
		(start 25.842722 -347.646244)
		(end 25.315926 -347.119448)
		(width 0.2286)
		(layer "F.Cu")
		(net "PVDDCR_CPU1_P1_PVCC")
	)
	(segment
		(start 75.30211 -335.391252)
		(end 75.081638 -335.391252)
		(width 0.2286)
		(layer "F.Cu")
		(net "PVDDCR_CPU1_P1_PVCC")
	)
	(segment
		(start 84.186522 -335.90357)
		(end 83.659726 -335.376774)
		(width 0.2286)
		(layer "F.Cu")
		(net "PVDDCR_CPU1_P1_PVCC")
	)
	(segment
		(start 75.828906 -335.918048)
		(end 75.30211 -335.391252)
		(width 0.2286)
		(layer "F.Cu")
		(net "PVDDCR_CPU1_P1_PVCC")
	)
	(via
		(at 33.198054 -347.730572)
		(size 0.508)
		(drill 0.254)
		(layers "F.Cu" "B.Cu")
		(net "PVDDCR_CPU1_P1_PVCC")
	)
	(via
		(at 91.770454 -336.038698)
		(size 0.508)
		(drill 0.254)
		(layers "F.Cu" "B.Cu")
		(net "PVDDCR_CPU1_P1_PVCC")
	)
	(via
		(at 24.917654 -347.730572)
		(size 0.508)
		(drill 0.254)
		(layers "F.Cu" "B.Cu")
		(net "PVDDCR_CPU1_P1_PVCC")
	)
	(via
		(at 100.046282 -340.948772)
		(size 0.508)
		(drill 0.254)
		(layers "F.Cu" "B.Cu")
		(net "PVDDCR_CPU1_P1_PVCC")
	)
	(via
		(at 66.726054 -336.009488)
		(size 0.508)
		(drill 0.254)
		(layers "F.Cu" "B.Cu")
		(net "PVDDCR_CPU1_P1_PVCC")
	)
	(via
		(at 75.081638 -336.002376)
		(size 0.508)
		(drill 0.254)
		(layers "F.Cu" "B.Cu")
		(net "PVDDCR_CPU1_P1_PVCC")
	)
	(via
		(at 49.860454 -347.730572)
		(size 0.508)
		(drill 0.254)
		(layers "F.Cu" "B.Cu")
		(net "PVDDCR_CPU1_P1_PVCC")
	)
	(via
		(at 41.503854 -347.730572)
		(size 0.508)
		(drill 0.254)
		(layers "F.Cu" "B.Cu")
		(net "PVDDCR_CPU1_P1_PVCC")
	)
	(via
		(at 23.671022 -349.950278)
		(size 0.762)
		(drill 0.381)
		(layers "F.Cu" "B.Cu")
		(net "PVDDCR_CPU1_P1_PVCC")
	)
	(via
		(at 83.439254 -335.987898)
		(size 0.508)
		(drill 0.254)
		(layers "F.Cu" "B.Cu")
		(net "PVDDCR_CPU1_P1_PVCC")
	)
	(via
		(at 58.191654 -347.730572)
		(size 0.508)
		(drill 0.254)
		(layers "F.Cu" "B.Cu")
		(net "PVDDCR_CPU1_P1_PVCC")
	)
	(segment
		(start 25.26792 -347.380306)
		(end 24.917654 -347.730572)
		(width 0.381)
		(layer "B.Cu")
		(net "PVDDCR_CPU1_P1_PVCC")
	)
	(segment
		(start 75.092052 -335.991962)
		(end 75.081638 -336.002376)
		(width 0.254)
		(layer "B.Cu")
		(net "PVDDCR_CPU1_P1_PVCC")
	)
	(segment
		(start 26.289762 -347.380306)
		(end 25.26792 -347.380306)
		(width 0.381)
		(layer "B.Cu")
		(net "PVDDCR_CPU1_P1_PVCC")
	)
	(segment
		(start 92.398342 -336.028284)
		(end 91.780868 -336.028284)
		(width 0.254)
		(layer "B.Cu")
		(net "PVDDCR_CPU1_P1_PVCC")
	)
	(segment
		(start 50.23231 -347.380306)
		(end 49.882044 -347.730572)
		(width 0.381)
		(layer "B.Cu")
		(net "PVDDCR_CPU1_P1_PVCC")
	)
	(segment
		(start 42.875962 -347.380306)
		(end 41.85412 -347.380306)
		(width 0.381)
		(layer "B.Cu")
		(net "PVDDCR_CPU1_P1_PVCC")
	)
	(segment
		(start 100.67417 -340.938358)
		(end 100.056696 -340.938358)
		(width 0.254)
		(layer "B.Cu")
		(net "PVDDCR_CPU1_P1_PVCC")
	)
	(segment
		(start 101.014022 -340.598506)
		(end 100.67417 -340.938358)
		(width 0.254)
		(layer "B.Cu")
		(net "PVDDCR_CPU1_P1_PVCC")
	)
	(segment
		(start 58.54192 -347.380306)
		(end 58.191654 -347.730572)
		(width 0.381)
		(layer "B.Cu")
		(net "PVDDCR_CPU1_P1_PVCC")
	)
	(segment
		(start 100.056696 -340.938358)
		(end 100.046282 -340.948772)
		(width 0.254)
		(layer "B.Cu")
		(net "PVDDCR_CPU1_P1_PVCC")
	)
	(segment
		(start 84.067142 -335.977484)
		(end 83.449668 -335.977484)
		(width 0.254)
		(layer "B.Cu")
		(net "PVDDCR_CPU1_P1_PVCC")
	)
	(segment
		(start 76.049378 -335.65211)
		(end 75.709526 -335.991962)
		(width 0.254)
		(layer "B.Cu")
		(net "PVDDCR_CPU1_P1_PVCC")
	)
	(segment
		(start 66.736468 -335.999074)
		(end 66.726054 -336.009488)
		(width 0.254)
		(layer "B.Cu")
		(net "PVDDCR_CPU1_P1_PVCC")
	)
	(segment
		(start 101.41839 -340.598506)
		(end 101.014022 -340.598506)
		(width 0.254)
		(layer "B.Cu")
		(net "PVDDCR_CPU1_P1_PVCC")
	)
	(segment
		(start 67.693794 -335.659222)
		(end 67.353942 -335.999074)
		(width 0.254)
		(layer "B.Cu")
		(net "PVDDCR_CPU1_P1_PVCC")
	)
	(segment
		(start 75.709526 -335.991962)
		(end 75.092052 -335.991962)
		(width 0.254)
		(layer "B.Cu")
		(net "PVDDCR_CPU1_P1_PVCC")
	)
	(segment
		(start 84.811362 -335.637632)
		(end 84.406994 -335.637632)
		(width 0.254)
		(layer "B.Cu")
		(net "PVDDCR_CPU1_P1_PVCC")
	)
	(segment
		(start 84.406994 -335.637632)
		(end 84.067142 -335.977484)
		(width 0.254)
		(layer "B.Cu")
		(net "PVDDCR_CPU1_P1_PVCC")
	)
	(segment
		(start 34.570162 -347.380306)
		(end 33.54832 -347.380306)
		(width 0.381)
		(layer "B.Cu")
		(net "PVDDCR_CPU1_P1_PVCC")
	)
	(segment
		(start 76.453746 -335.65211)
		(end 76.049378 -335.65211)
		(width 0.254)
		(layer "B.Cu")
		(net "PVDDCR_CPU1_P1_PVCC")
	)
	(segment
		(start 93.142562 -335.688432)
		(end 92.738194 -335.688432)
		(width 0.254)
		(layer "B.Cu")
		(net "PVDDCR_CPU1_P1_PVCC")
	)
	(segment
		(start 83.449668 -335.977484)
		(end 83.439254 -335.987898)
		(width 0.254)
		(layer "B.Cu")
		(net "PVDDCR_CPU1_P1_PVCC")
	)
	(segment
		(start 91.780868 -336.028284)
		(end 91.770454 -336.038698)
		(width 0.254)
		(layer "B.Cu")
		(net "PVDDCR_CPU1_P1_PVCC")
	)
	(segment
		(start 33.54832 -347.380306)
		(end 33.198054 -347.730572)
		(width 0.381)
		(layer "B.Cu")
		(net "PVDDCR_CPU1_P1_PVCC")
	)
	(segment
		(start 49.882044 -347.730572)
		(end 49.860454 -347.730572)
		(width 0.381)
		(layer "B.Cu")
		(net "PVDDCR_CPU1_P1_PVCC")
	)
	(segment
		(start 67.353942 -335.999074)
		(end 66.736468 -335.999074)
		(width 0.254)
		(layer "B.Cu")
		(net "PVDDCR_CPU1_P1_PVCC")
	)
	(segment
		(start 51.232562 -347.380306)
		(end 50.23231 -347.380306)
		(width 0.381)
		(layer "B.Cu")
		(net "PVDDCR_CPU1_P1_PVCC")
	)
	(segment
		(start 68.098162 -335.659222)
		(end 67.693794 -335.659222)
		(width 0.254)
		(layer "B.Cu")
		(net "PVDDCR_CPU1_P1_PVCC")
	)
	(segment
		(start 59.563762 -347.380306)
		(end 58.54192 -347.380306)
		(width 0.381)
		(layer "B.Cu")
		(net "PVDDCR_CPU1_P1_PVCC")
	)
	(segment
		(start 92.738194 -335.688432)
		(end 92.398342 -336.028284)
		(width 0.254)
		(layer "B.Cu")
		(net "PVDDCR_CPU1_P1_PVCC")
	)
	(segment
		(start 41.85412 -347.380306)
		(end 41.503854 -347.730572)
		(width 0.381)
		(layer "B.Cu")
		(net "PVDDCR_CPU1_P1_PVCC")
	)
	(segment
		(start 74.945494 -333.059278)
		(end 75.710542 -332.29423)
		(width 0.508)
		(layer "In6.Cu")
		(net "PVDDCR_CPU1_P1_PVCC")
	)
	(segment
		(start 57.937654 -344.593418)
		(end 58.824622 -343.70645)
		(width 0.508)
		(layer "In6.Cu")
		(net "PVDDCR_CPU1_P1_PVCC")
	)
	(segment
		(start 91.516454 -335.784698)
		(end 91.516454 -333.521558)
		(width 0.508)
		(layer "In6.Cu")
		(net "PVDDCR_CPU1_P1_PVCC")
	)
	(segment
		(start 49.855882 -347.730572)
		(end 49.672494 -347.547184)
		(width 0.508)
		(layer "In6.Cu")
		(net "PVDDCR_CPU1_P1_PVCC")
	)
	(segment
		(start 42.164762 -342.279478)
		(end 41.71442 -341.829136)
		(width 0.508)
		(layer "In6.Cu")
		(net "PVDDCR_CPU1_P1_PVCC")
	)
	(segment
		(start 75.710542 -330.862178)
		(end 76.300584 -330.272136)
		(width 0.508)
		(layer "In6.Cu")
		(net "PVDDCR_CPU1_P1_PVCC")
	)
	(segment
		(start 83.073494 -335.622138)
		(end 83.439254 -335.987898)
		(width 0.508)
		(layer "In6.Cu")
		(net "PVDDCR_CPU1_P1_PVCC")
	)
	(segment
		(start 75.710542 -332.29423)
		(end 75.710542 -330.862178)
		(width 0.508)
		(layer "In6.Cu")
		(net "PVDDCR_CPU1_P1_PVCC")
	)
	(segment
		(start 100.046282 -340.948772)
		(end 100.046282 -339.429598)
		(width 0.508)
		(layer "In6.Cu")
		(net "PVDDCR_CPU1_P1_PVCC")
	)
	(segment
		(start 91.516454 -333.521558)
		(end 92.428822 -332.60919)
		(width 0.508)
		(layer "In6.Cu")
		(net "PVDDCR_CPU1_P1_PVCC")
	)
	(segment
		(start 101.012752 -335.786222)
		(end 101.012752 -334.684878)
		(width 0.508)
		(layer "In6.Cu")
		(net "PVDDCR_CPU1_P1_PVCC")
	)
	(segment
		(start 67.376802 -331.94117)
		(end 67.376802 -331.080364)
		(width 0.508)
		(layer "In6.Cu")
		(net "PVDDCR_CPU1_P1_PVCC")
	)
	(segment
		(start 92.428822 -330.857098)
		(end 91.71686 -330.145136)
		(width 0.508)
		(layer "In6.Cu")
		(net "PVDDCR_CPU1_P1_PVCC")
	)
	(segment
		(start 49.672494 -347.547184)
		(end 49.672494 -344.553286)
		(width 0.508)
		(layer "In6.Cu")
		(net "PVDDCR_CPU1_P1_PVCC")
	)
	(segment
		(start 84.067142 -331.71257)
		(end 83.073494 -332.706218)
		(width 0.508)
		(layer "In6.Cu")
		(net "PVDDCR_CPU1_P1_PVCC")
	)
	(segment
		(start 64.785494 -337.257136)
		(end 66.033142 -336.009488)
		(width 0.508)
		(layer "In6.Cu")
		(net "PVDDCR_CPU1_P1_PVCC")
	)
	(segment
		(start 93.140784 -330.145136)
		(end 92.428822 -330.857098)
		(width 0.508)
		(layer "In6.Cu")
		(net "PVDDCR_CPU1_P1_PVCC")
	)
	(segment
		(start 74.945494 -335.866232)
		(end 74.945494 -333.059278)
		(width 0.508)
		(layer "In6.Cu")
		(net "PVDDCR_CPU1_P1_PVCC")
	)
	(segment
		(start 41.232582 -347.4593)
		(end 41.232582 -345.081098)
		(width 0.508)
		(layer "In6.Cu")
		(net "PVDDCR_CPU1_P1_PVCC")
	)
	(segment
		(start 32.944054 -347.476572)
		(end 33.198054 -347.730572)
		(width 0.508)
		(layer "In6.Cu")
		(net "PVDDCR_CPU1_P1_PVCC")
	)
	(segment
		(start 100.726494 -330.145136)
		(end 93.140784 -330.145136)
		(width 0.508)
		(layer "In6.Cu")
		(net "PVDDCR_CPU1_P1_PVCC")
	)
	(segment
		(start 100.046282 -339.429598)
		(end 99.949 -339.194902)
		(width 0.508)
		(layer "In6.Cu")
		(net "PVDDCR_CPU1_P1_PVCC")
	)
	(segment
		(start 66.309494 -333.008478)
		(end 67.376802 -331.94117)
		(width 0.508)
		(layer "In6.Cu")
		(net "PVDDCR_CPU1_P1_PVCC")
	)
	(segment
		(start 50.521362 -342.332818)
		(end 51.152044 -341.702136)
		(width 0.508)
		(layer "In6.Cu")
		(net "PVDDCR_CPU1_P1_PVCC")
	)
	(segment
		(start 101.012752 -334.684878)
		(end 101.234494 -334.463136)
		(width 0.508)
		(layer "In6.Cu")
		(net "PVDDCR_CPU1_P1_PVCC")
	)
	(segment
		(start 66.726054 -335.235296)
		(end 66.309494 -334.818736)
		(width 0.508)
		(layer "In6.Cu")
		(net "PVDDCR_CPU1_P1_PVCC")
	)
	(segment
		(start 83.52028 -330.272136)
		(end 84.067142 -330.818998)
		(width 0.508)
		(layer "In6.Cu")
		(net "PVDDCR_CPU1_P1_PVCC")
	)
	(segment
		(start 42.742104 -341.702136)
		(end 49.89068 -341.702136)
		(width 0.508)
		(layer "In6.Cu")
		(net "PVDDCR_CPU1_P1_PVCC")
	)
	(segment
		(start 75.081638 -336.002376)
		(end 74.945494 -335.866232)
		(width 0.508)
		(layer "In6.Cu")
		(net "PVDDCR_CPU1_P1_PVCC")
	)
	(segment
		(start 41.71442 -341.829136)
		(end 34.438844 -341.829136)
		(width 0.508)
		(layer "In6.Cu")
		(net "PVDDCR_CPU1_P1_PVCC")
	)
	(segment
		(start 49.672494 -344.553286)
		(end 50.521362 -343.704418)
		(width 0.508)
		(layer "In6.Cu")
		(net "PVDDCR_CPU1_P1_PVCC")
	)
	(segment
		(start 58.3819 -341.702136)
		(end 58.824622 -342.144858)
		(width 0.508)
		(layer "In6.Cu")
		(net "PVDDCR_CPU1_P1_PVCC")
	)
	(segment
		(start 33.820862 -342.447118)
		(end 33.820862 -343.623138)
		(width 0.508)
		(layer "In6.Cu")
		(net "PVDDCR_CPU1_P1_PVCC")
	)
	(segment
		(start 57.937654 -347.476572)
		(end 57.937654 -344.593418)
		(width 0.508)
		(layer "In6.Cu")
		(net "PVDDCR_CPU1_P1_PVCC")
	)
	(segment
		(start 42.164762 -342.279478)
		(end 42.742104 -341.702136)
		(width 0.508)
		(layer "In6.Cu")
		(net "PVDDCR_CPU1_P1_PVCC")
	)
	(segment
		(start 33.820862 -343.623138)
		(end 32.944054 -344.499946)
		(width 0.508)
		(layer "In6.Cu")
		(net "PVDDCR_CPU1_P1_PVCC")
	)
	(segment
		(start 66.033142 -336.009488)
		(end 66.726054 -336.009488)
		(width 0.508)
		(layer "In6.Cu")
		(net "PVDDCR_CPU1_P1_PVCC")
	)
	(segment
		(start 76.300584 -330.272136)
		(end 83.52028 -330.272136)
		(width 0.508)
		(layer "In6.Cu")
		(net "PVDDCR_CPU1_P1_PVCC")
	)
	(segment
		(start 92.428822 -332.60919)
		(end 92.428822 -330.857098)
		(width 0.508)
		(layer "In6.Cu")
		(net "PVDDCR_CPU1_P1_PVCC")
	)
	(segment
		(start 84.741004 -330.145136)
		(end 84.067142 -330.818998)
		(width 0.508)
		(layer "In6.Cu")
		(net "PVDDCR_CPU1_P1_PVCC")
	)
	(segment
		(start 64.785494 -341.067136)
		(end 64.785494 -337.257136)
		(width 0.508)
		(layer "In6.Cu")
		(net "PVDDCR_CPU1_P1_PVCC")
	)
	(segment
		(start 34.438844 -341.829136)
		(end 33.820862 -342.447118)
		(width 0.508)
		(layer "In6.Cu")
		(net "PVDDCR_CPU1_P1_PVCC")
	)
	(segment
		(start 58.824622 -342.144858)
		(end 59.267344 -341.702136)
		(width 0.508)
		(layer "In6.Cu")
		(net "PVDDCR_CPU1_P1_PVCC")
	)
	(segment
		(start 91.770454 -336.038698)
		(end 91.516454 -335.784698)
		(width 0.508)
		(layer "In6.Cu")
		(net "PVDDCR_CPU1_P1_PVCC")
	)
	(segment
		(start 66.309494 -334.818736)
		(end 66.309494 -333.008478)
		(width 0.508)
		(layer "In6.Cu")
		(net "PVDDCR_CPU1_P1_PVCC")
	)
	(segment
		(start 75.1205 -330.272136)
		(end 75.710542 -330.862178)
		(width 0.508)
		(layer "In6.Cu")
		(net "PVDDCR_CPU1_P1_PVCC")
	)
	(segment
		(start 99.949 -336.849974)
		(end 101.012752 -335.786222)
		(width 0.508)
		(layer "In6.Cu")
		(net "PVDDCR_CPU1_P1_PVCC")
	)
	(segment
		(start 49.89068 -341.702136)
		(end 50.521362 -342.332818)
		(width 0.508)
		(layer "In6.Cu")
		(net "PVDDCR_CPU1_P1_PVCC")
	)
	(segment
		(start 101.234494 -330.653136)
		(end 100.726494 -330.145136)
		(width 0.508)
		(layer "In6.Cu")
		(net "PVDDCR_CPU1_P1_PVCC")
	)
	(segment
		(start 59.267344 -341.702136)
		(end 64.150494 -341.702136)
		(width 0.508)
		(layer "In6.Cu")
		(net "PVDDCR_CPU1_P1_PVCC")
	)
	(segment
		(start 84.067142 -330.818998)
		(end 84.067142 -331.71257)
		(width 0.508)
		(layer "In6.Cu")
		(net "PVDDCR_CPU1_P1_PVCC")
	)
	(segment
		(start 41.232582 -345.081098)
		(end 42.164762 -344.148918)
		(width 0.508)
		(layer "In6.Cu")
		(net "PVDDCR_CPU1_P1_PVCC")
	)
	(segment
		(start 101.234494 -334.463136)
		(end 101.234494 -330.653136)
		(width 0.508)
		(layer "In6.Cu")
		(net "PVDDCR_CPU1_P1_PVCC")
	)
	(segment
		(start 32.944054 -344.499946)
		(end 32.944054 -347.476572)
		(width 0.508)
		(layer "In6.Cu")
		(net "PVDDCR_CPU1_P1_PVCC")
	)
	(segment
		(start 68.18503 -330.272136)
		(end 75.1205 -330.272136)
		(width 0.508)
		(layer "In6.Cu")
		(net "PVDDCR_CPU1_P1_PVCC")
	)
	(segment
		(start 66.726054 -336.009488)
		(end 66.726054 -335.235296)
		(width 0.508)
		(layer "In6.Cu")
		(net "PVDDCR_CPU1_P1_PVCC")
	)
	(segment
		(start 49.860454 -347.730572)
		(end 49.855882 -347.730572)
		(width 0.508)
		(layer "In6.Cu")
		(net "PVDDCR_CPU1_P1_PVCC")
	)
	(segment
		(start 99.949 -339.194902)
		(end 99.949 -336.849974)
		(width 0.508)
		(layer "In6.Cu")
		(net "PVDDCR_CPU1_P1_PVCC")
	)
	(segment
		(start 58.191654 -347.730572)
		(end 57.937654 -347.476572)
		(width 0.508)
		(layer "In6.Cu")
		(net "PVDDCR_CPU1_P1_PVCC")
	)
	(segment
		(start 83.073494 -332.706218)
		(end 83.073494 -335.622138)
		(width 0.508)
		(layer "In6.Cu")
		(net "PVDDCR_CPU1_P1_PVCC")
	)
	(segment
		(start 42.164762 -344.148918)
		(end 42.164762 -342.279478)
		(width 0.508)
		(layer "In6.Cu")
		(net "PVDDCR_CPU1_P1_PVCC")
	)
	(segment
		(start 41.503854 -347.730572)
		(end 41.232582 -347.4593)
		(width 0.508)
		(layer "In6.Cu")
		(net "PVDDCR_CPU1_P1_PVCC")
	)
	(segment
		(start 67.376802 -331.080364)
		(end 68.18503 -330.272136)
		(width 0.508)
		(layer "In6.Cu")
		(net "PVDDCR_CPU1_P1_PVCC")
	)
	(segment
		(start 51.152044 -341.702136)
		(end 58.3819 -341.702136)
		(width 0.508)
		(layer "In6.Cu")
		(net "PVDDCR_CPU1_P1_PVCC")
	)
	(segment
		(start 50.521362 -343.704418)
		(end 50.521362 -342.332818)
		(width 0.508)
		(layer "In6.Cu")
		(net "PVDDCR_CPU1_P1_PVCC")
	)
	(segment
		(start 91.71686 -330.145136)
		(end 84.741004 -330.145136)
		(width 0.508)
		(layer "In6.Cu")
		(net "PVDDCR_CPU1_P1_PVCC")
	)
	(segment
		(start 58.824622 -343.70645)
		(end 58.824622 -342.144858)
		(width 0.508)
		(layer "In6.Cu")
		(net "PVDDCR_CPU1_P1_PVCC")
	)
	(segment
		(start 64.150494 -341.702136)
		(end 64.785494 -341.067136)
		(width 0.508)
		(layer "In6.Cu")
		(net "PVDDCR_CPU1_P1_PVCC")
	)
	(segment
		(start 33.08096 -347.613478)
		(end 33.198054 -347.730572)
		(width 0.508)
		(layer "In11.Cu")
		(net "PVDDCR_CPU1_P1_PVCC")
	)
	(segment
		(start 24.917654 -347.730572)
		(end 24.917654 -346.301568)
		(width 0.508)
		(layer "In11.Cu")
		(net "PVDDCR_CPU1_P1_PVCC")
	)
	(segment
		(start 33.08096 -342.37168)
		(end 33.08096 -347.613478)
		(width 0.508)
		(layer "In11.Cu")
		(net "PVDDCR_CPU1_P1_PVCC")
	)
	(segment
		(start 24.64562 -345.644724)
		(end 24.64562 -343.17432)
		(width 0.508)
		(layer "In11.Cu")
		(net "PVDDCR_CPU1_P1_PVCC")
	)
	(segment
		(start 31.99892 -341.28964)
		(end 33.08096 -342.37168)
		(width 0.508)
		(layer "In11.Cu")
		(net "PVDDCR_CPU1_P1_PVCC")
	)
	(segment
		(start 26.5303 -341.28964)
		(end 31.99892 -341.28964)
		(width 0.508)
		(layer "In11.Cu")
		(net "PVDDCR_CPU1_P1_PVCC")
	)
	(segment
		(start 24.917654 -346.301568)
		(end 24.64562 -345.644724)
		(width 0.508)
		(layer "In11.Cu")
		(net "PVDDCR_CPU1_P1_PVCC")
	)
	(segment
		(start 24.64562 -343.17432)
		(end 26.5303 -341.28964)
		(width 0.508)
		(layer "In11.Cu")
		(net "PVDDCR_CPU1_P1_PVCC")
	)
	(segment
		(start 34.127948 -363.509052)
		(end 33.355026 -363.509052)
		(width 0.10668)
		(layer "F.Cu")
		(net "PVDDCR_CPU1_P1_OCP_N_R")
	)
	(segment
		(start 34.925 -363.22)
		(end 34.417 -363.22)
		(width 0.10668)
		(layer "F.Cu")
		(net "PVDDCR_CPU1_P1_OCP_N_R")
	)
	(segment
		(start 34.417 -363.22)
		(end 34.127948 -363.509052)
		(width 0.10668)
		(layer "F.Cu")
		(net "PVDDCR_CPU1_P1_OCP_N_R")
	)
	(segment
		(start 35.776662 -362.368338)
		(end 34.925 -363.22)
		(width 0.10668)
		(layer "F.Cu")
		(net "PVDDCR_CPU1_P1_OCP_N_R")
	)
	(segment
		(start 36.81095 -362.077)
		(end 36.519612 -362.368338)
		(width 0.10668)
		(layer "F.Cu")
		(net "PVDDCR_CPU1_P1_OCP_N_R")
	)
	(segment
		(start 36.81095 -361.061)
		(end 36.81095 -362.077)
		(width 0.10668)
		(layer "F.Cu")
		(net "PVDDCR_CPU1_P1_OCP_N_R")
	)
	(segment
		(start 36.519612 -362.368338)
		(end 35.776662 -362.368338)
		(width 0.10668)
		(layer "F.Cu")
		(net "PVDDCR_CPU1_P1_OCP_N_R")
	)
	(segment
		(start 37.61105 -361.061)
		(end 38.209728 -361.061)
		(width 0.10668)
		(layer "F.Cu")
		(net "PVDDCR_CPU1_P1_OCP_N")
	)
	(segment
		(start 38.908736 -361.760008)
		(end 38.908736 -363.831124)
		(width 0.10668)
		(layer "F.Cu")
		(net "PVDDCR_CPU1_P1_OCP_N")
	)
	(segment
		(start 38.908736 -363.831124)
		(end 39.668196 -364.590584)
		(width 0.10668)
		(layer "F.Cu")
		(net "PVDDCR_CPU1_P1_OCP_N")
	)
	(segment
		(start 38.209728 -361.061)
		(end 38.908736 -361.760008)
		(width 0.10668)
		(layer "F.Cu")
		(net "PVDDCR_CPU1_P1_OCP_N")
	)
	(via
		(at 115.130326 -121.510552)
		(size 0.508)
		(drill 0.254)
		(layers "F.Cu" "B.Cu")
		(net "PVDDCR_CPU1_P1_OCP_N")
	)
	(via
		(at 39.668196 -364.590584)
		(size 0.508)
		(drill 0.254)
		(layers "F.Cu" "B.Cu")
		(net "PVDDCR_CPU1_P1_OCP_N")
	)
	(via
		(at 178.7398 -98.255328)
		(size 0.508)
		(drill 0.254)
		(layers "F.Cu" "B.Cu")
		(net "PVDDCR_CPU1_P1_OCP_N")
	)
	(via
		(at 169.304208 -87.91321)
		(size 0.508)
		(drill 0.254)
		(layers "F.Cu" "B.Cu")
		(net "PVDDCR_CPU1_P1_OCP_N")
	)
	(segment
		(start 178.390296 -99.894898)
		(end 178.181 -99.685602)
		(width 0.10668)
		(layer "B.Cu")
		(net "PVDDCR_CPU1_P1_OCP_N")
	)
	(segment
		(start 178.181 -99.685602)
		(end 178.181 -98.814128)
		(width 0.10668)
		(layer "B.Cu")
		(net "PVDDCR_CPU1_P1_OCP_N")
	)
	(segment
		(start 178.181 -98.814128)
		(end 178.7398 -98.255328)
		(width 0.10668)
		(layer "B.Cu")
		(net "PVDDCR_CPU1_P1_OCP_N")
	)
	(segment
		(start 178.689 -99.894898)
		(end 178.390296 -99.894898)
		(width 0.10668)
		(layer "B.Cu")
		(net "PVDDCR_CPU1_P1_OCP_N")
	)
	(segment
		(start 174.588932 -88.69172)
		(end 179.21732 -93.320108)
		(width 0.11684)
		(layer "In4.Cu")
		(net "PVDDCR_CPU1_P1_OCP_N")
	)
	(segment
		(start 170.082718 -88.69172)
		(end 174.588932 -88.69172)
		(width 0.11684)
		(layer "In4.Cu")
		(net "PVDDCR_CPU1_P1_OCP_N")
	)
	(segment
		(start 179.21732 -97.03308)
		(end 178.7398 -97.5106)
		(width 0.11684)
		(layer "In4.Cu")
		(net "PVDDCR_CPU1_P1_OCP_N")
	)
	(segment
		(start 179.21732 -93.320108)
		(end 179.21732 -97.03308)
		(width 0.11684)
		(layer "In4.Cu")
		(net "PVDDCR_CPU1_P1_OCP_N")
	)
	(segment
		(start 178.7398 -97.5106)
		(end 178.7398 -98.255328)
		(width 0.11684)
		(layer "In4.Cu")
		(net "PVDDCR_CPU1_P1_OCP_N")
	)
	(segment
		(start 169.304208 -87.91321)
		(end 170.082718 -88.69172)
		(width 0.11684)
		(layer "In4.Cu")
		(net "PVDDCR_CPU1_P1_OCP_N")
	)
	(segment
		(start 169.304208 -87.91321)
		(end 169.304208 -88.242394)
		(width 0.11684)
		(layer "In6.Cu")
		(net "PVDDCR_CPU1_P1_OCP_N")
	)
	(segment
		(start 154.160728 -118.37035)
		(end 148.433536 -118.37035)
		(width 0.11684)
		(layer "In6.Cu")
		(net "PVDDCR_CPU1_P1_OCP_N")
	)
	(segment
		(start 148.433536 -118.37035)
		(end 148.240242 -118.563644)
		(width 0.11684)
		(layer "In6.Cu")
		(net "PVDDCR_CPU1_P1_OCP_N")
	)
	(segment
		(start 160.129474 -97.417128)
		(end 160.129474 -105.770172)
		(width 0.11684)
		(layer "In6.Cu")
		(net "PVDDCR_CPU1_P1_OCP_N")
	)
	(segment
		(start 160.129474 -110.338616)
		(end 160.129474 -112.401604)
		(width 0.11684)
		(layer "In6.Cu")
		(net "PVDDCR_CPU1_P1_OCP_N")
	)
	(segment
		(start 117.045486 -119.595392)
		(end 115.130326 -121.510552)
		(width 0.11684)
		(layer "In6.Cu")
		(net "PVDDCR_CPU1_P1_OCP_N")
	)
	(segment
		(start 160.976056 -106.616754)
		(end 160.976056 -109.492034)
		(width 0.11684)
		(layer "In6.Cu")
		(net "PVDDCR_CPU1_P1_OCP_N")
	)
	(segment
		(start 160.976056 -109.492034)
		(end 160.129474 -110.338616)
		(width 0.11684)
		(layer "In6.Cu")
		(net "PVDDCR_CPU1_P1_OCP_N")
	)
	(segment
		(start 148.230082 -118.563644)
		(end 147.198334 -119.595392)
		(width 0.11684)
		(layer "In6.Cu")
		(net "PVDDCR_CPU1_P1_OCP_N")
	)
	(segment
		(start 160.129474 -112.401604)
		(end 154.160728 -118.37035)
		(width 0.11684)
		(layer "In6.Cu")
		(net "PVDDCR_CPU1_P1_OCP_N")
	)
	(segment
		(start 147.198334 -119.595392)
		(end 117.045486 -119.595392)
		(width 0.11684)
		(layer "In6.Cu")
		(net "PVDDCR_CPU1_P1_OCP_N")
	)
	(segment
		(start 148.240242 -118.563644)
		(end 148.230082 -118.563644)
		(width 0.11684)
		(layer "In6.Cu")
		(net "PVDDCR_CPU1_P1_OCP_N")
	)
	(segment
		(start 160.129474 -105.770172)
		(end 160.976056 -106.616754)
		(width 0.11684)
		(layer "In6.Cu")
		(net "PVDDCR_CPU1_P1_OCP_N")
	)
	(segment
		(start 169.304208 -88.242394)
		(end 160.129474 -97.417128)
		(width 0.11684)
		(layer "In6.Cu")
		(net "PVDDCR_CPU1_P1_OCP_N")
	)
	(segment
		(start 7.99465 -168.237408)
		(end 6.981444 -169.250614)
		(width 0.11684)
		(layer "In11.Cu")
		(net "PVDDCR_CPU1_P1_OCP_N")
	)
	(segment
		(start 6.981444 -335.37779)
		(end 16.65224 -345.048586)
		(width 0.11684)
		(layer "In11.Cu")
		(net "PVDDCR_CPU1_P1_OCP_N")
	)
	(segment
		(start 20.057364 -355.60381)
		(end 22.58314 -355.60381)
		(width 0.11684)
		(layer "In11.Cu")
		(net "PVDDCR_CPU1_P1_OCP_N")
	)
	(segment
		(start 6.981444 -169.250614)
		(end 6.981444 -335.37779)
		(width 0.11684)
		(layer "In11.Cu")
		(net "PVDDCR_CPU1_P1_OCP_N")
	)
	(segment
		(start 32.406082 -368.394234)
		(end 35.111182 -368.394234)
		(width 0.11684)
		(layer "In11.Cu")
		(net "PVDDCR_CPU1_P1_OCP_N")
	)
	(segment
		(start 88.572086 -132.496814)
		(end 86.892384 -132.496814)
		(width 0.11684)
		(layer "In11.Cu")
		(net "PVDDCR_CPU1_P1_OCP_N")
	)
	(segment
		(start 38.090602 -366.888522)
		(end 38.090602 -365.861346)
		(width 0.11684)
		(layer "In11.Cu")
		(net "PVDDCR_CPU1_P1_OCP_N")
	)
	(segment
		(start 16.65224 -345.048586)
		(end 16.65224 -352.198686)
		(width 0.11684)
		(layer "In11.Cu")
		(net "PVDDCR_CPU1_P1_OCP_N")
	)
	(segment
		(start 26.8478 -366.462564)
		(end 27.843734 -367.458498)
		(width 0.11684)
		(layer "In11.Cu")
		(net "PVDDCR_CPU1_P1_OCP_N")
	)
	(segment
		(start 115.130326 -121.510552)
		(end 115.130326 -121.983246)
		(width 0.11684)
		(layer "In11.Cu")
		(net "PVDDCR_CPU1_P1_OCP_N")
	)
	(segment
		(start 35.111182 -368.394234)
		(end 35.693858 -367.811558)
		(width 0.11684)
		(layer "In11.Cu")
		(net "PVDDCR_CPU1_P1_OCP_N")
	)
	(segment
		(start 44.774358 -138.651742)
		(end 26.858722 -138.651742)
		(width 0.11684)
		(layer "In11.Cu")
		(net "PVDDCR_CPU1_P1_OCP_N")
	)
	(segment
		(start 85.91931 -131.575048)
		(end 85.826092 -131.48183)
		(width 0.11684)
		(layer "In11.Cu")
		(net "PVDDCR_CPU1_P1_OCP_N")
	)
	(segment
		(start 24.098504 -361.859576)
		(end 25.509982 -363.271054)
		(width 0.11684)
		(layer "In11.Cu")
		(net "PVDDCR_CPU1_P1_OCP_N")
	)
	(segment
		(start 86.892384 -132.496814)
		(end 85.970618 -131.575048)
		(width 0.11684)
		(layer "In11.Cu")
		(net "PVDDCR_CPU1_P1_OCP_N")
	)
	(segment
		(start 26.8478 -364.038642)
		(end 26.8478 -366.462564)
		(width 0.11684)
		(layer "In11.Cu")
		(net "PVDDCR_CPU1_P1_OCP_N")
	)
	(segment
		(start 31.470346 -367.458498)
		(end 32.406082 -368.394234)
		(width 0.11684)
		(layer "In11.Cu")
		(net "PVDDCR_CPU1_P1_OCP_N")
	)
	(segment
		(start 26.080212 -363.271054)
		(end 26.8478 -364.038642)
		(width 0.11684)
		(layer "In11.Cu")
		(net "PVDDCR_CPU1_P1_OCP_N")
	)
	(segment
		(start 14.39799 -168.237408)
		(end 7.99465 -168.237408)
		(width 0.11684)
		(layer "In11.Cu")
		(net "PVDDCR_CPU1_P1_OCP_N")
	)
	(segment
		(start 16.65224 -352.198686)
		(end 20.057364 -355.60381)
		(width 0.11684)
		(layer "In11.Cu")
		(net "PVDDCR_CPU1_P1_OCP_N")
	)
	(segment
		(start 27.843734 -367.458498)
		(end 31.470346 -367.458498)
		(width 0.11684)
		(layer "In11.Cu")
		(net "PVDDCR_CPU1_P1_OCP_N")
	)
	(segment
		(start 22.58314 -355.60381)
		(end 24.098504 -357.119174)
		(width 0.11684)
		(layer "In11.Cu")
		(net "PVDDCR_CPU1_P1_OCP_N")
	)
	(segment
		(start 96.113346 -124.955554)
		(end 88.572086 -132.496814)
		(width 0.11684)
		(layer "In11.Cu")
		(net "PVDDCR_CPU1_P1_OCP_N")
	)
	(segment
		(start 24.098504 -357.119174)
		(end 24.098504 -361.859576)
		(width 0.11684)
		(layer "In11.Cu")
		(net "PVDDCR_CPU1_P1_OCP_N")
	)
	(segment
		(start 19.11858 -146.391884)
		(end 19.11858 -163.516818)
		(width 0.11684)
		(layer "In11.Cu")
		(net "PVDDCR_CPU1_P1_OCP_N")
	)
	(segment
		(start 115.130326 -121.983246)
		(end 112.158018 -124.955554)
		(width 0.11684)
		(layer "In11.Cu")
		(net "PVDDCR_CPU1_P1_OCP_N")
	)
	(segment
		(start 38.090602 -365.861346)
		(end 39.361364 -364.590584)
		(width 0.11684)
		(layer "In11.Cu")
		(net "PVDDCR_CPU1_P1_OCP_N")
	)
	(segment
		(start 26.858722 -138.651742)
		(end 19.11858 -146.391884)
		(width 0.11684)
		(layer "In11.Cu")
		(net "PVDDCR_CPU1_P1_OCP_N")
	)
	(segment
		(start 39.361364 -364.590584)
		(end 39.668196 -364.590584)
		(width 0.11684)
		(layer "In11.Cu")
		(net "PVDDCR_CPU1_P1_OCP_N")
	)
	(segment
		(start 35.693858 -367.811558)
		(end 37.167566 -367.811558)
		(width 0.11684)
		(layer "In11.Cu")
		(net "PVDDCR_CPU1_P1_OCP_N")
	)
	(segment
		(start 37.167566 -367.811558)
		(end 38.090602 -366.888522)
		(width 0.11684)
		(layer "In11.Cu")
		(net "PVDDCR_CPU1_P1_OCP_N")
	)
	(segment
		(start 51.94427 -131.48183)
		(end 44.774358 -138.651742)
		(width 0.11684)
		(layer "In11.Cu")
		(net "PVDDCR_CPU1_P1_OCP_N")
	)
	(segment
		(start 112.158018 -124.955554)
		(end 96.113346 -124.955554)
		(width 0.11684)
		(layer "In11.Cu")
		(net "PVDDCR_CPU1_P1_OCP_N")
	)
	(segment
		(start 25.509982 -363.271054)
		(end 26.080212 -363.271054)
		(width 0.11684)
		(layer "In11.Cu")
		(net "PVDDCR_CPU1_P1_OCP_N")
	)
	(segment
		(start 19.11858 -163.516818)
		(end 14.39799 -168.237408)
		(width 0.11684)
		(layer "In11.Cu")
		(net "PVDDCR_CPU1_P1_OCP_N")
	)
	(segment
		(start 85.826092 -131.48183)
		(end 51.94427 -131.48183)
		(width 0.11684)
		(layer "In11.Cu")
		(net "PVDDCR_CPU1_P1_OCP_N")
	)
	(segment
		(start 85.970618 -131.575048)
		(end 85.91931 -131.575048)
		(width 0.11684)
		(layer "In11.Cu")
		(net "PVDDCR_CPU1_P1_OCP_N")
	)
	(segment
		(start 102.639368 -342.839294)
		(end 102.639368 -343.245186)
		(width 0.127)
		(layer "F.Cu")
		(net "PVDDCR_CPU1_P1_LSET6")
	)
	(segment
		(start 102.639368 -343.245186)
		(end 102.26675 -343.617804)
		(width 0.127)
		(layer "F.Cu")
		(net "PVDDCR_CPU1_P1_LSET6")
	)
	(segment
		(start 102.26675 -344.908886)
		(end 102.024688 -345.150948)
		(width 0.127)
		(layer "F.Cu")
		(net "PVDDCR_CPU1_P1_LSET6")
	)
	(segment
		(start 102.26675 -343.617804)
		(end 102.26675 -344.001852)
		(width 0.127)
		(layer "F.Cu")
		(net "PVDDCR_CPU1_P1_LSET6")
	)
	(segment
		(start 102.26675 -344.001852)
		(end 102.26675 -344.908886)
		(width 0.127)
		(layer "F.Cu")
		(net "PVDDCR_CPU1_P1_LSET6")
	)
	(via
		(at 102.26675 -344.001852)
		(size 0.4064)
		(drill 0.2032)
		(layers "F.Cu" "B.Cu")
		(net "PVDDCR_CPU1_P1_LSET6")
	)
	(segment
		(start 93.990922 -339.100668)
		(end 93.990922 -339.998812)
		(width 0.127)
		(layer "F.Cu")
		(net "PVDDCR_CPU1_P1_LSET5")
	)
	(segment
		(start 93.990922 -338.70773)
		(end 93.990922 -339.100668)
		(width 0.127)
		(layer "F.Cu")
		(net "PVDDCR_CPU1_P1_LSET5")
	)
	(segment
		(start 94.36354 -338.335112)
		(end 93.990922 -338.70773)
		(width 0.127)
		(layer "F.Cu")
		(net "PVDDCR_CPU1_P1_LSET5")
	)
	(segment
		(start 93.990922 -339.998812)
		(end 93.74886 -340.240874)
		(width 0.127)
		(layer "F.Cu")
		(net "PVDDCR_CPU1_P1_LSET5")
	)
	(segment
		(start 94.36354 -337.92922)
		(end 94.36354 -338.335112)
		(width 0.127)
		(layer "F.Cu")
		(net "PVDDCR_CPU1_P1_LSET5")
	)
	(via
		(at 93.990922 -339.100668)
		(size 0.4064)
		(drill 0.2032)
		(layers "F.Cu" "B.Cu")
		(net "PVDDCR_CPU1_P1_LSET5")
	)
	(segment
		(start 60.412122 -351.690686)
		(end 60.412122 -350.775016)
		(width 0.127)
		(layer "F.Cu")
		(net "PVDDCR_CPU1_P1_LSET4")
	)
	(segment
		(start 60.412122 -350.399604)
		(end 60.78474 -350.026986)
		(width 0.127)
		(layer "F.Cu")
		(net "PVDDCR_CPU1_P1_LSET4")
	)
	(segment
		(start 60.78474 -350.026986)
		(end 60.78474 -349.621094)
		(width 0.127)
		(layer "F.Cu")
		(net "PVDDCR_CPU1_P1_LSET4")
	)
	(segment
		(start 60.17006 -351.932748)
		(end 60.412122 -351.690686)
		(width 0.127)
		(layer "F.Cu")
		(net "PVDDCR_CPU1_P1_LSET4")
	)
	(segment
		(start 60.412122 -350.775016)
		(end 60.412122 -350.399604)
		(width 0.127)
		(layer "F.Cu")
		(net "PVDDCR_CPU1_P1_LSET4")
	)
	(via
		(at 60.412122 -350.775016)
		(size 0.4064)
		(drill 0.2032)
		(layers "F.Cu" "B.Cu")
		(net "PVDDCR_CPU1_P1_LSET4")
	)
	(segment
		(start 69.31914 -338.305902)
		(end 68.946522 -338.67852)
		(width 0.127)
		(layer "F.Cu")
		(net "PVDDCR_CPU1_P1_LSET3")
	)
	(segment
		(start 68.946522 -338.67852)
		(end 68.946522 -339.08873)
		(width 0.127)
		(layer "F.Cu")
		(net "PVDDCR_CPU1_P1_LSET3")
	)
	(segment
		(start 68.946522 -339.08873)
		(end 68.946522 -339.969602)
		(width 0.127)
		(layer "F.Cu")
		(net "PVDDCR_CPU1_P1_LSET3")
	)
	(segment
		(start 69.31914 -337.90001)
		(end 69.31914 -338.305902)
		(width 0.127)
		(layer "F.Cu")
		(net "PVDDCR_CPU1_P1_LSET3")
	)
	(segment
		(start 68.946522 -339.969602)
		(end 68.70446 -340.211664)
		(width 0.127)
		(layer "F.Cu")
		(net "PVDDCR_CPU1_P1_LSET3")
	)
	(via
		(at 68.946522 -339.08873)
		(size 0.4064)
		(drill 0.2032)
		(layers "F.Cu" "B.Cu")
		(net "PVDDCR_CPU1_P1_LSET3")
	)
	(segment
		(start 77.674724 -338.29879)
		(end 77.302106 -338.671408)
		(width 0.127)
		(layer "F.Cu")
		(net "PVDDCR_CPU1_P1_LSET2")
	)
	(segment
		(start 77.302106 -339.08873)
		(end 77.302106 -339.96249)
		(width 0.127)
		(layer "F.Cu")
		(net "PVDDCR_CPU1_P1_LSET2")
	)
	(segment
		(start 77.302106 -339.96249)
		(end 77.060044 -340.204552)
		(width 0.127)
		(layer "F.Cu")
		(net "PVDDCR_CPU1_P1_LSET2")
	)
	(segment
		(start 77.302106 -338.671408)
		(end 77.302106 -339.08873)
		(width 0.127)
		(layer "F.Cu")
		(net "PVDDCR_CPU1_P1_LSET2")
	)
	(segment
		(start 77.674724 -337.892898)
		(end 77.674724 -338.29879)
		(width 0.127)
		(layer "F.Cu")
		(net "PVDDCR_CPU1_P1_LSET2")
	)
	(via
		(at 77.302106 -339.08873)
		(size 0.4064)
		(drill 0.2032)
		(layers "F.Cu" "B.Cu")
		(net "PVDDCR_CPU1_P1_LSET2")
	)
	(segment
		(start 86.03234 -338.284312)
		(end 85.659722 -338.65693)
		(width 0.127)
		(layer "F.Cu")
		(net "PVDDCR_CPU1_P1_LSET1")
	)
	(segment
		(start 85.659722 -339.053424)
		(end 85.659722 -339.948012)
		(width 0.127)
		(layer "F.Cu")
		(net "PVDDCR_CPU1_P1_LSET1")
	)
	(segment
		(start 86.03234 -337.87842)
		(end 86.03234 -338.284312)
		(width 0.127)
		(layer "F.Cu")
		(net "PVDDCR_CPU1_P1_LSET1")
	)
	(segment
		(start 85.659722 -339.948012)
		(end 85.41766 -340.190074)
		(width 0.127)
		(layer "F.Cu")
		(net "PVDDCR_CPU1_P1_LSET1")
	)
	(segment
		(start 85.659722 -338.65693)
		(end 85.659722 -339.053424)
		(width 0.127)
		(layer "F.Cu")
		(net "PVDDCR_CPU1_P1_LSET1")
	)
	(via
		(at 85.659722 -339.053424)
		(size 0.4064)
		(drill 0.2032)
		(layers "F.Cu" "B.Cu")
		(net "PVDDCR_CPU1_P1_LSET1")
	)
	(segment
		(start 101.752146 -343.652348)
		(end 102.18928 -343.215214)
		(width 0.2286)
		(layer "F.Cu")
		(net "PVDDCR_CPU1_P1_IMON6")
	)
	(segment
		(start 31.079948 -358.079548)
		(end 31.079948 -361.233974)
		(width 0.1778)
		(layer "F.Cu")
		(net "PVDDCR_CPU1_P1_IMON6")
	)
	(segment
		(start 101.752146 -343.75979)
		(end 101.752146 -343.652348)
		(width 0.2286)
		(layer "F.Cu")
		(net "PVDDCR_CPU1_P1_IMON6")
	)
	(segment
		(start 101.76383 -343.75979)
		(end 101.752146 -343.75979)
		(width 0.2286)
		(layer "F.Cu")
		(net "PVDDCR_CPU1_P1_IMON6")
	)
	(segment
		(start 30.6578 -357.6574)
		(end 31.079948 -358.079548)
		(width 0.1778)
		(layer "F.Cu")
		(net "PVDDCR_CPU1_P1_IMON6")
	)
	(segment
		(start 102.18928 -343.215214)
		(end 102.18928 -342.839294)
		(width 0.2286)
		(layer "F.Cu")
		(net "PVDDCR_CPU1_P1_IMON6")
	)
	(via
		(at 30.6578 -357.6574)
		(size 0.762)
		(drill 0.254)
		(layers "F.Cu" "B.Cu")
		(net "PVDDCR_CPU1_P1_IMON6")
	)
	(via
		(at 101.76383 -343.75979)
		(size 0.508)
		(drill 0.254)
		(layers "F.Cu" "B.Cu")
		(net "PVDDCR_CPU1_P1_IMON6")
	)
	(segment
		(start 96.518222 -342.660478)
		(end 78.738222 -342.660478)
		(width 0.254)
		(layer "In13.Cu")
		(net "PVDDCR_CPU1_P1_IMON6")
	)
	(segment
		(start 32.542988 -357.8352)
		(end 30.8356 -357.8352)
		(width 0.254)
		(layer "In13.Cu")
		(net "PVDDCR_CPU1_P1_IMON6")
	)
	(segment
		(start 101.247194 -344.171778)
		(end 101.247194 -345.317826)
		(width 0.254)
		(layer "In13.Cu")
		(net "PVDDCR_CPU1_P1_IMON6")
	)
	(segment
		(start 100.678742 -345.886278)
		(end 99.744022 -345.886278)
		(width 0.254)
		(layer "In13.Cu")
		(net "PVDDCR_CPU1_P1_IMON6")
	)
	(segment
		(start 78.738222 -342.660478)
		(end 66.246502 -355.152198)
		(width 0.254)
		(layer "In13.Cu")
		(net "PVDDCR_CPU1_P1_IMON6")
	)
	(segment
		(start 39.964614 -355.152198)
		(end 36.951412 -358.1654)
		(width 0.254)
		(layer "In13.Cu")
		(net "PVDDCR_CPU1_P1_IMON6")
	)
	(segment
		(start 36.951412 -358.1654)
		(end 32.873188 -358.1654)
		(width 0.254)
		(layer "In13.Cu")
		(net "PVDDCR_CPU1_P1_IMON6")
	)
	(segment
		(start 101.659182 -343.75979)
		(end 101.247194 -344.171778)
		(width 0.254)
		(layer "In13.Cu")
		(net "PVDDCR_CPU1_P1_IMON6")
	)
	(segment
		(start 101.247194 -345.317826)
		(end 100.678742 -345.886278)
		(width 0.254)
		(layer "In13.Cu")
		(net "PVDDCR_CPU1_P1_IMON6")
	)
	(segment
		(start 99.744022 -345.886278)
		(end 96.518222 -342.660478)
		(width 0.254)
		(layer "In13.Cu")
		(net "PVDDCR_CPU1_P1_IMON6")
	)
	(segment
		(start 101.76383 -343.75979)
		(end 101.659182 -343.75979)
		(width 0.254)
		(layer "In13.Cu")
		(net "PVDDCR_CPU1_P1_IMON6")
	)
	(segment
		(start 30.8356 -357.8352)
		(end 30.6578 -357.6574)
		(width 0.254)
		(layer "In13.Cu")
		(net "PVDDCR_CPU1_P1_IMON6")
	)
	(segment
		(start 32.873188 -358.1654)
		(end 32.542988 -357.8352)
		(width 0.254)
		(layer "In13.Cu")
		(net "PVDDCR_CPU1_P1_IMON6")
	)
	(segment
		(start 66.246502 -355.152198)
		(end 39.964614 -355.152198)
		(width 0.254)
		(layer "In13.Cu")
		(net "PVDDCR_CPU1_P1_IMON6")
	)
	(segment
		(start 93.913452 -337.92922)
		(end 93.913452 -338.30514)
		(width 0.2286)
		(layer "F.Cu")
		(net "PVDDCR_CPU1_P1_IMON5")
	)
	(segment
		(start 93.476318 -338.742274)
		(end 93.476318 -338.849716)
		(width 0.2286)
		(layer "F.Cu")
		(net "PVDDCR_CPU1_P1_IMON5")
	)
	(segment
		(start 93.476318 -338.849716)
		(end 93.488002 -338.849716)
		(width 0.2286)
		(layer "F.Cu")
		(net "PVDDCR_CPU1_P1_IMON5")
	)
	(segment
		(start 30.679898 -358.549194)
		(end 30.679898 -361.233974)
		(width 0.1778)
		(layer "F.Cu")
		(net "PVDDCR_CPU1_P1_IMON5")
	)
	(segment
		(start 29.956252 -357.825548)
		(end 30.679898 -358.549194)
		(width 0.1778)
		(layer "F.Cu")
		(net "PVDDCR_CPU1_P1_IMON5")
	)
	(segment
		(start 30.423104 -356.5525)
		(end 29.956252 -357.019352)
		(width 0.1778)
		(layer "F.Cu")
		(net "PVDDCR_CPU1_P1_IMON5")
	)
	(segment
		(start 29.956252 -357.019352)
		(end 29.956252 -357.825548)
		(width 0.1778)
		(layer "F.Cu")
		(net "PVDDCR_CPU1_P1_IMON5")
	)
	(segment
		(start 31.0007 -356.5525)
		(end 30.423104 -356.5525)
		(width 0.1778)
		(layer "F.Cu")
		(net "PVDDCR_CPU1_P1_IMON5")
	)
	(segment
		(start 93.913452 -338.30514)
		(end 93.476318 -338.742274)
		(width 0.2286)
		(layer "F.Cu")
		(net "PVDDCR_CPU1_P1_IMON5")
	)
	(via
		(at 31.0007 -356.5525)
		(size 0.508)
		(drill 0.254)
		(layers "F.Cu" "B.Cu")
		(net "PVDDCR_CPU1_P1_IMON5")
	)
	(via
		(at 93.488002 -338.849716)
		(size 0.508)
		(drill 0.254)
		(layers "F.Cu" "B.Cu")
		(net "PVDDCR_CPU1_P1_IMON5")
	)
	(segment
		(start 39.141908 -353.872292)
		(end 65.59423 -353.872292)
		(width 0.254)
		(layer "In13.Cu")
		(net "PVDDCR_CPU1_P1_IMON5")
	)
	(segment
		(start 65.59423 -353.872292)
		(end 78.370684 -341.095838)
		(width 0.254)
		(layer "In13.Cu")
		(net "PVDDCR_CPU1_P1_IMON5")
	)
	(segment
		(start 78.370684 -341.095838)
		(end 92.33916 -341.095838)
		(width 0.254)
		(layer "In13.Cu")
		(net "PVDDCR_CPU1_P1_IMON5")
	)
	(segment
		(start 92.33916 -341.095838)
		(end 92.903802 -340.531196)
		(width 0.254)
		(layer "In13.Cu")
		(net "PVDDCR_CPU1_P1_IMON5")
	)
	(segment
		(start 92.903802 -339.134196)
		(end 93.188282 -338.849716)
		(width 0.254)
		(layer "In13.Cu")
		(net "PVDDCR_CPU1_P1_IMON5")
	)
	(segment
		(start 92.903802 -340.531196)
		(end 92.903802 -339.134196)
		(width 0.254)
		(layer "In13.Cu")
		(net "PVDDCR_CPU1_P1_IMON5")
	)
	(segment
		(start 31.1658 -356.7176)
		(end 36.2966 -356.7176)
		(width 0.254)
		(layer "In13.Cu")
		(net "PVDDCR_CPU1_P1_IMON5")
	)
	(segment
		(start 36.2966 -356.7176)
		(end 39.141908 -353.872292)
		(width 0.254)
		(layer "In13.Cu")
		(net "PVDDCR_CPU1_P1_IMON5")
	)
	(segment
		(start 31.0007 -356.5525)
		(end 31.1658 -356.7176)
		(width 0.254)
		(layer "In13.Cu")
		(net "PVDDCR_CPU1_P1_IMON5")
	)
	(segment
		(start 93.188282 -338.849716)
		(end 93.488002 -338.849716)
		(width 0.254)
		(layer "In13.Cu")
		(net "PVDDCR_CPU1_P1_IMON5")
	)
	(segment
		(start 60.334652 -349.997014)
		(end 59.897518 -350.434148)
		(width 0.2286)
		(layer "F.Cu")
		(net "PVDDCR_CPU1_P1_IMON4")
	)
	(segment
		(start 60.334652 -349.621094)
		(end 60.334652 -349.997014)
		(width 0.2286)
		(layer "F.Cu")
		(net "PVDDCR_CPU1_P1_IMON4")
	)
	(segment
		(start 59.897518 -350.54159)
		(end 59.909202 -350.54159)
		(width 0.2286)
		(layer "F.Cu")
		(net "PVDDCR_CPU1_P1_IMON4")
	)
	(segment
		(start 30.280102 -358.905302)
		(end 30.280102 -361.233974)
		(width 0.1778)
		(layer "F.Cu")
		(net "PVDDCR_CPU1_P1_IMON4")
	)
	(segment
		(start 29.6418 -358.267)
		(end 30.280102 -358.905302)
		(width 0.1778)
		(layer "F.Cu")
		(net "PVDDCR_CPU1_P1_IMON4")
	)
	(segment
		(start 59.897518 -350.434148)
		(end 59.897518 -350.54159)
		(width 0.2286)
		(layer "F.Cu")
		(net "PVDDCR_CPU1_P1_IMON4")
	)
	(via
		(at 29.6418 -358.267)
		(size 0.508)
		(drill 0.254)
		(layers "F.Cu" "B.Cu")
		(net "PVDDCR_CPU1_P1_IMON4")
	)
	(via
		(at 59.909202 -350.54159)
		(size 0.508)
		(drill 0.254)
		(layers "F.Cu" "B.Cu")
		(net "PVDDCR_CPU1_P1_IMON4")
	)
	(segment
		(start 33.6042 -358.9274)
		(end 35.01263 -358.9274)
		(width 0.254)
		(layer "In6.Cu")
		(net "PVDDCR_CPU1_P1_IMON4")
	)
	(segment
		(start 30.8102 -358.4956)
		(end 31.4452 -357.8606)
		(width 0.254)
		(layer "In6.Cu")
		(net "PVDDCR_CPU1_P1_IMON4")
	)
	(segment
		(start 35.01263 -358.9274)
		(end 39.540688 -354.399342)
		(width 0.254)
		(layer "In6.Cu")
		(net "PVDDCR_CPU1_P1_IMON4")
	)
	(segment
		(start 59.352942 -352.175318)
		(end 59.352942 -350.821498)
		(width 0.254)
		(layer "In6.Cu")
		(net "PVDDCR_CPU1_P1_IMON4")
	)
	(segment
		(start 59.63285 -350.54159)
		(end 59.909202 -350.54159)
		(width 0.254)
		(layer "In6.Cu")
		(net "PVDDCR_CPU1_P1_IMON4")
	)
	(segment
		(start 58.649362 -352.878898)
		(end 59.352942 -352.175318)
		(width 0.254)
		(layer "In6.Cu")
		(net "PVDDCR_CPU1_P1_IMON4")
	)
	(segment
		(start 31.4452 -357.8606)
		(end 32.5374 -357.8606)
		(width 0.254)
		(layer "In6.Cu")
		(net "PVDDCR_CPU1_P1_IMON4")
	)
	(segment
		(start 29.6418 -358.267)
		(end 29.8704 -358.4956)
		(width 0.254)
		(layer "In6.Cu")
		(net "PVDDCR_CPU1_P1_IMON4")
	)
	(segment
		(start 45.057568 -354.399342)
		(end 46.578012 -352.878898)
		(width 0.254)
		(layer "In6.Cu")
		(net "PVDDCR_CPU1_P1_IMON4")
	)
	(segment
		(start 32.5374 -357.8606)
		(end 33.6042 -358.9274)
		(width 0.254)
		(layer "In6.Cu")
		(net "PVDDCR_CPU1_P1_IMON4")
	)
	(segment
		(start 46.578012 -352.878898)
		(end 58.649362 -352.878898)
		(width 0.254)
		(layer "In6.Cu")
		(net "PVDDCR_CPU1_P1_IMON4")
	)
	(segment
		(start 39.540688 -354.399342)
		(end 45.057568 -354.399342)
		(width 0.254)
		(layer "In6.Cu")
		(net "PVDDCR_CPU1_P1_IMON4")
	)
	(segment
		(start 29.8704 -358.4956)
		(end 30.8102 -358.4956)
		(width 0.254)
		(layer "In6.Cu")
		(net "PVDDCR_CPU1_P1_IMON4")
	)
	(segment
		(start 59.352942 -350.821498)
		(end 59.63285 -350.54159)
		(width 0.254)
		(layer "In6.Cu")
		(net "PVDDCR_CPU1_P1_IMON4")
	)
	(segment
		(start 68.869052 -338.27593)
		(end 68.431918 -338.713064)
		(width 0.2286)
		(layer "F.Cu")
		(net "PVDDCR_CPU1_P1_IMON3")
	)
	(segment
		(start 29.880052 -359.826052)
		(end 29.6418 -359.5878)
		(width 0.1778)
		(layer "F.Cu")
		(net "PVDDCR_CPU1_P1_IMON3")
	)
	(segment
		(start 68.431918 -338.713064)
		(end 68.431918 -338.820506)
		(width 0.2286)
		(layer "F.Cu")
		(net "PVDDCR_CPU1_P1_IMON3")
	)
	(segment
		(start 68.869052 -337.90001)
		(end 68.869052 -338.27593)
		(width 0.2286)
		(layer "F.Cu")
		(net "PVDDCR_CPU1_P1_IMON3")
	)
	(segment
		(start 68.431918 -338.820506)
		(end 68.443602 -338.820506)
		(width 0.2286)
		(layer "F.Cu")
		(net "PVDDCR_CPU1_P1_IMON3")
	)
	(segment
		(start 29.880052 -361.233974)
		(end 29.880052 -359.826052)
		(width 0.1778)
		(layer "F.Cu")
		(net "PVDDCR_CPU1_P1_IMON3")
	)
	(via
		(at 68.443602 -338.820506)
		(size 0.508)
		(drill 0.254)
		(layers "F.Cu" "B.Cu")
		(net "PVDDCR_CPU1_P1_IMON3")
	)
	(via
		(at 29.6418 -359.5878)
		(size 0.508)
		(drill 0.254)
		(layers "F.Cu" "B.Cu")
		(net "PVDDCR_CPU1_P1_IMON3")
	)
	(segment
		(start 47.361856 -354.143056)
		(end 45.681646 -355.823266)
		(width 0.254)
		(layer "In6.Cu")
		(net "PVDDCR_CPU1_P1_IMON3")
	)
	(segment
		(start 67.01409 -350.285558)
		(end 63.156592 -354.143056)
		(width 0.254)
		(layer "In6.Cu")
		(net "PVDDCR_CPU1_P1_IMON3")
	)
	(segment
		(start 67.926966 -339.229446)
		(end 67.926966 -340.378542)
		(width 0.254)
		(layer "In6.Cu")
		(net "PVDDCR_CPU1_P1_IMON3")
	)
	(segment
		(start 65.972182 -342.333326)
		(end 65.972182 -346.887038)
		(width 0.254)
		(layer "In6.Cu")
		(net "PVDDCR_CPU1_P1_IMON3")
	)
	(segment
		(start 67.926966 -340.378542)
		(end 65.972182 -342.333326)
		(width 0.254)
		(layer "In6.Cu")
		(net "PVDDCR_CPU1_P1_IMON3")
	)
	(segment
		(start 68.443602 -338.820506)
		(end 68.335906 -338.820506)
		(width 0.254)
		(layer "In6.Cu")
		(net "PVDDCR_CPU1_P1_IMON3")
	)
	(segment
		(start 30.7848 -360.7308)
		(end 29.6418 -359.5878)
		(width 0.254)
		(layer "In6.Cu")
		(net "PVDDCR_CPU1_P1_IMON3")
	)
	(segment
		(start 68.335906 -338.820506)
		(end 67.926966 -339.229446)
		(width 0.254)
		(layer "In6.Cu")
		(net "PVDDCR_CPU1_P1_IMON3")
	)
	(segment
		(start 67.01409 -347.928946)
		(end 67.01409 -350.285558)
		(width 0.254)
		(layer "In6.Cu")
		(net "PVDDCR_CPU1_P1_IMON3")
	)
	(segment
		(start 45.681646 -355.823266)
		(end 40.845486 -355.823266)
		(width 0.254)
		(layer "In6.Cu")
		(net "PVDDCR_CPU1_P1_IMON3")
	)
	(segment
		(start 39.352728 -357.750872)
		(end 36.3728 -360.7308)
		(width 0.254)
		(layer "In6.Cu")
		(net "PVDDCR_CPU1_P1_IMON3")
	)
	(segment
		(start 65.972182 -346.887038)
		(end 67.01409 -347.928946)
		(width 0.254)
		(layer "In6.Cu")
		(net "PVDDCR_CPU1_P1_IMON3")
	)
	(segment
		(start 36.3728 -360.7308)
		(end 30.7848 -360.7308)
		(width 0.254)
		(layer "In6.Cu")
		(net "PVDDCR_CPU1_P1_IMON3")
	)
	(segment
		(start 40.845486 -355.823266)
		(end 39.352728 -357.316024)
		(width 0.254)
		(layer "In6.Cu")
		(net "PVDDCR_CPU1_P1_IMON3")
	)
	(segment
		(start 39.352728 -357.316024)
		(end 39.352728 -357.750872)
		(width 0.254)
		(layer "In6.Cu")
		(net "PVDDCR_CPU1_P1_IMON3")
	)
	(segment
		(start 63.156592 -354.143056)
		(end 47.361856 -354.143056)
		(width 0.254)
		(layer "In6.Cu")
		(net "PVDDCR_CPU1_P1_IMON3")
	)
	(segment
		(start 29.480002 -360.20629)
		(end 29.480002 -361.233974)
		(width 0.1778)
		(layer "F.Cu")
		(net "PVDDCR_CPU1_P1_IMON2")
	)
	(segment
		(start 28.9052 -355.2444)
		(end 29.1084 -355.4476)
		(width 0.1778)
		(layer "F.Cu")
		(net "PVDDCR_CPU1_P1_IMON2")
	)
	(segment
		(start 28.829 -355.2444)
		(end 28.9052 -355.2444)
		(width 0.1778)
		(layer "F.Cu")
		(net "PVDDCR_CPU1_P1_IMON2")
	)
	(segment
		(start 77.224636 -338.268818)
		(end 76.787502 -338.705952)
		(width 0.2286)
		(layer "F.Cu")
		(net "PVDDCR_CPU1_P1_IMON2")
	)
	(segment
		(start 76.787502 -338.705952)
		(end 76.787502 -338.813394)
		(width 0.2286)
		(layer "F.Cu")
		(net "PVDDCR_CPU1_P1_IMON2")
	)
	(segment
		(start 29.1084 -359.834688)
		(end 29.480002 -360.20629)
		(width 0.1778)
		(layer "F.Cu")
		(net "PVDDCR_CPU1_P1_IMON2")
	)
	(segment
		(start 29.1084 -355.4476)
		(end 29.1084 -359.834688)
		(width 0.1778)
		(layer "F.Cu")
		(net "PVDDCR_CPU1_P1_IMON2")
	)
	(segment
		(start 76.787502 -338.813394)
		(end 76.799186 -338.813394)
		(width 0.2286)
		(layer "F.Cu")
		(net "PVDDCR_CPU1_P1_IMON2")
	)
	(segment
		(start 77.224636 -337.892898)
		(end 77.224636 -338.268818)
		(width 0.2286)
		(layer "F.Cu")
		(net "PVDDCR_CPU1_P1_IMON2")
	)
	(via
		(at 28.829 -355.2444)
		(size 0.762)
		(drill 0.254)
		(layers "F.Cu" "B.Cu")
		(net "PVDDCR_CPU1_P1_IMON2")
	)
	(via
		(at 76.799186 -338.813394)
		(size 0.508)
		(drill 0.254)
		(layers "F.Cu" "B.Cu")
		(net "PVDDCR_CPU1_P1_IMON2")
	)
	(segment
		(start 76.242926 -344.510614)
		(end 76.242926 -339.093302)
		(width 0.254)
		(layer "In11.Cu")
		(net "PVDDCR_CPU1_P1_IMON2")
	)
	(segment
		(start 29.1084 -355.2444)
		(end 31.605728 -352.747072)
		(width 0.254)
		(layer "In11.Cu")
		(net "PVDDCR_CPU1_P1_IMON2")
	)
	(segment
		(start 68.006468 -352.747072)
		(end 76.242926 -344.510614)
		(width 0.254)
		(layer "In11.Cu")
		(net "PVDDCR_CPU1_P1_IMON2")
	)
	(segment
		(start 76.522834 -338.813394)
		(end 76.799186 -338.813394)
		(width 0.254)
		(layer "In11.Cu")
		(net "PVDDCR_CPU1_P1_IMON2")
	)
	(segment
		(start 31.605728 -352.747072)
		(end 68.006468 -352.747072)
		(width 0.254)
		(layer "In11.Cu")
		(net "PVDDCR_CPU1_P1_IMON2")
	)
	(segment
		(start 28.829 -355.2444)
		(end 29.1084 -355.2444)
		(width 0.254)
		(layer "In11.Cu")
		(net "PVDDCR_CPU1_P1_IMON2")
	)
	(segment
		(start 76.242926 -339.093302)
		(end 76.522834 -338.813394)
		(width 0.254)
		(layer "In11.Cu")
		(net "PVDDCR_CPU1_P1_IMON2")
	)
	(segment
		(start 85.145118 -338.691474)
		(end 85.582252 -338.25434)
		(width 0.2286)
		(layer "F.Cu")
		(net "PVDDCR_CPU1_P1_IMON1")
	)
	(segment
		(start 28.575 -359.8672)
		(end 29.079952 -360.372152)
		(width 0.1778)
		(layer "F.Cu")
		(net "PVDDCR_CPU1_P1_IMON1")
	)
	(segment
		(start 29.079952 -360.372152)
		(end 29.079952 -361.233974)
		(width 0.1778)
		(layer "F.Cu")
		(net "PVDDCR_CPU1_P1_IMON1")
	)
	(segment
		(start 28.575 -356.616)
		(end 28.575 -359.8672)
		(width 0.1778)
		(layer "F.Cu")
		(net "PVDDCR_CPU1_P1_IMON1")
	)
	(segment
		(start 85.582252 -338.25434)
		(end 85.582252 -337.87842)
		(width 0.2286)
		(layer "F.Cu")
		(net "PVDDCR_CPU1_P1_IMON1")
	)
	(segment
		(start 85.156802 -338.798916)
		(end 85.145118 -338.798916)
		(width 0.2286)
		(layer "F.Cu")
		(net "PVDDCR_CPU1_P1_IMON1")
	)
	(segment
		(start 28.3464 -356.3874)
		(end 28.575 -356.616)
		(width 0.1778)
		(layer "F.Cu")
		(net "PVDDCR_CPU1_P1_IMON1")
	)
	(segment
		(start 85.145118 -338.798916)
		(end 85.145118 -338.691474)
		(width 0.2286)
		(layer "F.Cu")
		(net "PVDDCR_CPU1_P1_IMON1")
	)
	(via
		(at 28.3464 -356.3874)
		(size 0.508)
		(drill 0.254)
		(layers "F.Cu" "B.Cu")
		(net "PVDDCR_CPU1_P1_IMON1")
	)
	(via
		(at 85.156802 -338.798916)
		(size 0.508)
		(drill 0.254)
		(layers "F.Cu" "B.Cu")
		(net "PVDDCR_CPU1_P1_IMON1")
	)
	(segment
		(start 32.065468 -354.166932)
		(end 69.228208 -354.166932)
		(width 0.254)
		(layer "In11.Cu")
		(net "PVDDCR_CPU1_P1_IMON1")
	)
	(segment
		(start 28.3464 -356.3874)
		(end 28.6258 -356.6668)
		(width 0.254)
		(layer "In11.Cu")
		(net "PVDDCR_CPU1_P1_IMON1")
	)
	(segment
		(start 83.553808 -341.601298)
		(end 84.600542 -340.554564)
		(width 0.254)
		(layer "In11.Cu")
		(net "PVDDCR_CPU1_P1_IMON1")
	)
	(segment
		(start 28.6258 -356.6668)
		(end 29.5656 -356.6668)
		(width 0.254)
		(layer "In11.Cu")
		(net "PVDDCR_CPU1_P1_IMON1")
	)
	(segment
		(start 84.600542 -340.554564)
		(end 84.600542 -339.078824)
		(width 0.254)
		(layer "In11.Cu")
		(net "PVDDCR_CPU1_P1_IMON1")
	)
	(segment
		(start 69.228208 -354.166932)
		(end 81.793842 -341.601298)
		(width 0.254)
		(layer "In11.Cu")
		(net "PVDDCR_CPU1_P1_IMON1")
	)
	(segment
		(start 81.793842 -341.601298)
		(end 83.553808 -341.601298)
		(width 0.254)
		(layer "In11.Cu")
		(net "PVDDCR_CPU1_P1_IMON1")
	)
	(segment
		(start 29.5656 -356.6668)
		(end 32.065468 -354.166932)
		(width 0.254)
		(layer "In11.Cu")
		(net "PVDDCR_CPU1_P1_IMON1")
	)
	(segment
		(start 84.88045 -338.798916)
		(end 85.156802 -338.798916)
		(width 0.254)
		(layer "In11.Cu")
		(net "PVDDCR_CPU1_P1_IMON1")
	)
	(segment
		(start 84.600542 -339.078824)
		(end 84.88045 -338.798916)
		(width 0.254)
		(layer "In11.Cu")
		(net "PVDDCR_CPU1_P1_IMON1")
	)
	(segment
		(start 25.654 -364.617)
		(end 25.16505 -364.617)
		(width 0.10668)
		(layer "F.Cu")
		(net "PVDDCR_CPU1_P1_EN_R")
	)
	(segment
		(start 26.4033 -364.744)
		(end 26.68905 -364.744)
		(width 0.10668)
		(layer "F.Cu")
		(net "PVDDCR_CPU1_P1_EN_R")
	)
	(segment
		(start 26.68905 -364.744)
		(end 26.724102 -364.708948)
		(width 0.10668)
		(layer "F.Cu")
		(net "PVDDCR_CPU1_P1_EN_R")
	)
	(segment
		(start 25.781 -364.744)
		(end 26.4033 -364.744)
		(width 0.10668)
		(layer "F.Cu")
		(net "PVDDCR_CPU1_P1_EN_R")
	)
	(segment
		(start 25.781 -364.744)
		(end 25.654 -364.617)
		(width 0.10668)
		(layer "F.Cu")
		(net "PVDDCR_CPU1_P1_EN_R")
	)
	(segment
		(start 26.724102 -364.708948)
		(end 27.604974 -364.708948)
		(width 0.10668)
		(layer "F.Cu")
		(net "PVDDCR_CPU1_P1_EN_R")
	)
	(via
		(at 25.781 -364.744)
		(size 0.508)
		(drill 0.254)
		(layers "F.Cu" "B.Cu")
		(net "PVDDCR_CPU1_P1_EN_R")
	)
	(via
		(at 26.4033 -364.744)
		(size 0.4064)
		(drill 0.2032)
		(layers "F.Cu" "B.Cu")
		(net "PVDDCR_CPU1_P1_EN_R")
	)
	(segment
		(start 25.781 -364.744)
		(end 25.654 -364.617)
		(width 0.10668)
		(layer "B.Cu")
		(net "PVDDCR_CPU1_P1_EN_R")
	)
	(segment
		(start 25.654 -364.617)
		(end 25.16505 -364.617)
		(width 0.10668)
		(layer "B.Cu")
		(net "PVDDCR_CPU1_P1_EN_R")
	)
	(segment
		(start 19.355562 -366.494822)
		(end 18.75028 -366.494822)
		(width 0.10668)
		(layer "F.Cu")
		(net "PVDDCR_CPU1_P1_EN1_ADDR_CFG")
	)
	(segment
		(start 19.558 -367.648998)
		(end 19.558 -366.69726)
		(width 0.10668)
		(layer "F.Cu")
		(net "PVDDCR_CPU1_P1_EN1_ADDR_CFG")
	)
	(segment
		(start 19.558 -366.69726)
		(end 19.355562 -366.494822)
		(width 0.10668)
		(layer "F.Cu")
		(net "PVDDCR_CPU1_P1_EN1_ADDR_CFG")
	)
	(segment
		(start 33.355026 -363.909102)
		(end 34.362898 -363.909102)
		(width 0.10668)
		(layer "F.Cu")
		(net "PVDDCR_CPU1_P1_EN1_ADDR_CFG")
	)
	(segment
		(start 34.362898 -363.909102)
		(end 34.544 -363.728)
		(width 0.10668)
		(layer "F.Cu")
		(net "PVDDCR_CPU1_P1_EN1_ADDR_CFG")
	)
	(via
		(at 33.870646 -364.401354)
		(size 0.6604)
		(drill 0.3302)
		(layers "F.Cu" "B.Cu")
		(net "PVDDCR_CPU1_P1_EN1_ADDR_CFG")
	)
	(via
		(at 34.544 -363.728)
		(size 0.508)
		(drill 0.254)
		(layers "F.Cu" "B.Cu")
		(net "PVDDCR_CPU1_P1_EN1_ADDR_CFG")
	)
	(via
		(at 18.75028 -366.494822)
		(size 0.508)
		(drill 0.254)
		(layers "F.Cu" "B.Cu")
		(net "PVDDCR_CPU1_P1_EN1_ADDR_CFG")
	)
	(segment
		(start 33.03905 -364.871)
		(end 33.401 -364.871)
		(width 0.10668)
		(layer "B.Cu")
		(net "PVDDCR_CPU1_P1_EN1_ADDR_CFG")
	)
	(segment
		(start 33.401 -364.871)
		(end 33.870646 -364.401354)
		(width 0.10668)
		(layer "B.Cu")
		(net "PVDDCR_CPU1_P1_EN1_ADDR_CFG")
	)
	(segment
		(start 33.870646 -364.401354)
		(end 34.544 -363.728)
		(width 0.10668)
		(layer "B.Cu")
		(net "PVDDCR_CPU1_P1_EN1_ADDR_CFG")
	)
	(segment
		(start 34.544 -364.868714)
		(end 34.544 -363.728)
		(width 0.11684)
		(layer "In2.Cu")
		(net "PVDDCR_CPU1_P1_EN1_ADDR_CFG")
	)
	(segment
		(start 19.326352 -366.733582)
		(end 21.085048 -368.492278)
		(width 0.11684)
		(layer "In2.Cu")
		(net "PVDDCR_CPU1_P1_EN1_ADDR_CFG")
	)
	(segment
		(start 21.085048 -368.492278)
		(end 24.032718 -368.492278)
		(width 0.11684)
		(layer "In2.Cu")
		(net "PVDDCR_CPU1_P1_EN1_ADDR_CFG")
	)
	(segment
		(start 25.96642 -366.558576)
		(end 32.854138 -366.558576)
		(width 0.11684)
		(layer "In2.Cu")
		(net "PVDDCR_CPU1_P1_EN1_ADDR_CFG")
	)
	(segment
		(start 32.854138 -366.558576)
		(end 34.544 -364.868714)
		(width 0.11684)
		(layer "In2.Cu")
		(net "PVDDCR_CPU1_P1_EN1_ADDR_CFG")
	)
	(segment
		(start 24.032718 -368.492278)
		(end 25.96642 -366.558576)
		(width 0.11684)
		(layer "In2.Cu")
		(net "PVDDCR_CPU1_P1_EN1_ADDR_CFG")
	)
	(segment
		(start 18.75028 -366.494822)
		(end 19.326352 -366.733582)
		(width 0.11684)
		(layer "In2.Cu")
		(net "PVDDCR_CPU1_P1_EN1_ADDR_CFG")
	)
	(segment
		(start 99.857814 -291.64026)
		(end 99.390962 -291.906198)
		(width 0.350012)
		(layer "F.Cu")
		(net "PVDDCR_CPU1_P1")
	)
	(segment
		(start 103.617776 -286.780478)
		(end 103.151178 -287.046162)
		(width 0.350012)
		(layer "F.Cu")
		(net "PVDDCR_CPU1_P1")
	)
	(segment
		(start 114.428016 -271.390364)
		(end 114.894614 -271.656302)
		(width 0.350012)
		(layer "F.Cu")
		(net "PVDDCR_CPU1_P1")
	)
	(segment
		(start 101.268022 -268.15034)
		(end 100.80117 -268.416278)
		(width 0.350012)
		(layer "F.Cu")
		(net "PVDDCR_CPU1_P1")
	)
	(segment
		(start 102.677976 -291.64026)
		(end 102.211124 -291.906198)
		(width 0.350012)
		(layer "F.Cu")
		(net "PVDDCR_CPU1_P1")
	)
	(segment
		(start 121.007886 -292.450266)
		(end 121.474738 -292.716204)
		(width 0.350012)
		(layer "F.Cu")
		(net "PVDDCR_CPU1_P1")
	)
	(segment
		(start 122.41784 -272.20037)
		(end 122.884692 -272.466308)
		(width 0.350012)
		(layer "F.Cu")
		(net "PVDDCR_CPU1_P1")
	)
	(segment
		(start 102.677976 -294.880284)
		(end 102.211124 -295.146222)
		(width 0.350012)
		(layer "F.Cu")
		(net "PVDDCR_CPU1_P1")
	)
	(segment
		(start 97.97796 -283.540454)
		(end 97.511108 -283.806392)
		(width 0.350012)
		(layer "F.Cu")
		(net "PVDDCR_CPU1_P1")
	)
	(segment
		(start 104.55783 -278.680418)
		(end 104.090978 -278.946356)
		(width 0.350012)
		(layer "F.Cu")
		(net "PVDDCR_CPU1_P1")
	)
	(segment
		(start 98.918014 -272.20037)
		(end 98.451162 -272.466308)
		(width 0.350012)
		(layer "F.Cu")
		(net "PVDDCR_CPU1_P1")
	)
	(segment
		(start 100.797868 -294.880284)
		(end 100.331016 -295.146222)
		(width 0.350012)
		(layer "F.Cu")
		(net "PVDDCR_CPU1_P1")
	)
	(segment
		(start 110.6678 -271.390364)
		(end 110.200948 -271.656302)
		(width 0.350012)
		(layer "F.Cu")
		(net "PVDDCR_CPU1_P1")
	)
	(segment
		(start 119.597932 -272.20037)
		(end 120.064784 -272.466308)
		(width 0.350012)
		(layer "F.Cu")
		(net "PVDDCR_CPU1_P1")
	)
	(segment
		(start 107.377992 -283.540454)
		(end 106.91114 -283.806392)
		(width 0.350012)
		(layer "F.Cu")
		(net "PVDDCR_CPU1_P1")
	)
	(segment
		(start 114.428016 -282.730448)
		(end 114.894614 -282.996386)
		(width 0.350012)
		(layer "F.Cu")
		(net "PVDDCR_CPU1_P1")
	)
	(segment
		(start 103.617776 -294.880284)
		(end 103.151178 -295.146222)
		(width 0.350012)
		(layer "F.Cu")
		(net "PVDDCR_CPU1_P1")
	)
	(segment
		(start 106.437938 -278.680418)
		(end 105.971086 -278.946356)
		(width 0.350012)
		(layer "F.Cu")
		(net "PVDDCR_CPU1_P1")
	)
	(segment
		(start 117.717824 -275.440394)
		(end 118.184676 -275.706332)
		(width 0.350012)
		(layer "F.Cu")
		(net "PVDDCR_CPU1_P1")
	)
	(segment
		(start 119.597932 -286.780478)
		(end 120.064784 -287.046162)
		(width 0.350012)
		(layer "F.Cu")
		(net "PVDDCR_CPU1_P1")
	)
	(segment
		(start 123.827794 -268.15034)
		(end 124.294646 -268.416278)
		(width 0.350012)
		(layer "F.Cu")
		(net "PVDDCR_CPU1_P1")
	)
	(segment
		(start 114.428016 -285.970472)
		(end 114.894614 -286.23641)
		(width 0.350012)
		(layer "F.Cu")
		(net "PVDDCR_CPU1_P1")
	)
	(segment
		(start 94.217998 -294.880284)
		(end 93.751146 -295.146222)
		(width 0.350012)
		(layer "F.Cu")
		(net "PVDDCR_CPU1_P1")
	)
	(segment
		(start 101.737922 -268.960346)
		(end 101.27107 -269.226284)
		(width 0.350012)
		(layer "F.Cu")
		(net "PVDDCR_CPU1_P1")
	)
	(segment
		(start 114.897916 -280.30043)
		(end 115.364768 -280.566368)
		(width 0.350012)
		(layer "F.Cu")
		(net "PVDDCR_CPU1_P1")
	)
	(segment
		(start 97.97796 -272.20037)
		(end 97.511108 -272.466308)
		(width 0.350012)
		(layer "F.Cu")
		(net "PVDDCR_CPU1_P1")
	)
	(segment
		(start 118.657878 -291.64026)
		(end 119.12473 -291.906198)
		(width 0.350012)
		(layer "F.Cu")
		(net "PVDDCR_CPU1_P1")
	)
	(segment
		(start 126.177802 -272.20037)
		(end 126.644654 -272.466308)
		(width 0.350012)
		(layer "F.Cu")
		(net "PVDDCR_CPU1_P1")
	)
	(segment
		(start 101.737922 -278.680418)
		(end 101.27107 -278.946356)
		(width 0.350012)
		(layer "F.Cu")
		(net "PVDDCR_CPU1_P1")
	)
	(segment
		(start 126.177802 -275.440394)
		(end 126.644654 -275.706332)
		(width 0.350012)
		(layer "F.Cu")
		(net "PVDDCR_CPU1_P1")
	)
	(segment
		(start 104.55783 -275.440394)
		(end 104.090978 -275.706332)
		(width 0.350012)
		(layer "F.Cu")
		(net "PVDDCR_CPU1_P1")
	)
	(segment
		(start 106.907838 -268.15034)
		(end 106.440986 -268.416278)
		(width 0.350012)
		(layer "F.Cu")
		(net "PVDDCR_CPU1_P1")
	)
	(segment
		(start 109.728 -289.210242)
		(end 109.261148 -289.47618)
		(width 0.350012)
		(layer "F.Cu")
		(net "PVDDCR_CPU1_P1")
	)
	(segment
		(start 123.357894 -283.540454)
		(end 123.824746 -283.806392)
		(width 0.350012)
		(layer "F.Cu")
		(net "PVDDCR_CPU1_P1")
	)
	(segment
		(start 110.6678 -290.830254)
		(end 110.200948 -291.096192)
		(width 0.350012)
		(layer "F.Cu")
		(net "PVDDCR_CPU1_P1")
	)
	(segment
		(start 98.918014 -268.960346)
		(end 98.451162 -269.226284)
		(width 0.350012)
		(layer "F.Cu")
		(net "PVDDCR_CPU1_P1")
	)
	(segment
		(start 104.55783 -283.540454)
		(end 104.090978 -283.806392)
		(width 0.350012)
		(layer "F.Cu")
		(net "PVDDCR_CPU1_P1")
	)
	(segment
		(start 107.377992 -278.680418)
		(end 106.91114 -278.946356)
		(width 0.350012)
		(layer "F.Cu")
		(net "PVDDCR_CPU1_P1")
	)
	(segment
		(start 117.717824 -283.540454)
		(end 118.184676 -283.806392)
		(width 0.350012)
		(layer "F.Cu")
		(net "PVDDCR_CPU1_P1")
	)
	(segment
		(start 110.1979 -280.30043)
		(end 109.731048 -280.566368)
		(width 0.350012)
		(layer "F.Cu")
		(net "PVDDCR_CPU1_P1")
	)
	(segment
		(start 98.918014 -275.440394)
		(end 98.451162 -275.706332)
		(width 0.350012)
		(layer "F.Cu")
		(net "PVDDCR_CPU1_P1")
	)
	(segment
		(start 126.177802 -278.680418)
		(end 126.644654 -278.946356)
		(width 0.350012)
		(layer "F.Cu")
		(net "PVDDCR_CPU1_P1")
	)
	(segment
		(start 126.177802 -283.540454)
		(end 126.644654 -283.806392)
		(width 0.350012)
		(layer "F.Cu")
		(net "PVDDCR_CPU1_P1")
	)
	(segment
		(start 101.268022 -266.530328)
		(end 100.80117 -266.796266)
		(width 0.350012)
		(layer "F.Cu")
		(net "PVDDCR_CPU1_P1")
	)
	(segment
		(start 111.137954 -267.340334)
		(end 110.671102 -267.606272)
		(width 0.350012)
		(layer "F.Cu")
		(net "PVDDCR_CPU1_P1")
	)
	(segment
		(start 120.537986 -278.680418)
		(end 121.004838 -278.946356)
		(width 0.350012)
		(layer "F.Cu")
		(net "PVDDCR_CPU1_P1")
	)
	(segment
		(start 113.487962 -282.730448)
		(end 113.954814 -282.996386)
		(width 0.350012)
		(layer "F.Cu")
		(net "PVDDCR_CPU1_P1")
	)
	(segment
		(start 110.6678 -282.730448)
		(end 110.200948 -282.996386)
		(width 0.350012)
		(layer "F.Cu")
		(net "PVDDCR_CPU1_P1")
	)
	(segment
		(start 100.797868 -286.780478)
		(end 100.331016 -287.046162)
		(width 0.350012)
		(layer "F.Cu")
		(net "PVDDCR_CPU1_P1")
	)
	(segment
		(start 117.247924 -281.110436)
		(end 117.714776 -281.376374)
		(width 0.350012)
		(layer "F.Cu")
		(net "PVDDCR_CPU1_P1")
	)
	(segment
		(start 120.537986 -294.880284)
		(end 121.004838 -295.146222)
		(width 0.350012)
		(layer "F.Cu")
		(net "PVDDCR_CPU1_P1")
	)
	(segment
		(start 117.717824 -294.880284)
		(end 118.184676 -295.146222)
		(width 0.350012)
		(layer "F.Cu")
		(net "PVDDCR_CPU1_P1")
	)
	(segment
		(start 124.297948 -294.880284)
		(end 124.7648 -295.146222)
		(width 0.350012)
		(layer "F.Cu")
		(net "PVDDCR_CPU1_P1")
	)
	(segment
		(start 107.377992 -275.440394)
		(end 106.91114 -275.706332)
		(width 0.350012)
		(layer "F.Cu")
		(net "PVDDCR_CPU1_P1")
	)
	(segment
		(start 113.487962 -271.390364)
		(end 113.954814 -271.656302)
		(width 0.350012)
		(layer "F.Cu")
		(net "PVDDCR_CPU1_P1")
	)
	(segment
		(start 119.597932 -267.340334)
		(end 120.064784 -267.606272)
		(width 0.350012)
		(layer "F.Cu")
		(net "PVDDCR_CPU1_P1")
	)
	(segment
		(start 101.737922 -275.440394)
		(end 101.27107 -275.706332)
		(width 0.350012)
		(layer "F.Cu")
		(net "PVDDCR_CPU1_P1")
	)
	(segment
		(start 109.728 -271.390364)
		(end 109.261148 -271.656302)
		(width 0.350012)
		(layer "F.Cu")
		(net "PVDDCR_CPU1_P1")
	)
	(segment
		(start 104.08793 -281.110436)
		(end 103.621078 -281.376374)
		(width 0.350012)
		(layer "F.Cu")
		(net "PVDDCR_CPU1_P1")
	)
	(segment
		(start 117.717824 -267.340334)
		(end 118.184676 -267.606272)
		(width 0.350012)
		(layer "F.Cu")
		(net "PVDDCR_CPU1_P1")
	)
	(segment
		(start 100.797868 -290.020248)
		(end 100.331016 -290.286186)
		(width 0.350012)
		(layer "F.Cu")
		(net "PVDDCR_CPU1_P1")
	)
	(segment
		(start 116.30787 -268.15034)
		(end 116.774722 -268.416278)
		(width 0.350012)
		(layer "F.Cu")
		(net "PVDDCR_CPU1_P1")
	)
	(segment
		(start 110.6678 -289.210242)
		(end 110.200948 -289.47618)
		(width 0.350012)
		(layer "F.Cu")
		(net "PVDDCR_CPU1_P1")
	)
	(segment
		(start 120.537986 -286.780478)
		(end 121.004584 -287.046162)
		(width 0.350012)
		(layer "F.Cu")
		(net "PVDDCR_CPU1_P1")
	)
	(segment
		(start 97.97796 -275.440394)
		(end 97.511108 -275.706332)
		(width 0.350012)
		(layer "F.Cu")
		(net "PVDDCR_CPU1_P1")
	)
	(segment
		(start 109.728 -285.970472)
		(end 109.261148 -286.23641)
		(width 0.350012)
		(layer "F.Cu")
		(net "PVDDCR_CPU1_P1")
	)
	(segment
		(start 114.428016 -277.870412)
		(end 114.894614 -278.13635)
		(width 0.350012)
		(layer "F.Cu")
		(net "PVDDCR_CPU1_P1")
	)
	(segment
		(start 127.117856 -294.880284)
		(end 127.584708 -295.146222)
		(width 0.350012)
		(layer "F.Cu")
		(net "PVDDCR_CPU1_P1")
	)
	(segment
		(start 118.187978 -292.450266)
		(end 118.65483 -292.716204)
		(width 0.350012)
		(layer "F.Cu")
		(net "PVDDCR_CPU1_P1")
	)
	(segment
		(start 119.597932 -290.020248)
		(end 120.064784 -290.286186)
		(width 0.350012)
		(layer "F.Cu")
		(net "PVDDCR_CPU1_P1")
	)
	(segment
		(start 104.55783 -272.20037)
		(end 104.090978 -272.466308)
		(width 0.350012)
		(layer "F.Cu")
		(net "PVDDCR_CPU1_P1")
	)
	(segment
		(start 105.497884 -291.64026)
		(end 105.031032 -291.906198)
		(width 0.350012)
		(layer "F.Cu")
		(net "PVDDCR_CPU1_P1")
	)
	(segment
		(start 97.97796 -286.780478)
		(end 97.511108 -287.046162)
		(width 0.350012)
		(layer "F.Cu")
		(net "PVDDCR_CPU1_P1")
	)
	(segment
		(start 125.238002 -267.340334)
		(end 125.704854 -267.606272)
		(width 0.350012)
		(layer "F.Cu")
		(net "PVDDCR_CPU1_P1")
	)
	(segment
		(start 114.428016 -268.15034)
		(end 114.894614 -268.416278)
		(width 0.350012)
		(layer "F.Cu")
		(net "PVDDCR_CPU1_P1")
	)
	(segment
		(start 115.367816 -292.450266)
		(end 115.834668 -292.716204)
		(width 0.350012)
		(layer "F.Cu")
		(net "PVDDCR_CPU1_P1")
	)
	(segment
		(start 128.997964 -294.880284)
		(end 129.464816 -295.146222)
		(width 0.350012)
		(layer "F.Cu")
		(net "PVDDCR_CPU1_P1")
	)
	(segment
		(start 97.97796 -278.680418)
		(end 97.511108 -278.946356)
		(width 0.350012)
		(layer "F.Cu")
		(net "PVDDCR_CPU1_P1")
	)
	(segment
		(start 119.597932 -268.960346)
		(end 120.064784 -269.226284)
		(width 0.350012)
		(layer "F.Cu")
		(net "PVDDCR_CPU1_P1")
	)
	(segment
		(start 120.067832 -281.110436)
		(end 120.534684 -281.376374)
		(width 0.350012)
		(layer "F.Cu")
		(net "PVDDCR_CPU1_P1")
	)
	(segment
		(start 126.177802 -268.960346)
		(end 126.644654 -269.226284)
		(width 0.350012)
		(layer "F.Cu")
		(net "PVDDCR_CPU1_P1")
	)
	(segment
		(start 104.55783 -286.780478)
		(end 104.090978 -287.046162)
		(width 0.350012)
		(layer "F.Cu")
		(net "PVDDCR_CPU1_P1")
	)
	(segment
		(start 98.918014 -278.680418)
		(end 98.451162 -278.946356)
		(width 0.350012)
		(layer "F.Cu")
		(net "PVDDCR_CPU1_P1")
	)
	(segment
		(start 123.357894 -286.780478)
		(end 123.824746 -287.046162)
		(width 0.350012)
		(layer "F.Cu")
		(net "PVDDCR_CPU1_P1")
	)
	(segment
		(start 104.55783 -290.020248)
		(end 104.090978 -290.286186)
		(width 0.350012)
		(layer "F.Cu")
		(net "PVDDCR_CPU1_P1")
	)
	(segment
		(start 120.537986 -268.960346)
		(end 121.004838 -269.226284)
		(width 0.350012)
		(layer "F.Cu")
		(net "PVDDCR_CPU1_P1")
	)
	(segment
		(start 107.377992 -272.20037)
		(end 106.91114 -272.466308)
		(width 0.350012)
		(layer "F.Cu")
		(net "PVDDCR_CPU1_P1")
	)
	(segment
		(start 123.357894 -267.340334)
		(end 123.824746 -267.606272)
		(width 0.350012)
		(layer "F.Cu")
		(net "PVDDCR_CPU1_P1")
	)
	(segment
		(start 115.83797 -294.880284)
		(end 116.304822 -295.146222)
		(width 0.350012)
		(layer "F.Cu")
		(net "PVDDCR_CPU1_P1")
	)
	(segment
		(start 106.437938 -275.440394)
		(end 105.971086 -275.706332)
		(width 0.350012)
		(layer "F.Cu")
		(net "PVDDCR_CPU1_P1")
	)
	(segment
		(start 117.717824 -272.20037)
		(end 118.184676 -272.466308)
		(width 0.350012)
		(layer "F.Cu")
		(net "PVDDCR_CPU1_P1")
	)
	(segment
		(start 115.83797 -267.340334)
		(end 116.304822 -267.606272)
		(width 0.350012)
		(layer "F.Cu")
		(net "PVDDCR_CPU1_P1")
	)
	(segment
		(start 113.487962 -285.970472)
		(end 113.954814 -286.23641)
		(width 0.350012)
		(layer "F.Cu")
		(net "PVDDCR_CPU1_P1")
	)
	(segment
		(start 129.467864 -294.070278)
		(end 129.934716 -294.336216)
		(width 0.350012)
		(layer "F.Cu")
		(net "PVDDCR_CPU1_P1")
	)
	(segment
		(start 123.357894 -275.440394)
		(end 123.824746 -275.706332)
		(width 0.350012)
		(layer "F.Cu")
		(net "PVDDCR_CPU1_P1")
	)
	(segment
		(start 114.428016 -274.630388)
		(end 114.894614 -274.896326)
		(width 0.350012)
		(layer "F.Cu")
		(net "PVDDCR_CPU1_P1")
	)
	(segment
		(start 100.327968 -292.450266)
		(end 99.861116 -292.716204)
		(width 0.350012)
		(layer "F.Cu")
		(net "PVDDCR_CPU1_P1")
	)
	(segment
		(start 125.238002 -283.540454)
		(end 125.704854 -283.806392)
		(width 0.350012)
		(layer "F.Cu")
		(net "PVDDCR_CPU1_P1")
	)
	(segment
		(start 124.297948 -291.64026)
		(end 124.7648 -291.906198)
		(width 0.350012)
		(layer "F.Cu")
		(net "PVDDCR_CPU1_P1")
	)
	(segment
		(start 103.617776 -290.020248)
		(end 103.151178 -290.286186)
		(width 0.350012)
		(layer "F.Cu")
		(net "PVDDCR_CPU1_P1")
	)
	(segment
		(start 98.918014 -283.540454)
		(end 98.451162 -283.806392)
		(width 0.350012)
		(layer "F.Cu")
		(net "PVDDCR_CPU1_P1")
	)
	(segment
		(start 97.97796 -290.020248)
		(end 97.511108 -290.286186)
		(width 0.350012)
		(layer "F.Cu")
		(net "PVDDCR_CPU1_P1")
	)
	(segment
		(start 125.238002 -278.680418)
		(end 125.704854 -278.946356)
		(width 0.350012)
		(layer "F.Cu")
		(net "PVDDCR_CPU1_P1")
	)
	(segment
		(start 100.797868 -283.540454)
		(end 100.331016 -283.806392)
		(width 0.350012)
		(layer "F.Cu")
		(net "PVDDCR_CPU1_P1")
	)
	(segment
		(start 114.428016 -266.530328)
		(end 114.894614 -266.796266)
		(width 0.350012)
		(layer "F.Cu")
		(net "PVDDCR_CPU1_P1")
	)
	(segment
		(start 120.537986 -275.440394)
		(end 121.004838 -275.706332)
		(width 0.350012)
		(layer "F.Cu")
		(net "PVDDCR_CPU1_P1")
	)
	(segment
		(start 100.797868 -268.960346)
		(end 100.331016 -269.226284)
		(width 0.350012)
		(layer "F.Cu")
		(net "PVDDCR_CPU1_P1")
	)
	(segment
		(start 97.507806 -292.450266)
		(end 97.040954 -292.716204)
		(width 0.350012)
		(layer "F.Cu")
		(net "PVDDCR_CPU1_P1")
	)
	(segment
		(start 108.787946 -268.15034)
		(end 108.321094 -268.416278)
		(width 0.350012)
		(layer "F.Cu")
		(net "PVDDCR_CPU1_P1")
	)
	(segment
		(start 108.787946 -266.530328)
		(end 108.321094 -266.796266)
		(width 0.350012)
		(layer "F.Cu")
		(net "PVDDCR_CPU1_P1")
	)
	(segment
		(start 115.83797 -291.64026)
		(end 116.304822 -291.906198)
		(width 0.350012)
		(layer "F.Cu")
		(net "PVDDCR_CPU1_P1")
	)
	(segment
		(start 109.257846 -280.30043)
		(end 108.790994 -280.566368)
		(width 0.350012)
		(layer "F.Cu")
		(net "PVDDCR_CPU1_P1")
	)
	(segment
		(start 99.387914 -268.15034)
		(end 98.921062 -268.416278)
		(width 0.350012)
		(layer "F.Cu")
		(net "PVDDCR_CPU1_P1")
	)
	(segment
		(start 123.357894 -278.680418)
		(end 123.824746 -278.946356)
		(width 0.350012)
		(layer "F.Cu")
		(net "PVDDCR_CPU1_P1")
	)
	(segment
		(start 110.6678 -277.870412)
		(end 110.200948 -278.13635)
		(width 0.350012)
		(layer "F.Cu")
		(net "PVDDCR_CPU1_P1")
	)
	(segment
		(start 121.477786 -267.340334)
		(end 121.944638 -267.606272)
		(width 0.350012)
		(layer "F.Cu")
		(net "PVDDCR_CPU1_P1")
	)
	(segment
		(start 118.187978 -268.15034)
		(end 118.65483 -268.416278)
		(width 0.350012)
		(layer "F.Cu")
		(net "PVDDCR_CPU1_P1")
	)
	(segment
		(start 103.147876 -268.15034)
		(end 102.681024 -268.416278)
		(width 0.350012)
		(layer "F.Cu")
		(net "PVDDCR_CPU1_P1")
	)
	(segment
		(start 129.938018 -294.880284)
		(end 130.40487 -295.146222)
		(width 0.350012)
		(layer "F.Cu")
		(net "PVDDCR_CPU1_P1")
	)
	(segment
		(start 109.257846 -267.340334)
		(end 108.790994 -267.606272)
		(width 0.350012)
		(layer "F.Cu")
		(net "PVDDCR_CPU1_P1")
	)
	(segment
		(start 116.77777 -286.780478)
		(end 117.244622 -287.046162)
		(width 0.350012)
		(layer "F.Cu")
		(net "PVDDCR_CPU1_P1")
	)
	(segment
		(start 106.907838 -281.110436)
		(end 106.440986 -281.376374)
		(width 0.350012)
		(layer "F.Cu")
		(net "PVDDCR_CPU1_P1")
	)
	(segment
		(start 101.737922 -272.20037)
		(end 101.27107 -272.466308)
		(width 0.350012)
		(layer "F.Cu")
		(net "PVDDCR_CPU1_P1")
	)
	(segment
		(start 94.687898 -294.070278)
		(end 94.221046 -294.336216)
		(width 0.350012)
		(layer "F.Cu")
		(net "PVDDCR_CPU1_P1")
	)
	(segment
		(start 113.487962 -290.830254)
		(end 113.954814 -291.096192)
		(width 0.350012)
		(layer "F.Cu")
		(net "PVDDCR_CPU1_P1")
	)
	(segment
		(start 120.537986 -290.020248)
		(end 121.004838 -290.286186)
		(width 0.350012)
		(layer "F.Cu")
		(net "PVDDCR_CPU1_P1")
	)
	(segment
		(start 107.377992 -290.020248)
		(end 106.91114 -290.286186)
		(width 0.350012)
		(layer "F.Cu")
		(net "PVDDCR_CPU1_P1")
	)
	(segment
		(start 114.428016 -289.210242)
		(end 114.894614 -289.47618)
		(width 0.350012)
		(layer "F.Cu")
		(net "PVDDCR_CPU1_P1")
	)
	(segment
		(start 123.357894 -272.20037)
		(end 123.824746 -272.466308)
		(width 0.350012)
		(layer "F.Cu")
		(net "PVDDCR_CPU1_P1")
	)
	(segment
		(start 114.897916 -294.880284)
		(end 115.364768 -295.146222)
		(width 0.350012)
		(layer "F.Cu")
		(net "PVDDCR_CPU1_P1")
	)
	(segment
		(start 118.657878 -294.880284)
		(end 119.12473 -295.146222)
		(width 0.350012)
		(layer "F.Cu")
		(net "PVDDCR_CPU1_P1")
	)
	(segment
		(start 118.187978 -266.530328)
		(end 118.65483 -266.796266)
		(width 0.350012)
		(layer "F.Cu")
		(net "PVDDCR_CPU1_P1")
	)
	(segment
		(start 113.487962 -289.210242)
		(end 113.954814 -289.47618)
		(width 0.350012)
		(layer "F.Cu")
		(net "PVDDCR_CPU1_P1")
	)
	(segment
		(start 97.97796 -268.960346)
		(end 97.511108 -269.226284)
		(width 0.350012)
		(layer "F.Cu")
		(net "PVDDCR_CPU1_P1")
	)
	(segment
		(start 116.30787 -281.110436)
		(end 116.774722 -281.376374)
		(width 0.350012)
		(layer "F.Cu")
		(net "PVDDCR_CPU1_P1")
	)
	(segment
		(start 107.377992 -268.960346)
		(end 106.91114 -269.226284)
		(width 0.350012)
		(layer "F.Cu")
		(net "PVDDCR_CPU1_P1")
	)
	(segment
		(start 123.357894 -290.020248)
		(end 123.824746 -290.286186)
		(width 0.350012)
		(layer "F.Cu")
		(net "PVDDCR_CPU1_P1")
	)
	(segment
		(start 126.177802 -286.780478)
		(end 126.644654 -287.046162)
		(width 0.350012)
		(layer "F.Cu")
		(net "PVDDCR_CPU1_P1")
	)
	(segment
		(start 122.41784 -278.680418)
		(end 122.884692 -278.946356)
		(width 0.350012)
		(layer "F.Cu")
		(net "PVDDCR_CPU1_P1")
	)
	(segment
		(start 105.967784 -292.450266)
		(end 105.500932 -292.716204)
		(width 0.350012)
		(layer "F.Cu")
		(net "PVDDCR_CPU1_P1")
	)
	(segment
		(start 125.707902 -268.15034)
		(end 126.174754 -268.416278)
		(width 0.350012)
		(layer "F.Cu")
		(net "PVDDCR_CPU1_P1")
	)
	(segment
		(start 103.147876 -292.450266)
		(end 102.681024 -292.716204)
		(width 0.350012)
		(layer "F.Cu")
		(net "PVDDCR_CPU1_P1")
	)
	(segment
		(start 126.177802 -290.020248)
		(end 126.644654 -290.286186)
		(width 0.350012)
		(layer "F.Cu")
		(net "PVDDCR_CPU1_P1")
	)
	(segment
		(start 116.77777 -275.440394)
		(end 117.244622 -275.706332)
		(width 0.350012)
		(layer "F.Cu")
		(net "PVDDCR_CPU1_P1")
	)
	(segment
		(start 123.827794 -292.450266)
		(end 124.294646 -292.716204)
		(width 0.350012)
		(layer "F.Cu")
		(net "PVDDCR_CPU1_P1")
	)
	(segment
		(start 113.957862 -280.30043)
		(end 114.424714 -280.566368)
		(width 0.350012)
		(layer "F.Cu")
		(net "PVDDCR_CPU1_P1")
	)
	(segment
		(start 116.77777 -283.540454)
		(end 117.244622 -283.806392)
		(width 0.350012)
		(layer "F.Cu")
		(net "PVDDCR_CPU1_P1")
	)
	(segment
		(start 109.728 -290.830254)
		(end 109.261148 -291.096192)
		(width 0.350012)
		(layer "F.Cu")
		(net "PVDDCR_CPU1_P1")
	)
	(segment
		(start 117.717824 -268.960346)
		(end 118.184676 -269.226284)
		(width 0.350012)
		(layer "F.Cu")
		(net "PVDDCR_CPU1_P1")
	)
	(segment
		(start 103.617776 -272.20037)
		(end 103.151178 -272.466308)
		(width 0.350012)
		(layer "F.Cu")
		(net "PVDDCR_CPU1_P1")
	)
	(segment
		(start 121.477786 -291.64026)
		(end 121.944638 -291.906198)
		(width 0.350012)
		(layer "F.Cu")
		(net "PVDDCR_CPU1_P1")
	)
	(segment
		(start 119.597932 -275.440394)
		(end 120.064784 -275.706332)
		(width 0.350012)
		(layer "F.Cu")
		(net "PVDDCR_CPU1_P1")
	)
	(segment
		(start 127.117856 -291.64026)
		(end 127.584708 -291.906198)
		(width 0.350012)
		(layer "F.Cu")
		(net "PVDDCR_CPU1_P1")
	)
	(segment
		(start 116.77777 -278.680418)
		(end 117.244622 -278.946356)
		(width 0.350012)
		(layer "F.Cu")
		(net "PVDDCR_CPU1_P1")
	)
	(segment
		(start 117.717824 -278.680418)
		(end 118.184676 -278.946356)
		(width 0.350012)
		(layer "F.Cu")
		(net "PVDDCR_CPU1_P1")
	)
	(segment
		(start 109.728 -274.630388)
		(end 109.261148 -274.896326)
		(width 0.350012)
		(layer "F.Cu")
		(net "PVDDCR_CPU1_P1")
	)
	(segment
		(start 103.617776 -283.540454)
		(end 103.151178 -283.806392)
		(width 0.350012)
		(layer "F.Cu")
		(net "PVDDCR_CPU1_P1")
	)
	(segment
		(start 113.487962 -277.870412)
		(end 113.954814 -278.13635)
		(width 0.350012)
		(layer "F.Cu")
		(net "PVDDCR_CPU1_P1")
	)
	(segment
		(start 119.597932 -278.680418)
		(end 120.064784 -278.946356)
		(width 0.350012)
		(layer "F.Cu")
		(net "PVDDCR_CPU1_P1")
	)
	(segment
		(start 107.377992 -286.780478)
		(end 106.91114 -287.046162)
		(width 0.350012)
		(layer "F.Cu")
		(net "PVDDCR_CPU1_P1")
	)
	(segment
		(start 114.428016 -292.450266)
		(end 114.894614 -292.716204)
		(width 0.350012)
		(layer "F.Cu")
		(net "PVDDCR_CPU1_P1")
	)
	(segment
		(start 108.787946 -292.450266)
		(end 108.321094 -292.716204)
		(width 0.350012)
		(layer "F.Cu")
		(net "PVDDCR_CPU1_P1")
	)
	(segment
		(start 117.717824 -290.020248)
		(end 118.184676 -290.286186)
		(width 0.350012)
		(layer "F.Cu")
		(net "PVDDCR_CPU1_P1")
	)
	(segment
		(start 113.487962 -274.630388)
		(end 113.954814 -274.896326)
		(width 0.350012)
		(layer "F.Cu")
		(net "PVDDCR_CPU1_P1")
	)
	(segment
		(start 109.257846 -294.880284)
		(end 108.790994 -295.146222)
		(width 0.350012)
		(layer "F.Cu")
		(net "PVDDCR_CPU1_P1")
	)
	(segment
		(start 126.647956 -292.450266)
		(end 127.114808 -292.716204)
		(width 0.350012)
		(layer "F.Cu")
		(net "PVDDCR_CPU1_P1")
	)
	(segment
		(start 125.238002 -286.780478)
		(end 125.704854 -287.046162)
		(width 0.350012)
		(layer "F.Cu")
		(net "PVDDCR_CPU1_P1")
	)
	(segment
		(start 116.77777 -268.960346)
		(end 117.244622 -269.226284)
		(width 0.350012)
		(layer "F.Cu")
		(net "PVDDCR_CPU1_P1")
	)
	(segment
		(start 105.497884 -294.880284)
		(end 105.031032 -295.146222)
		(width 0.350012)
		(layer "F.Cu")
		(net "PVDDCR_CPU1_P1")
	)
	(segment
		(start 106.437938 -272.20037)
		(end 105.971086 -272.466308)
		(width 0.350012)
		(layer "F.Cu")
		(net "PVDDCR_CPU1_P1")
	)
	(segment
		(start 105.027984 -268.15034)
		(end 104.561132 -268.416278)
		(width 0.350012)
		(layer "F.Cu")
		(net "PVDDCR_CPU1_P1")
	)
	(segment
		(start 101.737922 -267.340334)
		(end 101.27107 -267.606272)
		(width 0.350012)
		(layer "F.Cu")
		(net "PVDDCR_CPU1_P1")
	)
	(segment
		(start 122.41784 -283.540454)
		(end 122.884692 -283.806392)
		(width 0.350012)
		(layer "F.Cu")
		(net "PVDDCR_CPU1_P1")
	)
	(segment
		(start 103.617776 -275.440394)
		(end 103.151178 -275.706332)
		(width 0.350012)
		(layer "F.Cu")
		(net "PVDDCR_CPU1_P1")
	)
	(segment
		(start 105.027984 -266.530328)
		(end 104.561132 -266.796266)
		(width 0.350012)
		(layer "F.Cu")
		(net "PVDDCR_CPU1_P1")
	)
	(segment
		(start 121.94794 -266.530328)
		(end 122.414792 -266.796266)
		(width 0.350012)
		(layer "F.Cu")
		(net "PVDDCR_CPU1_P1")
	)
	(segment
		(start 117.717824 -286.780478)
		(end 118.184676 -287.046162)
		(width 0.350012)
		(layer "F.Cu")
		(net "PVDDCR_CPU1_P1")
	)
	(segment
		(start 97.97796 -294.880284)
		(end 97.511108 -295.146222)
		(width 0.350012)
		(layer "F.Cu")
		(net "PVDDCR_CPU1_P1")
	)
	(segment
		(start 125.238002 -275.440394)
		(end 125.704854 -275.706332)
		(width 0.350012)
		(layer "F.Cu")
		(net "PVDDCR_CPU1_P1")
	)
	(segment
		(start 101.737922 -290.020248)
		(end 101.27107 -290.286186)
		(width 0.350012)
		(layer "F.Cu")
		(net "PVDDCR_CPU1_P1")
	)
	(segment
		(start 98.918014 -290.020248)
		(end 98.451162 -290.286186)
		(width 0.350012)
		(layer "F.Cu")
		(net "PVDDCR_CPU1_P1")
	)
	(segment
		(start 119.597932 -283.540454)
		(end 120.064784 -283.806392)
		(width 0.350012)
		(layer "F.Cu")
		(net "PVDDCR_CPU1_P1")
	)
	(segment
		(start 120.067832 -268.15034)
		(end 120.534684 -268.416278)
		(width 0.350012)
		(layer "F.Cu")
		(net "PVDDCR_CPU1_P1")
	)
	(segment
		(start 125.238002 -290.020248)
		(end 125.704854 -290.286186)
		(width 0.350012)
		(layer "F.Cu")
		(net "PVDDCR_CPU1_P1")
	)
	(segment
		(start 125.238002 -268.960346)
		(end 125.704854 -269.226284)
		(width 0.350012)
		(layer "F.Cu")
		(net "PVDDCR_CPU1_P1")
	)
	(segment
		(start 103.617776 -268.960346)
		(end 103.151178 -269.226284)
		(width 0.350012)
		(layer "F.Cu")
		(net "PVDDCR_CPU1_P1")
	)
	(segment
		(start 107.377992 -267.340334)
		(end 106.91114 -267.606272)
		(width 0.350012)
		(layer "F.Cu")
		(net "PVDDCR_CPU1_P1")
	)
	(segment
		(start 98.918014 -286.780478)
		(end 98.451162 -287.046162)
		(width 0.350012)
		(layer "F.Cu")
		(net "PVDDCR_CPU1_P1")
	)
	(segment
		(start 120.537986 -272.20037)
		(end 121.004838 -272.466308)
		(width 0.350012)
		(layer "F.Cu")
		(net "PVDDCR_CPU1_P1")
	)
	(segment
		(start 125.238002 -272.20037)
		(end 125.704854 -272.466308)
		(width 0.350012)
		(layer "F.Cu")
		(net "PVDDCR_CPU1_P1")
	)
	(segment
		(start 121.94794 -268.15034)
		(end 122.414792 -268.416278)
		(width 0.350012)
		(layer "F.Cu")
		(net "PVDDCR_CPU1_P1")
	)
	(segment
		(start 110.6678 -285.970472)
		(end 110.200948 -286.23641)
		(width 0.350012)
		(layer "F.Cu")
		(net "PVDDCR_CPU1_P1")
	)
	(segment
		(start 100.797868 -278.680418)
		(end 100.331016 -278.946356)
		(width 0.350012)
		(layer "F.Cu")
		(net "PVDDCR_CPU1_P1")
	)
	(segment
		(start 101.737922 -286.780478)
		(end 101.27107 -287.046162)
		(width 0.350012)
		(layer "F.Cu")
		(net "PVDDCR_CPU1_P1")
	)
	(segment
		(start 108.317792 -291.64026)
		(end 107.85094 -291.906198)
		(width 0.350012)
		(layer "F.Cu")
		(net "PVDDCR_CPU1_P1")
	)
	(segment
		(start 121.477786 -294.880284)
		(end 121.944638 -295.146222)
		(width 0.350012)
		(layer "F.Cu")
		(net "PVDDCR_CPU1_P1")
	)
	(segment
		(start 122.41784 -268.960346)
		(end 122.884692 -269.226284)
		(width 0.350012)
		(layer "F.Cu")
		(net "PVDDCR_CPU1_P1")
	)
	(segment
		(start 106.437938 -290.020248)
		(end 105.971086 -290.286186)
		(width 0.350012)
		(layer "F.Cu")
		(net "PVDDCR_CPU1_P1")
	)
	(segment
		(start 109.728 -292.450266)
		(end 109.261148 -292.716204)
		(width 0.350012)
		(layer "F.Cu")
		(net "PVDDCR_CPU1_P1")
	)
	(segment
		(start 114.428016 -290.830254)
		(end 114.894614 -291.096192)
		(width 0.350012)
		(layer "F.Cu")
		(net "PVDDCR_CPU1_P1")
	)
	(segment
		(start 97.037906 -291.64026)
		(end 96.571054 -291.906198)
		(width 0.350012)
		(layer "F.Cu")
		(net "PVDDCR_CPU1_P1")
	)
	(segment
		(start 100.797868 -275.440394)
		(end 100.331016 -275.706332)
		(width 0.350012)
		(layer "F.Cu")
		(net "PVDDCR_CPU1_P1")
	)
	(segment
		(start 106.437938 -286.780478)
		(end 105.971086 -287.046162)
		(width 0.350012)
		(layer "F.Cu")
		(net "PVDDCR_CPU1_P1")
	)
	(segment
		(start 100.797868 -272.20037)
		(end 100.331016 -272.466308)
		(width 0.350012)
		(layer "F.Cu")
		(net "PVDDCR_CPU1_P1")
	)
	(segment
		(start 122.41784 -275.440394)
		(end 122.884692 -275.706332)
		(width 0.350012)
		(layer "F.Cu")
		(net "PVDDCR_CPU1_P1")
	)
	(segment
		(start 104.55783 -268.960346)
		(end 104.090978 -269.226284)
		(width 0.350012)
		(layer "F.Cu")
		(net "PVDDCR_CPU1_P1")
	)
	(segment
		(start 106.437938 -283.540454)
		(end 105.971086 -283.806392)
		(width 0.350012)
		(layer "F.Cu")
		(net "PVDDCR_CPU1_P1")
	)
	(segment
		(start 107.847892 -281.110436)
		(end 107.38104 -281.376374)
		(width 0.350012)
		(layer "F.Cu")
		(net "PVDDCR_CPU1_P1")
	)
	(segment
		(start 101.737922 -283.540454)
		(end 101.27107 -283.806392)
		(width 0.350012)
		(layer "F.Cu")
		(net "PVDDCR_CPU1_P1")
	)
	(segment
		(start 116.77777 -290.020248)
		(end 117.244622 -290.286186)
		(width 0.350012)
		(layer "F.Cu")
		(net "PVDDCR_CPU1_P1")
	)
	(segment
		(start 109.728 -277.870412)
		(end 109.261148 -278.13635)
		(width 0.350012)
		(layer "F.Cu")
		(net "PVDDCR_CPU1_P1")
	)
	(segment
		(start 95.157798 -294.880284)
		(end 94.690946 -295.146222)
		(width 0.350012)
		(layer "F.Cu")
		(net "PVDDCR_CPU1_P1")
	)
	(segment
		(start 105.027984 -281.110436)
		(end 104.561132 -281.376374)
		(width 0.350012)
		(layer "F.Cu")
		(net "PVDDCR_CPU1_P1")
	)
	(segment
		(start 123.357894 -268.960346)
		(end 123.824746 -269.226284)
		(width 0.350012)
		(layer "F.Cu")
		(net "PVDDCR_CPU1_P1")
	)
	(segment
		(start 110.6678 -274.630388)
		(end 110.200948 -274.896326)
		(width 0.350012)
		(layer "F.Cu")
		(net "PVDDCR_CPU1_P1")
	)
	(segment
		(start 116.77777 -272.20037)
		(end 117.244622 -272.466308)
		(width 0.350012)
		(layer "F.Cu")
		(net "PVDDCR_CPU1_P1")
	)
	(segment
		(start 99.857814 -294.880284)
		(end 99.390962 -295.146222)
		(width 0.350012)
		(layer "F.Cu")
		(net "PVDDCR_CPU1_P1")
	)
	(segment
		(start 122.41784 -286.780478)
		(end 122.884692 -287.046162)
		(width 0.350012)
		(layer "F.Cu")
		(net "PVDDCR_CPU1_P1")
	)
	(segment
		(start 106.437938 -294.880284)
		(end 105.971086 -295.146222)
		(width 0.350012)
		(layer "F.Cu")
		(net "PVDDCR_CPU1_P1")
	)
	(segment
		(start 103.617776 -278.680418)
		(end 103.151178 -278.946356)
		(width 0.350012)
		(layer "F.Cu")
		(net "PVDDCR_CPU1_P1")
	)
	(segment
		(start 109.728 -282.730448)
		(end 109.261148 -282.996386)
		(width 0.350012)
		(layer "F.Cu")
		(net "PVDDCR_CPU1_P1")
	)
	(segment
		(start 105.497884 -267.340334)
		(end 105.031032 -267.606272)
		(width 0.350012)
		(layer "F.Cu")
		(net "PVDDCR_CPU1_P1")
	)
	(segment
		(start 113.957862 -267.340334)
		(end 114.424714 -267.606272)
		(width 0.350012)
		(layer "F.Cu")
		(net "PVDDCR_CPU1_P1")
	)
	(segment
		(start 106.437938 -268.960346)
		(end 105.971086 -269.226284)
		(width 0.350012)
		(layer "F.Cu")
		(net "PVDDCR_CPU1_P1")
	)
	(segment
		(start 126.177802 -294.880284)
		(end 126.644654 -295.146222)
		(width 0.350012)
		(layer "F.Cu")
		(net "PVDDCR_CPU1_P1")
	)
	(segment
		(start 123.357894 -294.880284)
		(end 123.824746 -295.146222)
		(width 0.350012)
		(layer "F.Cu")
		(net "PVDDCR_CPU1_P1")
	)
	(segment
		(start 119.127778 -281.110436)
		(end 119.59463 -281.376374)
		(width 0.350012)
		(layer "F.Cu")
		(net "PVDDCR_CPU1_P1")
	)
	(segment
		(start 122.41784 -290.020248)
		(end 122.884692 -290.286186)
		(width 0.350012)
		(layer "F.Cu")
		(net "PVDDCR_CPU1_P1")
	)
	(segment
		(start 103.617776 -267.340334)
		(end 103.151178 -267.606272)
		(width 0.350012)
		(layer "F.Cu")
		(net "PVDDCR_CPU1_P1")
	)
	(segment
		(start 108.317792 -294.880284)
		(end 107.85094 -295.146222)
		(width 0.350012)
		(layer "F.Cu")
		(net "PVDDCR_CPU1_P1")
	)
	(segment
		(start 110.6678 -268.15034)
		(end 110.200948 -268.416278)
		(width 0.350012)
		(layer "F.Cu")
		(net "PVDDCR_CPU1_P1")
	)
	(segment
		(start 120.537986 -283.540454)
		(end 121.004838 -283.806392)
		(width 0.350012)
		(layer "F.Cu")
		(net "PVDDCR_CPU1_P1")
	)
	(segment
		(start 97.037906 -294.880284)
		(end 96.571054 -295.146222)
		(width 0.350012)
		(layer "F.Cu")
		(net "PVDDCR_CPU1_P1")
	)
	(via
		(at 97.500694 -322.378324)
		(size 0.508)
		(drill 0.254)
		(layers "F.Cu" "B.Cu")
		(net "PVDDCR_CPU1_P1")
	)
	(via
		(at 117.244622 -269.226284)
		(size 0.4064)
		(drill 0.2032)
		(layers "F.Cu" "B.Cu")
		(net "PVDDCR_CPU1_P1")
	)
	(via
		(at 80.889094 -321.093846)
		(size 0.508)
		(drill 0.254)
		(layers "F.Cu" "B.Cu")
		(net "PVDDCR_CPU1_P1")
	)
	(via
		(at 96.865694 -318.563752)
		(size 0.508)
		(drill 0.254)
		(layers "F.Cu" "B.Cu")
		(net "PVDDCR_CPU1_P1")
	)
	(via
		(at 109.261148 -282.996386)
		(size 0.4064)
		(drill 0.2032)
		(layers "F.Cu" "B.Cu")
		(net "PVDDCR_CPU1_P1")
	)
	(via
		(at 110.200948 -286.23641)
		(size 0.4064)
		(drill 0.2032)
		(layers "F.Cu" "B.Cu")
		(net "PVDDCR_CPU1_P1")
	)
	(via
		(at 124.294646 -292.716204)
		(size 0.4064)
		(drill 0.2032)
		(layers "F.Cu" "B.Cu")
		(net "PVDDCR_CPU1_P1")
	)
	(via
		(at 59.17311 -332.83652)
		(size 0.508)
		(drill 0.254)
		(layers "F.Cu" "B.Cu")
		(net "PVDDCR_CPU1_P1")
	)
	(via
		(at 85.20811 -318.549274)
		(size 0.508)
		(drill 0.254)
		(layers "F.Cu" "B.Cu")
		(net "PVDDCR_CPU1_P1")
	)
	(via
		(at 59.80811 -332.20152)
		(size 0.508)
		(drill 0.254)
		(layers "F.Cu" "B.Cu")
		(net "PVDDCR_CPU1_P1")
	)
	(via
		(at 113.954814 -289.47618)
		(size 0.4064)
		(drill 0.2032)
		(layers "F.Cu" "B.Cu")
		(net "PVDDCR_CPU1_P1")
	)
	(via
		(at 126.644654 -290.286186)
		(size 0.4064)
		(drill 0.2032)
		(layers "F.Cu" "B.Cu")
		(net "PVDDCR_CPU1_P1")
	)
	(via
		(at 81.524094 -318.549274)
		(size 0.508)
		(drill 0.254)
		(layers "F.Cu" "B.Cu")
		(net "PVDDCR_CPU1_P1")
	)
	(via
		(at 121.004838 -295.146222)
		(size 0.4064)
		(drill 0.2032)
		(layers "F.Cu" "B.Cu")
		(net "PVDDCR_CPU1_P1")
	)
	(via
		(at 84.57311 -316.644274)
		(size 0.508)
		(drill 0.254)
		(layers "F.Cu" "B.Cu")
		(net "PVDDCR_CPU1_P1")
	)
	(via
		(at 117.244622 -283.806392)
		(size 0.4064)
		(drill 0.2032)
		(layers "F.Cu" "B.Cu")
		(net "PVDDCR_CPU1_P1")
	)
	(via
		(at 63.18631 -329.02652)
		(size 0.508)
		(drill 0.254)
		(layers "F.Cu" "B.Cu")
		(net "PVDDCR_CPU1_P1")
	)
	(via
		(at 89.88171 -319.819274)
		(size 0.508)
		(drill 0.254)
		(layers "F.Cu" "B.Cu")
		(net "PVDDCR_CPU1_P1")
	)
	(via
		(at 123.824746 -269.226284)
		(size 0.4064)
		(drill 0.2032)
		(layers "F.Cu" "B.Cu")
		(net "PVDDCR_CPU1_P1")
	)
	(via
		(at 89.24671 -319.819274)
		(size 0.508)
		(drill 0.254)
		(layers "F.Cu" "B.Cu")
		(net "PVDDCR_CPU1_P1")
	)
	(via
		(at 84.57311 -319.184274)
		(size 0.508)
		(drill 0.254)
		(layers "F.Cu" "B.Cu")
		(net "PVDDCR_CPU1_P1")
	)
	(via
		(at 123.824746 -275.706332)
		(size 0.4064)
		(drill 0.2032)
		(layers "F.Cu" "B.Cu")
		(net "PVDDCR_CPU1_P1")
	)
	(via
		(at 100.331016 -278.946356)
		(size 0.4064)
		(drill 0.2032)
		(layers "F.Cu" "B.Cu")
		(net "PVDDCR_CPU1_P1")
	)
	(via
		(at 101.840538 -325.41972)
		(size 0.508)
		(drill 0.254)
		(layers "F.Cu" "B.Cu")
		(net "PVDDCR_CPU1_P1")
	)
	(via
		(at 97.500694 -318.563752)
		(size 0.508)
		(drill 0.254)
		(layers "F.Cu" "B.Cu")
		(net "PVDDCR_CPU1_P1")
	)
	(via
		(at 64.028066 -327.669398)
		(size 0.6604)
		(drill 0.3302)
		(layers "F.Cu" "B.Cu")
		(net "PVDDCR_CPU1_P1")
	)
	(via
		(at 67.105276 -338.781898)
		(size 0.508)
		(drill 0.254)
		(layers "F.Cu" "B.Cu")
		(net "PVDDCR_CPU1_P1")
	)
	(via
		(at 120.064784 -283.806392)
		(size 0.4064)
		(drill 0.2032)
		(layers "F.Cu" "B.Cu")
		(net "PVDDCR_CPU1_P1")
	)
	(via
		(at 60.44311 -334.10652)
		(size 0.508)
		(drill 0.254)
		(layers "F.Cu" "B.Cu")
		(net "PVDDCR_CPU1_P1")
	)
	(via
		(at 117.244622 -290.286186)
		(size 0.4064)
		(drill 0.2032)
		(layers "F.Cu" "B.Cu")
		(net "PVDDCR_CPU1_P1")
	)
	(via
		(at 76.875894 -321.728846)
		(size 0.508)
		(drill 0.254)
		(layers "F.Cu" "B.Cu")
		(net "PVDDCR_CPU1_P1")
	)
	(via
		(at 63.18631 -333.47152)
		(size 0.508)
		(drill 0.254)
		(layers "F.Cu" "B.Cu")
		(net "PVDDCR_CPU1_P1")
	)
	(via
		(at 113.95456 -295.956228)
		(size 0.4064)
		(drill 0.2032)
		(layers "F.Cu" "B.Cu")
		(net "PVDDCR_CPU1_P1")
	)
	(via
		(at 99.861116 -292.716204)
		(size 0.4064)
		(drill 0.2032)
		(layers "F.Cu" "B.Cu")
		(net "PVDDCR_CPU1_P1")
	)
	(via
		(at 104.090978 -272.466308)
		(size 0.4064)
		(drill 0.2032)
		(layers "F.Cu" "B.Cu")
		(net "PVDDCR_CPU1_P1")
	)
	(via
		(at 72.53351 -318.570864)
		(size 0.508)
		(drill 0.254)
		(layers "F.Cu" "B.Cu")
		(net "PVDDCR_CPU1_P1")
	)
	(via
		(at 103.151178 -275.706332)
		(size 0.4064)
		(drill 0.2032)
		(layers "F.Cu" "B.Cu")
		(net "PVDDCR_CPU1_P1")
	)
	(via
		(at 85.20811 -317.914274)
		(size 0.508)
		(drill 0.254)
		(layers "F.Cu" "B.Cu")
		(net "PVDDCR_CPU1_P1")
	)
	(via
		(at 60.44311 -333.47152)
		(size 0.508)
		(drill 0.254)
		(layers "F.Cu" "B.Cu")
		(net "PVDDCR_CPU1_P1")
	)
	(via
		(at 98.135694 -321.129152)
		(size 0.508)
		(drill 0.254)
		(layers "F.Cu" "B.Cu")
		(net "PVDDCR_CPU1_P1")
	)
	(via
		(at 85.207094 -323.008752)
		(size 0.508)
		(drill 0.254)
		(layers "F.Cu" "B.Cu")
		(net "PVDDCR_CPU1_P1")
	)
	(via
		(at 100.425504 -343.721182)
		(size 0.508)
		(drill 0.254)
		(layers "F.Cu" "B.Cu")
		(net "PVDDCR_CPU1_P1")
	)
	(via
		(at 123.824746 -283.806392)
		(size 0.4064)
		(drill 0.2032)
		(layers "F.Cu" "B.Cu")
		(net "PVDDCR_CPU1_P1")
	)
	(via
		(at 88.61171 -319.184274)
		(size 0.508)
		(drill 0.254)
		(layers "F.Cu" "B.Cu")
		(net "PVDDCR_CPU1_P1")
	)
	(via
		(at 125.704854 -267.606272)
		(size 0.4064)
		(drill 0.2032)
		(layers "F.Cu" "B.Cu")
		(net "PVDDCR_CPU1_P1")
	)
	(via
		(at 105.853738 -326.68972)
		(size 0.508)
		(drill 0.254)
		(layers "F.Cu" "B.Cu")
		(net "PVDDCR_CPU1_P1")
	)
	(via
		(at 126.174754 -268.416278)
		(size 0.4064)
		(drill 0.2032)
		(layers "F.Cu" "B.Cu")
		(net "PVDDCR_CPU1_P1")
	)
	(via
		(at 116.774722 -268.416278)
		(size 0.4064)
		(drill 0.2032)
		(layers "F.Cu" "B.Cu")
		(net "PVDDCR_CPU1_P1")
	)
	(via
		(at 76.215494 -322.359274)
		(size 0.508)
		(drill 0.254)
		(layers "F.Cu" "B.Cu")
		(net "PVDDCR_CPU1_P1")
	)
	(via
		(at 85.84311 -319.819274)
		(size 0.508)
		(drill 0.254)
		(layers "F.Cu" "B.Cu")
		(net "PVDDCR_CPU1_P1")
	)
	(via
		(at 63.18631 -334.74152)
		(size 0.508)
		(drill 0.254)
		(layers "F.Cu" "B.Cu")
		(net "PVDDCR_CPU1_P1")
	)
	(via
		(at 106.91114 -283.806392)
		(size 0.4064)
		(drill 0.2032)
		(layers "F.Cu" "B.Cu")
		(net "PVDDCR_CPU1_P1")
	)
	(via
		(at 76.850494 -316.644274)
		(size 0.508)
		(drill 0.254)
		(layers "F.Cu" "B.Cu")
		(net "PVDDCR_CPU1_P1")
	)
	(via
		(at 88.61171 -322.363846)
		(size 0.508)
		(drill 0.254)
		(layers "F.Cu" "B.Cu")
		(net "PVDDCR_CPU1_P1")
	)
	(via
		(at 105.882694 -327.969626)
		(size 0.508)
		(drill 0.254)
		(layers "F.Cu" "B.Cu")
		(net "PVDDCR_CPU1_P1")
	)
	(via
		(at 85.842094 -323.008752)
		(size 0.508)
		(drill 0.254)
		(layers "F.Cu" "B.Cu")
		(net "PVDDCR_CPU1_P1")
	)
	(via
		(at 72.53351 -320.480436)
		(size 0.508)
		(drill 0.254)
		(layers "F.Cu" "B.Cu")
		(net "PVDDCR_CPU1_P1")
	)
	(via
		(at 103.621078 -281.376374)
		(size 0.4064)
		(drill 0.2032)
		(layers "F.Cu" "B.Cu")
		(net "PVDDCR_CPU1_P1")
	)
	(via
		(at 105.853738 -326.05472)
		(size 0.508)
		(drill 0.254)
		(layers "F.Cu" "B.Cu")
		(net "PVDDCR_CPU1_P1")
	)
	(via
		(at 101.27107 -275.706332)
		(size 0.4064)
		(drill 0.2032)
		(layers "F.Cu" "B.Cu")
		(net "PVDDCR_CPU1_P1")
	)
	(via
		(at 125.704854 -287.046162)
		(size 0.4064)
		(drill 0.2032)
		(layers "F.Cu" "B.Cu")
		(net "PVDDCR_CPU1_P1")
	)
	(via
		(at 89.245694 -323.008752)
		(size 0.508)
		(drill 0.254)
		(layers "F.Cu" "B.Cu")
		(net "PVDDCR_CPU1_P1")
	)
	(via
		(at 98.451162 -272.466308)
		(size 0.4064)
		(drill 0.2032)
		(layers "F.Cu" "B.Cu")
		(net "PVDDCR_CPU1_P1")
	)
	(via
		(at 101.180138 -323.510148)
		(size 0.508)
		(drill 0.254)
		(layers "F.Cu" "B.Cu")
		(net "PVDDCR_CPU1_P1")
	)
	(via
		(at 106.488738 -324.780148)
		(size 0.508)
		(drill 0.254)
		(layers "F.Cu" "B.Cu")
		(net "PVDDCR_CPU1_P1")
	)
	(via
		(at 110.200948 -291.096192)
		(size 0.4064)
		(drill 0.2032)
		(layers "F.Cu" "B.Cu")
		(net "PVDDCR_CPU1_P1")
	)
	(via
		(at 100.331016 -283.806392)
		(size 0.4064)
		(drill 0.2032)
		(layers "F.Cu" "B.Cu")
		(net "PVDDCR_CPU1_P1")
	)
	(via
		(at 92.827094 -319.833752)
		(size 0.508)
		(drill 0.254)
		(layers "F.Cu" "B.Cu")
		(net "PVDDCR_CPU1_P1")
	)
	(via
		(at 88.61171 -321.728846)
		(size 0.508)
		(drill 0.254)
		(layers "F.Cu" "B.Cu")
		(net "PVDDCR_CPU1_P1")
	)
	(via
		(at 103.151178 -290.286186)
		(size 0.4064)
		(drill 0.2032)
		(layers "F.Cu" "B.Cu")
		(net "PVDDCR_CPU1_P1")
	)
	(via
		(at 94.122494 -321.108324)
		(size 0.508)
		(drill 0.254)
		(layers "F.Cu" "B.Cu")
		(net "PVDDCR_CPU1_P1")
	)
	(via
		(at 71.89851 -318.570864)
		(size 0.508)
		(drill 0.254)
		(layers "F.Cu" "B.Cu")
		(net "PVDDCR_CPU1_P1")
	)
	(via
		(at 98.135694 -316.658752)
		(size 0.508)
		(drill 0.254)
		(layers "F.Cu" "B.Cu")
		(net "PVDDCR_CPU1_P1")
	)
	(via
		(at 105.971086 -283.806392)
		(size 0.4064)
		(drill 0.2032)
		(layers "F.Cu" "B.Cu")
		(net "PVDDCR_CPU1_P1")
	)
	(via
		(at 120.064784 -278.946356)
		(size 0.4064)
		(drill 0.2032)
		(layers "F.Cu" "B.Cu")
		(net "PVDDCR_CPU1_P1")
	)
	(via
		(at 97.040954 -292.716204)
		(size 0.4064)
		(drill 0.2032)
		(layers "F.Cu" "B.Cu")
		(net "PVDDCR_CPU1_P1")
	)
	(via
		(at 110.200948 -274.896326)
		(size 0.4064)
		(drill 0.2032)
		(layers "F.Cu" "B.Cu")
		(net "PVDDCR_CPU1_P1")
	)
	(via
		(at 126.644654 -283.806392)
		(size 0.4064)
		(drill 0.2032)
		(layers "F.Cu" "B.Cu")
		(net "PVDDCR_CPU1_P1")
	)
	(via
		(at 63.18631 -328.39152)
		(size 0.508)
		(drill 0.254)
		(layers "F.Cu" "B.Cu")
		(net "PVDDCR_CPU1_P1")
	)
	(via
		(at 122.884692 -269.226284)
		(size 0.4064)
		(drill 0.2032)
		(layers "F.Cu" "B.Cu")
		(net "PVDDCR_CPU1_P1")
	)
	(via
		(at 68.49491 -319.840864)
		(size 0.508)
		(drill 0.254)
		(layers "F.Cu" "B.Cu")
		(net "PVDDCR_CPU1_P1")
	)
	(via
		(at 102.475538 -325.41972)
		(size 0.508)
		(drill 0.254)
		(layers "F.Cu" "B.Cu")
		(net "PVDDCR_CPU1_P1")
	)
	(via
		(at 85.20811 -317.279274)
		(size 0.508)
		(drill 0.254)
		(layers "F.Cu" "B.Cu")
		(net "PVDDCR_CPU1_P1")
	)
	(via
		(at 100.331016 -272.466308)
		(size 0.4064)
		(drill 0.2032)
		(layers "F.Cu" "B.Cu")
		(net "PVDDCR_CPU1_P1")
	)
	(via
		(at 114.894614 -266.796266)
		(size 0.4064)
		(drill 0.2032)
		(layers "F.Cu" "B.Cu")
		(net "PVDDCR_CPU1_P1")
	)
	(via
		(at 81.524094 -316.644274)
		(size 0.508)
		(drill 0.254)
		(layers "F.Cu" "B.Cu")
		(net "PVDDCR_CPU1_P1")
	)
	(via
		(at 93.462094 -319.198752)
		(size 0.508)
		(drill 0.254)
		(layers "F.Cu" "B.Cu")
		(net "PVDDCR_CPU1_P1")
	)
	(via
		(at 84.57311 -319.819274)
		(size 0.508)
		(drill 0.254)
		(layers "F.Cu" "B.Cu")
		(net "PVDDCR_CPU1_P1")
	)
	(via
		(at 73.16851 -321.745864)
		(size 0.508)
		(drill 0.254)
		(layers "F.Cu" "B.Cu")
		(net "PVDDCR_CPU1_P1")
	)
	(via
		(at 89.24671 -317.279274)
		(size 0.508)
		(drill 0.254)
		(layers "F.Cu" "B.Cu")
		(net "PVDDCR_CPU1_P1")
	)
	(via
		(at 94.12605 -315.93663)
		(size 0.6604)
		(drill 0.3302)
		(layers "F.Cu" "B.Cu")
		(net "PVDDCR_CPU1_P1")
	)
	(via
		(at 121.004838 -278.946356)
		(size 0.4064)
		(drill 0.2032)
		(layers "F.Cu" "B.Cu")
		(net "PVDDCR_CPU1_P1")
	)
	(via
		(at 76.21905 -323.008752)
		(size 0.508)
		(drill 0.254)
		(layers "F.Cu" "B.Cu")
		(net "PVDDCR_CPU1_P1")
	)
	(via
		(at 81.524094 -321.089274)
		(size 0.508)
		(drill 0.254)
		(layers "F.Cu" "B.Cu")
		(net "PVDDCR_CPU1_P1")
	)
	(via
		(at 109.261148 -291.096192)
		(size 0.4064)
		(drill 0.2032)
		(layers "F.Cu" "B.Cu")
		(net "PVDDCR_CPU1_P1")
	)
	(via
		(at 85.86851 -322.363846)
		(size 0.508)
		(drill 0.254)
		(layers "F.Cu" "B.Cu")
		(net "PVDDCR_CPU1_P1")
	)
	(via
		(at 106.488738 -323.510148)
		(size 0.508)
		(drill 0.254)
		(layers "F.Cu" "B.Cu")
		(net "PVDDCR_CPU1_P1")
	)
	(via
		(at 105.971086 -278.946356)
		(size 0.4064)
		(drill 0.2032)
		(layers "F.Cu" "B.Cu")
		(net "PVDDCR_CPU1_P1")
	)
	(via
		(at 93.487494 -321.108324)
		(size 0.508)
		(drill 0.254)
		(layers "F.Cu" "B.Cu")
		(net "PVDDCR_CPU1_P1")
	)
	(via
		(at 119.594884 -295.956228)
		(size 0.4064)
		(drill 0.2032)
		(layers "F.Cu" "B.Cu")
		(net "PVDDCR_CPU1_P1")
	)
	(via
		(at 100.331016 -290.286186)
		(size 0.4064)
		(drill 0.2032)
		(layers "F.Cu" "B.Cu")
		(net "PVDDCR_CPU1_P1")
	)
	(via
		(at 106.440986 -281.376374)
		(size 0.4064)
		(drill 0.2032)
		(layers "F.Cu" "B.Cu")
		(net "PVDDCR_CPU1_P1")
	)
	(via
		(at 105.853738 -322.240148)
		(size 0.508)
		(drill 0.254)
		(layers "F.Cu" "B.Cu")
		(net "PVDDCR_CPU1_P1")
	)
	(via
		(at 102.475538 -327.32472)
		(size 0.508)
		(drill 0.254)
		(layers "F.Cu" "B.Cu")
		(net "PVDDCR_CPU1_P1")
	)
	(via
		(at 106.517694 -325.429626)
		(size 0.508)
		(drill 0.254)
		(layers "F.Cu" "B.Cu")
		(net "PVDDCR_CPU1_P1")
	)
	(via
		(at 118.184676 -290.286186)
		(size 0.4064)
		(drill 0.2032)
		(layers "F.Cu" "B.Cu")
		(net "PVDDCR_CPU1_P1")
	)
	(via
		(at 97.500694 -316.658752)
		(size 0.508)
		(drill 0.254)
		(layers "F.Cu" "B.Cu")
		(net "PVDDCR_CPU1_P1")
	)
	(via
		(at 118.184676 -287.046162)
		(size 0.4064)
		(drill 0.2032)
		(layers "F.Cu" "B.Cu")
		(net "PVDDCR_CPU1_P1")
	)
	(via
		(at 118.184676 -275.706332)
		(size 0.4064)
		(drill 0.2032)
		(layers "F.Cu" "B.Cu")
		(net "PVDDCR_CPU1_P1")
	)
	(via
		(at 63.82131 -333.47152)
		(size 0.508)
		(drill 0.254)
		(layers "F.Cu" "B.Cu")
		(net "PVDDCR_CPU1_P1")
	)
	(via
		(at 105.971086 -272.466308)
		(size 0.4064)
		(drill 0.2032)
		(layers "F.Cu" "B.Cu")
		(net "PVDDCR_CPU1_P1")
	)
	(via
		(at 102.450138 -324.145148)
		(size 0.508)
		(drill 0.254)
		(layers "F.Cu" "B.Cu")
		(net "PVDDCR_CPU1_P1")
	)
	(via
		(at 88.610694 -323.008752)
		(size 0.508)
		(drill 0.254)
		(layers "F.Cu" "B.Cu")
		(net "PVDDCR_CPU1_P1")
	)
	(via
		(at 85.84311 -317.914274)
		(size 0.508)
		(drill 0.254)
		(layers "F.Cu" "B.Cu")
		(net "PVDDCR_CPU1_P1")
	)
	(via
		(at 126.644654 -275.706332)
		(size 0.4064)
		(drill 0.2032)
		(layers "F.Cu" "B.Cu")
		(net "PVDDCR_CPU1_P1")
	)
	(via
		(at 84.57311 -317.914274)
		(size 0.508)
		(drill 0.254)
		(layers "F.Cu" "B.Cu")
		(net "PVDDCR_CPU1_P1")
	)
	(via
		(at 97.511108 -290.286186)
		(size 0.4064)
		(drill 0.2032)
		(layers "F.Cu" "B.Cu")
		(net "PVDDCR_CPU1_P1")
	)
	(via
		(at 63.82131 -332.20152)
		(size 0.508)
		(drill 0.254)
		(layers "F.Cu" "B.Cu")
		(net "PVDDCR_CPU1_P1")
	)
	(via
		(at 84.572094 -323.008752)
		(size 0.508)
		(drill 0.254)
		(layers "F.Cu" "B.Cu")
		(net "PVDDCR_CPU1_P1")
	)
	(via
		(at 105.031032 -295.146222)
		(size 0.4064)
		(drill 0.2032)
		(layers "F.Cu" "B.Cu")
		(net "PVDDCR_CPU1_P1")
	)
	(via
		(at 117.244622 -287.046162)
		(size 0.4064)
		(drill 0.2032)
		(layers "F.Cu" "B.Cu")
		(net "PVDDCR_CPU1_P1")
	)
	(via
		(at 67.863466 -321.760342)
		(size 0.508)
		(drill 0.254)
		(layers "F.Cu" "B.Cu")
		(net "PVDDCR_CPU1_P1")
	)
	(via
		(at 125.704854 -283.806392)
		(size 0.4064)
		(drill 0.2032)
		(layers "F.Cu" "B.Cu")
		(net "PVDDCR_CPU1_P1")
	)
	(via
		(at 80.889094 -318.549274)
		(size 0.508)
		(drill 0.254)
		(layers "F.Cu" "B.Cu")
		(net "PVDDCR_CPU1_P1")
	)
	(via
		(at 96.571054 -291.906198)
		(size 0.4064)
		(drill 0.2032)
		(layers "F.Cu" "B.Cu")
		(net "PVDDCR_CPU1_P1")
	)
	(via
		(at 103.151178 -272.466308)
		(size 0.4064)
		(drill 0.2032)
		(layers "F.Cu" "B.Cu")
		(net "PVDDCR_CPU1_P1")
	)
	(via
		(at 59.17311 -334.10652)
		(size 0.508)
		(drill 0.254)
		(layers "F.Cu" "B.Cu")
		(net "PVDDCR_CPU1_P1")
	)
	(via
		(at 76.215494 -319.819274)
		(size 0.508)
		(drill 0.254)
		(layers "F.Cu" "B.Cu")
		(net "PVDDCR_CPU1_P1")
	)
	(via
		(at 93.487494 -321.743324)
		(size 0.508)
		(drill 0.254)
		(layers "F.Cu" "B.Cu")
		(net "PVDDCR_CPU1_P1")
	)
	(via
		(at 97.500694 -321.743324)
		(size 0.508)
		(drill 0.254)
		(layers "F.Cu" "B.Cu")
		(net "PVDDCR_CPU1_P1")
	)
	(via
		(at 89.24671 -318.549274)
		(size 0.508)
		(drill 0.254)
		(layers "F.Cu" "B.Cu")
		(net "PVDDCR_CPU1_P1")
	)
	(via
		(at 104.090978 -278.946356)
		(size 0.4064)
		(drill 0.2032)
		(layers "F.Cu" "B.Cu")
		(net "PVDDCR_CPU1_P1")
	)
	(via
		(at 110.200948 -278.13635)
		(size 0.4064)
		(drill 0.2032)
		(layers "F.Cu" "B.Cu")
		(net "PVDDCR_CPU1_P1")
	)
	(via
		(at 60.44311 -330.29652)
		(size 0.508)
		(drill 0.254)
		(layers "F.Cu" "B.Cu")
		(net "PVDDCR_CPU1_P1")
	)
	(via
		(at 101.27107 -272.466308)
		(size 0.4064)
		(drill 0.2032)
		(layers "F.Cu" "B.Cu")
		(net "PVDDCR_CPU1_P1")
	)
	(via
		(at 125.704854 -269.226284)
		(size 0.4064)
		(drill 0.2032)
		(layers "F.Cu" "B.Cu")
		(net "PVDDCR_CPU1_P1")
	)
	(via
		(at 63.18631 -329.66152)
		(size 0.508)
		(drill 0.254)
		(layers "F.Cu" "B.Cu")
		(net "PVDDCR_CPU1_P1")
	)
	(via
		(at 102.450138 -323.510148)
		(size 0.508)
		(drill 0.254)
		(layers "F.Cu" "B.Cu")
		(net "PVDDCR_CPU1_P1")
	)
	(via
		(at 117.244622 -278.946356)
		(size 0.4064)
		(drill 0.2032)
		(layers "F.Cu" "B.Cu")
		(net "PVDDCR_CPU1_P1")
	)
	(via
		(at 97.500694 -320.473324)
		(size 0.508)
		(drill 0.254)
		(layers "F.Cu" "B.Cu")
		(net "PVDDCR_CPU1_P1")
	)
	(via
		(at 94.097094 -317.293752)
		(size 0.508)
		(drill 0.254)
		(layers "F.Cu" "B.Cu")
		(net "PVDDCR_CPU1_P1")
	)
	(via
		(at 104.090978 -290.286186)
		(size 0.4064)
		(drill 0.2032)
		(layers "F.Cu" "B.Cu")
		(net "PVDDCR_CPU1_P1")
	)
	(via
		(at 92.852494 -323.034152)
		(size 0.508)
		(drill 0.254)
		(layers "F.Cu" "B.Cu")
		(net "PVDDCR_CPU1_P1")
	)
	(via
		(at 123.824746 -290.286186)
		(size 0.4064)
		(drill 0.2032)
		(layers "F.Cu" "B.Cu")
		(net "PVDDCR_CPU1_P1")
	)
	(via
		(at 63.18631 -330.29652)
		(size 0.508)
		(drill 0.254)
		(layers "F.Cu" "B.Cu")
		(net "PVDDCR_CPU1_P1")
	)
	(via
		(at 89.24671 -317.914274)
		(size 0.508)
		(drill 0.254)
		(layers "F.Cu" "B.Cu")
		(net "PVDDCR_CPU1_P1")
	)
	(via
		(at 118.184676 -267.606272)
		(size 0.4064)
		(drill 0.2032)
		(layers "F.Cu" "B.Cu")
		(net "PVDDCR_CPU1_P1")
	)
	(via
		(at 106.91114 -287.046162)
		(size 0.4064)
		(drill 0.2032)
		(layers "F.Cu" "B.Cu")
		(net "PVDDCR_CPU1_P1")
	)
	(via
		(at 104.561132 -268.416278)
		(size 0.4064)
		(drill 0.2032)
		(layers "F.Cu" "B.Cu")
		(net "PVDDCR_CPU1_P1")
	)
	(via
		(at 84.572094 -320.468752)
		(size 0.508)
		(drill 0.254)
		(layers "F.Cu" "B.Cu")
		(net "PVDDCR_CPU1_P1")
	)
	(via
		(at 72.53351 -321.750436)
		(size 0.508)
		(drill 0.254)
		(layers "F.Cu" "B.Cu")
		(net "PVDDCR_CPU1_P1")
	)
	(via
		(at 97.511108 -295.146222)
		(size 0.4064)
		(drill 0.2032)
		(layers "F.Cu" "B.Cu")
		(net "PVDDCR_CPU1_P1")
	)
	(via
		(at 94.097094 -317.928752)
		(size 0.508)
		(drill 0.254)
		(layers "F.Cu" "B.Cu")
		(net "PVDDCR_CPU1_P1")
	)
	(via
		(at 85.20811 -319.819274)
		(size 0.508)
		(drill 0.254)
		(layers "F.Cu" "B.Cu")
		(net "PVDDCR_CPU1_P1")
	)
	(via
		(at 69.133466 -323.030342)
		(size 0.508)
		(drill 0.254)
		(layers "F.Cu" "B.Cu")
		(net "PVDDCR_CPU1_P1")
	)
	(via
		(at 106.488738 -324.145148)
		(size 0.508)
		(drill 0.254)
		(layers "F.Cu" "B.Cu")
		(net "PVDDCR_CPU1_P1")
	)
	(via
		(at 101.840538 -326.68972)
		(size 0.508)
		(drill 0.254)
		(layers "F.Cu" "B.Cu")
		(net "PVDDCR_CPU1_P1")
	)
	(via
		(at 76.875894 -320.458846)
		(size 0.508)
		(drill 0.254)
		(layers "F.Cu" "B.Cu")
		(net "PVDDCR_CPU1_P1")
	)
	(via
		(at 94.690946 -295.146222)
		(size 0.4064)
		(drill 0.2032)
		(layers "F.Cu" "B.Cu")
		(net "PVDDCR_CPU1_P1")
	)
	(via
		(at 101.27107 -267.606272)
		(size 0.4064)
		(drill 0.2032)
		(layers "F.Cu" "B.Cu")
		(net "PVDDCR_CPU1_P1")
	)
	(via
		(at 77.485494 -317.279274)
		(size 0.508)
		(drill 0.254)
		(layers "F.Cu" "B.Cu")
		(net "PVDDCR_CPU1_P1")
	)
	(via
		(at 112.054386 -267.091414)
		(size 0.4826)
		(drill 0.254)
		(layers "F.Cu" "B.Cu")
		(net "PVDDCR_CPU1_P1")
	)
	(via
		(at 59.17311 -331.56652)
		(size 0.508)
		(drill 0.254)
		(layers "F.Cu" "B.Cu")
		(net "PVDDCR_CPU1_P1")
	)
	(via
		(at 96.865694 -321.108324)
		(size 0.508)
		(drill 0.254)
		(layers "F.Cu" "B.Cu")
		(net "PVDDCR_CPU1_P1")
	)
	(via
		(at 101.840538 -326.05472)
		(size 0.508)
		(drill 0.254)
		(layers "F.Cu" "B.Cu")
		(net "PVDDCR_CPU1_P1")
	)
	(via
		(at 109.261148 -278.13635)
		(size 0.4064)
		(drill 0.2032)
		(layers "F.Cu" "B.Cu")
		(net "PVDDCR_CPU1_P1")
	)
	(via
		(at 80.254094 -321.093846)
		(size 0.508)
		(drill 0.254)
		(layers "F.Cu" "B.Cu")
		(net "PVDDCR_CPU1_P1")
	)
	(via
		(at 100.331016 -295.146222)
		(size 0.4064)
		(drill 0.2032)
		(layers "F.Cu" "B.Cu")
		(net "PVDDCR_CPU1_P1")
	)
	(via
		(at 88.61171 -317.279274)
		(size 0.508)
		(drill 0.254)
		(layers "F.Cu" "B.Cu")
		(net "PVDDCR_CPU1_P1")
	)
	(via
		(at 106.488738 -322.875148)
		(size 0.508)
		(drill 0.254)
		(layers "F.Cu" "B.Cu")
		(net "PVDDCR_CPU1_P1")
	)
	(via
		(at 76.850494 -319.184274)
		(size 0.508)
		(drill 0.254)
		(layers "F.Cu" "B.Cu")
		(net "PVDDCR_CPU1_P1")
	)
	(via
		(at 93.487494 -323.034152)
		(size 0.508)
		(drill 0.254)
		(layers "F.Cu" "B.Cu")
		(net "PVDDCR_CPU1_P1")
	)
	(via
		(at 122.884692 -287.046162)
		(size 0.4064)
		(drill 0.2032)
		(layers "F.Cu" "B.Cu")
		(net "PVDDCR_CPU1_P1")
	)
	(via
		(at 126.644654 -272.466308)
		(size 0.4064)
		(drill 0.2032)
		(layers "F.Cu" "B.Cu")
		(net "PVDDCR_CPU1_P1")
	)
	(via
		(at 106.517694 -326.699626)
		(size 0.508)
		(drill 0.254)
		(layers "F.Cu" "B.Cu")
		(net "PVDDCR_CPU1_P1")
	)
	(via
		(at 105.500932 -292.716204)
		(size 0.4064)
		(drill 0.2032)
		(layers "F.Cu" "B.Cu")
		(net "PVDDCR_CPU1_P1")
	)
	(via
		(at 114.894614 -268.416278)
		(size 0.4064)
		(drill 0.2032)
		(layers "F.Cu" "B.Cu")
		(net "PVDDCR_CPU1_P1")
	)
	(via
		(at 117.244622 -272.466308)
		(size 0.4064)
		(drill 0.2032)
		(layers "F.Cu" "B.Cu")
		(net "PVDDCR_CPU1_P1")
	)
	(via
		(at 114.894614 -274.896326)
		(size 0.4064)
		(drill 0.2032)
		(layers "F.Cu" "B.Cu")
		(net "PVDDCR_CPU1_P1")
	)
	(via
		(at 88.61171 -317.914274)
		(size 0.508)
		(drill 0.254)
		(layers "F.Cu" "B.Cu")
		(net "PVDDCR_CPU1_P1")
	)
	(via
		(at 83.818476 -338.760308)
		(size 0.508)
		(drill 0.254)
		(layers "F.Cu" "B.Cu")
		(net "PVDDCR_CPU1_P1")
	)
	(via
		(at 105.971086 -295.146222)
		(size 0.4064)
		(drill 0.2032)
		(layers "F.Cu" "B.Cu")
		(net "PVDDCR_CPU1_P1")
	)
	(via
		(at 96.571054 -295.146222)
		(size 0.4064)
		(drill 0.2032)
		(layers "F.Cu" "B.Cu")
		(net "PVDDCR_CPU1_P1")
	)
	(via
		(at 105.853738 -323.510148)
		(size 0.508)
		(drill 0.254)
		(layers "F.Cu" "B.Cu")
		(net "PVDDCR_CPU1_P1")
	)
	(via
		(at 89.88171 -322.359274)
		(size 0.508)
		(drill 0.254)
		(layers "F.Cu" "B.Cu")
		(net "PVDDCR_CPU1_P1")
	)
	(via
		(at 105.218738 -324.780148)
		(size 0.508)
		(drill 0.254)
		(layers "F.Cu" "B.Cu")
		(net "PVDDCR_CPU1_P1")
	)
	(via
		(at 115.364768 -295.146222)
		(size 0.4064)
		(drill 0.2032)
		(layers "F.Cu" "B.Cu")
		(net "PVDDCR_CPU1_P1")
	)
	(via
		(at 88.61171 -319.819274)
		(size 0.508)
		(drill 0.254)
		(layers "F.Cu" "B.Cu")
		(net "PVDDCR_CPU1_P1")
	)
	(via
		(at 59.80811 -332.83652)
		(size 0.508)
		(drill 0.254)
		(layers "F.Cu" "B.Cu")
		(net "PVDDCR_CPU1_P1")
	)
	(via
		(at 99.390962 -295.146222)
		(size 0.4064)
		(drill 0.2032)
		(layers "F.Cu" "B.Cu")
		(net "PVDDCR_CPU1_P1")
	)
	(via
		(at 118.65483 -266.796266)
		(size 0.4064)
		(drill 0.2032)
		(layers "F.Cu" "B.Cu")
		(net "PVDDCR_CPU1_P1")
	)
	(via
		(at 71.89851 -317.935864)
		(size 0.508)
		(drill 0.254)
		(layers "F.Cu" "B.Cu")
		(net "PVDDCR_CPU1_P1")
	)
	(via
		(at 88.61171 -316.644274)
		(size 0.508)
		(drill 0.254)
		(layers "F.Cu" "B.Cu")
		(net "PVDDCR_CPU1_P1")
	)
	(via
		(at 76.875894 -321.093846)
		(size 0.508)
		(drill 0.254)
		(layers "F.Cu" "B.Cu")
		(net "PVDDCR_CPU1_P1")
	)
	(via
		(at 71.89851 -320.480436)
		(size 0.508)
		(drill 0.254)
		(layers "F.Cu" "B.Cu")
		(net "PVDDCR_CPU1_P1")
	)
	(via
		(at 114.894614 -278.13635)
		(size 0.4064)
		(drill 0.2032)
		(layers "F.Cu" "B.Cu")
		(net "PVDDCR_CPU1_P1")
	)
	(via
		(at 89.24671 -316.644274)
		(size 0.508)
		(drill 0.254)
		(layers "F.Cu" "B.Cu")
		(net "PVDDCR_CPU1_P1")
	)
	(via
		(at 105.218738 -325.41972)
		(size 0.508)
		(drill 0.254)
		(layers "F.Cu" "B.Cu")
		(net "PVDDCR_CPU1_P1")
	)
	(via
		(at 116.304822 -267.606272)
		(size 0.4064)
		(drill 0.2032)
		(layers "F.Cu" "B.Cu")
		(net "PVDDCR_CPU1_P1")
	)
	(via
		(at 73.16851 -317.300864)
		(size 0.508)
		(drill 0.254)
		(layers "F.Cu" "B.Cu")
		(net "PVDDCR_CPU1_P1")
	)
	(via
		(at 72.53351 -317.300864)
		(size 0.508)
		(drill 0.254)
		(layers "F.Cu" "B.Cu")
		(net "PVDDCR_CPU1_P1")
	)
	(via
		(at 80.254094 -322.363846)
		(size 0.508)
		(drill 0.254)
		(layers "F.Cu" "B.Cu")
		(net "PVDDCR_CPU1_P1")
	)
	(via
		(at 104.090978 -283.806392)
		(size 0.4064)
		(drill 0.2032)
		(layers "F.Cu" "B.Cu")
		(net "PVDDCR_CPU1_P1")
	)
	(via
		(at 75.46086 -338.774786)
		(size 0.508)
		(drill 0.254)
		(layers "F.Cu" "B.Cu")
		(net "PVDDCR_CPU1_P1")
	)
	(via
		(at 80.889094 -321.728846)
		(size 0.508)
		(drill 0.254)
		(layers "F.Cu" "B.Cu")
		(net "PVDDCR_CPU1_P1")
	)
	(via
		(at 114.894614 -271.656302)
		(size 0.4064)
		(drill 0.2032)
		(layers "F.Cu" "B.Cu")
		(net "PVDDCR_CPU1_P1")
	)
	(via
		(at 76.850494 -317.279274)
		(size 0.508)
		(drill 0.254)
		(layers "F.Cu" "B.Cu")
		(net "PVDDCR_CPU1_P1")
	)
	(via
		(at 69.15531 -321.115436)
		(size 0.508)
		(drill 0.254)
		(layers "F.Cu" "B.Cu")
		(net "PVDDCR_CPU1_P1")
	)
	(via
		(at 80.254094 -321.728846)
		(size 0.508)
		(drill 0.254)
		(layers "F.Cu" "B.Cu")
		(net "PVDDCR_CPU1_P1")
	)
	(via
		(at 114.894614 -282.996386)
		(size 0.4064)
		(drill 0.2032)
		(layers "F.Cu" "B.Cu")
		(net "PVDDCR_CPU1_P1")
	)
	(via
		(at 101.27107 -278.946356)
		(size 0.4064)
		(drill 0.2032)
		(layers "F.Cu" "B.Cu")
		(net "PVDDCR_CPU1_P1")
	)
	(via
		(at 89.88171 -318.549274)
		(size 0.508)
		(drill 0.254)
		(layers "F.Cu" "B.Cu")
		(net "PVDDCR_CPU1_P1")
	)
	(via
		(at 106.91114 -290.286186)
		(size 0.4064)
		(drill 0.2032)
		(layers "F.Cu" "B.Cu")
		(net "PVDDCR_CPU1_P1")
	)
	(via
		(at 105.218738 -326.68972)
		(size 0.508)
		(drill 0.254)
		(layers "F.Cu" "B.Cu")
		(net "PVDDCR_CPU1_P1")
	)
	(via
		(at 123.824746 -287.046162)
		(size 0.4064)
		(drill 0.2032)
		(layers "F.Cu" "B.Cu")
		(net "PVDDCR_CPU1_P1")
	)
	(via
		(at 63.82131 -329.02652)
		(size 0.508)
		(drill 0.254)
		(layers "F.Cu" "B.Cu")
		(net "PVDDCR_CPU1_P1")
	)
	(via
		(at 81.524094 -322.359274)
		(size 0.508)
		(drill 0.254)
		(layers "F.Cu" "B.Cu")
		(net "PVDDCR_CPU1_P1")
	)
	(via
		(at 121.944638 -291.906198)
		(size 0.4064)
		(drill 0.2032)
		(layers "F.Cu" "B.Cu")
		(net "PVDDCR_CPU1_P1")
	)
	(via
		(at 125.2347 -295.956228)
		(size 0.4064)
		(drill 0.2032)
		(layers "F.Cu" "B.Cu")
		(net "PVDDCR_CPU1_P1")
	)
	(via
		(at 58.570876 -350.502982)
		(size 0.508)
		(drill 0.254)
		(layers "F.Cu" "B.Cu")
		(net "PVDDCR_CPU1_P1")
	)
	(via
		(at 98.451162 -290.286186)
		(size 0.4064)
		(drill 0.2032)
		(layers "F.Cu" "B.Cu")
		(net "PVDDCR_CPU1_P1")
	)
	(via
		(at 102.479094 -320.883026)
		(size 0.6604)
		(drill 0.3302)
		(layers "F.Cu" "B.Cu")
		(net "PVDDCR_CPU1_P1")
	)
	(via
		(at 120.064784 -275.706332)
		(size 0.4064)
		(drill 0.2032)
		(layers "F.Cu" "B.Cu")
		(net "PVDDCR_CPU1_P1")
	)
	(via
		(at 108.321094 -266.796266)
		(size 0.4064)
		(drill 0.2032)
		(layers "F.Cu" "B.Cu")
		(net "PVDDCR_CPU1_P1")
	)
	(via
		(at 115.364768 -280.566368)
		(size 0.4064)
		(drill 0.2032)
		(layers "F.Cu" "B.Cu")
		(net "PVDDCR_CPU1_P1")
	)
	(via
		(at 98.451162 -269.226284)
		(size 0.4064)
		(drill 0.2032)
		(layers "F.Cu" "B.Cu")
		(net "PVDDCR_CPU1_P1")
	)
	(via
		(at 108.321094 -268.416278)
		(size 0.4064)
		(drill 0.2032)
		(layers "F.Cu" "B.Cu")
		(net "PVDDCR_CPU1_P1")
	)
	(via
		(at 96.865694 -319.833752)
		(size 0.508)
		(drill 0.254)
		(layers "F.Cu" "B.Cu")
		(net "PVDDCR_CPU1_P1")
	)
	(via
		(at 104.090978 -287.046162)
		(size 0.4064)
		(drill 0.2032)
		(layers "F.Cu" "B.Cu")
		(net "PVDDCR_CPU1_P1")
	)
	(via
		(at 88.61171 -320.458846)
		(size 0.508)
		(drill 0.254)
		(layers "F.Cu" "B.Cu")
		(net "PVDDCR_CPU1_P1")
	)
	(via
		(at 101.840538 -327.32472)
		(size 0.508)
		(drill 0.254)
		(layers "F.Cu" "B.Cu")
		(net "PVDDCR_CPU1_P1")
	)
	(via
		(at 80.254094 -319.819274)
		(size 0.508)
		(drill 0.254)
		(layers "F.Cu" "B.Cu")
		(net "PVDDCR_CPU1_P1")
	)
	(via
		(at 127.114808 -292.716204)
		(size 0.4064)
		(drill 0.2032)
		(layers "F.Cu" "B.Cu")
		(net "PVDDCR_CPU1_P1")
	)
	(via
		(at 108.790994 -267.606272)
		(size 0.4064)
		(drill 0.2032)
		(layers "F.Cu" "B.Cu")
		(net "PVDDCR_CPU1_P1")
	)
	(via
		(at 103.151178 -269.226284)
		(size 0.4064)
		(drill 0.2032)
		(layers "F.Cu" "B.Cu")
		(net "PVDDCR_CPU1_P1")
	)
	(via
		(at 89.88171 -317.279274)
		(size 0.508)
		(drill 0.254)
		(layers "F.Cu" "B.Cu")
		(net "PVDDCR_CPU1_P1")
	)
	(via
		(at 85.84311 -319.184274)
		(size 0.508)
		(drill 0.254)
		(layers "F.Cu" "B.Cu")
		(net "PVDDCR_CPU1_P1")
	)
	(via
		(at 118.184676 -269.226284)
		(size 0.4064)
		(drill 0.2032)
		(layers "F.Cu" "B.Cu")
		(net "PVDDCR_CPU1_P1")
	)
	(via
		(at 102.211124 -291.906198)
		(size 0.4064)
		(drill 0.2032)
		(layers "F.Cu" "B.Cu")
		(net "PVDDCR_CPU1_P1")
	)
	(via
		(at 105.853738 -324.780148)
		(size 0.508)
		(drill 0.254)
		(layers "F.Cu" "B.Cu")
		(net "PVDDCR_CPU1_P1")
	)
	(via
		(at 85.23351 -321.093846)
		(size 0.508)
		(drill 0.254)
		(layers "F.Cu" "B.Cu")
		(net "PVDDCR_CPU1_P1")
	)
	(via
		(at 85.86851 -321.093846)
		(size 0.508)
		(drill 0.254)
		(layers "F.Cu" "B.Cu")
		(net "PVDDCR_CPU1_P1")
	)
	(via
		(at 125.704854 -275.706332)
		(size 0.4064)
		(drill 0.2032)
		(layers "F.Cu" "B.Cu")
		(net "PVDDCR_CPU1_P1")
	)
	(via
		(at 93.462094 -317.928752)
		(size 0.508)
		(drill 0.254)
		(layers "F.Cu" "B.Cu")
		(net "PVDDCR_CPU1_P1")
	)
	(via
		(at 105.218738 -327.32472)
		(size 0.508)
		(drill 0.254)
		(layers "F.Cu" "B.Cu")
		(net "PVDDCR_CPU1_P1")
	)
	(via
		(at 77.510894 -321.093846)
		(size 0.508)
		(drill 0.254)
		(layers "F.Cu" "B.Cu")
		(net "PVDDCR_CPU1_P1")
	)
	(via
		(at 73.16851 -321.110864)
		(size 0.508)
		(drill 0.254)
		(layers "F.Cu" "B.Cu")
		(net "PVDDCR_CPU1_P1")
	)
	(via
		(at 93.462094 -316.658752)
		(size 0.508)
		(drill 0.254)
		(layers "F.Cu" "B.Cu")
		(net "PVDDCR_CPU1_P1")
	)
	(via
		(at 59.17311 -329.66152)
		(size 0.508)
		(drill 0.254)
		(layers "F.Cu" "B.Cu")
		(net "PVDDCR_CPU1_P1")
	)
	(via
		(at 102.450138 -324.780148)
		(size 0.508)
		(drill 0.254)
		(layers "F.Cu" "B.Cu")
		(net "PVDDCR_CPU1_P1")
	)
	(via
		(at 85.20811 -319.184274)
		(size 0.508)
		(drill 0.254)
		(layers "F.Cu" "B.Cu")
		(net "PVDDCR_CPU1_P1")
	)
	(via
		(at 92.852494 -320.494152)
		(size 0.508)
		(drill 0.254)
		(layers "F.Cu" "B.Cu")
		(net "PVDDCR_CPU1_P1")
	)
	(via
		(at 124.7648 -295.146222)
		(size 0.4064)
		(drill 0.2032)
		(layers "F.Cu" "B.Cu")
		(net "PVDDCR_CPU1_P1")
	)
	(via
		(at 125.704854 -290.286186)
		(size 0.4064)
		(drill 0.2032)
		(layers "F.Cu" "B.Cu")
		(net "PVDDCR_CPU1_P1")
	)
	(via
		(at 106.91114 -269.226284)
		(size 0.4064)
		(drill 0.2032)
		(layers "F.Cu" "B.Cu")
		(net "PVDDCR_CPU1_P1")
	)
	(via
		(at 93.487494 -322.378324)
		(size 0.508)
		(drill 0.254)
		(layers "F.Cu" "B.Cu")
		(net "PVDDCR_CPU1_P1")
	)
	(via
		(at 108.321094 -292.716204)
		(size 0.4064)
		(drill 0.2032)
		(layers "F.Cu" "B.Cu")
		(net "PVDDCR_CPU1_P1")
	)
	(via
		(at 124.294646 -268.416278)
		(size 0.4064)
		(drill 0.2032)
		(layers "F.Cu" "B.Cu")
		(net "PVDDCR_CPU1_P1")
	)
	(via
		(at 109.261148 -289.47618)
		(size 0.4064)
		(drill 0.2032)
		(layers "F.Cu" "B.Cu")
		(net "PVDDCR_CPU1_P1")
	)
	(via
		(at 71.89851 -321.750436)
		(size 0.508)
		(drill 0.254)
		(layers "F.Cu" "B.Cu")
		(net "PVDDCR_CPU1_P1")
	)
	(via
		(at 109.731048 -280.566368)
		(size 0.4064)
		(drill 0.2032)
		(layers "F.Cu" "B.Cu")
		(net "PVDDCR_CPU1_P1")
	)
	(via
		(at 101.180138 -324.780148)
		(size 0.508)
		(drill 0.254)
		(layers "F.Cu" "B.Cu")
		(net "PVDDCR_CPU1_P1")
	)
	(via
		(at 121.944638 -267.606272)
		(size 0.4064)
		(drill 0.2032)
		(layers "F.Cu" "B.Cu")
		(net "PVDDCR_CPU1_P1")
	)
	(via
		(at 98.451162 -283.806392)
		(size 0.4064)
		(drill 0.2032)
		(layers "F.Cu" "B.Cu")
		(net "PVDDCR_CPU1_P1")
	)
	(via
		(at 100.80117 -266.796266)
		(size 0.4064)
		(drill 0.2032)
		(layers "F.Cu" "B.Cu")
		(net "PVDDCR_CPU1_P1")
	)
	(via
		(at 98.135694 -317.928752)
		(size 0.508)
		(drill 0.254)
		(layers "F.Cu" "B.Cu")
		(net "PVDDCR_CPU1_P1")
	)
	(via
		(at 126.644654 -269.226284)
		(size 0.4064)
		(drill 0.2032)
		(layers "F.Cu" "B.Cu")
		(net "PVDDCR_CPU1_P1")
	)
	(via
		(at 105.031032 -291.906198)
		(size 0.4064)
		(drill 0.2032)
		(layers "F.Cu" "B.Cu")
		(net "PVDDCR_CPU1_P1")
	)
	(via
		(at 59.80811 -334.10652)
		(size 0.508)
		(drill 0.254)
		(layers "F.Cu" "B.Cu")
		(net "PVDDCR_CPU1_P1")
	)
	(via
		(at 92.852494 -322.399152)
		(size 0.508)
		(drill 0.254)
		(layers "F.Cu" "B.Cu")
		(net "PVDDCR_CPU1_P1")
	)
	(via
		(at 96.865694 -317.293752)
		(size 0.508)
		(drill 0.254)
		(layers "F.Cu" "B.Cu")
		(net "PVDDCR_CPU1_P1")
	)
	(via
		(at 63.18631 -330.93152)
		(size 0.508)
		(drill 0.254)
		(layers "F.Cu" "B.Cu")
		(net "PVDDCR_CPU1_P1")
	)
	(via
		(at 103.151178 -283.806392)
		(size 0.4064)
		(drill 0.2032)
		(layers "F.Cu" "B.Cu")
		(net "PVDDCR_CPU1_P1")
	)
	(via
		(at 63.18631 -334.10652)
		(size 0.508)
		(drill 0.254)
		(layers "F.Cu" "B.Cu")
		(net "PVDDCR_CPU1_P1")
	)
	(via
		(at 80.889094 -319.184274)
		(size 0.508)
		(drill 0.254)
		(layers "F.Cu" "B.Cu")
		(net "PVDDCR_CPU1_P1")
	)
	(via
		(at 114.894614 -289.47618)
		(size 0.4064)
		(drill 0.2032)
		(layers "F.Cu" "B.Cu")
		(net "PVDDCR_CPU1_P1")
	)
	(via
		(at 120.064784 -272.466308)
		(size 0.4064)
		(drill 0.2032)
		(layers "F.Cu" "B.Cu")
		(net "PVDDCR_CPU1_P1")
	)
	(via
		(at 106.91114 -275.706332)
		(size 0.4064)
		(drill 0.2032)
		(layers "F.Cu" "B.Cu")
		(net "PVDDCR_CPU1_P1")
	)
	(via
		(at 110.200948 -268.416278)
		(size 0.4064)
		(drill 0.2032)
		(layers "F.Cu" "B.Cu")
		(net "PVDDCR_CPU1_P1")
	)
	(via
		(at 100.80117 -268.416278)
		(size 0.4064)
		(drill 0.2032)
		(layers "F.Cu" "B.Cu")
		(net "PVDDCR_CPU1_P1")
	)
	(via
		(at 67.863466 -323.030342)
		(size 0.508)
		(drill 0.254)
		(layers "F.Cu" "B.Cu")
		(net "PVDDCR_CPU1_P1")
	)
	(via
		(at 63.82131 -332.83652)
		(size 0.508)
		(drill 0.254)
		(layers "F.Cu" "B.Cu")
		(net "PVDDCR_CPU1_P1")
	)
	(via
		(at 89.24671 -321.728846)
		(size 0.508)
		(drill 0.254)
		(layers "F.Cu" "B.Cu")
		(net "PVDDCR_CPU1_P1")
	)
	(via
		(at 105.971086 -290.286186)
		(size 0.4064)
		(drill 0.2032)
		(layers "F.Cu" "B.Cu")
		(net "PVDDCR_CPU1_P1")
	)
	(via
		(at 59.80811 -333.47152)
		(size 0.508)
		(drill 0.254)
		(layers "F.Cu" "B.Cu")
		(net "PVDDCR_CPU1_P1")
	)
	(via
		(at 60.44311 -331.56652)
		(size 0.508)
		(drill 0.254)
		(layers "F.Cu" "B.Cu")
		(net "PVDDCR_CPU1_P1")
	)
	(via
		(at 123.824746 -272.466308)
		(size 0.4064)
		(drill 0.2032)
		(layers "F.Cu" "B.Cu")
		(net "PVDDCR_CPU1_P1")
	)
	(via
		(at 85.86851 -321.728846)
		(size 0.508)
		(drill 0.254)
		(layers "F.Cu" "B.Cu")
		(net "PVDDCR_CPU1_P1")
	)
	(via
		(at 88.61171 -321.093846)
		(size 0.508)
		(drill 0.254)
		(layers "F.Cu" "B.Cu")
		(net "PVDDCR_CPU1_P1")
	)
	(via
		(at 106.517694 -327.969626)
		(size 0.508)
		(drill 0.254)
		(layers "F.Cu" "B.Cu")
		(net "PVDDCR_CPU1_P1")
	)
	(via
		(at 129.464816 -295.146222)
		(size 0.4064)
		(drill 0.2032)
		(layers "F.Cu" "B.Cu")
		(net "PVDDCR_CPU1_P1")
	)
	(via
		(at 129.934716 -294.336216)
		(size 0.4064)
		(drill 0.2032)
		(layers "F.Cu" "B.Cu")
		(net "PVDDCR_CPU1_P1")
	)
	(via
		(at 120.064784 -290.286186)
		(size 0.4064)
		(drill 0.2032)
		(layers "F.Cu" "B.Cu")
		(net "PVDDCR_CPU1_P1")
	)
	(via
		(at 98.451162 -275.706332)
		(size 0.4064)
		(drill 0.2032)
		(layers "F.Cu" "B.Cu")
		(net "PVDDCR_CPU1_P1")
	)
	(via
		(at 97.511108 -278.946356)
		(size 0.4064)
		(drill 0.2032)
		(layers "F.Cu" "B.Cu")
		(net "PVDDCR_CPU1_P1")
	)
	(via
		(at 92.827094 -317.928752)
		(size 0.508)
		(drill 0.254)
		(layers "F.Cu" "B.Cu")
		(net "PVDDCR_CPU1_P1")
	)
	(via
		(at 114.424714 -280.566368)
		(size 0.4064)
		(drill 0.2032)
		(layers "F.Cu" "B.Cu")
		(net "PVDDCR_CPU1_P1")
	)
	(via
		(at 101.180138 -324.145148)
		(size 0.508)
		(drill 0.254)
		(layers "F.Cu" "B.Cu")
		(net "PVDDCR_CPU1_P1")
	)
	(via
		(at 63.82131 -329.66152)
		(size 0.508)
		(drill 0.254)
		(layers "F.Cu" "B.Cu")
		(net "PVDDCR_CPU1_P1")
	)
	(via
		(at 114.424714 -267.606272)
		(size 0.4064)
		(drill 0.2032)
		(layers "F.Cu" "B.Cu")
		(net "PVDDCR_CPU1_P1")
	)
	(via
		(at 118.184676 -283.806392)
		(size 0.4064)
		(drill 0.2032)
		(layers "F.Cu" "B.Cu")
		(net "PVDDCR_CPU1_P1")
	)
	(via
		(at 97.511108 -275.706332)
		(size 0.4064)
		(drill 0.2032)
		(layers "F.Cu" "B.Cu")
		(net "PVDDCR_CPU1_P1")
	)
	(via
		(at 121.944638 -295.146222)
		(size 0.4064)
		(drill 0.2032)
		(layers "F.Cu" "B.Cu")
		(net "PVDDCR_CPU1_P1")
	)
	(via
		(at 76.215494 -319.184274)
		(size 0.508)
		(drill 0.254)
		(layers "F.Cu" "B.Cu")
		(net "PVDDCR_CPU1_P1")
	)
	(via
		(at 59.80811 -330.93152)
		(size 0.508)
		(drill 0.254)
		(layers "F.Cu" "B.Cu")
		(net "PVDDCR_CPU1_P1")
	)
	(via
		(at 101.180138 -321.605148)
		(size 0.508)
		(drill 0.254)
		(layers "F.Cu" "B.Cu")
		(net "PVDDCR_CPU1_P1")
	)
	(via
		(at 126.644654 -278.946356)
		(size 0.4064)
		(drill 0.2032)
		(layers "F.Cu" "B.Cu")
		(net "PVDDCR_CPU1_P1")
	)
	(via
		(at 77.510894 -322.363846)
		(size 0.508)
		(drill 0.254)
		(layers "F.Cu" "B.Cu")
		(net "PVDDCR_CPU1_P1")
	)
	(via
		(at 120.064784 -269.226284)
		(size 0.4064)
		(drill 0.2032)
		(layers "F.Cu" "B.Cu")
		(net "PVDDCR_CPU1_P1")
	)
	(via
		(at 72.53351 -317.935864)
		(size 0.508)
		(drill 0.254)
		(layers "F.Cu" "B.Cu")
		(net "PVDDCR_CPU1_P1")
	)
	(via
		(at 101.205538 -327.345548)
		(size 0.508)
		(drill 0.254)
		(layers "F.Cu" "B.Cu")
		(net "PVDDCR_CPU1_P1")
	)
	(via
		(at 98.135694 -321.764152)
		(size 0.508)
		(drill 0.254)
		(layers "F.Cu" "B.Cu")
		(net "PVDDCR_CPU1_P1")
	)
	(via
		(at 71.876666 -323.030342)
		(size 0.508)
		(drill 0.254)
		(layers "F.Cu" "B.Cu")
		(net "PVDDCR_CPU1_P1")
	)
	(via
		(at 97.500694 -321.108324)
		(size 0.508)
		(drill 0.254)
		(layers "F.Cu" "B.Cu")
		(net "PVDDCR_CPU1_P1")
	)
	(via
		(at 110.200948 -271.656302)
		(size 0.4064)
		(drill 0.2032)
		(layers "F.Cu" "B.Cu")
		(net "PVDDCR_CPU1_P1")
	)
	(via
		(at 89.24671 -321.093846)
		(size 0.508)
		(drill 0.254)
		(layers "F.Cu" "B.Cu")
		(net "PVDDCR_CPU1_P1")
	)
	(via
		(at 63.82131 -330.93152)
		(size 0.508)
		(drill 0.254)
		(layers "F.Cu" "B.Cu")
		(net "PVDDCR_CPU1_P1")
	)
	(via
		(at 97.511108 -283.806392)
		(size 0.4064)
		(drill 0.2032)
		(layers "F.Cu" "B.Cu")
		(net "PVDDCR_CPU1_P1")
	)
	(via
		(at 97.500694 -317.293752)
		(size 0.508)
		(drill 0.254)
		(layers "F.Cu" "B.Cu")
		(net "PVDDCR_CPU1_P1")
	)
	(via
		(at 106.91114 -272.466308)
		(size 0.4064)
		(drill 0.2032)
		(layers "F.Cu" "B.Cu")
		(net "PVDDCR_CPU1_P1")
	)
	(via
		(at 101.27107 -283.806392)
		(size 0.4064)
		(drill 0.2032)
		(layers "F.Cu" "B.Cu")
		(net "PVDDCR_CPU1_P1")
	)
	(via
		(at 76.850494 -318.549274)
		(size 0.508)
		(drill 0.254)
		(layers "F.Cu" "B.Cu")
		(net "PVDDCR_CPU1_P1")
	)
	(via
		(at 121.004838 -269.226284)
		(size 0.4064)
		(drill 0.2032)
		(layers "F.Cu" "B.Cu")
		(net "PVDDCR_CPU1_P1")
	)
	(via
		(at 100.331016 -275.706332)
		(size 0.4064)
		(drill 0.2032)
		(layers "F.Cu" "B.Cu")
		(net "PVDDCR_CPU1_P1")
	)
	(via
		(at 92.827094 -317.293752)
		(size 0.508)
		(drill 0.254)
		(layers "F.Cu" "B.Cu")
		(net "PVDDCR_CPU1_P1")
	)
	(via
		(at 107.38104 -281.376374)
		(size 0.4064)
		(drill 0.2032)
		(layers "F.Cu" "B.Cu")
		(net "PVDDCR_CPU1_P1")
	)
	(via
		(at 81.524094 -319.819274)
		(size 0.508)
		(drill 0.254)
		(layers "F.Cu" "B.Cu")
		(net "PVDDCR_CPU1_P1")
	)
	(via
		(at 122.884692 -290.286186)
		(size 0.4064)
		(drill 0.2032)
		(layers "F.Cu" "B.Cu")
		(net "PVDDCR_CPU1_P1")
	)
	(via
		(at 85.84311 -316.644274)
		(size 0.508)
		(drill 0.254)
		(layers "F.Cu" "B.Cu")
		(net "PVDDCR_CPU1_P1")
	)
	(via
		(at 101.205538 -326.075548)
		(size 0.508)
		(drill 0.254)
		(layers "F.Cu" "B.Cu")
		(net "PVDDCR_CPU1_P1")
	)
	(via
		(at 80.254094 -316.644274)
		(size 0.508)
		(drill 0.254)
		(layers "F.Cu" "B.Cu")
		(net "PVDDCR_CPU1_P1")
	)
	(via
		(at 80.889094 -319.819274)
		(size 0.508)
		(drill 0.254)
		(layers "F.Cu" "B.Cu")
		(net "PVDDCR_CPU1_P1")
	)
	(via
		(at 114.894614 -292.716204)
		(size 0.4064)
		(drill 0.2032)
		(layers "F.Cu" "B.Cu")
		(net "PVDDCR_CPU1_P1")
	)
	(via
		(at 94.122494 -320.473324)
		(size 0.508)
		(drill 0.254)
		(layers "F.Cu" "B.Cu")
		(net "PVDDCR_CPU1_P1")
	)
	(via
		(at 101.27107 -287.046162)
		(size 0.4064)
		(drill 0.2032)
		(layers "F.Cu" "B.Cu")
		(net "PVDDCR_CPU1_P1")
	)
	(via
		(at 69.12991 -319.205864)
		(size 0.508)
		(drill 0.254)
		(layers "F.Cu" "B.Cu")
		(net "PVDDCR_CPU1_P1")
	)
	(via
		(at 113.954814 -274.896326)
		(size 0.4064)
		(drill 0.2032)
		(layers "F.Cu" "B.Cu")
		(net "PVDDCR_CPU1_P1")
	)
	(via
		(at 101.27107 -290.286186)
		(size 0.4064)
		(drill 0.2032)
		(layers "F.Cu" "B.Cu")
		(net "PVDDCR_CPU1_P1")
	)
	(via
		(at 59.17311 -330.93152)
		(size 0.508)
		(drill 0.254)
		(layers "F.Cu" "B.Cu")
		(net "PVDDCR_CPU1_P1")
	)
	(via
		(at 89.88171 -319.184274)
		(size 0.508)
		(drill 0.254)
		(layers "F.Cu" "B.Cu")
		(net "PVDDCR_CPU1_P1")
	)
	(via
		(at 109.261148 -286.23641)
		(size 0.4064)
		(drill 0.2032)
		(layers "F.Cu" "B.Cu")
		(net "PVDDCR_CPU1_P1")
	)
	(via
		(at 77.510894 -321.728846)
		(size 0.508)
		(drill 0.254)
		(layers "F.Cu" "B.Cu")
		(net "PVDDCR_CPU1_P1")
	)
	(via
		(at 63.82131 -330.29652)
		(size 0.508)
		(drill 0.254)
		(layers "F.Cu" "B.Cu")
		(net "PVDDCR_CPU1_P1")
	)
	(via
		(at 126.644654 -295.146222)
		(size 0.4064)
		(drill 0.2032)
		(layers "F.Cu" "B.Cu")
		(net "PVDDCR_CPU1_P1")
	)
	(via
		(at 76.215494 -320.454274)
		(size 0.508)
		(drill 0.254)
		(layers "F.Cu" "B.Cu")
		(net "PVDDCR_CPU1_P1")
	)
	(via
		(at 59.17311 -330.29652)
		(size 0.508)
		(drill 0.254)
		(layers "F.Cu" "B.Cu")
		(net "PVDDCR_CPU1_P1")
	)
	(via
		(at 99.390962 -291.906198)
		(size 0.4064)
		(drill 0.2032)
		(layers "F.Cu" "B.Cu")
		(net "PVDDCR_CPU1_P1")
	)
	(via
		(at 122.884692 -278.946356)
		(size 0.4064)
		(drill 0.2032)
		(layers "F.Cu" "B.Cu")
		(net "PVDDCR_CPU1_P1")
	)
	(via
		(at 116.304822 -295.146222)
		(size 0.4064)
		(drill 0.2032)
		(layers "F.Cu" "B.Cu")
		(net "PVDDCR_CPU1_P1")
	)
	(via
		(at 113.954814 -282.996386)
		(size 0.4064)
		(drill 0.2032)
		(layers "F.Cu" "B.Cu")
		(net "PVDDCR_CPU1_P1")
	)
	(via
		(at 77.48905 -323.008752)
		(size 0.508)
		(drill 0.254)
		(layers "F.Cu" "B.Cu")
		(net "PVDDCR_CPU1_P1")
	)
	(via
		(at 92.852494 -321.764152)
		(size 0.508)
		(drill 0.254)
		(layers "F.Cu" "B.Cu")
		(net "PVDDCR_CPU1_P1")
	)
	(via
		(at 71.89851 -319.840864)
		(size 0.508)
		(drill 0.254)
		(layers "F.Cu" "B.Cu")
		(net "PVDDCR_CPU1_P1")
	)
	(via
		(at 76.215494 -316.644274)
		(size 0.508)
		(drill 0.254)
		(layers "F.Cu" "B.Cu")
		(net "PVDDCR_CPU1_P1")
	)
	(via
		(at 105.218738 -323.510148)
		(size 0.508)
		(drill 0.254)
		(layers "F.Cu" "B.Cu")
		(net "PVDDCR_CPU1_P1")
	)
	(via
		(at 110.671102 -267.606272)
		(size 0.4064)
		(drill 0.2032)
		(layers "F.Cu" "B.Cu")
		(net "PVDDCR_CPU1_P1")
	)
	(via
		(at 85.86851 -320.458846)
		(size 0.508)
		(drill 0.254)
		(layers "F.Cu" "B.Cu")
		(net "PVDDCR_CPU1_P1")
	)
	(via
		(at 125.704854 -278.946356)
		(size 0.4064)
		(drill 0.2032)
		(layers "F.Cu" "B.Cu")
		(net "PVDDCR_CPU1_P1")
	)
	(via
		(at 92.827094 -319.198752)
		(size 0.508)
		(drill 0.254)
		(layers "F.Cu" "B.Cu")
		(net "PVDDCR_CPU1_P1")
	)
	(via
		(at 102.450138 -322.875148)
		(size 0.508)
		(drill 0.254)
		(layers "F.Cu" "B.Cu")
		(net "PVDDCR_CPU1_P1")
	)
	(via
		(at 107.85094 -295.146222)
		(size 0.4064)
		(drill 0.2032)
		(layers "F.Cu" "B.Cu")
		(net "PVDDCR_CPU1_P1")
	)
	(via
		(at 121.004838 -290.286186)
		(size 0.4064)
		(drill 0.2032)
		(layers "F.Cu" "B.Cu")
		(net "PVDDCR_CPU1_P1")
	)
	(via
		(at 68.52031 -321.115436)
		(size 0.508)
		(drill 0.254)
		(layers "F.Cu" "B.Cu")
		(net "PVDDCR_CPU1_P1")
	)
	(via
		(at 89.88171 -317.914274)
		(size 0.508)
		(drill 0.254)
		(layers "F.Cu" "B.Cu")
		(net "PVDDCR_CPU1_P1")
	)
	(via
		(at 89.88171 -320.454274)
		(size 0.508)
		(drill 0.254)
		(layers "F.Cu" "B.Cu")
		(net "PVDDCR_CPU1_P1")
	)
	(via
		(at 71.89851 -322.385436)
		(size 0.508)
		(drill 0.254)
		(layers "F.Cu" "B.Cu")
		(net "PVDDCR_CPU1_P1")
	)
	(via
		(at 84.57311 -317.279274)
		(size 0.508)
		(drill 0.254)
		(layers "F.Cu" "B.Cu")
		(net "PVDDCR_CPU1_P1")
	)
	(via
		(at 105.971086 -269.226284)
		(size 0.4064)
		(drill 0.2032)
		(layers "F.Cu" "B.Cu")
		(net "PVDDCR_CPU1_P1")
	)
	(via
		(at 63.82131 -334.10652)
		(size 0.508)
		(drill 0.254)
		(layers "F.Cu" "B.Cu")
		(net "PVDDCR_CPU1_P1")
	)
	(via
		(at 80.254094 -317.279274)
		(size 0.508)
		(drill 0.254)
		(layers "F.Cu" "B.Cu")
		(net "PVDDCR_CPU1_P1")
	)
	(via
		(at 107.85094 -291.906198)
		(size 0.4064)
		(drill 0.2032)
		(layers "F.Cu" "B.Cu")
		(net "PVDDCR_CPU1_P1")
	)
	(via
		(at 127.584708 -291.906198)
		(size 0.4064)
		(drill 0.2032)
		(layers "F.Cu" "B.Cu")
		(net "PVDDCR_CPU1_P1")
	)
	(via
		(at 92.827094 -318.563752)
		(size 0.508)
		(drill 0.254)
		(layers "F.Cu" "B.Cu")
		(net "PVDDCR_CPU1_P1")
	)
	(via
		(at 84.572094 -321.738752)
		(size 0.508)
		(drill 0.254)
		(layers "F.Cu" "B.Cu")
		(net "PVDDCR_CPU1_P1")
	)
	(via
		(at 114.894614 -286.23641)
		(size 0.4064)
		(drill 0.2032)
		(layers "F.Cu" "B.Cu")
		(net "PVDDCR_CPU1_P1")
	)
	(via
		(at 80.254094 -317.914274)
		(size 0.508)
		(drill 0.254)
		(layers "F.Cu" "B.Cu")
		(net "PVDDCR_CPU1_P1")
	)
	(via
		(at 97.500694 -319.198752)
		(size 0.508)
		(drill 0.254)
		(layers "F.Cu" "B.Cu")
		(net "PVDDCR_CPU1_P1")
	)
	(via
		(at 80.254094 -319.184274)
		(size 0.508)
		(drill 0.254)
		(layers "F.Cu" "B.Cu")
		(net "PVDDCR_CPU1_P1")
	)
	(via
		(at 122.884692 -283.806392)
		(size 0.4064)
		(drill 0.2032)
		(layers "F.Cu" "B.Cu")
		(net "PVDDCR_CPU1_P1")
	)
	(via
		(at 101.180138 -322.240148)
		(size 0.508)
		(drill 0.254)
		(layers "F.Cu" "B.Cu")
		(net "PVDDCR_CPU1_P1")
	)
	(via
		(at 102.681024 -292.716204)
		(size 0.4064)
		(drill 0.2032)
		(layers "F.Cu" "B.Cu")
		(net "PVDDCR_CPU1_P1")
	)
	(via
		(at 105.853738 -325.41972)
		(size 0.508)
		(drill 0.254)
		(layers "F.Cu" "B.Cu")
		(net "PVDDCR_CPU1_P1")
	)
	(via
		(at 118.184676 -295.146222)
		(size 0.4064)
		(drill 0.2032)
		(layers "F.Cu" "B.Cu")
		(net "PVDDCR_CPU1_P1")
	)
	(via
		(at 80.889094 -317.279274)
		(size 0.508)
		(drill 0.254)
		(layers "F.Cu" "B.Cu")
		(net "PVDDCR_CPU1_P1")
	)
	(via
		(at 100.331016 -269.226284)
		(size 0.4064)
		(drill 0.2032)
		(layers "F.Cu" "B.Cu")
		(net "PVDDCR_CPU1_P1")
	)
	(via
		(at 96.865694 -319.198752)
		(size 0.508)
		(drill 0.254)
		(layers "F.Cu" "B.Cu")
		(net "PVDDCR_CPU1_P1")
	)
	(via
		(at 73.16851 -319.840864)
		(size 0.508)
		(drill 0.254)
		(layers "F.Cu" "B.Cu")
		(net "PVDDCR_CPU1_P1")
	)
	(via
		(at 96.865694 -316.658752)
		(size 0.508)
		(drill 0.254)
		(layers "F.Cu" "B.Cu")
		(net "PVDDCR_CPU1_P1")
	)
	(via
		(at 97.500694 -323.034152)
		(size 0.508)
		(drill 0.254)
		(layers "F.Cu" "B.Cu")
		(net "PVDDCR_CPU1_P1")
	)
	(via
		(at 76.850494 -317.914274)
		(size 0.508)
		(drill 0.254)
		(layers "F.Cu" "B.Cu")
		(net "PVDDCR_CPU1_P1")
	)
	(via
		(at 72.53351 -321.115436)
		(size 0.508)
		(drill 0.254)
		(layers "F.Cu" "B.Cu")
		(net "PVDDCR_CPU1_P1")
	)
	(via
		(at 117.244622 -275.706332)
		(size 0.4064)
		(drill 0.2032)
		(layers "F.Cu" "B.Cu")
		(net "PVDDCR_CPU1_P1")
	)
	(via
		(at 106.517694 -327.334626)
		(size 0.508)
		(drill 0.254)
		(layers "F.Cu" "B.Cu")
		(net "PVDDCR_CPU1_P1")
	)
	(via
		(at 69.12991 -319.840864)
		(size 0.508)
		(drill 0.254)
		(layers "F.Cu" "B.Cu")
		(net "PVDDCR_CPU1_P1")
	)
	(via
		(at 108.790994 -280.566368)
		(size 0.4064)
		(drill 0.2032)
		(layers "F.Cu" "B.Cu")
		(net "PVDDCR_CPU1_P1")
	)
	(via
		(at 105.853738 -322.875148)
		(size 0.508)
		(drill 0.254)
		(layers "F.Cu" "B.Cu")
		(net "PVDDCR_CPU1_P1")
	)
	(via
		(at 101.205538 -326.710548)
		(size 0.508)
		(drill 0.254)
		(layers "F.Cu" "B.Cu")
		(net "PVDDCR_CPU1_P1")
	)
	(via
		(at 113.954814 -271.656302)
		(size 0.4064)
		(drill 0.2032)
		(layers "F.Cu" "B.Cu")
		(net "PVDDCR_CPU1_P1")
	)
	(via
		(at 69.15531 -322.385436)
		(size 0.508)
		(drill 0.254)
		(layers "F.Cu" "B.Cu")
		(net "PVDDCR_CPU1_P1")
	)
	(via
		(at 77.485494 -318.549274)
		(size 0.508)
		(drill 0.254)
		(layers "F.Cu" "B.Cu")
		(net "PVDDCR_CPU1_P1")
	)
	(via
		(at 121.004584 -287.046162)
		(size 0.4064)
		(drill 0.2032)
		(layers "F.Cu" "B.Cu")
		(net "PVDDCR_CPU1_P1")
	)
	(via
		(at 105.218738 -326.05472)
		(size 0.508)
		(drill 0.254)
		(layers "F.Cu" "B.Cu")
		(net "PVDDCR_CPU1_P1")
	)
	(via
		(at 102.211124 -295.146222)
		(size 0.4064)
		(drill 0.2032)
		(layers "F.Cu" "B.Cu")
		(net "PVDDCR_CPU1_P1")
	)
	(via
		(at 113.954814 -286.23641)
		(size 0.4064)
		(drill 0.2032)
		(layers "F.Cu" "B.Cu")
		(net "PVDDCR_CPU1_P1")
	)
	(via
		(at 103.151178 -278.946356)
		(size 0.4064)
		(drill 0.2032)
		(layers "F.Cu" "B.Cu")
		(net "PVDDCR_CPU1_P1")
	)
	(via
		(at 109.261148 -271.656302)
		(size 0.4064)
		(drill 0.2032)
		(layers "F.Cu" "B.Cu")
		(net "PVDDCR_CPU1_P1")
	)
	(via
		(at 89.24671 -319.184274)
		(size 0.508)
		(drill 0.254)
		(layers "F.Cu" "B.Cu")
		(net "PVDDCR_CPU1_P1")
	)
	(via
		(at 60.44311 -329.66152)
		(size 0.508)
		(drill 0.254)
		(layers "F.Cu" "B.Cu")
		(net "PVDDCR_CPU1_P1")
	)
	(via
		(at 121.004838 -272.466308)
		(size 0.4064)
		(drill 0.2032)
		(layers "F.Cu" "B.Cu")
		(net "PVDDCR_CPU1_P1")
	)
	(via
		(at 93.487494 -320.473324)
		(size 0.508)
		(drill 0.254)
		(layers "F.Cu" "B.Cu")
		(net "PVDDCR_CPU1_P1")
	)
	(via
		(at 105.971086 -287.046162)
		(size 0.4064)
		(drill 0.2032)
		(layers "F.Cu" "B.Cu")
		(net "PVDDCR_CPU1_P1")
	)
	(via
		(at 68.498466 -323.030342)
		(size 0.508)
		(drill 0.254)
		(layers "F.Cu" "B.Cu")
		(net "PVDDCR_CPU1_P1")
	)
	(via
		(at 101.209094 -327.995026)
		(size 0.508)
		(drill 0.254)
		(layers "F.Cu" "B.Cu")
		(net "PVDDCR_CPU1_P1")
	)
	(via
		(at 118.65483 -292.716204)
		(size 0.4064)
		(drill 0.2032)
		(layers "F.Cu" "B.Cu")
		(net "PVDDCR_CPU1_P1")
	)
	(via
		(at 77.510894 -320.458846)
		(size 0.508)
		(drill 0.254)
		(layers "F.Cu" "B.Cu")
		(net "PVDDCR_CPU1_P1")
	)
	(via
		(at 72.53351 -322.385436)
		(size 0.508)
		(drill 0.254)
		(layers "F.Cu" "B.Cu")
		(net "PVDDCR_CPU1_P1")
	)
	(via
		(at 94.122494 -322.378324)
		(size 0.508)
		(drill 0.254)
		(layers "F.Cu" "B.Cu")
		(net "PVDDCR_CPU1_P1")
	)
	(via
		(at 102.479094 -327.995026)
		(size 0.508)
		(drill 0.254)
		(layers "F.Cu" "B.Cu")
		(net "PVDDCR_CPU1_P1")
	)
	(via
		(at 89.88171 -316.644274)
		(size 0.508)
		(drill 0.254)
		(layers "F.Cu" "B.Cu")
		(net "PVDDCR_CPU1_P1")
	)
	(via
		(at 98.135694 -318.563752)
		(size 0.508)
		(drill 0.254)
		(layers "F.Cu" "B.Cu")
		(net "PVDDCR_CPU1_P1")
	)
	(via
		(at 69.15531 -320.480436)
		(size 0.508)
		(drill 0.254)
		(layers "F.Cu" "B.Cu")
		(net "PVDDCR_CPU1_P1")
	)
	(via
		(at 84.572094 -322.373752)
		(size 0.508)
		(drill 0.254)
		(layers "F.Cu" "B.Cu")
		(net "PVDDCR_CPU1_P1")
	)
	(via
		(at 121.474738 -292.716204)
		(size 0.4064)
		(drill 0.2032)
		(layers "F.Cu" "B.Cu")
		(net "PVDDCR_CPU1_P1")
	)
	(via
		(at 122.884692 -275.706332)
		(size 0.4064)
		(drill 0.2032)
		(layers "F.Cu" "B.Cu")
		(net "PVDDCR_CPU1_P1")
	)
	(via
		(at 80.86725 -323.008752)
		(size 0.508)
		(drill 0.254)
		(layers "F.Cu" "B.Cu")
		(net "PVDDCR_CPU1_P1")
	)
	(via
		(at 115.834668 -292.716204)
		(size 0.4064)
		(drill 0.2032)
		(layers "F.Cu" "B.Cu")
		(net "PVDDCR_CPU1_P1")
	)
	(via
		(at 105.031032 -267.606272)
		(size 0.4064)
		(drill 0.2032)
		(layers "F.Cu" "B.Cu")
		(net "PVDDCR_CPU1_P1")
	)
	(via
		(at 94.097094 -316.658752)
		(size 0.508)
		(drill 0.254)
		(layers "F.Cu" "B.Cu")
		(net "PVDDCR_CPU1_P1")
	)
	(via
		(at 81.50225 -323.008752)
		(size 0.508)
		(drill 0.254)
		(layers "F.Cu" "B.Cu")
		(net "PVDDCR_CPU1_P1")
	)
	(via
		(at 76.85405 -323.008752)
		(size 0.508)
		(drill 0.254)
		(layers "F.Cu" "B.Cu")
		(net "PVDDCR_CPU1_P1")
	)
	(via
		(at 97.500694 -319.833752)
		(size 0.508)
		(drill 0.254)
		(layers "F.Cu" "B.Cu")
		(net "PVDDCR_CPU1_P1")
	)
	(via
		(at 73.16851 -318.570864)
		(size 0.508)
		(drill 0.254)
		(layers "F.Cu" "B.Cu")
		(net "PVDDCR_CPU1_P1")
	)
	(via
		(at 68.52031 -320.480436)
		(size 0.508)
		(drill 0.254)
		(layers "F.Cu" "B.Cu")
		(net "PVDDCR_CPU1_P1")
	)
	(via
		(at 88.61171 -318.549274)
		(size 0.508)
		(drill 0.254)
		(layers "F.Cu" "B.Cu")
		(net "PVDDCR_CPU1_P1")
	)
	(via
		(at 97.511108 -272.466308)
		(size 0.4064)
		(drill 0.2032)
		(layers "F.Cu" "B.Cu")
		(net "PVDDCR_CPU1_P1")
	)
	(via
		(at 96.865694 -317.928752)
		(size 0.508)
		(drill 0.254)
		(layers "F.Cu" "B.Cu")
		(net "PVDDCR_CPU1_P1")
	)
	(via
		(at 98.451162 -287.046162)
		(size 0.4064)
		(drill 0.2032)
		(layers "F.Cu" "B.Cu")
		(net "PVDDCR_CPU1_P1")
	)
	(via
		(at 63.82131 -331.56652)
		(size 0.508)
		(drill 0.254)
		(layers "F.Cu" "B.Cu")
		(net "PVDDCR_CPU1_P1")
	)
	(via
		(at 73.16851 -322.380864)
		(size 0.508)
		(drill 0.254)
		(layers "F.Cu" "B.Cu")
		(net "PVDDCR_CPU1_P1")
	)
	(via
		(at 59.17311 -333.47152)
		(size 0.508)
		(drill 0.254)
		(layers "F.Cu" "B.Cu")
		(net "PVDDCR_CPU1_P1")
	)
	(via
		(at 60.44311 -332.20152)
		(size 0.508)
		(drill 0.254)
		(layers "F.Cu" "B.Cu")
		(net "PVDDCR_CPU1_P1")
	)
	(via
		(at 105.218738 -322.875148)
		(size 0.508)
		(drill 0.254)
		(layers "F.Cu" "B.Cu")
		(net "PVDDCR_CPU1_P1")
	)
	(via
		(at 98.135694 -319.833752)
		(size 0.508)
		(drill 0.254)
		(layers "F.Cu" "B.Cu")
		(net "PVDDCR_CPU1_P1")
	)
	(via
		(at 77.485494 -319.819274)
		(size 0.508)
		(drill 0.254)
		(layers "F.Cu" "B.Cu")
		(net "PVDDCR_CPU1_P1")
	)
	(via
		(at 63.18631 -332.83652)
		(size 0.508)
		(drill 0.254)
		(layers "F.Cu" "B.Cu")
		(net "PVDDCR_CPU1_P1")
	)
	(via
		(at 76.215494 -321.089274)
		(size 0.508)
		(drill 0.254)
		(layers "F.Cu" "B.Cu")
		(net "PVDDCR_CPU1_P1")
	)
	(via
		(at 80.889094 -317.914274)
		(size 0.508)
		(drill 0.254)
		(layers "F.Cu" "B.Cu")
		(net "PVDDCR_CPU1_P1")
	)
	(via
		(at 102.475538 -326.05472)
		(size 0.508)
		(drill 0.254)
		(layers "F.Cu" "B.Cu")
		(net "PVDDCR_CPU1_P1")
	)
	(via
		(at 101.815138 -323.510148)
		(size 0.508)
		(drill 0.254)
		(layers "F.Cu" "B.Cu")
		(net "PVDDCR_CPU1_P1")
	)
	(via
		(at 89.24671 -320.458846)
		(size 0.508)
		(drill 0.254)
		(layers "F.Cu" "B.Cu")
		(net "PVDDCR_CPU1_P1")
	)
	(via
		(at 76.850494 -319.819274)
		(size 0.508)
		(drill 0.254)
		(layers "F.Cu" "B.Cu")
		(net "PVDDCR_CPU1_P1")
	)
	(via
		(at 89.88171 -321.724274)
		(size 0.508)
		(drill 0.254)
		(layers "F.Cu" "B.Cu")
		(net "PVDDCR_CPU1_P1")
	)
	(via
		(at 93.751146 -295.146222)
		(size 0.4064)
		(drill 0.2032)
		(layers "F.Cu" "B.Cu")
		(net "PVDDCR_CPU1_P1")
	)
	(via
		(at 101.180138 -322.875148)
		(size 0.508)
		(drill 0.254)
		(layers "F.Cu" "B.Cu")
		(net "PVDDCR_CPU1_P1")
	)
	(via
		(at 67.863466 -321.125342)
		(size 0.508)
		(drill 0.254)
		(layers "F.Cu" "B.Cu")
		(net "PVDDCR_CPU1_P1")
	)
	(via
		(at 89.880694 -323.008752)
		(size 0.508)
		(drill 0.254)
		(layers "F.Cu" "B.Cu")
		(net "PVDDCR_CPU1_P1")
	)
	(via
		(at 76.215494 -321.724274)
		(size 0.508)
		(drill 0.254)
		(layers "F.Cu" "B.Cu")
		(net "PVDDCR_CPU1_P1")
	)
	(via
		(at 97.511108 -287.046162)
		(size 0.4064)
		(drill 0.2032)
		(layers "F.Cu" "B.Cu")
		(net "PVDDCR_CPU1_P1")
	)
	(via
		(at 73.16851 -316.665864)
		(size 0.508)
		(drill 0.254)
		(layers "F.Cu" "B.Cu")
		(net "PVDDCR_CPU1_P1")
	)
	(via
		(at 59.80811 -330.29652)
		(size 0.508)
		(drill 0.254)
		(layers "F.Cu" "B.Cu")
		(net "PVDDCR_CPU1_P1")
	)
	(via
		(at 98.135694 -320.494152)
		(size 0.508)
		(drill 0.254)
		(layers "F.Cu" "B.Cu")
		(net "PVDDCR_CPU1_P1")
	)
	(via
		(at 101.815138 -321.605148)
		(size 0.508)
		(drill 0.254)
		(layers "F.Cu" "B.Cu")
		(net "PVDDCR_CPU1_P1")
	)
	(via
		(at 63.82131 -328.39152)
		(size 0.508)
		(drill 0.254)
		(layers "F.Cu" "B.Cu")
		(net "PVDDCR_CPU1_P1")
	)
	(via
		(at 77.51445 -315.922152)
		(size 0.6604)
		(drill 0.3302)
		(layers "F.Cu" "B.Cu")
		(net "PVDDCR_CPU1_P1")
	)
	(via
		(at 76.875894 -322.363846)
		(size 0.508)
		(drill 0.254)
		(layers "F.Cu" "B.Cu")
		(net "PVDDCR_CPU1_P1")
	)
	(via
		(at 120.534684 -268.416278)
		(size 0.4064)
		(drill 0.2032)
		(layers "F.Cu" "B.Cu")
		(net "PVDDCR_CPU1_P1")
	)
	(via
		(at 94.097094 -319.833752)
		(size 0.508)
		(drill 0.254)
		(layers "F.Cu" "B.Cu")
		(net "PVDDCR_CPU1_P1")
	)
	(via
		(at 81.524094 -319.184274)
		(size 0.508)
		(drill 0.254)
		(layers "F.Cu" "B.Cu")
		(net "PVDDCR_CPU1_P1")
	)
	(via
		(at 96.865694 -320.473324)
		(size 0.508)
		(drill 0.254)
		(layers "F.Cu" "B.Cu")
		(net "PVDDCR_CPU1_P1")
	)
	(via
		(at 105.853738 -327.32472)
		(size 0.508)
		(drill 0.254)
		(layers "F.Cu" "B.Cu")
		(net "PVDDCR_CPU1_P1")
	)
	(via
		(at 97.500694 -317.928752)
		(size 0.508)
		(drill 0.254)
		(layers "F.Cu" "B.Cu")
		(net "PVDDCR_CPU1_P1")
	)
	(via
		(at 69.15531 -321.750436)
		(size 0.508)
		(drill 0.254)
		(layers "F.Cu" "B.Cu")
		(net "PVDDCR_CPU1_P1")
	)
	(via
		(at 109.261148 -274.896326)
		(size 0.4064)
		(drill 0.2032)
		(layers "F.Cu" "B.Cu")
		(net "PVDDCR_CPU1_P1")
	)
	(via
		(at 94.221046 -294.336216)
		(size 0.4064)
		(drill 0.2032)
		(layers "F.Cu" "B.Cu")
		(net "PVDDCR_CPU1_P1")
	)
	(via
		(at 76.215494 -318.549274)
		(size 0.508)
		(drill 0.254)
		(layers "F.Cu" "B.Cu")
		(net "PVDDCR_CPU1_P1")
	)
	(via
		(at 96.865694 -321.743324)
		(size 0.508)
		(drill 0.254)
		(layers "F.Cu" "B.Cu")
		(net "PVDDCR_CPU1_P1")
	)
	(via
		(at 101.205538 -325.440548)
		(size 0.508)
		(drill 0.254)
		(layers "F.Cu" "B.Cu")
		(net "PVDDCR_CPU1_P1")
	)
	(via
		(at 109.261148 -292.716204)
		(size 0.4064)
		(drill 0.2032)
		(layers "F.Cu" "B.Cu")
		(net "PVDDCR_CPU1_P1")
	)
	(via
		(at 96.865694 -322.378324)
		(size 0.508)
		(drill 0.254)
		(layers "F.Cu" "B.Cu")
		(net "PVDDCR_CPU1_P1")
	)
	(via
		(at 71.89851 -316.665864)
		(size 0.508)
		(drill 0.254)
		(layers "F.Cu" "B.Cu")
		(net "PVDDCR_CPU1_P1")
	)
	(via
		(at 106.488738 -322.240148)
		(size 0.508)
		(drill 0.254)
		(layers "F.Cu" "B.Cu")
		(net "PVDDCR_CPU1_P1")
	)
	(via
		(at 92.852494 -321.129152)
		(size 0.508)
		(drill 0.254)
		(layers "F.Cu" "B.Cu")
		(net "PVDDCR_CPU1_P1")
	)
	(via
		(at 76.215494 -317.914274)
		(size 0.508)
		(drill 0.254)
		(layers "F.Cu" "B.Cu")
		(net "PVDDCR_CPU1_P1")
	)
	(via
		(at 101.815138 -322.875148)
		(size 0.508)
		(drill 0.254)
		(layers "F.Cu" "B.Cu")
		(net "PVDDCR_CPU1_P1")
	)
	(via
		(at 120.534684 -281.376374)
		(size 0.4064)
		(drill 0.2032)
		(layers "F.Cu" "B.Cu")
		(net "PVDDCR_CPU1_P1")
	)
	(via
		(at 92.827094 -316.658752)
		(size 0.508)
		(drill 0.254)
		(layers "F.Cu" "B.Cu")
		(net "PVDDCR_CPU1_P1")
	)
	(via
		(at 104.090978 -269.226284)
		(size 0.4064)
		(drill 0.2032)
		(layers "F.Cu" "B.Cu")
		(net "PVDDCR_CPU1_P1")
	)
	(via
		(at 71.89851 -321.115436)
		(size 0.508)
		(drill 0.254)
		(layers "F.Cu" "B.Cu")
		(net "PVDDCR_CPU1_P1")
	)
	(via
		(at 122.884692 -272.466308)
		(size 0.4064)
		(drill 0.2032)
		(layers "F.Cu" "B.Cu")
		(net "PVDDCR_CPU1_P1")
	)
	(via
		(at 72.53351 -319.840864)
		(size 0.508)
		(drill 0.254)
		(layers "F.Cu" "B.Cu")
		(net "PVDDCR_CPU1_P1")
	)
	(via
		(at 63.18631 -331.56652)
		(size 0.508)
		(drill 0.254)
		(layers "F.Cu" "B.Cu")
		(net "PVDDCR_CPU1_P1")
	)
	(via
		(at 85.23351 -321.728846)
		(size 0.508)
		(drill 0.254)
		(layers "F.Cu" "B.Cu")
		(net "PVDDCR_CPU1_P1")
	)
	(via
		(at 81.524094 -317.914274)
		(size 0.508)
		(drill 0.254)
		(layers "F.Cu" "B.Cu")
		(net "PVDDCR_CPU1_P1")
	)
	(via
		(at 119.12473 -291.906198)
		(size 0.4064)
		(drill 0.2032)
		(layers "F.Cu" "B.Cu")
		(net "PVDDCR_CPU1_P1")
	)
	(via
		(at 103.151178 -287.046162)
		(size 0.4064)
		(drill 0.2032)
		(layers "F.Cu" "B.Cu")
		(net "PVDDCR_CPU1_P1")
	)
	(via
		(at 59.17311 -332.20152)
		(size 0.508)
		(drill 0.254)
		(layers "F.Cu" "B.Cu")
		(net "PVDDCR_CPU1_P1")
	)
	(via
		(at 105.971086 -275.706332)
		(size 0.4064)
		(drill 0.2032)
		(layers "F.Cu" "B.Cu")
		(net "PVDDCR_CPU1_P1")
	)
	(via
		(at 130.40487 -295.146222)
		(size 0.4064)
		(drill 0.2032)
		(layers "F.Cu" "B.Cu")
		(net "PVDDCR_CPU1_P1")
	)
	(via
		(at 59.80811 -329.66152)
		(size 0.508)
		(drill 0.254)
		(layers "F.Cu" "B.Cu")
		(net "PVDDCR_CPU1_P1")
	)
	(via
		(at 77.485494 -316.644274)
		(size 0.508)
		(drill 0.254)
		(layers "F.Cu" "B.Cu")
		(net "PVDDCR_CPU1_P1")
	)
	(via
		(at 116.304822 -291.906198)
		(size 0.4064)
		(drill 0.2032)
		(layers "F.Cu" "B.Cu")
		(net "PVDDCR_CPU1_P1")
	)
	(via
		(at 122.414792 -266.796266)
		(size 0.4064)
		(drill 0.2032)
		(layers "F.Cu" "B.Cu")
		(net "PVDDCR_CPU1_P1")
	)
	(via
		(at 93.462094 -318.563752)
		(size 0.508)
		(drill 0.254)
		(layers "F.Cu" "B.Cu")
		(net "PVDDCR_CPU1_P1")
	)
	(via
		(at 103.151178 -267.606272)
		(size 0.4064)
		(drill 0.2032)
		(layers "F.Cu" "B.Cu")
		(net "PVDDCR_CPU1_P1")
	)
	(via
		(at 101.815138 -322.240148)
		(size 0.508)
		(drill 0.254)
		(layers "F.Cu" "B.Cu")
		(net "PVDDCR_CPU1_P1")
	)
	(via
		(at 119.12473 -295.146222)
		(size 0.4064)
		(drill 0.2032)
		(layers "F.Cu" "B.Cu")
		(net "PVDDCR_CPU1_P1")
	)
	(via
		(at 67.863466 -322.395342)
		(size 0.508)
		(drill 0.254)
		(layers "F.Cu" "B.Cu")
		(net "PVDDCR_CPU1_P1")
	)
	(via
		(at 106.440986 -268.416278)
		(size 0.4064)
		(drill 0.2032)
		(layers "F.Cu" "B.Cu")
		(net "PVDDCR_CPU1_P1")
	)
	(via
		(at 85.23351 -320.458846)
		(size 0.508)
		(drill 0.254)
		(layers "F.Cu" "B.Cu")
		(net "PVDDCR_CPU1_P1")
	)
	(via
		(at 102.475538 -326.68972)
		(size 0.508)
		(drill 0.254)
		(layers "F.Cu" "B.Cu")
		(net "PVDDCR_CPU1_P1")
	)
	(via
		(at 113.954814 -278.13635)
		(size 0.4064)
		(drill 0.2032)
		(layers "F.Cu" "B.Cu")
		(net "PVDDCR_CPU1_P1")
	)
	(via
		(at 104.090978 -275.706332)
		(size 0.4064)
		(drill 0.2032)
		(layers "F.Cu" "B.Cu")
		(net "PVDDCR_CPU1_P1")
	)
	(via
		(at 98.135694 -323.034152)
		(size 0.508)
		(drill 0.254)
		(layers "F.Cu" "B.Cu")
		(net "PVDDCR_CPU1_P1")
	)
	(via
		(at 118.184676 -278.946356)
		(size 0.4064)
		(drill 0.2032)
		(layers "F.Cu" "B.Cu")
		(net "PVDDCR_CPU1_P1")
	)
	(via
		(at 59.80811 -331.56652)
		(size 0.508)
		(drill 0.254)
		(layers "F.Cu" "B.Cu")
		(net "PVDDCR_CPU1_P1")
	)
	(via
		(at 98.921062 -268.416278)
		(size 0.4064)
		(drill 0.2032)
		(layers "F.Cu" "B.Cu")
		(net "PVDDCR_CPU1_P1")
	)
	(via
		(at 71.89851 -319.205864)
		(size 0.508)
		(drill 0.254)
		(layers "F.Cu" "B.Cu")
		(net "PVDDCR_CPU1_P1")
	)
	(via
		(at 120.064784 -267.606272)
		(size 0.4064)
		(drill 0.2032)
		(layers "F.Cu" "B.Cu")
		(net "PVDDCR_CPU1_P1")
	)
	(via
		(at 84.57311 -318.549274)
		(size 0.508)
		(drill 0.254)
		(layers "F.Cu" "B.Cu")
		(net "PVDDCR_CPU1_P1")
	)
	(via
		(at 80.889094 -322.363846)
		(size 0.508)
		(drill 0.254)
		(layers "F.Cu" "B.Cu")
		(net "PVDDCR_CPU1_P1")
	)
	(via
		(at 105.218738 -324.145148)
		(size 0.508)
		(drill 0.254)
		(layers "F.Cu" "B.Cu")
		(net "PVDDCR_CPU1_P1")
	)
	(via
		(at 84.572094 -321.103752)
		(size 0.508)
		(drill 0.254)
		(layers "F.Cu" "B.Cu")
		(net "PVDDCR_CPU1_P1")
	)
	(via
		(at 63.18631 -332.20152)
		(size 0.508)
		(drill 0.254)
		(layers "F.Cu" "B.Cu")
		(net "PVDDCR_CPU1_P1")
	)
	(via
		(at 81.524094 -317.279274)
		(size 0.508)
		(drill 0.254)
		(layers "F.Cu" "B.Cu")
		(net "PVDDCR_CPU1_P1")
	)
	(via
		(at 116.774722 -281.376374)
		(size 0.4064)
		(drill 0.2032)
		(layers "F.Cu" "B.Cu")
		(net "PVDDCR_CPU1_P1")
	)
	(via
		(at 98.135694 -317.293752)
		(size 0.508)
		(drill 0.254)
		(layers "F.Cu" "B.Cu")
		(net "PVDDCR_CPU1_P1")
	)
	(via
		(at 121.004838 -283.806392)
		(size 0.4064)
		(drill 0.2032)
		(layers "F.Cu" "B.Cu")
		(net "PVDDCR_CPU1_P1")
	)
	(via
		(at 67.863466 -320.490342)
		(size 0.508)
		(drill 0.254)
		(layers "F.Cu" "B.Cu")
		(net "PVDDCR_CPU1_P1")
	)
	(via
		(at 63.82131 -334.74152)
		(size 0.508)
		(drill 0.254)
		(layers "F.Cu" "B.Cu")
		(net "PVDDCR_CPU1_P1")
	)
	(via
		(at 93.462094 -317.293752)
		(size 0.508)
		(drill 0.254)
		(layers "F.Cu" "B.Cu")
		(net "PVDDCR_CPU1_P1")
	)
	(via
		(at 104.561132 -281.376374)
		(size 0.4064)
		(drill 0.2032)
		(layers "F.Cu" "B.Cu")
		(net "PVDDCR_CPU1_P1")
	)
	(via
		(at 102.681024 -268.416278)
		(size 0.4064)
		(drill 0.2032)
		(layers "F.Cu" "B.Cu")
		(net "PVDDCR_CPU1_P1")
	)
	(via
		(at 94.097094 -319.198752)
		(size 0.508)
		(drill 0.254)
		(layers "F.Cu" "B.Cu")
		(net "PVDDCR_CPU1_P1")
	)
	(via
		(at 80.23225 -323.008752)
		(size 0.508)
		(drill 0.254)
		(layers "F.Cu" "B.Cu")
		(net "PVDDCR_CPU1_P1")
	)
	(via
		(at 101.815138 -324.780148)
		(size 0.508)
		(drill 0.254)
		(layers "F.Cu" "B.Cu")
		(net "PVDDCR_CPU1_P1")
	)
	(via
		(at 73.146666 -323.030342)
		(size 0.508)
		(drill 0.254)
		(layers "F.Cu" "B.Cu")
		(net "PVDDCR_CPU1_P1")
	)
	(via
		(at 97.511108 -269.226284)
		(size 0.4064)
		(drill 0.2032)
		(layers "F.Cu" "B.Cu")
		(net "PVDDCR_CPU1_P1")
	)
	(via
		(at 123.824746 -295.146222)
		(size 0.4064)
		(drill 0.2032)
		(layers "F.Cu" "B.Cu")
		(net "PVDDCR_CPU1_P1")
	)
	(via
		(at 80.889094 -316.644274)
		(size 0.508)
		(drill 0.254)
		(layers "F.Cu" "B.Cu")
		(net "PVDDCR_CPU1_P1")
	)
	(via
		(at 124.7648 -291.906198)
		(size 0.4064)
		(drill 0.2032)
		(layers "F.Cu" "B.Cu")
		(net "PVDDCR_CPU1_P1")
	)
	(via
		(at 105.247694 -327.969626)
		(size 0.508)
		(drill 0.254)
		(layers "F.Cu" "B.Cu")
		(net "PVDDCR_CPU1_P1")
	)
	(via
		(at 60.44311 -330.93152)
		(size 0.508)
		(drill 0.254)
		(layers "F.Cu" "B.Cu")
		(net "PVDDCR_CPU1_P1")
	)
	(via
		(at 81.524094 -321.724274)
		(size 0.508)
		(drill 0.254)
		(layers "F.Cu" "B.Cu")
		(net "PVDDCR_CPU1_P1")
	)
	(via
		(at 81.524094 -320.454274)
		(size 0.508)
		(drill 0.254)
		(layers "F.Cu" "B.Cu")
		(net "PVDDCR_CPU1_P1")
	)
	(via
		(at 85.20811 -316.644274)
		(size 0.508)
		(drill 0.254)
		(layers "F.Cu" "B.Cu")
		(net "PVDDCR_CPU1_P1")
	)
	(via
		(at 94.122494 -321.743324)
		(size 0.508)
		(drill 0.254)
		(layers "F.Cu" "B.Cu")
		(net "PVDDCR_CPU1_P1")
	)
	(via
		(at 104.561132 -266.796266)
		(size 0.4064)
		(drill 0.2032)
		(layers "F.Cu" "B.Cu")
		(net "PVDDCR_CPU1_P1")
	)
	(via
		(at 98.135694 -319.198752)
		(size 0.508)
		(drill 0.254)
		(layers "F.Cu" "B.Cu")
		(net "PVDDCR_CPU1_P1")
	)
	(via
		(at 96.865694 -323.034152)
		(size 0.508)
		(drill 0.254)
		(layers "F.Cu" "B.Cu")
		(net "PVDDCR_CPU1_P1")
	)
	(via
		(at 68.52031 -322.385436)
		(size 0.508)
		(drill 0.254)
		(layers "F.Cu" "B.Cu")
		(net "PVDDCR_CPU1_P1")
	)
	(via
		(at 85.23351 -322.363846)
		(size 0.508)
		(drill 0.254)
		(layers "F.Cu" "B.Cu")
		(net "PVDDCR_CPU1_P1")
	)
	(via
		(at 102.450138 -321.605148)
		(size 0.508)
		(drill 0.254)
		(layers "F.Cu" "B.Cu")
		(net "PVDDCR_CPU1_P1")
	)
	(via
		(at 110.200948 -282.996386)
		(size 0.4064)
		(drill 0.2032)
		(layers "F.Cu" "B.Cu")
		(net "PVDDCR_CPU1_P1")
	)
	(via
		(at 118.184676 -272.466308)
		(size 0.4064)
		(drill 0.2032)
		(layers "F.Cu" "B.Cu")
		(net "PVDDCR_CPU1_P1")
	)
	(via
		(at 105.853738 -324.145148)
		(size 0.508)
		(drill 0.254)
		(layers "F.Cu" "B.Cu")
		(net "PVDDCR_CPU1_P1")
	)
	(via
		(at 72.53351 -316.665864)
		(size 0.508)
		(drill 0.254)
		(layers "F.Cu" "B.Cu")
		(net "PVDDCR_CPU1_P1")
	)
	(via
		(at 110.200948 -289.47618)
		(size 0.4064)
		(drill 0.2032)
		(layers "F.Cu" "B.Cu")
		(net "PVDDCR_CPU1_P1")
	)
	(via
		(at 77.485494 -319.184274)
		(size 0.508)
		(drill 0.254)
		(layers "F.Cu" "B.Cu")
		(net "PVDDCR_CPU1_P1")
	)
	(via
		(at 120.064784 -287.046162)
		(size 0.4064)
		(drill 0.2032)
		(layers "F.Cu" "B.Cu")
		(net "PVDDCR_CPU1_P1")
	)
	(via
		(at 98.451162 -278.946356)
		(size 0.4064)
		(drill 0.2032)
		(layers "F.Cu" "B.Cu")
		(net "PVDDCR_CPU1_P1")
	)
	(via
		(at 92.149676 -338.811108)
		(size 0.508)
		(drill 0.254)
		(layers "F.Cu" "B.Cu")
		(net "PVDDCR_CPU1_P1")
	)
	(via
		(at 76.215494 -317.279274)
		(size 0.508)
		(drill 0.254)
		(layers "F.Cu" "B.Cu")
		(net "PVDDCR_CPU1_P1")
	)
	(via
		(at 114.894614 -291.096192)
		(size 0.4064)
		(drill 0.2032)
		(layers "F.Cu" "B.Cu")
		(net "PVDDCR_CPU1_P1")
	)
	(via
		(at 73.16851 -317.935864)
		(size 0.508)
		(drill 0.254)
		(layers "F.Cu" "B.Cu")
		(net "PVDDCR_CPU1_P1")
	)
	(via
		(at 73.16851 -319.205864)
		(size 0.508)
		(drill 0.254)
		(layers "F.Cu" "B.Cu")
		(net "PVDDCR_CPU1_P1")
	)
	(via
		(at 117.714776 -281.376374)
		(size 0.4064)
		(drill 0.2032)
		(layers "F.Cu" "B.Cu")
		(net "PVDDCR_CPU1_P1")
	)
	(via
		(at 106.91114 -278.946356)
		(size 0.4064)
		(drill 0.2032)
		(layers "F.Cu" "B.Cu")
		(net "PVDDCR_CPU1_P1")
	)
	(via
		(at 89.24671 -322.363846)
		(size 0.508)
		(drill 0.254)
		(layers "F.Cu" "B.Cu")
		(net "PVDDCR_CPU1_P1")
	)
	(via
		(at 113.954814 -291.096192)
		(size 0.4064)
		(drill 0.2032)
		(layers "F.Cu" "B.Cu")
		(net "PVDDCR_CPU1_P1")
	)
	(via
		(at 80.254094 -318.549274)
		(size 0.508)
		(drill 0.254)
		(layers "F.Cu" "B.Cu")
		(net "PVDDCR_CPU1_P1")
	)
	(via
		(at 106.517694 -326.064626)
		(size 0.508)
		(drill 0.254)
		(layers "F.Cu" "B.Cu")
		(net "PVDDCR_CPU1_P1")
	)
	(via
		(at 102.450138 -322.240148)
		(size 0.508)
		(drill 0.254)
		(layers "F.Cu" "B.Cu")
		(net "PVDDCR_CPU1_P1")
	)
	(via
		(at 93.462094 -319.833752)
		(size 0.508)
		(drill 0.254)
		(layers "F.Cu" "B.Cu")
		(net "PVDDCR_CPU1_P1")
	)
	(via
		(at 94.122494 -323.034152)
		(size 0.508)
		(drill 0.254)
		(layers "F.Cu" "B.Cu")
		(net "PVDDCR_CPU1_P1")
	)
	(via
		(at 121.004838 -275.706332)
		(size 0.4064)
		(drill 0.2032)
		(layers "F.Cu" "B.Cu")
		(net "PVDDCR_CPU1_P1")
	)
	(via
		(at 98.135694 -322.399152)
		(size 0.508)
		(drill 0.254)
		(layers "F.Cu" "B.Cu")
		(net "PVDDCR_CPU1_P1")
	)
	(via
		(at 123.824746 -278.946356)
		(size 0.4064)
		(drill 0.2032)
		(layers "F.Cu" "B.Cu")
		(net "PVDDCR_CPU1_P1")
	)
	(via
		(at 94.097094 -318.563752)
		(size 0.508)
		(drill 0.254)
		(layers "F.Cu" "B.Cu")
		(net "PVDDCR_CPU1_P1")
	)
	(via
		(at 80.889094 -320.458846)
		(size 0.508)
		(drill 0.254)
		(layers "F.Cu" "B.Cu")
		(net "PVDDCR_CPU1_P1")
	)
	(via
		(at 122.414792 -268.416278)
		(size 0.4064)
		(drill 0.2032)
		(layers "F.Cu" "B.Cu")
		(net "PVDDCR_CPU1_P1")
	)
	(via
		(at 101.815138 -324.145148)
		(size 0.508)
		(drill 0.254)
		(layers "F.Cu" "B.Cu")
		(net "PVDDCR_CPU1_P1")
	)
	(via
		(at 72.53351 -319.205864)
		(size 0.508)
		(drill 0.254)
		(layers "F.Cu" "B.Cu")
		(net "PVDDCR_CPU1_P1")
	)
	(via
		(at 73.16851 -320.475864)
		(size 0.508)
		(drill 0.254)
		(layers "F.Cu" "B.Cu")
		(net "PVDDCR_CPU1_P1")
	)
	(via
		(at 60.44311 -332.83652)
		(size 0.508)
		(drill 0.254)
		(layers "F.Cu" "B.Cu")
		(net "PVDDCR_CPU1_P1")
	)
	(via
		(at 101.27107 -269.226284)
		(size 0.4064)
		(drill 0.2032)
		(layers "F.Cu" "B.Cu")
		(net "PVDDCR_CPU1_P1")
	)
	(via
		(at 72.511666 -323.030342)
		(size 0.508)
		(drill 0.254)
		(layers "F.Cu" "B.Cu")
		(net "PVDDCR_CPU1_P1")
	)
	(via
		(at 125.704854 -272.466308)
		(size 0.4064)
		(drill 0.2032)
		(layers "F.Cu" "B.Cu")
		(net "PVDDCR_CPU1_P1")
	)
	(via
		(at 77.485494 -317.914274)
		(size 0.508)
		(drill 0.254)
		(layers "F.Cu" "B.Cu")
		(net "PVDDCR_CPU1_P1")
	)
	(via
		(at 71.89851 -317.300864)
		(size 0.508)
		(drill 0.254)
		(layers "F.Cu" "B.Cu")
		(net "PVDDCR_CPU1_P1")
	)
	(via
		(at 100.331016 -287.046162)
		(size 0.4064)
		(drill 0.2032)
		(layers "F.Cu" "B.Cu")
		(net "PVDDCR_CPU1_P1")
	)
	(via
		(at 119.59463 -281.376374)
		(size 0.4064)
		(drill 0.2032)
		(layers "F.Cu" "B.Cu")
		(net "PVDDCR_CPU1_P1")
	)
	(via
		(at 127.584708 -295.146222)
		(size 0.4064)
		(drill 0.2032)
		(layers "F.Cu" "B.Cu")
		(net "PVDDCR_CPU1_P1")
	)
	(via
		(at 80.254094 -320.458846)
		(size 0.508)
		(drill 0.254)
		(layers "F.Cu" "B.Cu")
		(net "PVDDCR_CPU1_P1")
	)
	(via
		(at 89.88171 -321.089274)
		(size 0.508)
		(drill 0.254)
		(layers "F.Cu" "B.Cu")
		(net "PVDDCR_CPU1_P1")
	)
	(via
		(at 123.824746 -267.606272)
		(size 0.4064)
		(drill 0.2032)
		(layers "F.Cu" "B.Cu")
		(net "PVDDCR_CPU1_P1")
	)
	(via
		(at 106.91114 -267.606272)
		(size 0.4064)
		(drill 0.2032)
		(layers "F.Cu" "B.Cu")
		(net "PVDDCR_CPU1_P1")
	)
	(via
		(at 68.52031 -321.750436)
		(size 0.508)
		(drill 0.254)
		(layers "F.Cu" "B.Cu")
		(net "PVDDCR_CPU1_P1")
	)
	(via
		(at 118.65483 -268.416278)
		(size 0.4064)
		(drill 0.2032)
		(layers "F.Cu" "B.Cu")
		(net "PVDDCR_CPU1_P1")
	)
	(via
		(at 108.790994 -295.146222)
		(size 0.4064)
		(drill 0.2032)
		(layers "F.Cu" "B.Cu")
		(net "PVDDCR_CPU1_P1")
	)
	(via
		(at 103.151178 -295.146222)
		(size 0.4064)
		(drill 0.2032)
		(layers "F.Cu" "B.Cu")
		(net "PVDDCR_CPU1_P1")
	)
	(via
		(at 105.218738 -322.240148)
		(size 0.508)
		(drill 0.254)
		(layers "F.Cu" "B.Cu")
		(net "PVDDCR_CPU1_P1")
	)
	(via
		(at 85.84311 -318.549274)
		(size 0.508)
		(drill 0.254)
		(layers "F.Cu" "B.Cu")
		(net "PVDDCR_CPU1_P1")
	)
	(via
		(at 126.644654 -287.046162)
		(size 0.4064)
		(drill 0.2032)
		(layers "F.Cu" "B.Cu")
		(net "PVDDCR_CPU1_P1")
	)
	(via
		(at 85.84311 -317.279274)
		(size 0.508)
		(drill 0.254)
		(layers "F.Cu" "B.Cu")
		(net "PVDDCR_CPU1_P1")
	)
	(via
		(at 101.844094 -327.995026)
		(size 0.508)
		(drill 0.254)
		(layers "F.Cu" "B.Cu")
		(net "PVDDCR_CPU1_P1")
	)
	(segment
		(start 83.460844 -338.402676)
		(end 83.818476 -338.760308)
		(width 0.508)
		(layer "B.Cu")
		(net "PVDDCR_CPU1_P1")
	)
	(segment
		(start 75.103228 -338.058252)
		(end 75.103228 -338.417154)
		(width 0.508)
		(layer "B.Cu")
		(net "PVDDCR_CPU1_P1")
	)
	(segment
		(start 100.067872 -343.004648)
		(end 100.067872 -343.36355)
		(width 0.508)
		(layer "B.Cu")
		(net "PVDDCR_CPU1_P1")
	)
	(segment
		(start 58.213244 -350.14535)
		(end 58.570876 -350.502982)
		(width 0.381)
		(layer "B.Cu")
		(net "PVDDCR_CPU1_P1")
	)
	(segment
		(start 66.747644 -338.065364)
		(end 66.747644 -338.424266)
		(width 0.508)
		(layer "B.Cu")
		(net "PVDDCR_CPU1_P1")
	)
	(segment
		(start 100.067872 -343.36355)
		(end 100.425504 -343.721182)
		(width 0.508)
		(layer "B.Cu")
		(net "PVDDCR_CPU1_P1")
	)
	(segment
		(start 91.792044 -338.094574)
		(end 91.792044 -338.453476)
		(width 0.508)
		(layer "B.Cu")
		(net "PVDDCR_CPU1_P1")
	)
	(segment
		(start 66.747644 -338.424266)
		(end 67.105276 -338.781898)
		(width 0.508)
		(layer "B.Cu")
		(net "PVDDCR_CPU1_P1")
	)
	(segment
		(start 91.792044 -338.453476)
		(end 92.149676 -338.811108)
		(width 0.508)
		(layer "B.Cu")
		(net "PVDDCR_CPU1_P1")
	)
	(segment
		(start 83.460844 -338.043774)
		(end 83.460844 -338.402676)
		(width 0.508)
		(layer "B.Cu")
		(net "PVDDCR_CPU1_P1")
	)
	(segment
		(start 75.103228 -338.417154)
		(end 75.46086 -338.774786)
		(width 0.508)
		(layer "B.Cu")
		(net "PVDDCR_CPU1_P1")
	)
	(segment
		(start 58.213244 -349.786448)
		(end 58.213244 -350.14535)
		(width 0.381)
		(layer "B.Cu")
		(net "PVDDCR_CPU1_P1")
	)
	(segment
		(start 84.368894 -335.71307)
		(end 84.368894 -336.682588)
		(width 0.381)
		(layer "In2.Cu")
		(net "PVDDCR_CPU1_P1")
	)
	(segment
		(start 75.156822 -337.523582)
		(end 76.012294 -336.66811)
		(width 0.381)
		(layer "In2.Cu")
		(net "PVDDCR_CPU1_P1")
	)
	(segment
		(start 100.020882 -339.693758)
		(end 100.020882 -337.027774)
		(width 0.381)
		(layer "In2.Cu")
		(net "PVDDCR_CPU1_P1")
	)
	(segment
		(start 91.712542 -334.804258)
		(end 92.649294 -335.74101)
		(width 0.381)
		(layer "In2.Cu")
		(net "PVDDCR_CPU1_P1")
	)
	(segment
		(start 67.660266 -335.895442)
		(end 66.685922 -334.921098)
		(width 0.381)
		(layer "In2.Cu")
		(net "PVDDCR_CPU1_P1")
	)
	(segment
		(start 91.839542 -338.500974)
		(end 92.149676 -338.811108)
		(width 0.381)
		(layer "In2.Cu")
		(net "PVDDCR_CPU1_P1")
	)
	(segment
		(start 84.368894 -336.682588)
		(end 83.589622 -337.46186)
		(width 0.381)
		(layer "In2.Cu")
		(net "PVDDCR_CPU1_P1")
	)
	(segment
		(start 57.869582 -335.220818)
		(end 58.9661 -334.1243)
		(width 0.381)
		(layer "In2.Cu")
		(net "PVDDCR_CPU1_P1")
	)
	(segment
		(start 101.005894 -340.67877)
		(end 100.020882 -339.693758)
		(width 0.381)
		(layer "In2.Cu")
		(net "PVDDCR_CPU1_P1")
	)
	(segment
		(start 84.572094 -332.237588)
		(end 83.300062 -333.50962)
		(width 0.381)
		(layer "In2.Cu")
		(net "PVDDCR_CPU1_P1")
	)
	(segment
		(start 83.589622 -338.531454)
		(end 83.818476 -338.760308)
		(width 0.381)
		(layer "In2.Cu")
		(net "PVDDCR_CPU1_P1")
	)
	(segment
		(start 67.863466 -332.259178)
		(end 67.863466 -323.030342)
		(width 0.381)
		(layer "In2.Cu")
		(net "PVDDCR_CPU1_P1")
	)
	(segment
		(start 100.091494 -343.387172)
		(end 100.091494 -342.583262)
		(width 0.381)
		(layer "In2.Cu")
		(net "PVDDCR_CPU1_P1")
	)
	(segment
		(start 92.649294 -336.707988)
		(end 91.839542 -337.51774)
		(width 0.381)
		(layer "In2.Cu")
		(net "PVDDCR_CPU1_P1")
	)
	(segment
		(start 58.9661 -334.1243)
		(end 58.9661 -334.10652)
		(width 0.381)
		(layer "In2.Cu")
		(net "PVDDCR_CPU1_P1")
	)
	(segment
		(start 76.21905 -332.219554)
		(end 76.21905 -323.008752)
		(width 0.381)
		(layer "In2.Cu")
		(net "PVDDCR_CPU1_P1")
	)
	(segment
		(start 100.091494 -342.583262)
		(end 101.005894 -341.668862)
		(width 0.381)
		(layer "In2.Cu")
		(net "PVDDCR_CPU1_P1")
	)
	(segment
		(start 92.649294 -335.74101)
		(end 92.649294 -336.707988)
		(width 0.381)
		(layer "In2.Cu")
		(net "PVDDCR_CPU1_P1")
	)
	(segment
		(start 83.300062 -334.644238)
		(end 84.368894 -335.71307)
		(width 0.381)
		(layer "In2.Cu")
		(net "PVDDCR_CPU1_P1")
	)
	(segment
		(start 76.012294 -335.37525)
		(end 74.994262 -334.357218)
		(width 0.381)
		(layer "In2.Cu")
		(net "PVDDCR_CPU1_P1")
	)
	(segment
		(start 59.349894 -348.301564)
		(end 59.349894 -338.26577)
		(width 0.381)
		(layer "In2.Cu")
		(net "PVDDCR_CPU1_P1")
	)
	(segment
		(start 100.020882 -337.027774)
		(end 101.209094 -335.839562)
		(width 0.381)
		(layer "In2.Cu")
		(net "PVDDCR_CPU1_P1")
	)
	(segment
		(start 83.589622 -337.46186)
		(end 83.589622 -338.531454)
		(width 0.381)
		(layer "In2.Cu")
		(net "PVDDCR_CPU1_P1")
	)
	(segment
		(start 66.745866 -338.422488)
		(end 66.745866 -337.618578)
		(width 0.381)
		(layer "In2.Cu")
		(net "PVDDCR_CPU1_P1")
	)
	(segment
		(start 66.685922 -334.921098)
		(end 66.685922 -333.436722)
		(width 0.381)
		(layer "In2.Cu")
		(net "PVDDCR_CPU1_P1")
	)
	(segment
		(start 92.852494 -332.262988)
		(end 91.712542 -333.40294)
		(width 0.381)
		(layer "In2.Cu")
		(net "PVDDCR_CPU1_P1")
	)
	(segment
		(start 57.869582 -336.785458)
		(end 57.869582 -335.220818)
		(width 0.381)
		(layer "In2.Cu")
		(net "PVDDCR_CPU1_P1")
	)
	(segment
		(start 74.994262 -333.444342)
		(end 76.21905 -332.219554)
		(width 0.381)
		(layer "In2.Cu")
		(net "PVDDCR_CPU1_P1")
	)
	(segment
		(start 91.712542 -333.40294)
		(end 91.712542 -334.804258)
		(width 0.381)
		(layer "In2.Cu")
		(net "PVDDCR_CPU1_P1")
	)
	(segment
		(start 75.156822 -338.470748)
		(end 75.156822 -337.523582)
		(width 0.381)
		(layer "In2.Cu")
		(net "PVDDCR_CPU1_P1")
	)
	(segment
		(start 101.209094 -335.839562)
		(end 101.209094 -327.995026)
		(width 0.381)
		(layer "In2.Cu")
		(net "PVDDCR_CPU1_P1")
	)
	(segment
		(start 58.279538 -349.37192)
		(end 59.349894 -348.301564)
		(width 0.381)
		(layer "In2.Cu")
		(net "PVDDCR_CPU1_P1")
	)
	(segment
		(start 67.660266 -336.704178)
		(end 67.660266 -335.895442)
		(width 0.381)
		(layer "In2.Cu")
		(net "PVDDCR_CPU1_P1")
	)
	(segment
		(start 76.012294 -336.66811)
		(end 76.012294 -335.37525)
		(width 0.381)
		(layer "In2.Cu")
		(net "PVDDCR_CPU1_P1")
	)
	(segment
		(start 91.839542 -337.51774)
		(end 91.839542 -338.500974)
		(width 0.381)
		(layer "In2.Cu")
		(net "PVDDCR_CPU1_P1")
	)
	(segment
		(start 67.105276 -338.781898)
		(end 66.745866 -338.422488)
		(width 0.381)
		(layer "In2.Cu")
		(net "PVDDCR_CPU1_P1")
	)
	(segment
		(start 66.745866 -337.618578)
		(end 67.660266 -336.704178)
		(width 0.381)
		(layer "In2.Cu")
		(net "PVDDCR_CPU1_P1")
	)
	(segment
		(start 101.005894 -341.668862)
		(end 101.005894 -340.67877)
		(width 0.381)
		(layer "In2.Cu")
		(net "PVDDCR_CPU1_P1")
	)
	(segment
		(start 58.570876 -350.502982)
		(end 58.279538 -350.211644)
		(width 0.381)
		(layer "In2.Cu")
		(net "PVDDCR_CPU1_P1")
	)
	(segment
		(start 83.300062 -333.50962)
		(end 83.300062 -334.644238)
		(width 0.381)
		(layer "In2.Cu")
		(net "PVDDCR_CPU1_P1")
	)
	(segment
		(start 74.994262 -334.357218)
		(end 74.994262 -333.444342)
		(width 0.381)
		(layer "In2.Cu")
		(net "PVDDCR_CPU1_P1")
	)
	(segment
		(start 66.685922 -333.436722)
		(end 67.863466 -332.259178)
		(width 0.381)
		(layer "In2.Cu")
		(net "PVDDCR_CPU1_P1")
	)
	(segment
		(start 59.349894 -338.26577)
		(end 57.869582 -336.785458)
		(width 0.381)
		(layer "In2.Cu")
		(net "PVDDCR_CPU1_P1")
	)
	(segment
		(start 75.46086 -338.774786)
		(end 75.156822 -338.470748)
		(width 0.381)
		(layer "In2.Cu")
		(net "PVDDCR_CPU1_P1")
	)
	(segment
		(start 84.572094 -323.008752)
		(end 84.572094 -332.237588)
		(width 0.381)
		(layer "In2.Cu")
		(net "PVDDCR_CPU1_P1")
	)
	(segment
		(start 92.852494 -323.034152)
		(end 92.852494 -332.262988)
		(width 0.381)
		(layer "In2.Cu")
		(net "PVDDCR_CPU1_P1")
	)
	(segment
		(start 58.9661 -334.10652)
		(end 59.17311 -334.10652)
		(width 0.381)
		(layer "In2.Cu")
		(net "PVDDCR_CPU1_P1")
	)
	(segment
		(start 58.279538 -350.211644)
		(end 58.279538 -349.37192)
		(width 0.381)
		(layer "In2.Cu")
		(net "PVDDCR_CPU1_P1")
	)
	(segment
		(start 100.425504 -343.721182)
		(end 100.091494 -343.387172)
		(width 0.381)
		(layer "In2.Cu")
		(net "PVDDCR_CPU1_P1")
	)
	(segment
		(start 349.266002 -342.496394)
		(end 348.94139 -342.821006)
		(width 0.2032)
		(layer "F.Cu")
		(net "PVDDCR_CPU1_P0_VOS6")
	)
	(segment
		(start 349.266002 -342.209628)
		(end 349.266002 -342.496394)
		(width 0.2032)
		(layer "F.Cu")
		(net "PVDDCR_CPU1_P0_VOS6")
	)
	(via
		(at 348.94139 -342.821006)
		(size 0.508)
		(drill 0.254)
		(layers "F.Cu" "B.Cu")
		(net "PVDDCR_CPU1_P0_VOS6")
	)
	(segment
		(start 348.320106 -342.199722)
		(end 348.94139 -342.821006)
		(width 0.2286)
		(layer "B.Cu")
		(net "PVDDCR_CPU1_P0_VOS6")
	)
	(segment
		(start 348.004638 -342.199722)
		(end 348.320106 -342.199722)
		(width 0.2286)
		(layer "B.Cu")
		(net "PVDDCR_CPU1_P0_VOS6")
	)
	(segment
		(start 340.990174 -337.58632)
		(end 340.665562 -337.910932)
		(width 0.2032)
		(layer "F.Cu")
		(net "PVDDCR_CPU1_P0_VOS5")
	)
	(segment
		(start 340.990174 -337.299554)
		(end 340.990174 -337.58632)
		(width 0.2032)
		(layer "F.Cu")
		(net "PVDDCR_CPU1_P0_VOS5")
	)
	(via
		(at 340.665562 -337.910932)
		(size 0.508)
		(drill 0.254)
		(layers "F.Cu" "B.Cu")
		(net "PVDDCR_CPU1_P0_VOS5")
	)
	(segment
		(start 339.72881 -337.289648)
		(end 340.044278 -337.289648)
		(width 0.2286)
		(layer "B.Cu")
		(net "PVDDCR_CPU1_P0_VOS5")
	)
	(segment
		(start 340.044278 -337.289648)
		(end 340.665562 -337.910932)
		(width 0.2286)
		(layer "B.Cu")
		(net "PVDDCR_CPU1_P0_VOS5")
	)
	(segment
		(start 306.29606 -348.991428)
		(end 306.29606 -349.278194)
		(width 0.2032)
		(layer "F.Cu")
		(net "PVDDCR_CPU1_P0_VOS4")
	)
	(segment
		(start 306.29606 -349.278194)
		(end 305.971448 -349.602806)
		(width 0.2032)
		(layer "F.Cu")
		(net "PVDDCR_CPU1_P0_VOS4")
	)
	(via
		(at 305.971448 -349.602806)
		(size 0.508)
		(drill 0.254)
		(layers "F.Cu" "B.Cu")
		(net "PVDDCR_CPU1_P0_VOS4")
	)
	(segment
		(start 305.350164 -348.981522)
		(end 305.971448 -349.602806)
		(width 0.2286)
		(layer "B.Cu")
		(net "PVDDCR_CPU1_P0_VOS4")
	)
	(segment
		(start 305.034696 -348.981522)
		(end 305.350164 -348.981522)
		(width 0.2286)
		(layer "B.Cu")
		(net "PVDDCR_CPU1_P0_VOS4")
	)
	(segment
		(start 315.945774 -337.55711)
		(end 315.621162 -337.881722)
		(width 0.2032)
		(layer "F.Cu")
		(net "PVDDCR_CPU1_P0_VOS3")
	)
	(segment
		(start 315.945774 -337.270344)
		(end 315.945774 -337.55711)
		(width 0.2032)
		(layer "F.Cu")
		(net "PVDDCR_CPU1_P0_VOS3")
	)
	(via
		(at 315.621162 -337.881722)
		(size 0.508)
		(drill 0.254)
		(layers "F.Cu" "B.Cu")
		(net "PVDDCR_CPU1_P0_VOS3")
	)
	(segment
		(start 314.68441 -337.260438)
		(end 314.999878 -337.260438)
		(width 0.2286)
		(layer "B.Cu")
		(net "PVDDCR_CPU1_P0_VOS3")
	)
	(segment
		(start 314.999878 -337.260438)
		(end 315.621162 -337.881722)
		(width 0.2286)
		(layer "B.Cu")
		(net "PVDDCR_CPU1_P0_VOS3")
	)
	(segment
		(start 324.301358 -337.549998)
		(end 323.976746 -337.87461)
		(width 0.2032)
		(layer "F.Cu")
		(net "PVDDCR_CPU1_P0_VOS2")
	)
	(segment
		(start 324.301358 -337.263232)
		(end 324.301358 -337.549998)
		(width 0.2032)
		(layer "F.Cu")
		(net "PVDDCR_CPU1_P0_VOS2")
	)
	(via
		(at 323.976746 -337.87461)
		(size 0.508)
		(drill 0.254)
		(layers "F.Cu" "B.Cu")
		(net "PVDDCR_CPU1_P0_VOS2")
	)
	(segment
		(start 323.039994 -337.253326)
		(end 323.355462 -337.253326)
		(width 0.2286)
		(layer "B.Cu")
		(net "PVDDCR_CPU1_P0_VOS2")
	)
	(segment
		(start 323.355462 -337.253326)
		(end 323.976746 -337.87461)
		(width 0.2286)
		(layer "B.Cu")
		(net "PVDDCR_CPU1_P0_VOS2")
	)
	(segment
		(start 332.658974 -337.53552)
		(end 332.334362 -337.860132)
		(width 0.2032)
		(layer "F.Cu")
		(net "PVDDCR_CPU1_P0_VOS1")
	)
	(segment
		(start 332.658974 -337.248754)
		(end 332.658974 -337.53552)
		(width 0.2032)
		(layer "F.Cu")
		(net "PVDDCR_CPU1_P0_VOS1")
	)
	(via
		(at 332.334362 -337.860132)
		(size 0.508)
		(drill 0.254)
		(layers "F.Cu" "B.Cu")
		(net "PVDDCR_CPU1_P0_VOS1")
	)
	(segment
		(start 331.713078 -337.238848)
		(end 332.334362 -337.860132)
		(width 0.2286)
		(layer "B.Cu")
		(net "PVDDCR_CPU1_P0_VOS1")
	)
	(segment
		(start 331.39761 -337.238848)
		(end 331.713078 -337.238848)
		(width 0.2286)
		(layer "B.Cu")
		(net "PVDDCR_CPU1_P0_VOS1")
	)
	(segment
		(start 314.324746 -361.823)
		(end 314.181744 -361.679998)
		(width 0.1778)
		(layer "F.Cu")
		(net "PVDDCR_CPU1_P0_VMON")
	)
	(segment
		(start 317.210186 -361.46105)
		(end 316.848236 -361.823)
		(width 0.254)
		(layer "F.Cu")
		(net "PVDDCR_CPU1_P0_VMON")
	)
	(segment
		(start 318.226186 -361.46105)
		(end 319.242186 -361.46105)
		(width 0.254)
		(layer "F.Cu")
		(net "PVDDCR_CPU1_P0_VMON")
	)
	(segment
		(start 316.848236 -361.823)
		(end 314.324746 -361.823)
		(width 0.254)
		(layer "F.Cu")
		(net "PVDDCR_CPU1_P0_VMON")
	)
	(segment
		(start 317.210186 -361.46105)
		(end 318.226186 -361.46105)
		(width 0.254)
		(layer "F.Cu")
		(net "PVDDCR_CPU1_P0_VMON")
	)
	(segment
		(start 314.181744 -361.679998)
		(end 313.009026 -361.679998)
		(width 0.1778)
		(layer "F.Cu")
		(net "PVDDCR_CPU1_P0_VMON")
	)
	(segment
		(start 314.336176 -362.596176)
		(end 314.1345 -362.3945)
		(width 0.254)
		(layer "F.Cu")
		(net "PVDDCR_CPU1_P0_VINSEN")
	)
	(segment
		(start 315.108336 -362.43895)
		(end 314.95111 -362.596176)
		(width 0.254)
		(layer "F.Cu")
		(net "PVDDCR_CPU1_P0_VINSEN")
	)
	(segment
		(start 314.95111 -362.596176)
		(end 314.336176 -362.596176)
		(width 0.254)
		(layer "F.Cu")
		(net "PVDDCR_CPU1_P0_VINSEN")
	)
	(segment
		(start 316.23 -362.43895)
		(end 315.108336 -362.43895)
		(width 0.254)
		(layer "F.Cu")
		(net "PVDDCR_CPU1_P0_VINSEN")
	)
	(segment
		(start 317.246 -362.43895)
		(end 316.23 -362.43895)
		(width 0.254)
		(layer "F.Cu")
		(net "PVDDCR_CPU1_P0_VINSEN")
	)
	(segment
		(start 313.820048 -362.080048)
		(end 313.009026 -362.080048)
		(width 0.1778)
		(layer "F.Cu")
		(net "PVDDCR_CPU1_P0_VINSEN")
	)
	(segment
		(start 314.1345 -362.3945)
		(end 313.820048 -362.080048)
		(width 0.1778)
		(layer "F.Cu")
		(net "PVDDCR_CPU1_P0_VINSEN")
	)
	(segment
		(start 318.262 -362.43895)
		(end 317.246 -362.43895)
		(width 0.254)
		(layer "F.Cu")
		(net "PVDDCR_CPU1_P0_VINSEN")
	)
	(via
		(at 314.95111 -362.596176)
		(size 0.762)
		(drill 0.381)
		(layers "F.Cu" "B.Cu")
		(net "PVDDCR_CPU1_P0_VINSEN")
	)
	(segment
		(start 313.436 -363.093)
		(end 313.436 -363.601)
		(width 0.1778)
		(layer "F.Cu")
		(net "PVDDCR_CPU1_P0_VCCS")
	)
	(segment
		(start 297.670982 -351.173796)
		(end 298.399454 -351.173796)
		(width 0.254)
		(layer "F.Cu")
		(net "PVDDCR_CPU1_P0_VCCS")
	)
	(segment
		(start 313.222894 -362.879894)
		(end 313.436 -363.093)
		(width 0.1778)
		(layer "F.Cu")
		(net "PVDDCR_CPU1_P0_VCCS")
	)
	(segment
		(start 306.002182 -350.510856)
		(end 306.002182 -351.173796)
		(width 0.2286)
		(layer "F.Cu")
		(net "PVDDCR_CPU1_P0_VCCS")
	)
	(segment
		(start 333.06893 -337.873594)
		(end 333.06893 -338.064348)
		(width 0.2286)
		(layer "F.Cu")
		(net "PVDDCR_CPU1_P0_VCCS")
	)
	(segment
		(start 289.314382 -350.510856)
		(end 289.314382 -351.173796)
		(width 0.2286)
		(layer "F.Cu")
		(net "PVDDCR_CPU1_P0_VCCS")
	)
	(segment
		(start 313.009026 -362.879894)
		(end 313.222894 -362.879894)
		(width 0.1778)
		(layer "F.Cu")
		(net "PVDDCR_CPU1_P0_VCCS")
	)
	(segment
		(start 314.8457 -365.0107)
		(end 314.8457 -365.62665)
		(width 0.254)
		(layer "F.Cu")
		(net "PVDDCR_CPU1_P0_VCCS")
	)
	(segment
		(start 306.002182 -351.173796)
		(end 306.730654 -351.173796)
		(width 0.254)
		(layer "F.Cu")
		(net "PVDDCR_CPU1_P0_VCCS")
	)
	(segment
		(start 333.06893 -338.064348)
		(end 332.365096 -338.768182)
		(width 0.2286)
		(layer "F.Cu")
		(net "PVDDCR_CPU1_P0_VCCS")
	)
	(segment
		(start 289.314382 -351.173796)
		(end 290.042854 -351.173796)
		(width 0.254)
		(layer "F.Cu")
		(net "PVDDCR_CPU1_P0_VCCS")
	)
	(segment
		(start 314.8457 -365.62665)
		(end 315.214 -365.99495)
		(width 0.254)
		(layer "F.Cu")
		(net "PVDDCR_CPU1_P0_VCCS")
	)
	(segment
		(start 316.35573 -338.085938)
		(end 315.651896 -338.789772)
		(width 0.2286)
		(layer "F.Cu")
		(net "PVDDCR_CPU1_P0_VCCS")
	)
	(segment
		(start 349.675958 -343.025222)
		(end 348.972124 -343.729056)
		(width 0.2286)
		(layer "F.Cu")
		(net "PVDDCR_CPU1_P0_VCCS")
	)
	(segment
		(start 298.374816 -349.807022)
		(end 297.670982 -350.510856)
		(width 0.2286)
		(layer "F.Cu")
		(net "PVDDCR_CPU1_P0_VCCS")
	)
	(segment
		(start 281.008582 -351.173796)
		(end 281.737054 -351.173796)
		(width 0.254)
		(layer "F.Cu")
		(net "PVDDCR_CPU1_P0_VCCS")
	)
	(segment
		(start 273.432016 -349.807022)
		(end 272.728182 -350.510856)
		(width 0.2286)
		(layer "F.Cu")
		(net "PVDDCR_CPU1_P0_VCCS")
	)
	(segment
		(start 332.365096 -339.431122)
		(end 333.093568 -339.431122)
		(width 0.254)
		(layer "F.Cu")
		(net "PVDDCR_CPU1_P0_VCCS")
	)
	(segment
		(start 348.972124 -344.391996)
		(end 349.700596 -344.391996)
		(width 0.254)
		(layer "F.Cu")
		(net "PVDDCR_CPU1_P0_VCCS")
	)
	(segment
		(start 306.706016 -349.616268)
		(end 306.706016 -349.807022)
		(width 0.2286)
		(layer "F.Cu")
		(net "PVDDCR_CPU1_P0_VCCS")
	)
	(segment
		(start 316.23 -365.99495)
		(end 315.214 -365.99495)
		(width 0.254)
		(layer "F.Cu")
		(net "PVDDCR_CPU1_P0_VCCS")
	)
	(segment
		(start 272.728182 -351.173796)
		(end 273.456654 -351.173796)
		(width 0.254)
		(layer "F.Cu")
		(net "PVDDCR_CPU1_P0_VCCS")
	)
	(segment
		(start 298.374816 -349.616268)
		(end 298.374816 -349.807022)
		(width 0.2286)
		(layer "F.Cu")
		(net "PVDDCR_CPU1_P0_VCCS")
	)
	(segment
		(start 348.972124 -343.729056)
		(end 348.972124 -344.391996)
		(width 0.2286)
		(layer "F.Cu")
		(net "PVDDCR_CPU1_P0_VCCS")
	)
	(segment
		(start 341.40013 -338.115148)
		(end 340.696296 -338.818982)
		(width 0.2286)
		(layer "F.Cu")
		(net "PVDDCR_CPU1_P0_VCCS")
	)
	(segment
		(start 332.365096 -338.768182)
		(end 332.365096 -339.431122)
		(width 0.2286)
		(layer "F.Cu")
		(net "PVDDCR_CPU1_P0_VCCS")
	)
	(segment
		(start 324.00748 -339.4456)
		(end 324.735952 -339.4456)
		(width 0.254)
		(layer "F.Cu")
		(net "PVDDCR_CPU1_P0_VCCS")
	)
	(segment
		(start 290.018216 -349.616268)
		(end 290.018216 -349.807022)
		(width 0.2286)
		(layer "F.Cu")
		(net "PVDDCR_CPU1_P0_VCCS")
	)
	(segment
		(start 324.711314 -337.888072)
		(end 324.711314 -338.078826)
		(width 0.2286)
		(layer "F.Cu")
		(net "PVDDCR_CPU1_P0_VCCS")
	)
	(segment
		(start 281.008582 -350.510856)
		(end 281.008582 -351.173796)
		(width 0.2286)
		(layer "F.Cu")
		(net "PVDDCR_CPU1_P0_VCCS")
	)
	(segment
		(start 281.712416 -349.807022)
		(end 281.008582 -350.510856)
		(width 0.2286)
		(layer "F.Cu")
		(net "PVDDCR_CPU1_P0_VCCS")
	)
	(segment
		(start 316.35573 -337.895184)
		(end 316.35573 -338.085938)
		(width 0.2286)
		(layer "F.Cu")
		(net "PVDDCR_CPU1_P0_VCCS")
	)
	(segment
		(start 313.436 -363.601)
		(end 314.8457 -365.0107)
		(width 0.254)
		(layer "F.Cu")
		(net "PVDDCR_CPU1_P0_VCCS")
	)
	(segment
		(start 273.432016 -349.616268)
		(end 273.432016 -349.807022)
		(width 0.2286)
		(layer "F.Cu")
		(net "PVDDCR_CPU1_P0_VCCS")
	)
	(segment
		(start 349.675958 -342.834468)
		(end 349.675958 -343.025222)
		(width 0.2286)
		(layer "F.Cu")
		(net "PVDDCR_CPU1_P0_VCCS")
	)
	(segment
		(start 297.670982 -350.510856)
		(end 297.670982 -351.173796)
		(width 0.2286)
		(layer "F.Cu")
		(net "PVDDCR_CPU1_P0_VCCS")
	)
	(segment
		(start 315.651896 -338.789772)
		(end 315.651896 -339.452712)
		(width 0.2286)
		(layer "F.Cu")
		(net "PVDDCR_CPU1_P0_VCCS")
	)
	(segment
		(start 272.728182 -350.510856)
		(end 272.728182 -351.173796)
		(width 0.2286)
		(layer "F.Cu")
		(net "PVDDCR_CPU1_P0_VCCS")
	)
	(segment
		(start 324.711314 -338.078826)
		(end 324.00748 -338.78266)
		(width 0.2286)
		(layer "F.Cu")
		(net "PVDDCR_CPU1_P0_VCCS")
	)
	(segment
		(start 324.00748 -338.78266)
		(end 324.00748 -339.4456)
		(width 0.2286)
		(layer "F.Cu")
		(net "PVDDCR_CPU1_P0_VCCS")
	)
	(segment
		(start 341.40013 -337.924394)
		(end 341.40013 -338.115148)
		(width 0.2286)
		(layer "F.Cu")
		(net "PVDDCR_CPU1_P0_VCCS")
	)
	(segment
		(start 306.706016 -349.807022)
		(end 306.002182 -350.510856)
		(width 0.2286)
		(layer "F.Cu")
		(net "PVDDCR_CPU1_P0_VCCS")
	)
	(segment
		(start 340.696296 -339.481922)
		(end 341.424768 -339.481922)
		(width 0.254)
		(layer "F.Cu")
		(net "PVDDCR_CPU1_P0_VCCS")
	)
	(segment
		(start 340.696296 -338.818982)
		(end 340.696296 -339.481922)
		(width 0.2286)
		(layer "F.Cu")
		(net "PVDDCR_CPU1_P0_VCCS")
	)
	(segment
		(start 281.712416 -349.616268)
		(end 281.712416 -349.807022)
		(width 0.2286)
		(layer "F.Cu")
		(net "PVDDCR_CPU1_P0_VCCS")
	)
	(segment
		(start 315.651896 -339.452712)
		(end 316.380368 -339.452712)
		(width 0.254)
		(layer "F.Cu")
		(net "PVDDCR_CPU1_P0_VCCS")
	)
	(segment
		(start 290.018216 -349.807022)
		(end 289.314382 -350.510856)
		(width 0.2286)
		(layer "F.Cu")
		(net "PVDDCR_CPU1_P0_VCCS")
	)
	(via
		(at 333.093568 -339.431122)
		(size 0.508)
		(drill 0.254)
		(layers "F.Cu" "B.Cu")
		(net "PVDDCR_CPU1_P0_VCCS")
	)
	(via
		(at 314.8457 -365.0107)
		(size 0.508)
		(drill 0.254)
		(layers "F.Cu" "B.Cu")
		(net "PVDDCR_CPU1_P0_VCCS")
	)
	(via
		(at 324.735952 -339.4456)
		(size 0.508)
		(drill 0.254)
		(layers "F.Cu" "B.Cu")
		(net "PVDDCR_CPU1_P0_VCCS")
	)
	(via
		(at 273.456654 -351.173796)
		(size 0.508)
		(drill 0.254)
		(layers "F.Cu" "B.Cu")
		(net "PVDDCR_CPU1_P0_VCCS")
	)
	(via
		(at 306.730654 -351.173796)
		(size 0.508)
		(drill 0.254)
		(layers "F.Cu" "B.Cu")
		(net "PVDDCR_CPU1_P0_VCCS")
	)
	(via
		(at 316.380368 -339.452712)
		(size 0.508)
		(drill 0.254)
		(layers "F.Cu" "B.Cu")
		(net "PVDDCR_CPU1_P0_VCCS")
	)
	(via
		(at 290.042854 -351.173796)
		(size 0.508)
		(drill 0.254)
		(layers "F.Cu" "B.Cu")
		(net "PVDDCR_CPU1_P0_VCCS")
	)
	(via
		(at 341.424768 -339.481922)
		(size 0.508)
		(drill 0.254)
		(layers "F.Cu" "B.Cu")
		(net "PVDDCR_CPU1_P0_VCCS")
	)
	(via
		(at 349.700596 -344.391996)
		(size 0.508)
		(drill 0.254)
		(layers "F.Cu" "B.Cu")
		(net "PVDDCR_CPU1_P0_VCCS")
	)
	(via
		(at 281.737054 -351.173796)
		(size 0.508)
		(drill 0.254)
		(layers "F.Cu" "B.Cu")
		(net "PVDDCR_CPU1_P0_VCCS")
	)
	(via
		(at 298.399454 -351.173796)
		(size 0.508)
		(drill 0.254)
		(layers "F.Cu" "B.Cu")
		(net "PVDDCR_CPU1_P0_VCCS")
	)
	(segment
		(start 281.408886 -351.868486)
		(end 282.2956 -352.7552)
		(width 0.254)
		(layer "In6.Cu")
		(net "PVDDCR_CPU1_P0_VCCS")
	)
	(segment
		(start 313.9186 -354.33)
		(end 313.9186 -354.654612)
		(width 0.254)
		(layer "In6.Cu")
		(net "PVDDCR_CPU1_P0_VCCS")
	)
	(segment
		(start 313.9186 -354.654612)
		(end 312.674 -355.899212)
		(width 0.254)
		(layer "In6.Cu")
		(net "PVDDCR_CPU1_P0_VCCS")
	)
	(segment
		(start 281.408886 -351.501964)
		(end 281.408886 -351.868486)
		(width 0.254)
		(layer "In6.Cu")
		(net "PVDDCR_CPU1_P0_VCCS")
	)
	(segment
		(start 314.6044 -351.663)
		(end 317.373 -351.663)
		(width 0.254)
		(layer "In6.Cu")
		(net "PVDDCR_CPU1_P0_VCCS")
	)
	(segment
		(start 313.1312 -353.949)
		(end 314.0964 -353.949)
		(width 0.254)
		(layer "In6.Cu")
		(net "PVDDCR_CPU1_P0_VCCS")
	)
	(segment
		(start 314.6806 -353.4664)
		(end 317.9318 -353.4664)
		(width 0.254)
		(layer "In6.Cu")
		(net "PVDDCR_CPU1_P0_VCCS")
	)
	(segment
		(start 316.263274 -340.905846)
		(end 316.263274 -339.569806)
		(width 0.254)
		(layer "In6.Cu")
		(net "PVDDCR_CPU1_P0_VCCS")
	)
	(segment
		(start 312.674 -355.899212)
		(end 312.674 -356.8192)
		(width 0.254)
		(layer "In6.Cu")
		(net "PVDDCR_CPU1_P0_VCCS")
	)
	(segment
		(start 324.102984 -347.295216)
		(end 324.102984 -345.0971)
		(width 0.254)
		(layer "In6.Cu")
		(net "PVDDCR_CPU1_P0_VCCS")
	)
	(segment
		(start 307.757576 -357.251)
		(end 303.904396 -353.39782)
		(width 0.254)
		(layer "In6.Cu")
		(net "PVDDCR_CPU1_P0_VCCS")
	)
	(segment
		(start 312.0644 -351.8662)
		(end 312.806588 -351.8662)
		(width 0.254)
		(layer "In6.Cu")
		(net "PVDDCR_CPU1_P0_VCCS")
	)
	(segment
		(start 310.3372 -354.1522)
		(end 310.3372 -353.5934)
		(width 0.254)
		(layer "In6.Cu")
		(net "PVDDCR_CPU1_P0_VCCS")
	)
	(segment
		(start 317.373 -351.663)
		(end 322.304664 -346.731336)
		(width 0.254)
		(layer "In6.Cu")
		(net "PVDDCR_CPU1_P0_VCCS")
	)
	(segment
		(start 324.308724 -339.872828)
		(end 324.735952 -339.4456)
		(width 0.254)
		(layer "In6.Cu")
		(net "PVDDCR_CPU1_P0_VCCS")
	)
	(segment
		(start 299.974 -352.7552)
		(end 300.6344 -352.0948)
		(width 0.254)
		(layer "In6.Cu")
		(net "PVDDCR_CPU1_P0_VCCS")
	)
	(segment
		(start 300.54042 -353.868228)
		(end 275.80717 -353.868228)
		(width 0.254)
		(layer "In6.Cu")
		(net "PVDDCR_CPU1_P0_VCCS")
	)
	(segment
		(start 312.2422 -357.251)
		(end 307.757576 -357.251)
		(width 0.254)
		(layer "In6.Cu")
		(net "PVDDCR_CPU1_P0_VCCS")
	)
	(segment
		(start 282.2956 -352.7552)
		(end 299.974 -352.7552)
		(width 0.254)
		(layer "In6.Cu")
		(net "PVDDCR_CPU1_P0_VCCS")
	)
	(segment
		(start 324.102984 -345.0971)
		(end 327.484232 -341.715852)
		(width 0.254)
		(layer "In6.Cu")
		(net "PVDDCR_CPU1_P0_VCCS")
	)
	(segment
		(start 309.9308 -355.8794)
		(end 311.15 -354.6602)
		(width 0.254)
		(layer "In6.Cu")
		(net "PVDDCR_CPU1_P0_VCCS")
	)
	(segment
		(start 273.456654 -351.517712)
		(end 273.456654 -351.173796)
		(width 0.254)
		(layer "In6.Cu")
		(net "PVDDCR_CPU1_P0_VCCS")
	)
	(segment
		(start 303.904396 -353.39782)
		(end 301.010828 -353.39782)
		(width 0.254)
		(layer "In6.Cu")
		(net "PVDDCR_CPU1_P0_VCCS")
	)
	(segment
		(start 312.806588 -351.8662)
		(end 314.140088 -350.5327)
		(width 0.254)
		(layer "In6.Cu")
		(net "PVDDCR_CPU1_P0_VCCS")
	)
	(segment
		(start 324.308724 -341.4268)
		(end 324.308724 -339.872828)
		(width 0.254)
		(layer "In6.Cu")
		(net "PVDDCR_CPU1_P0_VCCS")
	)
	(segment
		(start 322.304664 -343.43086)
		(end 324.308724 -341.4268)
		(width 0.254)
		(layer "In6.Cu")
		(net "PVDDCR_CPU1_P0_VCCS")
	)
	(segment
		(start 281.737054 -351.173796)
		(end 281.408886 -351.501964)
		(width 0.254)
		(layer "In6.Cu")
		(net "PVDDCR_CPU1_P0_VCCS")
	)
	(segment
		(start 317.9318 -353.4664)
		(end 324.102984 -347.295216)
		(width 0.254)
		(layer "In6.Cu")
		(net "PVDDCR_CPU1_P0_VCCS")
	)
	(segment
		(start 327.484232 -341.715852)
		(end 331.855572 -341.715852)
		(width 0.254)
		(layer "In6.Cu")
		(net "PVDDCR_CPU1_P0_VCCS")
	)
	(segment
		(start 312.674 -356.8192)
		(end 312.2422 -357.251)
		(width 0.254)
		(layer "In6.Cu")
		(net "PVDDCR_CPU1_P0_VCCS")
	)
	(segment
		(start 314.140088 -350.5327)
		(end 314.140088 -343.029032)
		(width 0.254)
		(layer "In6.Cu")
		(net "PVDDCR_CPU1_P0_VCCS")
	)
	(segment
		(start 333.093568 -340.477856)
		(end 333.093568 -339.431122)
		(width 0.254)
		(layer "In6.Cu")
		(net "PVDDCR_CPU1_P0_VCCS")
	)
	(segment
		(start 331.855572 -341.715852)
		(end 333.093568 -340.477856)
		(width 0.254)
		(layer "In6.Cu")
		(net "PVDDCR_CPU1_P0_VCCS")
	)
	(segment
		(start 275.80717 -353.868228)
		(end 273.456654 -351.517712)
		(width 0.254)
		(layer "In6.Cu")
		(net "PVDDCR_CPU1_P0_VCCS")
	)
	(segment
		(start 322.304664 -346.731336)
		(end 322.304664 -343.43086)
		(width 0.254)
		(layer "In6.Cu")
		(net "PVDDCR_CPU1_P0_VCCS")
	)
	(segment
		(start 314.140088 -343.029032)
		(end 316.263274 -340.905846)
		(width 0.254)
		(layer "In6.Cu")
		(net "PVDDCR_CPU1_P0_VCCS")
	)
	(segment
		(start 312.42 -354.6602)
		(end 313.1312 -353.949)
		(width 0.254)
		(layer "In6.Cu")
		(net "PVDDCR_CPU1_P0_VCCS")
	)
	(segment
		(start 312.1152 -354.1522)
		(end 314.6044 -351.663)
		(width 0.254)
		(layer "In6.Cu")
		(net "PVDDCR_CPU1_P0_VCCS")
	)
	(segment
		(start 304.4444 -352.0948)
		(end 308.229 -355.8794)
		(width 0.254)
		(layer "In6.Cu")
		(net "PVDDCR_CPU1_P0_VCCS")
	)
	(segment
		(start 310.3372 -353.5934)
		(end 312.0644 -351.8662)
		(width 0.254)
		(layer "In6.Cu")
		(net "PVDDCR_CPU1_P0_VCCS")
	)
	(segment
		(start 308.229 -355.8794)
		(end 309.9308 -355.8794)
		(width 0.254)
		(layer "In6.Cu")
		(net "PVDDCR_CPU1_P0_VCCS")
	)
	(segment
		(start 311.15 -354.6602)
		(end 312.42 -354.6602)
		(width 0.254)
		(layer "In6.Cu")
		(net "PVDDCR_CPU1_P0_VCCS")
	)
	(segment
		(start 316.263274 -339.569806)
		(end 316.380368 -339.452712)
		(width 0.254)
		(layer "In6.Cu")
		(net "PVDDCR_CPU1_P0_VCCS")
	)
	(segment
		(start 300.6344 -352.0948)
		(end 304.4444 -352.0948)
		(width 0.254)
		(layer "In6.Cu")
		(net "PVDDCR_CPU1_P0_VCCS")
	)
	(segment
		(start 301.010828 -353.39782)
		(end 300.54042 -353.868228)
		(width 0.254)
		(layer "In6.Cu")
		(net "PVDDCR_CPU1_P0_VCCS")
	)
	(segment
		(start 311.4294 -354.6856)
		(end 312.3184 -354.6856)
		(width 0.254)
		(layer "In11.Cu")
		(net "PVDDCR_CPU1_P0_VCCS")
	)
	(segment
		(start 312.6994 -355.0666)
		(end 314.579 -355.0666)
		(width 0.254)
		(layer "In11.Cu")
		(net "PVDDCR_CPU1_P0_VCCS")
	)
	(segment
		(start 290.042854 -351.173796)
		(end 289.78479 -351.43186)
		(width 0.254)
		(layer "In11.Cu")
		(net "PVDDCR_CPU1_P0_VCCS")
	)
	(segment
		(start 306.40909 -351.92589)
		(end 306.40909 -351.49536)
		(width 0.254)
		(layer "In11.Cu")
		(net "PVDDCR_CPU1_P0_VCCS")
	)
	(segment
		(start 310.1848 -355.9302)
		(end 311.4294 -354.6856)
		(width 0.254)
		(layer "In11.Cu")
		(net "PVDDCR_CPU1_P0_VCCS")
	)
	(segment
		(start 348.965774 -346.186252)
		(end 349.386652 -345.765374)
		(width 0.254)
		(layer "In11.Cu")
		(net "PVDDCR_CPU1_P0_VCCS")
	)
	(segment
		(start 314.731654 -351.9932)
		(end 319.195704 -351.9932)
		(width 0.254)
		(layer "In11.Cu")
		(net "PVDDCR_CPU1_P0_VCCS")
	)
	(segment
		(start 289.78479 -351.43186)
		(end 289.78479 -351.936812)
		(width 0.254)
		(layer "In11.Cu")
		(net "PVDDCR_CPU1_P0_VCCS")
	)
	(segment
		(start 314.579 -355.0666)
		(end 315.3156 -355.8032)
		(width 0.254)
		(layer "In11.Cu")
		(net "PVDDCR_CPU1_P0_VCCS")
	)
	(segment
		(start 298.757086 -352.395028)
		(end 304.592228 -352.395028)
		(width 0.254)
		(layer "In11.Cu")
		(net "PVDDCR_CPU1_P0_VCCS")
	)
	(segment
		(start 298.147486 -351.425764)
		(end 298.147486 -351.785428)
		(width 0.254)
		(layer "In11.Cu")
		(net "PVDDCR_CPU1_P0_VCCS")
	)
	(segment
		(start 311.531 -354.1522)
		(end 311.531 -353.116388)
		(width 0.254)
		(layer "In11.Cu")
		(net "PVDDCR_CPU1_P0_VCCS")
	)
	(segment
		(start 311.531 -353.116388)
		(end 313.974988 -350.6724)
		(width 0.254)
		(layer "In11.Cu")
		(net "PVDDCR_CPU1_P0_VCCS")
	)
	(segment
		(start 343.589356 -343.158572)
		(end 346.617036 -346.186252)
		(width 0.254)
		(layer "In11.Cu")
		(net "PVDDCR_CPU1_P0_VCCS")
	)
	(segment
		(start 312.3184 -354.6856)
		(end 312.6994 -355.0666)
		(width 0.254)
		(layer "In11.Cu")
		(net "PVDDCR_CPU1_P0_VCCS")
	)
	(segment
		(start 349.386652 -345.765374)
		(end 349.386652 -344.70594)
		(width 0.254)
		(layer "In11.Cu")
		(net "PVDDCR_CPU1_P0_VCCS")
	)
	(segment
		(start 317.953644 -350.6724)
		(end 326.839072 -341.786972)
		(width 0.254)
		(layer "In11.Cu")
		(net "PVDDCR_CPU1_P0_VCCS")
	)
	(segment
		(start 291.288978 -353.441)
		(end 303.911 -353.441)
		(width 0.254)
		(layer "In11.Cu")
		(net "PVDDCR_CPU1_P0_VCCS")
	)
	(segment
		(start 313.182 -356.2096)
		(end 313.8932 -356.2096)
		(width 0.254)
		(layer "In11.Cu")
		(net "PVDDCR_CPU1_P0_VCCS")
	)
	(segment
		(start 311.6072 -357.7844)
		(end 313.182 -356.2096)
		(width 0.254)
		(layer "In11.Cu")
		(net "PVDDCR_CPU1_P0_VCCS")
	)
	(segment
		(start 298.399454 -351.173796)
		(end 298.147486 -351.425764)
		(width 0.254)
		(layer "In11.Cu")
		(net "PVDDCR_CPU1_P0_VCCS")
	)
	(segment
		(start 307.7464 -352.425)
		(end 306.9082 -352.425)
		(width 0.254)
		(layer "In11.Cu")
		(net "PVDDCR_CPU1_P0_VCCS")
	)
	(segment
		(start 308.1274 -355.9302)
		(end 310.1848 -355.9302)
		(width 0.254)
		(layer "In11.Cu")
		(net "PVDDCR_CPU1_P0_VCCS")
	)
	(segment
		(start 326.839072 -341.786972)
		(end 340.179152 -341.786972)
		(width 0.254)
		(layer "In11.Cu")
		(net "PVDDCR_CPU1_P0_VCCS")
	)
	(segment
		(start 306.9082 -352.425)
		(end 306.40909 -351.92589)
		(width 0.254)
		(layer "In11.Cu")
		(net "PVDDCR_CPU1_P0_VCCS")
	)
	(segment
		(start 313.8932 -356.2096)
		(end 314.2488 -356.5652)
		(width 0.254)
		(layer "In11.Cu")
		(net "PVDDCR_CPU1_P0_VCCS")
	)
	(segment
		(start 308.2544 -357.7844)
		(end 311.6072 -357.7844)
		(width 0.254)
		(layer "In11.Cu")
		(net "PVDDCR_CPU1_P0_VCCS")
	)
	(segment
		(start 328.030332 -343.158572)
		(end 343.589356 -343.158572)
		(width 0.254)
		(layer "In11.Cu")
		(net "PVDDCR_CPU1_P0_VCCS")
	)
	(segment
		(start 313.974988 -350.6724)
		(end 317.953644 -350.6724)
		(width 0.254)
		(layer "In11.Cu")
		(net "PVDDCR_CPU1_P0_VCCS")
	)
	(segment
		(start 319.195704 -351.9932)
		(end 328.030332 -343.158572)
		(width 0.254)
		(layer "In11.Cu")
		(net "PVDDCR_CPU1_P0_VCCS")
	)
	(segment
		(start 314.2996 -353.6442)
		(end 314.2996 -352.425254)
		(width 0.254)
		(layer "In11.Cu")
		(net "PVDDCR_CPU1_P0_VCCS")
	)
	(segment
		(start 349.386652 -344.70594)
		(end 349.700596 -344.391996)
		(width 0.254)
		(layer "In11.Cu")
		(net "PVDDCR_CPU1_P0_VCCS")
	)
	(segment
		(start 304.592228 -352.395028)
		(end 308.1274 -355.9302)
		(width 0.254)
		(layer "In11.Cu")
		(net "PVDDCR_CPU1_P0_VCCS")
	)
	(segment
		(start 310.3626 -355.0412)
		(end 307.7464 -352.425)
		(width 0.254)
		(layer "In11.Cu")
		(net "PVDDCR_CPU1_P0_VCCS")
	)
	(segment
		(start 340.179152 -341.786972)
		(end 341.110824 -340.8553)
		(width 0.254)
		(layer "In11.Cu")
		(net "PVDDCR_CPU1_P0_VCCS")
	)
	(segment
		(start 306.40909 -351.49536)
		(end 306.730654 -351.173796)
		(width 0.254)
		(layer "In11.Cu")
		(net "PVDDCR_CPU1_P0_VCCS")
	)
	(segment
		(start 314.2996 -352.425254)
		(end 314.731654 -351.9932)
		(width 0.254)
		(layer "In11.Cu")
		(net "PVDDCR_CPU1_P0_VCCS")
	)
	(segment
		(start 346.617036 -346.186252)
		(end 348.965774 -346.186252)
		(width 0.254)
		(layer "In11.Cu")
		(net "PVDDCR_CPU1_P0_VCCS")
	)
	(segment
		(start 298.147486 -351.785428)
		(end 298.757086 -352.395028)
		(width 0.254)
		(layer "In11.Cu")
		(net "PVDDCR_CPU1_P0_VCCS")
	)
	(segment
		(start 341.110824 -339.795866)
		(end 341.424768 -339.481922)
		(width 0.254)
		(layer "In11.Cu")
		(net "PVDDCR_CPU1_P0_VCCS")
	)
	(segment
		(start 341.110824 -340.8553)
		(end 341.110824 -339.795866)
		(width 0.254)
		(layer "In11.Cu")
		(net "PVDDCR_CPU1_P0_VCCS")
	)
	(segment
		(start 303.911 -353.441)
		(end 308.2544 -357.7844)
		(width 0.254)
		(layer "In11.Cu")
		(net "PVDDCR_CPU1_P0_VCCS")
	)
	(segment
		(start 289.78479 -351.936812)
		(end 291.288978 -353.441)
		(width 0.254)
		(layer "In11.Cu")
		(net "PVDDCR_CPU1_P0_VCCS")
	)
	(segment
		(start 348.615254 -341.309452)
		(end 349.266002 -341.309452)
		(width 0.2286)
		(layer "F.Cu")
		(net "PVDDCR_CPU1_P0_VCC6")
	)
	(segment
		(start 351.476056 -343.54643)
		(end 351.400364 -343.622122)
		(width 0.2286)
		(layer "F.Cu")
		(net "PVDDCR_CPU1_P0_VCC6")
	)
	(segment
		(start 347.983048 -342.199722)
		(end 347.983048 -341.58936)
		(width 0.4572)
		(layer "F.Cu")
		(net "PVDDCR_CPU1_P0_VCC6")
	)
	(segment
		(start 351.476056 -342.834468)
		(end 351.476056 -343.54643)
		(width 0.2286)
		(layer "F.Cu")
		(net "PVDDCR_CPU1_P0_VCC6")
	)
	(segment
		(start 348.335346 -341.58936)
		(end 348.615254 -341.309452)
		(width 0.2286)
		(layer "F.Cu")
		(net "PVDDCR_CPU1_P0_VCC6")
	)
	(segment
		(start 347.983048 -341.58936)
		(end 348.335346 -341.58936)
		(width 0.2286)
		(layer "F.Cu")
		(net "PVDDCR_CPU1_P0_VCC6")
	)
	(via
		(at 349.810578 -342.703658)
		(size 0.6604)
		(drill 0.3302)
		(layers "F.Cu" "B.Cu")
		(net "PVDDCR_CPU1_P0_VCC6")
	)
	(via
		(at 351.400364 -343.622122)
		(size 0.508)
		(drill 0.254)
		(layers "F.Cu" "B.Cu")
		(net "PVDDCR_CPU1_P0_VCC6")
	)
	(via
		(at 347.983048 -341.58936)
		(size 0.508)
		(drill 0.254)
		(layers "F.Cu" "B.Cu")
		(net "PVDDCR_CPU1_P0_VCC6")
	)
	(segment
		(start 349.810578 -342.703658)
		(end 349.810578 -342.809322)
		(width 0.381)
		(layer "B.Cu")
		(net "PVDDCR_CPU1_P0_VCC6")
	)
	(segment
		(start 349.355156 -341.39378)
		(end 348.845378 -341.39378)
		(width 0.381)
		(layer "B.Cu")
		(net "PVDDCR_CPU1_P0_VCC6")
	)
	(segment
		(start 349.355156 -342.248236)
		(end 349.810578 -342.703658)
		(width 0.381)
		(layer "B.Cu")
		(net "PVDDCR_CPU1_P0_VCC6")
	)
	(segment
		(start 348.845378 -341.39378)
		(end 348.649798 -341.58936)
		(width 0.381)
		(layer "B.Cu")
		(net "PVDDCR_CPU1_P0_VCC6")
	)
	(segment
		(start 348.649798 -341.58936)
		(end 347.983048 -341.58936)
		(width 0.381)
		(layer "B.Cu")
		(net "PVDDCR_CPU1_P0_VCC6")
	)
	(segment
		(start 350.124014 -343.122758)
		(end 350.901 -343.122758)
		(width 0.4572)
		(layer "B.Cu")
		(net "PVDDCR_CPU1_P0_VCC6")
	)
	(segment
		(start 349.355156 -341.39378)
		(end 349.355156 -342.248236)
		(width 0.381)
		(layer "B.Cu")
		(net "PVDDCR_CPU1_P0_VCC6")
	)
	(segment
		(start 350.901 -343.122758)
		(end 351.400364 -343.622122)
		(width 0.4572)
		(layer "B.Cu")
		(net "PVDDCR_CPU1_P0_VCC6")
	)
	(segment
		(start 349.810578 -342.809322)
		(end 350.124014 -343.122758)
		(width 0.4572)
		(layer "B.Cu")
		(net "PVDDCR_CPU1_P0_VCC6")
	)
	(segment
		(start 343.200228 -338.636356)
		(end 343.124536 -338.712048)
		(width 0.2286)
		(layer "F.Cu")
		(net "PVDDCR_CPU1_P0_VCC5")
	)
	(segment
		(start 339.70722 -336.679286)
		(end 340.059518 -336.679286)
		(width 0.2286)
		(layer "F.Cu")
		(net "PVDDCR_CPU1_P0_VCC5")
	)
	(segment
		(start 340.339426 -336.399378)
		(end 340.990174 -336.399378)
		(width 0.2286)
		(layer "F.Cu")
		(net "PVDDCR_CPU1_P0_VCC5")
	)
	(segment
		(start 339.70722 -337.289648)
		(end 339.70722 -336.679286)
		(width 0.4572)
		(layer "F.Cu")
		(net "PVDDCR_CPU1_P0_VCC5")
	)
	(segment
		(start 343.200228 -337.924394)
		(end 343.200228 -338.636356)
		(width 0.2286)
		(layer "F.Cu")
		(net "PVDDCR_CPU1_P0_VCC5")
	)
	(segment
		(start 340.059518 -336.679286)
		(end 340.339426 -336.399378)
		(width 0.2286)
		(layer "F.Cu")
		(net "PVDDCR_CPU1_P0_VCC5")
	)
	(via
		(at 341.53475 -337.793584)
		(size 0.6604)
		(drill 0.3302)
		(layers "F.Cu" "B.Cu")
		(net "PVDDCR_CPU1_P0_VCC5")
	)
	(via
		(at 343.124536 -338.712048)
		(size 0.508)
		(drill 0.254)
		(layers "F.Cu" "B.Cu")
		(net "PVDDCR_CPU1_P0_VCC5")
	)
	(via
		(at 339.70722 -336.679286)
		(size 0.508)
		(drill 0.254)
		(layers "F.Cu" "B.Cu")
		(net "PVDDCR_CPU1_P0_VCC5")
	)
	(segment
		(start 341.848186 -338.212684)
		(end 341.53475 -337.899248)
		(width 0.4572)
		(layer "B.Cu")
		(net "PVDDCR_CPU1_P0_VCC5")
	)
	(segment
		(start 339.70722 -336.679286)
		(end 340.37397 -336.679286)
		(width 0.381)
		(layer "B.Cu")
		(net "PVDDCR_CPU1_P0_VCC5")
	)
	(segment
		(start 342.625172 -338.212684)
		(end 341.848186 -338.212684)
		(width 0.4572)
		(layer "B.Cu")
		(net "PVDDCR_CPU1_P0_VCC5")
	)
	(segment
		(start 343.124536 -338.712048)
		(end 342.625172 -338.212684)
		(width 0.4572)
		(layer "B.Cu")
		(net "PVDDCR_CPU1_P0_VCC5")
	)
	(segment
		(start 341.53475 -337.793584)
		(end 341.079328 -337.338162)
		(width 0.381)
		(layer "B.Cu")
		(net "PVDDCR_CPU1_P0_VCC5")
	)
	(segment
		(start 340.37397 -336.679286)
		(end 340.56955 -336.483706)
		(width 0.381)
		(layer "B.Cu")
		(net "PVDDCR_CPU1_P0_VCC5")
	)
	(segment
		(start 341.079328 -337.338162)
		(end 341.079328 -336.483706)
		(width 0.381)
		(layer "B.Cu")
		(net "PVDDCR_CPU1_P0_VCC5")
	)
	(segment
		(start 340.56955 -336.483706)
		(end 341.079328 -336.483706)
		(width 0.381)
		(layer "B.Cu")
		(net "PVDDCR_CPU1_P0_VCC5")
	)
	(segment
		(start 341.53475 -337.899248)
		(end 341.53475 -337.793584)
		(width 0.381)
		(layer "B.Cu")
		(net "PVDDCR_CPU1_P0_VCC5")
	)
	(segment
		(start 305.645312 -348.091252)
		(end 305.365404 -348.37116)
		(width 0.2286)
		(layer "F.Cu")
		(net "PVDDCR_CPU1_P0_VCC4")
	)
	(segment
		(start 308.506114 -349.616268)
		(end 308.506114 -350.32823)
		(width 0.2286)
		(layer "F.Cu")
		(net "PVDDCR_CPU1_P0_VCC4")
	)
	(segment
		(start 308.506114 -350.32823)
		(end 308.430422 -350.403922)
		(width 0.2286)
		(layer "F.Cu")
		(net "PVDDCR_CPU1_P0_VCC4")
	)
	(segment
		(start 306.29606 -348.091252)
		(end 305.645312 -348.091252)
		(width 0.2286)
		(layer "F.Cu")
		(net "PVDDCR_CPU1_P0_VCC4")
	)
	(segment
		(start 305.365404 -348.37116)
		(end 305.013106 -348.37116)
		(width 0.2286)
		(layer "F.Cu")
		(net "PVDDCR_CPU1_P0_VCC4")
	)
	(segment
		(start 305.013106 -348.37116)
		(end 305.013106 -348.981522)
		(width 0.4572)
		(layer "F.Cu")
		(net "PVDDCR_CPU1_P0_VCC4")
	)
	(via
		(at 308.430422 -350.403922)
		(size 0.508)
		(drill 0.254)
		(layers "F.Cu" "B.Cu")
		(net "PVDDCR_CPU1_P0_VCC4")
	)
	(via
		(at 305.013106 -348.37116)
		(size 0.508)
		(drill 0.254)
		(layers "F.Cu" "B.Cu")
		(net "PVDDCR_CPU1_P0_VCC4")
	)
	(via
		(at 306.840636 -349.485458)
		(size 0.6604)
		(drill 0.3302)
		(layers "F.Cu" "B.Cu")
		(net "PVDDCR_CPU1_P0_VCC4")
	)
	(segment
		(start 305.875436 -348.17558)
		(end 306.385214 -348.17558)
		(width 0.381)
		(layer "B.Cu")
		(net "PVDDCR_CPU1_P0_VCC4")
	)
	(segment
		(start 308.430422 -350.361758)
		(end 308.430422 -350.403922)
		(width 0.4572)
		(layer "B.Cu")
		(net "PVDDCR_CPU1_P0_VCC4")
	)
	(segment
		(start 306.840636 -349.485458)
		(end 307.219604 -349.864426)
		(width 0.4572)
		(layer "B.Cu")
		(net "PVDDCR_CPU1_P0_VCC4")
	)
	(segment
		(start 307.219604 -349.864426)
		(end 307.93309 -349.864426)
		(width 0.4572)
		(layer "B.Cu")
		(net "PVDDCR_CPU1_P0_VCC4")
	)
	(segment
		(start 305.013106 -348.37116)
		(end 305.679856 -348.37116)
		(width 0.381)
		(layer "B.Cu")
		(net "PVDDCR_CPU1_P0_VCC4")
	)
	(segment
		(start 306.385214 -349.030036)
		(end 306.840636 -349.485458)
		(width 0.381)
		(layer "B.Cu")
		(net "PVDDCR_CPU1_P0_VCC4")
	)
	(segment
		(start 305.679856 -348.37116)
		(end 305.875436 -348.17558)
		(width 0.381)
		(layer "B.Cu")
		(net "PVDDCR_CPU1_P0_VCC4")
	)
	(segment
		(start 306.385214 -348.17558)
		(end 306.385214 -349.030036)
		(width 0.381)
		(layer "B.Cu")
		(net "PVDDCR_CPU1_P0_VCC4")
	)
	(segment
		(start 307.93309 -349.864426)
		(end 308.430422 -350.361758)
		(width 0.4572)
		(layer "B.Cu")
		(net "PVDDCR_CPU1_P0_VCC4")
	)
	(segment
		(start 315.015118 -336.650076)
		(end 314.66282 -336.650076)
		(width 0.2286)
		(layer "F.Cu")
		(net "PVDDCR_CPU1_P0_VCC3")
	)
	(segment
		(start 314.66282 -336.650076)
		(end 314.66282 -337.260438)
		(width 0.4572)
		(layer "F.Cu")
		(net "PVDDCR_CPU1_P0_VCC3")
	)
	(segment
		(start 315.945774 -336.370168)
		(end 315.295026 -336.370168)
		(width 0.2286)
		(layer "F.Cu")
		(net "PVDDCR_CPU1_P0_VCC3")
	)
	(segment
		(start 318.155828 -337.895184)
		(end 318.155828 -338.607146)
		(width 0.2286)
		(layer "F.Cu")
		(net "PVDDCR_CPU1_P0_VCC3")
	)
	(segment
		(start 315.295026 -336.370168)
		(end 315.015118 -336.650076)
		(width 0.2286)
		(layer "F.Cu")
		(net "PVDDCR_CPU1_P0_VCC3")
	)
	(segment
		(start 318.155828 -338.607146)
		(end 318.080136 -338.682838)
		(width 0.2286)
		(layer "F.Cu")
		(net "PVDDCR_CPU1_P0_VCC3")
	)
	(via
		(at 314.66282 -336.650076)
		(size 0.508)
		(drill 0.254)
		(layers "F.Cu" "B.Cu")
		(net "PVDDCR_CPU1_P0_VCC3")
	)
	(via
		(at 318.080136 -338.682838)
		(size 0.508)
		(drill 0.254)
		(layers "F.Cu" "B.Cu")
		(net "PVDDCR_CPU1_P0_VCC3")
	)
	(via
		(at 316.49035 -337.764374)
		(size 0.6604)
		(drill 0.3302)
		(layers "F.Cu" "B.Cu")
		(net "PVDDCR_CPU1_P0_VCC3")
	)
	(segment
		(start 316.803786 -338.183474)
		(end 317.580772 -338.183474)
		(width 0.4572)
		(layer "B.Cu")
		(net "PVDDCR_CPU1_P0_VCC3")
	)
	(segment
		(start 314.66282 -336.650076)
		(end 315.32957 -336.650076)
		(width 0.381)
		(layer "B.Cu")
		(net "PVDDCR_CPU1_P0_VCC3")
	)
	(segment
		(start 315.32957 -336.650076)
		(end 315.52515 -336.454496)
		(width 0.381)
		(layer "B.Cu")
		(net "PVDDCR_CPU1_P0_VCC3")
	)
	(segment
		(start 315.52515 -336.454496)
		(end 316.034928 -336.454496)
		(width 0.381)
		(layer "B.Cu")
		(net "PVDDCR_CPU1_P0_VCC3")
	)
	(segment
		(start 316.034928 -337.308952)
		(end 316.49035 -337.764374)
		(width 0.381)
		(layer "B.Cu")
		(net "PVDDCR_CPU1_P0_VCC3")
	)
	(segment
		(start 316.49035 -337.870038)
		(end 316.803786 -338.183474)
		(width 0.4572)
		(layer "B.Cu")
		(net "PVDDCR_CPU1_P0_VCC3")
	)
	(segment
		(start 316.49035 -337.764374)
		(end 316.49035 -337.870038)
		(width 0.381)
		(layer "B.Cu")
		(net "PVDDCR_CPU1_P0_VCC3")
	)
	(segment
		(start 317.580772 -338.183474)
		(end 318.080136 -338.682838)
		(width 0.4572)
		(layer "B.Cu")
		(net "PVDDCR_CPU1_P0_VCC3")
	)
	(segment
		(start 316.034928 -336.454496)
		(end 316.034928 -337.308952)
		(width 0.381)
		(layer "B.Cu")
		(net "PVDDCR_CPU1_P0_VCC3")
	)
	(segment
		(start 326.511412 -338.600034)
		(end 326.43572 -338.675726)
		(width 0.2286)
		(layer "F.Cu")
		(net "PVDDCR_CPU1_P0_VCC2")
	)
	(segment
		(start 326.511412 -337.888072)
		(end 326.511412 -338.600034)
		(width 0.2286)
		(layer "F.Cu")
		(net "PVDDCR_CPU1_P0_VCC2")
	)
	(segment
		(start 323.65061 -336.363056)
		(end 323.370702 -336.642964)
		(width 0.2286)
		(layer "F.Cu")
		(net "PVDDCR_CPU1_P0_VCC2")
	)
	(segment
		(start 323.370702 -336.642964)
		(end 323.018404 -336.642964)
		(width 0.2286)
		(layer "F.Cu")
		(net "PVDDCR_CPU1_P0_VCC2")
	)
	(segment
		(start 324.301358 -336.363056)
		(end 323.65061 -336.363056)
		(width 0.2286)
		(layer "F.Cu")
		(net "PVDDCR_CPU1_P0_VCC2")
	)
	(segment
		(start 323.018404 -336.642964)
		(end 323.018404 -337.253326)
		(width 0.4572)
		(layer "F.Cu")
		(net "PVDDCR_CPU1_P0_VCC2")
	)
	(via
		(at 323.018404 -336.642964)
		(size 0.508)
		(drill 0.254)
		(layers "F.Cu" "B.Cu")
		(net "PVDDCR_CPU1_P0_VCC2")
	)
	(via
		(at 324.845934 -337.757262)
		(size 0.6604)
		(drill 0.3302)
		(layers "F.Cu" "B.Cu")
		(net "PVDDCR_CPU1_P0_VCC2")
	)
	(via
		(at 326.43572 -338.675726)
		(size 0.508)
		(drill 0.254)
		(layers "F.Cu" "B.Cu")
		(net "PVDDCR_CPU1_P0_VCC2")
	)
	(segment
		(start 323.880734 -336.447384)
		(end 324.390512 -336.447384)
		(width 0.381)
		(layer "B.Cu")
		(net "PVDDCR_CPU1_P0_VCC2")
	)
	(segment
		(start 326.43572 -338.675726)
		(end 325.936356 -338.176362)
		(width 0.4572)
		(layer "B.Cu")
		(net "PVDDCR_CPU1_P0_VCC2")
	)
	(segment
		(start 323.018404 -336.642964)
		(end 323.685154 -336.642964)
		(width 0.381)
		(layer "B.Cu")
		(net "PVDDCR_CPU1_P0_VCC2")
	)
	(segment
		(start 324.845934 -337.862926)
		(end 324.845934 -337.757262)
		(width 0.381)
		(layer "B.Cu")
		(net "PVDDCR_CPU1_P0_VCC2")
	)
	(segment
		(start 325.936356 -338.176362)
		(end 325.15937 -338.176362)
		(width 0.4572)
		(layer "B.Cu")
		(net "PVDDCR_CPU1_P0_VCC2")
	)
	(segment
		(start 324.390512 -337.30184)
		(end 324.390512 -336.447384)
		(width 0.381)
		(layer "B.Cu")
		(net "PVDDCR_CPU1_P0_VCC2")
	)
	(segment
		(start 323.685154 -336.642964)
		(end 323.880734 -336.447384)
		(width 0.381)
		(layer "B.Cu")
		(net "PVDDCR_CPU1_P0_VCC2")
	)
	(segment
		(start 324.845934 -337.757262)
		(end 324.390512 -337.30184)
		(width 0.381)
		(layer "B.Cu")
		(net "PVDDCR_CPU1_P0_VCC2")
	)
	(segment
		(start 325.15937 -338.176362)
		(end 324.845934 -337.862926)
		(width 0.4572)
		(layer "B.Cu")
		(net "PVDDCR_CPU1_P0_VCC2")
	)
	(segment
		(start 334.869028 -337.873594)
		(end 334.869028 -338.585556)
		(width 0.2286)
		(layer "F.Cu")
		(net "PVDDCR_CPU1_P0_VCC1")
	)
	(segment
		(start 331.728318 -336.628486)
		(end 332.008226 -336.348578)
		(width 0.2286)
		(layer "F.Cu")
		(net "PVDDCR_CPU1_P0_VCC1")
	)
	(segment
		(start 331.37602 -337.238848)
		(end 331.37602 -336.628486)
		(width 0.4572)
		(layer "F.Cu")
		(net "PVDDCR_CPU1_P0_VCC1")
	)
	(segment
		(start 334.869028 -338.585556)
		(end 334.793336 -338.661248)
		(width 0.2286)
		(layer "F.Cu")
		(net "PVDDCR_CPU1_P0_VCC1")
	)
	(segment
		(start 331.37602 -336.628486)
		(end 331.728318 -336.628486)
		(width 0.2286)
		(layer "F.Cu")
		(net "PVDDCR_CPU1_P0_VCC1")
	)
	(segment
		(start 332.008226 -336.348578)
		(end 332.658974 -336.348578)
		(width 0.2286)
		(layer "F.Cu")
		(net "PVDDCR_CPU1_P0_VCC1")
	)
	(via
		(at 331.37602 -336.628486)
		(size 0.508)
		(drill 0.254)
		(layers "F.Cu" "B.Cu")
		(net "PVDDCR_CPU1_P0_VCC1")
	)
	(via
		(at 333.20355 -337.742784)
		(size 0.6604)
		(drill 0.3302)
		(layers "F.Cu" "B.Cu")
		(net "PVDDCR_CPU1_P0_VCC1")
	)
	(via
		(at 334.793336 -338.661248)
		(size 0.508)
		(drill 0.254)
		(layers "F.Cu" "B.Cu")
		(net "PVDDCR_CPU1_P0_VCC1")
	)
	(segment
		(start 332.04277 -336.628486)
		(end 332.23835 -336.432906)
		(width 0.381)
		(layer "B.Cu")
		(net "PVDDCR_CPU1_P0_VCC1")
	)
	(segment
		(start 334.793336 -338.661248)
		(end 334.293972 -338.161884)
		(width 0.4572)
		(layer "B.Cu")
		(net "PVDDCR_CPU1_P0_VCC1")
	)
	(segment
		(start 334.293972 -338.161884)
		(end 333.516986 -338.161884)
		(width 0.4572)
		(layer "B.Cu")
		(net "PVDDCR_CPU1_P0_VCC1")
	)
	(segment
		(start 331.37602 -336.628486)
		(end 332.04277 -336.628486)
		(width 0.381)
		(layer "B.Cu")
		(net "PVDDCR_CPU1_P0_VCC1")
	)
	(segment
		(start 333.516986 -338.161884)
		(end 333.20355 -337.848448)
		(width 0.4572)
		(layer "B.Cu")
		(net "PVDDCR_CPU1_P0_VCC1")
	)
	(segment
		(start 332.23835 -336.432906)
		(end 332.748128 -336.432906)
		(width 0.381)
		(layer "B.Cu")
		(net "PVDDCR_CPU1_P0_VCC1")
	)
	(segment
		(start 332.748128 -337.287362)
		(end 332.748128 -336.432906)
		(width 0.381)
		(layer "B.Cu")
		(net "PVDDCR_CPU1_P0_VCC1")
	)
	(segment
		(start 333.20355 -337.848448)
		(end 333.20355 -337.742784)
		(width 0.381)
		(layer "B.Cu")
		(net "PVDDCR_CPU1_P0_VCC1")
	)
	(segment
		(start 333.20355 -337.742784)
		(end 332.748128 -337.287362)
		(width 0.381)
		(layer "B.Cu")
		(net "PVDDCR_CPU1_P0_VCC1")
	)
	(segment
		(start 313.458098 -362.480098)
		(end 313.009026 -362.480098)
		(width 0.1778)
		(layer "F.Cu")
		(net "PVDDCR_CPU1_P0_VCC")
	)
	(segment
		(start 316.23 -364.21695)
		(end 317.246 -364.21695)
		(width 0.254)
		(layer "F.Cu")
		(net "PVDDCR_CPU1_P0_VCC")
	)
	(segment
		(start 315.19495 -364.21695)
		(end 314.198 -363.22)
		(width 0.254)
		(layer "F.Cu")
		(net "PVDDCR_CPU1_P0_VCC")
	)
	(segment
		(start 316.23 -364.21695)
		(end 315.19495 -364.21695)
		(width 0.254)
		(layer "F.Cu")
		(net "PVDDCR_CPU1_P0_VCC")
	)
	(segment
		(start 314.198 -363.22)
		(end 313.458098 -362.480098)
		(width 0.1778)
		(layer "F.Cu")
		(net "PVDDCR_CPU1_P0_VCC")
	)
	(segment
		(start 317.246 -364.21695)
		(end 318.262 -364.21695)
		(width 0.254)
		(layer "F.Cu")
		(net "PVDDCR_CPU1_P0_VCC")
	)
	(segment
		(start 317.384684 -338.641944)
		(end 317.70574 -338.320888)
		(width 0.2286)
		(layer "F.Cu")
		(net "PVDDCR_CPU1_P0_TEMP0")
	)
	(segment
		(start 342.429084 -338.95792)
		(end 342.429084 -338.671154)
		(width 0.2286)
		(layer "F.Cu")
		(net "PVDDCR_CPU1_P0_TEMP0")
	)
	(segment
		(start 317.384684 -338.92871)
		(end 317.384684 -338.641944)
		(width 0.2286)
		(layer "F.Cu")
		(net "PVDDCR_CPU1_P0_TEMP0")
	)
	(segment
		(start 342.75014 -338.350098)
		(end 342.75014 -337.924394)
		(width 0.2286)
		(layer "F.Cu")
		(net "PVDDCR_CPU1_P0_TEMP0")
	)
	(segment
		(start 308.056026 -350.041972)
		(end 308.056026 -349.616268)
		(width 0.2286)
		(layer "F.Cu")
		(net "PVDDCR_CPU1_P0_TEMP0")
	)
	(segment
		(start 307.73497 -350.649794)
		(end 307.73497 -350.363028)
		(width 0.2286)
		(layer "F.Cu")
		(net "PVDDCR_CPU1_P0_TEMP0")
	)
	(segment
		(start 325.740268 -338.921598)
		(end 325.740268 -338.634832)
		(width 0.2286)
		(layer "F.Cu")
		(net "PVDDCR_CPU1_P0_TEMP0")
	)
	(segment
		(start 315.413136 -361.279948)
		(end 314.637674 -361.279948)
		(width 0.1778)
		(layer "F.Cu")
		(net "PVDDCR_CPU1_P0_TEMP0")
	)
	(segment
		(start 350.704912 -343.581228)
		(end 351.025968 -343.260172)
		(width 0.2286)
		(layer "F.Cu")
		(net "PVDDCR_CPU1_P0_TEMP0")
	)
	(segment
		(start 334.097884 -338.90712)
		(end 334.097884 -338.620354)
		(width 0.2286)
		(layer "F.Cu")
		(net "PVDDCR_CPU1_P0_TEMP0")
	)
	(segment
		(start 325.740268 -338.634832)
		(end 326.061324 -338.313776)
		(width 0.2286)
		(layer "F.Cu")
		(net "PVDDCR_CPU1_P0_TEMP0")
	)
	(segment
		(start 334.41894 -338.299298)
		(end 334.41894 -337.873594)
		(width 0.2286)
		(layer "F.Cu")
		(net "PVDDCR_CPU1_P0_TEMP0")
	)
	(segment
		(start 334.097884 -338.620354)
		(end 334.41894 -338.299298)
		(width 0.2286)
		(layer "F.Cu")
		(net "PVDDCR_CPU1_P0_TEMP0")
	)
	(segment
		(start 307.73497 -350.363028)
		(end 308.056026 -350.041972)
		(width 0.2286)
		(layer "F.Cu")
		(net "PVDDCR_CPU1_P0_TEMP0")
	)
	(segment
		(start 317.70574 -338.320888)
		(end 317.70574 -337.895184)
		(width 0.2286)
		(layer "F.Cu")
		(net "PVDDCR_CPU1_P0_TEMP0")
	)
	(segment
		(start 314.637674 -361.279948)
		(end 313.009026 -361.279948)
		(width 0.1778)
		(layer "F.Cu")
		(net "PVDDCR_CPU1_P0_TEMP0")
	)
	(segment
		(start 351.025968 -343.260172)
		(end 351.025968 -342.834468)
		(width 0.2286)
		(layer "F.Cu")
		(net "PVDDCR_CPU1_P0_TEMP0")
	)
	(segment
		(start 350.704912 -343.867994)
		(end 350.704912 -343.581228)
		(width 0.2286)
		(layer "F.Cu")
		(net "PVDDCR_CPU1_P0_TEMP0")
	)
	(segment
		(start 342.429084 -338.671154)
		(end 342.75014 -338.350098)
		(width 0.2286)
		(layer "F.Cu")
		(net "PVDDCR_CPU1_P0_TEMP0")
	)
	(segment
		(start 326.061324 -338.313776)
		(end 326.061324 -337.888072)
		(width 0.2286)
		(layer "F.Cu")
		(net "PVDDCR_CPU1_P0_TEMP0")
	)
	(via
		(at 317.384684 -338.92871)
		(size 0.508)
		(drill 0.254)
		(layers "F.Cu" "B.Cu")
		(net "PVDDCR_CPU1_P0_TEMP0")
	)
	(via
		(at 314.637674 -361.279948)
		(size 0.508)
		(drill 0.254)
		(layers "F.Cu" "B.Cu")
		(net "PVDDCR_CPU1_P0_TEMP0")
	)
	(via
		(at 334.097884 -338.90712)
		(size 0.508)
		(drill 0.254)
		(layers "F.Cu" "B.Cu")
		(net "PVDDCR_CPU1_P0_TEMP0")
	)
	(via
		(at 325.740268 -338.921598)
		(size 0.508)
		(drill 0.254)
		(layers "F.Cu" "B.Cu")
		(net "PVDDCR_CPU1_P0_TEMP0")
	)
	(via
		(at 307.73497 -350.649794)
		(size 0.508)
		(drill 0.254)
		(layers "F.Cu" "B.Cu")
		(net "PVDDCR_CPU1_P0_TEMP0")
	)
	(via
		(at 342.429084 -338.95792)
		(size 0.508)
		(drill 0.254)
		(layers "F.Cu" "B.Cu")
		(net "PVDDCR_CPU1_P0_TEMP0")
	)
	(via
		(at 350.704912 -343.867994)
		(size 0.508)
		(drill 0.254)
		(layers "F.Cu" "B.Cu")
		(net "PVDDCR_CPU1_P0_TEMP0")
	)
	(segment
		(start 326.31126 -341.06231)
		(end 333.42326 -341.06231)
		(width 0.254)
		(layer "In2.Cu")
		(net "PVDDCR_CPU1_P0_TEMP0")
	)
	(segment
		(start 349.80626 -346.14231)
		(end 350.56826 -345.38031)
		(width 0.254)
		(layer "In2.Cu")
		(net "PVDDCR_CPU1_P0_TEMP0")
	)
	(segment
		(start 308.6862 -352.3742)
		(end 309.499 -351.5614)
		(width 0.254)
		(layer "In2.Cu")
		(net "PVDDCR_CPU1_P0_TEMP0")
	)
	(segment
		(start 313.063128 -357.4288)
		(end 315.367924 -359.733596)
		(width 0.254)
		(layer "In2.Cu")
		(net "PVDDCR_CPU1_P0_TEMP0")
	)
	(segment
		(start 306.3748 -353.24923)
		(end 306.3748 -354.9904)
		(width 0.254)
		(layer "In2.Cu")
		(net "PVDDCR_CPU1_P0_TEMP0")
	)
	(segment
		(start 350.56826 -344.004646)
		(end 350.704912 -343.867994)
		(width 0.254)
		(layer "In2.Cu")
		(net "PVDDCR_CPU1_P0_TEMP0")
	)
	(segment
		(start 334.772508 -341.06231)
		(end 341.93226 -341.06231)
		(width 0.254)
		(layer "In2.Cu")
		(net "PVDDCR_CPU1_P0_TEMP0")
	)
	(segment
		(start 325.19493 -341.03564)
		(end 321.452494 -341.03564)
		(width 0.254)
		(layer "In2.Cu")
		(net "PVDDCR_CPU1_P0_TEMP0")
	)
	(segment
		(start 325.740268 -338.921598)
		(end 325.740268 -340.490302)
		(width 0.254)
		(layer "In2.Cu")
		(net "PVDDCR_CPU1_P0_TEMP0")
	)
	(segment
		(start 314.637674 -361.219496)
		(end 314.637674 -361.279948)
		(width 0.254)
		(layer "In2.Cu")
		(net "PVDDCR_CPU1_P0_TEMP0")
	)
	(segment
		(start 308.8132 -357.4288)
		(end 313.063128 -357.4288)
		(width 0.254)
		(layer "In2.Cu")
		(net "PVDDCR_CPU1_P0_TEMP0")
	)
	(segment
		(start 309.499 -351.5614)
		(end 313.334146 -351.5614)
		(width 0.254)
		(layer "In2.Cu")
		(net "PVDDCR_CPU1_P0_TEMP0")
	)
	(segment
		(start 313.334146 -351.5614)
		(end 314.238894 -350.656652)
		(width 0.254)
		(layer "In2.Cu")
		(net "PVDDCR_CPU1_P0_TEMP0")
	)
	(segment
		(start 317.940182 -340.819232)
		(end 317.384684 -340.263734)
		(width 0.254)
		(layer "In2.Cu")
		(net "PVDDCR_CPU1_P0_TEMP0")
	)
	(segment
		(start 350.56826 -345.38031)
		(end 350.56826 -344.004646)
		(width 0.254)
		(layer "In2.Cu")
		(net "PVDDCR_CPU1_P0_TEMP0")
	)
	(segment
		(start 308.22011 -352.3742)
		(end 308.6862 -352.3742)
		(width 0.254)
		(layer "In2.Cu")
		(net "PVDDCR_CPU1_P0_TEMP0")
	)
	(segment
		(start 307.73497 -351.88906)
		(end 306.3748 -353.24923)
		(width 0.254)
		(layer "In2.Cu")
		(net "PVDDCR_CPU1_P0_TEMP0")
	)
	(segment
		(start 345.36126 -344.87231)
		(end 346.63126 -346.14231)
		(width 0.254)
		(layer "In2.Cu")
		(net "PVDDCR_CPU1_P0_TEMP0")
	)
	(segment
		(start 325.740268 -340.490302)
		(end 325.740268 -340.491318)
		(width 0.254)
		(layer "In2.Cu")
		(net "PVDDCR_CPU1_P0_TEMP0")
	)
	(segment
		(start 333.42326 -341.06231)
		(end 334.097884 -340.387686)
		(width 0.254)
		(layer "In2.Cu")
		(net "PVDDCR_CPU1_P0_TEMP0")
	)
	(segment
		(start 317.072518 -340.5759)
		(end 317.384684 -340.263734)
		(width 0.254)
		(layer "In2.Cu")
		(net "PVDDCR_CPU1_P0_TEMP0")
	)
	(segment
		(start 325.740268 -340.491318)
		(end 326.31126 -341.06231)
		(width 0.254)
		(layer "In2.Cu")
		(net "PVDDCR_CPU1_P0_TEMP0")
	)
	(segment
		(start 345.36126 -343.47531)
		(end 345.36126 -344.87231)
		(width 0.254)
		(layer "In2.Cu")
		(net "PVDDCR_CPU1_P0_TEMP0")
	)
	(segment
		(start 342.429084 -338.95792)
		(end 342.429084 -340.543134)
		(width 0.254)
		(layer "In2.Cu")
		(net "PVDDCR_CPU1_P0_TEMP0")
	)
	(segment
		(start 341.93226 -341.06231)
		(end 342.44026 -340.55431)
		(width 0.254)
		(layer "In2.Cu")
		(net "PVDDCR_CPU1_P0_TEMP0")
	)
	(segment
		(start 307.73497 -351.88906)
		(end 308.22011 -352.3742)
		(width 0.254)
		(layer "In2.Cu")
		(net "PVDDCR_CPU1_P0_TEMP0")
	)
	(segment
		(start 315.367924 -359.733596)
		(end 315.367924 -360.489246)
		(width 0.254)
		(layer "In2.Cu")
		(net "PVDDCR_CPU1_P0_TEMP0")
	)
	(segment
		(start 315.367924 -360.489246)
		(end 314.637674 -361.219496)
		(width 0.254)
		(layer "In2.Cu")
		(net "PVDDCR_CPU1_P0_TEMP0")
	)
	(segment
		(start 334.097884 -340.387686)
		(end 334.772508 -341.06231)
		(width 0.254)
		(layer "In2.Cu")
		(net "PVDDCR_CPU1_P0_TEMP0")
	)
	(segment
		(start 314.238894 -342.763602)
		(end 316.426596 -340.5759)
		(width 0.254)
		(layer "In2.Cu")
		(net "PVDDCR_CPU1_P0_TEMP0")
	)
	(segment
		(start 321.452494 -341.03564)
		(end 320.923666 -340.506812)
		(width 0.254)
		(layer "In2.Cu")
		(net "PVDDCR_CPU1_P0_TEMP0")
	)
	(segment
		(start 334.097884 -338.90712)
		(end 334.097884 -340.387686)
		(width 0.254)
		(layer "In2.Cu")
		(net "PVDDCR_CPU1_P0_TEMP0")
	)
	(segment
		(start 316.426596 -340.5759)
		(end 317.072518 -340.5759)
		(width 0.254)
		(layer "In2.Cu")
		(net "PVDDCR_CPU1_P0_TEMP0")
	)
	(segment
		(start 314.238894 -350.656652)
		(end 314.238894 -342.763602)
		(width 0.254)
		(layer "In2.Cu")
		(net "PVDDCR_CPU1_P0_TEMP0")
	)
	(segment
		(start 342.44026 -340.55431)
		(end 345.36126 -343.47531)
		(width 0.254)
		(layer "In2.Cu")
		(net "PVDDCR_CPU1_P0_TEMP0")
	)
	(segment
		(start 307.73497 -351.88906)
		(end 307.73497 -350.649794)
		(width 0.254)
		(layer "In2.Cu")
		(net "PVDDCR_CPU1_P0_TEMP0")
	)
	(segment
		(start 320.923666 -340.506812)
		(end 318.967358 -340.506812)
		(width 0.254)
		(layer "In2.Cu")
		(net "PVDDCR_CPU1_P0_TEMP0")
	)
	(segment
		(start 318.654938 -340.819232)
		(end 317.940182 -340.819232)
		(width 0.254)
		(layer "In2.Cu")
		(net "PVDDCR_CPU1_P0_TEMP0")
	)
	(segment
		(start 317.384684 -340.263734)
		(end 317.384684 -338.92871)
		(width 0.254)
		(layer "In2.Cu")
		(net "PVDDCR_CPU1_P0_TEMP0")
	)
	(segment
		(start 318.967358 -340.506812)
		(end 318.654938 -340.819232)
		(width 0.254)
		(layer "In2.Cu")
		(net "PVDDCR_CPU1_P0_TEMP0")
	)
	(segment
		(start 342.429084 -340.543134)
		(end 342.44026 -340.55431)
		(width 0.254)
		(layer "In2.Cu")
		(net "PVDDCR_CPU1_P0_TEMP0")
	)
	(segment
		(start 306.3748 -354.9904)
		(end 308.8132 -357.4288)
		(width 0.254)
		(layer "In2.Cu")
		(net "PVDDCR_CPU1_P0_TEMP0")
	)
	(segment
		(start 346.63126 -346.14231)
		(end 349.80626 -346.14231)
		(width 0.254)
		(layer "In2.Cu")
		(net "PVDDCR_CPU1_P0_TEMP0")
	)
	(segment
		(start 325.740268 -340.490302)
		(end 325.19493 -341.03564)
		(width 0.254)
		(layer "In2.Cu")
		(net "PVDDCR_CPU1_P0_TEMP0")
	)
	(segment
		(start 305.994054 -364.703106)
		(end 305.994054 -363.319568)
		(width 0.10668)
		(layer "F.Cu")
		(net "PVDDCR_CPU1_P0_SMB_ALERT_R")
	)
	(segment
		(start 304.81905 -365.125)
		(end 305.57216 -365.125)
		(width 0.10668)
		(layer "F.Cu")
		(net "PVDDCR_CPU1_P0_SMB_ALERT_R")
	)
	(segment
		(start 306.778152 -362.080048)
		(end 307.258974 -362.080048)
		(width 0.10668)
		(layer "F.Cu")
		(net "PVDDCR_CPU1_P0_SMB_ALERT_R")
	)
	(segment
		(start 306.315872 -362.542328)
		(end 306.778152 -362.080048)
		(width 0.10668)
		(layer "F.Cu")
		(net "PVDDCR_CPU1_P0_SMB_ALERT_R")
	)
	(segment
		(start 305.994054 -363.319568)
		(end 306.315872 -362.542328)
		(width 0.10668)
		(layer "F.Cu")
		(net "PVDDCR_CPU1_P0_SMB_ALERT_R")
	)
	(segment
		(start 305.57216 -365.125)
		(end 305.994054 -364.703106)
		(width 0.10668)
		(layer "F.Cu")
		(net "PVDDCR_CPU1_P0_SMB_ALERT_R")
	)
	(via
		(at 305.57216 -365.125)
		(size 0.508)
		(drill 0.254)
		(layers "F.Cu" "B.Cu")
		(net "PVDDCR_CPU1_P0_SMB_ALERT_R")
	)
	(segment
		(start 302.53305 -365.125)
		(end 303.276 -365.125)
		(width 0.10668)
		(layer "F.Cu")
		(net "PVDDCR_CPU1_P0_SMB_ALERT")
	)
	(segment
		(start 185.122058 -109.852968)
		(end 184.732168 -109.463078)
		(width 0.10668)
		(layer "F.Cu")
		(net "PVDDCR_CPU1_P0_SMB_ALERT")
	)
	(segment
		(start 304.01895 -365.125)
		(end 303.276 -365.125)
		(width 0.10668)
		(layer "F.Cu")
		(net "PVDDCR_CPU1_P0_SMB_ALERT")
	)
	(via
		(at 303.276 -365.125)
		(size 0.508)
		(drill 0.254)
		(layers "F.Cu" "B.Cu")
		(net "PVDDCR_CPU1_P0_SMB_ALERT")
	)
	(via
		(at 184.732168 -109.463078)
		(size 0.4572)
		(drill 0.254)
		(layers "F.Cu" "B.Cu")
		(net "PVDDCR_CPU1_P0_SMB_ALERT")
	)
	(via
		(at 185.007758 -102.191058)
		(size 0.6604)
		(drill 0.3302)
		(layers "F.Cu" "B.Cu")
		(net "PVDDCR_CPU1_P0_SMB_ALERT")
	)
	(via
		(at 384.026918 -122.905012)
		(size 0.508)
		(drill 0.254)
		(layers "F.Cu" "B.Cu")
		(net "PVDDCR_CPU1_P0_SMB_ALERT")
	)
	(via
		(at 327.0504 -362.6104)
		(size 0.508)
		(drill 0.254)
		(layers "F.Cu" "B.Cu")
		(net "PVDDCR_CPU1_P0_SMB_ALERT")
	)
	(segment
		(start 185.007758 -102.074726)
		(end 185.007758 -102.191058)
		(width 0.10668)
		(layer "B.Cu")
		(net "PVDDCR_CPU1_P0_SMB_ALERT")
	)
	(segment
		(start 415.007298 -329.635104)
		(end 416.86353 -327.778872)
		(width 0.10668)
		(layer "B.Cu")
		(net "PVDDCR_CPU1_P0_SMB_ALERT")
	)
	(segment
		(start 434.662834 -156.071824)
		(end 434.662834 -140.070586)
		(width 0.10668)
		(layer "B.Cu")
		(net "PVDDCR_CPU1_P0_SMB_ALERT")
	)
	(segment
		(start 184.823608 -102.462584)
		(end 184.823608 -105.71099)
		(width 0.10668)
		(layer "B.Cu")
		(net "PVDDCR_CPU1_P0_SMB_ALERT")
	)
	(segment
		(start 416.86353 -327.778872)
		(end 453.306434 -327.778872)
		(width 0.10668)
		(layer "B.Cu")
		(net "PVDDCR_CPU1_P0_SMB_ALERT")
	)
	(segment
		(start 185.175398 -109.019848)
		(end 184.732168 -109.463078)
		(width 0.10668)
		(layer "B.Cu")
		(net "PVDDCR_CPU1_P0_SMB_ALERT")
	)
	(segment
		(start 327.0504 -362.6104)
		(end 327.866248 -362.6104)
		(width 0.10668)
		(layer "B.Cu")
		(net "PVDDCR_CPU1_P0_SMB_ALERT")
	)
	(segment
		(start 415.007298 -337.004152)
		(end 415.007298 -329.635104)
		(width 0.10668)
		(layer "B.Cu")
		(net "PVDDCR_CPU1_P0_SMB_ALERT")
	)
	(segment
		(start 185.007758 -102.287578)
		(end 184.959752 -102.335584)
		(width 0.10668)
		(layer "B.Cu")
		(net "PVDDCR_CPU1_P0_SMB_ALERT")
	)
	(segment
		(start 401.340574 -358.964484)
		(end 406.857454 -358.964484)
		(width 0.10668)
		(layer "B.Cu")
		(net "PVDDCR_CPU1_P0_SMB_ALERT")
	)
	(segment
		(start 327.866248 -362.6104)
		(end 329.868022 -364.612174)
		(width 0.10668)
		(layer "B.Cu")
		(net "PVDDCR_CPU1_P0_SMB_ALERT")
	)
	(segment
		(start 408.413966 -357.407972)
		(end 408.413966 -343.597484)
		(width 0.10668)
		(layer "B.Cu")
		(net "PVDDCR_CPU1_P0_SMB_ALERT")
	)
	(segment
		(start 434.662834 -140.070586)
		(end 416.99434 -122.402092)
		(width 0.10668)
		(layer "B.Cu")
		(net "PVDDCR_CPU1_P0_SMB_ALERT")
	)
	(segment
		(start 416.99434 -122.402092)
		(end 384.529838 -122.402092)
		(width 0.10668)
		(layer "B.Cu")
		(net "PVDDCR_CPU1_P0_SMB_ALERT")
	)
	(segment
		(start 458.41539 -188.290454)
		(end 447.453004 -177.328068)
		(width 0.10668)
		(layer "B.Cu")
		(net "PVDDCR_CPU1_P0_SMB_ALERT")
	)
	(segment
		(start 447.453004 -177.328068)
		(end 447.453004 -166.033196)
		(width 0.10668)
		(layer "B.Cu")
		(net "PVDDCR_CPU1_P0_SMB_ALERT")
	)
	(segment
		(start 184.959752 -102.335584)
		(end 184.950608 -102.335584)
		(width 0.10668)
		(layer "B.Cu")
		(net "PVDDCR_CPU1_P0_SMB_ALERT")
	)
	(segment
		(start 453.306434 -327.778872)
		(end 453.515476 -327.56983)
		(width 0.10668)
		(layer "B.Cu")
		(net "PVDDCR_CPU1_P0_SMB_ALERT")
	)
	(segment
		(start 395.692884 -364.612174)
		(end 401.340574 -358.964484)
		(width 0.10668)
		(layer "B.Cu")
		(net "PVDDCR_CPU1_P0_SMB_ALERT")
	)
	(segment
		(start 406.857454 -358.964484)
		(end 408.413966 -357.407972)
		(width 0.10668)
		(layer "B.Cu")
		(net "PVDDCR_CPU1_P0_SMB_ALERT")
	)
	(segment
		(start 443.288928 -161.86912)
		(end 440.46013 -161.86912)
		(width 0.10668)
		(layer "B.Cu")
		(net "PVDDCR_CPU1_P0_SMB_ALERT")
	)
	(segment
		(start 447.453004 -166.033196)
		(end 443.288928 -161.86912)
		(width 0.10668)
		(layer "B.Cu")
		(net "PVDDCR_CPU1_P0_SMB_ALERT")
	)
	(segment
		(start 454.32472 -327.56983)
		(end 458.41539 -323.47916)
		(width 0.10668)
		(layer "B.Cu")
		(net "PVDDCR_CPU1_P0_SMB_ALERT")
	)
	(segment
		(start 458.41539 -323.47916)
		(end 458.41539 -188.290454)
		(width 0.10668)
		(layer "B.Cu")
		(net "PVDDCR_CPU1_P0_SMB_ALERT")
	)
	(segment
		(start 384.529838 -122.402092)
		(end 384.026918 -122.905012)
		(width 0.10668)
		(layer "B.Cu")
		(net "PVDDCR_CPU1_P0_SMB_ALERT")
	)
	(segment
		(start 184.785 -100.694998)
		(end 184.785 -101.851968)
		(width 0.10668)
		(layer "B.Cu")
		(net "PVDDCR_CPU1_P0_SMB_ALERT")
	)
	(segment
		(start 329.868022 -364.612174)
		(end 395.692884 -364.612174)
		(width 0.10668)
		(layer "B.Cu")
		(net "PVDDCR_CPU1_P0_SMB_ALERT")
	)
	(segment
		(start 184.823608 -105.71099)
		(end 185.175398 -106.06278)
		(width 0.10668)
		(layer "B.Cu")
		(net "PVDDCR_CPU1_P0_SMB_ALERT")
	)
	(segment
		(start 453.515476 -327.56983)
		(end 454.32472 -327.56983)
		(width 0.10668)
		(layer "B.Cu")
		(net "PVDDCR_CPU1_P0_SMB_ALERT")
	)
	(segment
		(start 185.007758 -102.191058)
		(end 185.007758 -102.287578)
		(width 0.10668)
		(layer "B.Cu")
		(net "PVDDCR_CPU1_P0_SMB_ALERT")
	)
	(segment
		(start 184.785 -101.851968)
		(end 185.007758 -102.074726)
		(width 0.10668)
		(layer "B.Cu")
		(net "PVDDCR_CPU1_P0_SMB_ALERT")
	)
	(segment
		(start 408.413966 -343.597484)
		(end 415.007298 -337.004152)
		(width 0.10668)
		(layer "B.Cu")
		(net "PVDDCR_CPU1_P0_SMB_ALERT")
	)
	(segment
		(start 185.175398 -106.06278)
		(end 185.175398 -109.019848)
		(width 0.10668)
		(layer "B.Cu")
		(net "PVDDCR_CPU1_P0_SMB_ALERT")
	)
	(segment
		(start 184.950608 -102.335584)
		(end 184.823608 -102.462584)
		(width 0.10668)
		(layer "B.Cu")
		(net "PVDDCR_CPU1_P0_SMB_ALERT")
	)
	(segment
		(start 440.46013 -161.86912)
		(end 434.662834 -156.071824)
		(width 0.10668)
		(layer "B.Cu")
		(net "PVDDCR_CPU1_P0_SMB_ALERT")
	)
	(segment
		(start 254.044196 -101.163882)
		(end 255.468882 -99.739196)
		(width 0.11684)
		(layer "In6.Cu")
		(net "PVDDCR_CPU1_P0_SMB_ALERT")
	)
	(segment
		(start 210.400646 -101.1809)
		(end 213.308184 -101.1809)
		(width 0.11684)
		(layer "In6.Cu")
		(net "PVDDCR_CPU1_P0_SMB_ALERT")
	)
	(segment
		(start 273.177762 -97.93351)
		(end 273.304 -98.059748)
		(width 0.11684)
		(layer "In6.Cu")
		(net "PVDDCR_CPU1_P0_SMB_ALERT")
	)
	(segment
		(start 192.054734 -102.700328)
		(end 195.784216 -102.700328)
		(width 0.11684)
		(layer "In6.Cu")
		(net "PVDDCR_CPU1_P0_SMB_ALERT")
	)
	(segment
		(start 185.266838 -108.928408)
		(end 185.266838 -106.233976)
		(width 0.11684)
		(layer "In6.Cu")
		(net "PVDDCR_CPU1_P0_SMB_ALERT")
	)
	(segment
		(start 255.468882 -99.739196)
		(end 257.63347 -99.739196)
		(width 0.11684)
		(layer "In6.Cu")
		(net "PVDDCR_CPU1_P0_SMB_ALERT")
	)
	(segment
		(start 189.904878 -104.850184)
		(end 192.054734 -102.700328)
		(width 0.11684)
		(layer "In6.Cu")
		(net "PVDDCR_CPU1_P0_SMB_ALERT")
	)
	(segment
		(start 221.291404 -101.163882)
		(end 254.044196 -101.163882)
		(width 0.11684)
		(layer "In6.Cu")
		(net "PVDDCR_CPU1_P0_SMB_ALERT")
	)
	(segment
		(start 184.732168 -109.463078)
		(end 185.266838 -108.928408)
		(width 0.11684)
		(layer "In6.Cu")
		(net "PVDDCR_CPU1_P0_SMB_ALERT")
	)
	(segment
		(start 273.304 -98.059748)
		(end 278.958802 -98.059748)
		(width 0.11684)
		(layer "In6.Cu")
		(net "PVDDCR_CPU1_P0_SMB_ALERT")
	)
	(segment
		(start 213.308184 -101.1809)
		(end 213.61273 -100.876354)
		(width 0.11684)
		(layer "In6.Cu")
		(net "PVDDCR_CPU1_P0_SMB_ALERT")
	)
	(segment
		(start 270.65986 -97.93351)
		(end 273.177762 -97.93351)
		(width 0.11684)
		(layer "In6.Cu")
		(net "PVDDCR_CPU1_P0_SMB_ALERT")
	)
	(segment
		(start 324.506844 -109.773212)
		(end 374.472708 -109.773212)
		(width 0.11684)
		(layer "In6.Cu")
		(net "PVDDCR_CPU1_P0_SMB_ALERT")
	)
	(segment
		(start 280.965402 -100.066348)
		(end 313.23407 -100.066348)
		(width 0.11684)
		(layer "In6.Cu")
		(net "PVDDCR_CPU1_P0_SMB_ALERT")
	)
	(segment
		(start 321.239388 -108.071666)
		(end 322.805298 -108.071666)
		(width 0.11684)
		(layer "In6.Cu")
		(net "PVDDCR_CPU1_P0_SMB_ALERT")
	)
	(segment
		(start 185.266838 -106.233976)
		(end 186.65063 -104.850184)
		(width 0.11684)
		(layer "In6.Cu")
		(net "PVDDCR_CPU1_P0_SMB_ALERT")
	)
	(segment
		(start 213.61273 -100.876354)
		(end 214.643716 -100.876354)
		(width 0.11684)
		(layer "In6.Cu")
		(net "PVDDCR_CPU1_P0_SMB_ALERT")
	)
	(segment
		(start 195.784216 -102.700328)
		(end 196.842634 -101.64191)
		(width 0.11684)
		(layer "In6.Cu")
		(net "PVDDCR_CPU1_P0_SMB_ALERT")
	)
	(segment
		(start 209.939636 -101.64191)
		(end 210.400646 -101.1809)
		(width 0.11684)
		(layer "In6.Cu")
		(net "PVDDCR_CPU1_P0_SMB_ALERT")
	)
	(segment
		(start 322.805298 -108.071666)
		(end 324.506844 -109.773212)
		(width 0.11684)
		(layer "In6.Cu")
		(net "PVDDCR_CPU1_P0_SMB_ALERT")
	)
	(segment
		(start 313.23407 -100.066348)
		(end 321.239388 -108.071666)
		(width 0.11684)
		(layer "In6.Cu")
		(net "PVDDCR_CPU1_P0_SMB_ALERT")
	)
	(segment
		(start 257.63347 -99.739196)
		(end 260.964934 -96.407732)
		(width 0.11684)
		(layer "In6.Cu")
		(net "PVDDCR_CPU1_P0_SMB_ALERT")
	)
	(segment
		(start 269.134082 -96.407732)
		(end 270.65986 -97.93351)
		(width 0.11684)
		(layer "In6.Cu")
		(net "PVDDCR_CPU1_P0_SMB_ALERT")
	)
	(segment
		(start 196.842634 -101.64191)
		(end 209.939636 -101.64191)
		(width 0.11684)
		(layer "In6.Cu")
		(net "PVDDCR_CPU1_P0_SMB_ALERT")
	)
	(segment
		(start 186.65063 -104.850184)
		(end 189.904878 -104.850184)
		(width 0.11684)
		(layer "In6.Cu")
		(net "PVDDCR_CPU1_P0_SMB_ALERT")
	)
	(segment
		(start 220.46946 -100.341938)
		(end 221.291404 -101.163882)
		(width 0.11684)
		(layer "In6.Cu")
		(net "PVDDCR_CPU1_P0_SMB_ALERT")
	)
	(segment
		(start 214.643716 -100.876354)
		(end 215.178132 -100.341938)
		(width 0.11684)
		(layer "In6.Cu")
		(net "PVDDCR_CPU1_P0_SMB_ALERT")
	)
	(segment
		(start 278.958802 -98.059748)
		(end 280.965402 -100.066348)
		(width 0.11684)
		(layer "In6.Cu")
		(net "PVDDCR_CPU1_P0_SMB_ALERT")
	)
	(segment
		(start 384.026918 -119.327422)
		(end 384.026918 -122.905012)
		(width 0.11684)
		(layer "In6.Cu")
		(net "PVDDCR_CPU1_P0_SMB_ALERT")
	)
	(segment
		(start 374.472708 -109.773212)
		(end 384.026918 -119.327422)
		(width 0.11684)
		(layer "In6.Cu")
		(net "PVDDCR_CPU1_P0_SMB_ALERT")
	)
	(segment
		(start 260.964934 -96.407732)
		(end 269.134082 -96.407732)
		(width 0.11684)
		(layer "In6.Cu")
		(net "PVDDCR_CPU1_P0_SMB_ALERT")
	)
	(segment
		(start 215.178132 -100.341938)
		(end 220.46946 -100.341938)
		(width 0.11684)
		(layer "In6.Cu")
		(net "PVDDCR_CPU1_P0_SMB_ALERT")
	)
	(segment
		(start 327.0504 -362.6104)
		(end 323.9643 -362.6104)
		(width 0.11684)
		(layer "In13.Cu")
		(net "PVDDCR_CPU1_P0_SMB_ALERT")
	)
	(segment
		(start 313.305952 -365.6838)
		(end 311.4294 -365.6838)
		(width 0.11684)
		(layer "In13.Cu")
		(net "PVDDCR_CPU1_P0_SMB_ALERT")
	)
	(segment
		(start 313.471052 -365.8489)
		(end 313.305952 -365.6838)
		(width 0.11684)
		(layer "In13.Cu")
		(net "PVDDCR_CPU1_P0_SMB_ALERT")
	)
	(segment
		(start 304.4952 -366.3442)
		(end 303.276 -365.125)
		(width 0.11684)
		(layer "In13.Cu")
		(net "PVDDCR_CPU1_P0_SMB_ALERT")
	)
	(segment
		(start 320.7258 -365.8489)
		(end 313.471052 -365.8489)
		(width 0.11684)
		(layer "In13.Cu")
		(net "PVDDCR_CPU1_P0_SMB_ALERT")
	)
	(segment
		(start 311.4294 -365.6838)
		(end 310.769 -366.3442)
		(width 0.11684)
		(layer "In13.Cu")
		(net "PVDDCR_CPU1_P0_SMB_ALERT")
	)
	(segment
		(start 323.9643 -362.6104)
		(end 320.7258 -365.8489)
		(width 0.11684)
		(layer "In13.Cu")
		(net "PVDDCR_CPU1_P0_SMB_ALERT")
	)
	(segment
		(start 310.769 -366.3442)
		(end 304.4952 -366.3442)
		(width 0.11684)
		(layer "In13.Cu")
		(net "PVDDCR_CPU1_P0_SMB_ALERT")
	)
	(segment
		(start 305.198526 -361.696)
		(end 305.591718 -361.302808)
		(width 0.10668)
		(layer "F.Cu")
		(net "PVDDCR_CPU1_P0_RESET_N_R")
	)
	(segment
		(start 304.81905 -361.696)
		(end 305.198526 -361.696)
		(width 0.10668)
		(layer "F.Cu")
		(net "PVDDCR_CPU1_P0_RESET_N_R")
	)
	(segment
		(start 305.591718 -361.302808)
		(end 305.891184 -361.003342)
		(width 0.10668)
		(layer "F.Cu")
		(net "PVDDCR_CPU1_P0_RESET_N_R")
	)
	(segment
		(start 305.891184 -361.003342)
		(end 306.282598 -361.003342)
		(width 0.10668)
		(layer "F.Cu")
		(net "PVDDCR_CPU1_P0_RESET_N_R")
	)
	(segment
		(start 306.282598 -361.003342)
		(end 306.406042 -360.879898)
		(width 0.10668)
		(layer "F.Cu")
		(net "PVDDCR_CPU1_P0_RESET_N_R")
	)
	(segment
		(start 306.406042 -360.879898)
		(end 307.258974 -360.879898)
		(width 0.10668)
		(layer "F.Cu")
		(net "PVDDCR_CPU1_P0_RESET_N_R")
	)
	(via
		(at 305.591718 -361.302808)
		(size 0.508)
		(drill 0.254)
		(layers "F.Cu" "B.Cu")
		(net "PVDDCR_CPU1_P0_RESET_N_R")
	)
	(segment
		(start 304.81905 -360.53014)
		(end 305.591718 -361.302808)
		(width 0.10668)
		(layer "B.Cu")
		(net "PVDDCR_CPU1_P0_RESET_N_R")
	)
	(segment
		(start 304.81905 -360.426)
		(end 304.81905 -360.53014)
		(width 0.10668)
		(layer "B.Cu")
		(net "PVDDCR_CPU1_P0_RESET_N_R")
	)
	(segment
		(start 303.276 -361.696)
		(end 304.01895 -361.696)
		(width 0.10668)
		(layer "F.Cu")
		(net "PVDDCR_CPU1_P0_RESET_N")
	)
	(segment
		(start 394.151866 -134.797292)
		(end 394.151866 -138.733276)
		(width 0.10668)
		(layer "F.Cu")
		(net "PVDDCR_CPU1_P0_RESET_N")
	)
	(segment
		(start 394.151866 -138.733276)
		(end 392.489436 -140.395706)
		(width 0.10668)
		(layer "F.Cu")
		(net "PVDDCR_CPU1_P0_RESET_N")
	)
	(segment
		(start 392.489436 -140.395706)
		(end 392.489436 -141.02461)
		(width 0.10668)
		(layer "F.Cu")
		(net "PVDDCR_CPU1_P0_RESET_N")
	)
	(via
		(at 303.276 -361.696)
		(size 0.508)
		(drill 0.254)
		(layers "F.Cu" "B.Cu")
		(net "PVDDCR_CPU1_P0_RESET_N")
	)
	(via
		(at 394.151866 -134.797292)
		(size 0.508)
		(drill 0.254)
		(layers "F.Cu" "B.Cu")
		(net "PVDDCR_CPU1_P0_RESET_N")
	)
	(via
		(at 327.0504 -361.4674)
		(size 0.508)
		(drill 0.254)
		(layers "F.Cu" "B.Cu")
		(net "PVDDCR_CPU1_P0_RESET_N")
	)
	(segment
		(start 415.810192 -129.464562)
		(end 399.484596 -129.464562)
		(width 0.10668)
		(layer "B.Cu")
		(net "PVDDCR_CPU1_P0_RESET_N")
	)
	(segment
		(start 327.948544 -362.1786)
		(end 330.021438 -364.251494)
		(width 0.10668)
		(layer "B.Cu")
		(net "PVDDCR_CPU1_P0_RESET_N")
	)
	(segment
		(start 414.437576 -329.398884)
		(end 416.62731 -327.20915)
		(width 0.10668)
		(layer "B.Cu")
		(net "PVDDCR_CPU1_P0_RESET_N")
	)
	(segment
		(start 440.308492 -162.2298)
		(end 434.057044 -155.978352)
		(width 0.10668)
		(layer "B.Cu")
		(net "PVDDCR_CPU1_P0_RESET_N")
	)
	(segment
		(start 416.62731 -327.20915)
		(end 454.175114 -327.20915)
		(width 0.10668)
		(layer "B.Cu")
		(net "PVDDCR_CPU1_P0_RESET_N")
	)
	(segment
		(start 443.139322 -162.2298)
		(end 440.308492 -162.2298)
		(width 0.10668)
		(layer "B.Cu")
		(net "PVDDCR_CPU1_P0_RESET_N")
	)
	(segment
		(start 407.844244 -343.361264)
		(end 414.437576 -336.767932)
		(width 0.10668)
		(layer "B.Cu")
		(net "PVDDCR_CPU1_P0_RESET_N")
	)
	(segment
		(start 434.057044 -155.978352)
		(end 434.057044 -147.711414)
		(width 0.10668)
		(layer "B.Cu")
		(net "PVDDCR_CPU1_P0_RESET_N")
	)
	(segment
		(start 327.0504 -361.4674)
		(end 327.7616 -362.1786)
		(width 0.10668)
		(layer "B.Cu")
		(net "PVDDCR_CPU1_P0_RESET_N")
	)
	(segment
		(start 447.092324 -166.182802)
		(end 443.139322 -162.2298)
		(width 0.10668)
		(layer "B.Cu")
		(net "PVDDCR_CPU1_P0_RESET_N")
	)
	(segment
		(start 401.115022 -358.332532)
		(end 406.683464 -358.332532)
		(width 0.10668)
		(layer "B.Cu")
		(net "PVDDCR_CPU1_P0_RESET_N")
	)
	(segment
		(start 330.021438 -364.251494)
		(end 395.19606 -364.251494)
		(width 0.10668)
		(layer "B.Cu")
		(net "PVDDCR_CPU1_P0_RESET_N")
	)
	(segment
		(start 399.484596 -129.464562)
		(end 394.151866 -134.797292)
		(width 0.10668)
		(layer "B.Cu")
		(net "PVDDCR_CPU1_P0_RESET_N")
	)
	(segment
		(start 447.092324 -177.477674)
		(end 447.092324 -166.182802)
		(width 0.10668)
		(layer "B.Cu")
		(net "PVDDCR_CPU1_P0_RESET_N")
	)
	(segment
		(start 434.057044 -147.711414)
		(end 415.810192 -129.464562)
		(width 0.10668)
		(layer "B.Cu")
		(net "PVDDCR_CPU1_P0_RESET_N")
	)
	(segment
		(start 458.05471 -323.329554)
		(end 458.05471 -188.44006)
		(width 0.10668)
		(layer "B.Cu")
		(net "PVDDCR_CPU1_P0_RESET_N")
	)
	(segment
		(start 407.844244 -357.171752)
		(end 407.844244 -343.361264)
		(width 0.10668)
		(layer "B.Cu")
		(net "PVDDCR_CPU1_P0_RESET_N")
	)
	(segment
		(start 327.7616 -362.1786)
		(end 327.948544 -362.1786)
		(width 0.10668)
		(layer "B.Cu")
		(net "PVDDCR_CPU1_P0_RESET_N")
	)
	(segment
		(start 414.437576 -336.767932)
		(end 414.437576 -329.398884)
		(width 0.10668)
		(layer "B.Cu")
		(net "PVDDCR_CPU1_P0_RESET_N")
	)
	(segment
		(start 395.19606 -364.251494)
		(end 401.115022 -358.332532)
		(width 0.10668)
		(layer "B.Cu")
		(net "PVDDCR_CPU1_P0_RESET_N")
	)
	(segment
		(start 406.683464 -358.332532)
		(end 407.844244 -357.171752)
		(width 0.10668)
		(layer "B.Cu")
		(net "PVDDCR_CPU1_P0_RESET_N")
	)
	(segment
		(start 458.05471 -188.44006)
		(end 447.092324 -177.477674)
		(width 0.10668)
		(layer "B.Cu")
		(net "PVDDCR_CPU1_P0_RESET_N")
	)
	(segment
		(start 454.175114 -327.20915)
		(end 458.05471 -323.329554)
		(width 0.10668)
		(layer "B.Cu")
		(net "PVDDCR_CPU1_P0_RESET_N")
	)
	(segment
		(start 303.276 -361.696)
		(end 303.48936 -361.90936)
		(width 0.11684)
		(layer "In13.Cu")
		(net "PVDDCR_CPU1_P0_RESET_N")
	)
	(segment
		(start 312.039 -363.474)
		(end 312.293 -363.728)
		(width 0.11684)
		(layer "In13.Cu")
		(net "PVDDCR_CPU1_P0_RESET_N")
	)
	(segment
		(start 305.72456 -361.90936)
		(end 307.2892 -363.474)
		(width 0.11684)
		(layer "In13.Cu")
		(net "PVDDCR_CPU1_P0_RESET_N")
	)
	(segment
		(start 303.48936 -361.90936)
		(end 305.72456 -361.90936)
		(width 0.11684)
		(layer "In13.Cu")
		(net "PVDDCR_CPU1_P0_RESET_N")
	)
	(segment
		(start 320.419476 -364.897924)
		(end 323.85 -361.4674)
		(width 0.11684)
		(layer "In13.Cu")
		(net "PVDDCR_CPU1_P0_RESET_N")
	)
	(segment
		(start 307.2892 -363.474)
		(end 312.039 -363.474)
		(width 0.11684)
		(layer "In13.Cu")
		(net "PVDDCR_CPU1_P0_RESET_N")
	)
	(segment
		(start 312.293 -363.728)
		(end 315.6966 -363.728)
		(width 0.11684)
		(layer "In13.Cu")
		(net "PVDDCR_CPU1_P0_RESET_N")
	)
	(segment
		(start 323.85 -361.4674)
		(end 327.0504 -361.4674)
		(width 0.11684)
		(layer "In13.Cu")
		(net "PVDDCR_CPU1_P0_RESET_N")
	)
	(segment
		(start 316.866524 -364.897924)
		(end 320.419476 -364.897924)
		(width 0.11684)
		(layer "In13.Cu")
		(net "PVDDCR_CPU1_P0_RESET_N")
	)
	(segment
		(start 315.6966 -363.728)
		(end 316.866524 -364.897924)
		(width 0.11684)
		(layer "In13.Cu")
		(net "PVDDCR_CPU1_P0_RESET_N")
	)
	(segment
		(start 351.926144 -343.939114)
		(end 351.590864 -344.274394)
		(width 0.1778)
		(layer "F.Cu")
		(net "PVDDCR_CPU1_P0_PWM6")
	)
	(segment
		(start 310.3372 -365.445802)
		(end 310.3372 -364.464346)
		(width 0.1524)
		(layer "F.Cu")
		(net "PVDDCR_CPU1_P0_PWM6")
	)
	(segment
		(start 310.346598 -365.4552)
		(end 310.3372 -365.445802)
		(width 0.1524)
		(layer "F.Cu")
		(net "PVDDCR_CPU1_P0_PWM6")
	)
	(segment
		(start 310.3372 -364.464346)
		(end 309.934102 -364.061248)
		(width 0.1524)
		(layer "F.Cu")
		(net "PVDDCR_CPU1_P0_PWM6")
	)
	(segment
		(start 351.926144 -342.834468)
		(end 351.926144 -343.939114)
		(width 0.1778)
		(layer "F.Cu")
		(net "PVDDCR_CPU1_P0_PWM6")
	)
	(segment
		(start 309.934102 -364.061248)
		(end 309.934102 -363.555026)
		(width 0.1524)
		(layer "F.Cu")
		(net "PVDDCR_CPU1_P0_PWM6")
	)
	(via
		(at 351.590864 -344.274394)
		(size 0.508)
		(drill 0.254)
		(layers "F.Cu" "B.Cu")
		(net "PVDDCR_CPU1_P0_PWM6")
	)
	(via
		(at 310.346598 -365.4552)
		(size 0.762)
		(drill 0.254)
		(layers "F.Cu" "B.Cu")
		(net "PVDDCR_CPU1_P0_PWM6")
	)
	(segment
		(start 332.21041 -349.62338)
		(end 332.21041 -354.14839)
		(width 0.1524)
		(layer "In4.Cu")
		(net "PVDDCR_CPU1_P0_PWM6")
	)
	(segment
		(start 313.9694 -366.903)
		(end 312.5216 -365.4552)
		(width 0.1524)
		(layer "In4.Cu")
		(net "PVDDCR_CPU1_P0_PWM6")
	)
	(segment
		(start 351.590864 -344.274394)
		(end 351.272856 -344.274394)
		(width 0.1524)
		(layer "In4.Cu")
		(net "PVDDCR_CPU1_P0_PWM6")
	)
	(segment
		(start 351.272856 -344.274394)
		(end 350.493584 -345.053666)
		(width 0.1524)
		(layer "In4.Cu")
		(net "PVDDCR_CPU1_P0_PWM6")
	)
	(segment
		(start 312.5216 -365.4552)
		(end 310.346598 -365.4552)
		(width 0.1524)
		(layer "In4.Cu")
		(net "PVDDCR_CPU1_P0_PWM6")
	)
	(segment
		(start 332.21041 -354.14839)
		(end 319.4558 -366.903)
		(width 0.1524)
		(layer "In4.Cu")
		(net "PVDDCR_CPU1_P0_PWM6")
	)
	(segment
		(start 350.087184 -347.577664)
		(end 340.90991 -347.577664)
		(width 0.1524)
		(layer "In4.Cu")
		(net "PVDDCR_CPU1_P0_PWM6")
	)
	(segment
		(start 319.4558 -366.903)
		(end 313.9694 -366.903)
		(width 0.1524)
		(layer "In4.Cu")
		(net "PVDDCR_CPU1_P0_PWM6")
	)
	(segment
		(start 340.909656 -347.57741)
		(end 334.25638 -347.57741)
		(width 0.1524)
		(layer "In4.Cu")
		(net "PVDDCR_CPU1_P0_PWM6")
	)
	(segment
		(start 350.493584 -347.171264)
		(end 350.087184 -347.577664)
		(width 0.1524)
		(layer "In4.Cu")
		(net "PVDDCR_CPU1_P0_PWM6")
	)
	(segment
		(start 340.90991 -347.577664)
		(end 340.909656 -347.57741)
		(width 0.1524)
		(layer "In4.Cu")
		(net "PVDDCR_CPU1_P0_PWM6")
	)
	(segment
		(start 334.25638 -347.57741)
		(end 332.21041 -349.62338)
		(width 0.1524)
		(layer "In4.Cu")
		(net "PVDDCR_CPU1_P0_PWM6")
	)
	(segment
		(start 350.493584 -345.053666)
		(end 350.493584 -347.171264)
		(width 0.1524)
		(layer "In4.Cu")
		(net "PVDDCR_CPU1_P0_PWM6")
	)
	(segment
		(start 343.650316 -339.02904)
		(end 343.650316 -337.924394)
		(width 0.1778)
		(layer "F.Cu")
		(net "PVDDCR_CPU1_P0_PWM5")
	)
	(segment
		(start 343.315036 -339.36432)
		(end 343.650316 -339.02904)
		(width 0.1778)
		(layer "F.Cu")
		(net "PVDDCR_CPU1_P0_PWM5")
	)
	(segment
		(start 309.534052 -364.525052)
		(end 309.534052 -363.555026)
		(width 0.1524)
		(layer "F.Cu")
		(net "PVDDCR_CPU1_P0_PWM5")
	)
	(segment
		(start 309.753 -364.744)
		(end 309.534052 -364.525052)
		(width 0.1524)
		(layer "F.Cu")
		(net "PVDDCR_CPU1_P0_PWM5")
	)
	(via
		(at 343.315036 -339.36432)
		(size 0.508)
		(drill 0.254)
		(layers "F.Cu" "B.Cu")
		(net "PVDDCR_CPU1_P0_PWM5")
	)
	(via
		(at 309.753 -364.744)
		(size 0.508)
		(drill 0.254)
		(layers "F.Cu" "B.Cu")
		(net "PVDDCR_CPU1_P0_PWM5")
	)
	(segment
		(start 313.3852 -364.744)
		(end 309.753 -364.744)
		(width 0.1524)
		(layer "In4.Cu")
		(net "PVDDCR_CPU1_P0_PWM5")
	)
	(segment
		(start 333.51724 -346.300806)
		(end 330.78801 -349.030036)
		(width 0.1524)
		(layer "In4.Cu")
		(net "PVDDCR_CPU1_P0_PWM5")
	)
	(segment
		(start 330.78801 -349.030036)
		(end 330.78801 -353.84359)
		(width 0.1524)
		(layer "In4.Cu")
		(net "PVDDCR_CPU1_P0_PWM5")
	)
	(segment
		(start 343.699084 -339.748368)
		(end 343.699084 -344.19286)
		(width 0.1524)
		(layer "In4.Cu")
		(net "PVDDCR_CPU1_P0_PWM5")
	)
	(segment
		(start 330.78801 -353.84359)
		(end 318.7446 -365.887)
		(width 0.1524)
		(layer "In4.Cu")
		(net "PVDDCR_CPU1_P0_PWM5")
	)
	(segment
		(start 314.5282 -365.887)
		(end 313.3852 -364.744)
		(width 0.1524)
		(layer "In4.Cu")
		(net "PVDDCR_CPU1_P0_PWM5")
	)
	(segment
		(start 318.7446 -365.887)
		(end 314.5282 -365.887)
		(width 0.1524)
		(layer "In4.Cu")
		(net "PVDDCR_CPU1_P0_PWM5")
	)
	(segment
		(start 341.591138 -346.300806)
		(end 333.51724 -346.300806)
		(width 0.1524)
		(layer "In4.Cu")
		(net "PVDDCR_CPU1_P0_PWM5")
	)
	(segment
		(start 343.315036 -339.36432)
		(end 343.699084 -339.748368)
		(width 0.1524)
		(layer "In4.Cu")
		(net "PVDDCR_CPU1_P0_PWM5")
	)
	(segment
		(start 343.699084 -344.19286)
		(end 341.591138 -346.300806)
		(width 0.1524)
		(layer "In4.Cu")
		(net "PVDDCR_CPU1_P0_PWM5")
	)
	(segment
		(start 308.5846 -365.7092)
		(end 309.134002 -365.159798)
		(width 0.1524)
		(layer "F.Cu")
		(net "PVDDCR_CPU1_P0_PWM4")
	)
	(segment
		(start 308.956202 -350.720914)
		(end 308.956202 -349.616268)
		(width 0.1778)
		(layer "F.Cu")
		(net "PVDDCR_CPU1_P0_PWM4")
	)
	(segment
		(start 308.620922 -351.056194)
		(end 308.956202 -350.720914)
		(width 0.1778)
		(layer "F.Cu")
		(net "PVDDCR_CPU1_P0_PWM4")
	)
	(segment
		(start 309.134002 -365.159798)
		(end 309.134002 -363.555026)
		(width 0.1524)
		(layer "F.Cu")
		(net "PVDDCR_CPU1_P0_PWM4")
	)
	(via
		(at 308.620922 -351.056194)
		(size 0.508)
		(drill 0.254)
		(layers "F.Cu" "B.Cu")
		(net "PVDDCR_CPU1_P0_PWM4")
	)
	(via
		(at 308.5846 -365.7092)
		(size 0.508)
		(drill 0.254)
		(layers "F.Cu" "B.Cu")
		(net "PVDDCR_CPU1_P0_PWM4")
	)
	(segment
		(start 303.911 -364.333536)
		(end 303.911 -355.3714)
		(width 0.1524)
		(layer "In4.Cu")
		(net "PVDDCR_CPU1_P0_PWM4")
	)
	(segment
		(start 307.94706 -351.33534)
		(end 308.620922 -351.056194)
		(width 0.1524)
		(layer "In4.Cu")
		(net "PVDDCR_CPU1_P0_PWM4")
	)
	(segment
		(start 308.5846 -365.7092)
		(end 307.9496 -366.3442)
		(width 0.1524)
		(layer "In4.Cu")
		(net "PVDDCR_CPU1_P0_PWM4")
	)
	(segment
		(start 303.911 -355.3714)
		(end 307.94706 -351.33534)
		(width 0.1524)
		(layer "In4.Cu")
		(net "PVDDCR_CPU1_P0_PWM4")
	)
	(segment
		(start 305.921664 -366.3442)
		(end 303.911 -364.333536)
		(width 0.1524)
		(layer "In4.Cu")
		(net "PVDDCR_CPU1_P0_PWM4")
	)
	(segment
		(start 307.9496 -366.3442)
		(end 305.921664 -366.3442)
		(width 0.1524)
		(layer "In4.Cu")
		(net "PVDDCR_CPU1_P0_PWM4")
	)
	(segment
		(start 307.831744 -365.598456)
		(end 308.733952 -364.696248)
		(width 0.1524)
		(layer "F.Cu")
		(net "PVDDCR_CPU1_P0_PWM3")
	)
	(segment
		(start 308.733952 -364.696248)
		(end 308.733952 -363.555026)
		(width 0.1524)
		(layer "F.Cu")
		(net "PVDDCR_CPU1_P0_PWM3")
	)
	(segment
		(start 307.4416 -365.76)
		(end 307.831744 -365.598456)
		(width 0.1524)
		(layer "F.Cu")
		(net "PVDDCR_CPU1_P0_PWM3")
	)
	(segment
		(start 318.605916 -338.99983)
		(end 318.605916 -337.895184)
		(width 0.1778)
		(layer "F.Cu")
		(net "PVDDCR_CPU1_P0_PWM3")
	)
	(segment
		(start 318.270636 -339.33511)
		(end 318.605916 -338.99983)
		(width 0.1778)
		(layer "F.Cu")
		(net "PVDDCR_CPU1_P0_PWM3")
	)
	(via
		(at 307.4416 -365.76)
		(size 0.508)
		(drill 0.254)
		(layers "F.Cu" "B.Cu")
		(net "PVDDCR_CPU1_P0_PWM3")
	)
	(via
		(at 318.270636 -339.33511)
		(size 0.508)
		(drill 0.254)
		(layers "F.Cu" "B.Cu")
		(net "PVDDCR_CPU1_P0_PWM3")
	)
	(segment
		(start 319.238884 -339.33511)
		(end 318.270636 -339.33511)
		(width 0.1524)
		(layer "In4.Cu")
		(net "PVDDCR_CPU1_P0_PWM3")
	)
	(segment
		(start 307.237892 -365.76)
		(end 306.223924 -364.746032)
		(width 0.1524)
		(layer "In4.Cu")
		(net "PVDDCR_CPU1_P0_PWM3")
	)
	(segment
		(start 317.3476 -357.6066)
		(end 321.184778 -353.769422)
		(width 0.1524)
		(layer "In4.Cu")
		(net "PVDDCR_CPU1_P0_PWM3")
	)
	(segment
		(start 321.184778 -353.769422)
		(end 321.184778 -341.281004)
		(width 0.1524)
		(layer "In4.Cu")
		(net "PVDDCR_CPU1_P0_PWM3")
	)
	(segment
		(start 307.5432 -357.6066)
		(end 317.3476 -357.6066)
		(width 0.1524)
		(layer "In4.Cu")
		(net "PVDDCR_CPU1_P0_PWM3")
	)
	(segment
		(start 306.223924 -364.746032)
		(end 306.223924 -358.925876)
		(width 0.1524)
		(layer "In4.Cu")
		(net "PVDDCR_CPU1_P0_PWM3")
	)
	(segment
		(start 307.4416 -365.76)
		(end 307.237892 -365.76)
		(width 0.1524)
		(layer "In4.Cu")
		(net "PVDDCR_CPU1_P0_PWM3")
	)
	(segment
		(start 306.223924 -358.925876)
		(end 307.5432 -357.6066)
		(width 0.1524)
		(layer "In4.Cu")
		(net "PVDDCR_CPU1_P0_PWM3")
	)
	(segment
		(start 321.184778 -341.281004)
		(end 319.238884 -339.33511)
		(width 0.1524)
		(layer "In4.Cu")
		(net "PVDDCR_CPU1_P0_PWM3")
	)
	(segment
		(start 326.62622 -339.327998)
		(end 326.9615 -338.992718)
		(width 0.1778)
		(layer "F.Cu")
		(net "PVDDCR_CPU1_P0_PWM2")
	)
	(segment
		(start 326.9615 -338.992718)
		(end 326.9615 -337.888072)
		(width 0.1778)
		(layer "F.Cu")
		(net "PVDDCR_CPU1_P0_PWM2")
	)
	(segment
		(start 308.333902 -364.258098)
		(end 308.333902 -363.555026)
		(width 0.1524)
		(layer "F.Cu")
		(net "PVDDCR_CPU1_P0_PWM2")
	)
	(segment
		(start 308.102 -364.49)
		(end 308.333902 -364.258098)
		(width 0.1524)
		(layer "F.Cu")
		(net "PVDDCR_CPU1_P0_PWM2")
	)
	(via
		(at 326.62622 -339.327998)
		(size 0.508)
		(drill 0.254)
		(layers "F.Cu" "B.Cu")
		(net "PVDDCR_CPU1_P0_PWM2")
	)
	(via
		(at 308.102 -364.49)
		(size 0.508)
		(drill 0.254)
		(layers "F.Cu" "B.Cu")
		(net "PVDDCR_CPU1_P0_PWM2")
	)
	(segment
		(start 319.6844 -361.061)
		(end 317.0174 -361.061)
		(width 0.1524)
		(layer "In4.Cu")
		(net "PVDDCR_CPU1_P0_PWM2")
	)
	(segment
		(start 322.655184 -342.801194)
		(end 322.655184 -358.090216)
		(width 0.1524)
		(layer "In4.Cu")
		(net "PVDDCR_CPU1_P0_PWM2")
	)
	(segment
		(start 313.9694 -362.331)
		(end 313.0804 -363.22)
		(width 0.1524)
		(layer "In4.Cu")
		(net "PVDDCR_CPU1_P0_PWM2")
	)
	(segment
		(start 317.0174 -361.061)
		(end 315.7474 -362.331)
		(width 0.1524)
		(layer "In4.Cu")
		(net "PVDDCR_CPU1_P0_PWM2")
	)
	(segment
		(start 309.372 -363.22)
		(end 308.102 -364.49)
		(width 0.1524)
		(layer "In4.Cu")
		(net "PVDDCR_CPU1_P0_PWM2")
	)
	(segment
		(start 326.62622 -339.327998)
		(end 326.356726 -339.597492)
		(width 0.1524)
		(layer "In4.Cu")
		(net "PVDDCR_CPU1_P0_PWM2")
	)
	(segment
		(start 326.356726 -339.597492)
		(end 325.858886 -339.597492)
		(width 0.1524)
		(layer "In4.Cu")
		(net "PVDDCR_CPU1_P0_PWM2")
	)
	(segment
		(start 313.0804 -363.22)
		(end 309.372 -363.22)
		(width 0.1524)
		(layer "In4.Cu")
		(net "PVDDCR_CPU1_P0_PWM2")
	)
	(segment
		(start 325.858886 -339.597492)
		(end 322.655184 -342.801194)
		(width 0.1524)
		(layer "In4.Cu")
		(net "PVDDCR_CPU1_P0_PWM2")
	)
	(segment
		(start 322.655184 -358.090216)
		(end 319.6844 -361.061)
		(width 0.1524)
		(layer "In4.Cu")
		(net "PVDDCR_CPU1_P0_PWM2")
	)
	(segment
		(start 315.7474 -362.331)
		(end 313.9694 -362.331)
		(width 0.1524)
		(layer "In4.Cu")
		(net "PVDDCR_CPU1_P0_PWM2")
	)
	(segment
		(start 307.3654 -364.3884)
		(end 307.934106 -363.819694)
		(width 0.1524)
		(layer "F.Cu")
		(net "PVDDCR_CPU1_P0_PWM1")
	)
	(segment
		(start 307.934106 -363.819694)
		(end 307.934106 -363.555026)
		(width 0.1524)
		(layer "F.Cu")
		(net "PVDDCR_CPU1_P0_PWM1")
	)
	(segment
		(start 334.983836 -339.31352)
		(end 335.319116 -338.97824)
		(width 0.1778)
		(layer "F.Cu")
		(net "PVDDCR_CPU1_P0_PWM1")
	)
	(segment
		(start 307.3654 -364.871)
		(end 307.3654 -364.3884)
		(width 0.1524)
		(layer "F.Cu")
		(net "PVDDCR_CPU1_P0_PWM1")
	)
	(segment
		(start 335.319116 -338.97824)
		(end 335.319116 -337.873594)
		(width 0.1778)
		(layer "F.Cu")
		(net "PVDDCR_CPU1_P0_PWM1")
	)
	(via
		(at 307.3654 -364.871)
		(size 0.508)
		(drill 0.254)
		(layers "F.Cu" "B.Cu")
		(net "PVDDCR_CPU1_P0_PWM1")
	)
	(via
		(at 334.983836 -339.31352)
		(size 0.508)
		(drill 0.254)
		(layers "F.Cu" "B.Cu")
		(net "PVDDCR_CPU1_P0_PWM1")
	)
	(segment
		(start 308.551834 -365.005366)
		(end 308.26329 -365.125)
		(width 0.1524)
		(layer "In4.Cu")
		(net "PVDDCR_CPU1_P0_PWM1")
	)
	(segment
		(start 331.300074 -342.448642)
		(end 327.088754 -342.448642)
		(width 0.1524)
		(layer "In4.Cu")
		(net "PVDDCR_CPU1_P0_PWM1")
	)
	(segment
		(start 327.088754 -342.448642)
		(end 324.428104 -345.109292)
		(width 0.1524)
		(layer "In4.Cu")
		(net "PVDDCR_CPU1_P0_PWM1")
	)
	(segment
		(start 307.6194 -365.125)
		(end 307.3654 -364.871)
		(width 0.1524)
		(layer "In4.Cu")
		(net "PVDDCR_CPU1_P0_PWM1")
	)
	(segment
		(start 324.428104 -345.109292)
		(end 324.428104 -357.714296)
		(width 0.1524)
		(layer "In4.Cu")
		(net "PVDDCR_CPU1_P0_PWM1")
	)
	(segment
		(start 309.4482 -364.109)
		(end 308.551834 -365.005366)
		(width 0.1524)
		(layer "In4.Cu")
		(net "PVDDCR_CPU1_P0_PWM1")
	)
	(segment
		(start 315.7474 -364.109)
		(end 309.4482 -364.109)
		(width 0.1524)
		(layer "In4.Cu")
		(net "PVDDCR_CPU1_P0_PWM1")
	)
	(segment
		(start 324.428104 -357.714296)
		(end 319.9384 -362.204)
		(width 0.1524)
		(layer "In4.Cu")
		(net "PVDDCR_CPU1_P0_PWM1")
	)
	(segment
		(start 334.712564 -339.584792)
		(end 334.163924 -339.584792)
		(width 0.1524)
		(layer "In4.Cu")
		(net "PVDDCR_CPU1_P0_PWM1")
	)
	(segment
		(start 317.6524 -362.204)
		(end 315.7474 -364.109)
		(width 0.1524)
		(layer "In4.Cu")
		(net "PVDDCR_CPU1_P0_PWM1")
	)
	(segment
		(start 319.9384 -362.204)
		(end 317.6524 -362.204)
		(width 0.1524)
		(layer "In4.Cu")
		(net "PVDDCR_CPU1_P0_PWM1")
	)
	(segment
		(start 308.26329 -365.125)
		(end 307.6194 -365.125)
		(width 0.1524)
		(layer "In4.Cu")
		(net "PVDDCR_CPU1_P0_PWM1")
	)
	(segment
		(start 334.983836 -339.31352)
		(end 334.712564 -339.584792)
		(width 0.1524)
		(layer "In4.Cu")
		(net "PVDDCR_CPU1_P0_PWM1")
	)
	(segment
		(start 334.163924 -339.584792)
		(end 331.300074 -342.448642)
		(width 0.1524)
		(layer "In4.Cu")
		(net "PVDDCR_CPU1_P0_PWM1")
	)
	(segment
		(start 339.70722 -335.422748)
		(end 339.70722 -336.033872)
		(width 0.4572)
		(layer "F.Cu")
		(net "PVDDCR_CPU1_P0_PVCC")
	)
	(segment
		(start 297.96486 -347.641418)
		(end 297.429174 -347.641418)
		(width 0.2286)
		(layer "F.Cu")
		(net "PVDDCR_CPU1_P0_PVCC")
	)
	(segment
		(start 315.410088 -335.920334)
		(end 315.945774 -335.920334)
		(width 0.2286)
		(layer "F.Cu")
		(net "PVDDCR_CPU1_P0_PVCC")
	)
	(segment
		(start 289.072574 -347.641418)
		(end 288.545778 -347.114622)
		(width 0.2286)
		(layer "F.Cu")
		(net "PVDDCR_CPU1_P0_PVCC")
	)
	(segment
		(start 305.760374 -347.641418)
		(end 305.233578 -347.114622)
		(width 0.2286)
		(layer "F.Cu")
		(net "PVDDCR_CPU1_P0_PVCC")
	)
	(segment
		(start 280.019506 -347.725746)
		(end 280.019506 -347.114622)
		(width 0.4572)
		(layer "F.Cu")
		(net "PVDDCR_CPU1_P0_PVCC")
	)
	(segment
		(start 271.739106 -347.114622)
		(end 272.10512 -347.114622)
		(width 0.2286)
		(layer "F.Cu")
		(net "PVDDCR_CPU1_P0_PVCC")
	)
	(segment
		(start 348.20352 -340.332822)
		(end 347.983048 -340.332822)
		(width 0.2286)
		(layer "F.Cu")
		(net "PVDDCR_CPU1_P0_PVCC")
	)
	(segment
		(start 280.766774 -347.641418)
		(end 281.30246 -347.641418)
		(width 0.2286)
		(layer "F.Cu")
		(net "PVDDCR_CPU1_P0_PVCC")
	)
	(segment
		(start 349.266002 -340.859618)
		(end 348.730316 -340.859618)
		(width 0.2286)
		(layer "F.Cu")
		(net "PVDDCR_CPU1_P0_PVCC")
	)
	(segment
		(start 296.681906 -347.114622)
		(end 296.681906 -347.725746)
		(width 0.4572)
		(layer "F.Cu")
		(net "PVDDCR_CPU1_P0_PVCC")
	)
	(segment
		(start 332.658974 -335.898744)
		(end 332.123288 -335.898744)
		(width 0.2286)
		(layer "F.Cu")
		(net "PVDDCR_CPU1_P0_PVCC")
	)
	(segment
		(start 280.239978 -347.114622)
		(end 280.766774 -347.641418)
		(width 0.2286)
		(layer "F.Cu")
		(net "PVDDCR_CPU1_P0_PVCC")
	)
	(segment
		(start 323.238876 -335.386426)
		(end 323.018404 -335.386426)
		(width 0.2286)
		(layer "F.Cu")
		(net "PVDDCR_CPU1_P0_PVCC")
	)
	(segment
		(start 332.123288 -335.898744)
		(end 331.596492 -335.371948)
		(width 0.2286)
		(layer "F.Cu")
		(net "PVDDCR_CPU1_P0_PVCC")
	)
	(segment
		(start 331.596492 -335.371948)
		(end 331.37602 -335.371948)
		(width 0.2286)
		(layer "F.Cu")
		(net "PVDDCR_CPU1_P0_PVCC")
	)
	(segment
		(start 305.013106 -347.114622)
		(end 305.013106 -347.725746)
		(width 0.4572)
		(layer "F.Cu")
		(net "PVDDCR_CPU1_P0_PVCC")
	)
	(segment
		(start 280.019506 -347.114622)
		(end 280.239978 -347.114622)
		(width 0.2286)
		(layer "F.Cu")
		(net "PVDDCR_CPU1_P0_PVCC")
	)
	(segment
		(start 297.429174 -347.641418)
		(end 296.902378 -347.114622)
		(width 0.2286)
		(layer "F.Cu")
		(net "PVDDCR_CPU1_P0_PVCC")
	)
	(segment
		(start 331.37602 -335.371948)
		(end 331.37602 -335.983072)
		(width 0.4572)
		(layer "F.Cu")
		(net "PVDDCR_CPU1_P0_PVCC")
	)
	(segment
		(start 339.927692 -335.422748)
		(end 339.70722 -335.422748)
		(width 0.2286)
		(layer "F.Cu")
		(net "PVDDCR_CPU1_P0_PVCC")
	)
	(segment
		(start 305.233578 -347.114622)
		(end 305.013106 -347.114622)
		(width 0.2286)
		(layer "F.Cu")
		(net "PVDDCR_CPU1_P0_PVCC")
	)
	(segment
		(start 288.545778 -347.114622)
		(end 288.325306 -347.114622)
		(width 0.2286)
		(layer "F.Cu")
		(net "PVDDCR_CPU1_P0_PVCC")
	)
	(segment
		(start 348.730316 -340.859618)
		(end 348.20352 -340.332822)
		(width 0.2286)
		(layer "F.Cu")
		(net "PVDDCR_CPU1_P0_PVCC")
	)
	(segment
		(start 347.983048 -340.332822)
		(end 347.983048 -340.943946)
		(width 0.4572)
		(layer "F.Cu")
		(net "PVDDCR_CPU1_P0_PVCC")
	)
	(segment
		(start 323.018404 -335.386426)
		(end 323.018404 -335.99755)
		(width 0.4572)
		(layer "F.Cu")
		(net "PVDDCR_CPU1_P0_PVCC")
	)
	(segment
		(start 272.631916 -347.641418)
		(end 273.02206 -347.641418)
		(width 0.2286)
		(layer "F.Cu")
		(net "PVDDCR_CPU1_P0_PVCC")
	)
	(segment
		(start 340.454488 -335.949544)
		(end 339.927692 -335.422748)
		(width 0.2286)
		(layer "F.Cu")
		(net "PVDDCR_CPU1_P0_PVCC")
	)
	(segment
		(start 314.66282 -336.004662)
		(end 314.66282 -335.393538)
		(width 0.4572)
		(layer "F.Cu")
		(net "PVDDCR_CPU1_P0_PVCC")
	)
	(segment
		(start 324.301358 -335.913222)
		(end 323.765672 -335.913222)
		(width 0.2286)
		(layer "F.Cu")
		(net "PVDDCR_CPU1_P0_PVCC")
	)
	(segment
		(start 289.60826 -347.641418)
		(end 289.072574 -347.641418)
		(width 0.2286)
		(layer "F.Cu")
		(net "PVDDCR_CPU1_P0_PVCC")
	)
	(segment
		(start 296.902378 -347.114622)
		(end 296.681906 -347.114622)
		(width 0.2286)
		(layer "F.Cu")
		(net "PVDDCR_CPU1_P0_PVCC")
	)
	(segment
		(start 272.10512 -347.114622)
		(end 272.631916 -347.641418)
		(width 0.2286)
		(layer "F.Cu")
		(net "PVDDCR_CPU1_P0_PVCC")
	)
	(segment
		(start 340.990174 -335.949544)
		(end 340.454488 -335.949544)
		(width 0.2286)
		(layer "F.Cu")
		(net "PVDDCR_CPU1_P0_PVCC")
	)
	(segment
		(start 288.325306 -347.114622)
		(end 288.325306 -347.725746)
		(width 0.4572)
		(layer "F.Cu")
		(net "PVDDCR_CPU1_P0_PVCC")
	)
	(segment
		(start 306.29606 -347.641418)
		(end 305.760374 -347.641418)
		(width 0.2286)
		(layer "F.Cu")
		(net "PVDDCR_CPU1_P0_PVCC")
	)
	(segment
		(start 314.883292 -335.393538)
		(end 315.410088 -335.920334)
		(width 0.2286)
		(layer "F.Cu")
		(net "PVDDCR_CPU1_P0_PVCC")
	)
	(segment
		(start 323.765672 -335.913222)
		(end 323.238876 -335.386426)
		(width 0.2286)
		(layer "F.Cu")
		(net "PVDDCR_CPU1_P0_PVCC")
	)
	(segment
		(start 314.66282 -335.393538)
		(end 314.883292 -335.393538)
		(width 0.2286)
		(layer "F.Cu")
		(net "PVDDCR_CPU1_P0_PVCC")
	)
	(via
		(at 314.66282 -336.004662)
		(size 0.508)
		(drill 0.254)
		(layers "F.Cu" "B.Cu")
		(net "PVDDCR_CPU1_P0_PVCC")
	)
	(via
		(at 339.70722 -336.033872)
		(size 0.508)
		(drill 0.254)
		(layers "F.Cu" "B.Cu")
		(net "PVDDCR_CPU1_P0_PVCC")
	)
	(via
		(at 280.019506 -347.725746)
		(size 0.508)
		(drill 0.254)
		(layers "F.Cu" "B.Cu")
		(net "PVDDCR_CPU1_P0_PVCC")
	)
	(via
		(at 305.013106 -347.725746)
		(size 0.508)
		(drill 0.254)
		(layers "F.Cu" "B.Cu")
		(net "PVDDCR_CPU1_P0_PVCC")
	)
	(via
		(at 271.739106 -347.725746)
		(size 0.508)
		(drill 0.254)
		(layers "F.Cu" "B.Cu")
		(net "PVDDCR_CPU1_P0_PVCC")
	)
	(via
		(at 347.983048 -340.943946)
		(size 0.508)
		(drill 0.254)
		(layers "F.Cu" "B.Cu")
		(net "PVDDCR_CPU1_P0_PVCC")
	)
	(via
		(at 288.325306 -347.725746)
		(size 0.508)
		(drill 0.254)
		(layers "F.Cu" "B.Cu")
		(net "PVDDCR_CPU1_P0_PVCC")
	)
	(via
		(at 331.37602 -335.983072)
		(size 0.508)
		(drill 0.254)
		(layers "F.Cu" "B.Cu")
		(net "PVDDCR_CPU1_P0_PVCC")
	)
	(via
		(at 296.681906 -347.725746)
		(size 0.508)
		(drill 0.254)
		(layers "F.Cu" "B.Cu")
		(net "PVDDCR_CPU1_P0_PVCC")
	)
	(via
		(at 270.768826 -350.163638)
		(size 0.762)
		(drill 0.381)
		(layers "F.Cu" "B.Cu")
		(net "PVDDCR_CPU1_P0_PVCC")
	)
	(via
		(at 323.018404 -335.99755)
		(size 0.508)
		(drill 0.254)
		(layers "F.Cu" "B.Cu")
		(net "PVDDCR_CPU1_P0_PVCC")
	)
	(segment
		(start 324.390512 -335.647284)
		(end 323.39026 -335.647284)
		(width 0.381)
		(layer "B.Cu")
		(net "PVDDCR_CPU1_P0_PVCC")
	)
	(segment
		(start 349.355156 -340.59368)
		(end 348.333314 -340.59368)
		(width 0.381)
		(layer "B.Cu")
		(net "PVDDCR_CPU1_P0_PVCC")
	)
	(segment
		(start 273.111214 -347.37548)
		(end 272.089372 -347.37548)
		(width 0.381)
		(layer "B.Cu")
		(net "PVDDCR_CPU1_P0_PVCC")
	)
	(segment
		(start 323.039994 -335.99755)
		(end 323.018404 -335.99755)
		(width 0.381)
		(layer "B.Cu")
		(net "PVDDCR_CPU1_P0_PVCC")
	)
	(segment
		(start 315.034676 -335.654396)
		(end 314.68441 -336.004662)
		(width 0.381)
		(layer "B.Cu")
		(net "PVDDCR_CPU1_P0_PVCC")
	)
	(segment
		(start 281.391614 -347.37548)
		(end 280.369772 -347.37548)
		(width 0.381)
		(layer "B.Cu")
		(net "PVDDCR_CPU1_P0_PVCC")
	)
	(segment
		(start 314.68441 -336.004662)
		(end 314.66282 -336.004662)
		(width 0.381)
		(layer "B.Cu")
		(net "PVDDCR_CPU1_P0_PVCC")
	)
	(segment
		(start 272.089372 -347.37548)
		(end 271.739106 -347.725746)
		(width 0.381)
		(layer "B.Cu")
		(net "PVDDCR_CPU1_P0_PVCC")
	)
	(segment
		(start 339.72881 -336.033872)
		(end 339.70722 -336.033872)
		(width 0.381)
		(layer "B.Cu")
		(net "PVDDCR_CPU1_P0_PVCC")
	)
	(segment
		(start 331.39761 -335.983072)
		(end 331.37602 -335.983072)
		(width 0.381)
		(layer "B.Cu")
		(net "PVDDCR_CPU1_P0_PVCC")
	)
	(segment
		(start 289.697414 -347.37548)
		(end 288.675572 -347.37548)
		(width 0.381)
		(layer "B.Cu")
		(net "PVDDCR_CPU1_P0_PVCC")
	)
	(segment
		(start 340.079076 -335.683606)
		(end 339.72881 -336.033872)
		(width 0.381)
		(layer "B.Cu")
		(net "PVDDCR_CPU1_P0_PVCC")
	)
	(segment
		(start 297.032172 -347.37548)
		(end 296.681906 -347.725746)
		(width 0.381)
		(layer "B.Cu")
		(net "PVDDCR_CPU1_P0_PVCC")
	)
	(segment
		(start 323.39026 -335.647284)
		(end 323.039994 -335.99755)
		(width 0.381)
		(layer "B.Cu")
		(net "PVDDCR_CPU1_P0_PVCC")
	)
	(segment
		(start 280.369772 -347.37548)
		(end 280.019506 -347.725746)
		(width 0.381)
		(layer "B.Cu")
		(net "PVDDCR_CPU1_P0_PVCC")
	)
	(segment
		(start 316.034928 -335.654396)
		(end 315.034676 -335.654396)
		(width 0.381)
		(layer "B.Cu")
		(net "PVDDCR_CPU1_P0_PVCC")
	)
	(segment
		(start 332.748128 -335.632806)
		(end 331.747876 -335.632806)
		(width 0.381)
		(layer "B.Cu")
		(net "PVDDCR_CPU1_P0_PVCC")
	)
	(segment
		(start 348.333314 -340.59368)
		(end 347.983048 -340.943946)
		(width 0.381)
		(layer "B.Cu")
		(net "PVDDCR_CPU1_P0_PVCC")
	)
	(segment
		(start 341.079328 -335.683606)
		(end 340.079076 -335.683606)
		(width 0.381)
		(layer "B.Cu")
		(net "PVDDCR_CPU1_P0_PVCC")
	)
	(segment
		(start 331.747876 -335.632806)
		(end 331.39761 -335.983072)
		(width 0.381)
		(layer "B.Cu")
		(net "PVDDCR_CPU1_P0_PVCC")
	)
	(segment
		(start 306.385214 -347.37548)
		(end 305.363372 -347.37548)
		(width 0.381)
		(layer "B.Cu")
		(net "PVDDCR_CPU1_P0_PVCC")
	)
	(segment
		(start 298.054014 -347.37548)
		(end 297.032172 -347.37548)
		(width 0.381)
		(layer "B.Cu")
		(net "PVDDCR_CPU1_P0_PVCC")
	)
	(segment
		(start 305.363372 -347.37548)
		(end 305.013106 -347.725746)
		(width 0.381)
		(layer "B.Cu")
		(net "PVDDCR_CPU1_P0_PVCC")
	)
	(segment
		(start 288.675572 -347.37548)
		(end 288.325306 -347.725746)
		(width 0.381)
		(layer "B.Cu")
		(net "PVDDCR_CPU1_P0_PVCC")
	)
	(segment
		(start 304.240946 -341.69731)
		(end 297.128946 -341.69731)
		(width 0.508)
		(layer "In6.Cu")
		(net "PVDDCR_CPU1_P0_PVCC")
	)
	(segment
		(start 296.493946 -347.537786)
		(end 296.681906 -347.725746)
		(width 0.508)
		(layer "In6.Cu")
		(net "PVDDCR_CPU1_P0_PVCC")
	)
	(segment
		(start 296.366946 -341.69731)
		(end 288.873946 -341.69731)
		(width 0.508)
		(layer "In6.Cu")
		(net "PVDDCR_CPU1_P0_PVCC")
	)
	(segment
		(start 288.873946 -341.69731)
		(end 288.325306 -342.24595)
		(width 0.508)
		(layer "In6.Cu")
		(net "PVDDCR_CPU1_P0_PVCC")
	)
	(segment
		(start 279.765506 -347.471746)
		(end 279.765506 -342.36787)
		(width 0.508)
		(layer "In6.Cu")
		(net "PVDDCR_CPU1_P0_PVCC")
	)
	(segment
		(start 314.66282 -336.004662)
		(end 314.041536 -336.004662)
		(width 0.508)
		(layer "In6.Cu")
		(net "PVDDCR_CPU1_P0_PVCC")
	)
	(segment
		(start 322.88226 -335.861406)
		(end 322.88226 -330.77531)
		(width 0.508)
		(layer "In6.Cu")
		(net "PVDDCR_CPU1_P0_PVCC")
	)
	(segment
		(start 279.221946 -341.82431)
		(end 272.490946 -341.82431)
		(width 0.508)
		(layer "In6.Cu")
		(net "PVDDCR_CPU1_P0_PVCC")
	)
	(segment
		(start 287.857946 -341.82431)
		(end 280.237946 -341.82431)
		(width 0.508)
		(layer "In6.Cu")
		(net "PVDDCR_CPU1_P0_PVCC")
	)
	(segment
		(start 271.485106 -347.471746)
		(end 271.739106 -347.725746)
		(width 0.508)
		(layer "In6.Cu")
		(net "PVDDCR_CPU1_P0_PVCC")
	)
	(segment
		(start 313.804046 -340.846664)
		(end 312.9534 -341.69731)
		(width 0.508)
		(layer "In6.Cu")
		(net "PVDDCR_CPU1_P0_PVCC")
	)
	(segment
		(start 338.94522 -330.14031)
		(end 331.39126 -330.14031)
		(width 0.508)
		(layer "In6.Cu")
		(net "PVDDCR_CPU1_P0_PVCC")
	)
	(segment
		(start 272.490946 -341.82431)
		(end 271.485106 -342.83015)
		(width 0.508)
		(layer "In6.Cu")
		(net "PVDDCR_CPU1_P0_PVCC")
	)
	(segment
		(start 296.681906 -342.14435)
		(end 296.493946 -342.33231)
		(width 0.508)
		(layer "In6.Cu")
		(net "PVDDCR_CPU1_P0_PVCC")
	)
	(segment
		(start 347.475048 -330.14031)
		(end 339.90026 -330.14031)
		(width 0.508)
		(layer "In6.Cu")
		(net "PVDDCR_CPU1_P0_PVCC")
	)
	(segment
		(start 296.681906 -342.01227)
		(end 296.366946 -341.69731)
		(width 0.508)
		(layer "In6.Cu")
		(net "PVDDCR_CPU1_P0_PVCC")
	)
	(segment
		(start 331.01026 -330.52131)
		(end 331.01026 -330.77531)
		(width 0.508)
		(layer "In6.Cu")
		(net "PVDDCR_CPU1_P0_PVCC")
	)
	(segment
		(start 271.485106 -342.83015)
		(end 271.485106 -347.471746)
		(width 0.508)
		(layer "In6.Cu")
		(net "PVDDCR_CPU1_P0_PVCC")
	)
	(segment
		(start 279.765506 -342.36787)
		(end 279.221946 -341.82431)
		(width 0.508)
		(layer "In6.Cu")
		(net "PVDDCR_CPU1_P0_PVCC")
	)
	(segment
		(start 279.765506 -342.29675)
		(end 279.765506 -342.36787)
		(width 0.508)
		(layer "In6.Cu")
		(net "PVDDCR_CPU1_P0_PVCC")
	)
	(segment
		(start 288.325306 -342.24595)
		(end 288.325306 -342.29167)
		(width 0.508)
		(layer "In6.Cu")
		(net "PVDDCR_CPU1_P0_PVCC")
	)
	(segment
		(start 280.237946 -341.82431)
		(end 279.765506 -342.29675)
		(width 0.508)
		(layer "In6.Cu")
		(net "PVDDCR_CPU1_P0_PVCC")
	)
	(segment
		(start 288.162492 -347.562932)
		(end 288.162492 -342.454484)
		(width 0.508)
		(layer "In6.Cu")
		(net "PVDDCR_CPU1_P0_PVCC")
	)
	(segment
		(start 347.983048 -340.943946)
		(end 347.899736 -340.860634)
		(width 0.508)
		(layer "In6.Cu")
		(net "PVDDCR_CPU1_P0_PVCC")
	)
	(segment
		(start 296.493946 -342.33231)
		(end 296.493946 -347.537786)
		(width 0.508)
		(layer "In6.Cu")
		(net "PVDDCR_CPU1_P0_PVCC")
	)
	(segment
		(start 339.90026 -330.14031)
		(end 339.45322 -330.58735)
		(width 0.508)
		(layer "In6.Cu")
		(net "PVDDCR_CPU1_P0_PVCC")
	)
	(segment
		(start 288.162492 -342.454484)
		(end 288.325306 -342.29167)
		(width 0.508)
		(layer "In6.Cu")
		(net "PVDDCR_CPU1_P0_PVCC")
	)
	(segment
		(start 314.041536 -336.004662)
		(end 313.804046 -336.242152)
		(width 0.508)
		(layer "In6.Cu")
		(net "PVDDCR_CPU1_P0_PVCC")
	)
	(segment
		(start 331.39126 -330.14031)
		(end 331.01026 -330.52131)
		(width 0.508)
		(layer "In6.Cu")
		(net "PVDDCR_CPU1_P0_PVCC")
	)
	(segment
		(start 288.325306 -342.29167)
		(end 287.857946 -341.82431)
		(width 0.508)
		(layer "In6.Cu")
		(net "PVDDCR_CPU1_P0_PVCC")
	)
	(segment
		(start 339.70722 -336.033872)
		(end 339.45322 -335.779872)
		(width 0.508)
		(layer "In6.Cu")
		(net "PVDDCR_CPU1_P0_PVCC")
	)
	(segment
		(start 315.51626 -330.26731)
		(end 314.477146 -331.306424)
		(width 0.508)
		(layer "In6.Cu")
		(net "PVDDCR_CPU1_P0_PVCC")
	)
	(segment
		(start 297.128946 -341.69731)
		(end 296.681906 -342.14435)
		(width 0.508)
		(layer "In6.Cu")
		(net "PVDDCR_CPU1_P0_PVCC")
	)
	(segment
		(start 312.9534 -341.69731)
		(end 305.277266 -341.69731)
		(width 0.508)
		(layer "In6.Cu")
		(net "PVDDCR_CPU1_P0_PVCC")
	)
	(segment
		(start 339.45322 -330.64831)
		(end 338.94522 -330.14031)
		(width 0.508)
		(layer "In6.Cu")
		(net "PVDDCR_CPU1_P0_PVCC")
	)
	(segment
		(start 347.899736 -335.44637)
		(end 348.193106 -335.153)
		(width 0.508)
		(layer "In6.Cu")
		(net "PVDDCR_CPU1_P0_PVCC")
	)
	(segment
		(start 331.37602 -335.983072)
		(end 331.01026 -335.617312)
		(width 0.508)
		(layer "In6.Cu")
		(net "PVDDCR_CPU1_P0_PVCC")
	)
	(segment
		(start 304.759106 -347.471746)
		(end 304.759106 -342.21547)
		(width 0.508)
		(layer "In6.Cu")
		(net "PVDDCR_CPU1_P0_PVCC")
	)
	(segment
		(start 347.899736 -340.860634)
		(end 347.899736 -335.44637)
		(width 0.508)
		(layer "In6.Cu")
		(net "PVDDCR_CPU1_P0_PVCC")
	)
	(segment
		(start 339.45322 -330.58735)
		(end 339.45322 -330.64831)
		(width 0.508)
		(layer "In6.Cu")
		(net "PVDDCR_CPU1_P0_PVCC")
	)
	(segment
		(start 305.013106 -347.725746)
		(end 304.759106 -347.471746)
		(width 0.508)
		(layer "In6.Cu")
		(net "PVDDCR_CPU1_P0_PVCC")
	)
	(segment
		(start 313.804046 -336.242152)
		(end 313.804046 -340.846664)
		(width 0.508)
		(layer "In6.Cu")
		(net "PVDDCR_CPU1_P0_PVCC")
	)
	(segment
		(start 296.681906 -342.14435)
		(end 296.681906 -342.01227)
		(width 0.508)
		(layer "In6.Cu")
		(net "PVDDCR_CPU1_P0_PVCC")
	)
	(segment
		(start 314.477146 -335.818988)
		(end 314.66282 -336.004662)
		(width 0.508)
		(layer "In6.Cu")
		(net "PVDDCR_CPU1_P0_PVCC")
	)
	(segment
		(start 339.45322 -335.779872)
		(end 339.45322 -330.64831)
		(width 0.508)
		(layer "In6.Cu")
		(net "PVDDCR_CPU1_P0_PVCC")
	)
	(segment
		(start 323.39026 -330.26731)
		(end 322.88226 -330.77531)
		(width 0.508)
		(layer "In6.Cu")
		(net "PVDDCR_CPU1_P0_PVCC")
	)
	(segment
		(start 322.88226 -330.77531)
		(end 322.88226 -330.64831)
		(width 0.508)
		(layer "In6.Cu")
		(net "PVDDCR_CPU1_P0_PVCC")
	)
	(segment
		(start 322.50126 -330.26731)
		(end 315.51626 -330.26731)
		(width 0.508)
		(layer "In6.Cu")
		(net "PVDDCR_CPU1_P0_PVCC")
	)
	(segment
		(start 330.50226 -330.26731)
		(end 323.39026 -330.26731)
		(width 0.508)
		(layer "In6.Cu")
		(net "PVDDCR_CPU1_P0_PVCC")
	)
	(segment
		(start 322.88226 -330.64831)
		(end 322.50126 -330.26731)
		(width 0.508)
		(layer "In6.Cu")
		(net "PVDDCR_CPU1_P0_PVCC")
	)
	(segment
		(start 280.019506 -347.725746)
		(end 279.765506 -347.471746)
		(width 0.508)
		(layer "In6.Cu")
		(net "PVDDCR_CPU1_P0_PVCC")
	)
	(segment
		(start 331.01026 -330.77531)
		(end 330.50226 -330.26731)
		(width 0.508)
		(layer "In6.Cu")
		(net "PVDDCR_CPU1_P0_PVCC")
	)
	(segment
		(start 348.193106 -335.153)
		(end 348.193106 -330.858368)
		(width 0.508)
		(layer "In6.Cu")
		(net "PVDDCR_CPU1_P0_PVCC")
	)
	(segment
		(start 288.325306 -347.725746)
		(end 288.162492 -347.562932)
		(width 0.508)
		(layer "In6.Cu")
		(net "PVDDCR_CPU1_P0_PVCC")
	)
	(segment
		(start 305.277266 -341.69731)
		(end 304.759106 -342.21547)
		(width 0.508)
		(layer "In6.Cu")
		(net "PVDDCR_CPU1_P0_PVCC")
	)
	(segment
		(start 331.01026 -335.617312)
		(end 331.01026 -330.77531)
		(width 0.508)
		(layer "In6.Cu")
		(net "PVDDCR_CPU1_P0_PVCC")
	)
	(segment
		(start 314.477146 -331.306424)
		(end 314.477146 -335.818988)
		(width 0.508)
		(layer "In6.Cu")
		(net "PVDDCR_CPU1_P0_PVCC")
	)
	(segment
		(start 304.759106 -342.21547)
		(end 304.240946 -341.69731)
		(width 0.508)
		(layer "In6.Cu")
		(net "PVDDCR_CPU1_P0_PVCC")
	)
	(segment
		(start 323.018404 -335.99755)
		(end 322.88226 -335.861406)
		(width 0.508)
		(layer "In6.Cu")
		(net "PVDDCR_CPU1_P0_PVCC")
	)
	(segment
		(start 348.193106 -330.858368)
		(end 347.475048 -330.14031)
		(width 0.508)
		(layer "In6.Cu")
		(net "PVDDCR_CPU1_P0_PVCC")
	)
	(segment
		(start 313.557412 -360.080052)
		(end 313.009026 -360.080052)
		(width 0.10668)
		(layer "F.Cu")
		(net "PVDDCR_CPU1_P0_OCP_N_R")
	)
	(segment
		(start 316.33795 -358.267)
		(end 316.33795 -359.283)
		(width 0.10668)
		(layer "F.Cu")
		(net "PVDDCR_CPU1_P0_OCP_N_R")
	)
	(segment
		(start 315.369702 -359.283)
		(end 315.087 -359.283)
		(width 0.10668)
		(layer "F.Cu")
		(net "PVDDCR_CPU1_P0_OCP_N_R")
	)
	(segment
		(start 315.087 -359.283)
		(end 314.579 -359.791)
		(width 0.10668)
		(layer "F.Cu")
		(net "PVDDCR_CPU1_P0_OCP_N_R")
	)
	(segment
		(start 314.579 -359.791)
		(end 313.846464 -359.791)
		(width 0.10668)
		(layer "F.Cu")
		(net "PVDDCR_CPU1_P0_OCP_N_R")
	)
	(segment
		(start 316.33795 -359.283)
		(end 315.369702 -359.283)
		(width 0.10668)
		(layer "F.Cu")
		(net "PVDDCR_CPU1_P0_OCP_N_R")
	)
	(segment
		(start 313.846464 -359.791)
		(end 313.557412 -360.080052)
		(width 0.10668)
		(layer "F.Cu")
		(net "PVDDCR_CPU1_P0_OCP_N_R")
	)
	(via
		(at 315.369702 -359.283)
		(size 0.762)
		(drill 0.381)
		(layers "F.Cu" "B.Cu")
		(net "PVDDCR_CPU1_P0_OCP_N_R")
	)
	(segment
		(start 320.749676 -358.267)
		(end 317.13805 -358.267)
		(width 0.10668)
		(layer "F.Cu")
		(net "PVDDCR_CPU1_P0_OCP_N")
	)
	(segment
		(start 322.844668 -360.361992)
		(end 320.749676 -358.267)
		(width 0.10668)
		(layer "F.Cu")
		(net "PVDDCR_CPU1_P0_OCP_N")
	)
	(via
		(at 389.784336 -118.635018)
		(size 0.508)
		(drill 0.254)
		(layers "F.Cu" "B.Cu")
		(net "PVDDCR_CPU1_P0_OCP_N")
	)
	(via
		(at 179.705 -98.262948)
		(size 0.508)
		(drill 0.254)
		(layers "F.Cu" "B.Cu")
		(net "PVDDCR_CPU1_P0_OCP_N")
	)
	(via
		(at 322.844668 -360.361992)
		(size 0.508)
		(drill 0.254)
		(layers "F.Cu" "B.Cu")
		(net "PVDDCR_CPU1_P0_OCP_N")
	)
	(segment
		(start 328.13625 -365.653574)
		(end 322.844668 -360.361992)
		(width 0.10668)
		(layer "B.Cu")
		(net "PVDDCR_CPU1_P0_OCP_N")
	)
	(segment
		(start 398.373092 -365.653574)
		(end 328.13625 -365.653574)
		(width 0.10668)
		(layer "B.Cu")
		(net "PVDDCR_CPU1_P0_OCP_N")
	)
	(segment
		(start 449.882514 -146.256248)
		(end 449.882514 -177.223928)
		(width 0.10668)
		(layer "B.Cu")
		(net "PVDDCR_CPU1_P0_OCP_N")
	)
	(segment
		(start 410.817314 -367.07191)
		(end 410.817314 -364.446312)
		(width 0.10668)
		(layer "B.Cu")
		(net "PVDDCR_CPU1_P0_OCP_N")
	)
	(segment
		(start 456.819508 -328.91857)
		(end 456.819508 -332.707234)
		(width 0.10668)
		(layer "B.Cu")
		(net "PVDDCR_CPU1_P0_OCP_N")
	)
	(segment
		(start 429.940466 -369.816888)
		(end 413.562292 -369.816888)
		(width 0.10668)
		(layer "B.Cu")
		(net "PVDDCR_CPU1_P0_OCP_N")
	)
	(segment
		(start 449.882514 -177.223928)
		(end 460.354934 -187.696348)
		(width 0.10668)
		(layer "B.Cu")
		(net "PVDDCR_CPU1_P0_OCP_N")
	)
	(segment
		(start 179.197 -99.634802)
		(end 179.197 -98.770948)
		(width 0.10668)
		(layer "B.Cu")
		(net "PVDDCR_CPU1_P0_OCP_N")
	)
	(segment
		(start 406.951434 -360.580432)
		(end 403.446234 -360.580432)
		(width 0.10668)
		(layer "B.Cu")
		(net "PVDDCR_CPU1_P0_OCP_N")
	)
	(segment
		(start 460.354934 -187.696348)
		(end 460.354934 -324.286626)
		(width 0.10668)
		(layer "B.Cu")
		(net "PVDDCR_CPU1_P0_OCP_N")
	)
	(segment
		(start 458.96403 -326.774048)
		(end 456.819508 -328.91857)
		(width 0.10668)
		(layer "B.Cu")
		(net "PVDDCR_CPU1_P0_OCP_N")
	)
	(segment
		(start 456.819508 -332.707234)
		(end 447.595498 -341.931244)
		(width 0.10668)
		(layer "B.Cu")
		(net "PVDDCR_CPU1_P0_OCP_N")
	)
	(segment
		(start 413.562292 -369.816888)
		(end 410.817314 -367.07191)
		(width 0.10668)
		(layer "B.Cu")
		(net "PVDDCR_CPU1_P0_OCP_N")
	)
	(segment
		(start 458.96403 -325.67753)
		(end 458.96403 -326.774048)
		(width 0.10668)
		(layer "B.Cu")
		(net "PVDDCR_CPU1_P0_OCP_N")
	)
	(segment
		(start 447.595498 -341.931244)
		(end 447.595498 -363.947202)
		(width 0.10668)
		(layer "B.Cu")
		(net "PVDDCR_CPU1_P0_OCP_N")
	)
	(segment
		(start 179.197 -98.770948)
		(end 179.705 -98.262948)
		(width 0.10668)
		(layer "B.Cu")
		(net "PVDDCR_CPU1_P0_OCP_N")
	)
	(segment
		(start 444.45809 -367.08461)
		(end 440.0423 -367.08461)
		(width 0.10668)
		(layer "B.Cu")
		(net "PVDDCR_CPU1_P0_OCP_N")
	)
	(segment
		(start 440.0423 -367.08461)
		(end 439.337958 -367.788952)
		(width 0.10668)
		(layer "B.Cu")
		(net "PVDDCR_CPU1_P0_OCP_N")
	)
	(segment
		(start 460.354934 -324.286626)
		(end 458.96403 -325.67753)
		(width 0.10668)
		(layer "B.Cu")
		(net "PVDDCR_CPU1_P0_OCP_N")
	)
	(segment
		(start 431.968402 -367.788952)
		(end 429.940466 -369.816888)
		(width 0.10668)
		(layer "B.Cu")
		(net "PVDDCR_CPU1_P0_OCP_N")
	)
	(segment
		(start 410.817314 -364.446312)
		(end 406.951434 -360.580432)
		(width 0.10668)
		(layer "B.Cu")
		(net "PVDDCR_CPU1_P0_OCP_N")
	)
	(segment
		(start 389.784336 -118.635018)
		(end 422.261284 -118.635018)
		(width 0.10668)
		(layer "B.Cu")
		(net "PVDDCR_CPU1_P0_OCP_N")
	)
	(segment
		(start 403.446234 -360.580432)
		(end 398.373092 -365.653574)
		(width 0.10668)
		(layer "B.Cu")
		(net "PVDDCR_CPU1_P0_OCP_N")
	)
	(segment
		(start 179.457096 -99.894898)
		(end 179.197 -99.634802)
		(width 0.10668)
		(layer "B.Cu")
		(net "PVDDCR_CPU1_P0_OCP_N")
	)
	(segment
		(start 422.261284 -118.635018)
		(end 449.882514 -146.256248)
		(width 0.10668)
		(layer "B.Cu")
		(net "PVDDCR_CPU1_P0_OCP_N")
	)
	(segment
		(start 179.705 -99.894898)
		(end 179.457096 -99.894898)
		(width 0.10668)
		(layer "B.Cu")
		(net "PVDDCR_CPU1_P0_OCP_N")
	)
	(segment
		(start 439.337958 -367.788952)
		(end 431.968402 -367.788952)
		(width 0.10668)
		(layer "B.Cu")
		(net "PVDDCR_CPU1_P0_OCP_N")
	)
	(segment
		(start 447.595498 -363.947202)
		(end 444.45809 -367.08461)
		(width 0.10668)
		(layer "B.Cu")
		(net "PVDDCR_CPU1_P0_OCP_N")
	)
	(segment
		(start 235.95203 -99.655122)
		(end 235.029502 -98.732594)
		(width 0.11684)
		(layer "In6.Cu")
		(net "PVDDCR_CPU1_P0_OCP_N")
	)
	(segment
		(start 319.656968 -102.165658)
		(end 318.537844 -102.165658)
		(width 0.11684)
		(layer "In6.Cu")
		(net "PVDDCR_CPU1_P0_OCP_N")
	)
	(segment
		(start 376.500644 -108.386372)
		(end 325.877682 -108.386372)
		(width 0.11684)
		(layer "In6.Cu")
		(net "PVDDCR_CPU1_P0_OCP_N")
	)
	(segment
		(start 182.231538 -93.590872)
		(end 182.231538 -96.267016)
		(width 0.11684)
		(layer "In6.Cu")
		(net "PVDDCR_CPU1_P0_OCP_N")
	)
	(segment
		(start 318.537844 -102.165658)
		(end 315.094874 -98.722688)
		(width 0.11684)
		(layer "In6.Cu")
		(net "PVDDCR_CPU1_P0_OCP_N")
	)
	(segment
		(start 256.920492 -98.580956)
		(end 252.62332 -98.580956)
		(width 0.11684)
		(layer "In6.Cu")
		(net "PVDDCR_CPU1_P0_OCP_N")
	)
	(segment
		(start 182.231538 -96.267016)
		(end 180.847746 -97.650808)
		(width 0.11684)
		(layer "In6.Cu")
		(net "PVDDCR_CPU1_P0_OCP_N")
	)
	(segment
		(start 252.62332 -98.580956)
		(end 251.549154 -99.655122)
		(width 0.11684)
		(layer "In6.Cu")
		(net "PVDDCR_CPU1_P0_OCP_N")
	)
	(segment
		(start 207.524604 -99.005644)
		(end 200.880726 -99.005644)
		(width 0.11684)
		(layer "In6.Cu")
		(net "PVDDCR_CPU1_P0_OCP_N")
	)
	(segment
		(start 275.193252 -96.561148)
		(end 273.917156 -95.285052)
		(width 0.11684)
		(layer "In6.Cu")
		(net "PVDDCR_CPU1_P0_OCP_N")
	)
	(segment
		(start 194.67703 -92.801948)
		(end 183.020462 -92.801948)
		(width 0.11684)
		(layer "In6.Cu")
		(net "PVDDCR_CPU1_P0_OCP_N")
	)
	(segment
		(start 325.877682 -108.386372)
		(end 319.656968 -102.165658)
		(width 0.11684)
		(layer "In6.Cu")
		(net "PVDDCR_CPU1_P0_OCP_N")
	)
	(segment
		(start 273.917156 -95.285052)
		(end 260.216396 -95.285052)
		(width 0.11684)
		(layer "In6.Cu")
		(net "PVDDCR_CPU1_P0_OCP_N")
	)
	(segment
		(start 180.31714 -97.650808)
		(end 179.705 -98.262948)
		(width 0.11684)
		(layer "In6.Cu")
		(net "PVDDCR_CPU1_P0_OCP_N")
	)
	(segment
		(start 281.522424 -98.722688)
		(end 279.360884 -96.561148)
		(width 0.11684)
		(layer "In6.Cu")
		(net "PVDDCR_CPU1_P0_OCP_N")
	)
	(segment
		(start 315.094874 -98.722688)
		(end 281.522424 -98.722688)
		(width 0.11684)
		(layer "In6.Cu")
		(net "PVDDCR_CPU1_P0_OCP_N")
	)
	(segment
		(start 183.020462 -92.801948)
		(end 182.231538 -93.590872)
		(width 0.11684)
		(layer "In6.Cu")
		(net "PVDDCR_CPU1_P0_OCP_N")
	)
	(segment
		(start 235.029502 -98.732594)
		(end 207.797654 -98.732594)
		(width 0.11684)
		(layer "In6.Cu")
		(net "PVDDCR_CPU1_P0_OCP_N")
	)
	(segment
		(start 200.880726 -99.005644)
		(end 194.67703 -92.801948)
		(width 0.11684)
		(layer "In6.Cu")
		(net "PVDDCR_CPU1_P0_OCP_N")
	)
	(segment
		(start 279.360884 -96.561148)
		(end 275.193252 -96.561148)
		(width 0.11684)
		(layer "In6.Cu")
		(net "PVDDCR_CPU1_P0_OCP_N")
	)
	(segment
		(start 260.216396 -95.285052)
		(end 256.920492 -98.580956)
		(width 0.11684)
		(layer "In6.Cu")
		(net "PVDDCR_CPU1_P0_OCP_N")
	)
	(segment
		(start 180.847746 -97.650808)
		(end 180.31714 -97.650808)
		(width 0.11684)
		(layer "In6.Cu")
		(net "PVDDCR_CPU1_P0_OCP_N")
	)
	(segment
		(start 207.797654 -98.732594)
		(end 207.524604 -99.005644)
		(width 0.11684)
		(layer "In6.Cu")
		(net "PVDDCR_CPU1_P0_OCP_N")
	)
	(segment
		(start 386.74929 -118.635018)
		(end 376.500644 -108.386372)
		(width 0.11684)
		(layer "In6.Cu")
		(net "PVDDCR_CPU1_P0_OCP_N")
	)
	(segment
		(start 251.549154 -99.655122)
		(end 235.95203 -99.655122)
		(width 0.11684)
		(layer "In6.Cu")
		(net "PVDDCR_CPU1_P0_OCP_N")
	)
	(segment
		(start 389.784336 -118.635018)
		(end 386.74929 -118.635018)
		(width 0.11684)
		(layer "In6.Cu")
		(net "PVDDCR_CPU1_P0_OCP_N")
	)
	(segment
		(start 350.203516 -343.612978)
		(end 350.203516 -343.996772)
		(width 0.127)
		(layer "F.Cu")
		(net "PVDDCR_CPU1_P0_LSET6")
	)
	(segment
		(start 350.203516 -344.90406)
		(end 349.961454 -345.146122)
		(width 0.127)
		(layer "F.Cu")
		(net "PVDDCR_CPU1_P0_LSET6")
	)
	(segment
		(start 350.203516 -343.996772)
		(end 350.203516 -344.90406)
		(width 0.127)
		(layer "F.Cu")
		(net "PVDDCR_CPU1_P0_LSET6")
	)
	(segment
		(start 350.576134 -343.24036)
		(end 350.203516 -343.612978)
		(width 0.127)
		(layer "F.Cu")
		(net "PVDDCR_CPU1_P0_LSET6")
	)
	(segment
		(start 350.576134 -342.834468)
		(end 350.576134 -343.24036)
		(width 0.127)
		(layer "F.Cu")
		(net "PVDDCR_CPU1_P0_LSET6")
	)
	(via
		(at 350.203516 -343.996772)
		(size 0.4064)
		(drill 0.2032)
		(layers "F.Cu" "B.Cu")
		(net "PVDDCR_CPU1_P0_LSET6")
	)
	(segment
		(start 341.927688 -338.702904)
		(end 341.927688 -339.125814)
		(width 0.127)
		(layer "F.Cu")
		(net "PVDDCR_CPU1_P0_LSET5")
	)
	(segment
		(start 341.927688 -339.125814)
		(end 341.927688 -339.993986)
		(width 0.127)
		(layer "F.Cu")
		(net "PVDDCR_CPU1_P0_LSET5")
	)
	(segment
		(start 342.300306 -338.330286)
		(end 341.927688 -338.702904)
		(width 0.127)
		(layer "F.Cu")
		(net "PVDDCR_CPU1_P0_LSET5")
	)
	(segment
		(start 341.927688 -339.993986)
		(end 341.685626 -340.236048)
		(width 0.127)
		(layer "F.Cu")
		(net "PVDDCR_CPU1_P0_LSET5")
	)
	(segment
		(start 342.300306 -337.924394)
		(end 342.300306 -338.330286)
		(width 0.127)
		(layer "F.Cu")
		(net "PVDDCR_CPU1_P0_LSET5")
	)
	(via
		(at 341.927688 -339.125814)
		(size 0.4064)
		(drill 0.2032)
		(layers "F.Cu" "B.Cu")
		(net "PVDDCR_CPU1_P0_LSET5")
	)
	(segment
		(start 307.233574 -350.811846)
		(end 307.233574 -351.68586)
		(width 0.127)
		(layer "F.Cu")
		(net "PVDDCR_CPU1_P0_LSET4")
	)
	(segment
		(start 307.233574 -351.68586)
		(end 306.991512 -351.927922)
		(width 0.127)
		(layer "F.Cu")
		(net "PVDDCR_CPU1_P0_LSET4")
	)
	(segment
		(start 307.233574 -350.394778)
		(end 307.233574 -350.811846)
		(width 0.127)
		(layer "F.Cu")
		(net "PVDDCR_CPU1_P0_LSET4")
	)
	(segment
		(start 307.606192 -350.02216)
		(end 307.233574 -350.394778)
		(width 0.127)
		(layer "F.Cu")
		(net "PVDDCR_CPU1_P0_LSET4")
	)
	(segment
		(start 307.606192 -349.616268)
		(end 307.606192 -350.02216)
		(width 0.127)
		(layer "F.Cu")
		(net "PVDDCR_CPU1_P0_LSET4")
	)
	(via
		(at 307.233574 -350.811846)
		(size 0.4064)
		(drill 0.2032)
		(layers "F.Cu" "B.Cu")
		(net "PVDDCR_CPU1_P0_LSET4")
	)
	(segment
		(start 317.255906 -338.301076)
		(end 316.883288 -338.673694)
		(width 0.127)
		(layer "F.Cu")
		(net "PVDDCR_CPU1_P0_LSET3")
	)
	(segment
		(start 317.255906 -337.895184)
		(end 317.255906 -338.301076)
		(width 0.127)
		(layer "F.Cu")
		(net "PVDDCR_CPU1_P0_LSET3")
	)
	(segment
		(start 316.883288 -338.673694)
		(end 316.883288 -339.113876)
		(width 0.127)
		(layer "F.Cu")
		(net "PVDDCR_CPU1_P0_LSET3")
	)
	(segment
		(start 316.883288 -339.113876)
		(end 316.883288 -339.964776)
		(width 0.127)
		(layer "F.Cu")
		(net "PVDDCR_CPU1_P0_LSET3")
	)
	(segment
		(start 316.883288 -339.964776)
		(end 316.641226 -340.206838)
		(width 0.127)
		(layer "F.Cu")
		(net "PVDDCR_CPU1_P0_LSET3")
	)
	(via
		(at 316.883288 -339.113876)
		(size 0.4064)
		(drill 0.2032)
		(layers "F.Cu" "B.Cu")
		(net "PVDDCR_CPU1_P0_LSET3")
	)
	(segment
		(start 325.238872 -339.957664)
		(end 324.99681 -340.199726)
		(width 0.127)
		(layer "F.Cu")
		(net "PVDDCR_CPU1_P0_LSET2")
	)
	(segment
		(start 325.238872 -338.666582)
		(end 325.238872 -339.090254)
		(width 0.127)
		(layer "F.Cu")
		(net "PVDDCR_CPU1_P0_LSET2")
	)
	(segment
		(start 325.61149 -337.888072)
		(end 325.61149 -338.293964)
		(width 0.127)
		(layer "F.Cu")
		(net "PVDDCR_CPU1_P0_LSET2")
	)
	(segment
		(start 325.238872 -339.090254)
		(end 325.238872 -339.957664)
		(width 0.127)
		(layer "F.Cu")
		(net "PVDDCR_CPU1_P0_LSET2")
	)
	(segment
		(start 325.61149 -338.293964)
		(end 325.238872 -338.666582)
		(width 0.127)
		(layer "F.Cu")
		(net "PVDDCR_CPU1_P0_LSET2")
	)
	(via
		(at 325.238872 -339.090254)
		(size 0.4064)
		(drill 0.2032)
		(layers "F.Cu" "B.Cu")
		(net "PVDDCR_CPU1_P0_LSET2")
	)
	(segment
		(start 333.596488 -339.066378)
		(end 333.596488 -339.943186)
		(width 0.127)
		(layer "F.Cu")
		(net "PVDDCR_CPU1_P0_LSET1")
	)
	(segment
		(start 333.969106 -337.873594)
		(end 333.969106 -338.279486)
		(width 0.127)
		(layer "F.Cu")
		(net "PVDDCR_CPU1_P0_LSET1")
	)
	(segment
		(start 333.596488 -338.652104)
		(end 333.596488 -339.066378)
		(width 0.127)
		(layer "F.Cu")
		(net "PVDDCR_CPU1_P0_LSET1")
	)
	(segment
		(start 333.596488 -339.943186)
		(end 333.354426 -340.185248)
		(width 0.127)
		(layer "F.Cu")
		(net "PVDDCR_CPU1_P0_LSET1")
	)
	(segment
		(start 333.969106 -338.279486)
		(end 333.596488 -338.652104)
		(width 0.127)
		(layer "F.Cu")
		(net "PVDDCR_CPU1_P0_LSET1")
	)
	(via
		(at 333.596488 -339.066378)
		(size 0.4064)
		(drill 0.2032)
		(layers "F.Cu" "B.Cu")
		(net "PVDDCR_CPU1_P0_LSET1")
	)
	(segment
		(start 350.126046 -342.834468)
		(end 350.126046 -343.210388)
		(width 0.2286)
		(layer "F.Cu")
		(net "PVDDCR_CPU1_P0_IMON6")
	)
	(segment
		(start 350.126046 -343.210388)
		(end 349.688912 -343.647522)
		(width 0.2286)
		(layer "F.Cu")
		(net "PVDDCR_CPU1_P0_IMON6")
	)
	(segment
		(start 310.733948 -355.635052)
		(end 310.733948 -357.804974)
		(width 0.1778)
		(layer "F.Cu")
		(net "PVDDCR_CPU1_P0_IMON6")
	)
	(segment
		(start 313.7916 -353.3648)
		(end 313.0042 -353.3648)
		(width 0.1778)
		(layer "F.Cu")
		(net "PVDDCR_CPU1_P0_IMON6")
	)
	(segment
		(start 349.688912 -343.647522)
		(end 349.688912 -343.754964)
		(width 0.2286)
		(layer "F.Cu")
		(net "PVDDCR_CPU1_P0_IMON6")
	)
	(segment
		(start 313.0042 -353.3648)
		(end 310.733948 -355.635052)
		(width 0.1778)
		(layer "F.Cu")
		(net "PVDDCR_CPU1_P0_IMON6")
	)
	(segment
		(start 349.688912 -343.754964)
		(end 349.700596 -343.754964)
		(width 0.2286)
		(layer "F.Cu")
		(net "PVDDCR_CPU1_P0_IMON6")
	)
	(via
		(at 313.7916 -353.3648)
		(size 0.508)
		(drill 0.254)
		(layers "F.Cu" "B.Cu")
		(net "PVDDCR_CPU1_P0_IMON6")
	)
	(via
		(at 349.700596 -343.754964)
		(size 0.508)
		(drill 0.254)
		(layers "F.Cu" "B.Cu")
		(net "PVDDCR_CPU1_P0_IMON6")
	)
	(segment
		(start 349.005652 -344.351102)
		(end 349.60179 -343.754964)
		(width 0.254)
		(layer "In11.Cu")
		(net "PVDDCR_CPU1_P0_IMON6")
	)
	(segment
		(start 313.9186 -353.2378)
		(end 313.9186 -352.2472)
		(width 0.254)
		(layer "In11.Cu")
		(net "PVDDCR_CPU1_P0_IMON6")
	)
	(segment
		(start 349.60179 -343.754964)
		(end 349.700596 -343.754964)
		(width 0.254)
		(layer "In11.Cu")
		(net "PVDDCR_CPU1_P0_IMON6")
	)
	(segment
		(start 327.872344 -342.777572)
		(end 343.747344 -342.777572)
		(width 0.254)
		(layer "In11.Cu")
		(net "PVDDCR_CPU1_P0_IMON6")
	)
	(segment
		(start 319.037716 -351.6122)
		(end 327.872344 -342.777572)
		(width 0.254)
		(layer "In11.Cu")
		(net "PVDDCR_CPU1_P0_IMON6")
	)
	(segment
		(start 348.751652 -345.805252)
		(end 349.005652 -345.551252)
		(width 0.254)
		(layer "In11.Cu")
		(net "PVDDCR_CPU1_P0_IMON6")
	)
	(segment
		(start 314.5536 -351.6122)
		(end 319.037716 -351.6122)
		(width 0.254)
		(layer "In11.Cu")
		(net "PVDDCR_CPU1_P0_IMON6")
	)
	(segment
		(start 349.005652 -345.551252)
		(end 349.005652 -344.351102)
		(width 0.254)
		(layer "In11.Cu")
		(net "PVDDCR_CPU1_P0_IMON6")
	)
	(segment
		(start 313.7916 -353.3648)
		(end 313.9186 -353.2378)
		(width 0.254)
		(layer "In11.Cu")
		(net "PVDDCR_CPU1_P0_IMON6")
	)
	(segment
		(start 343.747344 -342.777572)
		(end 346.775024 -345.805252)
		(width 0.254)
		(layer "In11.Cu")
		(net "PVDDCR_CPU1_P0_IMON6")
	)
	(segment
		(start 313.9186 -352.2472)
		(end 314.5536 -351.6122)
		(width 0.254)
		(layer "In11.Cu")
		(net "PVDDCR_CPU1_P0_IMON6")
	)
	(segment
		(start 346.775024 -345.805252)
		(end 348.751652 -345.805252)
		(width 0.254)
		(layer "In11.Cu")
		(net "PVDDCR_CPU1_P0_IMON6")
	)
	(segment
		(start 310.9468 -354.7364)
		(end 310.333898 -355.349302)
		(width 0.1778)
		(layer "F.Cu")
		(net "PVDDCR_CPU1_P0_IMON5")
	)
	(segment
		(start 341.850218 -337.924394)
		(end 341.850218 -338.300314)
		(width 0.2286)
		(layer "F.Cu")
		(net "PVDDCR_CPU1_P0_IMON5")
	)
	(segment
		(start 341.850218 -338.300314)
		(end 341.413084 -338.737448)
		(width 0.2286)
		(layer "F.Cu")
		(net "PVDDCR_CPU1_P0_IMON5")
	)
	(segment
		(start 310.333898 -355.349302)
		(end 310.333898 -357.804974)
		(width 0.1778)
		(layer "F.Cu")
		(net "PVDDCR_CPU1_P0_IMON5")
	)
	(segment
		(start 341.413084 -338.84489)
		(end 341.424768 -338.84489)
		(width 0.2286)
		(layer "F.Cu")
		(net "PVDDCR_CPU1_P0_IMON5")
	)
	(segment
		(start 341.413084 -338.737448)
		(end 341.413084 -338.84489)
		(width 0.2286)
		(layer "F.Cu")
		(net "PVDDCR_CPU1_P0_IMON5")
	)
	(segment
		(start 310.9468 -353.949)
		(end 310.9468 -354.7364)
		(width 0.1778)
		(layer "F.Cu")
		(net "PVDDCR_CPU1_P0_IMON5")
	)
	(via
		(at 310.9468 -353.949)
		(size 0.762)
		(drill 0.254)
		(layers "F.Cu" "B.Cu")
		(net "PVDDCR_CPU1_P0_IMON5")
	)
	(via
		(at 341.424768 -338.84489)
		(size 0.508)
		(drill 0.254)
		(layers "F.Cu" "B.Cu")
		(net "PVDDCR_CPU1_P0_IMON5")
	)
	(segment
		(start 311.15 -353.7458)
		(end 310.9468 -353.949)
		(width 0.254)
		(layer "In11.Cu")
		(net "PVDDCR_CPU1_P0_IMON5")
	)
	(segment
		(start 341.325454 -338.84489)
		(end 340.729824 -339.44052)
		(width 0.254)
		(layer "In11.Cu")
		(net "PVDDCR_CPU1_P0_IMON5")
	)
	(segment
		(start 340.021164 -341.405972)
		(end 326.681084 -341.405972)
		(width 0.254)
		(layer "In11.Cu")
		(net "PVDDCR_CPU1_P0_IMON5")
	)
	(segment
		(start 340.729824 -340.697312)
		(end 340.021164 -341.405972)
		(width 0.254)
		(layer "In11.Cu")
		(net "PVDDCR_CPU1_P0_IMON5")
	)
	(segment
		(start 326.681084 -341.405972)
		(end 317.795656 -350.2914)
		(width 0.254)
		(layer "In11.Cu")
		(net "PVDDCR_CPU1_P0_IMON5")
	)
	(segment
		(start 311.15 -352.9584)
		(end 311.15 -353.7458)
		(width 0.254)
		(layer "In11.Cu")
		(net "PVDDCR_CPU1_P0_IMON5")
	)
	(segment
		(start 341.424768 -338.84489)
		(end 341.325454 -338.84489)
		(width 0.254)
		(layer "In11.Cu")
		(net "PVDDCR_CPU1_P0_IMON5")
	)
	(segment
		(start 313.817 -350.2914)
		(end 311.15 -352.9584)
		(width 0.254)
		(layer "In11.Cu")
		(net "PVDDCR_CPU1_P0_IMON5")
	)
	(segment
		(start 340.729824 -339.44052)
		(end 340.729824 -340.697312)
		(width 0.254)
		(layer "In11.Cu")
		(net "PVDDCR_CPU1_P0_IMON5")
	)
	(segment
		(start 317.795656 -350.2914)
		(end 313.817 -350.2914)
		(width 0.254)
		(layer "In11.Cu")
		(net "PVDDCR_CPU1_P0_IMON5")
	)
	(segment
		(start 307.156104 -349.992188)
		(end 306.71897 -350.429322)
		(width 0.2286)
		(layer "F.Cu")
		(net "PVDDCR_CPU1_P0_IMON4")
	)
	(segment
		(start 309.753 -355.854)
		(end 309.934102 -356.035102)
		(width 0.1778)
		(layer "F.Cu")
		(net "PVDDCR_CPU1_P0_IMON4")
	)
	(segment
		(start 307.156104 -349.616268)
		(end 307.156104 -349.992188)
		(width 0.2286)
		(layer "F.Cu")
		(net "PVDDCR_CPU1_P0_IMON4")
	)
	(segment
		(start 306.71897 -350.429322)
		(end 306.71897 -350.536764)
		(width 0.2286)
		(layer "F.Cu")
		(net "PVDDCR_CPU1_P0_IMON4")
	)
	(segment
		(start 306.71897 -350.536764)
		(end 306.730654 -350.536764)
		(width 0.2286)
		(layer "F.Cu")
		(net "PVDDCR_CPU1_P0_IMON4")
	)
	(segment
		(start 309.753 -355.3206)
		(end 309.753 -355.854)
		(width 0.1778)
		(layer "F.Cu")
		(net "PVDDCR_CPU1_P0_IMON4")
	)
	(segment
		(start 309.934102 -356.035102)
		(end 309.934102 -357.804974)
		(width 0.1778)
		(layer "F.Cu")
		(net "PVDDCR_CPU1_P0_IMON4")
	)
	(via
		(at 309.753 -355.3206)
		(size 0.508)
		(drill 0.254)
		(layers "F.Cu" "B.Cu")
		(net "PVDDCR_CPU1_P0_IMON4")
	)
	(via
		(at 306.730654 -350.536764)
		(size 0.508)
		(drill 0.254)
		(layers "F.Cu" "B.Cu")
		(net "PVDDCR_CPU1_P0_IMON4")
	)
	(segment
		(start 309.753 -355.3206)
		(end 309.753 -354.979986)
		(width 0.254)
		(layer "In11.Cu")
		(net "PVDDCR_CPU1_P0_IMON4")
	)
	(segment
		(start 309.753 -354.979986)
		(end 307.585618 -352.812604)
		(width 0.254)
		(layer "In11.Cu")
		(net "PVDDCR_CPU1_P0_IMON4")
	)
	(segment
		(start 306.021486 -352.086672)
		(end 306.021486 -351.066608)
		(width 0.254)
		(layer "In11.Cu")
		(net "PVDDCR_CPU1_P0_IMON4")
	)
	(segment
		(start 307.585618 -352.812604)
		(end 306.747418 -352.812604)
		(width 0.254)
		(layer "In11.Cu")
		(net "PVDDCR_CPU1_P0_IMON4")
	)
	(segment
		(start 306.55133 -350.536764)
		(end 306.730654 -350.536764)
		(width 0.254)
		(layer "In11.Cu")
		(net "PVDDCR_CPU1_P0_IMON4")
	)
	(segment
		(start 306.747418 -352.812604)
		(end 306.021486 -352.086672)
		(width 0.254)
		(layer "In11.Cu")
		(net "PVDDCR_CPU1_P0_IMON4")
	)
	(segment
		(start 306.021486 -351.066608)
		(end 306.55133 -350.536764)
		(width 0.254)
		(layer "In11.Cu")
		(net "PVDDCR_CPU1_P0_IMON4")
	)
	(segment
		(start 309.7911 -353.5807)
		(end 309.1942 -354.1776)
		(width 0.1778)
		(layer "F.Cu")
		(net "PVDDCR_CPU1_P0_IMON3")
	)
	(segment
		(start 316.368684 -338.708238)
		(end 316.368684 -338.81568)
		(width 0.2286)
		(layer "F.Cu")
		(net "PVDDCR_CPU1_P0_IMON3")
	)
	(segment
		(start 316.368684 -338.81568)
		(end 316.380368 -338.81568)
		(width 0.2286)
		(layer "F.Cu")
		(net "PVDDCR_CPU1_P0_IMON3")
	)
	(segment
		(start 316.805818 -337.895184)
		(end 316.805818 -338.271104)
		(width 0.2286)
		(layer "F.Cu")
		(net "PVDDCR_CPU1_P0_IMON3")
	)
	(segment
		(start 316.805818 -338.271104)
		(end 316.368684 -338.708238)
		(width 0.2286)
		(layer "F.Cu")
		(net "PVDDCR_CPU1_P0_IMON3")
	)
	(segment
		(start 309.1942 -356.1334)
		(end 309.534052 -356.473252)
		(width 0.1778)
		(layer "F.Cu")
		(net "PVDDCR_CPU1_P0_IMON3")
	)
	(segment
		(start 309.534052 -356.473252)
		(end 309.534052 -357.804974)
		(width 0.1778)
		(layer "F.Cu")
		(net "PVDDCR_CPU1_P0_IMON3")
	)
	(segment
		(start 309.1942 -354.1776)
		(end 309.1942 -356.1334)
		(width 0.1778)
		(layer "F.Cu")
		(net "PVDDCR_CPU1_P0_IMON3")
	)
	(via
		(at 309.7911 -353.5807)
		(size 0.508)
		(drill 0.254)
		(layers "F.Cu" "B.Cu")
		(net "PVDDCR_CPU1_P0_IMON3")
	)
	(via
		(at 316.380368 -338.81568)
		(size 0.508)
		(drill 0.254)
		(layers "F.Cu" "B.Cu")
		(net "PVDDCR_CPU1_P0_IMON3")
	)
	(segment
		(start 315.87059 -340.759542)
		(end 315.87059 -339.146134)
		(width 0.254)
		(layer "In6.Cu")
		(net "PVDDCR_CPU1_P0_IMON3")
	)
	(segment
		(start 312.6486 -351.4852)
		(end 313.759088 -350.374712)
		(width 0.254)
		(layer "In6.Cu")
		(net "PVDDCR_CPU1_P0_IMON3")
	)
	(segment
		(start 313.759088 -342.871044)
		(end 315.87059 -340.759542)
		(width 0.254)
		(layer "In6.Cu")
		(net "PVDDCR_CPU1_P0_IMON3")
	)
	(segment
		(start 313.759088 -350.374712)
		(end 313.759088 -342.871044)
		(width 0.254)
		(layer "In6.Cu")
		(net "PVDDCR_CPU1_P0_IMON3")
	)
	(segment
		(start 311.8866 -351.4852)
		(end 312.6486 -351.4852)
		(width 0.254)
		(layer "In6.Cu")
		(net "PVDDCR_CPU1_P0_IMON3")
	)
	(segment
		(start 309.7911 -353.5807)
		(end 311.8866 -351.4852)
		(width 0.254)
		(layer "In6.Cu")
		(net "PVDDCR_CPU1_P0_IMON3")
	)
	(segment
		(start 315.87059 -339.146134)
		(end 316.201044 -338.81568)
		(width 0.254)
		(layer "In6.Cu")
		(net "PVDDCR_CPU1_P0_IMON3")
	)
	(segment
		(start 316.201044 -338.81568)
		(end 316.380368 -338.81568)
		(width 0.254)
		(layer "In6.Cu")
		(net "PVDDCR_CPU1_P0_IMON3")
	)
	(segment
		(start 312.1152 -353.3902)
		(end 311.8104 -353.0854)
		(width 0.1778)
		(layer "F.Cu")
		(net "PVDDCR_CPU1_P0_IMON2")
	)
	(segment
		(start 309.134002 -356.759002)
		(end 309.134002 -357.804974)
		(width 0.1778)
		(layer "F.Cu")
		(net "PVDDCR_CPU1_P0_IMON2")
	)
	(segment
		(start 309.5752 -353.0854)
		(end 308.7116 -353.949)
		(width 0.1778)
		(layer "F.Cu")
		(net "PVDDCR_CPU1_P0_IMON2")
	)
	(segment
		(start 325.161402 -338.263992)
		(end 324.724268 -338.701126)
		(width 0.2286)
		(layer "F.Cu")
		(net "PVDDCR_CPU1_P0_IMON2")
	)
	(segment
		(start 311.8104 -353.0854)
		(end 309.5752 -353.0854)
		(width 0.1778)
		(layer "F.Cu")
		(net "PVDDCR_CPU1_P0_IMON2")
	)
	(segment
		(start 308.7116 -353.949)
		(end 308.7116 -356.3366)
		(width 0.1778)
		(layer "F.Cu")
		(net "PVDDCR_CPU1_P0_IMON2")
	)
	(segment
		(start 308.7116 -356.3366)
		(end 309.134002 -356.759002)
		(width 0.1778)
		(layer "F.Cu")
		(net "PVDDCR_CPU1_P0_IMON2")
	)
	(segment
		(start 325.161402 -337.888072)
		(end 325.161402 -338.263992)
		(width 0.2286)
		(layer "F.Cu")
		(net "PVDDCR_CPU1_P0_IMON2")
	)
	(segment
		(start 324.724268 -338.701126)
		(end 324.724268 -338.808568)
		(width 0.2286)
		(layer "F.Cu")
		(net "PVDDCR_CPU1_P0_IMON2")
	)
	(segment
		(start 324.724268 -338.808568)
		(end 324.735952 -338.808568)
		(width 0.2286)
		(layer "F.Cu")
		(net "PVDDCR_CPU1_P0_IMON2")
	)
	(via
		(at 312.1152 -353.3902)
		(size 0.508)
		(drill 0.254)
		(layers "F.Cu" "B.Cu")
		(net "PVDDCR_CPU1_P0_IMON2")
	)
	(via
		(at 324.735952 -338.808568)
		(size 0.508)
		(drill 0.254)
		(layers "F.Cu" "B.Cu")
		(net "PVDDCR_CPU1_P0_IMON2")
	)
	(segment
		(start 321.923664 -346.573348)
		(end 321.923664 -343.272872)
		(width 0.254)
		(layer "In6.Cu")
		(net "PVDDCR_CPU1_P0_IMON2")
	)
	(segment
		(start 323.927724 -341.268812)
		(end 323.927724 -339.509608)
		(width 0.254)
		(layer "In6.Cu")
		(net "PVDDCR_CPU1_P0_IMON2")
	)
	(segment
		(start 312.338212 -353.3902)
		(end 314.446412 -351.282)
		(width 0.254)
		(layer "In6.Cu")
		(net "PVDDCR_CPU1_P0_IMON2")
	)
	(segment
		(start 314.446412 -351.282)
		(end 317.215012 -351.282)
		(width 0.254)
		(layer "In6.Cu")
		(net "PVDDCR_CPU1_P0_IMON2")
	)
	(segment
		(start 317.215012 -351.282)
		(end 321.923664 -346.573348)
		(width 0.254)
		(layer "In6.Cu")
		(net "PVDDCR_CPU1_P0_IMON2")
	)
	(segment
		(start 321.923664 -343.272872)
		(end 323.927724 -341.268812)
		(width 0.254)
		(layer "In6.Cu")
		(net "PVDDCR_CPU1_P0_IMON2")
	)
	(segment
		(start 324.628764 -338.808568)
		(end 324.735952 -338.808568)
		(width 0.254)
		(layer "In6.Cu")
		(net "PVDDCR_CPU1_P0_IMON2")
	)
	(segment
		(start 312.1152 -353.3902)
		(end 312.338212 -353.3902)
		(width 0.254)
		(layer "In6.Cu")
		(net "PVDDCR_CPU1_P0_IMON2")
	)
	(segment
		(start 323.927724 -339.509608)
		(end 324.628764 -338.808568)
		(width 0.254)
		(layer "In6.Cu")
		(net "PVDDCR_CPU1_P0_IMON2")
	)
	(segment
		(start 308.2798 -353.7204)
		(end 308.2798 -356.489)
		(width 0.1778)
		(layer "F.Cu")
		(net "PVDDCR_CPU1_P0_IMON1")
	)
	(segment
		(start 309.3212 -352.679)
		(end 308.2798 -353.7204)
		(width 0.1778)
		(layer "F.Cu")
		(net "PVDDCR_CPU1_P0_IMON1")
	)
	(segment
		(start 333.081884 -338.686648)
		(end 333.081884 -338.79409)
		(width 0.2286)
		(layer "F.Cu")
		(net "PVDDCR_CPU1_P0_IMON1")
	)
	(segment
		(start 314.6552 -352.679)
		(end 309.3212 -352.679)
		(width 0.1778)
		(layer "F.Cu")
		(net "PVDDCR_CPU1_P0_IMON1")
	)
	(segment
		(start 333.519018 -338.249514)
		(end 333.081884 -338.686648)
		(width 0.2286)
		(layer "F.Cu")
		(net "PVDDCR_CPU1_P0_IMON1")
	)
	(segment
		(start 308.733952 -356.943152)
		(end 308.733952 -357.804974)
		(width 0.1778)
		(layer "F.Cu")
		(net "PVDDCR_CPU1_P0_IMON1")
	)
	(segment
		(start 333.081884 -338.79409)
		(end 333.093568 -338.79409)
		(width 0.2286)
		(layer "F.Cu")
		(net "PVDDCR_CPU1_P0_IMON1")
	)
	(segment
		(start 314.9092 -352.933)
		(end 314.6552 -352.679)
		(width 0.1778)
		(layer "F.Cu")
		(net "PVDDCR_CPU1_P0_IMON1")
	)
	(segment
		(start 333.519018 -337.873594)
		(end 333.519018 -338.249514)
		(width 0.2286)
		(layer "F.Cu")
		(net "PVDDCR_CPU1_P0_IMON1")
	)
	(segment
		(start 308.2798 -356.489)
		(end 308.733952 -356.943152)
		(width 0.1778)
		(layer "F.Cu")
		(net "PVDDCR_CPU1_P0_IMON1")
	)
	(via
		(at 333.093568 -338.79409)
		(size 0.508)
		(drill 0.254)
		(layers "F.Cu" "B.Cu")
		(net "PVDDCR_CPU1_P0_IMON1")
	)
	(via
		(at 314.9092 -352.933)
		(size 0.762)
		(drill 0.254)
		(layers "F.Cu" "B.Cu")
		(net "PVDDCR_CPU1_P0_IMON1")
	)
	(segment
		(start 315.0616 -353.0854)
		(end 317.773812 -353.0854)
		(width 0.254)
		(layer "In6.Cu")
		(net "PVDDCR_CPU1_P0_IMON1")
	)
	(segment
		(start 323.721984 -347.137228)
		(end 323.721984 -344.939112)
		(width 0.254)
		(layer "In6.Cu")
		(net "PVDDCR_CPU1_P0_IMON1")
	)
	(segment
		(start 331.697584 -341.334852)
		(end 332.555088 -340.477348)
		(width 0.254)
		(layer "In6.Cu")
		(net "PVDDCR_CPU1_P0_IMON1")
	)
	(segment
		(start 317.773812 -353.0854)
		(end 323.721984 -347.137228)
		(width 0.254)
		(layer "In6.Cu")
		(net "PVDDCR_CPU1_P0_IMON1")
	)
	(segment
		(start 332.555088 -340.477348)
		(end 332.555088 -339.19287)
		(width 0.254)
		(layer "In6.Cu")
		(net "PVDDCR_CPU1_P0_IMON1")
	)
	(segment
		(start 332.953868 -338.79409)
		(end 333.093568 -338.79409)
		(width 0.254)
		(layer "In6.Cu")
		(net "PVDDCR_CPU1_P0_IMON1")
	)
	(segment
		(start 332.555088 -339.19287)
		(end 332.953868 -338.79409)
		(width 0.254)
		(layer "In6.Cu")
		(net "PVDDCR_CPU1_P0_IMON1")
	)
	(segment
		(start 327.326244 -341.334852)
		(end 331.697584 -341.334852)
		(width 0.254)
		(layer "In6.Cu")
		(net "PVDDCR_CPU1_P0_IMON1")
	)
	(segment
		(start 314.9092 -352.933)
		(end 315.0616 -353.0854)
		(width 0.254)
		(layer "In6.Cu")
		(net "PVDDCR_CPU1_P0_IMON1")
	)
	(segment
		(start 323.721984 -344.939112)
		(end 327.326244 -341.334852)
		(width 0.254)
		(layer "In6.Cu")
		(net "PVDDCR_CPU1_P0_IMON1")
	)
	(segment
		(start 306.519326 -361.279948)
		(end 305.412394 -362.38688)
		(width 0.10668)
		(layer "F.Cu")
		(net "PVDDCR_CPU1_P0_EN_R")
	)
	(segment
		(start 305.412394 -362.56214)
		(end 305.135534 -362.839)
		(width 0.10668)
		(layer "F.Cu")
		(net "PVDDCR_CPU1_P0_EN_R")
	)
	(segment
		(start 305.135534 -362.839)
		(end 304.81905 -362.839)
		(width 0.10668)
		(layer "F.Cu")
		(net "PVDDCR_CPU1_P0_EN_R")
	)
	(segment
		(start 307.258974 -361.279948)
		(end 306.519326 -361.279948)
		(width 0.10668)
		(layer "F.Cu")
		(net "PVDDCR_CPU1_P0_EN_R")
	)
	(segment
		(start 305.412394 -362.38688)
		(end 305.412394 -362.56214)
		(width 0.10668)
		(layer "F.Cu")
		(net "PVDDCR_CPU1_P0_EN_R")
	)
	(via
		(at 305.412394 -362.56214)
		(size 0.508)
		(drill 0.254)
		(layers "F.Cu" "B.Cu")
		(net "PVDDCR_CPU1_P0_EN_R")
	)
	(segment
		(start 304.81905 -361.696)
		(end 304.81905 -361.968796)
		(width 0.10668)
		(layer "B.Cu")
		(net "PVDDCR_CPU1_P0_EN_R")
	)
	(segment
		(start 304.81905 -361.968796)
		(end 305.412394 -362.56214)
		(width 0.10668)
		(layer "B.Cu")
		(net "PVDDCR_CPU1_P0_EN_R")
	)
	(segment
		(start 313.784996 -360.480102)
		(end 313.862466 -360.402632)
		(width 0.10668)
		(layer "F.Cu")
		(net "PVDDCR_CPU1_P0_EN1_ADDR_CFG")
	)
	(segment
		(start 296.681398 -367.03)
		(end 295.509188 -367.03)
		(width 0.10668)
		(layer "F.Cu")
		(net "PVDDCR_CPU1_P0_EN1_ADDR_CFG")
	)
	(segment
		(start 313.009026 -360.480102)
		(end 313.784996 -360.480102)
		(width 0.10668)
		(layer "F.Cu")
		(net "PVDDCR_CPU1_P0_EN1_ADDR_CFG")
	)
	(via
		(at 295.509188 -367.03)
		(size 0.508)
		(drill 0.254)
		(layers "F.Cu" "B.Cu")
		(net "PVDDCR_CPU1_P0_EN1_ADDR_CFG")
	)
	(via
		(at 313.862466 -360.402632)
		(size 0.508)
		(drill 0.254)
		(layers "F.Cu" "B.Cu")
		(net "PVDDCR_CPU1_P0_EN1_ADDR_CFG")
	)
	(segment
		(start 299.176948 -365.42345)
		(end 297.115738 -365.42345)
		(width 0.10668)
		(layer "B.Cu")
		(net "PVDDCR_CPU1_P0_EN1_ADDR_CFG")
	)
	(segment
		(start 313.862466 -360.045)
		(end 313.862466 -360.402632)
		(width 0.10668)
		(layer "B.Cu")
		(net "PVDDCR_CPU1_P0_EN1_ADDR_CFG")
	)
	(segment
		(start 301.201582 -363.398816)
		(end 299.176948 -365.42345)
		(width 0.10668)
		(layer "B.Cu")
		(net "PVDDCR_CPU1_P0_EN1_ADDR_CFG")
	)
	(segment
		(start 304.11801 -363.398816)
		(end 301.201582 -363.398816)
		(width 0.10668)
		(layer "B.Cu")
		(net "PVDDCR_CPU1_P0_EN1_ADDR_CFG")
	)
	(segment
		(start 306.383944 -363.308646)
		(end 306.243482 -363.168184)
		(width 0.10668)
		(layer "B.Cu")
		(net "PVDDCR_CPU1_P0_EN1_ADDR_CFG")
	)
	(segment
		(start 297.115738 -365.42345)
		(end 295.509188 -367.03)
		(width 0.10668)
		(layer "B.Cu")
		(net "PVDDCR_CPU1_P0_EN1_ADDR_CFG")
	)
	(segment
		(start 304.348642 -363.168184)
		(end 304.11801 -363.398816)
		(width 0.10668)
		(layer "B.Cu")
		(net "PVDDCR_CPU1_P0_EN1_ADDR_CFG")
	)
	(segment
		(start 312.94705 -359.918)
		(end 313.735466 -359.918)
		(width 0.10668)
		(layer "B.Cu")
		(net "PVDDCR_CPU1_P0_EN1_ADDR_CFG")
	)
	(segment
		(start 312.477658 -363.308646)
		(end 306.383944 -363.308646)
		(width 0.10668)
		(layer "B.Cu")
		(net "PVDDCR_CPU1_P0_EN1_ADDR_CFG")
	)
	(segment
		(start 313.735466 -359.918)
		(end 313.862466 -360.045)
		(width 0.10668)
		(layer "B.Cu")
		(net "PVDDCR_CPU1_P0_EN1_ADDR_CFG")
	)
	(segment
		(start 312.94705 -362.839254)
		(end 312.477658 -363.308646)
		(width 0.10668)
		(layer "B.Cu")
		(net "PVDDCR_CPU1_P0_EN1_ADDR_CFG")
	)
	(segment
		(start 312.94705 -359.918)
		(end 312.94705 -362.839254)
		(width 0.10668)
		(layer "B.Cu")
		(net "PVDDCR_CPU1_P0_EN1_ADDR_CFG")
	)
	(segment
		(start 306.243482 -363.168184)
		(end 304.348642 -363.168184)
		(width 0.10668)
		(layer "B.Cu")
		(net "PVDDCR_CPU1_P0_EN1_ADDR_CFG")
	)
	(segment
		(start 342.158066 -294.88003)
		(end 341.691214 -295.145968)
		(width 0.350012)
		(layer "F.Cu")
		(net "PVDDCR_CPU1_P0")
	)
	(segment
		(start 351.557844 -268.960092)
		(end 351.091246 -269.22603)
		(width 0.350012)
		(layer "F.Cu")
		(net "PVDDCR_CPU1_P0")
	)
	(segment
		(start 367.538 -272.200116)
		(end 368.004852 -272.466054)
		(width 0.350012)
		(layer "F.Cu")
		(net "PVDDCR_CPU1_P0")
	)
	(segment
		(start 355.31806 -290.019994)
		(end 354.851208 -290.285932)
		(width 0.350012)
		(layer "F.Cu")
		(net "PVDDCR_CPU1_P0")
	)
	(segment
		(start 369.888008 -268.150086)
		(end 370.35486 -268.416024)
		(width 0.350012)
		(layer "F.Cu")
		(net "PVDDCR_CPU1_P0")
	)
	(segment
		(start 346.858082 -272.200116)
		(end 346.39123 -272.466054)
		(width 0.350012)
		(layer "F.Cu")
		(net "PVDDCR_CPU1_P0")
	)
	(segment
		(start 369.417854 -267.34008)
		(end 369.884706 -267.606018)
		(width 0.350012)
		(layer "F.Cu")
		(net "PVDDCR_CPU1_P0")
	)
	(segment
		(start 372.238016 -294.88003)
		(end 372.704868 -295.145968)
		(width 0.350012)
		(layer "F.Cu")
		(net "PVDDCR_CPU1_P0")
	)
	(segment
		(start 349.67799 -275.44014)
		(end 349.211138 -275.706078)
		(width 0.350012)
		(layer "F.Cu")
		(net "PVDDCR_CPU1_P0")
	)
	(segment
		(start 364.247938 -268.150086)
		(end 364.71479 -268.416024)
		(width 0.350012)
		(layer "F.Cu")
		(net "PVDDCR_CPU1_P0")
	)
	(segment
		(start 367.538 -283.5402)
		(end 368.004852 -283.806138)
		(width 0.350012)
		(layer "F.Cu")
		(net "PVDDCR_CPU1_P0")
	)
	(segment
		(start 345.918028 -294.88003)
		(end 345.451176 -295.145968)
		(width 0.350012)
		(layer "F.Cu")
		(net "PVDDCR_CPU1_P0")
	)
	(segment
		(start 355.31806 -267.34008)
		(end 354.851208 -267.606018)
		(width 0.350012)
		(layer "F.Cu")
		(net "PVDDCR_CPU1_P0")
	)
	(segment
		(start 365.657892 -286.780224)
		(end 366.124744 -287.045908)
		(width 0.350012)
		(layer "F.Cu")
		(net "PVDDCR_CPU1_P0")
	)
	(segment
		(start 355.31806 -278.680164)
		(end 354.851208 -278.946102)
		(width 0.350012)
		(layer "F.Cu")
		(net "PVDDCR_CPU1_P0")
	)
	(segment
		(start 343.097866 -294.88003)
		(end 342.631014 -295.145968)
		(width 0.350012)
		(layer "F.Cu")
		(net "PVDDCR_CPU1_P0")
	)
	(segment
		(start 365.657892 -294.88003)
		(end 366.124744 -295.145968)
		(width 0.350012)
		(layer "F.Cu")
		(net "PVDDCR_CPU1_P0")
	)
	(segment
		(start 355.31806 -268.960092)
		(end 354.851208 -269.22603)
		(width 0.350012)
		(layer "F.Cu")
		(net "PVDDCR_CPU1_P0")
	)
	(segment
		(start 351.557844 -275.44014)
		(end 351.091246 -275.706078)
		(width 0.350012)
		(layer "F.Cu")
		(net "PVDDCR_CPU1_P0")
	)
	(segment
		(start 351.557844 -283.5402)
		(end 351.091246 -283.806138)
		(width 0.350012)
		(layer "F.Cu")
		(net "PVDDCR_CPU1_P0")
	)
	(segment
		(start 346.858082 -268.960092)
		(end 346.39123 -269.22603)
		(width 0.350012)
		(layer "F.Cu")
		(net "PVDDCR_CPU1_P0")
	)
	(segment
		(start 375.057924 -291.640006)
		(end 375.524776 -291.905944)
		(width 0.350012)
		(layer "F.Cu")
		(net "PVDDCR_CPU1_P0")
	)
	(segment
		(start 370.357908 -283.5402)
		(end 370.82476 -283.806138)
		(width 0.350012)
		(layer "F.Cu")
		(net "PVDDCR_CPU1_P0")
	)
	(segment
		(start 353.437952 -291.640006)
		(end 352.9711 -291.905944)
		(width 0.350012)
		(layer "F.Cu")
		(net "PVDDCR_CPU1_P0")
	)
	(segment
		(start 354.378006 -272.200116)
		(end 353.911154 -272.466054)
		(width 0.350012)
		(layer "F.Cu")
		(net "PVDDCR_CPU1_P0")
	)
	(segment
		(start 366.597946 -294.88003)
		(end 367.064798 -295.145968)
		(width 0.350012)
		(layer "F.Cu")
		(net "PVDDCR_CPU1_P0")
	)
	(segment
		(start 370.357908 -268.960092)
		(end 370.82476 -269.22603)
		(width 0.350012)
		(layer "F.Cu")
		(net "PVDDCR_CPU1_P0")
	)
	(segment
		(start 358.607868 -290.83)
		(end 358.141016 -291.095938)
		(width 0.350012)
		(layer "F.Cu")
		(net "PVDDCR_CPU1_P0")
	)
	(segment
		(start 365.657892 -283.5402)
		(end 366.124744 -283.806138)
		(width 0.350012)
		(layer "F.Cu")
		(net "PVDDCR_CPU1_P0")
	)
	(segment
		(start 350.618044 -294.88003)
		(end 350.151192 -295.145968)
		(width 0.350012)
		(layer "F.Cu")
		(net "PVDDCR_CPU1_P0")
	)
	(segment
		(start 351.557844 -267.34008)
		(end 351.091246 -267.606018)
		(width 0.350012)
		(layer "F.Cu")
		(net "PVDDCR_CPU1_P0")
	)
	(segment
		(start 366.128046 -268.150086)
		(end 366.594898 -268.416024)
		(width 0.350012)
		(layer "F.Cu")
		(net "PVDDCR_CPU1_P0")
	)
	(segment
		(start 368.944906 -295.145968)
		(end 368.478054 -294.88003)
		(width 0.350012)
		(layer "F.Cu")
		(net "PVDDCR_CPU1_P0")
	)
	(segment
		(start 362.368084 -292.450012)
		(end 362.834682 -292.71595)
		(width 0.350012)
		(layer "F.Cu")
		(net "PVDDCR_CPU1_P0")
	)
	(segment
		(start 345.918028 -290.019994)
		(end 345.451176 -290.285932)
		(width 0.350012)
		(layer "F.Cu")
		(net "PVDDCR_CPU1_P0")
	)
	(segment
		(start 365.657892 -275.44014)
		(end 366.124744 -275.706078)
		(width 0.350012)
		(layer "F.Cu")
		(net "PVDDCR_CPU1_P0")
	)
	(segment
		(start 374.11787 -275.44014)
		(end 374.584722 -275.706078)
		(width 0.350012)
		(layer "F.Cu")
		(net "PVDDCR_CPU1_P0")
	)
	(segment
		(start 358.607868 -277.870158)
		(end 358.141016 -278.136096)
		(width 0.350012)
		(layer "F.Cu")
		(net "PVDDCR_CPU1_P0")
	)
	(segment
		(start 345.918028 -286.780224)
		(end 345.451176 -287.045908)
		(width 0.350012)
		(layer "F.Cu")
		(net "PVDDCR_CPU1_P0")
	)
	(segment
		(start 356.728014 -266.530074)
		(end 356.261162 -266.796012)
		(width 0.350012)
		(layer "F.Cu")
		(net "PVDDCR_CPU1_P0")
	)
	(segment
		(start 349.67799 -272.200116)
		(end 349.211138 -272.466054)
		(width 0.350012)
		(layer "F.Cu")
		(net "PVDDCR_CPU1_P0")
	)
	(segment
		(start 346.858082 -290.019994)
		(end 346.39123 -290.285932)
		(width 0.350012)
		(layer "F.Cu")
		(net "PVDDCR_CPU1_P0")
	)
	(segment
		(start 362.837984 -280.300176)
		(end 363.304836 -280.566114)
		(width 0.350012)
		(layer "F.Cu")
		(net "PVDDCR_CPU1_P0")
	)
	(segment
		(start 358.137968 -280.300176)
		(end 357.671116 -280.566114)
		(width 0.350012)
		(layer "F.Cu")
		(net "PVDDCR_CPU1_P0")
	)
	(segment
		(start 373.17807 -283.5402)
		(end 373.644922 -283.806138)
		(width 0.350012)
		(layer "F.Cu")
		(net "PVDDCR_CPU1_P0")
	)
	(segment
		(start 364.717838 -278.680164)
		(end 365.18469 -278.946102)
		(width 0.350012)
		(layer "F.Cu")
		(net "PVDDCR_CPU1_P0")
	)
	(segment
		(start 368.478054 -278.680164)
		(end 368.944906 -278.946102)
		(width 0.350012)
		(layer "F.Cu")
		(net "PVDDCR_CPU1_P0")
	)
	(segment
		(start 374.11787 -286.780224)
		(end 374.584722 -287.045908)
		(width 0.350012)
		(layer "F.Cu")
		(net "PVDDCR_CPU1_P0")
	)
	(segment
		(start 370.357908 -272.200116)
		(end 370.82476 -272.466054)
		(width 0.350012)
		(layer "F.Cu")
		(net "PVDDCR_CPU1_P0")
	)
	(segment
		(start 371.297962 -294.88003)
		(end 371.764814 -295.145968)
		(width 0.350012)
		(layer "F.Cu")
		(net "PVDDCR_CPU1_P0")
	)
	(segment
		(start 352.497898 -283.5402)
		(end 352.031046 -283.806138)
		(width 0.350012)
		(layer "F.Cu")
		(net "PVDDCR_CPU1_P0")
	)
	(segment
		(start 352.968052 -268.150086)
		(end 352.5012 -268.416024)
		(width 0.350012)
		(layer "F.Cu")
		(net "PVDDCR_CPU1_P0")
	)
	(segment
		(start 354.378006 -268.960092)
		(end 353.911154 -269.22603)
		(width 0.350012)
		(layer "F.Cu")
		(net "PVDDCR_CPU1_P0")
	)
	(segment
		(start 364.717838 -290.019994)
		(end 365.18469 -290.285932)
		(width 0.350012)
		(layer "F.Cu")
		(net "PVDDCR_CPU1_P0")
	)
	(segment
		(start 351.557844 -278.680164)
		(end 351.091246 -278.946102)
		(width 0.350012)
		(layer "F.Cu")
		(net "PVDDCR_CPU1_P0")
	)
	(segment
		(start 367.538 -286.780224)
		(end 368.004852 -287.045908)
		(width 0.350012)
		(layer "F.Cu")
		(net "PVDDCR_CPU1_P0")
	)
	(segment
		(start 367.067846 -281.110182)
		(end 367.534698 -281.37612)
		(width 0.350012)
		(layer "F.Cu")
		(net "PVDDCR_CPU1_P0")
	)
	(segment
		(start 373.64797 -268.150086)
		(end 374.114822 -268.416024)
		(width 0.350012)
		(layer "F.Cu")
		(net "PVDDCR_CPU1_P0")
	)
	(segment
		(start 374.11787 -278.680164)
		(end 374.584722 -278.946102)
		(width 0.350012)
		(layer "F.Cu")
		(net "PVDDCR_CPU1_P0")
	)
	(segment
		(start 374.11787 -283.5402)
		(end 374.584722 -283.806138)
		(width 0.350012)
		(layer "F.Cu")
		(net "PVDDCR_CPU1_P0")
	)
	(segment
		(start 364.717838 -275.44014)
		(end 365.18469 -275.706078)
		(width 0.350012)
		(layer "F.Cu")
		(net "PVDDCR_CPU1_P0")
	)
	(segment
		(start 357.668068 -290.83)
		(end 357.201216 -291.095938)
		(width 0.350012)
		(layer "F.Cu")
		(net "PVDDCR_CPU1_P0")
	)
	(segment
		(start 374.588024 -292.450012)
		(end 375.054876 -292.71595)
		(width 0.350012)
		(layer "F.Cu")
		(net "PVDDCR_CPU1_P0")
	)
	(segment
		(start 354.378006 -290.019994)
		(end 353.911154 -290.285932)
		(width 0.350012)
		(layer "F.Cu")
		(net "PVDDCR_CPU1_P0")
	)
	(segment
		(start 348.737936 -290.019994)
		(end 348.271084 -290.285932)
		(width 0.350012)
		(layer "F.Cu")
		(net "PVDDCR_CPU1_P0")
	)
	(segment
		(start 346.858082 -275.44014)
		(end 346.39123 -275.706078)
		(width 0.350012)
		(layer "F.Cu")
		(net "PVDDCR_CPU1_P0")
	)
	(segment
		(start 367.538 -278.680164)
		(end 368.004852 -278.946102)
		(width 0.350012)
		(layer "F.Cu")
		(net "PVDDCR_CPU1_P0")
	)
	(segment
		(start 368.0079 -281.110182)
		(end 368.474752 -281.37612)
		(width 0.350012)
		(layer "F.Cu")
		(net "PVDDCR_CPU1_P0")
	)
	(segment
		(start 365.657892 -272.200116)
		(end 366.124744 -272.466054)
		(width 0.350012)
		(layer "F.Cu")
		(net "PVDDCR_CPU1_P0")
	)
	(segment
		(start 368.478054 -272.200116)
		(end 368.944906 -272.466054)
		(width 0.350012)
		(layer "F.Cu")
		(net "PVDDCR_CPU1_P0")
	)
	(segment
		(start 371.297962 -290.019994)
		(end 371.764814 -290.285932)
		(width 0.350012)
		(layer "F.Cu")
		(net "PVDDCR_CPU1_P0")
	)
	(segment
		(start 371.297962 -278.680164)
		(end 371.764814 -278.946102)
		(width 0.350012)
		(layer "F.Cu")
		(net "PVDDCR_CPU1_P0")
	)
	(segment
		(start 368.947954 -292.450012)
		(end 369.414806 -292.71595)
		(width 0.350012)
		(layer "F.Cu")
		(net "PVDDCR_CPU1_P0")
	)
	(segment
		(start 352.497898 -272.200116)
		(end 352.031046 -272.466054)
		(width 0.350012)
		(layer "F.Cu")
		(net "PVDDCR_CPU1_P0")
	)
	(segment
		(start 358.607868 -289.209988)
		(end 358.141016 -289.475926)
		(width 0.350012)
		(layer "F.Cu")
		(net "PVDDCR_CPU1_P0")
	)
	(segment
		(start 342.627966 -294.070024)
		(end 342.161114 -294.335962)
		(width 0.350012)
		(layer "F.Cu")
		(net "PVDDCR_CPU1_P0")
	)
	(segment
		(start 352.968052 -281.110182)
		(end 352.5012 -281.37612)
		(width 0.350012)
		(layer "F.Cu")
		(net "PVDDCR_CPU1_P0")
	)
	(segment
		(start 371.297962 -283.5402)
		(end 371.764814 -283.806138)
		(width 0.350012)
		(layer "F.Cu")
		(net "PVDDCR_CPU1_P0")
	)
	(segment
		(start 376.938032 -294.88003)
		(end 377.404884 -295.145968)
		(width 0.350012)
		(layer "F.Cu")
		(net "PVDDCR_CPU1_P0")
	)
	(segment
		(start 355.31806 -286.780224)
		(end 354.851208 -287.045908)
		(width 0.350012)
		(layer "F.Cu")
		(net "PVDDCR_CPU1_P0")
	)
	(segment
		(start 345.918028 -268.960092)
		(end 345.451176 -269.22603)
		(width 0.350012)
		(layer "F.Cu")
		(net "PVDDCR_CPU1_P0")
	)
	(segment
		(start 352.027998 -281.110182)
		(end 351.561146 -281.37612)
		(width 0.350012)
		(layer "F.Cu")
		(net "PVDDCR_CPU1_P0")
	)
	(segment
		(start 357.668068 -292.450012)
		(end 357.201216 -292.71595)
		(width 0.350012)
		(layer "F.Cu")
		(net "PVDDCR_CPU1_P0")
	)
	(segment
		(start 362.368084 -266.530074)
		(end 362.834682 -266.796012)
		(width 0.350012)
		(layer "F.Cu")
		(net "PVDDCR_CPU1_P0")
	)
	(segment
		(start 365.657892 -268.960092)
		(end 366.124744 -269.22603)
		(width 0.350012)
		(layer "F.Cu")
		(net "PVDDCR_CPU1_P0")
	)
	(segment
		(start 371.297962 -267.34008)
		(end 371.764814 -267.606018)
		(width 0.350012)
		(layer "F.Cu")
		(net "PVDDCR_CPU1_P0")
	)
	(segment
		(start 351.087944 -268.150086)
		(end 350.621092 -268.416024)
		(width 0.350012)
		(layer "F.Cu")
		(net "PVDDCR_CPU1_P0")
	)
	(segment
		(start 374.11787 -268.960092)
		(end 374.584722 -269.22603)
		(width 0.350012)
		(layer "F.Cu")
		(net "PVDDCR_CPU1_P0")
	)
	(segment
		(start 354.378006 -283.5402)
		(end 353.911154 -283.806138)
		(width 0.350012)
		(layer "F.Cu")
		(net "PVDDCR_CPU1_P0")
	)
	(segment
		(start 346.858082 -286.780224)
		(end 346.39123 -287.045908)
		(width 0.350012)
		(layer "F.Cu")
		(net "PVDDCR_CPU1_P0")
	)
	(segment
		(start 354.378006 -294.88003)
		(end 353.911154 -295.145968)
		(width 0.350012)
		(layer "F.Cu")
		(net "PVDDCR_CPU1_P0")
	)
	(segment
		(start 357.668068 -282.730194)
		(end 357.201216 -282.996132)
		(width 0.350012)
		(layer "F.Cu")
		(net "PVDDCR_CPU1_P0")
	)
	(segment
		(start 373.17807 -272.200116)
		(end 373.644922 -272.466054)
		(width 0.350012)
		(layer "F.Cu")
		(net "PVDDCR_CPU1_P0")
	)
	(segment
		(start 352.497898 -278.680164)
		(end 352.031046 -278.946102)
		(width 0.350012)
		(layer "F.Cu")
		(net "PVDDCR_CPU1_P0")
	)
	(segment
		(start 357.668068 -289.209988)
		(end 357.201216 -289.475926)
		(width 0.350012)
		(layer "F.Cu")
		(net "PVDDCR_CPU1_P0")
	)
	(segment
		(start 346.858082 -278.680164)
		(end 346.39123 -278.946102)
		(width 0.350012)
		(layer "F.Cu")
		(net "PVDDCR_CPU1_P0")
	)
	(segment
		(start 345.447874 -292.450012)
		(end 344.981022 -292.71595)
		(width 0.350012)
		(layer "F.Cu")
		(net "PVDDCR_CPU1_P0")
	)
	(segment
		(start 357.197914 -280.300176)
		(end 356.731062 -280.566114)
		(width 0.350012)
		(layer "F.Cu")
		(net "PVDDCR_CPU1_P0")
	)
	(segment
		(start 352.968052 -266.530074)
		(end 352.5012 -266.796012)
		(width 0.350012)
		(layer "F.Cu")
		(net "PVDDCR_CPU1_P0")
	)
	(segment
		(start 349.67799 -290.019994)
		(end 349.211138 -290.285932)
		(width 0.350012)
		(layer "F.Cu")
		(net "PVDDCR_CPU1_P0")
	)
	(segment
		(start 356.25786 -291.640006)
		(end 355.791008 -291.905944)
		(width 0.350012)
		(layer "F.Cu")
		(net "PVDDCR_CPU1_P0")
	)
	(segment
		(start 362.368084 -282.730194)
		(end 362.834682 -282.996132)
		(width 0.350012)
		(layer "F.Cu")
		(net "PVDDCR_CPU1_P0")
	)
	(segment
		(start 357.668068 -285.970218)
		(end 357.201216 -286.236156)
		(width 0.350012)
		(layer "F.Cu")
		(net "PVDDCR_CPU1_P0")
	)
	(segment
		(start 371.297962 -272.200116)
		(end 371.764814 -272.466054)
		(width 0.350012)
		(layer "F.Cu")
		(net "PVDDCR_CPU1_P0")
	)
	(segment
		(start 357.197914 -267.34008)
		(end 356.731062 -267.606018)
		(width 0.350012)
		(layer "F.Cu")
		(net "PVDDCR_CPU1_P0")
	)
	(segment
		(start 345.918028 -272.200116)
		(end 345.451176 -272.466054)
		(width 0.350012)
		(layer "F.Cu")
		(net "PVDDCR_CPU1_P0")
	)
	(segment
		(start 373.17807 -286.780224)
		(end 373.644922 -287.045908)
		(width 0.350012)
		(layer "F.Cu")
		(net "PVDDCR_CPU1_P0")
	)
	(segment
		(start 375.057924 -294.88003)
		(end 375.524776 -295.145968)
		(width 0.350012)
		(layer "F.Cu")
		(net "PVDDCR_CPU1_P0")
	)
	(segment
		(start 348.737936 -294.88003)
		(end 348.271084 -295.145968)
		(width 0.350012)
		(layer "F.Cu")
		(net "PVDDCR_CPU1_P0")
	)
	(segment
		(start 352.497898 -268.960092)
		(end 352.031046 -269.22603)
		(width 0.350012)
		(layer "F.Cu")
		(net "PVDDCR_CPU1_P0")
	)
	(segment
		(start 348.737936 -272.200116)
		(end 348.271084 -272.466054)
		(width 0.350012)
		(layer "F.Cu")
		(net "PVDDCR_CPU1_P0")
	)
	(segment
		(start 361.42803 -282.730194)
		(end 361.894882 -282.996132)
		(width 0.350012)
		(layer "F.Cu")
		(net "PVDDCR_CPU1_P0")
	)
	(segment
		(start 348.737936 -286.780224)
		(end 348.271084 -287.045908)
		(width 0.350012)
		(layer "F.Cu")
		(net "PVDDCR_CPU1_P0")
	)
	(segment
		(start 364.247938 -281.110182)
		(end 364.71479 -281.37612)
		(width 0.350012)
		(layer "F.Cu")
		(net "PVDDCR_CPU1_P0")
	)
	(segment
		(start 351.557844 -290.019994)
		(end 351.091246 -290.285932)
		(width 0.350012)
		(layer "F.Cu")
		(net "PVDDCR_CPU1_P0")
	)
	(segment
		(start 362.368084 -268.150086)
		(end 362.834682 -268.416024)
		(width 0.350012)
		(layer "F.Cu")
		(net "PVDDCR_CPU1_P0")
	)
	(segment
		(start 362.368084 -289.209988)
		(end 362.834682 -289.475926)
		(width 0.350012)
		(layer "F.Cu")
		(net "PVDDCR_CPU1_P0")
	)
	(segment
		(start 357.668068 -271.39011)
		(end 357.201216 -271.656048)
		(width 0.350012)
		(layer "F.Cu")
		(net "PVDDCR_CPU1_P0")
	)
	(segment
		(start 351.557844 -286.780224)
		(end 351.091246 -287.045908)
		(width 0.350012)
		(layer "F.Cu")
		(net "PVDDCR_CPU1_P0")
	)
	(segment
		(start 367.538 -268.960092)
		(end 368.004852 -269.22603)
		(width 0.350012)
		(layer "F.Cu")
		(net "PVDDCR_CPU1_P0")
	)
	(segment
		(start 348.737936 -268.960092)
		(end 348.271084 -269.22603)
		(width 0.350012)
		(layer "F.Cu")
		(net "PVDDCR_CPU1_P0")
	)
	(segment
		(start 349.20809 -266.530074)
		(end 348.741238 -266.796012)
		(width 0.350012)
		(layer "F.Cu")
		(net "PVDDCR_CPU1_P0")
	)
	(segment
		(start 353.437952 -294.88003)
		(end 352.9711 -295.145968)
		(width 0.350012)
		(layer "F.Cu")
		(net "PVDDCR_CPU1_P0")
	)
	(segment
		(start 371.767862 -292.450012)
		(end 372.234714 -292.71595)
		(width 0.350012)
		(layer "F.Cu")
		(net "PVDDCR_CPU1_P0")
	)
	(segment
		(start 348.268036 -292.450012)
		(end 347.801184 -292.71595)
		(width 0.350012)
		(layer "F.Cu")
		(net "PVDDCR_CPU1_P0")
	)
	(segment
		(start 368.478054 -275.44014)
		(end 368.944906 -275.706078)
		(width 0.350012)
		(layer "F.Cu")
		(net "PVDDCR_CPU1_P0")
	)
	(segment
		(start 356.728014 -292.450012)
		(end 356.261162 -292.71595)
		(width 0.350012)
		(layer "F.Cu")
		(net "PVDDCR_CPU1_P0")
	)
	(segment
		(start 351.087944 -292.450012)
		(end 350.621092 -292.71595)
		(width 0.350012)
		(layer "F.Cu")
		(net "PVDDCR_CPU1_P0")
	)
	(segment
		(start 366.597946 -291.640006)
		(end 367.064798 -291.905944)
		(width 0.350012)
		(layer "F.Cu")
		(net "PVDDCR_CPU1_P0")
	)
	(segment
		(start 374.11787 -290.019994)
		(end 374.584722 -290.285932)
		(width 0.350012)
		(layer "F.Cu")
		(net "PVDDCR_CPU1_P0")
	)
	(segment
		(start 368.478054 -286.780224)
		(end 368.944906 -287.046162)
		(width 0.350012)
		(layer "F.Cu")
		(net "PVDDCR_CPU1_P0")
	)
	(segment
		(start 347.797882 -294.88003)
		(end 347.33103 -295.145968)
		(width 0.350012)
		(layer "F.Cu")
		(net "PVDDCR_CPU1_P0")
	)
	(segment
		(start 377.878086 -294.88003)
		(end 378.344938 -295.145968)
		(width 0.350012)
		(layer "F.Cu")
		(net "PVDDCR_CPU1_P0")
	)
	(segment
		(start 361.89793 -280.300176)
		(end 362.364782 -280.566114)
		(width 0.350012)
		(layer "F.Cu")
		(net "PVDDCR_CPU1_P0")
	)
	(segment
		(start 355.31806 -283.5402)
		(end 354.851208 -283.806138)
		(width 0.350012)
		(layer "F.Cu")
		(net "PVDDCR_CPU1_P0")
	)
	(segment
		(start 362.368084 -290.83)
		(end 362.834682 -291.095938)
		(width 0.350012)
		(layer "F.Cu")
		(net "PVDDCR_CPU1_P0")
	)
	(segment
		(start 344.977974 -294.88003)
		(end 344.511122 -295.145968)
		(width 0.350012)
		(layer "F.Cu")
		(net "PVDDCR_CPU1_P0")
	)
	(segment
		(start 358.607868 -274.630134)
		(end 358.141016 -274.896072)
		(width 0.350012)
		(layer "F.Cu")
		(net "PVDDCR_CPU1_P0")
	)
	(segment
		(start 371.297962 -268.960092)
		(end 371.764814 -269.22603)
		(width 0.350012)
		(layer "F.Cu")
		(net "PVDDCR_CPU1_P0")
	)
	(segment
		(start 349.67799 -286.780224)
		(end 349.211138 -287.045908)
		(width 0.350012)
		(layer "F.Cu")
		(net "PVDDCR_CPU1_P0")
	)
	(segment
		(start 355.31806 -272.200116)
		(end 354.851208 -272.466054)
		(width 0.350012)
		(layer "F.Cu")
		(net "PVDDCR_CPU1_P0")
	)
	(segment
		(start 374.11787 -272.200116)
		(end 374.584722 -272.466054)
		(width 0.350012)
		(layer "F.Cu")
		(net "PVDDCR_CPU1_P0")
	)
	(segment
		(start 365.187992 -281.110182)
		(end 365.654844 -281.37612)
		(width 0.350012)
		(layer "F.Cu")
		(net "PVDDCR_CPU1_P0")
	)
	(segment
		(start 354.378006 -275.44014)
		(end 353.911154 -275.706078)
		(width 0.350012)
		(layer "F.Cu")
		(net "PVDDCR_CPU1_P0")
	)
	(segment
		(start 357.668068 -277.870158)
		(end 357.201216 -278.136096)
		(width 0.350012)
		(layer "F.Cu")
		(net "PVDDCR_CPU1_P0")
	)
	(segment
		(start 354.378006 -286.780224)
		(end 353.911154 -287.045908)
		(width 0.350012)
		(layer "F.Cu")
		(net "PVDDCR_CPU1_P0")
	)
	(segment
		(start 348.737936 -278.680164)
		(end 348.271084 -278.946102)
		(width 0.350012)
		(layer "F.Cu")
		(net "PVDDCR_CPU1_P0")
	)
	(segment
		(start 346.858082 -283.5402)
		(end 346.39123 -283.806138)
		(width 0.350012)
		(layer "F.Cu")
		(net "PVDDCR_CPU1_P0")
	)
	(segment
		(start 349.67799 -268.960092)
		(end 349.211138 -269.22603)
		(width 0.350012)
		(layer "F.Cu")
		(net "PVDDCR_CPU1_P0")
	)
	(segment
		(start 370.357908 -275.44014)
		(end 370.82476 -275.706078)
		(width 0.350012)
		(layer "F.Cu")
		(net "PVDDCR_CPU1_P0")
	)
	(segment
		(start 367.538 -275.44014)
		(end 368.004852 -275.706078)
		(width 0.350012)
		(layer "F.Cu")
		(net "PVDDCR_CPU1_P0")
	)
	(segment
		(start 358.607868 -282.730194)
		(end 358.141016 -282.996132)
		(width 0.350012)
		(layer "F.Cu")
		(net "PVDDCR_CPU1_P0")
	)
	(segment
		(start 358.607868 -285.970218)
		(end 358.141016 -286.236156)
		(width 0.350012)
		(layer "F.Cu")
		(net "PVDDCR_CPU1_P0")
	)
	(segment
		(start 361.42803 -285.970218)
		(end 361.894882 -286.236156)
		(width 0.350012)
		(layer "F.Cu")
		(net "PVDDCR_CPU1_P0")
	)
	(segment
		(start 353.437952 -267.34008)
		(end 352.9711 -267.606018)
		(width 0.350012)
		(layer "F.Cu")
		(net "PVDDCR_CPU1_P0")
	)
	(segment
		(start 368.0079 -268.150086)
		(end 368.474752 -268.416024)
		(width 0.350012)
		(layer "F.Cu")
		(net "PVDDCR_CPU1_P0")
	)
	(segment
		(start 369.888008 -266.530074)
		(end 370.35486 -266.796012)
		(width 0.350012)
		(layer "F.Cu")
		(net "PVDDCR_CPU1_P0")
	)
	(segment
		(start 345.918028 -275.44014)
		(end 345.451176 -275.706078)
		(width 0.350012)
		(layer "F.Cu")
		(net "PVDDCR_CPU1_P0")
	)
	(segment
		(start 365.657892 -278.680164)
		(end 366.124744 -278.946102)
		(width 0.350012)
		(layer "F.Cu")
		(net "PVDDCR_CPU1_P0")
	)
	(segment
		(start 368.478054 -283.5402)
		(end 368.944906 -283.806138)
		(width 0.350012)
		(layer "F.Cu")
		(net "PVDDCR_CPU1_P0")
	)
	(segment
		(start 361.42803 -277.870158)
		(end 361.894882 -278.136096)
		(width 0.350012)
		(layer "F.Cu")
		(net "PVDDCR_CPU1_P0")
	)
	(segment
		(start 362.368084 -271.39011)
		(end 362.834682 -271.656048)
		(width 0.350012)
		(layer "F.Cu")
		(net "PVDDCR_CPU1_P0")
	)
	(segment
		(start 352.497898 -286.780224)
		(end 352.031046 -287.045908)
		(width 0.350012)
		(layer "F.Cu")
		(net "PVDDCR_CPU1_P0")
	)
	(segment
		(start 370.357908 -278.680164)
		(end 370.82476 -278.946102)
		(width 0.350012)
		(layer "F.Cu")
		(net "PVDDCR_CPU1_P0")
	)
	(segment
		(start 370.357908 -290.019994)
		(end 370.82476 -290.285932)
		(width 0.350012)
		(layer "F.Cu")
		(net "PVDDCR_CPU1_P0")
	)
	(segment
		(start 372.238016 -291.640006)
		(end 372.704868 -291.905944)
		(width 0.350012)
		(layer "F.Cu")
		(net "PVDDCR_CPU1_P0")
	)
	(segment
		(start 348.737936 -275.44014)
		(end 348.271084 -275.706078)
		(width 0.350012)
		(layer "F.Cu")
		(net "PVDDCR_CPU1_P0")
	)
	(segment
		(start 349.20809 -268.150086)
		(end 348.741238 -268.416024)
		(width 0.350012)
		(layer "F.Cu")
		(net "PVDDCR_CPU1_P0")
	)
	(segment
		(start 362.368084 -285.970218)
		(end 362.834682 -286.236156)
		(width 0.350012)
		(layer "F.Cu")
		(net "PVDDCR_CPU1_P0")
	)
	(segment
		(start 361.42803 -290.83)
		(end 361.894882 -291.095938)
		(width 0.350012)
		(layer "F.Cu")
		(net "PVDDCR_CPU1_P0")
	)
	(segment
		(start 356.728014 -268.150086)
		(end 356.261162 -268.416024)
		(width 0.350012)
		(layer "F.Cu")
		(net "PVDDCR_CPU1_P0")
	)
	(segment
		(start 371.297962 -275.44014)
		(end 371.764814 -275.706078)
		(width 0.350012)
		(layer "F.Cu")
		(net "PVDDCR_CPU1_P0")
	)
	(segment
		(start 366.128046 -292.450012)
		(end 366.594898 -292.71595)
		(width 0.350012)
		(layer "F.Cu")
		(net "PVDDCR_CPU1_P0")
	)
	(segment
		(start 347.327982 -268.150086)
		(end 346.86113 -268.416024)
		(width 0.350012)
		(layer "F.Cu")
		(net "PVDDCR_CPU1_P0")
	)
	(segment
		(start 373.17807 -278.680164)
		(end 373.644922 -278.946102)
		(width 0.350012)
		(layer "F.Cu")
		(net "PVDDCR_CPU1_P0")
	)
	(segment
		(start 361.42803 -274.630134)
		(end 361.894882 -274.896072)
		(width 0.350012)
		(layer "F.Cu")
		(net "PVDDCR_CPU1_P0")
	)
	(segment
		(start 368.478054 -290.019994)
		(end 368.944906 -290.285932)
		(width 0.350012)
		(layer "F.Cu")
		(net "PVDDCR_CPU1_P0")
	)
	(segment
		(start 365.657892 -290.019994)
		(end 366.124744 -290.285932)
		(width 0.350012)
		(layer "F.Cu")
		(net "PVDDCR_CPU1_P0")
	)
	(segment
		(start 347.797882 -291.640006)
		(end 347.33103 -291.905944)
		(width 0.350012)
		(layer "F.Cu")
		(net "PVDDCR_CPU1_P0")
	)
	(segment
		(start 361.42803 -271.39011)
		(end 361.894882 -271.656048)
		(width 0.350012)
		(layer "F.Cu")
		(net "PVDDCR_CPU1_P0")
	)
	(segment
		(start 366.128046 -266.530074)
		(end 366.594898 -266.796012)
		(width 0.350012)
		(layer "F.Cu")
		(net "PVDDCR_CPU1_P0")
	)
	(segment
		(start 365.657892 -267.34008)
		(end 366.124744 -267.606018)
		(width 0.350012)
		(layer "F.Cu")
		(net "PVDDCR_CPU1_P0")
	)
	(segment
		(start 373.17807 -267.34008)
		(end 373.644922 -267.606018)
		(width 0.350012)
		(layer "F.Cu")
		(net "PVDDCR_CPU1_P0")
	)
	(segment
		(start 373.17807 -275.44014)
		(end 373.644922 -275.706078)
		(width 0.350012)
		(layer "F.Cu")
		(net "PVDDCR_CPU1_P0")
	)
	(segment
		(start 345.918028 -283.5402)
		(end 345.451176 -283.806138)
		(width 0.350012)
		(layer "F.Cu")
		(net "PVDDCR_CPU1_P0")
	)
	(segment
		(start 351.557844 -294.88003)
		(end 351.091246 -295.145968)
		(width 0.350012)
		(layer "F.Cu")
		(net "PVDDCR_CPU1_P0")
	)
	(segment
		(start 358.607868 -271.39011)
		(end 358.141016 -271.656048)
		(width 0.350012)
		(layer "F.Cu")
		(net "PVDDCR_CPU1_P0")
	)
	(segment
		(start 353.907852 -292.450012)
		(end 353.441 -292.71595)
		(width 0.350012)
		(layer "F.Cu")
		(net "PVDDCR_CPU1_P0")
	)
	(segment
		(start 354.847906 -281.110182)
		(end 354.381054 -281.37612)
		(width 0.350012)
		(layer "F.Cu")
		(net "PVDDCR_CPU1_P0")
	)
	(segment
		(start 345.918028 -278.680164)
		(end 345.451176 -278.946102)
		(width 0.350012)
		(layer "F.Cu")
		(net "PVDDCR_CPU1_P0")
	)
	(segment
		(start 367.538 -290.019994)
		(end 368.004852 -290.285932)
		(width 0.350012)
		(layer "F.Cu")
		(net "PVDDCR_CPU1_P0")
	)
	(segment
		(start 373.17807 -290.019994)
		(end 373.644922 -290.285932)
		(width 0.350012)
		(layer "F.Cu")
		(net "PVDDCR_CPU1_P0")
	)
	(segment
		(start 364.717838 -286.780224)
		(end 365.18469 -287.045908)
		(width 0.350012)
		(layer "F.Cu")
		(net "PVDDCR_CPU1_P0")
	)
	(segment
		(start 355.78796 -281.110182)
		(end 355.321108 -281.37612)
		(width 0.350012)
		(layer "F.Cu")
		(net "PVDDCR_CPU1_P0")
	)
	(segment
		(start 349.67799 -283.5402)
		(end 349.211138 -283.806138)
		(width 0.350012)
		(layer "F.Cu")
		(net "PVDDCR_CPU1_P0")
	)
	(segment
		(start 363.778038 -267.34008)
		(end 364.24489 -267.606018)
		(width 0.350012)
		(layer "F.Cu")
		(net "PVDDCR_CPU1_P0")
	)
	(segment
		(start 370.357908 -286.780224)
		(end 370.82476 -287.045908)
		(width 0.350012)
		(layer "F.Cu")
		(net "PVDDCR_CPU1_P0")
	)
	(segment
		(start 357.668068 -274.630134)
		(end 357.201216 -274.896072)
		(width 0.350012)
		(layer "F.Cu")
		(net "PVDDCR_CPU1_P0")
	)
	(segment
		(start 371.297962 -286.780224)
		(end 371.764814 -287.045908)
		(width 0.350012)
		(layer "F.Cu")
		(net "PVDDCR_CPU1_P0")
	)
	(segment
		(start 373.17807 -268.960092)
		(end 373.644922 -269.22603)
		(width 0.350012)
		(layer "F.Cu")
		(net "PVDDCR_CPU1_P0")
	)
	(segment
		(start 355.31806 -275.44014)
		(end 354.851208 -275.706078)
		(width 0.350012)
		(layer "F.Cu")
		(net "PVDDCR_CPU1_P0")
	)
	(segment
		(start 359.078022 -267.34008)
		(end 358.61117 -267.606018)
		(width 0.350012)
		(layer "F.Cu")
		(net "PVDDCR_CPU1_P0")
	)
	(segment
		(start 364.717838 -272.200116)
		(end 365.18469 -272.466054)
		(width 0.350012)
		(layer "F.Cu")
		(net "PVDDCR_CPU1_P0")
	)
	(segment
		(start 357.197914 -294.88003)
		(end 356.731062 -295.145968)
		(width 0.350012)
		(layer "F.Cu")
		(net "PVDDCR_CPU1_P0")
	)
	(segment
		(start 362.837984 -294.88003)
		(end 363.304836 -295.145968)
		(width 0.350012)
		(layer "F.Cu")
		(net "PVDDCR_CPU1_P0")
	)
	(segment
		(start 349.67799 -278.680164)
		(end 349.211138 -278.946102)
		(width 0.350012)
		(layer "F.Cu")
		(net "PVDDCR_CPU1_P0")
	)
	(segment
		(start 368.478054 -268.960092)
		(end 368.944906 -269.22603)
		(width 0.350012)
		(layer "F.Cu")
		(net "PVDDCR_CPU1_P0")
	)
	(segment
		(start 352.497898 -290.019994)
		(end 352.031046 -290.285932)
		(width 0.350012)
		(layer "F.Cu")
		(net "PVDDCR_CPU1_P0")
	)
	(segment
		(start 362.368084 -274.630134)
		(end 362.834682 -274.896072)
		(width 0.350012)
		(layer "F.Cu")
		(net "PVDDCR_CPU1_P0")
	)
	(segment
		(start 371.767862 -268.150086)
		(end 372.234714 -268.416024)
		(width 0.350012)
		(layer "F.Cu")
		(net "PVDDCR_CPU1_P0")
	)
	(segment
		(start 350.618044 -291.640006)
		(end 350.151192 -291.905944)
		(width 0.350012)
		(layer "F.Cu")
		(net "PVDDCR_CPU1_P0")
	)
	(segment
		(start 351.557844 -272.200116)
		(end 351.091246 -272.466054)
		(width 0.350012)
		(layer "F.Cu")
		(net "PVDDCR_CPU1_P0")
	)
	(segment
		(start 358.607868 -268.150086)
		(end 358.141016 -268.416024)
		(width 0.350012)
		(layer "F.Cu")
		(net "PVDDCR_CPU1_P0")
	)
	(segment
		(start 348.737936 -283.5402)
		(end 348.271084 -283.806138)
		(width 0.350012)
		(layer "F.Cu")
		(net "PVDDCR_CPU1_P0")
	)
	(segment
		(start 354.378006 -278.680164)
		(end 353.911154 -278.946102)
		(width 0.350012)
		(layer "F.Cu")
		(net "PVDDCR_CPU1_P0")
	)
	(segment
		(start 352.497898 -275.44014)
		(end 352.031046 -275.706078)
		(width 0.350012)
		(layer "F.Cu")
		(net "PVDDCR_CPU1_P0")
	)
	(segment
		(start 367.538 -267.34008)
		(end 368.004852 -267.606018)
		(width 0.350012)
		(layer "F.Cu")
		(net "PVDDCR_CPU1_P0")
	)
	(segment
		(start 363.778038 -291.640006)
		(end 364.24489 -291.905944)
		(width 0.350012)
		(layer "F.Cu")
		(net "PVDDCR_CPU1_P0")
	)
	(segment
		(start 364.717838 -268.960092)
		(end 365.18469 -269.22603)
		(width 0.350012)
		(layer "F.Cu")
		(net "PVDDCR_CPU1_P0")
	)
	(segment
		(start 369.417854 -294.88003)
		(end 369.884706 -295.145968)
		(width 0.350012)
		(layer "F.Cu")
		(net "PVDDCR_CPU1_P0")
	)
	(segment
		(start 356.25786 -294.88003)
		(end 355.791008 -295.145968)
		(width 0.350012)
		(layer "F.Cu")
		(net "PVDDCR_CPU1_P0")
	)
	(segment
		(start 354.847906 -268.150086)
		(end 354.381054 -268.416024)
		(width 0.350012)
		(layer "F.Cu")
		(net "PVDDCR_CPU1_P0")
	)
	(segment
		(start 349.67799 -267.34008)
		(end 349.211138 -267.606018)
		(width 0.350012)
		(layer "F.Cu")
		(net "PVDDCR_CPU1_P0")
	)
	(segment
		(start 377.407932 -294.070024)
		(end 377.874784 -294.335962)
		(width 0.350012)
		(layer "F.Cu")
		(net "PVDDCR_CPU1_P0")
	)
	(segment
		(start 363.307884 -292.450012)
		(end 363.774736 -292.71595)
		(width 0.350012)
		(layer "F.Cu")
		(net "PVDDCR_CPU1_P0")
	)
	(segment
		(start 374.11787 -294.88003)
		(end 374.584722 -295.145968)
		(width 0.350012)
		(layer "F.Cu")
		(net "PVDDCR_CPU1_P0")
	)
	(segment
		(start 369.417854 -291.640006)
		(end 369.884706 -291.905944)
		(width 0.350012)
		(layer "F.Cu")
		(net "PVDDCR_CPU1_P0")
	)
	(segment
		(start 362.368084 -277.870158)
		(end 362.834682 -278.136096)
		(width 0.350012)
		(layer "F.Cu")
		(net "PVDDCR_CPU1_P0")
	)
	(segment
		(start 361.42803 -289.209988)
		(end 361.894882 -289.475926)
		(width 0.350012)
		(layer "F.Cu")
		(net "PVDDCR_CPU1_P0")
	)
	(segment
		(start 344.977974 -291.640006)
		(end 344.511122 -291.905944)
		(width 0.350012)
		(layer "F.Cu")
		(net "PVDDCR_CPU1_P0")
	)
	(segment
		(start 361.89793 -267.34008)
		(end 362.364782 -267.606018)
		(width 0.350012)
		(layer "F.Cu")
		(net "PVDDCR_CPU1_P0")
	)
	(segment
		(start 364.717838 -283.5402)
		(end 365.18469 -283.806138)
		(width 0.350012)
		(layer "F.Cu")
		(net "PVDDCR_CPU1_P0")
	)
	(segment
		(start 363.778038 -294.88003)
		(end 364.24489 -295.145968)
		(width 0.350012)
		(layer "F.Cu")
		(net "PVDDCR_CPU1_P0")
	)
	(via
		(at 354.425504 -325.435722)
		(size 0.508)
		(drill 0.254)
		(layers "F.Cu" "B.Cu")
		(net "PVDDCR_CPU1_P0")
	)
	(via
		(at 374.584722 -290.285932)
		(size 0.4064)
		(drill 0.2032)
		(layers "F.Cu" "B.Cu")
		(net "PVDDCR_CPU1_P0")
	)
	(via
		(at 373.644922 -267.606018)
		(size 0.4064)
		(drill 0.2032)
		(layers "F.Cu" "B.Cu")
		(net "PVDDCR_CPU1_P0")
	)
	(via
		(at 353.790504 -323.505322)
		(size 0.508)
		(drill 0.254)
		(layers "F.Cu" "B.Cu")
		(net "PVDDCR_CPU1_P0")
	)
	(via
		(at 352.9711 -267.606018)
		(size 0.4064)
		(drill 0.2032)
		(layers "F.Cu" "B.Cu")
		(net "PVDDCR_CPU1_P0")
	)
	(via
		(at 362.834682 -271.656048)
		(size 0.4064)
		(drill 0.2032)
		(layers "F.Cu" "B.Cu")
		(net "PVDDCR_CPU1_P0")
	)
	(via
		(at 366.124744 -278.946102)
		(size 0.4064)
		(drill 0.2032)
		(layers "F.Cu" "B.Cu")
		(net "PVDDCR_CPU1_P0")
	)
	(via
		(at 337.183476 -318.544448)
		(size 0.508)
		(drill 0.254)
		(layers "F.Cu" "B.Cu")
		(net "PVDDCR_CPU1_P0")
	)
	(via
		(at 349.116904 -322.870322)
		(size 0.508)
		(drill 0.254)
		(layers "F.Cu" "B.Cu")
		(net "PVDDCR_CPU1_P0")
	)
	(via
		(at 370.82476 -287.045908)
		(size 0.4064)
		(drill 0.2032)
		(layers "F.Cu" "B.Cu")
		(net "PVDDCR_CPU1_P0")
	)
	(via
		(at 374.114822 -268.416024)
		(size 0.4064)
		(drill 0.2032)
		(layers "F.Cu" "B.Cu")
		(net "PVDDCR_CPU1_P0")
	)
	(via
		(at 353.155504 -322.870322)
		(size 0.508)
		(drill 0.254)
		(layers "F.Cu" "B.Cu")
		(net "PVDDCR_CPU1_P0")
	)
	(via
		(at 344.511122 -291.905944)
		(size 0.4064)
		(drill 0.2032)
		(layers "F.Cu" "B.Cu")
		(net "PVDDCR_CPU1_P0")
	)
	(via
		(at 321.105276 -321.106038)
		(size 0.508)
		(drill 0.254)
		(layers "F.Cu" "B.Cu")
		(net "PVDDCR_CPU1_P0")
	)
	(via
		(at 368.944906 -287.046162)
		(size 0.4064)
		(drill 0.2032)
		(layers "F.Cu" "B.Cu")
		(net "PVDDCR_CPU1_P0")
	)
	(via
		(at 324.81266 -320.45402)
		(size 0.508)
		(drill 0.254)
		(layers "F.Cu" "B.Cu")
		(net "PVDDCR_CPU1_P0")
	)
	(via
		(at 372.234714 -268.416024)
		(size 0.4064)
		(drill 0.2032)
		(layers "F.Cu" "B.Cu")
		(net "PVDDCR_CPU1_P0")
	)
	(via
		(at 350.412304 -325.414894)
		(size 0.508)
		(drill 0.254)
		(layers "F.Cu" "B.Cu")
		(net "PVDDCR_CPU1_P0")
	)
	(via
		(at 354.851208 -290.285932)
		(size 0.4064)
		(drill 0.2032)
		(layers "F.Cu" "B.Cu")
		(net "PVDDCR_CPU1_P0")
	)
	(via
		(at 358.61117 -267.606018)
		(size 0.4064)
		(drill 0.2032)
		(layers "F.Cu" "B.Cu")
		(net "PVDDCR_CPU1_P0")
	)
	(via
		(at 340.78926 -320.489326)
		(size 0.508)
		(drill 0.254)
		(layers "F.Cu" "B.Cu")
		(net "PVDDCR_CPU1_P0")
	)
	(via
		(at 349.142304 -327.975722)
		(size 0.508)
		(drill 0.254)
		(layers "F.Cu" "B.Cu")
		(net "PVDDCR_CPU1_P0")
	)
	(via
		(at 349.211138 -283.806138)
		(size 0.4064)
		(drill 0.2032)
		(layers "F.Cu" "B.Cu")
		(net "PVDDCR_CPU1_P0")
	)
	(via
		(at 348.271084 -278.946102)
		(size 0.4064)
		(drill 0.2032)
		(layers "F.Cu" "B.Cu")
		(net "PVDDCR_CPU1_P0")
	)
	(via
		(at 372.234714 -292.71595)
		(size 0.4064)
		(drill 0.2032)
		(layers "F.Cu" "B.Cu")
		(net "PVDDCR_CPU1_P0")
	)
	(via
		(at 354.381054 -281.37612)
		(size 0.4064)
		(drill 0.2032)
		(layers "F.Cu" "B.Cu")
		(net "PVDDCR_CPU1_P0")
	)
	(via
		(at 369.414806 -292.71595)
		(size 0.4064)
		(drill 0.2032)
		(layers "F.Cu" "B.Cu")
		(net "PVDDCR_CPU1_P0")
	)
	(via
		(at 363.304836 -295.145968)
		(size 0.4064)
		(drill 0.2032)
		(layers "F.Cu" "B.Cu")
		(net "PVDDCR_CPU1_P0")
	)
	(via
		(at 346.39123 -269.22603)
		(size 0.4064)
		(drill 0.2032)
		(layers "F.Cu" "B.Cu")
		(net "PVDDCR_CPU1_P0")
	)
	(via
		(at 349.142304 -327.340722)
		(size 0.508)
		(drill 0.254)
		(layers "F.Cu" "B.Cu")
		(net "PVDDCR_CPU1_P0")
	)
	(via
		(at 317.070232 -323.025516)
		(size 0.508)
		(drill 0.254)
		(layers "F.Cu" "B.Cu")
		(net "PVDDCR_CPU1_P0")
	)
	(via
		(at 324.15226 -319.814448)
		(size 0.508)
		(drill 0.254)
		(layers "F.Cu" "B.Cu")
		(net "PVDDCR_CPU1_P0")
	)
	(via
		(at 346.07246 -320.489326)
		(size 0.508)
		(drill 0.254)
		(layers "F.Cu" "B.Cu")
		(net "PVDDCR_CPU1_P0")
	)
	(via
		(at 328.19086 -321.72402)
		(size 0.508)
		(drill 0.254)
		(layers "F.Cu" "B.Cu")
		(net "PVDDCR_CPU1_P0")
	)
	(via
		(at 342.05926 -322.373498)
		(size 0.508)
		(drill 0.254)
		(layers "F.Cu" "B.Cu")
		(net "PVDDCR_CPU1_P0")
	)
	(via
		(at 324.78726 -316.639448)
		(size 0.508)
		(drill 0.254)
		(layers "F.Cu" "B.Cu")
		(net "PVDDCR_CPU1_P0")
	)
	(via
		(at 373.644922 -287.045908)
		(size 0.4064)
		(drill 0.2032)
		(layers "F.Cu" "B.Cu")
		(net "PVDDCR_CPU1_P0")
	)
	(via
		(at 366.124744 -272.466054)
		(size 0.4064)
		(drill 0.2032)
		(layers "F.Cu" "B.Cu")
		(net "PVDDCR_CPU1_P0")
	)
	(via
		(at 349.116904 -322.235322)
		(size 0.508)
		(drill 0.254)
		(layers "F.Cu" "B.Cu")
		(net "PVDDCR_CPU1_P0")
	)
	(via
		(at 357.671116 -280.566114)
		(size 0.4064)
		(drill 0.2032)
		(layers "F.Cu" "B.Cu")
		(net "PVDDCR_CPU1_P0")
	)
	(via
		(at 337.183476 -319.179448)
		(size 0.508)
		(drill 0.254)
		(layers "F.Cu" "B.Cu")
		(net "PVDDCR_CPU1_P0")
	)
	(via
		(at 350.386904 -324.775322)
		(size 0.508)
		(drill 0.254)
		(layers "F.Cu" "B.Cu")
		(net "PVDDCR_CPU1_P0")
	)
	(via
		(at 319.813432 -323.025516)
		(size 0.508)
		(drill 0.254)
		(layers "F.Cu" "B.Cu")
		(net "PVDDCR_CPU1_P0")
	)
	(via
		(at 353.911154 -275.706078)
		(size 0.4064)
		(drill 0.2032)
		(layers "F.Cu" "B.Cu")
		(net "PVDDCR_CPU1_P0")
	)
	(via
		(at 325.44766 -322.35902)
		(size 0.508)
		(drill 0.254)
		(layers "F.Cu" "B.Cu")
		(net "PVDDCR_CPU1_P0")
	)
	(via
		(at 361.894882 -289.475926)
		(size 0.4064)
		(drill 0.2032)
		(layers "F.Cu" "B.Cu")
		(net "PVDDCR_CPU1_P0")
	)
	(via
		(at 349.211138 -275.706078)
		(size 0.4064)
		(drill 0.2032)
		(layers "F.Cu" "B.Cu")
		(net "PVDDCR_CPU1_P0")
	)
	(via
		(at 329.46086 -318.544448)
		(size 0.508)
		(drill 0.254)
		(layers "F.Cu" "B.Cu")
		(net "PVDDCR_CPU1_P0")
	)
	(via
		(at 347.801184 -292.71595)
		(size 0.4064)
		(drill 0.2032)
		(layers "F.Cu" "B.Cu")
		(net "PVDDCR_CPU1_P0")
	)
	(via
		(at 328.82586 -321.72402)
		(size 0.508)
		(drill 0.254)
		(layers "F.Cu" "B.Cu")
		(net "PVDDCR_CPU1_P0")
	)
	(via
		(at 345.451176 -290.285932)
		(size 0.4064)
		(drill 0.2032)
		(layers "F.Cu" "B.Cu")
		(net "PVDDCR_CPU1_P0")
	)
	(via
		(at 351.091246 -290.285932)
		(size 0.4064)
		(drill 0.2032)
		(layers "F.Cu" "B.Cu")
		(net "PVDDCR_CPU1_P0")
	)
	(via
		(at 350.412304 -327.319894)
		(size 0.508)
		(drill 0.254)
		(layers "F.Cu" "B.Cu")
		(net "PVDDCR_CPU1_P0")
	)
	(via
		(at 310.185562 -330.291694)
		(size 0.508)
		(drill 0.254)
		(layers "F.Cu" "B.Cu")
		(net "PVDDCR_CPU1_P0")
	)
	(via
		(at 357.201216 -278.136096)
		(size 0.4064)
		(drill 0.2032)
		(layers "F.Cu" "B.Cu")
		(net "PVDDCR_CPU1_P0")
	)
	(via
		(at 348.741238 -268.416024)
		(size 0.4064)
		(drill 0.2032)
		(layers "F.Cu" "B.Cu")
		(net "PVDDCR_CPU1_P0")
	)
	(via
		(at 328.19086 -319.814448)
		(size 0.508)
		(drill 0.254)
		(layers "F.Cu" "B.Cu")
		(net "PVDDCR_CPU1_P0")
	)
	(via
		(at 370.82476 -275.706078)
		(size 0.4064)
		(drill 0.2032)
		(layers "F.Cu" "B.Cu")
		(net "PVDDCR_CPU1_P0")
	)
	(via
		(at 328.82586 -321.08902)
		(size 0.508)
		(drill 0.254)
		(layers "F.Cu" "B.Cu")
		(net "PVDDCR_CPU1_P0")
	)
	(via
		(at 361.894882 -282.996132)
		(size 0.4064)
		(drill 0.2032)
		(layers "F.Cu" "B.Cu")
		(net "PVDDCR_CPU1_P0")
	)
	(via
		(at 325.42226 -317.274448)
		(size 0.508)
		(drill 0.254)
		(layers "F.Cu" "B.Cu")
		(net "PVDDCR_CPU1_P0")
	)
	(via
		(at 345.451176 -272.466054)
		(size 0.4064)
		(drill 0.2032)
		(layers "F.Cu" "B.Cu")
		(net "PVDDCR_CPU1_P0")
	)
	(via
		(at 353.911154 -295.145968)
		(size 0.4064)
		(drill 0.2032)
		(layers "F.Cu" "B.Cu")
		(net "PVDDCR_CPU1_P0")
	)
	(via
		(at 356.261162 -292.71595)
		(size 0.4064)
		(drill 0.2032)
		(layers "F.Cu" "B.Cu")
		(net "PVDDCR_CPU1_P0")
	)
	(via
		(at 353.155504 -326.049894)
		(size 0.508)
		(drill 0.254)
		(layers "F.Cu" "B.Cu")
		(net "PVDDCR_CPU1_P0")
	)
	(via
		(at 345.43746 -323.029326)
		(size 0.508)
		(drill 0.254)
		(layers "F.Cu" "B.Cu")
		(net "PVDDCR_CPU1_P0")
	)
	(via
		(at 324.15226 -322.354448)
		(size 0.508)
		(drill 0.254)
		(layers "F.Cu" "B.Cu")
		(net "PVDDCR_CPU1_P0")
	)
	(via
		(at 345.43746 -319.193926)
		(size 0.508)
		(drill 0.254)
		(layers "F.Cu" "B.Cu")
		(net "PVDDCR_CPU1_P0")
	)
	(via
		(at 337.183476 -321.72402)
		(size 0.508)
		(drill 0.254)
		(layers "F.Cu" "B.Cu")
		(net "PVDDCR_CPU1_P0")
	)
	(via
		(at 320.470276 -321.11061)
		(size 0.508)
		(drill 0.254)
		(layers "F.Cu" "B.Cu")
		(net "PVDDCR_CPU1_P0")
	)
	(via
		(at 346.07246 -316.653926)
		(size 0.508)
		(drill 0.254)
		(layers "F.Cu" "B.Cu")
		(net "PVDDCR_CPU1_P0")
	)
	(via
		(at 310.185562 -332.196694)
		(size 0.508)
		(drill 0.254)
		(layers "F.Cu" "B.Cu")
		(net "PVDDCR_CPU1_P0")
	)
	(via
		(at 332.509876 -317.274448)
		(size 0.508)
		(drill 0.254)
		(layers "F.Cu" "B.Cu")
		(net "PVDDCR_CPU1_P0")
	)
	(via
		(at 362.834682 -286.236156)
		(size 0.4064)
		(drill 0.2032)
		(layers "F.Cu" "B.Cu")
		(net "PVDDCR_CPU1_P0")
	)
	(via
		(at 359.994454 -267.09116)
		(size 0.4826)
		(drill 0.254)
		(layers "F.Cu" "B.Cu")
		(net "PVDDCR_CPU1_P0")
	)
	(via
		(at 358.141016 -274.896072)
		(size 0.4064)
		(drill 0.2032)
		(layers "F.Cu" "B.Cu")
		(net "PVDDCR_CPU1_P0")
	)
	(via
		(at 340.086442 -338.806282)
		(size 0.508)
		(drill 0.254)
		(layers "F.Cu" "B.Cu")
		(net "PVDDCR_CPU1_P0")
	)
	(via
		(at 336.548476 -318.544448)
		(size 0.508)
		(drill 0.254)
		(layers "F.Cu" "B.Cu")
		(net "PVDDCR_CPU1_P0")
	)
	(via
		(at 368.004852 -267.606018)
		(size 0.4064)
		(drill 0.2032)
		(layers "F.Cu" "B.Cu")
		(net "PVDDCR_CPU1_P0")
	)
	(via
		(at 342.05926 -321.103498)
		(size 0.508)
		(drill 0.254)
		(layers "F.Cu" "B.Cu")
		(net "PVDDCR_CPU1_P0")
	)
	(via
		(at 324.81266 -321.72402)
		(size 0.508)
		(drill 0.254)
		(layers "F.Cu" "B.Cu")
		(net "PVDDCR_CPU1_P0")
	)
	(via
		(at 336.54746 -323.003926)
		(size 0.508)
		(drill 0.254)
		(layers "F.Cu" "B.Cu")
		(net "PVDDCR_CPU1_P0")
	)
	(via
		(at 356.261162 -266.796012)
		(size 0.4064)
		(drill 0.2032)
		(layers "F.Cu" "B.Cu")
		(net "PVDDCR_CPU1_P0")
	)
	(via
		(at 321.105276 -318.566038)
		(size 0.508)
		(drill 0.254)
		(layers "F.Cu" "B.Cu")
		(net "PVDDCR_CPU1_P0")
	)
	(via
		(at 337.818476 -317.909448)
		(size 0.508)
		(drill 0.254)
		(layers "F.Cu" "B.Cu")
		(net "PVDDCR_CPU1_P0")
	)
	(via
		(at 337.818476 -317.274448)
		(size 0.508)
		(drill 0.254)
		(layers "F.Cu" "B.Cu")
		(net "PVDDCR_CPU1_P0")
	)
	(via
		(at 324.15226 -320.449448)
		(size 0.508)
		(drill 0.254)
		(layers "F.Cu" "B.Cu")
		(net "PVDDCR_CPU1_P0")
	)
	(via
		(at 329.46086 -321.719448)
		(size 0.508)
		(drill 0.254)
		(layers "F.Cu" "B.Cu")
		(net "PVDDCR_CPU1_P0")
	)
	(via
		(at 310.185562 -331.561694)
		(size 0.508)
		(drill 0.254)
		(layers "F.Cu" "B.Cu")
		(net "PVDDCR_CPU1_P0")
	)
	(via
		(at 352.9711 -291.905944)
		(size 0.4064)
		(drill 0.2032)
		(layers "F.Cu" "B.Cu")
		(net "PVDDCR_CPU1_P0")
	)
	(via
		(at 320.470276 -321.74561)
		(size 0.508)
		(drill 0.254)
		(layers "F.Cu" "B.Cu")
		(net "PVDDCR_CPU1_P0")
	)
	(via
		(at 345.451176 -275.706078)
		(size 0.4064)
		(drill 0.2032)
		(layers "F.Cu" "B.Cu")
		(net "PVDDCR_CPU1_P0")
	)
	(via
		(at 355.791008 -291.905944)
		(size 0.4064)
		(drill 0.2032)
		(layers "F.Cu" "B.Cu")
		(net "PVDDCR_CPU1_P0")
	)
	(via
		(at 316.457076 -321.74561)
		(size 0.508)
		(drill 0.254)
		(layers "F.Cu" "B.Cu")
		(net "PVDDCR_CPU1_P0")
	)
	(via
		(at 354.851208 -267.606018)
		(size 0.4064)
		(drill 0.2032)
		(layers "F.Cu" "B.Cu")
		(net "PVDDCR_CPU1_P0")
	)
	(via
		(at 342.03386 -317.288926)
		(size 0.508)
		(drill 0.254)
		(layers "F.Cu" "B.Cu")
		(net "PVDDCR_CPU1_P0")
	)
	(via
		(at 373.644922 -275.706078)
		(size 0.4064)
		(drill 0.2032)
		(layers "F.Cu" "B.Cu")
		(net "PVDDCR_CPU1_P0")
	)
	(via
		(at 346.07246 -321.124326)
		(size 0.508)
		(drill 0.254)
		(layers "F.Cu" "B.Cu")
		(net "PVDDCR_CPU1_P0")
	)
	(via
		(at 371.764814 -275.706078)
		(size 0.4064)
		(drill 0.2032)
		(layers "F.Cu" "B.Cu")
		(net "PVDDCR_CPU1_P0")
	)
	(via
		(at 362.834682 -289.475926)
		(size 0.4064)
		(drill 0.2032)
		(layers "F.Cu" "B.Cu")
		(net "PVDDCR_CPU1_P0")
	)
	(via
		(at 368.004852 -269.22603)
		(size 0.4064)
		(drill 0.2032)
		(layers "F.Cu" "B.Cu")
		(net "PVDDCR_CPU1_P0")
	)
	(via
		(at 332.50886 -323.003926)
		(size 0.508)
		(drill 0.254)
		(layers "F.Cu" "B.Cu")
		(net "PVDDCR_CPU1_P0")
	)
	(via
		(at 324.15226 -317.274448)
		(size 0.508)
		(drill 0.254)
		(layers "F.Cu" "B.Cu")
		(net "PVDDCR_CPU1_P0")
	)
	(via
		(at 354.425504 -327.340722)
		(size 0.508)
		(drill 0.254)
		(layers "F.Cu" "B.Cu")
		(net "PVDDCR_CPU1_P0")
	)
	(via
		(at 344.80246 -316.653926)
		(size 0.508)
		(drill 0.254)
		(layers "F.Cu" "B.Cu")
		(net "PVDDCR_CPU1_P0")
	)
	(via
		(at 354.425504 -323.505322)
		(size 0.508)
		(drill 0.254)
		(layers "F.Cu" "B.Cu")
		(net "PVDDCR_CPU1_P0")
	)
	(via
		(at 368.004852 -283.806138)
		(size 0.4064)
		(drill 0.2032)
		(layers "F.Cu" "B.Cu")
		(net "PVDDCR_CPU1_P0")
	)
	(via
		(at 363.304836 -280.566114)
		(size 0.4064)
		(drill 0.2032)
		(layers "F.Cu" "B.Cu")
		(net "PVDDCR_CPU1_P0")
	)
	(via
		(at 368.474752 -281.37612)
		(size 0.4064)
		(drill 0.2032)
		(layers "F.Cu" "B.Cu")
		(net "PVDDCR_CPU1_P0")
	)
	(via
		(at 337.183476 -320.45402)
		(size 0.508)
		(drill 0.254)
		(layers "F.Cu" "B.Cu")
		(net "PVDDCR_CPU1_P0")
	)
	(via
		(at 352.5012 -281.37612)
		(size 0.4064)
		(drill 0.2032)
		(layers "F.Cu" "B.Cu")
		(net "PVDDCR_CPU1_P0")
	)
	(via
		(at 315.796676 -321.741038)
		(size 0.508)
		(drill 0.254)
		(layers "F.Cu" "B.Cu")
		(net "PVDDCR_CPU1_P0")
	)
	(via
		(at 352.5012 -266.796012)
		(size 0.4064)
		(drill 0.2032)
		(layers "F.Cu" "B.Cu")
		(net "PVDDCR_CPU1_P0")
	)
	(via
		(at 328.19086 -318.544448)
		(size 0.508)
		(drill 0.254)
		(layers "F.Cu" "B.Cu")
		(net "PVDDCR_CPU1_P0")
	)
	(via
		(at 353.155504 -325.414894)
		(size 0.508)
		(drill 0.254)
		(layers "F.Cu" "B.Cu")
		(net "PVDDCR_CPU1_P0")
	)
	(via
		(at 306.172362 -330.291694)
		(size 0.508)
		(drill 0.254)
		(layers "F.Cu" "B.Cu")
		(net "PVDDCR_CPU1_P0")
	)
	(via
		(at 350.621092 -292.71595)
		(size 0.4064)
		(drill 0.2032)
		(layers "F.Cu" "B.Cu")
		(net "PVDDCR_CPU1_P0")
	)
	(via
		(at 344.80246 -321.103498)
		(size 0.508)
		(drill 0.254)
		(layers "F.Cu" "B.Cu")
		(net "PVDDCR_CPU1_P0")
	)
	(via
		(at 349.751904 -321.600322)
		(size 0.508)
		(drill 0.254)
		(layers "F.Cu" "B.Cu")
		(net "PVDDCR_CPU1_P0")
	)
	(via
		(at 344.80246 -319.828926)
		(size 0.508)
		(drill 0.254)
		(layers "F.Cu" "B.Cu")
		(net "PVDDCR_CPU1_P0")
	)
	(via
		(at 344.80246 -317.923926)
		(size 0.508)
		(drill 0.254)
		(layers "F.Cu" "B.Cu")
		(net "PVDDCR_CPU1_P0")
	)
	(via
		(at 350.386904 -322.235322)
		(size 0.508)
		(drill 0.254)
		(layers "F.Cu" "B.Cu")
		(net "PVDDCR_CPU1_P0")
	)
	(via
		(at 324.790816 -323.003926)
		(size 0.508)
		(drill 0.254)
		(layers "F.Cu" "B.Cu")
		(net "PVDDCR_CPU1_P0")
	)
	(via
		(at 349.211138 -290.285932)
		(size 0.4064)
		(drill 0.2032)
		(layers "F.Cu" "B.Cu")
		(net "PVDDCR_CPU1_P0")
	)
	(via
		(at 362.834682 -292.71595)
		(size 0.4064)
		(drill 0.2032)
		(layers "F.Cu" "B.Cu")
		(net "PVDDCR_CPU1_P0")
	)
	(via
		(at 365.18469 -278.946102)
		(size 0.4064)
		(drill 0.2032)
		(layers "F.Cu" "B.Cu")
		(net "PVDDCR_CPU1_P0")
	)
	(via
		(at 349.777304 -327.319894)
		(size 0.508)
		(drill 0.254)
		(layers "F.Cu" "B.Cu")
		(net "PVDDCR_CPU1_P0")
	)
	(via
		(at 342.03386 -318.558926)
		(size 0.508)
		(drill 0.254)
		(layers "F.Cu" "B.Cu")
		(net "PVDDCR_CPU1_P0")
	)
	(via
		(at 345.43746 -320.468498)
		(size 0.508)
		(drill 0.254)
		(layers "F.Cu" "B.Cu")
		(net "PVDDCR_CPU1_P0")
	)
	(via
		(at 328.19086 -322.35902)
		(size 0.508)
		(drill 0.254)
		(layers "F.Cu" "B.Cu")
		(net "PVDDCR_CPU1_P0")
	)
	(via
		(at 307.442362 -330.926694)
		(size 0.508)
		(drill 0.254)
		(layers "F.Cu" "B.Cu")
		(net "PVDDCR_CPU1_P0")
	)
	(via
		(at 321.105276 -321.741038)
		(size 0.508)
		(drill 0.254)
		(layers "F.Cu" "B.Cu")
		(net "PVDDCR_CPU1_P0")
	)
	(via
		(at 307.442362 -331.561694)
		(size 0.508)
		(drill 0.254)
		(layers "F.Cu" "B.Cu")
		(net "PVDDCR_CPU1_P0")
	)
	(via
		(at 354.851208 -272.466054)
		(size 0.4064)
		(drill 0.2032)
		(layers "F.Cu" "B.Cu")
		(net "PVDDCR_CPU1_P0")
	)
	(via
		(at 361.894882 -286.236156)
		(size 0.4064)
		(drill 0.2032)
		(layers "F.Cu" "B.Cu")
		(net "PVDDCR_CPU1_P0")
	)
	(via
		(at 370.82476 -272.466054)
		(size 0.4064)
		(drill 0.2032)
		(layers "F.Cu" "B.Cu")
		(net "PVDDCR_CPU1_P0")
	)
	(via
		(at 320.470276 -322.38061)
		(size 0.508)
		(drill 0.254)
		(layers "F.Cu" "B.Cu")
		(net "PVDDCR_CPU1_P0")
	)
	(via
		(at 371.764814 -287.045908)
		(size 0.4064)
		(drill 0.2032)
		(layers "F.Cu" "B.Cu")
		(net "PVDDCR_CPU1_P0")
	)
	(via
		(at 356.731062 -280.566114)
		(size 0.4064)
		(drill 0.2032)
		(layers "F.Cu" "B.Cu")
		(net "PVDDCR_CPU1_P0")
	)
	(via
		(at 337.183476 -321.08902)
		(size 0.508)
		(drill 0.254)
		(layers "F.Cu" "B.Cu")
		(net "PVDDCR_CPU1_P0")
	)
	(via
		(at 321.105276 -317.931038)
		(size 0.508)
		(drill 0.254)
		(layers "F.Cu" "B.Cu")
		(net "PVDDCR_CPU1_P0")
	)
	(via
		(at 341.39886 -317.288926)
		(size 0.508)
		(drill 0.254)
		(layers "F.Cu" "B.Cu")
		(net "PVDDCR_CPU1_P0")
	)
	(via
		(at 306.807362 -330.291694)
		(size 0.508)
		(drill 0.254)
		(layers "F.Cu" "B.Cu")
		(net "PVDDCR_CPU1_P0")
	)
	(via
		(at 362.834682 -268.416024)
		(size 0.4064)
		(drill 0.2032)
		(layers "F.Cu" "B.Cu")
		(net "PVDDCR_CPU1_P0")
	)
	(via
		(at 352.031046 -275.706078)
		(size 0.4064)
		(drill 0.2032)
		(layers "F.Cu" "B.Cu")
		(net "PVDDCR_CPU1_P0")
	)
	(via
		(at 333.77886 -323.003926)
		(size 0.508)
		(drill 0.254)
		(layers "F.Cu" "B.Cu")
		(net "PVDDCR_CPU1_P0")
	)
	(via
		(at 353.911154 -290.285932)
		(size 0.4064)
		(drill 0.2032)
		(layers "F.Cu" "B.Cu")
		(net "PVDDCR_CPU1_P0")
	)
	(via
		(at 348.271084 -287.045908)
		(size 0.4064)
		(drill 0.2032)
		(layers "F.Cu" "B.Cu")
		(net "PVDDCR_CPU1_P0")
	)
	(via
		(at 337.818476 -322.354448)
		(size 0.508)
		(drill 0.254)
		(layers "F.Cu" "B.Cu")
		(net "PVDDCR_CPU1_P0")
	)
	(via
		(at 337.818476 -321.084448)
		(size 0.508)
		(drill 0.254)
		(layers "F.Cu" "B.Cu")
		(net "PVDDCR_CPU1_P0")
	)
	(via
		(at 319.835276 -321.74561)
		(size 0.508)
		(drill 0.254)
		(layers "F.Cu" "B.Cu")
		(net "PVDDCR_CPU1_P0")
	)
	(via
		(at 345.43746 -322.373498)
		(size 0.508)
		(drill 0.254)
		(layers "F.Cu" "B.Cu")
		(net "PVDDCR_CPU1_P0")
	)
	(via
		(at 341.42426 -323.029326)
		(size 0.508)
		(drill 0.254)
		(layers "F.Cu" "B.Cu")
		(net "PVDDCR_CPU1_P0")
	)
	(via
		(at 324.15226 -319.179448)
		(size 0.508)
		(drill 0.254)
		(layers "F.Cu" "B.Cu")
		(net "PVDDCR_CPU1_P0")
	)
	(via
		(at 307.442362 -332.196694)
		(size 0.508)
		(drill 0.254)
		(layers "F.Cu" "B.Cu")
		(net "PVDDCR_CPU1_P0")
	)
	(via
		(at 354.425504 -322.870322)
		(size 0.508)
		(drill 0.254)
		(layers "F.Cu" "B.Cu")
		(net "PVDDCR_CPU1_P0")
	)
	(via
		(at 324.78726 -319.179448)
		(size 0.508)
		(drill 0.254)
		(layers "F.Cu" "B.Cu")
		(net "PVDDCR_CPU1_P0")
	)
	(via
		(at 352.031046 -269.22603)
		(size 0.4064)
		(drill 0.2032)
		(layers "F.Cu" "B.Cu")
		(net "PVDDCR_CPU1_P0")
	)
	(via
		(at 310.820562 -330.926694)
		(size 0.508)
		(drill 0.254)
		(layers "F.Cu" "B.Cu")
		(net "PVDDCR_CPU1_P0")
	)
	(via
		(at 349.777304 -326.684894)
		(size 0.508)
		(drill 0.254)
		(layers "F.Cu" "B.Cu")
		(net "PVDDCR_CPU1_P0")
	)
	(via
		(at 340.76386 -317.923926)
		(size 0.508)
		(drill 0.254)
		(layers "F.Cu" "B.Cu")
		(net "PVDDCR_CPU1_P0")
	)
	(via
		(at 352.031046 -272.466054)
		(size 0.4064)
		(drill 0.2032)
		(layers "F.Cu" "B.Cu")
		(net "PVDDCR_CPU1_P0")
	)
	(via
		(at 325.425816 -323.003926)
		(size 0.508)
		(drill 0.254)
		(layers "F.Cu" "B.Cu")
		(net "PVDDCR_CPU1_P0")
	)
	(via
		(at 349.777304 -326.049894)
		(size 0.508)
		(drill 0.254)
		(layers "F.Cu" "B.Cu")
		(net "PVDDCR_CPU1_P0")
	)
	(via
		(at 306.172362 -331.561694)
		(size 0.508)
		(drill 0.254)
		(layers "F.Cu" "B.Cu")
		(net "PVDDCR_CPU1_P0")
	)
	(via
		(at 348.271084 -272.466054)
		(size 0.4064)
		(drill 0.2032)
		(layers "F.Cu" "B.Cu")
		(net "PVDDCR_CPU1_P0")
	)
	(via
		(at 319.835276 -321.11061)
		(size 0.508)
		(drill 0.254)
		(layers "F.Cu" "B.Cu")
		(net "PVDDCR_CPU1_P0")
	)
	(via
		(at 361.894882 -291.095938)
		(size 0.4064)
		(drill 0.2032)
		(layers "F.Cu" "B.Cu")
		(net "PVDDCR_CPU1_P0")
	)
	(via
		(at 348.741238 -266.796012)
		(size 0.4064)
		(drill 0.2032)
		(layers "F.Cu" "B.Cu")
		(net "PVDDCR_CPU1_P0")
	)
	(via
		(at 315.800232 -323.025516)
		(size 0.508)
		(drill 0.254)
		(layers "F.Cu" "B.Cu")
		(net "PVDDCR_CPU1_P0")
	)
	(via
		(at 328.82586 -316.639448)
		(size 0.508)
		(drill 0.254)
		(layers "F.Cu" "B.Cu")
		(net "PVDDCR_CPU1_P0")
	)
	(via
		(at 306.172362 -330.926694)
		(size 0.508)
		(drill 0.254)
		(layers "F.Cu" "B.Cu")
		(net "PVDDCR_CPU1_P0")
	)
	(via
		(at 328.19086 -317.274448)
		(size 0.508)
		(drill 0.254)
		(layers "F.Cu" "B.Cu")
		(net "PVDDCR_CPU1_P0")
	)
	(via
		(at 325.44766 -320.45402)
		(size 0.508)
		(drill 0.254)
		(layers "F.Cu" "B.Cu")
		(net "PVDDCR_CPU1_P0")
	)
	(via
		(at 337.18246 -323.003926)
		(size 0.508)
		(drill 0.254)
		(layers "F.Cu" "B.Cu")
		(net "PVDDCR_CPU1_P0")
	)
	(via
		(at 328.19086 -319.179448)
		(size 0.508)
		(drill 0.254)
		(layers "F.Cu" "B.Cu")
		(net "PVDDCR_CPU1_P0")
	)
	(via
		(at 321.105276 -320.471038)
		(size 0.508)
		(drill 0.254)
		(layers "F.Cu" "B.Cu")
		(net "PVDDCR_CPU1_P0")
	)
	(via
		(at 353.790504 -324.775322)
		(size 0.508)
		(drill 0.254)
		(layers "F.Cu" "B.Cu")
		(net "PVDDCR_CPU1_P0")
	)
	(via
		(at 328.82586 -319.814448)
		(size 0.508)
		(drill 0.254)
		(layers "F.Cu" "B.Cu")
		(net "PVDDCR_CPU1_P0")
	)
	(via
		(at 350.412304 -327.975722)
		(size 0.508)
		(drill 0.254)
		(layers "F.Cu" "B.Cu")
		(net "PVDDCR_CPU1_P0")
	)
	(via
		(at 307.442362 -334.736694)
		(size 0.508)
		(drill 0.254)
		(layers "F.Cu" "B.Cu")
		(net "PVDDCR_CPU1_P0")
	)
	(via
		(at 345.43746 -317.288926)
		(size 0.508)
		(drill 0.254)
		(layers "F.Cu" "B.Cu")
		(net "PVDDCR_CPU1_P0")
	)
	(via
		(at 347.33103 -291.905944)
		(size 0.4064)
		(drill 0.2032)
		(layers "F.Cu" "B.Cu")
		(net "PVDDCR_CPU1_P0")
	)
	(via
		(at 324.81266 -321.08902)
		(size 0.508)
		(drill 0.254)
		(layers "F.Cu" "B.Cu")
		(net "PVDDCR_CPU1_P0")
	)
	(via
		(at 336.548476 -321.72402)
		(size 0.508)
		(drill 0.254)
		(layers "F.Cu" "B.Cu")
		(net "PVDDCR_CPU1_P0")
	)
	(via
		(at 337.81746 -323.003926)
		(size 0.508)
		(drill 0.254)
		(layers "F.Cu" "B.Cu")
		(net "PVDDCR_CPU1_P0")
	)
	(via
		(at 374.584722 -278.946102)
		(size 0.4064)
		(drill 0.2032)
		(layers "F.Cu" "B.Cu")
		(net "PVDDCR_CPU1_P0")
	)
	(via
		(at 366.124744 -275.706078)
		(size 0.4064)
		(drill 0.2032)
		(layers "F.Cu" "B.Cu")
		(net "PVDDCR_CPU1_P0")
	)
	(via
		(at 306.807362 -331.561694)
		(size 0.508)
		(drill 0.254)
		(layers "F.Cu" "B.Cu")
		(net "PVDDCR_CPU1_P0")
	)
	(via
		(at 328.19086 -317.909448)
		(size 0.508)
		(drill 0.254)
		(layers "F.Cu" "B.Cu")
		(net "PVDDCR_CPU1_P0")
	)
	(via
		(at 348.271084 -295.145968)
		(size 0.4064)
		(drill 0.2032)
		(layers "F.Cu" "B.Cu")
		(net "PVDDCR_CPU1_P0")
	)
	(via
		(at 315.796676 -320.471038)
		(size 0.508)
		(drill 0.254)
		(layers "F.Cu" "B.Cu")
		(net "PVDDCR_CPU1_P0")
	)
	(via
		(at 342.03386 -317.923926)
		(size 0.508)
		(drill 0.254)
		(layers "F.Cu" "B.Cu")
		(net "PVDDCR_CPU1_P0")
	)
	(via
		(at 350.621092 -268.416024)
		(size 0.4064)
		(drill 0.2032)
		(layers "F.Cu" "B.Cu")
		(net "PVDDCR_CPU1_P0")
	)
	(via
		(at 351.091246 -278.946102)
		(size 0.4064)
		(drill 0.2032)
		(layers "F.Cu" "B.Cu")
		(net "PVDDCR_CPU1_P0")
	)
	(via
		(at 332.50886 -322.368926)
		(size 0.508)
		(drill 0.254)
		(layers "F.Cu" "B.Cu")
		(net "PVDDCR_CPU1_P0")
	)
	(via
		(at 333.805276 -321.72402)
		(size 0.508)
		(drill 0.254)
		(layers "F.Cu" "B.Cu")
		(net "PVDDCR_CPU1_P0")
	)
	(via
		(at 319.835276 -318.566038)
		(size 0.508)
		(drill 0.254)
		(layers "F.Cu" "B.Cu")
		(net "PVDDCR_CPU1_P0")
	)
	(via
		(at 358.141016 -268.416024)
		(size 0.4064)
		(drill 0.2032)
		(layers "F.Cu" "B.Cu")
		(net "PVDDCR_CPU1_P0")
	)
	(via
		(at 341.39886 -318.558926)
		(size 0.508)
		(drill 0.254)
		(layers "F.Cu" "B.Cu")
		(net "PVDDCR_CPU1_P0")
	)
	(via
		(at 332.50886 -320.463926)
		(size 0.508)
		(drill 0.254)
		(layers "F.Cu" "B.Cu")
		(net "PVDDCR_CPU1_P0")
	)
	(via
		(at 348.271084 -283.806138)
		(size 0.4064)
		(drill 0.2032)
		(layers "F.Cu" "B.Cu")
		(net "PVDDCR_CPU1_P0")
	)
	(via
		(at 317.066676 -319.836038)
		(size 0.508)
		(drill 0.254)
		(layers "F.Cu" "B.Cu")
		(net "PVDDCR_CPU1_P0")
	)
	(via
		(at 320.470276 -317.296038)
		(size 0.508)
		(drill 0.254)
		(layers "F.Cu" "B.Cu")
		(net "PVDDCR_CPU1_P0")
	)
	(via
		(at 324.15226 -317.909448)
		(size 0.508)
		(drill 0.254)
		(layers "F.Cu" "B.Cu")
		(net "PVDDCR_CPU1_P0")
	)
	(via
		(at 374.584722 -283.806138)
		(size 0.4064)
		(drill 0.2032)
		(layers "F.Cu" "B.Cu")
		(net "PVDDCR_CPU1_P0")
	)
	(via
		(at 368.944906 -275.706078)
		(size 0.4064)
		(drill 0.2032)
		(layers "F.Cu" "B.Cu")
		(net "PVDDCR_CPU1_P0")
	)
	(via
		(at 364.24489 -291.905944)
		(size 0.4064)
		(drill 0.2032)
		(layers "F.Cu" "B.Cu")
		(net "PVDDCR_CPU1_P0")
	)
	(via
		(at 333.144876 -317.909448)
		(size 0.508)
		(drill 0.254)
		(layers "F.Cu" "B.Cu")
		(net "PVDDCR_CPU1_P0")
	)
	(via
		(at 306.172362 -332.831694)
		(size 0.508)
		(drill 0.254)
		(layers "F.Cu" "B.Cu")
		(net "PVDDCR_CPU1_P0")
	)
	(via
		(at 310.185562 -330.926694)
		(size 0.508)
		(drill 0.254)
		(layers "F.Cu" "B.Cu")
		(net "PVDDCR_CPU1_P0")
	)
	(via
		(at 349.751904 -324.775322)
		(size 0.508)
		(drill 0.254)
		(layers "F.Cu" "B.Cu")
		(net "PVDDCR_CPU1_P0")
	)
	(via
		(at 332.509876 -319.179448)
		(size 0.508)
		(drill 0.254)
		(layers "F.Cu" "B.Cu")
		(net "PVDDCR_CPU1_P0")
	)
	(via
		(at 329.46086 -320.449448)
		(size 0.508)
		(drill 0.254)
		(layers "F.Cu" "B.Cu")
		(net "PVDDCR_CPU1_P0")
	)
	(via
		(at 374.584722 -287.045908)
		(size 0.4064)
		(drill 0.2032)
		(layers "F.Cu" "B.Cu")
		(net "PVDDCR_CPU1_P0")
	)
	(via
		(at 375.524776 -291.905944)
		(size 0.4064)
		(drill 0.2032)
		(layers "F.Cu" "B.Cu")
		(net "PVDDCR_CPU1_P0")
	)
	(via
		(at 317.092076 -320.47561)
		(size 0.508)
		(drill 0.254)
		(layers "F.Cu" "B.Cu")
		(net "PVDDCR_CPU1_P0")
	)
	(via
		(at 342.161114 -294.335962)
		(size 0.4064)
		(drill 0.2032)
		(layers "F.Cu" "B.Cu")
		(net "PVDDCR_CPU1_P0")
	)
	(via
		(at 353.790504 -326.049894)
		(size 0.508)
		(drill 0.254)
		(layers "F.Cu" "B.Cu")
		(net "PVDDCR_CPU1_P0")
	)
	(via
		(at 325.42226 -319.179448)
		(size 0.508)
		(drill 0.254)
		(layers "F.Cu" "B.Cu")
		(net "PVDDCR_CPU1_P0")
	)
	(via
		(at 337.818476 -320.449448)
		(size 0.508)
		(drill 0.254)
		(layers "F.Cu" "B.Cu")
		(net "PVDDCR_CPU1_P0")
	)
	(via
		(at 328.19086 -316.639448)
		(size 0.508)
		(drill 0.254)
		(layers "F.Cu" "B.Cu")
		(net "PVDDCR_CPU1_P0")
	)
	(via
		(at 305.392328 -350.498156)
		(size 0.508)
		(drill 0.254)
		(layers "F.Cu" "B.Cu")
		(net "PVDDCR_CPU1_P0")
	)
	(via
		(at 371.764814 -278.946102)
		(size 0.4064)
		(drill 0.2032)
		(layers "F.Cu" "B.Cu")
		(net "PVDDCR_CPU1_P0")
	)
	(via
		(at 351.091246 -283.806138)
		(size 0.4064)
		(drill 0.2032)
		(layers "F.Cu" "B.Cu")
		(net "PVDDCR_CPU1_P0")
	)
	(via
		(at 333.144876 -319.179448)
		(size 0.508)
		(drill 0.254)
		(layers "F.Cu" "B.Cu")
		(net "PVDDCR_CPU1_P0")
	)
	(via
		(at 357.201216 -286.236156)
		(size 0.4064)
		(drill 0.2032)
		(layers "F.Cu" "B.Cu")
		(net "PVDDCR_CPU1_P0")
	)
	(via
		(at 324.15226 -316.639448)
		(size 0.508)
		(drill 0.254)
		(layers "F.Cu" "B.Cu")
		(net "PVDDCR_CPU1_P0")
	)
	(via
		(at 348.271084 -269.22603)
		(size 0.4064)
		(drill 0.2032)
		(layers "F.Cu" "B.Cu")
		(net "PVDDCR_CPU1_P0")
	)
	(via
		(at 354.381054 -268.416024)
		(size 0.4064)
		(drill 0.2032)
		(layers "F.Cu" "B.Cu")
		(net "PVDDCR_CPU1_P0")
	)
	(via
		(at 310.185562 -333.466694)
		(size 0.508)
		(drill 0.254)
		(layers "F.Cu" "B.Cu")
		(net "PVDDCR_CPU1_P0")
	)
	(via
		(at 345.451176 -278.946102)
		(size 0.4064)
		(drill 0.2032)
		(layers "F.Cu" "B.Cu")
		(net "PVDDCR_CPU1_P0")
	)
	(via
		(at 320.448432 -323.025516)
		(size 0.508)
		(drill 0.254)
		(layers "F.Cu" "B.Cu")
		(net "PVDDCR_CPU1_P0")
	)
	(via
		(at 310.820562 -332.831694)
		(size 0.508)
		(drill 0.254)
		(layers "F.Cu" "B.Cu")
		(net "PVDDCR_CPU1_P0")
	)
	(via
		(at 344.80246 -320.468498)
		(size 0.508)
		(drill 0.254)
		(layers "F.Cu" "B.Cu")
		(net "PVDDCR_CPU1_P0")
	)
	(via
		(at 357.201216 -292.71595)
		(size 0.4064)
		(drill 0.2032)
		(layers "F.Cu" "B.Cu")
		(net "PVDDCR_CPU1_P0")
	)
	(via
		(at 366.594898 -268.416024)
		(size 0.4064)
		(drill 0.2032)
		(layers "F.Cu" "B.Cu")
		(net "PVDDCR_CPU1_P0")
	)
	(via
		(at 320.470276 -317.931038)
		(size 0.508)
		(drill 0.254)
		(layers "F.Cu" "B.Cu")
		(net "PVDDCR_CPU1_P0")
	)
	(via
		(at 358.141016 -286.236156)
		(size 0.4064)
		(drill 0.2032)
		(layers "F.Cu" "B.Cu")
		(net "PVDDCR_CPU1_P0")
	)
	(via
		(at 329.46086 -322.354448)
		(size 0.508)
		(drill 0.254)
		(layers "F.Cu" "B.Cu")
		(net "PVDDCR_CPU1_P0")
	)
	(via
		(at 353.911154 -278.946102)
		(size 0.4064)
		(drill 0.2032)
		(layers "F.Cu" "B.Cu")
		(net "PVDDCR_CPU1_P0")
	)
	(via
		(at 328.82586 -317.909448)
		(size 0.508)
		(drill 0.254)
		(layers "F.Cu" "B.Cu")
		(net "PVDDCR_CPU1_P0")
	)
	(via
		(at 353.911154 -283.806138)
		(size 0.4064)
		(drill 0.2032)
		(layers "F.Cu" "B.Cu")
		(net "PVDDCR_CPU1_P0")
	)
	(via
		(at 371.764814 -267.606018)
		(size 0.4064)
		(drill 0.2032)
		(layers "F.Cu" "B.Cu")
		(net "PVDDCR_CPU1_P0")
	)
	(via
		(at 337.183476 -319.814448)
		(size 0.508)
		(drill 0.254)
		(layers "F.Cu" "B.Cu")
		(net "PVDDCR_CPU1_P0")
	)
	(via
		(at 349.142304 -325.435722)
		(size 0.508)
		(drill 0.254)
		(layers "F.Cu" "B.Cu")
		(net "PVDDCR_CPU1_P0")
	)
	(via
		(at 349.142304 -326.705722)
		(size 0.508)
		(drill 0.254)
		(layers "F.Cu" "B.Cu")
		(net "PVDDCR_CPU1_P0")
	)
	(via
		(at 366.594898 -266.796012)
		(size 0.4064)
		(drill 0.2032)
		(layers "F.Cu" "B.Cu")
		(net "PVDDCR_CPU1_P0")
	)
	(via
		(at 366.124744 -290.285932)
		(size 0.4064)
		(drill 0.2032)
		(layers "F.Cu" "B.Cu")
		(net "PVDDCR_CPU1_P0")
	)
	(via
		(at 333.779876 -316.639448)
		(size 0.508)
		(drill 0.254)
		(layers "F.Cu" "B.Cu")
		(net "PVDDCR_CPU1_P0")
	)
	(via
		(at 358.141016 -289.475926)
		(size 0.4064)
		(drill 0.2032)
		(layers "F.Cu" "B.Cu")
		(net "PVDDCR_CPU1_P0")
	)
	(via
		(at 349.751904 -323.505322)
		(size 0.508)
		(drill 0.254)
		(layers "F.Cu" "B.Cu")
		(net "PVDDCR_CPU1_P0")
	)
	(via
		(at 346.07246 -317.923926)
		(size 0.508)
		(drill 0.254)
		(layers "F.Cu" "B.Cu")
		(net "PVDDCR_CPU1_P0")
	)
	(via
		(at 353.155504 -326.684894)
		(size 0.508)
		(drill 0.254)
		(layers "F.Cu" "B.Cu")
		(net "PVDDCR_CPU1_P0")
	)
	(via
		(at 357.201216 -289.475926)
		(size 0.4064)
		(drill 0.2032)
		(layers "F.Cu" "B.Cu")
		(net "PVDDCR_CPU1_P0")
	)
	(via
		(at 333.805276 -320.45402)
		(size 0.508)
		(drill 0.254)
		(layers "F.Cu" "B.Cu")
		(net "PVDDCR_CPU1_P0")
	)
	(via
		(at 353.155504 -324.775322)
		(size 0.508)
		(drill 0.254)
		(layers "F.Cu" "B.Cu")
		(net "PVDDCR_CPU1_P0")
	)
	(via
		(at 354.425504 -322.235322)
		(size 0.508)
		(drill 0.254)
		(layers "F.Cu" "B.Cu")
		(net "PVDDCR_CPU1_P0")
	)
	(via
		(at 307.442362 -332.831694)
		(size 0.508)
		(drill 0.254)
		(layers "F.Cu" "B.Cu")
		(net "PVDDCR_CPU1_P0")
	)
	(via
		(at 328.804016 -323.003926)
		(size 0.508)
		(drill 0.254)
		(layers "F.Cu" "B.Cu")
		(net "PVDDCR_CPU1_P0")
	)
	(via
		(at 333.779876 -317.909448)
		(size 0.508)
		(drill 0.254)
		(layers "F.Cu" "B.Cu")
		(net "PVDDCR_CPU1_P0")
	)
	(via
		(at 333.779876 -319.179448)
		(size 0.508)
		(drill 0.254)
		(layers "F.Cu" "B.Cu")
		(net "PVDDCR_CPU1_P0")
	)
	(via
		(at 328.82586 -319.179448)
		(size 0.508)
		(drill 0.254)
		(layers "F.Cu" "B.Cu")
		(net "PVDDCR_CPU1_P0")
	)
	(via
		(at 317.092076 -321.11061)
		(size 0.508)
		(drill 0.254)
		(layers "F.Cu" "B.Cu")
		(net "PVDDCR_CPU1_P0")
	)
	(via
		(at 349.142304 -326.070722)
		(size 0.508)
		(drill 0.254)
		(layers "F.Cu" "B.Cu")
		(net "PVDDCR_CPU1_P0")
	)
	(via
		(at 333.170276 -322.35902)
		(size 0.508)
		(drill 0.254)
		(layers "F.Cu" "B.Cu")
		(net "PVDDCR_CPU1_P0")
	)
	(via
		(at 310.820562 -330.291694)
		(size 0.508)
		(drill 0.254)
		(layers "F.Cu" "B.Cu")
		(net "PVDDCR_CPU1_P0")
	)
	(via
		(at 328.19086 -320.45402)
		(size 0.508)
		(drill 0.254)
		(layers "F.Cu" "B.Cu")
		(net "PVDDCR_CPU1_P0")
	)
	(via
		(at 362.834682 -291.095938)
		(size 0.4064)
		(drill 0.2032)
		(layers "F.Cu" "B.Cu")
		(net "PVDDCR_CPU1_P0")
	)
	(via
		(at 344.80246 -323.029326)
		(size 0.508)
		(drill 0.254)
		(layers "F.Cu" "B.Cu")
		(net "PVDDCR_CPU1_P0")
	)
	(via
		(at 329.439016 -323.003926)
		(size 0.508)
		(drill 0.254)
		(layers "F.Cu" "B.Cu")
		(net "PVDDCR_CPU1_P0")
	)
	(via
		(at 371.764814 -295.145968)
		(size 0.4064)
		(drill 0.2032)
		(layers "F.Cu" "B.Cu")
		(net "PVDDCR_CPU1_P0")
	)
	(via
		(at 337.818476 -319.179448)
		(size 0.508)
		(drill 0.254)
		(layers "F.Cu" "B.Cu")
		(net "PVDDCR_CPU1_P0")
	)
	(via
		(at 367.064798 -295.145968)
		(size 0.4064)
		(drill 0.2032)
		(layers "F.Cu" "B.Cu")
		(net "PVDDCR_CPU1_P0")
	)
	(via
		(at 354.851208 -283.806138)
		(size 0.4064)
		(drill 0.2032)
		(layers "F.Cu" "B.Cu")
		(net "PVDDCR_CPU1_P0")
	)
	(via
		(at 377.874784 -294.335962)
		(size 0.4064)
		(drill 0.2032)
		(layers "F.Cu" "B.Cu")
		(net "PVDDCR_CPU1_P0")
	)
	(via
		(at 349.751904 -324.140322)
		(size 0.508)
		(drill 0.254)
		(layers "F.Cu" "B.Cu")
		(net "PVDDCR_CPU1_P0")
	)
	(via
		(at 354.851208 -269.22603)
		(size 0.4064)
		(drill 0.2032)
		(layers "F.Cu" "B.Cu")
		(net "PVDDCR_CPU1_P0")
	)
	(via
		(at 310.820562 -332.196694)
		(size 0.508)
		(drill 0.254)
		(layers "F.Cu" "B.Cu")
		(net "PVDDCR_CPU1_P0")
	)
	(via
		(at 310.820562 -331.561694)
		(size 0.508)
		(drill 0.254)
		(layers "F.Cu" "B.Cu")
		(net "PVDDCR_CPU1_P0")
	)
	(via
		(at 342.05926 -315.917326)
		(size 0.6604)
		(drill 0.3302)
		(layers "F.Cu" "B.Cu")
		(net "PVDDCR_CPU1_P0")
	)
	(via
		(at 344.981022 -292.71595)
		(size 0.4064)
		(drill 0.2032)
		(layers "F.Cu" "B.Cu")
		(net "PVDDCR_CPU1_P0")
	)
	(via
		(at 344.80246 -317.288926)
		(size 0.508)
		(drill 0.254)
		(layers "F.Cu" "B.Cu")
		(net "PVDDCR_CPU1_P0")
	)
	(via
		(at 367.534698 -281.37612)
		(size 0.4064)
		(drill 0.2032)
		(layers "F.Cu" "B.Cu")
		(net "PVDDCR_CPU1_P0")
	)
	(via
		(at 371.764814 -272.466054)
		(size 0.4064)
		(drill 0.2032)
		(layers "F.Cu" "B.Cu")
		(net "PVDDCR_CPU1_P0")
	)
	(via
		(at 354.425504 -324.140322)
		(size 0.508)
		(drill 0.254)
		(layers "F.Cu" "B.Cu")
		(net "PVDDCR_CPU1_P0")
	)
	(via
		(at 349.211138 -278.946102)
		(size 0.4064)
		(drill 0.2032)
		(layers "F.Cu" "B.Cu")
		(net "PVDDCR_CPU1_P0")
	)
	(via
		(at 340.78926 -321.759326)
		(size 0.508)
		(drill 0.254)
		(layers "F.Cu" "B.Cu")
		(net "PVDDCR_CPU1_P0")
	)
	(via
		(at 328.82586 -322.35902)
		(size 0.508)
		(drill 0.254)
		(layers "F.Cu" "B.Cu")
		(net "PVDDCR_CPU1_P0")
	)
	(via
		(at 332.509876 -319.814448)
		(size 0.508)
		(drill 0.254)
		(layers "F.Cu" "B.Cu")
		(net "PVDDCR_CPU1_P0")
	)
	(via
		(at 362.364782 -280.566114)
		(size 0.4064)
		(drill 0.2032)
		(layers "F.Cu" "B.Cu")
		(net "PVDDCR_CPU1_P0")
	)
	(via
		(at 357.201216 -291.095938)
		(size 0.4064)
		(drill 0.2032)
		(layers "F.Cu" "B.Cu")
		(net "PVDDCR_CPU1_P0")
	)
	(via
		(at 332.509876 -318.544448)
		(size 0.508)
		(drill 0.254)
		(layers "F.Cu" "B.Cu")
		(net "PVDDCR_CPU1_P0")
	)
	(via
		(at 368.944906 -290.285932)
		(size 0.4064)
		(drill 0.2032)
		(layers "F.Cu" "B.Cu")
		(net "PVDDCR_CPU1_P0")
	)
	(via
		(at 341.42426 -320.468498)
		(size 0.508)
		(drill 0.254)
		(layers "F.Cu" "B.Cu")
		(net "PVDDCR_CPU1_P0")
	)
	(via
		(at 337.818476 -318.544448)
		(size 0.508)
		(drill 0.254)
		(layers "F.Cu" "B.Cu")
		(net "PVDDCR_CPU1_P0")
	)
	(via
		(at 323.397626 -338.76996)
		(size 0.508)
		(drill 0.254)
		(layers "F.Cu" "B.Cu")
		(net "PVDDCR_CPU1_P0")
	)
	(via
		(at 337.183476 -316.639448)
		(size 0.508)
		(drill 0.254)
		(layers "F.Cu" "B.Cu")
		(net "PVDDCR_CPU1_P0")
	)
	(via
		(at 319.835276 -317.296038)
		(size 0.508)
		(drill 0.254)
		(layers "F.Cu" "B.Cu")
		(net "PVDDCR_CPU1_P0")
	)
	(via
		(at 340.76386 -319.828926)
		(size 0.508)
		(drill 0.254)
		(layers "F.Cu" "B.Cu")
		(net "PVDDCR_CPU1_P0")
	)
	(via
		(at 325.42226 -317.909448)
		(size 0.508)
		(drill 0.254)
		(layers "F.Cu" "B.Cu")
		(net "PVDDCR_CPU1_P0")
	)
	(via
		(at 358.141016 -291.095938)
		(size 0.4064)
		(drill 0.2032)
		(layers "F.Cu" "B.Cu")
		(net "PVDDCR_CPU1_P0")
	)
	(via
		(at 346.39123 -283.806138)
		(size 0.4064)
		(drill 0.2032)
		(layers "F.Cu" "B.Cu")
		(net "PVDDCR_CPU1_P0")
	)
	(via
		(at 341.39886 -316.653926)
		(size 0.508)
		(drill 0.254)
		(layers "F.Cu" "B.Cu")
		(net "PVDDCR_CPU1_P0")
	)
	(via
		(at 306.172362 -334.736694)
		(size 0.508)
		(drill 0.254)
		(layers "F.Cu" "B.Cu")
		(net "PVDDCR_CPU1_P0")
	)
	(via
		(at 352.031046 -287.045908)
		(size 0.4064)
		(drill 0.2032)
		(layers "F.Cu" "B.Cu")
		(net "PVDDCR_CPU1_P0")
	)
	(via
		(at 307.442362 -334.101694)
		(size 0.508)
		(drill 0.254)
		(layers "F.Cu" "B.Cu")
		(net "PVDDCR_CPU1_P0")
	)
	(via
		(at 351.091246 -287.045908)
		(size 0.4064)
		(drill 0.2032)
		(layers "F.Cu" "B.Cu")
		(net "PVDDCR_CPU1_P0")
	)
	(via
		(at 332.509876 -316.639448)
		(size 0.508)
		(drill 0.254)
		(layers "F.Cu" "B.Cu")
		(net "PVDDCR_CPU1_P0")
	)
	(via
		(at 350.412304 -326.049894)
		(size 0.508)
		(drill 0.254)
		(layers "F.Cu" "B.Cu")
		(net "PVDDCR_CPU1_P0")
	)
	(via
		(at 368.944906 -295.145968)
		(size 0.4064)
		(drill 0.2032)
		(layers "F.Cu" "B.Cu")
		(net "PVDDCR_CPU1_P0")
	)
	(via
		(at 333.805276 -315.902848)
		(size 0.6604)
		(drill 0.3302)
		(layers "F.Cu" "B.Cu")
		(net "PVDDCR_CPU1_P0")
	)
	(via
		(at 336.548476 -317.274448)
		(size 0.508)
		(drill 0.254)
		(layers "F.Cu" "B.Cu")
		(net "PVDDCR_CPU1_P0")
	)
	(via
		(at 354.425504 -326.070722)
		(size 0.508)
		(drill 0.254)
		(layers "F.Cu" "B.Cu")
		(net "PVDDCR_CPU1_P0")
	)
	(via
		(at 354.851208 -275.706078)
		(size 0.4064)
		(drill 0.2032)
		(layers "F.Cu" "B.Cu")
		(net "PVDDCR_CPU1_P0")
	)
	(via
		(at 346.07246 -319.193926)
		(size 0.508)
		(drill 0.254)
		(layers "F.Cu" "B.Cu")
		(net "PVDDCR_CPU1_P0")
	)
	(via
		(at 365.18469 -290.285932)
		(size 0.4064)
		(drill 0.2032)
		(layers "F.Cu" "B.Cu")
		(net "PVDDCR_CPU1_P0")
	)
	(via
		(at 353.155504 -327.319894)
		(size 0.508)
		(drill 0.254)
		(layers "F.Cu" "B.Cu")
		(net "PVDDCR_CPU1_P0")
	)
	(via
		(at 321.083432 -323.025516)
		(size 0.508)
		(drill 0.254)
		(layers "F.Cu" "B.Cu")
		(net "PVDDCR_CPU1_P0")
	)
	(via
		(at 336.548476 -316.639448)
		(size 0.508)
		(drill 0.254)
		(layers "F.Cu" "B.Cu")
		(net "PVDDCR_CPU1_P0")
	)
	(via
		(at 353.441 -292.71595)
		(size 0.4064)
		(drill 0.2032)
		(layers "F.Cu" "B.Cu")
		(net "PVDDCR_CPU1_P0")
	)
	(via
		(at 352.5012 -268.416024)
		(size 0.4064)
		(drill 0.2032)
		(layers "F.Cu" "B.Cu")
		(net "PVDDCR_CPU1_P0")
	)
	(via
		(at 329.46086 -319.814448)
		(size 0.508)
		(drill 0.254)
		(layers "F.Cu" "B.Cu")
		(net "PVDDCR_CPU1_P0")
	)
	(via
		(at 336.548476 -320.45402)
		(size 0.508)
		(drill 0.254)
		(layers "F.Cu" "B.Cu")
		(net "PVDDCR_CPU1_P0")
	)
	(via
		(at 320.470276 -320.47561)
		(size 0.508)
		(drill 0.254)
		(layers "F.Cu" "B.Cu")
		(net "PVDDCR_CPU1_P0")
	)
	(via
		(at 345.43746 -319.828926)
		(size 0.508)
		(drill 0.254)
		(layers "F.Cu" "B.Cu")
		(net "PVDDCR_CPU1_P0")
	)
	(via
		(at 357.201216 -274.896072)
		(size 0.4064)
		(drill 0.2032)
		(layers "F.Cu" "B.Cu")
		(net "PVDDCR_CPU1_P0")
	)
	(via
		(at 353.155504 -327.975722)
		(size 0.508)
		(drill 0.254)
		(layers "F.Cu" "B.Cu")
		(net "PVDDCR_CPU1_P0")
	)
	(via
		(at 345.43746 -317.923926)
		(size 0.508)
		(drill 0.254)
		(layers "F.Cu" "B.Cu")
		(net "PVDDCR_CPU1_P0")
	)
	(via
		(at 374.584722 -275.706078)
		(size 0.4064)
		(drill 0.2032)
		(layers "F.Cu" "B.Cu")
		(net "PVDDCR_CPU1_P0")
	)
	(via
		(at 310.185562 -334.101694)
		(size 0.508)
		(drill 0.254)
		(layers "F.Cu" "B.Cu")
		(net "PVDDCR_CPU1_P0")
	)
	(via
		(at 349.751904 -322.870322)
		(size 0.508)
		(drill 0.254)
		(layers "F.Cu" "B.Cu")
		(net "PVDDCR_CPU1_P0")
	)
	(via
		(at 342.05926 -321.738498)
		(size 0.508)
		(drill 0.254)
		(layers "F.Cu" "B.Cu")
		(net "PVDDCR_CPU1_P0")
	)
	(via
		(at 337.818476 -316.639448)
		(size 0.508)
		(drill 0.254)
		(layers "F.Cu" "B.Cu")
		(net "PVDDCR_CPU1_P0")
	)
	(via
		(at 310.820562 -334.736694)
		(size 0.508)
		(drill 0.254)
		(layers "F.Cu" "B.Cu")
		(net "PVDDCR_CPU1_P0")
	)
	(via
		(at 371.764814 -269.22603)
		(size 0.4064)
		(drill 0.2032)
		(layers "F.Cu" "B.Cu")
		(net "PVDDCR_CPU1_P0")
	)
	(via
		(at 352.031046 -290.285932)
		(size 0.4064)
		(drill 0.2032)
		(layers "F.Cu" "B.Cu")
		(net "PVDDCR_CPU1_P0")
	)
	(via
		(at 306.807362 -334.736694)
		(size 0.508)
		(drill 0.254)
		(layers "F.Cu" "B.Cu")
		(net "PVDDCR_CPU1_P0")
	)
	(via
		(at 366.124744 -283.806138)
		(size 0.4064)
		(drill 0.2032)
		(layers "F.Cu" "B.Cu")
		(net "PVDDCR_CPU1_P0")
	)
	(via
		(at 333.805276 -322.35902)
		(size 0.508)
		(drill 0.254)
		(layers "F.Cu" "B.Cu")
		(net "PVDDCR_CPU1_P0")
	)
	(via
		(at 332.509876 -317.909448)
		(size 0.508)
		(drill 0.254)
		(layers "F.Cu" "B.Cu")
		(net "PVDDCR_CPU1_P0")
	)
	(via
		(at 373.644922 -269.22603)
		(size 0.4064)
		(drill 0.2032)
		(layers "F.Cu" "B.Cu")
		(net "PVDDCR_CPU1_P0")
	)
	(via
		(at 370.35486 -268.416024)
		(size 0.4064)
		(drill 0.2032)
		(layers "F.Cu" "B.Cu")
		(net "PVDDCR_CPU1_P0")
	)
	(via
		(at 329.46086 -321.084448)
		(size 0.508)
		(drill 0.254)
		(layers "F.Cu" "B.Cu")
		(net "PVDDCR_CPU1_P0")
	)
	(via
		(at 348.271084 -275.706078)
		(size 0.4064)
		(drill 0.2032)
		(layers "F.Cu" "B.Cu")
		(net "PVDDCR_CPU1_P0")
	)
	(via
		(at 324.15226 -321.719448)
		(size 0.508)
		(drill 0.254)
		(layers "F.Cu" "B.Cu")
		(net "PVDDCR_CPU1_P0")
	)
	(via
		(at 336.548476 -321.08902)
		(size 0.508)
		(drill 0.254)
		(layers "F.Cu" "B.Cu")
		(net "PVDDCR_CPU1_P0")
	)
	(via
		(at 316.457076 -321.11061)
		(size 0.508)
		(drill 0.254)
		(layers "F.Cu" "B.Cu")
		(net "PVDDCR_CPU1_P0")
	)
	(via
		(at 341.39886 -319.193926)
		(size 0.508)
		(drill 0.254)
		(layers "F.Cu" "B.Cu")
		(net "PVDDCR_CPU1_P0")
	)
	(via
		(at 307.442362 -333.466694)
		(size 0.508)
		(drill 0.254)
		(layers "F.Cu" "B.Cu")
		(net "PVDDCR_CPU1_P0")
	)
	(via
		(at 373.644922 -272.466054)
		(size 0.4064)
		(drill 0.2032)
		(layers "F.Cu" "B.Cu")
		(net "PVDDCR_CPU1_P0")
	)
	(via
		(at 351.561146 -281.37612)
		(size 0.4064)
		(drill 0.2032)
		(layers "F.Cu" "B.Cu")
		(net "PVDDCR_CPU1_P0")
	)
	(via
		(at 368.474752 -268.416024)
		(size 0.4064)
		(drill 0.2032)
		(layers "F.Cu" "B.Cu")
		(net "PVDDCR_CPU1_P0")
	)
	(via
		(at 316.431676 -319.836038)
		(size 0.508)
		(drill 0.254)
		(layers "F.Cu" "B.Cu")
		(net "PVDDCR_CPU1_P0")
	)
	(via
		(at 349.116904 -324.140322)
		(size 0.508)
		(drill 0.254)
		(layers "F.Cu" "B.Cu")
		(net "PVDDCR_CPU1_P0")
	)
	(via
		(at 368.944906 -278.946102)
		(size 0.4064)
		(drill 0.2032)
		(layers "F.Cu" "B.Cu")
		(net "PVDDCR_CPU1_P0")
	)
	(via
		(at 320.470276 -319.836038)
		(size 0.508)
		(drill 0.254)
		(layers "F.Cu" "B.Cu")
		(net "PVDDCR_CPU1_P0")
	)
	(via
		(at 315.796676 -321.106038)
		(size 0.508)
		(drill 0.254)
		(layers "F.Cu" "B.Cu")
		(net "PVDDCR_CPU1_P0")
	)
	(via
		(at 346.86113 -268.416024)
		(size 0.4064)
		(drill 0.2032)
		(layers "F.Cu" "B.Cu")
		(net "PVDDCR_CPU1_P0")
	)
	(via
		(at 324.15226 -318.544448)
		(size 0.508)
		(drill 0.254)
		(layers "F.Cu" "B.Cu")
		(net "PVDDCR_CPU1_P0")
	)
	(via
		(at 373.644922 -283.806138)
		(size 0.4064)
		(drill 0.2032)
		(layers "F.Cu" "B.Cu")
		(net "PVDDCR_CPU1_P0")
	)
	(via
		(at 341.691214 -295.145968)
		(size 0.4064)
		(drill 0.2032)
		(layers "F.Cu" "B.Cu")
		(net "PVDDCR_CPU1_P0")
	)
	(via
		(at 346.39123 -287.045908)
		(size 0.4064)
		(drill 0.2032)
		(layers "F.Cu" "B.Cu")
		(net "PVDDCR_CPU1_P0")
	)
	(via
		(at 328.19086 -321.08902)
		(size 0.508)
		(drill 0.254)
		(layers "F.Cu" "B.Cu")
		(net "PVDDCR_CPU1_P0")
	)
	(via
		(at 353.790504 -324.140322)
		(size 0.508)
		(drill 0.254)
		(layers "F.Cu" "B.Cu")
		(net "PVDDCR_CPU1_P0")
	)
	(via
		(at 306.172362 -334.101694)
		(size 0.508)
		(drill 0.254)
		(layers "F.Cu" "B.Cu")
		(net "PVDDCR_CPU1_P0")
	)
	(via
		(at 321.105276 -319.201038)
		(size 0.508)
		(drill 0.254)
		(layers "F.Cu" "B.Cu")
		(net "PVDDCR_CPU1_P0")
	)
	(via
		(at 373.644922 -278.946102)
		(size 0.4064)
		(drill 0.2032)
		(layers "F.Cu" "B.Cu")
		(net "PVDDCR_CPU1_P0")
	)
	(via
		(at 352.9711 -295.145968)
		(size 0.4064)
		(drill 0.2032)
		(layers "F.Cu" "B.Cu")
		(net "PVDDCR_CPU1_P0")
	)
	(via
		(at 336.548476 -319.179448)
		(size 0.508)
		(drill 0.254)
		(layers "F.Cu" "B.Cu")
		(net "PVDDCR_CPU1_P0")
	)
	(via
		(at 350.386904 -324.140322)
		(size 0.508)
		(drill 0.254)
		(layers "F.Cu" "B.Cu")
		(net "PVDDCR_CPU1_P0")
	)
	(via
		(at 370.35486 -266.796012)
		(size 0.4064)
		(drill 0.2032)
		(layers "F.Cu" "B.Cu")
		(net "PVDDCR_CPU1_P0")
	)
	(via
		(at 353.911154 -272.466054)
		(size 0.4064)
		(drill 0.2032)
		(layers "F.Cu" "B.Cu")
		(net "PVDDCR_CPU1_P0")
	)
	(via
		(at 344.511122 -295.145968)
		(size 0.4064)
		(drill 0.2032)
		(layers "F.Cu" "B.Cu")
		(net "PVDDCR_CPU1_P0")
	)
	(via
		(at 366.124744 -267.606018)
		(size 0.4064)
		(drill 0.2032)
		(layers "F.Cu" "B.Cu")
		(net "PVDDCR_CPU1_P0")
	)
	(via
		(at 332.50886 -321.733926)
		(size 0.508)
		(drill 0.254)
		(layers "F.Cu" "B.Cu")
		(net "PVDDCR_CPU1_P0")
	)
	(via
		(at 345.451176 -283.806138)
		(size 0.4064)
		(drill 0.2032)
		(layers "F.Cu" "B.Cu")
		(net "PVDDCR_CPU1_P0")
	)
	(via
		(at 368.004852 -275.706078)
		(size 0.4064)
		(drill 0.2032)
		(layers "F.Cu" "B.Cu")
		(net "PVDDCR_CPU1_P0")
	)
	(via
		(at 341.42426 -322.373498)
		(size 0.508)
		(drill 0.254)
		(layers "F.Cu" "B.Cu")
		(net "PVDDCR_CPU1_P0")
	)
	(via
		(at 354.425504 -327.975722)
		(size 0.508)
		(drill 0.254)
		(layers "F.Cu" "B.Cu")
		(net "PVDDCR_CPU1_P0")
	)
	(via
		(at 356.731062 -295.145968)
		(size 0.4064)
		(drill 0.2032)
		(layers "F.Cu" "B.Cu")
		(net "PVDDCR_CPU1_P0")
	)
	(via
		(at 365.18469 -272.466054)
		(size 0.4064)
		(drill 0.2032)
		(layers "F.Cu" "B.Cu")
		(net "PVDDCR_CPU1_P0")
	)
	(via
		(at 375.524776 -295.145968)
		(size 0.4064)
		(drill 0.2032)
		(layers "F.Cu" "B.Cu")
		(net "PVDDCR_CPU1_P0")
	)
	(via
		(at 340.78926 -322.394326)
		(size 0.508)
		(drill 0.254)
		(layers "F.Cu" "B.Cu")
		(net "PVDDCR_CPU1_P0")
	)
	(via
		(at 316.457076 -320.47561)
		(size 0.508)
		(drill 0.254)
		(layers "F.Cu" "B.Cu")
		(net "PVDDCR_CPU1_P0")
	)
	(via
		(at 307.442362 -330.291694)
		(size 0.508)
		(drill 0.254)
		(layers "F.Cu" "B.Cu")
		(net "PVDDCR_CPU1_P0")
	)
	(via
		(at 333.14386 -323.003926)
		(size 0.508)
		(drill 0.254)
		(layers "F.Cu" "B.Cu")
		(net "PVDDCR_CPU1_P0")
	)
	(via
		(at 351.091246 -275.706078)
		(size 0.4064)
		(drill 0.2032)
		(layers "F.Cu" "B.Cu")
		(net "PVDDCR_CPU1_P0")
	)
	(via
		(at 346.39123 -272.466054)
		(size 0.4064)
		(drill 0.2032)
		(layers "F.Cu" "B.Cu")
		(net "PVDDCR_CPU1_P0")
	)
	(via
		(at 317.092076 -321.74561)
		(size 0.508)
		(drill 0.254)
		(layers "F.Cu" "B.Cu")
		(net "PVDDCR_CPU1_P0")
	)
	(via
		(at 350.412304 -326.684894)
		(size 0.508)
		(drill 0.254)
		(layers "F.Cu" "B.Cu")
		(net "PVDDCR_CPU1_P0")
	)
	(via
		(at 350.151192 -295.145968)
		(size 0.4064)
		(drill 0.2032)
		(layers "F.Cu" "B.Cu")
		(net "PVDDCR_CPU1_P0")
	)
	(via
		(at 363.774736 -292.71595)
		(size 0.4064)
		(drill 0.2032)
		(layers "F.Cu" "B.Cu")
		(net "PVDDCR_CPU1_P0")
	)
	(via
		(at 324.81266 -322.35902)
		(size 0.508)
		(drill 0.254)
		(layers "F.Cu" "B.Cu")
		(net "PVDDCR_CPU1_P0")
	)
	(via
		(at 353.155504 -322.235322)
		(size 0.508)
		(drill 0.254)
		(layers "F.Cu" "B.Cu")
		(net "PVDDCR_CPU1_P0")
	)
	(via
		(at 329.46086 -317.909448)
		(size 0.508)
		(drill 0.254)
		(layers "F.Cu" "B.Cu")
		(net "PVDDCR_CPU1_P0")
	)
	(via
		(at 366.124744 -287.045908)
		(size 0.4064)
		(drill 0.2032)
		(layers "F.Cu" "B.Cu")
		(net "PVDDCR_CPU1_P0")
	)
	(via
		(at 345.43746 -321.738498)
		(size 0.508)
		(drill 0.254)
		(layers "F.Cu" "B.Cu")
		(net "PVDDCR_CPU1_P0")
	)
	(via
		(at 319.835276 -319.201038)
		(size 0.508)
		(drill 0.254)
		(layers "F.Cu" "B.Cu")
		(net "PVDDCR_CPU1_P0")
	)
	(via
		(at 368.004852 -290.285932)
		(size 0.4064)
		(drill 0.2032)
		(layers "F.Cu" "B.Cu")
		(net "PVDDCR_CPU1_P0")
	)
	(via
		(at 328.82586 -317.274448)
		(size 0.508)
		(drill 0.254)
		(layers "F.Cu" "B.Cu")
		(net "PVDDCR_CPU1_P0")
	)
	(via
		(at 341.39886 -319.828926)
		(size 0.508)
		(drill 0.254)
		(layers "F.Cu" "B.Cu")
		(net "PVDDCR_CPU1_P0")
	)
	(via
		(at 366.594898 -292.71595)
		(size 0.4064)
		(drill 0.2032)
		(layers "F.Cu" "B.Cu")
		(net "PVDDCR_CPU1_P0")
	)
	(via
		(at 370.82476 -278.946102)
		(size 0.4064)
		(drill 0.2032)
		(layers "F.Cu" "B.Cu")
		(net "PVDDCR_CPU1_P0")
	)
	(via
		(at 317.092076 -322.38061)
		(size 0.508)
		(drill 0.254)
		(layers "F.Cu" "B.Cu")
		(net "PVDDCR_CPU1_P0")
	)
	(via
		(at 333.170276 -321.72402)
		(size 0.508)
		(drill 0.254)
		(layers "F.Cu" "B.Cu")
		(net "PVDDCR_CPU1_P0")
	)
	(via
		(at 349.777304 -325.414894)
		(size 0.508)
		(drill 0.254)
		(layers "F.Cu" "B.Cu")
		(net "PVDDCR_CPU1_P0")
	)
	(via
		(at 353.790504 -322.870322)
		(size 0.508)
		(drill 0.254)
		(layers "F.Cu" "B.Cu")
		(net "PVDDCR_CPU1_P0")
	)
	(via
		(at 345.451176 -269.22603)
		(size 0.4064)
		(drill 0.2032)
		(layers "F.Cu" "B.Cu")
		(net "PVDDCR_CPU1_P0")
	)
	(via
		(at 353.911154 -269.22603)
		(size 0.4064)
		(drill 0.2032)
		(layers "F.Cu" "B.Cu")
		(net "PVDDCR_CPU1_P0")
	)
	(via
		(at 337.818476 -321.719448)
		(size 0.508)
		(drill 0.254)
		(layers "F.Cu" "B.Cu")
		(net "PVDDCR_CPU1_P0")
	)
	(via
		(at 372.704868 -291.905944)
		(size 0.4064)
		(drill 0.2032)
		(layers "F.Cu" "B.Cu")
		(net "PVDDCR_CPU1_P0")
	)
	(via
		(at 325.44766 -315.902848)
		(size 0.6604)
		(drill 0.3302)
		(layers "F.Cu" "B.Cu")
		(net "PVDDCR_CPU1_P0")
	)
	(via
		(at 341.42426 -321.103498)
		(size 0.508)
		(drill 0.254)
		(layers "F.Cu" "B.Cu")
		(net "PVDDCR_CPU1_P0")
	)
	(via
		(at 346.39123 -278.946102)
		(size 0.4064)
		(drill 0.2032)
		(layers "F.Cu" "B.Cu")
		(net "PVDDCR_CPU1_P0")
	)
	(via
		(at 333.805276 -321.08902)
		(size 0.508)
		(drill 0.254)
		(layers "F.Cu" "B.Cu")
		(net "PVDDCR_CPU1_P0")
	)
	(via
		(at 340.76386 -319.193926)
		(size 0.508)
		(drill 0.254)
		(layers "F.Cu" "B.Cu")
		(net "PVDDCR_CPU1_P0")
	)
	(via
		(at 353.790504 -327.975722)
		(size 0.508)
		(drill 0.254)
		(layers "F.Cu" "B.Cu")
		(net "PVDDCR_CPU1_P0")
	)
	(via
		(at 356.731062 -267.606018)
		(size 0.4064)
		(drill 0.2032)
		(layers "F.Cu" "B.Cu")
		(net "PVDDCR_CPU1_P0")
	)
	(via
		(at 316.457076 -322.38061)
		(size 0.508)
		(drill 0.254)
		(layers "F.Cu" "B.Cu")
		(net "PVDDCR_CPU1_P0")
	)
	(via
		(at 358.141016 -271.656048)
		(size 0.4064)
		(drill 0.2032)
		(layers "F.Cu" "B.Cu")
		(net "PVDDCR_CPU1_P0")
	)
	(via
		(at 333.779876 -319.814448)
		(size 0.508)
		(drill 0.254)
		(layers "F.Cu" "B.Cu")
		(net "PVDDCR_CPU1_P0")
	)
	(via
		(at 364.71479 -281.37612)
		(size 0.4064)
		(drill 0.2032)
		(layers "F.Cu" "B.Cu")
		(net "PVDDCR_CPU1_P0")
	)
	(via
		(at 306.807362 -332.196694)
		(size 0.508)
		(drill 0.254)
		(layers "F.Cu" "B.Cu")
		(net "PVDDCR_CPU1_P0")
	)
	(via
		(at 337.183476 -317.909448)
		(size 0.508)
		(drill 0.254)
		(layers "F.Cu" "B.Cu")
		(net "PVDDCR_CPU1_P0")
	)
	(via
		(at 346.07246 -317.288926)
		(size 0.508)
		(drill 0.254)
		(layers "F.Cu" "B.Cu")
		(net "PVDDCR_CPU1_P0")
	)
	(via
		(at 370.82476 -290.285932)
		(size 0.4064)
		(drill 0.2032)
		(layers "F.Cu" "B.Cu")
		(net "PVDDCR_CPU1_P0")
	)
	(via
		(at 362.834682 -282.996132)
		(size 0.4064)
		(drill 0.2032)
		(layers "F.Cu" "B.Cu")
		(net "PVDDCR_CPU1_P0")
	)
	(via
		(at 368.004852 -278.946102)
		(size 0.4064)
		(drill 0.2032)
		(layers "F.Cu" "B.Cu")
		(net "PVDDCR_CPU1_P0")
	)
	(via
		(at 337.183476 -322.35902)
		(size 0.508)
		(drill 0.254)
		(layers "F.Cu" "B.Cu")
		(net "PVDDCR_CPU1_P0")
	)
	(via
		(at 353.790504 -327.319894)
		(size 0.508)
		(drill 0.254)
		(layers "F.Cu" "B.Cu")
		(net "PVDDCR_CPU1_P0")
	)
	(via
		(at 349.211138 -287.045908)
		(size 0.4064)
		(drill 0.2032)
		(layers "F.Cu" "B.Cu")
		(net "PVDDCR_CPU1_P0")
	)
	(via
		(at 349.211138 -269.22603)
		(size 0.4064)
		(drill 0.2032)
		(layers "F.Cu" "B.Cu")
		(net "PVDDCR_CPU1_P0")
	)
	(via
		(at 368.944906 -272.466054)
		(size 0.4064)
		(drill 0.2032)
		(layers "F.Cu" "B.Cu")
		(net "PVDDCR_CPU1_P0")
	)
	(via
		(at 368.944906 -283.806138)
		(size 0.4064)
		(drill 0.2032)
		(layers "F.Cu" "B.Cu")
		(net "PVDDCR_CPU1_P0")
	)
	(via
		(at 353.155504 -323.505322)
		(size 0.508)
		(drill 0.254)
		(layers "F.Cu" "B.Cu")
		(net "PVDDCR_CPU1_P0")
	)
	(via
		(at 333.170276 -320.45402)
		(size 0.508)
		(drill 0.254)
		(layers "F.Cu" "B.Cu")
		(net "PVDDCR_CPU1_P0")
	)
	(via
		(at 345.43746 -316.653926)
		(size 0.508)
		(drill 0.254)
		(layers "F.Cu" "B.Cu")
		(net "PVDDCR_CPU1_P0")
	)
	(via
		(at 369.884706 -267.606018)
		(size 0.4064)
		(drill 0.2032)
		(layers "F.Cu" "B.Cu")
		(net "PVDDCR_CPU1_P0")
	)
	(via
		(at 350.386904 -322.870322)
		(size 0.508)
		(drill 0.254)
		(layers "F.Cu" "B.Cu")
		(net "PVDDCR_CPU1_P0")
	)
	(via
		(at 365.18469 -275.706078)
		(size 0.4064)
		(drill 0.2032)
		(layers "F.Cu" "B.Cu")
		(net "PVDDCR_CPU1_P0")
	)
	(via
		(at 348.36227 -343.716356)
		(size 0.508)
		(drill 0.254)
		(layers "F.Cu" "B.Cu")
		(net "PVDDCR_CPU1_P0")
	)
	(via
		(at 349.751904 -322.235322)
		(size 0.508)
		(drill 0.254)
		(layers "F.Cu" "B.Cu")
		(net "PVDDCR_CPU1_P0")
	)
	(via
		(at 333.144876 -319.814448)
		(size 0.508)
		(drill 0.254)
		(layers "F.Cu" "B.Cu")
		(net "PVDDCR_CPU1_P0")
	)
	(via
		(at 341.39886 -317.923926)
		(size 0.508)
		(drill 0.254)
		(layers "F.Cu" "B.Cu")
		(net "PVDDCR_CPU1_P0")
	)
	(via
		(at 319.835276 -319.836038)
		(size 0.508)
		(drill 0.254)
		(layers "F.Cu" "B.Cu")
		(net "PVDDCR_CPU1_P0")
	)
	(via
		(at 332.50886 -321.098926)
		(size 0.508)
		(drill 0.254)
		(layers "F.Cu" "B.Cu")
		(net "PVDDCR_CPU1_P0")
	)
	(via
		(at 372.704868 -295.145968)
		(size 0.4064)
		(drill 0.2032)
		(layers "F.Cu" "B.Cu")
		(net "PVDDCR_CPU1_P0")
	)
	(via
		(at 306.807362 -332.831694)
		(size 0.508)
		(drill 0.254)
		(layers "F.Cu" "B.Cu")
		(net "PVDDCR_CPU1_P0")
	)
	(via
		(at 324.155816 -323.003926)
		(size 0.508)
		(drill 0.254)
		(layers "F.Cu" "B.Cu")
		(net "PVDDCR_CPU1_P0")
	)
	(via
		(at 324.78726 -317.909448)
		(size 0.508)
		(drill 0.254)
		(layers "F.Cu" "B.Cu")
		(net "PVDDCR_CPU1_P0")
	)
	(via
		(at 344.80246 -321.738498)
		(size 0.508)
		(drill 0.254)
		(layers "F.Cu" "B.Cu")
		(net "PVDDCR_CPU1_P0")
	)
	(via
		(at 315.796676 -322.376038)
		(size 0.508)
		(drill 0.254)
		(layers "F.Cu" "B.Cu")
		(net "PVDDCR_CPU1_P0")
	)
	(via
		(at 378.344938 -295.145968)
		(size 0.4064)
		(drill 0.2032)
		(layers "F.Cu" "B.Cu")
		(net "PVDDCR_CPU1_P0")
	)
	(via
		(at 349.777304 -327.975722)
		(size 0.508)
		(drill 0.254)
		(layers "F.Cu" "B.Cu")
		(net "PVDDCR_CPU1_P0")
	)
	(via
		(at 333.779876 -318.544448)
		(size 0.508)
		(drill 0.254)
		(layers "F.Cu" "B.Cu")
		(net "PVDDCR_CPU1_P0")
	)
	(via
		(at 317.066676 -319.201038)
		(size 0.508)
		(drill 0.254)
		(layers "F.Cu" "B.Cu")
		(net "PVDDCR_CPU1_P0")
	)
	(via
		(at 362.834682 -278.136096)
		(size 0.4064)
		(drill 0.2032)
		(layers "F.Cu" "B.Cu")
		(net "PVDDCR_CPU1_P0")
	)
	(via
		(at 306.172362 -333.466694)
		(size 0.508)
		(drill 0.254)
		(layers "F.Cu" "B.Cu")
		(net "PVDDCR_CPU1_P0")
	)
	(via
		(at 340.78926 -323.029326)
		(size 0.508)
		(drill 0.254)
		(layers "F.Cu" "B.Cu")
		(net "PVDDCR_CPU1_P0")
	)
	(via
		(at 346.07246 -318.558926)
		(size 0.508)
		(drill 0.254)
		(layers "F.Cu" "B.Cu")
		(net "PVDDCR_CPU1_P0")
	)
	(via
		(at 353.911154 -287.045908)
		(size 0.4064)
		(drill 0.2032)
		(layers "F.Cu" "B.Cu")
		(net "PVDDCR_CPU1_P0")
	)
	(via
		(at 354.851208 -278.946102)
		(size 0.4064)
		(drill 0.2032)
		(layers "F.Cu" "B.Cu")
		(net "PVDDCR_CPU1_P0")
	)
	(via
		(at 349.211138 -267.606018)
		(size 0.4064)
		(drill 0.2032)
		(layers "F.Cu" "B.Cu")
		(net "PVDDCR_CPU1_P0")
	)
	(via
		(at 324.15226 -321.084448)
		(size 0.508)
		(drill 0.254)
		(layers "F.Cu" "B.Cu")
		(net "PVDDCR_CPU1_P0")
	)
	(via
		(at 349.116904 -323.505322)
		(size 0.508)
		(drill 0.254)
		(layers "F.Cu" "B.Cu")
		(net "PVDDCR_CPU1_P0")
	)
	(via
		(at 350.151192 -291.905944)
		(size 0.4064)
		(drill 0.2032)
		(layers "F.Cu" "B.Cu")
		(net "PVDDCR_CPU1_P0")
	)
	(via
		(at 345.451176 -295.145968)
		(size 0.4064)
		(drill 0.2032)
		(layers "F.Cu" "B.Cu")
		(net "PVDDCR_CPU1_P0")
	)
	(via
		(at 346.39123 -275.706078)
		(size 0.4064)
		(drill 0.2032)
		(layers "F.Cu" "B.Cu")
		(net "PVDDCR_CPU1_P0")
	)
	(via
		(at 355.321108 -281.37612)
		(size 0.4064)
		(drill 0.2032)
		(layers "F.Cu" "B.Cu")
		(net "PVDDCR_CPU1_P0")
	)
	(via
		(at 350.386904 -321.600322)
		(size 0.508)
		(drill 0.254)
		(layers "F.Cu" "B.Cu")
		(net "PVDDCR_CPU1_P0")
	)
	(via
		(at 354.425504 -324.775322)
		(size 0.508)
		(drill 0.254)
		(layers "F.Cu" "B.Cu")
		(net "PVDDCR_CPU1_P0")
	)
	(via
		(at 310.185562 -332.831694)
		(size 0.508)
		(drill 0.254)
		(layers "F.Cu" "B.Cu")
		(net "PVDDCR_CPU1_P0")
	)
	(via
		(at 352.031046 -278.946102)
		(size 0.4064)
		(drill 0.2032)
		(layers "F.Cu" "B.Cu")
		(net "PVDDCR_CPU1_P0")
	)
	(via
		(at 325.42226 -316.639448)
		(size 0.508)
		(drill 0.254)
		(layers "F.Cu" "B.Cu")
		(net "PVDDCR_CPU1_P0")
	)
	(via
		(at 337.183476 -317.274448)
		(size 0.508)
		(drill 0.254)
		(layers "F.Cu" "B.Cu")
		(net "PVDDCR_CPU1_P0")
	)
	(via
		(at 329.46086 -316.639448)
		(size 0.508)
		(drill 0.254)
		(layers "F.Cu" "B.Cu")
		(net "PVDDCR_CPU1_P0")
	)
	(via
		(at 351.091246 -295.145968)
		(size 0.4064)
		(drill 0.2032)
		(layers "F.Cu" "B.Cu")
		(net "PVDDCR_CPU1_P0")
	)
	(via
		(at 315.042042 -338.777072)
		(size 0.508)
		(drill 0.254)
		(layers "F.Cu" "B.Cu")
		(net "PVDDCR_CPU1_P0")
	)
	(via
		(at 342.03386 -316.653926)
		(size 0.508)
		(drill 0.254)
		(layers "F.Cu" "B.Cu")
		(net "PVDDCR_CPU1_P0")
	)
	(via
		(at 346.07246 -322.394326)
		(size 0.508)
		(drill 0.254)
		(layers "F.Cu" "B.Cu")
		(net "PVDDCR_CPU1_P0")
	)
	(via
		(at 306.807362 -330.926694)
		(size 0.508)
		(drill 0.254)
		(layers "F.Cu" "B.Cu")
		(net "PVDDCR_CPU1_P0")
	)
	(via
		(at 329.46086 -319.179448)
		(size 0.508)
		(drill 0.254)
		(layers "F.Cu" "B.Cu")
		(net "PVDDCR_CPU1_P0")
	)
	(via
		(at 357.201216 -271.656048)
		(size 0.4064)
		(drill 0.2032)
		(layers "F.Cu" "B.Cu")
		(net "PVDDCR_CPU1_P0")
	)
	(via
		(at 354.425504 -326.705722)
		(size 0.508)
		(drill 0.254)
		(layers "F.Cu" "B.Cu")
		(net "PVDDCR_CPU1_P0")
	)
	(via
		(at 342.631014 -295.145968)
		(size 0.4064)
		(drill 0.2032)
		(layers "F.Cu" "B.Cu")
		(net "PVDDCR_CPU1_P0")
	)
	(via
		(at 346.07246 -319.828926)
		(size 0.508)
		(drill 0.254)
		(layers "F.Cu" "B.Cu")
		(net "PVDDCR_CPU1_P0")
	)
	(via
		(at 369.884706 -291.905944)
		(size 0.4064)
		(drill 0.2032)
		(layers "F.Cu" "B.Cu")
		(net "PVDDCR_CPU1_P0")
	)
	(via
		(at 346.39123 -290.285932)
		(size 0.4064)
		(drill 0.2032)
		(layers "F.Cu" "B.Cu")
		(net "PVDDCR_CPU1_P0")
	)
	(via
		(at 320.470276 -319.201038)
		(size 0.508)
		(drill 0.254)
		(layers "F.Cu" "B.Cu")
		(net "PVDDCR_CPU1_P0")
	)
	(via
		(at 344.80246 -318.558926)
		(size 0.508)
		(drill 0.254)
		(layers "F.Cu" "B.Cu")
		(net "PVDDCR_CPU1_P0")
	)
	(via
		(at 310.185562 -334.736694)
		(size 0.508)
		(drill 0.254)
		(layers "F.Cu" "B.Cu")
		(net "PVDDCR_CPU1_P0")
	)
	(via
		(at 342.03386 -319.193926)
		(size 0.508)
		(drill 0.254)
		(layers "F.Cu" "B.Cu")
		(net "PVDDCR_CPU1_P0")
	)
	(via
		(at 328.82586 -318.544448)
		(size 0.508)
		(drill 0.254)
		(layers "F.Cu" "B.Cu")
		(net "PVDDCR_CPU1_P0")
	)
	(via
		(at 362.364782 -267.606018)
		(size 0.4064)
		(drill 0.2032)
		(layers "F.Cu" "B.Cu")
		(net "PVDDCR_CPU1_P0")
	)
	(via
		(at 361.894882 -274.896072)
		(size 0.4064)
		(drill 0.2032)
		(layers "F.Cu" "B.Cu")
		(net "PVDDCR_CPU1_P0")
	)
	(via
		(at 340.78926 -321.124326)
		(size 0.508)
		(drill 0.254)
		(layers "F.Cu" "B.Cu")
		(net "PVDDCR_CPU1_P0")
	)
	(via
		(at 341.42426 -321.738498)
		(size 0.508)
		(drill 0.254)
		(layers "F.Cu" "B.Cu")
		(net "PVDDCR_CPU1_P0")
	)
	(via
		(at 321.105276 -319.836038)
		(size 0.508)
		(drill 0.254)
		(layers "F.Cu" "B.Cu")
		(net "PVDDCR_CPU1_P0")
	)
	(via
		(at 377.404884 -295.145968)
		(size 0.4064)
		(drill 0.2032)
		(layers "F.Cu" "B.Cu")
		(net "PVDDCR_CPU1_P0")
	)
	(via
		(at 345.43746 -321.103498)
		(size 0.508)
		(drill 0.254)
		(layers "F.Cu" "B.Cu")
		(net "PVDDCR_CPU1_P0")
	)
	(via
		(at 342.03386 -319.828926)
		(size 0.508)
		(drill 0.254)
		(layers "F.Cu" "B.Cu")
		(net "PVDDCR_CPU1_P0")
	)
	(via
		(at 367.064798 -291.905944)
		(size 0.4064)
		(drill 0.2032)
		(layers "F.Cu" "B.Cu")
		(net "PVDDCR_CPU1_P0")
	)
	(via
		(at 370.82476 -283.806138)
		(size 0.4064)
		(drill 0.2032)
		(layers "F.Cu" "B.Cu")
		(net "PVDDCR_CPU1_P0")
	)
	(via
		(at 348.271084 -290.285932)
		(size 0.4064)
		(drill 0.2032)
		(layers "F.Cu" "B.Cu")
		(net "PVDDCR_CPU1_P0")
	)
	(via
		(at 346.07246 -323.029326)
		(size 0.508)
		(drill 0.254)
		(layers "F.Cu" "B.Cu")
		(net "PVDDCR_CPU1_P0")
	)
	(via
		(at 324.78726 -317.274448)
		(size 0.508)
		(drill 0.254)
		(layers "F.Cu" "B.Cu")
		(net "PVDDCR_CPU1_P0")
	)
	(via
		(at 344.80246 -319.193926)
		(size 0.508)
		(drill 0.254)
		(layers "F.Cu" "B.Cu")
		(net "PVDDCR_CPU1_P0")
	)
	(via
		(at 349.211138 -272.466054)
		(size 0.4064)
		(drill 0.2032)
		(layers "F.Cu" "B.Cu")
		(net "PVDDCR_CPU1_P0")
	)
	(via
		(at 351.091246 -272.466054)
		(size 0.4064)
		(drill 0.2032)
		(layers "F.Cu" "B.Cu")
		(net "PVDDCR_CPU1_P0")
	)
	(via
		(at 371.764814 -290.285932)
		(size 0.4064)
		(drill 0.2032)
		(layers "F.Cu" "B.Cu")
		(net "PVDDCR_CPU1_P0")
	)
	(via
		(at 321.105276 -317.296038)
		(size 0.508)
		(drill 0.254)
		(layers "F.Cu" "B.Cu")
		(net "PVDDCR_CPU1_P0")
	)
	(via
		(at 354.851208 -287.045908)
		(size 0.4064)
		(drill 0.2032)
		(layers "F.Cu" "B.Cu")
		(net "PVDDCR_CPU1_P0")
	)
	(via
		(at 319.835276 -320.47561)
		(size 0.508)
		(drill 0.254)
		(layers "F.Cu" "B.Cu")
		(net "PVDDCR_CPU1_P0")
	)
	(via
		(at 333.144876 -318.544448)
		(size 0.508)
		(drill 0.254)
		(layers "F.Cu" "B.Cu")
		(net "PVDDCR_CPU1_P0")
	)
	(via
		(at 324.78726 -319.814448)
		(size 0.508)
		(drill 0.254)
		(layers "F.Cu" "B.Cu")
		(net "PVDDCR_CPU1_P0")
	)
	(via
		(at 316.435232 -323.025516)
		(size 0.508)
		(drill 0.254)
		(layers "F.Cu" "B.Cu")
		(net "PVDDCR_CPU1_P0")
	)
	(via
		(at 325.42226 -319.814448)
		(size 0.508)
		(drill 0.254)
		(layers "F.Cu" "B.Cu")
		(net "PVDDCR_CPU1_P0")
	)
	(via
		(at 325.44766 -321.72402)
		(size 0.508)
		(drill 0.254)
		(layers "F.Cu" "B.Cu")
		(net "PVDDCR_CPU1_P0")
	)
	(via
		(at 368.004852 -287.045908)
		(size 0.4064)
		(drill 0.2032)
		(layers "F.Cu" "B.Cu")
		(net "PVDDCR_CPU1_P0")
	)
	(via
		(at 365.18469 -269.22603)
		(size 0.4064)
		(drill 0.2032)
		(layers "F.Cu" "B.Cu")
		(net "PVDDCR_CPU1_P0")
	)
	(via
		(at 358.141016 -278.136096)
		(size 0.4064)
		(drill 0.2032)
		(layers "F.Cu" "B.Cu")
		(net "PVDDCR_CPU1_P0")
	)
	(via
		(at 368.004852 -272.466054)
		(size 0.4064)
		(drill 0.2032)
		(layers "F.Cu" "B.Cu")
		(net "PVDDCR_CPU1_P0")
	)
	(via
		(at 353.155504 -324.140322)
		(size 0.508)
		(drill 0.254)
		(layers "F.Cu" "B.Cu")
		(net "PVDDCR_CPU1_P0")
	)
	(via
		(at 357.201216 -282.996132)
		(size 0.4064)
		(drill 0.2032)
		(layers "F.Cu" "B.Cu")
		(net "PVDDCR_CPU1_P0")
	)
	(via
		(at 342.05926 -323.029326)
		(size 0.508)
		(drill 0.254)
		(layers "F.Cu" "B.Cu")
		(net "PVDDCR_CPU1_P0")
	)
	(via
		(at 370.82476 -269.22603)
		(size 0.4064)
		(drill 0.2032)
		(layers "F.Cu" "B.Cu")
		(net "PVDDCR_CPU1_P0")
	)
	(via
		(at 337.818476 -319.814448)
		(size 0.508)
		(drill 0.254)
		(layers "F.Cu" "B.Cu")
		(net "PVDDCR_CPU1_P0")
	)
	(via
		(at 336.548476 -319.814448)
		(size 0.508)
		(drill 0.254)
		(layers "F.Cu" "B.Cu")
		(net "PVDDCR_CPU1_P0")
	)
	(via
		(at 349.116904 -321.600322)
		(size 0.508)
		(drill 0.254)
		(layers "F.Cu" "B.Cu")
		(net "PVDDCR_CPU1_P0")
	)
	(via
		(at 321.105276 -316.661038)
		(size 0.508)
		(drill 0.254)
		(layers "F.Cu" "B.Cu")
		(net "PVDDCR_CPU1_P0")
	)
	(via
		(at 306.807362 -334.101694)
		(size 0.508)
		(drill 0.254)
		(layers "F.Cu" "B.Cu")
		(net "PVDDCR_CPU1_P0")
	)
	(via
		(at 368.944906 -269.22603)
		(size 0.4064)
		(drill 0.2032)
		(layers "F.Cu" "B.Cu")
		(net "PVDDCR_CPU1_P0")
	)
	(via
		(at 362.834682 -274.896072)
		(size 0.4064)
		(drill 0.2032)
		(layers "F.Cu" "B.Cu")
		(net "PVDDCR_CPU1_P0")
	)
	(via
		(at 329.46086 -317.274448)
		(size 0.508)
		(drill 0.254)
		(layers "F.Cu" "B.Cu")
		(net "PVDDCR_CPU1_P0")
	)
	(via
		(at 371.764814 -283.806138)
		(size 0.4064)
		(drill 0.2032)
		(layers "F.Cu" "B.Cu")
		(net "PVDDCR_CPU1_P0")
	)
	(via
		(at 306.172362 -332.196694)
		(size 0.508)
		(drill 0.254)
		(layers "F.Cu" "B.Cu")
		(net "PVDDCR_CPU1_P0")
	)
	(via
		(at 306.807362 -333.466694)
		(size 0.508)
		(drill 0.254)
		(layers "F.Cu" "B.Cu")
		(net "PVDDCR_CPU1_P0")
	)
	(via
		(at 321.105276 -322.376038)
		(size 0.508)
		(drill 0.254)
		(layers "F.Cu" "B.Cu")
		(net "PVDDCR_CPU1_P0")
	)
	(via
		(at 374.584722 -272.466054)
		(size 0.4064)
		(drill 0.2032)
		(layers "F.Cu" "B.Cu")
		(net "PVDDCR_CPU1_P0")
	)
	(via
		(at 358.141016 -282.996132)
		(size 0.4064)
		(drill 0.2032)
		(layers "F.Cu" "B.Cu")
		(net "PVDDCR_CPU1_P0")
	)
	(via
		(at 319.835276 -317.931038)
		(size 0.508)
		(drill 0.254)
		(layers "F.Cu" "B.Cu")
		(net "PVDDCR_CPU1_P0")
	)
	(via
		(at 333.144876 -316.639448)
		(size 0.508)
		(drill 0.254)
		(layers "F.Cu" "B.Cu")
		(net "PVDDCR_CPU1_P0")
	)
	(via
		(at 361.894882 -278.136096)
		(size 0.4064)
		(drill 0.2032)
		(layers "F.Cu" "B.Cu")
		(net "PVDDCR_CPU1_P0")
	)
	(via
		(at 355.791008 -295.145968)
		(size 0.4064)
		(drill 0.2032)
		(layers "F.Cu" "B.Cu")
		(net "PVDDCR_CPU1_P0")
	)
	(via
		(at 328.82586 -320.45402)
		(size 0.508)
		(drill 0.254)
		(layers "F.Cu" "B.Cu")
		(net "PVDDCR_CPU1_P0")
	)
	(via
		(at 366.124744 -269.22603)
		(size 0.4064)
		(drill 0.2032)
		(layers "F.Cu" "B.Cu")
		(net "PVDDCR_CPU1_P0")
	)
	(via
		(at 345.451176 -287.045908)
		(size 0.4064)
		(drill 0.2032)
		(layers "F.Cu" "B.Cu")
		(net "PVDDCR_CPU1_P0")
	)
	(via
		(at 350.386904 -323.505322)
		(size 0.508)
		(drill 0.254)
		(layers "F.Cu" "B.Cu")
		(net "PVDDCR_CPU1_P0")
	)
	(via
		(at 362.834682 -266.796012)
		(size 0.4064)
		(drill 0.2032)
		(layers "F.Cu" "B.Cu")
		(net "PVDDCR_CPU1_P0")
	)
	(via
		(at 366.124744 -295.145968)
		(size 0.4064)
		(drill 0.2032)
		(layers "F.Cu" "B.Cu")
		(net "PVDDCR_CPU1_P0")
	)
	(via
		(at 342.05926 -320.468498)
		(size 0.508)
		(drill 0.254)
		(layers "F.Cu" "B.Cu")
		(net "PVDDCR_CPU1_P0")
	)
	(via
		(at 320.470276 -316.661038)
		(size 0.508)
		(drill 0.254)
		(layers "F.Cu" "B.Cu")
		(net "PVDDCR_CPU1_P0")
	)
	(via
		(at 364.71479 -268.416024)
		(size 0.4064)
		(drill 0.2032)
		(layers "F.Cu" "B.Cu")
		(net "PVDDCR_CPU1_P0")
	)
	(via
		(at 340.76386 -317.288926)
		(size 0.508)
		(drill 0.254)
		(layers "F.Cu" "B.Cu")
		(net "PVDDCR_CPU1_P0")
	)
	(via
		(at 351.091246 -269.22603)
		(size 0.4064)
		(drill 0.2032)
		(layers "F.Cu" "B.Cu")
		(net "PVDDCR_CPU1_P0")
	)
	(via
		(at 344.80246 -322.373498)
		(size 0.508)
		(drill 0.254)
		(layers "F.Cu" "B.Cu")
		(net "PVDDCR_CPU1_P0")
	)
	(via
		(at 353.790504 -326.684894)
		(size 0.508)
		(drill 0.254)
		(layers "F.Cu" "B.Cu")
		(net "PVDDCR_CPU1_P0")
	)
	(via
		(at 374.584722 -295.145968)
		(size 0.4064)
		(drill 0.2032)
		(layers "F.Cu" "B.Cu")
		(net "PVDDCR_CPU1_P0")
	)
	(via
		(at 353.790504 -322.235322)
		(size 0.508)
		(drill 0.254)
		(layers "F.Cu" "B.Cu")
		(net "PVDDCR_CPU1_P0")
	)
	(via
		(at 365.18469 -287.045908)
		(size 0.4064)
		(drill 0.2032)
		(layers "F.Cu" "B.Cu")
		(net "PVDDCR_CPU1_P0")
	)
	(via
		(at 351.091246 -267.606018)
		(size 0.4064)
		(drill 0.2032)
		(layers "F.Cu" "B.Cu")
		(net "PVDDCR_CPU1_P0")
	)
	(via
		(at 365.654844 -281.37612)
		(size 0.4064)
		(drill 0.2032)
		(layers "F.Cu" "B.Cu")
		(net "PVDDCR_CPU1_P0")
	)
	(via
		(at 373.644922 -290.285932)
		(size 0.4064)
		(drill 0.2032)
		(layers "F.Cu" "B.Cu")
		(net "PVDDCR_CPU1_P0")
	)
	(via
		(at 345.43746 -318.558926)
		(size 0.508)
		(drill 0.254)
		(layers "F.Cu" "B.Cu")
		(net "PVDDCR_CPU1_P0")
	)
	(via
		(at 325.44766 -321.08902)
		(size 0.508)
		(drill 0.254)
		(layers "F.Cu" "B.Cu")
		(net "PVDDCR_CPU1_P0")
	)
	(via
		(at 353.790504 -325.414894)
		(size 0.508)
		(drill 0.254)
		(layers "F.Cu" "B.Cu")
		(net "PVDDCR_CPU1_P0")
	)
	(via
		(at 352.031046 -283.806138)
		(size 0.4064)
		(drill 0.2032)
		(layers "F.Cu" "B.Cu")
		(net "PVDDCR_CPU1_P0")
	)
	(via
		(at 365.18469 -283.806138)
		(size 0.4064)
		(drill 0.2032)
		(layers "F.Cu" "B.Cu")
		(net "PVDDCR_CPU1_P0")
	)
	(via
		(at 333.779876 -317.274448)
		(size 0.508)
		(drill 0.254)
		(layers "F.Cu" "B.Cu")
		(net "PVDDCR_CPU1_P0")
	)
	(via
		(at 346.07246 -321.759326)
		(size 0.508)
		(drill 0.254)
		(layers "F.Cu" "B.Cu")
		(net "PVDDCR_CPU1_P0")
	)
	(via
		(at 333.144876 -317.274448)
		(size 0.508)
		(drill 0.254)
		(layers "F.Cu" "B.Cu")
		(net "PVDDCR_CPU1_P0")
	)
	(via
		(at 319.835276 -322.38061)
		(size 0.508)
		(drill 0.254)
		(layers "F.Cu" "B.Cu")
		(net "PVDDCR_CPU1_P0")
	)
	(via
		(at 336.548476 -322.35902)
		(size 0.508)
		(drill 0.254)
		(layers "F.Cu" "B.Cu")
		(net "PVDDCR_CPU1_P0")
	)
	(via
		(at 347.33103 -295.145968)
		(size 0.4064)
		(drill 0.2032)
		(layers "F.Cu" "B.Cu")
		(net "PVDDCR_CPU1_P0")
	)
	(via
		(at 319.835276 -316.661038)
		(size 0.508)
		(drill 0.254)
		(layers "F.Cu" "B.Cu")
		(net "PVDDCR_CPU1_P0")
	)
	(via
		(at 364.24489 -267.606018)
		(size 0.4064)
		(drill 0.2032)
		(layers "F.Cu" "B.Cu")
		(net "PVDDCR_CPU1_P0")
	)
	(via
		(at 324.78726 -318.544448)
		(size 0.508)
		(drill 0.254)
		(layers "F.Cu" "B.Cu")
		(net "PVDDCR_CPU1_P0")
	)
	(via
		(at 364.24489 -295.145968)
		(size 0.4064)
		(drill 0.2032)
		(layers "F.Cu" "B.Cu")
		(net "PVDDCR_CPU1_P0")
	)
	(via
		(at 310.820562 -334.101694)
		(size 0.508)
		(drill 0.254)
		(layers "F.Cu" "B.Cu")
		(net "PVDDCR_CPU1_P0")
	)
	(via
		(at 356.261162 -268.416024)
		(size 0.4064)
		(drill 0.2032)
		(layers "F.Cu" "B.Cu")
		(net "PVDDCR_CPU1_P0")
	)
	(via
		(at 325.42226 -318.544448)
		(size 0.508)
		(drill 0.254)
		(layers "F.Cu" "B.Cu")
		(net "PVDDCR_CPU1_P0")
	)
	(via
		(at 328.169016 -323.003926)
		(size 0.508)
		(drill 0.254)
		(layers "F.Cu" "B.Cu")
		(net "PVDDCR_CPU1_P0")
	)
	(via
		(at 331.755242 -338.755482)
		(size 0.508)
		(drill 0.254)
		(layers "F.Cu" "B.Cu")
		(net "PVDDCR_CPU1_P0")
	)
	(via
		(at 336.548476 -317.909448)
		(size 0.508)
		(drill 0.254)
		(layers "F.Cu" "B.Cu")
		(net "PVDDCR_CPU1_P0")
	)
	(via
		(at 310.820562 -333.466694)
		(size 0.508)
		(drill 0.254)
		(layers "F.Cu" "B.Cu")
		(net "PVDDCR_CPU1_P0")
	)
	(via
		(at 361.894882 -271.656048)
		(size 0.4064)
		(drill 0.2032)
		(layers "F.Cu" "B.Cu")
		(net "PVDDCR_CPU1_P0")
	)
	(via
		(at 340.76386 -316.653926)
		(size 0.508)
		(drill 0.254)
		(layers "F.Cu" "B.Cu")
		(net "PVDDCR_CPU1_P0")
	)
	(via
		(at 320.470276 -318.566038)
		(size 0.508)
		(drill 0.254)
		(layers "F.Cu" "B.Cu")
		(net "PVDDCR_CPU1_P0")
	)
	(via
		(at 349.116904 -324.775322)
		(size 0.508)
		(drill 0.254)
		(layers "F.Cu" "B.Cu")
		(net "PVDDCR_CPU1_P0")
	)
	(via
		(at 340.76386 -318.558926)
		(size 0.508)
		(drill 0.254)
		(layers "F.Cu" "B.Cu")
		(net "PVDDCR_CPU1_P0")
	)
	(via
		(at 369.884706 -295.145968)
		(size 0.4064)
		(drill 0.2032)
		(layers "F.Cu" "B.Cu")
		(net "PVDDCR_CPU1_P0")
	)
	(via
		(at 375.054876 -292.71595)
		(size 0.4064)
		(drill 0.2032)
		(layers "F.Cu" "B.Cu")
		(net "PVDDCR_CPU1_P0")
	)
	(via
		(at 333.170276 -321.08902)
		(size 0.508)
		(drill 0.254)
		(layers "F.Cu" "B.Cu")
		(net "PVDDCR_CPU1_P0")
	)
	(via
		(at 374.584722 -269.22603)
		(size 0.4064)
		(drill 0.2032)
		(layers "F.Cu" "B.Cu")
		(net "PVDDCR_CPU1_P0")
	)
	(segment
		(start 305.034696 -349.781622)
		(end 305.034696 -350.140524)
		(width 0.381)
		(layer "B.Cu")
		(net "PVDDCR_CPU1_P0")
	)
	(segment
		(start 323.039994 -338.053426)
		(end 323.039994 -338.412328)
		(width 0.381)
		(layer "B.Cu")
		(net "PVDDCR_CPU1_P0")
	)
	(segment
		(start 314.68441 -338.41944)
		(end 315.042042 -338.777072)
		(width 0.381)
		(layer "B.Cu")
		(net "PVDDCR_CPU1_P0")
	)
	(segment
		(start 371.900958 -272.32991)
		(end 371.764814 -272.466054)
		(width 0.508)
		(layer "B.Cu")
		(net "PVDDCR_CPU1_P0")
	)
	(segment
		(start 348.101158 -272.296128)
		(end 348.271084 -272.466054)
		(width 0.508)
		(layer "B.Cu")
		(net "PVDDCR_CPU1_P0")
	)
	(segment
		(start 348.101158 -272.278602)
		(end 348.101158 -272.296128)
		(width 0.508)
		(layer "B.Cu")
		(net "PVDDCR_CPU1_P0")
	)
	(segment
		(start 323.039994 -338.412328)
		(end 323.397626 -338.76996)
		(width 0.381)
		(layer "B.Cu")
		(net "PVDDCR_CPU1_P0")
	)
	(segment
		(start 339.72881 -338.44865)
		(end 340.086442 -338.806282)
		(width 0.381)
		(layer "B.Cu")
		(net "PVDDCR_CPU1_P0")
	)
	(segment
		(start 357.111808 -271.395952)
		(end 357.111808 -271.56664)
		(width 0.508)
		(layer "B.Cu")
		(net "PVDDCR_CPU1_P0")
	)
	(segment
		(start 314.68441 -338.060538)
		(end 314.68441 -338.41944)
		(width 0.381)
		(layer "B.Cu")
		(net "PVDDCR_CPU1_P0")
	)
	(segment
		(start 362.941108 -271.549622)
		(end 362.834682 -271.656048)
		(width 0.508)
		(layer "B.Cu")
		(net "PVDDCR_CPU1_P0")
	)
	(segment
		(start 371.900958 -272.253202)
		(end 371.900958 -272.32991)
		(width 0.508)
		(layer "B.Cu")
		(net "PVDDCR_CPU1_P0")
	)
	(segment
		(start 348.004638 -343.358724)
		(end 348.36227 -343.716356)
		(width 0.381)
		(layer "B.Cu")
		(net "PVDDCR_CPU1_P0")
	)
	(segment
		(start 331.39761 -338.39785)
		(end 331.755242 -338.755482)
		(width 0.381)
		(layer "B.Cu")
		(net "PVDDCR_CPU1_P0")
	)
	(segment
		(start 305.034696 -350.140524)
		(end 305.392328 -350.498156)
		(width 0.381)
		(layer "B.Cu")
		(net "PVDDCR_CPU1_P0")
	)
	(segment
		(start 339.72881 -338.089748)
		(end 339.72881 -338.44865)
		(width 0.381)
		(layer "B.Cu")
		(net "PVDDCR_CPU1_P0")
	)
	(segment
		(start 331.39761 -338.038948)
		(end 331.39761 -338.39785)
		(width 0.381)
		(layer "B.Cu")
		(net "PVDDCR_CPU1_P0")
	)
	(segment
		(start 362.941108 -271.395952)
		(end 362.941108 -271.549622)
		(width 0.508)
		(layer "B.Cu")
		(net "PVDDCR_CPU1_P0")
	)
	(segment
		(start 357.111808 -271.56664)
		(end 357.201216 -271.656048)
		(width 0.508)
		(layer "B.Cu")
		(net "PVDDCR_CPU1_P0")
	)
	(segment
		(start 348.004638 -342.999822)
		(end 348.004638 -343.358724)
		(width 0.381)
		(layer "B.Cu")
		(net "PVDDCR_CPU1_P0")
	)
	(segment
		(start 315.800232 -323.025516)
		(end 315.800232 -336.496152)
		(width 0.381)
		(layer "In2.Cu")
		(net "PVDDCR_CPU1_P0")
	)
	(segment
		(start 305.509168 -334.101694)
		(end 304.69205 -334.918812)
		(width 0.381)
		(layer "In2.Cu")
		(net "PVDDCR_CPU1_P0")
	)
	(segment
		(start 305.22799 -349.240094)
		(end 305.22799 -350.333818)
		(width 0.381)
		(layer "In2.Cu")
		(net "PVDDCR_CPU1_P0")
	)
	(segment
		(start 331.51445 -338.51469)
		(end 331.51445 -337.468972)
		(width 0.381)
		(layer "In2.Cu")
		(net "PVDDCR_CPU1_P0")
	)
	(segment
		(start 349.092266 -340.806786)
		(end 349.152972 -340.867492)
		(width 0.381)
		(layer "In2.Cu")
		(net "PVDDCR_CPU1_P0")
	)
	(segment
		(start 324.15226 -336.3341)
		(end 323.150738 -337.335622)
		(width 0.381)
		(layer "In2.Cu")
		(net "PVDDCR_CPU1_P0")
	)
	(segment
		(start 339.873844 -337.33105)
		(end 340.78926 -336.415634)
		(width 0.381)
		(layer "In2.Cu")
		(net "PVDDCR_CPU1_P0")
	)
	(segment
		(start 349.092266 -328.02576)
		(end 349.092266 -340.806786)
		(width 0.381)
		(layer "In2.Cu")
		(net "PVDDCR_CPU1_P0")
	)
	(segment
		(start 340.78926 -336.415634)
		(end 340.78926 -323.029326)
		(width 0.381)
		(layer "In2.Cu")
		(net "PVDDCR_CPU1_P0")
	)
	(segment
		(start 306.171346 -338.559648)
		(end 306.171346 -348.296738)
		(width 0.381)
		(layer "In2.Cu")
		(net "PVDDCR_CPU1_P0")
	)
	(segment
		(start 340.086442 -338.806282)
		(end 339.873844 -338.593684)
		(width 0.381)
		(layer "In2.Cu")
		(net "PVDDCR_CPU1_P0")
	)
	(segment
		(start 323.150738 -338.523072)
		(end 323.397626 -338.76996)
		(width 0.381)
		(layer "In2.Cu")
		(net "PVDDCR_CPU1_P0")
	)
	(segment
		(start 339.873844 -338.593684)
		(end 339.873844 -337.33105)
		(width 0.381)
		(layer "In2.Cu")
		(net "PVDDCR_CPU1_P0")
	)
	(segment
		(start 314.663582 -338.398612)
		(end 315.042042 -338.777072)
		(width 0.381)
		(layer "In2.Cu")
		(net "PVDDCR_CPU1_P0")
	)
	(segment
		(start 347.842078 -342.575388)
		(end 347.842078 -343.196164)
		(width 0.381)
		(layer "In2.Cu")
		(net "PVDDCR_CPU1_P0")
	)
	(segment
		(start 314.663582 -337.632802)
		(end 314.663582 -338.398612)
		(width 0.381)
		(layer "In2.Cu")
		(net "PVDDCR_CPU1_P0")
	)
	(segment
		(start 304.69205 -337.080352)
		(end 306.171346 -338.559648)
		(width 0.381)
		(layer "In2.Cu")
		(net "PVDDCR_CPU1_P0")
	)
	(segment
		(start 349.152972 -340.867492)
		(end 349.152972 -341.264494)
		(width 0.381)
		(layer "In2.Cu")
		(net "PVDDCR_CPU1_P0")
	)
	(segment
		(start 349.142304 -327.975722)
		(end 349.092266 -328.02576)
		(width 0.381)
		(layer "In2.Cu")
		(net "PVDDCR_CPU1_P0")
	)
	(segment
		(start 332.50886 -336.474562)
		(end 332.50886 -323.003926)
		(width 0.381)
		(layer "In2.Cu")
		(net "PVDDCR_CPU1_P0")
	)
	(segment
		(start 349.152972 -341.264494)
		(end 347.842078 -342.575388)
		(width 0.381)
		(layer "In2.Cu")
		(net "PVDDCR_CPU1_P0")
	)
	(segment
		(start 305.22799 -350.333818)
		(end 305.392328 -350.498156)
		(width 0.381)
		(layer "In2.Cu")
		(net "PVDDCR_CPU1_P0")
	)
	(segment
		(start 331.51445 -337.468972)
		(end 332.50886 -336.474562)
		(width 0.381)
		(layer "In2.Cu")
		(net "PVDDCR_CPU1_P0")
	)
	(segment
		(start 324.15226 -323.003926)
		(end 324.15226 -336.3341)
		(width 0.381)
		(layer "In2.Cu")
		(net "PVDDCR_CPU1_P0")
	)
	(segment
		(start 315.800232 -336.496152)
		(end 314.663582 -337.632802)
		(width 0.381)
		(layer "In2.Cu")
		(net "PVDDCR_CPU1_P0")
	)
	(segment
		(start 324.155816 -323.003926)
		(end 324.15226 -323.003926)
		(width 0.381)
		(layer "In2.Cu")
		(net "PVDDCR_CPU1_P0")
	)
	(segment
		(start 306.171346 -348.296738)
		(end 305.22799 -349.240094)
		(width 0.381)
		(layer "In2.Cu")
		(net "PVDDCR_CPU1_P0")
	)
	(segment
		(start 347.842078 -343.196164)
		(end 348.36227 -343.716356)
		(width 0.381)
		(layer "In2.Cu")
		(net "PVDDCR_CPU1_P0")
	)
	(segment
		(start 304.69205 -334.918812)
		(end 304.69205 -337.080352)
		(width 0.381)
		(layer "In2.Cu")
		(net "PVDDCR_CPU1_P0")
	)
	(segment
		(start 331.755242 -338.755482)
		(end 331.51445 -338.51469)
		(width 0.381)
		(layer "In2.Cu")
		(net "PVDDCR_CPU1_P0")
	)
	(segment
		(start 306.172362 -334.101694)
		(end 305.509168 -334.101694)
		(width 0.381)
		(layer "In2.Cu")
		(net "PVDDCR_CPU1_P0")
	)
	(segment
		(start 323.150738 -337.335622)
		(end 323.150738 -338.523072)
		(width 0.381)
		(layer "In2.Cu")
		(net "PVDDCR_CPU1_P0")
	)
	(segment
		(start 68.047616 -166.653464)
		(end 68.097654 -166.603426)
		(width 0.2032)
		(layer "F.Cu")
		(net "PVDDCR_CPU0_P1_VOS6")
	)
	(segment
		(start 68.097654 -166.603426)
		(end 68.097654 -166.31666)
		(width 0.2032)
		(layer "F.Cu")
		(net "PVDDCR_CPU0_P1_VOS6")
	)
	(segment
		(start 68.097654 -166.31666)
		(end 68.372228 -166.042086)
		(width 0.2032)
		(layer "F.Cu")
		(net "PVDDCR_CPU0_P1_VOS6")
	)
	(via
		(at 68.372228 -166.042086)
		(size 0.508)
		(drill 0.254)
		(layers "F.Cu" "B.Cu")
		(net "PVDDCR_CPU0_P1_VOS6")
	)
	(segment
		(start 68.993512 -166.66337)
		(end 68.372228 -166.042086)
		(width 0.2286)
		(layer "B.Cu")
		(net "PVDDCR_CPU0_P1_VOS6")
	)
	(segment
		(start 69.30898 -166.66337)
		(end 68.993512 -166.66337)
		(width 0.2286)
		(layer "B.Cu")
		(net "PVDDCR_CPU0_P1_VOS6")
	)
	(segment
		(start 76.411074 -175.30064)
		(end 76.411074 -175.013874)
		(width 0.2032)
		(layer "F.Cu")
		(net "PVDDCR_CPU0_P1_VOS5")
	)
	(segment
		(start 76.411074 -175.013874)
		(end 76.685648 -174.7393)
		(width 0.2032)
		(layer "F.Cu")
		(net "PVDDCR_CPU0_P1_VOS5")
	)
	(segment
		(start 76.361036 -175.350678)
		(end 76.411074 -175.30064)
		(width 0.2032)
		(layer "F.Cu")
		(net "PVDDCR_CPU0_P1_VOS5")
	)
	(via
		(at 76.685648 -174.7393)
		(size 0.508)
		(drill 0.254)
		(layers "F.Cu" "B.Cu")
		(net "PVDDCR_CPU0_P1_VOS5")
	)
	(segment
		(start 77.6224 -175.360584)
		(end 77.306932 -175.360584)
		(width 0.2286)
		(layer "B.Cu")
		(net "PVDDCR_CPU0_P1_VOS5")
	)
	(segment
		(start 77.306932 -175.360584)
		(end 76.685648 -174.7393)
		(width 0.2286)
		(layer "B.Cu")
		(net "PVDDCR_CPU0_P1_VOS5")
	)
	(segment
		(start 110.180628 -175.2854)
		(end 109.856016 -175.610012)
		(width 0.2032)
		(layer "F.Cu")
		(net "PVDDCR_CPU0_P1_VOS4")
	)
	(segment
		(start 109.856016 -175.610012)
		(end 109.856016 -175.896778)
		(width 0.2032)
		(layer "F.Cu")
		(net "PVDDCR_CPU0_P1_VOS4")
	)
	(via
		(at 110.180628 -175.2854)
		(size 0.508)
		(drill 0.254)
		(layers "F.Cu" "B.Cu")
		(net "PVDDCR_CPU0_P1_VOS4")
	)
	(segment
		(start 110.801912 -175.906684)
		(end 110.180628 -175.2854)
		(width 0.2286)
		(layer "B.Cu")
		(net "PVDDCR_CPU0_P1_VOS4")
	)
	(segment
		(start 111.11738 -175.906684)
		(end 110.801912 -175.906684)
		(width 0.2286)
		(layer "B.Cu")
		(net "PVDDCR_CPU0_P1_VOS4")
	)
	(segment
		(start 101.474016 -180.131212)
		(end 101.474016 -180.417978)
		(width 0.2032)
		(layer "F.Cu")
		(net "PVDDCR_CPU0_P1_VOS3")
	)
	(segment
		(start 101.798628 -179.8066)
		(end 101.474016 -180.131212)
		(width 0.2032)
		(layer "F.Cu")
		(net "PVDDCR_CPU0_P1_VOS3")
	)
	(via
		(at 101.798628 -179.8066)
		(size 0.508)
		(drill 0.254)
		(layers "F.Cu" "B.Cu")
		(net "PVDDCR_CPU0_P1_VOS3")
	)
	(segment
		(start 102.73538 -180.427884)
		(end 102.419912 -180.427884)
		(width 0.2286)
		(layer "B.Cu")
		(net "PVDDCR_CPU0_P1_VOS3")
	)
	(segment
		(start 102.419912 -180.427884)
		(end 101.798628 -179.8066)
		(width 0.2286)
		(layer "B.Cu")
		(net "PVDDCR_CPU0_P1_VOS3")
	)
	(segment
		(start 93.131894 -180.350668)
		(end 93.131894 -180.063902)
		(width 0.2032)
		(layer "F.Cu")
		(net "PVDDCR_CPU0_P1_VOS2")
	)
	(segment
		(start 93.081856 -180.400706)
		(end 93.131894 -180.350668)
		(width 0.2032)
		(layer "F.Cu")
		(net "PVDDCR_CPU0_P1_VOS2")
	)
	(segment
		(start 93.131894 -180.063902)
		(end 93.406468 -179.789328)
		(width 0.2032)
		(layer "F.Cu")
		(net "PVDDCR_CPU0_P1_VOS2")
	)
	(via
		(at 93.406468 -179.789328)
		(size 0.508)
		(drill 0.254)
		(layers "F.Cu" "B.Cu")
		(net "PVDDCR_CPU0_P1_VOS2")
	)
	(segment
		(start 94.34322 -180.410612)
		(end 94.027752 -180.410612)
		(width 0.2286)
		(layer "B.Cu")
		(net "PVDDCR_CPU0_P1_VOS2")
	)
	(segment
		(start 94.027752 -180.410612)
		(end 93.406468 -179.789328)
		(width 0.2286)
		(layer "B.Cu")
		(net "PVDDCR_CPU0_P1_VOS2")
	)
	(segment
		(start 84.684616 -180.182012)
		(end 84.684616 -180.468778)
		(width 0.2032)
		(layer "F.Cu")
		(net "PVDDCR_CPU0_P1_VOS1")
	)
	(segment
		(start 85.009228 -179.8574)
		(end 84.684616 -180.182012)
		(width 0.2032)
		(layer "F.Cu")
		(net "PVDDCR_CPU0_P1_VOS1")
	)
	(via
		(at 85.009228 -179.8574)
		(size 0.508)
		(drill 0.254)
		(layers "F.Cu" "B.Cu")
		(net "PVDDCR_CPU0_P1_VOS1")
	)
	(segment
		(start 85.94598 -180.478684)
		(end 85.630512 -180.478684)
		(width 0.2286)
		(layer "B.Cu")
		(net "PVDDCR_CPU0_P1_VOS1")
	)
	(segment
		(start 85.630512 -180.478684)
		(end 85.009228 -179.8574)
		(width 0.2286)
		(layer "B.Cu")
		(net "PVDDCR_CPU0_P1_VOS1")
	)
	(segment
		(start 100.85959 -143.477488)
		(end 100.499926 -143.117824)
		(width 0.254)
		(layer "F.Cu")
		(net "PVDDCR_CPU0_P1_VMON")
	)
	(segment
		(start 100.863654 -143.811752)
		(end 100.85959 -143.815816)
		(width 0.254)
		(layer "F.Cu")
		(net "PVDDCR_CPU0_P1_VMON")
	)
	(segment
		(start 99.245928 -143.74241)
		(end 100.786184 -143.74241)
		(width 0.254)
		(layer "F.Cu")
		(net "PVDDCR_CPU0_P1_VMON")
	)
	(segment
		(start 100.786184 -143.74241)
		(end 100.85959 -143.815816)
		(width 0.254)
		(layer "F.Cu")
		(net "PVDDCR_CPU0_P1_VMON")
	)
	(segment
		(start 100.499926 -143.117824)
		(end 100.499926 -143.085312)
		(width 0.254)
		(layer "F.Cu")
		(net "PVDDCR_CPU0_P1_VMON")
	)
	(segment
		(start 100.985828 -142.59941)
		(end 101.548184 -142.59941)
		(width 0.254)
		(layer "F.Cu")
		(net "PVDDCR_CPU0_P1_VMON")
	)
	(segment
		(start 100.85959 -143.815816)
		(end 100.85959 -143.477488)
		(width 0.254)
		(layer "F.Cu")
		(net "PVDDCR_CPU0_P1_VMON")
	)
	(segment
		(start 100.499926 -143.085312)
		(end 100.985828 -142.59941)
		(width 0.254)
		(layer "F.Cu")
		(net "PVDDCR_CPU0_P1_VMON")
	)
	(via
		(at 100.863654 -143.811752)
		(size 0.762)
		(drill 0.381)
		(layers "F.Cu" "B.Cu")
		(net "PVDDCR_CPU0_P1_VMON")
	)
	(via
		(at 100.499926 -143.085312)
		(size 0.508)
		(drill 0.254)
		(layers "F.Cu" "B.Cu")
		(net "PVDDCR_CPU0_P1_VMON")
	)
	(segment
		(start 98.545904 -143.758412)
		(end 99.402646 -143.758412)
		(width 0.1524)
		(layer "B.Cu")
		(net "PVDDCR_CPU0_P1_VMON")
	)
	(segment
		(start 99.402646 -143.758412)
		(end 100.075746 -143.085312)
		(width 0.1524)
		(layer "B.Cu")
		(net "PVDDCR_CPU0_P1_VMON")
	)
	(segment
		(start 100.075746 -143.085312)
		(end 100.499926 -143.085312)
		(width 0.1524)
		(layer "B.Cu")
		(net "PVDDCR_CPU0_P1_VMON")
	)
	(segment
		(start 100.499926 -143.085312)
		(end 100.985828 -142.59941)
		(width 0.254)
		(layer "B.Cu")
		(net "PVDDCR_CPU0_P1_VMON")
	)
	(segment
		(start 101.548184 -141.20241)
		(end 101.548184 -140.18641)
		(width 0.254)
		(layer "F.Cu")
		(net "PVDDCR_CPU0_P1_VINSEN")
	)
	(segment
		(start 101.274626 -141.20241)
		(end 100.373434 -142.103602)
		(width 0.254)
		(layer "F.Cu")
		(net "PVDDCR_CPU0_P1_VINSEN")
	)
	(segment
		(start 101.548184 -141.20241)
		(end 101.274626 -141.20241)
		(width 0.254)
		(layer "F.Cu")
		(net "PVDDCR_CPU0_P1_VINSEN")
	)
	(via
		(at 100.373434 -142.103602)
		(size 0.762)
		(drill 0.254)
		(layers "F.Cu" "B.Cu")
		(net "PVDDCR_CPU0_P1_VINSEN")
	)
	(segment
		(start 100.893626 -141.58341)
		(end 100.985828 -141.58341)
		(width 0.254)
		(layer "B.Cu")
		(net "PVDDCR_CPU0_P1_VINSEN")
	)
	(segment
		(start 100.373434 -142.103602)
		(end 100.893626 -141.58341)
		(width 0.254)
		(layer "B.Cu")
		(net "PVDDCR_CPU0_P1_VINSEN")
	)
	(segment
		(start 99.91725 -142.559786)
		(end 100.373434 -142.103602)
		(width 0.254)
		(layer "B.Cu")
		(net "PVDDCR_CPU0_P1_VINSEN")
	)
	(segment
		(start 99.335336 -143.358362)
		(end 99.91725 -142.776448)
		(width 0.254)
		(layer "B.Cu")
		(net "PVDDCR_CPU0_P1_VINSEN")
	)
	(segment
		(start 98.545904 -143.358362)
		(end 99.335336 -143.358362)
		(width 0.1778)
		(layer "B.Cu")
		(net "PVDDCR_CPU0_P1_VINSEN")
	)
	(segment
		(start 99.91725 -142.776448)
		(end 99.91725 -142.559786)
		(width 0.254)
		(layer "B.Cu")
		(net "PVDDCR_CPU0_P1_VINSEN")
	)
	(segment
		(start 68.341494 -164.471096)
		(end 68.341494 -165.134036)
		(width 0.2286)
		(layer "F.Cu")
		(net "PVDDCR_CPU0_P1_VCCS")
	)
	(segment
		(start 84.27466 -179.653184)
		(end 84.978494 -178.94935)
		(width 0.2286)
		(layer "F.Cu")
		(net "PVDDCR_CPU0_P1_VCCS")
	)
	(segment
		(start 67.613022 -164.471096)
		(end 68.341494 -164.471096)
		(width 0.254)
		(layer "F.Cu")
		(net "PVDDCR_CPU0_P1_VCCS")
	)
	(segment
		(start 135.118094 -152.836626)
		(end 134.41426 -153.54046)
		(width 0.2286)
		(layer "F.Cu")
		(net "PVDDCR_CPU0_P1_VCCS")
	)
	(segment
		(start 75.95108 -174.535084)
		(end 76.654914 -173.83125)
		(width 0.2286)
		(layer "F.Cu")
		(net "PVDDCR_CPU0_P1_VCCS")
	)
	(segment
		(start 126.659894 -160.73501)
		(end 125.931422 -160.73501)
		(width 0.254)
		(layer "F.Cu")
		(net "PVDDCR_CPU0_P1_VCCS")
	)
	(segment
		(start 109.44606 -175.081184)
		(end 110.149894 -174.37735)
		(width 0.2286)
		(layer "F.Cu")
		(net "PVDDCR_CPU0_P1_VCCS")
	)
	(segment
		(start 109.44606 -175.271938)
		(end 109.44606 -175.081184)
		(width 0.2286)
		(layer "F.Cu")
		(net "PVDDCR_CPU0_P1_VCCS")
	)
	(segment
		(start 68.341494 -165.134036)
		(end 67.63766 -165.83787)
		(width 0.2286)
		(layer "F.Cu")
		(net "PVDDCR_CPU0_P1_VCCS")
	)
	(segment
		(start 126.659894 -161.39795)
		(end 126.659894 -160.73501)
		(width 0.2286)
		(layer "F.Cu")
		(net "PVDDCR_CPU0_P1_VCCS")
	)
	(segment
		(start 76.654914 -173.83125)
		(end 76.654914 -173.16831)
		(width 0.2286)
		(layer "F.Cu")
		(net "PVDDCR_CPU0_P1_VCCS")
	)
	(segment
		(start 84.978494 -178.94935)
		(end 84.978494 -178.28641)
		(width 0.2286)
		(layer "F.Cu")
		(net "PVDDCR_CPU0_P1_VCCS")
	)
	(segment
		(start 101.767894 -178.89855)
		(end 101.767894 -178.23561)
		(width 0.2286)
		(layer "F.Cu")
		(net "PVDDCR_CPU0_P1_VCCS")
	)
	(segment
		(start 134.41426 -153.54046)
		(end 134.41426 -153.631138)
		(width 0.2286)
		(layer "F.Cu")
		(net "PVDDCR_CPU0_P1_VCCS")
	)
	(segment
		(start 117.67566 -168.832784)
		(end 117.67566 -169.023538)
		(width 0.2286)
		(layer "F.Cu")
		(net "PVDDCR_CPU0_P1_VCCS")
	)
	(segment
		(start 135.118094 -152.07361)
		(end 135.118094 -152.836626)
		(width 0.2286)
		(layer "F.Cu")
		(net "PVDDCR_CPU0_P1_VCCS")
	)
	(segment
		(start 93.375734 -178.881278)
		(end 93.375734 -178.218338)
		(width 0.2286)
		(layer "F.Cu")
		(net "PVDDCR_CPU0_P1_VCCS")
	)
	(segment
		(start 84.978494 -178.28641)
		(end 84.250022 -178.28641)
		(width 0.254)
		(layer "F.Cu")
		(net "PVDDCR_CPU0_P1_VCCS")
	)
	(segment
		(start 92.6719 -179.775866)
		(end 92.6719 -179.585112)
		(width 0.2286)
		(layer "F.Cu")
		(net "PVDDCR_CPU0_P1_VCCS")
	)
	(segment
		(start 110.149894 -173.71441)
		(end 109.421422 -173.71441)
		(width 0.254)
		(layer "F.Cu")
		(net "PVDDCR_CPU0_P1_VCCS")
	)
	(segment
		(start 93.375734 -178.218338)
		(end 92.647262 -178.218338)
		(width 0.254)
		(layer "F.Cu")
		(net "PVDDCR_CPU0_P1_VCCS")
	)
	(segment
		(start 92.6719 -179.585112)
		(end 93.375734 -178.881278)
		(width 0.2286)
		(layer "F.Cu")
		(net "PVDDCR_CPU0_P1_VCCS")
	)
	(segment
		(start 110.149894 -174.37735)
		(end 110.149894 -173.71441)
		(width 0.2286)
		(layer "F.Cu")
		(net "PVDDCR_CPU0_P1_VCCS")
	)
	(segment
		(start 101.06406 -179.793138)
		(end 101.06406 -179.602384)
		(width 0.2286)
		(layer "F.Cu")
		(net "PVDDCR_CPU0_P1_VCCS")
	)
	(segment
		(start 84.27466 -179.843938)
		(end 84.27466 -179.653184)
		(width 0.2286)
		(layer "F.Cu")
		(net "PVDDCR_CPU0_P1_VCCS")
	)
	(segment
		(start 125.95606 -162.101784)
		(end 126.659894 -161.39795)
		(width 0.2286)
		(layer "F.Cu")
		(net "PVDDCR_CPU0_P1_VCCS")
	)
	(segment
		(start 117.651022 -167.46601)
		(end 118.379494 -167.46601)
		(width 0.254)
		(layer "F.Cu")
		(net "PVDDCR_CPU0_P1_VCCS")
	)
	(segment
		(start 75.95108 -174.725838)
		(end 75.95108 -174.535084)
		(width 0.2286)
		(layer "F.Cu")
		(net "PVDDCR_CPU0_P1_VCCS")
	)
	(segment
		(start 118.379494 -168.12895)
		(end 117.67566 -168.832784)
		(width 0.2286)
		(layer "F.Cu")
		(net "PVDDCR_CPU0_P1_VCCS")
	)
	(segment
		(start 101.767894 -178.23561)
		(end 101.039422 -178.23561)
		(width 0.254)
		(layer "F.Cu")
		(net "PVDDCR_CPU0_P1_VCCS")
	)
	(segment
		(start 67.63766 -165.83787)
		(end 67.63766 -166.028624)
		(width 0.2286)
		(layer "F.Cu")
		(net "PVDDCR_CPU0_P1_VCCS")
	)
	(segment
		(start 76.654914 -173.16831)
		(end 75.926442 -173.16831)
		(width 0.254)
		(layer "F.Cu")
		(net "PVDDCR_CPU0_P1_VCCS")
	)
	(segment
		(start 125.95606 -162.292538)
		(end 125.95606 -162.101784)
		(width 0.2286)
		(layer "F.Cu")
		(net "PVDDCR_CPU0_P1_VCCS")
	)
	(segment
		(start 101.06406 -179.602384)
		(end 101.767894 -178.89855)
		(width 0.2286)
		(layer "F.Cu")
		(net "PVDDCR_CPU0_P1_VCCS")
	)
	(segment
		(start 134.404862 -152.07869)
		(end 134.409942 -152.07361)
		(width 0.254)
		(layer "F.Cu")
		(net "PVDDCR_CPU0_P1_VCCS")
	)
	(segment
		(start 134.409942 -152.07361)
		(end 135.118094 -152.07361)
		(width 0.254)
		(layer "F.Cu")
		(net "PVDDCR_CPU0_P1_VCCS")
	)
	(segment
		(start 118.379494 -167.46601)
		(end 118.379494 -168.12895)
		(width 0.2286)
		(layer "F.Cu")
		(net "PVDDCR_CPU0_P1_VCCS")
	)
	(via
		(at 117.651022 -167.46601)
		(size 0.508)
		(drill 0.254)
		(layers "F.Cu" "B.Cu")
		(net "PVDDCR_CPU0_P1_VCCS")
	)
	(via
		(at 84.250022 -178.28641)
		(size 0.508)
		(drill 0.254)
		(layers "F.Cu" "B.Cu")
		(net "PVDDCR_CPU0_P1_VCCS")
	)
	(via
		(at 134.404862 -152.07869)
		(size 0.508)
		(drill 0.254)
		(layers "F.Cu" "B.Cu")
		(net "PVDDCR_CPU0_P1_VCCS")
	)
	(via
		(at 109.421422 -173.71441)
		(size 0.508)
		(drill 0.254)
		(layers "F.Cu" "B.Cu")
		(net "PVDDCR_CPU0_P1_VCCS")
	)
	(via
		(at 92.647262 -178.218338)
		(size 0.508)
		(drill 0.254)
		(layers "F.Cu" "B.Cu")
		(net "PVDDCR_CPU0_P1_VCCS")
	)
	(via
		(at 67.613022 -164.471096)
		(size 0.508)
		(drill 0.254)
		(layers "F.Cu" "B.Cu")
		(net "PVDDCR_CPU0_P1_VCCS")
	)
	(via
		(at 98.80219 -140.93698)
		(size 0.762)
		(drill 0.254)
		(layers "F.Cu" "B.Cu")
		(net "PVDDCR_CPU0_P1_VCCS")
	)
	(via
		(at 75.926442 -173.16831)
		(size 0.508)
		(drill 0.254)
		(layers "F.Cu" "B.Cu")
		(net "PVDDCR_CPU0_P1_VCCS")
	)
	(via
		(at 125.931422 -160.73501)
		(size 0.508)
		(drill 0.254)
		(layers "F.Cu" "B.Cu")
		(net "PVDDCR_CPU0_P1_VCCS")
	)
	(via
		(at 101.039422 -178.23561)
		(size 0.508)
		(drill 0.254)
		(layers "F.Cu" "B.Cu")
		(net "PVDDCR_CPU0_P1_VCCS")
	)
	(segment
		(start 91.554554 -149.437852)
		(end 91.000834 -149.437852)
		(width 0.254)
		(layer "In4.Cu")
		(net "PVDDCR_CPU0_P1_VCCS")
	)
	(segment
		(start 104.456484 -172.244004)
		(end 101.512878 -169.300398)
		(width 0.254)
		(layer "In4.Cu")
		(net "PVDDCR_CPU0_P1_VCCS")
	)
	(segment
		(start 134.024878 -150.72741)
		(end 128.309878 -150.72741)
		(width 0.254)
		(layer "In4.Cu")
		(net "PVDDCR_CPU0_P1_VCCS")
	)
	(segment
		(start 124.525278 -158.34741)
		(end 107.540298 -158.34741)
		(width 0.254)
		(layer "In4.Cu")
		(net "PVDDCR_CPU0_P1_VCCS")
	)
	(segment
		(start 92.876878 -177.988722)
		(end 92.876878 -176.085754)
		(width 0.254)
		(layer "In4.Cu")
		(net "PVDDCR_CPU0_P1_VCCS")
	)
	(segment
		(start 134.609078 -151.854154)
		(end 134.609078 -151.31161)
		(width 0.254)
		(layer "In4.Cu")
		(net "PVDDCR_CPU0_P1_VCCS")
	)
	(segment
		(start 134.404862 -152.07869)
		(end 134.404862 -152.05837)
		(width 0.254)
		(layer "In4.Cu")
		(net "PVDDCR_CPU0_P1_VCCS")
	)
	(segment
		(start 126.150878 -160.515554)
		(end 126.150878 -159.97301)
		(width 0.254)
		(layer "In4.Cu")
		(net "PVDDCR_CPU0_P1_VCCS")
	)
	(segment
		(start 99.001834 -175.216566)
		(end 99.001834 -159.039052)
		(width 0.254)
		(layer "In4.Cu")
		(net "PVDDCR_CPU0_P1_VCCS")
	)
	(segment
		(start 93.413834 -152.841452)
		(end 93.388434 -152.816052)
		(width 0.254)
		(layer "In4.Cu")
		(net "PVDDCR_CPU0_P1_VCCS")
	)
	(segment
		(start 109.421422 -173.71441)
		(end 109.640878 -173.494954)
		(width 0.254)
		(layer "In4.Cu")
		(net "PVDDCR_CPU0_P1_VCCS")
	)
	(segment
		(start 92.647262 -178.218338)
		(end 92.876878 -177.988722)
		(width 0.254)
		(layer "In4.Cu")
		(net "PVDDCR_CPU0_P1_VCCS")
	)
	(segment
		(start 117.870478 -166.70401)
		(end 117.870478 -167.246554)
		(width 0.254)
		(layer "In4.Cu")
		(net "PVDDCR_CPU0_P1_VCCS")
	)
	(segment
		(start 96.334834 -172.627798)
		(end 96.334834 -160.309052)
		(width 0.254)
		(layer "In4.Cu")
		(net "PVDDCR_CPU0_P1_VCCS")
	)
	(segment
		(start 128.309878 -150.72741)
		(end 122.495818 -156.54147)
		(width 0.254)
		(layer "In4.Cu")
		(net "PVDDCR_CPU0_P1_VCCS")
	)
	(segment
		(start 109.640878 -172.95241)
		(end 108.932472 -172.244004)
		(width 0.254)
		(layer "In4.Cu")
		(net "PVDDCR_CPU0_P1_VCCS")
	)
	(segment
		(start 99.100894 -152.201372)
		(end 99.100894 -153.143712)
		(width 0.254)
		(layer "In4.Cu")
		(net "PVDDCR_CPU0_P1_VCCS")
	)
	(segment
		(start 108.932472 -172.244004)
		(end 104.456484 -172.244004)
		(width 0.254)
		(layer "In4.Cu")
		(net "PVDDCR_CPU0_P1_VCCS")
	)
	(segment
		(start 101.039422 -178.23561)
		(end 101.258878 -178.016154)
		(width 0.254)
		(layer "In4.Cu")
		(net "PVDDCR_CPU0_P1_VCCS")
	)
	(segment
		(start 96.334834 -160.309052)
		(end 93.413834 -157.388052)
		(width 0.254)
		(layer "In4.Cu")
		(net "PVDDCR_CPU0_P1_VCCS")
	)
	(segment
		(start 100.860098 -151.66721)
		(end 100.449634 -151.66721)
		(width 0.254)
		(layer "In4.Cu")
		(net "PVDDCR_CPU0_P1_VCCS")
	)
	(segment
		(start 94.737174 -154.774392)
		(end 94.737174 -152.843992)
		(width 0.254)
		(layer "In4.Cu")
		(net "PVDDCR_CPU0_P1_VCCS")
	)
	(segment
		(start 107.860592 -161.90341)
		(end 113.069878 -161.90341)
		(width 0.254)
		(layer "In4.Cu")
		(net "PVDDCR_CPU0_P1_VCCS")
	)
	(segment
		(start 109.640878 -173.494954)
		(end 109.640878 -172.95241)
		(width 0.254)
		(layer "In4.Cu")
		(net "PVDDCR_CPU0_P1_VCCS")
	)
	(segment
		(start 101.258878 -177.47361)
		(end 99.001834 -175.216566)
		(width 0.254)
		(layer "In4.Cu")
		(net "PVDDCR_CPU0_P1_VCCS")
	)
	(segment
		(start 101.512878 -169.300398)
		(end 101.512878 -158.832296)
		(width 0.254)
		(layer "In4.Cu")
		(net "PVDDCR_CPU0_P1_VCCS")
	)
	(segment
		(start 89.245694 -151.192992)
		(end 84.41182 -151.192992)
		(width 0.254)
		(layer "In4.Cu")
		(net "PVDDCR_CPU0_P1_VCCS")
	)
	(segment
		(start 134.609078 -151.31161)
		(end 134.024878 -150.72741)
		(width 0.254)
		(layer "In4.Cu")
		(net "PVDDCR_CPU0_P1_VCCS")
	)
	(segment
		(start 107.540298 -158.34741)
		(end 100.860098 -151.66721)
		(width 0.254)
		(layer "In4.Cu")
		(net "PVDDCR_CPU0_P1_VCCS")
	)
	(segment
		(start 122.495818 -156.54147)
		(end 107.604052 -156.54147)
		(width 0.254)
		(layer "In4.Cu")
		(net "PVDDCR_CPU0_P1_VCCS")
	)
	(segment
		(start 126.150878 -159.97301)
		(end 124.525278 -158.34741)
		(width 0.254)
		(layer "In4.Cu")
		(net "PVDDCR_CPU0_P1_VCCS")
	)
	(segment
		(start 117.870478 -167.246554)
		(end 117.651022 -167.46601)
		(width 0.254)
		(layer "In4.Cu")
		(net "PVDDCR_CPU0_P1_VCCS")
	)
	(segment
		(start 93.413834 -157.388052)
		(end 93.413834 -152.841452)
		(width 0.254)
		(layer "In4.Cu")
		(net "PVDDCR_CPU0_P1_VCCS")
	)
	(segment
		(start 125.931422 -160.73501)
		(end 126.150878 -160.515554)
		(width 0.254)
		(layer "In4.Cu")
		(net "PVDDCR_CPU0_P1_VCCS")
	)
	(segment
		(start 80.588866 -173.643798)
		(end 84.469478 -177.52441)
		(width 0.254)
		(layer "In4.Cu")
		(net "PVDDCR_CPU0_P1_VCCS")
	)
	(segment
		(start 92.876878 -176.085754)
		(end 96.334834 -172.627798)
		(width 0.254)
		(layer "In4.Cu")
		(net "PVDDCR_CPU0_P1_VCCS")
	)
	(segment
		(start 113.069878 -161.90341)
		(end 117.870478 -166.70401)
		(width 0.254)
		(layer "In4.Cu")
		(net "PVDDCR_CPU0_P1_VCCS")
	)
	(segment
		(start 84.41182 -151.192992)
		(end 80.588866 -155.015946)
		(width 0.254)
		(layer "In4.Cu")
		(net "PVDDCR_CPU0_P1_VCCS")
	)
	(segment
		(start 101.258878 -178.016154)
		(end 101.258878 -177.47361)
		(width 0.254)
		(layer "In4.Cu")
		(net "PVDDCR_CPU0_P1_VCCS")
	)
	(segment
		(start 91.000834 -149.437852)
		(end 89.245694 -151.192992)
		(width 0.254)
		(layer "In4.Cu")
		(net "PVDDCR_CPU0_P1_VCCS")
	)
	(segment
		(start 84.469478 -178.066954)
		(end 84.250022 -178.28641)
		(width 0.254)
		(layer "In4.Cu")
		(net "PVDDCR_CPU0_P1_VCCS")
	)
	(segment
		(start 107.604052 -156.54147)
		(end 101.186234 -150.123652)
		(width 0.254)
		(layer "In4.Cu")
		(net "PVDDCR_CPU0_P1_VCCS")
	)
	(segment
		(start 84.469478 -177.52441)
		(end 84.469478 -178.066954)
		(width 0.254)
		(layer "In4.Cu")
		(net "PVDDCR_CPU0_P1_VCCS")
	)
	(segment
		(start 101.512878 -158.832296)
		(end 95.740474 -153.059892)
		(width 0.254)
		(layer "In4.Cu")
		(net "PVDDCR_CPU0_P1_VCCS")
	)
	(segment
		(start 80.588866 -155.015946)
		(end 80.588866 -173.643798)
		(width 0.254)
		(layer "In4.Cu")
		(net "PVDDCR_CPU0_P1_VCCS")
	)
	(segment
		(start 134.404862 -152.05837)
		(end 134.609078 -151.854154)
		(width 0.254)
		(layer "In4.Cu")
		(net "PVDDCR_CPU0_P1_VCCS")
	)
	(segment
		(start 99.001834 -159.039052)
		(end 94.737174 -154.774392)
		(width 0.254)
		(layer "In4.Cu")
		(net "PVDDCR_CPU0_P1_VCCS")
	)
	(segment
		(start 99.100894 -153.143712)
		(end 107.860592 -161.90341)
		(width 0.254)
		(layer "In4.Cu")
		(net "PVDDCR_CPU0_P1_VCCS")
	)
	(segment
		(start 91.714574 -149.277832)
		(end 91.554554 -149.437852)
		(width 0.254)
		(layer "In4.Cu")
		(net "PVDDCR_CPU0_P1_VCCS")
	)
	(segment
		(start 76.976986 -171.129452)
		(end 76.145898 -171.96054)
		(width 0.254)
		(layer "In11.Cu")
		(net "PVDDCR_CPU0_P1_VCCS")
	)
	(segment
		(start 76.145898 -171.96054)
		(end 76.145898 -172.948854)
		(width 0.254)
		(layer "In11.Cu")
		(net "PVDDCR_CPU0_P1_VCCS")
	)
	(segment
		(start 92.570046 -148.2471)
		(end 89.817956 -150.99919)
		(width 0.254)
		(layer "In11.Cu")
		(net "PVDDCR_CPU0_P1_VCCS")
	)
	(segment
		(start 67.832478 -164.25164)
		(end 67.613022 -164.471096)
		(width 0.254)
		(layer "In11.Cu")
		(net "PVDDCR_CPU0_P1_VCCS")
	)
	(segment
		(start 93.08846 -148.2471)
		(end 92.570046 -148.2471)
		(width 0.254)
		(layer "In11.Cu")
		(net "PVDDCR_CPU0_P1_VCCS")
	)
	(segment
		(start 96.482154 -151.739092)
		(end 96.482154 -169.247312)
		(width 0.254)
		(layer "In11.Cu")
		(net "PVDDCR_CPU0_P1_VCCS")
	)
	(segment
		(start 69.922136 -156.953204)
		(end 67.832478 -159.042862)
		(width 0.254)
		(layer "In11.Cu")
		(net "PVDDCR_CPU0_P1_VCCS")
	)
	(segment
		(start 96.243394 -151.500332)
		(end 96.482154 -151.739092)
		(width 0.254)
		(layer "In11.Cu")
		(net "PVDDCR_CPU0_P1_VCCS")
	)
	(segment
		(start 83.969098 -150.99919)
		(end 78.015084 -156.953204)
		(width 0.254)
		(layer "In11.Cu")
		(net "PVDDCR_CPU0_P1_VCCS")
	)
	(segment
		(start 89.817956 -150.99919)
		(end 83.969098 -150.99919)
		(width 0.254)
		(layer "In11.Cu")
		(net "PVDDCR_CPU0_P1_VCCS")
	)
	(segment
		(start 78.015084 -156.953204)
		(end 69.922136 -156.953204)
		(width 0.254)
		(layer "In11.Cu")
		(net "PVDDCR_CPU0_P1_VCCS")
	)
	(segment
		(start 94.600014 -171.129452)
		(end 76.976986 -171.129452)
		(width 0.254)
		(layer "In11.Cu")
		(net "PVDDCR_CPU0_P1_VCCS")
	)
	(segment
		(start 67.832478 -159.042862)
		(end 67.832478 -164.25164)
		(width 0.254)
		(layer "In11.Cu")
		(net "PVDDCR_CPU0_P1_VCCS")
	)
	(segment
		(start 76.145898 -172.948854)
		(end 75.926442 -173.16831)
		(width 0.254)
		(layer "In11.Cu")
		(net "PVDDCR_CPU0_P1_VCCS")
	)
	(segment
		(start 96.482154 -169.247312)
		(end 94.600014 -171.129452)
		(width 0.254)
		(layer "In11.Cu")
		(net "PVDDCR_CPU0_P1_VCCS")
	)
	(segment
		(start 68.698364 -167.55364)
		(end 68.047616 -167.55364)
		(width 0.2286)
		(layer "F.Cu")
		(net "PVDDCR_CPU0_P1_VCC6")
	)
	(segment
		(start 65.847468 -165.306756)
		(end 65.913254 -165.24097)
		(width 0.2286)
		(layer "F.Cu")
		(net "PVDDCR_CPU0_P1_VCC6")
	)
	(segment
		(start 69.33057 -167.273732)
		(end 68.978272 -167.273732)
		(width 0.2286)
		(layer "F.Cu")
		(net "PVDDCR_CPU0_P1_VCC6")
	)
	(segment
		(start 65.837562 -166.028624)
		(end 65.847468 -166.018718)
		(width 0.2286)
		(layer "F.Cu")
		(net "PVDDCR_CPU0_P1_VCC6")
	)
	(segment
		(start 68.978272 -167.273732)
		(end 68.698364 -167.55364)
		(width 0.2286)
		(layer "F.Cu")
		(net "PVDDCR_CPU0_P1_VCC6")
	)
	(segment
		(start 65.847468 -166.018718)
		(end 65.847468 -165.306756)
		(width 0.2286)
		(layer "F.Cu")
		(net "PVDDCR_CPU0_P1_VCC6")
	)
	(segment
		(start 69.33057 -166.66337)
		(end 69.33057 -167.273732)
		(width 0.381)
		(layer "F.Cu")
		(net "PVDDCR_CPU0_P1_VCC6")
	)
	(via
		(at 69.33057 -167.273732)
		(size 0.508)
		(drill 0.254)
		(layers "F.Cu" "B.Cu")
		(net "PVDDCR_CPU0_P1_VCC6")
	)
	(via
		(at 67.508628 -166.102538)
		(size 0.6604)
		(drill 0.3302)
		(layers "F.Cu" "B.Cu")
		(net "PVDDCR_CPU0_P1_VCC6")
	)
	(via
		(at 65.913254 -165.24097)
		(size 0.508)
		(drill 0.254)
		(layers "F.Cu" "B.Cu")
		(net "PVDDCR_CPU0_P1_VCC6")
	)
	(segment
		(start 65.913254 -165.83406)
		(end 66.130424 -166.05123)
		(width 0.508)
		(layer "B.Cu")
		(net "PVDDCR_CPU0_P1_VCC6")
	)
	(segment
		(start 67.551808 -166.102538)
		(end 67.958462 -166.509192)
		(width 0.381)
		(layer "B.Cu")
		(net "PVDDCR_CPU0_P1_VCC6")
	)
	(segment
		(start 68.46824 -167.469312)
		(end 68.66382 -167.273732)
		(width 0.381)
		(layer "B.Cu")
		(net "PVDDCR_CPU0_P1_VCC6")
	)
	(segment
		(start 67.958462 -167.469312)
		(end 68.46824 -167.469312)
		(width 0.381)
		(layer "B.Cu")
		(net "PVDDCR_CPU0_P1_VCC6")
	)
	(segment
		(start 67.45732 -166.05123)
		(end 67.508628 -166.102538)
		(width 0.381)
		(layer "B.Cu")
		(net "PVDDCR_CPU0_P1_VCC6")
	)
	(segment
		(start 67.508628 -166.102538)
		(end 67.551808 -166.102538)
		(width 0.381)
		(layer "B.Cu")
		(net "PVDDCR_CPU0_P1_VCC6")
	)
	(segment
		(start 66.130424 -166.05123)
		(end 66.180208 -166.05123)
		(width 0.508)
		(layer "B.Cu")
		(net "PVDDCR_CPU0_P1_VCC6")
	)
	(segment
		(start 68.66382 -167.273732)
		(end 69.33057 -167.273732)
		(width 0.381)
		(layer "B.Cu")
		(net "PVDDCR_CPU0_P1_VCC6")
	)
	(segment
		(start 65.913254 -165.24097)
		(end 65.913254 -165.83406)
		(width 0.508)
		(layer "B.Cu")
		(net "PVDDCR_CPU0_P1_VCC6")
	)
	(segment
		(start 66.180208 -166.05123)
		(end 67.45732 -166.05123)
		(width 0.381)
		(layer "B.Cu")
		(net "PVDDCR_CPU0_P1_VCC6")
	)
	(segment
		(start 67.958462 -166.509192)
		(end 67.958462 -167.469312)
		(width 0.381)
		(layer "B.Cu")
		(net "PVDDCR_CPU0_P1_VCC6")
	)
	(segment
		(start 74.150982 -174.725838)
		(end 74.150982 -174.013876)
		(width 0.2286)
		(layer "F.Cu")
		(net "PVDDCR_CPU0_P1_VCC5")
	)
	(segment
		(start 74.150982 -174.013876)
		(end 74.226674 -173.938184)
		(width 0.2286)
		(layer "F.Cu")
		(net "PVDDCR_CPU0_P1_VCC5")
	)
	(segment
		(start 77.291692 -175.970946)
		(end 77.011784 -176.250854)
		(width 0.2286)
		(layer "F.Cu")
		(net "PVDDCR_CPU0_P1_VCC5")
	)
	(segment
		(start 77.64399 -175.970946)
		(end 77.291692 -175.970946)
		(width 0.2286)
		(layer "F.Cu")
		(net "PVDDCR_CPU0_P1_VCC5")
	)
	(segment
		(start 77.64399 -175.360584)
		(end 77.64399 -175.970946)
		(width 0.381)
		(layer "F.Cu")
		(net "PVDDCR_CPU0_P1_VCC5")
	)
	(segment
		(start 77.011784 -176.250854)
		(end 76.361036 -176.250854)
		(width 0.2286)
		(layer "F.Cu")
		(net "PVDDCR_CPU0_P1_VCC5")
	)
	(via
		(at 74.629518 -174.748444)
		(size 0.6604)
		(drill 0.3302)
		(layers "F.Cu" "B.Cu")
		(net "PVDDCR_CPU0_P1_VCC5")
	)
	(via
		(at 74.226674 -173.938184)
		(size 0.508)
		(drill 0.254)
		(layers "F.Cu" "B.Cu")
		(net "PVDDCR_CPU0_P1_VCC5")
	)
	(via
		(at 77.64399 -175.970946)
		(size 0.508)
		(drill 0.254)
		(layers "F.Cu" "B.Cu")
		(net "PVDDCR_CPU0_P1_VCC5")
	)
	(segment
		(start 76.271882 -175.206406)
		(end 76.271882 -176.166526)
		(width 0.381)
		(layer "B.Cu")
		(net "PVDDCR_CPU0_P1_VCC5")
	)
	(segment
		(start 76.97724 -175.970946)
		(end 77.64399 -175.970946)
		(width 0.381)
		(layer "B.Cu")
		(net "PVDDCR_CPU0_P1_VCC5")
	)
	(segment
		(start 76.271882 -176.166526)
		(end 76.78166 -176.166526)
		(width 0.381)
		(layer "B.Cu")
		(net "PVDDCR_CPU0_P1_VCC5")
	)
	(segment
		(start 74.226674 -173.938184)
		(end 74.226674 -174.531274)
		(width 0.508)
		(layer "B.Cu")
		(net "PVDDCR_CPU0_P1_VCC5")
	)
	(segment
		(start 74.443844 -174.748444)
		(end 74.493628 -174.748444)
		(width 0.508)
		(layer "B.Cu")
		(net "PVDDCR_CPU0_P1_VCC5")
	)
	(segment
		(start 74.629518 -174.748444)
		(end 75.81392 -174.748444)
		(width 0.381)
		(layer "B.Cu")
		(net "PVDDCR_CPU0_P1_VCC5")
	)
	(segment
		(start 74.226674 -174.531274)
		(end 74.443844 -174.748444)
		(width 0.508)
		(layer "B.Cu")
		(net "PVDDCR_CPU0_P1_VCC5")
	)
	(segment
		(start 75.81392 -174.748444)
		(end 76.271882 -175.206406)
		(width 0.381)
		(layer "B.Cu")
		(net "PVDDCR_CPU0_P1_VCC5")
	)
	(segment
		(start 74.493628 -174.748444)
		(end 74.629518 -174.748444)
		(width 0.381)
		(layer "B.Cu")
		(net "PVDDCR_CPU0_P1_VCC5")
	)
	(segment
		(start 76.78166 -176.166526)
		(end 76.97724 -175.970946)
		(width 0.381)
		(layer "B.Cu")
		(net "PVDDCR_CPU0_P1_VCC5")
	)
	(segment
		(start 107.645962 -174.559976)
		(end 107.721654 -174.484284)
		(width 0.2286)
		(layer "F.Cu")
		(net "PVDDCR_CPU0_P1_VCC4")
	)
	(segment
		(start 111.13897 -175.906684)
		(end 111.13897 -176.517046)
		(width 0.381)
		(layer "F.Cu")
		(net "PVDDCR_CPU0_P1_VCC4")
	)
	(segment
		(start 110.786672 -176.517046)
		(end 110.506764 -176.796954)
		(width 0.2286)
		(layer "F.Cu")
		(net "PVDDCR_CPU0_P1_VCC4")
	)
	(segment
		(start 107.645962 -175.271938)
		(end 107.645962 -174.559976)
		(width 0.2286)
		(layer "F.Cu")
		(net "PVDDCR_CPU0_P1_VCC4")
	)
	(segment
		(start 110.506764 -176.796954)
		(end 109.856016 -176.796954)
		(width 0.2286)
		(layer "F.Cu")
		(net "PVDDCR_CPU0_P1_VCC4")
	)
	(segment
		(start 111.13897 -176.517046)
		(end 110.786672 -176.517046)
		(width 0.2286)
		(layer "F.Cu")
		(net "PVDDCR_CPU0_P1_VCC4")
	)
	(via
		(at 107.988608 -175.294544)
		(size 0.6604)
		(drill 0.3302)
		(layers "F.Cu" "B.Cu")
		(net "PVDDCR_CPU0_P1_VCC4")
	)
	(via
		(at 107.721654 -174.484284)
		(size 0.508)
		(drill 0.254)
		(layers "F.Cu" "B.Cu")
		(net "PVDDCR_CPU0_P1_VCC4")
	)
	(via
		(at 111.13897 -176.517046)
		(size 0.508)
		(drill 0.254)
		(layers "F.Cu" "B.Cu")
		(net "PVDDCR_CPU0_P1_VCC4")
	)
	(segment
		(start 107.721654 -175.077374)
		(end 107.938824 -175.294544)
		(width 0.508)
		(layer "B.Cu")
		(net "PVDDCR_CPU0_P1_VCC4")
	)
	(segment
		(start 110.426246 -176.712626)
		(end 110.621826 -176.517046)
		(width 0.381)
		(layer "B.Cu")
		(net "PVDDCR_CPU0_P1_VCC4")
	)
	(segment
		(start 109.3089 -175.294544)
		(end 109.766862 -175.752506)
		(width 0.381)
		(layer "B.Cu")
		(net "PVDDCR_CPU0_P1_VCC4")
	)
	(segment
		(start 109.766862 -176.712626)
		(end 110.426246 -176.712626)
		(width 0.381)
		(layer "B.Cu")
		(net "PVDDCR_CPU0_P1_VCC4")
	)
	(segment
		(start 107.721654 -174.484284)
		(end 107.721654 -175.077374)
		(width 0.508)
		(layer "B.Cu")
		(net "PVDDCR_CPU0_P1_VCC4")
	)
	(segment
		(start 109.766862 -175.752506)
		(end 109.766862 -176.712626)
		(width 0.381)
		(layer "B.Cu")
		(net "PVDDCR_CPU0_P1_VCC4")
	)
	(segment
		(start 107.988608 -175.294544)
		(end 109.3089 -175.294544)
		(width 0.381)
		(layer "B.Cu")
		(net "PVDDCR_CPU0_P1_VCC4")
	)
	(segment
		(start 110.621826 -176.517046)
		(end 111.13897 -176.517046)
		(width 0.381)
		(layer "B.Cu")
		(net "PVDDCR_CPU0_P1_VCC4")
	)
	(segment
		(start 107.938824 -175.294544)
		(end 107.988608 -175.294544)
		(width 0.508)
		(layer "B.Cu")
		(net "PVDDCR_CPU0_P1_VCC4")
	)
	(segment
		(start 102.404672 -181.038246)
		(end 102.124764 -181.318154)
		(width 0.2286)
		(layer "F.Cu")
		(net "PVDDCR_CPU0_P1_VCC3")
	)
	(segment
		(start 102.75697 -181.038246)
		(end 102.404672 -181.038246)
		(width 0.2286)
		(layer "F.Cu")
		(net "PVDDCR_CPU0_P1_VCC3")
	)
	(segment
		(start 102.75697 -180.427884)
		(end 102.75697 -181.038246)
		(width 0.381)
		(layer "F.Cu")
		(net "PVDDCR_CPU0_P1_VCC3")
	)
	(segment
		(start 99.263962 -179.793138)
		(end 99.263962 -179.081176)
		(width 0.2286)
		(layer "F.Cu")
		(net "PVDDCR_CPU0_P1_VCC3")
	)
	(segment
		(start 99.263962 -179.081176)
		(end 99.339654 -179.005484)
		(width 0.2286)
		(layer "F.Cu")
		(net "PVDDCR_CPU0_P1_VCC3")
	)
	(segment
		(start 102.124764 -181.318154)
		(end 101.474016 -181.318154)
		(width 0.2286)
		(layer "F.Cu")
		(net "PVDDCR_CPU0_P1_VCC3")
	)
	(via
		(at 99.90201 -179.815744)
		(size 0.6604)
		(drill 0.3302)
		(layers "F.Cu" "B.Cu")
		(net "PVDDCR_CPU0_P1_VCC3")
	)
	(via
		(at 99.339654 -179.005484)
		(size 0.508)
		(drill 0.254)
		(layers "F.Cu" "B.Cu")
		(net "PVDDCR_CPU0_P1_VCC3")
	)
	(via
		(at 102.75697 -181.038246)
		(size 0.508)
		(drill 0.254)
		(layers "F.Cu" "B.Cu")
		(net "PVDDCR_CPU0_P1_VCC3")
	)
	(segment
		(start 99.339654 -179.598574)
		(end 99.556824 -179.815744)
		(width 0.508)
		(layer "B.Cu")
		(net "PVDDCR_CPU0_P1_VCC3")
	)
	(segment
		(start 100.9269 -179.815744)
		(end 101.384862 -180.273706)
		(width 0.381)
		(layer "B.Cu")
		(net "PVDDCR_CPU0_P1_VCC3")
	)
	(segment
		(start 101.89464 -181.233826)
		(end 102.09022 -181.038246)
		(width 0.381)
		(layer "B.Cu")
		(net "PVDDCR_CPU0_P1_VCC3")
	)
	(segment
		(start 99.556824 -179.815744)
		(end 99.606608 -179.815744)
		(width 0.508)
		(layer "B.Cu")
		(net "PVDDCR_CPU0_P1_VCC3")
	)
	(segment
		(start 99.606608 -179.815744)
		(end 99.90201 -179.815744)
		(width 0.381)
		(layer "B.Cu")
		(net "PVDDCR_CPU0_P1_VCC3")
	)
	(segment
		(start 99.90201 -179.815744)
		(end 100.9269 -179.815744)
		(width 0.381)
		(layer "B.Cu")
		(net "PVDDCR_CPU0_P1_VCC3")
	)
	(segment
		(start 99.339654 -179.005484)
		(end 99.339654 -179.598574)
		(width 0.508)
		(layer "B.Cu")
		(net "PVDDCR_CPU0_P1_VCC3")
	)
	(segment
		(start 101.384862 -180.273706)
		(end 101.384862 -181.233826)
		(width 0.381)
		(layer "B.Cu")
		(net "PVDDCR_CPU0_P1_VCC3")
	)
	(segment
		(start 102.09022 -181.038246)
		(end 102.75697 -181.038246)
		(width 0.381)
		(layer "B.Cu")
		(net "PVDDCR_CPU0_P1_VCC3")
	)
	(segment
		(start 101.384862 -181.233826)
		(end 101.89464 -181.233826)
		(width 0.381)
		(layer "B.Cu")
		(net "PVDDCR_CPU0_P1_VCC3")
	)
	(segment
		(start 93.766132 -181.300882)
		(end 94.04604 -181.020974)
		(width 0.2286)
		(layer "F.Cu")
		(net "PVDDCR_CPU0_P1_VCC2")
	)
	(segment
		(start 90.871802 -179.063904)
		(end 90.871802 -179.775866)
		(width 0.2286)
		(layer "F.Cu")
		(net "PVDDCR_CPU0_P1_VCC2")
	)
	(segment
		(start 90.947494 -178.988212)
		(end 90.871802 -179.063904)
		(width 0.2286)
		(layer "F.Cu")
		(net "PVDDCR_CPU0_P1_VCC2")
	)
	(segment
		(start 94.36481 -181.020974)
		(end 94.36481 -180.410612)
		(width 0.381)
		(layer "F.Cu")
		(net "PVDDCR_CPU0_P1_VCC2")
	)
	(segment
		(start 94.04604 -181.020974)
		(end 94.36481 -181.020974)
		(width 0.2286)
		(layer "F.Cu")
		(net "PVDDCR_CPU0_P1_VCC2")
	)
	(segment
		(start 93.081856 -181.300882)
		(end 93.766132 -181.300882)
		(width 0.2286)
		(layer "F.Cu")
		(net "PVDDCR_CPU0_P1_VCC2")
	)
	(via
		(at 91.402916 -179.798472)
		(size 0.6604)
		(drill 0.3302)
		(layers "F.Cu" "B.Cu")
		(net "PVDDCR_CPU0_P1_VCC2")
	)
	(via
		(at 90.947494 -178.988212)
		(size 0.508)
		(drill 0.254)
		(layers "F.Cu" "B.Cu")
		(net "PVDDCR_CPU0_P1_VCC2")
	)
	(via
		(at 94.36481 -181.020974)
		(size 0.508)
		(drill 0.254)
		(layers "F.Cu" "B.Cu")
		(net "PVDDCR_CPU0_P1_VCC2")
	)
	(segment
		(start 90.947494 -179.581302)
		(end 91.164664 -179.798472)
		(width 0.508)
		(layer "B.Cu")
		(net "PVDDCR_CPU0_P1_VCC2")
	)
	(segment
		(start 92.992702 -181.216554)
		(end 93.50248 -181.216554)
		(width 0.381)
		(layer "B.Cu")
		(net "PVDDCR_CPU0_P1_VCC2")
	)
	(segment
		(start 92.992702 -180.256434)
		(end 92.992702 -181.216554)
		(width 0.381)
		(layer "B.Cu")
		(net "PVDDCR_CPU0_P1_VCC2")
	)
	(segment
		(start 91.402916 -179.798472)
		(end 92.53474 -179.798472)
		(width 0.381)
		(layer "B.Cu")
		(net "PVDDCR_CPU0_P1_VCC2")
	)
	(segment
		(start 93.69806 -181.020974)
		(end 94.36481 -181.020974)
		(width 0.381)
		(layer "B.Cu")
		(net "PVDDCR_CPU0_P1_VCC2")
	)
	(segment
		(start 92.53474 -179.798472)
		(end 92.992702 -180.256434)
		(width 0.381)
		(layer "B.Cu")
		(net "PVDDCR_CPU0_P1_VCC2")
	)
	(segment
		(start 91.214448 -179.798472)
		(end 91.402916 -179.798472)
		(width 0.381)
		(layer "B.Cu")
		(net "PVDDCR_CPU0_P1_VCC2")
	)
	(segment
		(start 91.164664 -179.798472)
		(end 91.214448 -179.798472)
		(width 0.508)
		(layer "B.Cu")
		(net "PVDDCR_CPU0_P1_VCC2")
	)
	(segment
		(start 93.50248 -181.216554)
		(end 93.69806 -181.020974)
		(width 0.381)
		(layer "B.Cu")
		(net "PVDDCR_CPU0_P1_VCC2")
	)
	(segment
		(start 90.947494 -178.988212)
		(end 90.947494 -179.581302)
		(width 0.508)
		(layer "B.Cu")
		(net "PVDDCR_CPU0_P1_VCC2")
	)
	(segment
		(start 85.96757 -180.478684)
		(end 85.96757 -181.089046)
		(width 0.381)
		(layer "F.Cu")
		(net "PVDDCR_CPU0_P1_VCC1")
	)
	(segment
		(start 85.335364 -181.368954)
		(end 84.684616 -181.368954)
		(width 0.2286)
		(layer "F.Cu")
		(net "PVDDCR_CPU0_P1_VCC1")
	)
	(segment
		(start 82.474562 -179.843938)
		(end 82.474562 -179.131976)
		(width 0.2286)
		(layer "F.Cu")
		(net "PVDDCR_CPU0_P1_VCC1")
	)
	(segment
		(start 85.615272 -181.089046)
		(end 85.335364 -181.368954)
		(width 0.2286)
		(layer "F.Cu")
		(net "PVDDCR_CPU0_P1_VCC1")
	)
	(segment
		(start 85.96757 -181.089046)
		(end 85.615272 -181.089046)
		(width 0.2286)
		(layer "F.Cu")
		(net "PVDDCR_CPU0_P1_VCC1")
	)
	(segment
		(start 82.474562 -179.131976)
		(end 82.550254 -179.056284)
		(width 0.2286)
		(layer "F.Cu")
		(net "PVDDCR_CPU0_P1_VCC1")
	)
	(via
		(at 82.903822 -179.866544)
		(size 0.6604)
		(drill 0.3302)
		(layers "F.Cu" "B.Cu")
		(net "PVDDCR_CPU0_P1_VCC1")
	)
	(via
		(at 85.96757 -181.089046)
		(size 0.508)
		(drill 0.254)
		(layers "F.Cu" "B.Cu")
		(net "PVDDCR_CPU0_P1_VCC1")
	)
	(via
		(at 82.550254 -179.056284)
		(size 0.508)
		(drill 0.254)
		(layers "F.Cu" "B.Cu")
		(net "PVDDCR_CPU0_P1_VCC1")
	)
	(segment
		(start 85.10524 -181.284626)
		(end 85.30082 -181.089046)
		(width 0.381)
		(layer "B.Cu")
		(net "PVDDCR_CPU0_P1_VCC1")
	)
	(segment
		(start 84.595462 -180.324506)
		(end 84.595462 -181.284626)
		(width 0.381)
		(layer "B.Cu")
		(net "PVDDCR_CPU0_P1_VCC1")
	)
	(segment
		(start 82.903822 -179.866544)
		(end 84.1375 -179.866544)
		(width 0.381)
		(layer "B.Cu")
		(net "PVDDCR_CPU0_P1_VCC1")
	)
	(segment
		(start 82.550254 -179.056284)
		(end 82.550254 -179.649374)
		(width 0.508)
		(layer "B.Cu")
		(net "PVDDCR_CPU0_P1_VCC1")
	)
	(segment
		(start 82.767424 -179.866544)
		(end 82.817208 -179.866544)
		(width 0.508)
		(layer "B.Cu")
		(net "PVDDCR_CPU0_P1_VCC1")
	)
	(segment
		(start 84.1375 -179.866544)
		(end 84.595462 -180.324506)
		(width 0.381)
		(layer "B.Cu")
		(net "PVDDCR_CPU0_P1_VCC1")
	)
	(segment
		(start 84.595462 -181.284626)
		(end 85.10524 -181.284626)
		(width 0.381)
		(layer "B.Cu")
		(net "PVDDCR_CPU0_P1_VCC1")
	)
	(segment
		(start 82.550254 -179.649374)
		(end 82.767424 -179.866544)
		(width 0.508)
		(layer "B.Cu")
		(net "PVDDCR_CPU0_P1_VCC1")
	)
	(segment
		(start 82.817208 -179.866544)
		(end 82.903822 -179.866544)
		(width 0.381)
		(layer "B.Cu")
		(net "PVDDCR_CPU0_P1_VCC1")
	)
	(segment
		(start 85.30082 -181.089046)
		(end 85.96757 -181.089046)
		(width 0.381)
		(layer "B.Cu")
		(net "PVDDCR_CPU0_P1_VCC1")
	)
	(via
		(at 99.708716 -141.498574)
		(size 0.6604)
		(drill 0.3302)
		(layers "F.Cu" "B.Cu")
		(net "PVDDCR_CPU0_P1_VCC")
	)
	(segment
		(start 108.204762 -174.721774)
		(end 108.09605 -174.984156)
		(width 0.2286)
		(layer "F.Cu")
		(net "PVDDCR_CPU0_P1_TEMP0")
	)
	(segment
		(start 99.840542 -179.225194)
		(end 99.71405 -179.530756)
		(width 0.2286)
		(layer "F.Cu")
		(net "PVDDCR_CPU0_P1_TEMP0")
	)
	(segment
		(start 108.417106 -174.50943)
		(end 108.204762 -174.721774)
		(width 0.2286)
		(layer "F.Cu")
		(net "PVDDCR_CPU0_P1_TEMP0")
	)
	(segment
		(start 100.035106 -179.03063)
		(end 99.840542 -179.225194)
		(width 0.2286)
		(layer "F.Cu")
		(net "PVDDCR_CPU0_P1_TEMP0")
	)
	(segment
		(start 66.28765 -165.778688)
		(end 66.423032 -165.45179)
		(width 0.2286)
		(layer "F.Cu")
		(net "PVDDCR_CPU0_P1_TEMP0")
	)
	(segment
		(start 99.71405 -179.530756)
		(end 99.71405 -179.793138)
		(width 0.2286)
		(layer "F.Cu")
		(net "PVDDCR_CPU0_P1_TEMP0")
	)
	(segment
		(start 66.28765 -166.028624)
		(end 66.28765 -165.778688)
		(width 0.2286)
		(layer "F.Cu")
		(net "PVDDCR_CPU0_P1_TEMP0")
	)
	(segment
		(start 83.245706 -178.810412)
		(end 83.245706 -179.08143)
		(width 0.2286)
		(layer "F.Cu")
		(net "PVDDCR_CPU0_P1_TEMP0")
	)
	(segment
		(start 91.32189 -179.52974)
		(end 91.32189 -179.775866)
		(width 0.2286)
		(layer "F.Cu")
		(net "PVDDCR_CPU0_P1_TEMP0")
	)
	(segment
		(start 91.642946 -178.74234)
		(end 91.642946 -179.013358)
		(width 0.2286)
		(layer "F.Cu")
		(net "PVDDCR_CPU0_P1_TEMP0")
	)
	(segment
		(start 108.417106 -174.238412)
		(end 108.417106 -174.50943)
		(width 0.2286)
		(layer "F.Cu")
		(net "PVDDCR_CPU0_P1_TEMP0")
	)
	(segment
		(start 74.922126 -173.692312)
		(end 74.922126 -173.96333)
		(width 0.2286)
		(layer "F.Cu")
		(net "PVDDCR_CPU0_P1_TEMP0")
	)
	(segment
		(start 91.642946 -179.013358)
		(end 91.460066 -179.196238)
		(width 0.2286)
		(layer "F.Cu")
		(net "PVDDCR_CPU0_P1_TEMP0")
	)
	(segment
		(start 108.09605 -174.984156)
		(end 108.09605 -175.271938)
		(width 0.2286)
		(layer "F.Cu")
		(net "PVDDCR_CPU0_P1_TEMP0")
	)
	(segment
		(start 100.035106 -178.759612)
		(end 100.035106 -179.03063)
		(width 0.2286)
		(layer "F.Cu")
		(net "PVDDCR_CPU0_P1_TEMP0")
	)
	(segment
		(start 66.423032 -165.45179)
		(end 66.608706 -165.266116)
		(width 0.2286)
		(layer "F.Cu")
		(net "PVDDCR_CPU0_P1_TEMP0")
	)
	(segment
		(start 83.033362 -179.293774)
		(end 82.92465 -179.556156)
		(width 0.2286)
		(layer "F.Cu")
		(net "PVDDCR_CPU0_P1_TEMP0")
	)
	(segment
		(start 91.460066 -179.196238)
		(end 91.32189 -179.52974)
		(width 0.2286)
		(layer "F.Cu")
		(net "PVDDCR_CPU0_P1_TEMP0")
	)
	(segment
		(start 74.705718 -174.179738)
		(end 74.60107 -174.432214)
		(width 0.2286)
		(layer "F.Cu")
		(net "PVDDCR_CPU0_P1_TEMP0")
	)
	(segment
		(start 82.92465 -179.556156)
		(end 82.92465 -179.843938)
		(width 0.2286)
		(layer "F.Cu")
		(net "PVDDCR_CPU0_P1_TEMP0")
	)
	(segment
		(start 66.608706 -165.266116)
		(end 66.608706 -164.995098)
		(width 0.2286)
		(layer "F.Cu")
		(net "PVDDCR_CPU0_P1_TEMP0")
	)
	(segment
		(start 74.922126 -173.96333)
		(end 74.705718 -174.179738)
		(width 0.2286)
		(layer "F.Cu")
		(net "PVDDCR_CPU0_P1_TEMP0")
	)
	(segment
		(start 74.60107 -174.432214)
		(end 74.60107 -174.725838)
		(width 0.2286)
		(layer "F.Cu")
		(net "PVDDCR_CPU0_P1_TEMP0")
	)
	(segment
		(start 83.245706 -179.08143)
		(end 83.033362 -179.293774)
		(width 0.2286)
		(layer "F.Cu")
		(net "PVDDCR_CPU0_P1_TEMP0")
	)
	(via
		(at 83.245706 -178.810412)
		(size 0.508)
		(drill 0.254)
		(layers "F.Cu" "B.Cu")
		(net "PVDDCR_CPU0_P1_TEMP0")
	)
	(via
		(at 108.417106 -174.238412)
		(size 0.508)
		(drill 0.254)
		(layers "F.Cu" "B.Cu")
		(net "PVDDCR_CPU0_P1_TEMP0")
	)
	(via
		(at 74.922126 -173.692312)
		(size 0.508)
		(drill 0.254)
		(layers "F.Cu" "B.Cu")
		(net "PVDDCR_CPU0_P1_TEMP0")
	)
	(via
		(at 102.837234 -144.103852)
		(size 0.508)
		(drill 0.254)
		(layers "F.Cu" "B.Cu")
		(net "PVDDCR_CPU0_P1_TEMP0")
	)
	(via
		(at 91.642946 -178.74234)
		(size 0.508)
		(drill 0.254)
		(layers "F.Cu" "B.Cu")
		(net "PVDDCR_CPU0_P1_TEMP0")
	)
	(via
		(at 66.608706 -164.995098)
		(size 0.508)
		(drill 0.254)
		(layers "F.Cu" "B.Cu")
		(net "PVDDCR_CPU0_P1_TEMP0")
	)
	(via
		(at 100.035106 -178.759612)
		(size 0.508)
		(drill 0.254)
		(layers "F.Cu" "B.Cu")
		(net "PVDDCR_CPU0_P1_TEMP0")
	)
	(segment
		(start 98.545904 -144.158462)
		(end 99.252278 -144.158462)
		(width 0.1778)
		(layer "B.Cu")
		(net "PVDDCR_CPU0_P1_TEMP0")
	)
	(segment
		(start 99.50577 -144.158462)
		(end 99.939348 -143.724884)
		(width 0.254)
		(layer "B.Cu")
		(net "PVDDCR_CPU0_P1_TEMP0")
	)
	(segment
		(start 100.876354 -143.724884)
		(end 100.985828 -143.61541)
		(width 0.254)
		(layer "B.Cu")
		(net "PVDDCR_CPU0_P1_TEMP0")
	)
	(segment
		(start 99.252278 -144.158462)
		(end 99.50577 -144.158462)
		(width 0.254)
		(layer "B.Cu")
		(net "PVDDCR_CPU0_P1_TEMP0")
	)
	(segment
		(start 100.985828 -143.61541)
		(end 101.47427 -144.103852)
		(width 0.1524)
		(layer "B.Cu")
		(net "PVDDCR_CPU0_P1_TEMP0")
	)
	(segment
		(start 99.939348 -143.724884)
		(end 100.876354 -143.724884)
		(width 0.254)
		(layer "B.Cu")
		(net "PVDDCR_CPU0_P1_TEMP0")
	)
	(segment
		(start 101.47427 -144.103852)
		(end 102.837234 -144.103852)
		(width 0.1524)
		(layer "B.Cu")
		(net "PVDDCR_CPU0_P1_TEMP0")
	)
	(segment
		(start 98.52406 -146.105626)
		(end 98.52406 -144.480026)
		(width 0.254)
		(layer "In2.Cu")
		(net "PVDDCR_CPU0_P1_TEMP0")
	)
	(segment
		(start 103.163878 -149.936708)
		(end 100.555552 -147.328382)
		(width 0.254)
		(layer "In2.Cu")
		(net "PVDDCR_CPU0_P1_TEMP0")
	)
	(segment
		(start 91.642946 -178.74234)
		(end 91.642946 -177.005742)
		(width 0.254)
		(layer "In2.Cu")
		(net "PVDDCR_CPU0_P1_TEMP0")
	)
	(segment
		(start 99.230434 -143.773652)
		(end 100.889054 -143.773652)
		(width 0.254)
		(layer "In2.Cu")
		(net "PVDDCR_CPU0_P1_TEMP0")
	)
	(segment
		(start 66.608706 -164.092382)
		(end 67.476878 -163.22421)
		(width 0.254)
		(layer "In2.Cu")
		(net "PVDDCR_CPU0_P1_TEMP0")
	)
	(segment
		(start 108.015278 -172.13961)
		(end 103.163878 -172.13961)
		(width 0.254)
		(layer "In2.Cu")
		(net "PVDDCR_CPU0_P1_TEMP0")
	)
	(segment
		(start 74.922126 -171.984162)
		(end 75.300078 -171.60621)
		(width 0.254)
		(layer "In2.Cu")
		(net "PVDDCR_CPU0_P1_TEMP0")
	)
	(segment
		(start 101.651054 -143.011652)
		(end 102.903274 -143.011652)
		(width 0.254)
		(layer "In2.Cu")
		(net "PVDDCR_CPU0_P1_TEMP0")
	)
	(segment
		(start 103.163878 -172.13961)
		(end 103.163878 -149.936708)
		(width 0.254)
		(layer "In2.Cu")
		(net "PVDDCR_CPU0_P1_TEMP0")
	)
	(segment
		(start 108.417106 -172.541438)
		(end 108.015278 -172.13961)
		(width 0.254)
		(layer "In2.Cu")
		(net "PVDDCR_CPU0_P1_TEMP0")
	)
	(segment
		(start 91.018614 -176.38141)
		(end 83.859878 -176.38141)
		(width 0.254)
		(layer "In2.Cu")
		(net "PVDDCR_CPU0_P1_TEMP0")
	)
	(segment
		(start 108.417106 -174.238412)
		(end 108.417106 -172.541438)
		(width 0.254)
		(layer "In2.Cu")
		(net "PVDDCR_CPU0_P1_TEMP0")
	)
	(segment
		(start 66.608706 -164.995098)
		(end 66.608706 -164.092382)
		(width 0.254)
		(layer "In2.Cu")
		(net "PVDDCR_CPU0_P1_TEMP0")
	)
	(segment
		(start 99.746816 -147.328382)
		(end 98.52406 -146.105626)
		(width 0.254)
		(layer "In2.Cu")
		(net "PVDDCR_CPU0_P1_TEMP0")
	)
	(segment
		(start 70.042278 -163.22421)
		(end 71.109078 -164.29101)
		(width 0.254)
		(layer "In2.Cu")
		(net "PVDDCR_CPU0_P1_TEMP0")
	)
	(segment
		(start 83.859878 -176.38141)
		(end 83.245706 -176.995582)
		(width 0.254)
		(layer "In2.Cu")
		(net "PVDDCR_CPU0_P1_TEMP0")
	)
	(segment
		(start 67.476878 -163.22421)
		(end 70.042278 -163.22421)
		(width 0.254)
		(layer "In2.Cu")
		(net "PVDDCR_CPU0_P1_TEMP0")
	)
	(segment
		(start 92.165678 -176.48301)
		(end 99.573334 -176.48301)
		(width 0.254)
		(layer "In2.Cu")
		(net "PVDDCR_CPU0_P1_TEMP0")
	)
	(segment
		(start 71.109078 -164.29101)
		(end 71.109078 -168.171114)
		(width 0.254)
		(layer "In2.Cu")
		(net "PVDDCR_CPU0_P1_TEMP0")
	)
	(segment
		(start 102.903274 -143.011652)
		(end 103.126794 -143.235172)
		(width 0.254)
		(layer "In2.Cu")
		(net "PVDDCR_CPU0_P1_TEMP0")
	)
	(segment
		(start 101.055678 -174.24781)
		(end 101.055678 -175.92421)
		(width 0.254)
		(layer "In2.Cu")
		(net "PVDDCR_CPU0_P1_TEMP0")
	)
	(segment
		(start 91.642946 -177.005742)
		(end 92.165678 -176.48301)
		(width 0.254)
		(layer "In2.Cu")
		(net "PVDDCR_CPU0_P1_TEMP0")
	)
	(segment
		(start 77.856334 -171.60621)
		(end 83.245706 -176.995582)
		(width 0.254)
		(layer "In2.Cu")
		(net "PVDDCR_CPU0_P1_TEMP0")
	)
	(segment
		(start 100.035106 -176.944782)
		(end 100.035106 -178.759612)
		(width 0.254)
		(layer "In2.Cu")
		(net "PVDDCR_CPU0_P1_TEMP0")
	)
	(segment
		(start 103.163878 -172.13961)
		(end 101.055678 -174.24781)
		(width 0.254)
		(layer "In2.Cu")
		(net "PVDDCR_CPU0_P1_TEMP0")
	)
	(segment
		(start 99.573334 -176.48301)
		(end 100.035106 -176.944782)
		(width 0.254)
		(layer "In2.Cu")
		(net "PVDDCR_CPU0_P1_TEMP0")
	)
	(segment
		(start 83.245706 -178.810412)
		(end 83.245706 -176.995582)
		(width 0.254)
		(layer "In2.Cu")
		(net "PVDDCR_CPU0_P1_TEMP0")
	)
	(segment
		(start 103.126794 -143.235172)
		(end 103.126794 -143.814292)
		(width 0.254)
		(layer "In2.Cu")
		(net "PVDDCR_CPU0_P1_TEMP0")
	)
	(segment
		(start 91.642946 -177.005742)
		(end 91.018614 -176.38141)
		(width 0.254)
		(layer "In2.Cu")
		(net "PVDDCR_CPU0_P1_TEMP0")
	)
	(segment
		(start 100.555552 -147.328382)
		(end 99.746816 -147.328382)
		(width 0.254)
		(layer "In2.Cu")
		(net "PVDDCR_CPU0_P1_TEMP0")
	)
	(segment
		(start 100.889054 -143.773652)
		(end 101.651054 -143.011652)
		(width 0.254)
		(layer "In2.Cu")
		(net "PVDDCR_CPU0_P1_TEMP0")
	)
	(segment
		(start 98.52406 -144.480026)
		(end 99.230434 -143.773652)
		(width 0.254)
		(layer "In2.Cu")
		(net "PVDDCR_CPU0_P1_TEMP0")
	)
	(segment
		(start 71.109078 -168.171114)
		(end 74.922126 -171.984162)
		(width 0.254)
		(layer "In2.Cu")
		(net "PVDDCR_CPU0_P1_TEMP0")
	)
	(segment
		(start 74.922126 -173.692312)
		(end 74.922126 -171.984162)
		(width 0.254)
		(layer "In2.Cu")
		(net "PVDDCR_CPU0_P1_TEMP0")
	)
	(segment
		(start 103.126794 -143.814292)
		(end 102.837234 -144.103852)
		(width 0.254)
		(layer "In2.Cu")
		(net "PVDDCR_CPU0_P1_TEMP0")
	)
	(segment
		(start 101.055678 -175.92421)
		(end 100.035106 -176.944782)
		(width 0.254)
		(layer "In2.Cu")
		(net "PVDDCR_CPU0_P1_TEMP0")
	)
	(segment
		(start 75.300078 -171.60621)
		(end 77.856334 -171.60621)
		(width 0.254)
		(layer "In2.Cu")
		(net "PVDDCR_CPU0_P1_TEMP0")
	)
	(segment
		(start 91.002866 -144.01546)
		(end 91.2368 -144.01546)
		(width 0.10668)
		(layer "F.Cu")
		(net "PVDDCR_CPU0_P1_RESET_N_R")
	)
	(segment
		(start 90.609928 -143.86941)
		(end 90.856816 -143.86941)
		(width 0.10668)
		(layer "F.Cu")
		(net "PVDDCR_CPU0_P1_RESET_N_R")
	)
	(segment
		(start 90.856816 -143.86941)
		(end 91.002866 -144.01546)
		(width 0.10668)
		(layer "F.Cu")
		(net "PVDDCR_CPU0_P1_RESET_N_R")
	)
	(via
		(at 91.694 -144.47266)
		(size 0.4064)
		(drill 0.2032)
		(layers "F.Cu" "B.Cu")
		(net "PVDDCR_CPU0_P1_RESET_N_R")
	)
	(via
		(at 91.2368 -144.01546)
		(size 0.508)
		(drill 0.254)
		(layers "F.Cu" "B.Cu")
		(net "PVDDCR_CPU0_P1_RESET_N_R")
	)
	(segment
		(start 91.86926 -144.64792)
		(end 92.22486 -144.64792)
		(width 0.10668)
		(layer "B.Cu")
		(net "PVDDCR_CPU0_P1_RESET_N_R")
	)
	(segment
		(start 91.694 -144.47266)
		(end 91.86926 -144.64792)
		(width 0.10668)
		(layer "B.Cu")
		(net "PVDDCR_CPU0_P1_RESET_N_R")
	)
	(segment
		(start 90.609928 -143.86941)
		(end 90.631518 -143.891)
		(width 0.10668)
		(layer "B.Cu")
		(net "PVDDCR_CPU0_P1_RESET_N_R")
	)
	(segment
		(start 90.631518 -143.891)
		(end 91.11234 -143.891)
		(width 0.10668)
		(layer "B.Cu")
		(net "PVDDCR_CPU0_P1_RESET_N_R")
	)
	(segment
		(start 91.2368 -144.01546)
		(end 91.694 -144.47266)
		(width 0.10668)
		(layer "B.Cu")
		(net "PVDDCR_CPU0_P1_RESET_N_R")
	)
	(segment
		(start 92.314268 -144.558512)
		(end 92.795852 -144.558512)
		(width 0.10668)
		(layer "B.Cu")
		(net "PVDDCR_CPU0_P1_RESET_N_R")
	)
	(segment
		(start 92.22486 -144.64792)
		(end 92.314268 -144.558512)
		(width 0.10668)
		(layer "B.Cu")
		(net "PVDDCR_CPU0_P1_RESET_N_R")
	)
	(segment
		(start 91.11234 -143.891)
		(end 91.2368 -144.01546)
		(width 0.10668)
		(layer "B.Cu")
		(net "PVDDCR_CPU0_P1_RESET_N_R")
	)
	(segment
		(start 82.757264 -142.308834)
		(end 82.757264 -141.988286)
		(width 0.10668)
		(layer "F.Cu")
		(net "PVDDCR_CPU0_P1_RESET_N")
	)
	(segment
		(start 82.757264 -141.988286)
		(end 82.03057 -141.261592)
		(width 0.10668)
		(layer "F.Cu")
		(net "PVDDCR_CPU0_P1_RESET_N")
	)
	(via
		(at 82.03057 -141.261592)
		(size 0.508)
		(drill 0.254)
		(layers "F.Cu" "B.Cu")
		(net "PVDDCR_CPU0_P1_RESET_N")
	)
	(via
		(at 88.746838 -143.372586)
		(size 0.508)
		(drill 0.254)
		(layers "F.Cu" "B.Cu")
		(net "PVDDCR_CPU0_P1_RESET_N")
	)
	(segment
		(start 89.45372 -143.372586)
		(end 88.746838 -143.372586)
		(width 0.10668)
		(layer "B.Cu")
		(net "PVDDCR_CPU0_P1_RESET_N")
	)
	(segment
		(start 89.809828 -143.728694)
		(end 89.45372 -143.372586)
		(width 0.10668)
		(layer "B.Cu")
		(net "PVDDCR_CPU0_P1_RESET_N")
	)
	(segment
		(start 89.809828 -143.86941)
		(end 89.809828 -143.728694)
		(width 0.10668)
		(layer "B.Cu")
		(net "PVDDCR_CPU0_P1_RESET_N")
	)
	(segment
		(start 82.03057 -141.261592)
		(end 86.635844 -141.261592)
		(width 0.11684)
		(layer "In2.Cu")
		(net "PVDDCR_CPU0_P1_RESET_N")
	)
	(segment
		(start 86.635844 -141.261592)
		(end 88.746838 -143.372586)
		(width 0.11684)
		(layer "In2.Cu")
		(net "PVDDCR_CPU0_P1_RESET_N")
	)
	(segment
		(start 65.722754 -164.588698)
		(end 65.387474 -164.923978)
		(width 0.1524)
		(layer "F.Cu")
		(net "PVDDCR_CPU0_P1_PWM6")
	)
	(segment
		(start 65.387474 -164.923978)
		(end 65.387474 -166.028624)
		(width 0.1524)
		(layer "F.Cu")
		(net "PVDDCR_CPU0_P1_PWM6")
	)
	(via
		(at 95.885508 -140.765022)
		(size 0.508)
		(drill 0.254)
		(layers "F.Cu" "B.Cu")
		(net "PVDDCR_CPU0_P1_PWM6")
	)
	(via
		(at 65.722754 -164.588698)
		(size 0.508)
		(drill 0.254)
		(layers "F.Cu" "B.Cu")
		(net "PVDDCR_CPU0_P1_PWM6")
	)
	(segment
		(start 95.885508 -140.765022)
		(end 95.47098 -141.17955)
		(width 0.1524)
		(layer "B.Cu")
		(net "PVDDCR_CPU0_P1_PWM6")
	)
	(segment
		(start 95.47098 -141.17955)
		(end 95.47098 -141.883384)
		(width 0.1524)
		(layer "B.Cu")
		(net "PVDDCR_CPU0_P1_PWM6")
	)
	(segment
		(start 88.31326 -141.198346)
		(end 87.802974 -141.708632)
		(width 0.1524)
		(layer "In6.Cu")
		(net "PVDDCR_CPU0_P1_PWM6")
	)
	(segment
		(start 95.903034 -140.747496)
		(end 95.903034 -140.065252)
		(width 0.1524)
		(layer "In6.Cu")
		(net "PVDDCR_CPU0_P1_PWM6")
	)
	(segment
		(start 95.903034 -140.065252)
		(end 93.505274 -137.667492)
		(width 0.1524)
		(layer "In6.Cu")
		(net "PVDDCR_CPU0_P1_PWM6")
	)
	(segment
		(start 65.313814 -163.474146)
		(end 65.313814 -164.179758)
		(width 0.1524)
		(layer "In6.Cu")
		(net "PVDDCR_CPU0_P1_PWM6")
	)
	(segment
		(start 80.678528 -147.754594)
		(end 80.678528 -153.968958)
		(width 0.1524)
		(layer "In6.Cu")
		(net "PVDDCR_CPU0_P1_PWM6")
	)
	(segment
		(start 87.802974 -141.708632)
		(end 85.344254 -141.708632)
		(width 0.1524)
		(layer "In6.Cu")
		(net "PVDDCR_CPU0_P1_PWM6")
	)
	(segment
		(start 95.885508 -140.765022)
		(end 95.903034 -140.747496)
		(width 0.1524)
		(layer "In6.Cu")
		(net "PVDDCR_CPU0_P1_PWM6")
	)
	(segment
		(start 77.767434 -156.880052)
		(end 71.907908 -156.880052)
		(width 0.1524)
		(layer "In6.Cu")
		(net "PVDDCR_CPU0_P1_PWM6")
	)
	(segment
		(start 83.558634 -144.874488)
		(end 80.678528 -147.754594)
		(width 0.1524)
		(layer "In6.Cu")
		(net "PVDDCR_CPU0_P1_PWM6")
	)
	(segment
		(start 71.907908 -156.880052)
		(end 65.313814 -163.474146)
		(width 0.1524)
		(layer "In6.Cu")
		(net "PVDDCR_CPU0_P1_PWM6")
	)
	(segment
		(start 83.558634 -143.494252)
		(end 83.558634 -144.874488)
		(width 0.1524)
		(layer "In6.Cu")
		(net "PVDDCR_CPU0_P1_PWM6")
	)
	(segment
		(start 85.344254 -141.708632)
		(end 83.558634 -143.494252)
		(width 0.1524)
		(layer "In6.Cu")
		(net "PVDDCR_CPU0_P1_PWM6")
	)
	(segment
		(start 88.31326 -139.276074)
		(end 88.31326 -141.198346)
		(width 0.1524)
		(layer "In6.Cu")
		(net "PVDDCR_CPU0_P1_PWM6")
	)
	(segment
		(start 80.678528 -153.968958)
		(end 77.767434 -156.880052)
		(width 0.1524)
		(layer "In6.Cu")
		(net "PVDDCR_CPU0_P1_PWM6")
	)
	(segment
		(start 93.505274 -137.667492)
		(end 89.921842 -137.667492)
		(width 0.1524)
		(layer "In6.Cu")
		(net "PVDDCR_CPU0_P1_PWM6")
	)
	(segment
		(start 89.921842 -137.667492)
		(end 88.31326 -139.276074)
		(width 0.1524)
		(layer "In6.Cu")
		(net "PVDDCR_CPU0_P1_PWM6")
	)
	(segment
		(start 65.313814 -164.179758)
		(end 65.722754 -164.588698)
		(width 0.1524)
		(layer "In6.Cu")
		(net "PVDDCR_CPU0_P1_PWM6")
	)
	(segment
		(start 73.700894 -173.621192)
		(end 74.036174 -173.285912)
		(width 0.1778)
		(layer "F.Cu")
		(net "PVDDCR_CPU0_P1_PWM5")
	)
	(segment
		(start 73.700894 -174.725838)
		(end 73.700894 -173.621192)
		(width 0.1778)
		(layer "F.Cu")
		(net "PVDDCR_CPU0_P1_PWM5")
	)
	(via
		(at 74.036174 -173.285912)
		(size 0.508)
		(drill 0.254)
		(layers "F.Cu" "B.Cu")
		(net "PVDDCR_CPU0_P1_PWM5")
	)
	(via
		(at 95.35414 -140.272516)
		(size 0.508)
		(drill 0.254)
		(layers "F.Cu" "B.Cu")
		(net "PVDDCR_CPU0_P1_PWM5")
	)
	(segment
		(start 95.35414 -140.272516)
		(end 95.07093 -140.555726)
		(width 0.1524)
		(layer "B.Cu")
		(net "PVDDCR_CPU0_P1_PWM5")
	)
	(segment
		(start 95.07093 -140.555726)
		(end 95.07093 -141.883384)
		(width 0.1524)
		(layer "B.Cu")
		(net "PVDDCR_CPU0_P1_PWM5")
	)
	(segment
		(start 79.189834 -156.765498)
		(end 82.334862 -153.62047)
		(width 0.1524)
		(layer "In6.Cu")
		(net "PVDDCR_CPU0_P1_PWM5")
	)
	(segment
		(start 89.961974 -140.96238)
		(end 92.825062 -138.099292)
		(width 0.1524)
		(layer "In6.Cu")
		(net "PVDDCR_CPU0_P1_PWM5")
	)
	(segment
		(start 92.825062 -138.099292)
		(end 93.180916 -138.099292)
		(width 0.1524)
		(layer "In6.Cu")
		(net "PVDDCR_CPU0_P1_PWM5")
	)
	(segment
		(start 73.712832 -171.923456)
		(end 79.189834 -166.446454)
		(width 0.1524)
		(layer "In6.Cu")
		(net "PVDDCR_CPU0_P1_PWM5")
	)
	(segment
		(start 79.189834 -166.446454)
		(end 79.189834 -156.765498)
		(width 0.1524)
		(layer "In6.Cu")
		(net "PVDDCR_CPU0_P1_PWM5")
	)
	(segment
		(start 89.961974 -150.156926)
		(end 89.961974 -140.96238)
		(width 0.1524)
		(layer "In6.Cu")
		(net "PVDDCR_CPU0_P1_PWM5")
	)
	(segment
		(start 83.85175 -150.954232)
		(end 89.164668 -150.954232)
		(width 0.1524)
		(layer "In6.Cu")
		(net "PVDDCR_CPU0_P1_PWM5")
	)
	(segment
		(start 93.180916 -138.099292)
		(end 95.35414 -140.272516)
		(width 0.1524)
		(layer "In6.Cu")
		(net "PVDDCR_CPU0_P1_PWM5")
	)
	(segment
		(start 82.334862 -153.62047)
		(end 82.334862 -152.47112)
		(width 0.1524)
		(layer "In6.Cu")
		(net "PVDDCR_CPU0_P1_PWM5")
	)
	(segment
		(start 89.164668 -150.954232)
		(end 89.961974 -150.156926)
		(width 0.1524)
		(layer "In6.Cu")
		(net "PVDDCR_CPU0_P1_PWM5")
	)
	(segment
		(start 82.334862 -152.47112)
		(end 83.85175 -150.954232)
		(width 0.1524)
		(layer "In6.Cu")
		(net "PVDDCR_CPU0_P1_PWM5")
	)
	(segment
		(start 74.036174 -173.285912)
		(end 73.712832 -172.96257)
		(width 0.1524)
		(layer "In6.Cu")
		(net "PVDDCR_CPU0_P1_PWM5")
	)
	(segment
		(start 73.712832 -172.96257)
		(end 73.712832 -171.923456)
		(width 0.1524)
		(layer "In6.Cu")
		(net "PVDDCR_CPU0_P1_PWM5")
	)
	(segment
		(start 107.195874 -175.271938)
		(end 107.195874 -174.167292)
		(width 0.2032)
		(layer "F.Cu")
		(net "PVDDCR_CPU0_P1_PWM4")
	)
	(segment
		(start 107.195874 -174.167292)
		(end 107.531154 -173.832012)
		(width 0.1778)
		(layer "F.Cu")
		(net "PVDDCR_CPU0_P1_PWM4")
	)
	(via
		(at 107.531154 -173.832012)
		(size 0.508)
		(drill 0.254)
		(layers "F.Cu" "B.Cu")
		(net "PVDDCR_CPU0_P1_PWM4")
	)
	(via
		(at 94.480634 -140.497052)
		(size 0.508)
		(drill 0.254)
		(layers "F.Cu" "B.Cu")
		(net "PVDDCR_CPU0_P1_PWM4")
	)
	(segment
		(start 94.67088 -140.687298)
		(end 94.67088 -141.883384)
		(width 0.1524)
		(layer "B.Cu")
		(net "PVDDCR_CPU0_P1_PWM4")
	)
	(segment
		(start 94.480634 -140.497052)
		(end 94.67088 -140.687298)
		(width 0.1524)
		(layer "B.Cu")
		(net "PVDDCR_CPU0_P1_PWM4")
	)
	(segment
		(start 103.192834 -169.493692)
		(end 107.531154 -173.832012)
		(width 0.1524)
		(layer "In6.Cu")
		(net "PVDDCR_CPU0_P1_PWM4")
	)
	(segment
		(start 98.773234 -147.6629)
		(end 103.192834 -152.0825)
		(width 0.1524)
		(layer "In6.Cu")
		(net "PVDDCR_CPU0_P1_PWM4")
	)
	(segment
		(start 95.471234 -141.487652)
		(end 97.325434 -141.487652)
		(width 0.1524)
		(layer "In6.Cu")
		(net "PVDDCR_CPU0_P1_PWM4")
	)
	(segment
		(start 103.192834 -152.0825)
		(end 103.192834 -169.493692)
		(width 0.1524)
		(layer "In6.Cu")
		(net "PVDDCR_CPU0_P1_PWM4")
	)
	(segment
		(start 94.480634 -140.497052)
		(end 95.471234 -141.487652)
		(width 0.1524)
		(layer "In6.Cu")
		(net "PVDDCR_CPU0_P1_PWM4")
	)
	(segment
		(start 98.773234 -142.935452)
		(end 98.773234 -147.6629)
		(width 0.1524)
		(layer "In6.Cu")
		(net "PVDDCR_CPU0_P1_PWM4")
	)
	(segment
		(start 97.325434 -141.487652)
		(end 98.773234 -142.935452)
		(width 0.1524)
		(layer "In6.Cu")
		(net "PVDDCR_CPU0_P1_PWM4")
	)
	(segment
		(start 98.813874 -179.793138)
		(end 98.813874 -178.688492)
		(width 0.1778)
		(layer "F.Cu")
		(net "PVDDCR_CPU0_P1_PWM3")
	)
	(segment
		(start 98.813874 -178.688492)
		(end 99.149154 -178.353212)
		(width 0.1778)
		(layer "F.Cu")
		(net "PVDDCR_CPU0_P1_PWM3")
	)
	(via
		(at 94.048834 -140.979652)
		(size 0.508)
		(drill 0.254)
		(layers "F.Cu" "B.Cu")
		(net "PVDDCR_CPU0_P1_PWM3")
	)
	(via
		(at 99.149154 -178.353212)
		(size 0.508)
		(drill 0.254)
		(layers "F.Cu" "B.Cu")
		(net "PVDDCR_CPU0_P1_PWM3")
	)
	(segment
		(start 94.048834 -140.979652)
		(end 94.27083 -141.201648)
		(width 0.1524)
		(layer "B.Cu")
		(net "PVDDCR_CPU0_P1_PWM3")
	)
	(segment
		(start 94.27083 -141.201648)
		(end 94.27083 -141.883384)
		(width 0.1524)
		(layer "B.Cu")
		(net "PVDDCR_CPU0_P1_PWM3")
	)
	(segment
		(start 98.825812 -178.02987)
		(end 98.825812 -176.311052)
		(width 0.1524)
		(layer "In6.Cu")
		(net "PVDDCR_CPU0_P1_PWM3")
	)
	(segment
		(start 97.34804 -148.518118)
		(end 96.548194 -147.718272)
		(width 0.1524)
		(layer "In6.Cu")
		(net "PVDDCR_CPU0_P1_PWM3")
	)
	(segment
		(start 95.191834 -142.122652)
		(end 94.048834 -140.979652)
		(width 0.1524)
		(layer "In6.Cu")
		(net "PVDDCR_CPU0_P1_PWM3")
	)
	(segment
		(start 98.825812 -176.311052)
		(end 97.706434 -175.191674)
		(width 0.1524)
		(layer "In6.Cu")
		(net "PVDDCR_CPU0_P1_PWM3")
	)
	(segment
		(start 96.548194 -147.718272)
		(end 96.548194 -142.691358)
		(width 0.1524)
		(layer "In6.Cu")
		(net "PVDDCR_CPU0_P1_PWM3")
	)
	(segment
		(start 97.34804 -154.083258)
		(end 97.34804 -148.518118)
		(width 0.1524)
		(layer "In6.Cu")
		(net "PVDDCR_CPU0_P1_PWM3")
	)
	(segment
		(start 97.706434 -175.191674)
		(end 97.706434 -154.441652)
		(width 0.1524)
		(layer "In6.Cu")
		(net "PVDDCR_CPU0_P1_PWM3")
	)
	(segment
		(start 99.149154 -178.353212)
		(end 98.825812 -178.02987)
		(width 0.1524)
		(layer "In6.Cu")
		(net "PVDDCR_CPU0_P1_PWM3")
	)
	(segment
		(start 95.979488 -142.122652)
		(end 95.191834 -142.122652)
		(width 0.1524)
		(layer "In6.Cu")
		(net "PVDDCR_CPU0_P1_PWM3")
	)
	(segment
		(start 96.548194 -142.691358)
		(end 95.979488 -142.122652)
		(width 0.1524)
		(layer "In6.Cu")
		(net "PVDDCR_CPU0_P1_PWM3")
	)
	(segment
		(start 97.706434 -154.441652)
		(end 97.34804 -154.083258)
		(width 0.1524)
		(layer "In6.Cu")
		(net "PVDDCR_CPU0_P1_PWM3")
	)
	(segment
		(start 90.421714 -179.775866)
		(end 90.421714 -178.67122)
		(width 0.1778)
		(layer "F.Cu")
		(net "PVDDCR_CPU0_P1_PWM2")
	)
	(segment
		(start 90.421714 -178.67122)
		(end 90.756994 -178.33594)
		(width 0.1778)
		(layer "F.Cu")
		(net "PVDDCR_CPU0_P1_PWM2")
	)
	(via
		(at 90.756994 -178.33594)
		(size 0.508)
		(drill 0.254)
		(layers "F.Cu" "B.Cu")
		(net "PVDDCR_CPU0_P1_PWM2")
	)
	(via
		(at 93.566234 -140.471652)
		(size 0.508)
		(drill 0.254)
		(layers "F.Cu" "B.Cu")
		(net "PVDDCR_CPU0_P1_PWM2")
	)
	(segment
		(start 93.87078 -141.563344)
		(end 93.87078 -141.883384)
		(width 0.1524)
		(layer "B.Cu")
		(net "PVDDCR_CPU0_P1_PWM2")
	)
	(segment
		(start 93.566234 -140.471652)
		(end 93.566234 -141.258798)
		(width 0.1524)
		(layer "B.Cu")
		(net "PVDDCR_CPU0_P1_PWM2")
	)
	(segment
		(start 93.566234 -141.258798)
		(end 93.87078 -141.563344)
		(width 0.1524)
		(layer "B.Cu")
		(net "PVDDCR_CPU0_P1_PWM2")
	)
	(segment
		(start 93.083634 -147.43684)
		(end 94.521274 -148.87448)
		(width 0.1524)
		(layer "In6.Cu")
		(net "PVDDCR_CPU0_P1_PWM2")
	)
	(segment
		(start 94.521274 -149.72665)
		(end 93.932756 -150.315168)
		(width 0.1524)
		(layer "In6.Cu")
		(net "PVDDCR_CPU0_P1_PWM2")
	)
	(segment
		(start 93.932756 -151.359616)
		(end 95.655638 -153.082498)
		(width 0.1524)
		(layer "In6.Cu")
		(net "PVDDCR_CPU0_P1_PWM2")
	)
	(segment
		(start 93.566234 -140.471652)
		(end 93.083634 -140.954252)
		(width 0.1524)
		(layer "In6.Cu")
		(net "PVDDCR_CPU0_P1_PWM2")
	)
	(segment
		(start 93.932756 -150.315168)
		(end 93.932756 -151.359616)
		(width 0.1524)
		(layer "In6.Cu")
		(net "PVDDCR_CPU0_P1_PWM2")
	)
	(segment
		(start 94.521274 -148.87448)
		(end 94.521274 -149.72665)
		(width 0.1524)
		(layer "In6.Cu")
		(net "PVDDCR_CPU0_P1_PWM2")
	)
	(segment
		(start 90.433652 -176.243234)
		(end 90.433652 -178.012598)
		(width 0.1524)
		(layer "In6.Cu")
		(net "PVDDCR_CPU0_P1_PWM2")
	)
	(segment
		(start 95.655638 -153.082498)
		(end 95.655638 -171.021248)
		(width 0.1524)
		(layer "In6.Cu")
		(net "PVDDCR_CPU0_P1_PWM2")
	)
	(segment
		(start 95.655638 -171.021248)
		(end 90.433652 -176.243234)
		(width 0.1524)
		(layer "In6.Cu")
		(net "PVDDCR_CPU0_P1_PWM2")
	)
	(segment
		(start 90.433652 -178.012598)
		(end 90.756994 -178.33594)
		(width 0.1524)
		(layer "In6.Cu")
		(net "PVDDCR_CPU0_P1_PWM2")
	)
	(segment
		(start 93.083634 -140.954252)
		(end 93.083634 -147.43684)
		(width 0.1524)
		(layer "In6.Cu")
		(net "PVDDCR_CPU0_P1_PWM2")
	)
	(segment
		(start 82.024474 -178.739292)
		(end 82.359754 -178.404012)
		(width 0.1524)
		(layer "F.Cu")
		(net "PVDDCR_CPU0_P1_PWM1")
	)
	(segment
		(start 82.024474 -179.843938)
		(end 82.024474 -178.739292)
		(width 0.1524)
		(layer "F.Cu")
		(net "PVDDCR_CPU0_P1_PWM1")
	)
	(via
		(at 82.359754 -178.404012)
		(size 0.508)
		(drill 0.254)
		(layers "F.Cu" "B.Cu")
		(net "PVDDCR_CPU0_P1_PWM1")
	)
	(via
		(at 92.728034 -139.963652)
		(size 0.762)
		(drill 0.254)
		(layers "F.Cu" "B.Cu")
		(net "PVDDCR_CPU0_P1_PWM1")
	)
	(segment
		(start 93.037914 -140.273532)
		(end 92.728034 -139.963652)
		(width 0.1524)
		(layer "B.Cu")
		(net "PVDDCR_CPU0_P1_PWM1")
	)
	(segment
		(start 93.037914 -141.187932)
		(end 93.037914 -140.273532)
		(width 0.1524)
		(layer "B.Cu")
		(net "PVDDCR_CPU0_P1_PWM1")
	)
	(segment
		(start 93.470984 -141.883384)
		(end 93.470984 -141.621002)
		(width 0.1524)
		(layer "B.Cu")
		(net "PVDDCR_CPU0_P1_PWM1")
	)
	(segment
		(start 93.470984 -141.621002)
		(end 93.037914 -141.187932)
		(width 0.1524)
		(layer "B.Cu")
		(net "PVDDCR_CPU0_P1_PWM1")
	)
	(segment
		(start 82.771742 -152.666192)
		(end 82.771742 -153.896314)
		(width 0.1524)
		(layer "In6.Cu")
		(net "PVDDCR_CPU0_P1_PWM1")
	)
	(segment
		(start 84.008468 -151.429466)
		(end 82.771742 -152.666192)
		(width 0.1524)
		(layer "In6.Cu")
		(net "PVDDCR_CPU0_P1_PWM1")
	)
	(segment
		(start 92.728034 -139.963652)
		(end 90.508074 -142.183612)
		(width 0.1524)
		(layer "In6.Cu")
		(net "PVDDCR_CPU0_P1_PWM1")
	)
	(segment
		(start 82.771742 -153.896314)
		(end 80.332834 -156.335222)
		(width 0.1524)
		(layer "In6.Cu")
		(net "PVDDCR_CPU0_P1_PWM1")
	)
	(segment
		(start 90.508074 -142.183612)
		(end 90.508074 -150.631652)
		(width 0.1524)
		(layer "In6.Cu")
		(net "PVDDCR_CPU0_P1_PWM1")
	)
	(segment
		(start 90.508074 -150.631652)
		(end 89.71026 -151.429466)
		(width 0.1524)
		(layer "In6.Cu")
		(net "PVDDCR_CPU0_P1_PWM1")
	)
	(segment
		(start 81.856834 -177.901092)
		(end 82.359754 -178.404012)
		(width 0.1524)
		(layer "In6.Cu")
		(net "PVDDCR_CPU0_P1_PWM1")
	)
	(segment
		(start 89.71026 -151.429466)
		(end 84.008468 -151.429466)
		(width 0.1524)
		(layer "In6.Cu")
		(net "PVDDCR_CPU0_P1_PWM1")
	)
	(segment
		(start 80.332834 -156.335222)
		(end 80.332834 -171.104052)
		(width 0.1524)
		(layer "In6.Cu")
		(net "PVDDCR_CPU0_P1_PWM1")
	)
	(segment
		(start 80.332834 -171.104052)
		(end 81.856834 -172.628052)
		(width 0.1524)
		(layer "In6.Cu")
		(net "PVDDCR_CPU0_P1_PWM1")
	)
	(segment
		(start 81.856834 -172.628052)
		(end 81.856834 -177.901092)
		(width 0.1524)
		(layer "In6.Cu")
		(net "PVDDCR_CPU0_P1_PWM1")
	)
	(segment
		(start 118.621048 -170.998388)
		(end 118.085616 -170.998388)
		(width 0.2286)
		(layer "F.Cu")
		(net "PVDDCR_CPU0_P1_PVCC")
	)
	(segment
		(start 135.359902 -155.605988)
		(end 134.824216 -155.605988)
		(width 0.2286)
		(layer "F.Cu")
		(net "PVDDCR_CPU0_P1_PVCC")
	)
	(segment
		(start 77.423518 -177.227484)
		(end 76.896722 -176.700688)
		(width 0.2286)
		(layer "F.Cu")
		(net "PVDDCR_CPU0_P1_PVCC")
	)
	(segment
		(start 126.366016 -164.267388)
		(end 126.901702 -164.267388)
		(width 0.2286)
		(layer "F.Cu")
		(net "PVDDCR_CPU0_P1_PVCC")
	)
	(segment
		(start 110.918498 -177.773584)
		(end 111.13897 -177.773584)
		(width 0.2286)
		(layer "F.Cu")
		(net "PVDDCR_CPU0_P1_PVCC")
	)
	(segment
		(start 102.75697 -181.68366)
		(end 102.75697 -182.294784)
		(width 0.381)
		(layer "F.Cu")
		(net "PVDDCR_CPU0_P1_PVCC")
	)
	(segment
		(start 136.10717 -155.52166)
		(end 136.10717 -156.132784)
		(width 0.254)
		(layer "F.Cu")
		(net "PVDDCR_CPU0_P1_PVCC")
	)
	(segment
		(start 119.36857 -170.91406)
		(end 119.36857 -171.525184)
		(width 0.381)
		(layer "F.Cu")
		(net "PVDDCR_CPU0_P1_PVCC")
	)
	(segment
		(start 68.583302 -168.003474)
		(end 69.110098 -168.53027)
		(width 0.2286)
		(layer "F.Cu")
		(net "PVDDCR_CPU0_P1_PVCC")
	)
	(segment
		(start 77.64399 -176.61636)
		(end 77.64399 -177.227484)
		(width 0.381)
		(layer "F.Cu")
		(net "PVDDCR_CPU0_P1_PVCC")
	)
	(segment
		(start 135.886698 -156.132784)
		(end 135.359902 -155.605988)
		(width 0.2286)
		(layer "F.Cu")
		(net "PVDDCR_CPU0_P1_PVCC")
	)
	(segment
		(start 127.428498 -164.794184)
		(end 127.64897 -164.794184)
		(width 0.2286)
		(layer "F.Cu")
		(net "PVDDCR_CPU0_P1_PVCC")
	)
	(segment
		(start 119.148098 -171.525184)
		(end 118.626382 -171.003468)
		(width 0.2286)
		(layer "F.Cu")
		(net "PVDDCR_CPU0_P1_PVCC")
	)
	(segment
		(start 110.391702 -177.246788)
		(end 110.918498 -177.773584)
		(width 0.2286)
		(layer "F.Cu")
		(net "PVDDCR_CPU0_P1_PVCC")
	)
	(segment
		(start 136.10717 -156.132784)
		(end 135.886698 -156.132784)
		(width 0.2286)
		(layer "F.Cu")
		(net "PVDDCR_CPU0_P1_PVCC")
	)
	(segment
		(start 94.36481 -181.666388)
		(end 94.36481 -182.277512)
		(width 0.381)
		(layer "F.Cu")
		(net "PVDDCR_CPU0_P1_PVCC")
	)
	(segment
		(start 111.13897 -177.773584)
		(end 111.13897 -177.16246)
		(width 0.381)
		(layer "F.Cu")
		(net "PVDDCR_CPU0_P1_PVCC")
	)
	(segment
		(start 118.626382 -171.003468)
		(end 118.626128 -171.003468)
		(width 0.2286)
		(layer "F.Cu")
		(net "PVDDCR_CPU0_P1_PVCC")
	)
	(segment
		(start 85.220302 -181.818788)
		(end 84.684616 -181.818788)
		(width 0.2286)
		(layer "F.Cu")
		(net "PVDDCR_CPU0_P1_PVCC")
	)
	(segment
		(start 94.36481 -182.277512)
		(end 94.144338 -182.277512)
		(width 0.2286)
		(layer "F.Cu")
		(net "PVDDCR_CPU0_P1_PVCC")
	)
	(segment
		(start 93.617542 -181.750716)
		(end 93.081856 -181.750716)
		(width 0.2286)
		(layer "F.Cu")
		(net "PVDDCR_CPU0_P1_PVCC")
	)
	(segment
		(start 68.047616 -168.003474)
		(end 68.583302 -168.003474)
		(width 0.2286)
		(layer "F.Cu")
		(net "PVDDCR_CPU0_P1_PVCC")
	)
	(segment
		(start 102.009702 -181.767988)
		(end 101.474016 -181.767988)
		(width 0.2286)
		(layer "F.Cu")
		(net "PVDDCR_CPU0_P1_PVCC")
	)
	(segment
		(start 77.64399 -177.227484)
		(end 77.423518 -177.227484)
		(width 0.2286)
		(layer "F.Cu")
		(net "PVDDCR_CPU0_P1_PVCC")
	)
	(segment
		(start 85.96757 -182.345584)
		(end 85.747098 -182.345584)
		(width 0.2286)
		(layer "F.Cu")
		(net "PVDDCR_CPU0_P1_PVCC")
	)
	(segment
		(start 102.536498 -182.294784)
		(end 102.009702 -181.767988)
		(width 0.2286)
		(layer "F.Cu")
		(net "PVDDCR_CPU0_P1_PVCC")
	)
	(segment
		(start 102.75697 -182.294784)
		(end 102.536498 -182.294784)
		(width 0.2286)
		(layer "F.Cu")
		(net "PVDDCR_CPU0_P1_PVCC")
	)
	(segment
		(start 69.33057 -168.53027)
		(end 69.33057 -167.919146)
		(width 0.381)
		(layer "F.Cu")
		(net "PVDDCR_CPU0_P1_PVCC")
	)
	(segment
		(start 76.896722 -176.700688)
		(end 76.361036 -176.700688)
		(width 0.2286)
		(layer "F.Cu")
		(net "PVDDCR_CPU0_P1_PVCC")
	)
	(segment
		(start 119.36857 -171.525184)
		(end 119.148098 -171.525184)
		(width 0.2286)
		(layer "F.Cu")
		(net "PVDDCR_CPU0_P1_PVCC")
	)
	(segment
		(start 126.901702 -164.267388)
		(end 127.428498 -164.794184)
		(width 0.2286)
		(layer "F.Cu")
		(net "PVDDCR_CPU0_P1_PVCC")
	)
	(segment
		(start 109.856016 -177.246788)
		(end 110.391702 -177.246788)
		(width 0.2286)
		(layer "F.Cu")
		(net "PVDDCR_CPU0_P1_PVCC")
	)
	(segment
		(start 69.110098 -168.53027)
		(end 69.33057 -168.53027)
		(width 0.2286)
		(layer "F.Cu")
		(net "PVDDCR_CPU0_P1_PVCC")
	)
	(segment
		(start 85.96757 -181.73446)
		(end 85.96757 -182.345584)
		(width 0.381)
		(layer "F.Cu")
		(net "PVDDCR_CPU0_P1_PVCC")
	)
	(segment
		(start 127.64897 -164.794184)
		(end 127.64897 -164.18306)
		(width 0.381)
		(layer "F.Cu")
		(net "PVDDCR_CPU0_P1_PVCC")
	)
	(segment
		(start 94.144338 -182.277512)
		(end 93.617542 -181.750716)
		(width 0.2286)
		(layer "F.Cu")
		(net "PVDDCR_CPU0_P1_PVCC")
	)
	(segment
		(start 85.747098 -182.345584)
		(end 85.220302 -181.818788)
		(width 0.2286)
		(layer "F.Cu")
		(net "PVDDCR_CPU0_P1_PVCC")
	)
	(segment
		(start 118.626128 -171.003468)
		(end 118.621048 -170.998388)
		(width 0.2286)
		(layer "F.Cu")
		(net "PVDDCR_CPU0_P1_PVCC")
	)
	(via
		(at 69.33057 -167.919146)
		(size 0.508)
		(drill 0.254)
		(layers "F.Cu" "B.Cu")
		(net "PVDDCR_CPU0_P1_PVCC")
	)
	(via
		(at 136.10717 -155.52166)
		(size 0.508)
		(drill 0.254)
		(layers "F.Cu" "B.Cu")
		(net "PVDDCR_CPU0_P1_PVCC")
	)
	(via
		(at 137.350754 -153.263092)
		(size 0.762)
		(drill 0.381)
		(layers "F.Cu" "B.Cu")
		(net "PVDDCR_CPU0_P1_PVCC")
	)
	(via
		(at 111.13897 -177.16246)
		(size 0.508)
		(drill 0.254)
		(layers "F.Cu" "B.Cu")
		(net "PVDDCR_CPU0_P1_PVCC")
	)
	(via
		(at 119.36857 -170.91406)
		(size 0.508)
		(drill 0.254)
		(layers "F.Cu" "B.Cu")
		(net "PVDDCR_CPU0_P1_PVCC")
	)
	(via
		(at 102.75697 -181.68366)
		(size 0.508)
		(drill 0.254)
		(layers "F.Cu" "B.Cu")
		(net "PVDDCR_CPU0_P1_PVCC")
	)
	(via
		(at 77.64399 -176.61636)
		(size 0.508)
		(drill 0.254)
		(layers "F.Cu" "B.Cu")
		(net "PVDDCR_CPU0_P1_PVCC")
	)
	(via
		(at 137.072878 -154.345132)
		(size 0.508)
		(drill 0.254)
		(layers "F.Cu" "B.Cu")
		(net "PVDDCR_CPU0_P1_PVCC")
	)
	(via
		(at 94.36481 -181.666388)
		(size 0.508)
		(drill 0.254)
		(layers "F.Cu" "B.Cu")
		(net "PVDDCR_CPU0_P1_PVCC")
	)
	(via
		(at 85.96757 -181.73446)
		(size 0.508)
		(drill 0.254)
		(layers "F.Cu" "B.Cu")
		(net "PVDDCR_CPU0_P1_PVCC")
	)
	(via
		(at 127.64897 -164.18306)
		(size 0.508)
		(drill 0.254)
		(layers "F.Cu" "B.Cu")
		(net "PVDDCR_CPU0_P1_PVCC")
	)
	(segment
		(start 69.30898 -167.919146)
		(end 69.33057 -167.919146)
		(width 0.381)
		(layer "B.Cu")
		(net "PVDDCR_CPU0_P1_PVCC")
	)
	(segment
		(start 127.62738 -164.18306)
		(end 127.64897 -164.18306)
		(width 0.381)
		(layer "B.Cu")
		(net "PVDDCR_CPU0_P1_PVCC")
	)
	(segment
		(start 93.992954 -182.016654)
		(end 94.34322 -181.666388)
		(width 0.381)
		(layer "B.Cu")
		(net "PVDDCR_CPU0_P1_PVCC")
	)
	(segment
		(start 111.11738 -177.16246)
		(end 111.13897 -177.16246)
		(width 0.381)
		(layer "B.Cu")
		(net "PVDDCR_CPU0_P1_PVCC")
	)
	(segment
		(start 109.766862 -177.512726)
		(end 110.767114 -177.512726)
		(width 0.381)
		(layer "B.Cu")
		(net "PVDDCR_CPU0_P1_PVCC")
	)
	(segment
		(start 110.767114 -177.512726)
		(end 111.11738 -177.16246)
		(width 0.381)
		(layer "B.Cu")
		(net "PVDDCR_CPU0_P1_PVCC")
	)
	(segment
		(start 76.271882 -176.966626)
		(end 77.293724 -176.966626)
		(width 0.381)
		(layer "B.Cu")
		(net "PVDDCR_CPU0_P1_PVCC")
	)
	(segment
		(start 85.94598 -181.73446)
		(end 85.96757 -181.73446)
		(width 0.381)
		(layer "B.Cu")
		(net "PVDDCR_CPU0_P1_PVCC")
	)
	(segment
		(start 85.595714 -182.084726)
		(end 85.94598 -181.73446)
		(width 0.381)
		(layer "B.Cu")
		(net "PVDDCR_CPU0_P1_PVCC")
	)
	(segment
		(start 134.735062 -155.871926)
		(end 135.735314 -155.871926)
		(width 0.381)
		(layer "B.Cu")
		(net "PVDDCR_CPU0_P1_PVCC")
	)
	(segment
		(start 126.276862 -164.533326)
		(end 127.277114 -164.533326)
		(width 0.381)
		(layer "B.Cu")
		(net "PVDDCR_CPU0_P1_PVCC")
	)
	(segment
		(start 102.385114 -182.033926)
		(end 102.73538 -181.68366)
		(width 0.381)
		(layer "B.Cu")
		(net "PVDDCR_CPU0_P1_PVCC")
	)
	(segment
		(start 117.996462 -171.264326)
		(end 118.996714 -171.264326)
		(width 0.381)
		(layer "B.Cu")
		(net "PVDDCR_CPU0_P1_PVCC")
	)
	(segment
		(start 92.992702 -182.016654)
		(end 93.992954 -182.016654)
		(width 0.381)
		(layer "B.Cu")
		(net "PVDDCR_CPU0_P1_PVCC")
	)
	(segment
		(start 135.735314 -155.871926)
		(end 136.08558 -155.52166)
		(width 0.381)
		(layer "B.Cu")
		(net "PVDDCR_CPU0_P1_PVCC")
	)
	(segment
		(start 119.34698 -170.91406)
		(end 119.36857 -170.91406)
		(width 0.381)
		(layer "B.Cu")
		(net "PVDDCR_CPU0_P1_PVCC")
	)
	(segment
		(start 94.34322 -181.666388)
		(end 94.36481 -181.666388)
		(width 0.381)
		(layer "B.Cu")
		(net "PVDDCR_CPU0_P1_PVCC")
	)
	(segment
		(start 67.958462 -168.269412)
		(end 68.958714 -168.269412)
		(width 0.381)
		(layer "B.Cu")
		(net "PVDDCR_CPU0_P1_PVCC")
	)
	(segment
		(start 136.08558 -155.52166)
		(end 136.10717 -155.52166)
		(width 0.381)
		(layer "B.Cu")
		(net "PVDDCR_CPU0_P1_PVCC")
	)
	(segment
		(start 118.996714 -171.264326)
		(end 119.34698 -170.91406)
		(width 0.381)
		(layer "B.Cu")
		(net "PVDDCR_CPU0_P1_PVCC")
	)
	(segment
		(start 127.277114 -164.533326)
		(end 127.62738 -164.18306)
		(width 0.381)
		(layer "B.Cu")
		(net "PVDDCR_CPU0_P1_PVCC")
	)
	(segment
		(start 102.73538 -181.68366)
		(end 102.75697 -181.68366)
		(width 0.381)
		(layer "B.Cu")
		(net "PVDDCR_CPU0_P1_PVCC")
	)
	(segment
		(start 68.958714 -168.269412)
		(end 69.30898 -167.919146)
		(width 0.381)
		(layer "B.Cu")
		(net "PVDDCR_CPU0_P1_PVCC")
	)
	(segment
		(start 84.595462 -182.084726)
		(end 85.595714 -182.084726)
		(width 0.381)
		(layer "B.Cu")
		(net "PVDDCR_CPU0_P1_PVCC")
	)
	(segment
		(start 101.384862 -182.033926)
		(end 102.385114 -182.033926)
		(width 0.381)
		(layer "B.Cu")
		(net "PVDDCR_CPU0_P1_PVCC")
	)
	(segment
		(start 77.293724 -176.966626)
		(end 77.64399 -176.61636)
		(width 0.381)
		(layer "B.Cu")
		(net "PVDDCR_CPU0_P1_PVCC")
	)
	(segment
		(start 120.435878 -172.673264)
		(end 119.36857 -171.605956)
		(width 0.508)
		(layer "In6.Cu")
		(net "PVDDCR_CPU0_P1_PVCC")
	)
	(segment
		(start 111.34217 -184.67451)
		(end 108.58627 -187.43041)
		(width 0.508)
		(layer "In6.Cu")
		(net "PVDDCR_CPU0_P1_PVCC")
	)
	(segment
		(start 77.64399 -176.61636)
		(end 77.793088 -176.765458)
		(width 0.508)
		(layer "In6.Cu")
		(net "PVDDCR_CPU0_P1_PVCC")
	)
	(segment
		(start 103.417878 -182.858664)
		(end 102.75697 -182.197756)
		(width 0.508)
		(layer "In6.Cu")
		(net "PVDDCR_CPU0_P1_PVCC")
	)
	(segment
		(start 76.620878 -183.23941)
		(end 76.112878 -182.73141)
		(width 0.508)
		(layer "In6.Cu")
		(net "PVDDCR_CPU0_P1_PVCC")
	)
	(segment
		(start 111.34217 -180.756052)
		(end 118.966234 -180.756052)
		(width 0.508)
		(layer "In6.Cu")
		(net "PVDDCR_CPU0_P1_PVCC")
	)
	(segment
		(start 69.686678 -168.275254)
		(end 69.33057 -167.919146)
		(width 0.508)
		(layer "In6.Cu")
		(net "PVDDCR_CPU0_P1_PVCC")
	)
	(segment
		(start 108.58627 -187.43041)
		(end 103.417878 -187.43041)
		(width 0.508)
		(layer "In6.Cu")
		(net "PVDDCR_CPU0_P1_PVCC")
	)
	(segment
		(start 78.652878 -190.98641)
		(end 85.002878 -190.98641)
		(width 0.508)
		(layer "In6.Cu")
		(net "PVDDCR_CPU0_P1_PVCC")
	)
	(segment
		(start 77.793088 -182.074312)
		(end 77.13599 -182.73141)
		(width 0.508)
		(layer "In6.Cu")
		(net "PVDDCR_CPU0_P1_PVCC")
	)
	(segment
		(start 119.36857 -171.605956)
		(end 119.36857 -170.91406)
		(width 0.508)
		(layer "In6.Cu")
		(net "PVDDCR_CPU0_P1_PVCC")
	)
	(segment
		(start 86.450678 -185.72861)
		(end 85.637878 -186.54141)
		(width 0.508)
		(layer "In6.Cu")
		(net "PVDDCR_CPU0_P1_PVCC")
	)
	(segment
		(start 94.654878 -182.977028)
		(end 94.654878 -185.14441)
		(width 0.508)
		(layer "In6.Cu")
		(net "PVDDCR_CPU0_P1_PVCC")
	)
	(segment
		(start 94.36481 -181.666388)
		(end 94.36481 -182.68696)
		(width 0.508)
		(layer "In6.Cu")
		(net "PVDDCR_CPU0_P1_PVCC")
	)
	(segment
		(start 103.417878 -187.43041)
		(end 103.417878 -182.858664)
		(width 0.508)
		(layer "In6.Cu")
		(net "PVDDCR_CPU0_P1_PVCC")
	)
	(segment
		(start 121.909078 -174.22241)
		(end 121.401078 -173.71441)
		(width 0.508)
		(layer "In6.Cu")
		(net "PVDDCR_CPU0_P1_PVCC")
	)
	(segment
		(start 93.892878 -190.98641)
		(end 101.893878 -190.98641)
		(width 0.508)
		(layer "In6.Cu")
		(net "PVDDCR_CPU0_P1_PVCC")
	)
	(segment
		(start 101.893878 -190.98641)
		(end 102.75697 -190.123318)
		(width 0.508)
		(layer "In6.Cu")
		(net "PVDDCR_CPU0_P1_PVCC")
	)
	(segment
		(start 111.34217 -177.36566)
		(end 111.34217 -180.756052)
		(width 0.508)
		(layer "In6.Cu")
		(net "PVDDCR_CPU0_P1_PVCC")
	)
	(segment
		(start 86.272878 -190.98641)
		(end 92.622878 -190.98641)
		(width 0.508)
		(layer "In6.Cu")
		(net "PVDDCR_CPU0_P1_PVCC")
	)
	(segment
		(start 128.208278 -165.332664)
		(end 128.208278 -173.30801)
		(width 0.508)
		(layer "In6.Cu")
		(net "PVDDCR_CPU0_P1_PVCC")
	)
	(segment
		(start 69.686678 -172.36821)
		(end 69.686678 -168.275254)
		(width 0.508)
		(layer "In6.Cu")
		(net "PVDDCR_CPU0_P1_PVCC")
	)
	(segment
		(start 102.75697 -190.123318)
		(end 102.75697 -188.091318)
		(width 0.508)
		(layer "In6.Cu")
		(net "PVDDCR_CPU0_P1_PVCC")
	)
	(segment
		(start 135.991854 -164.18306)
		(end 127.64897 -164.18306)
		(width 0.508)
		(layer "In6.Cu")
		(net "PVDDCR_CPU0_P1_PVCC")
	)
	(segment
		(start 85.637878 -186.54141)
		(end 85.637878 -190.35141)
		(width 0.508)
		(layer "In6.Cu")
		(net "PVDDCR_CPU0_P1_PVCC")
	)
	(segment
		(start 102.75697 -182.197756)
		(end 102.75697 -181.68366)
		(width 0.508)
		(layer "In6.Cu")
		(net "PVDDCR_CPU0_P1_PVCC")
	)
	(segment
		(start 93.257878 -190.35141)
		(end 93.892878 -190.98641)
		(width 0.508)
		(layer "In6.Cu")
		(net "PVDDCR_CPU0_P1_PVCC")
	)
	(segment
		(start 111.13897 -177.16246)
		(end 111.34217 -177.36566)
		(width 0.508)
		(layer "In6.Cu")
		(net "PVDDCR_CPU0_P1_PVCC")
	)
	(segment
		(start 85.002878 -190.98641)
		(end 85.637878 -190.35141)
		(width 0.508)
		(layer "In6.Cu")
		(net "PVDDCR_CPU0_P1_PVCC")
	)
	(segment
		(start 127.293878 -174.22241)
		(end 121.909078 -174.22241)
		(width 0.508)
		(layer "In6.Cu")
		(net "PVDDCR_CPU0_P1_PVCC")
	)
	(segment
		(start 77.890878 -190.22441)
		(end 78.652878 -190.98641)
		(width 0.508)
		(layer "In6.Cu")
		(net "PVDDCR_CPU0_P1_PVCC")
	)
	(segment
		(start 120.435878 -179.286408)
		(end 120.435878 -172.673264)
		(width 0.508)
		(layer "In6.Cu")
		(net "PVDDCR_CPU0_P1_PVCC")
	)
	(segment
		(start 77.890878 -188.31941)
		(end 77.890878 -190.22441)
		(width 0.508)
		(layer "In6.Cu")
		(net "PVDDCR_CPU0_P1_PVCC")
	)
	(segment
		(start 85.637878 -190.35141)
		(end 86.272878 -190.98641)
		(width 0.508)
		(layer "In6.Cu")
		(net "PVDDCR_CPU0_P1_PVCC")
	)
	(segment
		(start 68.492878 -173.56201)
		(end 69.686678 -172.36821)
		(width 0.508)
		(layer "In6.Cu")
		(net "PVDDCR_CPU0_P1_PVCC")
	)
	(segment
		(start 94.654878 -185.14441)
		(end 93.257878 -186.54141)
		(width 0.508)
		(layer "In6.Cu")
		(net "PVDDCR_CPU0_P1_PVCC")
	)
	(segment
		(start 92.622878 -190.98641)
		(end 93.257878 -190.35141)
		(width 0.508)
		(layer "In6.Cu")
		(net "PVDDCR_CPU0_P1_PVCC")
	)
	(segment
		(start 127.64897 -164.18306)
		(end 127.64897 -164.773356)
		(width 0.508)
		(layer "In6.Cu")
		(net "PVDDCR_CPU0_P1_PVCC")
	)
	(segment
		(start 102.75697 -188.091318)
		(end 103.417878 -187.43041)
		(width 0.508)
		(layer "In6.Cu")
		(net "PVDDCR_CPU0_P1_PVCC")
	)
	(segment
		(start 118.966234 -180.756052)
		(end 120.435878 -179.286408)
		(width 0.508)
		(layer "In6.Cu")
		(net "PVDDCR_CPU0_P1_PVCC")
	)
	(segment
		(start 69.000878 -182.73141)
		(end 68.492878 -182.22341)
		(width 0.508)
		(layer "In6.Cu")
		(net "PVDDCR_CPU0_P1_PVCC")
	)
	(segment
		(start 127.64897 -164.773356)
		(end 128.208278 -165.332664)
		(width 0.508)
		(layer "In6.Cu")
		(net "PVDDCR_CPU0_P1_PVCC")
	)
	(segment
		(start 68.492878 -182.22341)
		(end 68.492878 -173.56201)
		(width 0.508)
		(layer "In6.Cu")
		(net "PVDDCR_CPU0_P1_PVCC")
	)
	(segment
		(start 93.257878 -186.54141)
		(end 93.257878 -190.35141)
		(width 0.508)
		(layer "In6.Cu")
		(net "PVDDCR_CPU0_P1_PVCC")
	)
	(segment
		(start 137.072878 -163.102036)
		(end 135.991854 -164.18306)
		(width 0.508)
		(layer "In6.Cu")
		(net "PVDDCR_CPU0_P1_PVCC")
	)
	(segment
		(start 77.13599 -182.73141)
		(end 77.128878 -182.73141)
		(width 0.508)
		(layer "In6.Cu")
		(net "PVDDCR_CPU0_P1_PVCC")
	)
	(segment
		(start 121.401078 -171.88561)
		(end 120.429528 -170.91406)
		(width 0.508)
		(layer "In6.Cu")
		(net "PVDDCR_CPU0_P1_PVCC")
	)
	(segment
		(start 77.128878 -182.73141)
		(end 76.620878 -183.23941)
		(width 0.508)
		(layer "In6.Cu")
		(net "PVDDCR_CPU0_P1_PVCC")
	)
	(segment
		(start 76.620878 -183.23941)
		(end 76.620878 -187.04941)
		(width 0.508)
		(layer "In6.Cu")
		(net "PVDDCR_CPU0_P1_PVCC")
	)
	(segment
		(start 76.620878 -187.04941)
		(end 77.890878 -188.31941)
		(width 0.508)
		(layer "In6.Cu")
		(net "PVDDCR_CPU0_P1_PVCC")
	)
	(segment
		(start 76.112878 -182.73141)
		(end 69.000878 -182.73141)
		(width 0.508)
		(layer "In6.Cu")
		(net "PVDDCR_CPU0_P1_PVCC")
	)
	(segment
		(start 86.450678 -182.217568)
		(end 86.450678 -185.72861)
		(width 0.508)
		(layer "In6.Cu")
		(net "PVDDCR_CPU0_P1_PVCC")
	)
	(segment
		(start 137.072878 -154.345132)
		(end 137.072878 -163.102036)
		(width 0.508)
		(layer "In6.Cu")
		(net "PVDDCR_CPU0_P1_PVCC")
	)
	(segment
		(start 111.34217 -180.756052)
		(end 111.34217 -184.67451)
		(width 0.508)
		(layer "In6.Cu")
		(net "PVDDCR_CPU0_P1_PVCC")
	)
	(segment
		(start 77.793088 -176.765458)
		(end 77.793088 -182.074312)
		(width 0.508)
		(layer "In6.Cu")
		(net "PVDDCR_CPU0_P1_PVCC")
	)
	(segment
		(start 120.429528 -170.91406)
		(end 119.36857 -170.91406)
		(width 0.508)
		(layer "In6.Cu")
		(net "PVDDCR_CPU0_P1_PVCC")
	)
	(segment
		(start 128.208278 -173.30801)
		(end 127.293878 -174.22241)
		(width 0.508)
		(layer "In6.Cu")
		(net "PVDDCR_CPU0_P1_PVCC")
	)
	(segment
		(start 94.36481 -182.68696)
		(end 94.654878 -182.977028)
		(width 0.508)
		(layer "In6.Cu")
		(net "PVDDCR_CPU0_P1_PVCC")
	)
	(segment
		(start 85.96757 -181.73446)
		(end 86.450678 -182.217568)
		(width 0.508)
		(layer "In6.Cu")
		(net "PVDDCR_CPU0_P1_PVCC")
	)
	(segment
		(start 121.401078 -173.71441)
		(end 121.401078 -171.88561)
		(width 0.508)
		(layer "In6.Cu")
		(net "PVDDCR_CPU0_P1_PVCC")
	)
	(via
		(at 92.467938 -141.420342)
		(size 0.762)
		(drill 0.254)
		(layers "F.Cu" "B.Cu")
		(net "PVDDCR_CPU0_P1_PMSDA_R")
	)
	(segment
		(start 92.782136 -141.73454)
		(end 92.782136 -142.5448)
		(width 0.10668)
		(layer "B.Cu")
		(net "PVDDCR_CPU0_P1_PMSDA_R")
	)
	(segment
		(start 92.782136 -142.5448)
		(end 92.795852 -142.558516)
		(width 0.10668)
		(layer "B.Cu")
		(net "PVDDCR_CPU0_P1_PMSDA_R")
	)
	(segment
		(start 91.987878 -140.58646)
		(end 91.987878 -140.940282)
		(width 0.10668)
		(layer "B.Cu")
		(net "PVDDCR_CPU0_P1_PMSDA_R")
	)
	(segment
		(start 91.987878 -140.940282)
		(end 92.467938 -141.420342)
		(width 0.10668)
		(layer "B.Cu")
		(net "PVDDCR_CPU0_P1_PMSDA_R")
	)
	(segment
		(start 92.467938 -141.420342)
		(end 92.782136 -141.73454)
		(width 0.10668)
		(layer "B.Cu")
		(net "PVDDCR_CPU0_P1_PMSDA_R")
	)
	(via
		(at 90.8304 -137.94232)
		(size 0.6604)
		(drill 0.3302)
		(layers "F.Cu" "B.Cu")
		(net "PVDDCR_CPU0_P1_PMSCL_R")
	)
	(segment
		(start 91.254834 -139.11834)
		(end 91.254834 -140.949934)
		(width 0.10668)
		(layer "B.Cu")
		(net "PVDDCR_CPU0_P1_PMSCL_R")
	)
	(segment
		(start 91.47556 -137.94232)
		(end 91.5416 -138.00836)
		(width 0.10668)
		(layer "B.Cu")
		(net "PVDDCR_CPU0_P1_PMSCL_R")
	)
	(segment
		(start 91.254834 -140.949934)
		(end 92.284042 -141.979142)
		(width 0.10668)
		(layer "B.Cu")
		(net "PVDDCR_CPU0_P1_PMSCL_R")
	)
	(segment
		(start 92.497402 -142.958312)
		(end 92.795852 -142.958312)
		(width 0.10668)
		(layer "B.Cu")
		(net "PVDDCR_CPU0_P1_PMSCL_R")
	)
	(segment
		(start 90.8304 -137.94232)
		(end 91.47556 -137.94232)
		(width 0.10668)
		(layer "B.Cu")
		(net "PVDDCR_CPU0_P1_PMSCL_R")
	)
	(segment
		(start 91.5416 -138.00836)
		(end 91.5416 -138.362182)
		(width 0.10668)
		(layer "B.Cu")
		(net "PVDDCR_CPU0_P1_PMSCL_R")
	)
	(segment
		(start 92.284042 -142.744952)
		(end 92.497402 -142.958312)
		(width 0.10668)
		(layer "B.Cu")
		(net "PVDDCR_CPU0_P1_PMSCL_R")
	)
	(segment
		(start 91.5416 -138.362182)
		(end 91.987878 -138.80846)
		(width 0.10668)
		(layer "B.Cu")
		(net "PVDDCR_CPU0_P1_PMSCL_R")
	)
	(segment
		(start 90.8304 -137.94232)
		(end 90.8304 -138.693906)
		(width 0.10668)
		(layer "B.Cu")
		(net "PVDDCR_CPU0_P1_PMSCL_R")
	)
	(segment
		(start 92.284042 -141.979142)
		(end 92.284042 -142.744952)
		(width 0.10668)
		(layer "B.Cu")
		(net "PVDDCR_CPU0_P1_PMSCL_R")
	)
	(segment
		(start 90.8304 -138.693906)
		(end 91.254834 -139.11834)
		(width 0.10668)
		(layer "B.Cu")
		(net "PVDDCR_CPU0_P1_PMSCL_R")
	)
	(via
		(at 91.604846 -141.816328)
		(size 0.4064)
		(drill 0.2032)
		(layers "F.Cu" "B.Cu")
		(net "PVDDCR_CPU0_P1_PMALERT_R")
	)
	(segment
		(start 92.015564 -142.869158)
		(end 92.504768 -143.358362)
		(width 0.10668)
		(layer "B.Cu")
		(net "PVDDCR_CPU0_P1_PMALERT_R")
	)
	(segment
		(start 92.015564 -142.227046)
		(end 92.015564 -142.869158)
		(width 0.10668)
		(layer "B.Cu")
		(net "PVDDCR_CPU0_P1_PMALERT_R")
	)
	(segment
		(start 91.604846 -141.816328)
		(end 92.015564 -142.227046)
		(width 0.10668)
		(layer "B.Cu")
		(net "PVDDCR_CPU0_P1_PMALERT_R")
	)
	(segment
		(start 90.609928 -140.82141)
		(end 91.604846 -141.816328)
		(width 0.10668)
		(layer "B.Cu")
		(net "PVDDCR_CPU0_P1_PMALERT_R")
	)
	(segment
		(start 92.504768 -143.358362)
		(end 92.795852 -143.358362)
		(width 0.10668)
		(layer "B.Cu")
		(net "PVDDCR_CPU0_P1_PMALERT_R")
	)
	(segment
		(start 185.777124 -96.496124)
		(end 186.48045 -97.19945)
		(width 0.10668)
		(layer "F.Cu")
		(net "PVDDCR_CPU0_P1_PMALERT")
	)
	(segment
		(start 186.48045 -97.19945)
		(end 186.48045 -97.926398)
		(width 0.10668)
		(layer "F.Cu")
		(net "PVDDCR_CPU0_P1_PMALERT")
	)
	(segment
		(start 185.922158 -109.852968)
		(end 186.312048 -109.463078)
		(width 0.10668)
		(layer "F.Cu")
		(net "PVDDCR_CPU0_P1_PMALERT")
	)
	(segment
		(start 186.48045 -97.926398)
		(end 186.817 -98.262948)
		(width 0.10668)
		(layer "F.Cu")
		(net "PVDDCR_CPU0_P1_PMALERT")
	)
	(via
		(at 89.193878 -139.80541)
		(size 0.762)
		(drill 0.254)
		(layers "F.Cu" "B.Cu")
		(net "PVDDCR_CPU0_P1_PMALERT")
	)
	(via
		(at 186.817 -98.262948)
		(size 0.508)
		(drill 0.254)
		(layers "F.Cu" "B.Cu")
		(net "PVDDCR_CPU0_P1_PMALERT")
	)
	(via
		(at 165.202616 -126.009908)
		(size 0.508)
		(drill 0.254)
		(layers "F.Cu" "B.Cu")
		(net "PVDDCR_CPU0_P1_PMALERT")
	)
	(via
		(at 97.746058 -128.792478)
		(size 0.508)
		(drill 0.254)
		(layers "F.Cu" "B.Cu")
		(net "PVDDCR_CPU0_P1_PMALERT")
	)
	(via
		(at 186.312048 -109.463078)
		(size 0.4572)
		(drill 0.254)
		(layers "F.Cu" "B.Cu")
		(net "PVDDCR_CPU0_P1_PMALERT")
	)
	(segment
		(start 156.890212 -128.659636)
		(end 157.991556 -127.558292)
		(width 0.10668)
		(layer "B.Cu")
		(net "PVDDCR_CPU0_P1_PMALERT")
	)
	(segment
		(start 114.78641 -128.086866)
		(end 155.303728 -128.086866)
		(width 0.10668)
		(layer "B.Cu")
		(net "PVDDCR_CPU0_P1_PMALERT")
	)
	(segment
		(start 89.194132 -139.805664)
		(end 89.193878 -139.80541)
		(width 0.10668)
		(layer "B.Cu")
		(net "PVDDCR_CPU0_P1_PMALERT")
	)
	(segment
		(start 89.809574 -139.805664)
		(end 89.194132 -139.805664)
		(width 0.10668)
		(layer "B.Cu")
		(net "PVDDCR_CPU0_P1_PMALERT")
	)
	(segment
		(start 105.78084 -127.4064)
		(end 107.634532 -125.552708)
		(width 0.10668)
		(layer "B.Cu")
		(net "PVDDCR_CPU0_P1_PMALERT")
	)
	(segment
		(start 155.876498 -128.659636)
		(end 156.890212 -128.659636)
		(width 0.10668)
		(layer "B.Cu")
		(net "PVDDCR_CPU0_P1_PMALERT")
	)
	(segment
		(start 157.991556 -126.620016)
		(end 159.489648 -125.121924)
		(width 0.10668)
		(layer "B.Cu")
		(net "PVDDCR_CPU0_P1_PMALERT")
	)
	(segment
		(start 165.202616 -125.683518)
		(end 165.202616 -126.009908)
		(width 0.10668)
		(layer "B.Cu")
		(net "PVDDCR_CPU0_P1_PMALERT")
	)
	(segment
		(start 97.746058 -128.152398)
		(end 98.492056 -127.4064)
		(width 0.10668)
		(layer "B.Cu")
		(net "PVDDCR_CPU0_P1_PMALERT")
	)
	(segment
		(start 159.489648 -125.121924)
		(end 164.641022 -125.121924)
		(width 0.10668)
		(layer "B.Cu")
		(net "PVDDCR_CPU0_P1_PMALERT")
	)
	(segment
		(start 108.888784 -126.231904)
		(end 112.931448 -126.231904)
		(width 0.10668)
		(layer "B.Cu")
		(net "PVDDCR_CPU0_P1_PMALERT")
	)
	(segment
		(start 107.634532 -125.552708)
		(end 108.209588 -125.552708)
		(width 0.10668)
		(layer "B.Cu")
		(net "PVDDCR_CPU0_P1_PMALERT")
	)
	(segment
		(start 97.746058 -128.792478)
		(end 97.746058 -128.152398)
		(width 0.10668)
		(layer "B.Cu")
		(net "PVDDCR_CPU0_P1_PMALERT")
	)
	(segment
		(start 89.809828 -140.82141)
		(end 89.809828 -139.80541)
		(width 0.10668)
		(layer "B.Cu")
		(net "PVDDCR_CPU0_P1_PMALERT")
	)
	(segment
		(start 98.492056 -127.4064)
		(end 105.78084 -127.4064)
		(width 0.10668)
		(layer "B.Cu")
		(net "PVDDCR_CPU0_P1_PMALERT")
	)
	(segment
		(start 155.303728 -128.086866)
		(end 155.876498 -128.659636)
		(width 0.10668)
		(layer "B.Cu")
		(net "PVDDCR_CPU0_P1_PMALERT")
	)
	(segment
		(start 157.991556 -127.558292)
		(end 157.991556 -126.620016)
		(width 0.10668)
		(layer "B.Cu")
		(net "PVDDCR_CPU0_P1_PMALERT")
	)
	(segment
		(start 108.209588 -125.552708)
		(end 108.888784 -126.231904)
		(width 0.10668)
		(layer "B.Cu")
		(net "PVDDCR_CPU0_P1_PMALERT")
	)
	(segment
		(start 112.931448 -126.231904)
		(end 114.78641 -128.086866)
		(width 0.10668)
		(layer "B.Cu")
		(net "PVDDCR_CPU0_P1_PMALERT")
	)
	(segment
		(start 89.809828 -139.80541)
		(end 89.809574 -139.805664)
		(width 0.10668)
		(layer "B.Cu")
		(net "PVDDCR_CPU0_P1_PMALERT")
	)
	(segment
		(start 164.641022 -125.121924)
		(end 165.202616 -125.683518)
		(width 0.10668)
		(layer "B.Cu")
		(net "PVDDCR_CPU0_P1_PMALERT")
	)
	(segment
		(start 89.875614 -136.969754)
		(end 97.746058 -129.09931)
		(width 0.11684)
		(layer "In2.Cu")
		(net "PVDDCR_CPU0_P1_PMALERT")
	)
	(segment
		(start 89.193878 -139.80541)
		(end 88.419178 -139.03071)
		(width 0.11684)
		(layer "In2.Cu")
		(net "PVDDCR_CPU0_P1_PMALERT")
	)
	(segment
		(start 88.837008 -136.969754)
		(end 89.875614 -136.969754)
		(width 0.11684)
		(layer "In2.Cu")
		(net "PVDDCR_CPU0_P1_PMALERT")
	)
	(segment
		(start 97.746058 -129.09931)
		(end 97.746058 -128.792478)
		(width 0.11684)
		(layer "In2.Cu")
		(net "PVDDCR_CPU0_P1_PMALERT")
	)
	(segment
		(start 88.419178 -139.03071)
		(end 88.419178 -137.387584)
		(width 0.11684)
		(layer "In2.Cu")
		(net "PVDDCR_CPU0_P1_PMALERT")
	)
	(segment
		(start 88.419178 -137.387584)
		(end 88.837008 -136.969754)
		(width 0.11684)
		(layer "In2.Cu")
		(net "PVDDCR_CPU0_P1_PMALERT")
	)
	(segment
		(start 185.923428 -106.07675)
		(end 187.3758 -104.624378)
		(width 0.11684)
		(layer "In4.Cu")
		(net "PVDDCR_CPU0_P1_PMALERT")
	)
	(segment
		(start 185.923428 -109.074458)
		(end 185.923428 -106.07675)
		(width 0.11684)
		(layer "In4.Cu")
		(net "PVDDCR_CPU0_P1_PMALERT")
	)
	(segment
		(start 187.3758 -104.624378)
		(end 187.3758 -98.466402)
		(width 0.11684)
		(layer "In4.Cu")
		(net "PVDDCR_CPU0_P1_PMALERT")
	)
	(segment
		(start 187.3758 -98.466402)
		(end 187.172346 -98.262948)
		(width 0.11684)
		(layer "In4.Cu")
		(net "PVDDCR_CPU0_P1_PMALERT")
	)
	(segment
		(start 187.172346 -98.262948)
		(end 186.817 -98.262948)
		(width 0.11684)
		(layer "In4.Cu")
		(net "PVDDCR_CPU0_P1_PMALERT")
	)
	(segment
		(start 186.312048 -109.463078)
		(end 185.923428 -109.074458)
		(width 0.11684)
		(layer "In4.Cu")
		(net "PVDDCR_CPU0_P1_PMALERT")
	)
	(segment
		(start 186.312048 -109.463078)
		(end 186.446414 -109.463078)
		(width 0.11684)
		(layer "In6.Cu")
		(net "PVDDCR_CPU0_P1_PMALERT")
	)
	(segment
		(start 172.30852 -120.523508)
		(end 172.047408 -120.78462)
		(width 0.11684)
		(layer "In6.Cu")
		(net "PVDDCR_CPU0_P1_PMALERT")
	)
	(segment
		(start 169.23893 -121.111264)
		(end 164.823902 -121.111264)
		(width 0.11684)
		(layer "In6.Cu")
		(net "PVDDCR_CPU0_P1_PMALERT")
	)
	(segment
		(start 164.562536 -122.939302)
		(end 165.71849 -124.095256)
		(width 0.11684)
		(layer "In6.Cu")
		(net "PVDDCR_CPU0_P1_PMALERT")
	)
	(segment
		(start 186.70397 -109.720634)
		(end 186.70397 -114.645186)
		(width 0.11684)
		(layer "In6.Cu")
		(net "PVDDCR_CPU0_P1_PMALERT")
	)
	(segment
		(start 165.71849 -124.095256)
		(end 165.71849 -125.494034)
		(width 0.11684)
		(layer "In6.Cu")
		(net "PVDDCR_CPU0_P1_PMALERT")
	)
	(segment
		(start 164.562536 -121.37263)
		(end 164.562536 -122.939302)
		(width 0.11684)
		(layer "In6.Cu")
		(net "PVDDCR_CPU0_P1_PMALERT")
	)
	(segment
		(start 184.888124 -119.439436)
		(end 176.044606 -119.439436)
		(width 0.11684)
		(layer "In6.Cu")
		(net "PVDDCR_CPU0_P1_PMALERT")
	)
	(segment
		(start 176.044606 -119.439436)
		(end 174.960534 -120.523508)
		(width 0.11684)
		(layer "In6.Cu")
		(net "PVDDCR_CPU0_P1_PMALERT")
	)
	(segment
		(start 185.645806 -118.681754)
		(end 184.888124 -119.439436)
		(width 0.11684)
		(layer "In6.Cu")
		(net "PVDDCR_CPU0_P1_PMALERT")
	)
	(segment
		(start 186.02452 -114.984784)
		(end 185.645806 -115.363498)
		(width 0.11684)
		(layer "In6.Cu")
		(net "PVDDCR_CPU0_P1_PMALERT")
	)
	(segment
		(start 185.645806 -115.363498)
		(end 185.645806 -118.681754)
		(width 0.11684)
		(layer "In6.Cu")
		(net "PVDDCR_CPU0_P1_PMALERT")
	)
	(segment
		(start 186.70397 -114.645186)
		(end 186.364372 -114.984784)
		(width 0.11684)
		(layer "In6.Cu")
		(net "PVDDCR_CPU0_P1_PMALERT")
	)
	(segment
		(start 186.364372 -114.984784)
		(end 186.02452 -114.984784)
		(width 0.11684)
		(layer "In6.Cu")
		(net "PVDDCR_CPU0_P1_PMALERT")
	)
	(segment
		(start 186.446414 -109.463078)
		(end 186.70397 -109.720634)
		(width 0.11684)
		(layer "In6.Cu")
		(net "PVDDCR_CPU0_P1_PMALERT")
	)
	(segment
		(start 172.047408 -120.78462)
		(end 169.565574 -120.78462)
		(width 0.11684)
		(layer "In6.Cu")
		(net "PVDDCR_CPU0_P1_PMALERT")
	)
	(segment
		(start 164.823902 -121.111264)
		(end 164.562536 -121.37263)
		(width 0.11684)
		(layer "In6.Cu")
		(net "PVDDCR_CPU0_P1_PMALERT")
	)
	(segment
		(start 165.71849 -125.494034)
		(end 165.202616 -126.009908)
		(width 0.11684)
		(layer "In6.Cu")
		(net "PVDDCR_CPU0_P1_PMALERT")
	)
	(segment
		(start 169.565574 -120.78462)
		(end 169.23893 -121.111264)
		(width 0.11684)
		(layer "In6.Cu")
		(net "PVDDCR_CPU0_P1_PMALERT")
	)
	(segment
		(start 174.960534 -120.523508)
		(end 172.30852 -120.523508)
		(width 0.11684)
		(layer "In6.Cu")
		(net "PVDDCR_CPU0_P1_PMALERT")
	)
	(segment
		(start 100.369878 -145.74901)
		(end 101.141276 -144.977612)
		(width 0.10668)
		(layer "F.Cu")
		(net "PVDDCR_CPU0_P1_OCP_N_R")
	)
	(segment
		(start 101.141276 -144.977612)
		(end 101.770942 -144.977612)
		(width 0.10668)
		(layer "F.Cu")
		(net "PVDDCR_CPU0_P1_OCP_N_R")
	)
	(via
		(at 100.369878 -145.74901)
		(size 0.762)
		(drill 0.254)
		(layers "F.Cu" "B.Cu")
		(net "PVDDCR_CPU0_P1_OCP_N_R")
	)
	(segment
		(start 100.985828 -145.64741)
		(end 100.884228 -145.74901)
		(width 0.10668)
		(layer "B.Cu")
		(net "PVDDCR_CPU0_P1_OCP_N_R")
	)
	(segment
		(start 99.543362 -145.358358)
		(end 98.545904 -145.358358)
		(width 0.10668)
		(layer "B.Cu")
		(net "PVDDCR_CPU0_P1_OCP_N_R")
	)
	(segment
		(start 99.984306 -145.64741)
		(end 99.725226 -145.540222)
		(width 0.10668)
		(layer "B.Cu")
		(net "PVDDCR_CPU0_P1_OCP_N_R")
	)
	(segment
		(start 100.268278 -145.64741)
		(end 99.984306 -145.64741)
		(width 0.10668)
		(layer "B.Cu")
		(net "PVDDCR_CPU0_P1_OCP_N_R")
	)
	(segment
		(start 100.369878 -145.74901)
		(end 100.268278 -145.64741)
		(width 0.10668)
		(layer "B.Cu")
		(net "PVDDCR_CPU0_P1_OCP_N_R")
	)
	(segment
		(start 100.884228 -145.74901)
		(end 100.369878 -145.74901)
		(width 0.10668)
		(layer "B.Cu")
		(net "PVDDCR_CPU0_P1_OCP_N_R")
	)
	(segment
		(start 99.725226 -145.540222)
		(end 99.543362 -145.358358)
		(width 0.10668)
		(layer "B.Cu")
		(net "PVDDCR_CPU0_P1_OCP_N_R")
	)
	(segment
		(start 164.35959 -94.42069)
		(end 167.775636 -91.004644)
		(width 0.10668)
		(layer "F.Cu")
		(net "PVDDCR_CPU0_P1_OCP_N")
	)
	(segment
		(start 183.261 -99.660202)
		(end 183.026304 -99.894898)
		(width 0.10668)
		(layer "F.Cu")
		(net "PVDDCR_CPU0_P1_OCP_N")
	)
	(segment
		(start 184.058306 -98.80219)
		(end 183.54167 -98.80219)
		(width 0.10668)
		(layer "F.Cu")
		(net "PVDDCR_CPU0_P1_OCP_N")
	)
	(segment
		(start 184.081674 -97.75571)
		(end 184.311036 -97.985072)
		(width 0.10668)
		(layer "F.Cu")
		(net "PVDDCR_CPU0_P1_OCP_N")
	)
	(segment
		(start 183.026304 -99.894898)
		(end 182.753 -99.894898)
		(width 0.10668)
		(layer "F.Cu")
		(net "PVDDCR_CPU0_P1_OCP_N")
	)
	(segment
		(start 184.081674 -94.303342)
		(end 184.081674 -97.75571)
		(width 0.10668)
		(layer "F.Cu")
		(net "PVDDCR_CPU0_P1_OCP_N")
	)
	(segment
		(start 184.287414 -91.131644)
		(end 184.287414 -94.097602)
		(width 0.10668)
		(layer "F.Cu")
		(net "PVDDCR_CPU0_P1_OCP_N")
	)
	(segment
		(start 184.311036 -97.985072)
		(end 184.311036 -98.54946)
		(width 0.10668)
		(layer "F.Cu")
		(net "PVDDCR_CPU0_P1_OCP_N")
	)
	(segment
		(start 183.261 -99.08286)
		(end 183.261 -99.660202)
		(width 0.10668)
		(layer "F.Cu")
		(net "PVDDCR_CPU0_P1_OCP_N")
	)
	(segment
		(start 183.54167 -98.80219)
		(end 183.261 -99.08286)
		(width 0.10668)
		(layer "F.Cu")
		(net "PVDDCR_CPU0_P1_OCP_N")
	)
	(segment
		(start 184.160414 -91.004644)
		(end 184.287414 -91.131644)
		(width 0.10668)
		(layer "F.Cu")
		(net "PVDDCR_CPU0_P1_OCP_N")
	)
	(segment
		(start 184.287414 -94.097602)
		(end 184.081674 -94.303342)
		(width 0.10668)
		(layer "F.Cu")
		(net "PVDDCR_CPU0_P1_OCP_N")
	)
	(segment
		(start 184.311036 -98.54946)
		(end 184.058306 -98.80219)
		(width 0.10668)
		(layer "F.Cu")
		(net "PVDDCR_CPU0_P1_OCP_N")
	)
	(segment
		(start 167.775636 -91.004644)
		(end 184.160414 -91.004644)
		(width 0.10668)
		(layer "F.Cu")
		(net "PVDDCR_CPU0_P1_OCP_N")
	)
	(segment
		(start 164.35959 -98.972624)
		(end 164.35959 -94.42069)
		(width 0.10668)
		(layer "F.Cu")
		(net "PVDDCR_CPU0_P1_OCP_N")
	)
	(segment
		(start 162.759136 -100.573078)
		(end 164.35959 -98.972624)
		(width 0.10668)
		(layer "F.Cu")
		(net "PVDDCR_CPU0_P1_OCP_N")
	)
	(via
		(at 104.168194 -145.442432)
		(size 0.508)
		(drill 0.254)
		(layers "F.Cu" "B.Cu")
		(net "PVDDCR_CPU0_P1_OCP_N")
	)
	(via
		(at 162.759136 -100.573078)
		(size 0.508)
		(drill 0.254)
		(layers "F.Cu" "B.Cu")
		(net "PVDDCR_CPU0_P1_OCP_N")
	)
	(segment
		(start 103.48468 -145.442432)
		(end 104.168194 -145.442432)
		(width 0.10668)
		(layer "B.Cu")
		(net "PVDDCR_CPU0_P1_OCP_N")
	)
	(segment
		(start 101.785928 -145.64741)
		(end 101.785928 -145.361406)
		(width 0.10668)
		(layer "B.Cu")
		(net "PVDDCR_CPU0_P1_OCP_N")
	)
	(segment
		(start 101.785928 -145.361406)
		(end 102.056946 -145.090388)
		(width 0.10668)
		(layer "B.Cu")
		(net "PVDDCR_CPU0_P1_OCP_N")
	)
	(segment
		(start 103.132636 -145.090388)
		(end 103.48468 -145.442432)
		(width 0.10668)
		(layer "B.Cu")
		(net "PVDDCR_CPU0_P1_OCP_N")
	)
	(segment
		(start 102.056946 -145.090388)
		(end 103.132636 -145.090388)
		(width 0.10668)
		(layer "B.Cu")
		(net "PVDDCR_CPU0_P1_OCP_N")
	)
	(segment
		(start 143.67764 -102.864412)
		(end 143.279114 -103.262938)
		(width 0.11684)
		(layer "In2.Cu")
		(net "PVDDCR_CPU0_P1_OCP_N")
	)
	(segment
		(start 161.96818 -100.48494)
		(end 160.874202 -100.48494)
		(width 0.11684)
		(layer "In2.Cu")
		(net "PVDDCR_CPU0_P1_OCP_N")
	)
	(segment
		(start 158.69793 -102.661212)
		(end 158.69793 -103.06177)
		(width 0.11684)
		(layer "In2.Cu")
		(net "PVDDCR_CPU0_P1_OCP_N")
	)
	(segment
		(start 138.966194 -102.046024)
		(end 131.502404 -109.509814)
		(width 0.11684)
		(layer "In2.Cu")
		(net "PVDDCR_CPU0_P1_OCP_N")
	)
	(segment
		(start 160.874202 -100.48494)
		(end 158.69793 -102.661212)
		(width 0.11684)
		(layer "In2.Cu")
		(net "PVDDCR_CPU0_P1_OCP_N")
	)
	(segment
		(start 156.24556 -104.403144)
		(end 155.289504 -103.447088)
		(width 0.11684)
		(layer "In2.Cu")
		(net "PVDDCR_CPU0_P1_OCP_N")
	)
	(segment
		(start 157.356556 -104.403144)
		(end 156.24556 -104.403144)
		(width 0.11684)
		(layer "In2.Cu")
		(net "PVDDCR_CPU0_P1_OCP_N")
	)
	(segment
		(start 131.502404 -109.509814)
		(end 131.502404 -122.794522)
		(width 0.11684)
		(layer "In2.Cu")
		(net "PVDDCR_CPU0_P1_OCP_N")
	)
	(segment
		(start 108.854494 -145.442432)
		(end 104.168194 -145.442432)
		(width 0.11684)
		(layer "In2.Cu")
		(net "PVDDCR_CPU0_P1_OCP_N")
	)
	(segment
		(start 146.969226 -102.864412)
		(end 143.67764 -102.864412)
		(width 0.11684)
		(layer "In2.Cu")
		(net "PVDDCR_CPU0_P1_OCP_N")
	)
	(segment
		(start 155.289504 -103.447088)
		(end 147.551902 -103.447088)
		(width 0.11684)
		(layer "In2.Cu")
		(net "PVDDCR_CPU0_P1_OCP_N")
	)
	(segment
		(start 147.551902 -103.447088)
		(end 146.969226 -102.864412)
		(width 0.11684)
		(layer "In2.Cu")
		(net "PVDDCR_CPU0_P1_OCP_N")
	)
	(segment
		(start 143.279114 -103.262938)
		(end 141.667738 -103.262938)
		(width 0.11684)
		(layer "In2.Cu")
		(net "PVDDCR_CPU0_P1_OCP_N")
	)
	(segment
		(start 162.056318 -100.573078)
		(end 161.96818 -100.48494)
		(width 0.11684)
		(layer "In2.Cu")
		(net "PVDDCR_CPU0_P1_OCP_N")
	)
	(segment
		(start 141.667738 -103.262938)
		(end 140.450824 -102.046024)
		(width 0.11684)
		(layer "In2.Cu")
		(net "PVDDCR_CPU0_P1_OCP_N")
	)
	(segment
		(start 162.759136 -100.573078)
		(end 162.056318 -100.573078)
		(width 0.11684)
		(layer "In2.Cu")
		(net "PVDDCR_CPU0_P1_OCP_N")
	)
	(segment
		(start 140.450824 -102.046024)
		(end 138.966194 -102.046024)
		(width 0.11684)
		(layer "In2.Cu")
		(net "PVDDCR_CPU0_P1_OCP_N")
	)
	(segment
		(start 131.502404 -122.794522)
		(end 108.854494 -145.442432)
		(width 0.11684)
		(layer "In2.Cu")
		(net "PVDDCR_CPU0_P1_OCP_N")
	)
	(segment
		(start 158.69793 -103.06177)
		(end 157.356556 -104.403144)
		(width 0.11684)
		(layer "In2.Cu")
		(net "PVDDCR_CPU0_P1_OCP_N")
	)
	(segment
		(start 67.110102 -164.07384)
		(end 67.110102 -164.855398)
		(width 0.1524)
		(layer "F.Cu")
		(net "PVDDCR_CPU0_P1_LSET6")
	)
	(segment
		(start 66.737484 -165.614604)
		(end 66.737484 -166.028624)
		(width 0.1524)
		(layer "F.Cu")
		(net "PVDDCR_CPU0_P1_LSET6")
	)
	(segment
		(start 67.352164 -163.71697)
		(end 67.352164 -163.831778)
		(width 0.1524)
		(layer "F.Cu")
		(net "PVDDCR_CPU0_P1_LSET6")
	)
	(segment
		(start 67.352164 -163.831778)
		(end 67.110102 -164.07384)
		(width 0.1524)
		(layer "F.Cu")
		(net "PVDDCR_CPU0_P1_LSET6")
	)
	(segment
		(start 67.110102 -164.855398)
		(end 67.110102 -165.241986)
		(width 0.1524)
		(layer "F.Cu")
		(net "PVDDCR_CPU0_P1_LSET6")
	)
	(segment
		(start 67.110102 -165.241986)
		(end 66.737484 -165.614604)
		(width 0.1524)
		(layer "F.Cu")
		(net "PVDDCR_CPU0_P1_LSET6")
	)
	(via
		(at 67.110102 -164.855398)
		(size 0.4064)
		(drill 0.2032)
		(layers "F.Cu" "B.Cu")
		(net "PVDDCR_CPU0_P1_LSET6")
	)
	(segment
		(start 75.050904 -174.319946)
		(end 75.050904 -174.725838)
		(width 0.1524)
		(layer "F.Cu")
		(net "PVDDCR_CPU0_P1_LSET5")
	)
	(segment
		(start 75.427078 -173.522132)
		(end 75.427078 -173.943772)
		(width 0.1524)
		(layer "F.Cu")
		(net "PVDDCR_CPU0_P1_LSET5")
	)
	(segment
		(start 75.665584 -172.414184)
		(end 75.427078 -172.65269)
		(width 0.1524)
		(layer "F.Cu")
		(net "PVDDCR_CPU0_P1_LSET5")
	)
	(segment
		(start 75.427078 -172.65269)
		(end 75.427078 -173.522132)
		(width 0.1524)
		(layer "F.Cu")
		(net "PVDDCR_CPU0_P1_LSET5")
	)
	(segment
		(start 75.427078 -173.943772)
		(end 75.050904 -174.319946)
		(width 0.1524)
		(layer "F.Cu")
		(net "PVDDCR_CPU0_P1_LSET5")
	)
	(via
		(at 75.427078 -173.522132)
		(size 0.4064)
		(drill 0.2032)
		(layers "F.Cu" "B.Cu")
		(net "PVDDCR_CPU0_P1_LSET5")
	)
	(segment
		(start 109.160564 -172.960284)
		(end 108.918502 -173.202346)
		(width 0.127)
		(layer "F.Cu")
		(net "PVDDCR_CPU0_P1_LSET4")
	)
	(segment
		(start 108.918502 -174.493428)
		(end 108.545884 -174.866046)
		(width 0.127)
		(layer "F.Cu")
		(net "PVDDCR_CPU0_P1_LSET4")
	)
	(segment
		(start 108.918502 -173.202346)
		(end 108.918502 -174.102776)
		(width 0.127)
		(layer "F.Cu")
		(net "PVDDCR_CPU0_P1_LSET4")
	)
	(segment
		(start 108.918502 -174.102776)
		(end 108.918502 -174.493428)
		(width 0.127)
		(layer "F.Cu")
		(net "PVDDCR_CPU0_P1_LSET4")
	)
	(segment
		(start 108.545884 -174.866046)
		(end 108.545884 -175.271938)
		(width 0.127)
		(layer "F.Cu")
		(net "PVDDCR_CPU0_P1_LSET4")
	)
	(via
		(at 108.918502 -174.102776)
		(size 0.4064)
		(drill 0.2032)
		(layers "F.Cu" "B.Cu")
		(net "PVDDCR_CPU0_P1_LSET4")
	)
	(segment
		(start 100.163884 -179.387246)
		(end 100.163884 -179.793138)
		(width 0.127)
		(layer "F.Cu")
		(net "PVDDCR_CPU0_P1_LSET3")
	)
	(segment
		(start 100.778564 -177.481484)
		(end 100.536502 -177.723546)
		(width 0.127)
		(layer "F.Cu")
		(net "PVDDCR_CPU0_P1_LSET3")
	)
	(segment
		(start 100.536502 -179.014628)
		(end 100.163884 -179.387246)
		(width 0.127)
		(layer "F.Cu")
		(net "PVDDCR_CPU0_P1_LSET3")
	)
	(segment
		(start 100.536502 -177.723546)
		(end 100.536502 -178.606704)
		(width 0.127)
		(layer "F.Cu")
		(net "PVDDCR_CPU0_P1_LSET3")
	)
	(segment
		(start 100.536502 -178.606704)
		(end 100.536502 -179.014628)
		(width 0.127)
		(layer "F.Cu")
		(net "PVDDCR_CPU0_P1_LSET3")
	)
	(via
		(at 100.536502 -178.606704)
		(size 0.4064)
		(drill 0.2032)
		(layers "F.Cu" "B.Cu")
		(net "PVDDCR_CPU0_P1_LSET3")
	)
	(segment
		(start 91.771724 -179.369974)
		(end 91.771724 -179.775866)
		(width 0.127)
		(layer "F.Cu")
		(net "PVDDCR_CPU0_P1_LSET2")
	)
	(segment
		(start 92.144342 -178.997356)
		(end 91.771724 -179.369974)
		(width 0.127)
		(layer "F.Cu")
		(net "PVDDCR_CPU0_P1_LSET2")
	)
	(segment
		(start 92.144342 -177.706274)
		(end 92.144342 -178.594766)
		(width 0.127)
		(layer "F.Cu")
		(net "PVDDCR_CPU0_P1_LSET2")
	)
	(segment
		(start 92.144342 -178.594766)
		(end 92.144342 -178.997356)
		(width 0.127)
		(layer "F.Cu")
		(net "PVDDCR_CPU0_P1_LSET2")
	)
	(segment
		(start 92.386404 -177.464212)
		(end 92.144342 -177.706274)
		(width 0.127)
		(layer "F.Cu")
		(net "PVDDCR_CPU0_P1_LSET2")
	)
	(via
		(at 92.144342 -178.594766)
		(size 0.4064)
		(drill 0.2032)
		(layers "F.Cu" "B.Cu")
		(net "PVDDCR_CPU0_P1_LSET2")
	)
	(segment
		(start 83.989164 -177.532284)
		(end 83.747102 -177.774346)
		(width 0.127)
		(layer "F.Cu")
		(net "PVDDCR_CPU0_P1_LSET1")
	)
	(segment
		(start 83.747102 -178.653948)
		(end 83.747102 -179.065428)
		(width 0.127)
		(layer "F.Cu")
		(net "PVDDCR_CPU0_P1_LSET1")
	)
	(segment
		(start 83.374484 -179.438046)
		(end 83.374484 -179.843938)
		(width 0.127)
		(layer "F.Cu")
		(net "PVDDCR_CPU0_P1_LSET1")
	)
	(segment
		(start 83.747102 -179.065428)
		(end 83.374484 -179.438046)
		(width 0.127)
		(layer "F.Cu")
		(net "PVDDCR_CPU0_P1_LSET1")
	)
	(segment
		(start 83.747102 -177.774346)
		(end 83.747102 -178.653948)
		(width 0.127)
		(layer "F.Cu")
		(net "PVDDCR_CPU0_P1_LSET1")
	)
	(via
		(at 83.747102 -178.653948)
		(size 0.4064)
		(drill 0.2032)
		(layers "F.Cu" "B.Cu")
		(net "PVDDCR_CPU0_P1_LSET1")
	)
	(segment
		(start 67.613022 -165.19652)
		(end 67.187572 -165.62197)
		(width 0.2286)
		(layer "F.Cu")
		(net "PVDDCR_CPU0_P1_IMON6")
	)
	(segment
		(start 67.187572 -165.62197)
		(end 67.187572 -166.028624)
		(width 0.2286)
		(layer "F.Cu")
		(net "PVDDCR_CPU0_P1_IMON6")
	)
	(segment
		(start 67.613022 -165.108128)
		(end 67.613022 -165.19652)
		(width 0.2286)
		(layer "F.Cu")
		(net "PVDDCR_CPU0_P1_IMON6")
	)
	(via
		(at 96.441006 -148.85416)
		(size 0.762)
		(drill 0.254)
		(layers "F.Cu" "B.Cu")
		(net "PVDDCR_CPU0_P1_IMON6")
	)
	(via
		(at 67.613022 -165.108128)
		(size 0.508)
		(drill 0.254)
		(layers "F.Cu" "B.Cu")
		(net "PVDDCR_CPU0_P1_IMON6")
	)
	(segment
		(start 96.270826 -148.443696)
		(end 96.270826 -147.633436)
		(width 0.1778)
		(layer "B.Cu")
		(net "PVDDCR_CPU0_P1_IMON6")
	)
	(segment
		(start 96.441006 -148.85416)
		(end 96.270826 -148.443696)
		(width 0.1778)
		(layer "B.Cu")
		(net "PVDDCR_CPU0_P1_IMON6")
	)
	(segment
		(start 90.042746 -151.46274)
		(end 84.224114 -151.46274)
		(width 0.254)
		(layer "In11.Cu")
		(net "PVDDCR_CPU0_P1_IMON6")
	)
	(segment
		(start 84.224114 -151.46274)
		(end 78.293722 -157.393132)
		(width 0.254)
		(layer "In11.Cu")
		(net "PVDDCR_CPU0_P1_IMON6")
	)
	(segment
		(start 78.293722 -157.393132)
		(end 70.200774 -157.393132)
		(width 0.254)
		(layer "In11.Cu")
		(net "PVDDCR_CPU0_P1_IMON6")
	)
	(segment
		(start 96.389698 -148.802852)
		(end 92.702634 -148.802852)
		(width 0.254)
		(layer "In11.Cu")
		(net "PVDDCR_CPU0_P1_IMON6")
	)
	(segment
		(start 96.441006 -148.85416)
		(end 96.389698 -148.802852)
		(width 0.254)
		(layer "In11.Cu")
		(net "PVDDCR_CPU0_P1_IMON6")
	)
	(segment
		(start 67.732402 -165.106096)
		(end 67.73037 -165.108128)
		(width 0.254)
		(layer "In11.Cu")
		(net "PVDDCR_CPU0_P1_IMON6")
	)
	(segment
		(start 68.248022 -164.554662)
		(end 68.248022 -164.73424)
		(width 0.254)
		(layer "In11.Cu")
		(net "PVDDCR_CPU0_P1_IMON6")
	)
	(segment
		(start 68.248022 -164.73424)
		(end 67.876166 -165.106096)
		(width 0.254)
		(layer "In11.Cu")
		(net "PVDDCR_CPU0_P1_IMON6")
	)
	(segment
		(start 70.200774 -157.393132)
		(end 68.340478 -159.253428)
		(width 0.254)
		(layer "In11.Cu")
		(net "PVDDCR_CPU0_P1_IMON6")
	)
	(segment
		(start 92.702634 -148.802852)
		(end 90.042746 -151.46274)
		(width 0.254)
		(layer "In11.Cu")
		(net "PVDDCR_CPU0_P1_IMON6")
	)
	(segment
		(start 68.340478 -159.253428)
		(end 68.340478 -164.462206)
		(width 0.254)
		(layer "In11.Cu")
		(net "PVDDCR_CPU0_P1_IMON6")
	)
	(segment
		(start 67.876166 -165.106096)
		(end 67.732402 -165.106096)
		(width 0.254)
		(layer "In11.Cu")
		(net "PVDDCR_CPU0_P1_IMON6")
	)
	(segment
		(start 68.340478 -164.462206)
		(end 68.248022 -164.554662)
		(width 0.254)
		(layer "In11.Cu")
		(net "PVDDCR_CPU0_P1_IMON6")
	)
	(segment
		(start 67.73037 -165.108128)
		(end 67.613022 -165.108128)
		(width 0.254)
		(layer "In11.Cu")
		(net "PVDDCR_CPU0_P1_IMON6")
	)
	(segment
		(start 75.926442 -173.805342)
		(end 75.926442 -173.924468)
		(width 0.2286)
		(layer "F.Cu")
		(net "PVDDCR_CPU0_P1_IMON5")
	)
	(segment
		(start 75.926442 -173.924468)
		(end 75.500992 -174.349918)
		(width 0.2286)
		(layer "F.Cu")
		(net "PVDDCR_CPU0_P1_IMON5")
	)
	(segment
		(start 75.500992 -174.349918)
		(end 75.500992 -174.725838)
		(width 0.2286)
		(layer "F.Cu")
		(net "PVDDCR_CPU0_P1_IMON5")
	)
	(via
		(at 75.926442 -173.805342)
		(size 0.508)
		(drill 0.254)
		(layers "F.Cu" "B.Cu")
		(net "PVDDCR_CPU0_P1_IMON5")
	)
	(via
		(at 95.904558 -149.892004)
		(size 0.508)
		(drill 0.254)
		(layers "F.Cu" "B.Cu")
		(net "PVDDCR_CPU0_P1_IMON5")
	)
	(segment
		(start 95.904558 -148.226018)
		(end 95.870776 -148.192236)
		(width 0.1778)
		(layer "B.Cu")
		(net "PVDDCR_CPU0_P1_IMON5")
	)
	(segment
		(start 95.870776 -148.192236)
		(end 95.870776 -147.633436)
		(width 0.1778)
		(layer "B.Cu")
		(net "PVDDCR_CPU0_P1_IMON5")
	)
	(segment
		(start 95.904558 -149.892004)
		(end 95.904558 -148.226018)
		(width 0.1778)
		(layer "B.Cu")
		(net "PVDDCR_CPU0_P1_IMON5")
	)
	(segment
		(start 96.863154 -150.339552)
		(end 96.415606 -149.892004)
		(width 0.254)
		(layer "In11.Cu")
		(net "PVDDCR_CPU0_P1_IMON5")
	)
	(segment
		(start 77.134974 -171.510452)
		(end 94.787974 -171.510452)
		(width 0.254)
		(layer "In11.Cu")
		(net "PVDDCR_CPU0_P1_IMON5")
	)
	(segment
		(start 94.787974 -171.510452)
		(end 96.863154 -169.435272)
		(width 0.254)
		(layer "In11.Cu")
		(net "PVDDCR_CPU0_P1_IMON5")
	)
	(segment
		(start 76.526898 -172.118528)
		(end 77.134974 -171.510452)
		(width 0.254)
		(layer "In11.Cu")
		(net "PVDDCR_CPU0_P1_IMON5")
	)
	(segment
		(start 75.926442 -173.805342)
		(end 76.04379 -173.805342)
		(width 0.254)
		(layer "In11.Cu")
		(net "PVDDCR_CPU0_P1_IMON5")
	)
	(segment
		(start 76.04379 -173.805342)
		(end 76.526898 -173.322234)
		(width 0.254)
		(layer "In11.Cu")
		(net "PVDDCR_CPU0_P1_IMON5")
	)
	(segment
		(start 76.526898 -173.322234)
		(end 76.526898 -172.118528)
		(width 0.254)
		(layer "In11.Cu")
		(net "PVDDCR_CPU0_P1_IMON5")
	)
	(segment
		(start 96.415606 -149.892004)
		(end 95.904558 -149.892004)
		(width 0.254)
		(layer "In11.Cu")
		(net "PVDDCR_CPU0_P1_IMON5")
	)
	(segment
		(start 96.863154 -169.435272)
		(end 96.863154 -150.339552)
		(width 0.254)
		(layer "In11.Cu")
		(net "PVDDCR_CPU0_P1_IMON5")
	)
	(segment
		(start 109.421422 -174.492666)
		(end 108.995972 -174.918116)
		(width 0.2286)
		(layer "F.Cu")
		(net "PVDDCR_CPU0_P1_IMON4")
	)
	(segment
		(start 108.995972 -174.918116)
		(end 108.995972 -175.271938)
		(width 0.2286)
		(layer "F.Cu")
		(net "PVDDCR_CPU0_P1_IMON4")
	)
	(segment
		(start 109.421422 -174.351442)
		(end 109.421422 -174.492666)
		(width 0.2286)
		(layer "F.Cu")
		(net "PVDDCR_CPU0_P1_IMON4")
	)
	(via
		(at 109.421422 -174.351442)
		(size 0.508)
		(drill 0.254)
		(layers "F.Cu" "B.Cu")
		(net "PVDDCR_CPU0_P1_IMON4")
	)
	(via
		(at 96.158558 -150.628604)
		(size 0.508)
		(drill 0.254)
		(layers "F.Cu" "B.Cu")
		(net "PVDDCR_CPU0_P1_IMON4")
	)
	(segment
		(start 95.268034 -149.183852)
		(end 95.47098 -148.980906)
		(width 0.1778)
		(layer "B.Cu")
		(net "PVDDCR_CPU0_P1_IMON4")
	)
	(segment
		(start 95.593408 -150.495254)
		(end 95.41764 -150.319486)
		(width 0.1778)
		(layer "B.Cu")
		(net "PVDDCR_CPU0_P1_IMON4")
	)
	(segment
		(start 95.914972 -150.628604)
		(end 95.593408 -150.495254)
		(width 0.1778)
		(layer "B.Cu")
		(net "PVDDCR_CPU0_P1_IMON4")
	)
	(segment
		(start 96.158558 -150.628604)
		(end 95.914972 -150.628604)
		(width 0.1778)
		(layer "B.Cu")
		(net "PVDDCR_CPU0_P1_IMON4")
	)
	(segment
		(start 95.47098 -148.980906)
		(end 95.47098 -147.633436)
		(width 0.1778)
		(layer "B.Cu")
		(net "PVDDCR_CPU0_P1_IMON4")
	)
	(segment
		(start 95.41764 -150.319486)
		(end 95.268034 -149.958298)
		(width 0.1778)
		(layer "B.Cu")
		(net "PVDDCR_CPU0_P1_IMON4")
	)
	(segment
		(start 95.268034 -149.958298)
		(end 95.268034 -149.183852)
		(width 0.1778)
		(layer "B.Cu")
		(net "PVDDCR_CPU0_P1_IMON4")
	)
	(segment
		(start 110.021878 -172.794422)
		(end 109.09046 -171.863004)
		(width 0.254)
		(layer "In4.Cu")
		(net "PVDDCR_CPU0_P1_IMON4")
	)
	(segment
		(start 109.09046 -171.863004)
		(end 104.614472 -171.863004)
		(width 0.254)
		(layer "In4.Cu")
		(net "PVDDCR_CPU0_P1_IMON4")
	)
	(segment
		(start 101.893878 -158.578042)
		(end 96.155002 -152.839166)
		(width 0.254)
		(layer "In4.Cu")
		(net "PVDDCR_CPU0_P1_IMON4")
	)
	(segment
		(start 96.155002 -150.63216)
		(end 96.158558 -150.628604)
		(width 0.254)
		(layer "In4.Cu")
		(net "PVDDCR_CPU0_P1_IMON4")
	)
	(segment
		(start 109.53877 -174.351442)
		(end 110.021878 -173.868334)
		(width 0.254)
		(layer "In4.Cu")
		(net "PVDDCR_CPU0_P1_IMON4")
	)
	(segment
		(start 110.021878 -173.868334)
		(end 110.021878 -172.794422)
		(width 0.254)
		(layer "In4.Cu")
		(net "PVDDCR_CPU0_P1_IMON4")
	)
	(segment
		(start 101.893878 -169.14241)
		(end 101.893878 -158.578042)
		(width 0.254)
		(layer "In4.Cu")
		(net "PVDDCR_CPU0_P1_IMON4")
	)
	(segment
		(start 96.155002 -152.839166)
		(end 96.155002 -150.63216)
		(width 0.254)
		(layer "In4.Cu")
		(net "PVDDCR_CPU0_P1_IMON4")
	)
	(segment
		(start 104.614472 -171.863004)
		(end 101.893878 -169.14241)
		(width 0.254)
		(layer "In4.Cu")
		(net "PVDDCR_CPU0_P1_IMON4")
	)
	(segment
		(start 109.421422 -174.351442)
		(end 109.53877 -174.351442)
		(width 0.254)
		(layer "In4.Cu")
		(net "PVDDCR_CPU0_P1_IMON4")
	)
	(segment
		(start 100.613972 -179.417218)
		(end 101.051106 -178.980084)
		(width 0.2286)
		(layer "F.Cu")
		(net "PVDDCR_CPU0_P1_IMON3")
	)
	(segment
		(start 101.051106 -178.980084)
		(end 101.051106 -178.872642)
		(width 0.2286)
		(layer "F.Cu")
		(net "PVDDCR_CPU0_P1_IMON3")
	)
	(segment
		(start 100.613972 -179.793138)
		(end 100.613972 -179.417218)
		(width 0.2286)
		(layer "F.Cu")
		(net "PVDDCR_CPU0_P1_IMON3")
	)
	(segment
		(start 101.051106 -178.872642)
		(end 101.039422 -178.872642)
		(width 0.2286)
		(layer "F.Cu")
		(net "PVDDCR_CPU0_P1_IMON3")
	)
	(via
		(at 101.039422 -178.872642)
		(size 0.508)
		(drill 0.254)
		(layers "F.Cu" "B.Cu")
		(net "PVDDCR_CPU0_P1_IMON3")
	)
	(via
		(at 94.863158 -150.707852)
		(size 0.508)
		(drill 0.254)
		(layers "F.Cu" "B.Cu")
		(net "PVDDCR_CPU0_P1_IMON3")
	)
	(segment
		(start 94.658434 -148.929852)
		(end 95.07093 -148.517356)
		(width 0.1778)
		(layer "B.Cu")
		(net "PVDDCR_CPU0_P1_IMON3")
	)
	(segment
		(start 95.07093 -148.517356)
		(end 95.07093 -147.633436)
		(width 0.1778)
		(layer "B.Cu")
		(net "PVDDCR_CPU0_P1_IMON3")
	)
	(segment
		(start 94.863158 -150.707852)
		(end 94.658434 -150.503128)
		(width 0.1778)
		(layer "B.Cu")
		(net "PVDDCR_CPU0_P1_IMON3")
	)
	(segment
		(start 94.658434 -150.503128)
		(end 94.658434 -148.929852)
		(width 0.1778)
		(layer "B.Cu")
		(net "PVDDCR_CPU0_P1_IMON3")
	)
	(segment
		(start 95.13824 -150.982934)
		(end 95.13824 -154.594052)
		(width 0.254)
		(layer "In4.Cu")
		(net "PVDDCR_CPU0_P1_IMON3")
	)
	(segment
		(start 99.382834 -175.058578)
		(end 101.639878 -177.315622)
		(width 0.254)
		(layer "In4.Cu")
		(net "PVDDCR_CPU0_P1_IMON3")
	)
	(segment
		(start 101.15677 -178.872642)
		(end 101.039422 -178.872642)
		(width 0.254)
		(layer "In4.Cu")
		(net "PVDDCR_CPU0_P1_IMON3")
	)
	(segment
		(start 95.13824 -154.594052)
		(end 99.382834 -158.838646)
		(width 0.254)
		(layer "In4.Cu")
		(net "PVDDCR_CPU0_P1_IMON3")
	)
	(segment
		(start 99.382834 -158.838646)
		(end 99.382834 -175.058578)
		(width 0.254)
		(layer "In4.Cu")
		(net "PVDDCR_CPU0_P1_IMON3")
	)
	(segment
		(start 101.639878 -178.389534)
		(end 101.15677 -178.872642)
		(width 0.254)
		(layer "In4.Cu")
		(net "PVDDCR_CPU0_P1_IMON3")
	)
	(segment
		(start 101.639878 -177.315622)
		(end 101.639878 -178.389534)
		(width 0.254)
		(layer "In4.Cu")
		(net "PVDDCR_CPU0_P1_IMON3")
	)
	(segment
		(start 94.863158 -150.707852)
		(end 95.13824 -150.982934)
		(width 0.254)
		(layer "In4.Cu")
		(net "PVDDCR_CPU0_P1_IMON3")
	)
	(segment
		(start 92.221812 -179.398676)
		(end 92.221812 -179.775866)
		(width 0.2286)
		(layer "F.Cu")
		(net "PVDDCR_CPU0_P1_IMON2")
	)
	(segment
		(start 92.647262 -178.85537)
		(end 92.647262 -178.973226)
		(width 0.2286)
		(layer "F.Cu")
		(net "PVDDCR_CPU0_P1_IMON2")
	)
	(segment
		(start 92.647262 -178.973226)
		(end 92.221812 -179.398676)
		(width 0.2286)
		(layer "F.Cu")
		(net "PVDDCR_CPU0_P1_IMON2")
	)
	(via
		(at 92.647262 -178.85537)
		(size 0.508)
		(drill 0.254)
		(layers "F.Cu" "B.Cu")
		(net "PVDDCR_CPU0_P1_IMON2")
	)
	(via
		(at 93.794834 -152.435052)
		(size 0.508)
		(drill 0.254)
		(layers "F.Cu" "B.Cu")
		(net "PVDDCR_CPU0_P1_IMON2")
	)
	(segment
		(start 94.271592 -149.583648)
		(end 94.271592 -149.088856)
		(width 0.1778)
		(layer "B.Cu")
		(net "PVDDCR_CPU0_P1_IMON2")
	)
	(segment
		(start 93.794834 -150.276052)
		(end 94.26702 -149.803866)
		(width 0.1778)
		(layer "B.Cu")
		(net "PVDDCR_CPU0_P1_IMON2")
	)
	(segment
		(start 94.26702 -149.58822)
		(end 94.271592 -149.583648)
		(width 0.1778)
		(layer "B.Cu")
		(net "PVDDCR_CPU0_P1_IMON2")
	)
	(segment
		(start 94.26702 -148.762212)
		(end 94.67088 -148.358352)
		(width 0.1778)
		(layer "B.Cu")
		(net "PVDDCR_CPU0_P1_IMON2")
	)
	(segment
		(start 94.271592 -149.088856)
		(end 94.26702 -149.084284)
		(width 0.1778)
		(layer "B.Cu")
		(net "PVDDCR_CPU0_P1_IMON2")
	)
	(segment
		(start 94.26702 -149.084284)
		(end 94.26702 -148.762212)
		(width 0.1778)
		(layer "B.Cu")
		(net "PVDDCR_CPU0_P1_IMON2")
	)
	(segment
		(start 94.67088 -148.358352)
		(end 94.67088 -147.633436)
		(width 0.1778)
		(layer "B.Cu")
		(net "PVDDCR_CPU0_P1_IMON2")
	)
	(segment
		(start 94.26702 -149.803866)
		(end 94.26702 -149.58822)
		(width 0.1778)
		(layer "B.Cu")
		(net "PVDDCR_CPU0_P1_IMON2")
	)
	(segment
		(start 93.794834 -152.435052)
		(end 93.794834 -150.276052)
		(width 0.1778)
		(layer "B.Cu")
		(net "PVDDCR_CPU0_P1_IMON2")
	)
	(segment
		(start 93.257878 -178.362102)
		(end 92.76461 -178.85537)
		(width 0.254)
		(layer "In4.Cu")
		(net "PVDDCR_CPU0_P1_IMON2")
	)
	(segment
		(start 93.794834 -152.435052)
		(end 93.794834 -157.230064)
		(width 0.254)
		(layer "In4.Cu")
		(net "PVDDCR_CPU0_P1_IMON2")
	)
	(segment
		(start 96.715834 -172.853096)
		(end 93.257878 -176.311052)
		(width 0.254)
		(layer "In4.Cu")
		(net "PVDDCR_CPU0_P1_IMON2")
	)
	(segment
		(start 92.76461 -178.85537)
		(end 92.647262 -178.85537)
		(width 0.254)
		(layer "In4.Cu")
		(net "PVDDCR_CPU0_P1_IMON2")
	)
	(segment
		(start 96.715834 -160.151064)
		(end 96.715834 -172.853096)
		(width 0.254)
		(layer "In4.Cu")
		(net "PVDDCR_CPU0_P1_IMON2")
	)
	(segment
		(start 93.794834 -157.230064)
		(end 96.715834 -160.151064)
		(width 0.254)
		(layer "In4.Cu")
		(net "PVDDCR_CPU0_P1_IMON2")
	)
	(segment
		(start 93.257878 -176.311052)
		(end 93.257878 -178.362102)
		(width 0.254)
		(layer "In4.Cu")
		(net "PVDDCR_CPU0_P1_IMON2")
	)
	(segment
		(start 83.824572 -179.843938)
		(end 83.824572 -179.490116)
		(width 0.2286)
		(layer "F.Cu")
		(net "PVDDCR_CPU0_P1_IMON1")
	)
	(segment
		(start 84.250022 -179.064666)
		(end 84.250022 -178.923442)
		(width 0.2286)
		(layer "F.Cu")
		(net "PVDDCR_CPU0_P1_IMON1")
	)
	(segment
		(start 83.824572 -179.490116)
		(end 84.250022 -179.064666)
		(width 0.2286)
		(layer "F.Cu")
		(net "PVDDCR_CPU0_P1_IMON1")
	)
	(via
		(at 93.674692 -149.336252)
		(size 0.762)
		(drill 0.254)
		(layers "F.Cu" "B.Cu")
		(net "PVDDCR_CPU0_P1_IMON1")
	)
	(via
		(at 84.250022 -178.923442)
		(size 0.508)
		(drill 0.254)
		(layers "F.Cu" "B.Cu")
		(net "PVDDCR_CPU0_P1_IMON1")
	)
	(segment
		(start 93.674692 -148.815044)
		(end 94.27083 -148.218906)
		(width 0.1778)
		(layer "B.Cu")
		(net "PVDDCR_CPU0_P1_IMON1")
	)
	(segment
		(start 93.674692 -149.336252)
		(end 93.674692 -148.815044)
		(width 0.1778)
		(layer "B.Cu")
		(net "PVDDCR_CPU0_P1_IMON1")
	)
	(segment
		(start 94.27083 -148.218906)
		(end 94.27083 -147.633436)
		(width 0.1778)
		(layer "B.Cu")
		(net "PVDDCR_CPU0_P1_IMON1")
	)
	(segment
		(start 84.36737 -178.923442)
		(end 84.250022 -178.923442)
		(width 0.254)
		(layer "In4.Cu")
		(net "PVDDCR_CPU0_P1_IMON1")
	)
	(segment
		(start 80.969866 -173.48581)
		(end 84.850478 -177.366422)
		(width 0.254)
		(layer "In4.Cu")
		(net "PVDDCR_CPU0_P1_IMON1")
	)
	(segment
		(start 84.850478 -177.366422)
		(end 84.850478 -178.440334)
		(width 0.254)
		(layer "In4.Cu")
		(net "PVDDCR_CPU0_P1_IMON1")
	)
	(segment
		(start 80.969866 -155.173934)
		(end 80.969866 -173.48581)
		(width 0.254)
		(layer "In4.Cu")
		(net "PVDDCR_CPU0_P1_IMON1")
	)
	(segment
		(start 93.674692 -149.336252)
		(end 93.192092 -149.818852)
		(width 0.254)
		(layer "In4.Cu")
		(net "PVDDCR_CPU0_P1_IMON1")
	)
	(segment
		(start 91.166188 -149.818852)
		(end 89.411048 -151.573992)
		(width 0.254)
		(layer "In4.Cu")
		(net "PVDDCR_CPU0_P1_IMON1")
	)
	(segment
		(start 84.569808 -151.573992)
		(end 80.969866 -155.173934)
		(width 0.254)
		(layer "In4.Cu")
		(net "PVDDCR_CPU0_P1_IMON1")
	)
	(segment
		(start 84.850478 -178.440334)
		(end 84.36737 -178.923442)
		(width 0.254)
		(layer "In4.Cu")
		(net "PVDDCR_CPU0_P1_IMON1")
	)
	(segment
		(start 93.192092 -149.818852)
		(end 91.166188 -149.818852)
		(width 0.254)
		(layer "In4.Cu")
		(net "PVDDCR_CPU0_P1_IMON1")
	)
	(segment
		(start 89.411048 -151.573992)
		(end 84.569808 -151.573992)
		(width 0.254)
		(layer "In4.Cu")
		(net "PVDDCR_CPU0_P1_IMON1")
	)
	(segment
		(start 90.609928 -142.85341)
		(end 90.609928 -142.874492)
		(width 0.10668)
		(layer "F.Cu")
		(net "PVDDCR_CPU0_P1_EN_R")
	)
	(segment
		(start 90.609928 -142.874492)
		(end 90.966544 -143.231108)
		(width 0.10668)
		(layer "F.Cu")
		(net "PVDDCR_CPU0_P1_EN_R")
	)
	(segment
		(start 90.966544 -143.231108)
		(end 91.275408 -143.231108)
		(width 0.10668)
		(layer "F.Cu")
		(net "PVDDCR_CPU0_P1_EN_R")
	)
	(segment
		(start 91.275408 -143.231108)
		(end 91.9988 -143.9545)
		(width 0.10668)
		(layer "F.Cu")
		(net "PVDDCR_CPU0_P1_EN_R")
	)
	(via
		(at 91.9988 -143.9545)
		(size 0.762)
		(drill 0.254)
		(layers "F.Cu" "B.Cu")
		(net "PVDDCR_CPU0_P1_EN_R")
	)
	(segment
		(start 91.9988 -143.981932)
		(end 92.17533 -144.158462)
		(width 0.10668)
		(layer "B.Cu")
		(net "PVDDCR_CPU0_P1_EN_R")
	)
	(segment
		(start 90.89771 -142.85341)
		(end 91.9988 -143.9545)
		(width 0.10668)
		(layer "B.Cu")
		(net "PVDDCR_CPU0_P1_EN_R")
	)
	(segment
		(start 92.17533 -144.158462)
		(end 92.795852 -144.158462)
		(width 0.10668)
		(layer "B.Cu")
		(net "PVDDCR_CPU0_P1_EN_R")
	)
	(segment
		(start 91.9988 -143.9545)
		(end 91.9988 -143.981932)
		(width 0.10668)
		(layer "B.Cu")
		(net "PVDDCR_CPU0_P1_EN_R")
	)
	(segment
		(start 90.609928 -142.85341)
		(end 90.89771 -142.85341)
		(width 0.10668)
		(layer "B.Cu")
		(net "PVDDCR_CPU0_P1_EN_R")
	)
	(segment
		(start 88.798654 -142.318232)
		(end 87.762334 -143.354552)
		(width 0.10668)
		(layer "F.Cu")
		(net "PVDDCR_CPU0_P1_EN")
	)
	(segment
		(start 89.662254 -142.318232)
		(end 88.798654 -142.318232)
		(width 0.10668)
		(layer "F.Cu")
		(net "PVDDCR_CPU0_P1_EN")
	)
	(segment
		(start 89.809828 -142.465806)
		(end 89.662254 -142.318232)
		(width 0.10668)
		(layer "F.Cu")
		(net "PVDDCR_CPU0_P1_EN")
	)
	(segment
		(start 89.809828 -142.85341)
		(end 89.809828 -142.465806)
		(width 0.10668)
		(layer "F.Cu")
		(net "PVDDCR_CPU0_P1_EN")
	)
	(segment
		(start 201.339958 -107.529376)
		(end 202.255882 -107.529376)
		(width 0.10668)
		(layer "F.Cu")
		(net "PVDDCR_CPU0_P1_EN")
	)
	(via
		(at 202.255882 -107.529376)
		(size 0.508)
		(drill 0.254)
		(layers "F.Cu" "B.Cu")
		(net "PVDDCR_CPU0_P1_EN")
	)
	(via
		(at 149.308566 -113.065052)
		(size 0.508)
		(drill 0.254)
		(layers "F.Cu" "B.Cu")
		(net "PVDDCR_CPU0_P1_EN")
	)
	(via
		(at 161.55797 -134.26567)
		(size 0.508)
		(drill 0.254)
		(layers "F.Cu" "B.Cu")
		(net "PVDDCR_CPU0_P1_EN")
	)
	(via
		(at 87.762334 -143.354552)
		(size 0.508)
		(drill 0.254)
		(layers "F.Cu" "B.Cu")
		(net "PVDDCR_CPU0_P1_EN")
	)
	(segment
		(start 214.252556 -101.371908)
		(end 216.384886 -101.371908)
		(width 0.10668)
		(layer "B.Cu")
		(net "PVDDCR_CPU0_P1_EN")
	)
	(segment
		(start 93.55455 -136.981692)
		(end 94.82582 -138.252962)
		(width 0.10668)
		(layer "B.Cu")
		(net "PVDDCR_CPU0_P1_EN")
	)
	(segment
		(start 154.739086 -135.062468)
		(end 160.761172 -135.062468)
		(width 0.10668)
		(layer "B.Cu")
		(net "PVDDCR_CPU0_P1_EN")
	)
	(segment
		(start 216.77122 -108.074714)
		(end 209.188304 -108.074714)
		(width 0.10668)
		(layer "B.Cu")
		(net "PVDDCR_CPU0_P1_EN")
	)
	(segment
		(start 164.160708 -94.615508)
		(end 168.318688 -90.457528)
		(width 0.10668)
		(layer "B.Cu")
		(net "PVDDCR_CPU0_P1_EN")
	)
	(segment
		(start 157.79115 -109.593126)
		(end 158.440374 -109.593126)
		(width 0.10668)
		(layer "B.Cu")
		(net "PVDDCR_CPU0_P1_EN")
	)
	(segment
		(start 149.34565 -113.424462)
		(end 149.764242 -113.843054)
		(width 0.10668)
		(layer "B.Cu")
		(net "PVDDCR_CPU0_P1_EN")
	)
	(segment
		(start 88.320372 -136.981692)
		(end 93.55455 -136.981692)
		(width 0.10668)
		(layer "B.Cu")
		(net "PVDDCR_CPU0_P1_EN")
	)
	(segment
		(start 96.425004 -137.595102)
		(end 103.708454 -137.595102)
		(width 0.10668)
		(layer "B.Cu")
		(net "PVDDCR_CPU0_P1_EN")
	)
	(segment
		(start 149.764242 -113.843054)
		(end 153.541222 -113.843054)
		(width 0.10668)
		(layer "B.Cu")
		(net "PVDDCR_CPU0_P1_EN")
	)
	(segment
		(start 216.384886 -101.371908)
		(end 217.89771 -102.884732)
		(width 0.10668)
		(layer "B.Cu")
		(net "PVDDCR_CPU0_P1_EN")
	)
	(segment
		(start 210.768692 -94.622366)
		(end 210.768692 -97.888044)
		(width 0.10668)
		(layer "B.Cu")
		(net "PVDDCR_CPU0_P1_EN")
	)
	(segment
		(start 217.89771 -106.948224)
		(end 216.77122 -108.074714)
		(width 0.10668)
		(layer "B.Cu")
		(net "PVDDCR_CPU0_P1_EN")
	)
	(segment
		(start 87.762334 -143.354552)
		(end 87.051134 -142.643352)
		(width 0.10668)
		(layer "B.Cu")
		(net "PVDDCR_CPU0_P1_EN")
	)
	(segment
		(start 158.440374 -109.593126)
		(end 160.998154 -107.035346)
		(width 0.10668)
		(layer "B.Cu")
		(net "PVDDCR_CPU0_P1_EN")
	)
	(segment
		(start 168.318688 -90.457528)
		(end 188.33211 -90.457528)
		(width 0.10668)
		(layer "B.Cu")
		(net "PVDDCR_CPU0_P1_EN")
	)
	(segment
		(start 103.708454 -137.595102)
		(end 104.664764 -136.638792)
		(width 0.10668)
		(layer "B.Cu")
		(net "PVDDCR_CPU0_P1_EN")
	)
	(segment
		(start 153.541222 -113.843054)
		(end 157.79115 -109.593126)
		(width 0.10668)
		(layer "B.Cu")
		(net "PVDDCR_CPU0_P1_EN")
	)
	(segment
		(start 207.610964 -107.474004)
		(end 206.970884 -106.833924)
		(width 0.10668)
		(layer "B.Cu")
		(net "PVDDCR_CPU0_P1_EN")
	)
	(segment
		(start 209.188304 -108.074714)
		(end 208.587594 -107.474004)
		(width 0.10668)
		(layer "B.Cu")
		(net "PVDDCR_CPU0_P1_EN")
	)
	(segment
		(start 104.664764 -136.638792)
		(end 153.162762 -136.638792)
		(width 0.10668)
		(layer "B.Cu")
		(net "PVDDCR_CPU0_P1_EN")
	)
	(segment
		(start 205.054708 -88.908382)
		(end 210.768692 -94.622366)
		(width 0.10668)
		(layer "B.Cu")
		(net "PVDDCR_CPU0_P1_EN")
	)
	(segment
		(start 164.160708 -104.502712)
		(end 164.160708 -94.615508)
		(width 0.10668)
		(layer "B.Cu")
		(net "PVDDCR_CPU0_P1_EN")
	)
	(segment
		(start 153.162762 -136.638792)
		(end 154.739086 -135.062468)
		(width 0.10668)
		(layer "B.Cu")
		(net "PVDDCR_CPU0_P1_EN")
	)
	(segment
		(start 206.970884 -106.833924)
		(end 205.971902 -106.833924)
		(width 0.10668)
		(layer "B.Cu")
		(net "PVDDCR_CPU0_P1_EN")
	)
	(segment
		(start 161.628074 -107.035346)
		(end 164.160708 -104.502712)
		(width 0.10668)
		(layer "B.Cu")
		(net "PVDDCR_CPU0_P1_EN")
	)
	(segment
		(start 87.051134 -142.643352)
		(end 87.051134 -138.25093)
		(width 0.10668)
		(layer "B.Cu")
		(net "PVDDCR_CPU0_P1_EN")
	)
	(segment
		(start 149.308566 -113.065052)
		(end 149.34565 -113.102136)
		(width 0.10668)
		(layer "B.Cu")
		(net "PVDDCR_CPU0_P1_EN")
	)
	(segment
		(start 217.89771 -102.884732)
		(end 217.89771 -106.948224)
		(width 0.10668)
		(layer "B.Cu")
		(net "PVDDCR_CPU0_P1_EN")
	)
	(segment
		(start 94.82582 -138.252962)
		(end 95.767144 -138.252962)
		(width 0.10668)
		(layer "B.Cu")
		(net "PVDDCR_CPU0_P1_EN")
	)
	(segment
		(start 160.761172 -135.062468)
		(end 161.55797 -134.26567)
		(width 0.10668)
		(layer "B.Cu")
		(net "PVDDCR_CPU0_P1_EN")
	)
	(segment
		(start 205.27645 -107.529376)
		(end 202.255882 -107.529376)
		(width 0.10668)
		(layer "B.Cu")
		(net "PVDDCR_CPU0_P1_EN")
	)
	(segment
		(start 87.051134 -138.25093)
		(end 88.320372 -136.981692)
		(width 0.10668)
		(layer "B.Cu")
		(net "PVDDCR_CPU0_P1_EN")
	)
	(segment
		(start 210.768692 -97.888044)
		(end 214.252556 -101.371908)
		(width 0.10668)
		(layer "B.Cu")
		(net "PVDDCR_CPU0_P1_EN")
	)
	(segment
		(start 189.881256 -88.908382)
		(end 205.054708 -88.908382)
		(width 0.10668)
		(layer "B.Cu")
		(net "PVDDCR_CPU0_P1_EN")
	)
	(segment
		(start 160.998154 -107.035346)
		(end 161.628074 -107.035346)
		(width 0.10668)
		(layer "B.Cu")
		(net "PVDDCR_CPU0_P1_EN")
	)
	(segment
		(start 149.34565 -113.102136)
		(end 149.34565 -113.424462)
		(width 0.10668)
		(layer "B.Cu")
		(net "PVDDCR_CPU0_P1_EN")
	)
	(segment
		(start 188.33211 -90.457528)
		(end 189.881256 -88.908382)
		(width 0.10668)
		(layer "B.Cu")
		(net "PVDDCR_CPU0_P1_EN")
	)
	(segment
		(start 205.971902 -106.833924)
		(end 205.27645 -107.529376)
		(width 0.10668)
		(layer "B.Cu")
		(net "PVDDCR_CPU0_P1_EN")
	)
	(segment
		(start 95.767144 -138.252962)
		(end 96.425004 -137.595102)
		(width 0.10668)
		(layer "B.Cu")
		(net "PVDDCR_CPU0_P1_EN")
	)
	(segment
		(start 208.587594 -107.474004)
		(end 207.610964 -107.474004)
		(width 0.10668)
		(layer "B.Cu")
		(net "PVDDCR_CPU0_P1_EN")
	)
	(segment
		(start 151.107902 -118.985284)
		(end 151.467312 -118.625874)
		(width 0.11684)
		(layer "In11.Cu")
		(net "PVDDCR_CPU0_P1_EN")
	)
	(segment
		(start 157.8229 -128.8923)
		(end 156.603446 -128.8923)
		(width 0.11684)
		(layer "In11.Cu")
		(net "PVDDCR_CPU0_P1_EN")
	)
	(segment
		(start 151.467312 -116.826792)
		(end 149.331172 -114.690652)
		(width 0.11684)
		(layer "In11.Cu")
		(net "PVDDCR_CPU0_P1_EN")
	)
	(segment
		(start 149.331172 -113.087658)
		(end 149.308566 -113.065052)
		(width 0.11684)
		(layer "In11.Cu")
		(net "PVDDCR_CPU0_P1_EN")
	)
	(segment
		(start 158.4706 -129.54)
		(end 157.8229 -128.8923)
		(width 0.11684)
		(layer "In11.Cu")
		(net "PVDDCR_CPU0_P1_EN")
	)
	(segment
		(start 156.603446 -128.8923)
		(end 151.107902 -123.396756)
		(width 0.11684)
		(layer "In11.Cu")
		(net "PVDDCR_CPU0_P1_EN")
	)
	(segment
		(start 161.55797 -133.846824)
		(end 158.4706 -130.759454)
		(width 0.11684)
		(layer "In11.Cu")
		(net "PVDDCR_CPU0_P1_EN")
	)
	(segment
		(start 158.4706 -130.759454)
		(end 158.4706 -129.54)
		(width 0.11684)
		(layer "In11.Cu")
		(net "PVDDCR_CPU0_P1_EN")
	)
	(segment
		(start 149.331172 -114.690652)
		(end 149.331172 -113.087658)
		(width 0.11684)
		(layer "In11.Cu")
		(net "PVDDCR_CPU0_P1_EN")
	)
	(segment
		(start 151.107902 -123.396756)
		(end 151.107902 -118.985284)
		(width 0.11684)
		(layer "In11.Cu")
		(net "PVDDCR_CPU0_P1_EN")
	)
	(segment
		(start 151.467312 -118.625874)
		(end 151.467312 -116.826792)
		(width 0.11684)
		(layer "In11.Cu")
		(net "PVDDCR_CPU0_P1_EN")
	)
	(segment
		(start 161.55797 -134.26567)
		(end 161.55797 -133.846824)
		(width 0.11684)
		(layer "In11.Cu")
		(net "PVDDCR_CPU0_P1_EN")
	)
	(segment
		(start 123.05792 -250.420378)
		(end 123.524772 -250.15444)
		(width 0.350012)
		(layer "F.Cu")
		(net "PVDDCR_CPU0_P1")
	)
	(segment
		(start 103.787956 -236.650276)
		(end 103.321104 -236.384338)
		(width 0.350012)
		(layer "F.Cu")
		(net "PVDDCR_CPU0_P1")
	)
	(segment
		(start 100.497894 -227.740464)
		(end 100.031042 -227.474526)
		(width 0.350012)
		(layer "F.Cu")
		(net "PVDDCR_CPU0_P1")
	)
	(segment
		(start 109.427772 -231.79024)
		(end 108.961174 -231.524302)
		(width 0.350012)
		(layer "F.Cu")
		(net "PVDDCR_CPU0_P1")
	)
	(segment
		(start 113.187988 -235.030264)
		(end 113.65484 -234.764326)
		(width 0.350012)
		(layer "F.Cu")
		(net "PVDDCR_CPU0_P1")
	)
	(segment
		(start 101.437948 -250.420378)
		(end 100.971096 -250.15444)
		(width 0.350012)
		(layer "F.Cu")
		(net "PVDDCR_CPU0_P1")
	)
	(segment
		(start 122.117866 -234.220258)
		(end 122.584718 -233.95432)
		(width 0.350012)
		(layer "F.Cu")
		(net "PVDDCR_CPU0_P1")
	)
	(segment
		(start 122.117866 -242.320318)
		(end 122.584718 -242.05438)
		(width 0.350012)
		(layer "F.Cu")
		(net "PVDDCR_CPU0_P1")
	)
	(segment
		(start 113.187988 -243.130324)
		(end 113.65484 -242.864386)
		(width 0.350012)
		(layer "F.Cu")
		(net "PVDDCR_CPU0_P1")
	)
	(segment
		(start 123.52782 -249.610372)
		(end 123.994672 -249.344434)
		(width 0.350012)
		(layer "F.Cu")
		(net "PVDDCR_CPU0_P1")
	)
	(segment
		(start 125.877828 -230.980234)
		(end 126.34468 -230.71455)
		(width 0.350012)
		(layer "F.Cu")
		(net "PVDDCR_CPU0_P1")
	)
	(segment
		(start 107.078018 -239.080294)
		(end 106.611166 -238.814356)
		(width 0.350012)
		(layer "F.Cu")
		(net "PVDDCR_CPU0_P1")
	)
	(segment
		(start 119.767858 -249.610372)
		(end 120.23471 -249.344434)
		(width 0.350012)
		(layer "F.Cu")
		(net "PVDDCR_CPU0_P1")
	)
	(segment
		(start 123.05792 -242.320318)
		(end 123.524772 -242.05438)
		(width 0.350012)
		(layer "F.Cu")
		(net "PVDDCR_CPU0_P1")
	)
	(segment
		(start 105.19791 -226.120452)
		(end 104.731058 -225.854514)
		(width 0.350012)
		(layer "F.Cu")
		(net "PVDDCR_CPU0_P1")
	)
	(segment
		(start 104.72801 -236.650276)
		(end 104.261158 -236.384338)
		(width 0.350012)
		(layer "F.Cu")
		(net "PVDDCR_CPU0_P1")
	)
	(segment
		(start 123.997974 -226.120452)
		(end 124.464826 -225.854514)
		(width 0.350012)
		(layer "F.Cu")
		(net "PVDDCR_CPU0_P1")
	)
	(segment
		(start 103.317802 -250.420378)
		(end 102.85095 -250.15444)
		(width 0.350012)
		(layer "F.Cu")
		(net "PVDDCR_CPU0_P1")
	)
	(segment
		(start 124.937774 -227.740464)
		(end 125.404626 -227.474526)
		(width 0.350012)
		(layer "F.Cu")
		(net "PVDDCR_CPU0_P1")
	)
	(segment
		(start 102.847902 -225.310446)
		(end 102.38105 -225.044508)
		(width 0.350012)
		(layer "F.Cu")
		(net "PVDDCR_CPU0_P1")
	)
	(segment
		(start 108.487972 -249.610372)
		(end 108.02112 -249.344434)
		(width 0.350012)
		(layer "F.Cu")
		(net "PVDDCR_CPU0_P1")
	)
	(segment
		(start 119.767858 -236.650276)
		(end 120.23471 -236.384338)
		(width 0.350012)
		(layer "F.Cu")
		(net "PVDDCR_CPU0_P1")
	)
	(segment
		(start 117.41785 -230.980234)
		(end 117.884702 -230.71455)
		(width 0.350012)
		(layer "F.Cu")
		(net "PVDDCR_CPU0_P1")
	)
	(segment
		(start 120.238012 -230.980234)
		(end 120.70461 -230.71455)
		(width 0.350012)
		(layer "F.Cu")
		(net "PVDDCR_CPU0_P1")
	)
	(segment
		(start 114.127788 -243.130324)
		(end 114.59464 -242.864386)
		(width 0.350012)
		(layer "F.Cu")
		(net "PVDDCR_CPU0_P1")
	)
	(segment
		(start 116.477796 -227.740464)
		(end 116.944648 -227.474526)
		(width 0.350012)
		(layer "F.Cu")
		(net "PVDDCR_CPU0_P1")
	)
	(segment
		(start 116.007896 -236.650276)
		(end 116.474748 -236.384338)
		(width 0.350012)
		(layer "F.Cu")
		(net "PVDDCR_CPU0_P1")
	)
	(segment
		(start 102.378002 -226.120452)
		(end 101.91115 -225.854514)
		(width 0.350012)
		(layer "F.Cu")
		(net "PVDDCR_CPU0_P1")
	)
	(segment
		(start 100.497894 -242.320318)
		(end 100.031042 -242.05438)
		(width 0.350012)
		(layer "F.Cu")
		(net "PVDDCR_CPU0_P1")
	)
	(segment
		(start 98.617786 -248.800366)
		(end 98.150934 -248.534428)
		(width 0.350012)
		(layer "F.Cu")
		(net "PVDDCR_CPU0_P1")
	)
	(segment
		(start 104.257856 -242.320318)
		(end 103.791004 -242.05438)
		(width 0.350012)
		(layer "F.Cu")
		(net "PVDDCR_CPU0_P1")
	)
	(segment
		(start 100.497894 -245.560342)
		(end 100.031042 -245.294404)
		(width 0.350012)
		(layer "F.Cu")
		(net "PVDDCR_CPU0_P1")
	)
	(segment
		(start 119.297958 -248.800366)
		(end 119.76481 -248.534428)
		(width 0.350012)
		(layer "F.Cu")
		(net "PVDDCR_CPU0_P1")
	)
	(segment
		(start 119.297958 -250.420378)
		(end 119.76481 -250.15444)
		(width 0.350012)
		(layer "F.Cu")
		(net "PVDDCR_CPU0_P1")
	)
	(segment
		(start 116.007896 -249.610372)
		(end 116.474748 -249.344434)
		(width 0.350012)
		(layer "F.Cu")
		(net "PVDDCR_CPU0_P1")
	)
	(segment
		(start 109.897926 -237.460282)
		(end 109.431074 -237.194344)
		(width 0.350012)
		(layer "F.Cu")
		(net "PVDDCR_CPU0_P1")
	)
	(segment
		(start 103.317802 -239.080294)
		(end 102.85095 -238.814356)
		(width 0.350012)
		(layer "F.Cu")
		(net "PVDDCR_CPU0_P1")
	)
	(segment
		(start 123.05792 -227.740464)
		(end 123.524772 -227.474526)
		(width 0.350012)
		(layer "F.Cu")
		(net "PVDDCR_CPU0_P1")
	)
	(segment
		(start 108.017818 -226.120452)
		(end 107.550966 -225.854514)
		(width 0.350012)
		(layer "F.Cu")
		(net "PVDDCR_CPU0_P1")
	)
	(segment
		(start 105.66781 -225.310446)
		(end 105.200958 -225.044508)
		(width 0.350012)
		(layer "F.Cu")
		(net "PVDDCR_CPU0_P1")
	)
	(segment
		(start 119.297958 -239.080294)
		(end 119.76481 -238.814356)
		(width 0.350012)
		(layer "F.Cu")
		(net "PVDDCR_CPU0_P1")
	)
	(segment
		(start 114.127788 -225.310446)
		(end 114.59464 -225.044508)
		(width 0.350012)
		(layer "F.Cu")
		(net "PVDDCR_CPU0_P1")
	)
	(segment
		(start 100.497894 -230.980234)
		(end 100.031042 -230.71455)
		(width 0.350012)
		(layer "F.Cu")
		(net "PVDDCR_CPU0_P1")
	)
	(segment
		(start 116.477796 -245.560342)
		(end 116.944648 -245.294404)
		(width 0.350012)
		(layer "F.Cu")
		(net "PVDDCR_CPU0_P1")
	)
	(segment
		(start 116.477796 -234.220258)
		(end 116.944648 -233.95432)
		(width 0.350012)
		(layer "F.Cu")
		(net "PVDDCR_CPU0_P1")
	)
	(segment
		(start 113.657888 -237.460282)
		(end 114.12474 -237.194344)
		(width 0.350012)
		(layer "F.Cu")
		(net "PVDDCR_CPU0_P1")
	)
	(segment
		(start 115.537996 -226.120452)
		(end 116.004848 -225.854514)
		(width 0.350012)
		(layer "F.Cu")
		(net "PVDDCR_CPU0_P1")
	)
	(segment
		(start 109.427772 -235.030264)
		(end 108.961174 -234.764326)
		(width 0.350012)
		(layer "F.Cu")
		(net "PVDDCR_CPU0_P1")
	)
	(segment
		(start 114.127788 -231.79024)
		(end 114.59464 -231.524302)
		(width 0.350012)
		(layer "F.Cu")
		(net "PVDDCR_CPU0_P1")
	)
	(segment
		(start 115.537996 -222.880428)
		(end 116.004848 -222.61449)
		(width 0.350012)
		(layer "F.Cu")
		(net "PVDDCR_CPU0_P1")
	)
	(segment
		(start 116.477796 -239.080294)
		(end 116.944648 -238.814356)
		(width 0.350012)
		(layer "F.Cu")
		(net "PVDDCR_CPU0_P1")
	)
	(segment
		(start 103.317802 -234.220258)
		(end 102.85095 -233.95432)
		(width 0.350012)
		(layer "F.Cu")
		(net "PVDDCR_CPU0_P1")
	)
	(segment
		(start 107.078018 -245.560342)
		(end 106.611166 -245.294404)
		(width 0.350012)
		(layer "F.Cu")
		(net "PVDDCR_CPU0_P1")
	)
	(segment
		(start 113.187988 -231.79024)
		(end 113.65484 -231.524302)
		(width 0.350012)
		(layer "F.Cu")
		(net "PVDDCR_CPU0_P1")
	)
	(segment
		(start 128.69799 -222.880428)
		(end 129.164842 -222.61449)
		(width 0.350012)
		(layer "F.Cu")
		(net "PVDDCR_CPU0_P1")
	)
	(segment
		(start 117.41785 -248.800366)
		(end 117.884702 -248.534428)
		(width 0.350012)
		(layer "F.Cu")
		(net "PVDDCR_CPU0_P1")
	)
	(segment
		(start 119.767858 -251.230384)
		(end 120.23471 -250.964446)
		(width 0.350012)
		(layer "F.Cu")
		(net "PVDDCR_CPU0_P1")
	)
	(segment
		(start 117.41785 -234.220258)
		(end 117.884702 -233.95432)
		(width 0.350012)
		(layer "F.Cu")
		(net "PVDDCR_CPU0_P1")
	)
	(segment
		(start 124.937774 -245.560342)
		(end 125.404626 -245.294404)
		(width 0.350012)
		(layer "F.Cu")
		(net "PVDDCR_CPU0_P1")
	)
	(segment
		(start 101.437948 -245.560342)
		(end 100.971096 -245.294404)
		(width 0.350012)
		(layer "F.Cu")
		(net "PVDDCR_CPU0_P1")
	)
	(segment
		(start 104.257856 -245.560342)
		(end 103.791004 -245.294404)
		(width 0.350012)
		(layer "F.Cu")
		(net "PVDDCR_CPU0_P1")
	)
	(segment
		(start 125.877828 -234.220258)
		(end 126.34468 -233.95432)
		(width 0.350012)
		(layer "F.Cu")
		(net "PVDDCR_CPU0_P1")
	)
	(segment
		(start 107.078018 -230.980234)
		(end 106.611166 -230.71455)
		(width 0.350012)
		(layer "F.Cu")
		(net "PVDDCR_CPU0_P1")
	)
	(segment
		(start 104.257856 -239.080294)
		(end 103.791004 -238.814356)
		(width 0.350012)
		(layer "F.Cu")
		(net "PVDDCR_CPU0_P1")
	)
	(segment
		(start 98.617786 -234.220258)
		(end 98.150934 -233.95432)
		(width 0.350012)
		(layer "F.Cu")
		(net "PVDDCR_CPU0_P1")
	)
	(segment
		(start 123.05792 -239.080294)
		(end 123.524772 -238.814356)
		(width 0.350012)
		(layer "F.Cu")
		(net "PVDDCR_CPU0_P1")
	)
	(segment
		(start 125.877828 -242.320318)
		(end 126.34468 -242.05438)
		(width 0.350012)
		(layer "F.Cu")
		(net "PVDDCR_CPU0_P1")
	)
	(segment
		(start 110.367826 -246.370348)
		(end 109.900974 -246.10441)
		(width 0.350012)
		(layer "F.Cu")
		(net "PVDDCR_CPU0_P1")
	)
	(segment
		(start 123.997974 -222.880428)
		(end 124.464826 -222.61449)
		(width 0.350012)
		(layer "F.Cu")
		(net "PVDDCR_CPU0_P1")
	)
	(segment
		(start 117.888004 -225.310446)
		(end 118.354856 -225.044508)
		(width 0.350012)
		(layer "F.Cu")
		(net "PVDDCR_CPU0_P1")
	)
	(segment
		(start 121.177812 -226.120452)
		(end 121.644664 -225.854514)
		(width 0.350012)
		(layer "F.Cu")
		(net "PVDDCR_CPU0_P1")
	)
	(segment
		(start 97.677986 -230.980234)
		(end 97.211134 -230.71455)
		(width 0.350012)
		(layer "F.Cu")
		(net "PVDDCR_CPU0_P1")
	)
	(segment
		(start 124.937774 -239.080294)
		(end 125.404626 -238.814356)
		(width 0.350012)
		(layer "F.Cu")
		(net "PVDDCR_CPU0_P1")
	)
	(segment
		(start 103.317802 -248.800366)
		(end 102.85095 -248.534428)
		(width 0.350012)
		(layer "F.Cu")
		(net "PVDDCR_CPU0_P1")
	)
	(segment
		(start 124.937774 -248.800366)
		(end 125.404626 -248.534428)
		(width 0.350012)
		(layer "F.Cu")
		(net "PVDDCR_CPU0_P1")
	)
	(segment
		(start 114.127788 -246.370348)
		(end 114.59464 -246.10441)
		(width 0.350012)
		(layer "F.Cu")
		(net "PVDDCR_CPU0_P1")
	)
	(segment
		(start 108.487972 -251.230384)
		(end 108.02112 -250.964446)
		(width 0.350012)
		(layer "F.Cu")
		(net "PVDDCR_CPU0_P1")
	)
	(segment
		(start 125.877828 -239.080294)
		(end 126.34468 -238.814356)
		(width 0.350012)
		(layer "F.Cu")
		(net "PVDDCR_CPU0_P1")
	)
	(segment
		(start 106.137964 -230.980234)
		(end 105.671112 -230.71455)
		(width 0.350012)
		(layer "F.Cu")
		(net "PVDDCR_CPU0_P1")
	)
	(segment
		(start 113.187988 -228.55047)
		(end 113.65484 -228.284532)
		(width 0.350012)
		(layer "F.Cu")
		(net "PVDDCR_CPU0_P1")
	)
	(segment
		(start 116.477796 -230.980234)
		(end 116.944648 -230.71455)
		(width 0.350012)
		(layer "F.Cu")
		(net "PVDDCR_CPU0_P1")
	)
	(segment
		(start 96.737932 -222.880428)
		(end 96.27108 -222.61449)
		(width 0.350012)
		(layer "F.Cu")
		(net "PVDDCR_CPU0_P1")
	)
	(segment
		(start 120.238012 -222.880428)
		(end 120.70461 -222.61449)
		(width 0.350012)
		(layer "F.Cu")
		(net "PVDDCR_CPU0_P1")
	)
	(segment
		(start 96.737932 -226.120452)
		(end 96.27108 -225.854514)
		(width 0.350012)
		(layer "F.Cu")
		(net "PVDDCR_CPU0_P1")
	)
	(segment
		(start 100.497894 -239.080294)
		(end 100.031042 -238.814356)
		(width 0.350012)
		(layer "F.Cu")
		(net "PVDDCR_CPU0_P1")
	)
	(segment
		(start 107.078018 -234.220258)
		(end 106.611166 -233.95432)
		(width 0.350012)
		(layer "F.Cu")
		(net "PVDDCR_CPU0_P1")
	)
	(segment
		(start 124.937774 -250.420378)
		(end 125.404626 -250.15444)
		(width 0.350012)
		(layer "F.Cu")
		(net "PVDDCR_CPU0_P1")
	)
	(segment
		(start 97.677986 -222.880428)
		(end 97.211134 -222.61449)
		(width 0.350012)
		(layer "F.Cu")
		(net "PVDDCR_CPU0_P1")
	)
	(segment
		(start 120.238012 -234.220258)
		(end 120.70461 -233.95432)
		(width 0.350012)
		(layer "F.Cu")
		(net "PVDDCR_CPU0_P1")
	)
	(segment
		(start 97.677986 -242.320318)
		(end 97.211134 -242.05438)
		(width 0.350012)
		(layer "F.Cu")
		(net "PVDDCR_CPU0_P1")
	)
	(segment
		(start 99.55784 -226.120452)
		(end 99.090988 -225.854514)
		(width 0.350012)
		(layer "F.Cu")
		(net "PVDDCR_CPU0_P1")
	)
	(segment
		(start 121.177812 -250.420378)
		(end 121.644664 -250.15444)
		(width 0.350012)
		(layer "F.Cu")
		(net "PVDDCR_CPU0_P1")
	)
	(segment
		(start 110.367826 -243.130324)
		(end 109.900974 -242.864386)
		(width 0.350012)
		(layer "F.Cu")
		(net "PVDDCR_CPU0_P1")
	)
	(segment
		(start 108.957872 -222.880428)
		(end 108.49102 -222.61449)
		(width 0.350012)
		(layer "F.Cu")
		(net "PVDDCR_CPU0_P1")
	)
	(segment
		(start 105.19791 -250.420378)
		(end 104.731058 -250.15444)
		(width 0.350012)
		(layer "F.Cu")
		(net "PVDDCR_CPU0_P1")
	)
	(segment
		(start 103.317802 -245.560342)
		(end 102.85095 -245.294404)
		(width 0.350012)
		(layer "F.Cu")
		(net "PVDDCR_CPU0_P1")
	)
	(segment
		(start 108.957872 -250.420378)
		(end 108.49102 -250.15444)
		(width 0.350012)
		(layer "F.Cu")
		(net "PVDDCR_CPU0_P1")
	)
	(segment
		(start 114.127788 -235.030264)
		(end 114.59464 -234.764326)
		(width 0.350012)
		(layer "F.Cu")
		(net "PVDDCR_CPU0_P1")
	)
	(segment
		(start 117.41785 -222.880428)
		(end 117.884702 -222.61449)
		(width 0.350012)
		(layer "F.Cu")
		(net "PVDDCR_CPU0_P1")
	)
	(segment
		(start 109.427772 -226.930458)
		(end 108.961174 -226.66452)
		(width 0.350012)
		(layer "F.Cu")
		(net "PVDDCR_CPU0_P1")
	)
	(segment
		(start 117.41785 -242.320318)
		(end 117.884702 -242.05438)
		(width 0.350012)
		(layer "F.Cu")
		(net "PVDDCR_CPU0_P1")
	)
	(segment
		(start 98.617786 -242.320318)
		(end 98.150934 -242.05438)
		(width 0.350012)
		(layer "F.Cu")
		(net "PVDDCR_CPU0_P1")
	)
	(segment
		(start 118.357904 -222.880428)
		(end 118.824756 -222.61449)
		(width 0.350012)
		(layer "F.Cu")
		(net "PVDDCR_CPU0_P1")
	)
	(segment
		(start 98.617786 -227.740464)
		(end 98.150934 -227.474526)
		(width 0.350012)
		(layer "F.Cu")
		(net "PVDDCR_CPU0_P1")
	)
	(segment
		(start 97.207832 -225.310446)
		(end 96.74098 -225.044508)
		(width 0.350012)
		(layer "F.Cu")
		(net "PVDDCR_CPU0_P1")
	)
	(segment
		(start 108.017818 -222.880428)
		(end 107.550966 -222.61449)
		(width 0.350012)
		(layer "F.Cu")
		(net "PVDDCR_CPU0_P1")
	)
	(segment
		(start 97.677986 -245.560342)
		(end 97.211134 -245.294404)
		(width 0.350012)
		(layer "F.Cu")
		(net "PVDDCR_CPU0_P1")
	)
	(segment
		(start 120.707912 -225.310446)
		(end 121.174764 -225.044508)
		(width 0.350012)
		(layer "F.Cu")
		(net "PVDDCR_CPU0_P1")
	)
	(segment
		(start 106.137964 -227.740464)
		(end 105.671112 -227.474526)
		(width 0.350012)
		(layer "F.Cu")
		(net "PVDDCR_CPU0_P1")
	)
	(segment
		(start 120.238012 -242.320318)
		(end 120.70461 -242.05438)
		(width 0.350012)
		(layer "F.Cu")
		(net "PVDDCR_CPU0_P1")
	)
	(segment
		(start 123.52782 -251.230384)
		(end 123.994672 -250.964446)
		(width 0.350012)
		(layer "F.Cu")
		(net "PVDDCR_CPU0_P1")
	)
	(segment
		(start 94.857824 -224.50044)
		(end 94.390972 -224.234502)
		(width 0.350012)
		(layer "F.Cu")
		(net "PVDDCR_CPU0_P1")
	)
	(segment
		(start 116.94795 -236.650276)
		(end 117.414802 -236.384338)
		(width 0.350012)
		(layer "F.Cu")
		(net "PVDDCR_CPU0_P1")
	)
	(segment
		(start 120.238012 -239.080294)
		(end 120.70461 -238.814356)
		(width 0.350012)
		(layer "F.Cu")
		(net "PVDDCR_CPU0_P1")
	)
	(segment
		(start 123.05792 -248.800366)
		(end 123.524772 -248.534428)
		(width 0.350012)
		(layer "F.Cu")
		(net "PVDDCR_CPU0_P1")
	)
	(segment
		(start 102.847902 -251.230384)
		(end 102.38105 -250.964446)
		(width 0.350012)
		(layer "F.Cu")
		(net "PVDDCR_CPU0_P1")
	)
	(segment
		(start 108.957872 -237.460282)
		(end 108.49102 -237.194344)
		(width 0.350012)
		(layer "F.Cu")
		(net "PVDDCR_CPU0_P1")
	)
	(segment
		(start 116.477796 -248.800366)
		(end 116.944648 -248.534428)
		(width 0.350012)
		(layer "F.Cu")
		(net "PVDDCR_CPU0_P1")
	)
	(segment
		(start 95.797878 -224.50044)
		(end 95.331026 -224.234502)
		(width 0.350012)
		(layer "F.Cu")
		(net "PVDDCR_CPU0_P1")
	)
	(segment
		(start 103.317802 -230.980234)
		(end 102.85095 -230.714296)
		(width 0.350012)
		(layer "F.Cu")
		(net "PVDDCR_CPU0_P1")
	)
	(segment
		(start 97.677986 -234.220258)
		(end 97.211134 -233.95432)
		(width 0.350012)
		(layer "F.Cu")
		(net "PVDDCR_CPU0_P1")
	)
	(segment
		(start 100.497894 -248.800366)
		(end 100.031042 -248.534428)
		(width 0.350012)
		(layer "F.Cu")
		(net "PVDDCR_CPU0_P1")
	)
	(segment
		(start 119.297958 -234.220258)
		(end 119.76481 -233.95432)
		(width 0.350012)
		(layer "F.Cu")
		(net "PVDDCR_CPU0_P1")
	)
	(segment
		(start 106.137964 -239.080294)
		(end 105.671112 -238.814356)
		(width 0.350012)
		(layer "F.Cu")
		(net "PVDDCR_CPU0_P1")
	)
	(segment
		(start 114.127788 -249.610372)
		(end 114.59464 -249.344434)
		(width 0.350012)
		(layer "F.Cu")
		(net "PVDDCR_CPU0_P1")
	)
	(segment
		(start 124.937774 -230.980234)
		(end 125.404626 -230.71455)
		(width 0.350012)
		(layer "F.Cu")
		(net "PVDDCR_CPU0_P1")
	)
	(segment
		(start 107.078018 -248.800366)
		(end 106.611166 -248.534428)
		(width 0.350012)
		(layer "F.Cu")
		(net "PVDDCR_CPU0_P1")
	)
	(segment
		(start 125.407928 -249.610372)
		(end 125.87478 -249.344434)
		(width 0.350012)
		(layer "F.Cu")
		(net "PVDDCR_CPU0_P1")
	)
	(segment
		(start 122.117866 -248.800366)
		(end 122.584718 -248.534428)
		(width 0.350012)
		(layer "F.Cu")
		(net "PVDDCR_CPU0_P1")
	)
	(segment
		(start 117.888004 -249.610372)
		(end 118.354856 -249.344434)
		(width 0.350012)
		(layer "F.Cu")
		(net "PVDDCR_CPU0_P1")
	)
	(segment
		(start 106.137964 -222.880428)
		(end 105.671112 -222.61449)
		(width 0.350012)
		(layer "F.Cu")
		(net "PVDDCR_CPU0_P1")
	)
	(segment
		(start 121.647966 -249.610372)
		(end 122.114818 -249.344434)
		(width 0.350012)
		(layer "F.Cu")
		(net "PVDDCR_CPU0_P1")
	)
	(segment
		(start 101.437948 -242.320318)
		(end 100.971096 -242.05438)
		(width 0.350012)
		(layer "F.Cu")
		(net "PVDDCR_CPU0_P1")
	)
	(segment
		(start 124.937774 -242.320318)
		(end 125.404626 -242.05438)
		(width 0.350012)
		(layer "F.Cu")
		(net "PVDDCR_CPU0_P1")
	)
	(segment
		(start 110.367826 -249.610372)
		(end 109.900974 -249.344434)
		(width 0.350012)
		(layer "F.Cu")
		(net "PVDDCR_CPU0_P1")
	)
	(segment
		(start 109.427772 -243.130324)
		(end 108.961174 -242.864386)
		(width 0.350012)
		(layer "F.Cu")
		(net "PVDDCR_CPU0_P1")
	)
	(segment
		(start 107.547918 -236.650276)
		(end 107.081066 -236.384338)
		(width 0.350012)
		(layer "F.Cu")
		(net "PVDDCR_CPU0_P1")
	)
	(segment
		(start 103.317802 -242.320318)
		(end 102.85095 -242.05438)
		(width 0.350012)
		(layer "F.Cu")
		(net "PVDDCR_CPU0_P1")
	)
	(segment
		(start 122.117866 -239.080294)
		(end 122.584718 -238.814356)
		(width 0.350012)
		(layer "F.Cu")
		(net "PVDDCR_CPU0_P1")
	)
	(segment
		(start 110.367826 -231.79024)
		(end 109.900974 -231.524302)
		(width 0.350012)
		(layer "F.Cu")
		(net "PVDDCR_CPU0_P1")
	)
	(segment
		(start 104.257856 -230.980234)
		(end 103.791004 -230.71455)
		(width 0.350012)
		(layer "F.Cu")
		(net "PVDDCR_CPU0_P1")
	)
	(segment
		(start 103.317802 -227.740464)
		(end 102.85095 -227.474526)
		(width 0.350012)
		(layer "F.Cu")
		(net "PVDDCR_CPU0_P1")
	)
	(segment
		(start 123.05792 -234.220258)
		(end 123.524772 -233.95432)
		(width 0.350012)
		(layer "F.Cu")
		(net "PVDDCR_CPU0_P1")
	)
	(segment
		(start 116.477796 -242.320318)
		(end 116.944648 -242.05438)
		(width 0.350012)
		(layer "F.Cu")
		(net "PVDDCR_CPU0_P1")
	)
	(segment
		(start 101.437948 -248.800366)
		(end 100.971096 -248.534428)
		(width 0.350012)
		(layer "F.Cu")
		(net "PVDDCR_CPU0_P1")
	)
	(segment
		(start 120.238012 -245.560342)
		(end 120.70461 -245.294404)
		(width 0.350012)
		(layer "F.Cu")
		(net "PVDDCR_CPU0_P1")
	)
	(segment
		(start 110.367826 -226.930458)
		(end 109.900974 -226.66452)
		(width 0.350012)
		(layer "F.Cu")
		(net "PVDDCR_CPU0_P1")
	)
	(segment
		(start 97.677986 -248.800366)
		(end 97.211134 -248.534428)
		(width 0.350012)
		(layer "F.Cu")
		(net "PVDDCR_CPU0_P1")
	)
	(segment
		(start 113.187988 -246.370348)
		(end 113.65484 -246.10441)
		(width 0.350012)
		(layer "F.Cu")
		(net "PVDDCR_CPU0_P1")
	)
	(segment
		(start 100.497894 -222.880428)
		(end 100.031042 -222.61449)
		(width 0.350012)
		(layer "F.Cu")
		(net "PVDDCR_CPU0_P1")
	)
	(segment
		(start 110.367826 -228.55047)
		(end 109.900974 -228.284532)
		(width 0.350012)
		(layer "F.Cu")
		(net "PVDDCR_CPU0_P1")
	)
	(segment
		(start 125.877828 -222.880428)
		(end 126.34468 -222.61449)
		(width 0.350012)
		(layer "F.Cu")
		(net "PVDDCR_CPU0_P1")
	)
	(segment
		(start 114.597942 -222.880428)
		(end 115.064794 -222.61449)
		(width 0.350012)
		(layer "F.Cu")
		(net "PVDDCR_CPU0_P1")
	)
	(segment
		(start 110.367826 -235.030264)
		(end 109.900974 -234.764326)
		(width 0.350012)
		(layer "F.Cu")
		(net "PVDDCR_CPU0_P1")
	)
	(segment
		(start 123.05792 -222.880428)
		(end 123.524772 -222.61449)
		(width 0.350012)
		(layer "F.Cu")
		(net "PVDDCR_CPU0_P1")
	)
	(segment
		(start 121.177812 -222.880428)
		(end 121.644664 -222.61449)
		(width 0.350012)
		(layer "F.Cu")
		(net "PVDDCR_CPU0_P1")
	)
	(segment
		(start 115.067842 -225.310446)
		(end 115.534694 -225.044508)
		(width 0.350012)
		(layer "F.Cu")
		(net "PVDDCR_CPU0_P1")
	)
	(segment
		(start 117.41785 -227.740464)
		(end 117.884702 -227.474526)
		(width 0.350012)
		(layer "F.Cu")
		(net "PVDDCR_CPU0_P1")
	)
	(segment
		(start 102.847902 -249.610372)
		(end 102.38105 -249.344434)
		(width 0.350012)
		(layer "F.Cu")
		(net "PVDDCR_CPU0_P1")
	)
	(segment
		(start 110.367826 -239.8903)
		(end 109.900974 -239.624362)
		(width 0.350012)
		(layer "F.Cu")
		(net "PVDDCR_CPU0_P1")
	)
	(segment
		(start 124.937774 -234.220258)
		(end 125.404626 -233.95432)
		(width 0.350012)
		(layer "F.Cu")
		(net "PVDDCR_CPU0_P1")
	)
	(segment
		(start 120.238012 -248.800366)
		(end 120.70461 -248.534428)
		(width 0.350012)
		(layer "F.Cu")
		(net "PVDDCR_CPU0_P1")
	)
	(segment
		(start 117.41785 -250.420378)
		(end 117.884702 -250.15444)
		(width 0.350012)
		(layer "F.Cu")
		(net "PVDDCR_CPU0_P1")
	)
	(segment
		(start 107.078018 -227.740464)
		(end 106.611166 -227.474526)
		(width 0.350012)
		(layer "F.Cu")
		(net "PVDDCR_CPU0_P1")
	)
	(segment
		(start 98.617786 -239.080294)
		(end 98.150934 -238.814356)
		(width 0.350012)
		(layer "F.Cu")
		(net "PVDDCR_CPU0_P1")
	)
	(segment
		(start 98.617786 -230.980234)
		(end 98.150934 -230.71455)
		(width 0.350012)
		(layer "F.Cu")
		(net "PVDDCR_CPU0_P1")
	)
	(segment
		(start 113.187988 -226.930458)
		(end 113.65484 -226.66452)
		(width 0.350012)
		(layer "F.Cu")
		(net "PVDDCR_CPU0_P1")
	)
	(segment
		(start 114.127788 -228.55047)
		(end 114.59464 -228.284532)
		(width 0.350012)
		(layer "F.Cu")
		(net "PVDDCR_CPU0_P1")
	)
	(segment
		(start 114.127788 -226.930458)
		(end 114.59464 -226.66452)
		(width 0.350012)
		(layer "F.Cu")
		(net "PVDDCR_CPU0_P1")
	)
	(segment
		(start 119.297958 -242.320318)
		(end 119.76481 -242.05438)
		(width 0.350012)
		(layer "F.Cu")
		(net "PVDDCR_CPU0_P1")
	)
	(segment
		(start 126.347982 -225.310446)
		(end 126.814834 -225.044508)
		(width 0.350012)
		(layer "F.Cu")
		(net "PVDDCR_CPU0_P1")
	)
	(segment
		(start 109.427772 -246.370348)
		(end 108.961174 -246.10441)
		(width 0.350012)
		(layer "F.Cu")
		(net "PVDDCR_CPU0_P1")
	)
	(segment
		(start 102.378002 -222.880428)
		(end 101.91115 -222.61449)
		(width 0.350012)
		(layer "F.Cu")
		(net "PVDDCR_CPU0_P1")
	)
	(segment
		(start 106.607864 -249.610372)
		(end 106.141012 -249.344434)
		(width 0.350012)
		(layer "F.Cu")
		(net "PVDDCR_CPU0_P1")
	)
	(segment
		(start 128.227836 -223.690434)
		(end 128.694688 -223.424496)
		(width 0.350012)
		(layer "F.Cu")
		(net "PVDDCR_CPU0_P1")
	)
	(segment
		(start 119.297958 -227.740464)
		(end 119.76481 -227.474526)
		(width 0.350012)
		(layer "F.Cu")
		(net "PVDDCR_CPU0_P1")
	)
	(segment
		(start 123.52782 -225.310446)
		(end 123.994672 -225.044508)
		(width 0.350012)
		(layer "F.Cu")
		(net "PVDDCR_CPU0_P1")
	)
	(segment
		(start 97.677986 -227.740464)
		(end 97.211134 -227.474526)
		(width 0.350012)
		(layer "F.Cu")
		(net "PVDDCR_CPU0_P1")
	)
	(segment
		(start 123.05792 -245.560342)
		(end 123.524772 -245.294404)
		(width 0.350012)
		(layer "F.Cu")
		(net "PVDDCR_CPU0_P1")
	)
	(segment
		(start 126.817882 -226.120452)
		(end 127.284734 -225.854514)
		(width 0.350012)
		(layer "F.Cu")
		(net "PVDDCR_CPU0_P1")
	)
	(segment
		(start 97.677986 -239.080294)
		(end 97.211134 -238.814356)
		(width 0.350012)
		(layer "F.Cu")
		(net "PVDDCR_CPU0_P1")
	)
	(segment
		(start 122.117866 -230.980234)
		(end 122.584718 -230.71455)
		(width 0.350012)
		(layer "F.Cu")
		(net "PVDDCR_CPU0_P1")
	)
	(segment
		(start 107.078018 -250.420378)
		(end 106.611166 -250.15444)
		(width 0.350012)
		(layer "F.Cu")
		(net "PVDDCR_CPU0_P1")
	)
	(segment
		(start 114.127788 -239.8903)
		(end 114.59464 -239.624362)
		(width 0.350012)
		(layer "F.Cu")
		(net "PVDDCR_CPU0_P1")
	)
	(segment
		(start 93.91777 -222.880428)
		(end 93.450918 -222.61449)
		(width 0.350012)
		(layer "F.Cu")
		(net "PVDDCR_CPU0_P1")
	)
	(segment
		(start 108.487972 -225.310446)
		(end 108.02112 -225.044508)
		(width 0.350012)
		(layer "F.Cu")
		(net "PVDDCR_CPU0_P1")
	)
	(segment
		(start 104.72801 -251.230384)
		(end 104.261158 -250.964446)
		(width 0.350012)
		(layer "F.Cu")
		(net "PVDDCR_CPU0_P1")
	)
	(segment
		(start 106.607864 -236.650276)
		(end 106.141012 -236.384338)
		(width 0.350012)
		(layer "F.Cu")
		(net "PVDDCR_CPU0_P1")
	)
	(segment
		(start 126.817882 -222.880428)
		(end 127.284734 -222.61449)
		(width 0.350012)
		(layer "F.Cu")
		(net "PVDDCR_CPU0_P1")
	)
	(segment
		(start 115.537996 -250.420378)
		(end 116.004848 -250.15444)
		(width 0.350012)
		(layer "F.Cu")
		(net "PVDDCR_CPU0_P1")
	)
	(segment
		(start 94.857824 -222.880428)
		(end 94.390972 -222.61449)
		(width 0.350012)
		(layer "F.Cu")
		(net "PVDDCR_CPU0_P1")
	)
	(segment
		(start 100.967794 -249.610372)
		(end 100.500942 -249.344434)
		(width 0.350012)
		(layer "F.Cu")
		(net "PVDDCR_CPU0_P1")
	)
	(segment
		(start 98.617786 -245.560342)
		(end 98.150934 -245.294404)
		(width 0.350012)
		(layer "F.Cu")
		(net "PVDDCR_CPU0_P1")
	)
	(segment
		(start 118.827804 -236.650276)
		(end 119.294656 -236.384338)
		(width 0.350012)
		(layer "F.Cu")
		(net "PVDDCR_CPU0_P1")
	)
	(segment
		(start 114.597942 -237.460282)
		(end 115.064794 -237.194344)
		(width 0.350012)
		(layer "F.Cu")
		(net "PVDDCR_CPU0_P1")
	)
	(segment
		(start 113.187988 -239.8903)
		(end 113.65484 -239.624362)
		(width 0.350012)
		(layer "F.Cu")
		(net "PVDDCR_CPU0_P1")
	)
	(segment
		(start 100.497894 -234.220258)
		(end 100.031042 -233.95432)
		(width 0.350012)
		(layer "F.Cu")
		(net "PVDDCR_CPU0_P1")
	)
	(segment
		(start 99.55784 -222.880428)
		(end 99.090988 -222.61449)
		(width 0.350012)
		(layer "F.Cu")
		(net "PVDDCR_CPU0_P1")
	)
	(segment
		(start 101.437948 -230.980234)
		(end 100.971096 -230.71455)
		(width 0.350012)
		(layer "F.Cu")
		(net "PVDDCR_CPU0_P1")
	)
	(segment
		(start 104.72801 -249.610372)
		(end 104.261158 -249.344434)
		(width 0.350012)
		(layer "F.Cu")
		(net "PVDDCR_CPU0_P1")
	)
	(segment
		(start 105.19791 -222.880428)
		(end 104.731058 -222.61449)
		(width 0.350012)
		(layer "F.Cu")
		(net "PVDDCR_CPU0_P1")
	)
	(segment
		(start 123.05792 -230.980234)
		(end 123.524772 -230.71455)
		(width 0.350012)
		(layer "F.Cu")
		(net "PVDDCR_CPU0_P1")
	)
	(segment
		(start 104.257856 -234.220258)
		(end 103.791004 -233.95432)
		(width 0.350012)
		(layer "F.Cu")
		(net "PVDDCR_CPU0_P1")
	)
	(segment
		(start 106.137964 -242.320318)
		(end 105.671112 -242.05438)
		(width 0.350012)
		(layer "F.Cu")
		(net "PVDDCR_CPU0_P1")
	)
	(segment
		(start 122.117866 -245.560342)
		(end 122.584718 -245.294404)
		(width 0.350012)
		(layer "F.Cu")
		(net "PVDDCR_CPU0_P1")
	)
	(segment
		(start 101.437948 -239.080294)
		(end 100.971096 -238.814356)
		(width 0.350012)
		(layer "F.Cu")
		(net "PVDDCR_CPU0_P1")
	)
	(segment
		(start 109.427772 -239.8903)
		(end 108.961174 -239.624362)
		(width 0.350012)
		(layer "F.Cu")
		(net "PVDDCR_CPU0_P1")
	)
	(segment
		(start 119.297958 -245.560342)
		(end 119.76481 -245.294404)
		(width 0.350012)
		(layer "F.Cu")
		(net "PVDDCR_CPU0_P1")
	)
	(segment
		(start 101.437948 -227.740464)
		(end 100.971096 -227.474526)
		(width 0.350012)
		(layer "F.Cu")
		(net "PVDDCR_CPU0_P1")
	)
	(segment
		(start 106.607864 -251.230384)
		(end 106.141012 -250.964446)
		(width 0.350012)
		(layer "F.Cu")
		(net "PVDDCR_CPU0_P1")
	)
	(segment
		(start 117.41785 -239.080294)
		(end 117.884702 -238.814356)
		(width 0.350012)
		(layer "F.Cu")
		(net "PVDDCR_CPU0_P1")
	)
	(segment
		(start 106.137964 -248.800366)
		(end 105.671112 -248.534428)
		(width 0.350012)
		(layer "F.Cu")
		(net "PVDDCR_CPU0_P1")
	)
	(segment
		(start 117.41785 -245.560342)
		(end 117.884702 -245.294404)
		(width 0.350012)
		(layer "F.Cu")
		(net "PVDDCR_CPU0_P1")
	)
	(segment
		(start 110.83798 -250.420378)
		(end 110.371128 -250.15444)
		(width 0.350012)
		(layer "F.Cu")
		(net "PVDDCR_CPU0_P1")
	)
	(segment
		(start 118.357904 -226.120452)
		(end 118.824756 -225.854514)
		(width 0.350012)
		(layer "F.Cu")
		(net "PVDDCR_CPU0_P1")
	)
	(segment
		(start 116.007896 -251.230384)
		(end 116.474748 -250.964446)
		(width 0.350012)
		(layer "F.Cu")
		(net "PVDDCR_CPU0_P1")
	)
	(segment
		(start 101.437948 -234.220258)
		(end 100.971096 -233.95432)
		(width 0.350012)
		(layer "F.Cu")
		(net "PVDDCR_CPU0_P1")
	)
	(segment
		(start 100.027994 -225.310446)
		(end 99.561142 -225.044508)
		(width 0.350012)
		(layer "F.Cu")
		(net "PVDDCR_CPU0_P1")
	)
	(segment
		(start 104.257856 -248.800366)
		(end 103.791004 -248.534428)
		(width 0.350012)
		(layer "F.Cu")
		(net "PVDDCR_CPU0_P1")
	)
	(segment
		(start 119.297958 -230.980234)
		(end 119.76481 -230.71455)
		(width 0.350012)
		(layer "F.Cu")
		(net "PVDDCR_CPU0_P1")
	)
	(segment
		(start 125.877828 -245.560342)
		(end 126.34468 -245.294404)
		(width 0.350012)
		(layer "F.Cu")
		(net "PVDDCR_CPU0_P1")
	)
	(segment
		(start 125.877828 -248.800366)
		(end 126.34468 -248.534428)
		(width 0.350012)
		(layer "F.Cu")
		(net "PVDDCR_CPU0_P1")
	)
	(segment
		(start 107.078018 -242.320318)
		(end 106.611166 -242.05438)
		(width 0.350012)
		(layer "F.Cu")
		(net "PVDDCR_CPU0_P1")
	)
	(segment
		(start 120.238012 -227.740464)
		(end 120.70461 -227.474526)
		(width 0.350012)
		(layer "F.Cu")
		(net "PVDDCR_CPU0_P1")
	)
	(segment
		(start 122.117866 -227.740464)
		(end 122.584718 -227.474526)
		(width 0.350012)
		(layer "F.Cu")
		(net "PVDDCR_CPU0_P1")
	)
	(segment
		(start 103.317802 -222.880428)
		(end 102.85095 -222.61449)
		(width 0.350012)
		(layer "F.Cu")
		(net "PVDDCR_CPU0_P1")
	)
	(segment
		(start 129.63779 -222.880428)
		(end 130.104642 -222.61449)
		(width 0.350012)
		(layer "F.Cu")
		(net "PVDDCR_CPU0_P1")
	)
	(segment
		(start 104.257856 -227.740464)
		(end 103.791004 -227.474526)
		(width 0.350012)
		(layer "F.Cu")
		(net "PVDDCR_CPU0_P1")
	)
	(segment
		(start 125.877828 -227.740464)
		(end 126.34468 -227.474526)
		(width 0.350012)
		(layer "F.Cu")
		(net "PVDDCR_CPU0_P1")
	)
	(segment
		(start 106.137964 -234.220258)
		(end 105.671112 -233.95432)
		(width 0.350012)
		(layer "F.Cu")
		(net "PVDDCR_CPU0_P1")
	)
	(segment
		(start 109.427772 -228.55047)
		(end 108.961174 -228.284532)
		(width 0.350012)
		(layer "F.Cu")
		(net "PVDDCR_CPU0_P1")
	)
	(segment
		(start 106.137964 -245.560342)
		(end 105.671112 -245.294404)
		(width 0.350012)
		(layer "F.Cu")
		(net "PVDDCR_CPU0_P1")
	)
	(segment
		(start 113.657888 -250.420378)
		(end 114.12474 -250.15444)
		(width 0.350012)
		(layer "F.Cu")
		(net "PVDDCR_CPU0_P1")
	)
	(via
		(at 113.65484 -246.10441)
		(size 0.4064)
		(drill 0.2032)
		(layers "F.Cu" "B.Cu")
		(net "PVDDCR_CPU0_P1")
	)
	(via
		(at 96.948498 -199.12584)
		(size 0.508)
		(drill 0.254)
		(layers "F.Cu" "B.Cu")
		(net "PVDDCR_CPU0_P1")
	)
	(via
		(at 62.887098 -182.18404)
		(size 0.508)
		(drill 0.254)
		(layers "F.Cu" "B.Cu")
		(net "PVDDCR_CPU0_P1")
	)
	(via
		(at 106.141012 -236.384338)
		(size 0.4064)
		(drill 0.2032)
		(layers "F.Cu" "B.Cu")
		(net "PVDDCR_CPU0_P1")
	)
	(via
		(at 89.192354 -197.24116)
		(size 0.508)
		(drill 0.254)
		(layers "F.Cu" "B.Cu")
		(net "PVDDCR_CPU0_P1")
	)
	(via
		(at 102.85095 -238.814356)
		(size 0.4064)
		(drill 0.2032)
		(layers "F.Cu" "B.Cu")
		(net "PVDDCR_CPU0_P1")
	)
	(via
		(at 76.483718 -195.98894)
		(size 0.508)
		(drill 0.254)
		(layers "F.Cu" "B.Cu")
		(net "PVDDCR_CPU0_P1")
	)
	(via
		(at 108.961174 -231.524302)
		(size 0.4064)
		(drill 0.2032)
		(layers "F.Cu" "B.Cu")
		(net "PVDDCR_CPU0_P1")
	)
	(via
		(at 83.538314 -195.358512)
		(size 0.508)
		(drill 0.254)
		(layers "F.Cu" "B.Cu")
		(net "PVDDCR_CPU0_P1")
	)
	(via
		(at 105.450132 -195.87845)
		(size 0.508)
		(drill 0.254)
		(layers "F.Cu" "B.Cu")
		(net "PVDDCR_CPU0_P1")
	)
	(via
		(at 122.584718 -238.814356)
		(size 0.4064)
		(drill 0.2032)
		(layers "F.Cu" "B.Cu")
		(net "PVDDCR_CPU0_P1")
	)
	(via
		(at 88.531954 -200.420732)
		(size 0.508)
		(drill 0.254)
		(layers "F.Cu" "B.Cu")
		(net "PVDDCR_CPU0_P1")
	)
	(via
		(at 106.721148 -190.790322)
		(size 0.508)
		(drill 0.254)
		(layers "F.Cu" "B.Cu")
		(net "PVDDCR_CPU0_P1")
	)
	(via
		(at 100.971096 -248.534428)
		(size 0.4064)
		(drill 0.2032)
		(layers "F.Cu" "B.Cu")
		(net "PVDDCR_CPU0_P1")
	)
	(via
		(at 83.537298 -197.90664)
		(size 0.508)
		(drill 0.254)
		(layers "F.Cu" "B.Cu")
		(net "PVDDCR_CPU0_P1")
	)
	(via
		(at 75.848718 -195.35394)
		(size 0.508)
		(drill 0.254)
		(layers "F.Cu" "B.Cu")
		(net "PVDDCR_CPU0_P1")
	)
	(via
		(at 102.85095 -222.61449)
		(size 0.4064)
		(drill 0.2032)
		(layers "F.Cu" "B.Cu")
		(net "PVDDCR_CPU0_P1")
	)
	(via
		(at 100.971096 -242.05438)
		(size 0.4064)
		(drill 0.2032)
		(layers "F.Cu" "B.Cu")
		(net "PVDDCR_CPU0_P1")
	)
	(via
		(at 122.584718 -227.474526)
		(size 0.4064)
		(drill 0.2032)
		(layers "F.Cu" "B.Cu")
		(net "PVDDCR_CPU0_P1")
	)
	(via
		(at 115.534694 -225.044508)
		(size 0.4064)
		(drill 0.2032)
		(layers "F.Cu" "B.Cu")
		(net "PVDDCR_CPU0_P1")
	)
	(via
		(at 93.205554 -195.340732)
		(size 0.508)
		(drill 0.254)
		(layers "F.Cu" "B.Cu")
		(net "PVDDCR_CPU0_P1")
	)
	(via
		(at 91.935554 -200.420732)
		(size 0.508)
		(drill 0.254)
		(layers "F.Cu" "B.Cu")
		(net "PVDDCR_CPU0_P1")
	)
	(via
		(at 106.086148 -192.060322)
		(size 0.508)
		(drill 0.254)
		(layers "F.Cu" "B.Cu")
		(net "PVDDCR_CPU0_P1")
	)
	(via
		(at 117.884702 -248.534428)
		(size 0.4064)
		(drill 0.2032)
		(layers "F.Cu" "B.Cu")
		(net "PVDDCR_CPU0_P1")
	)
	(via
		(at 80.794098 -199.81164)
		(size 0.508)
		(drill 0.254)
		(layers "F.Cu" "B.Cu")
		(net "PVDDCR_CPU0_P1")
	)
	(via
		(at 101.597714 -197.24624)
		(size 0.508)
		(drill 0.254)
		(layers "F.Cu" "B.Cu")
		(net "PVDDCR_CPU0_P1")
	)
	(via
		(at 101.597714 -197.88124)
		(size 0.508)
		(drill 0.254)
		(layers "F.Cu" "B.Cu")
		(net "PVDDCR_CPU0_P1")
	)
	(via
		(at 80.794098 -200.44664)
		(size 0.508)
		(drill 0.254)
		(layers "F.Cu" "B.Cu")
		(net "PVDDCR_CPU0_P1")
	)
	(via
		(at 106.720132 -194.60845)
		(size 0.508)
		(drill 0.254)
		(layers "F.Cu" "B.Cu")
		(net "PVDDCR_CPU0_P1")
	)
	(via
		(at 119.76481 -227.474526)
		(size 0.4064)
		(drill 0.2032)
		(layers "F.Cu" "B.Cu")
		(net "PVDDCR_CPU0_P1")
	)
	(via
		(at 120.70461 -230.71455)
		(size 0.4064)
		(drill 0.2032)
		(layers "F.Cu" "B.Cu")
		(net "PVDDCR_CPU0_P1")
	)
	(via
		(at 100.031042 -233.95432)
		(size 0.4064)
		(drill 0.2032)
		(layers "F.Cu" "B.Cu")
		(net "PVDDCR_CPU0_P1")
	)
	(via
		(at 97.211134 -233.95432)
		(size 0.4064)
		(drill 0.2032)
		(layers "F.Cu" "B.Cu")
		(net "PVDDCR_CPU0_P1")
	)
	(via
		(at 66.901314 -182.813198)
		(size 0.508)
		(drill 0.254)
		(layers "F.Cu" "B.Cu")
		(net "PVDDCR_CPU0_P1")
	)
	(via
		(at 116.944648 -245.294404)
		(size 0.4064)
		(drill 0.2032)
		(layers "F.Cu" "B.Cu")
		(net "PVDDCR_CPU0_P1")
	)
	(via
		(at 71.200518 -192.81394)
		(size 0.508)
		(drill 0.254)
		(layers "F.Cu" "B.Cu")
		(net "PVDDCR_CPU0_P1")
	)
	(via
		(at 120.23471 -250.964446)
		(size 0.4064)
		(drill 0.2032)
		(layers "F.Cu" "B.Cu")
		(net "PVDDCR_CPU0_P1")
	)
	(via
		(at 96.27108 -225.854514)
		(size 0.4064)
		(drill 0.2032)
		(layers "F.Cu" "B.Cu")
		(net "PVDDCR_CPU0_P1")
	)
	(via
		(at 64.158114 -183.448198)
		(size 0.508)
		(drill 0.254)
		(layers "F.Cu" "B.Cu")
		(net "PVDDCR_CPU0_P1")
	)
	(via
		(at 75.214734 -191.510412)
		(size 0.508)
		(drill 0.254)
		(layers "F.Cu" "B.Cu")
		(net "PVDDCR_CPU0_P1")
	)
	(via
		(at 116.944648 -242.05438)
		(size 0.4064)
		(drill 0.2032)
		(layers "F.Cu" "B.Cu")
		(net "PVDDCR_CPU0_P1")
	)
	(via
		(at 120.70461 -242.05438)
		(size 0.4064)
		(drill 0.2032)
		(layers "F.Cu" "B.Cu")
		(net "PVDDCR_CPU0_P1")
	)
	(via
		(at 91.935554 -199.150732)
		(size 0.508)
		(drill 0.254)
		(layers "F.Cu" "B.Cu")
		(net "PVDDCR_CPU0_P1")
	)
	(via
		(at 122.584718 -245.294404)
		(size 0.4064)
		(drill 0.2032)
		(layers "F.Cu" "B.Cu")
		(net "PVDDCR_CPU0_P1")
	)
	(via
		(at 87.896954 -200.420732)
		(size 0.508)
		(drill 0.254)
		(layers "F.Cu" "B.Cu")
		(net "PVDDCR_CPU0_P1")
	)
	(via
		(at 119.76481 -250.15444)
		(size 0.4064)
		(drill 0.2032)
		(layers "F.Cu" "B.Cu")
		(net "PVDDCR_CPU0_P1")
	)
	(via
		(at 83.538314 -195.993512)
		(size 0.508)
		(drill 0.254)
		(layers "F.Cu" "B.Cu")
		(net "PVDDCR_CPU0_P1")
	)
	(via
		(at 80.794098 -194.723512)
		(size 0.508)
		(drill 0.254)
		(layers "F.Cu" "B.Cu")
		(net "PVDDCR_CPU0_P1")
	)
	(via
		(at 67.536314 -181.543198)
		(size 0.508)
		(drill 0.254)
		(layers "F.Cu" "B.Cu")
		(net "PVDDCR_CPU0_P1")
	)
	(via
		(at 125.404626 -242.05438)
		(size 0.4064)
		(drill 0.2032)
		(layers "F.Cu" "B.Cu")
		(net "PVDDCR_CPU0_P1")
	)
	(via
		(at 117.884702 -242.05438)
		(size 0.4064)
		(drill 0.2032)
		(layers "F.Cu" "B.Cu")
		(net "PVDDCR_CPU0_P1")
	)
	(via
		(at 120.70461 -233.95432)
		(size 0.4064)
		(drill 0.2032)
		(layers "F.Cu" "B.Cu")
		(net "PVDDCR_CPU0_P1")
	)
	(via
		(at 97.584514 -197.212712)
		(size 0.508)
		(drill 0.254)
		(layers "F.Cu" "B.Cu")
		(net "PVDDCR_CPU0_P1")
	)
	(via
		(at 93.205554 -197.245732)
		(size 0.508)
		(drill 0.254)
		(layers "F.Cu" "B.Cu")
		(net "PVDDCR_CPU0_P1")
	)
	(via
		(at 109.464348 -192.695322)
		(size 0.508)
		(drill 0.254)
		(layers "F.Cu" "B.Cu")
		(net "PVDDCR_CPU0_P1")
	)
	(via
		(at 125.404626 -245.294404)
		(size 0.4064)
		(drill 0.2032)
		(layers "F.Cu" "B.Cu")
		(net "PVDDCR_CPU0_P1")
	)
	(via
		(at 124.464826 -225.854514)
		(size 0.4064)
		(drill 0.2032)
		(layers "F.Cu" "B.Cu")
		(net "PVDDCR_CPU0_P1")
	)
	(via
		(at 84.173314 -196.628512)
		(size 0.508)
		(drill 0.254)
		(layers "F.Cu" "B.Cu")
		(net "PVDDCR_CPU0_P1")
	)
	(via
		(at 96.949514 -197.212712)
		(size 0.508)
		(drill 0.254)
		(layers "F.Cu" "B.Cu")
		(net "PVDDCR_CPU0_P1")
	)
	(via
		(at 109.900974 -228.284532)
		(size 0.4064)
		(drill 0.2032)
		(layers "F.Cu" "B.Cu")
		(net "PVDDCR_CPU0_P1")
	)
	(via
		(at 122.584718 -248.534428)
		(size 0.4064)
		(drill 0.2032)
		(layers "F.Cu" "B.Cu")
		(net "PVDDCR_CPU0_P1")
	)
	(via
		(at 103.791004 -233.95432)
		(size 0.4064)
		(drill 0.2032)
		(layers "F.Cu" "B.Cu")
		(net "PVDDCR_CPU0_P1")
	)
	(via
		(at 76.484734 -192.149984)
		(size 0.508)
		(drill 0.254)
		(layers "F.Cu" "B.Cu")
		(net "PVDDCR_CPU0_P1")
	)
	(via
		(at 98.150934 -238.814356)
		(size 0.4064)
		(drill 0.2032)
		(layers "F.Cu" "B.Cu")
		(net "PVDDCR_CPU0_P1")
	)
	(via
		(at 100.327714 -195.942712)
		(size 0.508)
		(drill 0.254)
		(layers "F.Cu" "B.Cu")
		(net "PVDDCR_CPU0_P1")
	)
	(via
		(at 92.570554 -199.785732)
		(size 0.508)
		(drill 0.254)
		(layers "F.Cu" "B.Cu")
		(net "PVDDCR_CPU0_P1")
	)
	(via
		(at 103.321104 -236.384338)
		(size 0.4064)
		(drill 0.2032)
		(layers "F.Cu" "B.Cu")
		(net "PVDDCR_CPU0_P1")
	)
	(via
		(at 83.538314 -196.628512)
		(size 0.508)
		(drill 0.254)
		(layers "F.Cu" "B.Cu")
		(net "PVDDCR_CPU0_P1")
	)
	(via
		(at 106.611166 -238.814356)
		(size 0.4064)
		(drill 0.2032)
		(layers "F.Cu" "B.Cu")
		(net "PVDDCR_CPU0_P1")
	)
	(via
		(at 80.795114 -196.628512)
		(size 0.508)
		(drill 0.254)
		(layers "F.Cu" "B.Cu")
		(net "PVDDCR_CPU0_P1")
	)
	(via
		(at 95.331026 -224.234502)
		(size 0.4064)
		(drill 0.2032)
		(layers "F.Cu" "B.Cu")
		(net "PVDDCR_CPU0_P1")
	)
	(via
		(at 88.531954 -198.515732)
		(size 0.508)
		(drill 0.254)
		(layers "F.Cu" "B.Cu")
		(net "PVDDCR_CPU0_P1")
	)
	(via
		(at 108.961174 -226.66452)
		(size 0.4064)
		(drill 0.2032)
		(layers "F.Cu" "B.Cu")
		(net "PVDDCR_CPU0_P1")
	)
	(via
		(at 101.91115 -225.854514)
		(size 0.4064)
		(drill 0.2032)
		(layers "F.Cu" "B.Cu")
		(net "PVDDCR_CPU0_P1")
	)
	(via
		(at 83.537298 -199.17664)
		(size 0.508)
		(drill 0.254)
		(layers "F.Cu" "B.Cu")
		(net "PVDDCR_CPU0_P1")
	)
	(via
		(at 102.85095 -227.474526)
		(size 0.4064)
		(drill 0.2032)
		(layers "F.Cu" "B.Cu")
		(net "PVDDCR_CPU0_P1")
	)
	(via
		(at 96.313498 -200.39584)
		(size 0.508)
		(drill 0.254)
		(layers "F.Cu" "B.Cu")
		(net "PVDDCR_CPU0_P1")
	)
	(via
		(at 103.791004 -245.294404)
		(size 0.4064)
		(drill 0.2032)
		(layers "F.Cu" "B.Cu")
		(net "PVDDCR_CPU0_P1")
	)
	(via
		(at 108.961174 -234.764326)
		(size 0.4064)
		(drill 0.2032)
		(layers "F.Cu" "B.Cu")
		(net "PVDDCR_CPU0_P1")
	)
	(via
		(at 105.671112 -230.71455)
		(size 0.4064)
		(drill 0.2032)
		(layers "F.Cu" "B.Cu")
		(net "PVDDCR_CPU0_P1")
	)
	(via
		(at 117.414802 -236.384338)
		(size 0.4064)
		(drill 0.2032)
		(layers "F.Cu" "B.Cu")
		(net "PVDDCR_CPU0_P1")
	)
	(via
		(at 104.731058 -250.15444)
		(size 0.4064)
		(drill 0.2032)
		(layers "F.Cu" "B.Cu")
		(net "PVDDCR_CPU0_P1")
	)
	(via
		(at 121.644664 -222.61449)
		(size 0.4064)
		(drill 0.2032)
		(layers "F.Cu" "B.Cu")
		(net "PVDDCR_CPU0_P1")
	)
	(via
		(at 106.721148 -192.060322)
		(size 0.508)
		(drill 0.254)
		(layers "F.Cu" "B.Cu")
		(net "PVDDCR_CPU0_P1")
	)
	(via
		(at 115.064794 -237.194344)
		(size 0.4064)
		(drill 0.2032)
		(layers "F.Cu" "B.Cu")
		(net "PVDDCR_CPU0_P1")
	)
	(via
		(at 106.611166 -227.474526)
		(size 0.4064)
		(drill 0.2032)
		(layers "F.Cu" "B.Cu")
		(net "PVDDCR_CPU0_P1")
	)
	(via
		(at 105.200958 -225.044508)
		(size 0.4064)
		(drill 0.2032)
		(layers "F.Cu" "B.Cu")
		(net "PVDDCR_CPU0_P1")
	)
	(via
		(at 101.597714 -198.51624)
		(size 0.508)
		(drill 0.254)
		(layers "F.Cu" "B.Cu")
		(net "PVDDCR_CPU0_P1")
	)
	(via
		(at 100.031042 -222.61449)
		(size 0.4064)
		(drill 0.2032)
		(layers "F.Cu" "B.Cu")
		(net "PVDDCR_CPU0_P1")
	)
	(via
		(at 80.160114 -195.358512)
		(size 0.508)
		(drill 0.254)
		(layers "F.Cu" "B.Cu")
		(net "PVDDCR_CPU0_P1")
	)
	(via
		(at 105.450132 -195.24345)
		(size 0.508)
		(drill 0.254)
		(layers "F.Cu" "B.Cu")
		(net "PVDDCR_CPU0_P1")
	)
	(via
		(at 108.961174 -228.284532)
		(size 0.4064)
		(drill 0.2032)
		(layers "F.Cu" "B.Cu")
		(net "PVDDCR_CPU0_P1")
	)
	(via
		(at 71.200518 -189.605412)
		(size 0.508)
		(drill 0.254)
		(layers "F.Cu" "B.Cu")
		(net "PVDDCR_CPU0_P1")
	)
	(via
		(at 75.848718 -193.44894)
		(size 0.508)
		(drill 0.254)
		(layers "F.Cu" "B.Cu")
		(net "PVDDCR_CPU0_P1")
	)
	(via
		(at 113.65484 -234.764326)
		(size 0.4064)
		(drill 0.2032)
		(layers "F.Cu" "B.Cu")
		(net "PVDDCR_CPU0_P1")
	)
	(via
		(at 105.450132 -192.70345)
		(size 0.508)
		(drill 0.254)
		(layers "F.Cu" "B.Cu")
		(net "PVDDCR_CPU0_P1")
	)
	(via
		(at 84.172298 -201.08164)
		(size 0.508)
		(drill 0.254)
		(layers "F.Cu" "B.Cu")
		(net "PVDDCR_CPU0_P1")
	)
	(via
		(at 116.944648 -238.814356)
		(size 0.4064)
		(drill 0.2032)
		(layers "F.Cu" "B.Cu")
		(net "PVDDCR_CPU0_P1")
	)
	(via
		(at 63.523114 -182.813198)
		(size 0.508)
		(drill 0.254)
		(layers "F.Cu" "B.Cu")
		(net "PVDDCR_CPU0_P1")
	)
	(via
		(at 75.214734 -190.875412)
		(size 0.508)
		(drill 0.254)
		(layers "F.Cu" "B.Cu")
		(net "PVDDCR_CPU0_P1")
	)
	(via
		(at 84.172298 -200.44664)
		(size 0.508)
		(drill 0.254)
		(layers "F.Cu" "B.Cu")
		(net "PVDDCR_CPU0_P1")
	)
	(via
		(at 120.70461 -248.534428)
		(size 0.4064)
		(drill 0.2032)
		(layers "F.Cu" "B.Cu")
		(net "PVDDCR_CPU0_P1")
	)
	(via
		(at 66.874898 -185.99404)
		(size 0.508)
		(drill 0.254)
		(layers "F.Cu" "B.Cu")
		(net "PVDDCR_CPU0_P1")
	)
	(via
		(at 120.23471 -249.344434)
		(size 0.4064)
		(drill 0.2032)
		(layers "F.Cu" "B.Cu")
		(net "PVDDCR_CPU0_P1")
	)
	(via
		(at 100.500942 -249.344434)
		(size 0.4064)
		(drill 0.2032)
		(layers "F.Cu" "B.Cu")
		(net "PVDDCR_CPU0_P1")
	)
	(via
		(at 96.948498 -201.03084)
		(size 0.508)
		(drill 0.254)
		(layers "F.Cu" "B.Cu")
		(net "PVDDCR_CPU0_P1")
	)
	(via
		(at 87.896954 -195.340732)
		(size 0.508)
		(drill 0.254)
		(layers "F.Cu" "B.Cu")
		(net "PVDDCR_CPU0_P1")
	)
	(via
		(at 96.313498 -196.58584)
		(size 0.508)
		(drill 0.254)
		(layers "F.Cu" "B.Cu")
		(net "PVDDCR_CPU0_P1")
	)
	(via
		(at 79.524098 -196.63664)
		(size 0.508)
		(drill 0.254)
		(layers "F.Cu" "B.Cu")
		(net "PVDDCR_CPU0_P1")
	)
	(via
		(at 113.65484 -242.864386)
		(size 0.4064)
		(drill 0.2032)
		(layers "F.Cu" "B.Cu")
		(net "PVDDCR_CPU0_P1")
	)
	(via
		(at 100.971096 -230.71455)
		(size 0.4064)
		(drill 0.2032)
		(layers "F.Cu" "B.Cu")
		(net "PVDDCR_CPU0_P1")
	)
	(via
		(at 79.524098 -198.54164)
		(size 0.508)
		(drill 0.254)
		(layers "F.Cu" "B.Cu")
		(net "PVDDCR_CPU0_P1")
	)
	(via
		(at 106.611166 -230.71455)
		(size 0.4064)
		(drill 0.2032)
		(layers "F.Cu" "B.Cu")
		(net "PVDDCR_CPU0_P1")
	)
	(via
		(at 89.192354 -196.60616)
		(size 0.508)
		(drill 0.254)
		(layers "F.Cu" "B.Cu")
		(net "PVDDCR_CPU0_P1")
	)
	(via
		(at 125.404626 -227.474526)
		(size 0.4064)
		(drill 0.2032)
		(layers "F.Cu" "B.Cu")
		(net "PVDDCR_CPU0_P1")
	)
	(via
		(at 100.031042 -245.294404)
		(size 0.4064)
		(drill 0.2032)
		(layers "F.Cu" "B.Cu")
		(net "PVDDCR_CPU0_P1")
	)
	(via
		(at 64.158114 -182.813198)
		(size 0.508)
		(drill 0.254)
		(layers "F.Cu" "B.Cu")
		(net "PVDDCR_CPU0_P1")
	)
	(via
		(at 109.900974 -234.764326)
		(size 0.4064)
		(drill 0.2032)
		(layers "F.Cu" "B.Cu")
		(net "PVDDCR_CPU0_P1")
	)
	(via
		(at 102.85095 -245.294404)
		(size 0.4064)
		(drill 0.2032)
		(layers "F.Cu" "B.Cu")
		(net "PVDDCR_CPU0_P1")
	)
	(via
		(at 66.874898 -187.26404)
		(size 0.508)
		(drill 0.254)
		(layers "F.Cu" "B.Cu")
		(net "PVDDCR_CPU0_P1")
	)
	(via
		(at 71.200518 -190.90894)
		(size 0.508)
		(drill 0.254)
		(layers "F.Cu" "B.Cu")
		(net "PVDDCR_CPU0_P1")
	)
	(via
		(at 83.538314 -197.263512)
		(size 0.508)
		(drill 0.254)
		(layers "F.Cu" "B.Cu")
		(net "PVDDCR_CPU0_P1")
	)
	(via
		(at 109.900974 -242.864386)
		(size 0.4064)
		(drill 0.2032)
		(layers "F.Cu" "B.Cu")
		(net "PVDDCR_CPU0_P1")
	)
	(via
		(at 116.944648 -230.71455)
		(size 0.4064)
		(drill 0.2032)
		(layers "F.Cu" "B.Cu")
		(net "PVDDCR_CPU0_P1")
	)
	(via
		(at 96.313498 -199.76084)
		(size 0.508)
		(drill 0.254)
		(layers "F.Cu" "B.Cu")
		(net "PVDDCR_CPU0_P1")
	)
	(via
		(at 75.213718 -195.98894)
		(size 0.508)
		(drill 0.254)
		(layers "F.Cu" "B.Cu")
		(net "PVDDCR_CPU0_P1")
	)
	(via
		(at 91.935554 -197.24116)
		(size 0.508)
		(drill 0.254)
		(layers "F.Cu" "B.Cu")
		(net "PVDDCR_CPU0_P1")
	)
	(via
		(at 119.76481 -242.05438)
		(size 0.4064)
		(drill 0.2032)
		(layers "F.Cu" "B.Cu")
		(net "PVDDCR_CPU0_P1")
	)
	(via
		(at 97.211134 -245.294404)
		(size 0.4064)
		(drill 0.2032)
		(layers "F.Cu" "B.Cu")
		(net "PVDDCR_CPU0_P1")
	)
	(via
		(at 88.557354 -195.97116)
		(size 0.508)
		(drill 0.254)
		(layers "F.Cu" "B.Cu")
		(net "PVDDCR_CPU0_P1")
	)
	(via
		(at 91.935554 -198.515732)
		(size 0.508)
		(drill 0.254)
		(layers "F.Cu" "B.Cu")
		(net "PVDDCR_CPU0_P1")
	)
	(via
		(at 117.884702 -230.71455)
		(size 0.4064)
		(drill 0.2032)
		(layers "F.Cu" "B.Cu")
		(net "PVDDCR_CPU0_P1")
	)
	(via
		(at 72.470518 -193.44894)
		(size 0.508)
		(drill 0.254)
		(layers "F.Cu" "B.Cu")
		(net "PVDDCR_CPU0_P1")
	)
	(via
		(at 84.807298 -198.54164)
		(size 0.508)
		(drill 0.254)
		(layers "F.Cu" "B.Cu")
		(net "PVDDCR_CPU0_P1")
	)
	(via
		(at 89.166954 -199.150732)
		(size 0.508)
		(drill 0.254)
		(layers "F.Cu" "B.Cu")
		(net "PVDDCR_CPU0_P1")
	)
	(via
		(at 80.795114 -195.358512)
		(size 0.508)
		(drill 0.254)
		(layers "F.Cu" "B.Cu")
		(net "PVDDCR_CPU0_P1")
	)
	(via
		(at 105.450132 -192.06845)
		(size 0.508)
		(drill 0.254)
		(layers "F.Cu" "B.Cu")
		(net "PVDDCR_CPU0_P1")
	)
	(via
		(at 84.172298 -197.90664)
		(size 0.508)
		(drill 0.254)
		(layers "F.Cu" "B.Cu")
		(net "PVDDCR_CPU0_P1")
	)
	(via
		(at 102.85095 -233.95432)
		(size 0.4064)
		(drill 0.2032)
		(layers "F.Cu" "B.Cu")
		(net "PVDDCR_CPU0_P1")
	)
	(via
		(at 102.85095 -242.05438)
		(size 0.4064)
		(drill 0.2032)
		(layers "F.Cu" "B.Cu")
		(net "PVDDCR_CPU0_P1")
	)
	(via
		(at 96.313498 -195.31584)
		(size 0.508)
		(drill 0.254)
		(layers "F.Cu" "B.Cu")
		(net "PVDDCR_CPU0_P1")
	)
	(via
		(at 80.159098 -199.17664)
		(size 0.508)
		(drill 0.254)
		(layers "F.Cu" "B.Cu")
		(net "PVDDCR_CPU0_P1")
	)
	(via
		(at 80.159098 -194.723512)
		(size 0.508)
		(drill 0.254)
		(layers "F.Cu" "B.Cu")
		(net "PVDDCR_CPU0_P1")
	)
	(via
		(at 62.887098 -184.08904)
		(size 0.508)
		(drill 0.254)
		(layers "F.Cu" "B.Cu")
		(net "PVDDCR_CPU0_P1")
	)
	(via
		(at 100.971096 -245.294404)
		(size 0.4064)
		(drill 0.2032)
		(layers "F.Cu" "B.Cu")
		(net "PVDDCR_CPU0_P1")
	)
	(via
		(at 80.159098 -200.44664)
		(size 0.508)
		(drill 0.254)
		(layers "F.Cu" "B.Cu")
		(net "PVDDCR_CPU0_P1")
	)
	(via
		(at 96.313498 -201.03084)
		(size 0.508)
		(drill 0.254)
		(layers "F.Cu" "B.Cu")
		(net "PVDDCR_CPU0_P1")
	)
	(via
		(at 84.172298 -194.723512)
		(size 0.508)
		(drill 0.254)
		(layers "F.Cu" "B.Cu")
		(net "PVDDCR_CPU0_P1")
	)
	(via
		(at 96.313498 -195.95084)
		(size 0.508)
		(drill 0.254)
		(layers "F.Cu" "B.Cu")
		(net "PVDDCR_CPU0_P1")
	)
	(via
		(at 71.200518 -191.54394)
		(size 0.508)
		(drill 0.254)
		(layers "F.Cu" "B.Cu")
		(net "PVDDCR_CPU0_P1")
	)
	(via
		(at 116.944648 -227.474526)
		(size 0.4064)
		(drill 0.2032)
		(layers "F.Cu" "B.Cu")
		(net "PVDDCR_CPU0_P1")
	)
	(via
		(at 103.791004 -242.05438)
		(size 0.4064)
		(drill 0.2032)
		(layers "F.Cu" "B.Cu")
		(net "PVDDCR_CPU0_P1")
	)
	(via
		(at 98.150934 -230.71455)
		(size 0.4064)
		(drill 0.2032)
		(layers "F.Cu" "B.Cu")
		(net "PVDDCR_CPU0_P1")
	)
	(via
		(at 116.474748 -236.384338)
		(size 0.4064)
		(drill 0.2032)
		(layers "F.Cu" "B.Cu")
		(net "PVDDCR_CPU0_P1")
	)
	(via
		(at 100.961698 -199.78624)
		(size 0.508)
		(drill 0.254)
		(layers "F.Cu" "B.Cu")
		(net "PVDDCR_CPU0_P1")
	)
	(via
		(at 106.720132 -190.155322)
		(size 0.508)
		(drill 0.254)
		(layers "F.Cu" "B.Cu")
		(net "PVDDCR_CPU0_P1")
	)
	(via
		(at 108.02112 -225.044508)
		(size 0.4064)
		(drill 0.2032)
		(layers "F.Cu" "B.Cu")
		(net "PVDDCR_CPU0_P1")
	)
	(via
		(at 124.464826 -222.61449)
		(size 0.4064)
		(drill 0.2032)
		(layers "F.Cu" "B.Cu")
		(net "PVDDCR_CPU0_P1")
	)
	(via
		(at 75.213718 -194.08394)
		(size 0.508)
		(drill 0.254)
		(layers "F.Cu" "B.Cu")
		(net "PVDDCR_CPU0_P1")
	)
	(via
		(at 97.584514 -196.577712)
		(size 0.508)
		(drill 0.254)
		(layers "F.Cu" "B.Cu")
		(net "PVDDCR_CPU0_P1")
	)
	(via
		(at 123.994672 -225.044508)
		(size 0.4064)
		(drill 0.2032)
		(layers "F.Cu" "B.Cu")
		(net "PVDDCR_CPU0_P1")
	)
	(via
		(at 72.471534 -192.145412)
		(size 0.508)
		(drill 0.254)
		(layers "F.Cu" "B.Cu")
		(net "PVDDCR_CPU0_P1")
	)
	(via
		(at 119.76481 -248.534428)
		(size 0.4064)
		(drill 0.2032)
		(layers "F.Cu" "B.Cu")
		(net "PVDDCR_CPU0_P1")
	)
	(via
		(at 96.313498 -199.12584)
		(size 0.508)
		(drill 0.254)
		(layers "F.Cu" "B.Cu")
		(net "PVDDCR_CPU0_P1")
	)
	(via
		(at 76.483718 -195.35394)
		(size 0.508)
		(drill 0.254)
		(layers "F.Cu" "B.Cu")
		(net "PVDDCR_CPU0_P1")
	)
	(via
		(at 120.70461 -227.474526)
		(size 0.4064)
		(drill 0.2032)
		(layers "F.Cu" "B.Cu")
		(net "PVDDCR_CPU0_P1")
	)
	(via
		(at 84.173314 -195.358512)
		(size 0.508)
		(drill 0.254)
		(layers "F.Cu" "B.Cu")
		(net "PVDDCR_CPU0_P1")
	)
	(via
		(at 75.213718 -189.605412)
		(size 0.508)
		(drill 0.254)
		(layers "F.Cu" "B.Cu")
		(net "PVDDCR_CPU0_P1")
	)
	(via
		(at 71.836534 -190.240412)
		(size 0.508)
		(drill 0.254)
		(layers "F.Cu" "B.Cu")
		(net "PVDDCR_CPU0_P1")
	)
	(via
		(at 84.808314 -195.363084)
		(size 0.508)
		(drill 0.254)
		(layers "F.Cu" "B.Cu")
		(net "PVDDCR_CPU0_P1")
	)
	(via
		(at 105.671112 -233.95432)
		(size 0.4064)
		(drill 0.2032)
		(layers "F.Cu" "B.Cu")
		(net "PVDDCR_CPU0_P1")
	)
	(via
		(at 75.214734 -192.145412)
		(size 0.508)
		(drill 0.254)
		(layers "F.Cu" "B.Cu")
		(net "PVDDCR_CPU0_P1")
	)
	(via
		(at 100.961698 -194.672712)
		(size 0.508)
		(drill 0.254)
		(layers "F.Cu" "B.Cu")
		(net "PVDDCR_CPU0_P1")
	)
	(via
		(at 109.431074 -237.194344)
		(size 0.4064)
		(drill 0.2032)
		(layers "F.Cu" "B.Cu")
		(net "PVDDCR_CPU0_P1")
	)
	(via
		(at 93.205554 -196.610732)
		(size 0.508)
		(drill 0.254)
		(layers "F.Cu" "B.Cu")
		(net "PVDDCR_CPU0_P1")
	)
	(via
		(at 91.935554 -195.33616)
		(size 0.508)
		(drill 0.254)
		(layers "F.Cu" "B.Cu")
		(net "PVDDCR_CPU0_P1")
	)
	(via
		(at 121.644664 -225.854514)
		(size 0.4064)
		(drill 0.2032)
		(layers "F.Cu" "B.Cu")
		(net "PVDDCR_CPU0_P1")
	)
	(via
		(at 83.537298 -201.84364)
		(size 0.6604)
		(drill 0.3302)
		(layers "F.Cu" "B.Cu")
		(net "PVDDCR_CPU0_P1")
	)
	(via
		(at 88.531954 -197.880732)
		(size 0.508)
		(drill 0.254)
		(layers "F.Cu" "B.Cu")
		(net "PVDDCR_CPU0_P1")
	)
	(via
		(at 63.522098 -184.72404)
		(size 0.508)
		(drill 0.254)
		(layers "F.Cu" "B.Cu")
		(net "PVDDCR_CPU0_P1")
	)
	(via
		(at 108.961174 -246.10441)
		(size 0.4064)
		(drill 0.2032)
		(layers "F.Cu" "B.Cu")
		(net "PVDDCR_CPU0_P1")
	)
	(via
		(at 75.848718 -195.98894)
		(size 0.508)
		(drill 0.254)
		(layers "F.Cu" "B.Cu")
		(net "PVDDCR_CPU0_P1")
	)
	(via
		(at 83.537298 -200.44664)
		(size 0.508)
		(drill 0.254)
		(layers "F.Cu" "B.Cu")
		(net "PVDDCR_CPU0_P1")
	)
	(via
		(at 106.085132 -190.155322)
		(size 0.508)
		(drill 0.254)
		(layers "F.Cu" "B.Cu")
		(net "PVDDCR_CPU0_P1")
	)
	(via
		(at 106.085132 -193.33845)
		(size 0.508)
		(drill 0.254)
		(layers "F.Cu" "B.Cu")
		(net "PVDDCR_CPU0_P1")
	)
	(via
		(at 96.948498 -200.39584)
		(size 0.508)
		(drill 0.254)
		(layers "F.Cu" "B.Cu")
		(net "PVDDCR_CPU0_P1")
	)
	(via
		(at 100.971096 -250.15444)
		(size 0.4064)
		(drill 0.2032)
		(layers "F.Cu" "B.Cu")
		(net "PVDDCR_CPU0_P1")
	)
	(via
		(at 126.34468 -230.71455)
		(size 0.4064)
		(drill 0.2032)
		(layers "F.Cu" "B.Cu")
		(net "PVDDCR_CPU0_P1")
	)
	(via
		(at 62.887098 -181.54904)
		(size 0.508)
		(drill 0.254)
		(layers "F.Cu" "B.Cu")
		(net "PVDDCR_CPU0_P1")
	)
	(via
		(at 83.537298 -194.723512)
		(size 0.508)
		(drill 0.254)
		(layers "F.Cu" "B.Cu")
		(net "PVDDCR_CPU0_P1")
	)
	(via
		(at 89.166954 -199.785732)
		(size 0.508)
		(drill 0.254)
		(layers "F.Cu" "B.Cu")
		(net "PVDDCR_CPU0_P1")
	)
	(via
		(at 110.759748 -174.39005)
		(size 0.508)
		(drill 0.254)
		(layers "F.Cu" "B.Cu")
		(net "PVDDCR_CPU0_P1")
	)
	(via
		(at 76.483718 -193.44894)
		(size 0.508)
		(drill 0.254)
		(layers "F.Cu" "B.Cu")
		(net "PVDDCR_CPU0_P1")
	)
	(via
		(at 113.65484 -239.624362)
		(size 0.4064)
		(drill 0.2032)
		(layers "F.Cu" "B.Cu")
		(net "PVDDCR_CPU0_P1")
	)
	(via
		(at 130.104642 -222.61449)
		(size 0.4064)
		(drill 0.2032)
		(layers "F.Cu" "B.Cu")
		(net "PVDDCR_CPU0_P1")
	)
	(via
		(at 98.150934 -248.534428)
		(size 0.4064)
		(drill 0.2032)
		(layers "F.Cu" "B.Cu")
		(net "PVDDCR_CPU0_P1")
	)
	(via
		(at 87.896954 -199.150732)
		(size 0.508)
		(drill 0.254)
		(layers "F.Cu" "B.Cu")
		(net "PVDDCR_CPU0_P1")
	)
	(via
		(at 71.836534 -190.875412)
		(size 0.508)
		(drill 0.254)
		(layers "F.Cu" "B.Cu")
		(net "PVDDCR_CPU0_P1")
	)
	(via
		(at 98.150934 -245.294404)
		(size 0.4064)
		(drill 0.2032)
		(layers "F.Cu" "B.Cu")
		(net "PVDDCR_CPU0_P1")
	)
	(via
		(at 66.874898 -184.08904)
		(size 0.508)
		(drill 0.254)
		(layers "F.Cu" "B.Cu")
		(net "PVDDCR_CPU0_P1")
	)
	(via
		(at 67.509898 -184.72404)
		(size 0.508)
		(drill 0.254)
		(layers "F.Cu" "B.Cu")
		(net "PVDDCR_CPU0_P1")
	)
	(via
		(at 120.23471 -236.384338)
		(size 0.4064)
		(drill 0.2032)
		(layers "F.Cu" "B.Cu")
		(net "PVDDCR_CPU0_P1")
	)
	(via
		(at 76.483718 -194.08394)
		(size 0.508)
		(drill 0.254)
		(layers "F.Cu" "B.Cu")
		(net "PVDDCR_CPU0_P1")
	)
	(via
		(at 127.284734 -222.61449)
		(size 0.4064)
		(drill 0.2032)
		(layers "F.Cu" "B.Cu")
		(net "PVDDCR_CPU0_P1")
	)
	(via
		(at 88.556338 -194.70116)
		(size 0.508)
		(drill 0.254)
		(layers "F.Cu" "B.Cu")
		(net "PVDDCR_CPU0_P1")
	)
	(via
		(at 79.524098 -201.08164)
		(size 0.508)
		(drill 0.254)
		(layers "F.Cu" "B.Cu")
		(net "PVDDCR_CPU0_P1")
	)
	(via
		(at 100.031042 -230.71455)
		(size 0.4064)
		(drill 0.2032)
		(layers "F.Cu" "B.Cu")
		(net "PVDDCR_CPU0_P1")
	)
	(via
		(at 106.611166 -233.95432)
		(size 0.4064)
		(drill 0.2032)
		(layers "F.Cu" "B.Cu")
		(net "PVDDCR_CPU0_P1")
	)
	(via
		(at 103.791004 -227.474526)
		(size 0.4064)
		(drill 0.2032)
		(layers "F.Cu" "B.Cu")
		(net "PVDDCR_CPU0_P1")
	)
	(via
		(at 111.800386 -250.276614)
		(size 0.4826)
		(drill 0.254)
		(layers "F.Cu" "B.Cu")
		(net "PVDDCR_CPU0_P1")
	)
	(via
		(at 101.597714 -195.34124)
		(size 0.508)
		(drill 0.254)
		(layers "F.Cu" "B.Cu")
		(net "PVDDCR_CPU0_P1")
	)
	(via
		(at 120.70461 -245.294404)
		(size 0.4064)
		(drill 0.2032)
		(layers "F.Cu" "B.Cu")
		(net "PVDDCR_CPU0_P1")
	)
	(via
		(at 120.70461 -222.61449)
		(size 0.4064)
		(drill 0.2032)
		(layers "F.Cu" "B.Cu")
		(net "PVDDCR_CPU0_P1")
	)
	(via
		(at 121.174764 -225.044508)
		(size 0.4064)
		(drill 0.2032)
		(layers "F.Cu" "B.Cu")
		(net "PVDDCR_CPU0_P1")
	)
	(via
		(at 67.509898 -185.99404)
		(size 0.508)
		(drill 0.254)
		(layers "F.Cu" "B.Cu")
		(net "PVDDCR_CPU0_P1")
	)
	(via
		(at 116.944648 -248.534428)
		(size 0.4064)
		(drill 0.2032)
		(layers "F.Cu" "B.Cu")
		(net "PVDDCR_CPU0_P1")
	)
	(via
		(at 84.808314 -195.998084)
		(size 0.508)
		(drill 0.254)
		(layers "F.Cu" "B.Cu")
		(net "PVDDCR_CPU0_P1")
	)
	(via
		(at 76.484734 -190.879984)
		(size 0.508)
		(drill 0.254)
		(layers "F.Cu" "B.Cu")
		(net "PVDDCR_CPU0_P1")
	)
	(via
		(at 118.354856 -225.044508)
		(size 0.4064)
		(drill 0.2032)
		(layers "F.Cu" "B.Cu")
		(net "PVDDCR_CPU0_P1")
	)
	(via
		(at 97.583498 -194.672712)
		(size 0.508)
		(drill 0.254)
		(layers "F.Cu" "B.Cu")
		(net "PVDDCR_CPU0_P1")
	)
	(via
		(at 64.157098 -180.908198)
		(size 0.508)
		(drill 0.254)
		(layers "F.Cu" "B.Cu")
		(net "PVDDCR_CPU0_P1")
	)
	(via
		(at 104.261158 -250.964446)
		(size 0.4064)
		(drill 0.2032)
		(layers "F.Cu" "B.Cu")
		(net "PVDDCR_CPU0_P1")
	)
	(via
		(at 84.808314 -196.633084)
		(size 0.508)
		(drill 0.254)
		(layers "F.Cu" "B.Cu")
		(net "PVDDCR_CPU0_P1")
	)
	(via
		(at 84.807298 -199.81164)
		(size 0.508)
		(drill 0.254)
		(layers "F.Cu" "B.Cu")
		(net "PVDDCR_CPU0_P1")
	)
	(via
		(at 106.611166 -248.534428)
		(size 0.4064)
		(drill 0.2032)
		(layers "F.Cu" "B.Cu")
		(net "PVDDCR_CPU0_P1")
	)
	(via
		(at 80.794098 -199.17664)
		(size 0.508)
		(drill 0.254)
		(layers "F.Cu" "B.Cu")
		(net "PVDDCR_CPU0_P1")
	)
	(via
		(at 117.884702 -222.61449)
		(size 0.4064)
		(drill 0.2032)
		(layers "F.Cu" "B.Cu")
		(net "PVDDCR_CPU0_P1")
	)
	(via
		(at 100.031042 -238.814356)
		(size 0.4064)
		(drill 0.2032)
		(layers "F.Cu" "B.Cu")
		(net "PVDDCR_CPU0_P1")
	)
	(via
		(at 84.172298 -199.81164)
		(size 0.508)
		(drill 0.254)
		(layers "F.Cu" "B.Cu")
		(net "PVDDCR_CPU0_P1")
	)
	(via
		(at 72.471534 -190.240412)
		(size 0.508)
		(drill 0.254)
		(layers "F.Cu" "B.Cu")
		(net "PVDDCR_CPU0_P1")
	)
	(via
		(at 114.59464 -249.344434)
		(size 0.4064)
		(drill 0.2032)
		(layers "F.Cu" "B.Cu")
		(net "PVDDCR_CPU0_P1")
	)
	(via
		(at 126.34468 -238.814356)
		(size 0.4064)
		(drill 0.2032)
		(layers "F.Cu" "B.Cu")
		(net "PVDDCR_CPU0_P1")
	)
	(via
		(at 89.166954 -198.515732)
		(size 0.508)
		(drill 0.254)
		(layers "F.Cu" "B.Cu")
		(net "PVDDCR_CPU0_P1")
	)
	(via
		(at 67.536314 -182.813198)
		(size 0.508)
		(drill 0.254)
		(layers "F.Cu" "B.Cu")
		(net "PVDDCR_CPU0_P1")
	)
	(via
		(at 100.326698 -200.42124)
		(size 0.508)
		(drill 0.254)
		(layers "F.Cu" "B.Cu")
		(net "PVDDCR_CPU0_P1")
	)
	(via
		(at 100.326698 -199.15124)
		(size 0.508)
		(drill 0.254)
		(layers "F.Cu" "B.Cu")
		(net "PVDDCR_CPU0_P1")
	)
	(via
		(at 105.450132 -190.79845)
		(size 0.508)
		(drill 0.254)
		(layers "F.Cu" "B.Cu")
		(net "PVDDCR_CPU0_P1")
	)
	(via
		(at 105.671112 -238.814356)
		(size 0.4064)
		(drill 0.2032)
		(layers "F.Cu" "B.Cu")
		(net "PVDDCR_CPU0_P1")
	)
	(via
		(at 92.570554 -199.150732)
		(size 0.508)
		(drill 0.254)
		(layers "F.Cu" "B.Cu")
		(net "PVDDCR_CPU0_P1")
	)
	(via
		(at 116.944648 -233.95432)
		(size 0.4064)
		(drill 0.2032)
		(layers "F.Cu" "B.Cu")
		(net "PVDDCR_CPU0_P1")
	)
	(via
		(at 75.848718 -189.605412)
		(size 0.508)
		(drill 0.254)
		(layers "F.Cu" "B.Cu")
		(net "PVDDCR_CPU0_P1")
	)
	(via
		(at 97.583498 -200.39584)
		(size 0.508)
		(drill 0.254)
		(layers "F.Cu" "B.Cu")
		(net "PVDDCR_CPU0_P1")
	)
	(via
		(at 79.524098 -197.27164)
		(size 0.508)
		(drill 0.254)
		(layers "F.Cu" "B.Cu")
		(net "PVDDCR_CPU0_P1")
	)
	(via
		(at 66.901314 -181.543198)
		(size 0.508)
		(drill 0.254)
		(layers "F.Cu" "B.Cu")
		(net "PVDDCR_CPU0_P1")
	)
	(via
		(at 75.213718 -195.35394)
		(size 0.508)
		(drill 0.254)
		(layers "F.Cu" "B.Cu")
		(net "PVDDCR_CPU0_P1")
	)
	(via
		(at 87.921338 -194.70116)
		(size 0.508)
		(drill 0.254)
		(layers "F.Cu" "B.Cu")
		(net "PVDDCR_CPU0_P1")
	)
	(via
		(at 109.900974 -226.66452)
		(size 0.4064)
		(drill 0.2032)
		(layers "F.Cu" "B.Cu")
		(net "PVDDCR_CPU0_P1")
	)
	(via
		(at 71.835518 -193.44894)
		(size 0.508)
		(drill 0.254)
		(layers "F.Cu" "B.Cu")
		(net "PVDDCR_CPU0_P1")
	)
	(via
		(at 96.948498 -199.76084)
		(size 0.508)
		(drill 0.254)
		(layers "F.Cu" "B.Cu")
		(net "PVDDCR_CPU0_P1")
	)
	(via
		(at 109.900974 -239.624362)
		(size 0.4064)
		(drill 0.2032)
		(layers "F.Cu" "B.Cu")
		(net "PVDDCR_CPU0_P1")
	)
	(via
		(at 67.536314 -183.448198)
		(size 0.508)
		(drill 0.254)
		(layers "F.Cu" "B.Cu")
		(net "PVDDCR_CPU0_P1")
	)
	(via
		(at 93.205554 -195.975732)
		(size 0.508)
		(drill 0.254)
		(layers "F.Cu" "B.Cu")
		(net "PVDDCR_CPU0_P1")
	)
	(via
		(at 87.896954 -198.515732)
		(size 0.508)
		(drill 0.254)
		(layers "F.Cu" "B.Cu")
		(net "PVDDCR_CPU0_P1")
	)
	(via
		(at 66.874898 -186.62904)
		(size 0.508)
		(drill 0.254)
		(layers "F.Cu" "B.Cu")
		(net "PVDDCR_CPU0_P1")
	)
	(via
		(at 97.584514 -195.942712)
		(size 0.508)
		(drill 0.254)
		(layers "F.Cu" "B.Cu")
		(net "PVDDCR_CPU0_P1")
	)
	(via
		(at 126.34468 -248.534428)
		(size 0.4064)
		(drill 0.2032)
		(layers "F.Cu" "B.Cu")
		(net "PVDDCR_CPU0_P1")
	)
	(via
		(at 100.326698 -199.78624)
		(size 0.508)
		(drill 0.254)
		(layers "F.Cu" "B.Cu")
		(net "PVDDCR_CPU0_P1")
	)
	(via
		(at 100.971096 -233.95432)
		(size 0.4064)
		(drill 0.2032)
		(layers "F.Cu" "B.Cu")
		(net "PVDDCR_CPU0_P1")
	)
	(via
		(at 126.34468 -242.05438)
		(size 0.4064)
		(drill 0.2032)
		(layers "F.Cu" "B.Cu")
		(net "PVDDCR_CPU0_P1")
	)
	(via
		(at 123.524772 -238.814356)
		(size 0.4064)
		(drill 0.2032)
		(layers "F.Cu" "B.Cu")
		(net "PVDDCR_CPU0_P1")
	)
	(via
		(at 106.611166 -242.05438)
		(size 0.4064)
		(drill 0.2032)
		(layers "F.Cu" "B.Cu")
		(net "PVDDCR_CPU0_P1")
	)
	(via
		(at 97.211134 -238.814356)
		(size 0.4064)
		(drill 0.2032)
		(layers "F.Cu" "B.Cu")
		(net "PVDDCR_CPU0_P1")
	)
	(via
		(at 106.085132 -194.60845)
		(size 0.508)
		(drill 0.254)
		(layers "F.Cu" "B.Cu")
		(net "PVDDCR_CPU0_P1")
	)
	(via
		(at 97.583498 -199.12584)
		(size 0.508)
		(drill 0.254)
		(layers "F.Cu" "B.Cu")
		(net "PVDDCR_CPU0_P1")
	)
	(via
		(at 114.59464 -246.10441)
		(size 0.4064)
		(drill 0.2032)
		(layers "F.Cu" "B.Cu")
		(net "PVDDCR_CPU0_P1")
	)
	(via
		(at 101.597714 -195.97624)
		(size 0.508)
		(drill 0.254)
		(layers "F.Cu" "B.Cu")
		(net "PVDDCR_CPU0_P1")
	)
	(via
		(at 125.404626 -238.814356)
		(size 0.4064)
		(drill 0.2032)
		(layers "F.Cu" "B.Cu")
		(net "PVDDCR_CPU0_P1")
	)
	(via
		(at 84.172298 -199.17664)
		(size 0.508)
		(drill 0.254)
		(layers "F.Cu" "B.Cu")
		(net "PVDDCR_CPU0_P1")
	)
	(via
		(at 72.470518 -189.605412)
		(size 0.508)
		(drill 0.254)
		(layers "F.Cu" "B.Cu")
		(net "PVDDCR_CPU0_P1")
	)
	(via
		(at 106.085132 -195.24345)
		(size 0.508)
		(drill 0.254)
		(layers "F.Cu" "B.Cu")
		(net "PVDDCR_CPU0_P1")
	)
	(via
		(at 84.172298 -198.54164)
		(size 0.508)
		(drill 0.254)
		(layers "F.Cu" "B.Cu")
		(net "PVDDCR_CPU0_P1")
	)
	(via
		(at 87.896954 -195.975732)
		(size 0.508)
		(drill 0.254)
		(layers "F.Cu" "B.Cu")
		(net "PVDDCR_CPU0_P1")
	)
	(via
		(at 107.550966 -222.61449)
		(size 0.4064)
		(drill 0.2032)
		(layers "F.Cu" "B.Cu")
		(net "PVDDCR_CPU0_P1")
	)
	(via
		(at 89.166954 -201.055732)
		(size 0.508)
		(drill 0.254)
		(layers "F.Cu" "B.Cu")
		(net "PVDDCR_CPU0_P1")
	)
	(via
		(at 108.961174 -239.624362)
		(size 0.4064)
		(drill 0.2032)
		(layers "F.Cu" "B.Cu")
		(net "PVDDCR_CPU0_P1")
	)
	(via
		(at 99.090988 -225.854514)
		(size 0.4064)
		(drill 0.2032)
		(layers "F.Cu" "B.Cu")
		(net "PVDDCR_CPU0_P1")
	)
	(via
		(at 123.994672 -250.964446)
		(size 0.4064)
		(drill 0.2032)
		(layers "F.Cu" "B.Cu")
		(net "PVDDCR_CPU0_P1")
	)
	(via
		(at 79.524098 -194.723512)
		(size 0.508)
		(drill 0.254)
		(layers "F.Cu" "B.Cu")
		(net "PVDDCR_CPU0_P1")
	)
	(via
		(at 66.874898 -184.72404)
		(size 0.508)
		(drill 0.254)
		(layers "F.Cu" "B.Cu")
		(net "PVDDCR_CPU0_P1")
	)
	(via
		(at 126.34468 -222.61449)
		(size 0.4064)
		(drill 0.2032)
		(layers "F.Cu" "B.Cu")
		(net "PVDDCR_CPU0_P1")
	)
	(via
		(at 96.313498 -197.22084)
		(size 0.508)
		(drill 0.254)
		(layers "F.Cu" "B.Cu")
		(net "PVDDCR_CPU0_P1")
	)
	(via
		(at 76.484734 -191.514984)
		(size 0.508)
		(drill 0.254)
		(layers "F.Cu" "B.Cu")
		(net "PVDDCR_CPU0_P1")
	)
	(via
		(at 105.671112 -227.474526)
		(size 0.4064)
		(drill 0.2032)
		(layers "F.Cu" "B.Cu")
		(net "PVDDCR_CPU0_P1")
	)
	(via
		(at 105.450132 -194.60845)
		(size 0.508)
		(drill 0.254)
		(layers "F.Cu" "B.Cu")
		(net "PVDDCR_CPU0_P1")
	)
	(via
		(at 114.59464 -225.044508)
		(size 0.4064)
		(drill 0.2032)
		(layers "F.Cu" "B.Cu")
		(net "PVDDCR_CPU0_P1")
	)
	(via
		(at 96.949514 -195.307712)
		(size 0.508)
		(drill 0.254)
		(layers "F.Cu" "B.Cu")
		(net "PVDDCR_CPU0_P1")
	)
	(via
		(at 75.848718 -194.08394)
		(size 0.508)
		(drill 0.254)
		(layers "F.Cu" "B.Cu")
		(net "PVDDCR_CPU0_P1")
	)
	(via
		(at 109.464348 -190.790322)
		(size 0.508)
		(drill 0.254)
		(layers "F.Cu" "B.Cu")
		(net "PVDDCR_CPU0_P1")
	)
	(via
		(at 100.962714 -195.942712)
		(size 0.508)
		(drill 0.254)
		(layers "F.Cu" "B.Cu")
		(net "PVDDCR_CPU0_P1")
	)
	(via
		(at 110.099348 -191.425322)
		(size 0.508)
		(drill 0.254)
		(layers "F.Cu" "B.Cu")
		(net "PVDDCR_CPU0_P1")
	)
	(via
		(at 100.962714 -197.212712)
		(size 0.508)
		(drill 0.254)
		(layers "F.Cu" "B.Cu")
		(net "PVDDCR_CPU0_P1")
	)
	(via
		(at 97.583498 -197.85584)
		(size 0.508)
		(drill 0.254)
		(layers "F.Cu" "B.Cu")
		(net "PVDDCR_CPU0_P1")
	)
	(via
		(at 109.463332 -190.155322)
		(size 0.508)
		(drill 0.254)
		(layers "F.Cu" "B.Cu")
		(net "PVDDCR_CPU0_P1")
	)
	(via
		(at 125.87478 -249.344434)
		(size 0.4064)
		(drill 0.2032)
		(layers "F.Cu" "B.Cu")
		(net "PVDDCR_CPU0_P1")
	)
	(via
		(at 101.597714 -199.15124)
		(size 0.508)
		(drill 0.254)
		(layers "F.Cu" "B.Cu")
		(net "PVDDCR_CPU0_P1")
	)
	(via
		(at 100.961698 -197.88124)
		(size 0.508)
		(drill 0.254)
		(layers "F.Cu" "B.Cu")
		(net "PVDDCR_CPU0_P1")
	)
	(via
		(at 126.34468 -245.294404)
		(size 0.4064)
		(drill 0.2032)
		(layers "F.Cu" "B.Cu")
		(net "PVDDCR_CPU0_P1")
	)
	(via
		(at 126.34468 -233.95432)
		(size 0.4064)
		(drill 0.2032)
		(layers "F.Cu" "B.Cu")
		(net "PVDDCR_CPU0_P1")
	)
	(via
		(at 108.49102 -237.194344)
		(size 0.4064)
		(drill 0.2032)
		(layers "F.Cu" "B.Cu")
		(net "PVDDCR_CPU0_P1")
	)
	(via
		(at 119.76481 -230.71455)
		(size 0.4064)
		(drill 0.2032)
		(layers "F.Cu" "B.Cu")
		(net "PVDDCR_CPU0_P1")
	)
	(via
		(at 92.569538 -194.70116)
		(size 0.508)
		(drill 0.254)
		(layers "F.Cu" "B.Cu")
		(net "PVDDCR_CPU0_P1")
	)
	(via
		(at 64.158114 -181.543198)
		(size 0.508)
		(drill 0.254)
		(layers "F.Cu" "B.Cu")
		(net "PVDDCR_CPU0_P1")
	)
	(via
		(at 89.192354 -195.33616)
		(size 0.508)
		(drill 0.254)
		(layers "F.Cu" "B.Cu")
		(net "PVDDCR_CPU0_P1")
	)
	(via
		(at 117.884702 -238.814356)
		(size 0.4064)
		(drill 0.2032)
		(layers "F.Cu" "B.Cu")
		(net "PVDDCR_CPU0_P1")
	)
	(via
		(at 111.800386 -246.466614)
		(size 0.4826)
		(drill 0.254)
		(layers "F.Cu" "B.Cu")
		(net "PVDDCR_CPU0_P1")
	)
	(via
		(at 100.327714 -195.307712)
		(size 0.508)
		(drill 0.254)
		(layers "F.Cu" "B.Cu")
		(net "PVDDCR_CPU0_P1")
	)
	(via
		(at 91.935554 -195.97116)
		(size 0.508)
		(drill 0.254)
		(layers "F.Cu" "B.Cu")
		(net "PVDDCR_CPU0_P1")
	)
	(via
		(at 66.900298 -180.908198)
		(size 0.508)
		(drill 0.254)
		(layers "F.Cu" "B.Cu")
		(net "PVDDCR_CPU0_P1")
	)
	(via
		(at 108.49102 -250.15444)
		(size 0.4064)
		(drill 0.2032)
		(layers "F.Cu" "B.Cu")
		(net "PVDDCR_CPU0_P1")
	)
	(via
		(at 96.948498 -197.85584)
		(size 0.508)
		(drill 0.254)
		(layers "F.Cu" "B.Cu")
		(net "PVDDCR_CPU0_P1")
	)
	(via
		(at 94.390972 -224.234502)
		(size 0.4064)
		(drill 0.2032)
		(layers "F.Cu" "B.Cu")
		(net "PVDDCR_CPU0_P1")
	)
	(via
		(at 100.031042 -248.534428)
		(size 0.4064)
		(drill 0.2032)
		(layers "F.Cu" "B.Cu")
		(net "PVDDCR_CPU0_P1")
	)
	(via
		(at 92.570554 -195.97116)
		(size 0.508)
		(drill 0.254)
		(layers "F.Cu" "B.Cu")
		(net "PVDDCR_CPU0_P1")
	)
	(via
		(at 123.524772 -230.71455)
		(size 0.4064)
		(drill 0.2032)
		(layers "F.Cu" "B.Cu")
		(net "PVDDCR_CPU0_P1")
	)
	(via
		(at 97.211134 -248.534428)
		(size 0.4064)
		(drill 0.2032)
		(layers "F.Cu" "B.Cu")
		(net "PVDDCR_CPU0_P1")
	)
	(via
		(at 89.166954 -200.420732)
		(size 0.508)
		(drill 0.254)
		(layers "F.Cu" "B.Cu")
		(net "PVDDCR_CPU0_P1")
	)
	(via
		(at 67.536314 -182.178198)
		(size 0.508)
		(drill 0.254)
		(layers "F.Cu" "B.Cu")
		(net "PVDDCR_CPU0_P1")
	)
	(via
		(at 117.884702 -245.294404)
		(size 0.4064)
		(drill 0.2032)
		(layers "F.Cu" "B.Cu")
		(net "PVDDCR_CPU0_P1")
	)
	(via
		(at 93.205554 -200.420732)
		(size 0.508)
		(drill 0.254)
		(layers "F.Cu" "B.Cu")
		(net "PVDDCR_CPU0_P1")
	)
	(via
		(at 105.671112 -248.534428)
		(size 0.4064)
		(drill 0.2032)
		(layers "F.Cu" "B.Cu")
		(net "PVDDCR_CPU0_P1")
	)
	(via
		(at 97.583498 -199.76084)
		(size 0.508)
		(drill 0.254)
		(layers "F.Cu" "B.Cu")
		(net "PVDDCR_CPU0_P1")
	)
	(via
		(at 105.671112 -242.05438)
		(size 0.4064)
		(drill 0.2032)
		(layers "F.Cu" "B.Cu")
		(net "PVDDCR_CPU0_P1")
	)
	(via
		(at 116.004848 -250.15444)
		(size 0.4064)
		(drill 0.2032)
		(layers "F.Cu" "B.Cu")
		(net "PVDDCR_CPU0_P1")
	)
	(via
		(at 87.896954 -197.880732)
		(size 0.508)
		(drill 0.254)
		(layers "F.Cu" "B.Cu")
		(net "PVDDCR_CPU0_P1")
	)
	(via
		(at 62.887098 -184.72404)
		(size 0.508)
		(drill 0.254)
		(layers "F.Cu" "B.Cu")
		(net "PVDDCR_CPU0_P1")
	)
	(via
		(at 89.192354 -195.97116)
		(size 0.508)
		(drill 0.254)
		(layers "F.Cu" "B.Cu")
		(net "PVDDCR_CPU0_P1")
	)
	(via
		(at 102.38105 -225.044508)
		(size 0.4064)
		(drill 0.2032)
		(layers "F.Cu" "B.Cu")
		(net "PVDDCR_CPU0_P1")
	)
	(via
		(at 76.483718 -189.605412)
		(size 0.508)
		(drill 0.254)
		(layers "F.Cu" "B.Cu")
		(net "PVDDCR_CPU0_P1")
	)
	(via
		(at 96.949514 -196.577712)
		(size 0.508)
		(drill 0.254)
		(layers "F.Cu" "B.Cu")
		(net "PVDDCR_CPU0_P1")
	)
	(via
		(at 92.570554 -201.055732)
		(size 0.508)
		(drill 0.254)
		(layers "F.Cu" "B.Cu")
		(net "PVDDCR_CPU0_P1")
	)
	(via
		(at 80.159098 -199.81164)
		(size 0.508)
		(drill 0.254)
		(layers "F.Cu" "B.Cu")
		(net "PVDDCR_CPU0_P1")
	)
	(via
		(at 102.85095 -230.714296)
		(size 0.4064)
		(drill 0.2032)
		(layers "F.Cu" "B.Cu")
		(net "PVDDCR_CPU0_P1")
	)
	(via
		(at 125.404626 -248.534428)
		(size 0.4064)
		(drill 0.2032)
		(layers "F.Cu" "B.Cu")
		(net "PVDDCR_CPU0_P1")
	)
	(via
		(at 75.214734 -190.240412)
		(size 0.508)
		(drill 0.254)
		(layers "F.Cu" "B.Cu")
		(net "PVDDCR_CPU0_P1")
	)
	(via
		(at 119.76481 -233.95432)
		(size 0.4064)
		(drill 0.2032)
		(layers "F.Cu" "B.Cu")
		(net "PVDDCR_CPU0_P1")
	)
	(via
		(at 96.74098 -225.044508)
		(size 0.4064)
		(drill 0.2032)
		(layers "F.Cu" "B.Cu")
		(net "PVDDCR_CPU0_P1")
	)
	(via
		(at 87.896954 -199.785732)
		(size 0.508)
		(drill 0.254)
		(layers "F.Cu" "B.Cu")
		(net "PVDDCR_CPU0_P1")
	)
	(via
		(at 100.326698 -194.672712)
		(size 0.508)
		(drill 0.254)
		(layers "F.Cu" "B.Cu")
		(net "PVDDCR_CPU0_P1")
	)
	(via
		(at 97.211134 -227.474526)
		(size 0.4064)
		(drill 0.2032)
		(layers "F.Cu" "B.Cu")
		(net "PVDDCR_CPU0_P1")
	)
	(via
		(at 122.584718 -230.71455)
		(size 0.4064)
		(drill 0.2032)
		(layers "F.Cu" "B.Cu")
		(net "PVDDCR_CPU0_P1")
	)
	(via
		(at 105.450132 -196.64045)
		(size 0.6604)
		(drill 0.3302)
		(layers "F.Cu" "B.Cu")
		(net "PVDDCR_CPU0_P1")
	)
	(via
		(at 110.099348 -192.060322)
		(size 0.508)
		(drill 0.254)
		(layers "F.Cu" "B.Cu")
		(net "PVDDCR_CPU0_P1")
	)
	(via
		(at 106.611166 -245.294404)
		(size 0.4064)
		(drill 0.2032)
		(layers "F.Cu" "B.Cu")
		(net "PVDDCR_CPU0_P1")
	)
	(via
		(at 67.509898 -185.35904)
		(size 0.508)
		(drill 0.254)
		(layers "F.Cu" "B.Cu")
		(net "PVDDCR_CPU0_P1")
	)
	(via
		(at 91.935554 -196.60616)
		(size 0.508)
		(drill 0.254)
		(layers "F.Cu" "B.Cu")
		(net "PVDDCR_CPU0_P1")
	)
	(via
		(at 71.200518 -193.44894)
		(size 0.508)
		(drill 0.254)
		(layers "F.Cu" "B.Cu")
		(net "PVDDCR_CPU0_P1")
	)
	(via
		(at 92.570554 -195.33616)
		(size 0.508)
		(drill 0.254)
		(layers "F.Cu" "B.Cu")
		(net "PVDDCR_CPU0_P1")
	)
	(via
		(at 79.524098 -199.17664)
		(size 0.508)
		(drill 0.254)
		(layers "F.Cu" "B.Cu")
		(net "PVDDCR_CPU0_P1")
	)
	(via
		(at 80.159098 -198.54164)
		(size 0.508)
		(drill 0.254)
		(layers "F.Cu" "B.Cu")
		(net "PVDDCR_CPU0_P1")
	)
	(via
		(at 100.961698 -198.51624)
		(size 0.508)
		(drill 0.254)
		(layers "F.Cu" "B.Cu")
		(net "PVDDCR_CPU0_P1")
	)
	(via
		(at 72.471534 -190.875412)
		(size 0.508)
		(drill 0.254)
		(layers "F.Cu" "B.Cu")
		(net "PVDDCR_CPU0_P1")
	)
	(via
		(at 128.694688 -223.424496)
		(size 0.4064)
		(drill 0.2032)
		(layers "F.Cu" "B.Cu")
		(net "PVDDCR_CPU0_P1")
	)
	(via
		(at 72.470518 -192.81394)
		(size 0.508)
		(drill 0.254)
		(layers "F.Cu" "B.Cu")
		(net "PVDDCR_CPU0_P1")
	)
	(via
		(at 76.484734 -190.244984)
		(size 0.508)
		(drill 0.254)
		(layers "F.Cu" "B.Cu")
		(net "PVDDCR_CPU0_P1")
	)
	(via
		(at 108.02112 -249.344434)
		(size 0.4064)
		(drill 0.2032)
		(layers "F.Cu" "B.Cu")
		(net "PVDDCR_CPU0_P1")
	)
	(via
		(at 98.150934 -233.95432)
		(size 0.4064)
		(drill 0.2032)
		(layers "F.Cu" "B.Cu")
		(net "PVDDCR_CPU0_P1")
	)
	(via
		(at 75.848718 -192.81394)
		(size 0.508)
		(drill 0.254)
		(layers "F.Cu" "B.Cu")
		(net "PVDDCR_CPU0_P1")
	)
	(via
		(at 92.570554 -197.24116)
		(size 0.508)
		(drill 0.254)
		(layers "F.Cu" "B.Cu")
		(net "PVDDCR_CPU0_P1")
	)
	(via
		(at 123.524772 -222.61449)
		(size 0.4064)
		(drill 0.2032)
		(layers "F.Cu" "B.Cu")
		(net "PVDDCR_CPU0_P1")
	)
	(via
		(at 93.205554 -198.515732)
		(size 0.508)
		(drill 0.254)
		(layers "F.Cu" "B.Cu")
		(net "PVDDCR_CPU0_P1")
	)
	(via
		(at 106.721148 -192.695322)
		(size 0.508)
		(drill 0.254)
		(layers "F.Cu" "B.Cu")
		(net "PVDDCR_CPU0_P1")
	)
	(via
		(at 63.523114 -183.448198)
		(size 0.508)
		(drill 0.254)
		(layers "F.Cu" "B.Cu")
		(net "PVDDCR_CPU0_P1")
	)
	(via
		(at 102.85095 -250.15444)
		(size 0.4064)
		(drill 0.2032)
		(layers "F.Cu" "B.Cu")
		(net "PVDDCR_CPU0_P1")
	)
	(via
		(at 84.807298 -194.723512)
		(size 0.508)
		(drill 0.254)
		(layers "F.Cu" "B.Cu")
		(net "PVDDCR_CPU0_P1")
	)
	(via
		(at 79.524098 -195.36664)
		(size 0.508)
		(drill 0.254)
		(layers "F.Cu" "B.Cu")
		(net "PVDDCR_CPU0_P1")
	)
	(via
		(at 108.49102 -222.61449)
		(size 0.4064)
		(drill 0.2032)
		(layers "F.Cu" "B.Cu")
		(net "PVDDCR_CPU0_P1")
	)
	(via
		(at 114.59464 -242.864386)
		(size 0.4064)
		(drill 0.2032)
		(layers "F.Cu" "B.Cu")
		(net "PVDDCR_CPU0_P1")
	)
	(via
		(at 123.524772 -248.534428)
		(size 0.4064)
		(drill 0.2032)
		(layers "F.Cu" "B.Cu")
		(net "PVDDCR_CPU0_P1")
	)
	(via
		(at 114.59464 -228.284532)
		(size 0.4064)
		(drill 0.2032)
		(layers "F.Cu" "B.Cu")
		(net "PVDDCR_CPU0_P1")
	)
	(via
		(at 106.086148 -191.425322)
		(size 0.508)
		(drill 0.254)
		(layers "F.Cu" "B.Cu")
		(net "PVDDCR_CPU0_P1")
	)
	(via
		(at 106.086148 -190.790322)
		(size 0.508)
		(drill 0.254)
		(layers "F.Cu" "B.Cu")
		(net "PVDDCR_CPU0_P1")
	)
	(via
		(at 110.099348 -190.790322)
		(size 0.508)
		(drill 0.254)
		(layers "F.Cu" "B.Cu")
		(net "PVDDCR_CPU0_P1")
	)
	(via
		(at 80.795114 -197.263512)
		(size 0.508)
		(drill 0.254)
		(layers "F.Cu" "B.Cu")
		(net "PVDDCR_CPU0_P1")
	)
	(via
		(at 100.327714 -197.212712)
		(size 0.508)
		(drill 0.254)
		(layers "F.Cu" "B.Cu")
		(net "PVDDCR_CPU0_P1")
	)
	(via
		(at 93.204538 -194.70116)
		(size 0.508)
		(drill 0.254)
		(layers "F.Cu" "B.Cu")
		(net "PVDDCR_CPU0_P1")
	)
	(via
		(at 97.583498 -201.03084)
		(size 0.508)
		(drill 0.254)
		(layers "F.Cu" "B.Cu")
		(net "PVDDCR_CPU0_P1")
	)
	(via
		(at 105.671112 -245.294404)
		(size 0.4064)
		(drill 0.2032)
		(layers "F.Cu" "B.Cu")
		(net "PVDDCR_CPU0_P1")
	)
	(via
		(at 93.205554 -197.880732)
		(size 0.508)
		(drill 0.254)
		(layers "F.Cu" "B.Cu")
		(net "PVDDCR_CPU0_P1")
	)
	(via
		(at 102.377748 -178.91125)
		(size 0.508)
		(drill 0.254)
		(layers "F.Cu" "B.Cu")
		(net "PVDDCR_CPU0_P1")
	)
	(via
		(at 107.081066 -236.384338)
		(size 0.4064)
		(drill 0.2032)
		(layers "F.Cu" "B.Cu")
		(net "PVDDCR_CPU0_P1")
	)
	(via
		(at 105.450132 -191.43345)
		(size 0.508)
		(drill 0.254)
		(layers "F.Cu" "B.Cu")
		(net "PVDDCR_CPU0_P1")
	)
	(via
		(at 63.523114 -181.543198)
		(size 0.508)
		(drill 0.254)
		(layers "F.Cu" "B.Cu")
		(net "PVDDCR_CPU0_P1")
	)
	(via
		(at 66.874898 -188.02604)
		(size 0.6604)
		(drill 0.3302)
		(layers "F.Cu" "B.Cu")
		(net "PVDDCR_CPU0_P1")
	)
	(via
		(at 88.531954 -199.785732)
		(size 0.508)
		(drill 0.254)
		(layers "F.Cu" "B.Cu")
		(net "PVDDCR_CPU0_P1")
	)
	(via
		(at 113.65484 -231.524302)
		(size 0.4064)
		(drill 0.2032)
		(layers "F.Cu" "B.Cu")
		(net "PVDDCR_CPU0_P1")
	)
	(via
		(at 107.550966 -225.854514)
		(size 0.4064)
		(drill 0.2032)
		(layers "F.Cu" "B.Cu")
		(net "PVDDCR_CPU0_P1")
	)
	(via
		(at 79.524098 -200.44664)
		(size 0.508)
		(drill 0.254)
		(layers "F.Cu" "B.Cu")
		(net "PVDDCR_CPU0_P1")
	)
	(via
		(at 125.404626 -230.71455)
		(size 0.4064)
		(drill 0.2032)
		(layers "F.Cu" "B.Cu")
		(net "PVDDCR_CPU0_P1")
	)
	(via
		(at 77.264768 -173.84395)
		(size 0.508)
		(drill 0.254)
		(layers "F.Cu" "B.Cu")
		(net "PVDDCR_CPU0_P1")
	)
	(via
		(at 89.166954 -197.880732)
		(size 0.508)
		(drill 0.254)
		(layers "F.Cu" "B.Cu")
		(net "PVDDCR_CPU0_P1")
	)
	(via
		(at 92.570554 -196.60616)
		(size 0.508)
		(drill 0.254)
		(layers "F.Cu" "B.Cu")
		(net "PVDDCR_CPU0_P1")
	)
	(via
		(at 119.294656 -236.384338)
		(size 0.4064)
		(drill 0.2032)
		(layers "F.Cu" "B.Cu")
		(net "PVDDCR_CPU0_P1")
	)
	(via
		(at 75.213718 -196.75094)
		(size 0.6604)
		(drill 0.3302)
		(layers "F.Cu" "B.Cu")
		(net "PVDDCR_CPU0_P1")
	)
	(via
		(at 87.896954 -201.055732)
		(size 0.508)
		(drill 0.254)
		(layers "F.Cu" "B.Cu")
		(net "PVDDCR_CPU0_P1")
	)
	(via
		(at 71.835518 -189.605412)
		(size 0.508)
		(drill 0.254)
		(layers "F.Cu" "B.Cu")
		(net "PVDDCR_CPU0_P1")
	)
	(via
		(at 93.985588 -178.893978)
		(size 0.508)
		(drill 0.254)
		(layers "F.Cu" "B.Cu")
		(net "PVDDCR_CPU0_P1")
	)
	(via
		(at 114.59464 -226.66452)
		(size 0.4064)
		(drill 0.2032)
		(layers "F.Cu" "B.Cu")
		(net "PVDDCR_CPU0_P1")
	)
	(via
		(at 62.887098 -185.35904)
		(size 0.508)
		(drill 0.254)
		(layers "F.Cu" "B.Cu")
		(net "PVDDCR_CPU0_P1")
	)
	(via
		(at 106.721148 -191.425322)
		(size 0.508)
		(drill 0.254)
		(layers "F.Cu" "B.Cu")
		(net "PVDDCR_CPU0_P1")
	)
	(via
		(at 94.390972 -222.61449)
		(size 0.4064)
		(drill 0.2032)
		(layers "F.Cu" "B.Cu")
		(net "PVDDCR_CPU0_P1")
	)
	(via
		(at 80.159098 -197.90664)
		(size 0.508)
		(drill 0.254)
		(layers "F.Cu" "B.Cu")
		(net "PVDDCR_CPU0_P1")
	)
	(via
		(at 106.141012 -249.344434)
		(size 0.4064)
		(drill 0.2032)
		(layers "F.Cu" "B.Cu")
		(net "PVDDCR_CPU0_P1")
	)
	(via
		(at 120.70461 -238.814356)
		(size 0.4064)
		(drill 0.2032)
		(layers "F.Cu" "B.Cu")
		(net "PVDDCR_CPU0_P1")
	)
	(via
		(at 102.38105 -249.344434)
		(size 0.4064)
		(drill 0.2032)
		(layers "F.Cu" "B.Cu")
		(net "PVDDCR_CPU0_P1")
	)
	(via
		(at 100.961698 -199.15124)
		(size 0.508)
		(drill 0.254)
		(layers "F.Cu" "B.Cu")
		(net "PVDDCR_CPU0_P1")
	)
	(via
		(at 79.524098 -199.81164)
		(size 0.508)
		(drill 0.254)
		(layers "F.Cu" "B.Cu")
		(net "PVDDCR_CPU0_P1")
	)
	(via
		(at 72.471534 -191.510412)
		(size 0.508)
		(drill 0.254)
		(layers "F.Cu" "B.Cu")
		(net "PVDDCR_CPU0_P1")
	)
	(via
		(at 71.836534 -191.510412)
		(size 0.508)
		(drill 0.254)
		(layers "F.Cu" "B.Cu")
		(net "PVDDCR_CPU0_P1")
	)
	(via
		(at 84.807298 -200.44664)
		(size 0.508)
		(drill 0.254)
		(layers "F.Cu" "B.Cu")
		(net "PVDDCR_CPU0_P1")
	)
	(via
		(at 66.901314 -182.178198)
		(size 0.508)
		(drill 0.254)
		(layers "F.Cu" "B.Cu")
		(net "PVDDCR_CPU0_P1")
	)
	(via
		(at 113.65484 -228.284532)
		(size 0.4064)
		(drill 0.2032)
		(layers "F.Cu" "B.Cu")
		(net "PVDDCR_CPU0_P1")
	)
	(via
		(at 91.935554 -197.880732)
		(size 0.508)
		(drill 0.254)
		(layers "F.Cu" "B.Cu")
		(net "PVDDCR_CPU0_P1")
	)
	(via
		(at 80.160114 -196.628512)
		(size 0.508)
		(drill 0.254)
		(layers "F.Cu" "B.Cu")
		(net "PVDDCR_CPU0_P1")
	)
	(via
		(at 63.522098 -184.08904)
		(size 0.508)
		(drill 0.254)
		(layers "F.Cu" "B.Cu")
		(net "PVDDCR_CPU0_P1")
	)
	(via
		(at 87.896954 -197.245732)
		(size 0.508)
		(drill 0.254)
		(layers "F.Cu" "B.Cu")
		(net "PVDDCR_CPU0_P1")
	)
	(via
		(at 66.874898 -185.35904)
		(size 0.508)
		(drill 0.254)
		(layers "F.Cu" "B.Cu")
		(net "PVDDCR_CPU0_P1")
	)
	(via
		(at 80.794098 -198.54164)
		(size 0.508)
		(drill 0.254)
		(layers "F.Cu" "B.Cu")
		(net "PVDDCR_CPU0_P1")
	)
	(via
		(at 104.731058 -225.854514)
		(size 0.4064)
		(drill 0.2032)
		(layers "F.Cu" "B.Cu")
		(net "PVDDCR_CPU0_P1")
	)
	(via
		(at 122.584718 -242.05438)
		(size 0.4064)
		(drill 0.2032)
		(layers "F.Cu" "B.Cu")
		(net "PVDDCR_CPU0_P1")
	)
	(via
		(at 67.509898 -186.62904)
		(size 0.508)
		(drill 0.254)
		(layers "F.Cu" "B.Cu")
		(net "PVDDCR_CPU0_P1")
	)
	(via
		(at 75.213718 -192.81394)
		(size 0.508)
		(drill 0.254)
		(layers "F.Cu" "B.Cu")
		(net "PVDDCR_CPU0_P1")
	)
	(via
		(at 109.464348 -192.060322)
		(size 0.508)
		(drill 0.254)
		(layers "F.Cu" "B.Cu")
		(net "PVDDCR_CPU0_P1")
	)
	(via
		(at 108.02112 -250.964446)
		(size 0.4064)
		(drill 0.2032)
		(layers "F.Cu" "B.Cu")
		(net "PVDDCR_CPU0_P1")
	)
	(via
		(at 71.200518 -190.27394)
		(size 0.508)
		(drill 0.254)
		(layers "F.Cu" "B.Cu")
		(net "PVDDCR_CPU0_P1")
	)
	(via
		(at 71.835518 -192.81394)
		(size 0.508)
		(drill 0.254)
		(layers "F.Cu" "B.Cu")
		(net "PVDDCR_CPU0_P1")
	)
	(via
		(at 92.570554 -198.515732)
		(size 0.508)
		(drill 0.254)
		(layers "F.Cu" "B.Cu")
		(net "PVDDCR_CPU0_P1")
	)
	(via
		(at 126.34468 -227.474526)
		(size 0.4064)
		(drill 0.2032)
		(layers "F.Cu" "B.Cu")
		(net "PVDDCR_CPU0_P1")
	)
	(via
		(at 117.884702 -227.474526)
		(size 0.4064)
		(drill 0.2032)
		(layers "F.Cu" "B.Cu")
		(net "PVDDCR_CPU0_P1")
	)
	(via
		(at 79.524098 -196.00164)
		(size 0.508)
		(drill 0.254)
		(layers "F.Cu" "B.Cu")
		(net "PVDDCR_CPU0_P1")
	)
	(via
		(at 84.807298 -199.17664)
		(size 0.508)
		(drill 0.254)
		(layers "F.Cu" "B.Cu")
		(net "PVDDCR_CPU0_P1")
	)
	(via
		(at 118.354856 -249.344434)
		(size 0.4064)
		(drill 0.2032)
		(layers "F.Cu" "B.Cu")
		(net "PVDDCR_CPU0_P1")
	)
	(via
		(at 88.557354 -196.60616)
		(size 0.508)
		(drill 0.254)
		(layers "F.Cu" "B.Cu")
		(net "PVDDCR_CPU0_P1")
	)
	(via
		(at 89.191338 -194.70116)
		(size 0.508)
		(drill 0.254)
		(layers "F.Cu" "B.Cu")
		(net "PVDDCR_CPU0_P1")
	)
	(via
		(at 100.327714 -196.577712)
		(size 0.508)
		(drill 0.254)
		(layers "F.Cu" "B.Cu")
		(net "PVDDCR_CPU0_P1")
	)
	(via
		(at 113.65484 -226.66452)
		(size 0.4064)
		(drill 0.2032)
		(layers "F.Cu" "B.Cu")
		(net "PVDDCR_CPU0_P1")
	)
	(via
		(at 104.261158 -249.344434)
		(size 0.4064)
		(drill 0.2032)
		(layers "F.Cu" "B.Cu")
		(net "PVDDCR_CPU0_P1")
	)
	(via
		(at 96.27108 -222.61449)
		(size 0.4064)
		(drill 0.2032)
		(layers "F.Cu" "B.Cu")
		(net "PVDDCR_CPU0_P1")
	)
	(via
		(at 114.59464 -231.524302)
		(size 0.4064)
		(drill 0.2032)
		(layers "F.Cu" "B.Cu")
		(net "PVDDCR_CPU0_P1")
	)
	(via
		(at 118.824756 -222.61449)
		(size 0.4064)
		(drill 0.2032)
		(layers "F.Cu" "B.Cu")
		(net "PVDDCR_CPU0_P1")
	)
	(via
		(at 100.031042 -227.474526)
		(size 0.4064)
		(drill 0.2032)
		(layers "F.Cu" "B.Cu")
		(net "PVDDCR_CPU0_P1")
	)
	(via
		(at 88.531954 -201.055732)
		(size 0.508)
		(drill 0.254)
		(layers "F.Cu" "B.Cu")
		(net "PVDDCR_CPU0_P1")
	)
	(via
		(at 125.404626 -250.15444)
		(size 0.4064)
		(drill 0.2032)
		(layers "F.Cu" "B.Cu")
		(net "PVDDCR_CPU0_P1")
	)
	(via
		(at 109.900974 -231.524302)
		(size 0.4064)
		(drill 0.2032)
		(layers "F.Cu" "B.Cu")
		(net "PVDDCR_CPU0_P1")
	)
	(via
		(at 114.59464 -239.624362)
		(size 0.4064)
		(drill 0.2032)
		(layers "F.Cu" "B.Cu")
		(net "PVDDCR_CPU0_P1")
	)
	(via
		(at 99.090988 -222.61449)
		(size 0.4064)
		(drill 0.2032)
		(layers "F.Cu" "B.Cu")
		(net "PVDDCR_CPU0_P1")
	)
	(via
		(at 91.934538 -194.70116)
		(size 0.508)
		(drill 0.254)
		(layers "F.Cu" "B.Cu")
		(net "PVDDCR_CPU0_P1")
	)
	(via
		(at 102.85095 -248.534428)
		(size 0.4064)
		(drill 0.2032)
		(layers "F.Cu" "B.Cu")
		(net "PVDDCR_CPU0_P1")
	)
	(via
		(at 100.971096 -238.814356)
		(size 0.4064)
		(drill 0.2032)
		(layers "F.Cu" "B.Cu")
		(net "PVDDCR_CPU0_P1")
	)
	(via
		(at 122.584718 -233.95432)
		(size 0.4064)
		(drill 0.2032)
		(layers "F.Cu" "B.Cu")
		(net "PVDDCR_CPU0_P1")
	)
	(via
		(at 103.791004 -248.534428)
		(size 0.4064)
		(drill 0.2032)
		(layers "F.Cu" "B.Cu")
		(net "PVDDCR_CPU0_P1")
	)
	(via
		(at 108.961174 -242.864386)
		(size 0.4064)
		(drill 0.2032)
		(layers "F.Cu" "B.Cu")
		(net "PVDDCR_CPU0_P1")
	)
	(via
		(at 97.211134 -222.61449)
		(size 0.4064)
		(drill 0.2032)
		(layers "F.Cu" "B.Cu")
		(net "PVDDCR_CPU0_P1")
	)
	(via
		(at 84.173314 -197.263512)
		(size 0.508)
		(drill 0.254)
		(layers "F.Cu" "B.Cu")
		(net "PVDDCR_CPU0_P1")
	)
	(via
		(at 103.791004 -230.71455)
		(size 0.4064)
		(drill 0.2032)
		(layers "F.Cu" "B.Cu")
		(net "PVDDCR_CPU0_P1")
	)
	(via
		(at 91.935554 -199.785732)
		(size 0.508)
		(drill 0.254)
		(layers "F.Cu" "B.Cu")
		(net "PVDDCR_CPU0_P1")
	)
	(via
		(at 102.38105 -250.964446)
		(size 0.4064)
		(drill 0.2032)
		(layers "F.Cu" "B.Cu")
		(net "PVDDCR_CPU0_P1")
	)
	(via
		(at 109.900974 -249.344434)
		(size 0.4064)
		(drill 0.2032)
		(layers "F.Cu" "B.Cu")
		(net "PVDDCR_CPU0_P1")
	)
	(via
		(at 92.570554 -200.420732)
		(size 0.508)
		(drill 0.254)
		(layers "F.Cu" "B.Cu")
		(net "PVDDCR_CPU0_P1")
	)
	(via
		(at 103.791004 -238.814356)
		(size 0.4064)
		(drill 0.2032)
		(layers "F.Cu" "B.Cu")
		(net "PVDDCR_CPU0_P1")
	)
	(via
		(at 105.450132 -193.33845)
		(size 0.508)
		(drill 0.254)
		(layers "F.Cu" "B.Cu")
		(net "PVDDCR_CPU0_P1")
	)
	(via
		(at 105.671112 -222.61449)
		(size 0.4064)
		(drill 0.2032)
		(layers "F.Cu" "B.Cu")
		(net "PVDDCR_CPU0_P1")
	)
	(via
		(at 97.583498 -198.49084)
		(size 0.508)
		(drill 0.254)
		(layers "F.Cu" "B.Cu")
		(net "PVDDCR_CPU0_P1")
	)
	(via
		(at 115.064794 -222.61449)
		(size 0.4064)
		(drill 0.2032)
		(layers "F.Cu" "B.Cu")
		(net "PVDDCR_CPU0_P1")
	)
	(via
		(at 84.807298 -201.08164)
		(size 0.508)
		(drill 0.254)
		(layers "F.Cu" "B.Cu")
		(net "PVDDCR_CPU0_P1")
	)
	(via
		(at 117.884702 -250.15444)
		(size 0.4064)
		(drill 0.2032)
		(layers "F.Cu" "B.Cu")
		(net "PVDDCR_CPU0_P1")
	)
	(via
		(at 100.031042 -242.05438)
		(size 0.4064)
		(drill 0.2032)
		(layers "F.Cu" "B.Cu")
		(net "PVDDCR_CPU0_P1")
	)
	(via
		(at 114.12474 -250.15444)
		(size 0.4064)
		(drill 0.2032)
		(layers "F.Cu" "B.Cu")
		(net "PVDDCR_CPU0_P1")
	)
	(via
		(at 71.200518 -192.17894)
		(size 0.508)
		(drill 0.254)
		(layers "F.Cu" "B.Cu")
		(net "PVDDCR_CPU0_P1")
	)
	(via
		(at 84.173314 -195.993512)
		(size 0.508)
		(drill 0.254)
		(layers "F.Cu" "B.Cu")
		(net "PVDDCR_CPU0_P1")
	)
	(via
		(at 66.901314 -183.448198)
		(size 0.508)
		(drill 0.254)
		(layers "F.Cu" "B.Cu")
		(net "PVDDCR_CPU0_P1")
	)
	(via
		(at 123.524772 -245.294404)
		(size 0.4064)
		(drill 0.2032)
		(layers "F.Cu" "B.Cu")
		(net "PVDDCR_CPU0_P1")
	)
	(via
		(at 64.157098 -185.35904)
		(size 0.508)
		(drill 0.254)
		(layers "F.Cu" "B.Cu")
		(net "PVDDCR_CPU0_P1")
	)
	(via
		(at 123.524772 -227.474526)
		(size 0.4064)
		(drill 0.2032)
		(layers "F.Cu" "B.Cu")
		(net "PVDDCR_CPU0_P1")
	)
	(via
		(at 91.935554 -201.055732)
		(size 0.508)
		(drill 0.254)
		(layers "F.Cu" "B.Cu")
		(net "PVDDCR_CPU0_P1")
	)
	(via
		(at 63.522098 -185.35904)
		(size 0.508)
		(drill 0.254)
		(layers "F.Cu" "B.Cu")
		(net "PVDDCR_CPU0_P1")
	)
	(via
		(at 75.213718 -193.44894)
		(size 0.508)
		(drill 0.254)
		(layers "F.Cu" "B.Cu")
		(net "PVDDCR_CPU0_P1")
	)
	(via
		(at 119.76481 -245.294404)
		(size 0.4064)
		(drill 0.2032)
		(layers "F.Cu" "B.Cu")
		(net "PVDDCR_CPU0_P1")
	)
	(via
		(at 97.584514 -195.307712)
		(size 0.508)
		(drill 0.254)
		(layers "F.Cu" "B.Cu")
		(net "PVDDCR_CPU0_P1")
	)
	(via
		(at 85.588348 -178.96205)
		(size 0.508)
		(drill 0.254)
		(layers "F.Cu" "B.Cu")
		(net "PVDDCR_CPU0_P1")
	)
	(via
		(at 75.849734 -190.240412)
		(size 0.508)
		(drill 0.254)
		(layers "F.Cu" "B.Cu")
		(net "PVDDCR_CPU0_P1")
	)
	(via
		(at 126.814834 -225.044508)
		(size 0.4064)
		(drill 0.2032)
		(layers "F.Cu" "B.Cu")
		(net "PVDDCR_CPU0_P1")
	)
	(via
		(at 80.794098 -201.08164)
		(size 0.508)
		(drill 0.254)
		(layers "F.Cu" "B.Cu")
		(net "PVDDCR_CPU0_P1")
	)
	(via
		(at 100.962714 -195.307712)
		(size 0.508)
		(drill 0.254)
		(layers "F.Cu" "B.Cu")
		(net "PVDDCR_CPU0_P1")
	)
	(via
		(at 75.849734 -190.875412)
		(size 0.508)
		(drill 0.254)
		(layers "F.Cu" "B.Cu")
		(net "PVDDCR_CPU0_P1")
	)
	(via
		(at 109.464348 -191.425322)
		(size 0.508)
		(drill 0.254)
		(layers "F.Cu" "B.Cu")
		(net "PVDDCR_CPU0_P1")
	)
	(via
		(at 79.524098 -197.90664)
		(size 0.508)
		(drill 0.254)
		(layers "F.Cu" "B.Cu")
		(net "PVDDCR_CPU0_P1")
	)
	(via
		(at 106.085132 -193.97345)
		(size 0.508)
		(drill 0.254)
		(layers "F.Cu" "B.Cu")
		(net "PVDDCR_CPU0_P1")
	)
	(via
		(at 96.313498 -194.672712)
		(size 0.508)
		(drill 0.254)
		(layers "F.Cu" "B.Cu")
		(net "PVDDCR_CPU0_P1")
	)
	(via
		(at 116.474748 -250.964446)
		(size 0.4064)
		(drill 0.2032)
		(layers "F.Cu" "B.Cu")
		(net "PVDDCR_CPU0_P1")
	)
	(via
		(at 80.794098 -197.90664)
		(size 0.508)
		(drill 0.254)
		(layers "F.Cu" "B.Cu")
		(net "PVDDCR_CPU0_P1")
	)
	(via
		(at 97.211134 -230.71455)
		(size 0.4064)
		(drill 0.2032)
		(layers "F.Cu" "B.Cu")
		(net "PVDDCR_CPU0_P1")
	)
	(via
		(at 106.720132 -193.33845)
		(size 0.508)
		(drill 0.254)
		(layers "F.Cu" "B.Cu")
		(net "PVDDCR_CPU0_P1")
	)
	(via
		(at 100.971096 -227.474526)
		(size 0.4064)
		(drill 0.2032)
		(layers "F.Cu" "B.Cu")
		(net "PVDDCR_CPU0_P1")
	)
	(via
		(at 93.205554 -199.785732)
		(size 0.508)
		(drill 0.254)
		(layers "F.Cu" "B.Cu")
		(net "PVDDCR_CPU0_P1")
	)
	(via
		(at 62.887098 -182.81904)
		(size 0.508)
		(drill 0.254)
		(layers "F.Cu" "B.Cu")
		(net "PVDDCR_CPU0_P1")
	)
	(via
		(at 98.150934 -242.05438)
		(size 0.4064)
		(drill 0.2032)
		(layers "F.Cu" "B.Cu")
		(net "PVDDCR_CPU0_P1")
	)
	(via
		(at 71.836534 -192.145412)
		(size 0.508)
		(drill 0.254)
		(layers "F.Cu" "B.Cu")
		(net "PVDDCR_CPU0_P1")
	)
	(via
		(at 110.371128 -250.15444)
		(size 0.4064)
		(drill 0.2032)
		(layers "F.Cu" "B.Cu")
		(net "PVDDCR_CPU0_P1")
	)
	(via
		(at 87.896954 -196.610732)
		(size 0.508)
		(drill 0.254)
		(layers "F.Cu" "B.Cu")
		(net "PVDDCR_CPU0_P1")
	)
	(via
		(at 105.450132 -190.155322)
		(size 0.508)
		(drill 0.254)
		(layers "F.Cu" "B.Cu")
		(net "PVDDCR_CPU0_P1")
	)
	(via
		(at 75.213718 -194.71894)
		(size 0.508)
		(drill 0.254)
		(layers "F.Cu" "B.Cu")
		(net "PVDDCR_CPU0_P1")
	)
	(via
		(at 100.326698 -198.51624)
		(size 0.508)
		(drill 0.254)
		(layers "F.Cu" "B.Cu")
		(net "PVDDCR_CPU0_P1")
	)
	(via
		(at 117.884702 -233.95432)
		(size 0.4064)
		(drill 0.2032)
		(layers "F.Cu" "B.Cu")
		(net "PVDDCR_CPU0_P1")
	)
	(via
		(at 123.524772 -242.05438)
		(size 0.4064)
		(drill 0.2032)
		(layers "F.Cu" "B.Cu")
		(net "PVDDCR_CPU0_P1")
	)
	(via
		(at 64.158114 -182.178198)
		(size 0.508)
		(drill 0.254)
		(layers "F.Cu" "B.Cu")
		(net "PVDDCR_CPU0_P1")
	)
	(via
		(at 67.535298 -180.908198)
		(size 0.508)
		(drill 0.254)
		(layers "F.Cu" "B.Cu")
		(net "PVDDCR_CPU0_P1")
	)
	(via
		(at 114.12474 -237.194344)
		(size 0.4064)
		(drill 0.2032)
		(layers "F.Cu" "B.Cu")
		(net "PVDDCR_CPU0_P1")
	)
	(via
		(at 84.807298 -197.90664)
		(size 0.508)
		(drill 0.254)
		(layers "F.Cu" "B.Cu")
		(net "PVDDCR_CPU0_P1")
	)
	(via
		(at 76.483718 -192.81394)
		(size 0.508)
		(drill 0.254)
		(layers "F.Cu" "B.Cu")
		(net "PVDDCR_CPU0_P1")
	)
	(via
		(at 92.570554 -197.880732)
		(size 0.508)
		(drill 0.254)
		(layers "F.Cu" "B.Cu")
		(net "PVDDCR_CPU0_P1")
	)
	(via
		(at 84.808314 -197.268084)
		(size 0.508)
		(drill 0.254)
		(layers "F.Cu" "B.Cu")
		(net "PVDDCR_CPU0_P1")
	)
	(via
		(at 75.849734 -191.510412)
		(size 0.508)
		(drill 0.254)
		(layers "F.Cu" "B.Cu")
		(net "PVDDCR_CPU0_P1")
	)
	(via
		(at 75.848718 -194.71894)
		(size 0.508)
		(drill 0.254)
		(layers "F.Cu" "B.Cu")
		(net "PVDDCR_CPU0_P1")
	)
	(via
		(at 101.597714 -196.61124)
		(size 0.508)
		(drill 0.254)
		(layers "F.Cu" "B.Cu")
		(net "PVDDCR_CPU0_P1")
	)
	(via
		(at 101.91115 -222.61449)
		(size 0.4064)
		(drill 0.2032)
		(layers "F.Cu" "B.Cu")
		(net "PVDDCR_CPU0_P1")
	)
	(via
		(at 123.524772 -233.95432)
		(size 0.4064)
		(drill 0.2032)
		(layers "F.Cu" "B.Cu")
		(net "PVDDCR_CPU0_P1")
	)
	(via
		(at 83.537298 -201.08164)
		(size 0.508)
		(drill 0.254)
		(layers "F.Cu" "B.Cu")
		(net "PVDDCR_CPU0_P1")
	)
	(via
		(at 123.994672 -249.344434)
		(size 0.4064)
		(drill 0.2032)
		(layers "F.Cu" "B.Cu")
		(net "PVDDCR_CPU0_P1")
	)
	(via
		(at 129.164842 -222.61449)
		(size 0.4064)
		(drill 0.2032)
		(layers "F.Cu" "B.Cu")
		(net "PVDDCR_CPU0_P1")
	)
	(via
		(at 80.795114 -195.993512)
		(size 0.508)
		(drill 0.254)
		(layers "F.Cu" "B.Cu")
		(net "PVDDCR_CPU0_P1")
	)
	(via
		(at 123.524772 -250.15444)
		(size 0.4064)
		(drill 0.2032)
		(layers "F.Cu" "B.Cu")
		(net "PVDDCR_CPU0_P1")
	)
	(via
		(at 99.561142 -225.044508)
		(size 0.4064)
		(drill 0.2032)
		(layers "F.Cu" "B.Cu")
		(net "PVDDCR_CPU0_P1")
	)
	(via
		(at 93.205554 -199.150732)
		(size 0.508)
		(drill 0.254)
		(layers "F.Cu" "B.Cu")
		(net "PVDDCR_CPU0_P1")
	)
	(via
		(at 96.313498 -198.49084)
		(size 0.508)
		(drill 0.254)
		(layers "F.Cu" "B.Cu")
		(net "PVDDCR_CPU0_P1")
	)
	(via
		(at 104.261158 -236.384338)
		(size 0.4064)
		(drill 0.2032)
		(layers "F.Cu" "B.Cu")
		(net "PVDDCR_CPU0_P1")
	)
	(via
		(at 101.596698 -194.672712)
		(size 0.508)
		(drill 0.254)
		(layers "F.Cu" "B.Cu")
		(net "PVDDCR_CPU0_P1")
	)
	(via
		(at 68.951348 -165.146736)
		(size 0.508)
		(drill 0.254)
		(layers "F.Cu" "B.Cu")
		(net "PVDDCR_CPU0_P1")
	)
	(via
		(at 105.450132 -193.97345)
		(size 0.508)
		(drill 0.254)
		(layers "F.Cu" "B.Cu")
		(net "PVDDCR_CPU0_P1")
	)
	(via
		(at 106.720132 -193.97345)
		(size 0.508)
		(drill 0.254)
		(layers "F.Cu" "B.Cu")
		(net "PVDDCR_CPU0_P1")
	)
	(via
		(at 114.59464 -234.764326)
		(size 0.4064)
		(drill 0.2032)
		(layers "F.Cu" "B.Cu")
		(net "PVDDCR_CPU0_P1")
	)
	(via
		(at 118.824756 -225.854514)
		(size 0.4064)
		(drill 0.2032)
		(layers "F.Cu" "B.Cu")
		(net "PVDDCR_CPU0_P1")
	)
	(via
		(at 122.114818 -249.344434)
		(size 0.4064)
		(drill 0.2032)
		(layers "F.Cu" "B.Cu")
		(net "PVDDCR_CPU0_P1")
	)
	(via
		(at 75.849734 -192.145412)
		(size 0.508)
		(drill 0.254)
		(layers "F.Cu" "B.Cu")
		(net "PVDDCR_CPU0_P1")
	)
	(via
		(at 88.531954 -199.150732)
		(size 0.508)
		(drill 0.254)
		(layers "F.Cu" "B.Cu")
		(net "PVDDCR_CPU0_P1")
	)
	(via
		(at 80.160114 -195.993512)
		(size 0.508)
		(drill 0.254)
		(layers "F.Cu" "B.Cu")
		(net "PVDDCR_CPU0_P1")
	)
	(via
		(at 96.948498 -198.49084)
		(size 0.508)
		(drill 0.254)
		(layers "F.Cu" "B.Cu")
		(net "PVDDCR_CPU0_P1")
	)
	(via
		(at 98.150934 -227.474526)
		(size 0.4064)
		(drill 0.2032)
		(layers "F.Cu" "B.Cu")
		(net "PVDDCR_CPU0_P1")
	)
	(via
		(at 109.900974 -246.10441)
		(size 0.4064)
		(drill 0.2032)
		(layers "F.Cu" "B.Cu")
		(net "PVDDCR_CPU0_P1")
	)
	(via
		(at 64.157098 -184.72404)
		(size 0.508)
		(drill 0.254)
		(layers "F.Cu" "B.Cu")
		(net "PVDDCR_CPU0_P1")
	)
	(via
		(at 119.76481 -238.814356)
		(size 0.4064)
		(drill 0.2032)
		(layers "F.Cu" "B.Cu")
		(net "PVDDCR_CPU0_P1")
	)
	(via
		(at 93.450918 -222.61449)
		(size 0.4064)
		(drill 0.2032)
		(layers "F.Cu" "B.Cu")
		(net "PVDDCR_CPU0_P1")
	)
	(via
		(at 63.522098 -180.908198)
		(size 0.508)
		(drill 0.254)
		(layers "F.Cu" "B.Cu")
		(net "PVDDCR_CPU0_P1")
	)
	(via
		(at 116.474748 -249.344434)
		(size 0.4064)
		(drill 0.2032)
		(layers "F.Cu" "B.Cu")
		(net "PVDDCR_CPU0_P1")
	)
	(via
		(at 125.404626 -233.95432)
		(size 0.4064)
		(drill 0.2032)
		(layers "F.Cu" "B.Cu")
		(net "PVDDCR_CPU0_P1")
	)
	(via
		(at 116.004848 -222.61449)
		(size 0.4064)
		(drill 0.2032)
		(layers "F.Cu" "B.Cu")
		(net "PVDDCR_CPU0_P1")
	)
	(via
		(at 100.326698 -197.88124)
		(size 0.508)
		(drill 0.254)
		(layers "F.Cu" "B.Cu")
		(net "PVDDCR_CPU0_P1")
	)
	(via
		(at 121.644664 -250.15444)
		(size 0.4064)
		(drill 0.2032)
		(layers "F.Cu" "B.Cu")
		(net "PVDDCR_CPU0_P1")
	)
	(via
		(at 93.205554 -201.055732)
		(size 0.508)
		(drill 0.254)
		(layers "F.Cu" "B.Cu")
		(net "PVDDCR_CPU0_P1")
	)
	(via
		(at 63.523114 -182.178198)
		(size 0.508)
		(drill 0.254)
		(layers "F.Cu" "B.Cu")
		(net "PVDDCR_CPU0_P1")
	)
	(via
		(at 106.086148 -192.695322)
		(size 0.508)
		(drill 0.254)
		(layers "F.Cu" "B.Cu")
		(net "PVDDCR_CPU0_P1")
	)
	(via
		(at 67.509898 -187.26404)
		(size 0.508)
		(drill 0.254)
		(layers "F.Cu" "B.Cu")
		(net "PVDDCR_CPU0_P1")
	)
	(via
		(at 104.731058 -222.61449)
		(size 0.4064)
		(drill 0.2032)
		(layers "F.Cu" "B.Cu")
		(net "PVDDCR_CPU0_P1")
	)
	(via
		(at 127.284734 -225.854514)
		(size 0.4064)
		(drill 0.2032)
		(layers "F.Cu" "B.Cu")
		(net "PVDDCR_CPU0_P1")
	)
	(via
		(at 100.962714 -196.577712)
		(size 0.508)
		(drill 0.254)
		(layers "F.Cu" "B.Cu")
		(net "PVDDCR_CPU0_P1")
	)
	(via
		(at 96.313498 -197.85584)
		(size 0.508)
		(drill 0.254)
		(layers "F.Cu" "B.Cu")
		(net "PVDDCR_CPU0_P1")
	)
	(via
		(at 110.098332 -190.155322)
		(size 0.508)
		(drill 0.254)
		(layers "F.Cu" "B.Cu")
		(net "PVDDCR_CPU0_P1")
	)
	(via
		(at 76.483718 -194.71894)
		(size 0.508)
		(drill 0.254)
		(layers "F.Cu" "B.Cu")
		(net "PVDDCR_CPU0_P1")
	)
	(via
		(at 83.537298 -199.81164)
		(size 0.508)
		(drill 0.254)
		(layers "F.Cu" "B.Cu")
		(net "PVDDCR_CPU0_P1")
	)
	(via
		(at 62.887098 -180.908198)
		(size 0.508)
		(drill 0.254)
		(layers "F.Cu" "B.Cu")
		(net "PVDDCR_CPU0_P1")
	)
	(via
		(at 106.141012 -250.964446)
		(size 0.4064)
		(drill 0.2032)
		(layers "F.Cu" "B.Cu")
		(net "PVDDCR_CPU0_P1")
	)
	(via
		(at 97.211134 -242.05438)
		(size 0.4064)
		(drill 0.2032)
		(layers "F.Cu" "B.Cu")
		(net "PVDDCR_CPU0_P1")
	)
	(via
		(at 106.611166 -250.15444)
		(size 0.4064)
		(drill 0.2032)
		(layers "F.Cu" "B.Cu")
		(net "PVDDCR_CPU0_P1")
	)
	(via
		(at 96.949514 -195.942712)
		(size 0.508)
		(drill 0.254)
		(layers "F.Cu" "B.Cu")
		(net "PVDDCR_CPU0_P1")
	)
	(via
		(at 67.509898 -184.08904)
		(size 0.508)
		(drill 0.254)
		(layers "F.Cu" "B.Cu")
		(net "PVDDCR_CPU0_P1")
	)
	(via
		(at 111.800386 -248.371614)
		(size 0.4826)
		(drill 0.254)
		(layers "F.Cu" "B.Cu")
		(net "PVDDCR_CPU0_P1")
	)
	(via
		(at 116.004848 -225.854514)
		(size 0.4064)
		(drill 0.2032)
		(layers "F.Cu" "B.Cu")
		(net "PVDDCR_CPU0_P1")
	)
	(via
		(at 80.160114 -197.263512)
		(size 0.508)
		(drill 0.254)
		(layers "F.Cu" "B.Cu")
		(net "PVDDCR_CPU0_P1")
	)
	(via
		(at 83.537298 -198.54164)
		(size 0.508)
		(drill 0.254)
		(layers "F.Cu" "B.Cu")
		(net "PVDDCR_CPU0_P1")
	)
	(via
		(at 88.557354 -197.24116)
		(size 0.508)
		(drill 0.254)
		(layers "F.Cu" "B.Cu")
		(net "PVDDCR_CPU0_P1")
	)
	(via
		(at 88.557354 -195.33616)
		(size 0.508)
		(drill 0.254)
		(layers "F.Cu" "B.Cu")
		(net "PVDDCR_CPU0_P1")
	)
	(via
		(at 62.887098 -183.45404)
		(size 0.508)
		(drill 0.254)
		(layers "F.Cu" "B.Cu")
		(net "PVDDCR_CPU0_P1")
	)
	(via
		(at 64.157098 -184.08904)
		(size 0.508)
		(drill 0.254)
		(layers "F.Cu" "B.Cu")
		(net "PVDDCR_CPU0_P1")
	)
	(via
		(at 80.159098 -201.08164)
		(size 0.508)
		(drill 0.254)
		(layers "F.Cu" "B.Cu")
		(net "PVDDCR_CPU0_P1")
	)
	(via
		(at 96.948498 -194.672712)
		(size 0.508)
		(drill 0.254)
		(layers "F.Cu" "B.Cu")
		(net "PVDDCR_CPU0_P1")
	)
	(segment
		(start 94.34322 -179.610512)
		(end 94.34322 -179.25161)
		(width 0.381)
		(layer "B.Cu")
		(net "PVDDCR_CPU0_P1")
	)
	(segment
		(start 69.30898 -165.86327)
		(end 69.30898 -165.504368)
		(width 0.381)
		(layer "B.Cu")
		(net "PVDDCR_CPU0_P1")
	)
	(segment
		(start 77.6224 -174.201582)
		(end 77.264768 -173.84395)
		(width 0.381)
		(layer "B.Cu")
		(net "PVDDCR_CPU0_P1")
	)
	(segment
		(start 111.11738 -175.106584)
		(end 111.11738 -174.747682)
		(width 0.381)
		(layer "B.Cu")
		(net "PVDDCR_CPU0_P1")
	)
	(segment
		(start 69.30898 -165.504368)
		(end 68.951348 -165.146736)
		(width 0.381)
		(layer "B.Cu")
		(net "PVDDCR_CPU0_P1")
	)
	(segment
		(start 85.94598 -179.678584)
		(end 85.94598 -179.319682)
		(width 0.381)
		(layer "B.Cu")
		(net "PVDDCR_CPU0_P1")
	)
	(segment
		(start 102.73538 -179.268882)
		(end 102.377748 -178.91125)
		(width 0.381)
		(layer "B.Cu")
		(net "PVDDCR_CPU0_P1")
	)
	(segment
		(start 77.6224 -174.560484)
		(end 77.6224 -174.201582)
		(width 0.381)
		(layer "B.Cu")
		(net "PVDDCR_CPU0_P1")
	)
	(segment
		(start 94.34322 -179.25161)
		(end 93.985588 -178.893978)
		(width 0.381)
		(layer "B.Cu")
		(net "PVDDCR_CPU0_P1")
	)
	(segment
		(start 111.11738 -174.747682)
		(end 110.759748 -174.39005)
		(width 0.381)
		(layer "B.Cu")
		(net "PVDDCR_CPU0_P1")
	)
	(segment
		(start 102.73538 -179.627784)
		(end 102.73538 -179.268882)
		(width 0.381)
		(layer "B.Cu")
		(net "PVDDCR_CPU0_P1")
	)
	(segment
		(start 85.94598 -179.319682)
		(end 85.588348 -178.96205)
		(width 0.381)
		(layer "B.Cu")
		(net "PVDDCR_CPU0_P1")
	)
	(segment
		(start 94.276926 -180.02504)
		(end 93.563694 -180.738272)
		(width 0.381)
		(layer "In2.Cu")
		(net "PVDDCR_CPU0_P1")
	)
	(segment
		(start 110.098332 -189.687962)
		(end 110.098332 -190.155322)
		(width 0.381)
		(layer "In2.Cu")
		(net "PVDDCR_CPU0_P1")
	)
	(segment
		(start 94.276926 -179.185316)
		(end 94.276926 -180.02504)
		(width 0.381)
		(layer "In2.Cu")
		(net "PVDDCR_CPU0_P1")
	)
	(segment
		(start 93.985588 -178.893978)
		(end 94.276926 -179.185316)
		(width 0.381)
		(layer "In2.Cu")
		(net "PVDDCR_CPU0_P1")
	)
	(segment
		(start 76.540614 -175.990504)
		(end 76.540614 -189.548516)
		(width 0.381)
		(layer "In2.Cu")
		(net "PVDDCR_CPU0_P1")
	)
	(segment
		(start 93.563694 -182.229252)
		(end 93.267784 -182.525162)
		(width 0.381)
		(layer "In2.Cu")
		(net "PVDDCR_CPU0_P1")
	)
	(segment
		(start 111.051086 -175.521112)
		(end 110.008162 -176.564036)
		(width 0.381)
		(layer "In2.Cu")
		(net "PVDDCR_CPU0_P1")
	)
	(segment
		(start 69.242686 -166.277798)
		(end 68.204334 -167.31615)
		(width 0.381)
		(layer "In2.Cu")
		(net "PVDDCR_CPU0_P1")
	)
	(segment
		(start 102.669086 -179.202588)
		(end 102.669086 -180.042312)
		(width 0.381)
		(layer "In2.Cu")
		(net "PVDDCR_CPU0_P1")
	)
	(segment
		(start 84.850224 -181.122574)
		(end 84.850224 -194.680586)
		(width 0.381)
		(layer "In2.Cu")
		(net "PVDDCR_CPU0_P1")
	)
	(segment
		(start 77.556106 -174.135288)
		(end 77.556106 -174.975012)
		(width 0.381)
		(layer "In2.Cu")
		(net "PVDDCR_CPU0_P1")
	)
	(segment
		(start 110.008162 -189.597792)
		(end 110.098332 -189.687962)
		(width 0.381)
		(layer "In2.Cu")
		(net "PVDDCR_CPU0_P1")
	)
	(segment
		(start 77.556106 -174.975012)
		(end 76.540614 -175.990504)
		(width 0.381)
		(layer "In2.Cu")
		(net "PVDDCR_CPU0_P1")
	)
	(segment
		(start 76.540614 -189.548516)
		(end 76.483718 -189.605412)
		(width 0.381)
		(layer "In2.Cu")
		(net "PVDDCR_CPU0_P1")
	)
	(segment
		(start 102.669086 -180.042312)
		(end 101.626162 -181.085236)
		(width 0.381)
		(layer "In2.Cu")
		(net "PVDDCR_CPU0_P1")
	)
	(segment
		(start 85.879686 -180.093112)
		(end 84.850224 -181.122574)
		(width 0.381)
		(layer "In2.Cu")
		(net "PVDDCR_CPU0_P1")
	)
	(segment
		(start 93.267784 -194.637914)
		(end 93.204538 -194.70116)
		(width 0.381)
		(layer "In2.Cu")
		(net "PVDDCR_CPU0_P1")
	)
	(segment
		(start 101.626162 -194.643248)
		(end 101.596698 -194.672712)
		(width 0.381)
		(layer "In2.Cu")
		(net "PVDDCR_CPU0_P1")
	)
	(segment
		(start 110.759748 -174.39005)
		(end 111.051086 -174.681388)
		(width 0.381)
		(layer "In2.Cu")
		(net "PVDDCR_CPU0_P1")
	)
	(segment
		(start 85.588348 -178.96205)
		(end 85.879686 -179.253388)
		(width 0.381)
		(layer "In2.Cu")
		(net "PVDDCR_CPU0_P1")
	)
	(segment
		(start 68.204334 -167.31615)
		(end 68.204334 -180.239162)
		(width 0.381)
		(layer "In2.Cu")
		(net "PVDDCR_CPU0_P1")
	)
	(segment
		(start 68.951348 -165.146736)
		(end 69.242686 -165.438074)
		(width 0.381)
		(layer "In2.Cu")
		(net "PVDDCR_CPU0_P1")
	)
	(segment
		(start 69.242686 -165.438074)
		(end 69.242686 -166.277798)
		(width 0.381)
		(layer "In2.Cu")
		(net "PVDDCR_CPU0_P1")
	)
	(segment
		(start 85.879686 -179.253388)
		(end 85.879686 -180.093112)
		(width 0.381)
		(layer "In2.Cu")
		(net "PVDDCR_CPU0_P1")
	)
	(segment
		(start 68.204334 -180.239162)
		(end 67.535298 -180.908198)
		(width 0.381)
		(layer "In2.Cu")
		(net "PVDDCR_CPU0_P1")
	)
	(segment
		(start 102.377748 -178.91125)
		(end 102.669086 -179.202588)
		(width 0.381)
		(layer "In2.Cu")
		(net "PVDDCR_CPU0_P1")
	)
	(segment
		(start 93.267784 -182.525162)
		(end 93.267784 -194.637914)
		(width 0.381)
		(layer "In2.Cu")
		(net "PVDDCR_CPU0_P1")
	)
	(segment
		(start 110.008162 -176.564036)
		(end 110.008162 -189.597792)
		(width 0.381)
		(layer "In2.Cu")
		(net "PVDDCR_CPU0_P1")
	)
	(segment
		(start 84.850224 -194.680586)
		(end 84.807298 -194.723512)
		(width 0.381)
		(layer "In2.Cu")
		(net "PVDDCR_CPU0_P1")
	)
	(segment
		(start 101.626162 -181.085236)
		(end 101.626162 -194.643248)
		(width 0.381)
		(layer "In2.Cu")
		(net "PVDDCR_CPU0_P1")
	)
	(segment
		(start 111.051086 -174.681388)
		(end 111.051086 -175.521112)
		(width 0.381)
		(layer "In2.Cu")
		(net "PVDDCR_CPU0_P1")
	)
	(segment
		(start 93.563694 -180.738272)
		(end 93.563694 -182.229252)
		(width 0.381)
		(layer "In2.Cu")
		(net "PVDDCR_CPU0_P1")
	)
	(segment
		(start 77.264768 -173.84395)
		(end 77.556106 -174.135288)
		(width 0.381)
		(layer "In2.Cu")
		(net "PVDDCR_CPU0_P1")
	)
	(segment
		(start 350.127824 -158.8643)
		(end 350.127824 -158.577534)
		(width 0.2032)
		(layer "F.Cu")
		(net "PVDDCR_CPU0_P0_VOS6")
	)
	(segment
		(start 350.127824 -158.577534)
		(end 350.452436 -158.252922)
		(width 0.2032)
		(layer "F.Cu")
		(net "PVDDCR_CPU0_P0_VOS6")
	)
	(via
		(at 350.452436 -158.252922)
		(size 0.508)
		(drill 0.254)
		(layers "F.Cu" "B.Cu")
		(net "PVDDCR_CPU0_P0_VOS6")
	)
	(segment
		(start 351.07372 -158.874206)
		(end 350.452436 -158.252922)
		(width 0.2286)
		(layer "B.Cu")
		(net "PVDDCR_CPU0_P0_VOS6")
	)
	(segment
		(start 351.389188 -158.874206)
		(end 351.07372 -158.874206)
		(width 0.2286)
		(layer "B.Cu")
		(net "PVDDCR_CPU0_P0_VOS6")
	)
	(segment
		(start 358.483662 -166.884096)
		(end 358.758236 -166.609522)
		(width 0.2032)
		(layer "F.Cu")
		(net "PVDDCR_CPU0_P0_VOS5")
	)
	(segment
		(start 358.483662 -167.170862)
		(end 358.483662 -166.884096)
		(width 0.2032)
		(layer "F.Cu")
		(net "PVDDCR_CPU0_P0_VOS5")
	)
	(segment
		(start 358.433624 -167.2209)
		(end 358.483662 -167.170862)
		(width 0.2032)
		(layer "F.Cu")
		(net "PVDDCR_CPU0_P0_VOS5")
	)
	(via
		(at 358.758236 -166.609522)
		(size 0.508)
		(drill 0.254)
		(layers "F.Cu" "B.Cu")
		(net "PVDDCR_CPU0_P0_VOS5")
	)
	(segment
		(start 359.37952 -167.230806)
		(end 358.758236 -166.609522)
		(width 0.2286)
		(layer "B.Cu")
		(net "PVDDCR_CPU0_P0_VOS5")
	)
	(segment
		(start 359.694988 -167.230806)
		(end 359.37952 -167.230806)
		(width 0.2286)
		(layer "B.Cu")
		(net "PVDDCR_CPU0_P0_VOS5")
	)
	(segment
		(start 391.859262 -180.131974)
		(end 392.133836 -179.8574)
		(width 0.2032)
		(layer "F.Cu")
		(net "PVDDCR_CPU0_P0_VOS4")
	)
	(segment
		(start 391.859262 -180.41874)
		(end 391.859262 -180.131974)
		(width 0.2032)
		(layer "F.Cu")
		(net "PVDDCR_CPU0_P0_VOS4")
	)
	(segment
		(start 391.809224 -180.468778)
		(end 391.859262 -180.41874)
		(width 0.2032)
		(layer "F.Cu")
		(net "PVDDCR_CPU0_P0_VOS4")
	)
	(via
		(at 392.133836 -179.8574)
		(size 0.508)
		(drill 0.254)
		(layers "F.Cu" "B.Cu")
		(net "PVDDCR_CPU0_P0_VOS4")
	)
	(segment
		(start 393.070588 -180.478684)
		(end 392.75512 -180.478684)
		(width 0.2286)
		(layer "B.Cu")
		(net "PVDDCR_CPU0_P0_VOS4")
	)
	(segment
		(start 392.75512 -180.478684)
		(end 392.133836 -179.8574)
		(width 0.2286)
		(layer "B.Cu")
		(net "PVDDCR_CPU0_P0_VOS4")
	)
	(segment
		(start 383.528062 -180.461412)
		(end 383.478024 -180.51145)
		(width 0.2032)
		(layer "F.Cu")
		(net "PVDDCR_CPU0_P0_VOS3")
	)
	(segment
		(start 383.528062 -180.131974)
		(end 383.528062 -180.461412)
		(width 0.2032)
		(layer "F.Cu")
		(net "PVDDCR_CPU0_P0_VOS3")
	)
	(segment
		(start 383.802636 -179.8574)
		(end 383.528062 -180.131974)
		(width 0.2032)
		(layer "F.Cu")
		(net "PVDDCR_CPU0_P0_VOS3")
	)
	(via
		(at 383.802636 -179.8574)
		(size 0.508)
		(drill 0.254)
		(layers "F.Cu" "B.Cu")
		(net "PVDDCR_CPU0_P0_VOS3")
	)
	(segment
		(start 384.739388 -180.478684)
		(end 384.42392 -180.478684)
		(width 0.2286)
		(layer "B.Cu")
		(net "PVDDCR_CPU0_P0_VOS3")
	)
	(segment
		(start 384.42392 -180.478684)
		(end 383.802636 -179.8574)
		(width 0.2286)
		(layer "B.Cu")
		(net "PVDDCR_CPU0_P0_VOS3")
	)
	(segment
		(start 375.075196 -180.468778)
		(end 375.125234 -180.41874)
		(width 0.2032)
		(layer "F.Cu")
		(net "PVDDCR_CPU0_P0_VOS2")
	)
	(segment
		(start 375.125234 -180.41874)
		(end 375.125234 -180.131974)
		(width 0.2032)
		(layer "F.Cu")
		(net "PVDDCR_CPU0_P0_VOS2")
	)
	(segment
		(start 375.125234 -180.131974)
		(end 375.399808 -179.8574)
		(width 0.2032)
		(layer "F.Cu")
		(net "PVDDCR_CPU0_P0_VOS2")
	)
	(via
		(at 375.399808 -179.8574)
		(size 0.508)
		(drill 0.254)
		(layers "F.Cu" "B.Cu")
		(net "PVDDCR_CPU0_P0_VOS2")
	)
	(segment
		(start 376.33656 -180.478684)
		(end 376.021092 -180.478684)
		(width 0.2286)
		(layer "B.Cu")
		(net "PVDDCR_CPU0_P0_VOS2")
	)
	(segment
		(start 376.021092 -180.478684)
		(end 375.399808 -179.8574)
		(width 0.2286)
		(layer "B.Cu")
		(net "PVDDCR_CPU0_P0_VOS2")
	)
	(segment
		(start 366.714024 -175.49622)
		(end 366.764062 -175.446182)
		(width 0.2032)
		(layer "F.Cu")
		(net "PVDDCR_CPU0_P0_VOS1")
	)
	(segment
		(start 366.764062 -175.159416)
		(end 367.038636 -174.884842)
		(width 0.2032)
		(layer "F.Cu")
		(net "PVDDCR_CPU0_P0_VOS1")
	)
	(segment
		(start 366.764062 -175.446182)
		(end 366.764062 -175.159416)
		(width 0.2032)
		(layer "F.Cu")
		(net "PVDDCR_CPU0_P0_VOS1")
	)
	(via
		(at 367.038636 -174.884842)
		(size 0.508)
		(drill 0.254)
		(layers "F.Cu" "B.Cu")
		(net "PVDDCR_CPU0_P0_VOS1")
	)
	(segment
		(start 367.65992 -175.506126)
		(end 367.038636 -174.884842)
		(width 0.2286)
		(layer "B.Cu")
		(net "PVDDCR_CPU0_P0_VOS1")
	)
	(segment
		(start 367.975388 -175.506126)
		(end 367.65992 -175.506126)
		(width 0.2286)
		(layer "B.Cu")
		(net "PVDDCR_CPU0_P0_VOS1")
	)
	(segment
		(start 383.549906 -140.202158)
		(end 383.713228 -140.202158)
		(width 0.254)
		(layer "F.Cu")
		(net "PVDDCR_CPU0_P0_VMON")
	)
	(segment
		(start 382.941576 -140.810488)
		(end 383.549906 -140.202158)
		(width 0.254)
		(layer "F.Cu")
		(net "PVDDCR_CPU0_P0_VMON")
	)
	(segment
		(start 382.378966 -141.345158)
		(end 382.913636 -140.810488)
		(width 0.254)
		(layer "F.Cu")
		(net "PVDDCR_CPU0_P0_VMON")
	)
	(segment
		(start 382.913636 -140.810488)
		(end 382.941576 -140.810488)
		(width 0.254)
		(layer "F.Cu")
		(net "PVDDCR_CPU0_P0_VMON")
	)
	(segment
		(start 381.973328 -141.345158)
		(end 382.378966 -141.345158)
		(width 0.254)
		(layer "F.Cu")
		(net "PVDDCR_CPU0_P0_VMON")
	)
	(via
		(at 382.941576 -140.810488)
		(size 0.508)
		(drill 0.254)
		(layers "F.Cu" "B.Cu")
		(net "PVDDCR_CPU0_P0_VMON")
	)
	(segment
		(start 382.312164 -141.36116)
		(end 381.273304 -141.36116)
		(width 0.1524)
		(layer "B.Cu")
		(net "PVDDCR_CPU0_P0_VMON")
	)
	(segment
		(start 383.713228 -140.202158)
		(end 383.549906 -140.202158)
		(width 0.254)
		(layer "B.Cu")
		(net "PVDDCR_CPU0_P0_VMON")
	)
	(segment
		(start 383.549906 -140.202158)
		(end 382.941576 -140.810488)
		(width 0.254)
		(layer "B.Cu")
		(net "PVDDCR_CPU0_P0_VMON")
	)
	(segment
		(start 382.862836 -140.810488)
		(end 382.312164 -141.36116)
		(width 0.1524)
		(layer "B.Cu")
		(net "PVDDCR_CPU0_P0_VMON")
	)
	(segment
		(start 382.941576 -140.810488)
		(end 382.862836 -140.810488)
		(width 0.1524)
		(layer "B.Cu")
		(net "PVDDCR_CPU0_P0_VMON")
	)
	(segment
		(start 383.713228 -139.186158)
		(end 383.713228 -138.170158)
		(width 0.1524)
		(layer "F.Cu")
		(net "PVDDCR_CPU0_P0_VINSEN")
	)
	(segment
		(start 383.334514 -139.186158)
		(end 383.713228 -139.186158)
		(width 0.1524)
		(layer "F.Cu")
		(net "PVDDCR_CPU0_P0_VINSEN")
	)
	(segment
		(start 382.805686 -139.714986)
		(end 383.334514 -139.186158)
		(width 0.1524)
		(layer "F.Cu")
		(net "PVDDCR_CPU0_P0_VINSEN")
	)
	(via
		(at 382.805686 -139.714986)
		(size 0.762)
		(drill 0.254)
		(layers "F.Cu" "B.Cu")
		(net "PVDDCR_CPU0_P0_VINSEN")
	)
	(segment
		(start 383.621026 -139.186158)
		(end 383.713228 -139.186158)
		(width 0.254)
		(layer "B.Cu")
		(net "PVDDCR_CPU0_P0_VINSEN")
	)
	(segment
		(start 383.13868 -139.668504)
		(end 383.621026 -139.186158)
		(width 0.254)
		(layer "B.Cu")
		(net "PVDDCR_CPU0_P0_VINSEN")
	)
	(segment
		(start 382.084072 -140.96111)
		(end 382.343914 -140.701268)
		(width 0.254)
		(layer "B.Cu")
		(net "PVDDCR_CPU0_P0_VINSEN")
	)
	(segment
		(start 382.532128 -140.2461)
		(end 382.532128 -139.988544)
		(width 0.254)
		(layer "B.Cu")
		(net "PVDDCR_CPU0_P0_VINSEN")
	)
	(segment
		(start 382.532128 -139.988544)
		(end 382.805686 -139.714986)
		(width 0.254)
		(layer "B.Cu")
		(net "PVDDCR_CPU0_P0_VINSEN")
	)
	(segment
		(start 382.343914 -140.701268)
		(end 382.532128 -140.2461)
		(width 0.254)
		(layer "B.Cu")
		(net "PVDDCR_CPU0_P0_VINSEN")
	)
	(segment
		(start 382.805686 -139.714986)
		(end 382.852168 -139.668504)
		(width 0.254)
		(layer "B.Cu")
		(net "PVDDCR_CPU0_P0_VINSEN")
	)
	(segment
		(start 381.273304 -140.96111)
		(end 382.084072 -140.96111)
		(width 0.1778)
		(layer "B.Cu")
		(net "PVDDCR_CPU0_P0_VINSEN")
	)
	(segment
		(start 382.852168 -139.668504)
		(end 383.13868 -139.668504)
		(width 0.254)
		(layer "B.Cu")
		(net "PVDDCR_CPU0_P0_VINSEN")
	)
	(segment
		(start 374.66524 -179.843938)
		(end 374.66524 -179.73167)
		(width 0.2286)
		(layer "F.Cu")
		(net "PVDDCR_CPU0_P0_VCCS")
	)
	(segment
		(start 349.717868 -158.23946)
		(end 349.717868 -158.120842)
		(width 0.2286)
		(layer "F.Cu")
		(net "PVDDCR_CPU0_P0_VCCS")
	)
	(segment
		(start 399.78965 -172.71365)
		(end 400.518122 -172.71365)
		(width 0.254)
		(layer "F.Cu")
		(net "PVDDCR_CPU0_P0_VCCS")
	)
	(segment
		(start 383.771902 -178.94935)
		(end 383.771902 -178.28641)
		(width 0.2286)
		(layer "F.Cu")
		(net "PVDDCR_CPU0_P0_VCCS")
	)
	(segment
		(start 392.103102 -178.94935)
		(end 392.103102 -178.28641)
		(width 0.2286)
		(layer "F.Cu")
		(net "PVDDCR_CPU0_P0_VCCS")
	)
	(segment
		(start 366.304068 -174.87138)
		(end 366.304068 -174.680626)
		(width 0.2286)
		(layer "F.Cu")
		(net "PVDDCR_CPU0_P0_VCCS")
	)
	(segment
		(start 391.399268 -179.653184)
		(end 392.103102 -178.94935)
		(width 0.2286)
		(layer "F.Cu")
		(net "PVDDCR_CPU0_P0_VCCS")
	)
	(segment
		(start 391.399268 -179.843938)
		(end 391.399268 -179.653184)
		(width 0.2286)
		(layer "F.Cu")
		(net "PVDDCR_CPU0_P0_VCCS")
	)
	(segment
		(start 408.841702 -164.799264)
		(end 408.137868 -165.503098)
		(width 0.2286)
		(layer "F.Cu")
		(net "PVDDCR_CPU0_P0_VCCS")
	)
	(segment
		(start 375.369074 -179.027836)
		(end 375.369074 -178.28641)
		(width 0.2286)
		(layer "F.Cu")
		(net "PVDDCR_CPU0_P0_VCCS")
	)
	(segment
		(start 400.518122 -172.71365)
		(end 400.518122 -173.37659)
		(width 0.2286)
		(layer "F.Cu")
		(net "PVDDCR_CPU0_P0_VCCS")
	)
	(segment
		(start 366.304068 -174.680626)
		(end 367.007902 -173.976792)
		(width 0.2286)
		(layer "F.Cu")
		(net "PVDDCR_CPU0_P0_VCCS")
	)
	(segment
		(start 392.103102 -178.28641)
		(end 391.37463 -178.28641)
		(width 0.254)
		(layer "F.Cu")
		(net "PVDDCR_CPU0_P0_VCCS")
	)
	(segment
		(start 367.007902 -173.313852)
		(end 366.27943 -173.313852)
		(width 0.254)
		(layer "F.Cu")
		(net "PVDDCR_CPU0_P0_VCCS")
	)
	(segment
		(start 408.841702 -164.136324)
		(end 408.841702 -164.799264)
		(width 0.2286)
		(layer "F.Cu")
		(net "PVDDCR_CPU0_P0_VCCS")
	)
	(segment
		(start 374.66524 -179.73167)
		(end 375.369074 -179.027836)
		(width 0.2286)
		(layer "F.Cu")
		(net "PVDDCR_CPU0_P0_VCCS")
	)
	(segment
		(start 417.223702 -159.973264)
		(end 416.519868 -160.677098)
		(width 0.2286)
		(layer "F.Cu")
		(net "PVDDCR_CPU0_P0_VCCS")
	)
	(segment
		(start 358.023668 -166.59606)
		(end 358.023668 -166.405306)
		(width 0.2286)
		(layer "F.Cu")
		(net "PVDDCR_CPU0_P0_VCCS")
	)
	(segment
		(start 367.007902 -173.976792)
		(end 367.007902 -173.313852)
		(width 0.2286)
		(layer "F.Cu")
		(net "PVDDCR_CPU0_P0_VCCS")
	)
	(segment
		(start 416.49523 -159.310324)
		(end 417.223702 -159.310324)
		(width 0.254)
		(layer "F.Cu")
		(net "PVDDCR_CPU0_P0_VCCS")
	)
	(segment
		(start 358.727502 -165.701472)
		(end 358.727502 -165.038532)
		(width 0.2286)
		(layer "F.Cu")
		(net "PVDDCR_CPU0_P0_VCCS")
	)
	(segment
		(start 358.023668 -166.405306)
		(end 358.727502 -165.701472)
		(width 0.2286)
		(layer "F.Cu")
		(net "PVDDCR_CPU0_P0_VCCS")
	)
	(segment
		(start 375.369074 -178.28641)
		(end 374.640602 -178.28641)
		(width 0.254)
		(layer "F.Cu")
		(net "PVDDCR_CPU0_P0_VCCS")
	)
	(segment
		(start 416.519868 -160.677098)
		(end 416.519868 -160.867852)
		(width 0.2286)
		(layer "F.Cu")
		(net "PVDDCR_CPU0_P0_VCCS")
	)
	(segment
		(start 417.223702 -159.310324)
		(end 417.223702 -159.973264)
		(width 0.2286)
		(layer "F.Cu")
		(net "PVDDCR_CPU0_P0_VCCS")
	)
	(segment
		(start 383.068068 -179.653184)
		(end 383.771902 -178.94935)
		(width 0.254)
		(layer "F.Cu")
		(net "PVDDCR_CPU0_P0_VCCS")
	)
	(segment
		(start 408.11323 -164.136324)
		(end 408.841702 -164.136324)
		(width 0.254)
		(layer "F.Cu")
		(net "PVDDCR_CPU0_P0_VCCS")
	)
	(segment
		(start 349.717868 -158.120842)
		(end 350.421702 -157.417008)
		(width 0.2286)
		(layer "F.Cu")
		(net "PVDDCR_CPU0_P0_VCCS")
	)
	(segment
		(start 399.814288 -174.080424)
		(end 399.814288 -174.271178)
		(width 0.2286)
		(layer "F.Cu")
		(net "PVDDCR_CPU0_P0_VCCS")
	)
	(segment
		(start 400.518122 -173.37659)
		(end 399.814288 -174.080424)
		(width 0.2286)
		(layer "F.Cu")
		(net "PVDDCR_CPU0_P0_VCCS")
	)
	(segment
		(start 358.727502 -165.038532)
		(end 357.99903 -165.038532)
		(width 0.254)
		(layer "F.Cu")
		(net "PVDDCR_CPU0_P0_VCCS")
	)
	(segment
		(start 350.421702 -156.681932)
		(end 349.69323 -156.681932)
		(width 0.254)
		(layer "F.Cu")
		(net "PVDDCR_CPU0_P0_VCCS")
	)
	(segment
		(start 350.421702 -157.417008)
		(end 350.421702 -156.681932)
		(width 0.2286)
		(layer "F.Cu")
		(net "PVDDCR_CPU0_P0_VCCS")
	)
	(segment
		(start 383.771902 -178.28641)
		(end 383.04343 -178.28641)
		(width 0.254)
		(layer "F.Cu")
		(net "PVDDCR_CPU0_P0_VCCS")
	)
	(segment
		(start 383.068068 -179.88661)
		(end 383.068068 -179.653184)
		(width 0.254)
		(layer "F.Cu")
		(net "PVDDCR_CPU0_P0_VCCS")
	)
	(segment
		(start 408.137868 -165.503098)
		(end 408.137868 -165.693852)
		(width 0.2286)
		(layer "F.Cu")
		(net "PVDDCR_CPU0_P0_VCCS")
	)
	(via
		(at 383.04343 -178.28641)
		(size 0.508)
		(drill 0.254)
		(layers "F.Cu" "B.Cu")
		(net "PVDDCR_CPU0_P0_VCCS")
	)
	(via
		(at 374.640602 -178.28641)
		(size 0.508)
		(drill 0.254)
		(layers "F.Cu" "B.Cu")
		(net "PVDDCR_CPU0_P0_VCCS")
	)
	(via
		(at 391.37463 -178.28641)
		(size 0.508)
		(drill 0.254)
		(layers "F.Cu" "B.Cu")
		(net "PVDDCR_CPU0_P0_VCCS")
	)
	(via
		(at 399.78965 -172.71365)
		(size 0.508)
		(drill 0.254)
		(layers "F.Cu" "B.Cu")
		(net "PVDDCR_CPU0_P0_VCCS")
	)
	(via
		(at 381.52959 -138.539728)
		(size 0.762)
		(drill 0.254)
		(layers "F.Cu" "B.Cu")
		(net "PVDDCR_CPU0_P0_VCCS")
	)
	(via
		(at 416.49523 -159.310324)
		(size 0.508)
		(drill 0.254)
		(layers "F.Cu" "B.Cu")
		(net "PVDDCR_CPU0_P0_VCCS")
	)
	(via
		(at 349.69323 -156.681932)
		(size 0.508)
		(drill 0.254)
		(layers "F.Cu" "B.Cu")
		(net "PVDDCR_CPU0_P0_VCCS")
	)
	(via
		(at 357.99903 -165.038532)
		(size 0.508)
		(drill 0.254)
		(layers "F.Cu" "B.Cu")
		(net "PVDDCR_CPU0_P0_VCCS")
	)
	(via
		(at 408.11323 -164.136324)
		(size 0.508)
		(drill 0.254)
		(layers "F.Cu" "B.Cu")
		(net "PVDDCR_CPU0_P0_VCCS")
	)
	(via
		(at 366.27943 -173.313852)
		(size 0.508)
		(drill 0.254)
		(layers "F.Cu" "B.Cu")
		(net "PVDDCR_CPU0_P0_VCCS")
	)
	(segment
		(start 392.937238 -155.272232)
		(end 392.937238 -175.865282)
		(width 0.254)
		(layer "In4.Cu")
		(net "PVDDCR_CPU0_P0_VCCS")
	)
	(segment
		(start 408.171396 -164.078158)
		(end 408.11323 -164.136324)
		(width 0.254)
		(layer "In4.Cu")
		(net "PVDDCR_CPU0_P0_VCCS")
	)
	(segment
		(start 386.01396 -146.34718)
		(end 394.29055 -146.34718)
		(width 0.254)
		(layer "In4.Cu")
		(net "PVDDCR_CPU0_P0_VCCS")
	)
	(segment
		(start 395.072108 -150.61946)
		(end 408.171396 -163.718748)
		(width 0.254)
		(layer "In4.Cu")
		(net "PVDDCR_CPU0_P0_VCCS")
	)
	(segment
		(start 388.791958 -151.126952)
		(end 392.937238 -155.272232)
		(width 0.254)
		(layer "In4.Cu")
		(net "PVDDCR_CPU0_P0_VCCS")
	)
	(segment
		(start 399.49882 -171.624498)
		(end 400.009106 -172.134784)
		(width 0.254)
		(layer "In4.Cu")
		(net "PVDDCR_CPU0_P0_VCCS")
	)
	(segment
		(start 408.171396 -163.718748)
		(end 408.171396 -164.078158)
		(width 0.254)
		(layer "In4.Cu")
		(net "PVDDCR_CPU0_P0_VCCS")
	)
	(segment
		(start 374.771158 -147.316952)
		(end 373.877078 -148.211032)
		(width 0.254)
		(layer "In4.Cu")
		(net "PVDDCR_CPU0_P0_VCCS")
	)
	(segment
		(start 386.600192 -149.349206)
		(end 390.473692 -149.349206)
		(width 0.254)
		(layer "In4.Cu")
		(net "PVDDCR_CPU0_P0_VCCS")
	)
	(segment
		(start 382.695958 -150.237952)
		(end 383.584958 -151.126952)
		(width 0.254)
		(layer "In4.Cu")
		(net "PVDDCR_CPU0_P0_VCCS")
	)
	(segment
		(start 383.974086 -146.7231)
		(end 386.600192 -149.349206)
		(width 0.254)
		(layer "In4.Cu")
		(net "PVDDCR_CPU0_P0_VCCS")
	)
	(segment
		(start 395.072108 -147.128738)
		(end 395.072108 -150.61946)
		(width 0.254)
		(layer "In4.Cu")
		(net "PVDDCR_CPU0_P0_VCCS")
	)
	(segment
		(start 381.857758 -145.892012)
		(end 382.349756 -145.400014)
		(width 0.254)
		(layer "In4.Cu")
		(net "PVDDCR_CPU0_P0_VCCS")
	)
	(segment
		(start 374.860058 -178.066954)
		(end 374.640602 -178.28641)
		(width 0.254)
		(layer "In4.Cu")
		(net "PVDDCR_CPU0_P0_VCCS")
	)
	(segment
		(start 385.066794 -145.400014)
		(end 386.01396 -146.34718)
		(width 0.254)
		(layer "In4.Cu")
		(net "PVDDCR_CPU0_P0_VCCS")
	)
	(segment
		(start 400.009106 -172.134784)
		(end 400.009106 -172.494194)
		(width 0.254)
		(layer "In4.Cu")
		(net "PVDDCR_CPU0_P0_VCCS")
	)
	(segment
		(start 383.262886 -165.02888)
		(end 383.262886 -178.066954)
		(width 0.254)
		(layer "In4.Cu")
		(net "PVDDCR_CPU0_P0_VCCS")
	)
	(segment
		(start 394.29055 -146.34718)
		(end 395.072108 -147.128738)
		(width 0.254)
		(layer "In4.Cu")
		(net "PVDDCR_CPU0_P0_VCCS")
	)
	(segment
		(start 391.594086 -177.208434)
		(end 391.594086 -178.066954)
		(width 0.254)
		(layer "In4.Cu")
		(net "PVDDCR_CPU0_P0_VCCS")
	)
	(segment
		(start 382.349756 -145.400014)
		(end 385.066794 -145.400014)
		(width 0.254)
		(layer "In4.Cu")
		(net "PVDDCR_CPU0_P0_VCCS")
	)
	(segment
		(start 373.877078 -148.211032)
		(end 373.877078 -173.151038)
		(width 0.254)
		(layer "In4.Cu")
		(net "PVDDCR_CPU0_P0_VCCS")
	)
	(segment
		(start 392.937238 -175.865282)
		(end 391.594086 -177.208434)
		(width 0.254)
		(layer "In4.Cu")
		(net "PVDDCR_CPU0_P0_VCCS")
	)
	(segment
		(start 391.594086 -178.066954)
		(end 391.37463 -178.28641)
		(width 0.254)
		(layer "In4.Cu")
		(net "PVDDCR_CPU0_P0_VCCS")
	)
	(segment
		(start 399.49882 -158.374334)
		(end 399.49882 -171.624498)
		(width 0.254)
		(layer "In4.Cu")
		(net "PVDDCR_CPU0_P0_VCCS")
	)
	(segment
		(start 383.584958 -151.126952)
		(end 388.791958 -151.126952)
		(width 0.254)
		(layer "In4.Cu")
		(net "PVDDCR_CPU0_P0_VCCS")
	)
	(segment
		(start 373.877078 -173.151038)
		(end 374.860058 -174.134018)
		(width 0.254)
		(layer "In4.Cu")
		(net "PVDDCR_CPU0_P0_VCCS")
	)
	(segment
		(start 374.860058 -174.134018)
		(end 374.860058 -178.066954)
		(width 0.254)
		(layer "In4.Cu")
		(net "PVDDCR_CPU0_P0_VCCS")
	)
	(segment
		(start 376.472958 -158.238952)
		(end 383.262886 -165.02888)
		(width 0.254)
		(layer "In4.Cu")
		(net "PVDDCR_CPU0_P0_VCCS")
	)
	(segment
		(start 400.009106 -172.494194)
		(end 399.78965 -172.71365)
		(width 0.254)
		(layer "In4.Cu")
		(net "PVDDCR_CPU0_P0_VCCS")
	)
	(segment
		(start 383.262886 -178.066954)
		(end 383.04343 -178.28641)
		(width 0.254)
		(layer "In4.Cu")
		(net "PVDDCR_CPU0_P0_VCCS")
	)
	(segment
		(start 376.472958 -149.729952)
		(end 376.472958 -158.238952)
		(width 0.254)
		(layer "In4.Cu")
		(net "PVDDCR_CPU0_P0_VCCS")
	)
	(segment
		(start 390.473692 -149.349206)
		(end 399.49882 -158.374334)
		(width 0.254)
		(layer "In4.Cu")
		(net "PVDDCR_CPU0_P0_VCCS")
	)
	(segment
		(start 358.205278 -163.575238)
		(end 358.205278 -164.91331)
		(width 0.254)
		(layer "In11.Cu")
		(net "PVDDCR_CPU0_P0_VCCS")
	)
	(segment
		(start 384.909822 -147.38477)
		(end 395.61008 -158.085028)
		(width 0.254)
		(layer "In11.Cu")
		(net "PVDDCR_CPU0_P0_VCCS")
	)
	(segment
		(start 365.21771 -150.390352)
		(end 363.615732 -151.99233)
		(width 0.254)
		(layer "In11.Cu")
		(net "PVDDCR_CPU0_P0_VCCS")
	)
	(segment
		(start 395.61008 -158.085028)
		(end 415.966656 -158.085028)
		(width 0.254)
		(layer "In11.Cu")
		(net "PVDDCR_CPU0_P0_VCCS")
	)
	(segment
		(start 374.966992 -146.304)
		(end 373.856758 -147.414234)
		(width 0.254)
		(layer "In11.Cu")
		(net "PVDDCR_CPU0_P0_VCCS")
	)
	(segment
		(start 382.139698 -147.38477)
		(end 384.909822 -147.38477)
		(width 0.254)
		(layer "In11.Cu")
		(net "PVDDCR_CPU0_P0_VCCS")
	)
	(segment
		(start 373.856758 -148.586952)
		(end 372.053358 -150.390352)
		(width 0.254)
		(layer "In11.Cu")
		(net "PVDDCR_CPU0_P0_VCCS")
	)
	(segment
		(start 416.49523 -158.613602)
		(end 416.49523 -159.310324)
		(width 0.254)
		(layer "In11.Cu")
		(net "PVDDCR_CPU0_P0_VCCS")
	)
	(segment
		(start 375.972578 -150.677372)
		(end 375.972578 -161.995104)
		(width 0.254)
		(layer "In11.Cu")
		(net "PVDDCR_CPU0_P0_VCCS")
	)
	(segment
		(start 375.972578 -161.995104)
		(end 366.498886 -171.468796)
		(width 0.254)
		(layer "In11.Cu")
		(net "PVDDCR_CPU0_P0_VCCS")
	)
	(segment
		(start 356.10927 -148.39315)
		(end 349.950278 -154.552142)
		(width 0.254)
		(layer "In11.Cu")
		(net "PVDDCR_CPU0_P0_VCCS")
	)
	(segment
		(start 358.080056 -165.038532)
		(end 357.99903 -165.038532)
		(width 0.254)
		(layer "In11.Cu")
		(net "PVDDCR_CPU0_P0_VCCS")
	)
	(segment
		(start 373.856758 -147.414234)
		(end 373.856758 -148.586952)
		(width 0.254)
		(layer "In11.Cu")
		(net "PVDDCR_CPU0_P0_VCCS")
	)
	(segment
		(start 375.142252 -144.909286)
		(end 374.424702 -144.909286)
		(width 0.254)
		(layer "In11.Cu")
		(net "PVDDCR_CPU0_P0_VCCS")
	)
	(segment
		(start 415.966656 -158.085028)
		(end 416.49523 -158.613602)
		(width 0.254)
		(layer "In11.Cu")
		(net "PVDDCR_CPU0_P0_VCCS")
	)
	(segment
		(start 372.053358 -150.390352)
		(end 365.21771 -150.390352)
		(width 0.254)
		(layer "In11.Cu")
		(net "PVDDCR_CPU0_P0_VCCS")
	)
	(segment
		(start 372.588536 -146.745452)
		(end 372.588536 -147.888452)
		(width 0.254)
		(layer "In11.Cu")
		(net "PVDDCR_CPU0_P0_VCCS")
	)
	(segment
		(start 372.083838 -148.39315)
		(end 356.10927 -148.39315)
		(width 0.254)
		(layer "In11.Cu")
		(net "PVDDCR_CPU0_P0_VCCS")
	)
	(segment
		(start 375.863358 -150.568152)
		(end 375.972578 -150.677372)
		(width 0.254)
		(layer "In11.Cu")
		(net "PVDDCR_CPU0_P0_VCCS")
	)
	(segment
		(start 349.794068 -156.681932)
		(end 349.69323 -156.681932)
		(width 0.254)
		(layer "In11.Cu")
		(net "PVDDCR_CPU0_P0_VCCS")
	)
	(segment
		(start 349.950278 -154.552142)
		(end 349.950278 -156.525722)
		(width 0.254)
		(layer "In11.Cu")
		(net "PVDDCR_CPU0_P0_VCCS")
	)
	(segment
		(start 372.588536 -147.888452)
		(end 372.083838 -148.39315)
		(width 0.254)
		(layer "In11.Cu")
		(net "PVDDCR_CPU0_P0_VCCS")
	)
	(segment
		(start 349.950278 -156.525722)
		(end 349.794068 -156.681932)
		(width 0.254)
		(layer "In11.Cu")
		(net "PVDDCR_CPU0_P0_VCCS")
	)
	(segment
		(start 363.615732 -158.164784)
		(end 358.205278 -163.575238)
		(width 0.254)
		(layer "In11.Cu")
		(net "PVDDCR_CPU0_P0_VCCS")
	)
	(segment
		(start 366.498886 -173.094396)
		(end 366.27943 -173.313852)
		(width 0.254)
		(layer "In11.Cu")
		(net "PVDDCR_CPU0_P0_VCCS")
	)
	(segment
		(start 366.498886 -171.468796)
		(end 366.498886 -173.094396)
		(width 0.254)
		(layer "In11.Cu")
		(net "PVDDCR_CPU0_P0_VCCS")
	)
	(segment
		(start 374.424702 -144.909286)
		(end 372.588536 -146.745452)
		(width 0.254)
		(layer "In11.Cu")
		(net "PVDDCR_CPU0_P0_VCCS")
	)
	(segment
		(start 363.615732 -151.99233)
		(end 363.615732 -158.164784)
		(width 0.254)
		(layer "In11.Cu")
		(net "PVDDCR_CPU0_P0_VCCS")
	)
	(segment
		(start 358.205278 -164.91331)
		(end 358.080056 -165.038532)
		(width 0.254)
		(layer "In11.Cu")
		(net "PVDDCR_CPU0_P0_VCCS")
	)
	(segment
		(start 347.91777 -157.527498)
		(end 347.993462 -157.451806)
		(width 0.2286)
		(layer "F.Cu")
		(net "PVDDCR_CPU0_P0_VCC6")
	)
	(segment
		(start 350.778572 -159.764476)
		(end 350.127824 -159.764476)
		(width 0.2286)
		(layer "F.Cu")
		(net "PVDDCR_CPU0_P0_VCC6")
	)
	(segment
		(start 351.410778 -159.484568)
		(end 351.05848 -159.484568)
		(width 0.2286)
		(layer "F.Cu")
		(net "PVDDCR_CPU0_P0_VCC6")
	)
	(segment
		(start 351.410778 -158.874206)
		(end 351.410778 -159.484568)
		(width 0.381)
		(layer "F.Cu")
		(net "PVDDCR_CPU0_P0_VCC6")
	)
	(segment
		(start 351.05848 -159.484568)
		(end 350.778572 -159.764476)
		(width 0.2286)
		(layer "F.Cu")
		(net "PVDDCR_CPU0_P0_VCC6")
	)
	(segment
		(start 347.91777 -158.23946)
		(end 347.91777 -157.527498)
		(width 0.2286)
		(layer "F.Cu")
		(net "PVDDCR_CPU0_P0_VCC6")
	)
	(via
		(at 351.410778 -159.484568)
		(size 0.508)
		(drill 0.254)
		(layers "F.Cu" "B.Cu")
		(net "PVDDCR_CPU0_P0_VCC6")
	)
	(via
		(at 347.993462 -157.451806)
		(size 0.508)
		(drill 0.254)
		(layers "F.Cu" "B.Cu")
		(net "PVDDCR_CPU0_P0_VCC6")
	)
	(via
		(at 349.583248 -158.37027)
		(size 0.6604)
		(drill 0.3302)
		(layers "F.Cu" "B.Cu")
		(net "PVDDCR_CPU0_P0_VCC6")
	)
	(segment
		(start 350.03867 -158.825692)
		(end 350.03867 -159.680148)
		(width 0.381)
		(layer "B.Cu")
		(net "PVDDCR_CPU0_P0_VCC6")
	)
	(segment
		(start 349.583248 -158.264606)
		(end 349.583248 -158.37027)
		(width 0.381)
		(layer "B.Cu")
		(net "PVDDCR_CPU0_P0_VCC6")
	)
	(segment
		(start 349.583248 -158.37027)
		(end 350.03867 -158.825692)
		(width 0.381)
		(layer "B.Cu")
		(net "PVDDCR_CPU0_P0_VCC6")
	)
	(segment
		(start 350.744028 -159.484568)
		(end 351.410778 -159.484568)
		(width 0.381)
		(layer "B.Cu")
		(net "PVDDCR_CPU0_P0_VCC6")
	)
	(segment
		(start 349.269812 -157.95117)
		(end 349.583248 -158.264606)
		(width 0.508)
		(layer "B.Cu")
		(net "PVDDCR_CPU0_P0_VCC6")
	)
	(segment
		(start 350.03867 -159.680148)
		(end 350.548448 -159.680148)
		(width 0.381)
		(layer "B.Cu")
		(net "PVDDCR_CPU0_P0_VCC6")
	)
	(segment
		(start 347.993462 -157.451806)
		(end 348.492826 -157.95117)
		(width 0.508)
		(layer "B.Cu")
		(net "PVDDCR_CPU0_P0_VCC6")
	)
	(segment
		(start 350.548448 -159.680148)
		(end 350.744028 -159.484568)
		(width 0.381)
		(layer "B.Cu")
		(net "PVDDCR_CPU0_P0_VCC6")
	)
	(segment
		(start 348.492826 -157.95117)
		(end 349.269812 -157.95117)
		(width 0.508)
		(layer "B.Cu")
		(net "PVDDCR_CPU0_P0_VCC6")
	)
	(segment
		(start 359.084372 -168.121076)
		(end 358.433624 -168.121076)
		(width 0.2286)
		(layer "F.Cu")
		(net "PVDDCR_CPU0_P0_VCC5")
	)
	(segment
		(start 356.299262 -165.808406)
		(end 356.22357 -165.884098)
		(width 0.2286)
		(layer "F.Cu")
		(net "PVDDCR_CPU0_P0_VCC5")
	)
	(segment
		(start 359.716578 -167.230806)
		(end 359.716578 -167.841168)
		(width 0.381)
		(layer "F.Cu")
		(net "PVDDCR_CPU0_P0_VCC5")
	)
	(segment
		(start 359.716578 -167.841168)
		(end 359.36428 -167.841168)
		(width 0.2286)
		(layer "F.Cu")
		(net "PVDDCR_CPU0_P0_VCC5")
	)
	(segment
		(start 356.22357 -165.884098)
		(end 356.22357 -166.59606)
		(width 0.2286)
		(layer "F.Cu")
		(net "PVDDCR_CPU0_P0_VCC5")
	)
	(segment
		(start 359.36428 -167.841168)
		(end 359.084372 -168.121076)
		(width 0.2286)
		(layer "F.Cu")
		(net "PVDDCR_CPU0_P0_VCC5")
	)
	(via
		(at 357.889048 -166.72687)
		(size 0.6604)
		(drill 0.3302)
		(layers "F.Cu" "B.Cu")
		(net "PVDDCR_CPU0_P0_VCC5")
	)
	(via
		(at 356.299262 -165.808406)
		(size 0.508)
		(drill 0.254)
		(layers "F.Cu" "B.Cu")
		(net "PVDDCR_CPU0_P0_VCC5")
	)
	(via
		(at 359.716578 -167.841168)
		(size 0.508)
		(drill 0.254)
		(layers "F.Cu" "B.Cu")
		(net "PVDDCR_CPU0_P0_VCC5")
	)
	(segment
		(start 357.889048 -166.621206)
		(end 357.575612 -166.30777)
		(width 0.508)
		(layer "B.Cu")
		(net "PVDDCR_CPU0_P0_VCC5")
	)
	(segment
		(start 357.575612 -166.30777)
		(end 356.798626 -166.30777)
		(width 0.508)
		(layer "B.Cu")
		(net "PVDDCR_CPU0_P0_VCC5")
	)
	(segment
		(start 358.34447 -167.182292)
		(end 357.889048 -166.72687)
		(width 0.381)
		(layer "B.Cu")
		(net "PVDDCR_CPU0_P0_VCC5")
	)
	(segment
		(start 358.854248 -168.036748)
		(end 358.34447 -168.036748)
		(width 0.381)
		(layer "B.Cu")
		(net "PVDDCR_CPU0_P0_VCC5")
	)
	(segment
		(start 356.798626 -166.30777)
		(end 356.299262 -165.808406)
		(width 0.508)
		(layer "B.Cu")
		(net "PVDDCR_CPU0_P0_VCC5")
	)
	(segment
		(start 359.049828 -167.841168)
		(end 358.854248 -168.036748)
		(width 0.381)
		(layer "B.Cu")
		(net "PVDDCR_CPU0_P0_VCC5")
	)
	(segment
		(start 358.34447 -168.036748)
		(end 358.34447 -167.182292)
		(width 0.381)
		(layer "B.Cu")
		(net "PVDDCR_CPU0_P0_VCC5")
	)
	(segment
		(start 359.716578 -167.841168)
		(end 359.049828 -167.841168)
		(width 0.381)
		(layer "B.Cu")
		(net "PVDDCR_CPU0_P0_VCC5")
	)
	(segment
		(start 357.889048 -166.72687)
		(end 357.889048 -166.621206)
		(width 0.381)
		(layer "B.Cu")
		(net "PVDDCR_CPU0_P0_VCC5")
	)
	(segment
		(start 392.73988 -181.089046)
		(end 392.459972 -181.368954)
		(width 0.2286)
		(layer "F.Cu")
		(net "PVDDCR_CPU0_P0_VCC4")
	)
	(segment
		(start 392.459972 -181.368954)
		(end 391.809224 -181.368954)
		(width 0.2286)
		(layer "F.Cu")
		(net "PVDDCR_CPU0_P0_VCC4")
	)
	(segment
		(start 393.092178 -181.089046)
		(end 392.73988 -181.089046)
		(width 0.2286)
		(layer "F.Cu")
		(net "PVDDCR_CPU0_P0_VCC4")
	)
	(segment
		(start 389.59917 -179.843938)
		(end 389.59917 -179.131976)
		(width 0.2286)
		(layer "F.Cu")
		(net "PVDDCR_CPU0_P0_VCC4")
	)
	(segment
		(start 393.092178 -180.478684)
		(end 393.092178 -181.089046)
		(width 0.381)
		(layer "F.Cu")
		(net "PVDDCR_CPU0_P0_VCC4")
	)
	(segment
		(start 389.59917 -179.131976)
		(end 389.674862 -179.056284)
		(width 0.2286)
		(layer "F.Cu")
		(net "PVDDCR_CPU0_P0_VCC4")
	)
	(via
		(at 393.092178 -181.089046)
		(size 0.508)
		(drill 0.254)
		(layers "F.Cu" "B.Cu")
		(net "PVDDCR_CPU0_P0_VCC4")
	)
	(via
		(at 391.264648 -179.974748)
		(size 0.6604)
		(drill 0.3302)
		(layers "F.Cu" "B.Cu")
		(net "PVDDCR_CPU0_P0_VCC4")
	)
	(via
		(at 389.674862 -179.056284)
		(size 0.508)
		(drill 0.254)
		(layers "F.Cu" "B.Cu")
		(net "PVDDCR_CPU0_P0_VCC4")
	)
	(segment
		(start 391.264648 -179.974748)
		(end 391.72007 -180.43017)
		(width 0.381)
		(layer "B.Cu")
		(net "PVDDCR_CPU0_P0_VCC4")
	)
	(segment
		(start 389.674862 -179.056284)
		(end 390.174226 -179.555648)
		(width 0.508)
		(layer "B.Cu")
		(net "PVDDCR_CPU0_P0_VCC4")
	)
	(segment
		(start 391.72007 -181.284626)
		(end 392.229848 -181.284626)
		(width 0.381)
		(layer "B.Cu")
		(net "PVDDCR_CPU0_P0_VCC4")
	)
	(segment
		(start 391.264648 -179.869084)
		(end 391.264648 -179.974748)
		(width 0.381)
		(layer "B.Cu")
		(net "PVDDCR_CPU0_P0_VCC4")
	)
	(segment
		(start 390.174226 -179.555648)
		(end 390.951212 -179.555648)
		(width 0.508)
		(layer "B.Cu")
		(net "PVDDCR_CPU0_P0_VCC4")
	)
	(segment
		(start 391.72007 -180.43017)
		(end 391.72007 -181.284626)
		(width 0.381)
		(layer "B.Cu")
		(net "PVDDCR_CPU0_P0_VCC4")
	)
	(segment
		(start 392.229848 -181.284626)
		(end 392.425428 -181.089046)
		(width 0.381)
		(layer "B.Cu")
		(net "PVDDCR_CPU0_P0_VCC4")
	)
	(segment
		(start 392.425428 -181.089046)
		(end 393.092178 -181.089046)
		(width 0.381)
		(layer "B.Cu")
		(net "PVDDCR_CPU0_P0_VCC4")
	)
	(segment
		(start 390.951212 -179.555648)
		(end 391.264648 -179.869084)
		(width 0.508)
		(layer "B.Cu")
		(net "PVDDCR_CPU0_P0_VCC4")
	)
	(segment
		(start 384.0861 -181.411626)
		(end 383.478024 -181.411626)
		(width 0.2286)
		(layer "F.Cu")
		(net "PVDDCR_CPU0_P0_VCC3")
	)
	(segment
		(start 384.760978 -180.478684)
		(end 384.760978 -181.089046)
		(width 0.381)
		(layer "F.Cu")
		(net "PVDDCR_CPU0_P0_VCC3")
	)
	(segment
		(start 384.40868 -181.089046)
		(end 384.0861 -181.411626)
		(width 0.2286)
		(layer "F.Cu")
		(net "PVDDCR_CPU0_P0_VCC3")
	)
	(segment
		(start 384.760978 -181.089046)
		(end 384.40868 -181.089046)
		(width 0.2286)
		(layer "F.Cu")
		(net "PVDDCR_CPU0_P0_VCC3")
	)
	(segment
		(start 381.26797 -179.131976)
		(end 381.343662 -179.056284)
		(width 0.2286)
		(layer "F.Cu")
		(net "PVDDCR_CPU0_P0_VCC3")
	)
	(segment
		(start 381.26797 -179.88661)
		(end 381.26797 -179.131976)
		(width 0.2286)
		(layer "F.Cu")
		(net "PVDDCR_CPU0_P0_VCC3")
	)
	(via
		(at 384.760978 -181.089046)
		(size 0.508)
		(drill 0.254)
		(layers "F.Cu" "B.Cu")
		(net "PVDDCR_CPU0_P0_VCC3")
	)
	(via
		(at 382.933448 -179.974748)
		(size 0.6604)
		(drill 0.3302)
		(layers "F.Cu" "B.Cu")
		(net "PVDDCR_CPU0_P0_VCC3")
	)
	(via
		(at 381.343662 -179.056284)
		(size 0.508)
		(drill 0.254)
		(layers "F.Cu" "B.Cu")
		(net "PVDDCR_CPU0_P0_VCC3")
	)
	(segment
		(start 381.343662 -179.056284)
		(end 381.843026 -179.555648)
		(width 0.508)
		(layer "B.Cu")
		(net "PVDDCR_CPU0_P0_VCC3")
	)
	(segment
		(start 382.933448 -179.974748)
		(end 383.38887 -180.43017)
		(width 0.381)
		(layer "B.Cu")
		(net "PVDDCR_CPU0_P0_VCC3")
	)
	(segment
		(start 384.094228 -181.089046)
		(end 384.760978 -181.089046)
		(width 0.381)
		(layer "B.Cu")
		(net "PVDDCR_CPU0_P0_VCC3")
	)
	(segment
		(start 381.843026 -179.555648)
		(end 382.620012 -179.555648)
		(width 0.508)
		(layer "B.Cu")
		(net "PVDDCR_CPU0_P0_VCC3")
	)
	(segment
		(start 383.38887 -180.43017)
		(end 383.38887 -181.284626)
		(width 0.381)
		(layer "B.Cu")
		(net "PVDDCR_CPU0_P0_VCC3")
	)
	(segment
		(start 383.38887 -181.284626)
		(end 383.898648 -181.284626)
		(width 0.381)
		(layer "B.Cu")
		(net "PVDDCR_CPU0_P0_VCC3")
	)
	(segment
		(start 383.898648 -181.284626)
		(end 384.094228 -181.089046)
		(width 0.381)
		(layer "B.Cu")
		(net "PVDDCR_CPU0_P0_VCC3")
	)
	(segment
		(start 382.620012 -179.555648)
		(end 382.933448 -179.869084)
		(width 0.508)
		(layer "B.Cu")
		(net "PVDDCR_CPU0_P0_VCC3")
	)
	(segment
		(start 382.933448 -179.869084)
		(end 382.933448 -179.974748)
		(width 0.381)
		(layer "B.Cu")
		(net "PVDDCR_CPU0_P0_VCC3")
	)
	(segment
		(start 376.005852 -181.089046)
		(end 375.725944 -181.368954)
		(width 0.2286)
		(layer "F.Cu")
		(net "PVDDCR_CPU0_P0_VCC2")
	)
	(segment
		(start 372.865142 -179.843938)
		(end 372.865142 -179.131976)
		(width 0.2286)
		(layer "F.Cu")
		(net "PVDDCR_CPU0_P0_VCC2")
	)
	(segment
		(start 372.865142 -179.131976)
		(end 372.940834 -179.056284)
		(width 0.2286)
		(layer "F.Cu")
		(net "PVDDCR_CPU0_P0_VCC2")
	)
	(segment
		(start 376.35815 -181.089046)
		(end 376.005852 -181.089046)
		(width 0.2286)
		(layer "F.Cu")
		(net "PVDDCR_CPU0_P0_VCC2")
	)
	(segment
		(start 375.725944 -181.368954)
		(end 375.075196 -181.368954)
		(width 0.2286)
		(layer "F.Cu")
		(net "PVDDCR_CPU0_P0_VCC2")
	)
	(segment
		(start 376.35815 -180.478684)
		(end 376.35815 -181.089046)
		(width 0.381)
		(layer "F.Cu")
		(net "PVDDCR_CPU0_P0_VCC2")
	)
	(via
		(at 376.35815 -181.089046)
		(size 0.508)
		(drill 0.254)
		(layers "F.Cu" "B.Cu")
		(net "PVDDCR_CPU0_P0_VCC2")
	)
	(via
		(at 374.53062 -179.974748)
		(size 0.6604)
		(drill 0.3302)
		(layers "F.Cu" "B.Cu")
		(net "PVDDCR_CPU0_P0_VCC2")
	)
	(via
		(at 372.940834 -179.056284)
		(size 0.508)
		(drill 0.254)
		(layers "F.Cu" "B.Cu")
		(net "PVDDCR_CPU0_P0_VCC2")
	)
	(segment
		(start 374.253252 -179.69738)
		(end 374.53062 -179.974748)
		(width 0.381)
		(layer "B.Cu")
		(net "PVDDCR_CPU0_P0_VCC2")
	)
	(segment
		(start 373.58193 -179.69738)
		(end 374.253252 -179.69738)
		(width 0.381)
		(layer "B.Cu")
		(net "PVDDCR_CPU0_P0_VCC2")
	)
	(segment
		(start 374.53062 -179.974748)
		(end 374.986042 -180.43017)
		(width 0.381)
		(layer "B.Cu")
		(net "PVDDCR_CPU0_P0_VCC2")
	)
	(segment
		(start 375.6914 -181.089046)
		(end 376.35815 -181.089046)
		(width 0.381)
		(layer "B.Cu")
		(net "PVDDCR_CPU0_P0_VCC2")
	)
	(segment
		(start 374.986042 -181.284626)
		(end 375.49582 -181.284626)
		(width 0.381)
		(layer "B.Cu")
		(net "PVDDCR_CPU0_P0_VCC2")
	)
	(segment
		(start 372.940834 -179.056284)
		(end 373.58193 -179.69738)
		(width 0.508)
		(layer "B.Cu")
		(net "PVDDCR_CPU0_P0_VCC2")
	)
	(segment
		(start 374.986042 -180.43017)
		(end 374.986042 -181.284626)
		(width 0.381)
		(layer "B.Cu")
		(net "PVDDCR_CPU0_P0_VCC2")
	)
	(segment
		(start 375.49582 -181.284626)
		(end 375.6914 -181.089046)
		(width 0.381)
		(layer "B.Cu")
		(net "PVDDCR_CPU0_P0_VCC2")
	)
	(segment
		(start 367.996978 -175.506126)
		(end 367.996978 -176.116488)
		(width 0.381)
		(layer "F.Cu")
		(net "PVDDCR_CPU0_P0_VCC1")
	)
	(segment
		(start 364.50397 -174.159418)
		(end 364.579662 -174.083726)
		(width 0.2286)
		(layer "F.Cu")
		(net "PVDDCR_CPU0_P0_VCC1")
	)
	(segment
		(start 367.364772 -176.396396)
		(end 366.714024 -176.396396)
		(width 0.2286)
		(layer "F.Cu")
		(net "PVDDCR_CPU0_P0_VCC1")
	)
	(segment
		(start 364.50397 -174.87138)
		(end 364.50397 -174.159418)
		(width 0.2286)
		(layer "F.Cu")
		(net "PVDDCR_CPU0_P0_VCC1")
	)
	(segment
		(start 367.64468 -176.116488)
		(end 367.364772 -176.396396)
		(width 0.2286)
		(layer "F.Cu")
		(net "PVDDCR_CPU0_P0_VCC1")
	)
	(segment
		(start 367.996978 -176.116488)
		(end 367.64468 -176.116488)
		(width 0.2286)
		(layer "F.Cu")
		(net "PVDDCR_CPU0_P0_VCC1")
	)
	(via
		(at 364.579662 -174.083726)
		(size 0.508)
		(drill 0.254)
		(layers "F.Cu" "B.Cu")
		(net "PVDDCR_CPU0_P0_VCC1")
	)
	(via
		(at 366.169448 -175.00219)
		(size 0.6604)
		(drill 0.3302)
		(layers "F.Cu" "B.Cu")
		(net "PVDDCR_CPU0_P0_VCC1")
	)
	(via
		(at 367.996978 -176.116488)
		(size 0.508)
		(drill 0.254)
		(layers "F.Cu" "B.Cu")
		(net "PVDDCR_CPU0_P0_VCC1")
	)
	(segment
		(start 366.169448 -174.896526)
		(end 365.856012 -174.58309)
		(width 0.508)
		(layer "B.Cu")
		(net "PVDDCR_CPU0_P0_VCC1")
	)
	(segment
		(start 366.169448 -175.00219)
		(end 366.169448 -174.896526)
		(width 0.381)
		(layer "B.Cu")
		(net "PVDDCR_CPU0_P0_VCC1")
	)
	(segment
		(start 367.134648 -176.312068)
		(end 366.62487 -176.312068)
		(width 0.381)
		(layer "B.Cu")
		(net "PVDDCR_CPU0_P0_VCC1")
	)
	(segment
		(start 365.856012 -174.58309)
		(end 365.079026 -174.58309)
		(width 0.508)
		(layer "B.Cu")
		(net "PVDDCR_CPU0_P0_VCC1")
	)
	(segment
		(start 366.62487 -175.457612)
		(end 366.169448 -175.00219)
		(width 0.381)
		(layer "B.Cu")
		(net "PVDDCR_CPU0_P0_VCC1")
	)
	(segment
		(start 367.996978 -176.116488)
		(end 367.330228 -176.116488)
		(width 0.381)
		(layer "B.Cu")
		(net "PVDDCR_CPU0_P0_VCC1")
	)
	(segment
		(start 366.62487 -176.312068)
		(end 366.62487 -175.457612)
		(width 0.381)
		(layer "B.Cu")
		(net "PVDDCR_CPU0_P0_VCC1")
	)
	(segment
		(start 367.330228 -176.116488)
		(end 367.134648 -176.312068)
		(width 0.381)
		(layer "B.Cu")
		(net "PVDDCR_CPU0_P0_VCC1")
	)
	(segment
		(start 365.079026 -174.58309)
		(end 364.579662 -174.083726)
		(width 0.508)
		(layer "B.Cu")
		(net "PVDDCR_CPU0_P0_VCC1")
	)
	(via
		(at 382.74371 -138.801348)
		(size 0.6604)
		(drill 0.3302)
		(layers "F.Cu" "B.Cu")
		(net "PVDDCR_CPU0_P0_VCC")
	)
	(segment
		(start 364.954058 -174.87138)
		(end 364.954058 -174.593758)
		(width 0.2286)
		(layer "F.Cu")
		(net "PVDDCR_CPU0_P0_TEMP0")
	)
	(segment
		(start 381.718058 -179.572158)
		(end 381.8382 -179.282344)
		(width 0.2286)
		(layer "F.Cu")
		(net "PVDDCR_CPU0_P0_TEMP0")
	)
	(segment
		(start 365.275114 -174.108872)
		(end 365.275114 -173.837854)
		(width 0.2286)
		(layer "F.Cu")
		(net "PVDDCR_CPU0_P0_TEMP0")
	)
	(segment
		(start 348.367858 -157.968696)
		(end 348.367858 -158.23946)
		(width 0.2286)
		(layer "F.Cu")
		(net "PVDDCR_CPU0_P0_TEMP0")
	)
	(segment
		(start 364.954058 -174.593758)
		(end 365.069882 -174.314104)
		(width 0.2286)
		(layer "F.Cu")
		(net "PVDDCR_CPU0_P0_TEMP0")
	)
	(segment
		(start 373.31523 -179.563014)
		(end 373.428768 -179.288948)
		(width 0.2286)
		(layer "F.Cu")
		(net "PVDDCR_CPU0_P0_TEMP0")
	)
	(segment
		(start 390.049258 -179.843938)
		(end 390.049258 -179.559712)
		(width 0.2286)
		(layer "F.Cu")
		(net "PVDDCR_CPU0_P0_TEMP0")
	)
	(segment
		(start 373.636286 -179.08143)
		(end 373.636286 -178.810412)
		(width 0.2286)
		(layer "F.Cu")
		(net "PVDDCR_CPU0_P0_TEMP0")
	)
	(segment
		(start 356.79888 -166.029386)
		(end 356.994714 -165.833552)
		(width 0.2286)
		(layer "F.Cu")
		(net "PVDDCR_CPU0_P0_TEMP0")
	)
	(segment
		(start 373.428768 -179.288948)
		(end 373.636286 -179.08143)
		(width 0.2286)
		(layer "F.Cu")
		(net "PVDDCR_CPU0_P0_TEMP0")
	)
	(segment
		(start 365.069882 -174.314104)
		(end 365.275114 -174.108872)
		(width 0.2286)
		(layer "F.Cu")
		(net "PVDDCR_CPU0_P0_TEMP0")
	)
	(segment
		(start 390.16051 -179.291234)
		(end 390.370314 -179.08143)
		(width 0.2286)
		(layer "F.Cu")
		(net "PVDDCR_CPU0_P0_TEMP0")
	)
	(segment
		(start 348.688914 -157.205934)
		(end 348.688914 -157.476952)
		(width 0.2286)
		(layer "F.Cu")
		(net "PVDDCR_CPU0_P0_TEMP0")
	)
	(segment
		(start 390.049258 -179.559712)
		(end 390.16051 -179.291234)
		(width 0.2286)
		(layer "F.Cu")
		(net "PVDDCR_CPU0_P0_TEMP0")
	)
	(segment
		(start 356.673658 -166.59606)
		(end 356.673658 -166.331646)
		(width 0.2286)
		(layer "F.Cu")
		(net "PVDDCR_CPU0_P0_TEMP0")
	)
	(segment
		(start 382.039114 -179.08143)
		(end 382.039114 -178.810412)
		(width 0.2286)
		(layer "F.Cu")
		(net "PVDDCR_CPU0_P0_TEMP0")
	)
	(segment
		(start 381.8382 -179.282344)
		(end 382.039114 -179.08143)
		(width 0.2286)
		(layer "F.Cu")
		(net "PVDDCR_CPU0_P0_TEMP0")
	)
	(segment
		(start 381.718058 -179.88661)
		(end 381.718058 -179.572158)
		(width 0.2286)
		(layer "F.Cu")
		(net "PVDDCR_CPU0_P0_TEMP0")
	)
	(segment
		(start 390.370314 -179.08143)
		(end 390.370314 -178.810412)
		(width 0.2286)
		(layer "F.Cu")
		(net "PVDDCR_CPU0_P0_TEMP0")
	)
	(segment
		(start 373.31523 -179.843938)
		(end 373.31523 -179.563014)
		(width 0.2286)
		(layer "F.Cu")
		(net "PVDDCR_CPU0_P0_TEMP0")
	)
	(segment
		(start 356.994714 -165.833552)
		(end 356.994714 -165.562534)
		(width 0.2286)
		(layer "F.Cu")
		(net "PVDDCR_CPU0_P0_TEMP0")
	)
	(segment
		(start 348.488508 -157.677358)
		(end 348.367858 -157.968696)
		(width 0.2286)
		(layer "F.Cu")
		(net "PVDDCR_CPU0_P0_TEMP0")
	)
	(segment
		(start 348.688914 -157.476952)
		(end 348.488508 -157.677358)
		(width 0.2286)
		(layer "F.Cu")
		(net "PVDDCR_CPU0_P0_TEMP0")
	)
	(segment
		(start 356.673658 -166.331646)
		(end 356.79888 -166.029386)
		(width 0.2286)
		(layer "F.Cu")
		(net "PVDDCR_CPU0_P0_TEMP0")
	)
	(via
		(at 373.636286 -178.810412)
		(size 0.508)
		(drill 0.254)
		(layers "F.Cu" "B.Cu")
		(net "PVDDCR_CPU0_P0_TEMP0")
	)
	(via
		(at 356.994714 -165.562534)
		(size 0.508)
		(drill 0.254)
		(layers "F.Cu" "B.Cu")
		(net "PVDDCR_CPU0_P0_TEMP0")
	)
	(via
		(at 365.275114 -173.837854)
		(size 0.508)
		(drill 0.254)
		(layers "F.Cu" "B.Cu")
		(net "PVDDCR_CPU0_P0_TEMP0")
	)
	(via
		(at 385.942078 -141.309852)
		(size 0.762)
		(drill 0.254)
		(layers "F.Cu" "B.Cu")
		(net "PVDDCR_CPU0_P0_TEMP0")
	)
	(via
		(at 382.039114 -178.810412)
		(size 0.508)
		(drill 0.254)
		(layers "F.Cu" "B.Cu")
		(net "PVDDCR_CPU0_P0_TEMP0")
	)
	(via
		(at 390.370314 -178.810412)
		(size 0.508)
		(drill 0.254)
		(layers "F.Cu" "B.Cu")
		(net "PVDDCR_CPU0_P0_TEMP0")
	)
	(via
		(at 348.688914 -157.205934)
		(size 0.508)
		(drill 0.254)
		(layers "F.Cu" "B.Cu")
		(net "PVDDCR_CPU0_P0_TEMP0")
	)
	(segment
		(start 382.628394 -141.76121)
		(end 382.844802 -141.544802)
		(width 0.254)
		(layer "B.Cu")
		(net "PVDDCR_CPU0_P0_TEMP0")
	)
	(segment
		(start 384.221228 -141.726158)
		(end 385.525772 -141.726158)
		(width 0.1524)
		(layer "B.Cu")
		(net "PVDDCR_CPU0_P0_TEMP0")
	)
	(segment
		(start 382.844802 -141.544802)
		(end 383.386584 -141.544802)
		(width 0.254)
		(layer "B.Cu")
		(net "PVDDCR_CPU0_P0_TEMP0")
	)
	(segment
		(start 385.525772 -141.726158)
		(end 385.942078 -141.309852)
		(width 0.1524)
		(layer "B.Cu")
		(net "PVDDCR_CPU0_P0_TEMP0")
	)
	(segment
		(start 381.979678 -141.76121)
		(end 382.628394 -141.76121)
		(width 0.254)
		(layer "B.Cu")
		(net "PVDDCR_CPU0_P0_TEMP0")
	)
	(segment
		(start 383.713228 -141.218158)
		(end 384.221228 -141.726158)
		(width 0.1524)
		(layer "B.Cu")
		(net "PVDDCR_CPU0_P0_TEMP0")
	)
	(segment
		(start 383.386584 -141.544802)
		(end 383.713228 -141.218158)
		(width 0.254)
		(layer "B.Cu")
		(net "PVDDCR_CPU0_P0_TEMP0")
	)
	(segment
		(start 381.273304 -141.76121)
		(end 381.979678 -141.76121)
		(width 0.1778)
		(layer "B.Cu")
		(net "PVDDCR_CPU0_P0_TEMP0")
	)
	(segment
		(start 382.441958 -149.529546)
		(end 381.801878 -150.169626)
		(width 0.254)
		(layer "In2.Cu")
		(net "PVDDCR_CPU0_P0_TEMP0")
	)
	(segment
		(start 358.167178 -163.339272)
		(end 359.312464 -163.339272)
		(width 0.254)
		(layer "In2.Cu")
		(net "PVDDCR_CPU0_P0_TEMP0")
	)
	(segment
		(start 382.441958 -144.926304)
		(end 382.441958 -149.529546)
		(width 0.254)
		(layer "In2.Cu")
		(net "PVDDCR_CPU0_P0_TEMP0")
	)
	(segment
		(start 348.688914 -156.090874)
		(end 349.823278 -154.95651)
		(width 0.254)
		(layer "In2.Cu")
		(net "PVDDCR_CPU0_P0_TEMP0")
	)
	(segment
		(start 349.823278 -154.95651)
		(end 355.462078 -154.95651)
		(width 0.254)
		(layer "In2.Cu")
		(net "PVDDCR_CPU0_P0_TEMP0")
	)
	(segment
		(start 390.370314 -177.317146)
		(end 390.370314 -178.810412)
		(width 0.254)
		(layer "In2.Cu")
		(net "PVDDCR_CPU0_P0_TEMP0")
	)
	(segment
		(start 381.12446 -141.93012)
		(end 381.12446 -143.608806)
		(width 0.254)
		(layer "In2.Cu")
		(net "PVDDCR_CPU0_P0_TEMP0")
	)
	(segment
		(start 382.610868 -176.62652)
		(end 389.679688 -176.62652)
		(width 0.254)
		(layer "In2.Cu")
		(net "PVDDCR_CPU0_P0_TEMP0")
	)
	(segment
		(start 366.257078 -171.51731)
		(end 371.235478 -171.51731)
		(width 0.254)
		(layer "In2.Cu")
		(net "PVDDCR_CPU0_P0_TEMP0")
	)
	(segment
		(start 360.658664 -161.993072)
		(end 359.312464 -163.339272)
		(width 0.254)
		(layer "In2.Cu")
		(net "PVDDCR_CPU0_P0_TEMP0")
	)
	(segment
		(start 383.64414 -141.437868)
		(end 381.616712 -141.437868)
		(width 0.254)
		(layer "In2.Cu")
		(net "PVDDCR_CPU0_P0_TEMP0")
	)
	(segment
		(start 383.91465 -141.708378)
		(end 383.64414 -141.437868)
		(width 0.254)
		(layer "In2.Cu")
		(net "PVDDCR_CPU0_P0_TEMP0")
	)
	(segment
		(start 382.039114 -177.215546)
		(end 382.039114 -178.810412)
		(width 0.254)
		(layer "In2.Cu")
		(net "PVDDCR_CPU0_P0_TEMP0")
	)
	(segment
		(start 381.801878 -150.169626)
		(end 378.976382 -150.169626)
		(width 0.254)
		(layer "In2.Cu")
		(net "PVDDCR_CPU0_P0_TEMP0")
	)
	(segment
		(start 389.679688 -176.62652)
		(end 390.370314 -177.317146)
		(width 0.254)
		(layer "In2.Cu")
		(net "PVDDCR_CPU0_P0_TEMP0")
	)
	(segment
		(start 356.335838 -155.83027)
		(end 356.335838 -161.558732)
		(width 0.254)
		(layer "In2.Cu")
		(net "PVDDCR_CPU0_P0_TEMP0")
	)
	(segment
		(start 365.275114 -173.837854)
		(end 365.317278 -173.79569)
		(width 0.254)
		(layer "In2.Cu")
		(net "PVDDCR_CPU0_P0_TEMP0")
	)
	(segment
		(start 381.616712 -141.437868)
		(end 381.12446 -141.93012)
		(width 0.254)
		(layer "In2.Cu")
		(net "PVDDCR_CPU0_P0_TEMP0")
	)
	(segment
		(start 356.994714 -162.217608)
		(end 356.994714 -164.045392)
		(width 0.254)
		(layer "In2.Cu")
		(net "PVDDCR_CPU0_P0_TEMP0")
	)
	(segment
		(start 373.636286 -173.918118)
		(end 373.636286 -175.772318)
		(width 0.254)
		(layer "In2.Cu")
		(net "PVDDCR_CPU0_P0_TEMP0")
	)
	(segment
		(start 381.12446 -143.608806)
		(end 382.441958 -144.926304)
		(width 0.254)
		(layer "In2.Cu")
		(net "PVDDCR_CPU0_P0_TEMP0")
	)
	(segment
		(start 385.543552 -141.708378)
		(end 383.91465 -141.708378)
		(width 0.254)
		(layer "In2.Cu")
		(net "PVDDCR_CPU0_P0_TEMP0")
	)
	(segment
		(start 356.994714 -164.045392)
		(end 356.994714 -165.562534)
		(width 0.254)
		(layer "In2.Cu")
		(net "PVDDCR_CPU0_P0_TEMP0")
	)
	(segment
		(start 382.030478 -177.20691)
		(end 382.610868 -176.62652)
		(width 0.254)
		(layer "In2.Cu")
		(net "PVDDCR_CPU0_P0_TEMP0")
	)
	(segment
		(start 365.317278 -169.344086)
		(end 365.317278 -170.57751)
		(width 0.254)
		(layer "In2.Cu")
		(net "PVDDCR_CPU0_P0_TEMP0")
	)
	(segment
		(start 373.636286 -175.772318)
		(end 374.334278 -176.47031)
		(width 0.254)
		(layer "In2.Cu")
		(net "PVDDCR_CPU0_P0_TEMP0")
	)
	(segment
		(start 371.235478 -171.51731)
		(end 373.636286 -173.918118)
		(width 0.254)
		(layer "In2.Cu")
		(net "PVDDCR_CPU0_P0_TEMP0")
	)
	(segment
		(start 376.96775 -152.178258)
		(end 366.187482 -152.178258)
		(width 0.254)
		(layer "In2.Cu")
		(net "PVDDCR_CPU0_P0_TEMP0")
	)
	(segment
		(start 382.030478 -177.20691)
		(end 382.039114 -177.215546)
		(width 0.254)
		(layer "In2.Cu")
		(net "PVDDCR_CPU0_P0_TEMP0")
	)
	(segment
		(start 365.317278 -172.45711)
		(end 366.257078 -171.51731)
		(width 0.254)
		(layer "In2.Cu")
		(net "PVDDCR_CPU0_P0_TEMP0")
	)
	(segment
		(start 385.942078 -141.309852)
		(end 385.543552 -141.708378)
		(width 0.254)
		(layer "In2.Cu")
		(net "PVDDCR_CPU0_P0_TEMP0")
	)
	(segment
		(start 365.317278 -173.79569)
		(end 365.317278 -172.45711)
		(width 0.254)
		(layer "In2.Cu")
		(net "PVDDCR_CPU0_P0_TEMP0")
	)
	(segment
		(start 366.187482 -152.178258)
		(end 360.658664 -157.707076)
		(width 0.254)
		(layer "In2.Cu")
		(net "PVDDCR_CPU0_P0_TEMP0")
	)
	(segment
		(start 348.688914 -157.205934)
		(end 348.688914 -156.090874)
		(width 0.254)
		(layer "In2.Cu")
		(net "PVDDCR_CPU0_P0_TEMP0")
	)
	(segment
		(start 357.461058 -164.045392)
		(end 358.167178 -163.339272)
		(width 0.254)
		(layer "In2.Cu")
		(net "PVDDCR_CPU0_P0_TEMP0")
	)
	(segment
		(start 355.462078 -154.95651)
		(end 356.335838 -155.83027)
		(width 0.254)
		(layer "In2.Cu")
		(net "PVDDCR_CPU0_P0_TEMP0")
	)
	(segment
		(start 359.312464 -163.339272)
		(end 365.317278 -169.344086)
		(width 0.254)
		(layer "In2.Cu")
		(net "PVDDCR_CPU0_P0_TEMP0")
	)
	(segment
		(start 373.636286 -177.168302)
		(end 374.334278 -176.47031)
		(width 0.254)
		(layer "In2.Cu")
		(net "PVDDCR_CPU0_P0_TEMP0")
	)
	(segment
		(start 356.994714 -164.045392)
		(end 357.461058 -164.045392)
		(width 0.254)
		(layer "In2.Cu")
		(net "PVDDCR_CPU0_P0_TEMP0")
	)
	(segment
		(start 374.334278 -176.47031)
		(end 381.293878 -176.47031)
		(width 0.254)
		(layer "In2.Cu")
		(net "PVDDCR_CPU0_P0_TEMP0")
	)
	(segment
		(start 360.658664 -157.707076)
		(end 360.658664 -161.993072)
		(width 0.254)
		(layer "In2.Cu")
		(net "PVDDCR_CPU0_P0_TEMP0")
	)
	(segment
		(start 378.976382 -150.169626)
		(end 376.96775 -152.178258)
		(width 0.254)
		(layer "In2.Cu")
		(net "PVDDCR_CPU0_P0_TEMP0")
	)
	(segment
		(start 381.293878 -176.47031)
		(end 382.030478 -177.20691)
		(width 0.254)
		(layer "In2.Cu")
		(net "PVDDCR_CPU0_P0_TEMP0")
	)
	(segment
		(start 373.636286 -178.810412)
		(end 373.636286 -177.168302)
		(width 0.254)
		(layer "In2.Cu")
		(net "PVDDCR_CPU0_P0_TEMP0")
	)
	(segment
		(start 356.335838 -161.558732)
		(end 356.994714 -162.217608)
		(width 0.254)
		(layer "In2.Cu")
		(net "PVDDCR_CPU0_P0_TEMP0")
	)
	(segment
		(start 365.317278 -170.57751)
		(end 366.257078 -171.51731)
		(width 0.254)
		(layer "In2.Cu")
		(net "PVDDCR_CPU0_P0_TEMP0")
	)
	(segment
		(start 373.69369 -141.82852)
		(end 374.233948 -141.82852)
		(width 0.10668)
		(layer "F.Cu")
		(net "PVDDCR_CPU0_P0_RESET_N_R")
	)
	(segment
		(start 373.337328 -141.472158)
		(end 373.69369 -141.82852)
		(width 0.10668)
		(layer "F.Cu")
		(net "PVDDCR_CPU0_P0_RESET_N_R")
	)
	(via
		(at 374.233948 -141.82852)
		(size 0.508)
		(drill 0.254)
		(layers "F.Cu" "B.Cu")
		(net "PVDDCR_CPU0_P0_RESET_N_R")
	)
	(segment
		(start 374.266206 -141.82852)
		(end 374.233948 -141.82852)
		(width 0.10668)
		(layer "B.Cu")
		(net "PVDDCR_CPU0_P0_RESET_N_R")
	)
	(segment
		(start 374.598946 -142.16126)
		(end 374.266206 -141.82852)
		(width 0.10668)
		(layer "B.Cu")
		(net "PVDDCR_CPU0_P0_RESET_N_R")
	)
	(segment
		(start 375.523252 -142.16126)
		(end 374.598946 -142.16126)
		(width 0.10668)
		(layer "B.Cu")
		(net "PVDDCR_CPU0_P0_RESET_N_R")
	)
	(segment
		(start 373.69369 -141.82852)
		(end 373.337328 -141.472158)
		(width 0.10668)
		(layer "B.Cu")
		(net "PVDDCR_CPU0_P0_RESET_N_R")
	)
	(segment
		(start 374.233948 -141.82852)
		(end 373.69369 -141.82852)
		(width 0.10668)
		(layer "B.Cu")
		(net "PVDDCR_CPU0_P0_RESET_N_R")
	)
	(segment
		(start 391.189464 -141.02461)
		(end 391.189464 -141.86408)
		(width 0.10668)
		(layer "F.Cu")
		(net "PVDDCR_CPU0_P0_RESET_N")
	)
	(segment
		(start 391.189464 -141.86408)
		(end 391.082022 -141.971522)
		(width 0.10668)
		(layer "F.Cu")
		(net "PVDDCR_CPU0_P0_RESET_N")
	)
	(via
		(at 391.082022 -141.971522)
		(size 0.508)
		(drill 0.254)
		(layers "F.Cu" "B.Cu")
		(net "PVDDCR_CPU0_P0_RESET_N")
	)
	(via
		(at 371.474238 -140.975334)
		(size 0.508)
		(drill 0.254)
		(layers "F.Cu" "B.Cu")
		(net "PVDDCR_CPU0_P0_RESET_N")
	)
	(segment
		(start 372.537228 -141.472158)
		(end 372.537228 -141.27353)
		(width 0.10668)
		(layer "B.Cu")
		(net "PVDDCR_CPU0_P0_RESET_N")
	)
	(segment
		(start 372.239032 -140.975334)
		(end 371.474238 -140.975334)
		(width 0.10668)
		(layer "B.Cu")
		(net "PVDDCR_CPU0_P0_RESET_N")
	)
	(segment
		(start 372.537228 -141.27353)
		(end 372.239032 -140.975334)
		(width 0.10668)
		(layer "B.Cu")
		(net "PVDDCR_CPU0_P0_RESET_N")
	)
	(segment
		(start 372.029482 -133.94944)
		(end 370.326158 -135.652764)
		(width 0.11684)
		(layer "In11.Cu")
		(net "PVDDCR_CPU0_P0_RESET_N")
	)
	(segment
		(start 389.60425 -140.49375)
		(end 389.60425 -135.777478)
		(width 0.11684)
		(layer "In11.Cu")
		(net "PVDDCR_CPU0_P0_RESET_N")
	)
	(segment
		(start 389.60425 -135.777478)
		(end 387.776212 -133.94944)
		(width 0.11684)
		(layer "In11.Cu")
		(net "PVDDCR_CPU0_P0_RESET_N")
	)
	(segment
		(start 387.776212 -133.94944)
		(end 372.029482 -133.94944)
		(width 0.11684)
		(layer "In11.Cu")
		(net "PVDDCR_CPU0_P0_RESET_N")
	)
	(segment
		(start 370.326158 -139.827254)
		(end 371.474238 -140.975334)
		(width 0.11684)
		(layer "In11.Cu")
		(net "PVDDCR_CPU0_P0_RESET_N")
	)
	(segment
		(start 391.082022 -141.971522)
		(end 389.60425 -140.49375)
		(width 0.11684)
		(layer "In11.Cu")
		(net "PVDDCR_CPU0_P0_RESET_N")
	)
	(segment
		(start 370.326158 -135.652764)
		(end 370.326158 -139.827254)
		(width 0.11684)
		(layer "In11.Cu")
		(net "PVDDCR_CPU0_P0_RESET_N")
	)
	(segment
		(start 347.802962 -156.799534)
		(end 347.467682 -157.134814)
		(width 0.1778)
		(layer "F.Cu")
		(net "PVDDCR_CPU0_P0_PWM6")
	)
	(segment
		(start 347.467682 -157.134814)
		(end 347.467682 -158.23946)
		(width 0.1778)
		(layer "F.Cu")
		(net "PVDDCR_CPU0_P0_PWM6")
	)
	(via
		(at 347.802962 -156.799534)
		(size 0.508)
		(drill 0.254)
		(layers "F.Cu" "B.Cu")
		(net "PVDDCR_CPU0_P0_PWM6")
	)
	(via
		(at 378.612908 -138.36777)
		(size 0.508)
		(drill 0.254)
		(layers "F.Cu" "B.Cu")
		(net "PVDDCR_CPU0_P0_PWM6")
	)
	(segment
		(start 378.612908 -138.36777)
		(end 378.19838 -138.782298)
		(width 0.1524)
		(layer "B.Cu")
		(net "PVDDCR_CPU0_P0_PWM6")
	)
	(segment
		(start 378.19838 -138.782298)
		(end 378.19838 -139.486132)
		(width 0.1524)
		(layer "B.Cu")
		(net "PVDDCR_CPU0_P0_PWM6")
	)
	(segment
		(start 378.612908 -137.577068)
		(end 378.612908 -138.36777)
		(width 0.1524)
		(layer "In6.Cu")
		(net "PVDDCR_CPU0_P0_PWM6")
	)
	(segment
		(start 372.720108 -136.539986)
		(end 373.525542 -135.734552)
		(width 0.1524)
		(layer "In6.Cu")
		(net "PVDDCR_CPU0_P0_PWM6")
	)
	(segment
		(start 368.27587 -136.539986)
		(end 372.720108 -136.539986)
		(width 0.1524)
		(layer "In6.Cu")
		(net "PVDDCR_CPU0_P0_PWM6")
	)
	(segment
		(start 373.525542 -135.734552)
		(end 376.770392 -135.734552)
		(width 0.1524)
		(layer "In6.Cu")
		(net "PVDDCR_CPU0_P0_PWM6")
	)
	(segment
		(start 348.016322 -156.799534)
		(end 368.27587 -136.539986)
		(width 0.1524)
		(layer "In6.Cu")
		(net "PVDDCR_CPU0_P0_PWM6")
	)
	(segment
		(start 376.770392 -135.734552)
		(end 378.612908 -137.577068)
		(width 0.1524)
		(layer "In6.Cu")
		(net "PVDDCR_CPU0_P0_PWM6")
	)
	(segment
		(start 347.802962 -156.799534)
		(end 348.016322 -156.799534)
		(width 0.1524)
		(layer "In6.Cu")
		(net "PVDDCR_CPU0_P0_PWM6")
	)
	(segment
		(start 356.108762 -165.156134)
		(end 355.773482 -165.491414)
		(width 0.1778)
		(layer "F.Cu")
		(net "PVDDCR_CPU0_P0_PWM5")
	)
	(segment
		(start 355.773482 -165.491414)
		(end 355.773482 -166.59606)
		(width 0.1778)
		(layer "F.Cu")
		(net "PVDDCR_CPU0_P0_PWM5")
	)
	(via
		(at 356.108762 -165.156134)
		(size 0.508)
		(drill 0.254)
		(layers "F.Cu" "B.Cu")
		(net "PVDDCR_CPU0_P0_PWM5")
	)
	(via
		(at 378.08154 -137.875264)
		(size 0.508)
		(drill 0.254)
		(layers "F.Cu" "B.Cu")
		(net "PVDDCR_CPU0_P0_PWM5")
	)
	(segment
		(start 378.08154 -137.875264)
		(end 377.613164 -138.34364)
		(width 0.1524)
		(layer "B.Cu")
		(net "PVDDCR_CPU0_P0_PWM5")
	)
	(segment
		(start 377.613164 -138.34364)
		(end 377.613164 -138.665712)
		(width 0.1524)
		(layer "B.Cu")
		(net "PVDDCR_CPU0_P0_PWM5")
	)
	(segment
		(start 377.79833 -138.850878)
		(end 377.79833 -139.486132)
		(width 0.1524)
		(layer "B.Cu")
		(net "PVDDCR_CPU0_P0_PWM5")
	)
	(segment
		(start 377.613164 -138.665712)
		(end 377.79833 -138.850878)
		(width 0.1524)
		(layer "B.Cu")
		(net "PVDDCR_CPU0_P0_PWM5")
	)
	(segment
		(start 377.418092 -137.029952)
		(end 376.345958 -137.029952)
		(width 0.1524)
		(layer "In6.Cu")
		(net "PVDDCR_CPU0_P0_PWM5")
	)
	(segment
		(start 372.959884 -137.185146)
		(end 369.01247 -137.185146)
		(width 0.1524)
		(layer "In6.Cu")
		(net "PVDDCR_CPU0_P0_PWM5")
	)
	(segment
		(start 378.08154 -137.875264)
		(end 378.08154 -137.6934)
		(width 0.1524)
		(layer "In6.Cu")
		(net "PVDDCR_CPU0_P0_PWM5")
	)
	(segment
		(start 375.756678 -136.440672)
		(end 373.704358 -136.440672)
		(width 0.1524)
		(layer "In6.Cu")
		(net "PVDDCR_CPU0_P0_PWM5")
	)
	(segment
		(start 378.08154 -137.6934)
		(end 377.418092 -137.029952)
		(width 0.1524)
		(layer "In6.Cu")
		(net "PVDDCR_CPU0_P0_PWM5")
	)
	(segment
		(start 369.01247 -137.185146)
		(end 355.46792 -150.729696)
		(width 0.1524)
		(layer "In6.Cu")
		(net "PVDDCR_CPU0_P0_PWM5")
	)
	(segment
		(start 355.46792 -164.515292)
		(end 356.108762 -165.156134)
		(width 0.1524)
		(layer "In6.Cu")
		(net "PVDDCR_CPU0_P0_PWM5")
	)
	(segment
		(start 355.46792 -150.729696)
		(end 355.46792 -164.515292)
		(width 0.1524)
		(layer "In6.Cu")
		(net "PVDDCR_CPU0_P0_PWM5")
	)
	(segment
		(start 376.345958 -137.029952)
		(end 375.756678 -136.440672)
		(width 0.1524)
		(layer "In6.Cu")
		(net "PVDDCR_CPU0_P0_PWM5")
	)
	(segment
		(start 373.704358 -136.440672)
		(end 372.959884 -137.185146)
		(width 0.1524)
		(layer "In6.Cu")
		(net "PVDDCR_CPU0_P0_PWM5")
	)
	(segment
		(start 389.484362 -178.404012)
		(end 389.149082 -178.739292)
		(width 0.1778)
		(layer "F.Cu")
		(net "PVDDCR_CPU0_P0_PWM4")
	)
	(segment
		(start 389.149082 -178.739292)
		(end 389.149082 -179.843938)
		(width 0.1778)
		(layer "F.Cu")
		(net "PVDDCR_CPU0_P0_PWM4")
	)
	(via
		(at 389.484362 -178.404012)
		(size 0.508)
		(drill 0.254)
		(layers "F.Cu" "B.Cu")
		(net "PVDDCR_CPU0_P0_PWM4")
	)
	(via
		(at 377.041664 -137.581132)
		(size 0.508)
		(drill 0.254)
		(layers "F.Cu" "B.Cu")
		(net "PVDDCR_CPU0_P0_PWM4")
	)
	(segment
		(start 377.041664 -137.581132)
		(end 377.327414 -137.866882)
		(width 0.1524)
		(layer "B.Cu")
		(net "PVDDCR_CPU0_P0_PWM4")
	)
	(segment
		(start 377.39828 -138.940286)
		(end 377.39828 -139.486132)
		(width 0.1524)
		(layer "B.Cu")
		(net "PVDDCR_CPU0_P0_PWM4")
	)
	(segment
		(start 377.327414 -137.866882)
		(end 377.327414 -138.86942)
		(width 0.1524)
		(layer "B.Cu")
		(net "PVDDCR_CPU0_P0_PWM4")
	)
	(segment
		(start 377.327414 -138.86942)
		(end 377.39828 -138.940286)
		(width 0.1524)
		(layer "B.Cu")
		(net "PVDDCR_CPU0_P0_PWM4")
	)
	(segment
		(start 391.077958 -152.473152)
		(end 391.077958 -166.493952)
		(width 0.1524)
		(layer "In6.Cu")
		(net "PVDDCR_CPU0_P0_PWM4")
	)
	(segment
		(start 381.552958 -140.462762)
		(end 381.552958 -142.948152)
		(width 0.1524)
		(layer "In6.Cu")
		(net "PVDDCR_CPU0_P0_PWM4")
	)
	(segment
		(start 377.041664 -137.581132)
		(end 378.627894 -139.167362)
		(width 0.1524)
		(layer "In6.Cu")
		(net "PVDDCR_CPU0_P0_PWM4")
	)
	(segment
		(start 380.257558 -139.167362)
		(end 381.552958 -140.462762)
		(width 0.1524)
		(layer "In6.Cu")
		(net "PVDDCR_CPU0_P0_PWM4")
	)
	(segment
		(start 391.077958 -166.493952)
		(end 385.955794 -171.616116)
		(width 0.1524)
		(layer "In6.Cu")
		(net "PVDDCR_CPU0_P0_PWM4")
	)
	(segment
		(start 381.552958 -142.948152)
		(end 391.077958 -152.473152)
		(width 0.1524)
		(layer "In6.Cu")
		(net "PVDDCR_CPU0_P0_PWM4")
	)
	(segment
		(start 385.955794 -174.875444)
		(end 389.484362 -178.404012)
		(width 0.1524)
		(layer "In6.Cu")
		(net "PVDDCR_CPU0_P0_PWM4")
	)
	(segment
		(start 378.627894 -139.167362)
		(end 380.257558 -139.167362)
		(width 0.1524)
		(layer "In6.Cu")
		(net "PVDDCR_CPU0_P0_PWM4")
	)
	(segment
		(start 385.955794 -171.616116)
		(end 385.955794 -174.875444)
		(width 0.1524)
		(layer "In6.Cu")
		(net "PVDDCR_CPU0_P0_PWM4")
	)
	(segment
		(start 380.817882 -179.88661)
		(end 380.817882 -178.739292)
		(width 0.1778)
		(layer "F.Cu")
		(net "PVDDCR_CPU0_P0_PWM3")
	)
	(segment
		(start 380.817882 -178.739292)
		(end 381.153162 -178.404012)
		(width 0.1778)
		(layer "F.Cu")
		(net "PVDDCR_CPU0_P0_PWM3")
	)
	(via
		(at 381.153162 -178.404012)
		(size 0.508)
		(drill 0.254)
		(layers "F.Cu" "B.Cu")
		(net "PVDDCR_CPU0_P0_PWM3")
	)
	(via
		(at 376.439176 -137.799318)
		(size 0.508)
		(drill 0.254)
		(layers "F.Cu" "B.Cu")
		(net "PVDDCR_CPU0_P0_PWM3")
	)
	(segment
		(start 376.439176 -137.799318)
		(end 376.99823 -138.358372)
		(width 0.1524)
		(layer "B.Cu")
		(net "PVDDCR_CPU0_P0_PWM3")
	)
	(segment
		(start 376.99823 -138.358372)
		(end 376.99823 -139.486132)
		(width 0.1524)
		(layer "B.Cu")
		(net "PVDDCR_CPU0_P0_PWM3")
	)
	(segment
		(start 374.52046 -150.360634)
		(end 376.091958 -151.932132)
		(width 0.1524)
		(layer "In6.Cu")
		(net "PVDDCR_CPU0_P0_PWM3")
	)
	(segment
		(start 376.439176 -137.799318)
		(end 377.463558 -138.8237)
		(width 0.1524)
		(layer "In6.Cu")
		(net "PVDDCR_CPU0_P0_PWM3")
	)
	(segment
		(start 377.463558 -138.8237)
		(end 377.463558 -144.395952)
		(width 0.1524)
		(layer "In6.Cu")
		(net "PVDDCR_CPU0_P0_PWM3")
	)
	(segment
		(start 382.398778 -177.530252)
		(end 381.525018 -178.404012)
		(width 0.1524)
		(layer "In6.Cu")
		(net "PVDDCR_CPU0_P0_PWM3")
	)
	(segment
		(start 381.525018 -178.404012)
		(end 381.153162 -178.404012)
		(width 0.1524)
		(layer "In6.Cu")
		(net "PVDDCR_CPU0_P0_PWM3")
	)
	(segment
		(start 376.091958 -157.603952)
		(end 382.398778 -163.910772)
		(width 0.1524)
		(layer "In6.Cu")
		(net "PVDDCR_CPU0_P0_PWM3")
	)
	(segment
		(start 377.463558 -144.395952)
		(end 374.52046 -147.33905)
		(width 0.1524)
		(layer "In6.Cu")
		(net "PVDDCR_CPU0_P0_PWM3")
	)
	(segment
		(start 376.091958 -151.932132)
		(end 376.091958 -157.603952)
		(width 0.1524)
		(layer "In6.Cu")
		(net "PVDDCR_CPU0_P0_PWM3")
	)
	(segment
		(start 374.52046 -147.33905)
		(end 374.52046 -150.360634)
		(width 0.1524)
		(layer "In6.Cu")
		(net "PVDDCR_CPU0_P0_PWM3")
	)
	(segment
		(start 382.398778 -163.910772)
		(end 382.398778 -177.530252)
		(width 0.1524)
		(layer "In6.Cu")
		(net "PVDDCR_CPU0_P0_PWM3")
	)
	(segment
		(start 372.415054 -178.739292)
		(end 372.415054 -179.843938)
		(width 0.1778)
		(layer "F.Cu")
		(net "PVDDCR_CPU0_P0_PWM2")
	)
	(segment
		(start 372.750334 -178.404012)
		(end 372.415054 -178.739292)
		(width 0.1778)
		(layer "F.Cu")
		(net "PVDDCR_CPU0_P0_PWM2")
	)
	(via
		(at 372.750334 -178.404012)
		(size 0.508)
		(drill 0.254)
		(layers "F.Cu" "B.Cu")
		(net "PVDDCR_CPU0_P0_PWM2")
	)
	(via
		(at 376.239278 -138.424158)
		(size 0.508)
		(drill 0.254)
		(layers "F.Cu" "B.Cu")
		(net "PVDDCR_CPU0_P0_PWM2")
	)
	(segment
		(start 376.59818 -138.78306)
		(end 376.59818 -139.486132)
		(width 0.1524)
		(layer "B.Cu")
		(net "PVDDCR_CPU0_P0_PWM2")
	)
	(segment
		(start 376.239278 -138.424158)
		(end 376.59818 -138.78306)
		(width 0.1524)
		(layer "B.Cu")
		(net "PVDDCR_CPU0_P0_PWM2")
	)
	(segment
		(start 376.239278 -138.424158)
		(end 376.239278 -139.313412)
		(width 0.1524)
		(layer "In6.Cu")
		(net "PVDDCR_CPU0_P0_PWM2")
	)
	(segment
		(start 375.157238 -140.395452)
		(end 375.157238 -144.390872)
		(width 0.1524)
		(layer "In6.Cu")
		(net "PVDDCR_CPU0_P0_PWM2")
	)
	(segment
		(start 373.678958 -145.869152)
		(end 373.678958 -151.507952)
		(width 0.1524)
		(layer "In6.Cu")
		(net "PVDDCR_CPU0_P0_PWM2")
	)
	(segment
		(start 372.950994 -178.203352)
		(end 372.750334 -178.404012)
		(width 0.1524)
		(layer "In6.Cu")
		(net "PVDDCR_CPU0_P0_PWM2")
	)
	(segment
		(start 373.094758 -178.203352)
		(end 372.950994 -178.203352)
		(width 0.1524)
		(layer "In6.Cu")
		(net "PVDDCR_CPU0_P0_PWM2")
	)
	(segment
		(start 376.239278 -139.313412)
		(end 375.157238 -140.395452)
		(width 0.1524)
		(layer "In6.Cu")
		(net "PVDDCR_CPU0_P0_PWM2")
	)
	(segment
		(start 373.683276 -177.614834)
		(end 373.094758 -178.203352)
		(width 0.1524)
		(layer "In6.Cu")
		(net "PVDDCR_CPU0_P0_PWM2")
	)
	(segment
		(start 374.771158 -152.600152)
		(end 374.771158 -176.383188)
		(width 0.1524)
		(layer "In6.Cu")
		(net "PVDDCR_CPU0_P0_PWM2")
	)
	(segment
		(start 375.157238 -144.390872)
		(end 373.678958 -145.869152)
		(width 0.1524)
		(layer "In6.Cu")
		(net "PVDDCR_CPU0_P0_PWM2")
	)
	(segment
		(start 374.771158 -176.383188)
		(end 373.683276 -177.47107)
		(width 0.1524)
		(layer "In6.Cu")
		(net "PVDDCR_CPU0_P0_PWM2")
	)
	(segment
		(start 373.678958 -151.507952)
		(end 374.771158 -152.600152)
		(width 0.1524)
		(layer "In6.Cu")
		(net "PVDDCR_CPU0_P0_PWM2")
	)
	(segment
		(start 373.683276 -177.47107)
		(end 373.683276 -177.614834)
		(width 0.1524)
		(layer "In6.Cu")
		(net "PVDDCR_CPU0_P0_PWM2")
	)
	(segment
		(start 364.389162 -173.431454)
		(end 364.053882 -173.766734)
		(width 0.1778)
		(layer "F.Cu")
		(net "PVDDCR_CPU0_P0_PWM1")
	)
	(segment
		(start 364.053882 -173.766734)
		(end 364.053882 -174.87138)
		(width 0.1778)
		(layer "F.Cu")
		(net "PVDDCR_CPU0_P0_PWM1")
	)
	(via
		(at 375.477278 -138.170158)
		(size 0.508)
		(drill 0.254)
		(layers "F.Cu" "B.Cu")
		(net "PVDDCR_CPU0_P0_PWM1")
	)
	(via
		(at 364.389162 -173.431454)
		(size 0.508)
		(drill 0.254)
		(layers "F.Cu" "B.Cu")
		(net "PVDDCR_CPU0_P0_PWM1")
	)
	(segment
		(start 375.477278 -138.170158)
		(end 375.477278 -138.363452)
		(width 0.1524)
		(layer "B.Cu")
		(net "PVDDCR_CPU0_P0_PWM1")
	)
	(segment
		(start 376.198384 -139.084558)
		(end 376.198384 -139.486132)
		(width 0.1524)
		(layer "B.Cu")
		(net "PVDDCR_CPU0_P0_PWM1")
	)
	(segment
		(start 375.477278 -138.363452)
		(end 376.198384 -139.084558)
		(width 0.1524)
		(layer "B.Cu")
		(net "PVDDCR_CPU0_P0_PWM1")
	)
	(segment
		(start 363.079538 -172.12183)
		(end 364.389162 -173.431454)
		(width 0.1524)
		(layer "In6.Cu")
		(net "PVDDCR_CPU0_P0_PWM1")
	)
	(segment
		(start 364.23346 -143.309594)
		(end 364.23346 -154.487118)
		(width 0.1524)
		(layer "In6.Cu")
		(net "PVDDCR_CPU0_P0_PWM1")
	)
	(segment
		(start 363.079538 -155.64104)
		(end 363.079538 -172.12183)
		(width 0.1524)
		(layer "In6.Cu")
		(net "PVDDCR_CPU0_P0_PWM1")
	)
	(segment
		(start 369.728242 -137.814812)
		(end 364.23346 -143.309594)
		(width 0.1524)
		(layer "In6.Cu")
		(net "PVDDCR_CPU0_P0_PWM1")
	)
	(segment
		(start 375.477278 -138.170158)
		(end 375.121932 -137.814812)
		(width 0.1524)
		(layer "In6.Cu")
		(net "PVDDCR_CPU0_P0_PWM1")
	)
	(segment
		(start 375.121932 -137.814812)
		(end 369.728242 -137.814812)
		(width 0.1524)
		(layer "In6.Cu")
		(net "PVDDCR_CPU0_P0_PWM1")
	)
	(segment
		(start 364.23346 -154.487118)
		(end 363.079538 -155.64104)
		(width 0.1524)
		(layer "In6.Cu")
		(net "PVDDCR_CPU0_P0_PWM1")
	)
	(segment
		(start 392.871706 -182.345584)
		(end 392.34491 -181.818788)
		(width 0.2286)
		(layer "F.Cu")
		(net "PVDDCR_CPU0_P0_PVCC")
	)
	(segment
		(start 367.776506 -177.373026)
		(end 367.24971 -176.84623)
		(width 0.2286)
		(layer "F.Cu")
		(net "PVDDCR_CPU0_P0_PVCC")
	)
	(segment
		(start 367.996978 -176.761902)
		(end 367.996978 -177.373026)
		(width 0.381)
		(layer "F.Cu")
		(net "PVDDCR_CPU0_P0_PVCC")
	)
	(segment
		(start 401.286726 -176.772824)
		(end 401.507198 -176.772824)
		(width 0.2286)
		(layer "F.Cu")
		(net "PVDDCR_CPU0_P0_PVCC")
	)
	(segment
		(start 375.610882 -181.818788)
		(end 375.075196 -181.818788)
		(width 0.2286)
		(layer "F.Cu")
		(net "PVDDCR_CPU0_P0_PVCC")
	)
	(segment
		(start 392.34491 -181.818788)
		(end 391.809224 -181.818788)
		(width 0.2286)
		(layer "F.Cu")
		(net "PVDDCR_CPU0_P0_PVCC")
	)
	(segment
		(start 376.35815 -181.73446)
		(end 376.35815 -182.345584)
		(width 0.381)
		(layer "F.Cu")
		(net "PVDDCR_CPU0_P0_PVCC")
	)
	(segment
		(start 409.830778 -167.584374)
		(end 409.830778 -168.195498)
		(width 0.381)
		(layer "F.Cu")
		(net "PVDDCR_CPU0_P0_PVCC")
	)
	(segment
		(start 409.08351 -167.668702)
		(end 408.547824 -167.668702)
		(width 0.2286)
		(layer "F.Cu")
		(net "PVDDCR_CPU0_P0_PVCC")
	)
	(segment
		(start 350.66859 -160.21939)
		(end 350.66859 -160.21685)
		(width 0.2286)
		(layer "F.Cu")
		(net "PVDDCR_CPU0_P0_PVCC")
	)
	(segment
		(start 376.137678 -182.345584)
		(end 375.610882 -181.818788)
		(width 0.2286)
		(layer "F.Cu")
		(net "PVDDCR_CPU0_P0_PVCC")
	)
	(segment
		(start 359.716578 -168.486582)
		(end 359.716578 -169.097706)
		(width 0.381)
		(layer "F.Cu")
		(net "PVDDCR_CPU0_P0_PVCC")
	)
	(segment
		(start 401.507198 -176.772824)
		(end 401.507198 -176.1617)
		(width 0.381)
		(layer "F.Cu")
		(net "PVDDCR_CPU0_P0_PVCC")
	)
	(segment
		(start 384.056382 -181.86146)
		(end 383.478024 -181.86146)
		(width 0.2286)
		(layer "F.Cu")
		(net "PVDDCR_CPU0_P0_PVCC")
	)
	(segment
		(start 359.496106 -169.097706)
		(end 358.96931 -168.57091)
		(width 0.2286)
		(layer "F.Cu")
		(net "PVDDCR_CPU0_P0_PVCC")
	)
	(segment
		(start 358.96931 -168.57091)
		(end 358.433624 -168.57091)
		(width 0.2286)
		(layer "F.Cu")
		(net "PVDDCR_CPU0_P0_PVCC")
	)
	(segment
		(start 409.610306 -168.195498)
		(end 409.08351 -167.668702)
		(width 0.2286)
		(layer "F.Cu")
		(net "PVDDCR_CPU0_P0_PVCC")
	)
	(segment
		(start 393.092178 -182.345584)
		(end 392.871706 -182.345584)
		(width 0.2286)
		(layer "F.Cu")
		(net "PVDDCR_CPU0_P0_PVCC")
	)
	(segment
		(start 367.996978 -177.373026)
		(end 367.776506 -177.373026)
		(width 0.2286)
		(layer "F.Cu")
		(net "PVDDCR_CPU0_P0_PVCC")
	)
	(segment
		(start 351.190306 -160.741106)
		(end 350.66859 -160.21939)
		(width 0.2286)
		(layer "F.Cu")
		(net "PVDDCR_CPU0_P0_PVCC")
	)
	(segment
		(start 417.859464 -163.369498)
		(end 417.332668 -162.842702)
		(width 0.2286)
		(layer "F.Cu")
		(net "PVDDCR_CPU0_P0_PVCC")
	)
	(segment
		(start 359.716578 -169.097706)
		(end 359.496106 -169.097706)
		(width 0.2286)
		(layer "F.Cu")
		(net "PVDDCR_CPU0_P0_PVCC")
	)
	(segment
		(start 376.35815 -182.345584)
		(end 376.137678 -182.345584)
		(width 0.2286)
		(layer "F.Cu")
		(net "PVDDCR_CPU0_P0_PVCC")
	)
	(segment
		(start 400.224244 -176.246028)
		(end 400.75993 -176.246028)
		(width 0.2286)
		(layer "F.Cu")
		(net "PVDDCR_CPU0_P0_PVCC")
	)
	(segment
		(start 384.760978 -182.345584)
		(end 384.540506 -182.345584)
		(width 0.2286)
		(layer "F.Cu")
		(net "PVDDCR_CPU0_P0_PVCC")
	)
	(segment
		(start 417.332668 -162.842702)
		(end 416.929824 -162.842702)
		(width 0.2286)
		(layer "F.Cu")
		(net "PVDDCR_CPU0_P0_PVCC")
	)
	(segment
		(start 400.75993 -176.246028)
		(end 401.286726 -176.772824)
		(width 0.2286)
		(layer "F.Cu")
		(net "PVDDCR_CPU0_P0_PVCC")
	)
	(segment
		(start 350.66859 -160.21685)
		(end 350.66605 -160.21431)
		(width 0.2286)
		(layer "F.Cu")
		(net "PVDDCR_CPU0_P0_PVCC")
	)
	(segment
		(start 350.66605 -160.21431)
		(end 350.127824 -160.21431)
		(width 0.2286)
		(layer "F.Cu")
		(net "PVDDCR_CPU0_P0_PVCC")
	)
	(segment
		(start 418.212778 -163.369498)
		(end 417.859464 -163.369498)
		(width 0.2286)
		(layer "F.Cu")
		(net "PVDDCR_CPU0_P0_PVCC")
	)
	(segment
		(start 384.540506 -182.345584)
		(end 384.056382 -181.86146)
		(width 0.2286)
		(layer "F.Cu")
		(net "PVDDCR_CPU0_P0_PVCC")
	)
	(segment
		(start 393.092178 -181.73446)
		(end 393.092178 -182.345584)
		(width 0.381)
		(layer "F.Cu")
		(net "PVDDCR_CPU0_P0_PVCC")
	)
	(segment
		(start 351.410778 -160.129982)
		(end 351.410778 -160.741106)
		(width 0.381)
		(layer "F.Cu")
		(net "PVDDCR_CPU0_P0_PVCC")
	)
	(segment
		(start 351.410778 -160.741106)
		(end 351.190306 -160.741106)
		(width 0.2286)
		(layer "F.Cu")
		(net "PVDDCR_CPU0_P0_PVCC")
	)
	(segment
		(start 367.24971 -176.84623)
		(end 366.714024 -176.84623)
		(width 0.2286)
		(layer "F.Cu")
		(net "PVDDCR_CPU0_P0_PVCC")
	)
	(segment
		(start 384.760978 -181.73446)
		(end 384.760978 -182.345584)
		(width 0.381)
		(layer "F.Cu")
		(net "PVDDCR_CPU0_P0_PVCC")
	)
	(segment
		(start 409.830778 -168.195498)
		(end 409.610306 -168.195498)
		(width 0.2286)
		(layer "F.Cu")
		(net "PVDDCR_CPU0_P0_PVCC")
	)
	(via
		(at 384.760978 -181.73446)
		(size 0.508)
		(drill 0.254)
		(layers "F.Cu" "B.Cu")
		(net "PVDDCR_CPU0_P0_PVCC")
	)
	(via
		(at 393.092178 -181.73446)
		(size 0.508)
		(drill 0.254)
		(layers "F.Cu" "B.Cu")
		(net "PVDDCR_CPU0_P0_PVCC")
	)
	(via
		(at 401.507198 -176.1617)
		(size 0.508)
		(drill 0.254)
		(layers "F.Cu" "B.Cu")
		(net "PVDDCR_CPU0_P0_PVCC")
	)
	(via
		(at 409.830778 -167.584374)
		(size 0.508)
		(drill 0.254)
		(layers "F.Cu" "B.Cu")
		(net "PVDDCR_CPU0_P0_PVCC")
	)
	(via
		(at 376.35815 -181.73446)
		(size 0.508)
		(drill 0.254)
		(layers "F.Cu" "B.Cu")
		(net "PVDDCR_CPU0_P0_PVCC")
	)
	(via
		(at 351.410778 -160.129982)
		(size 0.508)
		(drill 0.254)
		(layers "F.Cu" "B.Cu")
		(net "PVDDCR_CPU0_P0_PVCC")
	)
	(via
		(at 419.292278 -159.237172)
		(size 0.762)
		(drill 0.381)
		(layers "F.Cu" "B.Cu")
		(net "PVDDCR_CPU0_P0_PVCC")
	)
	(via
		(at 367.996978 -176.761902)
		(size 0.508)
		(drill 0.254)
		(layers "F.Cu" "B.Cu")
		(net "PVDDCR_CPU0_P0_PVCC")
	)
	(via
		(at 359.716578 -168.486582)
		(size 0.508)
		(drill 0.254)
		(layers "F.Cu" "B.Cu")
		(net "PVDDCR_CPU0_P0_PVCC")
	)
	(via
		(at 418.212778 -162.758374)
		(size 0.508)
		(drill 0.254)
		(layers "F.Cu" "B.Cu")
		(net "PVDDCR_CPU0_P0_PVCC")
	)
	(segment
		(start 367.625122 -177.112168)
		(end 367.975388 -176.761902)
		(width 0.381)
		(layer "B.Cu")
		(net "PVDDCR_CPU0_P0_PVCC")
	)
	(segment
		(start 358.34447 -168.836848)
		(end 359.344722 -168.836848)
		(width 0.381)
		(layer "B.Cu")
		(net "PVDDCR_CPU0_P0_PVCC")
	)
	(segment
		(start 401.135342 -176.511966)
		(end 401.485608 -176.1617)
		(width 0.381)
		(layer "B.Cu")
		(net "PVDDCR_CPU0_P0_PVCC")
	)
	(segment
		(start 392.720322 -182.084726)
		(end 393.070588 -181.73446)
		(width 0.381)
		(layer "B.Cu")
		(net "PVDDCR_CPU0_P0_PVCC")
	)
	(segment
		(start 359.344722 -168.836848)
		(end 359.694988 -168.486582)
		(width 0.381)
		(layer "B.Cu")
		(net "PVDDCR_CPU0_P0_PVCC")
	)
	(segment
		(start 366.62487 -177.112168)
		(end 367.625122 -177.112168)
		(width 0.381)
		(layer "B.Cu")
		(net "PVDDCR_CPU0_P0_PVCC")
	)
	(segment
		(start 408.45867 -167.93464)
		(end 409.458922 -167.93464)
		(width 0.381)
		(layer "B.Cu")
		(net "PVDDCR_CPU0_P0_PVCC")
	)
	(segment
		(start 383.38887 -182.084726)
		(end 384.389122 -182.084726)
		(width 0.381)
		(layer "B.Cu")
		(net "PVDDCR_CPU0_P0_PVCC")
	)
	(segment
		(start 367.975388 -176.761902)
		(end 367.996978 -176.761902)
		(width 0.381)
		(layer "B.Cu")
		(net "PVDDCR_CPU0_P0_PVCC")
	)
	(segment
		(start 416.84067 -163.10864)
		(end 417.840922 -163.10864)
		(width 0.381)
		(layer "B.Cu")
		(net "PVDDCR_CPU0_P0_PVCC")
	)
	(segment
		(start 417.840922 -163.10864)
		(end 418.191188 -162.758374)
		(width 0.381)
		(layer "B.Cu")
		(net "PVDDCR_CPU0_P0_PVCC")
	)
	(segment
		(start 418.191188 -162.758374)
		(end 418.212778 -162.758374)
		(width 0.381)
		(layer "B.Cu")
		(net "PVDDCR_CPU0_P0_PVCC")
	)
	(segment
		(start 351.389188 -160.129982)
		(end 351.410778 -160.129982)
		(width 0.381)
		(layer "B.Cu")
		(net "PVDDCR_CPU0_P0_PVCC")
	)
	(segment
		(start 374.986042 -182.084726)
		(end 375.986294 -182.084726)
		(width 0.381)
		(layer "B.Cu")
		(net "PVDDCR_CPU0_P0_PVCC")
	)
	(segment
		(start 384.389122 -182.084726)
		(end 384.739388 -181.73446)
		(width 0.381)
		(layer "B.Cu")
		(net "PVDDCR_CPU0_P0_PVCC")
	)
	(segment
		(start 350.03867 -160.480248)
		(end 351.038922 -160.480248)
		(width 0.381)
		(layer "B.Cu")
		(net "PVDDCR_CPU0_P0_PVCC")
	)
	(segment
		(start 409.458922 -167.93464)
		(end 409.809188 -167.584374)
		(width 0.381)
		(layer "B.Cu")
		(net "PVDDCR_CPU0_P0_PVCC")
	)
	(segment
		(start 401.485608 -176.1617)
		(end 401.507198 -176.1617)
		(width 0.381)
		(layer "B.Cu")
		(net "PVDDCR_CPU0_P0_PVCC")
	)
	(segment
		(start 391.72007 -182.084726)
		(end 392.720322 -182.084726)
		(width 0.381)
		(layer "B.Cu")
		(net "PVDDCR_CPU0_P0_PVCC")
	)
	(segment
		(start 393.070588 -181.73446)
		(end 393.092178 -181.73446)
		(width 0.381)
		(layer "B.Cu")
		(net "PVDDCR_CPU0_P0_PVCC")
	)
	(segment
		(start 409.809188 -167.584374)
		(end 409.830778 -167.584374)
		(width 0.381)
		(layer "B.Cu")
		(net "PVDDCR_CPU0_P0_PVCC")
	)
	(segment
		(start 351.038922 -160.480248)
		(end 351.389188 -160.129982)
		(width 0.381)
		(layer "B.Cu")
		(net "PVDDCR_CPU0_P0_PVCC")
	)
	(segment
		(start 359.694988 -168.486582)
		(end 359.716578 -168.486582)
		(width 0.381)
		(layer "B.Cu")
		(net "PVDDCR_CPU0_P0_PVCC")
	)
	(segment
		(start 376.33656 -181.73446)
		(end 376.35815 -181.73446)
		(width 0.381)
		(layer "B.Cu")
		(net "PVDDCR_CPU0_P0_PVCC")
	)
	(segment
		(start 375.986294 -182.084726)
		(end 376.33656 -181.73446)
		(width 0.381)
		(layer "B.Cu")
		(net "PVDDCR_CPU0_P0_PVCC")
	)
	(segment
		(start 400.13509 -176.511966)
		(end 401.135342 -176.511966)
		(width 0.381)
		(layer "B.Cu")
		(net "PVDDCR_CPU0_P0_PVCC")
	)
	(segment
		(start 384.739388 -181.73446)
		(end 384.760978 -181.73446)
		(width 0.381)
		(layer "B.Cu")
		(net "PVDDCR_CPU0_P0_PVCC")
	)
	(segment
		(start 394.936218 -186.105292)
		(end 393.73429 -187.30722)
		(width 0.508)
		(layer "In6.Cu")
		(net "PVDDCR_CPU0_P0_PVCC")
	)
	(segment
		(start 360.785918 -182.65267)
		(end 358.639618 -180.50637)
		(width 0.508)
		(layer "In6.Cu")
		(net "PVDDCR_CPU0_P0_PVCC")
	)
	(segment
		(start 385.053078 -187.44057)
		(end 385.053078 -182.02656)
		(width 0.508)
		(layer "In6.Cu")
		(net "PVDDCR_CPU0_P0_PVCC")
	)
	(segment
		(start 415.670238 -172.69333)
		(end 418.568378 -169.79519)
		(width 0.508)
		(layer "In6.Cu")
		(net "PVDDCR_CPU0_P0_PVCC")
	)
	(segment
		(start 401.055078 -186.105292)
		(end 394.936218 -186.105292)
		(width 0.508)
		(layer "In6.Cu")
		(net "PVDDCR_CPU0_P0_PVCC")
	)
	(segment
		(start 367.996978 -182.95239)
		(end 367.996978 -186.51093)
		(width 0.508)
		(layer "In6.Cu")
		(net "PVDDCR_CPU0_P0_PVCC")
	)
	(segment
		(start 369.426998 -187.94095)
		(end 376.406156 -187.94095)
		(width 0.508)
		(layer "In6.Cu")
		(net "PVDDCR_CPU0_P0_PVCC")
	)
	(segment
		(start 349.620078 -166.08171)
		(end 349.620078 -171.78909)
		(width 0.508)
		(layer "In6.Cu")
		(net "PVDDCR_CPU0_P0_PVCC")
	)
	(segment
		(start 418.568378 -163.113974)
		(end 418.212778 -162.758374)
		(width 0.508)
		(layer "In6.Cu")
		(net "PVDDCR_CPU0_P0_PVCC")
	)
	(segment
		(start 409.830778 -167.584374)
		(end 410.351478 -168.105074)
		(width 0.508)
		(layer "In6.Cu")
		(net "PVDDCR_CPU0_P0_PVCC")
	)
	(segment
		(start 407.062178 -175.46193)
		(end 410.351478 -172.17263)
		(width 0.508)
		(layer "In6.Cu")
		(net "PVDDCR_CPU0_P0_PVCC")
	)
	(segment
		(start 349.620078 -171.78909)
		(end 352.231198 -174.40021)
		(width 0.508)
		(layer "In6.Cu")
		(net "PVDDCR_CPU0_P0_PVCC")
	)
	(segment
		(start 351.931478 -160.650682)
		(end 351.931478 -163.77031)
		(width 0.508)
		(layer "In6.Cu")
		(net "PVDDCR_CPU0_P0_PVCC")
	)
	(segment
		(start 367.697258 -182.65267)
		(end 360.785918 -182.65267)
		(width 0.508)
		(layer "In6.Cu")
		(net "PVDDCR_CPU0_P0_PVCC")
	)
	(segment
		(start 376.874278 -187.472828)
		(end 376.874278 -182.250588)
		(width 0.508)
		(layer "In6.Cu")
		(net "PVDDCR_CPU0_P0_PVCC")
	)
	(segment
		(start 351.410778 -160.129982)
		(end 351.931478 -160.650682)
		(width 0.508)
		(layer "In6.Cu")
		(net "PVDDCR_CPU0_P0_PVCC")
	)
	(segment
		(start 410.351478 -172.17263)
		(end 410.872178 -172.69333)
		(width 0.508)
		(layer "In6.Cu")
		(net "PVDDCR_CPU0_P0_PVCC")
	)
	(segment
		(start 376.406156 -187.94095)
		(end 376.874278 -187.472828)
		(width 0.508)
		(layer "In6.Cu")
		(net "PVDDCR_CPU0_P0_PVCC")
	)
	(segment
		(start 368.126518 -176.891442)
		(end 368.126518 -178.943508)
		(width 0.508)
		(layer "In6.Cu")
		(net "PVDDCR_CPU0_P0_PVCC")
	)
	(segment
		(start 390.09828 -187.94857)
		(end 390.73963 -187.30722)
		(width 0.508)
		(layer "In6.Cu")
		(net "PVDDCR_CPU0_P0_PVCC")
	)
	(segment
		(start 384.552698 -187.94095)
		(end 377.3424 -187.94095)
		(width 0.508)
		(layer "In6.Cu")
		(net "PVDDCR_CPU0_P0_PVCC")
	)
	(segment
		(start 367.697258 -179.372768)
		(end 367.697258 -182.65267)
		(width 0.508)
		(layer "In6.Cu")
		(net "PVDDCR_CPU0_P0_PVCC")
	)
	(segment
		(start 393.73429 -187.30722)
		(end 393.333478 -187.30722)
		(width 0.508)
		(layer "In6.Cu")
		(net "PVDDCR_CPU0_P0_PVCC")
	)
	(segment
		(start 390.73963 -187.30722)
		(end 393.333478 -187.30722)
		(width 0.508)
		(layer "In6.Cu")
		(net "PVDDCR_CPU0_P0_PVCC")
	)
	(segment
		(start 393.333478 -181.97576)
		(end 393.092178 -181.73446)
		(width 0.508)
		(layer "In6.Cu")
		(net "PVDDCR_CPU0_P0_PVCC")
	)
	(segment
		(start 359.716578 -168.486582)
		(end 360.364278 -169.134282)
		(width 0.508)
		(layer "In6.Cu")
		(net "PVDDCR_CPU0_P0_PVCC")
	)
	(segment
		(start 401.507198 -176.1617)
		(end 402.013928 -176.1617)
		(width 0.508)
		(layer "In6.Cu")
		(net "PVDDCR_CPU0_P0_PVCC")
	)
	(segment
		(start 360.364278 -171.19092)
		(end 358.639618 -172.91558)
		(width 0.508)
		(layer "In6.Cu")
		(net "PVDDCR_CPU0_P0_PVCC")
	)
	(segment
		(start 385.053078 -187.44057)
		(end 384.552698 -187.94095)
		(width 0.508)
		(layer "In6.Cu")
		(net "PVDDCR_CPU0_P0_PVCC")
	)
	(segment
		(start 401.766278 -185.394092)
		(end 401.055078 -186.105292)
		(width 0.508)
		(layer "In6.Cu")
		(net "PVDDCR_CPU0_P0_PVCC")
	)
	(segment
		(start 402.713698 -175.46193)
		(end 407.062178 -175.46193)
		(width 0.508)
		(layer "In6.Cu")
		(net "PVDDCR_CPU0_P0_PVCC")
	)
	(segment
		(start 358.639618 -180.50637)
		(end 358.639618 -174.40021)
		(width 0.508)
		(layer "In6.Cu")
		(net "PVDDCR_CPU0_P0_PVCC")
	)
	(segment
		(start 410.351478 -168.105074)
		(end 410.351478 -172.17263)
		(width 0.508)
		(layer "In6.Cu")
		(net "PVDDCR_CPU0_P0_PVCC")
	)
	(segment
		(start 377.3424 -187.94095)
		(end 376.874278 -187.472828)
		(width 0.508)
		(layer "In6.Cu")
		(net "PVDDCR_CPU0_P0_PVCC")
	)
	(segment
		(start 393.333478 -187.30722)
		(end 393.333478 -181.97576)
		(width 0.508)
		(layer "In6.Cu")
		(net "PVDDCR_CPU0_P0_PVCC")
	)
	(segment
		(start 367.996978 -176.761902)
		(end 368.126518 -176.891442)
		(width 0.508)
		(layer "In6.Cu")
		(net "PVDDCR_CPU0_P0_PVCC")
	)
	(segment
		(start 358.639618 -172.91558)
		(end 358.639618 -174.40021)
		(width 0.508)
		(layer "In6.Cu")
		(net "PVDDCR_CPU0_P0_PVCC")
	)
	(segment
		(start 402.013928 -176.1617)
		(end 402.713698 -175.46193)
		(width 0.508)
		(layer "In6.Cu")
		(net "PVDDCR_CPU0_P0_PVCC")
	)
	(segment
		(start 351.931478 -163.77031)
		(end 349.620078 -166.08171)
		(width 0.508)
		(layer "In6.Cu")
		(net "PVDDCR_CPU0_P0_PVCC")
	)
	(segment
		(start 367.996978 -186.51093)
		(end 369.426998 -187.94095)
		(width 0.508)
		(layer "In6.Cu")
		(net "PVDDCR_CPU0_P0_PVCC")
	)
	(segment
		(start 401.766278 -176.42078)
		(end 401.766278 -185.394092)
		(width 0.508)
		(layer "In6.Cu")
		(net "PVDDCR_CPU0_P0_PVCC")
	)
	(segment
		(start 385.053078 -187.44057)
		(end 385.561078 -187.94857)
		(width 0.508)
		(layer "In6.Cu")
		(net "PVDDCR_CPU0_P0_PVCC")
	)
	(segment
		(start 410.872178 -172.69333)
		(end 415.670238 -172.69333)
		(width 0.508)
		(layer "In6.Cu")
		(net "PVDDCR_CPU0_P0_PVCC")
	)
	(segment
		(start 418.568378 -169.79519)
		(end 418.568378 -163.113974)
		(width 0.508)
		(layer "In6.Cu")
		(net "PVDDCR_CPU0_P0_PVCC")
	)
	(segment
		(start 367.697258 -182.65267)
		(end 367.996978 -182.95239)
		(width 0.508)
		(layer "In6.Cu")
		(net "PVDDCR_CPU0_P0_PVCC")
	)
	(segment
		(start 376.874278 -182.250588)
		(end 376.35815 -181.73446)
		(width 0.508)
		(layer "In6.Cu")
		(net "PVDDCR_CPU0_P0_PVCC")
	)
	(segment
		(start 368.126518 -178.943508)
		(end 367.697258 -179.372768)
		(width 0.508)
		(layer "In6.Cu")
		(net "PVDDCR_CPU0_P0_PVCC")
	)
	(segment
		(start 401.507198 -176.1617)
		(end 401.766278 -176.42078)
		(width 0.508)
		(layer "In6.Cu")
		(net "PVDDCR_CPU0_P0_PVCC")
	)
	(segment
		(start 352.231198 -174.40021)
		(end 358.639618 -174.40021)
		(width 0.508)
		(layer "In6.Cu")
		(net "PVDDCR_CPU0_P0_PVCC")
	)
	(segment
		(start 360.364278 -169.134282)
		(end 360.364278 -171.19092)
		(width 0.508)
		(layer "In6.Cu")
		(net "PVDDCR_CPU0_P0_PVCC")
	)
	(segment
		(start 385.561078 -187.94857)
		(end 390.09828 -187.94857)
		(width 0.508)
		(layer "In6.Cu")
		(net "PVDDCR_CPU0_P0_PVCC")
	)
	(segment
		(start 385.053078 -182.02656)
		(end 384.760978 -181.73446)
		(width 0.508)
		(layer "In6.Cu")
		(net "PVDDCR_CPU0_P0_PVCC")
	)
	(via
		(at 375.449338 -139.122912)
		(size 0.762)
		(drill 0.254)
		(layers "F.Cu" "B.Cu")
		(net "PVDDCR_CPU0_P0_PMSDA_R")
	)
	(segment
		(start 374.715278 -138.388852)
		(end 374.715278 -138.189208)
		(width 0.10668)
		(layer "B.Cu")
		(net "PVDDCR_CPU0_P0_PMSDA_R")
	)
	(segment
		(start 375.449338 -139.122912)
		(end 374.715278 -138.388852)
		(width 0.10668)
		(layer "B.Cu")
		(net "PVDDCR_CPU0_P0_PMSDA_R")
	)
	(segment
		(start 375.449338 -139.122912)
		(end 375.449338 -140.08735)
		(width 0.10668)
		(layer "B.Cu")
		(net "PVDDCR_CPU0_P0_PMSDA_R")
	)
	(segment
		(start 375.449338 -140.08735)
		(end 375.523252 -140.161264)
		(width 0.10668)
		(layer "B.Cu")
		(net "PVDDCR_CPU0_P0_PMSDA_R")
	)
	(via
		(at 374.052338 -137.027412)
		(size 0.762)
		(drill 0.254)
		(layers "F.Cu" "B.Cu")
		(net "PVDDCR_CPU0_P0_PMSCL_R")
	)
	(segment
		(start 374.9548 -139.21486)
		(end 374.052338 -138.312398)
		(width 0.10668)
		(layer "B.Cu")
		(net "PVDDCR_CPU0_P0_PMSCL_R")
	)
	(segment
		(start 375.523252 -140.56106)
		(end 375.175018 -140.56106)
		(width 0.10668)
		(layer "B.Cu")
		(net "PVDDCR_CPU0_P0_PMSCL_R")
	)
	(segment
		(start 374.052338 -137.027412)
		(end 373.996458 -137.027412)
		(width 0.10668)
		(layer "B.Cu")
		(net "PVDDCR_CPU0_P0_PMSCL_R")
	)
	(segment
		(start 373.994172 -137.029698)
		(end 373.810276 -137.029698)
		(width 0.10668)
		(layer "B.Cu")
		(net "PVDDCR_CPU0_P0_PMSCL_R")
	)
	(segment
		(start 373.996458 -137.027412)
		(end 373.994172 -137.029698)
		(width 0.10668)
		(layer "B.Cu")
		(net "PVDDCR_CPU0_P0_PMSCL_R")
	)
	(segment
		(start 373.431816 -137.408158)
		(end 373.337328 -137.408158)
		(width 0.10668)
		(layer "B.Cu")
		(net "PVDDCR_CPU0_P0_PMSCL_R")
	)
	(segment
		(start 374.9548 -140.340842)
		(end 374.9548 -139.21486)
		(width 0.10668)
		(layer "B.Cu")
		(net "PVDDCR_CPU0_P0_PMSCL_R")
	)
	(segment
		(start 373.810276 -137.029698)
		(end 373.431816 -137.408158)
		(width 0.10668)
		(layer "B.Cu")
		(net "PVDDCR_CPU0_P0_PMSCL_R")
	)
	(segment
		(start 375.175018 -140.56106)
		(end 374.9548 -140.340842)
		(width 0.10668)
		(layer "B.Cu")
		(net "PVDDCR_CPU0_P0_PMSCL_R")
	)
	(segment
		(start 374.052338 -138.312398)
		(end 374.052338 -137.027412)
		(width 0.10668)
		(layer "B.Cu")
		(net "PVDDCR_CPU0_P0_PMSCL_R")
	)
	(via
		(at 374.245632 -139.178792)
		(size 0.508)
		(drill 0.254)
		(layers "F.Cu" "B.Cu")
		(net "PVDDCR_CPU0_P0_PMALERT_R")
	)
	(segment
		(start 375.523252 -140.96111)
		(end 375.240804 -140.96111)
		(width 0.10668)
		(layer "B.Cu")
		(net "PVDDCR_CPU0_P0_PMALERT_R")
	)
	(segment
		(start 374.69826 -139.636754)
		(end 374.245632 -139.184126)
		(width 0.10668)
		(layer "B.Cu")
		(net "PVDDCR_CPU0_P0_PMALERT_R")
	)
	(segment
		(start 374.69826 -140.418566)
		(end 374.69826 -139.636754)
		(width 0.10668)
		(layer "B.Cu")
		(net "PVDDCR_CPU0_P0_PMALERT_R")
	)
	(segment
		(start 375.240804 -140.96111)
		(end 374.69826 -140.418566)
		(width 0.10668)
		(layer "B.Cu")
		(net "PVDDCR_CPU0_P0_PMALERT_R")
	)
	(segment
		(start 373.490998 -138.424158)
		(end 373.337328 -138.424158)
		(width 0.10668)
		(layer "B.Cu")
		(net "PVDDCR_CPU0_P0_PMALERT_R")
	)
	(segment
		(start 374.245632 -139.184126)
		(end 374.245632 -139.178792)
		(width 0.10668)
		(layer "B.Cu")
		(net "PVDDCR_CPU0_P0_PMALERT_R")
	)
	(segment
		(start 374.245632 -139.178792)
		(end 373.490998 -138.424158)
		(width 0.10668)
		(layer "B.Cu")
		(net "PVDDCR_CPU0_P0_PMALERT_R")
	)
	(segment
		(start 195.98767 -104.895396)
		(end 197.363334 -104.895396)
		(width 0.10668)
		(layer "F.Cu")
		(net "PVDDCR_CPU0_P0_PMALERT")
	)
	(segment
		(start 194.312032 -107.862878)
		(end 195.634864 -106.540046)
		(width 0.10668)
		(layer "F.Cu")
		(net "PVDDCR_CPU0_P0_PMALERT")
	)
	(segment
		(start 197.363334 -104.895396)
		(end 197.52056 -105.052622)
		(width 0.10668)
		(layer "F.Cu")
		(net "PVDDCR_CPU0_P0_PMALERT")
	)
	(segment
		(start 197.52056 -105.052622)
		(end 197.52056 -105.119678)
		(width 0.10668)
		(layer "F.Cu")
		(net "PVDDCR_CPU0_P0_PMALERT")
	)
	(segment
		(start 195.634864 -106.540046)
		(end 195.634864 -105.248202)
		(width 0.10668)
		(layer "F.Cu")
		(net "PVDDCR_CPU0_P0_PMALERT")
	)
	(segment
		(start 193.922142 -108.252768)
		(end 194.312032 -107.862878)
		(width 0.10668)
		(layer "F.Cu")
		(net "PVDDCR_CPU0_P0_PMALERT")
	)
	(segment
		(start 197.898258 -105.497376)
		(end 197.923658 -105.497376)
		(width 0.10668)
		(layer "F.Cu")
		(net "PVDDCR_CPU0_P0_PMALERT")
	)
	(segment
		(start 197.52056 -105.119678)
		(end 197.898258 -105.497376)
		(width 0.10668)
		(layer "F.Cu")
		(net "PVDDCR_CPU0_P0_PMALERT")
	)
	(segment
		(start 195.634864 -105.248202)
		(end 195.98767 -104.895396)
		(width 0.10668)
		(layer "F.Cu")
		(net "PVDDCR_CPU0_P0_PMALERT")
	)
	(via
		(at 359.918 -116.931948)
		(size 0.508)
		(drill 0.254)
		(layers "F.Cu" "B.Cu")
		(net "PVDDCR_CPU0_P0_PMALERT")
	)
	(via
		(at 259.92328 -114.582448)
		(size 0.508)
		(drill 0.254)
		(layers "F.Cu" "B.Cu")
		(net "PVDDCR_CPU0_P0_PMALERT")
	)
	(via
		(at 194.312032 -107.862878)
		(size 0.4572)
		(drill 0.254)
		(layers "F.Cu" "B.Cu")
		(net "PVDDCR_CPU0_P0_PMALERT")
	)
	(segment
		(start 372.57482 -138.386566)
		(end 372.537228 -138.424158)
		(width 0.10668)
		(layer "B.Cu")
		(net "PVDDCR_CPU0_P0_PMALERT")
	)
	(segment
		(start 372.57482 -137.66165)
		(end 372.57482 -138.386566)
		(width 0.10668)
		(layer "B.Cu")
		(net "PVDDCR_CPU0_P0_PMALERT")
	)
	(segment
		(start 371.706648 -137.408158)
		(end 372.321328 -137.408158)
		(width 0.10668)
		(layer "B.Cu")
		(net "PVDDCR_CPU0_P0_PMALERT")
	)
	(segment
		(start 368.097816 -125.30836)
		(end 368.097816 -133.799326)
		(width 0.10668)
		(layer "B.Cu")
		(net "PVDDCR_CPU0_P0_PMALERT")
	)
	(segment
		(start 359.918 -116.931948)
		(end 359.918 -117.128544)
		(width 0.10668)
		(layer "B.Cu")
		(net "PVDDCR_CPU0_P0_PMALERT")
	)
	(segment
		(start 368.097816 -133.799326)
		(end 371.706648 -137.408158)
		(width 0.10668)
		(layer "B.Cu")
		(net "PVDDCR_CPU0_P0_PMALERT")
	)
	(segment
		(start 372.321328 -137.408158)
		(end 372.57482 -137.66165)
		(width 0.10668)
		(layer "B.Cu")
		(net "PVDDCR_CPU0_P0_PMALERT")
	)
	(segment
		(start 359.918 -117.128544)
		(end 368.097816 -125.30836)
		(width 0.10668)
		(layer "B.Cu")
		(net "PVDDCR_CPU0_P0_PMALERT")
	)
	(segment
		(start 206.437484 -109.002322)
		(end 212.626194 -109.002322)
		(width 0.11684)
		(layer "In2.Cu")
		(net "PVDDCR_CPU0_P0_PMALERT")
	)
	(segment
		(start 198.698104 -106.889296)
		(end 198.804022 -106.783378)
		(width 0.11684)
		(layer "In2.Cu")
		(net "PVDDCR_CPU0_P0_PMALERT")
	)
	(segment
		(start 194.312032 -107.862878)
		(end 195.49745 -106.67746)
		(width 0.11684)
		(layer "In2.Cu")
		(net "PVDDCR_CPU0_P0_PMALERT")
	)
	(segment
		(start 215.95715 -112.333278)
		(end 252.377702 -112.333278)
		(width 0.11684)
		(layer "In2.Cu")
		(net "PVDDCR_CPU0_P0_PMALERT")
	)
	(segment
		(start 198.804022 -106.783378)
		(end 199.218042 -106.783378)
		(width 0.11684)
		(layer "In2.Cu")
		(net "PVDDCR_CPU0_P0_PMALERT")
	)
	(segment
		(start 198.695564 -106.889296)
		(end 198.698104 -106.889296)
		(width 0.11684)
		(layer "In2.Cu")
		(net "PVDDCR_CPU0_P0_PMALERT")
	)
	(segment
		(start 199.400922 -106.966258)
		(end 199.91451 -106.966258)
		(width 0.11684)
		(layer "In2.Cu")
		(net "PVDDCR_CPU0_P0_PMALERT")
	)
	(segment
		(start 197.936358 -107.05973)
		(end 198.52513 -107.05973)
		(width 0.11684)
		(layer "In2.Cu")
		(net "PVDDCR_CPU0_P0_PMALERT")
	)
	(segment
		(start 195.49745 -106.67746)
		(end 197.554088 -106.67746)
		(width 0.11684)
		(layer "In2.Cu")
		(net "PVDDCR_CPU0_P0_PMALERT")
	)
	(segment
		(start 199.218042 -106.783378)
		(end 199.400922 -106.966258)
		(width 0.11684)
		(layer "In2.Cu")
		(net "PVDDCR_CPU0_P0_PMALERT")
	)
	(segment
		(start 197.554088 -106.67746)
		(end 197.936358 -107.05973)
		(width 0.11684)
		(layer "In2.Cu")
		(net "PVDDCR_CPU0_P0_PMALERT")
	)
	(segment
		(start 201.544682 -107.05973)
		(end 204.494892 -107.05973)
		(width 0.11684)
		(layer "In2.Cu")
		(net "PVDDCR_CPU0_P0_PMALERT")
	)
	(segment
		(start 199.91451 -106.966258)
		(end 199.991472 -106.889296)
		(width 0.11684)
		(layer "In2.Cu")
		(net "PVDDCR_CPU0_P0_PMALERT")
	)
	(segment
		(start 199.991472 -106.889296)
		(end 201.374248 -106.889296)
		(width 0.11684)
		(layer "In2.Cu")
		(net "PVDDCR_CPU0_P0_PMALERT")
	)
	(segment
		(start 204.494892 -107.05973)
		(end 206.437484 -109.002322)
		(width 0.11684)
		(layer "In2.Cu")
		(net "PVDDCR_CPU0_P0_PMALERT")
	)
	(segment
		(start 201.374248 -106.889296)
		(end 201.544682 -107.05973)
		(width 0.11684)
		(layer "In2.Cu")
		(net "PVDDCR_CPU0_P0_PMALERT")
	)
	(segment
		(start 252.377702 -112.333278)
		(end 254.626872 -114.582448)
		(width 0.11684)
		(layer "In2.Cu")
		(net "PVDDCR_CPU0_P0_PMALERT")
	)
	(segment
		(start 198.52513 -107.05973)
		(end 198.695564 -106.889296)
		(width 0.11684)
		(layer "In2.Cu")
		(net "PVDDCR_CPU0_P0_PMALERT")
	)
	(segment
		(start 212.626194 -109.002322)
		(end 215.95715 -112.333278)
		(width 0.11684)
		(layer "In2.Cu")
		(net "PVDDCR_CPU0_P0_PMALERT")
	)
	(segment
		(start 254.626872 -114.582448)
		(end 259.92328 -114.582448)
		(width 0.11684)
		(layer "In2.Cu")
		(net "PVDDCR_CPU0_P0_PMALERT")
	)
	(segment
		(start 320.850006 -117.735858)
		(end 359.11409 -117.735858)
		(width 0.11684)
		(layer "In6.Cu")
		(net "PVDDCR_CPU0_P0_PMALERT")
	)
	(segment
		(start 268.719808 -115.57508)
		(end 268.946122 -115.801394)
		(width 0.11684)
		(layer "In6.Cu")
		(net "PVDDCR_CPU0_P0_PMALERT")
	)
	(segment
		(start 282.479242 -115.984528)
		(end 292.862762 -115.984528)
		(width 0.11684)
		(layer "In6.Cu")
		(net "PVDDCR_CPU0_P0_PMALERT")
	)
	(segment
		(start 318.33185 -118.86565)
		(end 318.587882 -119.121682)
		(width 0.11684)
		(layer "In6.Cu")
		(net "PVDDCR_CPU0_P0_PMALERT")
	)
	(segment
		(start 297.340782 -120.462548)
		(end 305.523138 -120.462548)
		(width 0.11684)
		(layer "In6.Cu")
		(net "PVDDCR_CPU0_P0_PMALERT")
	)
	(segment
		(start 292.862762 -115.984528)
		(end 297.340782 -120.462548)
		(width 0.11684)
		(layer "In6.Cu")
		(net "PVDDCR_CPU0_P0_PMALERT")
	)
	(segment
		(start 276.11578 -116.690648)
		(end 279.1206 -116.690648)
		(width 0.11684)
		(layer "In6.Cu")
		(net "PVDDCR_CPU0_P0_PMALERT")
	)
	(segment
		(start 318.587882 -119.121682)
		(end 319.464182 -119.121682)
		(width 0.11684)
		(layer "In6.Cu")
		(net "PVDDCR_CPU0_P0_PMALERT")
	)
	(segment
		(start 319.464182 -119.121682)
		(end 320.850006 -117.735858)
		(width 0.11684)
		(layer "In6.Cu")
		(net "PVDDCR_CPU0_P0_PMALERT")
	)
	(segment
		(start 259.92328 -114.582448)
		(end 260.1087 -114.582448)
		(width 0.11684)
		(layer "In6.Cu")
		(net "PVDDCR_CPU0_P0_PMALERT")
	)
	(segment
		(start 279.1206 -116.690648)
		(end 280.27884 -115.532408)
		(width 0.11684)
		(layer "In6.Cu")
		(net "PVDDCR_CPU0_P0_PMALERT")
	)
	(segment
		(start 359.11409 -117.735858)
		(end 359.918 -116.931948)
		(width 0.11684)
		(layer "In6.Cu")
		(net "PVDDCR_CPU0_P0_PMALERT")
	)
	(segment
		(start 275.226526 -115.801394)
		(end 276.11578 -116.690648)
		(width 0.11684)
		(layer "In6.Cu")
		(net "PVDDCR_CPU0_P0_PMALERT")
	)
	(segment
		(start 260.1087 -114.582448)
		(end 261.101332 -115.57508)
		(width 0.11684)
		(layer "In6.Cu")
		(net "PVDDCR_CPU0_P0_PMALERT")
	)
	(segment
		(start 282.027122 -115.532408)
		(end 282.479242 -115.984528)
		(width 0.11684)
		(layer "In6.Cu")
		(net "PVDDCR_CPU0_P0_PMALERT")
	)
	(segment
		(start 305.523138 -120.462548)
		(end 307.120036 -118.86565)
		(width 0.11684)
		(layer "In6.Cu")
		(net "PVDDCR_CPU0_P0_PMALERT")
	)
	(segment
		(start 261.101332 -115.57508)
		(end 268.719808 -115.57508)
		(width 0.11684)
		(layer "In6.Cu")
		(net "PVDDCR_CPU0_P0_PMALERT")
	)
	(segment
		(start 307.120036 -118.86565)
		(end 318.33185 -118.86565)
		(width 0.11684)
		(layer "In6.Cu")
		(net "PVDDCR_CPU0_P0_PMALERT")
	)
	(segment
		(start 280.27884 -115.532408)
		(end 282.027122 -115.532408)
		(width 0.11684)
		(layer "In6.Cu")
		(net "PVDDCR_CPU0_P0_PMALERT")
	)
	(segment
		(start 268.946122 -115.801394)
		(end 275.226526 -115.801394)
		(width 0.11684)
		(layer "In6.Cu")
		(net "PVDDCR_CPU0_P0_PMALERT")
	)
	(segment
		(start 383.713228 -143.250158)
		(end 383.616708 -143.346678)
		(width 0.10668)
		(layer "F.Cu")
		(net "PVDDCR_CPU0_P0_OCP_N_R")
	)
	(segment
		(start 383.616708 -143.346678)
		(end 382.896872 -143.346678)
		(width 0.10668)
		(layer "F.Cu")
		(net "PVDDCR_CPU0_P0_OCP_N_R")
	)
	(via
		(at 382.896872 -143.346678)
		(size 0.508)
		(drill 0.254)
		(layers "F.Cu" "B.Cu")
		(net "PVDDCR_CPU0_P0_OCP_N_R")
	)
	(segment
		(start 382.88468 -143.346678)
		(end 382.363472 -143.131032)
		(width 0.10668)
		(layer "B.Cu")
		(net "PVDDCR_CPU0_P0_OCP_N_R")
	)
	(segment
		(start 382.363472 -143.131032)
		(end 382.193546 -142.961106)
		(width 0.10668)
		(layer "B.Cu")
		(net "PVDDCR_CPU0_P0_OCP_N_R")
	)
	(segment
		(start 382.193546 -142.961106)
		(end 381.273304 -142.961106)
		(width 0.10668)
		(layer "B.Cu")
		(net "PVDDCR_CPU0_P0_OCP_N_R")
	)
	(segment
		(start 383.713228 -143.250158)
		(end 383.616708 -143.346678)
		(width 0.10668)
		(layer "B.Cu")
		(net "PVDDCR_CPU0_P0_OCP_N_R")
	)
	(segment
		(start 382.896872 -143.346678)
		(end 382.88468 -143.346678)
		(width 0.10668)
		(layer "B.Cu")
		(net "PVDDCR_CPU0_P0_OCP_N_R")
	)
	(segment
		(start 383.616708 -143.346678)
		(end 382.896872 -143.346678)
		(width 0.10668)
		(layer "B.Cu")
		(net "PVDDCR_CPU0_P0_OCP_N_R")
	)
	(segment
		(start 181.229 -98.770948)
		(end 181.737 -98.262948)
		(width 0.10668)
		(layer "F.Cu")
		(net "PVDDCR_CPU0_P0_OCP_N")
	)
	(segment
		(start 181.591204 -99.894898)
		(end 181.229 -99.532694)
		(width 0.10668)
		(layer "F.Cu")
		(net "PVDDCR_CPU0_P0_OCP_N")
	)
	(segment
		(start 385.960112 -121.72061)
		(end 385.85648 -121.72061)
		(width 0.10668)
		(layer "F.Cu")
		(net "PVDDCR_CPU0_P0_OCP_N")
	)
	(segment
		(start 386.981446 -142.742158)
		(end 387.357874 -142.36573)
		(width 0.10668)
		(layer "F.Cu")
		(net "PVDDCR_CPU0_P0_OCP_N")
	)
	(segment
		(start 385.906518 -142.742158)
		(end 386.981446 -142.742158)
		(width 0.10668)
		(layer "F.Cu")
		(net "PVDDCR_CPU0_P0_OCP_N")
	)
	(segment
		(start 181.229 -99.532694)
		(end 181.229 -98.770948)
		(width 0.10668)
		(layer "F.Cu")
		(net "PVDDCR_CPU0_P0_OCP_N")
	)
	(segment
		(start 181.737 -99.894898)
		(end 181.591204 -99.894898)
		(width 0.10668)
		(layer "F.Cu")
		(net "PVDDCR_CPU0_P0_OCP_N")
	)
	(segment
		(start 387.357874 -123.118372)
		(end 385.960112 -121.72061)
		(width 0.10668)
		(layer "F.Cu")
		(net "PVDDCR_CPU0_P0_OCP_N")
	)
	(segment
		(start 387.357874 -142.36573)
		(end 387.357874 -123.118372)
		(width 0.10668)
		(layer "F.Cu")
		(net "PVDDCR_CPU0_P0_OCP_N")
	)
	(via
		(at 385.85648 -121.72061)
		(size 0.508)
		(drill 0.254)
		(layers "F.Cu" "B.Cu")
		(net "PVDDCR_CPU0_P0_OCP_N")
	)
	(via
		(at 181.737 -98.262948)
		(size 0.508)
		(drill 0.254)
		(layers "F.Cu" "B.Cu")
		(net "PVDDCR_CPU0_P0_OCP_N")
	)
	(via
		(at 385.906518 -142.742158)
		(size 0.508)
		(drill 0.254)
		(layers "F.Cu" "B.Cu")
		(net "PVDDCR_CPU0_P0_OCP_N")
	)
	(segment
		(start 384.513328 -143.250158)
		(end 385.021328 -142.742158)
		(width 0.10668)
		(layer "B.Cu")
		(net "PVDDCR_CPU0_P0_OCP_N")
	)
	(segment
		(start 385.021328 -142.742158)
		(end 385.906518 -142.742158)
		(width 0.10668)
		(layer "B.Cu")
		(net "PVDDCR_CPU0_P0_OCP_N")
	)
	(segment
		(start 320.177922 -103.885238)
		(end 325.187056 -108.894372)
		(width 0.11684)
		(layer "In6.Cu")
		(net "PVDDCR_CPU0_P0_OCP_N")
	)
	(segment
		(start 185.824622 -93.045788)
		(end 194.575938 -93.045788)
		(width 0.11684)
		(layer "In6.Cu")
		(net "PVDDCR_CPU0_P0_OCP_N")
	)
	(segment
		(start 319.861946 -103.885238)
		(end 320.177922 -103.885238)
		(width 0.11684)
		(layer "In6.Cu")
		(net "PVDDCR_CPU0_P0_OCP_N")
	)
	(segment
		(start 273.638518 -95.528892)
		(end 275.124164 -97.014538)
		(width 0.11684)
		(layer "In6.Cu")
		(net "PVDDCR_CPU0_P0_OCP_N")
	)
	(segment
		(start 200.83653 -99.30638)
		(end 212.78342 -99.30638)
		(width 0.11684)
		(layer "In6.Cu")
		(net "PVDDCR_CPU0_P0_OCP_N")
	)
	(segment
		(start 221.856808 -99.898962)
		(end 251.72924 -99.898962)
		(width 0.11684)
		(layer "In6.Cu")
		(net "PVDDCR_CPU0_P0_OCP_N")
	)
	(segment
		(start 252.790452 -98.83775)
		(end 257.263392 -98.83775)
		(width 0.11684)
		(layer "In6.Cu")
		(net "PVDDCR_CPU0_P0_OCP_N")
	)
	(segment
		(start 260.57225 -95.528892)
		(end 273.638518 -95.528892)
		(width 0.11684)
		(layer "In6.Cu")
		(net "PVDDCR_CPU0_P0_OCP_N")
	)
	(segment
		(start 315.164216 -99.187508)
		(end 319.861946 -103.885238)
		(width 0.11684)
		(layer "In6.Cu")
		(net "PVDDCR_CPU0_P0_OCP_N")
	)
	(segment
		(start 181.737 -97.822512)
		(end 185.295286 -94.264226)
		(width 0.11684)
		(layer "In6.Cu")
		(net "PVDDCR_CPU0_P0_OCP_N")
	)
	(segment
		(start 325.187056 -108.894372)
		(end 374.786652 -108.894372)
		(width 0.11684)
		(layer "In6.Cu")
		(net "PVDDCR_CPU0_P0_OCP_N")
	)
	(segment
		(start 212.78342 -99.30638)
		(end 213.088474 -99.611434)
		(width 0.11684)
		(layer "In6.Cu")
		(net "PVDDCR_CPU0_P0_OCP_N")
	)
	(segment
		(start 385.85648 -119.9642)
		(end 385.85648 -121.72061)
		(width 0.11684)
		(layer "In6.Cu")
		(net "PVDDCR_CPU0_P0_OCP_N")
	)
	(segment
		(start 194.575938 -93.045788)
		(end 200.83653 -99.30638)
		(width 0.11684)
		(layer "In6.Cu")
		(net "PVDDCR_CPU0_P0_OCP_N")
	)
	(segment
		(start 181.737 -98.262948)
		(end 181.737 -97.822512)
		(width 0.11684)
		(layer "In6.Cu")
		(net "PVDDCR_CPU0_P0_OCP_N")
	)
	(segment
		(start 279.156668 -97.014538)
		(end 281.329638 -99.187508)
		(width 0.11684)
		(layer "In6.Cu")
		(net "PVDDCR_CPU0_P0_OCP_N")
	)
	(segment
		(start 214.113872 -99.611434)
		(end 214.648288 -99.077018)
		(width 0.11684)
		(layer "In6.Cu")
		(net "PVDDCR_CPU0_P0_OCP_N")
	)
	(segment
		(start 251.72924 -99.898962)
		(end 252.790452 -98.83775)
		(width 0.11684)
		(layer "In6.Cu")
		(net "PVDDCR_CPU0_P0_OCP_N")
	)
	(segment
		(start 185.295286 -93.575124)
		(end 185.824622 -93.045788)
		(width 0.11684)
		(layer "In6.Cu")
		(net "PVDDCR_CPU0_P0_OCP_N")
	)
	(segment
		(start 185.295286 -94.264226)
		(end 185.295286 -93.575124)
		(width 0.11684)
		(layer "In6.Cu")
		(net "PVDDCR_CPU0_P0_OCP_N")
	)
	(segment
		(start 221.034864 -99.077018)
		(end 221.856808 -99.898962)
		(width 0.11684)
		(layer "In6.Cu")
		(net "PVDDCR_CPU0_P0_OCP_N")
	)
	(segment
		(start 281.329638 -99.187508)
		(end 315.164216 -99.187508)
		(width 0.11684)
		(layer "In6.Cu")
		(net "PVDDCR_CPU0_P0_OCP_N")
	)
	(segment
		(start 213.088474 -99.611434)
		(end 214.113872 -99.611434)
		(width 0.11684)
		(layer "In6.Cu")
		(net "PVDDCR_CPU0_P0_OCP_N")
	)
	(segment
		(start 275.124164 -97.014538)
		(end 279.156668 -97.014538)
		(width 0.11684)
		(layer "In6.Cu")
		(net "PVDDCR_CPU0_P0_OCP_N")
	)
	(segment
		(start 257.263392 -98.83775)
		(end 260.57225 -95.528892)
		(width 0.11684)
		(layer "In6.Cu")
		(net "PVDDCR_CPU0_P0_OCP_N")
	)
	(segment
		(start 374.786652 -108.894372)
		(end 385.85648 -119.9642)
		(width 0.11684)
		(layer "In6.Cu")
		(net "PVDDCR_CPU0_P0_OCP_N")
	)
	(segment
		(start 214.648288 -99.077018)
		(end 221.034864 -99.077018)
		(width 0.11684)
		(layer "In6.Cu")
		(net "PVDDCR_CPU0_P0_OCP_N")
	)
	(segment
		(start 349.432372 -155.927806)
		(end 349.19031 -156.169868)
		(width 0.127)
		(layer "F.Cu")
		(net "PVDDCR_CPU0_P0_LSET6")
	)
	(segment
		(start 349.19031 -156.169868)
		(end 349.19031 -157.041596)
		(width 0.127)
		(layer "F.Cu")
		(net "PVDDCR_CPU0_P0_LSET6")
	)
	(segment
		(start 349.19031 -157.46095)
		(end 348.817692 -157.833568)
		(width 0.127)
		(layer "F.Cu")
		(net "PVDDCR_CPU0_P0_LSET6")
	)
	(segment
		(start 349.19031 -157.041596)
		(end 349.19031 -157.46095)
		(width 0.127)
		(layer "F.Cu")
		(net "PVDDCR_CPU0_P0_LSET6")
	)
	(segment
		(start 348.817692 -157.833568)
		(end 348.817692 -158.23946)
		(width 0.127)
		(layer "F.Cu")
		(net "PVDDCR_CPU0_P0_LSET6")
	)
	(via
		(at 349.19031 -157.041596)
		(size 0.4064)
		(drill 0.2032)
		(layers "F.Cu" "B.Cu")
		(net "PVDDCR_CPU0_P0_LSET6")
	)
	(segment
		(start 357.49611 -164.526468)
		(end 357.49611 -165.41496)
		(width 0.127)
		(layer "F.Cu")
		(net "PVDDCR_CPU0_P0_LSET5")
	)
	(segment
		(start 357.49611 -165.81755)
		(end 357.123492 -166.190168)
		(width 0.127)
		(layer "F.Cu")
		(net "PVDDCR_CPU0_P0_LSET5")
	)
	(segment
		(start 357.738172 -164.284406)
		(end 357.49611 -164.526468)
		(width 0.127)
		(layer "F.Cu")
		(net "PVDDCR_CPU0_P0_LSET5")
	)
	(segment
		(start 357.123492 -166.190168)
		(end 357.123492 -166.59606)
		(width 0.127)
		(layer "F.Cu")
		(net "PVDDCR_CPU0_P0_LSET5")
	)
	(segment
		(start 357.49611 -165.41496)
		(end 357.49611 -165.81755)
		(width 0.127)
		(layer "F.Cu")
		(net "PVDDCR_CPU0_P0_LSET5")
	)
	(via
		(at 357.49611 -165.41496)
		(size 0.4064)
		(drill 0.2032)
		(layers "F.Cu" "B.Cu")
		(net "PVDDCR_CPU0_P0_LSET5")
	)
	(segment
		(start 390.499092 -179.438046)
		(end 390.499092 -179.843938)
		(width 0.127)
		(layer "F.Cu")
		(net "PVDDCR_CPU0_P0_LSET4")
	)
	(segment
		(start 390.87171 -178.676554)
		(end 390.87171 -179.065428)
		(width 0.127)
		(layer "F.Cu")
		(net "PVDDCR_CPU0_P0_LSET4")
	)
	(segment
		(start 390.87171 -179.065428)
		(end 390.499092 -179.438046)
		(width 0.127)
		(layer "F.Cu")
		(net "PVDDCR_CPU0_P0_LSET4")
	)
	(segment
		(start 391.113772 -177.532284)
		(end 390.87171 -177.774346)
		(width 0.127)
		(layer "F.Cu")
		(net "PVDDCR_CPU0_P0_LSET4")
	)
	(segment
		(start 390.87171 -177.774346)
		(end 390.87171 -178.676554)
		(width 0.127)
		(layer "F.Cu")
		(net "PVDDCR_CPU0_P0_LSET4")
	)
	(via
		(at 390.87171 -178.676554)
		(size 0.4064)
		(drill 0.2032)
		(layers "F.Cu" "B.Cu")
		(net "PVDDCR_CPU0_P0_LSET4")
	)
	(segment
		(start 382.54051 -177.774346)
		(end 382.54051 -178.664616)
		(width 0.127)
		(layer "F.Cu")
		(net "PVDDCR_CPU0_P0_LSET3")
	)
	(segment
		(start 382.54051 -179.065428)
		(end 382.54051 -178.664616)
		(width 0.127)
		(layer "F.Cu")
		(net "PVDDCR_CPU0_P0_LSET3")
	)
	(segment
		(start 382.167892 -179.438046)
		(end 382.54051 -179.065428)
		(width 0.127)
		(layer "F.Cu")
		(net "PVDDCR_CPU0_P0_LSET3")
	)
	(segment
		(start 382.782572 -177.532284)
		(end 382.54051 -177.774346)
		(width 0.127)
		(layer "F.Cu")
		(net "PVDDCR_CPU0_P0_LSET3")
	)
	(segment
		(start 382.167892 -179.88661)
		(end 382.167892 -179.438046)
		(width 0.1524)
		(layer "F.Cu")
		(net "PVDDCR_CPU0_P0_LSET3")
	)
	(via
		(at 382.54051 -178.664616)
		(size 0.4064)
		(drill 0.2032)
		(layers "F.Cu" "B.Cu")
		(net "PVDDCR_CPU0_P0_LSET3")
	)
	(segment
		(start 374.379744 -177.532284)
		(end 374.137682 -177.774346)
		(width 0.127)
		(layer "F.Cu")
		(net "PVDDCR_CPU0_P0_LSET2")
	)
	(segment
		(start 373.765064 -179.438046)
		(end 373.765064 -179.843938)
		(width 0.127)
		(layer "F.Cu")
		(net "PVDDCR_CPU0_P0_LSET2")
	)
	(segment
		(start 374.137682 -178.65979)
		(end 374.137682 -179.065428)
		(width 0.127)
		(layer "F.Cu")
		(net "PVDDCR_CPU0_P0_LSET2")
	)
	(segment
		(start 374.137682 -177.774346)
		(end 374.137682 -178.65979)
		(width 0.127)
		(layer "F.Cu")
		(net "PVDDCR_CPU0_P0_LSET2")
	)
	(segment
		(start 374.137682 -179.065428)
		(end 373.765064 -179.438046)
		(width 0.127)
		(layer "F.Cu")
		(net "PVDDCR_CPU0_P0_LSET2")
	)
	(via
		(at 374.137682 -178.65979)
		(size 0.4064)
		(drill 0.2032)
		(layers "F.Cu" "B.Cu")
		(net "PVDDCR_CPU0_P0_LSET2")
	)
	(segment
		(start 365.77651 -174.09287)
		(end 365.403892 -174.465488)
		(width 0.127)
		(layer "F.Cu")
		(net "PVDDCR_CPU0_P0_LSET1")
	)
	(segment
		(start 365.403892 -174.465488)
		(end 365.403892 -174.87138)
		(width 0.127)
		(layer "F.Cu")
		(net "PVDDCR_CPU0_P0_LSET1")
	)
	(segment
		(start 366.018572 -172.559726)
		(end 365.77651 -172.801788)
		(width 0.127)
		(layer "F.Cu")
		(net "PVDDCR_CPU0_P0_LSET1")
	)
	(segment
		(start 365.77651 -173.69409)
		(end 365.77651 -174.09287)
		(width 0.127)
		(layer "F.Cu")
		(net "PVDDCR_CPU0_P0_LSET1")
	)
	(segment
		(start 365.77651 -172.801788)
		(end 365.77651 -173.69409)
		(width 0.127)
		(layer "F.Cu")
		(net "PVDDCR_CPU0_P0_LSET1")
	)
	(via
		(at 365.77651 -173.69409)
		(size 0.4064)
		(drill 0.2032)
		(layers "F.Cu" "B.Cu")
		(net "PVDDCR_CPU0_P0_LSET1")
	)
	(segment
		(start 349.26778 -158.23946)
		(end 349.26778 -157.86354)
		(width 0.2286)
		(layer "F.Cu")
		(net "PVDDCR_CPU0_P0_IMON6")
	)
	(segment
		(start 349.696278 -157.435042)
		(end 349.696278 -157.352238)
		(width 0.2286)
		(layer "F.Cu")
		(net "PVDDCR_CPU0_P0_IMON6")
	)
	(segment
		(start 349.26778 -157.86354)
		(end 349.696278 -157.435042)
		(width 0.2286)
		(layer "F.Cu")
		(net "PVDDCR_CPU0_P0_IMON6")
	)
	(via
		(at 349.696278 -157.352238)
		(size 0.508)
		(drill 0.254)
		(layers "F.Cu" "B.Cu")
		(net "PVDDCR_CPU0_P0_IMON6")
	)
	(via
		(at 379.168406 -146.456908)
		(size 0.762)
		(drill 0.254)
		(layers "F.Cu" "B.Cu")
		(net "PVDDCR_CPU0_P0_IMON6")
	)
	(segment
		(start 379.168406 -146.456908)
		(end 378.998226 -146.046444)
		(width 0.1778)
		(layer "B.Cu")
		(net "PVDDCR_CPU0_P0_IMON6")
	)
	(segment
		(start 378.998226 -146.046444)
		(end 378.998226 -145.236184)
		(width 0.1778)
		(layer "B.Cu")
		(net "PVDDCR_CPU0_P0_IMON6")
	)
	(segment
		(start 379.168406 -146.456908)
		(end 379.168406 -145.933668)
		(width 0.254)
		(layer "In11.Cu")
		(net "PVDDCR_CPU0_P0_IMON6")
	)
	(segment
		(start 372.241826 -148.77415)
		(end 356.267258 -148.77415)
		(width 0.254)
		(layer "In11.Cu")
		(net "PVDDCR_CPU0_P0_IMON6")
	)
	(segment
		(start 374.433338 -145.457672)
		(end 372.979696 -146.911314)
		(width 0.254)
		(layer "In11.Cu")
		(net "PVDDCR_CPU0_P0_IMON6")
	)
	(segment
		(start 356.267258 -148.77415)
		(end 350.331278 -154.71013)
		(width 0.254)
		(layer "In11.Cu")
		(net "PVDDCR_CPU0_P0_IMON6")
	)
	(segment
		(start 350.01835 -157.352238)
		(end 349.696278 -157.352238)
		(width 0.254)
		(layer "In11.Cu")
		(net "PVDDCR_CPU0_P0_IMON6")
	)
	(segment
		(start 379.168406 -145.933668)
		(end 378.69241 -145.457672)
		(width 0.254)
		(layer "In11.Cu")
		(net "PVDDCR_CPU0_P0_IMON6")
	)
	(segment
		(start 372.979696 -146.911314)
		(end 372.979696 -148.03628)
		(width 0.254)
		(layer "In11.Cu")
		(net "PVDDCR_CPU0_P0_IMON6")
	)
	(segment
		(start 350.331278 -157.03931)
		(end 350.01835 -157.352238)
		(width 0.254)
		(layer "In11.Cu")
		(net "PVDDCR_CPU0_P0_IMON6")
	)
	(segment
		(start 350.331278 -154.71013)
		(end 350.331278 -157.03931)
		(width 0.254)
		(layer "In11.Cu")
		(net "PVDDCR_CPU0_P0_IMON6")
	)
	(segment
		(start 378.69241 -145.457672)
		(end 374.433338 -145.457672)
		(width 0.254)
		(layer "In11.Cu")
		(net "PVDDCR_CPU0_P0_IMON6")
	)
	(segment
		(start 372.979696 -148.03628)
		(end 372.241826 -148.77415)
		(width 0.254)
		(layer "In11.Cu")
		(net "PVDDCR_CPU0_P0_IMON6")
	)
	(segment
		(start 358.010714 -165.675564)
		(end 357.99903 -165.675564)
		(width 0.2286)
		(layer "F.Cu")
		(net "PVDDCR_CPU0_P0_IMON5")
	)
	(segment
		(start 357.57358 -166.22014)
		(end 358.010714 -165.783006)
		(width 0.2286)
		(layer "F.Cu")
		(net "PVDDCR_CPU0_P0_IMON5")
	)
	(segment
		(start 357.57358 -166.59606)
		(end 357.57358 -166.22014)
		(width 0.2286)
		(layer "F.Cu")
		(net "PVDDCR_CPU0_P0_IMON5")
	)
	(segment
		(start 358.010714 -165.783006)
		(end 358.010714 -165.675564)
		(width 0.2286)
		(layer "F.Cu")
		(net "PVDDCR_CPU0_P0_IMON5")
	)
	(via
		(at 378.631958 -147.494752)
		(size 0.508)
		(drill 0.254)
		(layers "F.Cu" "B.Cu")
		(net "PVDDCR_CPU0_P0_IMON5")
	)
	(via
		(at 357.99903 -165.675564)
		(size 0.508)
		(drill 0.254)
		(layers "F.Cu" "B.Cu")
		(net "PVDDCR_CPU0_P0_IMON5")
	)
	(segment
		(start 378.598176 -145.794984)
		(end 378.598176 -145.236184)
		(width 0.1778)
		(layer "B.Cu")
		(net "PVDDCR_CPU0_P0_IMON5")
	)
	(segment
		(start 378.631958 -145.828766)
		(end 378.598176 -145.794984)
		(width 0.1778)
		(layer "B.Cu")
		(net "PVDDCR_CPU0_P0_IMON5")
	)
	(segment
		(start 378.631958 -147.494752)
		(end 378.631958 -145.828766)
		(width 0.1778)
		(layer "B.Cu")
		(net "PVDDCR_CPU0_P0_IMON5")
	)
	(segment
		(start 378.30125 -147.302728)
		(end 378.089414 -146.791426)
		(width 0.254)
		(layer "In11.Cu")
		(net "PVDDCR_CPU0_P0_IMON5")
	)
	(segment
		(start 374.237758 -148.74494)
		(end 372.211346 -150.771352)
		(width 0.254)
		(layer "In11.Cu")
		(net "PVDDCR_CPU0_P0_IMON5")
	)
	(segment
		(start 365.375698 -150.771352)
		(end 363.996732 -152.150318)
		(width 0.254)
		(layer "In11.Cu")
		(net "PVDDCR_CPU0_P0_IMON5")
	)
	(segment
		(start 358.586278 -163.733226)
		(end 358.586278 -165.29431)
		(width 0.254)
		(layer "In11.Cu")
		(net "PVDDCR_CPU0_P0_IMON5")
	)
	(segment
		(start 372.211346 -150.771352)
		(end 365.375698 -150.771352)
		(width 0.254)
		(layer "In11.Cu")
		(net "PVDDCR_CPU0_P0_IMON5")
	)
	(segment
		(start 358.586278 -165.29431)
		(end 358.205024 -165.675564)
		(width 0.254)
		(layer "In11.Cu")
		(net "PVDDCR_CPU0_P0_IMON5")
	)
	(segment
		(start 363.996732 -152.150318)
		(end 363.996732 -158.322772)
		(width 0.254)
		(layer "In11.Cu")
		(net "PVDDCR_CPU0_P0_IMON5")
	)
	(segment
		(start 378.493274 -147.494752)
		(end 378.30125 -147.302728)
		(width 0.254)
		(layer "In11.Cu")
		(net "PVDDCR_CPU0_P0_IMON5")
	)
	(segment
		(start 375.48185 -146.417284)
		(end 374.237758 -147.661376)
		(width 0.254)
		(layer "In11.Cu")
		(net "PVDDCR_CPU0_P0_IMON5")
	)
	(segment
		(start 358.205024 -165.675564)
		(end 357.99903 -165.675564)
		(width 0.254)
		(layer "In11.Cu")
		(net "PVDDCR_CPU0_P0_IMON5")
	)
	(segment
		(start 374.237758 -147.661376)
		(end 374.237758 -148.74494)
		(width 0.254)
		(layer "In11.Cu")
		(net "PVDDCR_CPU0_P0_IMON5")
	)
	(segment
		(start 378.089414 -146.791426)
		(end 377.715272 -146.417284)
		(width 0.254)
		(layer "In11.Cu")
		(net "PVDDCR_CPU0_P0_IMON5")
	)
	(segment
		(start 377.715272 -146.417284)
		(end 375.48185 -146.417284)
		(width 0.254)
		(layer "In11.Cu")
		(net "PVDDCR_CPU0_P0_IMON5")
	)
	(segment
		(start 363.996732 -158.322772)
		(end 358.586278 -163.733226)
		(width 0.254)
		(layer "In11.Cu")
		(net "PVDDCR_CPU0_P0_IMON5")
	)
	(segment
		(start 378.631958 -147.494752)
		(end 378.493274 -147.494752)
		(width 0.254)
		(layer "In11.Cu")
		(net "PVDDCR_CPU0_P0_IMON5")
	)
	(segment
		(start 391.386314 -179.030884)
		(end 391.386314 -178.923442)
		(width 0.2286)
		(layer "F.Cu")
		(net "PVDDCR_CPU0_P0_IMON4")
	)
	(segment
		(start 391.386314 -178.923442)
		(end 391.37463 -178.923442)
		(width 0.2286)
		(layer "F.Cu")
		(net "PVDDCR_CPU0_P0_IMON4")
	)
	(segment
		(start 390.94918 -179.843938)
		(end 390.94918 -179.468018)
		(width 0.2286)
		(layer "F.Cu")
		(net "PVDDCR_CPU0_P0_IMON4")
	)
	(segment
		(start 390.94918 -179.468018)
		(end 391.386314 -179.030884)
		(width 0.2286)
		(layer "F.Cu")
		(net "PVDDCR_CPU0_P0_IMON4")
	)
	(via
		(at 391.37463 -178.923442)
		(size 0.508)
		(drill 0.254)
		(layers "F.Cu" "B.Cu")
		(net "PVDDCR_CPU0_P0_IMON4")
	)
	(via
		(at 378.885958 -148.231352)
		(size 0.508)
		(drill 0.254)
		(layers "F.Cu" "B.Cu")
		(net "PVDDCR_CPU0_P0_IMON4")
	)
	(segment
		(start 378.14504 -147.922234)
		(end 378.320808 -148.098002)
		(width 0.1778)
		(layer "B.Cu")
		(net "PVDDCR_CPU0_P0_IMON4")
	)
	(segment
		(start 378.19838 -146.702018)
		(end 378.022358 -146.87804)
		(width 0.1778)
		(layer "B.Cu")
		(net "PVDDCR_CPU0_P0_IMON4")
	)
	(segment
		(start 378.022358 -147.62607)
		(end 378.14504 -147.922234)
		(width 0.1778)
		(layer "B.Cu")
		(net "PVDDCR_CPU0_P0_IMON4")
	)
	(segment
		(start 378.022358 -146.87804)
		(end 378.022358 -147.62607)
		(width 0.1778)
		(layer "B.Cu")
		(net "PVDDCR_CPU0_P0_IMON4")
	)
	(segment
		(start 378.19838 -145.236184)
		(end 378.19838 -146.702018)
		(width 0.1778)
		(layer "B.Cu")
		(net "PVDDCR_CPU0_P0_IMON4")
	)
	(segment
		(start 378.320808 -148.098002)
		(end 378.642372 -148.231352)
		(width 0.1778)
		(layer "B.Cu")
		(net "PVDDCR_CPU0_P0_IMON4")
	)
	(segment
		(start 378.642372 -148.231352)
		(end 378.885958 -148.231352)
		(width 0.1778)
		(layer "B.Cu")
		(net "PVDDCR_CPU0_P0_IMON4")
	)
	(segment
		(start 383.763012 -150.745952)
		(end 388.949946 -150.745952)
		(width 0.254)
		(layer "In4.Cu")
		(net "PVDDCR_CPU0_P0_IMON4")
	)
	(segment
		(start 379.343158 -147.774152)
		(end 380.791212 -147.774152)
		(width 0.254)
		(layer "In4.Cu")
		(net "PVDDCR_CPU0_P0_IMON4")
	)
	(segment
		(start 393.318238 -155.114244)
		(end 393.318238 -176.02327)
		(width 0.254)
		(layer "In4.Cu")
		(net "PVDDCR_CPU0_P0_IMON4")
	)
	(segment
		(start 391.975086 -177.366422)
		(end 391.975086 -178.440334)
		(width 0.254)
		(layer "In4.Cu")
		(net "PVDDCR_CPU0_P0_IMON4")
	)
	(segment
		(start 393.318238 -176.02327)
		(end 391.975086 -177.366422)
		(width 0.254)
		(layer "In4.Cu")
		(net "PVDDCR_CPU0_P0_IMON4")
	)
	(segment
		(start 391.975086 -178.440334)
		(end 391.491978 -178.923442)
		(width 0.254)
		(layer "In4.Cu")
		(net "PVDDCR_CPU0_P0_IMON4")
	)
	(segment
		(start 380.791212 -147.774152)
		(end 383.763012 -150.745952)
		(width 0.254)
		(layer "In4.Cu")
		(net "PVDDCR_CPU0_P0_IMON4")
	)
	(segment
		(start 391.491978 -178.923442)
		(end 391.37463 -178.923442)
		(width 0.254)
		(layer "In4.Cu")
		(net "PVDDCR_CPU0_P0_IMON4")
	)
	(segment
		(start 378.885958 -148.231352)
		(end 379.343158 -147.774152)
		(width 0.254)
		(layer "In4.Cu")
		(net "PVDDCR_CPU0_P0_IMON4")
	)
	(segment
		(start 388.949946 -150.745952)
		(end 393.318238 -155.114244)
		(width 0.254)
		(layer "In4.Cu")
		(net "PVDDCR_CPU0_P0_IMON4")
	)
	(segment
		(start 383.04343 -178.923442)
		(end 383.04343 -179.08524)
		(width 0.2286)
		(layer "F.Cu")
		(net "PVDDCR_CPU0_P0_IMON3")
	)
	(segment
		(start 382.61798 -179.51069)
		(end 382.61798 -179.88661)
		(width 0.2286)
		(layer "F.Cu")
		(net "PVDDCR_CPU0_P0_IMON3")
	)
	(segment
		(start 383.04343 -179.08524)
		(end 382.61798 -179.51069)
		(width 0.2286)
		(layer "F.Cu")
		(net "PVDDCR_CPU0_P0_IMON3")
	)
	(via
		(at 383.04343 -178.923442)
		(size 0.508)
		(drill 0.254)
		(layers "F.Cu" "B.Cu")
		(net "PVDDCR_CPU0_P0_IMON3")
	)
	(via
		(at 377.86564 -148.779992)
		(size 0.508)
		(drill 0.254)
		(layers "F.Cu" "B.Cu")
		(net "PVDDCR_CPU0_P0_IMON3")
	)
	(segment
		(start 377.590558 -148.115528)
		(end 377.590558 -146.841464)
		(width 0.1778)
		(layer "B.Cu")
		(net "PVDDCR_CPU0_P0_IMON3")
	)
	(segment
		(start 377.79833 -146.633692)
		(end 377.79833 -145.236184)
		(width 0.1778)
		(layer "B.Cu")
		(net "PVDDCR_CPU0_P0_IMON3")
	)
	(segment
		(start 377.86564 -148.779992)
		(end 377.590558 -148.115528)
		(width 0.1778)
		(layer "B.Cu")
		(net "PVDDCR_CPU0_P0_IMON3")
	)
	(segment
		(start 377.590558 -146.841464)
		(end 377.79833 -146.633692)
		(width 0.1778)
		(layer "B.Cu")
		(net "PVDDCR_CPU0_P0_IMON3")
	)
	(segment
		(start 376.853958 -149.791674)
		(end 376.853958 -158.080964)
		(width 0.254)
		(layer "In4.Cu")
		(net "PVDDCR_CPU0_P0_IMON3")
	)
	(segment
		(start 376.853958 -158.080964)
		(end 383.643886 -164.870892)
		(width 0.254)
		(layer "In4.Cu")
		(net "PVDDCR_CPU0_P0_IMON3")
	)
	(segment
		(start 383.643886 -178.440334)
		(end 383.160778 -178.923442)
		(width 0.254)
		(layer "In4.Cu")
		(net "PVDDCR_CPU0_P0_IMON3")
	)
	(segment
		(start 383.160778 -178.923442)
		(end 383.04343 -178.923442)
		(width 0.254)
		(layer "In4.Cu")
		(net "PVDDCR_CPU0_P0_IMON3")
	)
	(segment
		(start 377.86564 -148.779992)
		(end 376.853958 -149.791674)
		(width 0.254)
		(layer "In4.Cu")
		(net "PVDDCR_CPU0_P0_IMON3")
	)
	(segment
		(start 383.643886 -164.870892)
		(end 383.643886 -178.440334)
		(width 0.254)
		(layer "In4.Cu")
		(net "PVDDCR_CPU0_P0_IMON3")
	)
	(segment
		(start 374.652286 -179.058824)
		(end 374.215152 -179.495958)
		(width 0.2286)
		(layer "F.Cu")
		(net "PVDDCR_CPU0_P0_IMON2")
	)
	(segment
		(start 374.652286 -178.939952)
		(end 374.652286 -179.058824)
		(width 0.2286)
		(layer "F.Cu")
		(net "PVDDCR_CPU0_P0_IMON2")
	)
	(segment
		(start 374.215152 -179.495958)
		(end 374.215152 -179.843938)
		(width 0.2286)
		(layer "F.Cu")
		(net "PVDDCR_CPU0_P0_IMON2")
	)
	(via
		(at 377.024138 -147.418552)
		(size 0.762)
		(drill 0.254)
		(layers "F.Cu" "B.Cu")
		(net "PVDDCR_CPU0_P0_IMON2")
	)
	(via
		(at 374.652286 -178.939952)
		(size 0.508)
		(drill 0.254)
		(layers "F.Cu" "B.Cu")
		(net "PVDDCR_CPU0_P0_IMON2")
	)
	(segment
		(start 377.024138 -146.794982)
		(end 377.39828 -146.42084)
		(width 0.1778)
		(layer "B.Cu")
		(net "PVDDCR_CPU0_P0_IMON2")
	)
	(segment
		(start 377.024138 -147.418552)
		(end 377.024138 -146.794982)
		(width 0.1778)
		(layer "B.Cu")
		(net "PVDDCR_CPU0_P0_IMON2")
	)
	(segment
		(start 377.39828 -146.42084)
		(end 377.39828 -145.236184)
		(width 0.1778)
		(layer "B.Cu")
		(net "PVDDCR_CPU0_P0_IMON2")
	)
	(segment
		(start 374.258078 -172.99305)
		(end 375.241058 -173.97603)
		(width 0.254)
		(layer "In4.Cu")
		(net "PVDDCR_CPU0_P0_IMON2")
	)
	(segment
		(start 375.241058 -178.440334)
		(end 374.74144 -178.939952)
		(width 0.254)
		(layer "In4.Cu")
		(net "PVDDCR_CPU0_P0_IMON2")
	)
	(segment
		(start 374.258078 -148.439632)
		(end 374.258078 -172.99305)
		(width 0.254)
		(layer "In4.Cu")
		(net "PVDDCR_CPU0_P0_IMON2")
	)
	(segment
		(start 377.024138 -147.418552)
		(end 375.279158 -147.418552)
		(width 0.254)
		(layer "In4.Cu")
		(net "PVDDCR_CPU0_P0_IMON2")
	)
	(segment
		(start 375.279158 -147.418552)
		(end 374.258078 -148.439632)
		(width 0.254)
		(layer "In4.Cu")
		(net "PVDDCR_CPU0_P0_IMON2")
	)
	(segment
		(start 374.74144 -178.939952)
		(end 374.652286 -178.939952)
		(width 0.254)
		(layer "In4.Cu")
		(net "PVDDCR_CPU0_P0_IMON2")
	)
	(segment
		(start 375.241058 -173.97603)
		(end 375.241058 -178.440334)
		(width 0.254)
		(layer "In4.Cu")
		(net "PVDDCR_CPU0_P0_IMON2")
	)
	(segment
		(start 366.291114 -173.950884)
		(end 366.291114 -174.058326)
		(width 0.2286)
		(layer "F.Cu")
		(net "PVDDCR_CPU0_P0_IMON1")
	)
	(segment
		(start 365.85398 -174.49546)
		(end 365.85398 -174.87138)
		(width 0.2286)
		(layer "F.Cu")
		(net "PVDDCR_CPU0_P0_IMON1")
	)
	(segment
		(start 366.291114 -174.058326)
		(end 365.85398 -174.49546)
		(width 0.2286)
		(layer "F.Cu")
		(net "PVDDCR_CPU0_P0_IMON1")
	)
	(via
		(at 376.402092 -148.710904)
		(size 0.508)
		(drill 0.254)
		(layers "F.Cu" "B.Cu")
		(net "PVDDCR_CPU0_P0_IMON1")
	)
	(via
		(at 366.291114 -173.950884)
		(size 0.508)
		(drill 0.254)
		(layers "F.Cu" "B.Cu")
		(net "PVDDCR_CPU0_P0_IMON1")
	)
	(segment
		(start 376.402092 -146.98472)
		(end 376.99823 -146.388582)
		(width 0.1778)
		(layer "B.Cu")
		(net "PVDDCR_CPU0_P0_IMON1")
	)
	(segment
		(start 376.402092 -148.710904)
		(end 376.402092 -146.98472)
		(width 0.1778)
		(layer "B.Cu")
		(net "PVDDCR_CPU0_P0_IMON1")
	)
	(segment
		(start 376.99823 -146.388582)
		(end 376.99823 -145.236184)
		(width 0.1778)
		(layer "B.Cu")
		(net "PVDDCR_CPU0_P0_IMON1")
	)
	(segment
		(start 366.881918 -173.465744)
		(end 366.396778 -173.950884)
		(width 0.254)
		(layer "In11.Cu")
		(net "PVDDCR_CPU0_P0_IMON1")
	)
	(segment
		(start 366.396778 -173.950884)
		(end 366.291114 -173.950884)
		(width 0.254)
		(layer "In11.Cu")
		(net "PVDDCR_CPU0_P0_IMON1")
	)
	(segment
		(start 376.402092 -162.104578)
		(end 366.881918 -171.624752)
		(width 0.254)
		(layer "In11.Cu")
		(net "PVDDCR_CPU0_P0_IMON1")
	)
	(segment
		(start 376.402092 -148.710904)
		(end 376.402092 -162.104578)
		(width 0.254)
		(layer "In11.Cu")
		(net "PVDDCR_CPU0_P0_IMON1")
	)
	(segment
		(start 366.881918 -171.624752)
		(end 366.881918 -173.465744)
		(width 0.254)
		(layer "In11.Cu")
		(net "PVDDCR_CPU0_P0_IMON1")
	)
	(segment
		(start 373.337328 -140.456158)
		(end 373.688102 -140.456158)
		(width 0.10668)
		(layer "F.Cu")
		(net "PVDDCR_CPU0_P0_EN_R")
	)
	(segment
		(start 373.688102 -140.456158)
		(end 374.254776 -141.022832)
		(width 0.10668)
		(layer "F.Cu")
		(net "PVDDCR_CPU0_P0_EN_R")
	)
	(via
		(at 374.254776 -141.022832)
		(size 0.762)
		(drill 0.254)
		(layers "F.Cu" "B.Cu")
		(net "PVDDCR_CPU0_P0_EN_R")
	)
	(segment
		(start 374.254776 -141.022832)
		(end 374.993154 -141.76121)
		(width 0.10668)
		(layer "B.Cu")
		(net "PVDDCR_CPU0_P0_EN_R")
	)
	(segment
		(start 374.993154 -141.76121)
		(end 375.523252 -141.76121)
		(width 0.10668)
		(layer "B.Cu")
		(net "PVDDCR_CPU0_P0_EN_R")
	)
	(segment
		(start 374.156478 -141.022832)
		(end 374.254776 -141.022832)
		(width 0.10668)
		(layer "B.Cu")
		(net "PVDDCR_CPU0_P0_EN_R")
	)
	(segment
		(start 373.967502 -140.833856)
		(end 374.156478 -141.022832)
		(width 0.10668)
		(layer "B.Cu")
		(net "PVDDCR_CPU0_P0_EN_R")
	)
	(segment
		(start 373.337328 -140.477494)
		(end 373.69369 -140.833856)
		(width 0.10668)
		(layer "B.Cu")
		(net "PVDDCR_CPU0_P0_EN_R")
	)
	(segment
		(start 373.69369 -140.833856)
		(end 373.967502 -140.833856)
		(width 0.10668)
		(layer "B.Cu")
		(net "PVDDCR_CPU0_P0_EN_R")
	)
	(segment
		(start 373.337328 -140.456158)
		(end 373.337328 -140.477494)
		(width 0.10668)
		(layer "B.Cu")
		(net "PVDDCR_CPU0_P0_EN_R")
	)
	(segment
		(start 177.922174 -119.452898)
		(end 177.532284 -119.842788)
		(width 0.10668)
		(layer "F.Cu")
		(net "PVDDCR_CPU0_P0_EN")
	)
	(segment
		(start 372.452138 -139.963652)
		(end 371.189758 -139.963652)
		(width 0.10668)
		(layer "F.Cu")
		(net "PVDDCR_CPU0_P0_EN")
	)
	(segment
		(start 372.537228 -140.456158)
		(end 372.537228 -140.048742)
		(width 0.10668)
		(layer "F.Cu")
		(net "PVDDCR_CPU0_P0_EN")
	)
	(segment
		(start 371.189758 -139.963652)
		(end 369.997228 -138.771122)
		(width 0.10668)
		(layer "F.Cu")
		(net "PVDDCR_CPU0_P0_EN")
	)
	(segment
		(start 369.997228 -138.771122)
		(end 369.997228 -116.124228)
		(width 0.10668)
		(layer "F.Cu")
		(net "PVDDCR_CPU0_P0_EN")
	)
	(segment
		(start 372.537228 -140.048742)
		(end 372.452138 -139.963652)
		(width 0.10668)
		(layer "F.Cu")
		(net "PVDDCR_CPU0_P0_EN")
	)
	(segment
		(start 369.997228 -116.124228)
		(end 369.951 -116.078)
		(width 0.10668)
		(layer "F.Cu")
		(net "PVDDCR_CPU0_P0_EN")
	)
	(via
		(at 369.951 -116.078)
		(size 0.508)
		(drill 0.254)
		(layers "F.Cu" "B.Cu")
		(net "PVDDCR_CPU0_P0_EN")
	)
	(via
		(at 177.532284 -119.842788)
		(size 0.4572)
		(drill 0.254)
		(layers "F.Cu" "B.Cu")
		(net "PVDDCR_CPU0_P0_EN")
	)
	(segment
		(start 276.525228 -111.303308)
		(end 297.71213 -111.303308)
		(width 0.11684)
		(layer "In6.Cu")
		(net "PVDDCR_CPU0_P0_EN")
	)
	(segment
		(start 189.32144 -117.848888)
		(end 197.492112 -117.848888)
		(width 0.11684)
		(layer "In6.Cu")
		(net "PVDDCR_CPU0_P0_EN")
	)
	(segment
		(start 188.90996 -118.646448)
		(end 189.12078 -118.435628)
		(width 0.11684)
		(layer "In6.Cu")
		(net "PVDDCR_CPU0_P0_EN")
	)
	(segment
		(start 276.032468 -110.810548)
		(end 276.525228 -111.303308)
		(width 0.11684)
		(layer "In6.Cu")
		(net "PVDDCR_CPU0_P0_EN")
	)
	(segment
		(start 197.492112 -117.848888)
		(end 198.124572 -117.216428)
		(width 0.11684)
		(layer "In6.Cu")
		(net "PVDDCR_CPU0_P0_EN")
	)
	(segment
		(start 177.938938 -120.249442)
		(end 185.084466 -120.249442)
		(width 0.11684)
		(layer "In6.Cu")
		(net "PVDDCR_CPU0_P0_EN")
	)
	(segment
		(start 201.081894 -116.181632)
		(end 204.809344 -116.181632)
		(width 0.11684)
		(layer "In6.Cu")
		(net "PVDDCR_CPU0_P0_EN")
	)
	(segment
		(start 305.69789 -112.12195)
		(end 318.278002 -112.12195)
		(width 0.11684)
		(layer "In6.Cu")
		(net "PVDDCR_CPU0_P0_EN")
	)
	(segment
		(start 233.7943 -113.426748)
		(end 247.523 -113.426748)
		(width 0.11684)
		(layer "In6.Cu")
		(net "PVDDCR_CPU0_P0_EN")
	)
	(segment
		(start 304.886868 -111.310928)
		(end 305.69789 -112.12195)
		(width 0.11684)
		(layer "In6.Cu")
		(net "PVDDCR_CPU0_P0_EN")
	)
	(segment
		(start 189.12078 -118.049548)
		(end 189.32144 -117.848888)
		(width 0.11684)
		(layer "In6.Cu")
		(net "PVDDCR_CPU0_P0_EN")
	)
	(segment
		(start 301.018194 -111.310928)
		(end 304.886868 -111.310928)
		(width 0.11684)
		(layer "In6.Cu")
		(net "PVDDCR_CPU0_P0_EN")
	)
	(segment
		(start 274.195032 -111.851948)
		(end 275.236432 -110.810548)
		(width 0.11684)
		(layer "In6.Cu")
		(net "PVDDCR_CPU0_P0_EN")
	)
	(segment
		(start 223.109536 -117.65534)
		(end 223.89846 -116.866416)
		(width 0.11684)
		(layer "In6.Cu")
		(net "PVDDCR_CPU0_P0_EN")
	)
	(segment
		(start 275.236432 -110.810548)
		(end 276.032468 -110.810548)
		(width 0.11684)
		(layer "In6.Cu")
		(net "PVDDCR_CPU0_P0_EN")
	)
	(segment
		(start 230.354632 -116.866416)
		(end 233.7943 -113.426748)
		(width 0.11684)
		(layer "In6.Cu")
		(net "PVDDCR_CPU0_P0_EN")
	)
	(segment
		(start 200.047098 -117.216428)
		(end 201.081894 -116.181632)
		(width 0.11684)
		(layer "In6.Cu")
		(net "PVDDCR_CPU0_P0_EN")
	)
	(segment
		(start 367.716308 -114.859308)
		(end 368.935 -116.078)
		(width 0.11684)
		(layer "In6.Cu")
		(net "PVDDCR_CPU0_P0_EN")
	)
	(segment
		(start 185.515504 -119.213884)
		(end 186.08294 -118.646448)
		(width 0.11684)
		(layer "In6.Cu")
		(net "PVDDCR_CPU0_P0_EN")
	)
	(segment
		(start 249.0978 -111.851948)
		(end 274.195032 -111.851948)
		(width 0.11684)
		(layer "In6.Cu")
		(net "PVDDCR_CPU0_P0_EN")
	)
	(segment
		(start 301.010574 -111.303308)
		(end 301.018194 -111.310928)
		(width 0.11684)
		(layer "In6.Cu")
		(net "PVDDCR_CPU0_P0_EN")
	)
	(segment
		(start 300.543976 -111.303308)
		(end 301.010574 -111.303308)
		(width 0.11684)
		(layer "In6.Cu")
		(net "PVDDCR_CPU0_P0_EN")
	)
	(segment
		(start 185.084466 -120.249442)
		(end 185.515504 -119.818404)
		(width 0.11684)
		(layer "In6.Cu")
		(net "PVDDCR_CPU0_P0_EN")
	)
	(segment
		(start 321.01536 -114.859308)
		(end 367.716308 -114.859308)
		(width 0.11684)
		(layer "In6.Cu")
		(net "PVDDCR_CPU0_P0_EN")
	)
	(segment
		(start 213.870032 -117.65534)
		(end 223.109536 -117.65534)
		(width 0.11684)
		(layer "In6.Cu")
		(net "PVDDCR_CPU0_P0_EN")
	)
	(segment
		(start 189.12078 -118.435628)
		(end 189.12078 -118.049548)
		(width 0.11684)
		(layer "In6.Cu")
		(net "PVDDCR_CPU0_P0_EN")
	)
	(segment
		(start 213.43112 -117.216428)
		(end 213.870032 -117.65534)
		(width 0.11684)
		(layer "In6.Cu")
		(net "PVDDCR_CPU0_P0_EN")
	)
	(segment
		(start 204.809344 -116.181632)
		(end 205.84414 -117.216428)
		(width 0.11684)
		(layer "In6.Cu")
		(net "PVDDCR_CPU0_P0_EN")
	)
	(segment
		(start 198.124572 -117.216428)
		(end 200.047098 -117.216428)
		(width 0.11684)
		(layer "In6.Cu")
		(net "PVDDCR_CPU0_P0_EN")
	)
	(segment
		(start 300.179994 -111.66729)
		(end 300.543976 -111.303308)
		(width 0.11684)
		(layer "In6.Cu")
		(net "PVDDCR_CPU0_P0_EN")
	)
	(segment
		(start 368.935 -116.078)
		(end 369.951 -116.078)
		(width 0.11684)
		(layer "In6.Cu")
		(net "PVDDCR_CPU0_P0_EN")
	)
	(segment
		(start 298.076112 -111.66729)
		(end 300.179994 -111.66729)
		(width 0.11684)
		(layer "In6.Cu")
		(net "PVDDCR_CPU0_P0_EN")
	)
	(segment
		(start 297.71213 -111.303308)
		(end 298.076112 -111.66729)
		(width 0.11684)
		(layer "In6.Cu")
		(net "PVDDCR_CPU0_P0_EN")
	)
	(segment
		(start 177.532284 -119.842788)
		(end 177.938938 -120.249442)
		(width 0.11684)
		(layer "In6.Cu")
		(net "PVDDCR_CPU0_P0_EN")
	)
	(segment
		(start 223.89846 -116.866416)
		(end 230.354632 -116.866416)
		(width 0.11684)
		(layer "In6.Cu")
		(net "PVDDCR_CPU0_P0_EN")
	)
	(segment
		(start 247.523 -113.426748)
		(end 249.0978 -111.851948)
		(width 0.11684)
		(layer "In6.Cu")
		(net "PVDDCR_CPU0_P0_EN")
	)
	(segment
		(start 318.278002 -112.12195)
		(end 321.01536 -114.859308)
		(width 0.11684)
		(layer "In6.Cu")
		(net "PVDDCR_CPU0_P0_EN")
	)
	(segment
		(start 205.84414 -117.216428)
		(end 213.43112 -117.216428)
		(width 0.11684)
		(layer "In6.Cu")
		(net "PVDDCR_CPU0_P0_EN")
	)
	(segment
		(start 186.08294 -118.646448)
		(end 188.90996 -118.646448)
		(width 0.11684)
		(layer "In6.Cu")
		(net "PVDDCR_CPU0_P0_EN")
	)
	(segment
		(start 185.515504 -119.818404)
		(end 185.515504 -119.213884)
		(width 0.11684)
		(layer "In6.Cu")
		(net "PVDDCR_CPU0_P0_EN")
	)
	(segment
		(start 367.238026 -230.97998)
		(end 367.704878 -230.714296)
		(width 0.350012)
		(layer "F.Cu")
		(net "PVDDCR_CPU0_P0")
	)
	(segment
		(start 354.547932 -249.610118)
		(end 354.08108 -249.34418)
		(width 0.350012)
		(layer "F.Cu")
		(net "PVDDCR_CPU0_P0")
	)
	(segment
		(start 357.36784 -243.13007)
		(end 356.901242 -242.864132)
		(width 0.350012)
		(layer "F.Cu")
		(net "PVDDCR_CPU0_P0")
	)
	(segment
		(start 354.078032 -222.880174)
		(end 353.61118 -222.614236)
		(width 0.350012)
		(layer "F.Cu")
		(net "PVDDCR_CPU0_P0")
	)
	(segment
		(start 372.877842 -242.320064)
		(end 373.344694 -242.054126)
		(width 0.350012)
		(layer "F.Cu")
		(net "PVDDCR_CPU0_P0")
	)
	(segment
		(start 346.557854 -242.320064)
		(end 346.091002 -242.054126)
		(width 0.350012)
		(layer "F.Cu")
		(net "PVDDCR_CPU0_P0")
	)
	(segment
		(start 348.437962 -239.08004)
		(end 347.97111 -238.814102)
		(width 0.350012)
		(layer "F.Cu")
		(net "PVDDCR_CPU0_P0")
	)
	(segment
		(start 362.067856 -225.310192)
		(end 362.534708 -225.044254)
		(width 0.350012)
		(layer "F.Cu")
		(net "PVDDCR_CPU0_P0")
	)
	(segment
		(start 367.238026 -234.220004)
		(end 367.704878 -233.954066)
		(width 0.350012)
		(layer "F.Cu")
		(net "PVDDCR_CPU0_P0")
	)
	(segment
		(start 351.25787 -230.97998)
		(end 350.791018 -230.714042)
		(width 0.350012)
		(layer "F.Cu")
		(net "PVDDCR_CPU0_P0")
	)
	(segment
		(start 362.067856 -235.03001)
		(end 362.534708 -234.764072)
		(width 0.350012)
		(layer "F.Cu")
		(net "PVDDCR_CPU0_P0")
	)
	(segment
		(start 346.557854 -227.74021)
		(end 346.091002 -227.474272)
		(width 0.350012)
		(layer "F.Cu")
		(net "PVDDCR_CPU0_P0")
	)
	(segment
		(start 377.577858 -222.880174)
		(end 378.04471 -222.614236)
		(width 0.350012)
		(layer "F.Cu")
		(net "PVDDCR_CPU0_P0")
	)
	(segment
		(start 348.437962 -242.320064)
		(end 347.97111 -242.054126)
		(width 0.350012)
		(layer "F.Cu")
		(net "PVDDCR_CPU0_P0")
	)
	(segment
		(start 353.137978 -222.880174)
		(end 352.671126 -222.614236)
		(width 0.350012)
		(layer "F.Cu")
		(net "PVDDCR_CPU0_P0")
	)
	(segment
		(start 362.067856 -239.890046)
		(end 362.534708 -239.624108)
		(width 0.350012)
		(layer "F.Cu")
		(net "PVDDCR_CPU0_P0")
	)
	(segment
		(start 354.078032 -242.320064)
		(end 353.61118 -242.054126)
		(width 0.350012)
		(layer "F.Cu")
		(net "PVDDCR_CPU0_P0")
	)
	(segment
		(start 354.078032 -230.97998)
		(end 353.61118 -230.714296)
		(width 0.350012)
		(layer "F.Cu")
		(net "PVDDCR_CPU0_P0")
	)
	(segment
		(start 355.018086 -230.97998)
		(end 354.551234 -230.714296)
		(width 0.350012)
		(layer "F.Cu")
		(net "PVDDCR_CPU0_P0")
	)
	(segment
		(start 372.877842 -250.420124)
		(end 373.344694 -250.154186)
		(width 0.350012)
		(layer "F.Cu")
		(net "PVDDCR_CPU0_P0")
	)
	(segment
		(start 353.607878 -225.310192)
		(end 353.141026 -225.044254)
		(width 0.350012)
		(layer "F.Cu")
		(net "PVDDCR_CPU0_P0")
	)
	(segment
		(start 351.25787 -242.320064)
		(end 350.791018 -242.054126)
		(width 0.350012)
		(layer "F.Cu")
		(net "PVDDCR_CPU0_P0")
	)
	(segment
		(start 357.837994 -237.460028)
		(end 357.371142 -237.19409)
		(width 0.350012)
		(layer "F.Cu")
		(net "PVDDCR_CPU0_P0")
	)
	(segment
		(start 342.930988 -172.311822)
		(end 343.096088 -172.146722)
		(width 0.254)
		(layer "F.Cu")
		(net "PVDDCR_CPU0_P0")
	)
	(segment
		(start 372.877842 -227.74021)
		(end 373.344694 -227.474272)
		(width 0.350012)
		(layer "F.Cu")
		(net "PVDDCR_CPU0_P0")
	)
	(segment
		(start 368.17808 -230.97998)
		(end 368.644678 -230.714296)
		(width 0.350012)
		(layer "F.Cu")
		(net "PVDDCR_CPU0_P0")
	)
	(segment
		(start 357.36784 -231.789986)
		(end 356.901242 -231.524048)
		(width 0.350012)
		(layer "F.Cu")
		(net "PVDDCR_CPU0_P0")
	)
	(segment
		(start 365.828072 -249.610118)
		(end 366.294924 -249.34418)
		(width 0.350012)
		(layer "F.Cu")
		(net "PVDDCR_CPU0_P0")
	)
	(segment
		(start 365.357918 -234.220004)
		(end 365.82477 -233.954066)
		(width 0.350012)
		(layer "F.Cu")
		(net "PVDDCR_CPU0_P0")
	)
	(segment
		(start 345.618054 -239.08004)
		(end 345.151202 -238.814102)
		(width 0.350012)
		(layer "F.Cu")
		(net "PVDDCR_CPU0_P0")
	)
	(segment
		(start 356.89794 -250.420124)
		(end 356.431088 -250.154186)
		(width 0.350012)
		(layer "F.Cu")
		(net "PVDDCR_CPU0_P0")
	)
	(segment
		(start 349.378016 -227.74021)
		(end 348.911164 -227.474272)
		(width 0.350012)
		(layer "F.Cu")
		(net "PVDDCR_CPU0_P0")
	)
	(segment
		(start 352.668078 -251.23013)
		(end 352.201226 -250.964192)
		(width 0.350012)
		(layer "F.Cu")
		(net "PVDDCR_CPU0_P0")
	)
	(segment
		(start 350.78797 -251.23013)
		(end 350.321118 -250.964192)
		(width 0.350012)
		(layer "F.Cu")
		(net "PVDDCR_CPU0_P0")
	)
	(segment
		(start 372.877842 -230.97998)
		(end 373.344694 -230.714296)
		(width 0.350012)
		(layer "F.Cu")
		(net "PVDDCR_CPU0_P0")
	)
	(segment
		(start 363.478064 -222.880174)
		(end 363.944916 -222.614236)
		(width 0.350012)
		(layer "F.Cu")
		(net "PVDDCR_CPU0_P0")
	)
	(segment
		(start 362.53801 -222.880174)
		(end 363.004862 -222.614236)
		(width 0.350012)
		(layer "F.Cu")
		(net "PVDDCR_CPU0_P0")
	)
	(segment
		(start 350.31807 -222.880174)
		(end 349.851218 -222.614236)
		(width 0.350012)
		(layer "F.Cu")
		(net "PVDDCR_CPU0_P0")
	)
	(segment
		(start 367.707926 -251.23013)
		(end 368.174778 -250.964192)
		(width 0.350012)
		(layer "F.Cu")
		(net "PVDDCR_CPU0_P0")
	)
	(segment
		(start 352.197924 -227.74021)
		(end 351.731072 -227.474272)
		(width 0.350012)
		(layer "F.Cu")
		(net "PVDDCR_CPU0_P0")
	)
	(segment
		(start 370.057934 -245.560088)
		(end 370.524786 -245.29415)
		(width 0.350012)
		(layer "F.Cu")
		(net "PVDDCR_CPU0_P0")
	)
	(segment
		(start 351.25787 -250.420124)
		(end 350.791018 -250.154186)
		(width 0.350012)
		(layer "F.Cu")
		(net "PVDDCR_CPU0_P0")
	)
	(segment
		(start 355.487986 -236.650022)
		(end 355.021134 -236.384084)
		(width 0.350012)
		(layer "F.Cu")
		(net "PVDDCR_CPU0_P0")
	)
	(segment
		(start 342.797892 -222.880174)
		(end 342.33104 -222.614236)
		(width 0.350012)
		(layer "F.Cu")
		(net "PVDDCR_CPU0_P0")
	)
	(segment
		(start 363.947964 -249.610118)
		(end 364.414816 -249.34418)
		(width 0.350012)
		(layer "F.Cu")
		(net "PVDDCR_CPU0_P0")
	)
	(segment
		(start 367.707926 -236.650022)
		(end 368.174778 -236.384084)
		(width 0.350012)
		(layer "F.Cu")
		(net "PVDDCR_CPU0_P0")
	)
	(segment
		(start 352.197924 -248.800112)
		(end 351.731072 -248.534174)
		(width 0.350012)
		(layer "F.Cu")
		(net "PVDDCR_CPU0_P0")
	)
	(segment
		(start 358.307894 -231.789986)
		(end 357.841042 -231.524048)
		(width 0.350012)
		(layer "F.Cu")
		(net "PVDDCR_CPU0_P0")
	)
	(segment
		(start 370.997988 -242.320064)
		(end 371.46484 -242.054126)
		(width 0.350012)
		(layer "F.Cu")
		(net "PVDDCR_CPU0_P0")
	)
	(segment
		(start 363.478064 -250.420124)
		(end 363.944916 -250.154186)
		(width 0.350012)
		(layer "F.Cu")
		(net "PVDDCR_CPU0_P0")
	)
	(segment
		(start 349.378016 -234.220004)
		(end 348.911164 -233.954066)
		(width 0.350012)
		(layer "F.Cu")
		(net "PVDDCR_CPU0_P0")
	)
	(segment
		(start 355.018086 -242.320064)
		(end 354.551234 -242.054126)
		(width 0.350012)
		(layer "F.Cu")
		(net "PVDDCR_CPU0_P0")
	)
	(segment
		(start 341.978234 -172.311822)
		(end 342.930988 -172.311822)
		(width 0.254)
		(layer "F.Cu")
		(net "PVDDCR_CPU0_P0")
	)
	(segment
		(start 348.437962 -230.97998)
		(end 347.97111 -230.714296)
		(width 0.350012)
		(layer "F.Cu")
		(net "PVDDCR_CPU0_P0")
	)
	(segment
		(start 352.197924 -230.97998)
		(end 351.731072 -230.714296)
		(width 0.350012)
		(layer "F.Cu")
		(net "PVDDCR_CPU0_P0")
	)
	(segment
		(start 349.378016 -248.800112)
		(end 348.911164 -248.534174)
		(width 0.350012)
		(layer "F.Cu")
		(net "PVDDCR_CPU0_P0")
	)
	(segment
		(start 349.378016 -239.08004)
		(end 348.911164 -238.814102)
		(width 0.350012)
		(layer "F.Cu")
		(net "PVDDCR_CPU0_P0")
	)
	(segment
		(start 347.497908 -226.120198)
		(end 347.031056 -225.85426)
		(width 0.350012)
		(layer "F.Cu")
		(net "PVDDCR_CPU0_P0")
	)
	(segment
		(start 351.25787 -222.880174)
		(end 350.791018 -222.614236)
		(width 0.350012)
		(layer "F.Cu")
		(net "PVDDCR_CPU0_P0")
	)
	(segment
		(start 354.078032 -239.08004)
		(end 353.61118 -238.814102)
		(width 0.350012)
		(layer "F.Cu")
		(net "PVDDCR_CPU0_P0")
	)
	(segment
		(start 345.618054 -245.560088)
		(end 345.151202 -245.29415)
		(width 0.350012)
		(layer "F.Cu")
		(net "PVDDCR_CPU0_P0")
	)
	(segment
		(start 362.067856 -231.789986)
		(end 362.534708 -231.524048)
		(width 0.350012)
		(layer "F.Cu")
		(net "PVDDCR_CPU0_P0")
	)
	(segment
		(start 376.167904 -223.69018)
		(end 376.634756 -223.424242)
		(width 0.350012)
		(layer "F.Cu")
		(net "PVDDCR_CPU0_P0")
	)
	(segment
		(start 373.347996 -249.610118)
		(end 373.814848 -249.34418)
		(width 0.350012)
		(layer "F.Cu")
		(net "PVDDCR_CPU0_P0")
	)
	(segment
		(start 374.75795 -226.120198)
		(end 375.224802 -225.85426)
		(width 0.350012)
		(layer "F.Cu")
		(net "PVDDCR_CPU0_P0")
	)
	(segment
		(start 352.197924 -245.560088)
		(end 351.731072 -245.29415)
		(width 0.350012)
		(layer "F.Cu")
		(net "PVDDCR_CPU0_P0")
	)
	(segment
		(start 365.357918 -227.74021)
		(end 365.82477 -227.474272)
		(width 0.350012)
		(layer "F.Cu")
		(net "PVDDCR_CPU0_P0")
	)
	(segment
		(start 365.828072 -225.310192)
		(end 366.294924 -225.044254)
		(width 0.350012)
		(layer "F.Cu")
		(net "PVDDCR_CPU0_P0")
	)
	(segment
		(start 368.17808 -234.220004)
		(end 368.644678 -233.954066)
		(width 0.350012)
		(layer "F.Cu")
		(net "PVDDCR_CPU0_P0")
	)
	(segment
		(start 364.417864 -242.320064)
		(end 364.884716 -242.054126)
		(width 0.350012)
		(layer "F.Cu")
		(net "PVDDCR_CPU0_P0")
	)
	(segment
		(start 349.378016 -230.97998)
		(end 348.911164 -230.714296)
		(width 0.350012)
		(layer "F.Cu")
		(net "PVDDCR_CPU0_P0")
	)
	(segment
		(start 369.11788 -250.420124)
		(end 369.584732 -250.154186)
		(width 0.350012)
		(layer "F.Cu")
		(net "PVDDCR_CPU0_P0")
	)
	(segment
		(start 347.497908 -222.880174)
		(end 347.031056 -222.614236)
		(width 0.350012)
		(layer "F.Cu")
		(net "PVDDCR_CPU0_P0")
	)
	(segment
		(start 349.378016 -245.560088)
		(end 348.911164 -245.29415)
		(width 0.350012)
		(layer "F.Cu")
		(net "PVDDCR_CPU0_P0")
	)
	(segment
		(start 357.36784 -228.550216)
		(end 356.901242 -228.284278)
		(width 0.350012)
		(layer "F.Cu")
		(net "PVDDCR_CPU0_P0")
	)
	(segment
		(start 346.557854 -245.560088)
		(end 346.091002 -245.29415)
		(width 0.350012)
		(layer "F.Cu")
		(net "PVDDCR_CPU0_P0")
	)
	(segment
		(start 361.128056 -235.03001)
		(end 361.594908 -234.764072)
		(width 0.350012)
		(layer "F.Cu")
		(net "PVDDCR_CPU0_P0")
	)
	(segment
		(start 345.618054 -248.800112)
		(end 345.151202 -248.534174)
		(width 0.350012)
		(layer "F.Cu")
		(net "PVDDCR_CPU0_P0")
	)
	(segment
		(start 367.707926 -249.610118)
		(end 368.174778 -249.34418)
		(width 0.350012)
		(layer "F.Cu")
		(net "PVDDCR_CPU0_P0")
	)
	(segment
		(start 355.018086 -248.800112)
		(end 354.551234 -248.534174)
		(width 0.350012)
		(layer "F.Cu")
		(net "PVDDCR_CPU0_P0")
	)
	(segment
		(start 344.678 -222.880174)
		(end 344.211148 -222.614236)
		(width 0.350012)
		(layer "F.Cu")
		(net "PVDDCR_CPU0_P0")
	)
	(segment
		(start 369.11788 -222.880174)
		(end 369.584732 -222.614236)
		(width 0.350012)
		(layer "F.Cu")
		(net "PVDDCR_CPU0_P0")
	)
	(segment
		(start 354.078032 -227.74021)
		(end 353.61118 -227.474272)
		(width 0.350012)
		(layer "F.Cu")
		(net "PVDDCR_CPU0_P0")
	)
	(segment
		(start 365.357918 -222.880174)
		(end 365.82477 -222.614236)
		(width 0.350012)
		(layer "F.Cu")
		(net "PVDDCR_CPU0_P0")
	)
	(segment
		(start 348.437962 -234.220004)
		(end 347.97111 -233.954066)
		(width 0.350012)
		(layer "F.Cu")
		(net "PVDDCR_CPU0_P0")
	)
	(segment
		(start 368.17808 -248.800112)
		(end 368.644678 -248.534174)
		(width 0.350012)
		(layer "F.Cu")
		(net "PVDDCR_CPU0_P0")
	)
	(segment
		(start 347.968062 -225.310192)
		(end 347.50121 -225.044254)
		(width 0.350012)
		(layer "F.Cu")
		(net "PVDDCR_CPU0_P0")
	)
	(segment
		(start 373.817896 -227.74021)
		(end 374.284748 -227.474272)
		(width 0.350012)
		(layer "F.Cu")
		(net "PVDDCR_CPU0_P0")
	)
	(segment
		(start 372.877842 -234.220004)
		(end 373.344694 -233.954066)
		(width 0.350012)
		(layer "F.Cu")
		(net "PVDDCR_CPU0_P0")
	)
	(segment
		(start 355.018086 -234.220004)
		(end 354.551234 -233.954066)
		(width 0.350012)
		(layer "F.Cu")
		(net "PVDDCR_CPU0_P0")
	)
	(segment
		(start 348.437962 -227.74021)
		(end 347.97111 -227.474272)
		(width 0.350012)
		(layer "F.Cu")
		(net "PVDDCR_CPU0_P0")
	)
	(segment
		(start 357.36784 -235.03001)
		(end 356.901242 -234.764072)
		(width 0.350012)
		(layer "F.Cu")
		(net "PVDDCR_CPU0_P0")
	)
	(segment
		(start 370.057934 -239.08004)
		(end 370.524786 -238.814102)
		(width 0.350012)
		(layer "F.Cu")
		(net "PVDDCR_CPU0_P0")
	)
	(segment
		(start 374.75795 -222.880174)
		(end 375.224802 -222.614236)
		(width 0.350012)
		(layer "F.Cu")
		(net "PVDDCR_CPU0_P0")
	)
	(segment
		(start 361.128056 -228.550216)
		(end 361.594908 -228.284278)
		(width 0.350012)
		(layer "F.Cu")
		(net "PVDDCR_CPU0_P0")
	)
	(segment
		(start 348.437962 -245.560088)
		(end 347.97111 -245.29415)
		(width 0.350012)
		(layer "F.Cu")
		(net "PVDDCR_CPU0_P0")
	)
	(segment
		(start 358.307894 -249.610118)
		(end 357.841042 -249.34418)
		(width 0.350012)
		(layer "F.Cu")
		(net "PVDDCR_CPU0_P0")
	)
	(segment
		(start 368.17808 -227.74021)
		(end 368.644932 -227.474272)
		(width 0.350012)
		(layer "F.Cu")
		(net "PVDDCR_CPU0_P0")
	)
	(segment
		(start 344.678 -226.120198)
		(end 344.211148 -225.85426)
		(width 0.350012)
		(layer "F.Cu")
		(net "PVDDCR_CPU0_P0")
	)
	(segment
		(start 356.42804 -225.310192)
		(end 355.961188 -225.044254)
		(width 0.350012)
		(layer "F.Cu")
		(net "PVDDCR_CPU0_P0")
	)
	(segment
		(start 346.557854 -230.97998)
		(end 346.091002 -230.714296)
		(width 0.350012)
		(layer "F.Cu")
		(net "PVDDCR_CPU0_P0")
	)
	(segment
		(start 364.417864 -234.220004)
		(end 364.884716 -233.954066)
		(width 0.350012)
		(layer "F.Cu")
		(net "PVDDCR_CPU0_P0")
	)
	(segment
		(start 372.877842 -245.560088)
		(end 373.344694 -245.29415)
		(width 0.350012)
		(layer "F.Cu")
		(net "PVDDCR_CPU0_P0")
	)
	(segment
		(start 367.238026 -227.74021)
		(end 367.704878 -227.474272)
		(width 0.350012)
		(layer "F.Cu")
		(net "PVDDCR_CPU0_P0")
	)
	(segment
		(start 370.057934 -230.97998)
		(end 370.524786 -230.714296)
		(width 0.350012)
		(layer "F.Cu")
		(net "PVDDCR_CPU0_P0")
	)
	(segment
		(start 369.11788 -226.120198)
		(end 369.584732 -225.85426)
		(width 0.350012)
		(layer "F.Cu")
		(net "PVDDCR_CPU0_P0")
	)
	(segment
		(start 362.067856 -243.13007)
		(end 362.534708 -242.864132)
		(width 0.350012)
		(layer "F.Cu")
		(net "PVDDCR_CPU0_P0")
	)
	(segment
		(start 351.728024 -236.650022)
		(end 351.261172 -236.384084)
		(width 0.350012)
		(layer "F.Cu")
		(net "PVDDCR_CPU0_P0")
	)
	(segment
		(start 364.417864 -227.74021)
		(end 364.884716 -227.474272)
		(width 0.350012)
		(layer "F.Cu")
		(net "PVDDCR_CPU0_P0")
	)
	(segment
		(start 371.938042 -226.120198)
		(end 372.404894 -225.85426)
		(width 0.350012)
		(layer "F.Cu")
		(net "PVDDCR_CPU0_P0")
	)
	(segment
		(start 373.817896 -242.320064)
		(end 374.284748 -242.054126)
		(width 0.350012)
		(layer "F.Cu")
		(net "PVDDCR_CPU0_P0")
	)
	(segment
		(start 355.018086 -250.420124)
		(end 354.551234 -250.154186)
		(width 0.350012)
		(layer "F.Cu")
		(net "PVDDCR_CPU0_P0")
	)
	(segment
		(start 365.357918 -248.800112)
		(end 365.82477 -248.534174)
		(width 0.350012)
		(layer "F.Cu")
		(net "PVDDCR_CPU0_P0")
	)
	(segment
		(start 366.297972 -222.880174)
		(end 366.764824 -222.614236)
		(width 0.350012)
		(layer "F.Cu")
		(net "PVDDCR_CPU0_P0")
	)
	(segment
		(start 351.25787 -239.08004)
		(end 350.791018 -238.814102)
		(width 0.350012)
		(layer "F.Cu")
		(net "PVDDCR_CPU0_P0")
	)
	(segment
		(start 358.307894 -228.550216)
		(end 357.841042 -228.284278)
		(width 0.350012)
		(layer "F.Cu")
		(net "PVDDCR_CPU0_P0")
	)
	(segment
		(start 343.096088 -172.146722)
		(end 344.037158 -173.087792)
		(width 0.254)
		(layer "F.Cu")
		(net "PVDDCR_CPU0_P0")
	)
	(segment
		(start 366.767872 -236.650022)
		(end 367.234724 -236.384084)
		(width 0.350012)
		(layer "F.Cu")
		(net "PVDDCR_CPU0_P0")
	)
	(segment
		(start 355.018086 -227.74021)
		(end 354.551234 -227.474272)
		(width 0.350012)
		(layer "F.Cu")
		(net "PVDDCR_CPU0_P0")
	)
	(segment
		(start 358.307894 -246.370094)
		(end 357.841042 -246.104156)
		(width 0.350012)
		(layer "F.Cu")
		(net "PVDDCR_CPU0_P0")
	)
	(segment
		(start 362.53801 -237.460028)
		(end 363.004862 -237.19409)
		(width 0.350012)
		(layer "F.Cu")
		(net "PVDDCR_CPU0_P0")
	)
	(segment
		(start 350.31807 -226.120198)
		(end 349.850964 -225.85426)
		(width 0.350012)
		(layer "F.Cu")
		(net "PVDDCR_CPU0_P0")
	)
	(segment
		(start 345.618054 -230.97998)
		(end 345.151202 -230.714296)
		(width 0.350012)
		(layer "F.Cu")
		(net "PVDDCR_CPU0_P0")
	)
	(segment
		(start 364.417864 -245.560088)
		(end 364.884716 -245.29415)
		(width 0.350012)
		(layer "F.Cu")
		(net "PVDDCR_CPU0_P0")
	)
	(segment
		(start 370.057934 -248.800112)
		(end 370.524786 -248.534174)
		(width 0.350012)
		(layer "F.Cu")
		(net "PVDDCR_CPU0_P0")
	)
	(segment
		(start 361.597956 -250.420124)
		(end 362.064808 -250.154186)
		(width 0.350012)
		(layer "F.Cu")
		(net "PVDDCR_CPU0_P0")
	)
	(segment
		(start 348.907862 -249.610118)
		(end 348.44101 -249.34418)
		(width 0.350012)
		(layer "F.Cu")
		(net "PVDDCR_CPU0_P0")
	)
	(segment
		(start 345.618054 -234.220004)
		(end 345.151202 -233.954066)
		(width 0.350012)
		(layer "F.Cu")
		(net "PVDDCR_CPU0_P0")
	)
	(segment
		(start 353.137978 -226.120198)
		(end 352.671126 -225.85426)
		(width 0.350012)
		(layer "F.Cu")
		(net "PVDDCR_CPU0_P0")
	)
	(segment
		(start 354.078032 -234.220004)
		(end 353.61118 -233.954066)
		(width 0.350012)
		(layer "F.Cu")
		(net "PVDDCR_CPU0_P0")
	)
	(segment
		(start 370.997988 -239.08004)
		(end 371.46484 -238.814102)
		(width 0.350012)
		(layer "F.Cu")
		(net "PVDDCR_CPU0_P0")
	)
	(segment
		(start 350.78797 -249.610118)
		(end 350.321118 -249.34418)
		(width 0.350012)
		(layer "F.Cu")
		(net "PVDDCR_CPU0_P0")
	)
	(segment
		(start 366.297972 -226.120198)
		(end 366.764824 -225.85426)
		(width 0.350012)
		(layer "F.Cu")
		(net "PVDDCR_CPU0_P0")
	)
	(segment
		(start 341.857838 -222.880174)
		(end 341.390986 -222.614236)
		(width 0.350012)
		(layer "F.Cu")
		(net "PVDDCR_CPU0_P0")
	)
	(segment
		(start 358.307894 -235.03001)
		(end 357.841042 -234.764072)
		(width 0.350012)
		(layer "F.Cu")
		(net "PVDDCR_CPU0_P0")
	)
	(segment
		(start 356.42804 -251.23013)
		(end 355.961188 -250.964192)
		(width 0.350012)
		(layer "F.Cu")
		(net "PVDDCR_CPU0_P0")
	)
	(segment
		(start 343.737946 -224.500186)
		(end 343.271094 -224.234248)
		(width 0.350012)
		(layer "F.Cu")
		(net "PVDDCR_CPU0_P0")
	)
	(segment
		(start 352.197924 -234.220004)
		(end 351.731072 -233.954066)
		(width 0.350012)
		(layer "F.Cu")
		(net "PVDDCR_CPU0_P0")
	)
	(segment
		(start 373.817896 -234.220004)
		(end 374.284748 -233.954066)
		(width 0.350012)
		(layer "F.Cu")
		(net "PVDDCR_CPU0_P0")
	)
	(segment
		(start 349.378016 -242.320064)
		(end 348.911164 -242.054126)
		(width 0.350012)
		(layer "F.Cu")
		(net "PVDDCR_CPU0_P0")
	)
	(segment
		(start 362.067856 -226.930204)
		(end 362.534708 -226.664266)
		(width 0.350012)
		(layer "F.Cu")
		(net "PVDDCR_CPU0_P0")
	)
	(segment
		(start 376.638058 -222.880174)
		(end 377.10491 -222.614236)
		(width 0.350012)
		(layer "F.Cu")
		(net "PVDDCR_CPU0_P0")
	)
	(segment
		(start 370.997988 -234.220004)
		(end 371.46484 -233.954066)
		(width 0.350012)
		(layer "F.Cu")
		(net "PVDDCR_CPU0_P0")
	)
	(segment
		(start 348.437962 -248.800112)
		(end 347.97111 -248.534174)
		(width 0.350012)
		(layer "F.Cu")
		(net "PVDDCR_CPU0_P0")
	)
	(segment
		(start 350.78797 -225.310192)
		(end 350.320864 -225.044254)
		(width 0.350012)
		(layer "F.Cu")
		(net "PVDDCR_CPU0_P0")
	)
	(segment
		(start 361.128056 -239.890046)
		(end 361.594908 -239.624108)
		(width 0.350012)
		(layer "F.Cu")
		(net "PVDDCR_CPU0_P0")
	)
	(segment
		(start 361.128056 -243.13007)
		(end 361.594908 -242.864132)
		(width 0.350012)
		(layer "F.Cu")
		(net "PVDDCR_CPU0_P0")
	)
	(segment
		(start 351.25787 -248.800112)
		(end 350.791018 -248.534174)
		(width 0.350012)
		(layer "F.Cu")
		(net "PVDDCR_CPU0_P0")
	)
	(segment
		(start 370.997988 -248.800112)
		(end 371.46484 -248.534174)
		(width 0.350012)
		(layer "F.Cu")
		(net "PVDDCR_CPU0_P0")
	)
	(segment
		(start 369.588034 -249.610118)
		(end 370.054886 -249.34418)
		(width 0.350012)
		(layer "F.Cu")
		(net "PVDDCR_CPU0_P0")
	)
	(segment
		(start 374.28805 -225.310192)
		(end 374.754902 -225.044254)
		(width 0.350012)
		(layer "F.Cu")
		(net "PVDDCR_CPU0_P0")
	)
	(segment
		(start 367.238026 -248.800112)
		(end 367.704878 -248.534174)
		(width 0.350012)
		(layer "F.Cu")
		(net "PVDDCR_CPU0_P0")
	)
	(segment
		(start 362.067856 -228.550216)
		(end 362.534708 -228.284278)
		(width 0.350012)
		(layer "F.Cu")
		(net "PVDDCR_CPU0_P0")
	)
	(segment
		(start 345.618054 -242.320064)
		(end 345.151202 -242.054126)
		(width 0.350012)
		(layer "F.Cu")
		(net "PVDDCR_CPU0_P0")
	)
	(segment
		(start 358.307894 -239.890046)
		(end 357.841042 -239.624108)
		(width 0.350012)
		(layer "F.Cu")
		(net "PVDDCR_CPU0_P0")
	)
	(segment
		(start 367.238026 -239.08004)
		(end 367.704878 -238.814102)
		(width 0.350012)
		(layer "F.Cu")
		(net "PVDDCR_CPU0_P0")
	)
	(segment
		(start 373.817896 -245.560088)
		(end 374.284748 -245.29415)
		(width 0.350012)
		(layer "F.Cu")
		(net "PVDDCR_CPU0_P0")
	)
	(segment
		(start 342.797892 -224.500186)
		(end 342.33104 -224.234248)
		(width 0.350012)
		(layer "F.Cu")
		(net "PVDDCR_CPU0_P0")
	)
	(segment
		(start 361.128056 -246.370094)
		(end 361.594908 -246.104156)
		(width 0.350012)
		(layer "F.Cu")
		(net "PVDDCR_CPU0_P0")
	)
	(segment
		(start 352.668078 -249.610118)
		(end 352.201226 -249.34418)
		(width 0.350012)
		(layer "F.Cu")
		(net "PVDDCR_CPU0_P0")
	)
	(segment
		(start 348.437962 -222.880174)
		(end 347.97111 -222.614236)
		(width 0.350012)
		(layer "F.Cu")
		(net "PVDDCR_CPU0_P0")
	)
	(segment
		(start 354.547932 -251.23013)
		(end 354.08108 -250.964192)
		(width 0.350012)
		(layer "F.Cu")
		(net "PVDDCR_CPU0_P0")
	)
	(segment
		(start 368.17808 -222.880174)
		(end 368.644932 -222.614236)
		(width 0.350012)
		(layer "F.Cu")
		(net "PVDDCR_CPU0_P0")
	)
	(segment
		(start 345.618054 -222.880174)
		(end 345.151202 -222.614236)
		(width 0.350012)
		(layer "F.Cu")
		(net "PVDDCR_CPU0_P0")
	)
	(segment
		(start 353.137978 -250.420124)
		(end 352.671126 -250.154186)
		(width 0.350012)
		(layer "F.Cu")
		(net "PVDDCR_CPU0_P0")
	)
	(segment
		(start 355.018086 -239.08004)
		(end 354.551234 -238.814102)
		(width 0.350012)
		(layer "F.Cu")
		(net "PVDDCR_CPU0_P0")
	)
	(segment
		(start 370.057934 -227.74021)
		(end 370.524786 -227.474272)
		(width 0.350012)
		(layer "F.Cu")
		(net "PVDDCR_CPU0_P0")
	)
	(segment
		(start 355.018086 -245.560088)
		(end 354.551234 -245.29415)
		(width 0.350012)
		(layer "F.Cu")
		(net "PVDDCR_CPU0_P0")
	)
	(segment
		(start 364.417864 -239.08004)
		(end 364.884716 -238.814102)
		(width 0.350012)
		(layer "F.Cu")
		(net "PVDDCR_CPU0_P0")
	)
	(segment
		(start 371.467888 -225.310192)
		(end 371.93474 -225.044254)
		(width 0.350012)
		(layer "F.Cu")
		(net "PVDDCR_CPU0_P0")
	)
	(segment
		(start 370.997988 -222.880174)
		(end 371.46484 -222.614236)
		(width 0.350012)
		(layer "F.Cu")
		(net "PVDDCR_CPU0_P0")
	)
	(segment
		(start 363.947964 -236.650022)
		(end 364.414816 -236.384084)
		(width 0.350012)
		(layer "F.Cu")
		(net "PVDDCR_CPU0_P0")
	)
	(segment
		(start 365.357918 -245.560088)
		(end 365.82477 -245.29415)
		(width 0.350012)
		(layer "F.Cu")
		(net "PVDDCR_CPU0_P0")
	)
	(segment
		(start 373.817896 -230.97998)
		(end 374.284748 -230.714296)
		(width 0.350012)
		(layer "F.Cu")
		(net "PVDDCR_CPU0_P0")
	)
	(segment
		(start 357.36784 -226.930204)
		(end 356.901242 -226.664266)
		(width 0.350012)
		(layer "F.Cu")
		(net "PVDDCR_CPU0_P0")
	)
	(segment
		(start 356.89794 -222.880174)
		(end 356.431088 -222.614236)
		(width 0.350012)
		(layer "F.Cu")
		(net "PVDDCR_CPU0_P0")
	)
	(segment
		(start 368.17808 -245.560088)
		(end 368.644678 -245.29415)
		(width 0.350012)
		(layer "F.Cu")
		(net "PVDDCR_CPU0_P0")
	)
	(segment
		(start 372.877842 -239.08004)
		(end 373.344694 -238.814102)
		(width 0.350012)
		(layer "F.Cu")
		(net "PVDDCR_CPU0_P0")
	)
	(segment
		(start 358.307894 -226.930204)
		(end 357.841042 -226.664266)
		(width 0.350012)
		(layer "F.Cu")
		(net "PVDDCR_CPU0_P0")
	)
	(segment
		(start 351.25787 -245.560088)
		(end 350.791018 -245.29415)
		(width 0.350012)
		(layer "F.Cu")
		(net "PVDDCR_CPU0_P0")
	)
	(segment
		(start 356.42804 -249.610118)
		(end 355.961188 -249.34418)
		(width 0.350012)
		(layer "F.Cu")
		(net "PVDDCR_CPU0_P0")
	)
	(segment
		(start 365.357918 -250.420124)
		(end 365.82477 -250.154186)
		(width 0.350012)
		(layer "F.Cu")
		(net "PVDDCR_CPU0_P0")
	)
	(segment
		(start 373.817896 -239.08004)
		(end 374.284748 -238.814102)
		(width 0.350012)
		(layer "F.Cu")
		(net "PVDDCR_CPU0_P0")
	)
	(segment
		(start 352.668078 -236.650022)
		(end 352.201226 -236.384084)
		(width 0.350012)
		(layer "F.Cu")
		(net "PVDDCR_CPU0_P0")
	)
	(segment
		(start 371.938042 -222.880174)
		(end 372.404894 -222.614236)
		(width 0.350012)
		(layer "F.Cu")
		(net "PVDDCR_CPU0_P0")
	)
	(segment
		(start 361.128056 -226.930204)
		(end 361.594908 -226.664266)
		(width 0.350012)
		(layer "F.Cu")
		(net "PVDDCR_CPU0_P0")
	)
	(segment
		(start 373.817896 -222.880174)
		(end 374.284748 -222.614236)
		(width 0.350012)
		(layer "F.Cu")
		(net "PVDDCR_CPU0_P0")
	)
	(segment
		(start 358.307894 -243.13007)
		(end 357.841042 -242.864132)
		(width 0.350012)
		(layer "F.Cu")
		(net "PVDDCR_CPU0_P0")
	)
	(segment
		(start 349.378016 -250.420124)
		(end 348.911164 -250.154186)
		(width 0.350012)
		(layer "F.Cu")
		(net "PVDDCR_CPU0_P0")
	)
	(segment
		(start 354.078032 -245.560088)
		(end 353.61118 -245.29415)
		(width 0.350012)
		(layer "F.Cu")
		(net "PVDDCR_CPU0_P0")
	)
	(segment
		(start 367.238026 -245.560088)
		(end 367.704878 -245.29415)
		(width 0.350012)
		(layer "F.Cu")
		(net "PVDDCR_CPU0_P0")
	)
	(segment
		(start 351.25787 -227.74021)
		(end 350.791018 -227.474272)
		(width 0.350012)
		(layer "F.Cu")
		(net "PVDDCR_CPU0_P0")
	)
	(segment
		(start 355.957886 -226.120198)
		(end 355.491034 -225.85426)
		(width 0.350012)
		(layer "F.Cu")
		(net "PVDDCR_CPU0_P0")
	)
	(segment
		(start 364.417864 -248.800112)
		(end 364.884716 -248.534174)
		(width 0.350012)
		(layer "F.Cu")
		(net "PVDDCR_CPU0_P0")
	)
	(segment
		(start 364.888018 -236.650022)
		(end 365.35487 -236.384084)
		(width 0.350012)
		(layer "F.Cu")
		(net "PVDDCR_CPU0_P0")
	)
	(segment
		(start 363.478064 -226.120198)
		(end 363.944916 -225.85426)
		(width 0.350012)
		(layer "F.Cu")
		(net "PVDDCR_CPU0_P0")
	)
	(segment
		(start 354.547932 -236.650022)
		(end 354.08108 -236.384084)
		(width 0.350012)
		(layer "F.Cu")
		(net "PVDDCR_CPU0_P0")
	)
	(segment
		(start 370.057934 -242.320064)
		(end 370.524786 -242.054126)
		(width 0.350012)
		(layer "F.Cu")
		(net "PVDDCR_CPU0_P0")
	)
	(segment
		(start 352.197924 -242.320064)
		(end 351.731072 -242.054126)
		(width 0.350012)
		(layer "F.Cu")
		(net "PVDDCR_CPU0_P0")
	)
	(segment
		(start 365.357918 -230.97998)
		(end 365.82477 -230.714296)
		(width 0.350012)
		(layer "F.Cu")
		(net "PVDDCR_CPU0_P0")
	)
	(segment
		(start 372.877842 -248.800112)
		(end 373.344694 -248.534174)
		(width 0.350012)
		(layer "F.Cu")
		(net "PVDDCR_CPU0_P0")
	)
	(segment
		(start 346.557854 -239.08004)
		(end 346.091002 -238.814102)
		(width 0.350012)
		(layer "F.Cu")
		(net "PVDDCR_CPU0_P0")
	)
	(segment
		(start 357.36784 -246.370094)
		(end 356.901242 -246.104156)
		(width 0.350012)
		(layer "F.Cu")
		(net "PVDDCR_CPU0_P0")
	)
	(segment
		(start 358.778048 -250.420124)
		(end 358.311196 -250.154186)
		(width 0.350012)
		(layer "F.Cu")
		(net "PVDDCR_CPU0_P0")
	)
	(segment
		(start 368.17808 -239.08004)
		(end 368.644678 -238.814102)
		(width 0.350012)
		(layer "F.Cu")
		(net "PVDDCR_CPU0_P0")
	)
	(segment
		(start 351.25787 -234.220004)
		(end 350.791018 -233.954066)
		(width 0.350012)
		(layer "F.Cu")
		(net "PVDDCR_CPU0_P0")
	)
	(segment
		(start 368.64798 -225.310192)
		(end 369.114832 -225.044254)
		(width 0.350012)
		(layer "F.Cu")
		(net "PVDDCR_CPU0_P0")
	)
	(segment
		(start 371.467888 -249.610118)
		(end 371.93474 -249.34418)
		(width 0.350012)
		(layer "F.Cu")
		(net "PVDDCR_CPU0_P0")
	)
	(segment
		(start 346.557854 -248.800112)
		(end 346.091002 -248.534174)
		(width 0.350012)
		(layer "F.Cu")
		(net "PVDDCR_CPU0_P0")
	)
	(segment
		(start 345.618054 -227.74021)
		(end 345.151202 -227.474272)
		(width 0.350012)
		(layer "F.Cu")
		(net "PVDDCR_CPU0_P0")
	)
	(segment
		(start 361.128056 -231.789986)
		(end 361.594908 -231.524048)
		(width 0.350012)
		(layer "F.Cu")
		(net "PVDDCR_CPU0_P0")
	)
	(segment
		(start 362.067856 -246.370094)
		(end 362.534708 -246.104156)
		(width 0.350012)
		(layer "F.Cu")
		(net "PVDDCR_CPU0_P0")
	)
	(segment
		(start 363.00791 -225.310192)
		(end 363.474762 -225.044254)
		(width 0.350012)
		(layer "F.Cu")
		(net "PVDDCR_CPU0_P0")
	)
	(segment
		(start 365.357918 -239.08004)
		(end 365.82477 -238.814102)
		(width 0.350012)
		(layer "F.Cu")
		(net "PVDDCR_CPU0_P0")
	)
	(segment
		(start 367.238026 -242.320064)
		(end 367.704878 -242.054126)
		(width 0.350012)
		(layer "F.Cu")
		(net "PVDDCR_CPU0_P0")
	)
	(segment
		(start 356.89794 -237.460028)
		(end 356.431088 -237.19409)
		(width 0.350012)
		(layer "F.Cu")
		(net "PVDDCR_CPU0_P0")
	)
	(segment
		(start 352.197924 -239.08004)
		(end 351.731072 -238.814102)
		(width 0.350012)
		(layer "F.Cu")
		(net "PVDDCR_CPU0_P0")
	)
	(segment
		(start 370.997988 -250.420124)
		(end 371.46484 -250.154186)
		(width 0.350012)
		(layer "F.Cu")
		(net "PVDDCR_CPU0_P0")
	)
	(segment
		(start 361.597956 -237.460028)
		(end 362.064808 -237.19409)
		(width 0.350012)
		(layer "F.Cu")
		(net "PVDDCR_CPU0_P0")
	)
	(segment
		(start 357.36784 -239.890046)
		(end 356.901242 -239.624108)
		(width 0.350012)
		(layer "F.Cu")
		(net "PVDDCR_CPU0_P0")
	)
	(segment
		(start 368.17808 -242.320064)
		(end 368.644678 -242.054126)
		(width 0.350012)
		(layer "F.Cu")
		(net "PVDDCR_CPU0_P0")
	)
	(segment
		(start 363.947964 -251.23013)
		(end 364.414816 -250.964192)
		(width 0.350012)
		(layer "F.Cu")
		(net "PVDDCR_CPU0_P0")
	)
	(segment
		(start 370.997988 -230.97998)
		(end 371.46484 -230.714296)
		(width 0.350012)
		(layer "F.Cu")
		(net "PVDDCR_CPU0_P0")
	)
	(segment
		(start 355.957886 -222.880174)
		(end 355.491034 -222.614236)
		(width 0.350012)
		(layer "F.Cu")
		(net "PVDDCR_CPU0_P0")
	)
	(segment
		(start 364.417864 -230.97998)
		(end 364.884716 -230.714296)
		(width 0.350012)
		(layer "F.Cu")
		(net "PVDDCR_CPU0_P0")
	)
	(segment
		(start 370.997988 -245.560088)
		(end 371.46484 -245.29415)
		(width 0.350012)
		(layer "F.Cu")
		(net "PVDDCR_CPU0_P0")
	)
	(segment
		(start 371.467888 -251.23013)
		(end 371.93474 -250.964192)
		(width 0.350012)
		(layer "F.Cu")
		(net "PVDDCR_CPU0_P0")
	)
	(segment
		(start 370.997988 -227.74021)
		(end 371.46484 -227.474272)
		(width 0.350012)
		(layer "F.Cu")
		(net "PVDDCR_CPU0_P0")
	)
	(segment
		(start 367.238026 -250.420124)
		(end 367.704878 -250.154186)
		(width 0.350012)
		(layer "F.Cu")
		(net "PVDDCR_CPU0_P0")
	)
	(segment
		(start 365.357918 -242.320064)
		(end 365.82477 -242.054126)
		(width 0.350012)
		(layer "F.Cu")
		(net "PVDDCR_CPU0_P0")
	)
	(segment
		(start 373.817896 -248.800112)
		(end 374.284748 -248.534174)
		(width 0.350012)
		(layer "F.Cu")
		(net "PVDDCR_CPU0_P0")
	)
	(segment
		(start 370.057934 -234.220004)
		(end 370.524786 -233.954066)
		(width 0.350012)
		(layer "F.Cu")
		(net "PVDDCR_CPU0_P0")
	)
	(segment
		(start 346.557854 -234.220004)
		(end 346.091002 -233.954066)
		(width 0.350012)
		(layer "F.Cu")
		(net "PVDDCR_CPU0_P0")
	)
	(segment
		(start 345.1479 -225.310192)
		(end 344.681048 -225.044254)
		(width 0.350012)
		(layer "F.Cu")
		(net "PVDDCR_CPU0_P0")
	)
	(segment
		(start 362.067856 -249.610118)
		(end 362.534708 -249.34418)
		(width 0.350012)
		(layer "F.Cu")
		(net "PVDDCR_CPU0_P0")
	)
	(segment
		(start 354.078032 -248.800112)
		(end 353.61118 -248.534174)
		(width 0.350012)
		(layer "F.Cu")
		(net "PVDDCR_CPU0_P0")
	)
	(via
		(at 370.524786 -248.534174)
		(size 0.4064)
		(drill 0.2032)
		(layers "F.Cu" "B.Cu")
		(net "PVDDCR_CPU0_P0")
	)
	(via
		(at 349.851218 -222.614236)
		(size 0.4064)
		(drill 0.2032)
		(layers "F.Cu" "B.Cu")
		(net "PVDDCR_CPU0_P0")
	)
	(via
		(at 342.468454 -221.30131)
		(size 0.508)
		(drill 0.254)
		(layers "F.Cu" "B.Cu")
		(net "PVDDCR_CPU0_P0")
	)
	(via
		(at 371.46484 -245.29415)
		(size 0.4064)
		(drill 0.2032)
		(layers "F.Cu" "B.Cu")
		(net "PVDDCR_CPU0_P0")
	)
	(via
		(at 354.551234 -233.954066)
		(size 0.4064)
		(drill 0.2032)
		(layers "F.Cu" "B.Cu")
		(net "PVDDCR_CPU0_P0")
	)
	(via
		(at 365.567722 -191.655954)
		(size 0.508)
		(drill 0.254)
		(layers "F.Cu" "B.Cu")
		(net "PVDDCR_CPU0_P0")
	)
	(via
		(at 361.594908 -239.624108)
		(size 0.4064)
		(drill 0.2032)
		(layers "F.Cu" "B.Cu")
		(net "PVDDCR_CPU0_P0")
	)
	(via
		(at 365.82477 -238.814102)
		(size 0.4064)
		(drill 0.2032)
		(layers "F.Cu" "B.Cu")
		(net "PVDDCR_CPU0_P0")
	)
	(via
		(at 373.928894 -195.993512)
		(size 0.508)
		(drill 0.254)
		(layers "F.Cu" "B.Cu")
		(net "PVDDCR_CPU0_P0")
	)
	(via
		(at 391.297922 -195.993512)
		(size 0.508)
		(drill 0.254)
		(layers "F.Cu" "B.Cu")
		(net "PVDDCR_CPU0_P0")
	)
	(via
		(at 353.61118 -230.714296)
		(size 0.4064)
		(drill 0.2032)
		(layers "F.Cu" "B.Cu")
		(net "PVDDCR_CPU0_P0")
	)
	(via
		(at 375.224802 -222.614236)
		(size 0.4064)
		(drill 0.2032)
		(layers "F.Cu" "B.Cu")
		(net "PVDDCR_CPU0_P0")
	)
	(via
		(at 356.431088 -222.614236)
		(size 0.4064)
		(drill 0.2032)
		(layers "F.Cu" "B.Cu")
		(net "PVDDCR_CPU0_P0")
	)
	(via
		(at 378.329698 -198.55434)
		(size 0.508)
		(drill 0.254)
		(layers "F.Cu" "B.Cu")
		(net "PVDDCR_CPU0_P0")
	)
	(via
		(at 362.064808 -237.19409)
		(size 0.4064)
		(drill 0.2032)
		(layers "F.Cu" "B.Cu")
		(net "PVDDCR_CPU0_P0")
	)
	(via
		(at 342.33104 -224.234248)
		(size 0.4064)
		(drill 0.2032)
		(layers "F.Cu" "B.Cu")
		(net "PVDDCR_CPU0_P0")
	)
	(via
		(at 382.342898 -197.91934)
		(size 0.508)
		(drill 0.254)
		(layers "F.Cu" "B.Cu")
		(net "PVDDCR_CPU0_P0")
	)
	(via
		(at 374.284748 -227.474272)
		(size 0.4064)
		(drill 0.2032)
		(layers "F.Cu" "B.Cu")
		(net "PVDDCR_CPU0_P0")
	)
	(via
		(at 354.551234 -248.534174)
		(size 0.4064)
		(drill 0.2032)
		(layers "F.Cu" "B.Cu")
		(net "PVDDCR_CPU0_P0")
	)
	(via
		(at 353.909122 -183.380634)
		(size 0.508)
		(drill 0.254)
		(layers "F.Cu" "B.Cu")
		(net "PVDDCR_CPU0_P0")
	)
	(via
		(at 378.329698 -199.18934)
		(size 0.508)
		(drill 0.254)
		(layers "F.Cu" "B.Cu")
		(net "PVDDCR_CPU0_P0")
	)
	(via
		(at 350.791018 -245.29415)
		(size 0.4064)
		(drill 0.2032)
		(layers "F.Cu" "B.Cu")
		(net "PVDDCR_CPU0_P0")
	)
	(via
		(at 349.05823 -173.119542)
		(size 0.508)
		(drill 0.254)
		(layers "F.Cu" "B.Cu")
		(net "PVDDCR_CPU0_P0")
	)
	(via
		(at 366.841278 -192.311782)
		(size 0.508)
		(drill 0.254)
		(layers "F.Cu" "B.Cu")
		(net "PVDDCR_CPU0_P0")
	)
	(via
		(at 368.644678 -230.714296)
		(size 0.4064)
		(drill 0.2032)
		(layers "F.Cu" "B.Cu")
		(net "PVDDCR_CPU0_P0")
	)
	(via
		(at 383.612898 -199.82434)
		(size 0.508)
		(drill 0.254)
		(layers "F.Cu" "B.Cu")
		(net "PVDDCR_CPU0_P0")
	)
	(via
		(at 363.004862 -237.19409)
		(size 0.4064)
		(drill 0.2032)
		(layers "F.Cu" "B.Cu")
		(net "PVDDCR_CPU0_P0")
	)
	(via
		(at 341.390986 -222.614236)
		(size 0.4064)
		(drill 0.2032)
		(layers "F.Cu" "B.Cu")
		(net "PVDDCR_CPU0_P0")
	)
	(via
		(at 363.944916 -225.85426)
		(size 0.4064)
		(drill 0.2032)
		(layers "F.Cu" "B.Cu")
		(net "PVDDCR_CPU0_P0")
	)
	(via
		(at 346.091002 -248.534174)
		(size 0.4064)
		(drill 0.2032)
		(layers "F.Cu" "B.Cu")
		(net "PVDDCR_CPU0_P0")
	)
	(via
		(at 362.534708 -231.524048)
		(size 0.4064)
		(drill 0.2032)
		(layers "F.Cu" "B.Cu")
		(net "PVDDCR_CPU0_P0")
	)
	(via
		(at 370.553234 -197.915784)
		(size 0.508)
		(drill 0.254)
		(layers "F.Cu" "B.Cu")
		(net "PVDDCR_CPU0_P0")
	)
	(via
		(at 362.534708 -234.764072)
		(size 0.4064)
		(drill 0.2032)
		(layers "F.Cu" "B.Cu")
		(net "PVDDCR_CPU0_P0")
	)
	(via
		(at 364.884716 -230.714296)
		(size 0.4064)
		(drill 0.2032)
		(layers "F.Cu" "B.Cu")
		(net "PVDDCR_CPU0_P0")
	)
	(via
		(at 362.815378 -193.581782)
		(size 0.508)
		(drill 0.254)
		(layers "F.Cu" "B.Cu")
		(net "PVDDCR_CPU0_P0")
	)
	(via
		(at 375.978928 -178.96205)
		(size 0.508)
		(drill 0.254)
		(layers "F.Cu" "B.Cu")
		(net "PVDDCR_CPU0_P0")
	)
	(via
		(at 387.284722 -196.628512)
		(size 0.508)
		(drill 0.254)
		(layers "F.Cu" "B.Cu")
		(net "PVDDCR_CPU0_P0")
	)
	(via
		(at 351.731072 -233.954066)
		(size 0.4064)
		(drill 0.2032)
		(layers "F.Cu" "B.Cu")
		(net "PVDDCR_CPU0_P0")
	)
	(via
		(at 382.977898 -198.55434)
		(size 0.508)
		(drill 0.254)
		(layers "F.Cu" "B.Cu")
		(net "PVDDCR_CPU0_P0")
	)
	(via
		(at 366.294924 -225.044254)
		(size 0.4064)
		(drill 0.2032)
		(layers "F.Cu" "B.Cu")
		(net "PVDDCR_CPU0_P0")
	)
	(via
		(at 353.909122 -184.015634)
		(size 0.508)
		(drill 0.254)
		(layers "F.Cu" "B.Cu")
		(net "PVDDCR_CPU0_P0")
	)
	(via
		(at 378.964698 -199.82434)
		(size 0.508)
		(drill 0.254)
		(layers "F.Cu" "B.Cu")
		(net "PVDDCR_CPU0_P0")
	)
	(via
		(at 379.588522 -195.358512)
		(size 0.508)
		(drill 0.254)
		(layers "F.Cu" "B.Cu")
		(net "PVDDCR_CPU0_P0")
	)
	(via
		(at 349.697294 -175.024542)
		(size 0.508)
		(drill 0.254)
		(layers "F.Cu" "B.Cu")
		(net "PVDDCR_CPU0_P0")
	)
	(via
		(at 367.704878 -248.534174)
		(size 0.4064)
		(drill 0.2032)
		(layers "F.Cu" "B.Cu")
		(net "PVDDCR_CPU0_P0")
	)
	(via
		(at 367.704878 -227.474272)
		(size 0.4064)
		(drill 0.2032)
		(layers "F.Cu" "B.Cu")
		(net "PVDDCR_CPU0_P0")
	)
	(via
		(at 353.264978 -184.036462)
		(size 0.508)
		(drill 0.254)
		(layers "F.Cu" "B.Cu")
		(net "PVDDCR_CPU0_P0")
	)
	(via
		(at 391.297922 -196.628512)
		(size 0.508)
		(drill 0.254)
		(layers "F.Cu" "B.Cu")
		(net "PVDDCR_CPU0_P0")
	)
	(via
		(at 357.928418 -187.838842)
		(size 0.508)
		(drill 0.254)
		(layers "F.Cu" "B.Cu")
		(net "PVDDCR_CPU0_P0")
	)
	(via
		(at 349.697294 -175.659542)
		(size 0.508)
		(drill 0.254)
		(layers "F.Cu" "B.Cu")
		(net "PVDDCR_CPU0_P0")
	)
	(via
		(at 371.46484 -230.714296)
		(size 0.4064)
		(drill 0.2032)
		(layers "F.Cu" "B.Cu")
		(net "PVDDCR_CPU0_P0")
	)
	(via
		(at 364.414816 -236.384084)
		(size 0.4064)
		(drill 0.2032)
		(layers "F.Cu" "B.Cu")
		(net "PVDDCR_CPU0_P0")
	)
	(via
		(at 357.287322 -182.745634)
		(size 0.508)
		(drill 0.254)
		(layers "F.Cu" "B.Cu")
		(net "PVDDCR_CPU0_P0")
	)
	(via
		(at 368.174778 -250.964192)
		(size 0.4064)
		(drill 0.2032)
		(layers "F.Cu" "B.Cu")
		(net "PVDDCR_CPU0_P0")
	)
	(via
		(at 355.021134 -236.384084)
		(size 0.4064)
		(drill 0.2032)
		(layers "F.Cu" "B.Cu")
		(net "PVDDCR_CPU0_P0")
	)
	(via
		(at 382.342898 -199.82434)
		(size 0.508)
		(drill 0.254)
		(layers "F.Cu" "B.Cu")
		(net "PVDDCR_CPU0_P0")
	)
	(via
		(at 370.524786 -227.474272)
		(size 0.4064)
		(drill 0.2032)
		(layers "F.Cu" "B.Cu")
		(net "PVDDCR_CPU0_P0")
	)
	(via
		(at 371.188234 -201.090784)
		(size 0.508)
		(drill 0.254)
		(layers "F.Cu" "B.Cu")
		(net "PVDDCR_CPU0_P0")
	)
	(via
		(at 346.319094 -173.754542)
		(size 0.508)
		(drill 0.254)
		(layers "F.Cu" "B.Cu")
		(net "PVDDCR_CPU0_P0")
	)
	(via
		(at 369.584732 -250.154186)
		(size 0.4064)
		(drill 0.2032)
		(layers "F.Cu" "B.Cu")
		(net "PVDDCR_CPU0_P0")
	)
	(via
		(at 345.684094 -175.659542)
		(size 0.508)
		(drill 0.254)
		(layers "F.Cu" "B.Cu")
		(net "PVDDCR_CPU0_P0")
	)
	(via
		(at 365.567722 -190.385954)
		(size 0.508)
		(drill 0.254)
		(layers "F.Cu" "B.Cu")
		(net "PVDDCR_CPU0_P0")
	)
	(via
		(at 354.08108 -236.384084)
		(size 0.4064)
		(drill 0.2032)
		(layers "F.Cu" "B.Cu")
		(net "PVDDCR_CPU0_P0")
	)
	(via
		(at 371.46484 -222.614236)
		(size 0.4064)
		(drill 0.2032)
		(layers "F.Cu" "B.Cu")
		(net "PVDDCR_CPU0_P0")
	)
	(via
		(at 354.551234 -242.054126)
		(size 0.4064)
		(drill 0.2032)
		(layers "F.Cu" "B.Cu")
		(net "PVDDCR_CPU0_P0")
	)
	(via
		(at 375.201434 -195.375784)
		(size 0.508)
		(drill 0.254)
		(layers "F.Cu" "B.Cu")
		(net "PVDDCR_CPU0_P0")
	)
	(via
		(at 366.206278 -195.486782)
		(size 0.508)
		(drill 0.254)
		(layers "F.Cu" "B.Cu")
		(net "PVDDCR_CPU0_P0")
	)
	(via
		(at 373.931434 -197.915784)
		(size 0.508)
		(drill 0.254)
		(layers "F.Cu" "B.Cu")
		(net "PVDDCR_CPU0_P0")
	)
	(via
		(at 387.284722 -195.358512)
		(size 0.508)
		(drill 0.254)
		(layers "F.Cu" "B.Cu")
		(net "PVDDCR_CPU0_P0")
	)
	(via
		(at 357.918258 -181.475634)
		(size 0.508)
		(drill 0.254)
		(layers "F.Cu" "B.Cu")
		(net "PVDDCR_CPU0_P0")
	)
	(via
		(at 373.92483 -194.723512)
		(size 0.508)
		(drill 0.254)
		(layers "F.Cu" "B.Cu")
		(net "PVDDCR_CPU0_P0")
	)
	(via
		(at 362.189522 -192.290954)
		(size 0.508)
		(drill 0.254)
		(layers "F.Cu" "B.Cu")
		(net "PVDDCR_CPU0_P0")
	)
	(via
		(at 387.919722 -195.358512)
		(size 0.508)
		(drill 0.254)
		(layers "F.Cu" "B.Cu")
		(net "PVDDCR_CPU0_P0")
	)
	(via
		(at 355.961188 -249.34418)
		(size 0.4064)
		(drill 0.2032)
		(layers "F.Cu" "B.Cu")
		(net "PVDDCR_CPU0_P0")
	)
	(via
		(at 365.571278 -194.216782)
		(size 0.508)
		(drill 0.254)
		(layers "F.Cu" "B.Cu")
		(net "PVDDCR_CPU0_P0")
	)
	(via
		(at 371.188234 -199.185784)
		(size 0.508)
		(drill 0.254)
		(layers "F.Cu" "B.Cu")
		(net "PVDDCR_CPU0_P0")
	)
	(via
		(at 373.931434 -199.820784)
		(size 0.508)
		(drill 0.254)
		(layers "F.Cu" "B.Cu")
		(net "PVDDCR_CPU0_P0")
	)
	(via
		(at 351.731072 -238.814102)
		(size 0.4064)
		(drill 0.2032)
		(layers "F.Cu" "B.Cu")
		(net "PVDDCR_CPU0_P0")
	)
	(via
		(at 356.431088 -237.19409)
		(size 0.4064)
		(drill 0.2032)
		(layers "F.Cu" "B.Cu")
		(net "PVDDCR_CPU0_P0")
	)
	(via
		(at 355.491034 -225.85426)
		(size 0.4064)
		(drill 0.2032)
		(layers "F.Cu" "B.Cu")
		(net "PVDDCR_CPU0_P0")
	)
	(via
		(at 346.091002 -230.714296)
		(size 0.4064)
		(drill 0.2032)
		(layers "F.Cu" "B.Cu")
		(net "PVDDCR_CPU0_P0")
	)
	(via
		(at 370.550694 -196.628512)
		(size 0.508)
		(drill 0.254)
		(layers "F.Cu" "B.Cu")
		(net "PVDDCR_CPU0_P0")
	)
	(via
		(at 361.547918 -189.750954)
		(size 0.508)
		(drill 0.254)
		(layers "F.Cu" "B.Cu")
		(net "PVDDCR_CPU0_P0")
	)
	(via
		(at 370.524786 -245.29415)
		(size 0.4064)
		(drill 0.2032)
		(layers "F.Cu" "B.Cu")
		(net "PVDDCR_CPU0_P0")
	)
	(via
		(at 361.594908 -246.104156)
		(size 0.4064)
		(drill 0.2032)
		(layers "F.Cu" "B.Cu")
		(net "PVDDCR_CPU0_P0")
	)
	(via
		(at 367.234724 -236.384084)
		(size 0.4064)
		(drill 0.2032)
		(layers "F.Cu" "B.Cu")
		(net "PVDDCR_CPU0_P0")
	)
	(via
		(at 382.966722 -195.358512)
		(size 0.508)
		(drill 0.254)
		(layers "F.Cu" "B.Cu")
		(net "PVDDCR_CPU0_P0")
	)
	(via
		(at 356.901242 -231.524048)
		(size 0.4064)
		(drill 0.2032)
		(layers "F.Cu" "B.Cu")
		(net "PVDDCR_CPU0_P0")
	)
	(via
		(at 368.174778 -236.384084)
		(size 0.4064)
		(drill 0.2032)
		(layers "F.Cu" "B.Cu")
		(net "PVDDCR_CPU0_P0")
	)
	(via
		(at 373.928894 -197.263512)
		(size 0.508)
		(drill 0.254)
		(layers "F.Cu" "B.Cu")
		(net "PVDDCR_CPU0_P0")
	)
	(via
		(at 357.928418 -185.933842)
		(size 0.508)
		(drill 0.254)
		(layers "F.Cu" "B.Cu")
		(net "PVDDCR_CPU0_P0")
	)
	(via
		(at 348.911164 -248.534174)
		(size 0.4064)
		(drill 0.2032)
		(layers "F.Cu" "B.Cu")
		(net "PVDDCR_CPU0_P0")
	)
	(via
		(at 352.671126 -225.85426)
		(size 0.4064)
		(drill 0.2032)
		(layers "F.Cu" "B.Cu")
		(net "PVDDCR_CPU0_P0")
	)
	(via
		(at 350.791018 -238.814102)
		(size 0.4064)
		(drill 0.2032)
		(layers "F.Cu" "B.Cu")
		(net "PVDDCR_CPU0_P0")
	)
	(via
		(at 369.90909 -195.37934)
		(size 0.508)
		(drill 0.254)
		(layers "F.Cu" "B.Cu")
		(net "PVDDCR_CPU0_P0")
	)
	(via
		(at 346.091002 -227.474272)
		(size 0.4064)
		(drill 0.2032)
		(layers "F.Cu" "B.Cu")
		(net "PVDDCR_CPU0_P0")
	)
	(via
		(at 369.90909 -197.28434)
		(size 0.508)
		(drill 0.254)
		(layers "F.Cu" "B.Cu")
		(net "PVDDCR_CPU0_P0")
	)
	(via
		(at 373.928894 -196.628512)
		(size 0.508)
		(drill 0.254)
		(layers "F.Cu" "B.Cu")
		(net "PVDDCR_CPU0_P0")
	)
	(via
		(at 350.321118 -249.34418)
		(size 0.4064)
		(drill 0.2032)
		(layers "F.Cu" "B.Cu")
		(net "PVDDCR_CPU0_P0")
	)
	(via
		(at 364.884716 -242.054126)
		(size 0.4064)
		(drill 0.2032)
		(layers "F.Cu" "B.Cu")
		(net "PVDDCR_CPU0_P0")
	)
	(via
		(at 365.571278 -195.486782)
		(size 0.508)
		(drill 0.254)
		(layers "F.Cu" "B.Cu")
		(net "PVDDCR_CPU0_P0")
	)
	(via
		(at 383.612898 -195.37934)
		(size 0.508)
		(drill 0.254)
		(layers "F.Cu" "B.Cu")
		(net "PVDDCR_CPU0_P0")
	)
	(via
		(at 367.704878 -242.054126)
		(size 0.4064)
		(drill 0.2032)
		(layers "F.Cu" "B.Cu")
		(net "PVDDCR_CPU0_P0")
	)
	(via
		(at 355.491034 -222.614236)
		(size 0.4064)
		(drill 0.2032)
		(layers "F.Cu" "B.Cu")
		(net "PVDDCR_CPU0_P0")
	)
	(via
		(at 366.841278 -194.851782)
		(size 0.508)
		(drill 0.254)
		(layers "F.Cu" "B.Cu")
		(net "PVDDCR_CPU0_P0")
	)
	(via
		(at 357.928418 -187.203842)
		(size 0.508)
		(drill 0.254)
		(layers "F.Cu" "B.Cu")
		(net "PVDDCR_CPU0_P0")
	)
	(via
		(at 364.884716 -227.474272)
		(size 0.4064)
		(drill 0.2032)
		(layers "F.Cu" "B.Cu")
		(net "PVDDCR_CPU0_P0")
	)
	(via
		(at 378.953522 -195.993512)
		(size 0.508)
		(drill 0.254)
		(layers "F.Cu" "B.Cu")
		(net "PVDDCR_CPU0_P0")
	)
	(via
		(at 364.884716 -238.814102)
		(size 0.4064)
		(drill 0.2032)
		(layers "F.Cu" "B.Cu")
		(net "PVDDCR_CPU0_P0")
	)
	(via
		(at 354.544122 -183.380634)
		(size 0.508)
		(drill 0.254)
		(layers "F.Cu" "B.Cu")
		(net "PVDDCR_CPU0_P0")
	)
	(via
		(at 361.594908 -234.764072)
		(size 0.4064)
		(drill 0.2032)
		(layers "F.Cu" "B.Cu")
		(net "PVDDCR_CPU0_P0")
	)
	(via
		(at 374.563894 -195.358512)
		(size 0.508)
		(drill 0.254)
		(layers "F.Cu" "B.Cu")
		(net "PVDDCR_CPU0_P0")
	)
	(via
		(at 349.062294 -175.024542)
		(size 0.508)
		(drill 0.254)
		(layers "F.Cu" "B.Cu")
		(net "PVDDCR_CPU0_P0")
	)
	(via
		(at 346.319094 -175.024542)
		(size 0.508)
		(drill 0.254)
		(layers "F.Cu" "B.Cu")
		(net "PVDDCR_CPU0_P0")
	)
	(via
		(at 382.331722 -196.628512)
		(size 0.508)
		(drill 0.254)
		(layers "F.Cu" "B.Cu")
		(net "PVDDCR_CPU0_P0")
	)
	(via
		(at 365.82477 -250.154186)
		(size 0.4064)
		(drill 0.2032)
		(layers "F.Cu" "B.Cu")
		(net "PVDDCR_CPU0_P0")
	)
	(via
		(at 379.599698 -199.18934)
		(size 0.508)
		(drill 0.254)
		(layers "F.Cu" "B.Cu")
		(net "PVDDCR_CPU0_P0")
	)
	(via
		(at 350.791018 -250.154186)
		(size 0.4064)
		(drill 0.2032)
		(layers "F.Cu" "B.Cu")
		(net "PVDDCR_CPU0_P0")
	)
	(via
		(at 353.909122 -182.745634)
		(size 0.508)
		(drill 0.254)
		(layers "F.Cu" "B.Cu")
		(net "PVDDCR_CPU0_P0")
	)
	(via
		(at 383.612898 -196.01434)
		(size 0.508)
		(drill 0.254)
		(layers "F.Cu" "B.Cu")
		(net "PVDDCR_CPU0_P0")
	)
	(via
		(at 353.61118 -227.474272)
		(size 0.4064)
		(drill 0.2032)
		(layers "F.Cu" "B.Cu")
		(net "PVDDCR_CPU0_P0")
	)
	(via
		(at 354.544122 -182.745634)
		(size 0.508)
		(drill 0.254)
		(layers "F.Cu" "B.Cu")
		(net "PVDDCR_CPU0_P0")
	)
	(via
		(at 369.584732 -222.614236)
		(size 0.4064)
		(drill 0.2032)
		(layers "F.Cu" "B.Cu")
		(net "PVDDCR_CPU0_P0")
	)
	(via
		(at 391.297922 -195.358512)
		(size 0.508)
		(drill 0.254)
		(layers "F.Cu" "B.Cu")
		(net "PVDDCR_CPU0_P0")
	)
	(via
		(at 346.319094 -174.389542)
		(size 0.508)
		(drill 0.254)
		(layers "F.Cu" "B.Cu")
		(net "PVDDCR_CPU0_P0")
	)
	(via
		(at 361.594908 -242.864132)
		(size 0.4064)
		(drill 0.2032)
		(layers "F.Cu" "B.Cu")
		(net "PVDDCR_CPU0_P0")
	)
	(via
		(at 362.824522 -191.655954)
		(size 0.508)
		(drill 0.254)
		(layers "F.Cu" "B.Cu")
		(net "PVDDCR_CPU0_P0")
	)
	(via
		(at 351.731072 -248.534174)
		(size 0.4064)
		(drill 0.2032)
		(layers "F.Cu" "B.Cu")
		(net "PVDDCR_CPU0_P0")
	)
	(via
		(at 353.915218 -185.298842)
		(size 0.508)
		(drill 0.254)
		(layers "F.Cu" "B.Cu")
		(net "PVDDCR_CPU0_P0")
	)
	(via
		(at 347.97111 -245.29415)
		(size 0.4064)
		(drill 0.2032)
		(layers "F.Cu" "B.Cu")
		(net "PVDDCR_CPU0_P0")
	)
	(via
		(at 362.817918 -189.750954)
		(size 0.508)
		(drill 0.254)
		(layers "F.Cu" "B.Cu")
		(net "PVDDCR_CPU0_P0")
	)
	(via
		(at 345.049094 -173.774354)
		(size 0.508)
		(drill 0.254)
		(layers "F.Cu" "B.Cu")
		(net "PVDDCR_CPU0_P0")
	)
	(via
		(at 361.545378 -192.311782)
		(size 0.508)
		(drill 0.254)
		(layers "F.Cu" "B.Cu")
		(net "PVDDCR_CPU0_P0")
	)
	(via
		(at 382.977898 -197.91934)
		(size 0.508)
		(drill 0.254)
		(layers "F.Cu" "B.Cu")
		(net "PVDDCR_CPU0_P0")
	)
	(via
		(at 357.928418 -184.663842)
		(size 0.508)
		(drill 0.254)
		(layers "F.Cu" "B.Cu")
		(net "PVDDCR_CPU0_P0")
	)
	(via
		(at 345.151202 -248.534174)
		(size 0.4064)
		(drill 0.2032)
		(layers "F.Cu" "B.Cu")
		(net "PVDDCR_CPU0_P0")
	)
	(via
		(at 374.566434 -199.185784)
		(size 0.508)
		(drill 0.254)
		(layers "F.Cu" "B.Cu")
		(net "PVDDCR_CPU0_P0")
	)
	(via
		(at 375.201434 -196.645784)
		(size 0.508)
		(drill 0.254)
		(layers "F.Cu" "B.Cu")
		(net "PVDDCR_CPU0_P0")
	)
	(via
		(at 367.617756 -173.989492)
		(size 0.508)
		(drill 0.254)
		(layers "F.Cu" "B.Cu")
		(net "PVDDCR_CPU0_P0")
	)
	(via
		(at 357.922322 -182.110634)
		(size 0.508)
		(drill 0.254)
		(layers "F.Cu" "B.Cu")
		(net "PVDDCR_CPU0_P0")
	)
	(via
		(at 345.151202 -222.614236)
		(size 0.4064)
		(drill 0.2032)
		(layers "F.Cu" "B.Cu")
		(net "PVDDCR_CPU0_P0")
	)
	(via
		(at 353.276662 -184.671462)
		(size 0.508)
		(drill 0.254)
		(layers "F.Cu" "B.Cu")
		(net "PVDDCR_CPU0_P0")
	)
	(via
		(at 368.644932 -227.474272)
		(size 0.4064)
		(drill 0.2032)
		(layers "F.Cu" "B.Cu")
		(net "PVDDCR_CPU0_P0")
	)
	(via
		(at 345.684094 -173.754542)
		(size 0.508)
		(drill 0.254)
		(layers "F.Cu" "B.Cu")
		(net "PVDDCR_CPU0_P0")
	)
	(via
		(at 351.261172 -236.384084)
		(size 0.4064)
		(drill 0.2032)
		(layers "F.Cu" "B.Cu")
		(net "PVDDCR_CPU0_P0")
	)
	(via
		(at 386.643118 -199.18934)
		(size 0.508)
		(drill 0.254)
		(layers "F.Cu" "B.Cu")
		(net "PVDDCR_CPU0_P0")
	)
	(via
		(at 382.977898 -199.82434)
		(size 0.508)
		(drill 0.254)
		(layers "F.Cu" "B.Cu")
		(net "PVDDCR_CPU0_P0")
	)
	(via
		(at 353.61118 -242.054126)
		(size 0.4064)
		(drill 0.2032)
		(layers "F.Cu" "B.Cu")
		(net "PVDDCR_CPU0_P0")
	)
	(via
		(at 353.61118 -222.614236)
		(size 0.4064)
		(drill 0.2032)
		(layers "F.Cu" "B.Cu")
		(net "PVDDCR_CPU0_P0")
	)
	(via
		(at 350.791018 -227.474272)
		(size 0.4064)
		(drill 0.2032)
		(layers "F.Cu" "B.Cu")
		(net "PVDDCR_CPU0_P0")
	)
	(via
		(at 347.97111 -242.054126)
		(size 0.4064)
		(drill 0.2032)
		(layers "F.Cu" "B.Cu")
		(net "PVDDCR_CPU0_P0")
	)
	(via
		(at 357.287322 -184.015634)
		(size 0.508)
		(drill 0.254)
		(layers "F.Cu" "B.Cu")
		(net "PVDDCR_CPU0_P0")
	)
	(via
		(at 340.690454 -221.30131)
		(size 0.508)
		(drill 0.254)
		(layers "F.Cu" "B.Cu")
		(net "PVDDCR_CPU0_P0")
	)
	(via
		(at 379.599698 -197.91934)
		(size 0.508)
		(drill 0.254)
		(layers "F.Cu" "B.Cu")
		(net "PVDDCR_CPU0_P0")
	)
	(via
		(at 390.658858 -199.31634)
		(size 0.508)
		(drill 0.254)
		(layers "F.Cu" "B.Cu")
		(net "PVDDCR_CPU0_P0")
	)
	(via
		(at 368.644678 -238.814102)
		(size 0.4064)
		(drill 0.2032)
		(layers "F.Cu" "B.Cu")
		(net "PVDDCR_CPU0_P0")
	)
	(via
		(at 366.202722 -191.655954)
		(size 0.508)
		(drill 0.254)
		(layers "F.Cu" "B.Cu")
		(net "PVDDCR_CPU0_P0")
	)
	(via
		(at 371.46484 -250.154186)
		(size 0.4064)
		(drill 0.2032)
		(layers "F.Cu" "B.Cu")
		(net "PVDDCR_CPU0_P0")
	)
	(via
		(at 366.202722 -192.290954)
		(size 0.508)
		(drill 0.254)
		(layers "F.Cu" "B.Cu")
		(net "PVDDCR_CPU0_P0")
	)
	(via
		(at 353.902518 -181.475634)
		(size 0.508)
		(drill 0.254)
		(layers "F.Cu" "B.Cu")
		(net "PVDDCR_CPU0_P0")
	)
	(via
		(at 364.884716 -245.29415)
		(size 0.4064)
		(drill 0.2032)
		(layers "F.Cu" "B.Cu")
		(net "PVDDCR_CPU0_P0")
	)
	(via
		(at 370.54409 -194.723512)
		(size 0.508)
		(drill 0.254)
		(layers "F.Cu" "B.Cu")
		(net "PVDDCR_CPU0_P0")
	)
	(via
		(at 369.90909 -196.64934)
		(size 0.508)
		(drill 0.254)
		(layers "F.Cu" "B.Cu")
		(net "PVDDCR_CPU0_P0")
	)
	(via
		(at 354.08108 -250.964192)
		(size 0.4064)
		(drill 0.2032)
		(layers "F.Cu" "B.Cu")
		(net "PVDDCR_CPU0_P0")
	)
	(via
		(at 348.44101 -249.34418)
		(size 0.4064)
		(drill 0.2032)
		(layers "F.Cu" "B.Cu")
		(net "PVDDCR_CPU0_P0")
	)
	(via
		(at 378.953522 -196.628512)
		(size 0.508)
		(drill 0.254)
		(layers "F.Cu" "B.Cu")
		(net "PVDDCR_CPU0_P0")
	)
	(via
		(at 345.049094 -176.314354)
		(size 0.508)
		(drill 0.254)
		(layers "F.Cu" "B.Cu")
		(net "PVDDCR_CPU0_P0")
	)
	(via
		(at 353.61118 -238.814102)
		(size 0.4064)
		(drill 0.2032)
		(layers "F.Cu" "B.Cu")
		(net "PVDDCR_CPU0_P0")
	)
	(via
		(at 356.901242 -228.284278)
		(size 0.4064)
		(drill 0.2032)
		(layers "F.Cu" "B.Cu")
		(net "PVDDCR_CPU0_P0")
	)
	(via
		(at 379.588522 -197.263512)
		(size 0.508)
		(drill 0.254)
		(layers "F.Cu" "B.Cu")
		(net "PVDDCR_CPU0_P0")
	)
	(via
		(at 387.919722 -195.993512)
		(size 0.508)
		(drill 0.254)
		(layers "F.Cu" "B.Cu")
		(net "PVDDCR_CPU0_P0")
	)
	(via
		(at 362.815378 -192.946782)
		(size 0.508)
		(drill 0.254)
		(layers "F.Cu" "B.Cu")
		(net "PVDDCR_CPU0_P0")
	)
	(via
		(at 353.61118 -233.954066)
		(size 0.4064)
		(drill 0.2032)
		(layers "F.Cu" "B.Cu")
		(net "PVDDCR_CPU0_P0")
	)
	(via
		(at 382.966722 -195.993512)
		(size 0.508)
		(drill 0.254)
		(layers "F.Cu" "B.Cu")
		(net "PVDDCR_CPU0_P0")
	)
	(via
		(at 382.966722 -196.628512)
		(size 0.508)
		(drill 0.254)
		(layers "F.Cu" "B.Cu")
		(net "PVDDCR_CPU0_P0")
	)
	(via
		(at 370.524786 -238.814102)
		(size 0.4064)
		(drill 0.2032)
		(layers "F.Cu" "B.Cu")
		(net "PVDDCR_CPU0_P0")
	)
	(via
		(at 390.662922 -196.628512)
		(size 0.508)
		(drill 0.254)
		(layers "F.Cu" "B.Cu")
		(net "PVDDCR_CPU0_P0")
	)
	(via
		(at 390.658858 -197.91934)
		(size 0.508)
		(drill 0.254)
		(layers "F.Cu" "B.Cu")
		(net "PVDDCR_CPU0_P0")
	)
	(via
		(at 379.599698 -199.82434)
		(size 0.508)
		(drill 0.254)
		(layers "F.Cu" "B.Cu")
		(net "PVDDCR_CPU0_P0")
	)
	(via
		(at 373.344694 -233.954066)
		(size 0.4064)
		(drill 0.2032)
		(layers "F.Cu" "B.Cu")
		(net "PVDDCR_CPU0_P0")
	)
	(via
		(at 357.841042 -239.624108)
		(size 0.4064)
		(drill 0.2032)
		(layers "F.Cu" "B.Cu")
		(net "PVDDCR_CPU0_P0")
	)
	(via
		(at 363.944916 -222.614236)
		(size 0.4064)
		(drill 0.2032)
		(layers "F.Cu" "B.Cu")
		(net "PVDDCR_CPU0_P0")
	)
	(via
		(at 347.97111 -238.814102)
		(size 0.4064)
		(drill 0.2032)
		(layers "F.Cu" "B.Cu")
		(net "PVDDCR_CPU0_P0")
	)
	(via
		(at 365.82477 -242.054126)
		(size 0.4064)
		(drill 0.2032)
		(layers "F.Cu" "B.Cu")
		(net "PVDDCR_CPU0_P0")
	)
	(via
		(at 375.201434 -197.915784)
		(size 0.508)
		(drill 0.254)
		(layers "F.Cu" "B.Cu")
		(net "PVDDCR_CPU0_P0")
	)
	(via
		(at 349.062294 -176.949354)
		(size 0.508)
		(drill 0.254)
		(layers "F.Cu" "B.Cu")
		(net "PVDDCR_CPU0_P0")
	)
	(via
		(at 374.284748 -238.814102)
		(size 0.4064)
		(drill 0.2032)
		(layers "F.Cu" "B.Cu")
		(net "PVDDCR_CPU0_P0")
	)
	(via
		(at 349.697294 -177.584354)
		(size 0.508)
		(drill 0.254)
		(layers "F.Cu" "B.Cu")
		(net "PVDDCR_CPU0_P0")
	)
	(via
		(at 366.206278 -196.121782)
		(size 0.508)
		(drill 0.254)
		(layers "F.Cu" "B.Cu")
		(net "PVDDCR_CPU0_P0")
	)
	(via
		(at 382.966722 -197.263512)
		(size 0.508)
		(drill 0.254)
		(layers "F.Cu" "B.Cu")
		(net "PVDDCR_CPU0_P0")
	)
	(via
		(at 352.201226 -236.384084)
		(size 0.4064)
		(drill 0.2032)
		(layers "F.Cu" "B.Cu")
		(net "PVDDCR_CPU0_P0")
	)
	(via
		(at 375.201434 -199.185784)
		(size 0.508)
		(drill 0.254)
		(layers "F.Cu" "B.Cu")
		(net "PVDDCR_CPU0_P0")
	)
	(via
		(at 370.524786 -233.954066)
		(size 0.4064)
		(drill 0.2032)
		(layers "F.Cu" "B.Cu")
		(net "PVDDCR_CPU0_P0")
	)
	(via
		(at 344.681048 -225.044254)
		(size 0.4064)
		(drill 0.2032)
		(layers "F.Cu" "B.Cu")
		(net "PVDDCR_CPU0_P0")
	)
	(via
		(at 348.911164 -233.954066)
		(size 0.4064)
		(drill 0.2032)
		(layers "F.Cu" "B.Cu")
		(net "PVDDCR_CPU0_P0")
	)
	(via
		(at 345.151202 -238.814102)
		(size 0.4064)
		(drill 0.2032)
		(layers "F.Cu" "B.Cu")
		(net "PVDDCR_CPU0_P0")
	)
	(via
		(at 357.922322 -183.380634)
		(size 0.508)
		(drill 0.254)
		(layers "F.Cu" "B.Cu")
		(net "PVDDCR_CPU0_P0")
	)
	(via
		(at 374.284748 -242.054126)
		(size 0.4064)
		(drill 0.2032)
		(layers "F.Cu" "B.Cu")
		(net "PVDDCR_CPU0_P0")
	)
	(via
		(at 382.331722 -195.993512)
		(size 0.508)
		(drill 0.254)
		(layers "F.Cu" "B.Cu")
		(net "PVDDCR_CPU0_P0")
	)
	(via
		(at 355.961188 -225.044254)
		(size 0.4064)
		(drill 0.2032)
		(layers "F.Cu" "B.Cu")
		(net "PVDDCR_CPU0_P0")
	)
	(via
		(at 375.224802 -225.85426)
		(size 0.4064)
		(drill 0.2032)
		(layers "F.Cu" "B.Cu")
		(net "PVDDCR_CPU0_P0")
	)
	(via
		(at 362.534708 -225.044254)
		(size 0.4064)
		(drill 0.2032)
		(layers "F.Cu" "B.Cu")
		(net "PVDDCR_CPU0_P0")
	)
	(via
		(at 390.662922 -197.263512)
		(size 0.508)
		(drill 0.254)
		(layers "F.Cu" "B.Cu")
		(net "PVDDCR_CPU0_P0")
	)
	(via
		(at 365.571278 -192.946782)
		(size 0.508)
		(drill 0.254)
		(layers "F.Cu" "B.Cu")
		(net "PVDDCR_CPU0_P0")
	)
	(via
		(at 352.671126 -222.614236)
		(size 0.4064)
		(drill 0.2032)
		(layers "F.Cu" "B.Cu")
		(net "PVDDCR_CPU0_P0")
	)
	(via
		(at 353.267518 -181.475634)
		(size 0.508)
		(drill 0.254)
		(layers "F.Cu" "B.Cu")
		(net "PVDDCR_CPU0_P0")
	)
	(via
		(at 346.091002 -233.954066)
		(size 0.4064)
		(drill 0.2032)
		(layers "F.Cu" "B.Cu")
		(net "PVDDCR_CPU0_P0")
	)
	(via
		(at 366.202722 -191.020954)
		(size 0.508)
		(drill 0.254)
		(layers "F.Cu" "B.Cu")
		(net "PVDDCR_CPU0_P0")
	)
	(via
		(at 366.841278 -194.216782)
		(size 0.508)
		(drill 0.254)
		(layers "F.Cu" "B.Cu")
		(net "PVDDCR_CPU0_P0")
	)
	(via
		(at 350.321118 -250.964192)
		(size 0.4064)
		(drill 0.2032)
		(layers "F.Cu" "B.Cu")
		(net "PVDDCR_CPU0_P0")
	)
	(via
		(at 378.329698 -199.82434)
		(size 0.508)
		(drill 0.254)
		(layers "F.Cu" "B.Cu")
		(net "PVDDCR_CPU0_P0")
	)
	(via
		(at 374.563894 -197.263512)
		(size 0.508)
		(drill 0.254)
		(layers "F.Cu" "B.Cu")
		(net "PVDDCR_CPU0_P0")
	)
	(via
		(at 382.342898 -199.18934)
		(size 0.508)
		(drill 0.254)
		(layers "F.Cu" "B.Cu")
		(net "PVDDCR_CPU0_P0")
	)
	(via
		(at 361.545378 -190.406782)
		(size 0.508)
		(drill 0.254)
		(layers "F.Cu" "B.Cu")
		(net "PVDDCR_CPU0_P0")
	)
	(via
		(at 368.644932 -222.614236)
		(size 0.4064)
		(drill 0.2032)
		(layers "F.Cu" "B.Cu")
		(net "PVDDCR_CPU0_P0")
	)
	(via
		(at 369.90909 -194.723512)
		(size 0.508)
		(drill 0.254)
		(layers "F.Cu" "B.Cu")
		(net "PVDDCR_CPU0_P0")
	)
	(via
		(at 349.697294 -176.314354)
		(size 0.508)
		(drill 0.254)
		(layers "F.Cu" "B.Cu")
		(net "PVDDCR_CPU0_P0")
	)
	(via
		(at 345.684094 -176.314354)
		(size 0.508)
		(drill 0.254)
		(layers "F.Cu" "B.Cu")
		(net "PVDDCR_CPU0_P0")
	)
	(via
		(at 357.928418 -185.298842)
		(size 0.508)
		(drill 0.254)
		(layers "F.Cu" "B.Cu")
		(net "PVDDCR_CPU0_P0")
	)
	(via
		(at 361.545378 -191.041782)
		(size 0.508)
		(drill 0.254)
		(layers "F.Cu" "B.Cu")
		(net "PVDDCR_CPU0_P0")
	)
	(via
		(at 349.69323 -173.119542)
		(size 0.508)
		(drill 0.254)
		(layers "F.Cu" "B.Cu")
		(net "PVDDCR_CPU0_P0")
	)
	(via
		(at 353.264978 -183.401462)
		(size 0.508)
		(drill 0.254)
		(layers "F.Cu" "B.Cu")
		(net "PVDDCR_CPU0_P0")
	)
	(via
		(at 379.599698 -198.55434)
		(size 0.508)
		(drill 0.254)
		(layers "F.Cu" "B.Cu")
		(net "PVDDCR_CPU0_P0")
	)
	(via
		(at 347.97111 -248.534174)
		(size 0.4064)
		(drill 0.2032)
		(layers "F.Cu" "B.Cu")
		(net "PVDDCR_CPU0_P0")
	)
	(via
		(at 357.287322 -183.380634)
		(size 0.508)
		(drill 0.254)
		(layers "F.Cu" "B.Cu")
		(net "PVDDCR_CPU0_P0")
	)
	(via
		(at 366.206278 -194.851782)
		(size 0.508)
		(drill 0.254)
		(layers "F.Cu" "B.Cu")
		(net "PVDDCR_CPU0_P0")
	)
	(via
		(at 371.17909 -194.723512)
		(size 0.508)
		(drill 0.254)
		(layers "F.Cu" "B.Cu")
		(net "PVDDCR_CPU0_P0")
	)
	(via
		(at 369.584732 -225.85426)
		(size 0.4064)
		(drill 0.2032)
		(layers "F.Cu" "B.Cu")
		(net "PVDDCR_CPU0_P0")
	)
	(via
		(at 368.644678 -248.534174)
		(size 0.4064)
		(drill 0.2032)
		(layers "F.Cu" "B.Cu")
		(net "PVDDCR_CPU0_P0")
	)
	(via
		(at 349.062294 -176.314354)
		(size 0.508)
		(drill 0.254)
		(layers "F.Cu" "B.Cu")
		(net "PVDDCR_CPU0_P0")
	)
	(via
		(at 369.918234 -198.55434)
		(size 0.508)
		(drill 0.254)
		(layers "F.Cu" "B.Cu")
		(net "PVDDCR_CPU0_P0")
	)
	(via
		(at 371.188234 -199.820784)
		(size 0.508)
		(drill 0.254)
		(layers "F.Cu" "B.Cu")
		(net "PVDDCR_CPU0_P0")
	)
	(via
		(at 387.919722 -197.263512)
		(size 0.508)
		(drill 0.254)
		(layers "F.Cu" "B.Cu")
		(net "PVDDCR_CPU0_P0")
	)
	(via
		(at 374.55983 -194.723512)
		(size 0.508)
		(drill 0.254)
		(layers "F.Cu" "B.Cu")
		(net "PVDDCR_CPU0_P0")
	)
	(via
		(at 366.764824 -222.614236)
		(size 0.4064)
		(drill 0.2032)
		(layers "F.Cu" "B.Cu")
		(net "PVDDCR_CPU0_P0")
	)
	(via
		(at 375.201434 -199.820784)
		(size 0.508)
		(drill 0.254)
		(layers "F.Cu" "B.Cu")
		(net "PVDDCR_CPU0_P0")
	)
	(via
		(at 354.551234 -250.154186)
		(size 0.4064)
		(drill 0.2032)
		(layers "F.Cu" "B.Cu")
		(net "PVDDCR_CPU0_P0")
	)
	(via
		(at 363.474762 -225.044254)
		(size 0.4064)
		(drill 0.2032)
		(layers "F.Cu" "B.Cu")
		(net "PVDDCR_CPU0_P0")
	)
	(via
		(at 390.662922 -195.358512)
		(size 0.508)
		(drill 0.254)
		(layers "F.Cu" "B.Cu")
		(net "PVDDCR_CPU0_P0")
	)
	(via
		(at 348.911164 -245.29415)
		(size 0.4064)
		(drill 0.2032)
		(layers "F.Cu" "B.Cu")
		(net "PVDDCR_CPU0_P0")
	)
	(via
		(at 378.311918 -195.37934)
		(size 0.508)
		(drill 0.254)
		(layers "F.Cu" "B.Cu")
		(net "PVDDCR_CPU0_P0")
	)
	(via
		(at 387.278118 -199.18934)
		(size 0.508)
		(drill 0.254)
		(layers "F.Cu" "B.Cu")
		(net "PVDDCR_CPU0_P0")
	)
	(via
		(at 387.913118 -198.55434)
		(size 0.508)
		(drill 0.254)
		(layers "F.Cu" "B.Cu")
		(net "PVDDCR_CPU0_P0")
	)
	(via
		(at 378.04471 -222.614236)
		(size 0.4064)
		(drill 0.2032)
		(layers "F.Cu" "B.Cu")
		(net "PVDDCR_CPU0_P0")
	)
	(via
		(at 348.911164 -227.474272)
		(size 0.4064)
		(drill 0.2032)
		(layers "F.Cu" "B.Cu")
		(net "PVDDCR_CPU0_P0")
	)
	(via
		(at 351.731072 -230.714296)
		(size 0.4064)
		(drill 0.2032)
		(layers "F.Cu" "B.Cu")
		(net "PVDDCR_CPU0_P0")
	)
	(via
		(at 365.567722 -191.020954)
		(size 0.508)
		(drill 0.254)
		(layers "F.Cu" "B.Cu")
		(net "PVDDCR_CPU0_P0")
	)
	(via
		(at 357.841042 -249.34418)
		(size 0.4064)
		(drill 0.2032)
		(layers "F.Cu" "B.Cu")
		(net "PVDDCR_CPU0_P0")
	)
	(via
		(at 373.814848 -249.34418)
		(size 0.4064)
		(drill 0.2032)
		(layers "F.Cu" "B.Cu")
		(net "PVDDCR_CPU0_P0")
	)
	(via
		(at 370.550694 -195.993512)
		(size 0.508)
		(drill 0.254)
		(layers "F.Cu" "B.Cu")
		(net "PVDDCR_CPU0_P0")
	)
	(via
		(at 370.553234 -198.550784)
		(size 0.508)
		(drill 0.254)
		(layers "F.Cu" "B.Cu")
		(net "PVDDCR_CPU0_P0")
	)
	(via
		(at 354.544122 -182.110634)
		(size 0.508)
		(drill 0.254)
		(layers "F.Cu" "B.Cu")
		(net "PVDDCR_CPU0_P0")
	)
	(via
		(at 345.684094 -174.389542)
		(size 0.508)
		(drill 0.254)
		(layers "F.Cu" "B.Cu")
		(net "PVDDCR_CPU0_P0")
	)
	(via
		(at 382.327658 -194.723512)
		(size 0.508)
		(drill 0.254)
		(layers "F.Cu" "B.Cu")
		(net "PVDDCR_CPU0_P0")
	)
	(via
		(at 378.311918 -197.28434)
		(size 0.508)
		(drill 0.254)
		(layers "F.Cu" "B.Cu")
		(net "PVDDCR_CPU0_P0")
	)
	(via
		(at 371.93474 -249.34418)
		(size 0.4064)
		(drill 0.2032)
		(layers "F.Cu" "B.Cu")
		(net "PVDDCR_CPU0_P0")
	)
	(via
		(at 383.612898 -198.55434)
		(size 0.508)
		(drill 0.254)
		(layers "F.Cu" "B.Cu")
		(net "PVDDCR_CPU0_P0")
	)
	(via
		(at 350.791018 -248.534174)
		(size 0.4064)
		(drill 0.2032)
		(layers "F.Cu" "B.Cu")
		(net "PVDDCR_CPU0_P0")
	)
	(via
		(at 356.901242 -239.624108)
		(size 0.4064)
		(drill 0.2032)
		(layers "F.Cu" "B.Cu")
		(net "PVDDCR_CPU0_P0")
	)
	(via
		(at 366.841278 -193.581782)
		(size 0.508)
		(drill 0.254)
		(layers "F.Cu" "B.Cu")
		(net "PVDDCR_CPU0_P0")
	)
	(via
		(at 377.10491 -222.614236)
		(size 0.4064)
		(drill 0.2032)
		(layers "F.Cu" "B.Cu")
		(net "PVDDCR_CPU0_P0")
	)
	(via
		(at 386.643118 -196.64934)
		(size 0.508)
		(drill 0.254)
		(layers "F.Cu" "B.Cu")
		(net "PVDDCR_CPU0_P0")
	)
	(via
		(at 375.201434 -200.455784)
		(size 0.508)
		(drill 0.254)
		(layers "F.Cu" "B.Cu")
		(net "PVDDCR_CPU0_P0")
	)
	(via
		(at 362.534708 -239.624108)
		(size 0.4064)
		(drill 0.2032)
		(layers "F.Cu" "B.Cu")
		(net "PVDDCR_CPU0_P0")
	)
	(via
		(at 386.643118 -198.55434)
		(size 0.508)
		(drill 0.254)
		(layers "F.Cu" "B.Cu")
		(net "PVDDCR_CPU0_P0")
	)
	(via
		(at 382.331722 -195.358512)
		(size 0.508)
		(drill 0.254)
		(layers "F.Cu" "B.Cu")
		(net "PVDDCR_CPU0_P0")
	)
	(via
		(at 351.731072 -227.474272)
		(size 0.4064)
		(drill 0.2032)
		(layers "F.Cu" "B.Cu")
		(net "PVDDCR_CPU0_P0")
	)
	(via
		(at 349.697294 -179.489354)
		(size 0.508)
		(drill 0.254)
		(layers "F.Cu" "B.Cu")
		(net "PVDDCR_CPU0_P0")
	)
	(via
		(at 386.643118 -197.28434)
		(size 0.508)
		(drill 0.254)
		(layers "F.Cu" "B.Cu")
		(net "PVDDCR_CPU0_P0")
	)
	(via
		(at 373.344694 -230.714296)
		(size 0.4064)
		(drill 0.2032)
		(layers "F.Cu" "B.Cu")
		(net "PVDDCR_CPU0_P0")
	)
	(via
		(at 348.911164 -238.814102)
		(size 0.4064)
		(drill 0.2032)
		(layers "F.Cu" "B.Cu")
		(net "PVDDCR_CPU0_P0")
	)
	(via
		(at 375.19483 -194.723512)
		(size 0.508)
		(drill 0.254)
		(layers "F.Cu" "B.Cu")
		(net "PVDDCR_CPU0_P0")
	)
	(via
		(at 357.928418 -186.568842)
		(size 0.508)
		(drill 0.254)
		(layers "F.Cu" "B.Cu")
		(net "PVDDCR_CPU0_P0")
	)
	(via
		(at 382.331722 -197.263512)
		(size 0.508)
		(drill 0.254)
		(layers "F.Cu" "B.Cu")
		(net "PVDDCR_CPU0_P0")
	)
	(via
		(at 387.284722 -195.993512)
		(size 0.508)
		(drill 0.254)
		(layers "F.Cu" "B.Cu")
		(net "PVDDCR_CPU0_P0")
	)
	(via
		(at 349.697294 -173.754542)
		(size 0.508)
		(drill 0.254)
		(layers "F.Cu" "B.Cu")
		(net "PVDDCR_CPU0_P0")
	)
	(via
		(at 346.31249 -173.119542)
		(size 0.508)
		(drill 0.254)
		(layers "F.Cu" "B.Cu")
		(net "PVDDCR_CPU0_P0")
	)
	(via
		(at 378.311918 -196.64934)
		(size 0.508)
		(drill 0.254)
		(layers "F.Cu" "B.Cu")
		(net "PVDDCR_CPU0_P0")
	)
	(via
		(at 378.953522 -195.358512)
		(size 0.508)
		(drill 0.254)
		(layers "F.Cu" "B.Cu")
		(net "PVDDCR_CPU0_P0")
	)
	(via
		(at 344.211148 -222.614236)
		(size 0.4064)
		(drill 0.2032)
		(layers "F.Cu" "B.Cu")
		(net "PVDDCR_CPU0_P0")
	)
	(via
		(at 367.704878 -238.814102)
		(size 0.4064)
		(drill 0.2032)
		(layers "F.Cu" "B.Cu")
		(net "PVDDCR_CPU0_P0")
	)
	(via
		(at 367.704878 -245.29415)
		(size 0.4064)
		(drill 0.2032)
		(layers "F.Cu" "B.Cu")
		(net "PVDDCR_CPU0_P0")
	)
	(via
		(at 353.909122 -182.110634)
		(size 0.508)
		(drill 0.254)
		(layers "F.Cu" "B.Cu")
		(net "PVDDCR_CPU0_P0")
	)
	(via
		(at 370.550694 -197.263512)
		(size 0.508)
		(drill 0.254)
		(layers "F.Cu" "B.Cu")
		(net "PVDDCR_CPU0_P0")
	)
	(via
		(at 387.913118 -194.723512)
		(size 0.508)
		(drill 0.254)
		(layers "F.Cu" "B.Cu")
		(net "PVDDCR_CPU0_P0")
	)
	(via
		(at 378.964698 -198.55434)
		(size 0.508)
		(drill 0.254)
		(layers "F.Cu" "B.Cu")
		(net "PVDDCR_CPU0_P0")
	)
	(via
		(at 353.264978 -182.131462)
		(size 0.508)
		(drill 0.254)
		(layers "F.Cu" "B.Cu")
		(net "PVDDCR_CPU0_P0")
	)
	(via
		(at 357.371142 -237.19409)
		(size 0.4064)
		(drill 0.2032)
		(layers "F.Cu" "B.Cu")
		(net "PVDDCR_CPU0_P0")
	)
	(via
		(at 376.634756 -223.424242)
		(size 0.4064)
		(drill 0.2032)
		(layers "F.Cu" "B.Cu")
		(net "PVDDCR_CPU0_P0")
	)
	(via
		(at 357.922322 -182.745634)
		(size 0.508)
		(drill 0.254)
		(layers "F.Cu" "B.Cu")
		(net "PVDDCR_CPU0_P0")
	)
	(via
		(at 383.597658 -194.723512)
		(size 0.508)
		(drill 0.254)
		(layers "F.Cu" "B.Cu")
		(net "PVDDCR_CPU0_P0")
	)
	(via
		(at 386.643118 -197.91934)
		(size 0.508)
		(drill 0.254)
		(layers "F.Cu" "B.Cu")
		(net "PVDDCR_CPU0_P0")
	)
	(via
		(at 349.062294 -173.754542)
		(size 0.508)
		(drill 0.254)
		(layers "F.Cu" "B.Cu")
		(net "PVDDCR_CPU0_P0")
	)
	(via
		(at 371.46484 -242.054126)
		(size 0.4064)
		(drill 0.2032)
		(layers "F.Cu" "B.Cu")
		(net "PVDDCR_CPU0_P0")
	)
	(via
		(at 356.431088 -250.154186)
		(size 0.4064)
		(drill 0.2032)
		(layers "F.Cu" "B.Cu")
		(net "PVDDCR_CPU0_P0")
	)
	(via
		(at 348.911164 -250.154186)
		(size 0.4064)
		(drill 0.2032)
		(layers "F.Cu" "B.Cu")
		(net "PVDDCR_CPU0_P0")
	)
	(via
		(at 383.612898 -197.28434)
		(size 0.508)
		(drill 0.254)
		(layers "F.Cu" "B.Cu")
		(net "PVDDCR_CPU0_P0")
	)
	(via
		(at 359.740454 -250.27636)
		(size 0.4826)
		(drill 0.254)
		(layers "F.Cu" "B.Cu")
		(net "PVDDCR_CPU0_P0")
	)
	(via
		(at 349.697294 -178.854354)
		(size 0.508)
		(drill 0.254)
		(layers "F.Cu" "B.Cu")
		(net "PVDDCR_CPU0_P0")
	)
	(via
		(at 350.791018 -233.954066)
		(size 0.4064)
		(drill 0.2032)
		(layers "F.Cu" "B.Cu")
		(net "PVDDCR_CPU0_P0")
	)
	(via
		(at 387.278118 -198.55434)
		(size 0.508)
		(drill 0.254)
		(layers "F.Cu" "B.Cu")
		(net "PVDDCR_CPU0_P0")
	)
	(via
		(at 378.964698 -197.91934)
		(size 0.508)
		(drill 0.254)
		(layers "F.Cu" "B.Cu")
		(net "PVDDCR_CPU0_P0")
	)
	(via
		(at 346.319094 -177.584354)
		(size 0.508)
		(drill 0.254)
		(layers "F.Cu" "B.Cu")
		(net "PVDDCR_CPU0_P0")
	)
	(via
		(at 374.563894 -196.628512)
		(size 0.508)
		(drill 0.254)
		(layers "F.Cu" "B.Cu")
		(net "PVDDCR_CPU0_P0")
	)
	(via
		(at 355.961188 -250.964192)
		(size 0.4064)
		(drill 0.2032)
		(layers "F.Cu" "B.Cu")
		(net "PVDDCR_CPU0_P0")
	)
	(via
		(at 354.544122 -184.015634)
		(size 0.508)
		(drill 0.254)
		(layers "F.Cu" "B.Cu")
		(net "PVDDCR_CPU0_P0")
	)
	(via
		(at 365.82477 -230.714296)
		(size 0.4064)
		(drill 0.2032)
		(layers "F.Cu" "B.Cu")
		(net "PVDDCR_CPU0_P0")
	)
	(via
		(at 354.550218 -184.663842)
		(size 0.508)
		(drill 0.254)
		(layers "F.Cu" "B.Cu")
		(net "PVDDCR_CPU0_P0")
	)
	(via
		(at 357.293418 -188.600842)
		(size 0.6604)
		(drill 0.3302)
		(layers "F.Cu" "B.Cu")
		(net "PVDDCR_CPU0_P0")
	)
	(via
		(at 374.563894 -195.993512)
		(size 0.508)
		(drill 0.254)
		(layers "F.Cu" "B.Cu")
		(net "PVDDCR_CPU0_P0")
	)
	(via
		(at 353.264978 -182.766462)
		(size 0.508)
		(drill 0.254)
		(layers "F.Cu" "B.Cu")
		(net "PVDDCR_CPU0_P0")
	)
	(via
		(at 370.054886 -249.34418)
		(size 0.4064)
		(drill 0.2032)
		(layers "F.Cu" "B.Cu")
		(net "PVDDCR_CPU0_P0")
	)
	(via
		(at 374.284748 -248.534174)
		(size 0.4064)
		(drill 0.2032)
		(layers "F.Cu" "B.Cu")
		(net "PVDDCR_CPU0_P0")
	)
	(via
		(at 365.567722 -192.290954)
		(size 0.508)
		(drill 0.254)
		(layers "F.Cu" "B.Cu")
		(net "PVDDCR_CPU0_P0")
	)
	(via
		(at 367.704878 -250.154186)
		(size 0.4064)
		(drill 0.2032)
		(layers "F.Cu" "B.Cu")
		(net "PVDDCR_CPU0_P0")
	)
	(via
		(at 375.201434 -198.550784)
		(size 0.508)
		(drill 0.254)
		(layers "F.Cu" "B.Cu")
		(net "PVDDCR_CPU0_P0")
	)
	(via
		(at 362.182918 -189.750954)
		(size 0.508)
		(drill 0.254)
		(layers "F.Cu" "B.Cu")
		(net "PVDDCR_CPU0_P0")
	)
	(via
		(at 354.550218 -185.933842)
		(size 0.508)
		(drill 0.254)
		(layers "F.Cu" "B.Cu")
		(net "PVDDCR_CPU0_P0")
	)
	(via
		(at 373.931434 -201.090784)
		(size 0.508)
		(drill 0.254)
		(layers "F.Cu" "B.Cu")
		(net "PVDDCR_CPU0_P0")
	)
	(via
		(at 374.566434 -200.455784)
		(size 0.508)
		(drill 0.254)
		(layers "F.Cu" "B.Cu")
		(net "PVDDCR_CPU0_P0")
	)
	(via
		(at 345.049094 -175.044354)
		(size 0.508)
		(drill 0.254)
		(layers "F.Cu" "B.Cu")
		(net "PVDDCR_CPU0_P0")
	)
	(via
		(at 349.062294 -178.854354)
		(size 0.508)
		(drill 0.254)
		(layers "F.Cu" "B.Cu")
		(net "PVDDCR_CPU0_P0")
	)
	(via
		(at 345.049094 -175.679354)
		(size 0.508)
		(drill 0.254)
		(layers "F.Cu" "B.Cu")
		(net "PVDDCR_CPU0_P0")
	)
	(via
		(at 387.284722 -197.263512)
		(size 0.508)
		(drill 0.254)
		(layers "F.Cu" "B.Cu")
		(net "PVDDCR_CPU0_P0")
	)
	(via
		(at 356.901242 -226.664266)
		(size 0.4064)
		(drill 0.2032)
		(layers "F.Cu" "B.Cu")
		(net "PVDDCR_CPU0_P0")
	)
	(via
		(at 354.551234 -245.29415)
		(size 0.4064)
		(drill 0.2032)
		(layers "F.Cu" "B.Cu")
		(net "PVDDCR_CPU0_P0")
	)
	(via
		(at 345.684094 -175.024542)
		(size 0.508)
		(drill 0.254)
		(layers "F.Cu" "B.Cu")
		(net "PVDDCR_CPU0_P0")
	)
	(via
		(at 374.754902 -225.044254)
		(size 0.4064)
		(drill 0.2032)
		(layers "F.Cu" "B.Cu")
		(net "PVDDCR_CPU0_P0")
	)
	(via
		(at 357.287322 -182.110634)
		(size 0.508)
		(drill 0.254)
		(layers "F.Cu" "B.Cu")
		(net "PVDDCR_CPU0_P0")
	)
	(via
		(at 362.189522 -190.385954)
		(size 0.508)
		(drill 0.254)
		(layers "F.Cu" "B.Cu")
		(net "PVDDCR_CPU0_P0")
	)
	(via
		(at 346.091002 -245.29415)
		(size 0.4064)
		(drill 0.2032)
		(layers "F.Cu" "B.Cu")
		(net "PVDDCR_CPU0_P0")
	)
	(via
		(at 366.294924 -249.34418)
		(size 0.4064)
		(drill 0.2032)
		(layers "F.Cu" "B.Cu")
		(net "PVDDCR_CPU0_P0")
	)
	(via
		(at 371.46484 -238.814102)
		(size 0.4064)
		(drill 0.2032)
		(layers "F.Cu" "B.Cu")
		(net "PVDDCR_CPU0_P0")
	)
	(via
		(at 361.594908 -231.524048)
		(size 0.4064)
		(drill 0.2032)
		(layers "F.Cu" "B.Cu")
		(net "PVDDCR_CPU0_P0")
	)
	(via
		(at 362.189522 -191.655954)
		(size 0.508)
		(drill 0.254)
		(layers "F.Cu" "B.Cu")
		(net "PVDDCR_CPU0_P0")
	)
	(via
		(at 366.206278 -192.946782)
		(size 0.508)
		(drill 0.254)
		(layers "F.Cu" "B.Cu")
		(net "PVDDCR_CPU0_P0")
	)
	(via
		(at 383.612898 -199.18934)
		(size 0.508)
		(drill 0.254)
		(layers "F.Cu" "B.Cu")
		(net "PVDDCR_CPU0_P0")
	)
	(via
		(at 370.553234 -199.185784)
		(size 0.508)
		(drill 0.254)
		(layers "F.Cu" "B.Cu")
		(net "PVDDCR_CPU0_P0")
	)
	(via
		(at 356.901242 -242.864132)
		(size 0.4064)
		(drill 0.2032)
		(layers "F.Cu" "B.Cu")
		(net "PVDDCR_CPU0_P0")
	)
	(via
		(at 382.342898 -198.55434)
		(size 0.508)
		(drill 0.254)
		(layers "F.Cu" "B.Cu")
		(net "PVDDCR_CPU0_P0")
	)
	(via
		(at 368.644678 -233.954066)
		(size 0.4064)
		(drill 0.2032)
		(layers "F.Cu" "B.Cu")
		(net "PVDDCR_CPU0_P0")
	)
	(via
		(at 365.82477 -222.614236)
		(size 0.4064)
		(drill 0.2032)
		(layers "F.Cu" "B.Cu")
		(net "PVDDCR_CPU0_P0")
	)
	(via
		(at 362.824522 -191.020954)
		(size 0.508)
		(drill 0.254)
		(layers "F.Cu" "B.Cu")
		(net "PVDDCR_CPU0_P0")
	)
	(via
		(at 375.201434 -197.280784)
		(size 0.508)
		(drill 0.254)
		(layers "F.Cu" "B.Cu")
		(net "PVDDCR_CPU0_P0")
	)
	(via
		(at 384.381756 -178.96205)
		(size 0.508)
		(drill 0.254)
		(layers "F.Cu" "B.Cu")
		(net "PVDDCR_CPU0_P0")
	)
	(via
		(at 350.791018 -230.714042)
		(size 0.4064)
		(drill 0.2032)
		(layers "F.Cu" "B.Cu")
		(net "PVDDCR_CPU0_P0")
	)
	(via
		(at 382.977898 -199.18934)
		(size 0.508)
		(drill 0.254)
		(layers "F.Cu" "B.Cu")
		(net "PVDDCR_CPU0_P0")
	)
	(via
		(at 373.928894 -195.358512)
		(size 0.508)
		(drill 0.254)
		(layers "F.Cu" "B.Cu")
		(net "PVDDCR_CPU0_P0")
	)
	(via
		(at 347.97111 -233.954066)
		(size 0.4064)
		(drill 0.2032)
		(layers "F.Cu" "B.Cu")
		(net "PVDDCR_CPU0_P0")
	)
	(via
		(at 354.550218 -185.298842)
		(size 0.508)
		(drill 0.254)
		(layers "F.Cu" "B.Cu")
		(net "PVDDCR_CPU0_P0")
	)
	(via
		(at 361.594908 -228.284278)
		(size 0.4064)
		(drill 0.2032)
		(layers "F.Cu" "B.Cu")
		(net "PVDDCR_CPU0_P0")
	)
	(via
		(at 392.712956 -178.96205)
		(size 0.508)
		(drill 0.254)
		(layers "F.Cu" "B.Cu")
		(net "PVDDCR_CPU0_P0")
	)
	(via
		(at 378.953522 -197.263512)
		(size 0.508)
		(drill 0.254)
		(layers "F.Cu" "B.Cu")
		(net "PVDDCR_CPU0_P0")
	)
	(via
		(at 357.293418 -184.663842)
		(size 0.508)
		(drill 0.254)
		(layers "F.Cu" "B.Cu")
		(net "PVDDCR_CPU0_P0")
	)
	(via
		(at 366.206278 -196.883782)
		(size 0.6604)
		(drill 0.3302)
		(layers "F.Cu" "B.Cu")
		(net "PVDDCR_CPU0_P0")
	)
	(via
		(at 349.062294 -175.659542)
		(size 0.508)
		(drill 0.254)
		(layers "F.Cu" "B.Cu")
		(net "PVDDCR_CPU0_P0")
	)
	(via
		(at 349.062294 -179.489354)
		(size 0.508)
		(drill 0.254)
		(layers "F.Cu" "B.Cu")
		(net "PVDDCR_CPU0_P0")
	)
	(via
		(at 346.319094 -175.659542)
		(size 0.508)
		(drill 0.254)
		(layers "F.Cu" "B.Cu")
		(net "PVDDCR_CPU0_P0")
	)
	(via
		(at 387.278118 -199.82434)
		(size 0.508)
		(drill 0.254)
		(layers "F.Cu" "B.Cu")
		(net "PVDDCR_CPU0_P0")
	)
	(via
		(at 369.918234 -199.18934)
		(size 0.508)
		(drill 0.254)
		(layers "F.Cu" "B.Cu")
		(net "PVDDCR_CPU0_P0")
	)
	(via
		(at 371.188234 -200.455784)
		(size 0.508)
		(drill 0.254)
		(layers "F.Cu" "B.Cu")
		(net "PVDDCR_CPU0_P0")
	)
	(via
		(at 350.320864 -225.044254)
		(size 0.4064)
		(drill 0.2032)
		(layers "F.Cu" "B.Cu")
		(net "PVDDCR_CPU0_P0")
	)
	(via
		(at 350.791018 -242.054126)
		(size 0.4064)
		(drill 0.2032)
		(layers "F.Cu" "B.Cu")
		(net "PVDDCR_CPU0_P0")
	)
	(via
		(at 349.062294 -174.389542)
		(size 0.508)
		(drill 0.254)
		(layers "F.Cu" "B.Cu")
		(net "PVDDCR_CPU0_P0")
	)
	(via
		(at 345.151202 -230.714296)
		(size 0.4064)
		(drill 0.2032)
		(layers "F.Cu" "B.Cu")
		(net "PVDDCR_CPU0_P0")
	)
	(via
		(at 362.180378 -192.946782)
		(size 0.508)
		(drill 0.254)
		(layers "F.Cu" "B.Cu")
		(net "PVDDCR_CPU0_P0")
	)
	(via
		(at 374.284748 -222.614236)
		(size 0.4064)
		(drill 0.2032)
		(layers "F.Cu" "B.Cu")
		(net "PVDDCR_CPU0_P0")
	)
	(via
		(at 373.344694 -250.154186)
		(size 0.4064)
		(drill 0.2032)
		(layers "F.Cu" "B.Cu")
		(net "PVDDCR_CPU0_P0")
	)
	(via
		(at 387.913118 -197.91934)
		(size 0.508)
		(drill 0.254)
		(layers "F.Cu" "B.Cu")
		(net "PVDDCR_CPU0_P0")
	)
	(via
		(at 368.644678 -242.054126)
		(size 0.4064)
		(drill 0.2032)
		(layers "F.Cu" "B.Cu")
		(net "PVDDCR_CPU0_P0")
	)
	(via
		(at 362.534708 -228.284278)
		(size 0.4064)
		(drill 0.2032)
		(layers "F.Cu" "B.Cu")
		(net "PVDDCR_CPU0_P0")
	)
	(via
		(at 362.824522 -192.290954)
		(size 0.508)
		(drill 0.254)
		(layers "F.Cu" "B.Cu")
		(net "PVDDCR_CPU0_P0")
	)
	(via
		(at 344.211148 -225.85426)
		(size 0.4064)
		(drill 0.2032)
		(layers "F.Cu" "B.Cu")
		(net "PVDDCR_CPU0_P0")
	)
	(via
		(at 353.915218 -184.663842)
		(size 0.508)
		(drill 0.254)
		(layers "F.Cu" "B.Cu")
		(net "PVDDCR_CPU0_P0")
	)
	(via
		(at 387.278118 -194.723512)
		(size 0.508)
		(drill 0.254)
		(layers "F.Cu" "B.Cu")
		(net "PVDDCR_CPU0_P0")
	)
	(via
		(at 357.841042 -226.664266)
		(size 0.4064)
		(drill 0.2032)
		(layers "F.Cu" "B.Cu")
		(net "PVDDCR_CPU0_P0")
	)
	(via
		(at 354.551234 -230.714296)
		(size 0.4064)
		(drill 0.2032)
		(layers "F.Cu" "B.Cu")
		(net "PVDDCR_CPU0_P0")
	)
	(via
		(at 353.141026 -225.044254)
		(size 0.4064)
		(drill 0.2032)
		(layers "F.Cu" "B.Cu")
		(net "PVDDCR_CPU0_P0")
	)
	(via
		(at 366.202722 -190.385954)
		(size 0.508)
		(drill 0.254)
		(layers "F.Cu" "B.Cu")
		(net "PVDDCR_CPU0_P0")
	)
	(via
		(at 369.90909 -196.01434)
		(size 0.508)
		(drill 0.254)
		(layers "F.Cu" "B.Cu")
		(net "PVDDCR_CPU0_P0")
	)
	(via
		(at 345.151202 -227.474272)
		(size 0.4064)
		(drill 0.2032)
		(layers "F.Cu" "B.Cu")
		(net "PVDDCR_CPU0_P0")
	)
	(via
		(at 357.922322 -184.015634)
		(size 0.508)
		(drill 0.254)
		(layers "F.Cu" "B.Cu")
		(net "PVDDCR_CPU0_P0")
	)
	(via
		(at 373.931434 -198.550784)
		(size 0.508)
		(drill 0.254)
		(layers "F.Cu" "B.Cu")
		(net "PVDDCR_CPU0_P0")
	)
	(via
		(at 345.049094 -174.409354)
		(size 0.508)
		(drill 0.254)
		(layers "F.Cu" "B.Cu")
		(net "PVDDCR_CPU0_P0")
	)
	(via
		(at 357.841042 -231.524048)
		(size 0.4064)
		(drill 0.2032)
		(layers "F.Cu" "B.Cu")
		(net "PVDDCR_CPU0_P0")
	)
	(via
		(at 357.841042 -228.284278)
		(size 0.4064)
		(drill 0.2032)
		(layers "F.Cu" "B.Cu")
		(net "PVDDCR_CPU0_P0")
	)
	(via
		(at 369.918234 -197.91934)
		(size 0.508)
		(drill 0.254)
		(layers "F.Cu" "B.Cu")
		(net "PVDDCR_CPU0_P0")
	)
	(via
		(at 347.50121 -225.044254)
		(size 0.4064)
		(drill 0.2032)
		(layers "F.Cu" "B.Cu")
		(net "PVDDCR_CPU0_P0")
	)
	(via
		(at 354.08108 -249.34418)
		(size 0.4064)
		(drill 0.2032)
		(layers "F.Cu" "B.Cu")
		(net "PVDDCR_CPU0_P0")
	)
	(via
		(at 342.33104 -222.614236)
		(size 0.4064)
		(drill 0.2032)
		(layers "F.Cu" "B.Cu")
		(net "PVDDCR_CPU0_P0")
	)
	(via
		(at 390.658858 -198.55434)
		(size 0.508)
		(drill 0.254)
		(layers "F.Cu" "B.Cu")
		(net "PVDDCR_CPU0_P0")
	)
	(via
		(at 357.841042 -246.104156)
		(size 0.4064)
		(drill 0.2032)
		(layers "F.Cu" "B.Cu")
		(net "PVDDCR_CPU0_P0")
	)
	(via
		(at 371.185694 -196.628512)
		(size 0.508)
		(drill 0.254)
		(layers "F.Cu" "B.Cu")
		(net "PVDDCR_CPU0_P0")
	)
	(via
		(at 345.151202 -233.954066)
		(size 0.4064)
		(drill 0.2032)
		(layers "F.Cu" "B.Cu")
		(net "PVDDCR_CPU0_P0")
	)
	(via
		(at 346.319094 -176.949354)
		(size 0.508)
		(drill 0.254)
		(layers "F.Cu" "B.Cu")
		(net "PVDDCR_CPU0_P0")
	)
	(via
		(at 363.004862 -222.614236)
		(size 0.4064)
		(drill 0.2032)
		(layers "F.Cu" "B.Cu")
		(net "PVDDCR_CPU0_P0")
	)
	(via
		(at 387.919722 -196.628512)
		(size 0.508)
		(drill 0.254)
		(layers "F.Cu" "B.Cu")
		(net "PVDDCR_CPU0_P0")
	)
	(via
		(at 378.311918 -196.01434)
		(size 0.508)
		(drill 0.254)
		(layers "F.Cu" "B.Cu")
		(net "PVDDCR_CPU0_P0")
	)
	(via
		(at 364.414816 -249.34418)
		(size 0.4064)
		(drill 0.2032)
		(layers "F.Cu" "B.Cu")
		(net "PVDDCR_CPU0_P0")
	)
	(via
		(at 359.740454 -248.37136)
		(size 0.4826)
		(drill 0.254)
		(layers "F.Cu" "B.Cu")
		(net "PVDDCR_CPU0_P0")
	)
	(via
		(at 362.534708 -246.104156)
		(size 0.4064)
		(drill 0.2032)
		(layers "F.Cu" "B.Cu")
		(net "PVDDCR_CPU0_P0")
	)
	(via
		(at 359.337356 -165.864032)
		(size 0.508)
		(drill 0.254)
		(layers "F.Cu" "B.Cu")
		(net "PVDDCR_CPU0_P0")
	)
	(via
		(at 345.684094 -176.949354)
		(size 0.508)
		(drill 0.254)
		(layers "F.Cu" "B.Cu")
		(net "PVDDCR_CPU0_P0")
	)
	(via
		(at 356.901242 -234.764072)
		(size 0.4064)
		(drill 0.2032)
		(layers "F.Cu" "B.Cu")
		(net "PVDDCR_CPU0_P0")
	)
	(via
		(at 373.931434 -200.455784)
		(size 0.508)
		(drill 0.254)
		(layers "F.Cu" "B.Cu")
		(net "PVDDCR_CPU0_P0")
	)
	(via
		(at 373.344694 -248.534174)
		(size 0.4064)
		(drill 0.2032)
		(layers "F.Cu" "B.Cu")
		(net "PVDDCR_CPU0_P0")
	)
	(via
		(at 375.201434 -196.010784)
		(size 0.508)
		(drill 0.254)
		(layers "F.Cu" "B.Cu")
		(net "PVDDCR_CPU0_P0")
	)
	(via
		(at 365.571278 -193.581782)
		(size 0.508)
		(drill 0.254)
		(layers "F.Cu" "B.Cu")
		(net "PVDDCR_CPU0_P0")
	)
	(via
		(at 373.344694 -227.474272)
		(size 0.4064)
		(drill 0.2032)
		(layers "F.Cu" "B.Cu")
		(net "PVDDCR_CPU0_P0")
	)
	(via
		(at 346.091002 -238.814102)
		(size 0.4064)
		(drill 0.2032)
		(layers "F.Cu" "B.Cu")
		(net "PVDDCR_CPU0_P0")
	)
	(via
		(at 365.563658 -189.750954)
		(size 0.508)
		(drill 0.254)
		(layers "F.Cu" "B.Cu")
		(net "PVDDCR_CPU0_P0")
	)
	(via
		(at 374.284748 -245.29415)
		(size 0.4064)
		(drill 0.2032)
		(layers "F.Cu" "B.Cu")
		(net "PVDDCR_CPU0_P0")
	)
	(via
		(at 371.188234 -197.915784)
		(size 0.508)
		(drill 0.254)
		(layers "F.Cu" "B.Cu")
		(net "PVDDCR_CPU0_P0")
	)
	(via
		(at 371.93474 -225.044254)
		(size 0.4064)
		(drill 0.2032)
		(layers "F.Cu" "B.Cu")
		(net "PVDDCR_CPU0_P0")
	)
	(via
		(at 390.662922 -195.993512)
		(size 0.508)
		(drill 0.254)
		(layers "F.Cu" "B.Cu")
		(net "PVDDCR_CPU0_P0")
	)
	(via
		(at 366.841278 -196.121782)
		(size 0.508)
		(drill 0.254)
		(layers "F.Cu" "B.Cu")
		(net "PVDDCR_CPU0_P0")
	)
	(via
		(at 367.704878 -233.954066)
		(size 0.4064)
		(drill 0.2032)
		(layers "F.Cu" "B.Cu")
		(net "PVDDCR_CPU0_P0")
	)
	(via
		(at 378.311918 -194.723512)
		(size 0.508)
		(drill 0.254)
		(layers "F.Cu" "B.Cu")
		(net "PVDDCR_CPU0_P0")
	)
	(via
		(at 387.913118 -199.18934)
		(size 0.508)
		(drill 0.254)
		(layers "F.Cu" "B.Cu")
		(net "PVDDCR_CPU0_P0")
	)
	(via
		(at 371.46484 -248.534174)
		(size 0.4064)
		(drill 0.2032)
		(layers "F.Cu" "B.Cu")
		(net "PVDDCR_CPU0_P0")
	)
	(via
		(at 359.740454 -246.46636)
		(size 0.4826)
		(drill 0.254)
		(layers "F.Cu" "B.Cu")
		(net "PVDDCR_CPU0_P0")
	)
	(via
		(at 382.962658 -194.723512)
		(size 0.508)
		(drill 0.254)
		(layers "F.Cu" "B.Cu")
		(net "PVDDCR_CPU0_P0")
	)
	(via
		(at 373.344694 -238.814102)
		(size 0.4064)
		(drill 0.2032)
		(layers "F.Cu" "B.Cu")
		(net "PVDDCR_CPU0_P0")
	)
	(via
		(at 386.643118 -195.37934)
		(size 0.508)
		(drill 0.254)
		(layers "F.Cu" "B.Cu")
		(net "PVDDCR_CPU0_P0")
	)
	(via
		(at 343.271094 -224.234248)
		(size 0.4064)
		(drill 0.2032)
		(layers "F.Cu" "B.Cu")
		(net "PVDDCR_CPU0_P0")
	)
	(via
		(at 356.901242 -246.104156)
		(size 0.4064)
		(drill 0.2032)
		(layers "F.Cu" "B.Cu")
		(net "PVDDCR_CPU0_P0")
	)
	(via
		(at 362.189522 -191.020954)
		(size 0.508)
		(drill 0.254)
		(layers "F.Cu" "B.Cu")
		(net "PVDDCR_CPU0_P0")
	)
	(via
		(at 383.612898 -197.91934)
		(size 0.508)
		(drill 0.254)
		(layers "F.Cu" "B.Cu")
		(net "PVDDCR_CPU0_P0")
	)
	(via
		(at 350.791018 -222.614236)
		(size 0.4064)
		(drill 0.2032)
		(layers "F.Cu" "B.Cu")
		(net "PVDDCR_CPU0_P0")
	)
	(via
		(at 352.201226 -250.964192)
		(size 0.4064)
		(drill 0.2032)
		(layers "F.Cu" "B.Cu")
		(net "PVDDCR_CPU0_P0")
	)
	(via
		(at 373.344694 -242.054126)
		(size 0.4064)
		(drill 0.2032)
		(layers "F.Cu" "B.Cu")
		(net "PVDDCR_CPU0_P0")
	)
	(via
		(at 362.534708 -249.34418)
		(size 0.4064)
		(drill 0.2032)
		(layers "F.Cu" "B.Cu")
		(net "PVDDCR_CPU0_P0")
	)
	(via
		(at 379.588522 -196.628512)
		(size 0.508)
		(drill 0.254)
		(layers "F.Cu" "B.Cu")
		(net "PVDDCR_CPU0_P0")
	)
	(via
		(at 374.566434 -198.550784)
		(size 0.508)
		(drill 0.254)
		(layers "F.Cu" "B.Cu")
		(net "PVDDCR_CPU0_P0")
	)
	(via
		(at 349.062294 -177.584354)
		(size 0.508)
		(drill 0.254)
		(layers "F.Cu" "B.Cu")
		(net "PVDDCR_CPU0_P0")
	)
	(via
		(at 347.97111 -227.474272)
		(size 0.4064)
		(drill 0.2032)
		(layers "F.Cu" "B.Cu")
		(net "PVDDCR_CPU0_P0")
	)
	(via
		(at 351.731072 -242.054126)
		(size 0.4064)
		(drill 0.2032)
		(layers "F.Cu" "B.Cu")
		(net "PVDDCR_CPU0_P0")
	)
	(via
		(at 347.97111 -230.714296)
		(size 0.4064)
		(drill 0.2032)
		(layers "F.Cu" "B.Cu")
		(net "PVDDCR_CPU0_P0")
	)
	(via
		(at 362.824522 -190.385954)
		(size 0.508)
		(drill 0.254)
		(layers "F.Cu" "B.Cu")
		(net "PVDDCR_CPU0_P0")
	)
	(via
		(at 372.404894 -222.614236)
		(size 0.4064)
		(drill 0.2032)
		(layers "F.Cu" "B.Cu")
		(net "PVDDCR_CPU0_P0")
	)
	(via
		(at 354.551234 -227.474272)
		(size 0.4064)
		(drill 0.2032)
		(layers "F.Cu" "B.Cu")
		(net "PVDDCR_CPU0_P0")
	)
	(via
		(at 345.04249 -173.119542)
		(size 0.508)
		(drill 0.254)
		(layers "F.Cu" "B.Cu")
		(net "PVDDCR_CPU0_P0")
	)
	(via
		(at 357.293418 -185.298842)
		(size 0.508)
		(drill 0.254)
		(layers "F.Cu" "B.Cu")
		(net "PVDDCR_CPU0_P0")
	)
	(via
		(at 358.311196 -250.154186)
		(size 0.4064)
		(drill 0.2032)
		(layers "F.Cu" "B.Cu")
		(net "PVDDCR_CPU0_P0")
	)
	(via
		(at 371.93474 -250.964192)
		(size 0.4064)
		(drill 0.2032)
		(layers "F.Cu" "B.Cu")
		(net "PVDDCR_CPU0_P0")
	)
	(via
		(at 365.35487 -236.384084)
		(size 0.4064)
		(drill 0.2032)
		(layers "F.Cu" "B.Cu")
		(net "PVDDCR_CPU0_P0")
	)
	(via
		(at 357.293418 -185.933842)
		(size 0.508)
		(drill 0.254)
		(layers "F.Cu" "B.Cu")
		(net "PVDDCR_CPU0_P0")
	)
	(via
		(at 347.031056 -225.85426)
		(size 0.4064)
		(drill 0.2032)
		(layers "F.Cu" "B.Cu")
		(net "PVDDCR_CPU0_P0")
	)
	(via
		(at 351.031556 -157.357572)
		(size 0.508)
		(drill 0.254)
		(layers "F.Cu" "B.Cu")
		(net "PVDDCR_CPU0_P0")
	)
	(via
		(at 357.293418 -187.838842)
		(size 0.508)
		(drill 0.254)
		(layers "F.Cu" "B.Cu")
		(net "PVDDCR_CPU0_P0")
	)
	(via
		(at 357.283258 -181.475634)
		(size 0.508)
		(drill 0.254)
		(layers "F.Cu" "B.Cu")
		(net "PVDDCR_CPU0_P0")
	)
	(via
		(at 365.82477 -248.534174)
		(size 0.4064)
		(drill 0.2032)
		(layers "F.Cu" "B.Cu")
		(net "PVDDCR_CPU0_P0")
	)
	(via
		(at 379.581918 -194.723512)
		(size 0.508)
		(drill 0.254)
		(layers "F.Cu" "B.Cu")
		(net "PVDDCR_CPU0_P0")
	)
	(via
		(at 346.319094 -176.314354)
		(size 0.508)
		(drill 0.254)
		(layers "F.Cu" "B.Cu")
		(net "PVDDCR_CPU0_P0")
	)
	(via
		(at 370.550694 -195.358512)
		(size 0.508)
		(drill 0.254)
		(layers "F.Cu" "B.Cu")
		(net "PVDDCR_CPU0_P0")
	)
	(via
		(at 368.174778 -249.34418)
		(size 0.4064)
		(drill 0.2032)
		(layers "F.Cu" "B.Cu")
		(net "PVDDCR_CPU0_P0")
	)
	(via
		(at 391.297922 -197.263512)
		(size 0.508)
		(drill 0.254)
		(layers "F.Cu" "B.Cu")
		(net "PVDDCR_CPU0_P0")
	)
	(via
		(at 357.293418 -186.568842)
		(size 0.508)
		(drill 0.254)
		(layers "F.Cu" "B.Cu")
		(net "PVDDCR_CPU0_P0")
	)
	(via
		(at 371.185694 -195.993512)
		(size 0.508)
		(drill 0.254)
		(layers "F.Cu" "B.Cu")
		(net "PVDDCR_CPU0_P0")
	)
	(via
		(at 386.643118 -196.01434)
		(size 0.508)
		(drill 0.254)
		(layers "F.Cu" "B.Cu")
		(net "PVDDCR_CPU0_P0")
	)
	(via
		(at 362.534708 -226.664266)
		(size 0.4064)
		(drill 0.2032)
		(layers "F.Cu" "B.Cu")
		(net "PVDDCR_CPU0_P0")
	)
	(via
		(at 341.579454 -221.30131)
		(size 0.508)
		(drill 0.254)
		(layers "F.Cu" "B.Cu")
		(net "PVDDCR_CPU0_P0")
	)
	(via
		(at 366.841278 -192.946782)
		(size 0.508)
		(drill 0.254)
		(layers "F.Cu" "B.Cu")
		(net "PVDDCR_CPU0_P0")
	)
	(via
		(at 374.566434 -201.090784)
		(size 0.508)
		(drill 0.254)
		(layers "F.Cu" "B.Cu")
		(net "PVDDCR_CPU0_P0")
	)
	(via
		(at 352.671126 -250.154186)
		(size 0.4064)
		(drill 0.2032)
		(layers "F.Cu" "B.Cu")
		(net "PVDDCR_CPU0_P0")
	)
	(via
		(at 374.566434 -199.820784)
		(size 0.508)
		(drill 0.254)
		(layers "F.Cu" "B.Cu")
		(net "PVDDCR_CPU0_P0")
	)
	(via
		(at 346.091002 -242.054126)
		(size 0.4064)
		(drill 0.2032)
		(layers "F.Cu" "B.Cu")
		(net "PVDDCR_CPU0_P0")
	)
	(via
		(at 347.97111 -222.614236)
		(size 0.4064)
		(drill 0.2032)
		(layers "F.Cu" "B.Cu")
		(net "PVDDCR_CPU0_P0")
	)
	(via
		(at 371.185694 -197.263512)
		(size 0.508)
		(drill 0.254)
		(layers "F.Cu" "B.Cu")
		(net "PVDDCR_CPU0_P0")
	)
	(via
		(at 371.46484 -233.954066)
		(size 0.4064)
		(drill 0.2032)
		(layers "F.Cu" "B.Cu")
		(net "PVDDCR_CPU0_P0")
	)
	(via
		(at 357.841042 -242.864132)
		(size 0.4064)
		(drill 0.2032)
		(layers "F.Cu" "B.Cu")
		(net "PVDDCR_CPU0_P0")
	)
	(via
		(at 374.284748 -230.714296)
		(size 0.4064)
		(drill 0.2032)
		(layers "F.Cu" "B.Cu")
		(net "PVDDCR_CPU0_P0")
	)
	(via
		(at 366.206278 -193.581782)
		(size 0.508)
		(drill 0.254)
		(layers "F.Cu" "B.Cu")
		(net "PVDDCR_CPU0_P0")
	)
	(via
		(at 352.201226 -249.34418)
		(size 0.4064)
		(drill 0.2032)
		(layers "F.Cu" "B.Cu")
		(net "PVDDCR_CPU0_P0")
	)
	(via
		(at 366.764824 -225.85426)
		(size 0.4064)
		(drill 0.2032)
		(layers "F.Cu" "B.Cu")
		(net "PVDDCR_CPU0_P0")
	)
	(via
		(at 365.571278 -194.851782)
		(size 0.508)
		(drill 0.254)
		(layers "F.Cu" "B.Cu")
		(net "PVDDCR_CPU0_P0")
	)
	(via
		(at 345.151202 -242.054126)
		(size 0.4064)
		(drill 0.2032)
		(layers "F.Cu" "B.Cu")
		(net "PVDDCR_CPU0_P0")
	)
	(via
		(at 364.414816 -250.964192)
		(size 0.4064)
		(drill 0.2032)
		(layers "F.Cu" "B.Cu")
		(net "PVDDCR_CPU0_P0")
	)
	(via
		(at 371.185694 -195.358512)
		(size 0.508)
		(drill 0.254)
		(layers "F.Cu" "B.Cu")
		(net "PVDDCR_CPU0_P0")
	)
	(via
		(at 370.524786 -230.714296)
		(size 0.4064)
		(drill 0.2032)
		(layers "F.Cu" "B.Cu")
		(net "PVDDCR_CPU0_P0")
	)
	(via
		(at 390.658858 -194.723512)
		(size 0.508)
		(drill 0.254)
		(layers "F.Cu" "B.Cu")
		(net "PVDDCR_CPU0_P0")
	)
	(via
		(at 368.644678 -245.29415)
		(size 0.4064)
		(drill 0.2032)
		(layers "F.Cu" "B.Cu")
		(net "PVDDCR_CPU0_P0")
	)
	(via
		(at 365.82477 -245.29415)
		(size 0.4064)
		(drill 0.2032)
		(layers "F.Cu" "B.Cu")
		(net "PVDDCR_CPU0_P0")
	)
	(via
		(at 369.114832 -225.044254)
		(size 0.4064)
		(drill 0.2032)
		(layers "F.Cu" "B.Cu")
		(net "PVDDCR_CPU0_P0")
	)
	(via
		(at 348.911164 -230.714296)
		(size 0.4064)
		(drill 0.2032)
		(layers "F.Cu" "B.Cu")
		(net "PVDDCR_CPU0_P0")
	)
	(via
		(at 361.594908 -226.664266)
		(size 0.4064)
		(drill 0.2032)
		(layers "F.Cu" "B.Cu")
		(net "PVDDCR_CPU0_P0")
	)
	(via
		(at 370.524786 -242.054126)
		(size 0.4064)
		(drill 0.2032)
		(layers "F.Cu" "B.Cu")
		(net "PVDDCR_CPU0_P0")
	)
	(via
		(at 362.534708 -242.864132)
		(size 0.4064)
		(drill 0.2032)
		(layers "F.Cu" "B.Cu")
		(net "PVDDCR_CPU0_P0")
	)
	(via
		(at 345.151202 -245.29415)
		(size 0.4064)
		(drill 0.2032)
		(layers "F.Cu" "B.Cu")
		(net "PVDDCR_CPU0_P0")
	)
	(via
		(at 391.293858 -194.723512)
		(size 0.508)
		(drill 0.254)
		(layers "F.Cu" "B.Cu")
		(net "PVDDCR_CPU0_P0")
	)
	(via
		(at 364.884716 -248.534174)
		(size 0.4064)
		(drill 0.2032)
		(layers "F.Cu" "B.Cu")
		(net "PVDDCR_CPU0_P0")
	)
	(via
		(at 386.643118 -194.723512)
		(size 0.508)
		(drill 0.254)
		(layers "F.Cu" "B.Cu")
		(net "PVDDCR_CPU0_P0")
	)
	(via
		(at 345.67749 -173.119542)
		(size 0.508)
		(drill 0.254)
		(layers "F.Cu" "B.Cu")
		(net "PVDDCR_CPU0_P0")
	)
	(via
		(at 378.964698 -199.18934)
		(size 0.508)
		(drill 0.254)
		(layers "F.Cu" "B.Cu")
		(net "PVDDCR_CPU0_P0")
	)
	(via
		(at 351.731072 -245.29415)
		(size 0.4064)
		(drill 0.2032)
		(layers "F.Cu" "B.Cu")
		(net "PVDDCR_CPU0_P0")
	)
	(via
		(at 364.884716 -233.954066)
		(size 0.4064)
		(drill 0.2032)
		(layers "F.Cu" "B.Cu")
		(net "PVDDCR_CPU0_P0")
	)
	(via
		(at 371.188234 -198.550784)
		(size 0.508)
		(drill 0.254)
		(layers "F.Cu" "B.Cu")
		(net "PVDDCR_CPU0_P0")
	)
	(via
		(at 349.697294 -178.219354)
		(size 0.508)
		(drill 0.254)
		(layers "F.Cu" "B.Cu")
		(net "PVDDCR_CPU0_P0")
	)
	(via
		(at 357.841042 -234.764072)
		(size 0.4064)
		(drill 0.2032)
		(layers "F.Cu" "B.Cu")
		(net "PVDDCR_CPU0_P0")
	)
	(via
		(at 378.946918 -194.723512)
		(size 0.508)
		(drill 0.254)
		(layers "F.Cu" "B.Cu")
		(net "PVDDCR_CPU0_P0")
	)
	(via
		(at 391.293858 -197.91934)
		(size 0.508)
		(drill 0.254)
		(layers "F.Cu" "B.Cu")
		(net "PVDDCR_CPU0_P0")
	)
	(via
		(at 353.61118 -248.534174)
		(size 0.4064)
		(drill 0.2032)
		(layers "F.Cu" "B.Cu")
		(net "PVDDCR_CPU0_P0")
	)
	(via
		(at 391.293858 -198.55434)
		(size 0.508)
		(drill 0.254)
		(layers "F.Cu" "B.Cu")
		(net "PVDDCR_CPU0_P0")
	)
	(via
		(at 353.61118 -245.29415)
		(size 0.4064)
		(drill 0.2032)
		(layers "F.Cu" "B.Cu")
		(net "PVDDCR_CPU0_P0")
	)
	(via
		(at 365.82477 -233.954066)
		(size 0.4064)
		(drill 0.2032)
		(layers "F.Cu" "B.Cu")
		(net "PVDDCR_CPU0_P0")
	)
	(via
		(at 361.545378 -191.676782)
		(size 0.508)
		(drill 0.254)
		(layers "F.Cu" "B.Cu")
		(net "PVDDCR_CPU0_P0")
	)
	(via
		(at 370.553234 -199.820784)
		(size 0.508)
		(drill 0.254)
		(layers "F.Cu" "B.Cu")
		(net "PVDDCR_CPU0_P0")
	)
	(via
		(at 386.643118 -199.82434)
		(size 0.508)
		(drill 0.254)
		(layers "F.Cu" "B.Cu")
		(net "PVDDCR_CPU0_P0")
	)
	(via
		(at 367.704878 -230.714296)
		(size 0.4064)
		(drill 0.2032)
		(layers "F.Cu" "B.Cu")
		(net "PVDDCR_CPU0_P0")
	)
	(via
		(at 365.82477 -227.474272)
		(size 0.4064)
		(drill 0.2032)
		(layers "F.Cu" "B.Cu")
		(net "PVDDCR_CPU0_P0")
	)
	(via
		(at 347.031056 -222.614236)
		(size 0.4064)
		(drill 0.2032)
		(layers "F.Cu" "B.Cu")
		(net "PVDDCR_CPU0_P0")
	)
	(via
		(at 362.064808 -250.154186)
		(size 0.4064)
		(drill 0.2032)
		(layers "F.Cu" "B.Cu")
		(net "PVDDCR_CPU0_P0")
	)
	(via
		(at 374.566434 -197.915784)
		(size 0.508)
		(drill 0.254)
		(layers "F.Cu" "B.Cu")
		(net "PVDDCR_CPU0_P0")
	)
	(via
		(at 387.913118 -199.82434)
		(size 0.508)
		(drill 0.254)
		(layers "F.Cu" "B.Cu")
		(net "PVDDCR_CPU0_P0")
	)
	(via
		(at 373.931434 -199.185784)
		(size 0.508)
		(drill 0.254)
		(layers "F.Cu" "B.Cu")
		(net "PVDDCR_CPU0_P0")
	)
	(via
		(at 366.206278 -194.216782)
		(size 0.508)
		(drill 0.254)
		(layers "F.Cu" "B.Cu")
		(net "PVDDCR_CPU0_P0")
	)
	(via
		(at 349.850964 -225.85426)
		(size 0.4064)
		(drill 0.2032)
		(layers "F.Cu" "B.Cu")
		(net "PVDDCR_CPU0_P0")
	)
	(via
		(at 373.344694 -245.29415)
		(size 0.4064)
		(drill 0.2032)
		(layers "F.Cu" "B.Cu")
		(net "PVDDCR_CPU0_P0")
	)
	(via
		(at 366.198658 -189.750954)
		(size 0.508)
		(drill 0.254)
		(layers "F.Cu" "B.Cu")
		(net "PVDDCR_CPU0_P0")
	)
	(via
		(at 349.062294 -178.219354)
		(size 0.508)
		(drill 0.254)
		(layers "F.Cu" "B.Cu")
		(net "PVDDCR_CPU0_P0")
	)
	(via
		(at 378.329698 -197.91934)
		(size 0.508)
		(drill 0.254)
		(layers "F.Cu" "B.Cu")
		(net "PVDDCR_CPU0_P0")
	)
	(via
		(at 349.697294 -174.389542)
		(size 0.508)
		(drill 0.254)
		(layers "F.Cu" "B.Cu")
		(net "PVDDCR_CPU0_P0")
	)
	(via
		(at 363.944916 -250.154186)
		(size 0.4064)
		(drill 0.2032)
		(layers "F.Cu" "B.Cu")
		(net "PVDDCR_CPU0_P0")
	)
	(via
		(at 349.697294 -176.949354)
		(size 0.508)
		(drill 0.254)
		(layers "F.Cu" "B.Cu")
		(net "PVDDCR_CPU0_P0")
	)
	(via
		(at 375.201434 -201.090784)
		(size 0.508)
		(drill 0.254)
		(layers "F.Cu" "B.Cu")
		(net "PVDDCR_CPU0_P0")
	)
	(via
		(at 383.612898 -196.64934)
		(size 0.508)
		(drill 0.254)
		(layers "F.Cu" "B.Cu")
		(net "PVDDCR_CPU0_P0")
	)
	(via
		(at 387.278118 -197.91934)
		(size 0.508)
		(drill 0.254)
		(layers "F.Cu" "B.Cu")
		(net "PVDDCR_CPU0_P0")
	)
	(via
		(at 348.911164 -242.054126)
		(size 0.4064)
		(drill 0.2032)
		(layers "F.Cu" "B.Cu")
		(net "PVDDCR_CPU0_P0")
	)
	(via
		(at 357.293418 -187.203842)
		(size 0.508)
		(drill 0.254)
		(layers "F.Cu" "B.Cu")
		(net "PVDDCR_CPU0_P0")
	)
	(via
		(at 372.404894 -225.85426)
		(size 0.4064)
		(drill 0.2032)
		(layers "F.Cu" "B.Cu")
		(net "PVDDCR_CPU0_P0")
	)
	(via
		(at 349.062294 -180.251354)
		(size 0.6604)
		(drill 0.3302)
		(layers "F.Cu" "B.Cu")
		(net "PVDDCR_CPU0_P0")
	)
	(via
		(at 379.588522 -195.993512)
		(size 0.508)
		(drill 0.254)
		(layers "F.Cu" "B.Cu")
		(net "PVDDCR_CPU0_P0")
	)
	(via
		(at 374.284748 -233.954066)
		(size 0.4064)
		(drill 0.2032)
		(layers "F.Cu" "B.Cu")
		(net "PVDDCR_CPU0_P0")
	)
	(via
		(at 354.551234 -238.814102)
		(size 0.4064)
		(drill 0.2032)
		(layers "F.Cu" "B.Cu")
		(net "PVDDCR_CPU0_P0")
	)
	(via
		(at 366.841278 -195.486782)
		(size 0.508)
		(drill 0.254)
		(layers "F.Cu" "B.Cu")
		(net "PVDDCR_CPU0_P0")
	)
	(via
		(at 354.537518 -181.475634)
		(size 0.508)
		(drill 0.254)
		(layers "F.Cu" "B.Cu")
		(net "PVDDCR_CPU0_P0")
	)
	(via
		(at 382.342898 -200.58634)
		(size 0.6604)
		(drill 0.3302)
		(layers "F.Cu" "B.Cu")
		(net "PVDDCR_CPU0_P0")
	)
	(via
		(at 371.46484 -227.474272)
		(size 0.4064)
		(drill 0.2032)
		(layers "F.Cu" "B.Cu")
		(net "PVDDCR_CPU0_P0")
	)
	(segment
		(start 384.739388 -179.319682)
		(end 384.381756 -178.96205)
		(width 0.381)
		(layer "B.Cu")
		(net "PVDDCR_CPU0_P0")
	)
	(segment
		(start 393.070588 -179.319682)
		(end 392.712956 -178.96205)
		(width 0.381)
		(layer "B.Cu")
		(net "PVDDCR_CPU0_P0")
	)
	(segment
		(start 393.070588 -179.678584)
		(end 393.070588 -179.319682)
		(width 0.381)
		(layer "B.Cu")
		(net "PVDDCR_CPU0_P0")
	)
	(segment
		(start 359.694988 -166.221664)
		(end 359.337356 -165.864032)
		(width 0.381)
		(layer "B.Cu")
		(net "PVDDCR_CPU0_P0")
	)
	(segment
		(start 371.639592 -245.468902)
		(end 371.46484 -245.29415)
		(width 0.508)
		(layer "B.Cu")
		(net "PVDDCR_CPU0_P0")
	)
	(segment
		(start 351.389188 -158.074106)
		(end 351.389188 -157.715204)
		(width 0.381)
		(layer "B.Cu")
		(net "PVDDCR_CPU0_P0")
	)
	(segment
		(start 384.739388 -179.678584)
		(end 384.739388 -179.319682)
		(width 0.381)
		(layer "B.Cu")
		(net "PVDDCR_CPU0_P0")
	)
	(segment
		(start 371.646958 -245.468902)
		(end 371.639592 -245.468902)
		(width 0.508)
		(layer "B.Cu")
		(net "PVDDCR_CPU0_P0")
	)
	(segment
		(start 376.33656 -179.319682)
		(end 375.978928 -178.96205)
		(width 0.381)
		(layer "B.Cu")
		(net "PVDDCR_CPU0_P0")
	)
	(segment
		(start 376.33656 -179.678584)
		(end 376.33656 -179.319682)
		(width 0.381)
		(layer "B.Cu")
		(net "PVDDCR_CPU0_P0")
	)
	(segment
		(start 367.975388 -174.706026)
		(end 367.975388 -174.347124)
		(width 0.381)
		(layer "B.Cu")
		(net "PVDDCR_CPU0_P0")
	)
	(segment
		(start 359.694988 -166.430706)
		(end 359.694988 -166.221664)
		(width 0.381)
		(layer "B.Cu")
		(net "PVDDCR_CPU0_P0")
	)
	(segment
		(start 367.975388 -174.347124)
		(end 367.617756 -173.989492)
		(width 0.381)
		(layer "B.Cu")
		(net "PVDDCR_CPU0_P0")
	)
	(segment
		(start 351.389188 -157.715204)
		(end 351.031556 -157.357572)
		(width 0.381)
		(layer "B.Cu")
		(net "PVDDCR_CPU0_P0")
	)
	(segment
		(start 375.248678 -194.669664)
		(end 375.19483 -194.723512)
		(width 0.381)
		(layer "In2.Cu")
		(net "PVDDCR_CPU0_P0")
	)
	(segment
		(start 367.909094 -175.120554)
		(end 366.866678 -176.16297)
		(width 0.381)
		(layer "In2.Cu")
		(net "PVDDCR_CPU0_P0")
	)
	(segment
		(start 366.866678 -176.16297)
		(end 366.866678 -189.082934)
		(width 0.381)
		(layer "In2.Cu")
		(net "PVDDCR_CPU0_P0")
	)
	(segment
		(start 383.923032 -188.78423)
		(end 383.923032 -194.398138)
		(width 0.381)
		(layer "In2.Cu")
		(net "PVDDCR_CPU0_P0")
	)
	(segment
		(start 359.628694 -166.15537)
		(end 359.628694 -166.845234)
		(width 0.381)
		(layer "In2.Cu")
		(net "PVDDCR_CPU0_P0")
	)
	(segment
		(start 393.004294 -179.253388)
		(end 393.004294 -180.135784)
		(width 0.381)
		(layer "In2.Cu")
		(net "PVDDCR_CPU0_P0")
	)
	(segment
		(start 391.293858 -188.827156)
		(end 391.293858 -194.723512)
		(width 0.381)
		(layer "In2.Cu")
		(net "PVDDCR_CPU0_P0")
	)
	(segment
		(start 367.909094 -174.28083)
		(end 367.909094 -175.120554)
		(width 0.381)
		(layer "In2.Cu")
		(net "PVDDCR_CPU0_P0")
	)
	(segment
		(start 384.381756 -178.96205)
		(end 384.61696 -179.197254)
		(width 0.381)
		(layer "In2.Cu")
		(net "PVDDCR_CPU0_P0")
	)
	(segment
		(start 359.628694 -166.845234)
		(end 358.586278 -167.88765)
		(width 0.381)
		(layer "In2.Cu")
		(net "PVDDCR_CPU0_P0")
	)
	(segment
		(start 383.612898 -181.153308)
		(end 383.612898 -188.474096)
		(width 0.381)
		(layer "In2.Cu")
		(net "PVDDCR_CPU0_P0")
	)
	(segment
		(start 392.712956 -178.96205)
		(end 393.004294 -179.253388)
		(width 0.381)
		(layer "In2.Cu")
		(net "PVDDCR_CPU0_P0")
	)
	(segment
		(start 367.617756 -173.989492)
		(end 367.909094 -174.28083)
		(width 0.381)
		(layer "In2.Cu")
		(net "PVDDCR_CPU0_P0")
	)
	(segment
		(start 376.270266 -180.093112)
		(end 375.248678 -181.1147)
		(width 0.381)
		(layer "In2.Cu")
		(net "PVDDCR_CPU0_P0")
	)
	(segment
		(start 383.612898 -188.474096)
		(end 383.923032 -188.78423)
		(width 0.381)
		(layer "In2.Cu")
		(net "PVDDCR_CPU0_P0")
	)
	(segment
		(start 351.415604 -158.395924)
		(end 351.415604 -157.74162)
		(width 0.381)
		(layer "In2.Cu")
		(net "PVDDCR_CPU0_P0")
	)
	(segment
		(start 391.961878 -181.1782)
		(end 391.961878 -188.159136)
		(width 0.381)
		(layer "In2.Cu")
		(net "PVDDCR_CPU0_P0")
	)
	(segment
		(start 358.586278 -167.88765)
		(end 358.586278 -180.807614)
		(width 0.381)
		(layer "In2.Cu")
		(net "PVDDCR_CPU0_P0")
	)
	(segment
		(start 391.961878 -188.159136)
		(end 391.293858 -188.827156)
		(width 0.381)
		(layer "In2.Cu")
		(net "PVDDCR_CPU0_P0")
	)
	(segment
		(start 375.248678 -181.1147)
		(end 375.248678 -194.669664)
		(width 0.381)
		(layer "In2.Cu")
		(net "PVDDCR_CPU0_P0")
	)
	(segment
		(start 376.270266 -179.253388)
		(end 376.270266 -180.093112)
		(width 0.381)
		(layer "In2.Cu")
		(net "PVDDCR_CPU0_P0")
	)
	(segment
		(start 383.923032 -194.398138)
		(end 383.597658 -194.723512)
		(width 0.381)
		(layer "In2.Cu")
		(net "PVDDCR_CPU0_P0")
	)
	(segment
		(start 375.978928 -178.96205)
		(end 376.270266 -179.253388)
		(width 0.381)
		(layer "In2.Cu")
		(net "PVDDCR_CPU0_P0")
	)
	(segment
		(start 358.586278 -180.807614)
		(end 357.918258 -181.475634)
		(width 0.381)
		(layer "In2.Cu")
		(net "PVDDCR_CPU0_P0")
	)
	(segment
		(start 349.69323 -165.338506)
		(end 350.280478 -164.751258)
		(width 0.381)
		(layer "In2.Cu")
		(net "PVDDCR_CPU0_P0")
	)
	(segment
		(start 366.866678 -189.082934)
		(end 366.198658 -189.750954)
		(width 0.381)
		(layer "In2.Cu")
		(net "PVDDCR_CPU0_P0")
	)
	(segment
		(start 359.337356 -165.864032)
		(end 359.628694 -166.15537)
		(width 0.381)
		(layer "In2.Cu")
		(net "PVDDCR_CPU0_P0")
	)
	(segment
		(start 384.61696 -179.197254)
		(end 384.61696 -180.149246)
		(width 0.381)
		(layer "In2.Cu")
		(net "PVDDCR_CPU0_P0")
	)
	(segment
		(start 350.280478 -159.53105)
		(end 351.415604 -158.395924)
		(width 0.381)
		(layer "In2.Cu")
		(net "PVDDCR_CPU0_P0")
	)
	(segment
		(start 393.004294 -180.135784)
		(end 391.961878 -181.1782)
		(width 0.381)
		(layer "In2.Cu")
		(net "PVDDCR_CPU0_P0")
	)
	(segment
		(start 350.280478 -164.751258)
		(end 350.280478 -159.53105)
		(width 0.381)
		(layer "In2.Cu")
		(net "PVDDCR_CPU0_P0")
	)
	(segment
		(start 351.415604 -157.74162)
		(end 351.031556 -157.357572)
		(width 0.381)
		(layer "In2.Cu")
		(net "PVDDCR_CPU0_P0")
	)
	(segment
		(start 349.69323 -173.119542)
		(end 349.69323 -165.338506)
		(width 0.381)
		(layer "In2.Cu")
		(net "PVDDCR_CPU0_P0")
	)
	(segment
		(start 384.61696 -180.149246)
		(end 383.612898 -181.153308)
		(width 0.381)
		(layer "In2.Cu")
		(net "PVDDCR_CPU0_P0")
	)
	(segment
		(start 181.384194 -172.430186)
		(end 180.889656 -171.935648)
		(width 0.10668)
		(layer "F.Cu")
		(net "PVDD33_S5_EN")
	)
	(segment
		(start 181.384194 -173.368716)
		(end 181.384194 -172.430186)
		(width 0.10668)
		(layer "F.Cu")
		(net "PVDD33_S5_EN")
	)
	(segment
		(start 191.651128 -183.63565)
		(end 181.384194 -173.368716)
		(width 0.10668)
		(layer "F.Cu")
		(net "PVDD33_S5_EN")
	)
	(segment
		(start 206.405734 -344.078052)
		(end 206.189834 -344.293952)
		(width 0.10668)
		(layer "F.Cu")
		(net "PVDD33_S5_EN")
	)
	(segment
		(start 204.813154 -342.945212)
		(end 206.116174 -342.945212)
		(width 0.10668)
		(layer "F.Cu")
		(net "PVDD33_S5_EN")
	)
	(segment
		(start 204.392784 -343.404952)
		(end 204.392784 -343.365582)
		(width 0.10668)
		(layer "F.Cu")
		(net "PVDD33_S5_EN")
	)
	(segment
		(start 204.392784 -343.365582)
		(end 204.813154 -342.945212)
		(width 0.10668)
		(layer "F.Cu")
		(net "PVDD33_S5_EN")
	)
	(segment
		(start 206.116174 -342.945212)
		(end 206.405734 -343.234772)
		(width 0.10668)
		(layer "F.Cu")
		(net "PVDD33_S5_EN")
	)
	(segment
		(start 202.254104 -341.855044)
		(end 202.709526 -341.855044)
		(width 0.10668)
		(layer "F.Cu")
		(net "PVDD33_S5_EN")
	)
	(segment
		(start 204.259434 -343.404952)
		(end 204.392784 -343.404952)
		(width 0.10668)
		(layer "F.Cu")
		(net "PVDD33_S5_EN")
	)
	(segment
		(start 206.405734 -343.234772)
		(end 206.405734 -344.078052)
		(width 0.10668)
		(layer "F.Cu")
		(net "PVDD33_S5_EN")
	)
	(segment
		(start 202.709526 -341.855044)
		(end 204.259434 -343.404952)
		(width 0.10668)
		(layer "F.Cu")
		(net "PVDD33_S5_EN")
	)
	(segment
		(start 191.651128 -186.908186)
		(end 191.651128 -183.63565)
		(width 0.10668)
		(layer "F.Cu")
		(net "PVDD33_S5_EN")
	)
	(via
		(at 211.786978 -107.507278)
		(size 0.508)
		(drill 0.254)
		(layers "F.Cu" "B.Cu")
		(net "PVDD33_S5_EN")
	)
	(via
		(at 180.889656 -171.935648)
		(size 0.508)
		(drill 0.254)
		(layers "F.Cu" "B.Cu")
		(net "PVDD33_S5_EN")
	)
	(via
		(at 191.651128 -186.908186)
		(size 0.508)
		(drill 0.254)
		(layers "F.Cu" "B.Cu")
		(net "PVDD33_S5_EN")
	)
	(via
		(at 217.038936 -164.448744)
		(size 0.508)
		(drill 0.254)
		(layers "F.Cu" "B.Cu")
		(net "PVDD33_S5_EN")
	)
	(via
		(at 206.189834 -344.293952)
		(size 0.508)
		(drill 0.254)
		(layers "F.Cu" "B.Cu")
		(net "PVDD33_S5_EN")
	)
	(segment
		(start 208.285334 -320.007488)
		(end 208.285334 -326.215248)
		(width 0.10668)
		(layer "B.Cu")
		(net "PVDD33_S5_EN")
	)
	(segment
		(start 201.938382 -104.89057)
		(end 205.253844 -104.89057)
		(width 0.10668)
		(layer "B.Cu")
		(net "PVDD33_S5_EN")
	)
	(segment
		(start 207.653636 -343.473024)
		(end 206.832708 -344.293952)
		(width 0.10668)
		(layer "B.Cu")
		(net "PVDD33_S5_EN")
	)
	(segment
		(start 201.350626 -105.478326)
		(end 201.938382 -104.89057)
		(width 0.10668)
		(layer "B.Cu")
		(net "PVDD33_S5_EN")
	)
	(segment
		(start 181.36743 -173.566074)
		(end 181.36743 -172.413422)
		(width 0.10668)
		(layer "B.Cu")
		(net "PVDD33_S5_EN")
	)
	(segment
		(start 201.03084 -110.213648)
		(end 201.03084 -109.471206)
		(width 0.10668)
		(layer "B.Cu")
		(net "PVDD33_S5_EN")
	)
	(segment
		(start 216.985596 -164.395404)
		(end 213.569296 -164.395404)
		(width 0.10668)
		(layer "B.Cu")
		(net "PVDD33_S5_EN")
	)
	(segment
		(start 205.253844 -104.89057)
		(end 206.410306 -106.047032)
		(width 0.10668)
		(layer "B.Cu")
		(net "PVDD33_S5_EN")
	)
	(segment
		(start 208.7626 -319.530222)
		(end 208.285334 -320.007488)
		(width 0.10668)
		(layer "B.Cu")
		(net "PVDD33_S5_EN")
	)
	(segment
		(start 212.309456 -192.055242)
		(end 212.309456 -313.567064)
		(width 0.10668)
		(layer "B.Cu")
		(net "PVDD33_S5_EN")
	)
	(segment
		(start 182.256176 -174.45482)
		(end 181.36743 -173.566074)
		(width 0.10668)
		(layer "B.Cu")
		(net "PVDD33_S5_EN")
	)
	(segment
		(start 181.36743 -172.413422)
		(end 180.889656 -171.935648)
		(width 0.10668)
		(layer "B.Cu")
		(net "PVDD33_S5_EN")
	)
	(segment
		(start 210.69554 -106.047032)
		(end 211.786978 -107.13847)
		(width 0.10668)
		(layer "B.Cu")
		(net "PVDD33_S5_EN")
	)
	(segment
		(start 207.653636 -326.846946)
		(end 207.653636 -343.473024)
		(width 0.10668)
		(layer "B.Cu")
		(net "PVDD33_S5_EN")
	)
	(segment
		(start 201.03084 -109.471206)
		(end 201.350626 -109.15142)
		(width 0.10668)
		(layer "B.Cu")
		(net "PVDD33_S5_EN")
	)
	(segment
		(start 208.285334 -326.215248)
		(end 207.653636 -326.846946)
		(width 0.10668)
		(layer "B.Cu")
		(net "PVDD33_S5_EN")
	)
	(segment
		(start 206.410306 -106.047032)
		(end 210.69554 -106.047032)
		(width 0.10668)
		(layer "B.Cu")
		(net "PVDD33_S5_EN")
	)
	(segment
		(start 211.786978 -107.13847)
		(end 211.786978 -107.507278)
		(width 0.10668)
		(layer "B.Cu")
		(net "PVDD33_S5_EN")
	)
	(segment
		(start 191.651128 -186.908186)
		(end 191.651128 -187.71997)
		(width 0.10668)
		(layer "B.Cu")
		(net "PVDD33_S5_EN")
	)
	(segment
		(start 192.694814 -188.763656)
		(end 209.01787 -188.763656)
		(width 0.10668)
		(layer "B.Cu")
		(net "PVDD33_S5_EN")
	)
	(segment
		(start 213.569296 -164.395404)
		(end 203.50988 -174.45482)
		(width 0.10668)
		(layer "B.Cu")
		(net "PVDD33_S5_EN")
	)
	(segment
		(start 191.651128 -187.71997)
		(end 192.694814 -188.763656)
		(width 0.10668)
		(layer "B.Cu")
		(net "PVDD33_S5_EN")
	)
	(segment
		(start 200.143872 -111.100616)
		(end 201.03084 -110.213648)
		(width 0.10668)
		(layer "B.Cu")
		(net "PVDD33_S5_EN")
	)
	(segment
		(start 203.50988 -174.45482)
		(end 182.256176 -174.45482)
		(width 0.10668)
		(layer "B.Cu")
		(net "PVDD33_S5_EN")
	)
	(segment
		(start 212.309456 -313.567064)
		(end 208.7626 -317.11392)
		(width 0.10668)
		(layer "B.Cu")
		(net "PVDD33_S5_EN")
	)
	(segment
		(start 206.832708 -344.293952)
		(end 206.189834 -344.293952)
		(width 0.10668)
		(layer "B.Cu")
		(net "PVDD33_S5_EN")
	)
	(segment
		(start 198.838058 -111.380016)
		(end 199.117458 -111.100616)
		(width 0.10668)
		(layer "B.Cu")
		(net "PVDD33_S5_EN")
	)
	(segment
		(start 209.01787 -188.763656)
		(end 212.309456 -192.055242)
		(width 0.10668)
		(layer "B.Cu")
		(net "PVDD33_S5_EN")
	)
	(segment
		(start 217.038936 -164.448744)
		(end 216.985596 -164.395404)
		(width 0.10668)
		(layer "B.Cu")
		(net "PVDD33_S5_EN")
	)
	(segment
		(start 201.350626 -109.15142)
		(end 201.350626 -105.478326)
		(width 0.10668)
		(layer "B.Cu")
		(net "PVDD33_S5_EN")
	)
	(segment
		(start 199.117458 -111.100616)
		(end 200.143872 -111.100616)
		(width 0.10668)
		(layer "B.Cu")
		(net "PVDD33_S5_EN")
	)
	(segment
		(start 208.7626 -317.11392)
		(end 208.7626 -319.530222)
		(width 0.10668)
		(layer "B.Cu")
		(net "PVDD33_S5_EN")
	)
	(segment
		(start 218.015566 -129.13614)
		(end 219.32011 -130.440684)
		(width 0.11684)
		(layer "In4.Cu")
		(net "PVDD33_S5_EN")
	)
	(segment
		(start 212.546946 -108.267246)
		(end 212.546946 -111.650526)
		(width 0.11684)
		(layer "In4.Cu")
		(net "PVDD33_S5_EN")
	)
	(segment
		(start 214.818214 -116.738908)
		(end 218.015566 -119.93626)
		(width 0.11684)
		(layer "In4.Cu")
		(net "PVDD33_S5_EN")
	)
	(segment
		(start 218.015566 -119.93626)
		(end 218.015566 -129.13614)
		(width 0.11684)
		(layer "In4.Cu")
		(net "PVDD33_S5_EN")
	)
	(segment
		(start 214.818214 -113.921794)
		(end 214.818214 -116.738908)
		(width 0.11684)
		(layer "In4.Cu")
		(net "PVDD33_S5_EN")
	)
	(segment
		(start 212.546946 -111.650526)
		(end 214.818214 -113.921794)
		(width 0.11684)
		(layer "In4.Cu")
		(net "PVDD33_S5_EN")
	)
	(segment
		(start 217.038936 -137.857992)
		(end 217.038936 -164.448744)
		(width 0.11684)
		(layer "In4.Cu")
		(net "PVDD33_S5_EN")
	)
	(segment
		(start 211.786978 -107.507278)
		(end 212.546946 -108.267246)
		(width 0.11684)
		(layer "In4.Cu")
		(net "PVDD33_S5_EN")
	)
	(segment
		(start 219.32011 -135.576818)
		(end 217.038936 -137.857992)
		(width 0.11684)
		(layer "In4.Cu")
		(net "PVDD33_S5_EN")
	)
	(segment
		(start 219.32011 -130.440684)
		(end 219.32011 -135.576818)
		(width 0.11684)
		(layer "In4.Cu")
		(net "PVDD33_S5_EN")
	)
	(segment
		(start 72.06615 -148.635212)
		(end 71.113904 -148.635212)
		(width 0.254)
		(layer "F.Cu")
		(net "PVDD18_SS_P1_RGND")
	)
	(segment
		(start 71.09079 -148.612098)
		(end 71.09079 -146.501612)
		(width 0.254)
		(layer "F.Cu")
		(net "PVDD18_SS_P1_RGND")
	)
	(segment
		(start 71.113904 -148.635212)
		(end 71.09079 -148.612098)
		(width 0.254)
		(layer "F.Cu")
		(net "PVDD18_SS_P1_RGND")
	)
	(segment
		(start 58.989468 -142.624048)
		(end 62.563756 -142.624048)
		(width 0.254)
		(layer "F.Cu")
		(net "PVDD18_SS_P1_RGND")
	)
	(segment
		(start 71.263764 -146.328638)
		(end 71.263764 -145.801588)
		(width 0.254)
		(layer "F.Cu")
		(net "PVDD18_SS_P1_RGND")
	)
	(segment
		(start 71.09079 -146.501612)
		(end 71.263764 -146.328638)
		(width 0.254)
		(layer "F.Cu")
		(net "PVDD18_SS_P1_RGND")
	)
	(segment
		(start 59.135518 -143.256508)
		(end 58.862468 -142.983458)
		(width 0.254)
		(layer "F.Cu")
		(net "PVDD18_SS_P1_RGND")
	)
	(segment
		(start 70.25132 -150.932642)
		(end 70.25132 -150.16861)
		(width 0.1778)
		(layer "F.Cu")
		(net "PVDD18_SS_P1_RGND")
	)
	(segment
		(start 70.25132 -150.16861)
		(end 70.725538 -149.023578)
		(width 0.1778)
		(layer "F.Cu")
		(net "PVDD18_SS_P1_RGND")
	)
	(segment
		(start 69.487796 -142.624048)
		(end 62.563756 -142.624048)
		(width 0.254)
		(layer "F.Cu")
		(net "PVDD18_SS_P1_RGND")
	)
	(segment
		(start 71.120254 -144.881092)
		(end 71.252842 -144.748504)
		(width 0.254)
		(layer "F.Cu")
		(net "PVDD18_SS_P1_RGND")
	)
	(segment
		(start 70.725538 -149.023578)
		(end 71.113904 -148.635212)
		(width 0.1778)
		(layer "F.Cu")
		(net "PVDD18_SS_P1_RGND")
	)
	(segment
		(start 58.862468 -142.751048)
		(end 58.989468 -142.624048)
		(width 0.254)
		(layer "F.Cu")
		(net "PVDD18_SS_P1_RGND")
	)
	(segment
		(start 71.252842 -144.389094)
		(end 69.487796 -142.624048)
		(width 0.254)
		(layer "F.Cu")
		(net "PVDD18_SS_P1_RGND")
	)
	(segment
		(start 71.263764 -145.801588)
		(end 71.263764 -145.024602)
		(width 0.254)
		(layer "F.Cu")
		(net "PVDD18_SS_P1_RGND")
	)
	(segment
		(start 72.066404 -148.635466)
		(end 72.06615 -148.635212)
		(width 0.254)
		(layer "F.Cu")
		(net "PVDD18_SS_P1_RGND")
	)
	(segment
		(start 71.263764 -145.024602)
		(end 71.120254 -144.881092)
		(width 0.254)
		(layer "F.Cu")
		(net "PVDD18_SS_P1_RGND")
	)
	(segment
		(start 71.252842 -144.748504)
		(end 71.252842 -144.389094)
		(width 0.254)
		(layer "F.Cu")
		(net "PVDD18_SS_P1_RGND")
	)
	(segment
		(start 58.862468 -142.983458)
		(end 58.862468 -142.751048)
		(width 0.254)
		(layer "F.Cu")
		(net "PVDD18_SS_P1_RGND")
	)
	(via
		(at 62.563756 -142.624048)
		(size 0.4064)
		(drill 0.2032)
		(layers "F.Cu" "B.Cu")
		(net "PVDD18_SS_P1_RGND")
	)
	(segment
		(start 68.032376 -155.237688)
		(end 68.032376 -154.589734)
		(width 0.381)
		(layer "F.Cu")
		(net "PVDD18_S5_P1_VCC")
	)
	(segment
		(start 68.032376 -154.589734)
		(end 67.970654 -154.528012)
		(width 0.381)
		(layer "F.Cu")
		(net "PVDD18_S5_P1_VCC")
	)
	(segment
		(start 67.970654 -154.528012)
		(end 68.151248 -154.347418)
		(width 0.254)
		(layer "F.Cu")
		(net "PVDD18_S5_P1_VCC")
	)
	(segment
		(start 68.151248 -154.347418)
		(end 68.151248 -153.732738)
		(width 0.254)
		(layer "F.Cu")
		(net "PVDD18_S5_P1_VCC")
	)
	(via
		(at 67.970654 -154.528012)
		(size 0.508)
		(drill 0.254)
		(layers "F.Cu" "B.Cu")
		(net "PVDD18_S5_P1_VCC")
	)
	(segment
		(start 71.773288 -148.851366)
		(end 67.970654 -152.654)
		(width 0.381)
		(layer "B.Cu")
		(net "PVDD18_S5_P1_VCC")
	)
	(segment
		(start 67.970654 -152.654)
		(end 67.970654 -154.528012)
		(width 0.381)
		(layer "B.Cu")
		(net "PVDD18_S5_P1_VCC")
	)
	(segment
		(start 75.51801 -148.851366)
		(end 71.773288 -148.851366)
		(width 0.381)
		(layer "B.Cu")
		(net "PVDD18_S5_P1_VCC")
	)
	(segment
		(start 190.721996 -112.25276)
		(end 191.111886 -111.86287)
		(width 0.10668)
		(layer "F.Cu")
		(net "PVDD18_S5_P1_R_EN")
	)
	(via
		(at 191.111886 -111.86287)
		(size 0.4572)
		(drill 0.254)
		(layers "F.Cu" "B.Cu")
		(net "PVDD18_S5_P1_R_EN")
	)
	(via
		(at 196.016372 -108.408216)
		(size 0.508)
		(drill 0.254)
		(layers "F.Cu" "B.Cu")
		(net "PVDD18_S5_P1_R_EN")
	)
	(segment
		(start 196.239384 -107.14355)
		(end 196.239384 -108.281216)
		(width 0.10668)
		(layer "B.Cu")
		(net "PVDD18_S5_P1_R_EN")
	)
	(segment
		(start 196.112384 -108.408216)
		(end 196.016372 -108.408216)
		(width 0.10668)
		(layer "B.Cu")
		(net "PVDD18_S5_P1_R_EN")
	)
	(segment
		(start 196.239384 -108.281216)
		(end 196.112384 -108.408216)
		(width 0.10668)
		(layer "B.Cu")
		(net "PVDD18_S5_P1_R_EN")
	)
	(segment
		(start 196.869558 -106.513376)
		(end 196.239384 -107.14355)
		(width 0.10668)
		(layer "B.Cu")
		(net "PVDD18_S5_P1_R_EN")
	)
	(segment
		(start 191.771778 -110.653576)
		(end 193.684652 -110.653576)
		(width 0.11684)
		(layer "In4.Cu")
		(net "PVDD18_S5_P1_R_EN")
	)
	(segment
		(start 191.523366 -111.45139)
		(end 191.523366 -110.901988)
		(width 0.11684)
		(layer "In4.Cu")
		(net "PVDD18_S5_P1_R_EN")
	)
	(segment
		(start 191.523366 -110.901988)
		(end 191.771778 -110.653576)
		(width 0.11684)
		(layer "In4.Cu")
		(net "PVDD18_S5_P1_R_EN")
	)
	(segment
		(start 194.89293 -109.445298)
		(end 194.89293 -108.940854)
		(width 0.11684)
		(layer "In4.Cu")
		(net "PVDD18_S5_P1_R_EN")
	)
	(segment
		(start 195.425568 -108.408216)
		(end 196.016372 -108.408216)
		(width 0.11684)
		(layer "In4.Cu")
		(net "PVDD18_S5_P1_R_EN")
	)
	(segment
		(start 193.684652 -110.653576)
		(end 194.89293 -109.445298)
		(width 0.11684)
		(layer "In4.Cu")
		(net "PVDD18_S5_P1_R_EN")
	)
	(segment
		(start 194.89293 -108.940854)
		(end 195.425568 -108.408216)
		(width 0.11684)
		(layer "In4.Cu")
		(net "PVDD18_S5_P1_R_EN")
	)
	(segment
		(start 191.111886 -111.86287)
		(end 191.523366 -111.45139)
		(width 0.11684)
		(layer "In4.Cu")
		(net "PVDD18_S5_P1_R_EN")
	)
	(segment
		(start 69.991732 -149.70633)
		(end 70.313804 -148.635212)
		(width 0.1778)
		(layer "F.Cu")
		(net "PVDD18_S5_P1_REF")
	)
	(segment
		(start 69.85127 -150.932642)
		(end 69.85127 -150.17369)
		(width 0.1778)
		(layer "F.Cu")
		(net "PVDD18_S5_P1_REF")
	)
	(segment
		(start 70.307454 -147.739862)
		(end 70.313804 -147.746212)
		(width 0.2032)
		(layer "F.Cu")
		(net "PVDD18_S5_P1_REF")
	)
	(segment
		(start 69.85127 -150.17369)
		(end 69.991732 -149.70633)
		(width 0.1778)
		(layer "F.Cu")
		(net "PVDD18_S5_P1_REF")
	)
	(segment
		(start 70.313804 -147.746212)
		(end 70.313804 -148.635212)
		(width 0.2032)
		(layer "F.Cu")
		(net "PVDD18_S5_P1_REF")
	)
	(via
		(at 69.991732 -149.70633)
		(size 0.4064)
		(drill 0.2032)
		(layers "F.Cu" "B.Cu")
		(net "PVDD18_S5_P1_REF")
	)
	(segment
		(start 69.394832 -149.412198)
		(end 69.45122 -150.250398)
		(width 0.1778)
		(layer "F.Cu")
		(net "PVDD18_S5_P1_MODE")
	)
	(segment
		(start 69.359526 -148.887942)
		(end 69.394832 -149.412198)
		(width 0.1778)
		(layer "F.Cu")
		(net "PVDD18_S5_P1_MODE")
	)
	(segment
		(start 69.359526 -148.62683)
		(end 69.359526 -148.887942)
		(width 0.1778)
		(layer "F.Cu")
		(net "PVDD18_S5_P1_MODE")
	)
	(segment
		(start 69.45122 -150.250398)
		(end 69.45122 -150.932642)
		(width 0.1778)
		(layer "F.Cu")
		(net "PVDD18_S5_P1_MODE")
	)
	(via
		(at 69.394832 -149.412198)
		(size 0.508)
		(drill 0.254)
		(layers "F.Cu" "B.Cu")
		(net "PVDD18_S5_P1_MODE")
	)
	(segment
		(start 71.8058 -144.623028)
		(end 71.8058 -144.1958)
		(width 0.254)
		(layer "F.Cu")
		(net "PVDD18_S5_P1_FB_RC")
	)
	(segment
		(start 72.063864 -144.881092)
		(end 71.8058 -144.623028)
		(width 0.254)
		(layer "F.Cu")
		(net "PVDD18_S5_P1_FB_RC")
	)
	(segment
		(start 71.8058 -144.1958)
		(end 69.726048 -142.116048)
		(width 0.254)
		(layer "F.Cu")
		(net "PVDD18_S5_P1_FB_RC")
	)
	(segment
		(start 72.063864 -146.735292)
		(end 72.063864 -147.649692)
		(width 0.254)
		(layer "F.Cu")
		(net "PVDD18_S5_P1_FB_RC")
	)
	(segment
		(start 58.83275 -142.116048)
		(end 67.36334 -142.116048)
		(width 0.254)
		(layer "F.Cu")
		(net "PVDD18_S5_P1_FB_RC")
	)
	(segment
		(start 72.063864 -146.735292)
		(end 72.063864 -145.801588)
		(width 0.254)
		(layer "F.Cu")
		(net "PVDD18_S5_P1_FB_RC")
	)
	(segment
		(start 58.31205 -143.036036)
		(end 58.31205 -142.636748)
		(width 0.254)
		(layer "F.Cu")
		(net "PVDD18_S5_P1_FB_RC")
	)
	(segment
		(start 58.08345 -143.264636)
		(end 58.31205 -143.036036)
		(width 0.254)
		(layer "F.Cu")
		(net "PVDD18_S5_P1_FB_RC")
	)
	(segment
		(start 72.063864 -145.801588)
		(end 72.063864 -144.881092)
		(width 0.254)
		(layer "F.Cu")
		(net "PVDD18_S5_P1_FB_RC")
	)
	(segment
		(start 69.726048 -142.116048)
		(end 67.36334 -142.116048)
		(width 0.254)
		(layer "F.Cu")
		(net "PVDD18_S5_P1_FB_RC")
	)
	(segment
		(start 58.31205 -142.636748)
		(end 58.83275 -142.116048)
		(width 0.254)
		(layer "F.Cu")
		(net "PVDD18_S5_P1_FB_RC")
	)
	(via
		(at 67.36334 -142.116048)
		(size 0.4064)
		(drill 0.2032)
		(layers "F.Cu" "B.Cu")
		(net "PVDD18_S5_P1_FB_RC")
	)
	(segment
		(start 72.866504 -148.634958)
		(end 72.863964 -148.632418)
		(width 0.254)
		(layer "F.Cu")
		(net "PVDD18_S5_P1_FB")
	)
	(segment
		(start 71.314564 -149.558502)
		(end 72.47636 -149.558502)
		(width 0.1778)
		(layer "F.Cu")
		(net "PVDD18_S5_P1_FB")
	)
	(segment
		(start 72.863964 -147.649692)
		(end 72.863964 -146.735292)
		(width 0.254)
		(layer "F.Cu")
		(net "PVDD18_S5_P1_FB")
	)
	(segment
		(start 72.863964 -148.632418)
		(end 72.863964 -147.649692)
		(width 0.254)
		(layer "F.Cu")
		(net "PVDD18_S5_P1_FB")
	)
	(segment
		(start 72.866504 -149.168358)
		(end 72.866504 -148.634958)
		(width 0.1778)
		(layer "F.Cu")
		(net "PVDD18_S5_P1_FB")
	)
	(segment
		(start 72.47636 -149.558502)
		(end 72.866504 -149.168358)
		(width 0.1778)
		(layer "F.Cu")
		(net "PVDD18_S5_P1_FB")
	)
	(segment
		(start 70.65137 -150.932642)
		(end 70.65137 -150.221696)
		(width 0.1778)
		(layer "F.Cu")
		(net "PVDD18_S5_P1_FB")
	)
	(segment
		(start 70.65137 -150.221696)
		(end 71.314564 -149.558502)
		(width 0.1778)
		(layer "F.Cu")
		(net "PVDD18_S5_P1_FB")
	)
	(segment
		(start 73.573386 -147.260564)
		(end 74.228198 -146.605752)
		(width 0.10668)
		(layer "F.Cu")
		(net "PVDD18_S5_P1_EN")
	)
	(segment
		(start 73.219818 -149.978618)
		(end 71.554848 -149.978618)
		(width 0.10668)
		(layer "F.Cu")
		(net "PVDD18_S5_P1_EN")
	)
	(segment
		(start 73.573386 -148.651976)
		(end 73.573386 -147.260564)
		(width 0.10668)
		(layer "F.Cu")
		(net "PVDD18_S5_P1_EN")
	)
	(segment
		(start 71.554848 -149.978618)
		(end 71.051166 -150.4823)
		(width 0.10668)
		(layer "F.Cu")
		(net "PVDD18_S5_P1_EN")
	)
	(segment
		(start 73.772776 -148.851366)
		(end 73.573386 -148.651976)
		(width 0.10668)
		(layer "F.Cu")
		(net "PVDD18_S5_P1_EN")
	)
	(segment
		(start 74.34707 -148.851366)
		(end 73.219818 -149.978618)
		(width 0.10668)
		(layer "F.Cu")
		(net "PVDD18_S5_P1_EN")
	)
	(segment
		(start 71.051166 -150.4823)
		(end 71.051166 -150.932642)
		(width 0.10668)
		(layer "F.Cu")
		(net "PVDD18_S5_P1_EN")
	)
	(segment
		(start 74.34707 -148.851366)
		(end 73.772776 -148.851366)
		(width 0.10668)
		(layer "F.Cu")
		(net "PVDD18_S5_P1_EN")
	)
	(segment
		(start 74.228198 -146.605752)
		(end 74.751946 -146.605752)
		(width 0.10668)
		(layer "F.Cu")
		(net "PVDD18_S5_P1_EN")
	)
	(via
		(at 199.524366 -68.696586)
		(size 0.508)
		(drill 0.254)
		(layers "F.Cu" "B.Cu")
		(net "PVDD18_S5_P1_EN")
	)
	(via
		(at 74.751946 -146.605752)
		(size 0.508)
		(drill 0.254)
		(layers "F.Cu" "B.Cu")
		(net "PVDD18_S5_P1_EN")
	)
	(via
		(at 204.066648 -102.610412)
		(size 0.508)
		(drill 0.254)
		(layers "F.Cu" "B.Cu")
		(net "PVDD18_S5_P1_EN")
	)
	(segment
		(start 197.669658 -106.513376)
		(end 197.669658 -106.155236)
		(width 0.10668)
		(layer "B.Cu")
		(net "PVDD18_S5_P1_EN")
	)
	(segment
		(start 199.210168 -106.048556)
		(end 201.534014 -103.72471)
		(width 0.10668)
		(layer "B.Cu")
		(net "PVDD18_S5_P1_EN")
	)
	(segment
		(start 201.534014 -103.72471)
		(end 202.95235 -103.72471)
		(width 0.10668)
		(layer "B.Cu")
		(net "PVDD18_S5_P1_EN")
	)
	(segment
		(start 197.776338 -106.048556)
		(end 199.210168 -106.048556)
		(width 0.10668)
		(layer "B.Cu")
		(net "PVDD18_S5_P1_EN")
	)
	(segment
		(start 197.669658 -106.155236)
		(end 197.776338 -106.048556)
		(width 0.10668)
		(layer "B.Cu")
		(net "PVDD18_S5_P1_EN")
	)
	(segment
		(start 202.95235 -103.72471)
		(end 204.066648 -102.610412)
		(width 0.10668)
		(layer "B.Cu")
		(net "PVDD18_S5_P1_EN")
	)
	(segment
		(start 204.633322 -87.244936)
		(end 204.633322 -90.68943)
		(width 0.11684)
		(layer "In4.Cu")
		(net "PVDD18_S5_P1_EN")
	)
	(segment
		(start 205.02626 -93.809566)
		(end 204.633322 -94.202504)
		(width 0.11684)
		(layer "In4.Cu")
		(net "PVDD18_S5_P1_EN")
	)
	(segment
		(start 203.505308 -85.100414)
		(end 204.795628 -86.390734)
		(width 0.11684)
		(layer "In4.Cu")
		(net "PVDD18_S5_P1_EN")
	)
	(segment
		(start 201.08418 -70.58914)
		(end 201.08418 -72.01281)
		(width 0.11684)
		(layer "In4.Cu")
		(net "PVDD18_S5_P1_EN")
	)
	(segment
		(start 204.633322 -90.68943)
		(end 205.02626 -91.082368)
		(width 0.11684)
		(layer "In4.Cu")
		(net "PVDD18_S5_P1_EN")
	)
	(segment
		(start 199.524366 -68.696586)
		(end 200.677018 -69.849238)
		(width 0.11684)
		(layer "In4.Cu")
		(net "PVDD18_S5_P1_EN")
	)
	(segment
		(start 204.066648 -99.162616)
		(end 204.066648 -102.610412)
		(width 0.11684)
		(layer "In4.Cu")
		(net "PVDD18_S5_P1_EN")
	)
	(segment
		(start 200.677018 -69.849238)
		(end 200.677018 -70.181978)
		(width 0.11684)
		(layer "In4.Cu")
		(net "PVDD18_S5_P1_EN")
	)
	(segment
		(start 200.677018 -70.181978)
		(end 201.08418 -70.58914)
		(width 0.11684)
		(layer "In4.Cu")
		(net "PVDD18_S5_P1_EN")
	)
	(segment
		(start 204.795628 -87.08263)
		(end 204.633322 -87.244936)
		(width 0.11684)
		(layer "In4.Cu")
		(net "PVDD18_S5_P1_EN")
	)
	(segment
		(start 204.633322 -94.202504)
		(end 204.633322 -98.595942)
		(width 0.11684)
		(layer "In4.Cu")
		(net "PVDD18_S5_P1_EN")
	)
	(segment
		(start 205.02626 -91.082368)
		(end 205.02626 -93.809566)
		(width 0.11684)
		(layer "In4.Cu")
		(net "PVDD18_S5_P1_EN")
	)
	(segment
		(start 204.633322 -98.595942)
		(end 204.066648 -99.162616)
		(width 0.11684)
		(layer "In4.Cu")
		(net "PVDD18_S5_P1_EN")
	)
	(segment
		(start 201.08418 -72.01281)
		(end 203.505308 -74.433938)
		(width 0.11684)
		(layer "In4.Cu")
		(net "PVDD18_S5_P1_EN")
	)
	(segment
		(start 203.505308 -74.433938)
		(end 203.505308 -85.100414)
		(width 0.11684)
		(layer "In4.Cu")
		(net "PVDD18_S5_P1_EN")
	)
	(segment
		(start 204.795628 -86.390734)
		(end 204.795628 -87.08263)
		(width 0.11684)
		(layer "In4.Cu")
		(net "PVDD18_S5_P1_EN")
	)
	(segment
		(start 191.027812 -70.34911)
		(end 192.173098 -69.203824)
		(width 0.11684)
		(layer "In6.Cu")
		(net "PVDD18_S5_P1_EN")
	)
	(segment
		(start 74.751946 -146.605752)
		(end 74.751946 -142.084044)
		(width 0.11684)
		(layer "In6.Cu")
		(net "PVDD18_S5_P1_EN")
	)
	(segment
		(start 174.69104 -80.961484)
		(end 178.535076 -80.961484)
		(width 0.11684)
		(layer "In6.Cu")
		(net "PVDD18_S5_P1_EN")
	)
	(segment
		(start 183.111648 -80.961738)
		(end 191.027812 -73.045574)
		(width 0.11684)
		(layer "In6.Cu")
		(net "PVDD18_S5_P1_EN")
	)
	(segment
		(start 199.017128 -69.203824)
		(end 199.524366 -68.696586)
		(width 0.11684)
		(layer "In6.Cu")
		(net "PVDD18_S5_P1_EN")
	)
	(segment
		(start 178.535076 -80.961484)
		(end 178.53533 -80.961738)
		(width 0.11684)
		(layer "In6.Cu")
		(net "PVDD18_S5_P1_EN")
	)
	(segment
		(start 178.53533 -80.961738)
		(end 183.111648 -80.961738)
		(width 0.11684)
		(layer "In6.Cu")
		(net "PVDD18_S5_P1_EN")
	)
	(segment
		(start 155.529788 -84.506054)
		(end 159.074104 -80.961738)
		(width 0.11684)
		(layer "In6.Cu")
		(net "PVDD18_S5_P1_EN")
	)
	(segment
		(start 191.027812 -73.045574)
		(end 191.027812 -70.34911)
		(width 0.11684)
		(layer "In6.Cu")
		(net "PVDD18_S5_P1_EN")
	)
	(segment
		(start 174.690786 -80.961738)
		(end 174.69104 -80.961484)
		(width 0.11684)
		(layer "In6.Cu")
		(net "PVDD18_S5_P1_EN")
	)
	(segment
		(start 145.196306 -84.506054)
		(end 155.529788 -84.506054)
		(width 0.11684)
		(layer "In6.Cu")
		(net "PVDD18_S5_P1_EN")
	)
	(segment
		(start 79.771494 -118.77294)
		(end 90.322654 -108.22178)
		(width 0.11684)
		(layer "In6.Cu")
		(net "PVDD18_S5_P1_EN")
	)
	(segment
		(start 121.48058 -108.22178)
		(end 145.196306 -84.506054)
		(width 0.11684)
		(layer "In6.Cu")
		(net "PVDD18_S5_P1_EN")
	)
	(segment
		(start 90.322654 -108.22178)
		(end 121.48058 -108.22178)
		(width 0.11684)
		(layer "In6.Cu")
		(net "PVDD18_S5_P1_EN")
	)
	(segment
		(start 79.771494 -119.739918)
		(end 79.771494 -118.77294)
		(width 0.11684)
		(layer "In6.Cu")
		(net "PVDD18_S5_P1_EN")
	)
	(segment
		(start 66.86931 -134.201408)
		(end 66.86931 -132.642102)
		(width 0.11684)
		(layer "In6.Cu")
		(net "PVDD18_S5_P1_EN")
	)
	(segment
		(start 192.173098 -69.203824)
		(end 199.017128 -69.203824)
		(width 0.11684)
		(layer "In6.Cu")
		(net "PVDD18_S5_P1_EN")
	)
	(segment
		(start 66.86931 -132.642102)
		(end 79.771494 -119.739918)
		(width 0.11684)
		(layer "In6.Cu")
		(net "PVDD18_S5_P1_EN")
	)
	(segment
		(start 159.074104 -80.961738)
		(end 174.690786 -80.961738)
		(width 0.11684)
		(layer "In6.Cu")
		(net "PVDD18_S5_P1_EN")
	)
	(segment
		(start 74.751946 -142.084044)
		(end 66.86931 -134.201408)
		(width 0.11684)
		(layer "In6.Cu")
		(net "PVDD18_S5_P1_EN")
	)
	(segment
		(start 69.05117 -150.932642)
		(end 69.05117 -150.401528)
		(width 0.1778)
		(layer "F.Cu")
		(net "PVDD18_S5_P1_CS")
	)
	(segment
		(start 68.42887 -149.337522)
		(end 68.42887 -148.61794)
		(width 0.1778)
		(layer "F.Cu")
		(net "PVDD18_S5_P1_CS")
	)
	(segment
		(start 68.653914 -149.722078)
		(end 68.42887 -149.337522)
		(width 0.1778)
		(layer "F.Cu")
		(net "PVDD18_S5_P1_CS")
	)
	(segment
		(start 69.05117 -150.401528)
		(end 68.653914 -149.722078)
		(width 0.1778)
		(layer "F.Cu")
		(net "PVDD18_S5_P1_CS")
	)
	(via
		(at 68.653914 -149.722078)
		(size 0.4064)
		(drill 0.2032)
		(layers "F.Cu" "B.Cu")
		(net "PVDD18_S5_P1_CS")
	)
	(segment
		(start 100.967794 -252.850396)
		(end 100.500942 -252.584458)
		(width 0.350012)
		(layer "F.Cu")
		(net "PVDD18_S5_P1")
	)
	(segment
		(start 131.320286 -217.549476)
		(end 130.73507 -217.549476)
		(width 0.508)
		(layer "F.Cu")
		(net "PVDD18_S5_P1")
	)
	(segment
		(start 153.592022 -324.688708)
		(end 154.081226 -324.688708)
		(width 0.4064)
		(layer "F.Cu")
		(net "PVDD18_S5_P1")
	)
	(segment
		(start 99.08794 -254.470408)
		(end 98.621088 -254.20447)
		(width 0.350012)
		(layer "F.Cu")
		(net "PVDD18_S5_P1")
	)
	(segment
		(start 144.386554 -321.295522)
		(end 144.311624 -321.220592)
		(width 0.508)
		(layer "F.Cu")
		(net "PVDD18_S5_P1")
	)
	(segment
		(start 142.542006 -319.034414)
		(end 131.220718 -319.034414)
		(width 0.508)
		(layer "F.Cu")
		(net "PVDD18_S5_P1")
	)
	(segment
		(start 155.250134 -199.897492)
		(end 154.823414 -200.324212)
		(width 0.508)
		(layer "F.Cu")
		(net "PVDD18_S5_P1")
	)
	(segment
		(start 153.249884 -320.699892)
		(end 153.738834 -320.699892)
		(width 0.4064)
		(layer "F.Cu")
		(net "PVDD18_S5_P1")
	)
	(segment
		(start 151.592534 -203.882752)
		(end 151.869394 -203.882752)
		(width 0.508)
		(layer "F.Cu")
		(net "PVDD18_S5_P1")
	)
	(segment
		(start 94.060264 -306.189888)
		(end 94.060264 -305.986942)
		(width 0.508)
		(layer "F.Cu")
		(net "PVDD18_S5_P1")
	)
	(segment
		(start 92.261944 -304.706528)
		(end 91.530932 -303.975516)
		(width 0.508)
		(layer "F.Cu")
		(net "PVDD18_S5_P1")
	)
	(segment
		(start 156.355034 -200.265792)
		(end 155.986734 -199.897492)
		(width 0.508)
		(layer "F.Cu")
		(net "PVDD18_S5_P1")
	)
	(segment
		(start 95.95104 -203.834746)
		(end 95.674434 -204.111352)
		(width 0.508)
		(layer "F.Cu")
		(net "PVDD18_S5_P1")
	)
	(segment
		(start 94.187264 -304.29962)
		(end 93.920818 -304.033174)
		(width 0.508)
		(layer "F.Cu")
		(net "PVDD18_S5_P1")
	)
	(segment
		(start 152.571196 -205.000352)
		(end 152.571196 -204.584046)
		(width 0.508)
		(layer "F.Cu")
		(net "PVDD18_S5_P1")
	)
	(segment
		(start 144.311624 -320.804032)
		(end 142.542006 -319.034414)
		(width 0.508)
		(layer "F.Cu")
		(net "PVDD18_S5_P1")
	)
	(segment
		(start 277.346918 -95.254572)
		(end 276.881844 -94.789498)
		(width 0.3556)
		(layer "F.Cu")
		(net "PVDD18_S5_P1")
	)
	(segment
		(start 102.179374 -145.777712)
		(end 101.770942 -145.777712)
		(width 0.4572)
		(layer "F.Cu")
		(net "PVDD18_S5_P1")
	)
	(segment
		(start 155.768294 -202.257152)
		(end 154.6606 -203.364846)
		(width 0.508)
		(layer "F.Cu")
		(net "PVDD18_S5_P1")
	)
	(segment
		(start 95.572834 -306.701952)
		(end 94.572328 -306.701952)
		(width 0.508)
		(layer "F.Cu")
		(net "PVDD18_S5_P1")
	)
	(segment
		(start 100.967794 -254.470408)
		(end 100.500942 -254.20447)
		(width 0.350012)
		(layer "F.Cu")
		(net "PVDD18_S5_P1")
	)
	(segment
		(start 25.16505 -363.347)
		(end 25.16505 -363.65815)
		(width 0.381)
		(layer "F.Cu")
		(net "PVDD18_S5_P1")
	)
	(segment
		(start 150.513288 -205.508352)
		(end 150.691596 -205.68666)
		(width 0.508)
		(layer "F.Cu")
		(net "PVDD18_S5_P1")
	)
	(segment
		(start 155.768294 -201.591672)
		(end 155.768294 -202.257152)
		(width 0.508)
		(layer "F.Cu")
		(net "PVDD18_S5_P1")
	)
	(segment
		(start 99.55784 -252.04039)
		(end 99.090988 -251.774452)
		(width 0.350012)
		(layer "F.Cu")
		(net "PVDD18_S5_P1")
	)
	(segment
		(start 112.716056 -300.529752)
		(end 112.716056 -299.56633)
		(width 0.508)
		(layer "F.Cu")
		(net "PVDD18_S5_P1")
	)
	(segment
		(start 97.677986 -255.280414)
		(end 97.211134 -255.014476)
		(width 0.350012)
		(layer "F.Cu")
		(net "PVDD18_S5_P1")
	)
	(segment
		(start 26.167588 -363.347)
		(end 26.351992 -363.531404)
		(width 0.381)
		(layer "F.Cu")
		(net "PVDD18_S5_P1")
	)
	(segment
		(start 153.516838 -324.763892)
		(end 153.592022 -324.688708)
		(width 0.4064)
		(layer "F.Cu")
		(net "PVDD18_S5_P1")
	)
	(segment
		(start 131.220718 -319.034414)
		(end 112.716056 -300.529752)
		(width 0.508)
		(layer "F.Cu")
		(net "PVDD18_S5_P1")
	)
	(segment
		(start 99.55784 -253.660402)
		(end 99.090988 -253.394464)
		(width 0.350012)
		(layer "F.Cu")
		(net "PVDD18_S5_P1")
	)
	(segment
		(start 277.346918 -95.67672)
		(end 277.346918 -95.254572)
		(width 0.3556)
		(layer "F.Cu")
		(net "PVDD18_S5_P1")
	)
	(segment
		(start 25.16505 -363.65815)
		(end 24.8412 -363.982)
		(width 0.381)
		(layer "F.Cu")
		(net "PVDD18_S5_P1")
	)
	(segment
		(start 97.207832 -256.09042)
		(end 96.74098 -255.824482)
		(width 0.350012)
		(layer "F.Cu")
		(net "PVDD18_S5_P1")
	)
	(segment
		(start 155.986734 -199.897492)
		(end 155.250134 -199.897492)
		(width 0.508)
		(layer "F.Cu")
		(net "PVDD18_S5_P1")
	)
	(segment
		(start 154.823414 -200.324212)
		(end 154.788108 -200.324212)
		(width 0.508)
		(layer "F.Cu")
		(net "PVDD18_S5_P1")
	)
	(segment
		(start 91.530932 -300.750732)
		(end 89.063322 -298.283122)
		(width 0.508)
		(layer "F.Cu")
		(net "PVDD18_S5_P1")
	)
	(segment
		(start 89.063322 -298.283122)
		(end 88.165178 -298.283122)
		(width 0.508)
		(layer "F.Cu")
		(net "PVDD18_S5_P1")
	)
	(segment
		(start 154.788108 -200.324212)
		(end 154.788108 -200.611486)
		(width 0.508)
		(layer "F.Cu")
		(net "PVDD18_S5_P1")
	)
	(segment
		(start 99.08794 -251.230384)
		(end 98.621088 -250.964446)
		(width 0.350012)
		(layer "F.Cu")
		(net "PVDD18_S5_P1")
	)
	(segment
		(start 122.41784 -262.480298)
		(end 122.884692 -262.746236)
		(width 0.350012)
		(layer "F.Cu")
		(net "PVDD18_S5_P1")
	)
	(segment
		(start 149.479 -206.271622)
		(end 149.750018 -206.271622)
		(width 0.508)
		(layer "F.Cu")
		(net "PVDD18_S5_P1")
	)
	(segment
		(start 144.48536 -321.295522)
		(end 144.97685 -320.804032)
		(width 0.508)
		(layer "F.Cu")
		(net "PVDD18_S5_P1")
	)
	(segment
		(start 101.437948 -252.04039)
		(end 100.971096 -251.774452)
		(width 0.350012)
		(layer "F.Cu")
		(net "PVDD18_S5_P1")
	)
	(segment
		(start 97.207832 -252.850396)
		(end 96.74098 -252.584458)
		(width 0.350012)
		(layer "F.Cu")
		(net "PVDD18_S5_P1")
	)
	(segment
		(start 152.485598 -203.364846)
		(end 151.967692 -203.882752)
		(width 0.508)
		(layer "F.Cu")
		(net "PVDD18_S5_P1")
	)
	(segment
		(start 99.08794 -252.850396)
		(end 98.621088 -252.584458)
		(width 0.350012)
		(layer "F.Cu")
		(net "PVDD18_S5_P1")
	)
	(segment
		(start 278.666194 -96.019112)
		(end 277.68931 -96.019112)
		(width 0.3556)
		(layer "F.Cu")
		(net "PVDD18_S5_P1")
	)
	(segment
		(start 153.738834 -320.699892)
		(end 153.865834 -320.826892)
		(width 0.4064)
		(layer "F.Cu")
		(net "PVDD18_S5_P1")
	)
	(segment
		(start 154.788108 -200.611486)
		(end 155.768294 -201.591672)
		(width 0.508)
		(layer "F.Cu")
		(net "PVDD18_S5_P1")
	)
	(segment
		(start 89.326212 -143.86941)
		(end 89.193878 -144.001744)
		(width 0.381)
		(layer "F.Cu")
		(net "PVDD18_S5_P1")
	)
	(segment
		(start 150.049484 -320.717672)
		(end 151.265128 -320.717672)
		(width 0.4064)
		(layer "F.Cu")
		(net "PVDD18_S5_P1")
	)
	(segment
		(start 157.286452 -349.270828)
		(end 156.623766 -349.270828)
		(width 0.381)
		(layer "F.Cu")
		(net "PVDD18_S5_P1")
	)
	(segment
		(start 100.967794 -251.230384)
		(end 100.500942 -250.964446)
		(width 0.350012)
		(layer "F.Cu")
		(net "PVDD18_S5_P1")
	)
	(segment
		(start 153.249884 -324.763892)
		(end 153.516838 -324.763892)
		(width 0.4064)
		(layer "F.Cu")
		(net "PVDD18_S5_P1")
	)
	(segment
		(start 276.881844 -94.789498)
		(end 276.881844 -94.085918)
		(width 0.3556)
		(layer "F.Cu")
		(net "PVDD18_S5_P1")
	)
	(segment
		(start 97.677986 -252.04039)
		(end 97.211134 -251.774452)
		(width 0.350012)
		(layer "F.Cu")
		(net "PVDD18_S5_P1")
	)
	(segment
		(start 97.207832 -249.610372)
		(end 96.74098 -249.344434)
		(width 0.350012)
		(layer "F.Cu")
		(net "PVDD18_S5_P1")
	)
	(segment
		(start 277.68931 -96.019112)
		(end 277.346918 -95.67672)
		(width 0.3556)
		(layer "F.Cu")
		(net "PVDD18_S5_P1")
	)
	(segment
		(start 97.207832 -254.470408)
		(end 96.74098 -254.20447)
		(width 0.350012)
		(layer "F.Cu")
		(net "PVDD18_S5_P1")
	)
	(segment
		(start 99.55784 -250.420378)
		(end 99.090988 -250.15444)
		(width 0.350012)
		(layer "F.Cu")
		(net "PVDD18_S5_P1")
	)
	(segment
		(start 130.73507 -217.549476)
		(end 117.02034 -203.834746)
		(width 0.508)
		(layer "F.Cu")
		(net "PVDD18_S5_P1")
	)
	(segment
		(start 93.454474 -304.033174)
		(end 92.935298 -304.033174)
		(width 0.508)
		(layer "F.Cu")
		(net "PVDD18_S5_P1")
	)
	(segment
		(start 152.570688 -204.584046)
		(end 151.869394 -203.882752)
		(width 0.508)
		(layer "F.Cu")
		(net "PVDD18_S5_P1")
	)
	(segment
		(start 151.967692 -203.882752)
		(end 151.869394 -203.882752)
		(width 0.508)
		(layer "F.Cu")
		(net "PVDD18_S5_P1")
	)
	(segment
		(start 144.386554 -321.295522)
		(end 144.48536 -321.295522)
		(width 0.508)
		(layer "F.Cu")
		(net "PVDD18_S5_P1")
	)
	(segment
		(start 151.884888 -205.68666)
		(end 152.571196 -205.000352)
		(width 0.508)
		(layer "F.Cu")
		(net "PVDD18_S5_P1")
	)
	(segment
		(start 99.08794 -256.09042)
		(end 98.621088 -255.824482)
		(width 0.350012)
		(layer "F.Cu")
		(net "PVDD18_S5_P1")
	)
	(segment
		(start 92.935298 -304.033174)
		(end 92.261944 -304.706528)
		(width 0.508)
		(layer "F.Cu")
		(net "PVDD18_S5_P1")
	)
	(segment
		(start 26.351992 -363.531404)
		(end 26.72969 -363.909102)
		(width 0.1778)
		(layer "F.Cu")
		(net "PVDD18_S5_P1")
	)
	(segment
		(start 152.571196 -204.584046)
		(end 152.570688 -204.584046)
		(width 0.508)
		(layer "F.Cu")
		(net "PVDD18_S5_P1")
	)
	(segment
		(start 99.55784 -255.280414)
		(end 99.090988 -255.014476)
		(width 0.350012)
		(layer "F.Cu")
		(net "PVDD18_S5_P1")
	)
	(segment
		(start 25.16505 -363.347)
		(end 26.167588 -363.347)
		(width 0.381)
		(layer "F.Cu")
		(net "PVDD18_S5_P1")
	)
	(segment
		(start 91.530932 -303.975516)
		(end 91.530932 -300.750732)
		(width 0.508)
		(layer "F.Cu")
		(net "PVDD18_S5_P1")
	)
	(segment
		(start 149.750018 -206.271622)
		(end 150.513288 -205.508352)
		(width 0.508)
		(layer "F.Cu")
		(net "PVDD18_S5_P1")
	)
	(segment
		(start 94.187264 -305.859942)
		(end 94.187264 -304.29962)
		(width 0.508)
		(layer "F.Cu")
		(net "PVDD18_S5_P1")
	)
	(segment
		(start 154.6606 -203.364846)
		(end 152.485598 -203.364846)
		(width 0.508)
		(layer "F.Cu")
		(net "PVDD18_S5_P1")
	)
	(segment
		(start 97.677986 -253.660402)
		(end 97.211134 -253.394464)
		(width 0.350012)
		(layer "F.Cu")
		(net "PVDD18_S5_P1")
	)
	(segment
		(start 94.572328 -306.701952)
		(end 94.060264 -306.189888)
		(width 0.508)
		(layer "F.Cu")
		(net "PVDD18_S5_P1")
	)
	(segment
		(start 102.458774 -145.673064)
		(end 102.284022 -145.673064)
		(width 0.4572)
		(layer "F.Cu")
		(net "PVDD18_S5_P1")
	)
	(segment
		(start 97.207832 -251.230384)
		(end 96.74098 -250.964446)
		(width 0.350012)
		(layer "F.Cu")
		(net "PVDD18_S5_P1")
	)
	(segment
		(start 144.311624 -321.220592)
		(end 144.311624 -320.804032)
		(width 0.508)
		(layer "F.Cu")
		(net "PVDD18_S5_P1")
	)
	(segment
		(start 89.809828 -143.86941)
		(end 89.326212 -143.86941)
		(width 0.381)
		(layer "F.Cu")
		(net "PVDD18_S5_P1")
	)
	(segment
		(start 93.920818 -304.033174)
		(end 93.454474 -304.033174)
		(width 0.508)
		(layer "F.Cu")
		(net "PVDD18_S5_P1")
	)
	(segment
		(start 102.284022 -145.673064)
		(end 102.179374 -145.777712)
		(width 0.4572)
		(layer "F.Cu")
		(net "PVDD18_S5_P1")
	)
	(segment
		(start 94.060264 -305.986942)
		(end 94.187264 -305.859942)
		(width 0.508)
		(layer "F.Cu")
		(net "PVDD18_S5_P1")
	)
	(segment
		(start 37.61105 -362.077)
		(end 38.3286 -362.077)
		(width 0.381)
		(layer "F.Cu")
		(net "PVDD18_S5_P1")
	)
	(segment
		(start 99.08794 -249.610372)
		(end 98.621088 -249.344434)
		(width 0.350012)
		(layer "F.Cu")
		(net "PVDD18_S5_P1")
	)
	(segment
		(start 150.691596 -205.68666)
		(end 151.884888 -205.68666)
		(width 0.508)
		(layer "F.Cu")
		(net "PVDD18_S5_P1")
	)
	(segment
		(start 183.007 -138.032998)
		(end 183.007 -138.737594)
		(width 0.508)
		(layer "F.Cu")
		(net "PVDD18_S5_P1")
	)
	(segment
		(start 117.02034 -203.834746)
		(end 95.95104 -203.834746)
		(width 0.508)
		(layer "F.Cu")
		(net "PVDD18_S5_P1")
	)
	(segment
		(start 26.72969 -363.909102)
		(end 27.604974 -363.909102)
		(width 0.1778)
		(layer "F.Cu")
		(net "PVDD18_S5_P1")
	)
	(segment
		(start 97.677986 -250.420378)
		(end 97.211134 -250.15444)
		(width 0.350012)
		(layer "F.Cu")
		(net "PVDD18_S5_P1")
	)
	(via
		(at 55.169308 -154.858974)
		(size 0.508)
		(drill 0.254)
		(layers "F.Cu" "B.Cu")
		(net "PVDD18_S5_P1")
	)
	(via
		(at 57.37733 -154.861514)
		(size 0.508)
		(drill 0.254)
		(layers "F.Cu" "B.Cu")
		(net "PVDD18_S5_P1")
	)
	(via
		(at 97.211134 -250.15444)
		(size 0.4064)
		(drill 0.2032)
		(layers "F.Cu" "B.Cu")
		(net "PVDD18_S5_P1")
	)
	(via
		(at 8.90016 -328.277982)
		(size 0.508)
		(drill 0.254)
		(layers "F.Cu" "B.Cu")
		(net "PVDD18_S5_P1")
	)
	(via
		(at 100.500942 -252.584458)
		(size 0.4064)
		(drill 0.2032)
		(layers "F.Cu" "B.Cu")
		(net "PVDD18_S5_P1")
	)
	(via
		(at 156.623766 -349.270828)
		(size 0.508)
		(drill 0.254)
		(layers "F.Cu" "B.Cu")
		(net "PVDD18_S5_P1")
	)
	(via
		(at 55.908194 -153.360628)
		(size 0.508)
		(drill 0.254)
		(layers "F.Cu" "B.Cu")
		(net "PVDD18_S5_P1")
	)
	(via
		(at 95.572834 -306.701952)
		(size 0.508)
		(drill 0.254)
		(layers "F.Cu" "B.Cu")
		(net "PVDD18_S5_P1")
	)
	(via
		(at 98.621088 -254.20447)
		(size 0.4064)
		(drill 0.2032)
		(layers "F.Cu" "B.Cu")
		(net "PVDD18_S5_P1")
	)
	(via
		(at 53.658516 -151.16683)
		(size 0.508)
		(drill 0.254)
		(layers "F.Cu" "B.Cu")
		(net "PVDD18_S5_P1")
	)
	(via
		(at 53.676804 -154.157172)
		(size 0.508)
		(drill 0.254)
		(layers "F.Cu" "B.Cu")
		(net "PVDD18_S5_P1")
	)
	(via
		(at 89.193878 -144.001744)
		(size 0.508)
		(drill 0.254)
		(layers "F.Cu" "B.Cu")
		(net "PVDD18_S5_P1")
	)
	(via
		(at 55.169308 -154.163522)
		(size 0.508)
		(drill 0.254)
		(layers "F.Cu" "B.Cu")
		(net "PVDD18_S5_P1")
	)
	(via
		(at 238.379 -230.505)
		(size 0.508)
		(drill 0.254)
		(layers "F.Cu" "B.Cu")
		(net "PVDD18_S5_P1")
	)
	(via
		(at 92.261944 -304.706528)
		(size 0.508)
		(drill 0.254)
		(layers "F.Cu" "B.Cu")
		(net "PVDD18_S5_P1")
	)
	(via
		(at 91.352878 -144.958308)
		(size 0.508)
		(drill 0.254)
		(layers "F.Cu" "B.Cu")
		(net "PVDD18_S5_P1")
	)
	(via
		(at 131.320286 -217.549476)
		(size 0.508)
		(drill 0.254)
		(layers "F.Cu" "B.Cu")
		(net "PVDD18_S5_P1")
	)
	(via
		(at 100.500942 -254.20447)
		(size 0.4064)
		(drill 0.2032)
		(layers "F.Cu" "B.Cu")
		(net "PVDD18_S5_P1")
	)
	(via
		(at 209.408776 -317.35268)
		(size 0.508)
		(drill 0.254)
		(layers "F.Cu" "B.Cu")
		(net "PVDD18_S5_P1")
	)
	(via
		(at 99.090988 -250.15444)
		(size 0.4064)
		(drill 0.2032)
		(layers "F.Cu" "B.Cu")
		(net "PVDD18_S5_P1")
	)
	(via
		(at 56.693308 -154.163522)
		(size 0.508)
		(drill 0.254)
		(layers "F.Cu" "B.Cu")
		(net "PVDD18_S5_P1")
	)
	(via
		(at 115.245642 -133.745732)
		(size 0.508)
		(drill 0.254)
		(layers "F.Cu" "B.Cu")
		(net "PVDD18_S5_P1")
	)
	(via
		(at 57.556146 -145.02638)
		(size 0.508)
		(drill 0.254)
		(layers "F.Cu" "B.Cu")
		(net "PVDD18_S5_P1")
	)
	(via
		(at 105.490772 -255.53035)
		(size 0.4826)
		(drill 0.254)
		(layers "F.Cu" "B.Cu")
		(net "PVDD18_S5_P1")
	)
	(via
		(at 96.74098 -252.584458)
		(size 0.4064)
		(drill 0.2032)
		(layers "F.Cu" "B.Cu")
		(net "PVDD18_S5_P1")
	)
	(via
		(at 8.91032 -329.78344)
		(size 0.508)
		(drill 0.254)
		(layers "F.Cu" "B.Cu")
		(net "PVDD18_S5_P1")
	)
	(via
		(at 54.609746 -148.759672)
		(size 0.508)
		(drill 0.254)
		(layers "F.Cu" "B.Cu")
		(net "PVDD18_S5_P1")
	)
	(via
		(at 96.74098 -254.20447)
		(size 0.4064)
		(drill 0.2032)
		(layers "F.Cu" "B.Cu")
		(net "PVDD18_S5_P1")
	)
	(via
		(at 56.133746 -148.759672)
		(size 0.508)
		(drill 0.254)
		(layers "F.Cu" "B.Cu")
		(net "PVDD18_S5_P1")
	)
	(via
		(at 96.74098 -255.824482)
		(size 0.4064)
		(drill 0.2032)
		(layers "F.Cu" "B.Cu")
		(net "PVDD18_S5_P1")
	)
	(via
		(at 38.3286 -362.077)
		(size 0.508)
		(drill 0.254)
		(layers "F.Cu" "B.Cu")
		(net "PVDD18_S5_P1")
	)
	(via
		(at 22.054058 -356.63632)
		(size 0.508)
		(drill 0.254)
		(layers "F.Cu" "B.Cu")
		(net "PVDD18_S5_P1")
	)
	(via
		(at 58.13933 -154.861514)
		(size 0.508)
		(drill 0.254)
		(layers "F.Cu" "B.Cu")
		(net "PVDD18_S5_P1")
	)
	(via
		(at 90.594434 -204.111352)
		(size 0.508)
		(drill 0.254)
		(layers "F.Cu" "B.Cu")
		(net "PVDD18_S5_P1")
	)
	(via
		(at 96.74098 -249.344434)
		(size 0.4064)
		(drill 0.2032)
		(layers "F.Cu" "B.Cu")
		(net "PVDD18_S5_P1")
	)
	(via
		(at 91.864434 -204.111352)
		(size 0.508)
		(drill 0.254)
		(layers "F.Cu" "B.Cu")
		(net "PVDD18_S5_P1")
	)
	(via
		(at 93.454474 -304.033174)
		(size 0.508)
		(drill 0.254)
		(layers "F.Cu" "B.Cu")
		(net "PVDD18_S5_P1")
	)
	(via
		(at 130.942842 -85.245702)
		(size 0.508)
		(drill 0.254)
		(layers "F.Cu" "B.Cu")
		(net "PVDD18_S5_P1")
	)
	(via
		(at 154.788108 -200.324212)
		(size 0.508)
		(drill 0.254)
		(layers "F.Cu" "B.Cu")
		(net "PVDD18_S5_P1")
	)
	(via
		(at 98.621088 -250.964446)
		(size 0.4064)
		(drill 0.2032)
		(layers "F.Cu" "B.Cu")
		(net "PVDD18_S5_P1")
	)
	(via
		(at 220.038676 -318.999362)
		(size 0.508)
		(drill 0.254)
		(layers "F.Cu" "B.Cu")
		(net "PVDD18_S5_P1")
	)
	(via
		(at 238.997998 -328.724514)
		(size 0.508)
		(drill 0.254)
		(layers "F.Cu" "B.Cu")
		(net "PVDD18_S5_P1")
	)
	(via
		(at 89.324434 -204.111352)
		(size 0.508)
		(drill 0.254)
		(layers "F.Cu" "B.Cu")
		(net "PVDD18_S5_P1")
	)
	(via
		(at 105.490772 -256.48031)
		(size 0.4826)
		(drill 0.254)
		(layers "F.Cu" "B.Cu")
		(net "PVDD18_S5_P1")
	)
	(via
		(at 154.081226 -324.688708)
		(size 0.508)
		(drill 0.254)
		(layers "F.Cu" "B.Cu")
		(net "PVDD18_S5_P1")
	)
	(via
		(at 14.667738 -322.69938)
		(size 0.508)
		(drill 0.254)
		(layers "F.Cu" "B.Cu")
		(net "PVDD18_S5_P1")
	)
	(via
		(at 235.077 -230.505)
		(size 0.508)
		(drill 0.254)
		(layers "F.Cu" "B.Cu")
		(net "PVDD18_S5_P1")
	)
	(via
		(at 183.007 -138.737594)
		(size 0.508)
		(drill 0.254)
		(layers "F.Cu" "B.Cu")
		(net "PVDD18_S5_P1")
	)
	(via
		(at 152.485598 -203.364846)
		(size 0.508)
		(drill 0.254)
		(layers "F.Cu" "B.Cu")
		(net "PVDD18_S5_P1")
	)
	(via
		(at 66.286634 -197.608952)
		(size 0.508)
		(drill 0.254)
		(layers "F.Cu" "B.Cu")
		(net "PVDD18_S5_P1")
	)
	(via
		(at 54.407308 -154.163522)
		(size 0.508)
		(drill 0.254)
		(layers "F.Cu" "B.Cu")
		(net "PVDD18_S5_P1")
	)
	(via
		(at 145.8468 -312.3946)
		(size 0.508)
		(drill 0.254)
		(layers "F.Cu" "B.Cu")
		(net "PVDD18_S5_P1")
	)
	(via
		(at 98.621088 -249.344434)
		(size 0.4064)
		(drill 0.2032)
		(layers "F.Cu" "B.Cu")
		(net "PVDD18_S5_P1")
	)
	(via
		(at 55.931308 -154.163522)
		(size 0.508)
		(drill 0.254)
		(layers "F.Cu" "B.Cu")
		(net "PVDD18_S5_P1")
	)
	(via
		(at 52.560982 -187.268358)
		(size 0.508)
		(drill 0.254)
		(layers "F.Cu" "B.Cu")
		(net "PVDD18_S5_P1")
	)
	(via
		(at 97.211134 -253.394464)
		(size 0.4064)
		(drill 0.2032)
		(layers "F.Cu" "B.Cu")
		(net "PVDD18_S5_P1")
	)
	(via
		(at 151.592534 -203.882752)
		(size 0.508)
		(drill 0.254)
		(layers "F.Cu" "B.Cu")
		(net "PVDD18_S5_P1")
	)
	(via
		(at 151.265128 -320.717672)
		(size 0.508)
		(drill 0.254)
		(layers "F.Cu" "B.Cu")
		(net "PVDD18_S5_P1")
	)
	(via
		(at 98.621088 -252.584458)
		(size 0.4064)
		(drill 0.2032)
		(layers "F.Cu" "B.Cu")
		(net "PVDD18_S5_P1")
	)
	(via
		(at 107.917742 -257.74523)
		(size 0.4826)
		(drill 0.254)
		(layers "F.Cu" "B.Cu")
		(net "PVDD18_S5_P1")
	)
	(via
		(at 93.134434 -204.111352)
		(size 0.508)
		(drill 0.254)
		(layers "F.Cu" "B.Cu")
		(net "PVDD18_S5_P1")
	)
	(via
		(at 99.090988 -251.774452)
		(size 0.4064)
		(drill 0.2032)
		(layers "F.Cu" "B.Cu")
		(net "PVDD18_S5_P1")
	)
	(via
		(at 88.165178 -298.283122)
		(size 0.508)
		(drill 0.254)
		(layers "F.Cu" "B.Cu")
		(net "PVDD18_S5_P1")
	)
	(via
		(at 53.658516 -153.22423)
		(size 0.508)
		(drill 0.254)
		(layers "F.Cu" "B.Cu")
		(net "PVDD18_S5_P1")
	)
	(via
		(at 157.165294 -321.814952)
		(size 0.508)
		(drill 0.254)
		(layers "F.Cu" "B.Cu")
		(net "PVDD18_S5_P1")
	)
	(via
		(at 55.931308 -154.858974)
		(size 0.508)
		(drill 0.254)
		(layers "F.Cu" "B.Cu")
		(net "PVDD18_S5_P1")
	)
	(via
		(at 95.674434 -204.111352)
		(size 0.508)
		(drill 0.254)
		(layers "F.Cu" "B.Cu")
		(net "PVDD18_S5_P1")
	)
	(via
		(at 8.90016 -329.02652)
		(size 0.508)
		(drill 0.254)
		(layers "F.Cu" "B.Cu")
		(net "PVDD18_S5_P1")
	)
	(via
		(at 276.881844 -94.085918)
		(size 0.508)
		(drill 0.254)
		(layers "F.Cu" "B.Cu")
		(net "PVDD18_S5_P1")
	)
	(via
		(at 97.211134 -251.774452)
		(size 0.4064)
		(drill 0.2032)
		(layers "F.Cu" "B.Cu")
		(net "PVDD18_S5_P1")
	)
	(via
		(at 100.971096 -251.774452)
		(size 0.4064)
		(drill 0.2032)
		(layers "F.Cu" "B.Cu")
		(net "PVDD18_S5_P1")
	)
	(via
		(at 54.407308 -154.858974)
		(size 0.508)
		(drill 0.254)
		(layers "F.Cu" "B.Cu")
		(net "PVDD18_S5_P1")
	)
	(via
		(at 122.884692 -262.746236)
		(size 0.4064)
		(drill 0.2032)
		(layers "F.Cu" "B.Cu")
		(net "PVDD18_S5_P1")
	)
	(via
		(at 153.865834 -320.826892)
		(size 0.508)
		(drill 0.254)
		(layers "F.Cu" "B.Cu")
		(net "PVDD18_S5_P1")
	)
	(via
		(at 52.896516 -153.22423)
		(size 0.508)
		(drill 0.254)
		(layers "F.Cu" "B.Cu")
		(net "PVDD18_S5_P1")
	)
	(via
		(at 56.902096 -160.62579)
		(size 0.508)
		(drill 0.254)
		(layers "F.Cu" "B.Cu")
		(net "PVDD18_S5_P1")
	)
	(via
		(at 55.378096 -158.08579)
		(size 0.508)
		(drill 0.254)
		(layers "F.Cu" "B.Cu")
		(net "PVDD18_S5_P1")
	)
	(via
		(at 56.670194 -153.360628)
		(size 0.508)
		(drill 0.254)
		(layers "F.Cu" "B.Cu")
		(net "PVDD18_S5_P1")
	)
	(via
		(at 97.211134 -255.014476)
		(size 0.4064)
		(drill 0.2032)
		(layers "F.Cu" "B.Cu")
		(net "PVDD18_S5_P1")
	)
	(via
		(at 57.664096 -158.08579)
		(size 0.508)
		(drill 0.254)
		(layers "F.Cu" "B.Cu")
		(net "PVDD18_S5_P1")
	)
	(via
		(at 56.140096 -160.62579)
		(size 0.508)
		(drill 0.254)
		(layers "F.Cu" "B.Cu")
		(net "PVDD18_S5_P1")
	)
	(via
		(at 144.97685 -320.804032)
		(size 0.508)
		(drill 0.254)
		(layers "F.Cu" "B.Cu")
		(net "PVDD18_S5_P1")
	)
	(via
		(at 100.500942 -250.964446)
		(size 0.4064)
		(drill 0.2032)
		(layers "F.Cu" "B.Cu")
		(net "PVDD18_S5_P1")
	)
	(via
		(at 99.090988 -255.014476)
		(size 0.4064)
		(drill 0.2032)
		(layers "F.Cu" "B.Cu")
		(net "PVDD18_S5_P1")
	)
	(via
		(at 52.834286 -154.940254)
		(size 0.508)
		(drill 0.254)
		(layers "F.Cu" "B.Cu")
		(net "PVDD18_S5_P1")
	)
	(via
		(at 56.902096 -158.08579)
		(size 0.508)
		(drill 0.254)
		(layers "F.Cu" "B.Cu")
		(net "PVDD18_S5_P1")
	)
	(via
		(at 102.458774 -145.673064)
		(size 0.508)
		(drill 0.254)
		(layers "F.Cu" "B.Cu")
		(net "PVDD18_S5_P1")
	)
	(via
		(at 56.895746 -148.759672)
		(size 0.508)
		(drill 0.254)
		(layers "F.Cu" "B.Cu")
		(net "PVDD18_S5_P1")
	)
	(via
		(at 56.140096 -158.08579)
		(size 0.508)
		(drill 0.254)
		(layers "F.Cu" "B.Cu")
		(net "PVDD18_S5_P1")
	)
	(via
		(at 55.378096 -160.62579)
		(size 0.508)
		(drill 0.254)
		(layers "F.Cu" "B.Cu")
		(net "PVDD18_S5_P1")
	)
	(via
		(at 71.488046 -205.640686)
		(size 0.508)
		(drill 0.254)
		(layers "F.Cu" "B.Cu")
		(net "PVDD18_S5_P1")
	)
	(via
		(at 57.664096 -160.62579)
		(size 0.508)
		(drill 0.254)
		(layers "F.Cu" "B.Cu")
		(net "PVDD18_S5_P1")
	)
	(via
		(at 168.100502 -348.000574)
		(size 0.508)
		(drill 0.254)
		(layers "F.Cu" "B.Cu")
		(net "PVDD18_S5_P1")
	)
	(via
		(at 94.060264 -305.986942)
		(size 0.508)
		(drill 0.254)
		(layers "F.Cu" "B.Cu")
		(net "PVDD18_S5_P1")
	)
	(via
		(at 157.165294 -324.781672)
		(size 0.508)
		(drill 0.254)
		(layers "F.Cu" "B.Cu")
		(net "PVDD18_S5_P1")
	)
	(via
		(at 8.89254 -327.52919)
		(size 0.508)
		(drill 0.254)
		(layers "F.Cu" "B.Cu")
		(net "PVDD18_S5_P1")
	)
	(via
		(at 99.090988 -253.394464)
		(size 0.4064)
		(drill 0.2032)
		(layers "F.Cu" "B.Cu")
		(net "PVDD18_S5_P1")
	)
	(via
		(at 52.896516 -151.16683)
		(size 0.508)
		(drill 0.254)
		(layers "F.Cu" "B.Cu")
		(net "PVDD18_S5_P1")
	)
	(via
		(at 68.7959 -202.59167)
		(size 0.508)
		(drill 0.254)
		(layers "F.Cu" "B.Cu")
		(net "PVDD18_S5_P1")
	)
	(via
		(at 134.446518 -102.561136)
		(size 0.508)
		(drill 0.254)
		(layers "F.Cu" "B.Cu")
		(net "PVDD18_S5_P1")
	)
	(via
		(at 98.621088 -255.824482)
		(size 0.4064)
		(drill 0.2032)
		(layers "F.Cu" "B.Cu")
		(net "PVDD18_S5_P1")
	)
	(via
		(at 56.693308 -154.858974)
		(size 0.508)
		(drill 0.254)
		(layers "F.Cu" "B.Cu")
		(net "PVDD18_S5_P1")
	)
	(via
		(at 52.914804 -154.157172)
		(size 0.508)
		(drill 0.254)
		(layers "F.Cu" "B.Cu")
		(net "PVDD18_S5_P1")
	)
	(via
		(at 156.355034 -200.265792)
		(size 0.508)
		(drill 0.254)
		(layers "F.Cu" "B.Cu")
		(net "PVDD18_S5_P1")
	)
	(via
		(at 150.513288 -205.508352)
		(size 0.508)
		(drill 0.254)
		(layers "F.Cu" "B.Cu")
		(net "PVDD18_S5_P1")
	)
	(via
		(at 149.479 -206.271622)
		(size 0.508)
		(drill 0.254)
		(layers "F.Cu" "B.Cu")
		(net "PVDD18_S5_P1")
	)
	(via
		(at 181.943502 -154.974036)
		(size 0.508)
		(drill 0.254)
		(layers "F.Cu" "B.Cu")
		(net "PVDD18_S5_P1")
	)
	(via
		(at 24.8412 -363.982)
		(size 0.508)
		(drill 0.254)
		(layers "F.Cu" "B.Cu")
		(net "PVDD18_S5_P1")
	)
	(via
		(at 94.404434 -204.111352)
		(size 0.508)
		(drill 0.254)
		(layers "F.Cu" "B.Cu")
		(net "PVDD18_S5_P1")
	)
	(via
		(at 53.596286 -154.940254)
		(size 0.508)
		(drill 0.254)
		(layers "F.Cu" "B.Cu")
		(net "PVDD18_S5_P1")
	)
	(via
		(at 96.74098 -250.964446)
		(size 0.4064)
		(drill 0.2032)
		(layers "F.Cu" "B.Cu")
		(net "PVDD18_S5_P1")
	)
	(via
		(at 112.716056 -299.56633)
		(size 0.508)
		(drill 0.254)
		(layers "F.Cu" "B.Cu")
		(net "PVDD18_S5_P1")
	)
	(via
		(at 55.371746 -148.759672)
		(size 0.508)
		(drill 0.254)
		(layers "F.Cu" "B.Cu")
		(net "PVDD18_S5_P1")
	)
	(segment
		(start 181.638702 -137.369296)
		(end 181.638702 -136.000744)
		(width 0.508)
		(layer "B.Cu")
		(net "PVDD18_S5_P1")
	)
	(segment
		(start 220.038676 -318.999362)
		(end 211.055458 -318.999362)
		(width 0.508)
		(layer "B.Cu")
		(net "PVDD18_S5_P1")
	)
	(segment
		(start 104.558338 -307.724048)
		(end 112.716056 -299.56633)
		(width 0.508)
		(layer "B.Cu")
		(net "PVDD18_S5_P1")
	)
	(segment
		(start 153.357834 -199.634602)
		(end 154.047444 -200.324212)
		(width 0.4064)
		(layer "B.Cu")
		(net "PVDD18_S5_P1")
	)
	(segment
		(start 149.420326 -206.212948)
		(end 149.479 -206.271622)
		(width 0.508)
		(layer "B.Cu")
		(net "PVDD18_S5_P1")
	)
	(segment
		(start 149.243034 -204.796898)
		(end 149.954488 -205.508352)
		(width 0.3556)
		(layer "B.Cu")
		(net "PVDD18_S5_P1")
	)
	(segment
		(start 144.97685 -320.804032)
		(end 144.462246 -320.804032)
		(width 0.3556)
		(layer "B.Cu")
		(net "PVDD18_S5_P1")
	)
	(segment
		(start 145.332704 -314.49899)
		(end 145.327624 -314.49391)
		(width 0.508)
		(layer "B.Cu")
		(net "PVDD18_S5_P1")
	)
	(segment
		(start 94.08795 -303.748948)
		(end 93.7387 -303.748948)
		(width 0.508)
		(layer "B.Cu")
		(net "PVDD18_S5_P1")
	)
	(segment
		(start 24.36495 -363.347)
		(end 24.36495 -363.50575)
		(width 0.381)
		(layer "B.Cu")
		(net "PVDD18_S5_P1")
	)
	(segment
		(start 181.57063 -135.932672)
		(end 181.57063 -134.238746)
		(width 0.508)
		(layer "B.Cu")
		(net "PVDD18_S5_P1")
	)
	(segment
		(start 148.463254 -206.212948)
		(end 149.420326 -206.212948)
		(width 0.508)
		(layer "B.Cu")
		(net "PVDD18_S5_P1")
	)
	(segment
		(start 69.747384 -202.663552)
		(end 68.867782 -202.663552)
		(width 0.381)
		(layer "B.Cu")
		(net "PVDD18_S5_P1")
	)
	(segment
		(start 144.462246 -320.804032)
		(end 143.5862 -319.927986)
		(width 0.3556)
		(layer "B.Cu")
		(net "PVDD18_S5_P1")
	)
	(segment
		(start 152.849834 -321.842892)
		(end 153.865834 -320.826892)
		(width 0.508)
		(layer "B.Cu")
		(net "PVDD18_S5_P1")
	)
	(segment
		(start 52.560982 -187.738766)
		(end 52.560982 -187.268358)
		(width 0.508)
		(layer "B.Cu")
		(net "PVDD18_S5_P1")
	)
	(segment
		(start 181.731412 -141.565884)
		(end 181.370224 -141.927072)
		(width 0.508)
		(layer "B.Cu")
		(net "PVDD18_S5_P1")
	)
	(segment
		(start 183.175656 -153.741882)
		(end 181.943502 -154.974036)
		(width 0.508)
		(layer "B.Cu")
		(net "PVDD18_S5_P1")
	)
	(segment
		(start 146.220434 -204.416152)
		(end 146.525488 -204.721206)
		(width 0.508)
		(layer "B.Cu")
		(net "PVDD18_S5_P1")
	)
	(segment
		(start 156.554424 -324.781672)
		(end 157.165294 -324.781672)
		(width 0.381)
		(layer "B.Cu")
		(net "PVDD18_S5_P1")
	)
	(segment
		(start 181.638702 -136.000744)
		(end 181.57063 -135.932672)
		(width 0.508)
		(layer "B.Cu")
		(net "PVDD18_S5_P1")
	)
	(segment
		(start 96.882712 -307.724048)
		(end 104.558338 -307.724048)
		(width 0.508)
		(layer "B.Cu")
		(net "PVDD18_S5_P1")
	)
	(segment
		(start 147.574 -205.323694)
		(end 148.463254 -206.212948)
		(width 0.508)
		(layer "B.Cu")
		(net "PVDD18_S5_P1")
	)
	(segment
		(start 96.442784 -306.701952)
		(end 96.442784 -307.28412)
		(width 0.508)
		(layer "B.Cu")
		(net "PVDD18_S5_P1")
	)
	(segment
		(start 156.554424 -321.817492)
		(end 156.551884 -321.814952)
		(width 0.381)
		(layer "B.Cu")
		(net "PVDD18_S5_P1")
	)
	(segment
		(start 55.869586 -191.04737)
		(end 52.560982 -187.738766)
		(width 0.508)
		(layer "B.Cu")
		(net "PVDD18_S5_P1")
	)
	(segment
		(start 156.551884 -321.814952)
		(end 157.165294 -321.814952)
		(width 0.381)
		(layer "B.Cu")
		(net "PVDD18_S5_P1")
	)
	(segment
		(start 92.795852 -144.958308)
		(end 92.241878 -144.958308)
		(width 0.1778)
		(layer "B.Cu")
		(net "PVDD18_S5_P1")
	)
	(segment
		(start 156.554424 -322.805552)
		(end 156.554424 -321.817492)
		(width 0.381)
		(layer "B.Cu")
		(net "PVDD18_S5_P1")
	)
	(segment
		(start 151.534114 -203.882752)
		(end 151.592534 -203.882752)
		(width 0.508)
		(layer "B.Cu")
		(net "PVDD18_S5_P1")
	)
	(segment
		(start 78.342998 -298.283122)
		(end 59.454796 -317.171324)
		(width 0.508)
		(layer "B.Cu")
		(net "PVDD18_S5_P1")
	)
	(segment
		(start 145.322544 -312.918856)
		(end 145.8468 -312.3946)
		(width 0.381)
		(layer "B.Cu")
		(net "PVDD18_S5_P1")
	)
	(segment
		(start 183.175656 -148.746464)
		(end 183.175656 -153.741882)
		(width 0.508)
		(layer "B.Cu")
		(net "PVDD18_S5_P1")
	)
	(segment
		(start 146.525488 -204.721206)
		(end 147.352258 -204.721206)
		(width 0.508)
		(layer "B.Cu")
		(net "PVDD18_S5_P1")
	)
	(segment
		(start 66.800984 -199.336152)
		(end 66.800984 -198.269352)
		(width 0.381)
		(layer "B.Cu")
		(net "PVDD18_S5_P1")
	)
	(segment
		(start 149.954488 -205.508352)
		(end 150.513288 -205.508352)
		(width 0.3556)
		(layer "B.Cu")
		(net "PVDD18_S5_P1")
	)
	(segment
		(start 156.355034 -199.634602)
		(end 156.355034 -200.265792)
		(width 0.4064)
		(layer "B.Cu")
		(net "PVDD18_S5_P1")
	)
	(segment
		(start 66.286634 -197.755002)
		(end 66.286634 -197.608952)
		(width 0.381)
		(layer "B.Cu")
		(net "PVDD18_S5_P1")
	)
	(segment
		(start 59.233562 -191.04737)
		(end 55.869586 -191.04737)
		(width 0.508)
		(layer "B.Cu")
		(net "PVDD18_S5_P1")
	)
	(segment
		(start 94.08795 -303.748948)
		(end 94.08795 -302.823118)
		(width 0.508)
		(layer "B.Cu")
		(net "PVDD18_S5_P1")
	)
	(segment
		(start 16.66367 -320.703448)
		(end 14.667738 -322.69938)
		(width 0.508)
		(layer "B.Cu")
		(net "PVDD18_S5_P1")
	)
	(segment
		(start 147.352258 -204.721206)
		(end 147.574 -204.942948)
		(width 0.508)
		(layer "B.Cu")
		(net "PVDD18_S5_P1")
	)
	(segment
		(start 92.241878 -144.958308)
		(end 91.352878 -144.958308)
		(width 0.2032)
		(layer "B.Cu")
		(net "PVDD18_S5_P1")
	)
	(segment
		(start 66.800984 -198.269352)
		(end 66.286634 -197.755002)
		(width 0.381)
		(layer "B.Cu")
		(net "PVDD18_S5_P1")
	)
	(segment
		(start 143.5862 -319.927986)
		(end 143.5862 -319.34658)
		(width 0.3556)
		(layer "B.Cu")
		(net "PVDD18_S5_P1")
	)
	(segment
		(start 68.7959 -202.59167)
		(end 68.547234 -202.343004)
		(width 0.381)
		(layer "B.Cu")
		(net "PVDD18_S5_P1")
	)
	(segment
		(start 152.849834 -322.503292)
		(end 152.849834 -321.842892)
		(width 0.508)
		(layer "B.Cu")
		(net "PVDD18_S5_P1")
	)
	(segment
		(start 94.017846 -306.672234)
		(end 94.060264 -306.714652)
		(width 0.381)
		(layer "B.Cu")
		(net "PVDD18_S5_P1")
	)
	(segment
		(start 143.5862 -319.34658)
		(end 144.724628 -318.208152)
		(width 0.3556)
		(layer "B.Cu")
		(net "PVDD18_S5_P1")
	)
	(segment
		(start 153.228294 -203.33081)
		(end 152.519634 -203.33081)
		(width 0.508)
		(layer "B.Cu")
		(net "PVDD18_S5_P1")
	)
	(segment
		(start 183.007 -138.737594)
		(end 181.638702 -137.369296)
		(width 0.508)
		(layer "B.Cu")
		(net "PVDD18_S5_P1")
	)
	(segment
		(start 55.287926 -320.703448)
		(end 16.66367 -320.703448)
		(width 0.508)
		(layer "B.Cu")
		(net "PVDD18_S5_P1")
	)
	(segment
		(start 91.671902 -304.325274)
		(end 91.88069 -304.325274)
		(width 0.508)
		(layer "B.Cu")
		(net "PVDD18_S5_P1")
	)
	(segment
		(start 145.327624 -313.46013)
		(end 145.322544 -313.45505)
		(width 0.508)
		(layer "B.Cu")
		(net "PVDD18_S5_P1")
	)
	(segment
		(start 145.332704 -315.49467)
		(end 145.332704 -314.49899)
		(width 0.508)
		(layer "B.Cu")
		(net "PVDD18_S5_P1")
	)
	(segment
		(start 235.077 -231.24795)
		(end 235.077 -230.505)
		(width 0.381)
		(layer "B.Cu")
		(net "PVDD18_S5_P1")
	)
	(segment
		(start 91.88069 -304.325274)
		(end 92.261944 -304.706528)
		(width 0.508)
		(layer "B.Cu")
		(net "PVDD18_S5_P1")
	)
	(segment
		(start 145.332704 -316.47511)
		(end 145.332704 -315.49467)
		(width 0.381)
		(layer "B.Cu")
		(net "PVDD18_S5_P1")
	)
	(segment
		(start 69.772784 -202.688952)
		(end 69.747384 -202.663552)
		(width 0.381)
		(layer "B.Cu")
		(net "PVDD18_S5_P1")
	)
	(segment
		(start 181.370224 -146.941032)
		(end 183.175656 -148.746464)
		(width 0.508)
		(layer "B.Cu")
		(net "PVDD18_S5_P1")
	)
	(segment
		(start 71.672704 -204.228192)
		(end 71.488046 -204.41285)
		(width 0.381)
		(layer "B.Cu")
		(net "PVDD18_S5_P1")
	)
	(segment
		(start 238.28121 -328.724514)
		(end 238.997998 -328.724514)
		(width 0.381)
		(layer "B.Cu")
		(net "PVDD18_S5_P1")
	)
	(segment
		(start 168.099994 -348.000066)
		(end 168.100502 -348.000574)
		(width 0.381)
		(layer "B.Cu")
		(net "PVDD18_S5_P1")
	)
	(segment
		(start 94.017846 -306.02936)
		(end 94.017846 -306.672234)
		(width 0.381)
		(layer "B.Cu")
		(net "PVDD18_S5_P1")
	)
	(segment
		(start 147.574 -204.942948)
		(end 147.574 -205.323694)
		(width 0.508)
		(layer "B.Cu")
		(net "PVDD18_S5_P1")
	)
	(segment
		(start 88.165178 -298.283122)
		(end 78.342998 -298.283122)
		(width 0.508)
		(layer "B.Cu")
		(net "PVDD18_S5_P1")
	)
	(segment
		(start 91.352878 -144.958308)
		(end 90.682826 -144.958308)
		(width 0.254)
		(layer "B.Cu")
		(net "PVDD18_S5_P1")
	)
	(segment
		(start 181.731412 -140.013182)
		(end 181.731412 -141.565884)
		(width 0.508)
		(layer "B.Cu")
		(net "PVDD18_S5_P1")
	)
	(segment
		(start 96.442784 -306.701952)
		(end 95.572834 -306.701952)
		(width 0.381)
		(layer "B.Cu")
		(net "PVDD18_S5_P1")
	)
	(segment
		(start 58.82005 -317.171324)
		(end 55.287926 -320.703448)
		(width 0.508)
		(layer "B.Cu")
		(net "PVDD18_S5_P1")
	)
	(segment
		(start 181.370224 -141.927072)
		(end 181.370224 -146.941032)
		(width 0.508)
		(layer "B.Cu")
		(net "PVDD18_S5_P1")
	)
	(segment
		(start 238.379 -231.24795)
		(end 238.379 -230.505)
		(width 0.381)
		(layer "B.Cu")
		(net "PVDD18_S5_P1")
	)
	(segment
		(start 145.327624 -314.49391)
		(end 145.327624 -313.46013)
		(width 0.508)
		(layer "B.Cu")
		(net "PVDD18_S5_P1")
	)
	(segment
		(start 154.047444 -200.324212)
		(end 154.788108 -200.324212)
		(width 0.4064)
		(layer "B.Cu")
		(net "PVDD18_S5_P1")
	)
	(segment
		(start 59.454796 -317.171324)
		(end 58.82005 -317.171324)
		(width 0.508)
		(layer "B.Cu")
		(net "PVDD18_S5_P1")
	)
	(segment
		(start 94.08795 -302.823118)
		(end 94.070424 -302.805592)
		(width 0.508)
		(layer "B.Cu")
		(net "PVDD18_S5_P1")
	)
	(segment
		(start 24.36495 -363.50575)
		(end 24.8412 -363.982)
		(width 0.381)
		(layer "B.Cu")
		(net "PVDD18_S5_P1")
	)
	(segment
		(start 96.442784 -307.28412)
		(end 96.882712 -307.724048)
		(width 0.508)
		(layer "B.Cu")
		(net "PVDD18_S5_P1")
	)
	(segment
		(start 68.547234 -202.343004)
		(end 68.547234 -201.946002)
		(width 0.381)
		(layer "B.Cu")
		(net "PVDD18_S5_P1")
	)
	(segment
		(start 156.554424 -323.798692)
		(end 156.554424 -324.781672)
		(width 0.381)
		(layer "B.Cu")
		(net "PVDD18_S5_P1")
	)
	(segment
		(start 93.7387 -303.748948)
		(end 93.454474 -304.033174)
		(width 0.508)
		(layer "B.Cu")
		(net "PVDD18_S5_P1")
	)
	(segment
		(start 150.259034 -202.377802)
		(end 150.259034 -202.607672)
		(width 0.508)
		(layer "B.Cu")
		(net "PVDD18_S5_P1")
	)
	(segment
		(start 149.243034 -204.105002)
		(end 149.243034 -204.796898)
		(width 0.3556)
		(layer "B.Cu")
		(net "PVDD18_S5_P1")
	)
	(segment
		(start 152.519634 -203.33081)
		(end 152.485598 -203.364846)
		(width 0.508)
		(layer "B.Cu")
		(net "PVDD18_S5_P1")
	)
	(segment
		(start 90.682826 -144.958308)
		(end 90.609928 -144.88541)
		(width 0.254)
		(layer "B.Cu")
		(net "PVDD18_S5_P1")
	)
	(segment
		(start 150.259034 -202.607672)
		(end 151.534114 -203.882752)
		(width 0.508)
		(layer "B.Cu")
		(net "PVDD18_S5_P1")
	)
	(segment
		(start 167.285162 -348.000066)
		(end 168.099994 -348.000066)
		(width 0.381)
		(layer "B.Cu")
		(net "PVDD18_S5_P1")
	)
	(segment
		(start 146.220434 -204.079602)
		(end 146.220434 -204.416152)
		(width 0.508)
		(layer "B.Cu")
		(net "PVDD18_S5_P1")
	)
	(segment
		(start 183.007 -138.737594)
		(end 181.731412 -140.013182)
		(width 0.508)
		(layer "B.Cu")
		(net "PVDD18_S5_P1")
	)
	(segment
		(start 71.488046 -204.41285)
		(end 71.488046 -205.640686)
		(width 0.381)
		(layer "B.Cu")
		(net "PVDD18_S5_P1")
	)
	(segment
		(start 68.867782 -202.663552)
		(end 68.7959 -202.59167)
		(width 0.381)
		(layer "B.Cu")
		(net "PVDD18_S5_P1")
	)
	(segment
		(start 94.060264 -305.986942)
		(end 94.017846 -306.02936)
		(width 0.381)
		(layer "B.Cu")
		(net "PVDD18_S5_P1")
	)
	(segment
		(start 211.055458 -318.999362)
		(end 209.408776 -317.35268)
		(width 0.508)
		(layer "B.Cu")
		(net "PVDD18_S5_P1")
	)
	(segment
		(start 145.322544 -313.45505)
		(end 145.322544 -312.918856)
		(width 0.381)
		(layer "B.Cu")
		(net "PVDD18_S5_P1")
	)
	(segment
		(start 246.638064 -79.24673)
		(end 245.334536 -80.550258)
		(width 0.508)
		(layer "In2.Cu")
		(net "PVDD18_S5_P1")
	)
	(segment
		(start 129.858008 -121.901966)
		(end 129.858008 -107.149646)
		(width 0.508)
		(layer "In2.Cu")
		(net "PVDD18_S5_P1")
	)
	(segment
		(start 240.275364 -89.04605)
		(end 217.1827 -89.04605)
		(width 0.508)
		(layer "In2.Cu")
		(net "PVDD18_S5_P1")
	)
	(segment
		(start 129.858008 -107.149646)
		(end 134.446518 -102.561136)
		(width 0.508)
		(layer "In2.Cu")
		(net "PVDD18_S5_P1")
	)
	(segment
		(start 131.498594 -85.801454)
		(end 130.942842 -85.245702)
		(width 0.508)
		(layer "In2.Cu")
		(net "PVDD18_S5_P1")
	)
	(segment
		(start 157.165294 -321.814952)
		(end 157.165294 -320.71691)
		(width 0.508)
		(layer "In2.Cu")
		(net "PVDD18_S5_P1")
	)
	(segment
		(start 198.742046 -84.921598)
		(end 196.643498 -87.020146)
		(width 0.508)
		(layer "In2.Cu")
		(net "PVDD18_S5_P1")
	)
	(segment
		(start 196.643498 -87.020146)
		(end 194.96659 -87.020146)
		(width 0.508)
		(layer "In2.Cu")
		(net "PVDD18_S5_P1")
	)
	(segment
		(start 193.22542 -85.278976)
		(end 183.11241 -85.278976)
		(width 0.508)
		(layer "In2.Cu")
		(net "PVDD18_S5_P1")
	)
	(segment
		(start 157.68701 -334.131666)
		(end 157.68701 -348.207584)
		(width 0.508)
		(layer "In2.Cu")
		(net "PVDD18_S5_P1")
	)
	(segment
		(start 157.68701 -348.207584)
		(end 156.623766 -349.270828)
		(width 0.508)
		(layer "In2.Cu")
		(net "PVDD18_S5_P1")
	)
	(segment
		(start 206.889858 -319.871598)
		(end 209.408776 -317.35268)
		(width 0.508)
		(layer "In2.Cu")
		(net "PVDD18_S5_P1")
	)
	(segment
		(start 276.881844 -94.017084)
		(end 262.11149 -79.24673)
		(width 0.508)
		(layer "In2.Cu")
		(net "PVDD18_S5_P1")
	)
	(segment
		(start 194.96659 -87.020146)
		(end 193.22542 -85.278976)
		(width 0.508)
		(layer "In2.Cu")
		(net "PVDD18_S5_P1")
	)
	(segment
		(start 217.1827 -89.04605)
		(end 214.083138 -85.946488)
		(width 0.508)
		(layer "In2.Cu")
		(net "PVDD18_S5_P1")
	)
	(segment
		(start 214.083138 -85.946488)
		(end 209.024474 -85.946488)
		(width 0.508)
		(layer "In2.Cu")
		(net "PVDD18_S5_P1")
	)
	(segment
		(start 115.245642 -132.43814)
		(end 115.635532 -132.04825)
		(width 0.508)
		(layer "In2.Cu")
		(net "PVDD18_S5_P1")
	)
	(segment
		(start 152.982422 -321.710304)
		(end 153.865834 -320.826892)
		(width 0.508)
		(layer "In2.Cu")
		(net "PVDD18_S5_P1")
	)
	(segment
		(start 183.11241 -85.278976)
		(end 181.949598 -84.116164)
		(width 0.508)
		(layer "In2.Cu")
		(net "PVDD18_S5_P1")
	)
	(segment
		(start 207.999584 -84.921598)
		(end 198.742046 -84.921598)
		(width 0.508)
		(layer "In2.Cu")
		(net "PVDD18_S5_P1")
	)
	(segment
		(start 160.62325 -84.116164)
		(end 158.93796 -85.801454)
		(width 0.508)
		(layer "In2.Cu")
		(net "PVDD18_S5_P1")
	)
	(segment
		(start 245.334536 -83.986878)
		(end 240.275364 -89.04605)
		(width 0.508)
		(layer "In2.Cu")
		(net "PVDD18_S5_P1")
	)
	(segment
		(start 144.97685 -320.804032)
		(end 147.938998 -323.76618)
		(width 0.508)
		(layer "In2.Cu")
		(net "PVDD18_S5_P1")
	)
	(segment
		(start 157.165294 -324.781672)
		(end 158.969202 -326.58558)
		(width 0.508)
		(layer "In2.Cu")
		(net "PVDD18_S5_P1")
	)
	(segment
		(start 115.635532 -132.04825)
		(end 119.711724 -132.04825)
		(width 0.508)
		(layer "In2.Cu")
		(net "PVDD18_S5_P1")
	)
	(segment
		(start 158.010606 -319.871598)
		(end 206.889858 -319.871598)
		(width 0.508)
		(layer "In2.Cu")
		(net "PVDD18_S5_P1")
	)
	(segment
		(start 157.165294 -320.71691)
		(end 158.010606 -319.871598)
		(width 0.508)
		(layer "In2.Cu")
		(net "PVDD18_S5_P1")
	)
	(segment
		(start 245.334536 -80.550258)
		(end 245.334536 -83.986878)
		(width 0.508)
		(layer "In2.Cu")
		(net "PVDD18_S5_P1")
	)
	(segment
		(start 181.949598 -84.116164)
		(end 160.62325 -84.116164)
		(width 0.508)
		(layer "In2.Cu")
		(net "PVDD18_S5_P1")
	)
	(segment
		(start 147.938998 -323.76618)
		(end 152.164796 -323.76618)
		(width 0.508)
		(layer "In2.Cu")
		(net "PVDD18_S5_P1")
	)
	(segment
		(start 152.982422 -322.948554)
		(end 152.982422 -321.710304)
		(width 0.508)
		(layer "In2.Cu")
		(net "PVDD18_S5_P1")
	)
	(segment
		(start 262.11149 -79.24673)
		(end 246.638064 -79.24673)
		(width 0.508)
		(layer "In2.Cu")
		(net "PVDD18_S5_P1")
	)
	(segment
		(start 276.881844 -94.085918)
		(end 276.881844 -94.017084)
		(width 0.508)
		(layer "In2.Cu")
		(net "PVDD18_S5_P1")
	)
	(segment
		(start 158.93796 -85.801454)
		(end 131.498594 -85.801454)
		(width 0.508)
		(layer "In2.Cu")
		(net "PVDD18_S5_P1")
	)
	(segment
		(start 158.969202 -326.58558)
		(end 158.969202 -332.849474)
		(width 0.508)
		(layer "In2.Cu")
		(net "PVDD18_S5_P1")
	)
	(segment
		(start 119.711724 -132.04825)
		(end 129.858008 -121.901966)
		(width 0.508)
		(layer "In2.Cu")
		(net "PVDD18_S5_P1")
	)
	(segment
		(start 115.245642 -133.745732)
		(end 115.245642 -132.43814)
		(width 0.508)
		(layer "In2.Cu")
		(net "PVDD18_S5_P1")
	)
	(segment
		(start 209.024474 -85.946488)
		(end 207.999584 -84.921598)
		(width 0.508)
		(layer "In2.Cu")
		(net "PVDD18_S5_P1")
	)
	(segment
		(start 152.164796 -323.76618)
		(end 152.982422 -322.948554)
		(width 0.508)
		(layer "In2.Cu")
		(net "PVDD18_S5_P1")
	)
	(segment
		(start 158.969202 -332.849474)
		(end 157.68701 -334.131666)
		(width 0.508)
		(layer "In2.Cu")
		(net "PVDD18_S5_P1")
	)
	(segment
		(start 234.115864 -329.926696)
		(end 233.558588 -330.483972)
		(width 0.508)
		(layer "In4.Cu")
		(net "PVDD18_S5_P1")
	)
	(segment
		(start 220.038676 -321.098418)
		(end 220.038676 -318.999362)
		(width 0.508)
		(layer "In4.Cu")
		(net "PVDD18_S5_P1")
	)
	(segment
		(start 229.42423 -330.483972)
		(end 220.038676 -321.098418)
		(width 0.508)
		(layer "In4.Cu")
		(net "PVDD18_S5_P1")
	)
	(segment
		(start 236.786674 -329.926696)
		(end 234.115864 -329.926696)
		(width 0.508)
		(layer "In4.Cu")
		(net "PVDD18_S5_P1")
	)
	(segment
		(start 9.837928 -327.52919)
		(end 14.667738 -322.69938)
		(width 0.508)
		(layer "In4.Cu")
		(net "PVDD18_S5_P1")
	)
	(segment
		(start 238.997998 -328.724514)
		(end 237.988856 -328.724514)
		(width 0.508)
		(layer "In4.Cu")
		(net "PVDD18_S5_P1")
	)
	(segment
		(start 130.942842 -85.245702)
		(end 130.942842 -99.05746)
		(width 0.4572)
		(layer "In4.Cu")
		(net "PVDD18_S5_P1")
	)
	(segment
		(start 8.89254 -327.52919)
		(end 9.837928 -327.52919)
		(width 0.508)
		(layer "In4.Cu")
		(net "PVDD18_S5_P1")
	)
	(segment
		(start 233.558588 -330.483972)
		(end 229.42423 -330.483972)
		(width 0.508)
		(layer "In4.Cu")
		(net "PVDD18_S5_P1")
	)
	(segment
		(start 130.942842 -99.05746)
		(end 134.446518 -102.561136)
		(width 0.4572)
		(layer "In4.Cu")
		(net "PVDD18_S5_P1")
	)
	(segment
		(start 237.988856 -328.724514)
		(end 236.786674 -329.926696)
		(width 0.508)
		(layer "In4.Cu")
		(net "PVDD18_S5_P1")
	)
	(segment
		(start 116.24183 -134.74192)
		(end 115.245642 -133.745732)
		(width 0.508)
		(layer "In6.Cu")
		(net "PVDD18_S5_P1")
	)
	(segment
		(start 141.2748 -134.74192)
		(end 116.24183 -134.74192)
		(width 0.508)
		(layer "In6.Cu")
		(net "PVDD18_S5_P1")
	)
	(segment
		(start 174.66183 -151.827484)
		(end 172.511466 -149.67712)
		(width 0.508)
		(layer "In6.Cu")
		(net "PVDD18_S5_P1")
	)
	(segment
		(start 157.47619 -348.418404)
		(end 156.623766 -349.270828)
		(width 0.508)
		(layer "In6.Cu")
		(net "PVDD18_S5_P1")
	)
	(segment
		(start 178.22799 -151.827484)
		(end 174.66183 -151.827484)
		(width 0.508)
		(layer "In6.Cu")
		(net "PVDD18_S5_P1")
	)
	(segment
		(start 169.525696 -348.000574)
		(end 169.885106 -347.641164)
		(width 0.508)
		(layer "In6.Cu")
		(net "PVDD18_S5_P1")
	)
	(segment
		(start 164.048694 -152.23744)
		(end 158.77032 -152.23744)
		(width 0.508)
		(layer "In6.Cu")
		(net "PVDD18_S5_P1")
	)
	(segment
		(start 131.320286 -217.549476)
		(end 131.320286 -214.916766)
		(width 0.508)
		(layer "In6.Cu")
		(net "PVDD18_S5_P1")
	)
	(segment
		(start 157.47619 -342.678258)
		(end 157.47619 -348.418404)
		(width 0.508)
		(layer "In6.Cu")
		(net "PVDD18_S5_P1")
	)
	(segment
		(start 131.320286 -214.916766)
		(end 136.777984 -209.459068)
		(width 0.508)
		(layer "In6.Cu")
		(net "PVDD18_S5_P1")
	)
	(segment
		(start 172.511466 -149.67712)
		(end 166.609014 -149.67712)
		(width 0.508)
		(layer "In6.Cu")
		(net "PVDD18_S5_P1")
	)
	(segment
		(start 169.885106 -347.641164)
		(end 169.885106 -343.962736)
		(width 0.508)
		(layer "In6.Cu")
		(net "PVDD18_S5_P1")
	)
	(segment
		(start 169.885106 -343.962736)
		(end 167.718232 -341.795862)
		(width 0.508)
		(layer "In6.Cu")
		(net "PVDD18_S5_P1")
	)
	(segment
		(start 181.374542 -154.974036)
		(end 178.22799 -151.827484)
		(width 0.508)
		(layer "In6.Cu")
		(net "PVDD18_S5_P1")
	)
	(segment
		(start 158.358586 -341.795862)
		(end 157.47619 -342.678258)
		(width 0.508)
		(layer "In6.Cu")
		(net "PVDD18_S5_P1")
	)
	(segment
		(start 136.777984 -209.459068)
		(end 146.291554 -209.459068)
		(width 0.508)
		(layer "In6.Cu")
		(net "PVDD18_S5_P1")
	)
	(segment
		(start 167.718232 -341.795862)
		(end 158.358586 -341.795862)
		(width 0.508)
		(layer "In6.Cu")
		(net "PVDD18_S5_P1")
	)
	(segment
		(start 168.100502 -348.000574)
		(end 169.525696 -348.000574)
		(width 0.508)
		(layer "In6.Cu")
		(net "PVDD18_S5_P1")
	)
	(segment
		(start 166.609014 -149.67712)
		(end 164.048694 -152.23744)
		(width 0.508)
		(layer "In6.Cu")
		(net "PVDD18_S5_P1")
	)
	(segment
		(start 158.77032 -152.23744)
		(end 141.2748 -134.74192)
		(width 0.508)
		(layer "In6.Cu")
		(net "PVDD18_S5_P1")
	)
	(segment
		(start 146.291554 -209.459068)
		(end 149.479 -206.271622)
		(width 0.508)
		(layer "In6.Cu")
		(net "PVDD18_S5_P1")
	)
	(segment
		(start 181.943502 -154.974036)
		(end 181.374542 -154.974036)
		(width 0.508)
		(layer "In6.Cu")
		(net "PVDD18_S5_P1")
	)
	(segment
		(start 102.831392 -145.300446)
		(end 102.458774 -145.673064)
		(width 0.508)
		(layer "In11.Cu")
		(net "PVDD18_S5_P1")
	)
	(segment
		(start 22.452838 -358.356916)
		(end 22.065742 -357.96982)
		(width 0.508)
		(layer "In11.Cu")
		(net "PVDD18_S5_P1")
	)
	(segment
		(start 103.092504 -145.300446)
		(end 102.831392 -145.300446)
		(width 0.508)
		(layer "In11.Cu")
		(net "PVDD18_S5_P1")
	)
	(segment
		(start 114.647218 -133.745732)
		(end 103.092504 -145.300446)
		(width 0.508)
		(layer "In11.Cu")
		(net "PVDD18_S5_P1")
	)
	(segment
		(start 22.065742 -357.96982)
		(end 22.065742 -356.648004)
		(width 0.508)
		(layer "In11.Cu")
		(net "PVDD18_S5_P1")
	)
	(segment
		(start 23.156164 -363.982)
		(end 22.452838 -363.278674)
		(width 0.508)
		(layer "In11.Cu")
		(net "PVDD18_S5_P1")
	)
	(segment
		(start 115.245642 -133.745732)
		(end 114.647218 -133.745732)
		(width 0.508)
		(layer "In11.Cu")
		(net "PVDD18_S5_P1")
	)
	(segment
		(start 22.452838 -363.278674)
		(end 22.452838 -358.356916)
		(width 0.508)
		(layer "In11.Cu")
		(net "PVDD18_S5_P1")
	)
	(segment
		(start 24.8412 -363.982)
		(end 23.156164 -363.982)
		(width 0.508)
		(layer "In11.Cu")
		(net "PVDD18_S5_P1")
	)
	(segment
		(start 22.065742 -356.648004)
		(end 22.054058 -356.63632)
		(width 0.508)
		(layer "In11.Cu")
		(net "PVDD18_S5_P1")
	)
	(segment
		(start 37.428678 -364.922054)
		(end 38.058598 -365.551974)
		(width 0.508)
		(layer "In13.Cu")
		(net "PVDD18_S5_P1")
	)
	(segment
		(start 69.63283 -202.61199)
		(end 71.488046 -204.467206)
		(width 0.508)
		(layer "In13.Cu")
		(net "PVDD18_S5_P1")
	)
	(segment
		(start 102.458774 -146.5072)
		(end 101.551994 -147.41398)
		(width 0.508)
		(layer "In13.Cu")
		(net "PVDD18_S5_P1")
	)
	(segment
		(start 85.976968 -144.528032)
		(end 88.016334 -144.528032)
		(width 0.508)
		(layer "In13.Cu")
		(net "PVDD18_S5_P1")
	)
	(segment
		(start 146.230086 -319.289684)
		(end 146.738086 -319.797684)
		(width 0.508)
		(layer "In13.Cu")
		(net "PVDD18_S5_P1")
	)
	(segment
		(start 157.165294 -324.781672)
		(end 157.165294 -321.814952)
		(width 0.508)
		(layer "In13.Cu")
		(net "PVDD18_S5_P1")
	)
	(segment
		(start 60.259214 -190.081154)
		(end 66.286634 -196.108574)
		(width 0.508)
		(layer "In13.Cu")
		(net "PVDD18_S5_P1")
	)
	(segment
		(start 153.784554 -324.688708)
		(end 154.081226 -324.688708)
		(width 0.508)
		(layer "In13.Cu")
		(net "PVDD18_S5_P1")
	)
	(segment
		(start 68.81622 -202.61199)
		(end 69.63283 -202.61199)
		(width 0.508)
		(layer "In13.Cu")
		(net "PVDD18_S5_P1")
	)
	(segment
		(start 88.016334 -144.528032)
		(end 88.236044 -144.308322)
		(width 0.508)
		(layer "In13.Cu")
		(net "PVDD18_S5_P1")
	)
	(segment
		(start 89.121742 -144.07388)
		(end 89.193878 -144.001744)
		(width 0.4572)
		(layer "In13.Cu")
		(net "PVDD18_S5_P1")
	)
	(segment
		(start 52.560982 -187.268358)
		(end 52.560982 -188.94552)
		(width 0.508)
		(layer "In13.Cu")
		(net "PVDD18_S5_P1")
	)
	(segment
		(start 66.286634 -196.108574)
		(end 66.286634 -197.608952)
		(width 0.508)
		(layer "In13.Cu")
		(net "PVDD18_S5_P1")
	)
	(segment
		(start 89.193878 -144.001744)
		(end 89.425526 -144.001744)
		(width 0.508)
		(layer "In13.Cu")
		(net "PVDD18_S5_P1")
	)
	(segment
		(start 88.470486 -144.07388)
		(end 89.121742 -144.07388)
		(width 0.4572)
		(layer "In13.Cu")
		(net "PVDD18_S5_P1")
	)
	(segment
		(start 145.7706 -316.1792)
		(end 146.230086 -316.638686)
		(width 0.508)
		(layer "In13.Cu")
		(net "PVDD18_S5_P1")
	)
	(segment
		(start 101.551994 -147.41398)
		(end 93.02877 -147.41398)
		(width 0.508)
		(layer "In13.Cu")
		(net "PVDD18_S5_P1")
	)
	(segment
		(start 153.792428 -320.753486)
		(end 153.09215 -320.753486)
		(width 0.508)
		(layer "In13.Cu")
		(net "PVDD18_S5_P1")
	)
	(segment
		(start 145.8468 -312.3946)
		(end 145.7706 -312.4708)
		(width 0.508)
		(layer "In13.Cu")
		(net "PVDD18_S5_P1")
	)
	(segment
		(start 66.286634 -200.082404)
		(end 68.7959 -202.59167)
		(width 0.508)
		(layer "In13.Cu")
		(net "PVDD18_S5_P1")
	)
	(segment
		(start 102.458774 -145.673064)
		(end 102.458774 -146.5072)
		(width 0.508)
		(layer "In13.Cu")
		(net "PVDD18_S5_P1")
	)
	(segment
		(start 80.99298 -155.681934)
		(end 80.99298 -149.51202)
		(width 0.508)
		(layer "In13.Cu")
		(net "PVDD18_S5_P1")
	)
	(segment
		(start 24.8412 -366.574578)
		(end 24.8412 -363.982)
		(width 0.508)
		(layer "In13.Cu")
		(net "PVDD18_S5_P1")
	)
	(segment
		(start 66.286634 -197.608952)
		(end 66.286634 -200.082404)
		(width 0.508)
		(layer "In13.Cu")
		(net "PVDD18_S5_P1")
	)
	(segment
		(start 71.488046 -204.467206)
		(end 71.488046 -205.640686)
		(width 0.508)
		(layer "In13.Cu")
		(net "PVDD18_S5_P1")
	)
	(segment
		(start 152.922478 -320.923158)
		(end 152.922478 -323.826632)
		(width 0.508)
		(layer "In13.Cu")
		(net "PVDD18_S5_P1")
	)
	(segment
		(start 52.560982 -188.94552)
		(end 53.696616 -190.081154)
		(width 0.508)
		(layer "In13.Cu")
		(net "PVDD18_S5_P1")
	)
	(segment
		(start 146.738086 -319.797684)
		(end 150.010876 -319.797684)
		(width 0.508)
		(layer "In13.Cu")
		(net "PVDD18_S5_P1")
	)
	(segment
		(start 31.134812 -367.248186)
		(end 25.514808 -367.248186)
		(width 0.508)
		(layer "In13.Cu")
		(net "PVDD18_S5_P1")
	)
	(segment
		(start 92.565474 -146.950684)
		(end 92.565474 -145.515584)
		(width 0.508)
		(layer "In13.Cu")
		(net "PVDD18_S5_P1")
	)
	(segment
		(start 154.081226 -324.688708)
		(end 154.123644 -324.688708)
		(width 0.508)
		(layer "In13.Cu")
		(net "PVDD18_S5_P1")
	)
	(segment
		(start 89.425526 -144.001744)
		(end 90.508074 -145.084292)
		(width 0.508)
		(layer "In13.Cu")
		(net "PVDD18_S5_P1")
	)
	(segment
		(start 152.922478 -323.826632)
		(end 153.784554 -324.688708)
		(width 0.508)
		(layer "In13.Cu")
		(net "PVDD18_S5_P1")
	)
	(segment
		(start 88.236044 -144.308322)
		(end 88.470486 -144.07388)
		(width 0.4572)
		(layer "In13.Cu")
		(net "PVDD18_S5_P1")
	)
	(segment
		(start 151.265128 -320.717672)
		(end 151.271986 -320.717672)
		(width 0.508)
		(layer "In13.Cu")
		(net "PVDD18_S5_P1")
	)
	(segment
		(start 36.460684 -368.627406)
		(end 32.514032 -368.627406)
		(width 0.508)
		(layer "In13.Cu")
		(net "PVDD18_S5_P1")
	)
	(segment
		(start 25.514808 -367.248186)
		(end 24.8412 -366.574578)
		(width 0.508)
		(layer "In13.Cu")
		(net "PVDD18_S5_P1")
	)
	(segment
		(start 80.99298 -149.51202)
		(end 85.976968 -144.528032)
		(width 0.508)
		(layer "In13.Cu")
		(net "PVDD18_S5_P1")
	)
	(segment
		(start 91.226894 -145.084292)
		(end 91.352878 -144.958308)
		(width 0.508)
		(layer "In13.Cu")
		(net "PVDD18_S5_P1")
	)
	(segment
		(start 145.7706 -312.4708)
		(end 145.7706 -316.1792)
		(width 0.508)
		(layer "In13.Cu")
		(net "PVDD18_S5_P1")
	)
	(segment
		(start 37.428678 -362.41736)
		(end 37.428678 -364.922054)
		(width 0.508)
		(layer "In13.Cu")
		(net "PVDD18_S5_P1")
	)
	(segment
		(start 32.514032 -368.627406)
		(end 31.134812 -367.248186)
		(width 0.508)
		(layer "In13.Cu")
		(net "PVDD18_S5_P1")
	)
	(segment
		(start 92.008198 -144.958308)
		(end 91.352878 -144.958308)
		(width 0.508)
		(layer "In13.Cu")
		(net "PVDD18_S5_P1")
	)
	(segment
		(start 150.010876 -319.797684)
		(end 150.847298 -320.634106)
		(width 0.508)
		(layer "In13.Cu")
		(net "PVDD18_S5_P1")
	)
	(segment
		(start 155.972002 -324.688708)
		(end 157.07233 -324.688708)
		(width 0.508)
		(layer "In13.Cu")
		(net "PVDD18_S5_P1")
	)
	(segment
		(start 146.230086 -316.638686)
		(end 146.230086 -319.289684)
		(width 0.508)
		(layer "In13.Cu")
		(net "PVDD18_S5_P1")
	)
	(segment
		(start 38.3286 -362.077)
		(end 37.769038 -362.077)
		(width 0.508)
		(layer "In13.Cu")
		(net "PVDD18_S5_P1")
	)
	(segment
		(start 151.5999 -320.389758)
		(end 152.728422 -320.389758)
		(width 0.508)
		(layer "In13.Cu")
		(net "PVDD18_S5_P1")
	)
	(segment
		(start 37.769038 -362.077)
		(end 37.428678 -362.41736)
		(width 0.508)
		(layer "In13.Cu")
		(net "PVDD18_S5_P1")
	)
	(segment
		(start 150.847298 -320.634106)
		(end 151.181562 -320.634106)
		(width 0.508)
		(layer "In13.Cu")
		(net "PVDD18_S5_P1")
	)
	(segment
		(start 154.123644 -324.688708)
		(end 154.483054 -325.048118)
		(width 0.508)
		(layer "In13.Cu")
		(net "PVDD18_S5_P1")
	)
	(segment
		(start 57.664096 -158.08579)
		(end 78.589124 -158.08579)
		(width 0.508)
		(layer "In13.Cu")
		(net "PVDD18_S5_P1")
	)
	(segment
		(start 152.728422 -320.389758)
		(end 153.09215 -320.753486)
		(width 0.508)
		(layer "In13.Cu")
		(net "PVDD18_S5_P1")
	)
	(segment
		(start 151.271986 -320.717672)
		(end 151.5999 -320.389758)
		(width 0.508)
		(layer "In13.Cu")
		(net "PVDD18_S5_P1")
	)
	(segment
		(start 38.058598 -365.551974)
		(end 38.058598 -367.029492)
		(width 0.508)
		(layer "In13.Cu")
		(net "PVDD18_S5_P1")
	)
	(segment
		(start 92.565474 -145.515584)
		(end 92.008198 -144.958308)
		(width 0.508)
		(layer "In13.Cu")
		(net "PVDD18_S5_P1")
	)
	(segment
		(start 68.7959 -202.59167)
		(end 68.81622 -202.61199)
		(width 0.508)
		(layer "In13.Cu")
		(net "PVDD18_S5_P1")
	)
	(segment
		(start 93.02877 -147.41398)
		(end 92.565474 -146.950684)
		(width 0.508)
		(layer "In13.Cu")
		(net "PVDD18_S5_P1")
	)
	(segment
		(start 53.696616 -190.081154)
		(end 60.259214 -190.081154)
		(width 0.508)
		(layer "In13.Cu")
		(net "PVDD18_S5_P1")
	)
	(segment
		(start 154.483054 -325.048118)
		(end 155.612592 -325.048118)
		(width 0.508)
		(layer "In13.Cu")
		(net "PVDD18_S5_P1")
	)
	(segment
		(start 151.181562 -320.634106)
		(end 151.265128 -320.717672)
		(width 0.508)
		(layer "In13.Cu")
		(net "PVDD18_S5_P1")
	)
	(segment
		(start 153.09215 -320.753486)
		(end 152.922478 -320.923158)
		(width 0.508)
		(layer "In13.Cu")
		(net "PVDD18_S5_P1")
	)
	(segment
		(start 153.865834 -320.826892)
		(end 153.792428 -320.753486)
		(width 0.508)
		(layer "In13.Cu")
		(net "PVDD18_S5_P1")
	)
	(segment
		(start 90.508074 -145.084292)
		(end 91.226894 -145.084292)
		(width 0.508)
		(layer "In13.Cu")
		(net "PVDD18_S5_P1")
	)
	(segment
		(start 157.07233 -324.688708)
		(end 157.165294 -324.781672)
		(width 0.508)
		(layer "In13.Cu")
		(net "PVDD18_S5_P1")
	)
	(segment
		(start 155.612592 -325.048118)
		(end 155.972002 -324.688708)
		(width 0.508)
		(layer "In13.Cu")
		(net "PVDD18_S5_P1")
	)
	(segment
		(start 78.589124 -158.08579)
		(end 80.99298 -155.681934)
		(width 0.508)
		(layer "In13.Cu")
		(net "PVDD18_S5_P1")
	)
	(segment
		(start 38.058598 -367.029492)
		(end 36.460684 -368.627406)
		(width 0.508)
		(layer "In13.Cu")
		(net "PVDD18_S5_P1")
	)
	(segment
		(start 337.71459 -142.698724)
		(end 338.410296 -142.698724)
		(width 0.381)
		(layer "F.Cu")
		(net "PVDD18_S5_P0_VCC")
	)
	(segment
		(start 336.91449 -142.570708)
		(end 337.586574 -142.570708)
		(width 0.254)
		(layer "F.Cu")
		(net "PVDD18_S5_P0_VCC")
	)
	(segment
		(start 338.410296 -142.698724)
		(end 338.41944 -142.68958)
		(width 0.381)
		(layer "F.Cu")
		(net "PVDD18_S5_P0_VCC")
	)
	(segment
		(start 337.586574 -142.570708)
		(end 337.71459 -142.698724)
		(width 0.254)
		(layer "F.Cu")
		(net "PVDD18_S5_P0_VCC")
	)
	(via
		(at 337.71459 -142.698724)
		(size 0.508)
		(drill 0.254)
		(layers "F.Cu" "B.Cu")
		(net "PVDD18_S5_P0_VCC")
	)
	(segment
		(start 336.566764 -142.751302)
		(end 337.662012 -142.751302)
		(width 0.381)
		(layer "B.Cu")
		(net "PVDD18_S5_P0_VCC")
	)
	(segment
		(start 333.742538 -139.927076)
		(end 336.566764 -142.751302)
		(width 0.381)
		(layer "B.Cu")
		(net "PVDD18_S5_P0_VCC")
	)
	(segment
		(start 337.662012 -142.751302)
		(end 337.71459 -142.698724)
		(width 0.381)
		(layer "B.Cu")
		(net "PVDD18_S5_P0_VCC")
	)
	(segment
		(start 332.039214 -136.474962)
		(end 333.742538 -138.178286)
		(width 0.381)
		(layer "B.Cu")
		(net "PVDD18_S5_P0_VCC")
	)
	(segment
		(start 333.742538 -138.178286)
		(end 333.742538 -139.927076)
		(width 0.381)
		(layer "B.Cu")
		(net "PVDD18_S5_P0_VCC")
	)
	(segment
		(start 331.135736 -139.290552)
		(end 330.584556 -139.843002)
		(width 0.254)
		(layer "F.Cu")
		(net "PVDD18_S5_P0_RGND")
	)
	(segment
		(start 332.070964 -139.608052)
		(end 331.753464 -139.290552)
		(width 0.254)
		(layer "F.Cu")
		(net "PVDD18_S5_P0_RGND")
	)
	(segment
		(start 333.489808 -140.470636)
		(end 332.627224 -139.608052)
		(width 0.1778)
		(layer "F.Cu")
		(net "PVDD18_S5_P0_RGND")
	)
	(segment
		(start 329.67041 -139.843002)
		(end 329.268074 -140.245338)
		(width 0.254)
		(layer "F.Cu")
		(net "PVDD18_S5_P0_RGND")
	)
	(segment
		(start 329.223624 -141.191742)
		(end 328.548492 -141.191742)
		(width 0.254)
		(layer "F.Cu")
		(net "PVDD18_S5_P0_RGND")
	)
	(segment
		(start 331.156818 -139.290552)
		(end 331.135736 -139.290552)
		(width 0.254)
		(layer "F.Cu")
		(net "PVDD18_S5_P0_RGND")
	)
	(segment
		(start 327.35393 -150.876762)
		(end 327.819258 -150.876762)
		(width 0.254)
		(layer "F.Cu")
		(net "PVDD18_S5_P0_RGND")
	)
	(segment
		(start 327.819258 -150.876762)
		(end 328.106786 -150.589234)
		(width 0.254)
		(layer "F.Cu")
		(net "PVDD18_S5_P0_RGND")
	)
	(segment
		(start 328.09053 -144.154144)
		(end 328.09053 -147.4216)
		(width 0.254)
		(layer "F.Cu")
		(net "PVDD18_S5_P0_RGND")
	)
	(segment
		(start 327.0504 -148.46173)
		(end 327.0504 -150.573232)
		(width 0.254)
		(layer "F.Cu")
		(net "PVDD18_S5_P0_RGND")
	)
	(segment
		(start 334.114394 -140.470636)
		(end 333.489808 -140.470636)
		(width 0.1778)
		(layer "F.Cu")
		(net "PVDD18_S5_P0_RGND")
	)
	(segment
		(start 330.584556 -139.843002)
		(end 329.67041 -139.843002)
		(width 0.254)
		(layer "F.Cu")
		(net "PVDD18_S5_P0_RGND")
	)
	(segment
		(start 331.753464 -139.290552)
		(end 331.156818 -139.290552)
		(width 0.254)
		(layer "F.Cu")
		(net "PVDD18_S5_P0_RGND")
	)
	(segment
		(start 328.09053 -147.4216)
		(end 327.0504 -148.46173)
		(width 0.254)
		(layer "F.Cu")
		(net "PVDD18_S5_P0_RGND")
	)
	(segment
		(start 328.548492 -141.191742)
		(end 328.09053 -141.649704)
		(width 0.254)
		(layer "F.Cu")
		(net "PVDD18_S5_P0_RGND")
	)
	(segment
		(start 329.268074 -140.245338)
		(end 329.268074 -141.147292)
		(width 0.254)
		(layer "F.Cu")
		(net "PVDD18_S5_P0_RGND")
	)
	(segment
		(start 329.268074 -141.147292)
		(end 329.223624 -141.191742)
		(width 0.254)
		(layer "F.Cu")
		(net "PVDD18_S5_P0_RGND")
	)
	(segment
		(start 328.09053 -141.649704)
		(end 328.09053 -144.154144)
		(width 0.254)
		(layer "F.Cu")
		(net "PVDD18_S5_P0_RGND")
	)
	(segment
		(start 327.0504 -150.573232)
		(end 327.35393 -150.876762)
		(width 0.254)
		(layer "F.Cu")
		(net "PVDD18_S5_P0_RGND")
	)
	(segment
		(start 332.627224 -139.608052)
		(end 332.070964 -139.608052)
		(width 0.1778)
		(layer "F.Cu")
		(net "PVDD18_S5_P0_RGND")
	)
	(via
		(at 328.09053 -144.154144)
		(size 0.4064)
		(drill 0.2032)
		(layers "F.Cu" "B.Cu")
		(net "PVDD18_S5_P0_RGND")
	)
	(segment
		(start 332.70698 -140.408152)
		(end 332.070964 -140.408152)
		(width 0.1778)
		(layer "F.Cu")
		(net "PVDD18_S5_P0_REF")
	)
	(segment
		(start 332.850744 -140.408152)
		(end 332.70698 -140.408152)
		(width 0.1778)
		(layer "F.Cu")
		(net "PVDD18_S5_P0_REF")
	)
	(segment
		(start 334.114394 -140.870686)
		(end 333.313278 -140.870686)
		(width 0.1778)
		(layer "F.Cu")
		(net "PVDD18_S5_P0_REF")
	)
	(segment
		(start 332.064614 -140.414502)
		(end 331.175614 -140.414502)
		(width 0.2032)
		(layer "F.Cu")
		(net "PVDD18_S5_P0_REF")
	)
	(segment
		(start 333.313278 -140.870686)
		(end 332.850744 -140.408152)
		(width 0.1778)
		(layer "F.Cu")
		(net "PVDD18_S5_P0_REF")
	)
	(segment
		(start 332.070964 -140.408152)
		(end 332.064614 -140.414502)
		(width 0.2032)
		(layer "F.Cu")
		(net "PVDD18_S5_P0_REF")
	)
	(via
		(at 332.70698 -140.408152)
		(size 0.508)
		(drill 0.254)
		(layers "F.Cu" "B.Cu")
		(net "PVDD18_S5_P0_REF")
	)
	(segment
		(start 334.114394 -141.270736)
		(end 332.8543 -141.270736)
		(width 0.1778)
		(layer "F.Cu")
		(net "PVDD18_S5_P0_MODE")
	)
	(segment
		(start 332.8543 -141.270736)
		(end 332.154276 -141.270736)
		(width 0.1778)
		(layer "F.Cu")
		(net "PVDD18_S5_P0_MODE")
	)
	(segment
		(start 332.154276 -141.270736)
		(end 332.062582 -141.36243)
		(width 0.1778)
		(layer "F.Cu")
		(net "PVDD18_S5_P0_MODE")
	)
	(via
		(at 332.8543 -141.270736)
		(size 0.4064)
		(drill 0.2032)
		(layers "F.Cu" "B.Cu")
		(net "PVDD18_S5_P0_MODE")
	)
	(segment
		(start 327.551796 -141.430248)
		(end 327.551796 -141.917928)
		(width 0.254)
		(layer "F.Cu")
		(net "PVDD18_S5_P0_FB_RC")
	)
	(segment
		(start 326.511666 -148.214334)
		(end 326.511666 -150.796498)
		(width 0.254)
		(layer "F.Cu")
		(net "PVDD18_S5_P0_FB_RC")
	)
	(segment
		(start 328.367644 -140.145008)
		(end 328.467974 -140.245338)
		(width 0.254)
		(layer "F.Cu")
		(net "PVDD18_S5_P0_FB_RC")
	)
	(segment
		(start 327.863454 -151.389842)
		(end 328.114914 -151.641302)
		(width 0.254)
		(layer "F.Cu")
		(net "PVDD18_S5_P0_FB_RC")
	)
	(segment
		(start 328.367644 -139.293092)
		(end 328.367644 -140.145008)
		(width 0.254)
		(layer "F.Cu")
		(net "PVDD18_S5_P0_FB_RC")
	)
	(segment
		(start 327.551796 -141.917928)
		(end 327.551796 -142.959836)
		(width 0.254)
		(layer "F.Cu")
		(net "PVDD18_S5_P0_FB_RC")
	)
	(segment
		(start 327.10501 -151.389842)
		(end 327.863454 -151.389842)
		(width 0.254)
		(layer "F.Cu")
		(net "PVDD18_S5_P0_FB_RC")
	)
	(segment
		(start 330.196444 -139.293092)
		(end 329.282044 -139.293092)
		(width 0.254)
		(layer "F.Cu")
		(net "PVDD18_S5_P0_FB_RC")
	)
	(segment
		(start 328.467974 -140.51407)
		(end 327.551796 -141.430248)
		(width 0.254)
		(layer "F.Cu")
		(net "PVDD18_S5_P0_FB_RC")
	)
	(segment
		(start 326.511666 -150.796498)
		(end 327.10501 -151.389842)
		(width 0.254)
		(layer "F.Cu")
		(net "PVDD18_S5_P0_FB_RC")
	)
	(segment
		(start 327.551796 -142.959836)
		(end 327.551796 -147.174204)
		(width 0.254)
		(layer "F.Cu")
		(net "PVDD18_S5_P0_FB_RC")
	)
	(segment
		(start 329.282044 -139.293092)
		(end 328.367644 -139.293092)
		(width 0.254)
		(layer "F.Cu")
		(net "PVDD18_S5_P0_FB_RC")
	)
	(segment
		(start 327.551796 -147.174204)
		(end 326.511666 -148.214334)
		(width 0.254)
		(layer "F.Cu")
		(net "PVDD18_S5_P0_FB_RC")
	)
	(segment
		(start 328.467974 -140.245338)
		(end 328.467974 -140.51407)
		(width 0.254)
		(layer "F.Cu")
		(net "PVDD18_S5_P0_FB_RC")
	)
	(via
		(at 327.551796 -142.959836)
		(size 0.4064)
		(drill 0.2032)
		(layers "F.Cu" "B.Cu")
		(net "PVDD18_S5_P0_FB_RC")
	)
	(segment
		(start 333.521304 -140.070586)
		(end 334.114394 -140.070586)
		(width 0.1778)
		(layer "F.Cu")
		(net "PVDD18_S5_P0_FB")
	)
	(segment
		(start 331.15631 -138.490452)
		(end 331.621892 -138.490452)
		(width 0.1778)
		(layer "F.Cu")
		(net "PVDD18_S5_P0_FB")
	)
	(segment
		(start 331.621892 -138.490452)
		(end 331.9907 -138.85926)
		(width 0.1778)
		(layer "F.Cu")
		(net "PVDD18_S5_P0_FB")
	)
	(segment
		(start 331.15631 -138.490452)
		(end 331.15377 -138.492992)
		(width 0.254)
		(layer "F.Cu")
		(net "PVDD18_S5_P0_FB")
	)
	(segment
		(start 331.9907 -138.85926)
		(end 332.22184 -139.0904)
		(width 0.1778)
		(layer "F.Cu")
		(net "PVDD18_S5_P0_FB")
	)
	(segment
		(start 332.541118 -139.0904)
		(end 333.521304 -140.070586)
		(width 0.1778)
		(layer "F.Cu")
		(net "PVDD18_S5_P0_FB")
	)
	(segment
		(start 330.196444 -138.492992)
		(end 329.282044 -138.492992)
		(width 0.254)
		(layer "F.Cu")
		(net "PVDD18_S5_P0_FB")
	)
	(segment
		(start 331.15377 -138.492992)
		(end 330.196444 -138.492992)
		(width 0.254)
		(layer "F.Cu")
		(net "PVDD18_S5_P0_FB")
	)
	(segment
		(start 332.22184 -139.0904)
		(end 332.541118 -139.0904)
		(width 0.1778)
		(layer "F.Cu")
		(net "PVDD18_S5_P0_FB")
	)
	(via
		(at 331.9907 -138.85926)
		(size 0.4064)
		(drill 0.2032)
		(layers "F.Cu" "B.Cu")
		(net "PVDD18_S5_P0_FB")
	)
	(segment
		(start 290.67506 -128.3462)
		(end 321.049142 -128.3462)
		(width 0.10668)
		(layer "F.Cu")
		(net "PVDD18_S5_P0_EN")
	)
	(segment
		(start 321.049142 -128.3462)
		(end 329.047856 -136.344914)
		(width 0.10668)
		(layer "F.Cu")
		(net "PVDD18_S5_P0_EN")
	)
	(segment
		(start 331.61605 -137.575036)
		(end 330.277978 -137.575036)
		(width 0.10668)
		(layer "F.Cu")
		(net "PVDD18_S5_P0_EN")
	)
	(segment
		(start 197.669658 -110.577376)
		(end 197.725538 -110.633256)
		(width 0.10668)
		(layer "F.Cu")
		(net "PVDD18_S5_P0_EN")
	)
	(segment
		(start 334.114394 -139.67079)
		(end 333.711804 -139.67079)
		(width 0.10668)
		(layer "F.Cu")
		(net "PVDD18_S5_P0_EN")
	)
	(segment
		(start 289.881818 -127.075184)
		(end 289.881818 -127.552958)
		(width 0.10668)
		(layer "F.Cu")
		(net "PVDD18_S5_P0_EN")
	)
	(segment
		(start 197.725538 -110.633256)
		(end 198.266558 -110.633256)
		(width 0.10668)
		(layer "F.Cu")
		(net "PVDD18_S5_P0_EN")
	)
	(segment
		(start 333.711804 -139.67079)
		(end 331.61605 -137.575036)
		(width 0.10668)
		(layer "F.Cu")
		(net "PVDD18_S5_P0_EN")
	)
	(segment
		(start 289.881818 -127.552958)
		(end 290.67506 -128.3462)
		(width 0.10668)
		(layer "F.Cu")
		(net "PVDD18_S5_P0_EN")
	)
	(segment
		(start 330.277978 -137.575036)
		(end 329.047856 -136.344914)
		(width 0.10668)
		(layer "F.Cu")
		(net "PVDD18_S5_P0_EN")
	)
	(via
		(at 289.881818 -127.075184)
		(size 0.762)
		(drill 0.254)
		(layers "F.Cu" "B.Cu")
		(net "PVDD18_S5_P0_EN")
	)
	(via
		(at 198.266558 -110.633256)
		(size 0.508)
		(drill 0.254)
		(layers "F.Cu" "B.Cu")
		(net "PVDD18_S5_P0_EN")
	)
	(segment
		(start 274.213066 -124.412248)
		(end 273.088354 -123.287536)
		(width 0.11684)
		(layer "In15.Cu")
		(net "PVDD18_S5_P0_EN")
	)
	(segment
		(start 273.088354 -123.287536)
		(end 273.088354 -123.064778)
		(width 0.11684)
		(layer "In15.Cu")
		(net "PVDD18_S5_P0_EN")
	)
	(segment
		(start 249.444002 -111.828326)
		(end 215.513412 -111.828326)
		(width 0.11684)
		(layer "In15.Cu")
		(net "PVDD18_S5_P0_EN")
	)
	(segment
		(start 274.712176 -124.412248)
		(end 274.213066 -124.412248)
		(width 0.11684)
		(layer "In15.Cu")
		(net "PVDD18_S5_P0_EN")
	)
	(segment
		(start 286.647128 -123.840494)
		(end 275.28393 -123.840494)
		(width 0.11684)
		(layer "In15.Cu")
		(net "PVDD18_S5_P0_EN")
	)
	(segment
		(start 270.534892 -121.028968)
		(end 264.743438 -121.028968)
		(width 0.11684)
		(layer "In15.Cu")
		(net "PVDD18_S5_P0_EN")
	)
	(segment
		(start 272.407126 -122.38355)
		(end 271.889474 -122.38355)
		(width 0.11684)
		(layer "In15.Cu")
		(net "PVDD18_S5_P0_EN")
	)
	(segment
		(start 214.746332 -111.061246)
		(end 211.409788 -111.061246)
		(width 0.11684)
		(layer "In15.Cu")
		(net "PVDD18_S5_P0_EN")
	)
	(segment
		(start 211.409788 -111.061246)
		(end 211.39531 -111.075724)
		(width 0.11684)
		(layer "In15.Cu")
		(net "PVDD18_S5_P0_EN")
	)
	(segment
		(start 264.743438 -121.028968)
		(end 257.832098 -114.117628)
		(width 0.11684)
		(layer "In15.Cu")
		(net "PVDD18_S5_P0_EN")
	)
	(segment
		(start 275.28393 -123.840494)
		(end 274.712176 -124.412248)
		(width 0.11684)
		(layer "In15.Cu")
		(net "PVDD18_S5_P0_EN")
	)
	(segment
		(start 273.088354 -123.064778)
		(end 272.407126 -122.38355)
		(width 0.11684)
		(layer "In15.Cu")
		(net "PVDD18_S5_P0_EN")
	)
	(segment
		(start 215.513412 -111.828326)
		(end 214.746332 -111.061246)
		(width 0.11684)
		(layer "In15.Cu")
		(net "PVDD18_S5_P0_EN")
	)
	(segment
		(start 271.889474 -122.38355)
		(end 270.534892 -121.028968)
		(width 0.11684)
		(layer "In15.Cu")
		(net "PVDD18_S5_P0_EN")
	)
	(segment
		(start 257.832098 -114.117628)
		(end 251.733304 -114.117628)
		(width 0.11684)
		(layer "In15.Cu")
		(net "PVDD18_S5_P0_EN")
	)
	(segment
		(start 211.39531 -111.075724)
		(end 198.709026 -111.075724)
		(width 0.11684)
		(layer "In15.Cu")
		(net "PVDD18_S5_P0_EN")
	)
	(segment
		(start 198.709026 -111.075724)
		(end 198.266558 -110.633256)
		(width 0.11684)
		(layer "In15.Cu")
		(net "PVDD18_S5_P0_EN")
	)
	(segment
		(start 289.881818 -127.075184)
		(end 286.647128 -123.840494)
		(width 0.11684)
		(layer "In15.Cu")
		(net "PVDD18_S5_P0_EN")
	)
	(segment
		(start 251.733304 -114.117628)
		(end 249.444002 -111.828326)
		(width 0.11684)
		(layer "In15.Cu")
		(net "PVDD18_S5_P0_EN")
	)
	(segment
		(start 332.103476 -142.243302)
		(end 332.622144 -142.243302)
		(width 0.1778)
		(layer "F.Cu")
		(net "PVDD18_S5_P0_CS")
	)
	(segment
		(start 333.58328 -141.670786)
		(end 334.114394 -141.670786)
		(width 0.1778)
		(layer "F.Cu")
		(net "PVDD18_S5_P0_CS")
	)
	(segment
		(start 332.622144 -142.243302)
		(end 332.668372 -142.197074)
		(width 0.1778)
		(layer "F.Cu")
		(net "PVDD18_S5_P0_CS")
	)
	(segment
		(start 332.683104 -142.197074)
		(end 333.58328 -141.670786)
		(width 0.1778)
		(layer "F.Cu")
		(net "PVDD18_S5_P0_CS")
	)
	(segment
		(start 332.053692 -142.293086)
		(end 332.103476 -142.243302)
		(width 0.1778)
		(layer "F.Cu")
		(net "PVDD18_S5_P0_CS")
	)
	(segment
		(start 332.668372 -142.197074)
		(end 332.683104 -142.197074)
		(width 0.1778)
		(layer "F.Cu")
		(net "PVDD18_S5_P0_CS")
	)
	(via
		(at 332.683104 -142.197074)
		(size 0.508)
		(drill 0.254)
		(layers "F.Cu" "B.Cu")
		(net "PVDD18_S5_P0_CS")
	)
	(segment
		(start 374.440958 -207.485488)
		(end 374.440958 -208.262982)
		(width 0.508)
		(layer "F.Cu")
		(net "PVDD18_S5_P0")
	)
	(segment
		(start 123.327414 -55.475632)
		(end 123.327414 -56.53786)
		(width 0.1778)
		(layer "F.Cu")
		(net "PVDD18_S5_P0")
	)
	(segment
		(start 304.81905 -360.73715)
		(end 304.81905 -360.426)
		(width 0.381)
		(layer "F.Cu")
		(net "PVDD18_S5_P0")
	)
	(segment
		(start 180.824378 -154.032712)
		(end 181.619398 -154.032712)
		(width 0.508)
		(layer "F.Cu")
		(net "PVDD18_S5_P0")
	)
	(segment
		(start 292.129972 -52.53609)
		(end 292.637972 -52.02809)
		(width 0.381)
		(layer "F.Cu")
		(net "PVDD18_S5_P0")
	)
	(segment
		(start 265.87069 -104.79278)
		(end 265.87069 -103.294434)
		(width 0.381)
		(layer "F.Cu")
		(net "PVDD18_S5_P0")
	)
	(segment
		(start 369.881404 -34.243772)
		(end 369.881404 -35.010598)
		(width 0.3556)
		(layer "F.Cu")
		(net "PVDD18_S5_P0")
	)
	(segment
		(start 263.158478 -137.395966)
		(end 263.474454 -137.07999)
		(width 0.381)
		(layer "F.Cu")
		(net "PVDD18_S5_P0")
	)
	(segment
		(start 323.762878 -171.410884)
		(end 323.762878 -193.276982)
		(width 0.381)
		(layer "F.Cu")
		(net "PVDD18_S5_P0")
	)
	(segment
		(start 348.907862 -251.23013)
		(end 348.44101 -250.964192)
		(width 0.350012)
		(layer "F.Cu")
		(net "PVDD18_S5_P0")
	)
	(segment
		(start 236.118146 -146.431254)
		(end 236.323124 -146.636232)
		(width 0.508)
		(layer "F.Cu")
		(net "PVDD18_S5_P0")
	)
	(segment
		(start 122.214894 -54.375558)
		(end 122.214894 -53.73243)
		(width 0.254)
		(layer "F.Cu")
		(net "PVDD18_S5_P0")
	)
	(segment
		(start 231.583738 -144.959324)
		(end 231.28351 -145.259552)
		(width 0.508)
		(layer "F.Cu")
		(net "PVDD18_S5_P0")
	)
	(segment
		(start 390.247378 -57.2135)
		(end 390.5123 -57.478422)
		(width 0.508)
		(layer "F.Cu")
		(net "PVDD18_S5_P0")
	)
	(segment
		(start 264.26795 -105.222802)
		(end 265.440668 -105.222802)
		(width 0.381)
		(layer "F.Cu")
		(net "PVDD18_S5_P0")
	)
	(segment
		(start 366.971326 -43.635168)
		(end 366.971326 -44.251118)
		(width 0.4572)
		(layer "F.Cu")
		(net "PVDD18_S5_P0")
	)
	(segment
		(start 256.192274 -130.705098)
		(end 256.192274 -129.617216)
		(width 0.3556)
		(layer "F.Cu")
		(net "PVDD18_S5_P0")
	)
	(segment
		(start 262.02005 -143.764)
		(end 262.02005 -144.25295)
		(width 0.381)
		(layer "F.Cu")
		(net "PVDD18_S5_P0")
	)
	(segment
		(start 355.8667 -308.679342)
		(end 367.369344 -320.181986)
		(width 0.508)
		(layer "F.Cu")
		(net "PVDD18_S5_P0")
	)
	(segment
		(start 129.36728 -54.374288)
		(end 128.305052 -54.374288)
		(width 0.1778)
		(layer "F.Cu")
		(net "PVDD18_S5_P0")
	)
	(segment
		(start 132.610352 -51.88839)
		(end 134.279132 -51.88839)
		(width 0.381)
		(layer "F.Cu")
		(net "PVDD18_S5_P0")
	)
	(segment
		(start 262.848852 -137.503154)
		(end 262.95604 -137.395966)
		(width 0.381)
		(layer "F.Cu")
		(net "PVDD18_S5_P0")
	)
	(segment
		(start 385.152392 -148.04898)
		(end 383.156968 -150.044404)
		(width 0.381)
		(layer "F.Cu")
		(net "PVDD18_S5_P0")
	)
	(segment
		(start 345.618054 -255.28016)
		(end 345.151202 -255.014222)
		(width 0.350012)
		(layer "F.Cu")
		(net "PVDD18_S5_P0")
	)
	(segment
		(start 180.730906 -153.93924)
		(end 180.824378 -154.032712)
		(width 0.508)
		(layer "F.Cu")
		(net "PVDD18_S5_P0")
	)
	(segment
		(start 262.30326 -138.048746)
		(end 262.848852 -137.503154)
		(width 0.1778)
		(layer "F.Cu")
		(net "PVDD18_S5_P0")
	)
	(segment
		(start 122.927618 -56.53786)
		(end 122.927618 -55.475632)
		(width 0.1778)
		(layer "F.Cu")
		(net "PVDD18_S5_P0")
	)
	(segment
		(start 347.497908 -255.28016)
		(end 347.031056 -255.014222)
		(width 0.350012)
		(layer "F.Cu")
		(net "PVDD18_S5_P0")
	)
	(segment
		(start 374.440958 -208.262982)
		(end 374.800368 -208.622392)
		(width 0.508)
		(layer "F.Cu")
		(net "PVDD18_S5_P0")
	)
	(segment
		(start 345.1479 -254.470154)
		(end 344.681048 -254.204216)
		(width 0.350012)
		(layer "F.Cu")
		(net "PVDD18_S5_P0")
	)
	(segment
		(start 384.882644 -143.250158)
		(end 385.152392 -143.519906)
		(width 0.381)
		(layer "F.Cu")
		(net "PVDD18_S5_P0")
	)
	(segment
		(start 345.1479 -256.090166)
		(end 344.681048 -255.824228)
		(width 0.350012)
		(layer "F.Cu")
		(net "PVDD18_S5_P0")
	)
	(segment
		(start 145.773394 -55.569866)
		(end 145.773394 -55.313834)
		(width 0.1778)
		(layer "F.Cu")
		(net "PVDD18_S5_P0")
	)
	(segment
		(start 393.764008 -323.643752)
		(end 393.764008 -324.659752)
		(width 0.3556)
		(layer "F.Cu")
		(net "PVDD18_S5_P0")
	)
	(segment
		(start 404.158958 -321.766946)
		(end 404.158958 -321.402202)
		(width 0.381)
		(layer "F.Cu")
		(net "PVDD18_S5_P0")
	)
	(segment
		(start 264.878566 -131.067556)
		(end 265.494516 -131.067556)
		(width 0.381)
		(layer "F.Cu")
		(net "PVDD18_S5_P0")
	)
	(segment
		(start 178.47183 -157.908244)
		(end 179.422298 -157.908244)
		(width 0.508)
		(layer "F.Cu")
		(net "PVDD18_S5_P0")
	)
	(segment
		(start 123.127516 -56.737758)
		(end 123.810268 -56.737758)
		(width 0.508)
		(layer "F.Cu")
		(net "PVDD18_S5_P0")
	)
	(segment
		(start 347.497908 -252.040136)
		(end 347.031056 -251.774198)
		(width 0.350012)
		(layer "F.Cu")
		(net "PVDD18_S5_P0")
	)
	(segment
		(start 130.91414 -51.96586)
		(end 130.77952 -52.10048)
		(width 0.1778)
		(layer "F.Cu")
		(net "PVDD18_S5_P0")
	)
	(segment
		(start 292.129972 -53.80609)
		(end 292.637972 -53.29809)
		(width 0.381)
		(layer "F.Cu")
		(net "PVDD18_S5_P0")
	)
	(segment
		(start 146.074892 -55.871364)
		(end 145.773394 -55.569866)
		(width 0.1778)
		(layer "F.Cu")
		(net "PVDD18_S5_P0")
	)
	(segment
		(start 330.6826 -167.817546)
		(end 327.323958 -171.176188)
		(width 0.381)
		(layer "F.Cu")
		(net "PVDD18_S5_P0")
	)
	(segment
		(start 328.243438 -166.930324)
		(end 323.762878 -171.410884)
		(width 0.381)
		(layer "F.Cu")
		(net "PVDD18_S5_P0")
	)
	(segment
		(start 395.269212 -321.548252)
		(end 396.279878 -321.548252)
		(width 0.508)
		(layer "F.Cu")
		(net "PVDD18_S5_P0")
	)
	(segment
		(start 261.640066 -138.048746)
		(end 262.30326 -138.048746)
		(width 0.1778)
		(layer "F.Cu")
		(net "PVDD18_S5_P0")
	)
	(segment
		(start 128.305052 -54.374288)
		(end 128.105154 -54.17439)
		(width 0.1778)
		(layer "F.Cu")
		(net "PVDD18_S5_P0")
	)
	(segment
		(start 317.13805 -359.283)
		(end 317.601346 -359.283)
		(width 0.381)
		(layer "F.Cu")
		(net "PVDD18_S5_P0")
	)
	(segment
		(start 404.914608 -325.472552)
		(end 404.305008 -324.862952)
		(width 0.3556)
		(layer "F.Cu")
		(net "PVDD18_S5_P0")
	)
	(segment
		(start 345.618054 -250.420124)
		(end 345.151202 -250.154186)
		(width 0.350012)
		(layer "F.Cu")
		(net "PVDD18_S5_P0")
	)
	(segment
		(start 264.878566 -135.654796)
		(end 265.494516 -135.654796)
		(width 0.381)
		(layer "F.Cu")
		(net "PVDD18_S5_P0")
	)
	(segment
		(start 122.214894 -53.73243)
		(end 122.10161 -53.619146)
		(width 0.254)
		(layer "F.Cu")
		(net "PVDD18_S5_P0")
	)
	(segment
		(start 132.610352 -51.88839)
		(end 130.99161 -51.88839)
		(width 0.508)
		(layer "F.Cu")
		(net "PVDD18_S5_P0")
	)
	(segment
		(start 386.611876 -58.7375)
		(end 389.42264 -58.7375)
		(width 0.508)
		(layer "F.Cu")
		(net "PVDD18_S5_P0")
	)
	(segment
		(start 232.889806 -155.339542)
		(end 230.357934 -155.339542)
		(width 0.381)
		(layer "F.Cu")
		(net "PVDD18_S5_P0")
	)
	(segment
		(start 372.537228 -141.472158)
		(end 372.053612 -141.472158)
		(width 0.381)
		(layer "F.Cu")
		(net "PVDD18_S5_P0")
	)
	(segment
		(start 347.028008 -252.850142)
		(end 346.561156 -252.584204)
		(width 0.350012)
		(layer "F.Cu")
		(net "PVDD18_S5_P0")
	)
	(segment
		(start 145.773394 -55.313834)
		(end 145.142458 -55.313834)
		(width 0.508)
		(layer "F.Cu")
		(net "PVDD18_S5_P0")
	)
	(segment
		(start 306.318158 -360.609134)
		(end 305.867816 -360.609134)
		(width 0.1778)
		(layer "F.Cu")
		(net "PVDD18_S5_P0")
	)
	(segment
		(start 373.752618 -149.85365)
		(end 373.752618 -147.800314)
		(width 0.381)
		(layer "F.Cu")
		(net "PVDD18_S5_P0")
	)
	(segment
		(start 307.258974 -360.480102)
		(end 306.44719 -360.480102)
		(width 0.1778)
		(layer "F.Cu")
		(net "PVDD18_S5_P0")
	)
	(segment
		(start 232.887774 -144.959324)
		(end 231.583738 -144.959324)
		(width 0.508)
		(layer "F.Cu")
		(net "PVDD18_S5_P0")
	)
	(segment
		(start 347.028008 -251.23013)
		(end 346.561156 -250.964192)
		(width 0.350012)
		(layer "F.Cu")
		(net "PVDD18_S5_P0")
	)
	(segment
		(start 370.357908 -262.480044)
		(end 370.82476 -262.745982)
		(width 0.350012)
		(layer "F.Cu")
		(net "PVDD18_S5_P0")
	)
	(segment
		(start 265.89228 -103.272844)
		(end 266.591542 -103.272844)
		(width 0.381)
		(layer "F.Cu")
		(net "PVDD18_S5_P0")
	)
	(segment
		(start 327.323958 -171.176188)
		(end 327.323958 -192.763902)
		(width 0.381)
		(layer "F.Cu")
		(net "PVDD18_S5_P0")
	)
	(segment
		(start 370.969032 -35.437572)
		(end 371.606318 -35.437572)
		(width 0.4064)
		(layer "F.Cu")
		(net "PVDD18_S5_P0")
	)
	(segment
		(start 263.906 -141.58595)
		(end 263.906 -140.97)
		(width 0.381)
		(layer "F.Cu")
		(net "PVDD18_S5_P0")
	)
	(segment
		(start 219.47251 -131.054094)
		(end 218.607132 -131.054094)
		(width 0.508)
		(layer "F.Cu")
		(net "PVDD18_S5_P0")
	)
	(segment
		(start 369.881404 -35.010598)
		(end 370.308378 -35.437572)
		(width 0.3556)
		(layer "F.Cu")
		(net "PVDD18_S5_P0")
	)
	(segment
		(start 230.003604 -151.752046)
		(end 230.003604 -151.042878)
		(width 0.381)
		(layer "F.Cu")
		(net "PVDD18_S5_P0")
	)
	(segment
		(start 387.957568 -60.456318)
		(end 386.611876 -60.456318)
		(width 0.508)
		(layer "F.Cu")
		(net "PVDD18_S5_P0")
	)
	(segment
		(start 265.440668 -105.222802)
		(end 265.87069 -104.79278)
		(width 0.381)
		(layer "F.Cu")
		(net "PVDD18_S5_P0")
	)
	(segment
		(start 192.151 -138.032998)
		(end 192.151 -138.648948)
		(width 0.508)
		(layer "F.Cu")
		(net "PVDD18_S5_P0")
	)
	(segment
		(start 345.618054 -252.040136)
		(end 345.151202 -251.774198)
		(width 0.350012)
		(layer "F.Cu")
		(net "PVDD18_S5_P0")
	)
	(segment
		(start 396.279878 -321.807332)
		(end 395.73708 -322.35013)
		(width 0.381)
		(layer "F.Cu")
		(net "PVDD18_S5_P0")
	)
	(segment
		(start 395.619986 -322.35013)
		(end 395.957298 -322.687442)
		(width 0.3556)
		(layer "F.Cu")
		(net "PVDD18_S5_P0")
	)
	(segment
		(start 317.601346 -359.283)
		(end 317.855346 -359.029)
		(width 0.381)
		(layer "F.Cu")
		(net "PVDD18_S5_P0")
	)
	(segment
		(start 365.701326 -45.667168)
		(end 365.701326 -46.283118)
		(width 0.4572)
		(layer "F.Cu")
		(net "PVDD18_S5_P0")
	)
	(segment
		(start 232.889806 -159.022542)
		(end 231.116632 -159.022542)
		(width 0.4064)
		(layer "F.Cu")
		(net "PVDD18_S5_P0")
	)
	(segment
		(start 394.55979 -323.396102)
		(end 394.31214 -323.643752)
		(width 0.3556)
		(layer "F.Cu")
		(net "PVDD18_S5_P0")
	)
	(segment
		(start 179.23764 -153.93924)
		(end 180.730906 -153.93924)
		(width 0.508)
		(layer "F.Cu")
		(net "PVDD18_S5_P0")
	)
	(segment
		(start 348.907862 -252.850142)
		(end 348.44101 -252.584204)
		(width 0.350012)
		(layer "F.Cu")
		(net "PVDD18_S5_P0")
	)
	(segment
		(start 345.50096 -308.679342)
		(end 355.8667 -308.679342)
		(width 0.508)
		(layer "F.Cu")
		(net "PVDD18_S5_P0")
	)
	(segment
		(start 236.118146 -144.958562)
		(end 236.118146 -146.431254)
		(width 0.508)
		(layer "F.Cu")
		(net "PVDD18_S5_P0")
	)
	(segment
		(start 403.578822 -322.347082)
		(end 404.158958 -321.766946)
		(width 0.381)
		(layer "F.Cu")
		(net "PVDD18_S5_P0")
	)
	(segment
		(start 395.810486 -323.45503)
		(end 395.751558 -323.396102)
		(width 0.381)
		(layer "F.Cu")
		(net "PVDD18_S5_P0")
	)
	(segment
		(start 232.0925 -147.92452)
		(end 231.083866 -147.92452)
		(width 0.3556)
		(layer "F.Cu")
		(net "PVDD18_S5_P0")
	)
	(segment
		(start 348.907862 -254.470154)
		(end 348.44101 -254.204216)
		(width 0.350012)
		(layer "F.Cu")
		(net "PVDD18_S5_P0")
	)
	(segment
		(start 230.357934 -155.339542)
		(end 230.303324 -155.284932)
		(width 0.381)
		(layer "F.Cu")
		(net "PVDD18_S5_P0")
	)
	(segment
		(start 231.28351 -145.259552)
		(end 231.28351 -147.034758)
		(width 0.508)
		(layer "F.Cu")
		(net "PVDD18_S5_P0")
	)
	(segment
		(start 401.751038 -329.602338)
		(end 401.3581 -329.2094)
		(width 0.3556)
		(layer "F.Cu")
		(net "PVDD18_S5_P0")
	)
	(segment
		(start 328.93 -166.4208)
		(end 328.93 -167.272208)
		(width 0.508)
		(layer "F.Cu")
		(net "PVDD18_S5_P0")
	)
	(segment
		(start 384.513328 -143.250158)
		(end 384.882644 -143.250158)
		(width 0.381)
		(layer "F.Cu")
		(net "PVDD18_S5_P0")
	)
	(segment
		(start 369.511326 -43.635168)
		(end 369.511326 -44.099226)
		(width 0.4572)
		(layer "F.Cu")
		(net "PVDD18_S5_P0")
	)
	(segment
		(start 395.957298 -322.687442)
		(end 395.957298 -323.190362)
		(width 0.3556)
		(layer "F.Cu")
		(net "PVDD18_S5_P0")
	)
	(segment
		(start 404.083012 -58.2295)
		(end 404.220172 -58.36666)
		(width 0.508)
		(layer "F.Cu")
		(net "PVDD18_S5_P0")
	)
	(segment
		(start 128.105154 -54.17439)
		(end 128.105154 -54.838854)
		(width 0.508)
		(layer "F.Cu")
		(net "PVDD18_S5_P0")
	)
	(segment
		(start 134.279132 -51.88839)
		(end 135.184388 -52.793646)
		(width 0.381)
		(layer "F.Cu")
		(net "PVDD18_S5_P0")
	)
	(segment
		(start 264.878566 -133.622796)
		(end 265.494516 -133.622796)
		(width 0.381)
		(layer "F.Cu")
		(net "PVDD18_S5_P0")
	)
	(segment
		(start 365.981234 -39.843964)
		(end 365.981234 -38.650164)
		(width 0.3556)
		(layer "F.Cu")
		(net "PVDD18_S5_P0")
	)
	(segment
		(start 213.835488 -135.91794)
		(end 214.653876 -135.91794)
		(width 0.508)
		(layer "F.Cu")
		(net "PVDD18_S5_P0")
	)
	(segment
		(start 386.611876 -57.2135)
		(end 390.247378 -57.2135)
		(width 0.508)
		(layer "F.Cu")
		(net "PVDD18_S5_P0")
	)
	(segment
		(start 232.141522 -147.973542)
		(end 232.0925 -147.92452)
		(width 0.3556)
		(layer "F.Cu")
		(net "PVDD18_S5_P0")
	)
	(segment
		(start 344.332814 -307.511196)
		(end 345.50096 -308.679342)
		(width 0.508)
		(layer "F.Cu")
		(net "PVDD18_S5_P0")
	)
	(segment
		(start 330.371958 -171.862242)
		(end 330.371958 -192.763902)
		(width 0.508)
		(layer "F.Cu")
		(net "PVDD18_S5_P0")
	)
	(segment
		(start 397.307308 -64.5795)
		(end 399.415508 -64.5795)
		(width 0.508)
		(layer "F.Cu")
		(net "PVDD18_S5_P0")
	)
	(segment
		(start 374.231408 -150.33244)
		(end 373.752618 -149.85365)
		(width 0.381)
		(layer "F.Cu")
		(net "PVDD18_S5_P0")
	)
	(segment
		(start 378.31776 -150.044404)
		(end 378.029724 -150.33244)
		(width 0.381)
		(layer "F.Cu")
		(net "PVDD18_S5_P0")
	)
	(segment
		(start 394.811758 -323.396102)
		(end 394.55979 -323.396102)
		(width 0.3556)
		(layer "F.Cu")
		(net "PVDD18_S5_P0")
	)
	(segment
		(start 130.77952 -52.10048)
		(end 130.77952 -52.732686)
		(width 0.1778)
		(layer "F.Cu")
		(net "PVDD18_S5_P0")
	)
	(segment
		(start 317.855346 -359.029)
		(end 318.2874 -359.029)
		(width 0.381)
		(layer "F.Cu")
		(net "PVDD18_S5_P0")
	)
	(segment
		(start 345.618054 -253.660148)
		(end 345.151202 -253.39421)
		(width 0.350012)
		(layer "F.Cu")
		(net "PVDD18_S5_P0")
	)
	(segment
		(start 332.6384 -169.5958)
		(end 330.371958 -171.862242)
		(width 0.508)
		(layer "F.Cu")
		(net "PVDD18_S5_P0")
	)
	(segment
		(start 378.009658 -207.536796)
		(end 377.932442 -207.45958)
		(width 0.508)
		(layer "F.Cu")
		(net "PVDD18_S5_P0")
	)
	(segment
		(start 349.378016 -252.040136)
		(end 348.911164 -251.774198)
		(width 0.350012)
		(layer "F.Cu")
		(net "PVDD18_S5_P0")
	)
	(segment
		(start 306.44719 -360.480102)
		(end 306.318158 -360.609134)
		(width 0.1778)
		(layer "F.Cu")
		(net "PVDD18_S5_P0")
	)
	(segment
		(start 347.497908 -250.420124)
		(end 347.031056 -250.154186)
		(width 0.350012)
		(layer "F.Cu")
		(net "PVDD18_S5_P0")
	)
	(segment
		(start 231.116632 -159.022542)
		(end 231.075738 -158.981648)
		(width 0.4064)
		(layer "F.Cu")
		(net "PVDD18_S5_P0")
	)
	(segment
		(start 367.369344 -324.29577)
		(end 383.84226 -340.768686)
		(width 0.508)
		(layer "F.Cu")
		(net "PVDD18_S5_P0")
	)
	(segment
		(start 305.867816 -360.609134)
		(end 305.322224 -360.609134)
		(width 0.381)
		(layer "F.Cu")
		(net "PVDD18_S5_P0")
	)
	(segment
		(start 345.1479 -249.610118)
		(end 344.681048 -249.34418)
		(width 0.350012)
		(layer "F.Cu")
		(net "PVDD18_S5_P0")
	)
	(segment
		(start 265.386566 -138.321796)
		(end 265.611864 -138.321796)
		(width 0.381)
		(layer "F.Cu")
		(net "PVDD18_S5_P0")
	)
	(segment
		(start 256.192274 -129.617216)
		(end 255.576324 -129.617216)
		(width 0.381)
		(layer "F.Cu")
		(net "PVDD18_S5_P0")
	)
	(segment
		(start 363.008926 -27.873452)
		(end 363.008926 -27.257502)
		(width 0.4572)
		(layer "F.Cu")
		(net "PVDD18_S5_P0")
	)
	(segment
		(start 304.4952 -361.061)
		(end 304.81905 -360.73715)
		(width 0.381)
		(layer "F.Cu")
		(net "PVDD18_S5_P0")
	)
	(segment
		(start 424.02379 -359.836212)
		(end 424.815254 -359.836212)
		(width 0.3556)
		(layer "F.Cu")
		(net "PVDD18_S5_P0")
	)
	(segment
		(start 328.93 -167.272208)
		(end 324.529958 -171.67225)
		(width 0.508)
		(layer "F.Cu")
		(net "PVDD18_S5_P0")
	)
	(segment
		(start 369.881404 -39.843964)
		(end 369.881404 -38.650164)
		(width 0.3556)
		(layer "F.Cu")
		(net "PVDD18_S5_P0")
	)
	(segment
		(start 385.152392 -143.519906)
		(end 385.152392 -148.04898)
		(width 0.381)
		(layer "F.Cu")
		(net "PVDD18_S5_P0")
	)
	(segment
		(start 378.029724 -150.33244)
		(end 374.231408 -150.33244)
		(width 0.381)
		(layer "F.Cu")
		(net "PVDD18_S5_P0")
	)
	(segment
		(start 394.31214 -323.643752)
		(end 393.764008 -323.643752)
		(width 0.3556)
		(layer "F.Cu")
		(net "PVDD18_S5_P0")
	)
	(segment
		(start 292.129972 -53.935376)
		(end 292.129972 -53.80609)
		(width 0.381)
		(layer "F.Cu")
		(net "PVDD18_S5_P0")
	)
	(segment
		(start 265.611864 -138.321796)
		(end 265.9888 -137.94486)
		(width 0.381)
		(layer "F.Cu")
		(net "PVDD18_S5_P0")
	)
	(segment
		(start 401.3581 -329.2094)
		(end 401.32254 -329.2094)
		(width 0.3556)
		(layer "F.Cu")
		(net "PVDD18_S5_P0")
	)
	(segment
		(start 230.099108 -151.656542)
		(end 230.003604 -151.752046)
		(width 0.381)
		(layer "F.Cu")
		(net "PVDD18_S5_P0")
	)
	(segment
		(start 123.327414 -56.53786)
		(end 123.127516 -56.737758)
		(width 0.1778)
		(layer "F.Cu")
		(net "PVDD18_S5_P0")
	)
	(segment
		(start 383.156968 -150.044404)
		(end 378.31776 -150.044404)
		(width 0.381)
		(layer "F.Cu")
		(net "PVDD18_S5_P0")
	)
	(segment
		(start 374.800368 -208.622392)
		(end 377.521216 -208.622392)
		(width 0.508)
		(layer "F.Cu")
		(net "PVDD18_S5_P0")
	)
	(segment
		(start 396.279878 -321.548252)
		(end 396.279878 -321.807332)
		(width 0.381)
		(layer "F.Cu")
		(net "PVDD18_S5_P0")
	)
	(segment
		(start 231.083866 -147.92452)
		(end 231.075738 -147.932648)
		(width 0.3556)
		(layer "F.Cu")
		(net "PVDD18_S5_P0")
	)
	(segment
		(start 404.220172 -58.36666)
		(end 405.501348 -58.36666)
		(width 0.508)
		(layer "F.Cu")
		(net "PVDD18_S5_P0")
	)
	(segment
		(start 403.563328 -322.347082)
		(end 403.578822 -322.347082)
		(width 0.381)
		(layer "F.Cu")
		(net "PVDD18_S5_P0")
	)
	(segment
		(start 230.303324 -155.284932)
		(end 230.303324 -155.971748)
		(width 0.381)
		(layer "F.Cu")
		(net "PVDD18_S5_P0")
	)
	(segment
		(start 232.889806 -147.973542)
		(end 232.141522 -147.973542)
		(width 0.3556)
		(layer "F.Cu")
		(net "PVDD18_S5_P0")
	)
	(segment
		(start 130.77952 -52.732686)
		(end 130.467354 -53.044852)
		(width 0.1778)
		(layer "F.Cu")
		(net "PVDD18_S5_P0")
	)
	(segment
		(start 384.465576 -54.9656)
		(end 384.492246 -54.99227)
		(width 0.508)
		(layer "F.Cu")
		(net "PVDD18_S5_P0")
	)
	(segment
		(start 262.95604 -137.395966)
		(end 263.158478 -137.395966)
		(width 0.381)
		(layer "F.Cu")
		(net "PVDD18_S5_P0")
	)
	(segment
		(start 403.142958 -321.402202)
		(end 404.158958 -321.402202)
		(width 0.3556)
		(layer "F.Cu")
		(net "PVDD18_S5_P0")
	)
	(segment
		(start 397.307308 -53.1495)
		(end 395.315186 -53.1495)
		(width 0.508)
		(layer "F.Cu")
		(net "PVDD18_S5_P0")
	)
	(segment
		(start 130.467354 -53.044852)
		(end 130.467354 -53.261768)
		(width 0.1778)
		(layer "F.Cu")
		(net "PVDD18_S5_P0")
	)
	(segment
		(start 347.028008 -254.470154)
		(end 346.561156 -254.204216)
		(width 0.350012)
		(layer "F.Cu")
		(net "PVDD18_S5_P0")
	)
	(segment
		(start 265.386566 -139.591796)
		(end 266.02309 -139.591796)
		(width 0.381)
		(layer "F.Cu")
		(net "PVDD18_S5_P0")
	)
	(segment
		(start 305.322224 -360.609134)
		(end 305.13909 -360.426)
		(width 0.381)
		(layer "F.Cu")
		(net "PVDD18_S5_P0")
	)
	(segment
		(start 345.1479 -252.850142)
		(end 344.681048 -252.584204)
		(width 0.350012)
		(layer "F.Cu")
		(net "PVDD18_S5_P0")
	)
	(segment
		(start 401.751038 -329.762612)
		(end 401.751038 -329.602338)
		(width 0.3556)
		(layer "F.Cu")
		(net "PVDD18_S5_P0")
	)
	(segment
		(start 383.84226 -340.768686)
		(end 396.985998 -340.768686)
		(width 0.508)
		(layer "F.Cu")
		(net "PVDD18_S5_P0")
	)
	(segment
		(start 323.762878 -193.276982)
		(end 323.513958 -193.525902)
		(width 0.381)
		(layer "F.Cu")
		(net "PVDD18_S5_P0")
	)
	(segment
		(start 395.73708 -322.35013)
		(end 395.619986 -322.35013)
		(width 0.381)
		(layer "F.Cu")
		(net "PVDD18_S5_P0")
	)
	(segment
		(start 384.492246 -54.99227)
		(end 385.497832 -54.99227)
		(width 0.508)
		(layer "F.Cu")
		(net "PVDD18_S5_P0")
	)
	(segment
		(start 345.1479 -251.23013)
		(end 344.681048 -250.964192)
		(width 0.350012)
		(layer "F.Cu")
		(net "PVDD18_S5_P0")
	)
	(segment
		(start 232.889806 -151.656542)
		(end 230.099108 -151.656542)
		(width 0.381)
		(layer "F.Cu")
		(net "PVDD18_S5_P0")
	)
	(segment
		(start 369.511326 -44.099226)
		(end 369.309396 -44.301156)
		(width 0.4572)
		(layer "F.Cu")
		(net "PVDD18_S5_P0")
	)
	(segment
		(start 231.075738 -147.932648)
		(end 231.075738 -147.24253)
		(width 0.3556)
		(layer "F.Cu")
		(net "PVDD18_S5_P0")
	)
	(segment
		(start 130.99161 -51.88839)
		(end 130.91414 -51.96586)
		(width 0.508)
		(layer "F.Cu")
		(net "PVDD18_S5_P0")
	)
	(segment
		(start 122.727212 -52.534058)
		(end 122.446542 -52.534058)
		(width 0.4572)
		(layer "F.Cu")
		(net "PVDD18_S5_P0")
	)
	(segment
		(start 404.914608 -325.774812)
		(end 404.914608 -325.472552)
		(width 0.3556)
		(layer "F.Cu")
		(net "PVDD18_S5_P0")
	)
	(segment
		(start 305.13909 -360.426)
		(end 304.81905 -360.426)
		(width 0.381)
		(layer "F.Cu")
		(net "PVDD18_S5_P0")
	)
	(segment
		(start 146.074892 -56.57596)
		(end 146.074892 -55.871364)
		(width 0.1778)
		(layer "F.Cu")
		(net "PVDD18_S5_P0")
	)
	(segment
		(start 265.87069 -103.294434)
		(end 265.89228 -103.272844)
		(width 0.381)
		(layer "F.Cu")
		(net "PVDD18_S5_P0")
	)
	(segment
		(start 370.308378 -35.437572)
		(end 370.969032 -35.437572)
		(width 0.3556)
		(layer "F.Cu")
		(net "PVDD18_S5_P0")
	)
	(segment
		(start 396.725902 -323.45503)
		(end 395.810486 -323.45503)
		(width 0.381)
		(layer "F.Cu")
		(net "PVDD18_S5_P0")
	)
	(segment
		(start 395.957298 -323.190362)
		(end 395.751558 -323.396102)
		(width 0.3556)
		(layer "F.Cu")
		(net "PVDD18_S5_P0")
	)
	(segment
		(start 231.075738 -158.981648)
		(end 231.075738 -159.620204)
		(width 0.4064)
		(layer "F.Cu")
		(net "PVDD18_S5_P0")
	)
	(segment
		(start 272.200624 -93.927168)
		(end 272.200624 -93.148404)
		(width 0.508)
		(layer "F.Cu")
		(net "PVDD18_S5_P0")
	)
	(segment
		(start 122.446542 -52.534058)
		(end 122.0978 -52.8828)
		(width 0.4572)
		(layer "F.Cu")
		(net "PVDD18_S5_P0")
	)
	(segment
		(start 347.028008 -249.610118)
		(end 346.561156 -249.34418)
		(width 0.350012)
		(layer "F.Cu")
		(net "PVDD18_S5_P0")
	)
	(segment
		(start 123.127516 -56.737758)
		(end 122.927618 -56.53786)
		(width 0.1778)
		(layer "F.Cu")
		(net "PVDD18_S5_P0")
	)
	(segment
		(start 413.925512 -362.804964)
		(end 413.313118 -362.804964)
		(width 0.3556)
		(layer "F.Cu")
		(net "PVDD18_S5_P0")
	)
	(segment
		(start 347.028008 -256.090166)
		(end 346.561156 -255.824228)
		(width 0.350012)
		(layer "F.Cu")
		(net "PVDD18_S5_P0")
	)
	(segment
		(start 183.007 -140.572998)
		(end 183.007 -141.188948)
		(width 0.508)
		(layer "F.Cu")
		(net "PVDD18_S5_P0")
	)
	(segment
		(start 402.126958 -321.402202)
		(end 403.142958 -321.402202)
		(width 0.3556)
		(layer "F.Cu")
		(net "PVDD18_S5_P0")
	)
	(segment
		(start 372.053612 -141.472158)
		(end 371.921278 -141.604492)
		(width 0.381)
		(layer "F.Cu")
		(net "PVDD18_S5_P0")
	)
	(segment
		(start 231.28351 -147.034758)
		(end 231.075738 -147.24253)
		(width 0.508)
		(layer "F.Cu")
		(net "PVDD18_S5_P0")
	)
	(segment
		(start 347.497908 -253.660148)
		(end 347.031056 -253.39421)
		(width 0.350012)
		(layer "F.Cu")
		(net "PVDD18_S5_P0")
	)
	(segment
		(start 378.009658 -208.13395)
		(end 378.009658 -207.536796)
		(width 0.508)
		(layer "F.Cu")
		(net "PVDD18_S5_P0")
	)
	(segment
		(start 262.02005 -144.25295)
		(end 261.874 -144.399)
		(width 0.381)
		(layer "F.Cu")
		(net "PVDD18_S5_P0")
	)
	(segment
		(start 377.521216 -208.622392)
		(end 378.009658 -208.13395)
		(width 0.508)
		(layer "F.Cu")
		(net "PVDD18_S5_P0")
	)
	(segment
		(start 324.529958 -171.67225)
		(end 324.529958 -193.525902)
		(width 0.508)
		(layer "F.Cu")
		(net "PVDD18_S5_P0")
	)
	(segment
		(start 129.36728 -53.974492)
		(end 128.305052 -53.974492)
		(width 0.1778)
		(layer "F.Cu")
		(net "PVDD18_S5_P0")
	)
	(segment
		(start 177.45583 -157.908244)
		(end 178.47183 -157.908244)
		(width 0.508)
		(layer "F.Cu")
		(net "PVDD18_S5_P0")
	)
	(segment
		(start 395.751558 -323.396102)
		(end 394.811758 -323.396102)
		(width 0.3556)
		(layer "F.Cu")
		(net "PVDD18_S5_P0")
	)
	(segment
		(start 395.315186 -53.1495)
		(end 394.80744 -52.641754)
		(width 0.508)
		(layer "F.Cu")
		(net "PVDD18_S5_P0")
	)
	(segment
		(start 292.129972 -52.665376)
		(end 292.129972 -52.53609)
		(width 0.381)
		(layer "F.Cu")
		(net "PVDD18_S5_P0")
	)
	(segment
		(start 367.369344 -320.181986)
		(end 367.369344 -324.29577)
		(width 0.508)
		(layer "F.Cu")
		(net "PVDD18_S5_P0")
	)
	(segment
		(start 128.305052 -53.974492)
		(end 128.105154 -54.17439)
		(width 0.1778)
		(layer "F.Cu")
		(net "PVDD18_S5_P0")
	)
	(segment
		(start 368.241326 -45.667168)
		(end 368.241326 -46.283118)
		(width 0.4572)
		(layer "F.Cu")
		(net "PVDD18_S5_P0")
	)
	(via
		(at 353.43084 -255.530096)
		(size 0.4826)
		(drill 0.254)
		(layers "F.Cu" "B.Cu")
		(net "PVDD18_S5_P0")
	)
	(via
		(at 266.02309 -139.591796)
		(size 0.508)
		(drill 0.254)
		(layers "F.Cu" "B.Cu")
		(net "PVDD18_S5_P0")
	)
	(via
		(at 408.660854 -326.615298)
		(size 0.508)
		(drill 0.254)
		(layers "F.Cu" "B.Cu")
		(net "PVDD18_S5_P0")
	)
	(via
		(at 334.585564 -151.692102)
		(size 0.508)
		(drill 0.254)
		(layers "F.Cu" "B.Cu")
		(net "PVDD18_S5_P0")
	)
	(via
		(at 353.43084 -256.480056)
		(size 0.4826)
		(drill 0.254)
		(layers "F.Cu" "B.Cu")
		(net "PVDD18_S5_P0")
	)
	(via
		(at 179.422298 -157.908244)
		(size 0.508)
		(drill 0.254)
		(layers "F.Cu" "B.Cu")
		(net "PVDD18_S5_P0")
	)
	(via
		(at 427.97095 -37.023548)
		(size 0.508)
		(drill 0.254)
		(layers "F.Cu" "B.Cu")
		(net "PVDD18_S5_P0")
	)
	(via
		(at 292.129972 -52.665376)
		(size 0.508)
		(drill 0.254)
		(layers "F.Cu" "B.Cu")
		(net "PVDD18_S5_P0")
	)
	(via
		(at 183.439054 -147.143724)
		(size 0.508)
		(drill 0.254)
		(layers "F.Cu" "B.Cu")
		(net "PVDD18_S5_P0")
	)
	(via
		(at 377.932442 -207.45958)
		(size 0.508)
		(drill 0.254)
		(layers "F.Cu" "B.Cu")
		(net "PVDD18_S5_P0")
	)
	(via
		(at 332.116176 -156.4894)
		(size 0.508)
		(drill 0.254)
		(layers "F.Cu" "B.Cu")
		(net "PVDD18_S5_P0")
	)
	(via
		(at 332.6384 -169.5958)
		(size 0.508)
		(drill 0.254)
		(layers "F.Cu" "B.Cu")
		(net "PVDD18_S5_P0")
	)
	(via
		(at 374.440958 -207.485488)
		(size 0.508)
		(drill 0.254)
		(layers "F.Cu" "B.Cu")
		(net "PVDD18_S5_P0")
	)
	(via
		(at 119.63781 -133.929882)
		(size 0.508)
		(drill 0.254)
		(layers "F.Cu" "B.Cu")
		(net "PVDD18_S5_P0")
	)
	(via
		(at 333.640176 -153.4414)
		(size 0.508)
		(drill 0.254)
		(layers "F.Cu" "B.Cu")
		(net "PVDD18_S5_P0")
	)
	(via
		(at 231.902 -230.886)
		(size 0.508)
		(drill 0.254)
		(layers "F.Cu" "B.Cu")
		(net "PVDD18_S5_P0")
	)
	(via
		(at 400.19478 -126.453138)
		(size 0.508)
		(drill 0.254)
		(layers "F.Cu" "B.Cu")
		(net "PVDD18_S5_P0")
	)
	(via
		(at 332.116176 -154.2034)
		(size 0.508)
		(drill 0.254)
		(layers "F.Cu" "B.Cu")
		(net "PVDD18_S5_P0")
	)
	(via
		(at 385.497832 -54.99227)
		(size 0.508)
		(drill 0.254)
		(layers "F.Cu" "B.Cu")
		(net "PVDD18_S5_P0")
	)
	(via
		(at 366.971326 -44.251118)
		(size 0.508)
		(drill 0.254)
		(layers "F.Cu" "B.Cu")
		(net "PVDD18_S5_P0")
	)
	(via
		(at 330.3016 -152.250902)
		(size 0.508)
		(drill 0.254)
		(layers "F.Cu" "B.Cu")
		(net "PVDD18_S5_P0")
	)
	(via
		(at 344.681048 -254.204216)
		(size 0.4064)
		(drill 0.2032)
		(layers "F.Cu" "B.Cu")
		(net "PVDD18_S5_P0")
	)
	(via
		(at 334.585564 -152.454102)
		(size 0.508)
		(drill 0.254)
		(layers "F.Cu" "B.Cu")
		(net "PVDD18_S5_P0")
	)
	(via
		(at 128.105154 -54.838854)
		(size 0.508)
		(drill 0.254)
		(layers "F.Cu" "B.Cu")
		(net "PVDD18_S5_P0")
	)
	(via
		(at 304.4952 -361.061)
		(size 0.508)
		(drill 0.254)
		(layers "F.Cu" "B.Cu")
		(net "PVDD18_S5_P0")
	)
	(via
		(at 414.509712 -320.272918)
		(size 0.508)
		(drill 0.254)
		(layers "F.Cu" "B.Cu")
		(net "PVDD18_S5_P0")
	)
	(via
		(at 344.681048 -255.824228)
		(size 0.4064)
		(drill 0.2032)
		(layers "F.Cu" "B.Cu")
		(net "PVDD18_S5_P0")
	)
	(via
		(at 346.561156 -252.584204)
		(size 0.4064)
		(drill 0.2032)
		(layers "F.Cu" "B.Cu")
		(net "PVDD18_S5_P0")
	)
	(via
		(at 396.985998 -340.768686)
		(size 0.508)
		(drill 0.254)
		(layers "F.Cu" "B.Cu")
		(net "PVDD18_S5_P0")
	)
	(via
		(at 348.44101 -250.964192)
		(size 0.4064)
		(drill 0.2032)
		(layers "F.Cu" "B.Cu")
		(net "PVDD18_S5_P0")
	)
	(via
		(at 292.129972 -53.935376)
		(size 0.508)
		(drill 0.254)
		(layers "F.Cu" "B.Cu")
		(net "PVDD18_S5_P0")
	)
	(via
		(at 346.561156 -249.34418)
		(size 0.4064)
		(drill 0.2032)
		(layers "F.Cu" "B.Cu")
		(net "PVDD18_S5_P0")
	)
	(via
		(at 122.10161 -53.619146)
		(size 0.508)
		(drill 0.254)
		(layers "F.Cu" "B.Cu")
		(net "PVDD18_S5_P0")
	)
	(via
		(at 371.921278 -141.604492)
		(size 0.508)
		(drill 0.254)
		(layers "F.Cu" "B.Cu")
		(net "PVDD18_S5_P0")
	)
	(via
		(at 395.254734 -202.829668)
		(size 0.508)
		(drill 0.254)
		(layers "F.Cu" "B.Cu")
		(net "PVDD18_S5_P0")
	)
	(via
		(at 266.591542 -103.272844)
		(size 0.508)
		(drill 0.254)
		(layers "F.Cu" "B.Cu")
		(net "PVDD18_S5_P0")
	)
	(via
		(at 231.075738 -159.620204)
		(size 0.508)
		(drill 0.254)
		(layers "F.Cu" "B.Cu")
		(net "PVDD18_S5_P0")
	)
	(via
		(at 399.427446 -65.402714)
		(size 0.508)
		(drill 0.254)
		(layers "F.Cu" "B.Cu")
		(net "PVDD18_S5_P0")
	)
	(via
		(at 330.6826 -167.817546)
		(size 0.508)
		(drill 0.254)
		(layers "F.Cu" "B.Cu")
		(net "PVDD18_S5_P0")
	)
	(via
		(at 345.151202 -253.39421)
		(size 0.4064)
		(drill 0.2032)
		(layers "F.Cu" "B.Cu")
		(net "PVDD18_S5_P0")
	)
	(via
		(at 181.619398 -154.032712)
		(size 0.508)
		(drill 0.254)
		(layers "F.Cu" "B.Cu")
		(net "PVDD18_S5_P0")
	)
	(via
		(at 345.151202 -251.774198)
		(size 0.4064)
		(drill 0.2032)
		(layers "F.Cu" "B.Cu")
		(net "PVDD18_S5_P0")
	)
	(via
		(at 344.681048 -252.584204)
		(size 0.4064)
		(drill 0.2032)
		(layers "F.Cu" "B.Cu")
		(net "PVDD18_S5_P0")
	)
	(via
		(at 398.2974 -327.766172)
		(size 0.508)
		(drill 0.254)
		(layers "F.Cu" "B.Cu")
		(net "PVDD18_S5_P0")
	)
	(via
		(at 431.031396 -140.49121)
		(size 0.508)
		(drill 0.254)
		(layers "F.Cu" "B.Cu")
		(net "PVDD18_S5_P0")
	)
	(via
		(at 345.151202 -250.154186)
		(size 0.4064)
		(drill 0.2032)
		(layers "F.Cu" "B.Cu")
		(net "PVDD18_S5_P0")
	)
	(via
		(at 368.241326 -46.283118)
		(size 0.508)
		(drill 0.254)
		(layers "F.Cu" "B.Cu")
		(net "PVDD18_S5_P0")
	)
	(via
		(at 319.861438 -202.891136)
		(size 0.508)
		(drill 0.254)
		(layers "F.Cu" "B.Cu")
		(net "PVDD18_S5_P0")
	)
	(via
		(at 230.003604 -151.042878)
		(size 0.508)
		(drill 0.254)
		(layers "F.Cu" "B.Cu")
		(net "PVDD18_S5_P0")
	)
	(via
		(at 377.234958 -204.085952)
		(size 0.508)
		(drill 0.254)
		(layers "F.Cu" "B.Cu")
		(net "PVDD18_S5_P0")
	)
	(via
		(at 381.552958 -207.521302)
		(size 0.508)
		(drill 0.254)
		(layers "F.Cu" "B.Cu")
		(net "PVDD18_S5_P0")
	)
	(via
		(at 332.4352 -158.8008)
		(size 0.508)
		(drill 0.254)
		(layers "F.Cu" "B.Cu")
		(net "PVDD18_S5_P0")
	)
	(via
		(at 272.200624 -93.148404)
		(size 0.508)
		(drill 0.254)
		(layers "F.Cu" "B.Cu")
		(net "PVDD18_S5_P0")
	)
	(via
		(at 284.893512 -102.08641)
		(size 0.508)
		(drill 0.254)
		(layers "F.Cu" "B.Cu")
		(net "PVDD18_S5_P0")
	)
	(via
		(at 369.881404 -38.650164)
		(size 0.508)
		(drill 0.254)
		(layers "F.Cu" "B.Cu")
		(net "PVDD18_S5_P0")
	)
	(via
		(at 263.474454 -137.07999)
		(size 0.508)
		(drill 0.254)
		(layers "F.Cu" "B.Cu")
		(net "PVDD18_S5_P0")
	)
	(via
		(at 333.640176 -154.9654)
		(size 0.508)
		(drill 0.254)
		(layers "F.Cu" "B.Cu")
		(net "PVDD18_S5_P0")
	)
	(via
		(at 427.97095 -31.435548)
		(size 0.508)
		(drill 0.254)
		(layers "F.Cu" "B.Cu")
		(net "PVDD18_S5_P0")
	)
	(via
		(at 415.144712 -320.272918)
		(size 0.508)
		(drill 0.254)
		(layers "F.Cu" "B.Cu")
		(net "PVDD18_S5_P0")
	)
	(via
		(at 398.28978 -126.453138)
		(size 0.508)
		(drill 0.254)
		(layers "F.Cu" "B.Cu")
		(net "PVDD18_S5_P0")
	)
	(via
		(at 400.98726 -325.96074)
		(size 0.508)
		(drill 0.254)
		(layers "F.Cu" "B.Cu")
		(net "PVDD18_S5_P0")
	)
	(via
		(at 432.047396 -140.49121)
		(size 0.508)
		(drill 0.254)
		(layers "F.Cu" "B.Cu")
		(net "PVDD18_S5_P0")
	)
	(via
		(at 210.269328 -140.784326)
		(size 0.508)
		(drill 0.254)
		(layers "F.Cu" "B.Cu")
		(net "PVDD18_S5_P0")
	)
	(via
		(at 190.114428 -141.49959)
		(size 0.508)
		(drill 0.254)
		(layers "F.Cu" "B.Cu")
		(net "PVDD18_S5_P0")
	)
	(via
		(at 214.653876 -135.91794)
		(size 0.508)
		(drill 0.254)
		(layers "F.Cu" "B.Cu")
		(net "PVDD18_S5_P0")
	)
	(via
		(at 236.323124 -146.636232)
		(size 0.508)
		(drill 0.254)
		(layers "F.Cu" "B.Cu")
		(net "PVDD18_S5_P0")
	)
	(via
		(at 365.981234 -38.650164)
		(size 0.508)
		(drill 0.254)
		(layers "F.Cu" "B.Cu")
		(net "PVDD18_S5_P0")
	)
	(via
		(at 293.15283 -148.930106)
		(size 0.508)
		(drill 0.254)
		(layers "F.Cu" "B.Cu")
		(net "PVDD18_S5_P0")
	)
	(via
		(at 255.79832 -93.240098)
		(size 0.508)
		(drill 0.254)
		(layers "F.Cu" "B.Cu")
		(net "PVDD18_S5_P0")
	)
	(via
		(at 347.031056 -253.39421)
		(size 0.4064)
		(drill 0.2032)
		(layers "F.Cu" "B.Cu")
		(net "PVDD18_S5_P0")
	)
	(via
		(at 335.89468 -166.844218)
		(size 0.508)
		(drill 0.254)
		(layers "F.Cu" "B.Cu")
		(net "PVDD18_S5_P0")
	)
	(via
		(at 332.4352 -158.0388)
		(size 0.508)
		(drill 0.254)
		(layers "F.Cu" "B.Cu")
		(net "PVDD18_S5_P0")
	)
	(via
		(at 344.681048 -250.964192)
		(size 0.4064)
		(drill 0.2032)
		(layers "F.Cu" "B.Cu")
		(net "PVDD18_S5_P0")
	)
	(via
		(at 135.184388 -52.793646)
		(size 0.508)
		(drill 0.254)
		(layers "F.Cu" "B.Cu")
		(net "PVDD18_S5_P0")
	)
	(via
		(at 183.007 -141.188948)
		(size 0.508)
		(drill 0.254)
		(layers "F.Cu" "B.Cu")
		(net "PVDD18_S5_P0")
	)
	(via
		(at 263.906 -140.97)
		(size 0.508)
		(drill 0.254)
		(layers "F.Cu" "B.Cu")
		(net "PVDD18_S5_P0")
	)
	(via
		(at 218.607132 -131.054094)
		(size 0.508)
		(drill 0.254)
		(layers "F.Cu" "B.Cu")
		(net "PVDD18_S5_P0")
	)
	(via
		(at 405.241252 -348.133162)
		(size 0.508)
		(drill 0.254)
		(layers "F.Cu" "B.Cu")
		(net "PVDD18_S5_P0")
	)
	(via
		(at 399.55978 -126.453138)
		(size 0.508)
		(drill 0.254)
		(layers "F.Cu" "B.Cu")
		(net "PVDD18_S5_P0")
	)
	(via
		(at 329.5396 -152.250902)
		(size 0.508)
		(drill 0.254)
		(layers "F.Cu" "B.Cu")
		(net "PVDD18_S5_P0")
	)
	(via
		(at 413.239712 -320.272918)
		(size 0.508)
		(drill 0.254)
		(layers "F.Cu" "B.Cu")
		(net "PVDD18_S5_P0")
	)
	(via
		(at 332.878176 -154.2034)
		(size 0.508)
		(drill 0.254)
		(layers "F.Cu" "B.Cu")
		(net "PVDD18_S5_P0")
	)
	(via
		(at 332.116176 -153.4414)
		(size 0.508)
		(drill 0.254)
		(layers "F.Cu" "B.Cu")
		(net "PVDD18_S5_P0")
	)
	(via
		(at 192.151 -138.648948)
		(size 0.508)
		(drill 0.254)
		(layers "F.Cu" "B.Cu")
		(net "PVDD18_S5_P0")
	)
	(via
		(at 250.845574 -103.716328)
		(size 0.508)
		(drill 0.254)
		(layers "F.Cu" "B.Cu")
		(net "PVDD18_S5_P0")
	)
	(via
		(at 135.519922 -102.64902)
		(size 0.508)
		(drill 0.254)
		(layers "F.Cu" "B.Cu")
		(net "PVDD18_S5_P0")
	)
	(via
		(at 272.982944 -100.819966)
		(size 0.508)
		(drill 0.254)
		(layers "F.Cu" "B.Cu")
		(net "PVDD18_S5_P0")
	)
	(via
		(at 398.928082 -203.226416)
		(size 0.508)
		(drill 0.254)
		(layers "F.Cu" "B.Cu")
		(net "PVDD18_S5_P0")
	)
	(via
		(at 272.32229 -100.814632)
		(size 0.508)
		(drill 0.254)
		(layers "F.Cu" "B.Cu")
		(net "PVDD18_S5_P0")
	)
	(via
		(at 336.642964 -152.454102)
		(size 0.508)
		(drill 0.254)
		(layers "F.Cu" "B.Cu")
		(net "PVDD18_S5_P0")
	)
	(via
		(at 401.32254 -329.2094)
		(size 0.508)
		(drill 0.254)
		(layers "F.Cu" "B.Cu")
		(net "PVDD18_S5_P0")
	)
	(via
		(at 321.735958 -203.958952)
		(size 0.508)
		(drill 0.254)
		(layers "F.Cu" "B.Cu")
		(net "PVDD18_S5_P0")
	)
	(via
		(at 407.834592 -365.07547)
		(size 0.508)
		(drill 0.254)
		(layers "F.Cu" "B.Cu")
		(net "PVDD18_S5_P0")
	)
	(via
		(at 413.313118 -362.804964)
		(size 0.508)
		(drill 0.254)
		(layers "F.Cu" "B.Cu")
		(net "PVDD18_S5_P0")
	)
	(via
		(at 346.561156 -255.824228)
		(size 0.4064)
		(drill 0.2032)
		(layers "F.Cu" "B.Cu")
		(net "PVDD18_S5_P0")
	)
	(via
		(at 250.08967 -103.75392)
		(size 0.508)
		(drill 0.254)
		(layers "F.Cu" "B.Cu")
		(net "PVDD18_S5_P0")
	)
	(via
		(at 400.897344 -345.250262)
		(size 0.508)
		(drill 0.254)
		(layers "F.Cu" "B.Cu")
		(net "PVDD18_S5_P0")
	)
	(via
		(at 334.8482 -158.0388)
		(size 0.508)
		(drill 0.254)
		(layers "F.Cu" "B.Cu")
		(net "PVDD18_S5_P0")
	)
	(via
		(at 332.116176 -154.9654)
		(size 0.508)
		(drill 0.254)
		(layers "F.Cu" "B.Cu")
		(net "PVDD18_S5_P0")
	)
	(via
		(at 332.429104 -152.191974)
		(size 0.508)
		(drill 0.254)
		(layers "F.Cu" "B.Cu")
		(net "PVDD18_S5_P0")
	)
	(via
		(at 430.015396 -140.49121)
		(size 0.508)
		(drill 0.254)
		(layers "F.Cu" "B.Cu")
		(net "PVDD18_S5_P0")
	)
	(via
		(at 413.874712 -320.272918)
		(size 0.508)
		(drill 0.254)
		(layers "F.Cu" "B.Cu")
		(net "PVDD18_S5_P0")
	)
	(via
		(at 242.29695 -228.727)
		(size 0.508)
		(drill 0.254)
		(layers "F.Cu" "B.Cu")
		(net "PVDD18_S5_P0")
	)
	(via
		(at 231.075738 -147.24253)
		(size 0.508)
		(drill 0.254)
		(layers "F.Cu" "B.Cu")
		(net "PVDD18_S5_P0")
	)
	(via
		(at 332.116176 -155.7274)
		(size 0.508)
		(drill 0.254)
		(layers "F.Cu" "B.Cu")
		(net "PVDD18_S5_P0")
	)
	(via
		(at 265.494516 -135.654796)
		(size 0.508)
		(drill 0.254)
		(layers "F.Cu" "B.Cu")
		(net "PVDD18_S5_P0")
	)
	(via
		(at 335.6102 -158.8008)
		(size 0.508)
		(drill 0.254)
		(layers "F.Cu" "B.Cu")
		(net "PVDD18_S5_P0")
	)
	(via
		(at 371.606318 -35.437572)
		(size 0.508)
		(drill 0.254)
		(layers "F.Cu" "B.Cu")
		(net "PVDD18_S5_P0")
	)
	(via
		(at 374.080278 -142.561056)
		(size 0.508)
		(drill 0.254)
		(layers "F.Cu" "B.Cu")
		(net "PVDD18_S5_P0")
	)
	(via
		(at 184.005982 -134.84098)
		(size 0.508)
		(drill 0.254)
		(layers "F.Cu" "B.Cu")
		(net "PVDD18_S5_P0")
	)
	(via
		(at 316.008258 -199.287892)
		(size 0.508)
		(drill 0.254)
		(layers "F.Cu" "B.Cu")
		(net "PVDD18_S5_P0")
	)
	(via
		(at 347.031056 -250.154186)
		(size 0.4064)
		(drill 0.2032)
		(layers "F.Cu" "B.Cu")
		(net "PVDD18_S5_P0")
	)
	(via
		(at 265.494516 -131.067556)
		(size 0.508)
		(drill 0.254)
		(layers "F.Cu" "B.Cu")
		(net "PVDD18_S5_P0")
	)
	(via
		(at 317.798958 -201.899012)
		(size 0.508)
		(drill 0.254)
		(layers "F.Cu" "B.Cu")
		(net "PVDD18_S5_P0")
	)
	(via
		(at 376.218958 -204.085952)
		(size 0.508)
		(drill 0.254)
		(layers "F.Cu" "B.Cu")
		(net "PVDD18_S5_P0")
	)
	(via
		(at 241.173 -225.171)
		(size 0.508)
		(drill 0.254)
		(layers "F.Cu" "B.Cu")
		(net "PVDD18_S5_P0")
	)
	(via
		(at 347.031056 -251.774198)
		(size 0.4064)
		(drill 0.2032)
		(layers "F.Cu" "B.Cu")
		(net "PVDD18_S5_P0")
	)
	(via
		(at 244.87505 -228.727)
		(size 0.508)
		(drill 0.254)
		(layers "F.Cu" "B.Cu")
		(net "PVDD18_S5_P0")
	)
	(via
		(at 265.494516 -133.622796)
		(size 0.508)
		(drill 0.254)
		(layers "F.Cu" "B.Cu")
		(net "PVDD18_S5_P0")
	)
	(via
		(at 233.934 -234.16895)
		(size 0.508)
		(drill 0.254)
		(layers "F.Cu" "B.Cu")
		(net "PVDD18_S5_P0")
	)
	(via
		(at 348.911164 -251.774198)
		(size 0.4064)
		(drill 0.2032)
		(layers "F.Cu" "B.Cu")
		(net "PVDD18_S5_P0")
	)
	(via
		(at 398.92478 -126.453138)
		(size 0.508)
		(drill 0.254)
		(layers "F.Cu" "B.Cu")
		(net "PVDD18_S5_P0")
	)
	(via
		(at 338.912454 -220.41231)
		(size 0.508)
		(drill 0.254)
		(layers "F.Cu" "B.Cu")
		(net "PVDD18_S5_P0")
	)
	(via
		(at 355.85781 -257.744976)
		(size 0.4826)
		(drill 0.254)
		(layers "F.Cu" "B.Cu")
		(net "PVDD18_S5_P0")
	)
	(via
		(at 344.332814 -307.511196)
		(size 0.508)
		(drill 0.254)
		(layers "F.Cu" "B.Cu")
		(net "PVDD18_S5_P0")
	)
	(via
		(at 338.125308 -306.445412)
		(size 0.508)
		(drill 0.254)
		(layers "F.Cu" "B.Cu")
		(net "PVDD18_S5_P0")
	)
	(via
		(at 293.887652 -148.919692)
		(size 0.508)
		(drill 0.254)
		(layers "F.Cu" "B.Cu")
		(net "PVDD18_S5_P0")
	)
	(via
		(at 389.42264 -58.7375)
		(size 0.508)
		(drill 0.254)
		(layers "F.Cu" "B.Cu")
		(net "PVDD18_S5_P0")
	)
	(via
		(at 293.15283 -148.168106)
		(size 0.508)
		(drill 0.254)
		(layers "F.Cu" "B.Cu")
		(net "PVDD18_S5_P0")
	)
	(via
		(at 314.517278 -198.050912)
		(size 0.508)
		(drill 0.254)
		(layers "F.Cu" "B.Cu")
		(net "PVDD18_S5_P0")
	)
	(via
		(at 212.221826 -147.334224)
		(size 0.508)
		(drill 0.254)
		(layers "F.Cu" "B.Cu")
		(net "PVDD18_S5_P0")
	)
	(via
		(at 399.415508 -64.5795)
		(size 0.508)
		(drill 0.254)
		(layers "F.Cu" "B.Cu")
		(net "PVDD18_S5_P0")
	)
	(via
		(at 332.878176 -153.4414)
		(size 0.508)
		(drill 0.254)
		(layers "F.Cu" "B.Cu")
		(net "PVDD18_S5_P0")
	)
	(via
		(at 333.640176 -154.2034)
		(size 0.508)
		(drill 0.254)
		(layers "F.Cu" "B.Cu")
		(net "PVDD18_S5_P0")
	)
	(via
		(at 241.596926 -231.24795)
		(size 0.508)
		(drill 0.254)
		(layers "F.Cu" "B.Cu")
		(net "PVDD18_S5_P0")
	)
	(via
		(at 433.063396 -140.49121)
		(size 0.508)
		(drill 0.254)
		(layers "F.Cu" "B.Cu")
		(net "PVDD18_S5_P0")
	)
	(via
		(at 345.151202 -255.014222)
		(size 0.4064)
		(drill 0.2032)
		(layers "F.Cu" "B.Cu")
		(net "PVDD18_S5_P0")
	)
	(via
		(at 348.44101 -252.584204)
		(size 0.4064)
		(drill 0.2032)
		(layers "F.Cu" "B.Cu")
		(net "PVDD18_S5_P0")
	)
	(via
		(at 336.642964 -151.692102)
		(size 0.508)
		(drill 0.254)
		(layers "F.Cu" "B.Cu")
		(net "PVDD18_S5_P0")
	)
	(via
		(at 255.576324 -129.617216)
		(size 0.508)
		(drill 0.254)
		(layers "F.Cu" "B.Cu")
		(net "PVDD18_S5_P0")
	)
	(via
		(at 390.5123 -57.478422)
		(size 0.508)
		(drill 0.254)
		(layers "F.Cu" "B.Cu")
		(net "PVDD18_S5_P0")
	)
	(via
		(at 328.243438 -166.930324)
		(size 0.508)
		(drill 0.254)
		(layers "F.Cu" "B.Cu")
		(net "PVDD18_S5_P0")
	)
	(via
		(at 370.82476 -262.745982)
		(size 0.4064)
		(drill 0.2032)
		(layers "F.Cu" "B.Cu")
		(net "PVDD18_S5_P0")
	)
	(via
		(at 318.765174 -200.044812)
		(size 0.508)
		(drill 0.254)
		(layers "F.Cu" "B.Cu")
		(net "PVDD18_S5_P0")
	)
	(via
		(at 333.640176 -156.4894)
		(size 0.508)
		(drill 0.254)
		(layers "F.Cu" "B.Cu")
		(net "PVDD18_S5_P0")
	)
	(via
		(at 405.501348 -58.36666)
		(size 0.508)
		(drill 0.254)
		(layers "F.Cu" "B.Cu")
		(net "PVDD18_S5_P0")
	)
	(via
		(at 339.801454 -220.41231)
		(size 0.508)
		(drill 0.254)
		(layers "F.Cu" "B.Cu")
		(net "PVDD18_S5_P0")
	)
	(via
		(at 123.810268 -56.737758)
		(size 0.508)
		(drill 0.254)
		(layers "F.Cu" "B.Cu")
		(net "PVDD18_S5_P0")
	)
	(via
		(at 334.8482 -157.2768)
		(size 0.508)
		(drill 0.254)
		(layers "F.Cu" "B.Cu")
		(net "PVDD18_S5_P0")
	)
	(via
		(at 407.76144 -328.82713)
		(size 0.508)
		(drill 0.254)
		(layers "F.Cu" "B.Cu")
		(net "PVDD18_S5_P0")
	)
	(via
		(at 243.919502 -346.114116)
		(size 0.508)
		(drill 0.254)
		(layers "F.Cu" "B.Cu")
		(net "PVDD18_S5_P0")
	)
	(via
		(at 335.6102 -158.0388)
		(size 0.508)
		(drill 0.254)
		(layers "F.Cu" "B.Cu")
		(net "PVDD18_S5_P0")
	)
	(via
		(at 363.008926 -27.257502)
		(size 0.508)
		(drill 0.254)
		(layers "F.Cu" "B.Cu")
		(net "PVDD18_S5_P0")
	)
	(via
		(at 348.44101 -254.204216)
		(size 0.4064)
		(drill 0.2032)
		(layers "F.Cu" "B.Cu")
		(net "PVDD18_S5_P0")
	)
	(via
		(at 340.690454 -220.41231)
		(size 0.508)
		(drill 0.254)
		(layers "F.Cu" "B.Cu")
		(net "PVDD18_S5_P0")
	)
	(via
		(at 285.56458 -102.77856)
		(size 0.508)
		(drill 0.254)
		(layers "F.Cu" "B.Cu")
		(net "PVDD18_S5_P0")
	)
	(via
		(at 334.8482 -158.8008)
		(size 0.508)
		(drill 0.254)
		(layers "F.Cu" "B.Cu")
		(net "PVDD18_S5_P0")
	)
	(via
		(at 338.830158 -310.428132)
		(size 0.508)
		(drill 0.254)
		(layers "F.Cu" "B.Cu")
		(net "PVDD18_S5_P0")
	)
	(via
		(at 395.619986 -322.35013)
		(size 0.508)
		(drill 0.254)
		(layers "F.Cu" "B.Cu")
		(net "PVDD18_S5_P0")
	)
	(via
		(at 332.878176 -155.7274)
		(size 0.508)
		(drill 0.254)
		(layers "F.Cu" "B.Cu")
		(net "PVDD18_S5_P0")
	)
	(via
		(at 393.985496 -203.527406)
		(size 0.508)
		(drill 0.254)
		(layers "F.Cu" "B.Cu")
		(net "PVDD18_S5_P0")
	)
	(via
		(at 387.957568 -60.456318)
		(size 0.508)
		(drill 0.254)
		(layers "F.Cu" "B.Cu")
		(net "PVDD18_S5_P0")
	)
	(via
		(at 300.482 -361.4166)
		(size 0.508)
		(drill 0.254)
		(layers "F.Cu" "B.Cu")
		(net "PVDD18_S5_P0")
	)
	(via
		(at 424.815254 -359.836212)
		(size 0.508)
		(drill 0.254)
		(layers "F.Cu" "B.Cu")
		(net "PVDD18_S5_P0")
	)
	(via
		(at 347.031056 -255.014222)
		(size 0.4064)
		(drill 0.2032)
		(layers "F.Cu" "B.Cu")
		(net "PVDD18_S5_P0")
	)
	(via
		(at 328.93 -166.4208)
		(size 0.508)
		(drill 0.254)
		(layers "F.Cu" "B.Cu")
		(net "PVDD18_S5_P0")
	)
	(via
		(at 346.561156 -254.204216)
		(size 0.4064)
		(drill 0.2032)
		(layers "F.Cu" "B.Cu")
		(net "PVDD18_S5_P0")
	)
	(via
		(at 332.878176 -156.4894)
		(size 0.508)
		(drill 0.254)
		(layers "F.Cu" "B.Cu")
		(net "PVDD18_S5_P0")
	)
	(via
		(at 256.49301 -102.843584)
		(size 0.508)
		(drill 0.254)
		(layers "F.Cu" "B.Cu")
		(net "PVDD18_S5_P0")
	)
	(via
		(at 392.118088 -315.218064)
		(size 0.508)
		(drill 0.254)
		(layers "F.Cu" "B.Cu")
		(net "PVDD18_S5_P0")
	)
	(via
		(at 238.993426 -327.698608)
		(size 0.508)
		(drill 0.254)
		(layers "F.Cu" "B.Cu")
		(net "PVDD18_S5_P0")
	)
	(via
		(at 335.6102 -157.2768)
		(size 0.508)
		(drill 0.254)
		(layers "F.Cu" "B.Cu")
		(net "PVDD18_S5_P0")
	)
	(via
		(at 122.0978 -52.8828)
		(size 0.508)
		(drill 0.254)
		(layers "F.Cu" "B.Cu")
		(net "PVDD18_S5_P0")
	)
	(via
		(at 333.640176 -155.7274)
		(size 0.508)
		(drill 0.254)
		(layers "F.Cu" "B.Cu")
		(net "PVDD18_S5_P0")
	)
	(via
		(at 230.303324 -155.971748)
		(size 0.508)
		(drill 0.254)
		(layers "F.Cu" "B.Cu")
		(net "PVDD18_S5_P0")
	)
	(via
		(at 344.681048 -249.34418)
		(size 0.4064)
		(drill 0.2032)
		(layers "F.Cu" "B.Cu")
		(net "PVDD18_S5_P0")
	)
	(via
		(at 369.309396 -44.301156)
		(size 0.508)
		(drill 0.254)
		(layers "F.Cu" "B.Cu")
		(net "PVDD18_S5_P0")
	)
	(via
		(at 265.9888 -137.94486)
		(size 0.508)
		(drill 0.254)
		(layers "F.Cu" "B.Cu")
		(net "PVDD18_S5_P0")
	)
	(via
		(at 365.701326 -46.283118)
		(size 0.508)
		(drill 0.254)
		(layers "F.Cu" "B.Cu")
		(net "PVDD18_S5_P0")
	)
	(via
		(at 346.561156 -250.964192)
		(size 0.4064)
		(drill 0.2032)
		(layers "F.Cu" "B.Cu")
		(net "PVDD18_S5_P0")
	)
	(via
		(at 404.11527 -327.378568)
		(size 0.508)
		(drill 0.254)
		(layers "F.Cu" "B.Cu")
		(net "PVDD18_S5_P0")
	)
	(via
		(at 332.4352 -157.2768)
		(size 0.508)
		(drill 0.254)
		(layers "F.Cu" "B.Cu")
		(net "PVDD18_S5_P0")
	)
	(via
		(at 192.558162 -141.445742)
		(size 0.508)
		(drill 0.254)
		(layers "F.Cu" "B.Cu")
		(net "PVDD18_S5_P0")
	)
	(via
		(at 293.887652 -148.157692)
		(size 0.508)
		(drill 0.254)
		(layers "F.Cu" "B.Cu")
		(net "PVDD18_S5_P0")
	)
	(via
		(at 332.878176 -154.9654)
		(size 0.508)
		(drill 0.254)
		(layers "F.Cu" "B.Cu")
		(net "PVDD18_S5_P0")
	)
	(via
		(at 145.142458 -55.313834)
		(size 0.508)
		(drill 0.254)
		(layers "F.Cu" "B.Cu")
		(net "PVDD18_S5_P0")
	)
	(via
		(at 403.563328 -322.347082)
		(size 0.508)
		(drill 0.254)
		(layers "F.Cu" "B.Cu")
		(net "PVDD18_S5_P0")
	)
	(via
		(at 404.914608 -325.774812)
		(size 0.508)
		(drill 0.254)
		(layers "F.Cu" "B.Cu")
		(net "PVDD18_S5_P0")
	)
	(via
		(at 332.528164 -152.835102)
		(size 0.508)
		(drill 0.254)
		(layers "F.Cu" "B.Cu")
		(net "PVDD18_S5_P0")
	)
	(via
		(at 394.80744 -52.641754)
		(size 0.508)
		(drill 0.254)
		(layers "F.Cu" "B.Cu")
		(net "PVDD18_S5_P0")
	)
	(via
		(at 402.985478 -331.345286)
		(size 0.508)
		(drill 0.254)
		(layers "F.Cu" "B.Cu")
		(net "PVDD18_S5_P0")
	)
	(via
		(at 261.874 -144.399)
		(size 0.508)
		(drill 0.254)
		(layers "F.Cu" "B.Cu")
		(net "PVDD18_S5_P0")
	)
	(via
		(at 318.2874 -359.029)
		(size 0.508)
		(drill 0.254)
		(layers "F.Cu" "B.Cu")
		(net "PVDD18_S5_P0")
	)
	(segment
		(start 325.799958 -201.713846)
		(end 318.423036 -201.713846)
		(width 0.381)
		(layer "B.Cu")
		(net "PVDD18_S5_P0")
	)
	(segment
		(start 402.722588 -321.179952)
		(end 402.722588 -320.189352)
		(width 0.508)
		(layer "B.Cu")
		(net "PVDD18_S5_P0")
	)
	(segment
		(start 318.769238 -198.116952)
		(end 319.235582 -198.583296)
		(width 0.508)
		(layer "B.Cu")
		(net "PVDD18_S5_P0")
	)
	(segment
		(start 378.504958 -208.130902)
		(end 377.488958 -208.130902)
		(width 0.508)
		(layer "B.Cu")
		(net "PVDD18_S5_P0")
	)
	(segment
		(start 271.25168 -364.856014)
		(end 257.584194 -351.188528)
		(width 0.508)
		(layer "B.Cu")
		(net "PVDD18_S5_P0")
	)
	(segment
		(start 405.02078 -362.9025)
		(end 399.55216 -368.37112)
		(width 0.508)
		(layer "B.Cu")
		(net "PVDD18_S5_P0")
	)
	(segment
		(start 405.241252 -348.795594)
		(end 405.241252 -348.133162)
		(width 0.508)
		(layer "B.Cu")
		(net "PVDD18_S5_P0")
	)
	(segment
		(start 395.254734 -203.479908)
		(end 396.218918 -203.479908)
		(width 0.3556)
		(layer "B.Cu")
		(net "PVDD18_S5_P0")
	)
	(segment
		(start 402.843238 -348.817692)
		(end 402.844 -348.818454)
		(width 0.508)
		(layer "B.Cu")
		(net "PVDD18_S5_P0")
	)
	(segment
		(start 402.985478 -331.1398)
		(end 402.985478 -331.345286)
		(width 0.508)
		(layer "B.Cu")
		(net "PVDD18_S5_P0")
	)
	(segment
		(start 318.765174 -200.044812)
		(end 322.312538 -200.044812)
		(width 0.381)
		(layer "B.Cu")
		(net "PVDD18_S5_P0")
	)
	(segment
		(start 241.173 -224.42805)
		(end 241.173 -225.171)
		(width 0.381)
		(layer "B.Cu")
		(net "PVDD18_S5_P0")
	)
	(segment
		(start 213.292436 -137.27938)
		(end 214.653876 -135.91794)
		(width 0.508)
		(layer "B.Cu")
		(net "PVDD18_S5_P0")
	)
	(segment
		(start 248.993914 -351.188528)
		(end 243.919502 -346.114116)
		(width 0.508)
		(layer "B.Cu")
		(net "PVDD18_S5_P0")
	)
	(segment
		(start 408.660854 -326.453754)
		(end 407.788618 -325.581518)
		(width 0.381)
		(layer "B.Cu")
		(net "PVDD18_S5_P0")
	)
	(segment
		(start 316.008258 -198.843392)
		(end 316.734698 -198.116952)
		(width 0.508)
		(layer "B.Cu")
		(net "PVDD18_S5_P0")
	)
	(segment
		(start 230.003604 -151.042878)
		(end 229.98303 -151.063452)
		(width 0.508)
		(layer "B.Cu")
		(net "PVDD18_S5_P0")
	)
	(segment
		(start 227.589588 -152.141936)
		(end 227.589588 -155.857702)
		(width 0.508)
		(layer "B.Cu")
		(net "PVDD18_S5_P0")
	)
	(segment
		(start 320.446908 -198.583296)
		(end 320.446908 -197.567296)
		(width 0.381)
		(layer "B.Cu")
		(net "PVDD18_S5_P0")
	)
	(segment
		(start 403.563328 -322.347082)
		(end 403.48535 -322.269104)
		(width 0.508)
		(layer "B.Cu")
		(net "PVDD18_S5_P0")
	)
	(segment
		(start 407.099008 -324.862952)
		(end 407.099008 -323.846952)
		(width 0.381)
		(layer "B.Cu")
		(net "PVDD18_S5_P0")
	)
	(segment
		(start 182.499 -145.94205)
		(end 183.439054 -146.882104)
		(width 0.381)
		(layer "B.Cu")
		(net "PVDD18_S5_P0")
	)
	(segment
		(start 400.98726 -325.96074)
		(end 400.611848 -326.336152)
		(width 0.381)
		(layer "B.Cu")
		(net "PVDD18_S5_P0")
	)
	(segment
		(start 193.171318 -140.832586)
		(end 192.558162 -141.445742)
		(width 0.508)
		(layer "B.Cu")
		(net "PVDD18_S5_P0")
	)
	(segment
		(start 374.080278 -142.561056)
		(end 373.410226 -142.561056)
		(width 0.254)
		(layer "B.Cu")
		(net "PVDD18_S5_P0")
	)
	(segment
		(start 335.89468 -171.964858)
		(end 337.218274 -173.288452)
		(width 0.508)
		(layer "B.Cu")
		(net "PVDD18_S5_P0")
	)
	(segment
		(start 242.29695 -229.489)
		(end 242.29695 -228.727)
		(width 0.381)
		(layer "B.Cu")
		(net "PVDD18_S5_P0")
	)
	(segment
		(start 407.788618 -325.370952)
		(end 407.280618 -324.862952)
		(width 0.381)
		(layer "B.Cu")
		(net "PVDD18_S5_P0")
	)
	(segment
		(start 399.55216 -368.37112)
		(end 323.4944 -368.37112)
		(width 0.508)
		(layer "B.Cu")
		(net "PVDD18_S5_P0")
	)
	(segment
		(start 274.50288 -364.856014)
		(end 271.25168 -364.856014)
		(width 0.508)
		(layer "B.Cu")
		(net "PVDD18_S5_P0")
	)
	(segment
		(start 236.118146 -146.431254)
		(end 236.323124 -146.636232)
		(width 0.508)
		(layer "B.Cu")
		(net "PVDD18_S5_P0")
	)
	(segment
		(start 407.788618 -325.581518)
		(end 407.788618 -325.370952)
		(width 0.381)
		(layer "B.Cu")
		(net "PVDD18_S5_P0")
	)
	(segment
		(start 400.611848 -326.336152)
		(end 400.611848 -326.666352)
		(width 0.381)
		(layer "B.Cu")
		(net "PVDD18_S5_P0")
	)
	(segment
		(start 242.535964 -225.314002)
		(end 242.535964 -225.00971)
		(width 0.381)
		(layer "B.Cu")
		(net "PVDD18_S5_P0")
	)
	(segment
		(start 326.815958 -201.713846)
		(end 325.799958 -201.713846)
		(width 0.381)
		(layer "B.Cu")
		(net "PVDD18_S5_P0")
	)
	(segment
		(start 275.710396 -366.06353)
		(end 274.50288 -364.856014)
		(width 0.508)
		(layer "B.Cu")
		(net "PVDD18_S5_P0")
	)
	(segment
		(start 300.482 -359.39095)
		(end 300.482 -361.4166)
		(width 0.508)
		(layer "B.Cu")
		(net "PVDD18_S5_P0")
	)
	(segment
		(start 300.482 -361.4166)
		(end 298.752768 -361.4166)
		(width 0.508)
		(layer "B.Cu")
		(net "PVDD18_S5_P0")
	)
	(segment
		(start 304.292 -361.061)
		(end 304.4952 -361.061)
		(width 0.4572)
		(layer "B.Cu")
		(net "PVDD18_S5_P0")
	)
	(segment
		(start 401.554696 -345.250262)
		(end 403.250654 -345.250262)
		(width 0.381)
		(layer "B.Cu")
		(net "PVDD18_S5_P0")
	)
	(segment
		(start 242.535964 -225.00971)
		(end 241.954304 -224.42805)
		(width 0.381)
		(layer "B.Cu")
		(net "PVDD18_S5_P0")
	)
	(segment
		(start 407.280618 -324.862952)
		(end 407.099008 -324.862952)
		(width 0.381)
		(layer "B.Cu")
		(net "PVDD18_S5_P0")
	)
	(segment
		(start 322.177664 -203.517246)
		(end 321.735958 -203.958952)
		(width 0.381)
		(layer "B.Cu")
		(net "PVDD18_S5_P0")
	)
	(segment
		(start 321.59956 -366.47628)
		(end 321.59956 -362.50753)
		(width 0.508)
		(layer "B.Cu")
		(net "PVDD18_S5_P0")
	)
	(segment
		(start 394.570458 -321.785996)
		(end 395.238732 -321.785996)
		(width 0.381)
		(layer "B.Cu")
		(net "PVDD18_S5_P0")
	)
	(segment
		(start 337.218274 -183.93029)
		(end 357.260906 -203.972922)
		(width 0.508)
		(layer "B.Cu")
		(net "PVDD18_S5_P0")
	)
	(segment
		(start 338.734908 -306.828952)
		(end 338.508848 -306.828952)
		(width 0.381)
		(layer "B.Cu")
		(net "PVDD18_S5_P0")
	)
	(segment
		(start 428.22495 -31.181548)
		(end 427.97095 -31.435548)
		(width 0.4064)
		(layer "B.Cu")
		(net "PVDD18_S5_P0")
	)
	(segment
		(start 322.986908 -199.980296)
		(end 322.986908 -198.964296)
		(width 0.381)
		(layer "B.Cu")
		(net "PVDD18_S5_P0")
	)
	(segment
		(start 233.172 -234.16895)
		(end 232.30205 -234.16895)
		(width 0.381)
		(layer "B.Cu")
		(net "PVDD18_S5_P0")
	)
	(segment
		(start 393.781534 -203.983336)
		(end 393.985496 -203.779374)
		(width 0.3556)
		(layer "B.Cu")
		(net "PVDD18_S5_P0")
	)
	(segment
		(start 401.212558 -330.865988)
		(end 401.212558 -330.090272)
		(width 0.381)
		(layer "B.Cu")
		(net "PVDD18_S5_P0")
	)
	(segment
		(start 231.075738 -159.343852)
		(end 231.075738 -159.620204)
		(width 0.508)
		(layer "B.Cu")
		(net "PVDD18_S5_P0")
	)
	(segment
		(start 394.160502 -322.195952)
		(end 394.570458 -321.785996)
		(width 0.381)
		(layer "B.Cu")
		(net "PVDD18_S5_P0")
	)
	(segment
		(start 402.844 -348.818454)
		(end 404.041102 -348.818454)
		(width 0.508)
		(layer "B.Cu")
		(net "PVDD18_S5_P0")
	)
	(segment
		(start 322.312538 -200.044812)
		(end 322.377054 -199.980296)
		(width 0.381)
		(layer "B.Cu")
		(net "PVDD18_S5_P0")
	)
	(segment
		(start 316.734698 -198.116952)
		(end 318.769238 -198.116952)
		(width 0.508)
		(layer "B.Cu")
		(net "PVDD18_S5_P0")
	)
	(segment
		(start 395.619986 -322.16725)
		(end 395.619986 -322.35013)
		(width 0.381)
		(layer "B.Cu")
		(net "PVDD18_S5_P0")
	)
	(segment
		(start 404.381208 -327.644506)
		(end 404.11527 -327.378568)
		(width 0.381)
		(layer "B.Cu")
		(net "PVDD18_S5_P0")
	)
	(segment
		(start 317.399924 -359.508806)
		(end 317.87973 -359.029)
		(width 0.508)
		(layer "B.Cu")
		(net "PVDD18_S5_P0")
	)
	(segment
		(start 238.30153 -327.698608)
		(end 238.993426 -327.698608)
		(width 0.381)
		(layer "B.Cu")
		(net "PVDD18_S5_P0")
	)
	(segment
		(start 403.48535 -322.269104)
		(end 403.48535 -321.517772)
		(width 0.508)
		(layer "B.Cu")
		(net "PVDD18_S5_P0")
	)
	(segment
		(start 241.954304 -224.42805)
		(end 241.173 -224.42805)
		(width 0.381)
		(layer "B.Cu")
		(net "PVDD18_S5_P0")
	)
	(segment
		(start 397.193008 -326.163432)
		(end 397.193008 -327.519792)
		(width 0.381)
		(layer "B.Cu")
		(net "PVDD18_S5_P0")
	)
	(segment
		(start 316.581282 -195.662296)
		(end 314.517278 -197.7263)
		(width 0.508)
		(layer "B.Cu")
		(net "PVDD18_S5_P0")
	)
	(segment
		(start 227.589588 -155.857702)
		(end 231.075738 -159.343852)
		(width 0.508)
		(layer "B.Cu")
		(net "PVDD18_S5_P0")
	)
	(segment
		(start 404.584408 -330.449682)
		(end 403.675596 -330.449682)
		(width 0.508)
		(layer "B.Cu")
		(net "PVDD18_S5_P0")
	)
	(segment
		(start 373.410226 -142.561056)
		(end 373.337328 -142.488158)
		(width 0.254)
		(layer "B.Cu")
		(net "PVDD18_S5_P0")
	)
	(segment
		(start 403.675596 -330.449682)
		(end 402.985478 -331.1398)
		(width 0.508)
		(layer "B.Cu")
		(net "PVDD18_S5_P0")
	)
	(segment
		(start 407.999438 -364.524544)
		(end 406.377394 -362.9025)
		(width 0.508)
		(layer "B.Cu")
		(net "PVDD18_S5_P0")
	)
	(segment
		(start 190.114428 -140.86459)
		(end 190.114428 -141.49959)
		(width 0.508)
		(layer "B.Cu")
		(net "PVDD18_S5_P0")
	)
	(segment
		(start 240.411 -231.24795)
		(end 241.596926 -231.24795)
		(width 0.381)
		(layer "B.Cu")
		(net "PVDD18_S5_P0")
	)
	(segment
		(start 401.554696 -345.250262)
		(end 400.897344 -345.250262)
		(width 0.381)
		(layer "B.Cu")
		(net "PVDD18_S5_P0")
	)
	(segment
		(start 322.377054 -199.980296)
		(end 322.986908 -199.980296)
		(width 0.381)
		(layer "B.Cu")
		(net "PVDD18_S5_P0")
	)
	(segment
		(start 314.517278 -197.7263)
		(end 314.517278 -198.050912)
		(width 0.508)
		(layer "B.Cu")
		(net "PVDD18_S5_P0")
	)
	(segment
		(start 210.521042 -140.784326)
		(end 213.292436 -138.012932)
		(width 0.508)
		(layer "B.Cu")
		(net "PVDD18_S5_P0")
	)
	(segment
		(start 183.732678 -134.84098)
		(end 183.364886 -134.473188)
		(width 0.508)
		(layer "B.Cu")
		(net "PVDD18_S5_P0")
	)
	(segment
		(start 401.212558 -330.090272)
		(end 401.32254 -329.98029)
		(width 0.381)
		(layer "B.Cu")
		(net "PVDD18_S5_P0")
	)
	(segment
		(start 337.218274 -173.288452)
		(end 337.218274 -183.93029)
		(width 0.508)
		(layer "B.Cu")
		(net "PVDD18_S5_P0")
	)
	(segment
		(start 218.607132 -134.609078)
		(end 218.607132 -131.054094)
		(width 0.508)
		(layer "B.Cu")
		(net "PVDD18_S5_P0")
	)
	(segment
		(start 401.619974 -348.817692)
		(end 402.843238 -348.817692)
		(width 0.508)
		(layer "B.Cu")
		(net "PVDD18_S5_P0")
	)
	(segment
		(start 319.235582 -198.583296)
		(end 320.446908 -198.583296)
		(width 0.381)
		(layer "B.Cu")
		(net "PVDD18_S5_P0")
	)
	(segment
		(start 228.05136 -151.680164)
		(end 227.589588 -152.141936)
		(width 0.508)
		(layer "B.Cu")
		(net "PVDD18_S5_P0")
	)
	(segment
		(start 338.508848 -306.828952)
		(end 338.125308 -306.445412)
		(width 0.381)
		(layer "B.Cu")
		(net "PVDD18_S5_P0")
	)
	(segment
		(start 393.985496 -203.779374)
		(end 393.985496 -203.527406)
		(width 0.3556)
		(layer "B.Cu")
		(net "PVDD18_S5_P0")
	)
	(segment
		(start 377.488958 -207.903064)
		(end 377.932442 -207.45958)
		(width 0.381)
		(layer "B.Cu")
		(net "PVDD18_S5_P0")
	)
	(segment
		(start 294.105838 -366.06353)
		(end 275.710396 -366.06353)
		(width 0.508)
		(layer "B.Cu")
		(net "PVDD18_S5_P0")
	)
	(segment
		(start 397.193008 -327.519792)
		(end 396.946628 -327.766172)
		(width 0.381)
		(layer "B.Cu")
		(net "PVDD18_S5_P0")
	)
	(segment
		(start 214.76081 -135.811006)
		(end 217.405204 -135.811006)
		(width 0.508)
		(layer "B.Cu")
		(net "PVDD18_S5_P0")
	)
	(segment
		(start 335.89468 -166.844218)
		(end 335.89468 -171.964858)
		(width 0.508)
		(layer "B.Cu")
		(net "PVDD18_S5_P0")
	)
	(segment
		(start 381.552958 -208.130902)
		(end 381.552958 -207.521302)
		(width 0.381)
		(layer "B.Cu")
		(net "PVDD18_S5_P0")
	)
	(segment
		(start 357.260906 -203.972922)
		(end 369.522502 -203.972922)
		(width 0.508)
		(layer "B.Cu")
		(net "PVDD18_S5_P0")
	)
	(segment
		(start 229.98303 -151.063452)
		(end 229.98303 -151.449278)
		(width 0.508)
		(layer "B.Cu")
		(net "PVDD18_S5_P0")
	)
	(segment
		(start 244.87505 -229.489)
		(end 244.87505 -228.727)
		(width 0.381)
		(layer "B.Cu")
		(net "PVDD18_S5_P0")
	)
	(segment
		(start 404.381208 -327.987152)
		(end 404.381208 -327.644506)
		(width 0.381)
		(layer "B.Cu")
		(net "PVDD18_S5_P0")
	)
	(segment
		(start 406.377394 -362.9025)
		(end 405.02078 -362.9025)
		(width 0.508)
		(layer "B.Cu")
		(net "PVDD18_S5_P0")
	)
	(segment
		(start 398.2974 -327.766172)
		(end 396.946628 -327.766172)
		(width 0.381)
		(layer "B.Cu")
		(net "PVDD18_S5_P0")
	)
	(segment
		(start 317.399924 -360.780838)
		(end 317.399924 -359.508806)
		(width 0.508)
		(layer "B.Cu")
		(net "PVDD18_S5_P0")
	)
	(segment
		(start 183.439054 -146.882104)
		(end 183.439054 -147.143724)
		(width 0.381)
		(layer "B.Cu")
		(net "PVDD18_S5_P0")
	)
	(segment
		(start 217.405204 -135.811006)
		(end 218.607132 -134.609078)
		(width 0.508)
		(layer "B.Cu")
		(net "PVDD18_S5_P0")
	)
	(segment
		(start 298.752768 -361.4166)
		(end 294.105838 -366.06353)
		(width 0.508)
		(layer "B.Cu")
		(net "PVDD18_S5_P0")
	)
	(segment
		(start 398.420082 -202.324208)
		(end 398.928082 -202.832208)
		(width 0.508)
		(layer "B.Cu")
		(net "PVDD18_S5_P0")
	)
	(segment
		(start 369.522502 -203.972922)
		(end 373.680482 -208.130902)
		(width 0.508)
		(layer "B.Cu")
		(net "PVDD18_S5_P0")
	)
	(segment
		(start 407.099008 -329.942952)
		(end 407.099008 -328.926952)
		(width 0.381)
		(layer "B.Cu")
		(net "PVDD18_S5_P0")
	)
	(segment
		(start 231.075738 -146.850354)
		(end 232.145332 -145.78076)
		(width 0.508)
		(layer "B.Cu")
		(net "PVDD18_S5_P0")
	)
	(segment
		(start 232.145332 -145.78076)
		(end 235.84027 -145.78076)
		(width 0.508)
		(layer "B.Cu")
		(net "PVDD18_S5_P0")
	)
	(segment
		(start 301.73295 -355.854)
		(end 301.73295 -356.997)
		(width 0.508)
		(layer "B.Cu")
		(net "PVDD18_S5_P0")
	)
	(segment
		(start 317.87973 -359.029)
		(end 318.2874 -359.029)
		(width 0.508)
		(layer "B.Cu")
		(net "PVDD18_S5_P0")
	)
	(segment
		(start 398.928082 -202.832208)
		(end 398.928082 -203.226416)
		(width 0.508)
		(layer "B.Cu")
		(net "PVDD18_S5_P0")
	)
	(segment
		(start 304.01895 -360.426)
		(end 304.01895 -360.78795)
		(width 0.4572)
		(layer "B.Cu")
		(net "PVDD18_S5_P0")
	)
	(segment
		(start 321.59956 -362.50753)
		(end 319.999868 -360.907838)
		(width 0.508)
		(layer "B.Cu")
		(net "PVDD18_S5_P0")
	)
	(segment
		(start 405.220932 -348.815914)
		(end 405.241252 -348.795594)
		(width 0.508)
		(layer "B.Cu")
		(net "PVDD18_S5_P0")
	)
	(segment
		(start 233.934 -234.16895)
		(end 233.172 -234.16895)
		(width 0.381)
		(layer "B.Cu")
		(net "PVDD18_S5_P0")
	)
	(segment
		(start 401.11807 -330.960476)
		(end 401.212558 -330.865988)
		(width 0.381)
		(layer "B.Cu")
		(net "PVDD18_S5_P0")
	)
	(segment
		(start 406.312878 -348.809564)
		(end 405.255222 -348.809564)
		(width 0.508)
		(layer "B.Cu")
		(net "PVDD18_S5_P0")
	)
	(segment
		(start 377.234958 -204.701902)
		(end 377.234958 -204.085952)
		(width 0.381)
		(layer "B.Cu")
		(net "PVDD18_S5_P0")
	)
	(segment
		(start 301.73295 -354.711)
		(end 301.73295 -355.854)
		(width 0.508)
		(layer "B.Cu")
		(net "PVDD18_S5_P0")
	)
	(segment
		(start 319.861438 -203.166726)
		(end 319.861438 -202.891136)
		(width 0.381)
		(layer "B.Cu")
		(net "PVDD18_S5_P0")
	)
	(segment
		(start 377.488958 -208.130902)
		(end 377.488958 -207.903064)
		(width 0.381)
		(layer "B.Cu")
		(net "PVDD18_S5_P0")
	)
	(segment
		(start 428.5869 -37.023548)
		(end 427.97095 -37.023548)
		(width 0.4064)
		(layer "B.Cu")
		(net "PVDD18_S5_P0")
	)
	(segment
		(start 395.254734 -203.479908)
		(end 395.252194 -203.482448)
		(width 0.3556)
		(layer "B.Cu")
		(net "PVDD18_S5_P0")
	)
	(segment
		(start 405.255222 -348.809564)
		(end 405.241252 -348.795594)
		(width 0.508)
		(layer "B.Cu")
		(net "PVDD18_S5_P0")
	)
	(segment
		(start 319.999868 -360.907838)
		(end 317.526924 -360.907838)
		(width 0.508)
		(layer "B.Cu")
		(net "PVDD18_S5_P0")
	)
	(segment
		(start 231.075738 -147.24253)
		(end 231.075738 -146.850354)
		(width 0.508)
		(layer "B.Cu")
		(net "PVDD18_S5_P0")
	)
	(segment
		(start 344.332814 -307.511196)
		(end 344.361008 -307.483002)
		(width 0.381)
		(layer "B.Cu")
		(net "PVDD18_S5_P0")
	)
	(segment
		(start 404.041102 -348.818454)
		(end 404.043642 -348.815914)
		(width 0.508)
		(layer "B.Cu")
		(net "PVDD18_S5_P0")
	)
	(segment
		(start 318.23787 -201.899012)
		(end 317.798958 -201.899012)
		(width 0.381)
		(layer "B.Cu")
		(net "PVDD18_S5_P0")
	)
	(segment
		(start 395.254734 -202.829668)
		(end 395.254734 -203.479908)
		(width 0.3556)
		(layer "B.Cu")
		(net "PVDD18_S5_P0")
	)
	(segment
		(start 408.660854 -326.615298)
		(end 408.660854 -326.453754)
		(width 0.381)
		(layer "B.Cu")
		(net "PVDD18_S5_P0")
	)
	(segment
		(start 404.043642 -348.815914)
		(end 405.220932 -348.815914)
		(width 0.508)
		(layer "B.Cu")
		(net "PVDD18_S5_P0")
	)
	(segment
		(start 428.5869 -31.181548)
		(end 428.22495 -31.181548)
		(width 0.4064)
		(layer "B.Cu")
		(net "PVDD18_S5_P0")
	)
	(segment
		(start 213.292436 -138.012932)
		(end 213.292436 -137.27938)
		(width 0.508)
		(layer "B.Cu")
		(net "PVDD18_S5_P0")
	)
	(segment
		(start 242.443 -231.24795)
		(end 241.596926 -231.24795)
		(width 0.381)
		(layer "B.Cu")
		(net "PVDD18_S5_P0")
	)
	(segment
		(start 236.118146 -146.058636)
		(end 236.118146 -146.431254)
		(width 0.508)
		(layer "B.Cu")
		(net "PVDD18_S5_P0")
	)
	(segment
		(start 301.73295 -356.997)
		(end 301.73295 -358.14)
		(width 0.508)
		(layer "B.Cu")
		(net "PVDD18_S5_P0")
	)
	(segment
		(start 184.005982 -134.84098)
		(end 183.732678 -134.84098)
		(width 0.508)
		(layer "B.Cu")
		(net "PVDD18_S5_P0")
	)
	(segment
		(start 397.637508 -340.768686)
		(end 396.985998 -340.768686)
		(width 0.381)
		(layer "B.Cu")
		(net "PVDD18_S5_P0")
	)
	(segment
		(start 338.830158 -309.614062)
		(end 338.830158 -310.428132)
		(width 0.381)
		(layer "B.Cu")
		(net "PVDD18_S5_P0")
	)
	(segment
		(start 393.781534 -204.249782)
		(end 393.781534 -203.983336)
		(width 0.3556)
		(layer "B.Cu")
		(net "PVDD18_S5_P0")
	)
	(segment
		(start 322.478908 -196.678296)
		(end 322.478908 -195.662296)
		(width 0.381)
		(layer "B.Cu")
		(net "PVDD18_S5_P0")
	)
	(segment
		(start 375.523252 -142.561056)
		(end 374.969278 -142.561056)
		(width 0.1778)
		(layer "B.Cu")
		(net "PVDD18_S5_P0")
	)
	(segment
		(start 407.099008 -328.926952)
		(end 407.661618 -328.926952)
		(width 0.381)
		(layer "B.Cu")
		(net "PVDD18_S5_P0")
	)
	(segment
		(start 376.218958 -204.701902)
		(end 376.218958 -204.085952)
		(width 0.381)
		(layer "B.Cu")
		(net "PVDD18_S5_P0")
	)
	(segment
		(start 401.32254 -329.98029)
		(end 401.32254 -329.2094)
		(width 0.381)
		(layer "B.Cu")
		(net "PVDD18_S5_P0")
	)
	(segment
		(start 322.478908 -195.662296)
		(end 316.581282 -195.662296)
		(width 0.381)
		(layer "B.Cu")
		(net "PVDD18_S5_P0")
	)
	(segment
		(start 403.14753 -321.179952)
		(end 402.722588 -321.179952)
		(width 0.508)
		(layer "B.Cu")
		(net "PVDD18_S5_P0")
	)
	(segment
		(start 407.834592 -365.07547)
		(end 407.999438 -364.910624)
		(width 0.508)
		(layer "B.Cu")
		(net "PVDD18_S5_P0")
	)
	(segment
		(start 407.099008 -328.926952)
		(end 407.099008 -327.910952)
		(width 0.381)
		(layer "B.Cu")
		(net "PVDD18_S5_P0")
	)
	(segment
		(start 374.440958 -207.485488)
		(end 374.440958 -208.130902)
		(width 0.381)
		(layer "B.Cu")
		(net "PVDD18_S5_P0")
	)
	(segment
		(start 316.008258 -199.287892)
		(end 316.008258 -198.843392)
		(width 0.508)
		(layer "B.Cu")
		(net "PVDD18_S5_P0")
	)
	(segment
		(start 407.661618 -328.926952)
		(end 407.76144 -328.82713)
		(width 0.381)
		(layer "B.Cu")
		(net "PVDD18_S5_P0")
	)
	(segment
		(start 323.4944 -368.37112)
		(end 321.59956 -366.47628)
		(width 0.508)
		(layer "B.Cu")
		(net "PVDD18_S5_P0")
	)
	(segment
		(start 320.211958 -203.517246)
		(end 319.861438 -203.166726)
		(width 0.381)
		(layer "B.Cu")
		(net "PVDD18_S5_P0")
	)
	(segment
		(start 373.680482 -208.130902)
		(end 374.440958 -208.130902)
		(width 0.381)
		(layer "B.Cu")
		(net "PVDD18_S5_P0")
	)
	(segment
		(start 304.01895 -360.78795)
		(end 304.292 -361.061)
		(width 0.4572)
		(layer "B.Cu")
		(net "PVDD18_S5_P0")
	)
	(segment
		(start 394.037058 -322.195952)
		(end 394.160502 -322.195952)
		(width 0.381)
		(layer "B.Cu")
		(net "PVDD18_S5_P0")
	)
	(segment
		(start 395.238732 -321.785996)
		(end 395.619986 -322.16725)
		(width 0.381)
		(layer "B.Cu")
		(net "PVDD18_S5_P0")
	)
	(segment
		(start 231.902 -230.886)
		(end 231.902 -231.75595)
		(width 0.381)
		(layer "B.Cu")
		(net "PVDD18_S5_P0")
	)
	(segment
		(start 317.526924 -360.907838)
		(end 317.399924 -360.780838)
		(width 0.508)
		(layer "B.Cu")
		(net "PVDD18_S5_P0")
	)
	(segment
		(start 235.84027 -145.78076)
		(end 236.118146 -146.058636)
		(width 0.508)
		(layer "B.Cu")
		(net "PVDD18_S5_P0")
	)
	(segment
		(start 344.361008 -307.483002)
		(end 344.361008 -306.828952)
		(width 0.381)
		(layer "B.Cu")
		(net "PVDD18_S5_P0")
	)
	(segment
		(start 322.370958 -203.517246)
		(end 322.177664 -203.517246)
		(width 0.381)
		(layer "B.Cu")
		(net "PVDD18_S5_P0")
	)
	(segment
		(start 229.752144 -151.680164)
		(end 228.05136 -151.680164)
		(width 0.508)
		(layer "B.Cu")
		(net "PVDD18_S5_P0")
	)
	(segment
		(start 318.423036 -201.713846)
		(end 318.23787 -201.899012)
		(width 0.381)
		(layer "B.Cu")
		(net "PVDD18_S5_P0")
	)
	(segment
		(start 183.364886 -134.473188)
		(end 183.364886 -134.195058)
		(width 0.508)
		(layer "B.Cu")
		(net "PVDD18_S5_P0")
	)
	(segment
		(start 392.118088 -314.572904)
		(end 392.118088 -315.218064)
		(width 0.254)
		(layer "B.Cu")
		(net "PVDD18_S5_P0")
	)
	(segment
		(start 374.969278 -142.561056)
		(end 374.080278 -142.561056)
		(width 0.2032)
		(layer "B.Cu")
		(net "PVDD18_S5_P0")
	)
	(segment
		(start 214.653876 -135.91794)
		(end 214.76081 -135.811006)
		(width 0.508)
		(layer "B.Cu")
		(net "PVDD18_S5_P0")
	)
	(segment
		(start 398.188942 -202.324208)
		(end 398.420082 -202.324208)
		(width 0.508)
		(layer "B.Cu")
		(net "PVDD18_S5_P0")
	)
	(segment
		(start 257.584194 -351.188528)
		(end 248.993914 -351.188528)
		(width 0.508)
		(layer "B.Cu")
		(net "PVDD18_S5_P0")
	)
	(segment
		(start 229.98303 -151.449278)
		(end 229.752144 -151.680164)
		(width 0.508)
		(layer "B.Cu")
		(net "PVDD18_S5_P0")
	)
	(segment
		(start 403.48535 -321.517772)
		(end 403.14753 -321.179952)
		(width 0.508)
		(layer "B.Cu")
		(net "PVDD18_S5_P0")
	)
	(segment
		(start 210.269328 -140.784326)
		(end 210.521042 -140.784326)
		(width 0.508)
		(layer "B.Cu")
		(net "PVDD18_S5_P0")
	)
	(segment
		(start 407.999438 -364.910624)
		(end 407.999438 -364.524544)
		(width 0.508)
		(layer "B.Cu")
		(net "PVDD18_S5_P0")
	)
	(segment
		(start 301.73295 -358.14)
		(end 300.482 -359.39095)
		(width 0.508)
		(layer "B.Cu")
		(net "PVDD18_S5_P0")
	)
	(segment
		(start 231.888538 -234.582462)
		(end 231.888538 -234.699302)
		(width 0.254)
		(layer "B.Cu")
		(net "PVDD18_S5_P0")
	)
	(segment
		(start 232.30205 -234.16895)
		(end 231.888538 -234.582462)
		(width 0.254)
		(layer "B.Cu")
		(net "PVDD18_S5_P0")
	)
	(segment
		(start 255.847342 -150.987252)
		(end 263.699244 -150.987252)
		(width 0.508)
		(layer "In2.Cu")
		(net "PVDD18_S5_P0")
	)
	(segment
		(start 411.144466 -369.62334)
		(end 413.415988 -369.62334)
		(width 0.508)
		(layer "In2.Cu")
		(net "PVDD18_S5_P0")
	)
	(segment
		(start 407.834592 -365.07547)
		(end 408.768296 -366.009174)
		(width 0.508)
		(layer "In2.Cu")
		(net "PVDD18_S5_P0")
	)
	(segment
		(start 130.765296 -122.802396)
		(end 130.765296 -107.403646)
		(width 0.508)
		(layer "In2.Cu")
		(net "PVDD18_S5_P0")
	)
	(segment
		(start 214.362792 -147.334224)
		(end 217.17635 -150.147782)
		(width 0.508)
		(layer "In2.Cu")
		(net "PVDD18_S5_P0")
	)
	(segment
		(start 179.422298 -157.908244)
		(end 179.422298 -156.229812)
		(width 0.508)
		(layer "In2.Cu")
		(net "PVDD18_S5_P0")
	)
	(segment
		(start 217.17635 -150.147782)
		(end 227.085652 -150.147782)
		(width 0.508)
		(layer "In2.Cu")
		(net "PVDD18_S5_P0")
	)
	(segment
		(start 413.415988 -369.62334)
		(end 414.295844 -368.743484)
		(width 0.508)
		(layer "In2.Cu")
		(net "PVDD18_S5_P0")
	)
	(segment
		(start 179.422298 -156.229812)
		(end 181.619398 -154.032712)
		(width 0.508)
		(layer "In2.Cu")
		(net "PVDD18_S5_P0")
	)
	(segment
		(start 230.003604 -151.151082)
		(end 230.003604 -151.042878)
		(width 0.508)
		(layer "In2.Cu")
		(net "PVDD18_S5_P0")
	)
	(segment
		(start 266.02309 -148.663406)
		(end 266.02309 -139.591796)
		(width 0.508)
		(layer "In2.Cu")
		(net "PVDD18_S5_P0")
	)
	(segment
		(start 408.768296 -366.009174)
		(end 408.768296 -367.24717)
		(width 0.508)
		(layer "In2.Cu")
		(net "PVDD18_S5_P0")
	)
	(segment
		(start 228.686868 -151.748998)
		(end 229.405688 -151.748998)
		(width 0.508)
		(layer "In2.Cu")
		(net "PVDD18_S5_P0")
	)
	(segment
		(start 130.765296 -107.403646)
		(end 135.519922 -102.64902)
		(width 0.508)
		(layer "In2.Cu")
		(net "PVDD18_S5_P0")
	)
	(segment
		(start 227.085652 -150.147782)
		(end 228.686868 -151.748998)
		(width 0.508)
		(layer "In2.Cu")
		(net "PVDD18_S5_P0")
	)
	(segment
		(start 212.221826 -147.334224)
		(end 214.362792 -147.334224)
		(width 0.508)
		(layer "In2.Cu")
		(net "PVDD18_S5_P0")
	)
	(segment
		(start 250.59894 -145.73885)
		(end 255.847342 -150.987252)
		(width 0.508)
		(layer "In2.Cu")
		(net "PVDD18_S5_P0")
	)
	(segment
		(start 414.295844 -368.743484)
		(end 414.295844 -363.862112)
		(width 0.508)
		(layer "In2.Cu")
		(net "PVDD18_S5_P0")
	)
	(segment
		(start 408.768296 -367.24717)
		(end 411.144466 -369.62334)
		(width 0.508)
		(layer "In2.Cu")
		(net "PVDD18_S5_P0")
	)
	(segment
		(start 119.63781 -133.929882)
		(end 130.765296 -122.802396)
		(width 0.508)
		(layer "In2.Cu")
		(net "PVDD18_S5_P0")
	)
	(segment
		(start 229.405688 -151.748998)
		(end 230.003604 -151.151082)
		(width 0.508)
		(layer "In2.Cu")
		(net "PVDD18_S5_P0")
	)
	(segment
		(start 413.313118 -362.879386)
		(end 413.313118 -362.804964)
		(width 0.508)
		(layer "In2.Cu")
		(net "PVDD18_S5_P0")
	)
	(segment
		(start 236.826806 -145.73885)
		(end 250.59894 -145.73885)
		(width 0.508)
		(layer "In2.Cu")
		(net "PVDD18_S5_P0")
	)
	(segment
		(start 263.699244 -150.987252)
		(end 266.02309 -148.663406)
		(width 0.508)
		(layer "In2.Cu")
		(net "PVDD18_S5_P0")
	)
	(segment
		(start 338.830158 -307.150262)
		(end 338.830158 -310.428132)
		(width 0.508)
		(layer "In2.Cu")
		(net "PVDD18_S5_P0")
	)
	(segment
		(start 338.125308 -306.445412)
		(end 338.830158 -307.150262)
		(width 0.508)
		(layer "In2.Cu")
		(net "PVDD18_S5_P0")
	)
	(segment
		(start 236.323124 -146.636232)
		(end 236.323124 -146.242532)
		(width 0.508)
		(layer "In2.Cu")
		(net "PVDD18_S5_P0")
	)
	(segment
		(start 414.295844 -363.862112)
		(end 413.313118 -362.879386)
		(width 0.508)
		(layer "In2.Cu")
		(net "PVDD18_S5_P0")
	)
	(segment
		(start 236.323124 -146.242532)
		(end 236.826806 -145.73885)
		(width 0.508)
		(layer "In2.Cu")
		(net "PVDD18_S5_P0")
	)
	(segment
		(start 402.731732 -348.133416)
		(end 405.240998 -348.133416)
		(width 0.508)
		(layer "In4.Cu")
		(net "PVDD18_S5_P0")
	)
	(segment
		(start 405.299672 -352.009202)
		(end 404.89124 -351.60077)
		(width 0.508)
		(layer "In4.Cu")
		(net "PVDD18_S5_P0")
	)
	(segment
		(start 230.303324 -155.971748)
		(end 230.303324 -153.250138)
		(width 0.508)
		(layer "In4.Cu")
		(net "PVDD18_S5_P0")
	)
	(segment
		(start 400.897344 -345.250262)
		(end 400.897344 -346.299028)
		(width 0.508)
		(layer "In4.Cu")
		(net "PVDD18_S5_P0")
	)
	(segment
		(start 238.993426 -327.698608)
		(end 239.436148 -327.698608)
		(width 0.508)
		(layer "In4.Cu")
		(net "PVDD18_S5_P0")
	)
	(segment
		(start 393.97051 -316.329822)
		(end 393.97051 -318.88557)
		(width 0.508)
		(layer "In4.Cu")
		(net "PVDD18_S5_P0")
	)
	(segment
		(start 230.303324 -153.250138)
		(end 230.003604 -152.950418)
		(width 0.508)
		(layer "In4.Cu")
		(net "PVDD18_S5_P0")
	)
	(segment
		(start 405.240998 -348.133416)
		(end 405.241252 -348.133162)
		(width 0.508)
		(layer "In4.Cu")
		(net "PVDD18_S5_P0")
	)
	(segment
		(start 429.086772 -31.651194)
		(end 428.877476 -31.441898)
		(width 0.508)
		(layer "In4.Cu")
		(net "PVDD18_S5_P0")
	)
	(segment
		(start 183.439054 -152.792684)
		(end 183.439054 -147.143724)
		(width 0.508)
		(layer "In4.Cu")
		(net "PVDD18_S5_P0")
	)
	(segment
		(start 183.007 -146.71167)
		(end 183.007 -141.188948)
		(width 0.508)
		(layer "In4.Cu")
		(net "PVDD18_S5_P0")
	)
	(segment
		(start 239.436148 -327.698608)
		(end 239.73663 -327.99909)
		(width 0.508)
		(layer "In4.Cu")
		(net "PVDD18_S5_P0")
	)
	(segment
		(start 407.834592 -365.07547)
		(end 407.834592 -363.959648)
		(width 0.508)
		(layer "In4.Cu")
		(net "PVDD18_S5_P0")
	)
	(segment
		(start 239.376712 -333.094838)
		(end 239.495076 -333.213202)
		(width 0.508)
		(layer "In4.Cu")
		(net "PVDD18_S5_P0")
	)
	(segment
		(start 231.146858 -147.31365)
		(end 231.075738 -147.24253)
		(width 0.508)
		(layer "In4.Cu")
		(net "PVDD18_S5_P0")
	)
	(segment
		(start 239.495076 -341.68969)
		(end 243.919502 -346.114116)
		(width 0.508)
		(layer "In4.Cu")
		(net "PVDD18_S5_P0")
	)
	(segment
		(start 182.199026 -154.032712)
		(end 183.439054 -152.792684)
		(width 0.508)
		(layer "In4.Cu")
		(net "PVDD18_S5_P0")
	)
	(segment
		(start 405.241252 -348.133162)
		(end 404.060406 -346.952316)
		(width 0.508)
		(layer "In4.Cu")
		(net "PVDD18_S5_P0")
	)
	(segment
		(start 404.89124 -351.60077)
		(end 404.89124 -350.708468)
		(width 0.508)
		(layer "In4.Cu")
		(net "PVDD18_S5_P0")
	)
	(segment
		(start 212.221826 -138.055096)
		(end 212.221826 -147.334224)
		(width 0.508)
		(layer "In4.Cu")
		(net "PVDD18_S5_P0")
	)
	(segment
		(start 396.985998 -340.768686)
		(end 396.985998 -344.15476)
		(width 0.508)
		(layer "In4.Cu")
		(net "PVDD18_S5_P0")
	)
	(segment
		(start 398.977104 -61.757306)
		(end 398.977104 -64.141096)
		(width 0.508)
		(layer "In4.Cu")
		(net "PVDD18_S5_P0")
	)
	(segment
		(start 398.0815 -345.250262)
		(end 400.897344 -345.250262)
		(width 0.508)
		(layer "In4.Cu")
		(net "PVDD18_S5_P0")
	)
	(segment
		(start 183.439054 -147.143724)
		(end 183.007 -146.71167)
		(width 0.508)
		(layer "In4.Cu")
		(net "PVDD18_S5_P0")
	)
	(segment
		(start 214.358982 -135.91794)
		(end 212.221826 -138.055096)
		(width 0.508)
		(layer "In4.Cu")
		(net "PVDD18_S5_P0")
	)
	(segment
		(start 230.003604 -152.950418)
		(end 230.003604 -151.042878)
		(width 0.508)
		(layer "In4.Cu")
		(net "PVDD18_S5_P0")
	)
	(segment
		(start 404.060406 -346.952316)
		(end 404.060406 -339.019642)
		(width 0.508)
		(layer "In4.Cu")
		(net "PVDD18_S5_P0")
	)
	(segment
		(start 428.679864 -37.023548)
		(end 429.086772 -36.61664)
		(width 0.508)
		(layer "In4.Cu")
		(net "PVDD18_S5_P0")
	)
	(segment
		(start 405.299672 -350.300036)
		(end 405.299672 -348.191582)
		(width 0.508)
		(layer "In4.Cu")
		(net "PVDD18_S5_P0")
	)
	(segment
		(start 232.071672 -147.31365)
		(end 231.146858 -147.31365)
		(width 0.508)
		(layer "In4.Cu")
		(net "PVDD18_S5_P0")
	)
	(segment
		(start 401.042378 -336.001614)
		(end 401.042378 -331.326236)
		(width 0.508)
		(layer "In4.Cu")
		(net "PVDD18_S5_P0")
	)
	(segment
		(start 427.97095 -37.023548)
		(end 428.679864 -37.023548)
		(width 0.508)
		(layer "In4.Cu")
		(net "PVDD18_S5_P0")
	)
	(segment
		(start 405.299672 -348.191582)
		(end 405.241252 -348.133162)
		(width 0.508)
		(layer "In4.Cu")
		(net "PVDD18_S5_P0")
	)
	(segment
		(start 398.977104 -64.141096)
		(end 399.415508 -64.5795)
		(width 0.508)
		(layer "In4.Cu")
		(net "PVDD18_S5_P0")
	)
	(segment
		(start 192.151 -140.457936)
		(end 192.558162 -140.865098)
		(width 0.508)
		(layer "In4.Cu")
		(net "PVDD18_S5_P0")
	)
	(segment
		(start 405.501348 -58.36666)
		(end 402.36775 -58.36666)
		(width 0.508)
		(layer "In4.Cu")
		(net "PVDD18_S5_P0")
	)
	(segment
		(start 428.877476 -31.441898)
		(end 427.9773 -31.441898)
		(width 0.508)
		(layer "In4.Cu")
		(net "PVDD18_S5_P0")
	)
	(segment
		(start 407.834592 -363.959648)
		(end 405.299672 -361.424728)
		(width 0.508)
		(layer "In4.Cu")
		(net "PVDD18_S5_P0")
	)
	(segment
		(start 232.016554 -151.042878)
		(end 232.617518 -150.441914)
		(width 0.508)
		(layer "In4.Cu")
		(net "PVDD18_S5_P0")
	)
	(segment
		(start 192.558162 -140.865098)
		(end 192.558162 -141.445742)
		(width 0.508)
		(layer "In4.Cu")
		(net "PVDD18_S5_P0")
	)
	(segment
		(start 429.086772 -36.61664)
		(end 429.086772 -31.651194)
		(width 0.508)
		(layer "In4.Cu")
		(net "PVDD18_S5_P0")
	)
	(segment
		(start 392.836654 -315.195966)
		(end 393.97051 -316.329822)
		(width 0.508)
		(layer "In4.Cu")
		(net "PVDD18_S5_P0")
	)
	(segment
		(start 396.985998 -344.15476)
		(end 398.0815 -345.250262)
		(width 0.508)
		(layer "In4.Cu")
		(net "PVDD18_S5_P0")
	)
	(segment
		(start 405.299672 -361.424728)
		(end 405.299672 -352.009202)
		(width 0.508)
		(layer "In4.Cu")
		(net "PVDD18_S5_P0")
	)
	(segment
		(start 427.9773 -31.441898)
		(end 427.97095 -31.435548)
		(width 0.508)
		(layer "In4.Cu")
		(net "PVDD18_S5_P0")
	)
	(segment
		(start 232.617518 -147.859496)
		(end 232.071672 -147.31365)
		(width 0.508)
		(layer "In4.Cu")
		(net "PVDD18_S5_P0")
	)
	(segment
		(start 230.003604 -151.042878)
		(end 232.016554 -151.042878)
		(width 0.508)
		(layer "In4.Cu")
		(net "PVDD18_S5_P0")
	)
	(segment
		(start 239.495076 -333.213202)
		(end 239.495076 -341.68969)
		(width 0.508)
		(layer "In4.Cu")
		(net "PVDD18_S5_P0")
	)
	(segment
		(start 404.060406 -339.019642)
		(end 401.042378 -336.001614)
		(width 0.508)
		(layer "In4.Cu")
		(net "PVDD18_S5_P0")
	)
	(segment
		(start 392.118088 -315.218064)
		(end 392.140186 -315.195966)
		(width 0.508)
		(layer "In4.Cu")
		(net "PVDD18_S5_P0")
	)
	(segment
		(start 181.619398 -154.032712)
		(end 182.199026 -154.032712)
		(width 0.508)
		(layer "In4.Cu")
		(net "PVDD18_S5_P0")
	)
	(segment
		(start 404.89124 -350.708468)
		(end 405.299672 -350.300036)
		(width 0.508)
		(layer "In4.Cu")
		(net "PVDD18_S5_P0")
	)
	(segment
		(start 214.653876 -135.91794)
		(end 214.358982 -135.91794)
		(width 0.508)
		(layer "In4.Cu")
		(net "PVDD18_S5_P0")
	)
	(segment
		(start 393.97051 -318.88557)
		(end 395.732 -320.64706)
		(width 0.508)
		(layer "In4.Cu")
		(net "PVDD18_S5_P0")
	)
	(segment
		(start 400.897344 -346.299028)
		(end 402.731732 -348.133416)
		(width 0.508)
		(layer "In4.Cu")
		(net "PVDD18_S5_P0")
	)
	(segment
		(start 192.151 -138.648948)
		(end 192.151 -140.457936)
		(width 0.508)
		(layer "In4.Cu")
		(net "PVDD18_S5_P0")
	)
	(segment
		(start 402.36775 -58.36666)
		(end 398.977104 -61.757306)
		(width 0.508)
		(layer "In4.Cu")
		(net "PVDD18_S5_P0")
	)
	(segment
		(start 392.140186 -315.195966)
		(end 392.836654 -315.195966)
		(width 0.508)
		(layer "In4.Cu")
		(net "PVDD18_S5_P0")
	)
	(segment
		(start 239.73663 -327.99909)
		(end 239.73663 -329.555348)
		(width 0.508)
		(layer "In4.Cu")
		(net "PVDD18_S5_P0")
	)
	(segment
		(start 232.617518 -150.441914)
		(end 232.617518 -147.859496)
		(width 0.508)
		(layer "In4.Cu")
		(net "PVDD18_S5_P0")
	)
	(segment
		(start 239.73663 -329.555348)
		(end 239.376712 -329.915266)
		(width 0.508)
		(layer "In4.Cu")
		(net "PVDD18_S5_P0")
	)
	(segment
		(start 239.376712 -329.915266)
		(end 239.376712 -333.094838)
		(width 0.508)
		(layer "In4.Cu")
		(net "PVDD18_S5_P0")
	)
	(segment
		(start 141.839188 -133.929882)
		(end 146.049238 -138.139932)
		(width 0.508)
		(layer "In6.Cu")
		(net "PVDD18_S5_P0")
	)
	(segment
		(start 204.720952 -141.036294)
		(end 210.01736 -141.036294)
		(width 0.508)
		(layer "In6.Cu")
		(net "PVDD18_S5_P0")
	)
	(segment
		(start 171.650406 -140.208254)
		(end 182.254144 -140.208254)
		(width 0.508)
		(layer "In6.Cu")
		(net "PVDD18_S5_P0")
	)
	(segment
		(start 183.007 -140.96111)
		(end 183.007 -141.188948)
		(width 0.508)
		(layer "In6.Cu")
		(net "PVDD18_S5_P0")
	)
	(segment
		(start 300.482 -361.4166)
		(end 302.1838 -361.4166)
		(width 0.508)
		(layer "In6.Cu")
		(net "PVDD18_S5_P0")
	)
	(segment
		(start 159.022796 -138.139932)
		(end 161.752026 -140.869162)
		(width 0.508)
		(layer "In6.Cu")
		(net "PVDD18_S5_P0")
	)
	(segment
		(start 161.752026 -140.869162)
		(end 170.989498 -140.869162)
		(width 0.508)
		(layer "In6.Cu")
		(net "PVDD18_S5_P0")
	)
	(segment
		(start 200.696322 -140.537692)
		(end 201.58075 -141.42212)
		(width 0.508)
		(layer "In6.Cu")
		(net "PVDD18_S5_P0")
	)
	(segment
		(start 201.58075 -141.42212)
		(end 204.335126 -141.42212)
		(width 0.508)
		(layer "In6.Cu")
		(net "PVDD18_S5_P0")
	)
	(segment
		(start 210.01736 -141.036294)
		(end 210.269328 -140.784326)
		(width 0.508)
		(layer "In6.Cu")
		(net "PVDD18_S5_P0")
	)
	(segment
		(start 182.254144 -140.208254)
		(end 183.007 -140.96111)
		(width 0.508)
		(layer "In6.Cu")
		(net "PVDD18_S5_P0")
	)
	(segment
		(start 204.335126 -141.42212)
		(end 204.720952 -141.036294)
		(width 0.508)
		(layer "In6.Cu")
		(net "PVDD18_S5_P0")
	)
	(segment
		(start 302.1838 -361.4166)
		(end 302.6918 -360.9086)
		(width 0.508)
		(layer "In6.Cu")
		(net "PVDD18_S5_P0")
	)
	(segment
		(start 170.989498 -140.869162)
		(end 171.650406 -140.208254)
		(width 0.508)
		(layer "In6.Cu")
		(net "PVDD18_S5_P0")
	)
	(segment
		(start 119.63781 -133.929882)
		(end 141.839188 -133.929882)
		(width 0.508)
		(layer "In6.Cu")
		(net "PVDD18_S5_P0")
	)
	(segment
		(start 146.049238 -138.139932)
		(end 159.022796 -138.139932)
		(width 0.508)
		(layer "In6.Cu")
		(net "PVDD18_S5_P0")
	)
	(segment
		(start 193.466212 -140.537692)
		(end 200.696322 -140.537692)
		(width 0.508)
		(layer "In6.Cu")
		(net "PVDD18_S5_P0")
	)
	(segment
		(start 192.558162 -141.445742)
		(end 193.466212 -140.537692)
		(width 0.508)
		(layer "In6.Cu")
		(net "PVDD18_S5_P0")
	)
	(segment
		(start 304.3428 -360.9086)
		(end 304.4952 -361.061)
		(width 0.508)
		(layer "In6.Cu")
		(net "PVDD18_S5_P0")
	)
	(segment
		(start 302.6918 -360.9086)
		(end 304.3428 -360.9086)
		(width 0.508)
		(layer "In6.Cu")
		(net "PVDD18_S5_P0")
	)
	(segment
		(start 137.818622 -100.35032)
		(end 137.818622 -88.089232)
		(width 0.508)
		(layer "In11.Cu")
		(net "PVDD18_S5_P0")
	)
	(segment
		(start 137.096246 -52.793646)
		(end 135.184388 -52.793646)
		(width 0.508)
		(layer "In11.Cu")
		(net "PVDD18_S5_P0")
	)
	(segment
		(start 410.126688 -53.523388)
		(end 421.230298 -42.419778)
		(width 0.508)
		(layer "In11.Cu")
		(net "PVDD18_S5_P0")
	)
	(segment
		(start 281.072082 -99.153472)
		(end 280.024586 -98.105976)
		(width 0.508)
		(layer "In11.Cu")
		(net "PVDD18_S5_P0")
	)
	(segment
		(start 280.024586 -61.986414)
		(end 288.075624 -53.935376)
		(width 0.508)
		(layer "In11.Cu")
		(net "PVDD18_S5_P0")
	)
	(segment
		(start 393.985496 -203.527406)
		(end 394.556996 -203.527406)
		(width 0.508)
		(layer "In11.Cu")
		(net "PVDD18_S5_P0")
	)
	(segment
		(start 137.818622 -88.089232)
		(end 135.3058 -85.57641)
		(width 0.508)
		(layer "In11.Cu")
		(net "PVDD18_S5_P0")
	)
	(segment
		(start 386.35432 -207.138778)
		(end 386.35432 -204.999082)
		(width 0.508)
		(layer "In11.Cu")
		(net "PVDD18_S5_P0")
	)
	(segment
		(start 317.9826 -359.029)
		(end 318.2874 -359.029)
		(width 0.508)
		(layer "In11.Cu")
		(net "PVDD18_S5_P0")
	)
	(segment
		(start 377.932442 -207.45958)
		(end 377.932442 -207.955642)
		(width 0.508)
		(layer "In11.Cu")
		(net "PVDD18_S5_P0")
	)
	(segment
		(start 384.87731 -208.615788)
		(end 386.35432 -207.138778)
		(width 0.508)
		(layer "In11.Cu")
		(net "PVDD18_S5_P0")
	)
	(segment
		(start 317.4238 -359.5878)
		(end 317.9826 -359.029)
		(width 0.508)
		(layer "In11.Cu")
		(net "PVDD18_S5_P0")
	)
	(segment
		(start 378.487686 -208.510886)
		(end 380.563374 -208.510886)
		(width 0.508)
		(layer "In11.Cu")
		(net "PVDD18_S5_P0")
	)
	(segment
		(start 138.3284 -63.1444)
		(end 138.3284 -54.0258)
		(width 0.508)
		(layer "In11.Cu")
		(net "PVDD18_S5_P0")
	)
	(segment
		(start 192.558162 -142.09141)
		(end 192.558162 -141.445742)
		(width 0.508)
		(layer "In11.Cu")
		(net "PVDD18_S5_P0")
	)
	(segment
		(start 381.552958 -207.521302)
		(end 381.552958 -207.931004)
		(width 0.508)
		(layer "In11.Cu")
		(net "PVDD18_S5_P0")
	)
	(segment
		(start 135.3058 -66.167)
		(end 138.3284 -63.1444)
		(width 0.508)
		(layer "In11.Cu")
		(net "PVDD18_S5_P0")
	)
	(segment
		(start 426.216826 -30.927294)
		(end 426.72508 -31.435548)
		(width 0.508)
		(layer "In11.Cu")
		(net "PVDD18_S5_P0")
	)
	(segment
		(start 377.932442 -207.955642)
		(end 378.487686 -208.510886)
		(width 0.508)
		(layer "In11.Cu")
		(net "PVDD18_S5_P0")
	)
	(segment
		(start 426.216826 -30.420564)
		(end 426.216826 -30.927294)
		(width 0.508)
		(layer "In11.Cu")
		(net "PVDD18_S5_P0")
	)
	(segment
		(start 138.3284 -54.0258)
		(end 137.096246 -52.793646)
		(width 0.508)
		(layer "In11.Cu")
		(net "PVDD18_S5_P0")
	)
	(segment
		(start 398.20088 -61.426852)
		(end 406.104344 -53.523388)
		(width 0.508)
		(layer "In11.Cu")
		(net "PVDD18_S5_P0")
	)
	(segment
		(start 380.563374 -208.510886)
		(end 381.552958 -207.521302)
		(width 0.508)
		(layer "In11.Cu")
		(net "PVDD18_S5_P0")
	)
	(segment
		(start 388.58571 -202.767692)
		(end 393.225782 -202.767692)
		(width 0.508)
		(layer "In11.Cu")
		(net "PVDD18_S5_P0")
	)
	(segment
		(start 386.35432 -204.999082)
		(end 388.58571 -202.767692)
		(width 0.508)
		(layer "In11.Cu")
		(net "PVDD18_S5_P0")
	)
	(segment
		(start 382.237742 -208.615788)
		(end 384.87731 -208.615788)
		(width 0.508)
		(layer "In11.Cu")
		(net "PVDD18_S5_P0")
	)
	(segment
		(start 304.4952 -368.6048)
		(end 306.2732 -370.3828)
		(width 0.508)
		(layer "In11.Cu")
		(net "PVDD18_S5_P0")
	)
	(segment
		(start 425.708826 -29.912564)
		(end 426.216826 -30.420564)
		(width 0.508)
		(layer "In11.Cu")
		(net "PVDD18_S5_P0")
	)
	(segment
		(start 421.230298 -33.327848)
		(end 424.645582 -29.912564)
		(width 0.508)
		(layer "In11.Cu")
		(net "PVDD18_S5_P0")
	)
	(segment
		(start 192.193672 -142.4559)
		(end 192.558162 -142.09141)
		(width 0.508)
		(layer "In11.Cu")
		(net "PVDD18_S5_P0")
	)
	(segment
		(start 426.72508 -31.435548)
		(end 427.97095 -31.435548)
		(width 0.508)
		(layer "In11.Cu")
		(net "PVDD18_S5_P0")
	)
	(segment
		(start 393.225782 -202.767692)
		(end 393.985496 -203.527406)
		(width 0.508)
		(layer "In11.Cu")
		(net "PVDD18_S5_P0")
	)
	(segment
		(start 306.2732 -370.3828)
		(end 313.4614 -370.3828)
		(width 0.508)
		(layer "In11.Cu")
		(net "PVDD18_S5_P0")
	)
	(segment
		(start 190.114428 -141.49959)
		(end 190.114428 -142.043404)
		(width 0.508)
		(layer "In11.Cu")
		(net "PVDD18_S5_P0")
	)
	(segment
		(start 280.024586 -98.105976)
		(end 280.024586 -61.986414)
		(width 0.508)
		(layer "In11.Cu")
		(net "PVDD18_S5_P0")
	)
	(segment
		(start 398.20088 -65.04432)
		(end 398.20088 -61.426852)
		(width 0.508)
		(layer "In11.Cu")
		(net "PVDD18_S5_P0")
	)
	(segment
		(start 190.526924 -142.4559)
		(end 192.193672 -142.4559)
		(width 0.508)
		(layer "In11.Cu")
		(net "PVDD18_S5_P0")
	)
	(segment
		(start 313.4614 -370.3828)
		(end 317.4238 -366.4204)
		(width 0.508)
		(layer "In11.Cu")
		(net "PVDD18_S5_P0")
	)
	(segment
		(start 394.556996 -203.527406)
		(end 395.254734 -202.829668)
		(width 0.508)
		(layer "In11.Cu")
		(net "PVDD18_S5_P0")
	)
	(segment
		(start 292.129972 -52.665376)
		(end 292.129972 -53.935376)
		(width 0.508)
		(layer "In11.Cu")
		(net "PVDD18_S5_P0")
	)
	(segment
		(start 190.114428 -142.043404)
		(end 190.526924 -142.4559)
		(width 0.508)
		(layer "In11.Cu")
		(net "PVDD18_S5_P0")
	)
	(segment
		(start 395.254734 -202.829668)
		(end 395.651482 -203.226416)
		(width 0.508)
		(layer "In11.Cu")
		(net "PVDD18_S5_P0")
	)
	(segment
		(start 424.645582 -29.912564)
		(end 425.708826 -29.912564)
		(width 0.508)
		(layer "In11.Cu")
		(net "PVDD18_S5_P0")
	)
	(segment
		(start 395.651482 -203.226416)
		(end 398.928082 -203.226416)
		(width 0.508)
		(layer "In11.Cu")
		(net "PVDD18_S5_P0")
	)
	(segment
		(start 406.104344 -53.523388)
		(end 410.126688 -53.523388)
		(width 0.508)
		(layer "In11.Cu")
		(net "PVDD18_S5_P0")
	)
	(segment
		(start 317.4238 -366.4204)
		(end 317.4238 -359.5878)
		(width 0.508)
		(layer "In11.Cu")
		(net "PVDD18_S5_P0")
	)
	(segment
		(start 421.230298 -42.419778)
		(end 421.230298 -33.327848)
		(width 0.508)
		(layer "In11.Cu")
		(net "PVDD18_S5_P0")
	)
	(segment
		(start 381.552958 -207.931004)
		(end 382.237742 -208.615788)
		(width 0.508)
		(layer "In11.Cu")
		(net "PVDD18_S5_P0")
	)
	(segment
		(start 304.4952 -361.061)
		(end 304.4952 -368.6048)
		(width 0.508)
		(layer "In11.Cu")
		(net "PVDD18_S5_P0")
	)
	(segment
		(start 135.3058 -85.57641)
		(end 135.3058 -66.167)
		(width 0.508)
		(layer "In11.Cu")
		(net "PVDD18_S5_P0")
	)
	(segment
		(start 135.519922 -102.64902)
		(end 137.818622 -100.35032)
		(width 0.508)
		(layer "In11.Cu")
		(net "PVDD18_S5_P0")
	)
	(segment
		(start 288.075624 -53.935376)
		(end 292.129972 -53.935376)
		(width 0.508)
		(layer "In11.Cu")
		(net "PVDD18_S5_P0")
	)
	(segment
		(start 372.318026 -141.604492)
		(end 373.30634 -142.592806)
		(width 0.508)
		(layer "In13.Cu")
		(net "PVDD18_S5_P0")
	)
	(segment
		(start 181.727856 -139.909804)
		(end 181.727856 -135.460232)
		(width 0.508)
		(layer "In13.Cu")
		(net "PVDD18_S5_P0")
	)
	(segment
		(start 183.007 -141.188948)
		(end 181.727856 -139.909804)
		(width 0.508)
		(layer "In13.Cu")
		(net "PVDD18_S5_P0")
	)
	(segment
		(start 183.727852 -134.56285)
		(end 184.005982 -134.84098)
		(width 0.508)
		(layer "In13.Cu")
		(net "PVDD18_S5_P0")
	)
	(segment
		(start 181.727856 -135.460232)
		(end 182.625238 -134.56285)
		(width 0.508)
		(layer "In13.Cu")
		(net "PVDD18_S5_P0")
	)
	(segment
		(start 371.921278 -141.604492)
		(end 372.318026 -141.604492)
		(width 0.508)
		(layer "In13.Cu")
		(net "PVDD18_S5_P0")
	)
	(segment
		(start 374.048528 -142.592806)
		(end 374.080278 -142.561056)
		(width 0.508)
		(layer "In13.Cu")
		(net "PVDD18_S5_P0")
	)
	(segment
		(start 373.30634 -142.592806)
		(end 374.048528 -142.592806)
		(width 0.508)
		(layer "In13.Cu")
		(net "PVDD18_S5_P0")
	)
	(segment
		(start 182.625238 -134.56285)
		(end 183.727852 -134.56285)
		(width 0.508)
		(layer "In13.Cu")
		(net "PVDD18_S5_P0")
	)
	(segment
		(start 344.361008 -309.249064)
		(end 344.361008 -307.53939)
		(width 0.508)
		(layer "In15.Cu")
		(net "PVDD18_S5_P0")
	)
	(segment
		(start 336.642964 -151.692102)
		(end 344.652346 -143.68272)
		(width 0.508)
		(layer "In15.Cu")
		(net "PVDD18_S5_P0")
	)
	(segment
		(start 338.830158 -310.428132)
		(end 338.830158 -311.001156)
		(width 0.508)
		(layer "In15.Cu")
		(net "PVDD18_S5_P0")
	)
	(segment
		(start 377.791218 -205.25867)
		(end 378.61875 -205.25867)
		(width 0.508)
		(layer "In15.Cu")
		(net "PVDD18_S5_P0")
	)
	(segment
		(start 339.075014 -311.246012)
		(end 342.36406 -311.246012)
		(width 0.508)
		(layer "In15.Cu")
		(net "PVDD18_S5_P0")
	)
	(segment
		(start 378.61875 -205.25867)
		(end 379.111002 -205.750922)
		(width 0.508)
		(layer "In15.Cu")
		(net "PVDD18_S5_P0")
	)
	(segment
		(start 189.314836 -142.299182)
		(end 190.114428 -141.49959)
		(width 0.508)
		(layer "In15.Cu")
		(net "PVDD18_S5_P0")
	)
	(segment
		(start 424.163744 -359.184702)
		(end 421.807132 -359.184702)
		(width 0.508)
		(layer "In15.Cu")
		(net "PVDD18_S5_P0")
	)
	(segment
		(start 414.449006 -361.669076)
		(end 413.313118 -362.804964)
		(width 0.508)
		(layer "In15.Cu")
		(net "PVDD18_S5_P0")
	)
	(segment
		(start 379.111002 -205.750922)
		(end 379.111002 -206.897986)
		(width 0.508)
		(layer "In15.Cu")
		(net "PVDD18_S5_P0")
	)
	(segment
		(start 369.75034 -148.57603)
		(end 372.74627 -148.57603)
		(width 0.508)
		(layer "In15.Cu")
		(net "PVDD18_S5_P0")
	)
	(segment
		(start 415.477706 -359.87609)
		(end 414.449006 -360.90479)
		(width 0.508)
		(layer "In15.Cu")
		(net "PVDD18_S5_P0")
	)
	(segment
		(start 184.117234 -142.299182)
		(end 189.314836 -142.299182)
		(width 0.508)
		(layer "In15.Cu")
		(net "PVDD18_S5_P0")
	)
	(segment
		(start 378.603002 -207.405986)
		(end 377.986036 -207.405986)
		(width 0.508)
		(layer "In15.Cu")
		(net "PVDD18_S5_P0")
	)
	(segment
		(start 424.815254 -359.836212)
		(end 424.163744 -359.184702)
		(width 0.508)
		(layer "In15.Cu")
		(net "PVDD18_S5_P0")
	)
	(segment
		(start 344.652346 -143.68272)
		(end 350.92132 -143.68272)
		(width 0.508)
		(layer "In15.Cu")
		(net "PVDD18_S5_P0")
	)
	(segment
		(start 350.92132 -143.68272)
		(end 352.672142 -145.433542)
		(width 0.508)
		(layer "In15.Cu")
		(net "PVDD18_S5_P0")
	)
	(segment
		(start 377.234958 -204.70241)
		(end 377.791218 -205.25867)
		(width 0.508)
		(layer "In15.Cu")
		(net "PVDD18_S5_P0")
	)
	(segment
		(start 366.607852 -145.433542)
		(end 369.75034 -148.57603)
		(width 0.508)
		(layer "In15.Cu")
		(net "PVDD18_S5_P0")
	)
	(segment
		(start 376.218958 -204.085952)
		(end 377.234958 -204.085952)
		(width 0.508)
		(layer "In15.Cu")
		(net "PVDD18_S5_P0")
	)
	(segment
		(start 336.642964 -151.692102)
		(end 336.642964 -152.454102)
		(width 0.508)
		(layer "In15.Cu")
		(net "PVDD18_S5_P0")
	)
	(segment
		(start 421.807132 -359.184702)
		(end 421.115744 -359.87609)
		(width 0.508)
		(layer "In15.Cu")
		(net "PVDD18_S5_P0")
	)
	(segment
		(start 374.90527 -143.386048)
		(end 374.080278 -142.561056)
		(width 0.508)
		(layer "In15.Cu")
		(net "PVDD18_S5_P0")
	)
	(segment
		(start 377.986036 -207.405986)
		(end 377.932442 -207.45958)
		(width 0.508)
		(layer "In15.Cu")
		(net "PVDD18_S5_P0")
	)
	(segment
		(start 379.111002 -206.897986)
		(end 378.603002 -207.405986)
		(width 0.508)
		(layer "In15.Cu")
		(net "PVDD18_S5_P0")
	)
	(segment
		(start 421.115744 -359.87609)
		(end 415.477706 -359.87609)
		(width 0.508)
		(layer "In15.Cu")
		(net "PVDD18_S5_P0")
	)
	(segment
		(start 414.449006 -360.90479)
		(end 414.449006 -361.669076)
		(width 0.508)
		(layer "In15.Cu")
		(net "PVDD18_S5_P0")
	)
	(segment
		(start 352.672142 -145.433542)
		(end 366.607852 -145.433542)
		(width 0.508)
		(layer "In15.Cu")
		(net "PVDD18_S5_P0")
	)
	(segment
		(start 377.234958 -204.085952)
		(end 377.234958 -204.70241)
		(width 0.508)
		(layer "In15.Cu")
		(net "PVDD18_S5_P0")
	)
	(segment
		(start 374.90527 -146.41703)
		(end 374.90527 -143.386048)
		(width 0.508)
		(layer "In15.Cu")
		(net "PVDD18_S5_P0")
	)
	(segment
		(start 342.36406 -311.246012)
		(end 344.361008 -309.249064)
		(width 0.508)
		(layer "In15.Cu")
		(net "PVDD18_S5_P0")
	)
	(segment
		(start 183.007 -141.188948)
		(end 184.117234 -142.299182)
		(width 0.508)
		(layer "In15.Cu")
		(net "PVDD18_S5_P0")
	)
	(segment
		(start 344.361008 -307.53939)
		(end 344.332814 -307.511196)
		(width 0.508)
		(layer "In15.Cu")
		(net "PVDD18_S5_P0")
	)
	(segment
		(start 372.74627 -148.57603)
		(end 374.90527 -146.41703)
		(width 0.508)
		(layer "In15.Cu")
		(net "PVDD18_S5_P0")
	)
	(segment
		(start 338.830158 -311.001156)
		(end 339.075014 -311.246012)
		(width 0.508)
		(layer "In15.Cu")
		(net "PVDD18_S5_P0")
	)
	(segment
		(start 188.521848 -354.207318)
		(end 188.84646 -353.882706)
		(width 0.2032)
		(layer "F.Cu")
		(net "PVDD11_S3_P1_VOS2")
	)
	(segment
		(start 188.84646 -353.882706)
		(end 188.84646 -353.59594)
		(width 0.2032)
		(layer "F.Cu")
		(net "PVDD11_S3_P1_VOS2")
	)
	(via
		(at 188.521848 -354.207318)
		(size 0.508)
		(drill 0.254)
		(layers "F.Cu" "B.Cu")
		(net "PVDD11_S3_P1_VOS2")
	)
	(segment
		(start 187.585096 -353.586034)
		(end 187.900564 -353.586034)
		(width 0.2286)
		(layer "B.Cu")
		(net "PVDD11_S3_P1_VOS2")
	)
	(segment
		(start 187.900564 -353.586034)
		(end 188.521848 -354.207318)
		(width 0.2286)
		(layer "B.Cu")
		(net "PVDD11_S3_P1_VOS2")
	)
	(segment
		(start 180.19522 -354.181918)
		(end 180.519832 -353.857306)
		(width 0.2032)
		(layer "F.Cu")
		(net "PVDD11_S3_P1_VOS1")
	)
	(segment
		(start 180.519832 -353.857306)
		(end 180.519832 -353.57054)
		(width 0.2032)
		(layer "F.Cu")
		(net "PVDD11_S3_P1_VOS1")
	)
	(via
		(at 180.19522 -354.181918)
		(size 0.508)
		(drill 0.254)
		(layers "F.Cu" "B.Cu")
		(net "PVDD11_S3_P1_VOS1")
	)
	(segment
		(start 179.573936 -353.560634)
		(end 180.19522 -354.181918)
		(width 0.2286)
		(layer "B.Cu")
		(net "PVDD11_S3_P1_VOS1")
	)
	(segment
		(start 179.258468 -353.560634)
		(end 179.573936 -353.560634)
		(width 0.2286)
		(layer "B.Cu")
		(net "PVDD11_S3_P1_VOS1")
	)
	(segment
		(start 164.628576 -349.153226)
		(end 165.598348 -349.153226)
		(width 0.1524)
		(layer "F.Cu")
		(net "PVDD11_S3_P1_VMON")
	)
	(segment
		(start 165.598348 -349.153226)
		(end 165.773354 -349.328232)
		(width 0.1524)
		(layer "F.Cu")
		(net "PVDD11_S3_P1_VMON")
	)
	(segment
		(start 165.773354 -349.328232)
		(end 165.836092 -349.265494)
		(width 0.1524)
		(layer "F.Cu")
		(net "PVDD11_S3_P1_VMON")
	)
	(segment
		(start 165.836092 -349.265494)
		(end 166.529258 -349.265494)
		(width 0.1524)
		(layer "F.Cu")
		(net "PVDD11_S3_P1_VMON")
	)
	(via
		(at 165.773354 -349.328232)
		(size 0.508)
		(drill 0.254)
		(layers "F.Cu" "B.Cu")
		(net "PVDD11_S3_P1_VMON")
	)
	(segment
		(start 164.725604 -349.228156)
		(end 164.82568 -349.328232)
		(width 0.254)
		(layer "B.Cu")
		(net "PVDD11_S3_P1_VMON")
	)
	(segment
		(start 164.82568 -349.328232)
		(end 165.773354 -349.328232)
		(width 0.254)
		(layer "B.Cu")
		(net "PVDD11_S3_P1_VMON")
	)
	(segment
		(start 167.148256 -349.328232)
		(end 167.536368 -349.716344)
		(width 0.254)
		(layer "B.Cu")
		(net "PVDD11_S3_P1_VMON")
	)
	(segment
		(start 165.773354 -349.328232)
		(end 167.148256 -349.328232)
		(width 0.254)
		(layer "B.Cu")
		(net "PVDD11_S3_P1_VMON")
	)
	(segment
		(start 165.891718 -350.021398)
		(end 166.118794 -350.248474)
		(width 0.1524)
		(layer "F.Cu")
		(net "PVDD11_S3_P1_VINSEN")
	)
	(segment
		(start 165.239192 -349.553276)
		(end 165.707314 -350.021398)
		(width 0.1524)
		(layer "F.Cu")
		(net "PVDD11_S3_P1_VINSEN")
	)
	(segment
		(start 165.707314 -350.021398)
		(end 165.891718 -350.021398)
		(width 0.1524)
		(layer "F.Cu")
		(net "PVDD11_S3_P1_VINSEN")
	)
	(segment
		(start 166.118794 -350.248474)
		(end 166.520622 -350.248474)
		(width 0.1524)
		(layer "F.Cu")
		(net "PVDD11_S3_P1_VINSEN")
	)
	(segment
		(start 164.628576 -349.553276)
		(end 165.239192 -349.553276)
		(width 0.1524)
		(layer "F.Cu")
		(net "PVDD11_S3_P1_VINSEN")
	)
	(via
		(at 166.367968 -350.732344)
		(size 0.6604)
		(drill 0.3302)
		(layers "F.Cu" "B.Cu")
		(net "PVDD11_S3_P1_VINSEN")
	)
	(via
		(at 165.891718 -350.021398)
		(size 0.508)
		(drill 0.254)
		(layers "F.Cu" "B.Cu")
		(net "PVDD11_S3_P1_VINSEN")
	)
	(segment
		(start 165.891718 -350.021398)
		(end 166.367968 -350.497648)
		(width 0.254)
		(layer "B.Cu")
		(net "PVDD11_S3_P1_VINSEN")
	)
	(segment
		(start 164.725604 -350.762062)
		(end 165.151054 -350.762062)
		(width 0.254)
		(layer "B.Cu")
		(net "PVDD11_S3_P1_VINSEN")
	)
	(segment
		(start 166.367968 -350.732344)
		(end 167.536368 -350.732344)
		(width 0.254)
		(layer "B.Cu")
		(net "PVDD11_S3_P1_VINSEN")
	)
	(segment
		(start 166.367968 -350.497648)
		(end 166.367968 -350.732344)
		(width 0.254)
		(layer "B.Cu")
		(net "PVDD11_S3_P1_VINSEN")
	)
	(segment
		(start 165.151054 -350.762062)
		(end 165.891718 -350.021398)
		(width 0.254)
		(layer "B.Cu")
		(net "PVDD11_S3_P1_VINSEN")
	)
	(segment
		(start 159.127444 -348.386908)
		(end 159.127444 -346.729812)
		(width 0.1524)
		(layer "F.Cu")
		(net "PVDD11_S3_P1_VDDIO")
	)
	(segment
		(start 158.438596 -346.040964)
		(end 158.098236 -346.040964)
		(width 0.1524)
		(layer "F.Cu")
		(net "PVDD11_S3_P1_VDDIO")
	)
	(segment
		(start 158.098236 -346.040964)
		(end 158.098236 -347.260164)
		(width 0.1524)
		(layer "F.Cu")
		(net "PVDD11_S3_P1_VDDIO")
	)
	(segment
		(start 159.127444 -346.729812)
		(end 158.438596 -346.040964)
		(width 0.1524)
		(layer "F.Cu")
		(net "PVDD11_S3_P1_VDDIO")
	)
	(segment
		(start 159.828484 -348.753176)
		(end 159.493712 -348.753176)
		(width 0.1524)
		(layer "F.Cu")
		(net "PVDD11_S3_P1_VDDIO")
	)
	(segment
		(start 159.493712 -348.753176)
		(end 159.127444 -348.386908)
		(width 0.1524)
		(layer "F.Cu")
		(net "PVDD11_S3_P1_VDDIO")
	)
	(via
		(at 158.098236 -346.040964)
		(size 0.762)
		(drill 0.381)
		(layers "F.Cu" "B.Cu")
		(net "PVDD11_S3_P1_VDDIO")
	)
	(segment
		(start 189.256416 -354.22078)
		(end 189.256416 -354.411534)
		(width 0.2286)
		(layer "F.Cu")
		(net "PVDD11_S3_P1_VCCS")
	)
	(segment
		(start 180.225954 -355.752908)
		(end 180.954426 -355.752908)
		(width 0.254)
		(layer "F.Cu")
		(net "PVDD11_S3_P1_VCCS")
	)
	(segment
		(start 180.225954 -355.089968)
		(end 180.225954 -355.752908)
		(width 0.2286)
		(layer "F.Cu")
		(net "PVDD11_S3_P1_VCCS")
	)
	(segment
		(start 188.552582 -355.115368)
		(end 188.552582 -355.778308)
		(width 0.2286)
		(layer "F.Cu")
		(net "PVDD11_S3_P1_VCCS")
	)
	(segment
		(start 189.256416 -354.411534)
		(end 188.552582 -355.115368)
		(width 0.2286)
		(layer "F.Cu")
		(net "PVDD11_S3_P1_VCCS")
	)
	(segment
		(start 188.552582 -355.778308)
		(end 189.281054 -355.778308)
		(width 0.254)
		(layer "F.Cu")
		(net "PVDD11_S3_P1_VCCS")
	)
	(segment
		(start 180.929788 -354.386134)
		(end 180.225954 -355.089968)
		(width 0.2286)
		(layer "F.Cu")
		(net "PVDD11_S3_P1_VCCS")
	)
	(segment
		(start 180.929788 -354.19538)
		(end 180.929788 -354.386134)
		(width 0.2286)
		(layer "F.Cu")
		(net "PVDD11_S3_P1_VCCS")
	)
	(via
		(at 164.439854 -351.57664)
		(size 0.508)
		(drill 0.254)
		(layers "F.Cu" "B.Cu")
		(net "PVDD11_S3_P1_VCCS")
	)
	(via
		(at 180.954426 -355.752908)
		(size 0.508)
		(drill 0.254)
		(layers "F.Cu" "B.Cu")
		(net "PVDD11_S3_P1_VCCS")
	)
	(via
		(at 189.281054 -355.778308)
		(size 0.508)
		(drill 0.254)
		(layers "F.Cu" "B.Cu")
		(net "PVDD11_S3_P1_VCCS")
	)
	(segment
		(start 182.619396 -358.216454)
		(end 183.100472 -358.69753)
		(width 0.254)
		(layer "In4.Cu")
		(net "PVDD11_S3_P1_VCCS")
	)
	(segment
		(start 158.374334 -356.803706)
		(end 178.820572 -356.803706)
		(width 0.254)
		(layer "In4.Cu")
		(net "PVDD11_S3_P1_VCCS")
	)
	(segment
		(start 180.938678 -355.768656)
		(end 180.954426 -355.752908)
		(width 0.254)
		(layer "In4.Cu")
		(net "PVDD11_S3_P1_VCCS")
	)
	(segment
		(start 179.319682 -356.304596)
		(end 179.690522 -356.304596)
		(width 0.254)
		(layer "In4.Cu")
		(net "PVDD11_S3_P1_VCCS")
	)
	(segment
		(start 152.785318 -351.21469)
		(end 158.374334 -356.803706)
		(width 0.254)
		(layer "In4.Cu")
		(net "PVDD11_S3_P1_VCCS")
	)
	(segment
		(start 150.99157 -351.895156)
		(end 157.312868 -358.216454)
		(width 0.254)
		(layer "In4.Cu")
		(net "PVDD11_S3_P1_VCCS")
	)
	(segment
		(start 183.100472 -358.69753)
		(end 187.804806 -358.69753)
		(width 0.254)
		(layer "In4.Cu")
		(net "PVDD11_S3_P1_VCCS")
	)
	(segment
		(start 179.690522 -356.304596)
		(end 180.226462 -355.768656)
		(width 0.254)
		(layer "In4.Cu")
		(net "PVDD11_S3_P1_VCCS")
	)
	(segment
		(start 160.64992 -344.438732)
		(end 154.486864 -344.438732)
		(width 0.254)
		(layer "In4.Cu")
		(net "PVDD11_S3_P1_VCCS")
	)
	(segment
		(start 178.820572 -356.803706)
		(end 179.319682 -356.304596)
		(width 0.254)
		(layer "In4.Cu")
		(net "PVDD11_S3_P1_VCCS")
	)
	(segment
		(start 150.99157 -345.222576)
		(end 150.99157 -351.895156)
		(width 0.254)
		(layer "In4.Cu")
		(net "PVDD11_S3_P1_VCCS")
	)
	(segment
		(start 152.785318 -346.140278)
		(end 152.785318 -351.21469)
		(width 0.254)
		(layer "In4.Cu")
		(net "PVDD11_S3_P1_VCCS")
	)
	(segment
		(start 161.917126 -343.765378)
		(end 161.641028 -343.48928)
		(width 0.254)
		(layer "In4.Cu")
		(net "PVDD11_S3_P1_VCCS")
	)
	(segment
		(start 161.641028 -342.762078)
		(end 160.287462 -341.408512)
		(width 0.254)
		(layer "In4.Cu")
		(net "PVDD11_S3_P1_VCCS")
	)
	(segment
		(start 157.312868 -358.216454)
		(end 182.619396 -358.216454)
		(width 0.254)
		(layer "In4.Cu")
		(net "PVDD11_S3_P1_VCCS")
	)
	(segment
		(start 154.486864 -344.438732)
		(end 152.785318 -346.140278)
		(width 0.254)
		(layer "In4.Cu")
		(net "PVDD11_S3_P1_VCCS")
	)
	(segment
		(start 161.641028 -343.48928)
		(end 161.641028 -342.762078)
		(width 0.254)
		(layer "In4.Cu")
		(net "PVDD11_S3_P1_VCCS")
	)
	(segment
		(start 154.805634 -341.408512)
		(end 150.99157 -345.222576)
		(width 0.254)
		(layer "In4.Cu")
		(net "PVDD11_S3_P1_VCCS")
	)
	(segment
		(start 180.226462 -355.768656)
		(end 180.938678 -355.768656)
		(width 0.254)
		(layer "In4.Cu")
		(net "PVDD11_S3_P1_VCCS")
	)
	(segment
		(start 187.804806 -358.69753)
		(end 189.052962 -357.449374)
		(width 0.254)
		(layer "In4.Cu")
		(net "PVDD11_S3_P1_VCCS")
	)
	(segment
		(start 160.287462 -341.408512)
		(end 154.805634 -341.408512)
		(width 0.254)
		(layer "In4.Cu")
		(net "PVDD11_S3_P1_VCCS")
	)
	(segment
		(start 189.052962 -357.449374)
		(end 189.052962 -356.0064)
		(width 0.254)
		(layer "In4.Cu")
		(net "PVDD11_S3_P1_VCCS")
	)
	(segment
		(start 189.052962 -356.0064)
		(end 189.281054 -355.778308)
		(width 0.254)
		(layer "In4.Cu")
		(net "PVDD11_S3_P1_VCCS")
	)
	(segment
		(start 187.915804 -352.975672)
		(end 188.195712 -352.695764)
		(width 0.2286)
		(layer "F.Cu")
		(net "PVDD11_S3_P1_VCC2")
	)
	(segment
		(start 187.563506 -352.975672)
		(end 187.915804 -352.975672)
		(width 0.2286)
		(layer "F.Cu")
		(net "PVDD11_S3_P1_VCC2")
	)
	(segment
		(start 188.195712 -352.695764)
		(end 188.84646 -352.695764)
		(width 0.2286)
		(layer "F.Cu")
		(net "PVDD11_S3_P1_VCC2")
	)
	(segment
		(start 191.056514 -354.22078)
		(end 191.056514 -354.932742)
		(width 0.2286)
		(layer "F.Cu")
		(net "PVDD11_S3_P1_VCC2")
	)
	(segment
		(start 187.563506 -353.586034)
		(end 187.563506 -352.975672)
		(width 0.4572)
		(layer "F.Cu")
		(net "PVDD11_S3_P1_VCC2")
	)
	(segment
		(start 191.056514 -354.932742)
		(end 190.980822 -355.008434)
		(width 0.2286)
		(layer "F.Cu")
		(net "PVDD11_S3_P1_VCC2")
	)
	(via
		(at 187.563506 -352.975672)
		(size 0.508)
		(drill 0.254)
		(layers "F.Cu" "B.Cu")
		(net "PVDD11_S3_P1_VCC2")
	)
	(via
		(at 190.980822 -355.008434)
		(size 0.508)
		(drill 0.254)
		(layers "F.Cu" "B.Cu")
		(net "PVDD11_S3_P1_VCC2")
	)
	(via
		(at 189.391036 -354.195634)
		(size 0.6604)
		(drill 0.3302)
		(layers "F.Cu" "B.Cu")
		(net "PVDD11_S3_P1_VCC2")
	)
	(segment
		(start 189.391036 -354.195634)
		(end 189.391036 -354.08997)
		(width 0.381)
		(layer "B.Cu")
		(net "PVDD11_S3_P1_VCC2")
	)
	(segment
		(start 189.704472 -354.50907)
		(end 189.391036 -354.195634)
		(width 0.4572)
		(layer "B.Cu")
		(net "PVDD11_S3_P1_VCC2")
	)
	(segment
		(start 188.230256 -352.975672)
		(end 188.425836 -352.780092)
		(width 0.381)
		(layer "B.Cu")
		(net "PVDD11_S3_P1_VCC2")
	)
	(segment
		(start 188.425836 -352.780092)
		(end 188.935614 -352.780092)
		(width 0.381)
		(layer "B.Cu")
		(net "PVDD11_S3_P1_VCC2")
	)
	(segment
		(start 190.481458 -354.50907)
		(end 189.704472 -354.50907)
		(width 0.4572)
		(layer "B.Cu")
		(net "PVDD11_S3_P1_VCC2")
	)
	(segment
		(start 188.935614 -353.634548)
		(end 188.935614 -352.780092)
		(width 0.381)
		(layer "B.Cu")
		(net "PVDD11_S3_P1_VCC2")
	)
	(segment
		(start 190.980822 -355.008434)
		(end 190.481458 -354.50907)
		(width 0.4572)
		(layer "B.Cu")
		(net "PVDD11_S3_P1_VCC2")
	)
	(segment
		(start 187.563506 -352.975672)
		(end 188.230256 -352.975672)
		(width 0.381)
		(layer "B.Cu")
		(net "PVDD11_S3_P1_VCC2")
	)
	(segment
		(start 189.391036 -354.08997)
		(end 188.935614 -353.634548)
		(width 0.381)
		(layer "B.Cu")
		(net "PVDD11_S3_P1_VCC2")
	)
	(segment
		(start 179.878736 -352.670364)
		(end 180.519832 -352.670364)
		(width 0.2286)
		(layer "F.Cu")
		(net "PVDD11_S3_P1_VCC1")
	)
	(segment
		(start 182.729886 -354.19538)
		(end 182.729886 -354.907342)
		(width 0.2286)
		(layer "F.Cu")
		(net "PVDD11_S3_P1_VCC1")
	)
	(segment
		(start 179.236878 -352.950272)
		(end 179.589176 -352.950272)
		(width 0.2286)
		(layer "F.Cu")
		(net "PVDD11_S3_P1_VCC1")
	)
	(segment
		(start 179.589176 -352.950272)
		(end 179.87391 -352.665538)
		(width 0.2286)
		(layer "F.Cu")
		(net "PVDD11_S3_P1_VCC1")
	)
	(segment
		(start 179.87391 -352.665538)
		(end 179.878736 -352.670364)
		(width 0.2286)
		(layer "F.Cu")
		(net "PVDD11_S3_P1_VCC1")
	)
	(segment
		(start 179.236878 -353.560634)
		(end 179.236878 -352.950272)
		(width 0.4572)
		(layer "F.Cu")
		(net "PVDD11_S3_P1_VCC1")
	)
	(segment
		(start 182.729886 -354.907342)
		(end 182.654194 -354.983034)
		(width 0.2286)
		(layer "F.Cu")
		(net "PVDD11_S3_P1_VCC1")
	)
	(via
		(at 182.654194 -354.983034)
		(size 0.508)
		(drill 0.254)
		(layers "F.Cu" "B.Cu")
		(net "PVDD11_S3_P1_VCC1")
	)
	(via
		(at 181.10708 -353.913694)
		(size 0.6604)
		(drill 0.3302)
		(layers "F.Cu" "B.Cu")
		(net "PVDD11_S3_P1_VCC1")
	)
	(via
		(at 179.236878 -352.950272)
		(size 0.508)
		(drill 0.254)
		(layers "F.Cu" "B.Cu")
		(net "PVDD11_S3_P1_VCC1")
	)
	(segment
		(start 181.10708 -353.913694)
		(end 180.608986 -353.4156)
		(width 0.381)
		(layer "B.Cu")
		(net "PVDD11_S3_P1_VCC1")
	)
	(segment
		(start 180.099208 -352.754692)
		(end 180.608986 -352.754692)
		(width 0.381)
		(layer "B.Cu")
		(net "PVDD11_S3_P1_VCC1")
	)
	(segment
		(start 179.236878 -352.950272)
		(end 179.903628 -352.950272)
		(width 0.381)
		(layer "B.Cu")
		(net "PVDD11_S3_P1_VCC1")
	)
	(segment
		(start 181.484778 -354.291392)
		(end 181.10708 -353.913694)
		(width 0.4572)
		(layer "B.Cu")
		(net "PVDD11_S3_P1_VCC1")
	)
	(segment
		(start 179.903628 -352.950272)
		(end 180.099208 -352.754692)
		(width 0.381)
		(layer "B.Cu")
		(net "PVDD11_S3_P1_VCC1")
	)
	(segment
		(start 180.608986 -353.4156)
		(end 180.608986 -352.754692)
		(width 0.381)
		(layer "B.Cu")
		(net "PVDD11_S3_P1_VCC1")
	)
	(segment
		(start 181.962552 -354.291392)
		(end 181.484778 -354.291392)
		(width 0.4572)
		(layer "B.Cu")
		(net "PVDD11_S3_P1_VCC1")
	)
	(segment
		(start 182.654194 -354.983034)
		(end 181.962552 -354.291392)
		(width 0.4572)
		(layer "B.Cu")
		(net "PVDD11_S3_P1_VCC1")
	)
	(segment
		(start 167.803576 -351.86366)
		(end 168.458896 -352.51898)
		(width 0.254)
		(layer "F.Cu")
		(net "PVDD11_S3_P1_VCC")
	)
	(segment
		(start 167.527986 -351.86366)
		(end 167.803576 -351.86366)
		(width 0.254)
		(layer "F.Cu")
		(net "PVDD11_S3_P1_VCC")
	)
	(via
		(at 168.458896 -352.51898)
		(size 0.762)
		(drill 0.381)
		(layers "F.Cu" "B.Cu")
		(net "PVDD11_S3_P1_VCC")
	)
	(segment
		(start 165.349428 -348.35338)
		(end 165.75786 -347.944948)
		(width 0.1524)
		(layer "F.Cu")
		(net "PVDD11_S3_P1_TEMP1")
	)
	(segment
		(start 165.75786 -347.944948)
		(end 165.887654 -347.944948)
		(width 0.1524)
		(layer "F.Cu")
		(net "PVDD11_S3_P1_TEMP1")
	)
	(segment
		(start 164.628576 -348.35338)
		(end 165.349428 -348.35338)
		(width 0.1524)
		(layer "F.Cu")
		(net "PVDD11_S3_P1_TEMP1")
	)
	(via
		(at 165.887654 -347.944948)
		(size 0.508)
		(drill 0.254)
		(layers "F.Cu" "B.Cu")
		(net "PVDD11_S3_P1_TEMP1")
	)
	(segment
		(start 165.522402 -348.180406)
		(end 165.75786 -347.944948)
		(width 0.1524)
		(layer "B.Cu")
		(net "PVDD11_S3_P1_TEMP1")
	)
	(segment
		(start 165.75786 -347.944948)
		(end 165.887654 -347.944948)
		(width 0.1524)
		(layer "B.Cu")
		(net "PVDD11_S3_P1_TEMP1")
	)
	(segment
		(start 164.725604 -348.180406)
		(end 165.522402 -348.180406)
		(width 0.1524)
		(layer "B.Cu")
		(net "PVDD11_S3_P1_TEMP1")
	)
	(segment
		(start 165.76167 -348.753176)
		(end 165.899846 -348.615)
		(width 0.1524)
		(layer "F.Cu")
		(net "PVDD11_S3_P1_TEMP0")
	)
	(segment
		(start 190.606426 -354.628196)
		(end 190.606426 -354.22078)
		(width 0.2286)
		(layer "F.Cu")
		(net "PVDD11_S3_P1_TEMP0")
	)
	(segment
		(start 190.28537 -355.254306)
		(end 190.28537 -354.949252)
		(width 0.2286)
		(layer "F.Cu")
		(net "PVDD11_S3_P1_TEMP0")
	)
	(segment
		(start 165.899846 -348.615)
		(end 166.20744 -348.615)
		(width 0.254)
		(layer "F.Cu")
		(net "PVDD11_S3_P1_TEMP0")
	)
	(segment
		(start 166.20744 -348.615)
		(end 166.537894 -348.284546)
		(width 0.254)
		(layer "F.Cu")
		(net "PVDD11_S3_P1_TEMP0")
	)
	(segment
		(start 190.28537 -354.949252)
		(end 190.606426 -354.628196)
		(width 0.2286)
		(layer "F.Cu")
		(net "PVDD11_S3_P1_TEMP0")
	)
	(segment
		(start 164.628576 -348.753176)
		(end 165.76167 -348.753176)
		(width 0.1524)
		(layer "F.Cu")
		(net "PVDD11_S3_P1_TEMP0")
	)
	(segment
		(start 182.279798 -354.621084)
		(end 182.279798 -354.19538)
		(width 0.2286)
		(layer "F.Cu")
		(net "PVDD11_S3_P1_TEMP0")
	)
	(segment
		(start 181.958742 -355.228906)
		(end 181.958742 -354.94214)
		(width 0.2286)
		(layer "F.Cu")
		(net "PVDD11_S3_P1_TEMP0")
	)
	(segment
		(start 181.958742 -354.94214)
		(end 182.279798 -354.621084)
		(width 0.2286)
		(layer "F.Cu")
		(net "PVDD11_S3_P1_TEMP0")
	)
	(via
		(at 165.899846 -348.615)
		(size 0.508)
		(drill 0.254)
		(layers "F.Cu" "B.Cu")
		(net "PVDD11_S3_P1_TEMP0")
	)
	(via
		(at 181.958742 -355.228906)
		(size 0.508)
		(drill 0.254)
		(layers "F.Cu" "B.Cu")
		(net "PVDD11_S3_P1_TEMP0")
	)
	(via
		(at 190.28537 -355.254306)
		(size 0.508)
		(drill 0.254)
		(layers "F.Cu" "B.Cu")
		(net "PVDD11_S3_P1_TEMP0")
	)
	(segment
		(start 182.680864 -357.526082)
		(end 181.958742 -356.80396)
		(width 0.254)
		(layer "In2.Cu")
		(net "PVDD11_S3_P1_TEMP0")
	)
	(segment
		(start 168.19499 -355.12121)
		(end 171.237148 -358.163368)
		(width 0.254)
		(layer "In2.Cu")
		(net "PVDD11_S3_P1_TEMP0")
	)
	(segment
		(start 180.512974 -358.163368)
		(end 180.966618 -357.709724)
		(width 0.254)
		(layer "In2.Cu")
		(net "PVDD11_S3_P1_TEMP0")
	)
	(segment
		(start 190.28537 -355.254306)
		(end 190.28537 -357.877618)
		(width 0.254)
		(layer "In2.Cu")
		(net "PVDD11_S3_P1_TEMP0")
	)
	(segment
		(start 181.916324 -356.761542)
		(end 181.958742 -356.80396)
		(width 0.254)
		(layer "In2.Cu")
		(net "PVDD11_S3_P1_TEMP0")
	)
	(segment
		(start 165.899846 -348.615)
		(end 167.353234 -350.068388)
		(width 0.254)
		(layer "In2.Cu")
		(net "PVDD11_S3_P1_TEMP0")
	)
	(segment
		(start 183.182768 -358.557322)
		(end 182.680864 -358.055418)
		(width 0.254)
		(layer "In2.Cu")
		(net "PVDD11_S3_P1_TEMP0")
	)
	(segment
		(start 167.353234 -350.068388)
		(end 168.19499 -352.100642)
		(width 0.254)
		(layer "In2.Cu")
		(net "PVDD11_S3_P1_TEMP0")
	)
	(segment
		(start 189.605666 -358.557322)
		(end 183.182768 -358.557322)
		(width 0.254)
		(layer "In2.Cu")
		(net "PVDD11_S3_P1_TEMP0")
	)
	(segment
		(start 182.680864 -358.055418)
		(end 182.680864 -357.526082)
		(width 0.254)
		(layer "In2.Cu")
		(net "PVDD11_S3_P1_TEMP0")
	)
	(segment
		(start 180.966618 -357.14305)
		(end 181.348126 -356.761542)
		(width 0.254)
		(layer "In2.Cu")
		(net "PVDD11_S3_P1_TEMP0")
	)
	(segment
		(start 181.958742 -356.80396)
		(end 181.958742 -355.228906)
		(width 0.254)
		(layer "In2.Cu")
		(net "PVDD11_S3_P1_TEMP0")
	)
	(segment
		(start 190.28537 -357.877618)
		(end 189.605666 -358.557322)
		(width 0.254)
		(layer "In2.Cu")
		(net "PVDD11_S3_P1_TEMP0")
	)
	(segment
		(start 181.348126 -356.761542)
		(end 181.916324 -356.761542)
		(width 0.254)
		(layer "In2.Cu")
		(net "PVDD11_S3_P1_TEMP0")
	)
	(segment
		(start 180.966618 -357.709724)
		(end 180.966618 -357.14305)
		(width 0.254)
		(layer "In2.Cu")
		(net "PVDD11_S3_P1_TEMP0")
	)
	(segment
		(start 171.237148 -358.163368)
		(end 180.512974 -358.163368)
		(width 0.254)
		(layer "In2.Cu")
		(net "PVDD11_S3_P1_TEMP0")
	)
	(segment
		(start 168.19499 -352.100642)
		(end 168.19499 -355.12121)
		(width 0.254)
		(layer "In2.Cu")
		(net "PVDD11_S3_P1_TEMP0")
	)
	(segment
		(start 158.69793 -348.807278)
		(end 158.69793 -348.779846)
		(width 0.10668)
		(layer "F.Cu")
		(net "PVDD11_S3_P1_RESET_N_R")
	)
	(segment
		(start 158.668466 -348.807278)
		(end 158.204916 -349.270828)
		(width 0.10668)
		(layer "F.Cu")
		(net "PVDD11_S3_P1_RESET_N_R")
	)
	(segment
		(start 158.198312 -348.280228)
		(end 158.086552 -348.280228)
		(width 0.10668)
		(layer "F.Cu")
		(net "PVDD11_S3_P1_RESET_N_R")
	)
	(segment
		(start 158.204916 -349.270828)
		(end 158.086552 -349.270828)
		(width 0.10668)
		(layer "F.Cu")
		(net "PVDD11_S3_P1_RESET_N_R")
	)
	(segment
		(start 158.69793 -348.779846)
		(end 158.198312 -348.280228)
		(width 0.10668)
		(layer "F.Cu")
		(net "PVDD11_S3_P1_RESET_N_R")
	)
	(segment
		(start 158.69793 -348.807278)
		(end 158.668466 -348.807278)
		(width 0.10668)
		(layer "F.Cu")
		(net "PVDD11_S3_P1_RESET_N_R")
	)
	(segment
		(start 159.828484 -349.153226)
		(end 159.043878 -349.153226)
		(width 0.10668)
		(layer "F.Cu")
		(net "PVDD11_S3_P1_RESET_N_R")
	)
	(segment
		(start 159.043878 -349.153226)
		(end 158.69793 -348.807278)
		(width 0.10668)
		(layer "F.Cu")
		(net "PVDD11_S3_P1_RESET_N_R")
	)
	(via
		(at 158.69793 -348.807278)
		(size 0.508)
		(drill 0.254)
		(layers "F.Cu" "B.Cu")
		(net "PVDD11_S3_P1_RESET_N_R")
	)
	(segment
		(start 159.08655 -348.418658)
		(end 159.08655 -348.10319)
		(width 0.10668)
		(layer "B.Cu")
		(net "PVDD11_S3_P1_RESET_N_R")
	)
	(segment
		(start 158.69793 -348.807278)
		(end 159.08655 -348.418658)
		(width 0.10668)
		(layer "B.Cu")
		(net "PVDD11_S3_P1_RESET_N_R")
	)
	(segment
		(start 159.08655 -348.10319)
		(end 159.526732 -347.663008)
		(width 0.10668)
		(layer "B.Cu")
		(net "PVDD11_S3_P1_RESET_N_R")
	)
	(segment
		(start 212.925406 -197.997064)
		(end 208.989676 -201.932794)
		(width 0.10668)
		(layer "F.Cu")
		(net "PVDD11_S3_P1_RESET_N")
	)
	(segment
		(start 193.684398 -168.844722)
		(end 196.643244 -168.844722)
		(width 0.10668)
		(layer "F.Cu")
		(net "PVDD11_S3_P1_RESET_N")
	)
	(segment
		(start 157.286452 -348.280228)
		(end 155.157424 -348.280228)
		(width 0.10668)
		(layer "F.Cu")
		(net "PVDD11_S3_P1_RESET_N")
	)
	(segment
		(start 212.925406 -188.029596)
		(end 212.925406 -197.997064)
		(width 0.10668)
		(layer "F.Cu")
		(net "PVDD11_S3_P1_RESET_N")
	)
	(segment
		(start 155.157424 -348.280228)
		(end 154.469592 -348.96806)
		(width 0.10668)
		(layer "F.Cu")
		(net "PVDD11_S3_P1_RESET_N")
	)
	(segment
		(start 182.722012 -118.652798)
		(end 182.332122 -119.042688)
		(width 0.10668)
		(layer "F.Cu")
		(net "PVDD11_S3_P1_RESET_N")
	)
	(segment
		(start 196.643244 -168.844722)
		(end 210.872832 -183.07431)
		(width 0.10668)
		(layer "F.Cu")
		(net "PVDD11_S3_P1_RESET_N")
	)
	(segment
		(start 191.340486 -166.50081)
		(end 193.684398 -168.844722)
		(width 0.10668)
		(layer "F.Cu")
		(net "PVDD11_S3_P1_RESET_N")
	)
	(segment
		(start 210.872832 -183.07431)
		(end 212.925406 -188.029596)
		(width 0.10668)
		(layer "F.Cu")
		(net "PVDD11_S3_P1_RESET_N")
	)
	(via
		(at 186.279028 -160.927796)
		(size 0.508)
		(drill 0.254)
		(layers "F.Cu" "B.Cu")
		(net "PVDD11_S3_P1_RESET_N")
	)
	(via
		(at 154.469592 -348.96806)
		(size 0.508)
		(drill 0.254)
		(layers "F.Cu" "B.Cu")
		(net "PVDD11_S3_P1_RESET_N")
	)
	(via
		(at 191.340486 -166.50081)
		(size 0.508)
		(drill 0.254)
		(layers "F.Cu" "B.Cu")
		(net "PVDD11_S3_P1_RESET_N")
	)
	(via
		(at 174.103792 -361.476798)
		(size 0.508)
		(drill 0.254)
		(layers "F.Cu" "B.Cu")
		(net "PVDD11_S3_P1_RESET_N")
	)
	(via
		(at 182.332122 -119.042688)
		(size 0.4572)
		(drill 0.254)
		(layers "F.Cu" "B.Cu")
		(net "PVDD11_S3_P1_RESET_N")
	)
	(via
		(at 208.989676 -201.932794)
		(size 0.508)
		(drill 0.254)
		(layers "F.Cu" "B.Cu")
		(net "PVDD11_S3_P1_RESET_N")
	)
	(segment
		(start 154.469592 -348.96806)
		(end 154.469592 -349.505524)
		(width 0.10668)
		(layer "B.Cu")
		(net "PVDD11_S3_P1_RESET_N")
	)
	(segment
		(start 168.340278 -357.622348)
		(end 172.194728 -361.476798)
		(width 0.10668)
		(layer "B.Cu")
		(net "PVDD11_S3_P1_RESET_N")
	)
	(segment
		(start 172.194728 -361.476798)
		(end 174.103792 -361.476798)
		(width 0.10668)
		(layer "B.Cu")
		(net "PVDD11_S3_P1_RESET_N")
	)
	(segment
		(start 186.279028 -161.75228)
		(end 186.279028 -160.927796)
		(width 0.10668)
		(layer "B.Cu")
		(net "PVDD11_S3_P1_RESET_N")
	)
	(segment
		(start 153.40457 -353.510088)
		(end 157.51683 -357.622348)
		(width 0.10668)
		(layer "B.Cu")
		(net "PVDD11_S3_P1_RESET_N")
	)
	(segment
		(start 187.494672 -162.654996)
		(end 187.181744 -162.654996)
		(width 0.10668)
		(layer "B.Cu")
		(net "PVDD11_S3_P1_RESET_N")
	)
	(segment
		(start 187.181744 -162.654996)
		(end 186.279028 -161.75228)
		(width 0.10668)
		(layer "B.Cu")
		(net "PVDD11_S3_P1_RESET_N")
	)
	(segment
		(start 191.340486 -166.50081)
		(end 187.494672 -162.654996)
		(width 0.10668)
		(layer "B.Cu")
		(net "PVDD11_S3_P1_RESET_N")
	)
	(segment
		(start 153.40457 -350.570546)
		(end 153.40457 -353.510088)
		(width 0.10668)
		(layer "B.Cu")
		(net "PVDD11_S3_P1_RESET_N")
	)
	(segment
		(start 154.469592 -349.505524)
		(end 153.40457 -350.570546)
		(width 0.10668)
		(layer "B.Cu")
		(net "PVDD11_S3_P1_RESET_N")
	)
	(segment
		(start 157.51683 -357.622348)
		(end 168.340278 -357.622348)
		(width 0.10668)
		(layer "B.Cu")
		(net "PVDD11_S3_P1_RESET_N")
	)
	(segment
		(start 184.541922 -133.235446)
		(end 183.471566 -134.305802)
		(width 0.11684)
		(layer "In4.Cu")
		(net "PVDD11_S3_P1_RESET_N")
	)
	(segment
		(start 182.42788 -119.042688)
		(end 182.725568 -119.340376)
		(width 0.11684)
		(layer "In4.Cu")
		(net "PVDD11_S3_P1_RESET_N")
	)
	(segment
		(start 183.53532 -128.923542)
		(end 184.541922 -129.930144)
		(width 0.11684)
		(layer "In4.Cu")
		(net "PVDD11_S3_P1_RESET_N")
	)
	(segment
		(start 184.60974 -138.228324)
		(end 184.60974 -141.277848)
		(width 0.11684)
		(layer "In4.Cu")
		(net "PVDD11_S3_P1_RESET_N")
	)
	(segment
		(start 182.725568 -119.340376)
		(end 182.725568 -120.053862)
		(width 0.11684)
		(layer "In4.Cu")
		(net "PVDD11_S3_P1_RESET_N")
	)
	(segment
		(start 183.40705 -120.244616)
		(end 183.53532 -120.372886)
		(width 0.11684)
		(layer "In4.Cu")
		(net "PVDD11_S3_P1_RESET_N")
	)
	(segment
		(start 185.510424 -149.537928)
		(end 184.541922 -150.50643)
		(width 0.11684)
		(layer "In4.Cu")
		(net "PVDD11_S3_P1_RESET_N")
	)
	(segment
		(start 185.655966 -155.24226)
		(end 185.655966 -160.304734)
		(width 0.11684)
		(layer "In4.Cu")
		(net "PVDD11_S3_P1_RESET_N")
	)
	(segment
		(start 184.541922 -150.50643)
		(end 184.541922 -154.128216)
		(width 0.11684)
		(layer "In4.Cu")
		(net "PVDD11_S3_P1_RESET_N")
	)
	(segment
		(start 182.916322 -120.244616)
		(end 183.40705 -120.244616)
		(width 0.11684)
		(layer "In4.Cu")
		(net "PVDD11_S3_P1_RESET_N")
	)
	(segment
		(start 183.53532 -120.372886)
		(end 183.53532 -128.923542)
		(width 0.11684)
		(layer "In4.Cu")
		(net "PVDD11_S3_P1_RESET_N")
	)
	(segment
		(start 183.471566 -134.305802)
		(end 183.471566 -137.09015)
		(width 0.11684)
		(layer "In4.Cu")
		(net "PVDD11_S3_P1_RESET_N")
	)
	(segment
		(start 183.471566 -137.09015)
		(end 184.60974 -138.228324)
		(width 0.11684)
		(layer "In4.Cu")
		(net "PVDD11_S3_P1_RESET_N")
	)
	(segment
		(start 184.60974 -141.277848)
		(end 185.510424 -142.178532)
		(width 0.11684)
		(layer "In4.Cu")
		(net "PVDD11_S3_P1_RESET_N")
	)
	(segment
		(start 184.541922 -154.128216)
		(end 185.655966 -155.24226)
		(width 0.11684)
		(layer "In4.Cu")
		(net "PVDD11_S3_P1_RESET_N")
	)
	(segment
		(start 184.541922 -129.930144)
		(end 184.541922 -133.235446)
		(width 0.11684)
		(layer "In4.Cu")
		(net "PVDD11_S3_P1_RESET_N")
	)
	(segment
		(start 185.655966 -160.304734)
		(end 186.279028 -160.927796)
		(width 0.11684)
		(layer "In4.Cu")
		(net "PVDD11_S3_P1_RESET_N")
	)
	(segment
		(start 185.510424 -142.178532)
		(end 185.510424 -149.537928)
		(width 0.11684)
		(layer "In4.Cu")
		(net "PVDD11_S3_P1_RESET_N")
	)
	(segment
		(start 182.725568 -120.053862)
		(end 182.916322 -120.244616)
		(width 0.11684)
		(layer "In4.Cu")
		(net "PVDD11_S3_P1_RESET_N")
	)
	(segment
		(start 182.332122 -119.042688)
		(end 182.42788 -119.042688)
		(width 0.11684)
		(layer "In4.Cu")
		(net "PVDD11_S3_P1_RESET_N")
	)
	(segment
		(start 212.722714 -321.981322)
		(end 212.722714 -205.226412)
		(width 0.11684)
		(layer "In6.Cu")
		(net "PVDD11_S3_P1_RESET_N")
	)
	(segment
		(start 176.426622 -363.975904)
		(end 180.689504 -368.238786)
		(width 0.11684)
		(layer "In6.Cu")
		(net "PVDD11_S3_P1_RESET_N")
	)
	(segment
		(start 223.64446 -358.135428)
		(end 223.64446 -332.903068)
		(width 0.11684)
		(layer "In6.Cu")
		(net "PVDD11_S3_P1_RESET_N")
	)
	(segment
		(start 219.942156 -367.02492)
		(end 219.942156 -364.826296)
		(width 0.11684)
		(layer "In6.Cu")
		(net "PVDD11_S3_P1_RESET_N")
	)
	(segment
		(start 221.289626 -360.490262)
		(end 223.64446 -358.135428)
		(width 0.11684)
		(layer "In6.Cu")
		(net "PVDD11_S3_P1_RESET_N")
	)
	(segment
		(start 212.722714 -205.226412)
		(end 209.429096 -201.932794)
		(width 0.11684)
		(layer "In6.Cu")
		(net "PVDD11_S3_P1_RESET_N")
	)
	(segment
		(start 221.289626 -363.478826)
		(end 221.289626 -360.490262)
		(width 0.11684)
		(layer "In6.Cu")
		(net "PVDD11_S3_P1_RESET_N")
	)
	(segment
		(start 180.689504 -368.238786)
		(end 218.72829 -368.238786)
		(width 0.11684)
		(layer "In6.Cu")
		(net "PVDD11_S3_P1_RESET_N")
	)
	(segment
		(start 223.64446 -332.903068)
		(end 212.722714 -321.981322)
		(width 0.11684)
		(layer "In6.Cu")
		(net "PVDD11_S3_P1_RESET_N")
	)
	(segment
		(start 174.103792 -362.195364)
		(end 175.884332 -363.975904)
		(width 0.11684)
		(layer "In6.Cu")
		(net "PVDD11_S3_P1_RESET_N")
	)
	(segment
		(start 219.942156 -364.826296)
		(end 221.289626 -363.478826)
		(width 0.11684)
		(layer "In6.Cu")
		(net "PVDD11_S3_P1_RESET_N")
	)
	(segment
		(start 209.429096 -201.932794)
		(end 208.989676 -201.932794)
		(width 0.11684)
		(layer "In6.Cu")
		(net "PVDD11_S3_P1_RESET_N")
	)
	(segment
		(start 218.72829 -368.238786)
		(end 219.942156 -367.02492)
		(width 0.11684)
		(layer "In6.Cu")
		(net "PVDD11_S3_P1_RESET_N")
	)
	(segment
		(start 174.103792 -361.476798)
		(end 174.103792 -362.195364)
		(width 0.11684)
		(layer "In6.Cu")
		(net "PVDD11_S3_P1_RESET_N")
	)
	(segment
		(start 175.884332 -363.975904)
		(end 176.426622 -363.975904)
		(width 0.11684)
		(layer "In6.Cu")
		(net "PVDD11_S3_P1_RESET_N")
	)
	(segment
		(start 191.506602 -355.325426)
		(end 191.506602 -354.22078)
		(width 0.1778)
		(layer "F.Cu")
		(net "PVDD11_S3_P1_PWM2")
	)
	(segment
		(start 161.628582 -351.262442)
		(end 162.026854 -351.660714)
		(width 0.1524)
		(layer "F.Cu")
		(net "PVDD11_S3_P1_PWM2")
	)
	(segment
		(start 161.628582 -350.953324)
		(end 161.628582 -351.262442)
		(width 0.1524)
		(layer "F.Cu")
		(net "PVDD11_S3_P1_PWM2")
	)
	(segment
		(start 162.026854 -351.660714)
		(end 162.065462 -351.660714)
		(width 0.1524)
		(layer "F.Cu")
		(net "PVDD11_S3_P1_PWM2")
	)
	(segment
		(start 191.171322 -355.660706)
		(end 191.506602 -355.325426)
		(width 0.1778)
		(layer "F.Cu")
		(net "PVDD11_S3_P1_PWM2")
	)
	(via
		(at 191.171322 -355.660706)
		(size 0.508)
		(drill 0.254)
		(layers "F.Cu" "B.Cu")
		(net "PVDD11_S3_P1_PWM2")
	)
	(via
		(at 162.065462 -351.660714)
		(size 0.508)
		(drill 0.254)
		(layers "F.Cu" "B.Cu")
		(net "PVDD11_S3_P1_PWM2")
	)
	(segment
		(start 163.462208 -354.831396)
		(end 168.594278 -354.831396)
		(width 0.1524)
		(layer "In6.Cu")
		(net "PVDD11_S3_P1_PWM2")
	)
	(segment
		(start 191.100964 -355.731064)
		(end 191.171322 -355.660706)
		(width 0.1524)
		(layer "In6.Cu")
		(net "PVDD11_S3_P1_PWM2")
	)
	(segment
		(start 190.828168 -355.731064)
		(end 191.100964 -355.731064)
		(width 0.1524)
		(layer "In6.Cu")
		(net "PVDD11_S3_P1_PWM2")
	)
	(segment
		(start 162.692588 -352.28784)
		(end 162.692588 -354.061776)
		(width 0.1524)
		(layer "In6.Cu")
		(net "PVDD11_S3_P1_PWM2")
	)
	(segment
		(start 188.259974 -358.299258)
		(end 190.828168 -355.731064)
		(width 0.1524)
		(layer "In6.Cu")
		(net "PVDD11_S3_P1_PWM2")
	)
	(segment
		(start 168.594278 -354.831396)
		(end 172.06214 -358.299258)
		(width 0.1524)
		(layer "In6.Cu")
		(net "PVDD11_S3_P1_PWM2")
	)
	(segment
		(start 162.065462 -351.660714)
		(end 162.692588 -352.28784)
		(width 0.1524)
		(layer "In6.Cu")
		(net "PVDD11_S3_P1_PWM2")
	)
	(segment
		(start 162.692588 -354.061776)
		(end 163.462208 -354.831396)
		(width 0.1524)
		(layer "In6.Cu")
		(net "PVDD11_S3_P1_PWM2")
	)
	(segment
		(start 172.06214 -358.299258)
		(end 188.259974 -358.299258)
		(width 0.1524)
		(layer "In6.Cu")
		(net "PVDD11_S3_P1_PWM2")
	)
	(segment
		(start 161.228532 -350.953324)
		(end 161.228532 -351.59188)
		(width 0.1524)
		(layer "F.Cu")
		(net "PVDD11_S3_P1_PWM1")
	)
	(segment
		(start 183.179974 -355.300026)
		(end 183.179974 -354.19538)
		(width 0.1778)
		(layer "F.Cu")
		(net "PVDD11_S3_P1_PWM1")
	)
	(segment
		(start 161.228532 -351.59188)
		(end 161.28873 -351.652078)
		(width 0.1524)
		(layer "F.Cu")
		(net "PVDD11_S3_P1_PWM1")
	)
	(segment
		(start 182.844694 -355.635306)
		(end 183.179974 -355.300026)
		(width 0.1778)
		(layer "F.Cu")
		(net "PVDD11_S3_P1_PWM1")
	)
	(via
		(at 182.844694 -355.635306)
		(size 0.508)
		(drill 0.254)
		(layers "F.Cu" "B.Cu")
		(net "PVDD11_S3_P1_PWM1")
	)
	(via
		(at 161.28873 -351.652078)
		(size 0.508)
		(drill 0.254)
		(layers "F.Cu" "B.Cu")
		(net "PVDD11_S3_P1_PWM1")
	)
	(segment
		(start 173.081696 -356.72395)
		(end 181.670198 -356.72395)
		(width 0.1524)
		(layer "In6.Cu")
		(net "PVDD11_S3_P1_PWM1")
	)
	(segment
		(start 161.28873 -351.49536)
		(end 161.795714 -350.988376)
		(width 0.1524)
		(layer "In6.Cu")
		(net "PVDD11_S3_P1_PWM1")
	)
	(segment
		(start 164.049964 -352.515678)
		(end 168.873424 -352.515678)
		(width 0.1524)
		(layer "In6.Cu")
		(net "PVDD11_S3_P1_PWM1")
	)
	(segment
		(start 168.873424 -352.515678)
		(end 173.081696 -356.72395)
		(width 0.1524)
		(layer "In6.Cu")
		(net "PVDD11_S3_P1_PWM1")
	)
	(segment
		(start 162.522662 -350.988376)
		(end 164.049964 -352.515678)
		(width 0.1524)
		(layer "In6.Cu")
		(net "PVDD11_S3_P1_PWM1")
	)
	(segment
		(start 181.670198 -356.72395)
		(end 182.758842 -355.635306)
		(width 0.1524)
		(layer "In6.Cu")
		(net "PVDD11_S3_P1_PWM1")
	)
	(segment
		(start 161.28873 -351.652078)
		(end 161.28873 -351.49536)
		(width 0.1524)
		(layer "In6.Cu")
		(net "PVDD11_S3_P1_PWM1")
	)
	(segment
		(start 161.795714 -350.988376)
		(end 162.522662 -350.988376)
		(width 0.1524)
		(layer "In6.Cu")
		(net "PVDD11_S3_P1_PWM1")
	)
	(segment
		(start 182.758842 -355.635306)
		(end 182.844694 -355.635306)
		(width 0.1524)
		(layer "In6.Cu")
		(net "PVDD11_S3_P1_PWM1")
	)
	(segment
		(start 188.310774 -352.24593)
		(end 188.84646 -352.24593)
		(width 0.2286)
		(layer "F.Cu")
		(net "PVDD11_S3_P1_PVCC")
	)
	(segment
		(start 180.174392 -352.22053)
		(end 180.519832 -352.22053)
		(width 0.2286)
		(layer "F.Cu")
		(net "PVDD11_S3_P1_PVCC")
	)
	(segment
		(start 187.563506 -351.719134)
		(end 187.783978 -351.719134)
		(width 0.2286)
		(layer "F.Cu")
		(net "PVDD11_S3_P1_PVCC")
	)
	(segment
		(start 179.236878 -351.693734)
		(end 179.647596 -351.693734)
		(width 0.2286)
		(layer "F.Cu")
		(net "PVDD11_S3_P1_PVCC")
	)
	(segment
		(start 187.783978 -351.719134)
		(end 188.310774 -352.24593)
		(width 0.2286)
		(layer "F.Cu")
		(net "PVDD11_S3_P1_PVCC")
	)
	(segment
		(start 179.647596 -351.693734)
		(end 180.174392 -352.22053)
		(width 0.2286)
		(layer "F.Cu")
		(net "PVDD11_S3_P1_PVCC")
	)
	(segment
		(start 187.563506 -352.330258)
		(end 187.563506 -351.719134)
		(width 0.4572)
		(layer "F.Cu")
		(net "PVDD11_S3_P1_PVCC")
	)
	(via
		(at 177.391314 -351.847912)
		(size 0.762)
		(drill 0.381)
		(layers "F.Cu" "B.Cu")
		(net "PVDD11_S3_P1_PVCC")
	)
	(via
		(at 187.563506 -352.330258)
		(size 0.508)
		(drill 0.254)
		(layers "F.Cu" "B.Cu")
		(net "PVDD11_S3_P1_PVCC")
	)
	(via
		(at 179.236878 -352.304858)
		(size 0.508)
		(drill 0.254)
		(layers "F.Cu" "B.Cu")
		(net "PVDD11_S3_P1_PVCC")
	)
	(segment
		(start 187.935362 -351.979992)
		(end 187.585096 -352.330258)
		(width 0.381)
		(layer "B.Cu")
		(net "PVDD11_S3_P1_PVCC")
	)
	(segment
		(start 188.935614 -351.979992)
		(end 187.935362 -351.979992)
		(width 0.381)
		(layer "B.Cu")
		(net "PVDD11_S3_P1_PVCC")
	)
	(segment
		(start 179.608734 -351.954592)
		(end 179.258468 -352.304858)
		(width 0.381)
		(layer "B.Cu")
		(net "PVDD11_S3_P1_PVCC")
	)
	(segment
		(start 187.585096 -352.330258)
		(end 187.563506 -352.330258)
		(width 0.381)
		(layer "B.Cu")
		(net "PVDD11_S3_P1_PVCC")
	)
	(segment
		(start 180.608986 -351.954592)
		(end 179.608734 -351.954592)
		(width 0.381)
		(layer "B.Cu")
		(net "PVDD11_S3_P1_PVCC")
	)
	(segment
		(start 179.258468 -352.304858)
		(end 179.236878 -352.304858)
		(width 0.381)
		(layer "B.Cu")
		(net "PVDD11_S3_P1_PVCC")
	)
	(segment
		(start 179.794154 -346.983812)
		(end 180.302154 -346.475812)
		(width 0.508)
		(layer "In6.Cu")
		(net "PVDD11_S3_P1_PVCC")
	)
	(segment
		(start 187.906914 -347.771212)
		(end 187.906914 -351.98685)
		(width 0.508)
		(layer "In6.Cu")
		(net "PVDD11_S3_P1_PVCC")
	)
	(segment
		(start 187.906914 -351.98685)
		(end 187.563506 -352.330258)
		(width 0.508)
		(layer "In6.Cu")
		(net "PVDD11_S3_P1_PVCC")
	)
	(segment
		(start 179.236878 -352.304858)
		(end 179.236878 -351.247202)
		(width 0.508)
		(layer "In6.Cu")
		(net "PVDD11_S3_P1_PVCC")
	)
	(segment
		(start 179.236878 -351.247202)
		(end 179.794154 -350.689926)
		(width 0.508)
		(layer "In6.Cu")
		(net "PVDD11_S3_P1_PVCC")
	)
	(segment
		(start 186.611514 -346.475812)
		(end 187.906914 -347.771212)
		(width 0.508)
		(layer "In6.Cu")
		(net "PVDD11_S3_P1_PVCC")
	)
	(segment
		(start 180.302154 -346.475812)
		(end 186.611514 -346.475812)
		(width 0.508)
		(layer "In6.Cu")
		(net "PVDD11_S3_P1_PVCC")
	)
	(segment
		(start 179.794154 -350.689926)
		(end 179.794154 -346.983812)
		(width 0.508)
		(layer "In6.Cu")
		(net "PVDD11_S3_P1_PVCC")
	)
	(segment
		(start 160.706562 -351.292668)
		(end 160.828482 -351.170748)
		(width 0.10668)
		(layer "F.Cu")
		(net "PVDD11_S3_P1_PMSDA_R")
	)
	(segment
		(start 160.828482 -351.170748)
		(end 160.828482 -350.953324)
		(width 0.10668)
		(layer "F.Cu")
		(net "PVDD11_S3_P1_PMSDA_R")
	)
	(segment
		(start 161.503868 -352.268028)
		(end 161.06013 -352.268028)
		(width 0.10668)
		(layer "F.Cu")
		(net "PVDD11_S3_P1_PMSDA_R")
	)
	(segment
		(start 162.267138 -353.031298)
		(end 161.503868 -352.268028)
		(width 0.10668)
		(layer "F.Cu")
		(net "PVDD11_S3_P1_PMSDA_R")
	)
	(segment
		(start 160.706562 -351.91446)
		(end 160.706562 -351.292668)
		(width 0.10668)
		(layer "F.Cu")
		(net "PVDD11_S3_P1_PMSDA_R")
	)
	(segment
		(start 161.06013 -352.268028)
		(end 160.706562 -351.91446)
		(width 0.10668)
		(layer "F.Cu")
		(net "PVDD11_S3_P1_PMSDA_R")
	)
	(via
		(at 162.267138 -353.031298)
		(size 0.762)
		(drill 0.381)
		(layers "F.Cu" "B.Cu")
		(net "PVDD11_S3_P1_PMSDA_R")
	)
	(segment
		(start 160.428432 -351.2439)
		(end 160.06953 -351.602802)
		(width 0.10668)
		(layer "F.Cu")
		(net "PVDD11_S3_P1_PMSCL_R")
	)
	(segment
		(start 160.428432 -350.953324)
		(end 160.428432 -351.2439)
		(width 0.10668)
		(layer "F.Cu")
		(net "PVDD11_S3_P1_PMSCL_R")
	)
	(segment
		(start 160.06953 -351.602802)
		(end 160.06953 -352.268028)
		(width 0.10668)
		(layer "F.Cu")
		(net "PVDD11_S3_P1_PMSCL_R")
	)
	(via
		(at 160.06953 -351.602802)
		(size 0.508)
		(drill 0.254)
		(layers "F.Cu" "B.Cu")
		(net "PVDD11_S3_P1_PMSCL_R")
	)
	(segment
		(start 159.561276 -352.750374)
		(end 159.561276 -354.483416)
		(width 0.10668)
		(layer "F.Cu")
		(net "PVDD11_S3_P1_PMALERT_R")
	)
	(segment
		(start 159.380174 -350.801686)
		(end 159.828484 -350.353376)
		(width 0.10668)
		(layer "F.Cu")
		(net "PVDD11_S3_P1_PMALERT_R")
	)
	(segment
		(start 159.07893 -352.268028)
		(end 159.561276 -352.750374)
		(width 0.10668)
		(layer "F.Cu")
		(net "PVDD11_S3_P1_PMALERT_R")
	)
	(segment
		(start 159.07893 -352.268028)
		(end 159.380174 -351.966784)
		(width 0.10668)
		(layer "F.Cu")
		(net "PVDD11_S3_P1_PMALERT_R")
	)
	(segment
		(start 159.380174 -351.966784)
		(end 159.380174 -350.801686)
		(width 0.10668)
		(layer "F.Cu")
		(net "PVDD11_S3_P1_PMALERT_R")
	)
	(via
		(at 159.561276 -354.483416)
		(size 0.762)
		(drill 0.381)
		(layers "F.Cu" "B.Cu")
		(net "PVDD11_S3_P1_PMALERT_R")
	)
	(segment
		(start 221.482412 -144.062196)
		(end 221.482412 -137.095992)
		(width 0.10668)
		(layer "F.Cu")
		(net "PVDD11_S3_P1_PMALERT")
	)
	(segment
		(start 222.354648 -202.5269)
		(end 223.749362 -201.132186)
		(width 0.10668)
		(layer "F.Cu")
		(net "PVDD11_S3_P1_PMALERT")
	)
	(segment
		(start 158.286704 -353.036632)
		(end 159.047434 -353.036632)
		(width 0.10668)
		(layer "F.Cu")
		(net "PVDD11_S3_P1_PMALERT")
	)
	(segment
		(start 185.801 -100.694998)
		(end 185.7502 -100.745798)
		(width 0.10668)
		(layer "F.Cu")
		(net "PVDD11_S3_P1_PMALERT")
	)
	(segment
		(start 218.990164 -115.151916)
		(end 220.54566 -113.59642)
		(width 0.10668)
		(layer "F.Cu")
		(net "PVDD11_S3_P1_PMALERT")
	)
	(segment
		(start 218.990164 -122.69089)
		(end 218.990164 -115.151916)
		(width 0.10668)
		(layer "F.Cu")
		(net "PVDD11_S3_P1_PMALERT")
	)
	(segment
		(start 223.749362 -199.52843)
		(end 224.28835 -198.989442)
		(width 0.10668)
		(layer "F.Cu")
		(net "PVDD11_S3_P1_PMALERT")
	)
	(segment
		(start 221.944692 -136.633712)
		(end 221.944692 -125.645418)
		(width 0.10668)
		(layer "F.Cu")
		(net "PVDD11_S3_P1_PMALERT")
	)
	(segment
		(start 158.077408 -353.89439)
		(end 158.077408 -353.245928)
		(width 0.10668)
		(layer "F.Cu")
		(net "PVDD11_S3_P1_PMALERT")
	)
	(segment
		(start 185.674 -101.33203)
		(end 185.674 -105.011474)
		(width 0.10668)
		(layer "F.Cu")
		(net "PVDD11_S3_P1_PMALERT")
	)
	(segment
		(start 223.749362 -201.132186)
		(end 223.749362 -199.52843)
		(width 0.10668)
		(layer "F.Cu")
		(net "PVDD11_S3_P1_PMALERT")
	)
	(segment
		(start 220.54566 -113.59642)
		(end 220.54566 -109.087158)
		(width 0.10668)
		(layer "F.Cu")
		(net "PVDD11_S3_P1_PMALERT")
	)
	(segment
		(start 222.923862 -164.273992)
		(end 219.710762 -161.060892)
		(width 0.10668)
		(layer "F.Cu")
		(net "PVDD11_S3_P1_PMALERT")
	)
	(segment
		(start 159.047434 -353.036632)
		(end 159.07893 -353.068128)
		(width 0.10668)
		(layer "F.Cu")
		(net "PVDD11_S3_P1_PMALERT")
	)
	(segment
		(start 185.726832 -101.279198)
		(end 185.674 -101.33203)
		(width 0.10668)
		(layer "F.Cu")
		(net "PVDD11_S3_P1_PMALERT")
	)
	(segment
		(start 222.923862 -166.706804)
		(end 222.923862 -164.273992)
		(width 0.10668)
		(layer "F.Cu")
		(net "PVDD11_S3_P1_PMALERT")
	)
	(segment
		(start 219.710762 -161.060892)
		(end 219.710762 -145.833846)
		(width 0.10668)
		(layer "F.Cu")
		(net "PVDD11_S3_P1_PMALERT")
	)
	(segment
		(start 219.710762 -145.833846)
		(end 221.482412 -144.062196)
		(width 0.10668)
		(layer "F.Cu")
		(net "PVDD11_S3_P1_PMALERT")
	)
	(segment
		(start 224.28835 -198.989442)
		(end 224.28835 -168.071292)
		(width 0.10668)
		(layer "F.Cu")
		(net "PVDD11_S3_P1_PMALERT")
	)
	(segment
		(start 185.7502 -100.745798)
		(end 185.7502 -101.25583)
		(width 0.10668)
		(layer "F.Cu")
		(net "PVDD11_S3_P1_PMALERT")
	)
	(segment
		(start 224.28835 -168.071292)
		(end 222.923862 -166.706804)
		(width 0.10668)
		(layer "F.Cu")
		(net "PVDD11_S3_P1_PMALERT")
	)
	(segment
		(start 186.722004 -106.059478)
		(end 186.722004 -106.652822)
		(width 0.10668)
		(layer "F.Cu")
		(net "PVDD11_S3_P1_PMALERT")
	)
	(segment
		(start 221.482412 -137.095992)
		(end 221.944692 -136.633712)
		(width 0.10668)
		(layer "F.Cu")
		(net "PVDD11_S3_P1_PMALERT")
	)
	(segment
		(start 220.54566 -109.087158)
		(end 220.996256 -108.636562)
		(width 0.10668)
		(layer "F.Cu")
		(net "PVDD11_S3_P1_PMALERT")
	)
	(segment
		(start 221.944692 -125.645418)
		(end 218.990164 -122.69089)
		(width 0.10668)
		(layer "F.Cu")
		(net "PVDD11_S3_P1_PMALERT")
	)
	(segment
		(start 158.077408 -353.245928)
		(end 158.286704 -353.036632)
		(width 0.10668)
		(layer "F.Cu")
		(net "PVDD11_S3_P1_PMALERT")
	)
	(segment
		(start 185.7502 -101.25583)
		(end 185.726832 -101.279198)
		(width 0.10668)
		(layer "F.Cu")
		(net "PVDD11_S3_P1_PMALERT")
	)
	(segment
		(start 185.674 -105.011474)
		(end 186.722004 -106.059478)
		(width 0.10668)
		(layer "F.Cu")
		(net "PVDD11_S3_P1_PMALERT")
	)
	(via
		(at 220.996256 -108.636562)
		(size 0.508)
		(drill 0.254)
		(layers "F.Cu" "B.Cu")
		(net "PVDD11_S3_P1_PMALERT")
	)
	(via
		(at 158.077408 -353.89439)
		(size 0.508)
		(drill 0.254)
		(layers "F.Cu" "B.Cu")
		(net "PVDD11_S3_P1_PMALERT")
	)
	(via
		(at 222.354648 -202.5269)
		(size 0.508)
		(drill 0.254)
		(layers "F.Cu" "B.Cu")
		(net "PVDD11_S3_P1_PMALERT")
	)
	(via
		(at 181.421786 -367.660682)
		(size 0.508)
		(drill 0.254)
		(layers "F.Cu" "B.Cu")
		(net "PVDD11_S3_P1_PMALERT")
	)
	(via
		(at 185.726832 -101.279198)
		(size 0.4572)
		(drill 0.254)
		(layers "F.Cu" "B.Cu")
		(net "PVDD11_S3_P1_PMALERT")
	)
	(segment
		(start 159.07893 -355.376734)
		(end 159.07893 -354.895912)
		(width 0.10668)
		(layer "B.Cu")
		(net "PVDD11_S3_P1_PMALERT")
	)
	(segment
		(start 181.421786 -367.660682)
		(end 170.239944 -356.47884)
		(width 0.10668)
		(layer "B.Cu")
		(net "PVDD11_S3_P1_PMALERT")
	)
	(segment
		(start 159.07893 -354.895912)
		(end 158.077408 -353.89439)
		(width 0.10668)
		(layer "B.Cu")
		(net "PVDD11_S3_P1_PMALERT")
	)
	(segment
		(start 170.239944 -356.47884)
		(end 160.181036 -356.47884)
		(width 0.10668)
		(layer "B.Cu")
		(net "PVDD11_S3_P1_PMALERT")
	)
	(segment
		(start 160.181036 -356.47884)
		(end 159.07893 -355.376734)
		(width 0.10668)
		(layer "B.Cu")
		(net "PVDD11_S3_P1_PMALERT")
	)
	(segment
		(start 217.441526 -105.081832)
		(end 220.996256 -108.636562)
		(width 0.11684)
		(layer "In2.Cu")
		(net "PVDD11_S3_P1_PMALERT")
	)
	(segment
		(start 197.67296 -100.287328)
		(end 198.55053 -99.409758)
		(width 0.11684)
		(layer "In2.Cu")
		(net "PVDD11_S3_P1_PMALERT")
	)
	(segment
		(start 217.441526 -104.686608)
		(end 217.441526 -105.081832)
		(width 0.11684)
		(layer "In2.Cu")
		(net "PVDD11_S3_P1_PMALERT")
	)
	(segment
		(start 206.561182 -99.300538)
		(end 208.31048 -99.300538)
		(width 0.11684)
		(layer "In2.Cu")
		(net "PVDD11_S3_P1_PMALERT")
	)
	(segment
		(start 216.303098 -103.54818)
		(end 217.441526 -104.686608)
		(width 0.11684)
		(layer "In2.Cu")
		(net "PVDD11_S3_P1_PMALERT")
	)
	(segment
		(start 206.506064 -99.355656)
		(end 206.561182 -99.300538)
		(width 0.11684)
		(layer "In2.Cu")
		(net "PVDD11_S3_P1_PMALERT")
	)
	(segment
		(start 210.527138 -101.517196)
		(end 213.01202 -101.517196)
		(width 0.11684)
		(layer "In2.Cu")
		(net "PVDD11_S3_P1_PMALERT")
	)
	(segment
		(start 203.26223 -99.848924)
		(end 204.388466 -99.848924)
		(width 0.11684)
		(layer "In2.Cu")
		(net "PVDD11_S3_P1_PMALERT")
	)
	(segment
		(start 202.823064 -99.409758)
		(end 203.26223 -99.848924)
		(width 0.11684)
		(layer "In2.Cu")
		(net "PVDD11_S3_P1_PMALERT")
	)
	(segment
		(start 186.718702 -100.287328)
		(end 197.67296 -100.287328)
		(width 0.11684)
		(layer "In2.Cu")
		(net "PVDD11_S3_P1_PMALERT")
	)
	(segment
		(start 208.31048 -99.300538)
		(end 210.527138 -101.517196)
		(width 0.11684)
		(layer "In2.Cu")
		(net "PVDD11_S3_P1_PMALERT")
	)
	(segment
		(start 198.55053 -99.409758)
		(end 202.823064 -99.409758)
		(width 0.11684)
		(layer "In2.Cu")
		(net "PVDD11_S3_P1_PMALERT")
	)
	(segment
		(start 213.01202 -101.517196)
		(end 215.043004 -103.54818)
		(width 0.11684)
		(layer "In2.Cu")
		(net "PVDD11_S3_P1_PMALERT")
	)
	(segment
		(start 215.043004 -103.54818)
		(end 216.303098 -103.54818)
		(width 0.11684)
		(layer "In2.Cu")
		(net "PVDD11_S3_P1_PMALERT")
	)
	(segment
		(start 204.388466 -99.848924)
		(end 204.881734 -99.355656)
		(width 0.11684)
		(layer "In2.Cu")
		(net "PVDD11_S3_P1_PMALERT")
	)
	(segment
		(start 185.726832 -101.279198)
		(end 186.718702 -100.287328)
		(width 0.11684)
		(layer "In2.Cu")
		(net "PVDD11_S3_P1_PMALERT")
	)
	(segment
		(start 204.881734 -99.355656)
		(end 206.506064 -99.355656)
		(width 0.11684)
		(layer "In2.Cu")
		(net "PVDD11_S3_P1_PMALERT")
	)
	(segment
		(start 181.421786 -367.660682)
		(end 193.868802 -367.660682)
		(width 0.11684)
		(layer "In4.Cu")
		(net "PVDD11_S3_P1_PMALERT")
	)
	(segment
		(start 213.654386 -212.310218)
		(end 222.354648 -203.609956)
		(width 0.11684)
		(layer "In4.Cu")
		(net "PVDD11_S3_P1_PMALERT")
	)
	(segment
		(start 205.437232 -362.631736)
		(end 205.437232 -359.642918)
		(width 0.11684)
		(layer "In4.Cu")
		(net "PVDD11_S3_P1_PMALERT")
	)
	(segment
		(start 222.507556 -332.135988)
		(end 213.050882 -322.679314)
		(width 0.11684)
		(layer "In4.Cu")
		(net "PVDD11_S3_P1_PMALERT")
	)
	(segment
		(start 213.654386 -320.106548)
		(end 213.654386 -212.310218)
		(width 0.11684)
		(layer "In4.Cu")
		(net "PVDD11_S3_P1_PMALERT")
	)
	(segment
		(start 223.369632 -334.434434)
		(end 222.507556 -333.572358)
		(width 0.11684)
		(layer "In4.Cu")
		(net "PVDD11_S3_P1_PMALERT")
	)
	(segment
		(start 222.354648 -203.609956)
		(end 222.354648 -202.5269)
		(width 0.11684)
		(layer "In4.Cu")
		(net "PVDD11_S3_P1_PMALERT")
	)
	(segment
		(start 213.050882 -320.710052)
		(end 213.654386 -320.106548)
		(width 0.11684)
		(layer "In4.Cu")
		(net "PVDD11_S3_P1_PMALERT")
	)
	(segment
		(start 194.556634 -366.97285)
		(end 201.096118 -366.97285)
		(width 0.11684)
		(layer "In4.Cu")
		(net "PVDD11_S3_P1_PMALERT")
	)
	(segment
		(start 193.868802 -367.660682)
		(end 194.556634 -366.97285)
		(width 0.11684)
		(layer "In4.Cu")
		(net "PVDD11_S3_P1_PMALERT")
	)
	(segment
		(start 201.096118 -366.97285)
		(end 205.437232 -362.631736)
		(width 0.11684)
		(layer "In4.Cu")
		(net "PVDD11_S3_P1_PMALERT")
	)
	(segment
		(start 205.437232 -359.642918)
		(end 223.369632 -341.710518)
		(width 0.11684)
		(layer "In4.Cu")
		(net "PVDD11_S3_P1_PMALERT")
	)
	(segment
		(start 223.369632 -341.710518)
		(end 223.369632 -334.434434)
		(width 0.11684)
		(layer "In4.Cu")
		(net "PVDD11_S3_P1_PMALERT")
	)
	(segment
		(start 222.507556 -333.572358)
		(end 222.507556 -332.135988)
		(width 0.11684)
		(layer "In4.Cu")
		(net "PVDD11_S3_P1_PMALERT")
	)
	(segment
		(start 213.050882 -322.679314)
		(end 213.050882 -320.710052)
		(width 0.11684)
		(layer "In4.Cu")
		(net "PVDD11_S3_P1_PMALERT")
	)
	(segment
		(start 165.22573 -347.212666)
		(end 165.22573 -346.587064)
		(width 0.10668)
		(layer "F.Cu")
		(net "PVDD11_S3_P1_OCP_N_R")
	)
	(segment
		(start 164.628576 -347.55328)
		(end 164.885116 -347.55328)
		(width 0.10668)
		(layer "F.Cu")
		(net "PVDD11_S3_P1_OCP_N_R")
	)
	(segment
		(start 164.885116 -347.55328)
		(end 165.22573 -347.212666)
		(width 0.10668)
		(layer "F.Cu")
		(net "PVDD11_S3_P1_OCP_N_R")
	)
	(segment
		(start 165.601142 -346.211652)
		(end 166.443914 -346.211652)
		(width 0.10668)
		(layer "F.Cu")
		(net "PVDD11_S3_P1_OCP_N_R")
	)
	(segment
		(start 165.22573 -346.587064)
		(end 165.601142 -346.211652)
		(width 0.10668)
		(layer "F.Cu")
		(net "PVDD11_S3_P1_OCP_N_R")
	)
	(segment
		(start 166.443914 -346.211652)
		(end 166.534338 -346.302076)
		(width 0.10668)
		(layer "F.Cu")
		(net "PVDD11_S3_P1_OCP_N_R")
	)
	(via
		(at 165.601142 -346.211652)
		(size 0.508)
		(drill 0.254)
		(layers "F.Cu" "B.Cu")
		(net "PVDD11_S3_P1_OCP_N_R")
	)
	(via
		(at 167.110664 -345.989402)
		(size 0.6604)
		(drill 0.3302)
		(layers "F.Cu" "B.Cu")
		(net "PVDD11_S3_P1_OCP_N_R")
	)
	(segment
		(start 167.285162 -346.1639)
		(end 167.285162 -347.199966)
		(width 0.10668)
		(layer "B.Cu")
		(net "PVDD11_S3_P1_OCP_N_R")
	)
	(segment
		(start 165.823392 -345.989402)
		(end 167.110664 -345.989402)
		(width 0.10668)
		(layer "B.Cu")
		(net "PVDD11_S3_P1_OCP_N_R")
	)
	(segment
		(start 167.110664 -345.989402)
		(end 167.285162 -346.1639)
		(width 0.10668)
		(layer "B.Cu")
		(net "PVDD11_S3_P1_OCP_N_R")
	)
	(segment
		(start 165.601142 -346.211652)
		(end 165.823392 -345.989402)
		(width 0.10668)
		(layer "B.Cu")
		(net "PVDD11_S3_P1_OCP_N_R")
	)
	(segment
		(start 208.757012 -203.202794)
		(end 208.989676 -203.202794)
		(width 0.1524)
		(layer "F.Cu")
		(net "PVDD11_S3_P1_OCP_N")
	)
	(segment
		(start 203.141326 -182.86603)
		(end 206.105252 -185.829956)
		(width 0.1524)
		(layer "F.Cu")
		(net "PVDD11_S3_P1_OCP_N")
	)
	(segment
		(start 167.334438 -346.302076)
		(end 168.076626 -346.302076)
		(width 0.1524)
		(layer "F.Cu")
		(net "PVDD11_S3_P1_OCP_N")
	)
	(segment
		(start 207.969358 -190.330582)
		(end 207.969358 -202.41514)
		(width 0.1524)
		(layer "F.Cu")
		(net "PVDD11_S3_P1_OCP_N")
	)
	(segment
		(start 196.047868 -182.86603)
		(end 203.141326 -182.86603)
		(width 0.1524)
		(layer "F.Cu")
		(net "PVDD11_S3_P1_OCP_N")
	)
	(segment
		(start 206.105252 -185.829956)
		(end 207.969358 -190.330582)
		(width 0.1524)
		(layer "F.Cu")
		(net "PVDD11_S3_P1_OCP_N")
	)
	(segment
		(start 185.632598 -172.45076)
		(end 196.047868 -182.86603)
		(width 0.1524)
		(layer "F.Cu")
		(net "PVDD11_S3_P1_OCP_N")
	)
	(segment
		(start 207.969358 -202.41514)
		(end 208.757012 -203.202794)
		(width 0.1524)
		(layer "F.Cu")
		(net "PVDD11_S3_P1_OCP_N")
	)
	(via
		(at 208.989676 -203.202794)
		(size 0.508)
		(drill 0.254)
		(layers "F.Cu" "B.Cu")
		(net "PVDD11_S3_P1_OCP_N")
	)
	(via
		(at 168.076626 -346.302076)
		(size 0.508)
		(drill 0.254)
		(layers "F.Cu" "B.Cu")
		(net "PVDD11_S3_P1_OCP_N")
	)
	(via
		(at 185.632598 -172.45076)
		(size 0.508)
		(drill 0.254)
		(layers "F.Cu" "B.Cu")
		(net "PVDD11_S3_P1_OCP_N")
	)
	(via
		(at 180.721 -98.262948)
		(size 0.508)
		(drill 0.254)
		(layers "F.Cu" "B.Cu")
		(net "PVDD11_S3_P1_OCP_N")
	)
	(via
		(at 162.579304 -126.482856)
		(size 0.508)
		(drill 0.254)
		(layers "F.Cu" "B.Cu")
		(net "PVDD11_S3_P1_OCP_N")
	)
	(segment
		(start 170.675046 -153.596086)
		(end 175.227996 -158.149036)
		(width 0.1524)
		(layer "B.Cu")
		(net "PVDD11_S3_P1_OCP_N")
	)
	(segment
		(start 170.675046 -139.060682)
		(end 170.675046 -153.596086)
		(width 0.1524)
		(layer "B.Cu")
		(net "PVDD11_S3_P1_OCP_N")
	)
	(segment
		(start 180.22697 -99.521772)
		(end 180.22697 -98.756978)
		(width 0.10668)
		(layer "B.Cu")
		(net "PVDD11_S3_P1_OCP_N")
	)
	(segment
		(start 163.707064 -129.633472)
		(end 163.707064 -132.0927)
		(width 0.1524)
		(layer "B.Cu")
		(net "PVDD11_S3_P1_OCP_N")
	)
	(segment
		(start 185.632598 -170.459908)
		(end 185.632598 -172.45076)
		(width 0.1524)
		(layer "B.Cu")
		(net "PVDD11_S3_P1_OCP_N")
	)
	(segment
		(start 178.21402 -170.332908)
		(end 185.505598 -170.332908)
		(width 0.1524)
		(layer "B.Cu")
		(net "PVDD11_S3_P1_OCP_N")
	)
	(segment
		(start 180.600096 -99.894898)
		(end 180.22697 -99.521772)
		(width 0.10668)
		(layer "B.Cu")
		(net "PVDD11_S3_P1_OCP_N")
	)
	(segment
		(start 180.22697 -98.756978)
		(end 180.721 -98.262948)
		(width 0.10668)
		(layer "B.Cu")
		(net "PVDD11_S3_P1_OCP_N")
	)
	(segment
		(start 163.707064 -132.0927)
		(end 170.675046 -139.060682)
		(width 0.1524)
		(layer "B.Cu")
		(net "PVDD11_S3_P1_OCP_N")
	)
	(segment
		(start 162.579304 -126.482856)
		(end 162.579304 -128.505712)
		(width 0.1524)
		(layer "B.Cu")
		(net "PVDD11_S3_P1_OCP_N")
	)
	(segment
		(start 162.579304 -128.505712)
		(end 163.707064 -129.633472)
		(width 0.1524)
		(layer "B.Cu")
		(net "PVDD11_S3_P1_OCP_N")
	)
	(segment
		(start 175.227996 -158.149036)
		(end 175.227996 -167.346884)
		(width 0.1524)
		(layer "B.Cu")
		(net "PVDD11_S3_P1_OCP_N")
	)
	(segment
		(start 180.721 -99.894898)
		(end 180.600096 -99.894898)
		(width 0.10668)
		(layer "B.Cu")
		(net "PVDD11_S3_P1_OCP_N")
	)
	(segment
		(start 185.505598 -170.332908)
		(end 185.632598 -170.459908)
		(width 0.1524)
		(layer "B.Cu")
		(net "PVDD11_S3_P1_OCP_N")
	)
	(segment
		(start 175.227996 -167.346884)
		(end 178.21402 -170.332908)
		(width 0.1524)
		(layer "B.Cu")
		(net "PVDD11_S3_P1_OCP_N")
	)
	(segment
		(start 209.776568 -324.979792)
		(end 209.776568 -349.38843)
		(width 0.1524)
		(layer "In6.Cu")
		(net "PVDD11_S3_P1_OCP_N")
	)
	(segment
		(start 159.61233 -353.850956)
		(end 159.61233 -347.449394)
		(width 0.1524)
		(layer "In6.Cu")
		(net "PVDD11_S3_P1_OCP_N")
	)
	(segment
		(start 208.266284 -323.469508)
		(end 209.776568 -324.979792)
		(width 0.1524)
		(layer "In6.Cu")
		(net "PVDD11_S3_P1_OCP_N")
	)
	(segment
		(start 162.851084 -345.754452)
		(end 167.529002 -345.754452)
		(width 0.1524)
		(layer "In6.Cu")
		(net "PVDD11_S3_P1_OCP_N")
	)
	(segment
		(start 183.379618 -366.878362)
		(end 182.691532 -366.190276)
		(width 0.1524)
		(layer "In6.Cu")
		(net "PVDD11_S3_P1_OCP_N")
	)
	(segment
		(start 209.776568 -349.38843)
		(end 219.415614 -359.027476)
		(width 0.1524)
		(layer "In6.Cu")
		(net "PVDD11_S3_P1_OCP_N")
	)
	(segment
		(start 215.330786 -366.878362)
		(end 183.379618 -366.878362)
		(width 0.1524)
		(layer "In6.Cu")
		(net "PVDD11_S3_P1_OCP_N")
	)
	(segment
		(start 165.215316 -359.453942)
		(end 159.61233 -353.850956)
		(width 0.1524)
		(layer "In6.Cu")
		(net "PVDD11_S3_P1_OCP_N")
	)
	(segment
		(start 210.636104 -316.747906)
		(end 210.636104 -318.186308)
		(width 0.1524)
		(layer "In6.Cu")
		(net "PVDD11_S3_P1_OCP_N")
	)
	(segment
		(start 180.455316 -366.190276)
		(end 173.718982 -359.453942)
		(width 0.1524)
		(layer "In6.Cu")
		(net "PVDD11_S3_P1_OCP_N")
	)
	(segment
		(start 208.989676 -203.202794)
		(end 211.710524 -205.923642)
		(width 0.1524)
		(layer "In6.Cu")
		(net "PVDD11_S3_P1_OCP_N")
	)
	(segment
		(start 211.710524 -205.923642)
		(end 211.710524 -315.673486)
		(width 0.1524)
		(layer "In6.Cu")
		(net "PVDD11_S3_P1_OCP_N")
	)
	(segment
		(start 159.61233 -347.449394)
		(end 161.065464 -345.99626)
		(width 0.1524)
		(layer "In6.Cu")
		(net "PVDD11_S3_P1_OCP_N")
	)
	(segment
		(start 208.266284 -320.556128)
		(end 208.266284 -323.469508)
		(width 0.1524)
		(layer "In6.Cu")
		(net "PVDD11_S3_P1_OCP_N")
	)
	(segment
		(start 211.710524 -315.673486)
		(end 210.636104 -316.747906)
		(width 0.1524)
		(layer "In6.Cu")
		(net "PVDD11_S3_P1_OCP_N")
	)
	(segment
		(start 167.529002 -345.754452)
		(end 168.076626 -346.302076)
		(width 0.1524)
		(layer "In6.Cu")
		(net "PVDD11_S3_P1_OCP_N")
	)
	(segment
		(start 219.415614 -359.027476)
		(end 219.415614 -362.793534)
		(width 0.1524)
		(layer "In6.Cu")
		(net "PVDD11_S3_P1_OCP_N")
	)
	(segment
		(start 182.691532 -366.190276)
		(end 180.455316 -366.190276)
		(width 0.1524)
		(layer "In6.Cu")
		(net "PVDD11_S3_P1_OCP_N")
	)
	(segment
		(start 162.609276 -345.99626)
		(end 162.851084 -345.754452)
		(width 0.1524)
		(layer "In6.Cu")
		(net "PVDD11_S3_P1_OCP_N")
	)
	(segment
		(start 173.718982 -359.453942)
		(end 165.215316 -359.453942)
		(width 0.1524)
		(layer "In6.Cu")
		(net "PVDD11_S3_P1_OCP_N")
	)
	(segment
		(start 210.636104 -318.186308)
		(end 208.266284 -320.556128)
		(width 0.1524)
		(layer "In6.Cu")
		(net "PVDD11_S3_P1_OCP_N")
	)
	(segment
		(start 161.065464 -345.99626)
		(end 162.609276 -345.99626)
		(width 0.1524)
		(layer "In6.Cu")
		(net "PVDD11_S3_P1_OCP_N")
	)
	(segment
		(start 219.415614 -362.793534)
		(end 215.330786 -366.878362)
		(width 0.1524)
		(layer "In6.Cu")
		(net "PVDD11_S3_P1_OCP_N")
	)
	(segment
		(start 179.702968 -94.403164)
		(end 180.203094 -94.90329)
		(width 0.1524)
		(layer "In15.Cu")
		(net "PVDD11_S3_P1_OCP_N")
	)
	(segment
		(start 166.10711 -104.378252)
		(end 168.72077 -101.764592)
		(width 0.1524)
		(layer "In15.Cu")
		(net "PVDD11_S3_P1_OCP_N")
	)
	(segment
		(start 164.651182 -105.330752)
		(end 165.603682 -104.378252)
		(width 0.1524)
		(layer "In15.Cu")
		(net "PVDD11_S3_P1_OCP_N")
	)
	(segment
		(start 170.588432 -94.403164)
		(end 179.702968 -94.403164)
		(width 0.1524)
		(layer "In15.Cu")
		(net "PVDD11_S3_P1_OCP_N")
	)
	(segment
		(start 165.603682 -104.378252)
		(end 166.10711 -104.378252)
		(width 0.1524)
		(layer "In15.Cu")
		(net "PVDD11_S3_P1_OCP_N")
	)
	(segment
		(start 168.72077 -96.270826)
		(end 170.588432 -94.403164)
		(width 0.1524)
		(layer "In15.Cu")
		(net "PVDD11_S3_P1_OCP_N")
	)
	(segment
		(start 164.651182 -108.532168)
		(end 164.651182 -105.330752)
		(width 0.1524)
		(layer "In15.Cu")
		(net "PVDD11_S3_P1_OCP_N")
	)
	(segment
		(start 163.797234 -109.386116)
		(end 164.651182 -108.532168)
		(width 0.1524)
		(layer "In15.Cu")
		(net "PVDD11_S3_P1_OCP_N")
	)
	(segment
		(start 162.579304 -122.35434)
		(end 163.797234 -121.13641)
		(width 0.1524)
		(layer "In15.Cu")
		(net "PVDD11_S3_P1_OCP_N")
	)
	(segment
		(start 168.72077 -101.764592)
		(end 168.72077 -96.270826)
		(width 0.1524)
		(layer "In15.Cu")
		(net "PVDD11_S3_P1_OCP_N")
	)
	(segment
		(start 180.203094 -94.90329)
		(end 180.203094 -97.745042)
		(width 0.1524)
		(layer "In15.Cu")
		(net "PVDD11_S3_P1_OCP_N")
	)
	(segment
		(start 162.579304 -126.482856)
		(end 162.579304 -122.35434)
		(width 0.1524)
		(layer "In15.Cu")
		(net "PVDD11_S3_P1_OCP_N")
	)
	(segment
		(start 180.203094 -97.745042)
		(end 180.721 -98.262948)
		(width 0.1524)
		(layer "In15.Cu")
		(net "PVDD11_S3_P1_OCP_N")
	)
	(segment
		(start 163.797234 -121.13641)
		(end 163.797234 -109.386116)
		(width 0.1524)
		(layer "In15.Cu")
		(net "PVDD11_S3_P1_OCP_N")
	)
	(segment
		(start 189.783974 -355.497892)
		(end 189.783974 -356.290372)
		(width 0.127)
		(layer "F.Cu")
		(net "PVDD11_S3_P1_LSET2")
	)
	(segment
		(start 189.783974 -354.99929)
		(end 189.783974 -355.497892)
		(width 0.127)
		(layer "F.Cu")
		(net "PVDD11_S3_P1_LSET2")
	)
	(segment
		(start 189.783974 -356.290372)
		(end 189.541912 -356.532434)
		(width 0.127)
		(layer "F.Cu")
		(net "PVDD11_S3_P1_LSET2")
	)
	(segment
		(start 190.156592 -354.22078)
		(end 190.156592 -354.626672)
		(width 0.127)
		(layer "F.Cu")
		(net "PVDD11_S3_P1_LSET2")
	)
	(segment
		(start 190.156592 -354.626672)
		(end 189.783974 -354.99929)
		(width 0.127)
		(layer "F.Cu")
		(net "PVDD11_S3_P1_LSET2")
	)
	(via
		(at 189.783974 -355.497892)
		(size 0.4064)
		(drill 0.2032)
		(layers "F.Cu" "B.Cu")
		(net "PVDD11_S3_P1_LSET2")
	)
	(segment
		(start 181.457346 -356.264972)
		(end 181.457346 -355.472492)
		(width 0.127)
		(layer "F.Cu")
		(net "PVDD11_S3_P1_LSET1")
	)
	(segment
		(start 181.829964 -354.601272)
		(end 181.829964 -354.19538)
		(width 0.127)
		(layer "F.Cu")
		(net "PVDD11_S3_P1_LSET1")
	)
	(segment
		(start 181.457346 -354.97389)
		(end 181.829964 -354.601272)
		(width 0.127)
		(layer "F.Cu")
		(net "PVDD11_S3_P1_LSET1")
	)
	(segment
		(start 181.215284 -356.507034)
		(end 181.457346 -356.264972)
		(width 0.127)
		(layer "F.Cu")
		(net "PVDD11_S3_P1_LSET1")
	)
	(segment
		(start 181.457346 -355.472492)
		(end 181.457346 -354.97389)
		(width 0.127)
		(layer "F.Cu")
		(net "PVDD11_S3_P1_LSET1")
	)
	(via
		(at 181.457346 -355.472492)
		(size 0.4064)
		(drill 0.2032)
		(layers "F.Cu" "B.Cu")
		(net "PVDD11_S3_P1_LSET1")
	)
	(segment
		(start 189.281054 -355.02215)
		(end 189.706504 -354.5967)
		(width 0.2286)
		(layer "F.Cu")
		(net "PVDD11_S3_P1_IMON2")
	)
	(segment
		(start 161.628582 -345.41333)
		(end 161.435796 -345.220544)
		(width 0.1778)
		(layer "F.Cu")
		(net "PVDD11_S3_P1_IMON2")
	)
	(segment
		(start 161.435796 -345.220544)
		(end 161.435796 -344.052398)
		(width 0.1778)
		(layer "F.Cu")
		(net "PVDD11_S3_P1_IMON2")
	)
	(segment
		(start 161.435796 -344.052398)
		(end 161.233104 -343.849706)
		(width 0.1778)
		(layer "F.Cu")
		(net "PVDD11_S3_P1_IMON2")
	)
	(segment
		(start 161.628582 -346.153232)
		(end 161.628582 -345.41333)
		(width 0.1778)
		(layer "F.Cu")
		(net "PVDD11_S3_P1_IMON2")
	)
	(segment
		(start 189.706504 -354.5967)
		(end 189.706504 -354.22078)
		(width 0.2286)
		(layer "F.Cu")
		(net "PVDD11_S3_P1_IMON2")
	)
	(segment
		(start 189.281054 -355.141276)
		(end 189.281054 -355.02215)
		(width 0.2286)
		(layer "F.Cu")
		(net "PVDD11_S3_P1_IMON2")
	)
	(via
		(at 189.281054 -355.141276)
		(size 0.508)
		(drill 0.254)
		(layers "F.Cu" "B.Cu")
		(net "PVDD11_S3_P1_IMON2")
	)
	(via
		(at 161.233104 -343.849706)
		(size 0.508)
		(drill 0.254)
		(layers "F.Cu" "B.Cu")
		(net "PVDD11_S3_P1_IMON2")
	)
	(segment
		(start 188.957458 -355.141276)
		(end 188.671962 -355.426772)
		(width 0.254)
		(layer "In4.Cu")
		(net "PVDD11_S3_P1_IMON2")
	)
	(segment
		(start 189.281054 -355.141276)
		(end 188.957458 -355.141276)
		(width 0.254)
		(layer "In4.Cu")
		(net "PVDD11_S3_P1_IMON2")
	)
	(segment
		(start 160.129474 -341.789512)
		(end 161.233104 -342.893142)
		(width 0.254)
		(layer "In4.Cu")
		(net "PVDD11_S3_P1_IMON2")
	)
	(segment
		(start 161.233104 -342.893142)
		(end 161.233104 -343.849706)
		(width 0.254)
		(layer "In4.Cu")
		(net "PVDD11_S3_P1_IMON2")
	)
	(segment
		(start 154.963622 -341.789512)
		(end 160.129474 -341.789512)
		(width 0.254)
		(layer "In4.Cu")
		(net "PVDD11_S3_P1_IMON2")
	)
	(segment
		(start 151.37257 -345.380564)
		(end 154.963622 -341.789512)
		(width 0.254)
		(layer "In4.Cu")
		(net "PVDD11_S3_P1_IMON2")
	)
	(segment
		(start 151.37257 -351.737168)
		(end 151.37257 -345.380564)
		(width 0.254)
		(layer "In4.Cu")
		(net "PVDD11_S3_P1_IMON2")
	)
	(segment
		(start 188.671962 -355.426772)
		(end 188.671962 -357.291386)
		(width 0.254)
		(layer "In4.Cu")
		(net "PVDD11_S3_P1_IMON2")
	)
	(segment
		(start 182.795164 -357.835454)
		(end 157.470856 -357.835454)
		(width 0.254)
		(layer "In4.Cu")
		(net "PVDD11_S3_P1_IMON2")
	)
	(segment
		(start 188.671962 -357.291386)
		(end 187.649612 -358.313736)
		(width 0.254)
		(layer "In4.Cu")
		(net "PVDD11_S3_P1_IMON2")
	)
	(segment
		(start 183.273446 -358.313736)
		(end 182.795164 -357.835454)
		(width 0.254)
		(layer "In4.Cu")
		(net "PVDD11_S3_P1_IMON2")
	)
	(segment
		(start 187.649612 -358.313736)
		(end 183.273446 -358.313736)
		(width 0.254)
		(layer "In4.Cu")
		(net "PVDD11_S3_P1_IMON2")
	)
	(segment
		(start 157.470856 -357.835454)
		(end 151.37257 -351.737168)
		(width 0.254)
		(layer "In4.Cu")
		(net "PVDD11_S3_P1_IMON2")
	)
	(segment
		(start 161.228532 -346.153232)
		(end 161.228532 -345.755976)
		(width 0.1778)
		(layer "F.Cu")
		(net "PVDD11_S3_P1_IMON1")
	)
	(segment
		(start 160.885124 -345.412568)
		(end 160.885124 -345.078304)
		(width 0.1778)
		(layer "F.Cu")
		(net "PVDD11_S3_P1_IMON1")
	)
	(segment
		(start 181.379876 -354.5713)
		(end 181.379876 -354.19538)
		(width 0.2286)
		(layer "F.Cu")
		(net "PVDD11_S3_P1_IMON1")
	)
	(segment
		(start 180.954426 -355.115876)
		(end 180.954426 -354.99675)
		(width 0.2286)
		(layer "F.Cu")
		(net "PVDD11_S3_P1_IMON1")
	)
	(segment
		(start 180.954426 -354.99675)
		(end 181.379876 -354.5713)
		(width 0.2286)
		(layer "F.Cu")
		(net "PVDD11_S3_P1_IMON1")
	)
	(segment
		(start 161.228532 -345.755976)
		(end 160.885124 -345.412568)
		(width 0.1778)
		(layer "F.Cu")
		(net "PVDD11_S3_P1_IMON1")
	)
	(via
		(at 180.954426 -355.115876)
		(size 0.508)
		(drill 0.254)
		(layers "F.Cu" "B.Cu")
		(net "PVDD11_S3_P1_IMON1")
	)
	(via
		(at 160.885124 -345.078304)
		(size 0.508)
		(drill 0.254)
		(layers "F.Cu" "B.Cu")
		(net "PVDD11_S3_P1_IMON1")
	)
	(segment
		(start 180.068474 -355.387656)
		(end 179.532534 -355.923596)
		(width 0.254)
		(layer "In4.Cu")
		(net "PVDD11_S3_P1_IMON1")
	)
	(segment
		(start 153.166318 -346.298266)
		(end 154.644852 -344.819732)
		(width 0.254)
		(layer "In4.Cu")
		(net "PVDD11_S3_P1_IMON1")
	)
	(segment
		(start 179.161694 -355.923596)
		(end 178.662584 -356.422706)
		(width 0.254)
		(layer "In4.Cu")
		(net "PVDD11_S3_P1_IMON1")
	)
	(segment
		(start 180.954426 -355.115876)
		(end 180.788818 -355.115876)
		(width 0.254)
		(layer "In4.Cu")
		(net "PVDD11_S3_P1_IMON1")
	)
	(segment
		(start 153.166318 -351.056702)
		(end 153.166318 -346.298266)
		(width 0.254)
		(layer "In4.Cu")
		(net "PVDD11_S3_P1_IMON1")
	)
	(segment
		(start 180.788818 -355.115876)
		(end 180.517038 -355.387656)
		(width 0.254)
		(layer "In4.Cu")
		(net "PVDD11_S3_P1_IMON1")
	)
	(segment
		(start 158.532322 -356.422706)
		(end 153.166318 -351.056702)
		(width 0.254)
		(layer "In4.Cu")
		(net "PVDD11_S3_P1_IMON1")
	)
	(segment
		(start 160.626552 -344.819732)
		(end 160.885124 -345.078304)
		(width 0.254)
		(layer "In4.Cu")
		(net "PVDD11_S3_P1_IMON1")
	)
	(segment
		(start 180.517038 -355.387656)
		(end 180.068474 -355.387656)
		(width 0.254)
		(layer "In4.Cu")
		(net "PVDD11_S3_P1_IMON1")
	)
	(segment
		(start 179.532534 -355.923596)
		(end 179.161694 -355.923596)
		(width 0.254)
		(layer "In4.Cu")
		(net "PVDD11_S3_P1_IMON1")
	)
	(segment
		(start 154.644852 -344.819732)
		(end 160.626552 -344.819732)
		(width 0.254)
		(layer "In4.Cu")
		(net "PVDD11_S3_P1_IMON1")
	)
	(segment
		(start 178.662584 -356.422706)
		(end 158.532322 -356.422706)
		(width 0.254)
		(layer "In4.Cu")
		(net "PVDD11_S3_P1_IMON1")
	)
	(segment
		(start 158.637224 -350.256856)
		(end 158.092902 -350.256856)
		(width 0.10668)
		(layer "F.Cu")
		(net "PVDD11_S3_P1_EN_R")
	)
	(segment
		(start 158.743904 -350.091502)
		(end 158.743904 -350.150176)
		(width 0.10668)
		(layer "F.Cu")
		(net "PVDD11_S3_P1_EN_R")
	)
	(segment
		(start 159.076644 -349.553276)
		(end 158.73603 -349.89389)
		(width 0.10668)
		(layer "F.Cu")
		(net "PVDD11_S3_P1_EN_R")
	)
	(segment
		(start 159.828484 -349.553276)
		(end 159.076644 -349.553276)
		(width 0.10668)
		(layer "F.Cu")
		(net "PVDD11_S3_P1_EN_R")
	)
	(segment
		(start 158.743904 -350.150176)
		(end 158.637224 -350.256856)
		(width 0.10668)
		(layer "F.Cu")
		(net "PVDD11_S3_P1_EN_R")
	)
	(segment
		(start 158.73603 -349.89389)
		(end 158.73603 -350.083628)
		(width 0.10668)
		(layer "F.Cu")
		(net "PVDD11_S3_P1_EN_R")
	)
	(segment
		(start 158.73603 -350.083628)
		(end 158.743904 -350.091502)
		(width 0.10668)
		(layer "F.Cu")
		(net "PVDD11_S3_P1_EN_R")
	)
	(via
		(at 158.743904 -350.091502)
		(size 0.508)
		(drill 0.254)
		(layers "F.Cu" "B.Cu")
		(net "PVDD11_S3_P1_EN_R")
	)
	(segment
		(start 157.625034 -350.091502)
		(end 158.743904 -350.091502)
		(width 0.10668)
		(layer "B.Cu")
		(net "PVDD11_S3_P1_EN_R")
	)
	(segment
		(start 157.426914 -350.289622)
		(end 157.625034 -350.091502)
		(width 0.10668)
		(layer "B.Cu")
		(net "PVDD11_S3_P1_EN_R")
	)
	(segment
		(start 180.966872 -369.457224)
		(end 200.25233 -369.457224)
		(width 0.10668)
		(layer "F.Cu")
		(net "PVDD11_S3_P1_EN")
	)
	(segment
		(start 175.195484 -366.639602)
		(end 175.570134 -367.014252)
		(width 0.10668)
		(layer "F.Cu")
		(net "PVDD11_S3_P1_EN")
	)
	(segment
		(start 223.249998 -148.531326)
		(end 225.146616 -146.634708)
		(width 0.10668)
		(layer "F.Cu")
		(net "PVDD11_S3_P1_EN")
	)
	(segment
		(start 218.221052 -222.17761)
		(end 224.96526 -215.433402)
		(width 0.10668)
		(layer "F.Cu")
		(net "PVDD11_S3_P1_EN")
	)
	(segment
		(start 178.5239 -367.014252)
		(end 180.966872 -369.457224)
		(width 0.10668)
		(layer "F.Cu")
		(net "PVDD11_S3_P1_EN")
	)
	(segment
		(start 200.25233 -369.457224)
		(end 201.4093 -370.614194)
		(width 0.10668)
		(layer "F.Cu")
		(net "PVDD11_S3_P1_EN")
	)
	(segment
		(start 197.669658 -108.545376)
		(end 198.342758 -108.545376)
		(width 0.10668)
		(layer "F.Cu")
		(net "PVDD11_S3_P1_EN")
	)
	(segment
		(start 227.0379 -363.138466)
		(end 227.0379 -335.693766)
		(width 0.10668)
		(layer "F.Cu")
		(net "PVDD11_S3_P1_EN")
	)
	(segment
		(start 202.527154 -86.465156)
		(end 198.948294 -86.465156)
		(width 0.10668)
		(layer "F.Cu")
		(net "PVDD11_S3_P1_EN")
	)
	(segment
		(start 175.570134 -367.014252)
		(end 178.5239 -367.014252)
		(width 0.10668)
		(layer "F.Cu")
		(net "PVDD11_S3_P1_EN")
	)
	(segment
		(start 225.61042 -329.69454)
		(end 218.221052 -322.305172)
		(width 0.10668)
		(layer "F.Cu")
		(net "PVDD11_S3_P1_EN")
	)
	(segment
		(start 175.195484 -364.681516)
		(end 175.195484 -366.639602)
		(width 0.10668)
		(layer "F.Cu")
		(net "PVDD11_S3_P1_EN")
	)
	(segment
		(start 225.740468 -364.435898)
		(end 227.0379 -363.138466)
		(width 0.10668)
		(layer "F.Cu")
		(net "PVDD11_S3_P1_EN")
	)
	(segment
		(start 223.519238 -364.435898)
		(end 225.740468 -364.435898)
		(width 0.10668)
		(layer "F.Cu")
		(net "PVDD11_S3_P1_EN")
	)
	(segment
		(start 223.249998 -159.72536)
		(end 223.249998 -148.531326)
		(width 0.10668)
		(layer "F.Cu")
		(net "PVDD11_S3_P1_EN")
	)
	(segment
		(start 209.080608 -87.709756)
		(end 203.771754 -87.709756)
		(width 0.10668)
		(layer "F.Cu")
		(net "PVDD11_S3_P1_EN")
	)
	(segment
		(start 224.570036 -96.187514)
		(end 220.198188 -91.815666)
		(width 0.10668)
		(layer "F.Cu")
		(net "PVDD11_S3_P1_EN")
	)
	(segment
		(start 173.581314 -363.067346)
		(end 175.195484 -364.681516)
		(width 0.10668)
		(layer "F.Cu")
		(net "PVDD11_S3_P1_EN")
	)
	(segment
		(start 225.61042 -334.266286)
		(end 225.61042 -329.69454)
		(width 0.10668)
		(layer "F.Cu")
		(net "PVDD11_S3_P1_EN")
	)
	(segment
		(start 225.146616 -138.91895)
		(end 225.757232 -138.308334)
		(width 0.10668)
		(layer "F.Cu")
		(net "PVDD11_S3_P1_EN")
	)
	(segment
		(start 222.010478 -366.65535)
		(end 222.010478 -365.944658)
		(width 0.10668)
		(layer "F.Cu")
		(net "PVDD11_S3_P1_EN")
	)
	(segment
		(start 220.198188 -91.815666)
		(end 213.186518 -91.815666)
		(width 0.10668)
		(layer "F.Cu")
		(net "PVDD11_S3_P1_EN")
	)
	(segment
		(start 224.96526 -215.433402)
		(end 224.96526 -205.496668)
		(width 0.10668)
		(layer "F.Cu")
		(net "PVDD11_S3_P1_EN")
	)
	(segment
		(start 225.757232 -124.10948)
		(end 222.696532 -121.04878)
		(width 0.10668)
		(layer "F.Cu")
		(net "PVDD11_S3_P1_EN")
	)
	(segment
		(start 228.23043 -202.231498)
		(end 228.23043 -164.705792)
		(width 0.10668)
		(layer "F.Cu")
		(net "PVDD11_S3_P1_EN")
	)
	(segment
		(start 203.771754 -87.709756)
		(end 202.527154 -86.465156)
		(width 0.10668)
		(layer "F.Cu")
		(net "PVDD11_S3_P1_EN")
	)
	(segment
		(start 218.221052 -322.305172)
		(end 218.221052 -222.17761)
		(width 0.10668)
		(layer "F.Cu")
		(net "PVDD11_S3_P1_EN")
	)
	(segment
		(start 213.186518 -91.815666)
		(end 209.080608 -87.709756)
		(width 0.10668)
		(layer "F.Cu")
		(net "PVDD11_S3_P1_EN")
	)
	(segment
		(start 222.696532 -118.296182)
		(end 224.570036 -116.422678)
		(width 0.10668)
		(layer "F.Cu")
		(net "PVDD11_S3_P1_EN")
	)
	(segment
		(start 222.010478 -365.944658)
		(end 223.519238 -364.435898)
		(width 0.10668)
		(layer "F.Cu")
		(net "PVDD11_S3_P1_EN")
	)
	(segment
		(start 225.757232 -138.308334)
		(end 225.757232 -124.10948)
		(width 0.10668)
		(layer "F.Cu")
		(net "PVDD11_S3_P1_EN")
	)
	(segment
		(start 224.570036 -116.422678)
		(end 224.570036 -96.187514)
		(width 0.10668)
		(layer "F.Cu")
		(net "PVDD11_S3_P1_EN")
	)
	(segment
		(start 227.0379 -335.693766)
		(end 225.61042 -334.266286)
		(width 0.10668)
		(layer "F.Cu")
		(net "PVDD11_S3_P1_EN")
	)
	(segment
		(start 173.581314 -360.814874)
		(end 173.581314 -363.067346)
		(width 0.10668)
		(layer "F.Cu")
		(net "PVDD11_S3_P1_EN")
	)
	(segment
		(start 228.23043 -164.705792)
		(end 223.249998 -159.72536)
		(width 0.10668)
		(layer "F.Cu")
		(net "PVDD11_S3_P1_EN")
	)
	(segment
		(start 225.146616 -146.634708)
		(end 225.146616 -138.91895)
		(width 0.10668)
		(layer "F.Cu")
		(net "PVDD11_S3_P1_EN")
	)
	(segment
		(start 218.051634 -370.614194)
		(end 222.010478 -366.65535)
		(width 0.10668)
		(layer "F.Cu")
		(net "PVDD11_S3_P1_EN")
	)
	(segment
		(start 198.948294 -86.465156)
		(end 198.580248 -86.833202)
		(width 0.10668)
		(layer "F.Cu")
		(net "PVDD11_S3_P1_EN")
	)
	(segment
		(start 201.4093 -370.614194)
		(end 218.051634 -370.614194)
		(width 0.10668)
		(layer "F.Cu")
		(net "PVDD11_S3_P1_EN")
	)
	(segment
		(start 222.696532 -121.04878)
		(end 222.696532 -118.296182)
		(width 0.10668)
		(layer "F.Cu")
		(net "PVDD11_S3_P1_EN")
	)
	(segment
		(start 224.96526 -205.496668)
		(end 228.23043 -202.231498)
		(width 0.10668)
		(layer "F.Cu")
		(net "PVDD11_S3_P1_EN")
	)
	(via
		(at 198.580248 -86.833202)
		(size 0.508)
		(drill 0.254)
		(layers "F.Cu" "B.Cu")
		(net "PVDD11_S3_P1_EN")
	)
	(via
		(at 173.581314 -360.814874)
		(size 0.508)
		(drill 0.254)
		(layers "F.Cu" "B.Cu")
		(net "PVDD11_S3_P1_EN")
	)
	(via
		(at 198.342758 -108.545376)
		(size 0.508)
		(drill 0.254)
		(layers "F.Cu" "B.Cu")
		(net "PVDD11_S3_P1_EN")
	)
	(via
		(at 155.458414 -350.289622)
		(size 0.6604)
		(drill 0.3302)
		(layers "F.Cu" "B.Cu")
		(net "PVDD11_S3_P1_EN")
	)
	(segment
		(start 153.829004 -351.919032)
		(end 153.829004 -353.403662)
		(width 0.10668)
		(layer "B.Cu")
		(net "PVDD11_S3_P1_EN")
	)
	(segment
		(start 168.703244 -357.261668)
		(end 172.25645 -360.814874)
		(width 0.10668)
		(layer "B.Cu")
		(net "PVDD11_S3_P1_EN")
	)
	(segment
		(start 153.829004 -353.403662)
		(end 157.68701 -357.261668)
		(width 0.10668)
		(layer "B.Cu")
		(net "PVDD11_S3_P1_EN")
	)
	(segment
		(start 156.626814 -350.289622)
		(end 155.458414 -350.289622)
		(width 0.10668)
		(layer "B.Cu")
		(net "PVDD11_S3_P1_EN")
	)
	(segment
		(start 157.68701 -357.261668)
		(end 168.703244 -357.261668)
		(width 0.10668)
		(layer "B.Cu")
		(net "PVDD11_S3_P1_EN")
	)
	(segment
		(start 155.458414 -350.289622)
		(end 153.829004 -351.919032)
		(width 0.10668)
		(layer "B.Cu")
		(net "PVDD11_S3_P1_EN")
	)
	(segment
		(start 172.25645 -360.814874)
		(end 173.581314 -360.814874)
		(width 0.10668)
		(layer "B.Cu")
		(net "PVDD11_S3_P1_EN")
	)
	(segment
		(start 198.728838 -107.818936)
		(end 198.342758 -108.205016)
		(width 0.11684)
		(layer "In4.Cu")
		(net "PVDD11_S3_P1_EN")
	)
	(segment
		(start 198.665084 -91.569794)
		(end 198.665084 -102.832916)
		(width 0.11684)
		(layer "In4.Cu")
		(net "PVDD11_S3_P1_EN")
	)
	(segment
		(start 198.665084 -102.832916)
		(end 198.374 -103.124)
		(width 0.11684)
		(layer "In4.Cu")
		(net "PVDD11_S3_P1_EN")
	)
	(segment
		(start 198.374 -104.316022)
		(end 200.331578 -106.2736)
		(width 0.11684)
		(layer "In4.Cu")
		(net "PVDD11_S3_P1_EN")
	)
	(segment
		(start 198.580248 -86.833202)
		(end 198.580248 -91.484958)
		(width 0.11684)
		(layer "In4.Cu")
		(net "PVDD11_S3_P1_EN")
	)
	(segment
		(start 200.331578 -106.2736)
		(end 200.331578 -107.691936)
		(width 0.11684)
		(layer "In4.Cu")
		(net "PVDD11_S3_P1_EN")
	)
	(segment
		(start 198.374 -103.124)
		(end 198.374 -104.316022)
		(width 0.11684)
		(layer "In4.Cu")
		(net "PVDD11_S3_P1_EN")
	)
	(segment
		(start 198.580248 -91.484958)
		(end 198.665084 -91.569794)
		(width 0.11684)
		(layer "In4.Cu")
		(net "PVDD11_S3_P1_EN")
	)
	(segment
		(start 198.342758 -108.205016)
		(end 198.342758 -108.545376)
		(width 0.11684)
		(layer "In4.Cu")
		(net "PVDD11_S3_P1_EN")
	)
	(segment
		(start 200.204578 -107.818936)
		(end 198.728838 -107.818936)
		(width 0.11684)
		(layer "In4.Cu")
		(net "PVDD11_S3_P1_EN")
	)
	(segment
		(start 200.331578 -107.691936)
		(end 200.204578 -107.818936)
		(width 0.11684)
		(layer "In4.Cu")
		(net "PVDD11_S3_P1_EN")
	)
	(segment
		(start 165.957504 -346.911422)
		(end 166.164006 -346.911422)
		(width 0.1524)
		(layer "F.Cu")
		(net "PVDD11_S3_P1_ADDR_CFG")
	)
	(segment
		(start 166.164006 -346.911422)
		(end 166.542466 -347.289882)
		(width 0.1524)
		(layer "F.Cu")
		(net "PVDD11_S3_P1_ADDR_CFG")
	)
	(segment
		(start 165.957504 -347.044518)
		(end 165.957504 -346.911422)
		(width 0.1524)
		(layer "F.Cu")
		(net "PVDD11_S3_P1_ADDR_CFG")
	)
	(segment
		(start 164.628576 -347.95333)
		(end 165.048692 -347.95333)
		(width 0.1524)
		(layer "F.Cu")
		(net "PVDD11_S3_P1_ADDR_CFG")
	)
	(segment
		(start 165.048692 -347.95333)
		(end 165.957504 -347.044518)
		(width 0.1524)
		(layer "F.Cu")
		(net "PVDD11_S3_P1_ADDR_CFG")
	)
	(via
		(at 165.957504 -346.911422)
		(size 0.508)
		(drill 0.254)
		(layers "F.Cu" "B.Cu")
		(net "PVDD11_S3_P1_ADDR_CFG")
	)
	(segment
		(start 229.067868 -237.963202)
		(end 230.245666 -239.141)
		(width 0.508)
		(layer "F.Cu")
		(net "PVDD11_S3_P1")
	)
	(segment
		(start 130.407918 -263.290304)
		(end 130.87477 -263.556242)
		(width 0.350012)
		(layer "F.Cu")
		(net "PVDD11_S3_P1")
	)
	(segment
		(start 143.567912 -273.010376)
		(end 144.034764 -273.276314)
		(width 0.350012)
		(layer "F.Cu")
		(net "PVDD11_S3_P1")
	)
	(segment
		(start 109.257846 -265.720322)
		(end 108.790994 -265.98626)
		(width 0.350012)
		(layer "F.Cu")
		(net "PVDD11_S3_P1")
	)
	(segment
		(start 143.567912 -277.870412)
		(end 144.034764 -278.13635)
		(width 0.350012)
		(layer "F.Cu")
		(net "PVDD11_S3_P1")
	)
	(segment
		(start 143.098012 -285.160466)
		(end 143.56461 -285.426404)
		(width 0.350012)
		(layer "F.Cu")
		(net "PVDD11_S3_P1")
	)
	(segment
		(start 125.707902 -264.910316)
		(end 126.174754 -265.176254)
		(width 0.350012)
		(layer "F.Cu")
		(net "PVDD11_S3_P1")
	)
	(segment
		(start 235.963714 -237.521242)
		(end 236.69371 -238.251238)
		(width 0.508)
		(layer "F.Cu")
		(net "PVDD11_S3_P1")
	)
	(segment
		(start 127.117856 -288.400236)
		(end 127.584708 -288.666174)
		(width 0.350012)
		(layer "F.Cu")
		(net "PVDD11_S3_P1")
	)
	(segment
		(start 143.098012 -290.020248)
		(end 143.56461 -290.286186)
		(width 0.350012)
		(layer "F.Cu")
		(net "PVDD11_S3_P1")
	)
	(segment
		(start 129.938018 -270.580358)
		(end 130.40487 -270.846296)
		(width 0.350012)
		(layer "F.Cu")
		(net "PVDD11_S3_P1")
	)
	(segment
		(start 121.94794 -263.290304)
		(end 122.414792 -263.556242)
		(width 0.350012)
		(layer "F.Cu")
		(net "PVDD11_S3_P1")
	)
	(segment
		(start 129.938018 -290.020248)
		(end 130.40487 -290.286186)
		(width 0.350012)
		(layer "F.Cu")
		(net "PVDD11_S3_P1")
	)
	(segment
		(start 45.61205 -171.831)
		(end 45.61205 -170.815)
		(width 0.508)
		(layer "F.Cu")
		(net "PVDD11_S3_P1")
	)
	(segment
		(start 110.6678 -266.530328)
		(end 110.200948 -266.796266)
		(width 0.350012)
		(layer "F.Cu")
		(net "PVDD11_S3_P1")
	)
	(segment
		(start 127.117856 -285.160466)
		(end 127.584708 -285.426404)
		(width 0.350012)
		(layer "F.Cu")
		(net "PVDD11_S3_P1")
	)
	(segment
		(start 136.517888 -270.580358)
		(end 136.98474 -270.846296)
		(width 0.350012)
		(layer "F.Cu")
		(net "PVDD11_S3_P1")
	)
	(segment
		(start 127.117856 -273.820382)
		(end 127.584708 -274.08632)
		(width 0.350012)
		(layer "F.Cu")
		(net "PVDD11_S3_P1")
	)
	(segment
		(start 96.5454 -130.5306)
		(end 96.0628 -130.048)
		(width 0.508)
		(layer "F.Cu")
		(net "PVDD11_S3_P1")
	)
	(segment
		(start 142.627858 -294.070278)
		(end 143.09471 -294.336216)
		(width 0.350012)
		(layer "F.Cu")
		(net "PVDD11_S3_P1")
	)
	(segment
		(start 103.617776 -265.720322)
		(end 103.151178 -265.98626)
		(width 0.350012)
		(layer "F.Cu")
		(net "PVDD11_S3_P1")
	)
	(segment
		(start 115.83797 -265.720322)
		(end 116.304822 -265.98626)
		(width 0.350012)
		(layer "F.Cu")
		(net "PVDD11_S3_P1")
	)
	(segment
		(start 136.517888 -285.160466)
		(end 136.98474 -285.426404)
		(width 0.350012)
		(layer "F.Cu")
		(net "PVDD11_S3_P1")
	)
	(segment
		(start 123.827794 -263.290304)
		(end 124.294646 -263.556242)
		(width 0.350012)
		(layer "F.Cu")
		(net "PVDD11_S3_P1")
	)
	(segment
		(start 125.238002 -264.10031)
		(end 125.704854 -264.366248)
		(width 0.350012)
		(layer "F.Cu")
		(net "PVDD11_S3_P1")
	)
	(segment
		(start 127.117856 -277.060406)
		(end 127.584708 -277.326344)
		(width 0.350012)
		(layer "F.Cu")
		(net "PVDD11_S3_P1")
	)
	(segment
		(start 113.957862 -265.720322)
		(end 114.424714 -265.98626)
		(width 0.350012)
		(layer "F.Cu")
		(net "PVDD11_S3_P1")
	)
	(segment
		(start 127.117856 -270.580358)
		(end 127.584708 -270.846296)
		(width 0.350012)
		(layer "F.Cu")
		(net "PVDD11_S3_P1")
	)
	(segment
		(start 46.355 -170.815)
		(end 45.61205 -170.815)
		(width 0.508)
		(layer "F.Cu")
		(net "PVDD11_S3_P1")
	)
	(segment
		(start 129.938018 -265.720322)
		(end 130.40487 -265.98626)
		(width 0.350012)
		(layer "F.Cu")
		(net "PVDD11_S3_P1")
	)
	(segment
		(start 101.737922 -264.10031)
		(end 101.27107 -264.366248)
		(width 0.350012)
		(layer "F.Cu")
		(net "PVDD11_S3_P1")
	)
	(segment
		(start 87.621618 -130.048)
		(end 79.95412 -137.715498)
		(width 0.508)
		(layer "F.Cu")
		(net "PVDD11_S3_P1")
	)
	(segment
		(start 116.30787 -266.530328)
		(end 116.774722 -266.796266)
		(width 0.350012)
		(layer "F.Cu")
		(net "PVDD11_S3_P1")
	)
	(segment
		(start 230.245666 -239.141)
		(end 233.553 -239.141)
		(width 0.508)
		(layer "F.Cu")
		(net "PVDD11_S3_P1")
	)
	(segment
		(start 143.567912 -287.590484)
		(end 144.034764 -287.856422)
		(width 0.350012)
		(layer "F.Cu")
		(net "PVDD11_S3_P1")
	)
	(segment
		(start 105.497884 -265.720322)
		(end 105.031032 -265.98626)
		(width 0.350012)
		(layer "F.Cu")
		(net "PVDD11_S3_P1")
	)
	(segment
		(start 127.117856 -265.720322)
		(end 127.584708 -265.98626)
		(width 0.350012)
		(layer "F.Cu")
		(net "PVDD11_S3_P1")
	)
	(segment
		(start 236.69371 -238.251238)
		(end 236.69371 -238.97971)
		(width 0.508)
		(layer "F.Cu")
		(net "PVDD11_S3_P1")
	)
	(segment
		(start 136.517888 -290.020248)
		(end 136.98474 -290.286186)
		(width 0.350012)
		(layer "F.Cu")
		(net "PVDD11_S3_P1")
	)
	(segment
		(start 129.938018 -285.160466)
		(end 130.40487 -285.426404)
		(width 0.350012)
		(layer "F.Cu")
		(net "PVDD11_S3_P1")
	)
	(segment
		(start 143.098012 -270.580358)
		(end 143.56461 -270.846296)
		(width 0.350012)
		(layer "F.Cu")
		(net "PVDD11_S3_P1")
	)
	(segment
		(start 136.987788 -282.730448)
		(end 137.45464 -282.996386)
		(width 0.350012)
		(layer "F.Cu")
		(net "PVDD11_S3_P1")
	)
	(segment
		(start 130.407918 -277.870412)
		(end 130.87477 -278.13635)
		(width 0.350012)
		(layer "F.Cu")
		(net "PVDD11_S3_P1")
	)
	(segment
		(start 234.177332 -237.521242)
		(end 235.963714 -237.521242)
		(width 0.508)
		(layer "F.Cu")
		(net "PVDD11_S3_P1")
	)
	(segment
		(start 107.377992 -265.720322)
		(end 106.91114 -265.98626)
		(width 0.350012)
		(layer "F.Cu")
		(net "PVDD11_S3_P1")
	)
	(segment
		(start 174.26813 -173.03623)
		(end 174.26813 -174.06112)
		(width 0.508)
		(layer "F.Cu")
		(net "PVDD11_S3_P1")
	)
	(segment
		(start 233.553 -238.145574)
		(end 234.177332 -237.521242)
		(width 0.508)
		(layer "F.Cu")
		(net "PVDD11_S3_P1")
	)
	(segment
		(start 117.717824 -265.720322)
		(end 118.184676 -265.98626)
		(width 0.350012)
		(layer "F.Cu")
		(net "PVDD11_S3_P1")
	)
	(segment
		(start 183.079898 -160.212024)
		(end 183.079898 -159.488378)
		(width 0.508)
		(layer "F.Cu")
		(net "PVDD11_S3_P1")
	)
	(segment
		(start 165.080188 -138.58494)
		(end 164.781484 -138.883644)
		(width 0.508)
		(layer "F.Cu")
		(net "PVDD11_S3_P1")
	)
	(segment
		(start 43.038014 -172.922946)
		(end 43.038014 -173.938946)
		(width 0.508)
		(layer "F.Cu")
		(net "PVDD11_S3_P1")
	)
	(segment
		(start 79.95412 -137.715498)
		(end 79.95412 -138.611864)
		(width 0.508)
		(layer "F.Cu")
		(net "PVDD11_S3_P1")
	)
	(segment
		(start 109.850174 -130.5306)
		(end 96.5454 -130.5306)
		(width 0.508)
		(layer "F.Cu")
		(net "PVDD11_S3_P1")
	)
	(segment
		(start 127.117856 -267.340334)
		(end 127.584708 -267.606272)
		(width 0.350012)
		(layer "F.Cu")
		(net "PVDD11_S3_P1")
	)
	(segment
		(start 121.94794 -264.910316)
		(end 122.414792 -265.176254)
		(width 0.350012)
		(layer "F.Cu")
		(net "PVDD11_S3_P1")
	)
	(segment
		(start 143.098012 -280.30043)
		(end 143.56461 -280.566368)
		(width 0.350012)
		(layer "F.Cu")
		(net "PVDD11_S3_P1")
	)
	(segment
		(start 136.987788 -277.870412)
		(end 137.45464 -278.13635)
		(width 0.350012)
		(layer "F.Cu")
		(net "PVDD11_S3_P1")
	)
	(segment
		(start 103.147876 -266.530328)
		(end 102.681024 -266.796266)
		(width 0.350012)
		(layer "F.Cu")
		(net "PVDD11_S3_P1")
	)
	(segment
		(start 130.407918 -268.15034)
		(end 130.87477 -268.416278)
		(width 0.350012)
		(layer "F.Cu")
		(net "PVDD11_S3_P1")
	)
	(segment
		(start 174.189644 -172.957744)
		(end 174.26813 -173.03623)
		(width 0.508)
		(layer "F.Cu")
		(net "PVDD11_S3_P1")
	)
	(segment
		(start 143.567912 -282.730448)
		(end 144.034764 -282.996386)
		(width 0.350012)
		(layer "F.Cu")
		(net "PVDD11_S3_P1")
	)
	(segment
		(start 169.443654 -178.885596)
		(end 169.443654 -186.962034)
		(width 0.508)
		(layer "F.Cu")
		(net "PVDD11_S3_P1")
	)
	(segment
		(start 120.067832 -266.530328)
		(end 120.534684 -266.796266)
		(width 0.350012)
		(layer "F.Cu")
		(net "PVDD11_S3_P1")
	)
	(segment
		(start 123.357894 -265.720322)
		(end 123.824746 -265.98626)
		(width 0.350012)
		(layer "F.Cu")
		(net "PVDD11_S3_P1")
	)
	(segment
		(start 129.938018 -280.30043)
		(end 130.40487 -280.566368)
		(width 0.350012)
		(layer "F.Cu")
		(net "PVDD11_S3_P1")
	)
	(segment
		(start 125.238002 -265.720322)
		(end 125.704854 -265.98626)
		(width 0.350012)
		(layer "F.Cu")
		(net "PVDD11_S3_P1")
	)
	(segment
		(start 101.737922 -265.720322)
		(end 101.27107 -265.98626)
		(width 0.350012)
		(layer "F.Cu")
		(net "PVDD11_S3_P1")
	)
	(segment
		(start 182.404766 -168.717468)
		(end 182.404766 -169.34815)
		(width 0.508)
		(layer "F.Cu")
		(net "PVDD11_S3_P1")
	)
	(segment
		(start 123.357894 -264.10031)
		(end 123.824746 -264.366248)
		(width 0.350012)
		(layer "F.Cu")
		(net "PVDD11_S3_P1")
	)
	(segment
		(start 136.987788 -273.010376)
		(end 137.45464 -273.276314)
		(width 0.350012)
		(layer "F.Cu")
		(net "PVDD11_S3_P1")
	)
	(segment
		(start 43.038014 -173.938946)
		(end 43.815 -173.938946)
		(width 0.508)
		(layer "F.Cu")
		(net "PVDD11_S3_P1")
	)
	(segment
		(start 127.117856 -264.10031)
		(end 127.584708 -264.366248)
		(width 0.350012)
		(layer "F.Cu")
		(net "PVDD11_S3_P1")
	)
	(segment
		(start 129.938018 -275.440394)
		(end 130.40487 -275.706332)
		(width 0.350012)
		(layer "F.Cu")
		(net "PVDD11_S3_P1")
	)
	(segment
		(start 142.470124 -138.883644)
		(end 132.731002 -129.144522)
		(width 0.508)
		(layer "F.Cu")
		(net "PVDD11_S3_P1")
	)
	(segment
		(start 123.827794 -266.530328)
		(end 124.294646 -266.796266)
		(width 0.350012)
		(layer "F.Cu")
		(net "PVDD11_S3_P1")
	)
	(segment
		(start 96.0628 -130.048)
		(end 87.621618 -130.048)
		(width 0.508)
		(layer "F.Cu")
		(net "PVDD11_S3_P1")
	)
	(segment
		(start 136.517888 -265.720322)
		(end 136.98474 -265.98626)
		(width 0.350012)
		(layer "F.Cu")
		(net "PVDD11_S3_P1")
	)
	(segment
		(start 130.407918 -282.730448)
		(end 130.87477 -282.996386)
		(width 0.350012)
		(layer "F.Cu")
		(net "PVDD11_S3_P1")
	)
	(segment
		(start 136.987788 -287.590484)
		(end 137.45464 -287.856422)
		(width 0.350012)
		(layer "F.Cu")
		(net "PVDD11_S3_P1")
	)
	(segment
		(start 174.26813 -174.06112)
		(end 169.443654 -178.885596)
		(width 0.508)
		(layer "F.Cu")
		(net "PVDD11_S3_P1")
	)
	(segment
		(start 236.69371 -238.97971)
		(end 236.855 -239.141)
		(width 0.508)
		(layer "F.Cu")
		(net "PVDD11_S3_P1")
	)
	(segment
		(start 121.477786 -264.10031)
		(end 121.944638 -264.366248)
		(width 0.350012)
		(layer "F.Cu")
		(net "PVDD11_S3_P1")
	)
	(segment
		(start 164.781484 -138.883644)
		(end 142.470124 -138.883644)
		(width 0.508)
		(layer "F.Cu")
		(net "PVDD11_S3_P1")
	)
	(segment
		(start 143.567912 -268.15034)
		(end 144.034764 -268.416278)
		(width 0.350012)
		(layer "F.Cu")
		(net "PVDD11_S3_P1")
	)
	(segment
		(start 130.407918 -287.590484)
		(end 130.87477 -287.856422)
		(width 0.350012)
		(layer "F.Cu")
		(net "PVDD11_S3_P1")
	)
	(segment
		(start 111.137954 -265.720322)
		(end 110.671102 -265.98626)
		(width 0.350012)
		(layer "F.Cu")
		(net "PVDD11_S3_P1")
	)
	(segment
		(start 106.907838 -266.530328)
		(end 106.440986 -266.796266)
		(width 0.350012)
		(layer "F.Cu")
		(net "PVDD11_S3_P1")
	)
	(segment
		(start 125.707902 -263.290304)
		(end 126.174754 -263.556242)
		(width 0.350012)
		(layer "F.Cu")
		(net "PVDD11_S3_P1")
	)
	(segment
		(start 136.987788 -292.450266)
		(end 137.45464 -292.716204)
		(width 0.350012)
		(layer "F.Cu")
		(net "PVDD11_S3_P1")
	)
	(segment
		(start 119.597932 -265.720322)
		(end 120.064784 -265.98626)
		(width 0.350012)
		(layer "F.Cu")
		(net "PVDD11_S3_P1")
	)
	(segment
		(start 34.265108 -172.53966)
		(end 34.265108 -171.52366)
		(width 0.508)
		(layer "F.Cu")
		(net "PVDD11_S3_P1")
	)
	(segment
		(start 183.420766 -168.717468)
		(end 183.420766 -169.34815)
		(width 0.508)
		(layer "F.Cu")
		(net "PVDD11_S3_P1")
	)
	(segment
		(start 130.407918 -273.010376)
		(end 130.87477 -273.276314)
		(width 0.350012)
		(layer "F.Cu")
		(net "PVDD11_S3_P1")
	)
	(segment
		(start 143.098012 -275.440394)
		(end 143.56461 -275.706332)
		(width 0.350012)
		(layer "F.Cu")
		(net "PVDD11_S3_P1")
	)
	(segment
		(start 143.567912 -292.450266)
		(end 144.034764 -292.716204)
		(width 0.350012)
		(layer "F.Cu")
		(net "PVDD11_S3_P1")
	)
	(segment
		(start 130.407918 -292.450266)
		(end 130.87477 -292.716204)
		(width 0.350012)
		(layer "F.Cu")
		(net "PVDD11_S3_P1")
	)
	(segment
		(start 127.117856 -281.920442)
		(end 127.584708 -282.18638)
		(width 0.350012)
		(layer "F.Cu")
		(net "PVDD11_S3_P1")
	)
	(segment
		(start 123.827794 -264.910316)
		(end 124.294646 -265.176254)
		(width 0.350012)
		(layer "F.Cu")
		(net "PVDD11_S3_P1")
	)
	(segment
		(start 111.236252 -129.144522)
		(end 109.850174 -130.5306)
		(width 0.508)
		(layer "F.Cu")
		(net "PVDD11_S3_P1")
	)
	(segment
		(start 132.731002 -129.144522)
		(end 111.236252 -129.144522)
		(width 0.508)
		(layer "F.Cu")
		(net "PVDD11_S3_P1")
	)
	(segment
		(start 233.553 -239.141)
		(end 233.553 -238.145574)
		(width 0.508)
		(layer "F.Cu")
		(net "PVDD11_S3_P1")
	)
	(segment
		(start 136.517888 -275.440394)
		(end 136.98474 -275.706332)
		(width 0.350012)
		(layer "F.Cu")
		(net "PVDD11_S3_P1")
	)
	(segment
		(start 121.477786 -265.720322)
		(end 121.944638 -265.98626)
		(width 0.350012)
		(layer "F.Cu")
		(net "PVDD11_S3_P1")
	)
	(segment
		(start 136.517888 -280.30043)
		(end 136.98474 -280.566368)
		(width 0.350012)
		(layer "F.Cu")
		(net "PVDD11_S3_P1")
	)
	(segment
		(start 34.265108 -172.53966)
		(end 33.51784 -172.53966)
		(width 0.508)
		(layer "F.Cu")
		(net "PVDD11_S3_P1")
	)
	(segment
		(start 126.647956 -279.490424)
		(end 127.114808 -279.756362)
		(width 0.350012)
		(layer "F.Cu")
		(net "PVDD11_S3_P1")
	)
	(segment
		(start 182.047134 -160.195768)
		(end 182.047134 -159.488378)
		(width 0.508)
		(layer "F.Cu")
		(net "PVDD11_S3_P1")
	)
	(segment
		(start 103.147876 -264.910316)
		(end 102.681024 -265.176254)
		(width 0.350012)
		(layer "F.Cu")
		(net "PVDD11_S3_P1")
	)
	(segment
		(start 136.987788 -268.15034)
		(end 137.45464 -268.416278)
		(width 0.350012)
		(layer "F.Cu")
		(net "PVDD11_S3_P1")
	)
	(via
		(at 33.51784 -172.53966)
		(size 0.508)
		(drill 0.254)
		(layers "F.Cu" "B.Cu")
		(net "PVDD11_S3_P1")
	)
	(via
		(at 195.437506 -336.028792)
		(size 0.508)
		(drill 0.254)
		(layers "F.Cu" "B.Cu")
		(net "PVDD11_S3_P1")
	)
	(via
		(at 136.98474 -265.98626)
		(size 0.4064)
		(drill 0.2032)
		(layers "F.Cu" "B.Cu")
		(net "PVDD11_S3_P1")
	)
	(via
		(at 183.420766 -169.34815)
		(size 0.508)
		(drill 0.254)
		(layers "F.Cu" "B.Cu")
		(net "PVDD11_S3_P1")
	)
	(via
		(at 173.956472 -337.722718)
		(size 0.508)
		(drill 0.254)
		(layers "F.Cu" "B.Cu")
		(net "PVDD11_S3_P1")
	)
	(via
		(at 173.956472 -338.357718)
		(size 0.508)
		(drill 0.254)
		(layers "F.Cu" "B.Cu")
		(net "PVDD11_S3_P1")
	)
	(via
		(at 189.405514 -338.435696)
		(size 0.508)
		(drill 0.254)
		(layers "F.Cu" "B.Cu")
		(net "PVDD11_S3_P1")
	)
	(via
		(at 110.671102 -265.98626)
		(size 0.4064)
		(drill 0.2032)
		(layers "F.Cu" "B.Cu")
		(net "PVDD11_S3_P1")
	)
	(via
		(at 193.614294 -341.864696)
		(size 0.508)
		(drill 0.254)
		(layers "F.Cu" "B.Cu")
		(net "PVDD11_S3_P1")
	)
	(via
		(at 183.220106 -334.530192)
		(size 0.508)
		(drill 0.254)
		(layers "F.Cu" "B.Cu")
		(net "PVDD11_S3_P1")
	)
	(via
		(at 186.877706 -336.054192)
		(size 0.508)
		(drill 0.254)
		(layers "F.Cu" "B.Cu")
		(net "PVDD11_S3_P1")
	)
	(via
		(at 180.413152 -337.737958)
		(size 0.508)
		(drill 0.254)
		(layers "F.Cu" "B.Cu")
		(net "PVDD11_S3_P1")
	)
	(via
		(at 193.089276 -340.366096)
		(size 0.508)
		(drill 0.254)
		(layers "F.Cu" "B.Cu")
		(net "PVDD11_S3_P1")
	)
	(via
		(at 136.98474 -270.846296)
		(size 0.4064)
		(drill 0.2032)
		(layers "F.Cu" "B.Cu")
		(net "PVDD11_S3_P1")
	)
	(via
		(at 180.807106 -335.368392)
		(size 0.508)
		(drill 0.254)
		(layers "F.Cu" "B.Cu")
		(net "PVDD11_S3_P1")
	)
	(via
		(at 179.413154 -354.987352)
		(size 0.508)
		(drill 0.254)
		(layers "F.Cu" "B.Cu")
		(net "PVDD11_S3_P1")
	)
	(via
		(at 177.766472 -338.995258)
		(size 0.508)
		(drill 0.254)
		(layers "F.Cu" "B.Cu")
		(net "PVDD11_S3_P1")
	)
	(via
		(at 193.739516 -337.137756)
		(size 0.508)
		(drill 0.254)
		(layers "F.Cu" "B.Cu")
		(net "PVDD11_S3_P1")
	)
	(via
		(at 118.35511 -262.180324)
		(size 0.4826)
		(drill 0.254)
		(layers "F.Cu" "B.Cu")
		(net "PVDD11_S3_P1")
	)
	(via
		(at 144.034764 -268.416278)
		(size 0.4064)
		(drill 0.2032)
		(layers "F.Cu" "B.Cu")
		(net "PVDD11_S3_P1")
	)
	(via
		(at 106.907838 -264.36828)
		(size 0.4064)
		(drill 0.2032)
		(layers "F.Cu" "B.Cu")
		(net "PVDD11_S3_P1")
	)
	(via
		(at 116.304822 -265.98626)
		(size 0.4064)
		(drill 0.2032)
		(layers "F.Cu" "B.Cu")
		(net "PVDD11_S3_P1")
	)
	(via
		(at 127.584708 -267.606272)
		(size 0.4064)
		(drill 0.2032)
		(layers "F.Cu" "B.Cu")
		(net "PVDD11_S3_P1")
	)
	(via
		(at 143.56461 -270.846296)
		(size 0.4064)
		(drill 0.2032)
		(layers "F.Cu" "B.Cu")
		(net "PVDD11_S3_P1")
	)
	(via
		(at 188.714634 -338.359496)
		(size 0.508)
		(drill 0.254)
		(layers "F.Cu" "B.Cu")
		(net "PVDD11_S3_P1")
	)
	(via
		(at 192.440052 -337.138518)
		(size 0.508)
		(drill 0.254)
		(layers "F.Cu" "B.Cu")
		(net "PVDD11_S3_P1")
	)
	(via
		(at 183.220106 -333.768192)
		(size 0.508)
		(drill 0.254)
		(layers "F.Cu" "B.Cu")
		(net "PVDD11_S3_P1")
	)
	(via
		(at 192.999106 -336.028792)
		(size 0.508)
		(drill 0.254)
		(layers "F.Cu" "B.Cu")
		(net "PVDD11_S3_P1")
	)
	(via
		(at 105.027984 -264.36828)
		(size 0.4064)
		(drill 0.2032)
		(layers "F.Cu" "B.Cu")
		(net "PVDD11_S3_P1")
	)
	(via
		(at 144.034764 -292.716204)
		(size 0.4064)
		(drill 0.2032)
		(layers "F.Cu" "B.Cu")
		(net "PVDD11_S3_P1")
	)
	(via
		(at 173.316392 -340.262718)
		(size 0.508)
		(drill 0.254)
		(layers "F.Cu" "B.Cu")
		(net "PVDD11_S3_P1")
	)
	(via
		(at 181.820312 -337.915758)
		(size 0.508)
		(drill 0.254)
		(layers "F.Cu" "B.Cu")
		(net "PVDD11_S3_P1")
	)
	(via
		(at 113.348008 -262.237474)
		(size 0.4826)
		(drill 0.254)
		(layers "F.Cu" "B.Cu")
		(net "PVDD11_S3_P1")
	)
	(via
		(at 116.774722 -266.796266)
		(size 0.4064)
		(drill 0.2032)
		(layers "F.Cu" "B.Cu")
		(net "PVDD11_S3_P1")
	)
	(via
		(at 189.405514 -340.340696)
		(size 0.508)
		(drill 0.254)
		(layers "F.Cu" "B.Cu")
		(net "PVDD11_S3_P1")
	)
	(via
		(at 130.40487 -270.846296)
		(size 0.4064)
		(drill 0.2032)
		(layers "F.Cu" "B.Cu")
		(net "PVDD11_S3_P1")
	)
	(via
		(at 190.039752 -337.138518)
		(size 0.508)
		(drill 0.254)
		(layers "F.Cu" "B.Cu")
		(net "PVDD11_S3_P1")
	)
	(via
		(at 106.440986 -266.796266)
		(size 0.4064)
		(drill 0.2032)
		(layers "F.Cu" "B.Cu")
		(net "PVDD11_S3_P1")
	)
	(via
		(at 124.294646 -266.796266)
		(size 0.4064)
		(drill 0.2032)
		(layers "F.Cu" "B.Cu")
		(net "PVDD11_S3_P1")
	)
	(via
		(at 177.766472 -339.630258)
		(size 0.508)
		(drill 0.254)
		(layers "F.Cu" "B.Cu")
		(net "PVDD11_S3_P1")
	)
	(via
		(at 181.104032 -338.423758)
		(size 0.508)
		(drill 0.254)
		(layers "F.Cu" "B.Cu")
		(net "PVDD11_S3_P1")
	)
	(via
		(at 127.114808 -279.756362)
		(size 0.4064)
		(drill 0.2032)
		(layers "F.Cu" "B.Cu")
		(net "PVDD11_S3_P1")
	)
	(via
		(at 178.406552 -337.725258)
		(size 0.508)
		(drill 0.254)
		(layers "F.Cu" "B.Cu")
		(net "PVDD11_S3_P1")
	)
	(via
		(at 110.200948 -266.796266)
		(size 0.4064)
		(drill 0.2032)
		(layers "F.Cu" "B.Cu")
		(net "PVDD11_S3_P1")
	)
	(via
		(at 121.944638 -265.98626)
		(size 0.4064)
		(drill 0.2032)
		(layers "F.Cu" "B.Cu")
		(net "PVDD11_S3_P1")
	)
	(via
		(at 136.98474 -290.286186)
		(size 0.4064)
		(drill 0.2032)
		(layers "F.Cu" "B.Cu")
		(net "PVDD11_S3_P1")
	)
	(via
		(at 127.584708 -270.846296)
		(size 0.4064)
		(drill 0.2032)
		(layers "F.Cu" "B.Cu")
		(net "PVDD11_S3_P1")
	)
	(via
		(at 112.397794 -262.237474)
		(size 0.4826)
		(drill 0.254)
		(layers "F.Cu" "B.Cu")
		(net "PVDD11_S3_P1")
	)
	(via
		(at 165.080188 -138.58494)
		(size 0.508)
		(drill 0.254)
		(layers "F.Cu" "B.Cu")
		(net "PVDD11_S3_P1")
	)
	(via
		(at 192.440052 -339.221318)
		(size 0.508)
		(drill 0.254)
		(layers "F.Cu" "B.Cu")
		(net "PVDD11_S3_P1")
	)
	(via
		(at 143.56461 -275.706332)
		(size 0.4064)
		(drill 0.2032)
		(layers "F.Cu" "B.Cu")
		(net "PVDD11_S3_P1")
	)
	(via
		(at 188.714634 -339.629496)
		(size 0.508)
		(drill 0.254)
		(layers "F.Cu" "B.Cu")
		(net "PVDD11_S3_P1")
	)
	(via
		(at 189.341506 -335.292192)
		(size 0.508)
		(drill 0.254)
		(layers "F.Cu" "B.Cu")
		(net "PVDD11_S3_P1")
	)
	(via
		(at 192.999106 -333.742792)
		(size 0.508)
		(drill 0.254)
		(layers "F.Cu" "B.Cu")
		(net "PVDD11_S3_P1")
	)
	(via
		(at 178.249834 -341.626952)
		(size 0.508)
		(drill 0.254)
		(layers "F.Cu" "B.Cu")
		(net "PVDD11_S3_P1")
	)
	(via
		(at 188.714634 -337.724496)
		(size 0.508)
		(drill 0.254)
		(layers "F.Cu" "B.Cu")
		(net "PVDD11_S3_P1")
	)
	(via
		(at 180.463952 -337.102958)
		(size 0.508)
		(drill 0.254)
		(layers "F.Cu" "B.Cu")
		(net "PVDD11_S3_P1")
	)
	(via
		(at 116.197888 -262.237474)
		(size 0.4826)
		(drill 0.254)
		(layers "F.Cu" "B.Cu")
		(net "PVDD11_S3_P1")
	)
	(via
		(at 177.766472 -337.725258)
		(size 0.508)
		(drill 0.254)
		(layers "F.Cu" "B.Cu")
		(net "PVDD11_S3_P1")
	)
	(via
		(at 105.031032 -265.98626)
		(size 0.4064)
		(drill 0.2032)
		(layers "F.Cu" "B.Cu")
		(net "PVDD11_S3_P1")
	)
	(via
		(at 174.742094 -335.358232)
		(size 0.508)
		(drill 0.254)
		(layers "F.Cu" "B.Cu")
		(net "PVDD11_S3_P1")
	)
	(via
		(at 114.297968 -262.237474)
		(size 0.4826)
		(drill 0.254)
		(layers "F.Cu" "B.Cu")
		(net "PVDD11_S3_P1")
	)
	(via
		(at 184.693052 -333.52486)
		(size 0.6604)
		(drill 0.3302)
		(layers "F.Cu" "B.Cu")
		(net "PVDD11_S3_P1")
	)
	(via
		(at 127.584708 -277.326344)
		(size 0.4064)
		(drill 0.2032)
		(layers "F.Cu" "B.Cu")
		(net "PVDD11_S3_P1")
	)
	(via
		(at 109.547914 -262.237474)
		(size 0.4826)
		(drill 0.254)
		(layers "F.Cu" "B.Cu")
		(net "PVDD11_S3_P1")
	)
	(via
		(at 136.98474 -275.706332)
		(size 0.4064)
		(drill 0.2032)
		(layers "F.Cu" "B.Cu")
		(net "PVDD11_S3_P1")
	)
	(via
		(at 120.067832 -264.36828)
		(size 0.4064)
		(drill 0.2032)
		(layers "F.Cu" "B.Cu")
		(net "PVDD11_S3_P1")
	)
	(via
		(at 46.355 -170.815)
		(size 0.508)
		(drill 0.254)
		(layers "F.Cu" "B.Cu")
		(net "PVDD11_S3_P1")
	)
	(via
		(at 143.56461 -285.426404)
		(size 0.4064)
		(drill 0.2032)
		(layers "F.Cu" "B.Cu")
		(net "PVDD11_S3_P1")
	)
	(via
		(at 192.440052 -337.951318)
		(size 0.508)
		(drill 0.254)
		(layers "F.Cu" "B.Cu")
		(net "PVDD11_S3_P1")
	)
	(via
		(at 184.759854 -340.34222)
		(size 0.508)
		(drill 0.254)
		(layers "F.Cu" "B.Cu")
		(net "PVDD11_S3_P1")
	)
	(via
		(at 121.944638 -264.366248)
		(size 0.4064)
		(drill 0.2032)
		(layers "F.Cu" "B.Cu")
		(net "PVDD11_S3_P1")
	)
	(via
		(at 173.956472 -337.087718)
		(size 0.508)
		(drill 0.254)
		(layers "F.Cu" "B.Cu")
		(net "PVDD11_S3_P1")
	)
	(via
		(at 130.40487 -280.566368)
		(size 0.4064)
		(drill 0.2032)
		(layers "F.Cu" "B.Cu")
		(net "PVDD11_S3_P1")
	)
	(via
		(at 178.249834 -340.991952)
		(size 0.508)
		(drill 0.254)
		(layers "F.Cu" "B.Cu")
		(net "PVDD11_S3_P1")
	)
	(via
		(at 102.681024 -265.176254)
		(size 0.4064)
		(drill 0.2032)
		(layers "F.Cu" "B.Cu")
		(net "PVDD11_S3_P1")
	)
	(via
		(at 184.096152 -337.915758)
		(size 0.508)
		(drill 0.254)
		(layers "F.Cu" "B.Cu")
		(net "PVDD11_S3_P1")
	)
	(via
		(at 125.704854 -265.98626)
		(size 0.4064)
		(drill 0.2032)
		(layers "F.Cu" "B.Cu")
		(net "PVDD11_S3_P1")
	)
	(via
		(at 126.174754 -265.176254)
		(size 0.4064)
		(drill 0.2032)
		(layers "F.Cu" "B.Cu")
		(net "PVDD11_S3_P1")
	)
	(via
		(at 130.87477 -287.856422)
		(size 0.4064)
		(drill 0.2032)
		(layers "F.Cu" "B.Cu")
		(net "PVDD11_S3_P1")
	)
	(via
		(at 174.742094 -334.596232)
		(size 0.508)
		(drill 0.254)
		(layers "F.Cu" "B.Cu")
		(net "PVDD11_S3_P1")
	)
	(via
		(at 229.067868 -237.963202)
		(size 0.508)
		(drill 0.254)
		(layers "F.Cu" "B.Cu")
		(net "PVDD11_S3_P1")
	)
	(via
		(at 187.833254 -341.564976)
		(size 0.508)
		(drill 0.254)
		(layers "F.Cu" "B.Cu")
		(net "PVDD11_S3_P1")
	)
	(via
		(at 184.096152 -338.550758)
		(size 0.508)
		(drill 0.254)
		(layers "F.Cu" "B.Cu")
		(net "PVDD11_S3_P1")
	)
	(via
		(at 193.091816 -338.458556)
		(size 0.508)
		(drill 0.254)
		(layers "F.Cu" "B.Cu")
		(net "PVDD11_S3_P1")
	)
	(via
		(at 101.27107 -265.98626)
		(size 0.4064)
		(drill 0.2032)
		(layers "F.Cu" "B.Cu")
		(net "PVDD11_S3_P1")
	)
	(via
		(at 136.98474 -280.566368)
		(size 0.4064)
		(drill 0.2032)
		(layers "F.Cu" "B.Cu")
		(net "PVDD11_S3_P1")
	)
	(via
		(at 185.425334 -337.11642)
		(size 0.508)
		(drill 0.254)
		(layers "F.Cu" "B.Cu")
		(net "PVDD11_S3_P1")
	)
	(via
		(at 184.759854 -338.43722)
		(size 0.508)
		(drill 0.254)
		(layers "F.Cu" "B.Cu")
		(net "PVDD11_S3_P1")
	)
	(via
		(at 137.45464 -287.856422)
		(size 0.4064)
		(drill 0.2032)
		(layers "F.Cu" "B.Cu")
		(net "PVDD11_S3_P1")
	)
	(via
		(at 174.742094 -333.834232)
		(size 0.508)
		(drill 0.254)
		(layers "F.Cu" "B.Cu")
		(net "PVDD11_S3_P1")
	)
	(via
		(at 143.56461 -290.286186)
		(size 0.4064)
		(drill 0.2032)
		(layers "F.Cu" "B.Cu")
		(net "PVDD11_S3_P1")
	)
	(via
		(at 173.956472 -338.992718)
		(size 0.508)
		(drill 0.254)
		(layers "F.Cu" "B.Cu")
		(net "PVDD11_S3_P1")
	)
	(via
		(at 130.40487 -265.98626)
		(size 0.4064)
		(drill 0.2032)
		(layers "F.Cu" "B.Cu")
		(net "PVDD11_S3_P1")
	)
	(via
		(at 173.956472 -340.262718)
		(size 0.508)
		(drill 0.254)
		(layers "F.Cu" "B.Cu")
		(net "PVDD11_S3_P1")
	)
	(via
		(at 106.91114 -265.98626)
		(size 0.4064)
		(drill 0.2032)
		(layers "F.Cu" "B.Cu")
		(net "PVDD11_S3_P1")
	)
	(via
		(at 192.440052 -338.586318)
		(size 0.508)
		(drill 0.254)
		(layers "F.Cu" "B.Cu")
		(net "PVDD11_S3_P1")
	)
	(via
		(at 189.341506 -334.530192)
		(size 0.508)
		(drill 0.254)
		(layers "F.Cu" "B.Cu")
		(net "PVDD11_S3_P1")
	)
	(via
		(at 127.584708 -285.426404)
		(size 0.4064)
		(drill 0.2032)
		(layers "F.Cu" "B.Cu")
		(net "PVDD11_S3_P1")
	)
	(via
		(at 177.766472 -340.265258)
		(size 0.508)
		(drill 0.254)
		(layers "F.Cu" "B.Cu")
		(net "PVDD11_S3_P1")
	)
	(via
		(at 125.704854 -264.366248)
		(size 0.4064)
		(drill 0.2032)
		(layers "F.Cu" "B.Cu")
		(net "PVDD11_S3_P1")
	)
	(via
		(at 127.584708 -264.366248)
		(size 0.4064)
		(drill 0.2032)
		(layers "F.Cu" "B.Cu")
		(net "PVDD11_S3_P1")
	)
	(via
		(at 185.425334 -339.02142)
		(size 0.508)
		(drill 0.254)
		(layers "F.Cu" "B.Cu")
		(net "PVDD11_S3_P1")
	)
	(via
		(at 126.174754 -263.556242)
		(size 0.4064)
		(drill 0.2032)
		(layers "F.Cu" "B.Cu")
		(net "PVDD11_S3_P1")
	)
	(via
		(at 130.87477 -263.556242)
		(size 0.4064)
		(drill 0.2032)
		(layers "F.Cu" "B.Cu")
		(net "PVDD11_S3_P1")
	)
	(via
		(at 127.584708 -265.98626)
		(size 0.4064)
		(drill 0.2032)
		(layers "F.Cu" "B.Cu")
		(net "PVDD11_S3_P1")
	)
	(via
		(at 180.413152 -338.372958)
		(size 0.508)
		(drill 0.254)
		(layers "F.Cu" "B.Cu")
		(net "PVDD11_S3_P1")
	)
	(via
		(at 108.597954 -262.237474)
		(size 0.4826)
		(drill 0.254)
		(layers "F.Cu" "B.Cu")
		(net "PVDD11_S3_P1")
	)
	(via
		(at 233.553 -239.141)
		(size 0.508)
		(drill 0.254)
		(layers "F.Cu" "B.Cu")
		(net "PVDD11_S3_P1")
	)
	(via
		(at 110.497874 -262.237474)
		(size 0.4826)
		(drill 0.254)
		(layers "F.Cu" "B.Cu")
		(net "PVDD11_S3_P1")
	)
	(via
		(at 103.150416 -264.36828)
		(size 0.4064)
		(drill 0.2032)
		(layers "F.Cu" "B.Cu")
		(net "PVDD11_S3_P1")
	)
	(via
		(at 190.039752 -339.221318)
		(size 0.508)
		(drill 0.254)
		(layers "F.Cu" "B.Cu")
		(net "PVDD11_S3_P1")
	)
	(via
		(at 188.714634 -337.089496)
		(size 0.508)
		(drill 0.254)
		(layers "F.Cu" "B.Cu")
		(net "PVDD11_S3_P1")
	)
	(via
		(at 173.495208 -341.007192)
		(size 0.508)
		(drill 0.254)
		(layers "F.Cu" "B.Cu")
		(net "PVDD11_S3_P1")
	)
	(via
		(at 189.405514 -337.800696)
		(size 0.508)
		(drill 0.254)
		(layers "F.Cu" "B.Cu")
		(net "PVDD11_S3_P1")
	)
	(via
		(at 195.803774 -341.844376)
		(size 0.508)
		(drill 0.254)
		(layers "F.Cu" "B.Cu")
		(net "PVDD11_S3_P1")
	)
	(via
		(at 190.039752 -338.586318)
		(size 0.508)
		(drill 0.254)
		(layers "F.Cu" "B.Cu")
		(net "PVDD11_S3_P1")
	)
	(via
		(at 181.820312 -337.128358)
		(size 0.508)
		(drill 0.254)
		(layers "F.Cu" "B.Cu")
		(net "PVDD11_S3_P1")
	)
	(via
		(at 180.413152 -340.277958)
		(size 0.508)
		(drill 0.254)
		(layers "F.Cu" "B.Cu")
		(net "PVDD11_S3_P1")
	)
	(via
		(at 183.220106 -336.054192)
		(size 0.508)
		(drill 0.254)
		(layers "F.Cu" "B.Cu")
		(net "PVDD11_S3_P1")
	)
	(via
		(at 143.09471 -294.336216)
		(size 0.4064)
		(drill 0.2032)
		(layers "F.Cu" "B.Cu")
		(net "PVDD11_S3_P1")
	)
	(via
		(at 108.787946 -264.36828)
		(size 0.4064)
		(drill 0.2032)
		(layers "F.Cu" "B.Cu")
		(net "PVDD11_S3_P1")
	)
	(via
		(at 173.316392 -337.087718)
		(size 0.508)
		(drill 0.254)
		(layers "F.Cu" "B.Cu")
		(net "PVDD11_S3_P1")
	)
	(via
		(at 181.820312 -338.550758)
		(size 0.508)
		(drill 0.254)
		(layers "F.Cu" "B.Cu")
		(net "PVDD11_S3_P1")
	)
	(via
		(at 193.091816 -337.823556)
		(size 0.508)
		(drill 0.254)
		(layers "F.Cu" "B.Cu")
		(net "PVDD11_S3_P1")
	)
	(via
		(at 130.87477 -273.276314)
		(size 0.4064)
		(drill 0.2032)
		(layers "F.Cu" "B.Cu")
		(net "PVDD11_S3_P1")
	)
	(via
		(at 193.089276 -339.731096)
		(size 0.508)
		(drill 0.254)
		(layers "F.Cu" "B.Cu")
		(net "PVDD11_S3_P1")
	)
	(via
		(at 137.45464 -268.416278)
		(size 0.4064)
		(drill 0.2032)
		(layers "F.Cu" "B.Cu")
		(net "PVDD11_S3_P1")
	)
	(via
		(at 102.681024 -266.796266)
		(size 0.4064)
		(drill 0.2032)
		(layers "F.Cu" "B.Cu")
		(net "PVDD11_S3_P1")
	)
	(via
		(at 178.406552 -340.265258)
		(size 0.508)
		(drill 0.254)
		(layers "F.Cu" "B.Cu")
		(net "PVDD11_S3_P1")
	)
	(via
		(at 174.742094 -336.120232)
		(size 0.508)
		(drill 0.254)
		(layers "F.Cu" "B.Cu")
		(net "PVDD11_S3_P1")
	)
	(via
		(at 120.534684 -266.796266)
		(size 0.4064)
		(drill 0.2032)
		(layers "F.Cu" "B.Cu")
		(net "PVDD11_S3_P1")
	)
	(via
		(at 130.87477 -268.416278)
		(size 0.4064)
		(drill 0.2032)
		(layers "F.Cu" "B.Cu")
		(net "PVDD11_S3_P1")
	)
	(via
		(at 195.803774 -341.209376)
		(size 0.508)
		(drill 0.254)
		(layers "F.Cu" "B.Cu")
		(net "PVDD11_S3_P1")
	)
	(via
		(at 189.341506 -336.054192)
		(size 0.508)
		(drill 0.254)
		(layers "F.Cu" "B.Cu")
		(net "PVDD11_S3_P1")
	)
	(via
		(at 178.406552 -338.995258)
		(size 0.508)
		(drill 0.254)
		(layers "F.Cu" "B.Cu")
		(net "PVDD11_S3_P1")
	)
	(via
		(at 180.413152 -339.007958)
		(size 0.508)
		(drill 0.254)
		(layers "F.Cu" "B.Cu")
		(net "PVDD11_S3_P1")
	)
	(via
		(at 122.414792 -263.556242)
		(size 0.4064)
		(drill 0.2032)
		(layers "F.Cu" "B.Cu")
		(net "PVDD11_S3_P1")
	)
	(via
		(at 118.184676 -265.98626)
		(size 0.4064)
		(drill 0.2032)
		(layers "F.Cu" "B.Cu")
		(net "PVDD11_S3_P1")
	)
	(via
		(at 180.807106 -334.606392)
		(size 0.508)
		(drill 0.254)
		(layers "F.Cu" "B.Cu")
		(net "PVDD11_S3_P1")
	)
	(via
		(at 130.87477 -278.13635)
		(size 0.4064)
		(drill 0.2032)
		(layers "F.Cu" "B.Cu")
		(net "PVDD11_S3_P1")
	)
	(via
		(at 123.824746 -265.98626)
		(size 0.4064)
		(drill 0.2032)
		(layers "F.Cu" "B.Cu")
		(net "PVDD11_S3_P1")
	)
	(via
		(at 181.104032 -340.328758)
		(size 0.508)
		(drill 0.254)
		(layers "F.Cu" "B.Cu")
		(net "PVDD11_S3_P1")
	)
	(via
		(at 177.155094 -334.520032)
		(size 0.508)
		(drill 0.254)
		(layers "F.Cu" "B.Cu")
		(net "PVDD11_S3_P1")
	)
	(via
		(at 127.584708 -274.08632)
		(size 0.4064)
		(drill 0.2032)
		(layers "F.Cu" "B.Cu")
		(net "PVDD11_S3_P1")
	)
	(via
		(at 177.155094 -335.282032)
		(size 0.508)
		(drill 0.254)
		(layers "F.Cu" "B.Cu")
		(net "PVDD11_S3_P1")
	)
	(via
		(at 120.064784 -265.98626)
		(size 0.4064)
		(drill 0.2032)
		(layers "F.Cu" "B.Cu")
		(net "PVDD11_S3_P1")
	)
	(via
		(at 137.45464 -282.996386)
		(size 0.4064)
		(drill 0.2032)
		(layers "F.Cu" "B.Cu")
		(net "PVDD11_S3_P1")
	)
	(via
		(at 184.759854 -339.07222)
		(size 0.508)
		(drill 0.254)
		(layers "F.Cu" "B.Cu")
		(net "PVDD11_S3_P1")
	)
	(via
		(at 173.495208 -341.642192)
		(size 0.508)
		(drill 0.254)
		(layers "F.Cu" "B.Cu")
		(net "PVDD11_S3_P1")
	)
	(via
		(at 193.091816 -339.093556)
		(size 0.508)
		(drill 0.254)
		(layers "F.Cu" "B.Cu")
		(net "PVDD11_S3_P1")
	)
	(via
		(at 144.034764 -273.276314)
		(size 0.4064)
		(drill 0.2032)
		(layers "F.Cu" "B.Cu")
		(net "PVDD11_S3_P1")
	)
	(via
		(at 184.785254 -337.11642)
		(size 0.508)
		(drill 0.254)
		(layers "F.Cu" "B.Cu")
		(net "PVDD11_S3_P1")
	)
	(via
		(at 173.956472 -339.627718)
		(size 0.508)
		(drill 0.254)
		(layers "F.Cu" "B.Cu")
		(net "PVDD11_S3_P1")
	)
	(via
		(at 178.406552 -338.360258)
		(size 0.508)
		(drill 0.254)
		(layers "F.Cu" "B.Cu")
		(net "PVDD11_S3_P1")
	)
	(via
		(at 189.405514 -339.705696)
		(size 0.508)
		(drill 0.254)
		(layers "F.Cu" "B.Cu")
		(net "PVDD11_S3_P1")
	)
	(via
		(at 180.807106 -336.130392)
		(size 0.508)
		(drill 0.254)
		(layers "F.Cu" "B.Cu")
		(net "PVDD11_S3_P1")
	)
	(via
		(at 193.739516 -339.042756)
		(size 0.508)
		(drill 0.254)
		(layers "F.Cu" "B.Cu")
		(net "PVDD11_S3_P1")
	)
	(via
		(at 184.096152 -337.128358)
		(size 0.508)
		(drill 0.254)
		(layers "F.Cu" "B.Cu")
		(net "PVDD11_S3_P1")
	)
	(via
		(at 183.220106 -335.292192)
		(size 0.508)
		(drill 0.254)
		(layers "F.Cu" "B.Cu")
		(net "PVDD11_S3_P1")
	)
	(via
		(at 177.155094 -333.758032)
		(size 0.508)
		(drill 0.254)
		(layers "F.Cu" "B.Cu")
		(net "PVDD11_S3_P1")
	)
	(via
		(at 177.766472 -338.360258)
		(size 0.508)
		(drill 0.254)
		(layers "F.Cu" "B.Cu")
		(net "PVDD11_S3_P1")
	)
	(via
		(at 193.614294 -341.229696)
		(size 0.508)
		(drill 0.254)
		(layers "F.Cu" "B.Cu")
		(net "PVDD11_S3_P1")
	)
	(via
		(at 193.739516 -337.772756)
		(size 0.508)
		(drill 0.254)
		(layers "F.Cu" "B.Cu")
		(net "PVDD11_S3_P1")
	)
	(via
		(at 106.405172 -262.180324)
		(size 0.4826)
		(drill 0.254)
		(layers "F.Cu" "B.Cu")
		(net "PVDD11_S3_P1")
	)
	(via
		(at 178.113182 -166.46017)
		(size 0.508)
		(drill 0.254)
		(layers "F.Cu" "B.Cu")
		(net "PVDD11_S3_P1")
	)
	(via
		(at 171.336208 -340.991952)
		(size 0.508)
		(drill 0.254)
		(layers "F.Cu" "B.Cu")
		(net "PVDD11_S3_P1")
	)
	(via
		(at 173.316392 -339.627718)
		(size 0.508)
		(drill 0.254)
		(layers "F.Cu" "B.Cu")
		(net "PVDD11_S3_P1")
	)
	(via
		(at 124.294646 -263.556242)
		(size 0.4064)
		(drill 0.2032)
		(layers "F.Cu" "B.Cu")
		(net "PVDD11_S3_P1")
	)
	(via
		(at 189.405514 -339.070696)
		(size 0.508)
		(drill 0.254)
		(layers "F.Cu" "B.Cu")
		(net "PVDD11_S3_P1")
	)
	(via
		(at 143.56461 -280.566368)
		(size 0.4064)
		(drill 0.2032)
		(layers "F.Cu" "B.Cu")
		(net "PVDD11_S3_P1")
	)
	(via
		(at 181.104032 -339.058758)
		(size 0.508)
		(drill 0.254)
		(layers "F.Cu" "B.Cu")
		(net "PVDD11_S3_P1")
	)
	(via
		(at 184.759854 -337.80222)
		(size 0.508)
		(drill 0.254)
		(layers "F.Cu" "B.Cu")
		(net "PVDD11_S3_P1")
	)
	(via
		(at 185.425334 -340.29142)
		(size 0.508)
		(drill 0.254)
		(layers "F.Cu" "B.Cu")
		(net "PVDD11_S3_P1")
	)
	(via
		(at 182.404766 -169.34815)
		(size 0.508)
		(drill 0.254)
		(layers "F.Cu" "B.Cu")
		(net "PVDD11_S3_P1")
	)
	(via
		(at 110.417864 -258.795266)
		(size 0.4826)
		(drill 0.254)
		(layers "F.Cu" "B.Cu")
		(net "PVDD11_S3_P1")
	)
	(via
		(at 184.759854 -339.70722)
		(size 0.508)
		(drill 0.254)
		(layers "F.Cu" "B.Cu")
		(net "PVDD11_S3_P1")
	)
	(via
		(at 180.807106 -333.844392)
		(size 0.508)
		(drill 0.254)
		(layers "F.Cu" "B.Cu")
		(net "PVDD11_S3_P1")
	)
	(via
		(at 111.447834 -262.237474)
		(size 0.4826)
		(drill 0.254)
		(layers "F.Cu" "B.Cu")
		(net "PVDD11_S3_P1")
	)
	(via
		(at 186.877706 -334.530192)
		(size 0.508)
		(drill 0.254)
		(layers "F.Cu" "B.Cu")
		(net "PVDD11_S3_P1")
	)
	(via
		(at 137.45464 -292.716204)
		(size 0.4064)
		(drill 0.2032)
		(layers "F.Cu" "B.Cu")
		(net "PVDD11_S3_P1")
	)
	(via
		(at 115.26774 -259.845302)
		(size 0.4826)
		(drill 0.254)
		(layers "F.Cu" "B.Cu")
		(net "PVDD11_S3_P1")
	)
	(via
		(at 173.316392 -338.992718)
		(size 0.508)
		(drill 0.254)
		(layers "F.Cu" "B.Cu")
		(net "PVDD11_S3_P1")
	)
	(via
		(at 209.277458 -230.549704)
		(size 0.508)
		(drill 0.254)
		(layers "F.Cu" "B.Cu")
		(net "PVDD11_S3_P1")
	)
	(via
		(at 107.647994 -262.237474)
		(size 0.4826)
		(drill 0.254)
		(layers "F.Cu" "B.Cu")
		(net "PVDD11_S3_P1")
	)
	(via
		(at 114.424714 -265.98626)
		(size 0.4064)
		(drill 0.2032)
		(layers "F.Cu" "B.Cu")
		(net "PVDD11_S3_P1")
	)
	(via
		(at 195.437506 -334.504792)
		(size 0.508)
		(drill 0.254)
		(layers "F.Cu" "B.Cu")
		(net "PVDD11_S3_P1")
	)
	(via
		(at 183.079898 -159.488378)
		(size 0.508)
		(drill 0.254)
		(layers "F.Cu" "B.Cu")
		(net "PVDD11_S3_P1")
	)
	(via
		(at 193.762376 -340.315296)
		(size 0.508)
		(drill 0.254)
		(layers "F.Cu" "B.Cu")
		(net "PVDD11_S3_P1")
	)
	(via
		(at 130.40487 -275.706332)
		(size 0.4064)
		(drill 0.2032)
		(layers "F.Cu" "B.Cu")
		(net "PVDD11_S3_P1")
	)
	(via
		(at 173.316392 -337.722718)
		(size 0.508)
		(drill 0.254)
		(layers "F.Cu" "B.Cu")
		(net "PVDD11_S3_P1")
	)
	(via
		(at 190.039752 -337.951318)
		(size 0.508)
		(drill 0.254)
		(layers "F.Cu" "B.Cu")
		(net "PVDD11_S3_P1")
	)
	(via
		(at 195.437506 -333.742792)
		(size 0.508)
		(drill 0.254)
		(layers "F.Cu" "B.Cu")
		(net "PVDD11_S3_P1")
	)
	(via
		(at 173.316392 -338.357718)
		(size 0.508)
		(drill 0.254)
		(layers "F.Cu" "B.Cu")
		(net "PVDD11_S3_P1")
	)
	(via
		(at 112.667796 -259.845302)
		(size 0.4826)
		(drill 0.254)
		(layers "F.Cu" "B.Cu")
		(net "PVDD11_S3_P1")
	)
	(via
		(at 177.766472 -337.090258)
		(size 0.508)
		(drill 0.254)
		(layers "F.Cu" "B.Cu")
		(net "PVDD11_S3_P1")
	)
	(via
		(at 181.104032 -337.788758)
		(size 0.508)
		(drill 0.254)
		(layers "F.Cu" "B.Cu")
		(net "PVDD11_S3_P1")
	)
	(via
		(at 101.27107 -264.366248)
		(size 0.4064)
		(drill 0.2032)
		(layers "F.Cu" "B.Cu")
		(net "PVDD11_S3_P1")
	)
	(via
		(at 187.942728 -355.102668)
		(size 0.508)
		(drill 0.254)
		(layers "F.Cu" "B.Cu")
		(net "PVDD11_S3_P1")
	)
	(via
		(at 182.047134 -159.488378)
		(size 0.508)
		(drill 0.254)
		(layers "F.Cu" "B.Cu")
		(net "PVDD11_S3_P1")
	)
	(via
		(at 116.30787 -264.36828)
		(size 0.4064)
		(drill 0.2032)
		(layers "F.Cu" "B.Cu")
		(net "PVDD11_S3_P1")
	)
	(via
		(at 236.855 -239.141)
		(size 0.508)
		(drill 0.254)
		(layers "F.Cu" "B.Cu")
		(net "PVDD11_S3_P1")
	)
	(via
		(at 189.341506 -333.768192)
		(size 0.508)
		(drill 0.254)
		(layers "F.Cu" "B.Cu")
		(net "PVDD11_S3_P1")
	)
	(via
		(at 186.877706 -333.768192)
		(size 0.508)
		(drill 0.254)
		(layers "F.Cu" "B.Cu")
		(net "PVDD11_S3_P1")
	)
	(via
		(at 210.339686 -313.564016)
		(size 0.508)
		(drill 0.254)
		(layers "F.Cu" "B.Cu")
		(net "PVDD11_S3_P1")
	)
	(via
		(at 177.155094 -336.044032)
		(size 0.508)
		(drill 0.254)
		(layers "F.Cu" "B.Cu")
		(net "PVDD11_S3_P1")
	)
	(via
		(at 181.820312 -339.185758)
		(size 0.508)
		(drill 0.254)
		(layers "F.Cu" "B.Cu")
		(net "PVDD11_S3_P1")
	)
	(via
		(at 178.406552 -337.090258)
		(size 0.508)
		(drill 0.254)
		(layers "F.Cu" "B.Cu")
		(net "PVDD11_S3_P1")
	)
	(via
		(at 130.87477 -282.996386)
		(size 0.4064)
		(drill 0.2032)
		(layers "F.Cu" "B.Cu")
		(net "PVDD11_S3_P1")
	)
	(via
		(at 127.584708 -288.666174)
		(size 0.4064)
		(drill 0.2032)
		(layers "F.Cu" "B.Cu")
		(net "PVDD11_S3_P1")
	)
	(via
		(at 180.413152 -339.642958)
		(size 0.508)
		(drill 0.254)
		(layers "F.Cu" "B.Cu")
		(net "PVDD11_S3_P1")
	)
	(via
		(at 187.833254 -340.929976)
		(size 0.508)
		(drill 0.254)
		(layers "F.Cu" "B.Cu")
		(net "PVDD11_S3_P1")
	)
	(via
		(at 195.437506 -335.266792)
		(size 0.508)
		(drill 0.254)
		(layers "F.Cu" "B.Cu")
		(net "PVDD11_S3_P1")
	)
	(via
		(at 184.096152 -339.185758)
		(size 0.508)
		(drill 0.254)
		(layers "F.Cu" "B.Cu")
		(net "PVDD11_S3_P1")
	)
	(via
		(at 188.714634 -338.994496)
		(size 0.508)
		(drill 0.254)
		(layers "F.Cu" "B.Cu")
		(net "PVDD11_S3_P1")
	)
	(via
		(at 185.425334 -339.65642)
		(size 0.508)
		(drill 0.254)
		(layers "F.Cu" "B.Cu")
		(net "PVDD11_S3_P1")
	)
	(via
		(at 181.104032 -339.693758)
		(size 0.508)
		(drill 0.254)
		(layers "F.Cu" "B.Cu")
		(net "PVDD11_S3_P1")
	)
	(via
		(at 112.492536 -264.862564)
		(size 0.4826)
		(drill 0.254)
		(layers "F.Cu" "B.Cu")
		(net "PVDD11_S3_P1")
	)
	(via
		(at 185.62193 -340.980776)
		(size 0.508)
		(drill 0.254)
		(layers "F.Cu" "B.Cu")
		(net "PVDD11_S3_P1")
	)
	(via
		(at 137.45464 -278.13635)
		(size 0.4064)
		(drill 0.2032)
		(layers "F.Cu" "B.Cu")
		(net "PVDD11_S3_P1")
	)
	(via
		(at 110.417864 -259.845302)
		(size 0.4826)
		(drill 0.254)
		(layers "F.Cu" "B.Cu")
		(net "PVDD11_S3_P1")
	)
	(via
		(at 124.294646 -265.176254)
		(size 0.4064)
		(drill 0.2032)
		(layers "F.Cu" "B.Cu")
		(net "PVDD11_S3_P1")
	)
	(via
		(at 122.414792 -265.176254)
		(size 0.4064)
		(drill 0.2032)
		(layers "F.Cu" "B.Cu")
		(net "PVDD11_S3_P1")
	)
	(via
		(at 79.95412 -138.611864)
		(size 0.508)
		(drill 0.254)
		(layers "F.Cu" "B.Cu")
		(net "PVDD11_S3_P1")
	)
	(via
		(at 185.425334 -338.38642)
		(size 0.508)
		(drill 0.254)
		(layers "F.Cu" "B.Cu")
		(net "PVDD11_S3_P1")
	)
	(via
		(at 180.396134 -340.991952)
		(size 0.508)
		(drill 0.254)
		(layers "F.Cu" "B.Cu")
		(net "PVDD11_S3_P1")
	)
	(via
		(at 118.187978 -264.36828)
		(size 0.4064)
		(drill 0.2032)
		(layers "F.Cu" "B.Cu")
		(net "PVDD11_S3_P1")
	)
	(via
		(at 189.354714 -337.089496)
		(size 0.508)
		(drill 0.254)
		(layers "F.Cu" "B.Cu")
		(net "PVDD11_S3_P1")
	)
	(via
		(at 186.877706 -335.292192)
		(size 0.508)
		(drill 0.254)
		(layers "F.Cu" "B.Cu")
		(net "PVDD11_S3_P1")
	)
	(via
		(at 43.815 -173.938946)
		(size 0.508)
		(drill 0.254)
		(layers "F.Cu" "B.Cu")
		(net "PVDD11_S3_P1")
	)
	(via
		(at 174.189644 -172.957744)
		(size 0.508)
		(drill 0.254)
		(layers "F.Cu" "B.Cu")
		(net "PVDD11_S3_P1")
	)
	(via
		(at 137.45464 -273.276314)
		(size 0.4064)
		(drill 0.2032)
		(layers "F.Cu" "B.Cu")
		(net "PVDD11_S3_P1")
	)
	(via
		(at 171.336208 -341.626952)
		(size 0.508)
		(drill 0.254)
		(layers "F.Cu" "B.Cu")
		(net "PVDD11_S3_P1")
	)
	(via
		(at 144.034764 -287.856422)
		(size 0.4064)
		(drill 0.2032)
		(layers "F.Cu" "B.Cu")
		(net "PVDD11_S3_P1")
	)
	(via
		(at 108.790994 -265.98626)
		(size 0.4064)
		(drill 0.2032)
		(layers "F.Cu" "B.Cu")
		(net "PVDD11_S3_P1")
	)
	(via
		(at 185.425334 -337.75142)
		(size 0.508)
		(drill 0.254)
		(layers "F.Cu" "B.Cu")
		(net "PVDD11_S3_P1")
	)
	(via
		(at 180.396134 -341.626952)
		(size 0.508)
		(drill 0.254)
		(layers "F.Cu" "B.Cu")
		(net "PVDD11_S3_P1")
	)
	(via
		(at 185.62193 -341.615776)
		(size 0.508)
		(drill 0.254)
		(layers "F.Cu" "B.Cu")
		(net "PVDD11_S3_P1")
	)
	(via
		(at 181.104032 -337.102958)
		(size 0.508)
		(drill 0.254)
		(layers "F.Cu" "B.Cu")
		(net "PVDD11_S3_P1")
	)
	(via
		(at 188.714634 -340.264496)
		(size 0.508)
		(drill 0.254)
		(layers "F.Cu" "B.Cu")
		(net "PVDD11_S3_P1")
	)
	(via
		(at 130.40487 -285.426404)
		(size 0.4064)
		(drill 0.2032)
		(layers "F.Cu" "B.Cu")
		(net "PVDD11_S3_P1")
	)
	(via
		(at 112.492536 -263.846564)
		(size 0.4826)
		(drill 0.254)
		(layers "F.Cu" "B.Cu")
		(net "PVDD11_S3_P1")
	)
	(via
		(at 169.443654 -186.962034)
		(size 0.508)
		(drill 0.254)
		(layers "F.Cu" "B.Cu")
		(net "PVDD11_S3_P1")
	)
	(via
		(at 103.151178 -265.98626)
		(size 0.4064)
		(drill 0.2032)
		(layers "F.Cu" "B.Cu")
		(net "PVDD11_S3_P1")
	)
	(via
		(at 127.584708 -282.18638)
		(size 0.4064)
		(drill 0.2032)
		(layers "F.Cu" "B.Cu")
		(net "PVDD11_S3_P1")
	)
	(via
		(at 193.739516 -338.407756)
		(size 0.508)
		(drill 0.254)
		(layers "F.Cu" "B.Cu")
		(net "PVDD11_S3_P1")
	)
	(via
		(at 123.824746 -264.366248)
		(size 0.4064)
		(drill 0.2032)
		(layers "F.Cu" "B.Cu")
		(net "PVDD11_S3_P1")
	)
	(via
		(at 193.762376 -339.680296)
		(size 0.508)
		(drill 0.254)
		(layers "F.Cu" "B.Cu")
		(net "PVDD11_S3_P1")
	)
	(via
		(at 194.959478 -337.314286)
		(size 0.6604)
		(drill 0.3302)
		(layers "F.Cu" "B.Cu")
		(net "PVDD11_S3_P1")
	)
	(via
		(at 192.999106 -335.266792)
		(size 0.508)
		(drill 0.254)
		(layers "F.Cu" "B.Cu")
		(net "PVDD11_S3_P1")
	)
	(via
		(at 193.091816 -337.137756)
		(size 0.508)
		(drill 0.254)
		(layers "F.Cu" "B.Cu")
		(net "PVDD11_S3_P1")
	)
	(via
		(at 178.406552 -339.630258)
		(size 0.508)
		(drill 0.254)
		(layers "F.Cu" "B.Cu")
		(net "PVDD11_S3_P1")
	)
	(via
		(at 192.999106 -334.504792)
		(size 0.508)
		(drill 0.254)
		(layers "F.Cu" "B.Cu")
		(net "PVDD11_S3_P1")
	)
	(via
		(at 115.247928 -262.237474)
		(size 0.4826)
		(drill 0.254)
		(layers "F.Cu" "B.Cu")
		(net "PVDD11_S3_P1")
	)
	(via
		(at 144.034764 -282.996386)
		(size 0.4064)
		(drill 0.2032)
		(layers "F.Cu" "B.Cu")
		(net "PVDD11_S3_P1")
	)
	(via
		(at 130.87477 -292.716204)
		(size 0.4064)
		(drill 0.2032)
		(layers "F.Cu" "B.Cu")
		(net "PVDD11_S3_P1")
	)
	(via
		(at 136.98474 -285.426404)
		(size 0.4064)
		(drill 0.2032)
		(layers "F.Cu" "B.Cu")
		(net "PVDD11_S3_P1")
	)
	(via
		(at 144.034764 -278.13635)
		(size 0.4064)
		(drill 0.2032)
		(layers "F.Cu" "B.Cu")
		(net "PVDD11_S3_P1")
	)
	(via
		(at 130.40487 -290.286186)
		(size 0.4064)
		(drill 0.2032)
		(layers "F.Cu" "B.Cu")
		(net "PVDD11_S3_P1")
	)
	(segment
		(start 209.277458 -230.549704)
		(end 208.562448 -229.834694)
		(width 0.508)
		(layer "B.Cu")
		(net "PVDD11_S3_P1")
	)
	(segment
		(start 179.258468 -354.360734)
		(end 179.258468 -354.832666)
		(width 0.381)
		(layer "B.Cu")
		(net "PVDD11_S3_P1")
	)
	(segment
		(start 236.855 -240.01095)
		(end 236.855 -239.141)
		(width 0.381)
		(layer "B.Cu")
		(net "PVDD11_S3_P1")
	)
	(segment
		(start 177.84572 -187.542678)
		(end 177.048668 -187.542678)
		(width 0.508)
		(layer "B.Cu")
		(net "PVDD11_S3_P1")
	)
	(segment
		(start 159.7152 -190.76035)
		(end 160.7312 -190.76035)
		(width 0.381)
		(layer "B.Cu")
		(net "PVDD11_S3_P1")
	)
	(segment
		(start 187.585096 -354.591874)
		(end 187.942728 -354.949506)
		(width 0.381)
		(layer "B.Cu")
		(net "PVDD11_S3_P1")
	)
	(segment
		(start 210.339686 -313.564016)
		(end 208.330546 -311.554876)
		(width 0.508)
		(layer "B.Cu")
		(net "PVDD11_S3_P1")
	)
	(segment
		(start 208.330546 -231.496616)
		(end 209.277458 -230.549704)
		(width 0.508)
		(layer "B.Cu")
		(net "PVDD11_S3_P1")
	)
	(segment
		(start 170.94327 -185.202322)
		(end 169.443654 -186.701938)
		(width 0.508)
		(layer "B.Cu")
		(net "PVDD11_S3_P1")
	)
	(segment
		(start 176.142904 -185.839862)
		(end 175.505364 -185.202322)
		(width 0.508)
		(layer "B.Cu")
		(net "PVDD11_S3_P1")
	)
	(segment
		(start 162.10915 -188.548772)
		(end 160.7312 -189.926722)
		(width 0.381)
		(layer "B.Cu")
		(net "PVDD11_S3_P1")
	)
	(segment
		(start 169.443654 -186.962034)
		(end 169.344848 -186.962034)
		(width 0.381)
		(layer "B.Cu")
		(net "PVDD11_S3_P1")
	)
	(segment
		(start 210.523836 -191.82334)
		(end 208.455514 -189.755018)
		(width 0.508)
		(layer "B.Cu")
		(net "PVDD11_S3_P1")
	)
	(segment
		(start 208.330546 -311.554876)
		(end 208.330546 -231.496616)
		(width 0.508)
		(layer "B.Cu")
		(net "PVDD11_S3_P1")
	)
	(segment
		(start 169.443654 -186.701938)
		(end 169.443654 -186.962034)
		(width 0.508)
		(layer "B.Cu")
		(net "PVDD11_S3_P1")
	)
	(segment
		(start 208.455514 -189.755018)
		(end 180.05806 -189.755018)
		(width 0.508)
		(layer "B.Cu")
		(net "PVDD11_S3_P1")
	)
	(segment
		(start 208.562448 -207.078326)
		(end 210.523836 -205.116938)
		(width 0.508)
		(layer "B.Cu")
		(net "PVDD11_S3_P1")
	)
	(segment
		(start 176.142904 -186.636914)
		(end 176.142904 -185.839862)
		(width 0.508)
		(layer "B.Cu")
		(net "PVDD11_S3_P1")
	)
	(segment
		(start 160.7312 -189.926722)
		(end 160.7312 -190.76035)
		(width 0.381)
		(layer "B.Cu")
		(net "PVDD11_S3_P1")
	)
	(segment
		(start 233.553 -240.01095)
		(end 233.553 -239.141)
		(width 0.381)
		(layer "B.Cu")
		(net "PVDD11_S3_P1")
	)
	(segment
		(start 187.942728 -354.949506)
		(end 187.942728 -355.102668)
		(width 0.381)
		(layer "B.Cu")
		(net "PVDD11_S3_P1")
	)
	(segment
		(start 180.05806 -189.755018)
		(end 177.84572 -187.542678)
		(width 0.508)
		(layer "B.Cu")
		(net "PVDD11_S3_P1")
	)
	(segment
		(start 177.048668 -187.542678)
		(end 176.142904 -186.636914)
		(width 0.508)
		(layer "B.Cu")
		(net "PVDD11_S3_P1")
	)
	(segment
		(start 167.75811 -188.548772)
		(end 162.10915 -188.548772)
		(width 0.381)
		(layer "B.Cu")
		(net "PVDD11_S3_P1")
	)
	(segment
		(start 169.344848 -186.962034)
		(end 167.75811 -188.548772)
		(width 0.381)
		(layer "B.Cu")
		(net "PVDD11_S3_P1")
	)
	(segment
		(start 210.523836 -205.116938)
		(end 210.523836 -191.82334)
		(width 0.508)
		(layer "B.Cu")
		(net "PVDD11_S3_P1")
	)
	(segment
		(start 175.505364 -185.202322)
		(end 170.94327 -185.202322)
		(width 0.508)
		(layer "B.Cu")
		(net "PVDD11_S3_P1")
	)
	(segment
		(start 187.585096 -354.386134)
		(end 187.585096 -354.591874)
		(width 0.381)
		(layer "B.Cu")
		(net "PVDD11_S3_P1")
	)
	(segment
		(start 179.258468 -354.832666)
		(end 179.413154 -354.987352)
		(width 0.381)
		(layer "B.Cu")
		(net "PVDD11_S3_P1")
	)
	(segment
		(start 208.562448 -229.834694)
		(end 208.562448 -207.078326)
		(width 0.508)
		(layer "B.Cu")
		(net "PVDD11_S3_P1")
	)
	(segment
		(start 189.405514 -340.340696)
		(end 189.405514 -340.975696)
		(width 0.508)
		(layer "In2.Cu")
		(net "PVDD11_S3_P1")
	)
	(segment
		(start 173.248828 -172.062394)
		(end 174.144178 -172.957744)
		(width 0.508)
		(layer "In2.Cu")
		(net "PVDD11_S3_P1")
	)
	(segment
		(start 178.113182 -164.453824)
		(end 178.113182 -166.46017)
		(width 0.508)
		(layer "In2.Cu")
		(net "PVDD11_S3_P1")
	)
	(segment
		(start 182.047134 -159.488378)
		(end 178.41976 -159.488378)
		(width 0.508)
		(layer "In2.Cu")
		(net "PVDD11_S3_P1")
	)
	(segment
		(start 180.236876 -351.576894)
		(end 180.236876 -353.037648)
		(width 0.508)
		(layer "In2.Cu")
		(net "PVDD11_S3_P1")
	)
	(segment
		(start 179.817014 -344.70848)
		(end 179.817014 -351.157032)
		(width 0.508)
		(layer "In2.Cu")
		(net "PVDD11_S3_P1")
	)
	(segment
		(start 183.079898 -159.488378)
		(end 182.047134 -159.488378)
		(width 0.508)
		(layer "In2.Cu")
		(net "PVDD11_S3_P1")
	)
	(segment
		(start 175.763174 -166.647622)
		(end 173.248828 -169.161968)
		(width 0.508)
		(layer "In2.Cu")
		(net "PVDD11_S3_P1")
	)
	(segment
		(start 177.291492 -163.632134)
		(end 178.113182 -164.453824)
		(width 0.508)
		(layer "In2.Cu")
		(net "PVDD11_S3_P1")
	)
	(segment
		(start 178.113182 -166.46017)
		(end 177.92573 -166.647622)
		(width 0.508)
		(layer "In2.Cu")
		(net "PVDD11_S3_P1")
	)
	(segment
		(start 180.236876 -353.037648)
		(end 179.413154 -353.86137)
		(width 0.508)
		(layer "In2.Cu")
		(net "PVDD11_S3_P1")
	)
	(segment
		(start 173.248828 -169.161968)
		(end 173.248828 -172.062394)
		(width 0.508)
		(layer "In2.Cu")
		(net "PVDD11_S3_P1")
	)
	(segment
		(start 188.549026 -348.27464)
		(end 188.549026 -353.069398)
		(width 0.508)
		(layer "In2.Cu")
		(net "PVDD11_S3_P1")
	)
	(segment
		(start 187.665614 -353.95281)
		(end 187.665614 -354.825554)
		(width 0.508)
		(layer "In2.Cu")
		(net "PVDD11_S3_P1")
	)
	(segment
		(start 187.665614 -354.825554)
		(end 187.942728 -355.102668)
		(width 0.508)
		(layer "In2.Cu")
		(net "PVDD11_S3_P1")
	)
	(segment
		(start 174.144178 -172.957744)
		(end 174.189644 -172.957744)
		(width 0.508)
		(layer "In2.Cu")
		(net "PVDD11_S3_P1")
	)
	(segment
		(start 177.291492 -160.616646)
		(end 177.291492 -163.632134)
		(width 0.508)
		(layer "In2.Cu")
		(net "PVDD11_S3_P1")
	)
	(segment
		(start 179.413154 -353.86137)
		(end 179.413154 -354.987352)
		(width 0.508)
		(layer "In2.Cu")
		(net "PVDD11_S3_P1")
	)
	(segment
		(start 189.354714 -341.026496)
		(end 189.354714 -347.468952)
		(width 0.508)
		(layer "In2.Cu")
		(net "PVDD11_S3_P1")
	)
	(segment
		(start 180.396134 -341.626952)
		(end 180.281834 -341.626952)
		(width 0.508)
		(layer "In2.Cu")
		(net "PVDD11_S3_P1")
	)
	(segment
		(start 179.577746 -342.33104)
		(end 179.577746 -344.469212)
		(width 0.508)
		(layer "In2.Cu")
		(net "PVDD11_S3_P1")
	)
	(segment
		(start 189.405514 -340.975696)
		(end 189.354714 -341.026496)
		(width 0.508)
		(layer "In2.Cu")
		(net "PVDD11_S3_P1")
	)
	(segment
		(start 189.354714 -347.468952)
		(end 188.549026 -348.27464)
		(width 0.508)
		(layer "In2.Cu")
		(net "PVDD11_S3_P1")
	)
	(segment
		(start 177.92573 -166.647622)
		(end 175.763174 -166.647622)
		(width 0.508)
		(layer "In2.Cu")
		(net "PVDD11_S3_P1")
	)
	(segment
		(start 188.549026 -353.069398)
		(end 187.665614 -353.95281)
		(width 0.508)
		(layer "In2.Cu")
		(net "PVDD11_S3_P1")
	)
	(segment
		(start 179.817014 -351.157032)
		(end 180.236876 -351.576894)
		(width 0.508)
		(layer "In2.Cu")
		(net "PVDD11_S3_P1")
	)
	(segment
		(start 178.41976 -159.488378)
		(end 177.291492 -160.616646)
		(width 0.508)
		(layer "In2.Cu")
		(net "PVDD11_S3_P1")
	)
	(segment
		(start 180.281834 -341.626952)
		(end 179.577746 -342.33104)
		(width 0.508)
		(layer "In2.Cu")
		(net "PVDD11_S3_P1")
	)
	(segment
		(start 179.577746 -344.469212)
		(end 179.817014 -344.70848)
		(width 0.508)
		(layer "In2.Cu")
		(net "PVDD11_S3_P1")
	)
	(segment
		(start 171.55922 -154.381708)
		(end 171.55922 -145.077434)
		(width 0.508)
		(layer "In4.Cu")
		(net "PVDD11_S3_P1")
	)
	(segment
		(start 165.080188 -138.598402)
		(end 165.080188 -138.58494)
		(width 0.508)
		(layer "In4.Cu")
		(net "PVDD11_S3_P1")
	)
	(segment
		(start 171.55922 -145.077434)
		(end 165.080188 -138.598402)
		(width 0.508)
		(layer "In4.Cu")
		(net "PVDD11_S3_P1")
	)
	(segment
		(start 177.67427 -166.46017)
		(end 175.043592 -163.829492)
		(width 0.508)
		(layer "In4.Cu")
		(net "PVDD11_S3_P1")
	)
	(segment
		(start 175.043592 -157.86608)
		(end 171.55922 -154.381708)
		(width 0.508)
		(layer "In4.Cu")
		(net "PVDD11_S3_P1")
	)
	(segment
		(start 175.043592 -163.829492)
		(end 175.043592 -157.86608)
		(width 0.508)
		(layer "In4.Cu")
		(net "PVDD11_S3_P1")
	)
	(segment
		(start 178.113182 -166.46017)
		(end 177.67427 -166.46017)
		(width 0.508)
		(layer "In4.Cu")
		(net "PVDD11_S3_P1")
	)
	(segment
		(start 44.781216 -173.938946)
		(end 43.815 -173.938946)
		(width 0.508)
		(layer "In6.Cu")
		(net "PVDD11_S3_P1")
	)
	(segment
		(start 46.355 -170.815)
		(end 46.355 -172.365162)
		(width 0.508)
		(layer "In6.Cu")
		(net "PVDD11_S3_P1")
	)
	(segment
		(start 195.437506 -333.742792)
		(end 206.637128 -333.742792)
		(width 0.508)
		(layer "In6.Cu")
		(net "PVDD11_S3_P1")
	)
	(segment
		(start 42.421302 -169.63517)
		(end 43.601132 -170.815)
		(width 0.508)
		(layer "In6.Cu")
		(net "PVDD11_S3_P1")
	)
	(segment
		(start 210.339686 -314.06846)
		(end 210.339686 -313.564016)
		(width 0.508)
		(layer "In6.Cu")
		(net "PVDD11_S3_P1")
	)
	(segment
		(start 208.57464 -331.80528)
		(end 208.57464 -325.16191)
		(width 0.508)
		(layer "In6.Cu")
		(net "PVDD11_S3_P1")
	)
	(segment
		(start 33.51784 -172.53966)
		(end 37.158676 -172.53966)
		(width 0.508)
		(layer "In6.Cu")
		(net "PVDD11_S3_P1")
	)
	(segment
		(start 208.57464 -325.16191)
		(end 207.604106 -324.191376)
		(width 0.508)
		(layer "In6.Cu")
		(net "PVDD11_S3_P1")
	)
	(segment
		(start 37.158676 -172.53966)
		(end 40.063166 -169.63517)
		(width 0.508)
		(layer "In6.Cu")
		(net "PVDD11_S3_P1")
	)
	(segment
		(start 206.637128 -333.742792)
		(end 208.57464 -331.80528)
		(width 0.508)
		(layer "In6.Cu")
		(net "PVDD11_S3_P1")
	)
	(segment
		(start 43.601132 -170.815)
		(end 46.355 -170.815)
		(width 0.508)
		(layer "In6.Cu")
		(net "PVDD11_S3_P1")
	)
	(segment
		(start 40.063166 -169.63517)
		(end 42.421302 -169.63517)
		(width 0.508)
		(layer "In6.Cu")
		(net "PVDD11_S3_P1")
	)
	(segment
		(start 46.355 -172.365162)
		(end 44.781216 -173.938946)
		(width 0.508)
		(layer "In6.Cu")
		(net "PVDD11_S3_P1")
	)
	(segment
		(start 207.604106 -316.80404)
		(end 210.339686 -314.06846)
		(width 0.508)
		(layer "In6.Cu")
		(net "PVDD11_S3_P1")
	)
	(segment
		(start 207.604106 -324.191376)
		(end 207.604106 -316.80404)
		(width 0.508)
		(layer "In6.Cu")
		(net "PVDD11_S3_P1")
	)
	(segment
		(start 79.356712 -138.014456)
		(end 53.494178 -138.014456)
		(width 0.508)
		(layer "In11.Cu")
		(net "PVDD11_S3_P1")
	)
	(segment
		(start 212.56625 -233.838496)
		(end 209.277458 -230.549704)
		(width 0.508)
		(layer "In11.Cu")
		(net "PVDD11_S3_P1")
	)
	(segment
		(start 229.067868 -237.963202)
		(end 224.943162 -233.838496)
		(width 0.508)
		(layer "In11.Cu")
		(net "PVDD11_S3_P1")
	)
	(segment
		(start 43.25239 -165.766242)
		(end 45.01769 -167.531542)
		(width 0.508)
		(layer "In11.Cu")
		(net "PVDD11_S3_P1")
	)
	(segment
		(start 45.01769 -167.531542)
		(end 45.01769 -169.47769)
		(width 0.508)
		(layer "In11.Cu")
		(net "PVDD11_S3_P1")
	)
	(segment
		(start 224.943162 -233.838496)
		(end 212.56625 -233.838496)
		(width 0.508)
		(layer "In11.Cu")
		(net "PVDD11_S3_P1")
	)
	(segment
		(start 53.494178 -138.014456)
		(end 43.25239 -148.256244)
		(width 0.508)
		(layer "In11.Cu")
		(net "PVDD11_S3_P1")
	)
	(segment
		(start 45.01769 -169.47769)
		(end 46.355 -170.815)
		(width 0.508)
		(layer "In11.Cu")
		(net "PVDD11_S3_P1")
	)
	(segment
		(start 79.95412 -138.611864)
		(end 79.356712 -138.014456)
		(width 0.508)
		(layer "In11.Cu")
		(net "PVDD11_S3_P1")
	)
	(segment
		(start 43.25239 -148.256244)
		(end 43.25239 -165.766242)
		(width 0.508)
		(layer "In11.Cu")
		(net "PVDD11_S3_P1")
	)
	(segment
		(start 178.133756 -166.518844)
		(end 178.113182 -166.49827)
		(width 0.508)
		(layer "In13.Cu")
		(net "PVDD11_S3_P1")
	)
	(segment
		(start 182.050436 -169.70248)
		(end 178.906424 -169.70248)
		(width 0.508)
		(layer "In13.Cu")
		(net "PVDD11_S3_P1")
	)
	(segment
		(start 182.404766 -169.34815)
		(end 182.050436 -169.70248)
		(width 0.508)
		(layer "In13.Cu")
		(net "PVDD11_S3_P1")
	)
	(segment
		(start 178.113182 -166.49827)
		(end 178.113182 -166.46017)
		(width 0.508)
		(layer "In13.Cu")
		(net "PVDD11_S3_P1")
	)
	(segment
		(start 182.404766 -169.34815)
		(end 183.420766 -169.34815)
		(width 0.508)
		(layer "In13.Cu")
		(net "PVDD11_S3_P1")
	)
	(segment
		(start 178.906424 -169.70248)
		(end 178.133756 -168.929812)
		(width 0.508)
		(layer "In13.Cu")
		(net "PVDD11_S3_P1")
	)
	(segment
		(start 178.133756 -168.929812)
		(end 178.133756 -166.518844)
		(width 0.508)
		(layer "In13.Cu")
		(net "PVDD11_S3_P1")
	)
	(segment
		(start 429.570642 -353.702112)
		(end 429.570642 -353.415346)
		(width 0.2032)
		(layer "F.Cu")
		(net "PVDD11_S3_P0_VOS2")
	)
	(segment
		(start 429.24603 -354.026724)
		(end 429.570642 -353.702112)
		(width 0.2032)
		(layer "F.Cu")
		(net "PVDD11_S3_P0_VOS2")
	)
	(via
		(at 429.24603 -354.026724)
		(size 0.508)
		(drill 0.254)
		(layers "F.Cu" "B.Cu")
		(net "PVDD11_S3_P0_VOS2")
	)
	(segment
		(start 428.624746 -353.40544)
		(end 429.24603 -354.026724)
		(width 0.2286)
		(layer "B.Cu")
		(net "PVDD11_S3_P0_VOS2")
	)
	(segment
		(start 428.309278 -353.40544)
		(end 428.624746 -353.40544)
		(width 0.2286)
		(layer "B.Cu")
		(net "PVDD11_S3_P0_VOS2")
	)
	(segment
		(start 421.244014 -353.676712)
		(end 421.244014 -353.389946)
		(width 0.2032)
		(layer "F.Cu")
		(net "PVDD11_S3_P0_VOS1")
	)
	(segment
		(start 420.919402 -354.001324)
		(end 421.244014 -353.676712)
		(width 0.2032)
		(layer "F.Cu")
		(net "PVDD11_S3_P0_VOS1")
	)
	(via
		(at 420.919402 -354.001324)
		(size 0.508)
		(drill 0.254)
		(layers "F.Cu" "B.Cu")
		(net "PVDD11_S3_P0_VOS1")
	)
	(segment
		(start 420.298118 -353.38004)
		(end 420.919402 -354.001324)
		(width 0.2286)
		(layer "B.Cu")
		(net "PVDD11_S3_P0_VOS1")
	)
	(segment
		(start 419.98265 -353.38004)
		(end 420.298118 -353.38004)
		(width 0.2286)
		(layer "B.Cu")
		(net "PVDD11_S3_P0_VOS1")
	)
	(segment
		(start 422.2877 -362.687362)
		(end 422.462706 -362.862368)
		(width 0.1524)
		(layer "F.Cu")
		(net "PVDD11_S3_P0_VMON")
	)
	(segment
		(start 422.525444 -362.79963)
		(end 423.21861 -362.79963)
		(width 0.1524)
		(layer "F.Cu")
		(net "PVDD11_S3_P0_VMON")
	)
	(segment
		(start 422.462706 -362.862368)
		(end 422.525444 -362.79963)
		(width 0.1524)
		(layer "F.Cu")
		(net "PVDD11_S3_P0_VMON")
	)
	(segment
		(start 421.317928 -362.687362)
		(end 422.2877 -362.687362)
		(width 0.1524)
		(layer "F.Cu")
		(net "PVDD11_S3_P0_VMON")
	)
	(via
		(at 422.462706 -362.862368)
		(size 0.508)
		(drill 0.254)
		(layers "F.Cu" "B.Cu")
		(net "PVDD11_S3_P0_VMON")
	)
	(via
		(at 423.41419 -363.131354)
		(size 0.6604)
		(drill 0.3302)
		(layers "F.Cu" "B.Cu")
		(net "PVDD11_S3_P0_VMON")
	)
	(segment
		(start 423.41419 -363.131354)
		(end 424.119294 -363.131354)
		(width 0.254)
		(layer "B.Cu")
		(net "PVDD11_S3_P0_VMON")
	)
	(segment
		(start 422.044368 -362.44403)
		(end 422.462706 -362.862368)
		(width 0.254)
		(layer "B.Cu")
		(net "PVDD11_S3_P0_VMON")
	)
	(segment
		(start 421.886126 -362.44403)
		(end 422.044368 -362.44403)
		(width 0.254)
		(layer "B.Cu")
		(net "PVDD11_S3_P0_VMON")
	)
	(segment
		(start 424.246548 -363.0041)
		(end 424.246548 -362.378244)
		(width 0.254)
		(layer "B.Cu")
		(net "PVDD11_S3_P0_VMON")
	)
	(segment
		(start 422.731692 -363.131354)
		(end 423.41419 -363.131354)
		(width 0.254)
		(layer "B.Cu")
		(net "PVDD11_S3_P0_VMON")
	)
	(segment
		(start 422.462706 -362.862368)
		(end 422.731692 -363.131354)
		(width 0.254)
		(layer "B.Cu")
		(net "PVDD11_S3_P0_VMON")
	)
	(segment
		(start 424.119294 -363.131354)
		(end 424.246548 -363.0041)
		(width 0.254)
		(layer "B.Cu")
		(net "PVDD11_S3_P0_VMON")
	)
	(segment
		(start 426.974 -365.74095)
		(end 426.974 -364.89005)
		(width 0.254)
		(layer "F.Cu")
		(net "PVDD11_S3_P0_VINSEN")
	)
	(segment
		(start 422.623742 -363.78261)
		(end 421.928544 -363.087412)
		(width 0.1524)
		(layer "F.Cu")
		(net "PVDD11_S3_P0_VINSEN")
	)
	(segment
		(start 423.209974 -364.380526)
		(end 423.209974 -363.78261)
		(width 0.254)
		(layer "F.Cu")
		(net "PVDD11_S3_P0_VINSEN")
	)
	(segment
		(start 424.454066 -364.507526)
		(end 423.336974 -364.507526)
		(width 0.254)
		(layer "F.Cu")
		(net "PVDD11_S3_P0_VINSEN")
	)
	(segment
		(start 421.928544 -363.087412)
		(end 421.317928 -363.087412)
		(width 0.1524)
		(layer "F.Cu")
		(net "PVDD11_S3_P0_VINSEN")
	)
	(segment
		(start 425.447714 -364.89005)
		(end 425.06519 -364.507526)
		(width 0.254)
		(layer "F.Cu")
		(net "PVDD11_S3_P0_VINSEN")
	)
	(segment
		(start 426.974 -364.89005)
		(end 425.447714 -364.89005)
		(width 0.254)
		(layer "F.Cu")
		(net "PVDD11_S3_P0_VINSEN")
	)
	(segment
		(start 423.336974 -364.507526)
		(end 423.209974 -364.380526)
		(width 0.254)
		(layer "F.Cu")
		(net "PVDD11_S3_P0_VINSEN")
	)
	(segment
		(start 423.209974 -363.78261)
		(end 422.623742 -363.78261)
		(width 0.1524)
		(layer "F.Cu")
		(net "PVDD11_S3_P0_VINSEN")
	)
	(segment
		(start 425.06519 -364.507526)
		(end 424.454066 -364.507526)
		(width 0.254)
		(layer "F.Cu")
		(net "PVDD11_S3_P0_VINSEN")
	)
	(via
		(at 424.454066 -364.507526)
		(size 0.508)
		(drill 0.254)
		(layers "F.Cu" "B.Cu")
		(net "PVDD11_S3_P0_VINSEN")
	)
	(segment
		(start 415.8234 -360.366056)
		(end 415.8234 -361.90428)
		(width 0.1524)
		(layer "F.Cu")
		(net "PVDD11_S3_P0_VDDIO")
	)
	(segment
		(start 414.737296 -360.7943)
		(end 414.737296 -359.91038)
		(width 0.1524)
		(layer "F.Cu")
		(net "PVDD11_S3_P0_VDDIO")
	)
	(segment
		(start 415.8234 -361.90428)
		(end 416.206432 -362.287312)
		(width 0.1524)
		(layer "F.Cu")
		(net "PVDD11_S3_P0_VDDIO")
	)
	(segment
		(start 414.737296 -359.91038)
		(end 415.05251 -359.595166)
		(width 0.1524)
		(layer "F.Cu")
		(net "PVDD11_S3_P0_VDDIO")
	)
	(segment
		(start 415.05251 -359.595166)
		(end 415.8234 -360.366056)
		(width 0.1524)
		(layer "F.Cu")
		(net "PVDD11_S3_P0_VDDIO")
	)
	(segment
		(start 416.206432 -362.287312)
		(end 416.517836 -362.287312)
		(width 0.1524)
		(layer "F.Cu")
		(net "PVDD11_S3_P0_VDDIO")
	)
	(via
		(at 415.05251 -359.595166)
		(size 0.762)
		(drill 0.381)
		(layers "F.Cu" "B.Cu")
		(net "PVDD11_S3_P0_VDDIO")
	)
	(segment
		(start 429.980598 -354.23094)
		(end 429.276764 -354.934774)
		(width 0.2286)
		(layer "F.Cu")
		(net "PVDD11_S3_P0_VCCS")
	)
	(segment
		(start 429.980598 -354.040186)
		(end 429.980598 -354.23094)
		(width 0.2286)
		(layer "F.Cu")
		(net "PVDD11_S3_P0_VCCS")
	)
	(segment
		(start 420.950136 -354.909374)
		(end 420.950136 -355.572314)
		(width 0.2286)
		(layer "F.Cu")
		(net "PVDD11_S3_P0_VCCS")
	)
	(segment
		(start 421.65397 -354.20554)
		(end 420.950136 -354.909374)
		(width 0.2286)
		(layer "F.Cu")
		(net "PVDD11_S3_P0_VCCS")
	)
	(segment
		(start 429.276764 -354.934774)
		(end 429.276764 -355.597714)
		(width 0.2286)
		(layer "F.Cu")
		(net "PVDD11_S3_P0_VCCS")
	)
	(segment
		(start 429.276764 -355.597714)
		(end 430.005236 -355.597714)
		(width 0.254)
		(layer "F.Cu")
		(net "PVDD11_S3_P0_VCCS")
	)
	(segment
		(start 421.65397 -354.014786)
		(end 421.65397 -354.20554)
		(width 0.2286)
		(layer "F.Cu")
		(net "PVDD11_S3_P0_VCCS")
	)
	(segment
		(start 420.950136 -355.572314)
		(end 421.678608 -355.572314)
		(width 0.254)
		(layer "F.Cu")
		(net "PVDD11_S3_P0_VCCS")
	)
	(via
		(at 430.005236 -355.597714)
		(size 0.508)
		(drill 0.254)
		(layers "F.Cu" "B.Cu")
		(net "PVDD11_S3_P0_VCCS")
	)
	(via
		(at 421.678608 -355.572314)
		(size 0.508)
		(drill 0.254)
		(layers "F.Cu" "B.Cu")
		(net "PVDD11_S3_P0_VCCS")
	)
	(via
		(at 421.154606 -365.110776)
		(size 0.508)
		(drill 0.254)
		(layers "F.Cu" "B.Cu")
		(net "PVDD11_S3_P0_VCCS")
	)
	(segment
		(start 420.954454 -357.41991)
		(end 421.411654 -356.96271)
		(width 0.254)
		(layer "In4.Cu")
		(net "PVDD11_S3_P0_VCCS")
	)
	(segment
		(start 427.9519 -358.73309)
		(end 419.676834 -358.73309)
		(width 0.254)
		(layer "In4.Cu")
		(net "PVDD11_S3_P0_VCCS")
	)
	(segment
		(start 421.411654 -356.96271)
		(end 421.411654 -356.04831)
		(width 0.254)
		(layer "In4.Cu")
		(net "PVDD11_S3_P0_VCCS")
	)
	(segment
		(start 419.676834 -358.73309)
		(end 419.426898 -358.983026)
		(width 0.254)
		(layer "In4.Cu")
		(net "PVDD11_S3_P0_VCCS")
	)
	(segment
		(start 430.005236 -355.597714)
		(end 430.005236 -356.679754)
		(width 0.254)
		(layer "In4.Cu")
		(net "PVDD11_S3_P0_VCCS")
	)
	(segment
		(start 417.525454 -358.66451)
		(end 418.770054 -357.41991)
		(width 0.254)
		(layer "In4.Cu")
		(net "PVDD11_S3_P0_VCCS")
	)
	(segment
		(start 421.678608 -355.781356)
		(end 421.678608 -355.572314)
		(width 0.254)
		(layer "In4.Cu")
		(net "PVDD11_S3_P0_VCCS")
	)
	(segment
		(start 430.005236 -356.679754)
		(end 427.9519 -358.73309)
		(width 0.254)
		(layer "In4.Cu")
		(net "PVDD11_S3_P0_VCCS")
	)
	(segment
		(start 421.411654 -356.04831)
		(end 421.678608 -355.781356)
		(width 0.254)
		(layer "In4.Cu")
		(net "PVDD11_S3_P0_VCCS")
	)
	(segment
		(start 418.770054 -357.41991)
		(end 420.954454 -357.41991)
		(width 0.254)
		(layer "In4.Cu")
		(net "PVDD11_S3_P0_VCCS")
	)
	(segment
		(start 428.287688 -352.795078)
		(end 428.287688 -353.40544)
		(width 0.3556)
		(layer "F.Cu")
		(net "PVDD11_S3_P0_VCC2")
	)
	(segment
		(start 431.780696 -354.040186)
		(end 431.780696 -354.752148)
		(width 0.2286)
		(layer "F.Cu")
		(net "PVDD11_S3_P0_VCC2")
	)
	(segment
		(start 428.919894 -352.51517)
		(end 428.639986 -352.795078)
		(width 0.2286)
		(layer "F.Cu")
		(net "PVDD11_S3_P0_VCC2")
	)
	(segment
		(start 431.780696 -354.752148)
		(end 431.705004 -354.82784)
		(width 0.2286)
		(layer "F.Cu")
		(net "PVDD11_S3_P0_VCC2")
	)
	(segment
		(start 428.639986 -352.795078)
		(end 428.287688 -352.795078)
		(width 0.2286)
		(layer "F.Cu")
		(net "PVDD11_S3_P0_VCC2")
	)
	(segment
		(start 429.570642 -352.51517)
		(end 428.919894 -352.51517)
		(width 0.2286)
		(layer "F.Cu")
		(net "PVDD11_S3_P0_VCC2")
	)
	(via
		(at 430.115218 -354.01504)
		(size 0.6604)
		(drill 0.3302)
		(layers "F.Cu" "B.Cu")
		(net "PVDD11_S3_P0_VCC2")
	)
	(via
		(at 431.705004 -354.82784)
		(size 0.508)
		(drill 0.254)
		(layers "F.Cu" "B.Cu")
		(net "PVDD11_S3_P0_VCC2")
	)
	(via
		(at 428.287688 -352.795078)
		(size 0.508)
		(drill 0.254)
		(layers "F.Cu" "B.Cu")
		(net "PVDD11_S3_P0_VCC2")
	)
	(segment
		(start 429.150018 -352.599498)
		(end 429.659796 -352.599498)
		(width 0.381)
		(layer "B.Cu")
		(net "PVDD11_S3_P0_VCC2")
	)
	(segment
		(start 431.20564 -354.328476)
		(end 431.705004 -354.82784)
		(width 0.4572)
		(layer "B.Cu")
		(net "PVDD11_S3_P0_VCC2")
	)
	(segment
		(start 429.84674 -353.746562)
		(end 430.115218 -354.01504)
		(width 0.381)
		(layer "B.Cu")
		(net "PVDD11_S3_P0_VCC2")
	)
	(segment
		(start 430.115218 -354.01504)
		(end 430.428654 -354.328476)
		(width 0.4572)
		(layer "B.Cu")
		(net "PVDD11_S3_P0_VCC2")
	)
	(segment
		(start 429.659796 -353.295204)
		(end 429.84674 -353.746562)
		(width 0.381)
		(layer "B.Cu")
		(net "PVDD11_S3_P0_VCC2")
	)
	(segment
		(start 429.659796 -352.599498)
		(end 429.659796 -353.295204)
		(width 0.381)
		(layer "B.Cu")
		(net "PVDD11_S3_P0_VCC2")
	)
	(segment
		(start 428.954438 -352.795078)
		(end 429.150018 -352.599498)
		(width 0.381)
		(layer "B.Cu")
		(net "PVDD11_S3_P0_VCC2")
	)
	(segment
		(start 430.428654 -354.328476)
		(end 431.20564 -354.328476)
		(width 0.4572)
		(layer "B.Cu")
		(net "PVDD11_S3_P0_VCC2")
	)
	(segment
		(start 428.287688 -352.795078)
		(end 428.954438 -352.795078)
		(width 0.381)
		(layer "B.Cu")
		(net "PVDD11_S3_P0_VCC2")
	)
	(segment
		(start 420.313358 -352.769678)
		(end 420.598092 -352.484944)
		(width 0.2286)
		(layer "F.Cu")
		(net "PVDD11_S3_P0_VCC1")
	)
	(segment
		(start 419.96106 -353.38004)
		(end 419.96106 -352.769678)
		(width 0.3556)
		(layer "F.Cu")
		(net "PVDD11_S3_P0_VCC1")
	)
	(segment
		(start 420.602918 -352.48977)
		(end 421.244014 -352.48977)
		(width 0.2286)
		(layer "F.Cu")
		(net "PVDD11_S3_P0_VCC1")
	)
	(segment
		(start 420.598092 -352.484944)
		(end 420.602918 -352.48977)
		(width 0.2286)
		(layer "F.Cu")
		(net "PVDD11_S3_P0_VCC1")
	)
	(segment
		(start 419.96106 -352.769678)
		(end 420.313358 -352.769678)
		(width 0.2286)
		(layer "F.Cu")
		(net "PVDD11_S3_P0_VCC1")
	)
	(segment
		(start 423.454068 -354.014786)
		(end 423.454068 -354.726748)
		(width 0.2286)
		(layer "F.Cu")
		(net "PVDD11_S3_P0_VCC1")
	)
	(segment
		(start 423.454068 -354.726748)
		(end 423.378376 -354.80244)
		(width 0.2286)
		(layer "F.Cu")
		(net "PVDD11_S3_P0_VCC1")
	)
	(via
		(at 423.378376 -354.80244)
		(size 0.508)
		(drill 0.254)
		(layers "F.Cu" "B.Cu")
		(net "PVDD11_S3_P0_VCC1")
	)
	(via
		(at 419.96106 -352.769678)
		(size 0.508)
		(drill 0.254)
		(layers "F.Cu" "B.Cu")
		(net "PVDD11_S3_P0_VCC1")
	)
	(via
		(at 421.78859 -353.98964)
		(size 0.6604)
		(drill 0.3302)
		(layers "F.Cu" "B.Cu")
		(net "PVDD11_S3_P0_VCC1")
	)
	(segment
		(start 419.96106 -352.769678)
		(end 420.62781 -352.769678)
		(width 0.381)
		(layer "B.Cu")
		(net "PVDD11_S3_P0_VCC1")
	)
	(segment
		(start 422.879012 -354.303076)
		(end 422.102026 -354.303076)
		(width 0.4572)
		(layer "B.Cu")
		(net "PVDD11_S3_P0_VCC1")
	)
	(segment
		(start 420.82339 -352.574098)
		(end 421.333168 -352.574098)
		(width 0.381)
		(layer "B.Cu")
		(net "PVDD11_S3_P0_VCC1")
	)
	(segment
		(start 421.78859 -353.945444)
		(end 421.333168 -353.490022)
		(width 0.381)
		(layer "B.Cu")
		(net "PVDD11_S3_P0_VCC1")
	)
	(segment
		(start 420.62781 -352.769678)
		(end 420.82339 -352.574098)
		(width 0.381)
		(layer "B.Cu")
		(net "PVDD11_S3_P0_VCC1")
	)
	(segment
		(start 423.378376 -354.80244)
		(end 422.879012 -354.303076)
		(width 0.4572)
		(layer "B.Cu")
		(net "PVDD11_S3_P0_VCC1")
	)
	(segment
		(start 421.333168 -353.490022)
		(end 421.333168 -352.574098)
		(width 0.381)
		(layer "B.Cu")
		(net "PVDD11_S3_P0_VCC1")
	)
	(segment
		(start 421.78859 -353.98964)
		(end 421.78859 -353.945444)
		(width 0.381)
		(layer "B.Cu")
		(net "PVDD11_S3_P0_VCC1")
	)
	(segment
		(start 422.102026 -354.303076)
		(end 421.78859 -353.98964)
		(width 0.4572)
		(layer "B.Cu")
		(net "PVDD11_S3_P0_VCC1")
	)
	(segment
		(start 424.818556 -365.397796)
		(end 425.35856 -365.9378)
		(width 0.254)
		(layer "F.Cu")
		(net "PVDD11_S3_P0_VCC")
	)
	(segment
		(start 424.217338 -365.397796)
		(end 424.818556 -365.397796)
		(width 0.254)
		(layer "F.Cu")
		(net "PVDD11_S3_P0_VCC")
	)
	(segment
		(start 425.35856 -365.9378)
		(end 425.35856 -367.192306)
		(width 0.254)
		(layer "F.Cu")
		(net "PVDD11_S3_P0_VCC")
	)
	(via
		(at 425.35856 -367.192306)
		(size 0.762)
		(drill 0.381)
		(layers "F.Cu" "B.Cu")
		(net "PVDD11_S3_P0_VCC")
	)
	(segment
		(start 422.185084 -361.741212)
		(end 422.271698 -361.741212)
		(width 0.1524)
		(layer "F.Cu")
		(net "PVDD11_S3_P0_TEMP1")
	)
	(segment
		(start 421.317928 -361.887516)
		(end 422.03878 -361.887516)
		(width 0.1524)
		(layer "F.Cu")
		(net "PVDD11_S3_P0_TEMP1")
	)
	(segment
		(start 422.03878 -361.887516)
		(end 422.185084 -361.741212)
		(width 0.1524)
		(layer "F.Cu")
		(net "PVDD11_S3_P0_TEMP1")
	)
	(via
		(at 421.21963 -361.473496)
		(size 0.6604)
		(drill 0.3302)
		(layers "F.Cu" "B.Cu")
		(net "PVDD11_S3_P0_TEMP1")
	)
	(via
		(at 422.271698 -361.741212)
		(size 0.508)
		(drill 0.254)
		(layers "F.Cu" "B.Cu")
		(net "PVDD11_S3_P0_TEMP1")
	)
	(segment
		(start 421.21963 -361.473496)
		(end 420.96563 -361.219496)
		(width 0.1524)
		(layer "B.Cu")
		(net "PVDD11_S3_P0_TEMP1")
	)
	(segment
		(start 421.404288 -361.473496)
		(end 421.21963 -361.473496)
		(width 0.1524)
		(layer "B.Cu")
		(net "PVDD11_S3_P0_TEMP1")
	)
	(segment
		(start 422.271698 -361.741212)
		(end 421.672004 -361.741212)
		(width 0.1524)
		(layer "B.Cu")
		(net "PVDD11_S3_P0_TEMP1")
	)
	(segment
		(start 420.91483 -360.272076)
		(end 420.91483 -359.736136)
		(width 0.1524)
		(layer "B.Cu")
		(net "PVDD11_S3_P0_TEMP1")
	)
	(segment
		(start 420.96563 -361.219496)
		(end 420.96563 -360.322876)
		(width 0.1524)
		(layer "B.Cu")
		(net "PVDD11_S3_P0_TEMP1")
	)
	(segment
		(start 420.96563 -360.322876)
		(end 420.91483 -360.272076)
		(width 0.1524)
		(layer "B.Cu")
		(net "PVDD11_S3_P0_TEMP1")
	)
	(segment
		(start 421.672004 -361.741212)
		(end 421.404288 -361.473496)
		(width 0.1524)
		(layer "B.Cu")
		(net "PVDD11_S3_P0_TEMP1")
	)
	(segment
		(start 422.682924 -354.777294)
		(end 422.92143 -354.538788)
		(width 0.2286)
		(layer "F.Cu")
		(net "PVDD11_S3_P0_TEMP0")
	)
	(segment
		(start 422.682924 -355.048312)
		(end 422.682924 -354.777294)
		(width 0.2286)
		(layer "F.Cu")
		(net "PVDD11_S3_P0_TEMP0")
	)
	(segment
		(start 422.92143 -354.538788)
		(end 423.00398 -354.339652)
		(width 0.2286)
		(layer "F.Cu")
		(net "PVDD11_S3_P0_TEMP0")
	)
	(segment
		(start 431.009552 -354.802694)
		(end 431.260504 -354.551742)
		(width 0.2286)
		(layer "F.Cu")
		(net "PVDD11_S3_P0_TEMP0")
	)
	(segment
		(start 422.746678 -362.274612)
		(end 422.872154 -362.149136)
		(width 0.254)
		(layer "F.Cu")
		(net "PVDD11_S3_P0_TEMP0")
	)
	(segment
		(start 431.260504 -354.551742)
		(end 431.330608 -354.382578)
		(width 0.2286)
		(layer "F.Cu")
		(net "PVDD11_S3_P0_TEMP0")
	)
	(segment
		(start 422.703498 -362.287312)
		(end 422.716198 -362.274612)
		(width 0.1524)
		(layer "F.Cu")
		(net "PVDD11_S3_P0_TEMP0")
	)
	(segment
		(start 423.00398 -354.339652)
		(end 423.00398 -354.014786)
		(width 0.2286)
		(layer "F.Cu")
		(net "PVDD11_S3_P0_TEMP0")
	)
	(segment
		(start 431.330608 -354.382578)
		(end 431.330608 -354.040186)
		(width 0.2286)
		(layer "F.Cu")
		(net "PVDD11_S3_P0_TEMP0")
	)
	(segment
		(start 422.896792 -362.149136)
		(end 423.227246 -361.818682)
		(width 0.254)
		(layer "F.Cu")
		(net "PVDD11_S3_P0_TEMP0")
	)
	(segment
		(start 422.872154 -362.149136)
		(end 422.896792 -362.149136)
		(width 0.254)
		(layer "F.Cu")
		(net "PVDD11_S3_P0_TEMP0")
	)
	(segment
		(start 421.317928 -362.287312)
		(end 422.703498 -362.287312)
		(width 0.1524)
		(layer "F.Cu")
		(net "PVDD11_S3_P0_TEMP0")
	)
	(segment
		(start 422.716198 -362.274612)
		(end 422.746678 -362.274612)
		(width 0.254)
		(layer "F.Cu")
		(net "PVDD11_S3_P0_TEMP0")
	)
	(segment
		(start 431.009552 -355.073712)
		(end 431.009552 -354.802694)
		(width 0.2286)
		(layer "F.Cu")
		(net "PVDD11_S3_P0_TEMP0")
	)
	(via
		(at 431.009552 -355.073712)
		(size 0.508)
		(drill 0.254)
		(layers "F.Cu" "B.Cu")
		(net "PVDD11_S3_P0_TEMP0")
	)
	(via
		(at 422.682924 -355.048312)
		(size 0.508)
		(drill 0.254)
		(layers "F.Cu" "B.Cu")
		(net "PVDD11_S3_P0_TEMP0")
	)
	(via
		(at 422.716198 -362.274612)
		(size 0.508)
		(drill 0.254)
		(layers "F.Cu" "B.Cu")
		(net "PVDD11_S3_P0_TEMP0")
	)
	(segment
		(start 430.936654 -355.14661)
		(end 430.936654 -356.53091)
		(width 0.254)
		(layer "In2.Cu")
		(net "PVDD11_S3_P0_TEMP0")
	)
	(segment
		(start 430.936654 -356.53091)
		(end 429.246792 -358.220772)
		(width 0.254)
		(layer "In2.Cu")
		(net "PVDD11_S3_P0_TEMP0")
	)
	(segment
		(start 431.009552 -355.073712)
		(end 430.936654 -355.14661)
		(width 0.254)
		(layer "In2.Cu")
		(net "PVDD11_S3_P0_TEMP0")
	)
	(segment
		(start 421.179752 -359.310432)
		(end 422.682924 -357.80726)
		(width 0.254)
		(layer "In2.Cu")
		(net "PVDD11_S3_P0_TEMP0")
	)
	(segment
		(start 422.716198 -362.274612)
		(end 422.032684 -362.274612)
		(width 0.254)
		(layer "In2.Cu")
		(net "PVDD11_S3_P0_TEMP0")
	)
	(segment
		(start 422.682924 -357.80726)
		(end 422.682924 -355.048312)
		(width 0.254)
		(layer "In2.Cu")
		(net "PVDD11_S3_P0_TEMP0")
	)
	(segment
		(start 429.246792 -358.220772)
		(end 423.096436 -358.220772)
		(width 0.254)
		(layer "In2.Cu")
		(net "PVDD11_S3_P0_TEMP0")
	)
	(segment
		(start 422.032684 -362.274612)
		(end 421.179752 -361.42168)
		(width 0.254)
		(layer "In2.Cu")
		(net "PVDD11_S3_P0_TEMP0")
	)
	(segment
		(start 423.096436 -358.220772)
		(end 422.682924 -357.80726)
		(width 0.254)
		(layer "In2.Cu")
		(net "PVDD11_S3_P0_TEMP0")
	)
	(segment
		(start 421.179752 -361.42168)
		(end 421.179752 -359.310432)
		(width 0.254)
		(layer "In2.Cu")
		(net "PVDD11_S3_P0_TEMP0")
	)
	(segment
		(start 415.361374 -361.3023)
		(end 415.361374 -362.07319)
		(width 0.10668)
		(layer "F.Cu")
		(net "PVDD11_S3_P0_RESET_N_R")
	)
	(segment
		(start 415.975546 -362.687362)
		(end 416.517836 -362.687362)
		(width 0.10668)
		(layer "F.Cu")
		(net "PVDD11_S3_P0_RESET_N_R")
	)
	(segment
		(start 415.237676 -361.3023)
		(end 415.361374 -361.3023)
		(width 0.10668)
		(layer "F.Cu")
		(net "PVDD11_S3_P0_RESET_N_R")
	)
	(segment
		(start 414.725612 -362.804964)
		(end 414.725612 -361.814364)
		(width 0.10668)
		(layer "F.Cu")
		(net "PVDD11_S3_P0_RESET_N_R")
	)
	(segment
		(start 415.361374 -362.07319)
		(end 415.975546 -362.687362)
		(width 0.10668)
		(layer "F.Cu")
		(net "PVDD11_S3_P0_RESET_N_R")
	)
	(segment
		(start 414.725612 -361.814364)
		(end 415.237676 -361.3023)
		(width 0.10668)
		(layer "F.Cu")
		(net "PVDD11_S3_P0_RESET_N_R")
	)
	(via
		(at 415.361374 -361.3023)
		(size 0.508)
		(drill 0.254)
		(layers "F.Cu" "B.Cu")
		(net "PVDD11_S3_P0_RESET_N_R")
	)
	(segment
		(start 415.086038 -361.026964)
		(end 415.361374 -361.3023)
		(width 0.10668)
		(layer "B.Cu")
		(net "PVDD11_S3_P0_RESET_N_R")
	)
	(segment
		(start 413.975804 -361.026964)
		(end 415.086038 -361.026964)
		(width 0.10668)
		(layer "B.Cu")
		(net "PVDD11_S3_P0_RESET_N_R")
	)
	(segment
		(start 296.30497 -376.917204)
		(end 298.36872 -374.853454)
		(width 0.10668)
		(layer "F.Cu")
		(net "PVDD11_S3_P0_RESET_N")
	)
	(segment
		(start 209.505296 -200.97623)
		(end 209.037428 -200.97623)
		(width 0.10668)
		(layer "F.Cu")
		(net "PVDD11_S3_P0_RESET_N")
	)
	(segment
		(start 413.67456 -361.404408)
		(end 413.925512 -361.65536)
		(width 0.10668)
		(layer "F.Cu")
		(net "PVDD11_S3_P0_RESET_N")
	)
	(segment
		(start 182.722012 -119.452898)
		(end 182.332122 -119.842788)
		(width 0.10668)
		(layer "F.Cu")
		(net "PVDD11_S3_P0_RESET_N")
	)
	(segment
		(start 349.308928 -374.853454)
		(end 362.757974 -361.404408)
		(width 0.10668)
		(layer "F.Cu")
		(net "PVDD11_S3_P0_RESET_N")
	)
	(segment
		(start 196.465444 -169.139108)
		(end 210.429348 -183.103012)
		(width 0.10668)
		(layer "F.Cu")
		(net "PVDD11_S3_P0_RESET_N")
	)
	(segment
		(start 212.701886 -197.77964)
		(end 209.505296 -200.97623)
		(width 0.10668)
		(layer "F.Cu")
		(net "PVDD11_S3_P0_RESET_N")
	)
	(segment
		(start 193.179446 -169.139108)
		(end 196.465444 -169.139108)
		(width 0.10668)
		(layer "F.Cu")
		(net "PVDD11_S3_P0_RESET_N")
	)
	(segment
		(start 212.701886 -188.589412)
		(end 212.701886 -197.77964)
		(width 0.10668)
		(layer "F.Cu")
		(net "PVDD11_S3_P0_RESET_N")
	)
	(segment
		(start 190.515748 -166.47541)
		(end 193.179446 -169.139108)
		(width 0.10668)
		(layer "F.Cu")
		(net "PVDD11_S3_P0_RESET_N")
	)
	(segment
		(start 210.429348 -183.103012)
		(end 212.701886 -188.589412)
		(width 0.10668)
		(layer "F.Cu")
		(net "PVDD11_S3_P0_RESET_N")
	)
	(segment
		(start 298.36872 -374.853454)
		(end 349.308928 -374.853454)
		(width 0.10668)
		(layer "F.Cu")
		(net "PVDD11_S3_P0_RESET_N")
	)
	(segment
		(start 362.757974 -361.404408)
		(end 413.67456 -361.404408)
		(width 0.10668)
		(layer "F.Cu")
		(net "PVDD11_S3_P0_RESET_N")
	)
	(segment
		(start 288.082482 -376.917204)
		(end 296.30497 -376.917204)
		(width 0.10668)
		(layer "F.Cu")
		(net "PVDD11_S3_P0_RESET_N")
	)
	(segment
		(start 413.925512 -361.65536)
		(end 413.925512 -361.814364)
		(width 0.10668)
		(layer "F.Cu")
		(net "PVDD11_S3_P0_RESET_N")
	)
	(via
		(at 190.515748 -166.47541)
		(size 0.508)
		(drill 0.254)
		(layers "F.Cu" "B.Cu")
		(net "PVDD11_S3_P0_RESET_N")
	)
	(via
		(at 182.332122 -119.842788)
		(size 0.4572)
		(drill 0.254)
		(layers "F.Cu" "B.Cu")
		(net "PVDD11_S3_P0_RESET_N")
	)
	(via
		(at 288.082482 -376.917204)
		(size 0.508)
		(drill 0.254)
		(layers "F.Cu" "B.Cu")
		(net "PVDD11_S3_P0_RESET_N")
	)
	(via
		(at 209.037428 -200.97623)
		(size 0.508)
		(drill 0.254)
		(layers "F.Cu" "B.Cu")
		(net "PVDD11_S3_P0_RESET_N")
	)
	(segment
		(start 182.374794 -133.859016)
		(end 181.290468 -132.77469)
		(width 0.11684)
		(layer "In4.Cu")
		(net "PVDD11_S3_P0_RESET_N")
	)
	(segment
		(start 181.290468 -132.77469)
		(end 181.290468 -131.188968)
		(width 0.11684)
		(layer "In4.Cu")
		(net "PVDD11_S3_P0_RESET_N")
	)
	(segment
		(start 243.040916 -203.678282)
		(end 250.850654 -211.48802)
		(width 0.11684)
		(layer "In4.Cu")
		(net "PVDD11_S3_P0_RESET_N")
	)
	(segment
		(start 259.969 -330.2)
		(end 259.969 -352.632772)
		(width 0.11684)
		(layer "In4.Cu")
		(net "PVDD11_S3_P0_RESET_N")
	)
	(segment
		(start 180.478938 -162.456114)
		(end 180.478938 -159.315912)
		(width 0.11684)
		(layer "In4.Cu")
		(net "PVDD11_S3_P0_RESET_N")
	)
	(segment
		(start 287.5407 -376.375422)
		(end 288.082482 -376.917204)
		(width 0.11684)
		(layer "In4.Cu")
		(net "PVDD11_S3_P0_RESET_N")
	)
	(segment
		(start 209.037428 -200.97623)
		(end 211.6836 -198.330058)
		(width 0.11684)
		(layer "In4.Cu")
		(net "PVDD11_S3_P0_RESET_N")
	)
	(segment
		(start 257.596386 -327.173844)
		(end 257.596386 -327.827386)
		(width 0.11684)
		(layer "In4.Cu")
		(net "PVDD11_S3_P0_RESET_N")
	)
	(segment
		(start 185.42381 -166.602156)
		(end 184.625234 -165.80358)
		(width 0.11684)
		(layer "In4.Cu")
		(net "PVDD11_S3_P0_RESET_N")
	)
	(segment
		(start 235.127038 -203.678282)
		(end 243.040916 -203.678282)
		(width 0.11684)
		(layer "In4.Cu")
		(net "PVDD11_S3_P0_RESET_N")
	)
	(segment
		(start 180.478938 -159.315912)
		(end 180.814726 -158.980124)
		(width 0.11684)
		(layer "In4.Cu")
		(net "PVDD11_S3_P0_RESET_N")
	)
	(segment
		(start 259.975096 -324.795134)
		(end 257.596386 -327.173844)
		(width 0.11684)
		(layer "In4.Cu")
		(net "PVDD11_S3_P0_RESET_N")
	)
	(segment
		(start 190.515748 -166.47541)
		(end 190.389002 -166.602156)
		(width 0.11684)
		(layer "In4.Cu")
		(net "PVDD11_S3_P0_RESET_N")
	)
	(segment
		(start 181.493414 -129.107184)
		(end 181.927246 -128.673352)
		(width 0.11684)
		(layer "In4.Cu")
		(net "PVDD11_S3_P0_RESET_N")
	)
	(segment
		(start 181.290468 -131.188968)
		(end 181.493414 -130.986022)
		(width 0.11684)
		(layer "In4.Cu")
		(net "PVDD11_S3_P0_RESET_N")
	)
	(segment
		(start 259.975096 -257.049524)
		(end 259.975096 -324.795134)
		(width 0.11684)
		(layer "In4.Cu")
		(net "PVDD11_S3_P0_RESET_N")
	)
	(segment
		(start 182.374794 -150.812754)
		(end 182.374794 -133.859016)
		(width 0.11684)
		(layer "In4.Cu")
		(net "PVDD11_S3_P0_RESET_N")
	)
	(segment
		(start 184.625234 -165.80358)
		(end 183.826404 -165.80358)
		(width 0.11684)
		(layer "In4.Cu")
		(net "PVDD11_S3_P0_RESET_N")
	)
	(segment
		(start 250.850654 -211.48802)
		(end 250.850654 -247.925082)
		(width 0.11684)
		(layer "In4.Cu")
		(net "PVDD11_S3_P0_RESET_N")
	)
	(segment
		(start 270.926306 -364.612428)
		(end 271.456912 -365.143034)
		(width 0.11684)
		(layer "In4.Cu")
		(net "PVDD11_S3_P0_RESET_N")
	)
	(segment
		(start 257.596386 -327.827386)
		(end 259.969 -330.2)
		(width 0.11684)
		(layer "In4.Cu")
		(net "PVDD11_S3_P0_RESET_N")
	)
	(segment
		(start 190.389002 -166.602156)
		(end 185.42381 -166.602156)
		(width 0.11684)
		(layer "In4.Cu")
		(net "PVDD11_S3_P0_RESET_N")
	)
	(segment
		(start 250.850654 -247.925082)
		(end 259.975096 -257.049524)
		(width 0.11684)
		(layer "In4.Cu")
		(net "PVDD11_S3_P0_RESET_N")
	)
	(segment
		(start 181.927246 -128.673352)
		(end 181.927246 -120.18137)
		(width 0.11684)
		(layer "In4.Cu")
		(net "PVDD11_S3_P0_RESET_N")
	)
	(segment
		(start 270.926306 -363.590078)
		(end 270.926306 -364.612428)
		(width 0.11684)
		(layer "In4.Cu")
		(net "PVDD11_S3_P0_RESET_N")
	)
	(segment
		(start 273.54276 -365.143034)
		(end 277.175468 -368.775742)
		(width 0.11684)
		(layer "In4.Cu")
		(net "PVDD11_S3_P0_RESET_N")
	)
	(segment
		(start 287.5407 -371.68455)
		(end 287.5407 -376.375422)
		(width 0.11684)
		(layer "In4.Cu")
		(net "PVDD11_S3_P0_RESET_N")
	)
	(segment
		(start 259.969 -352.632772)
		(end 270.926306 -363.590078)
		(width 0.11684)
		(layer "In4.Cu")
		(net "PVDD11_S3_P0_RESET_N")
	)
	(segment
		(start 284.631892 -368.775742)
		(end 287.5407 -371.68455)
		(width 0.11684)
		(layer "In4.Cu")
		(net "PVDD11_S3_P0_RESET_N")
	)
	(segment
		(start 222.214694 -198.330058)
		(end 235.127038 -203.678282)
		(width 0.11684)
		(layer "In4.Cu")
		(net "PVDD11_S3_P0_RESET_N")
	)
	(segment
		(start 181.927246 -120.18137)
		(end 182.265828 -119.842788)
		(width 0.11684)
		(layer "In4.Cu")
		(net "PVDD11_S3_P0_RESET_N")
	)
	(segment
		(start 211.6836 -198.330058)
		(end 222.214694 -198.330058)
		(width 0.11684)
		(layer "In4.Cu")
		(net "PVDD11_S3_P0_RESET_N")
	)
	(segment
		(start 183.826404 -165.80358)
		(end 180.478938 -162.456114)
		(width 0.11684)
		(layer "In4.Cu")
		(net "PVDD11_S3_P0_RESET_N")
	)
	(segment
		(start 271.456912 -365.143034)
		(end 273.54276 -365.143034)
		(width 0.11684)
		(layer "In4.Cu")
		(net "PVDD11_S3_P0_RESET_N")
	)
	(segment
		(start 182.265828 -119.842788)
		(end 182.332122 -119.842788)
		(width 0.11684)
		(layer "In4.Cu")
		(net "PVDD11_S3_P0_RESET_N")
	)
	(segment
		(start 180.814726 -158.980124)
		(end 180.814726 -152.372822)
		(width 0.11684)
		(layer "In4.Cu")
		(net "PVDD11_S3_P0_RESET_N")
	)
	(segment
		(start 180.814726 -152.372822)
		(end 182.374794 -150.812754)
		(width 0.11684)
		(layer "In4.Cu")
		(net "PVDD11_S3_P0_RESET_N")
	)
	(segment
		(start 181.493414 -130.986022)
		(end 181.493414 -129.107184)
		(width 0.11684)
		(layer "In4.Cu")
		(net "PVDD11_S3_P0_RESET_N")
	)
	(segment
		(start 277.175468 -368.775742)
		(end 284.631892 -368.775742)
		(width 0.11684)
		(layer "In4.Cu")
		(net "PVDD11_S3_P0_RESET_N")
	)
	(segment
		(start 432.230784 -355.144832)
		(end 431.895504 -355.480112)
		(width 0.1778)
		(layer "F.Cu")
		(net "PVDD11_S3_P0_PWM2")
	)
	(segment
		(start 432.230784 -354.040186)
		(end 432.230784 -355.144832)
		(width 0.1778)
		(layer "F.Cu")
		(net "PVDD11_S3_P0_PWM2")
	)
	(segment
		(start 418.317934 -364.652814)
		(end 418.317934 -364.48746)
		(width 0.1524)
		(layer "F.Cu")
		(net "PVDD11_S3_P0_PWM2")
	)
	(segment
		(start 418.402516 -364.856776)
		(end 418.317934 -364.652814)
		(width 0.1524)
		(layer "F.Cu")
		(net "PVDD11_S3_P0_PWM2")
	)
	(segment
		(start 419.2016 -365.20628)
		(end 418.75202 -365.20628)
		(width 0.1524)
		(layer "F.Cu")
		(net "PVDD11_S3_P0_PWM2")
	)
	(segment
		(start 418.75202 -365.20628)
		(end 418.402516 -364.856776)
		(width 0.1524)
		(layer "F.Cu")
		(net "PVDD11_S3_P0_PWM2")
	)
	(via
		(at 431.895504 -355.480112)
		(size 0.508)
		(drill 0.254)
		(layers "F.Cu" "B.Cu")
		(net "PVDD11_S3_P0_PWM2")
	)
	(via
		(at 419.2016 -365.20628)
		(size 0.508)
		(drill 0.254)
		(layers "F.Cu" "B.Cu")
		(net "PVDD11_S3_P0_PWM2")
	)
	(segment
		(start 422.713912 -358.352852)
		(end 421.335454 -359.73131)
		(width 0.1524)
		(layer "In6.Cu")
		(net "PVDD11_S3_P0_PWM2")
	)
	(segment
		(start 431.895504 -355.480112)
		(end 432.264058 -355.848666)
		(width 0.1524)
		(layer "In6.Cu")
		(net "PVDD11_S3_P0_PWM2")
	)
	(segment
		(start 421.335454 -363.71911)
		(end 419.848284 -365.20628)
		(width 0.1524)
		(layer "In6.Cu")
		(net "PVDD11_S3_P0_PWM2")
	)
	(segment
		(start 419.848284 -365.20628)
		(end 419.2016 -365.20628)
		(width 0.1524)
		(layer "In6.Cu")
		(net "PVDD11_S3_P0_PWM2")
	)
	(segment
		(start 426.852588 -357.363522)
		(end 425.863258 -358.352852)
		(width 0.1524)
		(layer "In6.Cu")
		(net "PVDD11_S3_P0_PWM2")
	)
	(segment
		(start 425.863258 -358.352852)
		(end 422.713912 -358.352852)
		(width 0.1524)
		(layer "In6.Cu")
		(net "PVDD11_S3_P0_PWM2")
	)
	(segment
		(start 421.335454 -359.73131)
		(end 421.335454 -363.71911)
		(width 0.1524)
		(layer "In6.Cu")
		(net "PVDD11_S3_P0_PWM2")
	)
	(segment
		(start 431.503582 -357.363522)
		(end 426.852588 -357.363522)
		(width 0.1524)
		(layer "In6.Cu")
		(net "PVDD11_S3_P0_PWM2")
	)
	(segment
		(start 432.264058 -356.603046)
		(end 431.503582 -357.363522)
		(width 0.1524)
		(layer "In6.Cu")
		(net "PVDD11_S3_P0_PWM2")
	)
	(segment
		(start 432.264058 -355.848666)
		(end 432.264058 -356.603046)
		(width 0.1524)
		(layer "In6.Cu")
		(net "PVDD11_S3_P0_PWM2")
	)
	(segment
		(start 417.917884 -364.48746)
		(end 417.917884 -365.078518)
		(width 0.1524)
		(layer "F.Cu")
		(net "PVDD11_S3_P0_PWM1")
	)
	(segment
		(start 417.917884 -365.078518)
		(end 418.078666 -365.2393)
		(width 0.1524)
		(layer "F.Cu")
		(net "PVDD11_S3_P0_PWM1")
	)
	(segment
		(start 423.568876 -355.454712)
		(end 423.904156 -355.119432)
		(width 0.1778)
		(layer "F.Cu")
		(net "PVDD11_S3_P0_PWM1")
	)
	(segment
		(start 423.904156 -355.119432)
		(end 423.904156 -354.014786)
		(width 0.1778)
		(layer "F.Cu")
		(net "PVDD11_S3_P0_PWM1")
	)
	(via
		(at 418.078666 -365.2393)
		(size 0.508)
		(drill 0.254)
		(layers "F.Cu" "B.Cu")
		(net "PVDD11_S3_P0_PWM1")
	)
	(via
		(at 423.568876 -355.454712)
		(size 0.508)
		(drill 0.254)
		(layers "F.Cu" "B.Cu")
		(net "PVDD11_S3_P0_PWM1")
	)
	(segment
		(start 421.294052 -357.131112)
		(end 418.75075 -359.674414)
		(width 0.1524)
		(layer "In6.Cu")
		(net "PVDD11_S3_P0_PWM1")
	)
	(segment
		(start 417.373562 -359.674414)
		(end 416.217354 -360.830622)
		(width 0.1524)
		(layer "In6.Cu")
		(net "PVDD11_S3_P0_PWM1")
	)
	(segment
		(start 423.723054 -355.454712)
		(end 424.026838 -355.758496)
		(width 0.1524)
		(layer "In6.Cu")
		(net "PVDD11_S3_P0_PWM1")
	)
	(segment
		(start 423.587164 -357.131112)
		(end 421.294052 -357.131112)
		(width 0.1524)
		(layer "In6.Cu")
		(net "PVDD11_S3_P0_PWM1")
	)
	(segment
		(start 423.568876 -355.454712)
		(end 423.723054 -355.454712)
		(width 0.1524)
		(layer "In6.Cu")
		(net "PVDD11_S3_P0_PWM1")
	)
	(segment
		(start 424.026838 -355.758496)
		(end 424.026838 -356.691438)
		(width 0.1524)
		(layer "In6.Cu")
		(net "PVDD11_S3_P0_PWM1")
	)
	(segment
		(start 424.026838 -356.691438)
		(end 423.587164 -357.131112)
		(width 0.1524)
		(layer "In6.Cu")
		(net "PVDD11_S3_P0_PWM1")
	)
	(segment
		(start 418.078666 -364.982252)
		(end 418.078666 -365.2393)
		(width 0.1524)
		(layer "In6.Cu")
		(net "PVDD11_S3_P0_PWM1")
	)
	(segment
		(start 416.217354 -363.12094)
		(end 418.078666 -364.982252)
		(width 0.1524)
		(layer "In6.Cu")
		(net "PVDD11_S3_P0_PWM1")
	)
	(segment
		(start 418.75075 -359.674414)
		(end 417.373562 -359.674414)
		(width 0.1524)
		(layer "In6.Cu")
		(net "PVDD11_S3_P0_PWM1")
	)
	(segment
		(start 416.217354 -360.830622)
		(end 416.217354 -363.12094)
		(width 0.1524)
		(layer "In6.Cu")
		(net "PVDD11_S3_P0_PWM1")
	)
	(segment
		(start 429.034956 -352.065336)
		(end 429.570642 -352.065336)
		(width 0.2286)
		(layer "F.Cu")
		(net "PVDD11_S3_P0_PVCC")
	)
	(segment
		(start 419.96106 -351.51314)
		(end 420.36746 -351.51314)
		(width 0.2286)
		(layer "F.Cu")
		(net "PVDD11_S3_P0_PVCC")
	)
	(segment
		(start 420.894256 -352.039936)
		(end 421.244014 -352.039936)
		(width 0.2286)
		(layer "F.Cu")
		(net "PVDD11_S3_P0_PVCC")
	)
	(segment
		(start 428.50816 -351.53854)
		(end 429.034956 -352.065336)
		(width 0.2286)
		(layer "F.Cu")
		(net "PVDD11_S3_P0_PVCC")
	)
	(segment
		(start 420.36746 -351.51314)
		(end 420.894256 -352.039936)
		(width 0.2286)
		(layer "F.Cu")
		(net "PVDD11_S3_P0_PVCC")
	)
	(segment
		(start 428.287688 -352.149664)
		(end 428.287688 -351.53854)
		(width 0.3556)
		(layer "F.Cu")
		(net "PVDD11_S3_P0_PVCC")
	)
	(segment
		(start 428.287688 -351.53854)
		(end 428.50816 -351.53854)
		(width 0.2286)
		(layer "F.Cu")
		(net "PVDD11_S3_P0_PVCC")
	)
	(via
		(at 418.433758 -351.893632)
		(size 0.762)
		(drill 0.381)
		(layers "F.Cu" "B.Cu")
		(net "PVDD11_S3_P0_PVCC")
	)
	(via
		(at 419.96106 -352.124264)
		(size 0.508)
		(drill 0.254)
		(layers "F.Cu" "B.Cu")
		(net "PVDD11_S3_P0_PVCC")
	)
	(via
		(at 428.287688 -352.149664)
		(size 0.508)
		(drill 0.254)
		(layers "F.Cu" "B.Cu")
		(net "PVDD11_S3_P0_PVCC")
	)
	(segment
		(start 428.309278 -352.149664)
		(end 428.287688 -352.149664)
		(width 0.381)
		(layer "B.Cu")
		(net "PVDD11_S3_P0_PVCC")
	)
	(segment
		(start 419.96106 -352.124264)
		(end 419.98265 -352.124264)
		(width 0.381)
		(layer "B.Cu")
		(net "PVDD11_S3_P0_PVCC")
	)
	(segment
		(start 428.659544 -351.799398)
		(end 428.309278 -352.149664)
		(width 0.381)
		(layer "B.Cu")
		(net "PVDD11_S3_P0_PVCC")
	)
	(segment
		(start 429.659796 -351.799398)
		(end 428.659544 -351.799398)
		(width 0.381)
		(layer "B.Cu")
		(net "PVDD11_S3_P0_PVCC")
	)
	(segment
		(start 419.98265 -352.124264)
		(end 420.332916 -351.773998)
		(width 0.381)
		(layer "B.Cu")
		(net "PVDD11_S3_P0_PVCC")
	)
	(segment
		(start 420.332916 -351.773998)
		(end 421.333168 -351.773998)
		(width 0.381)
		(layer "B.Cu")
		(net "PVDD11_S3_P0_PVCC")
	)
	(segment
		(start 420.607998 -346.52331)
		(end 420.607998 -348.257368)
		(width 0.508)
		(layer "In6.Cu")
		(net "PVDD11_S3_P0_PVCC")
	)
	(segment
		(start 420.192454 -351.502726)
		(end 419.96106 -351.73412)
		(width 0.508)
		(layer "In6.Cu")
		(net "PVDD11_S3_P0_PVCC")
	)
	(segment
		(start 420.607998 -348.257368)
		(end 420.192454 -348.672912)
		(width 0.508)
		(layer "In6.Cu")
		(net "PVDD11_S3_P0_PVCC")
	)
	(segment
		(start 428.344838 -348.822772)
		(end 428.954438 -348.213172)
		(width 0.508)
		(layer "In6.Cu")
		(net "PVDD11_S3_P0_PVCC")
	)
	(segment
		(start 428.344838 -352.092514)
		(end 428.344838 -348.822772)
		(width 0.508)
		(layer "In6.Cu")
		(net "PVDD11_S3_P0_PVCC")
	)
	(segment
		(start 421.115998 -346.01531)
		(end 420.607998 -346.52331)
		(width 0.508)
		(layer "In6.Cu")
		(net "PVDD11_S3_P0_PVCC")
	)
	(segment
		(start 428.954438 -348.213172)
		(end 428.954438 -347.039438)
		(width 0.508)
		(layer "In6.Cu")
		(net "PVDD11_S3_P0_PVCC")
	)
	(segment
		(start 428.287688 -352.149664)
		(end 428.344838 -352.092514)
		(width 0.508)
		(layer "In6.Cu")
		(net "PVDD11_S3_P0_PVCC")
	)
	(segment
		(start 420.192454 -348.672912)
		(end 420.192454 -351.502726)
		(width 0.508)
		(layer "In6.Cu")
		(net "PVDD11_S3_P0_PVCC")
	)
	(segment
		(start 419.96106 -351.73412)
		(end 419.96106 -352.124264)
		(width 0.508)
		(layer "In6.Cu")
		(net "PVDD11_S3_P0_PVCC")
	)
	(segment
		(start 428.954438 -347.039438)
		(end 427.93031 -346.01531)
		(width 0.508)
		(layer "In6.Cu")
		(net "PVDD11_S3_P0_PVCC")
	)
	(segment
		(start 427.93031 -346.01531)
		(end 421.115998 -346.01531)
		(width 0.508)
		(layer "In6.Cu")
		(net "PVDD11_S3_P0_PVCC")
	)
	(segment
		(start 418.236908 -365.883952)
		(end 418.236908 -366.159542)
		(width 0.10668)
		(layer "F.Cu")
		(net "PVDD11_S3_P0_PMSDA_R")
	)
	(segment
		(start 417.517834 -364.810548)
		(end 417.6268 -364.919514)
		(width 0.10668)
		(layer "F.Cu")
		(net "PVDD11_S3_P0_PMSDA_R")
	)
	(segment
		(start 418.236908 -366.159542)
		(end 418.219382 -366.177068)
		(width 0.10668)
		(layer "F.Cu")
		(net "PVDD11_S3_P0_PMSDA_R")
	)
	(segment
		(start 417.6268 -365.508794)
		(end 418.001958 -365.883952)
		(width 0.10668)
		(layer "F.Cu")
		(net "PVDD11_S3_P0_PMSDA_R")
	)
	(segment
		(start 417.517834 -364.48746)
		(end 417.517834 -364.810548)
		(width 0.10668)
		(layer "F.Cu")
		(net "PVDD11_S3_P0_PMSDA_R")
	)
	(segment
		(start 418.001958 -365.883952)
		(end 418.236908 -365.883952)
		(width 0.10668)
		(layer "F.Cu")
		(net "PVDD11_S3_P0_PMSDA_R")
	)
	(segment
		(start 417.6268 -364.919514)
		(end 417.6268 -365.508794)
		(width 0.10668)
		(layer "F.Cu")
		(net "PVDD11_S3_P0_PMSDA_R")
	)
	(segment
		(start 418.219382 -366.177068)
		(end 418.219382 -367.224818)
		(width 0.10668)
		(layer "F.Cu")
		(net "PVDD11_S3_P0_PMSDA_R")
	)
	(via
		(at 418.219382 -367.224818)
		(size 0.762)
		(drill 0.381)
		(layers "F.Cu" "B.Cu")
		(net "PVDD11_S3_P0_PMSDA_R")
	)
	(segment
		(start 417.117784 -364.48746)
		(end 417.117784 -364.880906)
		(width 0.10668)
		(layer "F.Cu")
		(net "PVDD11_S3_P0_PMSCL_R")
	)
	(segment
		(start 417.1696 -365.677196)
		(end 417.1696 -366.239044)
		(width 0.10668)
		(layer "F.Cu")
		(net "PVDD11_S3_P0_PMSCL_R")
	)
	(segment
		(start 417.1696 -366.239044)
		(end 417.256468 -366.325912)
		(width 0.10668)
		(layer "F.Cu")
		(net "PVDD11_S3_P0_PMSCL_R")
	)
	(segment
		(start 417.1696 -364.932722)
		(end 417.1696 -365.677196)
		(width 0.10668)
		(layer "F.Cu")
		(net "PVDD11_S3_P0_PMSCL_R")
	)
	(segment
		(start 417.117784 -364.880906)
		(end 417.1696 -364.932722)
		(width 0.10668)
		(layer "F.Cu")
		(net "PVDD11_S3_P0_PMSCL_R")
	)
	(via
		(at 417.1696 -365.677196)
		(size 0.508)
		(drill 0.254)
		(layers "F.Cu" "B.Cu")
		(net "PVDD11_S3_P0_PMSCL_R")
	)
	(segment
		(start 416.517836 -364.357412)
		(end 416.517836 -363.887512)
		(width 0.10668)
		(layer "F.Cu")
		(net "PVDD11_S3_P0_PMALERT_R")
	)
	(segment
		(start 415.586418 -365.481362)
		(end 415.586418 -365.388652)
		(width 0.10668)
		(layer "F.Cu")
		(net "PVDD11_S3_P0_PMALERT_R")
	)
	(segment
		(start 415.586418 -365.388652)
		(end 416.517836 -364.457234)
		(width 0.10668)
		(layer "F.Cu")
		(net "PVDD11_S3_P0_PMALERT_R")
	)
	(segment
		(start 416.517836 -364.457234)
		(end 416.517836 -364.357412)
		(width 0.10668)
		(layer "F.Cu")
		(net "PVDD11_S3_P0_PMALERT_R")
	)
	(via
		(at 416.517836 -364.357412)
		(size 0.508)
		(drill 0.254)
		(layers "F.Cu" "B.Cu")
		(net "PVDD11_S3_P0_PMALERT_R")
	)
	(segment
		(start 415.586418 -367.473484)
		(end 415.263838 -367.796064)
		(width 0.10668)
		(layer "F.Cu")
		(net "PVDD11_S3_P0_PMALERT")
	)
	(segment
		(start 415.586418 -366.281462)
		(end 415.586418 -367.473484)
		(width 0.10668)
		(layer "F.Cu")
		(net "PVDD11_S3_P0_PMALERT")
	)
	(segment
		(start 185.122058 -111.452914)
		(end 184.732168 -111.063024)
		(width 0.10668)
		(layer "F.Cu")
		(net "PVDD11_S3_P0_PMALERT")
	)
	(segment
		(start 415.263838 -367.796064)
		(end 414.716468 -367.796064)
		(width 0.10668)
		(layer "F.Cu")
		(net "PVDD11_S3_P0_PMALERT")
	)
	(via
		(at 415.586418 -367.473484)
		(size 0.508)
		(drill 0.254)
		(layers "F.Cu" "B.Cu")
		(net "PVDD11_S3_P0_PMALERT")
	)
	(via
		(at 381.96139 -118.06301)
		(size 0.508)
		(drill 0.254)
		(layers "F.Cu" "B.Cu")
		(net "PVDD11_S3_P0_PMALERT")
	)
	(via
		(at 184.732168 -111.063024)
		(size 0.4572)
		(drill 0.254)
		(layers "F.Cu" "B.Cu")
		(net "PVDD11_S3_P0_PMALERT")
	)
	(segment
		(start 460.078836 -323.973444)
		(end 460.078836 -187.799218)
		(width 0.10668)
		(layer "B.Cu")
		(net "PVDD11_S3_P0_PMALERT")
	)
	(segment
		(start 422.378124 -119.310404)
		(end 389.552434 -119.310404)
		(width 0.10668)
		(layer "B.Cu")
		(net "PVDD11_S3_P0_PMALERT")
	)
	(segment
		(start 429.413924 -369.583208)
		(end 431.56759 -367.429542)
		(width 0.10668)
		(layer "B.Cu")
		(net "PVDD11_S3_P0_PMALERT")
	)
	(segment
		(start 421.875966 -369.583208)
		(end 429.413924 -369.583208)
		(width 0.10668)
		(layer "B.Cu")
		(net "PVDD11_S3_P0_PMALERT")
	)
	(segment
		(start 388.226808 -117.984778)
		(end 382.039622 -117.984778)
		(width 0.10668)
		(layer "B.Cu")
		(net "PVDD11_S3_P0_PMALERT")
	)
	(segment
		(start 449.384674 -177.105056)
		(end 449.384674 -146.316954)
		(width 0.10668)
		(layer "B.Cu")
		(net "PVDD11_S3_P0_PMALERT")
	)
	(segment
		(start 455.053446 -333.481934)
		(end 455.053446 -328.998834)
		(width 0.10668)
		(layer "B.Cu")
		(net "PVDD11_S3_P0_PMALERT")
	)
	(segment
		(start 431.56759 -367.429542)
		(end 438.84469 -367.429542)
		(width 0.10668)
		(layer "B.Cu")
		(net "PVDD11_S3_P0_PMALERT")
	)
	(segment
		(start 389.552434 -119.310404)
		(end 388.226808 -117.984778)
		(width 0.10668)
		(layer "B.Cu")
		(net "PVDD11_S3_P0_PMALERT")
	)
	(segment
		(start 444.237364 -366.780318)
		(end 446.99301 -364.024672)
		(width 0.10668)
		(layer "B.Cu")
		(net "PVDD11_S3_P0_PMALERT")
	)
	(segment
		(start 449.384674 -146.316954)
		(end 422.378124 -119.310404)
		(width 0.10668)
		(layer "B.Cu")
		(net "PVDD11_S3_P0_PMALERT")
	)
	(segment
		(start 416.122358 -366.937544)
		(end 419.230302 -366.937544)
		(width 0.10668)
		(layer "B.Cu")
		(net "PVDD11_S3_P0_PMALERT")
	)
	(segment
		(start 415.586418 -367.473484)
		(end 416.122358 -366.937544)
		(width 0.10668)
		(layer "B.Cu")
		(net "PVDD11_S3_P0_PMALERT")
	)
	(segment
		(start 460.078836 -187.799218)
		(end 449.384674 -177.105056)
		(width 0.10668)
		(layer "B.Cu")
		(net "PVDD11_S3_P0_PMALERT")
	)
	(segment
		(start 439.493914 -366.780318)
		(end 444.237364 -366.780318)
		(width 0.10668)
		(layer "B.Cu")
		(net "PVDD11_S3_P0_PMALERT")
	)
	(segment
		(start 419.230302 -366.937544)
		(end 421.875966 -369.583208)
		(width 0.10668)
		(layer "B.Cu")
		(net "PVDD11_S3_P0_PMALERT")
	)
	(segment
		(start 446.99301 -341.54237)
		(end 455.053446 -333.481934)
		(width 0.10668)
		(layer "B.Cu")
		(net "PVDD11_S3_P0_PMALERT")
	)
	(segment
		(start 455.053446 -328.998834)
		(end 460.078836 -323.973444)
		(width 0.10668)
		(layer "B.Cu")
		(net "PVDD11_S3_P0_PMALERT")
	)
	(segment
		(start 382.039622 -117.984778)
		(end 381.96139 -118.06301)
		(width 0.10668)
		(layer "B.Cu")
		(net "PVDD11_S3_P0_PMALERT")
	)
	(segment
		(start 438.84469 -367.429542)
		(end 439.493914 -366.780318)
		(width 0.10668)
		(layer "B.Cu")
		(net "PVDD11_S3_P0_PMALERT")
	)
	(segment
		(start 446.99301 -364.024672)
		(end 446.99301 -341.54237)
		(width 0.10668)
		(layer "B.Cu")
		(net "PVDD11_S3_P0_PMALERT")
	)
	(segment
		(start 213.0171 -102.462838)
		(end 210.078574 -102.462838)
		(width 0.11684)
		(layer "In6.Cu")
		(net "PVDD11_S3_P0_PMALERT")
	)
	(segment
		(start 214.797894 -101.247194)
		(end 214.232744 -101.247194)
		(width 0.11684)
		(layer "In6.Cu")
		(net "PVDD11_S3_P0_PMALERT")
	)
	(segment
		(start 214.232744 -101.247194)
		(end 213.0171 -102.462838)
		(width 0.11684)
		(layer "In6.Cu")
		(net "PVDD11_S3_P0_PMALERT")
	)
	(segment
		(start 322.812664 -108.653834)
		(end 321.288918 -108.653834)
		(width 0.11684)
		(layer "In6.Cu")
		(net "PVDD11_S3_P0_PMALERT")
	)
	(segment
		(start 257.853942 -100.15855)
		(end 255.574038 -100.15855)
		(width 0.11684)
		(layer "In6.Cu")
		(net "PVDD11_S3_P0_PMALERT")
	)
	(segment
		(start 274.58289 -99.94011)
		(end 274.534376 -99.988624)
		(width 0.11684)
		(layer "In6.Cu")
		(net "PVDD11_S3_P0_PMALERT")
	)
	(segment
		(start 185.683398 -110.111794)
		(end 184.732168 -111.063024)
		(width 0.11684)
		(layer "In6.Cu")
		(net "PVDD11_S3_P0_PMALERT")
	)
	(segment
		(start 186.755786 -105.269538)
		(end 185.683398 -106.341926)
		(width 0.11684)
		(layer "In6.Cu")
		(net "PVDD11_S3_P0_PMALERT")
	)
	(segment
		(start 267.612876 -99.988624)
		(end 266.14374 -98.519488)
		(width 0.11684)
		(layer "In6.Cu")
		(net "PVDD11_S3_P0_PMALERT")
	)
	(segment
		(start 210.078574 -102.462838)
		(end 209.628486 -102.01275)
		(width 0.11684)
		(layer "In6.Cu")
		(net "PVDD11_S3_P0_PMALERT")
	)
	(segment
		(start 195.949062 -103.139748)
		(end 192.208404 -103.139748)
		(width 0.11684)
		(layer "In6.Cu")
		(net "PVDD11_S3_P0_PMALERT")
	)
	(segment
		(start 254.197866 -101.534722)
		(end 220.878908 -101.534722)
		(width 0.11684)
		(layer "In6.Cu")
		(net "PVDD11_S3_P0_PMALERT")
	)
	(segment
		(start 259.493004 -98.519488)
		(end 257.853942 -100.15855)
		(width 0.11684)
		(layer "In6.Cu")
		(net "PVDD11_S3_P0_PMALERT")
	)
	(segment
		(start 209.628486 -102.01275)
		(end 197.07606 -102.01275)
		(width 0.11684)
		(layer "In6.Cu")
		(net "PVDD11_S3_P0_PMALERT")
	)
	(segment
		(start 313.107832 -100.472748)
		(end 280.797 -100.472748)
		(width 0.11684)
		(layer "In6.Cu")
		(net "PVDD11_S3_P0_PMALERT")
	)
	(segment
		(start 220.056964 -100.712778)
		(end 215.33231 -100.712778)
		(width 0.11684)
		(layer "In6.Cu")
		(net "PVDD11_S3_P0_PMALERT")
	)
	(segment
		(start 185.683398 -106.341926)
		(end 185.683398 -110.111794)
		(width 0.11684)
		(layer "In6.Cu")
		(net "PVDD11_S3_P0_PMALERT")
	)
	(segment
		(start 324.338442 -110.179612)
		(end 322.812664 -108.653834)
		(width 0.11684)
		(layer "In6.Cu")
		(net "PVDD11_S3_P0_PMALERT")
	)
	(segment
		(start 190.078614 -105.269538)
		(end 186.755786 -105.269538)
		(width 0.11684)
		(layer "In6.Cu")
		(net "PVDD11_S3_P0_PMALERT")
	)
	(segment
		(start 321.288918 -108.653834)
		(end 313.107832 -100.472748)
		(width 0.11684)
		(layer "In6.Cu")
		(net "PVDD11_S3_P0_PMALERT")
	)
	(segment
		(start 266.14374 -98.519488)
		(end 259.493004 -98.519488)
		(width 0.11684)
		(layer "In6.Cu")
		(net "PVDD11_S3_P0_PMALERT")
	)
	(segment
		(start 280.264362 -99.94011)
		(end 274.58289 -99.94011)
		(width 0.11684)
		(layer "In6.Cu")
		(net "PVDD11_S3_P0_PMALERT")
	)
	(segment
		(start 255.574038 -100.15855)
		(end 254.197866 -101.534722)
		(width 0.11684)
		(layer "In6.Cu")
		(net "PVDD11_S3_P0_PMALERT")
	)
	(segment
		(start 215.33231 -100.712778)
		(end 214.797894 -101.247194)
		(width 0.11684)
		(layer "In6.Cu")
		(net "PVDD11_S3_P0_PMALERT")
	)
	(segment
		(start 280.797 -100.472748)
		(end 280.264362 -99.94011)
		(width 0.11684)
		(layer "In6.Cu")
		(net "PVDD11_S3_P0_PMALERT")
	)
	(segment
		(start 220.878908 -101.534722)
		(end 220.056964 -100.712778)
		(width 0.11684)
		(layer "In6.Cu")
		(net "PVDD11_S3_P0_PMALERT")
	)
	(segment
		(start 197.07606 -102.01275)
		(end 195.949062 -103.139748)
		(width 0.11684)
		(layer "In6.Cu")
		(net "PVDD11_S3_P0_PMALERT")
	)
	(segment
		(start 274.534376 -99.988624)
		(end 267.612876 -99.988624)
		(width 0.11684)
		(layer "In6.Cu")
		(net "PVDD11_S3_P0_PMALERT")
	)
	(segment
		(start 374.077992 -110.179612)
		(end 324.338442 -110.179612)
		(width 0.11684)
		(layer "In6.Cu")
		(net "PVDD11_S3_P0_PMALERT")
	)
	(segment
		(start 192.208404 -103.139748)
		(end 190.078614 -105.269538)
		(width 0.11684)
		(layer "In6.Cu")
		(net "PVDD11_S3_P0_PMALERT")
	)
	(segment
		(start 381.96139 -118.06301)
		(end 374.077992 -110.179612)
		(width 0.11684)
		(layer "In6.Cu")
		(net "PVDD11_S3_P0_PMALERT")
	)
	(segment
		(start 422.617138 -359.843832)
		(end 422.556178 -359.904792)
		(width 0.1524)
		(layer "F.Cu")
		(net "PVDD11_S3_P0_OCP_N_R")
	)
	(segment
		(start 422.098978 -360.682794)
		(end 421.694356 -361.087416)
		(width 0.1524)
		(layer "F.Cu")
		(net "PVDD11_S3_P0_OCP_N_R")
	)
	(segment
		(start 422.700958 -359.836212)
		(end 422.693338 -359.843832)
		(width 0.1524)
		(layer "F.Cu")
		(net "PVDD11_S3_P0_OCP_N_R")
	)
	(segment
		(start 423.22369 -359.836212)
		(end 422.700958 -359.836212)
		(width 0.1524)
		(layer "F.Cu")
		(net "PVDD11_S3_P0_OCP_N_R")
	)
	(segment
		(start 422.693338 -359.843832)
		(end 422.617138 -359.843832)
		(width 0.1524)
		(layer "F.Cu")
		(net "PVDD11_S3_P0_OCP_N_R")
	)
	(segment
		(start 422.556178 -359.904792)
		(end 422.098978 -359.904792)
		(width 0.1524)
		(layer "F.Cu")
		(net "PVDD11_S3_P0_OCP_N_R")
	)
	(segment
		(start 422.098978 -359.904792)
		(end 422.098978 -360.682794)
		(width 0.1524)
		(layer "F.Cu")
		(net "PVDD11_S3_P0_OCP_N_R")
	)
	(segment
		(start 421.694356 -361.087416)
		(end 421.317928 -361.087416)
		(width 0.1524)
		(layer "F.Cu")
		(net "PVDD11_S3_P0_OCP_N_R")
	)
	(via
		(at 422.098978 -359.904792)
		(size 0.508)
		(drill 0.254)
		(layers "F.Cu" "B.Cu")
		(net "PVDD11_S3_P0_OCP_N_R")
	)
	(segment
		(start 423.23004 -359.84434)
		(end 423.169588 -359.904792)
		(width 0.1524)
		(layer "B.Cu")
		(net "PVDD11_S3_P0_OCP_N_R")
	)
	(segment
		(start 423.169588 -359.904792)
		(end 422.098978 -359.904792)
		(width 0.1524)
		(layer "B.Cu")
		(net "PVDD11_S3_P0_OCP_N_R")
	)
	(via
		(at 410.134054 -107.337098)
		(size 0.508)
		(drill 0.254)
		(layers "F.Cu" "B.Cu")
		(net "PVDD11_S3_P0_OCP_N")
	)
	(via
		(at 256.901442 -71.853806)
		(size 0.508)
		(drill 0.254)
		(layers "F.Cu" "B.Cu")
		(net "PVDD11_S3_P0_OCP_N")
	)
	(via
		(at 198.038974 -79.515462)
		(size 0.508)
		(drill 0.254)
		(layers "F.Cu" "B.Cu")
		(net "PVDD11_S3_P0_OCP_N")
	)
	(via
		(at 270.092424 -80.847438)
		(size 0.508)
		(drill 0.254)
		(layers "F.Cu" "B.Cu")
		(net "PVDD11_S3_P0_OCP_N")
	)
	(via
		(at 192.59423 -87.315802)
		(size 0.508)
		(drill 0.254)
		(layers "F.Cu" "B.Cu")
		(net "PVDD11_S3_P0_OCP_N")
	)
	(via
		(at 424.789854 -361.53471)
		(size 0.508)
		(drill 0.254)
		(layers "F.Cu" "B.Cu")
		(net "PVDD11_S3_P0_OCP_N")
	)
	(via
		(at 424.03014 -361.180634)
		(size 0.6604)
		(drill 0.3302)
		(layers "F.Cu" "B.Cu")
		(net "PVDD11_S3_P0_OCP_N")
	)
	(via
		(at 181.737 -99.278948)
		(size 0.508)
		(drill 0.254)
		(layers "F.Cu" "B.Cu")
		(net "PVDD11_S3_P0_OCP_N")
	)
	(via
		(at 181.576218 -87.615522)
		(size 0.508)
		(drill 0.254)
		(layers "F.Cu" "B.Cu")
		(net "PVDD11_S3_P0_OCP_N")
	)
	(segment
		(start 258.955032 -76.31684)
		(end 258.955032 -79.864204)
		(width 0.1524)
		(layer "B.Cu")
		(net "PVDD11_S3_P0_OCP_N")
	)
	(segment
		(start 257.291078 -72.243442)
		(end 257.291078 -74.652886)
		(width 0.1524)
		(layer "B.Cu")
		(net "PVDD11_S3_P0_OCP_N")
	)
	(segment
		(start 182.289958 -88.991948)
		(end 185.296556 -88.991948)
		(width 0.1524)
		(layer "B.Cu")
		(net "PVDD11_S3_P0_OCP_N")
	)
	(segment
		(start 258.955032 -79.864204)
		(end 259.938266 -80.847438)
		(width 0.1524)
		(layer "B.Cu")
		(net "PVDD11_S3_P0_OCP_N")
	)
	(segment
		(start 424.03014 -361.180634)
		(end 424.03014 -359.84434)
		(width 0.1524)
		(layer "B.Cu")
		(net "PVDD11_S3_P0_OCP_N")
	)
	(segment
		(start 259.938266 -80.847438)
		(end 270.092424 -80.847438)
		(width 0.1524)
		(layer "B.Cu")
		(net "PVDD11_S3_P0_OCP_N")
	)
	(segment
		(start 185.847228 -87.807038)
		(end 186.91606 -86.738206)
		(width 0.1524)
		(layer "B.Cu")
		(net "PVDD11_S3_P0_OCP_N")
	)
	(segment
		(start 181.576218 -87.615522)
		(end 181.576218 -88.278208)
		(width 0.1524)
		(layer "B.Cu")
		(net "PVDD11_S3_P0_OCP_N")
	)
	(segment
		(start 181.737 -99.894898)
		(end 181.737 -99.278948)
		(width 0.10668)
		(layer "B.Cu")
		(net "PVDD11_S3_P0_OCP_N")
	)
	(segment
		(start 424.435778 -361.180634)
		(end 424.03014 -361.180634)
		(width 0.1524)
		(layer "B.Cu")
		(net "PVDD11_S3_P0_OCP_N")
	)
	(segment
		(start 181.576218 -88.278208)
		(end 182.289958 -88.991948)
		(width 0.1524)
		(layer "B.Cu")
		(net "PVDD11_S3_P0_OCP_N")
	)
	(segment
		(start 185.296556 -88.991948)
		(end 185.847228 -88.441276)
		(width 0.1524)
		(layer "B.Cu")
		(net "PVDD11_S3_P0_OCP_N")
	)
	(segment
		(start 185.847228 -88.441276)
		(end 185.847228 -87.807038)
		(width 0.1524)
		(layer "B.Cu")
		(net "PVDD11_S3_P0_OCP_N")
	)
	(segment
		(start 192.016634 -86.738206)
		(end 192.59423 -87.315802)
		(width 0.1524)
		(layer "B.Cu")
		(net "PVDD11_S3_P0_OCP_N")
	)
	(segment
		(start 256.901442 -71.853806)
		(end 257.291078 -72.243442)
		(width 0.1524)
		(layer "B.Cu")
		(net "PVDD11_S3_P0_OCP_N")
	)
	(segment
		(start 257.291078 -74.652886)
		(end 258.955032 -76.31684)
		(width 0.1524)
		(layer "B.Cu")
		(net "PVDD11_S3_P0_OCP_N")
	)
	(segment
		(start 424.789854 -361.53471)
		(end 424.435778 -361.180634)
		(width 0.1524)
		(layer "B.Cu")
		(net "PVDD11_S3_P0_OCP_N")
	)
	(segment
		(start 186.91606 -86.738206)
		(end 192.016634 -86.738206)
		(width 0.1524)
		(layer "B.Cu")
		(net "PVDD11_S3_P0_OCP_N")
	)
	(segment
		(start 203.590144 -78.548738)
		(end 203.916534 -78.222348)
		(width 0.1524)
		(layer "In2.Cu")
		(net "PVDD11_S3_P0_OCP_N")
	)
	(segment
		(start 213.16442 -77.556106)
		(end 216.142062 -77.556106)
		(width 0.1524)
		(layer "In2.Cu")
		(net "PVDD11_S3_P0_OCP_N")
	)
	(segment
		(start 255.992884 -72.762364)
		(end 256.901442 -71.853806)
		(width 0.1524)
		(layer "In2.Cu")
		(net "PVDD11_S3_P0_OCP_N")
	)
	(segment
		(start 198.038974 -79.515462)
		(end 201.343514 -79.515462)
		(width 0.1524)
		(layer "In2.Cu")
		(net "PVDD11_S3_P0_OCP_N")
	)
	(segment
		(start 319.216786 -107.337098)
		(end 316.532006 -104.652318)
		(width 0.1524)
		(layer "In2.Cu")
		(net "PVDD11_S3_P0_OCP_N")
	)
	(segment
		(start 203.916534 -78.222348)
		(end 209.53349 -78.222348)
		(width 0.1524)
		(layer "In2.Cu")
		(net "PVDD11_S3_P0_OCP_N")
	)
	(segment
		(start 220.909896 -75.884024)
		(end 222.594678 -75.884024)
		(width 0.1524)
		(layer "In2.Cu")
		(net "PVDD11_S3_P0_OCP_N")
	)
	(segment
		(start 232.181908 -72.057006)
		(end 232.887266 -72.762364)
		(width 0.1524)
		(layer "In2.Cu")
		(net "PVDD11_S3_P0_OCP_N")
	)
	(segment
		(start 209.833718 -78.522576)
		(end 212.19795 -78.522576)
		(width 0.1524)
		(layer "In2.Cu")
		(net "PVDD11_S3_P0_OCP_N")
	)
	(segment
		(start 328.93381 -107.337098)
		(end 328.120502 -108.150406)
		(width 0.1524)
		(layer "In2.Cu")
		(net "PVDD11_S3_P0_OCP_N")
	)
	(segment
		(start 327.069958 -108.150406)
		(end 326.25665 -107.337098)
		(width 0.1524)
		(layer "In2.Cu")
		(net "PVDD11_S3_P0_OCP_N")
	)
	(segment
		(start 230.588566 -72.592438)
		(end 231.123998 -72.057006)
		(width 0.1524)
		(layer "In2.Cu")
		(net "PVDD11_S3_P0_OCP_N")
	)
	(segment
		(start 212.19795 -78.522576)
		(end 213.16442 -77.556106)
		(width 0.1524)
		(layer "In2.Cu")
		(net "PVDD11_S3_P0_OCP_N")
	)
	(segment
		(start 216.142062 -77.556106)
		(end 216.79535 -76.902818)
		(width 0.1524)
		(layer "In2.Cu")
		(net "PVDD11_S3_P0_OCP_N")
	)
	(segment
		(start 201.343514 -79.515462)
		(end 202.310238 -78.548738)
		(width 0.1524)
		(layer "In2.Cu")
		(net "PVDD11_S3_P0_OCP_N")
	)
	(segment
		(start 222.594678 -75.884024)
		(end 225.886264 -72.592438)
		(width 0.1524)
		(layer "In2.Cu")
		(net "PVDD11_S3_P0_OCP_N")
	)
	(segment
		(start 410.134054 -107.337098)
		(end 328.93381 -107.337098)
		(width 0.1524)
		(layer "In2.Cu")
		(net "PVDD11_S3_P0_OCP_N")
	)
	(segment
		(start 219.891102 -76.902818)
		(end 220.909896 -75.884024)
		(width 0.1524)
		(layer "In2.Cu")
		(net "PVDD11_S3_P0_OCP_N")
	)
	(segment
		(start 209.53349 -78.222348)
		(end 209.833718 -78.522576)
		(width 0.1524)
		(layer "In2.Cu")
		(net "PVDD11_S3_P0_OCP_N")
	)
	(segment
		(start 328.120502 -108.150406)
		(end 327.069958 -108.150406)
		(width 0.1524)
		(layer "In2.Cu")
		(net "PVDD11_S3_P0_OCP_N")
	)
	(segment
		(start 326.25665 -107.337098)
		(end 319.216786 -107.337098)
		(width 0.1524)
		(layer "In2.Cu")
		(net "PVDD11_S3_P0_OCP_N")
	)
	(segment
		(start 316.532006 -104.652318)
		(end 293.897304 -104.652318)
		(width 0.1524)
		(layer "In2.Cu")
		(net "PVDD11_S3_P0_OCP_N")
	)
	(segment
		(start 293.897304 -104.652318)
		(end 270.092424 -80.847438)
		(width 0.1524)
		(layer "In2.Cu")
		(net "PVDD11_S3_P0_OCP_N")
	)
	(segment
		(start 225.886264 -72.592438)
		(end 230.588566 -72.592438)
		(width 0.1524)
		(layer "In2.Cu")
		(net "PVDD11_S3_P0_OCP_N")
	)
	(segment
		(start 216.79535 -76.902818)
		(end 219.891102 -76.902818)
		(width 0.1524)
		(layer "In2.Cu")
		(net "PVDD11_S3_P0_OCP_N")
	)
	(segment
		(start 232.887266 -72.762364)
		(end 255.992884 -72.762364)
		(width 0.1524)
		(layer "In2.Cu")
		(net "PVDD11_S3_P0_OCP_N")
	)
	(segment
		(start 202.310238 -78.548738)
		(end 203.590144 -78.548738)
		(width 0.1524)
		(layer "In2.Cu")
		(net "PVDD11_S3_P0_OCP_N")
	)
	(segment
		(start 231.123998 -72.057006)
		(end 232.181908 -72.057006)
		(width 0.1524)
		(layer "In2.Cu")
		(net "PVDD11_S3_P0_OCP_N")
	)
	(segment
		(start 453.467724 -170.790616)
		(end 449.109846 -166.432738)
		(width 0.1524)
		(layer "In4.Cu")
		(net "PVDD11_S3_P0_OCP_N")
	)
	(segment
		(start 446.35293 -334.207358)
		(end 455.244962 -325.315326)
		(width 0.1524)
		(layer "In4.Cu")
		(net "PVDD11_S3_P0_OCP_N")
	)
	(segment
		(start 181.687724 -99.278948)
		(end 181.202838 -98.794062)
		(width 0.1524)
		(layer "In4.Cu")
		(net "PVDD11_S3_P0_OCP_N")
	)
	(segment
		(start 193.122804 -86.787228)
		(end 192.59423 -87.315802)
		(width 0.1524)
		(layer "In4.Cu")
		(net "PVDD11_S3_P0_OCP_N")
	)
	(segment
		(start 453.467724 -182.030624)
		(end 453.467724 -170.790616)
		(width 0.1524)
		(layer "In4.Cu")
		(net "PVDD11_S3_P0_OCP_N")
	)
	(segment
		(start 424.789854 -361.53471)
		(end 424.770804 -361.53471)
		(width 0.1524)
		(layer "In4.Cu")
		(net "PVDD11_S3_P0_OCP_N")
	)
	(segment
		(start 455.244962 -323.817488)
		(end 458.462888 -320.599562)
		(width 0.1524)
		(layer "In4.Cu")
		(net "PVDD11_S3_P0_OCP_N")
	)
	(segment
		(start 181.202838 -87.988902)
		(end 181.576218 -87.615522)
		(width 0.1524)
		(layer "In4.Cu")
		(net "PVDD11_S3_P0_OCP_N")
	)
	(segment
		(start 449.109846 -166.432738)
		(end 449.109846 -147.153122)
		(width 0.1524)
		(layer "In4.Cu")
		(net "PVDD11_S3_P0_OCP_N")
	)
	(segment
		(start 181.737 -99.278948)
		(end 181.687724 -99.278948)
		(width 0.1524)
		(layer "In4.Cu")
		(net "PVDD11_S3_P0_OCP_N")
	)
	(segment
		(start 449.109846 -147.153122)
		(end 440.513724 -138.557)
		(width 0.1524)
		(layer "In4.Cu")
		(net "PVDD11_S3_P0_OCP_N")
	)
	(segment
		(start 442.62548 -370.220494)
		(end 446.35293 -366.493044)
		(width 0.1524)
		(layer "In4.Cu")
		(net "PVDD11_S3_P0_OCP_N")
	)
	(segment
		(start 198.038974 -79.515462)
		(end 198.038974 -79.597504)
		(width 0.1524)
		(layer "In4.Cu")
		(net "PVDD11_S3_P0_OCP_N")
	)
	(segment
		(start 446.35293 -366.493044)
		(end 446.35293 -334.207358)
		(width 0.1524)
		(layer "In4.Cu")
		(net "PVDD11_S3_P0_OCP_N")
	)
	(segment
		(start 425.276264 -370.220494)
		(end 442.62548 -370.220494)
		(width 0.1524)
		(layer "In4.Cu")
		(net "PVDD11_S3_P0_OCP_N")
	)
	(segment
		(start 181.94147 -92.882212)
		(end 181.202838 -92.14358)
		(width 0.1524)
		(layer "In4.Cu")
		(net "PVDD11_S3_P0_OCP_N")
	)
	(segment
		(start 411.996128 -109.199172)
		(end 410.134054 -107.337098)
		(width 0.1524)
		(layer "In4.Cu")
		(net "PVDD11_S3_P0_OCP_N")
	)
	(segment
		(start 458.462888 -320.599562)
		(end 458.462888 -187.025788)
		(width 0.1524)
		(layer "In4.Cu")
		(net "PVDD11_S3_P0_OCP_N")
	)
	(segment
		(start 183.255158 -95.830136)
		(end 183.255158 -93.128338)
		(width 0.1524)
		(layer "In4.Cu")
		(net "PVDD11_S3_P0_OCP_N")
	)
	(segment
		(start 193.122804 -84.513674)
		(end 193.122804 -86.787228)
		(width 0.1524)
		(layer "In4.Cu")
		(net "PVDD11_S3_P0_OCP_N")
	)
	(segment
		(start 425.115736 -366.675416)
		(end 425.115736 -370.059966)
		(width 0.1524)
		(layer "In4.Cu")
		(net "PVDD11_S3_P0_OCP_N")
	)
	(segment
		(start 423.613834 -365.173514)
		(end 425.115736 -366.675416)
		(width 0.1524)
		(layer "In4.Cu")
		(net "PVDD11_S3_P0_OCP_N")
	)
	(segment
		(start 183.009032 -92.882212)
		(end 181.94147 -92.882212)
		(width 0.1524)
		(layer "In4.Cu")
		(net "PVDD11_S3_P0_OCP_N")
	)
	(segment
		(start 425.115736 -370.059966)
		(end 425.276264 -370.220494)
		(width 0.1524)
		(layer "In4.Cu")
		(net "PVDD11_S3_P0_OCP_N")
	)
	(segment
		(start 198.038974 -79.597504)
		(end 193.122804 -84.513674)
		(width 0.1524)
		(layer "In4.Cu")
		(net "PVDD11_S3_P0_OCP_N")
	)
	(segment
		(start 411.996128 -118.372128)
		(end 411.996128 -109.199172)
		(width 0.1524)
		(layer "In4.Cu")
		(net "PVDD11_S3_P0_OCP_N")
	)
	(segment
		(start 432.181 -138.557)
		(end 411.996128 -118.372128)
		(width 0.1524)
		(layer "In4.Cu")
		(net "PVDD11_S3_P0_OCP_N")
	)
	(segment
		(start 423.613834 -362.69168)
		(end 423.613834 -365.173514)
		(width 0.1524)
		(layer "In4.Cu")
		(net "PVDD11_S3_P0_OCP_N")
	)
	(segment
		(start 455.244962 -325.315326)
		(end 455.244962 -323.817488)
		(width 0.1524)
		(layer "In4.Cu")
		(net "PVDD11_S3_P0_OCP_N")
	)
	(segment
		(start 181.202838 -98.794062)
		(end 181.202838 -97.882456)
		(width 0.1524)
		(layer "In4.Cu")
		(net "PVDD11_S3_P0_OCP_N")
	)
	(segment
		(start 440.513724 -138.557)
		(end 432.181 -138.557)
		(width 0.1524)
		(layer "In4.Cu")
		(net "PVDD11_S3_P0_OCP_N")
	)
	(segment
		(start 458.462888 -187.025788)
		(end 453.467724 -182.030624)
		(width 0.1524)
		(layer "In4.Cu")
		(net "PVDD11_S3_P0_OCP_N")
	)
	(segment
		(start 181.202838 -92.14358)
		(end 181.202838 -87.988902)
		(width 0.1524)
		(layer "In4.Cu")
		(net "PVDD11_S3_P0_OCP_N")
	)
	(segment
		(start 183.255158 -93.128338)
		(end 183.009032 -92.882212)
		(width 0.1524)
		(layer "In4.Cu")
		(net "PVDD11_S3_P0_OCP_N")
	)
	(segment
		(start 424.770804 -361.53471)
		(end 423.613834 -362.69168)
		(width 0.1524)
		(layer "In4.Cu")
		(net "PVDD11_S3_P0_OCP_N")
	)
	(segment
		(start 181.202838 -97.882456)
		(end 183.255158 -95.830136)
		(width 0.1524)
		(layer "In4.Cu")
		(net "PVDD11_S3_P0_OCP_N")
	)
	(segment
		(start 430.509426 -356.108508)
		(end 430.509426 -355.269546)
		(width 0.1524)
		(layer "F.Cu")
		(net "PVDD11_S3_P0_LSET2")
	)
	(segment
		(start 430.266094 -356.35184)
		(end 430.509426 -356.108508)
		(width 0.1524)
		(layer "F.Cu")
		(net "PVDD11_S3_P0_LSET2")
	)
	(segment
		(start 430.880774 -354.446078)
		(end 430.880774 -354.040186)
		(width 0.1524)
		(layer "F.Cu")
		(net "PVDD11_S3_P0_LSET2")
	)
	(segment
		(start 430.509426 -355.269546)
		(end 430.509426 -354.817426)
		(width 0.1524)
		(layer "F.Cu")
		(net "PVDD11_S3_P0_LSET2")
	)
	(segment
		(start 430.509426 -354.817426)
		(end 430.880774 -354.446078)
		(width 0.1524)
		(layer "F.Cu")
		(net "PVDD11_S3_P0_LSET2")
	)
	(via
		(at 430.509426 -355.269546)
		(size 0.4064)
		(drill 0.2032)
		(layers "F.Cu" "B.Cu")
		(net "PVDD11_S3_P0_LSET2")
	)
	(segment
		(start 422.554146 -354.420678)
		(end 422.554146 -354.014786)
		(width 0.1524)
		(layer "F.Cu")
		(net "PVDD11_S3_P0_LSET1")
	)
	(segment
		(start 422.182798 -354.792026)
		(end 422.554146 -354.420678)
		(width 0.1524)
		(layer "F.Cu")
		(net "PVDD11_S3_P0_LSET1")
	)
	(segment
		(start 422.182798 -355.244146)
		(end 422.182798 -354.792026)
		(width 0.1524)
		(layer "F.Cu")
		(net "PVDD11_S3_P0_LSET1")
	)
	(segment
		(start 421.939466 -356.32644)
		(end 422.182798 -356.083108)
		(width 0.1524)
		(layer "F.Cu")
		(net "PVDD11_S3_P0_LSET1")
	)
	(segment
		(start 422.182798 -356.083108)
		(end 422.182798 -355.244146)
		(width 0.1524)
		(layer "F.Cu")
		(net "PVDD11_S3_P0_LSET1")
	)
	(via
		(at 422.182798 -355.244146)
		(size 0.4064)
		(drill 0.2032)
		(layers "F.Cu" "B.Cu")
		(net "PVDD11_S3_P0_LSET1")
	)
	(segment
		(start 430.005236 -354.960682)
		(end 430.005236 -354.841556)
		(width 0.2286)
		(layer "F.Cu")
		(net "PVDD11_S3_P0_IMON2")
	)
	(segment
		(start 430.430686 -354.416106)
		(end 430.430686 -354.040186)
		(width 0.2286)
		(layer "F.Cu")
		(net "PVDD11_S3_P0_IMON2")
	)
	(segment
		(start 418.317934 -359.687368)
		(end 418.317934 -358.947466)
		(width 0.1778)
		(layer "F.Cu")
		(net "PVDD11_S3_P0_IMON2")
	)
	(segment
		(start 430.005236 -354.841556)
		(end 430.430686 -354.416106)
		(width 0.2286)
		(layer "F.Cu")
		(net "PVDD11_S3_P0_IMON2")
	)
	(segment
		(start 418.317934 -358.947466)
		(end 418.206682 -358.836214)
		(width 0.1778)
		(layer "F.Cu")
		(net "PVDD11_S3_P0_IMON2")
	)
	(via
		(at 418.206682 -358.836214)
		(size 0.508)
		(drill 0.254)
		(layers "F.Cu" "B.Cu")
		(net "PVDD11_S3_P0_IMON2")
	)
	(via
		(at 430.005236 -354.960682)
		(size 0.508)
		(drill 0.254)
		(layers "F.Cu" "B.Cu")
		(net "PVDD11_S3_P0_IMON2")
	)
	(segment
		(start 429.788828 -354.960682)
		(end 430.005236 -354.960682)
		(width 0.254)
		(layer "In4.Cu")
		(net "PVDD11_S3_P0_IMON2")
	)
	(segment
		(start 427.793912 -358.35209)
		(end 429.491648 -356.654354)
		(width 0.254)
		(layer "In4.Cu")
		(net "PVDD11_S3_P0_IMON2")
	)
	(segment
		(start 419.412674 -358.35209)
		(end 427.793912 -358.35209)
		(width 0.254)
		(layer "In4.Cu")
		(net "PVDD11_S3_P0_IMON2")
	)
	(segment
		(start 429.491648 -355.257862)
		(end 429.788828 -354.960682)
		(width 0.254)
		(layer "In4.Cu")
		(net "PVDD11_S3_P0_IMON2")
	)
	(segment
		(start 418.92855 -358.836214)
		(end 419.412674 -358.35209)
		(width 0.254)
		(layer "In4.Cu")
		(net "PVDD11_S3_P0_IMON2")
	)
	(segment
		(start 418.206682 -358.836214)
		(end 418.92855 -358.836214)
		(width 0.254)
		(layer "In4.Cu")
		(net "PVDD11_S3_P0_IMON2")
	)
	(segment
		(start 429.491648 -356.654354)
		(end 429.491648 -355.257862)
		(width 0.254)
		(layer "In4.Cu")
		(net "PVDD11_S3_P0_IMON2")
	)
	(segment
		(start 422.104058 -354.014786)
		(end 422.104058 -354.390706)
		(width 0.2286)
		(layer "F.Cu")
		(net "PVDD11_S3_P0_IMON1")
	)
	(segment
		(start 417.917884 -359.255568)
		(end 417.917884 -359.687368)
		(width 0.1778)
		(layer "F.Cu")
		(net "PVDD11_S3_P0_IMON1")
	)
	(segment
		(start 422.104058 -354.390706)
		(end 421.678608 -354.816156)
		(width 0.2286)
		(layer "F.Cu")
		(net "PVDD11_S3_P0_IMON1")
	)
	(segment
		(start 417.576254 -357.649526)
		(end 417.576254 -358.913938)
		(width 0.254)
		(layer "F.Cu")
		(net "PVDD11_S3_P0_IMON1")
	)
	(segment
		(start 421.678608 -354.816156)
		(end 421.678608 -354.935282)
		(width 0.2286)
		(layer "F.Cu")
		(net "PVDD11_S3_P0_IMON1")
	)
	(segment
		(start 417.576254 -358.913938)
		(end 417.917884 -359.255568)
		(width 0.1778)
		(layer "F.Cu")
		(net "PVDD11_S3_P0_IMON1")
	)
	(via
		(at 421.678608 -354.935282)
		(size 0.508)
		(drill 0.254)
		(layers "F.Cu" "B.Cu")
		(net "PVDD11_S3_P0_IMON1")
	)
	(via
		(at 417.576254 -357.649526)
		(size 0.508)
		(drill 0.254)
		(layers "F.Cu" "B.Cu")
		(net "PVDD11_S3_P0_IMON1")
	)
	(segment
		(start 417.586414 -357.659686)
		(end 417.576254 -357.649526)
		(width 0.254)
		(layer "In4.Cu")
		(net "PVDD11_S3_P0_IMON1")
	)
	(segment
		(start 421.678608 -354.935282)
		(end 421.538908 -354.935282)
		(width 0.254)
		(layer "In4.Cu")
		(net "PVDD11_S3_P0_IMON1")
	)
	(segment
		(start 421.538908 -354.935282)
		(end 421.030654 -355.443536)
		(width 0.254)
		(layer "In4.Cu")
		(net "PVDD11_S3_P0_IMON1")
	)
	(segment
		(start 418.566854 -357.03891)
		(end 417.946078 -357.659686)
		(width 0.254)
		(layer "In4.Cu")
		(net "PVDD11_S3_P0_IMON1")
	)
	(segment
		(start 420.776654 -357.03891)
		(end 418.566854 -357.03891)
		(width 0.254)
		(layer "In4.Cu")
		(net "PVDD11_S3_P0_IMON1")
	)
	(segment
		(start 421.030654 -355.443536)
		(end 421.030654 -356.78491)
		(width 0.254)
		(layer "In4.Cu")
		(net "PVDD11_S3_P0_IMON1")
	)
	(segment
		(start 417.946078 -357.659686)
		(end 417.586414 -357.659686)
		(width 0.254)
		(layer "In4.Cu")
		(net "PVDD11_S3_P0_IMON1")
	)
	(segment
		(start 421.030654 -356.78491)
		(end 420.776654 -357.03891)
		(width 0.254)
		(layer "In4.Cu")
		(net "PVDD11_S3_P0_IMON1")
	)
	(segment
		(start 413.654494 -363.324902)
		(end 413.530034 -363.449362)
		(width 0.10668)
		(layer "F.Cu")
		(net "PVDD11_S3_P0_EN_R")
	)
	(segment
		(start 412.120588 -363.449362)
		(end 411.734 -363.83595)
		(width 0.10668)
		(layer "F.Cu")
		(net "PVDD11_S3_P0_EN_R")
	)
	(segment
		(start 414.731962 -363.591348)
		(end 414.465516 -363.324902)
		(width 0.10668)
		(layer "F.Cu")
		(net "PVDD11_S3_P0_EN_R")
	)
	(segment
		(start 414.731962 -363.790992)
		(end 414.731962 -363.591348)
		(width 0.10668)
		(layer "F.Cu")
		(net "PVDD11_S3_P0_EN_R")
	)
	(segment
		(start 415.715958 -363.087412)
		(end 415.447226 -363.356144)
		(width 0.10668)
		(layer "F.Cu")
		(net "PVDD11_S3_P0_EN_R")
	)
	(segment
		(start 415.447226 -363.356144)
		(end 415.012378 -363.790992)
		(width 0.10668)
		(layer "F.Cu")
		(net "PVDD11_S3_P0_EN_R")
	)
	(segment
		(start 414.465516 -363.324902)
		(end 413.654494 -363.324902)
		(width 0.10668)
		(layer "F.Cu")
		(net "PVDD11_S3_P0_EN_R")
	)
	(segment
		(start 413.530034 -363.449362)
		(end 412.120588 -363.449362)
		(width 0.10668)
		(layer "F.Cu")
		(net "PVDD11_S3_P0_EN_R")
	)
	(segment
		(start 416.517836 -363.087412)
		(end 415.715958 -363.087412)
		(width 0.10668)
		(layer "F.Cu")
		(net "PVDD11_S3_P0_EN_R")
	)
	(segment
		(start 415.012378 -363.790992)
		(end 414.731962 -363.790992)
		(width 0.10668)
		(layer "F.Cu")
		(net "PVDD11_S3_P0_EN_R")
	)
	(via
		(at 415.447226 -363.356144)
		(size 0.508)
		(drill 0.254)
		(layers "F.Cu" "B.Cu")
		(net "PVDD11_S3_P0_EN_R")
	)
	(segment
		(start 201.339958 -105.497376)
		(end 202.255882 -105.497376)
		(width 0.10668)
		(layer "F.Cu")
		(net "PVDD11_S3_P0_EN")
	)
	(segment
		(start 411.734 -365.5314)
		(end 412.165038 -365.962438)
		(width 0.10668)
		(layer "F.Cu")
		(net "PVDD11_S3_P0_EN")
	)
	(segment
		(start 411.734 -364.63605)
		(end 411.734 -365.5314)
		(width 0.10668)
		(layer "F.Cu")
		(net "PVDD11_S3_P0_EN")
	)
	(via
		(at 202.255882 -105.497376)
		(size 0.508)
		(drill 0.254)
		(layers "F.Cu" "B.Cu")
		(net "PVDD11_S3_P0_EN")
	)
	(via
		(at 382.517396 -119.541544)
		(size 0.508)
		(drill 0.254)
		(layers "F.Cu" "B.Cu")
		(net "PVDD11_S3_P0_EN")
	)
	(via
		(at 412.165038 -365.962438)
		(size 0.508)
		(drill 0.254)
		(layers "F.Cu" "B.Cu")
		(net "PVDD11_S3_P0_EN")
	)
	(segment
		(start 438.396634 -366.708182)
		(end 430.808892 -366.708182)
		(width 0.10668)
		(layer "B.Cu")
		(net "PVDD11_S3_P0_EN")
	)
	(segment
		(start 421.937942 -120.081548)
		(end 448.63893 -146.782536)
		(width 0.10668)
		(layer "B.Cu")
		(net "PVDD11_S3_P0_EN")
	)
	(segment
		(start 387.85419 -118.755922)
		(end 389.179816 -120.081548)
		(width 0.10668)
		(layer "B.Cu")
		(net "PVDD11_S3_P0_EN")
	)
	(segment
		(start 389.179816 -120.081548)
		(end 421.937942 -120.081548)
		(width 0.10668)
		(layer "B.Cu")
		(net "PVDD11_S3_P0_EN")
	)
	(segment
		(start 459.28153 -188.022738)
		(end 459.28153 -323.71792)
		(width 0.10668)
		(layer "B.Cu")
		(net "PVDD11_S3_P0_EN")
	)
	(segment
		(start 444.028576 -365.845852)
		(end 439.258964 -365.845852)
		(width 0.10668)
		(layer "B.Cu")
		(net "PVDD11_S3_P0_EN")
	)
	(segment
		(start 446.24879 -341.23376)
		(end 446.24879 -363.625638)
		(width 0.10668)
		(layer "B.Cu")
		(net "PVDD11_S3_P0_EN")
	)
	(segment
		(start 429.652684 -367.86439)
		(end 422.55313 -367.86439)
		(width 0.10668)
		(layer "B.Cu")
		(net "PVDD11_S3_P0_EN")
	)
	(segment
		(start 422.55313 -367.86439)
		(end 421.186864 -366.498124)
		(width 0.10668)
		(layer "B.Cu")
		(net "PVDD11_S3_P0_EN")
	)
	(segment
		(start 420.12616 -366.21339)
		(end 412.41599 -366.21339)
		(width 0.10668)
		(layer "B.Cu")
		(net "PVDD11_S3_P0_EN")
	)
	(segment
		(start 454.332086 -328.667364)
		(end 454.332086 -333.150464)
		(width 0.10668)
		(layer "B.Cu")
		(net "PVDD11_S3_P0_EN")
	)
	(segment
		(start 421.186864 -366.498124)
		(end 420.410894 -366.498124)
		(width 0.10668)
		(layer "B.Cu")
		(net "PVDD11_S3_P0_EN")
	)
	(segment
		(start 412.41599 -366.21339)
		(end 412.165038 -365.962438)
		(width 0.10668)
		(layer "B.Cu")
		(net "PVDD11_S3_P0_EN")
	)
	(segment
		(start 454.332086 -333.150464)
		(end 446.24879 -341.23376)
		(width 0.10668)
		(layer "B.Cu")
		(net "PVDD11_S3_P0_EN")
	)
	(segment
		(start 383.303018 -118.755922)
		(end 387.85419 -118.755922)
		(width 0.10668)
		(layer "B.Cu")
		(net "PVDD11_S3_P0_EN")
	)
	(segment
		(start 439.258964 -365.845852)
		(end 438.396634 -366.708182)
		(width 0.10668)
		(layer "B.Cu")
		(net "PVDD11_S3_P0_EN")
	)
	(segment
		(start 420.410894 -366.498124)
		(end 420.12616 -366.21339)
		(width 0.10668)
		(layer "B.Cu")
		(net "PVDD11_S3_P0_EN")
	)
	(segment
		(start 448.63893 -146.782536)
		(end 448.63893 -177.380138)
		(width 0.10668)
		(layer "B.Cu")
		(net "PVDD11_S3_P0_EN")
	)
	(segment
		(start 446.24879 -363.625638)
		(end 444.028576 -365.845852)
		(width 0.10668)
		(layer "B.Cu")
		(net "PVDD11_S3_P0_EN")
	)
	(segment
		(start 459.28153 -323.71792)
		(end 454.332086 -328.667364)
		(width 0.10668)
		(layer "B.Cu")
		(net "PVDD11_S3_P0_EN")
	)
	(segment
		(start 382.517396 -119.541544)
		(end 383.303018 -118.755922)
		(width 0.10668)
		(layer "B.Cu")
		(net "PVDD11_S3_P0_EN")
	)
	(segment
		(start 430.808892 -366.708182)
		(end 429.652684 -367.86439)
		(width 0.10668)
		(layer "B.Cu")
		(net "PVDD11_S3_P0_EN")
	)
	(segment
		(start 448.63893 -177.380138)
		(end 459.28153 -188.022738)
		(width 0.10668)
		(layer "B.Cu")
		(net "PVDD11_S3_P0_EN")
	)
	(segment
		(start 274.961096 -101.768148)
		(end 275.158454 -101.57079)
		(width 0.11684)
		(layer "In6.Cu")
		(net "PVDD11_S3_P0_EN")
	)
	(segment
		(start 203.142342 -104.610916)
		(end 214.147146 -104.610916)
		(width 0.11684)
		(layer "In6.Cu")
		(net "PVDD11_S3_P0_EN")
	)
	(segment
		(start 202.255882 -105.497376)
		(end 203.142342 -104.610916)
		(width 0.11684)
		(layer "In6.Cu")
		(net "PVDD11_S3_P0_EN")
	)
	(segment
		(start 312.96102 -101.57079)
		(end 322.509642 -111.119412)
		(width 0.11684)
		(layer "In6.Cu")
		(net "PVDD11_S3_P0_EN")
	)
	(segment
		(start 214.147146 -104.610916)
		(end 215.668352 -103.08971)
		(width 0.11684)
		(layer "In6.Cu")
		(net "PVDD11_S3_P0_EN")
	)
	(segment
		(start 374.53062 -111.554768)
		(end 382.517396 -119.541544)
		(width 0.11684)
		(layer "In6.Cu")
		(net "PVDD11_S3_P0_EN")
	)
	(segment
		(start 275.158454 -101.57079)
		(end 312.96102 -101.57079)
		(width 0.11684)
		(layer "In6.Cu")
		(net "PVDD11_S3_P0_EN")
	)
	(segment
		(start 369.63858 -111.554768)
		(end 374.53062 -111.554768)
		(width 0.11684)
		(layer "In6.Cu")
		(net "PVDD11_S3_P0_EN")
	)
	(segment
		(start 215.668352 -103.08971)
		(end 254.839216 -103.08971)
		(width 0.11684)
		(layer "In6.Cu")
		(net "PVDD11_S3_P0_EN")
	)
	(segment
		(start 322.509642 -111.119412)
		(end 369.203224 -111.119412)
		(width 0.11684)
		(layer "In6.Cu")
		(net "PVDD11_S3_P0_EN")
	)
	(segment
		(start 256.160778 -101.768148)
		(end 274.961096 -101.768148)
		(width 0.11684)
		(layer "In6.Cu")
		(net "PVDD11_S3_P0_EN")
	)
	(segment
		(start 254.839216 -103.08971)
		(end 256.160778 -101.768148)
		(width 0.11684)
		(layer "In6.Cu")
		(net "PVDD11_S3_P0_EN")
	)
	(segment
		(start 369.203224 -111.119412)
		(end 369.63858 -111.554768)
		(width 0.11684)
		(layer "In6.Cu")
		(net "PVDD11_S3_P0_EN")
	)
	(segment
		(start 421.317928 -361.487466)
		(end 421.748458 -361.487466)
		(width 0.1524)
		(layer "F.Cu")
		(net "PVDD11_S3_P0_ADDR_CFG")
	)
	(segment
		(start 422.599358 -361.078272)
		(end 422.853612 -360.824018)
		(width 0.1524)
		(layer "F.Cu")
		(net "PVDD11_S3_P0_ADDR_CFG")
	)
	(segment
		(start 421.748458 -361.487466)
		(end 422.157652 -361.078272)
		(width 0.1524)
		(layer "F.Cu")
		(net "PVDD11_S3_P0_ADDR_CFG")
	)
	(segment
		(start 422.853612 -360.824018)
		(end 423.231818 -360.824018)
		(width 0.1524)
		(layer "F.Cu")
		(net "PVDD11_S3_P0_ADDR_CFG")
	)
	(segment
		(start 422.157652 -361.078272)
		(end 422.599358 -361.078272)
		(width 0.1524)
		(layer "F.Cu")
		(net "PVDD11_S3_P0_ADDR_CFG")
	)
	(via
		(at 422.599358 -361.078272)
		(size 0.508)
		(drill 0.254)
		(layers "F.Cu" "B.Cu")
		(net "PVDD11_S3_P0_ADDR_CFG")
	)
	(segment
		(start 391.03808 -275.44014)
		(end 391.504678 -275.706078)
		(width 0.350012)
		(layer "F.Cu")
		(net "PVDD11_S3_P0")
	)
	(segment
		(start 423.751756 -129.487676)
		(end 427.126654 -132.862574)
		(width 0.508)
		(layer "F.Cu")
		(net "PVDD11_S3_P0")
	)
	(segment
		(start 384.927856 -292.450012)
		(end 385.394708 -292.71595)
		(width 0.350012)
		(layer "F.Cu")
		(net "PVDD11_S3_P0")
	)
	(segment
		(start 375.057924 -273.820128)
		(end 375.524776 -274.086066)
		(width 0.350012)
		(layer "F.Cu")
		(net "PVDD11_S3_P0")
	)
	(segment
		(start 375.057924 -285.160212)
		(end 375.524776 -285.42615)
		(width 0.350012)
		(layer "F.Cu")
		(net "PVDD11_S3_P0")
	)
	(segment
		(start 375.057924 -265.720068)
		(end 375.524776 -265.986006)
		(width 0.350012)
		(layer "F.Cu")
		(net "PVDD11_S3_P0")
	)
	(segment
		(start 354.847906 -266.530074)
		(end 354.381054 -266.796012)
		(width 0.350012)
		(layer "F.Cu")
		(net "PVDD11_S3_P0")
	)
	(segment
		(start 375.057924 -277.060152)
		(end 375.524776 -277.32609)
		(width 0.350012)
		(layer "F.Cu")
		(net "PVDD11_S3_P0")
	)
	(segment
		(start 378.347986 -282.730194)
		(end 378.814838 -282.996132)
		(width 0.350012)
		(layer "F.Cu")
		(net "PVDD11_S3_P0")
	)
	(segment
		(start 378.347986 -277.870158)
		(end 378.814838 -278.136096)
		(width 0.350012)
		(layer "F.Cu")
		(net "PVDD11_S3_P0")
	)
	(segment
		(start 375.057924 -288.399982)
		(end 375.524776 -288.66592)
		(width 0.350012)
		(layer "F.Cu")
		(net "PVDD11_S3_P0")
	)
	(segment
		(start 391.03808 -285.160212)
		(end 391.504678 -285.42615)
		(width 0.350012)
		(layer "F.Cu")
		(net "PVDD11_S3_P0")
	)
	(segment
		(start 375.057924 -270.580104)
		(end 375.524776 -270.846042)
		(width 0.350012)
		(layer "F.Cu")
		(net "PVDD11_S3_P0")
	)
	(segment
		(start 358.607868 -266.530074)
		(end 358.141016 -266.796012)
		(width 0.350012)
		(layer "F.Cu")
		(net "PVDD11_S3_P0")
	)
	(segment
		(start 373.64797 -264.910062)
		(end 374.114822 -265.176)
		(width 0.350012)
		(layer "F.Cu")
		(net "PVDD11_S3_P0")
	)
	(segment
		(start 390.567926 -294.070024)
		(end 391.034778 -294.335962)
		(width 0.350012)
		(layer "F.Cu")
		(net "PVDD11_S3_P0")
	)
	(segment
		(start 371.297962 -264.100056)
		(end 371.764814 -264.365994)
		(width 0.350012)
		(layer "F.Cu")
		(net "PVDD11_S3_P0")
	)
	(segment
		(start 391.50798 -287.59023)
		(end 391.974832 -287.856168)
		(width 0.350012)
		(layer "F.Cu")
		(net "PVDD11_S3_P0")
	)
	(segment
		(start 391.03808 -290.019994)
		(end 391.504678 -290.285932)
		(width 0.350012)
		(layer "F.Cu")
		(net "PVDD11_S3_P0")
	)
	(segment
		(start 351.087944 -264.910062)
		(end 350.621092 -265.176)
		(width 0.350012)
		(layer "F.Cu")
		(net "PVDD11_S3_P0")
	)
	(segment
		(start 322.326 -179.41163)
		(end 322.326 -193.56705)
		(width 0.381)
		(layer "F.Cu")
		(net "PVDD11_S3_P0")
	)
	(segment
		(start 445.842898 -331.327252)
		(end 447.269616 -331.327252)
		(width 0.508)
		(layer "F.Cu")
		(net "PVDD11_S3_P0")
	)
	(segment
		(start 308.442106 -148.053044)
		(end 313.69 -153.300938)
		(width 0.381)
		(layer "F.Cu")
		(net "PVDD11_S3_P0")
	)
	(segment
		(start 357.197914 -265.720068)
		(end 356.731062 -265.986006)
		(width 0.350012)
		(layer "F.Cu")
		(net "PVDD11_S3_P0")
	)
	(segment
		(start 378.347986 -292.450012)
		(end 378.814838 -292.71595)
		(width 0.350012)
		(layer "F.Cu")
		(net "PVDD11_S3_P0")
	)
	(segment
		(start 378.347986 -287.59023)
		(end 378.814838 -287.856168)
		(width 0.350012)
		(layer "F.Cu")
		(net "PVDD11_S3_P0")
	)
	(segment
		(start 364.247938 -266.530074)
		(end 364.71479 -266.796012)
		(width 0.350012)
		(layer "F.Cu")
		(net "PVDD11_S3_P0")
	)
	(segment
		(start 443.352936 -168.911016)
		(end 443.352936 -169.726864)
		(width 0.508)
		(layer "F.Cu")
		(net "PVDD11_S3_P0")
	)
	(segment
		(start 353.437952 -265.720068)
		(end 352.9711 -265.986006)
		(width 0.350012)
		(layer "F.Cu")
		(net "PVDD11_S3_P0")
	)
	(segment
		(start 306.2986 -147.940522)
		(end 308.329584 -147.940522)
		(width 0.508)
		(layer "F.Cu")
		(net "PVDD11_S3_P0")
	)
	(segment
		(start 406.633172 -132.508752)
		(end 409.654248 -129.487676)
		(width 0.508)
		(layer "F.Cu")
		(net "PVDD11_S3_P0")
	)
	(segment
		(start 384.457956 -265.720068)
		(end 384.924808 -265.986006)
		(width 0.350012)
		(layer "F.Cu")
		(net "PVDD11_S3_P0")
	)
	(segment
		(start 378.347986 -273.010122)
		(end 378.814838 -273.27606)
		(width 0.350012)
		(layer "F.Cu")
		(net "PVDD11_S3_P0")
	)
	(segment
		(start 313.69 -153.300938)
		(end 313.69 -170.77563)
		(width 0.381)
		(layer "F.Cu")
		(net "PVDD11_S3_P0")
	)
	(segment
		(start 369.417854 -265.720068)
		(end 369.884706 -265.986006)
		(width 0.350012)
		(layer "F.Cu")
		(net "PVDD11_S3_P0")
	)
	(segment
		(start 384.927856 -273.010122)
		(end 385.394708 -273.27606)
		(width 0.350012)
		(layer "F.Cu")
		(net "PVDD11_S3_P0")
	)
	(segment
		(start 428.255176 -149.782276)
		(end 428.255176 -164.677852)
		(width 0.508)
		(layer "F.Cu")
		(net "PVDD11_S3_P0")
	)
	(segment
		(start 313.69 -170.77563)
		(end 322.326 -179.41163)
		(width 0.381)
		(layer "F.Cu")
		(net "PVDD11_S3_P0")
	)
	(segment
		(start 449.979034 -328.782172)
		(end 453.711818 -328.782172)
		(width 0.508)
		(layer "F.Cu")
		(net "PVDD11_S3_P0")
	)
	(segment
		(start 373.64797 -263.29005)
		(end 374.114822 -263.555988)
		(width 0.350012)
		(layer "F.Cu")
		(net "PVDD11_S3_P0")
	)
	(segment
		(start 355.31806 -265.720068)
		(end 354.851208 -265.986006)
		(width 0.350012)
		(layer "F.Cu")
		(net "PVDD11_S3_P0")
	)
	(segment
		(start 369.888008 -264.910062)
		(end 370.35486 -265.176)
		(width 0.350012)
		(layer "F.Cu")
		(net "PVDD11_S3_P0")
	)
	(segment
		(start 296.170604 -169.927524)
		(end 297.334432 -169.927524)
		(width 0.508)
		(layer "F.Cu")
		(net "PVDD11_S3_P0")
	)
	(segment
		(start 391.50798 -277.870158)
		(end 391.974832 -278.136096)
		(width 0.350012)
		(layer "F.Cu")
		(net "PVDD11_S3_P0")
	)
	(segment
		(start 434.278786 -168.208452)
		(end 434.278786 -169.224452)
		(width 0.508)
		(layer "F.Cu")
		(net "PVDD11_S3_P0")
	)
	(segment
		(start 384.927856 -277.870158)
		(end 385.394708 -278.136096)
		(width 0.350012)
		(layer "F.Cu")
		(net "PVDD11_S3_P0")
	)
	(segment
		(start 375.057924 -264.100056)
		(end 375.524776 -264.365994)
		(width 0.350012)
		(layer "F.Cu")
		(net "PVDD11_S3_P0")
	)
	(segment
		(start 446.909444 -169.726864)
		(end 443.352936 -169.726864)
		(width 0.508)
		(layer "F.Cu")
		(net "PVDD11_S3_P0")
	)
	(segment
		(start 409.654248 -129.487676)
		(end 423.751756 -129.487676)
		(width 0.508)
		(layer "F.Cu")
		(net "PVDD11_S3_P0")
	)
	(segment
		(start 456.949556 -325.544434)
		(end 460.127604 -325.544434)
		(width 0.508)
		(layer "F.Cu")
		(net "PVDD11_S3_P0")
	)
	(segment
		(start 391.03808 -270.580104)
		(end 391.504678 -270.846042)
		(width 0.350012)
		(layer "F.Cu")
		(net "PVDD11_S3_P0")
	)
	(segment
		(start 455.39533 -173.618144)
		(end 450.800724 -173.618144)
		(width 0.508)
		(layer "F.Cu")
		(net "PVDD11_S3_P0")
	)
	(segment
		(start 317.94196 -180.814726)
		(end 317.94196 -193.960242)
		(width 0.381)
		(layer "F.Cu")
		(net "PVDD11_S3_P0")
	)
	(segment
		(start 447.550032 -331.211174)
		(end 449.979034 -328.782172)
		(width 0.508)
		(layer "F.Cu")
		(net "PVDD11_S3_P0")
	)
	(segment
		(start 377.878086 -265.720068)
		(end 378.344938 -265.986006)
		(width 0.350012)
		(layer "F.Cu")
		(net "PVDD11_S3_P0")
	)
	(segment
		(start 374.588024 -279.49017)
		(end 375.054876 -279.756108)
		(width 0.350012)
		(layer "F.Cu")
		(net "PVDD11_S3_P0")
	)
	(segment
		(start 384.457956 -285.160212)
		(end 384.924808 -285.42615)
		(width 0.350012)
		(layer "F.Cu")
		(net "PVDD11_S3_P0")
	)
	(segment
		(start 447.269616 -331.327252)
		(end 447.550032 -331.211174)
		(width 0.508)
		(layer "F.Cu")
		(net "PVDD11_S3_P0")
	)
	(segment
		(start 369.888008 -263.29005)
		(end 370.35486 -263.555988)
		(width 0.350012)
		(layer "F.Cu")
		(net "PVDD11_S3_P0")
	)
	(segment
		(start 391.50798 -282.730194)
		(end 391.974832 -282.996132)
		(width 0.350012)
		(layer "F.Cu")
		(net "PVDD11_S3_P0")
	)
	(segment
		(start 384.457956 -280.300176)
		(end 384.924808 -280.566114)
		(width 0.350012)
		(layer "F.Cu")
		(net "PVDD11_S3_P0")
	)
	(segment
		(start 377.878086 -290.019994)
		(end 378.344938 -290.285932)
		(width 0.350012)
		(layer "F.Cu")
		(net "PVDD11_S3_P0")
	)
	(segment
		(start 377.878086 -280.300176)
		(end 378.344938 -280.566114)
		(width 0.350012)
		(layer "F.Cu")
		(net "PVDD11_S3_P0")
	)
	(segment
		(start 427.126654 -132.862574)
		(end 427.126654 -147.057618)
		(width 0.508)
		(layer "F.Cu")
		(net "PVDD11_S3_P0")
	)
	(segment
		(start 351.087944 -266.530074)
		(end 350.621092 -266.796012)
		(width 0.350012)
		(layer "F.Cu")
		(net "PVDD11_S3_P0")
	)
	(segment
		(start 351.557844 -265.720068)
		(end 351.091246 -265.986006)
		(width 0.350012)
		(layer "F.Cu")
		(net "PVDD11_S3_P0")
	)
	(segment
		(start 384.457956 -270.580104)
		(end 384.924808 -270.846042)
		(width 0.350012)
		(layer "F.Cu")
		(net "PVDD11_S3_P0")
	)
	(segment
		(start 363.778038 -265.720068)
		(end 364.24489 -265.986006)
		(width 0.350012)
		(layer "F.Cu")
		(net "PVDD11_S3_P0")
	)
	(segment
		(start 377.878086 -285.160212)
		(end 378.344938 -285.42615)
		(width 0.350012)
		(layer "F.Cu")
		(net "PVDD11_S3_P0")
	)
	(segment
		(start 391.50798 -292.450012)
		(end 391.974832 -292.71595)
		(width 0.350012)
		(layer "F.Cu")
		(net "PVDD11_S3_P0")
	)
	(segment
		(start 296.930318 -148.493988)
		(end 296.930318 -147.488148)
		(width 0.508)
		(layer "F.Cu")
		(net "PVDD11_S3_P0")
	)
	(segment
		(start 431.785776 -168.208452)
		(end 434.278786 -168.208452)
		(width 0.508)
		(layer "F.Cu")
		(net "PVDD11_S3_P0")
	)
	(segment
		(start 371.767862 -266.530074)
		(end 372.234714 -266.796012)
		(width 0.350012)
		(layer "F.Cu")
		(net "PVDD11_S3_P0")
	)
	(segment
		(start 371.297962 -265.720068)
		(end 371.764814 -265.986006)
		(width 0.350012)
		(layer "F.Cu")
		(net "PVDD11_S3_P0")
	)
	(segment
		(start 444.024258 -333.145892)
		(end 445.842898 -331.327252)
		(width 0.508)
		(layer "F.Cu")
		(net "PVDD11_S3_P0")
	)
	(segment
		(start 359.078022 -265.720068)
		(end 358.61117 -265.986006)
		(width 0.350012)
		(layer "F.Cu")
		(net "PVDD11_S3_P0")
	)
	(segment
		(start 442.633608 -168.710864)
		(end 443.152784 -168.710864)
		(width 0.508)
		(layer "F.Cu")
		(net "PVDD11_S3_P0")
	)
	(segment
		(start 427.126654 -147.057618)
		(end 428.255176 -149.782276)
		(width 0.508)
		(layer "F.Cu")
		(net "PVDD11_S3_P0")
	)
	(segment
		(start 373.17807 -264.100056)
		(end 373.644922 -264.365994)
		(width 0.350012)
		(layer "F.Cu")
		(net "PVDD11_S3_P0")
	)
	(segment
		(start 384.927856 -282.730194)
		(end 385.394708 -282.996132)
		(width 0.350012)
		(layer "F.Cu")
		(net "PVDD11_S3_P0")
	)
	(segment
		(start 296.915078 -147.472908)
		(end 296.197274 -147.472908)
		(width 0.508)
		(layer "F.Cu")
		(net "PVDD11_S3_P0")
	)
	(segment
		(start 305.482498 -149.210522)
		(end 305.482498 -147.940522)
		(width 0.508)
		(layer "F.Cu")
		(net "PVDD11_S3_P0")
	)
	(segment
		(start 371.767862 -264.910062)
		(end 372.234714 -265.176)
		(width 0.350012)
		(layer "F.Cu")
		(net "PVDD11_S3_P0")
	)
	(segment
		(start 318.291718 -194.31)
		(end 319.00495 -194.31)
		(width 0.381)
		(layer "F.Cu")
		(net "PVDD11_S3_P0")
	)
	(segment
		(start 349.67799 -265.720068)
		(end 349.211138 -265.986006)
		(width 0.350012)
		(layer "F.Cu")
		(net "PVDD11_S3_P0")
	)
	(segment
		(start 365.657892 -265.720068)
		(end 366.124744 -265.986006)
		(width 0.350012)
		(layer "F.Cu")
		(net "PVDD11_S3_P0")
	)
	(segment
		(start 312.006488 -174.879254)
		(end 317.94196 -180.814726)
		(width 0.381)
		(layer "F.Cu")
		(net "PVDD11_S3_P0")
	)
	(segment
		(start 453.711818 -328.782172)
		(end 456.949556 -325.544434)
		(width 0.508)
		(layer "F.Cu")
		(net "PVDD11_S3_P0")
	)
	(segment
		(start 391.50798 -273.010122)
		(end 391.974832 -273.27606)
		(width 0.350012)
		(layer "F.Cu")
		(net "PVDD11_S3_P0")
	)
	(segment
		(start 384.927856 -287.59023)
		(end 385.394708 -287.856168)
		(width 0.350012)
		(layer "F.Cu")
		(net "PVDD11_S3_P0")
	)
	(segment
		(start 384.457956 -275.44014)
		(end 384.924808 -275.706078)
		(width 0.350012)
		(layer "F.Cu")
		(net "PVDD11_S3_P0")
	)
	(segment
		(start 371.767862 -263.29005)
		(end 372.234714 -263.555988)
		(width 0.350012)
		(layer "F.Cu")
		(net "PVDD11_S3_P0")
	)
	(segment
		(start 367.538 -265.720068)
		(end 368.004852 -265.986006)
		(width 0.350012)
		(layer "F.Cu")
		(net "PVDD11_S3_P0")
	)
	(segment
		(start 361.89793 -265.720068)
		(end 362.364782 -265.986006)
		(width 0.350012)
		(layer "F.Cu")
		(net "PVDD11_S3_P0")
	)
	(segment
		(start 308.329584 -147.940522)
		(end 308.442106 -148.053044)
		(width 0.508)
		(layer "F.Cu")
		(net "PVDD11_S3_P0")
	)
	(segment
		(start 305.482498 -147.940522)
		(end 306.2986 -147.940522)
		(width 0.508)
		(layer "F.Cu")
		(net "PVDD11_S3_P0")
	)
	(segment
		(start 296.930318 -147.488148)
		(end 296.915078 -147.472908)
		(width 0.508)
		(layer "F.Cu")
		(net "PVDD11_S3_P0")
	)
	(segment
		(start 369.417854 -264.100056)
		(end 369.884706 -264.365994)
		(width 0.350012)
		(layer "F.Cu")
		(net "PVDD11_S3_P0")
	)
	(segment
		(start 384.457956 -290.019994)
		(end 384.924808 -290.285932)
		(width 0.350012)
		(layer "F.Cu")
		(net "PVDD11_S3_P0")
	)
	(segment
		(start 391.50798 -268.150086)
		(end 391.974832 -268.416024)
		(width 0.350012)
		(layer "F.Cu")
		(net "PVDD11_S3_P0")
	)
	(segment
		(start 434.278786 -169.224452)
		(end 434.278786 -170.236134)
		(width 0.508)
		(layer "F.Cu")
		(net "PVDD11_S3_P0")
	)
	(segment
		(start 322.326 -193.56705)
		(end 321.58305 -194.31)
		(width 0.381)
		(layer "F.Cu")
		(net "PVDD11_S3_P0")
	)
	(segment
		(start 375.057924 -281.920188)
		(end 375.524776 -282.186126)
		(width 0.350012)
		(layer "F.Cu")
		(net "PVDD11_S3_P0")
	)
	(segment
		(start 450.800724 -173.618144)
		(end 446.909444 -169.726864)
		(width 0.508)
		(layer "F.Cu")
		(net "PVDD11_S3_P0")
	)
	(segment
		(start 391.03808 -280.300176)
		(end 391.504678 -280.566114)
		(width 0.350012)
		(layer "F.Cu")
		(net "PVDD11_S3_P0")
	)
	(segment
		(start 378.347986 -263.29005)
		(end 378.814838 -263.555988)
		(width 0.350012)
		(layer "F.Cu")
		(net "PVDD11_S3_P0")
	)
	(segment
		(start 378.347986 -268.150086)
		(end 378.814838 -268.416024)
		(width 0.350012)
		(layer "F.Cu")
		(net "PVDD11_S3_P0")
	)
	(segment
		(start 384.927856 -268.150086)
		(end 385.394708 -268.416024)
		(width 0.350012)
		(layer "F.Cu")
		(net "PVDD11_S3_P0")
	)
	(segment
		(start 349.67799 -264.100056)
		(end 349.211138 -264.365994)
		(width 0.350012)
		(layer "F.Cu")
		(net "PVDD11_S3_P0")
	)
	(segment
		(start 297.334432 -169.927524)
		(end 312.774838 -185.36793)
		(width 0.508)
		(layer "F.Cu")
		(net "PVDD11_S3_P0")
	)
	(segment
		(start 373.17807 -265.720068)
		(end 373.644922 -265.986006)
		(width 0.350012)
		(layer "F.Cu")
		(net "PVDD11_S3_P0")
	)
	(segment
		(start 377.878086 -275.44014)
		(end 378.344938 -275.706078)
		(width 0.350012)
		(layer "F.Cu")
		(net "PVDD11_S3_P0")
	)
	(segment
		(start 375.057924 -267.34008)
		(end 375.524776 -267.606018)
		(width 0.350012)
		(layer "F.Cu")
		(net "PVDD11_S3_P0")
	)
	(segment
		(start 317.94196 -193.960242)
		(end 318.291718 -194.31)
		(width 0.381)
		(layer "F.Cu")
		(net "PVDD11_S3_P0")
	)
	(segment
		(start 428.255176 -164.677852)
		(end 431.785776 -168.208452)
		(width 0.508)
		(layer "F.Cu")
		(net "PVDD11_S3_P0")
	)
	(segment
		(start 442.633608 -169.726864)
		(end 443.352936 -169.726864)
		(width 0.508)
		(layer "F.Cu")
		(net "PVDD11_S3_P0")
	)
	(segment
		(start 377.878086 -270.580104)
		(end 378.344938 -270.846042)
		(width 0.350012)
		(layer "F.Cu")
		(net "PVDD11_S3_P0")
	)
	(segment
		(start 443.152784 -168.710864)
		(end 443.352936 -168.911016)
		(width 0.508)
		(layer "F.Cu")
		(net "PVDD11_S3_P0")
	)
	(segment
		(start 368.0079 -266.530074)
		(end 368.474752 -266.796012)
		(width 0.350012)
		(layer "F.Cu")
		(net "PVDD11_S3_P0")
	)
	(segment
		(start 312.774838 -185.36793)
		(end 312.774838 -195.495418)
		(width 0.508)
		(layer "F.Cu")
		(net "PVDD11_S3_P0")
	)
	(via
		(at 372.234714 -266.796012)
		(size 0.4064)
		(drill 0.2032)
		(layers "F.Cu" "B.Cu")
		(net "PVDD11_S3_P0")
	)
	(via
		(at 306.2986 -147.940522)
		(size 0.508)
		(drill 0.254)
		(layers "F.Cu" "B.Cu")
		(net "PVDD11_S3_P0")
	)
	(via
		(at 391.974832 -292.71595)
		(size 0.4064)
		(drill 0.2032)
		(layers "F.Cu" "B.Cu")
		(net "PVDD11_S3_P0")
	)
	(via
		(at 422.512998 -338.385404)
		(size 0.508)
		(drill 0.254)
		(layers "F.Cu" "B.Cu")
		(net "PVDD11_S3_P0")
	)
	(via
		(at 406.633172 -132.508752)
		(size 0.508)
		(drill 0.254)
		(layers "F.Cu" "B.Cu")
		(net "PVDD11_S3_P0")
	)
	(via
		(at 375.524776 -274.086066)
		(size 0.4064)
		(drill 0.2032)
		(layers "F.Cu" "B.Cu")
		(net "PVDD11_S3_P0")
	)
	(via
		(at 425.509436 -336.935826)
		(size 0.508)
		(drill 0.254)
		(layers "F.Cu" "B.Cu")
		(net "PVDD11_S3_P0")
	)
	(via
		(at 385.394708 -287.856168)
		(size 0.4064)
		(drill 0.2032)
		(layers "F.Cu" "B.Cu")
		(net "PVDD11_S3_P0")
	)
	(via
		(at 425.442888 -334.476598)
		(size 0.508)
		(drill 0.254)
		(layers "F.Cu" "B.Cu")
		(net "PVDD11_S3_P0")
	)
	(via
		(at 384.924808 -290.285932)
		(size 0.4064)
		(drill 0.2032)
		(layers "F.Cu" "B.Cu")
		(net "PVDD11_S3_P0")
	)
	(via
		(at 421.785288 -335.238598)
		(size 0.508)
		(drill 0.254)
		(layers "F.Cu" "B.Cu")
		(net "PVDD11_S3_P0")
	)
	(via
		(at 424.846242 -337.737704)
		(size 0.508)
		(drill 0.254)
		(layers "F.Cu" "B.Cu")
		(net "PVDD11_S3_P0")
	)
	(via
		(at 437.558688 -334.324198)
		(size 0.508)
		(drill 0.254)
		(layers "F.Cu" "B.Cu")
		(net "PVDD11_S3_P0")
	)
	(via
		(at 427.906688 -335.238598)
		(size 0.508)
		(drill 0.254)
		(layers "F.Cu" "B.Cu")
		(net "PVDD11_S3_P0")
	)
	(via
		(at 356.728014 -264.368026)
		(size 0.4064)
		(drill 0.2032)
		(layers "F.Cu" "B.Cu")
		(net "PVDD11_S3_P0")
	)
	(via
		(at 421.80129 -338.243164)
		(size 0.508)
		(drill 0.254)
		(layers "F.Cu" "B.Cu")
		(net "PVDD11_S3_P0")
	)
	(via
		(at 362.364782 -265.986006)
		(size 0.4064)
		(drill 0.2032)
		(layers "F.Cu" "B.Cu")
		(net "PVDD11_S3_P0")
	)
	(via
		(at 375.524776 -288.66592)
		(size 0.4064)
		(drill 0.2032)
		(layers "F.Cu" "B.Cu")
		(net "PVDD11_S3_P0")
	)
	(via
		(at 437.558688 -335.848198)
		(size 0.508)
		(drill 0.254)
		(layers "F.Cu" "B.Cu")
		(net "PVDD11_S3_P0")
	)
	(via
		(at 433.810664 -338.282026)
		(size 0.508)
		(drill 0.254)
		(layers "F.Cu" "B.Cu")
		(net "PVDD11_S3_P0")
	)
	(via
		(at 433.836064 -336.961226)
		(size 0.508)
		(drill 0.254)
		(layers "F.Cu" "B.Cu")
		(net "PVDD11_S3_P0")
	)
	(via
		(at 433.167282 -338.372704)
		(size 0.508)
		(drill 0.254)
		(layers "F.Cu" "B.Cu")
		(net "PVDD11_S3_P0")
	)
	(via
		(at 421.80129 -338.878164)
		(size 0.508)
		(drill 0.254)
		(layers "F.Cu" "B.Cu")
		(net "PVDD11_S3_P0")
	)
	(via
		(at 421.80129 -339.513164)
		(size 0.508)
		(drill 0.254)
		(layers "F.Cu" "B.Cu")
		(net "PVDD11_S3_P0")
	)
	(via
		(at 436.218584 -339.485986)
		(size 0.508)
		(drill 0.254)
		(layers "F.Cu" "B.Cu")
		(net "PVDD11_S3_P0")
	)
	(via
		(at 421.13581 -338.827364)
		(size 0.508)
		(drill 0.254)
		(layers "F.Cu" "B.Cu")
		(net "PVDD11_S3_P0")
	)
	(via
		(at 378.344938 -290.285932)
		(size 0.4064)
		(drill 0.2032)
		(layers "F.Cu" "B.Cu")
		(net "PVDD11_S3_P0")
	)
	(via
		(at 358.437942 -262.23722)
		(size 0.4826)
		(drill 0.254)
		(layers "F.Cu" "B.Cu")
		(net "PVDD11_S3_P0")
	)
	(via
		(at 374.114822 -265.176)
		(size 0.4064)
		(drill 0.2032)
		(layers "F.Cu" "B.Cu")
		(net "PVDD11_S3_P0")
	)
	(via
		(at 296.170604 -169.927524)
		(size 0.508)
		(drill 0.254)
		(layers "F.Cu" "B.Cu")
		(net "PVDD11_S3_P0")
	)
	(via
		(at 352.968052 -264.368026)
		(size 0.4064)
		(drill 0.2032)
		(layers "F.Cu" "B.Cu")
		(net "PVDD11_S3_P0")
	)
	(via
		(at 426.149516 -338.205826)
		(size 0.508)
		(drill 0.254)
		(layers "F.Cu" "B.Cu")
		(net "PVDD11_S3_P0")
	)
	(via
		(at 440.106308 -335.027778)
		(size 0.508)
		(drill 0.254)
		(layers "F.Cu" "B.Cu")
		(net "PVDD11_S3_P0")
	)
	(via
		(at 420.340282 -354.896674)
		(size 0.508)
		(drill 0.254)
		(layers "F.Cu" "B.Cu")
		(net "PVDD11_S3_P0")
	)
	(via
		(at 378.344938 -275.706078)
		(size 0.4064)
		(drill 0.2032)
		(layers "F.Cu" "B.Cu")
		(net "PVDD11_S3_P0")
	)
	(via
		(at 419.372288 -333.790798)
		(size 0.508)
		(drill 0.254)
		(layers "F.Cu" "B.Cu")
		(net "PVDD11_S3_P0")
	)
	(via
		(at 360.337862 -262.23722)
		(size 0.4826)
		(drill 0.254)
		(layers "F.Cu" "B.Cu")
		(net "PVDD11_S3_P0")
	)
	(via
		(at 358.61117 -265.986006)
		(size 0.4064)
		(drill 0.2032)
		(layers "F.Cu" "B.Cu")
		(net "PVDD11_S3_P0")
	)
	(via
		(at 385.394708 -273.27606)
		(size 0.4064)
		(drill 0.2032)
		(layers "F.Cu" "B.Cu")
		(net "PVDD11_S3_P0")
	)
	(via
		(at 430.795938 -337.737704)
		(size 0.508)
		(drill 0.254)
		(layers "F.Cu" "B.Cu")
		(net "PVDD11_S3_P0")
	)
	(via
		(at 434.002688 -335.213198)
		(size 0.508)
		(drill 0.254)
		(layers "F.Cu" "B.Cu")
		(net "PVDD11_S3_P0")
	)
	(via
		(at 248.038112 -204.099414)
		(size 0.508)
		(drill 0.254)
		(layers "F.Cu" "B.Cu")
		(net "PVDD11_S3_P0")
	)
	(via
		(at 425.484036 -338.256626)
		(size 0.508)
		(drill 0.254)
		(layers "F.Cu" "B.Cu")
		(net "PVDD11_S3_P0")
	)
	(via
		(at 248.038112 -204.734414)
		(size 0.508)
		(drill 0.254)
		(layers "F.Cu" "B.Cu")
		(net "PVDD11_S3_P0")
	)
	(via
		(at 430.795938 -338.372704)
		(size 0.508)
		(drill 0.254)
		(layers "F.Cu" "B.Cu")
		(net "PVDD11_S3_P0")
	)
	(via
		(at 430.127918 -337.633564)
		(size 0.508)
		(drill 0.254)
		(layers "F.Cu" "B.Cu")
		(net "PVDD11_S3_P0")
	)
	(via
		(at 436.218584 -337.580986)
		(size 0.508)
		(drill 0.254)
		(layers "F.Cu" "B.Cu")
		(net "PVDD11_S3_P0")
	)
	(via
		(at 433.167282 -336.950304)
		(size 0.508)
		(drill 0.254)
		(layers "F.Cu" "B.Cu")
		(net "PVDD11_S3_P0")
	)
	(via
		(at 431.564288 -334.451198)
		(size 0.508)
		(drill 0.254)
		(layers "F.Cu" "B.Cu")
		(net "PVDD11_S3_P0")
	)
	(via
		(at 425.442888 -336.000598)
		(size 0.508)
		(drill 0.254)
		(layers "F.Cu" "B.Cu")
		(net "PVDD11_S3_P0")
	)
	(via
		(at 434.002688 -334.451198)
		(size 0.508)
		(drill 0.254)
		(layers "F.Cu" "B.Cu")
		(net "PVDD11_S3_P0")
	)
	(via
		(at 434.278786 -170.236134)
		(size 0.508)
		(drill 0.254)
		(layers "F.Cu" "B.Cu")
		(net "PVDD11_S3_P0")
	)
	(via
		(at 433.167282 -339.007704)
		(size 0.508)
		(drill 0.254)
		(layers "F.Cu" "B.Cu")
		(net "PVDD11_S3_P0")
	)
	(via
		(at 427.906688 -334.476598)
		(size 0.508)
		(drill 0.254)
		(layers "F.Cu" "B.Cu")
		(net "PVDD11_S3_P0")
	)
	(via
		(at 460.127604 -325.544434)
		(size 0.508)
		(drill 0.254)
		(layers "F.Cu" "B.Cu")
		(net "PVDD11_S3_P0")
	)
	(via
		(at 391.974832 -287.856168)
		(size 0.4064)
		(drill 0.2032)
		(layers "F.Cu" "B.Cu")
		(net "PVDD11_S3_P0")
	)
	(via
		(at 425.442888 -335.238598)
		(size 0.508)
		(drill 0.254)
		(layers "F.Cu" "B.Cu")
		(net "PVDD11_S3_P0")
	)
	(via
		(at 419.372288 -334.552798)
		(size 0.508)
		(drill 0.254)
		(layers "F.Cu" "B.Cu")
		(net "PVDD11_S3_P0")
	)
	(via
		(at 375.524776 -264.365994)
		(size 0.4064)
		(drill 0.2032)
		(layers "F.Cu" "B.Cu")
		(net "PVDD11_S3_P0")
	)
	(via
		(at 434.476144 -338.866226)
		(size 0.508)
		(drill 0.254)
		(layers "F.Cu" "B.Cu")
		(net "PVDD11_S3_P0")
	)
	(via
		(at 349.211138 -264.365994)
		(size 0.4064)
		(drill 0.2032)
		(layers "F.Cu" "B.Cu")
		(net "PVDD11_S3_P0")
	)
	(via
		(at 378.344938 -280.566114)
		(size 0.4064)
		(drill 0.2032)
		(layers "F.Cu" "B.Cu")
		(net "PVDD11_S3_P0")
	)
	(via
		(at 363.207808 -259.845048)
		(size 0.4826)
		(drill 0.254)
		(layers "F.Cu" "B.Cu")
		(net "PVDD11_S3_P0")
	)
	(via
		(at 430.795938 -336.950304)
		(size 0.508)
		(drill 0.254)
		(layers "F.Cu" "B.Cu")
		(net "PVDD11_S3_P0")
	)
	(via
		(at 431.564288 -335.213198)
		(size 0.508)
		(drill 0.254)
		(layers "F.Cu" "B.Cu")
		(net "PVDD11_S3_P0")
	)
	(via
		(at 437.558688 -335.086198)
		(size 0.508)
		(drill 0.254)
		(layers "F.Cu" "B.Cu")
		(net "PVDD11_S3_P0")
	)
	(via
		(at 436.858664 -339.485986)
		(size 0.508)
		(drill 0.254)
		(layers "F.Cu" "B.Cu")
		(net "PVDD11_S3_P0")
	)
	(via
		(at 421.303958 -341.499952)
		(size 0.508)
		(drill 0.254)
		(layers "F.Cu" "B.Cu")
		(net "PVDD11_S3_P0")
	)
	(via
		(at 350.621092 -265.176)
		(size 0.4064)
		(drill 0.2032)
		(layers "F.Cu" "B.Cu")
		(net "PVDD11_S3_P0")
	)
	(via
		(at 366.124744 -265.986006)
		(size 0.4064)
		(drill 0.2032)
		(layers "F.Cu" "B.Cu")
		(net "PVDD11_S3_P0")
	)
	(via
		(at 391.974832 -278.136096)
		(size 0.4064)
		(drill 0.2032)
		(layers "F.Cu" "B.Cu")
		(net "PVDD11_S3_P0")
	)
	(via
		(at 364.71479 -266.796012)
		(size 0.4064)
		(drill 0.2032)
		(layers "F.Cu" "B.Cu")
		(net "PVDD11_S3_P0")
	)
	(via
		(at 375.524776 -270.846042)
		(size 0.4064)
		(drill 0.2032)
		(layers "F.Cu" "B.Cu")
		(net "PVDD11_S3_P0")
	)
	(via
		(at 427.906688 -333.714598)
		(size 0.508)
		(drill 0.254)
		(layers "F.Cu" "B.Cu")
		(net "PVDD11_S3_P0")
	)
	(via
		(at 428.557436 -341.384382)
		(size 0.508)
		(drill 0.254)
		(layers "F.Cu" "B.Cu")
		(net "PVDD11_S3_P0")
	)
	(via
		(at 391.974832 -273.27606)
		(size 0.4064)
		(drill 0.2032)
		(layers "F.Cu" "B.Cu")
		(net "PVDD11_S3_P0")
	)
	(via
		(at 429.437038 -336.947764)
		(size 0.508)
		(drill 0.254)
		(layers "F.Cu" "B.Cu")
		(net "PVDD11_S3_P0")
	)
	(via
		(at 430.127918 -338.903564)
		(size 0.508)
		(drill 0.254)
		(layers "F.Cu" "B.Cu")
		(net "PVDD11_S3_P0")
	)
	(via
		(at 232.918 -216.662)
		(size 0.508)
		(drill 0.254)
		(layers "F.Cu" "B.Cu")
		(net "PVDD11_S3_P0")
	)
	(via
		(at 351.091246 -265.986006)
		(size 0.4064)
		(drill 0.2032)
		(layers "F.Cu" "B.Cu")
		(net "PVDD11_S3_P0")
	)
	(via
		(at 390.982454 -298.64431)
		(size 0.508)
		(drill 0.254)
		(layers "F.Cu" "B.Cu")
		(net "PVDD11_S3_P0")
	)
	(via
		(at 421.13581 -338.192364)
		(size 0.508)
		(drill 0.254)
		(layers "F.Cu" "B.Cu")
		(net "PVDD11_S3_P0")
	)
	(via
		(at 426.149516 -337.570826)
		(size 0.508)
		(drill 0.254)
		(layers "F.Cu" "B.Cu")
		(net "PVDD11_S3_P0")
	)
	(via
		(at 391.034778 -294.335962)
		(size 0.4064)
		(drill 0.2032)
		(layers "F.Cu" "B.Cu")
		(net "PVDD11_S3_P0")
	)
	(via
		(at 385.394708 -292.71595)
		(size 0.4064)
		(drill 0.2032)
		(layers "F.Cu" "B.Cu")
		(net "PVDD11_S3_P0")
	)
	(via
		(at 384.924808 -270.846042)
		(size 0.4064)
		(drill 0.2032)
		(layers "F.Cu" "B.Cu")
		(net "PVDD11_S3_P0")
	)
	(via
		(at 238.76 -250.571)
		(size 0.508)
		(drill 0.254)
		(layers "F.Cu" "B.Cu")
		(net "PVDD11_S3_P0")
	)
	(via
		(at 385.394708 -278.136096)
		(size 0.4064)
		(drill 0.2032)
		(layers "F.Cu" "B.Cu")
		(net "PVDD11_S3_P0")
	)
	(via
		(at 378.814838 -292.71595)
		(size 0.4064)
		(drill 0.2032)
		(layers "F.Cu" "B.Cu")
		(net "PVDD11_S3_P0")
	)
	(via
		(at 368.0079 -264.368026)
		(size 0.4064)
		(drill 0.2032)
		(layers "F.Cu" "B.Cu")
		(net "PVDD11_S3_P0")
	)
	(via
		(at 378.814838 -282.996132)
		(size 0.4064)
		(drill 0.2032)
		(layers "F.Cu" "B.Cu")
		(net "PVDD11_S3_P0")
	)
	(via
		(at 378.814838 -287.856168)
		(size 0.4064)
		(drill 0.2032)
		(layers "F.Cu" "B.Cu")
		(net "PVDD11_S3_P0")
	)
	(via
		(at 384.924808 -280.566114)
		(size 0.4064)
		(drill 0.2032)
		(layers "F.Cu" "B.Cu")
		(net "PVDD11_S3_P0")
	)
	(via
		(at 434.384704 -340.890606)
		(size 0.508)
		(drill 0.254)
		(layers "F.Cu" "B.Cu")
		(net "PVDD11_S3_P0")
	)
	(via
		(at 372.234714 -263.555988)
		(size 0.4064)
		(drill 0.2032)
		(layers "F.Cu" "B.Cu")
		(net "PVDD11_S3_P0")
	)
	(via
		(at 424.846242 -339.007704)
		(size 0.508)
		(drill 0.254)
		(layers "F.Cu" "B.Cu")
		(net "PVDD11_S3_P0")
	)
	(via
		(at 361.288076 -262.23722)
		(size 0.4826)
		(drill 0.254)
		(layers "F.Cu" "B.Cu")
		(net "PVDD11_S3_P0")
	)
	(via
		(at 418.356288 -336.076798)
		(size 0.6604)
		(drill 0.3302)
		(layers "F.Cu" "B.Cu")
		(net "PVDD11_S3_P0")
	)
	(via
		(at 425.484036 -340.161626)
		(size 0.508)
		(drill 0.254)
		(layers "F.Cu" "B.Cu")
		(net "PVDD11_S3_P0")
	)
	(via
		(at 358.141016 -266.796012)
		(size 0.4064)
		(drill 0.2032)
		(layers "F.Cu" "B.Cu")
		(net "PVDD11_S3_P0")
	)
	(via
		(at 371.764814 -265.986006)
		(size 0.4064)
		(drill 0.2032)
		(layers "F.Cu" "B.Cu")
		(net "PVDD11_S3_P0")
	)
	(via
		(at 421.13581 -340.097364)
		(size 0.508)
		(drill 0.254)
		(layers "F.Cu" "B.Cu")
		(net "PVDD11_S3_P0")
	)
	(via
		(at 391.504678 -290.285932)
		(size 0.4064)
		(drill 0.2032)
		(layers "F.Cu" "B.Cu")
		(net "PVDD11_S3_P0")
	)
	(via
		(at 364.137956 -262.23722)
		(size 0.4826)
		(drill 0.254)
		(layers "F.Cu" "B.Cu")
		(net "PVDD11_S3_P0")
	)
	(via
		(at 336.965544 -166.8272)
		(size 0.508)
		(drill 0.254)
		(layers "F.Cu" "B.Cu")
		(net "PVDD11_S3_P0")
	)
	(via
		(at 430.548288 -335.975198)
		(size 0.6604)
		(drill 0.3302)
		(layers "F.Cu" "B.Cu")
		(net "PVDD11_S3_P0")
	)
	(via
		(at 436.218584 -340.120986)
		(size 0.508)
		(drill 0.254)
		(layers "F.Cu" "B.Cu")
		(net "PVDD11_S3_P0")
	)
	(via
		(at 421.13581 -339.462364)
		(size 0.508)
		(drill 0.254)
		(layers "F.Cu" "B.Cu")
		(net "PVDD11_S3_P0")
	)
	(via
		(at 427.906688 -336.000598)
		(size 0.508)
		(drill 0.254)
		(layers "F.Cu" "B.Cu")
		(net "PVDD11_S3_P0")
	)
	(via
		(at 384.924808 -275.706078)
		(size 0.4064)
		(drill 0.2032)
		(layers "F.Cu" "B.Cu")
		(net "PVDD11_S3_P0")
	)
	(via
		(at 421.80129 -340.148164)
		(size 0.508)
		(drill 0.254)
		(layers "F.Cu" "B.Cu")
		(net "PVDD11_S3_P0")
	)
	(via
		(at 436.551324 -340.773766)
		(size 0.508)
		(drill 0.254)
		(layers "F.Cu" "B.Cu")
		(net "PVDD11_S3_P0")
	)
	(via
		(at 421.16121 -336.922364)
		(size 0.508)
		(drill 0.254)
		(layers "F.Cu" "B.Cu")
		(net "PVDD11_S3_P0")
	)
	(via
		(at 421.785288 -333.714598)
		(size 0.508)
		(drill 0.254)
		(layers "F.Cu" "B.Cu")
		(net "PVDD11_S3_P0")
	)
	(via
		(at 360.51109 -135.625332)
		(size 0.508)
		(drill 0.254)
		(layers "F.Cu" "B.Cu")
		(net "PVDD11_S3_P0")
	)
	(via
		(at 422.512998 -336.937604)
		(size 0.508)
		(drill 0.254)
		(layers "F.Cu" "B.Cu")
		(net "PVDD11_S3_P0")
	)
	(via
		(at 419.372288 -335.314798)
		(size 0.508)
		(drill 0.254)
		(layers "F.Cu" "B.Cu")
		(net "PVDD11_S3_P0")
	)
	(via
		(at 248.038112 -203.464414)
		(size 0.508)
		(drill 0.254)
		(layers "F.Cu" "B.Cu")
		(net "PVDD11_S3_P0")
	)
	(via
		(at 436.858664 -340.120986)
		(size 0.508)
		(drill 0.254)
		(layers "F.Cu" "B.Cu")
		(net "PVDD11_S3_P0")
	)
	(via
		(at 429.437038 -340.122764)
		(size 0.508)
		(drill 0.254)
		(layers "F.Cu" "B.Cu")
		(net "PVDD11_S3_P0")
	)
	(via
		(at 429.437038 -338.852764)
		(size 0.508)
		(drill 0.254)
		(layers "F.Cu" "B.Cu")
		(net "PVDD11_S3_P0")
	)
	(via
		(at 419.372288 -336.076798)
		(size 0.508)
		(drill 0.254)
		(layers "F.Cu" "B.Cu")
		(net "PVDD11_S3_P0")
	)
	(via
		(at 375.524776 -282.186126)
		(size 0.4064)
		(drill 0.2032)
		(layers "F.Cu" "B.Cu")
		(net "PVDD11_S3_P0")
	)
	(via
		(at 434.476144 -338.231226)
		(size 0.508)
		(drill 0.254)
		(layers "F.Cu" "B.Cu")
		(net "PVDD11_S3_P0")
	)
	(via
		(at 440.106308 -333.503778)
		(size 0.508)
		(drill 0.254)
		(layers "F.Cu" "B.Cu")
		(net "PVDD11_S3_P0")
	)
	(via
		(at 443.352936 -169.726864)
		(size 0.508)
		(drill 0.254)
		(layers "F.Cu" "B.Cu")
		(net "PVDD11_S3_P0")
	)
	(via
		(at 384.924808 -285.42615)
		(size 0.4064)
		(drill 0.2032)
		(layers "F.Cu" "B.Cu")
		(net "PVDD11_S3_P0")
	)
	(via
		(at 360.432604 -264.86231)
		(size 0.4826)
		(drill 0.254)
		(layers "F.Cu" "B.Cu")
		(net "PVDD11_S3_P0")
	)
	(via
		(at 428.66691 -354.922074)
		(size 0.508)
		(drill 0.254)
		(layers "F.Cu" "B.Cu")
		(net "PVDD11_S3_P0")
	)
	(via
		(at 368.474752 -266.796012)
		(size 0.4064)
		(drill 0.2032)
		(layers "F.Cu" "B.Cu")
		(net "PVDD11_S3_P0")
	)
	(via
		(at 354.851208 -265.986006)
		(size 0.4064)
		(drill 0.2032)
		(layers "F.Cu" "B.Cu")
		(net "PVDD11_S3_P0")
	)
	(via
		(at 358.357932 -259.845048)
		(size 0.4826)
		(drill 0.254)
		(layers "F.Cu" "B.Cu")
		(net "PVDD11_S3_P0")
	)
	(via
		(at 373.644922 -265.986006)
		(size 0.4064)
		(drill 0.2032)
		(layers "F.Cu" "B.Cu")
		(net "PVDD11_S3_P0")
	)
	(via
		(at 370.35486 -263.555988)
		(size 0.4064)
		(drill 0.2032)
		(layers "F.Cu" "B.Cu")
		(net "PVDD11_S3_P0")
	)
	(via
		(at 378.344938 -265.986006)
		(size 0.4064)
		(drill 0.2032)
		(layers "F.Cu" "B.Cu")
		(net "PVDD11_S3_P0")
	)
	(via
		(at 366.128046 -264.368026)
		(size 0.4064)
		(drill 0.2032)
		(layers "F.Cu" "B.Cu")
		(net "PVDD11_S3_P0")
	)
	(via
		(at 364.247938 -264.368026)
		(size 0.4064)
		(drill 0.2032)
		(layers "F.Cu" "B.Cu")
		(net "PVDD11_S3_P0")
	)
	(via
		(at 425.484036 -338.891626)
		(size 0.508)
		(drill 0.254)
		(layers "F.Cu" "B.Cu")
		(net "PVDD11_S3_P0")
	)
	(via
		(at 375.524776 -267.606018)
		(size 0.4064)
		(drill 0.2032)
		(layers "F.Cu" "B.Cu")
		(net "PVDD11_S3_P0")
	)
	(via
		(at 366.295178 -262.18007)
		(size 0.4826)
		(drill 0.254)
		(layers "F.Cu" "B.Cu")
		(net "PVDD11_S3_P0")
	)
	(via
		(at 375.524776 -277.32609)
		(size 0.4064)
		(drill 0.2032)
		(layers "F.Cu" "B.Cu")
		(net "PVDD11_S3_P0")
	)
	(via
		(at 421.80129 -337.608164)
		(size 0.508)
		(drill 0.254)
		(layers "F.Cu" "B.Cu")
		(net "PVDD11_S3_P0")
	)
	(via
		(at 433.167282 -337.737704)
		(size 0.508)
		(drill 0.254)
		(layers "F.Cu" "B.Cu")
		(net "PVDD11_S3_P0")
	)
	(via
		(at 375.524776 -285.42615)
		(size 0.4064)
		(drill 0.2032)
		(layers "F.Cu" "B.Cu")
		(net "PVDD11_S3_P0")
	)
	(via
		(at 391.974832 -268.416024)
		(size 0.4064)
		(drill 0.2032)
		(layers "F.Cu" "B.Cu")
		(net "PVDD11_S3_P0")
	)
	(via
		(at 421.202358 -340.839552)
		(size 0.508)
		(drill 0.254)
		(layers "F.Cu" "B.Cu")
		(net "PVDD11_S3_P0")
	)
	(via
		(at 433.810664 -339.552026)
		(size 0.508)
		(drill 0.254)
		(layers "F.Cu" "B.Cu")
		(net "PVDD11_S3_P0")
	)
	(via
		(at 416.985958 -340.737952)
		(size 0.508)
		(drill 0.254)
		(layers "F.Cu" "B.Cu")
		(net "PVDD11_S3_P0")
	)
	(via
		(at 375.524776 -265.986006)
		(size 0.4064)
		(drill 0.2032)
		(layers "F.Cu" "B.Cu")
		(net "PVDD11_S3_P0")
	)
	(via
		(at 437.558688 -333.562198)
		(size 0.508)
		(drill 0.254)
		(layers "F.Cu" "B.Cu")
		(net "PVDD11_S3_P0")
	)
	(via
		(at 378.814838 -273.27606)
		(size 0.4064)
		(drill 0.2032)
		(layers "F.Cu" "B.Cu")
		(net "PVDD11_S3_P0")
	)
	(via
		(at 378.344938 -285.42615)
		(size 0.4064)
		(drill 0.2032)
		(layers "F.Cu" "B.Cu")
		(net "PVDD11_S3_P0")
	)
	(via
		(at 431.564288 -335.975198)
		(size 0.508)
		(drill 0.254)
		(layers "F.Cu" "B.Cu")
		(net "PVDD11_S3_P0")
	)
	(via
		(at 354.847906 -264.368026)
		(size 0.4064)
		(drill 0.2032)
		(layers "F.Cu" "B.Cu")
		(net "PVDD11_S3_P0")
	)
	(via
		(at 354.34524 -262.18007)
		(size 0.4826)
		(drill 0.254)
		(layers "F.Cu" "B.Cu")
		(net "PVDD11_S3_P0")
	)
	(via
		(at 434.002688 -333.689198)
		(size 0.508)
		(drill 0.254)
		(layers "F.Cu" "B.Cu")
		(net "PVDD11_S3_P0")
	)
	(via
		(at 378.814838 -263.555988)
		(size 0.4064)
		(drill 0.2032)
		(layers "F.Cu" "B.Cu")
		(net "PVDD11_S3_P0")
	)
	(via
		(at 364.24489 -265.986006)
		(size 0.4064)
		(drill 0.2032)
		(layers "F.Cu" "B.Cu")
		(net "PVDD11_S3_P0")
	)
	(via
		(at 378.814838 -268.416024)
		(size 0.4064)
		(drill 0.2032)
		(layers "F.Cu" "B.Cu")
		(net "PVDD11_S3_P0")
	)
	(via
		(at 429.437038 -337.582764)
		(size 0.508)
		(drill 0.254)
		(layers "F.Cu" "B.Cu")
		(net "PVDD11_S3_P0")
	)
	(via
		(at 436.858664 -336.945986)
		(size 0.508)
		(drill 0.254)
		(layers "F.Cu" "B.Cu")
		(net "PVDD11_S3_P0")
	)
	(via
		(at 433.810664 -340.187026)
		(size 0.508)
		(drill 0.254)
		(layers "F.Cu" "B.Cu")
		(net "PVDD11_S3_P0")
	)
	(via
		(at 428.557436 -340.749382)
		(size 0.508)
		(drill 0.254)
		(layers "F.Cu" "B.Cu")
		(net "PVDD11_S3_P0")
	)
	(via
		(at 429.437038 -338.217764)
		(size 0.508)
		(drill 0.254)
		(layers "F.Cu" "B.Cu")
		(net "PVDD11_S3_P0")
	)
	(via
		(at 426.149516 -338.840826)
		(size 0.508)
		(drill 0.254)
		(layers "F.Cu" "B.Cu")
		(net "PVDD11_S3_P0")
	)
	(via
		(at 440.106308 -334.265778)
		(size 0.508)
		(drill 0.254)
		(layers "F.Cu" "B.Cu")
		(net "PVDD11_S3_P0")
	)
	(via
		(at 419.144958 -340.737952)
		(size 0.508)
		(drill 0.254)
		(layers "F.Cu" "B.Cu")
		(net "PVDD11_S3_P0")
	)
	(via
		(at 429.437038 -339.487764)
		(size 0.508)
		(drill 0.254)
		(layers "F.Cu" "B.Cu")
		(net "PVDD11_S3_P0")
	)
	(via
		(at 436.858664 -338.850986)
		(size 0.508)
		(drill 0.254)
		(layers "F.Cu" "B.Cu")
		(net "PVDD11_S3_P0")
	)
	(via
		(at 374.114822 -263.555988)
		(size 0.4064)
		(drill 0.2032)
		(layers "F.Cu" "B.Cu")
		(net "PVDD11_S3_P0")
	)
	(via
		(at 436.551324 -341.408766)
		(size 0.508)
		(drill 0.254)
		(layers "F.Cu" "B.Cu")
		(net "PVDD11_S3_P0")
	)
	(via
		(at 360.607864 -259.845048)
		(size 0.4826)
		(drill 0.254)
		(layers "F.Cu" "B.Cu")
		(net "PVDD11_S3_P0")
	)
	(via
		(at 390.474454 -299.27931)
		(size 0.508)
		(drill 0.254)
		(layers "F.Cu" "B.Cu")
		(net "PVDD11_S3_P0")
	)
	(via
		(at 362.238036 -262.23722)
		(size 0.4826)
		(drill 0.254)
		(layers "F.Cu" "B.Cu")
		(net "PVDD11_S3_P0")
	)
	(via
		(at 391.152888 -205.059026)
		(size 0.508)
		(drill 0.254)
		(layers "F.Cu" "B.Cu")
		(net "PVDD11_S3_P0")
	)
	(via
		(at 233.299 -218.45905)
		(size 0.508)
		(drill 0.254)
		(layers "F.Cu" "B.Cu")
		(net "PVDD11_S3_P0")
	)
	(via
		(at 378.344938 -270.846042)
		(size 0.4064)
		(drill 0.2032)
		(layers "F.Cu" "B.Cu")
		(net "PVDD11_S3_P0")
	)
	(via
		(at 440.106308 -335.789778)
		(size 0.508)
		(drill 0.254)
		(layers "F.Cu" "B.Cu")
		(net "PVDD11_S3_P0")
	)
	(via
		(at 422.512998 -337.750404)
		(size 0.508)
		(drill 0.254)
		(layers "F.Cu" "B.Cu")
		(net "PVDD11_S3_P0")
	)
	(via
		(at 357.487982 -262.23722)
		(size 0.4826)
		(drill 0.254)
		(layers "F.Cu" "B.Cu")
		(net "PVDD11_S3_P0")
	)
	(via
		(at 426.149516 -340.110826)
		(size 0.508)
		(drill 0.254)
		(layers "F.Cu" "B.Cu")
		(net "PVDD11_S3_P0")
	)
	(via
		(at 455.39533 -173.618144)
		(size 0.508)
		(drill 0.254)
		(layers "F.Cu" "B.Cu")
		(net "PVDD11_S3_P0")
	)
	(via
		(at 426.473112 -341.435182)
		(size 0.508)
		(drill 0.254)
		(layers "F.Cu" "B.Cu")
		(net "PVDD11_S3_P0")
	)
	(via
		(at 425.484036 -337.621626)
		(size 0.508)
		(drill 0.254)
		(layers "F.Cu" "B.Cu")
		(net "PVDD11_S3_P0")
	)
	(via
		(at 381.381 -203.186792)
		(size 0.508)
		(drill 0.254)
		(layers "F.Cu" "B.Cu")
		(net "PVDD11_S3_P0")
	)
	(via
		(at 421.80129 -336.922364)
		(size 0.508)
		(drill 0.254)
		(layers "F.Cu" "B.Cu")
		(net "PVDD11_S3_P0")
	)
	(via
		(at 426.149516 -336.935826)
		(size 0.508)
		(drill 0.254)
		(layers "F.Cu" "B.Cu")
		(net "PVDD11_S3_P0")
	)
	(via
		(at 431.564288 -333.689198)
		(size 0.508)
		(drill 0.254)
		(layers "F.Cu" "B.Cu")
		(net "PVDD11_S3_P0")
	)
	(via
		(at 436.218584 -336.945986)
		(size 0.508)
		(drill 0.254)
		(layers "F.Cu" "B.Cu")
		(net "PVDD11_S3_P0")
	)
	(via
		(at 368.004852 -265.986006)
		(size 0.4064)
		(drill 0.2032)
		(layers "F.Cu" "B.Cu")
		(net "PVDD11_S3_P0")
	)
	(via
		(at 430.127918 -339.538564)
		(size 0.508)
		(drill 0.254)
		(layers "F.Cu" "B.Cu")
		(net "PVDD11_S3_P0")
	)
	(via
		(at 422.512998 -339.020404)
		(size 0.508)
		(drill 0.254)
		(layers "F.Cu" "B.Cu")
		(net "PVDD11_S3_P0")
	)
	(via
		(at 350.621092 -266.796012)
		(size 0.4064)
		(drill 0.2032)
		(layers "F.Cu" "B.Cu")
		(net "PVDD11_S3_P0")
	)
	(via
		(at 424.846242 -336.924904)
		(size 0.508)
		(drill 0.254)
		(layers "F.Cu" "B.Cu")
		(net "PVDD11_S3_P0")
	)
	(via
		(at 359.387902 -262.23722)
		(size 0.4826)
		(drill 0.254)
		(layers "F.Cu" "B.Cu")
		(net "PVDD11_S3_P0")
	)
	(via
		(at 354.381054 -266.796012)
		(size 0.4064)
		(drill 0.2032)
		(layers "F.Cu" "B.Cu")
		(net "PVDD11_S3_P0")
	)
	(via
		(at 370.35486 -265.176)
		(size 0.4064)
		(drill 0.2032)
		(layers "F.Cu" "B.Cu")
		(net "PVDD11_S3_P0")
	)
	(via
		(at 312.774838 -195.495418)
		(size 0.508)
		(drill 0.254)
		(layers "F.Cu" "B.Cu")
		(net "PVDD11_S3_P0")
	)
	(via
		(at 421.13581 -337.557364)
		(size 0.508)
		(drill 0.254)
		(layers "F.Cu" "B.Cu")
		(net "PVDD11_S3_P0")
	)
	(via
		(at 391.363454 -299.27931)
		(size 0.508)
		(drill 0.254)
		(layers "F.Cu" "B.Cu")
		(net "PVDD11_S3_P0")
	)
	(via
		(at 358.357932 -258.795012)
		(size 0.4826)
		(drill 0.254)
		(layers "F.Cu" "B.Cu")
		(net "PVDD11_S3_P0")
	)
	(via
		(at 375.054876 -279.756108)
		(size 0.4064)
		(drill 0.2032)
		(layers "F.Cu" "B.Cu")
		(net "PVDD11_S3_P0")
	)
	(via
		(at 384.924808 -265.986006)
		(size 0.4064)
		(drill 0.2032)
		(layers "F.Cu" "B.Cu")
		(net "PVDD11_S3_P0")
	)
	(via
		(at 391.504678 -275.706078)
		(size 0.4064)
		(drill 0.2032)
		(layers "F.Cu" "B.Cu")
		(net "PVDD11_S3_P0")
	)
	(via
		(at 349.211138 -265.986006)
		(size 0.4064)
		(drill 0.2032)
		(layers "F.Cu" "B.Cu")
		(net "PVDD11_S3_P0")
	)
	(via
		(at 434.002688 -335.975198)
		(size 0.508)
		(drill 0.254)
		(layers "F.Cu" "B.Cu")
		(net "PVDD11_S3_P0")
	)
	(via
		(at 425.442888 -333.714598)
		(size 0.508)
		(drill 0.254)
		(layers "F.Cu" "B.Cu")
		(net "PVDD11_S3_P0")
	)
	(via
		(at 430.127918 -340.173564)
		(size 0.508)
		(drill 0.254)
		(layers "F.Cu" "B.Cu")
		(net "PVDD11_S3_P0")
	)
	(via
		(at 360.432604 -263.84631)
		(size 0.4826)
		(drill 0.254)
		(layers "F.Cu" "B.Cu")
		(net "PVDD11_S3_P0")
	)
	(via
		(at 356.538022 -262.23722)
		(size 0.4826)
		(drill 0.254)
		(layers "F.Cu" "B.Cu")
		(net "PVDD11_S3_P0")
	)
	(via
		(at 434.476144 -336.961226)
		(size 0.508)
		(drill 0.254)
		(layers "F.Cu" "B.Cu")
		(net "PVDD11_S3_P0")
	)
	(via
		(at 296.197274 -147.472908)
		(size 0.508)
		(drill 0.254)
		(layers "F.Cu" "B.Cu")
		(net "PVDD11_S3_P0")
	)
	(via
		(at 371.764814 -264.365994)
		(size 0.4064)
		(drill 0.2032)
		(layers "F.Cu" "B.Cu")
		(net "PVDD11_S3_P0")
	)
	(via
		(at 425.484036 -339.526626)
		(size 0.508)
		(drill 0.254)
		(layers "F.Cu" "B.Cu")
		(net "PVDD11_S3_P0")
	)
	(via
		(at 426.149516 -339.475826)
		(size 0.508)
		(drill 0.254)
		(layers "F.Cu" "B.Cu")
		(net "PVDD11_S3_P0")
	)
	(via
		(at 434.476144 -339.501226)
		(size 0.508)
		(drill 0.254)
		(layers "F.Cu" "B.Cu")
		(net "PVDD11_S3_P0")
	)
	(via
		(at 434.476144 -340.136226)
		(size 0.508)
		(drill 0.254)
		(layers "F.Cu" "B.Cu")
		(net "PVDD11_S3_P0")
	)
	(via
		(at 434.384704 -341.525606)
		(size 0.508)
		(drill 0.254)
		(layers "F.Cu" "B.Cu")
		(net "PVDD11_S3_P0")
	)
	(via
		(at 436.218584 -338.215986)
		(size 0.508)
		(drill 0.254)
		(layers "F.Cu" "B.Cu")
		(net "PVDD11_S3_P0")
	)
	(via
		(at 312.006488 -174.879254)
		(size 0.508)
		(drill 0.254)
		(layers "F.Cu" "B.Cu")
		(net "PVDD11_S3_P0")
	)
	(via
		(at 369.884706 -265.986006)
		(size 0.4064)
		(drill 0.2032)
		(layers "F.Cu" "B.Cu")
		(net "PVDD11_S3_P0")
	)
	(via
		(at 355.588062 -262.23722)
		(size 0.4826)
		(drill 0.254)
		(layers "F.Cu" "B.Cu")
		(net "PVDD11_S3_P0")
	)
	(via
		(at 433.810664 -338.917026)
		(size 0.508)
		(drill 0.254)
		(layers "F.Cu" "B.Cu")
		(net "PVDD11_S3_P0")
	)
	(via
		(at 369.884706 -264.365994)
		(size 0.4064)
		(drill 0.2032)
		(layers "F.Cu" "B.Cu")
		(net "PVDD11_S3_P0")
	)
	(via
		(at 436.858664 -338.215986)
		(size 0.508)
		(drill 0.254)
		(layers "F.Cu" "B.Cu")
		(net "PVDD11_S3_P0")
	)
	(via
		(at 385.394708 -282.996132)
		(size 0.4064)
		(drill 0.2032)
		(layers "F.Cu" "B.Cu")
		(net "PVDD11_S3_P0")
	)
	(via
		(at 378.814838 -278.136096)
		(size 0.4064)
		(drill 0.2032)
		(layers "F.Cu" "B.Cu")
		(net "PVDD11_S3_P0")
	)
	(via
		(at 430.127918 -338.268564)
		(size 0.508)
		(drill 0.254)
		(layers "F.Cu" "B.Cu")
		(net "PVDD11_S3_P0")
	)
	(via
		(at 436.218584 -338.850986)
		(size 0.508)
		(drill 0.254)
		(layers "F.Cu" "B.Cu")
		(net "PVDD11_S3_P0")
	)
	(via
		(at 430.795938 -339.007704)
		(size 0.508)
		(drill 0.254)
		(layers "F.Cu" "B.Cu")
		(net "PVDD11_S3_P0")
	)
	(via
		(at 424.426888 -336.000598)
		(size 0.6604)
		(drill 0.3302)
		(layers "F.Cu" "B.Cu")
		(net "PVDD11_S3_P0")
	)
	(via
		(at 352.9711 -265.986006)
		(size 0.4064)
		(drill 0.2032)
		(layers "F.Cu" "B.Cu")
		(net "PVDD11_S3_P0")
	)
	(via
		(at 391.974832 -282.996132)
		(size 0.4064)
		(drill 0.2032)
		(layers "F.Cu" "B.Cu")
		(net "PVDD11_S3_P0")
	)
	(via
		(at 434.476144 -337.596226)
		(size 0.508)
		(drill 0.254)
		(layers "F.Cu" "B.Cu")
		(net "PVDD11_S3_P0")
	)
	(via
		(at 385.394708 -268.416024)
		(size 0.4064)
		(drill 0.2032)
		(layers "F.Cu" "B.Cu")
		(net "PVDD11_S3_P0")
	)
	(via
		(at 351.090484 -264.368026)
		(size 0.4064)
		(drill 0.2032)
		(layers "F.Cu" "B.Cu")
		(net "PVDD11_S3_P0")
	)
	(via
		(at 419.144958 -341.499952)
		(size 0.508)
		(drill 0.254)
		(layers "F.Cu" "B.Cu")
		(net "PVDD11_S3_P0")
	)
	(via
		(at 356.731062 -265.986006)
		(size 0.4064)
		(drill 0.2032)
		(layers "F.Cu" "B.Cu")
		(net "PVDD11_S3_P0")
	)
	(via
		(at 430.077118 -336.947764)
		(size 0.508)
		(drill 0.254)
		(layers "F.Cu" "B.Cu")
		(net "PVDD11_S3_P0")
	)
	(via
		(at 391.504678 -285.42615)
		(size 0.4064)
		(drill 0.2032)
		(layers "F.Cu" "B.Cu")
		(net "PVDD11_S3_P0")
	)
	(via
		(at 238.76 -247.269)
		(size 0.508)
		(drill 0.254)
		(layers "F.Cu" "B.Cu")
		(net "PVDD11_S3_P0")
	)
	(via
		(at 391.504678 -280.566114)
		(size 0.4064)
		(drill 0.2032)
		(layers "F.Cu" "B.Cu")
		(net "PVDD11_S3_P0")
	)
	(via
		(at 436.858664 -337.580986)
		(size 0.508)
		(drill 0.254)
		(layers "F.Cu" "B.Cu")
		(net "PVDD11_S3_P0")
	)
	(via
		(at 424.846242 -338.372704)
		(size 0.508)
		(drill 0.254)
		(layers "F.Cu" "B.Cu")
		(net "PVDD11_S3_P0")
	)
	(via
		(at 433.810664 -337.647026)
		(size 0.508)
		(drill 0.254)
		(layers "F.Cu" "B.Cu")
		(net "PVDD11_S3_P0")
	)
	(via
		(at 421.785288 -336.000598)
		(size 0.508)
		(drill 0.254)
		(layers "F.Cu" "B.Cu")
		(net "PVDD11_S3_P0")
	)
	(via
		(at 372.234714 -265.176)
		(size 0.4064)
		(drill 0.2032)
		(layers "F.Cu" "B.Cu")
		(net "PVDD11_S3_P0")
	)
	(via
		(at 248.038112 -205.369414)
		(size 0.508)
		(drill 0.254)
		(layers "F.Cu" "B.Cu")
		(net "PVDD11_S3_P0")
	)
	(via
		(at 373.644922 -264.365994)
		(size 0.4064)
		(drill 0.2032)
		(layers "F.Cu" "B.Cu")
		(net "PVDD11_S3_P0")
	)
	(via
		(at 363.187996 -262.23722)
		(size 0.4826)
		(drill 0.254)
		(layers "F.Cu" "B.Cu")
		(net "PVDD11_S3_P0")
	)
	(via
		(at 426.473112 -340.800182)
		(size 0.508)
		(drill 0.254)
		(layers "F.Cu" "B.Cu")
		(net "PVDD11_S3_P0")
	)
	(via
		(at 391.504678 -270.846042)
		(size 0.4064)
		(drill 0.2032)
		(layers "F.Cu" "B.Cu")
		(net "PVDD11_S3_P0")
	)
	(via
		(at 416.985958 -341.499952)
		(size 0.508)
		(drill 0.254)
		(layers "F.Cu" "B.Cu")
		(net "PVDD11_S3_P0")
	)
	(via
		(at 421.785288 -334.476598)
		(size 0.508)
		(drill 0.254)
		(layers "F.Cu" "B.Cu")
		(net "PVDD11_S3_P0")
	)
	(via
		(at 228.473 -216.662)
		(size 0.508)
		(drill 0.254)
		(layers "F.Cu" "B.Cu")
		(net "PVDD11_S3_P0")
	)
	(segment
		(start 428.309278 -354.564442)
		(end 428.66691 -354.922074)
		(width 0.381)
		(layer "B.Cu")
		(net "PVDD11_S3_P0")
	)
	(segment
		(start 337.980274 -183.614568)
		(end 357.273098 -202.907392)
		(width 0.508)
		(layer "B.Cu")
		(net "PVDD11_S3_P0")
	)
	(segment
		(start 336.965544 -171.455588)
		(end 337.980274 -172.470318)
		(width 0.508)
		(layer "B.Cu")
		(net "PVDD11_S3_P0")
	)
	(segment
		(start 379.266958 -203.448412)
		(end 379.266958 -204.701902)
		(width 0.381)
		(layer "B.Cu")
		(net "PVDD11_S3_P0")
	)
	(segment
		(start 378.725938 -202.907392)
		(end 379.266958 -203.448412)
		(width 0.508)
		(layer "B.Cu")
		(net "PVDD11_S3_P0")
	)
	(segment
		(start 428.309278 -354.20554)
		(end 428.309278 -354.564442)
		(width 0.381)
		(layer "B.Cu")
		(net "PVDD11_S3_P0")
	)
	(segment
		(start 382.016 -203.821792)
		(end 381.381 -203.186792)
		(width 0.381)
		(layer "B.Cu")
		(net "PVDD11_S3_P0")
	)
	(segment
		(start 419.98265 -354.18014)
		(end 419.98265 -354.539042)
		(width 0.381)
		(layer "B.Cu")
		(net "PVDD11_S3_P0")
	)
	(segment
		(start 337.980274 -172.470318)
		(end 337.980274 -183.614568)
		(width 0.508)
		(layer "B.Cu")
		(net "PVDD11_S3_P0")
	)
	(segment
		(start 357.273098 -202.907392)
		(end 378.725938 -202.907392)
		(width 0.508)
		(layer "B.Cu")
		(net "PVDD11_S3_P0")
	)
	(segment
		(start 232.537 -218.45905)
		(end 233.299 -218.45905)
		(width 0.381)
		(layer "B.Cu")
		(net "PVDD11_S3_P0")
	)
	(segment
		(start 228.473 -216.662)
		(end 229.21595 -216.662)
		(width 0.381)
		(layer "B.Cu")
		(net "PVDD11_S3_P0")
	)
	(segment
		(start 302.310292 -169.927524)
		(end 304.596038 -172.21327)
		(width 0.508)
		(layer "B.Cu")
		(net "PVDD11_S3_P0")
	)
	(segment
		(start 312.774838 -195.495418)
		(end 312.137298 -195.495418)
		(width 0.508)
		(layer "B.Cu")
		(net "PVDD11_S3_P0")
	)
	(segment
		(start 379.89637 -202.819)
		(end 379.266958 -203.448412)
		(width 0.508)
		(layer "B.Cu")
		(net "PVDD11_S3_P0")
	)
	(segment
		(start 232.537 -219.201746)
		(end 232.537 -218.45905)
		(width 0.381)
		(layer "B.Cu")
		(net "PVDD11_S3_P0")
	)
	(segment
		(start 392.036808 -204.175106)
		(end 392.036808 -203.50099)
		(width 0.508)
		(layer "B.Cu")
		(net "PVDD11_S3_P0")
	)
	(segment
		(start 391.152888 -205.059026)
		(end 392.036808 -204.175106)
		(width 0.508)
		(layer "B.Cu")
		(net "PVDD11_S3_P0")
	)
	(segment
		(start 238.01705 -250.571)
		(end 238.76 -250.571)
		(width 0.381)
		(layer "B.Cu")
		(net "PVDD11_S3_P0")
	)
	(segment
		(start 231.701086 -220.86697)
		(end 231.701086 -220.03766)
		(width 0.381)
		(layer "B.Cu")
		(net "PVDD11_S3_P0")
	)
	(segment
		(start 311.032144 -174.879254)
		(end 312.006488 -174.879254)
		(width 0.508)
		(layer "B.Cu")
		(net "PVDD11_S3_P0")
	)
	(segment
		(start 232.918 -216.662)
		(end 232.17505 -216.662)
		(width 0.381)
		(layer "B.Cu")
		(net "PVDD11_S3_P0")
	)
	(segment
		(start 336.965544 -166.8272)
		(end 336.965544 -171.455588)
		(width 0.508)
		(layer "B.Cu")
		(net "PVDD11_S3_P0")
	)
	(segment
		(start 312.137298 -195.495418)
		(end 311.387236 -196.24548)
		(width 0.508)
		(layer "B.Cu")
		(net "PVDD11_S3_P0")
	)
	(segment
		(start 381.381 -203.186792)
		(end 381.013208 -202.819)
		(width 0.508)
		(layer "B.Cu")
		(net "PVDD11_S3_P0")
	)
	(segment
		(start 381.013208 -202.819)
		(end 379.89637 -202.819)
		(width 0.508)
		(layer "B.Cu")
		(net "PVDD11_S3_P0")
	)
	(segment
		(start 231.701086 -220.03766)
		(end 232.537 -219.201746)
		(width 0.381)
		(layer "B.Cu")
		(net "PVDD11_S3_P0")
	)
	(segment
		(start 419.98265 -354.539042)
		(end 420.340282 -354.896674)
		(width 0.381)
		(layer "B.Cu")
		(net "PVDD11_S3_P0")
	)
	(segment
		(start 392.036808 -203.50099)
		(end 392.036808 -202.48499)
		(width 0.508)
		(layer "B.Cu")
		(net "PVDD11_S3_P0")
	)
	(segment
		(start 296.170604 -169.927524)
		(end 302.310292 -169.927524)
		(width 0.508)
		(layer "B.Cu")
		(net "PVDD11_S3_P0")
	)
	(segment
		(start 311.387236 -197.435978)
		(end 312.403236 -197.435978)
		(width 0.508)
		(layer "B.Cu")
		(net "PVDD11_S3_P0")
	)
	(segment
		(start 382.016 -204.701902)
		(end 382.016 -203.821792)
		(width 0.381)
		(layer "B.Cu")
		(net "PVDD11_S3_P0")
	)
	(segment
		(start 238.01705 -247.269)
		(end 238.76 -247.269)
		(width 0.381)
		(layer "B.Cu")
		(net "PVDD11_S3_P0")
	)
	(segment
		(start 311.387236 -196.24548)
		(end 311.387236 -197.435978)
		(width 0.508)
		(layer "B.Cu")
		(net "PVDD11_S3_P0")
	)
	(segment
		(start 304.596038 -172.21327)
		(end 311.032144 -174.879254)
		(width 0.508)
		(layer "B.Cu")
		(net "PVDD11_S3_P0")
	)
	(segment
		(start 419.942518 -353.872038)
		(end 420.751254 -353.063302)
		(width 0.381)
		(layer "In2.Cu")
		(net "PVDD11_S3_P0")
	)
	(segment
		(start 420.340282 -354.896674)
		(end 419.942518 -354.49891)
		(width 0.381)
		(layer "In2.Cu")
		(net "PVDD11_S3_P0")
	)
	(segment
		(start 419.942518 -354.49891)
		(end 419.942518 -353.872038)
		(width 0.381)
		(layer "In2.Cu")
		(net "PVDD11_S3_P0")
	)
	(segment
		(start 430.127918 -340.173564)
		(end 430.127918 -341.30615)
		(width 0.381)
		(layer "In2.Cu")
		(net "PVDD11_S3_P0")
	)
	(segment
		(start 428.454058 -354.709222)
		(end 428.66691 -354.922074)
		(width 0.381)
		(layer "In2.Cu")
		(net "PVDD11_S3_P0")
	)
	(segment
		(start 428.454058 -353.654106)
		(end 428.454058 -354.709222)
		(width 0.381)
		(layer "In2.Cu")
		(net "PVDD11_S3_P0")
	)
	(segment
		(start 429.269144 -352.83902)
		(end 428.454058 -353.654106)
		(width 0.381)
		(layer "In2.Cu")
		(net "PVDD11_S3_P0")
	)
	(segment
		(start 430.127918 -341.30615)
		(end 429.269144 -342.164924)
		(width 0.381)
		(layer "In2.Cu")
		(net "PVDD11_S3_P0")
	)
	(segment
		(start 420.751254 -353.063302)
		(end 420.751254 -342.052656)
		(width 0.381)
		(layer "In2.Cu")
		(net "PVDD11_S3_P0")
	)
	(segment
		(start 420.751254 -342.052656)
		(end 421.303958 -341.499952)
		(width 0.381)
		(layer "In2.Cu")
		(net "PVDD11_S3_P0")
	)
	(segment
		(start 429.269144 -342.164924)
		(end 429.269144 -352.83902)
		(width 0.381)
		(layer "In2.Cu")
		(net "PVDD11_S3_P0")
	)
	(segment
		(start 460.127604 -325.544434)
		(end 460.487014 -325.185024)
		(width 0.508)
		(layer "In4.Cu")
		(net "PVDD11_S3_P0")
	)
	(segment
		(start 442.155326 -172.729398)
		(end 443.461648 -171.423076)
		(width 0.508)
		(layer "In4.Cu")
		(net "PVDD11_S3_P0")
	)
	(segment
		(start 296.197274 -156.884116)
		(end 294.470328 -158.611062)
		(width 0.508)
		(layer "In4.Cu")
		(net "PVDD11_S3_P0")
	)
	(segment
		(start 460.487014 -325.185024)
		(end 460.487014 -185.83402)
		(width 0.508)
		(layer "In4.Cu")
		(net "PVDD11_S3_P0")
	)
	(segment
		(start 337.82 -161.416746)
		(end 340.487 -158.749746)
		(width 0.508)
		(layer "In4.Cu")
		(net "PVDD11_S3_P0")
	)
	(segment
		(start 360.51109 -135.625332)
		(end 363.62767 -132.508752)
		(width 0.508)
		(layer "In4.Cu")
		(net "PVDD11_S3_P0")
	)
	(segment
		(start 336.965544 -166.8272)
		(end 337.82 -165.972744)
		(width 0.508)
		(layer "In4.Cu")
		(net "PVDD11_S3_P0")
	)
	(segment
		(start 434.278786 -170.841162)
		(end 436.167022 -172.729398)
		(width 0.508)
		(layer "In4.Cu")
		(net "PVDD11_S3_P0")
	)
	(segment
		(start 443.461648 -169.835576)
		(end 443.352936 -169.726864)
		(width 0.508)
		(layer "In4.Cu")
		(net "PVDD11_S3_P0")
	)
	(segment
		(start 340.487 -144.923002)
		(end 349.78467 -135.625332)
		(width 0.508)
		(layer "In4.Cu")
		(net "PVDD11_S3_P0")
	)
	(segment
		(start 296.197274 -147.472908)
		(end 296.197274 -156.884116)
		(width 0.508)
		(layer "In4.Cu")
		(net "PVDD11_S3_P0")
	)
	(segment
		(start 294.470328 -158.611062)
		(end 294.470328 -168.227248)
		(width 0.508)
		(layer "In4.Cu")
		(net "PVDD11_S3_P0")
	)
	(segment
		(start 363.62767 -132.508752)
		(end 406.633172 -132.508752)
		(width 0.508)
		(layer "In4.Cu")
		(net "PVDD11_S3_P0")
	)
	(segment
		(start 460.487014 -185.83402)
		(end 455.39533 -180.742336)
		(width 0.508)
		(layer "In4.Cu")
		(net "PVDD11_S3_P0")
	)
	(segment
		(start 340.487 -158.749746)
		(end 340.487 -144.923002)
		(width 0.508)
		(layer "In4.Cu")
		(net "PVDD11_S3_P0")
	)
	(segment
		(start 436.167022 -172.729398)
		(end 442.155326 -172.729398)
		(width 0.508)
		(layer "In4.Cu")
		(net "PVDD11_S3_P0")
	)
	(segment
		(start 294.470328 -168.227248)
		(end 296.170604 -169.927524)
		(width 0.508)
		(layer "In4.Cu")
		(net "PVDD11_S3_P0")
	)
	(segment
		(start 443.461648 -171.423076)
		(end 443.461648 -169.835576)
		(width 0.508)
		(layer "In4.Cu")
		(net "PVDD11_S3_P0")
	)
	(segment
		(start 434.278786 -170.236134)
		(end 434.278786 -170.841162)
		(width 0.508)
		(layer "In4.Cu")
		(net "PVDD11_S3_P0")
	)
	(segment
		(start 349.78467 -135.625332)
		(end 360.51109 -135.625332)
		(width 0.508)
		(layer "In4.Cu")
		(net "PVDD11_S3_P0")
	)
	(segment
		(start 337.82 -165.972744)
		(end 337.82 -161.416746)
		(width 0.508)
		(layer "In4.Cu")
		(net "PVDD11_S3_P0")
	)
	(segment
		(start 455.39533 -180.742336)
		(end 455.39533 -173.618144)
		(width 0.508)
		(layer "In4.Cu")
		(net "PVDD11_S3_P0")
	)
	(segment
		(start 324.07606 -129.66954)
		(end 342.112092 -129.66954)
		(width 0.508)
		(layer "In6.Cu")
		(net "PVDD11_S3_P0")
	)
	(segment
		(start 342.112092 -129.66954)
		(end 347.227906 -134.785354)
		(width 0.508)
		(layer "In6.Cu")
		(net "PVDD11_S3_P0")
	)
	(segment
		(start 304.967386 -145.699988)
		(end 305.49596 -146.228562)
		(width 0.508)
		(layer "In6.Cu")
		(net "PVDD11_S3_P0")
	)
	(segment
		(start 312.924698 -132.692902)
		(end 320.915792 -132.692902)
		(width 0.508)
		(layer "In6.Cu")
		(net "PVDD11_S3_P0")
	)
	(segment
		(start 348.147132 -135.625332)
		(end 360.51109 -135.625332)
		(width 0.508)
		(layer "In6.Cu")
		(net "PVDD11_S3_P0")
	)
	(segment
		(start 381.381 -203.186792)
		(end 389.280654 -203.186792)
		(width 0.508)
		(layer "In6.Cu")
		(net "PVDD11_S3_P0")
	)
	(segment
		(start 389.280654 -203.186792)
		(end 391.152888 -205.059026)
		(width 0.508)
		(layer "In6.Cu")
		(net "PVDD11_S3_P0")
	)
	(segment
		(start 321.09537 -132.65023)
		(end 324.07606 -129.66954)
		(width 0.508)
		(layer "In6.Cu")
		(net "PVDD11_S3_P0")
	)
	(segment
		(start 305.49596 -147.137882)
		(end 306.2986 -147.940522)
		(width 0.508)
		(layer "In6.Cu")
		(net "PVDD11_S3_P0")
	)
	(segment
		(start 309.197756 -136.419844)
		(end 312.924698 -132.692902)
		(width 0.508)
		(layer "In6.Cu")
		(net "PVDD11_S3_P0")
	)
	(segment
		(start 309.197756 -145.761456)
		(end 309.197756 -136.419844)
		(width 0.508)
		(layer "In6.Cu")
		(net "PVDD11_S3_P0")
	)
	(segment
		(start 301.886874 -147.472908)
		(end 303.659794 -145.699988)
		(width 0.508)
		(layer "In6.Cu")
		(net "PVDD11_S3_P0")
	)
	(segment
		(start 347.307154 -134.785354)
		(end 348.147132 -135.625332)
		(width 0.508)
		(layer "In6.Cu")
		(net "PVDD11_S3_P0")
	)
	(segment
		(start 347.227906 -134.785354)
		(end 347.307154 -134.785354)
		(width 0.508)
		(layer "In6.Cu")
		(net "PVDD11_S3_P0")
	)
	(segment
		(start 303.659794 -145.699988)
		(end 304.967386 -145.699988)
		(width 0.508)
		(layer "In6.Cu")
		(net "PVDD11_S3_P0")
	)
	(segment
		(start 296.197274 -147.472908)
		(end 301.886874 -147.472908)
		(width 0.508)
		(layer "In6.Cu")
		(net "PVDD11_S3_P0")
	)
	(segment
		(start 320.958464 -132.65023)
		(end 321.09537 -132.65023)
		(width 0.508)
		(layer "In6.Cu")
		(net "PVDD11_S3_P0")
	)
	(segment
		(start 320.915792 -132.692902)
		(end 320.958464 -132.65023)
		(width 0.508)
		(layer "In6.Cu")
		(net "PVDD11_S3_P0")
	)
	(segment
		(start 307.01869 -147.940522)
		(end 309.197756 -145.761456)
		(width 0.508)
		(layer "In6.Cu")
		(net "PVDD11_S3_P0")
	)
	(segment
		(start 305.49596 -146.228562)
		(end 305.49596 -147.137882)
		(width 0.508)
		(layer "In6.Cu")
		(net "PVDD11_S3_P0")
	)
	(segment
		(start 306.2986 -147.940522)
		(end 307.01869 -147.940522)
		(width 0.508)
		(layer "In6.Cu")
		(net "PVDD11_S3_P0")
	)
	(via
		(at 244.636036 -219.456)
		(size 0.6604)
		(drill 0.3302)
		(layers "F.Cu" "B.Cu")
		(net "PU_U96_EN")
	)
	(segment
		(start 244.729 -219.363036)
		(end 244.636036 -219.456)
		(width 0.10668)
		(layer "B.Cu")
		(net "PU_U96_EN")
	)
	(segment
		(start 244.729 -218.58605)
		(end 244.729 -219.363036)
		(width 0.10668)
		(layer "B.Cu")
		(net "PU_U96_EN")
	)
	(segment
		(start 244.636036 -220.963998)
		(end 244.636036 -219.456)
		(width 0.10668)
		(layer "B.Cu")
		(net "PU_U96_EN")
	)
	(via
		(at 240.792 -218.948)
		(size 0.6604)
		(drill 0.3302)
		(layers "F.Cu" "B.Cu")
		(net "PU_U5_EN")
	)
	(segment
		(start 239.790478 -219.949522)
		(end 240.792 -218.948)
		(width 0.10668)
		(layer "B.Cu")
		(net "PU_U5_EN")
	)
	(segment
		(start 239.790478 -220.927168)
		(end 239.790478 -219.949522)
		(width 0.10668)
		(layer "B.Cu")
		(net "PU_U5_EN")
	)
	(segment
		(start 240.792 -218.948)
		(end 240.792 -218.07805)
		(width 0.10668)
		(layer "B.Cu")
		(net "PU_U5_EN")
	)
	(segment
		(start 342.7349 -15.428214)
		(end 342.7349 -14.957806)
		(width 0.10668)
		(layer "F.Cu")
		(net "PU_SMERR_LED")
	)
	(segment
		(start 342.137238 -14.360144)
		(end 341.33536 -14.360144)
		(width 0.10668)
		(layer "F.Cu")
		(net "PU_SMERR_LED")
	)
	(segment
		(start 341.33536 -15.579344)
		(end 341.33536 -14.360144)
		(width 0.10668)
		(layer "F.Cu")
		(net "PU_SMERR_LED")
	)
	(segment
		(start 342.7349 -14.957806)
		(end 342.137238 -14.360144)
		(width 0.10668)
		(layer "F.Cu")
		(net "PU_SMERR_LED")
	)
	(via
		(at 341.33536 -14.360144)
		(size 0.762)
		(drill 0.381)
		(layers "F.Cu" "B.Cu")
		(net "PU_SMERR_LED")
	)
	(segment
		(start 348.9325 -15.449296)
		(end 348.9325 -14.645132)
		(width 0.10668)
		(layer "F.Cu")
		(net "PU_P12V_ALL_PWROK_LED")
	)
	(segment
		(start 347.4593 -15.579344)
		(end 347.4593 -14.360144)
		(width 0.10668)
		(layer "F.Cu")
		(net "PU_P12V_ALL_PWROK_LED")
	)
	(segment
		(start 348.647512 -14.360144)
		(end 347.4593 -14.360144)
		(width 0.10668)
		(layer "F.Cu")
		(net "PU_P12V_ALL_PWROK_LED")
	)
	(segment
		(start 348.9325 -14.645132)
		(end 348.647512 -14.360144)
		(width 0.10668)
		(layer "F.Cu")
		(net "PU_P12V_ALL_PWROK_LED")
	)
	(via
		(at 347.4593 -14.360144)
		(size 0.762)
		(drill 0.381)
		(layers "F.Cu" "B.Cu")
		(net "PU_P12V_ALL_PWROK_LED")
	)
	(segment
		(start 99.47529 -38.815772)
		(end 99.825556 -38.815772)
		(width 0.10668)
		(layer "F.Cu")
		(net "PU_OCP_V3_2_WAKE_OE")
	)
	(segment
		(start 99.825556 -38.815772)
		(end 100.099114 -38.542214)
		(width 0.10668)
		(layer "F.Cu")
		(net "PU_OCP_V3_2_WAKE_OE")
	)
	(segment
		(start 100.099114 -38.542214)
		(end 100.86086 -38.542214)
		(width 0.10668)
		(layer "F.Cu")
		(net "PU_OCP_V3_2_WAKE_OE")
	)
	(segment
		(start 102.026974 -38.542214)
		(end 102.163372 -38.678612)
		(width 0.10668)
		(layer "F.Cu")
		(net "PU_OCP_V3_2_WAKE_OE")
	)
	(segment
		(start 100.86086 -38.542214)
		(end 102.026974 -38.542214)
		(width 0.10668)
		(layer "F.Cu")
		(net "PU_OCP_V3_2_WAKE_OE")
	)
	(via
		(at 100.86086 -38.542214)
		(size 0.762)
		(drill 0.381)
		(layers "F.Cu" "B.Cu")
		(net "PU_OCP_V3_2_WAKE_OE")
	)
	(segment
		(start 455.41311 -38.565836)
		(end 456.63231 -38.565836)
		(width 0.10668)
		(layer "F.Cu")
		(net "PU_OCP_SFF_WAKE_OE")
	)
	(segment
		(start 457.9112 -38.565836)
		(end 456.63231 -38.565836)
		(width 0.10668)
		(layer "F.Cu")
		(net "PU_OCP_SFF_WAKE_OE")
	)
	(via
		(at 456.63231 -38.565836)
		(size 0.762)
		(drill 0.381)
		(layers "F.Cu" "B.Cu")
		(net "PU_OCP_SFF_WAKE_OE")
	)
	(segment
		(start 239.10798 -47.003208)
		(end 238.833406 -47.003208)
		(width 0.10668)
		(layer "F.Cu")
		(net "PU_E1S_0_DUALPORT_EN_N")
	)
	(segment
		(start 237.234222 -47.364904)
		(end 236.599984 -47.364904)
		(width 0.10668)
		(layer "F.Cu")
		(net "PU_E1S_0_DUALPORT_EN_N")
	)
	(segment
		(start 238.570008 -46.73981)
		(end 237.859316 -46.73981)
		(width 0.10668)
		(layer "F.Cu")
		(net "PU_E1S_0_DUALPORT_EN_N")
	)
	(segment
		(start 238.833406 -47.003208)
		(end 238.570008 -46.73981)
		(width 0.10668)
		(layer "F.Cu")
		(net "PU_E1S_0_DUALPORT_EN_N")
	)
	(segment
		(start 237.859316 -46.73981)
		(end 237.234222 -47.364904)
		(width 0.10668)
		(layer "F.Cu")
		(net "PU_E1S_0_DUALPORT_EN_N")
	)
	(via
		(at 237.859316 -46.73981)
		(size 0.508)
		(drill 0.254)
		(layers "F.Cu" "B.Cu")
		(net "PU_E1S_0_DUALPORT_EN_N")
	)
	(segment
		(start 150.907242 -104.608884)
		(end 152.177242 -103.338884)
		(width 0.10668)
		(layer "F.Cu")
		(net "PU_BUFFER_HDD_ACTIVITY")
	)
	(segment
		(start 150.113492 -104.608884)
		(end 150.907242 -104.608884)
		(width 0.10668)
		(layer "F.Cu")
		(net "PU_BUFFER_HDD_ACTIVITY")
	)
	(segment
		(start 152.177242 -103.338884)
		(end 153.22423 -103.338884)
		(width 0.10668)
		(layer "F.Cu")
		(net "PU_BUFFER_HDD_ACTIVITY")
	)
	(segment
		(start 148.894292 -104.608884)
		(end 150.113492 -104.608884)
		(width 0.10668)
		(layer "F.Cu")
		(net "PU_BUFFER_HDD_ACTIVITY")
	)
	(via
		(at 150.113492 -104.608884)
		(size 0.762)
		(drill 0.381)
		(layers "F.Cu" "B.Cu")
		(net "PU_BUFFER_HDD_ACTIVITY")
	)
	(segment
		(start 338.31022 -15.58798)
		(end 338.31022 -14.36878)
		(width 0.10668)
		(layer "F.Cu")
		(net "PU_BOOT_RDY_LED")
	)
	(segment
		(start 339.70976 -14.645132)
		(end 339.433408 -14.36878)
		(width 0.10668)
		(layer "F.Cu")
		(net "PU_BOOT_RDY_LED")
	)
	(segment
		(start 339.433408 -14.36878)
		(end 338.31022 -14.36878)
		(width 0.10668)
		(layer "F.Cu")
		(net "PU_BOOT_RDY_LED")
	)
	(segment
		(start 339.70976 -15.449296)
		(end 339.70976 -14.645132)
		(width 0.10668)
		(layer "F.Cu")
		(net "PU_BOOT_RDY_LED")
	)
	(via
		(at 338.31022 -14.36878)
		(size 0.762)
		(drill 0.381)
		(layers "F.Cu" "B.Cu")
		(net "PU_BOOT_RDY_LED")
	)
	(segment
		(start 422.3766 -38.547548)
		(end 423.9514 -38.547548)
		(width 0.10668)
		(layer "F.Cu")
		(net "PU_BIOS_USB_RECOVERY")
	)
	(segment
		(start 421.1574 -38.547548)
		(end 422.3766 -38.547548)
		(width 0.10668)
		(layer "F.Cu")
		(net "PU_BIOS_USB_RECOVERY")
	)
	(via
		(at 422.3766 -38.547548)
		(size 0.762)
		(drill 0.381)
		(layers "F.Cu" "B.Cu")
		(net "PU_BIOS_USB_RECOVERY")
	)
	(segment
		(start 96.434148 -425.417234)
		(end 94.82582 -423.808906)
		(width 0.10668)
		(layer "F.Cu")
		(net "PRSNT_SWB_N")
	)
	(segment
		(start 97.279968 -425.417234)
		(end 96.434148 -425.417234)
		(width 0.10668)
		(layer "F.Cu")
		(net "PRSNT_SWB_N")
	)
	(via
		(at 94.82582 -423.808906)
		(size 0.508)
		(drill 0.254)
		(layers "F.Cu" "B.Cu")
		(net "PRSNT_SWB_N")
	)
	(segment
		(start 97.499678 -423.700194)
		(end 96.096328 -423.700194)
		(width 0.10668)
		(layer "B.Cu")
		(net "PRSNT_SWB_N")
	)
	(segment
		(start 100.123244 -424.885358)
		(end 99.138232 -424.885358)
		(width 0.10668)
		(layer "B.Cu")
		(net "PRSNT_SWB_N")
	)
	(segment
		(start 96.096328 -423.700194)
		(end 95.987616 -423.808906)
		(width 0.10668)
		(layer "B.Cu")
		(net "PRSNT_SWB_N")
	)
	(segment
		(start 98.444558 -424.191684)
		(end 97.991168 -424.191684)
		(width 0.10668)
		(layer "B.Cu")
		(net "PRSNT_SWB_N")
	)
	(segment
		(start 99.138232 -424.885358)
		(end 98.444558 -424.191684)
		(width 0.10668)
		(layer "B.Cu")
		(net "PRSNT_SWB_N")
	)
	(segment
		(start 97.991168 -424.191684)
		(end 97.499678 -423.700194)
		(width 0.10668)
		(layer "B.Cu")
		(net "PRSNT_SWB_N")
	)
	(segment
		(start 95.987616 -423.808906)
		(end 94.82582 -423.808906)
		(width 0.10668)
		(layer "B.Cu")
		(net "PRSNT_SWB_N")
	)
	(segment
		(start 94.82582 -423.808906)
		(end 92.518992 -423.808906)
		(width 0.11684)
		(layer "In2.Cu")
		(net "PRSNT_SWB_N")
	)
	(segment
		(start 91.21267 -422.502584)
		(end 77.01407 -422.502584)
		(width 0.11684)
		(layer "In2.Cu")
		(net "PRSNT_SWB_N")
	)
	(segment
		(start 77.01407 -422.502584)
		(end 73.754996 -425.761658)
		(width 0.11684)
		(layer "In2.Cu")
		(net "PRSNT_SWB_N")
	)
	(segment
		(start 92.518992 -423.808906)
		(end 91.21267 -422.502584)
		(width 0.11684)
		(layer "In2.Cu")
		(net "PRSNT_SWB_N")
	)
	(segment
		(start 73.754996 -425.761658)
		(end 73.754996 -440.708542)
		(width 0.11684)
		(layer "In2.Cu")
		(net "PRSNT_SWB_N")
	)
	(segment
		(start 73.511156 -440.952382)
		(end 72.058276 -440.952382)
		(width 0.11684)
		(layer "In2.Cu")
		(net "PRSNT_SWB_N")
	)
	(segment
		(start 72.058276 -440.952382)
		(end 71.595742 -440.489848)
		(width 0.11684)
		(layer "In2.Cu")
		(net "PRSNT_SWB_N")
	)
	(segment
		(start 71.595742 -440.489848)
		(end 70.649846 -440.489848)
		(width 0.11684)
		(layer "In2.Cu")
		(net "PRSNT_SWB_N")
	)
	(segment
		(start 73.754996 -440.708542)
		(end 73.511156 -440.952382)
		(width 0.11684)
		(layer "In2.Cu")
		(net "PRSNT_SWB_N")
	)
	(segment
		(start 403.282912 -54.4195)
		(end 402.063712 -54.4195)
		(width 0.10668)
		(layer "F.Cu")
		(net "PRSNT_HDT_R_N")
	)
	(segment
		(start 397.307308 -54.4195)
		(end 402.063712 -54.4195)
		(width 0.10668)
		(layer "F.Cu")
		(net "PRSNT_HDT_R_N")
	)
	(via
		(at 402.063712 -54.4195)
		(size 0.762)
		(drill 0.381)
		(layers "F.Cu" "B.Cu")
		(net "PRSNT_HDT_R_N")
	)
	(segment
		(start 196.869558 -124.801376)
		(end 196.262498 -124.801376)
		(width 0.10668)
		(layer "F.Cu")
		(net "PRSNT_HDT_N")
	)
	(segment
		(start 405.197056 -54.4195)
		(end 407.40838 -56.630824)
		(width 0.10668)
		(layer "F.Cu")
		(net "PRSNT_HDT_N")
	)
	(segment
		(start 196.262498 -124.801376)
		(end 196.18706 -124.725938)
		(width 0.10668)
		(layer "F.Cu")
		(net "PRSNT_HDT_N")
	)
	(segment
		(start 193.922142 -121.852944)
		(end 194.312032 -122.242834)
		(width 0.10668)
		(layer "F.Cu")
		(net "PRSNT_HDT_N")
	)
	(segment
		(start 404.083012 -54.4195)
		(end 405.197056 -54.4195)
		(width 0.10668)
		(layer "F.Cu")
		(net "PRSNT_HDT_N")
	)
	(via
		(at 194.312032 -122.242834)
		(size 0.4572)
		(drill 0.254)
		(layers "F.Cu" "B.Cu")
		(net "PRSNT_HDT_N")
	)
	(via
		(at 196.18706 -124.725938)
		(size 0.508)
		(drill 0.254)
		(layers "F.Cu" "B.Cu")
		(net "PRSNT_HDT_N")
	)
	(via
		(at 251.534168 -125.58268)
		(size 0.508)
		(drill 0.254)
		(layers "F.Cu" "B.Cu")
		(net "PRSNT_HDT_N")
	)
	(via
		(at 250.005088 -88.720422)
		(size 0.508)
		(drill 0.254)
		(layers "F.Cu" "B.Cu")
		(net "PRSNT_HDT_N")
	)
	(via
		(at 407.40838 -56.630824)
		(size 0.508)
		(drill 0.254)
		(layers "F.Cu" "B.Cu")
		(net "PRSNT_HDT_N")
	)
	(segment
		(start 195.104258 -124.322586)
		(end 195.104258 -123.03506)
		(width 0.11684)
		(layer "In2.Cu")
		(net "PRSNT_HDT_N")
	)
	(segment
		(start 195.104258 -123.03506)
		(end 194.312032 -122.242834)
		(width 0.11684)
		(layer "In2.Cu")
		(net "PRSNT_HDT_N")
	)
	(segment
		(start 195.50761 -124.725938)
		(end 195.104258 -124.322586)
		(width 0.11684)
		(layer "In2.Cu")
		(net "PRSNT_HDT_N")
	)
	(segment
		(start 196.18706 -124.725938)
		(end 195.50761 -124.725938)
		(width 0.11684)
		(layer "In2.Cu")
		(net "PRSNT_HDT_N")
	)
	(segment
		(start 253.308358 -85.417152)
		(end 272.464022 -85.417152)
		(width 0.11684)
		(layer "In6.Cu")
		(net "PRSNT_HDT_N")
	)
	(segment
		(start 282.23972 -75.641454)
		(end 282.23972 -66.5353)
		(width 0.11684)
		(layer "In6.Cu")
		(net "PRSNT_HDT_N")
	)
	(segment
		(start 308.312058 -59.563)
		(end 309.284878 -58.59018)
		(width 0.11684)
		(layer "In6.Cu")
		(net "PRSNT_HDT_N")
	)
	(segment
		(start 387.69036 -58.59018)
		(end 389.649716 -56.630824)
		(width 0.11684)
		(layer "In6.Cu")
		(net "PRSNT_HDT_N")
	)
	(segment
		(start 309.284878 -58.59018)
		(end 387.69036 -58.59018)
		(width 0.11684)
		(layer "In6.Cu")
		(net "PRSNT_HDT_N")
	)
	(segment
		(start 289.21202 -59.563)
		(end 308.312058 -59.563)
		(width 0.11684)
		(layer "In6.Cu")
		(net "PRSNT_HDT_N")
	)
	(segment
		(start 250.005088 -88.720422)
		(end 253.308358 -85.417152)
		(width 0.11684)
		(layer "In6.Cu")
		(net "PRSNT_HDT_N")
	)
	(segment
		(start 389.649716 -56.630824)
		(end 407.40838 -56.630824)
		(width 0.11684)
		(layer "In6.Cu")
		(net "PRSNT_HDT_N")
	)
	(segment
		(start 282.23972 -66.5353)
		(end 289.21202 -59.563)
		(width 0.11684)
		(layer "In6.Cu")
		(net "PRSNT_HDT_N")
	)
	(segment
		(start 272.464022 -85.417152)
		(end 282.23972 -75.641454)
		(width 0.11684)
		(layer "In6.Cu")
		(net "PRSNT_HDT_N")
	)
	(segment
		(start 247.817132 -107.51947)
		(end 249.01144 -108.713778)
		(width 0.11684)
		(layer "In11.Cu")
		(net "PRSNT_HDT_N")
	)
	(segment
		(start 247.817132 -91.949778)
		(end 247.817132 -107.51947)
		(width 0.11684)
		(layer "In11.Cu")
		(net "PRSNT_HDT_N")
	)
	(segment
		(start 249.75185 -88.97366)
		(end 249.75185 -90.01506)
		(width 0.11684)
		(layer "In11.Cu")
		(net "PRSNT_HDT_N")
	)
	(segment
		(start 250.005088 -88.720422)
		(end 249.75185 -88.97366)
		(width 0.11684)
		(layer "In11.Cu")
		(net "PRSNT_HDT_N")
	)
	(segment
		(start 249.01144 -108.713778)
		(end 249.01144 -123.059952)
		(width 0.11684)
		(layer "In11.Cu")
		(net "PRSNT_HDT_N")
	)
	(segment
		(start 249.01144 -123.059952)
		(end 251.534168 -125.58268)
		(width 0.11684)
		(layer "In11.Cu")
		(net "PRSNT_HDT_N")
	)
	(segment
		(start 249.75185 -90.01506)
		(end 247.817132 -91.949778)
		(width 0.11684)
		(layer "In11.Cu")
		(net "PRSNT_HDT_N")
	)
	(segment
		(start 216.693496 -125.044454)
		(end 215.714072 -124.06503)
		(width 0.11684)
		(layer "In15.Cu")
		(net "PRSNT_HDT_N")
	)
	(segment
		(start 208.228692 -123.54941)
		(end 207.895698 -123.216416)
		(width 0.11684)
		(layer "In15.Cu")
		(net "PRSNT_HDT_N")
	)
	(segment
		(start 203.187046 -123.446794)
		(end 203.187046 -124.182886)
		(width 0.11684)
		(layer "In15.Cu")
		(net "PRSNT_HDT_N")
	)
	(segment
		(start 211.606638 -124.06503)
		(end 211.091018 -123.54941)
		(width 0.11684)
		(layer "In15.Cu")
		(net "PRSNT_HDT_N")
	)
	(segment
		(start 228.293422 -126.771654)
		(end 227.287836 -125.766068)
		(width 0.11684)
		(layer "In15.Cu")
		(net "PRSNT_HDT_N")
	)
	(segment
		(start 206.506826 -124.17298)
		(end 205.840584 -124.17298)
		(width 0.11684)
		(layer "In15.Cu")
		(net "PRSNT_HDT_N")
	)
	(segment
		(start 198.830184 -124.801376)
		(end 196.262498 -124.801376)
		(width 0.11684)
		(layer "In15.Cu")
		(net "PRSNT_HDT_N")
	)
	(segment
		(start 217.55227 -125.494542)
		(end 217.102182 -125.044454)
		(width 0.11684)
		(layer "In15.Cu")
		(net "PRSNT_HDT_N")
	)
	(segment
		(start 247.837198 -124.997464)
		(end 246.063008 -126.771654)
		(width 0.11684)
		(layer "In15.Cu")
		(net "PRSNT_HDT_N")
	)
	(segment
		(start 204.820266 -123.152662)
		(end 203.481178 -123.152662)
		(width 0.11684)
		(layer "In15.Cu")
		(net "PRSNT_HDT_N")
	)
	(segment
		(start 196.262498 -124.801376)
		(end 196.18706 -124.725938)
		(width 0.11684)
		(layer "In15.Cu")
		(net "PRSNT_HDT_N")
	)
	(segment
		(start 207.46339 -123.216416)
		(end 206.506826 -124.17298)
		(width 0.11684)
		(layer "In15.Cu")
		(net "PRSNT_HDT_N")
	)
	(segment
		(start 207.895698 -123.216416)
		(end 207.46339 -123.216416)
		(width 0.11684)
		(layer "In15.Cu")
		(net "PRSNT_HDT_N")
	)
	(segment
		(start 205.840584 -124.17298)
		(end 204.820266 -123.152662)
		(width 0.11684)
		(layer "In15.Cu")
		(net "PRSNT_HDT_N")
	)
	(segment
		(start 200.838308 -124.44222)
		(end 200.386188 -123.9901)
		(width 0.11684)
		(layer "In15.Cu")
		(net "PRSNT_HDT_N")
	)
	(segment
		(start 215.714072 -124.06503)
		(end 211.606638 -124.06503)
		(width 0.11684)
		(layer "In15.Cu")
		(net "PRSNT_HDT_N")
	)
	(segment
		(start 220.922088 -125.766068)
		(end 220.526864 -126.161292)
		(width 0.11684)
		(layer "In15.Cu")
		(net "PRSNT_HDT_N")
	)
	(segment
		(start 250.948952 -124.997464)
		(end 247.837198 -124.997464)
		(width 0.11684)
		(layer "In15.Cu")
		(net "PRSNT_HDT_N")
	)
	(segment
		(start 218.94419 -125.494542)
		(end 217.55227 -125.494542)
		(width 0.11684)
		(layer "In15.Cu")
		(net "PRSNT_HDT_N")
	)
	(segment
		(start 246.063008 -126.771654)
		(end 228.293422 -126.771654)
		(width 0.11684)
		(layer "In15.Cu")
		(net "PRSNT_HDT_N")
	)
	(segment
		(start 217.102182 -125.044454)
		(end 216.693496 -125.044454)
		(width 0.11684)
		(layer "In15.Cu")
		(net "PRSNT_HDT_N")
	)
	(segment
		(start 202.927712 -124.44222)
		(end 200.838308 -124.44222)
		(width 0.11684)
		(layer "In15.Cu")
		(net "PRSNT_HDT_N")
	)
	(segment
		(start 220.526864 -126.161292)
		(end 219.61094 -126.161292)
		(width 0.11684)
		(layer "In15.Cu")
		(net "PRSNT_HDT_N")
	)
	(segment
		(start 203.187046 -124.182886)
		(end 202.927712 -124.44222)
		(width 0.11684)
		(layer "In15.Cu")
		(net "PRSNT_HDT_N")
	)
	(segment
		(start 211.091018 -123.54941)
		(end 208.228692 -123.54941)
		(width 0.11684)
		(layer "In15.Cu")
		(net "PRSNT_HDT_N")
	)
	(segment
		(start 199.64146 -123.9901)
		(end 198.830184 -124.801376)
		(width 0.11684)
		(layer "In15.Cu")
		(net "PRSNT_HDT_N")
	)
	(segment
		(start 251.534168 -125.58268)
		(end 250.948952 -124.997464)
		(width 0.11684)
		(layer "In15.Cu")
		(net "PRSNT_HDT_N")
	)
	(segment
		(start 219.61094 -126.161292)
		(end 218.94419 -125.494542)
		(width 0.11684)
		(layer "In15.Cu")
		(net "PRSNT_HDT_N")
	)
	(segment
		(start 200.386188 -123.9901)
		(end 199.64146 -123.9901)
		(width 0.11684)
		(layer "In15.Cu")
		(net "PRSNT_HDT_N")
	)
	(segment
		(start 203.481178 -123.152662)
		(end 203.187046 -123.446794)
		(width 0.11684)
		(layer "In15.Cu")
		(net "PRSNT_HDT_N")
	)
	(segment
		(start 227.287836 -125.766068)
		(end 220.922088 -125.766068)
		(width 0.11684)
		(layer "In15.Cu")
		(net "PRSNT_HDT_N")
	)
	(segment
		(start 423.9514 -33.467548)
		(end 424.9674 -33.467548)
		(width 0.10668)
		(layer "F.Cu")
		(net "PRSNT_CPU1_N")
	)
	(segment
		(start 70.75551 -199.372474)
		(end 69.034152 -199.372474)
		(width 0.10668)
		(layer "F.Cu")
		(net "PRSNT_CPU1_N")
	)
	(segment
		(start 89.483946 -216.562686)
		(end 89.483946 -209.411062)
		(width 0.10668)
		(layer "F.Cu")
		(net "PRSNT_CPU1_N")
	)
	(segment
		(start 85.457792 -220.58884)
		(end 89.483946 -216.562686)
		(width 0.10668)
		(layer "F.Cu")
		(net "PRSNT_CPU1_N")
	)
	(segment
		(start 85.457792 -222.880428)
		(end 85.457792 -220.58884)
		(width 0.10668)
		(layer "F.Cu")
		(net "PRSNT_CPU1_N")
	)
	(segment
		(start 69.034152 -199.372474)
		(end 68.89623 -199.510396)
		(width 0.10668)
		(layer "F.Cu")
		(net "PRSNT_CPU1_N")
	)
	(segment
		(start 75.825858 -204.442822)
		(end 70.75551 -199.372474)
		(width 0.10668)
		(layer "F.Cu")
		(net "PRSNT_CPU1_N")
	)
	(segment
		(start 84.515706 -204.442822)
		(end 75.825858 -204.442822)
		(width 0.10668)
		(layer "F.Cu")
		(net "PRSNT_CPU1_N")
	)
	(segment
		(start 89.483946 -209.411062)
		(end 84.515706 -204.442822)
		(width 0.10668)
		(layer "F.Cu")
		(net "PRSNT_CPU1_N")
	)
	(via
		(at 113.559336 -130.01498)
		(size 0.508)
		(drill 0.254)
		(layers "F.Cu" "B.Cu")
		(net "PRSNT_CPU1_N")
	)
	(via
		(at 167.41013 -96.77908)
		(size 0.508)
		(drill 0.254)
		(layers "F.Cu" "B.Cu")
		(net "PRSNT_CPU1_N")
	)
	(via
		(at 68.89623 -199.510396)
		(size 0.508)
		(drill 0.254)
		(layers "F.Cu" "B.Cu")
		(net "PRSNT_CPU1_N")
	)
	(via
		(at 424.9674 -33.467548)
		(size 0.508)
		(drill 0.254)
		(layers "F.Cu" "B.Cu")
		(net "PRSNT_CPU1_N")
	)
	(segment
		(start 426.1358 -33.467548)
		(end 424.9674 -33.467548)
		(width 0.10668)
		(layer "B.Cu")
		(net "PRSNT_CPU1_N")
	)
	(segment
		(start 134.183374 -101.951282)
		(end 135.231124 -101.951282)
		(width 0.11684)
		(layer "In2.Cu")
		(net "PRSNT_CPU1_N")
	)
	(segment
		(start 165.254686 -96.77908)
		(end 167.41013 -96.77908)
		(width 0.11684)
		(layer "In2.Cu")
		(net "PRSNT_CPU1_N")
	)
	(segment
		(start 156.420312 -103.981504)
		(end 157.181804 -103.981504)
		(width 0.11684)
		(layer "In2.Cu")
		(net "PRSNT_CPU1_N")
	)
	(segment
		(start 157.181804 -103.981504)
		(end 158.27629 -102.887018)
		(width 0.11684)
		(layer "In2.Cu")
		(net "PRSNT_CPU1_N")
	)
	(segment
		(start 158.27629 -102.48646)
		(end 164.07257 -96.69018)
		(width 0.11684)
		(layer "In2.Cu")
		(net "PRSNT_CPU1_N")
	)
	(segment
		(start 135.231124 -101.951282)
		(end 136.65708 -100.525326)
		(width 0.11684)
		(layer "In2.Cu")
		(net "PRSNT_CPU1_N")
	)
	(segment
		(start 128.918716 -120.22328)
		(end 128.918716 -107.21594)
		(width 0.11684)
		(layer "In2.Cu")
		(net "PRSNT_CPU1_N")
	)
	(segment
		(start 128.918716 -107.21594)
		(end 134.183374 -101.951282)
		(width 0.11684)
		(layer "In2.Cu")
		(net "PRSNT_CPU1_N")
	)
	(segment
		(start 158.27629 -102.887018)
		(end 158.27629 -102.48646)
		(width 0.11684)
		(layer "In2.Cu")
		(net "PRSNT_CPU1_N")
	)
	(segment
		(start 152.964134 -100.525326)
		(end 156.420312 -103.981504)
		(width 0.11684)
		(layer "In2.Cu")
		(net "PRSNT_CPU1_N")
	)
	(segment
		(start 136.65708 -100.525326)
		(end 152.964134 -100.525326)
		(width 0.11684)
		(layer "In2.Cu")
		(net "PRSNT_CPU1_N")
	)
	(segment
		(start 113.559336 -130.01498)
		(end 114.729514 -128.844802)
		(width 0.11684)
		(layer "In2.Cu")
		(net "PRSNT_CPU1_N")
	)
	(segment
		(start 165.165786 -96.69018)
		(end 165.254686 -96.77908)
		(width 0.11684)
		(layer "In2.Cu")
		(net "PRSNT_CPU1_N")
	)
	(segment
		(start 114.729514 -128.844802)
		(end 120.297194 -128.844802)
		(width 0.11684)
		(layer "In2.Cu")
		(net "PRSNT_CPU1_N")
	)
	(segment
		(start 164.07257 -96.69018)
		(end 165.165786 -96.69018)
		(width 0.11684)
		(layer "In2.Cu")
		(net "PRSNT_CPU1_N")
	)
	(segment
		(start 120.297194 -128.844802)
		(end 128.918716 -120.22328)
		(width 0.11684)
		(layer "In2.Cu")
		(net "PRSNT_CPU1_N")
	)
	(segment
		(start 172.465492 -92.136214)
		(end 172.737526 -91.86418)
		(width 0.11684)
		(layer "In6.Cu")
		(net "PRSNT_CPU1_N")
	)
	(segment
		(start 167.411146 -96.780096)
		(end 168.586658 -96.780096)
		(width 0.11684)
		(layer "In6.Cu")
		(net "PRSNT_CPU1_N")
	)
	(segment
		(start 177.616866 -85.832188)
		(end 193.076068 -85.832188)
		(width 0.11684)
		(layer "In6.Cu")
		(net "PRSNT_CPU1_N")
	)
	(segment
		(start 195.337938 -84.717382)
		(end 195.907406 -85.28685)
		(width 0.11684)
		(layer "In6.Cu")
		(net "PRSNT_CPU1_N")
	)
	(segment
		(start 172.75302 -91.86418)
		(end 175.714914 -88.902286)
		(width 0.11684)
		(layer "In6.Cu")
		(net "PRSNT_CPU1_N")
	)
	(segment
		(start 205.587092 -89.594436)
		(end 211.020914 -89.594436)
		(width 0.11684)
		(layer "In6.Cu")
		(net "PRSNT_CPU1_N")
	)
	(segment
		(start 195.907406 -85.28685)
		(end 196.65569 -85.28685)
		(width 0.11684)
		(layer "In6.Cu")
		(net "PRSNT_CPU1_N")
	)
	(segment
		(start 241.591338 -90.202004)
		(end 249.683016 -82.110326)
		(width 0.11684)
		(layer "In6.Cu")
		(net "PRSNT_CPU1_N")
	)
	(segment
		(start 197.096888 -85.728048)
		(end 201.720704 -85.728048)
		(width 0.11684)
		(layer "In6.Cu")
		(net "PRSNT_CPU1_N")
	)
	(segment
		(start 175.714914 -88.902286)
		(end 175.714914 -87.73414)
		(width 0.11684)
		(layer "In6.Cu")
		(net "PRSNT_CPU1_N")
	)
	(segment
		(start 196.65569 -85.28685)
		(end 197.096888 -85.728048)
		(width 0.11684)
		(layer "In6.Cu")
		(net "PRSNT_CPU1_N")
	)
	(segment
		(start 172.737526 -91.86418)
		(end 172.75302 -91.86418)
		(width 0.11684)
		(layer "In6.Cu")
		(net "PRSNT_CPU1_N")
	)
	(segment
		(start 303.903634 -56.19369)
		(end 306.807616 -53.289708)
		(width 0.11684)
		(layer "In6.Cu")
		(net "PRSNT_CPU1_N")
	)
	(segment
		(start 306.807616 -53.289708)
		(end 330.24318 -53.289708)
		(width 0.11684)
		(layer "In6.Cu")
		(net "PRSNT_CPU1_N")
	)
	(segment
		(start 211.020914 -89.594436)
		(end 211.628482 -90.202004)
		(width 0.11684)
		(layer "In6.Cu")
		(net "PRSNT_CPU1_N")
	)
	(segment
		(start 167.41013 -96.77908)
		(end 167.411146 -96.77908)
		(width 0.11684)
		(layer "In6.Cu")
		(net "PRSNT_CPU1_N")
	)
	(segment
		(start 249.683016 -82.110326)
		(end 259.763514 -82.110326)
		(width 0.11684)
		(layer "In6.Cu")
		(net "PRSNT_CPU1_N")
	)
	(segment
		(start 168.586658 -96.780096)
		(end 171.35602 -94.010734)
		(width 0.11684)
		(layer "In6.Cu")
		(net "PRSNT_CPU1_N")
	)
	(segment
		(start 269.533624 -72.340216)
		(end 274.490688 -72.340216)
		(width 0.11684)
		(layer "In6.Cu")
		(net "PRSNT_CPU1_N")
	)
	(segment
		(start 380.021592 -53.569108)
		(end 400.123152 -33.467548)
		(width 0.11684)
		(layer "In6.Cu")
		(net "PRSNT_CPU1_N")
	)
	(segment
		(start 211.628482 -90.202004)
		(end 241.591338 -90.202004)
		(width 0.11684)
		(layer "In6.Cu")
		(net "PRSNT_CPU1_N")
	)
	(segment
		(start 193.076068 -85.832188)
		(end 194.190874 -84.717382)
		(width 0.11684)
		(layer "In6.Cu")
		(net "PRSNT_CPU1_N")
	)
	(segment
		(start 172.465492 -92.151962)
		(end 172.465492 -92.136214)
		(width 0.11684)
		(layer "In6.Cu")
		(net "PRSNT_CPU1_N")
	)
	(segment
		(start 330.52258 -53.569108)
		(end 380.021592 -53.569108)
		(width 0.11684)
		(layer "In6.Cu")
		(net "PRSNT_CPU1_N")
	)
	(segment
		(start 278.932894 -67.89801)
		(end 278.932894 -64.879982)
		(width 0.11684)
		(layer "In6.Cu")
		(net "PRSNT_CPU1_N")
	)
	(segment
		(start 194.190874 -84.717382)
		(end 195.337938 -84.717382)
		(width 0.11684)
		(layer "In6.Cu")
		(net "PRSNT_CPU1_N")
	)
	(segment
		(start 259.763514 -82.110326)
		(end 269.533624 -72.340216)
		(width 0.11684)
		(layer "In6.Cu")
		(net "PRSNT_CPU1_N")
	)
	(segment
		(start 201.720704 -85.728048)
		(end 205.587092 -89.594436)
		(width 0.11684)
		(layer "In6.Cu")
		(net "PRSNT_CPU1_N")
	)
	(segment
		(start 167.411146 -96.77908)
		(end 167.411146 -96.780096)
		(width 0.11684)
		(layer "In6.Cu")
		(net "PRSNT_CPU1_N")
	)
	(segment
		(start 274.490688 -72.340216)
		(end 278.932894 -67.89801)
		(width 0.11684)
		(layer "In6.Cu")
		(net "PRSNT_CPU1_N")
	)
	(segment
		(start 171.35602 -94.010734)
		(end 171.35602 -93.261434)
		(width 0.11684)
		(layer "In6.Cu")
		(net "PRSNT_CPU1_N")
	)
	(segment
		(start 171.35602 -93.261434)
		(end 172.465492 -92.151962)
		(width 0.11684)
		(layer "In6.Cu")
		(net "PRSNT_CPU1_N")
	)
	(segment
		(start 330.24318 -53.289708)
		(end 330.52258 -53.569108)
		(width 0.11684)
		(layer "In6.Cu")
		(net "PRSNT_CPU1_N")
	)
	(segment
		(start 175.714914 -87.73414)
		(end 177.616866 -85.832188)
		(width 0.11684)
		(layer "In6.Cu")
		(net "PRSNT_CPU1_N")
	)
	(segment
		(start 278.932894 -64.879982)
		(end 287.619186 -56.19369)
		(width 0.11684)
		(layer "In6.Cu")
		(net "PRSNT_CPU1_N")
	)
	(segment
		(start 400.123152 -33.467548)
		(end 424.9674 -33.467548)
		(width 0.11684)
		(layer "In6.Cu")
		(net "PRSNT_CPU1_N")
	)
	(segment
		(start 287.619186 -56.19369)
		(end 303.903634 -56.19369)
		(width 0.11684)
		(layer "In6.Cu")
		(net "PRSNT_CPU1_N")
	)
	(segment
		(start 67.632834 -197.366382)
		(end 67.632834 -198.911718)
		(width 0.11684)
		(layer "In11.Cu")
		(net "PRSNT_CPU1_N")
	)
	(segment
		(start 38.494462 -183.22417)
		(end 38.494462 -187.535312)
		(width 0.11684)
		(layer "In11.Cu")
		(net "PRSNT_CPU1_N")
	)
	(segment
		(start 108.126022 -135.448294)
		(end 52.801774 -135.448294)
		(width 0.11684)
		(layer "In11.Cu")
		(net "PRSNT_CPU1_N")
	)
	(segment
		(start 32.578548 -177.308256)
		(end 38.494462 -183.22417)
		(width 0.11684)
		(layer "In11.Cu")
		(net "PRSNT_CPU1_N")
	)
	(segment
		(start 40.826436 -155.557982)
		(end 32.578548 -163.80587)
		(width 0.11684)
		(layer "In11.Cu")
		(net "PRSNT_CPU1_N")
	)
	(segment
		(start 60.124594 -189.858142)
		(end 67.632834 -197.366382)
		(width 0.11684)
		(layer "In11.Cu")
		(net "PRSNT_CPU1_N")
	)
	(segment
		(start 40.826436 -147.423632)
		(end 40.826436 -155.557982)
		(width 0.11684)
		(layer "In11.Cu")
		(net "PRSNT_CPU1_N")
	)
	(segment
		(start 52.801774 -135.448294)
		(end 40.826436 -147.423632)
		(width 0.11684)
		(layer "In11.Cu")
		(net "PRSNT_CPU1_N")
	)
	(segment
		(start 38.494462 -187.535312)
		(end 40.817292 -189.858142)
		(width 0.11684)
		(layer "In11.Cu")
		(net "PRSNT_CPU1_N")
	)
	(segment
		(start 68.231512 -199.510396)
		(end 68.89623 -199.510396)
		(width 0.11684)
		(layer "In11.Cu")
		(net "PRSNT_CPU1_N")
	)
	(segment
		(start 67.632834 -198.911718)
		(end 68.231512 -199.510396)
		(width 0.11684)
		(layer "In11.Cu")
		(net "PRSNT_CPU1_N")
	)
	(segment
		(start 40.817292 -189.858142)
		(end 60.124594 -189.858142)
		(width 0.11684)
		(layer "In11.Cu")
		(net "PRSNT_CPU1_N")
	)
	(segment
		(start 32.578548 -163.80587)
		(end 32.578548 -177.308256)
		(width 0.11684)
		(layer "In11.Cu")
		(net "PRSNT_CPU1_N")
	)
	(segment
		(start 113.559336 -130.01498)
		(end 108.126022 -135.448294)
		(width 0.11684)
		(layer "In11.Cu")
		(net "PRSNT_CPU1_N")
	)
	(segment
		(start 326.561958 -198.486776)
		(end 326.561958 -170.871388)
		(width 0.10668)
		(layer "F.Cu")
		(net "PRSNT_CPU0_N")
	)
	(segment
		(start 337.074256 -216.349072)
		(end 337.074256 -208.999074)
		(width 0.10668)
		(layer "F.Cu")
		(net "PRSNT_CPU0_N")
	)
	(segment
		(start 333.39786 -220.025468)
		(end 337.074256 -216.349072)
		(width 0.10668)
		(layer "F.Cu")
		(net "PRSNT_CPU0_N")
	)
	(segment
		(start 337.074256 -208.999074)
		(end 326.561958 -198.486776)
		(width 0.10668)
		(layer "F.Cu")
		(net "PRSNT_CPU0_N")
	)
	(segment
		(start 326.561958 -170.871388)
		(end 331.0255 -166.407846)
		(width 0.10668)
		(layer "F.Cu")
		(net "PRSNT_CPU0_N")
	)
	(segment
		(start 423.9514 -34.737548)
		(end 424.9674 -34.737548)
		(width 0.10668)
		(layer "F.Cu")
		(net "PRSNT_CPU0_N")
	)
	(segment
		(start 333.39786 -222.880174)
		(end 333.39786 -220.025468)
		(width 0.10668)
		(layer "F.Cu")
		(net "PRSNT_CPU0_N")
	)
	(via
		(at 331.0255 -166.407846)
		(size 0.508)
		(drill 0.254)
		(layers "F.Cu" "B.Cu")
		(net "PRSNT_CPU0_N")
	)
	(via
		(at 364.5916 -134.8232)
		(size 0.508)
		(drill 0.254)
		(layers "F.Cu" "B.Cu")
		(net "PRSNT_CPU0_N")
	)
	(via
		(at 424.9674 -34.737548)
		(size 0.508)
		(drill 0.254)
		(layers "F.Cu" "B.Cu")
		(net "PRSNT_CPU0_N")
	)
	(segment
		(start 426.1358 -34.737548)
		(end 424.9674 -34.737548)
		(width 0.10668)
		(layer "B.Cu")
		(net "PRSNT_CPU0_N")
	)
	(segment
		(start 400.742404 -128.760474)
		(end 397.83893 -131.663948)
		(width 0.11684)
		(layer "In11.Cu")
		(net "PRSNT_CPU0_N")
	)
	(segment
		(start 365.2012 -134.8232)
		(end 364.5916 -134.8232)
		(width 0.11684)
		(layer "In11.Cu")
		(net "PRSNT_CPU0_N")
	)
	(segment
		(start 397.83893 -131.663948)
		(end 368.360452 -131.663948)
		(width 0.11684)
		(layer "In11.Cu")
		(net "PRSNT_CPU0_N")
	)
	(segment
		(start 406.363424 -54.84241)
		(end 400.742404 -60.46343)
		(width 0.11684)
		(layer "In11.Cu")
		(net "PRSNT_CPU0_N")
	)
	(segment
		(start 412.97606 -54.84241)
		(end 406.363424 -54.84241)
		(width 0.11684)
		(layer "In11.Cu")
		(net "PRSNT_CPU0_N")
	)
	(segment
		(start 424.9674 -42.85107)
		(end 412.97606 -54.84241)
		(width 0.11684)
		(layer "In11.Cu")
		(net "PRSNT_CPU0_N")
	)
	(segment
		(start 400.742404 -60.46343)
		(end 400.742404 -128.760474)
		(width 0.11684)
		(layer "In11.Cu")
		(net "PRSNT_CPU0_N")
	)
	(segment
		(start 368.360452 -131.663948)
		(end 365.2012 -134.8232)
		(width 0.11684)
		(layer "In11.Cu")
		(net "PRSNT_CPU0_N")
	)
	(segment
		(start 424.9674 -34.737548)
		(end 424.9674 -42.85107)
		(width 0.11684)
		(layer "In11.Cu")
		(net "PRSNT_CPU0_N")
	)
	(segment
		(start 312.9026 -164.338)
		(end 318.8716 -170.307)
		(width 0.11684)
		(layer "In13.Cu")
		(net "PRSNT_CPU0_N")
	)
	(segment
		(start 312.9026 -147.7772)
		(end 312.9026 -164.338)
		(width 0.11684)
		(layer "In13.Cu")
		(net "PRSNT_CPU0_N")
	)
	(segment
		(start 318.8716 -170.307)
		(end 332.8162 -170.307)
		(width 0.11684)
		(layer "In13.Cu")
		(net "PRSNT_CPU0_N")
	)
	(segment
		(start 364.5916 -134.8232)
		(end 363.7026 -134.8232)
		(width 0.11684)
		(layer "In13.Cu")
		(net "PRSNT_CPU0_N")
	)
	(segment
		(start 333.1718 -169.9514)
		(end 333.1718 -168.054274)
		(width 0.11684)
		(layer "In13.Cu")
		(net "PRSNT_CPU0_N")
	)
	(segment
		(start 333.1718 -168.054274)
		(end 331.525372 -166.407846)
		(width 0.11684)
		(layer "In13.Cu")
		(net "PRSNT_CPU0_N")
	)
	(segment
		(start 363.7026 -134.8232)
		(end 359.5116 -130.6322)
		(width 0.11684)
		(layer "In13.Cu")
		(net "PRSNT_CPU0_N")
	)
	(segment
		(start 344.3224 -130.6322)
		(end 343.3318 -129.6416)
		(width 0.11684)
		(layer "In13.Cu")
		(net "PRSNT_CPU0_N")
	)
	(segment
		(start 332.8162 -170.307)
		(end 333.1718 -169.9514)
		(width 0.11684)
		(layer "In13.Cu")
		(net "PRSNT_CPU0_N")
	)
	(segment
		(start 359.5116 -130.6322)
		(end 344.3224 -130.6322)
		(width 0.11684)
		(layer "In13.Cu")
		(net "PRSNT_CPU0_N")
	)
	(segment
		(start 331.0382 -129.6416)
		(end 312.9026 -147.7772)
		(width 0.11684)
		(layer "In13.Cu")
		(net "PRSNT_CPU0_N")
	)
	(segment
		(start 331.525372 -166.407846)
		(end 331.0255 -166.407846)
		(width 0.11684)
		(layer "In13.Cu")
		(net "PRSNT_CPU0_N")
	)
	(segment
		(start 343.3318 -129.6416)
		(end 331.0382 -129.6416)
		(width 0.11684)
		(layer "In13.Cu")
		(net "PRSNT_CPU0_N")
	)
	(segment
		(start 189.861952 -16.549878)
		(end 189.861952 -18.142966)
		(width 0.10668)
		(layer "F.Cu")
		(net "PRSNT0_N")
	)
	(via
		(at 189.861952 -18.142966)
		(size 0.508)
		(drill 0.254)
		(layers "F.Cu" "B.Cu")
		(net "PRSNT0_N")
	)
	(segment
		(start 190.268352 -19.311366)
		(end 189.861952 -18.904966)
		(width 0.10668)
		(layer "B.Cu")
		(net "PRSNT0_N")
	)
	(segment
		(start 189.861952 -18.904966)
		(end 189.861952 -18.142966)
		(width 0.10668)
		(layer "B.Cu")
		(net "PRSNT0_N")
	)
	(segment
		(start 163.855908 -18.585434)
		(end 163.855908 -20.218908)
		(width 0.10668)
		(layer "F.Cu")
		(net "TP_PECI_BMC")
	)
	(segment
		(start 163.35756 -18.087086)
		(end 163.855908 -18.585434)
		(width 0.10668)
		(layer "F.Cu")
		(net "TP_PECI_BMC")
	)
	(segment
		(start 162.992562 -21.082254)
		(end 162.992562 -21.640038)
		(width 0.10668)
		(layer "F.Cu")
		(net "TP_PECI_BMC")
	)
	(segment
		(start 163.35756 -17.13103)
		(end 163.35756 -18.087086)
		(width 0.10668)
		(layer "F.Cu")
		(net "TP_PECI_BMC")
	)
	(segment
		(start 163.855908 -20.218908)
		(end 162.992562 -21.082254)
		(width 0.10668)
		(layer "F.Cu")
		(net "TP_PECI_BMC")
	)
	(segment
		(start 163.267136 -16.549878)
		(end 163.267136 -17.040606)
		(width 0.10668)
		(layer "F.Cu")
		(net "TP_PECI_BMC")
	)
	(segment
		(start 162.992562 -21.640038)
		(end 164.182552 -22.830028)
		(width 0.10668)
		(layer "F.Cu")
		(net "TP_PECI_BMC")
	)
	(segment
		(start 163.267136 -17.040606)
		(end 163.35756 -17.13103)
		(width 0.10668)
		(layer "F.Cu")
		(net "TP_PECI_BMC")
	)
	(via
		(at 164.182552 -22.830028)
		(size 0.762)
		(drill 0.381)
		(layers "F.Cu" "B.Cu")
		(net "TP_PECI_BMC")
	)
	(segment
		(start 169.558208 -47.049944)
		(end 166.437818 -47.049944)
		(width 0.10668)
		(layer "F.Cu")
		(net "PD_M2_0_DEVSLP")
	)
	(segment
		(start 165.259004 -47.292768)
		(end 164.921184 -46.954948)
		(width 0.10668)
		(layer "F.Cu")
		(net "PD_M2_0_DEVSLP")
	)
	(segment
		(start 166.437818 -47.049944)
		(end 166.194994 -47.292768)
		(width 0.10668)
		(layer "F.Cu")
		(net "PD_M2_0_DEVSLP")
	)
	(segment
		(start 166.194994 -47.292768)
		(end 165.259004 -47.292768)
		(width 0.10668)
		(layer "F.Cu")
		(net "PD_M2_0_DEVSLP")
	)
	(via
		(at 166.194994 -47.292768)
		(size 0.762)
		(drill 0.381)
		(layers "F.Cu" "B.Cu")
		(net "PD_M2_0_DEVSLP")
	)
	(segment
		(start 151.623776 -322.60921)
		(end 151.716486 -322.70192)
		(width 0.10668)
		(layer "F.Cu")
		(net "PD_ESPI_CPU1_CLK2")
	)
	(segment
		(start 122.41784 -293.260272)
		(end 122.884692 -293.52621)
		(width 0.10668)
		(layer "F.Cu")
		(net "PD_ESPI_CPU1_CLK2")
	)
	(segment
		(start 152.449784 -324.763892)
		(end 152.449784 -323.747892)
		(width 0.10668)
		(layer "F.Cu")
		(net "PD_ESPI_CPU1_CLK2")
	)
	(segment
		(start 151.716486 -322.70192)
		(end 151.716486 -323.014594)
		(width 0.10668)
		(layer "F.Cu")
		(net "PD_ESPI_CPU1_CLK2")
	)
	(segment
		(start 151.716486 -323.014594)
		(end 152.449784 -323.747892)
		(width 0.10668)
		(layer "F.Cu")
		(net "PD_ESPI_CPU1_CLK2")
	)
	(via
		(at 151.623776 -322.60921)
		(size 0.508)
		(drill 0.254)
		(layers "F.Cu" "B.Cu")
		(net "PD_ESPI_CPU1_CLK2")
	)
	(via
		(at 122.884692 -293.52621)
		(size 0.4064)
		(drill 0.2032)
		(layers "F.Cu" "B.Cu")
		(net "PD_ESPI_CPU1_CLK2")
	)
	(segment
		(start 123.309634 -294.878252)
		(end 122.884692 -294.45331)
		(width 0.10668)
		(layer "B.Cu")
		(net "PD_ESPI_CPU1_CLK2")
	)
	(segment
		(start 151.623776 -322.60921)
		(end 151.55799 -322.543424)
		(width 0.10668)
		(layer "B.Cu")
		(net "PD_ESPI_CPU1_CLK2")
	)
	(segment
		(start 150.508462 -321.813936)
		(end 148.006054 -321.813936)
		(width 0.10668)
		(layer "B.Cu")
		(net "PD_ESPI_CPU1_CLK2")
	)
	(segment
		(start 122.910854 -300.57217)
		(end 122.910854 -295.744392)
		(width 0.10668)
		(layer "B.Cu")
		(net "PD_ESPI_CPU1_CLK2")
	)
	(segment
		(start 122.910854 -295.744392)
		(end 123.309634 -295.345612)
		(width 0.10668)
		(layer "B.Cu")
		(net "PD_ESPI_CPU1_CLK2")
	)
	(segment
		(start 122.884692 -294.45331)
		(end 122.884692 -293.52621)
		(width 0.10668)
		(layer "B.Cu")
		(net "PD_ESPI_CPU1_CLK2")
	)
	(segment
		(start 143.753586 -321.414902)
		(end 122.910854 -300.57217)
		(width 0.10668)
		(layer "B.Cu")
		(net "PD_ESPI_CPU1_CLK2")
	)
	(segment
		(start 123.309634 -295.345612)
		(end 123.309634 -294.878252)
		(width 0.10668)
		(layer "B.Cu")
		(net "PD_ESPI_CPU1_CLK2")
	)
	(segment
		(start 151.23795 -322.543424)
		(end 150.508462 -321.813936)
		(width 0.10668)
		(layer "B.Cu")
		(net "PD_ESPI_CPU1_CLK2")
	)
	(segment
		(start 151.55799 -322.543424)
		(end 151.23795 -322.543424)
		(width 0.10668)
		(layer "B.Cu")
		(net "PD_ESPI_CPU1_CLK2")
	)
	(segment
		(start 147.60702 -321.414902)
		(end 143.753586 -321.414902)
		(width 0.10668)
		(layer "B.Cu")
		(net "PD_ESPI_CPU1_CLK2")
	)
	(segment
		(start 148.006054 -321.813936)
		(end 147.60702 -321.414902)
		(width 0.10668)
		(layer "B.Cu")
		(net "PD_ESPI_CPU1_CLK2")
	)
	(segment
		(start 370.357908 -293.260018)
		(end 370.82476 -293.525956)
		(width 0.10668)
		(layer "F.Cu")
		(net "PD_ESPI_CPU0_CLK2")
	)
	(via
		(at 398.74571 -328.588624)
		(size 0.6604)
		(drill 0.3302)
		(layers "F.Cu" "B.Cu")
		(net "PD_ESPI_CPU0_CLK2")
	)
	(via
		(at 370.82476 -293.525956)
		(size 0.4064)
		(drill 0.2032)
		(layers "F.Cu" "B.Cu")
		(net "PD_ESPI_CPU0_CLK2")
	)
	(segment
		(start 381.834644 -317.50381)
		(end 381.834644 -318.50457)
		(width 0.10668)
		(layer "B.Cu")
		(net "PD_ESPI_CPU0_CLK2")
	)
	(segment
		(start 370.078 -295.951402)
		(end 370.078 -305.144932)
		(width 0.10668)
		(layer "B.Cu")
		(net "PD_ESPI_CPU0_CLK2")
	)
	(segment
		(start 370.82476 -295.204642)
		(end 370.078 -295.951402)
		(width 0.10668)
		(layer "B.Cu")
		(net "PD_ESPI_CPU0_CLK2")
	)
	(segment
		(start 399.380202 -326.671432)
		(end 398.844008 -326.671432)
		(width 0.10668)
		(layer "B.Cu")
		(net "PD_ESPI_CPU0_CLK2")
	)
	(segment
		(start 391.671556 -326.414892)
		(end 391.671556 -327.167494)
		(width 0.10668)
		(layer "B.Cu")
		(net "PD_ESPI_CPU0_CLK2")
	)
	(segment
		(start 399.106898 -328.227436)
		(end 399.106898 -327.641712)
		(width 0.10668)
		(layer "B.Cu")
		(net "PD_ESPI_CPU0_CLK2")
	)
	(segment
		(start 399.106898 -327.641712)
		(end 398.820894 -327.355708)
		(width 0.10668)
		(layer "B.Cu")
		(net "PD_ESPI_CPU0_CLK2")
	)
	(segment
		(start 392.592814 -328.088752)
		(end 395.00302 -329.086972)
		(width 0.10668)
		(layer "B.Cu")
		(net "PD_ESPI_CPU0_CLK2")
	)
	(segment
		(start 395.00302 -329.086972)
		(end 398.247362 -329.086972)
		(width 0.10668)
		(layer "B.Cu")
		(net "PD_ESPI_CPU0_CLK2")
	)
	(segment
		(start 399.811748 -326.666352)
		(end 399.385282 -326.666352)
		(width 0.10668)
		(layer "B.Cu")
		(net "PD_ESPI_CPU0_CLK2")
	)
	(segment
		(start 370.82476 -293.525956)
		(end 370.82476 -295.204642)
		(width 0.10668)
		(layer "B.Cu")
		(net "PD_ESPI_CPU0_CLK2")
	)
	(segment
		(start 389.802624 -324.54596)
		(end 391.671556 -326.414892)
		(width 0.10668)
		(layer "B.Cu")
		(net "PD_ESPI_CPU0_CLK2")
	)
	(segment
		(start 370.503958 -306.173124)
		(end 381.834644 -317.50381)
		(width 0.10668)
		(layer "B.Cu")
		(net "PD_ESPI_CPU0_CLK2")
	)
	(segment
		(start 398.820894 -326.694546)
		(end 398.844008 -326.671432)
		(width 0.10668)
		(layer "B.Cu")
		(net "PD_ESPI_CPU0_CLK2")
	)
	(segment
		(start 398.247362 -329.086972)
		(end 398.74571 -328.588624)
		(width 0.10668)
		(layer "B.Cu")
		(net "PD_ESPI_CPU0_CLK2")
	)
	(segment
		(start 399.385282 -326.666352)
		(end 399.380202 -326.671432)
		(width 0.10668)
		(layer "B.Cu")
		(net "PD_ESPI_CPU0_CLK2")
	)
	(segment
		(start 381.834644 -318.50457)
		(end 387.876034 -324.54596)
		(width 0.10668)
		(layer "B.Cu")
		(net "PD_ESPI_CPU0_CLK2")
	)
	(segment
		(start 370.078 -305.144932)
		(end 370.503958 -306.173124)
		(width 0.10668)
		(layer "B.Cu")
		(net "PD_ESPI_CPU0_CLK2")
	)
	(segment
		(start 398.820894 -327.355708)
		(end 398.820894 -326.694546)
		(width 0.10668)
		(layer "B.Cu")
		(net "PD_ESPI_CPU0_CLK2")
	)
	(segment
		(start 391.671556 -327.167494)
		(end 392.592814 -328.088752)
		(width 0.10668)
		(layer "B.Cu")
		(net "PD_ESPI_CPU0_CLK2")
	)
	(segment
		(start 398.74571 -328.588624)
		(end 399.106898 -328.227436)
		(width 0.10668)
		(layer "B.Cu")
		(net "PD_ESPI_CPU0_CLK2")
	)
	(segment
		(start 387.876034 -324.54596)
		(end 389.802624 -324.54596)
		(width 0.10668)
		(layer "B.Cu")
		(net "PD_ESPI_CPU0_CLK2")
	)
	(segment
		(start 202.147932 -194.785234)
		(end 200.992232 -194.785234)
		(width 0.10668)
		(layer "F.Cu")
		(net "PD_CHL_CPU1_DIMM_SAA")
	)
	(via
		(at 200.992232 -194.785234)
		(size 0.508)
		(drill 0.254)
		(layers "F.Cu" "B.Cu")
		(net "PD_CHL_CPU1_DIMM_SAA")
	)
	(segment
		(start 201.539348 -194.91071)
		(end 202.069446 -194.91071)
		(width 0.10668)
		(layer "B.Cu")
		(net "PD_CHL_CPU1_DIMM_SAA")
	)
	(segment
		(start 201.413872 -194.785234)
		(end 201.539348 -194.91071)
		(width 0.10668)
		(layer "B.Cu")
		(net "PD_CHL_CPU1_DIMM_SAA")
	)
	(segment
		(start 202.094592 -194.885564)
		(end 202.503532 -194.885564)
		(width 0.10668)
		(layer "B.Cu")
		(net "PD_CHL_CPU1_DIMM_SAA")
	)
	(segment
		(start 202.069446 -194.91071)
		(end 202.094592 -194.885564)
		(width 0.10668)
		(layer "B.Cu")
		(net "PD_CHL_CPU1_DIMM_SAA")
	)
	(segment
		(start 200.992232 -194.785234)
		(end 201.413872 -194.785234)
		(width 0.10668)
		(layer "B.Cu")
		(net "PD_CHL_CPU1_DIMM_SAA")
	)
	(segment
		(start 450.088 -194.78498)
		(end 448.9323 -194.78498)
		(width 0.10668)
		(layer "F.Cu")
		(net "PD_CHL_CPU0_DIMM_SAA")
	)
	(via
		(at 448.9323 -194.78498)
		(size 0.508)
		(drill 0.254)
		(layers "F.Cu" "B.Cu")
		(net "PD_CHL_CPU0_DIMM_SAA")
	)
	(segment
		(start 448.9323 -194.78498)
		(end 449.35394 -194.78498)
		(width 0.10668)
		(layer "B.Cu")
		(net "PD_CHL_CPU0_DIMM_SAA")
	)
	(segment
		(start 449.45427 -194.88531)
		(end 450.4436 -194.88531)
		(width 0.10668)
		(layer "B.Cu")
		(net "PD_CHL_CPU0_DIMM_SAA")
	)
	(segment
		(start 449.35394 -194.78498)
		(end 449.45427 -194.88531)
		(width 0.10668)
		(layer "B.Cu")
		(net "PD_CHL_CPU0_DIMM_SAA")
	)
	(segment
		(start 194.604132 -194.785234)
		(end 193.448432 -194.785234)
		(width 0.10668)
		(layer "F.Cu")
		(net "PD_CHK_CPU1_DIMM_SAA")
	)
	(via
		(at 193.448432 -194.785234)
		(size 0.508)
		(drill 0.254)
		(layers "F.Cu" "B.Cu")
		(net "PD_CHK_CPU1_DIMM_SAA")
	)
	(segment
		(start 193.448432 -194.785234)
		(end 193.870072 -194.785234)
		(width 0.10668)
		(layer "B.Cu")
		(net "PD_CHK_CPU1_DIMM_SAA")
	)
	(segment
		(start 193.870072 -194.785234)
		(end 193.970402 -194.885564)
		(width 0.10668)
		(layer "B.Cu")
		(net "PD_CHK_CPU1_DIMM_SAA")
	)
	(segment
		(start 193.970402 -194.885564)
		(end 194.959732 -194.885564)
		(width 0.10668)
		(layer "B.Cu")
		(net "PD_CHK_CPU1_DIMM_SAA")
	)
	(segment
		(start 441.433204 -194.78498)
		(end 441.4139 -194.765676)
		(width 0.10668)
		(layer "F.Cu")
		(net "PD_CHK_CPU0_DIMM_SAA")
	)
	(segment
		(start 442.5442 -194.78498)
		(end 441.433204 -194.78498)
		(width 0.10668)
		(layer "F.Cu")
		(net "PD_CHK_CPU0_DIMM_SAA")
	)
	(via
		(at 441.4139 -194.765676)
		(size 0.508)
		(drill 0.254)
		(layers "F.Cu" "B.Cu")
		(net "PD_CHK_CPU0_DIMM_SAA")
	)
	(segment
		(start 441.81014 -194.78498)
		(end 441.91047 -194.88531)
		(width 0.10668)
		(layer "B.Cu")
		(net "PD_CHK_CPU0_DIMM_SAA")
	)
	(segment
		(start 441.91047 -194.88531)
		(end 442.8998 -194.88531)
		(width 0.10668)
		(layer "B.Cu")
		(net "PD_CHK_CPU0_DIMM_SAA")
	)
	(segment
		(start 441.4139 -194.765676)
		(end 441.433204 -194.78498)
		(width 0.10668)
		(layer "B.Cu")
		(net "PD_CHK_CPU0_DIMM_SAA")
	)
	(segment
		(start 441.433204 -194.78498)
		(end 441.81014 -194.78498)
		(width 0.10668)
		(layer "B.Cu")
		(net "PD_CHK_CPU0_DIMM_SAA")
	)
	(segment
		(start 187.060078 -194.785234)
		(end 185.791348 -194.785234)
		(width 0.10668)
		(layer "F.Cu")
		(net "PD_CHJ_CPU1_DIMM_SAA")
	)
	(via
		(at 185.791348 -194.785234)
		(size 0.4826)
		(drill 0.254)
		(layers "F.Cu" "B.Cu")
		(net "PD_CHJ_CPU1_DIMM_SAA")
	)
	(via
		(at 186.530234 -194.856608)
		(size 0.6604)
		(drill 0.3302)
		(layers "F.Cu" "B.Cu")
		(net "PD_CHJ_CPU1_DIMM_SAA")
	)
	(segment
		(start 186.55919 -194.885564)
		(end 187.415678 -194.885564)
		(width 0.10668)
		(layer "B.Cu")
		(net "PD_CHJ_CPU1_DIMM_SAA")
	)
	(segment
		(start 186.326018 -194.785234)
		(end 186.397392 -194.856608)
		(width 0.10668)
		(layer "B.Cu")
		(net "PD_CHJ_CPU1_DIMM_SAA")
	)
	(segment
		(start 185.791348 -194.785234)
		(end 186.326018 -194.785234)
		(width 0.10668)
		(layer "B.Cu")
		(net "PD_CHJ_CPU1_DIMM_SAA")
	)
	(segment
		(start 186.530234 -194.856608)
		(end 186.55919 -194.885564)
		(width 0.10668)
		(layer "B.Cu")
		(net "PD_CHJ_CPU1_DIMM_SAA")
	)
	(segment
		(start 186.397392 -194.856608)
		(end 186.530234 -194.856608)
		(width 0.10668)
		(layer "B.Cu")
		(net "PD_CHJ_CPU1_DIMM_SAA")
	)
	(segment
		(start 435.000146 -194.78498)
		(end 433.844446 -194.78498)
		(width 0.10668)
		(layer "F.Cu")
		(net "PD_CHJ_CPU0_DIMM_SAA")
	)
	(via
		(at 433.844446 -194.78498)
		(size 0.508)
		(drill 0.254)
		(layers "F.Cu" "B.Cu")
		(net "PD_CHJ_CPU0_DIMM_SAA")
	)
	(segment
		(start 434.366416 -194.88531)
		(end 435.355746 -194.88531)
		(width 0.10668)
		(layer "B.Cu")
		(net "PD_CHJ_CPU0_DIMM_SAA")
	)
	(segment
		(start 434.266086 -194.78498)
		(end 434.366416 -194.88531)
		(width 0.10668)
		(layer "B.Cu")
		(net "PD_CHJ_CPU0_DIMM_SAA")
	)
	(segment
		(start 433.844446 -194.78498)
		(end 434.266086 -194.78498)
		(width 0.10668)
		(layer "B.Cu")
		(net "PD_CHJ_CPU0_DIMM_SAA")
	)
	(segment
		(start 179.516024 -194.785234)
		(end 178.360324 -194.785234)
		(width 0.10668)
		(layer "F.Cu")
		(net "PD_CHI_CPU1_DIMM_SAA")
	)
	(via
		(at 178.360324 -194.785234)
		(size 0.508)
		(drill 0.254)
		(layers "F.Cu" "B.Cu")
		(net "PD_CHI_CPU1_DIMM_SAA")
	)
	(segment
		(start 178.781964 -194.785234)
		(end 178.882294 -194.885564)
		(width 0.10668)
		(layer "B.Cu")
		(net "PD_CHI_CPU1_DIMM_SAA")
	)
	(segment
		(start 178.360324 -194.785234)
		(end 178.781964 -194.785234)
		(width 0.10668)
		(layer "B.Cu")
		(net "PD_CHI_CPU1_DIMM_SAA")
	)
	(segment
		(start 178.882294 -194.885564)
		(end 179.871624 -194.885564)
		(width 0.10668)
		(layer "B.Cu")
		(net "PD_CHI_CPU1_DIMM_SAA")
	)
	(segment
		(start 427.456092 -194.78498)
		(end 426.300392 -194.78498)
		(width 0.10668)
		(layer "F.Cu")
		(net "PD_CHI_CPU0_DIMM_SAA")
	)
	(via
		(at 426.300392 -194.78498)
		(size 0.4826)
		(drill 0.254)
		(layers "F.Cu" "B.Cu")
		(net "PD_CHI_CPU0_DIMM_SAA")
	)
	(via
		(at 426.967396 -194.531234)
		(size 0.6604)
		(drill 0.3302)
		(layers "F.Cu" "B.Cu")
		(net "PD_CHI_CPU0_DIMM_SAA")
	)
	(segment
		(start 427.615096 -194.88531)
		(end 427.811692 -194.88531)
		(width 0.10668)
		(layer "B.Cu")
		(net "PD_CHI_CPU0_DIMM_SAA")
	)
	(segment
		(start 427.26102 -194.531234)
		(end 427.615096 -194.88531)
		(width 0.10668)
		(layer "B.Cu")
		(net "PD_CHI_CPU0_DIMM_SAA")
	)
	(segment
		(start 426.300392 -194.78498)
		(end 426.554138 -194.531234)
		(width 0.10668)
		(layer "B.Cu")
		(net "PD_CHI_CPU0_DIMM_SAA")
	)
	(segment
		(start 426.967396 -194.531234)
		(end 427.26102 -194.531234)
		(width 0.10668)
		(layer "B.Cu")
		(net "PD_CHI_CPU0_DIMM_SAA")
	)
	(segment
		(start 426.554138 -194.531234)
		(end 426.967396 -194.531234)
		(width 0.10668)
		(layer "B.Cu")
		(net "PD_CHI_CPU0_DIMM_SAA")
	)
	(segment
		(start 171.97197 -194.785234)
		(end 170.81627 -194.785234)
		(width 0.10668)
		(layer "F.Cu")
		(net "PD_CHH_CPU1_DIMM_SAA")
	)
	(via
		(at 170.81627 -194.785234)
		(size 0.508)
		(drill 0.254)
		(layers "F.Cu" "B.Cu")
		(net "PD_CHH_CPU1_DIMM_SAA")
	)
	(segment
		(start 171.33824 -194.885564)
		(end 172.32757 -194.885564)
		(width 0.10668)
		(layer "B.Cu")
		(net "PD_CHH_CPU1_DIMM_SAA")
	)
	(segment
		(start 170.81627 -194.785234)
		(end 171.23791 -194.785234)
		(width 0.10668)
		(layer "B.Cu")
		(net "PD_CHH_CPU1_DIMM_SAA")
	)
	(segment
		(start 171.23791 -194.785234)
		(end 171.33824 -194.885564)
		(width 0.10668)
		(layer "B.Cu")
		(net "PD_CHH_CPU1_DIMM_SAA")
	)
	(segment
		(start 419.912038 -194.78498)
		(end 418.756338 -194.78498)
		(width 0.10668)
		(layer "F.Cu")
		(net "PD_CHH_CPU0_DIMM_SAA")
	)
	(via
		(at 419.408356 -194.49415)
		(size 0.6604)
		(drill 0.3302)
		(layers "F.Cu" "B.Cu")
		(net "PD_CHH_CPU0_DIMM_SAA")
	)
	(via
		(at 418.756338 -194.78498)
		(size 0.4826)
		(drill 0.254)
		(layers "F.Cu" "B.Cu")
		(net "PD_CHH_CPU0_DIMM_SAA")
	)
	(segment
		(start 420.136828 -194.88531)
		(end 420.267638 -194.88531)
		(width 0.10668)
		(layer "B.Cu")
		(net "PD_CHH_CPU0_DIMM_SAA")
	)
	(segment
		(start 419.408356 -194.49415)
		(end 419.745668 -194.49415)
		(width 0.10668)
		(layer "B.Cu")
		(net "PD_CHH_CPU0_DIMM_SAA")
	)
	(segment
		(start 419.745668 -194.49415)
		(end 420.136828 -194.88531)
		(width 0.10668)
		(layer "B.Cu")
		(net "PD_CHH_CPU0_DIMM_SAA")
	)
	(segment
		(start 418.756338 -194.78498)
		(end 419.047168 -194.49415)
		(width 0.10668)
		(layer "B.Cu")
		(net "PD_CHH_CPU0_DIMM_SAA")
	)
	(segment
		(start 419.047168 -194.49415)
		(end 419.408356 -194.49415)
		(width 0.10668)
		(layer "B.Cu")
		(net "PD_CHH_CPU0_DIMM_SAA")
	)
	(segment
		(start 164.427916 -194.785234)
		(end 163.272216 -194.785234)
		(width 0.10668)
		(layer "F.Cu")
		(net "PD_CHG_CPU1_DIMM0_SAA")
	)
	(via
		(at 163.272216 -194.785234)
		(size 0.508)
		(drill 0.254)
		(layers "F.Cu" "B.Cu")
		(net "PD_CHG_CPU1_DIMM0_SAA")
	)
	(segment
		(start 163.272216 -194.785234)
		(end 163.693856 -194.785234)
		(width 0.10668)
		(layer "B.Cu")
		(net "PD_CHG_CPU1_DIMM0_SAA")
	)
	(segment
		(start 163.794186 -194.885564)
		(end 164.783516 -194.885564)
		(width 0.10668)
		(layer "B.Cu")
		(net "PD_CHG_CPU1_DIMM0_SAA")
	)
	(segment
		(start 163.693856 -194.785234)
		(end 163.794186 -194.885564)
		(width 0.10668)
		(layer "B.Cu")
		(net "PD_CHG_CPU1_DIMM0_SAA")
	)
	(segment
		(start 412.367984 -194.78498)
		(end 410.7688 -194.78498)
		(width 0.10668)
		(layer "F.Cu")
		(net "PD_CHG_CPU0_DIMM0_SAA")
	)
	(via
		(at 410.7688 -194.78498)
		(size 0.508)
		(drill 0.254)
		(layers "F.Cu" "B.Cu")
		(net "PD_CHG_CPU0_DIMM0_SAA")
	)
	(segment
		(start 411.212284 -194.78498)
		(end 411.312614 -194.88531)
		(width 0.10668)
		(layer "B.Cu")
		(net "PD_CHG_CPU0_DIMM0_SAA")
	)
	(segment
		(start 411.312614 -194.88531)
		(end 412.723584 -194.88531)
		(width 0.10668)
		(layer "B.Cu")
		(net "PD_CHG_CPU0_DIMM0_SAA")
	)
	(segment
		(start 410.7688 -194.78498)
		(end 411.212284 -194.78498)
		(width 0.10668)
		(layer "B.Cu")
		(net "PD_CHG_CPU0_DIMM0_SAA")
	)
	(segment
		(start 15.73276 -195.28282)
		(end 15.65148 -195.20154)
		(width 0.10668)
		(layer "F.Cu")
		(net "PD_CHF_CPU1_DIMM_SAA")
	)
	(segment
		(start 16.557752 -194.785234)
		(end 16.060166 -195.28282)
		(width 0.10668)
		(layer "F.Cu")
		(net "PD_CHF_CPU1_DIMM_SAA")
	)
	(segment
		(start 17.608042 -194.785234)
		(end 16.557752 -194.785234)
		(width 0.10668)
		(layer "F.Cu")
		(net "PD_CHF_CPU1_DIMM_SAA")
	)
	(segment
		(start 16.060166 -195.28282)
		(end 15.73276 -195.28282)
		(width 0.10668)
		(layer "F.Cu")
		(net "PD_CHF_CPU1_DIMM_SAA")
	)
	(via
		(at 15.65148 -195.20154)
		(size 0.508)
		(drill 0.254)
		(layers "F.Cu" "B.Cu")
		(net "PD_CHF_CPU1_DIMM_SAA")
	)
	(segment
		(start 16.550386 -196.552566)
		(end 16.550386 -196.100446)
		(width 0.10668)
		(layer "B.Cu")
		(net "PD_CHF_CPU1_DIMM_SAA")
	)
	(segment
		(start 16.550386 -196.100446)
		(end 15.65148 -195.20154)
		(width 0.10668)
		(layer "B.Cu")
		(net "PD_CHF_CPU1_DIMM_SAA")
	)
	(segment
		(start 265.54811 -194.78498)
		(end 264.39241 -194.78498)
		(width 0.10668)
		(layer "F.Cu")
		(net "PD_CHF_CPU0_DIMM_SAA")
	)
	(via
		(at 264.39241 -194.78498)
		(size 0.508)
		(drill 0.254)
		(layers "F.Cu" "B.Cu")
		(net "PD_CHF_CPU0_DIMM_SAA")
	)
	(segment
		(start 264.91438 -194.88531)
		(end 265.90371 -194.88531)
		(width 0.10668)
		(layer "B.Cu")
		(net "PD_CHF_CPU0_DIMM_SAA")
	)
	(segment
		(start 264.81405 -194.78498)
		(end 264.91438 -194.88531)
		(width 0.10668)
		(layer "B.Cu")
		(net "PD_CHF_CPU0_DIMM_SAA")
	)
	(segment
		(start 264.39241 -194.78498)
		(end 264.81405 -194.78498)
		(width 0.10668)
		(layer "B.Cu")
		(net "PD_CHF_CPU0_DIMM_SAA")
	)
	(segment
		(start 25.152096 -194.785234)
		(end 23.996396 -194.785234)
		(width 0.10668)
		(layer "F.Cu")
		(net "PD_CHE_CPU1_DIMM_SAA")
	)
	(via
		(at 23.996396 -194.785234)
		(size 0.508)
		(drill 0.254)
		(layers "F.Cu" "B.Cu")
		(net "PD_CHE_CPU1_DIMM_SAA")
	)
	(segment
		(start 24.418036 -194.785234)
		(end 24.518366 -194.885564)
		(width 0.10668)
		(layer "B.Cu")
		(net "PD_CHE_CPU1_DIMM_SAA")
	)
	(segment
		(start 24.518366 -194.885564)
		(end 25.52319 -194.885564)
		(width 0.10668)
		(layer "B.Cu")
		(net "PD_CHE_CPU1_DIMM_SAA")
	)
	(segment
		(start 23.996396 -194.785234)
		(end 24.418036 -194.785234)
		(width 0.10668)
		(layer "B.Cu")
		(net "PD_CHE_CPU1_DIMM_SAA")
	)
	(segment
		(start 273.092164 -194.78498)
		(end 271.936464 -194.78498)
		(width 0.10668)
		(layer "F.Cu")
		(net "PD_CHE_CPU0_DIMM_SAA")
	)
	(via
		(at 271.936464 -194.78498)
		(size 0.508)
		(drill 0.254)
		(layers "F.Cu" "B.Cu")
		(net "PD_CHE_CPU0_DIMM_SAA")
	)
	(segment
		(start 271.936464 -194.78498)
		(end 272.358104 -194.78498)
		(width 0.10668)
		(layer "B.Cu")
		(net "PD_CHE_CPU0_DIMM_SAA")
	)
	(segment
		(start 272.458434 -194.88531)
		(end 273.447764 -194.88531)
		(width 0.10668)
		(layer "B.Cu")
		(net "PD_CHE_CPU0_DIMM_SAA")
	)
	(segment
		(start 272.358104 -194.78498)
		(end 272.458434 -194.88531)
		(width 0.10668)
		(layer "B.Cu")
		(net "PD_CHE_CPU0_DIMM_SAA")
	)
	(segment
		(start 32.695896 -194.785234)
		(end 31.540196 -194.785234)
		(width 0.10668)
		(layer "F.Cu")
		(net "PD_CHD_CPU1_DIMM_SAA")
	)
	(via
		(at 31.540196 -194.785234)
		(size 0.508)
		(drill 0.254)
		(layers "F.Cu" "B.Cu")
		(net "PD_CHD_CPU1_DIMM_SAA")
	)
	(segment
		(start 31.540196 -194.785234)
		(end 31.961836 -194.785234)
		(width 0.10668)
		(layer "B.Cu")
		(net "PD_CHD_CPU1_DIMM_SAA")
	)
	(segment
		(start 31.961836 -194.785234)
		(end 32.062166 -194.885564)
		(width 0.10668)
		(layer "B.Cu")
		(net "PD_CHD_CPU1_DIMM_SAA")
	)
	(segment
		(start 32.062166 -194.885564)
		(end 33.067244 -194.885564)
		(width 0.10668)
		(layer "B.Cu")
		(net "PD_CHD_CPU1_DIMM_SAA")
	)
	(segment
		(start 280.635964 -194.78498)
		(end 279.480264 -194.78498)
		(width 0.10668)
		(layer "F.Cu")
		(net "PD_CHD_CPU0_DIMM_SAA")
	)
	(via
		(at 279.480264 -194.78498)
		(size 0.508)
		(drill 0.254)
		(layers "F.Cu" "B.Cu")
		(net "PD_CHD_CPU0_DIMM_SAA")
	)
	(segment
		(start 279.480264 -194.78498)
		(end 279.901904 -194.78498)
		(width 0.10668)
		(layer "B.Cu")
		(net "PD_CHD_CPU0_DIMM_SAA")
	)
	(segment
		(start 279.901904 -194.78498)
		(end 280.002234 -194.88531)
		(width 0.10668)
		(layer "B.Cu")
		(net "PD_CHD_CPU0_DIMM_SAA")
	)
	(segment
		(start 280.002234 -194.88531)
		(end 280.991564 -194.88531)
		(width 0.10668)
		(layer "B.Cu")
		(net "PD_CHD_CPU0_DIMM_SAA")
	)
	(segment
		(start 40.23995 -194.785234)
		(end 39.08425 -194.785234)
		(width 0.10668)
		(layer "F.Cu")
		(net "PD_CHC_CPU1_DIMM_SAA")
	)
	(via
		(at 39.08425 -194.785234)
		(size 0.508)
		(drill 0.254)
		(layers "F.Cu" "B.Cu")
		(net "PD_CHC_CPU1_DIMM_SAA")
	)
	(segment
		(start 39.08425 -194.785234)
		(end 39.50589 -194.785234)
		(width 0.10668)
		(layer "B.Cu")
		(net "PD_CHC_CPU1_DIMM_SAA")
	)
	(segment
		(start 39.50589 -194.785234)
		(end 39.60622 -194.885564)
		(width 0.10668)
		(layer "B.Cu")
		(net "PD_CHC_CPU1_DIMM_SAA")
	)
	(segment
		(start 39.60622 -194.885564)
		(end 40.59555 -194.885564)
		(width 0.10668)
		(layer "B.Cu")
		(net "PD_CHC_CPU1_DIMM_SAA")
	)
	(segment
		(start 288.180018 -194.78498)
		(end 287.024318 -194.78498)
		(width 0.10668)
		(layer "F.Cu")
		(net "PD_CHC_CPU0_DIMM_SAA")
	)
	(via
		(at 287.024318 -194.78498)
		(size 0.508)
		(drill 0.254)
		(layers "F.Cu" "B.Cu")
		(net "PD_CHC_CPU0_DIMM_SAA")
	)
	(segment
		(start 287.546288 -194.88531)
		(end 288.535618 -194.88531)
		(width 0.10668)
		(layer "B.Cu")
		(net "PD_CHC_CPU0_DIMM_SAA")
	)
	(segment
		(start 287.445958 -194.78498)
		(end 287.546288 -194.88531)
		(width 0.10668)
		(layer "B.Cu")
		(net "PD_CHC_CPU0_DIMM_SAA")
	)
	(segment
		(start 287.024318 -194.78498)
		(end 287.445958 -194.78498)
		(width 0.10668)
		(layer "B.Cu")
		(net "PD_CHC_CPU0_DIMM_SAA")
	)
	(segment
		(start 47.784004 -194.785234)
		(end 46.628304 -194.785234)
		(width 0.10668)
		(layer "F.Cu")
		(net "PD_CHB_CPU1_DIMM_SAA")
	)
	(via
		(at 46.628304 -194.785234)
		(size 0.508)
		(drill 0.254)
		(layers "F.Cu" "B.Cu")
		(net "PD_CHB_CPU1_DIMM_SAA")
	)
	(segment
		(start 47.150274 -194.885564)
		(end 48.155098 -194.885564)
		(width 0.10668)
		(layer "B.Cu")
		(net "PD_CHB_CPU1_DIMM_SAA")
	)
	(segment
		(start 47.049944 -194.785234)
		(end 47.150274 -194.885564)
		(width 0.10668)
		(layer "B.Cu")
		(net "PD_CHB_CPU1_DIMM_SAA")
	)
	(segment
		(start 46.628304 -194.785234)
		(end 47.049944 -194.785234)
		(width 0.10668)
		(layer "B.Cu")
		(net "PD_CHB_CPU1_DIMM_SAA")
	)
	(segment
		(start 295.724072 -194.78498)
		(end 294.568372 -194.78498)
		(width 0.10668)
		(layer "F.Cu")
		(net "PD_CHB_CPU0_DIMM_SAA")
	)
	(via
		(at 294.568372 -194.78498)
		(size 0.508)
		(drill 0.254)
		(layers "F.Cu" "B.Cu")
		(net "PD_CHB_CPU0_DIMM_SAA")
	)
	(segment
		(start 294.990012 -194.78498)
		(end 295.090342 -194.88531)
		(width 0.10668)
		(layer "B.Cu")
		(net "PD_CHB_CPU0_DIMM_SAA")
	)
	(segment
		(start 295.090342 -194.88531)
		(end 296.079672 -194.88531)
		(width 0.10668)
		(layer "B.Cu")
		(net "PD_CHB_CPU0_DIMM_SAA")
	)
	(segment
		(start 294.568372 -194.78498)
		(end 294.990012 -194.78498)
		(width 0.10668)
		(layer "B.Cu")
		(net "PD_CHB_CPU0_DIMM_SAA")
	)
	(segment
		(start 55.328058 -194.785234)
		(end 54.044088 -194.785234)
		(width 0.10668)
		(layer "F.Cu")
		(net "PD_CHA_CPU1_DIMM0_SAA")
	)
	(via
		(at 54.801262 -194.885564)
		(size 0.6604)
		(drill 0.3302)
		(layers "F.Cu" "B.Cu")
		(net "PD_CHA_CPU1_DIMM0_SAA")
	)
	(via
		(at 54.044088 -194.785234)
		(size 0.4826)
		(drill 0.254)
		(layers "F.Cu" "B.Cu")
		(net "PD_CHA_CPU1_DIMM0_SAA")
	)
	(segment
		(start 54.694328 -194.885564)
		(end 54.801262 -194.885564)
		(width 0.10668)
		(layer "B.Cu")
		(net "PD_CHA_CPU1_DIMM0_SAA")
	)
	(segment
		(start 54.044088 -194.785234)
		(end 54.593998 -194.785234)
		(width 0.10668)
		(layer "B.Cu")
		(net "PD_CHA_CPU1_DIMM0_SAA")
	)
	(segment
		(start 54.801262 -194.885564)
		(end 55.673752 -194.885564)
		(width 0.10668)
		(layer "B.Cu")
		(net "PD_CHA_CPU1_DIMM0_SAA")
	)
	(segment
		(start 54.593998 -194.785234)
		(end 54.694328 -194.885564)
		(width 0.10668)
		(layer "B.Cu")
		(net "PD_CHA_CPU1_DIMM0_SAA")
	)
	(segment
		(start 303.268126 -194.78498)
		(end 301.95647 -194.78498)
		(width 0.10668)
		(layer "F.Cu")
		(net "PD_CHA_CPU0_DIMM0_SAA")
	)
	(via
		(at 302.695356 -194.88531)
		(size 0.6604)
		(drill 0.3302)
		(layers "F.Cu" "B.Cu")
		(net "PD_CHA_CPU0_DIMM0_SAA")
	)
	(via
		(at 301.95647 -194.78498)
		(size 0.4826)
		(drill 0.254)
		(layers "F.Cu" "B.Cu")
		(net "PD_CHA_CPU0_DIMM0_SAA")
	)
	(segment
		(start 301.95647 -194.78498)
		(end 302.534066 -194.78498)
		(width 0.10668)
		(layer "B.Cu")
		(net "PD_CHA_CPU0_DIMM0_SAA")
	)
	(segment
		(start 302.534066 -194.78498)
		(end 302.634396 -194.88531)
		(width 0.10668)
		(layer "B.Cu")
		(net "PD_CHA_CPU0_DIMM0_SAA")
	)
	(segment
		(start 302.634396 -194.88531)
		(end 302.695356 -194.88531)
		(width 0.10668)
		(layer "B.Cu")
		(net "PD_CHA_CPU0_DIMM0_SAA")
	)
	(segment
		(start 302.695356 -194.88531)
		(end 303.623726 -194.88531)
		(width 0.10668)
		(layer "B.Cu")
		(net "PD_CHA_CPU0_DIMM0_SAA")
	)
	(segment
		(start 422.3766 -36.007548)
		(end 423.9514 -36.007548)
		(width 0.10668)
		(layer "F.Cu")
		(net "PD_BIOS_DEBUG_MODE")
	)
	(segment
		(start 421.1574 -36.007548)
		(end 422.3766 -36.007548)
		(width 0.10668)
		(layer "F.Cu")
		(net "PD_BIOS_DEBUG_MODE")
	)
	(via
		(at 422.3766 -36.007548)
		(size 0.762)
		(drill 0.381)
		(layers "F.Cu" "B.Cu")
		(net "PD_BIOS_DEBUG_MODE")
	)
	(segment
		(start 266.17041 -423.026586)
		(end 265.56843 -422.424606)
		(width 0.10668)
		(layer "F.Cu")
		(net "PDB_PRSNT_N")
	)
	(segment
		(start 266.726416 -423.026586)
		(end 266.17041 -423.026586)
		(width 0.10668)
		(layer "F.Cu")
		(net "PDB_PRSNT_N")
	)
	(via
		(at 265.56843 -422.424606)
		(size 0.508)
		(drill 0.254)
		(layers "F.Cu" "B.Cu")
		(net "PDB_PRSNT_N")
	)
	(via
		(at 234.007406 -423.249598)
		(size 0.508)
		(drill 0.254)
		(layers "F.Cu" "B.Cu")
		(net "PDB_PRSNT_N")
	)
	(segment
		(start 233.37012 -427.96206)
		(end 233.37012 -423.249598)
		(width 0.10668)
		(layer "B.Cu")
		(net "PDB_PRSNT_N")
	)
	(segment
		(start 233.37012 -423.249598)
		(end 234.007406 -423.249598)
		(width 0.10668)
		(layer "B.Cu")
		(net "PDB_PRSNT_N")
	)
	(segment
		(start 239.030002 -423.249598)
		(end 239.893348 -424.112944)
		(width 0.11684)
		(layer "In13.Cu")
		(net "PDB_PRSNT_N")
	)
	(segment
		(start 234.007406 -423.249598)
		(end 239.030002 -423.249598)
		(width 0.11684)
		(layer "In13.Cu")
		(net "PDB_PRSNT_N")
	)
	(segment
		(start 239.893348 -424.112944)
		(end 263.880092 -424.112944)
		(width 0.11684)
		(layer "In13.Cu")
		(net "PDB_PRSNT_N")
	)
	(segment
		(start 263.880092 -424.112944)
		(end 265.56843 -422.424606)
		(width 0.11684)
		(layer "In13.Cu")
		(net "PDB_PRSNT_N")
	)
	(segment
		(start 169.147744 -59.04357)
		(end 178.399694 -59.04357)
		(width 0.10668)
		(layer "F.Cu")
		(net "PCIE_M2_SSD0_PRSNT_N")
	)
	(segment
		(start 177.108358 -56.299862)
		(end 180.323998 -56.299862)
		(width 0.10668)
		(layer "F.Cu")
		(net "PCIE_M2_SSD0_PRSNT_N")
	)
	(segment
		(start 180.377084 -57.06618)
		(end 180.377084 -56.352948)
		(width 0.10668)
		(layer "F.Cu")
		(net "PCIE_M2_SSD0_PRSNT_N")
	)
	(segment
		(start 178.399694 -59.04357)
		(end 180.377084 -57.06618)
		(width 0.10668)
		(layer "F.Cu")
		(net "PCIE_M2_SSD0_PRSNT_N")
	)
	(segment
		(start 180.323998 -56.299862)
		(end 180.377084 -56.352948)
		(width 0.10668)
		(layer "F.Cu")
		(net "PCIE_M2_SSD0_PRSNT_N")
	)
	(segment
		(start 178.72202 -112.25276)
		(end 178.33213 -111.86287)
		(width 0.10668)
		(layer "F.Cu")
		(net "PCIE_M2_SSD0_PRSNT_N")
	)
	(segment
		(start 168.63441 -59.556904)
		(end 169.147744 -59.04357)
		(width 0.10668)
		(layer "F.Cu")
		(net "PCIE_M2_SSD0_PRSNT_N")
	)
	(via
		(at 178.33213 -111.86287)
		(size 0.4572)
		(drill 0.254)
		(layers "F.Cu" "B.Cu")
		(net "PCIE_M2_SSD0_PRSNT_N")
	)
	(via
		(at 168.63441 -59.556904)
		(size 0.508)
		(drill 0.254)
		(layers "F.Cu" "B.Cu")
		(net "PCIE_M2_SSD0_PRSNT_N")
	)
	(segment
		(start 177.37582 -111.86287)
		(end 178.33213 -111.86287)
		(width 0.11684)
		(layer "In11.Cu")
		(net "PCIE_M2_SSD0_PRSNT_N")
	)
	(segment
		(start 175.998632 -101.7397)
		(end 175.998632 -104.591358)
		(width 0.11684)
		(layer "In11.Cu")
		(net "PCIE_M2_SSD0_PRSNT_N")
	)
	(segment
		(start 173.447202 -97.557336)
		(end 174.08144 -98.191574)
		(width 0.11684)
		(layer "In11.Cu")
		(net "PCIE_M2_SSD0_PRSNT_N")
	)
	(segment
		(start 168.67759 -78.68539)
		(end 174.712884 -84.720684)
		(width 0.11684)
		(layer "In11.Cu")
		(net "PCIE_M2_SSD0_PRSNT_N")
	)
	(segment
		(start 173.447202 -90.472514)
		(end 173.447202 -97.557336)
		(width 0.11684)
		(layer "In11.Cu")
		(net "PCIE_M2_SSD0_PRSNT_N")
	)
	(segment
		(start 175.484282 -108.995464)
		(end 177.13198 -110.643162)
		(width 0.11684)
		(layer "In11.Cu")
		(net "PCIE_M2_SSD0_PRSNT_N")
	)
	(segment
		(start 174.712884 -84.720684)
		(end 174.712884 -89.206832)
		(width 0.11684)
		(layer "In11.Cu")
		(net "PCIE_M2_SSD0_PRSNT_N")
	)
	(segment
		(start 175.998632 -104.591358)
		(end 175.484282 -105.105708)
		(width 0.11684)
		(layer "In11.Cu")
		(net "PCIE_M2_SSD0_PRSNT_N")
	)
	(segment
		(start 174.712884 -89.206832)
		(end 173.447202 -90.472514)
		(width 0.11684)
		(layer "In11.Cu")
		(net "PCIE_M2_SSD0_PRSNT_N")
	)
	(segment
		(start 174.08144 -98.191574)
		(end 174.08144 -99.822508)
		(width 0.11684)
		(layer "In11.Cu")
		(net "PCIE_M2_SSD0_PRSNT_N")
	)
	(segment
		(start 168.63441 -59.556904)
		(end 168.67759 -59.600084)
		(width 0.11684)
		(layer "In11.Cu")
		(net "PCIE_M2_SSD0_PRSNT_N")
	)
	(segment
		(start 168.67759 -59.600084)
		(end 168.67759 -78.68539)
		(width 0.11684)
		(layer "In11.Cu")
		(net "PCIE_M2_SSD0_PRSNT_N")
	)
	(segment
		(start 174.08144 -99.822508)
		(end 175.998632 -101.7397)
		(width 0.11684)
		(layer "In11.Cu")
		(net "PCIE_M2_SSD0_PRSNT_N")
	)
	(segment
		(start 177.13198 -110.643162)
		(end 177.13198 -111.61903)
		(width 0.11684)
		(layer "In11.Cu")
		(net "PCIE_M2_SSD0_PRSNT_N")
	)
	(segment
		(start 175.484282 -105.105708)
		(end 175.484282 -108.995464)
		(width 0.11684)
		(layer "In11.Cu")
		(net "PCIE_M2_SSD0_PRSNT_N")
	)
	(segment
		(start 177.13198 -111.61903)
		(end 177.37582 -111.86287)
		(width 0.11684)
		(layer "In11.Cu")
		(net "PCIE_M2_SSD0_PRSNT_N")
	)
	(segment
		(start 345.8337 -15.449296)
		(end 345.8337 -14.645132)
		(width 0.10668)
		(layer "F.Cu")
		(net "P5V_STBY_PWR_LED")
	)
	(segment
		(start 344.3605 -15.579344)
		(end 344.3605 -14.360144)
		(width 0.10668)
		(layer "F.Cu")
		(net "P5V_STBY_PWR_LED")
	)
	(segment
		(start 345.548712 -14.360144)
		(end 344.3605 -14.360144)
		(width 0.10668)
		(layer "F.Cu")
		(net "P5V_STBY_PWR_LED")
	)
	(segment
		(start 345.8337 -14.645132)
		(end 345.548712 -14.360144)
		(width 0.10668)
		(layer "F.Cu")
		(net "P5V_STBY_PWR_LED")
	)
	(via
		(at 344.3605 -14.360144)
		(size 0.762)
		(drill 0.381)
		(layers "F.Cu" "B.Cu")
		(net "P5V_STBY_PWR_LED")
	)
	(segment
		(start 406.875996 -134.931404)
		(end 407.64206 -134.931404)
		(width 0.254)
		(layer "F.Cu")
		(net "P5V_AUX_VCC")
	)
	(segment
		(start 414.67024 -142.483078)
		(end 415.391854 -142.483078)
		(width 0.254)
		(layer "F.Cu")
		(net "P5V_AUX_VCC")
	)
	(segment
		(start 416.136836 -142.585948)
		(end 416.10915 -142.558262)
		(width 0.381)
		(layer "F.Cu")
		(net "P5V_AUX_VCC")
	)
	(segment
		(start 415.391854 -142.483078)
		(end 415.467038 -142.558262)
		(width 0.254)
		(layer "F.Cu")
		(net "P5V_AUX_VCC")
	)
	(segment
		(start 416.10915 -142.558262)
		(end 415.467038 -142.558262)
		(width 0.381)
		(layer "F.Cu")
		(net "P5V_AUX_VCC")
	)
	(via
		(at 415.467038 -142.558262)
		(size 0.508)
		(drill 0.254)
		(layers "F.Cu" "B.Cu")
		(net "P5V_AUX_VCC")
	)
	(via
		(at 407.64206 -134.931404)
		(size 0.508)
		(drill 0.254)
		(layers "F.Cu" "B.Cu")
		(net "P5V_AUX_VCC")
	)
	(segment
		(start 415.467038 -142.558262)
		(end 413.903668 -142.558262)
		(width 0.508)
		(layer "B.Cu")
		(net "P5V_AUX_VCC")
	)
	(segment
		(start 411.576266 -140.23086)
		(end 411.576266 -139.82954)
		(width 0.508)
		(layer "B.Cu")
		(net "P5V_AUX_VCC")
	)
	(segment
		(start 413.903668 -142.558262)
		(end 411.576266 -140.23086)
		(width 0.508)
		(layer "B.Cu")
		(net "P5V_AUX_VCC")
	)
	(segment
		(start 409.522422 -141.481302)
		(end 410.820616 -142.779496)
		(width 0.254)
		(layer "In2.Cu")
		(net "P5V_AUX_VCC")
	)
	(segment
		(start 415.245804 -142.779496)
		(end 415.467038 -142.558262)
		(width 0.254)
		(layer "In2.Cu")
		(net "P5V_AUX_VCC")
	)
	(segment
		(start 410.820616 -142.779496)
		(end 415.245804 -142.779496)
		(width 0.254)
		(layer "In2.Cu")
		(net "P5V_AUX_VCC")
	)
	(segment
		(start 407.64206 -134.931404)
		(end 409.522422 -136.811766)
		(width 0.254)
		(layer "In2.Cu")
		(net "P5V_AUX_VCC")
	)
	(segment
		(start 409.522422 -136.811766)
		(end 409.522422 -141.481302)
		(width 0.254)
		(layer "In2.Cu")
		(net "P5V_AUX_VCC")
	)
	(segment
		(start 410.184346 -140.884656)
		(end 409.834842 -140.884656)
		(width 0.1778)
		(layer "F.Cu")
		(net "P5V_AUX_REF")
	)
	(segment
		(start 410.285946 -140.783056)
		(end 410.184346 -140.884656)
		(width 0.1778)
		(layer "F.Cu")
		(net "P5V_AUX_REF")
	)
	(segment
		(start 411.870144 -140.783056)
		(end 410.285946 -140.783056)
		(width 0.1778)
		(layer "F.Cu")
		(net "P5V_AUX_REF")
	)
	(segment
		(start 411.142942 -141.183106)
		(end 410.647642 -141.183106)
		(width 0.2032)
		(layer "F.Cu")
		(net "P5V_AUX_MODE")
	)
	(segment
		(start 411.870144 -141.183106)
		(end 411.142942 -141.183106)
		(width 0.1778)
		(layer "F.Cu")
		(net "P5V_AUX_MODE")
	)
	(segment
		(start 410.647642 -141.183106)
		(end 410.514292 -141.316456)
		(width 0.2032)
		(layer "F.Cu")
		(net "P5V_AUX_MODE")
	)
	(via
		(at 410.514292 -141.316456)
		(size 0.508)
		(drill 0.254)
		(layers "F.Cu" "B.Cu")
		(net "P5V_AUX_MODE")
	)
	(segment
		(start 410.421328 -141.40942)
		(end 410.514292 -141.316456)
		(width 0.1524)
		(layer "B.Cu")
		(net "P5V_AUX_MODE")
	)
	(segment
		(start 409.071826 -141.40942)
		(end 410.421328 -141.40942)
		(width 0.1524)
		(layer "B.Cu")
		(net "P5V_AUX_MODE")
	)
	(segment
		(start 410.485336 -139.47267)
		(end 409.975558 -138.962892)
		(width 0.254)
		(layer "F.Cu")
		(net "P5V_AUX_FB")
	)
	(segment
		(start 411.009592 -139.614656)
		(end 410.799788 -139.614656)
		(width 0.1778)
		(layer "F.Cu")
		(net "P5V_AUX_FB")
	)
	(segment
		(start 409.63596 -138.962892)
		(end 409.79217 -138.962892)
		(width 0.254)
		(layer "F.Cu")
		(net "P5V_AUX_FB")
	)
	(segment
		(start 410.799788 -139.614656)
		(end 410.627322 -139.614656)
		(width 0.254)
		(layer "F.Cu")
		(net "P5V_AUX_FB")
	)
	(segment
		(start 411.377892 -139.982956)
		(end 411.009592 -139.614656)
		(width 0.1778)
		(layer "F.Cu")
		(net "P5V_AUX_FB")
	)
	(segment
		(start 408.83586 -139.762992)
		(end 409.63596 -138.962892)
		(width 0.254)
		(layer "F.Cu")
		(net "P5V_AUX_FB")
	)
	(segment
		(start 411.870144 -139.982956)
		(end 411.377892 -139.982956)
		(width 0.1778)
		(layer "F.Cu")
		(net "P5V_AUX_FB")
	)
	(segment
		(start 410.627322 -139.614656)
		(end 410.485336 -139.47267)
		(width 0.254)
		(layer "F.Cu")
		(net "P5V_AUX_FB")
	)
	(segment
		(start 408.758644 -139.762992)
		(end 408.83586 -139.762992)
		(width 0.254)
		(layer "F.Cu")
		(net "P5V_AUX_FB")
	)
	(segment
		(start 409.975558 -138.962892)
		(end 409.79217 -138.962892)
		(width 0.254)
		(layer "F.Cu")
		(net "P5V_AUX_FB")
	)
	(segment
		(start 407.742644 -139.762992)
		(end 408.758644 -139.762992)
		(width 0.254)
		(layer "F.Cu")
		(net "P5V_AUX_FB")
	)
	(via
		(at 410.485336 -139.47267)
		(size 0.508)
		(drill 0.254)
		(layers "F.Cu" "B.Cu")
		(net "P5V_AUX_FB")
	)
	(segment
		(start 411.870144 -141.583156)
		(end 411.428692 -141.583156)
		(width 0.1778)
		(layer "F.Cu")
		(net "P5V_AUX_CS")
	)
	(segment
		(start 410.298646 -142.009368)
		(end 409.850844 -142.009368)
		(width 0.2032)
		(layer "F.Cu")
		(net "P5V_AUX_CS")
	)
	(segment
		(start 411.428692 -141.583156)
		(end 411.327346 -141.583156)
		(width 0.2032)
		(layer "F.Cu")
		(net "P5V_AUX_CS")
	)
	(segment
		(start 411.327346 -141.583156)
		(end 410.298646 -142.009368)
		(width 0.2032)
		(layer "F.Cu")
		(net "P5V_AUX_CS")
	)
	(segment
		(start 344.3605 -16.379444)
		(end 344.3605 -16.989044)
		(width 0.4572)
		(layer "F.Cu")
		(net "P5V_AUX")
	)
	(segment
		(start 140.765784 -47.709074)
		(end 140.765784 -48.325024)
		(width 0.4572)
		(layer "F.Cu")
		(net "P5V_AUX")
	)
	(segment
		(start 11.7221 -394.62837)
		(end 12.08786 -394.62837)
		(width 0.381)
		(layer "F.Cu")
		(net "P5V_AUX")
	)
	(segment
		(start 104.469946 -52.46243)
		(end 104.469946 -48.077374)
		(width 0.4572)
		(layer "F.Cu")
		(net "P5V_AUX")
	)
	(segment
		(start 408.02052 -151.973788)
		(end 408.697176 -152.650444)
		(width 0.254)
		(layer "F.Cu")
		(net "P5V_AUX")
	)
	(segment
		(start 407.616152 -138.962892)
		(end 407.742644 -138.962892)
		(width 0.254)
		(layer "F.Cu")
		(net "P5V_AUX")
	)
	(segment
		(start 407.204672 -142.319248)
		(end 407.204672 -139.374372)
		(width 0.254)
		(layer "F.Cu")
		(net "P5V_AUX")
	)
	(segment
		(start 384.513328 -140.202158)
		(end 385.149344 -140.202158)
		(width 0.381)
		(layer "F.Cu")
		(net "P5V_AUX")
	)
	(segment
		(start 347.4593 -16.379444)
		(end 347.4593 -16.989044)
		(width 0.4572)
		(layer "F.Cu")
		(net "P5V_AUX")
	)
	(segment
		(start 102.618794 -142.86992)
		(end 102.348284 -142.59941)
		(width 0.381)
		(layer "F.Cu")
		(net "P5V_AUX")
	)
	(segment
		(start 4.88442 -357.912162)
		(end 8.233918 -354.562664)
		(width 0.381)
		(layer "F.Cu")
		(net "P5V_AUX")
	)
	(segment
		(start 418.896038 -354.163122)
		(end 418.896038 -354.772722)
		(width 0.3556)
		(layer "F.Cu")
		(net "P5V_AUX")
	)
	(segment
		(start 365.318548 -14.050518)
		(end 365.318548 -13.434568)
		(width 0.4572)
		(layer "F.Cu")
		(net "P5V_AUX")
	)
	(segment
		(start 408.758644 -138.962892)
		(end 407.742644 -138.962892)
		(width 0.254)
		(layer "F.Cu")
		(net "P5V_AUX")
	)
	(segment
		(start 105.258108 -142.061438)
		(end 104.449626 -142.86992)
		(width 0.381)
		(layer "F.Cu")
		(net "P5V_AUX")
	)
	(segment
		(start 24.057102 -353.61753)
		(end 24.057102 -352.021648)
		(width 0.381)
		(layer "F.Cu")
		(net "P5V_AUX")
	)
	(segment
		(start 269.348204 -363.607604)
		(end 268.768322 -364.187486)
		(width 0.381)
		(layer "F.Cu")
		(net "P5V_AUX")
	)
	(segment
		(start 319.242186 -360.66095)
		(end 319.428876 -360.47426)
		(width 0.381)
		(layer "F.Cu")
		(net "P5V_AUX")
	)
	(segment
		(start 415.929064 -41.68394)
		(end 414.3248 -41.68394)
		(width 0.508)
		(layer "F.Cu")
		(net "P5V_AUX")
	)
	(segment
		(start 420.153338 -157.206442)
		(end 420.153338 -156.596842)
		(width 0.508)
		(layer "F.Cu")
		(net "P5V_AUX")
	)
	(segment
		(start 105.258108 -138.35126)
		(end 105.258108 -142.061438)
		(width 0.381)
		(layer "F.Cu")
		(net "P5V_AUX")
	)
	(segment
		(start 138.016234 -150.974806)
		(end 138.016234 -151.219662)
		(width 0.4572)
		(layer "F.Cu")
		(net "P5V_AUX")
	)
	(segment
		(start 104.449626 -142.86992)
		(end 102.618794 -142.86992)
		(width 0.381)
		(layer "F.Cu")
		(net "P5V_AUX")
	)
	(segment
		(start 8.233918 -354.562664)
		(end 23.111968 -354.562664)
		(width 0.381)
		(layer "F.Cu")
		(net "P5V_AUX")
	)
	(segment
		(start 23.111968 -354.562664)
		(end 24.057102 -353.61753)
		(width 0.381)
		(layer "F.Cu")
		(net "P5V_AUX")
	)
	(segment
		(start 137.686034 -150.644606)
		(end 138.016234 -150.974806)
		(width 0.4572)
		(layer "F.Cu")
		(net "P5V_AUX")
	)
	(segment
		(start 319.428876 -360.47426)
		(end 319.428876 -359.918)
		(width 0.381)
		(layer "F.Cu")
		(net "P5V_AUX")
	)
	(segment
		(start 407.573734 -151.527002)
		(end 407.573734 -142.68831)
		(width 0.254)
		(layer "F.Cu")
		(net "P5V_AUX")
	)
	(segment
		(start 269.85087 -361.125008)
		(end 269.348204 -361.627674)
		(width 0.381)
		(layer "F.Cu")
		(net "P5V_AUX")
	)
	(segment
		(start 320.921888 -22.971506)
		(end 320.921888 -23.587456)
		(width 0.4572)
		(layer "F.Cu")
		(net "P5V_AUX")
	)
	(segment
		(start 439.471308 -406.188672)
		(end 439.471308 -406.931622)
		(width 0.4572)
		(layer "F.Cu")
		(net "P5V_AUX")
	)
	(segment
		(start 141.224762 -49.159414)
		(end 140.608812 -49.159414)
		(width 0.4572)
		(layer "F.Cu")
		(net "P5V_AUX")
	)
	(segment
		(start 407.573734 -142.68831)
		(end 407.204672 -142.319248)
		(width 0.254)
		(layer "F.Cu")
		(net "P5V_AUX")
	)
	(segment
		(start 140.820394 -39.793418)
		(end 142.108936 -39.793418)
		(width 0.381)
		(layer "F.Cu")
		(net "P5V_AUX")
	)
	(segment
		(start 269.85087 -351.940622)
		(end 269.85087 -361.125008)
		(width 0.381)
		(layer "F.Cu")
		(net "P5V_AUX")
	)
	(segment
		(start 269.348204 -361.627674)
		(end 269.348204 -363.607604)
		(width 0.381)
		(layer "F.Cu")
		(net "P5V_AUX")
	)
	(segment
		(start 425.044362 -50.799238)
		(end 415.929064 -41.68394)
		(width 0.508)
		(layer "F.Cu")
		(net "P5V_AUX")
	)
	(segment
		(start 177.223674 -354.358702)
		(end 177.223674 -354.968302)
		(width 0.381)
		(layer "F.Cu")
		(net "P5V_AUX")
	)
	(segment
		(start 320.62674 -362.788962)
		(end 321.816984 -361.598718)
		(width 0.508)
		(layer "F.Cu")
		(net "P5V_AUX")
	)
	(segment
		(start 4.88442 -367.400586)
		(end 4.88442 -357.912162)
		(width 0.381)
		(layer "F.Cu")
		(net "P5V_AUX")
	)
	(segment
		(start 12.08786 -394.62837)
		(end 12.422378 -394.962888)
		(width 0.381)
		(layer "F.Cu")
		(net "P5V_AUX")
	)
	(segment
		(start 104.469946 -48.077374)
		(end 104.74198 -47.80534)
		(width 0.4572)
		(layer "F.Cu")
		(net "P5V_AUX")
	)
	(segment
		(start 408.02052 -151.973788)
		(end 407.573734 -151.527002)
		(width 0.254)
		(layer "F.Cu")
		(net "P5V_AUX")
	)
	(segment
		(start 24.057102 -352.021648)
		(end 24.776684 -352.021648)
		(width 0.381)
		(layer "F.Cu")
		(net "P5V_AUX")
	)
	(segment
		(start 407.204672 -139.374372)
		(end 407.616152 -138.962892)
		(width 0.254)
		(layer "F.Cu")
		(net "P5V_AUX")
	)
	(via
		(at 4.88442 -367.400586)
		(size 0.508)
		(drill 0.254)
		(layers "F.Cu" "B.Cu")
		(net "P5V_AUX")
	)
	(via
		(at 239.012476 -321.471544)
		(size 0.508)
		(drill 0.254)
		(layers "F.Cu" "B.Cu")
		(net "P5V_AUX")
	)
	(via
		(at 104.74198 -47.80534)
		(size 0.508)
		(drill 0.254)
		(layers "F.Cu" "B.Cu")
		(net "P5V_AUX")
	)
	(via
		(at 419.403276 -152.388824)
		(size 0.508)
		(drill 0.254)
		(layers "F.Cu" "B.Cu")
		(net "P5V_AUX")
	)
	(via
		(at 412.753048 -153.16581)
		(size 0.508)
		(drill 0.254)
		(layers "F.Cu" "B.Cu")
		(net "P5V_AUX")
	)
	(via
		(at 344.3605 -16.989044)
		(size 0.508)
		(drill 0.254)
		(layers "F.Cu" "B.Cu")
		(net "P5V_AUX")
	)
	(via
		(at 321.816984 -361.598718)
		(size 0.508)
		(drill 0.254)
		(layers "F.Cu" "B.Cu")
		(net "P5V_AUX")
	)
	(via
		(at 428.696882 -373.905272)
		(size 0.508)
		(drill 0.254)
		(layers "F.Cu" "B.Cu")
		(net "P5V_AUX")
	)
	(via
		(at 418.896038 -354.772722)
		(size 0.508)
		(drill 0.254)
		(layers "F.Cu" "B.Cu")
		(net "P5V_AUX")
	)
	(via
		(at 420.165276 -154.8003)
		(size 0.508)
		(drill 0.254)
		(layers "F.Cu" "B.Cu")
		(net "P5V_AUX")
	)
	(via
		(at 175.863504 -365.334804)
		(size 0.508)
		(drill 0.254)
		(layers "F.Cu" "B.Cu")
		(net "P5V_AUX")
	)
	(via
		(at 320.62674 -362.788962)
		(size 0.508)
		(drill 0.254)
		(layers "F.Cu" "B.Cu")
		(net "P5V_AUX")
	)
	(via
		(at 10.202418 -414.63087)
		(size 0.508)
		(drill 0.254)
		(layers "F.Cu" "B.Cu")
		(net "P5V_AUX")
	)
	(via
		(at 452.723504 -141.814296)
		(size 0.508)
		(drill 0.254)
		(layers "F.Cu" "B.Cu")
		(net "P5V_AUX")
	)
	(via
		(at 319.428876 -359.918)
		(size 0.508)
		(drill 0.254)
		(layers "F.Cu" "B.Cu")
		(net "P5V_AUX")
	)
	(via
		(at 140.608812 -49.159414)
		(size 0.508)
		(drill 0.254)
		(layers "F.Cu" "B.Cu")
		(net "P5V_AUX")
	)
	(via
		(at 425.044362 -50.799238)
		(size 0.508)
		(drill 0.254)
		(layers "F.Cu" "B.Cu")
		(net "P5V_AUX")
	)
	(via
		(at 451.961504 -141.814296)
		(size 0.508)
		(drill 0.254)
		(layers "F.Cu" "B.Cu")
		(net "P5V_AUX")
	)
	(via
		(at 207.082898 -147.421854)
		(size 0.508)
		(drill 0.254)
		(layers "F.Cu" "B.Cu")
		(net "P5V_AUX")
	)
	(via
		(at 268.768322 -364.187486)
		(size 0.508)
		(drill 0.254)
		(layers "F.Cu" "B.Cu")
		(net "P5V_AUX")
	)
	(via
		(at 234.80522 -128.817624)
		(size 0.508)
		(drill 0.254)
		(layers "F.Cu" "B.Cu")
		(net "P5V_AUX")
	)
	(via
		(at 139.840462 -50.235612)
		(size 0.508)
		(drill 0.254)
		(layers "F.Cu" "B.Cu")
		(net "P5V_AUX")
	)
	(via
		(at 347.4593 -16.989044)
		(size 0.508)
		(drill 0.254)
		(layers "F.Cu" "B.Cu")
		(net "P5V_AUX")
	)
	(via
		(at 142.108936 -39.793418)
		(size 0.508)
		(drill 0.254)
		(layers "F.Cu" "B.Cu")
		(net "P5V_AUX")
	)
	(via
		(at 421.689276 -154.8003)
		(size 0.508)
		(drill 0.254)
		(layers "F.Cu" "B.Cu")
		(net "P5V_AUX")
	)
	(via
		(at 451.023228 -372.508272)
		(size 0.508)
		(drill 0.254)
		(layers "F.Cu" "B.Cu")
		(net "P5V_AUX")
	)
	(via
		(at 421.689276 -152.388824)
		(size 0.508)
		(drill 0.254)
		(layers "F.Cu" "B.Cu")
		(net "P5V_AUX")
	)
	(via
		(at 247.3071 -363.581696)
		(size 0.508)
		(drill 0.254)
		(layers "F.Cu" "B.Cu")
		(net "P5V_AUX")
	)
	(via
		(at 411.082236 -153.861262)
		(size 0.508)
		(drill 0.254)
		(layers "F.Cu" "B.Cu")
		(net "P5V_AUX")
	)
	(via
		(at 410.150818 -366.652048)
		(size 0.508)
		(drill 0.254)
		(layers "F.Cu" "B.Cu")
		(net "P5V_AUX")
	)
	(via
		(at 137.686034 -150.644606)
		(size 0.508)
		(drill 0.254)
		(layers "F.Cu" "B.Cu")
		(net "P5V_AUX")
	)
	(via
		(at 439.471308 -406.931622)
		(size 0.508)
		(drill 0.254)
		(layers "F.Cu" "B.Cu")
		(net "P5V_AUX")
	)
	(via
		(at 408.697176 -152.650444)
		(size 0.508)
		(drill 0.254)
		(layers "F.Cu" "B.Cu")
		(net "P5V_AUX")
	)
	(via
		(at 12.422378 -394.962888)
		(size 0.508)
		(drill 0.254)
		(layers "F.Cu" "B.Cu")
		(net "P5V_AUX")
	)
	(via
		(at 425.612814 -363.954314)
		(size 0.508)
		(drill 0.254)
		(layers "F.Cu" "B.Cu")
		(net "P5V_AUX")
	)
	(via
		(at 454.247504 -141.814296)
		(size 0.508)
		(drill 0.254)
		(layers "F.Cu" "B.Cu")
		(net "P5V_AUX")
	)
	(via
		(at 234.04322 -128.817624)
		(size 0.508)
		(drill 0.254)
		(layers "F.Cu" "B.Cu")
		(net "P5V_AUX")
	)
	(via
		(at 105.258108 -138.35126)
		(size 0.508)
		(drill 0.254)
		(layers "F.Cu" "B.Cu")
		(net "P5V_AUX")
	)
	(via
		(at 411.062424 -154.720798)
		(size 0.508)
		(drill 0.254)
		(layers "F.Cu" "B.Cu")
		(net "P5V_AUX")
	)
	(via
		(at 275.701252 -133.104382)
		(size 0.508)
		(drill 0.254)
		(layers "F.Cu" "B.Cu")
		(net "P5V_AUX")
	)
	(via
		(at 24.776684 -352.021648)
		(size 0.508)
		(drill 0.254)
		(layers "F.Cu" "B.Cu")
		(net "P5V_AUX")
	)
	(via
		(at 453.485504 -141.814296)
		(size 0.508)
		(drill 0.254)
		(layers "F.Cu" "B.Cu")
		(net "P5V_AUX")
	)
	(via
		(at 234.789218 -127.865378)
		(size 0.508)
		(drill 0.254)
		(layers "F.Cu" "B.Cu")
		(net "P5V_AUX")
	)
	(via
		(at 168.952418 -349.716344)
		(size 0.508)
		(drill 0.254)
		(layers "F.Cu" "B.Cu")
		(net "P5V_AUX")
	)
	(via
		(at 420.153338 -156.596842)
		(size 0.508)
		(drill 0.254)
		(layers "F.Cu" "B.Cu")
		(net "P5V_AUX")
	)
	(via
		(at 415.549588 -153.956004)
		(size 0.508)
		(drill 0.254)
		(layers "F.Cu" "B.Cu")
		(net "P5V_AUX")
	)
	(via
		(at 411.062424 -155.482798)
		(size 0.508)
		(drill 0.254)
		(layers "F.Cu" "B.Cu")
		(net "P5V_AUX")
	)
	(via
		(at 419.403276 -154.8003)
		(size 0.508)
		(drill 0.254)
		(layers "F.Cu" "B.Cu")
		(net "P5V_AUX")
	)
	(via
		(at 140.765784 -48.325024)
		(size 0.508)
		(drill 0.254)
		(layers "F.Cu" "B.Cu")
		(net "P5V_AUX")
	)
	(via
		(at 274.939252 -133.104382)
		(size 0.508)
		(drill 0.254)
		(layers "F.Cu" "B.Cu")
		(net "P5V_AUX")
	)
	(via
		(at 414.531048 -153.16581)
		(size 0.508)
		(drill 0.254)
		(layers "F.Cu" "B.Cu")
		(net "P5V_AUX")
	)
	(via
		(at 274.985988 -132.245608)
		(size 0.508)
		(drill 0.254)
		(layers "F.Cu" "B.Cu")
		(net "P5V_AUX")
	)
	(via
		(at 449.307966 -419.596824)
		(size 0.508)
		(drill 0.254)
		(layers "F.Cu" "B.Cu")
		(net "P5V_AUX")
	)
	(via
		(at 414.3248 -41.68394)
		(size 0.508)
		(drill 0.254)
		(layers "F.Cu" "B.Cu")
		(net "P5V_AUX")
	)
	(via
		(at 365.318548 -13.434568)
		(size 0.508)
		(drill 0.254)
		(layers "F.Cu" "B.Cu")
		(net "P5V_AUX")
	)
	(via
		(at 165.955472 -147.692872)
		(size 0.508)
		(drill 0.254)
		(layers "F.Cu" "B.Cu")
		(net "P5V_AUX")
	)
	(via
		(at 420.927276 -154.8003)
		(size 0.508)
		(drill 0.254)
		(layers "F.Cu" "B.Cu")
		(net "P5V_AUX")
	)
	(via
		(at 139.840462 -50.877216)
		(size 0.508)
		(drill 0.254)
		(layers "F.Cu" "B.Cu")
		(net "P5V_AUX")
	)
	(via
		(at 320.921888 -23.587456)
		(size 0.508)
		(drill 0.254)
		(layers "F.Cu" "B.Cu")
		(net "P5V_AUX")
	)
	(via
		(at 413.642048 -153.16581)
		(size 0.508)
		(drill 0.254)
		(layers "F.Cu" "B.Cu")
		(net "P5V_AUX")
	)
	(via
		(at 385.149344 -140.202158)
		(size 0.508)
		(drill 0.254)
		(layers "F.Cu" "B.Cu")
		(net "P5V_AUX")
	)
	(via
		(at 420.165276 -152.388824)
		(size 0.508)
		(drill 0.254)
		(layers "F.Cu" "B.Cu")
		(net "P5V_AUX")
	)
	(via
		(at 415.529776 -155.57754)
		(size 0.508)
		(drill 0.254)
		(layers "F.Cu" "B.Cu")
		(net "P5V_AUX")
	)
	(via
		(at 177.223674 -354.968302)
		(size 0.508)
		(drill 0.254)
		(layers "F.Cu" "B.Cu")
		(net "P5V_AUX")
	)
	(via
		(at 415.529776 -154.81554)
		(size 0.508)
		(drill 0.254)
		(layers "F.Cu" "B.Cu")
		(net "P5V_AUX")
	)
	(via
		(at 234.027218 -127.865378)
		(size 0.508)
		(drill 0.254)
		(layers "F.Cu" "B.Cu")
		(net "P5V_AUX")
	)
	(via
		(at 275.747988 -132.245608)
		(size 0.508)
		(drill 0.254)
		(layers "F.Cu" "B.Cu")
		(net "P5V_AUX")
	)
	(via
		(at 420.927276 -152.388824)
		(size 0.508)
		(drill 0.254)
		(layers "F.Cu" "B.Cu")
		(net "P5V_AUX")
	)
	(via
		(at 411.864048 -153.16581)
		(size 0.508)
		(drill 0.254)
		(layers "F.Cu" "B.Cu")
		(net "P5V_AUX")
	)
	(segment
		(start 181.01056 -369.253516)
		(end 177.091848 -365.334804)
		(width 0.4572)
		(layer "B.Cu")
		(net "P5V_AUX")
	)
	(segment
		(start 38.644576 -361.256072)
		(end 37.786818 -361.256072)
		(width 0.4572)
		(layer "B.Cu")
		(net "P5V_AUX")
	)
	(segment
		(start 406.841198 -361.631738)
		(end 404.190454 -361.631738)
		(width 0.4572)
		(layer "B.Cu")
		(net "P5V_AUX")
	)
	(segment
		(start 10.202418 -414.10382)
		(end 10.202418 -414.63087)
		(width 0.4572)
		(layer "B.Cu")
		(net "P5V_AUX")
	)
	(segment
		(start 37.786818 -361.256072)
		(end 37.09289 -361.95)
		(width 0.4572)
		(layer "B.Cu")
		(net "P5V_AUX")
	)
	(segment
		(start 31.712408 -358.147366)
		(end 30.897576 -358.962198)
		(width 0.4572)
		(layer "B.Cu")
		(net "P5V_AUX")
	)
	(segment
		(start 373.949976 -39.622222)
		(end 368.407188 -34.079434)
		(width 0.508)
		(layer "B.Cu")
		(net "P5V_AUX")
	)
	(segment
		(start 320.62674 -366.295432)
		(end 320.62674 -362.788962)
		(width 0.4572)
		(layer "B.Cu")
		(net "P5V_AUX")
	)
	(segment
		(start 313.311032 -367.015776)
		(end 313.82208 -367.526824)
		(width 0.4572)
		(layer "B.Cu")
		(net "P5V_AUX")
	)
	(segment
		(start 296.831004 -366.967262)
		(end 301.363888 -366.967262)
		(width 0.4572)
		(layer "B.Cu")
		(net "P5V_AUX")
	)
	(segment
		(start 41.693084 -365.334804)
		(end 39.589456 -363.231176)
		(width 0.4572)
		(layer "B.Cu")
		(net "P5V_AUX")
	)
	(segment
		(start 319.428876 -359.918)
		(end 320.136266 -359.918)
		(width 0.4572)
		(layer "B.Cu")
		(net "P5V_AUX")
	)
	(segment
		(start 320.136266 -359.918)
		(end 321.816984 -361.598718)
		(width 0.4572)
		(layer "B.Cu")
		(net "P5V_AUX")
	)
	(segment
		(start 265.632438 -365.668814)
		(end 255.133856 -365.668814)
		(width 0.4572)
		(layer "B.Cu")
		(net "P5V_AUX")
	)
	(segment
		(start 11.453368 -412.85287)
		(end 10.202418 -414.10382)
		(width 0.4572)
		(layer "B.Cu")
		(net "P5V_AUX")
	)
	(segment
		(start 247.3071 -363.581696)
		(end 246.785892 -363.581696)
		(width 0.4572)
		(layer "B.Cu")
		(net "P5V_AUX")
	)
	(segment
		(start 235.300266 -364.832646)
		(end 230.94061 -369.192302)
		(width 0.4572)
		(layer "B.Cu")
		(net "P5V_AUX")
	)
	(segment
		(start 32.876236 -358.147366)
		(end 31.712408 -358.147366)
		(width 0.4572)
		(layer "B.Cu")
		(net "P5V_AUX")
	)
	(segment
		(start 313.311032 -366.079532)
		(end 313.311032 -367.015776)
		(width 0.4572)
		(layer "B.Cu")
		(net "P5V_AUX")
	)
	(segment
		(start 292.160198 -367.928144)
		(end 295.870122 -367.928144)
		(width 0.4572)
		(layer "B.Cu")
		(net "P5V_AUX")
	)
	(segment
		(start 313.82208 -367.526824)
		(end 319.395348 -367.526824)
		(width 0.4572)
		(layer "B.Cu")
		(net "P5V_AUX")
	)
	(segment
		(start 310.413908 -366.336326)
		(end 310.731916 -366.336326)
		(width 0.4572)
		(layer "B.Cu")
		(net "P5V_AUX")
	)
	(segment
		(start 449.307966 -420.123874)
		(end 449.307966 -419.596824)
		(width 0.4572)
		(layer "B.Cu")
		(net "P5V_AUX")
	)
	(segment
		(start 412.263082 -39.622222)
		(end 373.949976 -39.622222)
		(width 0.508)
		(layer "B.Cu")
		(net "P5V_AUX")
	)
	(segment
		(start 409.262834 -364.053374)
		(end 406.841198 -361.631738)
		(width 0.4572)
		(layer "B.Cu")
		(net "P5V_AUX")
	)
	(segment
		(start 230.94061 -369.192302)
		(end 223.858328 -369.192302)
		(width 0.4572)
		(layer "B.Cu")
		(net "P5V_AUX")
	)
	(segment
		(start 404.190454 -361.631738)
		(end 399.632678 -366.189514)
		(width 0.4572)
		(layer "B.Cu")
		(net "P5V_AUX")
	)
	(segment
		(start 29.058616 -360.778044)
		(end 27.097482 -358.81691)
		(width 0.4572)
		(layer "B.Cu")
		(net "P5V_AUX")
	)
	(segment
		(start 364.425738 -34.079434)
		(end 362.146342 -31.800038)
		(width 0.508)
		(layer "B.Cu")
		(net "P5V_AUX")
	)
	(segment
		(start 216.50325 -369.501928)
		(end 190.01359 -369.501928)
		(width 0.4572)
		(layer "B.Cu")
		(net "P5V_AUX")
	)
	(segment
		(start 363.51845 -17.593818)
		(end 363.51845 -17.17294)
		(width 0.508)
		(layer "B.Cu")
		(net "P5V_AUX")
	)
	(segment
		(start 274.619212 -366.806988)
		(end 291.039042 -366.806988)
		(width 0.4572)
		(layer "B.Cu")
		(net "P5V_AUX")
	)
	(segment
		(start 247.80748 -363.581696)
		(end 247.3071 -363.581696)
		(width 0.4572)
		(layer "B.Cu")
		(net "P5V_AUX")
	)
	(segment
		(start 399.632678 -366.189514)
		(end 325.59498 -366.189514)
		(width 0.4572)
		(layer "B.Cu")
		(net "P5V_AUX")
	)
	(segment
		(start 255.133856 -365.668814)
		(end 254.297688 -364.832646)
		(width 0.4572)
		(layer "B.Cu")
		(net "P5V_AUX")
	)
	(segment
		(start 223.54921 -368.883184)
		(end 217.121994 -368.883184)
		(width 0.4572)
		(layer "B.Cu")
		(net "P5V_AUX")
	)
	(segment
		(start 254.297688 -364.832646)
		(end 249.05843 -364.832646)
		(width 0.4572)
		(layer "B.Cu")
		(net "P5V_AUX")
	)
	(segment
		(start 363.51845 -17.17294)
		(end 363.693456 -16.997934)
		(width 0.508)
		(layer "B.Cu")
		(net "P5V_AUX")
	)
	(segment
		(start 245.534942 -364.832646)
		(end 235.300266 -364.832646)
		(width 0.4572)
		(layer "B.Cu")
		(net "P5V_AUX")
	)
	(segment
		(start 368.407188 -34.079434)
		(end 364.425738 -34.079434)
		(width 0.508)
		(layer "B.Cu")
		(net "P5V_AUX")
	)
	(segment
		(start 409.262834 -365.764064)
		(end 409.262834 -364.053374)
		(width 0.4572)
		(layer "B.Cu")
		(net "P5V_AUX")
	)
	(segment
		(start 295.870122 -367.928144)
		(end 296.831004 -366.967262)
		(width 0.4572)
		(layer "B.Cu")
		(net "P5V_AUX")
	)
	(segment
		(start 268.768322 -364.187486)
		(end 268.648688 -364.30712)
		(width 0.4572)
		(layer "B.Cu")
		(net "P5V_AUX")
	)
	(segment
		(start 190.01359 -369.501928)
		(end 189.037214 -368.525552)
		(width 0.4572)
		(layer "B.Cu")
		(net "P5V_AUX")
	)
	(segment
		(start 35.70605 -361.95)
		(end 35.70605 -360.97718)
		(width 0.4572)
		(layer "B.Cu")
		(net "P5V_AUX")
	)
	(segment
		(start 35.70605 -360.97718)
		(end 32.876236 -358.147366)
		(width 0.4572)
		(layer "B.Cu")
		(net "P5V_AUX")
	)
	(segment
		(start 425.612814 -362.851446)
		(end 425.612814 -363.954314)
		(width 0.4572)
		(layer "B.Cu")
		(net "P5V_AUX")
	)
	(segment
		(start 291.039042 -366.806988)
		(end 292.160198 -367.928144)
		(width 0.4572)
		(layer "B.Cu")
		(net "P5V_AUX")
	)
	(segment
		(start 246.785892 -363.581696)
		(end 245.534942 -364.832646)
		(width 0.4572)
		(layer "B.Cu")
		(net "P5V_AUX")
	)
	(segment
		(start 24.776684 -355.006148)
		(end 24.776684 -352.021648)
		(width 0.4572)
		(layer "B.Cu")
		(net "P5V_AUX")
	)
	(segment
		(start 325.59498 -366.189514)
		(end 322.937632 -363.532166)
		(width 0.4572)
		(layer "B.Cu")
		(net "P5V_AUX")
	)
	(segment
		(start 308.313074 -368.43716)
		(end 310.413908 -366.336326)
		(width 0.4572)
		(layer "B.Cu")
		(net "P5V_AUX")
	)
	(segment
		(start 448.057016 -421.374824)
		(end 449.307966 -420.123874)
		(width 0.4572)
		(layer "B.Cu")
		(net "P5V_AUX")
	)
	(segment
		(start 37.09289 -361.95)
		(end 35.70605 -361.95)
		(width 0.4572)
		(layer "B.Cu")
		(net "P5V_AUX")
	)
	(segment
		(start 414.3248 -41.68394)
		(end 412.263082 -39.622222)
		(width 0.508)
		(layer "B.Cu")
		(net "P5V_AUX")
	)
	(segment
		(start 30.897576 -360.009694)
		(end 30.129226 -360.778044)
		(width 0.4572)
		(layer "B.Cu")
		(net "P5V_AUX")
	)
	(segment
		(start 362.146342 -18.965926)
		(end 363.51845 -17.593818)
		(width 0.508)
		(layer "B.Cu")
		(net "P5V_AUX")
	)
	(segment
		(start 310.731916 -366.336326)
		(end 311.6199 -365.448342)
		(width 0.4572)
		(layer "B.Cu")
		(net "P5V_AUX")
	)
	(segment
		(start 302.833786 -368.43716)
		(end 308.313074 -368.43716)
		(width 0.4572)
		(layer "B.Cu")
		(net "P5V_AUX")
	)
	(segment
		(start 266.994132 -364.30712)
		(end 265.632438 -365.668814)
		(width 0.4572)
		(layer "B.Cu")
		(net "P5V_AUX")
	)
	(segment
		(start 322.937632 -363.532166)
		(end 322.937632 -362.719366)
		(width 0.4572)
		(layer "B.Cu")
		(net "P5V_AUX")
	)
	(segment
		(start 30.129226 -360.778044)
		(end 29.058616 -360.778044)
		(width 0.4572)
		(layer "B.Cu")
		(net "P5V_AUX")
	)
	(segment
		(start 238.305594 -321.471544)
		(end 239.012476 -321.471544)
		(width 0.381)
		(layer "B.Cu")
		(net "P5V_AUX")
	)
	(segment
		(start 27.097482 -358.81691)
		(end 26.04389 -356.273354)
		(width 0.4572)
		(layer "B.Cu")
		(net "P5V_AUX")
	)
	(segment
		(start 186.018932 -368.525552)
		(end 185.290968 -369.253516)
		(width 0.4572)
		(layer "B.Cu")
		(net "P5V_AUX")
	)
	(segment
		(start 273.759676 -365.947452)
		(end 274.619212 -366.806988)
		(width 0.4572)
		(layer "B.Cu")
		(net "P5V_AUX")
	)
	(segment
		(start 185.290968 -369.253516)
		(end 181.01056 -369.253516)
		(width 0.4572)
		(layer "B.Cu")
		(net "P5V_AUX")
	)
	(segment
		(start 30.897576 -358.962198)
		(end 30.897576 -360.009694)
		(width 0.4572)
		(layer "B.Cu")
		(net "P5V_AUX")
	)
	(segment
		(start 39.589456 -363.231176)
		(end 39.589456 -362.200952)
		(width 0.4572)
		(layer "B.Cu")
		(net "P5V_AUX")
	)
	(segment
		(start 175.863504 -365.334804)
		(end 41.693084 -365.334804)
		(width 0.4572)
		(layer "B.Cu")
		(net "P5V_AUX")
	)
	(segment
		(start 217.121994 -368.883184)
		(end 216.50325 -369.501928)
		(width 0.4572)
		(layer "B.Cu")
		(net "P5V_AUX")
	)
	(segment
		(start 312.679842 -365.448342)
		(end 313.311032 -366.079532)
		(width 0.4572)
		(layer "B.Cu")
		(net "P5V_AUX")
	)
	(segment
		(start 39.589456 -362.200952)
		(end 38.644576 -361.256072)
		(width 0.4572)
		(layer "B.Cu")
		(net "P5V_AUX")
	)
	(segment
		(start 425.046648 -362.378244)
		(end 425.139612 -362.378244)
		(width 0.4572)
		(layer "B.Cu")
		(net "P5V_AUX")
	)
	(segment
		(start 249.05843 -364.832646)
		(end 247.80748 -363.581696)
		(width 0.4572)
		(layer "B.Cu")
		(net "P5V_AUX")
	)
	(segment
		(start 410.150818 -366.652048)
		(end 409.262834 -365.764064)
		(width 0.4572)
		(layer "B.Cu")
		(net "P5V_AUX")
	)
	(segment
		(start 319.395348 -367.526824)
		(end 320.62674 -366.295432)
		(width 0.4572)
		(layer "B.Cu")
		(net "P5V_AUX")
	)
	(segment
		(start 189.037214 -368.525552)
		(end 186.018932 -368.525552)
		(width 0.4572)
		(layer "B.Cu")
		(net "P5V_AUX")
	)
	(segment
		(start 362.146342 -31.800038)
		(end 362.146342 -18.965926)
		(width 0.508)
		(layer "B.Cu")
		(net "P5V_AUX")
	)
	(segment
		(start 363.693456 -16.997934)
		(end 365.318548 -15.372842)
		(width 0.4572)
		(layer "B.Cu")
		(net "P5V_AUX")
	)
	(segment
		(start 311.6199 -365.448342)
		(end 312.679842 -365.448342)
		(width 0.4572)
		(layer "B.Cu")
		(net "P5V_AUX")
	)
	(segment
		(start 425.139612 -362.378244)
		(end 425.612814 -362.851446)
		(width 0.4572)
		(layer "B.Cu")
		(net "P5V_AUX")
	)
	(segment
		(start 365.318548 -15.372842)
		(end 365.318548 -13.434568)
		(width 0.4572)
		(layer "B.Cu")
		(net "P5V_AUX")
	)
	(segment
		(start 322.937632 -362.719366)
		(end 321.816984 -361.598718)
		(width 0.4572)
		(layer "B.Cu")
		(net "P5V_AUX")
	)
	(segment
		(start 301.363888 -366.967262)
		(end 302.833786 -368.43716)
		(width 0.4572)
		(layer "B.Cu")
		(net "P5V_AUX")
	)
	(segment
		(start 268.768322 -364.187486)
		(end 270.528288 -365.947452)
		(width 0.4572)
		(layer "B.Cu")
		(net "P5V_AUX")
	)
	(segment
		(start 177.091848 -365.334804)
		(end 175.863504 -365.334804)
		(width 0.4572)
		(layer "B.Cu")
		(net "P5V_AUX")
	)
	(segment
		(start 268.648688 -364.30712)
		(end 266.994132 -364.30712)
		(width 0.4572)
		(layer "B.Cu")
		(net "P5V_AUX")
	)
	(segment
		(start 270.528288 -365.947452)
		(end 273.759676 -365.947452)
		(width 0.4572)
		(layer "B.Cu")
		(net "P5V_AUX")
	)
	(segment
		(start 168.336468 -349.716344)
		(end 168.952418 -349.716344)
		(width 0.4572)
		(layer "B.Cu")
		(net "P5V_AUX")
	)
	(segment
		(start 26.04389 -356.273354)
		(end 24.776684 -355.006148)
		(width 0.4572)
		(layer "B.Cu")
		(net "P5V_AUX")
	)
	(segment
		(start 223.858328 -369.192302)
		(end 223.54921 -368.883184)
		(width 0.4572)
		(layer "B.Cu")
		(net "P5V_AUX")
	)
	(segment
		(start 365.318548 -13.434568)
		(end 365.318548 -15.145258)
		(width 0.508)
		(layer "In2.Cu")
		(net "P5V_AUX")
	)
	(segment
		(start 174.061628 -148.660866)
		(end 166.878508 -148.660866)
		(width 1.016)
		(layer "In2.Cu")
		(net "P5V_AUX")
	)
	(segment
		(start 365.318548 -15.145258)
		(end 361.873292 -18.590514)
		(width 0.508)
		(layer "In2.Cu")
		(net "P5V_AUX")
	)
	(segment
		(start 183.290972 -151.470614)
		(end 176.871376 -151.470614)
		(width 1.016)
		(layer "In2.Cu")
		(net "P5V_AUX")
	)
	(segment
		(start 184.860946 -149.90064)
		(end 183.290972 -151.470614)
		(width 1.016)
		(layer "In2.Cu")
		(net "P5V_AUX")
	)
	(segment
		(start 190.0936 -147.854924)
		(end 188.047884 -149.90064)
		(width 1.016)
		(layer "In2.Cu")
		(net "P5V_AUX")
	)
	(segment
		(start 417.713922 -355.416104)
		(end 415.475928 -355.416104)
		(width 0.508)
		(layer "In2.Cu")
		(net "P5V_AUX")
	)
	(segment
		(start 166.117016 -147.854416)
		(end 165.955472 -147.692872)
		(width 1.016)
		(layer "In2.Cu")
		(net "P5V_AUX")
	)
	(segment
		(start 361.873292 -18.590514)
		(end 349.06077 -18.590514)
		(width 0.508)
		(layer "In2.Cu")
		(net "P5V_AUX")
	)
	(segment
		(start 192.91808 -146.685)
		(end 190.0936 -147.854924)
		(width 1.016)
		(layer "In2.Cu")
		(net "P5V_AUX")
	)
	(segment
		(start 415.475928 -355.416104)
		(end 411.704028 -359.188004)
		(width 0.762)
		(layer "In2.Cu")
		(net "P5V_AUX")
	)
	(segment
		(start 411.704028 -365.098838)
		(end 410.150818 -366.652048)
		(width 0.762)
		(layer "In2.Cu")
		(net "P5V_AUX")
	)
	(segment
		(start 418.357304 -354.772722)
		(end 417.713922 -355.416104)
		(width 0.508)
		(layer "In2.Cu")
		(net "P5V_AUX")
	)
	(segment
		(start 411.704028 -359.188004)
		(end 411.704028 -365.098838)
		(width 0.762)
		(layer "In2.Cu")
		(net "P5V_AUX")
	)
	(segment
		(start 188.047884 -149.90064)
		(end 184.860946 -149.90064)
		(width 1.016)
		(layer "In2.Cu")
		(net "P5V_AUX")
	)
	(segment
		(start 166.117016 -147.899374)
		(end 166.117016 -147.854416)
		(width 1.016)
		(layer "In2.Cu")
		(net "P5V_AUX")
	)
	(segment
		(start 199.221344 -146.685)
		(end 192.91808 -146.685)
		(width 1.016)
		(layer "In2.Cu")
		(net "P5V_AUX")
	)
	(segment
		(start 201.476864 -148.94052)
		(end 199.221344 -146.685)
		(width 1.016)
		(layer "In2.Cu")
		(net "P5V_AUX")
	)
	(segment
		(start 418.896038 -354.772722)
		(end 418.357304 -354.772722)
		(width 0.508)
		(layer "In2.Cu")
		(net "P5V_AUX")
	)
	(segment
		(start 207.082898 -147.421854)
		(end 205.564232 -148.94052)
		(width 1.016)
		(layer "In2.Cu")
		(net "P5V_AUX")
	)
	(segment
		(start 349.06077 -18.590514)
		(end 347.4593 -16.989044)
		(width 0.508)
		(layer "In2.Cu")
		(net "P5V_AUX")
	)
	(segment
		(start 166.878508 -148.660866)
		(end 166.117016 -147.899374)
		(width 1.016)
		(layer "In2.Cu")
		(net "P5V_AUX")
	)
	(segment
		(start 176.871376 -151.470614)
		(end 174.061628 -148.660866)
		(width 1.016)
		(layer "In2.Cu")
		(net "P5V_AUX")
	)
	(segment
		(start 205.564232 -148.94052)
		(end 201.476864 -148.94052)
		(width 1.016)
		(layer "In2.Cu")
		(net "P5V_AUX")
	)
	(segment
		(start 428.696882 -373.905272)
		(end 433.239672 -373.905272)
		(width 1.016)
		(layer "In4.Cu")
		(net "P5V_AUX")
	)
	(segment
		(start 423.78376 -372.94058)
		(end 416.43935 -372.94058)
		(width 1.016)
		(layer "In4.Cu")
		(net "P5V_AUX")
	)
	(segment
		(start 169.7863 -350.004634)
		(end 169.49801 -349.716344)
		(width 0.762)
		(layer "In4.Cu")
		(net "P5V_AUX")
	)
	(segment
		(start 433.239672 -373.905272)
		(end 435.23789 -371.907054)
		(width 1.016)
		(layer "In4.Cu")
		(net "P5V_AUX")
	)
	(segment
		(start 243.707666 -321.496436)
		(end 243.707666 -335.19872)
		(width 0.4572)
		(layer "In4.Cu")
		(net "P5V_AUX")
	)
	(segment
		(start 177.223674 -354.968302)
		(end 177.059336 -355.13264)
		(width 0.762)
		(layer "In4.Cu")
		(net "P5V_AUX")
	)
	(segment
		(start 428.696882 -373.905272)
		(end 424.748452 -373.905272)
		(width 1.016)
		(layer "In4.Cu")
		(net "P5V_AUX")
	)
	(segment
		(start 169.625264 -351.48012)
		(end 169.7863 -351.319084)
		(width 0.762)
		(layer "In4.Cu")
		(net "P5V_AUX")
	)
	(segment
		(start 416.43935 -372.94058)
		(end 410.150818 -366.652048)
		(width 1.016)
		(layer "In4.Cu")
		(net "P5V_AUX")
	)
	(segment
		(start 424.748452 -373.905272)
		(end 423.78376 -372.94058)
		(width 1.016)
		(layer "In4.Cu")
		(net "P5V_AUX")
	)
	(segment
		(start 169.49801 -349.716344)
		(end 168.952418 -349.716344)
		(width 0.762)
		(layer "In4.Cu")
		(net "P5V_AUX")
	)
	(segment
		(start 170.50893 -355.13264)
		(end 169.625264 -354.248974)
		(width 0.762)
		(layer "In4.Cu")
		(net "P5V_AUX")
	)
	(segment
		(start 239.012476 -321.471544)
		(end 240.318544 -321.471544)
		(width 0.4572)
		(layer "In4.Cu")
		(net "P5V_AUX")
	)
	(segment
		(start 177.059336 -355.13264)
		(end 170.50893 -355.13264)
		(width 0.762)
		(layer "In4.Cu")
		(net "P5V_AUX")
	)
	(segment
		(start 169.7863 -351.319084)
		(end 169.7863 -350.004634)
		(width 0.762)
		(layer "In4.Cu")
		(net "P5V_AUX")
	)
	(segment
		(start 240.318544 -321.471544)
		(end 240.89741 -320.892678)
		(width 0.4572)
		(layer "In4.Cu")
		(net "P5V_AUX")
	)
	(segment
		(start 247.3071 -338.798154)
		(end 247.3071 -363.581696)
		(width 0.4572)
		(layer "In4.Cu")
		(net "P5V_AUX")
	)
	(segment
		(start 243.707666 -335.19872)
		(end 247.3071 -338.798154)
		(width 0.4572)
		(layer "In4.Cu")
		(net "P5V_AUX")
	)
	(segment
		(start 435.23789 -371.907054)
		(end 449.680838 -371.907054)
		(width 1.016)
		(layer "In4.Cu")
		(net "P5V_AUX")
	)
	(segment
		(start 169.625264 -354.248974)
		(end 169.625264 -351.48012)
		(width 0.762)
		(layer "In4.Cu")
		(net "P5V_AUX")
	)
	(segment
		(start 240.89741 -320.892678)
		(end 243.103908 -320.892678)
		(width 0.4572)
		(layer "In4.Cu")
		(net "P5V_AUX")
	)
	(segment
		(start 243.103908 -320.892678)
		(end 243.707666 -321.496436)
		(width 0.4572)
		(layer "In4.Cu")
		(net "P5V_AUX")
	)
	(segment
		(start 428.696882 -371.813328)
		(end 425.612814 -368.72926)
		(width 0.762)
		(layer "In6.Cu")
		(net "P5V_AUX")
	)
	(segment
		(start 3.946144 -368.338862)
		(end 4.88442 -367.400586)
		(width 0.762)
		(layer "In6.Cu")
		(net "P5V_AUX")
	)
	(segment
		(start 425.612814 -368.72926)
		(end 425.612814 -363.954314)
		(width 0.762)
		(layer "In6.Cu")
		(net "P5V_AUX")
	)
	(segment
		(start 6.757924 -406.030938)
		(end 6.757924 -399.824702)
		(width 0.762)
		(layer "In6.Cu")
		(net "P5V_AUX")
	)
	(segment
		(start 11.619738 -394.962888)
		(end 12.083288 -394.962888)
		(width 0.762)
		(layer "In6.Cu")
		(net "P5V_AUX")
	)
	(segment
		(start 12.083288 -394.962888)
		(end 10.994644 -393.874244)
		(width 0.762)
		(layer "In6.Cu")
		(net "P5V_AUX")
	)
	(segment
		(start 428.696882 -373.905272)
		(end 428.696882 -371.813328)
		(width 0.762)
		(layer "In6.Cu")
		(net "P5V_AUX")
	)
	(segment
		(start 3.946144 -381.839724)
		(end 3.946144 -368.338862)
		(width 0.762)
		(layer "In6.Cu")
		(net "P5V_AUX")
	)
	(segment
		(start 320.921888 -21.581872)
		(end 326.775826 -15.727934)
		(width 0.508)
		(layer "In6.Cu")
		(net "P5V_AUX")
	)
	(segment
		(start 12.422378 -394.962888)
		(end 12.083288 -394.962888)
		(width 0.762)
		(layer "In6.Cu")
		(net "P5V_AUX")
	)
	(segment
		(start 320.921888 -23.587456)
		(end 320.921888 -21.581872)
		(width 0.508)
		(layer "In6.Cu")
		(net "P5V_AUX")
	)
	(segment
		(start 326.775826 -15.727934)
		(end 343.09939 -15.727934)
		(width 0.508)
		(layer "In6.Cu")
		(net "P5V_AUX")
	)
	(segment
		(start 10.994644 -388.888224)
		(end 3.946144 -381.839724)
		(width 0.762)
		(layer "In6.Cu")
		(net "P5V_AUX")
	)
	(segment
		(start 10.994644 -393.874244)
		(end 10.994644 -388.888224)
		(width 0.762)
		(layer "In6.Cu")
		(net "P5V_AUX")
	)
	(segment
		(start 9.947148 -414.88614)
		(end 8.559546 -414.88614)
		(width 0.762)
		(layer "In6.Cu")
		(net "P5V_AUX")
	)
	(segment
		(start 343.09939 -15.727934)
		(end 344.3605 -16.989044)
		(width 0.508)
		(layer "In6.Cu")
		(net "P5V_AUX")
	)
	(segment
		(start 8.08482 -414.411414)
		(end 8.08482 -407.357834)
		(width 0.762)
		(layer "In6.Cu")
		(net "P5V_AUX")
	)
	(segment
		(start 6.757924 -399.824702)
		(end 11.619738 -394.962888)
		(width 0.762)
		(layer "In6.Cu")
		(net "P5V_AUX")
	)
	(segment
		(start 10.202418 -414.63087)
		(end 9.947148 -414.88614)
		(width 0.762)
		(layer "In6.Cu")
		(net "P5V_AUX")
	)
	(segment
		(start 8.08482 -407.357834)
		(end 6.757924 -406.030938)
		(width 0.762)
		(layer "In6.Cu")
		(net "P5V_AUX")
	)
	(segment
		(start 346.650564 -17.79778)
		(end 347.4593 -16.989044)
		(width 0.4572)
		(layer "In6.Cu")
		(net "P5V_AUX")
	)
	(segment
		(start 345.169236 -17.79778)
		(end 346.650564 -17.79778)
		(width 0.4572)
		(layer "In6.Cu")
		(net "P5V_AUX")
	)
	(segment
		(start 8.559546 -414.88614)
		(end 8.08482 -414.411414)
		(width 0.762)
		(layer "In6.Cu")
		(net "P5V_AUX")
	)
	(segment
		(start 344.3605 -16.989044)
		(end 345.169236 -17.79778)
		(width 0.4572)
		(layer "In6.Cu")
		(net "P5V_AUX")
	)
	(segment
		(start 438.472072 -376.534172)
		(end 442.497972 -372.508272)
		(width 0.762)
		(layer "In11.Cu")
		(net "P5V_AUX")
	)
	(segment
		(start 445.982852 -418.257482)
		(end 447.322194 -419.596824)
		(width 0.762)
		(layer "In11.Cu")
		(net "P5V_AUX")
	)
	(segment
		(start 441.907676 -418.257482)
		(end 445.982852 -418.257482)
		(width 0.762)
		(layer "In11.Cu")
		(net "P5V_AUX")
	)
	(segment
		(start 439.471308 -415.821114)
		(end 441.907676 -418.257482)
		(width 0.762)
		(layer "In11.Cu")
		(net "P5V_AUX")
	)
	(segment
		(start 447.322194 -419.596824)
		(end 449.307966 -419.596824)
		(width 0.762)
		(layer "In11.Cu")
		(net "P5V_AUX")
	)
	(segment
		(start 439.13044 -394.339826)
		(end 440.31408 -393.156186)
		(width 0.762)
		(layer "In11.Cu")
		(net "P5V_AUX")
	)
	(segment
		(start 439.471308 -406.931622)
		(end 439.471308 -415.821114)
		(width 0.762)
		(layer "In11.Cu")
		(net "P5V_AUX")
	)
	(segment
		(start 439.471308 -406.931622)
		(end 439.471308 -404.241508)
		(width 0.762)
		(layer "In11.Cu")
		(net "P5V_AUX")
	)
	(segment
		(start 175.863504 -365.334804)
		(end 175.863504 -364.475776)
		(width 0.762)
		(layer "In11.Cu")
		(net "P5V_AUX")
	)
	(segment
		(start 177.223674 -363.115606)
		(end 177.223674 -354.968302)
		(width 0.762)
		(layer "In11.Cu")
		(net "P5V_AUX")
	)
	(segment
		(start 440.31408 -393.156186)
		(end 440.31408 -388.180072)
		(width 0.762)
		(layer "In11.Cu")
		(net "P5V_AUX")
	)
	(segment
		(start 438.472072 -386.338064)
		(end 438.472072 -376.534172)
		(width 0.762)
		(layer "In11.Cu")
		(net "P5V_AUX")
	)
	(segment
		(start 442.497972 -372.508272)
		(end 451.023228 -372.508272)
		(width 0.762)
		(layer "In11.Cu")
		(net "P5V_AUX")
	)
	(segment
		(start 439.13044 -403.90064)
		(end 439.13044 -394.339826)
		(width 0.762)
		(layer "In11.Cu")
		(net "P5V_AUX")
	)
	(segment
		(start 440.31408 -388.180072)
		(end 438.472072 -386.338064)
		(width 0.762)
		(layer "In11.Cu")
		(net "P5V_AUX")
	)
	(segment
		(start 439.471308 -404.241508)
		(end 439.13044 -403.90064)
		(width 0.762)
		(layer "In11.Cu")
		(net "P5V_AUX")
	)
	(segment
		(start 175.863504 -364.475776)
		(end 177.223674 -363.115606)
		(width 0.762)
		(layer "In11.Cu")
		(net "P5V_AUX")
	)
	(segment
		(start 165.955472 -147.692872)
		(end 165.934644 -147.7137)
		(width 1.016)
		(layer "In13.Cu")
		(net "P5V_AUX")
	)
	(segment
		(start 105.258108 -138.35126)
		(end 132.64642 -138.35126)
		(width 1.016)
		(layer "In13.Cu")
		(net "P5V_AUX")
	)
	(segment
		(start 132.64642 -138.35126)
		(end 137.686034 -143.390874)
		(width 1.016)
		(layer "In13.Cu")
		(net "P5V_AUX")
	)
	(segment
		(start 165.934644 -147.7137)
		(end 140.61694 -147.7137)
		(width 1.016)
		(layer "In13.Cu")
		(net "P5V_AUX")
	)
	(segment
		(start 137.686034 -143.390874)
		(end 137.686034 -150.644606)
		(width 1.016)
		(layer "In13.Cu")
		(net "P5V_AUX")
	)
	(segment
		(start 140.61694 -147.7137)
		(end 137.686034 -150.644606)
		(width 1.016)
		(layer "In13.Cu")
		(net "P5V_AUX")
	)
	(segment
		(start 276.2758 -26.289)
		(end 264.541 -38.0238)
		(width 0.4572)
		(layer "In15.Cu")
		(net "P5V_AUX")
	)
	(segment
		(start 193.91376 -39.13124)
		(end 185.900568 -39.13124)
		(width 0.4572)
		(layer "In15.Cu")
		(net "P5V_AUX")
	)
	(segment
		(start 142.108936 -37.316664)
		(end 142.108936 -39.793418)
		(width 0.4572)
		(layer "In15.Cu")
		(net "P5V_AUX")
	)
	(segment
		(start 264.541 -38.0238)
		(end 246.9388 -38.0238)
		(width 0.4572)
		(layer "In15.Cu")
		(net "P5V_AUX")
	)
	(segment
		(start 320.921888 -23.587456)
		(end 319.540382 -24.968962)
		(width 0.4572)
		(layer "In15.Cu")
		(net "P5V_AUX")
	)
	(segment
		(start 196.179948 -38.1)
		(end 194.945 -38.1)
		(width 0.4572)
		(layer "In15.Cu")
		(net "P5V_AUX")
	)
	(segment
		(start 211.0232 -40.4876)
		(end 198.567548 -40.4876)
		(width 0.4572)
		(layer "In15.Cu")
		(net "P5V_AUX")
	)
	(segment
		(start 316.757304 -26.289)
		(end 276.2758 -26.289)
		(width 0.4572)
		(layer "In15.Cu")
		(net "P5V_AUX")
	)
	(segment
		(start 246.9388 -38.0238)
		(end 242.824 -42.1386)
		(width 0.4572)
		(layer "In15.Cu")
		(net "P5V_AUX")
	)
	(segment
		(start 218.2876 -40.2336)
		(end 216.8652 -38.8112)
		(width 0.4572)
		(layer "In15.Cu")
		(net "P5V_AUX")
	)
	(segment
		(start 216.8652 -38.8112)
		(end 212.6996 -38.8112)
		(width 0.4572)
		(layer "In15.Cu")
		(net "P5V_AUX")
	)
	(segment
		(start 212.6996 -38.8112)
		(end 211.0232 -40.4876)
		(width 0.4572)
		(layer "In15.Cu")
		(net "P5V_AUX")
	)
	(segment
		(start 178.281838 -38.759638)
		(end 168.783 -29.2608)
		(width 0.4572)
		(layer "In15.Cu")
		(net "P5V_AUX")
	)
	(segment
		(start 319.540382 -24.968962)
		(end 318.077342 -24.968962)
		(width 0.4572)
		(layer "In15.Cu")
		(net "P5V_AUX")
	)
	(segment
		(start 242.824 -42.1386)
		(end 235.31703 -42.1386)
		(width 0.4572)
		(layer "In15.Cu")
		(net "P5V_AUX")
	)
	(segment
		(start 194.945 -38.1)
		(end 193.91376 -39.13124)
		(width 0.4572)
		(layer "In15.Cu")
		(net "P5V_AUX")
	)
	(segment
		(start 198.567548 -40.4876)
		(end 196.179948 -38.1)
		(width 0.4572)
		(layer "In15.Cu")
		(net "P5V_AUX")
	)
	(segment
		(start 168.783 -29.2608)
		(end 150.1648 -29.2608)
		(width 0.4572)
		(layer "In15.Cu")
		(net "P5V_AUX")
	)
	(segment
		(start 150.1648 -29.2608)
		(end 142.108936 -37.316664)
		(width 0.4572)
		(layer "In15.Cu")
		(net "P5V_AUX")
	)
	(segment
		(start 234.041442 -40.863012)
		(end 230.194612 -40.863012)
		(width 0.4572)
		(layer "In15.Cu")
		(net "P5V_AUX")
	)
	(segment
		(start 185.900568 -39.13124)
		(end 185.528966 -38.759638)
		(width 0.4572)
		(layer "In15.Cu")
		(net "P5V_AUX")
	)
	(segment
		(start 235.31703 -42.1386)
		(end 234.041442 -40.863012)
		(width 0.4572)
		(layer "In15.Cu")
		(net "P5V_AUX")
	)
	(segment
		(start 318.077342 -24.968962)
		(end 316.757304 -26.289)
		(width 0.4572)
		(layer "In15.Cu")
		(net "P5V_AUX")
	)
	(segment
		(start 185.528966 -38.759638)
		(end 178.281838 -38.759638)
		(width 0.4572)
		(layer "In15.Cu")
		(net "P5V_AUX")
	)
	(segment
		(start 229.5652 -40.2336)
		(end 218.2876 -40.2336)
		(width 0.4572)
		(layer "In15.Cu")
		(net "P5V_AUX")
	)
	(segment
		(start 230.194612 -40.863012)
		(end 229.5652 -40.2336)
		(width 0.4572)
		(layer "In15.Cu")
		(net "P5V_AUX")
	)
	(segment
		(start 125.701806 -369.30584)
		(end 125.701806 -370.00942)
		(width 0.12954)
		(layer "F.Cu")
		(net "P5E_CPU1_P3_TX_DP<9>")
	)
	(segment
		(start 125.701806 -370.00942)
		(end 125.405896 -370.30533)
		(width 0.12954)
		(layer "F.Cu")
		(net "P5E_CPU1_P3_TX_DP<9>")
	)
	(segment
		(start 125.431296 -369.03533)
		(end 125.701806 -369.30584)
		(width 0.12954)
		(layer "F.Cu")
		(net "P5E_CPU1_P3_TX_DP<9>")
	)
	(segment
		(start 119.127778 -276.2504)
		(end 119.59463 -276.516338)
		(width 0.12954)
		(layer "F.Cu")
		(net "P5E_CPU1_P3_TX_DP<9>")
	)
	(segment
		(start 121.152666 -278.600916)
		(end 121.191782 -278.623776)
		(width 0.1143)
		(layer "In11.Cu")
		(net "P5E_CPU1_P3_TX_DP<9>")
	)
	(segment
		(start 121.668286 -279.437592)
		(end 121.669556 -279.438354)
		(width 0.1143)
		(layer "In11.Cu")
		(net "P5E_CPU1_P3_TX_DP<9>")
	)
	(segment
		(start 121.152666 -288.320988)
		(end 121.191782 -288.343848)
		(width 0.1143)
		(layer "In11.Cu")
		(net "P5E_CPU1_P3_TX_DP<9>")
	)
	(segment
		(start 121.191782 -288.988754)
		(end 121.152666 -289.011614)
		(width 0.1143)
		(layer "In11.Cu")
		(net "P5E_CPU1_P3_TX_DP<9>")
	)
	(segment
		(start 121.191782 -284.128972)
		(end 121.152666 -284.151832)
		(width 0.1143)
		(layer "In11.Cu")
		(net "P5E_CPU1_P3_TX_DP<9>")
	)
	(segment
		(start 121.672096 -279.439624)
		(end 121.693432 -279.45207)
		(width 0.1143)
		(layer "In11.Cu")
		(net "P5E_CPU1_P3_TX_DP<9>")
	)
	(segment
		(start 121.191782 -285.103824)
		(end 121.222262 -285.121604)
		(width 0.1143)
		(layer "In11.Cu")
		(net "P5E_CPU1_P3_TX_DP<9>")
	)
	(segment
		(start 121.152666 -286.700976)
		(end 121.191782 -286.723836)
		(width 0.1143)
		(layer "In11.Cu")
		(net "P5E_CPU1_P3_TX_DP<9>")
	)
	(segment
		(start 120.25249 -277.004272)
		(end 120.255284 -277.005796)
		(width 0.1143)
		(layer "In11.Cu")
		(net "P5E_CPU1_P3_TX_DP<9>")
	)
	(segment
		(start 121.222262 -280.871168)
		(end 121.191782 -280.888948)
		(width 0.1143)
		(layer "In11.Cu")
		(net "P5E_CPU1_P3_TX_DP<9>")
	)
	(segment
		(start 121.885964 -297.022266)
		(end 122.72264 -299.780198)
		(width 0.14224)
		(layer "In11.Cu")
		(net "P5E_CPU1_P3_TX_DP<9>")
	)
	(segment
		(start 121.191782 -291.583618)
		(end 121.222262 -291.601398)
		(width 0.1143)
		(layer "In11.Cu")
		(net "P5E_CPU1_P3_TX_DP<9>")
	)
	(segment
		(start 121.630186 -279.415494)
		(end 121.661682 -279.433782)
		(width 0.1143)
		(layer "In11.Cu")
		(net "P5E_CPU1_P3_TX_DP<9>")
	)
	(segment
		(start 121.861326 -296.018204)
		(end 121.931684 -296.413936)
		(width 0.1143)
		(layer "In11.Cu")
		(net "P5E_CPU1_P3_TX_DP<9>")
	)
	(segment
		(start 120.753124 -277.832058)
		(end 120.753378 -277.832058)
		(width 0.1143)
		(layer "In11.Cu")
		(net "P5E_CPU1_P3_TX_DP<9>")
	)
	(segment
		(start 121.191782 -285.748984)
		(end 121.152666 -285.771844)
		(width 0.1143)
		(layer "In11.Cu")
		(net "P5E_CPU1_P3_TX_DP<9>")
	)
	(segment
		(start 121.152666 -289.940746)
		(end 121.191782 -289.963606)
		(width 0.1143)
		(layer "In11.Cu")
		(net "P5E_CPU1_P3_TX_DP<9>")
	)
	(segment
		(start 121.669556 -279.438354)
		(end 121.672096 -279.439624)
		(width 0.1143)
		(layer "In11.Cu")
		(net "P5E_CPU1_P3_TX_DP<9>")
	)
	(segment
		(start 121.191782 -282.50896)
		(end 121.152666 -282.53182)
		(width 0.1143)
		(layer "In11.Cu")
		(net "P5E_CPU1_P3_TX_DP<9>")
	)
	(segment
		(start 121.191782 -290.608766)
		(end 121.152666 -290.631626)
		(width 0.1143)
		(layer "In11.Cu")
		(net "P5E_CPU1_P3_TX_DP<9>")
	)
	(segment
		(start 122.72264 -299.780198)
		(end 124.579634 -302.559466)
		(width 0.14224)
		(layer "In11.Cu")
		(net "P5E_CPU1_P3_TX_DP<9>")
	)
	(segment
		(start 121.666 -279.436322)
		(end 121.667524 -279.437084)
		(width 0.1143)
		(layer "In11.Cu")
		(net "P5E_CPU1_P3_TX_DP<9>")
	)
	(segment
		(start 121.191782 -292.228778)
		(end 121.152666 -292.251638)
		(width 0.1143)
		(layer "In11.Cu")
		(net "P5E_CPU1_P3_TX_DP<9>")
	)
	(segment
		(start 121.222262 -292.210998)
		(end 121.191782 -292.228778)
		(width 0.1143)
		(layer "In11.Cu")
		(net "P5E_CPU1_P3_TX_DP<9>")
	)
	(segment
		(start 121.191782 -293.84879)
		(end 121.152666 -293.87165)
		(width 0.1143)
		(layer "In11.Cu")
		(net "P5E_CPU1_P3_TX_DP<9>")
	)
	(segment
		(start 120.439434 -277.326344)
		(end 120.439434 -277.329392)
		(width 0.1143)
		(layer "In11.Cu")
		(net "P5E_CPU1_P3_TX_DP<9>")
	)
	(segment
		(start 121.222262 -290.590986)
		(end 121.191782 -290.608766)
		(width 0.1143)
		(layer "In11.Cu")
		(net "P5E_CPU1_P3_TX_DP<9>")
	)
	(segment
		(start 120.251728 -277.003764)
		(end 120.251982 -277.004018)
		(width 0.1143)
		(layer "In11.Cu")
		(net "P5E_CPU1_P3_TX_DP<9>")
	)
	(segment
		(start 121.222262 -284.111192)
		(end 121.191782 -284.128972)
		(width 0.1143)
		(layer "In11.Cu")
		(net "P5E_CPU1_P3_TX_DP<9>")
	)
	(segment
		(start 121.622566 -279.410922)
		(end 121.629424 -279.414986)
		(width 0.1143)
		(layer "In11.Cu")
		(net "P5E_CPU1_P3_TX_DP<9>")
	)
	(segment
		(start 124.579634 -302.559466)
		(end 131.343908 -310.80202)
		(width 0.14224)
		(layer "In11.Cu")
		(net "P5E_CPU1_P3_TX_DP<9>")
	)
	(segment
		(start 121.379234 -295.146222)
		(end 121.379488 -295.146222)
		(width 0.1143)
		(layer "In11.Cu")
		(net "P5E_CPU1_P3_TX_DP<9>")
	)
	(segment
		(start 121.191782 -286.723836)
		(end 121.224294 -286.742632)
		(width 0.1143)
		(layer "In11.Cu")
		(net "P5E_CPU1_P3_TX_DP<9>")
	)
	(segment
		(start 121.191782 -294.823642)
		(end 121.222262 -294.841422)
		(width 0.1143)
		(layer "In11.Cu")
		(net "P5E_CPU1_P3_TX_DP<9>")
	)
	(segment
		(start 121.191782 -280.888948)
		(end 121.152666 -280.911808)
		(width 0.1143)
		(layer "In11.Cu")
		(net "P5E_CPU1_P3_TX_DP<9>")
	)
	(segment
		(start 121.660666 -280.07945)
		(end 121.659142 -280.080466)
		(width 0.1143)
		(layer "In11.Cu")
		(net "P5E_CPU1_P3_TX_DP<9>")
	)
	(segment
		(start 121.662444 -279.43429)
		(end 121.665238 -279.435814)
		(width 0.1143)
		(layer "In11.Cu")
		(net "P5E_CPU1_P3_TX_DP<9>")
	)
	(segment
		(start 121.665238 -279.435814)
		(end 121.666 -279.436322)
		(width 0.1143)
		(layer "In11.Cu")
		(net "P5E_CPU1_P3_TX_DP<9>")
	)
	(segment
		(start 121.191782 -293.20363)
		(end 121.222262 -293.22141)
		(width 0.1143)
		(layer "In11.Cu")
		(net "P5E_CPU1_P3_TX_DP<9>")
	)
	(segment
		(start 119.892572 -276.516338)
		(end 119.975376 -276.599142)
		(width 0.1143)
		(layer "In11.Cu")
		(net "P5E_CPU1_P3_TX_DP<9>")
	)
	(segment
		(start 134.95909 -361.277154)
		(end 130.901186 -365.335058)
		(width 0.14224)
		(layer "In11.Cu")
		(net "P5E_CPU1_P3_TX_DP<9>")
	)
	(segment
		(start 138.48334 -323.04863)
		(end 141.981936 -340.637114)
		(width 0.14224)
		(layer "In11.Cu")
		(net "P5E_CPU1_P3_TX_DP<9>")
	)
	(segment
		(start 130.421126 -365.655606)
		(end 126.640844 -367.221262)
		(width 0.14224)
		(layer "In11.Cu")
		(net "P5E_CPU1_P3_TX_DP<9>")
	)
	(segment
		(start 120.682004 -277.790656)
		(end 120.753124 -277.832058)
		(width 0.1143)
		(layer "In11.Cu")
		(net "P5E_CPU1_P3_TX_DP<9>")
	)
	(segment
		(start 121.931684 -296.538396)
		(end 121.885964 -296.584116)
		(width 0.1143)
		(layer "In11.Cu")
		(net "P5E_CPU1_P3_TX_DP<9>")
	)
	(segment
		(start 131.343908 -310.80202)
		(end 136.78027 -318.937894)
		(width 0.14224)
		(layer "In11.Cu")
		(net "P5E_CPU1_P3_TX_DP<9>")
	)
	(segment
		(start 121.152666 -283.460952)
		(end 121.191782 -283.483812)
		(width 0.1143)
		(layer "In11.Cu")
		(net "P5E_CPU1_P3_TX_DP<9>")
	)
	(segment
		(start 121.667524 -279.437084)
		(end 121.668286 -279.437592)
		(width 0.1143)
		(layer "In11.Cu")
		(net "P5E_CPU1_P3_TX_DP<9>")
	)
	(segment
		(start 121.662444 -280.078434)
		(end 121.661682 -280.078942)
		(width 0.1143)
		(layer "In11.Cu")
		(net "P5E_CPU1_P3_TX_DP<9>")
	)
	(segment
		(start 120.21947 -276.984968)
		(end 120.220232 -276.985476)
		(width 0.1143)
		(layer "In11.Cu")
		(net "P5E_CPU1_P3_TX_DP<9>")
	)
	(segment
		(start 120.671336 -277.783036)
		(end 120.682004 -277.790656)
		(width 0.1143)
		(layer "In11.Cu")
		(net "P5E_CPU1_P3_TX_DP<9>")
	)
	(segment
		(start 121.629424 -279.414986)
		(end 121.630186 -279.415494)
		(width 0.1143)
		(layer "In11.Cu")
		(net "P5E_CPU1_P3_TX_DP<9>")
	)
	(segment
		(start 120.251982 -277.004018)
		(end 120.25249 -277.004272)
		(width 0.1143)
		(layer "In11.Cu")
		(net "P5E_CPU1_P3_TX_DP<9>")
	)
	(segment
		(start 121.885964 -296.584116)
		(end 121.885964 -296.612564)
		(width 0.1143)
		(layer "In11.Cu")
		(net "P5E_CPU1_P3_TX_DP<9>")
	)
	(segment
		(start 136.78027 -318.937894)
		(end 138.48334 -323.04863)
		(width 0.14224)
		(layer "In11.Cu")
		(net "P5E_CPU1_P3_TX_DP<9>")
	)
	(segment
		(start 121.191782 -281.8638)
		(end 121.222262 -281.88158)
		(width 0.1143)
		(layer "In11.Cu")
		(net "P5E_CPU1_P3_TX_DP<9>")
	)
	(segment
		(start 125.722126 -368.140996)
		(end 125.722126 -368.7445)
		(width 0.14224)
		(layer "In11.Cu")
		(net "P5E_CPU1_P3_TX_DP<9>")
	)
	(segment
		(start 121.661682 -280.078942)
		(end 121.660666 -280.07945)
		(width 0.1143)
		(layer "In11.Cu")
		(net "P5E_CPU1_P3_TX_DP<9>")
	)
	(segment
		(start 121.693432 -280.060654)
		(end 121.662444 -280.078434)
		(width 0.1143)
		(layer "In11.Cu")
		(net "P5E_CPU1_P3_TX_DP<9>")
	)
	(segment
		(start 121.661682 -279.433782)
		(end 121.662444 -279.43429)
		(width 0.1143)
		(layer "In11.Cu")
		(net "P5E_CPU1_P3_TX_DP<9>")
	)
	(segment
		(start 121.152666 -291.560758)
		(end 121.191782 -291.583618)
		(width 0.1143)
		(layer "In11.Cu")
		(net "P5E_CPU1_P3_TX_DP<9>")
	)
	(segment
		(start 125.722126 -368.7445)
		(end 125.431296 -369.03533)
		(width 0.14224)
		(layer "In11.Cu")
		(net "P5E_CPU1_P3_TX_DP<9>")
	)
	(segment
		(start 121.191782 -288.343848)
		(end 121.224294 -288.362644)
		(width 0.1143)
		(layer "In11.Cu")
		(net "P5E_CPU1_P3_TX_DP<9>")
	)
	(segment
		(start 120.220232 -276.985476)
		(end 120.251728 -277.003764)
		(width 0.1143)
		(layer "In11.Cu")
		(net "P5E_CPU1_P3_TX_DP<9>")
	)
	(segment
		(start 121.152666 -281.84094)
		(end 121.191782 -281.8638)
		(width 0.1143)
		(layer "In11.Cu")
		(net "P5E_CPU1_P3_TX_DP<9>")
	)
	(segment
		(start 121.191782 -289.963606)
		(end 121.222262 -289.981386)
		(width 0.1143)
		(layer "In11.Cu")
		(net "P5E_CPU1_P3_TX_DP<9>")
	)
	(segment
		(start 141.406626 -348.722188)
		(end 138.241278 -356.364794)
		(width 0.14224)
		(layer "In11.Cu")
		(net "P5E_CPU1_P3_TX_DP<9>")
	)
	(segment
		(start 121.849642 -295.959022)
		(end 121.861326 -296.018204)
		(width 0.1143)
		(layer "In11.Cu")
		(net "P5E_CPU1_P3_TX_DP<9>")
	)
	(segment
		(start 120.255284 -277.005796)
		(end 120.281446 -277.021036)
		(width 0.1143)
		(layer "In11.Cu")
		(net "P5E_CPU1_P3_TX_DP<9>")
	)
	(segment
		(start 121.152666 -285.080964)
		(end 121.191782 -285.103824)
		(width 0.1143)
		(layer "In11.Cu")
		(net "P5E_CPU1_P3_TX_DP<9>")
	)
	(segment
		(start 121.191782 -278.623776)
		(end 121.222262 -278.641556)
		(width 0.1143)
		(layer "In11.Cu")
		(net "P5E_CPU1_P3_TX_DP<9>")
	)
	(segment
		(start 120.212612 -276.980904)
		(end 120.21947 -276.984968)
		(width 0.1143)
		(layer "In11.Cu")
		(net "P5E_CPU1_P3_TX_DP<9>")
	)
	(segment
		(start 121.222262 -288.970974)
		(end 121.191782 -288.988754)
		(width 0.1143)
		(layer "In11.Cu")
		(net "P5E_CPU1_P3_TX_DP<9>")
	)
	(segment
		(start 121.222262 -293.83101)
		(end 121.191782 -293.84879)
		(width 0.1143)
		(layer "In11.Cu")
		(net "P5E_CPU1_P3_TX_DP<9>")
	)
	(segment
		(start 121.152666 -294.800782)
		(end 121.191782 -294.823642)
		(width 0.1143)
		(layer "In11.Cu")
		(net "P5E_CPU1_P3_TX_DP<9>")
	)
	(segment
		(start 121.222262 -287.350962)
		(end 121.155206 -287.390078)
		(width 0.1143)
		(layer "In11.Cu")
		(net "P5E_CPU1_P3_TX_DP<9>")
	)
	(segment
		(start 121.931684 -296.413936)
		(end 121.931684 -296.538396)
		(width 0.1143)
		(layer "In11.Cu")
		(net "P5E_CPU1_P3_TX_DP<9>")
	)
	(segment
		(start 121.659142 -280.080466)
		(end 121.622566 -280.101802)
		(width 0.1143)
		(layer "In11.Cu")
		(net "P5E_CPU1_P3_TX_DP<9>")
	)
	(segment
		(start 121.191782 -283.483812)
		(end 121.222262 -283.501592)
		(width 0.1143)
		(layer "In11.Cu")
		(net "P5E_CPU1_P3_TX_DP<9>")
	)
	(segment
		(start 141.981936 -340.637114)
		(end 141.981936 -345.830652)
		(width 0.14224)
		(layer "In11.Cu")
		(net "P5E_CPU1_P3_TX_DP<9>")
	)
	(segment
		(start 119.59463 -276.516338)
		(end 119.892572 -276.516338)
		(width 0.1143)
		(layer "In11.Cu")
		(net "P5E_CPU1_P3_TX_DP<9>")
	)
	(segment
		(start 121.885964 -296.612564)
		(end 121.885964 -297.022266)
		(width 0.14224)
		(layer "In11.Cu")
		(net "P5E_CPU1_P3_TX_DP<9>")
	)
	(segment
		(start 121.222262 -282.49118)
		(end 121.191782 -282.50896)
		(width 0.1143)
		(layer "In11.Cu")
		(net "P5E_CPU1_P3_TX_DP<9>")
	)
	(segment
		(start 121.222262 -285.731204)
		(end 121.191782 -285.748984)
		(width 0.1143)
		(layer "In11.Cu")
		(net "P5E_CPU1_P3_TX_DP<9>")
	)
	(segment
		(start 121.62536 -295.612566)
		(end 121.69394 -295.652444)
		(width 0.1143)
		(layer "In11.Cu")
		(net "P5E_CPU1_P3_TX_DP<9>")
	)
	(segment
		(start 125.951234 -367.682018)
		(end 125.884686 -367.748566)
		(width 0.14224)
		(layer "In11.Cu")
		(net "P5E_CPU1_P3_TX_DP<9>")
	)
	(segment
		(start 121.152666 -293.18077)
		(end 121.191782 -293.20363)
		(width 0.1143)
		(layer "In11.Cu")
		(net "P5E_CPU1_P3_TX_DP<9>")
	)
	(arc
		(start 121.222262 -289.981386)
		(mid 121.379239 -290.286186)
		(end 121.222262 -290.590986)
		(width 0.1143)
		(layer "In11.Cu")
		(net "P5E_CPU1_P3_TX_DP<9>")
	)
	(arc
		(start 126.640844 -367.221262)
		(mid 126.27335 -367.417681)
		(end 125.951234 -367.682018)
		(width 0.14224)
		(layer "In11.Cu")
		(net "P5E_CPU1_P3_TX_DP<9>")
	)
	(arc
		(start 121.152666 -284.151832)
		(mid 120.909339 -284.616398)
		(end 121.152666 -285.080964)
		(width 0.1143)
		(layer "In11.Cu")
		(net "P5E_CPU1_P3_TX_DP<9>")
	)
	(arc
		(start 121.152666 -292.251638)
		(mid 120.909339 -292.716204)
		(end 121.152666 -293.18077)
		(width 0.1143)
		(layer "In11.Cu")
		(net "P5E_CPU1_P3_TX_DP<9>")
	)
	(arc
		(start 121.69394 -295.652444)
		(mid 121.730384 -295.682404)
		(end 121.762774 -295.716706)
		(width 0.1143)
		(layer "In11.Cu")
		(net "P5E_CPU1_P3_TX_DP<9>")
	)
	(arc
		(start 121.762774 -295.716706)
		(mid 121.825113 -295.831088)
		(end 121.849642 -295.959022)
		(width 0.1143)
		(layer "In11.Cu")
		(net "P5E_CPU1_P3_TX_DP<9>")
	)
	(arc
		(start 121.222262 -283.501592)
		(mid 121.379239 -283.806392)
		(end 121.222262 -284.111192)
		(width 0.1143)
		(layer "In11.Cu")
		(net "P5E_CPU1_P3_TX_DP<9>")
	)
	(arc
		(start 119.979186 -276.622002)
		(mid 120.060619 -276.8244)
		(end 120.212612 -276.980904)
		(width 0.1143)
		(layer "In11.Cu")
		(net "P5E_CPU1_P3_TX_DP<9>")
	)
	(arc
		(start 121.622566 -280.101802)
		(mid 121.443753 -280.304152)
		(end 121.379234 -280.566368)
		(width 0.1143)
		(layer "In11.Cu")
		(net "P5E_CPU1_P3_TX_DP<9>")
	)
	(arc
		(start 120.909334 -278.13635)
		(mid 120.973849 -278.398569)
		(end 121.152666 -278.600916)
		(width 0.1143)
		(layer "In11.Cu")
		(net "P5E_CPU1_P3_TX_DP<9>")
	)
	(arc
		(start 141.981936 -345.830652)
		(mid 141.836694 -347.304756)
		(end 141.406626 -348.722188)
		(width 0.14224)
		(layer "In11.Cu")
		(net "P5E_CPU1_P3_TX_DP<9>")
	)
	(arc
		(start 121.379234 -288.666174)
		(mid 121.337685 -288.837596)
		(end 121.222262 -288.970974)
		(width 0.1143)
		(layer "In11.Cu")
		(net "P5E_CPU1_P3_TX_DP<9>")
	)
	(arc
		(start 121.222262 -293.22141)
		(mid 121.379239 -293.52621)
		(end 121.222262 -293.83101)
		(width 0.1143)
		(layer "In11.Cu")
		(net "P5E_CPU1_P3_TX_DP<9>")
	)
	(arc
		(start 121.152666 -289.011614)
		(mid 120.909339 -289.47618)
		(end 121.152666 -289.940746)
		(width 0.1143)
		(layer "In11.Cu")
		(net "P5E_CPU1_P3_TX_DP<9>")
	)
	(arc
		(start 121.379234 -280.566368)
		(mid 121.337685 -280.73779)
		(end 121.222262 -280.871168)
		(width 0.1143)
		(layer "In11.Cu")
		(net "P5E_CPU1_P3_TX_DP<9>")
	)
	(arc
		(start 121.152666 -280.911808)
		(mid 120.909339 -281.376374)
		(end 121.152666 -281.84094)
		(width 0.1143)
		(layer "In11.Cu")
		(net "P5E_CPU1_P3_TX_DP<9>")
	)
	(arc
		(start 119.975376 -276.599142)
		(mid 119.977164 -276.610591)
		(end 119.979186 -276.622002)
		(width 0.1143)
		(layer "In11.Cu")
		(net "P5E_CPU1_P3_TX_DP<9>")
	)
	(arc
		(start 121.379234 -287.046162)
		(mid 121.337685 -287.217584)
		(end 121.222262 -287.350962)
		(width 0.1143)
		(layer "In11.Cu")
		(net "P5E_CPU1_P3_TX_DP<9>")
	)
	(arc
		(start 121.152666 -282.53182)
		(mid 120.909339 -282.996386)
		(end 121.152666 -283.460952)
		(width 0.1143)
		(layer "In11.Cu")
		(net "P5E_CPU1_P3_TX_DP<9>")
	)
	(arc
		(start 121.222262 -278.641556)
		(mid 121.337689 -278.774932)
		(end 121.379234 -278.946356)
		(width 0.1143)
		(layer "In11.Cu")
		(net "P5E_CPU1_P3_TX_DP<9>")
	)
	(arc
		(start 130.901186 -365.335058)
		(mid 130.676954 -365.518989)
		(end 130.421126 -365.655606)
		(width 0.14224)
		(layer "In11.Cu")
		(net "P5E_CPU1_P3_TX_DP<9>")
	)
	(arc
		(start 125.884686 -367.748566)
		(mid 125.764381 -367.928614)
		(end 125.722126 -368.140996)
		(width 0.14224)
		(layer "In11.Cu")
		(net "P5E_CPU1_P3_TX_DP<9>")
	)
	(arc
		(start 121.224294 -286.742632)
		(mid 121.338223 -286.875779)
		(end 121.379234 -287.046162)
		(width 0.1143)
		(layer "In11.Cu")
		(net "P5E_CPU1_P3_TX_DP<9>")
	)
	(arc
		(start 121.379234 -278.946356)
		(mid 121.443749 -279.208575)
		(end 121.622566 -279.410922)
		(width 0.1143)
		(layer "In11.Cu")
		(net "P5E_CPU1_P3_TX_DP<9>")
	)
	(arc
		(start 121.222262 -285.121604)
		(mid 121.379239 -285.426404)
		(end 121.222262 -285.731204)
		(width 0.1143)
		(layer "In11.Cu")
		(net "P5E_CPU1_P3_TX_DP<9>")
	)
	(arc
		(start 121.152666 -290.631626)
		(mid 120.909339 -291.096192)
		(end 121.152666 -291.560758)
		(width 0.1143)
		(layer "In11.Cu")
		(net "P5E_CPU1_P3_TX_DP<9>")
	)
	(arc
		(start 121.379488 -295.146222)
		(mid 121.444724 -295.409813)
		(end 121.62536 -295.612566)
		(width 0.1143)
		(layer "In11.Cu")
		(net "P5E_CPU1_P3_TX_DP<9>")
	)
	(arc
		(start 121.222262 -294.841422)
		(mid 121.337689 -294.974798)
		(end 121.379234 -295.146222)
		(width 0.1143)
		(layer "In11.Cu")
		(net "P5E_CPU1_P3_TX_DP<9>")
	)
	(arc
		(start 121.152666 -293.87165)
		(mid 120.909339 -294.336216)
		(end 121.152666 -294.800782)
		(width 0.1143)
		(layer "In11.Cu")
		(net "P5E_CPU1_P3_TX_DP<9>")
	)
	(arc
		(start 121.152666 -285.771844)
		(mid 120.909339 -286.23641)
		(end 121.152666 -286.700976)
		(width 0.1143)
		(layer "In11.Cu")
		(net "P5E_CPU1_P3_TX_DP<9>")
	)
	(arc
		(start 120.753378 -277.832058)
		(mid 120.868054 -277.965392)
		(end 120.909334 -278.13635)
		(width 0.1143)
		(layer "In11.Cu")
		(net "P5E_CPU1_P3_TX_DP<9>")
	)
	(arc
		(start 120.439434 -277.329392)
		(mid 120.500724 -277.584151)
		(end 120.671336 -277.783036)
		(width 0.1143)
		(layer "In11.Cu")
		(net "P5E_CPU1_P3_TX_DP<9>")
	)
	(arc
		(start 120.281446 -277.021036)
		(mid 120.397493 -277.154507)
		(end 120.439434 -277.326344)
		(width 0.1143)
		(layer "In11.Cu")
		(net "P5E_CPU1_P3_TX_DP<9>")
	)
	(arc
		(start 121.224294 -288.362644)
		(mid 121.338223 -288.495791)
		(end 121.379234 -288.666174)
		(width 0.1143)
		(layer "In11.Cu")
		(net "P5E_CPU1_P3_TX_DP<9>")
	)
	(arc
		(start 121.155206 -287.390078)
		(mid 120.974554 -287.592823)
		(end 120.909334 -287.856422)
		(width 0.1143)
		(layer "In11.Cu")
		(net "P5E_CPU1_P3_TX_DP<9>")
	)
	(arc
		(start 120.909334 -287.856422)
		(mid 120.973849 -288.118641)
		(end 121.152666 -288.320988)
		(width 0.1143)
		(layer "In11.Cu")
		(net "P5E_CPU1_P3_TX_DP<9>")
	)
	(arc
		(start 121.693432 -279.45207)
		(mid 121.84936 -279.756362)
		(end 121.693432 -280.060654)
		(width 0.1143)
		(layer "In11.Cu")
		(net "P5E_CPU1_P3_TX_DP<9>")
	)
	(arc
		(start 121.222262 -291.601398)
		(mid 121.379239 -291.906198)
		(end 121.222262 -292.210998)
		(width 0.1143)
		(layer "In11.Cu")
		(net "P5E_CPU1_P3_TX_DP<9>")
	)
	(arc
		(start 121.222262 -281.88158)
		(mid 121.379239 -282.18638)
		(end 121.222262 -282.49118)
		(width 0.1143)
		(layer "In11.Cu")
		(net "P5E_CPU1_P3_TX_DP<9>")
	)
	(arc
		(start 138.241278 -356.364794)
		(mid 136.842112 -358.98262)
		(end 134.95909 -361.277154)
		(width 0.14224)
		(layer "In11.Cu")
		(net "P5E_CPU1_P3_TX_DP<9>")
	)
	(segment
		(start 124.000006 -372.47322)
		(end 123.704096 -372.76913)
		(width 0.12954)
		(layer "F.Cu")
		(net "P5E_CPU1_P3_TX_DP<8>")
	)
	(segment
		(start 123.729496 -371.49913)
		(end 124.000006 -371.76964)
		(width 0.12954)
		(layer "F.Cu")
		(net "P5E_CPU1_P3_TX_DP<8>")
	)
	(segment
		(start 124.000006 -371.76964)
		(end 124.000006 -372.47322)
		(width 0.12954)
		(layer "F.Cu")
		(net "P5E_CPU1_P3_TX_DP<8>")
	)
	(segment
		(start 119.127778 -277.870412)
		(end 119.59463 -278.13635)
		(width 0.12954)
		(layer "F.Cu")
		(net "P5E_CPU1_P3_TX_DP<8>")
	)
	(segment
		(start 120.283478 -291.601906)
		(end 120.288558 -291.605462)
		(width 0.1143)
		(layer "In11.Cu")
		(net "P5E_CPU1_P3_TX_DP<8>")
	)
	(segment
		(start 120.254522 -289.965384)
		(end 120.25503 -289.965384)
		(width 0.1143)
		(layer "In11.Cu")
		(net "P5E_CPU1_P3_TX_DP<8>")
	)
	(segment
		(start 120.254776 -285.747206)
		(end 120.25249 -285.74873)
		(width 0.1143)
		(layer "In11.Cu")
		(net "P5E_CPU1_P3_TX_DP<8>")
	)
	(segment
		(start 120.698768 -295.620186)
		(end 120.753632 -295.652444)
		(width 0.1143)
		(layer "In11.Cu")
		(net "P5E_CPU1_P3_TX_DP<8>")
	)
	(segment
		(start 120.25249 -284.128718)
		(end 120.251728 -284.128972)
		(width 0.1143)
		(layer "In11.Cu")
		(net "P5E_CPU1_P3_TX_DP<8>")
	)
	(segment
		(start 120.254776 -293.847012)
		(end 120.25249 -293.848536)
		(width 0.1143)
		(layer "In11.Cu")
		(net "P5E_CPU1_P3_TX_DP<8>")
	)
	(segment
		(start 120.251728 -285.748984)
		(end 120.250712 -285.749492)
		(width 0.1143)
		(layer "In11.Cu")
		(net "P5E_CPU1_P3_TX_DP<8>")
	)
	(segment
		(start 120.218708 -288.324544)
		(end 120.218962 -288.324544)
		(width 0.1143)
		(layer "In11.Cu")
		(net "P5E_CPU1_P3_TX_DP<8>")
	)
	(segment
		(start 120.212612 -294.800782)
		(end 120.250712 -294.823134)
		(width 0.1143)
		(layer "In11.Cu")
		(net "P5E_CPU1_P3_TX_DP<8>")
	)
	(segment
		(start 123.944634 -303.317656)
		(end 130.744214 -311.602882)
		(width 0.14224)
		(layer "In11.Cu")
		(net "P5E_CPU1_P3_TX_DP<8>")
	)
	(segment
		(start 140.37564 -348.733364)
		(end 137.468102 -355.75367)
		(width 0.14224)
		(layer "In11.Cu")
		(net "P5E_CPU1_P3_TX_DP<8>")
	)
	(segment
		(start 120.251728 -283.483812)
		(end 120.25249 -283.48432)
		(width 0.1143)
		(layer "In11.Cu")
		(net "P5E_CPU1_P3_TX_DP<8>")
	)
	(segment
		(start 120.254776 -290.606988)
		(end 120.25249 -290.608512)
		(width 0.1143)
		(layer "In11.Cu")
		(net "P5E_CPU1_P3_TX_DP<8>")
	)
	(segment
		(start 120.250712 -284.12948)
		(end 120.212612 -284.151832)
		(width 0.1143)
		(layer "In11.Cu")
		(net "P5E_CPU1_P3_TX_DP<8>")
	)
	(segment
		(start 120.212612 -285.080964)
		(end 120.250712 -285.103316)
		(width 0.1143)
		(layer "In11.Cu")
		(net "P5E_CPU1_P3_TX_DP<8>")
	)
	(segment
		(start 120.25249 -292.22827)
		(end 120.251728 -292.228778)
		(width 0.1143)
		(layer "In11.Cu")
		(net "P5E_CPU1_P3_TX_DP<8>")
	)
	(segment
		(start 120.25249 -285.74873)
		(end 120.251728 -285.748984)
		(width 0.1143)
		(layer "In11.Cu")
		(net "P5E_CPU1_P3_TX_DP<8>")
	)
	(segment
		(start 120.247156 -292.231572)
		(end 120.24614 -292.23208)
		(width 0.1143)
		(layer "In11.Cu")
		(net "P5E_CPU1_P3_TX_DP<8>")
	)
	(segment
		(start 120.255284 -290.606988)
		(end 120.254776 -290.606988)
		(width 0.1143)
		(layer "In11.Cu")
		(net "P5E_CPU1_P3_TX_DP<8>")
	)
	(segment
		(start 120.254776 -282.507182)
		(end 120.25249 -282.508706)
		(width 0.1143)
		(layer "In11.Cu")
		(net "P5E_CPU1_P3_TX_DP<8>")
	)
	(segment
		(start 120.250712 -285.103316)
		(end 120.251728 -285.103824)
		(width 0.1143)
		(layer "In11.Cu")
		(net "P5E_CPU1_P3_TX_DP<8>")
	)
	(segment
		(start 120.250712 -288.989262)
		(end 120.212612 -289.011614)
		(width 0.1143)
		(layer "In11.Cu")
		(net "P5E_CPU1_P3_TX_DP<8>")
	)
	(segment
		(start 130.744214 -311.602882)
		(end 135.899144 -319.31737)
		(width 0.14224)
		(layer "In11.Cu")
		(net "P5E_CPU1_P3_TX_DP<8>")
	)
	(segment
		(start 120.24868 -292.230556)
		(end 120.247156 -292.231572)
		(width 0.1143)
		(layer "In11.Cu")
		(net "P5E_CPU1_P3_TX_DP<8>")
	)
	(segment
		(start 119.59463 -278.13635)
		(end 119.892572 -278.13635)
		(width 0.1143)
		(layer "In11.Cu")
		(net "P5E_CPU1_P3_TX_DP<8>")
	)
	(segment
		(start 120.220232 -278.605488)
		(end 120.251728 -278.623776)
		(width 0.1143)
		(layer "In11.Cu")
		(net "P5E_CPU1_P3_TX_DP<8>")
	)
	(segment
		(start 120.21947 -278.60498)
		(end 120.220232 -278.605488)
		(width 0.1143)
		(layer "In11.Cu")
		(net "P5E_CPU1_P3_TX_DP<8>")
	)
	(segment
		(start 120.25249 -280.88844)
		(end 120.251728 -280.888948)
		(width 0.1143)
		(layer "In11.Cu")
		(net "P5E_CPU1_P3_TX_DP<8>")
	)
	(segment
		(start 120.254522 -293.205408)
		(end 120.25503 -293.205408)
		(width 0.1143)
		(layer "In11.Cu")
		(net "P5E_CPU1_P3_TX_DP<8>")
	)
	(segment
		(start 120.250712 -280.889456)
		(end 120.212612 -280.911808)
		(width 0.1143)
		(layer "In11.Cu")
		(net "P5E_CPU1_P3_TX_DP<8>")
	)
	(segment
		(start 120.25249 -293.848536)
		(end 120.251728 -293.84879)
		(width 0.1143)
		(layer "In11.Cu")
		(net "P5E_CPU1_P3_TX_DP<8>")
	)
	(segment
		(start 120.253506 -278.624538)
		(end 120.267222 -278.632412)
		(width 0.1143)
		(layer "In11.Cu")
		(net "P5E_CPU1_P3_TX_DP<8>")
	)
	(segment
		(start 120.255284 -293.847012)
		(end 120.254776 -293.847012)
		(width 0.1143)
		(layer "In11.Cu")
		(net "P5E_CPU1_P3_TX_DP<8>")
	)
	(segment
		(start 120.212612 -281.84094)
		(end 120.250712 -281.863292)
		(width 0.1143)
		(layer "In11.Cu")
		(net "P5E_CPU1_P3_TX_DP<8>")
	)
	(segment
		(start 120.288558 -292.206934)
		(end 120.283478 -292.21049)
		(width 0.1143)
		(layer "In11.Cu")
		(net "P5E_CPU1_P3_TX_DP<8>")
	)
	(segment
		(start 120.212612 -289.940746)
		(end 120.250712 -289.963098)
		(width 0.1143)
		(layer "In11.Cu")
		(net "P5E_CPU1_P3_TX_DP<8>")
	)
	(segment
		(start 120.251728 -288.988754)
		(end 120.250712 -288.989262)
		(width 0.1143)
		(layer "In11.Cu")
		(net "P5E_CPU1_P3_TX_DP<8>")
	)
	(segment
		(start 120.255284 -288.986976)
		(end 120.254776 -288.986976)
		(width 0.1143)
		(layer "In11.Cu")
		(net "P5E_CPU1_P3_TX_DP<8>")
	)
	(segment
		(start 120.212612 -286.700976)
		(end 120.285256 -286.743394)
		(width 0.1143)
		(layer "In11.Cu")
		(net "P5E_CPU1_P3_TX_DP<8>")
	)
	(segment
		(start 120.255284 -284.127194)
		(end 120.254776 -284.127194)
		(width 0.1143)
		(layer "In11.Cu")
		(net "P5E_CPU1_P3_TX_DP<8>")
	)
	(segment
		(start 120.25249 -289.964114)
		(end 120.254522 -289.965384)
		(width 0.1143)
		(layer "In11.Cu")
		(net "P5E_CPU1_P3_TX_DP<8>")
	)
	(segment
		(start 121.884948 -300.235366)
		(end 123.944634 -303.317656)
		(width 0.14224)
		(layer "In11.Cu")
		(net "P5E_CPU1_P3_TX_DP<8>")
	)
	(segment
		(start 134.260336 -360.554524)
		(end 131.45897 -363.35589)
		(width 0.14224)
		(layer "In11.Cu")
		(net "P5E_CPU1_P3_TX_DP<8>")
	)
	(segment
		(start 120.251728 -282.50896)
		(end 120.250712 -282.509468)
		(width 0.1143)
		(layer "In11.Cu")
		(net "P5E_CPU1_P3_TX_DP<8>")
	)
	(segment
		(start 120.250712 -294.823134)
		(end 120.254268 -294.824912)
		(width 0.1143)
		(layer "In11.Cu")
		(net "P5E_CPU1_P3_TX_DP<8>")
	)
	(segment
		(start 120.254522 -285.105602)
		(end 120.25503 -285.105602)
		(width 0.1143)
		(layer "In11.Cu")
		(net "P5E_CPU1_P3_TX_DP<8>")
	)
	(segment
		(start 135.899144 -319.31737)
		(end 137.614406 -323.459348)
		(width 0.14224)
		(layer "In11.Cu")
		(net "P5E_CPU1_P3_TX_DP<8>")
	)
	(segment
		(start 120.25249 -281.864308)
		(end 120.254522 -281.865578)
		(width 0.1143)
		(layer "In11.Cu")
		(net "P5E_CPU1_P3_TX_DP<8>")
	)
	(segment
		(start 120.250712 -290.609274)
		(end 120.212612 -290.631626)
		(width 0.1143)
		(layer "In11.Cu")
		(net "P5E_CPU1_P3_TX_DP<8>")
	)
	(segment
		(start 120.218962 -288.324544)
		(end 120.254776 -288.345372)
		(width 0.1143)
		(layer "In11.Cu")
		(net "P5E_CPU1_P3_TX_DP<8>")
	)
	(segment
		(start 124.020326 -371.2083)
		(end 123.729496 -371.49913)
		(width 0.14224)
		(layer "In11.Cu")
		(net "P5E_CPU1_P3_TX_DP<8>")
	)
	(segment
		(start 120.251728 -284.128972)
		(end 120.250712 -284.12948)
		(width 0.1143)
		(layer "In11.Cu")
		(net "P5E_CPU1_P3_TX_DP<8>")
	)
	(segment
		(start 120.250712 -292.229286)
		(end 120.24868 -292.230556)
		(width 0.1143)
		(layer "In11.Cu")
		(net "P5E_CPU1_P3_TX_DP<8>")
	)
	(segment
		(start 120.250712 -293.203122)
		(end 120.251728 -293.20363)
		(width 0.1143)
		(layer "In11.Cu")
		(net "P5E_CPU1_P3_TX_DP<8>")
	)
	(segment
		(start 120.251728 -289.963606)
		(end 120.25249 -289.964114)
		(width 0.1143)
		(layer "In11.Cu")
		(net "P5E_CPU1_P3_TX_DP<8>")
	)
	(segment
		(start 119.892572 -278.13635)
		(end 119.975376 -278.219154)
		(width 0.1143)
		(layer "In11.Cu")
		(net "P5E_CPU1_P3_TX_DP<8>")
	)
	(segment
		(start 120.220232 -283.465524)
		(end 120.251728 -283.483812)
		(width 0.1143)
		(layer "In11.Cu")
		(net "P5E_CPU1_P3_TX_DP<8>")
	)
	(segment
		(start 120.250712 -293.849298)
		(end 120.212612 -293.87165)
		(width 0.1143)
		(layer "In11.Cu")
		(net "P5E_CPU1_P3_TX_DP<8>")
	)
	(segment
		(start 120.251728 -293.20363)
		(end 120.25249 -293.204138)
		(width 0.1143)
		(layer "In11.Cu")
		(net "P5E_CPU1_P3_TX_DP<8>")
	)
	(segment
		(start 120.254776 -288.345372)
		(end 120.25503 -288.345372)
		(width 0.1143)
		(layer "In11.Cu")
		(net "P5E_CPU1_P3_TX_DP<8>")
	)
	(segment
		(start 120.254776 -284.127194)
		(end 120.25249 -284.128718)
		(width 0.1143)
		(layer "In11.Cu")
		(net "P5E_CPU1_P3_TX_DP<8>")
	)
	(segment
		(start 120.251728 -280.888948)
		(end 120.250712 -280.889456)
		(width 0.1143)
		(layer "In11.Cu")
		(net "P5E_CPU1_P3_TX_DP<8>")
	)
	(segment
		(start 125.284992 -366.983264)
		(end 124.378212 -367.890044)
		(width 0.14224)
		(layer "In11.Cu")
		(net "P5E_CPU1_P3_TX_DP<8>")
	)
	(segment
		(start 120.250712 -282.509468)
		(end 120.212612 -282.53182)
		(width 0.1143)
		(layer "In11.Cu")
		(net "P5E_CPU1_P3_TX_DP<8>")
	)
	(segment
		(start 120.254522 -281.865578)
		(end 120.25503 -281.865578)
		(width 0.1143)
		(layer "In11.Cu")
		(net "P5E_CPU1_P3_TX_DP<8>")
	)
	(segment
		(start 120.25249 -293.204138)
		(end 120.254522 -293.205408)
		(width 0.1143)
		(layer "In11.Cu")
		(net "P5E_CPU1_P3_TX_DP<8>")
	)
	(segment
		(start 120.251728 -278.623776)
		(end 120.25249 -278.624284)
		(width 0.1143)
		(layer "In11.Cu")
		(net "P5E_CPU1_P3_TX_DP<8>")
	)
	(segment
		(start 120.439434 -287.046162)
		(end 120.439434 -287.050734)
		(width 0.1143)
		(layer "In11.Cu")
		(net "P5E_CPU1_P3_TX_DP<8>")
	)
	(segment
		(start 120.25249 -285.104332)
		(end 120.254522 -285.105602)
		(width 0.1143)
		(layer "In11.Cu")
		(net "P5E_CPU1_P3_TX_DP<8>")
	)
	(segment
		(start 124.020326 -368.754152)
		(end 124.020326 -371.2083)
		(width 0.14224)
		(layer "In11.Cu")
		(net "P5E_CPU1_P3_TX_DP<8>")
	)
	(segment
		(start 120.212612 -293.18077)
		(end 120.250712 -293.203122)
		(width 0.1143)
		(layer "In11.Cu")
		(net "P5E_CPU1_P3_TX_DP<8>")
	)
	(segment
		(start 120.682766 -295.610788)
		(end 120.697498 -295.619424)
		(width 0.1143)
		(layer "In11.Cu")
		(net "P5E_CPU1_P3_TX_DP<8>")
	)
	(segment
		(start 120.25249 -278.62403)
		(end 120.253506 -278.624538)
		(width 0.1143)
		(layer "In11.Cu")
		(net "P5E_CPU1_P3_TX_DP<8>")
	)
	(segment
		(start 120.90908 -295.944798)
		(end 120.91162 -296.019474)
		(width 0.1143)
		(layer "In11.Cu")
		(net "P5E_CPU1_P3_TX_DP<8>")
	)
	(segment
		(start 120.212612 -278.600916)
		(end 120.21947 -278.60498)
		(width 0.1143)
		(layer "In11.Cu")
		(net "P5E_CPU1_P3_TX_DP<8>")
	)
	(segment
		(start 120.25249 -288.9885)
		(end 120.251728 -288.988754)
		(width 0.1143)
		(layer "In11.Cu")
		(net "P5E_CPU1_P3_TX_DP<8>")
	)
	(segment
		(start 137.614406 -323.459348)
		(end 141.04747 -340.718394)
		(width 0.14224)
		(layer "In11.Cu")
		(net "P5E_CPU1_P3_TX_DP<8>")
	)
	(segment
		(start 120.940322 -296.659808)
		(end 120.94083 -296.660316)
		(width 0.14224)
		(layer "In11.Cu")
		(net "P5E_CPU1_P3_TX_DP<8>")
	)
	(segment
		(start 120.697498 -295.619424)
		(end 120.69826 -295.619932)
		(width 0.1143)
		(layer "In11.Cu")
		(net "P5E_CPU1_P3_TX_DP<8>")
	)
	(segment
		(start 120.254522 -283.48559)
		(end 120.25503 -283.48559)
		(width 0.1143)
		(layer "In11.Cu")
		(net "P5E_CPU1_P3_TX_DP<8>")
	)
	(segment
		(start 120.753378 -280.060654)
		(end 120.708674 -280.086562)
		(width 0.1143)
		(layer "In11.Cu")
		(net "P5E_CPU1_P3_TX_DP<8>")
	)
	(segment
		(start 120.427496 -280.57475)
		(end 120.427496 -280.58618)
		(width 0.1143)
		(layer "In11.Cu")
		(net "P5E_CPU1_P3_TX_DP<8>")
	)
	(segment
		(start 120.251728 -293.84879)
		(end 120.250712 -293.849298)
		(width 0.1143)
		(layer "In11.Cu")
		(net "P5E_CPU1_P3_TX_DP<8>")
	)
	(segment
		(start 120.255284 -285.747206)
		(end 120.254776 -285.747206)
		(width 0.1143)
		(layer "In11.Cu")
		(net "P5E_CPU1_P3_TX_DP<8>")
	)
	(segment
		(start 120.25249 -283.48432)
		(end 120.254522 -283.48559)
		(width 0.1143)
		(layer "In11.Cu")
		(net "P5E_CPU1_P3_TX_DP<8>")
	)
	(segment
		(start 120.283478 -287.350454)
		(end 120.215152 -287.390078)
		(width 0.1143)
		(layer "In11.Cu")
		(net "P5E_CPU1_P3_TX_DP<8>")
	)
	(segment
		(start 120.721882 -279.433782)
		(end 120.753378 -279.452324)
		(width 0.1143)
		(layer "In11.Cu")
		(net "P5E_CPU1_P3_TX_DP<8>")
	)
	(segment
		(start 120.25249 -290.608512)
		(end 120.251728 -290.608766)
		(width 0.1143)
		(layer "In11.Cu")
		(net "P5E_CPU1_P3_TX_DP<8>")
	)
	(segment
		(start 120.21947 -283.465016)
		(end 120.220232 -283.465524)
		(width 0.1143)
		(layer "In11.Cu")
		(net "P5E_CPU1_P3_TX_DP<8>")
	)
	(segment
		(start 120.287288 -287.34766)
		(end 120.283478 -287.350454)
		(width 0.1143)
		(layer "In11.Cu")
		(net "P5E_CPU1_P3_TX_DP<8>")
	)
	(segment
		(start 120.452134 -278.953722)
		(end 120.452134 -278.966168)
		(width 0.1143)
		(layer "In11.Cu")
		(net "P5E_CPU1_P3_TX_DP<8>")
	)
	(segment
		(start 120.940322 -296.612564)
		(end 120.940322 -296.659808)
		(width 0.14224)
		(layer "In11.Cu")
		(net "P5E_CPU1_P3_TX_DP<8>")
	)
	(segment
		(start 120.940322 -296.584116)
		(end 120.940322 -296.612564)
		(width 0.1143)
		(layer "In11.Cu")
		(net "P5E_CPU1_P3_TX_DP<8>")
	)
	(segment
		(start 141.04747 -340.718394)
		(end 141.04747 -345.35618)
		(width 0.14224)
		(layer "In11.Cu")
		(net "P5E_CPU1_P3_TX_DP<8>")
	)
	(segment
		(start 120.439434 -295.141904)
		(end 120.439434 -295.146222)
		(width 0.1143)
		(layer "In11.Cu")
		(net "P5E_CPU1_P3_TX_DP<8>")
	)
	(segment
		(start 120.94083 -297.122596)
		(end 121.884948 -300.235366)
		(width 0.14224)
		(layer "In11.Cu")
		(net "P5E_CPU1_P3_TX_DP<8>")
	)
	(segment
		(start 120.69826 -295.619932)
		(end 120.698768 -295.620186)
		(width 0.1143)
		(layer "In11.Cu")
		(net "P5E_CPU1_P3_TX_DP<8>")
	)
	(segment
		(start 120.251728 -285.103824)
		(end 120.25249 -285.104332)
		(width 0.1143)
		(layer "In11.Cu")
		(net "P5E_CPU1_P3_TX_DP<8>")
	)
	(segment
		(start 128.08458 -365.610902)
		(end 126.121668 -366.42421)
		(width 0.14224)
		(layer "In11.Cu")
		(net "P5E_CPU1_P3_TX_DP<8>")
	)
	(segment
		(start 120.250712 -289.963098)
		(end 120.251728 -289.963606)
		(width 0.1143)
		(layer "In11.Cu")
		(net "P5E_CPU1_P3_TX_DP<8>")
	)
	(segment
		(start 120.94083 -296.660316)
		(end 120.94083 -297.122596)
		(width 0.14224)
		(layer "In11.Cu")
		(net "P5E_CPU1_P3_TX_DP<8>")
	)
	(segment
		(start 120.251728 -292.228778)
		(end 120.250712 -292.229286)
		(width 0.1143)
		(layer "In11.Cu")
		(net "P5E_CPU1_P3_TX_DP<8>")
	)
	(segment
		(start 120.212612 -283.460952)
		(end 120.21947 -283.465016)
		(width 0.1143)
		(layer "In11.Cu")
		(net "P5E_CPU1_P3_TX_DP<8>")
	)
	(segment
		(start 120.212612 -288.320988)
		(end 120.218708 -288.324544)
		(width 0.1143)
		(layer "In11.Cu")
		(net "P5E_CPU1_P3_TX_DP<8>")
	)
	(segment
		(start 120.25249 -278.624284)
		(end 120.25249 -278.62403)
		(width 0.1143)
		(layer "In11.Cu")
		(net "P5E_CPU1_P3_TX_DP<8>")
	)
	(segment
		(start 120.24614 -292.23208)
		(end 120.212612 -292.251638)
		(width 0.1143)
		(layer "In11.Cu")
		(net "P5E_CPU1_P3_TX_DP<8>")
	)
	(segment
		(start 120.250712 -281.863292)
		(end 120.251728 -281.8638)
		(width 0.1143)
		(layer "In11.Cu")
		(net "P5E_CPU1_P3_TX_DP<8>")
	)
	(segment
		(start 120.251728 -290.608766)
		(end 120.250712 -290.609274)
		(width 0.1143)
		(layer "In11.Cu")
		(net "P5E_CPU1_P3_TX_DP<8>")
	)
	(segment
		(start 120.212612 -291.560758)
		(end 120.250712 -291.58311)
		(width 0.1143)
		(layer "In11.Cu")
		(net "P5E_CPU1_P3_TX_DP<8>")
	)
	(segment
		(start 120.254268 -294.824912)
		(end 120.284494 -294.842946)
		(width 0.1143)
		(layer "In11.Cu")
		(net "P5E_CPU1_P3_TX_DP<8>")
	)
	(segment
		(start 120.250712 -291.58311)
		(end 120.251728 -291.583618)
		(width 0.1143)
		(layer "In11.Cu")
		(net "P5E_CPU1_P3_TX_DP<8>")
	)
	(segment
		(start 120.986042 -296.335704)
		(end 120.986042 -296.538396)
		(width 0.1143)
		(layer "In11.Cu")
		(net "P5E_CPU1_P3_TX_DP<8>")
	)
	(segment
		(start 120.251728 -291.583618)
		(end 120.25249 -291.584126)
		(width 0.1143)
		(layer "In11.Cu")
		(net "P5E_CPU1_P3_TX_DP<8>")
	)
	(segment
		(start 120.283478 -292.21049)
		(end 120.25249 -292.22827)
		(width 0.1143)
		(layer "In11.Cu")
		(net "P5E_CPU1_P3_TX_DP<8>")
	)
	(segment
		(start 120.25249 -291.584126)
		(end 120.283478 -291.601906)
		(width 0.1143)
		(layer "In11.Cu")
		(net "P5E_CPU1_P3_TX_DP<8>")
	)
	(segment
		(start 120.254776 -288.986976)
		(end 120.25249 -288.9885)
		(width 0.1143)
		(layer "In11.Cu")
		(net "P5E_CPU1_P3_TX_DP<8>")
	)
	(segment
		(start 120.25249 -282.508706)
		(end 120.251728 -282.50896)
		(width 0.1143)
		(layer "In11.Cu")
		(net "P5E_CPU1_P3_TX_DP<8>")
	)
	(segment
		(start 120.932702 -296.124376)
		(end 120.959626 -296.193972)
		(width 0.1143)
		(layer "In11.Cu")
		(net "P5E_CPU1_P3_TX_DP<8>")
	)
	(segment
		(start 120.251728 -281.8638)
		(end 120.25249 -281.864308)
		(width 0.1143)
		(layer "In11.Cu")
		(net "P5E_CPU1_P3_TX_DP<8>")
	)
	(segment
		(start 120.255284 -282.507182)
		(end 120.254776 -282.507182)
		(width 0.1143)
		(layer "In11.Cu")
		(net "P5E_CPU1_P3_TX_DP<8>")
	)
	(segment
		(start 120.986042 -296.538396)
		(end 120.940322 -296.584116)
		(width 0.1143)
		(layer "In11.Cu")
		(net "P5E_CPU1_P3_TX_DP<8>")
	)
	(segment
		(start 120.250712 -285.749492)
		(end 120.212612 -285.771844)
		(width 0.1143)
		(layer "In11.Cu")
		(net "P5E_CPU1_P3_TX_DP<8>")
	)
	(arc
		(start 120.284494 -294.842946)
		(mid 120.398377 -294.97356)
		(end 120.439434 -295.141904)
		(width 0.1143)
		(layer "In11.Cu")
		(net "P5E_CPU1_P3_TX_DP<8>")
	)
	(arc
		(start 119.979186 -278.242014)
		(mid 120.060619 -278.444412)
		(end 120.212612 -278.600916)
		(width 0.1143)
		(layer "In11.Cu")
		(net "P5E_CPU1_P3_TX_DP<8>")
	)
	(arc
		(start 120.212612 -280.911808)
		(mid 119.969285 -281.376374)
		(end 120.212612 -281.84094)
		(width 0.1143)
		(layer "In11.Cu")
		(net "P5E_CPU1_P3_TX_DP<8>")
	)
	(arc
		(start 120.439434 -295.146222)
		(mid 120.503949 -295.408441)
		(end 120.682766 -295.610788)
		(width 0.1143)
		(layer "In11.Cu")
		(net "P5E_CPU1_P3_TX_DP<8>")
	)
	(arc
		(start 119.975376 -278.219154)
		(mid 119.977164 -278.230603)
		(end 119.979186 -278.242014)
		(width 0.1143)
		(layer "In11.Cu")
		(net "P5E_CPU1_P3_TX_DP<8>")
	)
	(arc
		(start 120.212612 -284.151832)
		(mid 119.969285 -284.616398)
		(end 120.212612 -285.080964)
		(width 0.1143)
		(layer "In11.Cu")
		(net "P5E_CPU1_P3_TX_DP<8>")
	)
	(arc
		(start 120.212612 -285.771844)
		(mid 119.969285 -286.23641)
		(end 120.212612 -286.700976)
		(width 0.1143)
		(layer "In11.Cu")
		(net "P5E_CPU1_P3_TX_DP<8>")
	)
	(arc
		(start 137.468102 -355.75367)
		(mid 136.100672 -358.31209)
		(end 134.260336 -360.554524)
		(width 0.14224)
		(layer "In11.Cu")
		(net "P5E_CPU1_P3_TX_DP<8>")
	)
	(arc
		(start 120.212612 -282.53182)
		(mid 119.969285 -282.996386)
		(end 120.212612 -283.460952)
		(width 0.1143)
		(layer "In11.Cu")
		(net "P5E_CPU1_P3_TX_DP<8>")
	)
	(arc
		(start 120.215152 -287.390078)
		(mid 120.0345 -287.592823)
		(end 119.96928 -287.856422)
		(width 0.1143)
		(layer "In11.Cu")
		(net "P5E_CPU1_P3_TX_DP<8>")
	)
	(arc
		(start 120.25503 -285.105602)
		(mid 120.439763 -285.426294)
		(end 120.255284 -285.747206)
		(width 0.1143)
		(layer "In11.Cu")
		(net "P5E_CPU1_P3_TX_DP<8>")
	)
	(arc
		(start 131.45897 -363.35589)
		(mid 129.882816 -364.649557)
		(end 128.08458 -365.610902)
		(width 0.14224)
		(layer "In11.Cu")
		(net "P5E_CPU1_P3_TX_DP<8>")
	)
	(arc
		(start 120.25503 -289.965384)
		(mid 120.439763 -290.286076)
		(end 120.255284 -290.606988)
		(width 0.1143)
		(layer "In11.Cu")
		(net "P5E_CPU1_P3_TX_DP<8>")
	)
	(arc
		(start 141.04747 -345.35618)
		(mid 140.877854 -347.077853)
		(end 140.37564 -348.733364)
		(width 0.14224)
		(layer "In11.Cu")
		(net "P5E_CPU1_P3_TX_DP<8>")
	)
	(arc
		(start 120.889014 -279.634696)
		(mid 120.891635 -279.870105)
		(end 120.753378 -280.060654)
		(width 0.1143)
		(layer "In11.Cu")
		(net "P5E_CPU1_P3_TX_DP<8>")
	)
	(arc
		(start 124.378212 -367.890044)
		(mid 124.113362 -368.286514)
		(end 124.020326 -368.754152)
		(width 0.14224)
		(layer "In11.Cu")
		(net "P5E_CPU1_P3_TX_DP<8>")
	)
	(arc
		(start 126.121668 -366.42421)
		(mid 125.675788 -366.662522)
		(end 125.284992 -366.983264)
		(width 0.14224)
		(layer "In11.Cu")
		(net "P5E_CPU1_P3_TX_DP<8>")
	)
	(arc
		(start 120.212612 -292.251638)
		(mid 119.969285 -292.716204)
		(end 120.212612 -293.18077)
		(width 0.1143)
		(layer "In11.Cu")
		(net "P5E_CPU1_P3_TX_DP<8>")
	)
	(arc
		(start 120.288558 -291.605462)
		(mid 120.442656 -291.906198)
		(end 120.288558 -292.206934)
		(width 0.1143)
		(layer "In11.Cu")
		(net "P5E_CPU1_P3_TX_DP<8>")
	)
	(arc
		(start 120.91162 -296.019474)
		(mid 120.917697 -296.072824)
		(end 120.932702 -296.124376)
		(width 0.1143)
		(layer "In11.Cu")
		(net "P5E_CPU1_P3_TX_DP<8>")
	)
	(arc
		(start 120.708674 -280.086562)
		(mid 120.502815 -280.293063)
		(end 120.427496 -280.57475)
		(width 0.1143)
		(layer "In11.Cu")
		(net "P5E_CPU1_P3_TX_DP<8>")
	)
	(arc
		(start 120.959626 -296.193972)
		(mid 120.979375 -296.26362)
		(end 120.986042 -296.335704)
		(width 0.1143)
		(layer "In11.Cu")
		(net "P5E_CPU1_P3_TX_DP<8>")
	)
	(arc
		(start 120.267222 -278.632412)
		(mid 120.40261 -278.768361)
		(end 120.452134 -278.953722)
		(width 0.1143)
		(layer "In11.Cu")
		(net "P5E_CPU1_P3_TX_DP<8>")
	)
	(arc
		(start 120.212612 -290.631626)
		(mid 119.969285 -291.096192)
		(end 120.212612 -291.560758)
		(width 0.1143)
		(layer "In11.Cu")
		(net "P5E_CPU1_P3_TX_DP<8>")
	)
	(arc
		(start 120.25503 -288.345372)
		(mid 120.439763 -288.666064)
		(end 120.255284 -288.986976)
		(width 0.1143)
		(layer "In11.Cu")
		(net "P5E_CPU1_P3_TX_DP<8>")
	)
	(arc
		(start 120.212612 -289.011614)
		(mid 119.969285 -289.47618)
		(end 120.212612 -289.940746)
		(width 0.1143)
		(layer "In11.Cu")
		(net "P5E_CPU1_P3_TX_DP<8>")
	)
	(arc
		(start 120.25503 -293.205408)
		(mid 120.439763 -293.5261)
		(end 120.255284 -293.847012)
		(width 0.1143)
		(layer "In11.Cu")
		(net "P5E_CPU1_P3_TX_DP<8>")
	)
	(arc
		(start 120.753632 -295.652444)
		(mid 120.865439 -295.780498)
		(end 120.90908 -295.944798)
		(width 0.1143)
		(layer "In11.Cu")
		(net "P5E_CPU1_P3_TX_DP<8>")
	)
	(arc
		(start 120.753378 -279.452324)
		(mid 120.835359 -279.532974)
		(end 120.889014 -279.634696)
		(width 0.1143)
		(layer "In11.Cu")
		(net "P5E_CPU1_P3_TX_DP<8>")
	)
	(arc
		(start 120.427496 -280.58618)
		(mid 120.380585 -280.760809)
		(end 120.25249 -280.88844)
		(width 0.1143)
		(layer "In11.Cu")
		(net "P5E_CPU1_P3_TX_DP<8>")
	)
	(arc
		(start 120.452134 -278.966168)
		(mid 120.524399 -279.236097)
		(end 120.721882 -279.433782)
		(width 0.1143)
		(layer "In11.Cu")
		(net "P5E_CPU1_P3_TX_DP<8>")
	)
	(arc
		(start 120.25503 -281.865578)
		(mid 120.439763 -282.18627)
		(end 120.255284 -282.507182)
		(width 0.1143)
		(layer "In11.Cu")
		(net "P5E_CPU1_P3_TX_DP<8>")
	)
	(arc
		(start 120.212612 -293.87165)
		(mid 119.969285 -294.336216)
		(end 120.212612 -294.800782)
		(width 0.1143)
		(layer "In11.Cu")
		(net "P5E_CPU1_P3_TX_DP<8>")
	)
	(arc
		(start 120.439434 -287.050734)
		(mid 120.399179 -287.217547)
		(end 120.287288 -287.34766)
		(width 0.1143)
		(layer "In11.Cu")
		(net "P5E_CPU1_P3_TX_DP<8>")
	)
	(arc
		(start 120.285256 -286.743394)
		(mid 120.398663 -286.876283)
		(end 120.439434 -287.046162)
		(width 0.1143)
		(layer "In11.Cu")
		(net "P5E_CPU1_P3_TX_DP<8>")
	)
	(arc
		(start 120.25503 -283.48559)
		(mid 120.439763 -283.806282)
		(end 120.255284 -284.127194)
		(width 0.1143)
		(layer "In11.Cu")
		(net "P5E_CPU1_P3_TX_DP<8>")
	)
	(arc
		(start 119.96928 -287.856422)
		(mid 120.033795 -288.118641)
		(end 120.212612 -288.320988)
		(width 0.1143)
		(layer "In11.Cu")
		(net "P5E_CPU1_P3_TX_DP<8>")
	)
	(segment
		(start 122.298206 -374.23344)
		(end 122.298206 -374.93702)
		(width 0.12954)
		(layer "F.Cu")
		(net "P5E_CPU1_P3_TX_DP<7>")
	)
	(segment
		(start 119.127778 -274.630388)
		(end 119.59463 -274.896326)
		(width 0.12954)
		(layer "F.Cu")
		(net "P5E_CPU1_P3_TX_DP<7>")
	)
	(segment
		(start 122.027696 -373.96293)
		(end 122.298206 -374.23344)
		(width 0.12954)
		(layer "F.Cu")
		(net "P5E_CPU1_P3_TX_DP<7>")
	)
	(segment
		(start 122.298206 -374.93702)
		(end 122.002296 -375.23293)
		(width 0.12954)
		(layer "F.Cu")
		(net "P5E_CPU1_P3_TX_DP<7>")
	)
	(segment
		(start 119.311674 -293.20363)
		(end 119.312436 -293.204138)
		(width 0.1143)
		(layer "In11.Cu")
		(net "P5E_CPU1_P3_TX_DP<7>")
	)
	(segment
		(start 119.297704 -278.615902)
		(end 119.29872 -278.61641)
		(width 0.1143)
		(layer "In11.Cu")
		(net "P5E_CPU1_P3_TX_DP<7>")
	)
	(segment
		(start 119.343424 -288.970466)
		(end 119.315992 -288.986214)
		(width 0.1143)
		(layer "In11.Cu")
		(net "P5E_CPU1_P3_TX_DP<7>")
	)
	(segment
		(start 118.810278 -277.795482)
		(end 118.841774 -277.81377)
		(width 0.1143)
		(layer "In11.Cu")
		(net "P5E_CPU1_P3_TX_DP<7>")
	)
	(segment
		(start 119.812308 -275.201126)
		(end 119.742712 -275.241766)
		(width 0.1143)
		(layer "In11.Cu")
		(net "P5E_CPU1_P3_TX_DP<7>")
	)
	(segment
		(start 119.311674 -293.84879)
		(end 119.294148 -293.85895)
		(width 0.1143)
		(layer "In11.Cu")
		(net "P5E_CPU1_P3_TX_DP<7>")
	)
	(segment
		(start 119.314214 -288.98723)
		(end 119.313452 -288.987738)
		(width 0.1143)
		(layer "In11.Cu")
		(net "P5E_CPU1_P3_TX_DP<7>")
	)
	(segment
		(start 119.343424 -293.830502)
		(end 119.311674 -293.84879)
		(width 0.1143)
		(layer "In11.Cu")
		(net "P5E_CPU1_P3_TX_DP<7>")
	)
	(segment
		(start 119.30126 -278.617934)
		(end 119.3038 -278.619204)
		(width 0.1143)
		(layer "In11.Cu")
		(net "P5E_CPU1_P3_TX_DP<7>")
	)
	(segment
		(start 119.299482 -278.616918)
		(end 119.300498 -278.617426)
		(width 0.1143)
		(layer "In11.Cu")
		(net "P5E_CPU1_P3_TX_DP<7>")
	)
	(segment
		(start 125.144276 -365.67491)
		(end 124.04344 -366.263174)
		(width 0.14224)
		(layer "In11.Cu")
		(net "P5E_CPU1_P3_TX_DP<7>")
	)
	(segment
		(start 119.59463 -274.896326)
		(end 119.892572 -274.896326)
		(width 0.1143)
		(layer "In11.Cu")
		(net "P5E_CPU1_P3_TX_DP<7>")
	)
	(segment
		(start 119.781828 -279.433782)
		(end 119.812308 -279.451562)
		(width 0.1143)
		(layer "In11.Cu")
		(net "P5E_CPU1_P3_TX_DP<7>")
	)
	(segment
		(start 135.013192 -319.686432)
		(end 136.743948 -323.863208)
		(width 0.14224)
		(layer "In11.Cu")
		(net "P5E_CPU1_P3_TX_DP<7>")
	)
	(segment
		(start 119.306594 -278.620728)
		(end 119.307356 -278.621236)
		(width 0.1143)
		(layer "In11.Cu")
		(net "P5E_CPU1_P3_TX_DP<7>")
	)
	(segment
		(start 119.273574 -278.601678)
		(end 119.296688 -278.61514)
		(width 0.1143)
		(layer "In11.Cu")
		(net "P5E_CPU1_P3_TX_DP<7>")
	)
	(segment
		(start 119.296688 -278.61514)
		(end 119.296434 -278.61514)
		(width 0.1143)
		(layer "In11.Cu")
		(net "P5E_CPU1_P3_TX_DP<7>")
	)
	(segment
		(start 118.842536 -277.814278)
		(end 118.84533 -277.815548)
		(width 0.1143)
		(layer "In11.Cu")
		(net "P5E_CPU1_P3_TX_DP<7>")
	)
	(segment
		(start 119.309896 -285.749746)
		(end 119.309134 -285.750254)
		(width 0.1143)
		(layer "In11.Cu")
		(net "P5E_CPU1_P3_TX_DP<7>")
	)
	(segment
		(start 119.969534 -296.538396)
		(end 119.923814 -296.584116)
		(width 0.1143)
		(layer "In11.Cu")
		(net "P5E_CPU1_P3_TX_DP<7>")
	)
	(segment
		(start 119.923814 -296.584116)
		(end 119.923814 -296.612564)
		(width 0.1143)
		(layer "In11.Cu")
		(net "P5E_CPU1_P3_TX_DP<7>")
	)
	(segment
		(start 119.311928 -278.623776)
		(end 119.313452 -278.624792)
		(width 0.1143)
		(layer "In11.Cu")
		(net "P5E_CPU1_P3_TX_DP<7>")
	)
	(segment
		(start 119.313452 -288.987738)
		(end 119.312436 -288.988246)
		(width 0.1143)
		(layer "In11.Cu")
		(net "P5E_CPU1_P3_TX_DP<7>")
	)
	(segment
		(start 119.307356 -278.621236)
		(end 119.308372 -278.621744)
		(width 0.1143)
		(layer "In11.Cu")
		(net "P5E_CPU1_P3_TX_DP<7>")
	)
	(segment
		(start 119.892572 -274.896326)
		(end 119.962422 -274.966176)
		(width 0.1143)
		(layer "In11.Cu")
		(net "P5E_CPU1_P3_TX_DP<7>")
	)
	(segment
		(start 120.946164 -300.52264)
		(end 123.255532 -303.978818)
		(width 0.14224)
		(layer "In11.Cu")
		(net "P5E_CPU1_P3_TX_DP<7>")
	)
	(segment
		(start 136.743948 -323.863208)
		(end 140.114528 -340.80958)
		(width 0.14224)
		(layer "In11.Cu")
		(net "P5E_CPU1_P3_TX_DP<7>")
	)
	(segment
		(start 119.308372 -278.621744)
		(end 119.309134 -278.622252)
		(width 0.1143)
		(layer "In11.Cu")
		(net "P5E_CPU1_P3_TX_DP<7>")
	)
	(segment
		(start 119.31142 -293.20363)
		(end 119.311674 -293.20363)
		(width 0.1143)
		(layer "In11.Cu")
		(net "P5E_CPU1_P3_TX_DP<7>")
	)
	(segment
		(start 119.311674 -292.228778)
		(end 119.31142 -292.229032)
		(width 0.1143)
		(layer "In11.Cu")
		(net "P5E_CPU1_P3_TX_DP<7>")
	)
	(segment
		(start 119.312436 -289.964114)
		(end 119.313706 -289.964876)
		(width 0.1143)
		(layer "In11.Cu")
		(net "P5E_CPU1_P3_TX_DP<7>")
	)
	(segment
		(start 119.969534 -295.992804)
		(end 119.969534 -296.538396)
		(width 0.1143)
		(layer "In11.Cu")
		(net "P5E_CPU1_P3_TX_DP<7>")
	)
	(segment
		(start 119.29872 -278.61641)
		(end 119.299482 -278.616918)
		(width 0.1143)
		(layer "In11.Cu")
		(net "P5E_CPU1_P3_TX_DP<7>")
	)
	(segment
		(start 119.312436 -293.204138)
		(end 119.313452 -293.204646)
		(width 0.1143)
		(layer "In11.Cu")
		(net "P5E_CPU1_P3_TX_DP<7>")
	)
	(segment
		(start 119.313706 -289.964876)
		(end 119.343424 -289.981894)
		(width 0.1143)
		(layer "In11.Cu")
		(net "P5E_CPU1_P3_TX_DP<7>")
	)
	(segment
		(start 119.312436 -276.029674)
		(end 119.312182 -276.029928)
		(width 0.1143)
		(layer "In11.Cu")
		(net "P5E_CPU1_P3_TX_DP<7>")
	)
	(segment
		(start 119.309134 -278.622252)
		(end 119.311928 -278.623776)
		(width 0.1143)
		(layer "In11.Cu")
		(net "P5E_CPU1_P3_TX_DP<7>")
	)
	(segment
		(start 119.311928 -282.506674)
		(end 119.310912 -282.507182)
		(width 0.1143)
		(layer "In11.Cu")
		(net "P5E_CPU1_P3_TX_DP<7>")
	)
	(segment
		(start 119.313452 -293.204646)
		(end 119.314214 -293.205154)
		(width 0.1143)
		(layer "In11.Cu")
		(net "P5E_CPU1_P3_TX_DP<7>")
	)
	(segment
		(start 119.311674 -288.988754)
		(end 119.30888 -288.990278)
		(width 0.1143)
		(layer "In11.Cu")
		(net "P5E_CPU1_P3_TX_DP<7>")
	)
	(segment
		(start 119.311674 -289.963606)
		(end 119.312436 -289.964114)
		(width 0.1143)
		(layer "In11.Cu")
		(net "P5E_CPU1_P3_TX_DP<7>")
	)
	(segment
		(start 119.312436 -291.584126)
		(end 119.313706 -291.584888)
		(width 0.1143)
		(layer "In11.Cu")
		(net "P5E_CPU1_P3_TX_DP<7>")
	)
	(segment
		(start 119.314214 -293.205154)
		(end 119.31523 -293.205662)
		(width 0.1143)
		(layer "In11.Cu")
		(net "P5E_CPU1_P3_TX_DP<7>")
	)
	(segment
		(start 119.315484 -287.36417)
		(end 119.310658 -287.366964)
		(width 0.1143)
		(layer "In11.Cu")
		(net "P5E_CPU1_P3_TX_DP<7>")
	)
	(segment
		(start 119.294148 -294.813482)
		(end 119.343424 -294.84193)
		(width 0.1143)
		(layer "In11.Cu")
		(net "P5E_CPU1_P3_TX_DP<7>")
	)
	(segment
		(start 119.313706 -291.584888)
		(end 119.343424 -291.601906)
		(width 0.1143)
		(layer "In11.Cu")
		(net "P5E_CPU1_P3_TX_DP<7>")
	)
	(segment
		(start 119.275352 -281.842718)
		(end 119.343424 -281.882088)
		(width 0.1143)
		(layer "In11.Cu")
		(net "P5E_CPU1_P3_TX_DP<7>")
	)
	(segment
		(start 119.275352 -283.46273)
		(end 119.343424 -283.5021)
		(width 0.1143)
		(layer "In11.Cu")
		(net "P5E_CPU1_P3_TX_DP<7>")
	)
	(segment
		(start 123.255532 -303.978818)
		(end 130.048508 -312.255916)
		(width 0.14224)
		(layer "In11.Cu")
		(net "P5E_CPU1_P3_TX_DP<7>")
	)
	(segment
		(start 119.311674 -280.888948)
		(end 119.310912 -280.889456)
		(width 0.1143)
		(layer "In11.Cu")
		(net "P5E_CPU1_P3_TX_DP<7>")
	)
	(segment
		(start 119.315992 -293.20617)
		(end 119.317008 -293.206678)
		(width 0.1143)
		(layer "In11.Cu")
		(net "P5E_CPU1_P3_TX_DP<7>")
	)
	(segment
		(start 119.304562 -278.619712)
		(end 119.306594 -278.620728)
		(width 0.1143)
		(layer "In11.Cu")
		(net "P5E_CPU1_P3_TX_DP<7>")
	)
	(segment
		(start 119.343424 -292.21049)
		(end 119.311674 -292.228778)
		(width 0.1143)
		(layer "In11.Cu")
		(net "P5E_CPU1_P3_TX_DP<7>")
	)
	(segment
		(start 119.315992 -288.986214)
		(end 119.31523 -288.986722)
		(width 0.1143)
		(layer "In11.Cu")
		(net "P5E_CPU1_P3_TX_DP<7>")
	)
	(segment
		(start 119.812308 -280.061162)
		(end 119.742712 -280.101802)
		(width 0.1143)
		(layer "In11.Cu")
		(net "P5E_CPU1_P3_TX_DP<7>")
	)
	(segment
		(start 119.311928 -284.126686)
		(end 119.310912 -284.127194)
		(width 0.1143)
		(layer "In11.Cu")
		(net "P5E_CPU1_P3_TX_DP<7>")
	)
	(segment
		(start 119.309134 -285.750254)
		(end 119.309388 -285.750254)
		(width 0.1143)
		(layer "In11.Cu")
		(net "P5E_CPU1_P3_TX_DP<7>")
	)
	(segment
		(start 130.048508 -312.255916)
		(end 135.013192 -319.686432)
		(width 0.14224)
		(layer "In11.Cu")
		(net "P5E_CPU1_P3_TX_DP<7>")
	)
	(segment
		(start 119.74195 -295.61028)
		(end 119.75211 -295.616376)
		(width 0.1143)
		(layer "In11.Cu")
		(net "P5E_CPU1_P3_TX_DP<7>")
	)
	(segment
		(start 119.314214 -278.625046)
		(end 119.314976 -278.625554)
		(width 0.1143)
		(layer "In11.Cu")
		(net "P5E_CPU1_P3_TX_DP<7>")
	)
	(segment
		(start 119.312182 -276.029928)
		(end 119.308372 -276.032214)
		(width 0.1143)
		(layer "In11.Cu")
		(net "P5E_CPU1_P3_TX_DP<7>")
	)
	(segment
		(start 118.802658 -277.79091)
		(end 118.809516 -277.794974)
		(width 0.1143)
		(layer "In11.Cu")
		(net "P5E_CPU1_P3_TX_DP<7>")
	)
	(segment
		(start 119.275098 -285.082488)
		(end 119.334026 -285.116778)
		(width 0.1143)
		(layer "In11.Cu")
		(net "P5E_CPU1_P3_TX_DP<7>")
	)
	(segment
		(start 119.32031 -293.208456)
		(end 119.343424 -293.221918)
		(width 0.1143)
		(layer "In11.Cu")
		(net "P5E_CPU1_P3_TX_DP<7>")
	)
	(segment
		(start 127.453644 -364.709964)
		(end 125.283468 -365.609124)
		(width 0.14224)
		(layer "In11.Cu")
		(net "P5E_CPU1_P3_TX_DP<7>")
	)
	(segment
		(start 140.114528 -340.80958)
		(end 140.114528 -345.101418)
		(width 0.14224)
		(layer "In11.Cu")
		(net "P5E_CPU1_P3_TX_DP<7>")
	)
	(segment
		(start 119.311674 -291.583618)
		(end 119.312436 -291.584126)
		(width 0.1143)
		(layer "In11.Cu")
		(net "P5E_CPU1_P3_TX_DP<7>")
	)
	(segment
		(start 118.873524 -276.82063)
		(end 118.802658 -276.861778)
		(width 0.1143)
		(layer "In11.Cu")
		(net "P5E_CPU1_P3_TX_DP<7>")
	)
	(segment
		(start 119.309388 -286.722566)
		(end 119.311674 -286.723836)
		(width 0.1143)
		(layer "In11.Cu")
		(net "P5E_CPU1_P3_TX_DP<7>")
	)
	(segment
		(start 119.923814 -296.612564)
		(end 119.923814 -297.151552)
		(width 0.14224)
		(layer "In11.Cu")
		(net "P5E_CPU1_P3_TX_DP<7>")
	)
	(segment
		(start 119.317008 -293.206678)
		(end 119.31777 -293.207186)
		(width 0.1143)
		(layer "In11.Cu")
		(net "P5E_CPU1_P3_TX_DP<7>")
	)
	(segment
		(start 119.311674 -286.723836)
		(end 119.345202 -286.743394)
		(width 0.1143)
		(layer "In11.Cu")
		(net "P5E_CPU1_P3_TX_DP<7>")
	)
	(segment
		(start 119.3038 -278.619204)
		(end 119.304562 -278.619712)
		(width 0.1143)
		(layer "In11.Cu")
		(net "P5E_CPU1_P3_TX_DP<7>")
	)
	(segment
		(start 118.841774 -277.81377)
		(end 118.842536 -277.814278)
		(width 0.1143)
		(layer "In11.Cu")
		(net "P5E_CPU1_P3_TX_DP<7>")
	)
	(segment
		(start 139.55141 -347.931486)
		(end 136.44626 -355.428804)
		(width 0.14224)
		(layer "In11.Cu")
		(net "P5E_CPU1_P3_TX_DP<7>")
	)
	(segment
		(start 119.315992 -278.626062)
		(end 119.343424 -278.642064)
		(width 0.1143)
		(layer "In11.Cu")
		(net "P5E_CPU1_P3_TX_DP<7>")
	)
	(segment
		(start 119.49938 -295.146222)
		(end 119.499634 -295.146222)
		(width 0.1143)
		(layer "In11.Cu")
		(net "P5E_CPU1_P3_TX_DP<7>")
	)
	(segment
		(start 119.313452 -280.887932)
		(end 119.311674 -280.888948)
		(width 0.1143)
		(layer "In11.Cu")
		(net "P5E_CPU1_P3_TX_DP<7>")
	)
	(segment
		(start 119.31523 -293.205662)
		(end 119.315992 -293.20617)
		(width 0.1143)
		(layer "In11.Cu")
		(net "P5E_CPU1_P3_TX_DP<7>")
	)
	(segment
		(start 119.333264 -285.736284)
		(end 119.309896 -285.749746)
		(width 0.1143)
		(layer "In11.Cu")
		(net "P5E_CPU1_P3_TX_DP<7>")
	)
	(segment
		(start 119.314976 -278.625554)
		(end 119.315992 -278.626062)
		(width 0.1143)
		(layer "In11.Cu")
		(net "P5E_CPU1_P3_TX_DP<7>")
	)
	(segment
		(start 119.343424 -290.590478)
		(end 119.311674 -290.608766)
		(width 0.1143)
		(layer "In11.Cu")
		(net "P5E_CPU1_P3_TX_DP<7>")
	)
	(segment
		(start 119.923814 -297.151552)
		(end 120.946164 -300.52264)
		(width 0.14224)
		(layer "In11.Cu")
		(net "P5E_CPU1_P3_TX_DP<7>")
	)
	(segment
		(start 119.296434 -278.61514)
		(end 119.297704 -278.615902)
		(width 0.1143)
		(layer "In11.Cu")
		(net "P5E_CPU1_P3_TX_DP<7>")
	)
	(segment
		(start 119.313452 -278.624792)
		(end 119.314214 -278.625046)
		(width 0.1143)
		(layer "In11.Cu")
		(net "P5E_CPU1_P3_TX_DP<7>")
	)
	(segment
		(start 119.31777 -293.207186)
		(end 119.32031 -293.208456)
		(width 0.1143)
		(layer "In11.Cu")
		(net "P5E_CPU1_P3_TX_DP<7>")
	)
	(segment
		(start 119.30888 -289.962082)
		(end 119.311674 -289.963606)
		(width 0.1143)
		(layer "In11.Cu")
		(net "P5E_CPU1_P3_TX_DP<7>")
	)
	(segment
		(start 119.312436 -288.988246)
		(end 119.311674 -288.988754)
		(width 0.1143)
		(layer "In11.Cu")
		(net "P5E_CPU1_P3_TX_DP<7>")
	)
	(segment
		(start 119.742712 -279.410922)
		(end 119.781828 -279.433782)
		(width 0.1143)
		(layer "In11.Cu")
		(net "P5E_CPU1_P3_TX_DP<7>")
	)
	(segment
		(start 119.275352 -288.322766)
		(end 119.345202 -288.363406)
		(width 0.1143)
		(layer "In11.Cu")
		(net "P5E_CPU1_P3_TX_DP<7>")
	)
	(segment
		(start 119.300498 -278.617426)
		(end 119.30126 -278.617934)
		(width 0.1143)
		(layer "In11.Cu")
		(net "P5E_CPU1_P3_TX_DP<7>")
	)
	(segment
		(start 122.318526 -369.14074)
		(end 122.318526 -373.605298)
		(width 0.14224)
		(layer "In11.Cu")
		(net "P5E_CPU1_P3_TX_DP<7>")
	)
	(segment
		(start 118.84533 -277.815548)
		(end 118.845838 -277.815802)
		(width 0.1143)
		(layer "In11.Cu")
		(net "P5E_CPU1_P3_TX_DP<7>")
	)
	(segment
		(start 122.271282 -373.719344)
		(end 122.027696 -373.96293)
		(width 0.14224)
		(layer "In11.Cu")
		(net "P5E_CPU1_P3_TX_DP<7>")
	)
	(segment
		(start 133.197854 -360.290364)
		(end 131.445508 -362.04271)
		(width 0.14224)
		(layer "In11.Cu")
		(net "P5E_CPU1_P3_TX_DP<7>")
	)
	(segment
		(start 118.809516 -277.794974)
		(end 118.810278 -277.795482)
		(width 0.1143)
		(layer "In11.Cu")
		(net "P5E_CPU1_P3_TX_DP<7>")
	)
	(segment
		(start 119.31523 -288.986722)
		(end 119.314214 -288.98723)
		(width 0.1143)
		(layer "In11.Cu")
		(net "P5E_CPU1_P3_TX_DP<7>")
	)
	(arc
		(start 140.114528 -345.101418)
		(mid 139.972325 -346.544179)
		(end 139.55141 -347.931486)
		(width 0.14224)
		(layer "In11.Cu")
		(net "P5E_CPU1_P3_TX_DP<7>")
	)
	(arc
		(start 119.343424 -293.221918)
		(mid 119.499352 -293.52621)
		(end 119.343424 -293.830502)
		(width 0.1143)
		(layer "In11.Cu")
		(net "P5E_CPU1_P3_TX_DP<7>")
	)
	(arc
		(start 119.310912 -282.507182)
		(mid 119.029843 -282.975133)
		(end 119.275352 -283.46273)
		(width 0.1143)
		(layer "In11.Cu")
		(net "P5E_CPU1_P3_TX_DP<7>")
	)
	(arc
		(start 136.44626 -355.428804)
		(mid 135.061476 -358.019561)
		(end 133.197854 -360.290364)
		(width 0.14224)
		(layer "In11.Cu")
		(net "P5E_CPU1_P3_TX_DP<7>")
	)
	(arc
		(start 119.31142 -292.229032)
		(mid 119.030773 -292.716394)
		(end 119.31142 -293.20363)
		(width 0.1143)
		(layer "In11.Cu")
		(net "P5E_CPU1_P3_TX_DP<7>")
	)
	(arc
		(start 119.310658 -287.366964)
		(mid 119.104804 -287.574195)
		(end 119.02948 -287.856422)
		(width 0.1143)
		(layer "In11.Cu")
		(net "P5E_CPU1_P3_TX_DP<7>")
	)
	(arc
		(start 118.845838 -277.815802)
		(mid 118.98031 -277.95164)
		(end 119.02948 -278.13635)
		(width 0.1143)
		(layer "In11.Cu")
		(net "P5E_CPU1_P3_TX_DP<7>")
	)
	(arc
		(start 119.962422 -274.966176)
		(mid 119.910005 -275.098107)
		(end 119.812308 -275.201126)
		(width 0.1143)
		(layer "In11.Cu")
		(net "P5E_CPU1_P3_TX_DP<7>")
	)
	(arc
		(start 118.802658 -276.861778)
		(mid 118.559331 -277.326344)
		(end 118.802658 -277.79091)
		(width 0.1143)
		(layer "In11.Cu")
		(net "P5E_CPU1_P3_TX_DP<7>")
	)
	(arc
		(start 119.345202 -288.363406)
		(mid 119.458609 -288.496295)
		(end 119.49938 -288.666174)
		(width 0.1143)
		(layer "In11.Cu")
		(net "P5E_CPU1_P3_TX_DP<7>")
	)
	(arc
		(start 119.49938 -287.046162)
		(mid 119.450106 -287.229853)
		(end 119.315484 -287.36417)
		(width 0.1143)
		(layer "In11.Cu")
		(net "P5E_CPU1_P3_TX_DP<7>")
	)
	(arc
		(start 119.345202 -286.743394)
		(mid 119.458609 -286.876283)
		(end 119.49938 -287.046162)
		(width 0.1143)
		(layer "In11.Cu")
		(net "P5E_CPU1_P3_TX_DP<7>")
	)
	(arc
		(start 119.02948 -287.856422)
		(mid 119.094716 -288.120013)
		(end 119.275352 -288.322766)
		(width 0.1143)
		(layer "In11.Cu")
		(net "P5E_CPU1_P3_TX_DP<7>")
	)
	(arc
		(start 119.343424 -294.84193)
		(mid 119.4581 -294.975264)
		(end 119.49938 -295.146222)
		(width 0.1143)
		(layer "In11.Cu")
		(net "P5E_CPU1_P3_TX_DP<7>")
	)
	(arc
		(start 119.311674 -290.608766)
		(mid 119.031027 -291.096192)
		(end 119.311674 -291.583618)
		(width 0.1143)
		(layer "In11.Cu")
		(net "P5E_CPU1_P3_TX_DP<7>")
	)
	(arc
		(start 119.02948 -276.516338)
		(mid 118.988225 -276.687309)
		(end 118.873524 -276.82063)
		(width 0.1143)
		(layer "In11.Cu")
		(net "P5E_CPU1_P3_TX_DP<7>")
	)
	(arc
		(start 124.04344 -366.263174)
		(mid 122.782763 -367.463255)
		(end 122.318526 -369.14074)
		(width 0.14224)
		(layer "In11.Cu")
		(net "P5E_CPU1_P3_TX_DP<7>")
	)
	(arc
		(start 119.75211 -295.616376)
		(mid 119.911264 -295.775453)
		(end 119.969534 -295.992804)
		(width 0.1143)
		(layer "In11.Cu")
		(net "P5E_CPU1_P3_TX_DP<7>")
	)
	(arc
		(start 119.499634 -295.146222)
		(mid 119.563869 -295.407968)
		(end 119.74195 -295.61028)
		(width 0.1143)
		(layer "In11.Cu")
		(net "P5E_CPU1_P3_TX_DP<7>")
	)
	(arc
		(start 119.304816 -284.13075)
		(mid 119.029698 -284.598494)
		(end 119.275098 -285.082488)
		(width 0.1143)
		(layer "In11.Cu")
		(net "P5E_CPU1_P3_TX_DP<7>")
	)
	(arc
		(start 119.343424 -283.5021)
		(mid 119.49776 -283.82291)
		(end 119.311928 -284.126686)
		(width 0.1143)
		(layer "In11.Cu")
		(net "P5E_CPU1_P3_TX_DP<7>")
	)
	(arc
		(start 119.310912 -284.127194)
		(mid 119.307859 -284.128963)
		(end 119.304816 -284.13075)
		(width 0.1143)
		(layer "In11.Cu")
		(net "P5E_CPU1_P3_TX_DP<7>")
	)
	(arc
		(start 119.334026 -285.116778)
		(mid 119.511876 -285.426797)
		(end 119.333264 -285.736284)
		(width 0.1143)
		(layer "In11.Cu")
		(net "P5E_CPU1_P3_TX_DP<7>")
	)
	(arc
		(start 119.742712 -275.241766)
		(mid 119.563899 -275.444116)
		(end 119.49938 -275.706332)
		(width 0.1143)
		(layer "In11.Cu")
		(net "P5E_CPU1_P3_TX_DP<7>")
	)
	(arc
		(start 119.328184 -276.020022)
		(mid 119.320369 -276.024944)
		(end 119.312436 -276.029674)
		(width 0.1143)
		(layer "In11.Cu")
		(net "P5E_CPU1_P3_TX_DP<7>")
	)
	(arc
		(start 119.343424 -281.882088)
		(mid 119.49776 -282.202898)
		(end 119.311928 -282.506674)
		(width 0.1143)
		(layer "In11.Cu")
		(net "P5E_CPU1_P3_TX_DP<7>")
	)
	(arc
		(start 119.308372 -276.032214)
		(mid 119.104163 -276.236974)
		(end 119.02948 -276.516338)
		(width 0.1143)
		(layer "In11.Cu")
		(net "P5E_CPU1_P3_TX_DP<7>")
	)
	(arc
		(start 122.318526 -373.605298)
		(mid 122.306249 -373.667021)
		(end 122.271282 -373.719344)
		(width 0.14224)
		(layer "In11.Cu")
		(net "P5E_CPU1_P3_TX_DP<7>")
	)
	(arc
		(start 119.30888 -288.990278)
		(mid 119.029045 -289.47618)
		(end 119.30888 -289.962082)
		(width 0.1143)
		(layer "In11.Cu")
		(net "P5E_CPU1_P3_TX_DP<7>")
	)
	(arc
		(start 125.283468 -365.609124)
		(mid 125.213068 -365.640315)
		(end 125.144276 -365.67491)
		(width 0.14224)
		(layer "In11.Cu")
		(net "P5E_CPU1_P3_TX_DP<7>")
	)
	(arc
		(start 119.02948 -278.13635)
		(mid 119.094202 -278.399089)
		(end 119.273574 -278.601678)
		(width 0.1143)
		(layer "In11.Cu")
		(net "P5E_CPU1_P3_TX_DP<7>")
	)
	(arc
		(start 119.49938 -280.566368)
		(mid 119.449557 -280.752098)
		(end 119.313452 -280.887932)
		(width 0.1143)
		(layer "In11.Cu")
		(net "P5E_CPU1_P3_TX_DP<7>")
	)
	(arc
		(start 119.742712 -280.101802)
		(mid 119.563899 -280.304152)
		(end 119.49938 -280.566368)
		(width 0.1143)
		(layer "In11.Cu")
		(net "P5E_CPU1_P3_TX_DP<7>")
	)
	(arc
		(start 119.343424 -291.601906)
		(mid 119.499352 -291.906198)
		(end 119.343424 -292.21049)
		(width 0.1143)
		(layer "In11.Cu")
		(net "P5E_CPU1_P3_TX_DP<7>")
	)
	(arc
		(start 119.49938 -288.666174)
		(mid 119.458125 -288.837145)
		(end 119.343424 -288.970466)
		(width 0.1143)
		(layer "In11.Cu")
		(net "P5E_CPU1_P3_TX_DP<7>")
	)
	(arc
		(start 119.49938 -278.946356)
		(mid 119.563895 -279.208575)
		(end 119.742712 -279.410922)
		(width 0.1143)
		(layer "In11.Cu")
		(net "P5E_CPU1_P3_TX_DP<7>")
	)
	(arc
		(start 119.812308 -279.451562)
		(mid 119.969285 -279.756362)
		(end 119.812308 -280.061162)
		(width 0.1143)
		(layer "In11.Cu")
		(net "P5E_CPU1_P3_TX_DP<7>")
	)
	(arc
		(start 119.309388 -285.750254)
		(mid 119.02946 -286.23641)
		(end 119.309388 -286.722566)
		(width 0.1143)
		(layer "In11.Cu")
		(net "P5E_CPU1_P3_TX_DP<7>")
	)
	(arc
		(start 119.343424 -289.981894)
		(mid 119.499352 -290.286186)
		(end 119.343424 -290.590478)
		(width 0.1143)
		(layer "In11.Cu")
		(net "P5E_CPU1_P3_TX_DP<7>")
	)
	(arc
		(start 119.310912 -280.889456)
		(mid 119.030346 -281.356319)
		(end 119.275352 -281.842718)
		(width 0.1143)
		(layer "In11.Cu")
		(net "P5E_CPU1_P3_TX_DP<7>")
	)
	(arc
		(start 119.343424 -278.642064)
		(mid 119.4581 -278.775398)
		(end 119.49938 -278.946356)
		(width 0.1143)
		(layer "In11.Cu")
		(net "P5E_CPU1_P3_TX_DP<7>")
	)
	(arc
		(start 119.294148 -293.85895)
		(mid 119.019379 -294.336216)
		(end 119.294148 -294.813482)
		(width 0.1143)
		(layer "In11.Cu")
		(net "P5E_CPU1_P3_TX_DP<7>")
	)
	(arc
		(start 131.445508 -362.04271)
		(mid 129.580921 -363.572912)
		(end 127.453644 -364.709964)
		(width 0.14224)
		(layer "In11.Cu")
		(net "P5E_CPU1_P3_TX_DP<7>")
	)
	(arc
		(start 119.49938 -275.706332)
		(mid 119.453786 -275.885001)
		(end 119.328184 -276.020022)
		(width 0.1143)
		(layer "In11.Cu")
		(net "P5E_CPU1_P3_TX_DP<7>")
	)
	(segment
		(start 118.894606 -369.30584)
		(end 118.894606 -370.00942)
		(width 0.12954)
		(layer "F.Cu")
		(net "P5E_CPU1_P3_TX_DP<6>")
	)
	(segment
		(start 118.894606 -370.00942)
		(end 118.598696 -370.30533)
		(width 0.12954)
		(layer "F.Cu")
		(net "P5E_CPU1_P3_TX_DP<6>")
	)
	(segment
		(start 116.30787 -276.2504)
		(end 116.774722 -276.516338)
		(width 0.12954)
		(layer "F.Cu")
		(net "P5E_CPU1_P3_TX_DP<6>")
	)
	(segment
		(start 118.624096 -369.03533)
		(end 118.894606 -369.30584)
		(width 0.12954)
		(layer "F.Cu")
		(net "P5E_CPU1_P3_TX_DP<6>")
	)
	(segment
		(start 118.831868 -280.084784)
		(end 118.832122 -280.08453)
		(width 0.1143)
		(layer "In11.Cu")
		(net "P5E_CPU1_P3_TX_DP<6>")
	)
	(segment
		(start 118.831106 -280.085292)
		(end 118.803674 -280.10104)
		(width 0.1143)
		(layer "In11.Cu")
		(net "P5E_CPU1_P3_TX_DP<6>")
	)
	(segment
		(start 118.805706 -295.61282)
		(end 118.841774 -295.633648)
		(width 0.1143)
		(layer "In11.Cu")
		(net "P5E_CPU1_P3_TX_DP<6>")
	)
	(segment
		(start 118.37162 -289.963352)
		(end 118.40337 -289.982148)
		(width 0.1143)
		(layer "In11.Cu")
		(net "P5E_CPU1_P3_TX_DP<6>")
	)
	(segment
		(start 117.861842 -277.790656)
		(end 117.932962 -277.832058)
		(width 0.1143)
		(layer "In11.Cu")
		(net "P5E_CPU1_P3_TX_DP<6>")
	)
	(segment
		(start 118.37162 -291.583364)
		(end 118.40337 -291.60216)
		(width 0.1143)
		(layer "In11.Cu")
		(net "P5E_CPU1_P3_TX_DP<6>")
	)
	(segment
		(start 118.873524 -280.0604)
		(end 118.848886 -280.074878)
		(width 0.1143)
		(layer "In11.Cu")
		(net "P5E_CPU1_P3_TX_DP<6>")
	)
	(segment
		(start 123.2154 -305.60137)
		(end 130.01625 -313.888374)
		(width 0.14224)
		(layer "In11.Cu")
		(net "P5E_CPU1_P3_TX_DP<6>")
	)
	(segment
		(start 118.832122 -280.08453)
		(end 118.831106 -280.085292)
		(width 0.1143)
		(layer "In11.Cu")
		(net "P5E_CPU1_P3_TX_DP<6>")
	)
	(segment
		(start 117.619526 -277.326344)
		(end 117.619526 -277.329392)
		(width 0.1143)
		(layer "In11.Cu")
		(net "P5E_CPU1_P3_TX_DP<6>")
	)
	(segment
		(start 116.774722 -276.516338)
		(end 117.072664 -276.516338)
		(width 0.1143)
		(layer "In11.Cu")
		(net "P5E_CPU1_P3_TX_DP<6>")
	)
	(segment
		(start 139.179046 -340.900766)
		(end 139.179046 -345.12504)
		(width 0.14224)
		(layer "In11.Cu")
		(net "P5E_CPU1_P3_TX_DP<6>")
	)
	(segment
		(start 138.833098 -346.863416)
		(end 135.279638 -355.44252)
		(width 0.14224)
		(layer "In11.Cu")
		(net "P5E_CPU1_P3_TX_DP<6>")
	)
	(segment
		(start 118.841774 -295.633648)
		(end 118.873524 -295.651936)
		(width 0.1143)
		(layer "In11.Cu")
		(net "P5E_CPU1_P3_TX_DP<6>")
	)
	(segment
		(start 130.01625 -313.888374)
		(end 134.1374 -320.05524)
		(width 0.14224)
		(layer "In11.Cu")
		(net "P5E_CPU1_P3_TX_DP<6>")
	)
	(segment
		(start 118.403624 -288.970212)
		(end 118.37162 -288.989008)
		(width 0.1143)
		(layer "In11.Cu")
		(net "P5E_CPU1_P3_TX_DP<6>")
	)
	(segment
		(start 118.37162 -280.889202)
		(end 118.334282 -280.910792)
		(width 0.1143)
		(layer "In11.Cu")
		(net "P5E_CPU1_P3_TX_DP<6>")
	)
	(segment
		(start 118.403624 -290.590224)
		(end 118.37162 -290.60902)
		(width 0.1143)
		(layer "In11.Cu")
		(net "P5E_CPU1_P3_TX_DP<6>")
	)
	(segment
		(start 118.37162 -283.483558)
		(end 118.40337 -283.502354)
		(width 0.1143)
		(layer "In11.Cu")
		(net "P5E_CPU1_P3_TX_DP<6>")
	)
	(segment
		(start 119.02948 -296.373042)
		(end 118.98376 -296.418762)
		(width 0.1143)
		(layer "In11.Cu")
		(net "P5E_CPU1_P3_TX_DP<6>")
	)
	(segment
		(start 118.37162 -282.509214)
		(end 118.334282 -282.530804)
		(width 0.1143)
		(layer "In11.Cu")
		(net "P5E_CPU1_P3_TX_DP<6>")
	)
	(segment
		(start 118.80342 -279.411684)
		(end 118.83517 -279.429972)
		(width 0.1143)
		(layer "In11.Cu")
		(net "P5E_CPU1_P3_TX_DP<6>")
	)
	(segment
		(start 118.844314 -279.435814)
		(end 118.851426 -279.43937)
		(width 0.1143)
		(layer "In11.Cu")
		(net "P5E_CPU1_P3_TX_DP<6>")
	)
	(segment
		(start 118.37162 -288.989008)
		(end 118.334282 -289.010598)
		(width 0.1143)
		(layer "In11.Cu")
		(net "P5E_CPU1_P3_TX_DP<6>")
	)
	(segment
		(start 118.403624 -292.210236)
		(end 118.37162 -292.229032)
		(width 0.1143)
		(layer "In11.Cu")
		(net "P5E_CPU1_P3_TX_DP<6>")
	)
	(segment
		(start 118.37162 -284.129226)
		(end 118.334282 -284.150816)
		(width 0.1143)
		(layer "In11.Cu")
		(net "P5E_CPU1_P3_TX_DP<6>")
	)
	(segment
		(start 118.401592 -287.351724)
		(end 118.334282 -287.39084)
		(width 0.1143)
		(layer "In11.Cu")
		(net "P5E_CPU1_P3_TX_DP<6>")
	)
	(segment
		(start 118.851426 -279.43937)
		(end 118.852188 -279.439878)
		(width 0.1143)
		(layer "In11.Cu")
		(net "P5E_CPU1_P3_TX_DP<6>")
	)
	(segment
		(start 118.334282 -281.841956)
		(end 118.37162 -281.863546)
		(width 0.1143)
		(layer "In11.Cu")
		(net "P5E_CPU1_P3_TX_DP<6>")
	)
	(segment
		(start 118.37162 -285.10357)
		(end 118.40337 -285.122366)
		(width 0.1143)
		(layer "In11.Cu")
		(net "P5E_CPU1_P3_TX_DP<6>")
	)
	(segment
		(start 118.334282 -294.801798)
		(end 118.37162 -294.823388)
		(width 0.1143)
		(layer "In11.Cu")
		(net "P5E_CPU1_P3_TX_DP<6>")
	)
	(segment
		(start 118.37162 -290.60902)
		(end 118.334282 -290.63061)
		(width 0.1143)
		(layer "In11.Cu")
		(net "P5E_CPU1_P3_TX_DP<6>")
	)
	(segment
		(start 118.80342 -295.611296)
		(end 118.805706 -295.61282)
		(width 0.1143)
		(layer "In11.Cu")
		(net "P5E_CPU1_P3_TX_DP<6>")
	)
	(segment
		(start 118.37162 -293.203376)
		(end 118.40337 -293.222172)
		(width 0.1143)
		(layer "In11.Cu")
		(net "P5E_CPU1_P3_TX_DP<6>")
	)
	(segment
		(start 124.911104 -364.733586)
		(end 119.130826 -367.823242)
		(width 0.14224)
		(layer "In11.Cu")
		(net "P5E_CPU1_P3_TX_DP<6>")
	)
	(segment
		(start 132.9309 -358.95788)
		(end 130.641598 -361.247182)
		(width 0.14224)
		(layer "In11.Cu")
		(net "P5E_CPU1_P3_TX_DP<6>")
	)
	(segment
		(start 117.393466 -276.981412)
		(end 117.406928 -276.989286)
		(width 0.1143)
		(layer "In11.Cu")
		(net "P5E_CPU1_P3_TX_DP<6>")
	)
	(segment
		(start 118.37162 -294.823388)
		(end 118.40337 -294.842184)
		(width 0.1143)
		(layer "In11.Cu")
		(net "P5E_CPU1_P3_TX_DP<6>")
	)
	(segment
		(start 118.403624 -285.730442)
		(end 118.37162 -285.749238)
		(width 0.1143)
		(layer "In11.Cu")
		(net "P5E_CPU1_P3_TX_DP<6>")
	)
	(segment
		(start 118.37162 -278.623522)
		(end 118.40337 -278.642318)
		(width 0.1143)
		(layer "In11.Cu")
		(net "P5E_CPU1_P3_TX_DP<6>")
	)
	(segment
		(start 118.841774 -279.43429)
		(end 118.84279 -279.434798)
		(width 0.1143)
		(layer "In11.Cu")
		(net "P5E_CPU1_P3_TX_DP<6>")
	)
	(segment
		(start 135.865108 -324.226174)
		(end 139.179046 -340.900766)
		(width 0.14224)
		(layer "In11.Cu")
		(net "P5E_CPU1_P3_TX_DP<6>")
	)
	(segment
		(start 118.98376 -296.418762)
		(end 118.98376 -296.44721)
		(width 0.1143)
		(layer "In11.Cu")
		(net "P5E_CPU1_P3_TX_DP<6>")
	)
	(segment
		(start 118.37162 -285.749238)
		(end 118.334282 -285.770828)
		(width 0.1143)
		(layer "In11.Cu")
		(net "P5E_CPU1_P3_TX_DP<6>")
	)
	(segment
		(start 118.371874 -288.343594)
		(end 118.40337 -288.362136)
		(width 0.1143)
		(layer "In11.Cu")
		(net "P5E_CPU1_P3_TX_DP<6>")
	)
	(segment
		(start 117.155468 -276.599142)
		(end 117.155722 -276.599142)
		(width 0.1143)
		(layer "In11.Cu")
		(net "P5E_CPU1_P3_TX_DP<6>")
	)
	(segment
		(start 118.334282 -289.941762)
		(end 118.37162 -289.963352)
		(width 0.1143)
		(layer "In11.Cu")
		(net "P5E_CPU1_P3_TX_DP<6>")
	)
	(segment
		(start 118.403624 -293.830248)
		(end 118.37162 -293.849044)
		(width 0.1143)
		(layer "In11.Cu")
		(net "P5E_CPU1_P3_TX_DP<6>")
	)
	(segment
		(start 120.07596 -300.902878)
		(end 123.2154 -305.60137)
		(width 0.14224)
		(layer "In11.Cu")
		(net "P5E_CPU1_P3_TX_DP<6>")
	)
	(segment
		(start 118.98376 -296.44721)
		(end 118.98376 -297.30192)
		(width 0.14224)
		(layer "In11.Cu")
		(net "P5E_CPU1_P3_TX_DP<6>")
	)
	(segment
		(start 118.403624 -282.490418)
		(end 118.37162 -282.509214)
		(width 0.1143)
		(layer "In11.Cu")
		(net "P5E_CPU1_P3_TX_DP<6>")
	)
	(segment
		(start 118.98376 -297.30192)
		(end 120.07596 -300.902878)
		(width 0.14224)
		(layer "In11.Cu")
		(net "P5E_CPU1_P3_TX_DP<6>")
	)
	(segment
		(start 134.1374 -320.05524)
		(end 135.865108 -324.226174)
		(width 0.14224)
		(layer "In11.Cu")
		(net "P5E_CPU1_P3_TX_DP<6>")
	)
	(segment
		(start 118.371874 -286.723582)
		(end 118.40337 -286.742124)
		(width 0.1143)
		(layer "In11.Cu")
		(net "P5E_CPU1_P3_TX_DP<6>")
	)
	(segment
		(start 118.914926 -368.7445)
		(end 118.624096 -369.03533)
		(width 0.14224)
		(layer "In11.Cu")
		(net "P5E_CPU1_P3_TX_DP<6>")
	)
	(segment
		(start 118.84279 -279.434798)
		(end 118.844314 -279.435814)
		(width 0.1143)
		(layer "In11.Cu")
		(net "P5E_CPU1_P3_TX_DP<6>")
	)
	(segment
		(start 117.406928 -276.989286)
		(end 117.461792 -277.021036)
		(width 0.1143)
		(layer "In11.Cu")
		(net "P5E_CPU1_P3_TX_DP<6>")
	)
	(segment
		(start 118.83517 -279.429972)
		(end 118.841774 -279.43429)
		(width 0.1143)
		(layer "In11.Cu")
		(net "P5E_CPU1_P3_TX_DP<6>")
	)
	(segment
		(start 118.331996 -286.700722)
		(end 118.371874 -286.723582)
		(width 0.1143)
		(layer "In11.Cu")
		(net "P5E_CPU1_P3_TX_DP<6>")
	)
	(segment
		(start 117.072664 -276.516338)
		(end 117.155468 -276.599142)
		(width 0.1143)
		(layer "In11.Cu")
		(net "P5E_CPU1_P3_TX_DP<6>")
	)
	(segment
		(start 118.914926 -368.183922)
		(end 118.914926 -368.7445)
		(width 0.14224)
		(layer "In11.Cu")
		(net "P5E_CPU1_P3_TX_DP<6>")
	)
	(segment
		(start 117.851428 -277.783036)
		(end 117.861842 -277.790656)
		(width 0.1143)
		(layer "In11.Cu")
		(net "P5E_CPU1_P3_TX_DP<6>")
	)
	(segment
		(start 117.932962 -277.832058)
		(end 117.933724 -277.832566)
		(width 0.1143)
		(layer "In11.Cu")
		(net "P5E_CPU1_P3_TX_DP<6>")
	)
	(segment
		(start 118.37162 -293.849044)
		(end 118.334282 -293.870634)
		(width 0.1143)
		(layer "In11.Cu")
		(net "P5E_CPU1_P3_TX_DP<6>")
	)
	(segment
		(start 118.334282 -293.181786)
		(end 118.37162 -293.203376)
		(width 0.1143)
		(layer "In11.Cu")
		(net "P5E_CPU1_P3_TX_DP<6>")
	)
	(segment
		(start 118.403624 -284.11043)
		(end 118.37162 -284.129226)
		(width 0.1143)
		(layer "In11.Cu")
		(net "P5E_CPU1_P3_TX_DP<6>")
	)
	(segment
		(start 118.841774 -280.078434)
		(end 118.836694 -280.081736)
		(width 0.1143)
		(layer "In11.Cu")
		(net "P5E_CPU1_P3_TX_DP<6>")
	)
	(segment
		(start 118.836694 -280.081736)
		(end 118.831868 -280.084784)
		(width 0.1143)
		(layer "In11.Cu")
		(net "P5E_CPU1_P3_TX_DP<6>")
	)
	(segment
		(start 126.260606 -364.174532)
		(end 124.911104 -364.733586)
		(width 0.14224)
		(layer "In11.Cu")
		(net "P5E_CPU1_P3_TX_DP<6>")
	)
	(segment
		(start 118.848886 -280.074878)
		(end 118.841774 -280.078434)
		(width 0.1143)
		(layer "In11.Cu")
		(net "P5E_CPU1_P3_TX_DP<6>")
	)
	(segment
		(start 118.334282 -291.561774)
		(end 118.37162 -291.583364)
		(width 0.1143)
		(layer "In11.Cu")
		(net "P5E_CPU1_P3_TX_DP<6>")
	)
	(segment
		(start 118.403624 -280.870406)
		(end 118.37162 -280.889202)
		(width 0.1143)
		(layer "In11.Cu")
		(net "P5E_CPU1_P3_TX_DP<6>")
	)
	(segment
		(start 118.331996 -288.320734)
		(end 118.371874 -288.343594)
		(width 0.1143)
		(layer "In11.Cu")
		(net "P5E_CPU1_P3_TX_DP<6>")
	)
	(segment
		(start 118.37162 -292.229032)
		(end 118.334282 -292.250622)
		(width 0.1143)
		(layer "In11.Cu")
		(net "P5E_CPU1_P3_TX_DP<6>")
	)
	(segment
		(start 119.02948 -295.956228)
		(end 119.02948 -296.373042)
		(width 0.1143)
		(layer "In11.Cu")
		(net "P5E_CPU1_P3_TX_DP<6>")
	)
	(segment
		(start 118.334282 -278.601932)
		(end 118.37162 -278.623522)
		(width 0.1143)
		(layer "In11.Cu")
		(net "P5E_CPU1_P3_TX_DP<6>")
	)
	(segment
		(start 118.852188 -279.439878)
		(end 118.873524 -279.452324)
		(width 0.1143)
		(layer "In11.Cu")
		(net "P5E_CPU1_P3_TX_DP<6>")
	)
	(segment
		(start 118.334282 -283.461968)
		(end 118.37162 -283.483558)
		(width 0.1143)
		(layer "In11.Cu")
		(net "P5E_CPU1_P3_TX_DP<6>")
	)
	(segment
		(start 118.37162 -281.863546)
		(end 118.40337 -281.882342)
		(width 0.1143)
		(layer "In11.Cu")
		(net "P5E_CPU1_P3_TX_DP<6>")
	)
	(segment
		(start 118.334282 -285.08198)
		(end 118.37162 -285.10357)
		(width 0.1143)
		(layer "In11.Cu")
		(net "P5E_CPU1_P3_TX_DP<6>")
	)
	(arc
		(start 118.55958 -287.046162)
		(mid 118.51774 -287.218148)
		(end 118.401592 -287.351724)
		(width 0.1143)
		(layer "In11.Cu")
		(net "P5E_CPU1_P3_TX_DP<6>")
	)
	(arc
		(start 118.40337 -286.742124)
		(mid 118.518213 -286.875272)
		(end 118.55958 -287.046162)
		(width 0.1143)
		(layer "In11.Cu")
		(net "P5E_CPU1_P3_TX_DP<6>")
	)
	(arc
		(start 117.933724 -277.832566)
		(mid 118.048343 -277.965644)
		(end 118.08968 -278.13635)
		(width 0.1143)
		(layer "In11.Cu")
		(net "P5E_CPU1_P3_TX_DP<6>")
	)
	(arc
		(start 118.55958 -278.946356)
		(mid 118.62418 -279.209055)
		(end 118.80342 -279.411684)
		(width 0.1143)
		(layer "In11.Cu")
		(net "P5E_CPU1_P3_TX_DP<6>")
	)
	(arc
		(start 118.55958 -280.566368)
		(mid 118.518321 -280.737225)
		(end 118.403624 -280.870406)
		(width 0.1143)
		(layer "In11.Cu")
		(net "P5E_CPU1_P3_TX_DP<6>")
	)
	(arc
		(start 118.803674 -280.10104)
		(mid 118.624329 -280.303643)
		(end 118.55958 -280.566368)
		(width 0.1143)
		(layer "In11.Cu")
		(net "P5E_CPU1_P3_TX_DP<6>")
	)
	(arc
		(start 118.40337 -291.60216)
		(mid 118.559303 -291.906095)
		(end 118.403624 -292.210236)
		(width 0.1143)
		(layer "In11.Cu")
		(net "P5E_CPU1_P3_TX_DP<6>")
	)
	(arc
		(start 118.334282 -289.010598)
		(mid 118.089461 -289.47618)
		(end 118.334282 -289.941762)
		(width 0.1143)
		(layer "In11.Cu")
		(net "P5E_CPU1_P3_TX_DP<6>")
	)
	(arc
		(start 118.334282 -285.770828)
		(mid 118.15449 -285.973416)
		(end 118.08968 -286.23641)
		(width 0.1143)
		(layer "In11.Cu")
		(net "P5E_CPU1_P3_TX_DP<6>")
	)
	(arc
		(start 118.873524 -295.651936)
		(mid 118.9882 -295.78527)
		(end 119.02948 -295.956228)
		(width 0.1143)
		(layer "In11.Cu")
		(net "P5E_CPU1_P3_TX_DP<6>")
	)
	(arc
		(start 139.179046 -345.12504)
		(mid 139.091697 -346.011269)
		(end 138.833098 -346.863416)
		(width 0.14224)
		(layer "In11.Cu")
		(net "P5E_CPU1_P3_TX_DP<6>")
	)
	(arc
		(start 118.40337 -288.362136)
		(mid 118.518213 -288.495284)
		(end 118.55958 -288.666174)
		(width 0.1143)
		(layer "In11.Cu")
		(net "P5E_CPU1_P3_TX_DP<6>")
	)
	(arc
		(start 118.40337 -294.842184)
		(mid 118.518213 -294.975332)
		(end 118.55958 -295.146222)
		(width 0.1143)
		(layer "In11.Cu")
		(net "P5E_CPU1_P3_TX_DP<6>")
	)
	(arc
		(start 118.334282 -290.63061)
		(mid 118.089461 -291.096192)
		(end 118.334282 -291.561774)
		(width 0.1143)
		(layer "In11.Cu")
		(net "P5E_CPU1_P3_TX_DP<6>")
	)
	(arc
		(start 118.40337 -283.502354)
		(mid 118.559303 -283.806289)
		(end 118.403624 -284.11043)
		(width 0.1143)
		(layer "In11.Cu")
		(net "P5E_CPU1_P3_TX_DP<6>")
	)
	(arc
		(start 118.873524 -279.452324)
		(mid 119.029457 -279.756362)
		(end 118.873524 -280.0604)
		(width 0.1143)
		(layer "In11.Cu")
		(net "P5E_CPU1_P3_TX_DP<6>")
	)
	(arc
		(start 118.334282 -282.530804)
		(mid 118.089461 -282.996386)
		(end 118.334282 -283.461968)
		(width 0.1143)
		(layer "In11.Cu")
		(net "P5E_CPU1_P3_TX_DP<6>")
	)
	(arc
		(start 118.334282 -287.39084)
		(mid 118.15449 -287.593428)
		(end 118.08968 -287.856422)
		(width 0.1143)
		(layer "In11.Cu")
		(net "P5E_CPU1_P3_TX_DP<6>")
	)
	(arc
		(start 118.08968 -278.13635)
		(mid 118.154498 -278.399339)
		(end 118.334282 -278.601932)
		(width 0.1143)
		(layer "In11.Cu")
		(net "P5E_CPU1_P3_TX_DP<6>")
	)
	(arc
		(start 118.334282 -292.250622)
		(mid 118.089461 -292.716204)
		(end 118.334282 -293.181786)
		(width 0.1143)
		(layer "In11.Cu")
		(net "P5E_CPU1_P3_TX_DP<6>")
	)
	(arc
		(start 118.40337 -293.222172)
		(mid 118.559303 -293.526107)
		(end 118.403624 -293.830248)
		(width 0.1143)
		(layer "In11.Cu")
		(net "P5E_CPU1_P3_TX_DP<6>")
	)
	(arc
		(start 118.40337 -281.882342)
		(mid 118.559303 -282.186277)
		(end 118.403624 -282.490418)
		(width 0.1143)
		(layer "In11.Cu")
		(net "P5E_CPU1_P3_TX_DP<6>")
	)
	(arc
		(start 118.334282 -293.870634)
		(mid 118.089461 -294.336216)
		(end 118.334282 -294.801798)
		(width 0.1143)
		(layer "In11.Cu")
		(net "P5E_CPU1_P3_TX_DP<6>")
	)
	(arc
		(start 117.619526 -277.329392)
		(mid 117.680816 -277.584151)
		(end 117.851428 -277.783036)
		(width 0.1143)
		(layer "In11.Cu")
		(net "P5E_CPU1_P3_TX_DP<6>")
	)
	(arc
		(start 118.334282 -284.150816)
		(mid 118.089461 -284.616398)
		(end 118.334282 -285.08198)
		(width 0.1143)
		(layer "In11.Cu")
		(net "P5E_CPU1_P3_TX_DP<6>")
	)
	(arc
		(start 118.40337 -285.122366)
		(mid 118.559303 -285.426301)
		(end 118.403624 -285.730442)
		(width 0.1143)
		(layer "In11.Cu")
		(net "P5E_CPU1_P3_TX_DP<6>")
	)
	(arc
		(start 118.40337 -278.642318)
		(mid 118.518213 -278.775466)
		(end 118.55958 -278.946356)
		(width 0.1143)
		(layer "In11.Cu")
		(net "P5E_CPU1_P3_TX_DP<6>")
	)
	(arc
		(start 118.40337 -289.982148)
		(mid 118.559303 -290.286083)
		(end 118.403624 -290.590224)
		(width 0.1143)
		(layer "In11.Cu")
		(net "P5E_CPU1_P3_TX_DP<6>")
	)
	(arc
		(start 130.641598 -361.247182)
		(mid 128.595252 -362.926587)
		(end 126.260606 -364.174532)
		(width 0.14224)
		(layer "In11.Cu")
		(net "P5E_CPU1_P3_TX_DP<6>")
	)
	(arc
		(start 119.130826 -367.823242)
		(mid 118.973014 -367.973738)
		(end 118.914926 -368.183922)
		(width 0.14224)
		(layer "In11.Cu")
		(net "P5E_CPU1_P3_TX_DP<6>")
	)
	(arc
		(start 118.55958 -288.666174)
		(mid 118.518321 -288.837031)
		(end 118.403624 -288.970212)
		(width 0.1143)
		(layer "In11.Cu")
		(net "P5E_CPU1_P3_TX_DP<6>")
	)
	(arc
		(start 118.08968 -287.856422)
		(mid 118.153856 -288.118309)
		(end 118.331996 -288.320734)
		(width 0.1143)
		(layer "In11.Cu")
		(net "P5E_CPU1_P3_TX_DP<6>")
	)
	(arc
		(start 135.279638 -355.44252)
		(mid 134.278388 -357.315867)
		(end 132.9309 -358.95788)
		(width 0.14224)
		(layer "In11.Cu")
		(net "P5E_CPU1_P3_TX_DP<6>")
	)
	(arc
		(start 117.155722 -276.599142)
		(mid 117.234939 -276.814925)
		(end 117.393466 -276.981412)
		(width 0.1143)
		(layer "In11.Cu")
		(net "P5E_CPU1_P3_TX_DP<6>")
	)
	(arc
		(start 118.08968 -286.23641)
		(mid 118.153856 -286.498297)
		(end 118.331996 -286.700722)
		(width 0.1143)
		(layer "In11.Cu")
		(net "P5E_CPU1_P3_TX_DP<6>")
	)
	(arc
		(start 118.334282 -280.910792)
		(mid 118.089461 -281.376374)
		(end 118.334282 -281.841956)
		(width 0.1143)
		(layer "In11.Cu")
		(net "P5E_CPU1_P3_TX_DP<6>")
	)
	(arc
		(start 117.461792 -277.021036)
		(mid 117.577747 -277.154526)
		(end 117.619526 -277.326344)
		(width 0.1143)
		(layer "In11.Cu")
		(net "P5E_CPU1_P3_TX_DP<6>")
	)
	(arc
		(start 118.55958 -295.146222)
		(mid 118.624239 -295.408779)
		(end 118.80342 -295.611296)
		(width 0.1143)
		(layer "In11.Cu")
		(net "P5E_CPU1_P3_TX_DP<6>")
	)
	(segment
		(start 116.30787 -277.870412)
		(end 116.774722 -278.13635)
		(width 0.12954)
		(layer "F.Cu")
		(net "P5E_CPU1_P3_TX_DP<5>")
	)
	(segment
		(start 117.192806 -371.76964)
		(end 117.192806 -372.47322)
		(width 0.12954)
		(layer "F.Cu")
		(net "P5E_CPU1_P3_TX_DP<5>")
	)
	(segment
		(start 117.192806 -372.47322)
		(end 116.896896 -372.76913)
		(width 0.12954)
		(layer "F.Cu")
		(net "P5E_CPU1_P3_TX_DP<5>")
	)
	(segment
		(start 116.922296 -371.49913)
		(end 117.192806 -371.76964)
		(width 0.12954)
		(layer "F.Cu")
		(net "P5E_CPU1_P3_TX_DP<5>")
	)
	(segment
		(start 119.226584 -301.320708)
		(end 122.473974 -306.180998)
		(width 0.14224)
		(layer "In11.Cu")
		(net "P5E_CPU1_P3_TX_DP<5>")
	)
	(segment
		(start 117.432582 -290.608512)
		(end 117.43182 -290.608766)
		(width 0.1143)
		(layer "In11.Cu")
		(net "P5E_CPU1_P3_TX_DP<5>")
	)
	(segment
		(start 118.620032 -367.004854)
		(end 117.751352 -367.717832)
		(width 0.14224)
		(layer "In11.Cu")
		(net "P5E_CPU1_P3_TX_DP<5>")
	)
	(segment
		(start 117.399562 -278.60498)
		(end 117.400324 -278.605488)
		(width 0.1143)
		(layer "In11.Cu")
		(net "P5E_CPU1_P3_TX_DP<5>")
	)
	(segment
		(start 117.43182 -292.228778)
		(end 117.430804 -292.229286)
		(width 0.1143)
		(layer "In11.Cu")
		(net "P5E_CPU1_P3_TX_DP<5>")
	)
	(segment
		(start 117.430804 -285.749492)
		(end 117.392704 -285.771844)
		(width 0.1143)
		(layer "In11.Cu")
		(net "P5E_CPU1_P3_TX_DP<5>")
	)
	(segment
		(start 117.434868 -288.986976)
		(end 117.432582 -288.9885)
		(width 0.1143)
		(layer "In11.Cu")
		(net "P5E_CPU1_P3_TX_DP<5>")
	)
	(segment
		(start 117.912134 -295.63949)
		(end 117.93347 -295.651936)
		(width 0.1143)
		(layer "In11.Cu")
		(net "P5E_CPU1_P3_TX_DP<5>")
	)
	(segment
		(start 117.434614 -285.105602)
		(end 117.435122 -285.105602)
		(width 0.1143)
		(layer "In11.Cu")
		(net "P5E_CPU1_P3_TX_DP<5>")
	)
	(segment
		(start 117.430804 -281.863292)
		(end 117.43182 -281.8638)
		(width 0.1143)
		(layer "In11.Cu")
		(net "P5E_CPU1_P3_TX_DP<5>")
	)
	(segment
		(start 117.392704 -294.800782)
		(end 117.430804 -294.823134)
		(width 0.1143)
		(layer "In11.Cu")
		(net "P5E_CPU1_P3_TX_DP<5>")
	)
	(segment
		(start 117.430804 -288.989262)
		(end 117.392704 -289.011614)
		(width 0.1143)
		(layer "In11.Cu")
		(net "P5E_CPU1_P3_TX_DP<5>")
	)
	(segment
		(start 117.432582 -278.62403)
		(end 117.433598 -278.624538)
		(width 0.1143)
		(layer "In11.Cu")
		(net "P5E_CPU1_P3_TX_DP<5>")
	)
	(segment
		(start 117.435376 -290.606988)
		(end 117.434868 -290.606988)
		(width 0.1143)
		(layer "In11.Cu")
		(net "P5E_CPU1_P3_TX_DP<5>")
	)
	(segment
		(start 117.432582 -285.104332)
		(end 117.434614 -285.105602)
		(width 0.1143)
		(layer "In11.Cu")
		(net "P5E_CPU1_P3_TX_DP<5>")
	)
	(segment
		(start 117.43182 -280.888948)
		(end 117.430804 -280.889456)
		(width 0.1143)
		(layer "In11.Cu")
		(net "P5E_CPU1_P3_TX_DP<5>")
	)
	(segment
		(start 117.902482 -295.634156)
		(end 117.905276 -295.63568)
		(width 0.1143)
		(layer "In11.Cu")
		(net "P5E_CPU1_P3_TX_DP<5>")
	)
	(segment
		(start 117.392704 -278.600916)
		(end 117.399562 -278.60498)
		(width 0.1143)
		(layer "In11.Cu")
		(net "P5E_CPU1_P3_TX_DP<5>")
	)
	(segment
		(start 117.46357 -292.21049)
		(end 117.432582 -292.22827)
		(width 0.1143)
		(layer "In11.Cu")
		(net "P5E_CPU1_P3_TX_DP<5>")
	)
	(segment
		(start 117.43182 -281.8638)
		(end 117.432582 -281.864308)
		(width 0.1143)
		(layer "In11.Cu")
		(net "P5E_CPU1_P3_TX_DP<5>")
	)
	(segment
		(start 118.08968 -295.956228)
		(end 118.08968 -296.373042)
		(width 0.1143)
		(layer "In11.Cu")
		(net "P5E_CPU1_P3_TX_DP<5>")
	)
	(segment
		(start 117.434868 -285.747206)
		(end 117.432582 -285.74873)
		(width 0.1143)
		(layer "In11.Cu")
		(net "P5E_CPU1_P3_TX_DP<5>")
	)
	(segment
		(start 117.432582 -278.624284)
		(end 117.432582 -278.62403)
		(width 0.1143)
		(layer "In11.Cu")
		(net "P5E_CPU1_P3_TX_DP<5>")
	)
	(segment
		(start 117.072664 -278.13635)
		(end 117.155468 -278.219154)
		(width 0.1143)
		(layer "In11.Cu")
		(net "P5E_CPU1_P3_TX_DP<5>")
	)
	(segment
		(start 117.430804 -282.509468)
		(end 117.392704 -282.53182)
		(width 0.1143)
		(layer "In11.Cu")
		(net "P5E_CPU1_P3_TX_DP<5>")
	)
	(segment
		(start 117.426232 -292.23208)
		(end 117.392704 -292.251638)
		(width 0.1143)
		(layer "In11.Cu")
		(net "P5E_CPU1_P3_TX_DP<5>")
	)
	(segment
		(start 117.392704 -285.080964)
		(end 117.430804 -285.103316)
		(width 0.1143)
		(layer "In11.Cu")
		(net "P5E_CPU1_P3_TX_DP<5>")
	)
	(segment
		(start 117.435376 -285.747206)
		(end 117.434868 -285.747206)
		(width 0.1143)
		(layer "In11.Cu")
		(net "P5E_CPU1_P3_TX_DP<5>")
	)
	(segment
		(start 117.430804 -292.229286)
		(end 117.428772 -292.230556)
		(width 0.1143)
		(layer "In11.Cu")
		(net "P5E_CPU1_P3_TX_DP<5>")
	)
	(segment
		(start 117.434614 -289.965384)
		(end 117.435122 -289.965384)
		(width 0.1143)
		(layer "In11.Cu")
		(net "P5E_CPU1_P3_TX_DP<5>")
	)
	(segment
		(start 117.392704 -289.940746)
		(end 117.430804 -289.963098)
		(width 0.1143)
		(layer "In11.Cu")
		(net "P5E_CPU1_P3_TX_DP<5>")
	)
	(segment
		(start 117.900704 -295.63314)
		(end 117.90172 -295.633648)
		(width 0.1143)
		(layer "In11.Cu")
		(net "P5E_CPU1_P3_TX_DP<5>")
	)
	(segment
		(start 117.435376 -293.847012)
		(end 117.434868 -293.847012)
		(width 0.1143)
		(layer "In11.Cu")
		(net "P5E_CPU1_P3_TX_DP<5>")
	)
	(segment
		(start 117.430804 -293.203122)
		(end 117.43182 -293.20363)
		(width 0.1143)
		(layer "In11.Cu")
		(net "P5E_CPU1_P3_TX_DP<5>")
	)
	(segment
		(start 133.21411 -320.356738)
		(end 134.847838 -324.301104)
		(width 0.14224)
		(layer "In11.Cu")
		(net "P5E_CPU1_P3_TX_DP<5>")
	)
	(segment
		(start 117.432582 -283.48432)
		(end 117.434614 -283.48559)
		(width 0.1143)
		(layer "In11.Cu")
		(net "P5E_CPU1_P3_TX_DP<5>")
	)
	(segment
		(start 117.432582 -285.74873)
		(end 117.43182 -285.748984)
		(width 0.1143)
		(layer "In11.Cu")
		(net "P5E_CPU1_P3_TX_DP<5>")
	)
	(segment
		(start 117.432582 -284.128718)
		(end 117.43182 -284.128972)
		(width 0.1143)
		(layer "In11.Cu")
		(net "P5E_CPU1_P3_TX_DP<5>")
	)
	(segment
		(start 117.907562 -295.63695)
		(end 117.908324 -295.637458)
		(width 0.1143)
		(layer "In11.Cu")
		(net "P5E_CPU1_P3_TX_DP<5>")
	)
	(segment
		(start 117.619526 -287.046162)
		(end 117.619526 -287.050734)
		(width 0.1143)
		(layer "In11.Cu")
		(net "P5E_CPU1_P3_TX_DP<5>")
	)
	(segment
		(start 117.908324 -295.637458)
		(end 117.909594 -295.63822)
		(width 0.1143)
		(layer "In11.Cu")
		(net "P5E_CPU1_P3_TX_DP<5>")
	)
	(segment
		(start 117.434868 -284.127194)
		(end 117.432582 -284.128718)
		(width 0.1143)
		(layer "In11.Cu")
		(net "P5E_CPU1_P3_TX_DP<5>")
	)
	(segment
		(start 117.46865 -292.206934)
		(end 117.46357 -292.21049)
		(width 0.1143)
		(layer "In11.Cu")
		(net "P5E_CPU1_P3_TX_DP<5>")
	)
	(segment
		(start 117.399562 -283.465016)
		(end 117.400324 -283.465524)
		(width 0.1143)
		(layer "In11.Cu")
		(net "P5E_CPU1_P3_TX_DP<5>")
	)
	(segment
		(start 117.434868 -293.847012)
		(end 117.432582 -293.848536)
		(width 0.1143)
		(layer "In11.Cu")
		(net "P5E_CPU1_P3_TX_DP<5>")
	)
	(segment
		(start 118.04396 -296.44721)
		(end 118.04396 -297.421808)
		(width 0.14224)
		(layer "In11.Cu")
		(net "P5E_CPU1_P3_TX_DP<5>")
	)
	(segment
		(start 117.430804 -280.889456)
		(end 117.392704 -280.911808)
		(width 0.1143)
		(layer "In11.Cu")
		(net "P5E_CPU1_P3_TX_DP<5>")
	)
	(segment
		(start 117.427248 -292.231572)
		(end 117.426232 -292.23208)
		(width 0.1143)
		(layer "In11.Cu")
		(net "P5E_CPU1_P3_TX_DP<5>")
	)
	(segment
		(start 117.43182 -293.20363)
		(end 117.432582 -293.204138)
		(width 0.1143)
		(layer "In11.Cu")
		(net "P5E_CPU1_P3_TX_DP<5>")
	)
	(segment
		(start 117.392704 -293.18077)
		(end 117.430804 -293.203122)
		(width 0.1143)
		(layer "In11.Cu")
		(net "P5E_CPU1_P3_TX_DP<5>")
	)
	(segment
		(start 116.774722 -278.13635)
		(end 117.072664 -278.13635)
		(width 0.1143)
		(layer "In11.Cu")
		(net "P5E_CPU1_P3_TX_DP<5>")
	)
	(segment
		(start 117.432582 -292.22827)
		(end 117.43182 -292.228778)
		(width 0.1143)
		(layer "In11.Cu")
		(net "P5E_CPU1_P3_TX_DP<5>")
	)
	(segment
		(start 117.43182 -285.103824)
		(end 117.432582 -285.104332)
		(width 0.1143)
		(layer "In11.Cu")
		(net "P5E_CPU1_P3_TX_DP<5>")
	)
	(segment
		(start 117.430804 -289.963098)
		(end 117.43182 -289.963606)
		(width 0.1143)
		(layer "In11.Cu")
		(net "P5E_CPU1_P3_TX_DP<5>")
	)
	(segment
		(start 117.619526 -295.146222)
		(end 117.619272 -295.146222)
		(width 0.1143)
		(layer "In11.Cu")
		(net "P5E_CPU1_P3_TX_DP<5>")
	)
	(segment
		(start 117.399054 -288.324544)
		(end 117.434868 -288.345372)
		(width 0.1143)
		(layer "In11.Cu")
		(net "P5E_CPU1_P3_TX_DP<5>")
	)
	(segment
		(start 117.392704 -281.84094)
		(end 117.430804 -281.863292)
		(width 0.1143)
		(layer "In11.Cu")
		(net "P5E_CPU1_P3_TX_DP<5>")
	)
	(segment
		(start 117.392704 -291.560758)
		(end 117.430804 -291.58311)
		(width 0.1143)
		(layer "In11.Cu")
		(net "P5E_CPU1_P3_TX_DP<5>")
	)
	(segment
		(start 117.43182 -283.483812)
		(end 117.432582 -283.48432)
		(width 0.1143)
		(layer "In11.Cu")
		(net "P5E_CPU1_P3_TX_DP<5>")
	)
	(segment
		(start 117.432582 -293.204138)
		(end 117.434614 -293.205408)
		(width 0.1143)
		(layer "In11.Cu")
		(net "P5E_CPU1_P3_TX_DP<5>")
	)
	(segment
		(start 117.213126 -368.653314)
		(end 117.213126 -371.2083)
		(width 0.14224)
		(layer "In11.Cu")
		(net "P5E_CPU1_P3_TX_DP<5>")
	)
	(segment
		(start 117.432582 -293.848536)
		(end 117.43182 -293.84879)
		(width 0.1143)
		(layer "In11.Cu")
		(net "P5E_CPU1_P3_TX_DP<5>")
	)
	(segment
		(start 117.43182 -285.748984)
		(end 117.430804 -285.749492)
		(width 0.1143)
		(layer "In11.Cu")
		(net "P5E_CPU1_P3_TX_DP<5>")
	)
	(segment
		(start 117.46357 -287.350454)
		(end 117.395244 -287.390078)
		(width 0.1143)
		(layer "In11.Cu")
		(net "P5E_CPU1_P3_TX_DP<5>")
	)
	(segment
		(start 118.08968 -296.373042)
		(end 118.04396 -296.418762)
		(width 0.1143)
		(layer "In11.Cu")
		(net "P5E_CPU1_P3_TX_DP<5>")
	)
	(segment
		(start 117.432582 -281.864308)
		(end 117.434614 -281.865578)
		(width 0.1143)
		(layer "In11.Cu")
		(net "P5E_CPU1_P3_TX_DP<5>")
	)
	(segment
		(start 117.46357 -291.601906)
		(end 117.46865 -291.605462)
		(width 0.1143)
		(layer "In11.Cu")
		(net "P5E_CPU1_P3_TX_DP<5>")
	)
	(segment
		(start 117.43182 -291.583618)
		(end 117.432582 -291.584126)
		(width 0.1143)
		(layer "In11.Cu")
		(net "P5E_CPU1_P3_TX_DP<5>")
	)
	(segment
		(start 117.46738 -287.34766)
		(end 117.46357 -287.350454)
		(width 0.1143)
		(layer "In11.Cu")
		(net "P5E_CPU1_P3_TX_DP<5>")
	)
	(segment
		(start 117.430804 -290.609274)
		(end 117.392704 -290.631626)
		(width 0.1143)
		(layer "In11.Cu")
		(net "P5E_CPU1_P3_TX_DP<5>")
	)
	(segment
		(start 117.43182 -288.988754)
		(end 117.430804 -288.989262)
		(width 0.1143)
		(layer "In11.Cu")
		(net "P5E_CPU1_P3_TX_DP<5>")
	)
	(segment
		(start 118.04396 -297.421808)
		(end 119.226584 -301.320708)
		(width 0.14224)
		(layer "In11.Cu")
		(net "P5E_CPU1_P3_TX_DP<5>")
	)
	(segment
		(start 117.901974 -279.433782)
		(end 117.93347 -279.452324)
		(width 0.1143)
		(layer "In11.Cu")
		(net "P5E_CPU1_P3_TX_DP<5>")
	)
	(segment
		(start 117.400324 -278.605488)
		(end 117.43182 -278.623776)
		(width 0.1143)
		(layer "In11.Cu")
		(net "P5E_CPU1_P3_TX_DP<5>")
	)
	(segment
		(start 117.432582 -289.964114)
		(end 117.434614 -289.965384)
		(width 0.1143)
		(layer "In11.Cu")
		(net "P5E_CPU1_P3_TX_DP<5>")
	)
	(segment
		(start 117.43182 -278.623776)
		(end 117.432582 -278.624284)
		(width 0.1143)
		(layer "In11.Cu")
		(net "P5E_CPU1_P3_TX_DP<5>")
	)
	(segment
		(start 117.430804 -294.823134)
		(end 117.43436 -294.824912)
		(width 0.1143)
		(layer "In11.Cu")
		(net "P5E_CPU1_P3_TX_DP<5>")
	)
	(segment
		(start 132.228336 -358.225852)
		(end 129.84353 -360.610658)
		(width 0.14224)
		(layer "In11.Cu")
		(net "P5E_CPU1_P3_TX_DP<5>")
	)
	(segment
		(start 117.428772 -292.230556)
		(end 117.427248 -292.231572)
		(width 0.1143)
		(layer "In11.Cu")
		(net "P5E_CPU1_P3_TX_DP<5>")
	)
	(segment
		(start 117.906038 -295.636188)
		(end 117.907562 -295.63695)
		(width 0.1143)
		(layer "In11.Cu")
		(net "P5E_CPU1_P3_TX_DP<5>")
	)
	(segment
		(start 117.619526 -295.141904)
		(end 117.619526 -295.146222)
		(width 0.1143)
		(layer "In11.Cu")
		(net "P5E_CPU1_P3_TX_DP<5>")
	)
	(segment
		(start 117.432582 -280.88844)
		(end 117.43182 -280.888948)
		(width 0.1143)
		(layer "In11.Cu")
		(net "P5E_CPU1_P3_TX_DP<5>")
	)
	(segment
		(start 117.434614 -281.865578)
		(end 117.435122 -281.865578)
		(width 0.1143)
		(layer "In11.Cu")
		(net "P5E_CPU1_P3_TX_DP<5>")
	)
	(segment
		(start 117.430804 -291.58311)
		(end 117.43182 -291.583618)
		(width 0.1143)
		(layer "In11.Cu")
		(net "P5E_CPU1_P3_TX_DP<5>")
	)
	(segment
		(start 117.862604 -295.610788)
		(end 117.900704 -295.63314)
		(width 0.1143)
		(layer "In11.Cu")
		(net "P5E_CPU1_P3_TX_DP<5>")
	)
	(segment
		(start 117.432582 -288.9885)
		(end 117.43182 -288.988754)
		(width 0.1143)
		(layer "In11.Cu")
		(net "P5E_CPU1_P3_TX_DP<5>")
	)
	(segment
		(start 125.886972 -363.120432)
		(end 118.620032 -367.004854)
		(width 0.14224)
		(layer "In11.Cu")
		(net "P5E_CPU1_P3_TX_DP<5>")
	)
	(segment
		(start 137.8077 -346.724478)
		(end 134.374382 -355.013768)
		(width 0.14224)
		(layer "In11.Cu")
		(net "P5E_CPU1_P3_TX_DP<5>")
	)
	(segment
		(start 117.213126 -371.2083)
		(end 116.922296 -371.49913)
		(width 0.14224)
		(layer "In11.Cu")
		(net "P5E_CPU1_P3_TX_DP<5>")
	)
	(segment
		(start 126.414276 -362.901992)
		(end 125.886972 -363.120432)
		(width 0.14224)
		(layer "In11.Cu")
		(net "P5E_CPU1_P3_TX_DP<5>")
	)
	(segment
		(start 117.43182 -282.50896)
		(end 117.430804 -282.509468)
		(width 0.1143)
		(layer "In11.Cu")
		(net "P5E_CPU1_P3_TX_DP<5>")
	)
	(segment
		(start 117.909594 -295.63822)
		(end 117.912134 -295.63949)
		(width 0.1143)
		(layer "In11.Cu")
		(net "P5E_CPU1_P3_TX_DP<5>")
	)
	(segment
		(start 117.400324 -283.465524)
		(end 117.43182 -283.483812)
		(width 0.1143)
		(layer "In11.Cu")
		(net "P5E_CPU1_P3_TX_DP<5>")
	)
	(segment
		(start 117.90172 -295.633648)
		(end 117.902482 -295.634156)
		(width 0.1143)
		(layer "In11.Cu")
		(net "P5E_CPU1_P3_TX_DP<5>")
	)
	(segment
		(start 117.43182 -289.963606)
		(end 117.432582 -289.964114)
		(width 0.1143)
		(layer "In11.Cu")
		(net "P5E_CPU1_P3_TX_DP<5>")
	)
	(segment
		(start 117.432582 -291.584126)
		(end 117.46357 -291.601906)
		(width 0.1143)
		(layer "In11.Cu")
		(net "P5E_CPU1_P3_TX_DP<5>")
	)
	(segment
		(start 118.04396 -296.418762)
		(end 118.04396 -296.44721)
		(width 0.1143)
		(layer "In11.Cu")
		(net "P5E_CPU1_P3_TX_DP<5>")
	)
	(segment
		(start 117.435376 -288.986976)
		(end 117.434868 -288.986976)
		(width 0.1143)
		(layer "In11.Cu")
		(net "P5E_CPU1_P3_TX_DP<5>")
	)
	(segment
		(start 117.93347 -280.060654)
		(end 117.888766 -280.086562)
		(width 0.1143)
		(layer "In11.Cu")
		(net "P5E_CPU1_P3_TX_DP<5>")
	)
	(segment
		(start 117.434868 -288.345372)
		(end 117.435122 -288.345372)
		(width 0.1143)
		(layer "In11.Cu")
		(net "P5E_CPU1_P3_TX_DP<5>")
	)
	(segment
		(start 117.434614 -283.48559)
		(end 117.435122 -283.48559)
		(width 0.1143)
		(layer "In11.Cu")
		(net "P5E_CPU1_P3_TX_DP<5>")
	)
	(segment
		(start 117.43182 -290.608766)
		(end 117.430804 -290.609274)
		(width 0.1143)
		(layer "In11.Cu")
		(net "P5E_CPU1_P3_TX_DP<5>")
	)
	(segment
		(start 117.433598 -278.624538)
		(end 117.447314 -278.632412)
		(width 0.1143)
		(layer "In11.Cu")
		(net "P5E_CPU1_P3_TX_DP<5>")
	)
	(segment
		(start 117.434868 -282.507182)
		(end 117.432582 -282.508706)
		(width 0.1143)
		(layer "In11.Cu")
		(net "P5E_CPU1_P3_TX_DP<5>")
	)
	(segment
		(start 117.3988 -288.324544)
		(end 117.399054 -288.324544)
		(width 0.1143)
		(layer "In11.Cu")
		(net "P5E_CPU1_P3_TX_DP<5>")
	)
	(segment
		(start 117.430804 -285.103316)
		(end 117.43182 -285.103824)
		(width 0.1143)
		(layer "In11.Cu")
		(net "P5E_CPU1_P3_TX_DP<5>")
	)
	(segment
		(start 117.392704 -283.460952)
		(end 117.399562 -283.465016)
		(width 0.1143)
		(layer "In11.Cu")
		(net "P5E_CPU1_P3_TX_DP<5>")
	)
	(segment
		(start 117.632226 -278.953722)
		(end 117.632226 -278.966168)
		(width 0.1143)
		(layer "In11.Cu")
		(net "P5E_CPU1_P3_TX_DP<5>")
	)
	(segment
		(start 117.435376 -284.127194)
		(end 117.434868 -284.127194)
		(width 0.1143)
		(layer "In11.Cu")
		(net "P5E_CPU1_P3_TX_DP<5>")
	)
	(segment
		(start 129.299208 -314.497466)
		(end 133.21411 -320.356738)
		(width 0.14224)
		(layer "In11.Cu")
		(net "P5E_CPU1_P3_TX_DP<5>")
	)
	(segment
		(start 117.434614 -293.205408)
		(end 117.435122 -293.205408)
		(width 0.1143)
		(layer "In11.Cu")
		(net "P5E_CPU1_P3_TX_DP<5>")
	)
	(segment
		(start 117.392704 -286.700976)
		(end 117.465348 -286.743394)
		(width 0.1143)
		(layer "In11.Cu")
		(net "P5E_CPU1_P3_TX_DP<5>")
	)
	(segment
		(start 117.430804 -293.849298)
		(end 117.392704 -293.87165)
		(width 0.1143)
		(layer "In11.Cu")
		(net "P5E_CPU1_P3_TX_DP<5>")
	)
	(segment
		(start 117.434868 -290.606988)
		(end 117.432582 -290.608512)
		(width 0.1143)
		(layer "In11.Cu")
		(net "P5E_CPU1_P3_TX_DP<5>")
	)
	(segment
		(start 117.432582 -282.508706)
		(end 117.43182 -282.50896)
		(width 0.1143)
		(layer "In11.Cu")
		(net "P5E_CPU1_P3_TX_DP<5>")
	)
	(segment
		(start 138.141456 -340.860126)
		(end 138.141456 -345.047316)
		(width 0.14224)
		(layer "In11.Cu")
		(net "P5E_CPU1_P3_TX_DP<5>")
	)
	(segment
		(start 117.905276 -295.63568)
		(end 117.906038 -295.636188)
		(width 0.1143)
		(layer "In11.Cu")
		(net "P5E_CPU1_P3_TX_DP<5>")
	)
	(segment
		(start 117.43182 -293.84879)
		(end 117.430804 -293.849298)
		(width 0.1143)
		(layer "In11.Cu")
		(net "P5E_CPU1_P3_TX_DP<5>")
	)
	(segment
		(start 117.392704 -288.320988)
		(end 117.3988 -288.324544)
		(width 0.1143)
		(layer "In11.Cu")
		(net "P5E_CPU1_P3_TX_DP<5>")
	)
	(segment
		(start 117.607588 -280.57475)
		(end 117.607588 -280.58618)
		(width 0.1143)
		(layer "In11.Cu")
		(net "P5E_CPU1_P3_TX_DP<5>")
	)
	(segment
		(start 117.43436 -294.824912)
		(end 117.464586 -294.842946)
		(width 0.1143)
		(layer "In11.Cu")
		(net "P5E_CPU1_P3_TX_DP<5>")
	)
	(segment
		(start 117.435376 -282.507182)
		(end 117.434868 -282.507182)
		(width 0.1143)
		(layer "In11.Cu")
		(net "P5E_CPU1_P3_TX_DP<5>")
	)
	(segment
		(start 117.751352 -367.717832)
		(end 117.493796 -367.975642)
		(width 0.14224)
		(layer "In11.Cu")
		(net "P5E_CPU1_P3_TX_DP<5>")
	)
	(segment
		(start 117.43182 -284.128972)
		(end 117.430804 -284.12948)
		(width 0.1143)
		(layer "In11.Cu")
		(net "P5E_CPU1_P3_TX_DP<5>")
	)
	(segment
		(start 122.473974 -306.180998)
		(end 129.299208 -314.497466)
		(width 0.14224)
		(layer "In11.Cu")
		(net "P5E_CPU1_P3_TX_DP<5>")
	)
	(segment
		(start 117.430804 -284.12948)
		(end 117.392704 -284.151832)
		(width 0.1143)
		(layer "In11.Cu")
		(net "P5E_CPU1_P3_TX_DP<5>")
	)
	(segment
		(start 134.847838 -324.301104)
		(end 138.141456 -340.860126)
		(width 0.14224)
		(layer "In11.Cu")
		(net "P5E_CPU1_P3_TX_DP<5>")
	)
	(arc
		(start 117.395244 -287.390078)
		(mid 117.214592 -287.592823)
		(end 117.149372 -287.856422)
		(width 0.1143)
		(layer "In11.Cu")
		(net "P5E_CPU1_P3_TX_DP<5>")
	)
	(arc
		(start 117.392704 -293.87165)
		(mid 117.149377 -294.336216)
		(end 117.392704 -294.800782)
		(width 0.1143)
		(layer "In11.Cu")
		(net "P5E_CPU1_P3_TX_DP<5>")
	)
	(arc
		(start 117.435122 -283.48559)
		(mid 117.619855 -283.806282)
		(end 117.435376 -284.127194)
		(width 0.1143)
		(layer "In11.Cu")
		(net "P5E_CPU1_P3_TX_DP<5>")
	)
	(arc
		(start 134.374382 -355.013768)
		(mid 133.459534 -356.725488)
		(end 132.228336 -358.225852)
		(width 0.14224)
		(layer "In11.Cu")
		(net "P5E_CPU1_P3_TX_DP<5>")
	)
	(arc
		(start 129.84353 -360.610658)
		(mid 128.241741 -361.925199)
		(end 126.414276 -362.901992)
		(width 0.14224)
		(layer "In11.Cu")
		(net "P5E_CPU1_P3_TX_DP<5>")
	)
	(arc
		(start 117.435122 -288.345372)
		(mid 117.619855 -288.666064)
		(end 117.435376 -288.986976)
		(width 0.1143)
		(layer "In11.Cu")
		(net "P5E_CPU1_P3_TX_DP<5>")
	)
	(arc
		(start 117.435122 -293.205408)
		(mid 117.619855 -293.5261)
		(end 117.435376 -293.847012)
		(width 0.1143)
		(layer "In11.Cu")
		(net "P5E_CPU1_P3_TX_DP<5>")
	)
	(arc
		(start 117.392704 -282.53182)
		(mid 117.149377 -282.996386)
		(end 117.392704 -283.460952)
		(width 0.1143)
		(layer "In11.Cu")
		(net "P5E_CPU1_P3_TX_DP<5>")
	)
	(arc
		(start 117.392704 -290.631626)
		(mid 117.149377 -291.096192)
		(end 117.392704 -291.560758)
		(width 0.1143)
		(layer "In11.Cu")
		(net "P5E_CPU1_P3_TX_DP<5>")
	)
	(arc
		(start 117.632226 -278.966168)
		(mid 117.704491 -279.236097)
		(end 117.901974 -279.433782)
		(width 0.1143)
		(layer "In11.Cu")
		(net "P5E_CPU1_P3_TX_DP<5>")
	)
	(arc
		(start 117.464586 -294.842946)
		(mid 117.578469 -294.97356)
		(end 117.619526 -295.141904)
		(width 0.1143)
		(layer "In11.Cu")
		(net "P5E_CPU1_P3_TX_DP<5>")
	)
	(arc
		(start 117.619272 -295.146222)
		(mid 117.683787 -295.408441)
		(end 117.862604 -295.610788)
		(width 0.1143)
		(layer "In11.Cu")
		(net "P5E_CPU1_P3_TX_DP<5>")
	)
	(arc
		(start 117.149372 -287.856422)
		(mid 117.213887 -288.118641)
		(end 117.392704 -288.320988)
		(width 0.1143)
		(layer "In11.Cu")
		(net "P5E_CPU1_P3_TX_DP<5>")
	)
	(arc
		(start 117.46865 -291.605462)
		(mid 117.622748 -291.906198)
		(end 117.46865 -292.206934)
		(width 0.1143)
		(layer "In11.Cu")
		(net "P5E_CPU1_P3_TX_DP<5>")
	)
	(arc
		(start 138.141456 -345.047316)
		(mid 138.057185 -345.902336)
		(end 137.8077 -346.724478)
		(width 0.14224)
		(layer "In11.Cu")
		(net "P5E_CPU1_P3_TX_DP<5>")
	)
	(arc
		(start 117.435122 -285.105602)
		(mid 117.619855 -285.426294)
		(end 117.435376 -285.747206)
		(width 0.1143)
		(layer "In11.Cu")
		(net "P5E_CPU1_P3_TX_DP<5>")
	)
	(arc
		(start 117.607588 -280.58618)
		(mid 117.560677 -280.760809)
		(end 117.432582 -280.88844)
		(width 0.1143)
		(layer "In11.Cu")
		(net "P5E_CPU1_P3_TX_DP<5>")
	)
	(arc
		(start 117.447314 -278.632412)
		(mid 117.582702 -278.768361)
		(end 117.632226 -278.953722)
		(width 0.1143)
		(layer "In11.Cu")
		(net "P5E_CPU1_P3_TX_DP<5>")
	)
	(arc
		(start 117.392704 -289.011614)
		(mid 117.149377 -289.47618)
		(end 117.392704 -289.940746)
		(width 0.1143)
		(layer "In11.Cu")
		(net "P5E_CPU1_P3_TX_DP<5>")
	)
	(arc
		(start 118.069106 -279.634696)
		(mid 118.071727 -279.870105)
		(end 117.93347 -280.060654)
		(width 0.1143)
		(layer "In11.Cu")
		(net "P5E_CPU1_P3_TX_DP<5>")
	)
	(arc
		(start 118.023386 -295.743884)
		(mid 118.072706 -295.845013)
		(end 118.08968 -295.956228)
		(width 0.1143)
		(layer "In11.Cu")
		(net "P5E_CPU1_P3_TX_DP<5>")
	)
	(arc
		(start 117.392704 -292.251638)
		(mid 117.149377 -292.716204)
		(end 117.392704 -293.18077)
		(width 0.1143)
		(layer "In11.Cu")
		(net "P5E_CPU1_P3_TX_DP<5>")
	)
	(arc
		(start 117.619526 -287.050734)
		(mid 117.579271 -287.217547)
		(end 117.46738 -287.34766)
		(width 0.1143)
		(layer "In11.Cu")
		(net "P5E_CPU1_P3_TX_DP<5>")
	)
	(arc
		(start 117.435122 -281.865578)
		(mid 117.619855 -282.18627)
		(end 117.435376 -282.507182)
		(width 0.1143)
		(layer "In11.Cu")
		(net "P5E_CPU1_P3_TX_DP<5>")
	)
	(arc
		(start 117.392704 -280.911808)
		(mid 117.149377 -281.376374)
		(end 117.392704 -281.84094)
		(width 0.1143)
		(layer "In11.Cu")
		(net "P5E_CPU1_P3_TX_DP<5>")
	)
	(arc
		(start 117.392704 -284.151832)
		(mid 117.149377 -284.616398)
		(end 117.392704 -285.080964)
		(width 0.1143)
		(layer "In11.Cu")
		(net "P5E_CPU1_P3_TX_DP<5>")
	)
	(arc
		(start 117.493796 -367.975642)
		(mid 117.286047 -368.286561)
		(end 117.213126 -368.653314)
		(width 0.14224)
		(layer "In11.Cu")
		(net "P5E_CPU1_P3_TX_DP<5>")
	)
	(arc
		(start 117.93347 -295.651936)
		(mid 117.982402 -295.694024)
		(end 118.023386 -295.743884)
		(width 0.1143)
		(layer "In11.Cu")
		(net "P5E_CPU1_P3_TX_DP<5>")
	)
	(arc
		(start 117.93347 -279.452324)
		(mid 118.015451 -279.532974)
		(end 118.069106 -279.634696)
		(width 0.1143)
		(layer "In11.Cu")
		(net "P5E_CPU1_P3_TX_DP<5>")
	)
	(arc
		(start 117.465348 -286.743394)
		(mid 117.578755 -286.876283)
		(end 117.619526 -287.046162)
		(width 0.1143)
		(layer "In11.Cu")
		(net "P5E_CPU1_P3_TX_DP<5>")
	)
	(arc
		(start 117.435122 -289.965384)
		(mid 117.619855 -290.286076)
		(end 117.435376 -290.606988)
		(width 0.1143)
		(layer "In11.Cu")
		(net "P5E_CPU1_P3_TX_DP<5>")
	)
	(arc
		(start 117.155468 -278.219154)
		(mid 117.157256 -278.230603)
		(end 117.159278 -278.242014)
		(width 0.1143)
		(layer "In11.Cu")
		(net "P5E_CPU1_P3_TX_DP<5>")
	)
	(arc
		(start 117.888766 -280.086562)
		(mid 117.682907 -280.293063)
		(end 117.607588 -280.57475)
		(width 0.1143)
		(layer "In11.Cu")
		(net "P5E_CPU1_P3_TX_DP<5>")
	)
	(arc
		(start 117.392704 -285.771844)
		(mid 117.149377 -286.23641)
		(end 117.392704 -286.700976)
		(width 0.1143)
		(layer "In11.Cu")
		(net "P5E_CPU1_P3_TX_DP<5>")
	)
	(arc
		(start 117.159278 -278.242014)
		(mid 117.240711 -278.444412)
		(end 117.392704 -278.600916)
		(width 0.1143)
		(layer "In11.Cu")
		(net "P5E_CPU1_P3_TX_DP<5>")
	)
	(segment
		(start 115.491006 -374.93702)
		(end 115.195096 -375.23293)
		(width 0.12954)
		(layer "F.Cu")
		(net "P5E_CPU1_P3_TX_DP<4>")
	)
	(segment
		(start 115.491006 -374.23344)
		(end 115.491006 -374.93702)
		(width 0.12954)
		(layer "F.Cu")
		(net "P5E_CPU1_P3_TX_DP<4>")
	)
	(segment
		(start 116.30787 -279.490424)
		(end 116.774722 -279.756362)
		(width 0.12954)
		(layer "F.Cu")
		(net "P5E_CPU1_P3_TX_DP<4>")
	)
	(segment
		(start 115.220496 -373.96293)
		(end 115.491006 -374.23344)
		(width 0.12954)
		(layer "F.Cu")
		(net "P5E_CPU1_P3_TX_DP<4>")
	)
	(segment
		(start 116.49075 -284.12948)
		(end 116.488464 -284.131004)
		(width 0.1143)
		(layer "In11.Cu")
		(net "P5E_CPU1_P3_TX_DP<4>")
	)
	(segment
		(start 116.491766 -285.748984)
		(end 116.49075 -285.749492)
		(width 0.1143)
		(layer "In11.Cu")
		(net "P5E_CPU1_P3_TX_DP<4>")
	)
	(segment
		(start 116.491766 -281.8638)
		(end 116.492528 -281.864308)
		(width 0.1143)
		(layer "In11.Cu")
		(net "P5E_CPU1_P3_TX_DP<4>")
	)
	(segment
		(start 116.459508 -291.564822)
		(end 116.46027 -291.56533)
		(width 0.1143)
		(layer "In11.Cu")
		(net "P5E_CPU1_P3_TX_DP<4>")
	)
	(segment
		(start 116.46027 -281.845512)
		(end 116.491766 -281.8638)
		(width 0.1143)
		(layer "In11.Cu")
		(net "P5E_CPU1_P3_TX_DP<4>")
	)
	(segment
		(start 116.459508 -289.94481)
		(end 116.46027 -289.945318)
		(width 0.1143)
		(layer "In11.Cu")
		(net "P5E_CPU1_P3_TX_DP<4>")
	)
	(segment
		(start 116.492528 -282.508706)
		(end 116.492528 -282.508452)
		(width 0.1143)
		(layer "In11.Cu")
		(net "P5E_CPU1_P3_TX_DP<4>")
	)
	(segment
		(start 116.923566 -295.61155)
		(end 116.94668 -295.625012)
		(width 0.1143)
		(layer "In11.Cu")
		(net "P5E_CPU1_P3_TX_DP<4>")
	)
	(segment
		(start 117.099334 -297.548554)
		(end 118.404132 -301.84979)
		(width 0.14224)
		(layer "In11.Cu")
		(net "P5E_CPU1_P3_TX_DP<4>")
	)
	(segment
		(start 116.491766 -291.583618)
		(end 116.491766 -291.583364)
		(width 0.1143)
		(layer "In11.Cu")
		(net "P5E_CPU1_P3_TX_DP<4>")
	)
	(segment
		(start 116.492528 -282.508452)
		(end 116.491766 -282.50896)
		(width 0.1143)
		(layer "In11.Cu")
		(net "P5E_CPU1_P3_TX_DP<4>")
	)
	(segment
		(start 116.487194 -282.5115)
		(end 116.48567 -282.512516)
		(width 0.1143)
		(layer "In11.Cu")
		(net "P5E_CPU1_P3_TX_DP<4>")
	)
	(segment
		(start 116.489226 -288.990278)
		(end 116.45265 -289.011614)
		(width 0.1143)
		(layer "In11.Cu")
		(net "P5E_CPU1_P3_TX_DP<4>")
	)
	(segment
		(start 116.50599 -284.120844)
		(end 116.505228 -284.121352)
		(width 0.1143)
		(layer "In11.Cu")
		(net "P5E_CPU1_P3_TX_DP<4>")
	)
	(segment
		(start 116.951252 -295.627806)
		(end 116.952268 -295.628314)
		(width 0.1143)
		(layer "In11.Cu")
		(net "P5E_CPU1_P3_TX_DP<4>")
	)
	(segment
		(start 116.45265 -281.84094)
		(end 116.459508 -281.845004)
		(width 0.1143)
		(layer "In11.Cu")
		(net "P5E_CPU1_P3_TX_DP<4>")
	)
	(segment
		(start 116.491766 -293.203376)
		(end 116.492274 -293.20363)
		(width 0.1143)
		(layer "In11.Cu")
		(net "P5E_CPU1_P3_TX_DP<4>")
	)
	(segment
		(start 117.099334 -296.778934)
		(end 117.099334 -297.548554)
		(width 0.14224)
		(layer "In11.Cu")
		(net "P5E_CPU1_P3_TX_DP<4>")
	)
	(segment
		(start 116.49075 -285.103316)
		(end 116.491766 -285.103824)
		(width 0.1143)
		(layer "In11.Cu")
		(net "P5E_CPU1_P3_TX_DP<4>")
	)
	(segment
		(start 116.491766 -293.849044)
		(end 116.491766 -293.84879)
		(width 0.1143)
		(layer "In11.Cu")
		(net "P5E_CPU1_P3_TX_DP<4>")
	)
	(segment
		(start 116.491766 -289.963606)
		(end 116.491766 -289.963352)
		(width 0.1143)
		(layer "In11.Cu")
		(net "P5E_CPU1_P3_TX_DP<4>")
	)
	(segment
		(start 116.492528 -285.748476)
		(end 116.491766 -285.748984)
		(width 0.1143)
		(layer "In11.Cu")
		(net "P5E_CPU1_P3_TX_DP<4>")
	)
	(segment
		(start 116.49075 -290.609274)
		(end 116.489226 -290.61029)
		(width 0.1143)
		(layer "In11.Cu")
		(net "P5E_CPU1_P3_TX_DP<4>")
	)
	(segment
		(start 116.48567 -282.512516)
		(end 116.4717 -282.520644)
		(width 0.1143)
		(layer "In11.Cu")
		(net "P5E_CPU1_P3_TX_DP<4>")
	)
	(segment
		(start 116.46027 -293.185342)
		(end 116.491766 -293.20363)
		(width 0.1143)
		(layer "In11.Cu")
		(net "P5E_CPU1_P3_TX_DP<4>")
	)
	(segment
		(start 116.487194 -285.101284)
		(end 116.48821 -285.101792)
		(width 0.1143)
		(layer "In11.Cu")
		(net "P5E_CPU1_P3_TX_DP<4>")
	)
	(segment
		(start 116.523516 -280.87066)
		(end 116.45265 -280.911808)
		(width 0.1143)
		(layer "In11.Cu")
		(net "P5E_CPU1_P3_TX_DP<4>")
	)
	(segment
		(start 116.492274 -290.608766)
		(end 116.491766 -290.60902)
		(width 0.1143)
		(layer "In11.Cu")
		(net "P5E_CPU1_P3_TX_DP<4>")
	)
	(segment
		(start 116.49075 -285.749492)
		(end 116.489226 -285.750508)
		(width 0.1143)
		(layer "In11.Cu")
		(net "P5E_CPU1_P3_TX_DP<4>")
	)
	(segment
		(start 118.404132 -301.84979)
		(end 122.0978 -307.377846)
		(width 0.14224)
		(layer "In11.Cu")
		(net "P5E_CPU1_P3_TX_DP<4>")
	)
	(segment
		(start 116.48821 -285.101792)
		(end 116.489988 -285.102808)
		(width 0.1143)
		(layer "In11.Cu")
		(net "P5E_CPU1_P3_TX_DP<4>")
	)
	(segment
		(start 116.961666 -280.078942)
		(end 116.923058 -280.101548)
		(width 0.1143)
		(layer "In11.Cu")
		(net "P5E_CPU1_P3_TX_DP<4>")
	)
	(segment
		(start 116.491766 -289.963352)
		(end 116.492274 -289.963606)
		(width 0.1143)
		(layer "In11.Cu")
		(net "P5E_CPU1_P3_TX_DP<4>")
	)
	(segment
		(start 116.492528 -281.864308)
		(end 116.49456 -281.865578)
		(width 0.1143)
		(layer "In11.Cu")
		(net "P5E_CPU1_P3_TX_DP<4>")
	)
	(segment
		(start 116.993416 -280.060654)
		(end 116.961666 -280.078942)
		(width 0.1143)
		(layer "In11.Cu")
		(net "P5E_CPU1_P3_TX_DP<4>")
	)
	(segment
		(start 116.489734 -283.482542)
		(end 116.490496 -283.48305)
		(width 0.1143)
		(layer "In11.Cu")
		(net "P5E_CPU1_P3_TX_DP<4>")
	)
	(segment
		(start 122.0978 -307.377846)
		(end 129.202688 -316.035436)
		(width 0.14224)
		(layer "In11.Cu")
		(net "P5E_CPU1_P3_TX_DP<4>")
	)
	(segment
		(start 116.49075 -292.229286)
		(end 116.489226 -292.230302)
		(width 0.1143)
		(layer "In11.Cu")
		(net "P5E_CPU1_P3_TX_DP<4>")
	)
	(segment
		(start 116.493036 -283.484574)
		(end 116.50853 -283.493464)
		(width 0.1143)
		(layer "In11.Cu")
		(net "P5E_CPU1_P3_TX_DP<4>")
	)
	(segment
		(start 115.511326 -369.371118)
		(end 115.511326 -373.605298)
		(width 0.14224)
		(layer "In11.Cu")
		(net "P5E_CPU1_P3_TX_DP<4>")
	)
	(segment
		(start 116.491766 -282.50896)
		(end 116.487194 -282.5115)
		(width 0.1143)
		(layer "In11.Cu")
		(net "P5E_CPU1_P3_TX_DP<4>")
	)
	(segment
		(start 116.489226 -292.230302)
		(end 116.45265 -292.251638)
		(width 0.1143)
		(layer "In11.Cu")
		(net "P5E_CPU1_P3_TX_DP<4>")
	)
	(segment
		(start 116.48567 -294.820086)
		(end 116.50218 -294.836596)
		(width 0.1143)
		(layer "In11.Cu")
		(net "P5E_CPU1_P3_TX_DP<4>")
	)
	(segment
		(start 125.523498 -362.21924)
		(end 120.213374 -364.731046)
		(width 0.14224)
		(layer "In11.Cu")
		(net "P5E_CPU1_P3_TX_DP<4>")
	)
	(segment
		(start 116.49075 -288.989262)
		(end 116.489226 -288.990278)
		(width 0.1143)
		(layer "In11.Cu")
		(net "P5E_CPU1_P3_TX_DP<4>")
	)
	(segment
		(start 116.679472 -280.563574)
		(end 116.679472 -280.566368)
		(width 0.1143)
		(layer "In11.Cu")
		(net "P5E_CPU1_P3_TX_DP<4>")
	)
	(segment
		(start 116.49456 -281.865578)
		(end 116.495068 -281.865578)
		(width 0.1143)
		(layer "In11.Cu")
		(net "P5E_CPU1_P3_TX_DP<4>")
	)
	(segment
		(start 116.46027 -291.56533)
		(end 116.491766 -291.583618)
		(width 0.1143)
		(layer "In11.Cu")
		(net "P5E_CPU1_P3_TX_DP<4>")
	)
	(segment
		(start 116.45265 -293.18077)
		(end 116.459508 -293.184834)
		(width 0.1143)
		(layer "In11.Cu")
		(net "P5E_CPU1_P3_TX_DP<4>")
	)
	(segment
		(start 137.191496 -340.912704)
		(end 137.191496 -344.787982)
		(width 0.14224)
		(layer "In11.Cu")
		(net "P5E_CPU1_P3_TX_DP<4>")
	)
	(segment
		(start 117.103906 -296.774362)
		(end 117.099334 -296.778934)
		(width 0.14224)
		(layer "In11.Cu")
		(net "P5E_CPU1_P3_TX_DP<4>")
	)
	(segment
		(start 116.494306 -284.127702)
		(end 116.49075 -284.12948)
		(width 0.1143)
		(layer "In11.Cu")
		(net "P5E_CPU1_P3_TX_DP<4>")
	)
	(segment
		(start 116.491766 -285.103824)
		(end 116.492528 -285.104332)
		(width 0.1143)
		(layer "In11.Cu")
		(net "P5E_CPU1_P3_TX_DP<4>")
	)
	(segment
		(start 116.509292 -284.118812)
		(end 116.50599 -284.120844)
		(width 0.1143)
		(layer "In11.Cu")
		(net "P5E_CPU1_P3_TX_DP<4>")
	)
	(segment
		(start 136.89203 -346.292678)
		(end 133.623558 -354.183696)
		(width 0.14224)
		(layer "In11.Cu")
		(net "P5E_CPU1_P3_TX_DP<4>")
	)
	(segment
		(start 116.491766 -290.60902)
		(end 116.491766 -290.608766)
		(width 0.1143)
		(layer "In11.Cu")
		(net "P5E_CPU1_P3_TX_DP<4>")
	)
	(segment
		(start 116.48694 -288.340546)
		(end 116.487702 -288.341054)
		(width 0.1143)
		(layer "In11.Cu")
		(net "P5E_CPU1_P3_TX_DP<4>")
	)
	(segment
		(start 116.492274 -283.484066)
		(end 116.493036 -283.484574)
		(width 0.1143)
		(layer "In11.Cu")
		(net "P5E_CPU1_P3_TX_DP<4>")
	)
	(segment
		(start 116.510562 -284.118304)
		(end 116.510054 -284.118304)
		(width 0.1143)
		(layer "In11.Cu")
		(net "P5E_CPU1_P3_TX_DP<4>")
	)
	(segment
		(start 134.062724 -325.181214)
		(end 137.191496 -340.912704)
		(width 0.14224)
		(layer "In11.Cu")
		(net "P5E_CPU1_P3_TX_DP<4>")
	)
	(segment
		(start 116.491766 -293.20363)
		(end 116.491766 -293.203376)
		(width 0.1143)
		(layer "In11.Cu")
		(net "P5E_CPU1_P3_TX_DP<4>")
	)
	(segment
		(start 116.493036 -288.988246)
		(end 116.491766 -288.988754)
		(width 0.1143)
		(layer "In11.Cu")
		(net "P5E_CPU1_P3_TX_DP<4>")
	)
	(segment
		(start 116.495322 -282.507182)
		(end 116.494814 -282.507182)
		(width 0.1143)
		(layer "In11.Cu")
		(net "P5E_CPU1_P3_TX_DP<4>")
	)
	(segment
		(start 116.491766 -293.84879)
		(end 116.49075 -293.849298)
		(width 0.1143)
		(layer "In11.Cu")
		(net "P5E_CPU1_P3_TX_DP<4>")
	)
	(segment
		(start 116.491766 -292.228778)
		(end 116.49075 -292.229286)
		(width 0.1143)
		(layer "In11.Cu")
		(net "P5E_CPU1_P3_TX_DP<4>")
	)
	(segment
		(start 117.103906 -296.418762)
		(end 117.103906 -296.44721)
		(width 0.1143)
		(layer "In11.Cu")
		(net "P5E_CPU1_P3_TX_DP<4>")
	)
	(segment
		(start 116.94668 -295.625012)
		(end 116.951252 -295.627806)
		(width 0.1143)
		(layer "In11.Cu")
		(net "P5E_CPU1_P3_TX_DP<4>")
	)
	(segment
		(start 116.489226 -293.850314)
		(end 116.487956 -293.851076)
		(width 0.1143)
		(layer "In11.Cu")
		(net "P5E_CPU1_P3_TX_DP<4>")
	)
	(segment
		(start 117.103906 -296.44721)
		(end 117.103906 -296.774362)
		(width 0.14224)
		(layer "In11.Cu")
		(net "P5E_CPU1_P3_TX_DP<4>")
	)
	(segment
		(start 116.45265 -289.940746)
		(end 116.459508 -289.94481)
		(width 0.1143)
		(layer "In11.Cu")
		(net "P5E_CPU1_P3_TX_DP<4>")
	)
	(segment
		(start 116.491766 -291.583364)
		(end 116.492274 -291.583618)
		(width 0.1143)
		(layer "In11.Cu")
		(net "P5E_CPU1_P3_TX_DP<4>")
	)
	(segment
		(start 131.082288 -357.987346)
		(end 130.010916 -359.058718)
		(width 0.14224)
		(layer "In11.Cu")
		(net "P5E_CPU1_P3_TX_DP<4>")
	)
	(segment
		(start 116.494814 -282.507182)
		(end 116.492528 -282.508706)
		(width 0.1143)
		(layer "In11.Cu")
		(net "P5E_CPU1_P3_TX_DP<4>")
	)
	(segment
		(start 117.149626 -295.956228)
		(end 117.149626 -296.373042)
		(width 0.1143)
		(layer "In11.Cu")
		(net "P5E_CPU1_P3_TX_DP<4>")
	)
	(segment
		(start 116.510054 -284.118304)
		(end 116.509292 -284.118812)
		(width 0.1143)
		(layer "In11.Cu")
		(net "P5E_CPU1_P3_TX_DP<4>")
	)
	(segment
		(start 116.492274 -286.723582)
		(end 116.520976 -286.740346)
		(width 0.1143)
		(layer "In11.Cu")
		(net "P5E_CPU1_P3_TX_DP<4>")
	)
	(segment
		(start 116.492274 -293.84879)
		(end 116.491766 -293.849044)
		(width 0.1143)
		(layer "In11.Cu")
		(net "P5E_CPU1_P3_TX_DP<4>")
	)
	(segment
		(start 116.491766 -292.229032)
		(end 116.491766 -292.228778)
		(width 0.1143)
		(layer "In11.Cu")
		(net "P5E_CPU1_P3_TX_DP<4>")
	)
	(segment
		(start 116.491766 -288.343594)
		(end 116.492782 -288.344102)
		(width 0.1143)
		(layer "In11.Cu")
		(net "P5E_CPU1_P3_TX_DP<4>")
	)
	(segment
		(start 115.464082 -373.719344)
		(end 115.220496 -373.96293)
		(width 0.14224)
		(layer "In11.Cu")
		(net "P5E_CPU1_P3_TX_DP<4>")
	)
	(segment
		(start 116.45265 -291.560758)
		(end 116.459508 -291.564822)
		(width 0.1143)
		(layer "In11.Cu")
		(net "P5E_CPU1_P3_TX_DP<4>")
	)
	(segment
		(start 116.523516 -285.730696)
		(end 116.492528 -285.748476)
		(width 0.1143)
		(layer "In11.Cu")
		(net "P5E_CPU1_P3_TX_DP<4>")
	)
	(segment
		(start 116.50853 -283.493464)
		(end 116.510054 -283.49448)
		(width 0.1143)
		(layer "In11.Cu")
		(net "P5E_CPU1_P3_TX_DP<4>")
	)
	(segment
		(start 116.470684 -283.47162)
		(end 116.489734 -283.482542)
		(width 0.1143)
		(layer "In11.Cu")
		(net "P5E_CPU1_P3_TX_DP<4>")
	)
	(segment
		(start 116.458238 -288.323782)
		(end 116.48694 -288.340546)
		(width 0.1143)
		(layer "In11.Cu")
		(net "P5E_CPU1_P3_TX_DP<4>")
	)
	(segment
		(start 116.50218 -294.836596)
		(end 116.511832 -294.836596)
		(width 0.1143)
		(layer "In11.Cu")
		(net "P5E_CPU1_P3_TX_DP<4>")
	)
	(segment
		(start 116.487702 -288.341054)
		(end 116.491766 -288.343594)
		(width 0.1143)
		(layer "In11.Cu")
		(net "P5E_CPU1_P3_TX_DP<4>")
	)
	(segment
		(start 116.489988 -285.102808)
		(end 116.49075 -285.103316)
		(width 0.1143)
		(layer "In11.Cu")
		(net "P5E_CPU1_P3_TX_DP<4>")
	)
	(segment
		(start 132.340096 -320.730626)
		(end 134.062724 -325.181214)
		(width 0.14224)
		(layer "In11.Cu")
		(net "P5E_CPU1_P3_TX_DP<4>")
	)
	(segment
		(start 116.492274 -292.228778)
		(end 116.491766 -292.229032)
		(width 0.1143)
		(layer "In11.Cu")
		(net "P5E_CPU1_P3_TX_DP<4>")
	)
	(segment
		(start 116.491766 -290.608766)
		(end 116.49075 -290.609274)
		(width 0.1143)
		(layer "In11.Cu")
		(net "P5E_CPU1_P3_TX_DP<4>")
	)
	(segment
		(start 116.489226 -285.750508)
		(end 116.45265 -285.771844)
		(width 0.1143)
		(layer "In11.Cu")
		(net "P5E_CPU1_P3_TX_DP<4>")
	)
	(segment
		(start 116.774722 -279.756362)
		(end 117.072664 -279.756362)
		(width 0.1143)
		(layer "In11.Cu")
		(net "P5E_CPU1_P3_TX_DP<4>")
	)
	(segment
		(start 116.510054 -283.49448)
		(end 116.510308 -283.49448)
		(width 0.1143)
		(layer "In11.Cu")
		(net "P5E_CPU1_P3_TX_DP<4>")
	)
	(segment
		(start 116.49075 -293.849298)
		(end 116.489226 -293.850314)
		(width 0.1143)
		(layer "In11.Cu")
		(net "P5E_CPU1_P3_TX_DP<4>")
	)
	(segment
		(start 116.459508 -281.845004)
		(end 116.46027 -281.845512)
		(width 0.1143)
		(layer "In11.Cu")
		(net "P5E_CPU1_P3_TX_DP<4>")
	)
	(segment
		(start 117.149626 -296.373042)
		(end 117.103906 -296.418762)
		(width 0.1143)
		(layer "In11.Cu")
		(net "P5E_CPU1_P3_TX_DP<4>")
	)
	(segment
		(start 116.491766 -288.988754)
		(end 116.49075 -288.989262)
		(width 0.1143)
		(layer "In11.Cu")
		(net "P5E_CPU1_P3_TX_DP<4>")
	)
	(segment
		(start 120.100344 -364.787942)
		(end 117.38737 -366.239552)
		(width 0.14224)
		(layer "In11.Cu")
		(net "P5E_CPU1_P3_TX_DP<4>")
	)
	(segment
		(start 117.072664 -279.756362)
		(end 117.142514 -279.826212)
		(width 0.1143)
		(layer "In11.Cu")
		(net "P5E_CPU1_P3_TX_DP<4>")
	)
	(segment
		(start 116.952268 -295.628314)
		(end 116.993416 -295.651936)
		(width 0.1143)
		(layer "In11.Cu")
		(net "P5E_CPU1_P3_TX_DP<4>")
	)
	(segment
		(start 116.505228 -284.121352)
		(end 116.494306 -284.127702)
		(width 0.1143)
		(layer "In11.Cu")
		(net "P5E_CPU1_P3_TX_DP<4>")
	)
	(segment
		(start 116.489226 -290.61029)
		(end 116.45265 -290.631626)
		(width 0.1143)
		(layer "In11.Cu")
		(net "P5E_CPU1_P3_TX_DP<4>")
	)
	(segment
		(start 116.459508 -293.184834)
		(end 116.46027 -293.185342)
		(width 0.1143)
		(layer "In11.Cu")
		(net "P5E_CPU1_P3_TX_DP<4>")
	)
	(segment
		(start 129.202688 -316.035436)
		(end 132.340096 -320.730626)
		(width 0.14224)
		(layer "In11.Cu")
		(net "P5E_CPU1_P3_TX_DP<4>")
	)
	(segment
		(start 116.51234 -287.356804)
		(end 116.45519 -287.390078)
		(width 0.1143)
		(layer "In11.Cu")
		(net "P5E_CPU1_P3_TX_DP<4>")
	)
	(segment
		(start 116.45265 -288.320988)
		(end 116.458238 -288.323782)
		(width 0.1143)
		(layer "In11.Cu")
		(net "P5E_CPU1_P3_TX_DP<4>")
	)
	(segment
		(start 116.492528 -285.104332)
		(end 116.523516 -285.122112)
		(width 0.1143)
		(layer "In11.Cu")
		(net "P5E_CPU1_P3_TX_DP<4>")
	)
	(segment
		(start 116.490496 -283.48305)
		(end 116.492274 -283.484066)
		(width 0.1143)
		(layer "In11.Cu")
		(net "P5E_CPU1_P3_TX_DP<4>")
	)
	(segment
		(start 116.46027 -289.945318)
		(end 116.491766 -289.963606)
		(width 0.1143)
		(layer "In11.Cu")
		(net "P5E_CPU1_P3_TX_DP<4>")
	)
	(segment
		(start 116.45265 -286.700976)
		(end 116.492274 -286.723582)
		(width 0.1143)
		(layer "In11.Cu")
		(net "P5E_CPU1_P3_TX_DP<4>")
	)
	(arc
		(start 116.679472 -295.146222)
		(mid 116.744194 -295.408961)
		(end 116.923566 -295.61155)
		(width 0.1143)
		(layer "In11.Cu")
		(net "P5E_CPU1_P3_TX_DP<4>")
	)
	(arc
		(start 116.492782 -288.344102)
		(mid 116.678234 -288.666064)
		(end 116.493036 -288.988246)
		(width 0.1143)
		(layer "In11.Cu")
		(net "P5E_CPU1_P3_TX_DP<4>")
	)
	(arc
		(start 116.45265 -289.011614)
		(mid 116.209323 -289.47618)
		(end 116.45265 -289.940746)
		(width 0.1143)
		(layer "In11.Cu")
		(net "P5E_CPU1_P3_TX_DP<4>")
	)
	(arc
		(start 116.523516 -285.122112)
		(mid 116.673901 -285.426404)
		(end 116.523516 -285.730696)
		(width 0.1143)
		(layer "In11.Cu")
		(net "P5E_CPU1_P3_TX_DP<4>")
	)
	(arc
		(start 116.510308 -283.49448)
		(mid 116.689882 -283.806282)
		(end 116.510562 -284.118304)
		(width 0.1143)
		(layer "In11.Cu")
		(net "P5E_CPU1_P3_TX_DP<4>")
	)
	(arc
		(start 133.623558 -354.183696)
		(mid 132.540216 -356.21065)
		(end 131.082288 -357.987346)
		(width 0.14224)
		(layer "In11.Cu")
		(net "P5E_CPU1_P3_TX_DP<4>")
	)
	(arc
		(start 116.520976 -286.740346)
		(mid 116.522885 -286.741737)
		(end 116.524786 -286.74314)
		(width 0.1143)
		(layer "In11.Cu")
		(net "P5E_CPU1_P3_TX_DP<4>")
	)
	(arc
		(start 116.209318 -287.856422)
		(mid 116.273833 -288.118641)
		(end 116.45265 -288.320988)
		(width 0.1143)
		(layer "In11.Cu")
		(net "P5E_CPU1_P3_TX_DP<4>")
	)
	(arc
		(start 116.45265 -292.251638)
		(mid 116.209323 -292.716204)
		(end 116.45265 -293.18077)
		(width 0.1143)
		(layer "In11.Cu")
		(net "P5E_CPU1_P3_TX_DP<4>")
	)
	(arc
		(start 137.191496 -344.787982)
		(mid 137.115881 -345.555082)
		(end 136.89203 -346.292678)
		(width 0.14224)
		(layer "In11.Cu")
		(net "P5E_CPU1_P3_TX_DP<4>")
	)
	(arc
		(start 116.45519 -287.390078)
		(mid 116.274538 -287.592823)
		(end 116.209318 -287.856422)
		(width 0.1143)
		(layer "In11.Cu")
		(net "P5E_CPU1_P3_TX_DP<4>")
	)
	(arc
		(start 116.495068 -281.865578)
		(mid 116.679801 -282.18627)
		(end 116.495322 -282.507182)
		(width 0.1143)
		(layer "In11.Cu")
		(net "P5E_CPU1_P3_TX_DP<4>")
	)
	(arc
		(start 116.492274 -289.963606)
		(mid 116.677912 -290.286186)
		(end 116.492274 -290.608766)
		(width 0.1143)
		(layer "In11.Cu")
		(net "P5E_CPU1_P3_TX_DP<4>")
	)
	(arc
		(start 117.38737 -366.239552)
		(mid 116.016222 -367.545861)
		(end 115.511326 -369.371118)
		(width 0.14224)
		(layer "In11.Cu")
		(net "P5E_CPU1_P3_TX_DP<4>")
	)
	(arc
		(start 116.45265 -290.631626)
		(mid 116.209323 -291.096192)
		(end 116.45265 -291.560758)
		(width 0.1143)
		(layer "In11.Cu")
		(net "P5E_CPU1_P3_TX_DP<4>")
	)
	(arc
		(start 116.679218 -287.036002)
		(mid 116.626394 -287.212318)
		(end 116.51234 -287.356804)
		(width 0.1143)
		(layer "In11.Cu")
		(net "P5E_CPU1_P3_TX_DP<4>")
	)
	(arc
		(start 116.45265 -280.911808)
		(mid 116.209323 -281.376374)
		(end 116.45265 -281.84094)
		(width 0.1143)
		(layer "In11.Cu")
		(net "P5E_CPU1_P3_TX_DP<4>")
	)
	(arc
		(start 115.511326 -373.605298)
		(mid 115.499049 -373.667021)
		(end 115.464082 -373.719344)
		(width 0.14224)
		(layer "In11.Cu")
		(net "P5E_CPU1_P3_TX_DP<4>")
	)
	(arc
		(start 120.213374 -364.731046)
		(mid 120.156508 -364.758797)
		(end 120.100344 -364.787942)
		(width 0.14224)
		(layer "In11.Cu")
		(net "P5E_CPU1_P3_TX_DP<4>")
	)
	(arc
		(start 117.142514 -279.826212)
		(mid 117.090465 -279.957731)
		(end 116.993416 -280.060654)
		(width 0.1143)
		(layer "In11.Cu")
		(net "P5E_CPU1_P3_TX_DP<4>")
	)
	(arc
		(start 116.511832 -294.836596)
		(mid 116.63485 -294.970182)
		(end 116.679472 -295.146222)
		(width 0.1143)
		(layer "In11.Cu")
		(net "P5E_CPU1_P3_TX_DP<4>")
	)
	(arc
		(start 116.993416 -295.651936)
		(mid 117.042348 -295.694024)
		(end 117.083332 -295.743884)
		(width 0.1143)
		(layer "In11.Cu")
		(net "P5E_CPU1_P3_TX_DP<4>")
	)
	(arc
		(start 116.679472 -280.566368)
		(mid 116.638217 -280.737339)
		(end 116.523516 -280.87066)
		(width 0.1143)
		(layer "In11.Cu")
		(net "P5E_CPU1_P3_TX_DP<4>")
	)
	(arc
		(start 117.083332 -295.743884)
		(mid 117.132652 -295.845013)
		(end 117.149626 -295.956228)
		(width 0.1143)
		(layer "In11.Cu")
		(net "P5E_CPU1_P3_TX_DP<4>")
	)
	(arc
		(start 130.010916 -359.058718)
		(mid 127.903279 -360.83218)
		(end 125.523498 -362.21924)
		(width 0.14224)
		(layer "In11.Cu")
		(net "P5E_CPU1_P3_TX_DP<4>")
	)
	(arc
		(start 116.923058 -280.101548)
		(mid 116.744128 -280.302432)
		(end 116.679472 -280.563574)
		(width 0.1143)
		(layer "In11.Cu")
		(net "P5E_CPU1_P3_TX_DP<4>")
	)
	(arc
		(start 116.492274 -291.583618)
		(mid 116.677912 -291.906198)
		(end 116.492274 -292.228778)
		(width 0.1143)
		(layer "In11.Cu")
		(net "P5E_CPU1_P3_TX_DP<4>")
	)
	(arc
		(start 116.45265 -285.771844)
		(mid 116.209323 -286.23641)
		(end 116.45265 -286.700976)
		(width 0.1143)
		(layer "In11.Cu")
		(net "P5E_CPU1_P3_TX_DP<4>")
	)
	(arc
		(start 116.492274 -293.20363)
		(mid 116.677912 -293.52621)
		(end 116.492274 -293.84879)
		(width 0.1143)
		(layer "In11.Cu")
		(net "P5E_CPU1_P3_TX_DP<4>")
	)
	(arc
		(start 116.4717 -282.520644)
		(mid 116.198627 -282.995819)
		(end 116.470684 -283.47162)
		(width 0.1143)
		(layer "In11.Cu")
		(net "P5E_CPU1_P3_TX_DP<4>")
	)
	(arc
		(start 116.524786 -286.74314)
		(mid 116.636224 -286.871541)
		(end 116.679218 -287.036002)
		(width 0.1143)
		(layer "In11.Cu")
		(net "P5E_CPU1_P3_TX_DP<4>")
	)
	(arc
		(start 116.488464 -284.131004)
		(mid 116.2097 -284.615722)
		(end 116.487194 -285.101284)
		(width 0.1143)
		(layer "In11.Cu")
		(net "P5E_CPU1_P3_TX_DP<4>")
	)
	(arc
		(start 116.487956 -293.851076)
		(mid 116.209412 -294.334909)
		(end 116.48567 -294.820086)
		(width 0.1143)
		(layer "In11.Cu")
		(net "P5E_CPU1_P3_TX_DP<4>")
	)
	(segment
		(start 116.30787 -274.630388)
		(end 116.774722 -274.896326)
		(width 0.12954)
		(layer "F.Cu")
		(net "P5E_CPU1_P3_TX_DP<3>")
	)
	(segment
		(start 112.087406 -369.30584)
		(end 112.087406 -370.00942)
		(width 0.12954)
		(layer "F.Cu")
		(net "P5E_CPU1_P3_TX_DP<3>")
	)
	(segment
		(start 112.087406 -370.00942)
		(end 111.791496 -370.30533)
		(width 0.12954)
		(layer "F.Cu")
		(net "P5E_CPU1_P3_TX_DP<3>")
	)
	(segment
		(start 111.816896 -369.03533)
		(end 112.087406 -369.30584)
		(width 0.12954)
		(layer "F.Cu")
		(net "P5E_CPU1_P3_TX_DP<3>")
	)
	(segment
		(start 116.209572 -296.373042)
		(end 116.163852 -296.418762)
		(width 0.1143)
		(layer "In11.Cu")
		(net "P5E_CPU1_P3_TX_DP<3>")
	)
	(segment
		(start 115.552474 -283.48432)
		(end 115.553744 -283.485082)
		(width 0.1143)
		(layer "In11.Cu")
		(net "P5E_CPU1_P3_TX_DP<3>")
	)
	(segment
		(start 115.520216 -291.56533)
		(end 115.551712 -291.583618)
		(width 0.1143)
		(layer "In11.Cu")
		(net "P5E_CPU1_P3_TX_DP<3>")
	)
	(segment
		(start 115.519454 -285.085028)
		(end 115.520216 -285.085536)
		(width 0.1143)
		(layer "In11.Cu")
		(net "P5E_CPU1_P3_TX_DP<3>")
	)
	(segment
		(start 115.552474 -293.204138)
		(end 115.553744 -293.2049)
		(width 0.1143)
		(layer "In11.Cu")
		(net "P5E_CPU1_P3_TX_DP<3>")
	)
	(segment
		(start 124.723906 -361.534964)
		(end 116.22659 -365.55426)
		(width 0.14224)
		(layer "In11.Cu")
		(net "P5E_CPU1_P3_TX_DP<3>")
	)
	(segment
		(start 115.550696 -293.849298)
		(end 115.549172 -293.850314)
		(width 0.1143)
		(layer "In11.Cu")
		(net "P5E_CPU1_P3_TX_DP<3>")
	)
	(segment
		(start 115.583462 -285.730696)
		(end 115.552474 -285.748476)
		(width 0.1143)
		(layer "In11.Cu")
		(net "P5E_CPU1_P3_TX_DP<3>")
	)
	(segment
		(start 136.258808 -341.298022)
		(end 136.258808 -344.477594)
		(width 0.14224)
		(layer "In11.Cu")
		(net "P5E_CPU1_P3_TX_DP<3>")
	)
	(segment
		(start 115.551712 -290.608766)
		(end 115.550696 -290.609274)
		(width 0.1143)
		(layer "In11.Cu")
		(net "P5E_CPU1_P3_TX_DP<3>")
	)
	(segment
		(start 115.551712 -283.483812)
		(end 115.552474 -283.48432)
		(width 0.1143)
		(layer "In11.Cu")
		(net "P5E_CPU1_P3_TX_DP<3>")
	)
	(segment
		(start 115.519454 -293.184834)
		(end 115.520216 -293.185342)
		(width 0.1143)
		(layer "In11.Cu")
		(net "P5E_CPU1_P3_TX_DP<3>")
	)
	(segment
		(start 115.552474 -285.104332)
		(end 115.553744 -285.105094)
		(width 0.1143)
		(layer "In11.Cu")
		(net "P5E_CPU1_P3_TX_DP<3>")
	)
	(segment
		(start 115.512596 -281.84094)
		(end 115.519454 -281.845004)
		(width 0.1143)
		(layer "In11.Cu")
		(net "P5E_CPU1_P3_TX_DP<3>")
	)
	(segment
		(start 115.549172 -293.850314)
		(end 115.512596 -293.87165)
		(width 0.1143)
		(layer "In11.Cu")
		(net "P5E_CPU1_P3_TX_DP<3>")
	)
	(segment
		(start 115.552474 -282.508452)
		(end 115.551712 -282.50896)
		(width 0.1143)
		(layer "In11.Cu")
		(net "P5E_CPU1_P3_TX_DP<3>")
	)
	(segment
		(start 112.107726 -368.7445)
		(end 111.816896 -369.03533)
		(width 0.14224)
		(layer "In11.Cu")
		(net "P5E_CPU1_P3_TX_DP<3>")
	)
	(segment
		(start 115.98275 -279.410922)
		(end 116.021866 -279.433782)
		(width 0.1143)
		(layer "In11.Cu")
		(net "P5E_CPU1_P3_TX_DP<3>")
	)
	(segment
		(start 115.550696 -280.889456)
		(end 115.549172 -280.890472)
		(width 0.1143)
		(layer "In11.Cu")
		(net "P5E_CPU1_P3_TX_DP<3>")
	)
	(segment
		(start 116.052346 -278.44115)
		(end 116.021866 -278.45893)
		(width 0.1143)
		(layer "In11.Cu")
		(net "P5E_CPU1_P3_TX_DP<3>")
	)
	(segment
		(start 128.53289 -316.711076)
		(end 131.217162 -320.72834)
		(width 0.14224)
		(layer "In11.Cu")
		(net "P5E_CPU1_P3_TX_DP<3>")
	)
	(segment
		(start 112.107726 -368.174016)
		(end 112.107726 -368.7445)
		(width 0.14224)
		(layer "In11.Cu")
		(net "P5E_CPU1_P3_TX_DP<3>")
	)
	(segment
		(start 115.512596 -291.560758)
		(end 115.519454 -291.564822)
		(width 0.1143)
		(layer "In11.Cu")
		(net "P5E_CPU1_P3_TX_DP<3>")
	)
	(segment
		(start 116.014754 -277.809452)
		(end 116.053362 -277.832312)
		(width 0.1143)
		(layer "In11.Cu")
		(net "P5E_CPU1_P3_TX_DP<3>")
	)
	(segment
		(start 115.520216 -285.085536)
		(end 115.551712 -285.103824)
		(width 0.1143)
		(layer "In11.Cu")
		(net "P5E_CPU1_P3_TX_DP<3>")
	)
	(segment
		(start 115.553744 -285.105094)
		(end 115.583462 -285.122112)
		(width 0.1143)
		(layer "In11.Cu")
		(net "P5E_CPU1_P3_TX_DP<3>")
	)
	(segment
		(start 115.520216 -283.465524)
		(end 115.551712 -283.483812)
		(width 0.1143)
		(layer "In11.Cu")
		(net "P5E_CPU1_P3_TX_DP<3>")
	)
	(segment
		(start 116.993416 -275.200618)
		(end 116.95938 -275.22043)
		(width 0.1143)
		(layer "In11.Cu")
		(net "P5E_CPU1_P3_TX_DP<3>")
	)
	(segment
		(start 116.163852 -297.056302)
		(end 116.164614 -297.056302)
		(width 0.14224)
		(layer "In11.Cu")
		(net "P5E_CPU1_P3_TX_DP<3>")
	)
	(segment
		(start 115.583462 -293.830502)
		(end 115.552474 -293.848282)
		(width 0.1143)
		(layer "In11.Cu")
		(net "P5E_CPU1_P3_TX_DP<3>")
	)
	(segment
		(start 115.583462 -288.970466)
		(end 115.552474 -288.988246)
		(width 0.1143)
		(layer "In11.Cu")
		(net "P5E_CPU1_P3_TX_DP<3>")
	)
	(segment
		(start 115.98275 -295.610788)
		(end 116.052346 -295.651428)
		(width 0.1143)
		(layer "In11.Cu")
		(net "P5E_CPU1_P3_TX_DP<3>")
	)
	(segment
		(start 115.549172 -280.890472)
		(end 115.512596 -280.911808)
		(width 0.1143)
		(layer "In11.Cu")
		(net "P5E_CPU1_P3_TX_DP<3>")
	)
	(segment
		(start 115.519454 -283.465016)
		(end 115.520216 -283.465524)
		(width 0.1143)
		(layer "In11.Cu")
		(net "P5E_CPU1_P3_TX_DP<3>")
	)
	(segment
		(start 115.512596 -288.320988)
		(end 115.551712 -288.343848)
		(width 0.1143)
		(layer "In11.Cu")
		(net "P5E_CPU1_P3_TX_DP<3>")
	)
	(segment
		(start 116.163852 -296.44721)
		(end 116.163852 -297.056302)
		(width 0.14224)
		(layer "In11.Cu")
		(net "P5E_CPU1_P3_TX_DP<3>")
	)
	(segment
		(start 115.551712 -289.963606)
		(end 115.552474 -289.964114)
		(width 0.1143)
		(layer "In11.Cu")
		(net "P5E_CPU1_P3_TX_DP<3>")
	)
	(segment
		(start 113.993168 -366.747806)
		(end 113.22685 -367.207546)
		(width 0.14224)
		(layer "In11.Cu")
		(net "P5E_CPU1_P3_TX_DP<3>")
	)
	(segment
		(start 115.550696 -282.509468)
		(end 115.549172 -282.510484)
		(width 0.1143)
		(layer "In11.Cu")
		(net "P5E_CPU1_P3_TX_DP<3>")
	)
	(segment
		(start 115.553744 -283.485082)
		(end 115.583462 -283.5021)
		(width 0.1143)
		(layer "In11.Cu")
		(net "P5E_CPU1_P3_TX_DP<3>")
	)
	(segment
		(start 116.524024 -276.005036)
		(end 116.452904 -276.046184)
		(width 0.1143)
		(layer "In11.Cu")
		(net "P5E_CPU1_P3_TX_DP<3>")
	)
	(segment
		(start 115.552474 -285.748476)
		(end 115.551712 -285.748984)
		(width 0.1143)
		(layer "In11.Cu")
		(net "P5E_CPU1_P3_TX_DP<3>")
	)
	(segment
		(start 116.22659 -365.55426)
		(end 113.993168 -366.747806)
		(width 0.14224)
		(layer "In11.Cu")
		(net "P5E_CPU1_P3_TX_DP<3>")
	)
	(segment
		(start 115.512596 -289.940746)
		(end 115.550696 -289.963098)
		(width 0.1143)
		(layer "In11.Cu")
		(net "P5E_CPU1_P3_TX_DP<3>")
	)
	(segment
		(start 116.021866 -278.45893)
		(end 115.98275 -278.48179)
		(width 0.1143)
		(layer "In11.Cu")
		(net "P5E_CPU1_P3_TX_DP<3>")
	)
	(segment
		(start 115.512596 -283.460952)
		(end 115.519454 -283.465016)
		(width 0.1143)
		(layer "In11.Cu")
		(net "P5E_CPU1_P3_TX_DP<3>")
	)
	(segment
		(start 116.054378 -276.814534)
		(end 115.981226 -276.857714)
		(width 0.1143)
		(layer "In11.Cu")
		(net "P5E_CPU1_P3_TX_DP<3>")
	)
	(segment
		(start 115.550696 -289.963098)
		(end 115.551712 -289.963606)
		(width 0.1143)
		(layer "In11.Cu")
		(net "P5E_CPU1_P3_TX_DP<3>")
	)
	(segment
		(start 115.553744 -294.824912)
		(end 115.583462 -294.84193)
		(width 0.1143)
		(layer "In11.Cu")
		(net "P5E_CPU1_P3_TX_DP<3>")
	)
	(segment
		(start 115.551712 -285.103824)
		(end 115.552474 -285.104332)
		(width 0.1143)
		(layer "In11.Cu")
		(net "P5E_CPU1_P3_TX_DP<3>")
	)
	(segment
		(start 115.551712 -284.128972)
		(end 115.550696 -284.12948)
		(width 0.1143)
		(layer "In11.Cu")
		(net "P5E_CPU1_P3_TX_DP<3>")
	)
	(segment
		(start 115.551712 -288.343848)
		(end 115.58524 -288.363406)
		(width 0.1143)
		(layer "In11.Cu")
		(net "P5E_CPU1_P3_TX_DP<3>")
	)
	(segment
		(start 115.520216 -294.805354)
		(end 115.551712 -294.823642)
		(width 0.1143)
		(layer "In11.Cu")
		(net "P5E_CPU1_P3_TX_DP<3>")
	)
	(segment
		(start 115.552474 -281.864308)
		(end 115.553744 -281.86507)
		(width 0.1143)
		(layer "In11.Cu")
		(net "P5E_CPU1_P3_TX_DP<3>")
	)
	(segment
		(start 115.520216 -281.845512)
		(end 115.551712 -281.8638)
		(width 0.1143)
		(layer "In11.Cu")
		(net "P5E_CPU1_P3_TX_DP<3>")
	)
	(segment
		(start 115.552474 -290.608258)
		(end 115.551712 -290.608766)
		(width 0.1143)
		(layer "In11.Cu")
		(net "P5E_CPU1_P3_TX_DP<3>")
	)
	(segment
		(start 115.550696 -288.989262)
		(end 115.549172 -288.990278)
		(width 0.1143)
		(layer "In11.Cu")
		(net "P5E_CPU1_P3_TX_DP<3>")
	)
	(segment
		(start 115.583462 -282.490672)
		(end 115.552474 -282.508452)
		(width 0.1143)
		(layer "In11.Cu")
		(net "P5E_CPU1_P3_TX_DP<3>")
	)
	(segment
		(start 115.512596 -286.700976)
		(end 115.551712 -286.723836)
		(width 0.1143)
		(layer "In11.Cu")
		(net "P5E_CPU1_P3_TX_DP<3>")
	)
	(segment
		(start 115.551712 -294.823642)
		(end 115.552474 -294.82415)
		(width 0.1143)
		(layer "In11.Cu")
		(net "P5E_CPU1_P3_TX_DP<3>")
	)
	(segment
		(start 115.549172 -292.230302)
		(end 115.512596 -292.251638)
		(width 0.1143)
		(layer "In11.Cu")
		(net "P5E_CPU1_P3_TX_DP<3>")
	)
	(segment
		(start 115.551712 -292.228778)
		(end 115.550696 -292.229286)
		(width 0.1143)
		(layer "In11.Cu")
		(net "P5E_CPU1_P3_TX_DP<3>")
	)
	(segment
		(start 115.512596 -294.800782)
		(end 115.519454 -294.804846)
		(width 0.1143)
		(layer "In11.Cu")
		(net "P5E_CPU1_P3_TX_DP<3>")
	)
	(segment
		(start 115.552474 -293.848282)
		(end 115.551712 -293.84879)
		(width 0.1143)
		(layer "In11.Cu")
		(net "P5E_CPU1_P3_TX_DP<3>")
	)
	(segment
		(start 115.519454 -294.804846)
		(end 115.520216 -294.805354)
		(width 0.1143)
		(layer "In11.Cu")
		(net "P5E_CPU1_P3_TX_DP<3>")
	)
	(segment
		(start 115.552474 -294.82415)
		(end 115.553744 -294.824912)
		(width 0.1143)
		(layer "In11.Cu")
		(net "P5E_CPU1_P3_TX_DP<3>")
	)
	(segment
		(start 115.552474 -280.88844)
		(end 115.551712 -280.888948)
		(width 0.1143)
		(layer "In11.Cu")
		(net "P5E_CPU1_P3_TX_DP<3>")
	)
	(segment
		(start 115.553744 -289.964876)
		(end 115.583462 -289.981894)
		(width 0.1143)
		(layer "In11.Cu")
		(net "P5E_CPU1_P3_TX_DP<3>")
	)
	(segment
		(start 116.163852 -296.418762)
		(end 116.163852 -296.44721)
		(width 0.1143)
		(layer "In11.Cu")
		(net "P5E_CPU1_P3_TX_DP<3>")
	)
	(segment
		(start 130.687572 -356.992174)
		(end 129.52857 -358.151176)
		(width 0.14224)
		(layer "In11.Cu")
		(net "P5E_CPU1_P3_TX_DP<3>")
	)
	(segment
		(start 116.164614 -297.056302)
		(end 116.164614 -297.705272)
		(width 0.14224)
		(layer "In11.Cu")
		(net "P5E_CPU1_P3_TX_DP<3>")
	)
	(segment
		(start 115.551712 -281.8638)
		(end 115.552474 -281.864308)
		(width 0.1143)
		(layer "In11.Cu")
		(net "P5E_CPU1_P3_TX_DP<3>")
	)
	(segment
		(start 115.583462 -280.87066)
		(end 115.552474 -280.88844)
		(width 0.1143)
		(layer "In11.Cu")
		(net "P5E_CPU1_P3_TX_DP<3>")
	)
	(segment
		(start 115.551712 -285.748984)
		(end 115.550696 -285.749492)
		(width 0.1143)
		(layer "In11.Cu")
		(net "P5E_CPU1_P3_TX_DP<3>")
	)
	(segment
		(start 115.519454 -281.845004)
		(end 115.520216 -281.845512)
		(width 0.1143)
		(layer "In11.Cu")
		(net "P5E_CPU1_P3_TX_DP<3>")
	)
	(segment
		(start 115.552474 -284.128464)
		(end 115.551712 -284.128972)
		(width 0.1143)
		(layer "In11.Cu")
		(net "P5E_CPU1_P3_TX_DP<3>")
	)
	(segment
		(start 115.552474 -288.988246)
		(end 115.551712 -288.988754)
		(width 0.1143)
		(layer "In11.Cu")
		(net "P5E_CPU1_P3_TX_DP<3>")
	)
	(segment
		(start 115.549172 -282.510484)
		(end 115.512596 -282.53182)
		(width 0.1143)
		(layer "In11.Cu")
		(net "P5E_CPU1_P3_TX_DP<3>")
	)
	(segment
		(start 115.552474 -292.22827)
		(end 115.551712 -292.228778)
		(width 0.1143)
		(layer "In11.Cu")
		(net "P5E_CPU1_P3_TX_DP<3>")
	)
	(segment
		(start 117.57406 -302.350678)
		(end 121.193306 -307.767228)
		(width 0.14224)
		(layer "In11.Cu")
		(net "P5E_CPU1_P3_TX_DP<3>")
	)
	(segment
		(start 115.550696 -284.12948)
		(end 115.549172 -284.130496)
		(width 0.1143)
		(layer "In11.Cu")
		(net "P5E_CPU1_P3_TX_DP<3>")
	)
	(segment
		(start 115.512596 -285.080964)
		(end 115.519454 -285.085028)
		(width 0.1143)
		(layer "In11.Cu")
		(net "P5E_CPU1_P3_TX_DP<3>")
	)
	(segment
		(start 115.549172 -285.750508)
		(end 115.512596 -285.771844)
		(width 0.1143)
		(layer "In11.Cu")
		(net "P5E_CPU1_P3_TX_DP<3>")
	)
	(segment
		(start 135.95223 -346.018358)
		(end 132.58038 -354.159312)
		(width 0.14224)
		(layer "In11.Cu")
		(net "P5E_CPU1_P3_TX_DP<3>")
	)
	(segment
		(start 115.549172 -284.130496)
		(end 115.512596 -284.151832)
		(width 0.1143)
		(layer "In11.Cu")
		(net "P5E_CPU1_P3_TX_DP<3>")
	)
	(segment
		(start 115.551712 -293.20363)
		(end 115.552474 -293.204138)
		(width 0.1143)
		(layer "In11.Cu")
		(net "P5E_CPU1_P3_TX_DP<3>")
	)
	(segment
		(start 116.211858 -276.506178)
		(end 116.211858 -276.509734)
		(width 0.1143)
		(layer "In11.Cu")
		(net "P5E_CPU1_P3_TX_DP<3>")
	)
	(segment
		(start 115.520216 -293.185342)
		(end 115.551712 -293.20363)
		(width 0.1143)
		(layer "In11.Cu")
		(net "P5E_CPU1_P3_TX_DP<3>")
	)
	(segment
		(start 121.193306 -307.767228)
		(end 128.53289 -316.711076)
		(width 0.14224)
		(layer "In11.Cu")
		(net "P5E_CPU1_P3_TX_DP<3>")
	)
	(segment
		(start 115.551712 -282.50896)
		(end 115.550696 -282.509468)
		(width 0.1143)
		(layer "In11.Cu")
		(net "P5E_CPU1_P3_TX_DP<3>")
	)
	(segment
		(start 115.553744 -281.86507)
		(end 115.583462 -281.882088)
		(width 0.1143)
		(layer "In11.Cu")
		(net "P5E_CPU1_P3_TX_DP<3>")
	)
	(segment
		(start 115.549172 -288.990278)
		(end 115.512596 -289.011614)
		(width 0.1143)
		(layer "In11.Cu")
		(net "P5E_CPU1_P3_TX_DP<3>")
	)
	(segment
		(start 115.551712 -291.583618)
		(end 115.552474 -291.584126)
		(width 0.1143)
		(layer "In11.Cu")
		(net "P5E_CPU1_P3_TX_DP<3>")
	)
	(segment
		(start 115.550696 -290.609274)
		(end 115.549172 -290.61029)
		(width 0.1143)
		(layer "In11.Cu")
		(net "P5E_CPU1_P3_TX_DP<3>")
	)
	(segment
		(start 116.021866 -279.433782)
		(end 116.052346 -279.451562)
		(width 0.1143)
		(layer "In11.Cu")
		(net "P5E_CPU1_P3_TX_DP<3>")
	)
	(segment
		(start 116.021866 -280.078942)
		(end 115.98275 -280.101802)
		(width 0.1143)
		(layer "In11.Cu")
		(net "P5E_CPU1_P3_TX_DP<3>")
	)
	(segment
		(start 115.583462 -290.590478)
		(end 115.552474 -290.608258)
		(width 0.1143)
		(layer "In11.Cu")
		(net "P5E_CPU1_P3_TX_DP<3>")
	)
	(segment
		(start 113.224564 -367.208562)
		(end 112.289336 -367.83391)
		(width 0.14224)
		(layer "In11.Cu")
		(net "P5E_CPU1_P3_TX_DP<3>")
	)
	(segment
		(start 116.052346 -280.061162)
		(end 116.021866 -280.078942)
		(width 0.1143)
		(layer "In11.Cu")
		(net "P5E_CPU1_P3_TX_DP<3>")
	)
	(segment
		(start 115.551712 -287.368742)
		(end 115.515136 -287.390078)
		(width 0.1143)
		(layer "In11.Cu")
		(net "P5E_CPU1_P3_TX_DP<3>")
	)
	(segment
		(start 115.583462 -284.110684)
		(end 115.552474 -284.128464)
		(width 0.1143)
		(layer "In11.Cu")
		(net "P5E_CPU1_P3_TX_DP<3>")
	)
	(segment
		(start 115.551712 -288.988754)
		(end 115.550696 -288.989262)
		(width 0.1143)
		(layer "In11.Cu")
		(net "P5E_CPU1_P3_TX_DP<3>")
	)
	(segment
		(start 115.519454 -291.564822)
		(end 115.520216 -291.56533)
		(width 0.1143)
		(layer "In11.Cu")
		(net "P5E_CPU1_P3_TX_DP<3>")
	)
	(segment
		(start 115.551712 -286.723836)
		(end 115.58524 -286.743394)
		(width 0.1143)
		(layer "In11.Cu")
		(net "P5E_CPU1_P3_TX_DP<3>")
	)
	(segment
		(start 116.209572 -295.956228)
		(end 116.209572 -296.373042)
		(width 0.1143)
		(layer "In11.Cu")
		(net "P5E_CPU1_P3_TX_DP<3>")
	)
	(segment
		(start 131.217162 -320.72834)
		(end 133.044946 -325.141336)
		(width 0.14224)
		(layer "In11.Cu")
		(net "P5E_CPU1_P3_TX_DP<3>")
	)
	(segment
		(start 115.551712 -280.888948)
		(end 115.550696 -280.889456)
		(width 0.1143)
		(layer "In11.Cu")
		(net "P5E_CPU1_P3_TX_DP<3>")
	)
	(segment
		(start 115.550696 -292.229286)
		(end 115.549172 -292.230302)
		(width 0.1143)
		(layer "In11.Cu")
		(net "P5E_CPU1_P3_TX_DP<3>")
	)
	(segment
		(start 117.072664 -274.896326)
		(end 117.142514 -274.966176)
		(width 0.1143)
		(layer "In11.Cu")
		(net "P5E_CPU1_P3_TX_DP<3>")
	)
	(segment
		(start 116.164614 -297.705272)
		(end 117.57406 -302.350678)
		(width 0.14224)
		(layer "In11.Cu")
		(net "P5E_CPU1_P3_TX_DP<3>")
	)
	(segment
		(start 115.583462 -292.21049)
		(end 115.552474 -292.22827)
		(width 0.1143)
		(layer "In11.Cu")
		(net "P5E_CPU1_P3_TX_DP<3>")
	)
	(segment
		(start 115.553744 -291.584888)
		(end 115.583462 -291.601906)
		(width 0.1143)
		(layer "In11.Cu")
		(net "P5E_CPU1_P3_TX_DP<3>")
	)
	(segment
		(start 115.512596 -293.18077)
		(end 115.519454 -293.184834)
		(width 0.1143)
		(layer "In11.Cu")
		(net "P5E_CPU1_P3_TX_DP<3>")
	)
	(segment
		(start 113.22685 -367.207546)
		(end 113.224564 -367.208562)
		(width 0.14224)
		(layer "In11.Cu")
		(net "P5E_CPU1_P3_TX_DP<3>")
	)
	(segment
		(start 115.550696 -285.749492)
		(end 115.549172 -285.750508)
		(width 0.1143)
		(layer "In11.Cu")
		(net "P5E_CPU1_P3_TX_DP<3>")
	)
	(segment
		(start 115.552474 -291.584126)
		(end 115.553744 -291.584888)
		(width 0.1143)
		(layer "In11.Cu")
		(net "P5E_CPU1_P3_TX_DP<3>")
	)
	(segment
		(start 116.774722 -274.896326)
		(end 117.072664 -274.896326)
		(width 0.1143)
		(layer "In11.Cu")
		(net "P5E_CPU1_P3_TX_DP<3>")
	)
	(segment
		(start 115.551712 -293.84879)
		(end 115.550696 -293.849298)
		(width 0.1143)
		(layer "In11.Cu")
		(net "P5E_CPU1_P3_TX_DP<3>")
	)
	(segment
		(start 133.044946 -325.141336)
		(end 136.258808 -341.298022)
		(width 0.14224)
		(layer "In11.Cu")
		(net "P5E_CPU1_P3_TX_DP<3>")
	)
	(segment
		(start 116.211858 -276.509734)
		(end 116.211604 -276.50948)
		(width 0.1143)
		(layer "In11.Cu")
		(net "P5E_CPU1_P3_TX_DP<3>")
	)
	(segment
		(start 115.549172 -290.61029)
		(end 115.512596 -290.631626)
		(width 0.1143)
		(layer "In11.Cu")
		(net "P5E_CPU1_P3_TX_DP<3>")
	)
	(segment
		(start 115.553744 -293.2049)
		(end 115.583462 -293.221918)
		(width 0.1143)
		(layer "In11.Cu")
		(net "P5E_CPU1_P3_TX_DP<3>")
	)
	(segment
		(start 115.552474 -289.964114)
		(end 115.553744 -289.964876)
		(width 0.1143)
		(layer "In11.Cu")
		(net "P5E_CPU1_P3_TX_DP<3>")
	)
	(segment
		(start 115.583462 -287.350454)
		(end 115.551712 -287.368742)
		(width 0.1143)
		(layer "In11.Cu")
		(net "P5E_CPU1_P3_TX_DP<3>")
	)
	(arc
		(start 115.739418 -288.666174)
		(mid 115.698163 -288.837145)
		(end 115.583462 -288.970466)
		(width 0.1143)
		(layer "In11.Cu")
		(net "P5E_CPU1_P3_TX_DP<3>")
	)
	(arc
		(start 115.583462 -285.122112)
		(mid 115.73939 -285.426404)
		(end 115.583462 -285.730696)
		(width 0.1143)
		(layer "In11.Cu")
		(net "P5E_CPU1_P3_TX_DP<3>")
	)
	(arc
		(start 115.58524 -286.743394)
		(mid 115.698647 -286.876283)
		(end 115.739418 -287.046162)
		(width 0.1143)
		(layer "In11.Cu")
		(net "P5E_CPU1_P3_TX_DP<3>")
	)
	(arc
		(start 115.583462 -281.882088)
		(mid 115.73939 -282.18638)
		(end 115.583462 -282.490672)
		(width 0.1143)
		(layer "In11.Cu")
		(net "P5E_CPU1_P3_TX_DP<3>")
	)
	(arc
		(start 116.052346 -295.651428)
		(mid 116.067368 -295.662746)
		(end 116.08181 -295.674796)
		(width 0.1143)
		(layer "In11.Cu")
		(net "P5E_CPU1_P3_TX_DP<3>")
	)
	(arc
		(start 115.512596 -285.771844)
		(mid 115.269269 -286.23641)
		(end 115.512596 -286.700976)
		(width 0.1143)
		(layer "In11.Cu")
		(net "P5E_CPU1_P3_TX_DP<3>")
	)
	(arc
		(start 132.58038 -354.159312)
		(mid 131.773478 -355.668951)
		(end 130.687572 -356.992174)
		(width 0.14224)
		(layer "In11.Cu")
		(net "P5E_CPU1_P3_TX_DP<3>")
	)
	(arc
		(start 115.58524 -288.363406)
		(mid 115.698647 -288.496295)
		(end 115.739418 -288.666174)
		(width 0.1143)
		(layer "In11.Cu")
		(net "P5E_CPU1_P3_TX_DP<3>")
	)
	(arc
		(start 116.052346 -279.451562)
		(mid 116.209323 -279.756362)
		(end 116.052346 -280.061162)
		(width 0.1143)
		(layer "In11.Cu")
		(net "P5E_CPU1_P3_TX_DP<3>")
	)
	(arc
		(start 115.583462 -283.5021)
		(mid 115.73939 -283.806392)
		(end 115.583462 -284.110684)
		(width 0.1143)
		(layer "In11.Cu")
		(net "P5E_CPU1_P3_TX_DP<3>")
	)
	(arc
		(start 115.515136 -287.390078)
		(mid 115.334484 -287.592823)
		(end 115.269264 -287.856422)
		(width 0.1143)
		(layer "In11.Cu")
		(net "P5E_CPU1_P3_TX_DP<3>")
	)
	(arc
		(start 115.583462 -294.84193)
		(mid 115.698138 -294.975264)
		(end 115.739418 -295.146222)
		(width 0.1143)
		(layer "In11.Cu")
		(net "P5E_CPU1_P3_TX_DP<3>")
	)
	(arc
		(start 112.289336 -367.83391)
		(mid 112.155949 -367.98123)
		(end 112.107726 -368.174016)
		(width 0.14224)
		(layer "In11.Cu")
		(net "P5E_CPU1_P3_TX_DP<3>")
	)
	(arc
		(start 115.98275 -278.48179)
		(mid 115.739423 -278.946356)
		(end 115.98275 -279.410922)
		(width 0.1143)
		(layer "In11.Cu")
		(net "P5E_CPU1_P3_TX_DP<3>")
	)
	(arc
		(start 115.512596 -290.631626)
		(mid 115.269269 -291.096192)
		(end 115.512596 -291.560758)
		(width 0.1143)
		(layer "In11.Cu")
		(net "P5E_CPU1_P3_TX_DP<3>")
	)
	(arc
		(start 115.583462 -293.221918)
		(mid 115.73939 -293.52621)
		(end 115.583462 -293.830502)
		(width 0.1143)
		(layer "In11.Cu")
		(net "P5E_CPU1_P3_TX_DP<3>")
	)
	(arc
		(start 115.512596 -293.87165)
		(mid 115.269269 -294.336216)
		(end 115.512596 -294.800782)
		(width 0.1143)
		(layer "In11.Cu")
		(net "P5E_CPU1_P3_TX_DP<3>")
	)
	(arc
		(start 116.211604 -276.50948)
		(mid 116.169974 -276.681059)
		(end 116.054378 -276.814534)
		(width 0.1143)
		(layer "In11.Cu")
		(net "P5E_CPU1_P3_TX_DP<3>")
	)
	(arc
		(start 115.739418 -295.146222)
		(mid 115.803933 -295.408441)
		(end 115.98275 -295.610788)
		(width 0.1143)
		(layer "In11.Cu")
		(net "P5E_CPU1_P3_TX_DP<3>")
	)
	(arc
		(start 116.95938 -275.22043)
		(mid 116.756388 -275.42271)
		(end 116.682012 -275.699474)
		(width 0.1143)
		(layer "In11.Cu")
		(net "P5E_CPU1_P3_TX_DP<3>")
	)
	(arc
		(start 115.739418 -287.046162)
		(mid 115.698163 -287.217133)
		(end 115.583462 -287.350454)
		(width 0.1143)
		(layer "In11.Cu")
		(net "P5E_CPU1_P3_TX_DP<3>")
	)
	(arc
		(start 115.739418 -280.566368)
		(mid 115.698163 -280.737339)
		(end 115.583462 -280.87066)
		(width 0.1143)
		(layer "In11.Cu")
		(net "P5E_CPU1_P3_TX_DP<3>")
	)
	(arc
		(start 115.512596 -292.251638)
		(mid 115.269269 -292.716204)
		(end 115.512596 -293.18077)
		(width 0.1143)
		(layer "In11.Cu")
		(net "P5E_CPU1_P3_TX_DP<3>")
	)
	(arc
		(start 115.583462 -289.981894)
		(mid 115.73939 -290.286186)
		(end 115.583462 -290.590478)
		(width 0.1143)
		(layer "In11.Cu")
		(net "P5E_CPU1_P3_TX_DP<3>")
	)
	(arc
		(start 115.512596 -284.151832)
		(mid 115.269269 -284.616398)
		(end 115.512596 -285.080964)
		(width 0.1143)
		(layer "In11.Cu")
		(net "P5E_CPU1_P3_TX_DP<3>")
	)
	(arc
		(start 115.512596 -289.011614)
		(mid 115.269269 -289.47618)
		(end 115.512596 -289.940746)
		(width 0.1143)
		(layer "In11.Cu")
		(net "P5E_CPU1_P3_TX_DP<3>")
	)
	(arc
		(start 129.52857 -358.151176)
		(mid 127.271918 -360.049919)
		(end 124.723906 -361.534964)
		(width 0.14224)
		(layer "In11.Cu")
		(net "P5E_CPU1_P3_TX_DP<3>")
	)
	(arc
		(start 116.682012 -275.699474)
		(mid 116.640172 -275.87146)
		(end 116.524024 -276.005036)
		(width 0.1143)
		(layer "In11.Cu")
		(net "P5E_CPU1_P3_TX_DP<3>")
	)
	(arc
		(start 115.98275 -280.101802)
		(mid 115.803937 -280.304152)
		(end 115.739418 -280.566368)
		(width 0.1143)
		(layer "In11.Cu")
		(net "P5E_CPU1_P3_TX_DP<3>")
	)
	(arc
		(start 115.512596 -280.911808)
		(mid 115.269269 -281.376374)
		(end 115.512596 -281.84094)
		(width 0.1143)
		(layer "In11.Cu")
		(net "P5E_CPU1_P3_TX_DP<3>")
	)
	(arc
		(start 115.269264 -287.856422)
		(mid 115.333779 -288.118641)
		(end 115.512596 -288.320988)
		(width 0.1143)
		(layer "In11.Cu")
		(net "P5E_CPU1_P3_TX_DP<3>")
	)
	(arc
		(start 115.512596 -282.53182)
		(mid 115.269269 -282.996386)
		(end 115.512596 -283.460952)
		(width 0.1143)
		(layer "In11.Cu")
		(net "P5E_CPU1_P3_TX_DP<3>")
	)
	(arc
		(start 116.08181 -295.674796)
		(mid 116.176089 -295.801713)
		(end 116.209572 -295.956228)
		(width 0.1143)
		(layer "In11.Cu")
		(net "P5E_CPU1_P3_TX_DP<3>")
	)
	(arc
		(start 117.142514 -274.966176)
		(mid 117.090465 -275.097695)
		(end 116.993416 -275.200618)
		(width 0.1143)
		(layer "In11.Cu")
		(net "P5E_CPU1_P3_TX_DP<3>")
	)
	(arc
		(start 115.583462 -291.601906)
		(mid 115.73939 -291.906198)
		(end 115.583462 -292.21049)
		(width 0.1143)
		(layer "In11.Cu")
		(net "P5E_CPU1_P3_TX_DP<3>")
	)
	(arc
		(start 116.155978 -277.944072)
		(mid 116.201256 -278.212819)
		(end 116.052346 -278.44115)
		(width 0.1143)
		(layer "In11.Cu")
		(net "P5E_CPU1_P3_TX_DP<3>")
	)
	(arc
		(start 116.053362 -277.832312)
		(mid 116.110391 -277.882939)
		(end 116.155978 -277.944072)
		(width 0.1143)
		(layer "In11.Cu")
		(net "P5E_CPU1_P3_TX_DP<3>")
	)
	(arc
		(start 116.452904 -276.046184)
		(mid 116.27567 -276.246472)
		(end 116.211858 -276.506178)
		(width 0.1143)
		(layer "In11.Cu")
		(net "P5E_CPU1_P3_TX_DP<3>")
	)
	(arc
		(start 115.981226 -276.857714)
		(mid 115.737395 -277.342724)
		(end 116.014754 -277.809452)
		(width 0.1143)
		(layer "In11.Cu")
		(net "P5E_CPU1_P3_TX_DP<3>")
	)
	(arc
		(start 136.258808 -344.477594)
		(mid 136.181402 -345.263077)
		(end 135.95223 -346.018358)
		(width 0.14224)
		(layer "In11.Cu")
		(net "P5E_CPU1_P3_TX_DP<3>")
	)
	(segment
		(start 110.115096 -371.49913)
		(end 110.385606 -371.76964)
		(width 0.12954)
		(layer "F.Cu")
		(net "P5E_CPU1_P3_TX_DP<2>")
	)
	(segment
		(start 110.385606 -371.76964)
		(end 110.385606 -372.47322)
		(width 0.12954)
		(layer "F.Cu")
		(net "P5E_CPU1_P3_TX_DP<2>")
	)
	(segment
		(start 110.385606 -372.47322)
		(end 110.089696 -372.76913)
		(width 0.12954)
		(layer "F.Cu")
		(net "P5E_CPU1_P3_TX_DP<2>")
	)
	(segment
		(start 113.957862 -278.680418)
		(end 114.424714 -278.946356)
		(width 0.12954)
		(layer "F.Cu")
		(net "P5E_CPU1_P3_TX_DP<2>")
	)
	(segment
		(start 114.615214 -293.205662)
		(end 114.615976 -293.20617)
		(width 0.1143)
		(layer "In11.Cu")
		(net "P5E_CPU1_P3_TX_DP<2>")
	)
	(segment
		(start 114.643408 -282.490672)
		(end 114.611658 -282.50896)
		(width 0.1143)
		(layer "In11.Cu")
		(net "P5E_CPU1_P3_TX_DP<2>")
	)
	(segment
		(start 110.39983 -368.918744)
		(end 110.39983 -371.214396)
		(width 0.14224)
		(layer "In11.Cu")
		(net "P5E_CPU1_P3_TX_DP<2>")
	)
	(segment
		(start 117.261894 -363.941614)
		(end 113.026698 -366.205008)
		(width 0.14224)
		(layer "In11.Cu")
		(net "P5E_CPU1_P3_TX_DP<2>")
	)
	(segment
		(start 114.610642 -292.229286)
		(end 114.609118 -292.230302)
		(width 0.1143)
		(layer "In11.Cu")
		(net "P5E_CPU1_P3_TX_DP<2>")
	)
	(segment
		(start 114.643154 -289.981894)
		(end 114.643408 -289.981894)
		(width 0.1143)
		(layer "In11.Cu")
		(net "P5E_CPU1_P3_TX_DP<2>")
	)
	(segment
		(start 114.611658 -282.50896)
		(end 114.604038 -282.513278)
		(width 0.1143)
		(layer "In11.Cu")
		(net "P5E_CPU1_P3_TX_DP<2>")
	)
	(segment
		(start 114.611658 -291.583618)
		(end 114.643408 -291.601906)
		(width 0.1143)
		(layer "In11.Cu")
		(net "P5E_CPU1_P3_TX_DP<2>")
	)
	(segment
		(start 113.026698 -366.205008)
		(end 111.207042 -367.42116)
		(width 0.14224)
		(layer "In11.Cu")
		(net "P5E_CPU1_P3_TX_DP<2>")
	)
	(segment
		(start 114.64163 -287.351724)
		(end 114.572034 -287.39211)
		(width 0.1143)
		(layer "In11.Cu")
		(net "P5E_CPU1_P3_TX_DP<2>")
	)
	(segment
		(start 115.223798 -296.418762)
		(end 115.223798 -296.44721)
		(width 0.1143)
		(layer "In11.Cu")
		(net "P5E_CPU1_P3_TX_DP<2>")
	)
	(segment
		(start 114.645948 -285.728918)
		(end 114.610134 -285.749492)
		(width 0.1143)
		(layer "In11.Cu")
		(net "P5E_CPU1_P3_TX_DP<2>")
	)
	(segment
		(start 114.611658 -290.608766)
		(end 114.575336 -290.629848)
		(width 0.1143)
		(layer "In11.Cu")
		(net "P5E_CPU1_P3_TX_DP<2>")
	)
	(segment
		(start 134.961122 -345.431364)
		(end 131.19989 -354.512372)
		(width 0.14224)
		(layer "In11.Cu")
		(net "P5E_CPU1_P3_TX_DP<2>")
	)
	(segment
		(start 114.572034 -287.39211)
		(end 114.561112 -287.39973)
		(width 0.1143)
		(layer "In11.Cu")
		(net "P5E_CPU1_P3_TX_DP<2>")
	)
	(segment
		(start 114.329464 -287.853628)
		(end 114.329464 -287.856422)
		(width 0.1143)
		(layer "In11.Cu")
		(net "P5E_CPU1_P3_TX_DP<2>")
	)
	(segment
		(start 114.573304 -289.011106)
		(end 114.561112 -289.019742)
		(width 0.1143)
		(layer "In11.Cu")
		(net "P5E_CPU1_P3_TX_DP<2>")
	)
	(segment
		(start 110.76813 -367.905284)
		(end 110.551976 -368.31016)
		(width 0.14224)
		(layer "In11.Cu")
		(net "P5E_CPU1_P3_TX_DP<2>")
	)
	(segment
		(start 114.611658 -284.128972)
		(end 114.609626 -284.129988)
		(width 0.1143)
		(layer "In11.Cu")
		(net "P5E_CPU1_P3_TX_DP<2>")
	)
	(segment
		(start 114.609372 -285.75)
		(end 114.609372 -285.750254)
		(width 0.1143)
		(layer "In11.Cu")
		(net "P5E_CPU1_P3_TX_DP<2>")
	)
	(segment
		(start 114.561112 -289.932618)
		(end 114.573304 -289.941254)
		(width 0.1143)
		(layer "In11.Cu")
		(net "P5E_CPU1_P3_TX_DP<2>")
	)
	(segment
		(start 114.5794 -293.184834)
		(end 114.580162 -293.185342)
		(width 0.1143)
		(layer "In11.Cu")
		(net "P5E_CPU1_P3_TX_DP<2>")
	)
	(segment
		(start 114.575336 -291.562536)
		(end 114.611658 -291.583618)
		(width 0.1143)
		(layer "In11.Cu")
		(net "P5E_CPU1_P3_TX_DP<2>")
	)
	(segment
		(start 114.643408 -280.87066)
		(end 114.60099 -280.895044)
		(width 0.1143)
		(layer "In11.Cu")
		(net "P5E_CPU1_P3_TX_DP<2>")
	)
	(segment
		(start 114.614452 -280.245312)
		(end 114.643408 -280.262076)
		(width 0.1143)
		(layer "In11.Cu")
		(net "P5E_CPU1_P3_TX_DP<2>")
	)
	(segment
		(start 110.39983 -371.214396)
		(end 110.115096 -371.49913)
		(width 0.14224)
		(layer "In11.Cu")
		(net "P5E_CPU1_P3_TX_DP<2>")
	)
	(segment
		(start 114.643408 -279.250648)
		(end 114.611658 -279.268936)
		(width 0.1143)
		(layer "In11.Cu")
		(net "P5E_CPU1_P3_TX_DP<2>")
	)
	(segment
		(start 114.609626 -280.242772)
		(end 114.612674 -280.244296)
		(width 0.1143)
		(layer "In11.Cu")
		(net "P5E_CPU1_P3_TX_DP<2>")
	)
	(segment
		(start 115.223798 -296.44721)
		(end 115.223798 -296.774362)
		(width 0.14224)
		(layer "In11.Cu")
		(net "P5E_CPU1_P3_TX_DP<2>")
	)
	(segment
		(start 116.702332 -302.7426)
		(end 120.585992 -308.554882)
		(width 0.14224)
		(layer "In11.Cu")
		(net "P5E_CPU1_P3_TX_DP<2>")
	)
	(segment
		(start 114.570002 -288.31921)
		(end 114.611912 -288.343594)
		(width 0.1143)
		(layer "In11.Cu")
		(net "P5E_CPU1_P3_TX_DP<2>")
	)
	(segment
		(start 114.611658 -292.228778)
		(end 114.610642 -292.229286)
		(width 0.1143)
		(layer "In11.Cu")
		(net "P5E_CPU1_P3_TX_DP<2>")
	)
	(segment
		(start 124.2441 -360.639106)
		(end 117.261894 -363.941614)
		(width 0.14224)
		(layer "In11.Cu")
		(net "P5E_CPU1_P3_TX_DP<2>")
	)
	(segment
		(start 127.988822 -317.57493)
		(end 130.388868 -321.166998)
		(width 0.14224)
		(layer "In11.Cu")
		(net "P5E_CPU1_P3_TX_DP<2>")
	)
	(segment
		(start 114.618262 -293.20744)
		(end 114.619278 -293.207948)
		(width 0.1143)
		(layer "In11.Cu")
		(net "P5E_CPU1_P3_TX_DP<2>")
	)
	(segment
		(start 114.643408 -290.590478)
		(end 114.611658 -290.608766)
		(width 0.1143)
		(layer "In11.Cu")
		(net "P5E_CPU1_P3_TX_DP<2>")
	)
	(segment
		(start 115.223798 -296.774362)
		(end 115.22329 -296.77487)
		(width 0.14224)
		(layer "In11.Cu")
		(net "P5E_CPU1_P3_TX_DP<2>")
	)
	(segment
		(start 114.663474 -280.856182)
		(end 114.643408 -280.87066)
		(width 0.1143)
		(layer "In11.Cu")
		(net "P5E_CPU1_P3_TX_DP<2>")
	)
	(segment
		(start 115.042696 -295.610788)
		(end 115.112292 -295.651428)
		(width 0.1143)
		(layer "In11.Cu")
		(net "P5E_CPU1_P3_TX_DP<2>")
	)
	(segment
		(start 114.59591 -293.845996)
		(end 114.564922 -293.866824)
		(width 0.1143)
		(layer "In11.Cu")
		(net "P5E_CPU1_P3_TX_DP<2>")
	)
	(segment
		(start 114.60099 -281.857704)
		(end 114.643408 -281.882088)
		(width 0.1143)
		(layer "In11.Cu")
		(net "P5E_CPU1_P3_TX_DP<2>")
	)
	(segment
		(start 114.643408 -287.350454)
		(end 114.64163 -287.351724)
		(width 0.1143)
		(layer "In11.Cu")
		(net "P5E_CPU1_P3_TX_DP<2>")
	)
	(segment
		(start 114.643408 -293.221918)
		(end 114.657886 -293.232332)
		(width 0.1143)
		(layer "In11.Cu")
		(net "P5E_CPU1_P3_TX_DP<2>")
	)
	(segment
		(start 114.615976 -293.20617)
		(end 114.6175 -293.206932)
		(width 0.1143)
		(layer "In11.Cu")
		(net "P5E_CPU1_P3_TX_DP<2>")
	)
	(segment
		(start 114.613436 -280.244804)
		(end 114.614452 -280.245312)
		(width 0.1143)
		(layer "In11.Cu")
		(net "P5E_CPU1_P3_TX_DP<2>")
	)
	(segment
		(start 114.640614 -294.840406)
		(end 114.643408 -294.84193)
		(width 0.1143)
		(layer "In11.Cu")
		(net "P5E_CPU1_P3_TX_DP<2>")
	)
	(segment
		(start 114.572542 -293.18077)
		(end 114.5794 -293.184834)
		(width 0.1143)
		(layer "In11.Cu")
		(net "P5E_CPU1_P3_TX_DP<2>")
	)
	(segment
		(start 130.388868 -321.166998)
		(end 132.126736 -325.362824)
		(width 0.14224)
		(layer "In11.Cu")
		(net "P5E_CPU1_P3_TX_DP<2>")
	)
	(segment
		(start 114.611658 -288.343848)
		(end 114.645186 -288.363406)
		(width 0.1143)
		(layer "In11.Cu")
		(net "P5E_CPU1_P3_TX_DP<2>")
	)
	(segment
		(start 114.424714 -278.946356)
		(end 114.722656 -278.946356)
		(width 0.1143)
		(layer "In11.Cu")
		(net "P5E_CPU1_P3_TX_DP<2>")
	)
	(segment
		(start 114.611658 -286.723836)
		(end 114.645186 -286.743394)
		(width 0.1143)
		(layer "In11.Cu")
		(net "P5E_CPU1_P3_TX_DP<2>")
	)
	(segment
		(start 114.580162 -293.185342)
		(end 114.611658 -293.20363)
		(width 0.1143)
		(layer "In11.Cu")
		(net "P5E_CPU1_P3_TX_DP<2>")
	)
	(segment
		(start 114.619278 -293.207948)
		(end 114.643408 -293.221918)
		(width 0.1143)
		(layer "In11.Cu")
		(net "P5E_CPU1_P3_TX_DP<2>")
	)
	(segment
		(start 114.608864 -293.837868)
		(end 114.608102 -293.838376)
		(width 0.1143)
		(layer "In11.Cu")
		(net "P5E_CPU1_P3_TX_DP<2>")
	)
	(segment
		(start 114.610388 -293.837106)
		(end 114.608864 -293.837868)
		(width 0.1143)
		(layer "In11.Cu")
		(net "P5E_CPU1_P3_TX_DP<2>")
	)
	(segment
		(start 114.608102 -293.838376)
		(end 114.606324 -293.839392)
		(width 0.1143)
		(layer "In11.Cu")
		(net "P5E_CPU1_P3_TX_DP<2>")
	)
	(segment
		(start 114.643916 -285.122366)
		(end 114.644678 -285.122874)
		(width 0.1143)
		(layer "In11.Cu")
		(net "P5E_CPU1_P3_TX_DP<2>")
	)
	(segment
		(start 114.573304 -289.941254)
		(end 114.643154 -289.981894)
		(width 0.1143)
		(layer "In11.Cu")
		(net "P5E_CPU1_P3_TX_DP<2>")
	)
	(segment
		(start 114.6175 -293.206932)
		(end 114.618262 -293.20744)
		(width 0.1143)
		(layer "In11.Cu")
		(net "P5E_CPU1_P3_TX_DP<2>")
	)
	(segment
		(start 114.643408 -292.21049)
		(end 114.61242 -292.22827)
		(width 0.1143)
		(layer "In11.Cu")
		(net "P5E_CPU1_P3_TX_DP<2>")
	)
	(segment
		(start 114.643408 -288.970466)
		(end 114.573304 -289.011106)
		(width 0.1143)
		(layer "In11.Cu")
		(net "P5E_CPU1_P3_TX_DP<2>")
	)
	(segment
		(start 114.609118 -292.230302)
		(end 114.604546 -292.232842)
		(width 0.1143)
		(layer "In11.Cu")
		(net "P5E_CPU1_P3_TX_DP<2>")
	)
	(segment
		(start 114.612674 -280.244296)
		(end 114.613436 -280.244804)
		(width 0.1143)
		(layer "In11.Cu")
		(net "P5E_CPU1_P3_TX_DP<2>")
	)
	(segment
		(start 114.722656 -278.946356)
		(end 114.792506 -279.016206)
		(width 0.1143)
		(layer "In11.Cu")
		(net "P5E_CPU1_P3_TX_DP<2>")
	)
	(segment
		(start 114.609626 -285.102808)
		(end 114.612674 -285.104332)
		(width 0.1143)
		(layer "In11.Cu")
		(net "P5E_CPU1_P3_TX_DP<2>")
	)
	(segment
		(start 135.31596 -341.395812)
		(end 135.31596 -343.64803)
		(width 0.14224)
		(layer "In11.Cu")
		(net "P5E_CPU1_P3_TX_DP<2>")
	)
	(segment
		(start 114.604546 -292.232842)
		(end 114.572542 -292.251638)
		(width 0.1143)
		(layer "In11.Cu")
		(net "P5E_CPU1_P3_TX_DP<2>")
	)
	(segment
		(start 129.949448 -356.383844)
		(end 129.147316 -357.185976)
		(width 0.14224)
		(layer "In11.Cu")
		(net "P5E_CPU1_P3_TX_DP<2>")
	)
	(segment
		(start 114.612674 -285.104332)
		(end 114.613436 -285.10484)
		(width 0.1143)
		(layer "In11.Cu")
		(net "P5E_CPU1_P3_TX_DP<2>")
	)
	(segment
		(start 114.611658 -279.268936)
		(end 114.609626 -279.269952)
		(width 0.1143)
		(layer "In11.Cu")
		(net "P5E_CPU1_P3_TX_DP<2>")
	)
	(segment
		(start 114.610134 -285.749492)
		(end 114.609372 -285.75)
		(width 0.1143)
		(layer "In11.Cu")
		(net "P5E_CPU1_P3_TX_DP<2>")
	)
	(segment
		(start 115.22329 -297.86707)
		(end 116.702332 -302.7426)
		(width 0.14224)
		(layer "In11.Cu")
		(net "P5E_CPU1_P3_TX_DP<2>")
	)
	(segment
		(start 115.269518 -296.373042)
		(end 115.223798 -296.418762)
		(width 0.1143)
		(layer "In11.Cu")
		(net "P5E_CPU1_P3_TX_DP<2>")
	)
	(segment
		(start 114.604038 -283.479494)
		(end 114.643408 -283.5021)
		(width 0.1143)
		(layer "In11.Cu")
		(net "P5E_CPU1_P3_TX_DP<2>")
	)
	(segment
		(start 114.627914 -293.826946)
		(end 114.610388 -293.837106)
		(width 0.1143)
		(layer "In11.Cu")
		(net "P5E_CPU1_P3_TX_DP<2>")
	)
	(segment
		(start 115.22329 -296.77487)
		(end 115.22329 -297.86707)
		(width 0.14224)
		(layer "In11.Cu")
		(net "P5E_CPU1_P3_TX_DP<2>")
	)
	(segment
		(start 114.611912 -288.343594)
		(end 114.611658 -288.343848)
		(width 0.1143)
		(layer "In11.Cu")
		(net "P5E_CPU1_P3_TX_DP<2>")
	)
	(segment
		(start 114.61242 -292.22827)
		(end 114.611658 -292.228778)
		(width 0.1143)
		(layer "In11.Cu")
		(net "P5E_CPU1_P3_TX_DP<2>")
	)
	(segment
		(start 114.61242 -293.204138)
		(end 114.615214 -293.205662)
		(width 0.1143)
		(layer "In11.Cu")
		(net "P5E_CPU1_P3_TX_DP<2>")
	)
	(segment
		(start 114.643408 -280.262076)
		(end 114.663474 -280.276554)
		(width 0.1143)
		(layer "In11.Cu")
		(net "P5E_CPU1_P3_TX_DP<2>")
	)
	(segment
		(start 114.643408 -285.122112)
		(end 114.643916 -285.122366)
		(width 0.1143)
		(layer "In11.Cu")
		(net "P5E_CPU1_P3_TX_DP<2>")
	)
	(segment
		(start 114.606324 -293.839392)
		(end 114.604292 -293.840662)
		(width 0.1143)
		(layer "In11.Cu")
		(net "P5E_CPU1_P3_TX_DP<2>")
	)
	(segment
		(start 132.126736 -325.362824)
		(end 135.31596 -341.395812)
		(width 0.14224)
		(layer "In11.Cu")
		(net "P5E_CPU1_P3_TX_DP<2>")
	)
	(segment
		(start 120.585992 -308.554882)
		(end 127.988822 -317.57493)
		(width 0.14224)
		(layer "In11.Cu")
		(net "P5E_CPU1_P3_TX_DP<2>")
	)
	(segment
		(start 114.643408 -284.110684)
		(end 114.611658 -284.128972)
		(width 0.1143)
		(layer "In11.Cu")
		(net "P5E_CPU1_P3_TX_DP<2>")
	)
	(segment
		(start 114.613436 -285.10484)
		(end 114.643408 -285.122112)
		(width 0.1143)
		(layer "In11.Cu")
		(net "P5E_CPU1_P3_TX_DP<2>")
	)
	(segment
		(start 115.269518 -295.956228)
		(end 115.269518 -296.373042)
		(width 0.1143)
		(layer "In11.Cu")
		(net "P5E_CPU1_P3_TX_DP<2>")
	)
	(segment
		(start 114.595148 -294.81399)
		(end 114.640614 -294.840406)
		(width 0.1143)
		(layer "In11.Cu")
		(net "P5E_CPU1_P3_TX_DP<2>")
	)
	(segment
		(start 114.611658 -293.20363)
		(end 114.61242 -293.204138)
		(width 0.1143)
		(layer "In11.Cu")
		(net "P5E_CPU1_P3_TX_DP<2>")
	)
	(segment
		(start 114.609372 -286.722566)
		(end 114.611658 -286.723836)
		(width 0.1143)
		(layer "In11.Cu")
		(net "P5E_CPU1_P3_TX_DP<2>")
	)
	(arc
		(start 115.112292 -295.651428)
		(mid 115.127314 -295.662746)
		(end 115.141756 -295.674796)
		(width 0.1143)
		(layer "In11.Cu")
		(net "P5E_CPU1_P3_TX_DP<2>")
	)
	(arc
		(start 114.643408 -291.601906)
		(mid 114.799336 -291.906198)
		(end 114.643408 -292.21049)
		(width 0.1143)
		(layer "In11.Cu")
		(net "P5E_CPU1_P3_TX_DP<2>")
	)
	(arc
		(start 114.60099 -280.895044)
		(mid 114.323844 -281.376374)
		(end 114.60099 -281.857704)
		(width 0.1143)
		(layer "In11.Cu")
		(net "P5E_CPU1_P3_TX_DP<2>")
	)
	(arc
		(start 114.799364 -288.666174)
		(mid 114.758109 -288.837145)
		(end 114.643408 -288.970466)
		(width 0.1143)
		(layer "In11.Cu")
		(net "P5E_CPU1_P3_TX_DP<2>")
	)
	(arc
		(start 114.643408 -281.882088)
		(mid 114.799336 -282.18638)
		(end 114.643408 -282.490672)
		(width 0.1143)
		(layer "In11.Cu")
		(net "P5E_CPU1_P3_TX_DP<2>")
	)
	(arc
		(start 114.792506 -279.016206)
		(mid 114.740457 -279.147725)
		(end 114.643408 -279.250648)
		(width 0.1143)
		(layer "In11.Cu")
		(net "P5E_CPU1_P3_TX_DP<2>")
	)
	(arc
		(start 114.643408 -294.84193)
		(mid 114.758084 -294.975264)
		(end 114.799364 -295.146222)
		(width 0.1143)
		(layer "In11.Cu")
		(net "P5E_CPU1_P3_TX_DP<2>")
	)
	(arc
		(start 114.609372 -285.750254)
		(mid 114.329444 -286.23641)
		(end 114.609372 -286.722566)
		(width 0.1143)
		(layer "In11.Cu")
		(net "P5E_CPU1_P3_TX_DP<2>")
	)
	(arc
		(start 114.663474 -280.276554)
		(mid 114.811981 -280.566368)
		(end 114.663474 -280.856182)
		(width 0.1143)
		(layer "In11.Cu")
		(net "P5E_CPU1_P3_TX_DP<2>")
	)
	(arc
		(start 114.575336 -290.629848)
		(mid 114.567158 -290.635491)
		(end 114.55908 -290.641278)
		(width 0.1143)
		(layer "In11.Cu")
		(net "P5E_CPU1_P3_TX_DP<2>")
	)
	(arc
		(start 114.561112 -287.39973)
		(mid 114.390569 -287.598751)
		(end 114.329464 -287.853628)
		(width 0.1143)
		(layer "In11.Cu")
		(net "P5E_CPU1_P3_TX_DP<2>")
	)
	(arc
		(start 110.551976 -368.31016)
		(mid 110.438415 -368.605077)
		(end 110.39983 -368.918744)
		(width 0.14224)
		(layer "In11.Cu")
		(net "P5E_CPU1_P3_TX_DP<2>")
	)
	(arc
		(start 114.799364 -287.046162)
		(mid 114.758109 -287.217133)
		(end 114.643408 -287.350454)
		(width 0.1143)
		(layer "In11.Cu")
		(net "P5E_CPU1_P3_TX_DP<2>")
	)
	(arc
		(start 114.644678 -285.122874)
		(mid 114.800834 -285.425592)
		(end 114.645948 -285.728918)
		(width 0.1143)
		(layer "In11.Cu")
		(net "P5E_CPU1_P3_TX_DP<2>")
	)
	(arc
		(start 114.55908 -291.551106)
		(mid 114.567158 -291.556892)
		(end 114.575336 -291.562536)
		(width 0.1143)
		(layer "In11.Cu")
		(net "P5E_CPU1_P3_TX_DP<2>")
	)
	(arc
		(start 131.19989 -354.512372)
		(mid 130.66682 -355.509678)
		(end 129.949448 -356.383844)
		(width 0.14224)
		(layer "In11.Cu")
		(net "P5E_CPU1_P3_TX_DP<2>")
	)
	(arc
		(start 135.31596 -343.64803)
		(mid 135.226358 -344.557169)
		(end 134.961122 -345.431364)
		(width 0.14224)
		(layer "In11.Cu")
		(net "P5E_CPU1_P3_TX_DP<2>")
	)
	(arc
		(start 114.657886 -293.232332)
		(mid 114.80472 -293.53775)
		(end 114.627914 -293.826946)
		(width 0.1143)
		(layer "In11.Cu")
		(net "P5E_CPU1_P3_TX_DP<2>")
	)
	(arc
		(start 114.609626 -284.129988)
		(mid 114.329605 -284.616398)
		(end 114.609626 -285.102808)
		(width 0.1143)
		(layer "In11.Cu")
		(net "P5E_CPU1_P3_TX_DP<2>")
	)
	(arc
		(start 114.329464 -287.856422)
		(mid 114.39314 -288.117226)
		(end 114.570002 -288.31921)
		(width 0.1143)
		(layer "In11.Cu")
		(net "P5E_CPU1_P3_TX_DP<2>")
	)
	(arc
		(start 114.645186 -286.743394)
		(mid 114.758593 -286.876283)
		(end 114.799364 -287.046162)
		(width 0.1143)
		(layer "In11.Cu")
		(net "P5E_CPU1_P3_TX_DP<2>")
	)
	(arc
		(start 115.141756 -295.674796)
		(mid 115.236035 -295.801713)
		(end 115.269518 -295.956228)
		(width 0.1143)
		(layer "In11.Cu")
		(net "P5E_CPU1_P3_TX_DP<2>")
	)
	(arc
		(start 114.561112 -289.019742)
		(mid 114.326691 -289.47618)
		(end 114.561112 -289.932618)
		(width 0.1143)
		(layer "In11.Cu")
		(net "P5E_CPU1_P3_TX_DP<2>")
	)
	(arc
		(start 114.604292 -293.840662)
		(mid 114.600089 -293.843311)
		(end 114.59591 -293.845996)
		(width 0.1143)
		(layer "In11.Cu")
		(net "P5E_CPU1_P3_TX_DP<2>")
	)
	(arc
		(start 114.799364 -295.146222)
		(mid 114.863879 -295.408441)
		(end 115.042696 -295.610788)
		(width 0.1143)
		(layer "In11.Cu")
		(net "P5E_CPU1_P3_TX_DP<2>")
	)
	(arc
		(start 114.609626 -279.269952)
		(mid 114.329605 -279.756362)
		(end 114.609626 -280.242772)
		(width 0.1143)
		(layer "In11.Cu")
		(net "P5E_CPU1_P3_TX_DP<2>")
	)
	(arc
		(start 114.572542 -292.251638)
		(mid 114.329215 -292.716204)
		(end 114.572542 -293.18077)
		(width 0.1143)
		(layer "In11.Cu")
		(net "P5E_CPU1_P3_TX_DP<2>")
	)
	(arc
		(start 114.55908 -290.641278)
		(mid 114.336196 -291.096192)
		(end 114.55908 -291.551106)
		(width 0.1143)
		(layer "In11.Cu")
		(net "P5E_CPU1_P3_TX_DP<2>")
	)
	(arc
		(start 129.147316 -357.185976)
		(mid 126.844382 -359.123646)
		(end 124.2441 -360.639106)
		(width 0.14224)
		(layer "In11.Cu")
		(net "P5E_CPU1_P3_TX_DP<2>")
	)
	(arc
		(start 114.643408 -283.5021)
		(mid 114.799336 -283.806392)
		(end 114.643408 -284.110684)
		(width 0.1143)
		(layer "In11.Cu")
		(net "P5E_CPU1_P3_TX_DP<2>")
	)
	(arc
		(start 114.564922 -293.866824)
		(mid 114.317191 -294.348743)
		(end 114.595148 -294.81399)
		(width 0.1143)
		(layer "In11.Cu")
		(net "P5E_CPU1_P3_TX_DP<2>")
	)
	(arc
		(start 111.207042 -367.42116)
		(mid 110.957751 -367.636168)
		(end 110.76813 -367.905284)
		(width 0.14224)
		(layer "In11.Cu")
		(net "P5E_CPU1_P3_TX_DP<2>")
	)
	(arc
		(start 114.604038 -282.513278)
		(mid 114.325861 -282.996386)
		(end 114.604038 -283.479494)
		(width 0.1143)
		(layer "In11.Cu")
		(net "P5E_CPU1_P3_TX_DP<2>")
	)
	(arc
		(start 114.645186 -288.363406)
		(mid 114.758593 -288.496295)
		(end 114.799364 -288.666174)
		(width 0.1143)
		(layer "In11.Cu")
		(net "P5E_CPU1_P3_TX_DP<2>")
	)
	(arc
		(start 114.643408 -289.981894)
		(mid 114.799336 -290.286186)
		(end 114.643408 -290.590478)
		(width 0.1143)
		(layer "In11.Cu")
		(net "P5E_CPU1_P3_TX_DP<2>")
	)
	(segment
		(start 113.957862 -277.060406)
		(end 114.424714 -277.326344)
		(width 0.12954)
		(layer "F.Cu")
		(net "P5E_CPU1_P3_TX_DP<1>")
	)
	(segment
		(start 109.504734 -376.23877)
		(end 109.800644 -375.94286)
		(width 0.12954)
		(layer "F.Cu")
		(net "P5E_CPU1_P3_TX_DP<1>")
	)
	(segment
		(start 108.801154 -376.23877)
		(end 109.504734 -376.23877)
		(width 0.12954)
		(layer "F.Cu")
		(net "P5E_CPU1_P3_TX_DP<1>")
	)
	(segment
		(start 108.530644 -375.96826)
		(end 108.801154 -376.23877)
		(width 0.12954)
		(layer "F.Cu")
		(net "P5E_CPU1_P3_TX_DP<1>")
	)
	(segment
		(start 113.702338 -282.49118)
		(end 113.672874 -282.508452)
		(width 0.1143)
		(layer "In11.Cu")
		(net "P5E_CPU1_P3_TX_DP<1>")
	)
	(segment
		(start 113.67262 -281.864308)
		(end 113.702338 -281.88158)
		(width 0.1143)
		(layer "In11.Cu")
		(net "P5E_CPU1_P3_TX_DP<1>")
	)
	(segment
		(start 114.643408 -277.630636)
		(end 114.611658 -277.648924)
		(width 0.1143)
		(layer "In11.Cu")
		(net "P5E_CPU1_P3_TX_DP<1>")
	)
	(segment
		(start 113.669572 -293.202614)
		(end 113.67262 -293.204138)
		(width 0.1143)
		(layer "In11.Cu")
		(net "P5E_CPU1_P3_TX_DP<1>")
	)
	(segment
		(start 113.702338 -280.871168)
		(end 113.672874 -280.88844)
		(width 0.1143)
		(layer "In11.Cu")
		(net "P5E_CPU1_P3_TX_DP<1>")
	)
	(segment
		(start 113.635536 -288.322766)
		(end 113.67135 -288.34334)
		(width 0.1143)
		(layer "In11.Cu")
		(net "P5E_CPU1_P3_TX_DP<1>")
	)
	(segment
		(start 109.42955 -373.945912)
		(end 109.623606 -373.945912)
		(width 0.14224)
		(layer "In11.Cu")
		(net "P5E_CPU1_P3_TX_DP<1>")
	)
	(segment
		(start 109.745526 -376.25909)
		(end 108.821474 -376.25909)
		(width 0.14224)
		(layer "In11.Cu")
		(net "P5E_CPU1_P3_TX_DP<1>")
	)
	(segment
		(start 109.623606 -373.945912)
		(end 109.887766 -374.210072)
		(width 0.14224)
		(layer "In11.Cu")
		(net "P5E_CPU1_P3_TX_DP<1>")
	)
	(segment
		(start 114.173508 -278.440642)
		(end 114.102642 -278.48179)
		(width 0.1143)
		(layer "In11.Cu")
		(net "P5E_CPU1_P3_TX_DP<1>")
	)
	(segment
		(start 114.329464 -278.133556)
		(end 114.329464 -278.13635)
		(width 0.1143)
		(layer "In11.Cu")
		(net "P5E_CPU1_P3_TX_DP<1>")
	)
	(segment
		(start 125.440186 -358.172004)
		(end 125.406404 -358.363012)
		(width 0.14224)
		(layer "In11.Cu")
		(net "P5E_CPU1_P3_TX_DP<1>")
	)
	(segment
		(start 113.389664 -286.23641)
		(end 113.389664 -286.239204)
		(width 0.1143)
		(layer "In11.Cu")
		(net "P5E_CPU1_P3_TX_DP<1>")
	)
	(segment
		(start 113.702338 -284.111192)
		(end 113.67262 -284.128464)
		(width 0.1143)
		(layer "In11.Cu")
		(net "P5E_CPU1_P3_TX_DP<1>")
	)
	(segment
		(start 113.67262 -293.204138)
		(end 113.673382 -293.204646)
		(width 0.1143)
		(layer "In11.Cu")
		(net "P5E_CPU1_P3_TX_DP<1>")
	)
	(segment
		(start 114.283744 -296.418762)
		(end 114.283744 -296.44721)
		(width 0.1143)
		(layer "In11.Cu")
		(net "P5E_CPU1_P3_TX_DP<1>")
	)
	(segment
		(start 109.787944 -375.14149)
		(end 109.787944 -375.56821)
		(width 0.14224)
		(layer "In11.Cu")
		(net "P5E_CPU1_P3_TX_DP<1>")
	)
	(segment
		(start 113.671858 -289.963606)
		(end 113.702338 -289.981386)
		(width 0.1143)
		(layer "In11.Cu")
		(net "P5E_CPU1_P3_TX_DP<1>")
	)
	(segment
		(start 115.84305 -303.135284)
		(end 119.929656 -309.251096)
		(width 0.14224)
		(layer "In11.Cu")
		(net "P5E_CPU1_P3_TX_DP<1>")
	)
	(segment
		(start 113.67135 -288.34334)
		(end 113.67643 -288.346388)
		(width 0.1143)
		(layer "In11.Cu")
		(net "P5E_CPU1_P3_TX_DP<1>")
	)
	(segment
		(start 113.671604 -285.103824)
		(end 113.671858 -285.103824)
		(width 0.1143)
		(layer "In11.Cu")
		(net "P5E_CPU1_P3_TX_DP<1>")
	)
	(segment
		(start 113.671858 -280.888948)
		(end 113.668048 -280.891234)
		(width 0.1143)
		(layer "In11.Cu")
		(net "P5E_CPU1_P3_TX_DP<1>")
	)
	(segment
		(start 113.671858 -293.84879)
		(end 113.635536 -293.869872)
		(width 0.1143)
		(layer "In11.Cu")
		(net "P5E_CPU1_P3_TX_DP<1>")
	)
	(segment
		(start 109.399578 -368.065558)
		(end 109.155484 -368.655092)
		(width 0.14224)
		(layer "In11.Cu")
		(net "P5E_CPU1_P3_TX_DP<1>")
	)
	(segment
		(start 108.821474 -376.25909)
		(end 108.530644 -375.96826)
		(width 0.14224)
		(layer "In11.Cu")
		(net "P5E_CPU1_P3_TX_DP<1>")
	)
	(segment
		(start 113.632742 -280.220928)
		(end 113.702338 -280.261568)
		(width 0.1143)
		(layer "In11.Cu")
		(net "P5E_CPU1_P3_TX_DP<1>")
	)
	(segment
		(start 109.127544 -373.44985)
		(end 109.127544 -373.643906)
		(width 0.14224)
		(layer "In11.Cu")
		(net "P5E_CPU1_P3_TX_DP<1>")
	)
	(segment
		(start 113.686082 -288.980118)
		(end 113.673382 -288.987992)
		(width 0.1143)
		(layer "In11.Cu")
		(net "P5E_CPU1_P3_TX_DP<1>")
	)
	(segment
		(start 129.534666 -321.567048)
		(end 131.213352 -325.619364)
		(width 0.14224)
		(layer "In11.Cu")
		(net "P5E_CPU1_P3_TX_DP<1>")
	)
	(segment
		(start 113.635536 -291.562536)
		(end 113.671858 -291.583618)
		(width 0.1143)
		(layer "In11.Cu")
		(net "P5E_CPU1_P3_TX_DP<1>")
	)
	(segment
		(start 122.592592 -360.331258)
		(end 117.571774 -362.706412)
		(width 0.14224)
		(layer "In11.Cu")
		(net "P5E_CPU1_P3_TX_DP<1>")
	)
	(segment
		(start 125.980952 -357.960422)
		(end 125.789944 -357.926894)
		(width 0.14224)
		(layer "In11.Cu")
		(net "P5E_CPU1_P3_TX_DP<1>")
	)
	(segment
		(start 109.127544 -373.643906)
		(end 109.42955 -373.945912)
		(width 0.14224)
		(layer "In11.Cu")
		(net "P5E_CPU1_P3_TX_DP<1>")
	)
	(segment
		(start 113.674398 -293.205154)
		(end 113.67516 -293.205662)
		(width 0.1143)
		(layer "In11.Cu")
		(net "P5E_CPU1_P3_TX_DP<1>")
	)
	(segment
		(start 113.38941 -286.23641)
		(end 113.389664 -286.23641)
		(width 0.1143)
		(layer "In11.Cu")
		(net "P5E_CPU1_P3_TX_DP<1>")
	)
	(segment
		(start 113.67516 -293.205662)
		(end 113.676176 -293.20617)
		(width 0.1143)
		(layer "In11.Cu")
		(net "P5E_CPU1_P3_TX_DP<1>")
	)
	(segment
		(start 108.560362 -371.647466)
		(end 108.560362 -372.470172)
		(width 0.14224)
		(layer "In11.Cu")
		(net "P5E_CPU1_P3_TX_DP<1>")
	)
	(segment
		(start 113.635536 -294.80256)
		(end 113.671858 -294.823642)
		(width 0.1143)
		(layer "In11.Cu")
		(net "P5E_CPU1_P3_TX_DP<1>")
	)
	(segment
		(start 113.671858 -294.823642)
		(end 113.702338 -294.841422)
		(width 0.1143)
		(layer "In11.Cu")
		(net "P5E_CPU1_P3_TX_DP<1>")
	)
	(segment
		(start 127.33274 -318.271652)
		(end 129.534666 -321.567048)
		(width 0.14224)
		(layer "In11.Cu")
		(net "P5E_CPU1_P3_TX_DP<1>")
	)
	(segment
		(start 134.375398 -341.528908)
		(end 134.375398 -343.223342)
		(width 0.14224)
		(layer "In11.Cu")
		(net "P5E_CPU1_P3_TX_DP<1>")
	)
	(segment
		(start 125.789944 -357.926894)
		(end 125.440186 -358.172004)
		(width 0.14224)
		(layer "In11.Cu")
		(net "P5E_CPU1_P3_TX_DP<1>")
	)
	(segment
		(start 113.672874 -282.508452)
		(end 113.671858 -282.50896)
		(width 0.1143)
		(layer "In11.Cu")
		(net "P5E_CPU1_P3_TX_DP<1>")
	)
	(segment
		(start 113.676176 -293.20617)
		(end 113.703354 -293.221918)
		(width 0.1143)
		(layer "In11.Cu")
		(net "P5E_CPU1_P3_TX_DP<1>")
	)
	(segment
		(start 114.424714 -277.326344)
		(end 114.722656 -277.326344)
		(width 0.1143)
		(layer "In11.Cu")
		(net "P5E_CPU1_P3_TX_DP<1>")
	)
	(segment
		(start 109.925104 -374.299988)
		(end 109.925104 -375.00433)
		(width 0.14224)
		(layer "In11.Cu")
		(net "P5E_CPU1_P3_TX_DP<1>")
	)
	(segment
		(start 114.102642 -295.610788)
		(end 114.172238 -295.651428)
		(width 0.1143)
		(layer "In11.Cu")
		(net "P5E_CPU1_P3_TX_DP<1>")
	)
	(segment
		(start 114.722656 -277.326344)
		(end 114.792506 -277.396194)
		(width 0.1143)
		(layer "In11.Cu")
		(net "P5E_CPU1_P3_TX_DP<1>")
	)
	(segment
		(start 109.887766 -376.169428)
		(end 109.835442 -376.221752)
		(width 0.14224)
		(layer "In11.Cu")
		(net "P5E_CPU1_P3_TX_DP<1>")
	)
	(segment
		(start 124.811536 -358.61244)
		(end 124.461778 -358.85755)
		(width 0.14224)
		(layer "In11.Cu")
		(net "P5E_CPU1_P3_TX_DP<1>")
	)
	(segment
		(start 110.40491 -366.76838)
		(end 109.987588 -367.185702)
		(width 0.14224)
		(layer "In11.Cu")
		(net "P5E_CPU1_P3_TX_DP<1>")
	)
	(segment
		(start 113.671858 -291.583618)
		(end 113.702338 -291.601398)
		(width 0.1143)
		(layer "In11.Cu")
		(net "P5E_CPU1_P3_TX_DP<1>")
	)
	(segment
		(start 114.329464 -295.956228)
		(end 114.329464 -296.373042)
		(width 0.1143)
		(layer "In11.Cu")
		(net "P5E_CPU1_P3_TX_DP<1>")
	)
	(segment
		(start 114.283744 -297.995086)
		(end 115.84305 -303.135284)
		(width 0.14224)
		(layer "In11.Cu")
		(net "P5E_CPU1_P3_TX_DP<1>")
	)
	(segment
		(start 113.673382 -293.204646)
		(end 113.674398 -293.205154)
		(width 0.1143)
		(layer "In11.Cu")
		(net "P5E_CPU1_P3_TX_DP<1>")
	)
	(segment
		(start 113.702338 -285.731204)
		(end 113.632742 -285.771844)
		(width 0.1143)
		(layer "In11.Cu")
		(net "P5E_CPU1_P3_TX_DP<1>")
	)
	(segment
		(start 113.673382 -288.987992)
		(end 113.672366 -288.9885)
		(width 0.1143)
		(layer "In11.Cu")
		(net "P5E_CPU1_P3_TX_DP<1>")
	)
	(segment
		(start 113.67262 -284.128464)
		(end 113.671858 -284.128972)
		(width 0.1143)
		(layer "In11.Cu")
		(net "P5E_CPU1_P3_TX_DP<1>")
	)
	(segment
		(start 113.702338 -293.83101)
		(end 113.671858 -293.84879)
		(width 0.1143)
		(layer "In11.Cu")
		(net "P5E_CPU1_P3_TX_DP<1>")
	)
	(segment
		(start 124.461778 -358.85755)
		(end 124.427996 -359.047796)
		(width 0.14224)
		(layer "In11.Cu")
		(net "P5E_CPU1_P3_TX_DP<1>")
	)
	(segment
		(start 113.67262 -283.48432)
		(end 113.702338 -283.501592)
		(width 0.1143)
		(layer "In11.Cu")
		(net "P5E_CPU1_P3_TX_DP<1>")
	)
	(segment
		(start 113.672366 -288.9885)
		(end 113.634266 -289.010598)
		(width 0.1143)
		(layer "In11.Cu")
		(net "P5E_CPU1_P3_TX_DP<1>")
	)
	(segment
		(start 108.851954 -373.17426)
		(end 109.127544 -373.44985)
		(width 0.14224)
		(layer "In11.Cu")
		(net "P5E_CPU1_P3_TX_DP<1>")
	)
	(segment
		(start 113.635536 -289.942524)
		(end 113.671858 -289.963606)
		(width 0.1143)
		(layer "In11.Cu")
		(net "P5E_CPU1_P3_TX_DP<1>")
	)
	(segment
		(start 129.986024 -354.577904)
		(end 129.173986 -355.698298)
		(width 0.14224)
		(layer "In11.Cu")
		(net "P5E_CPU1_P3_TX_DP<1>")
	)
	(segment
		(start 125.406404 -358.363012)
		(end 125.057154 -358.607614)
		(width 0.14224)
		(layer "In11.Cu")
		(net "P5E_CPU1_P3_TX_DP<1>")
	)
	(segment
		(start 113.671604 -292.228778)
		(end 113.669572 -292.229794)
		(width 0.1143)
		(layer "In11.Cu")
		(net "P5E_CPU1_P3_TX_DP<1>")
	)
	(segment
		(start 117.571774 -362.706412)
		(end 112.465104 -365.435896)
		(width 0.14224)
		(layer "In11.Cu")
		(net "P5E_CPU1_P3_TX_DP<1>")
	)
	(segment
		(start 113.671858 -284.128972)
		(end 113.671604 -284.129226)
		(width 0.1143)
		(layer "In11.Cu")
		(net "P5E_CPU1_P3_TX_DP<1>")
	)
	(segment
		(start 113.703354 -292.21049)
		(end 113.671604 -292.228778)
		(width 0.1143)
		(layer "In11.Cu")
		(net "P5E_CPU1_P3_TX_DP<1>")
	)
	(segment
		(start 134.070598 -344.754962)
		(end 130.047746 -354.467668)
		(width 0.14224)
		(layer "In11.Cu")
		(net "P5E_CPU1_P3_TX_DP<1>")
	)
	(segment
		(start 109.787944 -375.56821)
		(end 109.925104 -375.70537)
		(width 0.14224)
		(layer "In11.Cu")
		(net "P5E_CPU1_P3_TX_DP<1>")
	)
	(segment
		(start 113.671858 -282.50896)
		(end 113.668048 -282.511246)
		(width 0.1143)
		(layer "In11.Cu")
		(net "P5E_CPU1_P3_TX_DP<1>")
	)
	(segment
		(start 112.465104 -365.435896)
		(end 110.943898 -366.347756)
		(width 0.14224)
		(layer "In11.Cu")
		(net "P5E_CPU1_P3_TX_DP<1>")
	)
	(segment
		(start 113.671858 -285.103824)
		(end 113.702338 -285.121604)
		(width 0.1143)
		(layer "In11.Cu")
		(net "P5E_CPU1_P3_TX_DP<1>")
	)
	(segment
		(start 129.08407 -355.78669)
		(end 125.980952 -357.960422)
		(width 0.14224)
		(layer "In11.Cu")
		(net "P5E_CPU1_P3_TX_DP<1>")
	)
	(segment
		(start 113.668048 -283.481526)
		(end 113.67262 -283.48432)
		(width 0.1143)
		(layer "In11.Cu")
		(net "P5E_CPU1_P3_TX_DP<1>")
	)
	(segment
		(start 113.702338 -290.590986)
		(end 113.671858 -290.608766)
		(width 0.1143)
		(layer "In11.Cu")
		(net "P5E_CPU1_P3_TX_DP<1>")
	)
	(segment
		(start 114.283744 -296.44721)
		(end 114.283744 -297.995086)
		(width 0.14224)
		(layer "In11.Cu")
		(net "P5E_CPU1_P3_TX_DP<1>")
	)
	(segment
		(start 113.668048 -281.861514)
		(end 113.67262 -281.864308)
		(width 0.1143)
		(layer "In11.Cu")
		(net "P5E_CPU1_P3_TX_DP<1>")
	)
	(segment
		(start 113.702338 -279.251156)
		(end 113.63452 -279.291034)
		(width 0.1143)
		(layer "In11.Cu")
		(net "P5E_CPU1_P3_TX_DP<1>")
	)
	(segment
		(start 131.213352 -325.619364)
		(end 134.372858 -341.503762)
		(width 0.14224)
		(layer "In11.Cu")
		(net "P5E_CPU1_P3_TX_DP<1>")
	)
	(segment
		(start 109.925104 -375.00433)
		(end 109.787944 -375.14149)
		(width 0.14224)
		(layer "In11.Cu")
		(net "P5E_CPU1_P3_TX_DP<1>")
	)
	(segment
		(start 114.329464 -296.373042)
		(end 114.283744 -296.418762)
		(width 0.1143)
		(layer "In11.Cu")
		(net "P5E_CPU1_P3_TX_DP<1>")
	)
	(segment
		(start 124.427996 -359.047796)
		(end 122.592592 -360.331258)
		(width 0.14224)
		(layer "In11.Cu")
		(net "P5E_CPU1_P3_TX_DP<1>")
	)
	(segment
		(start 113.63325 -286.70123)
		(end 113.70437 -286.742632)
		(width 0.1143)
		(layer "In11.Cu")
		(net "P5E_CPU1_P3_TX_DP<1>")
	)
	(segment
		(start 113.702338 -287.350962)
		(end 113.63833 -287.3883)
		(width 0.1143)
		(layer "In11.Cu")
		(net "P5E_CPU1_P3_TX_DP<1>")
	)
	(segment
		(start 113.672874 -280.88844)
		(end 113.671858 -280.888948)
		(width 0.1143)
		(layer "In11.Cu")
		(net "P5E_CPU1_P3_TX_DP<1>")
	)
	(segment
		(start 114.611658 -277.648924)
		(end 114.57305 -277.67153)
		(width 0.1143)
		(layer "In11.Cu")
		(net "P5E_CPU1_P3_TX_DP<1>")
	)
	(segment
		(start 113.671858 -290.608766)
		(end 113.635536 -290.629848)
		(width 0.1143)
		(layer "In11.Cu")
		(net "P5E_CPU1_P3_TX_DP<1>")
	)
	(segment
		(start 124.936758 -358.634538)
		(end 124.811536 -358.61244)
		(width 0.14224)
		(layer "In11.Cu")
		(net "P5E_CPU1_P3_TX_DP<1>")
	)
	(segment
		(start 109.925104 -375.70537)
		(end 109.925104 -376.079512)
		(width 0.14224)
		(layer "In11.Cu")
		(net "P5E_CPU1_P3_TX_DP<1>")
	)
	(segment
		(start 119.929656 -309.251096)
		(end 127.33274 -318.271652)
		(width 0.14224)
		(layer "In11.Cu")
		(net "P5E_CPU1_P3_TX_DP<1>")
	)
	(arc
		(start 109.887766 -374.210072)
		(mid 109.915385 -374.251312)
		(end 109.925104 -374.299988)
		(width 0.14224)
		(layer "In11.Cu")
		(net "P5E_CPU1_P3_TX_DP<1>")
	)
	(arc
		(start 134.375398 -343.223342)
		(mid 134.298441 -344.004167)
		(end 134.070598 -344.754962)
		(width 0.14224)
		(layer "In11.Cu")
		(net "P5E_CPU1_P3_TX_DP<1>")
	)
	(arc
		(start 109.987588 -367.185702)
		(mid 109.650242 -367.596665)
		(end 109.399578 -368.065558)
		(width 0.14224)
		(layer "In11.Cu")
		(net "P5E_CPU1_P3_TX_DP<1>")
	)
	(arc
		(start 113.85931 -287.046162)
		(mid 113.817761 -287.217584)
		(end 113.702338 -287.350962)
		(width 0.1143)
		(layer "In11.Cu")
		(net "P5E_CPU1_P3_TX_DP<1>")
	)
	(arc
		(start 114.57305 -277.67153)
		(mid 114.39412 -277.872414)
		(end 114.329464 -278.133556)
		(width 0.1143)
		(layer "In11.Cu")
		(net "P5E_CPU1_P3_TX_DP<1>")
	)
	(arc
		(start 113.85931 -295.146222)
		(mid 113.923825 -295.408441)
		(end 114.102642 -295.610788)
		(width 0.1143)
		(layer "In11.Cu")
		(net "P5E_CPU1_P3_TX_DP<1>")
	)
	(arc
		(start 114.201702 -295.674796)
		(mid 114.295981 -295.801713)
		(end 114.329464 -295.956228)
		(width 0.1143)
		(layer "In11.Cu")
		(net "P5E_CPU1_P3_TX_DP<1>")
	)
	(arc
		(start 113.63452 -279.291034)
		(mid 113.459997 -279.498882)
		(end 113.38941 -279.760934)
		(width 0.1143)
		(layer "In11.Cu")
		(net "P5E_CPU1_P3_TX_DP<1>")
	)
	(arc
		(start 113.702338 -291.601398)
		(mid 113.817765 -291.734774)
		(end 113.85931 -291.906198)
		(width 0.1143)
		(layer "In11.Cu")
		(net "P5E_CPU1_P3_TX_DP<1>")
	)
	(arc
		(start 109.835442 -376.221752)
		(mid 109.794202 -376.249371)
		(end 109.745526 -376.25909)
		(width 0.14224)
		(layer "In11.Cu")
		(net "P5E_CPU1_P3_TX_DP<1>")
	)
	(arc
		(start 113.632742 -285.771844)
		(mid 113.453929 -285.974194)
		(end 113.38941 -286.23641)
		(width 0.1143)
		(layer "In11.Cu")
		(net "P5E_CPU1_P3_TX_DP<1>")
	)
	(arc
		(start 113.85931 -291.906198)
		(mid 113.818055 -292.077169)
		(end 113.703354 -292.21049)
		(width 0.1143)
		(layer "In11.Cu")
		(net "P5E_CPU1_P3_TX_DP<1>")
	)
	(arc
		(start 114.329464 -278.13635)
		(mid 114.288209 -278.307321)
		(end 114.173508 -278.440642)
		(width 0.1143)
		(layer "In11.Cu")
		(net "P5E_CPU1_P3_TX_DP<1>")
	)
	(arc
		(start 125.057154 -358.607614)
		(mid 124.99963 -358.633021)
		(end 124.936758 -358.634538)
		(width 0.14224)
		(layer "In11.Cu")
		(net "P5E_CPU1_P3_TX_DP<1>")
	)
	(arc
		(start 130.047746 -354.467668)
		(mid 130.020112 -354.524592)
		(end 129.986024 -354.577904)
		(width 0.14224)
		(layer "In11.Cu")
		(net "P5E_CPU1_P3_TX_DP<1>")
	)
	(arc
		(start 110.943898 -366.347756)
		(mid 110.799708 -366.440201)
		(end 110.66145 -366.541304)
		(width 0.14224)
		(layer "In11.Cu")
		(net "P5E_CPU1_P3_TX_DP<1>")
	)
	(arc
		(start 113.668048 -282.511246)
		(mid 113.389629 -282.996386)
		(end 113.668048 -283.481526)
		(width 0.1143)
		(layer "In11.Cu")
		(net "P5E_CPU1_P3_TX_DP<1>")
	)
	(arc
		(start 113.671604 -284.129226)
		(mid 113.39184 -284.616588)
		(end 113.671604 -285.103824)
		(width 0.1143)
		(layer "In11.Cu")
		(net "P5E_CPU1_P3_TX_DP<1>")
	)
	(arc
		(start 113.389664 -287.856422)
		(mid 113.4549 -288.120013)
		(end 113.635536 -288.322766)
		(width 0.1143)
		(layer "In11.Cu")
		(net "P5E_CPU1_P3_TX_DP<1>")
	)
	(arc
		(start 113.668048 -280.891234)
		(mid 113.389629 -281.376374)
		(end 113.668048 -281.861514)
		(width 0.1143)
		(layer "In11.Cu")
		(net "P5E_CPU1_P3_TX_DP<1>")
	)
	(arc
		(start 114.172238 -295.651428)
		(mid 114.18726 -295.662746)
		(end 114.201702 -295.674796)
		(width 0.1143)
		(layer "In11.Cu")
		(net "P5E_CPU1_P3_TX_DP<1>")
	)
	(arc
		(start 113.702338 -281.88158)
		(mid 113.859315 -282.18638)
		(end 113.702338 -282.49118)
		(width 0.1143)
		(layer "In11.Cu")
		(net "P5E_CPU1_P3_TX_DP<1>")
	)
	(arc
		(start 113.702338 -283.501592)
		(mid 113.859315 -283.806392)
		(end 113.702338 -284.111192)
		(width 0.1143)
		(layer "In11.Cu")
		(net "P5E_CPU1_P3_TX_DP<1>")
	)
	(arc
		(start 108.560362 -372.470172)
		(mid 108.636139 -372.851216)
		(end 108.851954 -373.17426)
		(width 0.14224)
		(layer "In11.Cu")
		(net "P5E_CPU1_P3_TX_DP<1>")
	)
	(arc
		(start 113.85931 -278.946356)
		(mid 113.817761 -279.117778)
		(end 113.702338 -279.251156)
		(width 0.1143)
		(layer "In11.Cu")
		(net "P5E_CPU1_P3_TX_DP<1>")
	)
	(arc
		(start 113.389664 -286.239204)
		(mid 113.454282 -286.500366)
		(end 113.63325 -286.70123)
		(width 0.1143)
		(layer "In11.Cu")
		(net "P5E_CPU1_P3_TX_DP<1>")
	)
	(arc
		(start 113.702338 -285.121604)
		(mid 113.859315 -285.426404)
		(end 113.702338 -285.731204)
		(width 0.1143)
		(layer "In11.Cu")
		(net "P5E_CPU1_P3_TX_DP<1>")
	)
	(arc
		(start 110.66145 -366.541304)
		(mid 110.529689 -366.650899)
		(end 110.40491 -366.76838)
		(width 0.14224)
		(layer "In11.Cu")
		(net "P5E_CPU1_P3_TX_DP<1>")
	)
	(arc
		(start 114.102642 -278.48179)
		(mid 113.923829 -278.68414)
		(end 113.85931 -278.946356)
		(width 0.1143)
		(layer "In11.Cu")
		(net "P5E_CPU1_P3_TX_DP<1>")
	)
	(arc
		(start 114.792506 -277.396194)
		(mid 114.740457 -277.527713)
		(end 114.643408 -277.630636)
		(width 0.1143)
		(layer "In11.Cu")
		(net "P5E_CPU1_P3_TX_DP<1>")
	)
	(arc
		(start 113.63833 -287.3883)
		(mid 113.455668 -287.591381)
		(end 113.389664 -287.856422)
		(width 0.1143)
		(layer "In11.Cu")
		(net "P5E_CPU1_P3_TX_DP<1>")
	)
	(arc
		(start 113.67643 -288.346388)
		(mid 113.860115 -288.660533)
		(end 113.686082 -288.980118)
		(width 0.1143)
		(layer "In11.Cu")
		(net "P5E_CPU1_P3_TX_DP<1>")
	)
	(arc
		(start 113.702338 -294.841422)
		(mid 113.817765 -294.974798)
		(end 113.85931 -295.146222)
		(width 0.1143)
		(layer "In11.Cu")
		(net "P5E_CPU1_P3_TX_DP<1>")
	)
	(arc
		(start 109.155484 -368.655092)
		(mid 108.710601 -370.121979)
		(end 108.560362 -371.647466)
		(width 0.14224)
		(layer "In11.Cu")
		(net "P5E_CPU1_P3_TX_DP<1>")
	)
	(arc
		(start 113.70437 -286.742632)
		(mid 113.818299 -286.875779)
		(end 113.85931 -287.046162)
		(width 0.1143)
		(layer "In11.Cu")
		(net "P5E_CPU1_P3_TX_DP<1>")
	)
	(arc
		(start 134.372858 -341.503762)
		(mid 134.374745 -341.516273)
		(end 134.375398 -341.528908)
		(width 0.14224)
		(layer "In11.Cu")
		(net "P5E_CPU1_P3_TX_DP<1>")
	)
	(arc
		(start 113.635536 -293.869872)
		(mid 113.389646 -294.336216)
		(end 113.635536 -294.80256)
		(width 0.1143)
		(layer "In11.Cu")
		(net "P5E_CPU1_P3_TX_DP<1>")
	)
	(arc
		(start 113.38941 -279.760934)
		(mid 113.454973 -280.020612)
		(end 113.632742 -280.220928)
		(width 0.1143)
		(layer "In11.Cu")
		(net "P5E_CPU1_P3_TX_DP<1>")
	)
	(arc
		(start 129.173986 -355.698298)
		(mid 129.132711 -355.74624)
		(end 129.08407 -355.78669)
		(width 0.14224)
		(layer "In11.Cu")
		(net "P5E_CPU1_P3_TX_DP<1>")
	)
	(arc
		(start 113.85931 -293.52621)
		(mid 113.817761 -293.697632)
		(end 113.702338 -293.83101)
		(width 0.1143)
		(layer "In11.Cu")
		(net "P5E_CPU1_P3_TX_DP<1>")
	)
	(arc
		(start 113.702338 -280.261568)
		(mid 113.859315 -280.566368)
		(end 113.702338 -280.871168)
		(width 0.1143)
		(layer "In11.Cu")
		(net "P5E_CPU1_P3_TX_DP<1>")
	)
	(arc
		(start 113.703354 -293.221918)
		(mid 113.81803 -293.355252)
		(end 113.85931 -293.52621)
		(width 0.1143)
		(layer "In11.Cu")
		(net "P5E_CPU1_P3_TX_DP<1>")
	)
	(arc
		(start 113.669572 -292.229794)
		(mid 113.389551 -292.716204)
		(end 113.669572 -293.202614)
		(width 0.1143)
		(layer "In11.Cu")
		(net "P5E_CPU1_P3_TX_DP<1>")
	)
	(arc
		(start 113.634266 -289.010598)
		(mid 113.389446 -289.476919)
		(end 113.635536 -289.942524)
		(width 0.1143)
		(layer "In11.Cu")
		(net "P5E_CPU1_P3_TX_DP<1>")
	)
	(arc
		(start 113.702338 -289.981386)
		(mid 113.859315 -290.286186)
		(end 113.702338 -290.590986)
		(width 0.1143)
		(layer "In11.Cu")
		(net "P5E_CPU1_P3_TX_DP<1>")
	)
	(arc
		(start 113.635536 -290.629848)
		(mid 113.389646 -291.096192)
		(end 113.635536 -291.562536)
		(width 0.1143)
		(layer "In11.Cu")
		(net "P5E_CPU1_P3_TX_DP<1>")
	)
	(arc
		(start 109.925104 -376.079512)
		(mid 109.915402 -376.128196)
		(end 109.887766 -376.169428)
		(width 0.14224)
		(layer "In11.Cu")
		(net "P5E_CPU1_P3_TX_DP<1>")
	)
	(segment
		(start 137.403586 -379.767338)
		(end 137.107676 -379.471428)
		(width 0.12954)
		(layer "F.Cu")
		(net "P5E_CPU1_P3_TX_DP<15>")
	)
	(segment
		(start 138.107166 -379.767338)
		(end 137.403586 -379.767338)
		(width 0.12954)
		(layer "F.Cu")
		(net "P5E_CPU1_P3_TX_DP<15>")
	)
	(segment
		(start 138.377676 -379.496828)
		(end 138.107166 -379.767338)
		(width 0.12954)
		(layer "F.Cu")
		(net "P5E_CPU1_P3_TX_DP<15>")
	)
	(segment
		(start 124.767848 -276.2504)
		(end 125.2347 -276.516338)
		(width 0.12954)
		(layer "F.Cu")
		(net "P5E_CPU1_P3_TX_DP<15>")
	)
	(segment
		(start 127.299212 -280.080466)
		(end 127.262636 -280.101802)
		(width 0.1143)
		(layer "In11.Cu")
		(net "P5E_CPU1_P3_TX_DP<15>")
	)
	(segment
		(start 126.862332 -284.111192)
		(end 126.831852 -284.128972)
		(width 0.1143)
		(layer "In11.Cu")
		(net "P5E_CPU1_P3_TX_DP<15>")
	)
	(segment
		(start 127.300736 -280.07945)
		(end 127.299212 -280.080466)
		(width 0.1143)
		(layer "In11.Cu")
		(net "P5E_CPU1_P3_TX_DP<15>")
	)
	(segment
		(start 127.309626 -279.438354)
		(end 127.312166 -279.439624)
		(width 0.1143)
		(layer "In11.Cu")
		(net "P5E_CPU1_P3_TX_DP<15>")
	)
	(segment
		(start 127.307594 -295.63695)
		(end 127.308356 -295.637458)
		(width 0.1143)
		(layer "In11.Cu")
		(net "P5E_CPU1_P3_TX_DP<15>")
	)
	(segment
		(start 125.892052 -277.004018)
		(end 125.89256 -277.004272)
		(width 0.1143)
		(layer "In11.Cu")
		(net "P5E_CPU1_P3_TX_DP<15>")
	)
	(segment
		(start 125.852682 -276.980904)
		(end 125.85954 -276.984968)
		(width 0.1143)
		(layer "In11.Cu")
		(net "P5E_CPU1_P3_TX_DP<15>")
	)
	(segment
		(start 126.792736 -291.560758)
		(end 126.831852 -291.583618)
		(width 0.1143)
		(layer "In11.Cu")
		(net "P5E_CPU1_P3_TX_DP<15>")
	)
	(segment
		(start 127.302514 -295.634156)
		(end 127.305308 -295.63568)
		(width 0.1143)
		(layer "In11.Cu")
		(net "P5E_CPU1_P3_TX_DP<15>")
	)
	(segment
		(start 125.860302 -276.985476)
		(end 125.891798 -277.003764)
		(width 0.1143)
		(layer "In11.Cu")
		(net "P5E_CPU1_P3_TX_DP<15>")
	)
	(segment
		(start 126.831852 -278.623776)
		(end 126.862332 -278.641556)
		(width 0.1143)
		(layer "In11.Cu")
		(net "P5E_CPU1_P3_TX_DP<15>")
	)
	(segment
		(start 126.792736 -293.18077)
		(end 126.831852 -293.20363)
		(width 0.1143)
		(layer "In11.Cu")
		(net "P5E_CPU1_P3_TX_DP<15>")
	)
	(segment
		(start 141.72057 -315.97981)
		(end 144.213326 -321.99707)
		(width 0.14224)
		(layer "In11.Cu")
		(net "P5E_CPU1_P3_TX_DP<15>")
	)
	(segment
		(start 126.862332 -287.350962)
		(end 126.795276 -287.390078)
		(width 0.1143)
		(layer "In11.Cu")
		(net "P5E_CPU1_P3_TX_DP<15>")
	)
	(segment
		(start 127.302514 -279.43429)
		(end 127.305308 -279.435814)
		(width 0.1143)
		(layer "In11.Cu")
		(net "P5E_CPU1_P3_TX_DP<15>")
	)
	(segment
		(start 141.038834 -367.578132)
		(end 141.038834 -368.010694)
		(width 0.14224)
		(layer "In11.Cu")
		(net "P5E_CPU1_P3_TX_DP<15>")
	)
	(segment
		(start 127.307594 -279.437084)
		(end 127.308356 -279.437592)
		(width 0.1143)
		(layer "In11.Cu")
		(net "P5E_CPU1_P3_TX_DP<15>")
	)
	(segment
		(start 126.862332 -292.210998)
		(end 126.831852 -292.228778)
		(width 0.1143)
		(layer "In11.Cu")
		(net "P5E_CPU1_P3_TX_DP<15>")
	)
	(segment
		(start 126.792736 -294.800782)
		(end 126.831852 -294.823642)
		(width 0.1143)
		(layer "In11.Cu")
		(net "P5E_CPU1_P3_TX_DP<15>")
	)
	(segment
		(start 127.308356 -295.637458)
		(end 127.309626 -295.63822)
		(width 0.1143)
		(layer "In11.Cu")
		(net "P5E_CPU1_P3_TX_DP<15>")
	)
	(segment
		(start 127.301752 -279.433782)
		(end 127.302514 -279.43429)
		(width 0.1143)
		(layer "In11.Cu")
		(net "P5E_CPU1_P3_TX_DP<15>")
	)
	(segment
		(start 127.727964 -296.809668)
		(end 127.727964 -296.838116)
		(width 0.1143)
		(layer "In11.Cu")
		(net "P5E_CPU1_P3_TX_DP<15>")
	)
	(segment
		(start 125.891798 -277.003764)
		(end 125.892052 -277.004018)
		(width 0.1143)
		(layer "In11.Cu")
		(net "P5E_CPU1_P3_TX_DP<15>")
	)
	(segment
		(start 126.831852 -288.343848)
		(end 126.864364 -288.362644)
		(width 0.1143)
		(layer "In11.Cu")
		(net "P5E_CPU1_P3_TX_DP<15>")
	)
	(segment
		(start 141.038834 -370.266214)
		(end 140.901674 -370.403374)
		(width 0.14224)
		(layer "In11.Cu")
		(net "P5E_CPU1_P3_TX_DP<15>")
	)
	(segment
		(start 126.862332 -282.49118)
		(end 126.831852 -282.50896)
		(width 0.1143)
		(layer "In11.Cu")
		(net "P5E_CPU1_P3_TX_DP<15>")
	)
	(segment
		(start 139.458446 -378.071888)
		(end 139.458446 -378.498608)
		(width 0.14224)
		(layer "In11.Cu")
		(net "P5E_CPU1_P3_TX_DP<15>")
	)
	(segment
		(start 125.89256 -277.004272)
		(end 125.895354 -277.005796)
		(width 0.1143)
		(layer "In11.Cu")
		(net "P5E_CPU1_P3_TX_DP<15>")
	)
	(segment
		(start 127.656844 -296.519092)
		(end 127.736092 -296.59834)
		(width 0.1143)
		(layer "In11.Cu")
		(net "P5E_CPU1_P3_TX_DP<15>")
	)
	(segment
		(start 126.831852 -285.748984)
		(end 126.792736 -285.771844)
		(width 0.1143)
		(layer "In11.Cu")
		(net "P5E_CPU1_P3_TX_DP<15>")
	)
	(segment
		(start 127.727964 -296.838116)
		(end 127.727964 -296.9133)
		(width 0.14224)
		(layer "In11.Cu")
		(net "P5E_CPU1_P3_TX_DP<15>")
	)
	(segment
		(start 141.038834 -371.393974)
		(end 140.936472 -371.909848)
		(width 0.14224)
		(layer "In11.Cu")
		(net "P5E_CPU1_P3_TX_DP<15>")
	)
	(segment
		(start 126.792736 -283.460952)
		(end 126.831852 -283.483812)
		(width 0.1143)
		(layer "In11.Cu")
		(net "P5E_CPU1_P3_TX_DP<15>")
	)
	(segment
		(start 141.038834 -369.138454)
		(end 140.901674 -369.275614)
		(width 0.14224)
		(layer "In11.Cu")
		(net "P5E_CPU1_P3_TX_DP<15>")
	)
	(segment
		(start 127.30607 -295.636188)
		(end 127.307594 -295.63695)
		(width 0.1143)
		(layer "In11.Cu")
		(net "P5E_CPU1_P3_TX_DP<15>")
	)
	(segment
		(start 126.831852 -282.50896)
		(end 126.792736 -282.53182)
		(width 0.1143)
		(layer "In11.Cu")
		(net "P5E_CPU1_P3_TX_DP<15>")
	)
	(segment
		(start 127.727964 -296.9133)
		(end 127.797814 -297.14317)
		(width 0.14224)
		(layer "In11.Cu")
		(net "P5E_CPU1_P3_TX_DP<15>")
	)
	(segment
		(start 147.217384 -351.711768)
		(end 141.402054 -365.752126)
		(width 0.14224)
		(layer "In11.Cu")
		(net "P5E_CPU1_P3_TX_DP<15>")
	)
	(segment
		(start 126.831852 -286.723836)
		(end 126.864364 -286.742632)
		(width 0.1143)
		(layer "In11.Cu")
		(net "P5E_CPU1_P3_TX_DP<15>")
	)
	(segment
		(start 126.831852 -280.888948)
		(end 126.792736 -280.911808)
		(width 0.1143)
		(layer "In11.Cu")
		(net "P5E_CPU1_P3_TX_DP<15>")
	)
	(segment
		(start 126.792736 -285.080964)
		(end 126.831852 -285.103824)
		(width 0.1143)
		(layer "In11.Cu")
		(net "P5E_CPU1_P3_TX_DP<15>")
	)
	(segment
		(start 126.831852 -289.963606)
		(end 126.862332 -289.981386)
		(width 0.1143)
		(layer "In11.Cu")
		(net "P5E_CPU1_P3_TX_DP<15>")
	)
	(segment
		(start 127.773684 -296.763948)
		(end 127.727964 -296.809668)
		(width 0.1143)
		(layer "In11.Cu")
		(net "P5E_CPU1_P3_TX_DP<15>")
	)
	(segment
		(start 127.309626 -295.63822)
		(end 127.312166 -295.63949)
		(width 0.1143)
		(layer "In11.Cu")
		(net "P5E_CPU1_P3_TX_DP<15>")
	)
	(segment
		(start 139.595606 -378.635768)
		(end 139.595606 -379.60808)
		(width 0.14224)
		(layer "In11.Cu")
		(net "P5E_CPU1_P3_TX_DP<15>")
	)
	(segment
		(start 139.458446 -378.498608)
		(end 139.595606 -378.635768)
		(width 0.14224)
		(layer "In11.Cu")
		(net "P5E_CPU1_P3_TX_DP<15>")
	)
	(segment
		(start 126.792736 -289.940746)
		(end 126.831852 -289.963606)
		(width 0.1143)
		(layer "In11.Cu")
		(net "P5E_CPU1_P3_TX_DP<15>")
	)
	(segment
		(start 139.595606 -377.934728)
		(end 139.458446 -378.071888)
		(width 0.14224)
		(layer "In11.Cu")
		(net "P5E_CPU1_P3_TX_DP<15>")
	)
	(segment
		(start 139.595606 -375.915936)
		(end 139.595606 -377.934728)
		(width 0.14224)
		(layer "In11.Cu")
		(net "P5E_CPU1_P3_TX_DP<15>")
	)
	(segment
		(start 126.831852 -281.8638)
		(end 126.862332 -281.88158)
		(width 0.1143)
		(layer "In11.Cu")
		(net "P5E_CPU1_P3_TX_DP<15>")
	)
	(segment
		(start 141.038834 -368.711734)
		(end 141.038834 -369.138454)
		(width 0.14224)
		(layer "In11.Cu")
		(net "P5E_CPU1_P3_TX_DP<15>")
	)
	(segment
		(start 126.792736 -288.320988)
		(end 126.831852 -288.343848)
		(width 0.1143)
		(layer "In11.Cu")
		(net "P5E_CPU1_P3_TX_DP<15>")
	)
	(segment
		(start 141.038834 -369.839494)
		(end 141.038834 -370.266214)
		(width 0.14224)
		(layer "In11.Cu")
		(net "P5E_CPU1_P3_TX_DP<15>")
	)
	(segment
		(start 125.85954 -276.984968)
		(end 125.860302 -276.985476)
		(width 0.1143)
		(layer "In11.Cu")
		(net "P5E_CPU1_P3_TX_DP<15>")
	)
	(segment
		(start 125.2347 -276.516338)
		(end 125.532642 -276.516338)
		(width 0.1143)
		(layer "In11.Cu")
		(net "P5E_CPU1_P3_TX_DP<15>")
	)
	(segment
		(start 127.302514 -280.078434)
		(end 127.301752 -280.078942)
		(width 0.1143)
		(layer "In11.Cu")
		(net "P5E_CPU1_P3_TX_DP<15>")
	)
	(segment
		(start 140.901674 -368.574574)
		(end 141.038834 -368.711734)
		(width 0.14224)
		(layer "In11.Cu")
		(net "P5E_CPU1_P3_TX_DP<15>")
	)
	(segment
		(start 127.423418 -295.743884)
		(end 127.423672 -295.74363)
		(width 0.1143)
		(layer "In11.Cu")
		(net "P5E_CPU1_P3_TX_DP<15>")
	)
	(segment
		(start 134.990332 -305.907186)
		(end 141.72057 -315.97981)
		(width 0.14224)
		(layer "In11.Cu")
		(net "P5E_CPU1_P3_TX_DP<15>")
	)
	(segment
		(start 127.305308 -279.435814)
		(end 127.30607 -279.436322)
		(width 0.1143)
		(layer "In11.Cu")
		(net "P5E_CPU1_P3_TX_DP<15>")
	)
	(segment
		(start 127.489712 -295.955974)
		(end 127.489712 -296.115232)
		(width 0.1143)
		(layer "In11.Cu")
		(net "P5E_CPU1_P3_TX_DP<15>")
	)
	(segment
		(start 138.668506 -379.787658)
		(end 138.377676 -379.496828)
		(width 0.14224)
		(layer "In11.Cu")
		(net "P5E_CPU1_P3_TX_DP<15>")
	)
	(segment
		(start 140.901674 -369.275614)
		(end 140.901674 -369.702334)
		(width 0.14224)
		(layer "In11.Cu")
		(net "P5E_CPU1_P3_TX_DP<15>")
	)
	(segment
		(start 147.792694 -339.993224)
		(end 147.792694 -348.820232)
		(width 0.14224)
		(layer "In11.Cu")
		(net "P5E_CPU1_P3_TX_DP<15>")
	)
	(segment
		(start 140.901674 -370.403374)
		(end 140.901674 -370.830094)
		(width 0.14224)
		(layer "In11.Cu")
		(net "P5E_CPU1_P3_TX_DP<15>")
	)
	(segment
		(start 126.831852 -293.20363)
		(end 126.862332 -293.22141)
		(width 0.1143)
		(layer "In11.Cu")
		(net "P5E_CPU1_P3_TX_DP<15>")
	)
	(segment
		(start 127.333502 -280.060654)
		(end 127.302514 -280.078434)
		(width 0.1143)
		(layer "In11.Cu")
		(net "P5E_CPU1_P3_TX_DP<15>")
	)
	(segment
		(start 140.901674 -368.147854)
		(end 140.901674 -368.574574)
		(width 0.14224)
		(layer "In11.Cu")
		(net "P5E_CPU1_P3_TX_DP<15>")
	)
	(segment
		(start 126.831852 -288.988754)
		(end 126.792736 -289.011614)
		(width 0.1143)
		(layer "In11.Cu")
		(net "P5E_CPU1_P3_TX_DP<15>")
	)
	(segment
		(start 126.831852 -285.103824)
		(end 126.862332 -285.121604)
		(width 0.1143)
		(layer "In11.Cu")
		(net "P5E_CPU1_P3_TX_DP<15>")
	)
	(segment
		(start 126.792736 -278.600916)
		(end 126.831852 -278.623776)
		(width 0.1143)
		(layer "In11.Cu")
		(net "P5E_CPU1_P3_TX_DP<15>")
	)
	(segment
		(start 127.489458 -295.956228)
		(end 127.489712 -295.955974)
		(width 0.1143)
		(layer "In11.Cu")
		(net "P5E_CPU1_P3_TX_DP<15>")
	)
	(segment
		(start 127.30607 -279.436322)
		(end 127.307594 -279.437084)
		(width 0.1143)
		(layer "In11.Cu")
		(net "P5E_CPU1_P3_TX_DP<15>")
	)
	(segment
		(start 127.269494 -279.414986)
		(end 127.270256 -279.415494)
		(width 0.1143)
		(layer "In11.Cu")
		(net "P5E_CPU1_P3_TX_DP<15>")
	)
	(segment
		(start 127.270256 -279.415494)
		(end 127.301752 -279.433782)
		(width 0.1143)
		(layer "In11.Cu")
		(net "P5E_CPU1_P3_TX_DP<15>")
	)
	(segment
		(start 127.300736 -295.63314)
		(end 127.301752 -295.633648)
		(width 0.1143)
		(layer "In11.Cu")
		(net "P5E_CPU1_P3_TX_DP<15>")
	)
	(segment
		(start 127.308356 -279.437592)
		(end 127.309626 -279.438354)
		(width 0.1143)
		(layer "In11.Cu")
		(net "P5E_CPU1_P3_TX_DP<15>")
	)
	(segment
		(start 140.901674 -369.702334)
		(end 141.038834 -369.839494)
		(width 0.14224)
		(layer "In11.Cu")
		(net "P5E_CPU1_P3_TX_DP<15>")
	)
	(segment
		(start 139.416028 -379.787658)
		(end 138.668506 -379.787658)
		(width 0.14224)
		(layer "In11.Cu")
		(net "P5E_CPU1_P3_TX_DP<15>")
	)
	(segment
		(start 140.901674 -370.830094)
		(end 141.038834 -370.967254)
		(width 0.14224)
		(layer "In11.Cu")
		(net "P5E_CPU1_P3_TX_DP<15>")
	)
	(segment
		(start 126.831852 -294.823642)
		(end 126.862332 -294.841422)
		(width 0.1143)
		(layer "In11.Cu")
		(net "P5E_CPU1_P3_TX_DP<15>")
	)
	(segment
		(start 126.831852 -292.228778)
		(end 126.792736 -292.251638)
		(width 0.1143)
		(layer "In11.Cu")
		(net "P5E_CPU1_P3_TX_DP<15>")
	)
	(segment
		(start 126.862332 -285.731204)
		(end 126.831852 -285.748984)
		(width 0.1143)
		(layer "In11.Cu")
		(net "P5E_CPU1_P3_TX_DP<15>")
	)
	(segment
		(start 126.079504 -277.326344)
		(end 126.079504 -277.329392)
		(width 0.1143)
		(layer "In11.Cu")
		(net "P5E_CPU1_P3_TX_DP<15>")
	)
	(segment
		(start 126.792736 -281.84094)
		(end 126.831852 -281.8638)
		(width 0.1143)
		(layer "In11.Cu")
		(net "P5E_CPU1_P3_TX_DP<15>")
	)
	(segment
		(start 126.831852 -290.608766)
		(end 126.792736 -290.631626)
		(width 0.1143)
		(layer "In11.Cu")
		(net "P5E_CPU1_P3_TX_DP<15>")
	)
	(segment
		(start 127.797814 -297.14317)
		(end 134.990332 -305.907186)
		(width 0.14224)
		(layer "In11.Cu")
		(net "P5E_CPU1_P3_TX_DP<15>")
	)
	(segment
		(start 126.831852 -293.84879)
		(end 126.792736 -293.87165)
		(width 0.1143)
		(layer "In11.Cu")
		(net "P5E_CPU1_P3_TX_DP<15>")
	)
	(segment
		(start 126.831852 -284.128972)
		(end 126.792736 -284.151832)
		(width 0.1143)
		(layer "In11.Cu")
		(net "P5E_CPU1_P3_TX_DP<15>")
	)
	(segment
		(start 126.862332 -288.970974)
		(end 126.831852 -288.988754)
		(width 0.1143)
		(layer "In11.Cu")
		(net "P5E_CPU1_P3_TX_DP<15>")
	)
	(segment
		(start 127.305308 -295.63568)
		(end 127.30607 -295.636188)
		(width 0.1143)
		(layer "In11.Cu")
		(net "P5E_CPU1_P3_TX_DP<15>")
	)
	(segment
		(start 125.895354 -277.005796)
		(end 125.921516 -277.021036)
		(width 0.1143)
		(layer "In11.Cu")
		(net "P5E_CPU1_P3_TX_DP<15>")
	)
	(segment
		(start 126.862332 -280.871168)
		(end 126.831852 -280.888948)
		(width 0.1143)
		(layer "In11.Cu")
		(net "P5E_CPU1_P3_TX_DP<15>")
	)
	(segment
		(start 126.831852 -283.483812)
		(end 126.862332 -283.501592)
		(width 0.1143)
		(layer "In11.Cu")
		(net "P5E_CPU1_P3_TX_DP<15>")
	)
	(segment
		(start 126.862332 -290.590986)
		(end 126.831852 -290.608766)
		(width 0.1143)
		(layer "In11.Cu")
		(net "P5E_CPU1_P3_TX_DP<15>")
	)
	(segment
		(start 139.558268 -379.697996)
		(end 139.505944 -379.75032)
		(width 0.14224)
		(layer "In11.Cu")
		(net "P5E_CPU1_P3_TX_DP<15>")
	)
	(segment
		(start 141.038834 -368.010694)
		(end 140.901674 -368.147854)
		(width 0.14224)
		(layer "In11.Cu")
		(net "P5E_CPU1_P3_TX_DP<15>")
	)
	(segment
		(start 127.262636 -295.610788)
		(end 127.300736 -295.63314)
		(width 0.1143)
		(layer "In11.Cu")
		(net "P5E_CPU1_P3_TX_DP<15>")
	)
	(segment
		(start 127.773684 -296.68851)
		(end 127.773684 -296.763948)
		(width 0.1143)
		(layer "In11.Cu")
		(net "P5E_CPU1_P3_TX_DP<15>")
	)
	(segment
		(start 127.301752 -295.633648)
		(end 127.302514 -295.634156)
		(width 0.1143)
		(layer "In11.Cu")
		(net "P5E_CPU1_P3_TX_DP<15>")
	)
	(segment
		(start 126.393194 -277.832058)
		(end 126.393448 -277.832058)
		(width 0.1143)
		(layer "In11.Cu")
		(net "P5E_CPU1_P3_TX_DP<15>")
	)
	(segment
		(start 141.038834 -370.967254)
		(end 141.038834 -371.393974)
		(width 0.14224)
		(layer "In11.Cu")
		(net "P5E_CPU1_P3_TX_DP<15>")
	)
	(segment
		(start 127.262636 -279.410922)
		(end 127.269494 -279.414986)
		(width 0.1143)
		(layer "In11.Cu")
		(net "P5E_CPU1_P3_TX_DP<15>")
	)
	(segment
		(start 125.532642 -276.516338)
		(end 125.615446 -276.599142)
		(width 0.1143)
		(layer "In11.Cu")
		(net "P5E_CPU1_P3_TX_DP<15>")
	)
	(segment
		(start 126.792736 -286.700976)
		(end 126.831852 -286.723836)
		(width 0.1143)
		(layer "In11.Cu")
		(net "P5E_CPU1_P3_TX_DP<15>")
	)
	(segment
		(start 127.312166 -279.439624)
		(end 127.333502 -279.45207)
		(width 0.1143)
		(layer "In11.Cu")
		(net "P5E_CPU1_P3_TX_DP<15>")
	)
	(segment
		(start 127.312166 -295.63949)
		(end 127.333502 -295.651936)
		(width 0.1143)
		(layer "In11.Cu")
		(net "P5E_CPU1_P3_TX_DP<15>")
	)
	(segment
		(start 144.213326 -321.99707)
		(end 147.792694 -339.993224)
		(width 0.14224)
		(layer "In11.Cu")
		(net "P5E_CPU1_P3_TX_DP<15>")
	)
	(segment
		(start 127.301752 -280.078942)
		(end 127.300736 -280.07945)
		(width 0.1143)
		(layer "In11.Cu")
		(net "P5E_CPU1_P3_TX_DP<15>")
	)
	(segment
		(start 126.322074 -277.790656)
		(end 126.393194 -277.832058)
		(width 0.1143)
		(layer "In11.Cu")
		(net "P5E_CPU1_P3_TX_DP<15>")
	)
	(segment
		(start 140.859256 -372.164102)
		(end 139.863576 -374.567958)
		(width 0.14224)
		(layer "In11.Cu")
		(net "P5E_CPU1_P3_TX_DP<15>")
	)
	(segment
		(start 126.862332 -293.83101)
		(end 126.831852 -293.84879)
		(width 0.1143)
		(layer "In11.Cu")
		(net "P5E_CPU1_P3_TX_DP<15>")
	)
	(segment
		(start 126.831852 -291.583618)
		(end 126.862332 -291.601398)
		(width 0.1143)
		(layer "In11.Cu")
		(net "P5E_CPU1_P3_TX_DP<15>")
	)
	(segment
		(start 126.311406 -277.783036)
		(end 126.322074 -277.790656)
		(width 0.1143)
		(layer "In11.Cu")
		(net "P5E_CPU1_P3_TX_DP<15>")
	)
	(arc
		(start 126.864364 -286.742632)
		(mid 126.978293 -286.875779)
		(end 127.019304 -287.046162)
		(width 0.1143)
		(layer "In11.Cu")
		(net "P5E_CPU1_P3_TX_DP<15>")
	)
	(arc
		(start 126.795276 -287.390078)
		(mid 126.614624 -287.592823)
		(end 126.549404 -287.856422)
		(width 0.1143)
		(layer "In11.Cu")
		(net "P5E_CPU1_P3_TX_DP<15>")
	)
	(arc
		(start 139.863576 -374.567958)
		(mid 139.663202 -375.228751)
		(end 139.595606 -375.915936)
		(width 0.14224)
		(layer "In11.Cu")
		(net "P5E_CPU1_P3_TX_DP<15>")
	)
	(arc
		(start 125.619256 -276.622002)
		(mid 125.700689 -276.8244)
		(end 125.852682 -276.980904)
		(width 0.1143)
		(layer "In11.Cu")
		(net "P5E_CPU1_P3_TX_DP<15>")
	)
	(arc
		(start 126.862332 -289.981386)
		(mid 127.019309 -290.286186)
		(end 126.862332 -290.590986)
		(width 0.1143)
		(layer "In11.Cu")
		(net "P5E_CPU1_P3_TX_DP<15>")
	)
	(arc
		(start 126.862332 -291.601398)
		(mid 127.019309 -291.906198)
		(end 126.862332 -292.210998)
		(width 0.1143)
		(layer "In11.Cu")
		(net "P5E_CPU1_P3_TX_DP<15>")
	)
	(arc
		(start 127.019304 -278.946356)
		(mid 127.083819 -279.208575)
		(end 127.262636 -279.410922)
		(width 0.1143)
		(layer "In11.Cu")
		(net "P5E_CPU1_P3_TX_DP<15>")
	)
	(arc
		(start 126.792736 -293.87165)
		(mid 126.549409 -294.336216)
		(end 126.792736 -294.800782)
		(width 0.1143)
		(layer "In11.Cu")
		(net "P5E_CPU1_P3_TX_DP<15>")
	)
	(arc
		(start 126.862332 -294.841422)
		(mid 126.977759 -294.974798)
		(end 127.019304 -295.146222)
		(width 0.1143)
		(layer "In11.Cu")
		(net "P5E_CPU1_P3_TX_DP<15>")
	)
	(arc
		(start 127.019304 -295.146222)
		(mid 127.083819 -295.408441)
		(end 127.262636 -295.610788)
		(width 0.1143)
		(layer "In11.Cu")
		(net "P5E_CPU1_P3_TX_DP<15>")
	)
	(arc
		(start 126.393448 -277.832058)
		(mid 126.508124 -277.965392)
		(end 126.549404 -278.13635)
		(width 0.1143)
		(layer "In11.Cu")
		(net "P5E_CPU1_P3_TX_DP<15>")
	)
	(arc
		(start 139.595606 -379.60808)
		(mid 139.585904 -379.656764)
		(end 139.558268 -379.697996)
		(width 0.14224)
		(layer "In11.Cu")
		(net "P5E_CPU1_P3_TX_DP<15>")
	)
	(arc
		(start 139.505944 -379.75032)
		(mid 139.464704 -379.777939)
		(end 139.416028 -379.787658)
		(width 0.14224)
		(layer "In11.Cu")
		(net "P5E_CPU1_P3_TX_DP<15>")
	)
	(arc
		(start 141.402054 -365.752126)
		(mid 141.130508 -366.647242)
		(end 141.038834 -367.578132)
		(width 0.14224)
		(layer "In11.Cu")
		(net "P5E_CPU1_P3_TX_DP<15>")
	)
	(arc
		(start 126.549404 -287.856422)
		(mid 126.613919 -288.118641)
		(end 126.792736 -288.320988)
		(width 0.1143)
		(layer "In11.Cu")
		(net "P5E_CPU1_P3_TX_DP<15>")
	)
	(arc
		(start 127.489712 -296.115232)
		(mid 127.533108 -296.333781)
		(end 127.656844 -296.519092)
		(width 0.1143)
		(layer "In11.Cu")
		(net "P5E_CPU1_P3_TX_DP<15>")
	)
	(arc
		(start 126.864364 -288.362644)
		(mid 126.978293 -288.495791)
		(end 127.019304 -288.666174)
		(width 0.1143)
		(layer "In11.Cu")
		(net "P5E_CPU1_P3_TX_DP<15>")
	)
	(arc
		(start 127.333502 -295.651936)
		(mid 127.382434 -295.694024)
		(end 127.423418 -295.743884)
		(width 0.1143)
		(layer "In11.Cu")
		(net "P5E_CPU1_P3_TX_DP<15>")
	)
	(arc
		(start 127.019304 -287.046162)
		(mid 126.977755 -287.217584)
		(end 126.862332 -287.350962)
		(width 0.1143)
		(layer "In11.Cu")
		(net "P5E_CPU1_P3_TX_DP<15>")
	)
	(arc
		(start 147.792694 -348.820232)
		(mid 147.647452 -350.294336)
		(end 147.217384 -351.711768)
		(width 0.14224)
		(layer "In11.Cu")
		(net "P5E_CPU1_P3_TX_DP<15>")
	)
	(arc
		(start 127.423672 -295.74363)
		(mid 127.472725 -295.84493)
		(end 127.489458 -295.956228)
		(width 0.1143)
		(layer "In11.Cu")
		(net "P5E_CPU1_P3_TX_DP<15>")
	)
	(arc
		(start 127.262636 -280.101802)
		(mid 127.083823 -280.304152)
		(end 127.019304 -280.566368)
		(width 0.1143)
		(layer "In11.Cu")
		(net "P5E_CPU1_P3_TX_DP<15>")
	)
	(arc
		(start 125.615446 -276.599142)
		(mid 125.617234 -276.610591)
		(end 125.619256 -276.622002)
		(width 0.1143)
		(layer "In11.Cu")
		(net "P5E_CPU1_P3_TX_DP<15>")
	)
	(arc
		(start 126.792736 -290.631626)
		(mid 126.549409 -291.096192)
		(end 126.792736 -291.560758)
		(width 0.1143)
		(layer "In11.Cu")
		(net "P5E_CPU1_P3_TX_DP<15>")
	)
	(arc
		(start 127.333502 -279.45207)
		(mid 127.48943 -279.756362)
		(end 127.333502 -280.060654)
		(width 0.1143)
		(layer "In11.Cu")
		(net "P5E_CPU1_P3_TX_DP<15>")
	)
	(arc
		(start 126.862332 -283.501592)
		(mid 127.019309 -283.806392)
		(end 126.862332 -284.111192)
		(width 0.1143)
		(layer "In11.Cu")
		(net "P5E_CPU1_P3_TX_DP<15>")
	)
	(arc
		(start 126.792736 -284.151832)
		(mid 126.549409 -284.616398)
		(end 126.792736 -285.080964)
		(width 0.1143)
		(layer "In11.Cu")
		(net "P5E_CPU1_P3_TX_DP<15>")
	)
	(arc
		(start 127.736092 -296.59834)
		(mid 127.763926 -296.639667)
		(end 127.773684 -296.68851)
		(width 0.1143)
		(layer "In11.Cu")
		(net "P5E_CPU1_P3_TX_DP<15>")
	)
	(arc
		(start 126.862332 -278.641556)
		(mid 126.977759 -278.774932)
		(end 127.019304 -278.946356)
		(width 0.1143)
		(layer "In11.Cu")
		(net "P5E_CPU1_P3_TX_DP<15>")
	)
	(arc
		(start 126.862332 -281.88158)
		(mid 127.019309 -282.18638)
		(end 126.862332 -282.49118)
		(width 0.1143)
		(layer "In11.Cu")
		(net "P5E_CPU1_P3_TX_DP<15>")
	)
	(arc
		(start 126.862332 -293.22141)
		(mid 127.019309 -293.52621)
		(end 126.862332 -293.83101)
		(width 0.1143)
		(layer "In11.Cu")
		(net "P5E_CPU1_P3_TX_DP<15>")
	)
	(arc
		(start 127.019304 -280.566368)
		(mid 126.977755 -280.73779)
		(end 126.862332 -280.871168)
		(width 0.1143)
		(layer "In11.Cu")
		(net "P5E_CPU1_P3_TX_DP<15>")
	)
	(arc
		(start 125.921516 -277.021036)
		(mid 126.037563 -277.154507)
		(end 126.079504 -277.326344)
		(width 0.1143)
		(layer "In11.Cu")
		(net "P5E_CPU1_P3_TX_DP<15>")
	)
	(arc
		(start 126.792736 -292.251638)
		(mid 126.549409 -292.716204)
		(end 126.792736 -293.18077)
		(width 0.1143)
		(layer "In11.Cu")
		(net "P5E_CPU1_P3_TX_DP<15>")
	)
	(arc
		(start 126.862332 -285.121604)
		(mid 127.019309 -285.426404)
		(end 126.862332 -285.731204)
		(width 0.1143)
		(layer "In11.Cu")
		(net "P5E_CPU1_P3_TX_DP<15>")
	)
	(arc
		(start 126.079504 -277.329392)
		(mid 126.140794 -277.584151)
		(end 126.311406 -277.783036)
		(width 0.1143)
		(layer "In11.Cu")
		(net "P5E_CPU1_P3_TX_DP<15>")
	)
	(arc
		(start 126.792736 -280.911808)
		(mid 126.549409 -281.376374)
		(end 126.792736 -281.84094)
		(width 0.1143)
		(layer "In11.Cu")
		(net "P5E_CPU1_P3_TX_DP<15>")
	)
	(arc
		(start 127.019304 -288.666174)
		(mid 126.977755 -288.837596)
		(end 126.862332 -288.970974)
		(width 0.1143)
		(layer "In11.Cu")
		(net "P5E_CPU1_P3_TX_DP<15>")
	)
	(arc
		(start 140.936472 -371.909848)
		(mid 140.904112 -372.038872)
		(end 140.859256 -372.164102)
		(width 0.14224)
		(layer "In11.Cu")
		(net "P5E_CPU1_P3_TX_DP<15>")
	)
	(arc
		(start 126.792736 -289.011614)
		(mid 126.549409 -289.47618)
		(end 126.792736 -289.940746)
		(width 0.1143)
		(layer "In11.Cu")
		(net "P5E_CPU1_P3_TX_DP<15>")
	)
	(arc
		(start 126.792736 -282.53182)
		(mid 126.549409 -282.996386)
		(end 126.792736 -283.460952)
		(width 0.1143)
		(layer "In11.Cu")
		(net "P5E_CPU1_P3_TX_DP<15>")
	)
	(arc
		(start 126.549404 -278.13635)
		(mid 126.613919 -278.398569)
		(end 126.792736 -278.600916)
		(width 0.1143)
		(layer "In11.Cu")
		(net "P5E_CPU1_P3_TX_DP<15>")
	)
	(arc
		(start 126.792736 -285.771844)
		(mid 126.549409 -286.23641)
		(end 126.792736 -286.700976)
		(width 0.1143)
		(layer "In11.Cu")
		(net "P5E_CPU1_P3_TX_DP<15>")
	)
	(segment
		(start 124.767848 -277.870412)
		(end 125.2347 -278.13635)
		(width 0.12954)
		(layer "F.Cu")
		(net "P5E_CPU1_P3_TX_DP<14>")
	)
	(segment
		(start 138.377676 -376.956828)
		(end 138.107166 -376.686318)
		(width 0.12954)
		(layer "F.Cu")
		(net "P5E_CPU1_P3_TX_DP<14>")
	)
	(segment
		(start 138.107166 -376.686318)
		(end 137.403586 -376.686318)
		(width 0.12954)
		(layer "F.Cu")
		(net "P5E_CPU1_P3_TX_DP<14>")
	)
	(segment
		(start 137.403586 -376.686318)
		(end 137.107676 -376.982228)
		(width 0.12954)
		(layer "F.Cu")
		(net "P5E_CPU1_P3_TX_DP<14>")
	)
	(segment
		(start 125.85954 -283.465016)
		(end 125.860302 -283.465524)
		(width 0.1143)
		(layer "In11.Cu")
		(net "P5E_CPU1_P3_TX_DP<14>")
	)
	(segment
		(start 125.927358 -287.34766)
		(end 125.923548 -287.350454)
		(width 0.1143)
		(layer "In11.Cu")
		(net "P5E_CPU1_P3_TX_DP<14>")
	)
	(segment
		(start 125.891798 -288.988754)
		(end 125.890782 -288.989262)
		(width 0.1143)
		(layer "In11.Cu")
		(net "P5E_CPU1_P3_TX_DP<14>")
	)
	(segment
		(start 125.89256 -293.848536)
		(end 125.891798 -293.84879)
		(width 0.1143)
		(layer "In11.Cu")
		(net "P5E_CPU1_P3_TX_DP<14>")
	)
	(segment
		(start 125.894338 -294.824912)
		(end 125.924564 -294.842946)
		(width 0.1143)
		(layer "In11.Cu")
		(net "P5E_CPU1_P3_TX_DP<14>")
	)
	(segment
		(start 125.890782 -285.103316)
		(end 125.891798 -285.103824)
		(width 0.1143)
		(layer "In11.Cu")
		(net "P5E_CPU1_P3_TX_DP<14>")
	)
	(segment
		(start 125.85954 -278.60498)
		(end 125.860302 -278.605488)
		(width 0.1143)
		(layer "In11.Cu")
		(net "P5E_CPU1_P3_TX_DP<14>")
	)
	(segment
		(start 141.0208 -363.30636)
		(end 140.048488 -365.653828)
		(width 0.14224)
		(layer "In11.Cu")
		(net "P5E_CPU1_P3_TX_DP<14>")
	)
	(segment
		(start 125.89256 -293.204138)
		(end 125.894592 -293.205408)
		(width 0.1143)
		(layer "In11.Cu")
		(net "P5E_CPU1_P3_TX_DP<14>")
	)
	(segment
		(start 126.36373 -295.634664)
		(end 126.393448 -295.651936)
		(width 0.1143)
		(layer "In11.Cu")
		(net "P5E_CPU1_P3_TX_DP<14>")
	)
	(segment
		(start 125.891798 -291.583618)
		(end 125.89256 -291.584126)
		(width 0.1143)
		(layer "In11.Cu")
		(net "P5E_CPU1_P3_TX_DP<14>")
	)
	(segment
		(start 125.89256 -288.9885)
		(end 125.891798 -288.988754)
		(width 0.1143)
		(layer "In11.Cu")
		(net "P5E_CPU1_P3_TX_DP<14>")
	)
	(segment
		(start 143.281654 -322.204842)
		(end 146.83105 -340.04885)
		(width 0.14224)
		(layer "In11.Cu")
		(net "P5E_CPU1_P3_TX_DP<14>")
	)
	(segment
		(start 141.021054 -363.30636)
		(end 141.0208 -363.30636)
		(width 0.14224)
		(layer "In11.Cu")
		(net "P5E_CPU1_P3_TX_DP<14>")
	)
	(segment
		(start 125.890782 -290.609274)
		(end 125.852682 -290.631626)
		(width 0.1143)
		(layer "In11.Cu")
		(net "P5E_CPU1_P3_TX_DP<14>")
	)
	(segment
		(start 125.858778 -288.324544)
		(end 125.859032 -288.324544)
		(width 0.1143)
		(layer "In11.Cu")
		(net "P5E_CPU1_P3_TX_DP<14>")
	)
	(segment
		(start 125.891798 -284.128972)
		(end 125.890782 -284.12948)
		(width 0.1143)
		(layer "In11.Cu")
		(net "P5E_CPU1_P3_TX_DP<14>")
	)
	(segment
		(start 125.2347 -278.13635)
		(end 125.532642 -278.13635)
		(width 0.1143)
		(layer "In11.Cu")
		(net "P5E_CPU1_P3_TX_DP<14>")
	)
	(segment
		(start 125.852682 -288.320988)
		(end 125.858778 -288.324544)
		(width 0.1143)
		(layer "In11.Cu")
		(net "P5E_CPU1_P3_TX_DP<14>")
	)
	(segment
		(start 140.048488 -365.653828)
		(end 140.029184 -365.66348)
		(width 0.14224)
		(layer "In11.Cu")
		(net "P5E_CPU1_P3_TX_DP<14>")
	)
	(segment
		(start 146.83105 -340.04885)
		(end 146.83105 -348.20987)
		(width 0.14224)
		(layer "In11.Cu")
		(net "P5E_CPU1_P3_TX_DP<14>")
	)
	(segment
		(start 125.89256 -289.964114)
		(end 125.894592 -289.965384)
		(width 0.1143)
		(layer "In11.Cu")
		(net "P5E_CPU1_P3_TX_DP<14>")
	)
	(segment
		(start 126.079504 -287.046162)
		(end 126.079504 -287.050734)
		(width 0.1143)
		(layer "In11.Cu")
		(net "P5E_CPU1_P3_TX_DP<14>")
	)
	(segment
		(start 126.783084 -296.838116)
		(end 126.783084 -296.866564)
		(width 0.1143)
		(layer "In11.Cu")
		(net "P5E_CPU1_P3_TX_DP<14>")
	)
	(segment
		(start 125.852682 -293.18077)
		(end 125.890782 -293.203122)
		(width 0.1143)
		(layer "In11.Cu")
		(net "P5E_CPU1_P3_TX_DP<14>")
	)
	(segment
		(start 125.852682 -285.080964)
		(end 125.890782 -285.103316)
		(width 0.1143)
		(layer "In11.Cu")
		(net "P5E_CPU1_P3_TX_DP<14>")
	)
	(segment
		(start 125.891798 -280.888948)
		(end 125.890782 -280.889456)
		(width 0.1143)
		(layer "In11.Cu")
		(net "P5E_CPU1_P3_TX_DP<14>")
	)
	(segment
		(start 125.895354 -284.127194)
		(end 125.894846 -284.127194)
		(width 0.1143)
		(layer "In11.Cu")
		(net "P5E_CPU1_P3_TX_DP<14>")
	)
	(segment
		(start 125.891798 -293.84879)
		(end 125.890782 -293.849298)
		(width 0.1143)
		(layer "In11.Cu")
		(net "P5E_CPU1_P3_TX_DP<14>")
	)
	(segment
		(start 126.549658 -295.956228)
		(end 126.549658 -296.070274)
		(width 0.1143)
		(layer "In11.Cu")
		(net "P5E_CPU1_P3_TX_DP<14>")
	)
	(segment
		(start 126.783084 -297.020996)
		(end 126.942088 -297.544998)
		(width 0.14224)
		(layer "In11.Cu")
		(net "P5E_CPU1_P3_TX_DP<14>")
	)
	(segment
		(start 125.895354 -285.747206)
		(end 125.894846 -285.747206)
		(width 0.1143)
		(layer "In11.Cu")
		(net "P5E_CPU1_P3_TX_DP<14>")
	)
	(segment
		(start 126.942088 -297.544998)
		(end 127.623062 -298.563792)
		(width 0.14224)
		(layer "In11.Cu")
		(net "P5E_CPU1_P3_TX_DP<14>")
	)
	(segment
		(start 125.894846 -282.507182)
		(end 125.89256 -282.508706)
		(width 0.1143)
		(layer "In11.Cu")
		(net "P5E_CPU1_P3_TX_DP<14>")
	)
	(segment
		(start 125.890782 -289.963098)
		(end 125.891798 -289.963606)
		(width 0.1143)
		(layer "In11.Cu")
		(net "P5E_CPU1_P3_TX_DP<14>")
	)
	(segment
		(start 125.890782 -291.58311)
		(end 125.891798 -291.583618)
		(width 0.1143)
		(layer "In11.Cu")
		(net "P5E_CPU1_P3_TX_DP<14>")
	)
	(segment
		(start 125.895354 -282.507182)
		(end 125.894846 -282.507182)
		(width 0.1143)
		(layer "In11.Cu")
		(net "P5E_CPU1_P3_TX_DP<14>")
	)
	(segment
		(start 125.887226 -292.231572)
		(end 125.88621 -292.23208)
		(width 0.1143)
		(layer "In11.Cu")
		(net "P5E_CPU1_P3_TX_DP<14>")
	)
	(segment
		(start 125.852682 -286.700976)
		(end 125.925326 -286.743394)
		(width 0.1143)
		(layer "In11.Cu")
		(net "P5E_CPU1_P3_TX_DP<14>")
	)
	(segment
		(start 140.899134 -316.456822)
		(end 143.281654 -322.204842)
		(width 0.14224)
		(layer "In11.Cu")
		(net "P5E_CPU1_P3_TX_DP<14>")
	)
	(segment
		(start 125.895354 -290.606988)
		(end 125.894846 -290.606988)
		(width 0.1143)
		(layer "In11.Cu")
		(net "P5E_CPU1_P3_TX_DP<14>")
	)
	(segment
		(start 126.092204 -278.953722)
		(end 126.092204 -278.966168)
		(width 0.1143)
		(layer "In11.Cu")
		(net "P5E_CPU1_P3_TX_DP<14>")
	)
	(segment
		(start 125.894846 -293.847012)
		(end 125.89256 -293.848536)
		(width 0.1143)
		(layer "In11.Cu")
		(net "P5E_CPU1_P3_TX_DP<14>")
	)
	(segment
		(start 125.895354 -288.986976)
		(end 125.894846 -288.986976)
		(width 0.1143)
		(layer "In11.Cu")
		(net "P5E_CPU1_P3_TX_DP<14>")
	)
	(segment
		(start 125.532642 -278.13635)
		(end 125.615446 -278.219154)
		(width 0.1143)
		(layer "In11.Cu")
		(net "P5E_CPU1_P3_TX_DP<14>")
	)
	(segment
		(start 125.89256 -278.624284)
		(end 125.89256 -278.62403)
		(width 0.1143)
		(layer "In11.Cu")
		(net "P5E_CPU1_P3_TX_DP<14>")
	)
	(segment
		(start 126.067566 -280.57475)
		(end 126.067566 -280.58618)
		(width 0.1143)
		(layer "In11.Cu")
		(net "P5E_CPU1_P3_TX_DP<14>")
	)
	(segment
		(start 125.860302 -283.465524)
		(end 125.891798 -283.483812)
		(width 0.1143)
		(layer "In11.Cu")
		(net "P5E_CPU1_P3_TX_DP<14>")
	)
	(segment
		(start 125.890782 -293.203122)
		(end 125.891798 -293.20363)
		(width 0.1143)
		(layer "In11.Cu")
		(net "P5E_CPU1_P3_TX_DP<14>")
	)
	(segment
		(start 125.890782 -282.509468)
		(end 125.852682 -282.53182)
		(width 0.1143)
		(layer "In11.Cu")
		(net "P5E_CPU1_P3_TX_DP<14>")
	)
	(segment
		(start 125.89256 -278.62403)
		(end 125.893576 -278.624538)
		(width 0.1143)
		(layer "In11.Cu")
		(net "P5E_CPU1_P3_TX_DP<14>")
	)
	(segment
		(start 125.894592 -283.48559)
		(end 125.8951 -283.48559)
		(width 0.1143)
		(layer "In11.Cu")
		(net "P5E_CPU1_P3_TX_DP<14>")
	)
	(segment
		(start 125.852682 -294.800782)
		(end 125.890782 -294.823134)
		(width 0.1143)
		(layer "In11.Cu")
		(net "P5E_CPU1_P3_TX_DP<14>")
	)
	(segment
		(start 125.890782 -285.749492)
		(end 125.852682 -285.771844)
		(width 0.1143)
		(layer "In11.Cu")
		(net "P5E_CPU1_P3_TX_DP<14>")
	)
	(segment
		(start 146.421856 -350.266508)
		(end 141.021054 -363.30636)
		(width 0.14224)
		(layer "In11.Cu")
		(net "P5E_CPU1_P3_TX_DP<14>")
	)
	(segment
		(start 125.89256 -282.508706)
		(end 125.891798 -282.50896)
		(width 0.1143)
		(layer "In11.Cu")
		(net "P5E_CPU1_P3_TX_DP<14>")
	)
	(segment
		(start 126.828804 -296.792396)
		(end 126.783084 -296.838116)
		(width 0.1143)
		(layer "In11.Cu")
		(net "P5E_CPU1_P3_TX_DP<14>")
	)
	(segment
		(start 126.361952 -279.433782)
		(end 126.393448 -279.452324)
		(width 0.1143)
		(layer "In11.Cu")
		(net "P5E_CPU1_P3_TX_DP<14>")
	)
	(segment
		(start 125.891798 -289.963606)
		(end 125.89256 -289.964114)
		(width 0.1143)
		(layer "In11.Cu")
		(net "P5E_CPU1_P3_TX_DP<14>")
	)
	(segment
		(start 125.891798 -278.623776)
		(end 125.89256 -278.624284)
		(width 0.1143)
		(layer "In11.Cu")
		(net "P5E_CPU1_P3_TX_DP<14>")
	)
	(segment
		(start 126.461266 -295.714928)
		(end 126.46152 -295.715182)
		(width 0.1143)
		(layer "In11.Cu")
		(net "P5E_CPU1_P3_TX_DP<14>")
	)
	(segment
		(start 140.029184 -365.66348)
		(end 139.85748 -366.079024)
		(width 0.14224)
		(layer "In11.Cu")
		(net "P5E_CPU1_P3_TX_DP<14>")
	)
	(segment
		(start 125.890782 -284.12948)
		(end 125.852682 -284.151832)
		(width 0.1143)
		(layer "In11.Cu")
		(net "P5E_CPU1_P3_TX_DP<14>")
	)
	(segment
		(start 127.623062 -298.563792)
		(end 134.729474 -307.223414)
		(width 0.14224)
		(layer "In11.Cu")
		(net "P5E_CPU1_P3_TX_DP<14>")
	)
	(segment
		(start 125.89256 -283.48432)
		(end 125.894592 -283.48559)
		(width 0.1143)
		(layer "In11.Cu")
		(net "P5E_CPU1_P3_TX_DP<14>")
	)
	(segment
		(start 126.642622 -296.295318)
		(end 126.791212 -296.443908)
		(width 0.1143)
		(layer "In11.Cu")
		(net "P5E_CPU1_P3_TX_DP<14>")
	)
	(segment
		(start 125.890782 -292.229286)
		(end 125.88875 -292.230556)
		(width 0.1143)
		(layer "In11.Cu")
		(net "P5E_CPU1_P3_TX_DP<14>")
	)
	(segment
		(start 125.891798 -281.8638)
		(end 125.89256 -281.864308)
		(width 0.1143)
		(layer "In11.Cu")
		(net "P5E_CPU1_P3_TX_DP<14>")
	)
	(segment
		(start 125.89256 -281.864308)
		(end 125.894592 -281.865578)
		(width 0.1143)
		(layer "In11.Cu")
		(net "P5E_CPU1_P3_TX_DP<14>")
	)
	(segment
		(start 125.852682 -283.460952)
		(end 125.85954 -283.465016)
		(width 0.1143)
		(layer "In11.Cu")
		(net "P5E_CPU1_P3_TX_DP<14>")
	)
	(segment
		(start 125.859032 -288.324544)
		(end 125.894846 -288.345372)
		(width 0.1143)
		(layer "In11.Cu")
		(net "P5E_CPU1_P3_TX_DP<14>")
	)
	(segment
		(start 125.89256 -291.584126)
		(end 125.923548 -291.601906)
		(width 0.1143)
		(layer "In11.Cu")
		(net "P5E_CPU1_P3_TX_DP<14>")
	)
	(segment
		(start 139.64539 -371.611652)
		(end 139.588494 -371.99062)
		(width 0.14224)
		(layer "In11.Cu")
		(net "P5E_CPU1_P3_TX_DP<14>")
	)
	(segment
		(start 125.89256 -284.128718)
		(end 125.891798 -284.128972)
		(width 0.1143)
		(layer "In11.Cu")
		(net "P5E_CPU1_P3_TX_DP<14>")
	)
	(segment
		(start 126.393448 -280.060654)
		(end 126.348744 -280.086562)
		(width 0.1143)
		(layer "In11.Cu")
		(net "P5E_CPU1_P3_TX_DP<14>")
	)
	(segment
		(start 125.891798 -285.748984)
		(end 125.890782 -285.749492)
		(width 0.1143)
		(layer "In11.Cu")
		(net "P5E_CPU1_P3_TX_DP<14>")
	)
	(segment
		(start 125.891798 -285.103824)
		(end 125.89256 -285.104332)
		(width 0.1143)
		(layer "In11.Cu")
		(net "P5E_CPU1_P3_TX_DP<14>")
	)
	(segment
		(start 125.894592 -281.865578)
		(end 125.8951 -281.865578)
		(width 0.1143)
		(layer "In11.Cu")
		(net "P5E_CPU1_P3_TX_DP<14>")
	)
	(segment
		(start 125.88875 -292.230556)
		(end 125.887226 -292.231572)
		(width 0.1143)
		(layer "In11.Cu")
		(net "P5E_CPU1_P3_TX_DP<14>")
	)
	(segment
		(start 125.891798 -290.608766)
		(end 125.890782 -290.609274)
		(width 0.1143)
		(layer "In11.Cu")
		(net "P5E_CPU1_P3_TX_DP<14>")
	)
	(segment
		(start 125.890782 -293.849298)
		(end 125.852682 -293.87165)
		(width 0.1143)
		(layer "In11.Cu")
		(net "P5E_CPU1_P3_TX_DP<14>")
	)
	(segment
		(start 125.894592 -285.105602)
		(end 125.8951 -285.105602)
		(width 0.1143)
		(layer "In11.Cu")
		(net "P5E_CPU1_P3_TX_DP<14>")
	)
	(segment
		(start 138.086846 -376.665998)
		(end 138.377676 -376.956828)
		(width 0.14224)
		(layer "In11.Cu")
		(net "P5E_CPU1_P3_TX_DP<14>")
	)
	(segment
		(start 125.894846 -285.747206)
		(end 125.89256 -285.74873)
		(width 0.1143)
		(layer "In11.Cu")
		(net "P5E_CPU1_P3_TX_DP<14>")
	)
	(segment
		(start 125.852682 -281.84094)
		(end 125.890782 -281.863292)
		(width 0.1143)
		(layer "In11.Cu")
		(net "P5E_CPU1_P3_TX_DP<14>")
	)
	(segment
		(start 125.923548 -287.350454)
		(end 125.855222 -287.390078)
		(width 0.1143)
		(layer "In11.Cu")
		(net "P5E_CPU1_P3_TX_DP<14>")
	)
	(segment
		(start 125.89256 -285.74873)
		(end 125.891798 -285.748984)
		(width 0.1143)
		(layer "In11.Cu")
		(net "P5E_CPU1_P3_TX_DP<14>")
	)
	(segment
		(start 125.852682 -291.560758)
		(end 125.890782 -291.58311)
		(width 0.1143)
		(layer "In11.Cu")
		(net "P5E_CPU1_P3_TX_DP<14>")
	)
	(segment
		(start 126.783084 -296.866564)
		(end 126.783084 -297.020996)
		(width 0.14224)
		(layer "In11.Cu")
		(net "P5E_CPU1_P3_TX_DP<14>")
	)
	(segment
		(start 125.894846 -288.345372)
		(end 125.8951 -288.345372)
		(width 0.1143)
		(layer "In11.Cu")
		(net "P5E_CPU1_P3_TX_DP<14>")
	)
	(segment
		(start 125.891798 -292.228778)
		(end 125.890782 -292.229286)
		(width 0.1143)
		(layer "In11.Cu")
		(net "P5E_CPU1_P3_TX_DP<14>")
	)
	(segment
		(start 139.04849 -373.130064)
		(end 136.86917 -375.309384)
		(width 0.14224)
		(layer "In11.Cu")
		(net "P5E_CPU1_P3_TX_DP<14>")
	)
	(segment
		(start 125.890782 -280.889456)
		(end 125.852682 -280.911808)
		(width 0.1143)
		(layer "In11.Cu")
		(net "P5E_CPU1_P3_TX_DP<14>")
	)
	(segment
		(start 136.739376 -375.623074)
		(end 136.739376 -376.188986)
		(width 0.14224)
		(layer "In11.Cu")
		(net "P5E_CPU1_P3_TX_DP<14>")
	)
	(segment
		(start 136.859264 -376.478546)
		(end 136.867646 -376.486928)
		(width 0.14224)
		(layer "In11.Cu")
		(net "P5E_CPU1_P3_TX_DP<14>")
	)
	(segment
		(start 125.88621 -292.23208)
		(end 125.852682 -292.251638)
		(width 0.1143)
		(layer "In11.Cu")
		(net "P5E_CPU1_P3_TX_DP<14>")
	)
	(segment
		(start 125.89256 -292.22827)
		(end 125.891798 -292.228778)
		(width 0.1143)
		(layer "In11.Cu")
		(net "P5E_CPU1_P3_TX_DP<14>")
	)
	(segment
		(start 125.890782 -288.989262)
		(end 125.852682 -289.011614)
		(width 0.1143)
		(layer "In11.Cu")
		(net "P5E_CPU1_P3_TX_DP<14>")
	)
	(segment
		(start 125.894592 -293.205408)
		(end 125.8951 -293.205408)
		(width 0.1143)
		(layer "In11.Cu")
		(net "P5E_CPU1_P3_TX_DP<14>")
	)
	(segment
		(start 125.89256 -290.608512)
		(end 125.891798 -290.608766)
		(width 0.1143)
		(layer "In11.Cu")
		(net "P5E_CPU1_P3_TX_DP<14>")
	)
	(segment
		(start 125.893576 -278.624538)
		(end 125.907292 -278.632412)
		(width 0.1143)
		(layer "In11.Cu")
		(net "P5E_CPU1_P3_TX_DP<14>")
	)
	(segment
		(start 125.89256 -280.88844)
		(end 125.891798 -280.888948)
		(width 0.1143)
		(layer "In11.Cu")
		(net "P5E_CPU1_P3_TX_DP<14>")
	)
	(segment
		(start 125.894846 -288.986976)
		(end 125.89256 -288.9885)
		(width 0.1143)
		(layer "In11.Cu")
		(net "P5E_CPU1_P3_TX_DP<14>")
	)
	(segment
		(start 125.895354 -293.847012)
		(end 125.894846 -293.847012)
		(width 0.1143)
		(layer "In11.Cu")
		(net "P5E_CPU1_P3_TX_DP<14>")
	)
	(segment
		(start 137.299954 -376.665998)
		(end 138.086846 -376.665998)
		(width 0.14224)
		(layer "In11.Cu")
		(net "P5E_CPU1_P3_TX_DP<14>")
	)
	(segment
		(start 125.891798 -283.483812)
		(end 125.89256 -283.48432)
		(width 0.1143)
		(layer "In11.Cu")
		(net "P5E_CPU1_P3_TX_DP<14>")
	)
	(segment
		(start 134.729474 -307.223414)
		(end 140.899134 -316.456822)
		(width 0.14224)
		(layer "In11.Cu")
		(net "P5E_CPU1_P3_TX_DP<14>")
	)
	(segment
		(start 125.89256 -285.104332)
		(end 125.894592 -285.105602)
		(width 0.1143)
		(layer "In11.Cu")
		(net "P5E_CPU1_P3_TX_DP<14>")
	)
	(segment
		(start 125.928628 -292.206934)
		(end 125.923548 -292.21049)
		(width 0.1143)
		(layer "In11.Cu")
		(net "P5E_CPU1_P3_TX_DP<14>")
	)
	(segment
		(start 125.923548 -291.601906)
		(end 125.928628 -291.605462)
		(width 0.1143)
		(layer "In11.Cu")
		(net "P5E_CPU1_P3_TX_DP<14>")
	)
	(segment
		(start 125.891798 -293.20363)
		(end 125.89256 -293.204138)
		(width 0.1143)
		(layer "In11.Cu")
		(net "P5E_CPU1_P3_TX_DP<14>")
	)
	(segment
		(start 125.923548 -292.21049)
		(end 125.89256 -292.22827)
		(width 0.1143)
		(layer "In11.Cu")
		(net "P5E_CPU1_P3_TX_DP<14>")
	)
	(segment
		(start 125.852682 -278.600916)
		(end 125.85954 -278.60498)
		(width 0.1143)
		(layer "In11.Cu")
		(net "P5E_CPU1_P3_TX_DP<14>")
	)
	(segment
		(start 139.654788 -367.09985)
		(end 139.654788 -371.485414)
		(width 0.14224)
		(layer "In11.Cu")
		(net "P5E_CPU1_P3_TX_DP<14>")
	)
	(segment
		(start 125.894592 -289.965384)
		(end 125.8951 -289.965384)
		(width 0.1143)
		(layer "In11.Cu")
		(net "P5E_CPU1_P3_TX_DP<14>")
	)
	(segment
		(start 126.828804 -296.534078)
		(end 126.828804 -296.792396)
		(width 0.1143)
		(layer "In11.Cu")
		(net "P5E_CPU1_P3_TX_DP<14>")
	)
	(segment
		(start 125.852682 -289.940746)
		(end 125.890782 -289.963098)
		(width 0.1143)
		(layer "In11.Cu")
		(net "P5E_CPU1_P3_TX_DP<14>")
	)
	(segment
		(start 125.890782 -281.863292)
		(end 125.891798 -281.8638)
		(width 0.1143)
		(layer "In11.Cu")
		(net "P5E_CPU1_P3_TX_DP<14>")
	)
	(segment
		(start 125.890782 -294.823134)
		(end 125.894338 -294.824912)
		(width 0.1143)
		(layer "In11.Cu")
		(net "P5E_CPU1_P3_TX_DP<14>")
	)
	(segment
		(start 125.894846 -284.127194)
		(end 125.89256 -284.128718)
		(width 0.1143)
		(layer "In11.Cu")
		(net "P5E_CPU1_P3_TX_DP<14>")
	)
	(segment
		(start 125.860302 -278.605488)
		(end 125.891798 -278.623776)
		(width 0.1143)
		(layer "In11.Cu")
		(net "P5E_CPU1_P3_TX_DP<14>")
	)
	(segment
		(start 125.894846 -290.606988)
		(end 125.89256 -290.608512)
		(width 0.1143)
		(layer "In11.Cu")
		(net "P5E_CPU1_P3_TX_DP<14>")
	)
	(segment
		(start 125.891798 -282.50896)
		(end 125.890782 -282.509468)
		(width 0.1143)
		(layer "In11.Cu")
		(net "P5E_CPU1_P3_TX_DP<14>")
	)
	(arc
		(start 125.925326 -286.743394)
		(mid 126.038733 -286.876283)
		(end 126.079504 -287.046162)
		(width 0.1143)
		(layer "In11.Cu")
		(net "P5E_CPU1_P3_TX_DP<14>")
	)
	(arc
		(start 125.852682 -280.911808)
		(mid 125.609355 -281.376374)
		(end 125.852682 -281.84094)
		(width 0.1143)
		(layer "In11.Cu")
		(net "P5E_CPU1_P3_TX_DP<14>")
	)
	(arc
		(start 126.549658 -296.070274)
		(mid 126.573767 -296.192038)
		(end 126.642622 -296.295318)
		(width 0.1143)
		(layer "In11.Cu")
		(net "P5E_CPU1_P3_TX_DP<14>")
	)
	(arc
		(start 125.852682 -289.011614)
		(mid 125.609355 -289.47618)
		(end 125.852682 -289.940746)
		(width 0.1143)
		(layer "In11.Cu")
		(net "P5E_CPU1_P3_TX_DP<14>")
	)
	(arc
		(start 125.8951 -285.105602)
		(mid 126.079833 -285.426294)
		(end 125.895354 -285.747206)
		(width 0.1143)
		(layer "In11.Cu")
		(net "P5E_CPU1_P3_TX_DP<14>")
	)
	(arc
		(start 125.907292 -278.632412)
		(mid 126.04268 -278.768361)
		(end 126.092204 -278.953722)
		(width 0.1143)
		(layer "In11.Cu")
		(net "P5E_CPU1_P3_TX_DP<14>")
	)
	(arc
		(start 125.619256 -278.242014)
		(mid 125.700689 -278.444412)
		(end 125.852682 -278.600916)
		(width 0.1143)
		(layer "In11.Cu")
		(net "P5E_CPU1_P3_TX_DP<14>")
	)
	(arc
		(start 136.86917 -375.309384)
		(mid 136.773034 -375.453307)
		(end 136.739376 -375.623074)
		(width 0.14224)
		(layer "In11.Cu")
		(net "P5E_CPU1_P3_TX_DP<14>")
	)
	(arc
		(start 125.852682 -292.251638)
		(mid 125.609355 -292.716204)
		(end 125.852682 -293.18077)
		(width 0.1143)
		(layer "In11.Cu")
		(net "P5E_CPU1_P3_TX_DP<14>")
	)
	(arc
		(start 126.079504 -287.050734)
		(mid 126.039249 -287.217547)
		(end 125.927358 -287.34766)
		(width 0.1143)
		(layer "In11.Cu")
		(net "P5E_CPU1_P3_TX_DP<14>")
	)
	(arc
		(start 126.348744 -280.086562)
		(mid 126.142885 -280.293063)
		(end 126.067566 -280.57475)
		(width 0.1143)
		(layer "In11.Cu")
		(net "P5E_CPU1_P3_TX_DP<14>")
	)
	(arc
		(start 125.924564 -294.842946)
		(mid 126.038447 -294.97356)
		(end 126.079504 -295.141904)
		(width 0.1143)
		(layer "In11.Cu")
		(net "P5E_CPU1_P3_TX_DP<14>")
	)
	(arc
		(start 125.8951 -288.345372)
		(mid 126.079833 -288.666064)
		(end 125.895354 -288.986976)
		(width 0.1143)
		(layer "In11.Cu")
		(net "P5E_CPU1_P3_TX_DP<14>")
	)
	(arc
		(start 125.852682 -282.53182)
		(mid 125.609355 -282.996386)
		(end 125.852682 -283.460952)
		(width 0.1143)
		(layer "In11.Cu")
		(net "P5E_CPU1_P3_TX_DP<14>")
	)
	(arc
		(start 126.092204 -278.966168)
		(mid 126.164469 -279.236097)
		(end 126.361952 -279.433782)
		(width 0.1143)
		(layer "In11.Cu")
		(net "P5E_CPU1_P3_TX_DP<14>")
	)
	(arc
		(start 126.393448 -279.452324)
		(mid 126.475429 -279.532974)
		(end 126.529084 -279.634696)
		(width 0.1143)
		(layer "In11.Cu")
		(net "P5E_CPU1_P3_TX_DP<14>")
	)
	(arc
		(start 126.529084 -279.634696)
		(mid 126.531705 -279.870105)
		(end 126.393448 -280.060654)
		(width 0.1143)
		(layer "In11.Cu")
		(net "P5E_CPU1_P3_TX_DP<14>")
	)
	(arc
		(start 139.561316 -372.114572)
		(mid 139.403914 -372.54627)
		(end 139.189206 -372.952518)
		(width 0.14224)
		(layer "In11.Cu")
		(net "P5E_CPU1_P3_TX_DP<14>")
	)
	(arc
		(start 136.867646 -376.486928)
		(mid 137.065991 -376.619458)
		(end 137.299954 -376.665998)
		(width 0.14224)
		(layer "In11.Cu")
		(net "P5E_CPU1_P3_TX_DP<14>")
	)
	(arc
		(start 125.615446 -278.219154)
		(mid 125.617234 -278.230603)
		(end 125.619256 -278.242014)
		(width 0.1143)
		(layer "In11.Cu")
		(net "P5E_CPU1_P3_TX_DP<14>")
	)
	(arc
		(start 126.46152 -295.715182)
		(mid 126.526887 -295.827917)
		(end 126.549658 -295.956228)
		(width 0.1143)
		(layer "In11.Cu")
		(net "P5E_CPU1_P3_TX_DP<14>")
	)
	(arc
		(start 126.067566 -280.58618)
		(mid 126.020655 -280.760809)
		(end 125.89256 -280.88844)
		(width 0.1143)
		(layer "In11.Cu")
		(net "P5E_CPU1_P3_TX_DP<14>")
	)
	(arc
		(start 125.8951 -289.965384)
		(mid 126.079833 -290.286076)
		(end 125.895354 -290.606988)
		(width 0.1143)
		(layer "In11.Cu")
		(net "P5E_CPU1_P3_TX_DP<14>")
	)
	(arc
		(start 126.393448 -295.651936)
		(mid 126.429311 -295.681328)
		(end 126.461266 -295.714928)
		(width 0.1143)
		(layer "In11.Cu")
		(net "P5E_CPU1_P3_TX_DP<14>")
	)
	(arc
		(start 125.8951 -293.205408)
		(mid 126.079833 -293.5261)
		(end 125.895354 -293.847012)
		(width 0.1143)
		(layer "In11.Cu")
		(net "P5E_CPU1_P3_TX_DP<14>")
	)
	(arc
		(start 125.852682 -285.771844)
		(mid 125.609355 -286.23641)
		(end 125.852682 -286.700976)
		(width 0.1143)
		(layer "In11.Cu")
		(net "P5E_CPU1_P3_TX_DP<14>")
	)
	(arc
		(start 139.654788 -371.485414)
		(mid 139.652441 -371.548708)
		(end 139.64539 -371.611652)
		(width 0.14224)
		(layer "In11.Cu")
		(net "P5E_CPU1_P3_TX_DP<14>")
	)
	(arc
		(start 125.928628 -291.605462)
		(mid 126.082726 -291.906198)
		(end 125.928628 -292.206934)
		(width 0.1143)
		(layer "In11.Cu")
		(net "P5E_CPU1_P3_TX_DP<14>")
	)
	(arc
		(start 125.852682 -293.87165)
		(mid 125.609355 -294.336216)
		(end 125.852682 -294.800782)
		(width 0.1143)
		(layer "In11.Cu")
		(net "P5E_CPU1_P3_TX_DP<14>")
	)
	(arc
		(start 136.739376 -376.188986)
		(mid 136.770528 -376.345689)
		(end 136.859264 -376.478546)
		(width 0.14224)
		(layer "In11.Cu")
		(net "P5E_CPU1_P3_TX_DP<14>")
	)
	(arc
		(start 146.83105 -348.20987)
		(mid 146.727731 -349.258339)
		(end 146.421856 -350.266508)
		(width 0.14224)
		(layer "In11.Cu")
		(net "P5E_CPU1_P3_TX_DP<14>")
	)
	(arc
		(start 125.8951 -283.48559)
		(mid 126.079833 -283.806282)
		(end 125.895354 -284.127194)
		(width 0.1143)
		(layer "In11.Cu")
		(net "P5E_CPU1_P3_TX_DP<14>")
	)
	(arc
		(start 125.852682 -290.631626)
		(mid 125.609355 -291.096192)
		(end 125.852682 -291.560758)
		(width 0.1143)
		(layer "In11.Cu")
		(net "P5E_CPU1_P3_TX_DP<14>")
	)
	(arc
		(start 125.852682 -284.151832)
		(mid 125.609355 -284.616398)
		(end 125.852682 -285.080964)
		(width 0.1143)
		(layer "In11.Cu")
		(net "P5E_CPU1_P3_TX_DP<14>")
	)
	(arc
		(start 126.079504 -295.141904)
		(mid 126.155658 -295.426326)
		(end 126.36373 -295.634664)
		(width 0.1143)
		(layer "In11.Cu")
		(net "P5E_CPU1_P3_TX_DP<14>")
	)
	(arc
		(start 125.8951 -281.865578)
		(mid 126.079833 -282.18627)
		(end 125.895354 -282.507182)
		(width 0.1143)
		(layer "In11.Cu")
		(net "P5E_CPU1_P3_TX_DP<14>")
	)
	(arc
		(start 139.189206 -372.952518)
		(mid 139.123981 -373.045359)
		(end 139.04849 -373.130064)
		(width 0.14224)
		(layer "In11.Cu")
		(net "P5E_CPU1_P3_TX_DP<14>")
	)
	(arc
		(start 126.791212 -296.443908)
		(mid 126.819046 -296.485235)
		(end 126.828804 -296.534078)
		(width 0.1143)
		(layer "In11.Cu")
		(net "P5E_CPU1_P3_TX_DP<14>")
	)
	(arc
		(start 139.85748 -366.079024)
		(mid 139.705881 -366.57946)
		(end 139.654788 -367.09985)
		(width 0.14224)
		(layer "In11.Cu")
		(net "P5E_CPU1_P3_TX_DP<14>")
	)
	(arc
		(start 125.60935 -287.856422)
		(mid 125.673865 -288.118641)
		(end 125.852682 -288.320988)
		(width 0.1143)
		(layer "In11.Cu")
		(net "P5E_CPU1_P3_TX_DP<14>")
	)
	(arc
		(start 139.588494 -371.99062)
		(mid 139.576962 -372.053047)
		(end 139.561316 -372.114572)
		(width 0.14224)
		(layer "In11.Cu")
		(net "P5E_CPU1_P3_TX_DP<14>")
	)
	(arc
		(start 125.855222 -287.390078)
		(mid 125.67457 -287.592823)
		(end 125.60935 -287.856422)
		(width 0.1143)
		(layer "In11.Cu")
		(net "P5E_CPU1_P3_TX_DP<14>")
	)
	(segment
		(start 135.642096 -369.03533)
		(end 135.912606 -369.30584)
		(width 0.12954)
		(layer "F.Cu")
		(net "P5E_CPU1_P3_TX_DP<13>")
	)
	(segment
		(start 135.912606 -370.00942)
		(end 135.616696 -370.30533)
		(width 0.12954)
		(layer "F.Cu")
		(net "P5E_CPU1_P3_TX_DP<13>")
	)
	(segment
		(start 135.912606 -369.30584)
		(end 135.912606 -370.00942)
		(width 0.12954)
		(layer "F.Cu")
		(net "P5E_CPU1_P3_TX_DP<13>")
	)
	(segment
		(start 124.767848 -274.630388)
		(end 125.2347 -274.896326)
		(width 0.12954)
		(layer "F.Cu")
		(net "P5E_CPU1_P3_TX_DP<13>")
	)
	(segment
		(start 124.947426 -285.751524)
		(end 124.945648 -285.75254)
		(width 0.1143)
		(layer "In11.Cu")
		(net "P5E_CPU1_P3_TX_DP<13>")
	)
	(segment
		(start 125.702568 -296.277284)
		(end 125.825758 -296.40022)
		(width 0.1143)
		(layer "In11.Cu")
		(net "P5E_CPU1_P3_TX_DP<13>")
	)
	(segment
		(start 124.920248 -294.805354)
		(end 124.951744 -294.823642)
		(width 0.1143)
		(layer "In11.Cu")
		(net "P5E_CPU1_P3_TX_DP<13>")
	)
	(segment
		(start 124.912628 -288.320988)
		(end 124.951744 -288.343848)
		(width 0.1143)
		(layer "In11.Cu")
		(net "P5E_CPU1_P3_TX_DP<13>")
	)
	(segment
		(start 124.947426 -292.231318)
		(end 124.945648 -292.232334)
		(width 0.1143)
		(layer "In11.Cu")
		(net "P5E_CPU1_P3_TX_DP<13>")
	)
	(segment
		(start 137.837418 -364.292134)
		(end 136.859772 -365.26978)
		(width 0.14224)
		(layer "In11.Cu")
		(net "P5E_CPU1_P3_TX_DP<13>")
	)
	(segment
		(start 124.949204 -288.990278)
		(end 124.948188 -288.990786)
		(width 0.1143)
		(layer "In11.Cu")
		(net "P5E_CPU1_P3_TX_DP<13>")
	)
	(segment
		(start 124.949204 -284.130496)
		(end 124.948188 -284.131004)
		(width 0.1143)
		(layer "In11.Cu")
		(net "P5E_CPU1_P3_TX_DP<13>")
	)
	(segment
		(start 124.95657 -293.206424)
		(end 124.957332 -293.206932)
		(width 0.1143)
		(layer "In11.Cu")
		(net "P5E_CPU1_P3_TX_DP<13>")
	)
	(segment
		(start 124.951744 -281.8638)
		(end 124.952506 -281.864308)
		(width 0.1143)
		(layer "In11.Cu")
		(net "P5E_CPU1_P3_TX_DP<13>")
	)
	(segment
		(start 124.945648 -285.75254)
		(end 124.944124 -285.753556)
		(width 0.1143)
		(layer "In11.Cu")
		(net "P5E_CPU1_P3_TX_DP<13>")
	)
	(segment
		(start 125.421898 -280.078942)
		(end 125.382782 -280.101802)
		(width 0.1143)
		(layer "In11.Cu")
		(net "P5E_CPU1_P3_TX_DP<13>")
	)
	(segment
		(start 142.361158 -322.470526)
		(end 145.87728 -340.148164)
		(width 0.14224)
		(layer "In11.Cu")
		(net "P5E_CPU1_P3_TX_DP<13>")
	)
	(segment
		(start 124.950728 -285.749492)
		(end 124.949204 -285.750508)
		(width 0.1143)
		(layer "In11.Cu")
		(net "P5E_CPU1_P3_TX_DP<13>")
	)
	(segment
		(start 124.948188 -290.610798)
		(end 124.947426 -290.611306)
		(width 0.1143)
		(layer "In11.Cu")
		(net "P5E_CPU1_P3_TX_DP<13>")
	)
	(segment
		(start 124.945648 -292.232334)
		(end 124.944124 -292.23335)
		(width 0.1143)
		(layer "In11.Cu")
		(net "P5E_CPU1_P3_TX_DP<13>")
	)
	(segment
		(start 124.9553 -294.825674)
		(end 124.95657 -294.826436)
		(width 0.1143)
		(layer "In11.Cu")
		(net "P5E_CPU1_P3_TX_DP<13>")
	)
	(segment
		(start 124.944124 -280.89352)
		(end 124.912628 -280.911808)
		(width 0.1143)
		(layer "In11.Cu")
		(net "P5E_CPU1_P3_TX_DP<13>")
	)
	(segment
		(start 124.952506 -276.028404)
		(end 124.951744 -276.028912)
		(width 0.1143)
		(layer "In11.Cu")
		(net "P5E_CPU1_P3_TX_DP<13>")
	)
	(segment
		(start 124.983494 -280.87066)
		(end 124.952506 -280.88844)
		(width 0.1143)
		(layer "In11.Cu")
		(net "P5E_CPU1_P3_TX_DP<13>")
	)
	(segment
		(start 124.950728 -292.229286)
		(end 124.949204 -292.230302)
		(width 0.1143)
		(layer "In11.Cu")
		(net "P5E_CPU1_P3_TX_DP<13>")
	)
	(segment
		(start 124.944124 -277.653496)
		(end 124.912628 -277.671784)
		(width 0.1143)
		(layer "In11.Cu")
		(net "P5E_CPU1_P3_TX_DP<13>")
	)
	(segment
		(start 124.951744 -287.368742)
		(end 124.915168 -287.390078)
		(width 0.1143)
		(layer "In11.Cu")
		(net "P5E_CPU1_P3_TX_DP<13>")
	)
	(segment
		(start 124.944124 -292.23335)
		(end 124.912628 -292.251638)
		(width 0.1143)
		(layer "In11.Cu")
		(net "P5E_CPU1_P3_TX_DP<13>")
	)
	(segment
		(start 125.421898 -279.433782)
		(end 125.452378 -279.451562)
		(width 0.1143)
		(layer "In11.Cu")
		(net "P5E_CPU1_P3_TX_DP<13>")
	)
	(segment
		(start 124.95657 -278.62657)
		(end 124.957332 -278.627078)
		(width 0.1143)
		(layer "In11.Cu")
		(net "P5E_CPU1_P3_TX_DP<13>")
	)
	(segment
		(start 124.950728 -282.509468)
		(end 124.949204 -282.510484)
		(width 0.1143)
		(layer "In11.Cu")
		(net "P5E_CPU1_P3_TX_DP<13>")
	)
	(segment
		(start 124.919486 -293.184834)
		(end 124.920248 -293.185342)
		(width 0.1143)
		(layer "In11.Cu")
		(net "P5E_CPU1_P3_TX_DP<13>")
	)
	(segment
		(start 124.948188 -288.990786)
		(end 124.947426 -288.991294)
		(width 0.1143)
		(layer "In11.Cu")
		(net "P5E_CPU1_P3_TX_DP<13>")
	)
	(segment
		(start 124.9553 -293.205662)
		(end 124.95657 -293.206424)
		(width 0.1143)
		(layer "In11.Cu")
		(net "P5E_CPU1_P3_TX_DP<13>")
	)
	(segment
		(start 124.951744 -293.84879)
		(end 124.950728 -293.849298)
		(width 0.1143)
		(layer "In11.Cu")
		(net "P5E_CPU1_P3_TX_DP<13>")
	)
	(segment
		(start 124.953776 -277.005034)
		(end 124.9553 -277.005796)
		(width 0.1143)
		(layer "In11.Cu")
		(net "P5E_CPU1_P3_TX_DP<13>")
	)
	(segment
		(start 124.949204 -293.850314)
		(end 124.912628 -293.87165)
		(width 0.1143)
		(layer "In11.Cu")
		(net "P5E_CPU1_P3_TX_DP<13>")
	)
	(segment
		(start 124.983494 -285.730696)
		(end 124.952506 -285.748476)
		(width 0.1143)
		(layer "In11.Cu")
		(net "P5E_CPU1_P3_TX_DP<13>")
	)
	(segment
		(start 124.912628 -283.460952)
		(end 124.950728 -283.483304)
		(width 0.1143)
		(layer "In11.Cu")
		(net "P5E_CPU1_P3_TX_DP<13>")
	)
	(segment
		(start 133.89737 -307.68417)
		(end 140.05052 -316.89294)
		(width 0.14224)
		(layer "In11.Cu")
		(net "P5E_CPU1_P3_TX_DP<13>")
	)
	(segment
		(start 124.912628 -294.800782)
		(end 124.919486 -294.804846)
		(width 0.1143)
		(layer "In11.Cu")
		(net "P5E_CPU1_P3_TX_DP<13>")
	)
	(segment
		(start 124.947426 -284.131512)
		(end 124.945648 -284.132528)
		(width 0.1143)
		(layer "In11.Cu")
		(net "P5E_CPU1_P3_TX_DP<13>")
	)
	(segment
		(start 124.950728 -285.103316)
		(end 124.951744 -285.103824)
		(width 0.1143)
		(layer "In11.Cu")
		(net "P5E_CPU1_P3_TX_DP<13>")
	)
	(segment
		(start 124.912628 -291.560758)
		(end 124.950728 -291.58311)
		(width 0.1143)
		(layer "In11.Cu")
		(net "P5E_CPU1_P3_TX_DP<13>")
	)
	(segment
		(start 124.950728 -284.12948)
		(end 124.949204 -284.130496)
		(width 0.1143)
		(layer "In11.Cu")
		(net "P5E_CPU1_P3_TX_DP<13>")
	)
	(segment
		(start 135.932926 -367.507266)
		(end 135.932926 -368.7445)
		(width 0.14224)
		(layer "In11.Cu")
		(net "P5E_CPU1_P3_TX_DP<13>")
	)
	(segment
		(start 124.952506 -290.608258)
		(end 124.951744 -290.608766)
		(width 0.1143)
		(layer "In11.Cu")
		(net "P5E_CPU1_P3_TX_DP<13>")
	)
	(segment
		(start 124.958348 -289.967416)
		(end 124.959618 -289.968178)
		(width 0.1143)
		(layer "In11.Cu")
		(net "P5E_CPU1_P3_TX_DP<13>")
	)
	(segment
		(start 125.883924 -296.540428)
		(end 125.883924 -296.792396)
		(width 0.1143)
		(layer "In11.Cu")
		(net "P5E_CPU1_P3_TX_DP<13>")
	)
	(segment
		(start 124.947426 -276.031452)
		(end 124.945648 -276.032468)
		(width 0.1143)
		(layer "In11.Cu")
		(net "P5E_CPU1_P3_TX_DP<13>")
	)
	(segment
		(start 124.983494 -293.830502)
		(end 124.951744 -293.84879)
		(width 0.1143)
		(layer "In11.Cu")
		(net "P5E_CPU1_P3_TX_DP<13>")
	)
	(segment
		(start 124.951744 -284.128972)
		(end 124.950728 -284.12948)
		(width 0.1143)
		(layer "In11.Cu")
		(net "P5E_CPU1_P3_TX_DP<13>")
	)
	(segment
		(start 124.951744 -292.228778)
		(end 124.950728 -292.229286)
		(width 0.1143)
		(layer "In11.Cu")
		(net "P5E_CPU1_P3_TX_DP<13>")
	)
	(segment
		(start 124.950728 -288.989262)
		(end 124.949204 -288.990278)
		(width 0.1143)
		(layer "In11.Cu")
		(net "P5E_CPU1_P3_TX_DP<13>")
	)
	(segment
		(start 124.958348 -281.86761)
		(end 124.959618 -281.868372)
		(width 0.1143)
		(layer "In11.Cu")
		(net "P5E_CPU1_P3_TX_DP<13>")
	)
	(segment
		(start 124.912628 -289.940746)
		(end 124.919486 -289.94481)
		(width 0.1143)
		(layer "In11.Cu")
		(net "P5E_CPU1_P3_TX_DP<13>")
	)
	(segment
		(start 125.2347 -274.896326)
		(end 125.532642 -274.896326)
		(width 0.1143)
		(layer "In11.Cu")
		(net "P5E_CPU1_P3_TX_DP<13>")
	)
	(segment
		(start 125.838712 -297.131994)
		(end 126.09703 -297.98391)
		(width 0.14224)
		(layer "In11.Cu")
		(net "P5E_CPU1_P3_TX_DP<13>")
	)
	(segment
		(start 124.944124 -288.993326)
		(end 124.912628 -289.011614)
		(width 0.1143)
		(layer "In11.Cu")
		(net "P5E_CPU1_P3_TX_DP<13>")
	)
	(segment
		(start 124.959618 -278.628348)
		(end 124.962158 -278.629618)
		(width 0.1143)
		(layer "In11.Cu")
		(net "P5E_CPU1_P3_TX_DP<13>")
	)
	(segment
		(start 124.950728 -291.58311)
		(end 124.951744 -291.583618)
		(width 0.1143)
		(layer "In11.Cu")
		(net "P5E_CPU1_P3_TX_DP<13>")
	)
	(segment
		(start 124.953776 -281.86507)
		(end 124.9553 -281.865832)
		(width 0.1143)
		(layer "In11.Cu")
		(net "P5E_CPU1_P3_TX_DP<13>")
	)
	(segment
		(start 124.949204 -277.650448)
		(end 124.948188 -277.650956)
		(width 0.1143)
		(layer "In11.Cu")
		(net "P5E_CPU1_P3_TX_DP<13>")
	)
	(segment
		(start 124.947426 -282.5115)
		(end 124.945648 -282.512516)
		(width 0.1143)
		(layer "In11.Cu")
		(net "P5E_CPU1_P3_TX_DP<13>")
	)
	(segment
		(start 124.951744 -294.823642)
		(end 124.952506 -294.82415)
		(width 0.1143)
		(layer "In11.Cu")
		(net "P5E_CPU1_P3_TX_DP<13>")
	)
	(segment
		(start 124.952506 -280.88844)
		(end 124.951744 -280.888948)
		(width 0.1143)
		(layer "In11.Cu")
		(net "P5E_CPU1_P3_TX_DP<13>")
	)
	(segment
		(start 124.948188 -282.510992)
		(end 124.947426 -282.5115)
		(width 0.1143)
		(layer "In11.Cu")
		(net "P5E_CPU1_P3_TX_DP<13>")
	)
	(segment
		(start 124.958348 -277.007574)
		(end 124.959618 -277.008336)
		(width 0.1143)
		(layer "In11.Cu")
		(net "P5E_CPU1_P3_TX_DP<13>")
	)
	(segment
		(start 125.838712 -296.935144)
		(end 125.838712 -297.131994)
		(width 0.14224)
		(layer "In11.Cu")
		(net "P5E_CPU1_P3_TX_DP<13>")
	)
	(segment
		(start 125.452378 -275.201126)
		(end 125.421898 -275.218906)
		(width 0.1143)
		(layer "In11.Cu")
		(net "P5E_CPU1_P3_TX_DP<13>")
	)
	(segment
		(start 124.957332 -277.007066)
		(end 124.958348 -277.007574)
		(width 0.1143)
		(layer "In11.Cu")
		(net "P5E_CPU1_P3_TX_DP<13>")
	)
	(segment
		(start 124.952506 -288.988246)
		(end 124.951744 -288.988754)
		(width 0.1143)
		(layer "In11.Cu")
		(net "P5E_CPU1_P3_TX_DP<13>")
	)
	(segment
		(start 124.962158 -278.629618)
		(end 124.983494 -278.642064)
		(width 0.1143)
		(layer "In11.Cu")
		(net "P5E_CPU1_P3_TX_DP<13>")
	)
	(segment
		(start 125.421644 -295.633648)
		(end 125.421898 -295.633648)
		(width 0.1143)
		(layer "In11.Cu")
		(net "P5E_CPU1_P3_TX_DP<13>")
	)
	(segment
		(start 124.953776 -283.485082)
		(end 124.983494 -283.5021)
		(width 0.1143)
		(layer "In11.Cu")
		(net "P5E_CPU1_P3_TX_DP<13>")
	)
	(segment
		(start 124.951744 -286.723836)
		(end 124.985272 -286.743394)
		(width 0.1143)
		(layer "In11.Cu")
		(net "P5E_CPU1_P3_TX_DP<13>")
	)
	(segment
		(start 124.962158 -277.009606)
		(end 124.983494 -277.022052)
		(width 0.1143)
		(layer "In11.Cu")
		(net "P5E_CPU1_P3_TX_DP<13>")
	)
	(segment
		(start 124.983494 -282.490672)
		(end 124.952506 -282.508452)
		(width 0.1143)
		(layer "In11.Cu")
		(net "P5E_CPU1_P3_TX_DP<13>")
	)
	(segment
		(start 126.09703 -297.98391)
		(end 126.801118 -299.037248)
		(width 0.14224)
		(layer "In11.Cu")
		(net "P5E_CPU1_P3_TX_DP<13>")
	)
	(segment
		(start 124.951744 -291.583618)
		(end 124.952506 -291.584126)
		(width 0.1143)
		(layer "In11.Cu")
		(net "P5E_CPU1_P3_TX_DP<13>")
	)
	(segment
		(start 125.883924 -296.792396)
		(end 125.838204 -296.838116)
		(width 0.1143)
		(layer "In11.Cu")
		(net "P5E_CPU1_P3_TX_DP<13>")
	)
	(segment
		(start 124.951744 -288.988754)
		(end 124.950728 -288.989262)
		(width 0.1143)
		(layer "In11.Cu")
		(net "P5E_CPU1_P3_TX_DP<13>")
	)
	(segment
		(start 124.951744 -288.343848)
		(end 124.985272 -288.363406)
		(width 0.1143)
		(layer "In11.Cu")
		(net "P5E_CPU1_P3_TX_DP<13>")
	)
	(segment
		(start 124.953776 -293.2049)
		(end 124.9553 -293.205662)
		(width 0.1143)
		(layer "In11.Cu")
		(net "P5E_CPU1_P3_TX_DP<13>")
	)
	(segment
		(start 124.953776 -285.105094)
		(end 124.983494 -285.122112)
		(width 0.1143)
		(layer "In11.Cu")
		(net "P5E_CPU1_P3_TX_DP<13>")
	)
	(segment
		(start 124.952506 -284.128464)
		(end 124.951744 -284.128972)
		(width 0.1143)
		(layer "In11.Cu")
		(net "P5E_CPU1_P3_TX_DP<13>")
	)
	(segment
		(start 124.962158 -293.209472)
		(end 124.983494 -293.221918)
		(width 0.1143)
		(layer "In11.Cu")
		(net "P5E_CPU1_P3_TX_DP<13>")
	)
	(segment
		(start 124.957332 -278.627078)
		(end 124.958348 -278.627586)
		(width 0.1143)
		(layer "In11.Cu")
		(net "P5E_CPU1_P3_TX_DP<13>")
	)
	(segment
		(start 124.959618 -293.208202)
		(end 124.962158 -293.209472)
		(width 0.1143)
		(layer "In11.Cu")
		(net "P5E_CPU1_P3_TX_DP<13>")
	)
	(segment
		(start 124.953776 -291.584888)
		(end 124.983494 -291.601906)
		(width 0.1143)
		(layer "In11.Cu")
		(net "P5E_CPU1_P3_TX_DP<13>")
	)
	(segment
		(start 124.959618 -289.968178)
		(end 124.962158 -289.969448)
		(width 0.1143)
		(layer "In11.Cu")
		(net "P5E_CPU1_P3_TX_DP<13>")
	)
	(segment
		(start 145.107914 -350.873822)
		(end 142.343632 -357.547926)
		(width 0.14224)
		(layer "In11.Cu")
		(net "P5E_CPU1_P3_TX_DP<13>")
	)
	(segment
		(start 124.957332 -281.867102)
		(end 124.958348 -281.86761)
		(width 0.1143)
		(layer "In11.Cu")
		(net "P5E_CPU1_P3_TX_DP<13>")
	)
	(segment
		(start 124.952506 -282.508452)
		(end 124.951744 -282.50896)
		(width 0.1143)
		(layer "In11.Cu")
		(net "P5E_CPU1_P3_TX_DP<13>")
	)
	(segment
		(start 124.919486 -281.845004)
		(end 124.920248 -281.845512)
		(width 0.1143)
		(layer "In11.Cu")
		(net "P5E_CPU1_P3_TX_DP<13>")
	)
	(segment
		(start 124.919486 -289.94481)
		(end 124.920248 -289.945318)
		(width 0.1143)
		(layer "In11.Cu")
		(net "P5E_CPU1_P3_TX_DP<13>")
	)
	(segment
		(start 124.920248 -276.985476)
		(end 124.951744 -277.003764)
		(width 0.1143)
		(layer "In11.Cu")
		(net "P5E_CPU1_P3_TX_DP<13>")
	)
	(segment
		(start 124.949204 -285.750508)
		(end 124.948188 -285.751016)
		(width 0.1143)
		(layer "In11.Cu")
		(net "P5E_CPU1_P3_TX_DP<13>")
	)
	(segment
		(start 124.920248 -278.605488)
		(end 124.951744 -278.623776)
		(width 0.1143)
		(layer "In11.Cu")
		(net "P5E_CPU1_P3_TX_DP<13>")
	)
	(segment
		(start 125.838204 -296.838116)
		(end 125.838204 -296.866564)
		(width 0.1143)
		(layer "In11.Cu")
		(net "P5E_CPU1_P3_TX_DP<13>")
	)
	(segment
		(start 125.609604 -295.956228)
		(end 125.609604 -296.05224)
		(width 0.1143)
		(layer "In11.Cu")
		(net "P5E_CPU1_P3_TX_DP<13>")
	)
	(segment
		(start 124.920248 -293.185342)
		(end 124.951744 -293.20363)
		(width 0.1143)
		(layer "In11.Cu")
		(net "P5E_CPU1_P3_TX_DP<13>")
	)
	(segment
		(start 124.949204 -280.890472)
		(end 124.948188 -280.89098)
		(width 0.1143)
		(layer "In11.Cu")
		(net "P5E_CPU1_P3_TX_DP<13>")
	)
	(segment
		(start 124.919486 -278.60498)
		(end 124.920248 -278.605488)
		(width 0.1143)
		(layer "In11.Cu")
		(net "P5E_CPU1_P3_TX_DP<13>")
	)
	(segment
		(start 124.958348 -294.827452)
		(end 124.959618 -294.828214)
		(width 0.1143)
		(layer "In11.Cu")
		(net "P5E_CPU1_P3_TX_DP<13>")
	)
	(segment
		(start 124.944124 -282.513532)
		(end 124.912628 -282.53182)
		(width 0.1143)
		(layer "In11.Cu")
		(net "P5E_CPU1_P3_TX_DP<13>")
	)
	(segment
		(start 124.948188 -292.23081)
		(end 124.947426 -292.231318)
		(width 0.1143)
		(layer "In11.Cu")
		(net "P5E_CPU1_P3_TX_DP<13>")
	)
	(segment
		(start 124.912628 -276.980904)
		(end 124.919486 -276.984968)
		(width 0.1143)
		(layer "In11.Cu")
		(net "P5E_CPU1_P3_TX_DP<13>")
	)
	(segment
		(start 124.945648 -284.132528)
		(end 124.944124 -284.133544)
		(width 0.1143)
		(layer "In11.Cu")
		(net "P5E_CPU1_P3_TX_DP<13>")
	)
	(segment
		(start 140.05052 -316.89294)
		(end 142.361158 -322.470526)
		(width 0.14224)
		(layer "In11.Cu")
		(net "P5E_CPU1_P3_TX_DP<13>")
	)
	(segment
		(start 124.951744 -277.648924)
		(end 124.950728 -277.649432)
		(width 0.1143)
		(layer "In11.Cu")
		(net "P5E_CPU1_P3_TX_DP<13>")
	)
	(segment
		(start 124.912628 -285.080964)
		(end 124.950728 -285.103316)
		(width 0.1143)
		(layer "In11.Cu")
		(net "P5E_CPU1_P3_TX_DP<13>")
	)
	(segment
		(start 124.952506 -289.964114)
		(end 124.953776 -289.964876)
		(width 0.1143)
		(layer "In11.Cu")
		(net "P5E_CPU1_P3_TX_DP<13>")
	)
	(segment
		(start 124.9553 -277.005796)
		(end 124.95657 -277.006558)
		(width 0.1143)
		(layer "In11.Cu")
		(net "P5E_CPU1_P3_TX_DP<13>")
	)
	(segment
		(start 124.957332 -294.826944)
		(end 124.958348 -294.827452)
		(width 0.1143)
		(layer "In11.Cu")
		(net "P5E_CPU1_P3_TX_DP<13>")
	)
	(segment
		(start 124.951744 -285.748984)
		(end 124.950728 -285.749492)
		(width 0.1143)
		(layer "In11.Cu")
		(net "P5E_CPU1_P3_TX_DP<13>")
	)
	(segment
		(start 125.452378 -280.061162)
		(end 125.421898 -280.078942)
		(width 0.1143)
		(layer "In11.Cu")
		(net "P5E_CPU1_P3_TX_DP<13>")
	)
	(segment
		(start 124.952506 -277.648416)
		(end 124.951744 -277.648924)
		(width 0.1143)
		(layer "In11.Cu")
		(net "P5E_CPU1_P3_TX_DP<13>")
	)
	(segment
		(start 124.945648 -277.65248)
		(end 124.944124 -277.653496)
		(width 0.1143)
		(layer "In11.Cu")
		(net "P5E_CPU1_P3_TX_DP<13>")
	)
	(segment
		(start 124.952506 -292.22827)
		(end 124.951744 -292.228778)
		(width 0.1143)
		(layer "In11.Cu")
		(net "P5E_CPU1_P3_TX_DP<13>")
	)
	(segment
		(start 124.95657 -294.826436)
		(end 124.957332 -294.826944)
		(width 0.1143)
		(layer "In11.Cu")
		(net "P5E_CPU1_P3_TX_DP<13>")
	)
	(segment
		(start 124.944124 -285.753556)
		(end 124.912628 -285.771844)
		(width 0.1143)
		(layer "In11.Cu")
		(net "P5E_CPU1_P3_TX_DP<13>")
	)
	(segment
		(start 124.952506 -285.104332)
		(end 124.953776 -285.105094)
		(width 0.1143)
		(layer "In11.Cu")
		(net "P5E_CPU1_P3_TX_DP<13>")
	)
	(segment
		(start 124.949204 -292.230302)
		(end 124.948188 -292.23081)
		(width 0.1143)
		(layer "In11.Cu")
		(net "P5E_CPU1_P3_TX_DP<13>")
	)
	(segment
		(start 125.532642 -274.896326)
		(end 125.602492 -274.966176)
		(width 0.1143)
		(layer "In11.Cu")
		(net "P5E_CPU1_P3_TX_DP<13>")
	)
	(segment
		(start 124.953776 -278.625046)
		(end 124.9553 -278.625808)
		(width 0.1143)
		(layer "In11.Cu")
		(net "P5E_CPU1_P3_TX_DP<13>")
	)
	(segment
		(start 124.9553 -278.625808)
		(end 124.95657 -278.62657)
		(width 0.1143)
		(layer "In11.Cu")
		(net "P5E_CPU1_P3_TX_DP<13>")
	)
	(segment
		(start 124.919486 -276.984968)
		(end 124.920248 -276.985476)
		(width 0.1143)
		(layer "In11.Cu")
		(net "P5E_CPU1_P3_TX_DP<13>")
	)
	(segment
		(start 124.952506 -281.864308)
		(end 124.953776 -281.86507)
		(width 0.1143)
		(layer "In11.Cu")
		(net "P5E_CPU1_P3_TX_DP<13>")
	)
	(segment
		(start 124.952506 -294.82415)
		(end 124.953776 -294.824912)
		(width 0.1143)
		(layer "In11.Cu")
		(net "P5E_CPU1_P3_TX_DP<13>")
	)
	(segment
		(start 124.983494 -292.21049)
		(end 124.952506 -292.22827)
		(width 0.1143)
		(layer "In11.Cu")
		(net "P5E_CPU1_P3_TX_DP<13>")
	)
	(segment
		(start 125.384052 -295.611804)
		(end 125.421644 -295.633648)
		(width 0.1143)
		(layer "In11.Cu")
		(net "P5E_CPU1_P3_TX_DP<13>")
	)
	(segment
		(start 124.953776 -294.824912)
		(end 124.9553 -294.825674)
		(width 0.1143)
		(layer "In11.Cu")
		(net "P5E_CPU1_P3_TX_DP<13>")
	)
	(segment
		(start 124.952506 -285.748476)
		(end 124.951744 -285.748984)
		(width 0.1143)
		(layer "In11.Cu")
		(net "P5E_CPU1_P3_TX_DP<13>")
	)
	(segment
		(start 124.953776 -289.964876)
		(end 124.9553 -289.965638)
		(width 0.1143)
		(layer "In11.Cu")
		(net "P5E_CPU1_P3_TX_DP<13>")
	)
	(segment
		(start 124.947426 -290.611306)
		(end 124.945648 -290.612322)
		(width 0.1143)
		(layer "In11.Cu")
		(net "P5E_CPU1_P3_TX_DP<13>")
	)
	(segment
		(start 124.947426 -280.891488)
		(end 124.945648 -280.892504)
		(width 0.1143)
		(layer "In11.Cu")
		(net "P5E_CPU1_P3_TX_DP<13>")
	)
	(segment
		(start 124.983494 -287.350454)
		(end 124.951744 -287.368742)
		(width 0.1143)
		(layer "In11.Cu")
		(net "P5E_CPU1_P3_TX_DP<13>")
	)
	(segment
		(start 124.958348 -293.20744)
		(end 124.959618 -293.208202)
		(width 0.1143)
		(layer "In11.Cu")
		(net "P5E_CPU1_P3_TX_DP<13>")
	)
	(segment
		(start 124.959618 -277.008336)
		(end 124.962158 -277.009606)
		(width 0.1143)
		(layer "In11.Cu")
		(net "P5E_CPU1_P3_TX_DP<13>")
	)
	(segment
		(start 124.952506 -278.624284)
		(end 124.953776 -278.625046)
		(width 0.1143)
		(layer "In11.Cu")
		(net "P5E_CPU1_P3_TX_DP<13>")
	)
	(segment
		(start 124.983494 -288.970466)
		(end 124.952506 -288.988246)
		(width 0.1143)
		(layer "In11.Cu")
		(net "P5E_CPU1_P3_TX_DP<13>")
	)
	(segment
		(start 124.983494 -277.630636)
		(end 124.952506 -277.648416)
		(width 0.1143)
		(layer "In11.Cu")
		(net "P5E_CPU1_P3_TX_DP<13>")
	)
	(segment
		(start 124.950728 -283.483304)
		(end 124.951744 -283.483812)
		(width 0.1143)
		(layer "In11.Cu")
		(net "P5E_CPU1_P3_TX_DP<13>")
	)
	(segment
		(start 124.948188 -284.131004)
		(end 124.947426 -284.131512)
		(width 0.1143)
		(layer "In11.Cu")
		(net "P5E_CPU1_P3_TX_DP<13>")
	)
	(segment
		(start 124.944124 -276.033484)
		(end 124.912628 -276.051772)
		(width 0.1143)
		(layer "In11.Cu")
		(net "P5E_CPU1_P3_TX_DP<13>")
	)
	(segment
		(start 124.912628 -286.700976)
		(end 124.951744 -286.723836)
		(width 0.1143)
		(layer "In11.Cu")
		(net "P5E_CPU1_P3_TX_DP<13>")
	)
	(segment
		(start 124.945648 -282.512516)
		(end 124.944124 -282.513532)
		(width 0.1143)
		(layer "In11.Cu")
		(net "P5E_CPU1_P3_TX_DP<13>")
	)
	(segment
		(start 124.983494 -276.010624)
		(end 124.952506 -276.028404)
		(width 0.1143)
		(layer "In11.Cu")
		(net "P5E_CPU1_P3_TX_DP<13>")
	)
	(segment
		(start 135.932926 -368.7445)
		(end 135.642096 -369.03533)
		(width 0.14224)
		(layer "In11.Cu")
		(net "P5E_CPU1_P3_TX_DP<13>")
	)
	(segment
		(start 124.983494 -284.110684)
		(end 124.952506 -284.128464)
		(width 0.1143)
		(layer "In11.Cu")
		(net "P5E_CPU1_P3_TX_DP<13>")
	)
	(segment
		(start 124.952506 -291.584126)
		(end 124.953776 -291.584888)
		(width 0.1143)
		(layer "In11.Cu")
		(net "P5E_CPU1_P3_TX_DP<13>")
	)
	(segment
		(start 124.9553 -281.865832)
		(end 124.95657 -281.866594)
		(width 0.1143)
		(layer "In11.Cu")
		(net "P5E_CPU1_P3_TX_DP<13>")
	)
	(segment
		(start 124.962158 -294.829484)
		(end 124.983494 -294.84193)
		(width 0.1143)
		(layer "In11.Cu")
		(net "P5E_CPU1_P3_TX_DP<13>")
	)
	(segment
		(start 124.958348 -278.627586)
		(end 124.959618 -278.628348)
		(width 0.1143)
		(layer "In11.Cu")
		(net "P5E_CPU1_P3_TX_DP<13>")
	)
	(segment
		(start 124.951744 -278.623776)
		(end 124.952506 -278.624284)
		(width 0.1143)
		(layer "In11.Cu")
		(net "P5E_CPU1_P3_TX_DP<13>")
	)
	(segment
		(start 124.920248 -281.845512)
		(end 124.951744 -281.8638)
		(width 0.1143)
		(layer "In11.Cu")
		(net "P5E_CPU1_P3_TX_DP<13>")
	)
	(segment
		(start 124.957332 -289.966908)
		(end 124.958348 -289.967416)
		(width 0.1143)
		(layer "In11.Cu")
		(net "P5E_CPU1_P3_TX_DP<13>")
	)
	(segment
		(start 126.801118 -299.037248)
		(end 133.89737 -307.68417)
		(width 0.14224)
		(layer "In11.Cu")
		(net "P5E_CPU1_P3_TX_DP<13>")
	)
	(segment
		(start 124.912628 -293.18077)
		(end 124.919486 -293.184834)
		(width 0.1143)
		(layer "In11.Cu")
		(net "P5E_CPU1_P3_TX_DP<13>")
	)
	(segment
		(start 124.950728 -280.889456)
		(end 124.949204 -280.890472)
		(width 0.1143)
		(layer "In11.Cu")
		(net "P5E_CPU1_P3_TX_DP<13>")
	)
	(segment
		(start 124.959618 -294.828214)
		(end 124.962158 -294.829484)
		(width 0.1143)
		(layer "In11.Cu")
		(net "P5E_CPU1_P3_TX_DP<13>")
	)
	(segment
		(start 124.949204 -276.030436)
		(end 124.948188 -276.030944)
		(width 0.1143)
		(layer "In11.Cu")
		(net "P5E_CPU1_P3_TX_DP<13>")
	)
	(segment
		(start 145.87728 -340.148164)
		(end 145.87728 -347.006418)
		(width 0.14224)
		(layer "In11.Cu")
		(net "P5E_CPU1_P3_TX_DP<13>")
	)
	(segment
		(start 124.951744 -283.483812)
		(end 124.952506 -283.48432)
		(width 0.1143)
		(layer "In11.Cu")
		(net "P5E_CPU1_P3_TX_DP<13>")
	)
	(segment
		(start 124.950728 -290.609274)
		(end 124.949204 -290.61029)
		(width 0.1143)
		(layer "In11.Cu")
		(net "P5E_CPU1_P3_TX_DP<13>")
	)
	(segment
		(start 124.952506 -283.48432)
		(end 124.953776 -283.485082)
		(width 0.1143)
		(layer "In11.Cu")
		(net "P5E_CPU1_P3_TX_DP<13>")
	)
	(segment
		(start 124.948188 -276.030944)
		(end 124.947426 -276.031452)
		(width 0.1143)
		(layer "In11.Cu")
		(net "P5E_CPU1_P3_TX_DP<13>")
	)
	(segment
		(start 124.948188 -277.650956)
		(end 124.947426 -277.651464)
		(width 0.1143)
		(layer "In11.Cu")
		(net "P5E_CPU1_P3_TX_DP<13>")
	)
	(segment
		(start 124.950728 -293.849298)
		(end 124.949204 -293.850314)
		(width 0.1143)
		(layer "In11.Cu")
		(net "P5E_CPU1_P3_TX_DP<13>")
	)
	(segment
		(start 124.950728 -277.649432)
		(end 124.949204 -277.650448)
		(width 0.1143)
		(layer "In11.Cu")
		(net "P5E_CPU1_P3_TX_DP<13>")
	)
	(segment
		(start 124.951744 -285.103824)
		(end 124.952506 -285.104332)
		(width 0.1143)
		(layer "In11.Cu")
		(net "P5E_CPU1_P3_TX_DP<13>")
	)
	(segment
		(start 124.959618 -281.868372)
		(end 124.962158 -281.869642)
		(width 0.1143)
		(layer "In11.Cu")
		(net "P5E_CPU1_P3_TX_DP<13>")
	)
	(segment
		(start 124.944124 -290.613338)
		(end 124.912628 -290.631626)
		(width 0.1143)
		(layer "In11.Cu")
		(net "P5E_CPU1_P3_TX_DP<13>")
	)
	(segment
		(start 124.951744 -290.608766)
		(end 124.950728 -290.609274)
		(width 0.1143)
		(layer "In11.Cu")
		(net "P5E_CPU1_P3_TX_DP<13>")
	)
	(segment
		(start 124.947426 -277.651464)
		(end 124.945648 -277.65248)
		(width 0.1143)
		(layer "In11.Cu")
		(net "P5E_CPU1_P3_TX_DP<13>")
	)
	(segment
		(start 124.948188 -285.751016)
		(end 124.947426 -285.751524)
		(width 0.1143)
		(layer "In11.Cu")
		(net "P5E_CPU1_P3_TX_DP<13>")
	)
	(segment
		(start 124.920248 -289.945318)
		(end 124.951744 -289.963606)
		(width 0.1143)
		(layer "In11.Cu")
		(net "P5E_CPU1_P3_TX_DP<13>")
	)
	(segment
		(start 124.919486 -294.804846)
		(end 124.920248 -294.805354)
		(width 0.1143)
		(layer "In11.Cu")
		(net "P5E_CPU1_P3_TX_DP<13>")
	)
	(segment
		(start 124.949204 -290.61029)
		(end 124.948188 -290.610798)
		(width 0.1143)
		(layer "In11.Cu")
		(net "P5E_CPU1_P3_TX_DP<13>")
	)
	(segment
		(start 124.951744 -280.888948)
		(end 124.950728 -280.889456)
		(width 0.1143)
		(layer "In11.Cu")
		(net "P5E_CPU1_P3_TX_DP<13>")
	)
	(segment
		(start 124.952506 -277.004272)
		(end 124.953776 -277.005034)
		(width 0.1143)
		(layer "In11.Cu")
		(net "P5E_CPU1_P3_TX_DP<13>")
	)
	(segment
		(start 124.951744 -276.028912)
		(end 124.950728 -276.02942)
		(width 0.1143)
		(layer "In11.Cu")
		(net "P5E_CPU1_P3_TX_DP<13>")
	)
	(segment
		(start 125.468888 -295.664128)
		(end 125.469142 -295.663874)
		(width 0.1143)
		(layer "In11.Cu")
		(net "P5E_CPU1_P3_TX_DP<13>")
	)
	(segment
		(start 124.983494 -290.590478)
		(end 124.952506 -290.608258)
		(width 0.1143)
		(layer "In11.Cu")
		(net "P5E_CPU1_P3_TX_DP<13>")
	)
	(segment
		(start 124.95657 -281.866594)
		(end 124.957332 -281.867102)
		(width 0.1143)
		(layer "In11.Cu")
		(net "P5E_CPU1_P3_TX_DP<13>")
	)
	(segment
		(start 124.95657 -289.9664)
		(end 124.957332 -289.966908)
		(width 0.1143)
		(layer "In11.Cu")
		(net "P5E_CPU1_P3_TX_DP<13>")
	)
	(segment
		(start 124.962158 -289.969448)
		(end 124.983494 -289.981894)
		(width 0.1143)
		(layer "In11.Cu")
		(net "P5E_CPU1_P3_TX_DP<13>")
	)
	(segment
		(start 124.951744 -277.003764)
		(end 124.952506 -277.004272)
		(width 0.1143)
		(layer "In11.Cu")
		(net "P5E_CPU1_P3_TX_DP<13>")
	)
	(segment
		(start 125.382782 -279.410922)
		(end 125.421898 -279.433782)
		(width 0.1143)
		(layer "In11.Cu")
		(net "P5E_CPU1_P3_TX_DP<13>")
	)
	(segment
		(start 124.945648 -290.612322)
		(end 124.944124 -290.613338)
		(width 0.1143)
		(layer "In11.Cu")
		(net "P5E_CPU1_P3_TX_DP<13>")
	)
	(segment
		(start 125.421898 -295.633648)
		(end 125.452378 -295.651428)
		(width 0.1143)
		(layer "In11.Cu")
		(net "P5E_CPU1_P3_TX_DP<13>")
	)
	(segment
		(start 125.421898 -275.218906)
		(end 125.382782 -275.241766)
		(width 0.1143)
		(layer "In11.Cu")
		(net "P5E_CPU1_P3_TX_DP<13>")
	)
	(segment
		(start 124.944124 -284.133544)
		(end 124.912628 -284.151832)
		(width 0.1143)
		(layer "In11.Cu")
		(net "P5E_CPU1_P3_TX_DP<13>")
	)
	(segment
		(start 124.957332 -293.206932)
		(end 124.958348 -293.20744)
		(width 0.1143)
		(layer "In11.Cu")
		(net "P5E_CPU1_P3_TX_DP<13>")
	)
	(segment
		(start 125.838204 -296.866564)
		(end 125.838204 -296.934636)
		(width 0.14224)
		(layer "In11.Cu")
		(net "P5E_CPU1_P3_TX_DP<13>")
	)
	(segment
		(start 124.948188 -280.89098)
		(end 124.947426 -280.891488)
		(width 0.1143)
		(layer "In11.Cu")
		(net "P5E_CPU1_P3_TX_DP<13>")
	)
	(segment
		(start 124.950728 -276.02942)
		(end 124.949204 -276.030436)
		(width 0.1143)
		(layer "In11.Cu")
		(net "P5E_CPU1_P3_TX_DP<13>")
	)
	(segment
		(start 124.912628 -278.600916)
		(end 124.919486 -278.60498)
		(width 0.1143)
		(layer "In11.Cu")
		(net "P5E_CPU1_P3_TX_DP<13>")
	)
	(segment
		(start 124.945648 -288.99231)
		(end 124.944124 -288.993326)
		(width 0.1143)
		(layer "In11.Cu")
		(net "P5E_CPU1_P3_TX_DP<13>")
	)
	(segment
		(start 124.9553 -289.965638)
		(end 124.95657 -289.9664)
		(width 0.1143)
		(layer "In11.Cu")
		(net "P5E_CPU1_P3_TX_DP<13>")
	)
	(segment
		(start 124.951744 -282.50896)
		(end 124.950728 -282.509468)
		(width 0.1143)
		(layer "In11.Cu")
		(net "P5E_CPU1_P3_TX_DP<13>")
	)
	(segment
		(start 124.962158 -281.869642)
		(end 124.983494 -281.882088)
		(width 0.1143)
		(layer "In11.Cu")
		(net "P5E_CPU1_P3_TX_DP<13>")
	)
	(segment
		(start 124.945648 -276.032468)
		(end 124.944124 -276.033484)
		(width 0.1143)
		(layer "In11.Cu")
		(net "P5E_CPU1_P3_TX_DP<13>")
	)
	(segment
		(start 124.947426 -288.991294)
		(end 124.945648 -288.99231)
		(width 0.1143)
		(layer "In11.Cu")
		(net "P5E_CPU1_P3_TX_DP<13>")
	)
	(segment
		(start 124.949204 -282.510484)
		(end 124.948188 -282.510992)
		(width 0.1143)
		(layer "In11.Cu")
		(net "P5E_CPU1_P3_TX_DP<13>")
	)
	(segment
		(start 125.838204 -296.934636)
		(end 125.838712 -296.935144)
		(width 0.14224)
		(layer "In11.Cu")
		(net "P5E_CPU1_P3_TX_DP<13>")
	)
	(segment
		(start 124.951744 -289.963606)
		(end 124.952506 -289.964114)
		(width 0.1143)
		(layer "In11.Cu")
		(net "P5E_CPU1_P3_TX_DP<13>")
	)
	(segment
		(start 124.951744 -293.20363)
		(end 124.952506 -293.204138)
		(width 0.1143)
		(layer "In11.Cu")
		(net "P5E_CPU1_P3_TX_DP<13>")
	)
	(segment
		(start 124.952506 -293.204138)
		(end 124.953776 -293.2049)
		(width 0.1143)
		(layer "In11.Cu")
		(net "P5E_CPU1_P3_TX_DP<13>")
	)
	(segment
		(start 124.95657 -277.006558)
		(end 124.957332 -277.007066)
		(width 0.1143)
		(layer "In11.Cu")
		(net "P5E_CPU1_P3_TX_DP<13>")
	)
	(segment
		(start 124.912628 -281.84094)
		(end 124.919486 -281.845004)
		(width 0.1143)
		(layer "In11.Cu")
		(net "P5E_CPU1_P3_TX_DP<13>")
	)
	(segment
		(start 124.945648 -280.892504)
		(end 124.944124 -280.89352)
		(width 0.1143)
		(layer "In11.Cu")
		(net "P5E_CPU1_P3_TX_DP<13>")
	)
	(arc
		(start 124.912628 -293.87165)
		(mid 124.669301 -294.336216)
		(end 124.912628 -294.800782)
		(width 0.1143)
		(layer "In11.Cu")
		(net "P5E_CPU1_P3_TX_DP<13>")
	)
	(arc
		(start 124.985272 -288.363406)
		(mid 125.098679 -288.496295)
		(end 125.13945 -288.666174)
		(width 0.1143)
		(layer "In11.Cu")
		(net "P5E_CPU1_P3_TX_DP<13>")
	)
	(arc
		(start 142.343632 -357.547926)
		(mid 140.422657 -361.141948)
		(end 137.837418 -364.292134)
		(width 0.14224)
		(layer "In11.Cu")
		(net "P5E_CPU1_P3_TX_DP<13>")
	)
	(arc
		(start 145.87728 -347.006418)
		(mid 145.683043 -348.978005)
		(end 145.107914 -350.873822)
		(width 0.14224)
		(layer "In11.Cu")
		(net "P5E_CPU1_P3_TX_DP<13>")
	)
	(arc
		(start 124.915168 -287.390078)
		(mid 124.734516 -287.592823)
		(end 124.669296 -287.856422)
		(width 0.1143)
		(layer "In11.Cu")
		(net "P5E_CPU1_P3_TX_DP<13>")
	)
	(arc
		(start 124.912628 -290.631626)
		(mid 124.669301 -291.096192)
		(end 124.912628 -291.560758)
		(width 0.1143)
		(layer "In11.Cu")
		(net "P5E_CPU1_P3_TX_DP<13>")
	)
	(arc
		(start 124.983494 -285.122112)
		(mid 125.139422 -285.426404)
		(end 124.983494 -285.730696)
		(width 0.1143)
		(layer "In11.Cu")
		(net "P5E_CPU1_P3_TX_DP<13>")
	)
	(arc
		(start 125.609604 -296.05224)
		(mid 125.633713 -296.174004)
		(end 125.702568 -296.277284)
		(width 0.1143)
		(layer "In11.Cu")
		(net "P5E_CPU1_P3_TX_DP<13>")
	)
	(arc
		(start 124.912628 -284.151832)
		(mid 124.669301 -284.616398)
		(end 124.912628 -285.080964)
		(width 0.1143)
		(layer "In11.Cu")
		(net "P5E_CPU1_P3_TX_DP<13>")
	)
	(arc
		(start 124.983494 -293.221918)
		(mid 125.139422 -293.52621)
		(end 124.983494 -293.830502)
		(width 0.1143)
		(layer "In11.Cu")
		(net "P5E_CPU1_P3_TX_DP<13>")
	)
	(arc
		(start 124.912628 -285.771844)
		(mid 124.669301 -286.23641)
		(end 124.912628 -286.700976)
		(width 0.1143)
		(layer "In11.Cu")
		(net "P5E_CPU1_P3_TX_DP<13>")
	)
	(arc
		(start 125.452378 -295.651428)
		(mid 125.460721 -295.657663)
		(end 125.468888 -295.664128)
		(width 0.1143)
		(layer "In11.Cu")
		(net "P5E_CPU1_P3_TX_DP<13>")
	)
	(arc
		(start 124.912628 -277.671784)
		(mid 124.669301 -278.13635)
		(end 124.912628 -278.600916)
		(width 0.1143)
		(layer "In11.Cu")
		(net "P5E_CPU1_P3_TX_DP<13>")
	)
	(arc
		(start 124.983494 -283.5021)
		(mid 125.139422 -283.806392)
		(end 124.983494 -284.110684)
		(width 0.1143)
		(layer "In11.Cu")
		(net "P5E_CPU1_P3_TX_DP<13>")
	)
	(arc
		(start 125.452378 -279.451562)
		(mid 125.609355 -279.756362)
		(end 125.452378 -280.061162)
		(width 0.1143)
		(layer "In11.Cu")
		(net "P5E_CPU1_P3_TX_DP<13>")
	)
	(arc
		(start 125.825758 -296.40022)
		(mid 125.868794 -296.464534)
		(end 125.883924 -296.540428)
		(width 0.1143)
		(layer "In11.Cu")
		(net "P5E_CPU1_P3_TX_DP<13>")
	)
	(arc
		(start 125.13945 -275.706332)
		(mid 125.098195 -275.877303)
		(end 124.983494 -276.010624)
		(width 0.1143)
		(layer "In11.Cu")
		(net "P5E_CPU1_P3_TX_DP<13>")
	)
	(arc
		(start 125.13945 -280.566368)
		(mid 125.098195 -280.737339)
		(end 124.983494 -280.87066)
		(width 0.1143)
		(layer "In11.Cu")
		(net "P5E_CPU1_P3_TX_DP<13>")
	)
	(arc
		(start 125.602492 -274.966176)
		(mid 125.550075 -275.098107)
		(end 125.452378 -275.201126)
		(width 0.1143)
		(layer "In11.Cu")
		(net "P5E_CPU1_P3_TX_DP<13>")
	)
	(arc
		(start 125.469142 -295.663874)
		(mid 125.572689 -295.794048)
		(end 125.609604 -295.956228)
		(width 0.1143)
		(layer "In11.Cu")
		(net "P5E_CPU1_P3_TX_DP<13>")
	)
	(arc
		(start 124.912628 -289.011614)
		(mid 124.669301 -289.47618)
		(end 124.912628 -289.940746)
		(width 0.1143)
		(layer "In11.Cu")
		(net "P5E_CPU1_P3_TX_DP<13>")
	)
	(arc
		(start 124.983494 -281.882088)
		(mid 125.139422 -282.18638)
		(end 124.983494 -282.490672)
		(width 0.1143)
		(layer "In11.Cu")
		(net "P5E_CPU1_P3_TX_DP<13>")
	)
	(arc
		(start 124.912628 -292.251638)
		(mid 124.669301 -292.716204)
		(end 124.912628 -293.18077)
		(width 0.1143)
		(layer "In11.Cu")
		(net "P5E_CPU1_P3_TX_DP<13>")
	)
	(arc
		(start 124.912628 -280.911808)
		(mid 124.669301 -281.376374)
		(end 124.912628 -281.84094)
		(width 0.1143)
		(layer "In11.Cu")
		(net "P5E_CPU1_P3_TX_DP<13>")
	)
	(arc
		(start 125.13945 -295.146222)
		(mid 125.204322 -295.409185)
		(end 125.384052 -295.611804)
		(width 0.1143)
		(layer "In11.Cu")
		(net "P5E_CPU1_P3_TX_DP<13>")
	)
	(arc
		(start 125.13945 -278.946356)
		(mid 125.203965 -279.208575)
		(end 125.382782 -279.410922)
		(width 0.1143)
		(layer "In11.Cu")
		(net "P5E_CPU1_P3_TX_DP<13>")
	)
	(arc
		(start 124.669296 -287.856422)
		(mid 124.733811 -288.118641)
		(end 124.912628 -288.320988)
		(width 0.1143)
		(layer "In11.Cu")
		(net "P5E_CPU1_P3_TX_DP<13>")
	)
	(arc
		(start 125.382782 -280.101802)
		(mid 125.203969 -280.304152)
		(end 125.13945 -280.566368)
		(width 0.1143)
		(layer "In11.Cu")
		(net "P5E_CPU1_P3_TX_DP<13>")
	)
	(arc
		(start 125.13945 -288.666174)
		(mid 125.098195 -288.837145)
		(end 124.983494 -288.970466)
		(width 0.1143)
		(layer "In11.Cu")
		(net "P5E_CPU1_P3_TX_DP<13>")
	)
	(arc
		(start 124.983494 -294.84193)
		(mid 125.09817 -294.975264)
		(end 125.13945 -295.146222)
		(width 0.1143)
		(layer "In11.Cu")
		(net "P5E_CPU1_P3_TX_DP<13>")
	)
	(arc
		(start 125.13945 -287.046162)
		(mid 125.098195 -287.217133)
		(end 124.983494 -287.350454)
		(width 0.1143)
		(layer "In11.Cu")
		(net "P5E_CPU1_P3_TX_DP<13>")
	)
	(arc
		(start 124.985272 -286.743394)
		(mid 125.098679 -286.876283)
		(end 125.13945 -287.046162)
		(width 0.1143)
		(layer "In11.Cu")
		(net "P5E_CPU1_P3_TX_DP<13>")
	)
	(arc
		(start 124.983494 -291.601906)
		(mid 125.139422 -291.906198)
		(end 124.983494 -292.21049)
		(width 0.1143)
		(layer "In11.Cu")
		(net "P5E_CPU1_P3_TX_DP<13>")
	)
	(arc
		(start 124.983494 -289.981894)
		(mid 125.139422 -290.286186)
		(end 124.983494 -290.590478)
		(width 0.1143)
		(layer "In11.Cu")
		(net "P5E_CPU1_P3_TX_DP<13>")
	)
	(arc
		(start 124.983494 -278.642064)
		(mid 125.09817 -278.775398)
		(end 125.13945 -278.946356)
		(width 0.1143)
		(layer "In11.Cu")
		(net "P5E_CPU1_P3_TX_DP<13>")
	)
	(arc
		(start 124.912628 -276.051772)
		(mid 124.669301 -276.516338)
		(end 124.912628 -276.980904)
		(width 0.1143)
		(layer "In11.Cu")
		(net "P5E_CPU1_P3_TX_DP<13>")
	)
	(arc
		(start 136.859772 -365.26978)
		(mid 136.173788 -366.296333)
		(end 135.932926 -367.507266)
		(width 0.14224)
		(layer "In11.Cu")
		(net "P5E_CPU1_P3_TX_DP<13>")
	)
	(arc
		(start 124.983494 -277.022052)
		(mid 125.139422 -277.326344)
		(end 124.983494 -277.630636)
		(width 0.1143)
		(layer "In11.Cu")
		(net "P5E_CPU1_P3_TX_DP<13>")
	)
	(arc
		(start 125.382782 -275.241766)
		(mid 125.203969 -275.444116)
		(end 125.13945 -275.706332)
		(width 0.1143)
		(layer "In11.Cu")
		(net "P5E_CPU1_P3_TX_DP<13>")
	)
	(arc
		(start 124.912628 -282.53182)
		(mid 124.669301 -282.996386)
		(end 124.912628 -283.460952)
		(width 0.1143)
		(layer "In11.Cu")
		(net "P5E_CPU1_P3_TX_DP<13>")
	)
	(segment
		(start 132.238496 -369.03533)
		(end 132.509006 -369.30584)
		(width 0.12954)
		(layer "F.Cu")
		(net "P5E_CPU1_P3_TX_DP<12>")
	)
	(segment
		(start 121.94794 -276.2504)
		(end 122.414792 -276.516338)
		(width 0.12954)
		(layer "F.Cu")
		(net "P5E_CPU1_P3_TX_DP<12>")
	)
	(segment
		(start 132.509006 -370.00942)
		(end 132.213096 -370.30533)
		(width 0.12954)
		(layer "F.Cu")
		(net "P5E_CPU1_P3_TX_DP<12>")
	)
	(segment
		(start 132.509006 -369.30584)
		(end 132.509006 -370.00942)
		(width 0.12954)
		(layer "F.Cu")
		(net "P5E_CPU1_P3_TX_DP<12>")
	)
	(segment
		(start 124.011944 -281.8638)
		(end 124.042424 -281.88158)
		(width 0.1143)
		(layer "In11.Cu")
		(net "P5E_CPU1_P3_TX_DP<12>")
	)
	(segment
		(start 124.87275 -296.890694)
		(end 124.873258 -296.891202)
		(width 0.14224)
		(layer "In11.Cu")
		(net "P5E_CPU1_P3_TX_DP<12>")
	)
	(segment
		(start 123.972828 -281.84094)
		(end 124.011944 -281.8638)
		(width 0.1143)
		(layer "In11.Cu")
		(net "P5E_CPU1_P3_TX_DP<12>")
	)
	(segment
		(start 123.972828 -285.080964)
		(end 124.011944 -285.103824)
		(width 0.1143)
		(layer "In11.Cu")
		(net "P5E_CPU1_P3_TX_DP<12>")
	)
	(segment
		(start 124.78131 -296.32021)
		(end 124.880878 -296.419778)
		(width 0.1143)
		(layer "In11.Cu")
		(net "P5E_CPU1_P3_TX_DP<12>")
	)
	(segment
		(start 124.042424 -290.590986)
		(end 124.011944 -290.608766)
		(width 0.1143)
		(layer "In11.Cu")
		(net "P5E_CPU1_P3_TX_DP<12>")
	)
	(segment
		(start 124.442728 -295.610788)
		(end 124.512324 -295.651428)
		(width 0.1143)
		(layer "In11.Cu")
		(net "P5E_CPU1_P3_TX_DP<12>")
	)
	(segment
		(start 123.040394 -276.985476)
		(end 123.07189 -277.003764)
		(width 0.1143)
		(layer "In11.Cu")
		(net "P5E_CPU1_P3_TX_DP<12>")
	)
	(segment
		(start 124.4854 -279.435814)
		(end 124.486162 -279.436322)
		(width 0.1143)
		(layer "In11.Cu")
		(net "P5E_CPU1_P3_TX_DP<12>")
	)
	(segment
		(start 123.972828 -293.18077)
		(end 124.011944 -293.20363)
		(width 0.1143)
		(layer "In11.Cu")
		(net "P5E_CPU1_P3_TX_DP<12>")
	)
	(segment
		(start 123.972828 -291.560758)
		(end 124.011944 -291.583618)
		(width 0.1143)
		(layer "In11.Cu")
		(net "P5E_CPU1_P3_TX_DP<12>")
	)
	(segment
		(start 124.042424 -280.871168)
		(end 124.011944 -280.888948)
		(width 0.1143)
		(layer "In11.Cu")
		(net "P5E_CPU1_P3_TX_DP<12>")
	)
	(segment
		(start 124.479304 -280.080466)
		(end 124.442728 -280.101802)
		(width 0.1143)
		(layer "In11.Cu")
		(net "P5E_CPU1_P3_TX_DP<12>")
	)
	(segment
		(start 124.513594 -280.060654)
		(end 124.482606 -280.078434)
		(width 0.1143)
		(layer "In11.Cu")
		(net "P5E_CPU1_P3_TX_DP<12>")
	)
	(segment
		(start 123.075446 -277.005796)
		(end 123.101608 -277.021036)
		(width 0.1143)
		(layer "In11.Cu")
		(net "P5E_CPU1_P3_TX_DP<12>")
	)
	(segment
		(start 123.072144 -277.004018)
		(end 123.072652 -277.004272)
		(width 0.1143)
		(layer "In11.Cu")
		(net "P5E_CPU1_P3_TX_DP<12>")
	)
	(segment
		(start 123.502166 -277.790656)
		(end 123.573286 -277.832058)
		(width 0.1143)
		(layer "In11.Cu")
		(net "P5E_CPU1_P3_TX_DP<12>")
	)
	(segment
		(start 124.669296 -296.042588)
		(end 124.66955 -296.042842)
		(width 0.1143)
		(layer "In11.Cu")
		(net "P5E_CPU1_P3_TX_DP<12>")
	)
	(segment
		(start 132.529326 -368.11458)
		(end 132.529326 -368.7445)
		(width 0.14224)
		(layer "In11.Cu")
		(net "P5E_CPU1_P3_TX_DP<12>")
	)
	(segment
		(start 124.042424 -284.111192)
		(end 124.011944 -284.128972)
		(width 0.1143)
		(layer "In11.Cu")
		(net "P5E_CPU1_P3_TX_DP<12>")
	)
	(segment
		(start 124.011944 -280.888948)
		(end 123.972828 -280.911808)
		(width 0.1143)
		(layer "In11.Cu")
		(net "P5E_CPU1_P3_TX_DP<12>")
	)
	(segment
		(start 124.482606 -280.078434)
		(end 124.481844 -280.078942)
		(width 0.1143)
		(layer "In11.Cu")
		(net "P5E_CPU1_P3_TX_DP<12>")
	)
	(segment
		(start 137.88771 -362.544106)
		(end 132.679186 -367.75263)
		(width 0.14224)
		(layer "In11.Cu")
		(net "P5E_CPU1_P3_TX_DP<12>")
	)
	(segment
		(start 124.042424 -292.210998)
		(end 124.011944 -292.228778)
		(width 0.1143)
		(layer "In11.Cu")
		(net "P5E_CPU1_P3_TX_DP<12>")
	)
	(segment
		(start 124.873258 -296.891202)
		(end 124.873258 -297.191684)
		(width 0.14224)
		(layer "In11.Cu")
		(net "P5E_CPU1_P3_TX_DP<12>")
	)
	(segment
		(start 139.242292 -317.444882)
		(end 141.143228 -322.033392)
		(width 0.14224)
		(layer "In11.Cu")
		(net "P5E_CPU1_P3_TX_DP<12>")
	)
	(segment
		(start 124.486162 -279.436322)
		(end 124.487686 -279.437084)
		(width 0.1143)
		(layer "In11.Cu")
		(net "P5E_CPU1_P3_TX_DP<12>")
	)
	(segment
		(start 124.489718 -279.438354)
		(end 124.492258 -279.439624)
		(width 0.1143)
		(layer "In11.Cu")
		(net "P5E_CPU1_P3_TX_DP<12>")
	)
	(segment
		(start 123.972828 -288.320988)
		(end 124.011944 -288.343848)
		(width 0.1143)
		(layer "In11.Cu")
		(net "P5E_CPU1_P3_TX_DP<12>")
	)
	(segment
		(start 124.442728 -279.410922)
		(end 124.449586 -279.414986)
		(width 0.1143)
		(layer "In11.Cu")
		(net "P5E_CPU1_P3_TX_DP<12>")
	)
	(segment
		(start 123.072652 -277.004272)
		(end 123.075446 -277.005796)
		(width 0.1143)
		(layer "In11.Cu")
		(net "P5E_CPU1_P3_TX_DP<12>")
	)
	(segment
		(start 123.972828 -289.940746)
		(end 124.011944 -289.963606)
		(width 0.1143)
		(layer "In11.Cu")
		(net "P5E_CPU1_P3_TX_DP<12>")
	)
	(segment
		(start 124.87275 -296.866564)
		(end 124.87275 -296.890694)
		(width 0.14224)
		(layer "In11.Cu")
		(net "P5E_CPU1_P3_TX_DP<12>")
	)
	(segment
		(start 124.66955 -295.956228)
		(end 124.669296 -295.956482)
		(width 0.1143)
		(layer "In11.Cu")
		(net "P5E_CPU1_P3_TX_DP<12>")
	)
	(segment
		(start 132.529326 -368.7445)
		(end 132.238496 -369.03533)
		(width 0.14224)
		(layer "In11.Cu")
		(net "P5E_CPU1_P3_TX_DP<12>")
	)
	(segment
		(start 123.259596 -277.326344)
		(end 123.259596 -277.329392)
		(width 0.1143)
		(layer "In11.Cu")
		(net "P5E_CPU1_P3_TX_DP<12>")
	)
	(segment
		(start 124.011944 -289.963606)
		(end 124.042424 -289.981386)
		(width 0.1143)
		(layer "In11.Cu")
		(net "P5E_CPU1_P3_TX_DP<12>")
	)
	(segment
		(start 124.482606 -279.43429)
		(end 124.4854 -279.435814)
		(width 0.1143)
		(layer "In11.Cu")
		(net "P5E_CPU1_P3_TX_DP<12>")
	)
	(segment
		(start 123.039632 -276.984968)
		(end 123.040394 -276.985476)
		(width 0.1143)
		(layer "In11.Cu")
		(net "P5E_CPU1_P3_TX_DP<12>")
	)
	(segment
		(start 124.011944 -278.623776)
		(end 124.042424 -278.641556)
		(width 0.1143)
		(layer "In11.Cu")
		(net "P5E_CPU1_P3_TX_DP<12>")
	)
	(segment
		(start 124.449586 -279.414986)
		(end 124.450348 -279.415494)
		(width 0.1143)
		(layer "In11.Cu")
		(net "P5E_CPU1_P3_TX_DP<12>")
	)
	(segment
		(start 123.491498 -277.783036)
		(end 123.502166 -277.790656)
		(width 0.1143)
		(layer "In11.Cu")
		(net "P5E_CPU1_P3_TX_DP<12>")
	)
	(segment
		(start 124.011944 -288.343848)
		(end 124.044456 -288.362644)
		(width 0.1143)
		(layer "In11.Cu")
		(net "P5E_CPU1_P3_TX_DP<12>")
	)
	(segment
		(start 124.487686 -279.437084)
		(end 124.488448 -279.437592)
		(width 0.1143)
		(layer "In11.Cu")
		(net "P5E_CPU1_P3_TX_DP<12>")
	)
	(segment
		(start 133.248146 -308.473856)
		(end 139.242292 -317.444882)
		(width 0.14224)
		(layer "In11.Cu")
		(net "P5E_CPU1_P3_TX_DP<12>")
	)
	(segment
		(start 124.488448 -279.437592)
		(end 124.489718 -279.438354)
		(width 0.1143)
		(layer "In11.Cu")
		(net "P5E_CPU1_P3_TX_DP<12>")
	)
	(segment
		(start 123.573286 -277.832058)
		(end 123.57354 -277.832058)
		(width 0.1143)
		(layer "In11.Cu")
		(net "P5E_CPU1_P3_TX_DP<12>")
	)
	(segment
		(start 124.011944 -292.228778)
		(end 123.972828 -292.251638)
		(width 0.1143)
		(layer "In11.Cu")
		(net "P5E_CPU1_P3_TX_DP<12>")
	)
	(segment
		(start 123.972828 -278.600916)
		(end 124.011944 -278.623776)
		(width 0.1143)
		(layer "In11.Cu")
		(net "P5E_CPU1_P3_TX_DP<12>")
	)
	(segment
		(start 124.011944 -285.103824)
		(end 124.042424 -285.121604)
		(width 0.1143)
		(layer "In11.Cu")
		(net "P5E_CPU1_P3_TX_DP<12>")
	)
	(segment
		(start 124.042424 -285.731204)
		(end 124.011944 -285.748984)
		(width 0.1143)
		(layer "In11.Cu")
		(net "P5E_CPU1_P3_TX_DP<12>")
	)
	(segment
		(start 144.929352 -340.281006)
		(end 144.929352 -346.962984)
		(width 0.14224)
		(layer "In11.Cu")
		(net "P5E_CPU1_P3_TX_DP<12>")
	)
	(segment
		(start 124.480828 -280.07945)
		(end 124.479304 -280.080466)
		(width 0.1143)
		(layer "In11.Cu")
		(net "P5E_CPU1_P3_TX_DP<12>")
	)
	(segment
		(start 124.492258 -279.439624)
		(end 124.513594 -279.45207)
		(width 0.1143)
		(layer "In11.Cu")
		(net "P5E_CPU1_P3_TX_DP<12>")
	)
	(segment
		(start 124.011944 -290.608766)
		(end 123.972828 -290.631626)
		(width 0.1143)
		(layer "In11.Cu")
		(net "P5E_CPU1_P3_TX_DP<12>")
	)
	(segment
		(start 124.011944 -293.84879)
		(end 123.972828 -293.87165)
		(width 0.1143)
		(layer "In11.Cu")
		(net "P5E_CPU1_P3_TX_DP<12>")
	)
	(segment
		(start 124.011944 -293.20363)
		(end 124.042424 -293.22141)
		(width 0.1143)
		(layer "In11.Cu")
		(net "P5E_CPU1_P3_TX_DP<12>")
	)
	(segment
		(start 123.972828 -286.700976)
		(end 124.011944 -286.723836)
		(width 0.1143)
		(layer "In11.Cu")
		(net "P5E_CPU1_P3_TX_DP<12>")
	)
	(segment
		(start 125.24232 -298.408598)
		(end 126.358142 -300.078394)
		(width 0.14224)
		(layer "In11.Cu")
		(net "P5E_CPU1_P3_TX_DP<12>")
	)
	(segment
		(start 126.358142 -300.078394)
		(end 133.248146 -308.473856)
		(width 0.14224)
		(layer "In11.Cu")
		(net "P5E_CPU1_P3_TX_DP<12>")
	)
	(segment
		(start 124.481844 -280.078942)
		(end 124.480828 -280.07945)
		(width 0.1143)
		(layer "In11.Cu")
		(net "P5E_CPU1_P3_TX_DP<12>")
	)
	(segment
		(start 124.481844 -279.433782)
		(end 124.482606 -279.43429)
		(width 0.1143)
		(layer "In11.Cu")
		(net "P5E_CPU1_P3_TX_DP<12>")
	)
	(segment
		(start 124.011944 -291.583618)
		(end 124.042424 -291.601398)
		(width 0.1143)
		(layer "In11.Cu")
		(net "P5E_CPU1_P3_TX_DP<12>")
	)
	(segment
		(start 141.143228 -322.033392)
		(end 144.929352 -340.281006)
		(width 0.14224)
		(layer "In11.Cu")
		(net "P5E_CPU1_P3_TX_DP<12>")
	)
	(segment
		(start 124.011944 -282.50896)
		(end 123.972828 -282.53182)
		(width 0.1143)
		(layer "In11.Cu")
		(net "P5E_CPU1_P3_TX_DP<12>")
	)
	(segment
		(start 124.450348 -279.415494)
		(end 124.481844 -279.433782)
		(width 0.1143)
		(layer "In11.Cu")
		(net "P5E_CPU1_P3_TX_DP<12>")
	)
	(segment
		(start 124.669296 -295.956482)
		(end 124.669296 -296.042588)
		(width 0.1143)
		(layer "In11.Cu")
		(net "P5E_CPU1_P3_TX_DP<12>")
	)
	(segment
		(start 124.873258 -297.191684)
		(end 125.24232 -298.408598)
		(width 0.14224)
		(layer "In11.Cu")
		(net "P5E_CPU1_P3_TX_DP<12>")
	)
	(segment
		(start 124.011944 -294.823642)
		(end 124.042424 -294.841422)
		(width 0.1143)
		(layer "In11.Cu")
		(net "P5E_CPU1_P3_TX_DP<12>")
	)
	(segment
		(start 123.972828 -294.800782)
		(end 124.011944 -294.823642)
		(width 0.1143)
		(layer "In11.Cu")
		(net "P5E_CPU1_P3_TX_DP<12>")
	)
	(segment
		(start 124.91847 -296.792396)
		(end 124.87275 -296.838116)
		(width 0.1143)
		(layer "In11.Cu")
		(net "P5E_CPU1_P3_TX_DP<12>")
	)
	(segment
		(start 124.011944 -288.988754)
		(end 123.972828 -289.011614)
		(width 0.1143)
		(layer "In11.Cu")
		(net "P5E_CPU1_P3_TX_DP<12>")
	)
	(segment
		(start 124.042424 -293.83101)
		(end 124.011944 -293.84879)
		(width 0.1143)
		(layer "In11.Cu")
		(net "P5E_CPU1_P3_TX_DP<12>")
	)
	(segment
		(start 124.011944 -284.128972)
		(end 123.972828 -284.151832)
		(width 0.1143)
		(layer "In11.Cu")
		(net "P5E_CPU1_P3_TX_DP<12>")
	)
	(segment
		(start 123.972828 -283.460952)
		(end 124.011944 -283.483812)
		(width 0.1143)
		(layer "In11.Cu")
		(net "P5E_CPU1_P3_TX_DP<12>")
	)
	(segment
		(start 124.042424 -287.350962)
		(end 123.975368 -287.390078)
		(width 0.1143)
		(layer "In11.Cu")
		(net "P5E_CPU1_P3_TX_DP<12>")
	)
	(segment
		(start 124.87275 -296.838116)
		(end 124.87275 -296.866564)
		(width 0.1143)
		(layer "In11.Cu")
		(net "P5E_CPU1_P3_TX_DP<12>")
	)
	(segment
		(start 123.07189 -277.003764)
		(end 123.072144 -277.004018)
		(width 0.1143)
		(layer "In11.Cu")
		(net "P5E_CPU1_P3_TX_DP<12>")
	)
	(segment
		(start 124.042424 -288.970974)
		(end 124.011944 -288.988754)
		(width 0.1143)
		(layer "In11.Cu")
		(net "P5E_CPU1_P3_TX_DP<12>")
	)
	(segment
		(start 123.032774 -276.980904)
		(end 123.039632 -276.984968)
		(width 0.1143)
		(layer "In11.Cu")
		(net "P5E_CPU1_P3_TX_DP<12>")
	)
	(segment
		(start 124.042424 -282.49118)
		(end 124.011944 -282.50896)
		(width 0.1143)
		(layer "In11.Cu")
		(net "P5E_CPU1_P3_TX_DP<12>")
	)
	(segment
		(start 144.464786 -349.298006)
		(end 140.757148 -358.249474)
		(width 0.14224)
		(layer "In11.Cu")
		(net "P5E_CPU1_P3_TX_DP<12>")
	)
	(segment
		(start 124.011944 -286.723836)
		(end 124.044456 -286.742632)
		(width 0.1143)
		(layer "In11.Cu")
		(net "P5E_CPU1_P3_TX_DP<12>")
	)
	(segment
		(start 124.66955 -296.042842)
		(end 124.66955 -296.050462)
		(width 0.1143)
		(layer "In11.Cu")
		(net "P5E_CPU1_P3_TX_DP<12>")
	)
	(segment
		(start 122.414792 -276.516338)
		(end 122.712734 -276.516338)
		(width 0.1143)
		(layer "In11.Cu")
		(net "P5E_CPU1_P3_TX_DP<12>")
	)
	(segment
		(start 124.91847 -296.509948)
		(end 124.91847 -296.792396)
		(width 0.1143)
		(layer "In11.Cu")
		(net "P5E_CPU1_P3_TX_DP<12>")
	)
	(segment
		(start 124.011944 -285.748984)
		(end 123.972828 -285.771844)
		(width 0.1143)
		(layer "In11.Cu")
		(net "P5E_CPU1_P3_TX_DP<12>")
	)
	(segment
		(start 122.712734 -276.516338)
		(end 122.795538 -276.599142)
		(width 0.1143)
		(layer "In11.Cu")
		(net "P5E_CPU1_P3_TX_DP<12>")
	)
	(segment
		(start 124.011944 -283.483812)
		(end 124.042424 -283.501592)
		(width 0.1143)
		(layer "In11.Cu")
		(net "P5E_CPU1_P3_TX_DP<12>")
	)
	(arc
		(start 122.799348 -276.622002)
		(mid 122.880781 -276.8244)
		(end 123.032774 -276.980904)
		(width 0.1143)
		(layer "In11.Cu")
		(net "P5E_CPU1_P3_TX_DP<12>")
	)
	(arc
		(start 124.042424 -281.88158)
		(mid 124.199401 -282.18638)
		(end 124.042424 -282.49118)
		(width 0.1143)
		(layer "In11.Cu")
		(net "P5E_CPU1_P3_TX_DP<12>")
	)
	(arc
		(start 123.729496 -278.13635)
		(mid 123.794011 -278.398569)
		(end 123.972828 -278.600916)
		(width 0.1143)
		(layer "In11.Cu")
		(net "P5E_CPU1_P3_TX_DP<12>")
	)
	(arc
		(start 123.729496 -287.856422)
		(mid 123.794011 -288.118641)
		(end 123.972828 -288.320988)
		(width 0.1143)
		(layer "In11.Cu")
		(net "P5E_CPU1_P3_TX_DP<12>")
	)
	(arc
		(start 124.199396 -287.046162)
		(mid 124.157847 -287.217584)
		(end 124.042424 -287.350962)
		(width 0.1143)
		(layer "In11.Cu")
		(net "P5E_CPU1_P3_TX_DP<12>")
	)
	(arc
		(start 124.042424 -285.121604)
		(mid 124.199401 -285.426404)
		(end 124.042424 -285.731204)
		(width 0.1143)
		(layer "In11.Cu")
		(net "P5E_CPU1_P3_TX_DP<12>")
	)
	(arc
		(start 124.042424 -291.601398)
		(mid 124.199401 -291.906198)
		(end 124.042424 -292.210998)
		(width 0.1143)
		(layer "In11.Cu")
		(net "P5E_CPU1_P3_TX_DP<12>")
	)
	(arc
		(start 123.972828 -280.911808)
		(mid 123.729501 -281.376374)
		(end 123.972828 -281.84094)
		(width 0.1143)
		(layer "In11.Cu")
		(net "P5E_CPU1_P3_TX_DP<12>")
	)
	(arc
		(start 123.972828 -293.87165)
		(mid 123.729501 -294.336216)
		(end 123.972828 -294.800782)
		(width 0.1143)
		(layer "In11.Cu")
		(net "P5E_CPU1_P3_TX_DP<12>")
	)
	(arc
		(start 123.975368 -287.390078)
		(mid 123.794716 -287.592823)
		(end 123.729496 -287.856422)
		(width 0.1143)
		(layer "In11.Cu")
		(net "P5E_CPU1_P3_TX_DP<12>")
	)
	(arc
		(start 123.972828 -282.53182)
		(mid 123.729501 -282.996386)
		(end 123.972828 -283.460952)
		(width 0.1143)
		(layer "In11.Cu")
		(net "P5E_CPU1_P3_TX_DP<12>")
	)
	(arc
		(start 123.972828 -285.771844)
		(mid 123.729501 -286.23641)
		(end 123.972828 -286.700976)
		(width 0.1143)
		(layer "In11.Cu")
		(net "P5E_CPU1_P3_TX_DP<12>")
	)
	(arc
		(start 124.042424 -283.501592)
		(mid 124.199401 -283.806392)
		(end 124.042424 -284.111192)
		(width 0.1143)
		(layer "In11.Cu")
		(net "P5E_CPU1_P3_TX_DP<12>")
	)
	(arc
		(start 123.972828 -284.151832)
		(mid 123.729501 -284.616398)
		(end 123.972828 -285.080964)
		(width 0.1143)
		(layer "In11.Cu")
		(net "P5E_CPU1_P3_TX_DP<12>")
	)
	(arc
		(start 124.513594 -279.45207)
		(mid 124.669522 -279.756362)
		(end 124.513594 -280.060654)
		(width 0.1143)
		(layer "In11.Cu")
		(net "P5E_CPU1_P3_TX_DP<12>")
	)
	(arc
		(start 124.442728 -280.101802)
		(mid 124.263915 -280.304152)
		(end 124.199396 -280.566368)
		(width 0.1143)
		(layer "In11.Cu")
		(net "P5E_CPU1_P3_TX_DP<12>")
	)
	(arc
		(start 123.57354 -277.832058)
		(mid 123.688216 -277.965392)
		(end 123.729496 -278.13635)
		(width 0.1143)
		(layer "In11.Cu")
		(net "P5E_CPU1_P3_TX_DP<12>")
	)
	(arc
		(start 124.042424 -278.641556)
		(mid 124.157851 -278.774932)
		(end 124.199396 -278.946356)
		(width 0.1143)
		(layer "In11.Cu")
		(net "P5E_CPU1_P3_TX_DP<12>")
	)
	(arc
		(start 144.929352 -346.962984)
		(mid 144.812051 -348.15337)
		(end 144.464786 -349.298006)
		(width 0.14224)
		(layer "In11.Cu")
		(net "P5E_CPU1_P3_TX_DP<12>")
	)
	(arc
		(start 123.101608 -277.021036)
		(mid 123.217655 -277.154507)
		(end 123.259596 -277.326344)
		(width 0.1143)
		(layer "In11.Cu")
		(net "P5E_CPU1_P3_TX_DP<12>")
	)
	(arc
		(start 123.259596 -277.329392)
		(mid 123.320886 -277.584151)
		(end 123.491498 -277.783036)
		(width 0.1143)
		(layer "In11.Cu")
		(net "P5E_CPU1_P3_TX_DP<12>")
	)
	(arc
		(start 124.199396 -280.566368)
		(mid 124.157847 -280.73779)
		(end 124.042424 -280.871168)
		(width 0.1143)
		(layer "In11.Cu")
		(net "P5E_CPU1_P3_TX_DP<12>")
	)
	(arc
		(start 124.199396 -295.146222)
		(mid 124.263911 -295.408441)
		(end 124.442728 -295.610788)
		(width 0.1143)
		(layer "In11.Cu")
		(net "P5E_CPU1_P3_TX_DP<12>")
	)
	(arc
		(start 124.042424 -293.22141)
		(mid 124.199401 -293.52621)
		(end 124.042424 -293.83101)
		(width 0.1143)
		(layer "In11.Cu")
		(net "P5E_CPU1_P3_TX_DP<12>")
	)
	(arc
		(start 140.757148 -358.249474)
		(mid 139.533942 -360.538114)
		(end 137.88771 -362.544106)
		(width 0.14224)
		(layer "In11.Cu")
		(net "P5E_CPU1_P3_TX_DP<12>")
	)
	(arc
		(start 124.199396 -278.946356)
		(mid 124.263911 -279.208575)
		(end 124.442728 -279.410922)
		(width 0.1143)
		(layer "In11.Cu")
		(net "P5E_CPU1_P3_TX_DP<12>")
	)
	(arc
		(start 123.972828 -289.011614)
		(mid 123.729501 -289.47618)
		(end 123.972828 -289.940746)
		(width 0.1143)
		(layer "In11.Cu")
		(net "P5E_CPU1_P3_TX_DP<12>")
	)
	(arc
		(start 124.528834 -295.664128)
		(mid 124.632484 -295.794149)
		(end 124.66955 -295.956228)
		(width 0.1143)
		(layer "In11.Cu")
		(net "P5E_CPU1_P3_TX_DP<12>")
	)
	(arc
		(start 124.512324 -295.651428)
		(mid 124.520667 -295.657663)
		(end 124.528834 -295.664128)
		(width 0.1143)
		(layer "In11.Cu")
		(net "P5E_CPU1_P3_TX_DP<12>")
	)
	(arc
		(start 123.972828 -292.251638)
		(mid 123.729501 -292.716204)
		(end 123.972828 -293.18077)
		(width 0.1143)
		(layer "In11.Cu")
		(net "P5E_CPU1_P3_TX_DP<12>")
	)
	(arc
		(start 124.880878 -296.419778)
		(mid 124.908712 -296.461105)
		(end 124.91847 -296.509948)
		(width 0.1143)
		(layer "In11.Cu")
		(net "P5E_CPU1_P3_TX_DP<12>")
	)
	(arc
		(start 124.044456 -288.362644)
		(mid 124.158385 -288.495791)
		(end 124.199396 -288.666174)
		(width 0.1143)
		(layer "In11.Cu")
		(net "P5E_CPU1_P3_TX_DP<12>")
	)
	(arc
		(start 132.679186 -367.75263)
		(mid 132.568279 -367.918708)
		(end 132.529326 -368.11458)
		(width 0.14224)
		(layer "In11.Cu")
		(net "P5E_CPU1_P3_TX_DP<12>")
	)
	(arc
		(start 124.044456 -286.742632)
		(mid 124.158385 -286.875779)
		(end 124.199396 -287.046162)
		(width 0.1143)
		(layer "In11.Cu")
		(net "P5E_CPU1_P3_TX_DP<12>")
	)
	(arc
		(start 123.972828 -290.631626)
		(mid 123.729501 -291.096192)
		(end 123.972828 -291.560758)
		(width 0.1143)
		(layer "In11.Cu")
		(net "P5E_CPU1_P3_TX_DP<12>")
	)
	(arc
		(start 124.66955 -296.050462)
		(mid 124.698591 -296.196459)
		(end 124.78131 -296.32021)
		(width 0.1143)
		(layer "In11.Cu")
		(net "P5E_CPU1_P3_TX_DP<12>")
	)
	(arc
		(start 124.199396 -288.666174)
		(mid 124.157847 -288.837596)
		(end 124.042424 -288.970974)
		(width 0.1143)
		(layer "In11.Cu")
		(net "P5E_CPU1_P3_TX_DP<12>")
	)
	(arc
		(start 124.042424 -294.841422)
		(mid 124.157851 -294.974798)
		(end 124.199396 -295.146222)
		(width 0.1143)
		(layer "In11.Cu")
		(net "P5E_CPU1_P3_TX_DP<12>")
	)
	(arc
		(start 122.795538 -276.599142)
		(mid 122.797326 -276.610591)
		(end 122.799348 -276.622002)
		(width 0.1143)
		(layer "In11.Cu")
		(net "P5E_CPU1_P3_TX_DP<12>")
	)
	(arc
		(start 124.042424 -289.981386)
		(mid 124.199401 -290.286186)
		(end 124.042424 -290.590986)
		(width 0.1143)
		(layer "In11.Cu")
		(net "P5E_CPU1_P3_TX_DP<12>")
	)
	(segment
		(start 130.807206 -371.76964)
		(end 130.807206 -372.47322)
		(width 0.12954)
		(layer "F.Cu")
		(net "P5E_CPU1_P3_TX_DP<11>")
	)
	(segment
		(start 121.94794 -277.870412)
		(end 122.414792 -278.13635)
		(width 0.12954)
		(layer "F.Cu")
		(net "P5E_CPU1_P3_TX_DP<11>")
	)
	(segment
		(start 130.536696 -371.49913)
		(end 130.807206 -371.76964)
		(width 0.12954)
		(layer "F.Cu")
		(net "P5E_CPU1_P3_TX_DP<11>")
	)
	(segment
		(start 130.807206 -372.47322)
		(end 130.511296 -372.76913)
		(width 0.12954)
		(layer "F.Cu")
		(net "P5E_CPU1_P3_TX_DP<11>")
	)
	(segment
		(start 123.07189 -280.888948)
		(end 123.070874 -280.889456)
		(width 0.1143)
		(layer "In11.Cu")
		(net "P5E_CPU1_P3_TX_DP<11>")
	)
	(segment
		(start 123.247658 -280.57475)
		(end 123.247658 -280.58618)
		(width 0.1143)
		(layer "In11.Cu")
		(net "P5E_CPU1_P3_TX_DP<11>")
	)
	(segment
		(start 123.070874 -282.509468)
		(end 123.032774 -282.53182)
		(width 0.1143)
		(layer "In11.Cu")
		(net "P5E_CPU1_P3_TX_DP<11>")
	)
	(segment
		(start 123.072652 -291.584126)
		(end 123.10364 -291.601906)
		(width 0.1143)
		(layer "In11.Cu")
		(net "P5E_CPU1_P3_TX_DP<11>")
	)
	(segment
		(start 123.072652 -282.508706)
		(end 123.07189 -282.50896)
		(width 0.1143)
		(layer "In11.Cu")
		(net "P5E_CPU1_P3_TX_DP<11>")
	)
	(segment
		(start 123.07189 -282.50896)
		(end 123.070874 -282.509468)
		(width 0.1143)
		(layer "In11.Cu")
		(net "P5E_CPU1_P3_TX_DP<11>")
	)
	(segment
		(start 123.97359 -296.504868)
		(end 123.97359 -296.792396)
		(width 0.1143)
		(layer "In11.Cu")
		(net "P5E_CPU1_P3_TX_DP<11>")
	)
	(segment
		(start 123.10745 -287.34766)
		(end 123.10364 -287.350454)
		(width 0.1143)
		(layer "In11.Cu")
		(net "P5E_CPU1_P3_TX_DP<11>")
	)
	(segment
		(start 122.712734 -278.13635)
		(end 122.795538 -278.219154)
		(width 0.1143)
		(layer "In11.Cu")
		(net "P5E_CPU1_P3_TX_DP<11>")
	)
	(segment
		(start 137.093198 -361.935014)
		(end 131.14147 -367.886742)
		(width 0.14224)
		(layer "In11.Cu")
		(net "P5E_CPU1_P3_TX_DP<11>")
	)
	(segment
		(start 123.039124 -288.324544)
		(end 123.074938 -288.345372)
		(width 0.1143)
		(layer "In11.Cu")
		(net "P5E_CPU1_P3_TX_DP<11>")
	)
	(segment
		(start 123.82246 -296.30116)
		(end 123.936252 -296.414698)
		(width 0.1143)
		(layer "In11.Cu")
		(net "P5E_CPU1_P3_TX_DP<11>")
	)
	(segment
		(start 123.072652 -293.848536)
		(end 123.07189 -293.84879)
		(width 0.1143)
		(layer "In11.Cu")
		(net "P5E_CPU1_P3_TX_DP<11>")
	)
	(segment
		(start 124.389642 -298.83481)
		(end 125.622304 -300.679612)
		(width 0.14224)
		(layer "In11.Cu")
		(net "P5E_CPU1_P3_TX_DP<11>")
	)
	(segment
		(start 132.481066 -309.03672)
		(end 138.39952 -317.894208)
		(width 0.14224)
		(layer "In11.Cu")
		(net "P5E_CPU1_P3_TX_DP<11>")
	)
	(segment
		(start 123.070874 -290.609274)
		(end 123.032774 -290.631626)
		(width 0.1143)
		(layer "In11.Cu")
		(net "P5E_CPU1_P3_TX_DP<11>")
	)
	(segment
		(start 123.07189 -284.128972)
		(end 123.070874 -284.12948)
		(width 0.1143)
		(layer "In11.Cu")
		(net "P5E_CPU1_P3_TX_DP<11>")
	)
	(segment
		(start 123.074938 -288.986976)
		(end 123.072652 -288.9885)
		(width 0.1143)
		(layer "In11.Cu")
		(net "P5E_CPU1_P3_TX_DP<11>")
	)
	(segment
		(start 123.259596 -295.141904)
		(end 123.259596 -295.146222)
		(width 0.1143)
		(layer "In11.Cu")
		(net "P5E_CPU1_P3_TX_DP<11>")
	)
	(segment
		(start 123.075446 -285.747206)
		(end 123.074938 -285.747206)
		(width 0.1143)
		(layer "In11.Cu")
		(net "P5E_CPU1_P3_TX_DP<11>")
	)
	(segment
		(start 123.074684 -285.105602)
		(end 123.075192 -285.105602)
		(width 0.1143)
		(layer "In11.Cu")
		(net "P5E_CPU1_P3_TX_DP<11>")
	)
	(segment
		(start 123.066302 -292.23208)
		(end 123.032774 -292.251638)
		(width 0.1143)
		(layer "In11.Cu")
		(net "P5E_CPU1_P3_TX_DP<11>")
	)
	(segment
		(start 123.07189 -290.608766)
		(end 123.070874 -290.609274)
		(width 0.1143)
		(layer "In11.Cu")
		(net "P5E_CPU1_P3_TX_DP<11>")
	)
	(segment
		(start 123.032774 -286.700976)
		(end 123.105418 -286.743394)
		(width 0.1143)
		(layer "In11.Cu")
		(net "P5E_CPU1_P3_TX_DP<11>")
	)
	(segment
		(start 123.070874 -285.103316)
		(end 123.07189 -285.103824)
		(width 0.1143)
		(layer "In11.Cu")
		(net "P5E_CPU1_P3_TX_DP<11>")
	)
	(segment
		(start 123.032774 -288.320988)
		(end 123.03887 -288.324544)
		(width 0.1143)
		(layer "In11.Cu")
		(net "P5E_CPU1_P3_TX_DP<11>")
	)
	(segment
		(start 143.384524 -349.257874)
		(end 139.83081 -357.83774)
		(width 0.14224)
		(layer "In11.Cu")
		(net "P5E_CPU1_P3_TX_DP<11>")
	)
	(segment
		(start 123.070874 -289.963098)
		(end 123.07189 -289.963606)
		(width 0.1143)
		(layer "In11.Cu")
		(net "P5E_CPU1_P3_TX_DP<11>")
	)
	(segment
		(start 123.07189 -293.84879)
		(end 123.070874 -293.849298)
		(width 0.1143)
		(layer "In11.Cu")
		(net "P5E_CPU1_P3_TX_DP<11>")
	)
	(segment
		(start 123.032774 -293.18077)
		(end 123.070874 -293.203122)
		(width 0.1143)
		(layer "In11.Cu")
		(net "P5E_CPU1_P3_TX_DP<11>")
	)
	(segment
		(start 123.070874 -293.849298)
		(end 123.032774 -293.87165)
		(width 0.1143)
		(layer "In11.Cu")
		(net "P5E_CPU1_P3_TX_DP<11>")
	)
	(segment
		(start 130.827526 -368.644678)
		(end 130.827526 -371.2083)
		(width 0.14224)
		(layer "In11.Cu")
		(net "P5E_CPU1_P3_TX_DP<11>")
	)
	(segment
		(start 123.259596 -295.146222)
		(end 123.259342 -295.146222)
		(width 0.1143)
		(layer "In11.Cu")
		(net "P5E_CPU1_P3_TX_DP<11>")
	)
	(segment
		(start 123.072652 -283.48432)
		(end 123.074684 -283.48559)
		(width 0.1143)
		(layer "In11.Cu")
		(net "P5E_CPU1_P3_TX_DP<11>")
	)
	(segment
		(start 123.075446 -288.986976)
		(end 123.074938 -288.986976)
		(width 0.1143)
		(layer "In11.Cu")
		(net "P5E_CPU1_P3_TX_DP<11>")
	)
	(segment
		(start 123.729242 -295.956228)
		(end 123.729496 -295.955974)
		(width 0.1143)
		(layer "In11.Cu")
		(net "P5E_CPU1_P3_TX_DP<11>")
	)
	(segment
		(start 123.07189 -283.483812)
		(end 123.072652 -283.48432)
		(width 0.1143)
		(layer "In11.Cu")
		(net "P5E_CPU1_P3_TX_DP<11>")
	)
	(segment
		(start 123.070874 -291.58311)
		(end 123.07189 -291.583618)
		(width 0.1143)
		(layer "In11.Cu")
		(net "P5E_CPU1_P3_TX_DP<11>")
	)
	(segment
		(start 123.928378 -296.905934)
		(end 123.928378 -297.31462)
		(width 0.14224)
		(layer "In11.Cu")
		(net "P5E_CPU1_P3_TX_DP<11>")
	)
	(segment
		(start 123.10364 -287.350454)
		(end 123.035314 -287.390078)
		(width 0.1143)
		(layer "In11.Cu")
		(net "P5E_CPU1_P3_TX_DP<11>")
	)
	(segment
		(start 123.92787 -296.866564)
		(end 123.92787 -296.905426)
		(width 0.14224)
		(layer "In11.Cu")
		(net "P5E_CPU1_P3_TX_DP<11>")
	)
	(segment
		(start 123.07189 -292.228778)
		(end 123.070874 -292.229286)
		(width 0.1143)
		(layer "In11.Cu")
		(net "P5E_CPU1_P3_TX_DP<11>")
	)
	(segment
		(start 123.928378 -297.31462)
		(end 124.389642 -298.83481)
		(width 0.14224)
		(layer "In11.Cu")
		(net "P5E_CPU1_P3_TX_DP<11>")
	)
	(segment
		(start 125.622304 -300.679612)
		(end 132.481066 -309.03672)
		(width 0.14224)
		(layer "In11.Cu")
		(net "P5E_CPU1_P3_TX_DP<11>")
	)
	(segment
		(start 123.10364 -291.601906)
		(end 123.10872 -291.605462)
		(width 0.1143)
		(layer "In11.Cu")
		(net "P5E_CPU1_P3_TX_DP<11>")
	)
	(segment
		(start 123.07189 -285.748984)
		(end 123.070874 -285.749492)
		(width 0.1143)
		(layer "In11.Cu")
		(net "P5E_CPU1_P3_TX_DP<11>")
	)
	(segment
		(start 123.07189 -281.8638)
		(end 123.072652 -281.864308)
		(width 0.1143)
		(layer "In11.Cu")
		(net "P5E_CPU1_P3_TX_DP<11>")
	)
	(segment
		(start 123.072652 -285.74873)
		(end 123.07189 -285.748984)
		(width 0.1143)
		(layer "In11.Cu")
		(net "P5E_CPU1_P3_TX_DP<11>")
	)
	(segment
		(start 123.07189 -291.583618)
		(end 123.072652 -291.584126)
		(width 0.1143)
		(layer "In11.Cu")
		(net "P5E_CPU1_P3_TX_DP<11>")
	)
	(segment
		(start 123.032774 -291.560758)
		(end 123.070874 -291.58311)
		(width 0.1143)
		(layer "In11.Cu")
		(net "P5E_CPU1_P3_TX_DP<11>")
	)
	(segment
		(start 123.074938 -293.847012)
		(end 123.072652 -293.848536)
		(width 0.1143)
		(layer "In11.Cu")
		(net "P5E_CPU1_P3_TX_DP<11>")
	)
	(segment
		(start 122.414792 -278.13635)
		(end 122.712734 -278.13635)
		(width 0.1143)
		(layer "In11.Cu")
		(net "P5E_CPU1_P3_TX_DP<11>")
	)
	(segment
		(start 123.075446 -284.127194)
		(end 123.074938 -284.127194)
		(width 0.1143)
		(layer "In11.Cu")
		(net "P5E_CPU1_P3_TX_DP<11>")
	)
	(segment
		(start 123.54179 -295.633648)
		(end 123.542552 -295.634156)
		(width 0.1143)
		(layer "In11.Cu")
		(net "P5E_CPU1_P3_TX_DP<11>")
	)
	(segment
		(start 123.10872 -292.206934)
		(end 123.10364 -292.21049)
		(width 0.1143)
		(layer "In11.Cu")
		(net "P5E_CPU1_P3_TX_DP<11>")
	)
	(segment
		(start 123.072652 -288.9885)
		(end 123.07189 -288.988754)
		(width 0.1143)
		(layer "In11.Cu")
		(net "P5E_CPU1_P3_TX_DP<11>")
	)
	(segment
		(start 123.074938 -282.507182)
		(end 123.072652 -282.508706)
		(width 0.1143)
		(layer "In11.Cu")
		(net "P5E_CPU1_P3_TX_DP<11>")
	)
	(segment
		(start 123.075446 -290.606988)
		(end 123.074938 -290.606988)
		(width 0.1143)
		(layer "In11.Cu")
		(net "P5E_CPU1_P3_TX_DP<11>")
	)
	(segment
		(start 123.074684 -281.865578)
		(end 123.075192 -281.865578)
		(width 0.1143)
		(layer "In11.Cu")
		(net "P5E_CPU1_P3_TX_DP<11>")
	)
	(segment
		(start 123.07443 -294.824912)
		(end 123.104656 -294.842946)
		(width 0.1143)
		(layer "In11.Cu")
		(net "P5E_CPU1_P3_TX_DP<11>")
	)
	(segment
		(start 123.729496 -295.955974)
		(end 123.729496 -296.076116)
		(width 0.1143)
		(layer "In11.Cu")
		(net "P5E_CPU1_P3_TX_DP<11>")
	)
	(segment
		(start 123.070874 -280.889456)
		(end 123.032774 -280.911808)
		(width 0.1143)
		(layer "In11.Cu")
		(net "P5E_CPU1_P3_TX_DP<11>")
	)
	(segment
		(start 123.92787 -296.838116)
		(end 123.92787 -296.866564)
		(width 0.1143)
		(layer "In11.Cu")
		(net "P5E_CPU1_P3_TX_DP<11>")
	)
	(segment
		(start 123.57354 -280.060654)
		(end 123.528836 -280.086562)
		(width 0.1143)
		(layer "In11.Cu")
		(net "P5E_CPU1_P3_TX_DP<11>")
	)
	(segment
		(start 123.068842 -292.230556)
		(end 123.067318 -292.231572)
		(width 0.1143)
		(layer "In11.Cu")
		(net "P5E_CPU1_P3_TX_DP<11>")
	)
	(segment
		(start 123.072652 -280.88844)
		(end 123.07189 -280.888948)
		(width 0.1143)
		(layer "In11.Cu")
		(net "P5E_CPU1_P3_TX_DP<11>")
	)
	(segment
		(start 123.070874 -294.823134)
		(end 123.07443 -294.824912)
		(width 0.1143)
		(layer "In11.Cu")
		(net "P5E_CPU1_P3_TX_DP<11>")
	)
	(segment
		(start 123.070874 -284.12948)
		(end 123.032774 -284.151832)
		(width 0.1143)
		(layer "In11.Cu")
		(net "P5E_CPU1_P3_TX_DP<11>")
	)
	(segment
		(start 123.92787 -296.905426)
		(end 123.928378 -296.905934)
		(width 0.14224)
		(layer "In11.Cu")
		(net "P5E_CPU1_P3_TX_DP<11>")
	)
	(segment
		(start 123.032774 -281.84094)
		(end 123.070874 -281.863292)
		(width 0.1143)
		(layer "In11.Cu")
		(net "P5E_CPU1_P3_TX_DP<11>")
	)
	(segment
		(start 123.032774 -278.600916)
		(end 123.039632 -278.60498)
		(width 0.1143)
		(layer "In11.Cu")
		(net "P5E_CPU1_P3_TX_DP<11>")
	)
	(segment
		(start 123.074938 -284.127194)
		(end 123.072652 -284.128718)
		(width 0.1143)
		(layer "In11.Cu")
		(net "P5E_CPU1_P3_TX_DP<11>")
	)
	(segment
		(start 123.542044 -279.433782)
		(end 123.57354 -279.452324)
		(width 0.1143)
		(layer "In11.Cu")
		(net "P5E_CPU1_P3_TX_DP<11>")
	)
	(segment
		(start 123.074684 -293.205408)
		(end 123.075192 -293.205408)
		(width 0.1143)
		(layer "In11.Cu")
		(net "P5E_CPU1_P3_TX_DP<11>")
	)
	(segment
		(start 123.072652 -289.964114)
		(end 123.074684 -289.965384)
		(width 0.1143)
		(layer "In11.Cu")
		(net "P5E_CPU1_P3_TX_DP<11>")
	)
	(segment
		(start 123.075446 -293.847012)
		(end 123.074938 -293.847012)
		(width 0.1143)
		(layer "In11.Cu")
		(net "P5E_CPU1_P3_TX_DP<11>")
	)
	(segment
		(start 123.272296 -278.953722)
		(end 123.272296 -278.966168)
		(width 0.1143)
		(layer "In11.Cu")
		(net "P5E_CPU1_P3_TX_DP<11>")
	)
	(segment
		(start 123.032774 -285.080964)
		(end 123.070874 -285.103316)
		(width 0.1143)
		(layer "In11.Cu")
		(net "P5E_CPU1_P3_TX_DP<11>")
	)
	(segment
		(start 123.067318 -292.231572)
		(end 123.066302 -292.23208)
		(width 0.1143)
		(layer "In11.Cu")
		(net "P5E_CPU1_P3_TX_DP<11>")
	)
	(segment
		(start 123.072652 -285.104332)
		(end 123.074684 -285.105602)
		(width 0.1143)
		(layer "In11.Cu")
		(net "P5E_CPU1_P3_TX_DP<11>")
	)
	(segment
		(start 123.074938 -285.747206)
		(end 123.072652 -285.74873)
		(width 0.1143)
		(layer "In11.Cu")
		(net "P5E_CPU1_P3_TX_DP<11>")
	)
	(segment
		(start 123.074684 -283.48559)
		(end 123.075192 -283.48559)
		(width 0.1143)
		(layer "In11.Cu")
		(net "P5E_CPU1_P3_TX_DP<11>")
	)
	(segment
		(start 123.07189 -285.103824)
		(end 123.072652 -285.104332)
		(width 0.1143)
		(layer "In11.Cu")
		(net "P5E_CPU1_P3_TX_DP<11>")
	)
	(segment
		(start 123.070874 -293.203122)
		(end 123.07189 -293.20363)
		(width 0.1143)
		(layer "In11.Cu")
		(net "P5E_CPU1_P3_TX_DP<11>")
	)
	(segment
		(start 123.03887 -288.324544)
		(end 123.039124 -288.324544)
		(width 0.1143)
		(layer "In11.Cu")
		(net "P5E_CPU1_P3_TX_DP<11>")
	)
	(segment
		(start 123.97359 -296.792396)
		(end 123.92787 -296.838116)
		(width 0.1143)
		(layer "In11.Cu")
		(net "P5E_CPU1_P3_TX_DP<11>")
	)
	(segment
		(start 123.07189 -293.20363)
		(end 123.072652 -293.204138)
		(width 0.1143)
		(layer "In11.Cu")
		(net "P5E_CPU1_P3_TX_DP<11>")
	)
	(segment
		(start 123.072652 -292.22827)
		(end 123.07189 -292.228778)
		(width 0.1143)
		(layer "In11.Cu")
		(net "P5E_CPU1_P3_TX_DP<11>")
	)
	(segment
		(start 123.072652 -290.608512)
		(end 123.07189 -290.608766)
		(width 0.1143)
		(layer "In11.Cu")
		(net "P5E_CPU1_P3_TX_DP<11>")
	)
	(segment
		(start 123.070874 -281.863292)
		(end 123.07189 -281.8638)
		(width 0.1143)
		(layer "In11.Cu")
		(net "P5E_CPU1_P3_TX_DP<11>")
	)
	(segment
		(start 123.032774 -283.460952)
		(end 123.039632 -283.465016)
		(width 0.1143)
		(layer "In11.Cu")
		(net "P5E_CPU1_P3_TX_DP<11>")
	)
	(segment
		(start 123.540774 -295.63314)
		(end 123.54179 -295.633648)
		(width 0.1143)
		(layer "In11.Cu")
		(net "P5E_CPU1_P3_TX_DP<11>")
	)
	(segment
		(start 123.072652 -278.62403)
		(end 123.073668 -278.624538)
		(width 0.1143)
		(layer "In11.Cu")
		(net "P5E_CPU1_P3_TX_DP<11>")
	)
	(segment
		(start 123.542552 -295.634156)
		(end 123.573794 -295.65219)
		(width 0.1143)
		(layer "In11.Cu")
		(net "P5E_CPU1_P3_TX_DP<11>")
	)
	(segment
		(start 123.074938 -288.345372)
		(end 123.075192 -288.345372)
		(width 0.1143)
		(layer "In11.Cu")
		(net "P5E_CPU1_P3_TX_DP<11>")
	)
	(segment
		(start 130.827526 -371.2083)
		(end 130.536696 -371.49913)
		(width 0.14224)
		(layer "In11.Cu")
		(net "P5E_CPU1_P3_TX_DP<11>")
	)
	(segment
		(start 123.10364 -292.21049)
		(end 123.072652 -292.22827)
		(width 0.1143)
		(layer "In11.Cu")
		(net "P5E_CPU1_P3_TX_DP<11>")
	)
	(segment
		(start 123.074938 -290.606988)
		(end 123.072652 -290.608512)
		(width 0.1143)
		(layer "In11.Cu")
		(net "P5E_CPU1_P3_TX_DP<11>")
	)
	(segment
		(start 123.040394 -278.605488)
		(end 123.07189 -278.623776)
		(width 0.1143)
		(layer "In11.Cu")
		(net "P5E_CPU1_P3_TX_DP<11>")
	)
	(segment
		(start 123.040394 -283.465524)
		(end 123.07189 -283.483812)
		(width 0.1143)
		(layer "In11.Cu")
		(net "P5E_CPU1_P3_TX_DP<11>")
	)
	(segment
		(start 123.072652 -278.624284)
		(end 123.072652 -278.62403)
		(width 0.1143)
		(layer "In11.Cu")
		(net "P5E_CPU1_P3_TX_DP<11>")
	)
	(segment
		(start 143.865092 -340.54542)
		(end 143.865092 -346.842334)
		(width 0.14224)
		(layer "In11.Cu")
		(net "P5E_CPU1_P3_TX_DP<11>")
	)
	(segment
		(start 123.07189 -278.623776)
		(end 123.072652 -278.624284)
		(width 0.1143)
		(layer "In11.Cu")
		(net "P5E_CPU1_P3_TX_DP<11>")
	)
	(segment
		(start 138.39952 -317.894208)
		(end 140.246608 -322.353178)
		(width 0.14224)
		(layer "In11.Cu")
		(net "P5E_CPU1_P3_TX_DP<11>")
	)
	(segment
		(start 123.07189 -289.963606)
		(end 123.072652 -289.964114)
		(width 0.1143)
		(layer "In11.Cu")
		(net "P5E_CPU1_P3_TX_DP<11>")
	)
	(segment
		(start 123.039632 -278.60498)
		(end 123.040394 -278.605488)
		(width 0.1143)
		(layer "In11.Cu")
		(net "P5E_CPU1_P3_TX_DP<11>")
	)
	(segment
		(start 123.072652 -293.204138)
		(end 123.074684 -293.205408)
		(width 0.1143)
		(layer "In11.Cu")
		(net "P5E_CPU1_P3_TX_DP<11>")
	)
	(segment
		(start 123.259596 -287.046162)
		(end 123.259596 -287.050734)
		(width 0.1143)
		(layer "In11.Cu")
		(net "P5E_CPU1_P3_TX_DP<11>")
	)
	(segment
		(start 123.070874 -288.989262)
		(end 123.032774 -289.011614)
		(width 0.1143)
		(layer "In11.Cu")
		(net "P5E_CPU1_P3_TX_DP<11>")
	)
	(segment
		(start 123.07189 -288.988754)
		(end 123.070874 -288.989262)
		(width 0.1143)
		(layer "In11.Cu")
		(net "P5E_CPU1_P3_TX_DP<11>")
	)
	(segment
		(start 123.032774 -294.800782)
		(end 123.070874 -294.823134)
		(width 0.1143)
		(layer "In11.Cu")
		(net "P5E_CPU1_P3_TX_DP<11>")
	)
	(segment
		(start 123.039632 -283.465016)
		(end 123.040394 -283.465524)
		(width 0.1143)
		(layer "In11.Cu")
		(net "P5E_CPU1_P3_TX_DP<11>")
	)
	(segment
		(start 123.502674 -295.610788)
		(end 123.540774 -295.63314)
		(width 0.1143)
		(layer "In11.Cu")
		(net "P5E_CPU1_P3_TX_DP<11>")
	)
	(segment
		(start 123.070874 -292.229286)
		(end 123.068842 -292.230556)
		(width 0.1143)
		(layer "In11.Cu")
		(net "P5E_CPU1_P3_TX_DP<11>")
	)
	(segment
		(start 123.074684 -289.965384)
		(end 123.075192 -289.965384)
		(width 0.1143)
		(layer "In11.Cu")
		(net "P5E_CPU1_P3_TX_DP<11>")
	)
	(segment
		(start 123.075446 -282.507182)
		(end 123.074938 -282.507182)
		(width 0.1143)
		(layer "In11.Cu")
		(net "P5E_CPU1_P3_TX_DP<11>")
	)
	(segment
		(start 140.246608 -322.353178)
		(end 143.865092 -340.54542)
		(width 0.14224)
		(layer "In11.Cu")
		(net "P5E_CPU1_P3_TX_DP<11>")
	)
	(segment
		(start 123.070874 -285.749492)
		(end 123.032774 -285.771844)
		(width 0.1143)
		(layer "In11.Cu")
		(net "P5E_CPU1_P3_TX_DP<11>")
	)
	(segment
		(start 123.072652 -281.864308)
		(end 123.074684 -281.865578)
		(width 0.1143)
		(layer "In11.Cu")
		(net "P5E_CPU1_P3_TX_DP<11>")
	)
	(segment
		(start 123.032774 -289.940746)
		(end 123.070874 -289.963098)
		(width 0.1143)
		(layer "In11.Cu")
		(net "P5E_CPU1_P3_TX_DP<11>")
	)
	(segment
		(start 123.072652 -284.128718)
		(end 123.07189 -284.128972)
		(width 0.1143)
		(layer "In11.Cu")
		(net "P5E_CPU1_P3_TX_DP<11>")
	)
	(segment
		(start 123.073668 -278.624538)
		(end 123.087384 -278.632412)
		(width 0.1143)
		(layer "In11.Cu")
		(net "P5E_CPU1_P3_TX_DP<11>")
	)
	(arc
		(start 123.075192 -293.205408)
		(mid 123.259925 -293.5261)
		(end 123.075446 -293.847012)
		(width 0.1143)
		(layer "In11.Cu")
		(net "P5E_CPU1_P3_TX_DP<11>")
	)
	(arc
		(start 123.087384 -278.632412)
		(mid 123.222772 -278.768361)
		(end 123.272296 -278.953722)
		(width 0.1143)
		(layer "In11.Cu")
		(net "P5E_CPU1_P3_TX_DP<11>")
	)
	(arc
		(start 123.709176 -279.634696)
		(mid 123.711797 -279.870105)
		(end 123.57354 -280.060654)
		(width 0.1143)
		(layer "In11.Cu")
		(net "P5E_CPU1_P3_TX_DP<11>")
	)
	(arc
		(start 123.032774 -284.151832)
		(mid 122.789447 -284.616398)
		(end 123.032774 -285.080964)
		(width 0.1143)
		(layer "In11.Cu")
		(net "P5E_CPU1_P3_TX_DP<11>")
	)
	(arc
		(start 123.729496 -296.076116)
		(mid 123.753605 -296.19788)
		(end 123.82246 -296.30116)
		(width 0.1143)
		(layer "In11.Cu")
		(net "P5E_CPU1_P3_TX_DP<11>")
	)
	(arc
		(start 123.936252 -296.414698)
		(mid 123.963841 -296.456083)
		(end 123.97359 -296.504868)
		(width 0.1143)
		(layer "In11.Cu")
		(net "P5E_CPU1_P3_TX_DP<11>")
	)
	(arc
		(start 123.032774 -292.251638)
		(mid 122.789447 -292.716204)
		(end 123.032774 -293.18077)
		(width 0.1143)
		(layer "In11.Cu")
		(net "P5E_CPU1_P3_TX_DP<11>")
	)
	(arc
		(start 123.075192 -281.865578)
		(mid 123.259925 -282.18627)
		(end 123.075446 -282.507182)
		(width 0.1143)
		(layer "In11.Cu")
		(net "P5E_CPU1_P3_TX_DP<11>")
	)
	(arc
		(start 123.10872 -291.605462)
		(mid 123.262818 -291.906198)
		(end 123.10872 -292.206934)
		(width 0.1143)
		(layer "In11.Cu")
		(net "P5E_CPU1_P3_TX_DP<11>")
	)
	(arc
		(start 123.528836 -280.086562)
		(mid 123.322977 -280.293063)
		(end 123.247658 -280.57475)
		(width 0.1143)
		(layer "In11.Cu")
		(net "P5E_CPU1_P3_TX_DP<11>")
	)
	(arc
		(start 122.789442 -287.856422)
		(mid 122.853957 -288.118641)
		(end 123.032774 -288.320988)
		(width 0.1143)
		(layer "In11.Cu")
		(net "P5E_CPU1_P3_TX_DP<11>")
	)
	(arc
		(start 123.032774 -280.911808)
		(mid 122.789447 -281.376374)
		(end 123.032774 -281.84094)
		(width 0.1143)
		(layer "In11.Cu")
		(net "P5E_CPU1_P3_TX_DP<11>")
	)
	(arc
		(start 123.032774 -282.53182)
		(mid 122.789447 -282.996386)
		(end 123.032774 -283.460952)
		(width 0.1143)
		(layer "In11.Cu")
		(net "P5E_CPU1_P3_TX_DP<11>")
	)
	(arc
		(start 131.14147 -367.886742)
		(mid 130.909115 -368.234486)
		(end 130.827526 -368.644678)
		(width 0.14224)
		(layer "In11.Cu")
		(net "P5E_CPU1_P3_TX_DP<11>")
	)
	(arc
		(start 123.57354 -279.452324)
		(mid 123.655521 -279.532974)
		(end 123.709176 -279.634696)
		(width 0.1143)
		(layer "In11.Cu")
		(net "P5E_CPU1_P3_TX_DP<11>")
	)
	(arc
		(start 123.032774 -290.631626)
		(mid 122.789447 -291.096192)
		(end 123.032774 -291.560758)
		(width 0.1143)
		(layer "In11.Cu")
		(net "P5E_CPU1_P3_TX_DP<11>")
	)
	(arc
		(start 123.075192 -283.48559)
		(mid 123.259925 -283.806282)
		(end 123.075446 -284.127194)
		(width 0.1143)
		(layer "In11.Cu")
		(net "P5E_CPU1_P3_TX_DP<11>")
	)
	(arc
		(start 123.075192 -288.345372)
		(mid 123.259925 -288.666064)
		(end 123.075446 -288.986976)
		(width 0.1143)
		(layer "In11.Cu")
		(net "P5E_CPU1_P3_TX_DP<11>")
	)
	(arc
		(start 122.795538 -278.219154)
		(mid 122.797326 -278.230603)
		(end 122.799348 -278.242014)
		(width 0.1143)
		(layer "In11.Cu")
		(net "P5E_CPU1_P3_TX_DP<11>")
	)
	(arc
		(start 123.104656 -294.842946)
		(mid 123.218539 -294.97356)
		(end 123.259596 -295.141904)
		(width 0.1143)
		(layer "In11.Cu")
		(net "P5E_CPU1_P3_TX_DP<11>")
	)
	(arc
		(start 123.075192 -285.105602)
		(mid 123.259925 -285.426294)
		(end 123.075446 -285.747206)
		(width 0.1143)
		(layer "In11.Cu")
		(net "P5E_CPU1_P3_TX_DP<11>")
	)
	(arc
		(start 123.259596 -287.050734)
		(mid 123.219341 -287.217547)
		(end 123.10745 -287.34766)
		(width 0.1143)
		(layer "In11.Cu")
		(net "P5E_CPU1_P3_TX_DP<11>")
	)
	(arc
		(start 123.247658 -280.58618)
		(mid 123.200747 -280.760809)
		(end 123.072652 -280.88844)
		(width 0.1143)
		(layer "In11.Cu")
		(net "P5E_CPU1_P3_TX_DP<11>")
	)
	(arc
		(start 123.573794 -295.65219)
		(mid 123.688154 -295.785473)
		(end 123.729242 -295.956228)
		(width 0.1143)
		(layer "In11.Cu")
		(net "P5E_CPU1_P3_TX_DP<11>")
	)
	(arc
		(start 123.259342 -295.146222)
		(mid 123.323857 -295.408441)
		(end 123.502674 -295.610788)
		(width 0.1143)
		(layer "In11.Cu")
		(net "P5E_CPU1_P3_TX_DP<11>")
	)
	(arc
		(start 123.035314 -287.390078)
		(mid 122.854662 -287.592823)
		(end 122.789442 -287.856422)
		(width 0.1143)
		(layer "In11.Cu")
		(net "P5E_CPU1_P3_TX_DP<11>")
	)
	(arc
		(start 123.075192 -289.965384)
		(mid 123.259925 -290.286076)
		(end 123.075446 -290.606988)
		(width 0.1143)
		(layer "In11.Cu")
		(net "P5E_CPU1_P3_TX_DP<11>")
	)
	(arc
		(start 123.032774 -289.011614)
		(mid 122.789447 -289.47618)
		(end 123.032774 -289.940746)
		(width 0.1143)
		(layer "In11.Cu")
		(net "P5E_CPU1_P3_TX_DP<11>")
	)
	(arc
		(start 122.799348 -278.242014)
		(mid 122.880781 -278.444412)
		(end 123.032774 -278.600916)
		(width 0.1143)
		(layer "In11.Cu")
		(net "P5E_CPU1_P3_TX_DP<11>")
	)
	(arc
		(start 123.032774 -285.771844)
		(mid 122.789447 -286.23641)
		(end 123.032774 -286.700976)
		(width 0.1143)
		(layer "In11.Cu")
		(net "P5E_CPU1_P3_TX_DP<11>")
	)
	(arc
		(start 143.865092 -346.842334)
		(mid 143.743766 -348.073772)
		(end 143.384524 -349.257874)
		(width 0.14224)
		(layer "In11.Cu")
		(net "P5E_CPU1_P3_TX_DP<11>")
	)
	(arc
		(start 123.272296 -278.966168)
		(mid 123.344561 -279.236097)
		(end 123.542044 -279.433782)
		(width 0.1143)
		(layer "In11.Cu")
		(net "P5E_CPU1_P3_TX_DP<11>")
	)
	(arc
		(start 123.032774 -293.87165)
		(mid 122.789447 -294.336216)
		(end 123.032774 -294.800782)
		(width 0.1143)
		(layer "In11.Cu")
		(net "P5E_CPU1_P3_TX_DP<11>")
	)
	(arc
		(start 139.83081 -357.83774)
		(mid 138.663788 -360.0212)
		(end 137.093198 -361.935014)
		(width 0.14224)
		(layer "In11.Cu")
		(net "P5E_CPU1_P3_TX_DP<11>")
	)
	(arc
		(start 123.105418 -286.743394)
		(mid 123.218825 -286.876283)
		(end 123.259596 -287.046162)
		(width 0.1143)
		(layer "In11.Cu")
		(net "P5E_CPU1_P3_TX_DP<11>")
	)
	(segment
		(start 129.105406 -374.93702)
		(end 128.809496 -375.23293)
		(width 0.12954)
		(layer "F.Cu")
		(net "P5E_CPU1_P3_TX_DP<10>")
	)
	(segment
		(start 129.105406 -374.23344)
		(end 129.105406 -374.93702)
		(width 0.12954)
		(layer "F.Cu")
		(net "P5E_CPU1_P3_TX_DP<10>")
	)
	(segment
		(start 128.834896 -373.96293)
		(end 129.105406 -374.23344)
		(width 0.12954)
		(layer "F.Cu")
		(net "P5E_CPU1_P3_TX_DP<10>")
	)
	(segment
		(start 121.94794 -274.630388)
		(end 122.414792 -274.896326)
		(width 0.12954)
		(layer "F.Cu")
		(net "P5E_CPU1_P3_TX_DP<10>")
	)
	(segment
		(start 122.135392 -294.825674)
		(end 122.136662 -294.826436)
		(width 0.1143)
		(layer "In11.Cu")
		(net "P5E_CPU1_P3_TX_DP<10>")
	)
	(segment
		(start 122.163586 -280.87066)
		(end 122.132598 -280.88844)
		(width 0.1143)
		(layer "In11.Cu")
		(net "P5E_CPU1_P3_TX_DP<10>")
	)
	(segment
		(start 122.136662 -277.006558)
		(end 122.137424 -277.007066)
		(width 0.1143)
		(layer "In11.Cu")
		(net "P5E_CPU1_P3_TX_DP<10>")
	)
	(segment
		(start 122.127518 -277.651464)
		(end 122.12574 -277.65248)
		(width 0.1143)
		(layer "In11.Cu")
		(net "P5E_CPU1_P3_TX_DP<10>")
	)
	(segment
		(start 122.14225 -281.869642)
		(end 122.163586 -281.882088)
		(width 0.1143)
		(layer "In11.Cu")
		(net "P5E_CPU1_P3_TX_DP<10>")
	)
	(segment
		(start 122.131836 -277.648924)
		(end 122.13082 -277.649432)
		(width 0.1143)
		(layer "In11.Cu")
		(net "P5E_CPU1_P3_TX_DP<10>")
	)
	(segment
		(start 122.099578 -294.804846)
		(end 122.10034 -294.805354)
		(width 0.1143)
		(layer "In11.Cu")
		(net "P5E_CPU1_P3_TX_DP<10>")
	)
	(segment
		(start 122.701304 -295.714674)
		(end 122.765058 -295.790366)
		(width 0.1143)
		(layer "In11.Cu")
		(net "P5E_CPU1_P3_TX_DP<10>")
	)
	(segment
		(start 122.602498 -295.634156)
		(end 122.605292 -295.63568)
		(width 0.1143)
		(layer "In11.Cu")
		(net "P5E_CPU1_P3_TX_DP<10>")
	)
	(segment
		(start 122.14225 -294.829484)
		(end 122.163586 -294.84193)
		(width 0.1143)
		(layer "In11.Cu")
		(net "P5E_CPU1_P3_TX_DP<10>")
	)
	(segment
		(start 122.127518 -284.131512)
		(end 122.12574 -284.132528)
		(width 0.1143)
		(layer "In11.Cu")
		(net "P5E_CPU1_P3_TX_DP<10>")
	)
	(segment
		(start 122.12828 -290.610798)
		(end 122.127518 -290.611306)
		(width 0.1143)
		(layer "In11.Cu")
		(net "P5E_CPU1_P3_TX_DP<10>")
	)
	(segment
		(start 122.13082 -293.849298)
		(end 122.129296 -293.850314)
		(width 0.1143)
		(layer "In11.Cu")
		(net "P5E_CPU1_P3_TX_DP<10>")
	)
	(segment
		(start 122.131836 -294.823642)
		(end 122.132598 -294.82415)
		(width 0.1143)
		(layer "In11.Cu")
		(net "P5E_CPU1_P3_TX_DP<10>")
	)
	(segment
		(start 122.129296 -280.890472)
		(end 122.12828 -280.89098)
		(width 0.1143)
		(layer "In11.Cu")
		(net "P5E_CPU1_P3_TX_DP<10>")
	)
	(segment
		(start 122.131836 -286.723836)
		(end 122.165364 -286.743394)
		(width 0.1143)
		(layer "In11.Cu")
		(net "P5E_CPU1_P3_TX_DP<10>")
	)
	(segment
		(start 122.12828 -282.510992)
		(end 122.127518 -282.5115)
		(width 0.1143)
		(layer "In11.Cu")
		(net "P5E_CPU1_P3_TX_DP<10>")
	)
	(segment
		(start 122.09272 -291.560758)
		(end 122.13082 -291.58311)
		(width 0.1143)
		(layer "In11.Cu")
		(net "P5E_CPU1_P3_TX_DP<10>")
	)
	(segment
		(start 122.124216 -280.89352)
		(end 122.09272 -280.911808)
		(width 0.1143)
		(layer "In11.Cu")
		(net "P5E_CPU1_P3_TX_DP<10>")
	)
	(segment
		(start 122.163586 -284.110684)
		(end 122.132598 -284.128464)
		(width 0.1143)
		(layer "In11.Cu")
		(net "P5E_CPU1_P3_TX_DP<10>")
	)
	(segment
		(start 142.915132 -340.549484)
		(end 142.915132 -346.793312)
		(width 0.14224)
		(layer "In11.Cu")
		(net "P5E_CPU1_P3_TX_DP<10>")
	)
	(segment
		(start 122.133868 -285.105094)
		(end 122.163586 -285.122112)
		(width 0.1143)
		(layer "In11.Cu")
		(net "P5E_CPU1_P3_TX_DP<10>")
	)
	(segment
		(start 122.127518 -285.751524)
		(end 122.12574 -285.75254)
		(width 0.1143)
		(layer "In11.Cu")
		(net "P5E_CPU1_P3_TX_DP<10>")
	)
	(segment
		(start 122.163586 -293.830502)
		(end 122.131836 -293.84879)
		(width 0.1143)
		(layer "In11.Cu")
		(net "P5E_CPU1_P3_TX_DP<10>")
	)
	(segment
		(start 122.135392 -293.205662)
		(end 122.136662 -293.206424)
		(width 0.1143)
		(layer "In11.Cu")
		(net "P5E_CPU1_P3_TX_DP<10>")
	)
	(segment
		(start 122.131836 -285.748984)
		(end 122.13082 -285.749492)
		(width 0.1143)
		(layer "In11.Cu")
		(net "P5E_CPU1_P3_TX_DP<10>")
	)
	(segment
		(start 122.12574 -288.99231)
		(end 122.124216 -288.993326)
		(width 0.1143)
		(layer "In11.Cu")
		(net "P5E_CPU1_P3_TX_DP<10>")
	)
	(segment
		(start 122.135392 -289.965638)
		(end 122.136662 -289.9664)
		(width 0.1143)
		(layer "In11.Cu")
		(net "P5E_CPU1_P3_TX_DP<10>")
	)
	(segment
		(start 122.127518 -292.231318)
		(end 122.12574 -292.232334)
		(width 0.1143)
		(layer "In11.Cu")
		(net "P5E_CPU1_P3_TX_DP<10>")
	)
	(segment
		(start 122.132598 -276.028404)
		(end 122.131836 -276.028912)
		(width 0.1143)
		(layer "In11.Cu")
		(net "P5E_CPU1_P3_TX_DP<10>")
	)
	(segment
		(start 122.132598 -277.004272)
		(end 122.133868 -277.005034)
		(width 0.1143)
		(layer "In11.Cu")
		(net "P5E_CPU1_P3_TX_DP<10>")
	)
	(segment
		(start 122.132598 -281.864308)
		(end 122.133868 -281.86507)
		(width 0.1143)
		(layer "In11.Cu")
		(net "P5E_CPU1_P3_TX_DP<10>")
	)
	(segment
		(start 122.56262 -295.610788)
		(end 122.60072 -295.63314)
		(width 0.1143)
		(layer "In11.Cu")
		(net "P5E_CPU1_P3_TX_DP<10>")
	)
	(segment
		(start 122.124216 -284.133544)
		(end 122.09272 -284.151832)
		(width 0.1143)
		(layer "In11.Cu")
		(net "P5E_CPU1_P3_TX_DP<10>")
	)
	(segment
		(start 122.09272 -278.600916)
		(end 122.099578 -278.60498)
		(width 0.1143)
		(layer "In11.Cu")
		(net "P5E_CPU1_P3_TX_DP<10>")
	)
	(segment
		(start 122.87631 -296.38879)
		(end 122.87631 -296.538396)
		(width 0.1143)
		(layer "In11.Cu")
		(net "P5E_CPU1_P3_TX_DP<10>")
	)
	(segment
		(start 122.10034 -278.605488)
		(end 122.131836 -278.623776)
		(width 0.1143)
		(layer "In11.Cu")
		(net "P5E_CPU1_P3_TX_DP<10>")
	)
	(segment
		(start 122.60199 -275.218906)
		(end 122.562874 -275.241766)
		(width 0.1143)
		(layer "In11.Cu")
		(net "P5E_CPU1_P3_TX_DP<10>")
	)
	(segment
		(start 122.60834 -295.637458)
		(end 122.60961 -295.63822)
		(width 0.1143)
		(layer "In11.Cu")
		(net "P5E_CPU1_P3_TX_DP<10>")
	)
	(segment
		(start 122.132598 -290.608258)
		(end 122.131836 -290.608766)
		(width 0.1143)
		(layer "In11.Cu")
		(net "P5E_CPU1_P3_TX_DP<10>")
	)
	(segment
		(start 122.83059 -296.612564)
		(end 122.83059 -296.919142)
		(width 0.14224)
		(layer "In11.Cu")
		(net "P5E_CPU1_P3_TX_DP<10>")
	)
	(segment
		(start 122.131836 -277.003764)
		(end 122.132598 -277.004272)
		(width 0.1143)
		(layer "In11.Cu")
		(net "P5E_CPU1_P3_TX_DP<10>")
	)
	(segment
		(start 122.163586 -287.350454)
		(end 122.131836 -287.368742)
		(width 0.1143)
		(layer "In11.Cu")
		(net "P5E_CPU1_P3_TX_DP<10>")
	)
	(segment
		(start 122.124216 -277.653496)
		(end 122.09272 -277.671784)
		(width 0.1143)
		(layer "In11.Cu")
		(net "P5E_CPU1_P3_TX_DP<10>")
	)
	(segment
		(start 122.131836 -285.103824)
		(end 122.132598 -285.104332)
		(width 0.1143)
		(layer "In11.Cu")
		(net "P5E_CPU1_P3_TX_DP<10>")
	)
	(segment
		(start 122.131836 -282.50896)
		(end 122.13082 -282.509468)
		(width 0.1143)
		(layer "In11.Cu")
		(net "P5E_CPU1_P3_TX_DP<10>")
	)
	(segment
		(start 131.835398 -309.775352)
		(end 137.54354 -318.317626)
		(width 0.14224)
		(layer "In11.Cu")
		(net "P5E_CPU1_P3_TX_DP<10>")
	)
	(segment
		(start 122.129296 -288.990278)
		(end 122.12828 -288.990786)
		(width 0.1143)
		(layer "In11.Cu")
		(net "P5E_CPU1_P3_TX_DP<10>")
	)
	(segment
		(start 122.129296 -276.030436)
		(end 122.12828 -276.030944)
		(width 0.1143)
		(layer "In11.Cu")
		(net "P5E_CPU1_P3_TX_DP<10>")
	)
	(segment
		(start 122.137424 -289.966908)
		(end 122.13844 -289.967416)
		(width 0.1143)
		(layer "In11.Cu")
		(net "P5E_CPU1_P3_TX_DP<10>")
	)
	(segment
		(start 122.12828 -292.23081)
		(end 122.127518 -292.231318)
		(width 0.1143)
		(layer "In11.Cu")
		(net "P5E_CPU1_P3_TX_DP<10>")
	)
	(segment
		(start 122.601736 -295.633648)
		(end 122.602498 -295.634156)
		(width 0.1143)
		(layer "In11.Cu")
		(net "P5E_CPU1_P3_TX_DP<10>")
	)
	(segment
		(start 122.137424 -278.627078)
		(end 122.13844 -278.627586)
		(width 0.1143)
		(layer "In11.Cu")
		(net "P5E_CPU1_P3_TX_DP<10>")
	)
	(segment
		(start 122.124216 -288.993326)
		(end 122.09272 -289.011614)
		(width 0.1143)
		(layer "In11.Cu")
		(net "P5E_CPU1_P3_TX_DP<10>")
	)
	(segment
		(start 122.60961 -295.63822)
		(end 122.61215 -295.63949)
		(width 0.1143)
		(layer "In11.Cu")
		(net "P5E_CPU1_P3_TX_DP<10>")
	)
	(segment
		(start 122.163586 -282.490672)
		(end 122.132598 -282.508452)
		(width 0.1143)
		(layer "In11.Cu")
		(net "P5E_CPU1_P3_TX_DP<10>")
	)
	(segment
		(start 122.133868 -289.964876)
		(end 122.135392 -289.965638)
		(width 0.1143)
		(layer "In11.Cu")
		(net "P5E_CPU1_P3_TX_DP<10>")
	)
	(segment
		(start 122.131836 -293.84879)
		(end 122.13082 -293.849298)
		(width 0.1143)
		(layer "In11.Cu")
		(net "P5E_CPU1_P3_TX_DP<10>")
	)
	(segment
		(start 122.12574 -277.65248)
		(end 122.124216 -277.653496)
		(width 0.1143)
		(layer "In11.Cu")
		(net "P5E_CPU1_P3_TX_DP<10>")
	)
	(segment
		(start 122.79503 -295.872408)
		(end 122.79503 -296.067988)
		(width 0.1143)
		(layer "In11.Cu")
		(net "P5E_CPU1_P3_TX_DP<10>")
	)
	(segment
		(start 122.09272 -288.320988)
		(end 122.131836 -288.343848)
		(width 0.1143)
		(layer "In11.Cu")
		(net "P5E_CPU1_P3_TX_DP<10>")
	)
	(segment
		(start 122.132598 -283.48432)
		(end 122.133868 -283.485082)
		(width 0.1143)
		(layer "In11.Cu")
		(net "P5E_CPU1_P3_TX_DP<10>")
	)
	(segment
		(start 122.09272 -283.460952)
		(end 122.13082 -283.483304)
		(width 0.1143)
		(layer "In11.Cu")
		(net "P5E_CPU1_P3_TX_DP<10>")
	)
	(segment
		(start 122.13971 -289.968178)
		(end 122.14225 -289.969448)
		(width 0.1143)
		(layer "In11.Cu")
		(net "P5E_CPU1_P3_TX_DP<10>")
	)
	(segment
		(start 142.545308 -348.652084)
		(end 138.820144 -357.646224)
		(width 0.14224)
		(layer "In11.Cu")
		(net "P5E_CPU1_P3_TX_DP<10>")
	)
	(segment
		(start 122.132598 -291.584126)
		(end 122.133868 -291.584888)
		(width 0.1143)
		(layer "In11.Cu")
		(net "P5E_CPU1_P3_TX_DP<10>")
	)
	(segment
		(start 122.099578 -281.845004)
		(end 122.10034 -281.845512)
		(width 0.1143)
		(layer "In11.Cu")
		(net "P5E_CPU1_P3_TX_DP<10>")
	)
	(segment
		(start 122.131836 -287.368742)
		(end 122.09526 -287.390078)
		(width 0.1143)
		(layer "In11.Cu")
		(net "P5E_CPU1_P3_TX_DP<10>")
	)
	(segment
		(start 122.13971 -294.828214)
		(end 122.14225 -294.829484)
		(width 0.1143)
		(layer "In11.Cu")
		(net "P5E_CPU1_P3_TX_DP<10>")
	)
	(segment
		(start 122.132598 -289.964114)
		(end 122.133868 -289.964876)
		(width 0.1143)
		(layer "In11.Cu")
		(net "P5E_CPU1_P3_TX_DP<10>")
	)
	(segment
		(start 136.437116 -361.212638)
		(end 131.693666 -365.956088)
		(width 0.14224)
		(layer "In11.Cu")
		(net "P5E_CPU1_P3_TX_DP<10>")
	)
	(segment
		(start 122.163586 -288.970466)
		(end 122.132598 -288.988246)
		(width 0.1143)
		(layer "In11.Cu")
		(net "P5E_CPU1_P3_TX_DP<10>")
	)
	(segment
		(start 129.078482 -373.719344)
		(end 128.834896 -373.96293)
		(width 0.14224)
		(layer "In11.Cu")
		(net "P5E_CPU1_P3_TX_DP<10>")
	)
	(segment
		(start 122.127518 -282.5115)
		(end 122.12574 -282.512516)
		(width 0.1143)
		(layer "In11.Cu")
		(net "P5E_CPU1_P3_TX_DP<10>")
	)
	(segment
		(start 122.12574 -280.892504)
		(end 122.124216 -280.89352)
		(width 0.1143)
		(layer "In11.Cu")
		(net "P5E_CPU1_P3_TX_DP<10>")
	)
	(segment
		(start 122.12828 -285.751016)
		(end 122.127518 -285.751524)
		(width 0.1143)
		(layer "In11.Cu")
		(net "P5E_CPU1_P3_TX_DP<10>")
	)
	(segment
		(start 122.132598 -285.104332)
		(end 122.133868 -285.105094)
		(width 0.1143)
		(layer "In11.Cu")
		(net "P5E_CPU1_P3_TX_DP<10>")
	)
	(segment
		(start 122.09272 -289.940746)
		(end 122.099578 -289.94481)
		(width 0.1143)
		(layer "In11.Cu")
		(net "P5E_CPU1_P3_TX_DP<10>")
	)
	(segment
		(start 122.131836 -283.483812)
		(end 122.132598 -283.48432)
		(width 0.1143)
		(layer "In11.Cu")
		(net "P5E_CPU1_P3_TX_DP<10>")
	)
	(segment
		(start 122.137424 -294.826944)
		(end 122.13844 -294.827452)
		(width 0.1143)
		(layer "In11.Cu")
		(net "P5E_CPU1_P3_TX_DP<10>")
	)
	(segment
		(start 122.12828 -277.650956)
		(end 122.127518 -277.651464)
		(width 0.1143)
		(layer "In11.Cu")
		(net "P5E_CPU1_P3_TX_DP<10>")
	)
	(segment
		(start 122.12574 -292.232334)
		(end 122.124216 -292.23335)
		(width 0.1143)
		(layer "In11.Cu")
		(net "P5E_CPU1_P3_TX_DP<10>")
	)
	(segment
		(start 122.13082 -277.649432)
		(end 122.129296 -277.650448)
		(width 0.1143)
		(layer "In11.Cu")
		(net "P5E_CPU1_P3_TX_DP<10>")
	)
	(segment
		(start 122.12574 -290.612322)
		(end 122.124216 -290.613338)
		(width 0.1143)
		(layer "In11.Cu")
		(net "P5E_CPU1_P3_TX_DP<10>")
	)
	(segment
		(start 122.124216 -282.513532)
		(end 122.09272 -282.53182)
		(width 0.1143)
		(layer "In11.Cu")
		(net "P5E_CPU1_P3_TX_DP<10>")
	)
	(segment
		(start 122.127518 -290.611306)
		(end 122.12574 -290.612322)
		(width 0.1143)
		(layer "In11.Cu")
		(net "P5E_CPU1_P3_TX_DP<10>")
	)
	(segment
		(start 122.135392 -278.625808)
		(end 122.136662 -278.62657)
		(width 0.1143)
		(layer "In11.Cu")
		(net "P5E_CPU1_P3_TX_DP<10>")
	)
	(segment
		(start 122.133868 -278.625046)
		(end 122.135392 -278.625808)
		(width 0.1143)
		(layer "In11.Cu")
		(net "P5E_CPU1_P3_TX_DP<10>")
	)
	(segment
		(start 122.132598 -282.508452)
		(end 122.131836 -282.50896)
		(width 0.1143)
		(layer "In11.Cu")
		(net "P5E_CPU1_P3_TX_DP<10>")
	)
	(segment
		(start 122.132598 -278.624284)
		(end 122.133868 -278.625046)
		(width 0.1143)
		(layer "In11.Cu")
		(net "P5E_CPU1_P3_TX_DP<10>")
	)
	(segment
		(start 122.129296 -293.850314)
		(end 122.09272 -293.87165)
		(width 0.1143)
		(layer "In11.Cu")
		(net "P5E_CPU1_P3_TX_DP<10>")
	)
	(segment
		(start 122.099578 -293.184834)
		(end 122.10034 -293.185342)
		(width 0.1143)
		(layer "In11.Cu")
		(net "P5E_CPU1_P3_TX_DP<10>")
	)
	(segment
		(start 122.133868 -283.485082)
		(end 122.163586 -283.5021)
		(width 0.1143)
		(layer "In11.Cu")
		(net "P5E_CPU1_P3_TX_DP<10>")
	)
	(segment
		(start 122.63247 -280.061162)
		(end 122.60199 -280.078942)
		(width 0.1143)
		(layer "In11.Cu")
		(net "P5E_CPU1_P3_TX_DP<10>")
	)
	(segment
		(start 122.13082 -282.509468)
		(end 122.129296 -282.510484)
		(width 0.1143)
		(layer "In11.Cu")
		(net "P5E_CPU1_P3_TX_DP<10>")
	)
	(segment
		(start 122.414792 -274.896326)
		(end 122.712734 -274.896326)
		(width 0.1143)
		(layer "In11.Cu")
		(net "P5E_CPU1_P3_TX_DP<10>")
	)
	(segment
		(start 122.13844 -281.86761)
		(end 122.13971 -281.868372)
		(width 0.1143)
		(layer "In11.Cu")
		(net "P5E_CPU1_P3_TX_DP<10>")
	)
	(segment
		(start 122.131836 -290.608766)
		(end 122.13082 -290.609274)
		(width 0.1143)
		(layer "In11.Cu")
		(net "P5E_CPU1_P3_TX_DP<10>")
	)
	(segment
		(start 122.163586 -277.630636)
		(end 122.132598 -277.648416)
		(width 0.1143)
		(layer "In11.Cu")
		(net "P5E_CPU1_P3_TX_DP<10>")
	)
	(segment
		(start 122.606054 -295.636188)
		(end 122.607578 -295.63695)
		(width 0.1143)
		(layer "In11.Cu")
		(net "P5E_CPU1_P3_TX_DP<10>")
	)
	(segment
		(start 122.14225 -278.629618)
		(end 122.163586 -278.642064)
		(width 0.1143)
		(layer "In11.Cu")
		(net "P5E_CPU1_P3_TX_DP<10>")
	)
	(segment
		(start 122.562874 -279.410922)
		(end 122.60199 -279.433782)
		(width 0.1143)
		(layer "In11.Cu")
		(net "P5E_CPU1_P3_TX_DP<10>")
	)
	(segment
		(start 122.13971 -277.008336)
		(end 122.14225 -277.009606)
		(width 0.1143)
		(layer "In11.Cu")
		(net "P5E_CPU1_P3_TX_DP<10>")
	)
	(segment
		(start 122.13082 -285.749492)
		(end 122.129296 -285.750508)
		(width 0.1143)
		(layer "In11.Cu")
		(net "P5E_CPU1_P3_TX_DP<10>")
	)
	(segment
		(start 122.319542 -295.146222)
		(end 122.319288 -295.146222)
		(width 0.1143)
		(layer "In11.Cu")
		(net "P5E_CPU1_P3_TX_DP<10>")
	)
	(segment
		(start 122.63247 -275.201126)
		(end 122.60199 -275.218906)
		(width 0.1143)
		(layer "In11.Cu")
		(net "P5E_CPU1_P3_TX_DP<10>")
	)
	(segment
		(start 129.125726 -369.33632)
		(end 129.125726 -373.605298)
		(width 0.14224)
		(layer "In11.Cu")
		(net "P5E_CPU1_P3_TX_DP<10>")
	)
	(segment
		(start 122.132598 -294.82415)
		(end 122.133868 -294.824912)
		(width 0.1143)
		(layer "In11.Cu")
		(net "P5E_CPU1_P3_TX_DP<10>")
	)
	(segment
		(start 122.607578 -295.63695)
		(end 122.60834 -295.637458)
		(width 0.1143)
		(layer "In11.Cu")
		(net "P5E_CPU1_P3_TX_DP<10>")
	)
	(segment
		(start 122.099578 -278.60498)
		(end 122.10034 -278.605488)
		(width 0.1143)
		(layer "In11.Cu")
		(net "P5E_CPU1_P3_TX_DP<10>")
	)
	(segment
		(start 122.09272 -286.700976)
		(end 122.131836 -286.723836)
		(width 0.1143)
		(layer "In11.Cu")
		(net "P5E_CPU1_P3_TX_DP<10>")
	)
	(segment
		(start 122.10034 -276.985476)
		(end 122.131836 -277.003764)
		(width 0.1143)
		(layer "In11.Cu")
		(net "P5E_CPU1_P3_TX_DP<10>")
	)
	(segment
		(start 122.137424 -293.206932)
		(end 122.13844 -293.20744)
		(width 0.1143)
		(layer "In11.Cu")
		(net "P5E_CPU1_P3_TX_DP<10>")
	)
	(segment
		(start 122.129296 -292.230302)
		(end 122.12828 -292.23081)
		(width 0.1143)
		(layer "In11.Cu")
		(net "P5E_CPU1_P3_TX_DP<10>")
	)
	(segment
		(start 122.13844 -293.20744)
		(end 122.13971 -293.208202)
		(width 0.1143)
		(layer "In11.Cu")
		(net "P5E_CPU1_P3_TX_DP<10>")
	)
	(segment
		(start 122.131836 -288.988754)
		(end 122.13082 -288.989262)
		(width 0.1143)
		(layer "In11.Cu")
		(net "P5E_CPU1_P3_TX_DP<10>")
	)
	(segment
		(start 122.137424 -277.007066)
		(end 122.13844 -277.007574)
		(width 0.1143)
		(layer "In11.Cu")
		(net "P5E_CPU1_P3_TX_DP<10>")
	)
	(segment
		(start 122.13844 -294.827452)
		(end 122.13971 -294.828214)
		(width 0.1143)
		(layer "In11.Cu")
		(net "P5E_CPU1_P3_TX_DP<10>")
	)
	(segment
		(start 122.13082 -283.483304)
		(end 122.131836 -283.483812)
		(width 0.1143)
		(layer "In11.Cu")
		(net "P5E_CPU1_P3_TX_DP<10>")
	)
	(segment
		(start 122.14225 -277.009606)
		(end 122.163586 -277.022052)
		(width 0.1143)
		(layer "In11.Cu")
		(net "P5E_CPU1_P3_TX_DP<10>")
	)
	(segment
		(start 122.131836 -291.583618)
		(end 122.132598 -291.584126)
		(width 0.1143)
		(layer "In11.Cu")
		(net "P5E_CPU1_P3_TX_DP<10>")
	)
	(segment
		(start 122.12574 -282.512516)
		(end 122.124216 -282.513532)
		(width 0.1143)
		(layer "In11.Cu")
		(net "P5E_CPU1_P3_TX_DP<10>")
	)
	(segment
		(start 122.133868 -294.824912)
		(end 122.135392 -294.825674)
		(width 0.1143)
		(layer "In11.Cu")
		(net "P5E_CPU1_P3_TX_DP<10>")
	)
	(segment
		(start 122.13082 -288.989262)
		(end 122.129296 -288.990278)
		(width 0.1143)
		(layer "In11.Cu")
		(net "P5E_CPU1_P3_TX_DP<10>")
	)
	(segment
		(start 122.131836 -284.128972)
		(end 122.13082 -284.12948)
		(width 0.1143)
		(layer "In11.Cu")
		(net "P5E_CPU1_P3_TX_DP<10>")
	)
	(segment
		(start 122.131836 -293.20363)
		(end 122.132598 -293.204138)
		(width 0.1143)
		(layer "In11.Cu")
		(net "P5E_CPU1_P3_TX_DP<10>")
	)
	(segment
		(start 122.124216 -285.753556)
		(end 122.09272 -285.771844)
		(width 0.1143)
		(layer "In11.Cu")
		(net "P5E_CPU1_P3_TX_DP<10>")
	)
	(segment
		(start 122.133868 -277.005034)
		(end 122.135392 -277.005796)
		(width 0.1143)
		(layer "In11.Cu")
		(net "P5E_CPU1_P3_TX_DP<10>")
	)
	(segment
		(start 122.12828 -280.89098)
		(end 122.127518 -280.891488)
		(width 0.1143)
		(layer "In11.Cu")
		(net "P5E_CPU1_P3_TX_DP<10>")
	)
	(segment
		(start 122.10034 -294.805354)
		(end 122.131836 -294.823642)
		(width 0.1143)
		(layer "In11.Cu")
		(net "P5E_CPU1_P3_TX_DP<10>")
	)
	(segment
		(start 122.13082 -284.12948)
		(end 122.129296 -284.130496)
		(width 0.1143)
		(layer "In11.Cu")
		(net "P5E_CPU1_P3_TX_DP<10>")
	)
	(segment
		(start 122.13971 -293.208202)
		(end 122.14225 -293.209472)
		(width 0.1143)
		(layer "In11.Cu")
		(net "P5E_CPU1_P3_TX_DP<10>")
	)
	(segment
		(start 122.099578 -289.94481)
		(end 122.10034 -289.945318)
		(width 0.1143)
		(layer "In11.Cu")
		(net "P5E_CPU1_P3_TX_DP<10>")
	)
	(segment
		(start 122.13082 -280.889456)
		(end 122.129296 -280.890472)
		(width 0.1143)
		(layer "In11.Cu")
		(net "P5E_CPU1_P3_TX_DP<10>")
	)
	(segment
		(start 122.10034 -293.185342)
		(end 122.131836 -293.20363)
		(width 0.1143)
		(layer "In11.Cu")
		(net "P5E_CPU1_P3_TX_DP<10>")
	)
	(segment
		(start 122.60072 -295.63314)
		(end 122.601736 -295.633648)
		(width 0.1143)
		(layer "In11.Cu")
		(net "P5E_CPU1_P3_TX_DP<10>")
	)
	(segment
		(start 122.131836 -288.343848)
		(end 122.165364 -288.363406)
		(width 0.1143)
		(layer "In11.Cu")
		(net "P5E_CPU1_P3_TX_DP<10>")
	)
	(segment
		(start 122.127518 -288.991294)
		(end 122.12574 -288.99231)
		(width 0.1143)
		(layer "In11.Cu")
		(net "P5E_CPU1_P3_TX_DP<10>")
	)
	(segment
		(start 122.13082 -276.02942)
		(end 122.129296 -276.030436)
		(width 0.1143)
		(layer "In11.Cu")
		(net "P5E_CPU1_P3_TX_DP<10>")
	)
	(segment
		(start 122.12574 -276.032468)
		(end 122.124216 -276.033484)
		(width 0.1143)
		(layer "In11.Cu")
		(net "P5E_CPU1_P3_TX_DP<10>")
	)
	(segment
		(start 139.370054 -322.72605)
		(end 142.915132 -340.549484)
		(width 0.14224)
		(layer "In11.Cu")
		(net "P5E_CPU1_P3_TX_DP<10>")
	)
	(segment
		(start 122.12828 -276.030944)
		(end 122.127518 -276.031452)
		(width 0.1143)
		(layer "In11.Cu")
		(net "P5E_CPU1_P3_TX_DP<10>")
	)
	(segment
		(start 122.131836 -280.888948)
		(end 122.13082 -280.889456)
		(width 0.1143)
		(layer "In11.Cu")
		(net "P5E_CPU1_P3_TX_DP<10>")
	)
	(segment
		(start 122.124216 -276.033484)
		(end 122.09272 -276.051772)
		(width 0.1143)
		(layer "In11.Cu")
		(net "P5E_CPU1_P3_TX_DP<10>")
	)
	(segment
		(start 122.13844 -289.967416)
		(end 122.13971 -289.968178)
		(width 0.1143)
		(layer "In11.Cu")
		(net "P5E_CPU1_P3_TX_DP<10>")
	)
	(segment
		(start 122.87631 -296.538396)
		(end 122.83059 -296.584116)
		(width 0.1143)
		(layer "In11.Cu")
		(net "P5E_CPU1_P3_TX_DP<10>")
	)
	(segment
		(start 122.12828 -284.131004)
		(end 122.127518 -284.131512)
		(width 0.1143)
		(layer "In11.Cu")
		(net "P5E_CPU1_P3_TX_DP<10>")
	)
	(segment
		(start 122.136662 -293.206424)
		(end 122.137424 -293.206932)
		(width 0.1143)
		(layer "In11.Cu")
		(net "P5E_CPU1_P3_TX_DP<10>")
	)
	(segment
		(start 122.12574 -284.132528)
		(end 122.124216 -284.133544)
		(width 0.1143)
		(layer "In11.Cu")
		(net "P5E_CPU1_P3_TX_DP<10>")
	)
	(segment
		(start 122.163586 -285.730696)
		(end 122.132598 -285.748476)
		(width 0.1143)
		(layer "In11.Cu")
		(net "P5E_CPU1_P3_TX_DP<10>")
	)
	(segment
		(start 122.83059 -296.584116)
		(end 122.83059 -296.612564)
		(width 0.1143)
		(layer "In11.Cu")
		(net "P5E_CPU1_P3_TX_DP<10>")
	)
	(segment
		(start 122.83059 -296.919142)
		(end 123.561856 -299.329602)
		(width 0.14224)
		(layer "In11.Cu")
		(net "P5E_CPU1_P3_TX_DP<10>")
	)
	(segment
		(start 122.09272 -285.080964)
		(end 122.13082 -285.103316)
		(width 0.1143)
		(layer "In11.Cu")
		(net "P5E_CPU1_P3_TX_DP<10>")
	)
	(segment
		(start 122.124216 -290.613338)
		(end 122.09272 -290.631626)
		(width 0.1143)
		(layer "In11.Cu")
		(net "P5E_CPU1_P3_TX_DP<10>")
	)
	(segment
		(start 122.131836 -276.028912)
		(end 122.13082 -276.02942)
		(width 0.1143)
		(layer "In11.Cu")
		(net "P5E_CPU1_P3_TX_DP<10>")
	)
	(segment
		(start 122.13844 -278.627586)
		(end 122.13971 -278.628348)
		(width 0.1143)
		(layer "In11.Cu")
		(net "P5E_CPU1_P3_TX_DP<10>")
	)
	(segment
		(start 122.133868 -293.2049)
		(end 122.135392 -293.205662)
		(width 0.1143)
		(layer "In11.Cu")
		(net "P5E_CPU1_P3_TX_DP<10>")
	)
	(segment
		(start 122.13844 -277.007574)
		(end 122.13971 -277.008336)
		(width 0.1143)
		(layer "In11.Cu")
		(net "P5E_CPU1_P3_TX_DP<10>")
	)
	(segment
		(start 122.099578 -276.984968)
		(end 122.10034 -276.985476)
		(width 0.1143)
		(layer "In11.Cu")
		(net "P5E_CPU1_P3_TX_DP<10>")
	)
	(segment
		(start 122.127518 -280.891488)
		(end 122.12574 -280.892504)
		(width 0.1143)
		(layer "In11.Cu")
		(net "P5E_CPU1_P3_TX_DP<10>")
	)
	(segment
		(start 122.132598 -280.88844)
		(end 122.131836 -280.888948)
		(width 0.1143)
		(layer "In11.Cu")
		(net "P5E_CPU1_P3_TX_DP<10>")
	)
	(segment
		(start 122.132598 -292.22827)
		(end 122.131836 -292.228778)
		(width 0.1143)
		(layer "In11.Cu")
		(net "P5E_CPU1_P3_TX_DP<10>")
	)
	(segment
		(start 122.132598 -293.204138)
		(end 122.133868 -293.2049)
		(width 0.1143)
		(layer "In11.Cu")
		(net "P5E_CPU1_P3_TX_DP<10>")
	)
	(segment
		(start 122.133868 -281.86507)
		(end 122.135392 -281.865832)
		(width 0.1143)
		(layer "In11.Cu")
		(net "P5E_CPU1_P3_TX_DP<10>")
	)
	(segment
		(start 122.61215 -295.63949)
		(end 122.633486 -295.651936)
		(width 0.1143)
		(layer "In11.Cu")
		(net "P5E_CPU1_P3_TX_DP<10>")
	)
	(segment
		(start 122.132598 -288.988246)
		(end 122.131836 -288.988754)
		(width 0.1143)
		(layer "In11.Cu")
		(net "P5E_CPU1_P3_TX_DP<10>")
	)
	(segment
		(start 122.133868 -291.584888)
		(end 122.163586 -291.601906)
		(width 0.1143)
		(layer "In11.Cu")
		(net "P5E_CPU1_P3_TX_DP<10>")
	)
	(segment
		(start 122.13082 -292.229286)
		(end 122.129296 -292.230302)
		(width 0.1143)
		(layer "In11.Cu")
		(net "P5E_CPU1_P3_TX_DP<10>")
	)
	(segment
		(start 137.54354 -318.317626)
		(end 139.370054 -322.72605)
		(width 0.14224)
		(layer "In11.Cu")
		(net "P5E_CPU1_P3_TX_DP<10>")
	)
	(segment
		(start 122.60199 -280.078942)
		(end 122.562874 -280.101802)
		(width 0.1143)
		(layer "In11.Cu")
		(net "P5E_CPU1_P3_TX_DP<10>")
	)
	(segment
		(start 122.129296 -282.510484)
		(end 122.12828 -282.510992)
		(width 0.1143)
		(layer "In11.Cu")
		(net "P5E_CPU1_P3_TX_DP<10>")
	)
	(segment
		(start 122.129296 -277.650448)
		(end 122.12828 -277.650956)
		(width 0.1143)
		(layer "In11.Cu")
		(net "P5E_CPU1_P3_TX_DP<10>")
	)
	(segment
		(start 122.163586 -292.21049)
		(end 122.132598 -292.22827)
		(width 0.1143)
		(layer "In11.Cu")
		(net "P5E_CPU1_P3_TX_DP<10>")
	)
	(segment
		(start 122.135392 -277.005796)
		(end 122.136662 -277.006558)
		(width 0.1143)
		(layer "In11.Cu")
		(net "P5E_CPU1_P3_TX_DP<10>")
	)
	(segment
		(start 122.135392 -281.865832)
		(end 122.136662 -281.866594)
		(width 0.1143)
		(layer "In11.Cu")
		(net "P5E_CPU1_P3_TX_DP<10>")
	)
	(segment
		(start 122.131836 -292.228778)
		(end 122.13082 -292.229286)
		(width 0.1143)
		(layer "In11.Cu")
		(net "P5E_CPU1_P3_TX_DP<10>")
	)
	(segment
		(start 122.136662 -281.866594)
		(end 122.137424 -281.867102)
		(width 0.1143)
		(layer "In11.Cu")
		(net "P5E_CPU1_P3_TX_DP<10>")
	)
	(segment
		(start 122.60199 -279.433782)
		(end 122.63247 -279.451562)
		(width 0.1143)
		(layer "In11.Cu")
		(net "P5E_CPU1_P3_TX_DP<10>")
	)
	(segment
		(start 122.132598 -284.128464)
		(end 122.131836 -284.128972)
		(width 0.1143)
		(layer "In11.Cu")
		(net "P5E_CPU1_P3_TX_DP<10>")
	)
	(segment
		(start 122.712734 -274.896326)
		(end 122.782584 -274.966176)
		(width 0.1143)
		(layer "In11.Cu")
		(net "P5E_CPU1_P3_TX_DP<10>")
	)
	(segment
		(start 122.132598 -277.648416)
		(end 122.131836 -277.648924)
		(width 0.1143)
		(layer "In11.Cu")
		(net "P5E_CPU1_P3_TX_DP<10>")
	)
	(segment
		(start 122.13082 -290.609274)
		(end 122.129296 -290.61029)
		(width 0.1143)
		(layer "In11.Cu")
		(net "P5E_CPU1_P3_TX_DP<10>")
	)
	(segment
		(start 122.163586 -276.010624)
		(end 122.132598 -276.028404)
		(width 0.1143)
		(layer "In11.Cu")
		(net "P5E_CPU1_P3_TX_DP<10>")
	)
	(segment
		(start 122.129296 -285.750508)
		(end 122.12828 -285.751016)
		(width 0.1143)
		(layer "In11.Cu")
		(net "P5E_CPU1_P3_TX_DP<10>")
	)
	(segment
		(start 122.09272 -276.980904)
		(end 122.099578 -276.984968)
		(width 0.1143)
		(layer "In11.Cu")
		(net "P5E_CPU1_P3_TX_DP<10>")
	)
	(segment
		(start 122.129296 -284.130496)
		(end 122.12828 -284.131004)
		(width 0.1143)
		(layer "In11.Cu")
		(net "P5E_CPU1_P3_TX_DP<10>")
	)
	(segment
		(start 122.14225 -289.969448)
		(end 122.163586 -289.981894)
		(width 0.1143)
		(layer "In11.Cu")
		(net "P5E_CPU1_P3_TX_DP<10>")
	)
	(segment
		(start 122.13971 -278.628348)
		(end 122.14225 -278.629618)
		(width 0.1143)
		(layer "In11.Cu")
		(net "P5E_CPU1_P3_TX_DP<10>")
	)
	(segment
		(start 122.09272 -294.800782)
		(end 122.099578 -294.804846)
		(width 0.1143)
		(layer "In11.Cu")
		(net "P5E_CPU1_P3_TX_DP<10>")
	)
	(segment
		(start 122.136662 -289.9664)
		(end 122.137424 -289.966908)
		(width 0.1143)
		(layer "In11.Cu")
		(net "P5E_CPU1_P3_TX_DP<10>")
	)
	(segment
		(start 122.132598 -285.748476)
		(end 122.131836 -285.748984)
		(width 0.1143)
		(layer "In11.Cu")
		(net "P5E_CPU1_P3_TX_DP<10>")
	)
	(segment
		(start 122.124216 -292.23335)
		(end 122.09272 -292.251638)
		(width 0.1143)
		(layer "In11.Cu")
		(net "P5E_CPU1_P3_TX_DP<10>")
	)
	(segment
		(start 122.131836 -281.8638)
		(end 122.132598 -281.864308)
		(width 0.1143)
		(layer "In11.Cu")
		(net "P5E_CPU1_P3_TX_DP<10>")
	)
	(segment
		(start 123.561856 -299.329602)
		(end 124.871734 -301.28972)
		(width 0.14224)
		(layer "In11.Cu")
		(net "P5E_CPU1_P3_TX_DP<10>")
	)
	(segment
		(start 122.12574 -285.75254)
		(end 122.124216 -285.753556)
		(width 0.1143)
		(layer "In11.Cu")
		(net "P5E_CPU1_P3_TX_DP<10>")
	)
	(segment
		(start 122.127518 -276.031452)
		(end 122.12574 -276.032468)
		(width 0.1143)
		(layer "In11.Cu")
		(net "P5E_CPU1_P3_TX_DP<10>")
	)
	(segment
		(start 122.605292 -295.63568)
		(end 122.606054 -295.636188)
		(width 0.1143)
		(layer "In11.Cu")
		(net "P5E_CPU1_P3_TX_DP<10>")
	)
	(segment
		(start 122.09272 -293.18077)
		(end 122.099578 -293.184834)
		(width 0.1143)
		(layer "In11.Cu")
		(net "P5E_CPU1_P3_TX_DP<10>")
	)
	(segment
		(start 122.09272 -281.84094)
		(end 122.099578 -281.845004)
		(width 0.1143)
		(layer "In11.Cu")
		(net "P5E_CPU1_P3_TX_DP<10>")
	)
	(segment
		(start 122.10034 -281.845512)
		(end 122.131836 -281.8638)
		(width 0.1143)
		(layer "In11.Cu")
		(net "P5E_CPU1_P3_TX_DP<10>")
	)
	(segment
		(start 122.136662 -294.826436)
		(end 122.137424 -294.826944)
		(width 0.1143)
		(layer "In11.Cu")
		(net "P5E_CPU1_P3_TX_DP<10>")
	)
	(segment
		(start 122.14225 -293.209472)
		(end 122.163586 -293.221918)
		(width 0.1143)
		(layer "In11.Cu")
		(net "P5E_CPU1_P3_TX_DP<10>")
	)
	(segment
		(start 122.131836 -289.963606)
		(end 122.132598 -289.964114)
		(width 0.1143)
		(layer "In11.Cu")
		(net "P5E_CPU1_P3_TX_DP<10>")
	)
	(segment
		(start 122.129296 -290.61029)
		(end 122.12828 -290.610798)
		(width 0.1143)
		(layer "In11.Cu")
		(net "P5E_CPU1_P3_TX_DP<10>")
	)
	(segment
		(start 122.136662 -278.62657)
		(end 122.137424 -278.627078)
		(width 0.1143)
		(layer "In11.Cu")
		(net "P5E_CPU1_P3_TX_DP<10>")
	)
	(segment
		(start 122.131836 -278.623776)
		(end 122.132598 -278.624284)
		(width 0.1143)
		(layer "In11.Cu")
		(net "P5E_CPU1_P3_TX_DP<10>")
	)
	(segment
		(start 122.13082 -291.58311)
		(end 122.131836 -291.583618)
		(width 0.1143)
		(layer "In11.Cu")
		(net "P5E_CPU1_P3_TX_DP<10>")
	)
	(segment
		(start 122.10034 -289.945318)
		(end 122.131836 -289.963606)
		(width 0.1143)
		(layer "In11.Cu")
		(net "P5E_CPU1_P3_TX_DP<10>")
	)
	(segment
		(start 122.13971 -281.868372)
		(end 122.14225 -281.869642)
		(width 0.1143)
		(layer "In11.Cu")
		(net "P5E_CPU1_P3_TX_DP<10>")
	)
	(segment
		(start 122.13082 -285.103316)
		(end 122.131836 -285.103824)
		(width 0.1143)
		(layer "In11.Cu")
		(net "P5E_CPU1_P3_TX_DP<10>")
	)
	(segment
		(start 122.137424 -281.867102)
		(end 122.13844 -281.86761)
		(width 0.1143)
		(layer "In11.Cu")
		(net "P5E_CPU1_P3_TX_DP<10>")
	)
	(segment
		(start 122.163586 -290.590478)
		(end 122.132598 -290.608258)
		(width 0.1143)
		(layer "In11.Cu")
		(net "P5E_CPU1_P3_TX_DP<10>")
	)
	(segment
		(start 124.871734 -301.28972)
		(end 131.835398 -309.775352)
		(width 0.14224)
		(layer "In11.Cu")
		(net "P5E_CPU1_P3_TX_DP<10>")
	)
	(segment
		(start 122.12828 -288.990786)
		(end 122.127518 -288.991294)
		(width 0.1143)
		(layer "In11.Cu")
		(net "P5E_CPU1_P3_TX_DP<10>")
	)
	(arc
		(start 122.782584 -274.966176)
		(mid 122.730167 -275.098107)
		(end 122.63247 -275.201126)
		(width 0.1143)
		(layer "In11.Cu")
		(net "P5E_CPU1_P3_TX_DP<10>")
	)
	(arc
		(start 122.163586 -278.642064)
		(mid 122.278262 -278.775398)
		(end 122.319542 -278.946356)
		(width 0.1143)
		(layer "In11.Cu")
		(net "P5E_CPU1_P3_TX_DP<10>")
	)
	(arc
		(start 122.319288 -295.146222)
		(mid 122.383803 -295.408441)
		(end 122.56262 -295.610788)
		(width 0.1143)
		(layer "In11.Cu")
		(net "P5E_CPU1_P3_TX_DP<10>")
	)
	(arc
		(start 122.09272 -285.771844)
		(mid 121.849393 -286.23641)
		(end 122.09272 -286.700976)
		(width 0.1143)
		(layer "In11.Cu")
		(net "P5E_CPU1_P3_TX_DP<10>")
	)
	(arc
		(start 122.09272 -293.87165)
		(mid 121.849393 -294.336216)
		(end 122.09272 -294.800782)
		(width 0.1143)
		(layer "In11.Cu")
		(net "P5E_CPU1_P3_TX_DP<10>")
	)
	(arc
		(start 131.042918 -366.435894)
		(mid 130.985891 -366.463738)
		(end 130.930142 -366.49406)
		(width 0.14224)
		(layer "In11.Cu")
		(net "P5E_CPU1_P3_TX_DP<10>")
	)
	(arc
		(start 122.63247 -279.451562)
		(mid 122.789447 -279.756362)
		(end 122.63247 -280.061162)
		(width 0.1143)
		(layer "In11.Cu")
		(net "P5E_CPU1_P3_TX_DP<10>")
	)
	(arc
		(start 122.163586 -277.022052)
		(mid 122.319514 -277.326344)
		(end 122.163586 -277.630636)
		(width 0.1143)
		(layer "In11.Cu")
		(net "P5E_CPU1_P3_TX_DP<10>")
	)
	(arc
		(start 122.09272 -290.631626)
		(mid 121.849393 -291.096192)
		(end 122.09272 -291.560758)
		(width 0.1143)
		(layer "In11.Cu")
		(net "P5E_CPU1_P3_TX_DP<10>")
	)
	(arc
		(start 122.165364 -288.363406)
		(mid 122.278771 -288.496295)
		(end 122.319542 -288.666174)
		(width 0.1143)
		(layer "In11.Cu")
		(net "P5E_CPU1_P3_TX_DP<10>")
	)
	(arc
		(start 122.633486 -295.651936)
		(mid 122.669328 -295.681215)
		(end 122.701304 -295.714674)
		(width 0.1143)
		(layer "In11.Cu")
		(net "P5E_CPU1_P3_TX_DP<10>")
	)
	(arc
		(start 122.163586 -293.221918)
		(mid 122.319514 -293.52621)
		(end 122.163586 -293.830502)
		(width 0.1143)
		(layer "In11.Cu")
		(net "P5E_CPU1_P3_TX_DP<10>")
	)
	(arc
		(start 131.693666 -365.956088)
		(mid 131.42189 -366.19455)
		(end 131.12115 -366.395254)
		(width 0.14224)
		(layer "In11.Cu")
		(net "P5E_CPU1_P3_TX_DP<10>")
	)
	(arc
		(start 122.163586 -283.5021)
		(mid 122.319514 -283.806392)
		(end 122.163586 -284.110684)
		(width 0.1143)
		(layer "In11.Cu")
		(net "P5E_CPU1_P3_TX_DP<10>")
	)
	(arc
		(start 122.09272 -280.911808)
		(mid 121.849393 -281.376374)
		(end 122.09272 -281.84094)
		(width 0.1143)
		(layer "In11.Cu")
		(net "P5E_CPU1_P3_TX_DP<10>")
	)
	(arc
		(start 122.163586 -281.882088)
		(mid 122.319514 -282.18638)
		(end 122.163586 -282.490672)
		(width 0.1143)
		(layer "In11.Cu")
		(net "P5E_CPU1_P3_TX_DP<10>")
	)
	(arc
		(start 122.319542 -287.046162)
		(mid 122.278287 -287.217133)
		(end 122.163586 -287.350454)
		(width 0.1143)
		(layer "In11.Cu")
		(net "P5E_CPU1_P3_TX_DP<10>")
	)
	(arc
		(start 122.09272 -277.671784)
		(mid 121.849393 -278.13635)
		(end 122.09272 -278.600916)
		(width 0.1143)
		(layer "In11.Cu")
		(net "P5E_CPU1_P3_TX_DP<10>")
	)
	(arc
		(start 122.09272 -276.051772)
		(mid 121.849393 -276.516338)
		(end 122.09272 -276.980904)
		(width 0.1143)
		(layer "In11.Cu")
		(net "P5E_CPU1_P3_TX_DP<10>")
	)
	(arc
		(start 122.562874 -275.241766)
		(mid 122.384061 -275.444116)
		(end 122.319542 -275.706332)
		(width 0.1143)
		(layer "In11.Cu")
		(net "P5E_CPU1_P3_TX_DP<10>")
	)
	(arc
		(start 122.163586 -285.122112)
		(mid 122.319514 -285.426404)
		(end 122.163586 -285.730696)
		(width 0.1143)
		(layer "In11.Cu")
		(net "P5E_CPU1_P3_TX_DP<10>")
	)
	(arc
		(start 142.915132 -346.793312)
		(mid 142.821761 -347.740913)
		(end 142.545308 -348.652084)
		(width 0.14224)
		(layer "In11.Cu")
		(net "P5E_CPU1_P3_TX_DP<10>")
	)
	(arc
		(start 121.849388 -287.856422)
		(mid 121.913903 -288.118641)
		(end 122.09272 -288.320988)
		(width 0.1143)
		(layer "In11.Cu")
		(net "P5E_CPU1_P3_TX_DP<10>")
	)
	(arc
		(start 122.163586 -294.84193)
		(mid 122.278262 -294.975264)
		(end 122.319542 -295.146222)
		(width 0.1143)
		(layer "In11.Cu")
		(net "P5E_CPU1_P3_TX_DP<10>")
	)
	(arc
		(start 131.12115 -366.395254)
		(mid 131.082478 -366.416428)
		(end 131.042918 -366.435894)
		(width 0.14224)
		(layer "In11.Cu")
		(net "P5E_CPU1_P3_TX_DP<10>")
	)
	(arc
		(start 129.125726 -373.605298)
		(mid 129.113449 -373.667021)
		(end 129.078482 -373.719344)
		(width 0.14224)
		(layer "In11.Cu")
		(net "P5E_CPU1_P3_TX_DP<10>")
	)
	(arc
		(start 122.165364 -286.743394)
		(mid 122.278771 -286.876283)
		(end 122.319542 -287.046162)
		(width 0.1143)
		(layer "In11.Cu")
		(net "P5E_CPU1_P3_TX_DP<10>")
	)
	(arc
		(start 122.09272 -284.151832)
		(mid 121.849393 -284.616398)
		(end 122.09272 -285.080964)
		(width 0.1143)
		(layer "In11.Cu")
		(net "P5E_CPU1_P3_TX_DP<10>")
	)
	(arc
		(start 129.13614 -369.172744)
		(mid 129.128233 -369.25436)
		(end 129.125726 -369.33632)
		(width 0.14224)
		(layer "In11.Cu")
		(net "P5E_CPU1_P3_TX_DP<10>")
	)
	(arc
		(start 122.09272 -282.53182)
		(mid 121.849393 -282.996386)
		(end 122.09272 -283.460952)
		(width 0.1143)
		(layer "In11.Cu")
		(net "P5E_CPU1_P3_TX_DP<10>")
	)
	(arc
		(start 122.319542 -275.706332)
		(mid 122.278287 -275.877303)
		(end 122.163586 -276.010624)
		(width 0.1143)
		(layer "In11.Cu")
		(net "P5E_CPU1_P3_TX_DP<10>")
	)
	(arc
		(start 122.09526 -287.390078)
		(mid 121.914608 -287.592823)
		(end 121.849388 -287.856422)
		(width 0.1143)
		(layer "In11.Cu")
		(net "P5E_CPU1_P3_TX_DP<10>")
	)
	(arc
		(start 122.163586 -289.981894)
		(mid 122.319514 -290.286186)
		(end 122.163586 -290.590478)
		(width 0.1143)
		(layer "In11.Cu")
		(net "P5E_CPU1_P3_TX_DP<10>")
	)
	(arc
		(start 122.09272 -292.251638)
		(mid 121.849393 -292.716204)
		(end 122.09272 -293.18077)
		(width 0.1143)
		(layer "In11.Cu")
		(net "P5E_CPU1_P3_TX_DP<10>")
	)
	(arc
		(start 122.319542 -288.666174)
		(mid 122.278287 -288.837145)
		(end 122.163586 -288.970466)
		(width 0.1143)
		(layer "In11.Cu")
		(net "P5E_CPU1_P3_TX_DP<10>")
	)
	(arc
		(start 122.833892 -296.22115)
		(mid 122.865579 -296.302322)
		(end 122.87631 -296.38879)
		(width 0.1143)
		(layer "In11.Cu")
		(net "P5E_CPU1_P3_TX_DP<10>")
	)
	(arc
		(start 122.562874 -280.101802)
		(mid 122.384061 -280.304152)
		(end 122.319542 -280.566368)
		(width 0.1143)
		(layer "In11.Cu")
		(net "P5E_CPU1_P3_TX_DP<10>")
	)
	(arc
		(start 122.79503 -296.067988)
		(mid 122.804926 -296.146989)
		(end 122.833892 -296.22115)
		(width 0.1143)
		(layer "In11.Cu")
		(net "P5E_CPU1_P3_TX_DP<10>")
	)
	(arc
		(start 122.319542 -278.946356)
		(mid 122.384057 -279.208575)
		(end 122.562874 -279.410922)
		(width 0.1143)
		(layer "In11.Cu")
		(net "P5E_CPU1_P3_TX_DP<10>")
	)
	(arc
		(start 130.930142 -366.49406)
		(mid 129.720937 -367.624314)
		(end 129.13614 -369.172744)
		(width 0.14224)
		(layer "In11.Cu")
		(net "P5E_CPU1_P3_TX_DP<10>")
	)
	(arc
		(start 122.09272 -289.011614)
		(mid 121.849393 -289.47618)
		(end 122.09272 -289.940746)
		(width 0.1143)
		(layer "In11.Cu")
		(net "P5E_CPU1_P3_TX_DP<10>")
	)
	(arc
		(start 138.820144 -357.646224)
		(mid 137.804278 -359.546799)
		(end 136.437116 -361.212638)
		(width 0.14224)
		(layer "In11.Cu")
		(net "P5E_CPU1_P3_TX_DP<10>")
	)
	(arc
		(start 122.163586 -291.601906)
		(mid 122.319514 -291.906198)
		(end 122.163586 -292.21049)
		(width 0.1143)
		(layer "In11.Cu")
		(net "P5E_CPU1_P3_TX_DP<10>")
	)
	(arc
		(start 122.765058 -295.790366)
		(mid 122.787306 -295.828735)
		(end 122.79503 -295.872408)
		(width 0.1143)
		(layer "In11.Cu")
		(net "P5E_CPU1_P3_TX_DP<10>")
	)
	(arc
		(start 122.319542 -280.566368)
		(mid 122.278287 -280.737339)
		(end 122.163586 -280.87066)
		(width 0.1143)
		(layer "In11.Cu")
		(net "P5E_CPU1_P3_TX_DP<10>")
	)
	(segment
		(start 108.530644 -382.36906)
		(end 108.801154 -382.09855)
		(width 0.12954)
		(layer "F.Cu")
		(net "P5E_CPU1_P3_TX_DP<0>")
	)
	(segment
		(start 109.504734 -382.09855)
		(end 109.800644 -382.39446)
		(width 0.12954)
		(layer "F.Cu")
		(net "P5E_CPU1_P3_TX_DP<0>")
	)
	(segment
		(start 113.957862 -275.440394)
		(end 114.424714 -275.706332)
		(width 0.12954)
		(layer "F.Cu")
		(net "P5E_CPU1_P3_TX_DP<0>")
	)
	(segment
		(start 108.801154 -382.09855)
		(end 109.504734 -382.09855)
		(width 0.12954)
		(layer "F.Cu")
		(net "P5E_CPU1_P3_TX_DP<0>")
	)
	(segment
		(start 114.424714 -275.706332)
		(end 114.722656 -275.706332)
		(width 0.1143)
		(layer "In11.Cu")
		(net "P5E_CPU1_P3_TX_DP<0>")
	)
	(segment
		(start 106.831384 -377.801378)
		(end 106.831384 -377.813316)
		(width 0.14224)
		(layer "In11.Cu")
		(net "P5E_CPU1_P3_TX_DP<0>")
	)
	(segment
		(start 114.643408 -276.010624)
		(end 114.57305 -276.051518)
		(width 0.1143)
		(layer "In11.Cu")
		(net "P5E_CPU1_P3_TX_DP<0>")
	)
	(segment
		(start 114.722656 -275.706332)
		(end 114.792506 -275.776182)
		(width 0.1143)
		(layer "In11.Cu")
		(net "P5E_CPU1_P3_TX_DP<0>")
	)
	(segment
		(start 106.831384 -377.813316)
		(end 106.828082 -381.209804)
		(width 0.14224)
		(layer "In11.Cu")
		(net "P5E_CPU1_P3_TX_DP<0>")
	)
	(segment
		(start 119.445786 -310.26989)
		(end 127.079502 -319.57137)
		(width 0.14224)
		(layer "In11.Cu")
		(net "P5E_CPU1_P3_TX_DP<0>")
	)
	(segment
		(start 111.995712 -364.570264)
		(end 110.436406 -365.505238)
		(width 0.14224)
		(layer "In11.Cu")
		(net "P5E_CPU1_P3_TX_DP<0>")
	)
	(segment
		(start 106.828082 -381.209804)
		(end 106.849164 -381.230632)
		(width 0.14224)
		(layer "In11.Cu")
		(net "P5E_CPU1_P3_TX_DP<0>")
	)
	(segment
		(start 114.14252 -276.83841)
		(end 114.141758 -276.838918)
		(width 0.1143)
		(layer "In11.Cu")
		(net "P5E_CPU1_P3_TX_DP<0>")
	)
	(segment
		(start 113.154206 -278.075898)
		(end 112.6744 -278.555704)
		(width 0.14224)
		(layer "In11.Cu")
		(net "P5E_CPU1_P3_TX_DP<0>")
	)
	(segment
		(start 112.6744 -278.555704)
		(end 112.6744 -295.71061)
		(width 0.14224)
		(layer "In11.Cu")
		(net "P5E_CPU1_P3_TX_DP<0>")
	)
	(segment
		(start 113.238534 -278.055832)
		(end 113.174272 -278.055832)
		(width 0.1143)
		(layer "In11.Cu")
		(net "P5E_CPU1_P3_TX_DP<0>")
	)
	(segment
		(start 117.980968 -361.46232)
		(end 116.38026 -362.219748)
		(width 0.14224)
		(layer "In11.Cu")
		(net "P5E_CPU1_P3_TX_DP<0>")
	)
	(segment
		(start 112.793018 -296.509948)
		(end 114.907314 -303.477676)
		(width 0.14224)
		(layer "In11.Cu")
		(net "P5E_CPU1_P3_TX_DP<0>")
	)
	(segment
		(start 128.25476 -354.589842)
		(end 121.191528 -359.56494)
		(width 0.14224)
		(layer "In11.Cu")
		(net "P5E_CPU1_P3_TX_DP<0>")
	)
	(segment
		(start 127.079756 -319.57137)
		(end 128.637538 -321.90309)
		(width 0.14224)
		(layer "In11.Cu")
		(net "P5E_CPU1_P3_TX_DP<0>")
	)
	(segment
		(start 114.131344 -276.84476)
		(end 114.130328 -276.845268)
		(width 0.1143)
		(layer "In11.Cu")
		(net "P5E_CPU1_P3_TX_DP<0>")
	)
	(segment
		(start 107.140248 -381.827532)
		(end 107.271058 -381.958342)
		(width 0.14224)
		(layer "In11.Cu")
		(net "P5E_CPU1_P3_TX_DP<0>")
	)
	(segment
		(start 114.132614 -276.844252)
		(end 114.131344 -276.84476)
		(width 0.1143)
		(layer "In11.Cu")
		(net "P5E_CPU1_P3_TX_DP<0>")
	)
	(segment
		(start 114.141758 -276.838918)
		(end 114.140742 -276.839426)
		(width 0.1143)
		(layer "In11.Cu")
		(net "P5E_CPU1_P3_TX_DP<0>")
	)
	(segment
		(start 110.30712 -365.592106)
		(end 109.78515 -365.984028)
		(width 0.14224)
		(layer "In11.Cu")
		(net "P5E_CPU1_P3_TX_DP<0>")
	)
	(segment
		(start 114.134138 -276.843236)
		(end 114.132614 -276.844252)
		(width 0.1143)
		(layer "In11.Cu")
		(net "P5E_CPU1_P3_TX_DP<0>")
	)
	(segment
		(start 114.136932 -276.841712)
		(end 114.135916 -276.84222)
		(width 0.1143)
		(layer "In11.Cu")
		(net "P5E_CPU1_P3_TX_DP<0>")
	)
	(segment
		(start 113.702338 -277.631144)
		(end 113.671858 -277.648924)
		(width 0.1143)
		(layer "In11.Cu")
		(net "P5E_CPU1_P3_TX_DP<0>")
	)
	(segment
		(start 114.139218 -276.840442)
		(end 114.138202 -276.84095)
		(width 0.1143)
		(layer "In11.Cu")
		(net "P5E_CPU1_P3_TX_DP<0>")
	)
	(segment
		(start 114.140742 -276.839426)
		(end 114.139218 -276.840442)
		(width 0.1143)
		(layer "In11.Cu")
		(net "P5E_CPU1_P3_TX_DP<0>")
	)
	(segment
		(start 112.6744 -295.71061)
		(end 112.793018 -296.509948)
		(width 0.14224)
		(layer "In11.Cu")
		(net "P5E_CPU1_P3_TX_DP<0>")
	)
	(segment
		(start 114.138202 -276.84095)
		(end 114.136932 -276.841712)
		(width 0.1143)
		(layer "In11.Cu")
		(net "P5E_CPU1_P3_TX_DP<0>")
	)
	(segment
		(start 113.556288 -277.738078)
		(end 113.238534 -278.055832)
		(width 0.1143)
		(layer "In11.Cu")
		(net "P5E_CPU1_P3_TX_DP<0>")
	)
	(segment
		(start 114.173508 -276.82063)
		(end 114.14252 -276.83841)
		(width 0.1143)
		(layer "In11.Cu")
		(net "P5E_CPU1_P3_TX_DP<0>")
	)
	(segment
		(start 108.845096 -367.0808)
		(end 108.005372 -368.652552)
		(width 0.14224)
		(layer "In11.Cu")
		(net "P5E_CPU1_P3_TX_DP<0>")
	)
	(segment
		(start 133.091936 -344.595958)
		(end 129.70002 -352.784156)
		(width 0.14224)
		(layer "In11.Cu")
		(net "P5E_CPU1_P3_TX_DP<0>")
	)
	(segment
		(start 107.264708 -372.276116)
		(end 106.831384 -377.801378)
		(width 0.14224)
		(layer "In11.Cu")
		(net "P5E_CPU1_P3_TX_DP<0>")
	)
	(segment
		(start 113.174272 -278.055832)
		(end 113.154206 -278.075898)
		(width 0.1143)
		(layer "In11.Cu")
		(net "P5E_CPU1_P3_TX_DP<0>")
	)
	(segment
		(start 107.681776 -369.621562)
		(end 107.264708 -372.276116)
		(width 0.14224)
		(layer "In11.Cu")
		(net "P5E_CPU1_P3_TX_DP<0>")
	)
	(segment
		(start 130.317494 -325.943976)
		(end 133.429502 -341.589106)
		(width 0.14224)
		(layer "In11.Cu")
		(net "P5E_CPU1_P3_TX_DP<0>")
	)
	(segment
		(start 128.697228 -322.014596)
		(end 130.29692 -325.875904)
		(width 0.14224)
		(layer "In11.Cu")
		(net "P5E_CPU1_P3_TX_DP<0>")
	)
	(segment
		(start 127.079502 -319.57137)
		(end 127.079756 -319.57137)
		(width 0.14224)
		(layer "In11.Cu")
		(net "P5E_CPU1_P3_TX_DP<0>")
	)
	(segment
		(start 113.671858 -277.648924)
		(end 113.671604 -277.649178)
		(width 0.1143)
		(layer "In11.Cu")
		(net "P5E_CPU1_P3_TX_DP<0>")
	)
	(segment
		(start 114.329464 -276.513544)
		(end 114.329464 -276.516338)
		(width 0.1143)
		(layer "In11.Cu")
		(net "P5E_CPU1_P3_TX_DP<0>")
	)
	(segment
		(start 116.38026 -362.219494)
		(end 116.380006 -362.219748)
		(width 0.14224)
		(layer "In11.Cu")
		(net "P5E_CPU1_P3_TX_DP<0>")
	)
	(segment
		(start 116.38026 -362.219748)
		(end 116.38026 -362.219494)
		(width 0.14224)
		(layer "In11.Cu")
		(net "P5E_CPU1_P3_TX_DP<0>")
	)
	(segment
		(start 107.560618 -382.07823)
		(end 108.239814 -382.07823)
		(width 0.14224)
		(layer "In11.Cu")
		(net "P5E_CPU1_P3_TX_DP<0>")
	)
	(segment
		(start 114.907314 -303.477676)
		(end 119.445786 -310.26989)
		(width 0.14224)
		(layer "In11.Cu")
		(net "P5E_CPU1_P3_TX_DP<0>")
	)
	(segment
		(start 108.239814 -382.07823)
		(end 108.530644 -382.36906)
		(width 0.14224)
		(layer "In11.Cu")
		(net "P5E_CPU1_P3_TX_DP<0>")
	)
	(segment
		(start 114.135916 -276.84222)
		(end 114.134138 -276.843236)
		(width 0.1143)
		(layer "In11.Cu")
		(net "P5E_CPU1_P3_TX_DP<0>")
	)
	(segment
		(start 133.441948 -341.71509)
		(end 133.441948 -342.837516)
		(width 0.14224)
		(layer "In11.Cu")
		(net "P5E_CPU1_P3_TX_DP<0>")
	)
	(segment
		(start 114.130328 -276.845268)
		(end 114.102642 -276.861778)
		(width 0.1143)
		(layer "In11.Cu")
		(net "P5E_CPU1_P3_TX_DP<0>")
	)
	(segment
		(start 116.192554 -362.313982)
		(end 112.404906 -364.338362)
		(width 0.14224)
		(layer "In11.Cu")
		(net "P5E_CPU1_P3_TX_DP<0>")
	)
	(arc
		(start 106.849164 -381.230632)
		(mid 106.944646 -381.553494)
		(end 107.140248 -381.827532)
		(width 0.14224)
		(layer "In11.Cu")
		(net "P5E_CPU1_P3_TX_DP<0>")
	)
	(arc
		(start 114.792506 -275.776182)
		(mid 114.740457 -275.907701)
		(end 114.643408 -276.010624)
		(width 0.1143)
		(layer "In11.Cu")
		(net "P5E_CPU1_P3_TX_DP<0>")
	)
	(arc
		(start 130.29692 -325.875904)
		(mid 130.308875 -325.909436)
		(end 130.317494 -325.943976)
		(width 0.14224)
		(layer "In11.Cu")
		(net "P5E_CPU1_P3_TX_DP<0>")
	)
	(arc
		(start 114.329464 -276.516338)
		(mid 114.288209 -276.687309)
		(end 114.173508 -276.82063)
		(width 0.1143)
		(layer "In11.Cu")
		(net "P5E_CPU1_P3_TX_DP<0>")
	)
	(arc
		(start 128.637538 -321.90309)
		(mid 128.670133 -321.957372)
		(end 128.697228 -322.014596)
		(width 0.14224)
		(layer "In11.Cu")
		(net "P5E_CPU1_P3_TX_DP<0>")
	)
	(arc
		(start 112.404906 -364.338362)
		(mid 112.198883 -364.451797)
		(end 111.995712 -364.570264)
		(width 0.14224)
		(layer "In11.Cu")
		(net "P5E_CPU1_P3_TX_DP<0>")
	)
	(arc
		(start 113.85931 -277.326344)
		(mid 113.817761 -277.497766)
		(end 113.702338 -277.631144)
		(width 0.1143)
		(layer "In11.Cu")
		(net "P5E_CPU1_P3_TX_DP<0>")
	)
	(arc
		(start 113.671604 -277.649178)
		(mid 113.611063 -277.689888)
		(end 113.556288 -277.738078)
		(width 0.1143)
		(layer "In11.Cu")
		(net "P5E_CPU1_P3_TX_DP<0>")
	)
	(arc
		(start 109.78515 -365.984028)
		(mid 109.255105 -366.480972)
		(end 108.845096 -367.0808)
		(width 0.14224)
		(layer "In11.Cu")
		(net "P5E_CPU1_P3_TX_DP<0>")
	)
	(arc
		(start 129.70002 -352.784156)
		(mid 129.105661 -353.789672)
		(end 128.25476 -354.589842)
		(width 0.14224)
		(layer "In11.Cu")
		(net "P5E_CPU1_P3_TX_DP<0>")
	)
	(arc
		(start 108.005372 -368.652552)
		(mid 107.803115 -369.123544)
		(end 107.681776 -369.621562)
		(width 0.14224)
		(layer "In11.Cu")
		(net "P5E_CPU1_P3_TX_DP<0>")
	)
	(arc
		(start 107.271058 -381.958342)
		(mid 107.403923 -382.047057)
		(end 107.560618 -382.07823)
		(width 0.14224)
		(layer "In11.Cu")
		(net "P5E_CPU1_P3_TX_DP<0>")
	)
	(arc
		(start 116.380006 -362.219748)
		(mid 116.285704 -362.265719)
		(end 116.192554 -362.313982)
		(width 0.14224)
		(layer "In11.Cu")
		(net "P5E_CPU1_P3_TX_DP<0>")
	)
	(arc
		(start 133.429502 -341.589106)
		(mid 133.438817 -341.651792)
		(end 133.441948 -341.71509)
		(width 0.14224)
		(layer "In11.Cu")
		(net "P5E_CPU1_P3_TX_DP<0>")
	)
	(arc
		(start 133.441948 -342.837516)
		(mid 133.353582 -343.733985)
		(end 133.091936 -344.595958)
		(width 0.14224)
		(layer "In11.Cu")
		(net "P5E_CPU1_P3_TX_DP<0>")
	)
	(arc
		(start 110.436406 -365.505238)
		(mid 110.370634 -365.546992)
		(end 110.30712 -365.592106)
		(width 0.14224)
		(layer "In11.Cu")
		(net "P5E_CPU1_P3_TX_DP<0>")
	)
	(arc
		(start 121.191528 -359.56494)
		(mid 119.624135 -360.57774)
		(end 117.980968 -361.46232)
		(width 0.14224)
		(layer "In11.Cu")
		(net "P5E_CPU1_P3_TX_DP<0>")
	)
	(arc
		(start 114.57305 -276.051518)
		(mid 114.39412 -276.252402)
		(end 114.329464 -276.513544)
		(width 0.1143)
		(layer "In11.Cu")
		(net "P5E_CPU1_P3_TX_DP<0>")
	)
	(arc
		(start 114.102642 -276.861778)
		(mid 113.923829 -277.064128)
		(end 113.85931 -277.326344)
		(width 0.1143)
		(layer "In11.Cu")
		(net "P5E_CPU1_P3_TX_DP<0>")
	)
	(segment
		(start 126.294896 -369.03533)
		(end 126.024386 -369.30584)
		(width 0.12954)
		(layer "F.Cu")
		(net "P5E_CPU1_P3_TX_DN<9>")
	)
	(segment
		(start 126.024386 -370.00942)
		(end 126.320296 -370.30533)
		(width 0.12954)
		(layer "F.Cu")
		(net "P5E_CPU1_P3_TX_DN<9>")
	)
	(segment
		(start 126.024386 -369.30584)
		(end 126.024386 -370.00942)
		(width 0.12954)
		(layer "F.Cu")
		(net "P5E_CPU1_P3_TX_DN<9>")
	)
	(segment
		(start 120.067832 -276.2504)
		(end 120.534684 -276.516338)
		(width 0.12954)
		(layer "F.Cu")
		(net "P5E_CPU1_P3_TX_DN<9>")
	)
	(segment
		(start 121.756932 -280.244296)
		(end 121.755662 -280.245058)
		(width 0.1143)
		(layer "In11.Cu")
		(net "P5E_CPU1_P3_TX_DN<9>")
	)
	(segment
		(start 121.25706 -284.921198)
		(end 121.28754 -284.938978)
		(width 0.1143)
		(layer "In11.Cu")
		(net "P5E_CPU1_P3_TX_DN<9>")
	)
	(segment
		(start 121.727468 -295.451276)
		(end 121.79681 -295.491662)
		(width 0.1143)
		(layer "In11.Cu")
		(net "P5E_CPU1_P3_TX_DN<9>")
	)
	(segment
		(start 120.236742 -276.516338)
		(end 120.166892 -276.586188)
		(width 0.1143)
		(layer "In11.Cu")
		(net "P5E_CPU1_P3_TX_DN<9>")
	)
	(segment
		(start 121.28754 -288.178748)
		(end 121.326656 -288.201608)
		(width 0.1143)
		(layer "In11.Cu")
		(net "P5E_CPU1_P3_TX_DN<9>")
	)
	(segment
		(start 120.346978 -276.83841)
		(end 120.34774 -276.838918)
		(width 0.1143)
		(layer "In11.Cu")
		(net "P5E_CPU1_P3_TX_DN<9>")
	)
	(segment
		(start 130.529076 -365.91621)
		(end 126.748794 -367.481866)
		(width 0.14224)
		(layer "In11.Cu")
		(net "P5E_CPU1_P3_TX_DN<9>")
	)
	(segment
		(start 121.255028 -286.53994)
		(end 121.28754 -286.558736)
		(width 0.1143)
		(layer "In11.Cu")
		(net "P5E_CPU1_P3_TX_DN<9>")
	)
	(segment
		(start 121.28754 -284.938978)
		(end 121.326656 -284.961838)
		(width 0.1143)
		(layer "In11.Cu")
		(net "P5E_CPU1_P3_TX_DN<9>")
	)
	(segment
		(start 121.25706 -278.44115)
		(end 121.28754 -278.45893)
		(width 0.1143)
		(layer "In11.Cu")
		(net "P5E_CPU1_P3_TX_DN<9>")
	)
	(segment
		(start 121.28754 -293.038784)
		(end 121.326656 -293.061644)
		(width 0.1143)
		(layer "In11.Cu")
		(net "P5E_CPU1_P3_TX_DN<9>")
	)
	(segment
		(start 120.34774 -276.838918)
		(end 120.351042 -276.84095)
		(width 0.1143)
		(layer "In11.Cu")
		(net "P5E_CPU1_P3_TX_DN<9>")
	)
	(segment
		(start 121.28754 -284.293818)
		(end 121.25706 -284.311598)
		(width 0.1143)
		(layer "In11.Cu")
		(net "P5E_CPU1_P3_TX_DN<9>")
	)
	(segment
		(start 121.28754 -281.698954)
		(end 121.326656 -281.721814)
		(width 0.1143)
		(layer "In11.Cu")
		(net "P5E_CPU1_P3_TX_DN<9>")
	)
	(segment
		(start 121.28754 -294.658796)
		(end 121.326656 -294.681656)
		(width 0.1143)
		(layer "In11.Cu")
		(net "P5E_CPU1_P3_TX_DN<9>")
	)
	(segment
		(start 120.31599 -276.82063)
		(end 120.346978 -276.83841)
		(width 0.1143)
		(layer "In11.Cu")
		(net "P5E_CPU1_P3_TX_DN<9>")
	)
	(segment
		(start 121.28754 -290.773612)
		(end 121.25706 -290.791392)
		(width 0.1143)
		(layer "In11.Cu")
		(net "P5E_CPU1_P3_TX_DN<9>")
	)
	(segment
		(start 121.28754 -282.673806)
		(end 121.25706 -282.691586)
		(width 0.1143)
		(layer "In11.Cu")
		(net "P5E_CPU1_P3_TX_DN<9>")
	)
	(segment
		(start 121.28754 -292.393624)
		(end 121.25706 -292.411404)
		(width 0.1143)
		(layer "In11.Cu")
		(net "P5E_CPU1_P3_TX_DN<9>")
	)
	(segment
		(start 121.757694 -280.243788)
		(end 121.756932 -280.244296)
		(width 0.1143)
		(layer "In11.Cu")
		(net "P5E_CPU1_P3_TX_DN<9>")
	)
	(segment
		(start 122.03938 -295.935654)
		(end 122.048778 -295.983152)
		(width 0.1143)
		(layer "In11.Cu")
		(net "P5E_CPU1_P3_TX_DN<9>")
	)
	(segment
		(start 121.28754 -283.318966)
		(end 121.326656 -283.341826)
		(width 0.1143)
		(layer "In11.Cu")
		(net "P5E_CPU1_P3_TX_DN<9>")
	)
	(segment
		(start 121.755662 -280.245058)
		(end 121.725944 -280.262076)
		(width 0.1143)
		(layer "In11.Cu")
		(net "P5E_CPU1_P3_TX_DN<9>")
	)
	(segment
		(start 121.28754 -289.79876)
		(end 121.326656 -289.82162)
		(width 0.1143)
		(layer "In11.Cu")
		(net "P5E_CPU1_P3_TX_DN<9>")
	)
	(segment
		(start 121.326656 -284.270958)
		(end 121.28754 -284.293818)
		(width 0.1143)
		(layer "In11.Cu")
		(net "P5E_CPU1_P3_TX_DN<9>")
	)
	(segment
		(start 121.28754 -291.418772)
		(end 121.326656 -291.441632)
		(width 0.1143)
		(layer "In11.Cu")
		(net "P5E_CPU1_P3_TX_DN<9>")
	)
	(segment
		(start 142.263876 -340.609174)
		(end 142.263876 -345.830906)
		(width 0.14224)
		(layer "In11.Cu")
		(net "P5E_CPU1_P3_TX_DN<9>")
	)
	(segment
		(start 121.326656 -289.13074)
		(end 121.28754 -289.1536)
		(width 0.1143)
		(layer "In11.Cu")
		(net "P5E_CPU1_P3_TX_DN<9>")
	)
	(segment
		(start 137.030206 -318.80429)
		(end 138.754612 -322.966334)
		(width 0.14224)
		(layer "In11.Cu")
		(net "P5E_CPU1_P3_TX_DN<9>")
	)
	(segment
		(start 121.326656 -281.030934)
		(end 121.28754 -281.053794)
		(width 0.1143)
		(layer "In11.Cu")
		(net "P5E_CPU1_P3_TX_DN<9>")
	)
	(segment
		(start 122.122184 -296.538396)
		(end 122.167904 -296.584116)
		(width 0.1143)
		(layer "In11.Cu")
		(net "P5E_CPU1_P3_TX_DN<9>")
	)
	(segment
		(start 121.25706 -293.021004)
		(end 121.28754 -293.038784)
		(width 0.1143)
		(layer "In11.Cu")
		(net "P5E_CPU1_P3_TX_DN<9>")
	)
	(segment
		(start 141.66723 -348.830138)
		(end 138.501882 -356.472744)
		(width 0.14224)
		(layer "In11.Cu")
		(net "P5E_CPU1_P3_TX_DN<9>")
	)
	(segment
		(start 121.28754 -294.013636)
		(end 121.25706 -294.031416)
		(width 0.1143)
		(layer "In11.Cu")
		(net "P5E_CPU1_P3_TX_DN<9>")
	)
	(segment
		(start 126.004066 -368.140996)
		(end 126.004066 -368.7445)
		(width 0.14224)
		(layer "In11.Cu")
		(net "P5E_CPU1_P3_TX_DN<9>")
	)
	(segment
		(start 131.57073 -310.633872)
		(end 137.030206 -318.80429)
		(width 0.14224)
		(layer "In11.Cu")
		(net "P5E_CPU1_P3_TX_DN<9>")
	)
	(segment
		(start 121.25706 -281.681174)
		(end 121.28754 -281.698954)
		(width 0.1143)
		(layer "In11.Cu")
		(net "P5E_CPU1_P3_TX_DN<9>")
	)
	(segment
		(start 121.760234 -279.27046)
		(end 121.76125 -279.270968)
		(width 0.1143)
		(layer "In11.Cu")
		(net "P5E_CPU1_P3_TX_DN<9>")
	)
	(segment
		(start 121.28754 -289.1536)
		(end 121.25706 -289.17138)
		(width 0.1143)
		(layer "In11.Cu")
		(net "P5E_CPU1_P3_TX_DN<9>")
	)
	(segment
		(start 120.783096 -277.628604)
		(end 120.78589 -277.630636)
		(width 0.1143)
		(layer "In11.Cu")
		(net "P5E_CPU1_P3_TX_DN<9>")
	)
	(segment
		(start 121.326656 -290.750752)
		(end 121.28754 -290.773612)
		(width 0.1143)
		(layer "In11.Cu")
		(net "P5E_CPU1_P3_TX_DN<9>")
	)
	(segment
		(start 121.25706 -294.641016)
		(end 121.28754 -294.658796)
		(width 0.1143)
		(layer "In11.Cu")
		(net "P5E_CPU1_P3_TX_DN<9>")
	)
	(segment
		(start 121.79681 -280.220928)
		(end 121.757694 -280.243788)
		(width 0.1143)
		(layer "In11.Cu")
		(net "P5E_CPU1_P3_TX_DN<9>")
	)
	(segment
		(start 122.122184 -296.396918)
		(end 122.122184 -296.538396)
		(width 0.1143)
		(layer "In11.Cu")
		(net "P5E_CPU1_P3_TX_DN<9>")
	)
	(segment
		(start 121.326656 -282.650946)
		(end 121.28754 -282.673806)
		(width 0.1143)
		(layer "In11.Cu")
		(net "P5E_CPU1_P3_TX_DN<9>")
	)
	(segment
		(start 122.167904 -296.980356)
		(end 122.98045 -299.658278)
		(width 0.14224)
		(layer "In11.Cu")
		(net "P5E_CPU1_P3_TX_DN<9>")
	)
	(segment
		(start 135.15848 -361.476544)
		(end 131.100576 -365.534448)
		(width 0.14224)
		(layer "In11.Cu")
		(net "P5E_CPU1_P3_TX_DN<9>")
	)
	(segment
		(start 121.255028 -288.159952)
		(end 121.28754 -288.178748)
		(width 0.1143)
		(layer "In11.Cu")
		(net "P5E_CPU1_P3_TX_DN<9>")
	)
	(segment
		(start 121.756932 -279.268428)
		(end 121.757694 -279.268936)
		(width 0.1143)
		(layer "In11.Cu")
		(net "P5E_CPU1_P3_TX_DN<9>")
	)
	(segment
		(start 122.98045 -299.658278)
		(end 124.806456 -302.391318)
		(width 0.14224)
		(layer "In11.Cu")
		(net "P5E_CPU1_P3_TX_DN<9>")
	)
	(segment
		(start 120.629934 -277.326344)
		(end 120.629934 -277.329392)
		(width 0.1143)
		(layer "In11.Cu")
		(net "P5E_CPU1_P3_TX_DN<9>")
	)
	(segment
		(start 121.75871 -279.269444)
		(end 121.760234 -279.27046)
		(width 0.1143)
		(layer "In11.Cu")
		(net "P5E_CPU1_P3_TX_DN<9>")
	)
	(segment
		(start 121.28754 -278.45893)
		(end 121.326656 -278.48179)
		(width 0.1143)
		(layer "In11.Cu")
		(net "P5E_CPU1_P3_TX_DN<9>")
	)
	(segment
		(start 121.76125 -279.270968)
		(end 121.79681 -279.291796)
		(width 0.1143)
		(layer "In11.Cu")
		(net "P5E_CPU1_P3_TX_DN<9>")
	)
	(segment
		(start 121.25706 -289.78098)
		(end 121.28754 -289.79876)
		(width 0.1143)
		(layer "In11.Cu")
		(net "P5E_CPU1_P3_TX_DN<9>")
	)
	(segment
		(start 121.326656 -285.89097)
		(end 121.28754 -285.91383)
		(width 0.1143)
		(layer "In11.Cu")
		(net "P5E_CPU1_P3_TX_DN<9>")
	)
	(segment
		(start 120.78589 -277.630636)
		(end 120.856756 -277.671784)
		(width 0.1143)
		(layer "In11.Cu")
		(net "P5E_CPU1_P3_TX_DN<9>")
	)
	(segment
		(start 126.150624 -367.881408)
		(end 126.084076 -367.947956)
		(width 0.14224)
		(layer "In11.Cu")
		(net "P5E_CPU1_P3_TX_DN<9>")
	)
	(segment
		(start 121.757694 -279.268936)
		(end 121.75871 -279.269444)
		(width 0.1143)
		(layer "In11.Cu")
		(net "P5E_CPU1_P3_TX_DN<9>")
	)
	(segment
		(start 126.004066 -368.7445)
		(end 126.294896 -369.03533)
		(width 0.14224)
		(layer "In11.Cu")
		(net "P5E_CPU1_P3_TX_DN<9>")
	)
	(segment
		(start 121.28754 -285.91383)
		(end 121.25706 -285.93161)
		(width 0.1143)
		(layer "In11.Cu")
		(net "P5E_CPU1_P3_TX_DN<9>")
	)
	(segment
		(start 124.806456 -302.391318)
		(end 131.57073 -310.633872)
		(width 0.14224)
		(layer "In11.Cu")
		(net "P5E_CPU1_P3_TX_DN<9>")
	)
	(segment
		(start 120.534684 -276.516338)
		(end 120.236742 -276.516338)
		(width 0.1143)
		(layer "In11.Cu")
		(net "P5E_CPU1_P3_TX_DN<9>")
	)
	(segment
		(start 120.351042 -276.84095)
		(end 120.384062 -276.86)
		(width 0.1143)
		(layer "In11.Cu")
		(net "P5E_CPU1_P3_TX_DN<9>")
	)
	(segment
		(start 122.167904 -296.612564)
		(end 122.167904 -296.980356)
		(width 0.14224)
		(layer "In11.Cu")
		(net "P5E_CPU1_P3_TX_DN<9>")
	)
	(segment
		(start 121.725944 -279.250648)
		(end 121.756932 -279.268428)
		(width 0.1143)
		(layer "In11.Cu")
		(net "P5E_CPU1_P3_TX_DN<9>")
	)
	(segment
		(start 122.048778 -295.983152)
		(end 122.122184 -296.396918)
		(width 0.1143)
		(layer "In11.Cu")
		(net "P5E_CPU1_P3_TX_DN<9>")
	)
	(segment
		(start 121.326656 -293.990776)
		(end 121.28754 -294.013636)
		(width 0.1143)
		(layer "In11.Cu")
		(net "P5E_CPU1_P3_TX_DN<9>")
	)
	(segment
		(start 122.167904 -296.584116)
		(end 122.167904 -296.612564)
		(width 0.1143)
		(layer "In11.Cu")
		(net "P5E_CPU1_P3_TX_DN<9>")
	)
	(segment
		(start 121.25706 -283.301186)
		(end 121.28754 -283.318966)
		(width 0.1143)
		(layer "In11.Cu")
		(net "P5E_CPU1_P3_TX_DN<9>")
	)
	(segment
		(start 121.326656 -292.370764)
		(end 121.28754 -292.393624)
		(width 0.1143)
		(layer "In11.Cu")
		(net "P5E_CPU1_P3_TX_DN<9>")
	)
	(segment
		(start 121.28754 -281.053794)
		(end 121.25706 -281.071574)
		(width 0.1143)
		(layer "In11.Cu")
		(net "P5E_CPU1_P3_TX_DN<9>")
	)
	(segment
		(start 138.754612 -322.966334)
		(end 142.263876 -340.609174)
		(width 0.14224)
		(layer "In11.Cu")
		(net "P5E_CPU1_P3_TX_DN<9>")
	)
	(segment
		(start 121.25706 -291.400992)
		(end 121.28754 -291.418772)
		(width 0.1143)
		(layer "In11.Cu")
		(net "P5E_CPU1_P3_TX_DN<9>")
	)
	(segment
		(start 121.324116 -287.512506)
		(end 121.25706 -287.551622)
		(width 0.1143)
		(layer "In11.Cu")
		(net "P5E_CPU1_P3_TX_DN<9>")
	)
	(segment
		(start 121.28754 -286.558736)
		(end 121.326656 -286.581596)
		(width 0.1143)
		(layer "In11.Cu")
		(net "P5E_CPU1_P3_TX_DN<9>")
	)
	(arc
		(start 121.25706 -287.551622)
		(mid 121.141633 -287.684998)
		(end 121.100088 -287.856422)
		(width 0.1143)
		(layer "In11.Cu")
		(net "P5E_CPU1_P3_TX_DN<9>")
	)
	(arc
		(start 138.501882 -356.472744)
		(mid 137.076597 -359.139292)
		(end 135.15848 -361.476544)
		(width 0.14224)
		(layer "In11.Cu")
		(net "P5E_CPU1_P3_TX_DN<9>")
	)
	(arc
		(start 121.100088 -286.23641)
		(mid 121.141054 -286.406816)
		(end 121.255028 -286.53994)
		(width 0.1143)
		(layer "In11.Cu")
		(net "P5E_CPU1_P3_TX_DN<9>")
	)
	(arc
		(start 126.748794 -367.481866)
		(mid 126.430022 -367.652166)
		(end 126.150624 -367.881408)
		(width 0.14224)
		(layer "In11.Cu")
		(net "P5E_CPU1_P3_TX_DN<9>")
	)
	(arc
		(start 121.326656 -294.681656)
		(mid 121.505469 -294.884006)
		(end 121.569988 -295.146222)
		(width 0.1143)
		(layer "In11.Cu")
		(net "P5E_CPU1_P3_TX_DN<9>")
	)
	(arc
		(start 121.326656 -278.48179)
		(mid 121.505469 -278.68414)
		(end 121.569988 -278.946356)
		(width 0.1143)
		(layer "In11.Cu")
		(net "P5E_CPU1_P3_TX_DN<9>")
	)
	(arc
		(start 121.911872 -295.598088)
		(mid 121.91289 -295.599357)
		(end 121.913904 -295.600628)
		(width 0.1143)
		(layer "In11.Cu")
		(net "P5E_CPU1_P3_TX_DN<9>")
	)
	(arc
		(start 121.326656 -286.581596)
		(mid 121.505469 -286.783946)
		(end 121.569988 -287.046162)
		(width 0.1143)
		(layer "In11.Cu")
		(net "P5E_CPU1_P3_TX_DN<9>")
	)
	(arc
		(start 121.326656 -291.441632)
		(mid 121.569983 -291.906198)
		(end 121.326656 -292.370764)
		(width 0.1143)
		(layer "In11.Cu")
		(net "P5E_CPU1_P3_TX_DN<9>")
	)
	(arc
		(start 120.384062 -276.86)
		(mid 120.564714 -277.062745)
		(end 120.629934 -277.326344)
		(width 0.1143)
		(layer "In11.Cu")
		(net "P5E_CPU1_P3_TX_DN<9>")
	)
	(arc
		(start 121.79681 -295.491662)
		(mid 121.858061 -295.540855)
		(end 121.911872 -295.598088)
		(width 0.1143)
		(layer "In11.Cu")
		(net "P5E_CPU1_P3_TX_DN<9>")
	)
	(arc
		(start 121.326656 -284.961838)
		(mid 121.569983 -285.426404)
		(end 121.326656 -285.89097)
		(width 0.1143)
		(layer "In11.Cu")
		(net "P5E_CPU1_P3_TX_DN<9>")
	)
	(arc
		(start 121.326656 -293.061644)
		(mid 121.569983 -293.52621)
		(end 121.326656 -293.990776)
		(width 0.1143)
		(layer "In11.Cu")
		(net "P5E_CPU1_P3_TX_DN<9>")
	)
	(arc
		(start 121.25706 -282.691586)
		(mid 121.100083 -282.996386)
		(end 121.25706 -283.301186)
		(width 0.1143)
		(layer "In11.Cu")
		(net "P5E_CPU1_P3_TX_DN<9>")
	)
	(arc
		(start 121.25706 -285.93161)
		(mid 121.141633 -286.064986)
		(end 121.100088 -286.23641)
		(width 0.1143)
		(layer "In11.Cu")
		(net "P5E_CPU1_P3_TX_DN<9>")
	)
	(arc
		(start 142.263876 -345.830906)
		(mid 142.113239 -347.359901)
		(end 141.66723 -348.830138)
		(width 0.14224)
		(layer "In11.Cu")
		(net "P5E_CPU1_P3_TX_DN<9>")
	)
	(arc
		(start 121.326656 -288.201608)
		(mid 121.569983 -288.666174)
		(end 121.326656 -289.13074)
		(width 0.1143)
		(layer "In11.Cu")
		(net "P5E_CPU1_P3_TX_DN<9>")
	)
	(arc
		(start 121.725944 -280.262076)
		(mid 121.611268 -280.39541)
		(end 121.569988 -280.566368)
		(width 0.1143)
		(layer "In11.Cu")
		(net "P5E_CPU1_P3_TX_DN<9>")
	)
	(arc
		(start 121.326656 -283.341826)
		(mid 121.569983 -283.806392)
		(end 121.326656 -284.270958)
		(width 0.1143)
		(layer "In11.Cu")
		(net "P5E_CPU1_P3_TX_DN<9>")
	)
	(arc
		(start 121.569988 -287.046162)
		(mid 121.504752 -287.309753)
		(end 121.324116 -287.512506)
		(width 0.1143)
		(layer "In11.Cu")
		(net "P5E_CPU1_P3_TX_DN<9>")
	)
	(arc
		(start 121.25706 -289.17138)
		(mid 121.100083 -289.47618)
		(end 121.25706 -289.78098)
		(width 0.1143)
		(layer "In11.Cu")
		(net "P5E_CPU1_P3_TX_DN<9>")
	)
	(arc
		(start 121.569988 -280.566368)
		(mid 121.505473 -280.828587)
		(end 121.326656 -281.030934)
		(width 0.1143)
		(layer "In11.Cu")
		(net "P5E_CPU1_P3_TX_DN<9>")
	)
	(arc
		(start 120.629934 -277.329392)
		(mid 120.67038 -277.497507)
		(end 120.783096 -277.628604)
		(width 0.1143)
		(layer "In11.Cu")
		(net "P5E_CPU1_P3_TX_DN<9>")
	)
	(arc
		(start 121.100088 -278.13635)
		(mid 121.141637 -278.307772)
		(end 121.25706 -278.44115)
		(width 0.1143)
		(layer "In11.Cu")
		(net "P5E_CPU1_P3_TX_DN<9>")
	)
	(arc
		(start 131.100576 -365.534448)
		(mid 130.833649 -365.753508)
		(end 130.529076 -365.91621)
		(width 0.14224)
		(layer "In11.Cu")
		(net "P5E_CPU1_P3_TX_DN<9>")
	)
	(arc
		(start 121.79681 -279.291796)
		(mid 122.040137 -279.756362)
		(end 121.79681 -280.220928)
		(width 0.1143)
		(layer "In11.Cu")
		(net "P5E_CPU1_P3_TX_DN<9>")
	)
	(arc
		(start 121.25706 -281.071574)
		(mid 121.100083 -281.376374)
		(end 121.25706 -281.681174)
		(width 0.1143)
		(layer "In11.Cu")
		(net "P5E_CPU1_P3_TX_DN<9>")
	)
	(arc
		(start 121.25706 -290.791392)
		(mid 121.100083 -291.096192)
		(end 121.25706 -291.400992)
		(width 0.1143)
		(layer "In11.Cu")
		(net "P5E_CPU1_P3_TX_DN<9>")
	)
	(arc
		(start 121.569988 -278.946356)
		(mid 121.611243 -279.117327)
		(end 121.725944 -279.250648)
		(width 0.1143)
		(layer "In11.Cu")
		(net "P5E_CPU1_P3_TX_DN<9>")
	)
	(arc
		(start 121.913904 -295.600628)
		(mid 122.001608 -295.758788)
		(end 122.03938 -295.935654)
		(width 0.1143)
		(layer "In11.Cu")
		(net "P5E_CPU1_P3_TX_DN<9>")
	)
	(arc
		(start 121.100088 -287.856422)
		(mid 121.141054 -288.026828)
		(end 121.255028 -288.159952)
		(width 0.1143)
		(layer "In11.Cu")
		(net "P5E_CPU1_P3_TX_DN<9>")
	)
	(arc
		(start 121.326656 -281.721814)
		(mid 121.569983 -282.18638)
		(end 121.326656 -282.650946)
		(width 0.1143)
		(layer "In11.Cu")
		(net "P5E_CPU1_P3_TX_DN<9>")
	)
	(arc
		(start 120.166892 -276.586188)
		(mid 120.218941 -276.717707)
		(end 120.31599 -276.82063)
		(width 0.1143)
		(layer "In11.Cu")
		(net "P5E_CPU1_P3_TX_DN<9>")
	)
	(arc
		(start 126.084076 -367.947956)
		(mid 126.024843 -368.036509)
		(end 126.004066 -368.140996)
		(width 0.14224)
		(layer "In11.Cu")
		(net "P5E_CPU1_P3_TX_DN<9>")
	)
	(arc
		(start 121.25706 -292.411404)
		(mid 121.100083 -292.716204)
		(end 121.25706 -293.021004)
		(width 0.1143)
		(layer "In11.Cu")
		(net "P5E_CPU1_P3_TX_DN<9>")
	)
	(arc
		(start 121.326656 -289.82162)
		(mid 121.569983 -290.286186)
		(end 121.326656 -290.750752)
		(width 0.1143)
		(layer "In11.Cu")
		(net "P5E_CPU1_P3_TX_DN<9>")
	)
	(arc
		(start 120.856756 -277.671784)
		(mid 121.035569 -277.874134)
		(end 121.100088 -278.13635)
		(width 0.1143)
		(layer "In11.Cu")
		(net "P5E_CPU1_P3_TX_DN<9>")
	)
	(arc
		(start 121.569988 -295.146222)
		(mid 121.611739 -295.317842)
		(end 121.727468 -295.451276)
		(width 0.1143)
		(layer "In11.Cu")
		(net "P5E_CPU1_P3_TX_DN<9>")
	)
	(arc
		(start 121.25706 -294.031416)
		(mid 121.100083 -294.336216)
		(end 121.25706 -294.641016)
		(width 0.1143)
		(layer "In11.Cu")
		(net "P5E_CPU1_P3_TX_DN<9>")
	)
	(arc
		(start 121.25706 -284.311598)
		(mid 121.100083 -284.616398)
		(end 121.25706 -284.921198)
		(width 0.1143)
		(layer "In11.Cu")
		(net "P5E_CPU1_P3_TX_DN<9>")
	)
	(segment
		(start 124.593096 -371.49913)
		(end 124.322586 -371.76964)
		(width 0.12954)
		(layer "F.Cu")
		(net "P5E_CPU1_P3_TX_DN<8>")
	)
	(segment
		(start 124.322586 -371.76964)
		(end 124.322586 -372.47322)
		(width 0.12954)
		(layer "F.Cu")
		(net "P5E_CPU1_P3_TX_DN<8>")
	)
	(segment
		(start 124.322586 -372.47322)
		(end 124.618496 -372.76913)
		(width 0.12954)
		(layer "F.Cu")
		(net "P5E_CPU1_P3_TX_DN<8>")
	)
	(segment
		(start 120.067832 -277.870412)
		(end 120.534684 -278.13635)
		(width 0.12954)
		(layer "F.Cu")
		(net "P5E_CPU1_P3_TX_DN<8>")
	)
	(segment
		(start 124.302266 -371.2083)
		(end 124.593096 -371.49913)
		(width 0.14224)
		(layer "In11.Cu")
		(net "P5E_CPU1_P3_TX_DN<8>")
	)
	(segment
		(start 120.804686 -280.251154)
		(end 120.804432 -280.251408)
		(width 0.1143)
		(layer "In11.Cu")
		(net "P5E_CPU1_P3_TX_DN<8>")
	)
	(segment
		(start 120.31599 -289.780472)
		(end 120.34774 -289.79876)
		(width 0.1143)
		(layer "In11.Cu")
		(net "P5E_CPU1_P3_TX_DN<8>")
	)
	(segment
		(start 120.34774 -283.318966)
		(end 120.350788 -283.320744)
		(width 0.1143)
		(layer "In11.Cu")
		(net "P5E_CPU1_P3_TX_DN<8>")
	)
	(segment
		(start 121.099834 -295.93921)
		(end 121.10212 -296.013886)
		(width 0.1143)
		(layer "In11.Cu")
		(net "P5E_CPU1_P3_TX_DN<8>")
	)
	(segment
		(start 121.22277 -297.080686)
		(end 122.142758 -300.113446)
		(width 0.14224)
		(layer "In11.Cu")
		(net "P5E_CPU1_P3_TX_DN<8>")
	)
	(segment
		(start 120.629934 -295.141904)
		(end 120.629934 -295.146222)
		(width 0.1143)
		(layer "In11.Cu")
		(net "P5E_CPU1_P3_TX_DN<8>")
	)
	(segment
		(start 136.14908 -319.183766)
		(end 137.885678 -323.377052)
		(width 0.14224)
		(layer "In11.Cu")
		(net "P5E_CPU1_P3_TX_DN<8>")
	)
	(segment
		(start 120.629934 -295.146222)
		(end 120.630188 -295.146222)
		(width 0.1143)
		(layer "In11.Cu")
		(net "P5E_CPU1_P3_TX_DN<8>")
	)
	(segment
		(start 121.222262 -296.584116)
		(end 121.222262 -296.612564)
		(width 0.1143)
		(layer "In11.Cu")
		(net "P5E_CPU1_P3_TX_DN<8>")
	)
	(segment
		(start 120.31599 -284.92069)
		(end 120.34774 -284.938978)
		(width 0.1143)
		(layer "In11.Cu")
		(net "P5E_CPU1_P3_TX_DN<8>")
	)
	(segment
		(start 120.31599 -291.400484)
		(end 120.34774 -291.418772)
		(width 0.1143)
		(layer "In11.Cu")
		(net "P5E_CPU1_P3_TX_DN<8>")
	)
	(segment
		(start 120.314212 -286.539178)
		(end 120.388888 -286.58312)
		(width 0.1143)
		(layer "In11.Cu")
		(net "P5E_CPU1_P3_TX_DN<8>")
	)
	(segment
		(start 120.31599 -294.640508)
		(end 120.34774 -294.658796)
		(width 0.1143)
		(layer "In11.Cu")
		(net "P5E_CPU1_P3_TX_DN<8>")
	)
	(segment
		(start 120.314974 -288.159698)
		(end 120.34774 -288.178748)
		(width 0.1143)
		(layer "In11.Cu")
		(net "P5E_CPU1_P3_TX_DN<8>")
	)
	(segment
		(start 120.314212 -288.15919)
		(end 120.314974 -288.159698)
		(width 0.1143)
		(layer "In11.Cu")
		(net "P5E_CPU1_P3_TX_DN<8>")
	)
	(segment
		(start 120.346978 -278.458422)
		(end 120.34774 -278.45893)
		(width 0.1143)
		(layer "In11.Cu")
		(net "P5E_CPU1_P3_TX_DN<8>")
	)
	(segment
		(start 120.346978 -283.318458)
		(end 120.34774 -283.318966)
		(width 0.1143)
		(layer "In11.Cu")
		(net "P5E_CPU1_P3_TX_DN<8>")
	)
	(segment
		(start 120.31599 -278.440642)
		(end 120.346978 -278.458422)
		(width 0.1143)
		(layer "In11.Cu")
		(net "P5E_CPU1_P3_TX_DN<8>")
	)
	(segment
		(start 120.350788 -289.151822)
		(end 120.31599 -289.171888)
		(width 0.1143)
		(layer "In11.Cu")
		(net "P5E_CPU1_P3_TX_DN<8>")
	)
	(segment
		(start 120.34774 -278.45893)
		(end 120.348756 -278.459438)
		(width 0.1143)
		(layer "In11.Cu")
		(net "P5E_CPU1_P3_TX_DN<8>")
	)
	(segment
		(start 125.484382 -367.182654)
		(end 124.577602 -368.089434)
		(width 0.14224)
		(layer "In11.Cu")
		(net "P5E_CPU1_P3_TX_DN<8>")
	)
	(segment
		(start 120.31599 -283.300678)
		(end 120.346978 -283.318458)
		(width 0.1143)
		(layer "In11.Cu")
		(net "P5E_CPU1_P3_TX_DN<8>")
	)
	(segment
		(start 120.236742 -278.13635)
		(end 120.166892 -278.2062)
		(width 0.1143)
		(layer "In11.Cu")
		(net "P5E_CPU1_P3_TX_DN<8>")
	)
	(segment
		(start 120.350788 -282.672028)
		(end 120.31599 -282.692094)
		(width 0.1143)
		(layer "In11.Cu")
		(net "P5E_CPU1_P3_TX_DN<8>")
	)
	(segment
		(start 120.34774 -281.053794)
		(end 120.31599 -281.072082)
		(width 0.1143)
		(layer "In11.Cu")
		(net "P5E_CPU1_P3_TX_DN<8>")
	)
	(segment
		(start 120.34774 -289.79876)
		(end 120.350788 -289.800538)
		(width 0.1143)
		(layer "In11.Cu")
		(net "P5E_CPU1_P3_TX_DN<8>")
	)
	(segment
		(start 120.34774 -281.698954)
		(end 120.350788 -281.700732)
		(width 0.1143)
		(layer "In11.Cu")
		(net "P5E_CPU1_P3_TX_DN<8>")
	)
	(segment
		(start 120.357646 -281.047698)
		(end 120.34774 -281.053794)
		(width 0.1143)
		(layer "In11.Cu")
		(net "P5E_CPU1_P3_TX_DN<8>")
	)
	(segment
		(start 120.34774 -291.419026)
		(end 120.38584 -291.440616)
		(width 0.1143)
		(layer "In11.Cu")
		(net "P5E_CPU1_P3_TX_DN<8>")
	)
	(segment
		(start 137.885678 -323.377052)
		(end 141.32941 -340.690454)
		(width 0.14224)
		(layer "In11.Cu")
		(net "P5E_CPU1_P3_TX_DN<8>")
	)
	(segment
		(start 128.192276 -365.871506)
		(end 126.229618 -366.684814)
		(width 0.14224)
		(layer "In11.Cu")
		(net "P5E_CPU1_P3_TX_DN<8>")
	)
	(segment
		(start 124.302266 -368.754152)
		(end 124.302266 -371.2083)
		(width 0.14224)
		(layer "In11.Cu")
		(net "P5E_CPU1_P3_TX_DN<8>")
	)
	(segment
		(start 120.399302 -287.501838)
		(end 120.387872 -287.510474)
		(width 0.1143)
		(layer "In11.Cu")
		(net "P5E_CPU1_P3_TX_DN<8>")
	)
	(segment
		(start 120.348756 -278.459438)
		(end 120.362726 -278.467566)
		(width 0.1143)
		(layer "In11.Cu")
		(net "P5E_CPU1_P3_TX_DN<8>")
	)
	(segment
		(start 121.110502 -296.055796)
		(end 121.137426 -296.125392)
		(width 0.1143)
		(layer "In11.Cu")
		(net "P5E_CPU1_P3_TX_DN<8>")
	)
	(segment
		(start 120.350788 -290.771834)
		(end 120.31599 -290.7919)
		(width 0.1143)
		(layer "In11.Cu")
		(net "P5E_CPU1_P3_TX_DN<8>")
	)
	(segment
		(start 120.34774 -284.938978)
		(end 120.350788 -284.940756)
		(width 0.1143)
		(layer "In11.Cu")
		(net "P5E_CPU1_P3_TX_DN<8>")
	)
	(segment
		(start 120.78716 -295.451022)
		(end 120.856756 -295.491662)
		(width 0.1143)
		(layer "In11.Cu")
		(net "P5E_CPU1_P3_TX_DN<8>")
	)
	(segment
		(start 120.34774 -288.178748)
		(end 120.350788 -288.180526)
		(width 0.1143)
		(layer "In11.Cu")
		(net "P5E_CPU1_P3_TX_DN<8>")
	)
	(segment
		(start 120.38584 -292.37178)
		(end 120.31599 -292.411912)
		(width 0.1143)
		(layer "In11.Cu")
		(net "P5E_CPU1_P3_TX_DN<8>")
	)
	(segment
		(start 122.142758 -300.113446)
		(end 124.171456 -303.149508)
		(width 0.14224)
		(layer "In11.Cu")
		(net "P5E_CPU1_P3_TX_DN<8>")
	)
	(segment
		(start 121.176542 -296.538396)
		(end 121.222262 -296.584116)
		(width 0.1143)
		(layer "In11.Cu")
		(net "P5E_CPU1_P3_TX_DN<8>")
	)
	(segment
		(start 134.459726 -360.753914)
		(end 131.65836 -363.55528)
		(width 0.14224)
		(layer "In11.Cu")
		(net "P5E_CPU1_P3_TX_DN<8>")
	)
	(segment
		(start 120.387872 -287.510474)
		(end 120.31599 -287.55213)
		(width 0.1143)
		(layer "In11.Cu")
		(net "P5E_CPU1_P3_TX_DN<8>")
	)
	(segment
		(start 120.34774 -293.038784)
		(end 120.350788 -293.040562)
		(width 0.1143)
		(layer "In11.Cu")
		(net "P5E_CPU1_P3_TX_DN<8>")
	)
	(segment
		(start 120.856756 -280.220928)
		(end 120.804686 -280.251154)
		(width 0.1143)
		(layer "In11.Cu")
		(net "P5E_CPU1_P3_TX_DN<8>")
	)
	(segment
		(start 121.176542 -296.33545)
		(end 121.176542 -296.538396)
		(width 0.1143)
		(layer "In11.Cu")
		(net "P5E_CPU1_P3_TX_DN<8>")
	)
	(segment
		(start 120.31599 -281.680666)
		(end 120.34774 -281.698954)
		(width 0.1143)
		(layer "In11.Cu")
		(net "P5E_CPU1_P3_TX_DN<8>")
	)
	(segment
		(start 120.38584 -291.440616)
		(end 120.398794 -291.450014)
		(width 0.1143)
		(layer "In11.Cu")
		(net "P5E_CPU1_P3_TX_DN<8>")
	)
	(segment
		(start 120.350788 -285.912052)
		(end 120.31599 -285.932118)
		(width 0.1143)
		(layer "In11.Cu")
		(net "P5E_CPU1_P3_TX_DN<8>")
	)
	(segment
		(start 121.222262 -296.612564)
		(end 121.22277 -296.613072)
		(width 0.14224)
		(layer "In11.Cu")
		(net "P5E_CPU1_P3_TX_DN<8>")
	)
	(segment
		(start 120.34774 -291.418772)
		(end 120.34774 -291.419026)
		(width 0.1143)
		(layer "In11.Cu")
		(net "P5E_CPU1_P3_TX_DN<8>")
	)
	(segment
		(start 120.350788 -294.011858)
		(end 120.31599 -294.031924)
		(width 0.1143)
		(layer "In11.Cu")
		(net "P5E_CPU1_P3_TX_DN<8>")
	)
	(segment
		(start 120.629934 -287.046162)
		(end 120.629934 -287.050734)
		(width 0.1143)
		(layer "In11.Cu")
		(net "P5E_CPU1_P3_TX_DN<8>")
	)
	(segment
		(start 120.617996 -280.57475)
		(end 120.617996 -280.58618)
		(width 0.1143)
		(layer "In11.Cu")
		(net "P5E_CPU1_P3_TX_DN<8>")
	)
	(segment
		(start 120.350788 -284.29204)
		(end 120.31599 -284.312106)
		(width 0.1143)
		(layer "In11.Cu")
		(net "P5E_CPU1_P3_TX_DN<8>")
	)
	(segment
		(start 140.636244 -348.841314)
		(end 137.728706 -355.86162)
		(width 0.14224)
		(layer "In11.Cu")
		(net "P5E_CPU1_P3_TX_DN<8>")
	)
	(segment
		(start 141.32941 -340.690454)
		(end 141.32941 -345.356434)
		(width 0.14224)
		(layer "In11.Cu")
		(net "P5E_CPU1_P3_TX_DN<8>")
	)
	(segment
		(start 120.34774 -294.658796)
		(end 120.387618 -294.682418)
		(width 0.1143)
		(layer "In11.Cu")
		(net "P5E_CPU1_P3_TX_DN<8>")
	)
	(segment
		(start 120.31599 -293.020496)
		(end 120.34774 -293.038784)
		(width 0.1143)
		(layer "In11.Cu")
		(net "P5E_CPU1_P3_TX_DN<8>")
	)
	(segment
		(start 120.398794 -292.362382)
		(end 120.38584 -292.37178)
		(width 0.1143)
		(layer "In11.Cu")
		(net "P5E_CPU1_P3_TX_DN<8>")
	)
	(segment
		(start 124.171456 -303.149508)
		(end 130.971036 -311.434734)
		(width 0.14224)
		(layer "In11.Cu")
		(net "P5E_CPU1_P3_TX_DN<8>")
	)
	(segment
		(start 130.971036 -311.434734)
		(end 136.14908 -319.183766)
		(width 0.14224)
		(layer "In11.Cu")
		(net "P5E_CPU1_P3_TX_DN<8>")
	)
	(segment
		(start 120.642634 -278.953722)
		(end 120.642634 -278.966168)
		(width 0.1143)
		(layer "In11.Cu")
		(net "P5E_CPU1_P3_TX_DN<8>")
	)
	(segment
		(start 121.22277 -296.613072)
		(end 121.22277 -297.080686)
		(width 0.14224)
		(layer "In11.Cu")
		(net "P5E_CPU1_P3_TX_DN<8>")
	)
	(segment
		(start 120.81764 -279.268936)
		(end 120.856756 -279.291796)
		(width 0.1143)
		(layer "In11.Cu")
		(net "P5E_CPU1_P3_TX_DN<8>")
	)
	(segment
		(start 120.534684 -278.13635)
		(end 120.236742 -278.13635)
		(width 0.1143)
		(layer "In11.Cu")
		(net "P5E_CPU1_P3_TX_DN<8>")
	)
	(arc
		(start 121.10212 -296.013886)
		(mid 121.104528 -296.035198)
		(end 121.110502 -296.055796)
		(width 0.1143)
		(layer "In11.Cu")
		(net "P5E_CPU1_P3_TX_DN<8>")
	)
	(arc
		(start 120.31599 -285.932118)
		(mid 120.201314 -286.065452)
		(end 120.160034 -286.23641)
		(width 0.1143)
		(layer "In11.Cu")
		(net "P5E_CPU1_P3_TX_DN<8>")
	)
	(arc
		(start 120.350788 -283.320744)
		(mid 120.630403 -283.806392)
		(end 120.350788 -284.29204)
		(width 0.1143)
		(layer "In11.Cu")
		(net "P5E_CPU1_P3_TX_DN<8>")
	)
	(arc
		(start 137.728706 -355.86162)
		(mid 136.335157 -358.468762)
		(end 134.459726 -360.753914)
		(width 0.14224)
		(layer "In11.Cu")
		(net "P5E_CPU1_P3_TX_DN<8>")
	)
	(arc
		(start 120.398794 -291.450014)
		(mid 120.633221 -291.906198)
		(end 120.398794 -292.362382)
		(width 0.1143)
		(layer "In11.Cu")
		(net "P5E_CPU1_P3_TX_DN<8>")
	)
	(arc
		(start 120.31599 -282.692094)
		(mid 120.160062 -282.996386)
		(end 120.31599 -283.300678)
		(width 0.1143)
		(layer "In11.Cu")
		(net "P5E_CPU1_P3_TX_DN<8>")
	)
	(arc
		(start 131.65836 -363.55528)
		(mid 130.03938 -364.884078)
		(end 128.192276 -365.871506)
		(width 0.14224)
		(layer "In11.Cu")
		(net "P5E_CPU1_P3_TX_DN<8>")
	)
	(arc
		(start 120.362726 -278.467566)
		(mid 120.567671 -278.673228)
		(end 120.642634 -278.953722)
		(width 0.1143)
		(layer "In11.Cu")
		(net "P5E_CPU1_P3_TX_DN<8>")
	)
	(arc
		(start 120.350788 -289.800538)
		(mid 120.630403 -290.286186)
		(end 120.350788 -290.771834)
		(width 0.1143)
		(layer "In11.Cu")
		(net "P5E_CPU1_P3_TX_DN<8>")
	)
	(arc
		(start 120.31599 -292.411912)
		(mid 120.160062 -292.716204)
		(end 120.31599 -293.020496)
		(width 0.1143)
		(layer "In11.Cu")
		(net "P5E_CPU1_P3_TX_DN<8>")
	)
	(arc
		(start 120.31599 -287.55213)
		(mid 120.201314 -287.685464)
		(end 120.160034 -287.856422)
		(width 0.1143)
		(layer "In11.Cu")
		(net "P5E_CPU1_P3_TX_DN<8>")
	)
	(arc
		(start 141.32941 -345.356434)
		(mid 141.154447 -347.133012)
		(end 140.636244 -348.841314)
		(width 0.14224)
		(layer "In11.Cu")
		(net "P5E_CPU1_P3_TX_DN<8>")
	)
	(arc
		(start 120.629934 -287.050734)
		(mid 120.568935 -287.304058)
		(end 120.399302 -287.501838)
		(width 0.1143)
		(layer "In11.Cu")
		(net "P5E_CPU1_P3_TX_DN<8>")
	)
	(arc
		(start 120.160034 -287.856422)
		(mid 120.200796 -288.026306)
		(end 120.314212 -288.15919)
		(width 0.1143)
		(layer "In11.Cu")
		(net "P5E_CPU1_P3_TX_DN<8>")
	)
	(arc
		(start 120.856756 -279.291796)
		(mid 121.099973 -279.756362)
		(end 120.856756 -280.220928)
		(width 0.1143)
		(layer "In11.Cu")
		(net "P5E_CPU1_P3_TX_DN<8>")
	)
	(arc
		(start 120.31599 -294.031924)
		(mid 120.160062 -294.336216)
		(end 120.31599 -294.640508)
		(width 0.1143)
		(layer "In11.Cu")
		(net "P5E_CPU1_P3_TX_DN<8>")
	)
	(arc
		(start 120.642634 -278.966168)
		(mid 120.689525 -279.141034)
		(end 120.81764 -279.268936)
		(width 0.1143)
		(layer "In11.Cu")
		(net "P5E_CPU1_P3_TX_DN<8>")
	)
	(arc
		(start 120.31599 -281.072082)
		(mid 120.160062 -281.376374)
		(end 120.31599 -281.680666)
		(width 0.1143)
		(layer "In11.Cu")
		(net "P5E_CPU1_P3_TX_DN<8>")
	)
	(arc
		(start 120.804432 -280.251408)
		(mid 120.667952 -280.388133)
		(end 120.617996 -280.57475)
		(width 0.1143)
		(layer "In11.Cu")
		(net "P5E_CPU1_P3_TX_DN<8>")
	)
	(arc
		(start 120.350788 -293.040562)
		(mid 120.630403 -293.52621)
		(end 120.350788 -294.011858)
		(width 0.1143)
		(layer "In11.Cu")
		(net "P5E_CPU1_P3_TX_DN<8>")
	)
	(arc
		(start 120.31599 -284.312106)
		(mid 120.160062 -284.616398)
		(end 120.31599 -284.92069)
		(width 0.1143)
		(layer "In11.Cu")
		(net "P5E_CPU1_P3_TX_DN<8>")
	)
	(arc
		(start 124.577602 -368.089434)
		(mid 124.373824 -368.394409)
		(end 124.302266 -368.754152)
		(width 0.14224)
		(layer "In11.Cu")
		(net "P5E_CPU1_P3_TX_DN<8>")
	)
	(arc
		(start 126.229618 -366.684814)
		(mid 125.832503 -366.89706)
		(end 125.484382 -367.182654)
		(width 0.14224)
		(layer "In11.Cu")
		(net "P5E_CPU1_P3_TX_DN<8>")
	)
	(arc
		(start 120.630188 -295.146222)
		(mid 120.671737 -295.317644)
		(end 120.78716 -295.451022)
		(width 0.1143)
		(layer "In11.Cu")
		(net "P5E_CPU1_P3_TX_DN<8>")
	)
	(arc
		(start 120.350788 -288.180526)
		(mid 120.630403 -288.666174)
		(end 120.350788 -289.151822)
		(width 0.1143)
		(layer "In11.Cu")
		(net "P5E_CPU1_P3_TX_DN<8>")
	)
	(arc
		(start 120.166892 -278.2062)
		(mid 120.218941 -278.337719)
		(end 120.31599 -278.440642)
		(width 0.1143)
		(layer "In11.Cu")
		(net "P5E_CPU1_P3_TX_DN<8>")
	)
	(arc
		(start 120.350788 -284.940756)
		(mid 120.630403 -285.426404)
		(end 120.350788 -285.912052)
		(width 0.1143)
		(layer "In11.Cu")
		(net "P5E_CPU1_P3_TX_DN<8>")
	)
	(arc
		(start 120.387618 -294.682418)
		(mid 120.565654 -294.882168)
		(end 120.629934 -295.141904)
		(width 0.1143)
		(layer "In11.Cu")
		(net "P5E_CPU1_P3_TX_DN<8>")
	)
	(arc
		(start 120.856756 -295.491662)
		(mid 121.031563 -295.686503)
		(end 121.099834 -295.93921)
		(width 0.1143)
		(layer "In11.Cu")
		(net "P5E_CPU1_P3_TX_DN<8>")
	)
	(arc
		(start 120.617996 -280.58618)
		(mid 120.54842 -280.851124)
		(end 120.357646 -281.047698)
		(width 0.1143)
		(layer "In11.Cu")
		(net "P5E_CPU1_P3_TX_DN<8>")
	)
	(arc
		(start 121.137426 -296.125392)
		(mid 121.166656 -296.22862)
		(end 121.176542 -296.33545)
		(width 0.1143)
		(layer "In11.Cu")
		(net "P5E_CPU1_P3_TX_DN<8>")
	)
	(arc
		(start 120.160034 -286.23641)
		(mid 120.200796 -286.406294)
		(end 120.314212 -286.539178)
		(width 0.1143)
		(layer "In11.Cu")
		(net "P5E_CPU1_P3_TX_DN<8>")
	)
	(arc
		(start 120.31599 -290.7919)
		(mid 120.160062 -291.096192)
		(end 120.31599 -291.400484)
		(width 0.1143)
		(layer "In11.Cu")
		(net "P5E_CPU1_P3_TX_DN<8>")
	)
	(arc
		(start 120.31599 -289.171888)
		(mid 120.160062 -289.47618)
		(end 120.31599 -289.780472)
		(width 0.1143)
		(layer "In11.Cu")
		(net "P5E_CPU1_P3_TX_DN<8>")
	)
	(arc
		(start 120.388888 -286.58312)
		(mid 120.566084 -286.785132)
		(end 120.629934 -287.046162)
		(width 0.1143)
		(layer "In11.Cu")
		(net "P5E_CPU1_P3_TX_DN<8>")
	)
	(arc
		(start 120.350788 -281.700732)
		(mid 120.630403 -282.18638)
		(end 120.350788 -282.672028)
		(width 0.1143)
		(layer "In11.Cu")
		(net "P5E_CPU1_P3_TX_DN<8>")
	)
	(segment
		(start 122.891296 -373.96293)
		(end 122.620786 -374.23344)
		(width 0.12954)
		(layer "F.Cu")
		(net "P5E_CPU1_P3_TX_DN<7>")
	)
	(segment
		(start 122.620786 -374.93702)
		(end 122.916696 -375.23293)
		(width 0.12954)
		(layer "F.Cu")
		(net "P5E_CPU1_P3_TX_DN<7>")
	)
	(segment
		(start 120.067832 -274.630388)
		(end 120.534684 -274.896326)
		(width 0.12954)
		(layer "F.Cu")
		(net "P5E_CPU1_P3_TX_DN<7>")
	)
	(segment
		(start 122.620786 -374.23344)
		(end 122.620786 -374.93702)
		(width 0.12954)
		(layer "F.Cu")
		(net "P5E_CPU1_P3_TX_DN<7>")
	)
	(segment
		(start 119.407432 -278.458676)
		(end 119.408448 -278.459184)
		(width 0.1143)
		(layer "In11.Cu")
		(net "P5E_CPU1_P3_TX_DN<7>")
	)
	(segment
		(start 119.393462 -278.450802)
		(end 119.394224 -278.45131)
		(width 0.1143)
		(layer "In11.Cu")
		(net "P5E_CPU1_P3_TX_DN<7>")
	)
	(segment
		(start 123.482354 -303.81067)
		(end 130.27533 -312.087768)
		(width 0.14224)
		(layer "In11.Cu")
		(net "P5E_CPU1_P3_TX_DN<7>")
	)
	(segment
		(start 119.416322 -293.043864)
		(end 119.44604 -293.061136)
		(width 0.1143)
		(layer "In11.Cu")
		(net "P5E_CPU1_P3_TX_DN<7>")
	)
	(segment
		(start 119.402606 -289.795966)
		(end 119.407686 -289.79876)
		(width 0.1143)
		(layer "In11.Cu")
		(net "P5E_CPU1_P3_TX_DN<7>")
	)
	(segment
		(start 119.41048 -281.052016)
		(end 119.40667 -281.054302)
		(width 0.1143)
		(layer "In11.Cu")
		(net "P5E_CPU1_P3_TX_DN<7>")
	)
	(segment
		(start 119.412512 -278.461724)
		(end 119.446802 -278.48179)
		(width 0.1143)
		(layer "In11.Cu")
		(net "P5E_CPU1_P3_TX_DN<7>")
	)
	(segment
		(start 119.430292 -276.181312)
		(end 119.40413 -276.197314)
		(width 0.1143)
		(layer "In11.Cu")
		(net "P5E_CPU1_P3_TX_DN<7>")
	)
	(segment
		(start 119.377714 -281.681682)
		(end 119.446294 -281.721306)
		(width 0.1143)
		(layer "In11.Cu")
		(net "P5E_CPU1_P3_TX_DN<7>")
	)
	(segment
		(start 119.377968 -288.161984)
		(end 119.407178 -288.179002)
		(width 0.1143)
		(layer "In11.Cu")
		(net "P5E_CPU1_P3_TX_DN<7>")
	)
	(segment
		(start 119.389652 -294.648636)
		(end 119.44604 -294.681148)
		(width 0.1143)
		(layer "In11.Cu")
		(net "P5E_CPU1_P3_TX_DN<7>")
	)
	(segment
		(start 119.877586 -279.268936)
		(end 119.916702 -279.291796)
		(width 0.1143)
		(layer "In11.Cu")
		(net "P5E_CPU1_P3_TX_DN<7>")
	)
	(segment
		(start 119.403876 -278.456644)
		(end 119.405908 -278.45766)
		(width 0.1143)
		(layer "In11.Cu")
		(net "P5E_CPU1_P3_TX_DN<7>")
	)
	(segment
		(start 119.403622 -286.556958)
		(end 119.405908 -286.558228)
		(width 0.1143)
		(layer "In11.Cu")
		(net "P5E_CPU1_P3_TX_DN<7>")
	)
	(segment
		(start 119.398796 -278.45385)
		(end 119.399558 -278.454358)
		(width 0.1143)
		(layer "In11.Cu")
		(net "P5E_CPU1_P3_TX_DN<7>")
	)
	(segment
		(start 119.407178 -286.55899)
		(end 119.407686 -286.559244)
		(width 0.1143)
		(layer "In11.Cu")
		(net "P5E_CPU1_P3_TX_DN<7>")
	)
	(segment
		(start 140.396468 -340.78164)
		(end 140.396468 -345.101672)
		(width 0.14224)
		(layer "In11.Cu")
		(net "P5E_CPU1_P3_TX_DN<7>")
	)
	(segment
		(start 119.408702 -291.41928)
		(end 119.410226 -291.420296)
		(width 0.1143)
		(layer "In11.Cu")
		(net "P5E_CPU1_P3_TX_DN<7>")
	)
	(segment
		(start 119.377714 -283.301694)
		(end 119.446294 -283.341318)
		(width 0.1143)
		(layer "In11.Cu")
		(net "P5E_CPU1_P3_TX_DN<7>")
	)
	(segment
		(start 133.397244 -360.489754)
		(end 131.644898 -362.2421)
		(width 0.14224)
		(layer "In11.Cu")
		(net "P5E_CPU1_P3_TX_DN<7>")
	)
	(segment
		(start 119.446802 -289.13074)
		(end 119.404892 -289.155124)
		(width 0.1143)
		(layer "In11.Cu")
		(net "P5E_CPU1_P3_TX_DN<7>")
	)
	(segment
		(start 119.375936 -278.440642)
		(end 119.393462 -278.450802)
		(width 0.1143)
		(layer "In11.Cu")
		(net "P5E_CPU1_P3_TX_DN<7>")
	)
	(segment
		(start 119.410226 -289.800284)
		(end 119.446802 -289.82162)
		(width 0.1143)
		(layer "In11.Cu")
		(net "P5E_CPU1_P3_TX_DN<7>")
	)
	(segment
		(start 120.236742 -274.896326)
		(end 120.153938 -274.97913)
		(width 0.1143)
		(layer "In11.Cu")
		(net "P5E_CPU1_P3_TX_DN<7>")
	)
	(segment
		(start 119.446802 -290.750752)
		(end 119.407178 -290.773866)
		(width 0.1143)
		(layer "In11.Cu")
		(net "P5E_CPU1_P3_TX_DN<7>")
	)
	(segment
		(start 118.937786 -277.648924)
		(end 118.940072 -277.650194)
		(width 0.1143)
		(layer "In11.Cu")
		(net "P5E_CPU1_P3_TX_DN<7>")
	)
	(segment
		(start 119.404892 -289.155124)
		(end 119.40286 -289.156394)
		(width 0.1143)
		(layer "In11.Cu")
		(net "P5E_CPU1_P3_TX_DN<7>")
	)
	(segment
		(start 119.410734 -287.52927)
		(end 119.40667 -287.53181)
		(width 0.1143)
		(layer "In11.Cu")
		(net "P5E_CPU1_P3_TX_DN<7>")
	)
	(segment
		(start 119.916702 -275.360892)
		(end 119.84609 -275.402294)
		(width 0.1143)
		(layer "In11.Cu")
		(net "P5E_CPU1_P3_TX_DN<7>")
	)
	(segment
		(start 120.160034 -295.992804)
		(end 120.160034 -296.538396)
		(width 0.1143)
		(layer "In11.Cu")
		(net "P5E_CPU1_P3_TX_DN<7>")
	)
	(segment
		(start 119.407178 -291.418772)
		(end 119.407686 -291.418772)
		(width 0.1143)
		(layer "In11.Cu")
		(net "P5E_CPU1_P3_TX_DN<7>")
	)
	(segment
		(start 119.446802 -293.990776)
		(end 119.389906 -294.023796)
		(width 0.1143)
		(layer "In11.Cu")
		(net "P5E_CPU1_P3_TX_DN<7>")
	)
	(segment
		(start 119.414798 -293.042848)
		(end 119.416322 -293.043864)
		(width 0.1143)
		(layer "In11.Cu")
		(net "P5E_CPU1_P3_TX_DN<7>")
	)
	(segment
		(start 118.906036 -277.630636)
		(end 118.937024 -277.648416)
		(width 0.1143)
		(layer "In11.Cu")
		(net "P5E_CPU1_P3_TX_DN<7>")
	)
	(segment
		(start 119.399558 -278.454358)
		(end 119.401844 -278.455374)
		(width 0.1143)
		(layer "In11.Cu")
		(net "P5E_CPU1_P3_TX_DN<7>")
	)
	(segment
		(start 119.407686 -288.178748)
		(end 119.425974 -288.189416)
		(width 0.1143)
		(layer "In11.Cu")
		(net "P5E_CPU1_P3_TX_DN<7>")
	)
	(segment
		(start 137.01522 -323.780912)
		(end 140.396468 -340.78164)
		(width 0.14224)
		(layer "In11.Cu")
		(net "P5E_CPU1_P3_TX_DN<7>")
	)
	(segment
		(start 119.446802 -292.370764)
		(end 119.408702 -292.393116)
		(width 0.1143)
		(layer "In11.Cu")
		(net "P5E_CPU1_P3_TX_DN<7>")
	)
	(segment
		(start 119.84609 -295.450514)
		(end 119.84736 -295.451276)
		(width 0.1143)
		(layer "In11.Cu")
		(net "P5E_CPU1_P3_TX_DN<7>")
	)
	(segment
		(start 118.975886 -276.981666)
		(end 118.952772 -276.995128)
		(width 0.1143)
		(layer "In11.Cu")
		(net "P5E_CPU1_P3_TX_DN<7>")
	)
	(segment
		(start 119.377968 -284.921706)
		(end 119.430038 -284.952186)
		(width 0.1143)
		(layer "In11.Cu")
		(net "P5E_CPU1_P3_TX_DN<7>")
	)
	(segment
		(start 119.408702 -289.799268)
		(end 119.410226 -289.800284)
		(width 0.1143)
		(layer "In11.Cu")
		(net "P5E_CPU1_P3_TX_DN<7>")
	)
	(segment
		(start 127.561594 -364.970568)
		(end 125.391418 -365.869728)
		(width 0.14224)
		(layer "In11.Cu")
		(net "P5E_CPU1_P3_TX_DN<7>")
	)
	(segment
		(start 119.431308 -276.18055)
		(end 119.430292 -276.181312)
		(width 0.1143)
		(layer "In11.Cu")
		(net "P5E_CPU1_P3_TX_DN<7>")
	)
	(segment
		(start 119.401844 -278.455374)
		(end 119.403114 -278.456136)
		(width 0.1143)
		(layer "In11.Cu")
		(net "P5E_CPU1_P3_TX_DN<7>")
	)
	(segment
		(start 120.205754 -296.584116)
		(end 120.205754 -296.612564)
		(width 0.1143)
		(layer "In11.Cu")
		(net "P5E_CPU1_P3_TX_DN<7>")
	)
	(segment
		(start 119.403114 -278.456136)
		(end 119.403876 -278.456644)
		(width 0.1143)
		(layer "In11.Cu")
		(net "P5E_CPU1_P3_TX_DN<7>")
	)
	(segment
		(start 119.410226 -291.420296)
		(end 119.446802 -291.441632)
		(width 0.1143)
		(layer "In11.Cu")
		(net "P5E_CPU1_P3_TX_DN<7>")
	)
	(segment
		(start 122.64771 -373.719344)
		(end 122.891296 -373.96293)
		(width 0.14224)
		(layer "In11.Cu")
		(net "P5E_CPU1_P3_TX_DN<7>")
	)
	(segment
		(start 122.600466 -369.14074)
		(end 122.600466 -373.605298)
		(width 0.14224)
		(layer "In11.Cu")
		(net "P5E_CPU1_P3_TX_DN<7>")
	)
	(segment
		(start 118.952772 -276.995128)
		(end 118.952772 -276.995382)
		(width 0.1143)
		(layer "In11.Cu")
		(net "P5E_CPU1_P3_TX_DN<7>")
	)
	(segment
		(start 120.160034 -296.538396)
		(end 120.205754 -296.584116)
		(width 0.1143)
		(layer "In11.Cu")
		(net "P5E_CPU1_P3_TX_DN<7>")
	)
	(segment
		(start 135.263128 -319.552828)
		(end 137.01522 -323.780912)
		(width 0.14224)
		(layer "In11.Cu")
		(net "P5E_CPU1_P3_TX_DN<7>")
	)
	(segment
		(start 119.407686 -289.79876)
		(end 119.408702 -289.799268)
		(width 0.1143)
		(layer "In11.Cu")
		(net "P5E_CPU1_P3_TX_DN<7>")
	)
	(segment
		(start 119.394224 -278.45131)
		(end 119.396256 -278.452326)
		(width 0.1143)
		(layer "In11.Cu")
		(net "P5E_CPU1_P3_TX_DN<7>")
	)
	(segment
		(start 119.40667 -281.054302)
		(end 119.406416 -281.054302)
		(width 0.1143)
		(layer "In11.Cu")
		(net "P5E_CPU1_P3_TX_DN<7>")
	)
	(segment
		(start 119.4054 -285.914846)
		(end 119.403876 -285.915862)
		(width 0.1143)
		(layer "In11.Cu")
		(net "P5E_CPU1_P3_TX_DN<7>")
	)
	(segment
		(start 119.428768 -285.901384)
		(end 119.4054 -285.914846)
		(width 0.1143)
		(layer "In11.Cu")
		(net "P5E_CPU1_P3_TX_DN<7>")
	)
	(segment
		(start 119.407178 -288.179002)
		(end 119.407686 -288.178748)
		(width 0.1143)
		(layer "In11.Cu")
		(net "P5E_CPU1_P3_TX_DN<7>")
	)
	(segment
		(start 118.947692 -276.99843)
		(end 118.906036 -277.022052)
		(width 0.1143)
		(layer "In11.Cu")
		(net "P5E_CPU1_P3_TX_DN<7>")
	)
	(segment
		(start 119.405908 -286.558228)
		(end 119.407178 -286.55899)
		(width 0.1143)
		(layer "In11.Cu")
		(net "P5E_CPU1_P3_TX_DN<7>")
	)
	(segment
		(start 119.410988 -278.460708)
		(end 119.412512 -278.461724)
		(width 0.1143)
		(layer "In11.Cu")
		(net "P5E_CPU1_P3_TX_DN<7>")
	)
	(segment
		(start 118.952772 -276.995382)
		(end 118.947692 -276.99843)
		(width 0.1143)
		(layer "In11.Cu")
		(net "P5E_CPU1_P3_TX_DN<7>")
	)
	(segment
		(start 120.534684 -274.896326)
		(end 120.236742 -274.896326)
		(width 0.1143)
		(layer "In11.Cu")
		(net "P5E_CPU1_P3_TX_DN<7>")
	)
	(segment
		(start 119.407686 -291.418772)
		(end 119.408702 -291.41928)
		(width 0.1143)
		(layer "In11.Cu")
		(net "P5E_CPU1_P3_TX_DN<7>")
	)
	(segment
		(start 120.205754 -296.612564)
		(end 120.205754 -297.109642)
		(width 0.14224)
		(layer "In11.Cu")
		(net "P5E_CPU1_P3_TX_DN<7>")
	)
	(segment
		(start 119.407686 -286.559244)
		(end 119.448834 -286.58312)
		(width 0.1143)
		(layer "In11.Cu")
		(net "P5E_CPU1_P3_TX_DN<7>")
	)
	(segment
		(start 119.408702 -292.393116)
		(end 119.407178 -292.393878)
		(width 0.1143)
		(layer "In11.Cu")
		(net "P5E_CPU1_P3_TX_DN<7>")
	)
	(segment
		(start 139.812014 -348.039436)
		(end 136.706864 -355.536754)
		(width 0.14224)
		(layer "In11.Cu")
		(net "P5E_CPU1_P3_TX_DN<7>")
	)
	(segment
		(start 118.937024 -277.648416)
		(end 118.937786 -277.648924)
		(width 0.1143)
		(layer "In11.Cu")
		(net "P5E_CPU1_P3_TX_DN<7>")
	)
	(segment
		(start 121.203974 -300.40072)
		(end 123.482354 -303.81067)
		(width 0.14224)
		(layer "In11.Cu")
		(net "P5E_CPU1_P3_TX_DN<7>")
	)
	(segment
		(start 120.205754 -297.109642)
		(end 121.203974 -300.40072)
		(width 0.14224)
		(layer "In11.Cu")
		(net "P5E_CPU1_P3_TX_DN<7>")
	)
	(segment
		(start 119.916702 -280.220928)
		(end 119.84609 -280.26233)
		(width 0.1143)
		(layer "In11.Cu")
		(net "P5E_CPU1_P3_TX_DN<7>")
	)
	(segment
		(start 130.27533 -312.087768)
		(end 135.263128 -319.552828)
		(width 0.14224)
		(layer "In11.Cu")
		(net "P5E_CPU1_P3_TX_DN<7>")
	)
	(segment
		(start 119.396256 -278.452326)
		(end 119.398796 -278.45385)
		(width 0.1143)
		(layer "In11.Cu")
		(net "P5E_CPU1_P3_TX_DN<7>")
	)
	(segment
		(start 119.425974 -288.189416)
		(end 119.446802 -288.201608)
		(width 0.1143)
		(layer "In11.Cu")
		(net "P5E_CPU1_P3_TX_DN<7>")
	)
	(segment
		(start 119.847106 -279.251156)
		(end 119.877586 -279.268936)
		(width 0.1143)
		(layer "In11.Cu")
		(net "P5E_CPU1_P3_TX_DN<7>")
	)
	(segment
		(start 119.408448 -278.459184)
		(end 119.410988 -278.460708)
		(width 0.1143)
		(layer "In11.Cu")
		(net "P5E_CPU1_P3_TX_DN<7>")
	)
	(segment
		(start 119.399812 -293.034212)
		(end 119.414798 -293.042848)
		(width 0.1143)
		(layer "In11.Cu")
		(net "P5E_CPU1_P3_TX_DN<7>")
	)
	(segment
		(start 125.277118 -365.92383)
		(end 124.176536 -366.512094)
		(width 0.14224)
		(layer "In11.Cu")
		(net "P5E_CPU1_P3_TX_DN<7>")
	)
	(segment
		(start 119.405908 -278.45766)
		(end 119.407432 -278.458676)
		(width 0.1143)
		(layer "In11.Cu")
		(net "P5E_CPU1_P3_TX_DN<7>")
	)
	(arc
		(start 120.153938 -274.97913)
		(mid 120.15215 -274.990579)
		(end 120.150128 -275.00199)
		(width 0.1143)
		(layer "In11.Cu")
		(net "P5E_CPU1_P3_TX_DN<7>")
	)
	(arc
		(start 119.84609 -280.26233)
		(mid 119.731247 -280.395478)
		(end 119.68988 -280.566368)
		(width 0.1143)
		(layer "In11.Cu")
		(net "P5E_CPU1_P3_TX_DN<7>")
	)
	(arc
		(start 119.430038 -284.952186)
		(mid 119.702425 -285.427144)
		(end 119.428768 -285.901384)
		(width 0.1143)
		(layer "In11.Cu")
		(net "P5E_CPU1_P3_TX_DN<7>")
	)
	(arc
		(start 119.84736 -295.451276)
		(mid 120.076229 -295.680155)
		(end 120.160034 -295.992804)
		(width 0.1143)
		(layer "In11.Cu")
		(net "P5E_CPU1_P3_TX_DN<7>")
	)
	(arc
		(start 119.446802 -293.061644)
		(mid 119.690129 -293.52621)
		(end 119.446802 -293.990776)
		(width 0.1143)
		(layer "In11.Cu")
		(net "P5E_CPU1_P3_TX_DN<7>")
	)
	(arc
		(start 119.690134 -278.946356)
		(mid 119.731683 -279.117778)
		(end 119.847106 -279.251156)
		(width 0.1143)
		(layer "In11.Cu")
		(net "P5E_CPU1_P3_TX_DN<7>")
	)
	(arc
		(start 119.446802 -294.681656)
		(mid 119.625615 -294.884006)
		(end 119.690134 -295.146222)
		(width 0.1143)
		(layer "In11.Cu")
		(net "P5E_CPU1_P3_TX_DN<7>")
	)
	(arc
		(start 119.44604 -294.681148)
		(mid 119.446421 -294.681402)
		(end 119.446802 -294.681656)
		(width 0.1143)
		(layer "In11.Cu")
		(net "P5E_CPU1_P3_TX_DN<7>")
	)
	(arc
		(start 119.407178 -290.773866)
		(mid 119.22154 -291.096382)
		(end 119.407178 -291.418772)
		(width 0.1143)
		(layer "In11.Cu")
		(net "P5E_CPU1_P3_TX_DN<7>")
	)
	(arc
		(start 119.407178 -292.393878)
		(mid 119.221658 -292.711935)
		(end 119.399812 -293.034212)
		(width 0.1143)
		(layer "In11.Cu")
		(net "P5E_CPU1_P3_TX_DN<7>")
	)
	(arc
		(start 119.446294 -283.341318)
		(mid 119.688333 -283.829897)
		(end 119.402606 -284.294326)
		(width 0.1143)
		(layer "In11.Cu")
		(net "P5E_CPU1_P3_TX_DN<7>")
	)
	(arc
		(start 119.448834 -286.58312)
		(mid 119.62603 -286.785132)
		(end 119.68988 -287.046162)
		(width 0.1143)
		(layer "In11.Cu")
		(net "P5E_CPU1_P3_TX_DN<7>")
	)
	(arc
		(start 136.706864 -355.536754)
		(mid 135.295962 -358.176233)
		(end 133.397244 -360.489754)
		(width 0.14224)
		(layer "In11.Cu")
		(net "P5E_CPU1_P3_TX_DN<7>")
	)
	(arc
		(start 119.68988 -280.566368)
		(mid 119.615052 -280.846519)
		(end 119.41048 -281.052016)
		(width 0.1143)
		(layer "In11.Cu")
		(net "P5E_CPU1_P3_TX_DN<7>")
	)
	(arc
		(start 119.402606 -282.674314)
		(mid 119.220295 -282.981267)
		(end 119.377714 -283.301694)
		(width 0.1143)
		(layer "In11.Cu")
		(net "P5E_CPU1_P3_TX_DN<7>")
	)
	(arc
		(start 119.402606 -284.294326)
		(mid 119.220291 -284.601382)
		(end 119.377968 -284.921706)
		(width 0.1143)
		(layer "In11.Cu")
		(net "P5E_CPU1_P3_TX_DN<7>")
	)
	(arc
		(start 119.446802 -278.48179)
		(mid 119.625615 -278.68414)
		(end 119.690134 -278.946356)
		(width 0.1143)
		(layer "In11.Cu")
		(net "P5E_CPU1_P3_TX_DN<7>")
	)
	(arc
		(start 119.446294 -281.721306)
		(mid 119.688333 -282.209885)
		(end 119.402606 -282.674314)
		(width 0.1143)
		(layer "In11.Cu")
		(net "P5E_CPU1_P3_TX_DN<7>")
	)
	(arc
		(start 118.906036 -277.022052)
		(mid 118.750108 -277.326344)
		(end 118.906036 -277.630636)
		(width 0.1143)
		(layer "In11.Cu")
		(net "P5E_CPU1_P3_TX_DN<7>")
	)
	(arc
		(start 119.21998 -278.13635)
		(mid 119.261235 -278.307321)
		(end 119.375936 -278.440642)
		(width 0.1143)
		(layer "In11.Cu")
		(net "P5E_CPU1_P3_TX_DN<7>")
	)
	(arc
		(start 140.396468 -345.101672)
		(mid 140.248917 -346.599338)
		(end 139.812014 -348.039436)
		(width 0.14224)
		(layer "In11.Cu")
		(net "P5E_CPU1_P3_TX_DN<7>")
	)
	(arc
		(start 119.406416 -281.054302)
		(mid 119.221073 -281.360123)
		(end 119.377714 -281.681682)
		(width 0.1143)
		(layer "In11.Cu")
		(net "P5E_CPU1_P3_TX_DN<7>")
	)
	(arc
		(start 119.84609 -275.402294)
		(mid 119.731247 -275.535442)
		(end 119.68988 -275.706332)
		(width 0.1143)
		(layer "In11.Cu")
		(net "P5E_CPU1_P3_TX_DN<7>")
	)
	(arc
		(start 119.44604 -293.061136)
		(mid 119.446421 -293.06139)
		(end 119.446802 -293.061644)
		(width 0.1143)
		(layer "In11.Cu")
		(net "P5E_CPU1_P3_TX_DN<7>")
	)
	(arc
		(start 119.403876 -285.915862)
		(mid 119.220119 -286.2363)
		(end 119.403622 -286.556958)
		(width 0.1143)
		(layer "In11.Cu")
		(net "P5E_CPU1_P3_TX_DN<7>")
	)
	(arc
		(start 119.40286 -289.156394)
		(mid 119.220011 -289.476071)
		(end 119.402606 -289.795966)
		(width 0.1143)
		(layer "In11.Cu")
		(net "P5E_CPU1_P3_TX_DN<7>")
	)
	(arc
		(start 119.40667 -287.53181)
		(mid 119.270012 -287.669212)
		(end 119.21998 -287.856422)
		(width 0.1143)
		(layer "In11.Cu")
		(net "P5E_CPU1_P3_TX_DN<7>")
	)
	(arc
		(start 119.21998 -276.516338)
		(mid 119.155258 -276.779077)
		(end 118.975886 -276.981666)
		(width 0.1143)
		(layer "In11.Cu")
		(net "P5E_CPU1_P3_TX_DN<7>")
	)
	(arc
		(start 119.21998 -287.856422)
		(mid 119.26182 -288.028408)
		(end 119.377968 -288.161984)
		(width 0.1143)
		(layer "In11.Cu")
		(net "P5E_CPU1_P3_TX_DN<7>")
	)
	(arc
		(start 119.446802 -289.82162)
		(mid 119.690129 -290.286186)
		(end 119.446802 -290.750752)
		(width 0.1143)
		(layer "In11.Cu")
		(net "P5E_CPU1_P3_TX_DN<7>")
	)
	(arc
		(start 119.40413 -276.197314)
		(mid 119.269453 -276.332219)
		(end 119.21998 -276.516338)
		(width 0.1143)
		(layer "In11.Cu")
		(net "P5E_CPU1_P3_TX_DN<7>")
	)
	(arc
		(start 119.690134 -295.146222)
		(mid 119.731389 -295.317193)
		(end 119.84609 -295.450514)
		(width 0.1143)
		(layer "In11.Cu")
		(net "P5E_CPU1_P3_TX_DN<7>")
	)
	(arc
		(start 131.644898 -362.2421)
		(mid 129.737616 -363.807431)
		(end 127.561594 -364.970568)
		(width 0.14224)
		(layer "In11.Cu")
		(net "P5E_CPU1_P3_TX_DN<7>")
	)
	(arc
		(start 124.176536 -366.512094)
		(mid 123.024788 -367.608332)
		(end 122.600466 -369.14074)
		(width 0.14224)
		(layer "In11.Cu")
		(net "P5E_CPU1_P3_TX_DN<7>")
	)
	(arc
		(start 118.940072 -277.650194)
		(mid 119.145017 -277.855856)
		(end 119.21998 -278.13635)
		(width 0.1143)
		(layer "In11.Cu")
		(net "P5E_CPU1_P3_TX_DN<7>")
	)
	(arc
		(start 119.916702 -279.291796)
		(mid 120.160029 -279.756362)
		(end 119.916702 -280.220928)
		(width 0.1143)
		(layer "In11.Cu")
		(net "P5E_CPU1_P3_TX_DN<7>")
	)
	(arc
		(start 122.600466 -373.605298)
		(mid 122.612743 -373.667021)
		(end 122.64771 -373.719344)
		(width 0.14224)
		(layer "In11.Cu")
		(net "P5E_CPU1_P3_TX_DN<7>")
	)
	(arc
		(start 125.391418 -365.869728)
		(mid 125.333602 -365.895373)
		(end 125.277118 -365.92383)
		(width 0.14224)
		(layer "In11.Cu")
		(net "P5E_CPU1_P3_TX_DN<7>")
	)
	(arc
		(start 119.446802 -288.201608)
		(mid 119.690129 -288.666174)
		(end 119.446802 -289.13074)
		(width 0.1143)
		(layer "In11.Cu")
		(net "P5E_CPU1_P3_TX_DN<7>")
	)
	(arc
		(start 119.446802 -291.441632)
		(mid 119.690129 -291.906198)
		(end 119.446802 -292.370764)
		(width 0.1143)
		(layer "In11.Cu")
		(net "P5E_CPU1_P3_TX_DN<7>")
	)
	(arc
		(start 120.150128 -275.00199)
		(mid 120.068695 -275.204388)
		(end 119.916702 -275.360892)
		(width 0.1143)
		(layer "In11.Cu")
		(net "P5E_CPU1_P3_TX_DN<7>")
	)
	(arc
		(start 119.389906 -294.023796)
		(mid 119.210019 -294.336106)
		(end 119.389652 -294.648636)
		(width 0.1143)
		(layer "In11.Cu")
		(net "P5E_CPU1_P3_TX_DN<7>")
	)
	(arc
		(start 119.68988 -287.046162)
		(mid 119.615069 -287.325129)
		(end 119.410734 -287.52927)
		(width 0.1143)
		(layer "In11.Cu")
		(net "P5E_CPU1_P3_TX_DN<7>")
	)
	(arc
		(start 119.68988 -275.706332)
		(mid 119.621089 -275.976423)
		(end 119.431308 -276.18055)
		(width 0.1143)
		(layer "In11.Cu")
		(net "P5E_CPU1_P3_TX_DN<7>")
	)
	(segment
		(start 117.247924 -276.2504)
		(end 117.714776 -276.516338)
		(width 0.12954)
		(layer "F.Cu")
		(net "P5E_CPU1_P3_TX_DN<6>")
	)
	(segment
		(start 119.487696 -369.03533)
		(end 119.217186 -369.30584)
		(width 0.12954)
		(layer "F.Cu")
		(net "P5E_CPU1_P3_TX_DN<6>")
	)
	(segment
		(start 119.217186 -370.00942)
		(end 119.513096 -370.30533)
		(width 0.12954)
		(layer "F.Cu")
		(net "P5E_CPU1_P3_TX_DN<6>")
	)
	(segment
		(start 119.217186 -369.30584)
		(end 119.217186 -370.00942)
		(width 0.12954)
		(layer "F.Cu")
		(net "P5E_CPU1_P3_TX_DN<6>")
	)
	(segment
		(start 133.13029 -359.15727)
		(end 130.840988 -361.446572)
		(width 0.14224)
		(layer "In11.Cu")
		(net "P5E_CPU1_P3_TX_DN<6>")
	)
	(segment
		(start 118.506748 -293.990776)
		(end 118.467632 -294.013636)
		(width 0.1143)
		(layer "In11.Cu")
		(net "P5E_CPU1_P3_TX_DN<6>")
	)
	(segment
		(start 118.437152 -281.681174)
		(end 118.467632 -281.698954)
		(width 0.1143)
		(layer "In11.Cu")
		(net "P5E_CPU1_P3_TX_DN<6>")
	)
	(segment
		(start 119.2657 -296.418762)
		(end 119.2657 -296.44721)
		(width 0.1143)
		(layer "In11.Cu")
		(net "P5E_CPU1_P3_TX_DN<6>")
	)
	(segment
		(start 118.467632 -293.038784)
		(end 118.506748 -293.061644)
		(width 0.1143)
		(layer "In11.Cu")
		(net "P5E_CPU1_P3_TX_DN<6>")
	)
	(segment
		(start 118.938802 -279.269444)
		(end 118.940326 -279.27046)
		(width 0.1143)
		(layer "In11.Cu")
		(net "P5E_CPU1_P3_TX_DN<6>")
	)
	(segment
		(start 118.437152 -291.400992)
		(end 118.467632 -291.418772)
		(width 0.1143)
		(layer "In11.Cu")
		(net "P5E_CPU1_P3_TX_DN<6>")
	)
	(segment
		(start 118.504208 -287.512506)
		(end 118.437152 -287.551622)
		(width 0.1143)
		(layer "In11.Cu")
		(net "P5E_CPU1_P3_TX_DN<6>")
	)
	(segment
		(start 118.506748 -292.370764)
		(end 118.467632 -292.393624)
		(width 0.1143)
		(layer "In11.Cu")
		(net "P5E_CPU1_P3_TX_DN<6>")
	)
	(segment
		(start 118.467632 -278.45893)
		(end 118.506748 -278.48179)
		(width 0.1143)
		(layer "In11.Cu")
		(net "P5E_CPU1_P3_TX_DN<6>")
	)
	(segment
		(start 139.093702 -346.971366)
		(end 135.540242 -355.55047)
		(width 0.14224)
		(layer "In11.Cu")
		(net "P5E_CPU1_P3_TX_DN<6>")
	)
	(segment
		(start 117.496082 -276.82063)
		(end 117.564154 -276.86)
		(width 0.1143)
		(layer "In11.Cu")
		(net "P5E_CPU1_P3_TX_DN<6>")
	)
	(segment
		(start 119.21998 -296.373042)
		(end 119.2657 -296.418762)
		(width 0.1143)
		(layer "In11.Cu")
		(net "P5E_CPU1_P3_TX_DN<6>")
	)
	(segment
		(start 117.714776 -276.516338)
		(end 117.416834 -276.516338)
		(width 0.1143)
		(layer "In11.Cu")
		(net "P5E_CPU1_P3_TX_DN<6>")
	)
	(segment
		(start 118.467632 -294.013636)
		(end 118.437152 -294.031416)
		(width 0.1143)
		(layer "In11.Cu")
		(net "P5E_CPU1_P3_TX_DN<6>")
	)
	(segment
		(start 119.2657 -297.26001)
		(end 120.33377 -300.780958)
		(width 0.14224)
		(layer "In11.Cu")
		(net "P5E_CPU1_P3_TX_DN<6>")
	)
	(segment
		(start 119.2657 -296.44721)
		(end 119.2657 -297.26001)
		(width 0.14224)
		(layer "In11.Cu")
		(net "P5E_CPU1_P3_TX_DN<6>")
	)
	(segment
		(start 118.937786 -280.243788)
		(end 118.937024 -280.244296)
		(width 0.1143)
		(layer "In11.Cu")
		(net "P5E_CPU1_P3_TX_DN<6>")
	)
	(segment
		(start 118.467632 -292.393624)
		(end 118.437152 -292.411404)
		(width 0.1143)
		(layer "In11.Cu")
		(net "P5E_CPU1_P3_TX_DN<6>")
	)
	(segment
		(start 118.43512 -288.159952)
		(end 118.467632 -288.178748)
		(width 0.1143)
		(layer "In11.Cu")
		(net "P5E_CPU1_P3_TX_DN<6>")
	)
	(segment
		(start 118.467632 -291.418772)
		(end 118.506748 -291.441632)
		(width 0.1143)
		(layer "In11.Cu")
		(net "P5E_CPU1_P3_TX_DN<6>")
	)
	(segment
		(start 118.437152 -284.921198)
		(end 118.467632 -284.938978)
		(width 0.1143)
		(layer "In11.Cu")
		(net "P5E_CPU1_P3_TX_DN<6>")
	)
	(segment
		(start 118.506748 -284.270958)
		(end 118.467632 -284.293818)
		(width 0.1143)
		(layer "In11.Cu")
		(net "P5E_CPU1_P3_TX_DN<6>")
	)
	(segment
		(start 118.906036 -279.250648)
		(end 118.937024 -279.268428)
		(width 0.1143)
		(layer "In11.Cu")
		(net "P5E_CPU1_P3_TX_DN<6>")
	)
	(segment
		(start 118.467632 -286.558736)
		(end 118.506748 -286.581596)
		(width 0.1143)
		(layer "In11.Cu")
		(net "P5E_CPU1_P3_TX_DN<6>")
	)
	(segment
		(start 118.937024 -280.244296)
		(end 118.935754 -280.245058)
		(width 0.1143)
		(layer "In11.Cu")
		(net "P5E_CPU1_P3_TX_DN<6>")
	)
	(segment
		(start 118.935754 -280.245058)
		(end 118.906036 -280.262076)
		(width 0.1143)
		(layer "In11.Cu")
		(net "P5E_CPU1_P3_TX_DN<6>")
	)
	(segment
		(start 139.460986 -340.872826)
		(end 139.460986 -345.125294)
		(width 0.14224)
		(layer "In11.Cu")
		(net "P5E_CPU1_P3_TX_DN<6>")
	)
	(segment
		(start 118.506748 -289.13074)
		(end 118.467632 -289.1536)
		(width 0.1143)
		(layer "In11.Cu")
		(net "P5E_CPU1_P3_TX_DN<6>")
	)
	(segment
		(start 130.243072 -313.720226)
		(end 134.387336 -319.921636)
		(width 0.14224)
		(layer "In11.Cu")
		(net "P5E_CPU1_P3_TX_DN<6>")
	)
	(segment
		(start 118.506748 -281.030934)
		(end 118.467632 -281.053794)
		(width 0.1143)
		(layer "In11.Cu")
		(net "P5E_CPU1_P3_TX_DN<6>")
	)
	(segment
		(start 118.467632 -281.053794)
		(end 118.437152 -281.071574)
		(width 0.1143)
		(layer "In11.Cu")
		(net "P5E_CPU1_P3_TX_DN<6>")
	)
	(segment
		(start 118.437152 -278.44115)
		(end 118.467632 -278.45893)
		(width 0.1143)
		(layer "In11.Cu")
		(net "P5E_CPU1_P3_TX_DN<6>")
	)
	(segment
		(start 119.196866 -368.183922)
		(end 119.196866 -368.7445)
		(width 0.14224)
		(layer "In11.Cu")
		(net "P5E_CPU1_P3_TX_DN<6>")
	)
	(segment
		(start 118.506748 -285.89097)
		(end 118.467632 -285.91383)
		(width 0.1143)
		(layer "In11.Cu")
		(net "P5E_CPU1_P3_TX_DN<6>")
	)
	(segment
		(start 118.906036 -295.450514)
		(end 118.976902 -295.491662)
		(width 0.1143)
		(layer "In11.Cu")
		(net "P5E_CPU1_P3_TX_DN<6>")
	)
	(segment
		(start 126.368556 -364.435136)
		(end 125.031754 -364.988856)
		(width 0.14224)
		(layer "In11.Cu")
		(net "P5E_CPU1_P3_TX_DN<6>")
	)
	(segment
		(start 118.43512 -286.53994)
		(end 118.467632 -286.558736)
		(width 0.1143)
		(layer "In11.Cu")
		(net "P5E_CPU1_P3_TX_DN<6>")
	)
	(segment
		(start 123.442222 -305.433222)
		(end 130.243072 -313.720226)
		(width 0.14224)
		(layer "In11.Cu")
		(net "P5E_CPU1_P3_TX_DN<6>")
	)
	(segment
		(start 118.437152 -283.301186)
		(end 118.467632 -283.318966)
		(width 0.1143)
		(layer "In11.Cu")
		(net "P5E_CPU1_P3_TX_DN<6>")
	)
	(segment
		(start 118.506748 -290.750752)
		(end 118.467632 -290.773612)
		(width 0.1143)
		(layer "In11.Cu")
		(net "P5E_CPU1_P3_TX_DN<6>")
	)
	(segment
		(start 118.467632 -284.293818)
		(end 118.437152 -284.311598)
		(width 0.1143)
		(layer "In11.Cu")
		(net "P5E_CPU1_P3_TX_DN<6>")
	)
	(segment
		(start 117.810026 -277.326344)
		(end 117.810026 -277.329392)
		(width 0.1143)
		(layer "In11.Cu")
		(net "P5E_CPU1_P3_TX_DN<6>")
	)
	(segment
		(start 118.467632 -285.91383)
		(end 118.437152 -285.93161)
		(width 0.1143)
		(layer "In11.Cu")
		(net "P5E_CPU1_P3_TX_DN<6>")
	)
	(segment
		(start 118.467632 -289.1536)
		(end 118.437152 -289.17138)
		(width 0.1143)
		(layer "In11.Cu")
		(net "P5E_CPU1_P3_TX_DN<6>")
	)
	(segment
		(start 134.387336 -319.921636)
		(end 136.13638 -324.143878)
		(width 0.14224)
		(layer "In11.Cu")
		(net "P5E_CPU1_P3_TX_DN<6>")
	)
	(segment
		(start 125.031754 -364.988856)
		(end 119.263922 -368.071908)
		(width 0.14224)
		(layer "In11.Cu")
		(net "P5E_CPU1_P3_TX_DN<6>")
	)
	(segment
		(start 119.196866 -368.7445)
		(end 119.487696 -369.03533)
		(width 0.14224)
		(layer "In11.Cu")
		(net "P5E_CPU1_P3_TX_DN<6>")
	)
	(segment
		(start 118.467632 -290.773612)
		(end 118.437152 -290.791392)
		(width 0.1143)
		(layer "In11.Cu")
		(net "P5E_CPU1_P3_TX_DN<6>")
	)
	(segment
		(start 118.467632 -288.178748)
		(end 118.506748 -288.201608)
		(width 0.1143)
		(layer "In11.Cu")
		(net "P5E_CPU1_P3_TX_DN<6>")
	)
	(segment
		(start 118.941342 -279.270968)
		(end 118.976902 -279.291796)
		(width 0.1143)
		(layer "In11.Cu")
		(net "P5E_CPU1_P3_TX_DN<6>")
	)
	(segment
		(start 118.976902 -280.220928)
		(end 118.937786 -280.243788)
		(width 0.1143)
		(layer "In11.Cu")
		(net "P5E_CPU1_P3_TX_DN<6>")
	)
	(segment
		(start 118.467632 -284.938978)
		(end 118.506748 -284.961838)
		(width 0.1143)
		(layer "In11.Cu")
		(net "P5E_CPU1_P3_TX_DN<6>")
	)
	(segment
		(start 118.506748 -282.650946)
		(end 118.467632 -282.673806)
		(width 0.1143)
		(layer "In11.Cu")
		(net "P5E_CPU1_P3_TX_DN<6>")
	)
	(segment
		(start 119.21998 -295.956228)
		(end 119.21998 -296.373042)
		(width 0.1143)
		(layer "In11.Cu")
		(net "P5E_CPU1_P3_TX_DN<6>")
	)
	(segment
		(start 118.467632 -283.318966)
		(end 118.506748 -283.341826)
		(width 0.1143)
		(layer "In11.Cu")
		(net "P5E_CPU1_P3_TX_DN<6>")
	)
	(segment
		(start 118.467632 -294.658796)
		(end 118.506748 -294.681656)
		(width 0.1143)
		(layer "In11.Cu")
		(net "P5E_CPU1_P3_TX_DN<6>")
	)
	(segment
		(start 118.467632 -282.673806)
		(end 118.437152 -282.691586)
		(width 0.1143)
		(layer "In11.Cu")
		(net "P5E_CPU1_P3_TX_DN<6>")
	)
	(segment
		(start 118.437152 -293.021004)
		(end 118.467632 -293.038784)
		(width 0.1143)
		(layer "In11.Cu")
		(net "P5E_CPU1_P3_TX_DN<6>")
	)
	(segment
		(start 117.963188 -277.628604)
		(end 117.965982 -277.630636)
		(width 0.1143)
		(layer "In11.Cu")
		(net "P5E_CPU1_P3_TX_DN<6>")
	)
	(segment
		(start 120.33377 -300.780958)
		(end 123.442222 -305.433222)
		(width 0.14224)
		(layer "In11.Cu")
		(net "P5E_CPU1_P3_TX_DN<6>")
	)
	(segment
		(start 118.467632 -289.79876)
		(end 118.506748 -289.82162)
		(width 0.1143)
		(layer "In11.Cu")
		(net "P5E_CPU1_P3_TX_DN<6>")
	)
	(segment
		(start 118.437152 -289.78098)
		(end 118.467632 -289.79876)
		(width 0.1143)
		(layer "In11.Cu")
		(net "P5E_CPU1_P3_TX_DN<6>")
	)
	(segment
		(start 118.467632 -281.698954)
		(end 118.506748 -281.721814)
		(width 0.1143)
		(layer "In11.Cu")
		(net "P5E_CPU1_P3_TX_DN<6>")
	)
	(segment
		(start 117.965982 -277.630636)
		(end 118.036848 -277.671784)
		(width 0.1143)
		(layer "In11.Cu")
		(net "P5E_CPU1_P3_TX_DN<6>")
	)
	(segment
		(start 118.937024 -279.268428)
		(end 118.937786 -279.268936)
		(width 0.1143)
		(layer "In11.Cu")
		(net "P5E_CPU1_P3_TX_DN<6>")
	)
	(segment
		(start 118.437152 -294.641016)
		(end 118.467632 -294.658796)
		(width 0.1143)
		(layer "In11.Cu")
		(net "P5E_CPU1_P3_TX_DN<6>")
	)
	(segment
		(start 118.940326 -279.27046)
		(end 118.941342 -279.270968)
		(width 0.1143)
		(layer "In11.Cu")
		(net "P5E_CPU1_P3_TX_DN<6>")
	)
	(segment
		(start 117.416834 -276.516338)
		(end 117.346984 -276.586188)
		(width 0.1143)
		(layer "In11.Cu")
		(net "P5E_CPU1_P3_TX_DN<6>")
	)
	(segment
		(start 118.937786 -279.268936)
		(end 118.938802 -279.269444)
		(width 0.1143)
		(layer "In11.Cu")
		(net "P5E_CPU1_P3_TX_DN<6>")
	)
	(segment
		(start 136.13638 -324.143878)
		(end 139.460986 -340.872826)
		(width 0.14224)
		(layer "In11.Cu")
		(net "P5E_CPU1_P3_TX_DN<6>")
	)
	(arc
		(start 118.506748 -286.581596)
		(mid 118.685561 -286.783946)
		(end 118.75008 -287.046162)
		(width 0.1143)
		(layer "In11.Cu")
		(net "P5E_CPU1_P3_TX_DN<6>")
	)
	(arc
		(start 118.506748 -288.201608)
		(mid 118.750075 -288.666174)
		(end 118.506748 -289.13074)
		(width 0.1143)
		(layer "In11.Cu")
		(net "P5E_CPU1_P3_TX_DN<6>")
	)
	(arc
		(start 118.75008 -280.566368)
		(mid 118.685565 -280.828587)
		(end 118.506748 -281.030934)
		(width 0.1143)
		(layer "In11.Cu")
		(net "P5E_CPU1_P3_TX_DN<6>")
	)
	(arc
		(start 117.564154 -276.86)
		(mid 117.744806 -277.062745)
		(end 117.810026 -277.326344)
		(width 0.1143)
		(layer "In11.Cu")
		(net "P5E_CPU1_P3_TX_DN<6>")
	)
	(arc
		(start 130.840988 -361.446572)
		(mid 128.751932 -363.161078)
		(end 126.368556 -364.435136)
		(width 0.14224)
		(layer "In11.Cu")
		(net "P5E_CPU1_P3_TX_DN<6>")
	)
	(arc
		(start 118.28018 -286.23641)
		(mid 118.321146 -286.406816)
		(end 118.43512 -286.53994)
		(width 0.1143)
		(layer "In11.Cu")
		(net "P5E_CPU1_P3_TX_DN<6>")
	)
	(arc
		(start 118.437152 -287.551622)
		(mid 118.321725 -287.684998)
		(end 118.28018 -287.856422)
		(width 0.1143)
		(layer "In11.Cu")
		(net "P5E_CPU1_P3_TX_DN<6>")
	)
	(arc
		(start 135.540242 -355.55047)
		(mid 134.512873 -357.47254)
		(end 133.13029 -359.15727)
		(width 0.14224)
		(layer "In11.Cu")
		(net "P5E_CPU1_P3_TX_DN<6>")
	)
	(arc
		(start 118.506748 -291.441632)
		(mid 118.750075 -291.906198)
		(end 118.506748 -292.370764)
		(width 0.1143)
		(layer "In11.Cu")
		(net "P5E_CPU1_P3_TX_DN<6>")
	)
	(arc
		(start 119.263922 -368.071908)
		(mid 119.21488 -368.118635)
		(end 119.196866 -368.183922)
		(width 0.14224)
		(layer "In11.Cu")
		(net "P5E_CPU1_P3_TX_DN<6>")
	)
	(arc
		(start 118.506748 -283.341826)
		(mid 118.750075 -283.806392)
		(end 118.506748 -284.270958)
		(width 0.1143)
		(layer "In11.Cu")
		(net "P5E_CPU1_P3_TX_DN<6>")
	)
	(arc
		(start 118.506748 -294.681656)
		(mid 118.685561 -294.884006)
		(end 118.75008 -295.146222)
		(width 0.1143)
		(layer "In11.Cu")
		(net "P5E_CPU1_P3_TX_DN<6>")
	)
	(arc
		(start 118.75008 -295.146222)
		(mid 118.791335 -295.317193)
		(end 118.906036 -295.450514)
		(width 0.1143)
		(layer "In11.Cu")
		(net "P5E_CPU1_P3_TX_DN<6>")
	)
	(arc
		(start 118.437152 -285.93161)
		(mid 118.321725 -286.064986)
		(end 118.28018 -286.23641)
		(width 0.1143)
		(layer "In11.Cu")
		(net "P5E_CPU1_P3_TX_DN<6>")
	)
	(arc
		(start 118.506748 -289.82162)
		(mid 118.750075 -290.286186)
		(end 118.506748 -290.750752)
		(width 0.1143)
		(layer "In11.Cu")
		(net "P5E_CPU1_P3_TX_DN<6>")
	)
	(arc
		(start 118.437152 -294.031416)
		(mid 118.280175 -294.336216)
		(end 118.437152 -294.641016)
		(width 0.1143)
		(layer "In11.Cu")
		(net "P5E_CPU1_P3_TX_DN<6>")
	)
	(arc
		(start 118.75008 -287.046162)
		(mid 118.684844 -287.309753)
		(end 118.504208 -287.512506)
		(width 0.1143)
		(layer "In11.Cu")
		(net "P5E_CPU1_P3_TX_DN<6>")
	)
	(arc
		(start 118.437152 -282.691586)
		(mid 118.280175 -282.996386)
		(end 118.437152 -283.301186)
		(width 0.1143)
		(layer "In11.Cu")
		(net "P5E_CPU1_P3_TX_DN<6>")
	)
	(arc
		(start 118.906036 -280.262076)
		(mid 118.79136 -280.39541)
		(end 118.75008 -280.566368)
		(width 0.1143)
		(layer "In11.Cu")
		(net "P5E_CPU1_P3_TX_DN<6>")
	)
	(arc
		(start 118.976902 -295.491662)
		(mid 119.15556 -295.694062)
		(end 119.21998 -295.956228)
		(width 0.1143)
		(layer "In11.Cu")
		(net "P5E_CPU1_P3_TX_DN<6>")
	)
	(arc
		(start 118.75008 -278.946356)
		(mid 118.791335 -279.117327)
		(end 118.906036 -279.250648)
		(width 0.1143)
		(layer "In11.Cu")
		(net "P5E_CPU1_P3_TX_DN<6>")
	)
	(arc
		(start 118.036848 -277.671784)
		(mid 118.215661 -277.874134)
		(end 118.28018 -278.13635)
		(width 0.1143)
		(layer "In11.Cu")
		(net "P5E_CPU1_P3_TX_DN<6>")
	)
	(arc
		(start 118.437152 -289.17138)
		(mid 118.280175 -289.47618)
		(end 118.437152 -289.78098)
		(width 0.1143)
		(layer "In11.Cu")
		(net "P5E_CPU1_P3_TX_DN<6>")
	)
	(arc
		(start 117.810026 -277.329392)
		(mid 117.850472 -277.497507)
		(end 117.963188 -277.628604)
		(width 0.1143)
		(layer "In11.Cu")
		(net "P5E_CPU1_P3_TX_DN<6>")
	)
	(arc
		(start 117.346984 -276.586188)
		(mid 117.399033 -276.717707)
		(end 117.496082 -276.82063)
		(width 0.1143)
		(layer "In11.Cu")
		(net "P5E_CPU1_P3_TX_DN<6>")
	)
	(arc
		(start 118.28018 -278.13635)
		(mid 118.321729 -278.307772)
		(end 118.437152 -278.44115)
		(width 0.1143)
		(layer "In11.Cu")
		(net "P5E_CPU1_P3_TX_DN<6>")
	)
	(arc
		(start 118.506748 -278.48179)
		(mid 118.685561 -278.68414)
		(end 118.75008 -278.946356)
		(width 0.1143)
		(layer "In11.Cu")
		(net "P5E_CPU1_P3_TX_DN<6>")
	)
	(arc
		(start 118.437152 -281.071574)
		(mid 118.280175 -281.376374)
		(end 118.437152 -281.681174)
		(width 0.1143)
		(layer "In11.Cu")
		(net "P5E_CPU1_P3_TX_DN<6>")
	)
	(arc
		(start 118.437152 -290.791392)
		(mid 118.280175 -291.096192)
		(end 118.437152 -291.400992)
		(width 0.1143)
		(layer "In11.Cu")
		(net "P5E_CPU1_P3_TX_DN<6>")
	)
	(arc
		(start 118.28018 -287.856422)
		(mid 118.321146 -288.026828)
		(end 118.43512 -288.159952)
		(width 0.1143)
		(layer "In11.Cu")
		(net "P5E_CPU1_P3_TX_DN<6>")
	)
	(arc
		(start 118.976902 -279.291796)
		(mid 119.220229 -279.756362)
		(end 118.976902 -280.220928)
		(width 0.1143)
		(layer "In11.Cu")
		(net "P5E_CPU1_P3_TX_DN<6>")
	)
	(arc
		(start 118.506748 -293.061644)
		(mid 118.750075 -293.52621)
		(end 118.506748 -293.990776)
		(width 0.1143)
		(layer "In11.Cu")
		(net "P5E_CPU1_P3_TX_DN<6>")
	)
	(arc
		(start 118.437152 -284.311598)
		(mid 118.280175 -284.616398)
		(end 118.437152 -284.921198)
		(width 0.1143)
		(layer "In11.Cu")
		(net "P5E_CPU1_P3_TX_DN<6>")
	)
	(arc
		(start 118.506748 -281.721814)
		(mid 118.750075 -282.18638)
		(end 118.506748 -282.650946)
		(width 0.1143)
		(layer "In11.Cu")
		(net "P5E_CPU1_P3_TX_DN<6>")
	)
	(arc
		(start 139.460986 -345.125294)
		(mid 139.368242 -346.066413)
		(end 139.093702 -346.971366)
		(width 0.14224)
		(layer "In11.Cu")
		(net "P5E_CPU1_P3_TX_DN<6>")
	)
	(arc
		(start 118.506748 -284.961838)
		(mid 118.750075 -285.426404)
		(end 118.506748 -285.89097)
		(width 0.1143)
		(layer "In11.Cu")
		(net "P5E_CPU1_P3_TX_DN<6>")
	)
	(arc
		(start 118.437152 -292.411404)
		(mid 118.280175 -292.716204)
		(end 118.437152 -293.021004)
		(width 0.1143)
		(layer "In11.Cu")
		(net "P5E_CPU1_P3_TX_DN<6>")
	)
	(segment
		(start 117.515386 -372.47322)
		(end 117.811296 -372.76913)
		(width 0.12954)
		(layer "F.Cu")
		(net "P5E_CPU1_P3_TX_DN<5>")
	)
	(segment
		(start 117.515386 -371.76964)
		(end 117.515386 -372.47322)
		(width 0.12954)
		(layer "F.Cu")
		(net "P5E_CPU1_P3_TX_DN<5>")
	)
	(segment
		(start 117.247924 -277.870412)
		(end 117.714776 -278.13635)
		(width 0.12954)
		(layer "F.Cu")
		(net "P5E_CPU1_P3_TX_DN<5>")
	)
	(segment
		(start 117.785896 -371.49913)
		(end 117.515386 -371.76964)
		(width 0.12954)
		(layer "F.Cu")
		(net "P5E_CPU1_P3_TX_DN<5>")
	)
	(segment
		(start 117.527832 -288.178748)
		(end 117.53088 -288.180526)
		(width 0.1143)
		(layer "In11.Cu")
		(net "P5E_CPU1_P3_TX_DN<5>")
	)
	(segment
		(start 126.522226 -363.162596)
		(end 126.007622 -363.375702)
		(width 0.14224)
		(layer "In11.Cu")
		(net "P5E_CPU1_P3_TX_DN<5>")
	)
	(segment
		(start 117.494304 -286.539178)
		(end 117.56898 -286.58312)
		(width 0.1143)
		(layer "In11.Cu")
		(net "P5E_CPU1_P3_TX_DN<5>")
	)
	(segment
		(start 117.527832 -278.45893)
		(end 117.528848 -278.459438)
		(width 0.1143)
		(layer "In11.Cu")
		(net "P5E_CPU1_P3_TX_DN<5>")
	)
	(segment
		(start 138.068304 -346.832428)
		(end 134.634986 -355.121718)
		(width 0.14224)
		(layer "In11.Cu")
		(net "P5E_CPU1_P3_TX_DN<5>")
	)
	(segment
		(start 117.53088 -284.29204)
		(end 117.496082 -284.312106)
		(width 0.1143)
		(layer "In11.Cu")
		(net "P5E_CPU1_P3_TX_DN<5>")
	)
	(segment
		(start 117.494304 -288.15919)
		(end 117.495066 -288.159698)
		(width 0.1143)
		(layer "In11.Cu")
		(net "P5E_CPU1_P3_TX_DN<5>")
	)
	(segment
		(start 138.423396 -340.832186)
		(end 138.423396 -345.04757)
		(width 0.14224)
		(layer "In11.Cu")
		(net "P5E_CPU1_P3_TX_DN<5>")
	)
	(segment
		(start 117.496082 -293.020496)
		(end 117.527832 -293.038784)
		(width 0.1143)
		(layer "In11.Cu")
		(net "P5E_CPU1_P3_TX_DN<5>")
	)
	(segment
		(start 117.527832 -281.698954)
		(end 117.53088 -281.700732)
		(width 0.1143)
		(layer "In11.Cu")
		(net "P5E_CPU1_P3_TX_DN<5>")
	)
	(segment
		(start 117.822726 -278.953722)
		(end 117.822726 -278.966168)
		(width 0.1143)
		(layer "In11.Cu")
		(net "P5E_CPU1_P3_TX_DN<5>")
	)
	(segment
		(start 117.496082 -289.780472)
		(end 117.527832 -289.79876)
		(width 0.1143)
		(layer "In11.Cu")
		(net "P5E_CPU1_P3_TX_DN<5>")
	)
	(segment
		(start 117.527832 -281.053794)
		(end 117.496082 -281.072082)
		(width 0.1143)
		(layer "In11.Cu")
		(net "P5E_CPU1_P3_TX_DN<5>")
	)
	(segment
		(start 117.527832 -283.318966)
		(end 117.53088 -283.320744)
		(width 0.1143)
		(layer "In11.Cu")
		(net "P5E_CPU1_P3_TX_DN<5>")
	)
	(segment
		(start 117.527832 -291.419026)
		(end 117.565932 -291.440616)
		(width 0.1143)
		(layer "In11.Cu")
		(net "P5E_CPU1_P3_TX_DN<5>")
	)
	(segment
		(start 117.527832 -291.418772)
		(end 117.527832 -291.419026)
		(width 0.1143)
		(layer "In11.Cu")
		(net "P5E_CPU1_P3_TX_DN<5>")
	)
	(segment
		(start 117.53088 -285.912052)
		(end 117.496082 -285.932118)
		(width 0.1143)
		(layer "In11.Cu")
		(net "P5E_CPU1_P3_TX_DN<5>")
	)
	(segment
		(start 133.464046 -320.223134)
		(end 135.11911 -324.218808)
		(width 0.14224)
		(layer "In11.Cu")
		(net "P5E_CPU1_P3_TX_DN<5>")
	)
	(segment
		(start 117.997732 -279.268936)
		(end 118.036848 -279.291796)
		(width 0.1143)
		(layer "In11.Cu")
		(net "P5E_CPU1_P3_TX_DN<5>")
	)
	(segment
		(start 117.527832 -289.79876)
		(end 117.53088 -289.800538)
		(width 0.1143)
		(layer "In11.Cu")
		(net "P5E_CPU1_P3_TX_DN<5>")
	)
	(segment
		(start 118.036848 -280.220928)
		(end 117.984778 -280.251154)
		(width 0.1143)
		(layer "In11.Cu")
		(net "P5E_CPU1_P3_TX_DN<5>")
	)
	(segment
		(start 117.496082 -278.440642)
		(end 117.52707 -278.458422)
		(width 0.1143)
		(layer "In11.Cu")
		(net "P5E_CPU1_P3_TX_DN<5>")
	)
	(segment
		(start 118.3259 -296.44721)
		(end 118.3259 -297.379898)
		(width 0.14224)
		(layer "In11.Cu")
		(net "P5E_CPU1_P3_TX_DN<5>")
	)
	(segment
		(start 117.416834 -278.13635)
		(end 117.346984 -278.2062)
		(width 0.1143)
		(layer "In11.Cu")
		(net "P5E_CPU1_P3_TX_DN<5>")
	)
	(segment
		(start 126.007622 -363.375702)
		(end 118.777512 -367.240566)
		(width 0.14224)
		(layer "In11.Cu")
		(net "P5E_CPU1_P3_TX_DN<5>")
	)
	(segment
		(start 117.495066 -368.653314)
		(end 117.495066 -371.2083)
		(width 0.14224)
		(layer "In11.Cu")
		(net "P5E_CPU1_P3_TX_DN<5>")
	)
	(segment
		(start 117.496082 -284.92069)
		(end 117.527832 -284.938978)
		(width 0.1143)
		(layer "In11.Cu")
		(net "P5E_CPU1_P3_TX_DN<5>")
	)
	(segment
		(start 117.52707 -278.458422)
		(end 117.527832 -278.45893)
		(width 0.1143)
		(layer "In11.Cu")
		(net "P5E_CPU1_P3_TX_DN<5>")
	)
	(segment
		(start 129.52603 -314.329318)
		(end 133.464046 -320.223134)
		(width 0.14224)
		(layer "In11.Cu")
		(net "P5E_CPU1_P3_TX_DN<5>")
	)
	(segment
		(start 118.3259 -296.418762)
		(end 118.3259 -296.44721)
		(width 0.1143)
		(layer "In11.Cu")
		(net "P5E_CPU1_P3_TX_DN<5>")
	)
	(segment
		(start 117.798088 -280.57475)
		(end 117.798088 -280.58618)
		(width 0.1143)
		(layer "In11.Cu")
		(net "P5E_CPU1_P3_TX_DN<5>")
	)
	(segment
		(start 117.965982 -295.450514)
		(end 117.997732 -295.468802)
		(width 0.1143)
		(layer "In11.Cu")
		(net "P5E_CPU1_P3_TX_DN<5>")
	)
	(segment
		(start 117.714776 -278.13635)
		(end 117.416834 -278.13635)
		(width 0.1143)
		(layer "In11.Cu")
		(net "P5E_CPU1_P3_TX_DN<5>")
	)
	(segment
		(start 117.565932 -291.440616)
		(end 117.578886 -291.450014)
		(width 0.1143)
		(layer "In11.Cu")
		(net "P5E_CPU1_P3_TX_DN<5>")
	)
	(segment
		(start 117.579394 -287.501838)
		(end 117.567964 -287.510474)
		(width 0.1143)
		(layer "In11.Cu")
		(net "P5E_CPU1_P3_TX_DN<5>")
	)
	(segment
		(start 117.53088 -290.771834)
		(end 117.496082 -290.7919)
		(width 0.1143)
		(layer "In11.Cu")
		(net "P5E_CPU1_P3_TX_DN<5>")
	)
	(segment
		(start 117.52707 -283.318458)
		(end 117.527832 -283.318966)
		(width 0.1143)
		(layer "In11.Cu")
		(net "P5E_CPU1_P3_TX_DN<5>")
	)
	(segment
		(start 117.537738 -281.047698)
		(end 117.527832 -281.053794)
		(width 0.1143)
		(layer "In11.Cu")
		(net "P5E_CPU1_P3_TX_DN<5>")
	)
	(segment
		(start 117.984778 -280.251154)
		(end 117.984524 -280.251408)
		(width 0.1143)
		(layer "In11.Cu")
		(net "P5E_CPU1_P3_TX_DN<5>")
	)
	(segment
		(start 118.000272 -295.470326)
		(end 118.001288 -295.470834)
		(width 0.1143)
		(layer "In11.Cu")
		(net "P5E_CPU1_P3_TX_DN<5>")
	)
	(segment
		(start 117.527832 -293.038784)
		(end 117.53088 -293.040562)
		(width 0.1143)
		(layer "In11.Cu")
		(net "P5E_CPU1_P3_TX_DN<5>")
	)
	(segment
		(start 119.484394 -301.198788)
		(end 122.700796 -306.01285)
		(width 0.14224)
		(layer "In11.Cu")
		(net "P5E_CPU1_P3_TX_DN<5>")
	)
	(segment
		(start 117.496082 -294.640508)
		(end 117.527832 -294.658796)
		(width 0.1143)
		(layer "In11.Cu")
		(net "P5E_CPU1_P3_TX_DN<5>")
	)
	(segment
		(start 117.94109 -367.927128)
		(end 117.693186 -368.175032)
		(width 0.14224)
		(layer "In11.Cu")
		(net "P5E_CPU1_P3_TX_DN<5>")
	)
	(segment
		(start 117.496082 -291.400484)
		(end 117.527832 -291.418772)
		(width 0.1143)
		(layer "In11.Cu")
		(net "P5E_CPU1_P3_TX_DN<5>")
	)
	(segment
		(start 135.11911 -324.218808)
		(end 138.423396 -340.832186)
		(width 0.14224)
		(layer "In11.Cu")
		(net "P5E_CPU1_P3_TX_DN<5>")
	)
	(segment
		(start 117.578886 -292.362382)
		(end 117.565932 -292.37178)
		(width 0.1143)
		(layer "In11.Cu")
		(net "P5E_CPU1_P3_TX_DN<5>")
	)
	(segment
		(start 117.53088 -289.151822)
		(end 117.496082 -289.171888)
		(width 0.1143)
		(layer "In11.Cu")
		(net "P5E_CPU1_P3_TX_DN<5>")
	)
	(segment
		(start 118.3259 -297.379898)
		(end 119.484394 -301.198788)
		(width 0.14224)
		(layer "In11.Cu")
		(net "P5E_CPU1_P3_TX_DN<5>")
	)
	(segment
		(start 117.495066 -288.159698)
		(end 117.527832 -288.178748)
		(width 0.1143)
		(layer "In11.Cu")
		(net "P5E_CPU1_P3_TX_DN<5>")
	)
	(segment
		(start 117.527832 -284.938978)
		(end 117.53088 -284.940756)
		(width 0.1143)
		(layer "In11.Cu")
		(net "P5E_CPU1_P3_TX_DN<5>")
	)
	(segment
		(start 132.427726 -358.425242)
		(end 130.04292 -360.810048)
		(width 0.14224)
		(layer "In11.Cu")
		(net "P5E_CPU1_P3_TX_DN<5>")
	)
	(segment
		(start 117.496082 -281.680666)
		(end 117.527832 -281.698954)
		(width 0.1143)
		(layer "In11.Cu")
		(net "P5E_CPU1_P3_TX_DN<5>")
	)
	(segment
		(start 117.53088 -294.011858)
		(end 117.496082 -294.031924)
		(width 0.1143)
		(layer "In11.Cu")
		(net "P5E_CPU1_P3_TX_DN<5>")
	)
	(segment
		(start 117.997732 -295.468802)
		(end 117.998748 -295.46931)
		(width 0.1143)
		(layer "In11.Cu")
		(net "P5E_CPU1_P3_TX_DN<5>")
	)
	(segment
		(start 117.565932 -292.37178)
		(end 117.496082 -292.411912)
		(width 0.1143)
		(layer "In11.Cu")
		(net "P5E_CPU1_P3_TX_DN<5>")
	)
	(segment
		(start 117.810026 -295.141904)
		(end 117.810026 -295.146222)
		(width 0.1143)
		(layer "In11.Cu")
		(net "P5E_CPU1_P3_TX_DN<5>")
	)
	(segment
		(start 117.527832 -294.658796)
		(end 117.56771 -294.682418)
		(width 0.1143)
		(layer "In11.Cu")
		(net "P5E_CPU1_P3_TX_DN<5>")
	)
	(segment
		(start 117.998748 -295.46931)
		(end 118.000272 -295.470326)
		(width 0.1143)
		(layer "In11.Cu")
		(net "P5E_CPU1_P3_TX_DN<5>")
	)
	(segment
		(start 118.001288 -295.470834)
		(end 118.036848 -295.491662)
		(width 0.1143)
		(layer "In11.Cu")
		(net "P5E_CPU1_P3_TX_DN<5>")
	)
	(segment
		(start 117.496082 -283.300678)
		(end 117.52707 -283.318458)
		(width 0.1143)
		(layer "In11.Cu")
		(net "P5E_CPU1_P3_TX_DN<5>")
	)
	(segment
		(start 118.28018 -296.373042)
		(end 118.3259 -296.418762)
		(width 0.1143)
		(layer "In11.Cu")
		(net "P5E_CPU1_P3_TX_DN<5>")
	)
	(segment
		(start 118.777512 -367.240566)
		(end 117.94109 -367.927128)
		(width 0.14224)
		(layer "In11.Cu")
		(net "P5E_CPU1_P3_TX_DN<5>")
	)
	(segment
		(start 117.567964 -287.510474)
		(end 117.496082 -287.55213)
		(width 0.1143)
		(layer "In11.Cu")
		(net "P5E_CPU1_P3_TX_DN<5>")
	)
	(segment
		(start 117.528848 -278.459438)
		(end 117.542818 -278.467566)
		(width 0.1143)
		(layer "In11.Cu")
		(net "P5E_CPU1_P3_TX_DN<5>")
	)
	(segment
		(start 117.810026 -287.046162)
		(end 117.810026 -287.050734)
		(width 0.1143)
		(layer "In11.Cu")
		(net "P5E_CPU1_P3_TX_DN<5>")
	)
	(segment
		(start 122.700796 -306.01285)
		(end 129.52603 -314.329318)
		(width 0.14224)
		(layer "In11.Cu")
		(net "P5E_CPU1_P3_TX_DN<5>")
	)
	(segment
		(start 118.28018 -295.956228)
		(end 118.28018 -296.373042)
		(width 0.1143)
		(layer "In11.Cu")
		(net "P5E_CPU1_P3_TX_DN<5>")
	)
	(segment
		(start 117.53088 -282.672028)
		(end 117.496082 -282.692094)
		(width 0.1143)
		(layer "In11.Cu")
		(net "P5E_CPU1_P3_TX_DN<5>")
	)
	(segment
		(start 117.495066 -371.2083)
		(end 117.785896 -371.49913)
		(width 0.14224)
		(layer "In11.Cu")
		(net "P5E_CPU1_P3_TX_DN<5>")
	)
	(arc
		(start 117.53088 -289.800538)
		(mid 117.810495 -290.286186)
		(end 117.53088 -290.771834)
		(width 0.1143)
		(layer "In11.Cu")
		(net "P5E_CPU1_P3_TX_DN<5>")
	)
	(arc
		(start 117.340126 -286.23641)
		(mid 117.380888 -286.406294)
		(end 117.494304 -286.539178)
		(width 0.1143)
		(layer "In11.Cu")
		(net "P5E_CPU1_P3_TX_DN<5>")
	)
	(arc
		(start 130.04292 -360.810048)
		(mid 128.398421 -362.15969)
		(end 126.522226 -363.162596)
		(width 0.14224)
		(layer "In11.Cu")
		(net "P5E_CPU1_P3_TX_DN<5>")
	)
	(arc
		(start 118.036848 -295.491662)
		(mid 118.115271 -295.557143)
		(end 118.180612 -295.63568)
		(width 0.1143)
		(layer "In11.Cu")
		(net "P5E_CPU1_P3_TX_DN<5>")
	)
	(arc
		(start 134.634986 -355.121718)
		(mid 133.694053 -356.882188)
		(end 132.427726 -358.425242)
		(width 0.14224)
		(layer "In11.Cu")
		(net "P5E_CPU1_P3_TX_DN<5>")
	)
	(arc
		(start 117.810026 -295.146222)
		(mid 117.851281 -295.317193)
		(end 117.965982 -295.450514)
		(width 0.1143)
		(layer "In11.Cu")
		(net "P5E_CPU1_P3_TX_DN<5>")
	)
	(arc
		(start 117.56771 -294.682418)
		(mid 117.745746 -294.882168)
		(end 117.810026 -295.141904)
		(width 0.1143)
		(layer "In11.Cu")
		(net "P5E_CPU1_P3_TX_DN<5>")
	)
	(arc
		(start 117.496082 -284.312106)
		(mid 117.340154 -284.616398)
		(end 117.496082 -284.92069)
		(width 0.1143)
		(layer "In11.Cu")
		(net "P5E_CPU1_P3_TX_DN<5>")
	)
	(arc
		(start 117.53088 -293.040562)
		(mid 117.810495 -293.52621)
		(end 117.53088 -294.011858)
		(width 0.1143)
		(layer "In11.Cu")
		(net "P5E_CPU1_P3_TX_DN<5>")
	)
	(arc
		(start 117.496082 -294.031924)
		(mid 117.340154 -294.336216)
		(end 117.496082 -294.640508)
		(width 0.1143)
		(layer "In11.Cu")
		(net "P5E_CPU1_P3_TX_DN<5>")
	)
	(arc
		(start 118.036848 -279.291796)
		(mid 118.280065 -279.756362)
		(end 118.036848 -280.220928)
		(width 0.1143)
		(layer "In11.Cu")
		(net "P5E_CPU1_P3_TX_DN<5>")
	)
	(arc
		(start 117.53088 -284.940756)
		(mid 117.810495 -285.426404)
		(end 117.53088 -285.912052)
		(width 0.1143)
		(layer "In11.Cu")
		(net "P5E_CPU1_P3_TX_DN<5>")
	)
	(arc
		(start 117.496082 -281.072082)
		(mid 117.340154 -281.376374)
		(end 117.496082 -281.680666)
		(width 0.1143)
		(layer "In11.Cu")
		(net "P5E_CPU1_P3_TX_DN<5>")
	)
	(arc
		(start 117.53088 -288.180526)
		(mid 117.810495 -288.666174)
		(end 117.53088 -289.151822)
		(width 0.1143)
		(layer "In11.Cu")
		(net "P5E_CPU1_P3_TX_DN<5>")
	)
	(arc
		(start 117.496082 -282.692094)
		(mid 117.340154 -282.996386)
		(end 117.496082 -283.300678)
		(width 0.1143)
		(layer "In11.Cu")
		(net "P5E_CPU1_P3_TX_DN<5>")
	)
	(arc
		(start 117.53088 -281.700732)
		(mid 117.810495 -282.18638)
		(end 117.53088 -282.672028)
		(width 0.1143)
		(layer "In11.Cu")
		(net "P5E_CPU1_P3_TX_DN<5>")
	)
	(arc
		(start 117.496082 -289.171888)
		(mid 117.340154 -289.47618)
		(end 117.496082 -289.780472)
		(width 0.1143)
		(layer "In11.Cu")
		(net "P5E_CPU1_P3_TX_DN<5>")
	)
	(arc
		(start 138.423396 -345.04757)
		(mid 138.33373 -345.957481)
		(end 138.068304 -346.832428)
		(width 0.14224)
		(layer "In11.Cu")
		(net "P5E_CPU1_P3_TX_DN<5>")
	)
	(arc
		(start 117.496082 -287.55213)
		(mid 117.381406 -287.685464)
		(end 117.340126 -287.856422)
		(width 0.1143)
		(layer "In11.Cu")
		(net "P5E_CPU1_P3_TX_DN<5>")
	)
	(arc
		(start 117.340126 -287.856422)
		(mid 117.380888 -288.026306)
		(end 117.494304 -288.15919)
		(width 0.1143)
		(layer "In11.Cu")
		(net "P5E_CPU1_P3_TX_DN<5>")
	)
	(arc
		(start 117.346984 -278.2062)
		(mid 117.399033 -278.337719)
		(end 117.496082 -278.440642)
		(width 0.1143)
		(layer "In11.Cu")
		(net "P5E_CPU1_P3_TX_DN<5>")
	)
	(arc
		(start 117.56898 -286.58312)
		(mid 117.746176 -286.785132)
		(end 117.810026 -287.046162)
		(width 0.1143)
		(layer "In11.Cu")
		(net "P5E_CPU1_P3_TX_DN<5>")
	)
	(arc
		(start 117.822726 -278.966168)
		(mid 117.869617 -279.141034)
		(end 117.997732 -279.268936)
		(width 0.1143)
		(layer "In11.Cu")
		(net "P5E_CPU1_P3_TX_DN<5>")
	)
	(arc
		(start 117.496082 -290.7919)
		(mid 117.340154 -291.096192)
		(end 117.496082 -291.400484)
		(width 0.1143)
		(layer "In11.Cu")
		(net "P5E_CPU1_P3_TX_DN<5>")
	)
	(arc
		(start 117.53088 -283.320744)
		(mid 117.810495 -283.806392)
		(end 117.53088 -284.29204)
		(width 0.1143)
		(layer "In11.Cu")
		(net "P5E_CPU1_P3_TX_DN<5>")
	)
	(arc
		(start 117.578886 -291.450014)
		(mid 117.813313 -291.906198)
		(end 117.578886 -292.362382)
		(width 0.1143)
		(layer "In11.Cu")
		(net "P5E_CPU1_P3_TX_DN<5>")
	)
	(arc
		(start 117.693186 -368.175032)
		(mid 117.546562 -368.39447)
		(end 117.495066 -368.653314)
		(width 0.14224)
		(layer "In11.Cu")
		(net "P5E_CPU1_P3_TX_DN<5>")
	)
	(arc
		(start 117.810026 -287.050734)
		(mid 117.749027 -287.304058)
		(end 117.579394 -287.501838)
		(width 0.1143)
		(layer "In11.Cu")
		(net "P5E_CPU1_P3_TX_DN<5>")
	)
	(arc
		(start 117.496082 -292.411912)
		(mid 117.340154 -292.716204)
		(end 117.496082 -293.020496)
		(width 0.1143)
		(layer "In11.Cu")
		(net "P5E_CPU1_P3_TX_DN<5>")
	)
	(arc
		(start 117.496082 -285.932118)
		(mid 117.381406 -286.065452)
		(end 117.340126 -286.23641)
		(width 0.1143)
		(layer "In11.Cu")
		(net "P5E_CPU1_P3_TX_DN<5>")
	)
	(arc
		(start 117.984524 -280.251408)
		(mid 117.848044 -280.388133)
		(end 117.798088 -280.57475)
		(width 0.1143)
		(layer "In11.Cu")
		(net "P5E_CPU1_P3_TX_DN<5>")
	)
	(arc
		(start 117.542818 -278.467566)
		(mid 117.747763 -278.673228)
		(end 117.822726 -278.953722)
		(width 0.1143)
		(layer "In11.Cu")
		(net "P5E_CPU1_P3_TX_DN<5>")
	)
	(arc
		(start 118.180612 -295.63568)
		(mid 118.254726 -295.788394)
		(end 118.28018 -295.956228)
		(width 0.1143)
		(layer "In11.Cu")
		(net "P5E_CPU1_P3_TX_DN<5>")
	)
	(arc
		(start 117.798088 -280.58618)
		(mid 117.728512 -280.851124)
		(end 117.537738 -281.047698)
		(width 0.1143)
		(layer "In11.Cu")
		(net "P5E_CPU1_P3_TX_DN<5>")
	)
	(segment
		(start 115.813586 -374.23344)
		(end 115.813586 -374.93702)
		(width 0.12954)
		(layer "F.Cu")
		(net "P5E_CPU1_P3_TX_DN<4>")
	)
	(segment
		(start 116.084096 -373.96293)
		(end 115.813586 -374.23344)
		(width 0.12954)
		(layer "F.Cu")
		(net "P5E_CPU1_P3_TX_DN<4>")
	)
	(segment
		(start 115.813586 -374.93702)
		(end 116.109496 -375.23293)
		(width 0.12954)
		(layer "F.Cu")
		(net "P5E_CPU1_P3_TX_DN<4>")
	)
	(segment
		(start 117.247924 -279.490424)
		(end 117.714776 -279.756362)
		(width 0.12954)
		(layer "F.Cu")
		(net "P5E_CPU1_P3_TX_DN<4>")
	)
	(segment
		(start 116.587016 -285.914338)
		(end 116.585746 -285.9151)
		(width 0.1143)
		(layer "In11.Cu")
		(net "P5E_CPU1_P3_TX_DN<4>")
	)
	(segment
		(start 116.584222 -283.316934)
		(end 116.586254 -283.318204)
		(width 0.1143)
		(layer "In11.Cu")
		(net "P5E_CPU1_P3_TX_DN<4>")
	)
	(segment
		(start 116.585746 -289.15487)
		(end 116.556028 -289.171888)
		(width 0.1143)
		(layer "In11.Cu")
		(net "P5E_CPU1_P3_TX_DN<4>")
	)
	(segment
		(start 116.566696 -283.307028)
		(end 116.58346 -283.316426)
		(width 0.1143)
		(layer "In11.Cu")
		(net "P5E_CPU1_P3_TX_DN<4>")
	)
	(segment
		(start 116.587016 -294.658288)
		(end 116.587778 -294.658796)
		(width 0.1143)
		(layer "In11.Cu")
		(net "P5E_CPU1_P3_TX_DN<4>")
	)
	(segment
		(start 116.596922 -284.288738)
		(end 116.59616 -284.289246)
		(width 0.1143)
		(layer "In11.Cu")
		(net "P5E_CPU1_P3_TX_DN<4>")
	)
	(segment
		(start 116.585746 -290.774882)
		(end 116.556028 -290.7919)
		(width 0.1143)
		(layer "In11.Cu")
		(net "P5E_CPU1_P3_TX_DN<4>")
	)
	(segment
		(start 117.385846 -296.418762)
		(end 117.385846 -296.44721)
		(width 0.1143)
		(layer "In11.Cu")
		(net "P5E_CPU1_P3_TX_DN<4>")
	)
	(segment
		(start 116.58854 -289.153092)
		(end 116.587016 -289.154108)
		(width 0.1143)
		(layer "In11.Cu")
		(net "P5E_CPU1_P3_TX_DN<4>")
	)
	(segment
		(start 116.58854 -283.319474)
		(end 116.605304 -283.329126)
		(width 0.1143)
		(layer "In11.Cu")
		(net "P5E_CPU1_P3_TX_DN<4>")
	)
	(segment
		(start 116.58219 -284.935676)
		(end 116.58473 -284.9372)
		(width 0.1143)
		(layer "In11.Cu")
		(net "P5E_CPU1_P3_TX_DN<4>")
	)
	(segment
		(start 115.793266 -369.371118)
		(end 115.793266 -373.605298)
		(width 0.14224)
		(layer "In11.Cu")
		(net "P5E_CPU1_P3_TX_DN<4>")
	)
	(segment
		(start 116.587524 -282.67406)
		(end 116.583968 -282.675838)
		(width 0.1143)
		(layer "In11.Cu")
		(net "P5E_CPU1_P3_TX_DN<4>")
	)
	(segment
		(start 116.587016 -289.798252)
		(end 116.587778 -289.79876)
		(width 0.1143)
		(layer "In11.Cu")
		(net "P5E_CPU1_P3_TX_DN<4>")
	)
	(segment
		(start 116.587016 -283.318712)
		(end 116.587016 -283.318458)
		(width 0.1143)
		(layer "In11.Cu")
		(net "P5E_CPU1_P3_TX_DN<4>")
	)
	(segment
		(start 137.473436 -340.884764)
		(end 137.473436 -344.788236)
		(width 0.14224)
		(layer "In11.Cu")
		(net "P5E_CPU1_P3_TX_DN<4>")
	)
	(segment
		(start 116.587778 -294.013636)
		(end 116.587016 -294.014144)
		(width 0.1143)
		(layer "In11.Cu")
		(net "P5E_CPU1_P3_TX_DN<4>")
	)
	(segment
		(start 116.602764 -281.045412)
		(end 116.597684 -281.04846)
		(width 0.1143)
		(layer "In11.Cu")
		(net "P5E_CPU1_P3_TX_DN<4>")
	)
	(segment
		(start 116.585746 -292.394894)
		(end 116.556028 -292.411912)
		(width 0.1143)
		(layer "In11.Cu")
		(net "P5E_CPU1_P3_TX_DN<4>")
	)
	(segment
		(start 116.6241 -285.892748)
		(end 116.587778 -285.91383)
		(width 0.1143)
		(layer "In11.Cu")
		(net "P5E_CPU1_P3_TX_DN<4>")
	)
	(segment
		(start 116.59616 -284.289246)
		(end 116.587778 -284.293818)
		(width 0.1143)
		(layer "In11.Cu")
		(net "P5E_CPU1_P3_TX_DN<4>")
	)
	(segment
		(start 116.580412 -284.934914)
		(end 116.58219 -284.935676)
		(width 0.1143)
		(layer "In11.Cu")
		(net "P5E_CPU1_P3_TX_DN<4>")
	)
	(segment
		(start 116.603272 -284.284928)
		(end 116.601494 -284.285944)
		(width 0.1143)
		(layer "In11.Cu")
		(net "P5E_CPU1_P3_TX_DN<4>")
	)
	(segment
		(start 122.324622 -307.209698)
		(end 129.42951 -315.867288)
		(width 0.14224)
		(layer "In11.Cu")
		(net "P5E_CPU1_P3_TX_DN<4>")
	)
	(segment
		(start 116.583968 -282.675838)
		(end 116.567712 -282.685236)
		(width 0.1143)
		(layer "In11.Cu")
		(net "P5E_CPU1_P3_TX_DN<4>")
	)
	(segment
		(start 132.59181 -320.599816)
		(end 134.334504 -325.10222)
		(width 0.14224)
		(layer "In11.Cu")
		(net "P5E_CPU1_P3_TX_DN<4>")
	)
	(segment
		(start 117.381274 -296.789602)
		(end 117.381274 -297.506644)
		(width 0.14224)
		(layer "In11.Cu")
		(net "P5E_CPU1_P3_TX_DN<4>")
	)
	(segment
		(start 116.601494 -284.285944)
		(end 116.59997 -284.28696)
		(width 0.1143)
		(layer "In11.Cu")
		(net "P5E_CPU1_P3_TX_DN<4>")
	)
	(segment
		(start 120.23344 -365.036608)
		(end 117.520466 -366.488218)
		(width 0.14224)
		(layer "In11.Cu")
		(net "P5E_CPU1_P3_TX_DN<4>")
	)
	(segment
		(start 116.587016 -293.038276)
		(end 116.587778 -293.038784)
		(width 0.1143)
		(layer "In11.Cu")
		(net "P5E_CPU1_P3_TX_DN<4>")
	)
	(segment
		(start 116.587778 -284.293818)
		(end 116.584476 -284.295596)
		(width 0.1143)
		(layer "In11.Cu")
		(net "P5E_CPU1_P3_TX_DN<4>")
	)
	(segment
		(start 116.587778 -281.698954)
		(end 116.590826 -281.700732)
		(width 0.1143)
		(layer "In11.Cu")
		(net "P5E_CPU1_P3_TX_DN<4>")
	)
	(segment
		(start 116.587016 -289.154108)
		(end 116.585746 -289.15487)
		(width 0.1143)
		(layer "In11.Cu")
		(net "P5E_CPU1_P3_TX_DN<4>")
	)
	(segment
		(start 116.58473 -284.9372)
		(end 116.587778 -284.938978)
		(width 0.1143)
		(layer "In11.Cu")
		(net "P5E_CPU1_P3_TX_DN<4>")
	)
	(segment
		(start 116.55425 -286.539178)
		(end 116.587778 -286.558736)
		(width 0.1143)
		(layer "In11.Cu")
		(net "P5E_CPU1_P3_TX_DN<4>")
	)
	(segment
		(start 129.42951 -315.867288)
		(end 132.59181 -320.599816)
		(width 0.14224)
		(layer "In11.Cu")
		(net "P5E_CPU1_P3_TX_DN<4>")
	)
	(segment
		(start 137.152634 -346.400628)
		(end 133.884162 -354.291646)
		(width 0.14224)
		(layer "In11.Cu")
		(net "P5E_CPU1_P3_TX_DN<4>")
	)
	(segment
		(start 116.587778 -288.178748)
		(end 116.58854 -288.179256)
		(width 0.1143)
		(layer "In11.Cu")
		(net "P5E_CPU1_P3_TX_DN<4>")
	)
	(segment
		(start 116.556028 -281.680666)
		(end 116.587016 -281.698446)
		(width 0.1143)
		(layer "In11.Cu")
		(net "P5E_CPU1_P3_TX_DN<4>")
	)
	(segment
		(start 116.55425 -288.15919)
		(end 116.587778 -288.178748)
		(width 0.1143)
		(layer "In11.Cu")
		(net "P5E_CPU1_P3_TX_DN<4>")
	)
	(segment
		(start 116.587016 -283.318458)
		(end 116.58854 -283.319474)
		(width 0.1143)
		(layer "In11.Cu")
		(net "P5E_CPU1_P3_TX_DN<4>")
	)
	(segment
		(start 116.556028 -291.400484)
		(end 116.587016 -291.418264)
		(width 0.1143)
		(layer "In11.Cu")
		(net "P5E_CPU1_P3_TX_DN<4>")
	)
	(segment
		(start 116.587778 -284.938978)
		(end 116.6241 -284.96006)
		(width 0.1143)
		(layer "In11.Cu")
		(net "P5E_CPU1_P3_TX_DN<4>")
	)
	(segment
		(start 116.582952 -294.656256)
		(end 116.585492 -294.65778)
		(width 0.1143)
		(layer "In11.Cu")
		(net "P5E_CPU1_P3_TX_DN<4>")
	)
	(segment
		(start 116.602764 -281.045158)
		(end 116.602764 -281.045412)
		(width 0.1143)
		(layer "In11.Cu")
		(net "P5E_CPU1_P3_TX_DN<4>")
	)
	(segment
		(start 117.340126 -296.373042)
		(end 117.385846 -296.418762)
		(width 0.1143)
		(layer "In11.Cu")
		(net "P5E_CPU1_P3_TX_DN<4>")
	)
	(segment
		(start 116.587016 -290.77412)
		(end 116.585746 -290.774882)
		(width 0.1143)
		(layer "In11.Cu")
		(net "P5E_CPU1_P3_TX_DN<4>")
	)
	(segment
		(start 134.334504 -325.10222)
		(end 137.473436 -340.884764)
		(width 0.14224)
		(layer "In11.Cu")
		(net "P5E_CPU1_P3_TX_DN<4>")
	)
	(segment
		(start 116.587016 -291.418264)
		(end 116.587778 -291.418772)
		(width 0.1143)
		(layer "In11.Cu")
		(net "P5E_CPU1_P3_TX_DN<4>")
	)
	(segment
		(start 117.416834 -279.756362)
		(end 117.33403 -279.839166)
		(width 0.1143)
		(layer "In11.Cu")
		(net "P5E_CPU1_P3_TX_DN<4>")
	)
	(segment
		(start 131.281678 -358.186736)
		(end 130.210306 -359.258108)
		(width 0.14224)
		(layer "In11.Cu")
		(net "P5E_CPU1_P3_TX_DN<4>")
	)
	(segment
		(start 116.587016 -294.014144)
		(end 116.584222 -294.015668)
		(width 0.1143)
		(layer "In11.Cu")
		(net "P5E_CPU1_P3_TX_DN<4>")
	)
	(segment
		(start 116.621306 -287.514284)
		(end 116.587778 -287.533842)
		(width 0.1143)
		(layer "In11.Cu")
		(net "P5E_CPU1_P3_TX_DN<4>")
	)
	(segment
		(start 116.587016 -281.698446)
		(end 116.587778 -281.698954)
		(width 0.1143)
		(layer "In11.Cu")
		(net "P5E_CPU1_P3_TX_DN<4>")
	)
	(segment
		(start 116.587778 -282.673806)
		(end 116.587524 -282.67406)
		(width 0.1143)
		(layer "In11.Cu")
		(net "P5E_CPU1_P3_TX_DN<4>")
	)
	(segment
		(start 116.625878 -281.031696)
		(end 116.602764 -281.045158)
		(width 0.1143)
		(layer "In11.Cu")
		(net "P5E_CPU1_P3_TX_DN<4>")
	)
	(segment
		(start 116.587778 -285.91383)
		(end 116.587016 -285.914338)
		(width 0.1143)
		(layer "In11.Cu")
		(net "P5E_CPU1_P3_TX_DN<4>")
	)
	(segment
		(start 116.587778 -292.393624)
		(end 116.587016 -292.394132)
		(width 0.1143)
		(layer "In11.Cu")
		(net "P5E_CPU1_P3_TX_DN<4>")
	)
	(segment
		(start 117.025928 -295.450514)
		(end 117.096794 -295.491662)
		(width 0.1143)
		(layer "In11.Cu")
		(net "P5E_CPU1_P3_TX_DN<4>")
	)
	(segment
		(start 116.587778 -287.533842)
		(end 116.556028 -287.55213)
		(width 0.1143)
		(layer "In11.Cu")
		(net "P5E_CPU1_P3_TX_DN<4>")
	)
	(segment
		(start 116.586254 -283.318204)
		(end 116.587016 -283.318712)
		(width 0.1143)
		(layer "In11.Cu")
		(net "P5E_CPU1_P3_TX_DN<4>")
	)
	(segment
		(start 116.605304 -283.329126)
		(end 116.606066 -283.329634)
		(width 0.1143)
		(layer "In11.Cu")
		(net "P5E_CPU1_P3_TX_DN<4>")
	)
	(segment
		(start 116.590826 -282.672028)
		(end 116.587778 -282.673806)
		(width 0.1143)
		(layer "In11.Cu")
		(net "P5E_CPU1_P3_TX_DN<4>")
	)
	(segment
		(start 116.59997 -284.28696)
		(end 116.596922 -284.288738)
		(width 0.1143)
		(layer "In11.Cu")
		(net "P5E_CPU1_P3_TX_DN<4>")
	)
	(segment
		(start 117.340126 -295.956228)
		(end 117.340126 -296.373042)
		(width 0.1143)
		(layer "In11.Cu")
		(net "P5E_CPU1_P3_TX_DN<4>")
	)
	(segment
		(start 116.587778 -286.558736)
		(end 116.6241 -286.579818)
		(width 0.1143)
		(layer "In11.Cu")
		(net "P5E_CPU1_P3_TX_DN<4>")
	)
	(segment
		(start 116.587016 -292.394132)
		(end 116.585746 -292.394894)
		(width 0.1143)
		(layer "In11.Cu")
		(net "P5E_CPU1_P3_TX_DN<4>")
	)
	(segment
		(start 117.714776 -279.756362)
		(end 117.416834 -279.756362)
		(width 0.1143)
		(layer "In11.Cu")
		(net "P5E_CPU1_P3_TX_DN<4>")
	)
	(segment
		(start 125.644148 -362.474256)
		(end 120.334024 -364.986062)
		(width 0.14224)
		(layer "In11.Cu")
		(net "P5E_CPU1_P3_TX_DN<4>")
	)
	(segment
		(start 116.597684 -281.04846)
		(end 116.556028 -281.072082)
		(width 0.1143)
		(layer "In11.Cu")
		(net "P5E_CPU1_P3_TX_DN<4>")
	)
	(segment
		(start 116.587778 -294.658796)
		(end 116.615718 -294.67683)
		(width 0.1143)
		(layer "In11.Cu")
		(net "P5E_CPU1_P3_TX_DN<4>")
	)
	(segment
		(start 116.604034 -284.28442)
		(end 116.603272 -284.284928)
		(width 0.1143)
		(layer "In11.Cu")
		(net "P5E_CPU1_P3_TX_DN<4>")
	)
	(segment
		(start 116.556028 -289.780472)
		(end 116.587016 -289.798252)
		(width 0.1143)
		(layer "In11.Cu")
		(net "P5E_CPU1_P3_TX_DN<4>")
	)
	(segment
		(start 116.556028 -293.020496)
		(end 116.587016 -293.038276)
		(width 0.1143)
		(layer "In11.Cu")
		(net "P5E_CPU1_P3_TX_DN<4>")
	)
	(segment
		(start 117.385846 -296.44721)
		(end 117.385846 -296.78503)
		(width 0.14224)
		(layer "In11.Cu")
		(net "P5E_CPU1_P3_TX_DN<4>")
	)
	(segment
		(start 116.587778 -290.773612)
		(end 116.587016 -290.77412)
		(width 0.1143)
		(layer "In11.Cu")
		(net "P5E_CPU1_P3_TX_DN<4>")
	)
	(segment
		(start 117.096794 -280.220928)
		(end 117.025928 -280.26233)
		(width 0.1143)
		(layer "In11.Cu")
		(net "P5E_CPU1_P3_TX_DN<4>")
	)
	(segment
		(start 117.381274 -297.506644)
		(end 118.661942 -301.72787)
		(width 0.14224)
		(layer "In11.Cu")
		(net "P5E_CPU1_P3_TX_DN<4>")
	)
	(segment
		(start 116.585746 -285.9151)
		(end 116.556028 -285.932118)
		(width 0.1143)
		(layer "In11.Cu")
		(net "P5E_CPU1_P3_TX_DN<4>")
	)
	(segment
		(start 116.585746 -294.657526)
		(end 116.587016 -294.658288)
		(width 0.1143)
		(layer "In11.Cu")
		(net "P5E_CPU1_P3_TX_DN<4>")
	)
	(segment
		(start 118.661942 -301.72787)
		(end 122.324622 -307.209698)
		(width 0.14224)
		(layer "In11.Cu")
		(net "P5E_CPU1_P3_TX_DN<4>")
	)
	(segment
		(start 116.869972 -280.563574)
		(end 116.869972 -280.566368)
		(width 0.1143)
		(layer "In11.Cu")
		(net "P5E_CPU1_P3_TX_DN<4>")
	)
	(segment
		(start 117.385846 -296.78503)
		(end 117.381274 -296.789602)
		(width 0.14224)
		(layer "In11.Cu")
		(net "P5E_CPU1_P3_TX_DN<4>")
	)
	(segment
		(start 116.577364 -284.933136)
		(end 116.580412 -284.934914)
		(width 0.1143)
		(layer "In11.Cu")
		(net "P5E_CPU1_P3_TX_DN<4>")
	)
	(segment
		(start 116.58346 -283.316426)
		(end 116.584222 -283.316934)
		(width 0.1143)
		(layer "In11.Cu")
		(net "P5E_CPU1_P3_TX_DN<4>")
	)
	(segment
		(start 116.585492 -294.65778)
		(end 116.585746 -294.657526)
		(width 0.1143)
		(layer "In11.Cu")
		(net "P5E_CPU1_P3_TX_DN<4>")
	)
	(segment
		(start 115.84051 -373.719344)
		(end 116.084096 -373.96293)
		(width 0.14224)
		(layer "In11.Cu")
		(net "P5E_CPU1_P3_TX_DN<4>")
	)
	(segment
		(start 116.606066 -284.28315)
		(end 116.604034 -284.28442)
		(width 0.1143)
		(layer "In11.Cu")
		(net "P5E_CPU1_P3_TX_DN<4>")
	)
	(arc
		(start 116.590826 -281.700732)
		(mid 116.870441 -282.18638)
		(end 116.590826 -282.672028)
		(width 0.1143)
		(layer "In11.Cu")
		(net "P5E_CPU1_P3_TX_DN<4>")
	)
	(arc
		(start 116.556028 -285.932118)
		(mid 116.441352 -286.065452)
		(end 116.400072 -286.23641)
		(width 0.1143)
		(layer "In11.Cu")
		(net "P5E_CPU1_P3_TX_DN<4>")
	)
	(arc
		(start 116.869972 -280.566368)
		(mid 116.80525 -280.829107)
		(end 116.625878 -281.031696)
		(width 0.1143)
		(layer "In11.Cu")
		(net "P5E_CPU1_P3_TX_DN<4>")
	)
	(arc
		(start 116.556028 -289.171888)
		(mid 116.4001 -289.47618)
		(end 116.556028 -289.780472)
		(width 0.1143)
		(layer "In11.Cu")
		(net "P5E_CPU1_P3_TX_DN<4>")
	)
	(arc
		(start 116.400072 -286.23641)
		(mid 116.440834 -286.406294)
		(end 116.55425 -286.539178)
		(width 0.1143)
		(layer "In11.Cu")
		(net "P5E_CPU1_P3_TX_DN<4>")
	)
	(arc
		(start 116.556028 -287.55213)
		(mid 116.441352 -287.685464)
		(end 116.400072 -287.856422)
		(width 0.1143)
		(layer "In11.Cu")
		(net "P5E_CPU1_P3_TX_DN<4>")
	)
	(arc
		(start 116.63934 -284.970728)
		(mid 116.864511 -285.426404)
		(end 116.63934 -285.88208)
		(width 0.1143)
		(layer "In11.Cu")
		(net "P5E_CPU1_P3_TX_DN<4>")
	)
	(arc
		(start 117.240558 -295.63568)
		(mid 117.314672 -295.788394)
		(end 117.340126 -295.956228)
		(width 0.1143)
		(layer "In11.Cu")
		(net "P5E_CPU1_P3_TX_DN<4>")
	)
	(arc
		(start 116.584222 -294.015668)
		(mid 116.400088 -294.33554)
		(end 116.582952 -294.656256)
		(width 0.1143)
		(layer "In11.Cu")
		(net "P5E_CPU1_P3_TX_DN<4>")
	)
	(arc
		(start 116.615718 -294.67683)
		(mid 116.802354 -294.879298)
		(end 116.869972 -295.146222)
		(width 0.1143)
		(layer "In11.Cu")
		(net "P5E_CPU1_P3_TX_DN<4>")
	)
	(arc
		(start 116.63934 -285.88208)
		(mid 116.631764 -285.887476)
		(end 116.6241 -285.892748)
		(width 0.1143)
		(layer "In11.Cu")
		(net "P5E_CPU1_P3_TX_DN<4>")
	)
	(arc
		(start 116.556028 -292.411912)
		(mid 116.4001 -292.716204)
		(end 116.556028 -293.020496)
		(width 0.1143)
		(layer "In11.Cu")
		(net "P5E_CPU1_P3_TX_DN<4>")
	)
	(arc
		(start 117.520466 -366.488218)
		(mid 116.258088 -367.690758)
		(end 115.793266 -369.371118)
		(width 0.14224)
		(layer "In11.Cu")
		(net "P5E_CPU1_P3_TX_DN<4>")
	)
	(arc
		(start 116.400072 -287.856422)
		(mid 116.440834 -288.026306)
		(end 116.55425 -288.15919)
		(width 0.1143)
		(layer "In11.Cu")
		(net "P5E_CPU1_P3_TX_DN<4>")
	)
	(arc
		(start 116.6241 -284.96006)
		(mid 116.631764 -284.965331)
		(end 116.63934 -284.970728)
		(width 0.1143)
		(layer "In11.Cu")
		(net "P5E_CPU1_P3_TX_DN<4>")
	)
	(arc
		(start 115.793266 -373.605298)
		(mid 115.805543 -373.667021)
		(end 115.84051 -373.719344)
		(width 0.14224)
		(layer "In11.Cu")
		(net "P5E_CPU1_P3_TX_DN<4>")
	)
	(arc
		(start 130.210306 -359.258108)
		(mid 128.06569 -361.062766)
		(end 125.644148 -362.474256)
		(width 0.14224)
		(layer "In11.Cu")
		(net "P5E_CPU1_P3_TX_DN<4>")
	)
	(arc
		(start 116.584476 -284.295596)
		(mid 116.400271 -284.612304)
		(end 116.577364 -284.933136)
		(width 0.1143)
		(layer "In11.Cu")
		(net "P5E_CPU1_P3_TX_DN<4>")
	)
	(arc
		(start 116.587778 -293.038784)
		(mid 116.868425 -293.52621)
		(end 116.587778 -294.013636)
		(width 0.1143)
		(layer "In11.Cu")
		(net "P5E_CPU1_P3_TX_DN<4>")
	)
	(arc
		(start 116.556028 -290.7919)
		(mid 116.4001 -291.096192)
		(end 116.556028 -291.400484)
		(width 0.1143)
		(layer "In11.Cu")
		(net "P5E_CPU1_P3_TX_DN<4>")
	)
	(arc
		(start 116.606066 -283.329634)
		(mid 116.880649 -283.806392)
		(end 116.606066 -284.28315)
		(width 0.1143)
		(layer "In11.Cu")
		(net "P5E_CPU1_P3_TX_DN<4>")
	)
	(arc
		(start 116.567712 -282.685236)
		(mid 116.389176 -282.995819)
		(end 116.566696 -283.307028)
		(width 0.1143)
		(layer "In11.Cu")
		(net "P5E_CPU1_P3_TX_DN<4>")
	)
	(arc
		(start 117.096794 -295.491662)
		(mid 117.175217 -295.557143)
		(end 117.240558 -295.63568)
		(width 0.1143)
		(layer "In11.Cu")
		(net "P5E_CPU1_P3_TX_DN<4>")
	)
	(arc
		(start 120.334024 -364.986062)
		(mid 120.28342 -365.010715)
		(end 120.23344 -365.036608)
		(width 0.14224)
		(layer "In11.Cu")
		(net "P5E_CPU1_P3_TX_DN<4>")
	)
	(arc
		(start 137.473436 -344.788236)
		(mid 137.392426 -345.610226)
		(end 137.152634 -346.400628)
		(width 0.14224)
		(layer "In11.Cu")
		(net "P5E_CPU1_P3_TX_DN<4>")
	)
	(arc
		(start 116.58854 -288.179256)
		(mid 116.868874 -288.666174)
		(end 116.58854 -289.153092)
		(width 0.1143)
		(layer "In11.Cu")
		(net "P5E_CPU1_P3_TX_DN<4>")
	)
	(arc
		(start 117.33022 -279.862026)
		(mid 117.248787 -280.064424)
		(end 117.096794 -280.220928)
		(width 0.1143)
		(layer "In11.Cu")
		(net "P5E_CPU1_P3_TX_DN<4>")
	)
	(arc
		(start 116.869972 -295.146222)
		(mid 116.911227 -295.317193)
		(end 117.025928 -295.450514)
		(width 0.1143)
		(layer "In11.Cu")
		(net "P5E_CPU1_P3_TX_DN<4>")
	)
	(arc
		(start 116.869972 -287.046162)
		(mid 116.79307 -287.305425)
		(end 116.621306 -287.514284)
		(width 0.1143)
		(layer "In11.Cu")
		(net "P5E_CPU1_P3_TX_DN<4>")
	)
	(arc
		(start 133.884162 -354.291646)
		(mid 132.774753 -356.367366)
		(end 131.281678 -358.186736)
		(width 0.14224)
		(layer "In11.Cu")
		(net "P5E_CPU1_P3_TX_DN<4>")
	)
	(arc
		(start 116.6241 -286.579818)
		(mid 116.630866 -286.584595)
		(end 116.637562 -286.58947)
		(width 0.1143)
		(layer "In11.Cu")
		(net "P5E_CPU1_P3_TX_DN<4>")
	)
	(arc
		(start 116.587778 -291.418772)
		(mid 116.868425 -291.906198)
		(end 116.587778 -292.393624)
		(width 0.1143)
		(layer "In11.Cu")
		(net "P5E_CPU1_P3_TX_DN<4>")
	)
	(arc
		(start 117.025928 -280.26233)
		(mid 116.9113 -280.393983)
		(end 116.869972 -280.563574)
		(width 0.1143)
		(layer "In11.Cu")
		(net "P5E_CPU1_P3_TX_DN<4>")
	)
	(arc
		(start 117.33403 -279.839166)
		(mid 117.332242 -279.850615)
		(end 117.33022 -279.862026)
		(width 0.1143)
		(layer "In11.Cu")
		(net "P5E_CPU1_P3_TX_DN<4>")
	)
	(arc
		(start 116.587778 -289.79876)
		(mid 116.868425 -290.286186)
		(end 116.587778 -290.773612)
		(width 0.1143)
		(layer "In11.Cu")
		(net "P5E_CPU1_P3_TX_DN<4>")
	)
	(arc
		(start 116.637562 -286.58947)
		(mid 116.808532 -286.789947)
		(end 116.869972 -287.046162)
		(width 0.1143)
		(layer "In11.Cu")
		(net "P5E_CPU1_P3_TX_DN<4>")
	)
	(arc
		(start 116.556028 -281.072082)
		(mid 116.4001 -281.376374)
		(end 116.556028 -281.680666)
		(width 0.1143)
		(layer "In11.Cu")
		(net "P5E_CPU1_P3_TX_DN<4>")
	)
	(segment
		(start 117.247924 -274.630388)
		(end 117.714776 -274.896326)
		(width 0.12954)
		(layer "F.Cu")
		(net "P5E_CPU1_P3_TX_DN<3>")
	)
	(segment
		(start 112.680496 -369.03533)
		(end 112.409986 -369.30584)
		(width 0.12954)
		(layer "F.Cu")
		(net "P5E_CPU1_P3_TX_DN<3>")
	)
	(segment
		(start 112.409986 -369.30584)
		(end 112.409986 -370.00942)
		(width 0.12954)
		(layer "F.Cu")
		(net "P5E_CPU1_P3_TX_DN<3>")
	)
	(segment
		(start 112.409986 -370.00942)
		(end 112.705896 -370.30533)
		(width 0.12954)
		(layer "F.Cu")
		(net "P5E_CPU1_P3_TX_DN<3>")
	)
	(segment
		(start 115.615974 -291.400484)
		(end 115.646962 -291.418264)
		(width 0.1143)
		(layer "In11.Cu")
		(net "P5E_CPU1_P3_TX_DN<3>")
	)
	(segment
		(start 115.614196 -286.539178)
		(end 115.647724 -286.558736)
		(width 0.1143)
		(layer "In11.Cu")
		(net "P5E_CPU1_P3_TX_DN<3>")
	)
	(segment
		(start 115.68684 -282.650946)
		(end 115.647724 -282.673806)
		(width 0.1143)
		(layer "In11.Cu")
		(net "P5E_CPU1_P3_TX_DN<3>")
	)
	(segment
		(start 116.353336 -365.806228)
		(end 114.13236 -366.993424)
		(width 0.14224)
		(layer "In11.Cu")
		(net "P5E_CPU1_P3_TX_DN<3>")
	)
	(segment
		(start 115.647724 -281.053794)
		(end 115.646962 -281.054302)
		(width 0.1143)
		(layer "In11.Cu")
		(net "P5E_CPU1_P3_TX_DN<3>")
	)
	(segment
		(start 116.117624 -277.648924)
		(end 116.15674 -277.671784)
		(width 0.1143)
		(layer "In11.Cu")
		(net "P5E_CPU1_P3_TX_DN<3>")
	)
	(segment
		(start 112.389666 -368.174016)
		(end 112.389666 -368.7445)
		(width 0.14224)
		(layer "In11.Cu")
		(net "P5E_CPU1_P3_TX_DN<3>")
	)
	(segment
		(start 116.400072 -295.95572)
		(end 116.400072 -296.373042)
		(width 0.1143)
		(layer "In11.Cu")
		(net "P5E_CPU1_P3_TX_DN<3>")
	)
	(segment
		(start 124.844556 -361.78998)
		(end 116.353336 -365.806228)
		(width 0.14224)
		(layer "In11.Cu")
		(net "P5E_CPU1_P3_TX_DN<3>")
	)
	(segment
		(start 115.650264 -289.800284)
		(end 115.68684 -289.82162)
		(width 0.1143)
		(layer "In11.Cu")
		(net "P5E_CPU1_P3_TX_DN<3>")
	)
	(segment
		(start 116.446554 -297.663362)
		(end 117.83187 -302.228758)
		(width 0.14224)
		(layer "In11.Cu")
		(net "P5E_CPU1_P3_TX_DN<3>")
	)
	(segment
		(start 115.645692 -284.295088)
		(end 115.615974 -284.312106)
		(width 0.1143)
		(layer "In11.Cu")
		(net "P5E_CPU1_P3_TX_DN<3>")
	)
	(segment
		(start 115.646962 -281.054302)
		(end 115.645692 -281.055064)
		(width 0.1143)
		(layer "In11.Cu")
		(net "P5E_CPU1_P3_TX_DN<3>")
	)
	(segment
		(start 115.646962 -284.93847)
		(end 115.647724 -284.938978)
		(width 0.1143)
		(layer "In11.Cu")
		(net "P5E_CPU1_P3_TX_DN<3>")
	)
	(segment
		(start 115.647724 -286.558736)
		(end 115.68684 -286.581596)
		(width 0.1143)
		(layer "In11.Cu")
		(net "P5E_CPU1_P3_TX_DN<3>")
	)
	(segment
		(start 136.533382 -341.232998)
		(end 136.533636 -341.234014)
		(width 0.14224)
		(layer "In11.Cu")
		(net "P5E_CPU1_P3_TX_DN<3>")
	)
	(segment
		(start 115.645692 -282.675076)
		(end 115.615974 -282.692094)
		(width 0.1143)
		(layer "In11.Cu")
		(net "P5E_CPU1_P3_TX_DN<3>")
	)
	(segment
		(start 115.650264 -294.66032)
		(end 115.68684 -294.681656)
		(width 0.1143)
		(layer "In11.Cu")
		(net "P5E_CPU1_P3_TX_DN<3>")
	)
	(segment
		(start 115.68684 -284.270958)
		(end 115.647724 -284.293818)
		(width 0.1143)
		(layer "In11.Cu")
		(net "P5E_CPU1_P3_TX_DN<3>")
	)
	(segment
		(start 115.645692 -294.014906)
		(end 115.615974 -294.031924)
		(width 0.1143)
		(layer "In11.Cu")
		(net "P5E_CPU1_P3_TX_DN<3>")
	)
	(segment
		(start 115.646962 -285.914338)
		(end 115.645692 -285.9151)
		(width 0.1143)
		(layer "In11.Cu")
		(net "P5E_CPU1_P3_TX_DN<3>")
	)
	(segment
		(start 113.370614 -367.45037)
		(end 112.446308 -368.068352)
		(width 0.14224)
		(layer "In11.Cu")
		(net "P5E_CPU1_P3_TX_DN<3>")
	)
	(segment
		(start 136.533636 -341.234014)
		(end 136.540748 -341.270844)
		(width 0.14224)
		(layer "In11.Cu")
		(net "P5E_CPU1_P3_TX_DN<3>")
	)
	(segment
		(start 130.886962 -357.191564)
		(end 129.72796 -358.350566)
		(width 0.14224)
		(layer "In11.Cu")
		(net "P5E_CPU1_P3_TX_DN<3>")
	)
	(segment
		(start 117.83187 -302.228758)
		(end 121.420128 -307.59908)
		(width 0.14224)
		(layer "In11.Cu")
		(net "P5E_CPU1_P3_TX_DN<3>")
	)
	(segment
		(start 128.759712 -316.542928)
		(end 131.467098 -320.594736)
		(width 0.14224)
		(layer "In11.Cu")
		(net "P5E_CPU1_P3_TX_DN<3>")
	)
	(segment
		(start 115.650264 -283.32049)
		(end 115.68684 -283.341826)
		(width 0.1143)
		(layer "In11.Cu")
		(net "P5E_CPU1_P3_TX_DN<3>")
	)
	(segment
		(start 115.64874 -289.799268)
		(end 115.650264 -289.800284)
		(width 0.1143)
		(layer "In11.Cu")
		(net "P5E_CPU1_P3_TX_DN<3>")
	)
	(segment
		(start 115.64874 -293.039292)
		(end 115.650264 -293.040308)
		(width 0.1143)
		(layer "In11.Cu")
		(net "P5E_CPU1_P3_TX_DN<3>")
	)
	(segment
		(start 133.316218 -325.05904)
		(end 136.533382 -341.232998)
		(width 0.14224)
		(layer "In11.Cu")
		(net "P5E_CPU1_P3_TX_DN<3>")
	)
	(segment
		(start 115.647724 -293.038784)
		(end 115.64874 -293.039292)
		(width 0.1143)
		(layer "In11.Cu")
		(net "P5E_CPU1_P3_TX_DN<3>")
	)
	(segment
		(start 115.646962 -291.418264)
		(end 115.647724 -291.418772)
		(width 0.1143)
		(layer "In11.Cu")
		(net "P5E_CPU1_P3_TX_DN<3>")
	)
	(segment
		(start 116.087144 -295.451022)
		(end 116.15674 -295.491662)
		(width 0.1143)
		(layer "In11.Cu")
		(net "P5E_CPU1_P3_TX_DN<3>")
	)
	(segment
		(start 115.650264 -281.700478)
		(end 115.68684 -281.721814)
		(width 0.1143)
		(layer "In11.Cu")
		(net "P5E_CPU1_P3_TX_DN<3>")
	)
	(segment
		(start 116.445792 -296.418762)
		(end 116.445792 -296.44721)
		(width 0.1143)
		(layer "In11.Cu")
		(net "P5E_CPU1_P3_TX_DN<3>")
	)
	(segment
		(start 115.68684 -285.89097)
		(end 115.647724 -285.91383)
		(width 0.1143)
		(layer "In11.Cu")
		(net "P5E_CPU1_P3_TX_DN<3>")
	)
	(segment
		(start 115.68684 -281.030934)
		(end 115.647724 -281.053794)
		(width 0.1143)
		(layer "In11.Cu")
		(net "P5E_CPU1_P3_TX_DN<3>")
	)
	(segment
		(start 131.467098 -320.594736)
		(end 133.316218 -325.05904)
		(width 0.14224)
		(layer "In11.Cu")
		(net "P5E_CPU1_P3_TX_DN<3>")
	)
	(segment
		(start 115.615974 -284.92069)
		(end 115.646962 -284.93847)
		(width 0.1143)
		(layer "In11.Cu")
		(net "P5E_CPU1_P3_TX_DN<3>")
	)
	(segment
		(start 136.540748 -341.270844)
		(end 136.540748 -344.477594)
		(width 0.14224)
		(layer "In11.Cu")
		(net "P5E_CPU1_P3_TX_DN<3>")
	)
	(segment
		(start 115.646962 -281.698446)
		(end 115.647724 -281.698954)
		(width 0.1143)
		(layer "In11.Cu")
		(net "P5E_CPU1_P3_TX_DN<3>")
	)
	(segment
		(start 115.647724 -284.293818)
		(end 115.646962 -284.294326)
		(width 0.1143)
		(layer "In11.Cu")
		(net "P5E_CPU1_P3_TX_DN<3>")
	)
	(segment
		(start 115.614196 -288.15919)
		(end 115.647724 -288.178748)
		(width 0.1143)
		(layer "In11.Cu")
		(net "P5E_CPU1_P3_TX_DN<3>")
	)
	(segment
		(start 115.646962 -293.038276)
		(end 115.647724 -293.038784)
		(width 0.1143)
		(layer "In11.Cu")
		(net "P5E_CPU1_P3_TX_DN<3>")
	)
	(segment
		(start 115.68684 -292.370764)
		(end 115.647724 -292.393624)
		(width 0.1143)
		(layer "In11.Cu")
		(net "P5E_CPU1_P3_TX_DN<3>")
	)
	(segment
		(start 115.615974 -293.020496)
		(end 115.646962 -293.038276)
		(width 0.1143)
		(layer "In11.Cu")
		(net "P5E_CPU1_P3_TX_DN<3>")
	)
	(segment
		(start 115.647724 -294.658796)
		(end 115.64874 -294.659304)
		(width 0.1143)
		(layer "In11.Cu")
		(net "P5E_CPU1_P3_TX_DN<3>")
	)
	(segment
		(start 116.62664 -276.165818)
		(end 116.556028 -276.206966)
		(width 0.1143)
		(layer "In11.Cu")
		(net "P5E_CPU1_P3_TX_DN<3>")
	)
	(segment
		(start 116.087144 -279.251156)
		(end 116.117624 -279.268936)
		(width 0.1143)
		(layer "In11.Cu")
		(net "P5E_CPU1_P3_TX_DN<3>")
	)
	(segment
		(start 116.157756 -276.975062)
		(end 116.084604 -277.018242)
		(width 0.1143)
		(layer "In11.Cu")
		(net "P5E_CPU1_P3_TX_DN<3>")
	)
	(segment
		(start 115.64874 -284.939486)
		(end 115.650264 -284.940502)
		(width 0.1143)
		(layer "In11.Cu")
		(net "P5E_CPU1_P3_TX_DN<3>")
	)
	(segment
		(start 115.615974 -294.640508)
		(end 115.646962 -294.658288)
		(width 0.1143)
		(layer "In11.Cu")
		(net "P5E_CPU1_P3_TX_DN<3>")
	)
	(segment
		(start 116.15674 -280.220928)
		(end 116.117624 -280.243788)
		(width 0.1143)
		(layer "In11.Cu")
		(net "P5E_CPU1_P3_TX_DN<3>")
	)
	(segment
		(start 116.15674 -278.600916)
		(end 116.117624 -278.623776)
		(width 0.1143)
		(layer "In11.Cu")
		(net "P5E_CPU1_P3_TX_DN<3>")
	)
	(segment
		(start 114.13236 -366.993424)
		(end 113.370614 -367.45037)
		(width 0.14224)
		(layer "In11.Cu")
		(net "P5E_CPU1_P3_TX_DN<3>")
	)
	(segment
		(start 115.647724 -282.673806)
		(end 115.646962 -282.674314)
		(width 0.1143)
		(layer "In11.Cu")
		(net "P5E_CPU1_P3_TX_DN<3>")
	)
	(segment
		(start 116.445792 -296.44721)
		(end 116.445792 -296.774362)
		(width 0.14224)
		(layer "In11.Cu")
		(net "P5E_CPU1_P3_TX_DN<3>")
	)
	(segment
		(start 115.650264 -284.940502)
		(end 115.68684 -284.961838)
		(width 0.1143)
		(layer "In11.Cu")
		(net "P5E_CPU1_P3_TX_DN<3>")
	)
	(segment
		(start 115.650264 -291.420296)
		(end 115.68684 -291.441632)
		(width 0.1143)
		(layer "In11.Cu")
		(net "P5E_CPU1_P3_TX_DN<3>")
	)
	(segment
		(start 115.647724 -287.533842)
		(end 115.615974 -287.55213)
		(width 0.1143)
		(layer "In11.Cu")
		(net "P5E_CPU1_P3_TX_DN<3>")
	)
	(segment
		(start 115.647724 -290.773612)
		(end 115.646962 -290.77412)
		(width 0.1143)
		(layer "In11.Cu")
		(net "P5E_CPU1_P3_TX_DN<3>")
	)
	(segment
		(start 115.647724 -281.698954)
		(end 115.64874 -281.699462)
		(width 0.1143)
		(layer "In11.Cu")
		(net "P5E_CPU1_P3_TX_DN<3>")
	)
	(segment
		(start 116.402358 -276.506178)
		(end 116.402358 -276.50948)
		(width 0.1143)
		(layer "In11.Cu")
		(net "P5E_CPU1_P3_TX_DN<3>")
	)
	(segment
		(start 115.64874 -281.699462)
		(end 115.650264 -281.700478)
		(width 0.1143)
		(layer "In11.Cu")
		(net "P5E_CPU1_P3_TX_DN<3>")
	)
	(segment
		(start 115.647724 -285.91383)
		(end 115.646962 -285.914338)
		(width 0.1143)
		(layer "In11.Cu")
		(net "P5E_CPU1_P3_TX_DN<3>")
	)
	(segment
		(start 115.647724 -289.1536)
		(end 115.646962 -289.154108)
		(width 0.1143)
		(layer "In11.Cu")
		(net "P5E_CPU1_P3_TX_DN<3>")
	)
	(segment
		(start 115.647724 -291.418772)
		(end 115.64874 -291.41928)
		(width 0.1143)
		(layer "In11.Cu")
		(net "P5E_CPU1_P3_TX_DN<3>")
	)
	(segment
		(start 115.645692 -285.9151)
		(end 115.615974 -285.932118)
		(width 0.1143)
		(layer "In11.Cu")
		(net "P5E_CPU1_P3_TX_DN<3>")
	)
	(segment
		(start 115.646962 -284.294326)
		(end 115.645692 -284.295088)
		(width 0.1143)
		(layer "In11.Cu")
		(net "P5E_CPU1_P3_TX_DN<3>")
	)
	(segment
		(start 115.645692 -289.15487)
		(end 115.615974 -289.171888)
		(width 0.1143)
		(layer "In11.Cu")
		(net "P5E_CPU1_P3_TX_DN<3>")
	)
	(segment
		(start 115.6843 -287.512506)
		(end 115.647724 -287.533842)
		(width 0.1143)
		(layer "In11.Cu")
		(net "P5E_CPU1_P3_TX_DN<3>")
	)
	(segment
		(start 115.646962 -292.394132)
		(end 115.645692 -292.394894)
		(width 0.1143)
		(layer "In11.Cu")
		(net "P5E_CPU1_P3_TX_DN<3>")
	)
	(segment
		(start 115.646962 -289.154108)
		(end 115.645692 -289.15487)
		(width 0.1143)
		(layer "In11.Cu")
		(net "P5E_CPU1_P3_TX_DN<3>")
	)
	(segment
		(start 115.645692 -290.774882)
		(end 115.615974 -290.7919)
		(width 0.1143)
		(layer "In11.Cu")
		(net "P5E_CPU1_P3_TX_DN<3>")
	)
	(segment
		(start 116.446554 -296.774362)
		(end 116.446554 -297.663362)
		(width 0.14224)
		(layer "In11.Cu")
		(net "P5E_CPU1_P3_TX_DN<3>")
	)
	(segment
		(start 115.615974 -283.300678)
		(end 115.646962 -283.318458)
		(width 0.1143)
		(layer "In11.Cu")
		(net "P5E_CPU1_P3_TX_DN<3>")
	)
	(segment
		(start 115.647724 -294.013636)
		(end 115.646962 -294.014144)
		(width 0.1143)
		(layer "In11.Cu")
		(net "P5E_CPU1_P3_TX_DN<3>")
	)
	(segment
		(start 115.647724 -289.79876)
		(end 115.64874 -289.799268)
		(width 0.1143)
		(layer "In11.Cu")
		(net "P5E_CPU1_P3_TX_DN<3>")
	)
	(segment
		(start 112.389666 -368.7445)
		(end 112.680496 -369.03533)
		(width 0.14224)
		(layer "In11.Cu")
		(net "P5E_CPU1_P3_TX_DN<3>")
	)
	(segment
		(start 117.714776 -274.896326)
		(end 117.416834 -274.896326)
		(width 0.1143)
		(layer "In11.Cu")
		(net "P5E_CPU1_P3_TX_DN<3>")
	)
	(segment
		(start 117.416834 -274.896326)
		(end 117.33403 -274.97913)
		(width 0.1143)
		(layer "In11.Cu")
		(net "P5E_CPU1_P3_TX_DN<3>")
	)
	(segment
		(start 115.68684 -293.990776)
		(end 115.647724 -294.013636)
		(width 0.1143)
		(layer "In11.Cu")
		(net "P5E_CPU1_P3_TX_DN<3>")
	)
	(segment
		(start 116.117624 -278.623776)
		(end 116.087144 -278.641556)
		(width 0.1143)
		(layer "In11.Cu")
		(net "P5E_CPU1_P3_TX_DN<3>")
	)
	(segment
		(start 121.420128 -307.59908)
		(end 128.759712 -316.542928)
		(width 0.14224)
		(layer "In11.Cu")
		(net "P5E_CPU1_P3_TX_DN<3>")
	)
	(segment
		(start 116.11356 -277.646384)
		(end 116.117624 -277.648924)
		(width 0.1143)
		(layer "In11.Cu")
		(net "P5E_CPU1_P3_TX_DN<3>")
	)
	(segment
		(start 115.646962 -294.658288)
		(end 115.647724 -294.658796)
		(width 0.1143)
		(layer "In11.Cu")
		(net "P5E_CPU1_P3_TX_DN<3>")
	)
	(segment
		(start 115.615974 -289.780472)
		(end 115.647724 -289.79876)
		(width 0.1143)
		(layer "In11.Cu")
		(net "P5E_CPU1_P3_TX_DN<3>")
	)
	(segment
		(start 115.68684 -289.13074)
		(end 115.647724 -289.1536)
		(width 0.1143)
		(layer "In11.Cu")
		(net "P5E_CPU1_P3_TX_DN<3>")
	)
	(segment
		(start 115.64874 -294.659304)
		(end 115.650264 -294.66032)
		(width 0.1143)
		(layer "In11.Cu")
		(net "P5E_CPU1_P3_TX_DN<3>")
	)
	(segment
		(start 115.645692 -292.394894)
		(end 115.615974 -292.411912)
		(width 0.1143)
		(layer "In11.Cu")
		(net "P5E_CPU1_P3_TX_DN<3>")
	)
	(segment
		(start 115.646962 -282.674314)
		(end 115.645692 -282.675076)
		(width 0.1143)
		(layer "In11.Cu")
		(net "P5E_CPU1_P3_TX_DN<3>")
	)
	(segment
		(start 115.68684 -290.750752)
		(end 115.647724 -290.773612)
		(width 0.1143)
		(layer "In11.Cu")
		(net "P5E_CPU1_P3_TX_DN<3>")
	)
	(segment
		(start 115.647724 -292.393624)
		(end 115.646962 -292.394132)
		(width 0.1143)
		(layer "In11.Cu")
		(net "P5E_CPU1_P3_TX_DN<3>")
	)
	(segment
		(start 116.445792 -296.774362)
		(end 116.446554 -296.774362)
		(width 0.14224)
		(layer "In11.Cu")
		(net "P5E_CPU1_P3_TX_DN<3>")
	)
	(segment
		(start 116.400072 -296.373042)
		(end 116.445792 -296.418762)
		(width 0.1143)
		(layer "In11.Cu")
		(net "P5E_CPU1_P3_TX_DN<3>")
	)
	(segment
		(start 116.117624 -279.268936)
		(end 116.15674 -279.291796)
		(width 0.1143)
		(layer "In11.Cu")
		(net "P5E_CPU1_P3_TX_DN<3>")
	)
	(segment
		(start 115.650264 -293.040308)
		(end 115.68684 -293.061644)
		(width 0.1143)
		(layer "In11.Cu")
		(net "P5E_CPU1_P3_TX_DN<3>")
	)
	(segment
		(start 115.647724 -288.178748)
		(end 115.68684 -288.201608)
		(width 0.1143)
		(layer "In11.Cu")
		(net "P5E_CPU1_P3_TX_DN<3>")
	)
	(segment
		(start 116.117624 -280.243788)
		(end 116.087144 -280.261568)
		(width 0.1143)
		(layer "In11.Cu")
		(net "P5E_CPU1_P3_TX_DN<3>")
	)
	(segment
		(start 117.096794 -275.360892)
		(end 117.053614 -275.386038)
		(width 0.1143)
		(layer "In11.Cu")
		(net "P5E_CPU1_P3_TX_DN<3>")
	)
	(segment
		(start 115.647724 -284.938978)
		(end 115.64874 -284.939486)
		(width 0.1143)
		(layer "In11.Cu")
		(net "P5E_CPU1_P3_TX_DN<3>")
	)
	(segment
		(start 115.645692 -281.055064)
		(end 115.615974 -281.072082)
		(width 0.1143)
		(layer "In11.Cu")
		(net "P5E_CPU1_P3_TX_DN<3>")
	)
	(segment
		(start 115.64874 -291.41928)
		(end 115.650264 -291.420296)
		(width 0.1143)
		(layer "In11.Cu")
		(net "P5E_CPU1_P3_TX_DN<3>")
	)
	(segment
		(start 115.646962 -294.014144)
		(end 115.645692 -294.014906)
		(width 0.1143)
		(layer "In11.Cu")
		(net "P5E_CPU1_P3_TX_DN<3>")
	)
	(segment
		(start 136.212834 -346.126308)
		(end 132.840984 -354.267262)
		(width 0.14224)
		(layer "In11.Cu")
		(net "P5E_CPU1_P3_TX_DN<3>")
	)
	(segment
		(start 115.615974 -281.680666)
		(end 115.646962 -281.698446)
		(width 0.1143)
		(layer "In11.Cu")
		(net "P5E_CPU1_P3_TX_DN<3>")
	)
	(segment
		(start 115.64874 -283.319474)
		(end 115.650264 -283.32049)
		(width 0.1143)
		(layer "In11.Cu")
		(net "P5E_CPU1_P3_TX_DN<3>")
	)
	(segment
		(start 115.647724 -283.318966)
		(end 115.64874 -283.319474)
		(width 0.1143)
		(layer "In11.Cu")
		(net "P5E_CPU1_P3_TX_DN<3>")
	)
	(segment
		(start 115.646962 -290.77412)
		(end 115.645692 -290.774882)
		(width 0.1143)
		(layer "In11.Cu")
		(net "P5E_CPU1_P3_TX_DN<3>")
	)
	(segment
		(start 115.646962 -283.318458)
		(end 115.647724 -283.318966)
		(width 0.1143)
		(layer "In11.Cu")
		(net "P5E_CPU1_P3_TX_DN<3>")
	)
	(arc
		(start 136.540748 -344.477594)
		(mid 136.457977 -345.318099)
		(end 136.212834 -346.126308)
		(width 0.14224)
		(layer "In11.Cu")
		(net "P5E_CPU1_P3_TX_DN<3>")
	)
	(arc
		(start 115.930172 -280.566368)
		(mid 115.865657 -280.828587)
		(end 115.68684 -281.030934)
		(width 0.1143)
		(layer "In11.Cu")
		(net "P5E_CPU1_P3_TX_DN<3>")
	)
	(arc
		(start 115.615974 -294.031924)
		(mid 115.460046 -294.336216)
		(end 115.615974 -294.640508)
		(width 0.1143)
		(layer "In11.Cu")
		(net "P5E_CPU1_P3_TX_DN<3>")
	)
	(arc
		(start 116.15674 -279.291796)
		(mid 116.400067 -279.756362)
		(end 116.15674 -280.220928)
		(width 0.1143)
		(layer "In11.Cu")
		(net "P5E_CPU1_P3_TX_DN<3>")
	)
	(arc
		(start 115.615974 -281.072082)
		(mid 115.460046 -281.376374)
		(end 115.615974 -281.680666)
		(width 0.1143)
		(layer "In11.Cu")
		(net "P5E_CPU1_P3_TX_DN<3>")
	)
	(arc
		(start 115.615974 -284.312106)
		(mid 115.460046 -284.616398)
		(end 115.615974 -284.92069)
		(width 0.1143)
		(layer "In11.Cu")
		(net "P5E_CPU1_P3_TX_DN<3>")
	)
	(arc
		(start 116.402358 -276.50948)
		(mid 116.33754 -276.772469)
		(end 116.157756 -276.975062)
		(width 0.1143)
		(layer "In11.Cu")
		(net "P5E_CPU1_P3_TX_DN<3>")
	)
	(arc
		(start 116.087144 -278.641556)
		(mid 115.930167 -278.946356)
		(end 116.087144 -279.251156)
		(width 0.1143)
		(layer "In11.Cu")
		(net "P5E_CPU1_P3_TX_DN<3>")
	)
	(arc
		(start 117.33403 -274.97913)
		(mid 117.332242 -274.990579)
		(end 117.33022 -275.00199)
		(width 0.1143)
		(layer "In11.Cu")
		(net "P5E_CPU1_P3_TX_DN<3>")
	)
	(arc
		(start 115.615974 -282.692094)
		(mid 115.460046 -282.996386)
		(end 115.615974 -283.300678)
		(width 0.1143)
		(layer "In11.Cu")
		(net "P5E_CPU1_P3_TX_DN<3>")
	)
	(arc
		(start 116.084604 -277.018242)
		(mid 115.928022 -277.340237)
		(end 116.11356 -277.646384)
		(width 0.1143)
		(layer "In11.Cu")
		(net "P5E_CPU1_P3_TX_DN<3>")
	)
	(arc
		(start 115.615974 -287.55213)
		(mid 115.501298 -287.685464)
		(end 115.460018 -287.856422)
		(width 0.1143)
		(layer "In11.Cu")
		(net "P5E_CPU1_P3_TX_DN<3>")
	)
	(arc
		(start 115.460018 -287.856422)
		(mid 115.50078 -288.026306)
		(end 115.614196 -288.15919)
		(width 0.1143)
		(layer "In11.Cu")
		(net "P5E_CPU1_P3_TX_DN<3>")
	)
	(arc
		(start 115.930172 -287.046162)
		(mid 115.864936 -287.309753)
		(end 115.6843 -287.512506)
		(width 0.1143)
		(layer "In11.Cu")
		(net "P5E_CPU1_P3_TX_DN<3>")
	)
	(arc
		(start 115.68684 -293.061644)
		(mid 115.930167 -293.52621)
		(end 115.68684 -293.990776)
		(width 0.1143)
		(layer "In11.Cu")
		(net "P5E_CPU1_P3_TX_DN<3>")
	)
	(arc
		(start 116.556028 -276.206966)
		(mid 116.442995 -276.337986)
		(end 116.402358 -276.506178)
		(width 0.1143)
		(layer "In11.Cu")
		(net "P5E_CPU1_P3_TX_DN<3>")
	)
	(arc
		(start 115.68684 -286.581596)
		(mid 115.865653 -286.783946)
		(end 115.930172 -287.046162)
		(width 0.1143)
		(layer "In11.Cu")
		(net "P5E_CPU1_P3_TX_DN<3>")
	)
	(arc
		(start 115.68684 -288.201608)
		(mid 115.930167 -288.666174)
		(end 115.68684 -289.13074)
		(width 0.1143)
		(layer "In11.Cu")
		(net "P5E_CPU1_P3_TX_DN<3>")
	)
	(arc
		(start 132.840984 -354.267262)
		(mid 132.007981 -355.825639)
		(end 130.886962 -357.191564)
		(width 0.14224)
		(layer "In11.Cu")
		(net "P5E_CPU1_P3_TX_DN<3>")
	)
	(arc
		(start 116.15674 -295.491662)
		(mid 116.335497 -295.693755)
		(end 116.400072 -295.95572)
		(width 0.1143)
		(layer "In11.Cu")
		(net "P5E_CPU1_P3_TX_DN<3>")
	)
	(arc
		(start 115.460018 -286.23641)
		(mid 115.50078 -286.406294)
		(end 115.614196 -286.539178)
		(width 0.1143)
		(layer "In11.Cu")
		(net "P5E_CPU1_P3_TX_DN<3>")
	)
	(arc
		(start 116.087144 -280.261568)
		(mid 115.971717 -280.394944)
		(end 115.930172 -280.566368)
		(width 0.1143)
		(layer "In11.Cu")
		(net "P5E_CPU1_P3_TX_DN<3>")
	)
	(arc
		(start 116.872512 -275.699474)
		(mid 116.807276 -275.963065)
		(end 116.62664 -276.165818)
		(width 0.1143)
		(layer "In11.Cu")
		(net "P5E_CPU1_P3_TX_DN<3>")
	)
	(arc
		(start 129.72796 -358.350566)
		(mid 127.434345 -360.280534)
		(end 124.844556 -361.78998)
		(width 0.14224)
		(layer "In11.Cu")
		(net "P5E_CPU1_P3_TX_DN<3>")
	)
	(arc
		(start 115.615974 -289.171888)
		(mid 115.460046 -289.47618)
		(end 115.615974 -289.780472)
		(width 0.1143)
		(layer "In11.Cu")
		(net "P5E_CPU1_P3_TX_DN<3>")
	)
	(arc
		(start 115.615974 -285.932118)
		(mid 115.501298 -286.065452)
		(end 115.460018 -286.23641)
		(width 0.1143)
		(layer "In11.Cu")
		(net "P5E_CPU1_P3_TX_DN<3>")
	)
	(arc
		(start 115.68684 -281.721814)
		(mid 115.930167 -282.18638)
		(end 115.68684 -282.650946)
		(width 0.1143)
		(layer "In11.Cu")
		(net "P5E_CPU1_P3_TX_DN<3>")
	)
	(arc
		(start 115.68684 -289.82162)
		(mid 115.930167 -290.286186)
		(end 115.68684 -290.750752)
		(width 0.1143)
		(layer "In11.Cu")
		(net "P5E_CPU1_P3_TX_DN<3>")
	)
	(arc
		(start 115.68684 -284.961838)
		(mid 115.930167 -285.426404)
		(end 115.68684 -285.89097)
		(width 0.1143)
		(layer "In11.Cu")
		(net "P5E_CPU1_P3_TX_DN<3>")
	)
	(arc
		(start 115.615974 -290.7919)
		(mid 115.460046 -291.096192)
		(end 115.615974 -291.400484)
		(width 0.1143)
		(layer "In11.Cu")
		(net "P5E_CPU1_P3_TX_DN<3>")
	)
	(arc
		(start 115.68684 -294.681656)
		(mid 115.865653 -294.884006)
		(end 115.930172 -295.146222)
		(width 0.1143)
		(layer "In11.Cu")
		(net "P5E_CPU1_P3_TX_DN<3>")
	)
	(arc
		(start 115.930172 -295.146222)
		(mid 115.971721 -295.317644)
		(end 116.087144 -295.451022)
		(width 0.1143)
		(layer "In11.Cu")
		(net "P5E_CPU1_P3_TX_DN<3>")
	)
	(arc
		(start 115.68684 -283.341826)
		(mid 115.930167 -283.806392)
		(end 115.68684 -284.270958)
		(width 0.1143)
		(layer "In11.Cu")
		(net "P5E_CPU1_P3_TX_DN<3>")
	)
	(arc
		(start 117.33022 -275.00199)
		(mid 117.248787 -275.204388)
		(end 117.096794 -275.360892)
		(width 0.1143)
		(layer "In11.Cu")
		(net "P5E_CPU1_P3_TX_DN<3>")
	)
	(arc
		(start 117.053614 -275.386038)
		(mid 116.921011 -275.518466)
		(end 116.872512 -275.699474)
		(width 0.1143)
		(layer "In11.Cu")
		(net "P5E_CPU1_P3_TX_DN<3>")
	)
	(arc
		(start 112.446308 -368.068352)
		(mid 112.404745 -368.114092)
		(end 112.389666 -368.174016)
		(width 0.14224)
		(layer "In11.Cu")
		(net "P5E_CPU1_P3_TX_DN<3>")
	)
	(arc
		(start 115.68684 -291.441632)
		(mid 115.930167 -291.906198)
		(end 115.68684 -292.370764)
		(width 0.1143)
		(layer "In11.Cu")
		(net "P5E_CPU1_P3_TX_DN<3>")
	)
	(arc
		(start 115.615974 -292.411912)
		(mid 115.460046 -292.716204)
		(end 115.615974 -293.020496)
		(width 0.1143)
		(layer "In11.Cu")
		(net "P5E_CPU1_P3_TX_DN<3>")
	)
	(arc
		(start 116.15674 -277.671784)
		(mid 116.400067 -278.13635)
		(end 116.15674 -278.600916)
		(width 0.1143)
		(layer "In11.Cu")
		(net "P5E_CPU1_P3_TX_DN<3>")
	)
	(segment
		(start 114.897916 -278.680418)
		(end 115.364768 -278.946356)
		(width 0.12954)
		(layer "F.Cu")
		(net "P5E_CPU1_P3_TX_DN<2>")
	)
	(segment
		(start 110.708186 -371.76964)
		(end 110.708186 -372.47322)
		(width 0.12954)
		(layer "F.Cu")
		(net "P5E_CPU1_P3_TX_DN<2>")
	)
	(segment
		(start 110.978696 -371.49913)
		(end 110.708186 -371.76964)
		(width 0.12954)
		(layer "F.Cu")
		(net "P5E_CPU1_P3_TX_DN<2>")
	)
	(segment
		(start 110.708186 -372.47322)
		(end 111.004096 -372.76913)
		(width 0.12954)
		(layer "F.Cu")
		(net "P5E_CPU1_P3_TX_DN<2>")
	)
	(segment
		(start 114.744246 -287.512506)
		(end 114.70767 -287.533842)
		(width 0.1143)
		(layer "In11.Cu")
		(net "P5E_CPU1_P3_TX_DN<2>")
	)
	(segment
		(start 114.70767 -292.393624)
		(end 114.706908 -292.394132)
		(width 0.1143)
		(layer "In11.Cu")
		(net "P5E_CPU1_P3_TX_DN<2>")
	)
	(segment
		(start 117.38864 -364.193582)
		(end 113.171986 -366.447324)
		(width 0.14224)
		(layer "In11.Cu")
		(net "P5E_CPU1_P3_TX_DN<2>")
	)
	(segment
		(start 114.674142 -288.15919)
		(end 114.746786 -288.201608)
		(width 0.1143)
		(layer "In11.Cu")
		(net "P5E_CPU1_P3_TX_DN<2>")
	)
	(segment
		(start 114.74704 -293.061644)
		(end 114.769138 -293.077392)
		(width 0.1143)
		(layer "In11.Cu")
		(net "P5E_CPU1_P3_TX_DN<2>")
	)
	(segment
		(start 115.505738 -296.788586)
		(end 115.50523 -296.789094)
		(width 0.14224)
		(layer "In11.Cu")
		(net "P5E_CPU1_P3_TX_DN<2>")
	)
	(segment
		(start 114.699034 -283.31414)
		(end 114.7064 -283.318204)
		(width 0.1143)
		(layer "In11.Cu")
		(net "P5E_CPU1_P3_TX_DN<2>")
	)
	(segment
		(start 114.746786 -279.410922)
		(end 114.702082 -279.437084)
		(width 0.1143)
		(layer "In11.Cu")
		(net "P5E_CPU1_P3_TX_DN<2>")
	)
	(segment
		(start 115.14709 -295.451022)
		(end 115.17757 -295.468802)
		(width 0.1143)
		(layer "In11.Cu")
		(net "P5E_CPU1_P3_TX_DN<2>")
	)
	(segment
		(start 114.67592 -293.020496)
		(end 114.706908 -293.038276)
		(width 0.1143)
		(layer "In11.Cu")
		(net "P5E_CPU1_P3_TX_DN<2>")
	)
	(segment
		(start 114.74704 -281.030934)
		(end 114.69624 -281.060144)
		(width 0.1143)
		(layer "In11.Cu")
		(net "P5E_CPU1_P3_TX_DN<2>")
	)
	(segment
		(start 114.70767 -291.418772)
		(end 114.746786 -291.441632)
		(width 0.1143)
		(layer "In11.Cu")
		(net "P5E_CPU1_P3_TX_DN<2>")
	)
	(segment
		(start 114.702082 -284.935676)
		(end 114.746024 -284.96133)
		(width 0.1143)
		(layer "In11.Cu")
		(net "P5E_CPU1_P3_TX_DN<2>")
	)
	(segment
		(start 114.690652 -294.649144)
		(end 114.746024 -294.681148)
		(width 0.1143)
		(layer "In11.Cu")
		(net "P5E_CPU1_P3_TX_DN<2>")
	)
	(segment
		(start 114.746786 -292.370764)
		(end 114.70767 -292.393624)
		(width 0.1143)
		(layer "In11.Cu")
		(net "P5E_CPU1_P3_TX_DN<2>")
	)
	(segment
		(start 114.701066 -294.005)
		(end 114.700558 -294.005254)
		(width 0.1143)
		(layer "In11.Cu")
		(net "P5E_CPU1_P3_TX_DN<2>")
	)
	(segment
		(start 114.70767 -293.038784)
		(end 114.708686 -293.039292)
		(width 0.1143)
		(layer "In11.Cu")
		(net "P5E_CPU1_P3_TX_DN<2>")
	)
	(segment
		(start 110.68177 -368.918744)
		(end 110.68177 -371.202204)
		(width 0.14224)
		(layer "In11.Cu")
		(net "P5E_CPU1_P3_TX_DN<2>")
	)
	(segment
		(start 114.70767 -290.773612)
		(end 114.67592 -290.7919)
		(width 0.1143)
		(layer "In11.Cu")
		(net "P5E_CPU1_P3_TX_DN<2>")
	)
	(segment
		(start 110.68177 -371.202204)
		(end 110.978696 -371.49913)
		(width 0.14224)
		(layer "In11.Cu")
		(net "P5E_CPU1_P3_TX_DN<2>")
	)
	(segment
		(start 115.17757 -295.468802)
		(end 115.216686 -295.491662)
		(width 0.1143)
		(layer "In11.Cu")
		(net "P5E_CPU1_P3_TX_DN<2>")
	)
	(segment
		(start 114.705384 -285.914846)
		(end 114.70386 -285.915862)
		(width 0.1143)
		(layer "In11.Cu")
		(net "P5E_CPU1_P3_TX_DN<2>")
	)
	(segment
		(start 115.364768 -278.946356)
		(end 115.066826 -278.946356)
		(width 0.1143)
		(layer "In11.Cu")
		(net "P5E_CPU1_P3_TX_DN<2>")
	)
	(segment
		(start 135.221726 -345.539314)
		(end 131.460494 -354.620322)
		(width 0.14224)
		(layer "In11.Cu")
		(net "P5E_CPU1_P3_TX_DN<2>")
	)
	(segment
		(start 114.703352 -292.396164)
		(end 114.702336 -292.396672)
		(width 0.1143)
		(layer "In11.Cu")
		(net "P5E_CPU1_P3_TX_DN<2>")
	)
	(segment
		(start 115.505738 -296.418762)
		(end 115.505738 -296.44721)
		(width 0.1143)
		(layer "In11.Cu")
		(net "P5E_CPU1_P3_TX_DN<2>")
	)
	(segment
		(start 114.700812 -284.935168)
		(end 114.702082 -284.935676)
		(width 0.1143)
		(layer "In11.Cu")
		(net "P5E_CPU1_P3_TX_DN<2>")
	)
	(segment
		(start 111.01705 -368.038126)
		(end 110.800896 -368.443002)
		(width 0.14224)
		(layer "In11.Cu")
		(net "P5E_CPU1_P3_TX_DN<2>")
	)
	(segment
		(start 130.148838 -356.583234)
		(end 129.346706 -357.385366)
		(width 0.14224)
		(layer "In11.Cu")
		(net "P5E_CPU1_P3_TX_DN<2>")
	)
	(segment
		(start 114.519964 -287.853374)
		(end 114.519964 -287.856422)
		(width 0.1143)
		(layer "In11.Cu")
		(net "P5E_CPU1_P3_TX_DN<2>")
	)
	(segment
		(start 114.71021 -293.040308)
		(end 114.711226 -293.040816)
		(width 0.1143)
		(layer "In11.Cu")
		(net "P5E_CPU1_P3_TX_DN<2>")
	)
	(segment
		(start 114.703606 -286.556958)
		(end 114.705892 -286.558228)
		(width 0.1143)
		(layer "In11.Cu")
		(net "P5E_CPU1_P3_TX_DN<2>")
	)
	(segment
		(start 115.50523 -297.82516)
		(end 116.960142 -302.62068)
		(width 0.14224)
		(layer "In11.Cu")
		(net "P5E_CPU1_P3_TX_DN<2>")
	)
	(segment
		(start 114.7064 -283.318204)
		(end 114.70894 -283.319728)
		(width 0.1143)
		(layer "In11.Cu")
		(net "P5E_CPU1_P3_TX_DN<2>")
	)
	(segment
		(start 114.700558 -292.397688)
		(end 114.67592 -292.411912)
		(width 0.1143)
		(layer "In11.Cu")
		(net "P5E_CPU1_P3_TX_DN<2>")
	)
	(segment
		(start 114.73942 -283.337508)
		(end 114.746024 -283.341318)
		(width 0.1143)
		(layer "In11.Cu")
		(net "P5E_CPU1_P3_TX_DN<2>")
	)
	(segment
		(start 114.77498 -281.010868)
		(end 114.74704 -281.030934)
		(width 0.1143)
		(layer "In11.Cu")
		(net "P5E_CPU1_P3_TX_DN<2>")
	)
	(segment
		(start 114.705638 -292.394894)
		(end 114.704114 -292.395656)
		(width 0.1143)
		(layer "In11.Cu")
		(net "P5E_CPU1_P3_TX_DN<2>")
	)
	(segment
		(start 114.746786 -290.750752)
		(end 114.70767 -290.773612)
		(width 0.1143)
		(layer "In11.Cu")
		(net "P5E_CPU1_P3_TX_DN<2>")
	)
	(segment
		(start 114.70767 -289.1536)
		(end 114.67592 -289.171888)
		(width 0.1143)
		(layer "In11.Cu")
		(net "P5E_CPU1_P3_TX_DN<2>")
	)
	(segment
		(start 114.710464 -283.320744)
		(end 114.738658 -283.337)
		(width 0.1143)
		(layer "In11.Cu")
		(net "P5E_CPU1_P3_TX_DN<2>")
	)
	(segment
		(start 114.748818 -285.8897)
		(end 114.705384 -285.914846)
		(width 0.1143)
		(layer "In11.Cu")
		(net "P5E_CPU1_P3_TX_DN<2>")
	)
	(segment
		(start 128.215644 -317.406782)
		(end 130.638804 -321.033394)
		(width 0.14224)
		(layer "In11.Cu")
		(net "P5E_CPU1_P3_TX_DN<2>")
	)
	(segment
		(start 114.746786 -284.961838)
		(end 114.748818 -284.963108)
		(width 0.1143)
		(layer "In11.Cu")
		(net "P5E_CPU1_P3_TX_DN<2>")
	)
	(segment
		(start 114.710718 -280.08072)
		(end 114.71148 -280.081228)
		(width 0.1143)
		(layer "In11.Cu")
		(net "P5E_CPU1_P3_TX_DN<2>")
	)
	(segment
		(start 114.71148 -280.081228)
		(end 114.747294 -280.101802)
		(width 0.1143)
		(layer "In11.Cu")
		(net "P5E_CPU1_P3_TX_DN<2>")
	)
	(segment
		(start 114.748818 -286.58312)
		(end 114.748818 -286.582866)
		(width 0.1143)
		(layer "In11.Cu")
		(net "P5E_CPU1_P3_TX_DN<2>")
	)
	(segment
		(start 114.746786 -289.13074)
		(end 114.70767 -289.1536)
		(width 0.1143)
		(layer "In11.Cu")
		(net "P5E_CPU1_P3_TX_DN<2>")
	)
	(segment
		(start 114.70767 -287.533842)
		(end 114.67592 -287.55213)
		(width 0.1143)
		(layer "In11.Cu")
		(net "P5E_CPU1_P3_TX_DN<2>")
	)
	(segment
		(start 114.708686 -293.039292)
		(end 114.71021 -293.040308)
		(width 0.1143)
		(layer "In11.Cu")
		(net "P5E_CPU1_P3_TX_DN<2>")
	)
	(segment
		(start 114.69624 -281.692604)
		(end 114.746024 -281.721306)
		(width 0.1143)
		(layer "In11.Cu")
		(net "P5E_CPU1_P3_TX_DN<2>")
	)
	(segment
		(start 116.960142 -302.62068)
		(end 120.812814 -308.386734)
		(width 0.14224)
		(layer "In11.Cu")
		(net "P5E_CPU1_P3_TX_DN<2>")
	)
	(segment
		(start 114.67592 -291.400484)
		(end 114.70767 -291.418772)
		(width 0.1143)
		(layer "In11.Cu")
		(net "P5E_CPU1_P3_TX_DN<2>")
	)
	(segment
		(start 115.460018 -296.373042)
		(end 115.505738 -296.418762)
		(width 0.1143)
		(layer "In11.Cu")
		(net "P5E_CPU1_P3_TX_DN<2>")
	)
	(segment
		(start 124.36475 -360.894122)
		(end 117.38864 -364.193582)
		(width 0.14224)
		(layer "In11.Cu")
		(net "P5E_CPU1_P3_TX_DN<2>")
	)
	(segment
		(start 114.738658 -283.337)
		(end 114.73942 -283.337508)
		(width 0.1143)
		(layer "In11.Cu")
		(net "P5E_CPU1_P3_TX_DN<2>")
	)
	(segment
		(start 114.711226 -293.040816)
		(end 114.713766 -293.04234)
		(width 0.1143)
		(layer "In11.Cu")
		(net "P5E_CPU1_P3_TX_DN<2>")
	)
	(segment
		(start 114.67592 -287.55213)
		(end 114.673126 -287.554162)
		(width 0.1143)
		(layer "In11.Cu")
		(net "P5E_CPU1_P3_TX_DN<2>")
	)
	(segment
		(start 130.638804 -321.033394)
		(end 132.398008 -325.280528)
		(width 0.14224)
		(layer "In11.Cu")
		(net "P5E_CPU1_P3_TX_DN<2>")
	)
	(segment
		(start 114.67592 -289.780472)
		(end 114.746786 -289.82162)
		(width 0.1143)
		(layer "In11.Cu")
		(net "P5E_CPU1_P3_TX_DN<2>")
	)
	(segment
		(start 113.171986 -366.447324)
		(end 111.36376 -367.655602)
		(width 0.14224)
		(layer "In11.Cu")
		(net "P5E_CPU1_P3_TX_DN<2>")
	)
	(segment
		(start 135.5979 -341.367872)
		(end 135.5979 -343.648284)
		(width 0.14224)
		(layer "In11.Cu")
		(net "P5E_CPU1_P3_TX_DN<2>")
	)
	(segment
		(start 114.700812 -280.075132)
		(end 114.702082 -280.07564)
		(width 0.1143)
		(layer "In11.Cu")
		(net "P5E_CPU1_P3_TX_DN<2>")
	)
	(segment
		(start 114.705892 -286.558228)
		(end 114.748818 -286.58312)
		(width 0.1143)
		(layer "In11.Cu")
		(net "P5E_CPU1_P3_TX_DN<2>")
	)
	(segment
		(start 114.746786 -284.270958)
		(end 114.702082 -284.29712)
		(width 0.1143)
		(layer "In11.Cu")
		(net "P5E_CPU1_P3_TX_DN<2>")
	)
	(segment
		(start 114.704114 -292.395656)
		(end 114.703352 -292.396164)
		(width 0.1143)
		(layer "In11.Cu")
		(net "P5E_CPU1_P3_TX_DN<2>")
	)
	(segment
		(start 115.066826 -278.946356)
		(end 114.984022 -279.02916)
		(width 0.1143)
		(layer "In11.Cu")
		(net "P5E_CPU1_P3_TX_DN<2>")
	)
	(segment
		(start 114.706908 -292.394132)
		(end 114.705638 -292.394894)
		(width 0.1143)
		(layer "In11.Cu")
		(net "P5E_CPU1_P3_TX_DN<2>")
	)
	(segment
		(start 114.671602 -289.777424)
		(end 114.67592 -289.780472)
		(width 0.1143)
		(layer "In11.Cu")
		(net "P5E_CPU1_P3_TX_DN<2>")
	)
	(segment
		(start 120.812814 -308.386734)
		(end 128.215644 -317.406782)
		(width 0.14224)
		(layer "In11.Cu")
		(net "P5E_CPU1_P3_TX_DN<2>")
	)
	(segment
		(start 114.7064 -282.674568)
		(end 114.699034 -282.678632)
		(width 0.1143)
		(layer "In11.Cu")
		(net "P5E_CPU1_P3_TX_DN<2>")
	)
	(segment
		(start 114.67592 -289.171888)
		(end 114.671602 -289.174936)
		(width 0.1143)
		(layer "In11.Cu")
		(net "P5E_CPU1_P3_TX_DN<2>")
	)
	(segment
		(start 114.71529 -293.043356)
		(end 114.74704 -293.061644)
		(width 0.1143)
		(layer "In11.Cu")
		(net "P5E_CPU1_P3_TX_DN<2>")
	)
	(segment
		(start 114.723418 -293.992046)
		(end 114.701066 -294.005)
		(width 0.1143)
		(layer "In11.Cu")
		(net "P5E_CPU1_P3_TX_DN<2>")
	)
	(segment
		(start 114.702082 -284.29712)
		(end 114.700812 -284.297628)
		(width 0.1143)
		(layer "In11.Cu")
		(net "P5E_CPU1_P3_TX_DN<2>")
	)
	(segment
		(start 114.702082 -280.07564)
		(end 114.710718 -280.08072)
		(width 0.1143)
		(layer "In11.Cu")
		(net "P5E_CPU1_P3_TX_DN<2>")
	)
	(segment
		(start 115.50523 -296.789094)
		(end 115.50523 -297.82516)
		(width 0.14224)
		(layer "In11.Cu")
		(net "P5E_CPU1_P3_TX_DN<2>")
	)
	(segment
		(start 114.702336 -292.396672)
		(end 114.701574 -292.39718)
		(width 0.1143)
		(layer "In11.Cu")
		(net "P5E_CPU1_P3_TX_DN<2>")
	)
	(segment
		(start 114.746786 -282.650946)
		(end 114.7064 -282.674568)
		(width 0.1143)
		(layer "In11.Cu")
		(net "P5E_CPU1_P3_TX_DN<2>")
	)
	(segment
		(start 114.701574 -292.39718)
		(end 114.700558 -292.397688)
		(width 0.1143)
		(layer "In11.Cu")
		(net "P5E_CPU1_P3_TX_DN<2>")
	)
	(segment
		(start 114.702082 -279.437084)
		(end 114.700812 -279.437592)
		(width 0.1143)
		(layer "In11.Cu")
		(net "P5E_CPU1_P3_TX_DN<2>")
	)
	(segment
		(start 114.713766 -293.04234)
		(end 114.71529 -293.043356)
		(width 0.1143)
		(layer "In11.Cu")
		(net "P5E_CPU1_P3_TX_DN<2>")
	)
	(segment
		(start 114.700558 -294.005254)
		(end 114.671094 -294.025066)
		(width 0.1143)
		(layer "In11.Cu")
		(net "P5E_CPU1_P3_TX_DN<2>")
	)
	(segment
		(start 114.747294 -280.101802)
		(end 114.77498 -280.121868)
		(width 0.1143)
		(layer "In11.Cu")
		(net "P5E_CPU1_P3_TX_DN<2>")
	)
	(segment
		(start 115.505738 -296.44721)
		(end 115.505738 -296.788586)
		(width 0.14224)
		(layer "In11.Cu")
		(net "P5E_CPU1_P3_TX_DN<2>")
	)
	(segment
		(start 132.398008 -325.280528)
		(end 135.5979 -341.367872)
		(width 0.14224)
		(layer "In11.Cu")
		(net "P5E_CPU1_P3_TX_DN<2>")
	)
	(segment
		(start 114.70894 -283.319728)
		(end 114.710464 -283.320744)
		(width 0.1143)
		(layer "In11.Cu")
		(net "P5E_CPU1_P3_TX_DN<2>")
	)
	(segment
		(start 115.460018 -295.956228)
		(end 115.460018 -296.373042)
		(width 0.1143)
		(layer "In11.Cu")
		(net "P5E_CPU1_P3_TX_DN<2>")
	)
	(segment
		(start 114.706908 -293.038276)
		(end 114.70767 -293.038784)
		(width 0.1143)
		(layer "In11.Cu")
		(net "P5E_CPU1_P3_TX_DN<2>")
	)
	(arc
		(start 114.746024 -294.681148)
		(mid 114.746405 -294.681402)
		(end 114.746786 -294.681656)
		(width 0.1143)
		(layer "In11.Cu")
		(net "P5E_CPU1_P3_TX_DN<2>")
	)
	(arc
		(start 114.67592 -290.7919)
		(mid 114.526823 -291.096192)
		(end 114.67592 -291.400484)
		(width 0.1143)
		(layer "In11.Cu")
		(net "P5E_CPU1_P3_TX_DN<2>")
	)
	(arc
		(start 114.70386 -285.915862)
		(mid 114.520103 -286.2363)
		(end 114.703606 -286.556958)
		(width 0.1143)
		(layer "In11.Cu")
		(net "P5E_CPU1_P3_TX_DN<2>")
	)
	(arc
		(start 114.746024 -283.341318)
		(mid 114.746405 -283.341572)
		(end 114.746786 -283.341826)
		(width 0.1143)
		(layer "In11.Cu")
		(net "P5E_CPU1_P3_TX_DN<2>")
	)
	(arc
		(start 111.36376 -367.655602)
		(mid 111.166818 -367.825485)
		(end 111.01705 -368.038126)
		(width 0.14224)
		(layer "In11.Cu")
		(net "P5E_CPU1_P3_TX_DN<2>")
	)
	(arc
		(start 114.69624 -281.060144)
		(mid 114.514449 -281.376374)
		(end 114.69624 -281.692604)
		(width 0.1143)
		(layer "In11.Cu")
		(net "P5E_CPU1_P3_TX_DN<2>")
	)
	(arc
		(start 114.699034 -282.678632)
		(mid 114.516557 -282.996386)
		(end 114.699034 -283.31414)
		(width 0.1143)
		(layer "In11.Cu")
		(net "P5E_CPU1_P3_TX_DN<2>")
	)
	(arc
		(start 114.769138 -293.077392)
		(mid 114.995339 -293.54712)
		(end 114.723418 -293.992046)
		(width 0.1143)
		(layer "In11.Cu")
		(net "P5E_CPU1_P3_TX_DN<2>")
	)
	(arc
		(start 114.746786 -288.201608)
		(mid 114.990113 -288.666174)
		(end 114.746786 -289.13074)
		(width 0.1143)
		(layer "In11.Cu")
		(net "P5E_CPU1_P3_TX_DN<2>")
	)
	(arc
		(start 114.671094 -294.025066)
		(mid 114.507431 -294.342595)
		(end 114.690652 -294.649144)
		(width 0.1143)
		(layer "In11.Cu")
		(net "P5E_CPU1_P3_TX_DN<2>")
	)
	(arc
		(start 114.748818 -284.963108)
		(mid 114.991538 -285.426404)
		(end 114.748818 -285.8897)
		(width 0.1143)
		(layer "In11.Cu")
		(net "P5E_CPU1_P3_TX_DN<2>")
	)
	(arc
		(start 114.984022 -279.02916)
		(mid 114.982234 -279.040609)
		(end 114.980212 -279.05202)
		(width 0.1143)
		(layer "In11.Cu")
		(net "P5E_CPU1_P3_TX_DN<2>")
	)
	(arc
		(start 114.746786 -294.681656)
		(mid 114.925599 -294.884006)
		(end 114.990118 -295.146222)
		(width 0.1143)
		(layer "In11.Cu")
		(net "P5E_CPU1_P3_TX_DN<2>")
	)
	(arc
		(start 131.460494 -354.620322)
		(mid 130.90134 -355.666378)
		(end 130.148838 -356.583234)
		(width 0.14224)
		(layer "In11.Cu")
		(net "P5E_CPU1_P3_TX_DN<2>")
	)
	(arc
		(start 115.216686 -295.491662)
		(mid 115.395561 -295.69398)
		(end 115.460018 -295.956228)
		(width 0.1143)
		(layer "In11.Cu")
		(net "P5E_CPU1_P3_TX_DN<2>")
	)
	(arc
		(start 135.5979 -343.648284)
		(mid 135.502955 -344.61233)
		(end 135.221726 -345.539314)
		(width 0.14224)
		(layer "In11.Cu")
		(net "P5E_CPU1_P3_TX_DN<2>")
	)
	(arc
		(start 114.746024 -284.96133)
		(mid 114.746405 -284.961584)
		(end 114.746786 -284.961838)
		(width 0.1143)
		(layer "In11.Cu")
		(net "P5E_CPU1_P3_TX_DN<2>")
	)
	(arc
		(start 114.980212 -279.05202)
		(mid 114.898779 -279.254418)
		(end 114.746786 -279.410922)
		(width 0.1143)
		(layer "In11.Cu")
		(net "P5E_CPU1_P3_TX_DN<2>")
	)
	(arc
		(start 114.673126 -287.554162)
		(mid 114.560485 -287.685298)
		(end 114.519964 -287.853374)
		(width 0.1143)
		(layer "In11.Cu")
		(net "P5E_CPU1_P3_TX_DN<2>")
	)
	(arc
		(start 114.519964 -287.856422)
		(mid 114.560726 -288.026306)
		(end 114.674142 -288.15919)
		(width 0.1143)
		(layer "In11.Cu")
		(net "P5E_CPU1_P3_TX_DN<2>")
	)
	(arc
		(start 110.800896 -368.443002)
		(mid 110.712015 -368.673531)
		(end 110.68177 -368.918744)
		(width 0.14224)
		(layer "In11.Cu")
		(net "P5E_CPU1_P3_TX_DN<2>")
	)
	(arc
		(start 129.346706 -357.385366)
		(mid 127.006793 -359.354233)
		(end 124.36475 -360.894122)
		(width 0.14224)
		(layer "In11.Cu")
		(net "P5E_CPU1_P3_TX_DN<2>")
	)
	(arc
		(start 114.67592 -292.411912)
		(mid 114.519992 -292.716204)
		(end 114.67592 -293.020496)
		(width 0.1143)
		(layer "In11.Cu")
		(net "P5E_CPU1_P3_TX_DN<2>")
	)
	(arc
		(start 114.746786 -289.82162)
		(mid 114.990113 -290.286186)
		(end 114.746786 -290.750752)
		(width 0.1143)
		(layer "In11.Cu")
		(net "P5E_CPU1_P3_TX_DN<2>")
	)
	(arc
		(start 114.746024 -281.721306)
		(mid 114.746405 -281.72156)
		(end 114.746786 -281.721814)
		(width 0.1143)
		(layer "In11.Cu")
		(net "P5E_CPU1_P3_TX_DN<2>")
	)
	(arc
		(start 114.748818 -286.582866)
		(mid 114.990116 -287.048909)
		(end 114.744246 -287.512506)
		(width 0.1143)
		(layer "In11.Cu")
		(net "P5E_CPU1_P3_TX_DN<2>")
	)
	(arc
		(start 114.671602 -289.174936)
		(mid 114.517197 -289.47618)
		(end 114.671602 -289.777424)
		(width 0.1143)
		(layer "In11.Cu")
		(net "P5E_CPU1_P3_TX_DN<2>")
	)
	(arc
		(start 114.77498 -280.121868)
		(mid 115.002668 -280.566368)
		(end 114.77498 -281.010868)
		(width 0.1143)
		(layer "In11.Cu")
		(net "P5E_CPU1_P3_TX_DN<2>")
	)
	(arc
		(start 114.700812 -284.297628)
		(mid 114.520327 -284.616398)
		(end 114.700812 -284.935168)
		(width 0.1143)
		(layer "In11.Cu")
		(net "P5E_CPU1_P3_TX_DN<2>")
	)
	(arc
		(start 114.990118 -295.146222)
		(mid 115.031667 -295.317644)
		(end 115.14709 -295.451022)
		(width 0.1143)
		(layer "In11.Cu")
		(net "P5E_CPU1_P3_TX_DN<2>")
	)
	(arc
		(start 114.700812 -279.437592)
		(mid 114.520327 -279.756362)
		(end 114.700812 -280.075132)
		(width 0.1143)
		(layer "In11.Cu")
		(net "P5E_CPU1_P3_TX_DN<2>")
	)
	(arc
		(start 114.746786 -291.441632)
		(mid 114.990113 -291.906198)
		(end 114.746786 -292.370764)
		(width 0.1143)
		(layer "In11.Cu")
		(net "P5E_CPU1_P3_TX_DN<2>")
	)
	(arc
		(start 114.746786 -281.721814)
		(mid 114.990113 -282.18638)
		(end 114.746786 -282.650946)
		(width 0.1143)
		(layer "In11.Cu")
		(net "P5E_CPU1_P3_TX_DN<2>")
	)
	(arc
		(start 114.746786 -283.341826)
		(mid 114.990113 -283.806392)
		(end 114.746786 -284.270958)
		(width 0.1143)
		(layer "In11.Cu")
		(net "P5E_CPU1_P3_TX_DN<2>")
	)
	(segment
		(start 108.530644 -376.83186)
		(end 108.801154 -376.56135)
		(width 0.12954)
		(layer "F.Cu")
		(net "P5E_CPU1_P3_TX_DN<1>")
	)
	(segment
		(start 108.801154 -376.56135)
		(end 109.504734 -376.56135)
		(width 0.12954)
		(layer "F.Cu")
		(net "P5E_CPU1_P3_TX_DN<1>")
	)
	(segment
		(start 114.897916 -277.060406)
		(end 115.364768 -277.326344)
		(width 0.12954)
		(layer "F.Cu")
		(net "P5E_CPU1_P3_TX_DN<1>")
	)
	(segment
		(start 109.504734 -376.56135)
		(end 109.800644 -376.85726)
		(width 0.12954)
		(layer "F.Cu")
		(net "P5E_CPU1_P3_TX_DN<1>")
	)
	(segment
		(start 113.73612 -286.540448)
		(end 113.806732 -286.581596)
		(width 0.1143)
		(layer "In11.Cu")
		(net "P5E_CPU1_P3_TX_DN<1>")
	)
	(segment
		(start 113.771426 -293.04107)
		(end 113.80597 -293.061136)
		(width 0.1143)
		(layer "In11.Cu")
		(net "P5E_CPU1_P3_TX_DN<1>")
	)
	(segment
		(start 113.787174 -289.141662)
		(end 113.786666 -289.141916)
		(width 0.1143)
		(layer "In11.Cu")
		(net "P5E_CPU1_P3_TX_DN<1>")
	)
	(segment
		(start 129.784602 -321.433444)
		(end 131.484624 -325.537068)
		(width 0.14224)
		(layer "In11.Cu")
		(net "P5E_CPU1_P3_TX_DN<1>")
	)
	(segment
		(start 125.219206 -358.838754)
		(end 122.734832 -360.576114)
		(width 0.14224)
		(layer "In11.Cu")
		(net "P5E_CPU1_P3_TX_DN<1>")
	)
	(segment
		(start 113.767616 -289.79876)
		(end 113.806732 -289.82162)
		(width 0.1143)
		(layer "In11.Cu")
		(net "P5E_CPU1_P3_TX_DN<1>")
	)
	(segment
		(start 109.745526 -376.54103)
		(end 108.821474 -376.54103)
		(width 0.14224)
		(layer "In11.Cu")
		(net "P5E_CPU1_P3_TX_DN<1>")
	)
	(segment
		(start 114.565684 -297.953176)
		(end 116.10086 -303.013364)
		(width 0.14224)
		(layer "In11.Cu")
		(net "P5E_CPU1_P3_TX_DN<1>")
	)
	(segment
		(start 114.237516 -295.468802)
		(end 114.276632 -295.491662)
		(width 0.1143)
		(layer "In11.Cu")
		(net "P5E_CPU1_P3_TX_DN<1>")
	)
	(segment
		(start 117.69852 -362.95838)
		(end 112.604296 -365.681514)
		(width 0.14224)
		(layer "In11.Cu")
		(net "P5E_CPU1_P3_TX_DN<1>")
	)
	(segment
		(start 115.364768 -277.326344)
		(end 115.066826 -277.326344)
		(width 0.1143)
		(layer "In11.Cu")
		(net "P5E_CPU1_P3_TX_DN<1>")
	)
	(segment
		(start 113.76533 -282.67533)
		(end 113.764314 -282.675838)
		(width 0.1143)
		(layer "In11.Cu")
		(net "P5E_CPU1_P3_TX_DN<1>")
	)
	(segment
		(start 114.252756 -278.615394)
		(end 114.248946 -278.61768)
		(width 0.1143)
		(layer "In11.Cu")
		(net "P5E_CPU1_P3_TX_DN<1>")
	)
	(segment
		(start 113.767616 -279.433782)
		(end 113.74247 -279.448768)
		(width 0.1143)
		(layer "In11.Cu")
		(net "P5E_CPU1_P3_TX_DN<1>")
	)
	(segment
		(start 114.519964 -296.373042)
		(end 114.565684 -296.418762)
		(width 0.1143)
		(layer "In11.Cu")
		(net "P5E_CPU1_P3_TX_DN<1>")
	)
	(segment
		(start 131.484624 -325.537068)
		(end 134.649464 -341.448898)
		(width 0.14224)
		(layer "In11.Cu")
		(net "P5E_CPU1_P3_TX_DN<1>")
	)
	(segment
		(start 114.565684 -296.44721)
		(end 114.565684 -297.953176)
		(width 0.14224)
		(layer "In11.Cu")
		(net "P5E_CPU1_P3_TX_DN<1>")
	)
	(segment
		(start 108.842302 -371.64772)
		(end 108.842302 -372.470172)
		(width 0.14224)
		(layer "In11.Cu")
		(net "P5E_CPU1_P3_TX_DN<1>")
	)
	(segment
		(start 113.737136 -291.400992)
		(end 113.767616 -291.418772)
		(width 0.1143)
		(layer "In11.Cu")
		(net "P5E_CPU1_P3_TX_DN<1>")
	)
	(segment
		(start 113.806732 -293.990776)
		(end 113.767616 -294.013636)
		(width 0.1143)
		(layer "In11.Cu")
		(net "P5E_CPU1_P3_TX_DN<1>")
	)
	(segment
		(start 125.218952 -358.838754)
		(end 125.219206 -358.838754)
		(width 0.14224)
		(layer "In11.Cu")
		(net "P5E_CPU1_P3_TX_DN<1>")
	)
	(segment
		(start 134.657338 -341.528908)
		(end 134.657338 -343.223342)
		(width 0.14224)
		(layer "In11.Cu")
		(net "P5E_CPU1_P3_TX_DN<1>")
	)
	(segment
		(start 114.252756 -278.61514)
		(end 114.252756 -278.615394)
		(width 0.1143)
		(layer "In11.Cu")
		(net "P5E_CPU1_P3_TX_DN<1>")
	)
	(segment
		(start 109.051344 -372.97487)
		(end 110.087156 -374.010682)
		(width 0.14224)
		(layer "In11.Cu")
		(net "P5E_CPU1_P3_TX_DN<1>")
	)
	(segment
		(start 113.786666 -289.141916)
		(end 113.772188 -289.151314)
		(width 0.1143)
		(layer "In11.Cu")
		(net "P5E_CPU1_P3_TX_DN<1>")
	)
	(segment
		(start 112.604296 -365.681514)
		(end 111.088932 -366.589564)
		(width 0.14224)
		(layer "In11.Cu")
		(net "P5E_CPU1_P3_TX_DN<1>")
	)
	(segment
		(start 113.76406 -283.316934)
		(end 113.76533 -283.317442)
		(width 0.1143)
		(layer "In11.Cu")
		(net "P5E_CPU1_P3_TX_DN<1>")
	)
	(segment
		(start 114.248946 -278.61768)
		(end 114.20602 -278.642064)
		(width 0.1143)
		(layer "In11.Cu")
		(net "P5E_CPU1_P3_TX_DN<1>")
	)
	(segment
		(start 113.762028 -293.035482)
		(end 113.770664 -293.040562)
		(width 0.1143)
		(layer "In11.Cu")
		(net "P5E_CPU1_P3_TX_DN<1>")
	)
	(segment
		(start 134.331202 -344.862912)
		(end 130.30835 -354.575618)
		(width 0.14224)
		(layer "In11.Cu")
		(net "P5E_CPU1_P3_TX_DN<1>")
	)
	(segment
		(start 120.156478 -309.082948)
		(end 127.559562 -318.103504)
		(width 0.14224)
		(layer "In11.Cu")
		(net "P5E_CPU1_P3_TX_DN<1>")
	)
	(segment
		(start 113.804192 -287.512506)
		(end 113.740184 -287.54959)
		(width 0.1143)
		(layer "In11.Cu")
		(net "P5E_CPU1_P3_TX_DN<1>")
	)
	(segment
		(start 122.734832 -360.576114)
		(end 117.69852 -362.95838)
		(width 0.14224)
		(layer "In11.Cu")
		(net "P5E_CPU1_P3_TX_DN<1>")
	)
	(segment
		(start 114.565684 -296.418762)
		(end 114.565684 -296.44721)
		(width 0.1143)
		(layer "In11.Cu")
		(net "P5E_CPU1_P3_TX_DN<1>")
	)
	(segment
		(start 113.76406 -281.696922)
		(end 113.76533 -281.69743)
		(width 0.1143)
		(layer "In11.Cu")
		(net "P5E_CPU1_P3_TX_DN<1>")
	)
	(segment
		(start 113.768886 -282.673044)
		(end 113.76533 -282.67533)
		(width 0.1143)
		(layer "In11.Cu")
		(net "P5E_CPU1_P3_TX_DN<1>")
	)
	(segment
		(start 113.767616 -289.1536)
		(end 113.737136 -289.17138)
		(width 0.1143)
		(layer "In11.Cu")
		(net "P5E_CPU1_P3_TX_DN<1>")
	)
	(segment
		(start 113.760758 -293.034974)
		(end 113.762028 -293.035482)
		(width 0.1143)
		(layer "In11.Cu")
		(net "P5E_CPU1_P3_TX_DN<1>")
	)
	(segment
		(start 108.821474 -376.54103)
		(end 108.530644 -376.83186)
		(width 0.14224)
		(layer "In11.Cu")
		(net "P5E_CPU1_P3_TX_DN<1>")
	)
	(segment
		(start 113.806732 -292.370764)
		(end 113.762028 -292.396926)
		(width 0.1143)
		(layer "In11.Cu")
		(net "P5E_CPU1_P3_TX_DN<1>")
	)
	(segment
		(start 113.735612 -280.060146)
		(end 113.767616 -280.078942)
		(width 0.1143)
		(layer "In11.Cu")
		(net "P5E_CPU1_P3_TX_DN<1>")
	)
	(segment
		(start 113.767616 -294.658796)
		(end 113.806732 -294.681656)
		(width 0.1143)
		(layer "In11.Cu")
		(net "P5E_CPU1_P3_TX_DN<1>")
	)
	(segment
		(start 113.806732 -284.270958)
		(end 113.768632 -284.29331)
		(width 0.1143)
		(layer "In11.Cu")
		(net "P5E_CPU1_P3_TX_DN<1>")
	)
	(segment
		(start 113.580164 -286.222694)
		(end 113.580164 -286.239204)
		(width 0.1143)
		(layer "In11.Cu")
		(net "P5E_CPU1_P3_TX_DN<1>")
	)
	(segment
		(start 113.759742 -284.934152)
		(end 113.805208 -284.960822)
		(width 0.1143)
		(layer "In11.Cu")
		(net "P5E_CPU1_P3_TX_DN<1>")
	)
	(segment
		(start 113.806732 -282.650946)
		(end 113.768886 -282.673044)
		(width 0.1143)
		(layer "In11.Cu")
		(net "P5E_CPU1_P3_TX_DN<1>")
	)
	(segment
		(start 110.207044 -374.299988)
		(end 110.207044 -376.079512)
		(width 0.14224)
		(layer "In11.Cu")
		(net "P5E_CPU1_P3_TX_DN<1>")
	)
	(segment
		(start 114.519964 -278.133556)
		(end 114.519964 -278.13635)
		(width 0.1143)
		(layer "In11.Cu")
		(net "P5E_CPU1_P3_TX_DN<1>")
	)
	(segment
		(start 113.737136 -289.78098)
		(end 113.767616 -289.79876)
		(width 0.1143)
		(layer "In11.Cu")
		(net "P5E_CPU1_P3_TX_DN<1>")
	)
	(segment
		(start 113.76533 -281.69743)
		(end 113.768886 -281.699716)
		(width 0.1143)
		(layer "In11.Cu")
		(net "P5E_CPU1_P3_TX_DN<1>")
	)
	(segment
		(start 113.806732 -281.030934)
		(end 113.768886 -281.053032)
		(width 0.1143)
		(layer "In11.Cu")
		(net "P5E_CPU1_P3_TX_DN<1>")
	)
	(segment
		(start 113.737136 -294.641016)
		(end 113.767616 -294.658796)
		(width 0.1143)
		(layer "In11.Cu")
		(net "P5E_CPU1_P3_TX_DN<1>")
	)
	(segment
		(start 113.767616 -294.013636)
		(end 113.737136 -294.031416)
		(width 0.1143)
		(layer "In11.Cu")
		(net "P5E_CPU1_P3_TX_DN<1>")
	)
	(segment
		(start 109.660182 -368.173508)
		(end 109.416088 -368.763042)
		(width 0.14224)
		(layer "In11.Cu")
		(net "P5E_CPU1_P3_TX_DN<1>")
	)
	(segment
		(start 113.768632 -284.29331)
		(end 113.76787 -284.293818)
		(width 0.1143)
		(layer "In11.Cu")
		(net "P5E_CPU1_P3_TX_DN<1>")
	)
	(segment
		(start 113.737644 -288.161476)
		(end 113.773712 -288.182304)
		(width 0.1143)
		(layer "In11.Cu")
		(net "P5E_CPU1_P3_TX_DN<1>")
	)
	(segment
		(start 113.772188 -289.15106)
		(end 113.767616 -289.1536)
		(width 0.1143)
		(layer "In11.Cu")
		(net "P5E_CPU1_P3_TX_DN<1>")
	)
	(segment
		(start 113.806732 -285.89097)
		(end 113.73612 -285.932372)
		(width 0.1143)
		(layer "In11.Cu")
		(net "P5E_CPU1_P3_TX_DN<1>")
	)
	(segment
		(start 113.772188 -289.151314)
		(end 113.772188 -289.15106)
		(width 0.1143)
		(layer "In11.Cu")
		(net "P5E_CPU1_P3_TX_DN<1>")
	)
	(segment
		(start 113.806732 -290.750752)
		(end 113.767616 -290.773612)
		(width 0.1143)
		(layer "In11.Cu")
		(net "P5E_CPU1_P3_TX_DN<1>")
	)
	(segment
		(start 113.770664 -293.040562)
		(end 113.771426 -293.04107)
		(width 0.1143)
		(layer "In11.Cu")
		(net "P5E_CPU1_P3_TX_DN<1>")
	)
	(segment
		(start 113.768886 -283.319728)
		(end 113.805208 -283.34081)
		(width 0.1143)
		(layer "In11.Cu")
		(net "P5E_CPU1_P3_TX_DN<1>")
	)
	(segment
		(start 113.767616 -291.418772)
		(end 113.806732 -291.441632)
		(width 0.1143)
		(layer "In11.Cu")
		(net "P5E_CPU1_P3_TX_DN<1>")
	)
	(segment
		(start 113.768886 -281.699716)
		(end 113.805208 -281.720798)
		(width 0.1143)
		(layer "In11.Cu")
		(net "P5E_CPU1_P3_TX_DN<1>")
	)
	(segment
		(start 113.767616 -290.773612)
		(end 113.737136 -290.791392)
		(width 0.1143)
		(layer "In11.Cu")
		(net "P5E_CPU1_P3_TX_DN<1>")
	)
	(segment
		(start 116.10086 -303.013364)
		(end 120.156478 -309.082948)
		(width 0.14224)
		(layer "In11.Cu")
		(net "P5E_CPU1_P3_TX_DN<1>")
	)
	(segment
		(start 113.767616 -280.078942)
		(end 113.806732 -280.101802)
		(width 0.1143)
		(layer "In11.Cu")
		(net "P5E_CPU1_P3_TX_DN<1>")
	)
	(segment
		(start 114.27587 -278.601678)
		(end 114.252756 -278.61514)
		(width 0.1143)
		(layer "In11.Cu")
		(net "P5E_CPU1_P3_TX_DN<1>")
	)
	(segment
		(start 113.806732 -279.410922)
		(end 113.767616 -279.433782)
		(width 0.1143)
		(layer "In11.Cu")
		(net "P5E_CPU1_P3_TX_DN<1>")
	)
	(segment
		(start 110.087156 -376.368818)
		(end 110.034832 -376.421142)
		(width 0.14224)
		(layer "In11.Cu")
		(net "P5E_CPU1_P3_TX_DN<1>")
	)
	(segment
		(start 114.746786 -277.79091)
		(end 114.67592 -277.832312)
		(width 0.1143)
		(layer "In11.Cu")
		(net "P5E_CPU1_P3_TX_DN<1>")
	)
	(segment
		(start 113.768886 -281.053032)
		(end 113.76533 -281.055318)
		(width 0.1143)
		(layer "In11.Cu")
		(net "P5E_CPU1_P3_TX_DN<1>")
	)
	(segment
		(start 113.76533 -281.055318)
		(end 113.764314 -281.055826)
		(width 0.1143)
		(layer "In11.Cu")
		(net "P5E_CPU1_P3_TX_DN<1>")
	)
	(segment
		(start 114.207036 -295.451022)
		(end 114.237516 -295.468802)
		(width 0.1143)
		(layer "In11.Cu")
		(net "P5E_CPU1_P3_TX_DN<1>")
	)
	(segment
		(start 127.559562 -318.103504)
		(end 129.784602 -321.433444)
		(width 0.14224)
		(layer "In11.Cu")
		(net "P5E_CPU1_P3_TX_DN<1>")
	)
	(segment
		(start 110.6043 -366.96777)
		(end 110.186978 -367.385092)
		(width 0.14224)
		(layer "In11.Cu")
		(net "P5E_CPU1_P3_TX_DN<1>")
	)
	(segment
		(start 115.066826 -277.326344)
		(end 114.984022 -277.409148)
		(width 0.1143)
		(layer "In11.Cu")
		(net "P5E_CPU1_P3_TX_DN<1>")
	)
	(segment
		(start 130.21437 -354.743512)
		(end 129.402332 -355.863906)
		(width 0.14224)
		(layer "In11.Cu")
		(net "P5E_CPU1_P3_TX_DN<1>")
	)
	(segment
		(start 114.519964 -295.956228)
		(end 114.519964 -296.373042)
		(width 0.1143)
		(layer "In11.Cu")
		(net "P5E_CPU1_P3_TX_DN<1>")
	)
	(segment
		(start 113.76533 -283.317442)
		(end 113.768886 -283.319728)
		(width 0.1143)
		(layer "In11.Cu")
		(net "P5E_CPU1_P3_TX_DN<1>")
	)
	(segment
		(start 129.245868 -356.01783)
		(end 125.218952 -358.838754)
		(width 0.14224)
		(layer "In11.Cu")
		(net "P5E_CPU1_P3_TX_DN<1>")
	)
	(segment
		(start 113.762028 -292.396926)
		(end 113.760758 -292.397434)
		(width 0.1143)
		(layer "In11.Cu")
		(net "P5E_CPU1_P3_TX_DN<1>")
	)
	(arc
		(start 113.737136 -289.17138)
		(mid 113.580159 -289.47618)
		(end 113.737136 -289.78098)
		(width 0.1143)
		(layer "In11.Cu")
		(net "P5E_CPU1_P3_TX_DN<1>")
	)
	(arc
		(start 134.649464 -341.448898)
		(mid 134.655364 -341.48871)
		(end 134.657338 -341.528908)
		(width 0.14224)
		(layer "In11.Cu")
		(net "P5E_CPU1_P3_TX_DN<1>")
	)
	(arc
		(start 113.580164 -286.239204)
		(mid 113.621527 -286.408777)
		(end 113.73612 -286.540448)
		(width 0.1143)
		(layer "In11.Cu")
		(net "P5E_CPU1_P3_TX_DN<1>")
	)
	(arc
		(start 113.806732 -289.82162)
		(mid 114.050059 -290.286186)
		(end 113.806732 -290.750752)
		(width 0.1143)
		(layer "In11.Cu")
		(net "P5E_CPU1_P3_TX_DN<1>")
	)
	(arc
		(start 113.73612 -285.932372)
		(mid 113.62454 -286.059473)
		(end 113.580164 -286.222694)
		(width 0.1143)
		(layer "In11.Cu")
		(net "P5E_CPU1_P3_TX_DN<1>")
	)
	(arc
		(start 113.806732 -293.061644)
		(mid 114.050059 -293.52621)
		(end 113.806732 -293.990776)
		(width 0.1143)
		(layer "In11.Cu")
		(net "P5E_CPU1_P3_TX_DN<1>")
	)
	(arc
		(start 113.773712 -288.182304)
		(mid 114.050853 -288.658244)
		(end 113.787174 -289.141662)
		(width 0.1143)
		(layer "In11.Cu")
		(net "P5E_CPU1_P3_TX_DN<1>")
	)
	(arc
		(start 113.74247 -279.448768)
		(mid 113.627883 -279.589442)
		(end 113.580164 -279.76449)
		(width 0.1143)
		(layer "In11.Cu")
		(net "P5E_CPU1_P3_TX_DN<1>")
	)
	(arc
		(start 113.806732 -280.101802)
		(mid 114.050059 -280.566368)
		(end 113.806732 -281.030934)
		(width 0.1143)
		(layer "In11.Cu")
		(net "P5E_CPU1_P3_TX_DN<1>")
	)
	(arc
		(start 113.806732 -286.581596)
		(mid 113.985545 -286.783946)
		(end 114.050064 -287.046162)
		(width 0.1143)
		(layer "In11.Cu")
		(net "P5E_CPU1_P3_TX_DN<1>")
	)
	(arc
		(start 113.580164 -287.856422)
		(mid 113.621915 -288.028042)
		(end 113.737644 -288.161476)
		(width 0.1143)
		(layer "In11.Cu")
		(net "P5E_CPU1_P3_TX_DN<1>")
	)
	(arc
		(start 114.20602 -278.642064)
		(mid 114.091344 -278.775398)
		(end 114.050064 -278.946356)
		(width 0.1143)
		(layer "In11.Cu")
		(net "P5E_CPU1_P3_TX_DN<1>")
	)
	(arc
		(start 113.806732 -281.721814)
		(mid 114.050059 -282.18638)
		(end 113.806732 -282.650946)
		(width 0.1143)
		(layer "In11.Cu")
		(net "P5E_CPU1_P3_TX_DN<1>")
	)
	(arc
		(start 129.402332 -355.863906)
		(mid 129.330514 -355.947387)
		(end 129.245868 -356.01783)
		(width 0.14224)
		(layer "In11.Cu")
		(net "P5E_CPU1_P3_TX_DN<1>")
	)
	(arc
		(start 114.276632 -295.491662)
		(mid 114.455507 -295.69398)
		(end 114.519964 -295.956228)
		(width 0.1143)
		(layer "In11.Cu")
		(net "P5E_CPU1_P3_TX_DN<1>")
	)
	(arc
		(start 109.416088 -368.763042)
		(mid 108.987138 -370.177126)
		(end 108.842302 -371.64772)
		(width 0.14224)
		(layer "In11.Cu")
		(net "P5E_CPU1_P3_TX_DN<1>")
	)
	(arc
		(start 113.80597 -293.061136)
		(mid 113.806351 -293.06139)
		(end 113.806732 -293.061644)
		(width 0.1143)
		(layer "In11.Cu")
		(net "P5E_CPU1_P3_TX_DN<1>")
	)
	(arc
		(start 113.806732 -294.681656)
		(mid 113.985545 -294.884006)
		(end 114.050064 -295.146222)
		(width 0.1143)
		(layer "In11.Cu")
		(net "P5E_CPU1_P3_TX_DN<1>")
	)
	(arc
		(start 113.580164 -279.76449)
		(mid 113.623088 -279.930617)
		(end 113.735612 -280.060146)
		(width 0.1143)
		(layer "In11.Cu")
		(net "P5E_CPU1_P3_TX_DN<1>")
	)
	(arc
		(start 113.76787 -284.293818)
		(mid 113.582892 -284.611672)
		(end 113.759742 -284.934152)
		(width 0.1143)
		(layer "In11.Cu")
		(net "P5E_CPU1_P3_TX_DN<1>")
	)
	(arc
		(start 114.050064 -287.046162)
		(mid 113.984828 -287.309753)
		(end 113.804192 -287.512506)
		(width 0.1143)
		(layer "In11.Cu")
		(net "P5E_CPU1_P3_TX_DN<1>")
	)
	(arc
		(start 113.805208 -281.720798)
		(mid 113.80597 -281.721305)
		(end 113.806732 -281.721814)
		(width 0.1143)
		(layer "In11.Cu")
		(net "P5E_CPU1_P3_TX_DN<1>")
	)
	(arc
		(start 114.050064 -295.146222)
		(mid 114.091613 -295.317644)
		(end 114.207036 -295.451022)
		(width 0.1143)
		(layer "In11.Cu")
		(net "P5E_CPU1_P3_TX_DN<1>")
	)
	(arc
		(start 113.806732 -291.441632)
		(mid 114.050059 -291.906198)
		(end 113.806732 -292.370764)
		(width 0.1143)
		(layer "In11.Cu")
		(net "P5E_CPU1_P3_TX_DN<1>")
	)
	(arc
		(start 113.740184 -287.54959)
		(mid 113.622561 -287.683392)
		(end 113.580164 -287.856422)
		(width 0.1143)
		(layer "In11.Cu")
		(net "P5E_CPU1_P3_TX_DN<1>")
	)
	(arc
		(start 113.760758 -292.397434)
		(mid 113.580273 -292.716204)
		(end 113.760758 -293.034974)
		(width 0.1143)
		(layer "In11.Cu")
		(net "P5E_CPU1_P3_TX_DN<1>")
	)
	(arc
		(start 114.980212 -277.432008)
		(mid 114.898779 -277.634406)
		(end 114.746786 -277.79091)
		(width 0.1143)
		(layer "In11.Cu")
		(net "P5E_CPU1_P3_TX_DN<1>")
	)
	(arc
		(start 114.67592 -277.832312)
		(mid 114.561292 -277.963965)
		(end 114.519964 -278.133556)
		(width 0.1143)
		(layer "In11.Cu")
		(net "P5E_CPU1_P3_TX_DN<1>")
	)
	(arc
		(start 113.806732 -284.961838)
		(mid 114.050059 -285.426404)
		(end 113.806732 -285.89097)
		(width 0.1143)
		(layer "In11.Cu")
		(net "P5E_CPU1_P3_TX_DN<1>")
	)
	(arc
		(start 113.805208 -283.34081)
		(mid 113.80597 -283.341317)
		(end 113.806732 -283.341826)
		(width 0.1143)
		(layer "In11.Cu")
		(net "P5E_CPU1_P3_TX_DN<1>")
	)
	(arc
		(start 134.657338 -343.223342)
		(mid 134.575011 -344.059187)
		(end 134.331202 -344.862912)
		(width 0.14224)
		(layer "In11.Cu")
		(net "P5E_CPU1_P3_TX_DN<1>")
	)
	(arc
		(start 113.764314 -281.055826)
		(mid 113.580432 -281.376264)
		(end 113.76406 -281.696922)
		(width 0.1143)
		(layer "In11.Cu")
		(net "P5E_CPU1_P3_TX_DN<1>")
	)
	(arc
		(start 130.30835 -354.575618)
		(mid 130.266281 -354.662319)
		(end 130.21437 -354.743512)
		(width 0.14224)
		(layer "In11.Cu")
		(net "P5E_CPU1_P3_TX_DN<1>")
	)
	(arc
		(start 113.805208 -284.960822)
		(mid 113.80597 -284.961329)
		(end 113.806732 -284.961838)
		(width 0.1143)
		(layer "In11.Cu")
		(net "P5E_CPU1_P3_TX_DN<1>")
	)
	(arc
		(start 110.186978 -367.385092)
		(mid 109.884733 -367.753345)
		(end 109.660182 -368.173508)
		(width 0.14224)
		(layer "In11.Cu")
		(net "P5E_CPU1_P3_TX_DN<1>")
	)
	(arc
		(start 113.737136 -294.031416)
		(mid 113.580159 -294.336216)
		(end 113.737136 -294.641016)
		(width 0.1143)
		(layer "In11.Cu")
		(net "P5E_CPU1_P3_TX_DN<1>")
	)
	(arc
		(start 114.519964 -278.13635)
		(mid 114.455242 -278.399089)
		(end 114.27587 -278.601678)
		(width 0.1143)
		(layer "In11.Cu")
		(net "P5E_CPU1_P3_TX_DN<1>")
	)
	(arc
		(start 108.842302 -372.470172)
		(mid 108.896632 -372.743308)
		(end 109.051344 -372.97487)
		(width 0.14224)
		(layer "In11.Cu")
		(net "P5E_CPU1_P3_TX_DN<1>")
	)
	(arc
		(start 110.207044 -376.079512)
		(mid 110.175881 -376.23609)
		(end 110.087156 -376.368818)
		(width 0.14224)
		(layer "In11.Cu")
		(net "P5E_CPU1_P3_TX_DN<1>")
	)
	(arc
		(start 110.034832 -376.421142)
		(mid 109.902112 -376.509886)
		(end 109.745526 -376.54103)
		(width 0.14224)
		(layer "In11.Cu")
		(net "P5E_CPU1_P3_TX_DN<1>")
	)
	(arc
		(start 113.764314 -282.675838)
		(mid 113.580432 -282.996276)
		(end 113.76406 -283.316934)
		(width 0.1143)
		(layer "In11.Cu")
		(net "P5E_CPU1_P3_TX_DN<1>")
	)
	(arc
		(start 113.737136 -290.791392)
		(mid 113.580159 -291.096192)
		(end 113.737136 -291.400992)
		(width 0.1143)
		(layer "In11.Cu")
		(net "P5E_CPU1_P3_TX_DN<1>")
	)
	(arc
		(start 110.087156 -374.010682)
		(mid 110.1759 -374.143402)
		(end 110.207044 -374.299988)
		(width 0.14224)
		(layer "In11.Cu")
		(net "P5E_CPU1_P3_TX_DN<1>")
	)
	(arc
		(start 114.050064 -278.946356)
		(mid 113.985549 -279.208575)
		(end 113.806732 -279.410922)
		(width 0.1143)
		(layer "In11.Cu")
		(net "P5E_CPU1_P3_TX_DN<1>")
	)
	(arc
		(start 111.088932 -366.589564)
		(mid 110.834982 -366.763761)
		(end 110.6043 -366.96777)
		(width 0.14224)
		(layer "In11.Cu")
		(net "P5E_CPU1_P3_TX_DN<1>")
	)
	(arc
		(start 113.806732 -283.341826)
		(mid 114.050059 -283.806392)
		(end 113.806732 -284.270958)
		(width 0.1143)
		(layer "In11.Cu")
		(net "P5E_CPU1_P3_TX_DN<1>")
	)
	(arc
		(start 114.984022 -277.409148)
		(mid 114.982234 -277.420597)
		(end 114.980212 -277.432008)
		(width 0.1143)
		(layer "In11.Cu")
		(net "P5E_CPU1_P3_TX_DN<1>")
	)
	(segment
		(start 138.107166 -380.089918)
		(end 137.403586 -380.089918)
		(width 0.12954)
		(layer "F.Cu")
		(net "P5E_CPU1_P3_TX_DN<15>")
	)
	(segment
		(start 137.403586 -380.089918)
		(end 137.107676 -380.385828)
		(width 0.12954)
		(layer "F.Cu")
		(net "P5E_CPU1_P3_TX_DN<15>")
	)
	(segment
		(start 138.377676 -380.360428)
		(end 138.107166 -380.089918)
		(width 0.12954)
		(layer "F.Cu")
		(net "P5E_CPU1_P3_TX_DN<15>")
	)
	(segment
		(start 125.707902 -276.2504)
		(end 126.174754 -276.516338)
		(width 0.12954)
		(layer "F.Cu")
		(net "P5E_CPU1_P3_TX_DN<15>")
	)
	(segment
		(start 141.970506 -315.846206)
		(end 144.484598 -321.914774)
		(width 0.14224)
		(layer "In11.Cu")
		(net "P5E_CPU1_P3_TX_DN<15>")
	)
	(segment
		(start 126.92761 -288.178748)
		(end 126.966726 -288.201608)
		(width 0.1143)
		(layer "In11.Cu")
		(net "P5E_CPU1_P3_TX_DN<15>")
	)
	(segment
		(start 126.92761 -281.053794)
		(end 126.89713 -281.071574)
		(width 0.1143)
		(layer "In11.Cu")
		(net "P5E_CPU1_P3_TX_DN<15>")
	)
	(segment
		(start 127.40132 -295.470834)
		(end 127.43688 -295.491662)
		(width 0.1143)
		(layer "In11.Cu")
		(net "P5E_CPU1_P3_TX_DN<15>")
	)
	(segment
		(start 126.89713 -291.400992)
		(end 126.92761 -291.418772)
		(width 0.1143)
		(layer "In11.Cu")
		(net "P5E_CPU1_P3_TX_DN<15>")
	)
	(segment
		(start 125.98781 -276.838918)
		(end 125.991112 -276.84095)
		(width 0.1143)
		(layer "In11.Cu")
		(net "P5E_CPU1_P3_TX_DN<15>")
	)
	(segment
		(start 126.895098 -286.53994)
		(end 126.92761 -286.558736)
		(width 0.1143)
		(layer "In11.Cu")
		(net "P5E_CPU1_P3_TX_DN<15>")
	)
	(segment
		(start 127.397764 -280.243788)
		(end 127.397002 -280.244296)
		(width 0.1143)
		(layer "In11.Cu")
		(net "P5E_CPU1_P3_TX_DN<15>")
	)
	(segment
		(start 127.39878 -295.46931)
		(end 127.400304 -295.470326)
		(width 0.1143)
		(layer "In11.Cu")
		(net "P5E_CPU1_P3_TX_DN<15>")
	)
	(segment
		(start 127.964184 -296.763948)
		(end 128.009904 -296.809668)
		(width 0.1143)
		(layer "In11.Cu")
		(net "P5E_CPU1_P3_TX_DN<15>")
	)
	(segment
		(start 128.05156 -297.007534)
		(end 135.217154 -305.739038)
		(width 0.14224)
		(layer "In11.Cu")
		(net "P5E_CPU1_P3_TX_DN<15>")
	)
	(segment
		(start 125.987048 -276.83841)
		(end 125.98781 -276.838918)
		(width 0.1143)
		(layer "In11.Cu")
		(net "P5E_CPU1_P3_TX_DN<15>")
	)
	(segment
		(start 127.400304 -279.27046)
		(end 127.40132 -279.270968)
		(width 0.1143)
		(layer "In11.Cu")
		(net "P5E_CPU1_P3_TX_DN<15>")
	)
	(segment
		(start 126.92761 -284.938978)
		(end 126.966726 -284.961838)
		(width 0.1143)
		(layer "In11.Cu")
		(net "P5E_CPU1_P3_TX_DN<15>")
	)
	(segment
		(start 126.966726 -289.13074)
		(end 126.92761 -289.1536)
		(width 0.1143)
		(layer "In11.Cu")
		(net "P5E_CPU1_P3_TX_DN<15>")
	)
	(segment
		(start 127.397002 -279.268428)
		(end 127.397764 -279.268936)
		(width 0.1143)
		(layer "In11.Cu")
		(net "P5E_CPU1_P3_TX_DN<15>")
	)
	(segment
		(start 126.966726 -281.030934)
		(end 126.92761 -281.053794)
		(width 0.1143)
		(layer "In11.Cu")
		(net "P5E_CPU1_P3_TX_DN<15>")
	)
	(segment
		(start 127.395732 -280.245058)
		(end 127.366014 -280.262076)
		(width 0.1143)
		(layer "In11.Cu")
		(net "P5E_CPU1_P3_TX_DN<15>")
	)
	(segment
		(start 127.366014 -295.450514)
		(end 127.397764 -295.468802)
		(width 0.1143)
		(layer "In11.Cu")
		(net "P5E_CPU1_P3_TX_DN<15>")
	)
	(segment
		(start 126.89713 -293.021004)
		(end 126.92761 -293.038784)
		(width 0.1143)
		(layer "In11.Cu")
		(net "P5E_CPU1_P3_TX_DN<15>")
	)
	(segment
		(start 126.92761 -282.673806)
		(end 126.89713 -282.691586)
		(width 0.1143)
		(layer "In11.Cu")
		(net "P5E_CPU1_P3_TX_DN<15>")
	)
	(segment
		(start 126.92761 -278.45893)
		(end 126.966726 -278.48179)
		(width 0.1143)
		(layer "In11.Cu")
		(net "P5E_CPU1_P3_TX_DN<15>")
	)
	(segment
		(start 147.477988 -351.819718)
		(end 141.662658 -365.860076)
		(width 0.14224)
		(layer "In11.Cu")
		(net "P5E_CPU1_P3_TX_DN<15>")
	)
	(segment
		(start 126.92761 -293.038784)
		(end 126.966726 -293.061644)
		(width 0.1143)
		(layer "In11.Cu")
		(net "P5E_CPU1_P3_TX_DN<15>")
	)
	(segment
		(start 127.43688 -280.220928)
		(end 127.397764 -280.243788)
		(width 0.1143)
		(layer "In11.Cu")
		(net "P5E_CPU1_P3_TX_DN<15>")
	)
	(segment
		(start 125.95606 -276.82063)
		(end 125.987048 -276.83841)
		(width 0.1143)
		(layer "In11.Cu")
		(net "P5E_CPU1_P3_TX_DN<15>")
	)
	(segment
		(start 126.92761 -291.418772)
		(end 126.966726 -291.441632)
		(width 0.1143)
		(layer "In11.Cu")
		(net "P5E_CPU1_P3_TX_DN<15>")
	)
	(segment
		(start 126.92761 -283.318966)
		(end 126.966726 -283.341826)
		(width 0.1143)
		(layer "In11.Cu")
		(net "P5E_CPU1_P3_TX_DN<15>")
	)
	(segment
		(start 128.009904 -296.809668)
		(end 128.009904 -296.838116)
		(width 0.1143)
		(layer "In11.Cu")
		(net "P5E_CPU1_P3_TX_DN<15>")
	)
	(segment
		(start 126.92761 -289.1536)
		(end 126.89713 -289.17138)
		(width 0.1143)
		(layer "In11.Cu")
		(net "P5E_CPU1_P3_TX_DN<15>")
	)
	(segment
		(start 127.397764 -279.268936)
		(end 127.39878 -279.269444)
		(width 0.1143)
		(layer "In11.Cu")
		(net "P5E_CPU1_P3_TX_DN<15>")
	)
	(segment
		(start 127.964184 -296.688256)
		(end 127.964184 -296.763948)
		(width 0.1143)
		(layer "In11.Cu")
		(net "P5E_CPU1_P3_TX_DN<15>")
	)
	(segment
		(start 148.074634 -339.965284)
		(end 148.074634 -348.820486)
		(width 0.14224)
		(layer "In11.Cu")
		(net "P5E_CPU1_P3_TX_DN<15>")
	)
	(segment
		(start 126.89713 -284.921198)
		(end 126.92761 -284.938978)
		(width 0.1143)
		(layer "In11.Cu")
		(net "P5E_CPU1_P3_TX_DN<15>")
	)
	(segment
		(start 126.270004 -277.326344)
		(end 126.270004 -277.329392)
		(width 0.1143)
		(layer "In11.Cu")
		(net "P5E_CPU1_P3_TX_DN<15>")
	)
	(segment
		(start 127.400304 -295.470326)
		(end 127.40132 -295.470834)
		(width 0.1143)
		(layer "In11.Cu")
		(net "P5E_CPU1_P3_TX_DN<15>")
	)
	(segment
		(start 138.668506 -380.069598)
		(end 138.377676 -380.360428)
		(width 0.14224)
		(layer "In11.Cu")
		(net "P5E_CPU1_P3_TX_DN<15>")
	)
	(segment
		(start 127.40132 -279.270968)
		(end 127.43688 -279.291796)
		(width 0.1143)
		(layer "In11.Cu")
		(net "P5E_CPU1_P3_TX_DN<15>")
	)
	(segment
		(start 127.791718 -296.384218)
		(end 127.870966 -296.463466)
		(width 0.1143)
		(layer "In11.Cu")
		(net "P5E_CPU1_P3_TX_DN<15>")
	)
	(segment
		(start 127.366014 -279.250648)
		(end 127.397002 -279.268428)
		(width 0.1143)
		(layer "In11.Cu")
		(net "P5E_CPU1_P3_TX_DN<15>")
	)
	(segment
		(start 139.877546 -375.915936)
		(end 139.877546 -379.60808)
		(width 0.14224)
		(layer "In11.Cu")
		(net "P5E_CPU1_P3_TX_DN<15>")
	)
	(segment
		(start 139.757658 -379.897386)
		(end 139.705334 -379.94971)
		(width 0.14224)
		(layer "In11.Cu")
		(net "P5E_CPU1_P3_TX_DN<15>")
	)
	(segment
		(start 141.320774 -371.421914)
		(end 141.213078 -371.964712)
		(width 0.14224)
		(layer "In11.Cu")
		(net "P5E_CPU1_P3_TX_DN<15>")
	)
	(segment
		(start 126.92761 -284.293818)
		(end 126.89713 -284.311598)
		(width 0.1143)
		(layer "In11.Cu")
		(net "P5E_CPU1_P3_TX_DN<15>")
	)
	(segment
		(start 126.966726 -282.650946)
		(end 126.92761 -282.673806)
		(width 0.1143)
		(layer "In11.Cu")
		(net "P5E_CPU1_P3_TX_DN<15>")
	)
	(segment
		(start 127.680212 -295.956228)
		(end 127.680212 -296.115232)
		(width 0.1143)
		(layer "In11.Cu")
		(net "P5E_CPU1_P3_TX_DN<15>")
	)
	(segment
		(start 128.009904 -296.838116)
		(end 128.009904 -296.87139)
		(width 0.14224)
		(layer "In11.Cu")
		(net "P5E_CPU1_P3_TX_DN<15>")
	)
	(segment
		(start 126.92761 -290.773612)
		(end 126.89713 -290.791392)
		(width 0.1143)
		(layer "In11.Cu")
		(net "P5E_CPU1_P3_TX_DN<15>")
	)
	(segment
		(start 126.89713 -294.641016)
		(end 126.92761 -294.658796)
		(width 0.1143)
		(layer "In11.Cu")
		(net "P5E_CPU1_P3_TX_DN<15>")
	)
	(segment
		(start 126.966726 -290.750752)
		(end 126.92761 -290.773612)
		(width 0.1143)
		(layer "In11.Cu")
		(net "P5E_CPU1_P3_TX_DN<15>")
	)
	(segment
		(start 126.423166 -277.628604)
		(end 126.42596 -277.630636)
		(width 0.1143)
		(layer "In11.Cu")
		(net "P5E_CPU1_P3_TX_DN<15>")
	)
	(segment
		(start 126.92761 -289.79876)
		(end 126.966726 -289.82162)
		(width 0.1143)
		(layer "In11.Cu")
		(net "P5E_CPU1_P3_TX_DN<15>")
	)
	(segment
		(start 126.89713 -283.301186)
		(end 126.92761 -283.318966)
		(width 0.1143)
		(layer "In11.Cu")
		(net "P5E_CPU1_P3_TX_DN<15>")
	)
	(segment
		(start 126.92761 -285.91383)
		(end 126.89713 -285.93161)
		(width 0.1143)
		(layer "In11.Cu")
		(net "P5E_CPU1_P3_TX_DN<15>")
	)
	(segment
		(start 126.966726 -292.370764)
		(end 126.92761 -292.393624)
		(width 0.1143)
		(layer "In11.Cu")
		(net "P5E_CPU1_P3_TX_DN<15>")
	)
	(segment
		(start 126.92761 -286.558736)
		(end 126.966726 -286.581596)
		(width 0.1143)
		(layer "In11.Cu")
		(net "P5E_CPU1_P3_TX_DN<15>")
	)
	(segment
		(start 126.174754 -276.516338)
		(end 125.876812 -276.516338)
		(width 0.1143)
		(layer "In11.Cu")
		(net "P5E_CPU1_P3_TX_DN<15>")
	)
	(segment
		(start 126.92761 -294.658796)
		(end 126.966726 -294.681656)
		(width 0.1143)
		(layer "In11.Cu")
		(net "P5E_CPU1_P3_TX_DN<15>")
	)
	(segment
		(start 126.92761 -281.698954)
		(end 126.966726 -281.721814)
		(width 0.1143)
		(layer "In11.Cu")
		(net "P5E_CPU1_P3_TX_DN<15>")
	)
	(segment
		(start 128.009904 -296.87139)
		(end 128.05156 -297.007534)
		(width 0.14224)
		(layer "In11.Cu")
		(net "P5E_CPU1_P3_TX_DN<15>")
	)
	(segment
		(start 126.89713 -289.78098)
		(end 126.92761 -289.79876)
		(width 0.1143)
		(layer "In11.Cu")
		(net "P5E_CPU1_P3_TX_DN<15>")
	)
	(segment
		(start 126.964186 -287.512506)
		(end 126.89713 -287.551622)
		(width 0.1143)
		(layer "In11.Cu")
		(net "P5E_CPU1_P3_TX_DN<15>")
	)
	(segment
		(start 141.320774 -367.578386)
		(end 141.320774 -371.421914)
		(width 0.14224)
		(layer "In11.Cu")
		(net "P5E_CPU1_P3_TX_DN<15>")
	)
	(segment
		(start 126.89713 -281.681174)
		(end 126.92761 -281.698954)
		(width 0.1143)
		(layer "In11.Cu")
		(net "P5E_CPU1_P3_TX_DN<15>")
	)
	(segment
		(start 126.92761 -294.013636)
		(end 126.89713 -294.031416)
		(width 0.1143)
		(layer "In11.Cu")
		(net "P5E_CPU1_P3_TX_DN<15>")
	)
	(segment
		(start 135.217154 -305.739038)
		(end 141.970506 -315.846206)
		(width 0.14224)
		(layer "In11.Cu")
		(net "P5E_CPU1_P3_TX_DN<15>")
	)
	(segment
		(start 141.11986 -372.272052)
		(end 140.12418 -374.675908)
		(width 0.14224)
		(layer "In11.Cu")
		(net "P5E_CPU1_P3_TX_DN<15>")
	)
	(segment
		(start 126.42596 -277.630636)
		(end 126.496826 -277.671784)
		(width 0.1143)
		(layer "In11.Cu")
		(net "P5E_CPU1_P3_TX_DN<15>")
	)
	(segment
		(start 127.397764 -295.468802)
		(end 127.39878 -295.46931)
		(width 0.1143)
		(layer "In11.Cu")
		(net "P5E_CPU1_P3_TX_DN<15>")
	)
	(segment
		(start 126.966726 -293.990776)
		(end 126.92761 -294.013636)
		(width 0.1143)
		(layer "In11.Cu")
		(net "P5E_CPU1_P3_TX_DN<15>")
	)
	(segment
		(start 139.416028 -380.069598)
		(end 138.668506 -380.069598)
		(width 0.14224)
		(layer "In11.Cu")
		(net "P5E_CPU1_P3_TX_DN<15>")
	)
	(segment
		(start 126.966726 -285.89097)
		(end 126.92761 -285.91383)
		(width 0.1143)
		(layer "In11.Cu")
		(net "P5E_CPU1_P3_TX_DN<15>")
	)
	(segment
		(start 126.89713 -278.44115)
		(end 126.92761 -278.45893)
		(width 0.1143)
		(layer "In11.Cu")
		(net "P5E_CPU1_P3_TX_DN<15>")
	)
	(segment
		(start 125.991112 -276.84095)
		(end 126.024132 -276.86)
		(width 0.1143)
		(layer "In11.Cu")
		(net "P5E_CPU1_P3_TX_DN<15>")
	)
	(segment
		(start 125.876812 -276.516338)
		(end 125.806962 -276.586188)
		(width 0.1143)
		(layer "In11.Cu")
		(net "P5E_CPU1_P3_TX_DN<15>")
	)
	(segment
		(start 144.484598 -321.914774)
		(end 148.074634 -339.965284)
		(width 0.14224)
		(layer "In11.Cu")
		(net "P5E_CPU1_P3_TX_DN<15>")
	)
	(segment
		(start 127.397002 -280.244296)
		(end 127.395732 -280.245058)
		(width 0.1143)
		(layer "In11.Cu")
		(net "P5E_CPU1_P3_TX_DN<15>")
	)
	(segment
		(start 126.92761 -292.393624)
		(end 126.89713 -292.411404)
		(width 0.1143)
		(layer "In11.Cu")
		(net "P5E_CPU1_P3_TX_DN<15>")
	)
	(segment
		(start 127.39878 -279.269444)
		(end 127.400304 -279.27046)
		(width 0.1143)
		(layer "In11.Cu")
		(net "P5E_CPU1_P3_TX_DN<15>")
	)
	(segment
		(start 126.895098 -288.159952)
		(end 126.92761 -288.178748)
		(width 0.1143)
		(layer "In11.Cu")
		(net "P5E_CPU1_P3_TX_DN<15>")
	)
	(segment
		(start 126.966726 -284.270958)
		(end 126.92761 -284.293818)
		(width 0.1143)
		(layer "In11.Cu")
		(net "P5E_CPU1_P3_TX_DN<15>")
	)
	(arc
		(start 126.966726 -288.201608)
		(mid 127.210053 -288.666174)
		(end 126.966726 -289.13074)
		(width 0.1143)
		(layer "In11.Cu")
		(net "P5E_CPU1_P3_TX_DN<15>")
	)
	(arc
		(start 139.877546 -379.60808)
		(mid 139.846383 -379.764658)
		(end 139.757658 -379.897386)
		(width 0.14224)
		(layer "In11.Cu")
		(net "P5E_CPU1_P3_TX_DN<15>")
	)
	(arc
		(start 126.89713 -290.791392)
		(mid 126.740153 -291.096192)
		(end 126.89713 -291.400992)
		(width 0.1143)
		(layer "In11.Cu")
		(net "P5E_CPU1_P3_TX_DN<15>")
	)
	(arc
		(start 126.89713 -281.071574)
		(mid 126.740153 -281.376374)
		(end 126.89713 -281.681174)
		(width 0.1143)
		(layer "In11.Cu")
		(net "P5E_CPU1_P3_TX_DN<15>")
	)
	(arc
		(start 140.12418 -374.675908)
		(mid 139.939797 -375.283777)
		(end 139.877546 -375.915936)
		(width 0.14224)
		(layer "In11.Cu")
		(net "P5E_CPU1_P3_TX_DN<15>")
	)
	(arc
		(start 126.89713 -289.17138)
		(mid 126.740153 -289.47618)
		(end 126.89713 -289.78098)
		(width 0.1143)
		(layer "In11.Cu")
		(net "P5E_CPU1_P3_TX_DN<15>")
	)
	(arc
		(start 126.740158 -287.856422)
		(mid 126.781124 -288.026828)
		(end 126.895098 -288.159952)
		(width 0.1143)
		(layer "In11.Cu")
		(net "P5E_CPU1_P3_TX_DN<15>")
	)
	(arc
		(start 148.074634 -348.820486)
		(mid 147.923997 -350.349481)
		(end 147.477988 -351.819718)
		(width 0.14224)
		(layer "In11.Cu")
		(net "P5E_CPU1_P3_TX_DN<15>")
	)
	(arc
		(start 127.366014 -280.262076)
		(mid 127.251338 -280.39541)
		(end 127.210058 -280.566368)
		(width 0.1143)
		(layer "In11.Cu")
		(net "P5E_CPU1_P3_TX_DN<15>")
	)
	(arc
		(start 127.680212 -296.115232)
		(mid 127.70919 -296.260826)
		(end 127.791718 -296.384218)
		(width 0.1143)
		(layer "In11.Cu")
		(net "P5E_CPU1_P3_TX_DN<15>")
	)
	(arc
		(start 126.89713 -285.93161)
		(mid 126.781703 -286.064986)
		(end 126.740158 -286.23641)
		(width 0.1143)
		(layer "In11.Cu")
		(net "P5E_CPU1_P3_TX_DN<15>")
	)
	(arc
		(start 141.662658 -365.860076)
		(mid 141.407092 -366.702394)
		(end 141.320774 -367.578386)
		(width 0.14224)
		(layer "In11.Cu")
		(net "P5E_CPU1_P3_TX_DN<15>")
	)
	(arc
		(start 127.43688 -295.491662)
		(mid 127.515303 -295.557143)
		(end 127.580644 -295.63568)
		(width 0.1143)
		(layer "In11.Cu")
		(net "P5E_CPU1_P3_TX_DN<15>")
	)
	(arc
		(start 126.740158 -286.23641)
		(mid 126.781124 -286.406816)
		(end 126.895098 -286.53994)
		(width 0.1143)
		(layer "In11.Cu")
		(net "P5E_CPU1_P3_TX_DN<15>")
	)
	(arc
		(start 139.705334 -379.94971)
		(mid 139.572614 -380.038454)
		(end 139.416028 -380.069598)
		(width 0.14224)
		(layer "In11.Cu")
		(net "P5E_CPU1_P3_TX_DN<15>")
	)
	(arc
		(start 126.966726 -278.48179)
		(mid 127.145539 -278.68414)
		(end 127.210058 -278.946356)
		(width 0.1143)
		(layer "In11.Cu")
		(net "P5E_CPU1_P3_TX_DN<15>")
	)
	(arc
		(start 126.966726 -283.341826)
		(mid 127.210053 -283.806392)
		(end 126.966726 -284.270958)
		(width 0.1143)
		(layer "In11.Cu")
		(net "P5E_CPU1_P3_TX_DN<15>")
	)
	(arc
		(start 127.43688 -279.291796)
		(mid 127.680207 -279.756362)
		(end 127.43688 -280.220928)
		(width 0.1143)
		(layer "In11.Cu")
		(net "P5E_CPU1_P3_TX_DN<15>")
	)
	(arc
		(start 126.270004 -277.329392)
		(mid 126.31045 -277.497507)
		(end 126.423166 -277.628604)
		(width 0.1143)
		(layer "In11.Cu")
		(net "P5E_CPU1_P3_TX_DN<15>")
	)
	(arc
		(start 127.210058 -295.146222)
		(mid 127.251313 -295.317193)
		(end 127.366014 -295.450514)
		(width 0.1143)
		(layer "In11.Cu")
		(net "P5E_CPU1_P3_TX_DN<15>")
	)
	(arc
		(start 126.966726 -286.581596)
		(mid 127.145539 -286.783946)
		(end 127.210058 -287.046162)
		(width 0.1143)
		(layer "In11.Cu")
		(net "P5E_CPU1_P3_TX_DN<15>")
	)
	(arc
		(start 126.966726 -291.441632)
		(mid 127.210053 -291.906198)
		(end 126.966726 -292.370764)
		(width 0.1143)
		(layer "In11.Cu")
		(net "P5E_CPU1_P3_TX_DN<15>")
	)
	(arc
		(start 127.210058 -280.566368)
		(mid 127.145543 -280.828587)
		(end 126.966726 -281.030934)
		(width 0.1143)
		(layer "In11.Cu")
		(net "P5E_CPU1_P3_TX_DN<15>")
	)
	(arc
		(start 126.966726 -281.721814)
		(mid 127.210053 -282.18638)
		(end 126.966726 -282.650946)
		(width 0.1143)
		(layer "In11.Cu")
		(net "P5E_CPU1_P3_TX_DN<15>")
	)
	(arc
		(start 127.210058 -287.046162)
		(mid 127.144822 -287.309753)
		(end 126.964186 -287.512506)
		(width 0.1143)
		(layer "In11.Cu")
		(net "P5E_CPU1_P3_TX_DN<15>")
	)
	(arc
		(start 126.89713 -284.311598)
		(mid 126.740153 -284.616398)
		(end 126.89713 -284.921198)
		(width 0.1143)
		(layer "In11.Cu")
		(net "P5E_CPU1_P3_TX_DN<15>")
	)
	(arc
		(start 125.806962 -276.586188)
		(mid 125.859011 -276.717707)
		(end 125.95606 -276.82063)
		(width 0.1143)
		(layer "In11.Cu")
		(net "P5E_CPU1_P3_TX_DN<15>")
	)
	(arc
		(start 141.213078 -371.964712)
		(mid 141.174037 -372.120678)
		(end 141.11986 -372.272052)
		(width 0.14224)
		(layer "In11.Cu")
		(net "P5E_CPU1_P3_TX_DN<15>")
	)
	(arc
		(start 126.966726 -284.961838)
		(mid 127.210053 -285.426404)
		(end 126.966726 -285.89097)
		(width 0.1143)
		(layer "In11.Cu")
		(net "P5E_CPU1_P3_TX_DN<15>")
	)
	(arc
		(start 126.966726 -293.061644)
		(mid 127.210053 -293.52621)
		(end 126.966726 -293.990776)
		(width 0.1143)
		(layer "In11.Cu")
		(net "P5E_CPU1_P3_TX_DN<15>")
	)
	(arc
		(start 126.89713 -282.691586)
		(mid 126.740153 -282.996386)
		(end 126.89713 -283.301186)
		(width 0.1143)
		(layer "In11.Cu")
		(net "P5E_CPU1_P3_TX_DN<15>")
	)
	(arc
		(start 126.496826 -277.671784)
		(mid 126.675639 -277.874134)
		(end 126.740158 -278.13635)
		(width 0.1143)
		(layer "In11.Cu")
		(net "P5E_CPU1_P3_TX_DN<15>")
	)
	(arc
		(start 126.89713 -287.551622)
		(mid 126.781703 -287.684998)
		(end 126.740158 -287.856422)
		(width 0.1143)
		(layer "In11.Cu")
		(net "P5E_CPU1_P3_TX_DN<15>")
	)
	(arc
		(start 126.966726 -289.82162)
		(mid 127.210053 -290.286186)
		(end 126.966726 -290.750752)
		(width 0.1143)
		(layer "In11.Cu")
		(net "P5E_CPU1_P3_TX_DN<15>")
	)
	(arc
		(start 126.740158 -278.13635)
		(mid 126.781707 -278.307772)
		(end 126.89713 -278.44115)
		(width 0.1143)
		(layer "In11.Cu")
		(net "P5E_CPU1_P3_TX_DN<15>")
	)
	(arc
		(start 126.966726 -294.681656)
		(mid 127.145539 -294.884006)
		(end 127.210058 -295.146222)
		(width 0.1143)
		(layer "In11.Cu")
		(net "P5E_CPU1_P3_TX_DN<15>")
	)
	(arc
		(start 126.024132 -276.86)
		(mid 126.204784 -277.062745)
		(end 126.270004 -277.326344)
		(width 0.1143)
		(layer "In11.Cu")
		(net "P5E_CPU1_P3_TX_DN<15>")
	)
	(arc
		(start 127.580644 -295.63568)
		(mid 127.654758 -295.788394)
		(end 127.680212 -295.956228)
		(width 0.1143)
		(layer "In11.Cu")
		(net "P5E_CPU1_P3_TX_DN<15>")
	)
	(arc
		(start 127.210058 -278.946356)
		(mid 127.251313 -279.117327)
		(end 127.366014 -279.250648)
		(width 0.1143)
		(layer "In11.Cu")
		(net "P5E_CPU1_P3_TX_DN<15>")
	)
	(arc
		(start 127.870966 -296.463466)
		(mid 127.939961 -296.566585)
		(end 127.964184 -296.688256)
		(width 0.1143)
		(layer "In11.Cu")
		(net "P5E_CPU1_P3_TX_DN<15>")
	)
	(arc
		(start 126.89713 -294.031416)
		(mid 126.740153 -294.336216)
		(end 126.89713 -294.641016)
		(width 0.1143)
		(layer "In11.Cu")
		(net "P5E_CPU1_P3_TX_DN<15>")
	)
	(arc
		(start 126.89713 -292.411404)
		(mid 126.740153 -292.716204)
		(end 126.89713 -293.021004)
		(width 0.1143)
		(layer "In11.Cu")
		(net "P5E_CPU1_P3_TX_DN<15>")
	)
	(segment
		(start 125.707902 -277.870412)
		(end 126.174754 -278.13635)
		(width 0.12954)
		(layer "F.Cu")
		(net "P5E_CPU1_P3_TX_DN<14>")
	)
	(segment
		(start 137.403586 -376.363738)
		(end 137.107676 -376.067828)
		(width 0.12954)
		(layer "F.Cu")
		(net "P5E_CPU1_P3_TX_DN<14>")
	)
	(segment
		(start 138.377676 -376.093228)
		(end 138.107166 -376.363738)
		(width 0.12954)
		(layer "F.Cu")
		(net "P5E_CPU1_P3_TX_DN<14>")
	)
	(segment
		(start 138.107166 -376.363738)
		(end 137.403586 -376.363738)
		(width 0.12954)
		(layer "F.Cu")
		(net "P5E_CPU1_P3_TX_DN<14>")
	)
	(segment
		(start 126.282704 -278.953722)
		(end 126.282704 -278.966168)
		(width 0.1143)
		(layer "In11.Cu")
		(net "P5E_CPU1_P3_TX_DN<14>")
	)
	(segment
		(start 127.849884 -298.395644)
		(end 134.956296 -307.055266)
		(width 0.14224)
		(layer "In11.Cu")
		(net "P5E_CPU1_P3_TX_DN<14>")
	)
	(segment
		(start 137.299954 -376.384058)
		(end 138.086846 -376.384058)
		(width 0.14224)
		(layer "In11.Cu")
		(net "P5E_CPU1_P3_TX_DN<14>")
	)
	(segment
		(start 126.740158 -295.955974)
		(end 126.740158 -296.070274)
		(width 0.1143)
		(layer "In11.Cu")
		(net "P5E_CPU1_P3_TX_DN<14>")
	)
	(segment
		(start 125.98781 -281.698954)
		(end 125.990858 -281.700732)
		(width 0.1143)
		(layer "In11.Cu")
		(net "P5E_CPU1_P3_TX_DN<14>")
	)
	(segment
		(start 126.02591 -292.37178)
		(end 125.95606 -292.411912)
		(width 0.1143)
		(layer "In11.Cu")
		(net "P5E_CPU1_P3_TX_DN<14>")
	)
	(segment
		(start 125.98781 -293.038784)
		(end 125.990858 -293.040562)
		(width 0.1143)
		(layer "In11.Cu")
		(net "P5E_CPU1_P3_TX_DN<14>")
	)
	(segment
		(start 126.459234 -295.469818)
		(end 126.496572 -295.491154)
		(width 0.1143)
		(layer "In11.Cu")
		(net "P5E_CPU1_P3_TX_DN<14>")
	)
	(segment
		(start 125.990858 -282.672028)
		(end 125.95606 -282.692094)
		(width 0.1143)
		(layer "In11.Cu")
		(net "P5E_CPU1_P3_TX_DN<14>")
	)
	(segment
		(start 139.936728 -369.78717)
		(end 140.073888 -369.92433)
		(width 0.14224)
		(layer "In11.Cu")
		(net "P5E_CPU1_P3_TX_DN<14>")
	)
	(segment
		(start 125.997716 -281.047698)
		(end 125.98781 -281.053794)
		(width 0.1143)
		(layer "In11.Cu")
		(net "P5E_CPU1_P3_TX_DN<14>")
	)
	(segment
		(start 139.936728 -370.555012)
		(end 139.936728 -371.48516)
		(width 0.14224)
		(layer "In11.Cu")
		(net "P5E_CPU1_P3_TX_DN<14>")
	)
	(segment
		(start 137.058654 -376.279156)
		(end 137.067036 -376.287538)
		(width 0.14224)
		(layer "In11.Cu")
		(net "P5E_CPU1_P3_TX_DN<14>")
	)
	(segment
		(start 126.496826 -280.220928)
		(end 126.444756 -280.251154)
		(width 0.1143)
		(layer "In11.Cu")
		(net "P5E_CPU1_P3_TX_DN<14>")
	)
	(segment
		(start 139.24788 -373.329454)
		(end 138.876278 -373.701056)
		(width 0.14224)
		(layer "In11.Cu")
		(net "P5E_CPU1_P3_TX_DN<14>")
	)
	(segment
		(start 125.990858 -285.912052)
		(end 125.95606 -285.932118)
		(width 0.1143)
		(layer "In11.Cu")
		(net "P5E_CPU1_P3_TX_DN<14>")
	)
	(segment
		(start 125.990858 -290.771834)
		(end 125.95606 -290.7919)
		(width 0.1143)
		(layer "In11.Cu")
		(net "P5E_CPU1_P3_TX_DN<14>")
	)
	(segment
		(start 140.26896 -365.85906)
		(end 140.249656 -365.868712)
		(width 0.14224)
		(layer "In11.Cu")
		(net "P5E_CPU1_P3_TX_DN<14>")
	)
	(segment
		(start 138.876278 -373.701056)
		(end 138.876278 -373.894858)
		(width 0.14224)
		(layer "In11.Cu")
		(net "P5E_CPU1_P3_TX_DN<14>")
	)
	(segment
		(start 127.065024 -296.979086)
		(end 127.199898 -297.423078)
		(width 0.14224)
		(layer "In11.Cu")
		(net "P5E_CPU1_P3_TX_DN<14>")
	)
	(segment
		(start 125.95606 -284.92069)
		(end 125.98781 -284.938978)
		(width 0.1143)
		(layer "In11.Cu")
		(net "P5E_CPU1_P3_TX_DN<14>")
	)
	(segment
		(start 125.987048 -283.318458)
		(end 125.98781 -283.318966)
		(width 0.1143)
		(layer "In11.Cu")
		(net "P5E_CPU1_P3_TX_DN<14>")
	)
	(segment
		(start 125.95606 -291.400484)
		(end 125.98781 -291.418772)
		(width 0.1143)
		(layer "In11.Cu")
		(net "P5E_CPU1_P3_TX_DN<14>")
	)
	(segment
		(start 140.073888 -369.22329)
		(end 139.936728 -369.36045)
		(width 0.14224)
		(layer "In11.Cu")
		(net "P5E_CPU1_P3_TX_DN<14>")
	)
	(segment
		(start 125.990858 -284.29204)
		(end 125.95606 -284.312106)
		(width 0.1143)
		(layer "In11.Cu")
		(net "P5E_CPU1_P3_TX_DN<14>")
	)
	(segment
		(start 125.991366 -294.660828)
		(end 125.992128 -294.661336)
		(width 0.1143)
		(layer "In11.Cu")
		(net "P5E_CPU1_P3_TX_DN<14>")
	)
	(segment
		(start 125.876812 -278.13635)
		(end 125.806962 -278.2062)
		(width 0.1143)
		(layer "In11.Cu")
		(net "P5E_CPU1_P3_TX_DN<14>")
	)
	(segment
		(start 125.954282 -286.539178)
		(end 126.028958 -286.58312)
		(width 0.1143)
		(layer "In11.Cu")
		(net "P5E_CPU1_P3_TX_DN<14>")
	)
	(segment
		(start 137.021316 -375.62282)
		(end 137.021316 -376.188986)
		(width 0.14224)
		(layer "In11.Cu")
		(net "P5E_CPU1_P3_TX_DN<14>")
	)
	(segment
		(start 125.954282 -288.15919)
		(end 125.955044 -288.159698)
		(width 0.1143)
		(layer "In11.Cu")
		(net "P5E_CPU1_P3_TX_DN<14>")
	)
	(segment
		(start 141.281658 -363.41431)
		(end 141.355826 -363.593634)
		(width 0.14224)
		(layer "In11.Cu")
		(net "P5E_CPU1_P3_TX_DN<14>")
	)
	(segment
		(start 141.14907 -316.323218)
		(end 143.552926 -322.122546)
		(width 0.14224)
		(layer "In11.Cu")
		(net "P5E_CPU1_P3_TX_DN<14>")
	)
	(segment
		(start 125.95606 -281.680666)
		(end 125.98781 -281.698954)
		(width 0.1143)
		(layer "In11.Cu")
		(net "P5E_CPU1_P3_TX_DN<14>")
	)
	(segment
		(start 125.95606 -294.640508)
		(end 125.98781 -294.658796)
		(width 0.1143)
		(layer "In11.Cu")
		(net "P5E_CPU1_P3_TX_DN<14>")
	)
	(segment
		(start 134.956296 -307.055266)
		(end 141.14907 -316.323218)
		(width 0.14224)
		(layer "In11.Cu")
		(net "P5E_CPU1_P3_TX_DN<14>")
	)
	(segment
		(start 125.992128 -294.661336)
		(end 126.027942 -294.682418)
		(width 0.1143)
		(layer "In11.Cu")
		(net "P5E_CPU1_P3_TX_DN<14>")
	)
	(segment
		(start 141.192504 -363.988096)
		(end 141.01318 -364.062264)
		(width 0.14224)
		(layer "In11.Cu")
		(net "P5E_CPU1_P3_TX_DN<14>")
	)
	(segment
		(start 125.987048 -278.458422)
		(end 125.98781 -278.45893)
		(width 0.1143)
		(layer "In11.Cu")
		(net "P5E_CPU1_P3_TX_DN<14>")
	)
	(segment
		(start 125.98781 -291.419026)
		(end 126.02591 -291.440616)
		(width 0.1143)
		(layer "In11.Cu")
		(net "P5E_CPU1_P3_TX_DN<14>")
	)
	(segment
		(start 125.955044 -288.159698)
		(end 125.98781 -288.178748)
		(width 0.1143)
		(layer "In11.Cu")
		(net "P5E_CPU1_P3_TX_DN<14>")
	)
	(segment
		(start 126.174754 -278.13635)
		(end 125.876812 -278.13635)
		(width 0.1143)
		(layer "In11.Cu")
		(net "P5E_CPU1_P3_TX_DN<14>")
	)
	(segment
		(start 126.777496 -296.160444)
		(end 126.926086 -296.309034)
		(width 0.1143)
		(layer "In11.Cu")
		(net "P5E_CPU1_P3_TX_DN<14>")
	)
	(segment
		(start 125.990858 -294.011858)
		(end 125.95606 -294.031924)
		(width 0.1143)
		(layer "In11.Cu")
		(net "P5E_CPU1_P3_TX_DN<14>")
	)
	(segment
		(start 125.98781 -281.053794)
		(end 125.95606 -281.072082)
		(width 0.1143)
		(layer "In11.Cu")
		(net "P5E_CPU1_P3_TX_DN<14>")
	)
	(segment
		(start 139.936728 -367.099596)
		(end 139.936728 -368.65941)
		(width 0.14224)
		(layer "In11.Cu")
		(net "P5E_CPU1_P3_TX_DN<14>")
	)
	(segment
		(start 125.990858 -289.151822)
		(end 125.95606 -289.171888)
		(width 0.1143)
		(layer "In11.Cu")
		(net "P5E_CPU1_P3_TX_DN<14>")
	)
	(segment
		(start 125.98781 -278.45893)
		(end 125.988826 -278.459438)
		(width 0.1143)
		(layer "In11.Cu")
		(net "P5E_CPU1_P3_TX_DN<14>")
	)
	(segment
		(start 127.199898 -297.423078)
		(end 127.849884 -298.395644)
		(width 0.14224)
		(layer "In11.Cu")
		(net "P5E_CPU1_P3_TX_DN<14>")
	)
	(segment
		(start 139.936728 -368.65941)
		(end 140.073888 -368.79657)
		(width 0.14224)
		(layer "In11.Cu")
		(net "P5E_CPU1_P3_TX_DN<14>")
	)
	(segment
		(start 125.95606 -289.780472)
		(end 125.98781 -289.79876)
		(width 0.1143)
		(layer "In11.Cu")
		(net "P5E_CPU1_P3_TX_DN<14>")
	)
	(segment
		(start 143.552926 -322.122546)
		(end 147.11299 -340.02091)
		(width 0.14224)
		(layer "In11.Cu")
		(net "P5E_CPU1_P3_TX_DN<14>")
	)
	(segment
		(start 125.98781 -288.178748)
		(end 125.990858 -288.180526)
		(width 0.1143)
		(layer "In11.Cu")
		(net "P5E_CPU1_P3_TX_DN<14>")
	)
	(segment
		(start 139.924282 -371.653562)
		(end 139.867386 -372.03253)
		(width 0.14224)
		(layer "In11.Cu")
		(net "P5E_CPU1_P3_TX_DN<14>")
	)
	(segment
		(start 125.95606 -283.300678)
		(end 125.987048 -283.318458)
		(width 0.1143)
		(layer "In11.Cu")
		(net "P5E_CPU1_P3_TX_DN<14>")
	)
	(segment
		(start 125.98781 -284.938978)
		(end 125.990858 -284.940756)
		(width 0.1143)
		(layer "In11.Cu")
		(net "P5E_CPU1_P3_TX_DN<14>")
	)
	(segment
		(start 125.98781 -283.318966)
		(end 125.990858 -283.320744)
		(width 0.1143)
		(layer "In11.Cu")
		(net "P5E_CPU1_P3_TX_DN<14>")
	)
	(segment
		(start 138.086846 -376.384058)
		(end 138.377676 -376.093228)
		(width 0.14224)
		(layer "In11.Cu")
		(net "P5E_CPU1_P3_TX_DN<14>")
	)
	(segment
		(start 141.355826 -363.593634)
		(end 141.192504 -363.988096)
		(width 0.14224)
		(layer "In11.Cu")
		(net "P5E_CPU1_P3_TX_DN<14>")
	)
	(segment
		(start 140.073888 -370.35105)
		(end 139.983972 -370.440966)
		(width 0.14224)
		(layer "In11.Cu")
		(net "P5E_CPU1_P3_TX_DN<14>")
	)
	(segment
		(start 127.065024 -296.866564)
		(end 127.065024 -296.979086)
		(width 0.14224)
		(layer "In11.Cu")
		(net "P5E_CPU1_P3_TX_DN<14>")
	)
	(segment
		(start 126.270004 -287.046162)
		(end 126.270004 -287.050734)
		(width 0.1143)
		(layer "In11.Cu")
		(net "P5E_CPU1_P3_TX_DN<14>")
	)
	(segment
		(start 125.95606 -293.020496)
		(end 125.98781 -293.038784)
		(width 0.1143)
		(layer "In11.Cu")
		(net "P5E_CPU1_P3_TX_DN<14>")
	)
	(segment
		(start 126.02591 -291.440616)
		(end 126.038864 -291.450014)
		(width 0.1143)
		(layer "In11.Cu")
		(net "P5E_CPU1_P3_TX_DN<14>")
	)
	(segment
		(start 126.258066 -280.57475)
		(end 126.258066 -280.58618)
		(width 0.1143)
		(layer "In11.Cu")
		(net "P5E_CPU1_P3_TX_DN<14>")
	)
	(segment
		(start 126.038864 -292.362382)
		(end 126.02591 -292.37178)
		(width 0.1143)
		(layer "In11.Cu")
		(net "P5E_CPU1_P3_TX_DN<14>")
	)
	(segment
		(start 140.073888 -369.92433)
		(end 140.073888 -370.35105)
		(width 0.14224)
		(layer "In11.Cu")
		(net "P5E_CPU1_P3_TX_DN<14>")
	)
	(segment
		(start 141.01318 -364.062264)
		(end 140.26896 -365.85906)
		(width 0.14224)
		(layer "In11.Cu")
		(net "P5E_CPU1_P3_TX_DN<14>")
	)
	(segment
		(start 125.98781 -294.658796)
		(end 125.991366 -294.660828)
		(width 0.1143)
		(layer "In11.Cu")
		(net "P5E_CPU1_P3_TX_DN<14>")
	)
	(segment
		(start 138.876278 -373.894858)
		(end 138.574272 -374.196864)
		(width 0.14224)
		(layer "In11.Cu")
		(net "P5E_CPU1_P3_TX_DN<14>")
	)
	(segment
		(start 125.98781 -289.79876)
		(end 125.990858 -289.800538)
		(width 0.1143)
		(layer "In11.Cu")
		(net "P5E_CPU1_P3_TX_DN<14>")
	)
	(segment
		(start 125.95606 -278.440642)
		(end 125.987048 -278.458422)
		(width 0.1143)
		(layer "In11.Cu")
		(net "P5E_CPU1_P3_TX_DN<14>")
	)
	(segment
		(start 146.68246 -350.374458)
		(end 141.281658 -363.41431)
		(width 0.14224)
		(layer "In11.Cu")
		(net "P5E_CPU1_P3_TX_DN<14>")
	)
	(segment
		(start 140.073888 -368.79657)
		(end 140.073888 -369.22329)
		(width 0.14224)
		(layer "In11.Cu")
		(net "P5E_CPU1_P3_TX_DN<14>")
	)
	(segment
		(start 125.98781 -291.418772)
		(end 125.98781 -291.419026)
		(width 0.1143)
		(layer "In11.Cu")
		(net "P5E_CPU1_P3_TX_DN<14>")
	)
	(segment
		(start 125.988826 -278.459438)
		(end 126.002796 -278.467566)
		(width 0.1143)
		(layer "In11.Cu")
		(net "P5E_CPU1_P3_TX_DN<14>")
	)
	(segment
		(start 126.444756 -280.251154)
		(end 126.444502 -280.251408)
		(width 0.1143)
		(layer "In11.Cu")
		(net "P5E_CPU1_P3_TX_DN<14>")
	)
	(segment
		(start 138.574272 -374.196864)
		(end 138.38047 -374.196864)
		(width 0.14224)
		(layer "In11.Cu")
		(net "P5E_CPU1_P3_TX_DN<14>")
	)
	(segment
		(start 127.019304 -296.533824)
		(end 127.019304 -296.792396)
		(width 0.1143)
		(layer "In11.Cu")
		(net "P5E_CPU1_P3_TX_DN<14>")
	)
	(segment
		(start 127.019304 -296.792396)
		(end 127.065024 -296.838116)
		(width 0.1143)
		(layer "In11.Cu")
		(net "P5E_CPU1_P3_TX_DN<14>")
	)
	(segment
		(start 126.027942 -287.510474)
		(end 125.95606 -287.55213)
		(width 0.1143)
		(layer "In11.Cu")
		(net "P5E_CPU1_P3_TX_DN<14>")
	)
	(segment
		(start 126.45771 -279.268936)
		(end 126.496826 -279.291796)
		(width 0.1143)
		(layer "In11.Cu")
		(net "P5E_CPU1_P3_TX_DN<14>")
	)
	(segment
		(start 140.249656 -365.868712)
		(end 140.118084 -366.18672)
		(width 0.14224)
		(layer "In11.Cu")
		(net "P5E_CPU1_P3_TX_DN<14>")
	)
	(segment
		(start 147.11299 -340.02091)
		(end 147.11299 -348.210124)
		(width 0.14224)
		(layer "In11.Cu")
		(net "P5E_CPU1_P3_TX_DN<14>")
	)
	(segment
		(start 138.38047 -374.196864)
		(end 137.06856 -375.508774)
		(width 0.14224)
		(layer "In11.Cu")
		(net "P5E_CPU1_P3_TX_DN<14>")
	)
	(segment
		(start 127.065024 -296.838116)
		(end 127.065024 -296.866564)
		(width 0.1143)
		(layer "In11.Cu")
		(net "P5E_CPU1_P3_TX_DN<14>")
	)
	(segment
		(start 139.936728 -369.36045)
		(end 139.936728 -369.78717)
		(width 0.14224)
		(layer "In11.Cu")
		(net "P5E_CPU1_P3_TX_DN<14>")
	)
	(segment
		(start 126.039372 -287.501838)
		(end 126.027942 -287.510474)
		(width 0.1143)
		(layer "In11.Cu")
		(net "P5E_CPU1_P3_TX_DN<14>")
	)
	(arc
		(start 126.607062 -295.592246)
		(mid 126.705762 -295.762346)
		(end 126.740158 -295.955974)
		(width 0.1143)
		(layer "In11.Cu")
		(net "P5E_CPU1_P3_TX_DN<14>")
	)
	(arc
		(start 126.028958 -286.58312)
		(mid 126.206154 -286.785132)
		(end 126.270004 -287.046162)
		(width 0.1143)
		(layer "In11.Cu")
		(net "P5E_CPU1_P3_TX_DN<14>")
	)
	(arc
		(start 125.806962 -278.2062)
		(mid 125.859011 -278.337719)
		(end 125.95606 -278.440642)
		(width 0.1143)
		(layer "In11.Cu")
		(net "P5E_CPU1_P3_TX_DN<14>")
	)
	(arc
		(start 139.428982 -373.100854)
		(mid 139.345049 -373.220398)
		(end 139.24788 -373.329454)
		(width 0.14224)
		(layer "In11.Cu")
		(net "P5E_CPU1_P3_TX_DN<14>")
	)
	(arc
		(start 126.444502 -280.251408)
		(mid 126.308022 -280.388133)
		(end 126.258066 -280.57475)
		(width 0.1143)
		(layer "In11.Cu")
		(net "P5E_CPU1_P3_TX_DN<14>")
	)
	(arc
		(start 125.95606 -287.55213)
		(mid 125.841384 -287.685464)
		(end 125.800104 -287.856422)
		(width 0.1143)
		(layer "In11.Cu")
		(net "P5E_CPU1_P3_TX_DN<14>")
	)
	(arc
		(start 125.95606 -289.171888)
		(mid 125.800132 -289.47618)
		(end 125.95606 -289.780472)
		(width 0.1143)
		(layer "In11.Cu")
		(net "P5E_CPU1_P3_TX_DN<14>")
	)
	(arc
		(start 137.021316 -376.188986)
		(mid 137.031022 -376.237781)
		(end 137.058654 -376.279156)
		(width 0.14224)
		(layer "In11.Cu")
		(net "P5E_CPU1_P3_TX_DN<14>")
	)
	(arc
		(start 126.496572 -295.491154)
		(mid 126.555179 -295.538025)
		(end 126.607062 -295.592246)
		(width 0.1143)
		(layer "In11.Cu")
		(net "P5E_CPU1_P3_TX_DN<14>")
	)
	(arc
		(start 139.983972 -370.440966)
		(mid 139.94901 -370.493291)
		(end 139.936728 -370.555012)
		(width 0.14224)
		(layer "In11.Cu")
		(net "P5E_CPU1_P3_TX_DN<14>")
	)
	(arc
		(start 126.496826 -279.291796)
		(mid 126.740043 -279.756362)
		(end 126.496826 -280.220928)
		(width 0.1143)
		(layer "In11.Cu")
		(net "P5E_CPU1_P3_TX_DN<14>")
	)
	(arc
		(start 125.800104 -287.856422)
		(mid 125.840866 -288.026306)
		(end 125.954282 -288.15919)
		(width 0.1143)
		(layer "In11.Cu")
		(net "P5E_CPU1_P3_TX_DN<14>")
	)
	(arc
		(start 126.926086 -296.309034)
		(mid 126.995081 -296.412153)
		(end 127.019304 -296.533824)
		(width 0.1143)
		(layer "In11.Cu")
		(net "P5E_CPU1_P3_TX_DN<14>")
	)
	(arc
		(start 125.95606 -285.932118)
		(mid 125.841384 -286.065452)
		(end 125.800104 -286.23641)
		(width 0.1143)
		(layer "In11.Cu")
		(net "P5E_CPU1_P3_TX_DN<14>")
	)
	(arc
		(start 147.11299 -348.210124)
		(mid 147.004324 -349.313498)
		(end 146.68246 -350.374458)
		(width 0.14224)
		(layer "In11.Cu")
		(net "P5E_CPU1_P3_TX_DN<14>")
	)
	(arc
		(start 139.867386 -372.03253)
		(mid 139.85379 -372.107438)
		(end 139.835636 -372.181374)
		(width 0.14224)
		(layer "In11.Cu")
		(net "P5E_CPU1_P3_TX_DN<14>")
	)
	(arc
		(start 126.270258 -295.141904)
		(mid 126.320811 -295.331194)
		(end 126.459234 -295.469818)
		(width 0.1143)
		(layer "In11.Cu")
		(net "P5E_CPU1_P3_TX_DN<14>")
	)
	(arc
		(start 125.95606 -281.072082)
		(mid 125.800132 -281.376374)
		(end 125.95606 -281.680666)
		(width 0.1143)
		(layer "In11.Cu")
		(net "P5E_CPU1_P3_TX_DN<14>")
	)
	(arc
		(start 125.990858 -281.700732)
		(mid 126.270473 -282.18638)
		(end 125.990858 -282.672028)
		(width 0.1143)
		(layer "In11.Cu")
		(net "P5E_CPU1_P3_TX_DN<14>")
	)
	(arc
		(start 140.118084 -366.18672)
		(mid 139.982476 -366.634232)
		(end 139.936728 -367.099596)
		(width 0.14224)
		(layer "In11.Cu")
		(net "P5E_CPU1_P3_TX_DN<14>")
	)
	(arc
		(start 125.95606 -294.031924)
		(mid 125.800132 -294.336216)
		(end 125.95606 -294.640508)
		(width 0.1143)
		(layer "In11.Cu")
		(net "P5E_CPU1_P3_TX_DN<14>")
	)
	(arc
		(start 125.990858 -293.040562)
		(mid 126.270473 -293.52621)
		(end 125.990858 -294.011858)
		(width 0.1143)
		(layer "In11.Cu")
		(net "P5E_CPU1_P3_TX_DN<14>")
	)
	(arc
		(start 125.990858 -283.320744)
		(mid 126.270473 -283.806392)
		(end 125.990858 -284.29204)
		(width 0.1143)
		(layer "In11.Cu")
		(net "P5E_CPU1_P3_TX_DN<14>")
	)
	(arc
		(start 125.990858 -284.940756)
		(mid 126.270473 -285.426404)
		(end 125.990858 -285.912052)
		(width 0.1143)
		(layer "In11.Cu")
		(net "P5E_CPU1_P3_TX_DN<14>")
	)
	(arc
		(start 126.270004 -287.050734)
		(mid 126.209005 -287.304058)
		(end 126.039372 -287.501838)
		(width 0.1143)
		(layer "In11.Cu")
		(net "P5E_CPU1_P3_TX_DN<14>")
	)
	(arc
		(start 125.95606 -284.312106)
		(mid 125.800132 -284.616398)
		(end 125.95606 -284.92069)
		(width 0.1143)
		(layer "In11.Cu")
		(net "P5E_CPU1_P3_TX_DN<14>")
	)
	(arc
		(start 126.258066 -280.58618)
		(mid 126.18849 -280.851124)
		(end 125.997716 -281.047698)
		(width 0.1143)
		(layer "In11.Cu")
		(net "P5E_CPU1_P3_TX_DN<14>")
	)
	(arc
		(start 139.835636 -372.181374)
		(mid 139.664123 -372.655185)
		(end 139.428982 -373.100854)
		(width 0.14224)
		(layer "In11.Cu")
		(net "P5E_CPU1_P3_TX_DN<14>")
	)
	(arc
		(start 137.067036 -376.287538)
		(mid 137.173885 -376.358996)
		(end 137.299954 -376.384058)
		(width 0.14224)
		(layer "In11.Cu")
		(net "P5E_CPU1_P3_TX_DN<14>")
	)
	(arc
		(start 126.027942 -294.682418)
		(mid 126.2059 -294.882193)
		(end 126.270258 -295.141904)
		(width 0.1143)
		(layer "In11.Cu")
		(net "P5E_CPU1_P3_TX_DN<14>")
	)
	(arc
		(start 126.002796 -278.467566)
		(mid 126.207741 -278.673228)
		(end 126.282704 -278.953722)
		(width 0.1143)
		(layer "In11.Cu")
		(net "P5E_CPU1_P3_TX_DN<14>")
	)
	(arc
		(start 126.740158 -296.070274)
		(mid 126.749864 -296.119069)
		(end 126.777496 -296.160444)
		(width 0.1143)
		(layer "In11.Cu")
		(net "P5E_CPU1_P3_TX_DN<14>")
	)
	(arc
		(start 137.06856 -375.508774)
		(mid 137.033598 -375.561099)
		(end 137.021316 -375.62282)
		(width 0.14224)
		(layer "In11.Cu")
		(net "P5E_CPU1_P3_TX_DN<14>")
	)
	(arc
		(start 139.936728 -371.48516)
		(mid 139.933664 -371.569595)
		(end 139.924282 -371.653562)
		(width 0.14224)
		(layer "In11.Cu")
		(net "P5E_CPU1_P3_TX_DN<14>")
	)
	(arc
		(start 125.95606 -292.411912)
		(mid 125.800132 -292.716204)
		(end 125.95606 -293.020496)
		(width 0.1143)
		(layer "In11.Cu")
		(net "P5E_CPU1_P3_TX_DN<14>")
	)
	(arc
		(start 125.800104 -286.23641)
		(mid 125.840866 -286.406294)
		(end 125.954282 -286.539178)
		(width 0.1143)
		(layer "In11.Cu")
		(net "P5E_CPU1_P3_TX_DN<14>")
	)
	(arc
		(start 125.95606 -282.692094)
		(mid 125.800132 -282.996386)
		(end 125.95606 -283.300678)
		(width 0.1143)
		(layer "In11.Cu")
		(net "P5E_CPU1_P3_TX_DN<14>")
	)
	(arc
		(start 125.95606 -290.7919)
		(mid 125.800132 -291.096192)
		(end 125.95606 -291.400484)
		(width 0.1143)
		(layer "In11.Cu")
		(net "P5E_CPU1_P3_TX_DN<14>")
	)
	(arc
		(start 126.038864 -291.450014)
		(mid 126.273291 -291.906198)
		(end 126.038864 -292.362382)
		(width 0.1143)
		(layer "In11.Cu")
		(net "P5E_CPU1_P3_TX_DN<14>")
	)
	(arc
		(start 126.282704 -278.966168)
		(mid 126.329595 -279.141034)
		(end 126.45771 -279.268936)
		(width 0.1143)
		(layer "In11.Cu")
		(net "P5E_CPU1_P3_TX_DN<14>")
	)
	(arc
		(start 125.990858 -289.800538)
		(mid 126.270473 -290.286186)
		(end 125.990858 -290.771834)
		(width 0.1143)
		(layer "In11.Cu")
		(net "P5E_CPU1_P3_TX_DN<14>")
	)
	(arc
		(start 125.990858 -288.180526)
		(mid 126.270473 -288.666174)
		(end 125.990858 -289.151822)
		(width 0.1143)
		(layer "In11.Cu")
		(net "P5E_CPU1_P3_TX_DN<14>")
	)
	(segment
		(start 136.505696 -369.03533)
		(end 136.235186 -369.30584)
		(width 0.12954)
		(layer "F.Cu")
		(net "P5E_CPU1_P3_TX_DN<13>")
	)
	(segment
		(start 136.235186 -369.30584)
		(end 136.235186 -370.00942)
		(width 0.12954)
		(layer "F.Cu")
		(net "P5E_CPU1_P3_TX_DN<13>")
	)
	(segment
		(start 125.707902 -274.630388)
		(end 126.174754 -274.896326)
		(width 0.12954)
		(layer "F.Cu")
		(net "P5E_CPU1_P3_TX_DN<13>")
	)
	(segment
		(start 136.235186 -370.00942)
		(end 136.531096 -370.30533)
		(width 0.12954)
		(layer "F.Cu")
		(net "P5E_CPU1_P3_TX_DN<13>")
	)
	(segment
		(start 125.016006 -281.680666)
		(end 125.046994 -281.698446)
		(width 0.1143)
		(layer "In11.Cu")
		(net "P5E_CPU1_P3_TX_DN<13>")
	)
	(segment
		(start 125.048772 -293.039292)
		(end 125.050296 -293.040308)
		(width 0.1143)
		(layer "In11.Cu")
		(net "P5E_CPU1_P3_TX_DN<13>")
	)
	(segment
		(start 125.048772 -285.913322)
		(end 125.047756 -285.91383)
		(width 0.1143)
		(layer "In11.Cu")
		(net "P5E_CPU1_P3_TX_DN<13>")
	)
	(segment
		(start 126.120144 -296.838116)
		(end 126.120144 -296.866564)
		(width 0.1143)
		(layer "In11.Cu")
		(net "P5E_CPU1_P3_TX_DN<13>")
	)
	(segment
		(start 125.517656 -280.243788)
		(end 125.487176 -280.261568)
		(width 0.1143)
		(layer "In11.Cu")
		(net "P5E_CPU1_P3_TX_DN<13>")
	)
	(segment
		(start 125.0442 -290.775644)
		(end 125.043438 -290.776152)
		(width 0.1143)
		(layer "In11.Cu")
		(net "P5E_CPU1_P3_TX_DN<13>")
	)
	(segment
		(start 126.120652 -297.090084)
		(end 126.35484 -297.86199)
		(width 0.14224)
		(layer "In11.Cu")
		(net "P5E_CPU1_P3_TX_DN<13>")
	)
	(segment
		(start 125.047756 -292.393624)
		(end 125.046994 -292.394132)
		(width 0.1143)
		(layer "In11.Cu")
		(net "P5E_CPU1_P3_TX_DN<13>")
	)
	(segment
		(start 125.050296 -276.840442)
		(end 125.051312 -276.84095)
		(width 0.1143)
		(layer "In11.Cu")
		(net "P5E_CPU1_P3_TX_DN<13>")
	)
	(segment
		(start 125.046994 -293.038276)
		(end 125.047756 -293.038784)
		(width 0.1143)
		(layer "In11.Cu")
		(net "P5E_CPU1_P3_TX_DN<13>")
	)
	(segment
		(start 125.040136 -282.678124)
		(end 125.016006 -282.692094)
		(width 0.1143)
		(layer "In11.Cu")
		(net "P5E_CPU1_P3_TX_DN<13>")
	)
	(segment
		(start 125.0442 -285.915862)
		(end 125.043438 -285.91637)
		(width 0.1143)
		(layer "In11.Cu")
		(net "P5E_CPU1_P3_TX_DN<13>")
	)
	(segment
		(start 125.046994 -289.798252)
		(end 125.047756 -289.79876)
		(width 0.1143)
		(layer "In11.Cu")
		(net "P5E_CPU1_P3_TX_DN<13>")
	)
	(segment
		(start 125.046994 -276.194266)
		(end 125.045724 -276.195028)
		(width 0.1143)
		(layer "In11.Cu")
		(net "P5E_CPU1_P3_TX_DN<13>")
	)
	(segment
		(start 125.050296 -281.700478)
		(end 125.051312 -281.700986)
		(width 0.1143)
		(layer "In11.Cu")
		(net "P5E_CPU1_P3_TX_DN<13>")
	)
	(segment
		(start 125.046994 -278.458422)
		(end 125.047756 -278.45893)
		(width 0.1143)
		(layer "In11.Cu")
		(net "P5E_CPU1_P3_TX_DN<13>")
	)
	(segment
		(start 125.048772 -292.393116)
		(end 125.047756 -292.393624)
		(width 0.1143)
		(layer "In11.Cu")
		(net "P5E_CPU1_P3_TX_DN<13>")
	)
	(segment
		(start 125.041914 -292.396926)
		(end 125.041152 -292.397434)
		(width 0.1143)
		(layer "In11.Cu")
		(net "P5E_CPU1_P3_TX_DN<13>")
	)
	(segment
		(start 125.086872 -276.170898)
		(end 125.048772 -276.19325)
		(width 0.1143)
		(layer "In11.Cu")
		(net "P5E_CPU1_P3_TX_DN<13>")
	)
	(segment
		(start 125.047756 -285.91383)
		(end 125.046994 -285.914338)
		(width 0.1143)
		(layer "In11.Cu")
		(net "P5E_CPU1_P3_TX_DN<13>")
	)
	(segment
		(start 125.046994 -285.914338)
		(end 125.045724 -285.9151)
		(width 0.1143)
		(layer "In11.Cu")
		(net "P5E_CPU1_P3_TX_DN<13>")
	)
	(segment
		(start 125.041152 -282.677616)
		(end 125.040136 -282.678124)
		(width 0.1143)
		(layer "In11.Cu")
		(net "P5E_CPU1_P3_TX_DN<13>")
	)
	(segment
		(start 125.014228 -286.539178)
		(end 125.047756 -286.558736)
		(width 0.1143)
		(layer "In11.Cu")
		(net "P5E_CPU1_P3_TX_DN<13>")
	)
	(segment
		(start 125.041152 -289.15741)
		(end 125.040136 -289.157918)
		(width 0.1143)
		(layer "In11.Cu")
		(net "P5E_CPU1_P3_TX_DN<13>")
	)
	(segment
		(start 125.517656 -279.268936)
		(end 125.556772 -279.291796)
		(width 0.1143)
		(layer "In11.Cu")
		(net "P5E_CPU1_P3_TX_DN<13>")
	)
	(segment
		(start 125.043438 -281.056334)
		(end 125.041914 -281.057096)
		(width 0.1143)
		(layer "In11.Cu")
		(net "P5E_CPU1_P3_TX_DN<13>")
	)
	(segment
		(start 125.016006 -289.780472)
		(end 125.046994 -289.798252)
		(width 0.1143)
		(layer "In11.Cu")
		(net "P5E_CPU1_P3_TX_DN<13>")
	)
	(segment
		(start 125.046994 -289.154108)
		(end 125.045724 -289.15487)
		(width 0.1143)
		(layer "In11.Cu")
		(net "P5E_CPU1_P3_TX_DN<13>")
	)
	(segment
		(start 125.048772 -284.939486)
		(end 125.050296 -284.940502)
		(width 0.1143)
		(layer "In11.Cu")
		(net "P5E_CPU1_P3_TX_DN<13>")
	)
	(segment
		(start 125.051312 -293.040816)
		(end 125.086872 -293.061644)
		(width 0.1143)
		(layer "In11.Cu")
		(net "P5E_CPU1_P3_TX_DN<13>")
	)
	(segment
		(start 125.487176 -295.451022)
		(end 125.517656 -295.468802)
		(width 0.1143)
		(layer "In11.Cu")
		(net "P5E_CPU1_P3_TX_DN<13>")
	)
	(segment
		(start 125.048772 -281.053286)
		(end 125.047756 -281.053794)
		(width 0.1143)
		(layer "In11.Cu")
		(net "P5E_CPU1_P3_TX_DN<13>")
	)
	(segment
		(start 125.086872 -277.79091)
		(end 125.048772 -277.813262)
		(width 0.1143)
		(layer "In11.Cu")
		(net "P5E_CPU1_P3_TX_DN<13>")
	)
	(segment
		(start 125.048772 -276.839426)
		(end 125.050296 -276.840442)
		(width 0.1143)
		(layer "In11.Cu")
		(net "P5E_CPU1_P3_TX_DN<13>")
	)
	(segment
		(start 125.046994 -294.658288)
		(end 125.047756 -294.658796)
		(width 0.1143)
		(layer "In11.Cu")
		(net "P5E_CPU1_P3_TX_DN<13>")
	)
	(segment
		(start 126.120652 -296.876978)
		(end 126.120652 -297.090084)
		(width 0.14224)
		(layer "In11.Cu")
		(net "P5E_CPU1_P3_TX_DN<13>")
	)
	(segment
		(start 125.046994 -277.814278)
		(end 125.045724 -277.81504)
		(width 0.1143)
		(layer "In11.Cu")
		(net "P5E_CPU1_P3_TX_DN<13>")
	)
	(segment
		(start 125.047756 -291.418772)
		(end 125.048772 -291.41928)
		(width 0.1143)
		(layer "In11.Cu")
		(net "P5E_CPU1_P3_TX_DN<13>")
	)
	(segment
		(start 125.556772 -275.360892)
		(end 125.517656 -275.383752)
		(width 0.1143)
		(layer "In11.Cu")
		(net "P5E_CPU1_P3_TX_DN<13>")
	)
	(segment
		(start 125.040136 -285.918148)
		(end 125.016006 -285.932118)
		(width 0.1143)
		(layer "In11.Cu")
		(net "P5E_CPU1_P3_TX_DN<13>")
	)
	(segment
		(start 125.084332 -287.512506)
		(end 125.047756 -287.533842)
		(width 0.1143)
		(layer "In11.Cu")
		(net "P5E_CPU1_P3_TX_DN<13>")
	)
	(segment
		(start 125.050296 -283.32049)
		(end 125.086872 -283.341826)
		(width 0.1143)
		(layer "In11.Cu")
		(net "P5E_CPU1_P3_TX_DN<13>")
	)
	(segment
		(start 125.041152 -292.397434)
		(end 125.040136 -292.397942)
		(width 0.1143)
		(layer "In11.Cu")
		(net "P5E_CPU1_P3_TX_DN<13>")
	)
	(segment
		(start 125.045724 -276.195028)
		(end 125.0442 -276.19579)
		(width 0.1143)
		(layer "In11.Cu")
		(net "P5E_CPU1_P3_TX_DN<13>")
	)
	(segment
		(start 125.048772 -284.29331)
		(end 125.047756 -284.293818)
		(width 0.1143)
		(layer "In11.Cu")
		(net "P5E_CPU1_P3_TX_DN<13>")
	)
	(segment
		(start 125.048772 -278.459438)
		(end 125.050296 -278.460454)
		(width 0.1143)
		(layer "In11.Cu")
		(net "P5E_CPU1_P3_TX_DN<13>")
	)
	(segment
		(start 125.0442 -276.19579)
		(end 125.043438 -276.196298)
		(width 0.1143)
		(layer "In11.Cu")
		(net "P5E_CPU1_P3_TX_DN<13>")
	)
	(segment
		(start 138.036808 -364.491524)
		(end 137.059162 -365.46917)
		(width 0.14224)
		(layer "In11.Cu")
		(net "P5E_CPU1_P3_TX_DN<13>")
	)
	(segment
		(start 125.046994 -281.698446)
		(end 125.047756 -281.698954)
		(width 0.1143)
		(layer "In11.Cu")
		(net "P5E_CPU1_P3_TX_DN<13>")
	)
	(segment
		(start 125.047756 -288.178748)
		(end 125.086872 -288.201608)
		(width 0.1143)
		(layer "In11.Cu")
		(net "P5E_CPU1_P3_TX_DN<13>")
	)
	(segment
		(start 125.016006 -284.92069)
		(end 125.047756 -284.938978)
		(width 0.1143)
		(layer "In11.Cu")
		(net "P5E_CPU1_P3_TX_DN<13>")
	)
	(segment
		(start 126.074424 -296.792396)
		(end 126.120144 -296.838116)
		(width 0.1143)
		(layer "In11.Cu")
		(net "P5E_CPU1_P3_TX_DN<13>")
	)
	(segment
		(start 125.051312 -278.460962)
		(end 125.086872 -278.48179)
		(width 0.1143)
		(layer "In11.Cu")
		(net "P5E_CPU1_P3_TX_DN<13>")
	)
	(segment
		(start 125.040136 -289.157918)
		(end 125.016006 -289.171888)
		(width 0.1143)
		(layer "In11.Cu")
		(net "P5E_CPU1_P3_TX_DN<13>")
	)
	(segment
		(start 136.214866 -367.507266)
		(end 136.214866 -368.7445)
		(width 0.14224)
		(layer "In11.Cu")
		(net "P5E_CPU1_P3_TX_DN<13>")
	)
	(segment
		(start 142.63243 -322.38823)
		(end 146.15922 -340.120224)
		(width 0.14224)
		(layer "In11.Cu")
		(net "P5E_CPU1_P3_TX_DN<13>")
	)
	(segment
		(start 125.016006 -278.440642)
		(end 125.046994 -278.458422)
		(width 0.1143)
		(layer "In11.Cu")
		(net "P5E_CPU1_P3_TX_DN<13>")
	)
	(segment
		(start 125.086872 -289.13074)
		(end 125.048772 -289.153092)
		(width 0.1143)
		(layer "In11.Cu")
		(net "P5E_CPU1_P3_TX_DN<13>")
	)
	(segment
		(start 125.086872 -292.370764)
		(end 125.048772 -292.393116)
		(width 0.1143)
		(layer "In11.Cu")
		(net "P5E_CPU1_P3_TX_DN<13>")
	)
	(segment
		(start 125.043438 -290.776152)
		(end 125.041914 -290.776914)
		(width 0.1143)
		(layer "In11.Cu")
		(net "P5E_CPU1_P3_TX_DN<13>")
	)
	(segment
		(start 125.043438 -284.296358)
		(end 125.041914 -284.29712)
		(width 0.1143)
		(layer "In11.Cu")
		(net "P5E_CPU1_P3_TX_DN<13>")
	)
	(segment
		(start 125.050296 -294.66032)
		(end 125.051312 -294.660828)
		(width 0.1143)
		(layer "In11.Cu")
		(net "P5E_CPU1_P3_TX_DN<13>")
	)
	(segment
		(start 125.047756 -294.013636)
		(end 125.046994 -294.014144)
		(width 0.1143)
		(layer "In11.Cu")
		(net "P5E_CPU1_P3_TX_DN<13>")
	)
	(segment
		(start 125.048772 -291.41928)
		(end 125.050296 -291.420296)
		(width 0.1143)
		(layer "In11.Cu")
		(net "P5E_CPU1_P3_TX_DN<13>")
	)
	(segment
		(start 125.040136 -281.058112)
		(end 125.016006 -281.072082)
		(width 0.1143)
		(layer "In11.Cu")
		(net "P5E_CPU1_P3_TX_DN<13>")
	)
	(segment
		(start 125.047756 -276.193758)
		(end 125.046994 -276.194266)
		(width 0.1143)
		(layer "In11.Cu")
		(net "P5E_CPU1_P3_TX_DN<13>")
	)
	(segment
		(start 125.050296 -293.040308)
		(end 125.051312 -293.040816)
		(width 0.1143)
		(layer "In11.Cu")
		(net "P5E_CPU1_P3_TX_DN<13>")
	)
	(segment
		(start 125.047756 -286.558736)
		(end 125.086872 -286.581596)
		(width 0.1143)
		(layer "In11.Cu")
		(net "P5E_CPU1_P3_TX_DN<13>")
	)
	(segment
		(start 125.047756 -294.658796)
		(end 125.048772 -294.659304)
		(width 0.1143)
		(layer "In11.Cu")
		(net "P5E_CPU1_P3_TX_DN<13>")
	)
	(segment
		(start 127.02794 -298.8691)
		(end 134.124192 -307.516022)
		(width 0.14224)
		(layer "In11.Cu")
		(net "P5E_CPU1_P3_TX_DN<13>")
	)
	(segment
		(start 125.041914 -284.29712)
		(end 125.041152 -284.297628)
		(width 0.1143)
		(layer "In11.Cu")
		(net "P5E_CPU1_P3_TX_DN<13>")
	)
	(segment
		(start 126.35484 -297.86199)
		(end 127.02794 -298.8691)
		(width 0.14224)
		(layer "In11.Cu")
		(net "P5E_CPU1_P3_TX_DN<13>")
	)
	(segment
		(start 125.047756 -283.318966)
		(end 125.048772 -283.319474)
		(width 0.1143)
		(layer "In11.Cu")
		(net "P5E_CPU1_P3_TX_DN<13>")
	)
	(segment
		(start 125.047756 -289.1536)
		(end 125.046994 -289.154108)
		(width 0.1143)
		(layer "In11.Cu")
		(net "P5E_CPU1_P3_TX_DN<13>")
	)
	(segment
		(start 125.045724 -294.014906)
		(end 125.016006 -294.031924)
		(width 0.1143)
		(layer "In11.Cu")
		(net "P5E_CPU1_P3_TX_DN<13>")
	)
	(segment
		(start 125.0442 -284.29585)
		(end 125.043438 -284.296358)
		(width 0.1143)
		(layer "In11.Cu")
		(net "P5E_CPU1_P3_TX_DN<13>")
	)
	(segment
		(start 125.0442 -277.815802)
		(end 125.043438 -277.81631)
		(width 0.1143)
		(layer "In11.Cu")
		(net "P5E_CPU1_P3_TX_DN<13>")
	)
	(segment
		(start 125.047756 -281.053794)
		(end 125.046994 -281.054302)
		(width 0.1143)
		(layer "In11.Cu")
		(net "P5E_CPU1_P3_TX_DN<13>")
	)
	(segment
		(start 125.046994 -282.674314)
		(end 125.045724 -282.675076)
		(width 0.1143)
		(layer "In11.Cu")
		(net "P5E_CPU1_P3_TX_DN<13>")
	)
	(segment
		(start 125.045724 -285.9151)
		(end 125.0442 -285.915862)
		(width 0.1143)
		(layer "In11.Cu")
		(net "P5E_CPU1_P3_TX_DN<13>")
	)
	(segment
		(start 125.041152 -277.81758)
		(end 125.040136 -277.818088)
		(width 0.1143)
		(layer "In11.Cu")
		(net "P5E_CPU1_P3_TX_DN<13>")
	)
	(segment
		(start 125.517656 -275.383752)
		(end 125.487176 -275.401532)
		(width 0.1143)
		(layer "In11.Cu")
		(net "P5E_CPU1_P3_TX_DN<13>")
	)
	(segment
		(start 125.045724 -284.295088)
		(end 125.0442 -284.29585)
		(width 0.1143)
		(layer "In11.Cu")
		(net "P5E_CPU1_P3_TX_DN<13>")
	)
	(segment
		(start 146.15922 -340.120224)
		(end 146.15922 -347.006672)
		(width 0.14224)
		(layer "In11.Cu")
		(net "P5E_CPU1_P3_TX_DN<13>")
	)
	(segment
		(start 125.045724 -277.81504)
		(end 125.0442 -277.815802)
		(width 0.1143)
		(layer "In11.Cu")
		(net "P5E_CPU1_P3_TX_DN<13>")
	)
	(segment
		(start 134.124192 -307.516022)
		(end 140.300456 -316.759336)
		(width 0.14224)
		(layer "In11.Cu")
		(net "P5E_CPU1_P3_TX_DN<13>")
	)
	(segment
		(start 125.047756 -284.938978)
		(end 125.048772 -284.939486)
		(width 0.1143)
		(layer "In11.Cu")
		(net "P5E_CPU1_P3_TX_DN<13>")
	)
	(segment
		(start 125.041914 -281.057096)
		(end 125.041152 -281.057604)
		(width 0.1143)
		(layer "In11.Cu")
		(net "P5E_CPU1_P3_TX_DN<13>")
	)
	(segment
		(start 125.047756 -289.79876)
		(end 125.048772 -289.799268)
		(width 0.1143)
		(layer "In11.Cu")
		(net "P5E_CPU1_P3_TX_DN<13>")
	)
	(segment
		(start 125.556772 -280.220928)
		(end 125.517656 -280.243788)
		(width 0.1143)
		(layer "In11.Cu")
		(net "P5E_CPU1_P3_TX_DN<13>")
	)
	(segment
		(start 125.046994 -276.83841)
		(end 125.047756 -276.838918)
		(width 0.1143)
		(layer "In11.Cu")
		(net "P5E_CPU1_P3_TX_DN<13>")
	)
	(segment
		(start 125.016006 -293.020496)
		(end 125.046994 -293.038276)
		(width 0.1143)
		(layer "In11.Cu")
		(net "P5E_CPU1_P3_TX_DN<13>")
	)
	(segment
		(start 125.047756 -281.698954)
		(end 125.048772 -281.699462)
		(width 0.1143)
		(layer "In11.Cu")
		(net "P5E_CPU1_P3_TX_DN<13>")
	)
	(segment
		(start 125.0442 -282.675838)
		(end 125.043438 -282.676346)
		(width 0.1143)
		(layer "In11.Cu")
		(net "P5E_CPU1_P3_TX_DN<13>")
	)
	(segment
		(start 125.086872 -290.750752)
		(end 125.048772 -290.773104)
		(width 0.1143)
		(layer "In11.Cu")
		(net "P5E_CPU1_P3_TX_DN<13>")
	)
	(segment
		(start 125.040136 -276.198076)
		(end 125.016006 -276.212046)
		(width 0.1143)
		(layer "In11.Cu")
		(net "P5E_CPU1_P3_TX_DN<13>")
	)
	(segment
		(start 125.487176 -279.251156)
		(end 125.517656 -279.268936)
		(width 0.1143)
		(layer "In11.Cu")
		(net "P5E_CPU1_P3_TX_DN<13>")
	)
	(segment
		(start 125.086872 -285.89097)
		(end 125.048772 -285.913322)
		(width 0.1143)
		(layer "In11.Cu")
		(net "P5E_CPU1_P3_TX_DN<13>")
	)
	(segment
		(start 125.048772 -281.699462)
		(end 125.050296 -281.700478)
		(width 0.1143)
		(layer "In11.Cu")
		(net "P5E_CPU1_P3_TX_DN<13>")
	)
	(segment
		(start 125.046994 -290.77412)
		(end 125.045724 -290.774882)
		(width 0.1143)
		(layer "In11.Cu")
		(net "P5E_CPU1_P3_TX_DN<13>")
	)
	(segment
		(start 125.046994 -292.394132)
		(end 125.045724 -292.394894)
		(width 0.1143)
		(layer "In11.Cu")
		(net "P5E_CPU1_P3_TX_DN<13>")
	)
	(segment
		(start 125.047756 -282.673806)
		(end 125.046994 -282.674314)
		(width 0.1143)
		(layer "In11.Cu")
		(net "P5E_CPU1_P3_TX_DN<13>")
	)
	(segment
		(start 125.047756 -284.293818)
		(end 125.046994 -284.294326)
		(width 0.1143)
		(layer "In11.Cu")
		(net "P5E_CPU1_P3_TX_DN<13>")
	)
	(segment
		(start 125.016006 -291.400484)
		(end 125.047756 -291.418772)
		(width 0.1143)
		(layer "In11.Cu")
		(net "P5E_CPU1_P3_TX_DN<13>")
	)
	(segment
		(start 126.120144 -296.866564)
		(end 126.120144 -296.87647)
		(width 0.14224)
		(layer "In11.Cu")
		(net "P5E_CPU1_P3_TX_DN<13>")
	)
	(segment
		(start 125.043438 -289.15614)
		(end 125.041914 -289.156902)
		(width 0.1143)
		(layer "In11.Cu")
		(net "P5E_CPU1_P3_TX_DN<13>")
	)
	(segment
		(start 126.074424 -296.540428)
		(end 126.074424 -296.792396)
		(width 0.1143)
		(layer "In11.Cu")
		(net "P5E_CPU1_P3_TX_DN<13>")
	)
	(segment
		(start 125.086872 -293.990776)
		(end 125.048772 -294.013128)
		(width 0.1143)
		(layer "In11.Cu")
		(net "P5E_CPU1_P3_TX_DN<13>")
	)
	(segment
		(start 125.041152 -276.197568)
		(end 125.040136 -276.198076)
		(width 0.1143)
		(layer "In11.Cu")
		(net "P5E_CPU1_P3_TX_DN<13>")
	)
	(segment
		(start 125.0442 -292.395656)
		(end 125.043438 -292.396164)
		(width 0.1143)
		(layer "In11.Cu")
		(net "P5E_CPU1_P3_TX_DN<13>")
	)
	(segment
		(start 125.045724 -292.394894)
		(end 125.0442 -292.395656)
		(width 0.1143)
		(layer "In11.Cu")
		(net "P5E_CPU1_P3_TX_DN<13>")
	)
	(segment
		(start 125.0442 -281.055826)
		(end 125.043438 -281.056334)
		(width 0.1143)
		(layer "In11.Cu")
		(net "P5E_CPU1_P3_TX_DN<13>")
	)
	(segment
		(start 125.041152 -281.057604)
		(end 125.040136 -281.058112)
		(width 0.1143)
		(layer "In11.Cu")
		(net "P5E_CPU1_P3_TX_DN<13>")
	)
	(segment
		(start 125.048772 -294.659304)
		(end 125.050296 -294.66032)
		(width 0.1143)
		(layer "In11.Cu")
		(net "P5E_CPU1_P3_TX_DN<13>")
	)
	(segment
		(start 125.041152 -284.297628)
		(end 125.040136 -284.298136)
		(width 0.1143)
		(layer "In11.Cu")
		(net "P5E_CPU1_P3_TX_DN<13>")
	)
	(segment
		(start 125.048772 -283.319474)
		(end 125.050296 -283.32049)
		(width 0.1143)
		(layer "In11.Cu")
		(net "P5E_CPU1_P3_TX_DN<13>")
	)
	(segment
		(start 125.050296 -278.460454)
		(end 125.051312 -278.460962)
		(width 0.1143)
		(layer "In11.Cu")
		(net "P5E_CPU1_P3_TX_DN<13>")
	)
	(segment
		(start 125.048772 -290.773104)
		(end 125.047756 -290.773612)
		(width 0.1143)
		(layer "In11.Cu")
		(net "P5E_CPU1_P3_TX_DN<13>")
	)
	(segment
		(start 125.050296 -284.940502)
		(end 125.086872 -284.961838)
		(width 0.1143)
		(layer "In11.Cu")
		(net "P5E_CPU1_P3_TX_DN<13>")
	)
	(segment
		(start 125.517656 -295.468802)
		(end 125.556772 -295.491662)
		(width 0.1143)
		(layer "In11.Cu")
		(net "P5E_CPU1_P3_TX_DN<13>")
	)
	(segment
		(start 125.051312 -289.800792)
		(end 125.086872 -289.82162)
		(width 0.1143)
		(layer "In11.Cu")
		(net "P5E_CPU1_P3_TX_DN<13>")
	)
	(segment
		(start 125.040136 -292.397942)
		(end 125.016006 -292.411912)
		(width 0.1143)
		(layer "In11.Cu")
		(net "P5E_CPU1_P3_TX_DN<13>")
	)
	(segment
		(start 125.045724 -282.675076)
		(end 125.0442 -282.675838)
		(width 0.1143)
		(layer "In11.Cu")
		(net "P5E_CPU1_P3_TX_DN<13>")
	)
	(segment
		(start 125.047756 -290.773612)
		(end 125.046994 -290.77412)
		(width 0.1143)
		(layer "In11.Cu")
		(net "P5E_CPU1_P3_TX_DN<13>")
	)
	(segment
		(start 125.048772 -289.153092)
		(end 125.047756 -289.1536)
		(width 0.1143)
		(layer "In11.Cu")
		(net "P5E_CPU1_P3_TX_DN<13>")
	)
	(segment
		(start 125.086872 -284.270958)
		(end 125.048772 -284.29331)
		(width 0.1143)
		(layer "In11.Cu")
		(net "P5E_CPU1_P3_TX_DN<13>")
	)
	(segment
		(start 125.043438 -292.396164)
		(end 125.041914 -292.396926)
		(width 0.1143)
		(layer "In11.Cu")
		(net "P5E_CPU1_P3_TX_DN<13>")
	)
	(segment
		(start 125.045724 -281.055064)
		(end 125.0442 -281.055826)
		(width 0.1143)
		(layer "In11.Cu")
		(net "P5E_CPU1_P3_TX_DN<13>")
	)
	(segment
		(start 125.800104 -295.956228)
		(end 125.800104 -296.05224)
		(width 0.1143)
		(layer "In11.Cu")
		(net "P5E_CPU1_P3_TX_DN<13>")
	)
	(segment
		(start 125.041914 -289.156902)
		(end 125.041152 -289.15741)
		(width 0.1143)
		(layer "In11.Cu")
		(net "P5E_CPU1_P3_TX_DN<13>")
	)
	(segment
		(start 125.045724 -289.15487)
		(end 125.0442 -289.155632)
		(width 0.1143)
		(layer "In11.Cu")
		(net "P5E_CPU1_P3_TX_DN<13>")
	)
	(segment
		(start 125.048772 -282.673298)
		(end 125.047756 -282.673806)
		(width 0.1143)
		(layer "In11.Cu")
		(net "P5E_CPU1_P3_TX_DN<13>")
	)
	(segment
		(start 125.041914 -277.817072)
		(end 125.041152 -277.81758)
		(width 0.1143)
		(layer "In11.Cu")
		(net "P5E_CPU1_P3_TX_DN<13>")
	)
	(segment
		(start 125.876812 -274.896326)
		(end 125.794008 -274.97913)
		(width 0.1143)
		(layer "In11.Cu")
		(net "P5E_CPU1_P3_TX_DN<13>")
	)
	(segment
		(start 126.120144 -296.87647)
		(end 126.120652 -296.876978)
		(width 0.14224)
		(layer "In11.Cu")
		(net "P5E_CPU1_P3_TX_DN<13>")
	)
	(segment
		(start 125.050296 -289.800284)
		(end 125.051312 -289.800792)
		(width 0.1143)
		(layer "In11.Cu")
		(net "P5E_CPU1_P3_TX_DN<13>")
	)
	(segment
		(start 125.046994 -284.294326)
		(end 125.045724 -284.295088)
		(width 0.1143)
		(layer "In11.Cu")
		(net "P5E_CPU1_P3_TX_DN<13>")
	)
	(segment
		(start 125.041152 -285.91764)
		(end 125.040136 -285.918148)
		(width 0.1143)
		(layer "In11.Cu")
		(net "P5E_CPU1_P3_TX_DN<13>")
	)
	(segment
		(start 125.046994 -281.054302)
		(end 125.045724 -281.055064)
		(width 0.1143)
		(layer "In11.Cu")
		(net "P5E_CPU1_P3_TX_DN<13>")
	)
	(segment
		(start 145.368518 -350.981772)
		(end 142.604236 -357.655876)
		(width 0.14224)
		(layer "In11.Cu")
		(net "P5E_CPU1_P3_TX_DN<13>")
	)
	(segment
		(start 126.174754 -274.896326)
		(end 125.876812 -274.896326)
		(width 0.1143)
		(layer "In11.Cu")
		(net "P5E_CPU1_P3_TX_DN<13>")
	)
	(segment
		(start 125.051312 -276.84095)
		(end 125.086872 -276.861778)
		(width 0.1143)
		(layer "In11.Cu")
		(net "P5E_CPU1_P3_TX_DN<13>")
	)
	(segment
		(start 125.048772 -289.799268)
		(end 125.050296 -289.800284)
		(width 0.1143)
		(layer "In11.Cu")
		(net "P5E_CPU1_P3_TX_DN<13>")
	)
	(segment
		(start 125.048772 -276.19325)
		(end 125.047756 -276.193758)
		(width 0.1143)
		(layer "In11.Cu")
		(net "P5E_CPU1_P3_TX_DN<13>")
	)
	(segment
		(start 125.016006 -276.82063)
		(end 125.046994 -276.83841)
		(width 0.1143)
		(layer "In11.Cu")
		(net "P5E_CPU1_P3_TX_DN<13>")
	)
	(segment
		(start 125.047756 -293.038784)
		(end 125.048772 -293.039292)
		(width 0.1143)
		(layer "In11.Cu")
		(net "P5E_CPU1_P3_TX_DN<13>")
	)
	(segment
		(start 125.016006 -283.300678)
		(end 125.047756 -283.318966)
		(width 0.1143)
		(layer "In11.Cu")
		(net "P5E_CPU1_P3_TX_DN<13>")
	)
	(segment
		(start 125.046994 -294.014144)
		(end 125.045724 -294.014906)
		(width 0.1143)
		(layer "In11.Cu")
		(net "P5E_CPU1_P3_TX_DN<13>")
	)
	(segment
		(start 125.047756 -287.533842)
		(end 125.016006 -287.55213)
		(width 0.1143)
		(layer "In11.Cu")
		(net "P5E_CPU1_P3_TX_DN<13>")
	)
	(segment
		(start 125.041914 -276.19706)
		(end 125.041152 -276.197568)
		(width 0.1143)
		(layer "In11.Cu")
		(net "P5E_CPU1_P3_TX_DN<13>")
	)
	(segment
		(start 140.300456 -316.759336)
		(end 142.63243 -322.38823)
		(width 0.14224)
		(layer "In11.Cu")
		(net "P5E_CPU1_P3_TX_DN<13>")
	)
	(segment
		(start 125.050296 -291.420296)
		(end 125.086872 -291.441632)
		(width 0.1143)
		(layer "In11.Cu")
		(net "P5E_CPU1_P3_TX_DN<13>")
	)
	(segment
		(start 136.214866 -368.7445)
		(end 136.505696 -369.03533)
		(width 0.14224)
		(layer "In11.Cu")
		(net "P5E_CPU1_P3_TX_DN<13>")
	)
	(segment
		(start 125.041152 -290.777422)
		(end 125.040136 -290.77793)
		(width 0.1143)
		(layer "In11.Cu")
		(net "P5E_CPU1_P3_TX_DN<13>")
	)
	(segment
		(start 125.041914 -282.677108)
		(end 125.041152 -282.677616)
		(width 0.1143)
		(layer "In11.Cu")
		(net "P5E_CPU1_P3_TX_DN<13>")
	)
	(segment
		(start 125.040136 -290.77793)
		(end 125.016006 -290.7919)
		(width 0.1143)
		(layer "In11.Cu")
		(net "P5E_CPU1_P3_TX_DN<13>")
	)
	(segment
		(start 125.0442 -289.155632)
		(end 125.043438 -289.15614)
		(width 0.1143)
		(layer "In11.Cu")
		(net "P5E_CPU1_P3_TX_DN<13>")
	)
	(segment
		(start 125.040136 -277.818088)
		(end 125.016006 -277.832058)
		(width 0.1143)
		(layer "In11.Cu")
		(net "P5E_CPU1_P3_TX_DN<13>")
	)
	(segment
		(start 125.047756 -278.45893)
		(end 125.048772 -278.459438)
		(width 0.1143)
		(layer "In11.Cu")
		(net "P5E_CPU1_P3_TX_DN<13>")
	)
	(segment
		(start 125.041914 -290.776914)
		(end 125.041152 -290.777422)
		(width 0.1143)
		(layer "In11.Cu")
		(net "P5E_CPU1_P3_TX_DN<13>")
	)
	(segment
		(start 125.045724 -290.774882)
		(end 125.0442 -290.775644)
		(width 0.1143)
		(layer "In11.Cu")
		(net "P5E_CPU1_P3_TX_DN<13>")
	)
	(segment
		(start 125.086872 -281.030934)
		(end 125.048772 -281.053286)
		(width 0.1143)
		(layer "In11.Cu")
		(net "P5E_CPU1_P3_TX_DN<13>")
	)
	(segment
		(start 125.051312 -294.660828)
		(end 125.086872 -294.681656)
		(width 0.1143)
		(layer "In11.Cu")
		(net "P5E_CPU1_P3_TX_DN<13>")
	)
	(segment
		(start 125.041914 -285.917132)
		(end 125.041152 -285.91764)
		(width 0.1143)
		(layer "In11.Cu")
		(net "P5E_CPU1_P3_TX_DN<13>")
	)
	(segment
		(start 125.048772 -277.813262)
		(end 125.047756 -277.81377)
		(width 0.1143)
		(layer "In11.Cu")
		(net "P5E_CPU1_P3_TX_DN<13>")
	)
	(segment
		(start 125.047756 -276.838918)
		(end 125.048772 -276.839426)
		(width 0.1143)
		(layer "In11.Cu")
		(net "P5E_CPU1_P3_TX_DN<13>")
	)
	(segment
		(start 125.043438 -277.81631)
		(end 125.041914 -277.817072)
		(width 0.1143)
		(layer "In11.Cu")
		(net "P5E_CPU1_P3_TX_DN<13>")
	)
	(segment
		(start 125.837442 -296.14241)
		(end 125.960378 -296.265346)
		(width 0.1143)
		(layer "In11.Cu")
		(net "P5E_CPU1_P3_TX_DN<13>")
	)
	(segment
		(start 125.040136 -284.298136)
		(end 125.016006 -284.312106)
		(width 0.1143)
		(layer "In11.Cu")
		(net "P5E_CPU1_P3_TX_DN<13>")
	)
	(segment
		(start 125.048772 -294.013128)
		(end 125.047756 -294.013636)
		(width 0.1143)
		(layer "In11.Cu")
		(net "P5E_CPU1_P3_TX_DN<13>")
	)
	(segment
		(start 125.043438 -276.196298)
		(end 125.041914 -276.19706)
		(width 0.1143)
		(layer "In11.Cu")
		(net "P5E_CPU1_P3_TX_DN<13>")
	)
	(segment
		(start 125.047756 -277.81377)
		(end 125.046994 -277.814278)
		(width 0.1143)
		(layer "In11.Cu")
		(net "P5E_CPU1_P3_TX_DN<13>")
	)
	(segment
		(start 125.051312 -281.700986)
		(end 125.086872 -281.721814)
		(width 0.1143)
		(layer "In11.Cu")
		(net "P5E_CPU1_P3_TX_DN<13>")
	)
	(segment
		(start 125.016006 -294.640508)
		(end 125.046994 -294.658288)
		(width 0.1143)
		(layer "In11.Cu")
		(net "P5E_CPU1_P3_TX_DN<13>")
	)
	(segment
		(start 125.043438 -285.91637)
		(end 125.041914 -285.917132)
		(width 0.1143)
		(layer "In11.Cu")
		(net "P5E_CPU1_P3_TX_DN<13>")
	)
	(segment
		(start 125.014228 -288.15919)
		(end 125.047756 -288.178748)
		(width 0.1143)
		(layer "In11.Cu")
		(net "P5E_CPU1_P3_TX_DN<13>")
	)
	(segment
		(start 125.086872 -282.650946)
		(end 125.048772 -282.673298)
		(width 0.1143)
		(layer "In11.Cu")
		(net "P5E_CPU1_P3_TX_DN<13>")
	)
	(segment
		(start 125.043438 -282.676346)
		(end 125.041914 -282.677108)
		(width 0.1143)
		(layer "In11.Cu")
		(net "P5E_CPU1_P3_TX_DN<13>")
	)
	(arc
		(start 125.556772 -295.491662)
		(mid 125.572723 -295.503072)
		(end 125.588268 -295.51503)
		(width 0.1143)
		(layer "In11.Cu")
		(net "P5E_CPU1_P3_TX_DN<13>")
	)
	(arc
		(start 125.330204 -275.706332)
		(mid 125.265689 -275.968551)
		(end 125.086872 -276.170898)
		(width 0.1143)
		(layer "In11.Cu")
		(net "P5E_CPU1_P3_TX_DN<13>")
	)
	(arc
		(start 125.790198 -275.00199)
		(mid 125.708765 -275.204388)
		(end 125.556772 -275.360892)
		(width 0.1143)
		(layer "In11.Cu")
		(net "P5E_CPU1_P3_TX_DN<13>")
	)
	(arc
		(start 125.016006 -281.072082)
		(mid 124.860078 -281.376374)
		(end 125.016006 -281.680666)
		(width 0.1143)
		(layer "In11.Cu")
		(net "P5E_CPU1_P3_TX_DN<13>")
	)
	(arc
		(start 125.086872 -293.061644)
		(mid 125.330199 -293.52621)
		(end 125.086872 -293.990776)
		(width 0.1143)
		(layer "In11.Cu")
		(net "P5E_CPU1_P3_TX_DN<13>")
	)
	(arc
		(start 125.086872 -286.581596)
		(mid 125.265685 -286.783946)
		(end 125.330204 -287.046162)
		(width 0.1143)
		(layer "In11.Cu")
		(net "P5E_CPU1_P3_TX_DN<13>")
	)
	(arc
		(start 125.800104 -296.05224)
		(mid 125.80981 -296.101035)
		(end 125.837442 -296.14241)
		(width 0.1143)
		(layer "In11.Cu")
		(net "P5E_CPU1_P3_TX_DN<13>")
	)
	(arc
		(start 146.15922 -347.006672)
		(mid 145.959635 -349.033164)
		(end 145.368518 -350.981772)
		(width 0.14224)
		(layer "In11.Cu")
		(net "P5E_CPU1_P3_TX_DN<13>")
	)
	(arc
		(start 125.330204 -295.146222)
		(mid 125.371753 -295.317644)
		(end 125.487176 -295.451022)
		(width 0.1143)
		(layer "In11.Cu")
		(net "P5E_CPU1_P3_TX_DN<13>")
	)
	(arc
		(start 125.016006 -285.932118)
		(mid 124.90133 -286.065452)
		(end 124.86005 -286.23641)
		(width 0.1143)
		(layer "In11.Cu")
		(net "P5E_CPU1_P3_TX_DN<13>")
	)
	(arc
		(start 125.016006 -294.031924)
		(mid 124.860078 -294.336216)
		(end 125.016006 -294.640508)
		(width 0.1143)
		(layer "In11.Cu")
		(net "P5E_CPU1_P3_TX_DN<13>")
	)
	(arc
		(start 125.086872 -281.721814)
		(mid 125.330199 -282.18638)
		(end 125.086872 -282.650946)
		(width 0.1143)
		(layer "In11.Cu")
		(net "P5E_CPU1_P3_TX_DN<13>")
	)
	(arc
		(start 125.330204 -287.046162)
		(mid 125.264968 -287.309753)
		(end 125.084332 -287.512506)
		(width 0.1143)
		(layer "In11.Cu")
		(net "P5E_CPU1_P3_TX_DN<13>")
	)
	(arc
		(start 125.016006 -292.411912)
		(mid 124.860078 -292.716204)
		(end 125.016006 -293.020496)
		(width 0.1143)
		(layer "In11.Cu")
		(net "P5E_CPU1_P3_TX_DN<13>")
	)
	(arc
		(start 125.086872 -284.961838)
		(mid 125.330199 -285.426404)
		(end 125.086872 -285.89097)
		(width 0.1143)
		(layer "In11.Cu")
		(net "P5E_CPU1_P3_TX_DN<13>")
	)
	(arc
		(start 125.016006 -276.212046)
		(mid 124.860078 -276.516338)
		(end 125.016006 -276.82063)
		(width 0.1143)
		(layer "In11.Cu")
		(net "P5E_CPU1_P3_TX_DN<13>")
	)
	(arc
		(start 125.016006 -290.7919)
		(mid 124.860078 -291.096192)
		(end 125.016006 -291.400484)
		(width 0.1143)
		(layer "In11.Cu")
		(net "P5E_CPU1_P3_TX_DN<13>")
	)
	(arc
		(start 125.086872 -276.861778)
		(mid 125.330199 -277.326344)
		(end 125.086872 -277.79091)
		(width 0.1143)
		(layer "In11.Cu")
		(net "P5E_CPU1_P3_TX_DN<13>")
	)
	(arc
		(start 125.016006 -282.692094)
		(mid 124.860078 -282.996386)
		(end 125.016006 -283.300678)
		(width 0.1143)
		(layer "In11.Cu")
		(net "P5E_CPU1_P3_TX_DN<13>")
	)
	(arc
		(start 125.556772 -279.291796)
		(mid 125.800099 -279.756362)
		(end 125.556772 -280.220928)
		(width 0.1143)
		(layer "In11.Cu")
		(net "P5E_CPU1_P3_TX_DN<13>")
	)
	(arc
		(start 125.588268 -295.51503)
		(mid 125.744391 -295.711522)
		(end 125.800104 -295.956228)
		(width 0.1143)
		(layer "In11.Cu")
		(net "P5E_CPU1_P3_TX_DN<13>")
	)
	(arc
		(start 125.016006 -277.832058)
		(mid 124.860078 -278.13635)
		(end 125.016006 -278.440642)
		(width 0.1143)
		(layer "In11.Cu")
		(net "P5E_CPU1_P3_TX_DN<13>")
	)
	(arc
		(start 125.086872 -278.48179)
		(mid 125.265685 -278.68414)
		(end 125.330204 -278.946356)
		(width 0.1143)
		(layer "In11.Cu")
		(net "P5E_CPU1_P3_TX_DN<13>")
	)
	(arc
		(start 125.086872 -289.82162)
		(mid 125.330199 -290.286186)
		(end 125.086872 -290.750752)
		(width 0.1143)
		(layer "In11.Cu")
		(net "P5E_CPU1_P3_TX_DN<13>")
	)
	(arc
		(start 125.016006 -289.171888)
		(mid 124.860078 -289.47618)
		(end 125.016006 -289.780472)
		(width 0.1143)
		(layer "In11.Cu")
		(net "P5E_CPU1_P3_TX_DN<13>")
	)
	(arc
		(start 125.794008 -274.97913)
		(mid 125.79222 -274.990579)
		(end 125.790198 -275.00199)
		(width 0.1143)
		(layer "In11.Cu")
		(net "P5E_CPU1_P3_TX_DN<13>")
	)
	(arc
		(start 125.016006 -287.55213)
		(mid 124.90133 -287.685464)
		(end 124.86005 -287.856422)
		(width 0.1143)
		(layer "In11.Cu")
		(net "P5E_CPU1_P3_TX_DN<13>")
	)
	(arc
		(start 125.487176 -280.261568)
		(mid 125.371749 -280.394944)
		(end 125.330204 -280.566368)
		(width 0.1143)
		(layer "In11.Cu")
		(net "P5E_CPU1_P3_TX_DN<13>")
	)
	(arc
		(start 125.330204 -280.566368)
		(mid 125.265689 -280.828587)
		(end 125.086872 -281.030934)
		(width 0.1143)
		(layer "In11.Cu")
		(net "P5E_CPU1_P3_TX_DN<13>")
	)
	(arc
		(start 125.086872 -294.681656)
		(mid 125.265685 -294.884006)
		(end 125.330204 -295.146222)
		(width 0.1143)
		(layer "In11.Cu")
		(net "P5E_CPU1_P3_TX_DN<13>")
	)
	(arc
		(start 125.016006 -284.312106)
		(mid 124.860078 -284.616398)
		(end 125.016006 -284.92069)
		(width 0.1143)
		(layer "In11.Cu")
		(net "P5E_CPU1_P3_TX_DN<13>")
	)
	(arc
		(start 124.86005 -287.856422)
		(mid 124.900812 -288.026306)
		(end 125.014228 -288.15919)
		(width 0.1143)
		(layer "In11.Cu")
		(net "P5E_CPU1_P3_TX_DN<13>")
	)
	(arc
		(start 125.086872 -283.341826)
		(mid 125.330199 -283.806392)
		(end 125.086872 -284.270958)
		(width 0.1143)
		(layer "In11.Cu")
		(net "P5E_CPU1_P3_TX_DN<13>")
	)
	(arc
		(start 125.960378 -296.265346)
		(mid 126.044762 -296.39154)
		(end 126.074424 -296.540428)
		(width 0.1143)
		(layer "In11.Cu")
		(net "P5E_CPU1_P3_TX_DN<13>")
	)
	(arc
		(start 125.086872 -291.441632)
		(mid 125.330199 -291.906198)
		(end 125.086872 -292.370764)
		(width 0.1143)
		(layer "In11.Cu")
		(net "P5E_CPU1_P3_TX_DN<13>")
	)
	(arc
		(start 125.487176 -275.401532)
		(mid 125.371749 -275.534908)
		(end 125.330204 -275.706332)
		(width 0.1143)
		(layer "In11.Cu")
		(net "P5E_CPU1_P3_TX_DN<13>")
	)
	(arc
		(start 125.086872 -288.201608)
		(mid 125.330199 -288.666174)
		(end 125.086872 -289.13074)
		(width 0.1143)
		(layer "In11.Cu")
		(net "P5E_CPU1_P3_TX_DN<13>")
	)
	(arc
		(start 137.059162 -365.46917)
		(mid 136.434304 -366.404242)
		(end 136.214866 -367.507266)
		(width 0.14224)
		(layer "In11.Cu")
		(net "P5E_CPU1_P3_TX_DN<13>")
	)
	(arc
		(start 124.86005 -286.23641)
		(mid 124.900812 -286.406294)
		(end 125.014228 -286.539178)
		(width 0.1143)
		(layer "In11.Cu")
		(net "P5E_CPU1_P3_TX_DN<13>")
	)
	(arc
		(start 125.330204 -278.946356)
		(mid 125.371753 -279.117778)
		(end 125.487176 -279.251156)
		(width 0.1143)
		(layer "In11.Cu")
		(net "P5E_CPU1_P3_TX_DN<13>")
	)
	(arc
		(start 142.604236 -357.655876)
		(mid 140.65716 -361.298635)
		(end 138.036808 -364.491524)
		(width 0.14224)
		(layer "In11.Cu")
		(net "P5E_CPU1_P3_TX_DN<13>")
	)
	(segment
		(start 132.831586 -369.30584)
		(end 132.831586 -370.00942)
		(width 0.12954)
		(layer "F.Cu")
		(net "P5E_CPU1_P3_TX_DN<12>")
	)
	(segment
		(start 122.887994 -276.2504)
		(end 123.354846 -276.516338)
		(width 0.12954)
		(layer "F.Cu")
		(net "P5E_CPU1_P3_TX_DN<12>")
	)
	(segment
		(start 132.831586 -370.00942)
		(end 133.127496 -370.30533)
		(width 0.12954)
		(layer "F.Cu")
		(net "P5E_CPU1_P3_TX_DN<12>")
	)
	(segment
		(start 133.102096 -369.03533)
		(end 132.831586 -369.30584)
		(width 0.12954)
		(layer "F.Cu")
		(net "P5E_CPU1_P3_TX_DN<12>")
	)
	(segment
		(start 124.107702 -284.293818)
		(end 124.077222 -284.311598)
		(width 0.1143)
		(layer "In11.Cu")
		(net "P5E_CPU1_P3_TX_DN<12>")
	)
	(segment
		(start 124.107702 -289.79876)
		(end 124.146818 -289.82162)
		(width 0.1143)
		(layer "In11.Cu")
		(net "P5E_CPU1_P3_TX_DN<12>")
	)
	(segment
		(start 124.616972 -280.220928)
		(end 124.577856 -280.243788)
		(width 0.1143)
		(layer "In11.Cu")
		(net "P5E_CPU1_P3_TX_DN<12>")
	)
	(segment
		(start 124.578872 -279.269444)
		(end 124.580396 -279.27046)
		(width 0.1143)
		(layer "In11.Cu")
		(net "P5E_CPU1_P3_TX_DN<12>")
	)
	(segment
		(start 124.107702 -288.178748)
		(end 124.146818 -288.201608)
		(width 0.1143)
		(layer "In11.Cu")
		(net "P5E_CPU1_P3_TX_DN<12>")
	)
	(segment
		(start 125.15469 -296.838116)
		(end 125.15469 -296.866564)
		(width 0.1143)
		(layer "In11.Cu")
		(net "P5E_CPU1_P3_TX_DN<12>")
	)
	(segment
		(start 124.577602 -295.468802)
		(end 124.616718 -295.491662)
		(width 0.1143)
		(layer "In11.Cu")
		(net "P5E_CPU1_P3_TX_DN<12>")
	)
	(segment
		(start 125.15469 -296.866564)
		(end 125.15469 -296.87647)
		(width 0.14224)
		(layer "In11.Cu")
		(net "P5E_CPU1_P3_TX_DN<12>")
	)
	(segment
		(start 124.577094 -280.244296)
		(end 124.575824 -280.245058)
		(width 0.1143)
		(layer "In11.Cu")
		(net "P5E_CPU1_P3_TX_DN<12>")
	)
	(segment
		(start 124.107702 -286.558736)
		(end 124.146818 -286.581596)
		(width 0.1143)
		(layer "In11.Cu")
		(net "P5E_CPU1_P3_TX_DN<12>")
	)
	(segment
		(start 123.450096 -277.326344)
		(end 123.450096 -277.329392)
		(width 0.1143)
		(layer "In11.Cu")
		(net "P5E_CPU1_P3_TX_DN<12>")
	)
	(segment
		(start 124.077222 -283.301186)
		(end 124.107702 -283.318966)
		(width 0.1143)
		(layer "In11.Cu")
		(net "P5E_CPU1_P3_TX_DN<12>")
	)
	(segment
		(start 124.107702 -278.45893)
		(end 124.146818 -278.48179)
		(width 0.1143)
		(layer "In11.Cu")
		(net "P5E_CPU1_P3_TX_DN<12>")
	)
	(segment
		(start 124.107702 -282.673806)
		(end 124.077222 -282.691586)
		(width 0.1143)
		(layer "In11.Cu")
		(net "P5E_CPU1_P3_TX_DN<12>")
	)
	(segment
		(start 133.474968 -308.305708)
		(end 136.479788 -312.802524)
		(width 0.14224)
		(layer "In11.Cu")
		(net "P5E_CPU1_P3_TX_DN<12>")
	)
	(segment
		(start 124.107702 -283.318966)
		(end 124.146818 -283.341826)
		(width 0.1143)
		(layer "In11.Cu")
		(net "P5E_CPU1_P3_TX_DN<12>")
	)
	(segment
		(start 123.136152 -276.82063)
		(end 123.16714 -276.83841)
		(width 0.1143)
		(layer "In11.Cu")
		(net "P5E_CPU1_P3_TX_DN<12>")
	)
	(segment
		(start 126.584964 -299.910246)
		(end 133.474968 -308.305708)
		(width 0.14224)
		(layer "In11.Cu")
		(net "P5E_CPU1_P3_TX_DN<12>")
	)
	(segment
		(start 144.72539 -349.405956)
		(end 141.017752 -358.357424)
		(width 0.14224)
		(layer "In11.Cu")
		(net "P5E_CPU1_P3_TX_DN<12>")
	)
	(segment
		(start 136.479788 -312.802778)
		(end 139.492228 -317.311278)
		(width 0.14224)
		(layer "In11.Cu")
		(net "P5E_CPU1_P3_TX_DN<12>")
	)
	(segment
		(start 124.146818 -281.030934)
		(end 124.107702 -281.053794)
		(width 0.1143)
		(layer "In11.Cu")
		(net "P5E_CPU1_P3_TX_DN<12>")
	)
	(segment
		(start 124.581412 -279.270968)
		(end 124.616972 -279.291796)
		(width 0.1143)
		(layer "In11.Cu")
		(net "P5E_CPU1_P3_TX_DN<12>")
	)
	(segment
		(start 124.107702 -293.038784)
		(end 124.146818 -293.061644)
		(width 0.1143)
		(layer "In11.Cu")
		(net "P5E_CPU1_P3_TX_DN<12>")
	)
	(segment
		(start 124.077222 -291.400992)
		(end 124.107702 -291.418772)
		(width 0.1143)
		(layer "In11.Cu")
		(net "P5E_CPU1_P3_TX_DN<12>")
	)
	(segment
		(start 141.413992 -321.95008)
		(end 145.211292 -340.25205)
		(width 0.14224)
		(layer "In11.Cu")
		(net "P5E_CPU1_P3_TX_DN<12>")
	)
	(segment
		(start 124.077222 -278.44115)
		(end 124.107702 -278.45893)
		(width 0.1143)
		(layer "In11.Cu")
		(net "P5E_CPU1_P3_TX_DN<12>")
	)
	(segment
		(start 125.10897 -296.509694)
		(end 125.10897 -296.792396)
		(width 0.1143)
		(layer "In11.Cu")
		(net "P5E_CPU1_P3_TX_DN<12>")
	)
	(segment
		(start 125.155198 -296.876978)
		(end 125.155198 -297.149774)
		(width 0.14224)
		(layer "In11.Cu")
		(net "P5E_CPU1_P3_TX_DN<12>")
	)
	(segment
		(start 124.916184 -296.185336)
		(end 125.015498 -296.284904)
		(width 0.1143)
		(layer "In11.Cu")
		(net "P5E_CPU1_P3_TX_DN<12>")
	)
	(segment
		(start 124.077222 -281.681174)
		(end 124.107702 -281.698954)
		(width 0.1143)
		(layer "In11.Cu")
		(net "P5E_CPU1_P3_TX_DN<12>")
	)
	(segment
		(start 124.077222 -284.921198)
		(end 124.107702 -284.938978)
		(width 0.1143)
		(layer "In11.Cu")
		(net "P5E_CPU1_P3_TX_DN<12>")
	)
	(segment
		(start 124.580396 -279.27046)
		(end 124.581412 -279.270968)
		(width 0.1143)
		(layer "In11.Cu")
		(net "P5E_CPU1_P3_TX_DN<12>")
	)
	(segment
		(start 124.577856 -280.243788)
		(end 124.577094 -280.244296)
		(width 0.1143)
		(layer "In11.Cu")
		(net "P5E_CPU1_P3_TX_DN<12>")
	)
	(segment
		(start 136.479788 -312.802524)
		(end 136.479788 -312.802778)
		(width 0.14224)
		(layer "In11.Cu")
		(net "P5E_CPU1_P3_TX_DN<12>")
	)
	(segment
		(start 124.107702 -291.418772)
		(end 124.146818 -291.441632)
		(width 0.1143)
		(layer "In11.Cu")
		(net "P5E_CPU1_P3_TX_DN<12>")
	)
	(segment
		(start 124.107702 -294.013636)
		(end 124.077222 -294.031416)
		(width 0.1143)
		(layer "In11.Cu")
		(net "P5E_CPU1_P3_TX_DN<12>")
	)
	(segment
		(start 124.07519 -288.159952)
		(end 124.107702 -288.178748)
		(width 0.1143)
		(layer "In11.Cu")
		(net "P5E_CPU1_P3_TX_DN<12>")
	)
	(segment
		(start 124.107702 -281.053794)
		(end 124.077222 -281.071574)
		(width 0.1143)
		(layer "In11.Cu")
		(net "P5E_CPU1_P3_TX_DN<12>")
	)
	(segment
		(start 124.146818 -285.89097)
		(end 124.107702 -285.91383)
		(width 0.1143)
		(layer "In11.Cu")
		(net "P5E_CPU1_P3_TX_DN<12>")
	)
	(segment
		(start 124.077222 -289.78098)
		(end 124.107702 -289.79876)
		(width 0.1143)
		(layer "In11.Cu")
		(net "P5E_CPU1_P3_TX_DN<12>")
	)
	(segment
		(start 124.107702 -281.698954)
		(end 124.146818 -281.721814)
		(width 0.1143)
		(layer "In11.Cu")
		(net "P5E_CPU1_P3_TX_DN<12>")
	)
	(segment
		(start 124.546106 -279.250648)
		(end 124.577094 -279.268428)
		(width 0.1143)
		(layer "In11.Cu")
		(net "P5E_CPU1_P3_TX_DN<12>")
	)
	(segment
		(start 125.155198 -297.149774)
		(end 125.50013 -298.286678)
		(width 0.14224)
		(layer "In11.Cu")
		(net "P5E_CPU1_P3_TX_DN<12>")
	)
	(segment
		(start 124.07519 -286.53994)
		(end 124.107702 -286.558736)
		(width 0.1143)
		(layer "In11.Cu")
		(net "P5E_CPU1_P3_TX_DN<12>")
	)
	(segment
		(start 124.146818 -290.750752)
		(end 124.107702 -290.773612)
		(width 0.1143)
		(layer "In11.Cu")
		(net "P5E_CPU1_P3_TX_DN<12>")
	)
	(segment
		(start 123.167902 -276.838918)
		(end 123.171204 -276.84095)
		(width 0.1143)
		(layer "In11.Cu")
		(net "P5E_CPU1_P3_TX_DN<12>")
	)
	(segment
		(start 124.077222 -293.021004)
		(end 124.107702 -293.038784)
		(width 0.1143)
		(layer "In11.Cu")
		(net "P5E_CPU1_P3_TX_DN<12>")
	)
	(segment
		(start 125.15469 -296.87647)
		(end 125.155198 -296.876978)
		(width 0.14224)
		(layer "In11.Cu")
		(net "P5E_CPU1_P3_TX_DN<12>")
	)
	(segment
		(start 123.16714 -276.83841)
		(end 123.167902 -276.838918)
		(width 0.1143)
		(layer "In11.Cu")
		(net "P5E_CPU1_P3_TX_DN<12>")
	)
	(segment
		(start 145.211292 -340.25205)
		(end 145.211292 -346.963238)
		(width 0.14224)
		(layer "In11.Cu")
		(net "P5E_CPU1_P3_TX_DN<12>")
	)
	(segment
		(start 124.077222 -294.641016)
		(end 124.107702 -294.658796)
		(width 0.1143)
		(layer "In11.Cu")
		(net "P5E_CPU1_P3_TX_DN<12>")
	)
	(segment
		(start 123.056904 -276.516338)
		(end 122.987054 -276.586188)
		(width 0.1143)
		(layer "In11.Cu")
		(net "P5E_CPU1_P3_TX_DN<12>")
	)
	(segment
		(start 124.107702 -292.393624)
		(end 124.077222 -292.411404)
		(width 0.1143)
		(layer "In11.Cu")
		(net "P5E_CPU1_P3_TX_DN<12>")
	)
	(segment
		(start 132.811266 -368.7445)
		(end 133.102096 -369.03533)
		(width 0.14224)
		(layer "In11.Cu")
		(net "P5E_CPU1_P3_TX_DN<12>")
	)
	(segment
		(start 138.0871 -362.743496)
		(end 132.878576 -367.95202)
		(width 0.14224)
		(layer "In11.Cu")
		(net "P5E_CPU1_P3_TX_DN<12>")
	)
	(segment
		(start 124.146818 -284.270958)
		(end 124.107702 -284.293818)
		(width 0.1143)
		(layer "In11.Cu")
		(net "P5E_CPU1_P3_TX_DN<12>")
	)
	(segment
		(start 124.577094 -279.268428)
		(end 124.577856 -279.268936)
		(width 0.1143)
		(layer "In11.Cu")
		(net "P5E_CPU1_P3_TX_DN<12>")
	)
	(segment
		(start 124.107702 -285.91383)
		(end 124.077222 -285.93161)
		(width 0.1143)
		(layer "In11.Cu")
		(net "P5E_CPU1_P3_TX_DN<12>")
	)
	(segment
		(start 125.50013 -298.286678)
		(end 126.584964 -299.910246)
		(width 0.14224)
		(layer "In11.Cu")
		(net "P5E_CPU1_P3_TX_DN<12>")
	)
	(segment
		(start 124.107702 -290.773612)
		(end 124.077222 -290.791392)
		(width 0.1143)
		(layer "In11.Cu")
		(net "P5E_CPU1_P3_TX_DN<12>")
	)
	(segment
		(start 125.10897 -296.792396)
		(end 125.15469 -296.838116)
		(width 0.1143)
		(layer "In11.Cu")
		(net "P5E_CPU1_P3_TX_DN<12>")
	)
	(segment
		(start 124.547122 -295.451022)
		(end 124.577602 -295.468802)
		(width 0.1143)
		(layer "In11.Cu")
		(net "P5E_CPU1_P3_TX_DN<12>")
	)
	(segment
		(start 124.86005 -295.956228)
		(end 124.86005 -296.050462)
		(width 0.1143)
		(layer "In11.Cu")
		(net "P5E_CPU1_P3_TX_DN<12>")
	)
	(segment
		(start 124.107702 -289.1536)
		(end 124.077222 -289.17138)
		(width 0.1143)
		(layer "In11.Cu")
		(net "P5E_CPU1_P3_TX_DN<12>")
	)
	(segment
		(start 139.492228 -317.311278)
		(end 141.413992 -321.95008)
		(width 0.14224)
		(layer "In11.Cu")
		(net "P5E_CPU1_P3_TX_DN<12>")
	)
	(segment
		(start 124.146818 -289.13074)
		(end 124.107702 -289.1536)
		(width 0.1143)
		(layer "In11.Cu")
		(net "P5E_CPU1_P3_TX_DN<12>")
	)
	(segment
		(start 132.811266 -368.11458)
		(end 132.811266 -368.7445)
		(width 0.14224)
		(layer "In11.Cu")
		(net "P5E_CPU1_P3_TX_DN<12>")
	)
	(segment
		(start 124.144278 -287.512506)
		(end 124.077222 -287.551622)
		(width 0.1143)
		(layer "In11.Cu")
		(net "P5E_CPU1_P3_TX_DN<12>")
	)
	(segment
		(start 124.146818 -282.650946)
		(end 124.107702 -282.673806)
		(width 0.1143)
		(layer "In11.Cu")
		(net "P5E_CPU1_P3_TX_DN<12>")
	)
	(segment
		(start 123.603258 -277.628604)
		(end 123.606052 -277.630636)
		(width 0.1143)
		(layer "In11.Cu")
		(net "P5E_CPU1_P3_TX_DN<12>")
	)
	(segment
		(start 124.146818 -292.370764)
		(end 124.107702 -292.393624)
		(width 0.1143)
		(layer "In11.Cu")
		(net "P5E_CPU1_P3_TX_DN<12>")
	)
	(segment
		(start 123.354846 -276.516338)
		(end 123.056904 -276.516338)
		(width 0.1143)
		(layer "In11.Cu")
		(net "P5E_CPU1_P3_TX_DN<12>")
	)
	(segment
		(start 123.171204 -276.84095)
		(end 123.204224 -276.86)
		(width 0.1143)
		(layer "In11.Cu")
		(net "P5E_CPU1_P3_TX_DN<12>")
	)
	(segment
		(start 124.577856 -279.268936)
		(end 124.578872 -279.269444)
		(width 0.1143)
		(layer "In11.Cu")
		(net "P5E_CPU1_P3_TX_DN<12>")
	)
	(segment
		(start 124.107702 -284.938978)
		(end 124.146818 -284.961838)
		(width 0.1143)
		(layer "In11.Cu")
		(net "P5E_CPU1_P3_TX_DN<12>")
	)
	(segment
		(start 124.107702 -294.658796)
		(end 124.146818 -294.681656)
		(width 0.1143)
		(layer "In11.Cu")
		(net "P5E_CPU1_P3_TX_DN<12>")
	)
	(segment
		(start 123.606052 -277.630636)
		(end 123.676918 -277.671784)
		(width 0.1143)
		(layer "In11.Cu")
		(net "P5E_CPU1_P3_TX_DN<12>")
	)
	(segment
		(start 124.146818 -293.990776)
		(end 124.107702 -294.013636)
		(width 0.1143)
		(layer "In11.Cu")
		(net "P5E_CPU1_P3_TX_DN<12>")
	)
	(segment
		(start 124.575824 -280.245058)
		(end 124.546106 -280.262076)
		(width 0.1143)
		(layer "In11.Cu")
		(net "P5E_CPU1_P3_TX_DN<12>")
	)
	(arc
		(start 124.616972 -279.291796)
		(mid 124.860299 -279.756362)
		(end 124.616972 -280.220928)
		(width 0.1143)
		(layer "In11.Cu")
		(net "P5E_CPU1_P3_TX_DN<12>")
	)
	(arc
		(start 124.146818 -281.721814)
		(mid 124.390145 -282.18638)
		(end 124.146818 -282.650946)
		(width 0.1143)
		(layer "In11.Cu")
		(net "P5E_CPU1_P3_TX_DN<12>")
	)
	(arc
		(start 145.211292 -346.963238)
		(mid 145.088644 -348.208529)
		(end 144.72539 -349.405956)
		(width 0.14224)
		(layer "In11.Cu")
		(net "P5E_CPU1_P3_TX_DN<12>")
	)
	(arc
		(start 123.92025 -287.856422)
		(mid 123.961216 -288.026828)
		(end 124.07519 -288.159952)
		(width 0.1143)
		(layer "In11.Cu")
		(net "P5E_CPU1_P3_TX_DN<12>")
	)
	(arc
		(start 124.39015 -287.046162)
		(mid 124.324914 -287.309753)
		(end 124.144278 -287.512506)
		(width 0.1143)
		(layer "In11.Cu")
		(net "P5E_CPU1_P3_TX_DN<12>")
	)
	(arc
		(start 123.204224 -276.86)
		(mid 123.384876 -277.062745)
		(end 123.450096 -277.326344)
		(width 0.1143)
		(layer "In11.Cu")
		(net "P5E_CPU1_P3_TX_DN<12>")
	)
	(arc
		(start 124.146818 -291.441632)
		(mid 124.390145 -291.906198)
		(end 124.146818 -292.370764)
		(width 0.1143)
		(layer "In11.Cu")
		(net "P5E_CPU1_P3_TX_DN<12>")
	)
	(arc
		(start 122.987054 -276.586188)
		(mid 123.039103 -276.717707)
		(end 123.136152 -276.82063)
		(width 0.1143)
		(layer "In11.Cu")
		(net "P5E_CPU1_P3_TX_DN<12>")
	)
	(arc
		(start 123.92025 -286.23641)
		(mid 123.961216 -286.406816)
		(end 124.07519 -286.53994)
		(width 0.1143)
		(layer "In11.Cu")
		(net "P5E_CPU1_P3_TX_DN<12>")
	)
	(arc
		(start 124.86005 -296.050462)
		(mid 124.874688 -296.12349)
		(end 124.916184 -296.185336)
		(width 0.1143)
		(layer "In11.Cu")
		(net "P5E_CPU1_P3_TX_DN<12>")
	)
	(arc
		(start 124.648214 -295.51503)
		(mid 124.804337 -295.711522)
		(end 124.86005 -295.956228)
		(width 0.1143)
		(layer "In11.Cu")
		(net "P5E_CPU1_P3_TX_DN<12>")
	)
	(arc
		(start 124.146818 -288.201608)
		(mid 124.390145 -288.666174)
		(end 124.146818 -289.13074)
		(width 0.1143)
		(layer "In11.Cu")
		(net "P5E_CPU1_P3_TX_DN<12>")
	)
	(arc
		(start 124.146818 -286.581596)
		(mid 124.325631 -286.783946)
		(end 124.39015 -287.046162)
		(width 0.1143)
		(layer "In11.Cu")
		(net "P5E_CPU1_P3_TX_DN<12>")
	)
	(arc
		(start 124.616718 -295.491662)
		(mid 124.632669 -295.503072)
		(end 124.648214 -295.51503)
		(width 0.1143)
		(layer "In11.Cu")
		(net "P5E_CPU1_P3_TX_DN<12>")
	)
	(arc
		(start 124.077222 -281.071574)
		(mid 123.920245 -281.376374)
		(end 124.077222 -281.681174)
		(width 0.1143)
		(layer "In11.Cu")
		(net "P5E_CPU1_P3_TX_DN<12>")
	)
	(arc
		(start 124.146818 -283.341826)
		(mid 124.390145 -283.806392)
		(end 124.146818 -284.270958)
		(width 0.1143)
		(layer "In11.Cu")
		(net "P5E_CPU1_P3_TX_DN<12>")
	)
	(arc
		(start 124.39015 -280.566368)
		(mid 124.325635 -280.828587)
		(end 124.146818 -281.030934)
		(width 0.1143)
		(layer "In11.Cu")
		(net "P5E_CPU1_P3_TX_DN<12>")
	)
	(arc
		(start 123.676918 -277.671784)
		(mid 123.855731 -277.874134)
		(end 123.92025 -278.13635)
		(width 0.1143)
		(layer "In11.Cu")
		(net "P5E_CPU1_P3_TX_DN<12>")
	)
	(arc
		(start 123.92025 -278.13635)
		(mid 123.961799 -278.307772)
		(end 124.077222 -278.44115)
		(width 0.1143)
		(layer "In11.Cu")
		(net "P5E_CPU1_P3_TX_DN<12>")
	)
	(arc
		(start 124.146818 -278.48179)
		(mid 124.325631 -278.68414)
		(end 124.39015 -278.946356)
		(width 0.1143)
		(layer "In11.Cu")
		(net "P5E_CPU1_P3_TX_DN<12>")
	)
	(arc
		(start 124.39015 -278.946356)
		(mid 124.431405 -279.117327)
		(end 124.546106 -279.250648)
		(width 0.1143)
		(layer "In11.Cu")
		(net "P5E_CPU1_P3_TX_DN<12>")
	)
	(arc
		(start 124.077222 -292.411404)
		(mid 123.920245 -292.716204)
		(end 124.077222 -293.021004)
		(width 0.1143)
		(layer "In11.Cu")
		(net "P5E_CPU1_P3_TX_DN<12>")
	)
	(arc
		(start 124.077222 -285.93161)
		(mid 123.961795 -286.064986)
		(end 123.92025 -286.23641)
		(width 0.1143)
		(layer "In11.Cu")
		(net "P5E_CPU1_P3_TX_DN<12>")
	)
	(arc
		(start 124.146818 -293.061644)
		(mid 124.390145 -293.52621)
		(end 124.146818 -293.990776)
		(width 0.1143)
		(layer "In11.Cu")
		(net "P5E_CPU1_P3_TX_DN<12>")
	)
	(arc
		(start 132.878576 -367.95202)
		(mid 132.828741 -368.026603)
		(end 132.811266 -368.11458)
		(width 0.14224)
		(layer "In11.Cu")
		(net "P5E_CPU1_P3_TX_DN<12>")
	)
	(arc
		(start 125.015498 -296.284904)
		(mid 125.084547 -296.388009)
		(end 125.10897 -296.509694)
		(width 0.1143)
		(layer "In11.Cu")
		(net "P5E_CPU1_P3_TX_DN<12>")
	)
	(arc
		(start 124.146818 -289.82162)
		(mid 124.390145 -290.286186)
		(end 124.146818 -290.750752)
		(width 0.1143)
		(layer "In11.Cu")
		(net "P5E_CPU1_P3_TX_DN<12>")
	)
	(arc
		(start 124.077222 -289.17138)
		(mid 123.920245 -289.47618)
		(end 124.077222 -289.78098)
		(width 0.1143)
		(layer "In11.Cu")
		(net "P5E_CPU1_P3_TX_DN<12>")
	)
	(arc
		(start 124.077222 -284.311598)
		(mid 123.920245 -284.616398)
		(end 124.077222 -284.921198)
		(width 0.1143)
		(layer "In11.Cu")
		(net "P5E_CPU1_P3_TX_DN<12>")
	)
	(arc
		(start 123.450096 -277.329392)
		(mid 123.490542 -277.497507)
		(end 123.603258 -277.628604)
		(width 0.1143)
		(layer "In11.Cu")
		(net "P5E_CPU1_P3_TX_DN<12>")
	)
	(arc
		(start 124.39015 -295.146222)
		(mid 124.431699 -295.317644)
		(end 124.547122 -295.451022)
		(width 0.1143)
		(layer "In11.Cu")
		(net "P5E_CPU1_P3_TX_DN<12>")
	)
	(arc
		(start 124.077222 -282.691586)
		(mid 123.920245 -282.996386)
		(end 124.077222 -283.301186)
		(width 0.1143)
		(layer "In11.Cu")
		(net "P5E_CPU1_P3_TX_DN<12>")
	)
	(arc
		(start 124.077222 -287.551622)
		(mid 123.961795 -287.684998)
		(end 123.92025 -287.856422)
		(width 0.1143)
		(layer "In11.Cu")
		(net "P5E_CPU1_P3_TX_DN<12>")
	)
	(arc
		(start 124.146818 -294.681656)
		(mid 124.325631 -294.884006)
		(end 124.39015 -295.146222)
		(width 0.1143)
		(layer "In11.Cu")
		(net "P5E_CPU1_P3_TX_DN<12>")
	)
	(arc
		(start 124.077222 -294.031416)
		(mid 123.920245 -294.336216)
		(end 124.077222 -294.641016)
		(width 0.1143)
		(layer "In11.Cu")
		(net "P5E_CPU1_P3_TX_DN<12>")
	)
	(arc
		(start 124.146818 -284.961838)
		(mid 124.390145 -285.426404)
		(end 124.146818 -285.89097)
		(width 0.1143)
		(layer "In11.Cu")
		(net "P5E_CPU1_P3_TX_DN<12>")
	)
	(arc
		(start 124.546106 -280.262076)
		(mid 124.43143 -280.39541)
		(end 124.39015 -280.566368)
		(width 0.1143)
		(layer "In11.Cu")
		(net "P5E_CPU1_P3_TX_DN<12>")
	)
	(arc
		(start 141.017752 -358.357424)
		(mid 139.768427 -360.694786)
		(end 138.0871 -362.743496)
		(width 0.14224)
		(layer "In11.Cu")
		(net "P5E_CPU1_P3_TX_DN<12>")
	)
	(arc
		(start 124.077222 -290.791392)
		(mid 123.920245 -291.096192)
		(end 124.077222 -291.400992)
		(width 0.1143)
		(layer "In11.Cu")
		(net "P5E_CPU1_P3_TX_DN<12>")
	)
	(segment
		(start 131.129786 -371.76964)
		(end 131.129786 -372.47322)
		(width 0.12954)
		(layer "F.Cu")
		(net "P5E_CPU1_P3_TX_DN<11>")
	)
	(segment
		(start 131.400296 -371.49913)
		(end 131.129786 -371.76964)
		(width 0.12954)
		(layer "F.Cu")
		(net "P5E_CPU1_P3_TX_DN<11>")
	)
	(segment
		(start 122.887994 -277.870412)
		(end 123.354846 -278.13635)
		(width 0.12954)
		(layer "F.Cu")
		(net "P5E_CPU1_P3_TX_DN<11>")
	)
	(segment
		(start 131.129786 -372.47322)
		(end 131.425696 -372.76913)
		(width 0.12954)
		(layer "F.Cu")
		(net "P5E_CPU1_P3_TX_DN<11>")
	)
	(segment
		(start 123.136152 -294.640508)
		(end 123.167902 -294.658796)
		(width 0.1143)
		(layer "In11.Cu")
		(net "P5E_CPU1_P3_TX_DN<11>")
	)
	(segment
		(start 123.136152 -278.440642)
		(end 123.16714 -278.458422)
		(width 0.1143)
		(layer "In11.Cu")
		(net "P5E_CPU1_P3_TX_DN<11>")
	)
	(segment
		(start 124.16409 -296.792396)
		(end 124.20981 -296.838116)
		(width 0.1143)
		(layer "In11.Cu")
		(net "P5E_CPU1_P3_TX_DN<11>")
	)
	(segment
		(start 123.167902 -281.053794)
		(end 123.136152 -281.072082)
		(width 0.1143)
		(layer "In11.Cu")
		(net "P5E_CPU1_P3_TX_DN<11>")
	)
	(segment
		(start 123.624848 -280.251154)
		(end 123.624594 -280.251408)
		(width 0.1143)
		(layer "In11.Cu")
		(net "P5E_CPU1_P3_TX_DN<11>")
	)
	(segment
		(start 123.135136 -288.159698)
		(end 123.167902 -288.178748)
		(width 0.1143)
		(layer "In11.Cu")
		(net "P5E_CPU1_P3_TX_DN<11>")
	)
	(segment
		(start 123.676918 -280.220928)
		(end 123.624848 -280.251154)
		(width 0.1143)
		(layer "In11.Cu")
		(net "P5E_CPU1_P3_TX_DN<11>")
	)
	(segment
		(start 123.167902 -293.038784)
		(end 123.17095 -293.040562)
		(width 0.1143)
		(layer "In11.Cu")
		(net "P5E_CPU1_P3_TX_DN<11>")
	)
	(segment
		(start 124.210318 -296.876978)
		(end 124.210318 -297.27271)
		(width 0.14224)
		(layer "In11.Cu")
		(net "P5E_CPU1_P3_TX_DN<11>")
	)
	(segment
		(start 123.136152 -281.680666)
		(end 123.167902 -281.698954)
		(width 0.1143)
		(layer "In11.Cu")
		(net "P5E_CPU1_P3_TX_DN<11>")
	)
	(segment
		(start 123.167902 -291.418772)
		(end 123.167902 -291.419026)
		(width 0.1143)
		(layer "In11.Cu")
		(net "P5E_CPU1_P3_TX_DN<11>")
	)
	(segment
		(start 123.438158 -280.57475)
		(end 123.438158 -280.58618)
		(width 0.1143)
		(layer "In11.Cu")
		(net "P5E_CPU1_P3_TX_DN<11>")
	)
	(segment
		(start 123.134374 -286.539178)
		(end 123.20905 -286.58312)
		(width 0.1143)
		(layer "In11.Cu")
		(net "P5E_CPU1_P3_TX_DN<11>")
	)
	(segment
		(start 124.20981 -296.87647)
		(end 124.210318 -296.876978)
		(width 0.14224)
		(layer "In11.Cu")
		(net "P5E_CPU1_P3_TX_DN<11>")
	)
	(segment
		(start 123.167902 -294.658796)
		(end 123.20778 -294.682418)
		(width 0.1143)
		(layer "In11.Cu")
		(net "P5E_CPU1_P3_TX_DN<11>")
	)
	(segment
		(start 124.20981 -296.866564)
		(end 124.20981 -296.87647)
		(width 0.14224)
		(layer "In11.Cu")
		(net "P5E_CPU1_P3_TX_DN<11>")
	)
	(segment
		(start 131.109466 -368.644678)
		(end 131.109466 -371.2083)
		(width 0.14224)
		(layer "In11.Cu")
		(net "P5E_CPU1_P3_TX_DN<11>")
	)
	(segment
		(start 123.136152 -291.400484)
		(end 123.167902 -291.418772)
		(width 0.1143)
		(layer "In11.Cu")
		(net "P5E_CPU1_P3_TX_DN<11>")
	)
	(segment
		(start 125.849126 -300.511464)
		(end 132.707888 -308.868572)
		(width 0.14224)
		(layer "In11.Cu")
		(net "P5E_CPU1_P3_TX_DN<11>")
	)
	(segment
		(start 123.167902 -288.178748)
		(end 123.17095 -288.180526)
		(width 0.1143)
		(layer "In11.Cu")
		(net "P5E_CPU1_P3_TX_DN<11>")
	)
	(segment
		(start 123.167902 -284.938978)
		(end 123.17095 -284.940756)
		(width 0.1143)
		(layer "In11.Cu")
		(net "P5E_CPU1_P3_TX_DN<11>")
	)
	(segment
		(start 123.136152 -293.020496)
		(end 123.167902 -293.038784)
		(width 0.1143)
		(layer "In11.Cu")
		(net "P5E_CPU1_P3_TX_DN<11>")
	)
	(segment
		(start 123.462796 -278.953722)
		(end 123.462796 -278.966168)
		(width 0.1143)
		(layer "In11.Cu")
		(net "P5E_CPU1_P3_TX_DN<11>")
	)
	(segment
		(start 123.957334 -296.166286)
		(end 124.071126 -296.280078)
		(width 0.1143)
		(layer "In11.Cu")
		(net "P5E_CPU1_P3_TX_DN<11>")
	)
	(segment
		(start 137.292588 -362.134404)
		(end 131.34086 -368.086132)
		(width 0.14224)
		(layer "In11.Cu")
		(net "P5E_CPU1_P3_TX_DN<11>")
	)
	(segment
		(start 123.168918 -278.459438)
		(end 123.182888 -278.467566)
		(width 0.1143)
		(layer "In11.Cu")
		(net "P5E_CPU1_P3_TX_DN<11>")
	)
	(segment
		(start 124.16409 -296.505122)
		(end 124.16409 -296.792396)
		(width 0.1143)
		(layer "In11.Cu")
		(net "P5E_CPU1_P3_TX_DN<11>")
	)
	(segment
		(start 123.206002 -292.37178)
		(end 123.136152 -292.411912)
		(width 0.1143)
		(layer "In11.Cu")
		(net "P5E_CPU1_P3_TX_DN<11>")
	)
	(segment
		(start 140.51788 -322.270882)
		(end 144.147032 -340.51748)
		(width 0.14224)
		(layer "In11.Cu")
		(net "P5E_CPU1_P3_TX_DN<11>")
	)
	(segment
		(start 123.17095 -284.29204)
		(end 123.136152 -284.312106)
		(width 0.1143)
		(layer "In11.Cu")
		(net "P5E_CPU1_P3_TX_DN<11>")
	)
	(segment
		(start 123.208034 -287.510474)
		(end 123.136152 -287.55213)
		(width 0.1143)
		(layer "In11.Cu")
		(net "P5E_CPU1_P3_TX_DN<11>")
	)
	(segment
		(start 123.206002 -291.440616)
		(end 123.218956 -291.450014)
		(width 0.1143)
		(layer "In11.Cu")
		(net "P5E_CPU1_P3_TX_DN<11>")
	)
	(segment
		(start 123.218956 -292.362382)
		(end 123.206002 -292.37178)
		(width 0.1143)
		(layer "In11.Cu")
		(net "P5E_CPU1_P3_TX_DN<11>")
	)
	(segment
		(start 123.16714 -278.458422)
		(end 123.167902 -278.45893)
		(width 0.1143)
		(layer "In11.Cu")
		(net "P5E_CPU1_P3_TX_DN<11>")
	)
	(segment
		(start 123.167902 -283.318966)
		(end 123.17095 -283.320744)
		(width 0.1143)
		(layer "In11.Cu")
		(net "P5E_CPU1_P3_TX_DN<11>")
	)
	(segment
		(start 123.16714 -283.318458)
		(end 123.167902 -283.318966)
		(width 0.1143)
		(layer "In11.Cu")
		(net "P5E_CPU1_P3_TX_DN<11>")
	)
	(segment
		(start 123.17095 -290.771834)
		(end 123.136152 -290.7919)
		(width 0.1143)
		(layer "In11.Cu")
		(net "P5E_CPU1_P3_TX_DN<11>")
	)
	(segment
		(start 123.219464 -287.501838)
		(end 123.208034 -287.510474)
		(width 0.1143)
		(layer "In11.Cu")
		(net "P5E_CPU1_P3_TX_DN<11>")
	)
	(segment
		(start 124.647452 -298.71289)
		(end 125.849126 -300.511464)
		(width 0.14224)
		(layer "In11.Cu")
		(net "P5E_CPU1_P3_TX_DN<11>")
	)
	(segment
		(start 123.17095 -294.011858)
		(end 123.136152 -294.031924)
		(width 0.1143)
		(layer "In11.Cu")
		(net "P5E_CPU1_P3_TX_DN<11>")
	)
	(segment
		(start 143.645128 -349.365824)
		(end 140.091414 -357.94569)
		(width 0.14224)
		(layer "In11.Cu")
		(net "P5E_CPU1_P3_TX_DN<11>")
	)
	(segment
		(start 123.136152 -284.92069)
		(end 123.167902 -284.938978)
		(width 0.1143)
		(layer "In11.Cu")
		(net "P5E_CPU1_P3_TX_DN<11>")
	)
	(segment
		(start 123.17095 -282.672028)
		(end 123.136152 -282.692094)
		(width 0.1143)
		(layer "In11.Cu")
		(net "P5E_CPU1_P3_TX_DN<11>")
	)
	(segment
		(start 123.167902 -281.698954)
		(end 123.17095 -281.700732)
		(width 0.1143)
		(layer "In11.Cu")
		(net "P5E_CPU1_P3_TX_DN<11>")
	)
	(segment
		(start 123.919996 -295.956228)
		(end 123.919996 -296.076116)
		(width 0.1143)
		(layer "In11.Cu")
		(net "P5E_CPU1_P3_TX_DN<11>")
	)
	(segment
		(start 123.167902 -289.79876)
		(end 123.17095 -289.800538)
		(width 0.1143)
		(layer "In11.Cu")
		(net "P5E_CPU1_P3_TX_DN<11>")
	)
	(segment
		(start 123.450096 -287.046162)
		(end 123.450096 -287.050734)
		(width 0.1143)
		(layer "In11.Cu")
		(net "P5E_CPU1_P3_TX_DN<11>")
	)
	(segment
		(start 123.056904 -278.13635)
		(end 122.987054 -278.2062)
		(width 0.1143)
		(layer "In11.Cu")
		(net "P5E_CPU1_P3_TX_DN<11>")
	)
	(segment
		(start 132.707888 -308.868572)
		(end 138.649456 -317.760604)
		(width 0.14224)
		(layer "In11.Cu")
		(net "P5E_CPU1_P3_TX_DN<11>")
	)
	(segment
		(start 124.20981 -296.838116)
		(end 124.20981 -296.866564)
		(width 0.1143)
		(layer "In11.Cu")
		(net "P5E_CPU1_P3_TX_DN<11>")
	)
	(segment
		(start 131.109466 -371.2083)
		(end 131.400296 -371.49913)
		(width 0.14224)
		(layer "In11.Cu")
		(net "P5E_CPU1_P3_TX_DN<11>")
	)
	(segment
		(start 123.136152 -283.300678)
		(end 123.16714 -283.318458)
		(width 0.1143)
		(layer "In11.Cu")
		(net "P5E_CPU1_P3_TX_DN<11>")
	)
	(segment
		(start 123.450096 -295.141904)
		(end 123.450096 -295.146222)
		(width 0.1143)
		(layer "In11.Cu")
		(net "P5E_CPU1_P3_TX_DN<11>")
	)
	(segment
		(start 123.17095 -285.912052)
		(end 123.136152 -285.932118)
		(width 0.1143)
		(layer "In11.Cu")
		(net "P5E_CPU1_P3_TX_DN<11>")
	)
	(segment
		(start 123.177808 -281.047698)
		(end 123.167902 -281.053794)
		(width 0.1143)
		(layer "In11.Cu")
		(net "P5E_CPU1_P3_TX_DN<11>")
	)
	(segment
		(start 123.136152 -289.780472)
		(end 123.167902 -289.79876)
		(width 0.1143)
		(layer "In11.Cu")
		(net "P5E_CPU1_P3_TX_DN<11>")
	)
	(segment
		(start 144.147032 -340.51748)
		(end 144.147032 -346.842334)
		(width 0.14224)
		(layer "In11.Cu")
		(net "P5E_CPU1_P3_TX_DN<11>")
	)
	(segment
		(start 123.167902 -278.45893)
		(end 123.168918 -278.459438)
		(width 0.1143)
		(layer "In11.Cu")
		(net "P5E_CPU1_P3_TX_DN<11>")
	)
	(segment
		(start 123.606052 -295.450514)
		(end 123.676156 -295.4909)
		(width 0.1143)
		(layer "In11.Cu")
		(net "P5E_CPU1_P3_TX_DN<11>")
	)
	(segment
		(start 123.17095 -289.151822)
		(end 123.136152 -289.171888)
		(width 0.1143)
		(layer "In11.Cu")
		(net "P5E_CPU1_P3_TX_DN<11>")
	)
	(segment
		(start 123.637802 -279.268936)
		(end 123.676918 -279.291796)
		(width 0.1143)
		(layer "In11.Cu")
		(net "P5E_CPU1_P3_TX_DN<11>")
	)
	(segment
		(start 123.354846 -278.13635)
		(end 123.056904 -278.13635)
		(width 0.1143)
		(layer "In11.Cu")
		(net "P5E_CPU1_P3_TX_DN<11>")
	)
	(segment
		(start 138.649456 -317.760604)
		(end 140.51788 -322.270882)
		(width 0.14224)
		(layer "In11.Cu")
		(net "P5E_CPU1_P3_TX_DN<11>")
	)
	(segment
		(start 124.210318 -297.27271)
		(end 124.647452 -298.71289)
		(width 0.14224)
		(layer "In11.Cu")
		(net "P5E_CPU1_P3_TX_DN<11>")
	)
	(segment
		(start 123.134374 -288.15919)
		(end 123.135136 -288.159698)
		(width 0.1143)
		(layer "In11.Cu")
		(net "P5E_CPU1_P3_TX_DN<11>")
	)
	(segment
		(start 123.167902 -291.419026)
		(end 123.206002 -291.440616)
		(width 0.1143)
		(layer "In11.Cu")
		(net "P5E_CPU1_P3_TX_DN<11>")
	)
	(arc
		(start 123.462796 -278.966168)
		(mid 123.509687 -279.141034)
		(end 123.637802 -279.268936)
		(width 0.1143)
		(layer "In11.Cu")
		(net "P5E_CPU1_P3_TX_DN<11>")
	)
	(arc
		(start 123.136152 -284.312106)
		(mid 122.980224 -284.616398)
		(end 123.136152 -284.92069)
		(width 0.1143)
		(layer "In11.Cu")
		(net "P5E_CPU1_P3_TX_DN<11>")
	)
	(arc
		(start 123.17095 -288.180526)
		(mid 123.450565 -288.666174)
		(end 123.17095 -289.151822)
		(width 0.1143)
		(layer "In11.Cu")
		(net "P5E_CPU1_P3_TX_DN<11>")
	)
	(arc
		(start 123.17095 -283.320744)
		(mid 123.450565 -283.806392)
		(end 123.17095 -284.29204)
		(width 0.1143)
		(layer "In11.Cu")
		(net "P5E_CPU1_P3_TX_DN<11>")
	)
	(arc
		(start 123.136152 -292.411912)
		(mid 122.980224 -292.716204)
		(end 123.136152 -293.020496)
		(width 0.1143)
		(layer "In11.Cu")
		(net "P5E_CPU1_P3_TX_DN<11>")
	)
	(arc
		(start 123.17095 -289.800538)
		(mid 123.450565 -290.286186)
		(end 123.17095 -290.771834)
		(width 0.1143)
		(layer "In11.Cu")
		(net "P5E_CPU1_P3_TX_DN<11>")
	)
	(arc
		(start 123.450096 -287.050734)
		(mid 123.389097 -287.304058)
		(end 123.219464 -287.501838)
		(width 0.1143)
		(layer "In11.Cu")
		(net "P5E_CPU1_P3_TX_DN<11>")
	)
	(arc
		(start 123.676918 -279.291796)
		(mid 123.920135 -279.756362)
		(end 123.676918 -280.220928)
		(width 0.1143)
		(layer "In11.Cu")
		(net "P5E_CPU1_P3_TX_DN<11>")
	)
	(arc
		(start 123.919996 -296.076116)
		(mid 123.929702 -296.124911)
		(end 123.957334 -296.166286)
		(width 0.1143)
		(layer "In11.Cu")
		(net "P5E_CPU1_P3_TX_DN<11>")
	)
	(arc
		(start 124.071126 -296.280078)
		(mid 124.13998 -296.383358)
		(end 124.16409 -296.505122)
		(width 0.1143)
		(layer "In11.Cu")
		(net "P5E_CPU1_P3_TX_DN<11>")
	)
	(arc
		(start 144.147032 -346.842334)
		(mid 144.02034 -348.128794)
		(end 143.645128 -349.365824)
		(width 0.14224)
		(layer "In11.Cu")
		(net "P5E_CPU1_P3_TX_DN<11>")
	)
	(arc
		(start 123.136152 -290.7919)
		(mid 122.980224 -291.096192)
		(end 123.136152 -291.400484)
		(width 0.1143)
		(layer "In11.Cu")
		(net "P5E_CPU1_P3_TX_DN<11>")
	)
	(arc
		(start 123.450096 -295.146222)
		(mid 123.491351 -295.317193)
		(end 123.606052 -295.450514)
		(width 0.1143)
		(layer "In11.Cu")
		(net "P5E_CPU1_P3_TX_DN<11>")
	)
	(arc
		(start 123.20905 -286.58312)
		(mid 123.386246 -286.785132)
		(end 123.450096 -287.046162)
		(width 0.1143)
		(layer "In11.Cu")
		(net "P5E_CPU1_P3_TX_DN<11>")
	)
	(arc
		(start 131.34086 -368.086132)
		(mid 131.16963 -368.342395)
		(end 131.109466 -368.644678)
		(width 0.14224)
		(layer "In11.Cu")
		(net "P5E_CPU1_P3_TX_DN<11>")
	)
	(arc
		(start 122.980196 -287.856422)
		(mid 123.020958 -288.026306)
		(end 123.134374 -288.15919)
		(width 0.1143)
		(layer "In11.Cu")
		(net "P5E_CPU1_P3_TX_DN<11>")
	)
	(arc
		(start 123.438158 -280.58618)
		(mid 123.368582 -280.851124)
		(end 123.177808 -281.047698)
		(width 0.1143)
		(layer "In11.Cu")
		(net "P5E_CPU1_P3_TX_DN<11>")
	)
	(arc
		(start 123.182888 -278.467566)
		(mid 123.387833 -278.673228)
		(end 123.462796 -278.953722)
		(width 0.1143)
		(layer "In11.Cu")
		(net "P5E_CPU1_P3_TX_DN<11>")
	)
	(arc
		(start 123.218956 -291.450014)
		(mid 123.453383 -291.906198)
		(end 123.218956 -292.362382)
		(width 0.1143)
		(layer "In11.Cu")
		(net "P5E_CPU1_P3_TX_DN<11>")
	)
	(arc
		(start 122.980196 -286.23641)
		(mid 123.020958 -286.406294)
		(end 123.134374 -286.539178)
		(width 0.1143)
		(layer "In11.Cu")
		(net "P5E_CPU1_P3_TX_DN<11>")
	)
	(arc
		(start 123.20778 -294.682418)
		(mid 123.385816 -294.882168)
		(end 123.450096 -295.141904)
		(width 0.1143)
		(layer "In11.Cu")
		(net "P5E_CPU1_P3_TX_DN<11>")
	)
	(arc
		(start 123.136152 -289.171888)
		(mid 122.980224 -289.47618)
		(end 123.136152 -289.780472)
		(width 0.1143)
		(layer "In11.Cu")
		(net "P5E_CPU1_P3_TX_DN<11>")
	)
	(arc
		(start 123.17095 -281.700732)
		(mid 123.450565 -282.18638)
		(end 123.17095 -282.672028)
		(width 0.1143)
		(layer "In11.Cu")
		(net "P5E_CPU1_P3_TX_DN<11>")
	)
	(arc
		(start 140.091414 -357.94569)
		(mid 138.898273 -360.177873)
		(end 137.292588 -362.134404)
		(width 0.14224)
		(layer "In11.Cu")
		(net "P5E_CPU1_P3_TX_DN<11>")
	)
	(arc
		(start 123.136152 -281.072082)
		(mid 122.980224 -281.376374)
		(end 123.136152 -281.680666)
		(width 0.1143)
		(layer "In11.Cu")
		(net "P5E_CPU1_P3_TX_DN<11>")
	)
	(arc
		(start 123.136152 -282.692094)
		(mid 122.980224 -282.996386)
		(end 123.136152 -283.300678)
		(width 0.1143)
		(layer "In11.Cu")
		(net "P5E_CPU1_P3_TX_DN<11>")
	)
	(arc
		(start 123.17095 -293.040562)
		(mid 123.450565 -293.52621)
		(end 123.17095 -294.011858)
		(width 0.1143)
		(layer "In11.Cu")
		(net "P5E_CPU1_P3_TX_DN<11>")
	)
	(arc
		(start 123.17095 -284.940756)
		(mid 123.450565 -285.426404)
		(end 123.17095 -285.912052)
		(width 0.1143)
		(layer "In11.Cu")
		(net "P5E_CPU1_P3_TX_DN<11>")
	)
	(arc
		(start 123.136152 -285.932118)
		(mid 123.021476 -286.065452)
		(end 122.980196 -286.23641)
		(width 0.1143)
		(layer "In11.Cu")
		(net "P5E_CPU1_P3_TX_DN<11>")
	)
	(arc
		(start 123.136152 -294.031924)
		(mid 122.980224 -294.336216)
		(end 123.136152 -294.640508)
		(width 0.1143)
		(layer "In11.Cu")
		(net "P5E_CPU1_P3_TX_DN<11>")
	)
	(arc
		(start 123.136152 -287.55213)
		(mid 123.021476 -287.685464)
		(end 122.980196 -287.856422)
		(width 0.1143)
		(layer "In11.Cu")
		(net "P5E_CPU1_P3_TX_DN<11>")
	)
	(arc
		(start 123.624594 -280.251408)
		(mid 123.488114 -280.388133)
		(end 123.438158 -280.57475)
		(width 0.1143)
		(layer "In11.Cu")
		(net "P5E_CPU1_P3_TX_DN<11>")
	)
	(arc
		(start 123.676156 -295.4909)
		(mid 123.855408 -295.693523)
		(end 123.919996 -295.956228)
		(width 0.1143)
		(layer "In11.Cu")
		(net "P5E_CPU1_P3_TX_DN<11>")
	)
	(arc
		(start 122.987054 -278.2062)
		(mid 123.039103 -278.337719)
		(end 123.136152 -278.440642)
		(width 0.1143)
		(layer "In11.Cu")
		(net "P5E_CPU1_P3_TX_DN<11>")
	)
	(segment
		(start 122.887994 -274.630388)
		(end 123.354846 -274.896326)
		(width 0.12954)
		(layer "F.Cu")
		(net "P5E_CPU1_P3_TX_DN<10>")
	)
	(segment
		(start 129.698496 -373.96293)
		(end 129.427986 -374.23344)
		(width 0.12954)
		(layer "F.Cu")
		(net "P5E_CPU1_P3_TX_DN<10>")
	)
	(segment
		(start 129.427986 -374.93702)
		(end 129.723896 -375.23293)
		(width 0.12954)
		(layer "F.Cu")
		(net "P5E_CPU1_P3_TX_DN<10>")
	)
	(segment
		(start 129.427986 -374.23344)
		(end 129.427986 -374.93702)
		(width 0.12954)
		(layer "F.Cu")
		(net "P5E_CPU1_P3_TX_DN<10>")
	)
	(segment
		(start 122.225816 -285.9151)
		(end 122.224292 -285.915862)
		(width 0.1143)
		(layer "In11.Cu")
		(net "P5E_CPU1_P3_TX_DN<10>")
	)
	(segment
		(start 122.227848 -291.418772)
		(end 122.228864 -291.41928)
		(width 0.1143)
		(layer "In11.Cu")
		(net "P5E_CPU1_P3_TX_DN<10>")
	)
	(segment
		(start 122.231404 -293.040816)
		(end 122.266964 -293.061644)
		(width 0.1143)
		(layer "In11.Cu")
		(net "P5E_CPU1_P3_TX_DN<10>")
	)
	(segment
		(start 122.221244 -290.777422)
		(end 122.220228 -290.77793)
		(width 0.1143)
		(layer "In11.Cu")
		(net "P5E_CPU1_P3_TX_DN<10>")
	)
	(segment
		(start 122.227848 -288.178748)
		(end 122.266964 -288.201608)
		(width 0.1143)
		(layer "In11.Cu")
		(net "P5E_CPU1_P3_TX_DN<10>")
	)
	(segment
		(start 122.228864 -290.773104)
		(end 122.227848 -290.773612)
		(width 0.1143)
		(layer "In11.Cu")
		(net "P5E_CPU1_P3_TX_DN<10>")
	)
	(segment
		(start 122.227086 -292.394132)
		(end 122.225816 -292.394894)
		(width 0.1143)
		(layer "In11.Cu")
		(net "P5E_CPU1_P3_TX_DN<10>")
	)
	(segment
		(start 122.19432 -286.539178)
		(end 122.227848 -286.558736)
		(width 0.1143)
		(layer "In11.Cu")
		(net "P5E_CPU1_P3_TX_DN<10>")
	)
	(segment
		(start 122.697748 -275.383752)
		(end 122.667268 -275.401532)
		(width 0.1143)
		(layer "In11.Cu")
		(net "P5E_CPU1_P3_TX_DN<10>")
	)
	(segment
		(start 122.228864 -277.813262)
		(end 122.227848 -277.81377)
		(width 0.1143)
		(layer "In11.Cu")
		(net "P5E_CPU1_P3_TX_DN<10>")
	)
	(segment
		(start 122.220228 -290.77793)
		(end 122.196098 -290.7919)
		(width 0.1143)
		(layer "In11.Cu")
		(net "P5E_CPU1_P3_TX_DN<10>")
	)
	(segment
		(start 122.227848 -281.053794)
		(end 122.227086 -281.054302)
		(width 0.1143)
		(layer "In11.Cu")
		(net "P5E_CPU1_P3_TX_DN<10>")
	)
	(segment
		(start 122.227848 -277.81377)
		(end 122.227086 -277.814278)
		(width 0.1143)
		(layer "In11.Cu")
		(net "P5E_CPU1_P3_TX_DN<10>")
	)
	(segment
		(start 122.227086 -293.038276)
		(end 122.227848 -293.038784)
		(width 0.1143)
		(layer "In11.Cu")
		(net "P5E_CPU1_P3_TX_DN<10>")
	)
	(segment
		(start 122.227848 -294.013636)
		(end 122.227086 -294.014144)
		(width 0.1143)
		(layer "In11.Cu")
		(net "P5E_CPU1_P3_TX_DN<10>")
	)
	(segment
		(start 122.227848 -286.558736)
		(end 122.266964 -286.581596)
		(width 0.1143)
		(layer "In11.Cu")
		(net "P5E_CPU1_P3_TX_DN<10>")
	)
	(segment
		(start 122.227086 -285.914338)
		(end 122.225816 -285.9151)
		(width 0.1143)
		(layer "In11.Cu")
		(net "P5E_CPU1_P3_TX_DN<10>")
	)
	(segment
		(start 122.224292 -292.395656)
		(end 122.22353 -292.396164)
		(width 0.1143)
		(layer "In11.Cu")
		(net "P5E_CPU1_P3_TX_DN<10>")
	)
	(segment
		(start 122.228864 -283.319474)
		(end 122.230388 -283.32049)
		(width 0.1143)
		(layer "In11.Cu")
		(net "P5E_CPU1_P3_TX_DN<10>")
	)
	(segment
		(start 122.196098 -281.680666)
		(end 122.227086 -281.698446)
		(width 0.1143)
		(layer "In11.Cu")
		(net "P5E_CPU1_P3_TX_DN<10>")
	)
	(segment
		(start 123.354846 -274.896326)
		(end 123.056904 -274.896326)
		(width 0.1143)
		(layer "In11.Cu")
		(net "P5E_CPU1_P3_TX_DN<10>")
	)
	(segment
		(start 122.264424 -287.512506)
		(end 122.227848 -287.533842)
		(width 0.1143)
		(layer "In11.Cu")
		(net "P5E_CPU1_P3_TX_DN<10>")
	)
	(segment
		(start 123.819666 -299.207682)
		(end 125.098556 -301.121572)
		(width 0.14224)
		(layer "In11.Cu")
		(net "P5E_CPU1_P3_TX_DN<10>")
	)
	(segment
		(start 122.227086 -284.294326)
		(end 122.225816 -284.295088)
		(width 0.1143)
		(layer "In11.Cu")
		(net "P5E_CPU1_P3_TX_DN<10>")
	)
	(segment
		(start 136.636506 -361.412028)
		(end 131.893056 -366.155478)
		(width 0.14224)
		(layer "In11.Cu")
		(net "P5E_CPU1_P3_TX_DN<10>")
	)
	(segment
		(start 122.227086 -289.798252)
		(end 122.227848 -289.79876)
		(width 0.1143)
		(layer "In11.Cu")
		(net "P5E_CPU1_P3_TX_DN<10>")
	)
	(segment
		(start 122.227848 -289.79876)
		(end 122.228864 -289.799268)
		(width 0.1143)
		(layer "In11.Cu")
		(net "P5E_CPU1_P3_TX_DN<10>")
	)
	(segment
		(start 122.221244 -277.81758)
		(end 122.220228 -277.818088)
		(width 0.1143)
		(layer "In11.Cu")
		(net "P5E_CPU1_P3_TX_DN<10>")
	)
	(segment
		(start 122.222006 -290.776914)
		(end 122.221244 -290.777422)
		(width 0.1143)
		(layer "In11.Cu")
		(net "P5E_CPU1_P3_TX_DN<10>")
	)
	(segment
		(start 122.224292 -276.19579)
		(end 122.22353 -276.196298)
		(width 0.1143)
		(layer "In11.Cu")
		(net "P5E_CPU1_P3_TX_DN<10>")
	)
	(segment
		(start 122.227848 -281.698954)
		(end 122.228864 -281.699462)
		(width 0.1143)
		(layer "In11.Cu")
		(net "P5E_CPU1_P3_TX_DN<10>")
	)
	(segment
		(start 122.220228 -281.058112)
		(end 122.196098 -281.072082)
		(width 0.1143)
		(layer "In11.Cu")
		(net "P5E_CPU1_P3_TX_DN<10>")
	)
	(segment
		(start 122.220228 -277.818088)
		(end 122.196098 -277.832058)
		(width 0.1143)
		(layer "In11.Cu")
		(net "P5E_CPU1_P3_TX_DN<10>")
	)
	(segment
		(start 122.736864 -280.220928)
		(end 122.697748 -280.243788)
		(width 0.1143)
		(layer "In11.Cu")
		(net "P5E_CPU1_P3_TX_DN<10>")
	)
	(segment
		(start 122.227086 -289.154108)
		(end 122.225816 -289.15487)
		(width 0.1143)
		(layer "In11.Cu")
		(net "P5E_CPU1_P3_TX_DN<10>")
	)
	(segment
		(start 122.224292 -289.155632)
		(end 122.22353 -289.15614)
		(width 0.1143)
		(layer "In11.Cu")
		(net "P5E_CPU1_P3_TX_DN<10>")
	)
	(segment
		(start 123.11253 -296.612564)
		(end 123.11253 -296.877232)
		(width 0.14224)
		(layer "In11.Cu")
		(net "P5E_CPU1_P3_TX_DN<10>")
	)
	(segment
		(start 122.227086 -294.658288)
		(end 122.227848 -294.658796)
		(width 0.1143)
		(layer "In11.Cu")
		(net "P5E_CPU1_P3_TX_DN<10>")
	)
	(segment
		(start 132.06222 -309.607204)
		(end 137.793476 -318.184022)
		(width 0.14224)
		(layer "In11.Cu")
		(net "P5E_CPU1_P3_TX_DN<10>")
	)
	(segment
		(start 122.227086 -294.014144)
		(end 122.225816 -294.014906)
		(width 0.1143)
		(layer "In11.Cu")
		(net "P5E_CPU1_P3_TX_DN<10>")
	)
	(segment
		(start 122.196098 -278.440642)
		(end 122.227086 -278.458422)
		(width 0.1143)
		(layer "In11.Cu")
		(net "P5E_CPU1_P3_TX_DN<10>")
	)
	(segment
		(start 122.221244 -276.197568)
		(end 122.220228 -276.198076)
		(width 0.1143)
		(layer "In11.Cu")
		(net "P5E_CPU1_P3_TX_DN<10>")
	)
	(segment
		(start 122.227086 -276.83841)
		(end 122.227848 -276.838918)
		(width 0.1143)
		(layer "In11.Cu")
		(net "P5E_CPU1_P3_TX_DN<10>")
	)
	(segment
		(start 122.224292 -281.055826)
		(end 122.22353 -281.056334)
		(width 0.1143)
		(layer "In11.Cu")
		(net "P5E_CPU1_P3_TX_DN<10>")
	)
	(segment
		(start 122.227086 -281.698446)
		(end 122.227848 -281.698954)
		(width 0.1143)
		(layer "In11.Cu")
		(net "P5E_CPU1_P3_TX_DN<10>")
	)
	(segment
		(start 122.220228 -282.678124)
		(end 122.196098 -282.692094)
		(width 0.1143)
		(layer "In11.Cu")
		(net "P5E_CPU1_P3_TX_DN<10>")
	)
	(segment
		(start 122.510296 -295.146222)
		(end 122.510042 -295.146222)
		(width 0.1143)
		(layer "In11.Cu")
		(net "P5E_CPU1_P3_TX_DN<10>")
	)
	(segment
		(start 122.22353 -289.15614)
		(end 122.222006 -289.156902)
		(width 0.1143)
		(layer "In11.Cu")
		(net "P5E_CPU1_P3_TX_DN<10>")
	)
	(segment
		(start 123.11253 -296.877232)
		(end 123.819666 -299.207682)
		(width 0.14224)
		(layer "In11.Cu")
		(net "P5E_CPU1_P3_TX_DN<10>")
	)
	(segment
		(start 122.196098 -293.020496)
		(end 122.227086 -293.038276)
		(width 0.1143)
		(layer "In11.Cu")
		(net "P5E_CPU1_P3_TX_DN<10>")
	)
	(segment
		(start 122.225816 -276.195028)
		(end 122.224292 -276.19579)
		(width 0.1143)
		(layer "In11.Cu")
		(net "P5E_CPU1_P3_TX_DN<10>")
	)
	(segment
		(start 122.225816 -277.81504)
		(end 122.224292 -277.815802)
		(width 0.1143)
		(layer "In11.Cu")
		(net "P5E_CPU1_P3_TX_DN<10>")
	)
	(segment
		(start 122.667268 -279.251156)
		(end 122.697748 -279.268936)
		(width 0.1143)
		(layer "In11.Cu")
		(net "P5E_CPU1_P3_TX_DN<10>")
	)
	(segment
		(start 122.227848 -289.1536)
		(end 122.227086 -289.154108)
		(width 0.1143)
		(layer "In11.Cu")
		(net "P5E_CPU1_P3_TX_DN<10>")
	)
	(segment
		(start 122.22353 -290.776152)
		(end 122.222006 -290.776914)
		(width 0.1143)
		(layer "In11.Cu")
		(net "P5E_CPU1_P3_TX_DN<10>")
	)
	(segment
		(start 128.571752 -305.35372)
		(end 132.06222 -309.607204)
		(width 0.14224)
		(layer "In11.Cu")
		(net "P5E_CPU1_P3_TX_DN<10>")
	)
	(segment
		(start 122.228864 -281.699462)
		(end 122.230388 -281.700478)
		(width 0.1143)
		(layer "In11.Cu")
		(net "P5E_CPU1_P3_TX_DN<10>")
	)
	(segment
		(start 122.228864 -293.039292)
		(end 122.230388 -293.040308)
		(width 0.1143)
		(layer "In11.Cu")
		(net "P5E_CPU1_P3_TX_DN<10>")
	)
	(segment
		(start 122.227848 -282.673806)
		(end 122.227086 -282.674314)
		(width 0.1143)
		(layer "In11.Cu")
		(net "P5E_CPU1_P3_TX_DN<10>")
	)
	(segment
		(start 122.224292 -282.675838)
		(end 122.22353 -282.676346)
		(width 0.1143)
		(layer "In11.Cu")
		(net "P5E_CPU1_P3_TX_DN<10>")
	)
	(segment
		(start 122.222006 -277.817072)
		(end 122.221244 -277.81758)
		(width 0.1143)
		(layer "In11.Cu")
		(net "P5E_CPU1_P3_TX_DN<10>")
	)
	(segment
		(start 122.231404 -289.800792)
		(end 122.266964 -289.82162)
		(width 0.1143)
		(layer "In11.Cu")
		(net "P5E_CPU1_P3_TX_DN<10>")
	)
	(segment
		(start 122.227086 -281.054302)
		(end 122.225816 -281.055064)
		(width 0.1143)
		(layer "In11.Cu")
		(net "P5E_CPU1_P3_TX_DN<10>")
	)
	(segment
		(start 122.266964 -285.89097)
		(end 122.228864 -285.913322)
		(width 0.1143)
		(layer "In11.Cu")
		(net "P5E_CPU1_P3_TX_DN<10>")
	)
	(segment
		(start 123.11253 -296.584116)
		(end 123.11253 -296.612564)
		(width 0.1143)
		(layer "In11.Cu")
		(net "P5E_CPU1_P3_TX_DN<10>")
	)
	(segment
		(start 122.22353 -276.196298)
		(end 122.222006 -276.19706)
		(width 0.1143)
		(layer "In11.Cu")
		(net "P5E_CPU1_P3_TX_DN<10>")
	)
	(segment
		(start 122.224292 -285.915862)
		(end 122.22353 -285.91637)
		(width 0.1143)
		(layer "In11.Cu")
		(net "P5E_CPU1_P3_TX_DN<10>")
	)
	(segment
		(start 122.228864 -291.41928)
		(end 122.230388 -291.420296)
		(width 0.1143)
		(layer "In11.Cu")
		(net "P5E_CPU1_P3_TX_DN<10>")
	)
	(segment
		(start 122.227848 -284.938978)
		(end 122.228864 -284.939486)
		(width 0.1143)
		(layer "In11.Cu")
		(net "P5E_CPU1_P3_TX_DN<10>")
	)
	(segment
		(start 122.697748 -279.268936)
		(end 122.736864 -279.291796)
		(width 0.1143)
		(layer "In11.Cu")
		(net "P5E_CPU1_P3_TX_DN<10>")
	)
	(segment
		(start 129.45491 -373.719344)
		(end 129.698496 -373.96293)
		(width 0.14224)
		(layer "In11.Cu")
		(net "P5E_CPU1_P3_TX_DN<10>")
	)
	(segment
		(start 122.222006 -285.917132)
		(end 122.221244 -285.91764)
		(width 0.1143)
		(layer "In11.Cu")
		(net "P5E_CPU1_P3_TX_DN<10>")
	)
	(segment
		(start 122.228864 -281.053286)
		(end 122.227848 -281.053794)
		(width 0.1143)
		(layer "In11.Cu")
		(net "P5E_CPU1_P3_TX_DN<10>")
	)
	(segment
		(start 123.06681 -296.388536)
		(end 123.06681 -296.538396)
		(width 0.1143)
		(layer "In11.Cu")
		(net "P5E_CPU1_P3_TX_DN<10>")
	)
	(segment
		(start 122.22353 -292.396164)
		(end 122.222006 -292.396926)
		(width 0.1143)
		(layer "In11.Cu")
		(net "P5E_CPU1_P3_TX_DN<10>")
	)
	(segment
		(start 122.225816 -294.014906)
		(end 122.196098 -294.031924)
		(width 0.1143)
		(layer "In11.Cu")
		(net "P5E_CPU1_P3_TX_DN<10>")
	)
	(segment
		(start 122.228864 -278.459438)
		(end 122.230388 -278.460454)
		(width 0.1143)
		(layer "In11.Cu")
		(net "P5E_CPU1_P3_TX_DN<10>")
	)
	(segment
		(start 122.228864 -289.153092)
		(end 122.227848 -289.1536)
		(width 0.1143)
		(layer "In11.Cu")
		(net "P5E_CPU1_P3_TX_DN<10>")
	)
	(segment
		(start 122.221244 -282.677616)
		(end 122.220228 -282.678124)
		(width 0.1143)
		(layer "In11.Cu")
		(net "P5E_CPU1_P3_TX_DN<10>")
	)
	(segment
		(start 122.228864 -284.939486)
		(end 122.230388 -284.940502)
		(width 0.1143)
		(layer "In11.Cu")
		(net "P5E_CPU1_P3_TX_DN<10>")
	)
	(segment
		(start 122.22353 -285.91637)
		(end 122.222006 -285.917132)
		(width 0.1143)
		(layer "In11.Cu")
		(net "P5E_CPU1_P3_TX_DN<10>")
	)
	(segment
		(start 122.196098 -294.640508)
		(end 122.227086 -294.658288)
		(width 0.1143)
		(layer "In11.Cu")
		(net "P5E_CPU1_P3_TX_DN<10>")
	)
	(segment
		(start 122.228864 -276.19325)
		(end 122.227848 -276.193758)
		(width 0.1143)
		(layer "In11.Cu")
		(net "P5E_CPU1_P3_TX_DN<10>")
	)
	(segment
		(start 122.22353 -277.81631)
		(end 122.222006 -277.817072)
		(width 0.1143)
		(layer "In11.Cu")
		(net "P5E_CPU1_P3_TX_DN<10>")
	)
	(segment
		(start 122.224292 -284.29585)
		(end 122.22353 -284.296358)
		(width 0.1143)
		(layer "In11.Cu")
		(net "P5E_CPU1_P3_TX_DN<10>")
	)
	(segment
		(start 122.266964 -290.750752)
		(end 122.228864 -290.773104)
		(width 0.1143)
		(layer "In11.Cu")
		(net "P5E_CPU1_P3_TX_DN<10>")
	)
	(segment
		(start 122.228864 -294.659304)
		(end 122.230388 -294.66032)
		(width 0.1143)
		(layer "In11.Cu")
		(net "P5E_CPU1_P3_TX_DN<10>")
	)
	(segment
		(start 122.222006 -292.396926)
		(end 122.221244 -292.397434)
		(width 0.1143)
		(layer "In11.Cu")
		(net "P5E_CPU1_P3_TX_DN<10>")
	)
	(segment
		(start 122.231404 -276.84095)
		(end 122.266964 -276.861778)
		(width 0.1143)
		(layer "In11.Cu")
		(net "P5E_CPU1_P3_TX_DN<10>")
	)
	(segment
		(start 122.220228 -292.397942)
		(end 122.196098 -292.411912)
		(width 0.1143)
		(layer "In11.Cu")
		(net "P5E_CPU1_P3_TX_DN<10>")
	)
	(segment
		(start 122.228864 -285.913322)
		(end 122.227848 -285.91383)
		(width 0.1143)
		(layer "In11.Cu")
		(net "P5E_CPU1_P3_TX_DN<10>")
	)
	(segment
		(start 122.224292 -277.815802)
		(end 122.22353 -277.81631)
		(width 0.1143)
		(layer "In11.Cu")
		(net "P5E_CPU1_P3_TX_DN<10>")
	)
	(segment
		(start 122.220228 -276.198076)
		(end 122.196098 -276.212046)
		(width 0.1143)
		(layer "In11.Cu")
		(net "P5E_CPU1_P3_TX_DN<10>")
	)
	(segment
		(start 122.222006 -289.156902)
		(end 122.221244 -289.15741)
		(width 0.1143)
		(layer "In11.Cu")
		(net "P5E_CPU1_P3_TX_DN<10>")
	)
	(segment
		(start 122.228864 -282.673298)
		(end 122.227848 -282.673806)
		(width 0.1143)
		(layer "In11.Cu")
		(net "P5E_CPU1_P3_TX_DN<10>")
	)
	(segment
		(start 128.571498 -305.353466)
		(end 128.571752 -305.35372)
		(width 0.14224)
		(layer "In11.Cu")
		(net "P5E_CPU1_P3_TX_DN<10>")
	)
	(segment
		(start 122.698764 -295.46931)
		(end 122.700288 -295.470326)
		(width 0.1143)
		(layer "In11.Cu")
		(net "P5E_CPU1_P3_TX_DN<10>")
	)
	(segment
		(start 122.222006 -282.677108)
		(end 122.221244 -282.677616)
		(width 0.1143)
		(layer "In11.Cu")
		(net "P5E_CPU1_P3_TX_DN<10>")
	)
	(segment
		(start 122.227848 -287.533842)
		(end 122.196098 -287.55213)
		(width 0.1143)
		(layer "In11.Cu")
		(net "P5E_CPU1_P3_TX_DN<10>")
	)
	(segment
		(start 122.227848 -284.293818)
		(end 122.227086 -284.294326)
		(width 0.1143)
		(layer "In11.Cu")
		(net "P5E_CPU1_P3_TX_DN<10>")
	)
	(segment
		(start 122.266964 -276.170898)
		(end 122.228864 -276.19325)
		(width 0.1143)
		(layer "In11.Cu")
		(net "P5E_CPU1_P3_TX_DN<10>")
	)
	(segment
		(start 122.225816 -290.774882)
		(end 122.224292 -290.775644)
		(width 0.1143)
		(layer "In11.Cu")
		(net "P5E_CPU1_P3_TX_DN<10>")
	)
	(segment
		(start 122.22353 -281.056334)
		(end 122.222006 -281.057096)
		(width 0.1143)
		(layer "In11.Cu")
		(net "P5E_CPU1_P3_TX_DN<10>")
	)
	(segment
		(start 122.736864 -275.360892)
		(end 122.697748 -275.383752)
		(width 0.1143)
		(layer "In11.Cu")
		(net "P5E_CPU1_P3_TX_DN<10>")
	)
	(segment
		(start 122.227848 -276.193758)
		(end 122.227086 -276.194266)
		(width 0.1143)
		(layer "In11.Cu")
		(net "P5E_CPU1_P3_TX_DN<10>")
	)
	(segment
		(start 122.22353 -284.296358)
		(end 122.222006 -284.29712)
		(width 0.1143)
		(layer "In11.Cu")
		(net "P5E_CPU1_P3_TX_DN<10>")
	)
	(segment
		(start 122.196098 -283.300678)
		(end 122.227848 -283.318966)
		(width 0.1143)
		(layer "In11.Cu")
		(net "P5E_CPU1_P3_TX_DN<10>")
	)
	(segment
		(start 122.230388 -281.700478)
		(end 122.231404 -281.700986)
		(width 0.1143)
		(layer "In11.Cu")
		(net "P5E_CPU1_P3_TX_DN<10>")
	)
	(segment
		(start 122.230388 -276.840442)
		(end 122.231404 -276.84095)
		(width 0.1143)
		(layer "In11.Cu")
		(net "P5E_CPU1_P3_TX_DN<10>")
	)
	(segment
		(start 122.266964 -277.79091)
		(end 122.228864 -277.813262)
		(width 0.1143)
		(layer "In11.Cu")
		(net "P5E_CPU1_P3_TX_DN<10>")
	)
	(segment
		(start 122.225816 -289.15487)
		(end 122.224292 -289.155632)
		(width 0.1143)
		(layer "In11.Cu")
		(net "P5E_CPU1_P3_TX_DN<10>")
	)
	(segment
		(start 123.056904 -274.896326)
		(end 122.9741 -274.97913)
		(width 0.1143)
		(layer "In11.Cu")
		(net "P5E_CPU1_P3_TX_DN<10>")
	)
	(segment
		(start 122.8471 -295.591738)
		(end 122.910854 -295.66743)
		(width 0.1143)
		(layer "In11.Cu")
		(net "P5E_CPU1_P3_TX_DN<10>")
	)
	(segment
		(start 122.266964 -292.370764)
		(end 122.228864 -292.393116)
		(width 0.1143)
		(layer "In11.Cu")
		(net "P5E_CPU1_P3_TX_DN<10>")
	)
	(segment
		(start 122.227848 -276.838918)
		(end 122.228864 -276.839426)
		(width 0.1143)
		(layer "In11.Cu")
		(net "P5E_CPU1_P3_TX_DN<10>")
	)
	(segment
		(start 122.227848 -294.658796)
		(end 122.228864 -294.659304)
		(width 0.1143)
		(layer "In11.Cu")
		(net "P5E_CPU1_P3_TX_DN<10>")
	)
	(segment
		(start 122.228864 -284.29331)
		(end 122.227848 -284.293818)
		(width 0.1143)
		(layer "In11.Cu")
		(net "P5E_CPU1_P3_TX_DN<10>")
	)
	(segment
		(start 122.227848 -290.773612)
		(end 122.227086 -290.77412)
		(width 0.1143)
		(layer "In11.Cu")
		(net "P5E_CPU1_P3_TX_DN<10>")
	)
	(segment
		(start 122.196098 -276.82063)
		(end 122.227086 -276.83841)
		(width 0.1143)
		(layer "In11.Cu")
		(net "P5E_CPU1_P3_TX_DN<10>")
	)
	(segment
		(start 122.266964 -293.990776)
		(end 122.228864 -294.013128)
		(width 0.1143)
		(layer "In11.Cu")
		(net "P5E_CPU1_P3_TX_DN<10>")
	)
	(segment
		(start 122.228864 -294.013128)
		(end 122.227848 -294.013636)
		(width 0.1143)
		(layer "In11.Cu")
		(net "P5E_CPU1_P3_TX_DN<10>")
	)
	(segment
		(start 122.230388 -291.420296)
		(end 122.266964 -291.441632)
		(width 0.1143)
		(layer "In11.Cu")
		(net "P5E_CPU1_P3_TX_DN<10>")
	)
	(segment
		(start 122.230388 -284.940502)
		(end 122.266964 -284.961838)
		(width 0.1143)
		(layer "In11.Cu")
		(net "P5E_CPU1_P3_TX_DN<10>")
	)
	(segment
		(start 122.221244 -284.297628)
		(end 122.220228 -284.298136)
		(width 0.1143)
		(layer "In11.Cu")
		(net "P5E_CPU1_P3_TX_DN<10>")
	)
	(segment
		(start 122.224292 -290.775644)
		(end 122.22353 -290.776152)
		(width 0.1143)
		(layer "In11.Cu")
		(net "P5E_CPU1_P3_TX_DN<10>")
	)
	(segment
		(start 122.227086 -282.674314)
		(end 122.225816 -282.675076)
		(width 0.1143)
		(layer "In11.Cu")
		(net "P5E_CPU1_P3_TX_DN<10>")
	)
	(segment
		(start 122.227848 -292.393624)
		(end 122.227086 -292.394132)
		(width 0.1143)
		(layer "In11.Cu")
		(net "P5E_CPU1_P3_TX_DN<10>")
	)
	(segment
		(start 122.227848 -293.038784)
		(end 122.228864 -293.039292)
		(width 0.1143)
		(layer "In11.Cu")
		(net "P5E_CPU1_P3_TX_DN<10>")
	)
	(segment
		(start 122.225816 -282.675076)
		(end 122.224292 -282.675838)
		(width 0.1143)
		(layer "In11.Cu")
		(net "P5E_CPU1_P3_TX_DN<10>")
	)
	(segment
		(start 137.793476 -318.184022)
		(end 139.641326 -322.643754)
		(width 0.14224)
		(layer "In11.Cu")
		(net "P5E_CPU1_P3_TX_DN<10>")
	)
	(segment
		(start 122.230388 -278.460454)
		(end 122.231404 -278.460962)
		(width 0.1143)
		(layer "In11.Cu")
		(net "P5E_CPU1_P3_TX_DN<10>")
	)
	(segment
		(start 122.227848 -283.318966)
		(end 122.228864 -283.319474)
		(width 0.1143)
		(layer "In11.Cu")
		(net "P5E_CPU1_P3_TX_DN<10>")
	)
	(segment
		(start 122.220228 -289.157918)
		(end 122.196098 -289.171888)
		(width 0.1143)
		(layer "In11.Cu")
		(net "P5E_CPU1_P3_TX_DN<10>")
	)
	(segment
		(start 122.697748 -280.243788)
		(end 122.667268 -280.261568)
		(width 0.1143)
		(layer "In11.Cu")
		(net "P5E_CPU1_P3_TX_DN<10>")
	)
	(segment
		(start 142.805912 -348.760034)
		(end 139.080748 -357.754174)
		(width 0.14224)
		(layer "In11.Cu")
		(net "P5E_CPU1_P3_TX_DN<10>")
	)
	(segment
		(start 122.697748 -295.468802)
		(end 122.698764 -295.46931)
		(width 0.1143)
		(layer "In11.Cu")
		(net "P5E_CPU1_P3_TX_DN<10>")
	)
	(segment
		(start 122.196098 -289.780472)
		(end 122.227086 -289.798252)
		(width 0.1143)
		(layer "In11.Cu")
		(net "P5E_CPU1_P3_TX_DN<10>")
	)
	(segment
		(start 122.228864 -292.393116)
		(end 122.227848 -292.393624)
		(width 0.1143)
		(layer "In11.Cu")
		(net "P5E_CPU1_P3_TX_DN<10>")
	)
	(segment
		(start 122.266964 -281.030934)
		(end 122.228864 -281.053286)
		(width 0.1143)
		(layer "In11.Cu")
		(net "P5E_CPU1_P3_TX_DN<10>")
	)
	(segment
		(start 122.266964 -282.650946)
		(end 122.228864 -282.673298)
		(width 0.1143)
		(layer "In11.Cu")
		(net "P5E_CPU1_P3_TX_DN<10>")
	)
	(segment
		(start 122.227848 -278.45893)
		(end 122.228864 -278.459438)
		(width 0.1143)
		(layer "In11.Cu")
		(net "P5E_CPU1_P3_TX_DN<10>")
	)
	(segment
		(start 143.197072 -340.521544)
		(end 143.197072 -346.793312)
		(width 0.14224)
		(layer "In11.Cu")
		(net "P5E_CPU1_P3_TX_DN<10>")
	)
	(segment
		(start 122.266964 -284.270958)
		(end 122.228864 -284.29331)
		(width 0.1143)
		(layer "In11.Cu")
		(net "P5E_CPU1_P3_TX_DN<10>")
	)
	(segment
		(start 122.221244 -281.057604)
		(end 122.220228 -281.058112)
		(width 0.1143)
		(layer "In11.Cu")
		(net "P5E_CPU1_P3_TX_DN<10>")
	)
	(segment
		(start 122.225816 -284.295088)
		(end 122.224292 -284.29585)
		(width 0.1143)
		(layer "In11.Cu")
		(net "P5E_CPU1_P3_TX_DN<10>")
	)
	(segment
		(start 122.196098 -284.92069)
		(end 122.227848 -284.938978)
		(width 0.1143)
		(layer "In11.Cu")
		(net "P5E_CPU1_P3_TX_DN<10>")
	)
	(segment
		(start 122.19432 -288.15919)
		(end 122.227848 -288.178748)
		(width 0.1143)
		(layer "In11.Cu")
		(net "P5E_CPU1_P3_TX_DN<10>")
	)
	(segment
		(start 122.230388 -289.800284)
		(end 122.231404 -289.800792)
		(width 0.1143)
		(layer "In11.Cu")
		(net "P5E_CPU1_P3_TX_DN<10>")
	)
	(segment
		(start 122.227086 -277.814278)
		(end 122.225816 -277.81504)
		(width 0.1143)
		(layer "In11.Cu")
		(net "P5E_CPU1_P3_TX_DN<10>")
	)
	(segment
		(start 122.228864 -276.839426)
		(end 122.230388 -276.840442)
		(width 0.1143)
		(layer "In11.Cu")
		(net "P5E_CPU1_P3_TX_DN<10>")
	)
	(segment
		(start 122.222006 -276.19706)
		(end 122.221244 -276.197568)
		(width 0.1143)
		(layer "In11.Cu")
		(net "P5E_CPU1_P3_TX_DN<10>")
	)
	(segment
		(start 122.227086 -276.194266)
		(end 122.225816 -276.195028)
		(width 0.1143)
		(layer "In11.Cu")
		(net "P5E_CPU1_P3_TX_DN<10>")
	)
	(segment
		(start 122.665998 -295.450514)
		(end 122.697748 -295.468802)
		(width 0.1143)
		(layer "In11.Cu")
		(net "P5E_CPU1_P3_TX_DN<10>")
	)
	(segment
		(start 122.225816 -292.394894)
		(end 122.224292 -292.395656)
		(width 0.1143)
		(layer "In11.Cu")
		(net "P5E_CPU1_P3_TX_DN<10>")
	)
	(segment
		(start 122.227086 -290.77412)
		(end 122.225816 -290.774882)
		(width 0.1143)
		(layer "In11.Cu")
		(net "P5E_CPU1_P3_TX_DN<10>")
	)
	(segment
		(start 122.222006 -284.29712)
		(end 122.221244 -284.297628)
		(width 0.1143)
		(layer "In11.Cu")
		(net "P5E_CPU1_P3_TX_DN<10>")
	)
	(segment
		(start 129.407666 -369.335812)
		(end 129.407666 -373.605298)
		(width 0.14224)
		(layer "In11.Cu")
		(net "P5E_CPU1_P3_TX_DN<10>")
	)
	(segment
		(start 122.221244 -289.15741)
		(end 122.220228 -289.157918)
		(width 0.1143)
		(layer "In11.Cu")
		(net "P5E_CPU1_P3_TX_DN<10>")
	)
	(segment
		(start 122.221244 -292.397434)
		(end 122.220228 -292.397942)
		(width 0.1143)
		(layer "In11.Cu")
		(net "P5E_CPU1_P3_TX_DN<10>")
	)
	(segment
		(start 122.220228 -285.918148)
		(end 122.196098 -285.932118)
		(width 0.1143)
		(layer "In11.Cu")
		(net "P5E_CPU1_P3_TX_DN<10>")
	)
	(segment
		(start 122.227086 -278.458422)
		(end 122.227848 -278.45893)
		(width 0.1143)
		(layer "In11.Cu")
		(net "P5E_CPU1_P3_TX_DN<10>")
	)
	(segment
		(start 122.225816 -281.055064)
		(end 122.224292 -281.055826)
		(width 0.1143)
		(layer "In11.Cu")
		(net "P5E_CPU1_P3_TX_DN<10>")
	)
	(segment
		(start 139.641326 -322.643754)
		(end 143.197072 -340.521544)
		(width 0.14224)
		(layer "In11.Cu")
		(net "P5E_CPU1_P3_TX_DN<10>")
	)
	(segment
		(start 122.230388 -294.66032)
		(end 122.231404 -294.660828)
		(width 0.1143)
		(layer "In11.Cu")
		(net "P5E_CPU1_P3_TX_DN<10>")
	)
	(segment
		(start 122.231404 -278.460962)
		(end 122.266964 -278.48179)
		(width 0.1143)
		(layer "In11.Cu")
		(net "P5E_CPU1_P3_TX_DN<10>")
	)
	(segment
		(start 122.231404 -281.700986)
		(end 122.266964 -281.721814)
		(width 0.1143)
		(layer "In11.Cu")
		(net "P5E_CPU1_P3_TX_DN<10>")
	)
	(segment
		(start 122.221244 -285.91764)
		(end 122.220228 -285.918148)
		(width 0.1143)
		(layer "In11.Cu")
		(net "P5E_CPU1_P3_TX_DN<10>")
	)
	(segment
		(start 122.22353 -282.676346)
		(end 122.222006 -282.677108)
		(width 0.1143)
		(layer "In11.Cu")
		(net "P5E_CPU1_P3_TX_DN<10>")
	)
	(segment
		(start 122.231404 -294.660828)
		(end 122.266964 -294.681656)
		(width 0.1143)
		(layer "In11.Cu")
		(net "P5E_CPU1_P3_TX_DN<10>")
	)
	(segment
		(start 122.266964 -289.13074)
		(end 122.228864 -289.153092)
		(width 0.1143)
		(layer "In11.Cu")
		(net "P5E_CPU1_P3_TX_DN<10>")
	)
	(segment
		(start 122.98553 -295.872408)
		(end 122.98553 -296.067734)
		(width 0.1143)
		(layer "In11.Cu")
		(net "P5E_CPU1_P3_TX_DN<10>")
	)
	(segment
		(start 122.230388 -293.040308)
		(end 122.231404 -293.040816)
		(width 0.1143)
		(layer "In11.Cu")
		(net "P5E_CPU1_P3_TX_DN<10>")
	)
	(segment
		(start 122.220228 -284.298136)
		(end 122.196098 -284.312106)
		(width 0.1143)
		(layer "In11.Cu")
		(net "P5E_CPU1_P3_TX_DN<10>")
	)
	(segment
		(start 122.700288 -295.470326)
		(end 122.701304 -295.470834)
		(width 0.1143)
		(layer "In11.Cu")
		(net "P5E_CPU1_P3_TX_DN<10>")
	)
	(segment
		(start 122.227848 -285.91383)
		(end 122.227086 -285.914338)
		(width 0.1143)
		(layer "In11.Cu")
		(net "P5E_CPU1_P3_TX_DN<10>")
	)
	(segment
		(start 122.228864 -289.799268)
		(end 122.230388 -289.800284)
		(width 0.1143)
		(layer "In11.Cu")
		(net "P5E_CPU1_P3_TX_DN<10>")
	)
	(segment
		(start 123.06681 -296.538396)
		(end 123.11253 -296.584116)
		(width 0.1143)
		(layer "In11.Cu")
		(net "P5E_CPU1_P3_TX_DN<10>")
	)
	(segment
		(start 122.222006 -281.057096)
		(end 122.221244 -281.057604)
		(width 0.1143)
		(layer "In11.Cu")
		(net "P5E_CPU1_P3_TX_DN<10>")
	)
	(segment
		(start 125.098556 -301.121572)
		(end 128.571498 -305.353466)
		(width 0.14224)
		(layer "In11.Cu")
		(net "P5E_CPU1_P3_TX_DN<10>")
	)
	(segment
		(start 122.701304 -295.470834)
		(end 122.73661 -295.491154)
		(width 0.1143)
		(layer "In11.Cu")
		(net "P5E_CPU1_P3_TX_DN<10>")
	)
	(segment
		(start 122.230388 -283.32049)
		(end 122.266964 -283.341826)
		(width 0.1143)
		(layer "In11.Cu")
		(net "P5E_CPU1_P3_TX_DN<10>")
	)
	(segment
		(start 122.196098 -291.400484)
		(end 122.227848 -291.418772)
		(width 0.1143)
		(layer "In11.Cu")
		(net "P5E_CPU1_P3_TX_DN<10>")
	)
	(arc
		(start 122.196098 -276.212046)
		(mid 122.04017 -276.516338)
		(end 122.196098 -276.82063)
		(width 0.1143)
		(layer "In11.Cu")
		(net "P5E_CPU1_P3_TX_DN<10>")
	)
	(arc
		(start 129.415794 -369.20932)
		(mid 129.409638 -369.272431)
		(end 129.407666 -369.335812)
		(width 0.14224)
		(layer "In11.Cu")
		(net "P5E_CPU1_P3_TX_DN<10>")
	)
	(arc
		(start 122.9741 -274.97913)
		(mid 122.972312 -274.990579)
		(end 122.97029 -275.00199)
		(width 0.1143)
		(layer "In11.Cu")
		(net "P5E_CPU1_P3_TX_DN<10>")
	)
	(arc
		(start 122.266964 -283.341826)
		(mid 122.510291 -283.806392)
		(end 122.266964 -284.270958)
		(width 0.1143)
		(layer "In11.Cu")
		(net "P5E_CPU1_P3_TX_DN<10>")
	)
	(arc
		(start 122.196098 -284.312106)
		(mid 122.04017 -284.616398)
		(end 122.196098 -284.92069)
		(width 0.1143)
		(layer "In11.Cu")
		(net "P5E_CPU1_P3_TX_DN<10>")
	)
	(arc
		(start 122.196098 -282.692094)
		(mid 122.04017 -282.996386)
		(end 122.196098 -283.300678)
		(width 0.1143)
		(layer "In11.Cu")
		(net "P5E_CPU1_P3_TX_DN<10>")
	)
	(arc
		(start 122.196098 -285.932118)
		(mid 122.081422 -286.065452)
		(end 122.040142 -286.23641)
		(width 0.1143)
		(layer "In11.Cu")
		(net "P5E_CPU1_P3_TX_DN<10>")
	)
	(arc
		(start 122.667268 -275.401532)
		(mid 122.551841 -275.534908)
		(end 122.510296 -275.706332)
		(width 0.1143)
		(layer "In11.Cu")
		(net "P5E_CPU1_P3_TX_DN<10>")
	)
	(arc
		(start 122.667268 -280.261568)
		(mid 122.551841 -280.394944)
		(end 122.510296 -280.566368)
		(width 0.1143)
		(layer "In11.Cu")
		(net "P5E_CPU1_P3_TX_DN<10>")
	)
	(arc
		(start 122.266964 -281.721814)
		(mid 122.510291 -282.18638)
		(end 122.266964 -282.650946)
		(width 0.1143)
		(layer "In11.Cu")
		(net "P5E_CPU1_P3_TX_DN<10>")
	)
	(arc
		(start 122.266964 -288.201608)
		(mid 122.510291 -288.666174)
		(end 122.266964 -289.13074)
		(width 0.1143)
		(layer "In11.Cu")
		(net "P5E_CPU1_P3_TX_DN<10>")
	)
	(arc
		(start 123.001532 -296.130472)
		(mid 123.050255 -296.255437)
		(end 123.06681 -296.388536)
		(width 0.1143)
		(layer "In11.Cu")
		(net "P5E_CPU1_P3_TX_DN<10>")
	)
	(arc
		(start 122.266964 -293.061644)
		(mid 122.510291 -293.52621)
		(end 122.266964 -293.990776)
		(width 0.1143)
		(layer "In11.Cu")
		(net "P5E_CPU1_P3_TX_DN<10>")
	)
	(arc
		(start 131.070858 -366.738662)
		(mid 129.955436 -367.781138)
		(end 129.415794 -369.20932)
		(width 0.14224)
		(layer "In11.Cu")
		(net "P5E_CPU1_P3_TX_DN<10>")
	)
	(arc
		(start 139.080748 -357.754174)
		(mid 138.038764 -359.703471)
		(end 136.636506 -361.412028)
		(width 0.14224)
		(layer "In11.Cu")
		(net "P5E_CPU1_P3_TX_DN<10>")
	)
	(arc
		(start 122.73661 -295.491154)
		(mid 122.795195 -295.537778)
		(end 122.8471 -295.591738)
		(width 0.1143)
		(layer "In11.Cu")
		(net "P5E_CPU1_P3_TX_DN<10>")
	)
	(arc
		(start 122.196098 -290.7919)
		(mid 122.04017 -291.096192)
		(end 122.196098 -291.400484)
		(width 0.1143)
		(layer "In11.Cu")
		(net "P5E_CPU1_P3_TX_DN<10>")
	)
	(arc
		(start 129.407666 -373.605298)
		(mid 129.419943 -373.667021)
		(end 129.45491 -373.719344)
		(width 0.14224)
		(layer "In11.Cu")
		(net "P5E_CPU1_P3_TX_DN<10>")
	)
	(arc
		(start 122.266964 -284.961838)
		(mid 122.510291 -285.426404)
		(end 122.266964 -285.89097)
		(width 0.1143)
		(layer "In11.Cu")
		(net "P5E_CPU1_P3_TX_DN<10>")
	)
	(arc
		(start 131.161536 -366.691926)
		(mid 131.115685 -366.714301)
		(end 131.070858 -366.738662)
		(width 0.14224)
		(layer "In11.Cu")
		(net "P5E_CPU1_P3_TX_DN<10>")
	)
	(arc
		(start 122.266964 -289.82162)
		(mid 122.510291 -290.286186)
		(end 122.266964 -290.750752)
		(width 0.1143)
		(layer "In11.Cu")
		(net "P5E_CPU1_P3_TX_DN<10>")
	)
	(arc
		(start 122.510296 -275.706332)
		(mid 122.445781 -275.968551)
		(end 122.266964 -276.170898)
		(width 0.1143)
		(layer "In11.Cu")
		(net "P5E_CPU1_P3_TX_DN<10>")
	)
	(arc
		(start 122.196098 -292.411912)
		(mid 122.04017 -292.716204)
		(end 122.196098 -293.020496)
		(width 0.1143)
		(layer "In11.Cu")
		(net "P5E_CPU1_P3_TX_DN<10>")
	)
	(arc
		(start 122.196098 -281.072082)
		(mid 122.04017 -281.376374)
		(end 122.196098 -281.680666)
		(width 0.1143)
		(layer "In11.Cu")
		(net "P5E_CPU1_P3_TX_DN<10>")
	)
	(arc
		(start 122.736864 -279.291796)
		(mid 122.980191 -279.756362)
		(end 122.736864 -280.220928)
		(width 0.1143)
		(layer "In11.Cu")
		(net "P5E_CPU1_P3_TX_DN<10>")
	)
	(arc
		(start 122.266964 -291.441632)
		(mid 122.510291 -291.906198)
		(end 122.266964 -292.370764)
		(width 0.1143)
		(layer "In11.Cu")
		(net "P5E_CPU1_P3_TX_DN<10>")
	)
	(arc
		(start 122.196098 -277.832058)
		(mid 122.04017 -278.13635)
		(end 122.196098 -278.440642)
		(width 0.1143)
		(layer "In11.Cu")
		(net "P5E_CPU1_P3_TX_DN<10>")
	)
	(arc
		(start 122.040142 -286.23641)
		(mid 122.080904 -286.406294)
		(end 122.19432 -286.539178)
		(width 0.1143)
		(layer "In11.Cu")
		(net "P5E_CPU1_P3_TX_DN<10>")
	)
	(arc
		(start 122.266964 -286.581596)
		(mid 122.445777 -286.783946)
		(end 122.510296 -287.046162)
		(width 0.1143)
		(layer "In11.Cu")
		(net "P5E_CPU1_P3_TX_DN<10>")
	)
	(arc
		(start 131.261866 -366.639602)
		(mid 131.212273 -366.66686)
		(end 131.161536 -366.691926)
		(width 0.14224)
		(layer "In11.Cu")
		(net "P5E_CPU1_P3_TX_DN<10>")
	)
	(arc
		(start 122.266964 -278.48179)
		(mid 122.445777 -278.68414)
		(end 122.510296 -278.946356)
		(width 0.1143)
		(layer "In11.Cu")
		(net "P5E_CPU1_P3_TX_DN<10>")
	)
	(arc
		(start 122.97029 -275.00199)
		(mid 122.888857 -275.204388)
		(end 122.736864 -275.360892)
		(width 0.1143)
		(layer "In11.Cu")
		(net "P5E_CPU1_P3_TX_DN<10>")
	)
	(arc
		(start 122.196098 -289.171888)
		(mid 122.04017 -289.47618)
		(end 122.196098 -289.780472)
		(width 0.1143)
		(layer "In11.Cu")
		(net "P5E_CPU1_P3_TX_DN<10>")
	)
	(arc
		(start 122.266964 -276.861778)
		(mid 122.510291 -277.326344)
		(end 122.266964 -277.79091)
		(width 0.1143)
		(layer "In11.Cu")
		(net "P5E_CPU1_P3_TX_DN<10>")
	)
	(arc
		(start 122.510296 -287.046162)
		(mid 122.44506 -287.309753)
		(end 122.264424 -287.512506)
		(width 0.1143)
		(layer "In11.Cu")
		(net "P5E_CPU1_P3_TX_DN<10>")
	)
	(arc
		(start 143.197072 -346.793312)
		(mid 143.098335 -347.795935)
		(end 142.805912 -348.760034)
		(width 0.14224)
		(layer "In11.Cu")
		(net "P5E_CPU1_P3_TX_DN<10>")
	)
	(arc
		(start 122.196098 -294.031924)
		(mid 122.04017 -294.336216)
		(end 122.196098 -294.640508)
		(width 0.1143)
		(layer "In11.Cu")
		(net "P5E_CPU1_P3_TX_DN<10>")
	)
	(arc
		(start 122.510042 -295.146222)
		(mid 122.551297 -295.317193)
		(end 122.665998 -295.450514)
		(width 0.1143)
		(layer "In11.Cu")
		(net "P5E_CPU1_P3_TX_DN<10>")
	)
	(arc
		(start 122.040142 -287.856422)
		(mid 122.080904 -288.026306)
		(end 122.19432 -288.15919)
		(width 0.1143)
		(layer "In11.Cu")
		(net "P5E_CPU1_P3_TX_DN<10>")
	)
	(arc
		(start 131.893056 -366.155478)
		(mid 131.593411 -366.418334)
		(end 131.261866 -366.639602)
		(width 0.14224)
		(layer "In11.Cu")
		(net "P5E_CPU1_P3_TX_DN<10>")
	)
	(arc
		(start 122.98553 -296.067734)
		(mid 122.989629 -296.100097)
		(end 123.001532 -296.130472)
		(width 0.1143)
		(layer "In11.Cu")
		(net "P5E_CPU1_P3_TX_DN<10>")
	)
	(arc
		(start 122.510296 -278.946356)
		(mid 122.551845 -279.117778)
		(end 122.667268 -279.251156)
		(width 0.1143)
		(layer "In11.Cu")
		(net "P5E_CPU1_P3_TX_DN<10>")
	)
	(arc
		(start 122.266964 -294.681656)
		(mid 122.445777 -294.884006)
		(end 122.510296 -295.146222)
		(width 0.1143)
		(layer "In11.Cu")
		(net "P5E_CPU1_P3_TX_DN<10>")
	)
	(arc
		(start 122.510296 -280.566368)
		(mid 122.445781 -280.828587)
		(end 122.266964 -281.030934)
		(width 0.1143)
		(layer "In11.Cu")
		(net "P5E_CPU1_P3_TX_DN<10>")
	)
	(arc
		(start 122.910854 -295.66743)
		(mid 122.966314 -295.763316)
		(end 122.98553 -295.872408)
		(width 0.1143)
		(layer "In11.Cu")
		(net "P5E_CPU1_P3_TX_DN<10>")
	)
	(arc
		(start 122.196098 -287.55213)
		(mid 122.081422 -287.685464)
		(end 122.040142 -287.856422)
		(width 0.1143)
		(layer "In11.Cu")
		(net "P5E_CPU1_P3_TX_DN<10>")
	)
	(segment
		(start 114.897916 -275.440394)
		(end 115.364768 -275.706332)
		(width 0.12954)
		(layer "F.Cu")
		(net "P5E_CPU1_P3_TX_DN<0>")
	)
	(segment
		(start 108.530644 -381.50546)
		(end 108.801154 -381.77597)
		(width 0.12954)
		(layer "F.Cu")
		(net "P5E_CPU1_P3_TX_DN<0>")
	)
	(segment
		(start 108.801154 -381.77597)
		(end 109.504734 -381.77597)
		(width 0.12954)
		(layer "F.Cu")
		(net "P5E_CPU1_P3_TX_DN<0>")
	)
	(segment
		(start 109.504734 -381.77597)
		(end 109.800644 -381.48006)
		(width 0.12954)
		(layer "F.Cu")
		(net "P5E_CPU1_P3_TX_DN<0>")
	)
	(segment
		(start 133.35254 -344.703908)
		(end 129.960624 -352.892106)
		(width 0.14224)
		(layer "In11.Cu")
		(net "P5E_CPU1_P3_TX_DN<0>")
	)
	(segment
		(start 112.140746 -364.812072)
		(end 110.58144 -365.747046)
		(width 0.14224)
		(layer "In11.Cu")
		(net "P5E_CPU1_P3_TX_DN<0>")
	)
	(segment
		(start 107.876086 -371.086634)
		(end 107.809792 -371.508528)
		(width 0.14224)
		(layer "In11.Cu")
		(net "P5E_CPU1_P3_TX_DN<0>")
	)
	(segment
		(start 107.33659 -376.721878)
		(end 107.189016 -376.847862)
		(width 0.14224)
		(layer "In11.Cu")
		(net "P5E_CPU1_P3_TX_DN<0>")
	)
	(segment
		(start 110.476538 -365.817658)
		(end 109.954568 -366.20958)
		(width 0.14224)
		(layer "In11.Cu")
		(net "P5E_CPU1_P3_TX_DN<0>")
	)
	(segment
		(start 112.95634 -278.672544)
		(end 112.95634 -295.689782)
		(width 0.14224)
		(layer "In11.Cu")
		(net "P5E_CPU1_P3_TX_DN<0>")
	)
	(segment
		(start 114.237008 -277.004272)
		(end 114.235738 -277.005034)
		(width 0.1143)
		(layer "In11.Cu")
		(net "P5E_CPU1_P3_TX_DN<0>")
	)
	(segment
		(start 107.55503 -373.938292)
		(end 107.521502 -374.363996)
		(width 0.14224)
		(layer "In11.Cu")
		(net "P5E_CPU1_P3_TX_DN<0>")
	)
	(segment
		(start 107.521502 -374.363996)
		(end 107.373928 -374.48998)
		(width 0.14224)
		(layer "In11.Cu")
		(net "P5E_CPU1_P3_TX_DN<0>")
	)
	(segment
		(start 127.306578 -319.403222)
		(end 128.92278 -321.822318)
		(width 0.14224)
		(layer "In11.Cu")
		(net "P5E_CPU1_P3_TX_DN<0>")
	)
	(segment
		(start 109.094016 -367.213642)
		(end 108.254292 -368.785394)
		(width 0.14224)
		(layer "In11.Cu")
		(net "P5E_CPU1_P3_TX_DN<0>")
	)
	(segment
		(start 113.373916 -278.189944)
		(end 113.373916 -278.254968)
		(width 0.1143)
		(layer "In11.Cu")
		(net "P5E_CPU1_P3_TX_DN<0>")
	)
	(segment
		(start 107.110276 -381.092964)
		(end 107.123738 -381.106426)
		(width 0.14224)
		(layer "In11.Cu")
		(net "P5E_CPU1_P3_TX_DN<0>")
	)
	(segment
		(start 114.746786 -276.170898)
		(end 114.67592 -276.2123)
		(width 0.1143)
		(layer "In11.Cu")
		(net "P5E_CPU1_P3_TX_DN<0>")
	)
	(segment
		(start 107.113324 -377.81357)
		(end 107.111546 -379.965204)
		(width 0.14224)
		(layer "In11.Cu")
		(net "P5E_CPU1_P3_TX_DN<0>")
	)
	(segment
		(start 114.232182 -277.007066)
		(end 114.230912 -277.007828)
		(width 0.1143)
		(layer "In11.Cu")
		(net "P5E_CPU1_P3_TX_DN<0>")
	)
	(segment
		(start 107.248198 -380.529338)
		(end 107.11053 -380.666498)
		(width 0.14224)
		(layer "In11.Cu")
		(net "P5E_CPU1_P3_TX_DN<0>")
	)
	(segment
		(start 113.35385 -278.275034)
		(end 112.95634 -278.672544)
		(width 0.14224)
		(layer "In11.Cu")
		(net "P5E_CPU1_P3_TX_DN<0>")
	)
	(segment
		(start 107.111546 -379.965204)
		(end 107.248452 -380.102364)
		(width 0.14224)
		(layer "In11.Cu")
		(net "P5E_CPU1_P3_TX_DN<0>")
	)
	(segment
		(start 133.723888 -341.714836)
		(end 133.723888 -342.83777)
		(width 0.14224)
		(layer "In11.Cu")
		(net "P5E_CPU1_P3_TX_DN<0>")
	)
	(segment
		(start 107.960414 -369.66525)
		(end 107.761786 -370.929916)
		(width 0.14224)
		(layer "In11.Cu")
		(net "P5E_CPU1_P3_TX_DN<0>")
	)
	(segment
		(start 107.545124 -372.309136)
		(end 107.429046 -373.790718)
		(width 0.14224)
		(layer "In11.Cu")
		(net "P5E_CPU1_P3_TX_DN<0>")
	)
	(segment
		(start 114.230912 -277.007828)
		(end 114.229388 -277.00859)
		(width 0.1143)
		(layer "In11.Cu")
		(net "P5E_CPU1_P3_TX_DN<0>")
	)
	(segment
		(start 107.373928 -374.48998)
		(end 107.24388 -376.1486)
		(width 0.14224)
		(layer "In11.Cu")
		(net "P5E_CPU1_P3_TX_DN<0>")
	)
	(segment
		(start 107.248452 -380.102364)
		(end 107.248198 -380.529338)
		(width 0.14224)
		(layer "In11.Cu")
		(net "P5E_CPU1_P3_TX_DN<0>")
	)
	(segment
		(start 107.761786 -370.929916)
		(end 107.876086 -371.086634)
		(width 0.14224)
		(layer "In11.Cu")
		(net "P5E_CPU1_P3_TX_DN<0>")
	)
	(segment
		(start 108.239814 -381.79629)
		(end 108.530644 -381.50546)
		(width 0.14224)
		(layer "In11.Cu")
		(net "P5E_CPU1_P3_TX_DN<0>")
	)
	(segment
		(start 113.691162 -277.872698)
		(end 113.373916 -278.189944)
		(width 0.1143)
		(layer "In11.Cu")
		(net "P5E_CPU1_P3_TX_DN<0>")
	)
	(segment
		(start 114.232944 -277.006558)
		(end 114.232182 -277.007066)
		(width 0.1143)
		(layer "In11.Cu")
		(net "P5E_CPU1_P3_TX_DN<0>")
	)
	(segment
		(start 114.276124 -276.981666)
		(end 114.239802 -277.002494)
		(width 0.1143)
		(layer "In11.Cu")
		(net "P5E_CPU1_P3_TX_DN<0>")
	)
	(segment
		(start 114.519964 -276.513544)
		(end 114.519964 -276.516338)
		(width 0.1143)
		(layer "In11.Cu")
		(net "P5E_CPU1_P3_TX_DN<0>")
	)
	(segment
		(start 107.339638 -381.628142)
		(end 107.470448 -381.758952)
		(width 0.14224)
		(layer "In11.Cu")
		(net "P5E_CPU1_P3_TX_DN<0>")
	)
	(segment
		(start 107.809792 -371.508528)
		(end 107.65282 -371.622828)
		(width 0.14224)
		(layer "In11.Cu")
		(net "P5E_CPU1_P3_TX_DN<0>")
	)
	(segment
		(start 114.229388 -277.00859)
		(end 114.228118 -277.009352)
		(width 0.1143)
		(layer "In11.Cu")
		(net "P5E_CPU1_P3_TX_DN<0>")
	)
	(segment
		(start 115.165124 -303.355756)
		(end 119.672608 -310.101742)
		(width 0.14224)
		(layer "In11.Cu")
		(net "P5E_CPU1_P3_TX_DN<0>")
	)
	(segment
		(start 114.22507 -277.010876)
		(end 114.224308 -277.011384)
		(width 0.1143)
		(layer "In11.Cu")
		(net "P5E_CPU1_P3_TX_DN<0>")
	)
	(segment
		(start 112.95634 -295.689782)
		(end 113.068862 -296.447972)
		(width 0.14224)
		(layer "In11.Cu")
		(net "P5E_CPU1_P3_TX_DN<0>")
	)
	(segment
		(start 114.235738 -277.005034)
		(end 114.234214 -277.005796)
		(width 0.1143)
		(layer "In11.Cu")
		(net "P5E_CPU1_P3_TX_DN<0>")
	)
	(segment
		(start 114.239802 -277.002494)
		(end 114.23777 -277.003764)
		(width 0.1143)
		(layer "In11.Cu")
		(net "P5E_CPU1_P3_TX_DN<0>")
	)
	(segment
		(start 115.066826 -275.706332)
		(end 114.984022 -275.789136)
		(width 0.1143)
		(layer "In11.Cu")
		(net "P5E_CPU1_P3_TX_DN<0>")
	)
	(segment
		(start 116.32565 -362.562902)
		(end 112.538002 -364.587282)
		(width 0.14224)
		(layer "In11.Cu")
		(net "P5E_CPU1_P3_TX_DN<0>")
	)
	(segment
		(start 114.228118 -277.009352)
		(end 114.22507 -277.010876)
		(width 0.1143)
		(layer "In11.Cu")
		(net "P5E_CPU1_P3_TX_DN<0>")
	)
	(segment
		(start 113.806732 -277.79091)
		(end 113.767616 -277.81377)
		(width 0.1143)
		(layer "In11.Cu")
		(net "P5E_CPU1_P3_TX_DN<0>")
	)
	(segment
		(start 115.364768 -275.706332)
		(end 115.066826 -275.706332)
		(width 0.1143)
		(layer "In11.Cu")
		(net "P5E_CPU1_P3_TX_DN<0>")
	)
	(segment
		(start 114.234214 -277.005796)
		(end 114.232944 -277.006558)
		(width 0.1143)
		(layer "In11.Cu")
		(net "P5E_CPU1_P3_TX_DN<0>")
	)
	(segment
		(start 107.65282 -371.622828)
		(end 107.545124 -372.309136)
		(width 0.14224)
		(layer "In11.Cu")
		(net "P5E_CPU1_P3_TX_DN<0>")
	)
	(segment
		(start 107.189016 -376.847862)
		(end 107.113324 -377.812554)
		(width 0.14224)
		(layer "In11.Cu")
		(net "P5E_CPU1_P3_TX_DN<0>")
	)
	(segment
		(start 128.41732 -354.820474)
		(end 121.353834 -359.795572)
		(width 0.14224)
		(layer "In11.Cu")
		(net "P5E_CPU1_P3_TX_DN<0>")
	)
	(segment
		(start 113.373916 -278.254968)
		(end 113.35385 -278.275034)
		(width 0.1143)
		(layer "In11.Cu")
		(net "P5E_CPU1_P3_TX_DN<0>")
	)
	(segment
		(start 107.113324 -377.812554)
		(end 107.113324 -377.81357)
		(width 0.14224)
		(layer "In11.Cu")
		(net "P5E_CPU1_P3_TX_DN<0>")
	)
	(segment
		(start 114.224308 -277.011384)
		(end 114.20602 -277.022052)
		(width 0.1143)
		(layer "In11.Cu")
		(net "P5E_CPU1_P3_TX_DN<0>")
	)
	(segment
		(start 119.672608 -310.101742)
		(end 127.306578 -319.403222)
		(width 0.14224)
		(layer "In11.Cu")
		(net "P5E_CPU1_P3_TX_DN<0>")
	)
	(segment
		(start 107.429046 -373.790718)
		(end 107.55503 -373.938292)
		(width 0.14224)
		(layer "In11.Cu")
		(net "P5E_CPU1_P3_TX_DN<0>")
	)
	(segment
		(start 114.23777 -277.003764)
		(end 114.237008 -277.004272)
		(width 0.1143)
		(layer "In11.Cu")
		(net "P5E_CPU1_P3_TX_DN<0>")
	)
	(segment
		(start 107.24388 -376.1486)
		(end 107.370118 -376.296174)
		(width 0.14224)
		(layer "In11.Cu")
		(net "P5E_CPU1_P3_TX_DN<0>")
	)
	(segment
		(start 107.11053 -380.666498)
		(end 107.110276 -381.092964)
		(width 0.14224)
		(layer "In11.Cu")
		(net "P5E_CPU1_P3_TX_DN<0>")
	)
	(segment
		(start 113.068862 -296.447972)
		(end 115.165124 -303.355756)
		(width 0.14224)
		(layer "In11.Cu")
		(net "P5E_CPU1_P3_TX_DN<0>")
	)
	(segment
		(start 107.370118 -376.296174)
		(end 107.33659 -376.721878)
		(width 0.14224)
		(layer "In11.Cu")
		(net "P5E_CPU1_P3_TX_DN<0>")
	)
	(segment
		(start 128.92278 -321.822318)
		(end 130.557524 -325.768208)
		(width 0.14224)
		(layer "In11.Cu")
		(net "P5E_CPU1_P3_TX_DN<0>")
	)
	(segment
		(start 107.560618 -381.79629)
		(end 108.239814 -381.79629)
		(width 0.14224)
		(layer "In11.Cu")
		(net "P5E_CPU1_P3_TX_DN<0>")
	)
	(segment
		(start 118.103142 -361.716574)
		(end 116.500656 -362.474764)
		(width 0.14224)
		(layer "In11.Cu")
		(net "P5E_CPU1_P3_TX_DN<0>")
	)
	(segment
		(start 130.5941 -325.888858)
		(end 133.706108 -341.534242)
		(width 0.14224)
		(layer "In11.Cu")
		(net "P5E_CPU1_P3_TX_DN<0>")
	)
	(arc
		(start 133.723888 -342.83777)
		(mid 133.630128 -343.78913)
		(end 133.35254 -344.703908)
		(width 0.14224)
		(layer "In11.Cu")
		(net "P5E_CPU1_P3_TX_DN<0>")
	)
	(arc
		(start 121.353834 -359.795572)
		(mid 119.766862 -360.821009)
		(end 118.103142 -361.716574)
		(width 0.14224)
		(layer "In11.Cu")
		(net "P5E_CPU1_P3_TX_DN<0>")
	)
	(arc
		(start 114.519964 -276.516338)
		(mid 114.455364 -276.779037)
		(end 114.276124 -276.981666)
		(width 0.1143)
		(layer "In11.Cu")
		(net "P5E_CPU1_P3_TX_DN<0>")
	)
	(arc
		(start 113.767616 -277.81377)
		(mid 113.727471 -277.840746)
		(end 113.691162 -277.872698)
		(width 0.1143)
		(layer "In11.Cu")
		(net "P5E_CPU1_P3_TX_DN<0>")
	)
	(arc
		(start 110.58144 -365.747046)
		(mid 110.528074 -365.780992)
		(end 110.476538 -365.817658)
		(width 0.14224)
		(layer "In11.Cu")
		(net "P5E_CPU1_P3_TX_DN<0>")
	)
	(arc
		(start 107.123738 -381.106426)
		(mid 107.179658 -381.388815)
		(end 107.339638 -381.628142)
		(width 0.14224)
		(layer "In11.Cu")
		(net "P5E_CPU1_P3_TX_DN<0>")
	)
	(arc
		(start 130.557524 -325.768208)
		(mid 130.578763 -325.827638)
		(end 130.5941 -325.888858)
		(width 0.14224)
		(layer "In11.Cu")
		(net "P5E_CPU1_P3_TX_DN<0>")
	)
	(arc
		(start 109.954568 -366.20958)
		(mid 109.469328 -366.664507)
		(end 109.094016 -367.213642)
		(width 0.14224)
		(layer "In11.Cu")
		(net "P5E_CPU1_P3_TX_DN<0>")
	)
	(arc
		(start 116.500656 -362.474764)
		(mid 116.412614 -362.517762)
		(end 116.32565 -362.562902)
		(width 0.14224)
		(layer "In11.Cu")
		(net "P5E_CPU1_P3_TX_DN<0>")
	)
	(arc
		(start 114.20602 -277.022052)
		(mid 114.091344 -277.155386)
		(end 114.050064 -277.326344)
		(width 0.1143)
		(layer "In11.Cu")
		(net "P5E_CPU1_P3_TX_DN<0>")
	)
	(arc
		(start 114.980212 -275.811996)
		(mid 114.898779 -276.014394)
		(end 114.746786 -276.170898)
		(width 0.1143)
		(layer "In11.Cu")
		(net "P5E_CPU1_P3_TX_DN<0>")
	)
	(arc
		(start 133.706108 -341.534242)
		(mid 133.719424 -341.624103)
		(end 133.723888 -341.714836)
		(width 0.14224)
		(layer "In11.Cu")
		(net "P5E_CPU1_P3_TX_DN<0>")
	)
	(arc
		(start 129.960624 -352.892106)
		(mid 129.325922 -353.965891)
		(end 128.41732 -354.820474)
		(width 0.14224)
		(layer "In11.Cu")
		(net "P5E_CPU1_P3_TX_DN<0>")
	)
	(arc
		(start 114.050064 -277.326344)
		(mid 113.985549 -277.588563)
		(end 113.806732 -277.79091)
		(width 0.1143)
		(layer "In11.Cu")
		(net "P5E_CPU1_P3_TX_DN<0>")
	)
	(arc
		(start 107.470448 -381.758952)
		(mid 107.511818 -381.786595)
		(end 107.560618 -381.79629)
		(width 0.14224)
		(layer "In11.Cu")
		(net "P5E_CPU1_P3_TX_DN<0>")
	)
	(arc
		(start 112.538002 -364.587282)
		(mid 112.337992 -364.697234)
		(end 112.140746 -364.812072)
		(width 0.14224)
		(layer "In11.Cu")
		(net "P5E_CPU1_P3_TX_DN<0>")
	)
	(arc
		(start 114.67592 -276.2123)
		(mid 114.561292 -276.343953)
		(end 114.519964 -276.513544)
		(width 0.1143)
		(layer "In11.Cu")
		(net "P5E_CPU1_P3_TX_DN<0>")
	)
	(arc
		(start 108.254292 -368.785394)
		(mid 108.070609 -369.21305)
		(end 107.960414 -369.66525)
		(width 0.14224)
		(layer "In11.Cu")
		(net "P5E_CPU1_P3_TX_DN<0>")
	)
	(arc
		(start 114.984022 -275.789136)
		(mid 114.982234 -275.800585)
		(end 114.980212 -275.811996)
		(width 0.1143)
		(layer "In11.Cu")
		(net "P5E_CPU1_P3_TX_DN<0>")
	)
	(segment
		(start 122.887994 -287.590484)
		(end 123.354846 -287.856422)
		(width 0.12954)
		(layer "F.Cu")
		(net "P5E_CPU1_P3_RX_DP<9>")
	)
	(segment
		(start 125.570488 -386.003292)
		(end 126.091188 -386.003292)
		(width 0.127)
		(layer "F.Cu")
		(net "P5E_CPU1_P3_RX_DP<9>")
	)
	(segment
		(start 122.22353 -289.15614)
		(end 122.224292 -289.155632)
		(width 0.1143)
		(layer "In4.Cu")
		(net "P5E_CPU1_P3_RX_DP<9>")
	)
	(segment
		(start 122.225562 -293.037514)
		(end 122.195844 -293.020242)
		(width 0.1143)
		(layer "In4.Cu")
		(net "P5E_CPU1_P3_RX_DP<9>")
	)
	(segment
		(start 122.233436 -294.010334)
		(end 122.235214 -294.009064)
		(width 0.1143)
		(layer "In4.Cu")
		(net "P5E_CPU1_P3_RX_DP<9>")
	)
	(segment
		(start 126.360428 -385.548632)
		(end 126.448566 -385.460494)
		(width 0.14224)
		(layer "In4.Cu")
		(net "P5E_CPU1_P3_RX_DP<9>")
	)
	(segment
		(start 122.195844 -292.412166)
		(end 122.200416 -292.409626)
		(width 0.1143)
		(layer "In4.Cu")
		(net "P5E_CPU1_P3_RX_DP<9>")
	)
	(segment
		(start 122.230388 -294.012112)
		(end 122.232166 -294.011096)
		(width 0.1143)
		(layer "In4.Cu")
		(net "P5E_CPU1_P3_RX_DP<9>")
	)
	(segment
		(start 122.22353 -291.416232)
		(end 122.222006 -291.41547)
		(width 0.1143)
		(layer "In4.Cu")
		(net "P5E_CPU1_P3_RX_DP<9>")
	)
	(segment
		(start 122.234198 -289.149536)
		(end 122.267218 -289.130232)
		(width 0.1143)
		(layer "In4.Cu")
		(net "P5E_CPU1_P3_RX_DP<9>")
	)
	(segment
		(start 122.222006 -291.41547)
		(end 122.221244 -291.414962)
		(width 0.1143)
		(layer "In4.Cu")
		(net "P5E_CPU1_P3_RX_DP<9>")
	)
	(segment
		(start 126.656592 -378.513848)
		(end 126.537974 -373.983504)
		(width 0.14224)
		(layer "In4.Cu")
		(net "P5E_CPU1_P3_RX_DP<9>")
	)
	(segment
		(start 122.235214 -294.009064)
		(end 122.248676 -294.000428)
		(width 0.1143)
		(layer "In4.Cu")
		(net "P5E_CPU1_P3_RX_DP<9>")
	)
	(segment
		(start 126.448566 -385.460494)
		(end 126.448566 -385.046982)
		(width 0.14224)
		(layer "In4.Cu")
		(net "P5E_CPU1_P3_RX_DP<9>")
	)
	(segment
		(start 122.20829 -292.4048)
		(end 122.221244 -292.396672)
		(width 0.1143)
		(layer "In4.Cu")
		(net "P5E_CPU1_P3_RX_DP<9>")
	)
	(segment
		(start 122.204226 -289.167062)
		(end 122.207274 -289.165284)
		(width 0.1143)
		(layer "In4.Cu")
		(net "P5E_CPU1_P3_RX_DP<9>")
	)
	(segment
		(start 122.227594 -295.633648)
		(end 122.268234 -295.609772)
		(width 0.1143)
		(layer "In4.Cu")
		(net "P5E_CPU1_P3_RX_DP<9>")
	)
	(segment
		(start 122.200416 -292.409626)
		(end 122.201178 -292.409118)
		(width 0.1143)
		(layer "In4.Cu")
		(net "P5E_CPU1_P3_RX_DP<9>")
	)
	(segment
		(start 122.039888 -296.38244)
		(end 122.039888 -295.956228)
		(width 0.1143)
		(layer "In4.Cu")
		(net "P5E_CPU1_P3_RX_DP<9>")
	)
	(segment
		(start 126.40056 -382.48844)
		(end 126.646432 -378.981716)
		(width 0.14224)
		(layer "In4.Cu")
		(net "P5E_CPU1_P3_RX_DP<9>")
	)
	(segment
		(start 122.201178 -292.409118)
		(end 122.203972 -292.407594)
		(width 0.1143)
		(layer "In4.Cu")
		(net "P5E_CPU1_P3_RX_DP<9>")
	)
	(segment
		(start 122.227848 -294.658796)
		(end 122.22607 -294.65778)
		(width 0.1143)
		(layer "In4.Cu")
		(net "P5E_CPU1_P3_RX_DP<9>")
	)
	(segment
		(start 122.226832 -294.014652)
		(end 122.228864 -294.013382)
		(width 0.1143)
		(layer "In4.Cu")
		(net "P5E_CPU1_P3_RX_DP<9>")
	)
	(segment
		(start 122.249692 -293.99992)
		(end 122.250454 -293.999412)
		(width 0.1143)
		(layer "In4.Cu")
		(net "P5E_CPU1_P3_RX_DP<9>")
	)
	(segment
		(start 122.225308 -294.657272)
		(end 122.225308 -294.657526)
		(width 0.1143)
		(layer "In4.Cu")
		(net "P5E_CPU1_P3_RX_DP<9>")
	)
	(segment
		(start 126.186184 -385.649216)
		(end 126.360428 -385.548632)
		(width 0.14224)
		(layer "In4.Cu")
		(net "P5E_CPU1_P3_RX_DP<9>")
	)
	(segment
		(start 121.79681 -290.631626)
		(end 121.757694 -290.608766)
		(width 0.1143)
		(layer "In4.Cu")
		(net "P5E_CPU1_P3_RX_DP<9>")
	)
	(segment
		(start 128.492758 -370.649754)
		(end 129.225294 -367.72596)
		(width 0.14224)
		(layer "In4.Cu")
		(net "P5E_CPU1_P3_RX_DP<9>")
	)
	(segment
		(start 122.235214 -291.422836)
		(end 122.235214 -291.42309)
		(width 0.1143)
		(layer "In4.Cu")
		(net "P5E_CPU1_P3_RX_DP<9>")
	)
	(segment
		(start 122.22607 -294.65778)
		(end 122.225308 -294.657272)
		(width 0.1143)
		(layer "In4.Cu")
		(net "P5E_CPU1_P3_RX_DP<9>")
	)
	(segment
		(start 122.230388 -293.040308)
		(end 122.228864 -293.039292)
		(width 0.1143)
		(layer "In4.Cu")
		(net "P5E_CPU1_P3_RX_DP<9>")
	)
	(segment
		(start 122.226832 -292.394132)
		(end 122.246898 -292.383972)
		(width 0.1143)
		(layer "In4.Cu")
		(net "P5E_CPU1_P3_RX_DP<9>")
	)
	(segment
		(start 122.230388 -294.66032)
		(end 122.228864 -294.659304)
		(width 0.1143)
		(layer "In4.Cu")
		(net "P5E_CPU1_P3_RX_DP<9>")
	)
	(segment
		(start 122.228864 -294.659304)
		(end 122.227848 -294.658796)
		(width 0.1143)
		(layer "In4.Cu")
		(net "P5E_CPU1_P3_RX_DP<9>")
	)
	(segment
		(start 126.448566 -385.046982)
		(end 126.13259 -384.731006)
		(width 0.14224)
		(layer "In4.Cu")
		(net "P5E_CPU1_P3_RX_DP<9>")
	)
	(segment
		(start 122.235214 -291.42309)
		(end 122.233182 -291.42182)
		(width 0.1143)
		(layer "In4.Cu")
		(net "P5E_CPU1_P3_RX_DP<9>")
	)
	(segment
		(start 122.21464 -289.16122)
		(end 122.216418 -289.160204)
		(width 0.1143)
		(layer "In4.Cu")
		(net "P5E_CPU1_P3_RX_DP<9>")
	)
	(segment
		(start 122.25528 -291.436298)
		(end 122.241056 -291.4269)
		(width 0.1143)
		(layer "In4.Cu")
		(net "P5E_CPU1_P3_RX_DP<9>")
	)
	(segment
		(start 122.220736 -294.018716)
		(end 122.226832 -294.014652)
		(width 0.1143)
		(layer "In4.Cu")
		(net "P5E_CPU1_P3_RX_DP<9>")
	)
	(segment
		(start 121.727214 -289.981386)
		(end 121.770902 -289.955986)
		(width 0.1143)
		(layer "In4.Cu")
		(net "P5E_CPU1_P3_RX_DP<9>")
	)
	(segment
		(start 140.847572 -356.438708)
		(end 140.847572 -336.904838)
		(width 0.14224)
		(layer "In4.Cu")
		(net "P5E_CPU1_P3_RX_DP<9>")
	)
	(segment
		(start 122.221244 -289.15741)
		(end 122.222006 -289.156902)
		(width 0.1143)
		(layer "In4.Cu")
		(net "P5E_CPU1_P3_RX_DP<9>")
	)
	(segment
		(start 132.808218 -312.048144)
		(end 123.93168 -301.232062)
		(width 0.14224)
		(layer "In4.Cu")
		(net "P5E_CPU1_P3_RX_DP<9>")
	)
	(segment
		(start 122.203972 -292.407594)
		(end 122.204734 -292.407086)
		(width 0.1143)
		(layer "In4.Cu")
		(net "P5E_CPU1_P3_RX_DP<9>")
	)
	(segment
		(start 122.510296 -288.666174)
		(end 122.510042 -288.666174)
		(width 0.1143)
		(layer "In4.Cu")
		(net "P5E_CPU1_P3_RX_DP<9>")
	)
	(segment
		(start 122.222514 -292.396164)
		(end 122.226832 -292.394132)
		(width 0.1143)
		(layer "In4.Cu")
		(net "P5E_CPU1_P3_RX_DP<9>")
	)
	(segment
		(start 122.217688 -289.159442)
		(end 122.21845 -289.158934)
		(width 0.1143)
		(layer "In4.Cu")
		(net "P5E_CPU1_P3_RX_DP<9>")
	)
	(segment
		(start 122.665998 -288.362136)
		(end 122.736864 -288.320988)
		(width 0.1143)
		(layer "In4.Cu")
		(net "P5E_CPU1_P3_RX_DP<9>")
	)
	(segment
		(start 127.12065 -372.52275)
		(end 127.837946 -371.805454)
		(width 0.14224)
		(layer "In4.Cu")
		(net "P5E_CPU1_P3_RX_DP<9>")
	)
	(segment
		(start 122.21845 -289.158934)
		(end 122.219974 -289.158172)
		(width 0.1143)
		(layer "In4.Cu")
		(net "P5E_CPU1_P3_RX_DP<9>")
	)
	(segment
		(start 122.212354 -294.023288)
		(end 122.220736 -294.018716)
		(width 0.1143)
		(layer "In4.Cu")
		(net "P5E_CPU1_P3_RX_DP<9>")
	)
	(segment
		(start 122.085608 -296.42816)
		(end 122.039888 -296.38244)
		(width 0.1143)
		(layer "In4.Cu")
		(net "P5E_CPU1_P3_RX_DP<9>")
	)
	(segment
		(start 122.9741 -287.939226)
		(end 123.056904 -287.856422)
		(width 0.1143)
		(layer "In4.Cu")
		(net "P5E_CPU1_P3_RX_DP<9>")
	)
	(segment
		(start 122.221244 -292.396672)
		(end 122.222514 -292.396164)
		(width 0.1143)
		(layer "In4.Cu")
		(net "P5E_CPU1_P3_RX_DP<9>")
	)
	(segment
		(start 122.227848 -291.418772)
		(end 122.227086 -291.418264)
		(width 0.1143)
		(layer "In4.Cu")
		(net "P5E_CPU1_P3_RX_DP<9>")
	)
	(segment
		(start 122.219974 -289.158172)
		(end 122.221244 -289.15741)
		(width 0.1143)
		(layer "In4.Cu")
		(net "P5E_CPU1_P3_RX_DP<9>")
	)
	(segment
		(start 122.222006 -289.156902)
		(end 122.22353 -289.15614)
		(width 0.1143)
		(layer "In4.Cu")
		(net "P5E_CPU1_P3_RX_DP<9>")
	)
	(segment
		(start 122.195844 -295.651936)
		(end 122.227594 -295.633648)
		(width 0.1143)
		(layer "In4.Cu")
		(net "P5E_CPU1_P3_RX_DP<9>")
	)
	(segment
		(start 122.264678 -293.060628)
		(end 122.239024 -293.045896)
		(width 0.1143)
		(layer "In4.Cu")
		(net "P5E_CPU1_P3_RX_DP<9>")
	)
	(segment
		(start 122.266964 -294.681656)
		(end 122.230388 -294.66032)
		(width 0.1143)
		(layer "In4.Cu")
		(net "P5E_CPU1_P3_RX_DP<9>")
	)
	(segment
		(start 122.227848 -293.038784)
		(end 122.226578 -293.038022)
		(width 0.1143)
		(layer "In4.Cu")
		(net "P5E_CPU1_P3_RX_DP<9>")
	)
	(segment
		(start 122.228864 -294.013382)
		(end 122.228864 -294.013128)
		(width 0.1143)
		(layer "In4.Cu")
		(net "P5E_CPU1_P3_RX_DP<9>")
	)
	(segment
		(start 122.232166 -291.421312)
		(end 122.230642 -291.420296)
		(width 0.1143)
		(layer "In4.Cu")
		(net "P5E_CPU1_P3_RX_DP<9>")
	)
	(segment
		(start 122.214132 -289.161474)
		(end 122.214386 -289.161474)
		(width 0.1143)
		(layer "In4.Cu")
		(net "P5E_CPU1_P3_RX_DP<9>")
	)
	(segment
		(start 122.230642 -291.420296)
		(end 122.228864 -291.41928)
		(width 0.1143)
		(layer "In4.Cu")
		(net "P5E_CPU1_P3_RX_DP<9>")
	)
	(segment
		(start 140.847572 -336.904838)
		(end 139.419076 -328.952098)
		(width 0.14224)
		(layer "In4.Cu")
		(net "P5E_CPU1_P3_RX_DP<9>")
	)
	(segment
		(start 122.248676 -294.000428)
		(end 122.249692 -293.99992)
		(width 0.1143)
		(layer "In4.Cu")
		(net "P5E_CPU1_P3_RX_DP<9>")
	)
	(segment
		(start 122.085608 -296.456608)
		(end 122.085608 -296.42816)
		(width 0.1143)
		(layer "In4.Cu")
		(net "P5E_CPU1_P3_RX_DP<9>")
	)
	(segment
		(start 126.40056 -384.086862)
		(end 126.40056 -382.48844)
		(width 0.14224)
		(layer "In4.Cu")
		(net "P5E_CPU1_P3_RX_DP<9>")
	)
	(segment
		(start 122.232166 -294.011096)
		(end 122.233436 -294.010334)
		(width 0.1143)
		(layer "In4.Cu")
		(net "P5E_CPU1_P3_RX_DP<9>")
	)
	(segment
		(start 122.227086 -291.418264)
		(end 122.224292 -291.41674)
		(width 0.1143)
		(layer "In4.Cu")
		(net "P5E_CPU1_P3_RX_DP<9>")
	)
	(segment
		(start 122.224292 -289.155632)
		(end 122.227086 -289.154108)
		(width 0.1143)
		(layer "In4.Cu")
		(net "P5E_CPU1_P3_RX_DP<9>")
	)
	(segment
		(start 134.916418 -315.992256)
		(end 132.808218 -312.048144)
		(width 0.14224)
		(layer "In4.Cu")
		(net "P5E_CPU1_P3_RX_DP<9>")
	)
	(segment
		(start 122.993404 -299.82795)
		(end 122.09526 -297.660314)
		(width 0.14224)
		(layer "In4.Cu")
		(net "P5E_CPU1_P3_RX_DP<9>")
	)
	(segment
		(start 122.214386 -289.161474)
		(end 122.21464 -289.16122)
		(width 0.1143)
		(layer "In4.Cu")
		(net "P5E_CPU1_P3_RX_DP<9>")
	)
	(segment
		(start 126.135638 -384.3528)
		(end 126.40056 -384.086862)
		(width 0.14224)
		(layer "In4.Cu")
		(net "P5E_CPU1_P3_RX_DP<9>")
	)
	(segment
		(start 122.207274 -289.165284)
		(end 122.214132 -289.161474)
		(width 0.1143)
		(layer "In4.Cu")
		(net "P5E_CPU1_P3_RX_DP<9>")
	)
	(segment
		(start 122.216418 -289.160204)
		(end 122.217688 -289.159442)
		(width 0.1143)
		(layer "In4.Cu")
		(net "P5E_CPU1_P3_RX_DP<9>")
	)
	(segment
		(start 122.233182 -291.42182)
		(end 122.232166 -291.421312)
		(width 0.1143)
		(layer "In4.Cu")
		(net "P5E_CPU1_P3_RX_DP<9>")
	)
	(segment
		(start 122.241056 -291.4269)
		(end 122.235214 -291.422836)
		(width 0.1143)
		(layer "In4.Cu")
		(net "P5E_CPU1_P3_RX_DP<9>")
	)
	(segment
		(start 122.196098 -294.032686)
		(end 122.212354 -294.023288)
		(width 0.1143)
		(layer "In4.Cu")
		(net "P5E_CPU1_P3_RX_DP<9>")
	)
	(segment
		(start 126.13259 -384.731006)
		(end 126.135638 -384.3528)
		(width 0.14224)
		(layer "In4.Cu")
		(net "P5E_CPU1_P3_RX_DP<9>")
	)
	(segment
		(start 122.510296 -295.14673)
		(end 122.510296 -295.146222)
		(width 0.1143)
		(layer "In4.Cu")
		(net "P5E_CPU1_P3_RX_DP<9>")
	)
	(segment
		(start 126.091188 -386.003292)
		(end 126.186184 -385.649216)
		(width 0.14224)
		(layer "In4.Cu")
		(net "P5E_CPU1_P3_RX_DP<9>")
	)
	(segment
		(start 122.267472 -291.44341)
		(end 122.25528 -291.436298)
		(width 0.1143)
		(layer "In4.Cu")
		(net "P5E_CPU1_P3_RX_DP<9>")
	)
	(segment
		(start 122.228864 -293.039292)
		(end 122.227848 -293.038784)
		(width 0.1143)
		(layer "In4.Cu")
		(net "P5E_CPU1_P3_RX_DP<9>")
	)
	(segment
		(start 131.348988 -364.71098)
		(end 139.247118 -359.433368)
		(width 0.14224)
		(layer "In4.Cu")
		(net "P5E_CPU1_P3_RX_DP<9>")
	)
	(segment
		(start 122.226578 -293.038022)
		(end 122.225562 -293.037514)
		(width 0.1143)
		(layer "In4.Cu")
		(net "P5E_CPU1_P3_RX_DP<9>")
	)
	(segment
		(start 123.056904 -287.856422)
		(end 123.354846 -287.856422)
		(width 0.1143)
		(layer "In4.Cu")
		(net "P5E_CPU1_P3_RX_DP<9>")
	)
	(segment
		(start 122.224292 -291.41674)
		(end 122.22353 -291.416232)
		(width 0.1143)
		(layer "In4.Cu")
		(net "P5E_CPU1_P3_RX_DP<9>")
	)
	(segment
		(start 122.230642 -293.040054)
		(end 122.230388 -293.040308)
		(width 0.1143)
		(layer "In4.Cu")
		(net "P5E_CPU1_P3_RX_DP<9>")
	)
	(segment
		(start 121.757694 -290.608766)
		(end 121.727214 -290.590986)
		(width 0.1143)
		(layer "In4.Cu")
		(net "P5E_CPU1_P3_RX_DP<9>")
	)
	(segment
		(start 122.228864 -294.013128)
		(end 122.230388 -294.012112)
		(width 0.1143)
		(layer "In4.Cu")
		(net "P5E_CPU1_P3_RX_DP<9>")
	)
	(segment
		(start 122.228864 -289.153092)
		(end 122.234198 -289.149536)
		(width 0.1143)
		(layer "In4.Cu")
		(net "P5E_CPU1_P3_RX_DP<9>")
	)
	(segment
		(start 122.204734 -292.407086)
		(end 122.20829 -292.4048)
		(width 0.1143)
		(layer "In4.Cu")
		(net "P5E_CPU1_P3_RX_DP<9>")
	)
	(segment
		(start 122.246898 -292.383972)
		(end 122.266456 -292.372796)
		(width 0.1143)
		(layer "In4.Cu")
		(net "P5E_CPU1_P3_RX_DP<9>")
	)
	(segment
		(start 122.228864 -291.41928)
		(end 122.227848 -291.418772)
		(width 0.1143)
		(layer "In4.Cu")
		(net "P5E_CPU1_P3_RX_DP<9>")
	)
	(segment
		(start 122.239024 -293.045896)
		(end 122.230642 -293.040054)
		(width 0.1143)
		(layer "In4.Cu")
		(net "P5E_CPU1_P3_RX_DP<9>")
	)
	(segment
		(start 122.250454 -293.999412)
		(end 122.264424 -293.991284)
		(width 0.1143)
		(layer "In4.Cu")
		(net "P5E_CPU1_P3_RX_DP<9>")
	)
	(segment
		(start 123.93168 -301.232062)
		(end 122.993404 -299.82795)
		(width 0.14224)
		(layer "In4.Cu")
		(net "P5E_CPU1_P3_RX_DP<9>")
	)
	(segment
		(start 122.227086 -289.154108)
		(end 122.227848 -289.1536)
		(width 0.1143)
		(layer "In4.Cu")
		(net "P5E_CPU1_P3_RX_DP<9>")
	)
	(segment
		(start 139.419076 -328.952098)
		(end 134.916418 -315.992256)
		(width 0.14224)
		(layer "In4.Cu")
		(net "P5E_CPU1_P3_RX_DP<9>")
	)
	(segment
		(start 122.085608 -297.611546)
		(end 122.085608 -296.456608)
		(width 0.14224)
		(layer "In4.Cu")
		(net "P5E_CPU1_P3_RX_DP<9>")
	)
	(segment
		(start 122.227848 -289.1536)
		(end 122.228864 -289.153092)
		(width 0.1143)
		(layer "In4.Cu")
		(net "P5E_CPU1_P3_RX_DP<9>")
	)
	(arc
		(start 122.510042 -288.666174)
		(mid 122.551301 -288.495317)
		(end 122.665998 -288.362136)
		(width 0.1143)
		(layer "In4.Cu")
		(net "P5E_CPU1_P3_RX_DP<9>")
	)
	(arc
		(start 122.048778 -289.470846)
		(mid 122.08989 -289.300214)
		(end 122.204226 -289.167062)
		(width 0.1143)
		(layer "In4.Cu")
		(net "P5E_CPU1_P3_RX_DP<9>")
	)
	(arc
		(start 121.727214 -290.590986)
		(mid 121.570237 -290.286186)
		(end 121.727214 -289.981386)
		(width 0.1143)
		(layer "In4.Cu")
		(net "P5E_CPU1_P3_RX_DP<9>")
	)
	(arc
		(start 122.195844 -293.020242)
		(mid 122.040017 -292.716204)
		(end 122.195844 -292.412166)
		(width 0.1143)
		(layer "In4.Cu")
		(net "P5E_CPU1_P3_RX_DP<9>")
	)
	(arc
		(start 122.039888 -295.956228)
		(mid 122.084476 -295.786963)
		(end 122.195844 -295.651936)
		(width 0.1143)
		(layer "In4.Cu")
		(net "P5E_CPU1_P3_RX_DP<9>")
	)
	(arc
		(start 129.225294 -367.72596)
		(mid 130.006525 -366.020809)
		(end 131.348988 -364.71098)
		(width 0.14224)
		(layer "In4.Cu")
		(net "P5E_CPU1_P3_RX_DP<9>")
	)
	(arc
		(start 122.266456 -292.372796)
		(mid 122.510309 -291.908357)
		(end 122.267472 -291.44341)
		(width 0.1143)
		(layer "In4.Cu")
		(net "P5E_CPU1_P3_RX_DP<9>")
	)
	(arc
		(start 122.09526 -297.660314)
		(mid 122.088048 -297.636404)
		(end 122.085608 -297.611546)
		(width 0.14224)
		(layer "In4.Cu")
		(net "P5E_CPU1_P3_RX_DP<9>")
	)
	(arc
		(start 139.247118 -359.433368)
		(mid 140.422346 -358.136455)
		(end 140.847572 -356.438708)
		(width 0.14224)
		(layer "In4.Cu")
		(net "P5E_CPU1_P3_RX_DP<9>")
	)
	(arc
		(start 122.268234 -295.609772)
		(mid 122.446077 -295.40795)
		(end 122.510296 -295.14673)
		(width 0.1143)
		(layer "In4.Cu")
		(net "P5E_CPU1_P3_RX_DP<9>")
	)
	(arc
		(start 122.736864 -288.320988)
		(mid 122.888851 -288.16448)
		(end 122.97029 -287.962086)
		(width 0.1143)
		(layer "In4.Cu")
		(net "P5E_CPU1_P3_RX_DP<9>")
	)
	(arc
		(start 126.537974 -373.983504)
		(mid 126.679035 -373.193178)
		(end 127.12065 -372.52275)
		(width 0.14224)
		(layer "In4.Cu")
		(net "P5E_CPU1_P3_RX_DP<9>")
	)
	(arc
		(start 127.837946 -371.805454)
		(mid 128.243795 -371.272054)
		(end 128.492758 -370.649754)
		(width 0.14224)
		(layer "In4.Cu")
		(net "P5E_CPU1_P3_RX_DP<9>")
	)
	(arc
		(start 122.040142 -291.084508)
		(mid 121.972997 -290.828756)
		(end 121.79681 -290.631626)
		(width 0.1143)
		(layer "In4.Cu")
		(net "P5E_CPU1_P3_RX_DP<9>")
	)
	(arc
		(start 126.646432 -378.981716)
		(mid 126.65714 -378.747904)
		(end 126.656592 -378.513848)
		(width 0.14224)
		(layer "In4.Cu")
		(net "P5E_CPU1_P3_RX_DP<9>")
	)
	(arc
		(start 122.225308 -294.657526)
		(mid 122.041362 -294.353071)
		(end 122.196098 -294.032686)
		(width 0.1143)
		(layer "In4.Cu")
		(net "P5E_CPU1_P3_RX_DP<9>")
	)
	(arc
		(start 122.267218 -289.130232)
		(mid 122.445883 -288.928119)
		(end 122.510296 -288.666174)
		(width 0.1143)
		(layer "In4.Cu")
		(net "P5E_CPU1_P3_RX_DP<9>")
	)
	(arc
		(start 122.510296 -295.146222)
		(mid 122.445781 -294.884003)
		(end 122.266964 -294.681656)
		(width 0.1143)
		(layer "In4.Cu")
		(net "P5E_CPU1_P3_RX_DP<9>")
	)
	(arc
		(start 122.221244 -291.414962)
		(mid 122.09023 -291.271928)
		(end 122.040142 -291.084508)
		(width 0.1143)
		(layer "In4.Cu")
		(net "P5E_CPU1_P3_RX_DP<9>")
	)
	(arc
		(start 122.264424 -293.991284)
		(mid 122.508706 -293.526061)
		(end 122.264678 -293.060628)
		(width 0.1143)
		(layer "In4.Cu")
		(net "P5E_CPU1_P3_RX_DP<9>")
	)
	(arc
		(start 122.97029 -287.962086)
		(mid 122.972313 -287.950676)
		(end 122.9741 -287.939226)
		(width 0.1143)
		(layer "In4.Cu")
		(net "P5E_CPU1_P3_RX_DP<9>")
	)
	(arc
		(start 121.770902 -289.955986)
		(mid 121.974499 -289.75044)
		(end 122.048778 -289.470846)
		(width 0.1143)
		(layer "In4.Cu")
		(net "P5E_CPU1_P3_RX_DP<9>")
	)
	(segment
		(start 124.370592 -386.003292)
		(end 124.891292 -386.003292)
		(width 0.127)
		(layer "F.Cu")
		(net "P5E_CPU1_P3_RX_DP<8>")
	)
	(segment
		(start 120.067832 -289.210242)
		(end 120.534684 -289.47618)
		(width 0.12954)
		(layer "F.Cu")
		(net "P5E_CPU1_P3_RX_DP<8>")
	)
	(segment
		(start 123.111514 -301.703486)
		(end 122.10415 -300.195742)
		(width 0.14224)
		(layer "In4.Cu")
		(net "P5E_CPU1_P3_RX_DP<8>")
	)
	(segment
		(start 125.24867 -385.460494)
		(end 125.24867 -385.046982)
		(width 0.14224)
		(layer "In4.Cu")
		(net "P5E_CPU1_P3_RX_DP<8>")
	)
	(segment
		(start 121.28754 -293.038784)
		(end 121.25706 -293.021004)
		(width 0.1143)
		(layer "In4.Cu")
		(net "P5E_CPU1_P3_RX_DP<8>")
	)
	(segment
		(start 121.25706 -294.031416)
		(end 121.28754 -294.013636)
		(width 0.1143)
		(layer "In4.Cu")
		(net "P5E_CPU1_P3_RX_DP<8>")
	)
	(segment
		(start 126.29515 -371.85219)
		(end 126.803404 -371.343936)
		(width 0.14224)
		(layer "In4.Cu")
		(net "P5E_CPU1_P3_RX_DP<8>")
	)
	(segment
		(start 121.100088 -296.389044)
		(end 121.100088 -295.956228)
		(width 0.1143)
		(layer "In4.Cu")
		(net "P5E_CPU1_P3_RX_DP<8>")
	)
	(segment
		(start 120.849898 -290.627562)
		(end 120.849136 -290.627054)
		(width 0.1143)
		(layer "In4.Cu")
		(net "P5E_CPU1_P3_RX_DP<8>")
	)
	(segment
		(start 120.820434 -290.61029)
		(end 120.818656 -290.609274)
		(width 0.1143)
		(layer "In4.Cu")
		(net "P5E_CPU1_P3_RX_DP<8>")
	)
	(segment
		(start 120.81764 -290.608766)
		(end 120.816878 -290.608258)
		(width 0.1143)
		(layer "In4.Cu")
		(net "P5E_CPU1_P3_RX_DP<8>")
	)
	(segment
		(start 125.24867 -385.046982)
		(end 124.932694 -384.731006)
		(width 0.14224)
		(layer "In4.Cu")
		(net "P5E_CPU1_P3_RX_DP<8>")
	)
	(segment
		(start 121.145808 -297.688762)
		(end 121.145808 -296.463212)
		(width 0.14224)
		(layer "In4.Cu")
		(net "P5E_CPU1_P3_RX_DP<8>")
	)
	(segment
		(start 120.822974 -290.611814)
		(end 120.821958 -290.611306)
		(width 0.1143)
		(layer "In4.Cu")
		(net "P5E_CPU1_P3_RX_DP<8>")
	)
	(segment
		(start 124.932694 -384.731006)
		(end 124.935742 -384.352546)
		(width 0.14224)
		(layer "In4.Cu")
		(net "P5E_CPU1_P3_RX_DP<8>")
	)
	(segment
		(start 121.28754 -292.393624)
		(end 121.326656 -292.370764)
		(width 0.1143)
		(layer "In4.Cu")
		(net "P5E_CPU1_P3_RX_DP<8>")
	)
	(segment
		(start 125.160532 -385.548632)
		(end 125.24867 -385.460494)
		(width 0.14224)
		(layer "In4.Cu")
		(net "P5E_CPU1_P3_RX_DP<8>")
	)
	(segment
		(start 130.833368 -363.930692)
		(end 138.357102 -358.90327)
		(width 0.14224)
		(layer "In4.Cu")
		(net "P5E_CPU1_P3_RX_DP<8>")
	)
	(segment
		(start 125.240542 -382.176274)
		(end 125.481334 -378.739654)
		(width 0.14224)
		(layer "In4.Cu")
		(net "P5E_CPU1_P3_RX_DP<8>")
	)
	(segment
		(start 120.166892 -289.54603)
		(end 120.236742 -289.47618)
		(width 0.1143)
		(layer "In4.Cu")
		(net "P5E_CPU1_P3_RX_DP<8>")
	)
	(segment
		(start 139.915392 -337.007454)
		(end 138.53541 -329.323954)
		(width 0.14224)
		(layer "In4.Cu")
		(net "P5E_CPU1_P3_RX_DP<8>")
	)
	(segment
		(start 122.10415 -300.195742)
		(end 121.219468 -298.059094)
		(width 0.14224)
		(layer "In4.Cu")
		(net "P5E_CPU1_P3_RX_DP<8>")
	)
	(segment
		(start 121.25706 -295.651428)
		(end 121.326656 -295.610788)
		(width 0.1143)
		(layer "In4.Cu")
		(net "P5E_CPU1_P3_RX_DP<8>")
	)
	(segment
		(start 124.891292 -386.003292)
		(end 124.986288 -385.649216)
		(width 0.14224)
		(layer "In4.Cu")
		(net "P5E_CPU1_P3_RX_DP<8>")
	)
	(segment
		(start 120.236742 -289.47618)
		(end 120.534684 -289.47618)
		(width 0.1143)
		(layer "In4.Cu")
		(net "P5E_CPU1_P3_RX_DP<8>")
	)
	(segment
		(start 121.326656 -291.441632)
		(end 121.28754 -291.418772)
		(width 0.1143)
		(layer "In4.Cu")
		(net "P5E_CPU1_P3_RX_DP<8>")
	)
	(segment
		(start 131.79806 -312.287158)
		(end 123.111514 -301.703486)
		(width 0.14224)
		(layer "In4.Cu")
		(net "P5E_CPU1_P3_RX_DP<8>")
	)
	(segment
		(start 121.28754 -294.013636)
		(end 121.326656 -293.990776)
		(width 0.1143)
		(layer "In4.Cu")
		(net "P5E_CPU1_P3_RX_DP<8>")
	)
	(segment
		(start 120.818656 -290.609274)
		(end 120.81764 -290.608766)
		(width 0.1143)
		(layer "In4.Cu")
		(net "P5E_CPU1_P3_RX_DP<8>")
	)
	(segment
		(start 124.935742 -384.352546)
		(end 125.240542 -384.047746)
		(width 0.14224)
		(layer "In4.Cu")
		(net "P5E_CPU1_P3_RX_DP<8>")
	)
	(segment
		(start 120.821958 -290.611306)
		(end 120.820434 -290.61029)
		(width 0.1143)
		(layer "In4.Cu")
		(net "P5E_CPU1_P3_RX_DP<8>")
	)
	(segment
		(start 138.53541 -329.323954)
		(end 134.140448 -316.670182)
		(width 0.14224)
		(layer "In4.Cu")
		(net "P5E_CPU1_P3_RX_DP<8>")
	)
	(segment
		(start 120.849136 -290.627054)
		(end 120.824498 -290.61283)
		(width 0.1143)
		(layer "In4.Cu")
		(net "P5E_CPU1_P3_RX_DP<8>")
	)
	(segment
		(start 125.240542 -384.047746)
		(end 125.240542 -382.176274)
		(width 0.14224)
		(layer "In4.Cu")
		(net "P5E_CPU1_P3_RX_DP<8>")
	)
	(segment
		(start 120.350534 -289.800538)
		(end 120.34774 -289.79876)
		(width 0.1143)
		(layer "In4.Cu")
		(net "P5E_CPU1_P3_RX_DP<8>")
	)
	(segment
		(start 124.986288 -385.649216)
		(end 125.160532 -385.548632)
		(width 0.14224)
		(layer "In4.Cu")
		(net "P5E_CPU1_P3_RX_DP<8>")
	)
	(segment
		(start 120.346724 -289.798252)
		(end 120.31599 -289.780472)
		(width 0.1143)
		(layer "In4.Cu")
		(net "P5E_CPU1_P3_RX_DP<8>")
	)
	(segment
		(start 139.915392 -355.987604)
		(end 139.915392 -337.007454)
		(width 0.14224)
		(layer "In4.Cu")
		(net "P5E_CPU1_P3_RX_DP<8>")
	)
	(segment
		(start 121.25706 -292.411404)
		(end 121.28754 -292.393624)
		(width 0.1143)
		(layer "In4.Cu")
		(net "P5E_CPU1_P3_RX_DP<8>")
	)
	(segment
		(start 121.145808 -296.434764)
		(end 121.100088 -296.389044)
		(width 0.1143)
		(layer "In4.Cu")
		(net "P5E_CPU1_P3_RX_DP<8>")
	)
	(segment
		(start 125.509528 -377.44908)
		(end 125.420374 -374.044972)
		(width 0.14224)
		(layer "In4.Cu")
		(net "P5E_CPU1_P3_RX_DP<8>")
	)
	(segment
		(start 134.140448 -316.670182)
		(end 131.79806 -312.287158)
		(width 0.14224)
		(layer "In4.Cu")
		(net "P5E_CPU1_P3_RX_DP<8>")
	)
	(segment
		(start 121.326656 -294.681656)
		(end 121.28754 -294.658796)
		(width 0.1143)
		(layer "In4.Cu")
		(net "P5E_CPU1_P3_RX_DP<8>")
	)
	(segment
		(start 121.145808 -296.463212)
		(end 121.145808 -296.434764)
		(width 0.1143)
		(layer "In4.Cu")
		(net "P5E_CPU1_P3_RX_DP<8>")
	)
	(segment
		(start 121.326656 -293.061644)
		(end 121.28754 -293.038784)
		(width 0.1143)
		(layer "In4.Cu")
		(net "P5E_CPU1_P3_RX_DP<8>")
	)
	(segment
		(start 120.824498 -290.61283)
		(end 120.822974 -290.611814)
		(width 0.1143)
		(layer "In4.Cu")
		(net "P5E_CPU1_P3_RX_DP<8>")
	)
	(segment
		(start 121.28754 -294.658796)
		(end 121.25706 -294.641016)
		(width 0.1143)
		(layer "In4.Cu")
		(net "P5E_CPU1_P3_RX_DP<8>")
	)
	(segment
		(start 120.856756 -290.631626)
		(end 120.849898 -290.627562)
		(width 0.1143)
		(layer "In4.Cu")
		(net "P5E_CPU1_P3_RX_DP<8>")
	)
	(segment
		(start 121.28754 -291.418772)
		(end 121.25706 -291.400992)
		(width 0.1143)
		(layer "In4.Cu")
		(net "P5E_CPU1_P3_RX_DP<8>")
	)
	(segment
		(start 120.34774 -289.79876)
		(end 120.346724 -289.798252)
		(width 0.1143)
		(layer "In4.Cu")
		(net "P5E_CPU1_P3_RX_DP<8>")
	)
	(segment
		(start 127.439166 -370.221764)
		(end 128.010412 -367.93932)
		(width 0.14224)
		(layer "In4.Cu")
		(net "P5E_CPU1_P3_RX_DP<8>")
	)
	(arc
		(start 121.25706 -294.641016)
		(mid 121.100083 -294.336216)
		(end 121.25706 -294.031416)
		(width 0.1143)
		(layer "In4.Cu")
		(net "P5E_CPU1_P3_RX_DP<8>")
	)
	(arc
		(start 121.25706 -293.021004)
		(mid 121.100083 -292.716204)
		(end 121.25706 -292.411404)
		(width 0.1143)
		(layer "In4.Cu")
		(net "P5E_CPU1_P3_RX_DP<8>")
	)
	(arc
		(start 120.816878 -290.608258)
		(mid 120.679476 -290.471425)
		(end 120.629172 -290.284154)
		(width 0.1143)
		(layer "In4.Cu")
		(net "P5E_CPU1_P3_RX_DP<8>")
	)
	(arc
		(start 120.31599 -289.780472)
		(mid 120.218855 -289.677603)
		(end 120.166892 -289.54603)
		(width 0.1143)
		(layer "In4.Cu")
		(net "P5E_CPU1_P3_RX_DP<8>")
	)
	(arc
		(start 120.629172 -290.284154)
		(mid 120.554533 -290.005077)
		(end 120.350534 -289.800538)
		(width 0.1143)
		(layer "In4.Cu")
		(net "P5E_CPU1_P3_RX_DP<8>")
	)
	(arc
		(start 121.326656 -295.610788)
		(mid 121.569983 -295.146222)
		(end 121.326656 -294.681656)
		(width 0.1143)
		(layer "In4.Cu")
		(net "P5E_CPU1_P3_RX_DP<8>")
	)
	(arc
		(start 121.100088 -291.096192)
		(mid 121.035573 -290.833973)
		(end 120.856756 -290.631626)
		(width 0.1143)
		(layer "In4.Cu")
		(net "P5E_CPU1_P3_RX_DP<8>")
	)
	(arc
		(start 128.010412 -367.93932)
		(mid 129.04869 -365.672201)
		(end 130.833368 -363.930692)
		(width 0.14224)
		(layer "In4.Cu")
		(net "P5E_CPU1_P3_RX_DP<8>")
	)
	(arc
		(start 121.326656 -293.990776)
		(mid 121.569983 -293.52621)
		(end 121.326656 -293.061644)
		(width 0.1143)
		(layer "In4.Cu")
		(net "P5E_CPU1_P3_RX_DP<8>")
	)
	(arc
		(start 138.357102 -358.90327)
		(mid 139.50142 -357.640597)
		(end 139.915392 -355.987604)
		(width 0.14224)
		(layer "In4.Cu")
		(net "P5E_CPU1_P3_RX_DP<8>")
	)
	(arc
		(start 125.481334 -378.739654)
		(mid 125.510956 -378.094706)
		(end 125.509528 -377.44908)
		(width 0.14224)
		(layer "In4.Cu")
		(net "P5E_CPU1_P3_RX_DP<8>")
	)
	(arc
		(start 121.100088 -295.956228)
		(mid 121.141637 -295.784806)
		(end 121.25706 -295.651428)
		(width 0.1143)
		(layer "In4.Cu")
		(net "P5E_CPU1_P3_RX_DP<8>")
	)
	(arc
		(start 125.420374 -374.044972)
		(mid 125.632171 -372.858581)
		(end 126.29515 -371.85219)
		(width 0.14224)
		(layer "In4.Cu")
		(net "P5E_CPU1_P3_RX_DP<8>")
	)
	(arc
		(start 121.326656 -292.370764)
		(mid 121.569983 -291.906198)
		(end 121.326656 -291.441632)
		(width 0.1143)
		(layer "In4.Cu")
		(net "P5E_CPU1_P3_RX_DP<8>")
	)
	(arc
		(start 121.25706 -291.400992)
		(mid 121.141633 -291.267616)
		(end 121.100088 -291.096192)
		(width 0.1143)
		(layer "In4.Cu")
		(net "P5E_CPU1_P3_RX_DP<8>")
	)
	(arc
		(start 121.219468 -298.059094)
		(mid 121.1644 -297.877555)
		(end 121.145808 -297.688762)
		(width 0.14224)
		(layer "In4.Cu")
		(net "P5E_CPU1_P3_RX_DP<8>")
	)
	(arc
		(start 126.803404 -371.343936)
		(mid 127.197528 -370.826043)
		(end 127.439166 -370.221764)
		(width 0.14224)
		(layer "In4.Cu")
		(net "P5E_CPU1_P3_RX_DP<8>")
	)
	(segment
		(start 123.170442 -386.003292)
		(end 123.691142 -386.003292)
		(width 0.127)
		(layer "F.Cu")
		(net "P5E_CPU1_P3_RX_DP<7>")
	)
	(segment
		(start 120.067832 -290.830254)
		(end 120.534684 -291.096192)
		(width 0.12954)
		(layer "F.Cu")
		(net "P5E_CPU1_P3_RX_DP<7>")
	)
	(segment
		(start 120.34774 -293.038784)
		(end 120.31599 -293.020496)
		(width 0.1143)
		(layer "In4.Cu")
		(net "P5E_CPU1_P3_RX_DP<7>")
	)
	(segment
		(start 123.964192 -373.036592)
		(end 123.81992 -372.89232)
		(width 0.14224)
		(layer "In4.Cu")
		(net "P5E_CPU1_P3_RX_DP<7>")
	)
	(segment
		(start 124.040392 -382.282446)
		(end 124.354082 -377.804934)
		(width 0.14224)
		(layer "In4.Cu")
		(net "P5E_CPU1_P3_RX_DP<7>")
	)
	(segment
		(start 138.983212 -355.28885)
		(end 138.983212 -337.09102)
		(width 0.14224)
		(layer "In4.Cu")
		(net "P5E_CPU1_P3_RX_DP<7>")
	)
	(segment
		(start 133.2865 -317.053976)
		(end 131.019804 -312.813192)
		(width 0.14224)
		(layer "In4.Cu")
		(net "P5E_CPU1_P3_RX_DP<7>")
	)
	(segment
		(start 120.34774 -295.633648)
		(end 120.348248 -295.633648)
		(width 0.1143)
		(layer "In4.Cu")
		(net "P5E_CPU1_P3_RX_DP<7>")
	)
	(segment
		(start 131.019804 -312.813192)
		(end 122.365516 -302.26762)
		(width 0.14224)
		(layer "In4.Cu")
		(net "P5E_CPU1_P3_RX_DP<7>")
	)
	(segment
		(start 137.586212 -329.433682)
		(end 133.2865 -317.053976)
		(width 0.14224)
		(layer "In4.Cu")
		(net "P5E_CPU1_P3_RX_DP<7>")
	)
	(segment
		(start 120.3452 -294.01516)
		(end 120.345962 -294.014652)
		(width 0.1143)
		(layer "In4.Cu")
		(net "P5E_CPU1_P3_RX_DP<7>")
	)
	(segment
		(start 120.348248 -293.038784)
		(end 120.34774 -293.038784)
		(width 0.1143)
		(layer "In4.Cu")
		(net "P5E_CPU1_P3_RX_DP<7>")
	)
	(segment
		(start 120.34139 -294.017192)
		(end 120.343422 -294.016176)
		(width 0.1143)
		(layer "In4.Cu")
		(net "P5E_CPU1_P3_RX_DP<7>")
	)
	(segment
		(start 120.34774 -291.418772)
		(end 120.31599 -291.400484)
		(width 0.1143)
		(layer "In4.Cu")
		(net "P5E_CPU1_P3_RX_DP<7>")
	)
	(segment
		(start 120.31599 -294.031924)
		(end 120.34139 -294.017192)
		(width 0.1143)
		(layer "In4.Cu")
		(net "P5E_CPU1_P3_RX_DP<7>")
	)
	(segment
		(start 123.691142 -386.003292)
		(end 123.786138 -385.649216)
		(width 0.14224)
		(layer "In4.Cu")
		(net "P5E_CPU1_P3_RX_DP<7>")
	)
	(segment
		(start 123.539504 -369.549934)
		(end 127.897382 -364.742222)
		(width 0.14224)
		(layer "In4.Cu")
		(net "P5E_CPU1_P3_RX_DP<7>")
	)
	(segment
		(start 120.205754 -296.462704)
		(end 120.205754 -296.434256)
		(width 0.1143)
		(layer "In4.Cu")
		(net "P5E_CPU1_P3_RX_DP<7>")
	)
	(segment
		(start 137.653522 -329.689968)
		(end 137.586212 -329.433682)
		(width 0.14224)
		(layer "In4.Cu")
		(net "P5E_CPU1_P3_RX_DP<7>")
	)
	(segment
		(start 120.205754 -297.960796)
		(end 120.205754 -296.462704)
		(width 0.14224)
		(layer "In4.Cu")
		(net "P5E_CPU1_P3_RX_DP<7>")
	)
	(segment
		(start 120.205754 -296.434256)
		(end 120.160034 -296.388536)
		(width 0.1143)
		(layer "In4.Cu")
		(net "P5E_CPU1_P3_RX_DP<7>")
	)
	(segment
		(start 121.287032 -300.670722)
		(end 120.243092 -298.14901)
		(width 0.14224)
		(layer "In4.Cu")
		(net "P5E_CPU1_P3_RX_DP<7>")
	)
	(segment
		(start 120.166892 -291.166042)
		(end 120.236742 -291.096192)
		(width 0.1143)
		(layer "In4.Cu")
		(net "P5E_CPU1_P3_RX_DP<7>")
	)
	(segment
		(start 123.006612 -372.411752)
		(end 123.005342 -372.410482)
		(width 0.14224)
		(layer "In4.Cu")
		(net "P5E_CPU1_P3_RX_DP<7>")
	)
	(segment
		(start 120.34774 -294.013636)
		(end 120.348248 -294.013636)
		(width 0.1143)
		(layer "In4.Cu")
		(net "P5E_CPU1_P3_RX_DP<7>")
	)
	(segment
		(start 123.006866 -372.411752)
		(end 123.006612 -372.411752)
		(width 0.14224)
		(layer "In4.Cu")
		(net "P5E_CPU1_P3_RX_DP<7>")
	)
	(segment
		(start 124.04852 -385.046982)
		(end 123.732544 -384.731006)
		(width 0.14224)
		(layer "In4.Cu")
		(net "P5E_CPU1_P3_RX_DP<7>")
	)
	(segment
		(start 123.735592 -384.3528)
		(end 124.040392 -384.048254)
		(width 0.14224)
		(layer "In4.Cu")
		(net "P5E_CPU1_P3_RX_DP<7>")
	)
	(segment
		(start 124.374402 -376.872246)
		(end 124.293884 -373.803418)
		(width 0.14224)
		(layer "In4.Cu")
		(net "P5E_CPU1_P3_RX_DP<7>")
	)
	(segment
		(start 120.348248 -294.658796)
		(end 120.34774 -294.658796)
		(width 0.1143)
		(layer "In4.Cu")
		(net "P5E_CPU1_P3_RX_DP<7>")
	)
	(segment
		(start 129.62763 -363.249718)
		(end 137.561828 -357.94823)
		(width 0.14224)
		(layer "In4.Cu")
		(net "P5E_CPU1_P3_RX_DP<7>")
	)
	(segment
		(start 120.31599 -292.411912)
		(end 120.34774 -292.393624)
		(width 0.1143)
		(layer "In4.Cu")
		(net "P5E_CPU1_P3_RX_DP<7>")
	)
	(segment
		(start 123.960382 -385.548632)
		(end 124.04852 -385.460494)
		(width 0.14224)
		(layer "In4.Cu")
		(net "P5E_CPU1_P3_RX_DP<7>")
	)
	(segment
		(start 120.344184 -294.015668)
		(end 120.3452 -294.01516)
		(width 0.1143)
		(layer "In4.Cu")
		(net "P5E_CPU1_P3_RX_DP<7>")
	)
	(segment
		(start 120.34774 -294.658796)
		(end 120.31599 -294.640508)
		(width 0.1143)
		(layer "In4.Cu")
		(net "P5E_CPU1_P3_RX_DP<7>")
	)
	(segment
		(start 123.46686 -372.656354)
		(end 123.218956 -372.553738)
		(width 0.14224)
		(layer "In4.Cu")
		(net "P5E_CPU1_P3_RX_DP<7>")
	)
	(segment
		(start 120.343422 -294.016176)
		(end 120.344184 -294.015668)
		(width 0.1143)
		(layer "In4.Cu")
		(net "P5E_CPU1_P3_RX_DP<7>")
	)
	(segment
		(start 120.346978 -295.634156)
		(end 120.34774 -295.633648)
		(width 0.1143)
		(layer "In4.Cu")
		(net "P5E_CPU1_P3_RX_DP<7>")
	)
	(segment
		(start 120.160034 -296.388536)
		(end 120.160034 -295.869868)
		(width 0.1143)
		(layer "In4.Cu")
		(net "P5E_CPU1_P3_RX_DP<7>")
	)
	(segment
		(start 123.786138 -385.649216)
		(end 123.960382 -385.548632)
		(width 0.14224)
		(layer "In4.Cu")
		(net "P5E_CPU1_P3_RX_DP<7>")
	)
	(segment
		(start 124.040392 -384.048254)
		(end 124.040392 -382.282446)
		(width 0.14224)
		(layer "In4.Cu")
		(net "P5E_CPU1_P3_RX_DP<7>")
	)
	(segment
		(start 124.04852 -385.460494)
		(end 124.04852 -385.046982)
		(width 0.14224)
		(layer "In4.Cu")
		(net "P5E_CPU1_P3_RX_DP<7>")
	)
	(segment
		(start 120.236742 -291.096192)
		(end 120.534684 -291.096192)
		(width 0.1143)
		(layer "In4.Cu")
		(net "P5E_CPU1_P3_RX_DP<7>")
	)
	(segment
		(start 120.345962 -294.014652)
		(end 120.346978 -294.014144)
		(width 0.1143)
		(layer "In4.Cu")
		(net "P5E_CPU1_P3_RX_DP<7>")
	)
	(segment
		(start 138.983212 -337.09102)
		(end 137.653522 -329.689968)
		(width 0.14224)
		(layer "In4.Cu")
		(net "P5E_CPU1_P3_RX_DP<7>")
	)
	(segment
		(start 122.365516 -302.26762)
		(end 121.287032 -300.670722)
		(width 0.14224)
		(layer "In4.Cu")
		(net "P5E_CPU1_P3_RX_DP<7>")
	)
	(segment
		(start 120.31599 -295.651936)
		(end 120.346978 -295.634156)
		(width 0.1143)
		(layer "In4.Cu")
		(net "P5E_CPU1_P3_RX_DP<7>")
	)
	(segment
		(start 123.732544 -384.731006)
		(end 123.735592 -384.3528)
		(width 0.14224)
		(layer "In4.Cu")
		(net "P5E_CPU1_P3_RX_DP<7>")
	)
	(segment
		(start 120.346978 -294.014144)
		(end 120.34774 -294.013636)
		(width 0.1143)
		(layer "In4.Cu")
		(net "P5E_CPU1_P3_RX_DP<7>")
	)
	(arc
		(start 120.31599 -293.020496)
		(mid 120.160062 -292.716204)
		(end 120.31599 -292.411912)
		(width 0.1143)
		(layer "In4.Cu")
		(net "P5E_CPU1_P3_RX_DP<7>")
	)
	(arc
		(start 124.354082 -377.804934)
		(mid 124.375449 -377.338834)
		(end 124.374402 -376.872246)
		(width 0.14224)
		(layer "In4.Cu")
		(net "P5E_CPU1_P3_RX_DP<7>")
	)
	(arc
		(start 120.367806 -294.670734)
		(mid 120.358087 -294.664667)
		(end 120.348248 -294.658796)
		(width 0.1143)
		(layer "In4.Cu")
		(net "P5E_CPU1_P3_RX_DP<7>")
	)
	(arc
		(start 120.31599 -291.400484)
		(mid 120.218855 -291.297615)
		(end 120.166892 -291.166042)
		(width 0.1143)
		(layer "In4.Cu")
		(net "P5E_CPU1_P3_RX_DP<7>")
	)
	(arc
		(start 127.897382 -364.742222)
		(mid 128.716665 -363.942827)
		(end 129.62763 -363.249718)
		(width 0.14224)
		(layer "In4.Cu")
		(net "P5E_CPU1_P3_RX_DP<7>")
	)
	(arc
		(start 122.691398 -370.9289)
		(mid 123.066073 -370.209049)
		(end 123.539504 -369.549934)
		(width 0.14224)
		(layer "In4.Cu")
		(net "P5E_CPU1_P3_RX_DP<7>")
	)
	(arc
		(start 120.348248 -295.633648)
		(mid 120.628652 -295.157679)
		(end 120.367806 -294.670734)
		(width 0.1143)
		(layer "In4.Cu")
		(net "P5E_CPU1_P3_RX_DP<7>")
	)
	(arc
		(start 123.81992 -372.89232)
		(mid 123.654999 -372.756971)
		(end 123.46686 -372.656354)
		(width 0.14224)
		(layer "In4.Cu")
		(net "P5E_CPU1_P3_RX_DP<7>")
	)
	(arc
		(start 123.005342 -372.410482)
		(mid 122.628603 -371.716245)
		(end 122.691398 -370.9289)
		(width 0.14224)
		(layer "In4.Cu")
		(net "P5E_CPU1_P3_RX_DP<7>")
	)
	(arc
		(start 123.218956 -372.553738)
		(mid 123.105932 -372.493172)
		(end 123.006866 -372.411752)
		(width 0.14224)
		(layer "In4.Cu")
		(net "P5E_CPU1_P3_RX_DP<7>")
	)
	(arc
		(start 137.561828 -357.94823)
		(mid 138.605539 -356.796539)
		(end 138.983212 -355.28885)
		(width 0.14224)
		(layer "In4.Cu")
		(net "P5E_CPU1_P3_RX_DP<7>")
	)
	(arc
		(start 120.243092 -298.14901)
		(mid 120.215167 -298.05674)
		(end 120.205754 -297.960796)
		(width 0.14224)
		(layer "In4.Cu")
		(net "P5E_CPU1_P3_RX_DP<7>")
	)
	(arc
		(start 124.293884 -373.803418)
		(mid 124.202723 -373.388317)
		(end 123.964192 -373.036592)
		(width 0.14224)
		(layer "In4.Cu")
		(net "P5E_CPU1_P3_RX_DP<7>")
	)
	(arc
		(start 120.367806 -293.050722)
		(mid 120.358087 -293.044655)
		(end 120.348248 -293.038784)
		(width 0.1143)
		(layer "In4.Cu")
		(net "P5E_CPU1_P3_RX_DP<7>")
	)
	(arc
		(start 120.348248 -294.013636)
		(mid 120.628652 -293.537667)
		(end 120.367806 -293.050722)
		(width 0.1143)
		(layer "In4.Cu")
		(net "P5E_CPU1_P3_RX_DP<7>")
	)
	(arc
		(start 120.31599 -294.640508)
		(mid 120.160062 -294.336216)
		(end 120.31599 -294.031924)
		(width 0.1143)
		(layer "In4.Cu")
		(net "P5E_CPU1_P3_RX_DP<7>")
	)
	(arc
		(start 120.34774 -292.393624)
		(mid 120.628387 -291.906198)
		(end 120.34774 -291.418772)
		(width 0.1143)
		(layer "In4.Cu")
		(net "P5E_CPU1_P3_RX_DP<7>")
	)
	(arc
		(start 120.160034 -295.869868)
		(mid 120.218159 -295.746701)
		(end 120.31599 -295.651936)
		(width 0.1143)
		(layer "In4.Cu")
		(net "P5E_CPU1_P3_RX_DP<7>")
	)
	(segment
		(start 121.970546 -386.003292)
		(end 122.491246 -386.003292)
		(width 0.127)
		(layer "F.Cu")
		(net "P5E_CPU1_P3_RX_DP<6>")
	)
	(segment
		(start 120.067832 -287.590484)
		(end 120.534684 -287.856422)
		(width 0.12954)
		(layer "F.Cu")
		(net "P5E_CPU1_P3_RX_DP<6>")
	)
	(segment
		(start 122.848624 -385.046982)
		(end 122.532648 -384.731006)
		(width 0.14224)
		(layer "In4.Cu")
		(net "P5E_CPU1_P3_RX_DP<6>")
	)
	(segment
		(start 119.408702 -293.039292)
		(end 119.407686 -293.038784)
		(width 0.1143)
		(layer "In4.Cu")
		(net "P5E_CPU1_P3_RX_DP<6>")
	)
	(segment
		(start 119.410226 -294.012112)
		(end 119.414798 -294.009572)
		(width 0.1143)
		(layer "In4.Cu")
		(net "P5E_CPU1_P3_RX_DP<6>")
	)
	(segment
		(start 119.401082 -289.15741)
		(end 119.401844 -289.156902)
		(width 0.1143)
		(layer "In4.Cu")
		(net "P5E_CPU1_P3_RX_DP<6>")
	)
	(segment
		(start 119.410226 -292.3921)
		(end 119.414798 -292.38956)
		(width 0.1143)
		(layer "In4.Cu")
		(net "P5E_CPU1_P3_RX_DP<6>")
	)
	(segment
		(start 118.937532 -289.963606)
		(end 118.976648 -289.940746)
		(width 0.1143)
		(layer "In4.Cu")
		(net "P5E_CPU1_P3_RX_DP<6>")
	)
	(segment
		(start 119.439182 -291.43706)
		(end 119.414544 -291.422836)
		(width 0.1143)
		(layer "In4.Cu")
		(net "P5E_CPU1_P3_RX_DP<6>")
	)
	(segment
		(start 119.401844 -291.41547)
		(end 119.401082 -291.414962)
		(width 0.1143)
		(layer "In4.Cu")
		(net "P5E_CPU1_P3_RX_DP<6>")
	)
	(segment
		(start 137.397998 -333.542386)
		(end 137.397998 -333.542132)
		(width 0.14224)
		(layer "In4.Cu")
		(net "P5E_CPU1_P3_RX_DP<6>")
	)
	(segment
		(start 137.397998 -333.542132)
		(end 137.398252 -333.542132)
		(width 0.14224)
		(layer "In4.Cu")
		(net "P5E_CPU1_P3_RX_DP<6>")
	)
	(segment
		(start 119.446802 -294.681656)
		(end 119.410226 -294.66032)
		(width 0.1143)
		(layer "In4.Cu")
		(net "P5E_CPU1_P3_RX_DP<6>")
	)
	(segment
		(start 119.877586 -288.343848)
		(end 119.916702 -288.320988)
		(width 0.1143)
		(layer "In4.Cu")
		(net "P5E_CPU1_P3_RX_DP<6>")
	)
	(segment
		(start 119.401082 -292.397434)
		(end 119.401844 -292.396926)
		(width 0.1143)
		(layer "In4.Cu")
		(net "P5E_CPU1_P3_RX_DP<6>")
	)
	(segment
		(start 119.410226 -294.66032)
		(end 119.408702 -294.659304)
		(width 0.1143)
		(layer "In4.Cu")
		(net "P5E_CPU1_P3_RX_DP<6>")
	)
	(segment
		(start 119.446802 -291.441632)
		(end 119.439944 -291.437568)
		(width 0.1143)
		(layer "In4.Cu")
		(net "P5E_CPU1_P3_RX_DP<6>")
	)
	(segment
		(start 119.406924 -294.014144)
		(end 119.407686 -294.013636)
		(width 0.1143)
		(layer "In4.Cu")
		(net "P5E_CPU1_P3_RX_DP<6>")
	)
	(segment
		(start 119.406924 -291.418264)
		(end 119.40413 -291.41674)
		(width 0.1143)
		(layer "In4.Cu")
		(net "P5E_CPU1_P3_RX_DP<6>")
	)
	(segment
		(start 119.375682 -295.651936)
		(end 119.448072 -295.609772)
		(width 0.1143)
		(layer "In4.Cu")
		(net "P5E_CPU1_P3_RX_DP<6>")
	)
	(segment
		(start 119.398288 -292.398958)
		(end 119.399812 -292.398196)
		(width 0.1143)
		(layer "In4.Cu")
		(net "P5E_CPU1_P3_RX_DP<6>")
	)
	(segment
		(start 119.265446 -298.205652)
		(end 119.265446 -296.457116)
		(width 0.14224)
		(layer "In4.Cu")
		(net "P5E_CPU1_P3_RX_DP<6>")
	)
	(segment
		(start 119.412004 -291.421312)
		(end 119.41048 -291.420296)
		(width 0.1143)
		(layer "In4.Cu")
		(net "P5E_CPU1_P3_RX_DP<6>")
	)
	(segment
		(start 122.856244 -368.863118)
		(end 127.108458 -364.171484)
		(width 0.14224)
		(layer "In4.Cu")
		(net "P5E_CPU1_P3_RX_DP<6>")
	)
	(segment
		(start 119.398288 -294.01897)
		(end 119.399812 -294.018208)
		(width 0.1143)
		(layer "In4.Cu")
		(net "P5E_CPU1_P3_RX_DP<6>")
	)
	(segment
		(start 119.407686 -291.418772)
		(end 119.406924 -291.418264)
		(width 0.1143)
		(layer "In4.Cu")
		(net "P5E_CPU1_P3_RX_DP<6>")
	)
	(segment
		(start 119.40413 -289.155632)
		(end 119.406924 -289.154108)
		(width 0.1143)
		(layer "In4.Cu")
		(net "P5E_CPU1_P3_RX_DP<6>")
	)
	(segment
		(start 119.375936 -289.171888)
		(end 119.397526 -289.159442)
		(width 0.1143)
		(layer "In4.Cu")
		(net "P5E_CPU1_P3_RX_DP<6>")
	)
	(segment
		(start 119.265446 -296.457116)
		(end 119.265446 -296.428668)
		(width 0.1143)
		(layer "In4.Cu")
		(net "P5E_CPU1_P3_RX_DP<6>")
	)
	(segment
		(start 119.410226 -293.040308)
		(end 119.408702 -293.039292)
		(width 0.1143)
		(layer "In4.Cu")
		(net "P5E_CPU1_P3_RX_DP<6>")
	)
	(segment
		(start 119.845074 -288.362644)
		(end 119.877586 -288.343848)
		(width 0.1143)
		(layer "In4.Cu")
		(net "P5E_CPU1_P3_RX_DP<6>")
	)
	(segment
		(start 119.439944 -291.437568)
		(end 119.439182 -291.43706)
		(width 0.1143)
		(layer "In4.Cu")
		(net "P5E_CPU1_P3_RX_DP<6>")
	)
	(segment
		(start 119.399812 -289.158172)
		(end 119.401082 -289.15741)
		(width 0.1143)
		(layer "In4.Cu")
		(net "P5E_CPU1_P3_RX_DP<6>")
	)
	(segment
		(start 119.403368 -292.396164)
		(end 119.40413 -292.395656)
		(width 0.1143)
		(layer "In4.Cu")
		(net "P5E_CPU1_P3_RX_DP<6>")
	)
	(segment
		(start 120.236742 -287.856422)
		(end 120.534684 -287.856422)
		(width 0.1143)
		(layer "In4.Cu")
		(net "P5E_CPU1_P3_RX_DP<6>")
	)
	(segment
		(start 119.219726 -296.382948)
		(end 119.219726 -295.954958)
		(width 0.1143)
		(layer "In4.Cu")
		(net "P5E_CPU1_P3_RX_DP<6>")
	)
	(segment
		(start 119.403368 -289.15614)
		(end 119.40413 -289.155632)
		(width 0.1143)
		(layer "In4.Cu")
		(net "P5E_CPU1_P3_RX_DP<6>")
	)
	(segment
		(start 119.407686 -293.038784)
		(end 119.375936 -293.020496)
		(width 0.1143)
		(layer "In4.Cu")
		(net "P5E_CPU1_P3_RX_DP<6>")
	)
	(segment
		(start 119.275098 -298.25442)
		(end 119.275098 -298.254166)
		(width 0.14224)
		(layer "In4.Cu")
		(net "P5E_CPU1_P3_RX_DP<6>")
	)
	(segment
		(start 122.586242 -385.649216)
		(end 122.760486 -385.548632)
		(width 0.14224)
		(layer "In4.Cu")
		(net "P5E_CPU1_P3_RX_DP<6>")
	)
	(segment
		(start 119.399812 -294.018208)
		(end 119.401082 -294.017446)
		(width 0.1143)
		(layer "In4.Cu")
		(net "P5E_CPU1_P3_RX_DP<6>")
	)
	(segment
		(start 119.406924 -289.154108)
		(end 119.407686 -289.1536)
		(width 0.1143)
		(layer "In4.Cu")
		(net "P5E_CPU1_P3_RX_DP<6>")
	)
	(segment
		(start 119.401844 -289.156902)
		(end 119.403368 -289.15614)
		(width 0.1143)
		(layer "In4.Cu")
		(net "P5E_CPU1_P3_RX_DP<6>")
	)
	(segment
		(start 119.407686 -294.658796)
		(end 119.375936 -294.640508)
		(width 0.1143)
		(layer "In4.Cu")
		(net "P5E_CPU1_P3_RX_DP<6>")
	)
	(segment
		(start 120.44299 -301.09033)
		(end 119.275098 -298.25442)
		(width 0.14224)
		(layer "In4.Cu")
		(net "P5E_CPU1_P3_RX_DP<6>")
	)
	(segment
		(start 119.375936 -294.031924)
		(end 119.397526 -294.019478)
		(width 0.1143)
		(layer "In4.Cu")
		(net "P5E_CPU1_P3_RX_DP<6>")
	)
	(segment
		(start 122.848624 -385.460494)
		(end 122.848624 -385.046982)
		(width 0.14224)
		(layer "In4.Cu")
		(net "P5E_CPU1_P3_RX_DP<6>")
	)
	(segment
		(start 119.397526 -294.019478)
		(end 119.398288 -294.01897)
		(width 0.1143)
		(layer "In4.Cu")
		(net "P5E_CPU1_P3_RX_DP<6>")
	)
	(segment
		(start 119.401844 -294.016938)
		(end 119.403368 -294.016176)
		(width 0.1143)
		(layer "In4.Cu")
		(net "P5E_CPU1_P3_RX_DP<6>")
	)
	(segment
		(start 119.690134 -295.14673)
		(end 119.690134 -295.146222)
		(width 0.1143)
		(layer "In4.Cu")
		(net "P5E_CPU1_P3_RX_DP<6>")
	)
	(segment
		(start 137.398252 -333.542132)
		(end 136.745726 -329.910186)
		(width 0.14224)
		(layer "In4.Cu")
		(net "P5E_CPU1_P3_RX_DP<6>")
	)
	(segment
		(start 119.408702 -291.41928)
		(end 119.407686 -291.418772)
		(width 0.1143)
		(layer "In4.Cu")
		(net "P5E_CPU1_P3_RX_DP<6>")
	)
	(segment
		(start 119.399812 -292.398196)
		(end 119.401082 -292.397434)
		(width 0.1143)
		(layer "In4.Cu")
		(net "P5E_CPU1_P3_RX_DP<6>")
	)
	(segment
		(start 119.397526 -292.399466)
		(end 119.398288 -292.398958)
		(width 0.1143)
		(layer "In4.Cu")
		(net "P5E_CPU1_P3_RX_DP<6>")
	)
	(segment
		(start 119.41048 -291.420296)
		(end 119.408702 -291.41928)
		(width 0.1143)
		(layer "In4.Cu")
		(net "P5E_CPU1_P3_RX_DP<6>")
	)
	(segment
		(start 119.40413 -292.395656)
		(end 119.406924 -292.394132)
		(width 0.1143)
		(layer "In4.Cu")
		(net "P5E_CPU1_P3_RX_DP<6>")
	)
	(segment
		(start 121.538492 -302.733202)
		(end 120.44299 -301.09033)
		(width 0.14224)
		(layer "In4.Cu")
		(net "P5E_CPU1_P3_RX_DP<6>")
	)
	(segment
		(start 119.401844 -292.396926)
		(end 119.403368 -292.396164)
		(width 0.1143)
		(layer "In4.Cu")
		(net "P5E_CPU1_P3_RX_DP<6>")
	)
	(segment
		(start 119.265446 -296.428668)
		(end 119.219726 -296.382948)
		(width 0.1143)
		(layer "In4.Cu")
		(net "P5E_CPU1_P3_RX_DP<6>")
	)
	(segment
		(start 136.745726 -329.910186)
		(end 132.375402 -317.32855)
		(width 0.14224)
		(layer "In4.Cu")
		(net "P5E_CPU1_P3_RX_DP<6>")
	)
	(segment
		(start 122.760486 -385.548632)
		(end 122.848624 -385.460494)
		(width 0.14224)
		(layer "In4.Cu")
		(net "P5E_CPU1_P3_RX_DP<6>")
	)
	(segment
		(start 137.722356 -335.347564)
		(end 137.398252 -333.543148)
		(width 0.14224)
		(layer "In4.Cu")
		(net "P5E_CPU1_P3_RX_DP<6>")
	)
	(segment
		(start 130.258058 -313.368182)
		(end 121.538492 -302.733202)
		(width 0.14224)
		(layer "In4.Cu")
		(net "P5E_CPU1_P3_RX_DP<6>")
	)
	(segment
		(start 119.446802 -293.061644)
		(end 119.410226 -293.040308)
		(width 0.1143)
		(layer "In4.Cu")
		(net "P5E_CPU1_P3_RX_DP<6>")
	)
	(segment
		(start 129.006346 -362.534454)
		(end 136.692386 -357.398574)
		(width 0.14224)
		(layer "In4.Cu")
		(net "P5E_CPU1_P3_RX_DP<6>")
	)
	(segment
		(start 137.398252 -333.54264)
		(end 137.397998 -333.542386)
		(width 0.14224)
		(layer "In4.Cu")
		(net "P5E_CPU1_P3_RX_DP<6>")
	)
	(segment
		(start 122.840496 -383.99593)
		(end 122.840496 -382.506728)
		(width 0.14224)
		(layer "In4.Cu")
		(net "P5E_CPU1_P3_RX_DP<6>")
	)
	(segment
		(start 119.401082 -294.017446)
		(end 119.401844 -294.016938)
		(width 0.1143)
		(layer "In4.Cu")
		(net "P5E_CPU1_P3_RX_DP<6>")
	)
	(segment
		(start 119.407686 -292.393624)
		(end 119.408702 -292.393116)
		(width 0.1143)
		(layer "In4.Cu")
		(net "P5E_CPU1_P3_RX_DP<6>")
	)
	(segment
		(start 119.408702 -292.393116)
		(end 119.410226 -292.3921)
		(width 0.1143)
		(layer "In4.Cu")
		(net "P5E_CPU1_P3_RX_DP<6>")
	)
	(segment
		(start 119.398288 -289.158934)
		(end 119.399812 -289.158172)
		(width 0.1143)
		(layer "In4.Cu")
		(net "P5E_CPU1_P3_RX_DP<6>")
	)
	(segment
		(start 120.153938 -287.939226)
		(end 120.236742 -287.856422)
		(width 0.1143)
		(layer "In4.Cu")
		(net "P5E_CPU1_P3_RX_DP<6>")
	)
	(segment
		(start 119.398796 -291.413692)
		(end 119.366284 -291.394642)
		(width 0.1143)
		(layer "In4.Cu")
		(net "P5E_CPU1_P3_RX_DP<6>")
	)
	(segment
		(start 119.403368 -291.416232)
		(end 119.401844 -291.41547)
		(width 0.1143)
		(layer "In4.Cu")
		(net "P5E_CPU1_P3_RX_DP<6>")
	)
	(segment
		(start 119.40413 -291.41674)
		(end 119.403368 -291.416232)
		(width 0.1143)
		(layer "In4.Cu")
		(net "P5E_CPU1_P3_RX_DP<6>")
	)
	(segment
		(start 137.722356 -335.347818)
		(end 137.722356 -335.347564)
		(width 0.14224)
		(layer "In4.Cu")
		(net "P5E_CPU1_P3_RX_DP<6>")
	)
	(segment
		(start 118.952772 -290.617656)
		(end 118.906036 -290.590224)
		(width 0.1143)
		(layer "In4.Cu")
		(net "P5E_CPU1_P3_RX_DP<6>")
	)
	(segment
		(start 118.907052 -289.981386)
		(end 118.937532 -289.963606)
		(width 0.1143)
		(layer "In4.Cu")
		(net "P5E_CPU1_P3_RX_DP<6>")
	)
	(segment
		(start 132.375402 -317.32855)
		(end 130.258058 -313.368182)
		(width 0.14224)
		(layer "In4.Cu")
		(net "P5E_CPU1_P3_RX_DP<6>")
	)
	(segment
		(start 119.375936 -292.411912)
		(end 119.397526 -292.399466)
		(width 0.1143)
		(layer "In4.Cu")
		(net "P5E_CPU1_P3_RX_DP<6>")
	)
	(segment
		(start 119.407686 -294.013636)
		(end 119.408702 -294.013128)
		(width 0.1143)
		(layer "In4.Cu")
		(net "P5E_CPU1_P3_RX_DP<6>")
	)
	(segment
		(start 119.414798 -289.149536)
		(end 119.446802 -289.13074)
		(width 0.1143)
		(layer "In4.Cu")
		(net "P5E_CPU1_P3_RX_DP<6>")
	)
	(segment
		(start 138.051032 -354.856542)
		(end 138.051032 -337.17738)
		(width 0.14224)
		(layer "In4.Cu")
		(net "P5E_CPU1_P3_RX_DP<6>")
	)
	(segment
		(start 119.414544 -291.422836)
		(end 119.41302 -291.42182)
		(width 0.1143)
		(layer "In4.Cu")
		(net "P5E_CPU1_P3_RX_DP<6>")
	)
	(segment
		(start 119.403368 -294.016176)
		(end 119.40413 -294.015668)
		(width 0.1143)
		(layer "In4.Cu")
		(net "P5E_CPU1_P3_RX_DP<6>")
	)
	(segment
		(start 119.408702 -289.153092)
		(end 119.410226 -289.152076)
		(width 0.1143)
		(layer "In4.Cu")
		(net "P5E_CPU1_P3_RX_DP<6>")
	)
	(segment
		(start 119.414798 -292.38956)
		(end 119.446802 -292.370764)
		(width 0.1143)
		(layer "In4.Cu")
		(net "P5E_CPU1_P3_RX_DP<6>")
	)
	(segment
		(start 119.23268 -291.163502)
		(end 119.23268 -291.10559)
		(width 0.1143)
		(layer "In4.Cu")
		(net "P5E_CPU1_P3_RX_DP<6>")
	)
	(segment
		(start 119.408702 -294.659304)
		(end 119.407686 -294.658796)
		(width 0.1143)
		(layer "In4.Cu")
		(net "P5E_CPU1_P3_RX_DP<6>")
	)
	(segment
		(start 119.397526 -289.159442)
		(end 119.398288 -289.158934)
		(width 0.1143)
		(layer "In4.Cu")
		(net "P5E_CPU1_P3_RX_DP<6>")
	)
	(segment
		(start 122.53595 -384.300476)
		(end 122.840496 -383.99593)
		(width 0.14224)
		(layer "In4.Cu")
		(net "P5E_CPU1_P3_RX_DP<6>")
	)
	(segment
		(start 119.41302 -291.42182)
		(end 119.412004 -291.421312)
		(width 0.1143)
		(layer "In4.Cu")
		(net "P5E_CPU1_P3_RX_DP<6>")
	)
	(segment
		(start 119.408702 -294.013128)
		(end 119.410226 -294.012112)
		(width 0.1143)
		(layer "In4.Cu")
		(net "P5E_CPU1_P3_RX_DP<6>")
	)
	(segment
		(start 138.051032 -337.17738)
		(end 137.722356 -335.347818)
		(width 0.14224)
		(layer "In4.Cu")
		(net "P5E_CPU1_P3_RX_DP<6>")
	)
	(segment
		(start 119.406924 -292.394132)
		(end 119.407686 -292.393624)
		(width 0.1143)
		(layer "In4.Cu")
		(net "P5E_CPU1_P3_RX_DP<6>")
	)
	(segment
		(start 119.40413 -294.015668)
		(end 119.406924 -294.014144)
		(width 0.1143)
		(layer "In4.Cu")
		(net "P5E_CPU1_P3_RX_DP<6>")
	)
	(segment
		(start 122.822716 -382.326134)
		(end 121.553478 -375.943622)
		(width 0.14224)
		(layer "In4.Cu")
		(net "P5E_CPU1_P3_RX_DP<6>")
	)
	(segment
		(start 119.401082 -291.414962)
		(end 119.398796 -291.413692)
		(width 0.1143)
		(layer "In4.Cu")
		(net "P5E_CPU1_P3_RX_DP<6>")
	)
	(segment
		(start 137.398252 -333.543148)
		(end 137.398252 -333.54264)
		(width 0.14224)
		(layer "In4.Cu")
		(net "P5E_CPU1_P3_RX_DP<6>")
	)
	(segment
		(start 119.407686 -289.1536)
		(end 119.408702 -289.153092)
		(width 0.1143)
		(layer "In4.Cu")
		(net "P5E_CPU1_P3_RX_DP<6>")
	)
	(segment
		(start 122.532648 -384.731006)
		(end 122.53595 -384.300476)
		(width 0.14224)
		(layer "In4.Cu")
		(net "P5E_CPU1_P3_RX_DP<6>")
	)
	(segment
		(start 120.799098 -373.141748)
		(end 121.76887 -370.627656)
		(width 0.14224)
		(layer "In4.Cu")
		(net "P5E_CPU1_P3_RX_DP<6>")
	)
	(segment
		(start 119.410226 -289.152076)
		(end 119.414798 -289.149536)
		(width 0.1143)
		(layer "In4.Cu")
		(net "P5E_CPU1_P3_RX_DP<6>")
	)
	(segment
		(start 119.414798 -294.009572)
		(end 119.446802 -293.990776)
		(width 0.1143)
		(layer "In4.Cu")
		(net "P5E_CPU1_P3_RX_DP<6>")
	)
	(segment
		(start 122.491246 -386.003292)
		(end 122.586242 -385.649216)
		(width 0.14224)
		(layer "In4.Cu")
		(net "P5E_CPU1_P3_RX_DP<6>")
	)
	(arc
		(start 119.446802 -289.13074)
		(mid 119.625615 -288.92839)
		(end 119.690134 -288.666174)
		(width 0.1143)
		(layer "In4.Cu")
		(net "P5E_CPU1_P3_RX_DP<6>")
	)
	(arc
		(start 119.690134 -288.666174)
		(mid 119.7311 -288.495768)
		(end 119.845074 -288.362644)
		(width 0.1143)
		(layer "In4.Cu")
		(net "P5E_CPU1_P3_RX_DP<6>")
	)
	(arc
		(start 121.553478 -375.943622)
		(mid 121.320678 -375.182767)
		(end 120.947434 -374.480074)
		(width 0.14224)
		(layer "In4.Cu")
		(net "P5E_CPU1_P3_RX_DP<6>")
	)
	(arc
		(start 119.219726 -295.954958)
		(mid 119.219725 -295.953942)
		(end 119.219726 -295.952926)
		(width 0.1143)
		(layer "In4.Cu")
		(net "P5E_CPU1_P3_RX_DP<6>")
	)
	(arc
		(start 118.976648 -289.940746)
		(mid 119.155461 -289.738396)
		(end 119.21998 -289.47618)
		(width 0.1143)
		(layer "In4.Cu")
		(net "P5E_CPU1_P3_RX_DP<6>")
	)
	(arc
		(start 120.947434 -374.480074)
		(mid 120.710052 -373.829011)
		(end 120.799098 -373.141748)
		(width 0.14224)
		(layer "In4.Cu")
		(net "P5E_CPU1_P3_RX_DP<6>")
	)
	(arc
		(start 119.375936 -293.020496)
		(mid 119.220008 -292.716204)
		(end 119.375936 -292.411912)
		(width 0.1143)
		(layer "In4.Cu")
		(net "P5E_CPU1_P3_RX_DP<6>")
	)
	(arc
		(start 119.375936 -294.640508)
		(mid 119.220008 -294.336216)
		(end 119.375936 -294.031924)
		(width 0.1143)
		(layer "In4.Cu")
		(net "P5E_CPU1_P3_RX_DP<6>")
	)
	(arc
		(start 119.446802 -293.990776)
		(mid 119.690129 -293.52621)
		(end 119.446802 -293.061644)
		(width 0.1143)
		(layer "In4.Cu")
		(net "P5E_CPU1_P3_RX_DP<6>")
	)
	(arc
		(start 119.366284 -291.394642)
		(mid 119.268552 -291.296952)
		(end 119.23268 -291.163502)
		(width 0.1143)
		(layer "In4.Cu")
		(net "P5E_CPU1_P3_RX_DP<6>")
	)
	(arc
		(start 118.80342 -290.478464)
		(mid 118.758142 -290.209717)
		(end 118.907052 -289.981386)
		(width 0.1143)
		(layer "In4.Cu")
		(net "P5E_CPU1_P3_RX_DP<6>")
	)
	(arc
		(start 119.275098 -298.254166)
		(mid 119.267878 -298.230383)
		(end 119.265446 -298.205652)
		(width 0.14224)
		(layer "In4.Cu")
		(net "P5E_CPU1_P3_RX_DP<6>")
	)
	(arc
		(start 120.150128 -287.962086)
		(mid 120.152151 -287.950676)
		(end 120.153938 -287.939226)
		(width 0.1143)
		(layer "In4.Cu")
		(net "P5E_CPU1_P3_RX_DP<6>")
	)
	(arc
		(start 119.448072 -295.609772)
		(mid 119.625915 -295.40795)
		(end 119.690134 -295.14673)
		(width 0.1143)
		(layer "In4.Cu")
		(net "P5E_CPU1_P3_RX_DP<6>")
	)
	(arc
		(start 119.446802 -292.370764)
		(mid 119.690129 -291.906198)
		(end 119.446802 -291.441632)
		(width 0.1143)
		(layer "In4.Cu")
		(net "P5E_CPU1_P3_RX_DP<6>")
	)
	(arc
		(start 119.23268 -291.10559)
		(mid 119.157727 -290.824341)
		(end 118.952772 -290.617656)
		(width 0.1143)
		(layer "In4.Cu")
		(net "P5E_CPU1_P3_RX_DP<6>")
	)
	(arc
		(start 119.690134 -295.146222)
		(mid 119.625619 -294.884003)
		(end 119.446802 -294.681656)
		(width 0.1143)
		(layer "In4.Cu")
		(net "P5E_CPU1_P3_RX_DP<6>")
	)
	(arc
		(start 127.108458 -364.171484)
		(mid 128.007117 -363.29467)
		(end 129.006346 -362.534454)
		(width 0.14224)
		(layer "In4.Cu")
		(net "P5E_CPU1_P3_RX_DP<6>")
	)
	(arc
		(start 136.692386 -357.398574)
		(mid 137.690062 -356.297709)
		(end 138.051032 -354.856542)
		(width 0.14224)
		(layer "In4.Cu")
		(net "P5E_CPU1_P3_RX_DP<6>")
	)
	(arc
		(start 121.76887 -370.627656)
		(mid 122.231132 -369.69521)
		(end 122.856244 -368.863118)
		(width 0.14224)
		(layer "In4.Cu")
		(net "P5E_CPU1_P3_RX_DP<6>")
	)
	(arc
		(start 119.219726 -295.952926)
		(mid 119.265018 -295.785493)
		(end 119.375682 -295.651936)
		(width 0.1143)
		(layer "In4.Cu")
		(net "P5E_CPU1_P3_RX_DP<6>")
	)
	(arc
		(start 119.916702 -288.320988)
		(mid 120.068689 -288.16448)
		(end 120.150128 -287.962086)
		(width 0.1143)
		(layer "In4.Cu")
		(net "P5E_CPU1_P3_RX_DP<6>")
	)
	(arc
		(start 122.840496 -382.506728)
		(mid 122.836044 -382.415994)
		(end 122.822716 -382.326134)
		(width 0.14224)
		(layer "In4.Cu")
		(net "P5E_CPU1_P3_RX_DP<6>")
	)
	(arc
		(start 119.21998 -289.47618)
		(mid 119.261235 -289.305209)
		(end 119.375936 -289.171888)
		(width 0.1143)
		(layer "In4.Cu")
		(net "P5E_CPU1_P3_RX_DP<6>")
	)
	(arc
		(start 118.906036 -290.590224)
		(mid 118.849007 -290.539597)
		(end 118.80342 -290.478464)
		(width 0.1143)
		(layer "In4.Cu")
		(net "P5E_CPU1_P3_RX_DP<6>")
	)
	(segment
		(start 120.77065 -386.003292)
		(end 121.29135 -386.003292)
		(width 0.127)
		(layer "F.Cu")
		(net "P5E_CPU1_P3_RX_DP<5>")
	)
	(segment
		(start 117.247924 -289.210242)
		(end 117.714776 -289.47618)
		(width 0.12954)
		(layer "F.Cu")
		(net "P5E_CPU1_P3_RX_DP<5>")
	)
	(segment
		(start 137.118852 -353.955096)
		(end 137.118852 -337.263486)
		(width 0.14224)
		(layer "In4.Cu")
		(net "P5E_CPU1_P3_RX_DP<5>")
	)
	(segment
		(start 129.484882 -313.89955)
		(end 120.814338 -303.333658)
		(width 0.14224)
		(layer "In4.Cu")
		(net "P5E_CPU1_P3_RX_DP<5>")
	)
	(segment
		(start 118.437152 -294.031416)
		(end 118.467632 -294.013636)
		(width 0.1143)
		(layer "In4.Cu")
		(net "P5E_CPU1_P3_RX_DP<5>")
	)
	(segment
		(start 118.3259 -296.330116)
		(end 118.28018 -296.284396)
		(width 0.1143)
		(layer "In4.Cu")
		(net "P5E_CPU1_P3_RX_DP<5>")
	)
	(segment
		(start 117.346984 -289.54603)
		(end 117.416834 -289.47618)
		(width 0.1143)
		(layer "In4.Cu")
		(net "P5E_CPU1_P3_RX_DP<5>")
	)
	(segment
		(start 118.00205 -290.611306)
		(end 118.000526 -290.61029)
		(width 0.1143)
		(layer "In4.Cu")
		(net "P5E_CPU1_P3_RX_DP<5>")
	)
	(segment
		(start 118.3259 -296.358564)
		(end 118.3259 -296.330116)
		(width 0.1143)
		(layer "In4.Cu")
		(net "P5E_CPU1_P3_RX_DP<5>")
	)
	(segment
		(start 118.437152 -295.651428)
		(end 118.467632 -295.633648)
		(width 0.1143)
		(layer "In4.Cu")
		(net "P5E_CPU1_P3_RX_DP<5>")
	)
	(segment
		(start 131.519168 -317.705994)
		(end 129.484882 -313.89955)
		(width 0.14224)
		(layer "In4.Cu")
		(net "P5E_CPU1_P3_RX_DP<5>")
	)
	(segment
		(start 118.036848 -290.631626)
		(end 118.02999 -290.627562)
		(width 0.1143)
		(layer "In4.Cu")
		(net "P5E_CPU1_P3_RX_DP<5>")
	)
	(segment
		(start 118.28018 -296.284396)
		(end 118.28018 -295.956228)
		(width 0.1143)
		(layer "In4.Cu")
		(net "P5E_CPU1_P3_RX_DP<5>")
	)
	(segment
		(start 118.467632 -293.038784)
		(end 118.437152 -293.021004)
		(width 0.1143)
		(layer "In4.Cu")
		(net "P5E_CPU1_P3_RX_DP<5>")
	)
	(segment
		(start 121.337832 -384.175762)
		(end 121.6406 -383.872994)
		(width 0.14224)
		(layer "In4.Cu")
		(net "P5E_CPU1_P3_RX_DP<5>")
	)
	(segment
		(start 118.437152 -292.411404)
		(end 118.467632 -292.393624)
		(width 0.1143)
		(layer "In4.Cu")
		(net "P5E_CPU1_P3_RX_DP<5>")
	)
	(segment
		(start 118.467632 -294.658796)
		(end 118.437152 -294.641016)
		(width 0.1143)
		(layer "In4.Cu")
		(net "P5E_CPU1_P3_RX_DP<5>")
	)
	(segment
		(start 135.841232 -330.150978)
		(end 131.519168 -317.705994)
		(width 0.14224)
		(layer "In4.Cu")
		(net "P5E_CPU1_P3_RX_DP<5>")
	)
	(segment
		(start 118.029228 -290.627054)
		(end 118.00459 -290.61283)
		(width 0.1143)
		(layer "In4.Cu")
		(net "P5E_CPU1_P3_RX_DP<5>")
	)
	(segment
		(start 118.506748 -291.441632)
		(end 118.467632 -291.418772)
		(width 0.1143)
		(layer "In4.Cu")
		(net "P5E_CPU1_P3_RX_DP<5>")
	)
	(segment
		(start 117.998748 -290.609274)
		(end 117.997732 -290.608766)
		(width 0.1143)
		(layer "In4.Cu")
		(net "P5E_CPU1_P3_RX_DP<5>")
	)
	(segment
		(start 118.3259 -298.224448)
		(end 118.3259 -296.358564)
		(width 0.14224)
		(layer "In4.Cu")
		(net "P5E_CPU1_P3_RX_DP<5>")
	)
	(segment
		(start 120.814338 -303.333658)
		(end 119.624094 -301.550578)
		(width 0.14224)
		(layer "In4.Cu")
		(net "P5E_CPU1_P3_RX_DP<5>")
	)
	(segment
		(start 122.194828 -368.158776)
		(end 126.404878 -363.51337)
		(width 0.14224)
		(layer "In4.Cu")
		(net "P5E_CPU1_P3_RX_DP<5>")
	)
	(segment
		(start 121.332752 -384.731006)
		(end 121.337832 -384.175762)
		(width 0.14224)
		(layer "In4.Cu")
		(net "P5E_CPU1_P3_RX_DP<5>")
	)
	(segment
		(start 118.467632 -292.393624)
		(end 118.506748 -292.370764)
		(width 0.1143)
		(layer "In4.Cu")
		(net "P5E_CPU1_P3_RX_DP<5>")
	)
	(segment
		(start 118.00459 -290.61283)
		(end 118.003066 -290.611814)
		(width 0.1143)
		(layer "In4.Cu")
		(net "P5E_CPU1_P3_RX_DP<5>")
	)
	(segment
		(start 118.506748 -293.061644)
		(end 118.467632 -293.038784)
		(width 0.1143)
		(layer "In4.Cu")
		(net "P5E_CPU1_P3_RX_DP<5>")
	)
	(segment
		(start 117.527832 -289.79876)
		(end 117.526816 -289.798252)
		(width 0.1143)
		(layer "In4.Cu")
		(net "P5E_CPU1_P3_RX_DP<5>")
	)
	(segment
		(start 121.6406 -383.872994)
		(end 121.6406 -382.45669)
		(width 0.14224)
		(layer "In4.Cu")
		(net "P5E_CPU1_P3_RX_DP<5>")
	)
	(segment
		(start 118.467632 -294.013636)
		(end 118.506748 -293.990776)
		(width 0.1143)
		(layer "In4.Cu")
		(net "P5E_CPU1_P3_RX_DP<5>")
	)
	(segment
		(start 117.526816 -289.798252)
		(end 117.496082 -289.780472)
		(width 0.1143)
		(layer "In4.Cu")
		(net "P5E_CPU1_P3_RX_DP<5>")
	)
	(segment
		(start 118.000526 -290.61029)
		(end 117.998748 -290.609274)
		(width 0.1143)
		(layer "In4.Cu")
		(net "P5E_CPU1_P3_RX_DP<5>")
	)
	(segment
		(start 119.811292 -373.051832)
		(end 120.868186 -370.312188)
		(width 0.14224)
		(layer "In4.Cu")
		(net "P5E_CPU1_P3_RX_DP<5>")
	)
	(segment
		(start 117.997732 -290.608766)
		(end 117.99697 -290.608258)
		(width 0.1143)
		(layer "In4.Cu")
		(net "P5E_CPU1_P3_RX_DP<5>")
	)
	(segment
		(start 119.624094 -301.550578)
		(end 118.39956 -298.594526)
		(width 0.14224)
		(layer "In4.Cu")
		(net "P5E_CPU1_P3_RX_DP<5>")
	)
	(segment
		(start 121.29135 -386.003292)
		(end 121.386346 -385.649216)
		(width 0.14224)
		(layer "In4.Cu")
		(net "P5E_CPU1_P3_RX_DP<5>")
	)
	(segment
		(start 137.118852 -337.263486)
		(end 135.841232 -330.150978)
		(width 0.14224)
		(layer "In4.Cu")
		(net "P5E_CPU1_P3_RX_DP<5>")
	)
	(segment
		(start 121.386346 -385.649216)
		(end 121.56059 -385.548632)
		(width 0.14224)
		(layer "In4.Cu")
		(net "P5E_CPU1_P3_RX_DP<5>")
	)
	(segment
		(start 128.32842 -361.854242)
		(end 135.434832 -357.105966)
		(width 0.14224)
		(layer "In4.Cu")
		(net "P5E_CPU1_P3_RX_DP<5>")
	)
	(segment
		(start 118.02999 -290.627562)
		(end 118.029228 -290.627054)
		(width 0.1143)
		(layer "In4.Cu")
		(net "P5E_CPU1_P3_RX_DP<5>")
	)
	(segment
		(start 118.467632 -291.418772)
		(end 118.437152 -291.400992)
		(width 0.1143)
		(layer "In4.Cu")
		(net "P5E_CPU1_P3_RX_DP<5>")
	)
	(segment
		(start 117.530626 -289.800538)
		(end 117.527832 -289.79876)
		(width 0.1143)
		(layer "In4.Cu")
		(net "P5E_CPU1_P3_RX_DP<5>")
	)
	(segment
		(start 118.467632 -295.633648)
		(end 118.506748 -295.610788)
		(width 0.1143)
		(layer "In4.Cu")
		(net "P5E_CPU1_P3_RX_DP<5>")
	)
	(segment
		(start 121.648728 -385.046982)
		(end 121.332752 -384.731006)
		(width 0.14224)
		(layer "In4.Cu")
		(net "P5E_CPU1_P3_RX_DP<5>")
	)
	(segment
		(start 118.506748 -294.681656)
		(end 118.467632 -294.658796)
		(width 0.1143)
		(layer "In4.Cu")
		(net "P5E_CPU1_P3_RX_DP<5>")
	)
	(segment
		(start 121.648728 -385.460494)
		(end 121.648728 -385.046982)
		(width 0.14224)
		(layer "In4.Cu")
		(net "P5E_CPU1_P3_RX_DP<5>")
	)
	(segment
		(start 117.416834 -289.47618)
		(end 117.714776 -289.47618)
		(width 0.1143)
		(layer "In4.Cu")
		(net "P5E_CPU1_P3_RX_DP<5>")
	)
	(segment
		(start 121.62282 -382.276096)
		(end 120.374664 -376.001788)
		(width 0.14224)
		(layer "In4.Cu")
		(net "P5E_CPU1_P3_RX_DP<5>")
	)
	(segment
		(start 118.003066 -290.611814)
		(end 118.00205 -290.611306)
		(width 0.1143)
		(layer "In4.Cu")
		(net "P5E_CPU1_P3_RX_DP<5>")
	)
	(segment
		(start 121.56059 -385.548632)
		(end 121.648728 -385.460494)
		(width 0.14224)
		(layer "In4.Cu")
		(net "P5E_CPU1_P3_RX_DP<5>")
	)
	(arc
		(start 118.39956 -298.594526)
		(mid 118.344521 -298.413113)
		(end 118.3259 -298.224448)
		(width 0.14224)
		(layer "In4.Cu")
		(net "P5E_CPU1_P3_RX_DP<5>")
	)
	(arc
		(start 117.809264 -290.284154)
		(mid 117.734625 -290.005077)
		(end 117.530626 -289.800538)
		(width 0.1143)
		(layer "In4.Cu")
		(net "P5E_CPU1_P3_RX_DP<5>")
	)
	(arc
		(start 118.506748 -293.990776)
		(mid 118.750075 -293.52621)
		(end 118.506748 -293.061644)
		(width 0.1143)
		(layer "In4.Cu")
		(net "P5E_CPU1_P3_RX_DP<5>")
	)
	(arc
		(start 118.437152 -294.641016)
		(mid 118.280175 -294.336216)
		(end 118.437152 -294.031416)
		(width 0.1143)
		(layer "In4.Cu")
		(net "P5E_CPU1_P3_RX_DP<5>")
	)
	(arc
		(start 120.051576 -375.22023)
		(mid 119.666972 -374.165344)
		(end 119.811292 -373.051832)
		(width 0.14224)
		(layer "In4.Cu")
		(net "P5E_CPU1_P3_RX_DP<5>")
	)
	(arc
		(start 120.868186 -370.312188)
		(mid 121.432135 -369.174263)
		(end 122.194828 -368.158776)
		(width 0.14224)
		(layer "In4.Cu")
		(net "P5E_CPU1_P3_RX_DP<5>")
	)
	(arc
		(start 120.374664 -376.001788)
		(mid 120.245385 -375.597672)
		(end 120.051576 -375.22023)
		(width 0.14224)
		(layer "In4.Cu")
		(net "P5E_CPU1_P3_RX_DP<5>")
	)
	(arc
		(start 126.404878 -363.51337)
		(mid 127.315676 -362.62471)
		(end 128.32842 -361.854242)
		(width 0.14224)
		(layer "In4.Cu")
		(net "P5E_CPU1_P3_RX_DP<5>")
	)
	(arc
		(start 118.28018 -291.096192)
		(mid 118.215665 -290.833973)
		(end 118.036848 -290.631626)
		(width 0.1143)
		(layer "In4.Cu")
		(net "P5E_CPU1_P3_RX_DP<5>")
	)
	(arc
		(start 118.28018 -295.956228)
		(mid 118.321729 -295.784806)
		(end 118.437152 -295.651428)
		(width 0.1143)
		(layer "In4.Cu")
		(net "P5E_CPU1_P3_RX_DP<5>")
	)
	(arc
		(start 121.6406 -382.45669)
		(mid 121.636147 -382.365956)
		(end 121.62282 -382.276096)
		(width 0.14224)
		(layer "In4.Cu")
		(net "P5E_CPU1_P3_RX_DP<5>")
	)
	(arc
		(start 118.506748 -295.610788)
		(mid 118.750075 -295.146222)
		(end 118.506748 -294.681656)
		(width 0.1143)
		(layer "In4.Cu")
		(net "P5E_CPU1_P3_RX_DP<5>")
	)
	(arc
		(start 135.434832 -357.105966)
		(mid 136.671446 -355.74143)
		(end 137.118852 -353.955096)
		(width 0.14224)
		(layer "In4.Cu")
		(net "P5E_CPU1_P3_RX_DP<5>")
	)
	(arc
		(start 118.437152 -291.400992)
		(mid 118.321725 -291.267616)
		(end 118.28018 -291.096192)
		(width 0.1143)
		(layer "In4.Cu")
		(net "P5E_CPU1_P3_RX_DP<5>")
	)
	(arc
		(start 118.437152 -293.021004)
		(mid 118.280175 -292.716204)
		(end 118.437152 -292.411404)
		(width 0.1143)
		(layer "In4.Cu")
		(net "P5E_CPU1_P3_RX_DP<5>")
	)
	(arc
		(start 117.496082 -289.780472)
		(mid 117.398947 -289.677603)
		(end 117.346984 -289.54603)
		(width 0.1143)
		(layer "In4.Cu")
		(net "P5E_CPU1_P3_RX_DP<5>")
	)
	(arc
		(start 118.506748 -292.370764)
		(mid 118.750075 -291.906198)
		(end 118.506748 -291.441632)
		(width 0.1143)
		(layer "In4.Cu")
		(net "P5E_CPU1_P3_RX_DP<5>")
	)
	(arc
		(start 117.99697 -290.608258)
		(mid 117.859568 -290.471425)
		(end 117.809264 -290.284154)
		(width 0.1143)
		(layer "In4.Cu")
		(net "P5E_CPU1_P3_RX_DP<5>")
	)
	(segment
		(start 119.5705 -386.003292)
		(end 120.0912 -386.003292)
		(width 0.127)
		(layer "F.Cu")
		(net "P5E_CPU1_P3_RX_DP<4>")
	)
	(segment
		(start 117.247924 -290.830254)
		(end 117.714776 -291.096192)
		(width 0.12954)
		(layer "F.Cu")
		(net "P5E_CPU1_P3_RX_DP<4>")
	)
	(segment
		(start 120.448578 -385.460494)
		(end 120.448578 -385.046982)
		(width 0.14224)
		(layer "In4.Cu")
		(net "P5E_CPU1_P3_RX_DP<4>")
	)
	(segment
		(start 128.704086 -314.418472)
		(end 120.042432 -303.863502)
		(width 0.14224)
		(layer "In4.Cu")
		(net "P5E_CPU1_P3_RX_DP<4>")
	)
	(segment
		(start 117.520974 -294.017446)
		(end 117.523514 -294.016176)
		(width 0.1143)
		(layer "In4.Cu")
		(net "P5E_CPU1_P3_RX_DP<4>")
	)
	(segment
		(start 117.346984 -291.166042)
		(end 117.416834 -291.096192)
		(width 0.1143)
		(layer "In4.Cu")
		(net "P5E_CPU1_P3_RX_DP<4>")
	)
	(segment
		(start 120.042432 -303.863502)
		(end 118.786148 -301.982124)
		(width 0.14224)
		(layer "In4.Cu")
		(net "P5E_CPU1_P3_RX_DP<4>")
	)
	(segment
		(start 120.448578 -385.046982)
		(end 120.132602 -384.731006)
		(width 0.14224)
		(layer "In4.Cu")
		(net "P5E_CPU1_P3_RX_DP<4>")
	)
	(segment
		(start 117.52834 -293.038784)
		(end 117.527832 -293.038784)
		(width 0.1143)
		(layer "In4.Cu")
		(net "P5E_CPU1_P3_RX_DP<4>")
	)
	(segment
		(start 117.348 -295.885362)
		(end 117.346984 -295.884092)
		(width 0.1143)
		(layer "In4.Cu")
		(net "P5E_CPU1_P3_RX_DP<4>")
	)
	(segment
		(start 117.902736 -374.023636)
		(end 117.20576 -372.980458)
		(width 0.14224)
		(layer "In4.Cu")
		(net "P5E_CPU1_P3_RX_DP<4>")
	)
	(segment
		(start 117.527832 -293.038784)
		(end 117.52707 -293.038276)
		(width 0.1143)
		(layer "In4.Cu")
		(net "P5E_CPU1_P3_RX_DP<4>")
	)
	(segment
		(start 117.49659 -292.412166)
		(end 117.526308 -292.395148)
		(width 0.1143)
		(layer "In4.Cu")
		(net "P5E_CPU1_P3_RX_DP<4>")
	)
	(segment
		(start 118.786148 -301.982124)
		(end 117.403372 -298.64431)
		(width 0.14224)
		(layer "In4.Cu")
		(net "P5E_CPU1_P3_RX_DP<4>")
	)
	(segment
		(start 134.935214 -330.384658)
		(end 130.66014 -318.077596)
		(width 0.14224)
		(layer "In4.Cu")
		(net "P5E_CPU1_P3_RX_DP<4>")
	)
	(segment
		(start 116.839238 -369.398804)
		(end 118.546118 -367.515648)
		(width 0.14224)
		(layer "In4.Cu")
		(net "P5E_CPU1_P3_RX_DP<4>")
	)
	(segment
		(start 117.39372 -296.362882)
		(end 117.39372 -296.334434)
		(width 0.1143)
		(layer "In4.Cu")
		(net "P5E_CPU1_P3_RX_DP<4>")
	)
	(segment
		(start 117.526054 -294.014652)
		(end 117.52707 -294.014144)
		(width 0.1143)
		(layer "In4.Cu")
		(net "P5E_CPU1_P3_RX_DP<4>")
	)
	(segment
		(start 117.39372 -296.334434)
		(end 117.348 -296.288714)
		(width 0.1143)
		(layer "In4.Cu")
		(net "P5E_CPU1_P3_RX_DP<4>")
	)
	(segment
		(start 120.132602 -384.731006)
		(end 120.137682 -384.115818)
		(width 0.14224)
		(layer "In4.Cu")
		(net "P5E_CPU1_P3_RX_DP<4>")
	)
	(segment
		(start 117.527832 -291.418772)
		(end 117.496082 -291.400484)
		(width 0.1143)
		(layer "In4.Cu")
		(net "P5E_CPU1_P3_RX_DP<4>")
	)
	(segment
		(start 120.36044 -385.548632)
		(end 120.448578 -385.460494)
		(width 0.14224)
		(layer "In4.Cu")
		(net "P5E_CPU1_P3_RX_DP<4>")
	)
	(segment
		(start 120.289828 -366.01146)
		(end 134.260082 -356.676198)
		(width 0.14224)
		(layer "In4.Cu")
		(net "P5E_CPU1_P3_RX_DP<4>")
	)
	(segment
		(start 117.497098 -295.651428)
		(end 117.566694 -295.610788)
		(width 0.1143)
		(layer "In4.Cu")
		(net "P5E_CPU1_P3_RX_DP<4>")
	)
	(segment
		(start 116.40566 -372.4783)
		(end 116.010944 -372.083584)
		(width 0.14224)
		(layer "In4.Cu")
		(net "P5E_CPU1_P3_RX_DP<4>")
	)
	(segment
		(start 120.44045 -383.81305)
		(end 120.44045 -382.850898)
		(width 0.14224)
		(layer "In4.Cu")
		(net "P5E_CPU1_P3_RX_DP<4>")
	)
	(segment
		(start 116.88953 -372.720616)
		(end 116.569998 -372.588282)
		(width 0.14224)
		(layer "In4.Cu")
		(net "P5E_CPU1_P3_RX_DP<4>")
	)
	(segment
		(start 117.497098 -294.641016)
		(end 117.496336 -294.640508)
		(width 0.1143)
		(layer "In4.Cu")
		(net "P5E_CPU1_P3_RX_DP<4>")
	)
	(segment
		(start 117.566694 -294.681656)
		(end 117.497098 -294.641016)
		(width 0.1143)
		(layer "In4.Cu")
		(net "P5E_CPU1_P3_RX_DP<4>")
	)
	(segment
		(start 136.186672 -337.351878)
		(end 134.935214 -330.384658)
		(width 0.14224)
		(layer "In4.Cu")
		(net "P5E_CPU1_P3_RX_DP<4>")
	)
	(segment
		(start 117.524276 -294.015668)
		(end 117.525292 -294.01516)
		(width 0.1143)
		(layer "In4.Cu")
		(net "P5E_CPU1_P3_RX_DP<4>")
	)
	(segment
		(start 136.186672 -353.07143)
		(end 136.186672 -337.351878)
		(width 0.14224)
		(layer "In4.Cu")
		(net "P5E_CPU1_P3_RX_DP<4>")
	)
	(segment
		(start 117.416834 -291.096192)
		(end 117.714776 -291.096192)
		(width 0.1143)
		(layer "In4.Cu")
		(net "P5E_CPU1_P3_RX_DP<4>")
	)
	(segment
		(start 117.523514 -294.016176)
		(end 117.524276 -294.015668)
		(width 0.1143)
		(layer "In4.Cu")
		(net "P5E_CPU1_P3_RX_DP<4>")
	)
	(segment
		(start 117.496336 -294.640508)
		(end 117.492018 -294.63746)
		(width 0.1143)
		(layer "In4.Cu")
		(net "P5E_CPU1_P3_RX_DP<4>")
	)
	(segment
		(start 120.0912 -386.003292)
		(end 120.186196 -385.649216)
		(width 0.14224)
		(layer "In4.Cu")
		(net "P5E_CPU1_P3_RX_DP<4>")
	)
	(segment
		(start 117.348 -296.288714)
		(end 117.348 -295.885362)
		(width 0.1143)
		(layer "In4.Cu")
		(net "P5E_CPU1_P3_RX_DP<4>")
	)
	(segment
		(start 117.527832 -294.013636)
		(end 117.52834 -294.013636)
		(width 0.1143)
		(layer "In4.Cu")
		(net "P5E_CPU1_P3_RX_DP<4>")
	)
	(segment
		(start 117.52707 -294.014144)
		(end 117.527832 -294.013636)
		(width 0.1143)
		(layer "In4.Cu")
		(net "P5E_CPU1_P3_RX_DP<4>")
	)
	(segment
		(start 130.66014 -318.077596)
		(end 128.704086 -314.418472)
		(width 0.14224)
		(layer "In4.Cu")
		(net "P5E_CPU1_P3_RX_DP<4>")
	)
	(segment
		(start 117.52707 -293.038276)
		(end 117.49659 -293.02075)
		(width 0.1143)
		(layer "In4.Cu")
		(net "P5E_CPU1_P3_RX_DP<4>")
	)
	(segment
		(start 120.137682 -384.115818)
		(end 120.44045 -383.81305)
		(width 0.14224)
		(layer "In4.Cu")
		(net "P5E_CPU1_P3_RX_DP<4>")
	)
	(segment
		(start 120.186196 -385.649216)
		(end 120.36044 -385.548632)
		(width 0.14224)
		(layer "In4.Cu")
		(net "P5E_CPU1_P3_RX_DP<4>")
	)
	(segment
		(start 120.349264 -381.924814)
		(end 119.586502 -378.088144)
		(width 0.14224)
		(layer "In4.Cu")
		(net "P5E_CPU1_P3_RX_DP<4>")
	)
	(segment
		(start 117.525292 -294.01516)
		(end 117.526054 -294.014652)
		(width 0.1143)
		(layer "In4.Cu")
		(net "P5E_CPU1_P3_RX_DP<4>")
	)
	(segment
		(start 117.39372 -298.595542)
		(end 117.39372 -296.362882)
		(width 0.14224)
		(layer "In4.Cu")
		(net "P5E_CPU1_P3_RX_DP<4>")
	)
	(arc
		(start 116.010944 -372.083584)
		(mid 115.756403 -371.613538)
		(end 115.800124 -371.080792)
		(width 0.14224)
		(layer "In4.Cu")
		(net "P5E_CPU1_P3_RX_DP<4>")
	)
	(arc
		(start 117.496082 -291.400484)
		(mid 117.398947 -291.297615)
		(end 117.346984 -291.166042)
		(width 0.1143)
		(layer "In4.Cu")
		(net "P5E_CPU1_P3_RX_DP<4>")
	)
	(arc
		(start 116.569998 -372.588282)
		(mid 116.482425 -372.541368)
		(end 116.40566 -372.4783)
		(width 0.14224)
		(layer "In4.Cu")
		(net "P5E_CPU1_P3_RX_DP<4>")
	)
	(arc
		(start 120.44045 -382.850898)
		(mid 120.417602 -382.385616)
		(end 120.349264 -381.924814)
		(width 0.14224)
		(layer "In4.Cu")
		(net "P5E_CPU1_P3_RX_DP<4>")
	)
	(arc
		(start 117.52834 -294.013636)
		(mid 117.808987 -293.52621)
		(end 117.52834 -293.038784)
		(width 0.1143)
		(layer "In4.Cu")
		(net "P5E_CPU1_P3_RX_DP<4>")
	)
	(arc
		(start 117.20576 -372.980458)
		(mid 117.066909 -372.827091)
		(end 116.88953 -372.720616)
		(width 0.14224)
		(layer "In4.Cu")
		(net "P5E_CPU1_P3_RX_DP<4>")
	)
	(arc
		(start 134.260082 -356.676198)
		(mid 135.674774 -355.115073)
		(end 136.186672 -353.07143)
		(width 0.14224)
		(layer "In4.Cu")
		(net "P5E_CPU1_P3_RX_DP<4>")
	)
	(arc
		(start 119.586502 -378.088144)
		(mid 118.944811 -375.972961)
		(end 117.902736 -374.023636)
		(width 0.14224)
		(layer "In4.Cu")
		(net "P5E_CPU1_P3_RX_DP<4>")
	)
	(arc
		(start 117.526308 -292.395148)
		(mid 117.808815 -291.907366)
		(end 117.527832 -291.418772)
		(width 0.1143)
		(layer "In4.Cu")
		(net "P5E_CPU1_P3_RX_DP<4>")
	)
	(arc
		(start 117.566694 -295.610788)
		(mid 117.810021 -295.146222)
		(end 117.566694 -294.681656)
		(width 0.1143)
		(layer "In4.Cu")
		(net "P5E_CPU1_P3_RX_DP<4>")
	)
	(arc
		(start 117.403372 -298.64431)
		(mid 117.396127 -298.620403)
		(end 117.39372 -298.595542)
		(width 0.14224)
		(layer "In4.Cu")
		(net "P5E_CPU1_P3_RX_DP<4>")
	)
	(arc
		(start 117.492018 -294.63746)
		(mid 117.337791 -294.319528)
		(end 117.520974 -294.017446)
		(width 0.1143)
		(layer "In4.Cu")
		(net "P5E_CPU1_P3_RX_DP<4>")
	)
	(arc
		(start 117.346984 -295.884092)
		(mid 117.387169 -295.77437)
		(end 117.459252 -295.682416)
		(width 0.1143)
		(layer "In4.Cu")
		(net "P5E_CPU1_P3_RX_DP<4>")
	)
	(arc
		(start 117.49659 -293.02075)
		(mid 117.340662 -292.716458)
		(end 117.49659 -292.412166)
		(width 0.1143)
		(layer "In4.Cu")
		(net "P5E_CPU1_P3_RX_DP<4>")
	)
	(arc
		(start 117.459252 -295.682416)
		(mid 117.477671 -295.666306)
		(end 117.497098 -295.651428)
		(width 0.1143)
		(layer "In4.Cu")
		(net "P5E_CPU1_P3_RX_DP<4>")
	)
	(arc
		(start 115.800124 -371.080792)
		(mid 116.249044 -370.196159)
		(end 116.839238 -369.398804)
		(width 0.14224)
		(layer "In4.Cu")
		(net "P5E_CPU1_P3_RX_DP<4>")
	)
	(arc
		(start 118.546118 -367.515648)
		(mid 119.371774 -366.709998)
		(end 120.289828 -366.01146)
		(width 0.14224)
		(layer "In4.Cu")
		(net "P5E_CPU1_P3_RX_DP<4>")
	)
	(segment
		(start 118.370604 -386.003292)
		(end 118.891304 -386.003292)
		(width 0.127)
		(layer "F.Cu")
		(net "P5E_CPU1_P3_RX_DP<3>")
	)
	(segment
		(start 117.247924 -287.590484)
		(end 117.714776 -287.856422)
		(width 0.12954)
		(layer "F.Cu")
		(net "P5E_CPU1_P3_RX_DP<3>")
	)
	(segment
		(start 117.607334 -377.855734)
		(end 114.351054 -374.599454)
		(width 0.14224)
		(layer "In4.Cu")
		(net "P5E_CPU1_P3_RX_DP<3>")
	)
	(segment
		(start 131.932172 -324.581774)
		(end 129.803398 -318.453262)
		(width 0.14224)
		(layer "In4.Cu")
		(net "P5E_CPU1_P3_RX_DP<3>")
	)
	(segment
		(start 116.619274 -291.43706)
		(end 116.594636 -291.422836)
		(width 0.1143)
		(layer "In4.Cu")
		(net "P5E_CPU1_P3_RX_DP<3>")
	)
	(segment
		(start 116.590318 -289.152076)
		(end 116.59489 -289.149536)
		(width 0.1143)
		(layer "In4.Cu")
		(net "P5E_CPU1_P3_RX_DP<3>")
	)
	(segment
		(start 117.416834 -287.856422)
		(end 117.714776 -287.856422)
		(width 0.1143)
		(layer "In4.Cu")
		(net "P5E_CPU1_P3_RX_DP<3>")
	)
	(segment
		(start 116.579904 -292.398196)
		(end 116.581174 -292.397434)
		(width 0.1143)
		(layer "In4.Cu")
		(net "P5E_CPU1_P3_RX_DP<3>")
	)
	(segment
		(start 116.446046 -296.330116)
		(end 116.400326 -296.284396)
		(width 0.1143)
		(layer "In4.Cu")
		(net "P5E_CPU1_P3_RX_DP<3>")
	)
	(segment
		(start 116.577618 -294.019478)
		(end 116.57838 -294.01897)
		(width 0.1143)
		(layer "In4.Cu")
		(net "P5E_CPU1_P3_RX_DP<3>")
	)
	(segment
		(start 116.59108 -294.660828)
		(end 116.588794 -294.659304)
		(width 0.1143)
		(layer "In4.Cu")
		(net "P5E_CPU1_P3_RX_DP<3>")
	)
	(segment
		(start 116.577618 -289.159442)
		(end 116.57838 -289.158934)
		(width 0.1143)
		(layer "In4.Cu")
		(net "P5E_CPU1_P3_RX_DP<3>")
	)
	(segment
		(start 116.581936 -289.156902)
		(end 116.58346 -289.15614)
		(width 0.1143)
		(layer "In4.Cu")
		(net "P5E_CPU1_P3_RX_DP<3>")
	)
	(segment
		(start 116.587778 -294.658796)
		(end 116.556028 -294.640508)
		(width 0.1143)
		(layer "In4.Cu")
		(net "P5E_CPU1_P3_RX_DP<3>")
	)
	(segment
		(start 134.030212 -330.620878)
		(end 131.932172 -324.582028)
		(width 0.14224)
		(layer "In4.Cu")
		(net "P5E_CPU1_P3_RX_DP<3>")
	)
	(segment
		(start 118.932706 -384.731006)
		(end 118.93804 -384.055366)
		(width 0.14224)
		(layer "In4.Cu")
		(net "P5E_CPU1_P3_RX_DP<3>")
	)
	(segment
		(start 116.59489 -294.009572)
		(end 116.626894 -293.990776)
		(width 0.1143)
		(layer "In4.Cu")
		(net "P5E_CPU1_P3_RX_DP<3>")
	)
	(segment
		(start 119.160544 -385.548632)
		(end 119.248682 -385.460494)
		(width 0.14224)
		(layer "In4.Cu")
		(net "P5E_CPU1_P3_RX_DP<3>")
	)
	(segment
		(start 116.400326 -295.954958)
		(end 116.399818 -295.954958)
		(width 0.1143)
		(layer "In4.Cu")
		(net "P5E_CPU1_P3_RX_DP<3>")
	)
	(segment
		(start 116.57838 -289.158934)
		(end 116.579904 -289.158172)
		(width 0.1143)
		(layer "In4.Cu")
		(net "P5E_CPU1_P3_RX_DP<3>")
	)
	(segment
		(start 116.59489 -289.149536)
		(end 116.626894 -289.13074)
		(width 0.1143)
		(layer "In4.Cu")
		(net "P5E_CPU1_P3_RX_DP<3>")
	)
	(segment
		(start 119.248682 -385.046982)
		(end 118.932706 -384.731006)
		(width 0.14224)
		(layer "In4.Cu")
		(net "P5E_CPU1_P3_RX_DP<3>")
	)
	(segment
		(start 135.254492 -337.43773)
		(end 134.030212 -330.620878)
		(width 0.14224)
		(layer "In4.Cu")
		(net "P5E_CPU1_P3_RX_DP<3>")
	)
	(segment
		(start 116.446046 -298.76369)
		(end 116.446046 -296.358564)
		(width 0.14224)
		(layer "In4.Cu")
		(net "P5E_CPU1_P3_RX_DP<3>")
	)
	(segment
		(start 115.08613 -369.859814)
		(end 117.587522 -367.100358)
		(width 0.14224)
		(layer "In4.Cu")
		(net "P5E_CPU1_P3_RX_DP<3>")
	)
	(segment
		(start 116.579904 -289.158172)
		(end 116.581174 -289.15741)
		(width 0.1143)
		(layer "In4.Cu")
		(net "P5E_CPU1_P3_RX_DP<3>")
	)
	(segment
		(start 116.588794 -291.41928)
		(end 116.587778 -291.418772)
		(width 0.1143)
		(layer "In4.Cu")
		(net "P5E_CPU1_P3_RX_DP<3>")
	)
	(segment
		(start 116.581936 -292.396926)
		(end 116.58346 -292.396164)
		(width 0.1143)
		(layer "In4.Cu")
		(net "P5E_CPU1_P3_RX_DP<3>")
	)
	(segment
		(start 116.587778 -293.038784)
		(end 116.556028 -293.020496)
		(width 0.1143)
		(layer "In4.Cu")
		(net "P5E_CPU1_P3_RX_DP<3>")
	)
	(segment
		(start 118.9863 -385.649216)
		(end 119.160544 -385.548632)
		(width 0.14224)
		(layer "In4.Cu")
		(net "P5E_CPU1_P3_RX_DP<3>")
	)
	(segment
		(start 116.556028 -294.031924)
		(end 116.576602 -294.019986)
		(width 0.1143)
		(layer "In4.Cu")
		(net "P5E_CPU1_P3_RX_DP<3>")
	)
	(segment
		(start 116.867432 -295.145714)
		(end 116.867432 -295.140888)
		(width 0.1143)
		(layer "In4.Cu")
		(net "P5E_CPU1_P3_RX_DP<3>")
	)
	(segment
		(start 116.556028 -292.411912)
		(end 116.576602 -292.399974)
		(width 0.1143)
		(layer "In4.Cu")
		(net "P5E_CPU1_P3_RX_DP<3>")
	)
	(segment
		(start 116.556028 -289.171888)
		(end 116.576602 -289.15995)
		(width 0.1143)
		(layer "In4.Cu")
		(net "P5E_CPU1_P3_RX_DP<3>")
	)
	(segment
		(start 116.581174 -291.414962)
		(end 116.57838 -291.413438)
		(width 0.1143)
		(layer "In4.Cu")
		(net "P5E_CPU1_P3_RX_DP<3>")
	)
	(segment
		(start 116.626894 -293.061644)
		(end 116.590318 -293.040308)
		(width 0.1143)
		(layer "In4.Cu")
		(net "P5E_CPU1_P3_RX_DP<3>")
	)
	(segment
		(start 129.803398 -318.453262)
		(end 127.998982 -315.07811)
		(width 0.14224)
		(layer "In4.Cu")
		(net "P5E_CPU1_P3_RX_DP<3>")
	)
	(segment
		(start 116.588794 -292.393116)
		(end 116.590318 -292.3921)
		(width 0.1143)
		(layer "In4.Cu")
		(net "P5E_CPU1_P3_RX_DP<3>")
	)
	(segment
		(start 116.576602 -289.15995)
		(end 116.577618 -289.159442)
		(width 0.1143)
		(layer "In4.Cu")
		(net "P5E_CPU1_P3_RX_DP<3>")
	)
	(segment
		(start 116.581174 -294.017446)
		(end 116.581936 -294.016938)
		(width 0.1143)
		(layer "In4.Cu")
		(net "P5E_CPU1_P3_RX_DP<3>")
	)
	(segment
		(start 116.592096 -291.421312)
		(end 116.590572 -291.420296)
		(width 0.1143)
		(layer "In4.Cu")
		(net "P5E_CPU1_P3_RX_DP<3>")
	)
	(segment
		(start 135.254492 -352.133408)
		(end 135.254492 -337.43773)
		(width 0.14224)
		(layer "In4.Cu")
		(net "P5E_CPU1_P3_RX_DP<3>")
	)
	(segment
		(start 116.58346 -291.416232)
		(end 116.581936 -291.41547)
		(width 0.1143)
		(layer "In4.Cu")
		(net "P5E_CPU1_P3_RX_DP<3>")
	)
	(segment
		(start 116.57838 -292.398958)
		(end 116.579904 -292.398196)
		(width 0.1143)
		(layer "In4.Cu")
		(net "P5E_CPU1_P3_RX_DP<3>")
	)
	(segment
		(start 116.587778 -291.418772)
		(end 116.587016 -291.418264)
		(width 0.1143)
		(layer "In4.Cu")
		(net "P5E_CPU1_P3_RX_DP<3>")
	)
	(segment
		(start 116.581936 -291.41547)
		(end 116.581174 -291.414962)
		(width 0.1143)
		(layer "In4.Cu")
		(net "P5E_CPU1_P3_RX_DP<3>")
	)
	(segment
		(start 116.59489 -292.38956)
		(end 116.626894 -292.370764)
		(width 0.1143)
		(layer "In4.Cu")
		(net "P5E_CPU1_P3_RX_DP<3>")
	)
	(segment
		(start 116.58346 -292.396164)
		(end 116.584222 -292.395656)
		(width 0.1143)
		(layer "In4.Cu")
		(net "P5E_CPU1_P3_RX_DP<3>")
	)
	(segment
		(start 116.577618 -292.399466)
		(end 116.57838 -292.398958)
		(width 0.1143)
		(layer "In4.Cu")
		(net "P5E_CPU1_P3_RX_DP<3>")
	)
	(segment
		(start 116.588794 -293.039292)
		(end 116.587778 -293.038784)
		(width 0.1143)
		(layer "In4.Cu")
		(net "P5E_CPU1_P3_RX_DP<3>")
	)
	(segment
		(start 116.590572 -291.420296)
		(end 116.588794 -291.41928)
		(width 0.1143)
		(layer "In4.Cu")
		(net "P5E_CPU1_P3_RX_DP<3>")
	)
	(segment
		(start 116.587016 -289.154108)
		(end 116.587778 -289.1536)
		(width 0.1143)
		(layer "In4.Cu")
		(net "P5E_CPU1_P3_RX_DP<3>")
	)
	(segment
		(start 116.588794 -294.659304)
		(end 116.587778 -294.658796)
		(width 0.1143)
		(layer "In4.Cu")
		(net "P5E_CPU1_P3_RX_DP<3>")
	)
	(segment
		(start 116.626894 -291.441632)
		(end 116.620036 -291.437568)
		(width 0.1143)
		(layer "In4.Cu")
		(net "P5E_CPU1_P3_RX_DP<3>")
	)
	(segment
		(start 127.998982 -315.07811)
		(end 119.431816 -304.639218)
		(width 0.14224)
		(layer "In4.Cu")
		(net "P5E_CPU1_P3_RX_DP<3>")
	)
	(segment
		(start 116.590318 -293.040308)
		(end 116.588794 -293.039292)
		(width 0.1143)
		(layer "In4.Cu")
		(net "P5E_CPU1_P3_RX_DP<3>")
	)
	(segment
		(start 116.125752 -290.613592)
		(end 116.087144 -290.590986)
		(width 0.1143)
		(layer "In4.Cu")
		(net "P5E_CPU1_P3_RX_DP<3>")
	)
	(segment
		(start 116.581174 -289.15741)
		(end 116.581936 -289.156902)
		(width 0.1143)
		(layer "In4.Cu")
		(net "P5E_CPU1_P3_RX_DP<3>")
	)
	(segment
		(start 119.431816 -304.639218)
		(end 117.950488 -302.421798)
		(width 0.14224)
		(layer "In4.Cu")
		(net "P5E_CPU1_P3_RX_DP<3>")
	)
	(segment
		(start 116.576602 -292.399974)
		(end 116.577618 -292.399466)
		(width 0.1143)
		(layer "In4.Cu")
		(net "P5E_CPU1_P3_RX_DP<3>")
	)
	(segment
		(start 116.587016 -294.014144)
		(end 116.587778 -294.013636)
		(width 0.1143)
		(layer "In4.Cu")
		(net "P5E_CPU1_P3_RX_DP<3>")
	)
	(segment
		(start 116.579904 -294.018208)
		(end 116.581174 -294.017446)
		(width 0.1143)
		(layer "In4.Cu")
		(net "P5E_CPU1_P3_RX_DP<3>")
	)
	(segment
		(start 116.593112 -291.42182)
		(end 116.592096 -291.421312)
		(width 0.1143)
		(layer "In4.Cu")
		(net "P5E_CPU1_P3_RX_DP<3>")
	)
	(segment
		(start 116.400326 -296.284396)
		(end 116.400326 -295.954958)
		(width 0.1143)
		(layer "In4.Cu")
		(net "P5E_CPU1_P3_RX_DP<3>")
	)
	(segment
		(start 118.93804 -384.055366)
		(end 119.240554 -383.752852)
		(width 0.14224)
		(layer "In4.Cu")
		(net "P5E_CPU1_P3_RX_DP<3>")
	)
	(segment
		(start 116.087144 -289.981386)
		(end 116.117624 -289.963606)
		(width 0.1143)
		(layer "In4.Cu")
		(net "P5E_CPU1_P3_RX_DP<3>")
	)
	(segment
		(start 116.588794 -289.153092)
		(end 116.590318 -289.152076)
		(width 0.1143)
		(layer "In4.Cu")
		(net "P5E_CPU1_P3_RX_DP<3>")
	)
	(segment
		(start 119.142002 -381.867664)
		(end 118.780814 -380.05131)
		(width 0.14224)
		(layer "In4.Cu")
		(net "P5E_CPU1_P3_RX_DP<3>")
	)
	(segment
		(start 116.584222 -292.395656)
		(end 116.587016 -292.394132)
		(width 0.1143)
		(layer "In4.Cu")
		(net "P5E_CPU1_P3_RX_DP<3>")
	)
	(segment
		(start 121.14784 -364.029498)
		(end 133.20141 -355.974904)
		(width 0.14224)
		(layer "In4.Cu")
		(net "P5E_CPU1_P3_RX_DP<3>")
	)
	(segment
		(start 116.117624 -289.963606)
		(end 116.15674 -289.940746)
		(width 0.1143)
		(layer "In4.Cu")
		(net "P5E_CPU1_P3_RX_DP<3>")
	)
	(segment
		(start 116.587778 -289.1536)
		(end 116.588794 -289.153092)
		(width 0.1143)
		(layer "In4.Cu")
		(net "P5E_CPU1_P3_RX_DP<3>")
	)
	(segment
		(start 116.620036 -291.437568)
		(end 116.619274 -291.43706)
		(width 0.1143)
		(layer "In4.Cu")
		(net "P5E_CPU1_P3_RX_DP<3>")
	)
	(segment
		(start 116.587016 -291.418264)
		(end 116.584222 -291.41674)
		(width 0.1143)
		(layer "In4.Cu")
		(net "P5E_CPU1_P3_RX_DP<3>")
	)
	(segment
		(start 119.248682 -385.460494)
		(end 119.248682 -385.046982)
		(width 0.14224)
		(layer "In4.Cu")
		(net "P5E_CPU1_P3_RX_DP<3>")
	)
	(segment
		(start 117.950488 -302.421798)
		(end 116.455698 -298.812458)
		(width 0.14224)
		(layer "In4.Cu")
		(net "P5E_CPU1_P3_RX_DP<3>")
	)
	(segment
		(start 118.891304 -386.003292)
		(end 118.9863 -385.649216)
		(width 0.14224)
		(layer "In4.Cu")
		(net "P5E_CPU1_P3_RX_DP<3>")
	)
	(segment
		(start 117.025166 -288.362644)
		(end 117.057678 -288.343848)
		(width 0.1143)
		(layer "In4.Cu")
		(net "P5E_CPU1_P3_RX_DP<3>")
	)
	(segment
		(start 116.58346 -294.016176)
		(end 116.584222 -294.015668)
		(width 0.1143)
		(layer "In4.Cu")
		(net "P5E_CPU1_P3_RX_DP<3>")
	)
	(segment
		(start 117.33403 -287.939226)
		(end 117.416834 -287.856422)
		(width 0.1143)
		(layer "In4.Cu")
		(net "P5E_CPU1_P3_RX_DP<3>")
	)
	(segment
		(start 116.584222 -294.015668)
		(end 116.587016 -294.014144)
		(width 0.1143)
		(layer "In4.Cu")
		(net "P5E_CPU1_P3_RX_DP<3>")
	)
	(segment
		(start 116.594636 -291.422836)
		(end 116.593112 -291.42182)
		(width 0.1143)
		(layer "In4.Cu")
		(net "P5E_CPU1_P3_RX_DP<3>")
	)
	(segment
		(start 116.584222 -289.155632)
		(end 116.587016 -289.154108)
		(width 0.1143)
		(layer "In4.Cu")
		(net "P5E_CPU1_P3_RX_DP<3>")
	)
	(segment
		(start 116.587778 -292.393624)
		(end 116.588794 -292.393116)
		(width 0.1143)
		(layer "In4.Cu")
		(net "P5E_CPU1_P3_RX_DP<3>")
	)
	(segment
		(start 116.555774 -295.651936)
		(end 116.55933 -295.649396)
		(width 0.1143)
		(layer "In4.Cu")
		(net "P5E_CPU1_P3_RX_DP<3>")
	)
	(segment
		(start 116.58346 -289.15614)
		(end 116.584222 -289.155632)
		(width 0.1143)
		(layer "In4.Cu")
		(net "P5E_CPU1_P3_RX_DP<3>")
	)
	(segment
		(start 116.588794 -294.013128)
		(end 116.590318 -294.012112)
		(width 0.1143)
		(layer "In4.Cu")
		(net "P5E_CPU1_P3_RX_DP<3>")
	)
	(segment
		(start 113.963704 -372.769892)
		(end 115.08613 -369.859814)
		(width 0.14224)
		(layer "In4.Cu")
		(net "P5E_CPU1_P3_RX_DP<3>")
	)
	(segment
		(start 131.932172 -324.582028)
		(end 131.932172 -324.581774)
		(width 0.14224)
		(layer "In4.Cu")
		(net "P5E_CPU1_P3_RX_DP<3>")
	)
	(segment
		(start 116.590318 -294.012112)
		(end 116.59489 -294.009572)
		(width 0.1143)
		(layer "In4.Cu")
		(net "P5E_CPU1_P3_RX_DP<3>")
	)
	(segment
		(start 116.446046 -296.358564)
		(end 116.446046 -296.330116)
		(width 0.1143)
		(layer "In4.Cu")
		(net "P5E_CPU1_P3_RX_DP<3>")
	)
	(segment
		(start 119.240554 -383.752852)
		(end 119.240554 -382.867154)
		(width 0.14224)
		(layer "In4.Cu")
		(net "P5E_CPU1_P3_RX_DP<3>")
	)
	(segment
		(start 116.625878 -294.680894)
		(end 116.59108 -294.660828)
		(width 0.1143)
		(layer "In4.Cu")
		(net "P5E_CPU1_P3_RX_DP<3>")
	)
	(segment
		(start 116.581174 -292.397434)
		(end 116.581936 -292.396926)
		(width 0.1143)
		(layer "In4.Cu")
		(net "P5E_CPU1_P3_RX_DP<3>")
	)
	(segment
		(start 117.057678 -288.343848)
		(end 117.096794 -288.320988)
		(width 0.1143)
		(layer "In4.Cu")
		(net "P5E_CPU1_P3_RX_DP<3>")
	)
	(segment
		(start 116.590318 -292.3921)
		(end 116.59489 -292.38956)
		(width 0.1143)
		(layer "In4.Cu")
		(net "P5E_CPU1_P3_RX_DP<3>")
	)
	(segment
		(start 116.587778 -294.013636)
		(end 116.588794 -294.013128)
		(width 0.1143)
		(layer "In4.Cu")
		(net "P5E_CPU1_P3_RX_DP<3>")
	)
	(segment
		(start 116.57838 -294.01897)
		(end 116.579904 -294.018208)
		(width 0.1143)
		(layer "In4.Cu")
		(net "P5E_CPU1_P3_RX_DP<3>")
	)
	(segment
		(start 116.576602 -294.019986)
		(end 116.577618 -294.019478)
		(width 0.1143)
		(layer "In4.Cu")
		(net "P5E_CPU1_P3_RX_DP<3>")
	)
	(segment
		(start 116.584222 -291.41674)
		(end 116.58346 -291.416232)
		(width 0.1143)
		(layer "In4.Cu")
		(net "P5E_CPU1_P3_RX_DP<3>")
	)
	(segment
		(start 116.611146 -295.616884)
		(end 116.621814 -295.611296)
		(width 0.1143)
		(layer "In4.Cu")
		(net "P5E_CPU1_P3_RX_DP<3>")
	)
	(segment
		(start 116.581936 -294.016938)
		(end 116.58346 -294.016176)
		(width 0.1143)
		(layer "In4.Cu")
		(net "P5E_CPU1_P3_RX_DP<3>")
	)
	(segment
		(start 116.587016 -292.394132)
		(end 116.587778 -292.393624)
		(width 0.1143)
		(layer "In4.Cu")
		(net "P5E_CPU1_P3_RX_DP<3>")
	)
	(segment
		(start 116.40566 -291.113718)
		(end 116.40566 -291.101526)
		(width 0.1143)
		(layer "In4.Cu")
		(net "P5E_CPU1_P3_RX_DP<3>")
	)
	(arc
		(start 116.399818 -295.954958)
		(mid 116.399817 -295.953942)
		(end 116.399818 -295.952926)
		(width 0.1143)
		(layer "In4.Cu")
		(net "P5E_CPU1_P3_RX_DP<3>")
	)
	(arc
		(start 116.087144 -290.590986)
		(mid 115.930167 -290.286186)
		(end 116.087144 -289.981386)
		(width 0.1143)
		(layer "In4.Cu")
		(net "P5E_CPU1_P3_RX_DP<3>")
	)
	(arc
		(start 116.621814 -295.611296)
		(mid 116.80226 -295.408901)
		(end 116.867432 -295.145714)
		(width 0.1143)
		(layer "In4.Cu")
		(net "P5E_CPU1_P3_RX_DP<3>")
	)
	(arc
		(start 116.55933 -295.649396)
		(mid 116.585003 -295.632765)
		(end 116.611146 -295.616884)
		(width 0.1143)
		(layer "In4.Cu")
		(net "P5E_CPU1_P3_RX_DP<3>")
	)
	(arc
		(start 116.626894 -292.370764)
		(mid 116.870221 -291.906198)
		(end 116.626894 -291.441632)
		(width 0.1143)
		(layer "In4.Cu")
		(net "P5E_CPU1_P3_RX_DP<3>")
	)
	(arc
		(start 133.20141 -355.974904)
		(mid 134.708997 -354.311256)
		(end 135.254492 -352.133408)
		(width 0.14224)
		(layer "In4.Cu")
		(net "P5E_CPU1_P3_RX_DP<3>")
	)
	(arc
		(start 116.556028 -293.020496)
		(mid 116.4001 -292.716204)
		(end 116.556028 -292.411912)
		(width 0.1143)
		(layer "In4.Cu")
		(net "P5E_CPU1_P3_RX_DP<3>")
	)
	(arc
		(start 116.626894 -293.990776)
		(mid 116.870221 -293.52621)
		(end 116.626894 -293.061644)
		(width 0.1143)
		(layer "In4.Cu")
		(net "P5E_CPU1_P3_RX_DP<3>")
	)
	(arc
		(start 116.57838 -291.413438)
		(mid 116.451946 -291.286675)
		(end 116.40566 -291.113718)
		(width 0.1143)
		(layer "In4.Cu")
		(net "P5E_CPU1_P3_RX_DP<3>")
	)
	(arc
		(start 116.400072 -289.47618)
		(mid 116.441327 -289.305209)
		(end 116.556028 -289.171888)
		(width 0.1143)
		(layer "In4.Cu")
		(net "P5E_CPU1_P3_RX_DP<3>")
	)
	(arc
		(start 118.780814 -380.05131)
		(mid 118.35696 -378.866463)
		(end 117.607334 -377.855734)
		(width 0.14224)
		(layer "In4.Cu")
		(net "P5E_CPU1_P3_RX_DP<3>")
	)
	(arc
		(start 116.405914 -295.900602)
		(mid 116.458033 -295.762526)
		(end 116.555774 -295.651936)
		(width 0.1143)
		(layer "In4.Cu")
		(net "P5E_CPU1_P3_RX_DP<3>")
	)
	(arc
		(start 117.096794 -288.320988)
		(mid 117.248781 -288.16448)
		(end 117.33022 -287.962086)
		(width 0.1143)
		(layer "In4.Cu")
		(net "P5E_CPU1_P3_RX_DP<3>")
	)
	(arc
		(start 116.455698 -298.812458)
		(mid 116.448453 -298.788551)
		(end 116.446046 -298.76369)
		(width 0.14224)
		(layer "In4.Cu")
		(net "P5E_CPU1_P3_RX_DP<3>")
	)
	(arc
		(start 116.399818 -295.952926)
		(mid 116.402025 -295.926666)
		(end 116.405914 -295.900602)
		(width 0.1143)
		(layer "In4.Cu")
		(net "P5E_CPU1_P3_RX_DP<3>")
	)
	(arc
		(start 117.587522 -367.100358)
		(mid 119.273393 -365.45561)
		(end 121.14784 -364.029498)
		(width 0.14224)
		(layer "In4.Cu")
		(net "P5E_CPU1_P3_RX_DP<3>")
	)
	(arc
		(start 117.33022 -287.962086)
		(mid 117.332243 -287.950676)
		(end 117.33403 -287.939226)
		(width 0.1143)
		(layer "In4.Cu")
		(net "P5E_CPU1_P3_RX_DP<3>")
	)
	(arc
		(start 116.556028 -294.640508)
		(mid 116.4001 -294.336216)
		(end 116.556028 -294.031924)
		(width 0.1143)
		(layer "In4.Cu")
		(net "P5E_CPU1_P3_RX_DP<3>")
	)
	(arc
		(start 116.870226 -288.666174)
		(mid 116.911192 -288.495768)
		(end 117.025166 -288.362644)
		(width 0.1143)
		(layer "In4.Cu")
		(net "P5E_CPU1_P3_RX_DP<3>")
	)
	(arc
		(start 119.240554 -382.867154)
		(mid 119.215835 -382.364987)
		(end 119.142002 -381.867664)
		(width 0.14224)
		(layer "In4.Cu")
		(net "P5E_CPU1_P3_RX_DP<3>")
	)
	(arc
		(start 116.40566 -291.101526)
		(mid 116.330707 -290.820277)
		(end 116.125752 -290.613592)
		(width 0.1143)
		(layer "In4.Cu")
		(net "P5E_CPU1_P3_RX_DP<3>")
	)
	(arc
		(start 116.15674 -289.940746)
		(mid 116.335553 -289.738396)
		(end 116.400072 -289.47618)
		(width 0.1143)
		(layer "In4.Cu")
		(net "P5E_CPU1_P3_RX_DP<3>")
	)
	(arc
		(start 116.626894 -289.13074)
		(mid 116.805707 -288.92839)
		(end 116.870226 -288.666174)
		(width 0.1143)
		(layer "In4.Cu")
		(net "P5E_CPU1_P3_RX_DP<3>")
	)
	(arc
		(start 114.351054 -374.599454)
		(mid 113.885913 -373.742125)
		(end 113.963704 -372.769892)
		(width 0.14224)
		(layer "In4.Cu")
		(net "P5E_CPU1_P3_RX_DP<3>")
	)
	(arc
		(start 116.867432 -295.140888)
		(mid 116.803428 -294.881077)
		(end 116.625878 -294.680894)
		(width 0.1143)
		(layer "In4.Cu")
		(net "P5E_CPU1_P3_RX_DP<3>")
	)
	(segment
		(start 114.897916 -290.020248)
		(end 115.364768 -290.286186)
		(width 0.12954)
		(layer "F.Cu")
		(net "P5E_CPU1_P3_RX_DP<2>")
	)
	(segment
		(start 117.170454 -386.003292)
		(end 117.691154 -386.003292)
		(width 0.127)
		(layer "F.Cu")
		(net "P5E_CPU1_P3_RX_DP<2>")
	)
	(segment
		(start 112.978946 -372.41861)
		(end 114.122454 -369.454176)
		(width 0.14224)
		(layer "In4.Cu")
		(net "P5E_CPU1_P3_RX_DP<2>")
	)
	(segment
		(start 115.638326 -291.413438)
		(end 115.637564 -291.41293)
		(width 0.1143)
		(layer "In4.Cu")
		(net "P5E_CPU1_P3_RX_DP<2>")
	)
	(segment
		(start 115.650264 -294.012112)
		(end 115.68684 -293.990776)
		(width 0.1143)
		(layer "In4.Cu")
		(net "P5E_CPU1_P3_RX_DP<2>")
	)
	(segment
		(start 117.738398 -384.008122)
		(end 118.040404 -383.706116)
		(width 0.14224)
		(layer "In4.Cu")
		(net "P5E_CPU1_P3_RX_DP<2>")
	)
	(segment
		(start 117.944138 -381.83312)
		(end 117.655086 -380.379478)
		(width 0.14224)
		(layer "In4.Cu")
		(net "P5E_CPU1_P3_RX_DP<2>")
	)
	(segment
		(start 115.658138 -294.664892)
		(end 115.657122 -294.664384)
		(width 0.1143)
		(layer "In4.Cu")
		(net "P5E_CPU1_P3_RX_DP<2>")
	)
	(segment
		(start 133.721348 -334.177386)
		(end 133.125718 -330.859638)
		(width 0.14224)
		(layer "In4.Cu")
		(net "P5E_CPU1_P3_RX_DP<2>")
	)
	(segment
		(start 115.64874 -294.013128)
		(end 115.650264 -294.012112)
		(width 0.1143)
		(layer "In4.Cu")
		(net "P5E_CPU1_P3_RX_DP<2>")
	)
	(segment
		(start 115.505738 -296.358564)
		(end 115.505738 -296.330116)
		(width 0.1143)
		(layer "In4.Cu")
		(net "P5E_CPU1_P3_RX_DP<2>")
	)
	(segment
		(start 115.658138 -291.424868)
		(end 115.657122 -291.42436)
		(width 0.1143)
		(layer "In4.Cu")
		(net "P5E_CPU1_P3_RX_DP<2>")
	)
	(segment
		(start 115.643406 -292.396164)
		(end 115.644168 -292.395656)
		(width 0.1143)
		(layer "In4.Cu")
		(net "P5E_CPU1_P3_RX_DP<2>")
	)
	(segment
		(start 133.125718 -330.859638)
		(end 128.94691 -318.829436)
		(width 0.14224)
		(layer "In4.Cu")
		(net "P5E_CPU1_P3_RX_DP<2>")
	)
	(segment
		(start 115.64874 -295.63314)
		(end 115.650518 -295.632124)
		(width 0.1143)
		(layer "In4.Cu")
		(net "P5E_CPU1_P3_RX_DP<2>")
	)
	(segment
		(start 115.216686 -290.631626)
		(end 115.14709 -290.590986)
		(width 0.1143)
		(layer "In4.Cu")
		(net "P5E_CPU1_P3_RX_DP<2>")
	)
	(segment
		(start 115.615974 -295.651936)
		(end 115.640612 -295.637712)
		(width 0.1143)
		(layer "In4.Cu")
		(net "P5E_CPU1_P3_RX_DP<2>")
	)
	(segment
		(start 115.65509 -293.043102)
		(end 115.638326 -293.03345)
		(width 0.1143)
		(layer "In4.Cu")
		(net "P5E_CPU1_P3_RX_DP<2>")
	)
	(segment
		(start 115.643152 -295.636188)
		(end 115.645692 -295.634918)
		(width 0.1143)
		(layer "In4.Cu")
		(net "P5E_CPU1_P3_RX_DP<2>")
	)
	(segment
		(start 115.65509 -294.663114)
		(end 115.638326 -294.653462)
		(width 0.1143)
		(layer "In4.Cu")
		(net "P5E_CPU1_P3_RX_DP<2>")
	)
	(segment
		(start 115.63985 -292.398196)
		(end 115.64112 -292.397434)
		(width 0.1143)
		(layer "In4.Cu")
		(net "P5E_CPU1_P3_RX_DP<2>")
	)
	(segment
		(start 116.990876 -379.136656)
		(end 113.70564 -375.85142)
		(width 0.14224)
		(layer "In4.Cu")
		(net "P5E_CPU1_P3_RX_DP<2>")
	)
	(segment
		(start 115.650264 -292.3921)
		(end 115.68684 -292.370764)
		(width 0.1143)
		(layer "In4.Cu")
		(net "P5E_CPU1_P3_RX_DP<2>")
	)
	(segment
		(start 128.94691 -318.829436)
		(end 127.23622 -315.62929)
		(width 0.14224)
		(layer "In4.Cu")
		(net "P5E_CPU1_P3_RX_DP<2>")
	)
	(segment
		(start 115.641882 -294.016938)
		(end 115.643406 -294.016176)
		(width 0.1143)
		(layer "In4.Cu")
		(net "P5E_CPU1_P3_RX_DP<2>")
	)
	(segment
		(start 115.647724 -295.633648)
		(end 115.64874 -295.63314)
		(width 0.1143)
		(layer "In4.Cu")
		(net "P5E_CPU1_P3_RX_DP<2>")
	)
	(segment
		(start 115.460018 -296.284396)
		(end 115.460018 -295.956228)
		(width 0.1143)
		(layer "In4.Cu")
		(net "P5E_CPU1_P3_RX_DP<2>")
	)
	(segment
		(start 117.78615 -385.649216)
		(end 117.960394 -385.548632)
		(width 0.14224)
		(layer "In4.Cu")
		(net "P5E_CPU1_P3_RX_DP<2>")
	)
	(segment
		(start 115.68684 -291.441632)
		(end 115.658138 -291.424868)
		(width 0.1143)
		(layer "In4.Cu")
		(net "P5E_CPU1_P3_RX_DP<2>")
	)
	(segment
		(start 115.505738 -298.93514)
		(end 115.505738 -296.358564)
		(width 0.14224)
		(layer "In4.Cu")
		(net "P5E_CPU1_P3_RX_DP<2>")
	)
	(segment
		(start 115.638326 -293.03345)
		(end 115.637564 -293.032942)
		(width 0.1143)
		(layer "In4.Cu")
		(net "P5E_CPU1_P3_RX_DP<2>")
	)
	(segment
		(start 115.641882 -292.396926)
		(end 115.643406 -292.396164)
		(width 0.1143)
		(layer "In4.Cu")
		(net "P5E_CPU1_P3_RX_DP<2>")
	)
	(segment
		(start 118.692422 -305.218592)
		(end 117.128798 -302.879252)
		(width 0.14224)
		(layer "In4.Cu")
		(net "P5E_CPU1_P3_RX_DP<2>")
	)
	(segment
		(start 115.638326 -294.653462)
		(end 115.637564 -294.652954)
		(width 0.1143)
		(layer "In4.Cu")
		(net "P5E_CPU1_P3_RX_DP<2>")
	)
	(segment
		(start 115.615974 -294.031924)
		(end 115.63985 -294.018208)
		(width 0.1143)
		(layer "In4.Cu")
		(net "P5E_CPU1_P3_RX_DP<2>")
	)
	(segment
		(start 115.647724 -292.393624)
		(end 115.64874 -292.393116)
		(width 0.1143)
		(layer "In4.Cu")
		(net "P5E_CPU1_P3_RX_DP<2>")
	)
	(segment
		(start 115.65509 -291.42309)
		(end 115.638326 -291.413438)
		(width 0.1143)
		(layer "In4.Cu")
		(net "P5E_CPU1_P3_RX_DP<2>")
	)
	(segment
		(start 115.64112 -292.397434)
		(end 115.641882 -292.396926)
		(width 0.1143)
		(layer "In4.Cu")
		(net "P5E_CPU1_P3_RX_DP<2>")
	)
	(segment
		(start 115.637564 -294.652954)
		(end 115.615974 -294.640508)
		(width 0.1143)
		(layer "In4.Cu")
		(net "P5E_CPU1_P3_RX_DP<2>")
	)
	(segment
		(start 115.64112 -294.017446)
		(end 115.641882 -294.016938)
		(width 0.1143)
		(layer "In4.Cu")
		(net "P5E_CPU1_P3_RX_DP<2>")
	)
	(segment
		(start 134.31774 -352.093784)
		(end 134.31774 -337.49869)
		(width 0.14224)
		(layer "In4.Cu")
		(net "P5E_CPU1_P3_RX_DP<2>")
	)
	(segment
		(start 115.63985 -294.018208)
		(end 115.64112 -294.017446)
		(width 0.1143)
		(layer "In4.Cu")
		(net "P5E_CPU1_P3_RX_DP<2>")
	)
	(segment
		(start 120.758204 -363.145578)
		(end 132.781294 -355.11232)
		(width 0.14224)
		(layer "In4.Cu")
		(net "P5E_CPU1_P3_RX_DP<2>")
	)
	(segment
		(start 117.960394 -385.548632)
		(end 118.048532 -385.460494)
		(width 0.14224)
		(layer "In4.Cu")
		(net "P5E_CPU1_P3_RX_DP<2>")
	)
	(segment
		(start 117.691154 -386.003292)
		(end 117.78615 -385.649216)
		(width 0.14224)
		(layer "In4.Cu")
		(net "P5E_CPU1_P3_RX_DP<2>")
	)
	(segment
		(start 117.128798 -302.879252)
		(end 115.51539 -298.983908)
		(width 0.14224)
		(layer "In4.Cu")
		(net "P5E_CPU1_P3_RX_DP<2>")
	)
	(segment
		(start 115.646962 -292.394132)
		(end 115.647724 -292.393624)
		(width 0.1143)
		(layer "In4.Cu")
		(net "P5E_CPU1_P3_RX_DP<2>")
	)
	(segment
		(start 133.721348 -334.17764)
		(end 133.721348 -334.177386)
		(width 0.14224)
		(layer "In4.Cu")
		(net "P5E_CPU1_P3_RX_DP<2>")
	)
	(segment
		(start 117.732556 -384.731006)
		(end 117.738398 -384.008122)
		(width 0.14224)
		(layer "In4.Cu")
		(net "P5E_CPU1_P3_RX_DP<2>")
	)
	(segment
		(start 115.650518 -295.632124)
		(end 115.68684 -295.610788)
		(width 0.1143)
		(layer "In4.Cu")
		(net "P5E_CPU1_P3_RX_DP<2>")
	)
	(segment
		(start 115.505738 -296.330116)
		(end 115.460018 -296.284396)
		(width 0.1143)
		(layer "In4.Cu")
		(net "P5E_CPU1_P3_RX_DP<2>")
	)
	(segment
		(start 115.64874 -292.393116)
		(end 115.650264 -292.3921)
		(width 0.1143)
		(layer "In4.Cu")
		(net "P5E_CPU1_P3_RX_DP<2>")
	)
	(segment
		(start 127.23622 -315.62929)
		(end 118.692422 -305.218592)
		(width 0.14224)
		(layer "In4.Cu")
		(net "P5E_CPU1_P3_RX_DP<2>")
	)
	(segment
		(start 115.658138 -293.04488)
		(end 115.657122 -293.044372)
		(width 0.1143)
		(layer "In4.Cu")
		(net "P5E_CPU1_P3_RX_DP<2>")
	)
	(segment
		(start 115.645692 -295.634918)
		(end 115.646962 -295.634156)
		(width 0.1143)
		(layer "In4.Cu")
		(net "P5E_CPU1_P3_RX_DP<2>")
	)
	(segment
		(start 115.643406 -294.016176)
		(end 115.644168 -294.015668)
		(width 0.1143)
		(layer "In4.Cu")
		(net "P5E_CPU1_P3_RX_DP<2>")
	)
	(segment
		(start 115.640612 -295.637712)
		(end 115.643152 -295.636188)
		(width 0.1143)
		(layer "In4.Cu")
		(net "P5E_CPU1_P3_RX_DP<2>")
	)
	(segment
		(start 115.637564 -291.41293)
		(end 115.615974 -291.400484)
		(width 0.1143)
		(layer "In4.Cu")
		(net "P5E_CPU1_P3_RX_DP<2>")
	)
	(segment
		(start 134.31774 -337.49869)
		(end 133.721348 -334.17764)
		(width 0.14224)
		(layer "In4.Cu")
		(net "P5E_CPU1_P3_RX_DP<2>")
	)
	(segment
		(start 115.68684 -294.681656)
		(end 115.658138 -294.664892)
		(width 0.1143)
		(layer "In4.Cu")
		(net "P5E_CPU1_P3_RX_DP<2>")
	)
	(segment
		(start 114.996976 -290.356036)
		(end 115.066826 -290.286186)
		(width 0.1143)
		(layer "In4.Cu")
		(net "P5E_CPU1_P3_RX_DP<2>")
	)
	(segment
		(start 115.637564 -293.032942)
		(end 115.615974 -293.020496)
		(width 0.1143)
		(layer "In4.Cu")
		(net "P5E_CPU1_P3_RX_DP<2>")
	)
	(segment
		(start 115.644168 -292.395656)
		(end 115.646962 -292.394132)
		(width 0.1143)
		(layer "In4.Cu")
		(net "P5E_CPU1_P3_RX_DP<2>")
	)
	(segment
		(start 115.644168 -294.015668)
		(end 115.646962 -294.014144)
		(width 0.1143)
		(layer "In4.Cu")
		(net "P5E_CPU1_P3_RX_DP<2>")
	)
	(segment
		(start 115.646962 -294.014144)
		(end 115.647724 -294.013636)
		(width 0.1143)
		(layer "In4.Cu")
		(net "P5E_CPU1_P3_RX_DP<2>")
	)
	(segment
		(start 115.68684 -293.061644)
		(end 115.658138 -293.04488)
		(width 0.1143)
		(layer "In4.Cu")
		(net "P5E_CPU1_P3_RX_DP<2>")
	)
	(segment
		(start 115.066826 -290.286186)
		(end 115.364768 -290.286186)
		(width 0.1143)
		(layer "In4.Cu")
		(net "P5E_CPU1_P3_RX_DP<2>")
	)
	(segment
		(start 118.048532 -385.460494)
		(end 118.048532 -385.046982)
		(width 0.14224)
		(layer "In4.Cu")
		(net "P5E_CPU1_P3_RX_DP<2>")
	)
	(segment
		(start 115.657122 -293.044372)
		(end 115.65509 -293.043102)
		(width 0.1143)
		(layer "In4.Cu")
		(net "P5E_CPU1_P3_RX_DP<2>")
	)
	(segment
		(start 118.040404 -383.706116)
		(end 118.040404 -382.812544)
		(width 0.14224)
		(layer "In4.Cu")
		(net "P5E_CPU1_P3_RX_DP<2>")
	)
	(segment
		(start 118.048532 -385.046982)
		(end 117.732556 -384.731006)
		(width 0.14224)
		(layer "In4.Cu")
		(net "P5E_CPU1_P3_RX_DP<2>")
	)
	(segment
		(start 114.122454 -369.454176)
		(end 116.55171 -366.774222)
		(width 0.14224)
		(layer "In4.Cu")
		(net "P5E_CPU1_P3_RX_DP<2>")
	)
	(segment
		(start 115.657122 -291.42436)
		(end 115.65509 -291.42309)
		(width 0.1143)
		(layer "In4.Cu")
		(net "P5E_CPU1_P3_RX_DP<2>")
	)
	(segment
		(start 115.646962 -295.634156)
		(end 115.647724 -295.633648)
		(width 0.1143)
		(layer "In4.Cu")
		(net "P5E_CPU1_P3_RX_DP<2>")
	)
	(segment
		(start 115.657122 -294.664384)
		(end 115.65509 -294.663114)
		(width 0.1143)
		(layer "In4.Cu")
		(net "P5E_CPU1_P3_RX_DP<2>")
	)
	(segment
		(start 115.647724 -294.013636)
		(end 115.64874 -294.013128)
		(width 0.1143)
		(layer "In4.Cu")
		(net "P5E_CPU1_P3_RX_DP<2>")
	)
	(segment
		(start 115.615974 -292.411912)
		(end 115.63985 -292.398196)
		(width 0.1143)
		(layer "In4.Cu")
		(net "P5E_CPU1_P3_RX_DP<2>")
	)
	(arc
		(start 133.980428 -353.563936)
		(mid 134.232235 -352.847939)
		(end 134.31774 -352.093784)
		(width 0.14224)
		(layer "In4.Cu")
		(net "P5E_CPU1_P3_RX_DP<2>")
	)
	(arc
		(start 113.70564 -375.85142)
		(mid 112.833115 -374.242812)
		(end 112.978946 -372.41861)
		(width 0.14224)
		(layer "In4.Cu")
		(net "P5E_CPU1_P3_RX_DP<2>")
	)
	(arc
		(start 115.615974 -294.640508)
		(mid 115.460046 -294.336216)
		(end 115.615974 -294.031924)
		(width 0.1143)
		(layer "In4.Cu")
		(net "P5E_CPU1_P3_RX_DP<2>")
	)
	(arc
		(start 115.68684 -293.990776)
		(mid 115.930167 -293.52621)
		(end 115.68684 -293.061644)
		(width 0.1143)
		(layer "In4.Cu")
		(net "P5E_CPU1_P3_RX_DP<2>")
	)
	(arc
		(start 115.615974 -291.400484)
		(mid 115.501298 -291.26715)
		(end 115.460018 -291.096192)
		(width 0.1143)
		(layer "In4.Cu")
		(net "P5E_CPU1_P3_RX_DP<2>")
	)
	(arc
		(start 115.68684 -292.370764)
		(mid 115.930167 -291.906198)
		(end 115.68684 -291.441632)
		(width 0.1143)
		(layer "In4.Cu")
		(net "P5E_CPU1_P3_RX_DP<2>")
	)
	(arc
		(start 115.615974 -293.020496)
		(mid 115.460046 -292.716204)
		(end 115.615974 -292.411912)
		(width 0.1143)
		(layer "In4.Cu")
		(net "P5E_CPU1_P3_RX_DP<2>")
	)
	(arc
		(start 117.655086 -380.379478)
		(mid 117.415171 -379.708798)
		(end 116.990876 -379.136656)
		(width 0.14224)
		(layer "In4.Cu")
		(net "P5E_CPU1_P3_RX_DP<2>")
	)
	(arc
		(start 116.55171 -366.774222)
		(mid 118.543502 -364.830696)
		(end 120.758204 -363.145578)
		(width 0.14224)
		(layer "In4.Cu")
		(net "P5E_CPU1_P3_RX_DP<2>")
	)
	(arc
		(start 115.460018 -295.956228)
		(mid 115.501273 -295.785257)
		(end 115.615974 -295.651936)
		(width 0.1143)
		(layer "In4.Cu")
		(net "P5E_CPU1_P3_RX_DP<2>")
	)
	(arc
		(start 132.781294 -355.11232)
		(mid 132.999732 -354.952592)
		(end 133.203696 -354.774754)
		(width 0.14224)
		(layer "In4.Cu")
		(net "P5E_CPU1_P3_RX_DP<2>")
	)
	(arc
		(start 133.203696 -354.774754)
		(mid 133.665068 -354.216178)
		(end 133.980428 -353.563936)
		(width 0.14224)
		(layer "In4.Cu")
		(net "P5E_CPU1_P3_RX_DP<2>")
	)
	(arc
		(start 115.14709 -290.590986)
		(mid 115.049325 -290.48801)
		(end 114.996976 -290.356036)
		(width 0.1143)
		(layer "In4.Cu")
		(net "P5E_CPU1_P3_RX_DP<2>")
	)
	(arc
		(start 115.51539 -298.983908)
		(mid 115.508145 -298.960001)
		(end 115.505738 -298.93514)
		(width 0.14224)
		(layer "In4.Cu")
		(net "P5E_CPU1_P3_RX_DP<2>")
	)
	(arc
		(start 115.68684 -295.610788)
		(mid 115.930167 -295.146222)
		(end 115.68684 -294.681656)
		(width 0.1143)
		(layer "In4.Cu")
		(net "P5E_CPU1_P3_RX_DP<2>")
	)
	(arc
		(start 118.040404 -382.812544)
		(mid 118.016317 -382.320469)
		(end 117.944138 -381.83312)
		(width 0.14224)
		(layer "In4.Cu")
		(net "P5E_CPU1_P3_RX_DP<2>")
	)
	(arc
		(start 115.460018 -291.096192)
		(mid 115.395503 -290.833973)
		(end 115.216686 -290.631626)
		(width 0.1143)
		(layer "In4.Cu")
		(net "P5E_CPU1_P3_RX_DP<2>")
	)
	(segment
		(start 115.970558 -386.003292)
		(end 116.491258 -386.003292)
		(width 0.127)
		(layer "F.Cu")
		(net "P5E_CPU1_P3_RX_DP<1>")
	)
	(segment
		(start 114.897916 -288.400236)
		(end 115.364768 -288.666174)
		(width 0.12954)
		(layer "F.Cu")
		(net "P5E_CPU1_P3_RX_DP<1>")
	)
	(segment
		(start 114.707416 -291.418772)
		(end 114.706654 -291.418264)
		(width 0.1143)
		(layer "In4.Cu")
		(net "P5E_CPU1_P3_RX_DP<1>")
	)
	(segment
		(start 114.70767 -293.038784)
		(end 114.67592 -293.020496)
		(width 0.1143)
		(layer "In4.Cu")
		(net "P5E_CPU1_P3_RX_DP<1>")
	)
	(segment
		(start 114.70767 -294.658796)
		(end 114.706908 -294.658288)
		(width 0.1143)
		(layer "In4.Cu")
		(net "P5E_CPU1_P3_RX_DP<1>")
	)
	(segment
		(start 114.23777 -290.608766)
		(end 114.20602 -290.590478)
		(width 0.1143)
		(layer "In4.Cu")
		(net "P5E_CPU1_P3_RX_DP<1>")
	)
	(segment
		(start 114.746024 -295.611296)
		(end 114.758216 -295.60266)
		(width 0.1143)
		(layer "In4.Cu")
		(net "P5E_CPU1_P3_RX_DP<1>")
	)
	(segment
		(start 114.565684 -298.99737)
		(end 114.565684 -296.358564)
		(width 0.14224)
		(layer "In4.Cu")
		(net "P5E_CPU1_P3_RX_DP<1>")
	)
	(segment
		(start 117.177058 -364.204758)
		(end 117.176804 -364.204758)
		(width 0.14224)
		(layer "In4.Cu")
		(net "P5E_CPU1_P3_RX_DP<1>")
	)
	(segment
		(start 114.706654 -291.418264)
		(end 114.705638 -291.417756)
		(width 0.1143)
		(layer "In4.Cu")
		(net "P5E_CPU1_P3_RX_DP<1>")
	)
	(segment
		(start 114.70767 -295.633648)
		(end 114.709702 -295.632632)
		(width 0.1143)
		(layer "In4.Cu")
		(net "P5E_CPU1_P3_RX_DP<1>")
	)
	(segment
		(start 114.745008 -292.372288)
		(end 114.758216 -292.362636)
		(width 0.1143)
		(layer "In4.Cu")
		(net "P5E_CPU1_P3_RX_DP<1>")
	)
	(segment
		(start 114.20602 -289.981894)
		(end 114.23777 -289.963606)
		(width 0.1143)
		(layer "In4.Cu")
		(net "P5E_CPU1_P3_RX_DP<1>")
	)
	(segment
		(start 114.706908 -295.634156)
		(end 114.70767 -295.633648)
		(width 0.1143)
		(layer "In4.Cu")
		(net "P5E_CPU1_P3_RX_DP<1>")
	)
	(segment
		(start 116.848636 -385.460494)
		(end 116.848636 -385.046982)
		(width 0.14224)
		(layer "In4.Cu")
		(net "P5E_CPU1_P3_RX_DP<1>")
	)
	(segment
		(start 116.301774 -303.325784)
		(end 114.618262 -299.261276)
		(width 0.14224)
		(layer "In4.Cu")
		(net "P5E_CPU1_P3_RX_DP<1>")
	)
	(segment
		(start 114.746024 -291.441124)
		(end 114.707416 -291.418772)
		(width 0.1143)
		(layer "In4.Cu")
		(net "P5E_CPU1_P3_RX_DP<1>")
	)
	(segment
		(start 114.703352 -292.396164)
		(end 114.704114 -292.395656)
		(width 0.1143)
		(layer "In4.Cu")
		(net "P5E_CPU1_P3_RX_DP<1>")
	)
	(segment
		(start 114.520726 -291.101272)
		(end 114.52098 -291.101272)
		(width 0.1143)
		(layer "In4.Cu")
		(net "P5E_CPU1_P3_RX_DP<1>")
	)
	(segment
		(start 114.746786 -293.061644)
		(end 114.71021 -293.040308)
		(width 0.1143)
		(layer "In4.Cu")
		(net "P5E_CPU1_P3_RX_DP<1>")
	)
	(segment
		(start 116.586254 -385.649216)
		(end 116.760498 -385.548632)
		(width 0.14224)
		(layer "In4.Cu")
		(net "P5E_CPU1_P3_RX_DP<1>")
	)
	(segment
		(start 114.706908 -292.394132)
		(end 114.70767 -292.393624)
		(width 0.1143)
		(layer "In4.Cu")
		(net "P5E_CPU1_P3_RX_DP<1>")
	)
	(segment
		(start 114.23777 -289.963606)
		(end 114.238278 -289.963352)
		(width 0.1143)
		(layer "In4.Cu")
		(net "P5E_CPU1_P3_RX_DP<1>")
	)
	(segment
		(start 114.70767 -289.1536)
		(end 114.708686 -289.153092)
		(width 0.1143)
		(layer "In4.Cu")
		(net "P5E_CPU1_P3_RX_DP<1>")
	)
	(segment
		(start 116.760498 -385.548632)
		(end 116.848636 -385.460494)
		(width 0.14224)
		(layer "In4.Cu")
		(net "P5E_CPU1_P3_RX_DP<1>")
	)
	(segment
		(start 114.70132 -292.39718)
		(end 114.703352 -292.396164)
		(width 0.1143)
		(layer "In4.Cu")
		(net "P5E_CPU1_P3_RX_DP<1>")
	)
	(segment
		(start 114.708686 -289.153092)
		(end 114.746786 -289.13074)
		(width 0.1143)
		(layer "In4.Cu")
		(net "P5E_CPU1_P3_RX_DP<1>")
	)
	(segment
		(start 114.699542 -295.638474)
		(end 114.701574 -295.637204)
		(width 0.1143)
		(layer "In4.Cu")
		(net "P5E_CPU1_P3_RX_DP<1>")
	)
	(segment
		(start 128.094994 -319.219326)
		(end 126.464822 -316.167262)
		(width 0.14224)
		(layer "In4.Cu")
		(net "P5E_CPU1_P3_RX_DP<1>")
	)
	(segment
		(start 114.706908 -294.658288)
		(end 114.67592 -294.640508)
		(width 0.1143)
		(layer "In4.Cu")
		(net "P5E_CPU1_P3_RX_DP<1>")
	)
	(segment
		(start 114.746024 -294.681148)
		(end 114.712496 -294.661844)
		(width 0.1143)
		(layer "In4.Cu")
		(net "P5E_CPU1_P3_RX_DP<1>")
	)
	(segment
		(start 114.706146 -289.154616)
		(end 114.70767 -289.1536)
		(width 0.1143)
		(layer "In4.Cu")
		(net "P5E_CPU1_P3_RX_DP<1>")
	)
	(segment
		(start 133.382258 -349.603568)
		(end 133.382258 -337.564222)
		(width 0.14224)
		(layer "In4.Cu")
		(net "P5E_CPU1_P3_RX_DP<1>")
	)
	(segment
		(start 114.705638 -291.417756)
		(end 114.681254 -291.403532)
		(width 0.1143)
		(layer "In4.Cu")
		(net "P5E_CPU1_P3_RX_DP<1>")
	)
	(segment
		(start 130.151378 -325.142352)
		(end 130.151124 -325.141844)
		(width 0.14224)
		(layer "In4.Cu")
		(net "P5E_CPU1_P3_RX_DP<1>")
	)
	(segment
		(start 116.77777 -382.006602)
		(end 116.621052 -381.219202)
		(width 0.14224)
		(layer "In4.Cu")
		(net "P5E_CPU1_P3_RX_DP<1>")
	)
	(segment
		(start 114.708686 -293.039292)
		(end 114.70767 -293.038784)
		(width 0.1143)
		(layer "In4.Cu")
		(net "P5E_CPU1_P3_RX_DP<1>")
	)
	(segment
		(start 114.565684 -296.330116)
		(end 114.519964 -296.284396)
		(width 0.1143)
		(layer "In4.Cu")
		(net "P5E_CPU1_P3_RX_DP<1>")
	)
	(segment
		(start 114.758216 -294.689784)
		(end 114.746024 -294.681148)
		(width 0.1143)
		(layer "In4.Cu")
		(net "P5E_CPU1_P3_RX_DP<1>")
	)
	(segment
		(start 114.704114 -295.63568)
		(end 114.706908 -295.634156)
		(width 0.1143)
		(layer "In4.Cu")
		(net "P5E_CPU1_P3_RX_DP<1>")
	)
	(segment
		(start 114.67592 -294.031924)
		(end 114.706908 -294.014144)
		(width 0.1143)
		(layer "In4.Cu")
		(net "P5E_CPU1_P3_RX_DP<1>")
	)
	(segment
		(start 114.206528 -365.435134)
		(end 117.177058 -364.204758)
		(width 0.14224)
		(layer "In4.Cu")
		(net "P5E_CPU1_P3_RX_DP<1>")
	)
	(segment
		(start 117.288056 -364.145322)
		(end 131.725924 -354.497894)
		(width 0.14224)
		(layer "In4.Cu")
		(net "P5E_CPU1_P3_RX_DP<1>")
	)
	(segment
		(start 109.14253 -371.000274)
		(end 111.227616 -367.87963)
		(width 0.14224)
		(layer "In4.Cu")
		(net "P5E_CPU1_P3_RX_DP<1>")
	)
	(segment
		(start 116.539518 -383.878582)
		(end 116.840508 -383.577592)
		(width 0.14224)
		(layer "In4.Cu")
		(net "P5E_CPU1_P3_RX_DP<1>")
	)
	(segment
		(start 133.271006 -351.236026)
		(end 133.377178 -349.749872)
		(width 0.14224)
		(layer "In4.Cu")
		(net "P5E_CPU1_P3_RX_DP<1>")
	)
	(segment
		(start 114.67592 -292.411912)
		(end 114.70132 -292.39718)
		(width 0.1143)
		(layer "In4.Cu")
		(net "P5E_CPU1_P3_RX_DP<1>")
	)
	(segment
		(start 114.704114 -292.395656)
		(end 114.706908 -292.394132)
		(width 0.1143)
		(layer "In4.Cu")
		(net "P5E_CPU1_P3_RX_DP<1>")
	)
	(segment
		(start 114.712496 -294.661844)
		(end 114.708686 -294.659304)
		(width 0.1143)
		(layer "In4.Cu")
		(net "P5E_CPU1_P3_RX_DP<1>")
	)
	(segment
		(start 114.708686 -294.013128)
		(end 114.746786 -293.990776)
		(width 0.1143)
		(layer "In4.Cu")
		(net "P5E_CPU1_P3_RX_DP<1>")
	)
	(segment
		(start 114.515646 -289.481514)
		(end 114.515646 -289.481006)
		(width 0.1143)
		(layer "In4.Cu")
		(net "P5E_CPU1_P3_RX_DP<1>")
	)
	(segment
		(start 114.706908 -294.014144)
		(end 114.70767 -294.013636)
		(width 0.1143)
		(layer "In4.Cu")
		(net "P5E_CPU1_P3_RX_DP<1>")
	)
	(segment
		(start 133.382258 -337.564222)
		(end 132.222748 -331.109066)
		(width 0.14224)
		(layer "In4.Cu")
		(net "P5E_CPU1_P3_RX_DP<1>")
	)
	(segment
		(start 114.70767 -294.013636)
		(end 114.708686 -294.013128)
		(width 0.1143)
		(layer "In4.Cu")
		(net "P5E_CPU1_P3_RX_DP<1>")
	)
	(segment
		(start 114.67592 -295.651936)
		(end 114.699542 -295.638474)
		(width 0.1143)
		(layer "In4.Cu")
		(net "P5E_CPU1_P3_RX_DP<1>")
	)
	(segment
		(start 114.758216 -291.44976)
		(end 114.746024 -291.441124)
		(width 0.1143)
		(layer "In4.Cu")
		(net "P5E_CPU1_P3_RX_DP<1>")
	)
	(segment
		(start 130.151124 -325.141844)
		(end 128.094994 -319.219326)
		(width 0.14224)
		(layer "In4.Cu")
		(net "P5E_CPU1_P3_RX_DP<1>")
	)
	(segment
		(start 114.984022 -288.748978)
		(end 115.066826 -288.666174)
		(width 0.1143)
		(layer "In4.Cu")
		(net "P5E_CPU1_P3_RX_DP<1>")
	)
	(segment
		(start 116.059712 -380.169166)
		(end 109.798104 -373.90705)
		(width 0.14224)
		(layer "In4.Cu")
		(net "P5E_CPU1_P3_RX_DP<1>")
	)
	(segment
		(start 114.701574 -295.637204)
		(end 114.702336 -295.636696)
		(width 0.1143)
		(layer "In4.Cu")
		(net "P5E_CPU1_P3_RX_DP<1>")
	)
	(segment
		(start 116.491258 -386.003292)
		(end 116.586254 -385.649216)
		(width 0.14224)
		(layer "In4.Cu")
		(net "P5E_CPU1_P3_RX_DP<1>")
	)
	(segment
		(start 114.709702 -295.632632)
		(end 114.711988 -295.631108)
		(width 0.1143)
		(layer "In4.Cu")
		(net "P5E_CPU1_P3_RX_DP<1>")
	)
	(segment
		(start 114.70386 -289.155886)
		(end 114.706146 -289.154616)
		(width 0.1143)
		(layer "In4.Cu")
		(net "P5E_CPU1_P3_RX_DP<1>")
	)
	(segment
		(start 116.53266 -384.731006)
		(end 116.539518 -383.878582)
		(width 0.14224)
		(layer "In4.Cu")
		(net "P5E_CPU1_P3_RX_DP<1>")
	)
	(segment
		(start 116.840508 -383.577592)
		(end 116.840508 -382.642872)
		(width 0.14224)
		(layer "In4.Cu")
		(net "P5E_CPU1_P3_RX_DP<1>")
	)
	(segment
		(start 114.52098 -291.101272)
		(end 114.514376 -291.000942)
		(width 0.1143)
		(layer "In4.Cu")
		(net "P5E_CPU1_P3_RX_DP<1>")
	)
	(segment
		(start 114.71021 -293.040308)
		(end 114.708686 -293.039292)
		(width 0.1143)
		(layer "In4.Cu")
		(net "P5E_CPU1_P3_RX_DP<1>")
	)
	(segment
		(start 115.066826 -288.666174)
		(end 115.364768 -288.666174)
		(width 0.1143)
		(layer "In4.Cu")
		(net "P5E_CPU1_P3_RX_DP<1>")
	)
	(segment
		(start 114.514376 -291.000942)
		(end 114.508534 -290.996116)
		(width 0.1143)
		(layer "In4.Cu")
		(net "P5E_CPU1_P3_RX_DP<1>")
	)
	(segment
		(start 114.711988 -295.631108)
		(end 114.746024 -295.611296)
		(width 0.1143)
		(layer "In4.Cu")
		(net "P5E_CPU1_P3_RX_DP<1>")
	)
	(segment
		(start 116.848636 -385.046982)
		(end 116.53266 -384.731006)
		(width 0.14224)
		(layer "In4.Cu")
		(net "P5E_CPU1_P3_RX_DP<1>")
	)
	(segment
		(start 114.565684 -296.358564)
		(end 114.565684 -296.330116)
		(width 0.1143)
		(layer "In4.Cu")
		(net "P5E_CPU1_P3_RX_DP<1>")
	)
	(segment
		(start 114.708686 -294.659304)
		(end 114.70767 -294.658796)
		(width 0.1143)
		(layer "In4.Cu")
		(net "P5E_CPU1_P3_RX_DP<1>")
	)
	(segment
		(start 114.703352 -295.636188)
		(end 114.704114 -295.63568)
		(width 0.1143)
		(layer "In4.Cu")
		(net "P5E_CPU1_P3_RX_DP<1>")
	)
	(segment
		(start 126.464822 -316.167262)
		(end 117.949472 -305.792124)
		(width 0.14224)
		(layer "In4.Cu")
		(net "P5E_CPU1_P3_RX_DP<1>")
	)
	(segment
		(start 132.222748 -331.109066)
		(end 130.151378 -325.142352)
		(width 0.14224)
		(layer "In4.Cu")
		(net "P5E_CPU1_P3_RX_DP<1>")
	)
	(segment
		(start 114.70767 -292.393624)
		(end 114.745008 -292.372288)
		(width 0.1143)
		(layer "In4.Cu")
		(net "P5E_CPU1_P3_RX_DP<1>")
	)
	(segment
		(start 114.519964 -296.284396)
		(end 114.519964 -295.956228)
		(width 0.1143)
		(layer "In4.Cu")
		(net "P5E_CPU1_P3_RX_DP<1>")
	)
	(segment
		(start 117.949472 -305.792124)
		(end 116.301774 -303.325784)
		(width 0.14224)
		(layer "In4.Cu")
		(net "P5E_CPU1_P3_RX_DP<1>")
	)
	(segment
		(start 114.702336 -295.636696)
		(end 114.703352 -295.636188)
		(width 0.1143)
		(layer "In4.Cu")
		(net "P5E_CPU1_P3_RX_DP<1>")
	)
	(arc
		(start 116.621052 -381.219202)
		(mid 116.418226 -380.652572)
		(end 116.059712 -380.169166)
		(width 0.14224)
		(layer "In4.Cu")
		(net "P5E_CPU1_P3_RX_DP<1>")
	)
	(arc
		(start 108.896404 -372.080282)
		(mid 108.886302 -372.017823)
		(end 108.880656 -371.954806)
		(width 0.14224)
		(layer "In4.Cu")
		(net "P5E_CPU1_P3_RX_DP<1>")
	)
	(arc
		(start 114.67592 -293.020496)
		(mid 114.519992 -292.716204)
		(end 114.67592 -292.411912)
		(width 0.1143)
		(layer "In4.Cu")
		(net "P5E_CPU1_P3_RX_DP<1>")
	)
	(arc
		(start 133.377178 -349.749872)
		(mid 133.381026 -349.676765)
		(end 133.382258 -349.603568)
		(width 0.14224)
		(layer "In4.Cu")
		(net "P5E_CPU1_P3_RX_DP<1>")
	)
	(arc
		(start 114.674142 -291.397944)
		(mid 114.572961 -291.262257)
		(end 114.520726 -291.101272)
		(width 0.1143)
		(layer "In4.Cu")
		(net "P5E_CPU1_P3_RX_DP<1>")
	)
	(arc
		(start 114.515646 -289.481006)
		(mid 114.566094 -289.293172)
		(end 114.70386 -289.155886)
		(width 0.1143)
		(layer "In4.Cu")
		(net "P5E_CPU1_P3_RX_DP<1>")
	)
	(arc
		(start 109.70133 -373.799608)
		(mid 109.19413 -372.98898)
		(end 108.896404 -372.080282)
		(width 0.14224)
		(layer "In4.Cu")
		(net "P5E_CPU1_P3_RX_DP<1>")
	)
	(arc
		(start 114.758216 -295.60266)
		(mid 114.992637 -295.146222)
		(end 114.758216 -294.689784)
		(width 0.1143)
		(layer "In4.Cu")
		(net "P5E_CPU1_P3_RX_DP<1>")
	)
	(arc
		(start 114.508534 -290.996116)
		(mid 114.415921 -290.772555)
		(end 114.23777 -290.608766)
		(width 0.1143)
		(layer "In4.Cu")
		(net "P5E_CPU1_P3_RX_DP<1>")
	)
	(arc
		(start 131.88823 -354.343462)
		(mid 132.716144 -352.943488)
		(end 133.245098 -351.405444)
		(width 0.14224)
		(layer "In4.Cu")
		(net "P5E_CPU1_P3_RX_DP<1>")
	)
	(arc
		(start 114.20602 -290.590478)
		(mid 114.050092 -290.286186)
		(end 114.20602 -289.981894)
		(width 0.1143)
		(layer "In4.Cu")
		(net "P5E_CPU1_P3_RX_DP<1>")
	)
	(arc
		(start 114.519964 -295.956228)
		(mid 114.561219 -295.785257)
		(end 114.67592 -295.651936)
		(width 0.1143)
		(layer "In4.Cu")
		(net "P5E_CPU1_P3_RX_DP<1>")
	)
	(arc
		(start 114.758216 -292.362636)
		(mid 114.992637 -291.906198)
		(end 114.758216 -291.44976)
		(width 0.1143)
		(layer "In4.Cu")
		(net "P5E_CPU1_P3_RX_DP<1>")
	)
	(arc
		(start 108.880656 -371.954806)
		(mid 108.934267 -371.456328)
		(end 109.14253 -371.000274)
		(width 0.14224)
		(layer "In4.Cu")
		(net "P5E_CPU1_P3_RX_DP<1>")
	)
	(arc
		(start 114.746786 -293.990776)
		(mid 114.990113 -293.52621)
		(end 114.746786 -293.061644)
		(width 0.1143)
		(layer "In4.Cu")
		(net "P5E_CPU1_P3_RX_DP<1>")
	)
	(arc
		(start 111.227616 -367.87963)
		(mid 112.535739 -366.436396)
		(end 114.206528 -365.435134)
		(width 0.14224)
		(layer "In4.Cu")
		(net "P5E_CPU1_P3_RX_DP<1>")
	)
	(arc
		(start 114.67592 -294.640508)
		(mid 114.526823 -294.336216)
		(end 114.67592 -294.031924)
		(width 0.1143)
		(layer "In4.Cu")
		(net "P5E_CPU1_P3_RX_DP<1>")
	)
	(arc
		(start 109.798104 -373.90705)
		(mid 109.74831 -373.854596)
		(end 109.70133 -373.799608)
		(width 0.14224)
		(layer "In4.Cu")
		(net "P5E_CPU1_P3_RX_DP<1>")
	)
	(arc
		(start 114.746786 -289.13074)
		(mid 114.898773 -288.974232)
		(end 114.980212 -288.771838)
		(width 0.1143)
		(layer "In4.Cu")
		(net "P5E_CPU1_P3_RX_DP<1>")
	)
	(arc
		(start 133.245098 -351.405444)
		(mid 133.261414 -351.321249)
		(end 133.271006 -351.236026)
		(width 0.14224)
		(layer "In4.Cu")
		(net "P5E_CPU1_P3_RX_DP<1>")
	)
	(arc
		(start 114.980212 -288.771838)
		(mid 114.982235 -288.760428)
		(end 114.984022 -288.748978)
		(width 0.1143)
		(layer "In4.Cu")
		(net "P5E_CPU1_P3_RX_DP<1>")
	)
	(arc
		(start 114.618262 -299.261276)
		(mid 114.578966 -299.131913)
		(end 114.565684 -298.99737)
		(width 0.14224)
		(layer "In4.Cu")
		(net "P5E_CPU1_P3_RX_DP<1>")
	)
	(arc
		(start 131.725924 -354.497894)
		(mid 131.813789 -354.427732)
		(end 131.88823 -354.343462)
		(width 0.14224)
		(layer "In4.Cu")
		(net "P5E_CPU1_P3_RX_DP<1>")
	)
	(arc
		(start 117.176804 -364.204758)
		(mid 117.233891 -364.177773)
		(end 117.288056 -364.145322)
		(width 0.14224)
		(layer "In4.Cu")
		(net "P5E_CPU1_P3_RX_DP<1>")
	)
	(arc
		(start 114.238278 -289.963352)
		(mid 114.441326 -289.759489)
		(end 114.515646 -289.481514)
		(width 0.1143)
		(layer "In4.Cu")
		(net "P5E_CPU1_P3_RX_DP<1>")
	)
	(arc
		(start 116.840508 -382.642872)
		(mid 116.824768 -382.323196)
		(end 116.77777 -382.006602)
		(width 0.14224)
		(layer "In4.Cu")
		(net "P5E_CPU1_P3_RX_DP<1>")
	)
	(arc
		(start 114.681254 -291.403532)
		(mid 114.677681 -291.40076)
		(end 114.674142 -291.397944)
		(width 0.1143)
		(layer "In4.Cu")
		(net "P5E_CPU1_P3_RX_DP<1>")
	)
	(segment
		(start 125.707902 -285.970472)
		(end 126.174754 -286.23641)
		(width 0.12954)
		(layer "F.Cu")
		(net "P5E_CPU1_P3_RX_DP<15>")
	)
	(segment
		(start 132.770626 -386.003292)
		(end 133.291326 -386.003292)
		(width 0.127)
		(layer "F.Cu")
		(net "P5E_CPU1_P3_RX_DP<15>")
	)
	(segment
		(start 125.876812 -286.23641)
		(end 126.174754 -286.23641)
		(width 0.1143)
		(layer "In4.Cu")
		(net "P5E_CPU1_P3_RX_DP<15>")
	)
	(segment
		(start 145.074894 -327.481184)
		(end 140.543788 -313.887358)
		(width 0.14224)
		(layer "In4.Cu")
		(net "P5E_CPU1_P3_RX_DP<15>")
	)
	(segment
		(start 127.39243 -290.605718)
		(end 127.391668 -290.60521)
		(width 0.1143)
		(layer "In4.Cu")
		(net "P5E_CPU1_P3_RX_DP<15>")
	)
	(segment
		(start 133.386322 -385.649216)
		(end 133.648704 -385.497832)
		(width 0.14224)
		(layer "In4.Cu")
		(net "P5E_CPU1_P3_RX_DP<15>")
	)
	(segment
		(start 127.90678 -293.061644)
		(end 127.867664 -293.038784)
		(width 0.1143)
		(layer "In4.Cu")
		(net "P5E_CPU1_P3_RX_DP<15>")
	)
	(segment
		(start 127.391668 -290.60521)
		(end 127.389128 -290.60394)
		(width 0.1143)
		(layer "In4.Cu")
		(net "P5E_CPU1_P3_RX_DP<15>")
	)
	(segment
		(start 126.494286 -287.390078)
		(end 126.488698 -287.38703)
		(width 0.1143)
		(layer "In4.Cu")
		(net "P5E_CPU1_P3_RX_DP<15>")
	)
	(segment
		(start 125.806962 -286.30626)
		(end 125.876812 -286.23641)
		(width 0.1143)
		(layer "In4.Cu")
		(net "P5E_CPU1_P3_RX_DP<15>")
	)
	(segment
		(start 133.648704 -384.852418)
		(end 135.04418 -383.456942)
		(width 0.14224)
		(layer "In4.Cu")
		(net "P5E_CPU1_P3_RX_DP<15>")
	)
	(segment
		(start 127.67818 -296.086784)
		(end 127.67818 -295.926764)
		(width 0.1143)
		(layer "In4.Cu")
		(net "P5E_CPU1_P3_RX_DP<15>")
	)
	(segment
		(start 127.867664 -294.658796)
		(end 127.837184 -294.641016)
		(width 0.1143)
		(layer "In4.Cu")
		(net "P5E_CPU1_P3_RX_DP<15>")
	)
	(segment
		(start 127.867664 -292.393624)
		(end 127.90678 -292.370764)
		(width 0.1143)
		(layer "In4.Cu")
		(net "P5E_CPU1_P3_RX_DP<15>")
	)
	(segment
		(start 127.837184 -294.031416)
		(end 127.867664 -294.013636)
		(width 0.1143)
		(layer "In4.Cu")
		(net "P5E_CPU1_P3_RX_DP<15>")
	)
	(segment
		(start 129.526792 -299.189648)
		(end 128.153668 -297.135296)
		(width 0.14224)
		(layer "In4.Cu")
		(net "P5E_CPU1_P3_RX_DP<15>")
	)
	(segment
		(start 126.89713 -289.17138)
		(end 126.92761 -289.1536)
		(width 0.1143)
		(layer "In4.Cu")
		(net "P5E_CPU1_P3_RX_DP<15>")
	)
	(segment
		(start 146.958558 -358.983788)
		(end 146.958558 -337.96732)
		(width 0.14224)
		(layer "In4.Cu")
		(net "P5E_CPU1_P3_RX_DP<15>")
	)
	(segment
		(start 128.153668 -297.135296)
		(end 127.946404 -296.928032)
		(width 0.14224)
		(layer "In4.Cu")
		(net "P5E_CPU1_P3_RX_DP<15>")
	)
	(segment
		(start 127.909066 -296.837862)
		(end 127.909066 -296.612564)
		(width 0.14224)
		(layer "In4.Cu")
		(net "P5E_CPU1_P3_RX_DP<15>")
	)
	(segment
		(start 127.909066 -296.584116)
		(end 127.863346 -296.538396)
		(width 0.1143)
		(layer "In4.Cu")
		(net "P5E_CPU1_P3_RX_DP<15>")
	)
	(segment
		(start 141.19352 -369.103148)
		(end 144.995392 -364.47095)
		(width 0.14224)
		(layer "In4.Cu")
		(net "P5E_CPU1_P3_RX_DP<15>")
	)
	(segment
		(start 126.966726 -289.82162)
		(end 126.92761 -289.79876)
		(width 0.1143)
		(layer "In4.Cu")
		(net "P5E_CPU1_P3_RX_DP<15>")
	)
	(segment
		(start 146.958558 -337.96732)
		(end 145.074894 -327.481184)
		(width 0.14224)
		(layer "In4.Cu")
		(net "P5E_CPU1_P3_RX_DP<15>")
	)
	(segment
		(start 140.543788 -313.887358)
		(end 138.394948 -309.995824)
		(width 0.14224)
		(layer "In4.Cu")
		(net "P5E_CPU1_P3_RX_DP<15>")
	)
	(segment
		(start 141.131798 -370.893086)
		(end 141.131798 -369.275868)
		(width 0.14224)
		(layer "In4.Cu")
		(net "P5E_CPU1_P3_RX_DP<15>")
	)
	(segment
		(start 127.867664 -291.418772)
		(end 127.837184 -291.400992)
		(width 0.1143)
		(layer "In4.Cu")
		(net "P5E_CPU1_P3_RX_DP<15>")
	)
	(segment
		(start 127.867664 -293.038784)
		(end 127.837184 -293.021004)
		(width 0.1143)
		(layer "In4.Cu")
		(net "P5E_CPU1_P3_RX_DP<15>")
	)
	(segment
		(start 135.584692 -382.446022)
		(end 136.859518 -376.038364)
		(width 0.14224)
		(layer "In4.Cu")
		(net "P5E_CPU1_P3_RX_DP<15>")
	)
	(segment
		(start 127.39878 -290.609274)
		(end 127.397764 -290.608766)
		(width 0.1143)
		(layer "In4.Cu")
		(net "P5E_CPU1_P3_RX_DP<15>")
	)
	(segment
		(start 127.42926 -290.627054)
		(end 127.39878 -290.609274)
		(width 0.1143)
		(layer "In4.Cu")
		(net "P5E_CPU1_P3_RX_DP<15>")
	)
	(segment
		(start 127.90678 -291.441632)
		(end 127.867664 -291.418772)
		(width 0.1143)
		(layer "In4.Cu")
		(net "P5E_CPU1_P3_RX_DP<15>")
	)
	(segment
		(start 137.163556 -375.469404)
		(end 140.701776 -371.931184)
		(width 0.14224)
		(layer "In4.Cu")
		(net "P5E_CPU1_P3_RX_DP<15>")
	)
	(segment
		(start 127.770128 -296.23131)
		(end 127.715772 -296.176954)
		(width 0.1143)
		(layer "In4.Cu")
		(net "P5E_CPU1_P3_RX_DP<15>")
	)
	(segment
		(start 127.395732 -290.607496)
		(end 127.394208 -290.606734)
		(width 0.1143)
		(layer "In4.Cu")
		(net "P5E_CPU1_P3_RX_DP<15>")
	)
	(segment
		(start 127.397002 -290.608258)
		(end 127.395732 -290.607496)
		(width 0.1143)
		(layer "In4.Cu")
		(net "P5E_CPU1_P3_RX_DP<15>")
	)
	(segment
		(start 127.756412 -295.72839)
		(end 127.912114 -295.606978)
		(width 0.1143)
		(layer "In4.Cu")
		(net "P5E_CPU1_P3_RX_DP<15>")
	)
	(segment
		(start 127.389128 -290.60394)
		(end 127.366014 -290.590478)
		(width 0.1143)
		(layer "In4.Cu")
		(net "P5E_CPU1_P3_RX_DP<15>")
	)
	(segment
		(start 127.393446 -290.606226)
		(end 127.39243 -290.605718)
		(width 0.1143)
		(layer "In4.Cu")
		(net "P5E_CPU1_P3_RX_DP<15>")
	)
	(segment
		(start 126.92761 -288.178748)
		(end 126.895098 -288.159952)
		(width 0.1143)
		(layer "In4.Cu")
		(net "P5E_CPU1_P3_RX_DP<15>")
	)
	(segment
		(start 127.90678 -294.681656)
		(end 127.867664 -294.658796)
		(width 0.1143)
		(layer "In4.Cu")
		(net "P5E_CPU1_P3_RX_DP<15>")
	)
	(segment
		(start 127.837184 -292.411404)
		(end 127.867664 -292.393624)
		(width 0.1143)
		(layer "In4.Cu")
		(net "P5E_CPU1_P3_RX_DP<15>")
	)
	(segment
		(start 126.92761 -289.79876)
		(end 126.89713 -289.78098)
		(width 0.1143)
		(layer "In4.Cu")
		(net "P5E_CPU1_P3_RX_DP<15>")
	)
	(segment
		(start 125.99543 -286.563562)
		(end 125.95606 -286.540448)
		(width 0.1143)
		(layer "In4.Cu")
		(net "P5E_CPU1_P3_RX_DP<15>")
	)
	(segment
		(start 126.966726 -288.201608)
		(end 126.92761 -288.178748)
		(width 0.1143)
		(layer "In4.Cu")
		(net "P5E_CPU1_P3_RX_DP<15>")
	)
	(segment
		(start 126.488698 -287.38703)
		(end 126.450852 -287.365186)
		(width 0.1143)
		(layer "In4.Cu")
		(net "P5E_CPU1_P3_RX_DP<15>")
	)
	(segment
		(start 127.715772 -296.176954)
		(end 127.715772 -296.177208)
		(width 0.1143)
		(layer "In4.Cu")
		(net "P5E_CPU1_P3_RX_DP<15>")
	)
	(segment
		(start 127.863346 -296.538396)
		(end 127.863346 -296.4561)
		(width 0.1143)
		(layer "In4.Cu")
		(net "P5E_CPU1_P3_RX_DP<15>")
	)
	(segment
		(start 127.430022 -290.627562)
		(end 127.42926 -290.627054)
		(width 0.1143)
		(layer "In4.Cu")
		(net "P5E_CPU1_P3_RX_DP<15>")
	)
	(segment
		(start 126.92761 -289.1536)
		(end 126.966726 -289.13074)
		(width 0.1143)
		(layer "In4.Cu")
		(net "P5E_CPU1_P3_RX_DP<15>")
	)
	(segment
		(start 133.648704 -385.497832)
		(end 133.648704 -384.852418)
		(width 0.14224)
		(layer "In4.Cu")
		(net "P5E_CPU1_P3_RX_DP<15>")
	)
	(segment
		(start 127.867664 -294.013636)
		(end 127.90678 -293.990776)
		(width 0.1143)
		(layer "In4.Cu")
		(net "P5E_CPU1_P3_RX_DP<15>")
	)
	(segment
		(start 127.909066 -296.612564)
		(end 127.909066 -296.584116)
		(width 0.1143)
		(layer "In4.Cu")
		(net "P5E_CPU1_P3_RX_DP<15>")
	)
	(segment
		(start 127.394208 -290.606734)
		(end 127.393446 -290.606226)
		(width 0.1143)
		(layer "In4.Cu")
		(net "P5E_CPU1_P3_RX_DP<15>")
	)
	(segment
		(start 133.291326 -386.003292)
		(end 133.386322 -385.649216)
		(width 0.14224)
		(layer "In4.Cu")
		(net "P5E_CPU1_P3_RX_DP<15>")
	)
	(segment
		(start 127.397764 -290.608766)
		(end 127.397002 -290.608258)
		(width 0.1143)
		(layer "In4.Cu")
		(net "P5E_CPU1_P3_RX_DP<15>")
	)
	(segment
		(start 127.43688 -290.631626)
		(end 127.430022 -290.627562)
		(width 0.1143)
		(layer "In4.Cu")
		(net "P5E_CPU1_P3_RX_DP<15>")
	)
	(segment
		(start 138.394948 -309.995824)
		(end 129.526792 -299.189648)
		(width 0.14224)
		(layer "In4.Cu")
		(net "P5E_CPU1_P3_RX_DP<15>")
	)
	(arc
		(start 127.67818 -295.926764)
		(mid 127.698461 -295.820158)
		(end 127.756412 -295.72839)
		(width 0.1143)
		(layer "In4.Cu")
		(net "P5E_CPU1_P3_RX_DP<15>")
	)
	(arc
		(start 141.131798 -369.275868)
		(mid 141.147652 -369.184146)
		(end 141.19352 -369.103148)
		(width 0.14224)
		(layer "In4.Cu")
		(net "P5E_CPU1_P3_RX_DP<15>")
	)
	(arc
		(start 126.89713 -289.78098)
		(mid 126.740153 -289.47618)
		(end 126.89713 -289.17138)
		(width 0.1143)
		(layer "In4.Cu")
		(net "P5E_CPU1_P3_RX_DP<15>")
	)
	(arc
		(start 127.715772 -296.177208)
		(mid 127.687944 -296.13575)
		(end 127.67818 -296.086784)
		(width 0.1143)
		(layer "In4.Cu")
		(net "P5E_CPU1_P3_RX_DP<15>")
	)
	(arc
		(start 127.837184 -294.641016)
		(mid 127.680207 -294.336216)
		(end 127.837184 -294.031416)
		(width 0.1143)
		(layer "In4.Cu")
		(net "P5E_CPU1_P3_RX_DP<15>")
	)
	(arc
		(start 140.701776 -371.931184)
		(mid 141.020018 -371.454901)
		(end 141.131798 -370.893086)
		(width 0.14224)
		(layer "In4.Cu")
		(net "P5E_CPU1_P3_RX_DP<15>")
	)
	(arc
		(start 127.210058 -290.286186)
		(mid 127.145543 -290.023967)
		(end 126.966726 -289.82162)
		(width 0.1143)
		(layer "In4.Cu")
		(net "P5E_CPU1_P3_RX_DP<15>")
	)
	(arc
		(start 125.949964 -286.535876)
		(mid 125.857021 -286.434423)
		(end 125.806962 -286.30626)
		(width 0.1143)
		(layer "In4.Cu")
		(net "P5E_CPU1_P3_RX_DP<15>")
	)
	(arc
		(start 125.95606 -286.540448)
		(mid 125.953 -286.538177)
		(end 125.949964 -286.535876)
		(width 0.1143)
		(layer "In4.Cu")
		(net "P5E_CPU1_P3_RX_DP<15>")
	)
	(arc
		(start 127.837184 -291.400992)
		(mid 127.721757 -291.267616)
		(end 127.680212 -291.096192)
		(width 0.1143)
		(layer "In4.Cu")
		(net "P5E_CPU1_P3_RX_DP<15>")
	)
	(arc
		(start 126.450852 -287.365186)
		(mid 126.320124 -287.229484)
		(end 126.272544 -287.047178)
		(width 0.1143)
		(layer "In4.Cu")
		(net "P5E_CPU1_P3_RX_DP<15>")
	)
	(arc
		(start 126.895098 -288.159952)
		(mid 126.781169 -288.026805)
		(end 126.740158 -287.856422)
		(width 0.1143)
		(layer "In4.Cu")
		(net "P5E_CPU1_P3_RX_DP<15>")
	)
	(arc
		(start 135.04418 -383.456942)
		(mid 135.389405 -382.991566)
		(end 135.584692 -382.446022)
		(width 0.14224)
		(layer "In4.Cu")
		(net "P5E_CPU1_P3_RX_DP<15>")
	)
	(arc
		(start 144.995392 -364.47095)
		(mid 146.453064 -361.897703)
		(end 146.958558 -358.983788)
		(width 0.14224)
		(layer "In4.Cu")
		(net "P5E_CPU1_P3_RX_DP<15>")
	)
	(arc
		(start 127.863346 -296.4561)
		(mid 127.839056 -296.334457)
		(end 127.770128 -296.23131)
		(width 0.1143)
		(layer "In4.Cu")
		(net "P5E_CPU1_P3_RX_DP<15>")
	)
	(arc
		(start 127.837184 -293.021004)
		(mid 127.680207 -292.716204)
		(end 127.837184 -292.411404)
		(width 0.1143)
		(layer "In4.Cu")
		(net "P5E_CPU1_P3_RX_DP<15>")
	)
	(arc
		(start 127.680212 -291.096192)
		(mid 127.615697 -290.833973)
		(end 127.43688 -290.631626)
		(width 0.1143)
		(layer "In4.Cu")
		(net "P5E_CPU1_P3_RX_DP<15>")
	)
	(arc
		(start 127.90678 -292.370764)
		(mid 128.150107 -291.906198)
		(end 127.90678 -291.441632)
		(width 0.1143)
		(layer "In4.Cu")
		(net "P5E_CPU1_P3_RX_DP<15>")
	)
	(arc
		(start 127.91313 -295.606216)
		(mid 128.129945 -295.259406)
		(end 128.06299 -294.8559)
		(width 0.1143)
		(layer "In4.Cu")
		(net "P5E_CPU1_P3_RX_DP<15>")
	)
	(arc
		(start 136.859518 -376.038364)
		(mid 136.969352 -375.731345)
		(end 137.163556 -375.469404)
		(width 0.14224)
		(layer "In4.Cu")
		(net "P5E_CPU1_P3_RX_DP<15>")
	)
	(arc
		(start 126.740158 -287.856422)
		(mid 126.674922 -287.592831)
		(end 126.494286 -287.390078)
		(width 0.1143)
		(layer "In4.Cu")
		(net "P5E_CPU1_P3_RX_DP<15>")
	)
	(arc
		(start 127.912114 -295.606978)
		(mid 127.912622 -295.606597)
		(end 127.91313 -295.606216)
		(width 0.1143)
		(layer "In4.Cu")
		(net "P5E_CPU1_P3_RX_DP<15>")
	)
	(arc
		(start 127.90678 -293.990776)
		(mid 128.150107 -293.52621)
		(end 127.90678 -293.061644)
		(width 0.1143)
		(layer "In4.Cu")
		(net "P5E_CPU1_P3_RX_DP<15>")
	)
	(arc
		(start 127.946404 -296.928032)
		(mid 127.918761 -296.886662)
		(end 127.909066 -296.837862)
		(width 0.14224)
		(layer "In4.Cu")
		(net "P5E_CPU1_P3_RX_DP<15>")
	)
	(arc
		(start 126.966726 -289.13074)
		(mid 127.210053 -288.666174)
		(end 126.966726 -288.201608)
		(width 0.1143)
		(layer "In4.Cu")
		(net "P5E_CPU1_P3_RX_DP<15>")
	)
	(arc
		(start 126.272544 -287.047178)
		(mid 126.198432 -286.768427)
		(end 125.99543 -286.563562)
		(width 0.1143)
		(layer "In4.Cu")
		(net "P5E_CPU1_P3_RX_DP<15>")
	)
	(arc
		(start 127.366014 -290.590478)
		(mid 127.251338 -290.457144)
		(end 127.210058 -290.286186)
		(width 0.1143)
		(layer "In4.Cu")
		(net "P5E_CPU1_P3_RX_DP<15>")
	)
	(arc
		(start 128.06299 -294.8559)
		(mid 127.993787 -294.760799)
		(end 127.90678 -294.681656)
		(width 0.1143)
		(layer "In4.Cu")
		(net "P5E_CPU1_P3_RX_DP<15>")
	)
	(segment
		(start 131.570476 -386.003292)
		(end 132.091176 -386.003292)
		(width 0.127)
		(layer "F.Cu")
		(net "P5E_CPU1_P3_RX_DP<14>")
	)
	(segment
		(start 125.707902 -289.210242)
		(end 126.174754 -289.47618)
		(width 0.12954)
		(layer "F.Cu")
		(net "P5E_CPU1_P3_RX_DP<14>")
	)
	(segment
		(start 125.990604 -289.800538)
		(end 125.98781 -289.79876)
		(width 0.1143)
		(layer "In4.Cu")
		(net "P5E_CPU1_P3_RX_DP<14>")
	)
	(segment
		(start 126.45771 -290.608766)
		(end 126.456948 -290.608258)
		(width 0.1143)
		(layer "In4.Cu")
		(net "P5E_CPU1_P3_RX_DP<14>")
	)
	(segment
		(start 126.461266 -290.610798)
		(end 126.45771 -290.608766)
		(width 0.1143)
		(layer "In4.Cu")
		(net "P5E_CPU1_P3_RX_DP<14>")
	)
	(segment
		(start 126.465838 -290.613592)
		(end 126.465076 -290.613084)
		(width 0.1143)
		(layer "In4.Cu")
		(net "P5E_CPU1_P3_RX_DP<14>")
	)
	(segment
		(start 139.171934 -313.661044)
		(end 137.267442 -310.09717)
		(width 0.14224)
		(layer "In4.Cu")
		(net "P5E_CPU1_P3_RX_DP<14>")
	)
	(segment
		(start 137.267442 -310.09717)
		(end 128.095756 -298.922186)
		(width 0.14224)
		(layer "In4.Cu")
		(net "P5E_CPU1_P3_RX_DP<14>")
	)
	(segment
		(start 140.340842 -367.927636)
		(end 144.443196 -362.928916)
		(width 0.14224)
		(layer "In4.Cu")
		(net "P5E_CPU1_P3_RX_DP<14>")
	)
	(segment
		(start 132.448554 -385.046982)
		(end 132.132578 -384.731006)
		(width 0.14224)
		(layer "In4.Cu")
		(net "P5E_CPU1_P3_RX_DP<14>")
	)
	(segment
		(start 132.13461 -384.463544)
		(end 132.440426 -384.157728)
		(width 0.14224)
		(layer "In4.Cu")
		(net "P5E_CPU1_P3_RX_DP<14>")
	)
	(segment
		(start 126.785878 -296.372534)
		(end 126.740158 -296.326814)
		(width 0.1143)
		(layer "In4.Cu")
		(net "P5E_CPU1_P3_RX_DP<14>")
	)
	(segment
		(start 132.186172 -385.649216)
		(end 132.360416 -385.548632)
		(width 0.14224)
		(layer "In4.Cu")
		(net "P5E_CPU1_P3_RX_DP<14>")
	)
	(segment
		(start 136.057132 -374.381014)
		(end 139.371324 -371.066822)
		(width 0.14224)
		(layer "In4.Cu")
		(net "P5E_CPU1_P3_RX_DP<14>")
	)
	(segment
		(start 132.091176 -386.003292)
		(end 132.186172 -385.649216)
		(width 0.14224)
		(layer "In4.Cu")
		(net "P5E_CPU1_P3_RX_DP<14>")
	)
	(segment
		(start 132.132578 -384.731006)
		(end 132.13461 -384.463544)
		(width 0.14224)
		(layer "In4.Cu")
		(net "P5E_CPU1_P3_RX_DP<14>")
	)
	(segment
		(start 132.448554 -385.460494)
		(end 132.448554 -385.046982)
		(width 0.14224)
		(layer "In4.Cu")
		(net "P5E_CPU1_P3_RX_DP<14>")
	)
	(segment
		(start 126.496826 -290.631626)
		(end 126.489968 -290.627562)
		(width 0.1143)
		(layer "In4.Cu")
		(net "P5E_CPU1_P3_RX_DP<14>")
	)
	(segment
		(start 132.440426 -382.057656)
		(end 134.907782 -376.101102)
		(width 0.14224)
		(layer "In4.Cu")
		(net "P5E_CPU1_P3_RX_DP<14>")
	)
	(segment
		(start 132.360416 -385.548632)
		(end 132.448554 -385.460494)
		(width 0.14224)
		(layer "In4.Cu")
		(net "P5E_CPU1_P3_RX_DP<14>")
	)
	(segment
		(start 139.953746 -369.660932)
		(end 139.953746 -369.009676)
		(width 0.14224)
		(layer "In4.Cu")
		(net "P5E_CPU1_P3_RX_DP<14>")
	)
	(segment
		(start 127.092456 -297.428412)
		(end 126.823216 -296.778934)
		(width 0.14224)
		(layer "In4.Cu")
		(net "P5E_CPU1_P3_RX_DP<14>")
	)
	(segment
		(start 125.98781 -289.79876)
		(end 125.986794 -289.798252)
		(width 0.1143)
		(layer "In4.Cu")
		(net "P5E_CPU1_P3_RX_DP<14>")
	)
	(segment
		(start 126.489968 -290.627562)
		(end 126.489206 -290.627054)
		(width 0.1143)
		(layer "In4.Cu")
		(net "P5E_CPU1_P3_RX_DP<14>")
	)
	(segment
		(start 125.876812 -289.47618)
		(end 126.174754 -289.47618)
		(width 0.1143)
		(layer "In4.Cu")
		(net "P5E_CPU1_P3_RX_DP<14>")
	)
	(segment
		(start 126.489206 -290.627054)
		(end 126.465838 -290.613592)
		(width 0.1143)
		(layer "In4.Cu")
		(net "P5E_CPU1_P3_RX_DP<14>")
	)
	(segment
		(start 126.785878 -296.400982)
		(end 126.785878 -296.372534)
		(width 0.1143)
		(layer "In4.Cu")
		(net "P5E_CPU1_P3_RX_DP<14>")
	)
	(segment
		(start 126.740158 -296.326814)
		(end 126.740158 -295.956228)
		(width 0.1143)
		(layer "In4.Cu")
		(net "P5E_CPU1_P3_RX_DP<14>")
	)
	(segment
		(start 127.196596 -297.61815)
		(end 127.092456 -297.428412)
		(width 0.14224)
		(layer "In4.Cu")
		(net "P5E_CPU1_P3_RX_DP<14>")
	)
	(segment
		(start 126.966726 -293.061644)
		(end 126.89713 -293.021004)
		(width 0.1143)
		(layer "In4.Cu")
		(net "P5E_CPU1_P3_RX_DP<14>")
	)
	(segment
		(start 145.881344 -338.281264)
		(end 143.909034 -327.299828)
		(width 0.14224)
		(layer "In4.Cu")
		(net "P5E_CPU1_P3_RX_DP<14>")
	)
	(segment
		(start 125.986794 -289.798252)
		(end 125.95606 -289.780472)
		(width 0.1143)
		(layer "In4.Cu")
		(net "P5E_CPU1_P3_RX_DP<14>")
	)
	(segment
		(start 143.909034 -327.299828)
		(end 139.171934 -313.661044)
		(width 0.14224)
		(layer "In4.Cu")
		(net "P5E_CPU1_P3_RX_DP<14>")
	)
	(segment
		(start 132.440426 -384.157728)
		(end 132.440426 -382.057656)
		(width 0.14224)
		(layer "In4.Cu")
		(net "P5E_CPU1_P3_RX_DP<14>")
	)
	(segment
		(start 126.966726 -294.681656)
		(end 126.89713 -294.641016)
		(width 0.1143)
		(layer "In4.Cu")
		(net "P5E_CPU1_P3_RX_DP<14>")
	)
	(segment
		(start 128.095756 -298.922186)
		(end 127.196596 -297.61815)
		(width 0.14224)
		(layer "In4.Cu")
		(net "P5E_CPU1_P3_RX_DP<14>")
	)
	(segment
		(start 126.465076 -290.613084)
		(end 126.462028 -290.611306)
		(width 0.1143)
		(layer "In4.Cu")
		(net "P5E_CPU1_P3_RX_DP<14>")
	)
	(segment
		(start 126.966726 -291.441632)
		(end 126.89713 -291.400992)
		(width 0.1143)
		(layer "In4.Cu")
		(net "P5E_CPU1_P3_RX_DP<14>")
	)
	(segment
		(start 145.881344 -358.90962)
		(end 145.881344 -338.281264)
		(width 0.14224)
		(layer "In4.Cu")
		(net "P5E_CPU1_P3_RX_DP<14>")
	)
	(segment
		(start 125.806962 -289.54603)
		(end 125.876812 -289.47618)
		(width 0.1143)
		(layer "In4.Cu")
		(net "P5E_CPU1_P3_RX_DP<14>")
	)
	(segment
		(start 126.89713 -294.031416)
		(end 126.966726 -293.990776)
		(width 0.1143)
		(layer "In4.Cu")
		(net "P5E_CPU1_P3_RX_DP<14>")
	)
	(segment
		(start 126.89713 -292.411404)
		(end 126.966726 -292.370764)
		(width 0.1143)
		(layer "In4.Cu")
		(net "P5E_CPU1_P3_RX_DP<14>")
	)
	(segment
		(start 126.785878 -296.59072)
		(end 126.785878 -296.400982)
		(width 0.14224)
		(layer "In4.Cu")
		(net "P5E_CPU1_P3_RX_DP<14>")
	)
	(segment
		(start 126.462028 -290.611306)
		(end 126.461266 -290.610798)
		(width 0.1143)
		(layer "In4.Cu")
		(net "P5E_CPU1_P3_RX_DP<14>")
	)
	(segment
		(start 126.89713 -295.651428)
		(end 126.966726 -295.610788)
		(width 0.1143)
		(layer "In4.Cu")
		(net "P5E_CPU1_P3_RX_DP<14>")
	)
	(arc
		(start 125.95606 -289.780472)
		(mid 125.858925 -289.677603)
		(end 125.806962 -289.54603)
		(width 0.1143)
		(layer "In4.Cu")
		(net "P5E_CPU1_P3_RX_DP<14>")
	)
	(arc
		(start 126.89713 -294.641016)
		(mid 126.740153 -294.336216)
		(end 126.89713 -294.031416)
		(width 0.1143)
		(layer "In4.Cu")
		(net "P5E_CPU1_P3_RX_DP<14>")
	)
	(arc
		(start 126.740158 -291.096192)
		(mid 126.675643 -290.833973)
		(end 126.496826 -290.631626)
		(width 0.1143)
		(layer "In4.Cu")
		(net "P5E_CPU1_P3_RX_DP<14>")
	)
	(arc
		(start 126.89713 -291.400992)
		(mid 126.781703 -291.267616)
		(end 126.740158 -291.096192)
		(width 0.1143)
		(layer "In4.Cu")
		(net "P5E_CPU1_P3_RX_DP<14>")
	)
	(arc
		(start 139.953746 -369.009676)
		(mid 140.053432 -368.435077)
		(end 140.340842 -367.927636)
		(width 0.14224)
		(layer "In4.Cu")
		(net "P5E_CPU1_P3_RX_DP<14>")
	)
	(arc
		(start 126.966726 -292.370764)
		(mid 127.210053 -291.906198)
		(end 126.966726 -291.441632)
		(width 0.1143)
		(layer "In4.Cu")
		(net "P5E_CPU1_P3_RX_DP<14>")
	)
	(arc
		(start 139.371324 -371.066822)
		(mid 139.802372 -370.421808)
		(end 139.953746 -369.660932)
		(width 0.14224)
		(layer "In4.Cu")
		(net "P5E_CPU1_P3_RX_DP<14>")
	)
	(arc
		(start 144.443196 -362.928916)
		(mid 145.510992 -361.044043)
		(end 145.881344 -358.90962)
		(width 0.14224)
		(layer "In4.Cu")
		(net "P5E_CPU1_P3_RX_DP<14>")
	)
	(arc
		(start 126.966726 -295.610788)
		(mid 127.210053 -295.146222)
		(end 126.966726 -294.681656)
		(width 0.1143)
		(layer "In4.Cu")
		(net "P5E_CPU1_P3_RX_DP<14>")
	)
	(arc
		(start 126.966726 -293.990776)
		(mid 127.210053 -293.52621)
		(end 126.966726 -293.061644)
		(width 0.1143)
		(layer "In4.Cu")
		(net "P5E_CPU1_P3_RX_DP<14>")
	)
	(arc
		(start 126.456948 -290.608258)
		(mid 126.319546 -290.471425)
		(end 126.269242 -290.284154)
		(width 0.1143)
		(layer "In4.Cu")
		(net "P5E_CPU1_P3_RX_DP<14>")
	)
	(arc
		(start 134.907782 -376.101102)
		(mid 135.397773 -375.184476)
		(end 136.057132 -374.381014)
		(width 0.14224)
		(layer "In4.Cu")
		(net "P5E_CPU1_P3_RX_DP<14>")
	)
	(arc
		(start 126.269242 -290.284154)
		(mid 126.194603 -290.005077)
		(end 125.990604 -289.800538)
		(width 0.1143)
		(layer "In4.Cu")
		(net "P5E_CPU1_P3_RX_DP<14>")
	)
	(arc
		(start 126.740158 -295.956228)
		(mid 126.781707 -295.784806)
		(end 126.89713 -295.651428)
		(width 0.1143)
		(layer "In4.Cu")
		(net "P5E_CPU1_P3_RX_DP<14>")
	)
	(arc
		(start 126.823216 -296.778934)
		(mid 126.795291 -296.686664)
		(end 126.785878 -296.59072)
		(width 0.14224)
		(layer "In4.Cu")
		(net "P5E_CPU1_P3_RX_DP<14>")
	)
	(arc
		(start 126.89713 -293.021004)
		(mid 126.740153 -292.716204)
		(end 126.89713 -292.411404)
		(width 0.1143)
		(layer "In4.Cu")
		(net "P5E_CPU1_P3_RX_DP<14>")
	)
	(segment
		(start 130.37058 -386.003292)
		(end 130.89128 -386.003292)
		(width 0.127)
		(layer "F.Cu")
		(net "P5E_CPU1_P3_RX_DP<13>")
	)
	(segment
		(start 125.707902 -290.830254)
		(end 126.174754 -291.096192)
		(width 0.12954)
		(layer "F.Cu")
		(net "P5E_CPU1_P3_RX_DP<13>")
	)
	(segment
		(start 125.95606 -295.651936)
		(end 125.98781 -295.633648)
		(width 0.1143)
		(layer "In4.Cu")
		(net "P5E_CPU1_P3_RX_DP<13>")
	)
	(segment
		(start 125.800104 -296.27703)
		(end 125.800104 -295.956228)
		(width 0.1143)
		(layer "In4.Cu")
		(net "P5E_CPU1_P3_RX_DP<13>")
	)
	(segment
		(start 130.89128 -386.003292)
		(end 130.986276 -385.649216)
		(width 0.14224)
		(layer "In4.Cu")
		(net "P5E_CPU1_P3_RX_DP<13>")
	)
	(segment
		(start 125.98781 -294.658796)
		(end 125.95606 -294.640508)
		(width 0.1143)
		(layer "In4.Cu")
		(net "P5E_CPU1_P3_RX_DP<13>")
	)
	(segment
		(start 131.248658 -385.046982)
		(end 130.932682 -384.731006)
		(width 0.14224)
		(layer "In4.Cu")
		(net "P5E_CPU1_P3_RX_DP<13>")
	)
	(segment
		(start 125.876812 -291.096192)
		(end 126.174754 -291.096192)
		(width 0.1143)
		(layer "In4.Cu")
		(net "P5E_CPU1_P3_RX_DP<13>")
	)
	(segment
		(start 125.98781 -293.038784)
		(end 125.95606 -293.020496)
		(width 0.1143)
		(layer "In4.Cu")
		(net "P5E_CPU1_P3_RX_DP<13>")
	)
	(segment
		(start 125.98781 -294.013636)
		(end 125.988318 -294.013636)
		(width 0.1143)
		(layer "In4.Cu")
		(net "P5E_CPU1_P3_RX_DP<13>")
	)
	(segment
		(start 130.986276 -385.649216)
		(end 131.16052 -385.548632)
		(width 0.14224)
		(layer "In4.Cu")
		(net "P5E_CPU1_P3_RX_DP<13>")
	)
	(segment
		(start 131.248658 -385.460494)
		(end 131.248658 -385.046982)
		(width 0.14224)
		(layer "In4.Cu")
		(net "P5E_CPU1_P3_RX_DP<13>")
	)
	(segment
		(start 130.935222 -384.425698)
		(end 131.24053 -384.120644)
		(width 0.14224)
		(layer "In4.Cu")
		(net "P5E_CPU1_P3_RX_DP<13>")
	)
	(segment
		(start 131.16052 -385.548632)
		(end 131.248658 -385.460494)
		(width 0.14224)
		(layer "In4.Cu")
		(net "P5E_CPU1_P3_RX_DP<13>")
	)
	(segment
		(start 131.429252 -381.66167)
		(end 134.935468 -373.196612)
		(width 0.14224)
		(layer "In4.Cu")
		(net "P5E_CPU1_P3_RX_DP<13>")
	)
	(segment
		(start 138.941048 -366.445038)
		(end 143.46428 -361.921806)
		(width 0.14224)
		(layer "In4.Cu")
		(net "P5E_CPU1_P3_RX_DP<13>")
	)
	(segment
		(start 125.95606 -294.031924)
		(end 125.985778 -294.014906)
		(width 0.1143)
		(layer "In4.Cu")
		(net "P5E_CPU1_P3_RX_DP<13>")
	)
	(segment
		(start 130.932682 -384.731006)
		(end 130.935222 -384.425698)
		(width 0.14224)
		(layer "In4.Cu")
		(net "P5E_CPU1_P3_RX_DP<13>")
	)
	(segment
		(start 125.806962 -291.166042)
		(end 125.876812 -291.096192)
		(width 0.1143)
		(layer "In4.Cu")
		(net "P5E_CPU1_P3_RX_DP<13>")
	)
	(segment
		(start 135.855202 -371.822218)
		(end 137.317988 -370.359432)
		(width 0.14224)
		(layer "In4.Cu")
		(net "P5E_CPU1_P3_RX_DP<13>")
	)
	(segment
		(start 125.845824 -296.32275)
		(end 125.800104 -296.27703)
		(width 0.1143)
		(layer "In4.Cu")
		(net "P5E_CPU1_P3_RX_DP<13>")
	)
	(segment
		(start 125.987048 -294.014144)
		(end 125.98781 -294.013636)
		(width 0.1143)
		(layer "In4.Cu")
		(net "P5E_CPU1_P3_RX_DP<13>")
	)
	(segment
		(start 125.98781 -291.418772)
		(end 125.95606 -291.400484)
		(width 0.1143)
		(layer "In4.Cu")
		(net "P5E_CPU1_P3_RX_DP<13>")
	)
	(segment
		(start 125.985778 -294.014906)
		(end 125.987048 -294.014144)
		(width 0.1143)
		(layer "In4.Cu")
		(net "P5E_CPU1_P3_RX_DP<13>")
	)
	(segment
		(start 127.154432 -299.249338)
		(end 126.381256 -298.09186)
		(width 0.14224)
		(layer "In4.Cu")
		(net "P5E_CPU1_P3_RX_DP<13>")
	)
	(segment
		(start 125.95606 -292.411912)
		(end 125.98781 -292.393624)
		(width 0.1143)
		(layer "In4.Cu")
		(net "P5E_CPU1_P3_RX_DP<13>")
	)
	(segment
		(start 142.9385 -327.34758)
		(end 138.314684 -314.035694)
		(width 0.14224)
		(layer "In4.Cu")
		(net "P5E_CPU1_P3_RX_DP<13>")
	)
	(segment
		(start 131.24053 -384.120644)
		(end 131.24053 -382.609852)
		(width 0.14224)
		(layer "In4.Cu")
		(net "P5E_CPU1_P3_RX_DP<13>")
	)
	(segment
		(start 125.845824 -296.351198)
		(end 125.845824 -296.32275)
		(width 0.1143)
		(layer "In4.Cu")
		(net "P5E_CPU1_P3_RX_DP<13>")
	)
	(segment
		(start 136.49579 -310.632602)
		(end 127.154432 -299.249338)
		(width 0.14224)
		(layer "In4.Cu")
		(net "P5E_CPU1_P3_RX_DP<13>")
	)
	(segment
		(start 138.314684 -314.035694)
		(end 136.49579 -310.632602)
		(width 0.14224)
		(layer "In4.Cu")
		(net "P5E_CPU1_P3_RX_DP<13>")
	)
	(segment
		(start 144.761458 -358.789986)
		(end 144.761458 -337.495896)
		(width 0.14224)
		(layer "In4.Cu")
		(net "P5E_CPU1_P3_RX_DP<13>")
	)
	(segment
		(start 125.988318 -293.038784)
		(end 125.98781 -293.038784)
		(width 0.1143)
		(layer "In4.Cu")
		(net "P5E_CPU1_P3_RX_DP<13>")
	)
	(segment
		(start 126.260098 -297.865546)
		(end 125.894338 -296.982388)
		(width 0.14224)
		(layer "In4.Cu")
		(net "P5E_CPU1_P3_RX_DP<13>")
	)
	(segment
		(start 125.845824 -296.738802)
		(end 125.845824 -296.351198)
		(width 0.14224)
		(layer "In4.Cu")
		(net "P5E_CPU1_P3_RX_DP<13>")
	)
	(segment
		(start 144.761458 -337.495896)
		(end 142.9385 -327.34758)
		(width 0.14224)
		(layer "In4.Cu")
		(net "P5E_CPU1_P3_RX_DP<13>")
	)
	(arc
		(start 143.46428 -361.921806)
		(mid 144.424326 -360.484901)
		(end 144.761458 -358.789986)
		(width 0.14224)
		(layer "In4.Cu")
		(net "P5E_CPU1_P3_RX_DP<13>")
	)
	(arc
		(start 137.317988 -370.359432)
		(mid 137.754395 -369.697854)
		(end 137.915142 -368.921792)
		(width 0.14224)
		(layer "In4.Cu")
		(net "P5E_CPU1_P3_RX_DP<13>")
	)
	(arc
		(start 131.24053 -382.609852)
		(mid 131.288199 -382.126469)
		(end 131.429252 -381.66167)
		(width 0.14224)
		(layer "In4.Cu")
		(net "P5E_CPU1_P3_RX_DP<13>")
	)
	(arc
		(start 125.95606 -291.400484)
		(mid 125.858925 -291.297615)
		(end 125.806962 -291.166042)
		(width 0.1143)
		(layer "In4.Cu")
		(net "P5E_CPU1_P3_RX_DP<13>")
	)
	(arc
		(start 137.915142 -368.921792)
		(mid 138.181766 -367.581382)
		(end 138.941048 -366.445038)
		(width 0.14224)
		(layer "In4.Cu")
		(net "P5E_CPU1_P3_RX_DP<13>")
	)
	(arc
		(start 125.988318 -294.013636)
		(mid 126.268965 -293.52621)
		(end 125.988318 -293.038784)
		(width 0.1143)
		(layer "In4.Cu")
		(net "P5E_CPU1_P3_RX_DP<13>")
	)
	(arc
		(start 134.935468 -373.196612)
		(mid 135.327943 -372.46432)
		(end 135.855202 -371.822218)
		(width 0.14224)
		(layer "In4.Cu")
		(net "P5E_CPU1_P3_RX_DP<13>")
	)
	(arc
		(start 125.894338 -296.982388)
		(mid 125.858099 -296.862983)
		(end 125.845824 -296.738802)
		(width 0.14224)
		(layer "In4.Cu")
		(net "P5E_CPU1_P3_RX_DP<13>")
	)
	(arc
		(start 125.95606 -293.020496)
		(mid 125.800132 -292.716204)
		(end 125.95606 -292.411912)
		(width 0.1143)
		(layer "In4.Cu")
		(net "P5E_CPU1_P3_RX_DP<13>")
	)
	(arc
		(start 126.381256 -298.09186)
		(mid 126.315125 -297.981675)
		(end 126.260098 -297.865546)
		(width 0.14224)
		(layer "In4.Cu")
		(net "P5E_CPU1_P3_RX_DP<13>")
	)
	(arc
		(start 125.800104 -295.956228)
		(mid 125.841359 -295.785257)
		(end 125.95606 -295.651936)
		(width 0.1143)
		(layer "In4.Cu")
		(net "P5E_CPU1_P3_RX_DP<13>")
	)
	(arc
		(start 125.98781 -295.633648)
		(mid 126.268457 -295.146222)
		(end 125.98781 -294.658796)
		(width 0.1143)
		(layer "In4.Cu")
		(net "P5E_CPU1_P3_RX_DP<13>")
	)
	(arc
		(start 125.98781 -292.393624)
		(mid 126.268457 -291.906198)
		(end 125.98781 -291.418772)
		(width 0.1143)
		(layer "In4.Cu")
		(net "P5E_CPU1_P3_RX_DP<13>")
	)
	(arc
		(start 125.95606 -294.640508)
		(mid 125.800132 -294.336216)
		(end 125.95606 -294.031924)
		(width 0.1143)
		(layer "In4.Cu")
		(net "P5E_CPU1_P3_RX_DP<13>")
	)
	(segment
		(start 125.707902 -287.590484)
		(end 126.174754 -287.856422)
		(width 0.12954)
		(layer "F.Cu")
		(net "P5E_CPU1_P3_RX_DP<12>")
	)
	(segment
		(start 129.17043 -386.003292)
		(end 129.69113 -386.003292)
		(width 0.127)
		(layer "F.Cu")
		(net "P5E_CPU1_P3_RX_DP<12>")
	)
	(segment
		(start 135.70839 -311.154826)
		(end 126.354586 -299.755814)
		(width 0.14224)
		(layer "In4.Cu")
		(net "P5E_CPU1_P3_RX_DP<12>")
	)
	(segment
		(start 125.054614 -291.422836)
		(end 125.050042 -291.420042)
		(width 0.1143)
		(layer "In4.Cu")
		(net "P5E_CPU1_P3_RX_DP<12>")
	)
	(segment
		(start 125.038358 -294.01897)
		(end 125.039882 -294.018208)
		(width 0.1143)
		(layer "In4.Cu")
		(net "P5E_CPU1_P3_RX_DP<12>")
	)
	(segment
		(start 125.061726 -289.145726)
		(end 125.086872 -289.130994)
		(width 0.1143)
		(layer "In4.Cu")
		(net "P5E_CPU1_P3_RX_DP<12>")
	)
	(segment
		(start 125.043438 -294.016176)
		(end 125.0442 -294.015668)
		(width 0.1143)
		(layer "In4.Cu")
		(net "P5E_CPU1_P3_RX_DP<12>")
	)
	(segment
		(start 125.034294 -294.649652)
		(end 125.012704 -294.637206)
		(width 0.1143)
		(layer "In4.Cu")
		(net "P5E_CPU1_P3_RX_DP<12>")
	)
	(segment
		(start 125.043692 -291.416486)
		(end 125.042676 -291.415978)
		(width 0.1143)
		(layer "In4.Cu")
		(net "P5E_CPU1_P3_RX_DP<12>")
	)
	(segment
		(start 125.052074 -289.151314)
		(end 125.053344 -289.150552)
		(width 0.1143)
		(layer "In4.Cu")
		(net "P5E_CPU1_P3_RX_DP<12>")
	)
	(segment
		(start 125.330204 -295.14673)
		(end 125.330204 -295.146222)
		(width 0.1143)
		(layer "In4.Cu")
		(net "P5E_CPU1_P3_RX_DP<12>")
	)
	(segment
		(start 125.794008 -287.939226)
		(end 125.876812 -287.856422)
		(width 0.1143)
		(layer "In4.Cu")
		(net "P5E_CPU1_P3_RX_DP<12>")
	)
	(segment
		(start 125.021086 -292.408864)
		(end 125.034548 -292.401244)
		(width 0.1143)
		(layer "In4.Cu")
		(net "P5E_CPU1_P3_RX_DP<12>")
	)
	(segment
		(start 125.046994 -294.014144)
		(end 125.047756 -294.013636)
		(width 0.1143)
		(layer "In4.Cu")
		(net "P5E_CPU1_P3_RX_DP<12>")
	)
	(segment
		(start 124.905516 -296.411396)
		(end 124.859796 -296.365676)
		(width 0.1143)
		(layer "In4.Cu")
		(net "P5E_CPU1_P3_RX_DP<12>")
	)
	(segment
		(start 142.004288 -327.501504)
		(end 137.47369 -314.45708)
		(width 0.14224)
		(layer "In4.Cu")
		(net "P5E_CPU1_P3_RX_DP<12>")
	)
	(segment
		(start 129.96037 -385.548632)
		(end 130.048508 -385.460494)
		(width 0.14224)
		(layer "In4.Cu")
		(net "P5E_CPU1_P3_RX_DP<12>")
	)
	(segment
		(start 130.048508 -385.046982)
		(end 129.732532 -384.731006)
		(width 0.14224)
		(layer "In4.Cu")
		(net "P5E_CPU1_P3_RX_DP<12>")
	)
	(segment
		(start 125.041152 -289.15741)
		(end 125.041914 -289.156902)
		(width 0.1143)
		(layer "In4.Cu")
		(net "P5E_CPU1_P3_RX_DP<12>")
	)
	(segment
		(start 143.644112 -358.653334)
		(end 143.644112 -336.631534)
		(width 0.14224)
		(layer "In4.Cu")
		(net "P5E_CPU1_P3_RX_DP<12>")
	)
	(segment
		(start 125.039882 -289.158172)
		(end 125.041152 -289.15741)
		(width 0.1143)
		(layer "In4.Cu")
		(net "P5E_CPU1_P3_RX_DP<12>")
	)
	(segment
		(start 125.054106 -292.389814)
		(end 125.086872 -292.370764)
		(width 0.1143)
		(layer "In4.Cu")
		(net "P5E_CPU1_P3_RX_DP<12>")
	)
	(segment
		(start 125.086872 -294.681656)
		(end 125.051312 -294.660828)
		(width 0.1143)
		(layer "In4.Cu")
		(net "P5E_CPU1_P3_RX_DP<12>")
	)
	(segment
		(start 124.538232 -289.974274)
		(end 124.593096 -289.942016)
		(width 0.1143)
		(layer "In4.Cu")
		(net "P5E_CPU1_P3_RX_DP<12>")
	)
	(segment
		(start 124.905516 -296.439844)
		(end 124.905516 -296.411396)
		(width 0.1143)
		(layer "In4.Cu")
		(net "P5E_CPU1_P3_RX_DP<12>")
	)
	(segment
		(start 125.034548 -294.021256)
		(end 125.036326 -294.02024)
		(width 0.1143)
		(layer "In4.Cu")
		(net "P5E_CPU1_P3_RX_DP<12>")
	)
	(segment
		(start 125.040136 -292.39845)
		(end 125.054106 -292.389814)
		(width 0.1143)
		(layer "In4.Cu")
		(net "P5E_CPU1_P3_RX_DP<12>")
	)
	(segment
		(start 125.043438 -289.15614)
		(end 125.0442 -289.155632)
		(width 0.1143)
		(layer "In4.Cu")
		(net "P5E_CPU1_P3_RX_DP<12>")
	)
	(segment
		(start 129.69113 -386.003292)
		(end 129.786126 -385.649216)
		(width 0.14224)
		(layer "In4.Cu")
		(net "P5E_CPU1_P3_RX_DP<12>")
	)
	(segment
		(start 125.050296 -293.040308)
		(end 125.016006 -293.020496)
		(width 0.1143)
		(layer "In4.Cu")
		(net "P5E_CPU1_P3_RX_DP<12>")
	)
	(segment
		(start 125.012704 -294.028622)
		(end 125.012958 -294.028368)
		(width 0.1143)
		(layer "In4.Cu")
		(net "P5E_CPU1_P3_RX_DP<12>")
	)
	(segment
		(start 129.732532 -384.731006)
		(end 129.73558 -384.370326)
		(width 0.14224)
		(layer "In4.Cu")
		(net "P5E_CPU1_P3_RX_DP<12>")
	)
	(segment
		(start 125.048772 -294.013128)
		(end 125.050296 -294.012112)
		(width 0.1143)
		(layer "In4.Cu")
		(net "P5E_CPU1_P3_RX_DP<12>")
	)
	(segment
		(start 125.01626 -289.171888)
		(end 125.037596 -289.159442)
		(width 0.1143)
		(layer "In4.Cu")
		(net "P5E_CPU1_P3_RX_DP<12>")
	)
	(segment
		(start 125.053344 -294.010334)
		(end 125.054106 -294.009826)
		(width 0.1143)
		(layer "In4.Cu")
		(net "P5E_CPU1_P3_RX_DP<12>")
	)
	(segment
		(start 125.041914 -294.016938)
		(end 125.043438 -294.016176)
		(width 0.1143)
		(layer "In4.Cu")
		(net "P5E_CPU1_P3_RX_DP<12>")
	)
	(segment
		(start 125.039882 -294.018208)
		(end 125.041152 -294.017446)
		(width 0.1143)
		(layer "In4.Cu")
		(net "P5E_CPU1_P3_RX_DP<12>")
	)
	(segment
		(start 129.73558 -384.370326)
		(end 130.04038 -384.065526)
		(width 0.14224)
		(layer "In4.Cu")
		(net "P5E_CPU1_P3_RX_DP<12>")
	)
	(segment
		(start 125.036326 -294.02024)
		(end 125.037596 -294.019478)
		(width 0.1143)
		(layer "In4.Cu")
		(net "P5E_CPU1_P3_RX_DP<12>")
	)
	(segment
		(start 129.786126 -385.649216)
		(end 129.96037 -385.548632)
		(width 0.14224)
		(layer "In4.Cu")
		(net "P5E_CPU1_P3_RX_DP<12>")
	)
	(segment
		(start 125.050296 -294.66032)
		(end 125.034294 -294.649652)
		(width 0.1143)
		(layer "In4.Cu")
		(net "P5E_CPU1_P3_RX_DP<12>")
	)
	(segment
		(start 125.490224 -298.462446)
		(end 124.953014 -297.166538)
		(width 0.14224)
		(layer "In4.Cu")
		(net "P5E_CPU1_P3_RX_DP<12>")
	)
	(segment
		(start 125.051312 -294.660828)
		(end 125.050296 -294.66032)
		(width 0.1143)
		(layer "In4.Cu")
		(net "P5E_CPU1_P3_RX_DP<12>")
	)
	(segment
		(start 125.012958 -294.028368)
		(end 125.034548 -294.021256)
		(width 0.1143)
		(layer "In4.Cu")
		(net "P5E_CPU1_P3_RX_DP<12>")
	)
	(segment
		(start 138.218926 -364.086394)
		(end 138.218672 -364.086394)
		(width 0.14224)
		(layer "In4.Cu")
		(net "P5E_CPU1_P3_RX_DP<12>")
	)
	(segment
		(start 125.054106 -294.009826)
		(end 125.086872 -293.990776)
		(width 0.1143)
		(layer "In4.Cu")
		(net "P5E_CPU1_P3_RX_DP<12>")
	)
	(segment
		(start 134.513066 -368.313208)
		(end 134.51332 -368.313462)
		(width 0.14224)
		(layer "In4.Cu")
		(net "P5E_CPU1_P3_RX_DP<12>")
	)
	(segment
		(start 125.048772 -291.419534)
		(end 125.043692 -291.416486)
		(width 0.1143)
		(layer "In4.Cu")
		(net "P5E_CPU1_P3_RX_DP<12>")
	)
	(segment
		(start 125.0442 -289.155632)
		(end 125.046994 -289.154108)
		(width 0.1143)
		(layer "In4.Cu")
		(net "P5E_CPU1_P3_RX_DP<12>")
	)
	(segment
		(start 130.04038 -384.065526)
		(end 130.04038 -382.597914)
		(width 0.14224)
		(layer "In4.Cu")
		(net "P5E_CPU1_P3_RX_DP<12>")
	)
	(segment
		(start 143.644112 -336.631534)
		(end 142.004288 -327.501504)
		(width 0.14224)
		(layer "In4.Cu")
		(net "P5E_CPU1_P3_RX_DP<12>")
	)
	(segment
		(start 124.616718 -290.631626)
		(end 124.566934 -290.60267)
		(width 0.1143)
		(layer "In4.Cu")
		(net "P5E_CPU1_P3_RX_DP<12>")
	)
	(segment
		(start 125.49886 -288.35477)
		(end 125.556772 -288.320988)
		(width 0.1143)
		(layer "In4.Cu")
		(net "P5E_CPU1_P3_RX_DP<12>")
	)
	(segment
		(start 124.859796 -296.365676)
		(end 124.859796 -295.956228)
		(width 0.1143)
		(layer "In4.Cu")
		(net "P5E_CPU1_P3_RX_DP<12>")
	)
	(segment
		(start 125.015752 -295.651936)
		(end 125.088142 -295.609772)
		(width 0.1143)
		(layer "In4.Cu")
		(net "P5E_CPU1_P3_RX_DP<12>")
	)
	(segment
		(start 125.038358 -289.158934)
		(end 125.039882 -289.158172)
		(width 0.1143)
		(layer "In4.Cu")
		(net "P5E_CPU1_P3_RX_DP<12>")
	)
	(segment
		(start 125.053344 -289.150552)
		(end 125.054868 -289.149536)
		(width 0.1143)
		(layer "In4.Cu")
		(net "P5E_CPU1_P3_RX_DP<12>")
	)
	(segment
		(start 125.050296 -289.15233)
		(end 125.052074 -289.151314)
		(width 0.1143)
		(layer "In4.Cu")
		(net "P5E_CPU1_P3_RX_DP<12>")
	)
	(segment
		(start 125.086872 -291.441632)
		(end 125.054614 -291.422836)
		(width 0.1143)
		(layer "In4.Cu")
		(net "P5E_CPU1_P3_RX_DP<12>")
	)
	(segment
		(start 125.041152 -294.017446)
		(end 125.041914 -294.016938)
		(width 0.1143)
		(layer "In4.Cu")
		(net "P5E_CPU1_P3_RX_DP<12>")
	)
	(segment
		(start 134.533386 -368.189256)
		(end 134.65302 -367.833402)
		(width 0.14224)
		(layer "In4.Cu")
		(net "P5E_CPU1_P3_RX_DP<12>")
	)
	(segment
		(start 125.046994 -289.154108)
		(end 125.047756 -289.1536)
		(width 0.1143)
		(layer "In4.Cu")
		(net "P5E_CPU1_P3_RX_DP<12>")
	)
	(segment
		(start 125.052074 -294.011096)
		(end 125.053344 -294.010334)
		(width 0.1143)
		(layer "In4.Cu")
		(net "P5E_CPU1_P3_RX_DP<12>")
	)
	(segment
		(start 125.042676 -291.415978)
		(end 125.041152 -291.414962)
		(width 0.1143)
		(layer "In4.Cu")
		(net "P5E_CPU1_P3_RX_DP<12>")
	)
	(segment
		(start 138.320526 -364.010448)
		(end 142.147544 -361.45343)
		(width 0.14224)
		(layer "In4.Cu")
		(net "P5E_CPU1_P3_RX_DP<12>")
	)
	(segment
		(start 125.037596 -294.019478)
		(end 125.038358 -294.01897)
		(width 0.1143)
		(layer "In4.Cu")
		(net "P5E_CPU1_P3_RX_DP<12>")
	)
	(segment
		(start 126.354586 -299.755814)
		(end 125.490224 -298.462446)
		(width 0.14224)
		(layer "In4.Cu")
		(net "P5E_CPU1_P3_RX_DP<12>")
	)
	(segment
		(start 125.086872 -293.061644)
		(end 125.050296 -293.040308)
		(width 0.1143)
		(layer "In4.Cu")
		(net "P5E_CPU1_P3_RX_DP<12>")
	)
	(segment
		(start 125.041914 -289.156902)
		(end 125.043438 -289.15614)
		(width 0.1143)
		(layer "In4.Cu")
		(net "P5E_CPU1_P3_RX_DP<12>")
	)
	(segment
		(start 125.0442 -294.015668)
		(end 125.046994 -294.014144)
		(width 0.1143)
		(layer "In4.Cu")
		(net "P5E_CPU1_P3_RX_DP<12>")
	)
	(segment
		(start 125.054868 -289.149536)
		(end 125.061726 -289.145726)
		(width 0.1143)
		(layer "In4.Cu")
		(net "P5E_CPU1_P3_RX_DP<12>")
	)
	(segment
		(start 137.47369 -314.45708)
		(end 135.70839 -311.154826)
		(width 0.14224)
		(layer "In4.Cu")
		(net "P5E_CPU1_P3_RX_DP<12>")
	)
	(segment
		(start 125.047756 -289.1536)
		(end 125.050296 -289.15233)
		(width 0.1143)
		(layer "In4.Cu")
		(net "P5E_CPU1_P3_RX_DP<12>")
	)
	(segment
		(start 125.016006 -292.411912)
		(end 125.021086 -292.408864)
		(width 0.1143)
		(layer "In4.Cu")
		(net "P5E_CPU1_P3_RX_DP<12>")
	)
	(segment
		(start 125.050296 -294.012112)
		(end 125.052074 -294.011096)
		(width 0.1143)
		(layer "In4.Cu")
		(net "P5E_CPU1_P3_RX_DP<12>")
	)
	(segment
		(start 125.034548 -292.401244)
		(end 125.040136 -292.39845)
		(width 0.1143)
		(layer "In4.Cu")
		(net "P5E_CPU1_P3_RX_DP<12>")
	)
	(segment
		(start 125.876812 -287.856422)
		(end 126.174754 -287.856422)
		(width 0.1143)
		(layer "In4.Cu")
		(net "P5E_CPU1_P3_RX_DP<12>")
	)
	(segment
		(start 134.513066 -368.796824)
		(end 134.513066 -368.313208)
		(width 0.14224)
		(layer "In4.Cu")
		(net "P5E_CPU1_P3_RX_DP<12>")
	)
	(segment
		(start 125.047756 -294.013636)
		(end 125.048772 -294.013128)
		(width 0.1143)
		(layer "In4.Cu")
		(net "P5E_CPU1_P3_RX_DP<12>")
	)
	(segment
		(start 130.048508 -385.460494)
		(end 130.048508 -385.046982)
		(width 0.14224)
		(layer "In4.Cu")
		(net "P5E_CPU1_P3_RX_DP<12>")
	)
	(segment
		(start 130.04038 -382.597914)
		(end 130.040634 -382.598168)
		(width 0.14224)
		(layer "In4.Cu")
		(net "P5E_CPU1_P3_RX_DP<12>")
	)
	(segment
		(start 125.050042 -291.420042)
		(end 125.048772 -291.419534)
		(width 0.1143)
		(layer "In4.Cu")
		(net "P5E_CPU1_P3_RX_DP<12>")
	)
	(segment
		(start 125.037596 -289.159442)
		(end 125.038358 -289.158934)
		(width 0.1143)
		(layer "In4.Cu")
		(net "P5E_CPU1_P3_RX_DP<12>")
	)
	(segment
		(start 124.905516 -296.928032)
		(end 124.905516 -296.439844)
		(width 0.14224)
		(layer "In4.Cu")
		(net "P5E_CPU1_P3_RX_DP<12>")
	)
	(segment
		(start 130.200908 -381.791464)
		(end 133.524752 -373.766842)
		(width 0.14224)
		(layer "In4.Cu")
		(net "P5E_CPU1_P3_RX_DP<12>")
	)
	(arc
		(start 125.556772 -288.320988)
		(mid 125.708759 -288.16448)
		(end 125.790198 -287.962086)
		(width 0.1143)
		(layer "In4.Cu")
		(net "P5E_CPU1_P3_RX_DP<12>")
	)
	(arc
		(start 134.712456 -367.721642)
		(mid 136.206112 -365.973142)
		(end 137.867898 -364.383574)
		(width 0.14224)
		(layer "In4.Cu")
		(net "P5E_CPU1_P3_RX_DP<12>")
	)
	(arc
		(start 125.086872 -292.370764)
		(mid 125.330199 -291.906198)
		(end 125.086872 -291.441632)
		(width 0.1143)
		(layer "In4.Cu")
		(net "P5E_CPU1_P3_RX_DP<12>")
	)
	(arc
		(start 142.147544 -361.45343)
		(mid 143.246499 -360.240805)
		(end 143.644112 -358.653334)
		(width 0.14224)
		(layer "In4.Cu")
		(net "P5E_CPU1_P3_RX_DP<12>")
	)
	(arc
		(start 134.51332 -368.313462)
		(mid 134.518299 -368.250541)
		(end 134.533386 -368.189256)
		(width 0.14224)
		(layer "In4.Cu")
		(net "P5E_CPU1_P3_RX_DP<12>")
	)
	(arc
		(start 125.790198 -287.962086)
		(mid 125.792221 -287.950676)
		(end 125.794008 -287.939226)
		(width 0.1143)
		(layer "In4.Cu")
		(net "P5E_CPU1_P3_RX_DP<12>")
	)
	(arc
		(start 125.041152 -291.414962)
		(mid 124.910138 -291.271928)
		(end 124.86005 -291.084508)
		(width 0.1143)
		(layer "In4.Cu")
		(net "P5E_CPU1_P3_RX_DP<12>")
	)
	(arc
		(start 137.867898 -364.383574)
		(mid 138.042664 -364.234101)
		(end 138.218926 -364.086394)
		(width 0.14224)
		(layer "In4.Cu")
		(net "P5E_CPU1_P3_RX_DP<12>")
	)
	(arc
		(start 124.566934 -290.60267)
		(mid 124.381442 -290.296233)
		(end 124.538232 -289.974274)
		(width 0.1143)
		(layer "In4.Cu")
		(net "P5E_CPU1_P3_RX_DP<12>")
	)
	(arc
		(start 124.859796 -295.956228)
		(mid 124.904384 -295.786963)
		(end 125.015752 -295.651936)
		(width 0.1143)
		(layer "In4.Cu")
		(net "P5E_CPU1_P3_RX_DP<12>")
	)
	(arc
		(start 134.65302 -367.833402)
		(mid 134.678075 -367.775041)
		(end 134.712456 -367.721642)
		(width 0.14224)
		(layer "In4.Cu")
		(net "P5E_CPU1_P3_RX_DP<12>")
	)
	(arc
		(start 133.524752 -373.766842)
		(mid 134.263673 -371.330505)
		(end 134.513066 -368.796824)
		(width 0.14224)
		(layer "In4.Cu")
		(net "P5E_CPU1_P3_RX_DP<12>")
	)
	(arc
		(start 125.012704 -294.637206)
		(mid 124.856776 -294.332914)
		(end 125.012704 -294.028622)
		(width 0.1143)
		(layer "In4.Cu")
		(net "P5E_CPU1_P3_RX_DP<12>")
	)
	(arc
		(start 124.860304 -289.47618)
		(mid 124.901559 -289.305209)
		(end 125.01626 -289.171888)
		(width 0.1143)
		(layer "In4.Cu")
		(net "P5E_CPU1_P3_RX_DP<12>")
	)
	(arc
		(start 124.86005 -291.084508)
		(mid 124.792905 -290.828756)
		(end 124.616718 -290.631626)
		(width 0.1143)
		(layer "In4.Cu")
		(net "P5E_CPU1_P3_RX_DP<12>")
	)
	(arc
		(start 125.086872 -289.130994)
		(mid 125.265685 -288.928644)
		(end 125.330204 -288.666428)
		(width 0.1143)
		(layer "In4.Cu")
		(net "P5E_CPU1_P3_RX_DP<12>")
	)
	(arc
		(start 124.953014 -297.166538)
		(mid 124.917505 -297.049627)
		(end 124.905516 -296.928032)
		(width 0.14224)
		(layer "In4.Cu")
		(net "P5E_CPU1_P3_RX_DP<12>")
	)
	(arc
		(start 130.040634 -382.598168)
		(mid 130.081038 -382.186921)
		(end 130.200908 -381.791464)
		(width 0.14224)
		(layer "In4.Cu")
		(net "P5E_CPU1_P3_RX_DP<12>")
	)
	(arc
		(start 124.593096 -289.942016)
		(mid 124.788729 -289.744685)
		(end 124.860304 -289.47618)
		(width 0.1143)
		(layer "In4.Cu")
		(net "P5E_CPU1_P3_RX_DP<12>")
	)
	(arc
		(start 125.330204 -295.146222)
		(mid 125.265689 -294.884003)
		(end 125.086872 -294.681656)
		(width 0.1143)
		(layer "In4.Cu")
		(net "P5E_CPU1_P3_RX_DP<12>")
	)
	(arc
		(start 125.016006 -293.020496)
		(mid 124.860078 -292.716204)
		(end 125.016006 -292.411912)
		(width 0.1143)
		(layer "In4.Cu")
		(net "P5E_CPU1_P3_RX_DP<12>")
	)
	(arc
		(start 138.218672 -364.086394)
		(mid 138.268616 -364.047103)
		(end 138.320526 -364.010448)
		(width 0.14224)
		(layer "In4.Cu")
		(net "P5E_CPU1_P3_RX_DP<12>")
	)
	(arc
		(start 125.086872 -293.990776)
		(mid 125.330199 -293.52621)
		(end 125.086872 -293.061644)
		(width 0.1143)
		(layer "In4.Cu")
		(net "P5E_CPU1_P3_RX_DP<12>")
	)
	(arc
		(start 125.464316 -288.3789)
		(mid 125.481059 -288.366078)
		(end 125.49886 -288.35477)
		(width 0.1143)
		(layer "In4.Cu")
		(net "P5E_CPU1_P3_RX_DP<12>")
	)
	(arc
		(start 125.088142 -295.609772)
		(mid 125.265985 -295.40795)
		(end 125.330204 -295.14673)
		(width 0.1143)
		(layer "In4.Cu")
		(net "P5E_CPU1_P3_RX_DP<12>")
	)
	(arc
		(start 125.330204 -288.666428)
		(mid 125.365389 -288.507803)
		(end 125.464316 -288.3789)
		(width 0.1143)
		(layer "In4.Cu")
		(net "P5E_CPU1_P3_RX_DP<12>")
	)
	(segment
		(start 122.887994 -289.210242)
		(end 123.354846 -289.47618)
		(width 0.12954)
		(layer "F.Cu")
		(net "P5E_CPU1_P3_RX_DP<11>")
	)
	(segment
		(start 127.970534 -386.003292)
		(end 128.491234 -386.003292)
		(width 0.127)
		(layer "F.Cu")
		(net "P5E_CPU1_P3_RX_DP<11>")
	)
	(segment
		(start 123.170696 -289.800538)
		(end 123.167902 -289.79876)
		(width 0.1143)
		(layer "In4.Cu")
		(net "P5E_CPU1_P3_RX_DP<11>")
	)
	(segment
		(start 123.96597 -297.227498)
		(end 123.96597 -296.42308)
		(width 0.14224)
		(layer "In4.Cu")
		(net "P5E_CPU1_P3_RX_DP<11>")
	)
	(segment
		(start 125.490224 -300.173898)
		(end 124.685552 -298.990512)
		(width 0.14224)
		(layer "In4.Cu")
		(net "P5E_CPU1_P3_RX_DP<11>")
	)
	(segment
		(start 123.67006 -290.627562)
		(end 123.669298 -290.627054)
		(width 0.1143)
		(layer "In4.Cu")
		(net "P5E_CPU1_P3_RX_DP<11>")
	)
	(segment
		(start 124.077222 -294.031416)
		(end 124.107702 -294.013636)
		(width 0.1143)
		(layer "In4.Cu")
		(net "P5E_CPU1_P3_RX_DP<11>")
	)
	(segment
		(start 124.107702 -294.658796)
		(end 124.077222 -294.641016)
		(width 0.1143)
		(layer "In4.Cu")
		(net "P5E_CPU1_P3_RX_DP<11>")
	)
	(segment
		(start 124.077222 -292.411404)
		(end 124.107702 -292.393624)
		(width 0.1143)
		(layer "In4.Cu")
		(net "P5E_CPU1_P3_RX_DP<11>")
	)
	(segment
		(start 128.848612 -385.046982)
		(end 128.532636 -384.731006)
		(width 0.14224)
		(layer "In4.Cu")
		(net "P5E_CPU1_P3_RX_DP<11>")
	)
	(segment
		(start 142.711932 -336.71891)
		(end 141.097762 -327.73366)
		(width 0.14224)
		(layer "In4.Cu")
		(net "P5E_CPU1_P3_RX_DP<11>")
	)
	(segment
		(start 122.987054 -289.54603)
		(end 123.056904 -289.47618)
		(width 0.1143)
		(layer "In4.Cu")
		(net "P5E_CPU1_P3_RX_DP<11>")
	)
	(segment
		(start 128.848612 -385.460494)
		(end 128.848612 -385.046982)
		(width 0.14224)
		(layer "In4.Cu")
		(net "P5E_CPU1_P3_RX_DP<11>")
	)
	(segment
		(start 123.643136 -290.611814)
		(end 123.64212 -290.611306)
		(width 0.1143)
		(layer "In4.Cu")
		(net "P5E_CPU1_P3_RX_DP<11>")
	)
	(segment
		(start 123.669298 -290.627054)
		(end 123.64466 -290.61283)
		(width 0.1143)
		(layer "In4.Cu")
		(net "P5E_CPU1_P3_RX_DP<11>")
	)
	(segment
		(start 124.146818 -293.061644)
		(end 124.107702 -293.038784)
		(width 0.1143)
		(layer "In4.Cu")
		(net "P5E_CPU1_P3_RX_DP<11>")
	)
	(segment
		(start 128.491234 -386.003292)
		(end 128.58623 -385.649216)
		(width 0.14224)
		(layer "In4.Cu")
		(net "P5E_CPU1_P3_RX_DP<11>")
	)
	(segment
		(start 124.107702 -294.013636)
		(end 124.146818 -293.990776)
		(width 0.1143)
		(layer "In4.Cu")
		(net "P5E_CPU1_P3_RX_DP<11>")
	)
	(segment
		(start 123.96597 -296.42308)
		(end 123.96597 -296.394632)
		(width 0.1143)
		(layer "In4.Cu")
		(net "P5E_CPU1_P3_RX_DP<11>")
	)
	(segment
		(start 123.637802 -290.608766)
		(end 123.63704 -290.608258)
		(width 0.1143)
		(layer "In4.Cu")
		(net "P5E_CPU1_P3_RX_DP<11>")
	)
	(segment
		(start 128.760474 -385.548632)
		(end 128.848612 -385.460494)
		(width 0.14224)
		(layer "In4.Cu")
		(net "P5E_CPU1_P3_RX_DP<11>")
	)
	(segment
		(start 124.107702 -295.633648)
		(end 124.146818 -295.610788)
		(width 0.1143)
		(layer "In4.Cu")
		(net "P5E_CPU1_P3_RX_DP<11>")
	)
	(segment
		(start 128.532636 -384.731006)
		(end 128.535938 -384.309874)
		(width 0.14224)
		(layer "In4.Cu")
		(net "P5E_CPU1_P3_RX_DP<11>")
	)
	(segment
		(start 131.595368 -370.016024)
		(end 131.26085 -369.681506)
		(width 0.14224)
		(layer "In4.Cu")
		(net "P5E_CPU1_P3_RX_DP<11>")
	)
	(segment
		(start 131.975606 -370.192554)
		(end 131.727956 -370.089938)
		(width 0.14224)
		(layer "In4.Cu")
		(net "P5E_CPU1_P3_RX_DP<11>")
	)
	(segment
		(start 124.685552 -298.990512)
		(end 123.975622 -297.276266)
		(width 0.14224)
		(layer "In4.Cu")
		(net "P5E_CPU1_P3_RX_DP<11>")
	)
	(segment
		(start 132.666232 -366.592104)
		(end 141.783054 -360.440732)
		(width 0.14224)
		(layer "In4.Cu")
		(net "P5E_CPU1_P3_RX_DP<11>")
	)
	(segment
		(start 124.146818 -291.441632)
		(end 124.107702 -291.418772)
		(width 0.1143)
		(layer "In4.Cu")
		(net "P5E_CPU1_P3_RX_DP<11>")
	)
	(segment
		(start 123.64466 -290.61283)
		(end 123.643136 -290.611814)
		(width 0.1143)
		(layer "In4.Cu")
		(net "P5E_CPU1_P3_RX_DP<11>")
	)
	(segment
		(start 128.840484 -384.005328)
		(end 128.840484 -382.78562)
		(width 0.14224)
		(layer "In4.Cu")
		(net "P5E_CPU1_P3_RX_DP<11>")
	)
	(segment
		(start 123.638818 -290.609274)
		(end 123.637802 -290.608766)
		(width 0.1143)
		(layer "In4.Cu")
		(net "P5E_CPU1_P3_RX_DP<11>")
	)
	(segment
		(start 131.97586 -370.192554)
		(end 131.975606 -370.192554)
		(width 0.14224)
		(layer "In4.Cu")
		(net "P5E_CPU1_P3_RX_DP<11>")
	)
	(segment
		(start 123.640596 -290.61029)
		(end 123.638818 -290.609274)
		(width 0.1143)
		(layer "In4.Cu")
		(net "P5E_CPU1_P3_RX_DP<11>")
	)
	(segment
		(start 124.107702 -292.393624)
		(end 124.146818 -292.370764)
		(width 0.1143)
		(layer "In4.Cu")
		(net "P5E_CPU1_P3_RX_DP<11>")
	)
	(segment
		(start 142.448026 -359.616502)
		(end 142.44828 -359.615994)
		(width 0.14224)
		(layer "In4.Cu")
		(net "P5E_CPU1_P3_RX_DP<11>")
	)
	(segment
		(start 124.107702 -291.418772)
		(end 124.077222 -291.400992)
		(width 0.1143)
		(layer "In4.Cu")
		(net "P5E_CPU1_P3_RX_DP<11>")
	)
	(segment
		(start 134.77367 -311.486804)
		(end 125.490224 -300.173898)
		(width 0.14224)
		(layer "In4.Cu")
		(net "P5E_CPU1_P3_RX_DP<11>")
	)
	(segment
		(start 123.166886 -289.798252)
		(end 123.136152 -289.780472)
		(width 0.1143)
		(layer "In4.Cu")
		(net "P5E_CPU1_P3_RX_DP<11>")
	)
	(segment
		(start 136.717278 -315.122306)
		(end 134.77367 -311.486804)
		(width 0.14224)
		(layer "In4.Cu")
		(net "P5E_CPU1_P3_RX_DP<11>")
	)
	(segment
		(start 142.711932 -358.256332)
		(end 142.711932 -336.71891)
		(width 0.14224)
		(layer "In4.Cu")
		(net "P5E_CPU1_P3_RX_DP<11>")
	)
	(segment
		(start 123.96597 -296.394632)
		(end 123.92025 -296.348912)
		(width 0.1143)
		(layer "In4.Cu")
		(net "P5E_CPU1_P3_RX_DP<11>")
	)
	(segment
		(start 132.498846 -370.598446)
		(end 132.32892 -370.42852)
		(width 0.14224)
		(layer "In4.Cu")
		(net "P5E_CPU1_P3_RX_DP<11>")
	)
	(segment
		(start 123.92025 -296.348912)
		(end 123.92025 -295.956228)
		(width 0.1143)
		(layer "In4.Cu")
		(net "P5E_CPU1_P3_RX_DP<11>")
	)
	(segment
		(start 123.167902 -289.79876)
		(end 123.166886 -289.798252)
		(width 0.1143)
		(layer "In4.Cu")
		(net "P5E_CPU1_P3_RX_DP<11>")
	)
	(segment
		(start 123.056904 -289.47618)
		(end 123.354846 -289.47618)
		(width 0.1143)
		(layer "In4.Cu")
		(net "P5E_CPU1_P3_RX_DP<11>")
	)
	(segment
		(start 129.04597 -381.752602)
		(end 132.87756 -372.501668)
		(width 0.14224)
		(layer "In4.Cu")
		(net "P5E_CPU1_P3_RX_DP<11>")
	)
	(segment
		(start 141.097762 -327.73366)
		(end 136.717278 -315.122306)
		(width 0.14224)
		(layer "In4.Cu")
		(net "P5E_CPU1_P3_RX_DP<11>")
	)
	(segment
		(start 128.535938 -384.309874)
		(end 128.840484 -384.005328)
		(width 0.14224)
		(layer "In4.Cu")
		(net "P5E_CPU1_P3_RX_DP<11>")
	)
	(segment
		(start 123.676918 -290.631626)
		(end 123.67006 -290.627562)
		(width 0.1143)
		(layer "In4.Cu")
		(net "P5E_CPU1_P3_RX_DP<11>")
	)
	(segment
		(start 124.146818 -294.681656)
		(end 124.107702 -294.658796)
		(width 0.1143)
		(layer "In4.Cu")
		(net "P5E_CPU1_P3_RX_DP<11>")
	)
	(segment
		(start 124.107702 -293.038784)
		(end 124.077222 -293.021004)
		(width 0.1143)
		(layer "In4.Cu")
		(net "P5E_CPU1_P3_RX_DP<11>")
	)
	(segment
		(start 124.077222 -295.651428)
		(end 124.107702 -295.633648)
		(width 0.1143)
		(layer "In4.Cu")
		(net "P5E_CPU1_P3_RX_DP<11>")
	)
	(segment
		(start 123.64212 -290.611306)
		(end 123.640596 -290.61029)
		(width 0.1143)
		(layer "In4.Cu")
		(net "P5E_CPU1_P3_RX_DP<11>")
	)
	(segment
		(start 128.58623 -385.649216)
		(end 128.760474 -385.548632)
		(width 0.14224)
		(layer "In4.Cu")
		(net "P5E_CPU1_P3_RX_DP<11>")
	)
	(arc
		(start 131.727956 -370.089938)
		(mid 131.659509 -370.056843)
		(end 131.595368 -370.016024)
		(width 0.14224)
		(layer "In4.Cu")
		(net "P5E_CPU1_P3_RX_DP<11>")
	)
	(arc
		(start 124.077222 -291.400992)
		(mid 123.961795 -291.267616)
		(end 123.92025 -291.096192)
		(width 0.1143)
		(layer "In4.Cu")
		(net "P5E_CPU1_P3_RX_DP<11>")
	)
	(arc
		(start 131.130548 -368.785394)
		(mid 131.699285 -367.549333)
		(end 132.666232 -366.592104)
		(width 0.14224)
		(layer "In4.Cu")
		(net "P5E_CPU1_P3_RX_DP<11>")
	)
	(arc
		(start 142.44828 -359.615994)
		(mid 142.645321 -358.948808)
		(end 142.711932 -358.256332)
		(width 0.14224)
		(layer "In4.Cu")
		(net "P5E_CPU1_P3_RX_DP<11>")
	)
	(arc
		(start 124.077222 -293.021004)
		(mid 123.920245 -292.716204)
		(end 124.077222 -292.411404)
		(width 0.1143)
		(layer "In4.Cu")
		(net "P5E_CPU1_P3_RX_DP<11>")
	)
	(arc
		(start 124.077222 -294.641016)
		(mid 123.920245 -294.336216)
		(end 124.077222 -294.031416)
		(width 0.1143)
		(layer "In4.Cu")
		(net "P5E_CPU1_P3_RX_DP<11>")
	)
	(arc
		(start 124.146818 -293.990776)
		(mid 124.390145 -293.52621)
		(end 124.146818 -293.061644)
		(width 0.1143)
		(layer "In4.Cu")
		(net "P5E_CPU1_P3_RX_DP<11>")
	)
	(arc
		(start 128.840484 -382.78562)
		(mid 128.892355 -382.258992)
		(end 129.04597 -381.752602)
		(width 0.14224)
		(layer "In4.Cu")
		(net "P5E_CPU1_P3_RX_DP<11>")
	)
	(arc
		(start 141.783054 -360.440732)
		(mid 142.177591 -360.078681)
		(end 142.448026 -359.616502)
		(width 0.14224)
		(layer "In4.Cu")
		(net "P5E_CPU1_P3_RX_DP<11>")
	)
	(arc
		(start 123.92025 -295.956228)
		(mid 123.961799 -295.784806)
		(end 124.077222 -295.651428)
		(width 0.1143)
		(layer "In4.Cu")
		(net "P5E_CPU1_P3_RX_DP<11>")
	)
	(arc
		(start 131.26085 -369.681506)
		(mid 131.152953 -369.528842)
		(end 131.101846 -369.34902)
		(width 0.14224)
		(layer "In4.Cu")
		(net "P5E_CPU1_P3_RX_DP<11>")
	)
	(arc
		(start 124.146818 -295.610788)
		(mid 124.390145 -295.146222)
		(end 124.146818 -294.681656)
		(width 0.1143)
		(layer "In4.Cu")
		(net "P5E_CPU1_P3_RX_DP<11>")
	)
	(arc
		(start 123.975622 -297.276266)
		(mid 123.968377 -297.252359)
		(end 123.96597 -297.227498)
		(width 0.14224)
		(layer "In4.Cu")
		(net "P5E_CPU1_P3_RX_DP<11>")
	)
	(arc
		(start 131.101846 -369.34902)
		(mid 131.095383 -369.066148)
		(end 131.130548 -368.785394)
		(width 0.14224)
		(layer "In4.Cu")
		(net "P5E_CPU1_P3_RX_DP<11>")
	)
	(arc
		(start 123.92025 -291.096192)
		(mid 123.855735 -290.833973)
		(end 123.676918 -290.631626)
		(width 0.1143)
		(layer "In4.Cu")
		(net "P5E_CPU1_P3_RX_DP<11>")
	)
	(arc
		(start 123.63704 -290.608258)
		(mid 123.499638 -290.471425)
		(end 123.449334 -290.284154)
		(width 0.1143)
		(layer "In4.Cu")
		(net "P5E_CPU1_P3_RX_DP<11>")
	)
	(arc
		(start 123.449334 -290.284154)
		(mid 123.374695 -290.005077)
		(end 123.170696 -289.800538)
		(width 0.1143)
		(layer "In4.Cu")
		(net "P5E_CPU1_P3_RX_DP<11>")
	)
	(arc
		(start 132.32892 -370.42852)
		(mid 132.163999 -370.293171)
		(end 131.97586 -370.192554)
		(width 0.14224)
		(layer "In4.Cu")
		(net "P5E_CPU1_P3_RX_DP<11>")
	)
	(arc
		(start 132.87756 -372.501668)
		(mid 132.976893 -371.492598)
		(end 132.498846 -370.598446)
		(width 0.14224)
		(layer "In4.Cu")
		(net "P5E_CPU1_P3_RX_DP<11>")
	)
	(arc
		(start 124.146818 -292.370764)
		(mid 124.390145 -291.906198)
		(end 124.146818 -291.441632)
		(width 0.1143)
		(layer "In4.Cu")
		(net "P5E_CPU1_P3_RX_DP<11>")
	)
	(arc
		(start 123.136152 -289.780472)
		(mid 123.039017 -289.677603)
		(end 122.987054 -289.54603)
		(width 0.1143)
		(layer "In4.Cu")
		(net "P5E_CPU1_P3_RX_DP<11>")
	)
	(segment
		(start 126.770638 -386.003292)
		(end 127.291338 -386.003292)
		(width 0.127)
		(layer "F.Cu")
		(net "P5E_CPU1_P3_RX_DP<10>")
	)
	(segment
		(start 122.887994 -290.830254)
		(end 123.354846 -291.096192)
		(width 0.12954)
		(layer "F.Cu")
		(net "P5E_CPU1_P3_RX_DP<10>")
	)
	(segment
		(start 123.025916 -297.383708)
		(end 123.025916 -296.489628)
		(width 0.14224)
		(layer "In4.Cu")
		(net "P5E_CPU1_P3_RX_DP<10>")
	)
	(segment
		(start 123.167902 -295.633648)
		(end 123.16841 -295.633648)
		(width 0.1143)
		(layer "In4.Cu")
		(net "P5E_CPU1_P3_RX_DP<10>")
	)
	(segment
		(start 123.16841 -294.658796)
		(end 123.167902 -294.658796)
		(width 0.1143)
		(layer "In4.Cu")
		(net "P5E_CPU1_P3_RX_DP<10>")
	)
	(segment
		(start 123.136152 -295.651936)
		(end 123.16714 -295.634156)
		(width 0.1143)
		(layer "In4.Cu")
		(net "P5E_CPU1_P3_RX_DP<10>")
	)
	(segment
		(start 123.161552 -294.017192)
		(end 123.163584 -294.016176)
		(width 0.1143)
		(layer "In4.Cu")
		(net "P5E_CPU1_P3_RX_DP<10>")
	)
	(segment
		(start 123.025916 -296.46118)
		(end 122.980196 -296.41546)
		(width 0.1143)
		(layer "In4.Cu")
		(net "P5E_CPU1_P3_RX_DP<10>")
	)
	(segment
		(start 127.835914 -378.9426)
		(end 127.703326 -373.905272)
		(width 0.14224)
		(layer "In4.Cu")
		(net "P5E_CPU1_P3_RX_DP<10>")
	)
	(segment
		(start 123.165362 -294.01516)
		(end 123.166124 -294.014652)
		(width 0.1143)
		(layer "In4.Cu")
		(net "P5E_CPU1_P3_RX_DP<10>")
	)
	(segment
		(start 123.167902 -294.658796)
		(end 123.136152 -294.640508)
		(width 0.1143)
		(layer "In4.Cu")
		(net "P5E_CPU1_P3_RX_DP<10>")
	)
	(segment
		(start 127.961136 -373.259604)
		(end 128.508506 -372.712234)
		(width 0.14224)
		(layer "In4.Cu")
		(net "P5E_CPU1_P3_RX_DP<10>")
	)
	(segment
		(start 127.386334 -385.649216)
		(end 127.560578 -385.548632)
		(width 0.14224)
		(layer "In4.Cu")
		(net "P5E_CPU1_P3_RX_DP<10>")
	)
	(segment
		(start 123.056904 -291.096192)
		(end 123.354846 -291.096192)
		(width 0.1143)
		(layer "In4.Cu")
		(net "P5E_CPU1_P3_RX_DP<10>")
	)
	(segment
		(start 141.779752 -357.671624)
		(end 141.779752 -336.810096)
		(width 0.14224)
		(layer "In4.Cu")
		(net "P5E_CPU1_P3_RX_DP<10>")
	)
	(segment
		(start 141.779752 -336.810096)
		(end 140.190728 -327.964038)
		(width 0.14224)
		(layer "In4.Cu")
		(net "P5E_CPU1_P3_RX_DP<10>")
	)
	(segment
		(start 124.64796 -300.623478)
		(end 123.861068 -299.445934)
		(width 0.14224)
		(layer "In4.Cu")
		(net "P5E_CPU1_P3_RX_DP<10>")
	)
	(segment
		(start 123.164346 -294.015668)
		(end 123.165362 -294.01516)
		(width 0.1143)
		(layer "In4.Cu")
		(net "P5E_CPU1_P3_RX_DP<10>")
	)
	(segment
		(start 135.97763 -315.836554)
		(end 133.818884 -311.798208)
		(width 0.14224)
		(layer "In4.Cu")
		(net "P5E_CPU1_P3_RX_DP<10>")
	)
	(segment
		(start 127.291338 -386.003292)
		(end 127.386334 -385.649216)
		(width 0.14224)
		(layer "In4.Cu")
		(net "P5E_CPU1_P3_RX_DP<10>")
	)
	(segment
		(start 123.167902 -294.013636)
		(end 123.16841 -294.013636)
		(width 0.1143)
		(layer "In4.Cu")
		(net "P5E_CPU1_P3_RX_DP<10>")
	)
	(segment
		(start 123.167902 -291.418772)
		(end 123.136152 -291.400484)
		(width 0.1143)
		(layer "In4.Cu")
		(net "P5E_CPU1_P3_RX_DP<10>")
	)
	(segment
		(start 123.136152 -292.411912)
		(end 123.167902 -292.393624)
		(width 0.1143)
		(layer "In4.Cu")
		(net "P5E_CPU1_P3_RX_DP<10>")
	)
	(segment
		(start 123.166124 -294.014652)
		(end 123.16714 -294.014144)
		(width 0.1143)
		(layer "In4.Cu")
		(net "P5E_CPU1_P3_RX_DP<10>")
	)
	(segment
		(start 127.560578 -385.548632)
		(end 127.648716 -385.460494)
		(width 0.14224)
		(layer "In4.Cu")
		(net "P5E_CPU1_P3_RX_DP<10>")
	)
	(segment
		(start 123.16714 -294.014144)
		(end 123.167902 -294.013636)
		(width 0.1143)
		(layer "In4.Cu")
		(net "P5E_CPU1_P3_RX_DP<10>")
	)
	(segment
		(start 127.33274 -384.731006)
		(end 127.33655 -384.24231)
		(width 0.14224)
		(layer "In4.Cu")
		(net "P5E_CPU1_P3_RX_DP<10>")
	)
	(segment
		(start 127.635 -382.337056)
		(end 127.81915 -379.706124)
		(width 0.14224)
		(layer "In4.Cu")
		(net "P5E_CPU1_P3_RX_DP<10>")
	)
	(segment
		(start 123.16714 -295.634156)
		(end 123.167902 -295.633648)
		(width 0.1143)
		(layer "In4.Cu")
		(net "P5E_CPU1_P3_RX_DP<10>")
	)
	(segment
		(start 127.648716 -385.046982)
		(end 127.33274 -384.731006)
		(width 0.14224)
		(layer "In4.Cu")
		(net "P5E_CPU1_P3_RX_DP<10>")
	)
	(segment
		(start 123.167902 -293.038784)
		(end 123.136152 -293.020496)
		(width 0.1143)
		(layer "In4.Cu")
		(net "P5E_CPU1_P3_RX_DP<10>")
	)
	(segment
		(start 123.136152 -294.031924)
		(end 123.161552 -294.017192)
		(width 0.1143)
		(layer "In4.Cu")
		(net "P5E_CPU1_P3_RX_DP<10>")
	)
	(segment
		(start 122.980196 -296.41546)
		(end 122.980196 -295.956228)
		(width 0.1143)
		(layer "In4.Cu")
		(net "P5E_CPU1_P3_RX_DP<10>")
	)
	(segment
		(start 127.33655 -384.24231)
		(end 127.635 -383.943098)
		(width 0.14224)
		(layer "In4.Cu")
		(net "P5E_CPU1_P3_RX_DP<10>")
	)
	(segment
		(start 122.987054 -291.166042)
		(end 123.056904 -291.096192)
		(width 0.1143)
		(layer "In4.Cu")
		(net "P5E_CPU1_P3_RX_DP<10>")
	)
	(segment
		(start 127.635 -383.943098)
		(end 127.635 -382.337056)
		(width 0.14224)
		(layer "In4.Cu")
		(net "P5E_CPU1_P3_RX_DP<10>")
	)
	(segment
		(start 129.510282 -370.944394)
		(end 130.246628 -368.004852)
		(width 0.14224)
		(layer "In4.Cu")
		(net "P5E_CPU1_P3_RX_DP<10>")
	)
	(segment
		(start 127.648716 -385.460494)
		(end 127.648716 -385.046982)
		(width 0.14224)
		(layer "In4.Cu")
		(net "P5E_CPU1_P3_RX_DP<10>")
	)
	(segment
		(start 123.025916 -296.489628)
		(end 123.025916 -296.46118)
		(width 0.1143)
		(layer "In4.Cu")
		(net "P5E_CPU1_P3_RX_DP<10>")
	)
	(segment
		(start 123.16841 -293.038784)
		(end 123.167902 -293.038784)
		(width 0.1143)
		(layer "In4.Cu")
		(net "P5E_CPU1_P3_RX_DP<10>")
	)
	(segment
		(start 140.190728 -327.964038)
		(end 135.97763 -315.836554)
		(width 0.14224)
		(layer "In4.Cu")
		(net "P5E_CPU1_P3_RX_DP<10>")
	)
	(segment
		(start 133.818884 -311.798208)
		(end 124.64796 -300.623478)
		(width 0.14224)
		(layer "In4.Cu")
		(net "P5E_CPU1_P3_RX_DP<10>")
	)
	(segment
		(start 123.861068 -299.445934)
		(end 123.043188 -297.470576)
		(width 0.14224)
		(layer "In4.Cu")
		(net "P5E_CPU1_P3_RX_DP<10>")
	)
	(segment
		(start 123.163584 -294.016176)
		(end 123.164346 -294.015668)
		(width 0.1143)
		(layer "In4.Cu")
		(net "P5E_CPU1_P3_RX_DP<10>")
	)
	(segment
		(start 131.910582 -365.642652)
		(end 139.794742 -360.374438)
		(width 0.14224)
		(layer "In4.Cu")
		(net "P5E_CPU1_P3_RX_DP<10>")
	)
	(arc
		(start 139.794742 -360.374438)
		(mid 140.314158 -360.014099)
		(end 140.820648 -359.635806)
		(width 0.14224)
		(layer "In4.Cu")
		(net "P5E_CPU1_P3_RX_DP<10>")
	)
	(arc
		(start 140.820648 -359.635806)
		(mid 140.889194 -359.577555)
		(end 140.951966 -359.513124)
		(width 0.14224)
		(layer "In4.Cu")
		(net "P5E_CPU1_P3_RX_DP<10>")
	)
	(arc
		(start 122.980196 -295.956228)
		(mid 123.021451 -295.785257)
		(end 123.136152 -295.651936)
		(width 0.1143)
		(layer "In4.Cu")
		(net "P5E_CPU1_P3_RX_DP<10>")
	)
	(arc
		(start 130.246628 -368.004852)
		(mid 130.858751 -366.66889)
		(end 131.910582 -365.642652)
		(width 0.14224)
		(layer "In4.Cu")
		(net "P5E_CPU1_P3_RX_DP<10>")
	)
	(arc
		(start 127.703326 -373.905272)
		(mid 127.765807 -373.555917)
		(end 127.961136 -373.259604)
		(width 0.14224)
		(layer "In4.Cu")
		(net "P5E_CPU1_P3_RX_DP<10>")
	)
	(arc
		(start 128.508506 -372.712234)
		(mid 129.129429 -371.896334)
		(end 129.510282 -370.944394)
		(width 0.14224)
		(layer "In4.Cu")
		(net "P5E_CPU1_P3_RX_DP<10>")
	)
	(arc
		(start 123.16841 -295.633648)
		(mid 123.449057 -295.146222)
		(end 123.16841 -294.658796)
		(width 0.1143)
		(layer "In4.Cu")
		(net "P5E_CPU1_P3_RX_DP<10>")
	)
	(arc
		(start 123.136152 -291.400484)
		(mid 123.039017 -291.297615)
		(end 122.987054 -291.166042)
		(width 0.1143)
		(layer "In4.Cu")
		(net "P5E_CPU1_P3_RX_DP<10>")
	)
	(arc
		(start 123.136152 -294.640508)
		(mid 122.980224 -294.336216)
		(end 123.136152 -294.031924)
		(width 0.1143)
		(layer "In4.Cu")
		(net "P5E_CPU1_P3_RX_DP<10>")
	)
	(arc
		(start 123.16841 -294.013636)
		(mid 123.449057 -293.52621)
		(end 123.16841 -293.038784)
		(width 0.1143)
		(layer "In4.Cu")
		(net "P5E_CPU1_P3_RX_DP<10>")
	)
	(arc
		(start 141.763496 -357.84917)
		(mid 141.775688 -357.76077)
		(end 141.779752 -357.671624)
		(width 0.14224)
		(layer "In4.Cu")
		(net "P5E_CPU1_P3_RX_DP<10>")
	)
	(arc
		(start 127.81915 -379.706124)
		(mid 127.836716 -379.324564)
		(end 127.835914 -378.9426)
		(width 0.14224)
		(layer "In4.Cu")
		(net "P5E_CPU1_P3_RX_DP<10>")
	)
	(arc
		(start 123.167902 -292.393624)
		(mid 123.448549 -291.906198)
		(end 123.167902 -291.418772)
		(width 0.1143)
		(layer "In4.Cu")
		(net "P5E_CPU1_P3_RX_DP<10>")
	)
	(arc
		(start 123.043188 -297.470576)
		(mid 123.030275 -297.427992)
		(end 123.025916 -297.383708)
		(width 0.14224)
		(layer "In4.Cu")
		(net "P5E_CPU1_P3_RX_DP<10>")
	)
	(arc
		(start 140.951966 -359.513124)
		(mid 141.470933 -358.736353)
		(end 141.763496 -357.84917)
		(width 0.14224)
		(layer "In4.Cu")
		(net "P5E_CPU1_P3_RX_DP<10>")
	)
	(arc
		(start 123.136152 -293.020496)
		(mid 122.980224 -292.716204)
		(end 123.136152 -292.411912)
		(width 0.1143)
		(layer "In4.Cu")
		(net "P5E_CPU1_P3_RX_DP<10>")
	)
	(segment
		(start 114.770662 -386.003292)
		(end 115.291362 -386.003292)
		(width 0.127)
		(layer "F.Cu")
		(net "P5E_CPU1_P3_RX_DP<0>")
	)
	(segment
		(start 114.897916 -286.780478)
		(end 115.364768 -287.046162)
		(width 0.12954)
		(layer "F.Cu")
		(net "P5E_CPU1_P3_RX_DP<0>")
	)
	(segment
		(start 115.64874 -385.460494)
		(end 115.64874 -385.046982)
		(width 0.14224)
		(layer "In4.Cu")
		(net "P5E_CPU1_P3_RX_DP<0>")
	)
	(segment
		(start 115.59921 -382.03632)
		(end 115.540536 -381.816864)
		(width 0.14224)
		(layer "In4.Cu")
		(net "P5E_CPU1_P3_RX_DP<0>")
	)
	(segment
		(start 115.357402 -303.609248)
		(end 113.970562 -300.266862)
		(width 0.14224)
		(layer "In4.Cu")
		(net "P5E_CPU1_P3_RX_DP<0>")
	)
	(segment
		(start 115.332764 -384.731006)
		(end 115.340384 -383.77495)
		(width 0.14224)
		(layer "In4.Cu")
		(net "P5E_CPU1_P3_RX_DP<0>")
	)
	(segment
		(start 115.640612 -383.474722)
		(end 115.640612 -382.458214)
		(width 0.14224)
		(layer "In4.Cu")
		(net "P5E_CPU1_P3_RX_DP<0>")
	)
	(segment
		(start 107.255564 -377.138946)
		(end 107.255564 -373.089424)
		(width 0.14224)
		(layer "In4.Cu")
		(net "P5E_CPU1_P3_RX_DP<0>")
	)
	(segment
		(start 113.420398 -298.455588)
		(end 112.98047 -296.245026)
		(width 0.14224)
		(layer "In4.Cu")
		(net "P5E_CPU1_P3_RX_DP<0>")
	)
	(segment
		(start 114.204242 -288.363406)
		(end 114.23777 -288.343848)
		(width 0.1143)
		(layer "In4.Cu")
		(net "P5E_CPU1_P3_RX_DP<0>")
	)
	(segment
		(start 114.23777 -288.343848)
		(end 114.238278 -288.343086)
		(width 0.1143)
		(layer "In4.Cu")
		(net "P5E_CPU1_P3_RX_DP<0>")
	)
	(segment
		(start 113.241074 -289.72764)
		(end 113.241074 -289.662616)
		(width 0.1143)
		(layer "In4.Cu")
		(net "P5E_CPU1_P3_RX_DP<0>")
	)
	(segment
		(start 114.520472 -287.853882)
		(end 114.520472 -287.852866)
		(width 0.1143)
		(layer "In4.Cu")
		(net "P5E_CPU1_P3_RX_DP<0>")
	)
	(segment
		(start 131.285996 -331.253846)
		(end 127.234696 -319.588134)
		(width 0.14224)
		(layer "In4.Cu")
		(net "P5E_CPU1_P3_RX_DP<0>")
	)
	(segment
		(start 127.234696 -319.588134)
		(end 125.689106 -316.69609)
		(width 0.14224)
		(layer "In4.Cu")
		(net "P5E_CPU1_P3_RX_DP<0>")
	)
	(segment
		(start 113.221008 -289.747706)
		(end 113.241074 -289.72764)
		(width 0.1143)
		(layer "In4.Cu")
		(net "P5E_CPU1_P3_RX_DP<0>")
	)
	(segment
		(start 132.44703 -337.71967)
		(end 131.285996 -331.253846)
		(width 0.14224)
		(layer "In4.Cu")
		(net "P5E_CPU1_P3_RX_DP<0>")
	)
	(segment
		(start 113.581942 -364.6424)
		(end 115.295172 -363.932724)
		(width 0.14224)
		(layer "In4.Cu")
		(net "P5E_CPU1_P3_RX_DP<0>")
	)
	(segment
		(start 114.63909 -287.594294)
		(end 114.747548 -287.516316)
		(width 0.1143)
		(layer "In4.Cu")
		(net "P5E_CPU1_P3_RX_DP<0>")
	)
	(segment
		(start 112.956594 -296.000932)
		(end 112.95634 -296.001186)
		(width 0.14224)
		(layer "In4.Cu")
		(net "P5E_CPU1_P3_RX_DP<0>")
	)
	(segment
		(start 108.125514 -370.22151)
		(end 109.7534 -367.784634)
		(width 0.14224)
		(layer "In4.Cu")
		(net "P5E_CPU1_P3_RX_DP<0>")
	)
	(segment
		(start 113.767616 -289.1536)
		(end 113.806732 -289.13074)
		(width 0.1143)
		(layer "In4.Cu")
		(net "P5E_CPU1_P3_RX_DP<0>")
	)
	(segment
		(start 115.386358 -385.649216)
		(end 115.560602 -385.548632)
		(width 0.14224)
		(layer "In4.Cu")
		(net "P5E_CPU1_P3_RX_DP<0>")
	)
	(segment
		(start 115.64874 -385.046982)
		(end 115.332764 -384.731006)
		(width 0.14224)
		(layer "In4.Cu")
		(net "P5E_CPU1_P3_RX_DP<0>")
	)
	(segment
		(start 114.984022 -287.128966)
		(end 115.066826 -287.046162)
		(width 0.1143)
		(layer "In4.Cu")
		(net "P5E_CPU1_P3_RX_DP<0>")
	)
	(segment
		(start 112.95634 -296.001186)
		(end 112.95634 -290.215828)
		(width 0.14224)
		(layer "In4.Cu")
		(net "P5E_CPU1_P3_RX_DP<0>")
	)
	(segment
		(start 115.560602 -385.548632)
		(end 115.64874 -385.460494)
		(width 0.14224)
		(layer "In4.Cu")
		(net "P5E_CPU1_P3_RX_DP<0>")
	)
	(segment
		(start 116.758974 -363.150658)
		(end 130.676142 -353.859592)
		(width 0.14224)
		(layer "In4.Cu")
		(net "P5E_CPU1_P3_RX_DP<0>")
	)
	(segment
		(start 132.44703 -348.864174)
		(end 132.44703 -337.71967)
		(width 0.14224)
		(layer "In4.Cu")
		(net "P5E_CPU1_P3_RX_DP<0>")
	)
	(segment
		(start 131.519422 -352.947224)
		(end 131.74345 -352.405696)
		(width 0.14224)
		(layer "In4.Cu")
		(net "P5E_CPU1_P3_RX_DP<0>")
	)
	(segment
		(start 117.14226 -306.281074)
		(end 115.357402 -303.609248)
		(width 0.14224)
		(layer "In4.Cu")
		(net "P5E_CPU1_P3_RX_DP<0>")
	)
	(segment
		(start 115.291362 -386.003292)
		(end 115.386358 -385.649216)
		(width 0.14224)
		(layer "In4.Cu")
		(net "P5E_CPU1_P3_RX_DP<0>")
	)
	(segment
		(start 125.689106 -316.69609)
		(end 117.14226 -306.281074)
		(width 0.14224)
		(layer "In4.Cu")
		(net "P5E_CPU1_P3_RX_DP<0>")
	)
	(segment
		(start 115.340384 -383.77495)
		(end 115.640612 -383.474722)
		(width 0.14224)
		(layer "In4.Cu")
		(net "P5E_CPU1_P3_RX_DP<0>")
	)
	(segment
		(start 113.100358 -289.868356)
		(end 113.221008 -289.747706)
		(width 0.14224)
		(layer "In4.Cu")
		(net "P5E_CPU1_P3_RX_DP<0>")
	)
	(segment
		(start 114.979958 -287.151826)
		(end 114.980212 -287.151826)
		(width 0.1143)
		(layer "In4.Cu")
		(net "P5E_CPU1_P3_RX_DP<0>")
	)
	(segment
		(start 115.066826 -287.046162)
		(end 115.364768 -287.046162)
		(width 0.1143)
		(layer "In4.Cu")
		(net "P5E_CPU1_P3_RX_DP<0>")
	)
	(segment
		(start 114.393472 -380.503684)
		(end 107.633262 -377.704096)
		(width 0.14224)
		(layer "In4.Cu")
		(net "P5E_CPU1_P3_RX_DP<0>")
	)
	(segment
		(start 113.241074 -289.662616)
		(end 113.691162 -289.212528)
		(width 0.1143)
		(layer "In4.Cu")
		(net "P5E_CPU1_P3_RX_DP<0>")
	)
	(segment
		(start 112.95634 -290.215828)
		(end 113.100358 -289.868356)
		(width 0.14224)
		(layer "In4.Cu")
		(net "P5E_CPU1_P3_RX_DP<0>")
	)
	(segment
		(start 130.676142 -353.859592)
		(end 131.380484 -353.15525)
		(width 0.14224)
		(layer "In4.Cu")
		(net "P5E_CPU1_P3_RX_DP<0>")
	)
	(arc
		(start 115.640612 -382.458214)
		(mid 115.630248 -382.246253)
		(end 115.59921 -382.03632)
		(width 0.14224)
		(layer "In4.Cu")
		(net "P5E_CPU1_P3_RX_DP<0>")
	)
	(arc
		(start 113.691162 -289.212528)
		(mid 113.727477 -289.180584)
		(end 113.767616 -289.1536)
		(width 0.1143)
		(layer "In4.Cu")
		(net "P5E_CPU1_P3_RX_DP<0>")
	)
	(arc
		(start 107.633262 -377.704096)
		(mid 107.358666 -377.478823)
		(end 107.255564 -377.138946)
		(width 0.14224)
		(layer "In4.Cu")
		(net "P5E_CPU1_P3_RX_DP<0>")
	)
	(arc
		(start 114.563398 -287.680146)
		(mid 114.596301 -287.63286)
		(end 114.63909 -287.594294)
		(width 0.1143)
		(layer "In4.Cu")
		(net "P5E_CPU1_P3_RX_DP<0>")
	)
	(arc
		(start 114.520472 -287.852866)
		(mid 114.520472 -287.852612)
		(end 114.520472 -287.852358)
		(width 0.1143)
		(layer "In4.Cu")
		(net "P5E_CPU1_P3_RX_DP<0>")
	)
	(arc
		(start 115.540536 -381.816864)
		(mid 115.368597 -381.381351)
		(end 115.101624 -380.996698)
		(width 0.14224)
		(layer "In4.Cu")
		(net "P5E_CPU1_P3_RX_DP<0>")
	)
	(arc
		(start 114.747548 -287.516316)
		(mid 114.898855 -287.356448)
		(end 114.979958 -287.151826)
		(width 0.1143)
		(layer "In4.Cu")
		(net "P5E_CPU1_P3_RX_DP<0>")
	)
	(arc
		(start 114.980212 -287.151826)
		(mid 114.982235 -287.140416)
		(end 114.984022 -287.128966)
		(width 0.1143)
		(layer "In4.Cu")
		(net "P5E_CPU1_P3_RX_DP<0>")
	)
	(arc
		(start 113.970562 -300.266862)
		(mid 113.650877 -299.374773)
		(end 113.420398 -298.455588)
		(width 0.14224)
		(layer "In4.Cu")
		(net "P5E_CPU1_P3_RX_DP<0>")
	)
	(arc
		(start 107.255564 -373.089424)
		(mid 107.477892 -371.590969)
		(end 108.125514 -370.22151)
		(width 0.14224)
		(layer "In4.Cu")
		(net "P5E_CPU1_P3_RX_DP<0>")
	)
	(arc
		(start 131.380484 -353.15525)
		(mid 131.422887 -353.108581)
		(end 131.460494 -353.057968)
		(width 0.14224)
		(layer "In4.Cu")
		(net "P5E_CPU1_P3_RX_DP<0>")
	)
	(arc
		(start 114.050064 -288.666174)
		(mid 114.090826 -288.49629)
		(end 114.204242 -288.363406)
		(width 0.1143)
		(layer "In4.Cu")
		(net "P5E_CPU1_P3_RX_DP<0>")
	)
	(arc
		(start 131.460494 -353.057968)
		(mid 131.492684 -353.004046)
		(end 131.519422 -352.947224)
		(width 0.14224)
		(layer "In4.Cu")
		(net "P5E_CPU1_P3_RX_DP<0>")
	)
	(arc
		(start 115.295172 -363.932724)
		(mid 116.046243 -363.577571)
		(end 116.758974 -363.150658)
		(width 0.14224)
		(layer "In4.Cu")
		(net "P5E_CPU1_P3_RX_DP<0>")
	)
	(arc
		(start 114.238278 -288.343086)
		(mid 114.44486 -288.13626)
		(end 114.520472 -287.853882)
		(width 0.1143)
		(layer "In4.Cu")
		(net "P5E_CPU1_P3_RX_DP<0>")
	)
	(arc
		(start 113.806732 -289.13074)
		(mid 113.985545 -288.92839)
		(end 114.050064 -288.666174)
		(width 0.1143)
		(layer "In4.Cu")
		(net "P5E_CPU1_P3_RX_DP<0>")
	)
	(arc
		(start 114.520472 -287.852358)
		(mid 114.531331 -287.763608)
		(end 114.563398 -287.680146)
		(width 0.1143)
		(layer "In4.Cu")
		(net "P5E_CPU1_P3_RX_DP<0>")
	)
	(arc
		(start 109.7534 -367.784634)
		(mid 111.434635 -365.929583)
		(end 113.581942 -364.6424)
		(width 0.14224)
		(layer "In4.Cu")
		(net "P5E_CPU1_P3_RX_DP<0>")
	)
	(arc
		(start 115.101624 -380.996698)
		(mid 114.773874 -380.712372)
		(end 114.393472 -380.503684)
		(width 0.14224)
		(layer "In4.Cu")
		(net "P5E_CPU1_P3_RX_DP<0>")
	)
	(arc
		(start 131.74345 -352.405696)
		(mid 132.269455 -350.669544)
		(end 132.44703 -348.864174)
		(width 0.14224)
		(layer "In4.Cu")
		(net "P5E_CPU1_P3_RX_DP<0>")
	)
	(arc
		(start 112.98047 -296.245026)
		(mid 112.962534 -296.123566)
		(end 112.956594 -296.000932)
		(width 0.14224)
		(layer "In4.Cu")
		(net "P5E_CPU1_P3_RX_DP<0>")
	)
	(segment
		(start 121.94794 -287.590484)
		(end 122.414792 -287.856422)
		(width 0.12954)
		(layer "F.Cu")
		(net "P5E_CPU1_P3_RX_DN<9>")
	)
	(segment
		(start 125.170438 -385.31038)
		(end 125.691138 -385.31038)
		(width 0.127)
		(layer "F.Cu")
		(net "P5E_CPU1_P3_RX_DN<9>")
	)
	(segment
		(start 122.13082 -291.58311)
		(end 122.129296 -291.582094)
		(width 0.1143)
		(layer "In4.Cu")
		(net "P5E_CPU1_P3_RX_DN<9>")
	)
	(segment
		(start 122.782584 -287.926272)
		(end 122.712734 -287.856422)
		(width 0.1143)
		(layer "In4.Cu")
		(net "P5E_CPU1_P3_RX_DN<9>")
	)
	(segment
		(start 122.13082 -294.823134)
		(end 122.128788 -294.821864)
		(width 0.1143)
		(layer "In4.Cu")
		(net "P5E_CPU1_P3_RX_DN<9>")
	)
	(segment
		(start 122.758962 -299.984668)
		(end 122.758708 -299.984668)
		(width 0.14224)
		(layer "In4.Cu")
		(net "P5E_CPU1_P3_RX_DN<9>")
	)
	(segment
		(start 125.85446 -384.235198)
		(end 126.11862 -383.970022)
		(width 0.14224)
		(layer "In4.Cu")
		(net "P5E_CPU1_P3_RX_DN<9>")
	)
	(segment
		(start 122.147838 -293.838376)
		(end 122.162062 -293.830248)
		(width 0.1143)
		(layer "In4.Cu")
		(net "P5E_CPU1_P3_RX_DN<9>")
	)
	(segment
		(start 122.122692 -288.994088)
		(end 122.12828 -288.990786)
		(width 0.1143)
		(layer "In4.Cu")
		(net "P5E_CPU1_P3_RX_DN<9>")
	)
	(segment
		(start 126.203202 -381.273304)
		(end 126.202948 -381.273304)
		(width 0.14224)
		(layer "In4.Cu")
		(net "P5E_CPU1_P3_RX_DN<9>")
	)
	(segment
		(start 122.121422 -293.855648)
		(end 122.13082 -293.849298)
		(width 0.1143)
		(layer "In4.Cu")
		(net "P5E_CPU1_P3_RX_DN<9>")
	)
	(segment
		(start 122.156982 -292.215824)
		(end 122.163586 -292.212014)
		(width 0.1143)
		(layer "In4.Cu")
		(net "P5E_CPU1_P3_RX_DN<9>")
	)
	(segment
		(start 122.129296 -291.582094)
		(end 122.12828 -291.581586)
		(width 0.1143)
		(layer "In4.Cu")
		(net "P5E_CPU1_P3_RX_DN<9>")
	)
	(segment
		(start 122.13082 -293.849298)
		(end 122.131836 -293.84879)
		(width 0.1143)
		(layer "In4.Cu")
		(net "P5E_CPU1_P3_RX_DN<9>")
	)
	(segment
		(start 122.115326 -288.998406)
		(end 122.116088 -288.997898)
		(width 0.1143)
		(layer "In4.Cu")
		(net "P5E_CPU1_P3_RX_DN<9>")
	)
	(segment
		(start 122.10923 -292.241986)
		(end 122.122184 -292.23335)
		(width 0.1143)
		(layer "In4.Cu")
		(net "P5E_CPU1_P3_RX_DN<9>")
	)
	(segment
		(start 128.2192 -370.581174)
		(end 128.951736 -367.65738)
		(width 0.14224)
		(layer "In4.Cu")
		(net "P5E_CPU1_P3_RX_DN<9>")
	)
	(segment
		(start 122.118628 -293.857172)
		(end 122.121422 -293.855648)
		(width 0.1143)
		(layer "In4.Cu")
		(net "P5E_CPU1_P3_RX_DN<9>")
	)
	(segment
		(start 122.09399 -295.490646)
		(end 122.164602 -295.449498)
		(width 0.1143)
		(layer "In4.Cu")
		(net "P5E_CPU1_P3_RX_DN<9>")
	)
	(segment
		(start 121.849388 -296.38244)
		(end 121.849388 -295.956228)
		(width 0.1143)
		(layer "In4.Cu")
		(net "P5E_CPU1_P3_RX_DN<9>")
	)
	(segment
		(start 126.92126 -372.32336)
		(end 127.638556 -371.606064)
		(width 0.14224)
		(layer "In4.Cu")
		(net "P5E_CPU1_P3_RX_DN<9>")
	)
	(segment
		(start 122.319796 -295.146476)
		(end 122.319796 -295.146222)
		(width 0.1143)
		(layer "In4.Cu")
		(net "P5E_CPU1_P3_RX_DN<9>")
	)
	(segment
		(start 122.562874 -288.201608)
		(end 122.634502 -288.159952)
		(width 0.1143)
		(layer "In4.Cu")
		(net "P5E_CPU1_P3_RX_DN<9>")
	)
	(segment
		(start 122.119644 -288.995866)
		(end 122.121168 -288.995104)
		(width 0.1143)
		(layer "In4.Cu")
		(net "P5E_CPU1_P3_RX_DN<9>")
	)
	(segment
		(start 126.374652 -378.521214)
		(end 126.31547 -376.257566)
		(width 0.14224)
		(layer "In4.Cu")
		(net "P5E_CPU1_P3_RX_DN<9>")
	)
	(segment
		(start 126.202948 -381.273304)
		(end 126.232666 -380.849124)
		(width 0.14224)
		(layer "In4.Cu")
		(net "P5E_CPU1_P3_RX_DN<9>")
	)
	(segment
		(start 121.803668 -296.456608)
		(end 121.803668 -296.42816)
		(width 0.1143)
		(layer "In4.Cu")
		(net "P5E_CPU1_P3_RX_DN<9>")
	)
	(segment
		(start 128.138682 -306.80279)
		(end 123.704858 -301.40021)
		(width 0.14224)
		(layer "In4.Cu")
		(net "P5E_CPU1_P3_RX_DN<9>")
	)
	(segment
		(start 125.691138 -385.31038)
		(end 126.044452 -385.405376)
		(width 0.14224)
		(layer "In4.Cu")
		(net "P5E_CPU1_P3_RX_DN<9>")
	)
	(segment
		(start 122.129296 -288.990278)
		(end 122.133106 -288.987738)
		(width 0.1143)
		(layer "In4.Cu")
		(net "P5E_CPU1_P3_RX_DN<9>")
	)
	(segment
		(start 121.692416 -290.791392)
		(end 121.661936 -290.773612)
		(width 0.1143)
		(layer "In4.Cu")
		(net "P5E_CPU1_P3_RX_DN<9>")
	)
	(segment
		(start 128.138428 -306.80279)
		(end 128.138682 -306.80279)
		(width 0.14224)
		(layer "In4.Cu")
		(net "P5E_CPU1_P3_RX_DN<9>")
	)
	(segment
		(start 126.282196 -380.148084)
		(end 126.281688 -380.14783)
		(width 0.14224)
		(layer "In4.Cu")
		(net "P5E_CPU1_P3_RX_DN<9>")
	)
	(segment
		(start 121.661936 -290.773612)
		(end 121.62282 -290.750752)
		(width 0.1143)
		(layer "In4.Cu")
		(net "P5E_CPU1_P3_RX_DN<9>")
	)
	(segment
		(start 122.743468 -299.961554)
		(end 121.834656 -297.768264)
		(width 0.14224)
		(layer "In4.Cu")
		(net "P5E_CPU1_P3_RX_DN<9>")
	)
	(segment
		(start 122.131836 -293.20363)
		(end 122.13082 -293.203122)
		(width 0.1143)
		(layer "In4.Cu")
		(net "P5E_CPU1_P3_RX_DN<9>")
	)
	(segment
		(start 123.704858 -301.40021)
		(end 122.758962 -299.984668)
		(width 0.14224)
		(layer "In4.Cu")
		(net "P5E_CPU1_P3_RX_DN<9>")
	)
	(segment
		(start 134.657338 -316.105794)
		(end 132.572506 -312.205624)
		(width 0.14224)
		(layer "In4.Cu")
		(net "P5E_CPU1_P3_RX_DN<9>")
	)
	(segment
		(start 122.758708 -299.984668)
		(end 122.743468 -299.961554)
		(width 0.14224)
		(layer "In4.Cu")
		(net "P5E_CPU1_P3_RX_DN<9>")
	)
	(segment
		(start 126.163324 -375.697242)
		(end 126.296928 -375.556526)
		(width 0.14224)
		(layer "In4.Cu")
		(net "P5E_CPU1_P3_RX_DN<9>")
	)
	(segment
		(start 121.803668 -297.611292)
		(end 121.803668 -296.456608)
		(width 0.14224)
		(layer "In4.Cu")
		(net "P5E_CPU1_P3_RX_DN<9>")
	)
	(segment
		(start 121.803668 -296.42816)
		(end 121.849388 -296.38244)
		(width 0.1143)
		(layer "In4.Cu")
		(net "P5E_CPU1_P3_RX_DN<9>")
	)
	(segment
		(start 126.31547 -376.257566)
		(end 126.1745 -376.124216)
		(width 0.14224)
		(layer "In4.Cu")
		(net "P5E_CPU1_P3_RX_DN<9>")
	)
	(segment
		(start 122.092974 -293.872158)
		(end 122.118628 -293.857172)
		(width 0.1143)
		(layer "In4.Cu")
		(net "P5E_CPU1_P3_RX_DN<9>")
	)
	(segment
		(start 122.10161 -289.00628)
		(end 122.112278 -289.000184)
		(width 0.1143)
		(layer "In4.Cu")
		(net "P5E_CPU1_P3_RX_DN<9>")
	)
	(segment
		(start 126.105666 -380.701296)
		(end 126.135384 -380.275338)
		(width 0.14224)
		(layer "In4.Cu")
		(net "P5E_CPU1_P3_RX_DN<9>")
	)
	(segment
		(start 122.11431 -288.998914)
		(end 122.115326 -288.998406)
		(width 0.1143)
		(layer "In4.Cu")
		(net "P5E_CPU1_P3_RX_DN<9>")
	)
	(segment
		(start 122.12828 -291.581586)
		(end 122.12574 -291.580062)
		(width 0.1143)
		(layer "In4.Cu")
		(net "P5E_CPU1_P3_RX_DN<9>")
	)
	(segment
		(start 126.166626 -385.163822)
		(end 125.849634 -384.84683)
		(width 0.14224)
		(layer "In4.Cu")
		(net "P5E_CPU1_P3_RX_DN<9>")
	)
	(segment
		(start 122.143012 -292.222428)
		(end 122.145552 -292.221412)
		(width 0.1143)
		(layer "In4.Cu")
		(net "P5E_CPU1_P3_RX_DN<9>")
	)
	(segment
		(start 122.132598 -293.848282)
		(end 122.133868 -293.84752)
		(width 0.1143)
		(layer "In4.Cu")
		(net "P5E_CPU1_P3_RX_DN<9>")
	)
	(segment
		(start 126.04496 -385.404868)
		(end 126.166626 -385.334764)
		(width 0.14224)
		(layer "In4.Cu")
		(net "P5E_CPU1_P3_RX_DN<9>")
	)
	(segment
		(start 126.1745 -376.124216)
		(end 126.163324 -375.697242)
		(width 0.14224)
		(layer "In4.Cu")
		(net "P5E_CPU1_P3_RX_DN<9>")
	)
	(segment
		(start 122.09272 -292.251638)
		(end 122.10923 -292.241986)
		(width 0.1143)
		(layer "In4.Cu")
		(net "P5E_CPU1_P3_RX_DN<9>")
	)
	(segment
		(start 121.62282 -289.82162)
		(end 121.673874 -289.791648)
		(width 0.1143)
		(layer "In4.Cu")
		(net "P5E_CPU1_P3_RX_DN<9>")
	)
	(segment
		(start 132.572506 -312.205624)
		(end 128.138428 -306.80279)
		(width 0.14224)
		(layer "In4.Cu")
		(net "P5E_CPU1_P3_RX_DN<9>")
	)
	(segment
		(start 126.281688 -380.14783)
		(end 126.365 -378.961904)
		(width 0.14224)
		(layer "In4.Cu")
		(net "P5E_CPU1_P3_RX_DN<9>")
	)
	(segment
		(start 126.135384 -380.275338)
		(end 126.282196 -380.148084)
		(width 0.14224)
		(layer "In4.Cu")
		(net "P5E_CPU1_P3_RX_DN<9>")
	)
	(segment
		(start 122.133868 -294.824912)
		(end 122.132598 -294.82415)
		(width 0.1143)
		(layer "In4.Cu")
		(net "P5E_CPU1_P3_RX_DN<9>")
	)
	(segment
		(start 122.131836 -291.583618)
		(end 122.13082 -291.58311)
		(width 0.1143)
		(layer "In4.Cu")
		(net "P5E_CPU1_P3_RX_DN<9>")
	)
	(segment
		(start 122.129296 -293.202106)
		(end 122.09272 -293.18077)
		(width 0.1143)
		(layer "In4.Cu")
		(net "P5E_CPU1_P3_RX_DN<9>")
	)
	(segment
		(start 122.132598 -294.82415)
		(end 122.131836 -294.823642)
		(width 0.1143)
		(layer "In4.Cu")
		(net "P5E_CPU1_P3_RX_DN<9>")
	)
	(segment
		(start 122.162062 -293.221664)
		(end 122.139456 -293.20871)
		(width 0.1143)
		(layer "In4.Cu")
		(net "P5E_CPU1_P3_RX_DN<9>")
	)
	(segment
		(start 131.19227 -364.476538)
		(end 139.0904 -359.198926)
		(width 0.14224)
		(layer "In4.Cu")
		(net "P5E_CPU1_P3_RX_DN<9>")
	)
	(segment
		(start 126.11862 -383.970022)
		(end 126.11862 -382.478534)
		(width 0.14224)
		(layer "In4.Cu")
		(net "P5E_CPU1_P3_RX_DN<9>")
	)
	(segment
		(start 122.124724 -291.5793)
		(end 122.123454 -291.578538)
		(width 0.1143)
		(layer "In4.Cu")
		(net "P5E_CPU1_P3_RX_DN<9>")
	)
	(segment
		(start 126.044452 -385.405376)
		(end 126.04496 -385.404868)
		(width 0.14224)
		(layer "In4.Cu")
		(net "P5E_CPU1_P3_RX_DN<9>")
	)
	(segment
		(start 126.026672 -381.826516)
		(end 126.05639 -381.400558)
		(width 0.14224)
		(layer "In4.Cu")
		(net "P5E_CPU1_P3_RX_DN<9>")
	)
	(segment
		(start 122.163586 -291.60343)
		(end 122.154188 -291.597842)
		(width 0.1143)
		(layer "In4.Cu")
		(net "P5E_CPU1_P3_RX_DN<9>")
	)
	(segment
		(start 126.153926 -381.97282)
		(end 126.026672 -381.826516)
		(width 0.14224)
		(layer "In4.Cu")
		(net "P5E_CPU1_P3_RX_DN<9>")
	)
	(segment
		(start 122.145552 -292.221412)
		(end 122.156982 -292.215824)
		(width 0.1143)
		(layer "In4.Cu")
		(net "P5E_CPU1_P3_RX_DN<9>")
	)
	(segment
		(start 122.136408 -291.586158)
		(end 122.133868 -291.584888)
		(width 0.1143)
		(layer "In4.Cu")
		(net "P5E_CPU1_P3_RX_DN<9>")
	)
	(segment
		(start 122.133868 -293.84752)
		(end 122.135392 -293.846758)
		(width 0.1143)
		(layer "In4.Cu")
		(net "P5E_CPU1_P3_RX_DN<9>")
	)
	(segment
		(start 122.133868 -291.584888)
		(end 122.132598 -291.584126)
		(width 0.1143)
		(layer "In4.Cu")
		(net "P5E_CPU1_P3_RX_DN<9>")
	)
	(segment
		(start 140.565632 -336.929984)
		(end 139.145264 -329.023726)
		(width 0.14224)
		(layer "In4.Cu")
		(net "P5E_CPU1_P3_RX_DN<9>")
	)
	(segment
		(start 122.12828 -288.990786)
		(end 122.129296 -288.990278)
		(width 0.1143)
		(layer "In4.Cu")
		(net "P5E_CPU1_P3_RX_DN<9>")
	)
	(segment
		(start 122.141488 -292.223444)
		(end 122.143012 -292.222428)
		(width 0.1143)
		(layer "In4.Cu")
		(net "P5E_CPU1_P3_RX_DN<9>")
	)
	(segment
		(start 122.116088 -288.997898)
		(end 122.117104 -288.99739)
		(width 0.1143)
		(layer "In4.Cu")
		(net "P5E_CPU1_P3_RX_DN<9>")
	)
	(segment
		(start 125.849634 -384.84683)
		(end 125.85446 -384.235198)
		(width 0.14224)
		(layer "In4.Cu")
		(net "P5E_CPU1_P3_RX_DN<9>")
	)
	(segment
		(start 122.131836 -293.84879)
		(end 122.132598 -293.848282)
		(width 0.1143)
		(layer "In4.Cu")
		(net "P5E_CPU1_P3_RX_DN<9>")
	)
	(segment
		(start 126.232666 -380.849124)
		(end 126.23292 -380.847854)
		(width 0.14224)
		(layer "In4.Cu")
		(net "P5E_CPU1_P3_RX_DN<9>")
	)
	(segment
		(start 122.133106 -288.987738)
		(end 122.137678 -288.984944)
		(width 0.1143)
		(layer "In4.Cu")
		(net "P5E_CPU1_P3_RX_DN<9>")
	)
	(segment
		(start 122.132598 -291.584126)
		(end 122.131836 -291.583618)
		(width 0.1143)
		(layer "In4.Cu")
		(net "P5E_CPU1_P3_RX_DN<9>")
	)
	(segment
		(start 122.117104 -288.99739)
		(end 122.117866 -288.996882)
		(width 0.1143)
		(layer "In4.Cu")
		(net "P5E_CPU1_P3_RX_DN<9>")
	)
	(segment
		(start 122.121168 -288.995104)
		(end 122.122692 -288.994088)
		(width 0.1143)
		(layer "In4.Cu")
		(net "P5E_CPU1_P3_RX_DN<9>")
	)
	(segment
		(start 122.127772 -292.230048)
		(end 122.141488 -292.223444)
		(width 0.1143)
		(layer "In4.Cu")
		(net "P5E_CPU1_P3_RX_DN<9>")
	)
	(segment
		(start 126.296928 -375.556526)
		(end 126.256034 -373.99087)
		(width 0.14224)
		(layer "In4.Cu")
		(net "P5E_CPU1_P3_RX_DN<9>")
	)
	(segment
		(start 126.05639 -381.400558)
		(end 126.203202 -381.273304)
		(width 0.14224)
		(layer "In4.Cu")
		(net "P5E_CPU1_P3_RX_DN<9>")
	)
	(segment
		(start 122.154188 -291.597842)
		(end 122.136408 -291.586158)
		(width 0.1143)
		(layer "In4.Cu")
		(net "P5E_CPU1_P3_RX_DN<9>")
	)
	(segment
		(start 122.137678 -288.984944)
		(end 122.16384 -288.969704)
		(width 0.1143)
		(layer "In4.Cu")
		(net "P5E_CPU1_P3_RX_DN<9>")
	)
	(segment
		(start 122.112278 -289.000184)
		(end 122.113548 -288.999422)
		(width 0.1143)
		(layer "In4.Cu")
		(net "P5E_CPU1_P3_RX_DN<9>")
	)
	(segment
		(start 122.135392 -293.846758)
		(end 122.147838 -293.838376)
		(width 0.1143)
		(layer "In4.Cu")
		(net "P5E_CPU1_P3_RX_DN<9>")
	)
	(segment
		(start 122.113548 -288.999422)
		(end 122.11431 -288.998914)
		(width 0.1143)
		(layer "In4.Cu")
		(net "P5E_CPU1_P3_RX_DN<9>")
	)
	(segment
		(start 122.712734 -287.856422)
		(end 122.414792 -287.856422)
		(width 0.1143)
		(layer "In4.Cu")
		(net "P5E_CPU1_P3_RX_DN<9>")
	)
	(segment
		(start 126.166626 -385.334764)
		(end 126.166626 -385.163822)
		(width 0.14224)
		(layer "In4.Cu")
		(net "P5E_CPU1_P3_RX_DN<9>")
	)
	(segment
		(start 122.131836 -294.823642)
		(end 122.13082 -294.823134)
		(width 0.1143)
		(layer "In4.Cu")
		(net "P5E_CPU1_P3_RX_DN<9>")
	)
	(segment
		(start 126.11862 -382.478534)
		(end 126.153926 -381.97282)
		(width 0.14224)
		(layer "In4.Cu")
		(net "P5E_CPU1_P3_RX_DN<9>")
	)
	(segment
		(start 122.117866 -288.996882)
		(end 122.118882 -288.996374)
		(width 0.1143)
		(layer "In4.Cu")
		(net "P5E_CPU1_P3_RX_DN<9>")
	)
	(segment
		(start 122.118882 -288.996374)
		(end 122.119644 -288.995866)
		(width 0.1143)
		(layer "In4.Cu")
		(net "P5E_CPU1_P3_RX_DN<9>")
	)
	(segment
		(start 122.12574 -291.580062)
		(end 122.124724 -291.5793)
		(width 0.1143)
		(layer "In4.Cu")
		(net "P5E_CPU1_P3_RX_DN<9>")
	)
	(segment
		(start 140.565632 -356.438708)
		(end 140.565632 -336.929984)
		(width 0.14224)
		(layer "In4.Cu")
		(net "P5E_CPU1_P3_RX_DN<9>")
	)
	(segment
		(start 122.139456 -293.20871)
		(end 122.131836 -293.20363)
		(width 0.1143)
		(layer "In4.Cu")
		(net "P5E_CPU1_P3_RX_DN<9>")
	)
	(segment
		(start 126.23292 -380.847854)
		(end 126.105666 -380.701296)
		(width 0.14224)
		(layer "In4.Cu")
		(net "P5E_CPU1_P3_RX_DN<9>")
	)
	(segment
		(start 139.145264 -329.023726)
		(end 134.657338 -316.105794)
		(width 0.14224)
		(layer "In4.Cu")
		(net "P5E_CPU1_P3_RX_DN<9>")
	)
	(segment
		(start 122.122184 -292.23335)
		(end 122.127772 -292.230048)
		(width 0.1143)
		(layer "In4.Cu")
		(net "P5E_CPU1_P3_RX_DN<9>")
	)
	(segment
		(start 122.123454 -291.578538)
		(end 122.115326 -291.573458)
		(width 0.1143)
		(layer "In4.Cu")
		(net "P5E_CPU1_P3_RX_DN<9>")
	)
	(segment
		(start 122.13082 -293.203122)
		(end 122.129296 -293.202106)
		(width 0.1143)
		(layer "In4.Cu")
		(net "P5E_CPU1_P3_RX_DN<9>")
	)
	(segment
		(start 122.163586 -294.84193)
		(end 122.133868 -294.824912)
		(width 0.1143)
		(layer "In4.Cu")
		(net "P5E_CPU1_P3_RX_DN<9>")
	)
	(arc
		(start 121.849388 -291.088318)
		(mid 121.806091 -290.921242)
		(end 121.692416 -290.791392)
		(width 0.1143)
		(layer "In4.Cu")
		(net "P5E_CPU1_P3_RX_DN<9>")
	)
	(arc
		(start 122.09272 -293.18077)
		(mid 121.849393 -292.716204)
		(end 122.09272 -292.251638)
		(width 0.1143)
		(layer "In4.Cu")
		(net "P5E_CPU1_P3_RX_DN<9>")
	)
	(arc
		(start 122.319542 -288.676842)
		(mid 122.381533 -288.40867)
		(end 122.562874 -288.201608)
		(width 0.1143)
		(layer "In4.Cu")
		(net "P5E_CPU1_P3_RX_DN<9>")
	)
	(arc
		(start 128.951736 -367.65738)
		(mid 129.775947 -365.858418)
		(end 131.19227 -364.476538)
		(width 0.14224)
		(layer "In4.Cu")
		(net "P5E_CPU1_P3_RX_DN<9>")
	)
	(arc
		(start 121.62282 -290.750752)
		(mid 121.379493 -290.286186)
		(end 121.62282 -289.82162)
		(width 0.1143)
		(layer "In4.Cu")
		(net "P5E_CPU1_P3_RX_DN<9>")
	)
	(arc
		(start 122.128788 -294.821864)
		(mid 121.850556 -294.35677)
		(end 122.092974 -293.872158)
		(width 0.1143)
		(layer "In4.Cu")
		(net "P5E_CPU1_P3_RX_DN<9>")
	)
	(arc
		(start 122.077988 -295.502076)
		(mid 122.085562 -295.496551)
		(end 122.093228 -295.491154)
		(width 0.1143)
		(layer "In4.Cu")
		(net "P5E_CPU1_P3_RX_DN<9>")
	)
	(arc
		(start 122.16384 -288.969704)
		(mid 122.275987 -288.841496)
		(end 122.319542 -288.676842)
		(width 0.1143)
		(layer "In4.Cu")
		(net "P5E_CPU1_P3_RX_DN<9>")
	)
	(arc
		(start 122.319796 -295.146222)
		(mid 122.278456 -294.975207)
		(end 122.163586 -294.84193)
		(width 0.1143)
		(layer "In4.Cu")
		(net "P5E_CPU1_P3_RX_DN<9>")
	)
	(arc
		(start 121.673874 -289.791648)
		(mid 121.808857 -289.655846)
		(end 121.858278 -289.470846)
		(width 0.1143)
		(layer "In4.Cu")
		(net "P5E_CPU1_P3_RX_DN<9>")
	)
	(arc
		(start 122.163586 -292.212014)
		(mid 122.319514 -291.907722)
		(end 122.163586 -291.60343)
		(width 0.1143)
		(layer "In4.Cu")
		(net "P5E_CPU1_P3_RX_DN<9>")
	)
	(arc
		(start 122.164602 -295.449498)
		(mid 122.278697 -295.316677)
		(end 122.319796 -295.146476)
		(width 0.1143)
		(layer "In4.Cu")
		(net "P5E_CPU1_P3_RX_DN<9>")
	)
	(arc
		(start 122.162062 -293.830248)
		(mid 122.31799 -293.525956)
		(end 122.162062 -293.221664)
		(width 0.1143)
		(layer "In4.Cu")
		(net "P5E_CPU1_P3_RX_DN<9>")
	)
	(arc
		(start 126.365 -378.961904)
		(mid 126.375117 -378.741675)
		(end 126.374652 -378.521214)
		(width 0.14224)
		(layer "In4.Cu")
		(net "P5E_CPU1_P3_RX_DN<9>")
	)
	(arc
		(start 121.834656 -297.768264)
		(mid 121.811429 -297.691306)
		(end 121.803668 -297.611292)
		(width 0.14224)
		(layer "In4.Cu")
		(net "P5E_CPU1_P3_RX_DN<9>")
	)
	(arc
		(start 122.115326 -291.573458)
		(mid 121.922844 -291.363507)
		(end 121.849388 -291.088318)
		(width 0.1143)
		(layer "In4.Cu")
		(net "P5E_CPU1_P3_RX_DN<9>")
	)
	(arc
		(start 121.849388 -295.956228)
		(mid 121.849375 -295.952291)
		(end 121.849388 -295.948354)
		(width 0.1143)
		(layer "In4.Cu")
		(net "P5E_CPU1_P3_RX_DN<9>")
	)
	(arc
		(start 127.638556 -371.606064)
		(mid 127.998462 -371.133043)
		(end 128.2192 -370.581174)
		(width 0.14224)
		(layer "In4.Cu")
		(net "P5E_CPU1_P3_RX_DN<9>")
	)
	(arc
		(start 126.256034 -373.99087)
		(mid 126.41708 -373.08866)
		(end 126.92126 -372.32336)
		(width 0.14224)
		(layer "In4.Cu")
		(net "P5E_CPU1_P3_RX_DN<9>")
	)
	(arc
		(start 121.849388 -295.948354)
		(mid 121.914734 -295.700131)
		(end 122.077988 -295.502076)
		(width 0.1143)
		(layer "In4.Cu")
		(net "P5E_CPU1_P3_RX_DN<9>")
	)
	(arc
		(start 121.858278 -289.470846)
		(mid 121.922793 -289.208627)
		(end 122.10161 -289.00628)
		(width 0.1143)
		(layer "In4.Cu")
		(net "P5E_CPU1_P3_RX_DN<9>")
	)
	(arc
		(start 122.093228 -295.491154)
		(mid 122.093609 -295.4909)
		(end 122.09399 -295.490646)
		(width 0.1143)
		(layer "In4.Cu")
		(net "P5E_CPU1_P3_RX_DN<9>")
	)
	(arc
		(start 122.634502 -288.159952)
		(mid 122.730942 -288.057297)
		(end 122.782584 -287.926272)
		(width 0.1143)
		(layer "In4.Cu")
		(net "P5E_CPU1_P3_RX_DN<9>")
	)
	(arc
		(start 139.0904 -359.198926)
		(mid 140.173711 -358.003573)
		(end 140.565632 -356.438708)
		(width 0.14224)
		(layer "In4.Cu")
		(net "P5E_CPU1_P3_RX_DN<9>")
	)
	(segment
		(start 119.127778 -289.210242)
		(end 119.59463 -289.47618)
		(width 0.12954)
		(layer "F.Cu")
		(net "P5E_CPU1_P3_RX_DN<8>")
	)
	(segment
		(start 123.970542 -385.31038)
		(end 124.491242 -385.31038)
		(width 0.127)
		(layer "F.Cu")
		(net "P5E_CPU1_P3_RX_DN<8>")
	)
	(segment
		(start 125.227588 -377.456446)
		(end 125.187202 -375.913904)
		(width 0.14224)
		(layer "In4.Cu")
		(net "P5E_CPU1_P3_RX_DN<8>")
	)
	(segment
		(start 120.863868 -297.688762)
		(end 120.863868 -296.463212)
		(width 0.14224)
		(layer "In4.Cu")
		(net "P5E_CPU1_P3_RX_DN<8>")
	)
	(segment
		(start 139.633452 -337.0326)
		(end 138.261598 -329.395582)
		(width 0.14224)
		(layer "In4.Cu")
		(net "P5E_CPU1_P3_RX_DN<8>")
	)
	(segment
		(start 124.654564 -384.23469)
		(end 124.958602 -383.930652)
		(width 0.14224)
		(layer "In4.Cu")
		(net "P5E_CPU1_P3_RX_DN<8>")
	)
	(segment
		(start 127.165608 -370.153184)
		(end 127.736854 -367.870994)
		(width 0.14224)
		(layer "In4.Cu")
		(net "P5E_CPU1_P3_RX_DN<8>")
	)
	(segment
		(start 124.96673 -385.334764)
		(end 124.96673 -385.163822)
		(width 0.14224)
		(layer "In4.Cu")
		(net "P5E_CPU1_P3_RX_DN<8>")
	)
	(segment
		(start 125.116082 -379.915928)
		(end 125.199902 -378.719842)
		(width 0.14224)
		(layer "In4.Cu")
		(net "P5E_CPU1_P3_RX_DN<8>")
	)
	(segment
		(start 127.7366 -367.870994)
		(end 127.736854 -367.87074)
		(width 0.14224)
		(layer "In4.Cu")
		(net "P5E_CPU1_P3_RX_DN<8>")
	)
	(segment
		(start 124.96673 -385.163822)
		(end 124.649738 -384.84683)
		(width 0.14224)
		(layer "In4.Cu")
		(net "P5E_CPU1_P3_RX_DN<8>")
	)
	(segment
		(start 125.06706 -380.615698)
		(end 125.067314 -380.615698)
		(width 0.14224)
		(layer "In4.Cu")
		(net "P5E_CPU1_P3_RX_DN<8>")
	)
	(segment
		(start 121.191782 -293.84879)
		(end 121.222262 -293.83101)
		(width 0.1143)
		(layer "In4.Cu")
		(net "P5E_CPU1_P3_RX_DN<8>")
	)
	(segment
		(start 120.909588 -296.389044)
		(end 120.909588 -296.172636)
		(width 0.1143)
		(layer "In4.Cu")
		(net "P5E_CPU1_P3_RX_DN<8>")
	)
	(segment
		(start 121.152666 -292.251638)
		(end 121.191782 -292.228778)
		(width 0.1143)
		(layer "In4.Cu")
		(net "P5E_CPU1_P3_RX_DN<8>")
	)
	(segment
		(start 121.854214 -300.329346)
		(end 120.958864 -298.167044)
		(width 0.14224)
		(layer "In4.Cu")
		(net "P5E_CPU1_P3_RX_DN<8>")
	)
	(segment
		(start 121.191782 -293.20363)
		(end 121.152666 -293.18077)
		(width 0.1143)
		(layer "In4.Cu")
		(net "P5E_CPU1_P3_RX_DN<8>")
	)
	(segment
		(start 133.881114 -316.78372)
		(end 131.562348 -312.444638)
		(width 0.14224)
		(layer "In4.Cu")
		(net "P5E_CPU1_P3_RX_DN<8>")
	)
	(segment
		(start 121.222262 -294.841422)
		(end 121.191782 -294.823642)
		(width 0.1143)
		(layer "In4.Cu")
		(net "P5E_CPU1_P3_RX_DN<8>")
	)
	(segment
		(start 124.861066 -381.59436)
		(end 124.890784 -381.168402)
		(width 0.14224)
		(layer "In4.Cu")
		(net "P5E_CPU1_P3_RX_DN<8>")
	)
	(segment
		(start 125.037088 -381.040894)
		(end 125.06706 -380.615698)
		(width 0.14224)
		(layer "In4.Cu")
		(net "P5E_CPU1_P3_RX_DN<8>")
	)
	(segment
		(start 124.890784 -381.168402)
		(end 125.037596 -381.041148)
		(width 0.14224)
		(layer "In4.Cu")
		(net "P5E_CPU1_P3_RX_DN<8>")
	)
	(segment
		(start 131.562348 -312.444638)
		(end 122.884692 -301.871634)
		(width 0.14224)
		(layer "In4.Cu")
		(net "P5E_CPU1_P3_RX_DN<8>")
	)
	(segment
		(start 120.753378 -290.7919)
		(end 120.72874 -290.777676)
		(width 0.1143)
		(layer "In4.Cu")
		(net "P5E_CPU1_P3_RX_DN<8>")
	)
	(segment
		(start 125.046232 -375.7803)
		(end 125.035056 -375.35358)
		(width 0.14224)
		(layer "In4.Cu")
		(net "P5E_CPU1_P3_RX_DN<8>")
	)
	(segment
		(start 121.222262 -291.601398)
		(end 121.191782 -291.583618)
		(width 0.1143)
		(layer "In4.Cu")
		(net "P5E_CPU1_P3_RX_DN<8>")
	)
	(segment
		(start 120.252236 -289.96386)
		(end 120.251474 -289.963352)
		(width 0.1143)
		(layer "In4.Cu")
		(net "P5E_CPU1_P3_RX_DN<8>")
	)
	(segment
		(start 125.187202 -375.913904)
		(end 125.046232 -375.7803)
		(width 0.14224)
		(layer "In4.Cu")
		(net "P5E_CPU1_P3_RX_DN<8>")
	)
	(segment
		(start 136.071356 -323.08927)
		(end 136.071356 -323.089524)
		(width 0.14224)
		(layer "In4.Cu")
		(net "P5E_CPU1_P3_RX_DN<8>")
	)
	(segment
		(start 125.116336 -379.915928)
		(end 125.116082 -379.915928)
		(width 0.14224)
		(layer "In4.Cu")
		(net "P5E_CPU1_P3_RX_DN<8>")
	)
	(segment
		(start 125.037596 -381.041148)
		(end 125.037088 -381.040894)
		(width 0.14224)
		(layer "In4.Cu")
		(net "P5E_CPU1_P3_RX_DN<8>")
	)
	(segment
		(start 121.191782 -294.823642)
		(end 121.152666 -294.800782)
		(width 0.1143)
		(layer "In4.Cu")
		(net "P5E_CPU1_P3_RX_DN<8>")
	)
	(segment
		(start 122.884692 -301.871634)
		(end 121.854214 -300.329346)
		(width 0.14224)
		(layer "In4.Cu")
		(net "P5E_CPU1_P3_RX_DN<8>")
	)
	(segment
		(start 120.72239 -290.77412)
		(end 120.721628 -290.773612)
		(width 0.1143)
		(layer "In4.Cu")
		(net "P5E_CPU1_P3_RX_DN<8>")
	)
	(segment
		(start 120.72366 -290.774882)
		(end 120.72239 -290.77412)
		(width 0.1143)
		(layer "In4.Cu")
		(net "P5E_CPU1_P3_RX_DN<8>")
	)
	(segment
		(start 120.251474 -289.963352)
		(end 120.213374 -289.941254)
		(width 0.1143)
		(layer "In4.Cu")
		(net "P5E_CPU1_P3_RX_DN<8>")
	)
	(segment
		(start 121.152666 -293.87165)
		(end 121.191782 -293.84879)
		(width 0.1143)
		(layer "In4.Cu")
		(net "P5E_CPU1_P3_RX_DN<8>")
	)
	(segment
		(start 125.035056 -375.35358)
		(end 125.16866 -375.212864)
		(width 0.14224)
		(layer "In4.Cu")
		(net "P5E_CPU1_P3_RX_DN<8>")
	)
	(segment
		(start 121.191782 -292.228778)
		(end 121.222262 -292.210998)
		(width 0.1143)
		(layer "In4.Cu")
		(net "P5E_CPU1_P3_RX_DN<8>")
	)
	(segment
		(start 121.191782 -291.583618)
		(end 121.152666 -291.560758)
		(width 0.1143)
		(layer "In4.Cu")
		(net "P5E_CPU1_P3_RX_DN<8>")
	)
	(segment
		(start 124.845064 -385.404868)
		(end 124.96673 -385.334764)
		(width 0.14224)
		(layer "In4.Cu")
		(net "P5E_CPU1_P3_RX_DN<8>")
	)
	(segment
		(start 119.975376 -289.558984)
		(end 119.892572 -289.47618)
		(width 0.1143)
		(layer "In4.Cu")
		(net "P5E_CPU1_P3_RX_DN<8>")
	)
	(segment
		(start 124.649738 -384.84683)
		(end 124.654564 -384.23469)
		(width 0.14224)
		(layer "In4.Cu")
		(net "P5E_CPU1_P3_RX_DN<8>")
	)
	(segment
		(start 127.736854 -367.870994)
		(end 127.7366 -367.870994)
		(width 0.14224)
		(layer "In4.Cu")
		(net "P5E_CPU1_P3_RX_DN<8>")
	)
	(segment
		(start 126.09576 -371.6528)
		(end 126.604014 -371.144546)
		(width 0.14224)
		(layer "In4.Cu")
		(net "P5E_CPU1_P3_RX_DN<8>")
	)
	(segment
		(start 120.909588 -296.172636)
		(end 120.909334 -295.956228)
		(width 0.1143)
		(layer "In4.Cu")
		(net "P5E_CPU1_P3_RX_DN<8>")
	)
	(segment
		(start 139.633452 -355.987604)
		(end 139.633452 -337.0326)
		(width 0.14224)
		(layer "In4.Cu")
		(net "P5E_CPU1_P3_RX_DN<8>")
	)
	(segment
		(start 136.071356 -323.089524)
		(end 133.881114 -316.78372)
		(width 0.14224)
		(layer "In4.Cu")
		(net "P5E_CPU1_P3_RX_DN<8>")
	)
	(segment
		(start 120.72874 -290.777676)
		(end 120.727724 -290.777168)
		(width 0.1143)
		(layer "In4.Cu")
		(net "P5E_CPU1_P3_RX_DN<8>")
	)
	(segment
		(start 119.892572 -289.47618)
		(end 119.59463 -289.47618)
		(width 0.1143)
		(layer "In4.Cu")
		(net "P5E_CPU1_P3_RX_DN<8>")
	)
	(segment
		(start 130.67665 -363.69625)
		(end 138.200384 -358.668828)
		(width 0.14224)
		(layer "In4.Cu")
		(net "P5E_CPU1_P3_RX_DN<8>")
	)
	(segment
		(start 124.958602 -382.166368)
		(end 124.98832 -381.740918)
		(width 0.14224)
		(layer "In4.Cu")
		(net "P5E_CPU1_P3_RX_DN<8>")
	)
	(segment
		(start 120.721628 -290.773612)
		(end 120.711722 -290.767516)
		(width 0.1143)
		(layer "In4.Cu")
		(net "P5E_CPU1_P3_RX_DN<8>")
	)
	(segment
		(start 120.863868 -296.463212)
		(end 120.863868 -296.434764)
		(width 0.1143)
		(layer "In4.Cu")
		(net "P5E_CPU1_P3_RX_DN<8>")
	)
	(segment
		(start 124.491242 -385.31038)
		(end 124.844556 -385.405376)
		(width 0.14224)
		(layer "In4.Cu")
		(net "P5E_CPU1_P3_RX_DN<8>")
	)
	(segment
		(start 120.25503 -289.965384)
		(end 120.252236 -289.96386)
		(width 0.1143)
		(layer "In4.Cu")
		(net "P5E_CPU1_P3_RX_DN<8>")
	)
	(segment
		(start 124.844556 -385.405376)
		(end 124.845064 -385.404868)
		(width 0.14224)
		(layer "In4.Cu")
		(net "P5E_CPU1_P3_RX_DN<8>")
	)
	(segment
		(start 138.261598 -329.395582)
		(end 136.071356 -323.08927)
		(width 0.14224)
		(layer "In4.Cu")
		(net "P5E_CPU1_P3_RX_DN<8>")
	)
	(segment
		(start 124.98832 -381.740918)
		(end 124.861066 -381.59436)
		(width 0.14224)
		(layer "In4.Cu")
		(net "P5E_CPU1_P3_RX_DN<8>")
	)
	(segment
		(start 124.94006 -380.46914)
		(end 124.969778 -380.043182)
		(width 0.14224)
		(layer "In4.Cu")
		(net "P5E_CPU1_P3_RX_DN<8>")
	)
	(segment
		(start 120.727724 -290.777168)
		(end 120.7262 -290.776152)
		(width 0.1143)
		(layer "In4.Cu")
		(net "P5E_CPU1_P3_RX_DN<8>")
	)
	(segment
		(start 124.958602 -383.930652)
		(end 124.958602 -382.166368)
		(width 0.14224)
		(layer "In4.Cu")
		(net "P5E_CPU1_P3_RX_DN<8>")
	)
	(segment
		(start 121.15419 -295.490646)
		(end 121.222262 -295.451022)
		(width 0.1143)
		(layer "In4.Cu")
		(net "P5E_CPU1_P3_RX_DN<8>")
	)
	(segment
		(start 125.067314 -380.615698)
		(end 124.94006 -380.46914)
		(width 0.14224)
		(layer "In4.Cu")
		(net "P5E_CPU1_P3_RX_DN<8>")
	)
	(segment
		(start 124.969778 -380.043182)
		(end 125.116336 -379.915928)
		(width 0.14224)
		(layer "In4.Cu")
		(net "P5E_CPU1_P3_RX_DN<8>")
	)
	(segment
		(start 121.222262 -293.22141)
		(end 121.191782 -293.20363)
		(width 0.1143)
		(layer "In4.Cu")
		(net "P5E_CPU1_P3_RX_DN<8>")
	)
	(segment
		(start 120.863868 -296.434764)
		(end 120.909588 -296.389044)
		(width 0.1143)
		(layer "In4.Cu")
		(net "P5E_CPU1_P3_RX_DN<8>")
	)
	(segment
		(start 125.16866 -375.212864)
		(end 125.138434 -374.052338)
		(width 0.14224)
		(layer "In4.Cu")
		(net "P5E_CPU1_P3_RX_DN<8>")
	)
	(segment
		(start 120.7262 -290.776152)
		(end 120.72366 -290.774882)
		(width 0.1143)
		(layer "In4.Cu")
		(net "P5E_CPU1_P3_RX_DN<8>")
	)
	(arc
		(start 120.711722 -290.767516)
		(mid 120.511664 -290.561727)
		(end 120.438672 -290.284154)
		(width 0.1143)
		(layer "In4.Cu")
		(net "P5E_CPU1_P3_RX_DN<8>")
	)
	(arc
		(start 120.909334 -295.956228)
		(mid 120.974274 -295.693198)
		(end 121.15419 -295.490646)
		(width 0.1143)
		(layer "In4.Cu")
		(net "P5E_CPU1_P3_RX_DN<8>")
	)
	(arc
		(start 138.200384 -358.668828)
		(mid 139.252706 -357.507689)
		(end 139.633452 -355.987604)
		(width 0.14224)
		(layer "In4.Cu")
		(net "P5E_CPU1_P3_RX_DN<8>")
	)
	(arc
		(start 126.604014 -371.144546)
		(mid 126.952156 -370.687015)
		(end 127.165608 -370.153184)
		(width 0.14224)
		(layer "In4.Cu")
		(net "P5E_CPU1_P3_RX_DN<8>")
	)
	(arc
		(start 120.438672 -290.284154)
		(mid 120.389483 -290.100203)
		(end 120.25503 -289.965384)
		(width 0.1143)
		(layer "In4.Cu")
		(net "P5E_CPU1_P3_RX_DN<8>")
	)
	(arc
		(start 121.152666 -294.800782)
		(mid 120.909339 -294.336216)
		(end 121.152666 -293.87165)
		(width 0.1143)
		(layer "In4.Cu")
		(net "P5E_CPU1_P3_RX_DN<8>")
	)
	(arc
		(start 121.152666 -291.560758)
		(mid 120.973853 -291.358408)
		(end 120.909334 -291.096192)
		(width 0.1143)
		(layer "In4.Cu")
		(net "P5E_CPU1_P3_RX_DN<8>")
	)
	(arc
		(start 120.909334 -291.096192)
		(mid 120.868079 -290.925221)
		(end 120.753378 -290.7919)
		(width 0.1143)
		(layer "In4.Cu")
		(net "P5E_CPU1_P3_RX_DN<8>")
	)
	(arc
		(start 120.212612 -289.940746)
		(mid 120.060625 -289.784238)
		(end 119.979186 -289.581844)
		(width 0.1143)
		(layer "In4.Cu")
		(net "P5E_CPU1_P3_RX_DN<8>")
	)
	(arc
		(start 127.736854 -367.87074)
		(mid 128.818111 -365.50981)
		(end 130.67665 -363.69625)
		(width 0.14224)
		(layer "In4.Cu")
		(net "P5E_CPU1_P3_RX_DN<8>")
	)
	(arc
		(start 120.213374 -289.941254)
		(mid 120.212993 -289.941)
		(end 120.212612 -289.940746)
		(width 0.1143)
		(layer "In4.Cu")
		(net "P5E_CPU1_P3_RX_DN<8>")
	)
	(arc
		(start 120.958864 -298.167044)
		(mid 120.887791 -297.932583)
		(end 120.863868 -297.688762)
		(width 0.14224)
		(layer "In4.Cu")
		(net "P5E_CPU1_P3_RX_DN<8>")
	)
	(arc
		(start 121.222262 -293.83101)
		(mid 121.379239 -293.52621)
		(end 121.222262 -293.22141)
		(width 0.1143)
		(layer "In4.Cu")
		(net "P5E_CPU1_P3_RX_DN<8>")
	)
	(arc
		(start 121.222262 -292.210998)
		(mid 121.379239 -291.906198)
		(end 121.222262 -291.601398)
		(width 0.1143)
		(layer "In4.Cu")
		(net "P5E_CPU1_P3_RX_DN<8>")
	)
	(arc
		(start 121.222262 -295.451022)
		(mid 121.379239 -295.146222)
		(end 121.222262 -294.841422)
		(width 0.1143)
		(layer "In4.Cu")
		(net "P5E_CPU1_P3_RX_DN<8>")
	)
	(arc
		(start 119.979186 -289.581844)
		(mid 119.977163 -289.570434)
		(end 119.975376 -289.558984)
		(width 0.1143)
		(layer "In4.Cu")
		(net "P5E_CPU1_P3_RX_DN<8>")
	)
	(arc
		(start 125.138434 -374.052338)
		(mid 125.370302 -372.754118)
		(end 126.09576 -371.6528)
		(width 0.14224)
		(layer "In4.Cu")
		(net "P5E_CPU1_P3_RX_DN<8>")
	)
	(arc
		(start 125.199902 -378.719842)
		(mid 125.228933 -378.088477)
		(end 125.227588 -377.456446)
		(width 0.14224)
		(layer "In4.Cu")
		(net "P5E_CPU1_P3_RX_DN<8>")
	)
	(arc
		(start 121.152666 -293.18077)
		(mid 120.909339 -292.716204)
		(end 121.152666 -292.251638)
		(width 0.1143)
		(layer "In4.Cu")
		(net "P5E_CPU1_P3_RX_DN<8>")
	)
	(segment
		(start 119.127778 -290.830254)
		(end 119.59463 -291.096192)
		(width 0.12954)
		(layer "F.Cu")
		(net "P5E_CPU1_P3_RX_DN<7>")
	)
	(segment
		(start 122.770646 -385.31038)
		(end 123.291346 -385.31038)
		(width 0.127)
		(layer "F.Cu")
		(net "P5E_CPU1_P3_RX_DN<7>")
	)
	(segment
		(start 123.76658 -385.163822)
		(end 123.449588 -384.84683)
		(width 0.14224)
		(layer "In4.Cu")
		(net "P5E_CPU1_P3_RX_DN<7>")
	)
	(segment
		(start 120.24106 -293.85514)
		(end 120.244108 -293.853108)
		(width 0.1143)
		(layer "In4.Cu")
		(net "P5E_CPU1_P3_RX_DN<7>")
	)
	(segment
		(start 137.377932 -329.750928)
		(end 137.31621 -329.515724)
		(width 0.14224)
		(layer "In4.Cu")
		(net "P5E_CPU1_P3_RX_DN<7>")
	)
	(segment
		(start 123.449588 -384.84683)
		(end 123.454414 -384.234944)
		(width 0.14224)
		(layer "In4.Cu")
		(net "P5E_CPU1_P3_RX_DN<7>")
	)
	(segment
		(start 137.31621 -329.515724)
		(end 133.027166 -317.167514)
		(width 0.14224)
		(layer "In4.Cu")
		(net "P5E_CPU1_P3_RX_DN<7>")
	)
	(segment
		(start 120.244616 -293.199312)
		(end 120.213374 -293.181278)
		(width 0.1143)
		(layer "In4.Cu")
		(net "P5E_CPU1_P3_RX_DN<7>")
	)
	(segment
		(start 120.212866 -293.871142)
		(end 120.24106 -293.85514)
		(width 0.1143)
		(layer "In4.Cu")
		(net "P5E_CPU1_P3_RX_DN<7>")
	)
	(segment
		(start 120.248172 -293.850314)
		(end 120.249188 -293.849806)
		(width 0.1143)
		(layer "In4.Cu")
		(net "P5E_CPU1_P3_RX_DN<7>")
	)
	(segment
		(start 123.809252 -381.54356)
		(end 123.682252 -381.397002)
		(width 0.14224)
		(layer "In4.Cu")
		(net "P5E_CPU1_P3_RX_DN<7>")
	)
	(segment
		(start 123.858528 -380.844044)
		(end 123.888246 -380.418594)
		(width 0.14224)
		(layer "In4.Cu")
		(net "P5E_CPU1_P3_RX_DN<7>")
	)
	(segment
		(start 123.888246 -380.418594)
		(end 123.760992 -380.272036)
		(width 0.14224)
		(layer "In4.Cu")
		(net "P5E_CPU1_P3_RX_DN<7>")
	)
	(segment
		(start 120.251474 -294.823388)
		(end 120.24868 -294.82161)
		(width 0.1143)
		(layer "In4.Cu")
		(net "P5E_CPU1_P3_RX_DN<7>")
	)
	(segment
		(start 123.76658 -385.334764)
		(end 123.76658 -385.163822)
		(width 0.14224)
		(layer "In4.Cu")
		(net "P5E_CPU1_P3_RX_DN<7>")
	)
	(segment
		(start 123.966732 -379.293628)
		(end 123.96724 -379.293374)
		(width 0.14224)
		(layer "In4.Cu")
		(net "P5E_CPU1_P3_RX_DN<7>")
	)
	(segment
		(start 123.937522 -379.718824)
		(end 123.937014 -379.71857)
		(width 0.14224)
		(layer "In4.Cu")
		(net "P5E_CPU1_P3_RX_DN<7>")
	)
	(segment
		(start 119.97563 -291.178996)
		(end 119.975376 -291.178996)
		(width 0.1143)
		(layer "In4.Cu")
		(net "P5E_CPU1_P3_RX_DN<7>")
	)
	(segment
		(start 120.249188 -293.849806)
		(end 120.24995 -293.849298)
		(width 0.1143)
		(layer "In4.Cu")
		(net "P5E_CPU1_P3_RX_DN<7>")
	)
	(segment
		(start 120.265444 -294.831516)
		(end 120.251474 -294.823388)
		(width 0.1143)
		(layer "In4.Cu")
		(net "P5E_CPU1_P3_RX_DN<7>")
	)
	(segment
		(start 129.470912 -363.015276)
		(end 137.40511 -357.713788)
		(width 0.14224)
		(layer "In4.Cu")
		(net "P5E_CPU1_P3_RX_DN<7>")
	)
	(segment
		(start 123.79071 -379.846078)
		(end 123.937522 -379.718824)
		(width 0.14224)
		(layer "In4.Cu")
		(net "P5E_CPU1_P3_RX_DN<7>")
	)
	(segment
		(start 123.644406 -385.405376)
		(end 123.644914 -385.404868)
		(width 0.14224)
		(layer "In4.Cu")
		(net "P5E_CPU1_P3_RX_DN<7>")
	)
	(segment
		(start 123.454414 -384.234944)
		(end 123.758452 -383.930906)
		(width 0.14224)
		(layer "In4.Cu")
		(net "P5E_CPU1_P3_RX_DN<7>")
	)
	(segment
		(start 123.760992 -380.272036)
		(end 123.79071 -379.846078)
		(width 0.14224)
		(layer "In4.Cu")
		(net "P5E_CPU1_P3_RX_DN<7>")
	)
	(segment
		(start 122.428254 -370.827554)
		(end 122.432572 -370.816886)
		(width 0.14224)
		(layer "In4.Cu")
		(net "P5E_CPU1_P3_RX_DN<7>")
	)
	(segment
		(start 124.092462 -376.879612)
		(end 124.011944 -373.810784)
		(width 0.14224)
		(layer "In4.Cu")
		(net "P5E_CPU1_P3_RX_DN<7>")
	)
	(segment
		(start 120.244616 -295.47312)
		(end 120.24614 -295.472104)
		(width 0.1143)
		(layer "In4.Cu")
		(net "P5E_CPU1_P3_RX_DN<7>")
	)
	(segment
		(start 119.969534 -296.388536)
		(end 119.969534 -295.847262)
		(width 0.1143)
		(layer "In4.Cu")
		(net "P5E_CPU1_P3_RX_DN<7>")
	)
	(segment
		(start 123.35891 -372.916958)
		(end 123.111006 -372.814342)
		(width 0.14224)
		(layer "In4.Cu")
		(net "P5E_CPU1_P3_RX_DN<7>")
	)
	(segment
		(start 119.923814 -296.434256)
		(end 119.969534 -296.388536)
		(width 0.1143)
		(layer "In4.Cu")
		(net "P5E_CPU1_P3_RX_DN<7>")
	)
	(segment
		(start 122.807222 -372.611142)
		(end 122.805952 -372.609872)
		(width 0.14224)
		(layer "In4.Cu")
		(net "P5E_CPU1_P3_RX_DN<7>")
	)
	(segment
		(start 120.215914 -295.489376)
		(end 120.244616 -295.47312)
		(width 0.1143)
		(layer "In4.Cu")
		(net "P5E_CPU1_P3_RX_DN<7>")
	)
	(segment
		(start 130.784092 -312.970672)
		(end 122.138948 -302.43653)
		(width 0.14224)
		(layer "In4.Cu")
		(net "P5E_CPU1_P3_RX_DN<7>")
	)
	(segment
		(start 123.682252 -381.397002)
		(end 123.71197 -380.971298)
		(width 0.14224)
		(layer "In4.Cu")
		(net "P5E_CPU1_P3_RX_DN<7>")
	)
	(segment
		(start 120.24614 -295.472104)
		(end 120.289828 -295.443148)
		(width 0.1143)
		(layer "In4.Cu")
		(net "P5E_CPU1_P3_RX_DN<7>")
	)
	(segment
		(start 120.244616 -294.819324)
		(end 120.213374 -294.80129)
		(width 0.1143)
		(layer "In4.Cu")
		(net "P5E_CPU1_P3_RX_DN<7>")
	)
	(segment
		(start 120.24868 -293.201598)
		(end 120.244616 -293.199312)
		(width 0.1143)
		(layer "In4.Cu")
		(net "P5E_CPU1_P3_RX_DN<7>")
	)
	(segment
		(start 120.24868 -294.82161)
		(end 120.244616 -294.819324)
		(width 0.1143)
		(layer "In4.Cu")
		(net "P5E_CPU1_P3_RX_DN<7>")
	)
	(segment
		(start 123.291346 -385.31038)
		(end 123.644406 -385.405376)
		(width 0.14224)
		(layer "In4.Cu")
		(net "P5E_CPU1_P3_RX_DN<7>")
	)
	(segment
		(start 120.251474 -293.203376)
		(end 120.24868 -293.201598)
		(width 0.1143)
		(layer "In4.Cu")
		(net "P5E_CPU1_P3_RX_DN<7>")
	)
	(segment
		(start 120.265444 -293.211504)
		(end 120.251474 -293.203376)
		(width 0.1143)
		(layer "In4.Cu")
		(net "P5E_CPU1_P3_RX_DN<7>")
	)
	(segment
		(start 123.839986 -379.146816)
		(end 123.869704 -378.720858)
		(width 0.14224)
		(layer "In4.Cu")
		(net "P5E_CPU1_P3_RX_DN<7>")
	)
	(segment
		(start 120.244108 -293.853108)
		(end 120.248172 -293.850314)
		(width 0.1143)
		(layer "In4.Cu")
		(net "P5E_CPU1_P3_RX_DN<7>")
	)
	(segment
		(start 120.252236 -291.583618)
		(end 120.213374 -291.561266)
		(width 0.1143)
		(layer "In4.Cu")
		(net "P5E_CPU1_P3_RX_DN<7>")
	)
	(segment
		(start 123.326398 -369.364768)
		(end 127.68834 -364.552738)
		(width 0.14224)
		(layer "In4.Cu")
		(net "P5E_CPU1_P3_RX_DN<7>")
	)
	(segment
		(start 122.138948 -302.43653)
		(end 121.03735 -300.804834)
		(width 0.14224)
		(layer "In4.Cu")
		(net "P5E_CPU1_P3_RX_DN<7>")
	)
	(segment
		(start 138.701272 -337.116166)
		(end 137.377932 -329.750928)
		(width 0.14224)
		(layer "In4.Cu")
		(net "P5E_CPU1_P3_RX_DN<7>")
	)
	(segment
		(start 123.71197 -380.971298)
		(end 123.858528 -380.844044)
		(width 0.14224)
		(layer "In4.Cu")
		(net "P5E_CPU1_P3_RX_DN<7>")
	)
	(segment
		(start 119.923814 -297.960542)
		(end 119.923814 -296.462704)
		(width 0.14224)
		(layer "In4.Cu")
		(net "P5E_CPU1_P3_RX_DN<7>")
	)
	(segment
		(start 123.758452 -382.27254)
		(end 123.809252 -381.54356)
		(width 0.14224)
		(layer "In4.Cu")
		(net "P5E_CPU1_P3_RX_DN<7>")
	)
	(segment
		(start 119.975376 -291.178996)
		(end 119.892572 -291.096192)
		(width 0.1143)
		(layer "In4.Cu")
		(net "P5E_CPU1_P3_RX_DN<7>")
	)
	(segment
		(start 123.644914 -385.404868)
		(end 123.76658 -385.334764)
		(width 0.14224)
		(layer "In4.Cu")
		(net "P5E_CPU1_P3_RX_DN<7>")
	)
	(segment
		(start 120.289828 -295.443148)
		(end 120.290844 -295.443148)
		(width 0.1143)
		(layer "In4.Cu")
		(net "P5E_CPU1_P3_RX_DN<7>")
	)
	(segment
		(start 133.027166 -317.167514)
		(end 130.784092 -312.970672)
		(width 0.14224)
		(layer "In4.Cu")
		(net "P5E_CPU1_P3_RX_DN<7>")
	)
	(segment
		(start 123.937014 -379.71857)
		(end 123.966732 -379.293628)
		(width 0.14224)
		(layer "In4.Cu")
		(net "P5E_CPU1_P3_RX_DN<7>")
	)
	(segment
		(start 119.923814 -296.462704)
		(end 119.923814 -296.434256)
		(width 0.1143)
		(layer "In4.Cu")
		(net "P5E_CPU1_P3_RX_DN<7>")
	)
	(segment
		(start 120.213374 -292.25113)
		(end 120.252236 -292.228778)
		(width 0.1143)
		(layer "In4.Cu")
		(net "P5E_CPU1_P3_RX_DN<7>")
	)
	(segment
		(start 120.289828 -293.823136)
		(end 120.290844 -293.823136)
		(width 0.1143)
		(layer "In4.Cu")
		(net "P5E_CPU1_P3_RX_DN<7>")
	)
	(segment
		(start 119.892572 -291.096192)
		(end 119.59463 -291.096192)
		(width 0.1143)
		(layer "In4.Cu")
		(net "P5E_CPU1_P3_RX_DN<7>")
	)
	(segment
		(start 138.701272 -355.28885)
		(end 138.701272 -337.116166)
		(width 0.14224)
		(layer "In4.Cu")
		(net "P5E_CPU1_P3_RX_DN<7>")
	)
	(segment
		(start 120.250966 -293.84879)
		(end 120.289828 -293.823136)
		(width 0.1143)
		(layer "In4.Cu")
		(net "P5E_CPU1_P3_RX_DN<7>")
	)
	(segment
		(start 123.764802 -373.235982)
		(end 123.62053 -373.09171)
		(width 0.14224)
		(layer "In4.Cu")
		(net "P5E_CPU1_P3_RX_DN<7>")
	)
	(segment
		(start 121.03735 -300.804834)
		(end 119.982488 -298.256706)
		(width 0.14224)
		(layer "In4.Cu")
		(net "P5E_CPU1_P3_RX_DN<7>")
	)
	(segment
		(start 124.016262 -378.593604)
		(end 124.07265 -377.785122)
		(width 0.14224)
		(layer "In4.Cu")
		(net "P5E_CPU1_P3_RX_DN<7>")
	)
	(segment
		(start 120.24995 -293.849298)
		(end 120.250966 -293.84879)
		(width 0.1143)
		(layer "In4.Cu")
		(net "P5E_CPU1_P3_RX_DN<7>")
	)
	(segment
		(start 123.758452 -383.930906)
		(end 123.758452 -382.27254)
		(width 0.14224)
		(layer "In4.Cu")
		(net "P5E_CPU1_P3_RX_DN<7>")
	)
	(segment
		(start 123.96724 -379.293374)
		(end 123.839986 -379.146816)
		(width 0.14224)
		(layer "In4.Cu")
		(net "P5E_CPU1_P3_RX_DN<7>")
	)
	(segment
		(start 123.869704 -378.720858)
		(end 124.016262 -378.593604)
		(width 0.14224)
		(layer "In4.Cu")
		(net "P5E_CPU1_P3_RX_DN<7>")
	)
	(arc
		(start 122.805952 -372.609872)
		(mid 122.352753 -371.774719)
		(end 122.428254 -370.827554)
		(width 0.14224)
		(layer "In4.Cu")
		(net "P5E_CPU1_P3_RX_DN<7>")
	)
	(arc
		(start 119.982488 -298.256706)
		(mid 119.938558 -298.111514)
		(end 119.923814 -297.960542)
		(width 0.14224)
		(layer "In4.Cu")
		(net "P5E_CPU1_P3_RX_DN<7>")
	)
	(arc
		(start 123.111006 -372.814342)
		(mid 122.949114 -372.727694)
		(end 122.807222 -372.611142)
		(width 0.14224)
		(layer "In4.Cu")
		(net "P5E_CPU1_P3_RX_DN<7>")
	)
	(arc
		(start 119.97944 -291.201602)
		(mid 119.977421 -291.190318)
		(end 119.97563 -291.178996)
		(width 0.1143)
		(layer "In4.Cu")
		(net "P5E_CPU1_P3_RX_DN<7>")
	)
	(arc
		(start 127.68834 -364.552738)
		(mid 128.532417 -363.729273)
		(end 129.470912 -363.015276)
		(width 0.14224)
		(layer "In4.Cu")
		(net "P5E_CPU1_P3_RX_DN<7>")
	)
	(arc
		(start 120.290844 -295.443148)
		(mid 120.437849 -295.130721)
		(end 120.265444 -294.831516)
		(width 0.1143)
		(layer "In4.Cu")
		(net "P5E_CPU1_P3_RX_DN<7>")
	)
	(arc
		(start 120.290844 -293.823136)
		(mid 120.437849 -293.510709)
		(end 120.265444 -293.211504)
		(width 0.1143)
		(layer "In4.Cu")
		(net "P5E_CPU1_P3_RX_DN<7>")
	)
	(arc
		(start 120.213374 -291.561266)
		(mid 120.0609 -291.404515)
		(end 119.97944 -291.201602)
		(width 0.1143)
		(layer "In4.Cu")
		(net "P5E_CPU1_P3_RX_DN<7>")
	)
	(arc
		(start 120.213374 -293.181278)
		(mid 119.96952 -292.716204)
		(end 120.213374 -292.25113)
		(width 0.1143)
		(layer "In4.Cu")
		(net "P5E_CPU1_P3_RX_DN<7>")
	)
	(arc
		(start 120.213374 -294.80129)
		(mid 119.969202 -294.336315)
		(end 120.212866 -293.871142)
		(width 0.1143)
		(layer "In4.Cu")
		(net "P5E_CPU1_P3_RX_DN<7>")
	)
	(arc
		(start 137.40511 -357.713788)
		(mid 138.356904 -356.663657)
		(end 138.701272 -355.28885)
		(width 0.14224)
		(layer "In4.Cu")
		(net "P5E_CPU1_P3_RX_DN<7>")
	)
	(arc
		(start 124.011944 -373.810784)
		(mid 123.943587 -373.499641)
		(end 123.764802 -373.235982)
		(width 0.14224)
		(layer "In4.Cu")
		(net "P5E_CPU1_P3_RX_DN<7>")
	)
	(arc
		(start 120.252236 -292.228778)
		(mid 120.437874 -291.906198)
		(end 120.252236 -291.583618)
		(width 0.1143)
		(layer "In4.Cu")
		(net "P5E_CPU1_P3_RX_DN<7>")
	)
	(arc
		(start 119.969534 -295.847262)
		(mid 120.057286 -295.643922)
		(end 120.215914 -295.489376)
		(width 0.1143)
		(layer "In4.Cu")
		(net "P5E_CPU1_P3_RX_DN<7>")
	)
	(arc
		(start 122.432572 -370.816886)
		(mid 122.827293 -370.058701)
		(end 123.326398 -369.364768)
		(width 0.14224)
		(layer "In4.Cu")
		(net "P5E_CPU1_P3_RX_DN<7>")
	)
	(arc
		(start 124.07265 -377.785122)
		(mid 124.093438 -377.332605)
		(end 124.092462 -376.879612)
		(width 0.14224)
		(layer "In4.Cu")
		(net "P5E_CPU1_P3_RX_DN<7>")
	)
	(arc
		(start 123.62053 -373.09171)
		(mid 123.49832 -372.991462)
		(end 123.35891 -372.916958)
		(width 0.14224)
		(layer "In4.Cu")
		(net "P5E_CPU1_P3_RX_DN<7>")
	)
	(segment
		(start 119.127778 -287.590484)
		(end 119.59463 -287.856422)
		(width 0.12954)
		(layer "F.Cu")
		(net "P5E_CPU1_P3_RX_DN<6>")
	)
	(segment
		(start 121.570496 -385.31038)
		(end 122.091196 -385.31038)
		(width 0.127)
		(layer "F.Cu")
		(net "P5E_CPU1_P3_RX_DN<6>")
	)
	(segment
		(start 119.343424 -291.601906)
		(end 119.318786 -291.587682)
		(width 0.1143)
		(layer "In4.Cu")
		(net "P5E_CPU1_P3_RX_DN<6>")
	)
	(segment
		(start 119.31777 -293.845234)
		(end 119.318786 -293.844726)
		(width 0.1143)
		(layer "In4.Cu")
		(net "P5E_CPU1_P3_RX_DN<6>")
	)
	(segment
		(start 119.04218 -291.163502)
		(end 119.04218 -291.10559)
		(width 0.1143)
		(layer "In4.Cu")
		(net "P5E_CPU1_P3_RX_DN<6>")
	)
	(segment
		(start 122.091196 -385.31038)
		(end 122.44451 -385.405376)
		(width 0.14224)
		(layer "In4.Cu")
		(net "P5E_CPU1_P3_RX_DN<6>")
	)
	(segment
		(start 119.315992 -292.226238)
		(end 119.317008 -292.22573)
		(width 0.1143)
		(layer "In4.Cu")
		(net "P5E_CPU1_P3_RX_DN<6>")
	)
	(segment
		(start 119.318786 -292.224714)
		(end 119.343424 -292.21049)
		(width 0.1143)
		(layer "In4.Cu")
		(net "P5E_CPU1_P3_RX_DN<6>")
	)
	(segment
		(start 119.311674 -292.228778)
		(end 119.312436 -292.22827)
		(width 0.1143)
		(layer "In4.Cu")
		(net "P5E_CPU1_P3_RX_DN<6>")
	)
	(segment
		(start 118.983506 -296.428668)
		(end 119.029226 -296.382948)
		(width 0.1143)
		(layer "In4.Cu")
		(net "P5E_CPU1_P3_RX_DN<6>")
	)
	(segment
		(start 119.312436 -294.82415)
		(end 119.311674 -294.823642)
		(width 0.1143)
		(layer "In4.Cu")
		(net "P5E_CPU1_P3_RX_DN<6>")
	)
	(segment
		(start 118.983506 -296.457116)
		(end 118.983506 -296.428668)
		(width 0.1143)
		(layer "In4.Cu")
		(net "P5E_CPU1_P3_RX_DN<6>")
	)
	(segment
		(start 119.317008 -293.845742)
		(end 119.31777 -293.845234)
		(width 0.1143)
		(layer "In4.Cu")
		(net "P5E_CPU1_P3_RX_DN<6>")
	)
	(segment
		(start 119.312436 -292.22827)
		(end 119.313706 -292.227508)
		(width 0.1143)
		(layer "In4.Cu")
		(net "P5E_CPU1_P3_RX_DN<6>")
	)
	(segment
		(start 128.849628 -362.300012)
		(end 136.535668 -357.164132)
		(width 0.14224)
		(layer "In4.Cu")
		(net "P5E_CPU1_P3_RX_DN<6>")
	)
	(segment
		(start 122.053858 -379.906784)
		(end 121.9708 -379.488446)
		(width 0.14224)
		(layer "In4.Cu")
		(net "P5E_CPU1_P3_RX_DN<6>")
	)
	(segment
		(start 121.833894 -378.800614)
		(end 121.276872 -375.999502)
		(width 0.14224)
		(layer "In4.Cu")
		(net "P5E_CPU1_P3_RX_DN<6>")
	)
	(segment
		(start 119.312436 -288.988246)
		(end 119.313706 -288.987484)
		(width 0.1143)
		(layer "In4.Cu")
		(net "P5E_CPU1_P3_RX_DN<6>")
	)
	(segment
		(start 119.311674 -293.20363)
		(end 119.310658 -293.203122)
		(width 0.1143)
		(layer "In4.Cu")
		(net "P5E_CPU1_P3_RX_DN<6>")
	)
	(segment
		(start 122.249692 -384.84683)
		(end 122.254772 -384.18262)
		(width 0.14224)
		(layer "In4.Cu")
		(net "P5E_CPU1_P3_RX_DN<6>")
	)
	(segment
		(start 121.311416 -302.90135)
		(end 120.1928 -301.22368)
		(width 0.14224)
		(layer "In4.Cu")
		(net "P5E_CPU1_P3_RX_DN<6>")
	)
	(segment
		(start 119.313706 -293.2049)
		(end 119.312436 -293.204138)
		(width 0.1143)
		(layer "In4.Cu")
		(net "P5E_CPU1_P3_RX_DN<6>")
	)
	(segment
		(start 122.54611 -382.380998)
		(end 122.410728 -381.700786)
		(width 0.14224)
		(layer "In4.Cu")
		(net "P5E_CPU1_P3_RX_DN<6>")
	)
	(segment
		(start 122.44451 -385.405376)
		(end 122.445018 -385.404868)
		(width 0.14224)
		(layer "In4.Cu")
		(net "P5E_CPU1_P3_RX_DN<6>")
	)
	(segment
		(start 119.315992 -288.986214)
		(end 119.317008 -288.985706)
		(width 0.1143)
		(layer "In4.Cu")
		(net "P5E_CPU1_P3_RX_DN<6>")
	)
	(segment
		(start 119.317008 -292.22573)
		(end 119.31777 -292.225222)
		(width 0.1143)
		(layer "In4.Cu")
		(net "P5E_CPU1_P3_RX_DN<6>")
	)
	(segment
		(start 121.809256 -379.380496)
		(end 121.725944 -378.961904)
		(width 0.14224)
		(layer "In4.Cu")
		(net "P5E_CPU1_P3_RX_DN<6>")
	)
	(segment
		(start 122.02922 -380.486666)
		(end 121.945908 -380.068074)
		(width 0.14224)
		(layer "In4.Cu")
		(net "P5E_CPU1_P3_RX_DN<6>")
	)
	(segment
		(start 122.410728 -381.700786)
		(end 122.410982 -381.700786)
		(width 0.14224)
		(layer "In4.Cu")
		(net "P5E_CPU1_P3_RX_DN<6>")
	)
	(segment
		(start 119.310658 -288.989262)
		(end 119.311674 -288.988754)
		(width 0.1143)
		(layer "In4.Cu")
		(net "P5E_CPU1_P3_RX_DN<6>")
	)
	(segment
		(start 119.312436 -293.848282)
		(end 119.313706 -293.84752)
		(width 0.1143)
		(layer "In4.Cu")
		(net "P5E_CPU1_P3_RX_DN<6>")
	)
	(segment
		(start 119.31523 -293.846758)
		(end 119.315992 -293.84625)
		(width 0.1143)
		(layer "In4.Cu")
		(net "P5E_CPU1_P3_RX_DN<6>")
	)
	(segment
		(start 119.304562 -291.5793)
		(end 119.27078 -291.559742)
		(width 0.1143)
		(layer "In4.Cu")
		(net "P5E_CPU1_P3_RX_DN<6>")
	)
	(segment
		(start 122.254772 -384.18262)
		(end 122.558556 -383.87909)
		(width 0.14224)
		(layer "In4.Cu")
		(net "P5E_CPU1_P3_RX_DN<6>")
	)
	(segment
		(start 119.781828 -288.178748)
		(end 119.81434 -288.159952)
		(width 0.1143)
		(layer "In4.Cu")
		(net "P5E_CPU1_P3_RX_DN<6>")
	)
	(segment
		(start 119.962422 -287.926272)
		(end 119.892572 -287.856422)
		(width 0.1143)
		(layer "In4.Cu")
		(net "P5E_CPU1_P3_RX_DN<6>")
	)
	(segment
		(start 119.300498 -288.995358)
		(end 119.30126 -288.99485)
		(width 0.1143)
		(layer "In4.Cu")
		(net "P5E_CPU1_P3_RX_DN<6>")
	)
	(segment
		(start 119.317008 -288.985706)
		(end 119.31777 -288.985198)
		(width 0.1143)
		(layer "In4.Cu")
		(net "P5E_CPU1_P3_RX_DN<6>")
	)
	(segment
		(start 118.856506 -290.782248)
		(end 118.802658 -290.750752)
		(width 0.1143)
		(layer "In4.Cu")
		(net "P5E_CPU1_P3_RX_DN<6>")
	)
	(segment
		(start 119.318786 -293.844726)
		(end 119.343424 -293.830502)
		(width 0.1143)
		(layer "In4.Cu")
		(net "P5E_CPU1_P3_RX_DN<6>")
	)
	(segment
		(start 119.310658 -292.229286)
		(end 119.311674 -292.228778)
		(width 0.1143)
		(layer "In4.Cu")
		(net "P5E_CPU1_P3_RX_DN<6>")
	)
	(segment
		(start 121.945908 -380.068074)
		(end 122.053858 -379.906784)
		(width 0.14224)
		(layer "In4.Cu")
		(net "P5E_CPU1_P3_RX_DN<6>")
	)
	(segment
		(start 119.272558 -293.87165)
		(end 119.300498 -293.855394)
		(width 0.1143)
		(layer "In4.Cu")
		(net "P5E_CPU1_P3_RX_DN<6>")
	)
	(segment
		(start 137.769092 -337.202526)
		(end 136.471914 -329.981814)
		(width 0.14224)
		(layer "In4.Cu")
		(net "P5E_CPU1_P3_RX_DN<6>")
	)
	(segment
		(start 122.566684 -385.334764)
		(end 122.566684 -385.163822)
		(width 0.14224)
		(layer "In4.Cu")
		(net "P5E_CPU1_P3_RX_DN<6>")
	)
	(segment
		(start 119.305578 -291.580062)
		(end 119.304562 -291.5793)
		(width 0.1143)
		(layer "In4.Cu")
		(net "P5E_CPU1_P3_RX_DN<6>")
	)
	(segment
		(start 119.30126 -293.854886)
		(end 119.308118 -293.850822)
		(width 0.1143)
		(layer "In4.Cu")
		(net "P5E_CPU1_P3_RX_DN<6>")
	)
	(segment
		(start 119.308118 -292.23081)
		(end 119.309134 -292.230302)
		(width 0.1143)
		(layer "In4.Cu")
		(net "P5E_CPU1_P3_RX_DN<6>")
	)
	(segment
		(start 122.273822 -381.012954)
		(end 122.190764 -380.594616)
		(width 0.14224)
		(layer "In4.Cu")
		(net "P5E_CPU1_P3_RX_DN<6>")
	)
	(segment
		(start 119.312436 -293.204138)
		(end 119.311674 -293.20363)
		(width 0.1143)
		(layer "In4.Cu")
		(net "P5E_CPU1_P3_RX_DN<6>")
	)
	(segment
		(start 118.983506 -298.205906)
		(end 118.983506 -296.457116)
		(width 0.14224)
		(layer "In4.Cu")
		(net "P5E_CPU1_P3_RX_DN<6>")
	)
	(segment
		(start 118.841774 -289.79876)
		(end 118.872254 -289.78098)
		(width 0.1143)
		(layer "In4.Cu")
		(net "P5E_CPU1_P3_RX_DN<6>")
	)
	(segment
		(start 119.272558 -289.011614)
		(end 119.300498 -288.995358)
		(width 0.1143)
		(layer "In4.Cu")
		(net "P5E_CPU1_P3_RX_DN<6>")
	)
	(segment
		(start 119.30126 -292.234874)
		(end 119.308118 -292.23081)
		(width 0.1143)
		(layer "In4.Cu")
		(net "P5E_CPU1_P3_RX_DN<6>")
	)
	(segment
		(start 119.309134 -292.230302)
		(end 119.310658 -292.229286)
		(width 0.1143)
		(layer "In4.Cu")
		(net "P5E_CPU1_P3_RX_DN<6>")
	)
	(segment
		(start 132.116068 -317.442088)
		(end 130.022346 -313.525662)
		(width 0.14224)
		(layer "In4.Cu")
		(net "P5E_CPU1_P3_RX_DN<6>")
	)
	(segment
		(start 119.311674 -288.988754)
		(end 119.312436 -288.988246)
		(width 0.1143)
		(layer "In4.Cu")
		(net "P5E_CPU1_P3_RX_DN<6>")
	)
	(segment
		(start 119.313706 -293.84752)
		(end 119.31523 -293.846758)
		(width 0.1143)
		(layer "In4.Cu")
		(net "P5E_CPU1_P3_RX_DN<6>")
	)
	(segment
		(start 119.31523 -288.986722)
		(end 119.315992 -288.986214)
		(width 0.1143)
		(layer "In4.Cu")
		(net "P5E_CPU1_P3_RX_DN<6>")
	)
	(segment
		(start 122.249438 -381.59309)
		(end 122.166126 -381.174244)
		(width 0.14224)
		(layer "In4.Cu")
		(net "P5E_CPU1_P3_RX_DN<6>")
	)
	(segment
		(start 122.647202 -368.673634)
		(end 126.899416 -363.982)
		(width 0.14224)
		(layer "In4.Cu")
		(net "P5E_CPU1_P3_RX_DN<6>")
	)
	(segment
		(start 136.471914 -329.981814)
		(end 132.116068 -317.442088)
		(width 0.14224)
		(layer "In4.Cu")
		(net "P5E_CPU1_P3_RX_DN<6>")
	)
	(segment
		(start 119.31777 -291.587174)
		(end 119.316246 -291.586158)
		(width 0.1143)
		(layer "In4.Cu")
		(net "P5E_CPU1_P3_RX_DN<6>")
	)
	(segment
		(start 122.190764 -380.594616)
		(end 122.02922 -380.486666)
		(width 0.14224)
		(layer "In4.Cu")
		(net "P5E_CPU1_P3_RX_DN<6>")
	)
	(segment
		(start 120.1928 -301.22368)
		(end 119.01424 -298.361608)
		(width 0.14224)
		(layer "In4.Cu")
		(net "P5E_CPU1_P3_RX_DN<6>")
	)
	(segment
		(start 118.802658 -289.82162)
		(end 118.841774 -289.79876)
		(width 0.1143)
		(layer "In4.Cu")
		(net "P5E_CPU1_P3_RX_DN<6>")
	)
	(segment
		(start 119.31777 -288.985198)
		(end 119.318786 -288.98469)
		(width 0.1143)
		(layer "In4.Cu")
		(net "P5E_CPU1_P3_RX_DN<6>")
	)
	(segment
		(start 119.313706 -288.987484)
		(end 119.31523 -288.986722)
		(width 0.1143)
		(layer "In4.Cu")
		(net "P5E_CPU1_P3_RX_DN<6>")
	)
	(segment
		(start 119.343424 -293.221918)
		(end 119.313706 -293.2049)
		(width 0.1143)
		(layer "In4.Cu")
		(net "P5E_CPU1_P3_RX_DN<6>")
	)
	(segment
		(start 119.029226 -296.382948)
		(end 119.029226 -295.956228)
		(width 0.1143)
		(layer "In4.Cu")
		(net "P5E_CPU1_P3_RX_DN<6>")
	)
	(segment
		(start 130.022346 -313.525662)
		(end 121.311416 -302.90135)
		(width 0.14224)
		(layer "In4.Cu")
		(net "P5E_CPU1_P3_RX_DN<6>")
	)
	(segment
		(start 119.309134 -288.990278)
		(end 119.310658 -288.989262)
		(width 0.1143)
		(layer "In4.Cu")
		(net "P5E_CPU1_P3_RX_DN<6>")
	)
	(segment
		(start 119.313706 -292.227508)
		(end 119.31523 -292.226746)
		(width 0.1143)
		(layer "In4.Cu")
		(net "P5E_CPU1_P3_RX_DN<6>")
	)
	(segment
		(start 119.313706 -294.824912)
		(end 119.312436 -294.82415)
		(width 0.1143)
		(layer "In4.Cu")
		(net "P5E_CPU1_P3_RX_DN<6>")
	)
	(segment
		(start 120.535954 -373.040148)
		(end 121.505726 -370.526056)
		(width 0.14224)
		(layer "In4.Cu")
		(net "P5E_CPU1_P3_RX_DN<6>")
	)
	(segment
		(start 122.558556 -383.87909)
		(end 122.558556 -382.506982)
		(width 0.14224)
		(layer "In4.Cu")
		(net "P5E_CPU1_P3_RX_DN<6>")
	)
	(segment
		(start 119.311674 -293.84879)
		(end 119.312436 -293.848282)
		(width 0.1143)
		(layer "In4.Cu")
		(net "P5E_CPU1_P3_RX_DN<6>")
	)
	(segment
		(start 119.31777 -292.225222)
		(end 119.318786 -292.224714)
		(width 0.1143)
		(layer "In4.Cu")
		(net "P5E_CPU1_P3_RX_DN<6>")
	)
	(segment
		(start 122.410982 -381.700786)
		(end 122.249438 -381.59309)
		(width 0.14224)
		(layer "In4.Cu")
		(net "P5E_CPU1_P3_RX_DN<6>")
	)
	(segment
		(start 122.166126 -381.174244)
		(end 122.273822 -381.012954)
		(width 0.14224)
		(layer "In4.Cu")
		(net "P5E_CPU1_P3_RX_DN<6>")
	)
	(segment
		(start 119.308118 -293.850822)
		(end 119.309134 -293.850314)
		(width 0.1143)
		(layer "In4.Cu")
		(net "P5E_CPU1_P3_RX_DN<6>")
	)
	(segment
		(start 119.308118 -291.581586)
		(end 119.305578 -291.580062)
		(width 0.1143)
		(layer "In4.Cu")
		(net "P5E_CPU1_P3_RX_DN<6>")
	)
	(segment
		(start 119.310658 -291.58311)
		(end 119.309134 -291.582094)
		(width 0.1143)
		(layer "In4.Cu")
		(net "P5E_CPU1_P3_RX_DN<6>")
	)
	(segment
		(start 119.318786 -291.587682)
		(end 119.31777 -291.587174)
		(width 0.1143)
		(layer "In4.Cu")
		(net "P5E_CPU1_P3_RX_DN<6>")
	)
	(segment
		(start 119.308118 -288.990786)
		(end 119.309134 -288.990278)
		(width 0.1143)
		(layer "In4.Cu")
		(net "P5E_CPU1_P3_RX_DN<6>")
	)
	(segment
		(start 137.769092 -354.856542)
		(end 137.769092 -337.202526)
		(width 0.14224)
		(layer "In4.Cu")
		(net "P5E_CPU1_P3_RX_DN<6>")
	)
	(segment
		(start 119.310658 -293.849298)
		(end 119.311674 -293.84879)
		(width 0.1143)
		(layer "In4.Cu")
		(net "P5E_CPU1_P3_RX_DN<6>")
	)
	(segment
		(start 121.725944 -378.961904)
		(end 121.833894 -378.800614)
		(width 0.14224)
		(layer "In4.Cu")
		(net "P5E_CPU1_P3_RX_DN<6>")
	)
	(segment
		(start 119.300498 -292.235382)
		(end 119.30126 -292.234874)
		(width 0.1143)
		(layer "In4.Cu")
		(net "P5E_CPU1_P3_RX_DN<6>")
	)
	(segment
		(start 119.310658 -294.823134)
		(end 119.272558 -294.800782)
		(width 0.1143)
		(layer "In4.Cu")
		(net "P5E_CPU1_P3_RX_DN<6>")
	)
	(segment
		(start 119.311674 -294.823642)
		(end 119.310658 -294.823134)
		(width 0.1143)
		(layer "In4.Cu")
		(net "P5E_CPU1_P3_RX_DN<6>")
	)
	(segment
		(start 119.892572 -287.856422)
		(end 119.59463 -287.856422)
		(width 0.1143)
		(layer "In4.Cu")
		(net "P5E_CPU1_P3_RX_DN<6>")
	)
	(segment
		(start 119.312436 -291.584126)
		(end 119.311674 -291.583618)
		(width 0.1143)
		(layer "In4.Cu")
		(net "P5E_CPU1_P3_RX_DN<6>")
	)
	(segment
		(start 119.343424 -294.84193)
		(end 119.313706 -294.824912)
		(width 0.1143)
		(layer "In4.Cu")
		(net "P5E_CPU1_P3_RX_DN<6>")
	)
	(segment
		(start 121.9708 -379.488446)
		(end 121.809256 -379.380496)
		(width 0.14224)
		(layer "In4.Cu")
		(net "P5E_CPU1_P3_RX_DN<6>")
	)
	(segment
		(start 119.499634 -295.146476)
		(end 119.499634 -295.146222)
		(width 0.1143)
		(layer "In4.Cu")
		(net "P5E_CPU1_P3_RX_DN<6>")
	)
	(segment
		(start 119.309134 -291.582094)
		(end 119.308118 -291.581586)
		(width 0.1143)
		(layer "In4.Cu")
		(net "P5E_CPU1_P3_RX_DN<6>")
	)
	(segment
		(start 119.273828 -295.490646)
		(end 119.34444 -295.449498)
		(width 0.1143)
		(layer "In4.Cu")
		(net "P5E_CPU1_P3_RX_DN<6>")
	)
	(segment
		(start 122.566684 -385.163822)
		(end 122.249692 -384.84683)
		(width 0.14224)
		(layer "In4.Cu")
		(net "P5E_CPU1_P3_RX_DN<6>")
	)
	(segment
		(start 119.318786 -288.98469)
		(end 119.343424 -288.970466)
		(width 0.1143)
		(layer "In4.Cu")
		(net "P5E_CPU1_P3_RX_DN<6>")
	)
	(segment
		(start 119.316246 -291.586158)
		(end 119.313706 -291.584888)
		(width 0.1143)
		(layer "In4.Cu")
		(net "P5E_CPU1_P3_RX_DN<6>")
	)
	(segment
		(start 119.310658 -293.203122)
		(end 119.272558 -293.18077)
		(width 0.1143)
		(layer "In4.Cu")
		(net "P5E_CPU1_P3_RX_DN<6>")
	)
	(segment
		(start 122.445018 -385.404868)
		(end 122.566684 -385.334764)
		(width 0.14224)
		(layer "In4.Cu")
		(net "P5E_CPU1_P3_RX_DN<6>")
	)
	(segment
		(start 119.30126 -288.99485)
		(end 119.308118 -288.990786)
		(width 0.1143)
		(layer "In4.Cu")
		(net "P5E_CPU1_P3_RX_DN<6>")
	)
	(segment
		(start 119.309134 -293.850314)
		(end 119.310658 -293.849298)
		(width 0.1143)
		(layer "In4.Cu")
		(net "P5E_CPU1_P3_RX_DN<6>")
	)
	(segment
		(start 119.311674 -291.583618)
		(end 119.310658 -291.58311)
		(width 0.1143)
		(layer "In4.Cu")
		(net "P5E_CPU1_P3_RX_DN<6>")
	)
	(segment
		(start 119.315992 -293.84625)
		(end 119.317008 -293.845742)
		(width 0.1143)
		(layer "In4.Cu")
		(net "P5E_CPU1_P3_RX_DN<6>")
	)
	(segment
		(start 119.313706 -291.584888)
		(end 119.312436 -291.584126)
		(width 0.1143)
		(layer "In4.Cu")
		(net "P5E_CPU1_P3_RX_DN<6>")
	)
	(segment
		(start 119.742712 -288.201608)
		(end 119.781828 -288.178748)
		(width 0.1143)
		(layer "In4.Cu")
		(net "P5E_CPU1_P3_RX_DN<6>")
	)
	(segment
		(start 119.31523 -292.226746)
		(end 119.315992 -292.226238)
		(width 0.1143)
		(layer "In4.Cu")
		(net "P5E_CPU1_P3_RX_DN<6>")
	)
	(segment
		(start 119.272558 -292.251638)
		(end 119.300498 -292.235382)
		(width 0.1143)
		(layer "In4.Cu")
		(net "P5E_CPU1_P3_RX_DN<6>")
	)
	(segment
		(start 119.300498 -293.855394)
		(end 119.30126 -293.854886)
		(width 0.1143)
		(layer "In4.Cu")
		(net "P5E_CPU1_P3_RX_DN<6>")
	)
	(arc
		(start 119.257826 -295.502076)
		(mid 119.2654 -295.496551)
		(end 119.273066 -295.491154)
		(width 0.1143)
		(layer "In4.Cu")
		(net "P5E_CPU1_P3_RX_DN<6>")
	)
	(arc
		(start 119.343424 -293.830502)
		(mid 119.499352 -293.52621)
		(end 119.343424 -293.221918)
		(width 0.1143)
		(layer "In4.Cu")
		(net "P5E_CPU1_P3_RX_DN<6>")
	)
	(arc
		(start 120.711976 -374.635268)
		(mid 120.429513 -373.859153)
		(end 120.535954 -373.040148)
		(width 0.14224)
		(layer "In4.Cu")
		(net "P5E_CPU1_P3_RX_DN<6>")
	)
	(arc
		(start 119.029226 -295.948354)
		(mid 119.094572 -295.700131)
		(end 119.257826 -295.502076)
		(width 0.1143)
		(layer "In4.Cu")
		(net "P5E_CPU1_P3_RX_DN<6>")
	)
	(arc
		(start 121.276872 -375.999502)
		(mid 121.059828 -375.290306)
		(end 120.711976 -374.635268)
		(width 0.14224)
		(layer "In4.Cu")
		(net "P5E_CPU1_P3_RX_DN<6>")
	)
	(arc
		(start 119.343424 -288.970466)
		(mid 119.4581 -288.837132)
		(end 119.49938 -288.666174)
		(width 0.1143)
		(layer "In4.Cu")
		(net "P5E_CPU1_P3_RX_DN<6>")
	)
	(arc
		(start 121.505726 -370.526056)
		(mid 121.990977 -369.547167)
		(end 122.647202 -368.673634)
		(width 0.14224)
		(layer "In4.Cu")
		(net "P5E_CPU1_P3_RX_DN<6>")
	)
	(arc
		(start 118.872254 -289.78098)
		(mid 118.987681 -289.647604)
		(end 119.029226 -289.47618)
		(width 0.1143)
		(layer "In4.Cu")
		(net "P5E_CPU1_P3_RX_DN<6>")
	)
	(arc
		(start 119.49938 -288.666174)
		(mid 119.563895 -288.403955)
		(end 119.742712 -288.201608)
		(width 0.1143)
		(layer "In4.Cu")
		(net "P5E_CPU1_P3_RX_DN<6>")
	)
	(arc
		(start 119.343424 -292.21049)
		(mid 119.499352 -291.906198)
		(end 119.343424 -291.601906)
		(width 0.1143)
		(layer "In4.Cu")
		(net "P5E_CPU1_P3_RX_DN<6>")
	)
	(arc
		(start 119.81434 -288.159952)
		(mid 119.91078 -288.057297)
		(end 119.962422 -287.926272)
		(width 0.1143)
		(layer "In4.Cu")
		(net "P5E_CPU1_P3_RX_DN<6>")
	)
	(arc
		(start 122.558556 -382.506982)
		(mid 122.555441 -382.443683)
		(end 122.54611 -382.380998)
		(width 0.14224)
		(layer "In4.Cu")
		(net "P5E_CPU1_P3_RX_DN<6>")
	)
	(arc
		(start 119.272558 -293.18077)
		(mid 119.029231 -292.716204)
		(end 119.272558 -292.251638)
		(width 0.1143)
		(layer "In4.Cu")
		(net "P5E_CPU1_P3_RX_DN<6>")
	)
	(arc
		(start 119.34444 -295.449498)
		(mid 119.458535 -295.316677)
		(end 119.499634 -295.146476)
		(width 0.1143)
		(layer "In4.Cu")
		(net "P5E_CPU1_P3_RX_DN<6>")
	)
	(arc
		(start 119.04218 -291.10559)
		(mid 118.992461 -290.919158)
		(end 118.856506 -290.782248)
		(width 0.1143)
		(layer "In4.Cu")
		(net "P5E_CPU1_P3_RX_DN<6>")
	)
	(arc
		(start 126.899416 -363.982)
		(mid 127.822868 -363.081116)
		(end 128.849628 -362.300012)
		(width 0.14224)
		(layer "In4.Cu")
		(net "P5E_CPU1_P3_RX_DN<6>")
	)
	(arc
		(start 119.029226 -295.956228)
		(mid 119.029213 -295.952291)
		(end 119.029226 -295.948354)
		(width 0.1143)
		(layer "In4.Cu")
		(net "P5E_CPU1_P3_RX_DN<6>")
	)
	(arc
		(start 118.802658 -290.750752)
		(mid 118.559331 -290.286186)
		(end 118.802658 -289.82162)
		(width 0.1143)
		(layer "In4.Cu")
		(net "P5E_CPU1_P3_RX_DN<6>")
	)
	(arc
		(start 119.27078 -291.559742)
		(mid 119.103428 -291.392229)
		(end 119.04218 -291.163502)
		(width 0.1143)
		(layer "In4.Cu")
		(net "P5E_CPU1_P3_RX_DN<6>")
	)
	(arc
		(start 119.499634 -295.146222)
		(mid 119.458294 -294.975207)
		(end 119.343424 -294.84193)
		(width 0.1143)
		(layer "In4.Cu")
		(net "P5E_CPU1_P3_RX_DN<6>")
	)
	(arc
		(start 119.273066 -295.491154)
		(mid 119.273447 -295.4909)
		(end 119.273828 -295.490646)
		(width 0.1143)
		(layer "In4.Cu")
		(net "P5E_CPU1_P3_RX_DN<6>")
	)
	(arc
		(start 119.029226 -289.47618)
		(mid 119.093741 -289.213961)
		(end 119.272558 -289.011614)
		(width 0.1143)
		(layer "In4.Cu")
		(net "P5E_CPU1_P3_RX_DN<6>")
	)
	(arc
		(start 119.272558 -294.800782)
		(mid 119.029231 -294.336216)
		(end 119.272558 -293.87165)
		(width 0.1143)
		(layer "In4.Cu")
		(net "P5E_CPU1_P3_RX_DN<6>")
	)
	(arc
		(start 136.535668 -357.164132)
		(mid 137.441427 -356.164827)
		(end 137.769092 -354.856542)
		(width 0.14224)
		(layer "In4.Cu")
		(net "P5E_CPU1_P3_RX_DN<6>")
	)
	(arc
		(start 119.01424 -298.361608)
		(mid 118.991245 -298.285261)
		(end 118.983506 -298.205906)
		(width 0.14224)
		(layer "In4.Cu")
		(net "P5E_CPU1_P3_RX_DN<6>")
	)
	(segment
		(start 120.3706 -385.31038)
		(end 120.8913 -385.31038)
		(width 0.127)
		(layer "F.Cu")
		(net "P5E_CPU1_P3_RX_DN<5>")
	)
	(segment
		(start 116.30787 -289.210242)
		(end 116.774722 -289.47618)
		(width 0.12954)
		(layer "F.Cu")
		(net "P5E_CPU1_P3_RX_DN<5>")
	)
	(segment
		(start 118.04396 -296.330116)
		(end 118.08968 -296.284396)
		(width 0.1143)
		(layer "In4.Cu")
		(net "P5E_CPU1_P3_RX_DN<5>")
	)
	(segment
		(start 120.629934 -378.732034)
		(end 120.09882 -376.061224)
		(width 0.14224)
		(layer "In4.Cu")
		(net "P5E_CPU1_P3_RX_DN<5>")
	)
	(segment
		(start 120.849898 -379.838204)
		(end 120.76684 -379.419866)
		(width 0.14224)
		(layer "In4.Cu")
		(net "P5E_CPU1_P3_RX_DN<5>")
	)
	(segment
		(start 120.587516 -303.501806)
		(end 119.374158 -301.684182)
		(width 0.14224)
		(layer "In4.Cu")
		(net "P5E_CPU1_P3_RX_DN<5>")
	)
	(segment
		(start 121.346214 -382.331214)
		(end 121.207276 -381.632206)
		(width 0.14224)
		(layer "In4.Cu")
		(net "P5E_CPU1_P3_RX_DN<5>")
	)
	(segment
		(start 117.908832 -290.777676)
		(end 117.907816 -290.777168)
		(width 0.1143)
		(layer "In4.Cu")
		(net "P5E_CPU1_P3_RX_DN<5>")
	)
	(segment
		(start 118.332758 -293.87165)
		(end 118.371874 -293.84879)
		(width 0.1143)
		(layer "In4.Cu")
		(net "P5E_CPU1_P3_RX_DN<5>")
	)
	(segment
		(start 118.402354 -293.22141)
		(end 118.371874 -293.20363)
		(width 0.1143)
		(layer "In4.Cu")
		(net "P5E_CPU1_P3_RX_DN<5>")
	)
	(segment
		(start 117.907816 -290.777168)
		(end 117.906292 -290.776152)
		(width 0.1143)
		(layer "In4.Cu")
		(net "P5E_CPU1_P3_RX_DN<5>")
	)
	(segment
		(start 118.332758 -295.491662)
		(end 118.402354 -295.451022)
		(width 0.1143)
		(layer "In4.Cu")
		(net "P5E_CPU1_P3_RX_DN<5>")
	)
	(segment
		(start 121.985786 -367.969546)
		(end 126.195836 -363.323886)
		(width 0.14224)
		(layer "In4.Cu")
		(net "P5E_CPU1_P3_RX_DN<5>")
	)
	(segment
		(start 118.04396 -298.224702)
		(end 118.04396 -296.358564)
		(width 0.14224)
		(layer "In4.Cu")
		(net "P5E_CPU1_P3_RX_DN<5>")
	)
	(segment
		(start 121.070116 -380.944374)
		(end 120.987058 -380.526036)
		(width 0.14224)
		(layer "In4.Cu")
		(net "P5E_CPU1_P3_RX_DN<5>")
	)
	(segment
		(start 117.155468 -289.558984)
		(end 117.072664 -289.47618)
		(width 0.1143)
		(layer "In4.Cu")
		(net "P5E_CPU1_P3_RX_DN<5>")
	)
	(segment
		(start 120.742202 -379.999494)
		(end 120.849898 -379.838204)
		(width 0.14224)
		(layer "In4.Cu")
		(net "P5E_CPU1_P3_RX_DN<5>")
	)
	(segment
		(start 118.332758 -292.251638)
		(end 118.371874 -292.228778)
		(width 0.1143)
		(layer "In4.Cu")
		(net "P5E_CPU1_P3_RX_DN<5>")
	)
	(segment
		(start 121.35866 -383.756154)
		(end 121.35866 -382.456944)
		(width 0.14224)
		(layer "In4.Cu")
		(net "P5E_CPU1_P3_RX_DN<5>")
	)
	(segment
		(start 121.056908 -384.057906)
		(end 121.35866 -383.756154)
		(width 0.14224)
		(layer "In4.Cu")
		(net "P5E_CPU1_P3_RX_DN<5>")
	)
	(segment
		(start 117.903752 -290.774882)
		(end 117.902482 -290.77412)
		(width 0.1143)
		(layer "In4.Cu")
		(net "P5E_CPU1_P3_RX_DN<5>")
	)
	(segment
		(start 121.245122 -385.404868)
		(end 121.366788 -385.334764)
		(width 0.14224)
		(layer "In4.Cu")
		(net "P5E_CPU1_P3_RX_DN<5>")
	)
	(segment
		(start 121.049542 -384.84683)
		(end 121.056908 -384.057906)
		(width 0.14224)
		(layer "In4.Cu")
		(net "P5E_CPU1_P3_RX_DN<5>")
	)
	(segment
		(start 119.548148 -372.950232)
		(end 120.605042 -370.210842)
		(width 0.14224)
		(layer "In4.Cu")
		(net "P5E_CPU1_P3_RX_DN<5>")
	)
	(segment
		(start 121.207276 -381.632206)
		(end 121.045732 -381.52451)
		(width 0.14224)
		(layer "In4.Cu")
		(net "P5E_CPU1_P3_RX_DN<5>")
	)
	(segment
		(start 129.24917 -314.05703)
		(end 120.587516 -303.501806)
		(width 0.14224)
		(layer "In4.Cu")
		(net "P5E_CPU1_P3_RX_DN<5>")
	)
	(segment
		(start 117.431566 -289.963352)
		(end 117.393466 -289.941254)
		(width 0.1143)
		(layer "In4.Cu")
		(net "P5E_CPU1_P3_RX_DN<5>")
	)
	(segment
		(start 118.371874 -292.228778)
		(end 118.402354 -292.210998)
		(width 0.1143)
		(layer "In4.Cu")
		(net "P5E_CPU1_P3_RX_DN<5>")
	)
	(segment
		(start 118.371874 -293.20363)
		(end 118.332758 -293.18077)
		(width 0.1143)
		(layer "In4.Cu")
		(net "P5E_CPU1_P3_RX_DN<5>")
	)
	(segment
		(start 118.371874 -291.583618)
		(end 118.332758 -291.560758)
		(width 0.1143)
		(layer "In4.Cu")
		(net "P5E_CPU1_P3_RX_DN<5>")
	)
	(segment
		(start 117.902482 -290.77412)
		(end 117.90172 -290.773612)
		(width 0.1143)
		(layer "In4.Cu")
		(net "P5E_CPU1_P3_RX_DN<5>")
	)
	(segment
		(start 121.045732 -381.52451)
		(end 120.96242 -381.105664)
		(width 0.14224)
		(layer "In4.Cu")
		(net "P5E_CPU1_P3_RX_DN<5>")
	)
	(segment
		(start 121.366788 -385.163822)
		(end 121.049542 -384.84683)
		(width 0.14224)
		(layer "In4.Cu")
		(net "P5E_CPU1_P3_RX_DN<5>")
	)
	(segment
		(start 136.836912 -337.288632)
		(end 135.56742 -330.222606)
		(width 0.14224)
		(layer "In4.Cu")
		(net "P5E_CPU1_P3_RX_DN<5>")
	)
	(segment
		(start 120.76684 -379.419866)
		(end 120.605296 -379.311916)
		(width 0.14224)
		(layer "In4.Cu")
		(net "P5E_CPU1_P3_RX_DN<5>")
	)
	(segment
		(start 118.04396 -296.358564)
		(end 118.04396 -296.330116)
		(width 0.1143)
		(layer "In4.Cu")
		(net "P5E_CPU1_P3_RX_DN<5>")
	)
	(segment
		(start 117.906292 -290.776152)
		(end 117.903752 -290.774882)
		(width 0.1143)
		(layer "In4.Cu")
		(net "P5E_CPU1_P3_RX_DN<5>")
	)
	(segment
		(start 117.435122 -289.965384)
		(end 117.432328 -289.96386)
		(width 0.1143)
		(layer "In4.Cu")
		(net "P5E_CPU1_P3_RX_DN<5>")
	)
	(segment
		(start 118.08968 -296.284396)
		(end 118.08968 -295.956228)
		(width 0.1143)
		(layer "In4.Cu")
		(net "P5E_CPU1_P3_RX_DN<5>")
	)
	(segment
		(start 117.432328 -289.96386)
		(end 117.431566 -289.963352)
		(width 0.1143)
		(layer "In4.Cu")
		(net "P5E_CPU1_P3_RX_DN<5>")
	)
	(segment
		(start 120.521984 -378.893324)
		(end 120.629934 -378.732034)
		(width 0.14224)
		(layer "In4.Cu")
		(net "P5E_CPU1_P3_RX_DN<5>")
	)
	(segment
		(start 135.56742 -330.222606)
		(end 131.259834 -317.819532)
		(width 0.14224)
		(layer "In4.Cu")
		(net "P5E_CPU1_P3_RX_DN<5>")
	)
	(segment
		(start 120.825514 -380.41834)
		(end 120.742202 -379.999494)
		(width 0.14224)
		(layer "In4.Cu")
		(net "P5E_CPU1_P3_RX_DN<5>")
	)
	(segment
		(start 128.171702 -361.6198)
		(end 135.278114 -356.871524)
		(width 0.14224)
		(layer "In4.Cu")
		(net "P5E_CPU1_P3_RX_DN<5>")
	)
	(segment
		(start 131.259834 -317.819532)
		(end 129.24917 -314.05703)
		(width 0.14224)
		(layer "In4.Cu")
		(net "P5E_CPU1_P3_RX_DN<5>")
	)
	(segment
		(start 120.987058 -380.526036)
		(end 120.825514 -380.41834)
		(width 0.14224)
		(layer "In4.Cu")
		(net "P5E_CPU1_P3_RX_DN<5>")
	)
	(segment
		(start 117.90172 -290.773612)
		(end 117.891814 -290.767516)
		(width 0.1143)
		(layer "In4.Cu")
		(net "P5E_CPU1_P3_RX_DN<5>")
	)
	(segment
		(start 118.402354 -294.841422)
		(end 118.371874 -294.823642)
		(width 0.1143)
		(layer "In4.Cu")
		(net "P5E_CPU1_P3_RX_DN<5>")
	)
	(segment
		(start 117.93347 -290.7919)
		(end 117.908832 -290.777676)
		(width 0.1143)
		(layer "In4.Cu")
		(net "P5E_CPU1_P3_RX_DN<5>")
	)
	(segment
		(start 119.374158 -301.684182)
		(end 118.138956 -298.702476)
		(width 0.14224)
		(layer "In4.Cu")
		(net "P5E_CPU1_P3_RX_DN<5>")
	)
	(segment
		(start 118.371874 -294.823642)
		(end 118.332758 -294.800782)
		(width 0.1143)
		(layer "In4.Cu")
		(net "P5E_CPU1_P3_RX_DN<5>")
	)
	(segment
		(start 121.366788 -385.334764)
		(end 121.366788 -385.163822)
		(width 0.14224)
		(layer "In4.Cu")
		(net "P5E_CPU1_P3_RX_DN<5>")
	)
	(segment
		(start 136.836912 -353.955096)
		(end 136.836912 -337.288632)
		(width 0.14224)
		(layer "In4.Cu")
		(net "P5E_CPU1_P3_RX_DN<5>")
	)
	(segment
		(start 117.072664 -289.47618)
		(end 116.774722 -289.47618)
		(width 0.1143)
		(layer "In4.Cu")
		(net "P5E_CPU1_P3_RX_DN<5>")
	)
	(segment
		(start 121.244614 -385.405376)
		(end 121.245122 -385.404868)
		(width 0.14224)
		(layer "In4.Cu")
		(net "P5E_CPU1_P3_RX_DN<5>")
	)
	(segment
		(start 118.402354 -291.601398)
		(end 118.371874 -291.583618)
		(width 0.1143)
		(layer "In4.Cu")
		(net "P5E_CPU1_P3_RX_DN<5>")
	)
	(segment
		(start 120.605296 -379.311916)
		(end 120.521984 -378.893324)
		(width 0.14224)
		(layer "In4.Cu")
		(net "P5E_CPU1_P3_RX_DN<5>")
	)
	(segment
		(start 120.96242 -381.105664)
		(end 121.070116 -380.944374)
		(width 0.14224)
		(layer "In4.Cu")
		(net "P5E_CPU1_P3_RX_DN<5>")
	)
	(segment
		(start 120.8913 -385.31038)
		(end 121.244614 -385.405376)
		(width 0.14224)
		(layer "In4.Cu")
		(net "P5E_CPU1_P3_RX_DN<5>")
	)
	(segment
		(start 118.371874 -293.84879)
		(end 118.402354 -293.83101)
		(width 0.1143)
		(layer "In4.Cu")
		(net "P5E_CPU1_P3_RX_DN<5>")
	)
	(arc
		(start 117.159278 -289.581844)
		(mid 117.157255 -289.570434)
		(end 117.155468 -289.558984)
		(width 0.1143)
		(layer "In4.Cu")
		(net "P5E_CPU1_P3_RX_DN<5>")
	)
	(arc
		(start 118.332758 -293.18077)
		(mid 118.089431 -292.716204)
		(end 118.332758 -292.251638)
		(width 0.1143)
		(layer "In4.Cu")
		(net "P5E_CPU1_P3_RX_DN<5>")
	)
	(arc
		(start 118.08968 -295.956228)
		(mid 118.154054 -295.694024)
		(end 118.332758 -295.491662)
		(width 0.1143)
		(layer "In4.Cu")
		(net "P5E_CPU1_P3_RX_DN<5>")
	)
	(arc
		(start 118.089426 -291.096192)
		(mid 118.048171 -290.925221)
		(end 117.93347 -290.7919)
		(width 0.1143)
		(layer "In4.Cu")
		(net "P5E_CPU1_P3_RX_DN<5>")
	)
	(arc
		(start 121.35866 -382.456944)
		(mid 121.355532 -382.393772)
		(end 121.346214 -382.331214)
		(width 0.14224)
		(layer "In4.Cu")
		(net "P5E_CPU1_P3_RX_DN<5>")
	)
	(arc
		(start 117.392704 -289.940746)
		(mid 117.240717 -289.784238)
		(end 117.159278 -289.581844)
		(width 0.1143)
		(layer "In4.Cu")
		(net "P5E_CPU1_P3_RX_DN<5>")
	)
	(arc
		(start 126.195836 -363.323886)
		(mid 127.131414 -362.411138)
		(end 128.171702 -361.6198)
		(width 0.14224)
		(layer "In4.Cu")
		(net "P5E_CPU1_P3_RX_DN<5>")
	)
	(arc
		(start 118.402354 -293.83101)
		(mid 118.559331 -293.52621)
		(end 118.402354 -293.22141)
		(width 0.1143)
		(layer "In4.Cu")
		(net "P5E_CPU1_P3_RX_DN<5>")
	)
	(arc
		(start 117.618764 -290.284154)
		(mid 117.569575 -290.100203)
		(end 117.435122 -289.965384)
		(width 0.1143)
		(layer "In4.Cu")
		(net "P5E_CPU1_P3_RX_DN<5>")
	)
	(arc
		(start 118.402354 -292.210998)
		(mid 118.559331 -291.906198)
		(end 118.402354 -291.601398)
		(width 0.1143)
		(layer "In4.Cu")
		(net "P5E_CPU1_P3_RX_DN<5>")
	)
	(arc
		(start 118.138956 -298.702476)
		(mid 118.067937 -298.468266)
		(end 118.04396 -298.224702)
		(width 0.14224)
		(layer "In4.Cu")
		(net "P5E_CPU1_P3_RX_DN<5>")
	)
	(arc
		(start 119.81434 -375.372884)
		(mid 119.386349 -374.193968)
		(end 119.548148 -372.950232)
		(width 0.14224)
		(layer "In4.Cu")
		(net "P5E_CPU1_P3_RX_DN<5>")
	)
	(arc
		(start 118.332758 -294.800782)
		(mid 118.089431 -294.336216)
		(end 118.332758 -293.87165)
		(width 0.1143)
		(layer "In4.Cu")
		(net "P5E_CPU1_P3_RX_DN<5>")
	)
	(arc
		(start 120.605042 -370.210842)
		(mid 121.191981 -369.026474)
		(end 121.985786 -367.969546)
		(width 0.14224)
		(layer "In4.Cu")
		(net "P5E_CPU1_P3_RX_DN<5>")
	)
	(arc
		(start 117.891814 -290.767516)
		(mid 117.691756 -290.561727)
		(end 117.618764 -290.284154)
		(width 0.1143)
		(layer "In4.Cu")
		(net "P5E_CPU1_P3_RX_DN<5>")
	)
	(arc
		(start 117.393466 -289.941254)
		(mid 117.393085 -289.941)
		(end 117.392704 -289.940746)
		(width 0.1143)
		(layer "In4.Cu")
		(net "P5E_CPU1_P3_RX_DN<5>")
	)
	(arc
		(start 120.09882 -376.061224)
		(mid 119.984681 -375.705441)
		(end 119.81434 -375.372884)
		(width 0.14224)
		(layer "In4.Cu")
		(net "P5E_CPU1_P3_RX_DN<5>")
	)
	(arc
		(start 135.278114 -356.871524)
		(mid 136.422732 -355.608522)
		(end 136.836912 -353.955096)
		(width 0.14224)
		(layer "In4.Cu")
		(net "P5E_CPU1_P3_RX_DN<5>")
	)
	(arc
		(start 118.332758 -291.560758)
		(mid 118.153945 -291.358408)
		(end 118.089426 -291.096192)
		(width 0.1143)
		(layer "In4.Cu")
		(net "P5E_CPU1_P3_RX_DN<5>")
	)
	(arc
		(start 118.402354 -295.451022)
		(mid 118.559331 -295.146222)
		(end 118.402354 -294.841422)
		(width 0.1143)
		(layer "In4.Cu")
		(net "P5E_CPU1_P3_RX_DN<5>")
	)
	(segment
		(start 116.30787 -290.830254)
		(end 116.774722 -291.096192)
		(width 0.12954)
		(layer "F.Cu")
		(net "P5E_CPU1_P3_RX_DN<4>")
	)
	(segment
		(start 119.17045 -385.31038)
		(end 119.69115 -385.31038)
		(width 0.127)
		(layer "F.Cu")
		(net "P5E_CPU1_P3_RX_DN<4>")
	)
	(segment
		(start 119.812054 -381.372364)
		(end 119.728742 -380.953772)
		(width 0.14224)
		(layer "In4.Cu")
		(net "P5E_CPU1_P3_RX_DN<4>")
	)
	(segment
		(start 117.423438 -293.19855)
		(end 117.393974 -293.181786)
		(width 0.1143)
		(layer "In4.Cu")
		(net "P5E_CPU1_P3_RX_DN<4>")
	)
	(segment
		(start 130.400806 -318.191134)
		(end 128.468374 -314.575952)
		(width 0.14224)
		(layer "In4.Cu")
		(net "P5E_CPU1_P3_RX_DN<4>")
	)
	(segment
		(start 119.81561 -304.03165)
		(end 118.536212 -302.115728)
		(width 0.14224)
		(layer "In4.Cu")
		(net "P5E_CPU1_P3_RX_DN<4>")
	)
	(segment
		(start 117.1575 -295.964356)
		(end 117.149372 -295.956228)
		(width 0.1143)
		(layer "In4.Cu")
		(net "P5E_CPU1_P3_RX_DN<4>")
	)
	(segment
		(start 117.424962 -293.199566)
		(end 117.423438 -293.19855)
		(width 0.1143)
		(layer "In4.Cu")
		(net "P5E_CPU1_P3_RX_DN<4>")
	)
	(segment
		(start 134.661402 -330.456286)
		(end 130.400806 -318.191134)
		(width 0.14224)
		(layer "In4.Cu")
		(net "P5E_CPU1_P3_RX_DN<4>")
	)
	(segment
		(start 119.616474 -379.686312)
		(end 119.533416 -379.267974)
		(width 0.14224)
		(layer "In4.Cu")
		(net "P5E_CPU1_P3_RX_DN<4>")
	)
	(segment
		(start 119.508778 -379.847602)
		(end 119.616474 -379.686312)
		(width 0.14224)
		(layer "In4.Cu")
		(net "P5E_CPU1_P3_RX_DN<4>")
	)
	(segment
		(start 120.166638 -385.334764)
		(end 120.166638 -385.163822)
		(width 0.14224)
		(layer "In4.Cu")
		(net "P5E_CPU1_P3_RX_DN<4>")
	)
	(segment
		(start 120.15851 -383.69621)
		(end 120.15851 -382.851152)
		(width 0.14224)
		(layer "In4.Cu")
		(net "P5E_CPU1_P3_RX_DN<4>")
	)
	(segment
		(start 119.288814 -378.741178)
		(end 119.39651 -378.580142)
		(width 0.14224)
		(layer "In4.Cu")
		(net "P5E_CPU1_P3_RX_DN<4>")
	)
	(segment
		(start 119.856504 -383.997962)
		(end 120.15851 -383.69621)
		(width 0.14224)
		(layer "In4.Cu")
		(net "P5E_CPU1_P3_RX_DN<4>")
	)
	(segment
		(start 128.468374 -314.575952)
		(end 119.81561 -304.03165)
		(width 0.14224)
		(layer "In4.Cu")
		(net "P5E_CPU1_P3_RX_DN<4>")
	)
	(segment
		(start 117.072664 -291.096192)
		(end 116.774722 -291.096192)
		(width 0.1143)
		(layer "In4.Cu")
		(net "P5E_CPU1_P3_RX_DN<4>")
	)
	(segment
		(start 117.668294 -374.180354)
		(end 116.971318 -373.137176)
		(width 0.14224)
		(layer "In4.Cu")
		(net "P5E_CPU1_P3_RX_DN<4>")
	)
	(segment
		(start 120.044972 -385.404868)
		(end 120.166638 -385.334764)
		(width 0.14224)
		(layer "In4.Cu")
		(net "P5E_CPU1_P3_RX_DN<4>")
	)
	(segment
		(start 119.75338 -380.374144)
		(end 119.591836 -380.266194)
		(width 0.14224)
		(layer "In4.Cu")
		(net "P5E_CPU1_P3_RX_DN<4>")
	)
	(segment
		(start 117.430042 -293.202614)
		(end 117.424962 -293.199566)
		(width 0.1143)
		(layer "In4.Cu")
		(net "P5E_CPU1_P3_RX_DN<4>")
	)
	(segment
		(start 117.4623 -294.841422)
		(end 117.394228 -294.801798)
		(width 0.1143)
		(layer "In4.Cu")
		(net "P5E_CPU1_P3_RX_DN<4>")
	)
	(segment
		(start 117.432582 -293.203884)
		(end 117.43182 -293.20363)
		(width 0.1143)
		(layer "In4.Cu")
		(net "P5E_CPU1_P3_RX_DN<4>")
	)
	(segment
		(start 117.11178 -298.595288)
		(end 117.11178 -296.362882)
		(width 0.14224)
		(layer "In4.Cu")
		(net "P5E_CPU1_P3_RX_DN<4>")
	)
	(segment
		(start 116.971318 -373.137176)
		(end 116.971064 -373.137176)
		(width 0.14224)
		(layer "In4.Cu")
		(net "P5E_CPU1_P3_RX_DN<4>")
	)
	(segment
		(start 120.072658 -381.979678)
		(end 119.973344 -381.480314)
		(width 0.14224)
		(layer "In4.Cu")
		(net "P5E_CPU1_P3_RX_DN<4>")
	)
	(segment
		(start 117.11178 -296.362882)
		(end 117.11178 -296.334434)
		(width 0.1143)
		(layer "In4.Cu")
		(net "P5E_CPU1_P3_RX_DN<4>")
	)
	(segment
		(start 119.973344 -381.480314)
		(end 119.812054 -381.372364)
		(width 0.14224)
		(layer "In4.Cu")
		(net "P5E_CPU1_P3_RX_DN<4>")
	)
	(segment
		(start 119.371872 -379.160024)
		(end 119.288814 -378.741178)
		(width 0.14224)
		(layer "In4.Cu")
		(net "P5E_CPU1_P3_RX_DN<4>")
	)
	(segment
		(start 120.044464 -385.405376)
		(end 120.044972 -385.404868)
		(width 0.14224)
		(layer "In4.Cu")
		(net "P5E_CPU1_P3_RX_DN<4>")
	)
	(segment
		(start 119.849646 -384.84683)
		(end 119.856504 -383.997962)
		(width 0.14224)
		(layer "In4.Cu")
		(net "P5E_CPU1_P3_RX_DN<4>")
	)
	(segment
		(start 119.836438 -380.792482)
		(end 119.75338 -380.374144)
		(width 0.14224)
		(layer "In4.Cu")
		(net "P5E_CPU1_P3_RX_DN<4>")
	)
	(segment
		(start 116.78158 -372.98122)
		(end 116.462048 -372.848886)
		(width 0.14224)
		(layer "In4.Cu")
		(net "P5E_CPU1_P3_RX_DN<4>")
	)
	(segment
		(start 117.42547 -293.8526)
		(end 117.44325 -293.842186)
		(width 0.1143)
		(layer "In4.Cu")
		(net "P5E_CPU1_P3_RX_DN<4>")
	)
	(segment
		(start 135.904732 -337.377024)
		(end 134.661402 -330.456286)
		(width 0.14224)
		(layer "In4.Cu")
		(net "P5E_CPU1_P3_RX_DN<4>")
	)
	(segment
		(start 117.11178 -296.334434)
		(end 117.1575 -296.288714)
		(width 0.1143)
		(layer "In4.Cu")
		(net "P5E_CPU1_P3_RX_DN<4>")
	)
	(segment
		(start 119.728742 -380.953772)
		(end 119.836438 -380.792482)
		(width 0.14224)
		(layer "In4.Cu")
		(net "P5E_CPU1_P3_RX_DN<4>")
	)
	(segment
		(start 117.43182 -293.20363)
		(end 117.430804 -293.203122)
		(width 0.1143)
		(layer "In4.Cu")
		(net "P5E_CPU1_P3_RX_DN<4>")
	)
	(segment
		(start 117.1575 -296.288714)
		(end 117.1575 -295.964356)
		(width 0.1143)
		(layer "In4.Cu")
		(net "P5E_CPU1_P3_RX_DN<4>")
	)
	(segment
		(start 120.13311 -365.777018)
		(end 134.103364 -356.441756)
		(width 0.14224)
		(layer "In4.Cu")
		(net "P5E_CPU1_P3_RX_DN<4>")
	)
	(segment
		(start 117.394228 -292.25113)
		(end 117.431058 -292.229794)
		(width 0.1143)
		(layer "In4.Cu")
		(net "P5E_CPU1_P3_RX_DN<4>")
	)
	(segment
		(start 117.392704 -295.491662)
		(end 117.4623 -295.451022)
		(width 0.1143)
		(layer "In4.Cu")
		(net "P5E_CPU1_P3_RX_DN<4>")
	)
	(segment
		(start 120.166638 -385.163822)
		(end 119.849646 -384.84683)
		(width 0.14224)
		(layer "In4.Cu")
		(net "P5E_CPU1_P3_RX_DN<4>")
	)
	(segment
		(start 119.533416 -379.267974)
		(end 119.371872 -379.160024)
		(width 0.14224)
		(layer "In4.Cu")
		(net "P5E_CPU1_P3_RX_DN<4>")
	)
	(segment
		(start 117.155722 -291.178996)
		(end 117.155468 -291.178996)
		(width 0.1143)
		(layer "In4.Cu")
		(net "P5E_CPU1_P3_RX_DN<4>")
	)
	(segment
		(start 119.591836 -380.266194)
		(end 119.508778 -379.847602)
		(width 0.14224)
		(layer "In4.Cu")
		(net "P5E_CPU1_P3_RX_DN<4>")
	)
	(segment
		(start 119.69115 -385.31038)
		(end 120.044464 -385.405376)
		(width 0.14224)
		(layer "In4.Cu")
		(net "P5E_CPU1_P3_RX_DN<4>")
	)
	(segment
		(start 117.394228 -294.801798)
		(end 117.388132 -294.79748)
		(width 0.1143)
		(layer "In4.Cu")
		(net "P5E_CPU1_P3_RX_DN<4>")
	)
	(segment
		(start 116.628672 -369.210844)
		(end 118.337076 -367.326164)
		(width 0.14224)
		(layer "In4.Cu")
		(net "P5E_CPU1_P3_RX_DN<4>")
	)
	(segment
		(start 117.444012 -293.210488)
		(end 117.432582 -293.203884)
		(width 0.1143)
		(layer "In4.Cu")
		(net "P5E_CPU1_P3_RX_DN<4>")
	)
	(segment
		(start 115.538504 -370.974874)
		(end 115.538758 -370.974874)
		(width 0.14224)
		(layer "In4.Cu")
		(net "P5E_CPU1_P3_RX_DN<4>")
	)
	(segment
		(start 117.155468 -291.178996)
		(end 117.072664 -291.096192)
		(width 0.1143)
		(layer "In4.Cu")
		(net "P5E_CPU1_P3_RX_DN<4>")
	)
	(segment
		(start 116.20627 -372.67769)
		(end 115.811554 -372.282974)
		(width 0.14224)
		(layer "In4.Cu")
		(net "P5E_CPU1_P3_RX_DN<4>")
	)
	(segment
		(start 118.536212 -302.115728)
		(end 117.142768 -298.752006)
		(width 0.14224)
		(layer "In4.Cu")
		(net "P5E_CPU1_P3_RX_DN<4>")
	)
	(segment
		(start 117.432328 -291.583872)
		(end 117.393466 -291.561266)
		(width 0.1143)
		(layer "In4.Cu")
		(net "P5E_CPU1_P3_RX_DN<4>")
	)
	(segment
		(start 135.904732 -353.07143)
		(end 135.904732 -337.377024)
		(width 0.14224)
		(layer "In4.Cu")
		(net "P5E_CPU1_P3_RX_DN<4>")
	)
	(segment
		(start 119.39651 -378.580142)
		(end 119.309896 -378.143008)
		(width 0.14224)
		(layer "In4.Cu")
		(net "P5E_CPU1_P3_RX_DN<4>")
	)
	(segment
		(start 117.430804 -293.203122)
		(end 117.430042 -293.202614)
		(width 0.1143)
		(layer "In4.Cu")
		(net "P5E_CPU1_P3_RX_DN<4>")
	)
	(arc
		(start 117.393974 -293.181786)
		(mid 117.149802 -292.716353)
		(end 117.394228 -292.25113)
		(width 0.1143)
		(layer "In4.Cu")
		(net "P5E_CPU1_P3_RX_DN<4>")
	)
	(arc
		(start 115.538758 -370.974874)
		(mid 116.009548 -370.047034)
		(end 116.628672 -369.210844)
		(width 0.14224)
		(layer "In4.Cu")
		(net "P5E_CPU1_P3_RX_DN<4>")
	)
	(arc
		(start 117.149372 -295.956228)
		(mid 117.196306 -295.730884)
		(end 117.329204 -295.54297)
		(width 0.1143)
		(layer "In4.Cu")
		(net "P5E_CPU1_P3_RX_DN<4>")
	)
	(arc
		(start 117.393466 -291.561266)
		(mid 117.23491 -291.394818)
		(end 117.155722 -291.178996)
		(width 0.1143)
		(layer "In4.Cu")
		(net "P5E_CPU1_P3_RX_DN<4>")
	)
	(arc
		(start 116.971064 -373.137176)
		(mid 116.887867 -373.045171)
		(end 116.78158 -372.98122)
		(width 0.14224)
		(layer "In4.Cu")
		(net "P5E_CPU1_P3_RX_DN<4>")
	)
	(arc
		(start 117.4623 -295.451022)
		(mid 117.619277 -295.146222)
		(end 117.4623 -294.841422)
		(width 0.1143)
		(layer "In4.Cu")
		(net "P5E_CPU1_P3_RX_DN<4>")
	)
	(arc
		(start 119.309896 -378.143008)
		(mid 118.684263 -376.080831)
		(end 117.668294 -374.180354)
		(width 0.14224)
		(layer "In4.Cu")
		(net "P5E_CPU1_P3_RX_DN<4>")
	)
	(arc
		(start 120.15851 -382.851152)
		(mid 120.137 -382.413305)
		(end 120.072658 -381.979678)
		(width 0.14224)
		(layer "In4.Cu")
		(net "P5E_CPU1_P3_RX_DN<4>")
	)
	(arc
		(start 117.44325 -293.842186)
		(mid 117.6182 -293.5266)
		(end 117.444012 -293.210488)
		(width 0.1143)
		(layer "In4.Cu")
		(net "P5E_CPU1_P3_RX_DN<4>")
	)
	(arc
		(start 117.388132 -294.79748)
		(mid 117.147382 -294.314821)
		(end 117.42547 -293.8526)
		(width 0.1143)
		(layer "In4.Cu")
		(net "P5E_CPU1_P3_RX_DN<4>")
	)
	(arc
		(start 117.329204 -295.54297)
		(mid 117.360023 -295.516163)
		(end 117.392704 -295.491662)
		(width 0.1143)
		(layer "In4.Cu")
		(net "P5E_CPU1_P3_RX_DN<4>")
	)
	(arc
		(start 116.462048 -372.848886)
		(mid 116.325725 -372.775887)
		(end 116.20627 -372.67769)
		(width 0.14224)
		(layer "In4.Cu")
		(net "P5E_CPU1_P3_RX_DN<4>")
	)
	(arc
		(start 115.811554 -372.282974)
		(mid 115.479926 -371.669644)
		(end 115.538504 -370.974874)
		(width 0.14224)
		(layer "In4.Cu")
		(net "P5E_CPU1_P3_RX_DN<4>")
	)
	(arc
		(start 118.337076 -367.326164)
		(mid 119.187526 -366.496443)
		(end 120.13311 -365.777018)
		(width 0.14224)
		(layer "In4.Cu")
		(net "P5E_CPU1_P3_RX_DN<4>")
	)
	(arc
		(start 117.431058 -292.229794)
		(mid 117.617862 -291.907192)
		(end 117.432328 -291.583872)
		(width 0.1143)
		(layer "In4.Cu")
		(net "P5E_CPU1_P3_RX_DN<4>")
	)
	(arc
		(start 117.142768 -298.752006)
		(mid 117.119565 -298.675172)
		(end 117.11178 -298.595288)
		(width 0.14224)
		(layer "In4.Cu")
		(net "P5E_CPU1_P3_RX_DN<4>")
	)
	(arc
		(start 134.103364 -356.441756)
		(mid 135.426139 -354.982191)
		(end 135.904732 -353.07143)
		(width 0.14224)
		(layer "In4.Cu")
		(net "P5E_CPU1_P3_RX_DN<4>")
	)
	(segment
		(start 117.970554 -385.31038)
		(end 118.491254 -385.31038)
		(width 0.127)
		(layer "F.Cu")
		(net "P5E_CPU1_P3_RX_DN<3>")
	)
	(segment
		(start 116.30787 -287.590484)
		(end 116.774722 -287.856422)
		(width 0.12954)
		(layer "F.Cu")
		(net "P5E_CPU1_P3_RX_DN<3>")
	)
	(segment
		(start 116.491766 -294.823642)
		(end 116.49075 -294.823134)
		(width 0.1143)
		(layer "In4.Cu")
		(net "P5E_CPU1_P3_RX_DN<3>")
	)
	(segment
		(start 116.48821 -291.581586)
		(end 116.48567 -291.580062)
		(width 0.1143)
		(layer "In4.Cu")
		(net "P5E_CPU1_P3_RX_DN<3>")
	)
	(segment
		(start 116.48821 -292.23081)
		(end 116.489226 -292.230302)
		(width 0.1143)
		(layer "In4.Cu")
		(net "P5E_CPU1_P3_RX_DN<3>")
	)
	(segment
		(start 116.495576 -294.825928)
		(end 116.493798 -294.824912)
		(width 0.1143)
		(layer "In4.Cu")
		(net "P5E_CPU1_P3_RX_DN<3>")
	)
	(segment
		(start 115.457478 -376.104658)
		(end 115.263422 -376.104658)
		(width 0.14224)
		(layer "In4.Cu")
		(net "P5E_CPU1_P3_RX_DN<3>")
	)
	(segment
		(start 131.657852 -324.652132)
		(end 131.650232 -324.630034)
		(width 0.14224)
		(layer "In4.Cu")
		(net "P5E_CPU1_P3_RX_DN<3>")
	)
	(segment
		(start 116.481352 -293.854886)
		(end 116.48821 -293.850822)
		(width 0.1143)
		(layer "In4.Cu")
		(net "P5E_CPU1_P3_RX_DN<3>")
	)
	(segment
		(start 116.481352 -288.99485)
		(end 116.48821 -288.990786)
		(width 0.1143)
		(layer "In4.Cu")
		(net "P5E_CPU1_P3_RX_DN<3>")
	)
	(segment
		(start 117.052344 -377.699524)
		(end 116.858542 -377.699524)
		(width 0.14224)
		(layer "In4.Cu")
		(net "P5E_CPU1_P3_RX_DN<3>")
	)
	(segment
		(start 116.495322 -292.226746)
		(end 116.496084 -292.226238)
		(width 0.1143)
		(layer "In4.Cu")
		(net "P5E_CPU1_P3_RX_DN<3>")
	)
	(segment
		(start 116.96192 -288.178748)
		(end 116.994432 -288.159952)
		(width 0.1143)
		(layer "In4.Cu")
		(net "P5E_CPU1_P3_RX_DN<3>")
	)
	(segment
		(start 116.492528 -294.82415)
		(end 116.491766 -294.823642)
		(width 0.1143)
		(layer "In4.Cu")
		(net "P5E_CPU1_P3_RX_DN<3>")
	)
	(segment
		(start 116.517928 -295.450514)
		(end 116.521738 -295.448482)
		(width 0.1143)
		(layer "In4.Cu")
		(net "P5E_CPU1_P3_RX_DN<3>")
	)
	(segment
		(start 118.64975 -384.84683)
		(end 118.656862 -383.93751)
		(width 0.14224)
		(layer "In4.Cu")
		(net "P5E_CPU1_P3_RX_DN<3>")
	)
	(segment
		(start 116.45265 -289.011614)
		(end 116.48059 -288.995358)
		(width 0.1143)
		(layer "In4.Cu")
		(net "P5E_CPU1_P3_RX_DN<3>")
	)
	(segment
		(start 116.491766 -288.988754)
		(end 116.492528 -288.988246)
		(width 0.1143)
		(layer "In4.Cu")
		(net "P5E_CPU1_P3_RX_DN<3>")
	)
	(segment
		(start 119.204994 -304.807366)
		(end 117.700552 -302.555402)
		(width 0.14224)
		(layer "In4.Cu")
		(net "P5E_CPU1_P3_RX_DN<3>")
	)
	(segment
		(start 116.491766 -292.228778)
		(end 116.492528 -292.22827)
		(width 0.1143)
		(layer "In4.Cu")
		(net "P5E_CPU1_P3_RX_DN<3>")
	)
	(segment
		(start 118.656862 -383.93751)
		(end 118.958614 -383.636012)
		(width 0.14224)
		(layer "In4.Cu")
		(net "P5E_CPU1_P3_RX_DN<3>")
	)
	(segment
		(start 116.498878 -292.224714)
		(end 116.523516 -292.21049)
		(width 0.1143)
		(layer "In4.Cu")
		(net "P5E_CPU1_P3_RX_DN<3>")
	)
	(segment
		(start 116.021866 -289.79876)
		(end 116.052346 -289.78098)
		(width 0.1143)
		(layer "In4.Cu")
		(net "P5E_CPU1_P3_RX_DN<3>")
	)
	(segment
		(start 116.164106 -296.358564)
		(end 116.164106 -296.330116)
		(width 0.1143)
		(layer "In4.Cu")
		(net "P5E_CPU1_P3_RX_DN<3>")
	)
	(segment
		(start 116.4971 -292.22573)
		(end 116.497862 -292.225222)
		(width 0.1143)
		(layer "In4.Cu")
		(net "P5E_CPU1_P3_RX_DN<3>")
	)
	(segment
		(start 116.676932 -295.14546)
		(end 116.676932 -295.140888)
		(width 0.1143)
		(layer "In4.Cu")
		(net "P5E_CPU1_P3_RX_DN<3>")
	)
	(segment
		(start 116.492528 -293.848282)
		(end 116.493798 -293.84752)
		(width 0.1143)
		(layer "In4.Cu")
		(net "P5E_CPU1_P3_RX_DN<3>")
	)
	(segment
		(start 116.48059 -288.995358)
		(end 116.481352 -288.99485)
		(width 0.1143)
		(layer "In4.Cu")
		(net "P5E_CPU1_P3_RX_DN<3>")
	)
	(segment
		(start 116.164106 -298.763436)
		(end 116.164106 -296.358564)
		(width 0.14224)
		(layer "In4.Cu")
		(net "P5E_CPU1_P3_RX_DN<3>")
	)
	(segment
		(start 116.858542 -377.699524)
		(end 116.556536 -377.397518)
		(width 0.14224)
		(layer "In4.Cu")
		(net "P5E_CPU1_P3_RX_DN<3>")
	)
	(segment
		(start 116.49075 -293.849298)
		(end 116.491766 -293.84879)
		(width 0.1143)
		(layer "In4.Cu")
		(net "P5E_CPU1_P3_RX_DN<3>")
	)
	(segment
		(start 116.492528 -292.22827)
		(end 116.493798 -292.227508)
		(width 0.1143)
		(layer "In4.Cu")
		(net "P5E_CPU1_P3_RX_DN<3>")
	)
	(segment
		(start 118.958614 -383.636012)
		(end 118.958614 -382.867408)
		(width 0.14224)
		(layer "In4.Cu")
		(net "P5E_CPU1_P3_RX_DN<3>")
	)
	(segment
		(start 116.45265 -293.87165)
		(end 116.48059 -293.855394)
		(width 0.1143)
		(layer "In4.Cu")
		(net "P5E_CPU1_P3_RX_DN<3>")
	)
	(segment
		(start 116.164106 -296.330116)
		(end 116.209826 -296.284396)
		(width 0.1143)
		(layer "In4.Cu")
		(net "P5E_CPU1_P3_RX_DN<3>")
	)
	(segment
		(start 116.49075 -291.58311)
		(end 116.489226 -291.582094)
		(width 0.1143)
		(layer "In4.Cu")
		(net "P5E_CPU1_P3_RX_DN<3>")
	)
	(segment
		(start 131.650232 -324.630034)
		(end 131.650232 -324.629526)
		(width 0.14224)
		(layer "In4.Cu")
		(net "P5E_CPU1_P3_RX_DN<3>")
	)
	(segment
		(start 116.48821 -288.990786)
		(end 116.489226 -288.990278)
		(width 0.1143)
		(layer "In4.Cu")
		(net "P5E_CPU1_P3_RX_DN<3>")
	)
	(segment
		(start 114.961416 -375.802652)
		(end 114.961416 -375.608596)
		(width 0.14224)
		(layer "In4.Cu")
		(net "P5E_CPU1_P3_RX_DN<3>")
	)
	(segment
		(start 118.966742 -385.163822)
		(end 118.64975 -384.84683)
		(width 0.14224)
		(layer "In4.Cu")
		(net "P5E_CPU1_P3_RX_DN<3>")
	)
	(segment
		(start 116.496084 -293.84625)
		(end 116.4971 -293.845742)
		(width 0.1143)
		(layer "In4.Cu")
		(net "P5E_CPU1_P3_RX_DN<3>")
	)
	(segment
		(start 116.493798 -292.227508)
		(end 116.495322 -292.226746)
		(width 0.1143)
		(layer "In4.Cu")
		(net "P5E_CPU1_P3_RX_DN<3>")
	)
	(segment
		(start 116.484654 -291.5793)
		(end 116.484146 -291.579046)
		(width 0.1143)
		(layer "In4.Cu")
		(net "P5E_CPU1_P3_RX_DN<3>")
	)
	(segment
		(start 116.523516 -291.601906)
		(end 116.498878 -291.587682)
		(width 0.1143)
		(layer "In4.Cu")
		(net "P5E_CPU1_P3_RX_DN<3>")
	)
	(segment
		(start 116.496084 -288.986214)
		(end 116.4971 -288.985706)
		(width 0.1143)
		(layer "In4.Cu")
		(net "P5E_CPU1_P3_RX_DN<3>")
	)
	(segment
		(start 116.523516 -294.84193)
		(end 116.496338 -294.826436)
		(width 0.1143)
		(layer "In4.Cu")
		(net "P5E_CPU1_P3_RX_DN<3>")
	)
	(segment
		(start 131.673854 -324.697852)
		(end 131.673346 -324.696582)
		(width 0.14224)
		(layer "In4.Cu")
		(net "P5E_CPU1_P3_RX_DN<3>")
	)
	(segment
		(start 116.49075 -294.823134)
		(end 116.45265 -294.800782)
		(width 0.1143)
		(layer "In4.Cu")
		(net "P5E_CPU1_P3_RX_DN<3>")
	)
	(segment
		(start 116.489226 -291.582094)
		(end 116.48821 -291.581586)
		(width 0.1143)
		(layer "In4.Cu")
		(net "P5E_CPU1_P3_RX_DN<3>")
	)
	(segment
		(start 116.491766 -291.583618)
		(end 116.49075 -291.58311)
		(width 0.1143)
		(layer "In4.Cu")
		(net "P5E_CPU1_P3_RX_DN<3>")
	)
	(segment
		(start 116.495322 -293.846758)
		(end 116.496084 -293.84625)
		(width 0.1143)
		(layer "In4.Cu")
		(net "P5E_CPU1_P3_RX_DN<3>")
	)
	(segment
		(start 116.497862 -292.225222)
		(end 116.498878 -292.224714)
		(width 0.1143)
		(layer "In4.Cu")
		(net "P5E_CPU1_P3_RX_DN<3>")
	)
	(segment
		(start 116.48821 -293.850822)
		(end 116.489226 -293.850314)
		(width 0.1143)
		(layer "In4.Cu")
		(net "P5E_CPU1_P3_RX_DN<3>")
	)
	(segment
		(start 116.497862 -293.845234)
		(end 116.498878 -293.844726)
		(width 0.1143)
		(layer "In4.Cu")
		(net "P5E_CPU1_P3_RX_DN<3>")
	)
	(segment
		(start 118.845076 -385.404868)
		(end 118.966742 -385.334764)
		(width 0.14224)
		(layer "In4.Cu")
		(net "P5E_CPU1_P3_RX_DN<3>")
	)
	(segment
		(start 117.407944 -378.055124)
		(end 117.052344 -377.699524)
		(width 0.14224)
		(layer "In4.Cu")
		(net "P5E_CPU1_P3_RX_DN<3>")
	)
	(segment
		(start 116.48059 -292.235382)
		(end 116.481352 -292.234874)
		(width 0.1143)
		(layer "In4.Cu")
		(net "P5E_CPU1_P3_RX_DN<3>")
	)
	(segment
		(start 120.991122 -363.795056)
		(end 133.044692 -355.740462)
		(width 0.14224)
		(layer "In4.Cu")
		(net "P5E_CPU1_P3_RX_DN<3>")
	)
	(segment
		(start 131.673346 -324.696582)
		(end 131.657852 -324.652132)
		(width 0.14224)
		(layer "In4.Cu")
		(net "P5E_CPU1_P3_RX_DN<3>")
	)
	(segment
		(start 116.491766 -293.20363)
		(end 116.49075 -293.203122)
		(width 0.1143)
		(layer "In4.Cu")
		(net "P5E_CPU1_P3_RX_DN<3>")
	)
	(segment
		(start 116.493798 -288.987484)
		(end 116.495322 -288.986722)
		(width 0.1143)
		(layer "In4.Cu")
		(net "P5E_CPU1_P3_RX_DN<3>")
	)
	(segment
		(start 116.556536 -377.397518)
		(end 116.556536 -377.203716)
		(width 0.14224)
		(layer "In4.Cu")
		(net "P5E_CPU1_P3_RX_DN<3>")
	)
	(segment
		(start 115.758976 -376.600212)
		(end 115.758976 -376.406156)
		(width 0.14224)
		(layer "In4.Cu")
		(net "P5E_CPU1_P3_RX_DN<3>")
	)
	(segment
		(start 116.493798 -293.2049)
		(end 116.492528 -293.204138)
		(width 0.1143)
		(layer "In4.Cu")
		(net "P5E_CPU1_P3_RX_DN<3>")
	)
	(segment
		(start 117.142514 -287.926272)
		(end 117.072664 -287.856422)
		(width 0.1143)
		(layer "In4.Cu")
		(net "P5E_CPU1_P3_RX_DN<3>")
	)
	(segment
		(start 115.98275 -289.82162)
		(end 116.021866 -289.79876)
		(width 0.1143)
		(layer "In4.Cu")
		(net "P5E_CPU1_P3_RX_DN<3>")
	)
	(segment
		(start 114.961416 -375.608596)
		(end 114.151664 -374.798844)
		(width 0.14224)
		(layer "In4.Cu")
		(net "P5E_CPU1_P3_RX_DN<3>")
	)
	(segment
		(start 116.496084 -292.226238)
		(end 116.4971 -292.22573)
		(width 0.1143)
		(layer "In4.Cu")
		(net "P5E_CPU1_P3_RX_DN<3>")
	)
	(segment
		(start 131.650232 -324.629526)
		(end 129.544318 -318.5668)
		(width 0.14224)
		(layer "In4.Cu")
		(net "P5E_CPU1_P3_RX_DN<3>")
	)
	(segment
		(start 116.492528 -288.988246)
		(end 116.493798 -288.987484)
		(width 0.1143)
		(layer "In4.Cu")
		(net "P5E_CPU1_P3_RX_DN<3>")
	)
	(segment
		(start 118.844568 -385.405376)
		(end 118.845076 -385.404868)
		(width 0.14224)
		(layer "In4.Cu")
		(net "P5E_CPU1_P3_RX_DN<3>")
	)
	(segment
		(start 116.255038 -376.902218)
		(end 116.060982 -376.902218)
		(width 0.14224)
		(layer "In4.Cu")
		(net "P5E_CPU1_P3_RX_DN<3>")
	)
	(segment
		(start 116.498878 -291.587682)
		(end 116.497862 -291.587174)
		(width 0.1143)
		(layer "In4.Cu")
		(net "P5E_CPU1_P3_RX_DN<3>")
	)
	(segment
		(start 115.758976 -376.406156)
		(end 115.457478 -376.104658)
		(width 0.14224)
		(layer "In4.Cu")
		(net "P5E_CPU1_P3_RX_DN<3>")
	)
	(segment
		(start 116.029486 -290.778184)
		(end 116.028978 -290.77793)
		(width 0.1143)
		(layer "In4.Cu")
		(net "P5E_CPU1_P3_RX_DN<3>")
	)
	(segment
		(start 116.491766 -293.84879)
		(end 116.492528 -293.848282)
		(width 0.1143)
		(layer "In4.Cu")
		(net "P5E_CPU1_P3_RX_DN<3>")
	)
	(segment
		(start 116.48567 -291.580062)
		(end 116.484654 -291.5793)
		(width 0.1143)
		(layer "In4.Cu")
		(net "P5E_CPU1_P3_RX_DN<3>")
	)
	(segment
		(start 113.70056 -372.668546)
		(end 114.841782 -369.709192)
		(width 0.14224)
		(layer "In4.Cu")
		(net "P5E_CPU1_P3_RX_DN<3>")
	)
	(segment
		(start 116.21516 -291.113718)
		(end 116.21516 -291.101526)
		(width 0.1143)
		(layer "In4.Cu")
		(net "P5E_CPU1_P3_RX_DN<3>")
	)
	(segment
		(start 116.060982 -376.902218)
		(end 115.758976 -376.600212)
		(width 0.14224)
		(layer "In4.Cu")
		(net "P5E_CPU1_P3_RX_DN<3>")
	)
	(segment
		(start 116.498878 -293.844726)
		(end 116.523516 -293.830502)
		(width 0.1143)
		(layer "In4.Cu")
		(net "P5E_CPU1_P3_RX_DN<3>")
	)
	(segment
		(start 116.481352 -292.234874)
		(end 116.48821 -292.23081)
		(width 0.1143)
		(layer "In4.Cu")
		(net "P5E_CPU1_P3_RX_DN<3>")
	)
	(segment
		(start 116.492528 -293.204138)
		(end 116.491766 -293.20363)
		(width 0.1143)
		(layer "In4.Cu")
		(net "P5E_CPU1_P3_RX_DN<3>")
	)
	(segment
		(start 116.493798 -291.584888)
		(end 116.492528 -291.584126)
		(width 0.1143)
		(layer "In4.Cu")
		(net "P5E_CPU1_P3_RX_DN<3>")
	)
	(segment
		(start 116.209826 -296.284396)
		(end 116.209826 -295.978072)
		(width 0.1143)
		(layer "In4.Cu")
		(net "P5E_CPU1_P3_RX_DN<3>")
	)
	(segment
		(start 116.493798 -294.824912)
		(end 116.492528 -294.82415)
		(width 0.1143)
		(layer "In4.Cu")
		(net "P5E_CPU1_P3_RX_DN<3>")
	)
	(segment
		(start 118.491254 -385.31038)
		(end 118.844568 -385.405376)
		(width 0.14224)
		(layer "In4.Cu")
		(net "P5E_CPU1_P3_RX_DN<3>")
	)
	(segment
		(start 134.972552 -352.133408)
		(end 134.972552 -337.462876)
		(width 0.14224)
		(layer "In4.Cu")
		(net "P5E_CPU1_P3_RX_DN<3>")
	)
	(segment
		(start 116.492528 -291.584126)
		(end 116.491766 -291.583618)
		(width 0.1143)
		(layer "In4.Cu")
		(net "P5E_CPU1_P3_RX_DN<3>")
	)
	(segment
		(start 116.489226 -288.990278)
		(end 116.49075 -288.989262)
		(width 0.1143)
		(layer "In4.Cu")
		(net "P5E_CPU1_P3_RX_DN<3>")
	)
	(segment
		(start 116.489226 -293.850314)
		(end 116.49075 -293.849298)
		(width 0.1143)
		(layer "In4.Cu")
		(net "P5E_CPU1_P3_RX_DN<3>")
	)
	(segment
		(start 116.495322 -288.986722)
		(end 116.496084 -288.986214)
		(width 0.1143)
		(layer "In4.Cu")
		(net "P5E_CPU1_P3_RX_DN<3>")
	)
	(segment
		(start 129.544318 -318.5668)
		(end 127.76327 -315.23559)
		(width 0.14224)
		(layer "In4.Cu")
		(net "P5E_CPU1_P3_RX_DN<3>")
	)
	(segment
		(start 116.922804 -288.201608)
		(end 116.96192 -288.178748)
		(width 0.1143)
		(layer "In4.Cu")
		(net "P5E_CPU1_P3_RX_DN<3>")
	)
	(segment
		(start 118.966742 -385.334764)
		(end 118.966742 -385.163822)
		(width 0.14224)
		(layer "In4.Cu")
		(net "P5E_CPU1_P3_RX_DN<3>")
	)
	(segment
		(start 116.484146 -291.579046)
		(end 116.482876 -291.578284)
		(width 0.1143)
		(layer "In4.Cu")
		(net "P5E_CPU1_P3_RX_DN<3>")
	)
	(segment
		(start 134.972552 -337.462876)
		(end 133.7564 -330.692506)
		(width 0.14224)
		(layer "In4.Cu")
		(net "P5E_CPU1_P3_RX_DN<3>")
	)
	(segment
		(start 116.493798 -293.84752)
		(end 116.495322 -293.846758)
		(width 0.1143)
		(layer "In4.Cu")
		(net "P5E_CPU1_P3_RX_DN<3>")
	)
	(segment
		(start 133.7564 -330.692506)
		(end 131.673854 -324.697852)
		(width 0.14224)
		(layer "In4.Cu")
		(net "P5E_CPU1_P3_RX_DN<3>")
	)
	(segment
		(start 114.841782 -369.709192)
		(end 117.378734 -366.910874)
		(width 0.14224)
		(layer "In4.Cu")
		(net "P5E_CPU1_P3_RX_DN<3>")
	)
	(segment
		(start 116.48059 -293.855394)
		(end 116.481352 -293.854886)
		(width 0.1143)
		(layer "In4.Cu")
		(net "P5E_CPU1_P3_RX_DN<3>")
	)
	(segment
		(start 116.496338 -294.826436)
		(end 116.495576 -294.825928)
		(width 0.1143)
		(layer "In4.Cu")
		(net "P5E_CPU1_P3_RX_DN<3>")
	)
	(segment
		(start 116.4971 -288.985706)
		(end 116.497862 -288.985198)
		(width 0.1143)
		(layer "In4.Cu")
		(net "P5E_CPU1_P3_RX_DN<3>")
	)
	(segment
		(start 116.523516 -293.221918)
		(end 116.493798 -293.2049)
		(width 0.1143)
		(layer "In4.Cu")
		(net "P5E_CPU1_P3_RX_DN<3>")
	)
	(segment
		(start 116.498878 -288.98469)
		(end 116.523516 -288.970466)
		(width 0.1143)
		(layer "In4.Cu")
		(net "P5E_CPU1_P3_RX_DN<3>")
	)
	(segment
		(start 116.4971 -293.845742)
		(end 116.497862 -293.845234)
		(width 0.1143)
		(layer "In4.Cu")
		(net "P5E_CPU1_P3_RX_DN<3>")
	)
	(segment
		(start 116.49075 -288.989262)
		(end 116.491766 -288.988754)
		(width 0.1143)
		(layer "In4.Cu")
		(net "P5E_CPU1_P3_RX_DN<3>")
	)
	(segment
		(start 116.496338 -291.586158)
		(end 116.493798 -291.584888)
		(width 0.1143)
		(layer "In4.Cu")
		(net "P5E_CPU1_P3_RX_DN<3>")
	)
	(segment
		(start 116.489226 -292.230302)
		(end 116.49075 -292.229286)
		(width 0.1143)
		(layer "In4.Cu")
		(net "P5E_CPU1_P3_RX_DN<3>")
	)
	(segment
		(start 117.700552 -302.555402)
		(end 116.195094 -298.920154)
		(width 0.14224)
		(layer "In4.Cu")
		(net "P5E_CPU1_P3_RX_DN<3>")
	)
	(segment
		(start 127.76327 -315.23559)
		(end 119.204994 -304.807366)
		(width 0.14224)
		(layer "In4.Cu")
		(net "P5E_CPU1_P3_RX_DN<3>")
	)
	(segment
		(start 116.49075 -293.203122)
		(end 116.45265 -293.18077)
		(width 0.1143)
		(layer "In4.Cu")
		(net "P5E_CPU1_P3_RX_DN<3>")
	)
	(segment
		(start 116.497862 -291.587174)
		(end 116.496338 -291.586158)
		(width 0.1143)
		(layer "In4.Cu")
		(net "P5E_CPU1_P3_RX_DN<3>")
	)
	(segment
		(start 116.45265 -292.251638)
		(end 116.48059 -292.235382)
		(width 0.1143)
		(layer "In4.Cu")
		(net "P5E_CPU1_P3_RX_DN<3>")
	)
	(segment
		(start 116.497862 -288.985198)
		(end 116.498878 -288.98469)
		(width 0.1143)
		(layer "In4.Cu")
		(net "P5E_CPU1_P3_RX_DN<3>")
	)
	(segment
		(start 116.028978 -290.77793)
		(end 115.984274 -290.751768)
		(width 0.1143)
		(layer "In4.Cu")
		(net "P5E_CPU1_P3_RX_DN<3>")
	)
	(segment
		(start 117.072664 -287.856422)
		(end 116.774722 -287.856422)
		(width 0.1143)
		(layer "In4.Cu")
		(net "P5E_CPU1_P3_RX_DN<3>")
	)
	(segment
		(start 118.865396 -381.922782)
		(end 118.504208 -380.106174)
		(width 0.14224)
		(layer "In4.Cu")
		(net "P5E_CPU1_P3_RX_DN<3>")
	)
	(segment
		(start 115.263422 -376.104658)
		(end 114.961416 -375.802652)
		(width 0.14224)
		(layer "In4.Cu")
		(net "P5E_CPU1_P3_RX_DN<3>")
	)
	(segment
		(start 116.556536 -377.203716)
		(end 116.255038 -376.902218)
		(width 0.14224)
		(layer "In4.Cu")
		(net "P5E_CPU1_P3_RX_DN<3>")
	)
	(segment
		(start 116.49075 -292.229286)
		(end 116.491766 -292.228778)
		(width 0.1143)
		(layer "In4.Cu")
		(net "P5E_CPU1_P3_RX_DN<3>")
	)
	(arc
		(start 116.523516 -288.970466)
		(mid 116.638192 -288.837132)
		(end 116.679472 -288.666174)
		(width 0.1143)
		(layer "In4.Cu")
		(net "P5E_CPU1_P3_RX_DN<3>")
	)
	(arc
		(start 118.958614 -382.867408)
		(mid 118.93522 -382.392804)
		(end 118.865396 -381.922782)
		(width 0.14224)
		(layer "In4.Cu")
		(net "P5E_CPU1_P3_RX_DN<3>")
	)
	(arc
		(start 118.504208 -380.106174)
		(mid 118.108226 -378.999327)
		(end 117.407944 -378.055124)
		(width 0.14224)
		(layer "In4.Cu")
		(net "P5E_CPU1_P3_RX_DN<3>")
	)
	(arc
		(start 115.98275 -290.750752)
		(mid 115.739423 -290.286186)
		(end 115.98275 -289.82162)
		(width 0.1143)
		(layer "In4.Cu")
		(net "P5E_CPU1_P3_RX_DN<3>")
	)
	(arc
		(start 116.521738 -295.448482)
		(mid 116.635833 -295.315661)
		(end 116.676932 -295.14546)
		(width 0.1143)
		(layer "In4.Cu")
		(net "P5E_CPU1_P3_RX_DN<3>")
	)
	(arc
		(start 115.984274 -290.751768)
		(mid 115.983512 -290.751261)
		(end 115.98275 -290.750752)
		(width 0.1143)
		(layer "In4.Cu")
		(net "P5E_CPU1_P3_RX_DN<3>")
	)
	(arc
		(start 116.209826 -295.978072)
		(mid 116.209369 -295.962962)
		(end 116.209318 -295.947846)
		(width 0.1143)
		(layer "In4.Cu")
		(net "P5E_CPU1_P3_RX_DN<3>")
	)
	(arc
		(start 116.482876 -291.578284)
		(mid 116.286885 -291.381808)
		(end 116.21516 -291.113718)
		(width 0.1143)
		(layer "In4.Cu")
		(net "P5E_CPU1_P3_RX_DN<3>")
	)
	(arc
		(start 116.523516 -292.21049)
		(mid 116.679444 -291.906198)
		(end 116.523516 -291.601906)
		(width 0.1143)
		(layer "In4.Cu")
		(net "P5E_CPU1_P3_RX_DN<3>")
	)
	(arc
		(start 116.45265 -294.800782)
		(mid 116.209323 -294.336216)
		(end 116.45265 -293.87165)
		(width 0.1143)
		(layer "In4.Cu")
		(net "P5E_CPU1_P3_RX_DN<3>")
	)
	(arc
		(start 116.523516 -293.830502)
		(mid 116.679444 -293.52621)
		(end 116.523516 -293.221918)
		(width 0.1143)
		(layer "In4.Cu")
		(net "P5E_CPU1_P3_RX_DN<3>")
	)
	(arc
		(start 116.676932 -295.140888)
		(mid 116.636324 -294.972895)
		(end 116.523516 -294.84193)
		(width 0.1143)
		(layer "In4.Cu")
		(net "P5E_CPU1_P3_RX_DN<3>")
	)
	(arc
		(start 116.437918 -295.502076)
		(mid 116.445492 -295.496551)
		(end 116.453158 -295.491154)
		(width 0.1143)
		(layer "In4.Cu")
		(net "P5E_CPU1_P3_RX_DN<3>")
	)
	(arc
		(start 116.45265 -293.18077)
		(mid 116.209323 -292.716204)
		(end 116.45265 -292.251638)
		(width 0.1143)
		(layer "In4.Cu")
		(net "P5E_CPU1_P3_RX_DN<3>")
	)
	(arc
		(start 114.151664 -374.798844)
		(mid 113.610063 -373.800599)
		(end 113.70056 -372.668546)
		(width 0.14224)
		(layer "In4.Cu")
		(net "P5E_CPU1_P3_RX_DN<3>")
	)
	(arc
		(start 133.044692 -355.740462)
		(mid 134.460362 -354.178374)
		(end 134.972552 -352.133408)
		(width 0.14224)
		(layer "In4.Cu")
		(net "P5E_CPU1_P3_RX_DN<3>")
	)
	(arc
		(start 116.052346 -289.78098)
		(mid 116.167773 -289.647604)
		(end 116.209318 -289.47618)
		(width 0.1143)
		(layer "In4.Cu")
		(net "P5E_CPU1_P3_RX_DN<3>")
	)
	(arc
		(start 116.21516 -291.101526)
		(mid 116.165441 -290.915094)
		(end 116.029486 -290.778184)
		(width 0.1143)
		(layer "In4.Cu")
		(net "P5E_CPU1_P3_RX_DN<3>")
	)
	(arc
		(start 117.378734 -366.910874)
		(mid 119.089278 -365.242072)
		(end 120.991122 -363.795056)
		(width 0.14224)
		(layer "In4.Cu")
		(net "P5E_CPU1_P3_RX_DN<3>")
	)
	(arc
		(start 116.679472 -288.666174)
		(mid 116.743987 -288.403955)
		(end 116.922804 -288.201608)
		(width 0.1143)
		(layer "In4.Cu")
		(net "P5E_CPU1_P3_RX_DN<3>")
	)
	(arc
		(start 116.218208 -295.866566)
		(mid 116.294618 -295.664163)
		(end 116.437918 -295.502076)
		(width 0.1143)
		(layer "In4.Cu")
		(net "P5E_CPU1_P3_RX_DN<3>")
	)
	(arc
		(start 116.209318 -289.47618)
		(mid 116.273833 -289.213961)
		(end 116.45265 -289.011614)
		(width 0.1143)
		(layer "In4.Cu")
		(net "P5E_CPU1_P3_RX_DN<3>")
	)
	(arc
		(start 116.453158 -295.491154)
		(mid 116.485231 -295.470337)
		(end 116.517928 -295.450514)
		(width 0.1143)
		(layer "In4.Cu")
		(net "P5E_CPU1_P3_RX_DN<3>")
	)
	(arc
		(start 116.994432 -288.159952)
		(mid 117.090872 -288.057297)
		(end 117.142514 -287.926272)
		(width 0.1143)
		(layer "In4.Cu")
		(net "P5E_CPU1_P3_RX_DN<3>")
	)
	(arc
		(start 116.195094 -298.920154)
		(mid 116.171891 -298.84332)
		(end 116.164106 -298.763436)
		(width 0.14224)
		(layer "In4.Cu")
		(net "P5E_CPU1_P3_RX_DN<3>")
	)
	(arc
		(start 116.209318 -295.947846)
		(mid 116.212377 -295.907054)
		(end 116.218208 -295.866566)
		(width 0.1143)
		(layer "In4.Cu")
		(net "P5E_CPU1_P3_RX_DN<3>")
	)
	(segment
		(start 116.770658 -385.31038)
		(end 117.291358 -385.31038)
		(width 0.127)
		(layer "F.Cu")
		(net "P5E_CPU1_P3_RX_DN<2>")
	)
	(segment
		(start 113.957862 -290.020248)
		(end 114.424714 -290.286186)
		(width 0.12954)
		(layer "F.Cu")
		(net "P5E_CPU1_P3_RX_DN<2>")
	)
	(segment
		(start 116.791486 -379.336046)
		(end 116.209064 -378.753624)
		(width 0.14224)
		(layer "In4.Cu")
		(net "P5E_CPU1_P3_RX_DN<2>")
	)
	(segment
		(start 115.56238 -291.589714)
		(end 115.560856 -291.588952)
		(width 0.1143)
		(layer "In4.Cu")
		(net "P5E_CPU1_P3_RX_DN<2>")
	)
	(segment
		(start 114.118136 -376.662696)
		(end 113.50625 -376.05081)
		(width 0.14224)
		(layer "In4.Cu")
		(net "P5E_CPU1_P3_RX_DN<2>")
	)
	(segment
		(start 117.667532 -381.887984)
		(end 117.37848 -380.434342)
		(width 0.14224)
		(layer "In4.Cu")
		(net "P5E_CPU1_P3_RX_DN<2>")
	)
	(segment
		(start 114.915696 -377.460256)
		(end 114.614198 -377.158758)
		(width 0.14224)
		(layer "In4.Cu")
		(net "P5E_CPU1_P3_RX_DN<2>")
	)
	(segment
		(start 115.541806 -293.198042)
		(end 115.512596 -293.18077)
		(width 0.1143)
		(layer "In4.Cu")
		(net "P5E_CPU1_P3_RX_DN<2>")
	)
	(segment
		(start 117.644418 -385.405376)
		(end 117.644926 -385.404868)
		(width 0.14224)
		(layer "In4.Cu")
		(net "P5E_CPU1_P3_RX_DN<2>")
	)
	(segment
		(start 117.758464 -382.81229)
		(end 117.75821 -382.812544)
		(width 0.14224)
		(layer "In4.Cu")
		(net "P5E_CPU1_P3_RX_DN<2>")
	)
	(segment
		(start 115.55857 -294.827706)
		(end 115.556284 -294.826182)
		(width 0.1143)
		(layer "In4.Cu")
		(net "P5E_CPU1_P3_RX_DN<2>")
	)
	(segment
		(start 115.519454 -295.487598)
		(end 115.520216 -295.48709)
		(width 0.1143)
		(layer "In4.Cu")
		(net "P5E_CPU1_P3_RX_DN<2>")
	)
	(segment
		(start 115.217702 -377.956318)
		(end 114.915696 -377.654312)
		(width 0.14224)
		(layer "In4.Cu")
		(net "P5E_CPU1_P3_RX_DN<2>")
	)
	(segment
		(start 115.520216 -295.48709)
		(end 115.544854 -295.472866)
		(width 0.1143)
		(layer "In4.Cu")
		(net "P5E_CPU1_P3_RX_DN<2>")
	)
	(segment
		(start 115.548156 -293.201598)
		(end 115.546632 -293.200582)
		(width 0.1143)
		(layer "In4.Cu")
		(net "P5E_CPU1_P3_RX_DN<2>")
	)
	(segment
		(start 115.550696 -291.58311)
		(end 115.549172 -291.582094)
		(width 0.1143)
		(layer "In4.Cu")
		(net "P5E_CPU1_P3_RX_DN<2>")
	)
	(segment
		(start 117.766592 -385.163822)
		(end 117.4496 -384.84683)
		(width 0.14224)
		(layer "In4.Cu")
		(net "P5E_CPU1_P3_RX_DN<2>")
	)
	(segment
		(start 115.559586 -291.58819)
		(end 115.55857 -291.587682)
		(width 0.1143)
		(layer "In4.Cu")
		(net "P5E_CPU1_P3_RX_DN<2>")
	)
	(segment
		(start 115.223798 -296.358564)
		(end 115.223798 -296.330116)
		(width 0.1143)
		(layer "In4.Cu")
		(net "P5E_CPU1_P3_RX_DN<2>")
	)
	(segment
		(start 115.556284 -291.586158)
		(end 115.553744 -291.584888)
		(width 0.1143)
		(layer "In4.Cu")
		(net "P5E_CPU1_P3_RX_DN<2>")
	)
	(segment
		(start 117.766592 -385.334764)
		(end 117.766592 -385.163822)
		(width 0.14224)
		(layer "In4.Cu")
		(net "P5E_CPU1_P3_RX_DN<2>")
	)
	(segment
		(start 114.614198 -377.158758)
		(end 114.420142 -377.158758)
		(width 0.14224)
		(layer "In4.Cu")
		(net "P5E_CPU1_P3_RX_DN<2>")
	)
	(segment
		(start 115.549172 -294.822118)
		(end 115.548156 -294.82161)
		(width 0.1143)
		(layer "In4.Cu")
		(net "P5E_CPU1_P3_RX_DN<2>")
	)
	(segment
		(start 115.559586 -293.208202)
		(end 115.55857 -293.207694)
		(width 0.1143)
		(layer "In4.Cu")
		(net "P5E_CPU1_P3_RX_DN<2>")
	)
	(segment
		(start 115.546632 -291.58057)
		(end 115.544092 -291.5793)
		(width 0.1143)
		(layer "In4.Cu")
		(net "P5E_CPU1_P3_RX_DN<2>")
	)
	(segment
		(start 115.546632 -294.820594)
		(end 115.544092 -294.819324)
		(width 0.1143)
		(layer "In4.Cu")
		(net "P5E_CPU1_P3_RX_DN<2>")
	)
	(segment
		(start 115.269518 -296.284396)
		(end 115.269518 -295.956228)
		(width 0.1143)
		(layer "In4.Cu")
		(net "P5E_CPU1_P3_RX_DN<2>")
	)
	(segment
		(start 115.560856 -291.588952)
		(end 115.559586 -291.58819)
		(width 0.1143)
		(layer "In4.Cu")
		(net "P5E_CPU1_P3_RX_DN<2>")
	)
	(segment
		(start 115.544092 -293.199312)
		(end 115.542822 -293.19855)
		(width 0.1143)
		(layer "In4.Cu")
		(net "P5E_CPU1_P3_RX_DN<2>")
	)
	(segment
		(start 115.542822 -291.578538)
		(end 115.541806 -291.57803)
		(width 0.1143)
		(layer "In4.Cu")
		(net "P5E_CPU1_P3_RX_DN<2>")
	)
	(segment
		(start 115.544092 -291.5793)
		(end 115.542822 -291.578538)
		(width 0.1143)
		(layer "In4.Cu")
		(net "P5E_CPU1_P3_RX_DN<2>")
	)
	(segment
		(start 115.560856 -293.208964)
		(end 115.559586 -293.208202)
		(width 0.1143)
		(layer "In4.Cu")
		(net "P5E_CPU1_P3_RX_DN<2>")
	)
	(segment
		(start 114.80546 -290.36899)
		(end 114.722656 -290.286186)
		(width 0.1143)
		(layer "In4.Cu")
		(net "P5E_CPU1_P3_RX_DN<2>")
	)
	(segment
		(start 114.118136 -376.856752)
		(end 114.118136 -376.662696)
		(width 0.14224)
		(layer "In4.Cu")
		(net "P5E_CPU1_P3_RX_DN<2>")
	)
	(segment
		(start 115.55857 -293.207694)
		(end 115.556284 -293.20617)
		(width 0.1143)
		(layer "In4.Cu")
		(net "P5E_CPU1_P3_RX_DN<2>")
	)
	(segment
		(start 115.553744 -294.824912)
		(end 115.552474 -294.82415)
		(width 0.1143)
		(layer "In4.Cu")
		(net "P5E_CPU1_P3_RX_DN<2>")
	)
	(segment
		(start 128.687576 -318.942974)
		(end 127.000508 -315.78677)
		(width 0.14224)
		(layer "In4.Cu")
		(net "P5E_CPU1_P3_RX_DN<2>")
	)
	(segment
		(start 115.541806 -294.818054)
		(end 115.512596 -294.800782)
		(width 0.1143)
		(layer "In4.Cu")
		(net "P5E_CPU1_P3_RX_DN<2>")
	)
	(segment
		(start 115.552474 -293.204138)
		(end 115.551712 -293.20363)
		(width 0.1143)
		(layer "In4.Cu")
		(net "P5E_CPU1_P3_RX_DN<2>")
	)
	(segment
		(start 117.758464 -383.589276)
		(end 117.758464 -382.81229)
		(width 0.14224)
		(layer "In4.Cu")
		(net "P5E_CPU1_P3_RX_DN<2>")
	)
	(segment
		(start 115.556284 -293.20617)
		(end 115.553744 -293.2049)
		(width 0.1143)
		(layer "In4.Cu")
		(net "P5E_CPU1_P3_RX_DN<2>")
	)
	(segment
		(start 115.56238 -293.209726)
		(end 115.560856 -293.208964)
		(width 0.1143)
		(layer "In4.Cu")
		(net "P5E_CPU1_P3_RX_DN<2>")
	)
	(segment
		(start 115.583462 -294.84193)
		(end 115.56238 -294.829738)
		(width 0.1143)
		(layer "In4.Cu")
		(net "P5E_CPU1_P3_RX_DN<2>")
	)
	(segment
		(start 116.015262 -378.753624)
		(end 115.713256 -378.451618)
		(width 0.14224)
		(layer "In4.Cu")
		(net "P5E_CPU1_P3_RX_DN<2>")
	)
	(segment
		(start 120.603518 -307.992272)
		(end 120.603772 -307.992272)
		(width 0.14224)
		(layer "In4.Cu")
		(net "P5E_CPU1_P3_RX_DN<2>")
	)
	(segment
		(start 134.0358 -352.09353)
		(end 134.0358 -337.523836)
		(width 0.14224)
		(layer "In4.Cu")
		(net "P5E_CPU1_P3_RX_DN<2>")
	)
	(segment
		(start 133.439154 -334.202786)
		(end 132.851906 -330.931266)
		(width 0.14224)
		(layer "In4.Cu")
		(net "P5E_CPU1_P3_RX_DN<2>")
	)
	(segment
		(start 118.4656 -305.38674)
		(end 116.878862 -303.012856)
		(width 0.14224)
		(layer "In4.Cu")
		(net "P5E_CPU1_P3_RX_DN<2>")
	)
	(segment
		(start 120.601486 -362.911136)
		(end 132.624576 -354.877624)
		(width 0.14224)
		(layer "In4.Cu")
		(net "P5E_CPU1_P3_RX_DN<2>")
	)
	(segment
		(start 122.7328 -310.586628)
		(end 122.733054 -310.586628)
		(width 0.14224)
		(layer "In4.Cu")
		(net "P5E_CPU1_P3_RX_DN<2>")
	)
	(segment
		(start 115.548156 -291.581586)
		(end 115.546632 -291.58057)
		(width 0.1143)
		(layer "In4.Cu")
		(net "P5E_CPU1_P3_RX_DN<2>")
	)
	(segment
		(start 115.560856 -294.828976)
		(end 115.559586 -294.828214)
		(width 0.1143)
		(layer "In4.Cu")
		(net "P5E_CPU1_P3_RX_DN<2>")
	)
	(segment
		(start 115.551712 -294.823642)
		(end 115.550696 -294.823134)
		(width 0.1143)
		(layer "In4.Cu")
		(net "P5E_CPU1_P3_RX_DN<2>")
	)
	(segment
		(start 115.542822 -294.818562)
		(end 115.541806 -294.818054)
		(width 0.1143)
		(layer "In4.Cu")
		(net "P5E_CPU1_P3_RX_DN<2>")
	)
	(segment
		(start 115.223798 -296.330116)
		(end 115.269518 -296.284396)
		(width 0.1143)
		(layer "In4.Cu")
		(net "P5E_CPU1_P3_RX_DN<2>")
	)
	(segment
		(start 115.541806 -291.57803)
		(end 115.512596 -291.560758)
		(width 0.1143)
		(layer "In4.Cu")
		(net "P5E_CPU1_P3_RX_DN<2>")
	)
	(segment
		(start 115.512596 -295.491662)
		(end 115.519454 -295.487598)
		(width 0.1143)
		(layer "In4.Cu")
		(net "P5E_CPU1_P3_RX_DN<2>")
	)
	(segment
		(start 117.4496 -384.84683)
		(end 117.45722 -383.890266)
		(width 0.14224)
		(layer "In4.Cu")
		(net "P5E_CPU1_P3_RX_DN<2>")
	)
	(segment
		(start 133.439408 -334.202786)
		(end 133.439154 -334.202786)
		(width 0.14224)
		(layer "In4.Cu")
		(net "P5E_CPU1_P3_RX_DN<2>")
	)
	(segment
		(start 115.556284 -294.826182)
		(end 115.553744 -294.824912)
		(width 0.1143)
		(layer "In4.Cu")
		(net "P5E_CPU1_P3_RX_DN<2>")
	)
	(segment
		(start 115.550696 -293.203122)
		(end 115.549172 -293.202106)
		(width 0.1143)
		(layer "In4.Cu")
		(net "P5E_CPU1_P3_RX_DN<2>")
	)
	(segment
		(start 130.76936 -324.936866)
		(end 128.687576 -318.942974)
		(width 0.14224)
		(layer "In4.Cu")
		(net "P5E_CPU1_P3_RX_DN<2>")
	)
	(segment
		(start 115.552474 -294.82415)
		(end 115.551712 -294.823642)
		(width 0.1143)
		(layer "In4.Cu")
		(net "P5E_CPU1_P3_RX_DN<2>")
	)
	(segment
		(start 114.915696 -377.654312)
		(end 114.915696 -377.460256)
		(width 0.14224)
		(layer "In4.Cu")
		(net "P5E_CPU1_P3_RX_DN<2>")
	)
	(segment
		(start 115.544092 -294.819324)
		(end 115.542822 -294.818562)
		(width 0.1143)
		(layer "In4.Cu")
		(net "P5E_CPU1_P3_RX_DN<2>")
	)
	(segment
		(start 115.546632 -293.200582)
		(end 115.544092 -293.199312)
		(width 0.1143)
		(layer "In4.Cu")
		(net "P5E_CPU1_P3_RX_DN<2>")
	)
	(segment
		(start 116.209064 -378.753624)
		(end 116.015262 -378.753624)
		(width 0.14224)
		(layer "In4.Cu")
		(net "P5E_CPU1_P3_RX_DN<2>")
	)
	(segment
		(start 115.552474 -291.584126)
		(end 115.551712 -291.583618)
		(width 0.1143)
		(layer "In4.Cu")
		(net "P5E_CPU1_P3_RX_DN<2>")
	)
	(segment
		(start 115.551712 -291.583618)
		(end 115.550696 -291.58311)
		(width 0.1143)
		(layer "In4.Cu")
		(net "P5E_CPU1_P3_RX_DN<2>")
	)
	(segment
		(start 115.411758 -377.956318)
		(end 115.217702 -377.956318)
		(width 0.14224)
		(layer "In4.Cu")
		(net "P5E_CPU1_P3_RX_DN<2>")
	)
	(segment
		(start 115.559586 -294.828214)
		(end 115.55857 -294.827706)
		(width 0.1143)
		(layer "In4.Cu")
		(net "P5E_CPU1_P3_RX_DN<2>")
	)
	(segment
		(start 114.722656 -290.286186)
		(end 114.424714 -290.286186)
		(width 0.1143)
		(layer "In4.Cu")
		(net "P5E_CPU1_P3_RX_DN<2>")
	)
	(segment
		(start 115.553998 -295.467532)
		(end 115.555014 -295.467024)
		(width 0.1143)
		(layer "In4.Cu")
		(net "P5E_CPU1_P3_RX_DN<2>")
	)
	(segment
		(start 115.553744 -293.2049)
		(end 115.552474 -293.204138)
		(width 0.1143)
		(layer "In4.Cu")
		(net "P5E_CPU1_P3_RX_DN<2>")
	)
	(segment
		(start 117.45722 -383.890266)
		(end 117.758464 -383.589276)
		(width 0.14224)
		(layer "In4.Cu")
		(net "P5E_CPU1_P3_RX_DN<2>")
	)
	(segment
		(start 115.549172 -293.202106)
		(end 115.548156 -293.201598)
		(width 0.1143)
		(layer "In4.Cu")
		(net "P5E_CPU1_P3_RX_DN<2>")
	)
	(segment
		(start 115.549172 -291.582094)
		(end 115.548156 -291.581586)
		(width 0.1143)
		(layer "In4.Cu")
		(net "P5E_CPU1_P3_RX_DN<2>")
	)
	(segment
		(start 114.420142 -377.158758)
		(end 114.118136 -376.856752)
		(width 0.14224)
		(layer "In4.Cu")
		(net "P5E_CPU1_P3_RX_DN<2>")
	)
	(segment
		(start 120.603772 -307.992272)
		(end 118.4656 -305.38674)
		(width 0.14224)
		(layer "In4.Cu")
		(net "P5E_CPU1_P3_RX_DN<2>")
	)
	(segment
		(start 116.878862 -303.012856)
		(end 115.254786 -299.091604)
		(width 0.14224)
		(layer "In4.Cu")
		(net "P5E_CPU1_P3_RX_DN<2>")
	)
	(segment
		(start 115.713256 -378.451618)
		(end 115.713256 -378.257816)
		(width 0.14224)
		(layer "In4.Cu")
		(net "P5E_CPU1_P3_RX_DN<2>")
	)
	(segment
		(start 117.644926 -385.404868)
		(end 117.766592 -385.334764)
		(width 0.14224)
		(layer "In4.Cu")
		(net "P5E_CPU1_P3_RX_DN<2>")
	)
	(segment
		(start 115.55857 -291.587682)
		(end 115.556284 -291.586158)
		(width 0.1143)
		(layer "In4.Cu")
		(net "P5E_CPU1_P3_RX_DN<2>")
	)
	(segment
		(start 115.555776 -295.466516)
		(end 115.557808 -295.4655)
		(width 0.1143)
		(layer "In4.Cu")
		(net "P5E_CPU1_P3_RX_DN<2>")
	)
	(segment
		(start 127.000508 -315.78677)
		(end 122.7328 -310.586628)
		(width 0.14224)
		(layer "In4.Cu")
		(net "P5E_CPU1_P3_RX_DN<2>")
	)
	(segment
		(start 115.553744 -291.584888)
		(end 115.552474 -291.584126)
		(width 0.1143)
		(layer "In4.Cu")
		(net "P5E_CPU1_P3_RX_DN<2>")
	)
	(segment
		(start 115.548156 -294.82161)
		(end 115.546632 -294.820594)
		(width 0.1143)
		(layer "In4.Cu")
		(net "P5E_CPU1_P3_RX_DN<2>")
	)
	(segment
		(start 115.56238 -294.829738)
		(end 115.560856 -294.828976)
		(width 0.1143)
		(layer "In4.Cu")
		(net "P5E_CPU1_P3_RX_DN<2>")
	)
	(segment
		(start 115.512596 -292.251638)
		(end 115.583462 -292.21049)
		(width 0.1143)
		(layer "In4.Cu")
		(net "P5E_CPU1_P3_RX_DN<2>")
	)
	(segment
		(start 130.769614 -324.936866)
		(end 130.76936 -324.936866)
		(width 0.14224)
		(layer "In4.Cu")
		(net "P5E_CPU1_P3_RX_DN<2>")
	)
	(segment
		(start 113.878106 -369.303554)
		(end 116.342668 -366.584738)
		(width 0.14224)
		(layer "In4.Cu")
		(net "P5E_CPU1_P3_RX_DN<2>")
	)
	(segment
		(start 115.223798 -298.934886)
		(end 115.223798 -296.358564)
		(width 0.14224)
		(layer "In4.Cu")
		(net "P5E_CPU1_P3_RX_DN<2>")
	)
	(segment
		(start 134.0358 -337.523836)
		(end 133.439408 -334.202786)
		(width 0.14224)
		(layer "In4.Cu")
		(net "P5E_CPU1_P3_RX_DN<2>")
	)
	(segment
		(start 115.551712 -293.20363)
		(end 115.550696 -293.203122)
		(width 0.1143)
		(layer "In4.Cu")
		(net "P5E_CPU1_P3_RX_DN<2>")
	)
	(segment
		(start 115.112292 -290.791392)
		(end 115.042696 -290.750752)
		(width 0.1143)
		(layer "In4.Cu")
		(net "P5E_CPU1_P3_RX_DN<2>")
	)
	(segment
		(start 115.512596 -293.87165)
		(end 115.583462 -293.830502)
		(width 0.1143)
		(layer "In4.Cu")
		(net "P5E_CPU1_P3_RX_DN<2>")
	)
	(segment
		(start 112.715802 -372.317264)
		(end 113.878106 -369.303554)
		(width 0.14224)
		(layer "In4.Cu")
		(net "P5E_CPU1_P3_RX_DN<2>")
	)
	(segment
		(start 115.555014 -295.467024)
		(end 115.555776 -295.466516)
		(width 0.1143)
		(layer "In4.Cu")
		(net "P5E_CPU1_P3_RX_DN<2>")
	)
	(segment
		(start 132.851906 -330.931266)
		(end 130.769614 -324.936866)
		(width 0.14224)
		(layer "In4.Cu")
		(net "P5E_CPU1_P3_RX_DN<2>")
	)
	(segment
		(start 115.583462 -293.221918)
		(end 115.56238 -293.209726)
		(width 0.1143)
		(layer "In4.Cu")
		(net "P5E_CPU1_P3_RX_DN<2>")
	)
	(segment
		(start 115.583462 -291.601906)
		(end 115.56238 -291.589714)
		(width 0.1143)
		(layer "In4.Cu")
		(net "P5E_CPU1_P3_RX_DN<2>")
	)
	(segment
		(start 115.550696 -294.823134)
		(end 115.549172 -294.822118)
		(width 0.1143)
		(layer "In4.Cu")
		(net "P5E_CPU1_P3_RX_DN<2>")
	)
	(segment
		(start 115.553236 -295.46804)
		(end 115.553998 -295.467532)
		(width 0.1143)
		(layer "In4.Cu")
		(net "P5E_CPU1_P3_RX_DN<2>")
	)
	(segment
		(start 115.544854 -295.472866)
		(end 115.553236 -295.46804)
		(width 0.1143)
		(layer "In4.Cu")
		(net "P5E_CPU1_P3_RX_DN<2>")
	)
	(segment
		(start 115.542822 -293.19855)
		(end 115.541806 -293.198042)
		(width 0.1143)
		(layer "In4.Cu")
		(net "P5E_CPU1_P3_RX_DN<2>")
	)
	(segment
		(start 115.557808 -295.4655)
		(end 115.583462 -295.450514)
		(width 0.1143)
		(layer "In4.Cu")
		(net "P5E_CPU1_P3_RX_DN<2>")
	)
	(segment
		(start 122.733054 -310.586628)
		(end 120.603518 -307.992272)
		(width 0.14224)
		(layer "In4.Cu")
		(net "P5E_CPU1_P3_RX_DN<2>")
	)
	(segment
		(start 115.713256 -378.257816)
		(end 115.411758 -377.956318)
		(width 0.14224)
		(layer "In4.Cu")
		(net "P5E_CPU1_P3_RX_DN<2>")
	)
	(segment
		(start 117.291358 -385.31038)
		(end 117.644418 -385.405376)
		(width 0.14224)
		(layer "In4.Cu")
		(net "P5E_CPU1_P3_RX_DN<2>")
	)
	(arc
		(start 115.583462 -295.450514)
		(mid 115.73939 -295.146222)
		(end 115.583462 -294.84193)
		(width 0.1143)
		(layer "In4.Cu")
		(net "P5E_CPU1_P3_RX_DN<2>")
	)
	(arc
		(start 115.269264 -291.096192)
		(mid 115.227715 -290.92477)
		(end 115.112292 -290.791392)
		(width 0.1143)
		(layer "In4.Cu")
		(net "P5E_CPU1_P3_RX_DN<2>")
	)
	(arc
		(start 115.512596 -293.18077)
		(mid 115.269269 -292.716204)
		(end 115.512596 -292.251638)
		(width 0.1143)
		(layer "In4.Cu")
		(net "P5E_CPU1_P3_RX_DN<2>")
	)
	(arc
		(start 115.583462 -293.830502)
		(mid 115.73939 -293.52621)
		(end 115.583462 -293.221918)
		(width 0.1143)
		(layer "In4.Cu")
		(net "P5E_CPU1_P3_RX_DN<2>")
	)
	(arc
		(start 115.583462 -292.21049)
		(mid 115.73939 -291.906198)
		(end 115.583462 -291.601906)
		(width 0.1143)
		(layer "In4.Cu")
		(net "P5E_CPU1_P3_RX_DN<2>")
	)
	(arc
		(start 117.37848 -380.434342)
		(mid 117.166438 -379.841661)
		(end 116.791486 -379.336046)
		(width 0.14224)
		(layer "In4.Cu")
		(net "P5E_CPU1_P3_RX_DN<2>")
	)
	(arc
		(start 133.719062 -353.456494)
		(mid 133.955503 -352.793154)
		(end 134.0358 -352.09353)
		(width 0.14224)
		(layer "In4.Cu")
		(net "P5E_CPU1_P3_RX_DN<2>")
	)
	(arc
		(start 115.512596 -291.560758)
		(mid 115.333783 -291.358408)
		(end 115.269264 -291.096192)
		(width 0.1143)
		(layer "In4.Cu")
		(net "P5E_CPU1_P3_RX_DN<2>")
	)
	(arc
		(start 132.624576 -354.877624)
		(mid 132.823442 -354.732196)
		(end 133.009132 -354.570284)
		(width 0.14224)
		(layer "In4.Cu")
		(net "P5E_CPU1_P3_RX_DN<2>")
	)
	(arc
		(start 115.269518 -295.956228)
		(mid 115.297434 -295.780252)
		(end 115.378738 -295.62171)
		(width 0.1143)
		(layer "In4.Cu")
		(net "P5E_CPU1_P3_RX_DN<2>")
	)
	(arc
		(start 115.254786 -299.091604)
		(mid 115.231583 -299.01477)
		(end 115.223798 -298.934886)
		(width 0.14224)
		(layer "In4.Cu")
		(net "P5E_CPU1_P3_RX_DN<2>")
	)
	(arc
		(start 113.50625 -376.05081)
		(mid 112.557265 -374.301287)
		(end 112.715802 -372.317264)
		(width 0.14224)
		(layer "In4.Cu")
		(net "P5E_CPU1_P3_RX_DN<2>")
	)
	(arc
		(start 116.342668 -366.584738)
		(mid 118.35924 -364.617124)
		(end 120.601486 -362.911136)
		(width 0.14224)
		(layer "In4.Cu")
		(net "P5E_CPU1_P3_RX_DN<2>")
	)
	(arc
		(start 114.80927 -290.39185)
		(mid 114.807247 -290.38044)
		(end 114.80546 -290.36899)
		(width 0.1143)
		(layer "In4.Cu")
		(net "P5E_CPU1_P3_RX_DN<2>")
	)
	(arc
		(start 115.512596 -294.800782)
		(mid 115.269269 -294.336216)
		(end 115.512596 -293.87165)
		(width 0.1143)
		(layer "In4.Cu")
		(net "P5E_CPU1_P3_RX_DN<2>")
	)
	(arc
		(start 115.378738 -295.62171)
		(mid 115.440257 -295.551116)
		(end 115.512596 -295.491662)
		(width 0.1143)
		(layer "In4.Cu")
		(net "P5E_CPU1_P3_RX_DN<2>")
	)
	(arc
		(start 133.009132 -354.570284)
		(mid 133.432104 -354.05674)
		(end 133.719062 -353.456494)
		(width 0.14224)
		(layer "In4.Cu")
		(net "P5E_CPU1_P3_RX_DN<2>")
	)
	(arc
		(start 115.042696 -290.750752)
		(mid 114.890709 -290.594244)
		(end 114.80927 -290.39185)
		(width 0.1143)
		(layer "In4.Cu")
		(net "P5E_CPU1_P3_RX_DN<2>")
	)
	(arc
		(start 117.75821 -382.812544)
		(mid 117.735573 -382.348037)
		(end 117.667532 -381.887984)
		(width 0.14224)
		(layer "In4.Cu")
		(net "P5E_CPU1_P3_RX_DN<2>")
	)
	(segment
		(start 113.957862 -288.400236)
		(end 114.424714 -288.666174)
		(width 0.12954)
		(layer "F.Cu")
		(net "P5E_CPU1_P3_RX_DN<1>")
	)
	(segment
		(start 115.570508 -385.31038)
		(end 116.091208 -385.31038)
		(width 0.127)
		(layer "F.Cu")
		(net "P5E_CPU1_P3_RX_DN<1>")
	)
	(segment
		(start 114.616484 -295.466008)
		(end 114.643408 -295.450514)
		(width 0.1143)
		(layer "In4.Cu")
		(net "P5E_CPU1_P3_RX_DN<1>")
	)
	(segment
		(start 112.652302 -377.160536)
		(end 109.598714 -374.10644)
		(width 0.14224)
		(layer "In4.Cu")
		(net "P5E_CPU1_P3_RX_DN<1>")
	)
	(segment
		(start 114.103404 -289.821112)
		(end 114.145822 -289.796474)
		(width 0.1143)
		(layer "In4.Cu")
		(net "P5E_CPU1_P3_RX_DN<1>")
	)
	(segment
		(start 131.661154 -354.175822)
		(end 131.661154 -354.176076)
		(width 0.14224)
		(layer "In4.Cu")
		(net "P5E_CPU1_P3_RX_DN<1>")
	)
	(segment
		(start 113.751868 -378.453904)
		(end 113.449862 -378.151898)
		(width 0.14224)
		(layer "In4.Cu")
		(net "P5E_CPU1_P3_RX_DN<1>")
	)
	(segment
		(start 114.610642 -295.46931)
		(end 114.611658 -295.468802)
		(width 0.1143)
		(layer "In4.Cu")
		(net "P5E_CPU1_P3_RX_DN<1>")
	)
	(segment
		(start 114.098578 -365.17453)
		(end 117.068854 -363.944154)
		(width 0.14224)
		(layer "In4.Cu")
		(net "P5E_CPU1_P3_RX_DN<1>")
	)
	(segment
		(start 117.131338 -363.910626)
		(end 124.350526 -359.086912)
		(width 0.14224)
		(layer "In4.Cu")
		(net "P5E_CPU1_P3_RX_DN<1>")
	)
	(segment
		(start 114.610642 -291.58311)
		(end 114.60988 -291.582602)
		(width 0.1143)
		(layer "In4.Cu")
		(net "P5E_CPU1_P3_RX_DN<1>")
	)
	(segment
		(start 114.329464 -296.284396)
		(end 114.329464 -295.956228)
		(width 0.1143)
		(layer "In4.Cu")
		(net "P5E_CPU1_P3_RX_DN<1>")
	)
	(segment
		(start 114.247422 -378.755656)
		(end 113.945924 -378.453904)
		(width 0.14224)
		(layer "In4.Cu")
		(net "P5E_CPU1_P3_RX_DN<1>")
	)
	(segment
		(start 114.611658 -291.583618)
		(end 114.610642 -291.58311)
		(width 0.1143)
		(layer "In4.Cu")
		(net "P5E_CPU1_P3_RX_DN<1>")
	)
	(segment
		(start 115.860322 -380.368556)
		(end 114.743484 -379.251718)
		(width 0.14224)
		(layer "In4.Cu")
		(net "P5E_CPU1_P3_RX_DN<1>")
	)
	(segment
		(start 114.643408 -294.84193)
		(end 114.61242 -294.82415)
		(width 0.1143)
		(layer "In4.Cu")
		(net "P5E_CPU1_P3_RX_DN<1>")
	)
	(segment
		(start 116.44503 -385.404868)
		(end 116.566696 -385.334764)
		(width 0.14224)
		(layer "In4.Cu")
		(net "P5E_CPU1_P3_RX_DN<1>")
	)
	(segment
		(start 114.643408 -291.601906)
		(end 114.611658 -291.583618)
		(width 0.1143)
		(layer "In4.Cu")
		(net "P5E_CPU1_P3_RX_DN<1>")
	)
	(segment
		(start 124.350526 -359.086912)
		(end 124.350526 -359.086658)
		(width 0.14224)
		(layer "In4.Cu")
		(net "P5E_CPU1_P3_RX_DN<1>")
	)
	(segment
		(start 131.568952 -354.263452)
		(end 131.56946 -354.263198)
		(width 0.14224)
		(layer "In4.Cu")
		(net "P5E_CPU1_P3_RX_DN<1>")
	)
	(segment
		(start 117.72265 -305.960272)
		(end 116.051838 -303.459388)
		(width 0.14224)
		(layer "In4.Cu")
		(net "P5E_CPU1_P3_RX_DN<1>")
	)
	(segment
		(start 124.350526 -359.086658)
		(end 131.569206 -354.263452)
		(width 0.14224)
		(layer "In4.Cu")
		(net "P5E_CPU1_P3_RX_DN<1>")
	)
	(segment
		(start 113.945924 -378.453904)
		(end 113.751868 -378.453904)
		(width 0.14224)
		(layer "In4.Cu")
		(net "P5E_CPU1_P3_RX_DN<1>")
	)
	(segment
		(start 114.645694 -292.208712)
		(end 114.647726 -292.207442)
		(width 0.1143)
		(layer "In4.Cu")
		(net "P5E_CPU1_P3_RX_DN<1>")
	)
	(segment
		(start 132.989574 -351.21596)
		(end 133.095746 -349.729806)
		(width 0.14224)
		(layer "In4.Cu")
		(net "P5E_CPU1_P3_RX_DN<1>")
	)
	(segment
		(start 129.890774 -325.25208)
		(end 129.89052 -325.251572)
		(width 0.14224)
		(layer "In4.Cu")
		(net "P5E_CPU1_P3_RX_DN<1>")
	)
	(segment
		(start 116.558568 -383.460752)
		(end 116.558568 -382.643126)
		(width 0.14224)
		(layer "In4.Cu")
		(net "P5E_CPU1_P3_RX_DN<1>")
	)
	(segment
		(start 114.604546 -295.47312)
		(end 114.605308 -295.472612)
		(width 0.1143)
		(layer "In4.Cu")
		(net "P5E_CPU1_P3_RX_DN<1>")
	)
	(segment
		(start 114.611658 -293.84879)
		(end 114.643408 -293.830502)
		(width 0.1143)
		(layer "In4.Cu")
		(net "P5E_CPU1_P3_RX_DN<1>")
	)
	(segment
		(start 116.091208 -385.31038)
		(end 116.444522 -385.405376)
		(width 0.14224)
		(layer "In4.Cu")
		(net "P5E_CPU1_P3_RX_DN<1>")
	)
	(segment
		(start 108.908088 -370.843556)
		(end 110.993174 -367.722912)
		(width 0.14224)
		(layer "In4.Cu")
		(net "P5E_CPU1_P3_RX_DN<1>")
	)
	(segment
		(start 114.614452 -295.467278)
		(end 114.615722 -295.466516)
		(width 0.1143)
		(layer "In4.Cu")
		(net "P5E_CPU1_P3_RX_DN<1>")
	)
	(segment
		(start 116.501164 -382.06172)
		(end 116.344446 -381.27432)
		(width 0.14224)
		(layer "In4.Cu")
		(net "P5E_CPU1_P3_RX_DN<1>")
	)
	(segment
		(start 114.643408 -293.221918)
		(end 114.61369 -293.2049)
		(width 0.1143)
		(layer "In4.Cu")
		(net "P5E_CPU1_P3_RX_DN<1>")
	)
	(segment
		(start 126.22911 -316.324742)
		(end 117.72265 -305.960272)
		(width 0.14224)
		(layer "In4.Cu")
		(net "P5E_CPU1_P3_RX_DN<1>")
	)
	(segment
		(start 114.325146 -289.481514)
		(end 114.325146 -289.481006)
		(width 0.1143)
		(layer "In4.Cu")
		(net "P5E_CPU1_P3_RX_DN<1>")
	)
	(segment
		(start 127.83566 -319.332864)
		(end 126.22911 -316.324742)
		(width 0.14224)
		(layer "In4.Cu")
		(net "P5E_CPU1_P3_RX_DN<1>")
	)
	(segment
		(start 114.643408 -292.209982)
		(end 114.645694 -292.208712)
		(width 0.1143)
		(layer "In4.Cu")
		(net "P5E_CPU1_P3_RX_DN<1>")
	)
	(segment
		(start 116.444522 -385.405376)
		(end 116.44503 -385.404868)
		(width 0.14224)
		(layer "In4.Cu")
		(net "P5E_CPU1_P3_RX_DN<1>")
	)
	(segment
		(start 114.643408 -295.450514)
		(end 114.647726 -295.447466)
		(width 0.1143)
		(layer "In4.Cu")
		(net "P5E_CPU1_P3_RX_DN<1>")
	)
	(segment
		(start 114.611658 -292.228778)
		(end 114.643408 -292.209982)
		(width 0.1143)
		(layer "In4.Cu")
		(net "P5E_CPU1_P3_RX_DN<1>")
	)
	(segment
		(start 114.647726 -294.844978)
		(end 114.643408 -294.84193)
		(width 0.1143)
		(layer "In4.Cu")
		(net "P5E_CPU1_P3_RX_DN<1>")
	)
	(segment
		(start 112.652302 -377.354338)
		(end 112.652302 -377.160536)
		(width 0.14224)
		(layer "In4.Cu")
		(net "P5E_CPU1_P3_RX_DN<1>")
	)
	(segment
		(start 114.283744 -296.358564)
		(end 114.283744 -296.330116)
		(width 0.1143)
		(layer "In4.Cu")
		(net "P5E_CPU1_P3_RX_DN<1>")
	)
	(segment
		(start 114.609118 -295.470326)
		(end 114.610642 -295.46931)
		(width 0.1143)
		(layer "In4.Cu")
		(net "P5E_CPU1_P3_RX_DN<1>")
	)
	(segment
		(start 114.792506 -288.736024)
		(end 114.722656 -288.666174)
		(width 0.1143)
		(layer "In4.Cu")
		(net "P5E_CPU1_P3_RX_DN<1>")
	)
	(segment
		(start 113.148364 -377.656344)
		(end 112.954308 -377.656344)
		(width 0.14224)
		(layer "In4.Cu")
		(net "P5E_CPU1_P3_RX_DN<1>")
	)
	(segment
		(start 114.327686 -291.069776)
		(end 114.325654 -291.069776)
		(width 0.1143)
		(layer "In4.Cu")
		(net "P5E_CPU1_P3_RX_DN<1>")
	)
	(segment
		(start 114.60988 -291.582602)
		(end 114.57559 -291.562536)
		(width 0.1143)
		(layer "In4.Cu")
		(net "P5E_CPU1_P3_RX_DN<1>")
	)
	(segment
		(start 133.100318 -337.589368)
		(end 131.948936 -331.180694)
		(width 0.14224)
		(layer "In4.Cu")
		(net "P5E_CPU1_P3_RX_DN<1>")
	)
	(segment
		(start 114.743484 -379.251718)
		(end 114.549428 -379.251718)
		(width 0.14224)
		(layer "In4.Cu")
		(net "P5E_CPU1_P3_RX_DN<1>")
	)
	(segment
		(start 114.647726 -291.604954)
		(end 114.643408 -291.601906)
		(width 0.1143)
		(layer "In4.Cu")
		(net "P5E_CPU1_P3_RX_DN<1>")
	)
	(segment
		(start 133.100318 -349.603314)
		(end 133.100318 -337.589368)
		(width 0.14224)
		(layer "In4.Cu")
		(net "P5E_CPU1_P3_RX_DN<1>")
	)
	(segment
		(start 114.611658 -293.20363)
		(end 114.610642 -293.203122)
		(width 0.1143)
		(layer "In4.Cu")
		(net "P5E_CPU1_P3_RX_DN<1>")
	)
	(segment
		(start 114.330226 -291.11575)
		(end 114.330226 -291.106098)
		(width 0.1143)
		(layer "In4.Cu")
		(net "P5E_CPU1_P3_RX_DN<1>")
	)
	(segment
		(start 112.954308 -377.656344)
		(end 112.652302 -377.354338)
		(width 0.14224)
		(layer "In4.Cu")
		(net "P5E_CPU1_P3_RX_DN<1>")
	)
	(segment
		(start 114.722656 -288.666174)
		(end 114.424714 -288.666174)
		(width 0.1143)
		(layer "In4.Cu")
		(net "P5E_CPU1_P3_RX_DN<1>")
	)
	(segment
		(start 114.610642 -292.229286)
		(end 114.611658 -292.228778)
		(width 0.1143)
		(layer "In4.Cu")
		(net "P5E_CPU1_P3_RX_DN<1>")
	)
	(segment
		(start 114.332258 -291.129974)
		(end 114.330226 -291.11575)
		(width 0.1143)
		(layer "In4.Cu")
		(net "P5E_CPU1_P3_RX_DN<1>")
	)
	(segment
		(start 114.60861 -288.990532)
		(end 114.611658 -288.988754)
		(width 0.1143)
		(layer "In4.Cu")
		(net "P5E_CPU1_P3_RX_DN<1>")
	)
	(segment
		(start 114.61242 -293.204138)
		(end 114.611658 -293.20363)
		(width 0.1143)
		(layer "In4.Cu")
		(net "P5E_CPU1_P3_RX_DN<1>")
	)
	(segment
		(start 116.051838 -303.459388)
		(end 114.357658 -299.369226)
		(width 0.14224)
		(layer "In4.Cu")
		(net "P5E_CPU1_P3_RX_DN<1>")
	)
	(segment
		(start 114.575336 -293.869872)
		(end 114.611658 -293.84879)
		(width 0.1143)
		(layer "In4.Cu")
		(net "P5E_CPU1_P3_RX_DN<1>")
	)
	(segment
		(start 114.601752 -288.99485)
		(end 114.60861 -288.990532)
		(width 0.1143)
		(layer "In4.Cu")
		(net "P5E_CPU1_P3_RX_DN<1>")
	)
	(segment
		(start 114.60734 -295.471342)
		(end 114.609118 -295.470326)
		(width 0.1143)
		(layer "In4.Cu")
		(net "P5E_CPU1_P3_RX_DN<1>")
	)
	(segment
		(start 129.89052 -325.251572)
		(end 127.83566 -319.332864)
		(width 0.14224)
		(layer "In4.Cu")
		(net "P5E_CPU1_P3_RX_DN<1>")
	)
	(segment
		(start 116.566696 -385.334764)
		(end 116.566696 -385.163822)
		(width 0.14224)
		(layer "In4.Cu")
		(net "P5E_CPU1_P3_RX_DN<1>")
	)
	(segment
		(start 113.449862 -378.151898)
		(end 113.449862 -377.958096)
		(width 0.14224)
		(layer "In4.Cu")
		(net "P5E_CPU1_P3_RX_DN<1>")
	)
	(segment
		(start 113.449862 -377.958096)
		(end 113.148364 -377.656344)
		(width 0.14224)
		(layer "In4.Cu")
		(net "P5E_CPU1_P3_RX_DN<1>")
	)
	(segment
		(start 116.249704 -384.84683)
		(end 116.25834 -383.760726)
		(width 0.14224)
		(layer "In4.Cu")
		(net "P5E_CPU1_P3_RX_DN<1>")
	)
	(segment
		(start 114.609118 -292.230302)
		(end 114.610642 -292.229286)
		(width 0.1143)
		(layer "In4.Cu")
		(net "P5E_CPU1_P3_RX_DN<1>")
	)
	(segment
		(start 131.569206 -354.263452)
		(end 131.568952 -354.263452)
		(width 0.14224)
		(layer "In4.Cu")
		(net "P5E_CPU1_P3_RX_DN<1>")
	)
	(segment
		(start 114.61369 -293.2049)
		(end 114.61242 -293.204138)
		(width 0.1143)
		(layer "In4.Cu")
		(net "P5E_CPU1_P3_RX_DN<1>")
	)
	(segment
		(start 114.330226 -291.106098)
		(end 114.327686 -291.069776)
		(width 0.1143)
		(layer "In4.Cu")
		(net "P5E_CPU1_P3_RX_DN<1>")
	)
	(segment
		(start 114.283744 -298.997624)
		(end 114.283744 -296.358564)
		(width 0.14224)
		(layer "In4.Cu")
		(net "P5E_CPU1_P3_RX_DN<1>")
	)
	(segment
		(start 114.611658 -288.988754)
		(end 114.643408 -288.970466)
		(width 0.1143)
		(layer "In4.Cu")
		(net "P5E_CPU1_P3_RX_DN<1>")
	)
	(segment
		(start 114.283744 -296.330116)
		(end 114.329464 -296.284396)
		(width 0.1143)
		(layer "In4.Cu")
		(net "P5E_CPU1_P3_RX_DN<1>")
	)
	(segment
		(start 114.613436 -295.467786)
		(end 114.614452 -295.467278)
		(width 0.1143)
		(layer "In4.Cu")
		(net "P5E_CPU1_P3_RX_DN<1>")
	)
	(segment
		(start 114.61242 -294.82415)
		(end 114.611658 -294.823642)
		(width 0.1143)
		(layer "In4.Cu")
		(net "P5E_CPU1_P3_RX_DN<1>")
	)
	(segment
		(start 114.610642 -293.203122)
		(end 114.572542 -293.18077)
		(width 0.1143)
		(layer "In4.Cu")
		(net "P5E_CPU1_P3_RX_DN<1>")
	)
	(segment
		(start 131.948936 -331.180694)
		(end 129.890774 -325.25208)
		(width 0.14224)
		(layer "In4.Cu")
		(net "P5E_CPU1_P3_RX_DN<1>")
	)
	(segment
		(start 114.549428 -379.251718)
		(end 114.247422 -378.949712)
		(width 0.14224)
		(layer "In4.Cu")
		(net "P5E_CPU1_P3_RX_DN<1>")
	)
	(segment
		(start 114.247422 -378.949712)
		(end 114.247422 -378.755656)
		(width 0.14224)
		(layer "In4.Cu")
		(net "P5E_CPU1_P3_RX_DN<1>")
	)
	(segment
		(start 114.611658 -294.823642)
		(end 114.575336 -294.80256)
		(width 0.1143)
		(layer "In4.Cu")
		(net "P5E_CPU1_P3_RX_DN<1>")
	)
	(segment
		(start 116.25834 -383.760726)
		(end 116.558568 -383.460752)
		(width 0.14224)
		(layer "In4.Cu")
		(net "P5E_CPU1_P3_RX_DN<1>")
	)
	(segment
		(start 114.615722 -295.466516)
		(end 114.616484 -295.466008)
		(width 0.1143)
		(layer "In4.Cu")
		(net "P5E_CPU1_P3_RX_DN<1>")
	)
	(segment
		(start 114.142266 -290.773866)
		(end 114.103404 -290.75126)
		(width 0.1143)
		(layer "In4.Cu")
		(net "P5E_CPU1_P3_RX_DN<1>")
	)
	(segment
		(start 114.572542 -292.251638)
		(end 114.609118 -292.230302)
		(width 0.1143)
		(layer "In4.Cu")
		(net "P5E_CPU1_P3_RX_DN<1>")
	)
	(segment
		(start 114.572542 -295.491662)
		(end 114.604546 -295.47312)
		(width 0.1143)
		(layer "In4.Cu")
		(net "P5E_CPU1_P3_RX_DN<1>")
	)
	(segment
		(start 116.566696 -385.163822)
		(end 116.249704 -384.84683)
		(width 0.14224)
		(layer "In4.Cu")
		(net "P5E_CPU1_P3_RX_DN<1>")
	)
	(segment
		(start 114.611658 -295.468802)
		(end 114.613436 -295.467786)
		(width 0.1143)
		(layer "In4.Cu")
		(net "P5E_CPU1_P3_RX_DN<1>")
	)
	(segment
		(start 114.605308 -295.472612)
		(end 114.60734 -295.471342)
		(width 0.1143)
		(layer "In4.Cu")
		(net "P5E_CPU1_P3_RX_DN<1>")
	)
	(arc
		(start 114.357658 -299.369226)
		(mid 114.302429 -299.187061)
		(end 114.283744 -298.997624)
		(width 0.14224)
		(layer "In4.Cu")
		(net "P5E_CPU1_P3_RX_DN<1>")
	)
	(arc
		(start 114.647726 -295.447466)
		(mid 114.802131 -295.146222)
		(end 114.647726 -294.844978)
		(width 0.1143)
		(layer "In4.Cu")
		(net "P5E_CPU1_P3_RX_DN<1>")
	)
	(arc
		(start 131.661154 -354.176076)
		(mid 132.460092 -352.825255)
		(end 132.970524 -351.341182)
		(width 0.14224)
		(layer "In4.Cu")
		(net "P5E_CPU1_P3_RX_DN<1>")
	)
	(arc
		(start 109.598714 -374.10644)
		(mid 109.538593 -374.043334)
		(end 109.481874 -373.977154)
		(width 0.14224)
		(layer "In4.Cu")
		(net "P5E_CPU1_P3_RX_DN<1>")
	)
	(arc
		(start 114.643408 -293.830502)
		(mid 114.799336 -293.52621)
		(end 114.643408 -293.221918)
		(width 0.1143)
		(layer "In4.Cu")
		(net "P5E_CPU1_P3_RX_DN<1>")
	)
	(arc
		(start 114.103404 -290.75126)
		(mid 114.103023 -290.751006)
		(end 114.102642 -290.750752)
		(width 0.1143)
		(layer "In4.Cu")
		(net "P5E_CPU1_P3_RX_DN<1>")
	)
	(arc
		(start 116.344446 -381.27432)
		(mid 116.169565 -380.785527)
		(end 115.860322 -380.368556)
		(width 0.14224)
		(layer "In4.Cu")
		(net "P5E_CPU1_P3_RX_DN<1>")
	)
	(arc
		(start 114.325654 -291.069776)
		(mid 114.323799 -291.049516)
		(end 114.320828 -291.02939)
		(width 0.1143)
		(layer "In4.Cu")
		(net "P5E_CPU1_P3_RX_DN<1>")
	)
	(arc
		(start 114.145822 -289.796474)
		(mid 114.277177 -289.662719)
		(end 114.325146 -289.481514)
		(width 0.1143)
		(layer "In4.Cu")
		(net "P5E_CPU1_P3_RX_DN<1>")
	)
	(arc
		(start 114.647726 -292.207442)
		(mid 114.802131 -291.906198)
		(end 114.647726 -291.604954)
		(width 0.1143)
		(layer "In4.Cu")
		(net "P5E_CPU1_P3_RX_DN<1>")
	)
	(arc
		(start 114.320828 -291.02939)
		(mid 114.259768 -290.881903)
		(end 114.142266 -290.773866)
		(width 0.1143)
		(layer "In4.Cu")
		(net "P5E_CPU1_P3_RX_DN<1>")
	)
	(arc
		(start 109.481874 -373.977154)
		(mid 108.938627 -373.108665)
		(end 108.619798 -372.135146)
		(width 0.14224)
		(layer "In4.Cu")
		(net "P5E_CPU1_P3_RX_DN<1>")
	)
	(arc
		(start 114.572542 -293.18077)
		(mid 114.329215 -292.716204)
		(end 114.572542 -292.251638)
		(width 0.1143)
		(layer "In4.Cu")
		(net "P5E_CPU1_P3_RX_DN<1>")
	)
	(arc
		(start 114.57559 -291.562536)
		(mid 114.56145 -291.551961)
		(end 114.54765 -291.540946)
		(width 0.1143)
		(layer "In4.Cu")
		(net "P5E_CPU1_P3_RX_DN<1>")
	)
	(arc
		(start 108.59897 -371.970046)
		(mid 108.662209 -371.381736)
		(end 108.908088 -370.843556)
		(width 0.14224)
		(layer "In4.Cu")
		(net "P5E_CPU1_P3_RX_DN<1>")
	)
	(arc
		(start 114.575336 -294.80256)
		(mid 114.567158 -294.796917)
		(end 114.55908 -294.79113)
		(width 0.1143)
		(layer "In4.Cu")
		(net "P5E_CPU1_P3_RX_DN<1>")
	)
	(arc
		(start 132.970524 -351.341182)
		(mid 132.982527 -351.278948)
		(end 132.989574 -351.21596)
		(width 0.14224)
		(layer "In4.Cu")
		(net "P5E_CPU1_P3_RX_DN<1>")
	)
	(arc
		(start 110.993174 -367.722912)
		(mid 112.356862 -366.218391)
		(end 114.098578 -365.17453)
		(width 0.14224)
		(layer "In4.Cu")
		(net "P5E_CPU1_P3_RX_DN<1>")
	)
	(arc
		(start 133.095746 -349.729806)
		(mid 133.099162 -349.666601)
		(end 133.100318 -349.603314)
		(width 0.14224)
		(layer "In4.Cu")
		(net "P5E_CPU1_P3_RX_DN<1>")
	)
	(arc
		(start 114.54765 -291.540946)
		(mid 114.405459 -291.353532)
		(end 114.332258 -291.129974)
		(width 0.1143)
		(layer "In4.Cu")
		(net "P5E_CPU1_P3_RX_DN<1>")
	)
	(arc
		(start 114.55908 -293.881302)
		(mid 114.567158 -293.875516)
		(end 114.575336 -293.869872)
		(width 0.1143)
		(layer "In4.Cu")
		(net "P5E_CPU1_P3_RX_DN<1>")
	)
	(arc
		(start 114.094768 -290.745164)
		(mid 113.859579 -290.280901)
		(end 114.103404 -289.821112)
		(width 0.1143)
		(layer "In4.Cu")
		(net "P5E_CPU1_P3_RX_DN<1>")
	)
	(arc
		(start 117.068854 -363.944154)
		(mid 117.100915 -363.928917)
		(end 117.131338 -363.910626)
		(width 0.14224)
		(layer "In4.Cu")
		(net "P5E_CPU1_P3_RX_DN<1>")
	)
	(arc
		(start 114.102642 -290.750752)
		(mid 114.098693 -290.747975)
		(end 114.094768 -290.745164)
		(width 0.1143)
		(layer "In4.Cu")
		(net "P5E_CPU1_P3_RX_DN<1>")
	)
	(arc
		(start 108.619798 -372.135146)
		(mid 108.606466 -372.052964)
		(end 108.59897 -371.970046)
		(width 0.14224)
		(layer "In4.Cu")
		(net "P5E_CPU1_P3_RX_DN<1>")
	)
	(arc
		(start 114.325146 -289.481006)
		(mid 114.399128 -289.201322)
		(end 114.601752 -288.99485)
		(width 0.1143)
		(layer "In4.Cu")
		(net "P5E_CPU1_P3_RX_DN<1>")
	)
	(arc
		(start 116.558568 -382.643126)
		(mid 116.544152 -382.351013)
		(end 116.501164 -382.06172)
		(width 0.14224)
		(layer "In4.Cu")
		(net "P5E_CPU1_P3_RX_DN<1>")
	)
	(arc
		(start 114.438684 -295.62171)
		(mid 114.500203 -295.551116)
		(end 114.572542 -295.491662)
		(width 0.1143)
		(layer "In4.Cu")
		(net "P5E_CPU1_P3_RX_DN<1>")
	)
	(arc
		(start 114.329464 -295.956228)
		(mid 114.35738 -295.780252)
		(end 114.438684 -295.62171)
		(width 0.1143)
		(layer "In4.Cu")
		(net "P5E_CPU1_P3_RX_DN<1>")
	)
	(arc
		(start 114.55908 -294.79113)
		(mid 114.336196 -294.336216)
		(end 114.55908 -293.881302)
		(width 0.1143)
		(layer "In4.Cu")
		(net "P5E_CPU1_P3_RX_DN<1>")
	)
	(arc
		(start 131.56946 -354.263198)
		(mid 131.619101 -354.223492)
		(end 131.661154 -354.175822)
		(width 0.14224)
		(layer "In4.Cu")
		(net "P5E_CPU1_P3_RX_DN<1>")
	)
	(arc
		(start 114.643408 -288.970466)
		(mid 114.740543 -288.867597)
		(end 114.792506 -288.736024)
		(width 0.1143)
		(layer "In4.Cu")
		(net "P5E_CPU1_P3_RX_DN<1>")
	)
	(segment
		(start 124.767848 -285.970472)
		(end 125.2347 -286.23641)
		(width 0.12954)
		(layer "F.Cu")
		(net "P5E_CPU1_P3_RX_DN<15>")
	)
	(segment
		(start 132.370576 -385.31038)
		(end 132.891276 -385.31038)
		(width 0.127)
		(layer "F.Cu")
		(net "P5E_CPU1_P3_RX_DN<15>")
	)
	(segment
		(start 127.73279 -292.251638)
		(end 127.771906 -292.228778)
		(width 0.1143)
		(layer "In4.Cu")
		(net "P5E_CPU1_P3_RX_DN<15>")
	)
	(segment
		(start 140.284454 -314.00115)
		(end 138.160506 -310.154828)
		(width 0.14224)
		(layer "In4.Cu")
		(net "P5E_CPU1_P3_RX_DN<15>")
	)
	(segment
		(start 146.676618 -358.983788)
		(end 146.676618 -337.992466)
		(width 0.14224)
		(layer "In4.Cu")
		(net "P5E_CPU1_P3_RX_DN<15>")
	)
	(segment
		(start 133.245098 -385.404868)
		(end 133.24586 -385.40436)
		(width 0.14224)
		(layer "In4.Cu")
		(net "P5E_CPU1_P3_RX_DN<15>")
	)
	(segment
		(start 144.800828 -327.551034)
		(end 140.284454 -314.00115)
		(width 0.14224)
		(layer "In4.Cu")
		(net "P5E_CPU1_P3_RX_DN<15>")
	)
	(segment
		(start 146.243294 -335.582514)
		(end 146.243294 -335.58099)
		(width 0.14224)
		(layer "In4.Cu")
		(net "P5E_CPU1_P3_RX_DN<15>")
	)
	(segment
		(start 135.707374 -380.383288)
		(end 135.599678 -380.221998)
		(width 0.14224)
		(layer "In4.Cu")
		(net "P5E_CPU1_P3_RX_DN<15>")
	)
	(segment
		(start 127.93472 -297.315128)
		(end 127.747014 -297.127422)
		(width 0.14224)
		(layer "In4.Cu")
		(net "P5E_CPU1_P3_RX_DN<15>")
	)
	(segment
		(start 135.844534 -379.695456)
		(end 135.927592 -379.277118)
		(width 0.14224)
		(layer "In4.Cu")
		(net "P5E_CPU1_P3_RX_DN<15>")
	)
	(segment
		(start 127.300736 -290.773104)
		(end 127.299212 -290.772088)
		(width 0.1143)
		(layer "In4.Cu")
		(net "P5E_CPU1_P3_RX_DN<15>")
	)
	(segment
		(start 126.831852 -288.343848)
		(end 126.792736 -288.320988)
		(width 0.1143)
		(layer "In4.Cu")
		(net "P5E_CPU1_P3_RX_DN<15>")
	)
	(segment
		(start 127.301752 -290.773612)
		(end 127.300736 -290.773104)
		(width 0.1143)
		(layer "In4.Cu")
		(net "P5E_CPU1_P3_RX_DN<15>")
	)
	(segment
		(start 129.29235 -299.346366)
		(end 127.93472 -297.315128)
		(width 0.14224)
		(layer "In4.Cu")
		(net "P5E_CPU1_P3_RX_DN<15>")
	)
	(segment
		(start 133.24459 -385.405376)
		(end 133.245098 -385.404868)
		(width 0.14224)
		(layer "In4.Cu")
		(net "P5E_CPU1_P3_RX_DN<15>")
	)
	(segment
		(start 127.30607 -290.776152)
		(end 127.305308 -290.775644)
		(width 0.1143)
		(layer "In4.Cu")
		(net "P5E_CPU1_P3_RX_DN<15>")
	)
	(segment
		(start 127.672846 -296.538396)
		(end 127.672846 -296.456354)
		(width 0.1143)
		(layer "In4.Cu")
		(net "P5E_CPU1_P3_RX_DN<15>")
	)
	(segment
		(start 127.635254 -296.366184)
		(end 127.580898 -296.311828)
		(width 0.1143)
		(layer "In4.Cu")
		(net "P5E_CPU1_P3_RX_DN<15>")
	)
	(segment
		(start 126.361698 -287.533842)
		(end 126.361444 -287.533842)
		(width 0.1143)
		(layer "In4.Cu")
		(net "P5E_CPU1_P3_RX_DN<15>")
	)
	(segment
		(start 125.532642 -286.23641)
		(end 125.2347 -286.23641)
		(width 0.1143)
		(layer "In4.Cu")
		(net "P5E_CPU1_P3_RX_DN<15>")
	)
	(segment
		(start 127.627888 -295.586912)
		(end 127.794766 -295.45661)
		(width 0.1143)
		(layer "In4.Cu")
		(net "P5E_CPU1_P3_RX_DN<15>")
	)
	(segment
		(start 127.626618 -295.588182)
		(end 127.627888 -295.586912)
		(width 0.1143)
		(layer "In4.Cu")
		(net "P5E_CPU1_P3_RX_DN<15>")
	)
	(segment
		(start 127.303784 -290.774882)
		(end 127.302514 -290.77412)
		(width 0.1143)
		(layer "In4.Cu")
		(net "P5E_CPU1_P3_RX_DN<15>")
	)
	(segment
		(start 135.308086 -382.390904)
		(end 135.48741 -381.489458)
		(width 0.14224)
		(layer "In4.Cu")
		(net "P5E_CPU1_P3_RX_DN<15>")
	)
	(segment
		(start 132.891276 -385.31038)
		(end 133.24459 -385.405376)
		(width 0.14224)
		(layer "In4.Cu")
		(net "P5E_CPU1_P3_RX_DN<15>")
	)
	(segment
		(start 127.771906 -292.228778)
		(end 127.802386 -292.210998)
		(width 0.1143)
		(layer "In4.Cu")
		(net "P5E_CPU1_P3_RX_DN<15>")
	)
	(segment
		(start 127.305308 -290.775644)
		(end 127.303784 -290.774882)
		(width 0.1143)
		(layer "In4.Cu")
		(net "P5E_CPU1_P3_RX_DN<15>")
	)
	(segment
		(start 135.462772 -380.909322)
		(end 135.624316 -380.801626)
		(width 0.14224)
		(layer "In4.Cu")
		(net "P5E_CPU1_P3_RX_DN<15>")
	)
	(segment
		(start 127.295148 -290.769802)
		(end 127.293624 -290.768786)
		(width 0.1143)
		(layer "In4.Cu")
		(net "P5E_CPU1_P3_RX_DN<15>")
	)
	(segment
		(start 127.771906 -293.84879)
		(end 127.802386 -293.83101)
		(width 0.1143)
		(layer "In4.Cu")
		(net "P5E_CPU1_P3_RX_DN<15>")
	)
	(segment
		(start 126.831852 -288.988754)
		(end 126.862332 -288.970974)
		(width 0.1143)
		(layer "In4.Cu")
		(net "P5E_CPU1_P3_RX_DN<15>")
	)
	(segment
		(start 127.73279 -293.87165)
		(end 127.771906 -293.84879)
		(width 0.1143)
		(layer "In4.Cu")
		(net "P5E_CPU1_P3_RX_DN<15>")
	)
	(segment
		(start 133.366764 -385.334764)
		(end 133.366764 -384.735578)
		(width 0.14224)
		(layer "In4.Cu")
		(net "P5E_CPU1_P3_RX_DN<15>")
	)
	(segment
		(start 127.293624 -290.768786)
		(end 127.262636 -290.750752)
		(width 0.1143)
		(layer "In4.Cu")
		(net "P5E_CPU1_P3_RX_DN<15>")
	)
	(segment
		(start 136.964166 -375.270014)
		(end 140.502386 -371.731794)
		(width 0.14224)
		(layer "In4.Cu")
		(net "P5E_CPU1_P3_RX_DN<15>")
	)
	(segment
		(start 127.302514 -290.77412)
		(end 127.301752 -290.773612)
		(width 0.1143)
		(layer "In4.Cu")
		(net "P5E_CPU1_P3_RX_DN<15>")
	)
	(segment
		(start 126.862332 -289.981386)
		(end 126.831852 -289.963606)
		(width 0.1143)
		(layer "In4.Cu")
		(net "P5E_CPU1_P3_RX_DN<15>")
	)
	(segment
		(start 126.864364 -288.362644)
		(end 126.831852 -288.343848)
		(width 0.1143)
		(layer "In4.Cu")
		(net "P5E_CPU1_P3_RX_DN<15>")
	)
	(segment
		(start 127.771906 -293.20363)
		(end 127.73279 -293.18077)
		(width 0.1143)
		(layer "In4.Cu")
		(net "P5E_CPU1_P3_RX_DN<15>")
	)
	(segment
		(start 127.30861 -290.777676)
		(end 127.30607 -290.776152)
		(width 0.1143)
		(layer "In4.Cu")
		(net "P5E_CPU1_P3_RX_DN<15>")
	)
	(segment
		(start 129.29997 -299.357796)
		(end 129.292096 -299.346366)
		(width 0.14224)
		(layer "In4.Cu")
		(net "P5E_CPU1_P3_RX_DN<15>")
	)
	(segment
		(start 140.975334 -368.924332)
		(end 144.777206 -364.29188)
		(width 0.14224)
		(layer "In4.Cu")
		(net "P5E_CPU1_P3_RX_DN<15>")
	)
	(segment
		(start 127.771906 -291.583618)
		(end 127.73279 -291.560758)
		(width 0.1143)
		(layer "In4.Cu")
		(net "P5E_CPU1_P3_RX_DN<15>")
	)
	(segment
		(start 135.68299 -379.803152)
		(end 135.844534 -379.695456)
		(width 0.14224)
		(layer "In4.Cu")
		(net "P5E_CPU1_P3_RX_DN<15>")
	)
	(segment
		(start 125.615446 -286.319214)
		(end 125.532642 -286.23641)
		(width 0.1143)
		(layer "In4.Cu")
		(net "P5E_CPU1_P3_RX_DN<15>")
	)
	(segment
		(start 127.333502 -290.7919)
		(end 127.30861 -290.777676)
		(width 0.1143)
		(layer "In4.Cu")
		(net "P5E_CPU1_P3_RX_DN<15>")
	)
	(segment
		(start 136.064752 -378.589286)
		(end 136.582912 -375.983246)
		(width 0.14224)
		(layer "In4.Cu")
		(net "P5E_CPU1_P3_RX_DN<15>")
	)
	(segment
		(start 135.819896 -379.115828)
		(end 135.903208 -378.696982)
		(width 0.14224)
		(layer "In4.Cu")
		(net "P5E_CPU1_P3_RX_DN<15>")
	)
	(segment
		(start 129.292096 -299.346366)
		(end 129.29235 -299.346366)
		(width 0.14224)
		(layer "In4.Cu")
		(net "P5E_CPU1_P3_RX_DN<15>")
	)
	(segment
		(start 133.366764 -384.735578)
		(end 134.84479 -383.257552)
		(width 0.14224)
		(layer "In4.Cu")
		(net "P5E_CPU1_P3_RX_DN<15>")
	)
	(segment
		(start 127.627126 -296.612564)
		(end 127.627126 -296.584116)
		(width 0.1143)
		(layer "In4.Cu")
		(net "P5E_CPU1_P3_RX_DN<15>")
	)
	(segment
		(start 146.676618 -337.992466)
		(end 146.243294 -335.582514)
		(width 0.14224)
		(layer "In4.Cu")
		(net "P5E_CPU1_P3_RX_DN<15>")
	)
	(segment
		(start 127.299212 -290.772088)
		(end 127.295148 -290.769802)
		(width 0.1143)
		(layer "In4.Cu")
		(net "P5E_CPU1_P3_RX_DN<15>")
	)
	(segment
		(start 127.627126 -296.584116)
		(end 127.672846 -296.538396)
		(width 0.1143)
		(layer "In4.Cu")
		(net "P5E_CPU1_P3_RX_DN<15>")
	)
	(segment
		(start 138.160506 -310.154828)
		(end 129.29997 -299.357796)
		(width 0.14224)
		(layer "In4.Cu")
		(net "P5E_CPU1_P3_RX_DN<15>")
	)
	(segment
		(start 135.624316 -380.801626)
		(end 135.707374 -380.383288)
		(width 0.14224)
		(layer "In4.Cu")
		(net "P5E_CPU1_P3_RX_DN<15>")
	)
	(segment
		(start 127.794766 -295.45661)
		(end 127.796798 -295.455086)
		(width 0.1143)
		(layer "In4.Cu")
		(net "P5E_CPU1_P3_RX_DN<15>")
	)
	(segment
		(start 127.802386 -293.22141)
		(end 127.771906 -293.20363)
		(width 0.1143)
		(layer "In4.Cu")
		(net "P5E_CPU1_P3_RX_DN<15>")
	)
	(segment
		(start 127.80137 -294.840914)
		(end 127.73279 -294.800782)
		(width 0.1143)
		(layer "In4.Cu")
		(net "P5E_CPU1_P3_RX_DN<15>")
	)
	(segment
		(start 126.831852 -289.963606)
		(end 126.792736 -289.940746)
		(width 0.1143)
		(layer "In4.Cu")
		(net "P5E_CPU1_P3_RX_DN<15>")
	)
	(segment
		(start 135.599678 -380.221998)
		(end 135.68299 -379.803152)
		(width 0.14224)
		(layer "In4.Cu")
		(net "P5E_CPU1_P3_RX_DN<15>")
	)
	(segment
		(start 125.898656 -286.7279)
		(end 125.852682 -286.700976)
		(width 0.1143)
		(layer "In4.Cu")
		(net "P5E_CPU1_P3_RX_DN<15>")
	)
	(segment
		(start 127.48768 -296.087038)
		(end 127.48768 -295.923716)
		(width 0.1143)
		(layer "In4.Cu")
		(net "P5E_CPU1_P3_RX_DN<15>")
	)
	(segment
		(start 126.792736 -289.011614)
		(end 126.831852 -288.988754)
		(width 0.1143)
		(layer "In4.Cu")
		(net "P5E_CPU1_P3_RX_DN<15>")
	)
	(segment
		(start 135.903208 -378.696982)
		(end 136.064752 -378.589286)
		(width 0.14224)
		(layer "In4.Cu")
		(net "P5E_CPU1_P3_RX_DN<15>")
	)
	(segment
		(start 135.379714 -381.328168)
		(end 135.462772 -380.909322)
		(width 0.14224)
		(layer "In4.Cu")
		(net "P5E_CPU1_P3_RX_DN<15>")
	)
	(segment
		(start 146.243294 -335.58099)
		(end 144.800828 -327.551034)
		(width 0.14224)
		(layer "In4.Cu")
		(net "P5E_CPU1_P3_RX_DN<15>")
	)
	(segment
		(start 140.849858 -370.893086)
		(end 140.849858 -369.275868)
		(width 0.14224)
		(layer "In4.Cu")
		(net "P5E_CPU1_P3_RX_DN<15>")
	)
	(segment
		(start 133.24586 -385.40436)
		(end 133.366764 -385.334764)
		(width 0.14224)
		(layer "In4.Cu")
		(net "P5E_CPU1_P3_RX_DN<15>")
	)
	(segment
		(start 127.802386 -291.601398)
		(end 127.771906 -291.583618)
		(width 0.1143)
		(layer "In4.Cu")
		(net "P5E_CPU1_P3_RX_DN<15>")
	)
	(segment
		(start 135.48741 -381.489458)
		(end 135.379714 -381.328168)
		(width 0.14224)
		(layer "In4.Cu")
		(net "P5E_CPU1_P3_RX_DN<15>")
	)
	(segment
		(start 126.393448 -287.55213)
		(end 126.361698 -287.533842)
		(width 0.1143)
		(layer "In4.Cu")
		(net "P5E_CPU1_P3_RX_DN<15>")
	)
	(segment
		(start 127.627126 -296.837862)
		(end 127.627126 -296.612564)
		(width 0.14224)
		(layer "In4.Cu")
		(net "P5E_CPU1_P3_RX_DN<15>")
	)
	(segment
		(start 135.927592 -379.277118)
		(end 135.819896 -379.115828)
		(width 0.14224)
		(layer "In4.Cu")
		(net "P5E_CPU1_P3_RX_DN<15>")
	)
	(arc
		(start 126.792736 -289.940746)
		(mid 126.549409 -289.47618)
		(end 126.792736 -289.011614)
		(width 0.1143)
		(layer "In4.Cu")
		(net "P5E_CPU1_P3_RX_DN<15>")
	)
	(arc
		(start 127.019304 -288.666174)
		(mid 126.978338 -288.495768)
		(end 126.864364 -288.362644)
		(width 0.1143)
		(layer "In4.Cu")
		(net "P5E_CPU1_P3_RX_DN<15>")
	)
	(arc
		(start 126.082044 -287.047178)
		(mid 126.03293 -286.863086)
		(end 125.898656 -286.7279)
		(width 0.1143)
		(layer "In4.Cu")
		(net "P5E_CPU1_P3_RX_DN<15>")
	)
	(arc
		(start 125.619256 -286.342074)
		(mid 125.617233 -286.330664)
		(end 125.615446 -286.319214)
		(width 0.1143)
		(layer "In4.Cu")
		(net "P5E_CPU1_P3_RX_DN<15>")
	)
	(arc
		(start 126.549404 -287.856422)
		(mid 126.508149 -287.685451)
		(end 126.393448 -287.55213)
		(width 0.1143)
		(layer "In4.Cu")
		(net "P5E_CPU1_P3_RX_DN<15>")
	)
	(arc
		(start 127.802386 -293.83101)
		(mid 127.959363 -293.52621)
		(end 127.802386 -293.22141)
		(width 0.1143)
		(layer "In4.Cu")
		(net "P5E_CPU1_P3_RX_DN<15>")
	)
	(arc
		(start 127.73279 -291.560758)
		(mid 127.553977 -291.358408)
		(end 127.489458 -291.096192)
		(width 0.1143)
		(layer "In4.Cu")
		(net "P5E_CPU1_P3_RX_DN<15>")
	)
	(arc
		(start 127.73279 -294.800782)
		(mid 127.489463 -294.336216)
		(end 127.73279 -293.87165)
		(width 0.1143)
		(layer "In4.Cu")
		(net "P5E_CPU1_P3_RX_DN<15>")
	)
	(arc
		(start 136.582912 -375.983246)
		(mid 136.720634 -375.598348)
		(end 136.964166 -375.270014)
		(width 0.14224)
		(layer "In4.Cu")
		(net "P5E_CPU1_P3_RX_DN<15>")
	)
	(arc
		(start 127.019304 -290.286186)
		(mid 126.977755 -290.114764)
		(end 126.862332 -289.981386)
		(width 0.1143)
		(layer "In4.Cu")
		(net "P5E_CPU1_P3_RX_DN<15>")
	)
	(arc
		(start 140.502386 -371.731794)
		(mid 140.759557 -371.347006)
		(end 140.849858 -370.893086)
		(width 0.14224)
		(layer "In4.Cu")
		(net "P5E_CPU1_P3_RX_DN<15>")
	)
	(arc
		(start 126.361444 -287.533842)
		(mid 126.15689 -287.32775)
		(end 126.082044 -287.047178)
		(width 0.1143)
		(layer "In4.Cu")
		(net "P5E_CPU1_P3_RX_DN<15>")
	)
	(arc
		(start 127.48768 -295.923716)
		(mid 127.523782 -295.742129)
		(end 127.626618 -295.588182)
		(width 0.1143)
		(layer "In4.Cu")
		(net "P5E_CPU1_P3_RX_DN<15>")
	)
	(arc
		(start 134.84479 -383.257552)
		(mid 135.140743 -382.858599)
		(end 135.308086 -382.390904)
		(width 0.14224)
		(layer "In4.Cu")
		(net "P5E_CPU1_P3_RX_DN<15>")
	)
	(arc
		(start 144.777206 -364.29188)
		(mid 146.187456 -361.802633)
		(end 146.676618 -358.983788)
		(width 0.14224)
		(layer "In4.Cu")
		(net "P5E_CPU1_P3_RX_DN<15>")
	)
	(arc
		(start 140.849858 -369.275868)
		(mid 140.882073 -369.089201)
		(end 140.975334 -368.924332)
		(width 0.14224)
		(layer "In4.Cu")
		(net "P5E_CPU1_P3_RX_DN<15>")
	)
	(arc
		(start 127.580898 -296.311828)
		(mid 127.511903 -296.208709)
		(end 127.48768 -296.087038)
		(width 0.1143)
		(layer "In4.Cu")
		(net "P5E_CPU1_P3_RX_DN<15>")
	)
	(arc
		(start 127.802386 -292.210998)
		(mid 127.959363 -291.906198)
		(end 127.802386 -291.601398)
		(width 0.1143)
		(layer "In4.Cu")
		(net "P5E_CPU1_P3_RX_DN<15>")
	)
	(arc
		(start 126.792736 -288.320988)
		(mid 126.613923 -288.118638)
		(end 126.549404 -287.856422)
		(width 0.1143)
		(layer "In4.Cu")
		(net "P5E_CPU1_P3_RX_DN<15>")
	)
	(arc
		(start 127.73279 -293.18077)
		(mid 127.489463 -292.716204)
		(end 127.73279 -292.251638)
		(width 0.1143)
		(layer "In4.Cu")
		(net "P5E_CPU1_P3_RX_DN<15>")
	)
	(arc
		(start 127.672846 -296.456354)
		(mid 127.663007 -296.407544)
		(end 127.635254 -296.366184)
		(width 0.1143)
		(layer "In4.Cu")
		(net "P5E_CPU1_P3_RX_DN<15>")
	)
	(arc
		(start 127.489458 -291.096192)
		(mid 127.448203 -290.925221)
		(end 127.333502 -290.7919)
		(width 0.1143)
		(layer "In4.Cu")
		(net "P5E_CPU1_P3_RX_DN<15>")
	)
	(arc
		(start 126.862332 -288.970974)
		(mid 126.977759 -288.837598)
		(end 127.019304 -288.666174)
		(width 0.1143)
		(layer "In4.Cu")
		(net "P5E_CPU1_P3_RX_DN<15>")
	)
	(arc
		(start 125.852682 -286.700976)
		(mid 125.700637 -286.5445)
		(end 125.619256 -286.342074)
		(width 0.1143)
		(layer "In4.Cu")
		(net "P5E_CPU1_P3_RX_DN<15>")
	)
	(arc
		(start 127.262636 -290.750752)
		(mid 127.083823 -290.548402)
		(end 127.019304 -290.286186)
		(width 0.1143)
		(layer "In4.Cu")
		(net "P5E_CPU1_P3_RX_DN<15>")
	)
	(arc
		(start 127.747014 -297.127422)
		(mid 127.658299 -296.994557)
		(end 127.627126 -296.837862)
		(width 0.14224)
		(layer "In4.Cu")
		(net "P5E_CPU1_P3_RX_DN<15>")
	)
	(arc
		(start 127.796798 -295.455086)
		(mid 127.950309 -295.149118)
		(end 127.80137 -294.840914)
		(width 0.1143)
		(layer "In4.Cu")
		(net "P5E_CPU1_P3_RX_DN<15>")
	)
	(segment
		(start 124.767848 -289.210242)
		(end 125.2347 -289.47618)
		(width 0.12954)
		(layer "F.Cu")
		(net "P5E_CPU1_P3_RX_DN<14>")
	)
	(segment
		(start 131.17068 -385.31038)
		(end 131.69138 -385.31038)
		(width 0.127)
		(layer "F.Cu")
		(net "P5E_CPU1_P3_RX_DN<14>")
	)
	(segment
		(start 133.29412 -378.901198)
		(end 133.457442 -378.506736)
		(width 0.14224)
		(layer "In4.Cu")
		(net "P5E_CPU1_P3_RX_DN<14>")
	)
	(segment
		(start 139.671806 -369.660932)
		(end 139.671806 -369.009676)
		(width 0.14224)
		(layer "In4.Cu")
		(net "P5E_CPU1_P3_RX_DN<14>")
	)
	(segment
		(start 126.393448 -290.7919)
		(end 126.371096 -290.7792)
		(width 0.1143)
		(layer "In4.Cu")
		(net "P5E_CPU1_P3_RX_DN<14>")
	)
	(segment
		(start 126.862332 -291.601398)
		(end 126.792736 -291.560758)
		(width 0.1143)
		(layer "In4.Cu")
		(net "P5E_CPU1_P3_RX_DN<14>")
	)
	(segment
		(start 133.025642 -379.548644)
		(end 133.20522 -379.474476)
		(width 0.14224)
		(layer "In4.Cu")
		(net "P5E_CPU1_P3_RX_DN<14>")
	)
	(segment
		(start 133.368288 -379.080268)
		(end 133.29412 -378.901198)
		(width 0.14224)
		(layer "In4.Cu")
		(net "P5E_CPU1_P3_RX_DN<14>")
	)
	(segment
		(start 126.956058 -297.766486)
		(end 126.837694 -297.550586)
		(width 0.14224)
		(layer "In4.Cu")
		(net "P5E_CPU1_P3_RX_DN<14>")
	)
	(segment
		(start 132.430774 -380.985268)
		(end 132.594096 -380.590806)
		(width 0.14224)
		(layer "In4.Cu")
		(net "P5E_CPU1_P3_RX_DN<14>")
	)
	(segment
		(start 132.15874 -382.00076)
		(end 132.504942 -381.164592)
		(width 0.14224)
		(layer "In4.Cu")
		(net "P5E_CPU1_P3_RX_DN<14>")
	)
	(segment
		(start 126.79426 -295.490646)
		(end 126.862332 -295.451022)
		(width 0.1143)
		(layer "In4.Cu")
		(net "P5E_CPU1_P3_RX_DN<14>")
	)
	(segment
		(start 126.837694 -297.550586)
		(end 126.562612 -296.88663)
		(width 0.14224)
		(layer "In4.Cu")
		(net "P5E_CPU1_P3_RX_DN<14>")
	)
	(segment
		(start 125.8951 -289.965384)
		(end 125.892306 -289.96386)
		(width 0.1143)
		(layer "In4.Cu")
		(net "P5E_CPU1_P3_RX_DN<14>")
	)
	(segment
		(start 137.03173 -310.25465)
		(end 127.870204 -299.092112)
		(width 0.14224)
		(layer "In4.Cu")
		(net "P5E_CPU1_P3_RX_DN<14>")
	)
	(segment
		(start 125.615446 -289.558984)
		(end 125.532642 -289.47618)
		(width 0.1143)
		(layer "In4.Cu")
		(net "P5E_CPU1_P3_RX_DN<14>")
	)
	(segment
		(start 125.892306 -289.96386)
		(end 125.891544 -289.963352)
		(width 0.1143)
		(layer "In4.Cu")
		(net "P5E_CPU1_P3_RX_DN<14>")
	)
	(segment
		(start 132.86232 -379.943106)
		(end 133.025642 -379.548644)
		(width 0.14224)
		(layer "In4.Cu")
		(net "P5E_CPU1_P3_RX_DN<14>")
	)
	(segment
		(start 132.158486 -382.001014)
		(end 132.15874 -382.00076)
		(width 0.14224)
		(layer "In4.Cu")
		(net "P5E_CPU1_P3_RX_DN<14>")
	)
	(segment
		(start 126.862332 -294.841422)
		(end 126.792736 -294.800782)
		(width 0.1143)
		(layer "In4.Cu")
		(net "P5E_CPU1_P3_RX_DN<14>")
	)
	(segment
		(start 132.166614 -385.163822)
		(end 131.849622 -384.847084)
		(width 0.14224)
		(layer "In4.Cu")
		(net "P5E_CPU1_P3_RX_DN<14>")
	)
	(segment
		(start 132.044948 -385.404868)
		(end 132.166614 -385.334764)
		(width 0.14224)
		(layer "In4.Cu")
		(net "P5E_CPU1_P3_RX_DN<14>")
	)
	(segment
		(start 143.635222 -327.371456)
		(end 138.9126 -313.774582)
		(width 0.14224)
		(layer "In4.Cu")
		(net "P5E_CPU1_P3_RX_DN<14>")
	)
	(segment
		(start 145.599404 -358.90962)
		(end 145.599404 -338.30641)
		(width 0.14224)
		(layer "In4.Cu")
		(net "P5E_CPU1_P3_RX_DN<14>")
	)
	(segment
		(start 132.773674 -380.516638)
		(end 132.936742 -380.12243)
		(width 0.14224)
		(layer "In4.Cu")
		(net "P5E_CPU1_P3_RX_DN<14>")
	)
	(segment
		(start 133.457442 -378.506736)
		(end 133.636766 -378.432314)
		(width 0.14224)
		(layer "In4.Cu")
		(net "P5E_CPU1_P3_RX_DN<14>")
	)
	(segment
		(start 126.503938 -296.372534)
		(end 126.549658 -296.326814)
		(width 0.1143)
		(layer "In4.Cu")
		(net "P5E_CPU1_P3_RX_DN<14>")
	)
	(segment
		(start 131.849622 -384.847084)
		(end 131.853432 -384.345942)
		(width 0.14224)
		(layer "In4.Cu")
		(net "P5E_CPU1_P3_RX_DN<14>")
	)
	(segment
		(start 126.862332 -293.22141)
		(end 126.792736 -293.18077)
		(width 0.1143)
		(layer "In4.Cu")
		(net "P5E_CPU1_P3_RX_DN<14>")
	)
	(segment
		(start 126.36627 -290.776152)
		(end 126.36373 -290.774882)
		(width 0.1143)
		(layer "In4.Cu")
		(net "P5E_CPU1_P3_RX_DN<14>")
	)
	(segment
		(start 142.17396 -365.248952)
		(end 144.22501 -362.749846)
		(width 0.14224)
		(layer "In4.Cu")
		(net "P5E_CPU1_P3_RX_DN<14>")
	)
	(segment
		(start 126.503938 -296.590466)
		(end 126.503938 -296.400982)
		(width 0.14224)
		(layer "In4.Cu")
		(net "P5E_CPU1_P3_RX_DN<14>")
	)
	(segment
		(start 138.9126 -313.774582)
		(end 137.03173 -310.25465)
		(width 0.14224)
		(layer "In4.Cu")
		(net "P5E_CPU1_P3_RX_DN<14>")
	)
	(segment
		(start 126.503938 -296.400982)
		(end 126.503938 -296.372534)
		(width 0.1143)
		(layer "In4.Cu")
		(net "P5E_CPU1_P3_RX_DN<14>")
	)
	(segment
		(start 125.532642 -289.47618)
		(end 125.2347 -289.47618)
		(width 0.1143)
		(layer "In4.Cu")
		(net "P5E_CPU1_P3_RX_DN<14>")
	)
	(segment
		(start 126.367794 -290.777168)
		(end 126.36627 -290.776152)
		(width 0.1143)
		(layer "In4.Cu")
		(net "P5E_CPU1_P3_RX_DN<14>")
	)
	(segment
		(start 133.20522 -379.474476)
		(end 133.368288 -379.080268)
		(width 0.14224)
		(layer "In4.Cu")
		(net "P5E_CPU1_P3_RX_DN<14>")
	)
	(segment
		(start 131.853432 -384.345942)
		(end 132.158486 -384.040888)
		(width 0.14224)
		(layer "In4.Cu")
		(net "P5E_CPU1_P3_RX_DN<14>")
	)
	(segment
		(start 142.17396 -365.249206)
		(end 142.17396 -365.248952)
		(width 0.14224)
		(layer "In4.Cu")
		(net "P5E_CPU1_P3_RX_DN<14>")
	)
	(segment
		(start 125.891544 -289.963352)
		(end 125.853444 -289.941254)
		(width 0.1143)
		(layer "In4.Cu")
		(net "P5E_CPU1_P3_RX_DN<14>")
	)
	(segment
		(start 127.870204 -299.092112)
		(end 126.956058 -297.766486)
		(width 0.14224)
		(layer "In4.Cu")
		(net "P5E_CPU1_P3_RX_DN<14>")
	)
	(segment
		(start 135.857742 -374.181624)
		(end 139.171934 -370.867432)
		(width 0.14224)
		(layer "In4.Cu")
		(net "P5E_CPU1_P3_RX_DN<14>")
	)
	(segment
		(start 131.69138 -385.31038)
		(end 132.04444 -385.405376)
		(width 0.14224)
		(layer "In4.Cu")
		(net "P5E_CPU1_P3_RX_DN<14>")
	)
	(segment
		(start 133.636766 -378.432314)
		(end 134.647178 -375.993152)
		(width 0.14224)
		(layer "In4.Cu")
		(net "P5E_CPU1_P3_RX_DN<14>")
	)
	(segment
		(start 140.122656 -367.748566)
		(end 142.17396 -365.249206)
		(width 0.14224)
		(layer "In4.Cu")
		(net "P5E_CPU1_P3_RX_DN<14>")
	)
	(segment
		(start 132.594096 -380.590806)
		(end 132.773674 -380.516638)
		(width 0.14224)
		(layer "In4.Cu")
		(net "P5E_CPU1_P3_RX_DN<14>")
	)
	(segment
		(start 145.599404 -338.30641)
		(end 143.635222 -327.371456)
		(width 0.14224)
		(layer "In4.Cu")
		(net "P5E_CPU1_P3_RX_DN<14>")
	)
	(segment
		(start 126.549658 -296.326814)
		(end 126.549658 -295.956228)
		(width 0.1143)
		(layer "In4.Cu")
		(net "P5E_CPU1_P3_RX_DN<14>")
	)
	(segment
		(start 132.158486 -384.040888)
		(end 132.158486 -382.001014)
		(width 0.14224)
		(layer "In4.Cu")
		(net "P5E_CPU1_P3_RX_DN<14>")
	)
	(segment
		(start 132.04444 -385.405376)
		(end 132.044948 -385.404868)
		(width 0.14224)
		(layer "In4.Cu")
		(net "P5E_CPU1_P3_RX_DN<14>")
	)
	(segment
		(start 126.792736 -292.251638)
		(end 126.862332 -292.210998)
		(width 0.1143)
		(layer "In4.Cu")
		(net "P5E_CPU1_P3_RX_DN<14>")
	)
	(segment
		(start 132.166614 -385.334764)
		(end 132.166614 -385.163822)
		(width 0.14224)
		(layer "In4.Cu")
		(net "P5E_CPU1_P3_RX_DN<14>")
	)
	(segment
		(start 132.936742 -380.12243)
		(end 132.86232 -379.943106)
		(width 0.14224)
		(layer "In4.Cu")
		(net "P5E_CPU1_P3_RX_DN<14>")
	)
	(segment
		(start 126.370334 -290.778692)
		(end 126.367794 -290.777168)
		(width 0.1143)
		(layer "In4.Cu")
		(net "P5E_CPU1_P3_RX_DN<14>")
	)
	(segment
		(start 126.792736 -293.87165)
		(end 126.862332 -293.83101)
		(width 0.1143)
		(layer "In4.Cu")
		(net "P5E_CPU1_P3_RX_DN<14>")
	)
	(segment
		(start 126.36373 -290.774882)
		(end 126.351792 -290.767516)
		(width 0.1143)
		(layer "In4.Cu")
		(net "P5E_CPU1_P3_RX_DN<14>")
	)
	(segment
		(start 126.371096 -290.7792)
		(end 126.370334 -290.778692)
		(width 0.1143)
		(layer "In4.Cu")
		(net "P5E_CPU1_P3_RX_DN<14>")
	)
	(segment
		(start 132.504942 -381.164592)
		(end 132.430774 -380.985268)
		(width 0.14224)
		(layer "In4.Cu")
		(net "P5E_CPU1_P3_RX_DN<14>")
	)
	(arc
		(start 126.351792 -290.767516)
		(mid 126.151734 -290.561727)
		(end 126.078742 -290.284154)
		(width 0.1143)
		(layer "In4.Cu")
		(net "P5E_CPU1_P3_RX_DN<14>")
	)
	(arc
		(start 125.853444 -289.941254)
		(mid 125.853063 -289.941)
		(end 125.852682 -289.940746)
		(width 0.1143)
		(layer "In4.Cu")
		(net "P5E_CPU1_P3_RX_DN<14>")
	)
	(arc
		(start 139.671806 -369.009676)
		(mid 139.78781 -368.339997)
		(end 140.122656 -367.748566)
		(width 0.14224)
		(layer "In4.Cu")
		(net "P5E_CPU1_P3_RX_DN<14>")
	)
	(arc
		(start 126.562612 -296.88663)
		(mid 126.518682 -296.741438)
		(end 126.503938 -296.590466)
		(width 0.14224)
		(layer "In4.Cu")
		(net "P5E_CPU1_P3_RX_DN<14>")
	)
	(arc
		(start 126.792736 -293.18077)
		(mid 126.549409 -292.716204)
		(end 126.792736 -292.251638)
		(width 0.1143)
		(layer "In4.Cu")
		(net "P5E_CPU1_P3_RX_DN<14>")
	)
	(arc
		(start 139.171934 -370.867432)
		(mid 139.54191 -370.313914)
		(end 139.671806 -369.660932)
		(width 0.14224)
		(layer "In4.Cu")
		(net "P5E_CPU1_P3_RX_DN<14>")
	)
	(arc
		(start 134.647178 -375.993152)
		(mid 135.163236 -375.027761)
		(end 135.857742 -374.181624)
		(width 0.14224)
		(layer "In4.Cu")
		(net "P5E_CPU1_P3_RX_DN<14>")
	)
	(arc
		(start 144.22501 -362.749846)
		(mid 145.245384 -360.948974)
		(end 145.599404 -358.90962)
		(width 0.14224)
		(layer "In4.Cu")
		(net "P5E_CPU1_P3_RX_DN<14>")
	)
	(arc
		(start 126.862332 -292.210998)
		(mid 127.019309 -291.906198)
		(end 126.862332 -291.601398)
		(width 0.1143)
		(layer "In4.Cu")
		(net "P5E_CPU1_P3_RX_DN<14>")
	)
	(arc
		(start 126.549404 -291.096192)
		(mid 126.508149 -290.925221)
		(end 126.393448 -290.7919)
		(width 0.1143)
		(layer "In4.Cu")
		(net "P5E_CPU1_P3_RX_DN<14>")
	)
	(arc
		(start 126.862332 -295.451022)
		(mid 127.019309 -295.146222)
		(end 126.862332 -294.841422)
		(width 0.1143)
		(layer "In4.Cu")
		(net "P5E_CPU1_P3_RX_DN<14>")
	)
	(arc
		(start 125.619256 -289.581844)
		(mid 125.617233 -289.570434)
		(end 125.615446 -289.558984)
		(width 0.1143)
		(layer "In4.Cu")
		(net "P5E_CPU1_P3_RX_DN<14>")
	)
	(arc
		(start 125.852682 -289.940746)
		(mid 125.700695 -289.784238)
		(end 125.619256 -289.581844)
		(width 0.1143)
		(layer "In4.Cu")
		(net "P5E_CPU1_P3_RX_DN<14>")
	)
	(arc
		(start 126.792736 -291.560758)
		(mid 126.613923 -291.358408)
		(end 126.549404 -291.096192)
		(width 0.1143)
		(layer "In4.Cu")
		(net "P5E_CPU1_P3_RX_DN<14>")
	)
	(arc
		(start 126.078742 -290.284154)
		(mid 126.029553 -290.100203)
		(end 125.8951 -289.965384)
		(width 0.1143)
		(layer "In4.Cu")
		(net "P5E_CPU1_P3_RX_DN<14>")
	)
	(arc
		(start 126.792736 -294.800782)
		(mid 126.549409 -294.336216)
		(end 126.792736 -293.87165)
		(width 0.1143)
		(layer "In4.Cu")
		(net "P5E_CPU1_P3_RX_DN<14>")
	)
	(arc
		(start 126.862332 -293.83101)
		(mid 127.019309 -293.52621)
		(end 126.862332 -293.22141)
		(width 0.1143)
		(layer "In4.Cu")
		(net "P5E_CPU1_P3_RX_DN<14>")
	)
	(arc
		(start 126.549658 -295.956228)
		(mid 126.614476 -295.693239)
		(end 126.79426 -295.490646)
		(width 0.1143)
		(layer "In4.Cu")
		(net "P5E_CPU1_P3_RX_DN<14>")
	)
	(segment
		(start 124.767848 -290.830254)
		(end 125.2347 -291.096192)
		(width 0.12954)
		(layer "F.Cu")
		(net "P5E_CPU1_P3_RX_DN<13>")
	)
	(segment
		(start 129.97053 -385.31038)
		(end 130.49123 -385.31038)
		(width 0.127)
		(layer "F.Cu")
		(net "P5E_CPU1_P3_RX_DN<13>")
	)
	(segment
		(start 125.6157 -291.178996)
		(end 125.615446 -291.178996)
		(width 0.1143)
		(layer "In4.Cu")
		(net "P5E_CPU1_P3_RX_DN<13>")
	)
	(segment
		(start 132.543042 -378.236226)
		(end 132.542534 -378.236226)
		(width 0.14224)
		(layer "In4.Cu")
		(net "P5E_CPU1_P3_RX_DN<13>")
	)
	(segment
		(start 132.111242 -379.278388)
		(end 132.27431 -378.88418)
		(width 0.14224)
		(layer "In4.Cu")
		(net "P5E_CPU1_P3_RX_DN<13>")
	)
	(segment
		(start 130.845052 -385.404868)
		(end 130.966718 -385.334764)
		(width 0.14224)
		(layer "In4.Cu")
		(net "P5E_CPU1_P3_RX_DN<13>")
	)
	(segment
		(start 125.891798 -293.20363)
		(end 125.890782 -293.203122)
		(width 0.1143)
		(layer "In4.Cu")
		(net "P5E_CPU1_P3_RX_DN<13>")
	)
	(segment
		(start 125.853444 -295.491154)
		(end 125.892306 -295.468802)
		(width 0.1143)
		(layer "In4.Cu")
		(net "P5E_CPU1_P3_RX_DN<13>")
	)
	(segment
		(start 144.479518 -337.521042)
		(end 142.664688 -327.419208)
		(width 0.14224)
		(layer "In4.Cu")
		(net "P5E_CPU1_P3_RX_DN<13>")
	)
	(segment
		(start 126.92761 -299.417486)
		(end 126.146814 -298.248578)
		(width 0.14224)
		(layer "In4.Cu")
		(net "P5E_CPU1_P3_RX_DN<13>")
	)
	(segment
		(start 125.852682 -293.87165)
		(end 125.889258 -293.850314)
		(width 0.1143)
		(layer "In4.Cu")
		(net "P5E_CPU1_P3_RX_DN<13>")
	)
	(segment
		(start 130.844544 -385.405376)
		(end 130.845052 -385.404868)
		(width 0.14224)
		(layer "In4.Cu")
		(net "P5E_CPU1_P3_RX_DN<13>")
	)
	(segment
		(start 130.95859 -384.00355)
		(end 130.95859 -382.609598)
		(width 0.14224)
		(layer "In4.Cu")
		(net "P5E_CPU1_P3_RX_DN<13>")
	)
	(segment
		(start 125.852682 -292.251638)
		(end 125.892306 -292.228524)
		(width 0.1143)
		(layer "In4.Cu")
		(net "P5E_CPU1_P3_RX_DN<13>")
	)
	(segment
		(start 142.664688 -327.419208)
		(end 138.05535 -314.149232)
		(width 0.14224)
		(layer "In4.Cu")
		(net "P5E_CPU1_P3_RX_DN<13>")
	)
	(segment
		(start 132.200142 -378.70511)
		(end 132.363464 -378.310648)
		(width 0.14224)
		(layer "In4.Cu")
		(net "P5E_CPU1_P3_RX_DN<13>")
	)
	(segment
		(start 138.05535 -314.149232)
		(end 136.260078 -310.790082)
		(width 0.14224)
		(layer "In4.Cu")
		(net "P5E_CPU1_P3_RX_DN<13>")
	)
	(segment
		(start 130.654044 -384.307842)
		(end 130.95859 -384.00355)
		(width 0.14224)
		(layer "In4.Cu")
		(net "P5E_CPU1_P3_RX_DN<13>")
	)
	(segment
		(start 125.890782 -293.849298)
		(end 125.891798 -293.84879)
		(width 0.1143)
		(layer "In4.Cu")
		(net "P5E_CPU1_P3_RX_DN<13>")
	)
	(segment
		(start 125.889258 -293.850314)
		(end 125.890782 -293.849298)
		(width 0.1143)
		(layer "In4.Cu")
		(net "P5E_CPU1_P3_RX_DN<13>")
	)
	(segment
		(start 125.563884 -296.739056)
		(end 125.563884 -296.351198)
		(width 0.14224)
		(layer "In4.Cu")
		(net "P5E_CPU1_P3_RX_DN<13>")
	)
	(segment
		(start 125.615446 -291.178996)
		(end 125.532642 -291.096192)
		(width 0.1143)
		(layer "In4.Cu")
		(net "P5E_CPU1_P3_RX_DN<13>")
	)
	(segment
		(start 125.890782 -293.203122)
		(end 125.852682 -293.18077)
		(width 0.1143)
		(layer "In4.Cu")
		(net "P5E_CPU1_P3_RX_DN<13>")
	)
	(segment
		(start 138.741658 -366.245648)
		(end 143.26489 -361.722416)
		(width 0.14224)
		(layer "In4.Cu")
		(net "P5E_CPU1_P3_RX_DN<13>")
	)
	(segment
		(start 131.168648 -381.55372)
		(end 131.410964 -380.968504)
		(width 0.14224)
		(layer "In4.Cu")
		(net "P5E_CPU1_P3_RX_DN<13>")
	)
	(segment
		(start 135.655812 -371.622828)
		(end 137.117328 -370.161312)
		(width 0.14224)
		(layer "In4.Cu")
		(net "P5E_CPU1_P3_RX_DN<13>")
	)
	(segment
		(start 131.931664 -379.35281)
		(end 132.111242 -379.278388)
		(width 0.14224)
		(layer "In4.Cu")
		(net "P5E_CPU1_P3_RX_DN<13>")
	)
	(segment
		(start 131.84251 -379.926342)
		(end 131.768342 -379.747272)
		(width 0.14224)
		(layer "In4.Cu")
		(net "P5E_CPU1_P3_RX_DN<13>")
	)
	(segment
		(start 125.892306 -294.823896)
		(end 125.875796 -294.814498)
		(width 0.1143)
		(layer "In4.Cu")
		(net "P5E_CPU1_P3_RX_DN<13>")
	)
	(segment
		(start 131.336796 -380.78918)
		(end 131.500118 -380.394718)
		(width 0.14224)
		(layer "In4.Cu")
		(net "P5E_CPU1_P3_RX_DN<13>")
	)
	(segment
		(start 131.679442 -380.32055)
		(end 131.84251 -379.926342)
		(width 0.14224)
		(layer "In4.Cu")
		(net "P5E_CPU1_P3_RX_DN<13>")
	)
	(segment
		(start 131.593844 -305.103784)
		(end 126.92761 -299.417486)
		(width 0.14224)
		(layer "In4.Cu")
		(net "P5E_CPU1_P3_RX_DN<13>")
	)
	(segment
		(start 134.67207 -373.095012)
		(end 134.672324 -373.094758)
		(width 0.14224)
		(layer "In4.Cu")
		(net "P5E_CPU1_P3_RX_DN<13>")
	)
	(segment
		(start 125.563884 -296.351198)
		(end 125.563884 -296.32275)
		(width 0.1143)
		(layer "In4.Cu")
		(net "P5E_CPU1_P3_RX_DN<13>")
	)
	(segment
		(start 125.532642 -291.096192)
		(end 125.2347 -291.096192)
		(width 0.1143)
		(layer "In4.Cu")
		(net "P5E_CPU1_P3_RX_DN<13>")
	)
	(segment
		(start 130.649726 -384.84683)
		(end 130.654044 -384.307842)
		(width 0.14224)
		(layer "In4.Cu")
		(net "P5E_CPU1_P3_RX_DN<13>")
	)
	(segment
		(start 130.49123 -385.31038)
		(end 130.844544 -385.405376)
		(width 0.14224)
		(layer "In4.Cu")
		(net "P5E_CPU1_P3_RX_DN<13>")
	)
	(segment
		(start 130.966718 -385.163822)
		(end 130.649726 -384.84683)
		(width 0.14224)
		(layer "In4.Cu")
		(net "P5E_CPU1_P3_RX_DN<13>")
	)
	(segment
		(start 125.891798 -293.84879)
		(end 125.903228 -293.842186)
		(width 0.1143)
		(layer "In4.Cu")
		(net "P5E_CPU1_P3_RX_DN<13>")
	)
	(segment
		(start 132.27431 -378.88418)
		(end 132.200142 -378.70511)
		(width 0.14224)
		(layer "In4.Cu")
		(net "P5E_CPU1_P3_RX_DN<13>")
	)
	(segment
		(start 131.410964 -380.968504)
		(end 131.336796 -380.78918)
		(width 0.14224)
		(layer "In4.Cu")
		(net "P5E_CPU1_P3_RX_DN<13>")
	)
	(segment
		(start 136.260078 -310.790082)
		(end 131.59359 -305.103784)
		(width 0.14224)
		(layer "In4.Cu")
		(net "P5E_CPU1_P3_RX_DN<13>")
	)
	(segment
		(start 132.363464 -378.310648)
		(end 132.543042 -378.236226)
		(width 0.14224)
		(layer "In4.Cu")
		(net "P5E_CPU1_P3_RX_DN<13>")
	)
	(segment
		(start 132.542534 -378.236226)
		(end 134.67207 -373.095012)
		(width 0.14224)
		(layer "In4.Cu")
		(net "P5E_CPU1_P3_RX_DN<13>")
	)
	(segment
		(start 125.90399 -293.210488)
		(end 125.89256 -293.203884)
		(width 0.1143)
		(layer "In4.Cu")
		(net "P5E_CPU1_P3_RX_DN<13>")
	)
	(segment
		(start 144.479518 -358.789986)
		(end 144.479518 -337.521042)
		(width 0.14224)
		(layer "In4.Cu")
		(net "P5E_CPU1_P3_RX_DN<13>")
	)
	(segment
		(start 125.892306 -291.583618)
		(end 125.853444 -291.561266)
		(width 0.1143)
		(layer "In4.Cu")
		(net "P5E_CPU1_P3_RX_DN<13>")
	)
	(segment
		(start 125.999494 -297.973496)
		(end 125.633734 -297.090338)
		(width 0.14224)
		(layer "In4.Cu")
		(net "P5E_CPU1_P3_RX_DN<13>")
	)
	(segment
		(start 125.89256 -293.203884)
		(end 125.891798 -293.20363)
		(width 0.1143)
		(layer "In4.Cu")
		(net "P5E_CPU1_P3_RX_DN<13>")
	)
	(segment
		(start 130.966718 -385.334764)
		(end 130.966718 -385.163822)
		(width 0.14224)
		(layer "In4.Cu")
		(net "P5E_CPU1_P3_RX_DN<13>")
	)
	(segment
		(start 131.768342 -379.747272)
		(end 131.931664 -379.35281)
		(width 0.14224)
		(layer "In4.Cu")
		(net "P5E_CPU1_P3_RX_DN<13>")
	)
	(segment
		(start 125.609604 -296.27703)
		(end 125.609604 -295.956228)
		(width 0.1143)
		(layer "In4.Cu")
		(net "P5E_CPU1_P3_RX_DN<13>")
	)
	(segment
		(start 131.500118 -380.394718)
		(end 131.679442 -380.32055)
		(width 0.14224)
		(layer "In4.Cu")
		(net "P5E_CPU1_P3_RX_DN<13>")
	)
	(segment
		(start 125.563884 -296.32275)
		(end 125.609604 -296.27703)
		(width 0.1143)
		(layer "In4.Cu")
		(net "P5E_CPU1_P3_RX_DN<13>")
	)
	(segment
		(start 131.59359 -305.103784)
		(end 131.593844 -305.103784)
		(width 0.14224)
		(layer "In4.Cu")
		(net "P5E_CPU1_P3_RX_DN<13>")
	)
	(segment
		(start 125.875796 -294.814498)
		(end 125.852682 -294.800782)
		(width 0.1143)
		(layer "In4.Cu")
		(net "P5E_CPU1_P3_RX_DN<13>")
	)
	(arc
		(start 137.117328 -370.161312)
		(mid 137.494316 -369.588898)
		(end 137.633202 -368.917728)
		(width 0.14224)
		(layer "In4.Cu")
		(net "P5E_CPU1_P3_RX_DN<13>")
	)
	(arc
		(start 125.892306 -295.468802)
		(mid 126.077724 -295.146412)
		(end 125.892306 -294.823896)
		(width 0.1143)
		(layer "In4.Cu")
		(net "P5E_CPU1_P3_RX_DN<13>")
	)
	(arc
		(start 125.852682 -294.800782)
		(mid 125.609355 -294.336216)
		(end 125.852682 -293.87165)
		(width 0.1143)
		(layer "In4.Cu")
		(net "P5E_CPU1_P3_RX_DN<13>")
	)
	(arc
		(start 125.892306 -292.228524)
		(mid 126.077724 -291.906134)
		(end 125.892306 -291.583618)
		(width 0.1143)
		(layer "In4.Cu")
		(net "P5E_CPU1_P3_RX_DN<13>")
	)
	(arc
		(start 125.633734 -297.090338)
		(mid 125.581514 -296.918136)
		(end 125.563884 -296.739056)
		(width 0.14224)
		(layer "In4.Cu")
		(net "P5E_CPU1_P3_RX_DN<13>")
	)
	(arc
		(start 126.146814 -298.248578)
		(mid 126.066388 -298.11466)
		(end 125.999494 -297.973496)
		(width 0.14224)
		(layer "In4.Cu")
		(net "P5E_CPU1_P3_RX_DN<13>")
	)
	(arc
		(start 125.903228 -293.842186)
		(mid 126.078178 -293.5266)
		(end 125.90399 -293.210488)
		(width 0.1143)
		(layer "In4.Cu")
		(net "P5E_CPU1_P3_RX_DN<13>")
	)
	(arc
		(start 125.852682 -293.18077)
		(mid 125.609355 -292.716204)
		(end 125.852682 -292.251638)
		(width 0.1143)
		(layer "In4.Cu")
		(net "P5E_CPU1_P3_RX_DN<13>")
	)
	(arc
		(start 130.95859 -382.609598)
		(mid 131.011606 -382.07131)
		(end 131.168648 -381.55372)
		(width 0.14224)
		(layer "In4.Cu")
		(net "P5E_CPU1_P3_RX_DN<13>")
	)
	(arc
		(start 125.609604 -295.956228)
		(mid 125.674263 -295.693671)
		(end 125.853444 -295.491154)
		(width 0.1143)
		(layer "In4.Cu")
		(net "P5E_CPU1_P3_RX_DN<13>")
	)
	(arc
		(start 134.672324 -373.094758)
		(mid 135.091562 -372.310344)
		(end 135.655812 -371.622828)
		(width 0.14224)
		(layer "In4.Cu")
		(net "P5E_CPU1_P3_RX_DN<13>")
	)
	(arc
		(start 125.853444 -291.561266)
		(mid 125.694888 -291.394818)
		(end 125.6157 -291.178996)
		(width 0.1143)
		(layer "In4.Cu")
		(net "P5E_CPU1_P3_RX_DN<13>")
	)
	(arc
		(start 137.633202 -368.917728)
		(mid 137.922049 -367.471596)
		(end 138.741658 -366.245648)
		(width 0.14224)
		(layer "In4.Cu")
		(net "P5E_CPU1_P3_RX_DN<13>")
	)
	(arc
		(start 143.26489 -361.722416)
		(mid 144.163864 -360.377006)
		(end 144.479518 -358.789986)
		(width 0.14224)
		(layer "In4.Cu")
		(net "P5E_CPU1_P3_RX_DN<13>")
	)
	(segment
		(start 124.767848 -287.590484)
		(end 125.2347 -287.856422)
		(width 0.12954)
		(layer "F.Cu")
		(net "P5E_CPU1_P3_RX_DN<12>")
	)
	(segment
		(start 128.770634 -385.31038)
		(end 129.291334 -385.31038)
		(width 0.127)
		(layer "F.Cu")
		(net "P5E_CPU1_P3_RX_DN<12>")
	)
	(segment
		(start 124.954538 -292.227254)
		(end 124.956062 -292.226238)
		(width 0.1143)
		(layer "In4.Cu")
		(net "P5E_CPU1_P3_RX_DN<12>")
	)
	(segment
		(start 124.669296 -296.365676)
		(end 124.669296 -295.956228)
		(width 0.1143)
		(layer "In4.Cu")
		(net "P5E_CPU1_P3_RX_DN<12>")
	)
	(segment
		(start 124.958856 -291.587682)
		(end 124.956316 -291.586158)
		(width 0.1143)
		(layer "In4.Cu")
		(net "P5E_CPU1_P3_RX_DN<12>")
	)
	(segment
		(start 129.766568 -385.163822)
		(end 129.449576 -384.84683)
		(width 0.14224)
		(layer "In4.Cu")
		(net "P5E_CPU1_P3_RX_DN<12>")
	)
	(segment
		(start 124.945648 -291.580062)
		(end 124.944632 -291.5793)
		(width 0.1143)
		(layer "In4.Cu")
		(net "P5E_CPU1_P3_RX_DN<12>")
	)
	(segment
		(start 124.950728 -291.58311)
		(end 124.949204 -291.582094)
		(width 0.1143)
		(layer "In4.Cu")
		(net "P5E_CPU1_P3_RX_DN<12>")
	)
	(segment
		(start 124.983494 -294.84193)
		(end 124.958348 -294.827452)
		(width 0.1143)
		(layer "In4.Cu")
		(net "P5E_CPU1_P3_RX_DN<12>")
	)
	(segment
		(start 135.472678 -311.312306)
		(end 126.127764 -299.923962)
		(width 0.14224)
		(layer "In4.Cu")
		(net "P5E_CPU1_P3_RX_DN<12>")
	)
	(segment
		(start 124.952506 -288.988246)
		(end 124.953776 -288.987484)
		(width 0.1143)
		(layer "In4.Cu")
		(net "P5E_CPU1_P3_RX_DN<12>")
	)
	(segment
		(start 124.623576 -296.411396)
		(end 124.669296 -296.365676)
		(width 0.1143)
		(layer "In4.Cu")
		(net "P5E_CPU1_P3_RX_DN<12>")
	)
	(segment
		(start 124.950728 -288.989262)
		(end 124.951744 -288.988754)
		(width 0.1143)
		(layer "In4.Cu")
		(net "P5E_CPU1_P3_RX_DN<12>")
	)
	(segment
		(start 124.965968 -288.980372)
		(end 124.971302 -288.977578)
		(width 0.1143)
		(layer "In4.Cu")
		(net "P5E_CPU1_P3_RX_DN<12>")
	)
	(segment
		(start 125.403356 -288.189924)
		(end 125.45187 -288.161476)
		(width 0.1143)
		(layer "In4.Cu")
		(net "P5E_CPU1_P3_RX_DN<12>")
	)
	(segment
		(start 124.9553 -288.986722)
		(end 124.956062 -288.986214)
		(width 0.1143)
		(layer "In4.Cu")
		(net "P5E_CPU1_P3_RX_DN<12>")
	)
	(segment
		(start 129.644394 -385.405376)
		(end 129.644902 -385.404868)
		(width 0.14224)
		(layer "In4.Cu")
		(net "P5E_CPU1_P3_RX_DN<12>")
	)
	(segment
		(start 126.127764 -299.923962)
		(end 125.240288 -298.59605)
		(width 0.14224)
		(layer "In4.Cu")
		(net "P5E_CPU1_P3_RX_DN<12>")
	)
	(segment
		(start 129.75844 -383.948432)
		(end 129.75844 -382.598168)
		(width 0.14224)
		(layer "In4.Cu")
		(net "P5E_CPU1_P3_RX_DN<12>")
	)
	(segment
		(start 124.958856 -288.98469)
		(end 124.96165 -288.983166)
		(width 0.1143)
		(layer "In4.Cu")
		(net "P5E_CPU1_P3_RX_DN<12>")
	)
	(segment
		(start 134.231126 -368.797078)
		(end 134.231126 -368.313462)
		(width 0.14224)
		(layer "In4.Cu")
		(net "P5E_CPU1_P3_RX_DN<12>")
	)
	(segment
		(start 125.45187 -288.161476)
		(end 125.453394 -288.16046)
		(width 0.1143)
		(layer "In4.Cu")
		(net "P5E_CPU1_P3_RX_DN<12>")
	)
	(segment
		(start 124.913898 -295.490646)
		(end 124.98451 -295.449498)
		(width 0.1143)
		(layer "In4.Cu")
		(net "P5E_CPU1_P3_RX_DN<12>")
	)
	(segment
		(start 130.268726 -380.531878)
		(end 130.44805 -380.45771)
		(width 0.14224)
		(layer "In4.Cu")
		(net "P5E_CPU1_P3_RX_DN<12>")
	)
	(segment
		(start 124.951744 -291.583618)
		(end 124.950728 -291.58311)
		(width 0.1143)
		(layer "In4.Cu")
		(net "P5E_CPU1_P3_RX_DN<12>")
	)
	(segment
		(start 124.925328 -292.244018)
		(end 124.92736 -292.242748)
		(width 0.1143)
		(layer "In4.Cu")
		(net "P5E_CPU1_P3_RX_DN<12>")
	)
	(segment
		(start 130.179572 -381.10541)
		(end 130.105404 -380.92634)
		(width 0.14224)
		(layer "In4.Cu")
		(net "P5E_CPU1_P3_RX_DN<12>")
	)
	(segment
		(start 129.454148 -384.25247)
		(end 129.75844 -383.948432)
		(width 0.14224)
		(layer "In4.Cu")
		(net "P5E_CPU1_P3_RX_DN<12>")
	)
	(segment
		(start 124.948188 -291.581586)
		(end 124.945648 -291.580062)
		(width 0.1143)
		(layer "In4.Cu")
		(net "P5E_CPU1_P3_RX_DN<12>")
	)
	(segment
		(start 124.983494 -293.221918)
		(end 124.950728 -293.203122)
		(width 0.1143)
		(layer "In4.Cu")
		(net "P5E_CPU1_P3_RX_DN<12>")
	)
	(segment
		(start 124.953522 -293.847266)
		(end 124.955554 -293.846504)
		(width 0.1143)
		(layer "In4.Cu")
		(net "P5E_CPU1_P3_RX_DN<12>")
	)
	(segment
		(start 124.934218 -292.23716)
		(end 124.952506 -292.228016)
		(width 0.1143)
		(layer "In4.Cu")
		(net "P5E_CPU1_P3_RX_DN<12>")
	)
	(segment
		(start 131.042918 -379.02134)
		(end 130.96875 -378.84227)
		(width 0.14224)
		(layer "In4.Cu")
		(net "P5E_CPU1_P3_RX_DN<12>")
	)
	(segment
		(start 124.956062 -292.226238)
		(end 124.957078 -292.22573)
		(width 0.1143)
		(layer "In4.Cu")
		(net "P5E_CPU1_P3_RX_DN<12>")
	)
	(segment
		(start 124.929138 -292.241732)
		(end 124.930154 -292.241224)
		(width 0.1143)
		(layer "In4.Cu")
		(net "P5E_CPU1_P3_RX_DN<12>")
	)
	(segment
		(start 124.96165 -288.983166)
		(end 124.96165 -288.982912)
		(width 0.1143)
		(layer "In4.Cu")
		(net "P5E_CPU1_P3_RX_DN<12>")
	)
	(segment
		(start 125.532642 -287.856422)
		(end 125.2347 -287.856422)
		(width 0.1143)
		(layer "In4.Cu")
		(net "P5E_CPU1_P3_RX_DN<12>")
	)
	(segment
		(start 124.983494 -291.601906)
		(end 124.958856 -291.587682)
		(width 0.1143)
		(layer "In4.Cu")
		(net "P5E_CPU1_P3_RX_DN<12>")
	)
	(segment
		(start 124.930154 -292.241224)
		(end 124.934218 -292.23716)
		(width 0.1143)
		(layer "In4.Cu")
		(net "P5E_CPU1_P3_RX_DN<12>")
	)
	(segment
		(start 124.623576 -296.439844)
		(end 124.623576 -296.411396)
		(width 0.1143)
		(layer "In4.Cu")
		(net "P5E_CPU1_P3_RX_DN<12>")
	)
	(segment
		(start 131.311396 -378.373132)
		(end 133.264148 -373.658892)
		(width 0.14224)
		(layer "In4.Cu")
		(net "P5E_CPU1_P3_RX_DN<12>")
	)
	(segment
		(start 124.951744 -288.988754)
		(end 124.952506 -288.988246)
		(width 0.1143)
		(layer "In4.Cu")
		(net "P5E_CPU1_P3_RX_DN<12>")
	)
	(segment
		(start 124.93371 -294.811704)
		(end 124.910088 -294.797988)
		(width 0.1143)
		(layer "In4.Cu")
		(net "P5E_CPU1_P3_RX_DN<12>")
	)
	(segment
		(start 124.956316 -291.586158)
		(end 124.953776 -291.584888)
		(width 0.1143)
		(layer "In4.Cu")
		(net "P5E_CPU1_P3_RX_DN<12>")
	)
	(segment
		(start 124.953776 -291.584888)
		(end 124.952506 -291.584126)
		(width 0.1143)
		(layer "In4.Cu")
		(net "P5E_CPU1_P3_RX_DN<12>")
	)
	(segment
		(start 124.957586 -294.826944)
		(end 124.956062 -294.826182)
		(width 0.1143)
		(layer "In4.Cu")
		(net "P5E_CPU1_P3_RX_DN<12>")
	)
	(segment
		(start 131.31165 -378.373386)
		(end 131.311396 -378.373132)
		(width 0.14224)
		(layer "In4.Cu")
		(net "P5E_CPU1_P3_RX_DN<12>")
	)
	(segment
		(start 124.96292 -288.981642)
		(end 124.963682 -288.981642)
		(width 0.1143)
		(layer "In4.Cu")
		(net "P5E_CPU1_P3_RX_DN<12>")
	)
	(segment
		(start 124.96165 -288.982912)
		(end 124.96292 -288.981642)
		(width 0.1143)
		(layer "In4.Cu")
		(net "P5E_CPU1_P3_RX_DN<12>")
	)
	(segment
		(start 131.132072 -378.447808)
		(end 131.31165 -378.373386)
		(width 0.14224)
		(layer "In4.Cu")
		(net "P5E_CPU1_P3_RX_DN<12>")
	)
	(segment
		(start 124.948188 -288.990786)
		(end 124.949204 -288.990278)
		(width 0.1143)
		(layer "In4.Cu")
		(net "P5E_CPU1_P3_RX_DN<12>")
	)
	(segment
		(start 124.887228 -293.86911)
		(end 124.953522 -293.847266)
		(width 0.1143)
		(layer "In4.Cu")
		(net "P5E_CPU1_P3_RX_DN<12>")
	)
	(segment
		(start 137.214356 -314.570618)
		(end 135.472678 -311.312306)
		(width 0.14224)
		(layer "In4.Cu")
		(net "P5E_CPU1_P3_RX_DN<12>")
	)
	(segment
		(start 124.623576 -296.928032)
		(end 124.623576 -296.439844)
		(width 0.14224)
		(layer "In4.Cu")
		(net "P5E_CPU1_P3_RX_DN<12>")
	)
	(segment
		(start 130.105404 -380.92634)
		(end 130.268726 -380.531878)
		(width 0.14224)
		(layer "In4.Cu")
		(net "P5E_CPU1_P3_RX_DN<12>")
	)
	(segment
		(start 124.957078 -293.845742)
		(end 124.983494 -293.830502)
		(width 0.1143)
		(layer "In4.Cu")
		(net "P5E_CPU1_P3_RX_DN<12>")
	)
	(segment
		(start 130.53695 -379.884432)
		(end 130.700272 -379.48997)
		(width 0.14224)
		(layer "In4.Cu")
		(net "P5E_CPU1_P3_RX_DN<12>")
	)
	(segment
		(start 124.9426 -288.994088)
		(end 124.948188 -288.990786)
		(width 0.1143)
		(layer "In4.Cu")
		(net "P5E_CPU1_P3_RX_DN<12>")
	)
	(segment
		(start 124.958094 -288.985198)
		(end 124.958856 -288.98469)
		(width 0.1143)
		(layer "In4.Cu")
		(net "P5E_CPU1_P3_RX_DN<12>")
	)
	(segment
		(start 125.602492 -287.926272)
		(end 125.532642 -287.856422)
		(width 0.1143)
		(layer "In4.Cu")
		(net "P5E_CPU1_P3_RX_DN<12>")
	)
	(segment
		(start 130.87985 -379.415548)
		(end 131.042918 -379.02134)
		(width 0.14224)
		(layer "In4.Cu")
		(net "P5E_CPU1_P3_RX_DN<12>")
	)
	(segment
		(start 129.766568 -385.334764)
		(end 129.766568 -385.163822)
		(width 0.14224)
		(layer "In4.Cu")
		(net "P5E_CPU1_P3_RX_DN<12>")
	)
	(segment
		(start 125.240288 -298.59605)
		(end 124.69241 -297.274488)
		(width 0.14224)
		(layer "In4.Cu")
		(net "P5E_CPU1_P3_RX_DN<12>")
	)
	(segment
		(start 130.96875 -378.84227)
		(end 131.132072 -378.447808)
		(width 0.14224)
		(layer "In4.Cu")
		(net "P5E_CPU1_P3_RX_DN<12>")
	)
	(segment
		(start 124.512324 -290.791392)
		(end 124.471684 -290.76777)
		(width 0.1143)
		(layer "In4.Cu")
		(net "P5E_CPU1_P3_RX_DN<12>")
	)
	(segment
		(start 124.964444 -288.981134)
		(end 124.965968 -288.980372)
		(width 0.1143)
		(layer "In4.Cu")
		(net "P5E_CPU1_P3_RX_DN<12>")
	)
	(segment
		(start 124.912628 -292.251638)
		(end 124.923042 -292.245288)
		(width 0.1143)
		(layer "In4.Cu")
		(net "P5E_CPU1_P3_RX_DN<12>")
	)
	(segment
		(start 130.44805 -380.45771)
		(end 130.611118 -380.063502)
		(width 0.14224)
		(layer "In4.Cu")
		(net "P5E_CPU1_P3_RX_DN<12>")
	)
	(segment
		(start 130.700272 -379.48997)
		(end 130.87985 -379.415548)
		(width 0.14224)
		(layer "In4.Cu")
		(net "P5E_CPU1_P3_RX_DN<12>")
	)
	(segment
		(start 143.362172 -336.65668)
		(end 141.730476 -327.573132)
		(width 0.14224)
		(layer "In4.Cu")
		(net "P5E_CPU1_P3_RX_DN<12>")
	)
	(segment
		(start 129.291334 -385.31038)
		(end 129.644394 -385.405376)
		(width 0.14224)
		(layer "In4.Cu")
		(net "P5E_CPU1_P3_RX_DN<12>")
	)
	(segment
		(start 138.163808 -363.776006)
		(end 141.990826 -361.218988)
		(width 0.14224)
		(layer "In4.Cu")
		(net "P5E_CPU1_P3_RX_DN<12>")
	)
	(segment
		(start 124.956062 -288.986214)
		(end 124.958094 -288.985198)
		(width 0.1143)
		(layer "In4.Cu")
		(net "P5E_CPU1_P3_RX_DN<12>")
	)
	(segment
		(start 124.941076 -288.995104)
		(end 124.9426 -288.994088)
		(width 0.1143)
		(layer "In4.Cu")
		(net "P5E_CPU1_P3_RX_DN<12>")
	)
	(segment
		(start 129.940304 -381.683514)
		(end 130.179572 -381.10541)
		(width 0.14224)
		(layer "In4.Cu")
		(net "P5E_CPU1_P3_RX_DN<12>")
	)
	(segment
		(start 124.912374 -289.011868)
		(end 124.941076 -288.995104)
		(width 0.1143)
		(layer "In4.Cu")
		(net "P5E_CPU1_P3_RX_DN<12>")
	)
	(segment
		(start 124.950728 -293.203122)
		(end 124.912628 -293.18077)
		(width 0.1143)
		(layer "In4.Cu")
		(net "P5E_CPU1_P3_RX_DN<12>")
	)
	(segment
		(start 143.362172 -358.653334)
		(end 143.362172 -336.65668)
		(width 0.14224)
		(layer "In4.Cu")
		(net "P5E_CPU1_P3_RX_DN<12>")
	)
	(segment
		(start 124.952506 -292.228016)
		(end 124.952506 -292.22827)
		(width 0.1143)
		(layer "In4.Cu")
		(net "P5E_CPU1_P3_RX_DN<12>")
	)
	(segment
		(start 124.944378 -294.818816)
		(end 124.93371 -294.811704)
		(width 0.1143)
		(layer "In4.Cu")
		(net "P5E_CPU1_P3_RX_DN<12>")
	)
	(segment
		(start 124.952506 -292.22827)
		(end 124.953776 -292.227508)
		(width 0.1143)
		(layer "In4.Cu")
		(net "P5E_CPU1_P3_RX_DN<12>")
	)
	(segment
		(start 124.963682 -288.981642)
		(end 124.964444 -288.981134)
		(width 0.1143)
		(layer "In4.Cu")
		(net "P5E_CPU1_P3_RX_DN<12>")
	)
	(segment
		(start 124.952506 -291.584126)
		(end 124.951744 -291.583618)
		(width 0.1143)
		(layer "In4.Cu")
		(net "P5E_CPU1_P3_RX_DN<12>")
	)
	(segment
		(start 125.139704 -295.146476)
		(end 125.139704 -295.146222)
		(width 0.1143)
		(layer "In4.Cu")
		(net "P5E_CPU1_P3_RX_DN<12>")
	)
	(segment
		(start 124.955554 -293.846504)
		(end 124.957078 -293.845742)
		(width 0.1143)
		(layer "In4.Cu")
		(net "P5E_CPU1_P3_RX_DN<12>")
	)
	(segment
		(start 130.611118 -380.063502)
		(end 130.53695 -379.884432)
		(width 0.14224)
		(layer "In4.Cu")
		(net "P5E_CPU1_P3_RX_DN<12>")
	)
	(segment
		(start 124.92736 -292.242748)
		(end 124.929138 -292.241732)
		(width 0.1143)
		(layer "In4.Cu")
		(net "P5E_CPU1_P3_RX_DN<12>")
	)
	(segment
		(start 124.949458 -288.990024)
		(end 124.950728 -288.989262)
		(width 0.1143)
		(layer "In4.Cu")
		(net "P5E_CPU1_P3_RX_DN<12>")
	)
	(segment
		(start 124.943362 -291.578538)
		(end 124.935234 -291.573458)
		(width 0.1143)
		(layer "In4.Cu")
		(net "P5E_CPU1_P3_RX_DN<12>")
	)
	(segment
		(start 124.949204 -291.582094)
		(end 124.948188 -291.581586)
		(width 0.1143)
		(layer "In4.Cu")
		(net "P5E_CPU1_P3_RX_DN<12>")
	)
	(segment
		(start 141.730476 -327.573132)
		(end 137.214356 -314.570618)
		(width 0.14224)
		(layer "In4.Cu")
		(net "P5E_CPU1_P3_RX_DN<12>")
	)
	(segment
		(start 124.949204 -288.990278)
		(end 124.949458 -288.990024)
		(width 0.1143)
		(layer "In4.Cu")
		(net "P5E_CPU1_P3_RX_DN<12>")
	)
	(segment
		(start 124.956062 -294.826182)
		(end 124.9553 -294.825674)
		(width 0.1143)
		(layer "In4.Cu")
		(net "P5E_CPU1_P3_RX_DN<12>")
	)
	(segment
		(start 124.957078 -292.22573)
		(end 124.983494 -292.21049)
		(width 0.1143)
		(layer "In4.Cu")
		(net "P5E_CPU1_P3_RX_DN<12>")
	)
	(segment
		(start 124.923042 -292.245288)
		(end 124.925328 -292.244018)
		(width 0.1143)
		(layer "In4.Cu")
		(net "P5E_CPU1_P3_RX_DN<12>")
	)
	(segment
		(start 124.9553 -294.825674)
		(end 124.949458 -294.822372)
		(width 0.1143)
		(layer "In4.Cu")
		(net "P5E_CPU1_P3_RX_DN<12>")
	)
	(segment
		(start 124.887482 -293.884096)
		(end 124.887228 -293.86911)
		(width 0.1143)
		(layer "In4.Cu")
		(net "P5E_CPU1_P3_RX_DN<12>")
	)
	(segment
		(start 124.944632 -291.5793)
		(end 124.943362 -291.578538)
		(width 0.1143)
		(layer "In4.Cu")
		(net "P5E_CPU1_P3_RX_DN<12>")
	)
	(segment
		(start 124.953776 -292.227508)
		(end 124.954538 -292.227254)
		(width 0.1143)
		(layer "In4.Cu")
		(net "P5E_CPU1_P3_RX_DN<12>")
	)
	(segment
		(start 124.949458 -294.822372)
		(end 124.944378 -294.818816)
		(width 0.1143)
		(layer "In4.Cu")
		(net "P5E_CPU1_P3_RX_DN<12>")
	)
	(segment
		(start 124.953776 -288.987484)
		(end 124.9553 -288.986722)
		(width 0.1143)
		(layer "In4.Cu")
		(net "P5E_CPU1_P3_RX_DN<12>")
	)
	(segment
		(start 124.4346 -289.814)
		(end 124.497084 -289.77717)
		(width 0.1143)
		(layer "In4.Cu")
		(net "P5E_CPU1_P3_RX_DN<12>")
	)
	(segment
		(start 124.958348 -294.827452)
		(end 124.957586 -294.826944)
		(width 0.1143)
		(layer "In4.Cu")
		(net "P5E_CPU1_P3_RX_DN<12>")
	)
	(segment
		(start 124.971302 -288.977578)
		(end 124.983494 -288.970466)
		(width 0.1143)
		(layer "In4.Cu")
		(net "P5E_CPU1_P3_RX_DN<12>")
	)
	(segment
		(start 129.449576 -384.84683)
		(end 129.454148 -384.25247)
		(width 0.14224)
		(layer "In4.Cu")
		(net "P5E_CPU1_P3_RX_DN<12>")
	)
	(segment
		(start 134.265924 -368.099594)
		(end 134.385558 -367.74374)
		(width 0.14224)
		(layer "In4.Cu")
		(net "P5E_CPU1_P3_RX_DN<12>")
	)
	(segment
		(start 129.644902 -385.404868)
		(end 129.766568 -385.334764)
		(width 0.14224)
		(layer "In4.Cu")
		(net "P5E_CPU1_P3_RX_DN<12>")
	)
	(arc
		(start 124.471684 -290.76777)
		(mid 124.190872 -290.30106)
		(end 124.4346 -289.814)
		(width 0.1143)
		(layer "In4.Cu")
		(net "P5E_CPU1_P3_RX_DN<12>")
	)
	(arc
		(start 137.683494 -364.170214)
		(mid 137.86041 -364.018826)
		(end 138.03884 -363.869224)
		(width 0.14224)
		(layer "In4.Cu")
		(net "P5E_CPU1_P3_RX_DN<12>")
	)
	(arc
		(start 125.139704 -288.666428)
		(mid 125.19274 -288.427233)
		(end 125.341888 -288.23285)
		(width 0.1143)
		(layer "In4.Cu")
		(net "P5E_CPU1_P3_RX_DN<12>")
	)
	(arc
		(start 124.669296 -295.956228)
		(mid 124.669283 -295.952291)
		(end 124.669296 -295.948354)
		(width 0.1143)
		(layer "In4.Cu")
		(net "P5E_CPU1_P3_RX_DN<12>")
	)
	(arc
		(start 134.385558 -367.74374)
		(mid 134.429171 -367.642411)
		(end 134.488936 -367.549684)
		(width 0.14224)
		(layer "In4.Cu")
		(net "P5E_CPU1_P3_RX_DN<12>")
	)
	(arc
		(start 124.910088 -294.797988)
		(mid 124.666296 -294.346834)
		(end 124.887482 -293.884096)
		(width 0.1143)
		(layer "In4.Cu")
		(net "P5E_CPU1_P3_RX_DN<12>")
	)
	(arc
		(start 124.669296 -291.088318)
		(mid 124.625999 -290.921242)
		(end 124.512324 -290.791392)
		(width 0.1143)
		(layer "In4.Cu")
		(net "P5E_CPU1_P3_RX_DN<12>")
	)
	(arc
		(start 124.669804 -289.47618)
		(mid 124.734101 -289.214252)
		(end 124.912374 -289.011868)
		(width 0.1143)
		(layer "In4.Cu")
		(net "P5E_CPU1_P3_RX_DN<12>")
	)
	(arc
		(start 138.03884 -363.869224)
		(mid 138.100114 -363.820993)
		(end 138.163808 -363.776006)
		(width 0.14224)
		(layer "In4.Cu")
		(net "P5E_CPU1_P3_RX_DN<12>")
	)
	(arc
		(start 133.264148 -373.658892)
		(mid 133.987039 -371.275602)
		(end 134.231126 -368.797078)
		(width 0.14224)
		(layer "In4.Cu")
		(net "P5E_CPU1_P3_RX_DN<12>")
	)
	(arc
		(start 141.990826 -361.218988)
		(mid 142.997864 -360.107923)
		(end 143.362172 -358.653334)
		(width 0.14224)
		(layer "In4.Cu")
		(net "P5E_CPU1_P3_RX_DN<12>")
	)
	(arc
		(start 124.897896 -295.502076)
		(mid 124.90547 -295.496551)
		(end 124.913136 -295.491154)
		(width 0.1143)
		(layer "In4.Cu")
		(net "P5E_CPU1_P3_RX_DN<12>")
	)
	(arc
		(start 124.983494 -288.970466)
		(mid 125.098337 -288.837318)
		(end 125.139704 -288.666428)
		(width 0.1143)
		(layer "In4.Cu")
		(net "P5E_CPU1_P3_RX_DN<12>")
	)
	(arc
		(start 124.98451 -295.449498)
		(mid 125.098605 -295.316677)
		(end 125.139704 -295.146476)
		(width 0.1143)
		(layer "In4.Cu")
		(net "P5E_CPU1_P3_RX_DN<12>")
	)
	(arc
		(start 129.75844 -382.598168)
		(mid 129.804314 -382.13188)
		(end 129.940304 -381.683514)
		(width 0.14224)
		(layer "In4.Cu")
		(net "P5E_CPU1_P3_RX_DN<12>")
	)
	(arc
		(start 125.341888 -288.23285)
		(mid 125.371687 -288.210048)
		(end 125.403356 -288.189924)
		(width 0.1143)
		(layer "In4.Cu")
		(net "P5E_CPU1_P3_RX_DN<12>")
	)
	(arc
		(start 124.912628 -293.18077)
		(mid 124.669301 -292.716204)
		(end 124.912628 -292.251638)
		(width 0.1143)
		(layer "In4.Cu")
		(net "P5E_CPU1_P3_RX_DN<12>")
	)
	(arc
		(start 124.983494 -293.830502)
		(mid 125.139422 -293.52621)
		(end 124.983494 -293.221918)
		(width 0.1143)
		(layer "In4.Cu")
		(net "P5E_CPU1_P3_RX_DN<12>")
	)
	(arc
		(start 134.488936 -367.549684)
		(mid 136.0011 -365.779491)
		(end 137.683494 -364.170214)
		(width 0.14224)
		(layer "In4.Cu")
		(net "P5E_CPU1_P3_RX_DN<12>")
	)
	(arc
		(start 124.913136 -295.491154)
		(mid 124.913517 -295.4909)
		(end 124.913898 -295.490646)
		(width 0.1143)
		(layer "In4.Cu")
		(net "P5E_CPU1_P3_RX_DN<12>")
	)
	(arc
		(start 124.669296 -295.948354)
		(mid 124.734642 -295.700131)
		(end 124.897896 -295.502076)
		(width 0.1143)
		(layer "In4.Cu")
		(net "P5E_CPU1_P3_RX_DN<12>")
	)
	(arc
		(start 125.139704 -295.146222)
		(mid 125.098364 -294.975207)
		(end 124.983494 -294.84193)
		(width 0.1143)
		(layer "In4.Cu")
		(net "P5E_CPU1_P3_RX_DN<12>")
	)
	(arc
		(start 134.231126 -368.313462)
		(mid 134.239868 -368.20512)
		(end 134.265924 -368.099594)
		(width 0.14224)
		(layer "In4.Cu")
		(net "P5E_CPU1_P3_RX_DN<12>")
	)
	(arc
		(start 125.453394 -288.16046)
		(mid 125.550401 -288.057669)
		(end 125.602492 -287.926272)
		(width 0.1143)
		(layer "In4.Cu")
		(net "P5E_CPU1_P3_RX_DN<12>")
	)
	(arc
		(start 124.69241 -297.274488)
		(mid 124.640896 -297.104655)
		(end 124.623576 -296.928032)
		(width 0.14224)
		(layer "In4.Cu")
		(net "P5E_CPU1_P3_RX_DN<12>")
	)
	(arc
		(start 124.935234 -291.573458)
		(mid 124.742752 -291.363507)
		(end 124.669296 -291.088318)
		(width 0.1143)
		(layer "In4.Cu")
		(net "P5E_CPU1_P3_RX_DN<12>")
	)
	(arc
		(start 124.983494 -292.21049)
		(mid 125.139422 -291.906198)
		(end 124.983494 -291.601906)
		(width 0.1143)
		(layer "In4.Cu")
		(net "P5E_CPU1_P3_RX_DN<12>")
	)
	(arc
		(start 124.497084 -289.77717)
		(mid 124.623521 -289.649668)
		(end 124.669804 -289.47618)
		(width 0.1143)
		(layer "In4.Cu")
		(net "P5E_CPU1_P3_RX_DN<12>")
	)
	(segment
		(start 127.570484 -385.31038)
		(end 128.091184 -385.31038)
		(width 0.127)
		(layer "F.Cu")
		(net "P5E_CPU1_P3_RX_DN<11>")
	)
	(segment
		(start 121.94794 -289.210242)
		(end 122.414792 -289.47618)
		(width 0.12954)
		(layer "F.Cu")
		(net "P5E_CPU1_P3_RX_DN<11>")
	)
	(segment
		(start 128.566672 -385.163822)
		(end 128.24968 -384.84683)
		(width 0.14224)
		(layer "In4.Cu")
		(net "P5E_CPU1_P3_RX_DN<11>")
	)
	(segment
		(start 123.72975 -296.348912)
		(end 123.72975 -295.956228)
		(width 0.1143)
		(layer "In4.Cu")
		(net "P5E_CPU1_P3_RX_DN<11>")
	)
	(segment
		(start 128.785366 -381.644652)
		(end 129.069338 -380.959106)
		(width 0.14224)
		(layer "In4.Cu")
		(net "P5E_CPU1_P3_RX_DN<11>")
	)
	(segment
		(start 124.042424 -291.601398)
		(end 124.011944 -291.583618)
		(width 0.1143)
		(layer "In4.Cu")
		(net "P5E_CPU1_P3_RX_DN<11>")
	)
	(segment
		(start 129.337816 -380.311152)
		(end 129.500884 -379.916944)
		(width 0.14224)
		(layer "In4.Cu")
		(net "P5E_CPU1_P3_RX_DN<11>")
	)
	(segment
		(start 124.042424 -294.841422)
		(end 124.011944 -294.823642)
		(width 0.1143)
		(layer "In4.Cu")
		(net "P5E_CPU1_P3_RX_DN<11>")
	)
	(segment
		(start 136.458198 -315.235844)
		(end 134.537958 -311.644284)
		(width 0.14224)
		(layer "In4.Cu")
		(net "P5E_CPU1_P3_RX_DN<11>")
	)
	(segment
		(start 123.546362 -290.776152)
		(end 123.543822 -290.774882)
		(width 0.1143)
		(layer "In4.Cu")
		(net "P5E_CPU1_P3_RX_DN<11>")
	)
	(segment
		(start 123.972828 -295.491662)
		(end 124.042424 -295.451022)
		(width 0.1143)
		(layer "In4.Cu")
		(net "P5E_CPU1_P3_RX_DN<11>")
	)
	(segment
		(start 125.26391 -300.343062)
		(end 124.436124 -299.125132)
		(width 0.14224)
		(layer "In4.Cu")
		(net "P5E_CPU1_P3_RX_DN<11>")
	)
	(segment
		(start 132.299456 -370.797836)
		(end 132.12953 -370.62791)
		(width 0.14224)
		(layer "In4.Cu")
		(net "P5E_CPU1_P3_RX_DN<11>")
	)
	(segment
		(start 123.543822 -290.774882)
		(end 123.542552 -290.77412)
		(width 0.1143)
		(layer "In4.Cu")
		(net "P5E_CPU1_P3_RX_DN<11>")
	)
	(segment
		(start 123.072398 -289.96386)
		(end 123.071636 -289.963352)
		(width 0.1143)
		(layer "In4.Cu")
		(net "P5E_CPU1_P3_RX_DN<11>")
	)
	(segment
		(start 132.507482 -366.358678)
		(end 141.62532 -360.206798)
		(width 0.14224)
		(layer "In4.Cu")
		(net "P5E_CPU1_P3_RX_DN<11>")
	)
	(segment
		(start 124.436124 -299.125132)
		(end 123.715018 -297.383962)
		(width 0.14224)
		(layer "In4.Cu")
		(net "P5E_CPU1_P3_RX_DN<11>")
	)
	(segment
		(start 124.042424 -293.22141)
		(end 124.011944 -293.20363)
		(width 0.1143)
		(layer "In4.Cu")
		(net "P5E_CPU1_P3_RX_DN<11>")
	)
	(segment
		(start 123.548902 -290.777676)
		(end 123.547886 -290.777168)
		(width 0.1143)
		(layer "In4.Cu")
		(net "P5E_CPU1_P3_RX_DN<11>")
	)
	(segment
		(start 123.68403 -296.394632)
		(end 123.72975 -296.348912)
		(width 0.1143)
		(layer "In4.Cu")
		(net "P5E_CPU1_P3_RX_DN<11>")
	)
	(segment
		(start 131.868164 -370.453158)
		(end 131.86791 -370.453158)
		(width 0.14224)
		(layer "In4.Cu")
		(net "P5E_CPU1_P3_RX_DN<11>")
	)
	(segment
		(start 130.021584 -378.30125)
		(end 130.200908 -378.226828)
		(width 0.14224)
		(layer "In4.Cu")
		(net "P5E_CPU1_P3_RX_DN<11>")
	)
	(segment
		(start 131.410456 -370.230146)
		(end 131.06146 -369.880896)
		(width 0.14224)
		(layer "In4.Cu")
		(net "P5E_CPU1_P3_RX_DN<11>")
	)
	(segment
		(start 131.86791 -370.453158)
		(end 131.620006 -370.350542)
		(width 0.14224)
		(layer "In4.Cu")
		(net "P5E_CPU1_P3_RX_DN<11>")
	)
	(segment
		(start 123.972828 -293.87165)
		(end 124.011944 -293.84879)
		(width 0.1143)
		(layer "In4.Cu")
		(net "P5E_CPU1_P3_RX_DN<11>")
	)
	(segment
		(start 123.542552 -290.77412)
		(end 123.54179 -290.773612)
		(width 0.1143)
		(layer "In4.Cu")
		(net "P5E_CPU1_P3_RX_DN<11>")
	)
	(segment
		(start 123.547886 -290.777168)
		(end 123.546362 -290.776152)
		(width 0.1143)
		(layer "In4.Cu")
		(net "P5E_CPU1_P3_RX_DN<11>")
	)
	(segment
		(start 142.429992 -336.744056)
		(end 140.82395 -327.805288)
		(width 0.14224)
		(layer "In4.Cu")
		(net "P5E_CPU1_P3_RX_DN<11>")
	)
	(segment
		(start 128.25476 -384.192272)
		(end 128.558544 -383.888488)
		(width 0.14224)
		(layer "In4.Cu")
		(net "P5E_CPU1_P3_RX_DN<11>")
	)
	(segment
		(start 129.858262 -378.695712)
		(end 130.021584 -378.30125)
		(width 0.14224)
		(layer "In4.Cu")
		(net "P5E_CPU1_P3_RX_DN<11>")
	)
	(segment
		(start 142.429992 -358.256078)
		(end 142.429992 -336.744056)
		(width 0.14224)
		(layer "In4.Cu")
		(net "P5E_CPU1_P3_RX_DN<11>")
	)
	(segment
		(start 123.68403 -297.227244)
		(end 123.68403 -296.42308)
		(width 0.14224)
		(layer "In4.Cu")
		(net "P5E_CPU1_P3_RX_DN<11>")
	)
	(segment
		(start 128.445006 -385.404868)
		(end 128.566672 -385.334764)
		(width 0.14224)
		(layer "In4.Cu")
		(net "P5E_CPU1_P3_RX_DN<11>")
	)
	(segment
		(start 134.537958 -311.644284)
		(end 125.26391 -300.343062)
		(width 0.14224)
		(layer "In4.Cu")
		(net "P5E_CPU1_P3_RX_DN<11>")
	)
	(segment
		(start 123.075192 -289.965384)
		(end 123.072398 -289.96386)
		(width 0.1143)
		(layer "In4.Cu")
		(net "P5E_CPU1_P3_RX_DN<11>")
	)
	(segment
		(start 122.712734 -289.47618)
		(end 122.414792 -289.47618)
		(width 0.1143)
		(layer "In4.Cu")
		(net "P5E_CPU1_P3_RX_DN<11>")
	)
	(segment
		(start 140.82395 -327.805288)
		(end 136.458198 -315.235844)
		(width 0.14224)
		(layer "In4.Cu")
		(net "P5E_CPU1_P3_RX_DN<11>")
	)
	(segment
		(start 124.011944 -292.228778)
		(end 124.042424 -292.210998)
		(width 0.1143)
		(layer "In4.Cu")
		(net "P5E_CPU1_P3_RX_DN<11>")
	)
	(segment
		(start 129.769362 -379.26899)
		(end 129.93243 -378.874782)
		(width 0.14224)
		(layer "In4.Cu")
		(net "P5E_CPU1_P3_RX_DN<11>")
	)
	(segment
		(start 129.500884 -379.916944)
		(end 129.426716 -379.737874)
		(width 0.14224)
		(layer "In4.Cu")
		(net "P5E_CPU1_P3_RX_DN<11>")
	)
	(segment
		(start 124.011944 -291.583618)
		(end 123.972828 -291.560758)
		(width 0.1143)
		(layer "In4.Cu")
		(net "P5E_CPU1_P3_RX_DN<11>")
	)
	(segment
		(start 129.069338 -380.959106)
		(end 128.994916 -380.779782)
		(width 0.14224)
		(layer "In4.Cu")
		(net "P5E_CPU1_P3_RX_DN<11>")
	)
	(segment
		(start 130.200908 -378.226828)
		(end 132.616956 -372.393718)
		(width 0.14224)
		(layer "In4.Cu")
		(net "P5E_CPU1_P3_RX_DN<11>")
	)
	(segment
		(start 123.071636 -289.963352)
		(end 123.033536 -289.941254)
		(width 0.1143)
		(layer "In4.Cu")
		(net "P5E_CPU1_P3_RX_DN<11>")
	)
	(segment
		(start 128.444498 -385.405376)
		(end 128.445006 -385.404868)
		(width 0.14224)
		(layer "In4.Cu")
		(net "P5E_CPU1_P3_RX_DN<11>")
	)
	(segment
		(start 123.68403 -296.42308)
		(end 123.68403 -296.394632)
		(width 0.1143)
		(layer "In4.Cu")
		(net "P5E_CPU1_P3_RX_DN<11>")
	)
	(segment
		(start 122.795538 -289.558984)
		(end 122.712734 -289.47618)
		(width 0.1143)
		(layer "In4.Cu")
		(net "P5E_CPU1_P3_RX_DN<11>")
	)
	(segment
		(start 128.558544 -383.888488)
		(end 128.558544 -382.78562)
		(width 0.14224)
		(layer "In4.Cu")
		(net "P5E_CPU1_P3_RX_DN<11>")
	)
	(segment
		(start 128.566672 -385.334764)
		(end 128.566672 -385.163822)
		(width 0.14224)
		(layer "In4.Cu")
		(net "P5E_CPU1_P3_RX_DN<11>")
	)
	(segment
		(start 124.011944 -293.84879)
		(end 124.042424 -293.83101)
		(width 0.1143)
		(layer "In4.Cu")
		(net "P5E_CPU1_P3_RX_DN<11>")
	)
	(segment
		(start 142.183104 -359.51922)
		(end 142.183358 -359.518458)
		(width 0.14224)
		(layer "In4.Cu")
		(net "P5E_CPU1_P3_RX_DN<11>")
	)
	(segment
		(start 129.93243 -378.874782)
		(end 129.858262 -378.695712)
		(width 0.14224)
		(layer "In4.Cu")
		(net "P5E_CPU1_P3_RX_DN<11>")
	)
	(segment
		(start 123.972828 -292.251638)
		(end 124.011944 -292.228778)
		(width 0.1143)
		(layer "In4.Cu")
		(net "P5E_CPU1_P3_RX_DN<11>")
	)
	(segment
		(start 124.011944 -293.20363)
		(end 123.972828 -293.18077)
		(width 0.1143)
		(layer "In4.Cu")
		(net "P5E_CPU1_P3_RX_DN<11>")
	)
	(segment
		(start 124.011944 -294.823642)
		(end 123.972828 -294.800782)
		(width 0.1143)
		(layer "In4.Cu")
		(net "P5E_CPU1_P3_RX_DN<11>")
	)
	(segment
		(start 130.855466 -368.723164)
		(end 130.857498 -368.715036)
		(width 0.14224)
		(layer "In4.Cu")
		(net "P5E_CPU1_P3_RX_DN<11>")
	)
	(segment
		(start 128.091184 -385.31038)
		(end 128.444498 -385.405376)
		(width 0.14224)
		(layer "In4.Cu")
		(net "P5E_CPU1_P3_RX_DN<11>")
	)
	(segment
		(start 129.426716 -379.737874)
		(end 129.590038 -379.343412)
		(width 0.14224)
		(layer "In4.Cu")
		(net "P5E_CPU1_P3_RX_DN<11>")
	)
	(segment
		(start 123.54179 -290.773612)
		(end 123.531884 -290.767516)
		(width 0.1143)
		(layer "In4.Cu")
		(net "P5E_CPU1_P3_RX_DN<11>")
	)
	(segment
		(start 129.590038 -379.343412)
		(end 129.769362 -379.26899)
		(width 0.14224)
		(layer "In4.Cu")
		(net "P5E_CPU1_P3_RX_DN<11>")
	)
	(segment
		(start 129.158238 -380.38532)
		(end 129.337816 -380.311152)
		(width 0.14224)
		(layer "In4.Cu")
		(net "P5E_CPU1_P3_RX_DN<11>")
	)
	(segment
		(start 123.57354 -290.7919)
		(end 123.548902 -290.777676)
		(width 0.1143)
		(layer "In4.Cu")
		(net "P5E_CPU1_P3_RX_DN<11>")
	)
	(segment
		(start 128.24968 -384.84683)
		(end 128.25476 -384.192272)
		(width 0.14224)
		(layer "In4.Cu")
		(net "P5E_CPU1_P3_RX_DN<11>")
	)
	(segment
		(start 128.994916 -380.779782)
		(end 129.158238 -380.38532)
		(width 0.14224)
		(layer "In4.Cu")
		(net "P5E_CPU1_P3_RX_DN<11>")
	)
	(arc
		(start 130.819906 -369.365784)
		(mid 130.814086 -369.043169)
		(end 130.855466 -368.723164)
		(width 0.14224)
		(layer "In4.Cu")
		(net "P5E_CPU1_P3_RX_DN<11>")
	)
	(arc
		(start 141.62532 -360.206798)
		(mid 141.955543 -359.904649)
		(end 142.183104 -359.51922)
		(width 0.14224)
		(layer "In4.Cu")
		(net "P5E_CPU1_P3_RX_DN<11>")
	)
	(arc
		(start 124.042424 -293.83101)
		(mid 124.199401 -293.52621)
		(end 124.042424 -293.22141)
		(width 0.1143)
		(layer "In4.Cu")
		(net "P5E_CPU1_P3_RX_DN<11>")
	)
	(arc
		(start 123.729496 -291.096192)
		(mid 123.688241 -290.925221)
		(end 123.57354 -290.7919)
		(width 0.1143)
		(layer "In4.Cu")
		(net "P5E_CPU1_P3_RX_DN<11>")
	)
	(arc
		(start 123.258834 -290.284154)
		(mid 123.209645 -290.100203)
		(end 123.075192 -289.965384)
		(width 0.1143)
		(layer "In4.Cu")
		(net "P5E_CPU1_P3_RX_DN<11>")
	)
	(arc
		(start 123.972828 -294.800782)
		(mid 123.729501 -294.336216)
		(end 123.972828 -293.87165)
		(width 0.1143)
		(layer "In4.Cu")
		(net "P5E_CPU1_P3_RX_DN<11>")
	)
	(arc
		(start 123.972828 -291.560758)
		(mid 123.794015 -291.358408)
		(end 123.729496 -291.096192)
		(width 0.1143)
		(layer "In4.Cu")
		(net "P5E_CPU1_P3_RX_DN<11>")
	)
	(arc
		(start 123.531884 -290.767516)
		(mid 123.331826 -290.561727)
		(end 123.258834 -290.284154)
		(width 0.1143)
		(layer "In4.Cu")
		(net "P5E_CPU1_P3_RX_DN<11>")
	)
	(arc
		(start 123.72975 -295.956228)
		(mid 123.794124 -295.694024)
		(end 123.972828 -295.491662)
		(width 0.1143)
		(layer "In4.Cu")
		(net "P5E_CPU1_P3_RX_DN<11>")
	)
	(arc
		(start 123.033536 -289.941254)
		(mid 123.033155 -289.941)
		(end 123.032774 -289.940746)
		(width 0.1143)
		(layer "In4.Cu")
		(net "P5E_CPU1_P3_RX_DN<11>")
	)
	(arc
		(start 132.12953 -370.62791)
		(mid 132.007435 -370.527693)
		(end 131.868164 -370.453158)
		(width 0.14224)
		(layer "In4.Cu")
		(net "P5E_CPU1_P3_RX_DN<11>")
	)
	(arc
		(start 124.042424 -295.451022)
		(mid 124.199401 -295.146222)
		(end 124.042424 -294.841422)
		(width 0.1143)
		(layer "In4.Cu")
		(net "P5E_CPU1_P3_RX_DN<11>")
	)
	(arc
		(start 131.620006 -370.350542)
		(mid 131.511326 -370.29714)
		(end 131.410456 -370.230146)
		(width 0.14224)
		(layer "In4.Cu")
		(net "P5E_CPU1_P3_RX_DN<11>")
	)
	(arc
		(start 124.042424 -292.210998)
		(mid 124.199401 -291.906198)
		(end 124.042424 -291.601398)
		(width 0.1143)
		(layer "In4.Cu")
		(net "P5E_CPU1_P3_RX_DN<11>")
	)
	(arc
		(start 142.183358 -359.518458)
		(mid 142.367627 -358.899177)
		(end 142.429992 -358.256078)
		(width 0.14224)
		(layer "In4.Cu")
		(net "P5E_CPU1_P3_RX_DN<11>")
	)
	(arc
		(start 123.032774 -289.940746)
		(mid 122.880787 -289.784238)
		(end 122.799348 -289.581844)
		(width 0.1143)
		(layer "In4.Cu")
		(net "P5E_CPU1_P3_RX_DN<11>")
	)
	(arc
		(start 122.799348 -289.581844)
		(mid 122.797325 -289.570434)
		(end 122.795538 -289.558984)
		(width 0.1143)
		(layer "In4.Cu")
		(net "P5E_CPU1_P3_RX_DN<11>")
	)
	(arc
		(start 132.616956 -372.393718)
		(mid 132.700236 -371.547627)
		(end 132.299456 -370.797836)
		(width 0.14224)
		(layer "In4.Cu")
		(net "P5E_CPU1_P3_RX_DN<11>")
	)
	(arc
		(start 123.972828 -293.18077)
		(mid 123.729501 -292.716204)
		(end 123.972828 -292.251638)
		(width 0.1143)
		(layer "In4.Cu")
		(net "P5E_CPU1_P3_RX_DN<11>")
	)
	(arc
		(start 123.715018 -297.383962)
		(mid 123.691815 -297.307128)
		(end 123.68403 -297.227244)
		(width 0.14224)
		(layer "In4.Cu")
		(net "P5E_CPU1_P3_RX_DN<11>")
	)
	(arc
		(start 131.06146 -369.880896)
		(mid 130.895586 -369.644488)
		(end 130.819906 -369.365784)
		(width 0.14224)
		(layer "In4.Cu")
		(net "P5E_CPU1_P3_RX_DN<11>")
	)
	(arc
		(start 128.558544 -382.78562)
		(mid 128.615781 -382.20397)
		(end 128.785366 -381.644652)
		(width 0.14224)
		(layer "In4.Cu")
		(net "P5E_CPU1_P3_RX_DN<11>")
	)
	(arc
		(start 130.857498 -368.715036)
		(mid 131.468575 -367.387079)
		(end 132.507482 -366.358678)
		(width 0.14224)
		(layer "In4.Cu")
		(net "P5E_CPU1_P3_RX_DN<11>")
	)
	(segment
		(start 121.94794 -290.830254)
		(end 122.414792 -291.096192)
		(width 0.12954)
		(layer "F.Cu")
		(net "P5E_CPU1_P3_RX_DN<10>")
	)
	(segment
		(start 126.370588 -385.31038)
		(end 126.891288 -385.31038)
		(width 0.127)
		(layer "F.Cu")
		(net "P5E_CPU1_P3_RX_DN<10>")
	)
	(segment
		(start 127.491236 -376.562366)
		(end 127.350266 -376.428762)
		(width 0.14224)
		(layer "In4.Cu")
		(net "P5E_CPU1_P3_RX_DN<10>")
	)
	(segment
		(start 139.916916 -328.035666)
		(end 135.71855 -315.950092)
		(width 0.14224)
		(layer "In4.Cu")
		(net "P5E_CPU1_P3_RX_DN<10>")
	)
	(segment
		(start 122.743976 -296.489628)
		(end 122.743976 -296.46118)
		(width 0.1143)
		(layer "In4.Cu")
		(net "P5E_CPU1_P3_RX_DN<10>")
	)
	(segment
		(start 122.795792 -291.178996)
		(end 122.795538 -291.178996)
		(width 0.1143)
		(layer "In4.Cu")
		(net "P5E_CPU1_P3_RX_DN<10>")
	)
	(segment
		(start 127.35306 -383.826512)
		(end 127.35306 -382.32715)
		(width 0.14224)
		(layer "In4.Cu")
		(net "P5E_CPU1_P3_RX_DN<10>")
	)
	(segment
		(start 122.789696 -296.41546)
		(end 122.789696 -295.956228)
		(width 0.1143)
		(layer "In4.Cu")
		(net "P5E_CPU1_P3_RX_DN<10>")
	)
	(segment
		(start 123.070874 -293.203122)
		(end 123.032774 -293.18077)
		(width 0.1143)
		(layer "In4.Cu")
		(net "P5E_CPU1_P3_RX_DN<10>")
	)
	(segment
		(start 127.379984 -377.556268)
		(end 127.368808 -377.129548)
		(width 0.14224)
		(layer "In4.Cu")
		(net "P5E_CPU1_P3_RX_DN<10>")
	)
	(segment
		(start 127.055372 -384.124708)
		(end 127.35306 -383.826512)
		(width 0.14224)
		(layer "In4.Cu")
		(net "P5E_CPU1_P3_RX_DN<10>")
	)
	(segment
		(start 127.47244 -375.861326)
		(end 127.421386 -373.912638)
		(width 0.14224)
		(layer "In4.Cu")
		(net "P5E_CPU1_P3_RX_DN<10>")
	)
	(segment
		(start 123.626372 -299.602652)
		(end 123.611132 -299.579538)
		(width 0.14224)
		(layer "In4.Cu")
		(net "P5E_CPU1_P3_RX_DN<10>")
	)
	(segment
		(start 127.24511 -385.404868)
		(end 127.366776 -385.334764)
		(width 0.14224)
		(layer "In4.Cu")
		(net "P5E_CPU1_P3_RX_DN<10>")
	)
	(segment
		(start 122.712734 -291.096192)
		(end 122.414792 -291.096192)
		(width 0.1143)
		(layer "In4.Cu")
		(net "P5E_CPU1_P3_RX_DN<10>")
	)
	(segment
		(start 127.366776 -385.163822)
		(end 127.049784 -384.84683)
		(width 0.14224)
		(layer "In4.Cu")
		(net "P5E_CPU1_P3_RX_DN<10>")
	)
	(segment
		(start 141.497812 -357.67137)
		(end 141.497812 -336.835242)
		(width 0.14224)
		(layer "In4.Cu")
		(net "P5E_CPU1_P3_RX_DN<10>")
	)
	(segment
		(start 123.03379 -295.4909)
		(end 123.070366 -295.469818)
		(width 0.1143)
		(layer "In4.Cu")
		(net "P5E_CPU1_P3_RX_DN<10>")
	)
	(segment
		(start 123.072398 -291.583618)
		(end 123.033536 -291.561266)
		(width 0.1143)
		(layer "In4.Cu")
		(net "P5E_CPU1_P3_RX_DN<10>")
	)
	(segment
		(start 122.795538 -291.178996)
		(end 122.712734 -291.096192)
		(width 0.1143)
		(layer "In4.Cu")
		(net "P5E_CPU1_P3_RX_DN<10>")
	)
	(segment
		(start 127.761746 -373.060214)
		(end 128.309116 -372.512844)
		(width 0.14224)
		(layer "In4.Cu")
		(net "P5E_CPU1_P3_RX_DN<10>")
	)
	(segment
		(start 123.070366 -295.469818)
		(end 123.07189 -295.468802)
		(width 0.1143)
		(layer "In4.Cu")
		(net "P5E_CPU1_P3_RX_DN<10>")
	)
	(segment
		(start 123.626626 -299.602652)
		(end 123.626372 -299.602652)
		(width 0.14224)
		(layer "In4.Cu")
		(net "P5E_CPU1_P3_RX_DN<10>")
	)
	(segment
		(start 127.434086 -381.169418)
		(end 127.537718 -379.686312)
		(width 0.14224)
		(layer "In4.Cu")
		(net "P5E_CPU1_P3_RX_DN<10>")
	)
	(segment
		(start 123.072652 -294.823896)
		(end 123.07189 -294.823642)
		(width 0.1143)
		(layer "In4.Cu")
		(net "P5E_CPU1_P3_RX_DN<10>")
	)
	(segment
		(start 127.33909 -376.002042)
		(end 127.47244 -375.861326)
		(width 0.14224)
		(layer "In4.Cu")
		(net "P5E_CPU1_P3_RX_DN<10>")
	)
	(segment
		(start 129.236724 -370.875814)
		(end 129.97307 -367.936272)
		(width 0.14224)
		(layer "In4.Cu")
		(net "P5E_CPU1_P3_RX_DN<10>")
	)
	(segment
		(start 131.753864 -365.40821)
		(end 139.638024 -360.139996)
		(width 0.14224)
		(layer "In4.Cu")
		(net "P5E_CPU1_P3_RX_DN<10>")
	)
	(segment
		(start 123.070874 -294.823134)
		(end 123.032774 -294.800782)
		(width 0.1143)
		(layer "In4.Cu")
		(net "P5E_CPU1_P3_RX_DN<10>")
	)
	(segment
		(start 123.07189 -293.20363)
		(end 123.070874 -293.203122)
		(width 0.1143)
		(layer "In4.Cu")
		(net "P5E_CPU1_P3_RX_DN<10>")
	)
	(segment
		(start 141.497812 -336.835242)
		(end 139.916916 -328.035666)
		(width 0.14224)
		(layer "In4.Cu")
		(net "P5E_CPU1_P3_RX_DN<10>")
	)
	(segment
		(start 127.385064 -381.869188)
		(end 127.25781 -381.72263)
		(width 0.14224)
		(layer "In4.Cu")
		(net "P5E_CPU1_P3_RX_DN<10>")
	)
	(segment
		(start 123.084082 -293.210488)
		(end 123.072652 -293.203884)
		(width 0.1143)
		(layer "In4.Cu")
		(net "P5E_CPU1_P3_RX_DN<10>")
	)
	(segment
		(start 122.743976 -297.383708)
		(end 122.743976 -296.489628)
		(width 0.14224)
		(layer "In4.Cu")
		(net "P5E_CPU1_P3_RX_DN<10>")
	)
	(segment
		(start 127.25781 -381.72263)
		(end 127.287528 -381.296672)
		(width 0.14224)
		(layer "In4.Cu")
		(net "P5E_CPU1_P3_RX_DN<10>")
	)
	(segment
		(start 123.07189 -294.823642)
		(end 123.070874 -294.823134)
		(width 0.1143)
		(layer "In4.Cu")
		(net "P5E_CPU1_P3_RX_DN<10>")
	)
	(segment
		(start 123.611132 -299.579538)
		(end 122.782584 -297.578526)
		(width 0.14224)
		(layer "In4.Cu")
		(net "P5E_CPU1_P3_RX_DN<10>")
	)
	(segment
		(start 127.366776 -385.334764)
		(end 127.366776 -385.163822)
		(width 0.14224)
		(layer "In4.Cu")
		(net "P5E_CPU1_P3_RX_DN<10>")
	)
	(segment
		(start 127.553974 -378.949966)
		(end 127.520954 -377.689872)
		(width 0.14224)
		(layer "In4.Cu")
		(net "P5E_CPU1_P3_RX_DN<10>")
	)
	(segment
		(start 122.743976 -296.46118)
		(end 122.789696 -296.41546)
		(width 0.1143)
		(layer "In4.Cu")
		(net "P5E_CPU1_P3_RX_DN<10>")
	)
	(segment
		(start 127.520954 -377.689872)
		(end 127.379984 -377.556268)
		(width 0.14224)
		(layer "In4.Cu")
		(net "P5E_CPU1_P3_RX_DN<10>")
	)
	(segment
		(start 123.084082 -294.8305)
		(end 123.072652 -294.823896)
		(width 0.1143)
		(layer "In4.Cu")
		(net "P5E_CPU1_P3_RX_DN<10>")
	)
	(segment
		(start 124.421138 -300.791626)
		(end 123.626626 -299.602652)
		(width 0.14224)
		(layer "In4.Cu")
		(net "P5E_CPU1_P3_RX_DN<10>")
	)
	(segment
		(start 127.244602 -385.405376)
		(end 127.24511 -385.404868)
		(width 0.14224)
		(layer "In4.Cu")
		(net "P5E_CPU1_P3_RX_DN<10>")
	)
	(segment
		(start 123.072652 -293.203884)
		(end 123.07189 -293.20363)
		(width 0.1143)
		(layer "In4.Cu")
		(net "P5E_CPU1_P3_RX_DN<10>")
	)
	(segment
		(start 127.049784 -384.84683)
		(end 127.055372 -384.124708)
		(width 0.14224)
		(layer "In4.Cu")
		(net "P5E_CPU1_P3_RX_DN<10>")
	)
	(segment
		(start 127.368808 -377.129548)
		(end 127.502412 -376.988832)
		(width 0.14224)
		(layer "In4.Cu")
		(net "P5E_CPU1_P3_RX_DN<10>")
	)
	(segment
		(start 127.287528 -381.296672)
		(end 127.434086 -381.169418)
		(width 0.14224)
		(layer "In4.Cu")
		(net "P5E_CPU1_P3_RX_DN<10>")
	)
	(segment
		(start 123.07189 -295.468802)
		(end 123.08332 -295.462198)
		(width 0.1143)
		(layer "In4.Cu")
		(net "P5E_CPU1_P3_RX_DN<10>")
	)
	(segment
		(start 126.891288 -385.31038)
		(end 127.244602 -385.405376)
		(width 0.14224)
		(layer "In4.Cu")
		(net "P5E_CPU1_P3_RX_DN<10>")
	)
	(segment
		(start 127.491236 -376.566938)
		(end 127.491236 -376.562366)
		(width 0.14224)
		(layer "In4.Cu")
		(net "P5E_CPU1_P3_RX_DN<10>")
	)
	(segment
		(start 135.71855 -315.950092)
		(end 133.583172 -311.955688)
		(width 0.14224)
		(layer "In4.Cu")
		(net "P5E_CPU1_P3_RX_DN<10>")
	)
	(segment
		(start 127.350266 -376.428762)
		(end 127.33909 -376.002042)
		(width 0.14224)
		(layer "In4.Cu")
		(net "P5E_CPU1_P3_RX_DN<10>")
	)
	(segment
		(start 127.35306 -382.32715)
		(end 127.385064 -381.869188)
		(width 0.14224)
		(layer "In4.Cu")
		(net "P5E_CPU1_P3_RX_DN<10>")
	)
	(segment
		(start 123.032774 -292.251638)
		(end 123.072398 -292.228524)
		(width 0.1143)
		(layer "In4.Cu")
		(net "P5E_CPU1_P3_RX_DN<10>")
	)
	(segment
		(start 127.502412 -376.988832)
		(end 127.491236 -376.566938)
		(width 0.14224)
		(layer "In4.Cu")
		(net "P5E_CPU1_P3_RX_DN<10>")
	)
	(segment
		(start 123.032774 -293.87165)
		(end 123.08332 -293.842186)
		(width 0.1143)
		(layer "In4.Cu")
		(net "P5E_CPU1_P3_RX_DN<10>")
	)
	(segment
		(start 133.583172 -311.955688)
		(end 124.421138 -300.791626)
		(width 0.14224)
		(layer "In4.Cu")
		(net "P5E_CPU1_P3_RX_DN<10>")
	)
	(arc
		(start 139.638024 -360.139996)
		(mid 140.149471 -359.785111)
		(end 140.648182 -359.41254)
		(width 0.14224)
		(layer "In4.Cu")
		(net "P5E_CPU1_P3_RX_DN<10>")
	)
	(arc
		(start 123.032774 -294.800782)
		(mid 122.789447 -294.336216)
		(end 123.032774 -293.87165)
		(width 0.1143)
		(layer "In4.Cu")
		(net "P5E_CPU1_P3_RX_DN<10>")
	)
	(arc
		(start 141.486128 -357.797608)
		(mid 141.494863 -357.734757)
		(end 141.497812 -357.67137)
		(width 0.14224)
		(layer "In4.Cu")
		(net "P5E_CPU1_P3_RX_DN<10>")
	)
	(arc
		(start 140.740892 -359.32618)
		(mid 141.217486 -358.612584)
		(end 141.486128 -357.797608)
		(width 0.14224)
		(layer "In4.Cu")
		(net "P5E_CPU1_P3_RX_DN<10>")
	)
	(arc
		(start 128.309116 -372.512844)
		(mid 128.884096 -371.757322)
		(end 129.236724 -370.875814)
		(width 0.14224)
		(layer "In4.Cu")
		(net "P5E_CPU1_P3_RX_DN<10>")
	)
	(arc
		(start 123.08332 -293.842186)
		(mid 123.25827 -293.5266)
		(end 123.084082 -293.210488)
		(width 0.1143)
		(layer "In4.Cu")
		(net "P5E_CPU1_P3_RX_DN<10>")
	)
	(arc
		(start 123.033536 -291.561266)
		(mid 122.87498 -291.394818)
		(end 122.795792 -291.178996)
		(width 0.1143)
		(layer "In4.Cu")
		(net "P5E_CPU1_P3_RX_DN<10>")
	)
	(arc
		(start 122.782584 -297.578526)
		(mid 122.753666 -297.48302)
		(end 122.743976 -297.383708)
		(width 0.14224)
		(layer "In4.Cu")
		(net "P5E_CPU1_P3_RX_DN<10>")
	)
	(arc
		(start 127.421386 -373.912638)
		(mid 127.503852 -373.451399)
		(end 127.761746 -373.060214)
		(width 0.14224)
		(layer "In4.Cu")
		(net "P5E_CPU1_P3_RX_DN<10>")
	)
	(arc
		(start 140.648182 -359.41254)
		(mid 140.696559 -359.371531)
		(end 140.740892 -359.32618)
		(width 0.14224)
		(layer "In4.Cu")
		(net "P5E_CPU1_P3_RX_DN<10>")
	)
	(arc
		(start 122.789696 -295.956228)
		(mid 122.854418 -295.693489)
		(end 123.03379 -295.4909)
		(width 0.1143)
		(layer "In4.Cu")
		(net "P5E_CPU1_P3_RX_DN<10>")
	)
	(arc
		(start 123.032774 -293.18077)
		(mid 122.789447 -292.716204)
		(end 123.032774 -292.251638)
		(width 0.1143)
		(layer "In4.Cu")
		(net "P5E_CPU1_P3_RX_DN<10>")
	)
	(arc
		(start 123.072398 -292.228524)
		(mid 123.257816 -291.906134)
		(end 123.072398 -291.583618)
		(width 0.1143)
		(layer "In4.Cu")
		(net "P5E_CPU1_P3_RX_DN<10>")
	)
	(arc
		(start 129.97307 -367.936272)
		(mid 130.628172 -366.506499)
		(end 131.753864 -365.40821)
		(width 0.14224)
		(layer "In4.Cu")
		(net "P5E_CPU1_P3_RX_DN<10>")
	)
	(arc
		(start 127.537718 -379.686312)
		(mid 127.554693 -379.318334)
		(end 127.553974 -378.949966)
		(width 0.14224)
		(layer "In4.Cu")
		(net "P5E_CPU1_P3_RX_DN<10>")
	)
	(arc
		(start 123.08332 -295.462198)
		(mid 123.25827 -295.146612)
		(end 123.084082 -294.8305)
		(width 0.1143)
		(layer "In4.Cu")
		(net "P5E_CPU1_P3_RX_DN<10>")
	)
	(segment
		(start 113.957862 -286.780478)
		(end 114.424714 -287.046162)
		(width 0.12954)
		(layer "F.Cu")
		(net "P5E_CPU1_P3_RX_DN<0>")
	)
	(segment
		(start 114.370612 -385.31038)
		(end 114.891312 -385.31038)
		(width 0.127)
		(layer "F.Cu")
		(net "P5E_CPU1_P3_RX_DN<0>")
	)
	(segment
		(start 113.021618 -289.548316)
		(end 113.021618 -289.54857)
		(width 0.1143)
		(layer "In4.Cu")
		(net "P5E_CPU1_P3_RX_DN<0>")
	)
	(segment
		(start 114.107976 -288.198306)
		(end 114.10823 -288.198052)
		(width 0.1143)
		(layer "In4.Cu")
		(net "P5E_CPU1_P3_RX_DN<0>")
	)
	(segment
		(start 115.107466 -303.743106)
		(end 113.709958 -300.375066)
		(width 0.14224)
		(layer "In4.Cu")
		(net "P5E_CPU1_P3_RX_DN<0>")
	)
	(segment
		(start 113.671604 -288.989008)
		(end 113.671858 -288.988754)
		(width 0.1143)
		(layer "In4.Cu")
		(net "P5E_CPU1_P3_RX_DN<0>")
	)
	(segment
		(start 131.258818 -352.839528)
		(end 131.482846 -352.298)
		(width 0.14224)
		(layer "In4.Cu")
		(net "P5E_CPU1_P3_RX_DN<0>")
	)
	(segment
		(start 128.993646 -325.513192)
		(end 128.993392 -325.513192)
		(width 0.14224)
		(layer "In4.Cu")
		(net "P5E_CPU1_P3_RX_DN<0>")
	)
	(segment
		(start 132.16509 -337.744816)
		(end 131.012184 -331.325474)
		(width 0.14224)
		(layer "In4.Cu")
		(net "P5E_CPU1_P3_RX_DN<0>")
	)
	(segment
		(start 114.102134 -288.202116)
		(end 114.103658 -288.201354)
		(width 0.1143)
		(layer "In4.Cu")
		(net "P5E_CPU1_P3_RX_DN<0>")
	)
	(segment
		(start 113.128552 -380.285498)
		(end 112.949228 -380.359666)
		(width 0.14224)
		(layer "In4.Cu")
		(net "P5E_CPU1_P3_RX_DN<0>")
	)
	(segment
		(start 115.3668 -385.334764)
		(end 115.3668 -385.163822)
		(width 0.14224)
		(layer "In4.Cu")
		(net "P5E_CPU1_P3_RX_DN<0>")
	)
	(segment
		(start 112.6744 -296.000932)
		(end 112.6744 -290.159694)
		(width 0.14224)
		(layer "In4.Cu")
		(net "P5E_CPU1_P3_RX_DN<0>")
	)
	(segment
		(start 114.10823 -288.198052)
		(end 114.141758 -288.178494)
		(width 0.1143)
		(layer "In4.Cu")
		(net "P5E_CPU1_P3_RX_DN<0>")
	)
	(segment
		(start 113.143792 -298.510706)
		(end 112.703864 -296.300144)
		(width 0.14224)
		(layer "In4.Cu")
		(net "P5E_CPU1_P3_RX_DN<0>")
	)
	(segment
		(start 115.324128 -382.100074)
		(end 115.267994 -381.889508)
		(width 0.14224)
		(layer "In4.Cu")
		(net "P5E_CPU1_P3_RX_DN<0>")
	)
	(segment
		(start 114.10442 -288.200338)
		(end 114.107976 -288.198306)
		(width 0.1143)
		(layer "In4.Cu")
		(net "P5E_CPU1_P3_RX_DN<0>")
	)
	(segment
		(start 116.602256 -362.915962)
		(end 130.49631 -353.64039)
		(width 0.14224)
		(layer "In4.Cu")
		(net "P5E_CPU1_P3_RX_DN<0>")
	)
	(segment
		(start 125.453394 -316.85357)
		(end 116.915438 -306.449222)
		(width 0.14224)
		(layer "In4.Cu")
		(net "P5E_CPU1_P3_RX_DN<0>")
	)
	(segment
		(start 113.021618 -289.54857)
		(end 113.041684 -289.528504)
		(width 0.1143)
		(layer "In4.Cu")
		(net "P5E_CPU1_P3_RX_DN<0>")
	)
	(segment
		(start 115.187476 -363.67212)
		(end 115.187222 -363.67212)
		(width 0.14224)
		(layer "In4.Cu")
		(net "P5E_CPU1_P3_RX_DN<0>")
	)
	(segment
		(start 111.438436 -379.58522)
		(end 107.525566 -377.9647)
		(width 0.14224)
		(layer "In4.Cu")
		(net "P5E_CPU1_P3_RX_DN<0>")
	)
	(segment
		(start 111.512858 -379.764544)
		(end 111.438436 -379.58522)
		(width 0.14224)
		(layer "In4.Cu")
		(net "P5E_CPU1_P3_RX_DN<0>")
	)
	(segment
		(start 114.103658 -288.201354)
		(end 114.10442 -288.200338)
		(width 0.1143)
		(layer "In4.Cu")
		(net "P5E_CPU1_P3_RX_DN<0>")
	)
	(segment
		(start 112.554766 -380.196344)
		(end 112.480598 -380.016766)
		(width 0.14224)
		(layer "In4.Cu")
		(net "P5E_CPU1_P3_RX_DN<0>")
	)
	(segment
		(start 114.527076 -287.440116)
		(end 114.527076 -287.439608)
		(width 0.1143)
		(layer "In4.Cu")
		(net "P5E_CPU1_P3_RX_DN<0>")
	)
	(segment
		(start 114.527076 -287.439608)
		(end 114.527838 -287.4391)
		(width 0.1143)
		(layer "In4.Cu")
		(net "P5E_CPU1_P3_RX_DN<0>")
	)
	(segment
		(start 115.049808 -384.84683)
		(end 115.059206 -383.657094)
		(width 0.14224)
		(layer "In4.Cu")
		(net "P5E_CPU1_P3_RX_DN<0>")
	)
	(segment
		(start 113.041684 -289.528504)
		(end 113.105692 -289.528504)
		(width 0.1143)
		(layer "In4.Cu")
		(net "P5E_CPU1_P3_RX_DN<0>")
	)
	(segment
		(start 112.6744 -290.159694)
		(end 112.839754 -289.760406)
		(width 0.14224)
		(layer "In4.Cu")
		(net "P5E_CPU1_P3_RX_DN<0>")
	)
	(segment
		(start 114.329718 -287.853882)
		(end 114.329972 -287.852866)
		(width 0.1143)
		(layer "In4.Cu")
		(net "P5E_CPU1_P3_RX_DN<0>")
	)
	(segment
		(start 114.10061 -288.203132)
		(end 114.102134 -288.202116)
		(width 0.1143)
		(layer "In4.Cu")
		(net "P5E_CPU1_P3_RX_DN<0>")
	)
	(segment
		(start 114.722656 -287.046162)
		(end 114.424714 -287.046162)
		(width 0.1143)
		(layer "In4.Cu")
		(net "P5E_CPU1_P3_RX_DN<0>")
	)
	(segment
		(start 113.85931 -288.666174)
		(end 113.859564 -288.666174)
		(width 0.1143)
		(layer "In4.Cu")
		(net "P5E_CPU1_P3_RX_DN<0>")
	)
	(segment
		(start 113.105692 -289.528504)
		(end 113.556288 -289.077908)
		(width 0.1143)
		(layer "In4.Cu")
		(net "P5E_CPU1_P3_RX_DN<0>")
	)
	(segment
		(start 113.671858 -288.988754)
		(end 113.702338 -288.970974)
		(width 0.1143)
		(layer "In4.Cu")
		(net "P5E_CPU1_P3_RX_DN<0>")
	)
	(segment
		(start 112.839754 -289.73018)
		(end 113.021618 -289.548316)
		(width 0.14224)
		(layer "In4.Cu")
		(net "P5E_CPU1_P3_RX_DN<0>")
	)
	(segment
		(start 113.473992 -364.381796)
		(end 115.187476 -363.67212)
		(width 0.14224)
		(layer "In4.Cu")
		(net "P5E_CPU1_P3_RX_DN<0>")
	)
	(segment
		(start 115.358672 -382.45796)
		(end 115.358418 -382.458214)
		(width 0.14224)
		(layer "In4.Cu")
		(net "P5E_CPU1_P3_RX_DN<0>")
	)
	(segment
		(start 112.839754 -289.760406)
		(end 112.839754 -289.73018)
		(width 0.14224)
		(layer "In4.Cu")
		(net "P5E_CPU1_P3_RX_DN<0>")
	)
	(segment
		(start 112.949228 -380.359666)
		(end 112.554766 -380.196344)
		(width 0.14224)
		(layer "In4.Cu")
		(net "P5E_CPU1_P3_RX_DN<0>")
	)
	(segment
		(start 112.480598 -380.016766)
		(end 112.08639 -379.853698)
		(width 0.14224)
		(layer "In4.Cu")
		(net "P5E_CPU1_P3_RX_DN<0>")
	)
	(segment
		(start 128.993392 -325.513192)
		(end 126.975362 -319.701672)
		(width 0.14224)
		(layer "In4.Cu")
		(net "P5E_CPU1_P3_RX_DN<0>")
	)
	(segment
		(start 107.891072 -370.064792)
		(end 109.518958 -367.627916)
		(width 0.14224)
		(layer "In4.Cu")
		(net "P5E_CPU1_P3_RX_DN<0>")
	)
	(segment
		(start 114.527838 -287.4391)
		(end 114.636296 -287.361376)
		(width 0.1143)
		(layer "In4.Cu")
		(net "P5E_CPU1_P3_RX_DN<0>")
	)
	(segment
		(start 114.141758 -288.178494)
		(end 114.142774 -288.177986)
		(width 0.1143)
		(layer "In4.Cu")
		(net "P5E_CPU1_P3_RX_DN<0>")
	)
	(segment
		(start 115.244626 -385.405376)
		(end 115.245134 -385.404868)
		(width 0.14224)
		(layer "In4.Cu")
		(net "P5E_CPU1_P3_RX_DN<0>")
	)
	(segment
		(start 115.059206 -383.657094)
		(end 115.358672 -383.357882)
		(width 0.14224)
		(layer "In4.Cu")
		(net "P5E_CPU1_P3_RX_DN<0>")
	)
	(segment
		(start 130.49631 -353.64039)
		(end 131.181094 -352.95586)
		(width 0.14224)
		(layer "In4.Cu")
		(net "P5E_CPU1_P3_RX_DN<0>")
	)
	(segment
		(start 106.973624 -377.138946)
		(end 106.973624 -373.08917)
		(width 0.14224)
		(layer "In4.Cu")
		(net "P5E_CPU1_P3_RX_DN<0>")
	)
	(segment
		(start 114.891312 -385.31038)
		(end 115.244626 -385.405376)
		(width 0.14224)
		(layer "In4.Cu")
		(net "P5E_CPU1_P3_RX_DN<0>")
	)
	(segment
		(start 112.08639 -379.853698)
		(end 111.90732 -379.927866)
		(width 0.14224)
		(layer "In4.Cu")
		(net "P5E_CPU1_P3_RX_DN<0>")
	)
	(segment
		(start 115.3668 -385.163822)
		(end 115.049808 -384.84683)
		(width 0.14224)
		(layer "In4.Cu")
		(net "P5E_CPU1_P3_RX_DN<0>")
	)
	(segment
		(start 116.915438 -306.449222)
		(end 115.107466 -303.743106)
		(width 0.14224)
		(layer "In4.Cu")
		(net "P5E_CPU1_P3_RX_DN<0>")
	)
	(segment
		(start 132.164836 -348.864174)
		(end 132.16509 -337.744816)
		(width 0.14224)
		(layer "In4.Cu")
		(net "P5E_CPU1_P3_RX_DN<0>")
	)
	(segment
		(start 131.012184 -331.325474)
		(end 128.993646 -325.513192)
		(width 0.14224)
		(layer "In4.Cu")
		(net "P5E_CPU1_P3_RX_DN<0>")
	)
	(segment
		(start 115.245134 -385.404868)
		(end 115.3668 -385.334764)
		(width 0.14224)
		(layer "In4.Cu")
		(net "P5E_CPU1_P3_RX_DN<0>")
	)
	(segment
		(start 114.79276 -287.116266)
		(end 114.722656 -287.046162)
		(width 0.1143)
		(layer "In4.Cu")
		(net "P5E_CPU1_P3_RX_DN<0>")
	)
	(segment
		(start 114.329972 -287.852866)
		(end 114.329972 -287.852612)
		(width 0.1143)
		(layer "In4.Cu")
		(net "P5E_CPU1_P3_RX_DN<0>")
	)
	(segment
		(start 126.975362 -319.701672)
		(end 125.453394 -316.85357)
		(width 0.14224)
		(layer "In4.Cu")
		(net "P5E_CPU1_P3_RX_DN<0>")
	)
	(segment
		(start 111.90732 -379.927866)
		(end 111.512858 -379.764544)
		(width 0.14224)
		(layer "In4.Cu")
		(net "P5E_CPU1_P3_RX_DN<0>")
	)
	(segment
		(start 107.525566 -377.9647)
		(end 107.525312 -377.9647)
		(width 0.14224)
		(layer "In4.Cu")
		(net "P5E_CPU1_P3_RX_DN<0>")
	)
	(segment
		(start 114.285014 -380.764288)
		(end 113.128552 -380.285498)
		(width 0.14224)
		(layer "In4.Cu")
		(net "P5E_CPU1_P3_RX_DN<0>")
	)
	(segment
		(start 115.358672 -383.357882)
		(end 115.358672 -382.45796)
		(width 0.14224)
		(layer "In4.Cu")
		(net "P5E_CPU1_P3_RX_DN<0>")
	)
	(arc
		(start 113.702338 -288.970974)
		(mid 113.817765 -288.837598)
		(end 113.85931 -288.666174)
		(width 0.1143)
		(layer "In4.Cu")
		(net "P5E_CPU1_P3_RX_DN<0>")
	)
	(arc
		(start 131.181094 -352.95586)
		(mid 131.225714 -352.901538)
		(end 131.258818 -352.839528)
		(width 0.14224)
		(layer "In4.Cu")
		(net "P5E_CPU1_P3_RX_DN<0>")
	)
	(arc
		(start 115.349782 -382.27889)
		(mid 115.339096 -382.189175)
		(end 115.324128 -382.100074)
		(width 0.14224)
		(layer "In4.Cu")
		(net "P5E_CPU1_P3_RX_DN<0>")
	)
	(arc
		(start 115.187222 -363.67212)
		(mid 115.913279 -363.328734)
		(end 116.602256 -362.915962)
		(width 0.14224)
		(layer "In4.Cu")
		(net "P5E_CPU1_P3_RX_DN<0>")
	)
	(arc
		(start 114.329972 -287.852612)
		(mid 114.346555 -287.71726)
		(end 114.395504 -287.589976)
		(width 0.1143)
		(layer "In4.Cu")
		(net "P5E_CPU1_P3_RX_DN<0>")
	)
	(arc
		(start 114.636296 -287.361376)
		(mid 114.738118 -287.253879)
		(end 114.79276 -287.116266)
		(width 0.1143)
		(layer "In4.Cu")
		(net "P5E_CPU1_P3_RX_DN<0>")
	)
	(arc
		(start 131.482846 -352.298)
		(mid 131.992775 -350.614636)
		(end 132.164836 -348.864174)
		(width 0.14224)
		(layer "In4.Cu")
		(net "P5E_CPU1_P3_RX_DN<0>")
	)
	(arc
		(start 114.395504 -287.589976)
		(mid 114.452754 -287.507555)
		(end 114.527076 -287.440116)
		(width 0.1143)
		(layer "In4.Cu")
		(net "P5E_CPU1_P3_RX_DN<0>")
	)
	(arc
		(start 107.525312 -377.9647)
		(mid 107.124234 -377.635492)
		(end 106.973624 -377.138946)
		(width 0.14224)
		(layer "In4.Cu")
		(net "P5E_CPU1_P3_RX_DN<0>")
	)
	(arc
		(start 113.709958 -300.375066)
		(mid 113.380955 -299.45683)
		(end 113.143792 -298.510706)
		(width 0.14224)
		(layer "In4.Cu")
		(net "P5E_CPU1_P3_RX_DN<0>")
	)
	(arc
		(start 114.142774 -288.177986)
		(mid 114.279641 -288.040962)
		(end 114.329718 -287.853882)
		(width 0.1143)
		(layer "In4.Cu")
		(net "P5E_CPU1_P3_RX_DN<0>")
	)
	(arc
		(start 113.556288 -289.077908)
		(mid 113.611061 -289.029716)
		(end 113.671604 -288.989008)
		(width 0.1143)
		(layer "In4.Cu")
		(net "P5E_CPU1_P3_RX_DN<0>")
	)
	(arc
		(start 113.859564 -288.666174)
		(mid 113.92337 -288.405121)
		(end 114.10061 -288.203132)
		(width 0.1143)
		(layer "In4.Cu")
		(net "P5E_CPU1_P3_RX_DN<0>")
	)
	(arc
		(start 115.358418 -382.458214)
		(mid 115.356232 -382.368449)
		(end 115.349782 -382.27889)
		(width 0.14224)
		(layer "In4.Cu")
		(net "P5E_CPU1_P3_RX_DN<0>")
	)
	(arc
		(start 109.518958 -367.627916)
		(mid 111.255732 -365.711534)
		(end 113.473992 -364.381796)
		(width 0.14224)
		(layer "In4.Cu")
		(net "P5E_CPU1_P3_RX_DN<0>")
	)
	(arc
		(start 114.892836 -381.186436)
		(mid 114.61134 -380.943089)
		(end 114.285014 -380.764288)
		(width 0.14224)
		(layer "In4.Cu")
		(net "P5E_CPU1_P3_RX_DN<0>")
	)
	(arc
		(start 115.267994 -381.889508)
		(mid 115.120888 -381.51638)
		(end 114.892836 -381.186436)
		(width 0.14224)
		(layer "In4.Cu")
		(net "P5E_CPU1_P3_RX_DN<0>")
	)
	(arc
		(start 112.703864 -296.300144)
		(mid 112.681779 -296.151262)
		(end 112.6744 -296.000932)
		(width 0.14224)
		(layer "In4.Cu")
		(net "P5E_CPU1_P3_RX_DN<0>")
	)
	(arc
		(start 106.973624 -373.08917)
		(mid 107.20806 -371.50894)
		(end 107.891072 -370.064792)
		(width 0.14224)
		(layer "In4.Cu")
		(net "P5E_CPU1_P3_RX_DN<0>")
	)
	(segment
		(start 157.959044 -369.03533)
		(end 158.229554 -369.30584)
		(width 0.12954)
		(layer "F.Cu")
		(net "P5E_CPU1_P2_TX_DP<9>")
	)
	(segment
		(start 119.127778 -271.390364)
		(end 119.59463 -271.656302)
		(width 0.12954)
		(layer "F.Cu")
		(net "P5E_CPU1_P2_TX_DP<9>")
	)
	(segment
		(start 158.229554 -369.30584)
		(end 158.229554 -370.00942)
		(width 0.12954)
		(layer "F.Cu")
		(net "P5E_CPU1_P2_TX_DP<9>")
	)
	(segment
		(start 158.229554 -370.00942)
		(end 157.933644 -370.30533)
		(width 0.12954)
		(layer "F.Cu")
		(net "P5E_CPU1_P2_TX_DP<9>")
	)
	(segment
		(start 121.191782 -290.608766)
		(end 121.152666 -290.631626)
		(width 0.1143)
		(layer "In13.Cu")
		(net "P5E_CPU1_P2_TX_DP<9>")
	)
	(segment
		(start 121.152666 -276.980904)
		(end 121.159524 -276.984968)
		(width 0.1143)
		(layer "In13.Cu")
		(net "P5E_CPU1_P2_TX_DP<9>")
	)
	(segment
		(start 121.159524 -278.60498)
		(end 121.160286 -278.605488)
		(width 0.1143)
		(layer "In13.Cu")
		(net "P5E_CPU1_P2_TX_DP<9>")
	)
	(segment
		(start 150.573486 -362.199936)
		(end 153.240486 -365.142526)
		(width 0.14224)
		(layer "In13.Cu")
		(net "P5E_CPU1_P2_TX_DP<9>")
	)
	(segment
		(start 121.160286 -278.605488)
		(end 121.191782 -278.623776)
		(width 0.1143)
		(layer "In13.Cu")
		(net "P5E_CPU1_P2_TX_DP<9>")
	)
	(segment
		(start 121.191782 -285.103824)
		(end 121.222262 -285.121604)
		(width 0.1143)
		(layer "In13.Cu")
		(net "P5E_CPU1_P2_TX_DP<9>")
	)
	(segment
		(start 158.14929 -367.944908)
		(end 158.249874 -368.09553)
		(width 0.14224)
		(layer "In13.Cu")
		(net "P5E_CPU1_P2_TX_DP<9>")
	)
	(segment
		(start 121.191782 -282.50896)
		(end 121.152666 -282.53182)
		(width 0.1143)
		(layer "In13.Cu")
		(net "P5E_CPU1_P2_TX_DP<9>")
	)
	(segment
		(start 121.192544 -278.624284)
		(end 121.223532 -278.642064)
		(width 0.1143)
		(layer "In13.Cu")
		(net "P5E_CPU1_P2_TX_DP<9>")
	)
	(segment
		(start 121.191782 -293.20363)
		(end 121.222262 -293.22141)
		(width 0.1143)
		(layer "In13.Cu")
		(net "P5E_CPU1_P2_TX_DP<9>")
	)
	(segment
		(start 121.191782 -294.823642)
		(end 121.222262 -294.841422)
		(width 0.1143)
		(layer "In13.Cu")
		(net "P5E_CPU1_P2_TX_DP<9>")
	)
	(segment
		(start 121.191782 -289.963606)
		(end 121.222262 -289.981386)
		(width 0.1143)
		(layer "In13.Cu")
		(net "P5E_CPU1_P2_TX_DP<9>")
	)
	(segment
		(start 121.191782 -275.383752)
		(end 121.192544 -275.38426)
		(width 0.1143)
		(layer "In13.Cu")
		(net "P5E_CPU1_P2_TX_DP<9>")
	)
	(segment
		(start 154.924252 -366.267746)
		(end 157.309058 -367.255552)
		(width 0.14224)
		(layer "In13.Cu")
		(net "P5E_CPU1_P2_TX_DP<9>")
	)
	(segment
		(start 121.152666 -294.800782)
		(end 121.191782 -294.823642)
		(width 0.1143)
		(layer "In13.Cu")
		(net "P5E_CPU1_P2_TX_DP<9>")
	)
	(segment
		(start 120.258332 -272.147538)
		(end 120.259348 -272.148046)
		(width 0.1143)
		(layer "In13.Cu")
		(net "P5E_CPU1_P2_TX_DP<9>")
	)
	(segment
		(start 121.160286 -276.985476)
		(end 121.191782 -277.003764)
		(width 0.1143)
		(layer "In13.Cu")
		(net "P5E_CPU1_P2_TX_DP<9>")
	)
	(segment
		(start 121.222262 -287.350962)
		(end 121.155206 -287.390078)
		(width 0.1143)
		(layer "In13.Cu")
		(net "P5E_CPU1_P2_TX_DP<9>")
	)
	(segment
		(start 119.59463 -271.656302)
		(end 119.892572 -271.656302)
		(width 0.1143)
		(layer "In13.Cu")
		(net "P5E_CPU1_P2_TX_DP<9>")
	)
	(segment
		(start 121.152666 -275.360892)
		(end 121.159524 -275.364956)
		(width 0.1143)
		(layer "In13.Cu")
		(net "P5E_CPU1_P2_TX_DP<9>")
	)
	(segment
		(start 158.249874 -368.7445)
		(end 157.959044 -369.03533)
		(width 0.14224)
		(layer "In13.Cu")
		(net "P5E_CPU1_P2_TX_DP<9>")
	)
	(segment
		(start 121.191782 -293.84879)
		(end 121.152666 -293.87165)
		(width 0.1143)
		(layer "In13.Cu")
		(net "P5E_CPU1_P2_TX_DP<9>")
	)
	(segment
		(start 120.25249 -272.144236)
		(end 120.255284 -272.14576)
		(width 0.1143)
		(layer "In13.Cu")
		(net "P5E_CPU1_P2_TX_DP<9>")
	)
	(segment
		(start 121.190766 -276.02942)
		(end 121.189242 -276.030436)
		(width 0.1143)
		(layer "In13.Cu")
		(net "P5E_CPU1_P2_TX_DP<9>")
	)
	(segment
		(start 121.160286 -273.745452)
		(end 121.191782 -273.76374)
		(width 0.1143)
		(layer "In13.Cu")
		(net "P5E_CPU1_P2_TX_DP<9>")
	)
	(segment
		(start 121.191782 -280.243788)
		(end 121.192544 -280.244296)
		(width 0.1143)
		(layer "In13.Cu")
		(net "P5E_CPU1_P2_TX_DP<9>")
	)
	(segment
		(start 120.21947 -272.124932)
		(end 120.220232 -272.12544)
		(width 0.1143)
		(layer "In13.Cu")
		(net "P5E_CPU1_P2_TX_DP<9>")
	)
	(segment
		(start 153.240486 -365.142526)
		(end 154.924252 -366.267746)
		(width 0.14224)
		(layer "In13.Cu")
		(net "P5E_CPU1_P2_TX_DP<9>")
	)
	(segment
		(start 121.222262 -290.590986)
		(end 121.191782 -290.608766)
		(width 0.1143)
		(layer "In13.Cu")
		(net "P5E_CPU1_P2_TX_DP<9>")
	)
	(segment
		(start 121.189242 -276.030436)
		(end 121.152666 -276.051772)
		(width 0.1143)
		(layer "In13.Cu")
		(net "P5E_CPU1_P2_TX_DP<9>")
	)
	(segment
		(start 121.223532 -279.250648)
		(end 121.192544 -279.268428)
		(width 0.1143)
		(layer "In13.Cu")
		(net "P5E_CPU1_P2_TX_DP<9>")
	)
	(segment
		(start 121.191782 -281.8638)
		(end 121.222262 -281.88158)
		(width 0.1143)
		(layer "In13.Cu")
		(net "P5E_CPU1_P2_TX_DP<9>")
	)
	(segment
		(start 120.25757 -272.14703)
		(end 120.258332 -272.147538)
		(width 0.1143)
		(layer "In13.Cu")
		(net "P5E_CPU1_P2_TX_DP<9>")
	)
	(segment
		(start 121.152666 -286.700976)
		(end 121.191782 -286.723836)
		(width 0.1143)
		(layer "In13.Cu")
		(net "P5E_CPU1_P2_TX_DP<9>")
	)
	(segment
		(start 121.192544 -277.648416)
		(end 121.191782 -277.648924)
		(width 0.1143)
		(layer "In13.Cu")
		(net "P5E_CPU1_P2_TX_DP<9>")
	)
	(segment
		(start 132.580126 -312.624978)
		(end 134.439914 -315.40831)
		(width 0.14224)
		(layer "In13.Cu")
		(net "P5E_CPU1_P2_TX_DP<9>")
	)
	(segment
		(start 134.439914 -315.40831)
		(end 138.060684 -322.18122)
		(width 0.14224)
		(layer "In13.Cu")
		(net "P5E_CPU1_P2_TX_DP<9>")
	)
	(segment
		(start 121.885964 -296.955718)
		(end 121.885964 -297.29684)
		(width 0.14224)
		(layer "In13.Cu")
		(net "P5E_CPU1_P2_TX_DP<9>")
	)
	(segment
		(start 121.243344 -280.856436)
		(end 121.223532 -280.87066)
		(width 0.1143)
		(layer "In13.Cu")
		(net "P5E_CPU1_P2_TX_DP<9>")
	)
	(segment
		(start 121.152666 -291.560758)
		(end 121.191782 -291.583618)
		(width 0.1143)
		(layer "In13.Cu")
		(net "P5E_CPU1_P2_TX_DP<9>")
	)
	(segment
		(start 121.885456 -296.95521)
		(end 121.885964 -296.955718)
		(width 0.14224)
		(layer "In13.Cu")
		(net "P5E_CPU1_P2_TX_DP<9>")
	)
	(segment
		(start 121.159524 -280.224992)
		(end 121.160286 -280.2255)
		(width 0.1143)
		(layer "In13.Cu")
		(net "P5E_CPU1_P2_TX_DP<9>")
	)
	(segment
		(start 121.191782 -285.748984)
		(end 121.152666 -285.771844)
		(width 0.1143)
		(layer "In13.Cu")
		(net "P5E_CPU1_P2_TX_DP<9>")
	)
	(segment
		(start 121.191782 -274.4089)
		(end 121.190766 -274.409408)
		(width 0.1143)
		(layer "In13.Cu")
		(net "P5E_CPU1_P2_TX_DP<9>")
	)
	(segment
		(start 121.189242 -279.27046)
		(end 121.152666 -279.291796)
		(width 0.1143)
		(layer "In13.Cu")
		(net "P5E_CPU1_P2_TX_DP<9>")
	)
	(segment
		(start 121.222262 -292.210998)
		(end 121.191782 -292.228778)
		(width 0.1143)
		(layer "In13.Cu")
		(net "P5E_CPU1_P2_TX_DP<9>")
	)
	(segment
		(start 121.15546 -280.909776)
		(end 121.152666 -280.911808)
		(width 0.1143)
		(layer "In13.Cu")
		(net "P5E_CPU1_P2_TX_DP<9>")
	)
	(segment
		(start 120.721882 -272.953734)
		(end 120.752362 -272.971514)
		(width 0.1143)
		(layer "In13.Cu")
		(net "P5E_CPU1_P2_TX_DP<9>")
	)
	(segment
		(start 121.243344 -279.236424)
		(end 121.223532 -279.250648)
		(width 0.1143)
		(layer "In13.Cu")
		(net "P5E_CPU1_P2_TX_DP<9>")
	)
	(segment
		(start 121.223532 -278.642064)
		(end 121.243344 -278.656288)
		(width 0.1143)
		(layer "In13.Cu")
		(net "P5E_CPU1_P2_TX_DP<9>")
	)
	(segment
		(start 121.152666 -283.460952)
		(end 121.191782 -283.483812)
		(width 0.1143)
		(layer "In13.Cu")
		(net "P5E_CPU1_P2_TX_DP<9>")
	)
	(segment
		(start 121.191782 -277.003764)
		(end 121.192544 -277.004272)
		(width 0.1143)
		(layer "In13.Cu")
		(net "P5E_CPU1_P2_TX_DP<9>")
	)
	(segment
		(start 121.191782 -279.268936)
		(end 121.190766 -279.269444)
		(width 0.1143)
		(layer "In13.Cu")
		(net "P5E_CPU1_P2_TX_DP<9>")
	)
	(segment
		(start 121.191782 -292.228778)
		(end 121.152666 -292.251638)
		(width 0.1143)
		(layer "In13.Cu")
		(net "P5E_CPU1_P2_TX_DP<9>")
	)
	(segment
		(start 121.223532 -274.390612)
		(end 121.192544 -274.408392)
		(width 0.1143)
		(layer "In13.Cu")
		(net "P5E_CPU1_P2_TX_DP<9>")
	)
	(segment
		(start 119.892572 -271.656302)
		(end 119.975376 -271.739106)
		(width 0.1143)
		(layer "In13.Cu")
		(net "P5E_CPU1_P2_TX_DP<9>")
	)
	(segment
		(start 121.191782 -291.583618)
		(end 121.222262 -291.601398)
		(width 0.1143)
		(layer "In13.Cu")
		(net "P5E_CPU1_P2_TX_DP<9>")
	)
	(segment
		(start 121.191782 -286.723836)
		(end 121.224294 -286.742632)
		(width 0.1143)
		(layer "In13.Cu")
		(net "P5E_CPU1_P2_TX_DP<9>")
	)
	(segment
		(start 121.160286 -280.2255)
		(end 121.191782 -280.243788)
		(width 0.1143)
		(layer "In13.Cu")
		(net "P5E_CPU1_P2_TX_DP<9>")
	)
	(segment
		(start 121.191782 -278.623776)
		(end 121.192544 -278.624284)
		(width 0.1143)
		(layer "In13.Cu")
		(net "P5E_CPU1_P2_TX_DP<9>")
	)
	(segment
		(start 121.159524 -275.364956)
		(end 121.160286 -275.365464)
		(width 0.1143)
		(layer "In13.Cu")
		(net "P5E_CPU1_P2_TX_DP<9>")
	)
	(segment
		(start 120.251728 -272.143728)
		(end 120.25249 -272.144236)
		(width 0.1143)
		(layer "In13.Cu")
		(net "P5E_CPU1_P2_TX_DP<9>")
	)
	(segment
		(start 121.192544 -280.244296)
		(end 121.223532 -280.262076)
		(width 0.1143)
		(layer "In13.Cu")
		(net "P5E_CPU1_P2_TX_DP<9>")
	)
	(segment
		(start 120.212612 -272.120868)
		(end 120.21947 -272.124932)
		(width 0.1143)
		(layer "In13.Cu")
		(net "P5E_CPU1_P2_TX_DP<9>")
	)
	(segment
		(start 121.191782 -288.343848)
		(end 121.224294 -288.362644)
		(width 0.1143)
		(layer "In13.Cu")
		(net "P5E_CPU1_P2_TX_DP<9>")
	)
	(segment
		(start 121.222262 -282.49118)
		(end 121.191782 -282.50896)
		(width 0.1143)
		(layer "In13.Cu")
		(net "P5E_CPU1_P2_TX_DP<9>")
	)
	(segment
		(start 121.190766 -277.649432)
		(end 121.189242 -277.650448)
		(width 0.1143)
		(layer "In13.Cu")
		(net "P5E_CPU1_P2_TX_DP<9>")
	)
	(segment
		(start 157.309058 -367.255552)
		(end 158.14929 -367.944908)
		(width 0.14224)
		(layer "In13.Cu")
		(net "P5E_CPU1_P2_TX_DP<9>")
	)
	(segment
		(start 158.249874 -368.09553)
		(end 158.249874 -368.7445)
		(width 0.14224)
		(layer "In13.Cu")
		(net "P5E_CPU1_P2_TX_DP<9>")
	)
	(segment
		(start 121.159524 -276.984968)
		(end 121.160286 -276.985476)
		(width 0.1143)
		(layer "In13.Cu")
		(net "P5E_CPU1_P2_TX_DP<9>")
	)
	(segment
		(start 121.192544 -274.408392)
		(end 121.191782 -274.4089)
		(width 0.1143)
		(layer "In13.Cu")
		(net "P5E_CPU1_P2_TX_DP<9>")
	)
	(segment
		(start 138.060684 -322.18122)
		(end 138.542014 -323.342508)
		(width 0.14224)
		(layer "In13.Cu")
		(net "P5E_CPU1_P2_TX_DP<9>")
	)
	(segment
		(start 121.191782 -283.483812)
		(end 121.222262 -283.501592)
		(width 0.1143)
		(layer "In13.Cu")
		(net "P5E_CPU1_P2_TX_DP<9>")
	)
	(segment
		(start 121.152666 -285.080964)
		(end 121.191782 -285.103824)
		(width 0.1143)
		(layer "In13.Cu")
		(net "P5E_CPU1_P2_TX_DP<9>")
	)
	(segment
		(start 121.191782 -277.648924)
		(end 121.190766 -277.649432)
		(width 0.1143)
		(layer "In13.Cu")
		(net "P5E_CPU1_P2_TX_DP<9>")
	)
	(segment
		(start 121.189242 -274.410424)
		(end 121.152666 -274.43176)
		(width 0.1143)
		(layer "In13.Cu")
		(net "P5E_CPU1_P2_TX_DP<9>")
	)
	(segment
		(start 121.849642 -295.956228)
		(end 121.849642 -296.178732)
		(width 0.1143)
		(layer "In13.Cu")
		(net "P5E_CPU1_P2_TX_DP<9>")
	)
	(segment
		(start 121.152666 -289.940746)
		(end 121.191782 -289.963606)
		(width 0.1143)
		(layer "In13.Cu")
		(net "P5E_CPU1_P2_TX_DP<9>")
	)
	(segment
		(start 121.222262 -293.83101)
		(end 121.191782 -293.84879)
		(width 0.1143)
		(layer "In13.Cu")
		(net "P5E_CPU1_P2_TX_DP<9>")
	)
	(segment
		(start 138.542014 -323.342508)
		(end 143.749522 -349.52432)
		(width 0.14224)
		(layer "In13.Cu")
		(net "P5E_CPU1_P2_TX_DP<9>")
	)
	(segment
		(start 121.152666 -281.84094)
		(end 121.191782 -281.8638)
		(width 0.1143)
		(layer "In13.Cu")
		(net "P5E_CPU1_P2_TX_DP<9>")
	)
	(segment
		(start 121.191782 -284.128972)
		(end 121.152666 -284.151832)
		(width 0.1143)
		(layer "In13.Cu")
		(net "P5E_CPU1_P2_TX_DP<9>")
	)
	(segment
		(start 121.152666 -278.600916)
		(end 121.159524 -278.60498)
		(width 0.1143)
		(layer "In13.Cu")
		(net "P5E_CPU1_P2_TX_DP<9>")
	)
	(segment
		(start 120.220232 -272.12544)
		(end 120.251728 -272.143728)
		(width 0.1143)
		(layer "In13.Cu")
		(net "P5E_CPU1_P2_TX_DP<9>")
	)
	(segment
		(start 120.259348 -272.148046)
		(end 120.283478 -272.162016)
		(width 0.1143)
		(layer "In13.Cu")
		(net "P5E_CPU1_P2_TX_DP<9>")
	)
	(segment
		(start 121.192544 -273.764248)
		(end 121.223532 -273.782028)
		(width 0.1143)
		(layer "In13.Cu")
		(net "P5E_CPU1_P2_TX_DP<9>")
	)
	(segment
		(start 121.849642 -296.178732)
		(end 121.931176 -296.260266)
		(width 0.1143)
		(layer "In13.Cu")
		(net "P5E_CPU1_P2_TX_DP<9>")
	)
	(segment
		(start 121.223532 -280.262076)
		(end 121.243344 -280.2763)
		(width 0.1143)
		(layer "In13.Cu")
		(net "P5E_CPU1_P2_TX_DP<9>")
	)
	(segment
		(start 121.223532 -277.630636)
		(end 121.192544 -277.648416)
		(width 0.1143)
		(layer "In13.Cu")
		(net "P5E_CPU1_P2_TX_DP<9>")
	)
	(segment
		(start 121.885964 -297.29684)
		(end 122.513852 -298.813728)
		(width 0.14224)
		(layer "In13.Cu")
		(net "P5E_CPU1_P2_TX_DP<9>")
	)
	(segment
		(start 121.222262 -288.970974)
		(end 121.191782 -288.988754)
		(width 0.1143)
		(layer "In13.Cu")
		(net "P5E_CPU1_P2_TX_DP<9>")
	)
	(segment
		(start 121.192544 -279.268428)
		(end 121.191782 -279.268936)
		(width 0.1143)
		(layer "In13.Cu")
		(net "P5E_CPU1_P2_TX_DP<9>")
	)
	(segment
		(start 121.192544 -277.004272)
		(end 121.223532 -277.022052)
		(width 0.1143)
		(layer "In13.Cu")
		(net "P5E_CPU1_P2_TX_DP<9>")
	)
	(segment
		(start 121.931176 -296.538396)
		(end 121.885456 -296.584116)
		(width 0.1143)
		(layer "In13.Cu")
		(net "P5E_CPU1_P2_TX_DP<9>")
	)
	(segment
		(start 121.222262 -285.731204)
		(end 121.191782 -285.748984)
		(width 0.1143)
		(layer "In13.Cu")
		(net "P5E_CPU1_P2_TX_DP<9>")
	)
	(segment
		(start 121.192544 -276.028404)
		(end 121.191782 -276.028912)
		(width 0.1143)
		(layer "In13.Cu")
		(net "P5E_CPU1_P2_TX_DP<9>")
	)
	(segment
		(start 121.62536 -295.612566)
		(end 121.693432 -295.651936)
		(width 0.1143)
		(layer "In13.Cu")
		(net "P5E_CPU1_P2_TX_DP<9>")
	)
	(segment
		(start 121.885456 -296.584116)
		(end 121.885456 -296.612564)
		(width 0.1143)
		(layer "In13.Cu")
		(net "P5E_CPU1_P2_TX_DP<9>")
	)
	(segment
		(start 143.749522 -349.52432)
		(end 148.91004 -359.775506)
		(width 0.14224)
		(layer "In13.Cu")
		(net "P5E_CPU1_P2_TX_DP<9>")
	)
	(segment
		(start 148.91004 -359.775506)
		(end 150.573486 -362.199936)
		(width 0.14224)
		(layer "In13.Cu")
		(net "P5E_CPU1_P2_TX_DP<9>")
	)
	(segment
		(start 121.159524 -273.744944)
		(end 121.160286 -273.745452)
		(width 0.1143)
		(layer "In13.Cu")
		(net "P5E_CPU1_P2_TX_DP<9>")
	)
	(segment
		(start 121.379234 -295.146222)
		(end 121.379488 -295.146222)
		(width 0.1143)
		(layer "In13.Cu")
		(net "P5E_CPU1_P2_TX_DP<9>")
	)
	(segment
		(start 121.152666 -280.220928)
		(end 121.159524 -280.224992)
		(width 0.1143)
		(layer "In13.Cu")
		(net "P5E_CPU1_P2_TX_DP<9>")
	)
	(segment
		(start 122.513852 -298.813728)
		(end 123.259342 -300.057566)
		(width 0.14224)
		(layer "In13.Cu")
		(net "P5E_CPU1_P2_TX_DP<9>")
	)
	(segment
		(start 121.191782 -288.988754)
		(end 121.152666 -289.011614)
		(width 0.1143)
		(layer "In13.Cu")
		(net "P5E_CPU1_P2_TX_DP<9>")
	)
	(segment
		(start 121.189242 -277.650448)
		(end 121.152666 -277.671784)
		(width 0.1143)
		(layer "In13.Cu")
		(net "P5E_CPU1_P2_TX_DP<9>")
	)
	(segment
		(start 121.931176 -296.260266)
		(end 121.931176 -296.538396)
		(width 0.1143)
		(layer "In13.Cu")
		(net "P5E_CPU1_P2_TX_DP<9>")
	)
	(segment
		(start 120.682766 -272.930874)
		(end 120.721882 -272.953734)
		(width 0.1143)
		(layer "In13.Cu")
		(net "P5E_CPU1_P2_TX_DP<9>")
	)
	(segment
		(start 121.190766 -274.409408)
		(end 121.189242 -274.410424)
		(width 0.1143)
		(layer "In13.Cu")
		(net "P5E_CPU1_P2_TX_DP<9>")
	)
	(segment
		(start 121.191782 -276.028912)
		(end 121.190766 -276.02942)
		(width 0.1143)
		(layer "In13.Cu")
		(net "P5E_CPU1_P2_TX_DP<9>")
	)
	(segment
		(start 121.152666 -293.18077)
		(end 121.191782 -293.20363)
		(width 0.1143)
		(layer "In13.Cu")
		(net "P5E_CPU1_P2_TX_DP<9>")
	)
	(segment
		(start 121.160286 -275.365464)
		(end 121.191782 -275.383752)
		(width 0.1143)
		(layer "In13.Cu")
		(net "P5E_CPU1_P2_TX_DP<9>")
	)
	(segment
		(start 121.152666 -273.74088)
		(end 121.159524 -273.744944)
		(width 0.1143)
		(layer "In13.Cu")
		(net "P5E_CPU1_P2_TX_DP<9>")
	)
	(segment
		(start 121.222262 -284.111192)
		(end 121.191782 -284.128972)
		(width 0.1143)
		(layer "In13.Cu")
		(net "P5E_CPU1_P2_TX_DP<9>")
	)
	(segment
		(start 121.223532 -276.010624)
		(end 121.192544 -276.028404)
		(width 0.1143)
		(layer "In13.Cu")
		(net "P5E_CPU1_P2_TX_DP<9>")
	)
	(segment
		(start 121.191782 -273.76374)
		(end 121.192544 -273.764248)
		(width 0.1143)
		(layer "In13.Cu")
		(net "P5E_CPU1_P2_TX_DP<9>")
	)
	(segment
		(start 120.255284 -272.14576)
		(end 120.256046 -272.146268)
		(width 0.1143)
		(layer "In13.Cu")
		(net "P5E_CPU1_P2_TX_DP<9>")
	)
	(segment
		(start 121.192544 -275.38426)
		(end 121.223532 -275.40204)
		(width 0.1143)
		(layer "In13.Cu")
		(net "P5E_CPU1_P2_TX_DP<9>")
	)
	(segment
		(start 121.190766 -279.269444)
		(end 121.189242 -279.27046)
		(width 0.1143)
		(layer "In13.Cu")
		(net "P5E_CPU1_P2_TX_DP<9>")
	)
	(segment
		(start 121.223532 -280.87066)
		(end 121.15546 -280.909776)
		(width 0.1143)
		(layer "In13.Cu")
		(net "P5E_CPU1_P2_TX_DP<9>")
	)
	(segment
		(start 121.152666 -288.320988)
		(end 121.191782 -288.343848)
		(width 0.1143)
		(layer "In13.Cu")
		(net "P5E_CPU1_P2_TX_DP<9>")
	)
	(segment
		(start 123.259342 -300.057566)
		(end 132.580126 -312.624978)
		(width 0.14224)
		(layer "In13.Cu")
		(net "P5E_CPU1_P2_TX_DP<9>")
	)
	(segment
		(start 121.885456 -296.612564)
		(end 121.885456 -296.95521)
		(width 0.14224)
		(layer "In13.Cu")
		(net "P5E_CPU1_P2_TX_DP<9>")
	)
	(segment
		(start 120.256046 -272.146268)
		(end 120.25757 -272.14703)
		(width 0.1143)
		(layer "In13.Cu")
		(net "P5E_CPU1_P2_TX_DP<9>")
	)
	(arc
		(start 121.152666 -290.631626)
		(mid 120.909339 -291.096192)
		(end 121.152666 -291.560758)
		(width 0.1143)
		(layer "In13.Cu")
		(net "P5E_CPU1_P2_TX_DP<9>")
	)
	(arc
		(start 121.693432 -295.651936)
		(mid 121.729295 -295.681328)
		(end 121.76125 -295.714928)
		(width 0.1143)
		(layer "In13.Cu")
		(net "P5E_CPU1_P2_TX_DP<9>")
	)
	(arc
		(start 121.76125 -295.714928)
		(mid 121.824231 -295.828696)
		(end 121.849642 -295.956228)
		(width 0.1143)
		(layer "In13.Cu")
		(net "P5E_CPU1_P2_TX_DP<9>")
	)
	(arc
		(start 121.222262 -283.501592)
		(mid 121.379239 -283.806392)
		(end 121.222262 -284.111192)
		(width 0.1143)
		(layer "In13.Cu")
		(net "P5E_CPU1_P2_TX_DP<9>")
	)
	(arc
		(start 121.152666 -285.771844)
		(mid 120.909339 -286.23641)
		(end 121.152666 -286.700976)
		(width 0.1143)
		(layer "In13.Cu")
		(net "P5E_CPU1_P2_TX_DP<9>")
	)
	(arc
		(start 121.152666 -274.43176)
		(mid 120.909339 -274.896326)
		(end 121.152666 -275.360892)
		(width 0.1143)
		(layer "In13.Cu")
		(net "P5E_CPU1_P2_TX_DP<9>")
	)
	(arc
		(start 121.223532 -275.40204)
		(mid 121.373917 -275.706332)
		(end 121.223532 -276.010624)
		(width 0.1143)
		(layer "In13.Cu")
		(net "P5E_CPU1_P2_TX_DP<9>")
	)
	(arc
		(start 121.222262 -289.981386)
		(mid 121.379239 -290.286186)
		(end 121.222262 -290.590986)
		(width 0.1143)
		(layer "In13.Cu")
		(net "P5E_CPU1_P2_TX_DP<9>")
	)
	(arc
		(start 120.909334 -287.856422)
		(mid 120.973849 -288.118641)
		(end 121.152666 -288.320988)
		(width 0.1143)
		(layer "In13.Cu")
		(net "P5E_CPU1_P2_TX_DP<9>")
	)
	(arc
		(start 121.379488 -295.146222)
		(mid 121.444724 -295.409813)
		(end 121.62536 -295.612566)
		(width 0.1143)
		(layer "In13.Cu")
		(net "P5E_CPU1_P2_TX_DP<9>")
	)
	(arc
		(start 119.979186 -271.761966)
		(mid 120.060619 -271.964364)
		(end 120.212612 -272.120868)
		(width 0.1143)
		(layer "In13.Cu")
		(net "P5E_CPU1_P2_TX_DP<9>")
	)
	(arc
		(start 121.222262 -281.88158)
		(mid 121.379239 -282.18638)
		(end 121.222262 -282.49118)
		(width 0.1143)
		(layer "In13.Cu")
		(net "P5E_CPU1_P2_TX_DP<9>")
	)
	(arc
		(start 120.909334 -273.276314)
		(mid 120.973849 -273.538533)
		(end 121.152666 -273.74088)
		(width 0.1143)
		(layer "In13.Cu")
		(net "P5E_CPU1_P2_TX_DP<9>")
	)
	(arc
		(start 121.152666 -284.151832)
		(mid 120.909339 -284.616398)
		(end 121.152666 -285.080964)
		(width 0.1143)
		(layer "In13.Cu")
		(net "P5E_CPU1_P2_TX_DP<9>")
	)
	(arc
		(start 121.379234 -288.666174)
		(mid 121.337685 -288.837596)
		(end 121.222262 -288.970974)
		(width 0.1143)
		(layer "In13.Cu")
		(net "P5E_CPU1_P2_TX_DP<9>")
	)
	(arc
		(start 121.222262 -294.841422)
		(mid 121.337689 -294.974798)
		(end 121.379234 -295.146222)
		(width 0.1143)
		(layer "In13.Cu")
		(net "P5E_CPU1_P2_TX_DP<9>")
	)
	(arc
		(start 121.152666 -276.051772)
		(mid 120.909339 -276.516338)
		(end 121.152666 -276.980904)
		(width 0.1143)
		(layer "In13.Cu")
		(net "P5E_CPU1_P2_TX_DP<9>")
	)
	(arc
		(start 119.975376 -271.739106)
		(mid 119.977164 -271.750555)
		(end 119.979186 -271.761966)
		(width 0.1143)
		(layer "In13.Cu")
		(net "P5E_CPU1_P2_TX_DP<9>")
	)
	(arc
		(start 121.222262 -285.121604)
		(mid 121.379239 -285.426404)
		(end 121.222262 -285.731204)
		(width 0.1143)
		(layer "In13.Cu")
		(net "P5E_CPU1_P2_TX_DP<9>")
	)
	(arc
		(start 121.243344 -280.2763)
		(mid 121.392058 -280.566368)
		(end 121.243344 -280.856436)
		(width 0.1143)
		(layer "In13.Cu")
		(net "P5E_CPU1_P2_TX_DP<9>")
	)
	(arc
		(start 121.155206 -287.390078)
		(mid 120.974554 -287.592823)
		(end 120.909334 -287.856422)
		(width 0.1143)
		(layer "In13.Cu")
		(net "P5E_CPU1_P2_TX_DP<9>")
	)
	(arc
		(start 120.283478 -272.162016)
		(mid 120.398154 -272.29535)
		(end 120.439434 -272.466308)
		(width 0.1143)
		(layer "In13.Cu")
		(net "P5E_CPU1_P2_TX_DP<9>")
	)
	(arc
		(start 121.152666 -292.251638)
		(mid 120.909339 -292.716204)
		(end 121.152666 -293.18077)
		(width 0.1143)
		(layer "In13.Cu")
		(net "P5E_CPU1_P2_TX_DP<9>")
	)
	(arc
		(start 121.222262 -293.22141)
		(mid 121.379239 -293.52621)
		(end 121.222262 -293.83101)
		(width 0.1143)
		(layer "In13.Cu")
		(net "P5E_CPU1_P2_TX_DP<9>")
	)
	(arc
		(start 121.223532 -273.782028)
		(mid 121.375121 -274.08632)
		(end 121.223532 -274.390612)
		(width 0.1143)
		(layer "In13.Cu")
		(net "P5E_CPU1_P2_TX_DP<9>")
	)
	(arc
		(start 120.752362 -272.971514)
		(mid 120.867789 -273.10489)
		(end 120.909334 -273.276314)
		(width 0.1143)
		(layer "In13.Cu")
		(net "P5E_CPU1_P2_TX_DP<9>")
	)
	(arc
		(start 121.223532 -277.022052)
		(mid 121.375121 -277.326344)
		(end 121.223532 -277.630636)
		(width 0.1143)
		(layer "In13.Cu")
		(net "P5E_CPU1_P2_TX_DP<9>")
	)
	(arc
		(start 121.152666 -277.671784)
		(mid 120.909339 -278.13635)
		(end 121.152666 -278.600916)
		(width 0.1143)
		(layer "In13.Cu")
		(net "P5E_CPU1_P2_TX_DP<9>")
	)
	(arc
		(start 121.152666 -289.011614)
		(mid 120.909339 -289.47618)
		(end 121.152666 -289.940746)
		(width 0.1143)
		(layer "In13.Cu")
		(net "P5E_CPU1_P2_TX_DP<9>")
	)
	(arc
		(start 121.243344 -278.656288)
		(mid 121.392058 -278.946356)
		(end 121.243344 -279.236424)
		(width 0.1143)
		(layer "In13.Cu")
		(net "P5E_CPU1_P2_TX_DP<9>")
	)
	(arc
		(start 121.152666 -282.53182)
		(mid 120.909339 -282.996386)
		(end 121.152666 -283.460952)
		(width 0.1143)
		(layer "In13.Cu")
		(net "P5E_CPU1_P2_TX_DP<9>")
	)
	(arc
		(start 121.224294 -286.742632)
		(mid 121.338223 -286.875779)
		(end 121.379234 -287.046162)
		(width 0.1143)
		(layer "In13.Cu")
		(net "P5E_CPU1_P2_TX_DP<9>")
	)
	(arc
		(start 121.152666 -279.291796)
		(mid 120.909339 -279.756362)
		(end 121.152666 -280.220928)
		(width 0.1143)
		(layer "In13.Cu")
		(net "P5E_CPU1_P2_TX_DP<9>")
	)
	(arc
		(start 121.224294 -288.362644)
		(mid 121.338223 -288.495791)
		(end 121.379234 -288.666174)
		(width 0.1143)
		(layer "In13.Cu")
		(net "P5E_CPU1_P2_TX_DP<9>")
	)
	(arc
		(start 121.222262 -291.601398)
		(mid 121.379239 -291.906198)
		(end 121.222262 -292.210998)
		(width 0.1143)
		(layer "In13.Cu")
		(net "P5E_CPU1_P2_TX_DP<9>")
	)
	(arc
		(start 121.152666 -280.911808)
		(mid 120.909339 -281.376374)
		(end 121.152666 -281.84094)
		(width 0.1143)
		(layer "In13.Cu")
		(net "P5E_CPU1_P2_TX_DP<9>")
	)
	(arc
		(start 121.379234 -287.046162)
		(mid 121.337685 -287.217584)
		(end 121.222262 -287.350962)
		(width 0.1143)
		(layer "In13.Cu")
		(net "P5E_CPU1_P2_TX_DP<9>")
	)
	(arc
		(start 121.152666 -293.87165)
		(mid 120.909339 -294.336216)
		(end 121.152666 -294.800782)
		(width 0.1143)
		(layer "In13.Cu")
		(net "P5E_CPU1_P2_TX_DP<9>")
	)
	(arc
		(start 120.439434 -272.466308)
		(mid 120.503949 -272.728527)
		(end 120.682766 -272.930874)
		(width 0.1143)
		(layer "In13.Cu")
		(net "P5E_CPU1_P2_TX_DP<9>")
	)
	(segment
		(start 156.257244 -371.49913)
		(end 156.527754 -371.76964)
		(width 0.12954)
		(layer "F.Cu")
		(net "P5E_CPU1_P2_TX_DP<8>")
	)
	(segment
		(start 156.527754 -372.47322)
		(end 156.231844 -372.76913)
		(width 0.12954)
		(layer "F.Cu")
		(net "P5E_CPU1_P2_TX_DP<8>")
	)
	(segment
		(start 119.127778 -273.010376)
		(end 119.59463 -273.276314)
		(width 0.12954)
		(layer "F.Cu")
		(net "P5E_CPU1_P2_TX_DP<8>")
	)
	(segment
		(start 156.527754 -371.76964)
		(end 156.527754 -372.47322)
		(width 0.12954)
		(layer "F.Cu")
		(net "P5E_CPU1_P2_TX_DP<8>")
	)
	(segment
		(start 120.251728 -278.623776)
		(end 120.25249 -278.624284)
		(width 0.1143)
		(layer "In13.Cu")
		(net "P5E_CPU1_P2_TX_DP<8>")
	)
	(segment
		(start 120.212612 -289.940746)
		(end 120.250712 -289.963098)
		(width 0.1143)
		(layer "In13.Cu")
		(net "P5E_CPU1_P2_TX_DP<8>")
	)
	(segment
		(start 120.254522 -285.105602)
		(end 120.25503 -285.105602)
		(width 0.1143)
		(layer "In13.Cu")
		(net "P5E_CPU1_P2_TX_DP<8>")
	)
	(segment
		(start 120.212612 -285.080964)
		(end 120.250712 -285.103316)
		(width 0.1143)
		(layer "In13.Cu")
		(net "P5E_CPU1_P2_TX_DP<8>")
	)
	(segment
		(start 120.283478 -280.87066)
		(end 120.251728 -280.888948)
		(width 0.1143)
		(layer "In13.Cu")
		(net "P5E_CPU1_P2_TX_DP<8>")
	)
	(segment
		(start 120.24995 -280.242772)
		(end 120.250712 -280.24328)
		(width 0.1143)
		(layer "In13.Cu")
		(net "P5E_CPU1_P2_TX_DP<8>")
	)
	(segment
		(start 133.67639 -315.97219)
		(end 137.141458 -322.455032)
		(width 0.14224)
		(layer "In13.Cu")
		(net "P5E_CPU1_P2_TX_DP<8>")
	)
	(segment
		(start 122.479054 -300.576996)
		(end 131.661916 -312.957718)
		(width 0.14224)
		(layer "In13.Cu")
		(net "P5E_CPU1_P2_TX_DP<8>")
	)
	(segment
		(start 120.255284 -293.847012)
		(end 120.254776 -293.847012)
		(width 0.1143)
		(layer "In13.Cu")
		(net "P5E_CPU1_P2_TX_DP<8>")
	)
	(segment
		(start 120.212612 -278.600916)
		(end 120.250712 -278.623268)
		(width 0.1143)
		(layer "In13.Cu")
		(net "P5E_CPU1_P2_TX_DP<8>")
	)
	(segment
		(start 120.254776 -290.606988)
		(end 120.25249 -290.608512)
		(width 0.1143)
		(layer "In13.Cu")
		(net "P5E_CPU1_P2_TX_DP<8>")
	)
	(segment
		(start 120.25249 -279.268428)
		(end 120.251728 -279.268936)
		(width 0.1143)
		(layer "In13.Cu")
		(net "P5E_CPU1_P2_TX_DP<8>")
	)
	(segment
		(start 120.250712 -290.609274)
		(end 120.212612 -290.631626)
		(width 0.1143)
		(layer "In13.Cu")
		(net "P5E_CPU1_P2_TX_DP<8>")
	)
	(segment
		(start 120.249188 -279.27046)
		(end 120.212612 -279.291796)
		(width 0.1143)
		(layer "In13.Cu")
		(net "P5E_CPU1_P2_TX_DP<8>")
	)
	(segment
		(start 120.251728 -288.988754)
		(end 120.250712 -288.989262)
		(width 0.1143)
		(layer "In13.Cu")
		(net "P5E_CPU1_P2_TX_DP<8>")
	)
	(segment
		(start 120.212612 -276.980904)
		(end 120.21947 -276.984968)
		(width 0.1143)
		(layer "In13.Cu")
		(net "P5E_CPU1_P2_TX_DP<8>")
	)
	(segment
		(start 120.220232 -283.465524)
		(end 120.251728 -283.483812)
		(width 0.1143)
		(layer "In13.Cu")
		(net "P5E_CPU1_P2_TX_DP<8>")
	)
	(segment
		(start 120.255284 -288.986976)
		(end 120.254776 -288.986976)
		(width 0.1143)
		(layer "In13.Cu")
		(net "P5E_CPU1_P2_TX_DP<8>")
	)
	(segment
		(start 120.251728 -293.84879)
		(end 120.250712 -293.849298)
		(width 0.1143)
		(layer "In13.Cu")
		(net "P5E_CPU1_P2_TX_DP<8>")
	)
	(segment
		(start 120.212612 -281.84094)
		(end 120.250712 -281.863292)
		(width 0.1143)
		(layer "In13.Cu")
		(net "P5E_CPU1_P2_TX_DP<8>")
	)
	(segment
		(start 120.250712 -284.12948)
		(end 120.212612 -284.151832)
		(width 0.1143)
		(layer "In13.Cu")
		(net "P5E_CPU1_P2_TX_DP<8>")
	)
	(segment
		(start 120.940322 -296.584116)
		(end 120.940322 -296.612564)
		(width 0.1143)
		(layer "In13.Cu")
		(net "P5E_CPU1_P2_TX_DP<8>")
	)
	(segment
		(start 120.25249 -277.648416)
		(end 120.251728 -277.648924)
		(width 0.1143)
		(layer "In13.Cu")
		(net "P5E_CPU1_P2_TX_DP<8>")
	)
	(segment
		(start 121.687844 -299.256958)
		(end 122.479054 -300.576996)
		(width 0.14224)
		(layer "In13.Cu")
		(net "P5E_CPU1_P2_TX_DP<8>")
	)
	(segment
		(start 120.254776 -285.747206)
		(end 120.25249 -285.74873)
		(width 0.1143)
		(layer "In13.Cu")
		(net "P5E_CPU1_P2_TX_DP<8>")
	)
	(segment
		(start 120.283478 -274.390612)
		(end 120.25249 -274.408392)
		(width 0.1143)
		(layer "In13.Cu")
		(net "P5E_CPU1_P2_TX_DP<8>")
	)
	(segment
		(start 120.255284 -285.747206)
		(end 120.254776 -285.747206)
		(width 0.1143)
		(layer "In13.Cu")
		(net "P5E_CPU1_P2_TX_DP<8>")
	)
	(segment
		(start 120.255284 -282.507182)
		(end 120.254776 -282.507182)
		(width 0.1143)
		(layer "In13.Cu")
		(net "P5E_CPU1_P2_TX_DP<8>")
	)
	(segment
		(start 120.986042 -296.253916)
		(end 120.986042 -296.538396)
		(width 0.1143)
		(layer "In13.Cu")
		(net "P5E_CPU1_P2_TX_DP<8>")
	)
	(segment
		(start 120.25249 -273.764248)
		(end 120.25376 -273.76501)
		(width 0.1143)
		(layer "In13.Cu")
		(net "P5E_CPU1_P2_TX_DP<8>")
	)
	(segment
		(start 120.251728 -291.583618)
		(end 120.25249 -291.584126)
		(width 0.1143)
		(layer "In13.Cu")
		(net "P5E_CPU1_P2_TX_DP<8>")
	)
	(segment
		(start 120.250712 -274.409408)
		(end 120.249188 -274.410424)
		(width 0.1143)
		(layer "In13.Cu")
		(net "P5E_CPU1_P2_TX_DP<8>")
	)
	(segment
		(start 120.254776 -293.847012)
		(end 120.25249 -293.848536)
		(width 0.1143)
		(layer "In13.Cu")
		(net "P5E_CPU1_P2_TX_DP<8>")
	)
	(segment
		(start 120.254776 -284.127194)
		(end 120.25249 -284.128718)
		(width 0.1143)
		(layer "In13.Cu")
		(net "P5E_CPU1_P2_TX_DP<8>")
	)
	(segment
		(start 120.250712 -289.963098)
		(end 120.251728 -289.963606)
		(width 0.1143)
		(layer "In13.Cu")
		(net "P5E_CPU1_P2_TX_DP<8>")
	)
	(segment
		(start 120.251728 -273.76374)
		(end 120.25249 -273.764248)
		(width 0.1143)
		(layer "In13.Cu")
		(net "P5E_CPU1_P2_TX_DP<8>")
	)
	(segment
		(start 120.212612 -280.220928)
		(end 120.24995 -280.242772)
		(width 0.1143)
		(layer "In13.Cu")
		(net "P5E_CPU1_P2_TX_DP<8>")
	)
	(segment
		(start 131.661916 -312.957718)
		(end 133.67639 -315.97219)
		(width 0.14224)
		(layer "In13.Cu")
		(net "P5E_CPU1_P2_TX_DP<8>")
	)
	(segment
		(start 120.25249 -289.964114)
		(end 120.254522 -289.965384)
		(width 0.1143)
		(layer "In13.Cu")
		(net "P5E_CPU1_P2_TX_DP<8>")
	)
	(segment
		(start 120.250712 -288.989262)
		(end 120.212612 -289.011614)
		(width 0.1143)
		(layer "In13.Cu")
		(net "P5E_CPU1_P2_TX_DP<8>")
	)
	(segment
		(start 120.283478 -291.601906)
		(end 120.288558 -291.605462)
		(width 0.1143)
		(layer "In13.Cu")
		(net "P5E_CPU1_P2_TX_DP<8>")
	)
	(segment
		(start 154.333448 -367.069624)
		(end 155.275788 -367.459768)
		(width 0.14224)
		(layer "In13.Cu")
		(net "P5E_CPU1_P2_TX_DP<8>")
	)
	(segment
		(start 120.25249 -285.104332)
		(end 120.254522 -285.105602)
		(width 0.1143)
		(layer "In13.Cu")
		(net "P5E_CPU1_P2_TX_DP<8>")
	)
	(segment
		(start 120.21947 -273.744944)
		(end 120.220232 -273.745452)
		(width 0.1143)
		(layer "In13.Cu")
		(net "P5E_CPU1_P2_TX_DP<8>")
	)
	(segment
		(start 120.250712 -293.203122)
		(end 120.251728 -293.20363)
		(width 0.1143)
		(layer "In13.Cu")
		(net "P5E_CPU1_P2_TX_DP<8>")
	)
	(segment
		(start 120.25249 -282.508706)
		(end 120.251728 -282.50896)
		(width 0.1143)
		(layer "In13.Cu")
		(net "P5E_CPU1_P2_TX_DP<8>")
	)
	(segment
		(start 120.250712 -277.649432)
		(end 120.249188 -277.650448)
		(width 0.1143)
		(layer "In13.Cu")
		(net "P5E_CPU1_P2_TX_DP<8>")
	)
	(segment
		(start 120.21947 -275.364956)
		(end 120.220232 -275.365464)
		(width 0.1143)
		(layer "In13.Cu")
		(net "P5E_CPU1_P2_TX_DP<8>")
	)
	(segment
		(start 120.250712 -285.103316)
		(end 120.251728 -285.103824)
		(width 0.1143)
		(layer "In13.Cu")
		(net "P5E_CPU1_P2_TX_DP<8>")
	)
	(segment
		(start 120.250712 -276.02942)
		(end 120.249188 -276.030436)
		(width 0.1143)
		(layer "In13.Cu")
		(net "P5E_CPU1_P2_TX_DP<8>")
	)
	(segment
		(start 120.254776 -288.345372)
		(end 120.25503 -288.345372)
		(width 0.1143)
		(layer "In13.Cu")
		(net "P5E_CPU1_P2_TX_DP<8>")
	)
	(segment
		(start 120.288558 -292.206934)
		(end 120.283478 -292.21049)
		(width 0.1143)
		(layer "In13.Cu")
		(net "P5E_CPU1_P2_TX_DP<8>")
	)
	(segment
		(start 120.909588 -296.177462)
		(end 120.986042 -296.253916)
		(width 0.1143)
		(layer "In13.Cu")
		(net "P5E_CPU1_P2_TX_DP<8>")
	)
	(segment
		(start 120.940322 -296.612564)
		(end 120.940322 -296.837354)
		(width 0.14224)
		(layer "In13.Cu")
		(net "P5E_CPU1_P2_TX_DP<8>")
	)
	(segment
		(start 148.142452 -360.327956)
		(end 149.91588 -362.912914)
		(width 0.14224)
		(layer "In13.Cu")
		(net "P5E_CPU1_P2_TX_DP<8>")
	)
	(segment
		(start 120.250712 -291.58311)
		(end 120.251728 -291.583618)
		(width 0.1143)
		(layer "In13.Cu")
		(net "P5E_CPU1_P2_TX_DP<8>")
	)
	(segment
		(start 120.250712 -293.849298)
		(end 120.212612 -293.87165)
		(width 0.1143)
		(layer "In13.Cu")
		(net "P5E_CPU1_P2_TX_DP<8>")
	)
	(segment
		(start 120.220232 -273.745452)
		(end 120.251728 -273.76374)
		(width 0.1143)
		(layer "In13.Cu")
		(net "P5E_CPU1_P2_TX_DP<8>")
	)
	(segment
		(start 120.25249 -274.408392)
		(end 120.251728 -274.4089)
		(width 0.1143)
		(layer "In13.Cu")
		(net "P5E_CPU1_P2_TX_DP<8>")
	)
	(segment
		(start 120.218962 -288.324544)
		(end 120.254776 -288.345372)
		(width 0.1143)
		(layer "In13.Cu")
		(net "P5E_CPU1_P2_TX_DP<8>")
	)
	(segment
		(start 120.251728 -274.4089)
		(end 120.250712 -274.409408)
		(width 0.1143)
		(layer "In13.Cu")
		(net "P5E_CPU1_P2_TX_DP<8>")
	)
	(segment
		(start 120.250712 -278.623268)
		(end 120.251728 -278.623776)
		(width 0.1143)
		(layer "In13.Cu")
		(net "P5E_CPU1_P2_TX_DP<8>")
	)
	(segment
		(start 120.25376 -277.005034)
		(end 120.283478 -277.022052)
		(width 0.1143)
		(layer "In13.Cu")
		(net "P5E_CPU1_P2_TX_DP<8>")
	)
	(segment
		(start 120.94083 -297.452034)
		(end 121.687844 -299.256958)
		(width 0.14224)
		(layer "In13.Cu")
		(net "P5E_CPU1_P2_TX_DP<8>")
	)
	(segment
		(start 120.21947 -283.465016)
		(end 120.220232 -283.465524)
		(width 0.1143)
		(layer "In13.Cu")
		(net "P5E_CPU1_P2_TX_DP<8>")
	)
	(segment
		(start 120.251728 -285.103824)
		(end 120.25249 -285.104332)
		(width 0.1143)
		(layer "In13.Cu")
		(net "P5E_CPU1_P2_TX_DP<8>")
	)
	(segment
		(start 120.25249 -276.028404)
		(end 120.251728 -276.028912)
		(width 0.1143)
		(layer "In13.Cu")
		(net "P5E_CPU1_P2_TX_DP<8>")
	)
	(segment
		(start 152.683718 -365.967264)
		(end 154.333448 -367.069624)
		(width 0.14224)
		(layer "In13.Cu")
		(net "P5E_CPU1_P2_TX_DP<8>")
	)
	(segment
		(start 155.275788 -367.459768)
		(end 156.287724 -368.290348)
		(width 0.14224)
		(layer "In13.Cu")
		(net "P5E_CPU1_P2_TX_DP<8>")
	)
	(segment
		(start 120.212612 -275.360892)
		(end 120.21947 -275.364956)
		(width 0.1143)
		(layer "In13.Cu")
		(net "P5E_CPU1_P2_TX_DP<8>")
	)
	(segment
		(start 120.909588 -295.955974)
		(end 120.909588 -296.177462)
		(width 0.1143)
		(layer "In13.Cu")
		(net "P5E_CPU1_P2_TX_DP<8>")
	)
	(segment
		(start 120.25249 -293.848536)
		(end 120.251728 -293.84879)
		(width 0.1143)
		(layer "In13.Cu")
		(net "P5E_CPU1_P2_TX_DP<8>")
	)
	(segment
		(start 120.94083 -296.837862)
		(end 120.94083 -297.452034)
		(width 0.14224)
		(layer "In13.Cu")
		(net "P5E_CPU1_P2_TX_DP<8>")
	)
	(segment
		(start 120.250712 -292.229286)
		(end 120.24868 -292.230556)
		(width 0.1143)
		(layer "In13.Cu")
		(net "P5E_CPU1_P2_TX_DP<8>")
	)
	(segment
		(start 120.212612 -286.700976)
		(end 120.285256 -286.743394)
		(width 0.1143)
		(layer "In13.Cu")
		(net "P5E_CPU1_P2_TX_DP<8>")
	)
	(segment
		(start 120.250712 -282.509468)
		(end 120.212612 -282.53182)
		(width 0.1143)
		(layer "In13.Cu")
		(net "P5E_CPU1_P2_TX_DP<8>")
	)
	(segment
		(start 120.251728 -283.483812)
		(end 120.25249 -283.48432)
		(width 0.1143)
		(layer "In13.Cu")
		(net "P5E_CPU1_P2_TX_DP<8>")
	)
	(segment
		(start 120.287288 -287.34766)
		(end 120.283478 -287.350454)
		(width 0.1143)
		(layer "In13.Cu")
		(net "P5E_CPU1_P2_TX_DP<8>")
	)
	(segment
		(start 120.218708 -288.324544)
		(end 120.218962 -288.324544)
		(width 0.1143)
		(layer "In13.Cu")
		(net "P5E_CPU1_P2_TX_DP<8>")
	)
	(segment
		(start 120.25249 -284.128718)
		(end 120.251728 -284.128972)
		(width 0.1143)
		(layer "In13.Cu")
		(net "P5E_CPU1_P2_TX_DP<8>")
	)
	(segment
		(start 120.247156 -292.231572)
		(end 120.24614 -292.23208)
		(width 0.1143)
		(layer "In13.Cu")
		(net "P5E_CPU1_P2_TX_DP<8>")
	)
	(segment
		(start 137.654792 -323.694552)
		(end 142.850108 -349.813372)
		(width 0.14224)
		(layer "In13.Cu")
		(net "P5E_CPU1_P2_TX_DP<8>")
	)
	(segment
		(start 120.25376 -278.625046)
		(end 120.283478 -278.642064)
		(width 0.1143)
		(layer "In13.Cu")
		(net "P5E_CPU1_P2_TX_DP<8>")
	)
	(segment
		(start 120.250712 -279.269444)
		(end 120.249188 -279.27046)
		(width 0.1143)
		(layer "In13.Cu")
		(net "P5E_CPU1_P2_TX_DP<8>")
	)
	(segment
		(start 120.283478 -279.250648)
		(end 120.25249 -279.268428)
		(width 0.1143)
		(layer "In13.Cu")
		(net "P5E_CPU1_P2_TX_DP<8>")
	)
	(segment
		(start 137.141458 -322.455032)
		(end 137.654792 -323.694552)
		(width 0.14224)
		(layer "In13.Cu")
		(net "P5E_CPU1_P2_TX_DP<8>")
	)
	(segment
		(start 120.251728 -289.963606)
		(end 120.25249 -289.964114)
		(width 0.1143)
		(layer "In13.Cu")
		(net "P5E_CPU1_P2_TX_DP<8>")
	)
	(segment
		(start 120.25376 -273.76501)
		(end 120.283478 -273.782028)
		(width 0.1143)
		(layer "In13.Cu")
		(net "P5E_CPU1_P2_TX_DP<8>")
	)
	(segment
		(start 120.251728 -281.8638)
		(end 120.25249 -281.864308)
		(width 0.1143)
		(layer "In13.Cu")
		(net "P5E_CPU1_P2_TX_DP<8>")
	)
	(segment
		(start 120.25249 -288.9885)
		(end 120.251728 -288.988754)
		(width 0.1143)
		(layer "In13.Cu")
		(net "P5E_CPU1_P2_TX_DP<8>")
	)
	(segment
		(start 120.283478 -287.350454)
		(end 120.215152 -287.390078)
		(width 0.1143)
		(layer "In13.Cu")
		(net "P5E_CPU1_P2_TX_DP<8>")
	)
	(segment
		(start 120.254268 -294.824912)
		(end 120.284494 -294.842946)
		(width 0.1143)
		(layer "In13.Cu")
		(net "P5E_CPU1_P2_TX_DP<8>")
	)
	(segment
		(start 120.254522 -293.205408)
		(end 120.25503 -293.205408)
		(width 0.1143)
		(layer "In13.Cu")
		(net "P5E_CPU1_P2_TX_DP<8>")
	)
	(segment
		(start 120.25249 -291.584126)
		(end 120.283478 -291.601906)
		(width 0.1143)
		(layer "In13.Cu")
		(net "P5E_CPU1_P2_TX_DP<8>")
	)
	(segment
		(start 120.255284 -284.127194)
		(end 120.254776 -284.127194)
		(width 0.1143)
		(layer "In13.Cu")
		(net "P5E_CPU1_P2_TX_DP<8>")
	)
	(segment
		(start 120.250712 -294.823134)
		(end 120.254268 -294.824912)
		(width 0.1143)
		(layer "In13.Cu")
		(net "P5E_CPU1_P2_TX_DP<8>")
	)
	(segment
		(start 120.706388 -295.624504)
		(end 120.753378 -295.65219)
		(width 0.1143)
		(layer "In13.Cu")
		(net "P5E_CPU1_P2_TX_DP<8>")
	)
	(segment
		(start 120.25249 -292.22827)
		(end 120.251728 -292.228778)
		(width 0.1143)
		(layer "In13.Cu")
		(net "P5E_CPU1_P2_TX_DP<8>")
	)
	(segment
		(start 120.439434 -295.141904)
		(end 120.439434 -295.146222)
		(width 0.1143)
		(layer "In13.Cu")
		(net "P5E_CPU1_P2_TX_DP<8>")
	)
	(segment
		(start 120.251728 -276.028912)
		(end 120.250712 -276.02942)
		(width 0.1143)
		(layer "In13.Cu")
		(net "P5E_CPU1_P2_TX_DP<8>")
	)
	(segment
		(start 120.255284 -290.606988)
		(end 120.254776 -290.606988)
		(width 0.1143)
		(layer "In13.Cu")
		(net "P5E_CPU1_P2_TX_DP<8>")
	)
	(segment
		(start 120.25249 -293.204138)
		(end 120.254522 -293.205408)
		(width 0.1143)
		(layer "In13.Cu")
		(net "P5E_CPU1_P2_TX_DP<8>")
	)
	(segment
		(start 120.212612 -291.560758)
		(end 120.250712 -291.58311)
		(width 0.1143)
		(layer "In13.Cu")
		(net "P5E_CPU1_P2_TX_DP<8>")
	)
	(segment
		(start 120.909334 -295.956228)
		(end 120.909588 -295.955974)
		(width 0.1143)
		(layer "In13.Cu")
		(net "P5E_CPU1_P2_TX_DP<8>")
	)
	(segment
		(start 120.439434 -287.046162)
		(end 120.439434 -287.050734)
		(width 0.1143)
		(layer "In13.Cu")
		(net "P5E_CPU1_P2_TX_DP<8>")
	)
	(segment
		(start 120.682766 -295.610788)
		(end 120.706134 -295.624504)
		(width 0.1143)
		(layer "In13.Cu")
		(net "P5E_CPU1_P2_TX_DP<8>")
	)
	(segment
		(start 120.251728 -275.383752)
		(end 120.25249 -275.38426)
		(width 0.1143)
		(layer "In13.Cu")
		(net "P5E_CPU1_P2_TX_DP<8>")
	)
	(segment
		(start 120.254522 -289.965384)
		(end 120.25503 -289.965384)
		(width 0.1143)
		(layer "In13.Cu")
		(net "P5E_CPU1_P2_TX_DP<8>")
	)
	(segment
		(start 120.254522 -283.48559)
		(end 120.25503 -283.48559)
		(width 0.1143)
		(layer "In13.Cu")
		(net "P5E_CPU1_P2_TX_DP<8>")
	)
	(segment
		(start 120.25249 -283.48432)
		(end 120.254522 -283.48559)
		(width 0.1143)
		(layer "In13.Cu")
		(net "P5E_CPU1_P2_TX_DP<8>")
	)
	(segment
		(start 120.25249 -281.864308)
		(end 120.254522 -281.865578)
		(width 0.1143)
		(layer "In13.Cu")
		(net "P5E_CPU1_P2_TX_DP<8>")
	)
	(segment
		(start 120.283478 -276.010624)
		(end 120.25249 -276.028404)
		(width 0.1143)
		(layer "In13.Cu")
		(net "P5E_CPU1_P2_TX_DP<8>")
	)
	(segment
		(start 142.850108 -349.813372)
		(end 148.142452 -360.327956)
		(width 0.14224)
		(layer "In13.Cu")
		(net "P5E_CPU1_P2_TX_DP<8>")
	)
	(segment
		(start 120.212612 -273.74088)
		(end 120.21947 -273.744944)
		(width 0.1143)
		(layer "In13.Cu")
		(net "P5E_CPU1_P2_TX_DP<8>")
	)
	(segment
		(start 120.25249 -290.608512)
		(end 120.251728 -290.608766)
		(width 0.1143)
		(layer "In13.Cu")
		(net "P5E_CPU1_P2_TX_DP<8>")
	)
	(segment
		(start 120.251728 -280.243788)
		(end 120.283478 -280.262076)
		(width 0.1143)
		(layer "In13.Cu")
		(net "P5E_CPU1_P2_TX_DP<8>")
	)
	(segment
		(start 120.251728 -282.50896)
		(end 120.250712 -282.509468)
		(width 0.1143)
		(layer "In13.Cu")
		(net "P5E_CPU1_P2_TX_DP<8>")
	)
	(segment
		(start 120.254776 -282.507182)
		(end 120.25249 -282.508706)
		(width 0.1143)
		(layer "In13.Cu")
		(net "P5E_CPU1_P2_TX_DP<8>")
	)
	(segment
		(start 120.250712 -280.24328)
		(end 120.251728 -280.243788)
		(width 0.1143)
		(layer "In13.Cu")
		(net "P5E_CPU1_P2_TX_DP<8>")
	)
	(segment
		(start 120.212612 -288.320988)
		(end 120.218708 -288.324544)
		(width 0.1143)
		(layer "In13.Cu")
		(net "P5E_CPU1_P2_TX_DP<8>")
	)
	(segment
		(start 120.940322 -296.837354)
		(end 120.94083 -296.837862)
		(width 0.14224)
		(layer "In13.Cu")
		(net "P5E_CPU1_P2_TX_DP<8>")
	)
	(segment
		(start 120.24614 -292.23208)
		(end 120.212612 -292.251638)
		(width 0.1143)
		(layer "In13.Cu")
		(net "P5E_CPU1_P2_TX_DP<8>")
	)
	(segment
		(start 120.706134 -295.624504)
		(end 120.706388 -295.624504)
		(width 0.1143)
		(layer "In13.Cu")
		(net "P5E_CPU1_P2_TX_DP<8>")
	)
	(segment
		(start 120.251728 -284.128972)
		(end 120.250712 -284.12948)
		(width 0.1143)
		(layer "In13.Cu")
		(net "P5E_CPU1_P2_TX_DP<8>")
	)
	(segment
		(start 120.215406 -280.909776)
		(end 120.212612 -280.911808)
		(width 0.1143)
		(layer "In13.Cu")
		(net "P5E_CPU1_P2_TX_DP<8>")
	)
	(segment
		(start 149.91588 -362.912914)
		(end 152.683718 -365.967264)
		(width 0.14224)
		(layer "In13.Cu")
		(net "P5E_CPU1_P2_TX_DP<8>")
	)
	(segment
		(start 120.283478 -292.21049)
		(end 120.25249 -292.22827)
		(width 0.1143)
		(layer "In13.Cu")
		(net "P5E_CPU1_P2_TX_DP<8>")
	)
	(segment
		(start 120.251728 -293.20363)
		(end 120.25249 -293.204138)
		(width 0.1143)
		(layer "In13.Cu")
		(net "P5E_CPU1_P2_TX_DP<8>")
	)
	(segment
		(start 120.251728 -285.748984)
		(end 120.250712 -285.749492)
		(width 0.1143)
		(layer "In13.Cu")
		(net "P5E_CPU1_P2_TX_DP<8>")
	)
	(segment
		(start 120.212612 -294.800782)
		(end 120.250712 -294.823134)
		(width 0.1143)
		(layer "In13.Cu")
		(net "P5E_CPU1_P2_TX_DP<8>")
	)
	(segment
		(start 120.250712 -281.863292)
		(end 120.251728 -281.8638)
		(width 0.1143)
		(layer "In13.Cu")
		(net "P5E_CPU1_P2_TX_DP<8>")
	)
	(segment
		(start 156.287724 -368.290348)
		(end 156.45384 -368.538506)
		(width 0.14224)
		(layer "In13.Cu")
		(net "P5E_CPU1_P2_TX_DP<8>")
	)
	(segment
		(start 120.25249 -275.38426)
		(end 120.25376 -275.385022)
		(width 0.1143)
		(layer "In13.Cu")
		(net "P5E_CPU1_P2_TX_DP<8>")
	)
	(segment
		(start 120.254776 -288.986976)
		(end 120.25249 -288.9885)
		(width 0.1143)
		(layer "In13.Cu")
		(net "P5E_CPU1_P2_TX_DP<8>")
	)
	(segment
		(start 120.251728 -280.888948)
		(end 120.215406 -280.909776)
		(width 0.1143)
		(layer "In13.Cu")
		(net "P5E_CPU1_P2_TX_DP<8>")
	)
	(segment
		(start 120.212612 -283.460952)
		(end 120.21947 -283.465016)
		(width 0.1143)
		(layer "In13.Cu")
		(net "P5E_CPU1_P2_TX_DP<8>")
	)
	(segment
		(start 119.59463 -273.276314)
		(end 119.892572 -273.276314)
		(width 0.1143)
		(layer "In13.Cu")
		(net "P5E_CPU1_P2_TX_DP<8>")
	)
	(segment
		(start 156.548074 -371.2083)
		(end 156.257244 -371.49913)
		(width 0.14224)
		(layer "In13.Cu")
		(net "P5E_CPU1_P2_TX_DP<8>")
	)
	(segment
		(start 156.548074 -368.849148)
		(end 156.548074 -371.2083)
		(width 0.14224)
		(layer "In13.Cu")
		(net "P5E_CPU1_P2_TX_DP<8>")
	)
	(segment
		(start 120.212612 -293.18077)
		(end 120.250712 -293.203122)
		(width 0.1143)
		(layer "In13.Cu")
		(net "P5E_CPU1_P2_TX_DP<8>")
	)
	(segment
		(start 120.24868 -292.230556)
		(end 120.247156 -292.231572)
		(width 0.1143)
		(layer "In13.Cu")
		(net "P5E_CPU1_P2_TX_DP<8>")
	)
	(segment
		(start 119.892572 -273.276314)
		(end 119.975376 -273.359118)
		(width 0.1143)
		(layer "In13.Cu")
		(net "P5E_CPU1_P2_TX_DP<8>")
	)
	(segment
		(start 120.283478 -277.630636)
		(end 120.25249 -277.648416)
		(width 0.1143)
		(layer "In13.Cu")
		(net "P5E_CPU1_P2_TX_DP<8>")
	)
	(segment
		(start 120.251728 -290.608766)
		(end 120.250712 -290.609274)
		(width 0.1143)
		(layer "In13.Cu")
		(net "P5E_CPU1_P2_TX_DP<8>")
	)
	(segment
		(start 120.251728 -292.228778)
		(end 120.250712 -292.229286)
		(width 0.1143)
		(layer "In13.Cu")
		(net "P5E_CPU1_P2_TX_DP<8>")
	)
	(segment
		(start 120.25249 -277.004272)
		(end 120.25376 -277.005034)
		(width 0.1143)
		(layer "In13.Cu")
		(net "P5E_CPU1_P2_TX_DP<8>")
	)
	(segment
		(start 120.21947 -276.984968)
		(end 120.220232 -276.985476)
		(width 0.1143)
		(layer "In13.Cu")
		(net "P5E_CPU1_P2_TX_DP<8>")
	)
	(segment
		(start 120.220232 -276.985476)
		(end 120.251728 -277.003764)
		(width 0.1143)
		(layer "In13.Cu")
		(net "P5E_CPU1_P2_TX_DP<8>")
	)
	(segment
		(start 120.249188 -274.410424)
		(end 120.212612 -274.43176)
		(width 0.1143)
		(layer "In13.Cu")
		(net "P5E_CPU1_P2_TX_DP<8>")
	)
	(segment
		(start 120.25249 -285.74873)
		(end 120.251728 -285.748984)
		(width 0.1143)
		(layer "In13.Cu")
		(net "P5E_CPU1_P2_TX_DP<8>")
	)
	(segment
		(start 120.986042 -296.538396)
		(end 120.940322 -296.584116)
		(width 0.1143)
		(layer "In13.Cu")
		(net "P5E_CPU1_P2_TX_DP<8>")
	)
	(segment
		(start 120.251728 -277.648924)
		(end 120.250712 -277.649432)
		(width 0.1143)
		(layer "In13.Cu")
		(net "P5E_CPU1_P2_TX_DP<8>")
	)
	(segment
		(start 120.249188 -277.650448)
		(end 120.212612 -277.671784)
		(width 0.1143)
		(layer "In13.Cu")
		(net "P5E_CPU1_P2_TX_DP<8>")
	)
	(segment
		(start 120.25249 -278.624284)
		(end 120.25376 -278.625046)
		(width 0.1143)
		(layer "In13.Cu")
		(net "P5E_CPU1_P2_TX_DP<8>")
	)
	(segment
		(start 120.254522 -281.865578)
		(end 120.25503 -281.865578)
		(width 0.1143)
		(layer "In13.Cu")
		(net "P5E_CPU1_P2_TX_DP<8>")
	)
	(segment
		(start 120.251728 -277.003764)
		(end 120.25249 -277.004272)
		(width 0.1143)
		(layer "In13.Cu")
		(net "P5E_CPU1_P2_TX_DP<8>")
	)
	(segment
		(start 120.251728 -279.268936)
		(end 120.250712 -279.269444)
		(width 0.1143)
		(layer "In13.Cu")
		(net "P5E_CPU1_P2_TX_DP<8>")
	)
	(segment
		(start 120.220232 -275.365464)
		(end 120.251728 -275.383752)
		(width 0.1143)
		(layer "In13.Cu")
		(net "P5E_CPU1_P2_TX_DP<8>")
	)
	(segment
		(start 120.249188 -276.030436)
		(end 120.212612 -276.051772)
		(width 0.1143)
		(layer "In13.Cu")
		(net "P5E_CPU1_P2_TX_DP<8>")
	)
	(segment
		(start 120.25376 -275.385022)
		(end 120.283478 -275.40204)
		(width 0.1143)
		(layer "In13.Cu")
		(net "P5E_CPU1_P2_TX_DP<8>")
	)
	(segment
		(start 120.250712 -285.749492)
		(end 120.212612 -285.771844)
		(width 0.1143)
		(layer "In13.Cu")
		(net "P5E_CPU1_P2_TX_DP<8>")
	)
	(arc
		(start 120.212612 -282.53182)
		(mid 119.969285 -282.996386)
		(end 120.212612 -283.460952)
		(width 0.1143)
		(layer "In13.Cu")
		(net "P5E_CPU1_P2_TX_DP<8>")
	)
	(arc
		(start 120.212612 -274.43176)
		(mid 119.969285 -274.896326)
		(end 120.212612 -275.360892)
		(width 0.1143)
		(layer "In13.Cu")
		(net "P5E_CPU1_P2_TX_DP<8>")
	)
	(arc
		(start 120.25503 -281.865578)
		(mid 120.439763 -282.18627)
		(end 120.255284 -282.507182)
		(width 0.1143)
		(layer "In13.Cu")
		(net "P5E_CPU1_P2_TX_DP<8>")
	)
	(arc
		(start 156.45384 -368.538506)
		(mid 156.524002 -368.686833)
		(end 156.548074 -368.849148)
		(width 0.14224)
		(layer "In13.Cu")
		(net "P5E_CPU1_P2_TX_DP<8>")
	)
	(arc
		(start 120.212612 -285.771844)
		(mid 119.969285 -286.23641)
		(end 120.212612 -286.700976)
		(width 0.1143)
		(layer "In13.Cu")
		(net "P5E_CPU1_P2_TX_DP<8>")
	)
	(arc
		(start 120.212612 -290.631626)
		(mid 119.969285 -291.096192)
		(end 120.212612 -291.560758)
		(width 0.1143)
		(layer "In13.Cu")
		(net "P5E_CPU1_P2_TX_DP<8>")
	)
	(arc
		(start 119.96928 -287.856422)
		(mid 120.033795 -288.118641)
		(end 120.212612 -288.320988)
		(width 0.1143)
		(layer "In13.Cu")
		(net "P5E_CPU1_P2_TX_DP<8>")
	)
	(arc
		(start 120.25503 -293.205408)
		(mid 120.439763 -293.5261)
		(end 120.255284 -293.847012)
		(width 0.1143)
		(layer "In13.Cu")
		(net "P5E_CPU1_P2_TX_DP<8>")
	)
	(arc
		(start 120.283478 -275.40204)
		(mid 120.439406 -275.706332)
		(end 120.283478 -276.010624)
		(width 0.1143)
		(layer "In13.Cu")
		(net "P5E_CPU1_P2_TX_DP<8>")
	)
	(arc
		(start 120.212612 -289.011614)
		(mid 119.969285 -289.47618)
		(end 120.212612 -289.940746)
		(width 0.1143)
		(layer "In13.Cu")
		(net "P5E_CPU1_P2_TX_DP<8>")
	)
	(arc
		(start 120.212612 -277.671784)
		(mid 119.969285 -278.13635)
		(end 120.212612 -278.600916)
		(width 0.1143)
		(layer "In13.Cu")
		(net "P5E_CPU1_P2_TX_DP<8>")
	)
	(arc
		(start 119.979186 -273.381978)
		(mid 120.060619 -273.584376)
		(end 120.212612 -273.74088)
		(width 0.1143)
		(layer "In13.Cu")
		(net "P5E_CPU1_P2_TX_DP<8>")
	)
	(arc
		(start 120.283478 -278.642064)
		(mid 120.439406 -278.946356)
		(end 120.283478 -279.250648)
		(width 0.1143)
		(layer "In13.Cu")
		(net "P5E_CPU1_P2_TX_DP<8>")
	)
	(arc
		(start 120.439434 -287.050734)
		(mid 120.399179 -287.217547)
		(end 120.287288 -287.34766)
		(width 0.1143)
		(layer "In13.Cu")
		(net "P5E_CPU1_P2_TX_DP<8>")
	)
	(arc
		(start 119.975376 -273.359118)
		(mid 119.977164 -273.370567)
		(end 119.979186 -273.381978)
		(width 0.1143)
		(layer "In13.Cu")
		(net "P5E_CPU1_P2_TX_DP<8>")
	)
	(arc
		(start 120.25503 -288.345372)
		(mid 120.439763 -288.666064)
		(end 120.255284 -288.986976)
		(width 0.1143)
		(layer "In13.Cu")
		(net "P5E_CPU1_P2_TX_DP<8>")
	)
	(arc
		(start 120.25503 -289.965384)
		(mid 120.439763 -290.286076)
		(end 120.255284 -290.606988)
		(width 0.1143)
		(layer "In13.Cu")
		(net "P5E_CPU1_P2_TX_DP<8>")
	)
	(arc
		(start 120.285256 -286.743394)
		(mid 120.398663 -286.876283)
		(end 120.439434 -287.046162)
		(width 0.1143)
		(layer "In13.Cu")
		(net "P5E_CPU1_P2_TX_DP<8>")
	)
	(arc
		(start 120.288558 -291.605462)
		(mid 120.442656 -291.906198)
		(end 120.288558 -292.206934)
		(width 0.1143)
		(layer "In13.Cu")
		(net "P5E_CPU1_P2_TX_DP<8>")
	)
	(arc
		(start 120.284494 -294.842946)
		(mid 120.398377 -294.97356)
		(end 120.439434 -295.141904)
		(width 0.1143)
		(layer "In13.Cu")
		(net "P5E_CPU1_P2_TX_DP<8>")
	)
	(arc
		(start 120.753378 -295.65219)
		(mid 120.868054 -295.785381)
		(end 120.909334 -295.956228)
		(width 0.1143)
		(layer "In13.Cu")
		(net "P5E_CPU1_P2_TX_DP<8>")
	)
	(arc
		(start 120.283478 -277.022052)
		(mid 120.439406 -277.326344)
		(end 120.283478 -277.630636)
		(width 0.1143)
		(layer "In13.Cu")
		(net "P5E_CPU1_P2_TX_DP<8>")
	)
	(arc
		(start 120.212612 -280.911808)
		(mid 119.969285 -281.376374)
		(end 120.212612 -281.84094)
		(width 0.1143)
		(layer "In13.Cu")
		(net "P5E_CPU1_P2_TX_DP<8>")
	)
	(arc
		(start 120.212612 -279.291796)
		(mid 119.969285 -279.756362)
		(end 120.212612 -280.220928)
		(width 0.1143)
		(layer "In13.Cu")
		(net "P5E_CPU1_P2_TX_DP<8>")
	)
	(arc
		(start 120.212612 -284.151832)
		(mid 119.969285 -284.616398)
		(end 120.212612 -285.080964)
		(width 0.1143)
		(layer "In13.Cu")
		(net "P5E_CPU1_P2_TX_DP<8>")
	)
	(arc
		(start 120.25503 -283.48559)
		(mid 120.439763 -283.806282)
		(end 120.255284 -284.127194)
		(width 0.1143)
		(layer "In13.Cu")
		(net "P5E_CPU1_P2_TX_DP<8>")
	)
	(arc
		(start 120.212612 -276.051772)
		(mid 119.969285 -276.516338)
		(end 120.212612 -276.980904)
		(width 0.1143)
		(layer "In13.Cu")
		(net "P5E_CPU1_P2_TX_DP<8>")
	)
	(arc
		(start 120.212612 -292.251638)
		(mid 119.969285 -292.716204)
		(end 120.212612 -293.18077)
		(width 0.1143)
		(layer "In13.Cu")
		(net "P5E_CPU1_P2_TX_DP<8>")
	)
	(arc
		(start 120.215152 -287.390078)
		(mid 120.0345 -287.592823)
		(end 119.96928 -287.856422)
		(width 0.1143)
		(layer "In13.Cu")
		(net "P5E_CPU1_P2_TX_DP<8>")
	)
	(arc
		(start 120.25503 -285.105602)
		(mid 120.439763 -285.426294)
		(end 120.255284 -285.747206)
		(width 0.1143)
		(layer "In13.Cu")
		(net "P5E_CPU1_P2_TX_DP<8>")
	)
	(arc
		(start 120.283478 -273.782028)
		(mid 120.439406 -274.08632)
		(end 120.283478 -274.390612)
		(width 0.1143)
		(layer "In13.Cu")
		(net "P5E_CPU1_P2_TX_DP<8>")
	)
	(arc
		(start 120.212612 -293.87165)
		(mid 119.969285 -294.336216)
		(end 120.212612 -294.800782)
		(width 0.1143)
		(layer "In13.Cu")
		(net "P5E_CPU1_P2_TX_DP<8>")
	)
	(arc
		(start 120.283478 -280.262076)
		(mid 120.439406 -280.566368)
		(end 120.283478 -280.87066)
		(width 0.1143)
		(layer "In13.Cu")
		(net "P5E_CPU1_P2_TX_DP<8>")
	)
	(arc
		(start 120.439434 -295.146222)
		(mid 120.503949 -295.408441)
		(end 120.682766 -295.610788)
		(width 0.1143)
		(layer "In13.Cu")
		(net "P5E_CPU1_P2_TX_DP<8>")
	)
	(segment
		(start 154.555444 -373.96293)
		(end 154.825954 -374.23344)
		(width 0.12954)
		(layer "F.Cu")
		(net "P5E_CPU1_P2_TX_DP<7>")
	)
	(segment
		(start 119.127778 -269.770352)
		(end 119.59463 -270.03629)
		(width 0.12954)
		(layer "F.Cu")
		(net "P5E_CPU1_P2_TX_DP<7>")
	)
	(segment
		(start 154.825954 -374.23344)
		(end 154.825954 -374.93702)
		(width 0.12954)
		(layer "F.Cu")
		(net "P5E_CPU1_P2_TX_DP<7>")
	)
	(segment
		(start 154.825954 -374.93702)
		(end 154.530044 -375.23293)
		(width 0.12954)
		(layer "F.Cu")
		(net "P5E_CPU1_P2_TX_DP<7>")
	)
	(segment
		(start 119.312436 -293.204138)
		(end 119.313452 -293.204646)
		(width 0.1143)
		(layer "In13.Cu")
		(net "P5E_CPU1_P2_TX_DP<7>")
	)
	(segment
		(start 119.311674 -289.963606)
		(end 119.312436 -289.964114)
		(width 0.1143)
		(layer "In13.Cu")
		(net "P5E_CPU1_P2_TX_DP<7>")
	)
	(segment
		(start 119.309134 -285.750254)
		(end 119.309388 -285.750254)
		(width 0.1143)
		(layer "In13.Cu")
		(net "P5E_CPU1_P2_TX_DP<7>")
	)
	(segment
		(start 119.343424 -288.970466)
		(end 119.31523 -288.986722)
		(width 0.1143)
		(layer "In13.Cu")
		(net "P5E_CPU1_P2_TX_DP<7>")
	)
	(segment
		(start 119.313452 -288.987738)
		(end 119.312436 -288.988246)
		(width 0.1143)
		(layer "In13.Cu")
		(net "P5E_CPU1_P2_TX_DP<7>")
	)
	(segment
		(start 130.86842 -313.467242)
		(end 132.78612 -316.337442)
		(width 0.14224)
		(layer "In13.Cu")
		(net "P5E_CPU1_P2_TX_DP<7>")
	)
	(segment
		(start 119.969534 -295.956228)
		(end 119.969534 -296.2529)
		(width 0.1143)
		(layer "In13.Cu")
		(net "P5E_CPU1_P2_TX_DP<7>")
	)
	(segment
		(start 119.969534 -296.2529)
		(end 119.923814 -296.29862)
		(width 0.1143)
		(layer "In13.Cu")
		(net "P5E_CPU1_P2_TX_DP<7>")
	)
	(segment
		(start 146.88566 -360.376724)
		(end 148.261324 -362.46308)
		(width 0.14224)
		(layer "In13.Cu")
		(net "P5E_CPU1_P2_TX_DP<7>")
	)
	(segment
		(start 119.32031 -293.208456)
		(end 119.343424 -293.221918)
		(width 0.1143)
		(layer "In13.Cu")
		(net "P5E_CPU1_P2_TX_DP<7>")
	)
	(segment
		(start 119.343424 -276.010624)
		(end 119.311674 -276.028912)
		(width 0.1143)
		(layer "In13.Cu")
		(net "P5E_CPU1_P2_TX_DP<7>")
	)
	(segment
		(start 119.275352 -283.46273)
		(end 119.343424 -283.5021)
		(width 0.1143)
		(layer "In13.Cu")
		(net "P5E_CPU1_P2_TX_DP<7>")
	)
	(segment
		(start 119.275352 -275.36267)
		(end 119.311674 -275.383752)
		(width 0.1143)
		(layer "In13.Cu")
		(net "P5E_CPU1_P2_TX_DP<7>")
	)
	(segment
		(start 119.343424 -274.390612)
		(end 119.311674 -274.4089)
		(width 0.1143)
		(layer "In13.Cu")
		(net "P5E_CPU1_P2_TX_DP<7>")
	)
	(segment
		(start 119.31523 -293.205662)
		(end 119.315992 -293.20617)
		(width 0.1143)
		(layer "In13.Cu")
		(net "P5E_CPU1_P2_TX_DP<7>")
	)
	(segment
		(start 119.275352 -273.742658)
		(end 119.311674 -273.76374)
		(width 0.1143)
		(layer "In13.Cu")
		(net "P5E_CPU1_P2_TX_DP<7>")
	)
	(segment
		(start 148.337524 -362.563918)
		(end 152.63368 -367.54435)
		(width 0.14224)
		(layer "In13.Cu")
		(net "P5E_CPU1_P2_TX_DP<7>")
	)
	(segment
		(start 119.312436 -280.88844)
		(end 119.310912 -280.889456)
		(width 0.1143)
		(layer "In13.Cu")
		(net "P5E_CPU1_P2_TX_DP<7>")
	)
	(segment
		(start 119.309896 -285.749746)
		(end 119.309134 -285.750254)
		(width 0.1143)
		(layer "In13.Cu")
		(net "P5E_CPU1_P2_TX_DP<7>")
	)
	(segment
		(start 119.892572 -270.03629)
		(end 119.962422 -270.10614)
		(width 0.1143)
		(layer "In13.Cu")
		(net "P5E_CPU1_P2_TX_DP<7>")
	)
	(segment
		(start 119.311674 -293.84879)
		(end 119.294148 -293.85895)
		(width 0.1143)
		(layer "In13.Cu")
		(net "P5E_CPU1_P2_TX_DP<7>")
	)
	(segment
		(start 119.313706 -280.887678)
		(end 119.312436 -280.88844)
		(width 0.1143)
		(layer "In13.Cu")
		(net "P5E_CPU1_P2_TX_DP<7>")
	)
	(segment
		(start 154.846274 -371.51183)
		(end 154.846274 -373.6721)
		(width 0.14224)
		(layer "In13.Cu")
		(net "P5E_CPU1_P2_TX_DP<7>")
	)
	(segment
		(start 119.275098 -285.082488)
		(end 119.334026 -285.116778)
		(width 0.1143)
		(layer "In13.Cu")
		(net "P5E_CPU1_P2_TX_DP<7>")
	)
	(segment
		(start 119.923814 -296.327068)
		(end 119.923814 -297.43527)
		(width 0.14224)
		(layer "In13.Cu")
		(net "P5E_CPU1_P2_TX_DP<7>")
	)
	(segment
		(start 119.31777 -293.207186)
		(end 119.32031 -293.208456)
		(width 0.1143)
		(layer "In13.Cu")
		(net "P5E_CPU1_P2_TX_DP<7>")
	)
	(segment
		(start 119.311674 -292.228778)
		(end 119.31142 -292.229032)
		(width 0.1143)
		(layer "In13.Cu")
		(net "P5E_CPU1_P2_TX_DP<7>")
	)
	(segment
		(start 119.30888 -289.962082)
		(end 119.311674 -289.963606)
		(width 0.1143)
		(layer "In13.Cu")
		(net "P5E_CPU1_P2_TX_DP<7>")
	)
	(segment
		(start 119.311674 -279.268936)
		(end 119.275352 -279.290018)
		(width 0.1143)
		(layer "In13.Cu")
		(net "P5E_CPU1_P2_TX_DP<7>")
	)
	(segment
		(start 119.923814 -297.43527)
		(end 120.895872 -299.782992)
		(width 0.14224)
		(layer "In13.Cu")
		(net "P5E_CPU1_P2_TX_DP<7>")
	)
	(segment
		(start 119.343424 -277.630636)
		(end 119.311674 -277.648924)
		(width 0.1143)
		(layer "In13.Cu")
		(net "P5E_CPU1_P2_TX_DP<7>")
	)
	(segment
		(start 121.64441 -301.031402)
		(end 130.86842 -313.467242)
		(width 0.14224)
		(layer "In13.Cu")
		(net "P5E_CPU1_P2_TX_DP<7>")
	)
	(segment
		(start 119.311674 -276.028912)
		(end 119.275352 -276.049994)
		(width 0.1143)
		(layer "In13.Cu")
		(net "P5E_CPU1_P2_TX_DP<7>")
	)
	(segment
		(start 119.343424 -279.250648)
		(end 119.311674 -279.268936)
		(width 0.1143)
		(layer "In13.Cu")
		(net "P5E_CPU1_P2_TX_DP<7>")
	)
	(segment
		(start 119.74195 -295.61028)
		(end 119.745252 -295.612566)
		(width 0.1143)
		(layer "In13.Cu")
		(net "P5E_CPU1_P2_TX_DP<7>")
	)
	(segment
		(start 119.343424 -293.830502)
		(end 119.311674 -293.84879)
		(width 0.1143)
		(layer "In13.Cu")
		(net "P5E_CPU1_P2_TX_DP<7>")
	)
	(segment
		(start 119.59463 -270.03629)
		(end 119.892572 -270.03629)
		(width 0.1143)
		(layer "In13.Cu")
		(net "P5E_CPU1_P2_TX_DP<7>")
	)
	(segment
		(start 154.846274 -373.6721)
		(end 154.555444 -373.96293)
		(width 0.14224)
		(layer "In13.Cu")
		(net "P5E_CPU1_P2_TX_DP<7>")
	)
	(segment
		(start 119.315992 -293.20617)
		(end 119.317008 -293.206678)
		(width 0.1143)
		(layer "In13.Cu")
		(net "P5E_CPU1_P2_TX_DP<7>")
	)
	(segment
		(start 120.895872 -299.782992)
		(end 121.64441 -301.031402)
		(width 0.14224)
		(layer "In13.Cu")
		(net "P5E_CPU1_P2_TX_DP<7>")
	)
	(segment
		(start 119.343424 -272.7706)
		(end 119.311674 -272.788888)
		(width 0.1143)
		(layer "In13.Cu")
		(net "P5E_CPU1_P2_TX_DP<7>")
	)
	(segment
		(start 119.311674 -277.648924)
		(end 119.275352 -277.670006)
		(width 0.1143)
		(layer "In13.Cu")
		(net "P5E_CPU1_P2_TX_DP<7>")
	)
	(segment
		(start 119.745252 -295.612566)
		(end 119.781828 -295.633648)
		(width 0.1143)
		(layer "In13.Cu")
		(net "P5E_CPU1_P2_TX_DP<7>")
	)
	(segment
		(start 119.333264 -285.736284)
		(end 119.309896 -285.749746)
		(width 0.1143)
		(layer "In13.Cu")
		(net "P5E_CPU1_P2_TX_DP<7>")
	)
	(segment
		(start 153.143204 -368.914934)
		(end 153.143204 -369.515136)
		(width 0.14224)
		(layer "In13.Cu")
		(net "P5E_CPU1_P2_TX_DP<7>")
	)
	(segment
		(start 119.311674 -278.623776)
		(end 119.343424 -278.642064)
		(width 0.1143)
		(layer "In13.Cu")
		(net "P5E_CPU1_P2_TX_DP<7>")
	)
	(segment
		(start 119.275352 -278.602694)
		(end 119.311674 -278.623776)
		(width 0.1143)
		(layer "In13.Cu")
		(net "P5E_CPU1_P2_TX_DP<7>")
	)
	(segment
		(start 153.18867 -369.746276)
		(end 153.260552 -369.920012)
		(width 0.14224)
		(layer "In13.Cu")
		(net "P5E_CPU1_P2_TX_DP<7>")
	)
	(segment
		(start 119.31523 -288.986722)
		(end 119.314214 -288.98723)
		(width 0.1143)
		(layer "In13.Cu")
		(net "P5E_CPU1_P2_TX_DP<7>")
	)
	(segment
		(start 119.343424 -280.87066)
		(end 119.313706 -280.887678)
		(width 0.1143)
		(layer "In13.Cu")
		(net "P5E_CPU1_P2_TX_DP<7>")
	)
	(segment
		(start 119.311674 -272.788888)
		(end 119.275352 -272.80997)
		(width 0.1143)
		(layer "In13.Cu")
		(net "P5E_CPU1_P2_TX_DP<7>")
	)
	(segment
		(start 119.311674 -275.383752)
		(end 119.343424 -275.40204)
		(width 0.1143)
		(layer "In13.Cu")
		(net "P5E_CPU1_P2_TX_DP<7>")
	)
	(segment
		(start 119.812308 -270.34109)
		(end 119.781828 -270.35887)
		(width 0.1143)
		(layer "In13.Cu")
		(net "P5E_CPU1_P2_TX_DP<7>")
	)
	(segment
		(start 119.311674 -277.003764)
		(end 119.343424 -277.022052)
		(width 0.1143)
		(layer "In13.Cu")
		(net "P5E_CPU1_P2_TX_DP<7>")
	)
	(segment
		(start 119.314214 -293.205154)
		(end 119.31523 -293.205662)
		(width 0.1143)
		(layer "In13.Cu")
		(net "P5E_CPU1_P2_TX_DP<7>")
	)
	(segment
		(start 136.348724 -323.010022)
		(end 141.645894 -349.640906)
		(width 0.14224)
		(layer "In13.Cu")
		(net "P5E_CPU1_P2_TX_DP<7>")
	)
	(segment
		(start 119.315484 -287.36417)
		(end 119.310658 -287.366964)
		(width 0.1143)
		(layer "In13.Cu")
		(net "P5E_CPU1_P2_TX_DP<7>")
	)
	(segment
		(start 119.312436 -291.584126)
		(end 119.313706 -291.584888)
		(width 0.1143)
		(layer "In13.Cu")
		(net "P5E_CPU1_P2_TX_DP<7>")
	)
	(segment
		(start 152.697688 -367.652808)
		(end 153.120852 -368.790982)
		(width 0.14224)
		(layer "In13.Cu")
		(net "P5E_CPU1_P2_TX_DP<7>")
	)
	(segment
		(start 119.343424 -292.21049)
		(end 119.311674 -292.228778)
		(width 0.1143)
		(layer "In13.Cu")
		(net "P5E_CPU1_P2_TX_DP<7>")
	)
	(segment
		(start 119.31142 -293.20363)
		(end 119.311674 -293.20363)
		(width 0.1143)
		(layer "In13.Cu")
		(net "P5E_CPU1_P2_TX_DP<7>")
	)
	(segment
		(start 119.311674 -273.76374)
		(end 119.343424 -273.782028)
		(width 0.1143)
		(layer "In13.Cu")
		(net "P5E_CPU1_P2_TX_DP<7>")
	)
	(segment
		(start 119.343424 -271.150588)
		(end 119.311674 -271.168876)
		(width 0.1143)
		(layer "In13.Cu")
		(net "P5E_CPU1_P2_TX_DP<7>")
	)
	(segment
		(start 119.311674 -272.143728)
		(end 119.343424 -272.162016)
		(width 0.1143)
		(layer "In13.Cu")
		(net "P5E_CPU1_P2_TX_DP<7>")
	)
	(segment
		(start 119.313706 -289.964876)
		(end 119.343424 -289.981894)
		(width 0.1143)
		(layer "In13.Cu")
		(net "P5E_CPU1_P2_TX_DP<7>")
	)
	(segment
		(start 119.275352 -280.222706)
		(end 119.311674 -280.243788)
		(width 0.1143)
		(layer "In13.Cu")
		(net "P5E_CPU1_P2_TX_DP<7>")
	)
	(segment
		(start 119.275352 -276.982682)
		(end 119.311674 -277.003764)
		(width 0.1143)
		(layer "In13.Cu")
		(net "P5E_CPU1_P2_TX_DP<7>")
	)
	(segment
		(start 119.311674 -291.583618)
		(end 119.312436 -291.584126)
		(width 0.1143)
		(layer "In13.Cu")
		(net "P5E_CPU1_P2_TX_DP<7>")
	)
	(segment
		(start 119.309388 -286.722566)
		(end 119.311674 -286.723836)
		(width 0.1143)
		(layer "In13.Cu")
		(net "P5E_CPU1_P2_TX_DP<7>")
	)
	(segment
		(start 119.275352 -272.122646)
		(end 119.311674 -272.143728)
		(width 0.1143)
		(layer "In13.Cu")
		(net "P5E_CPU1_P2_TX_DP<7>")
	)
	(segment
		(start 141.645894 -349.640906)
		(end 146.88566 -360.376724)
		(width 0.14224)
		(layer "In13.Cu")
		(net "P5E_CPU1_P2_TX_DP<7>")
	)
	(segment
		(start 119.312436 -288.988246)
		(end 119.311674 -288.988754)
		(width 0.1143)
		(layer "In13.Cu")
		(net "P5E_CPU1_P2_TX_DP<7>")
	)
	(segment
		(start 119.781828 -270.35887)
		(end 119.742712 -270.38173)
		(width 0.1143)
		(layer "In13.Cu")
		(net "P5E_CPU1_P2_TX_DP<7>")
	)
	(segment
		(start 119.275352 -281.842718)
		(end 119.343424 -281.882088)
		(width 0.1143)
		(layer "In13.Cu")
		(net "P5E_CPU1_P2_TX_DP<7>")
	)
	(segment
		(start 119.312436 -289.964114)
		(end 119.313706 -289.964876)
		(width 0.1143)
		(layer "In13.Cu")
		(net "P5E_CPU1_P2_TX_DP<7>")
	)
	(segment
		(start 119.314214 -288.98723)
		(end 119.313452 -288.987738)
		(width 0.1143)
		(layer "In13.Cu")
		(net "P5E_CPU1_P2_TX_DP<7>")
	)
	(segment
		(start 119.311674 -288.988754)
		(end 119.30888 -288.990278)
		(width 0.1143)
		(layer "In13.Cu")
		(net "P5E_CPU1_P2_TX_DP<7>")
	)
	(segment
		(start 119.311674 -271.168876)
		(end 119.275352 -271.189958)
		(width 0.1143)
		(layer "In13.Cu")
		(net "P5E_CPU1_P2_TX_DP<7>")
	)
	(segment
		(start 132.78612 -316.337442)
		(end 136.332214 -322.970652)
		(width 0.14224)
		(layer "In13.Cu")
		(net "P5E_CPU1_P2_TX_DP<7>")
	)
	(segment
		(start 119.343424 -290.590478)
		(end 119.311674 -290.608766)
		(width 0.1143)
		(layer "In13.Cu")
		(net "P5E_CPU1_P2_TX_DP<7>")
	)
	(segment
		(start 119.49938 -295.146222)
		(end 119.499634 -295.146222)
		(width 0.1143)
		(layer "In13.Cu")
		(net "P5E_CPU1_P2_TX_DP<7>")
	)
	(segment
		(start 119.311928 -284.126686)
		(end 119.310912 -284.127194)
		(width 0.1143)
		(layer "In13.Cu")
		(net "P5E_CPU1_P2_TX_DP<7>")
	)
	(segment
		(start 119.311674 -274.4089)
		(end 119.275352 -274.429982)
		(width 0.1143)
		(layer "In13.Cu")
		(net "P5E_CPU1_P2_TX_DP<7>")
	)
	(segment
		(start 119.311928 -282.506674)
		(end 119.310912 -282.507182)
		(width 0.1143)
		(layer "In13.Cu")
		(net "P5E_CPU1_P2_TX_DP<7>")
	)
	(segment
		(start 119.275352 -288.322766)
		(end 119.345202 -288.363406)
		(width 0.1143)
		(layer "In13.Cu")
		(net "P5E_CPU1_P2_TX_DP<7>")
	)
	(segment
		(start 119.317008 -293.206678)
		(end 119.31777 -293.207186)
		(width 0.1143)
		(layer "In13.Cu")
		(net "P5E_CPU1_P2_TX_DP<7>")
	)
	(segment
		(start 119.294148 -294.813482)
		(end 119.343424 -294.84193)
		(width 0.1143)
		(layer "In13.Cu")
		(net "P5E_CPU1_P2_TX_DP<7>")
	)
	(segment
		(start 136.332214 -322.970652)
		(end 136.348724 -323.010022)
		(width 0.14224)
		(layer "In13.Cu")
		(net "P5E_CPU1_P2_TX_DP<7>")
	)
	(segment
		(start 119.313706 -291.584888)
		(end 119.343424 -291.601906)
		(width 0.1143)
		(layer "In13.Cu")
		(net "P5E_CPU1_P2_TX_DP<7>")
	)
	(segment
		(start 119.311674 -293.20363)
		(end 119.312436 -293.204138)
		(width 0.1143)
		(layer "In13.Cu")
		(net "P5E_CPU1_P2_TX_DP<7>")
	)
	(segment
		(start 119.781828 -295.633648)
		(end 119.813578 -295.651936)
		(width 0.1143)
		(layer "In13.Cu")
		(net "P5E_CPU1_P2_TX_DP<7>")
	)
	(segment
		(start 119.923814 -296.29862)
		(end 119.923814 -296.327068)
		(width 0.1143)
		(layer "In13.Cu")
		(net "P5E_CPU1_P2_TX_DP<7>")
	)
	(segment
		(start 154.281378 -370.460778)
		(end 154.502358 -370.681758)
		(width 0.14224)
		(layer "In13.Cu")
		(net "P5E_CPU1_P2_TX_DP<7>")
	)
	(segment
		(start 119.311674 -286.723836)
		(end 119.345202 -286.743394)
		(width 0.1143)
		(layer "In13.Cu")
		(net "P5E_CPU1_P2_TX_DP<7>")
	)
	(segment
		(start 119.311674 -280.243788)
		(end 119.343424 -280.262076)
		(width 0.1143)
		(layer "In13.Cu")
		(net "P5E_CPU1_P2_TX_DP<7>")
	)
	(segment
		(start 119.313452 -293.204646)
		(end 119.314214 -293.205154)
		(width 0.1143)
		(layer "In13.Cu")
		(net "P5E_CPU1_P2_TX_DP<7>")
	)
	(arc
		(start 119.345202 -286.743394)
		(mid 119.458609 -286.876283)
		(end 119.49938 -287.046162)
		(width 0.1143)
		(layer "In13.Cu")
		(net "P5E_CPU1_P2_TX_DP<7>")
	)
	(arc
		(start 119.343424 -275.40204)
		(mid 119.499352 -275.706332)
		(end 119.343424 -276.010624)
		(width 0.1143)
		(layer "In13.Cu")
		(net "P5E_CPU1_P2_TX_DP<7>")
	)
	(arc
		(start 119.309388 -285.750254)
		(mid 119.02946 -286.23641)
		(end 119.309388 -286.722566)
		(width 0.1143)
		(layer "In13.Cu")
		(net "P5E_CPU1_P2_TX_DP<7>")
	)
	(arc
		(start 153.41219 -370.12626)
		(mid 153.685986 -370.295494)
		(end 153.99258 -370.393468)
		(width 0.14224)
		(layer "In13.Cu")
		(net "P5E_CPU1_P2_TX_DP<7>")
	)
	(arc
		(start 119.275352 -279.290018)
		(mid 119.268203 -279.294918)
		(end 119.261128 -279.299924)
		(width 0.1143)
		(layer "In13.Cu")
		(net "P5E_CPU1_P2_TX_DP<7>")
	)
	(arc
		(start 154.502358 -370.681758)
		(mid 154.756881 -371.062584)
		(end 154.846274 -371.51183)
		(width 0.14224)
		(layer "In13.Cu")
		(net "P5E_CPU1_P2_TX_DP<7>")
	)
	(arc
		(start 119.30888 -288.990278)
		(mid 119.029045 -289.47618)
		(end 119.30888 -289.962082)
		(width 0.1143)
		(layer "In13.Cu")
		(net "P5E_CPU1_P2_TX_DP<7>")
	)
	(arc
		(start 119.49938 -270.846296)
		(mid 119.458125 -271.017267)
		(end 119.343424 -271.150588)
		(width 0.1143)
		(layer "In13.Cu")
		(net "P5E_CPU1_P2_TX_DP<7>")
	)
	(arc
		(start 153.260552 -369.920012)
		(mid 153.32377 -370.032395)
		(end 153.41219 -370.12626)
		(width 0.14224)
		(layer "In13.Cu")
		(net "P5E_CPU1_P2_TX_DP<7>")
	)
	(arc
		(start 119.275352 -276.049994)
		(mid 119.268203 -276.054894)
		(end 119.261128 -276.0599)
		(width 0.1143)
		(layer "In13.Cu")
		(net "P5E_CPU1_P2_TX_DP<7>")
	)
	(arc
		(start 119.261128 -276.0599)
		(mid 119.033745 -276.516338)
		(end 119.261128 -276.972776)
		(width 0.1143)
		(layer "In13.Cu")
		(net "P5E_CPU1_P2_TX_DP<7>")
	)
	(arc
		(start 119.275352 -271.189958)
		(mid 119.268203 -271.194858)
		(end 119.261128 -271.199864)
		(width 0.1143)
		(layer "In13.Cu")
		(net "P5E_CPU1_P2_TX_DP<7>")
	)
	(arc
		(start 119.343424 -277.022052)
		(mid 119.499352 -277.326344)
		(end 119.343424 -277.630636)
		(width 0.1143)
		(layer "In13.Cu")
		(net "P5E_CPU1_P2_TX_DP<7>")
	)
	(arc
		(start 119.343424 -283.5021)
		(mid 119.49776 -283.82291)
		(end 119.311928 -284.126686)
		(width 0.1143)
		(layer "In13.Cu")
		(net "P5E_CPU1_P2_TX_DP<7>")
	)
	(arc
		(start 119.962422 -270.10614)
		(mid 119.910005 -270.238071)
		(end 119.812308 -270.34109)
		(width 0.1143)
		(layer "In13.Cu")
		(net "P5E_CPU1_P2_TX_DP<7>")
	)
	(arc
		(start 119.261128 -271.199864)
		(mid 119.033745 -271.656302)
		(end 119.261128 -272.11274)
		(width 0.1143)
		(layer "In13.Cu")
		(net "P5E_CPU1_P2_TX_DP<7>")
	)
	(arc
		(start 119.261128 -274.439888)
		(mid 119.033745 -274.896326)
		(end 119.261128 -275.352764)
		(width 0.1143)
		(layer "In13.Cu")
		(net "P5E_CPU1_P2_TX_DP<7>")
	)
	(arc
		(start 119.343424 -278.642064)
		(mid 119.499352 -278.946356)
		(end 119.343424 -279.250648)
		(width 0.1143)
		(layer "In13.Cu")
		(net "P5E_CPU1_P2_TX_DP<7>")
	)
	(arc
		(start 119.310912 -280.889456)
		(mid 119.030346 -281.356319)
		(end 119.275352 -281.842718)
		(width 0.1143)
		(layer "In13.Cu")
		(net "P5E_CPU1_P2_TX_DP<7>")
	)
	(arc
		(start 119.343424 -289.981894)
		(mid 119.499352 -290.286186)
		(end 119.343424 -290.590478)
		(width 0.1143)
		(layer "In13.Cu")
		(net "P5E_CPU1_P2_TX_DP<7>")
	)
	(arc
		(start 119.304816 -284.13075)
		(mid 119.029698 -284.598494)
		(end 119.275098 -285.082488)
		(width 0.1143)
		(layer "In13.Cu")
		(net "P5E_CPU1_P2_TX_DP<7>")
	)
	(arc
		(start 119.294148 -293.85895)
		(mid 119.019379 -294.336216)
		(end 119.294148 -294.813482)
		(width 0.1143)
		(layer "In13.Cu")
		(net "P5E_CPU1_P2_TX_DP<7>")
	)
	(arc
		(start 119.343424 -281.882088)
		(mid 119.49776 -282.202898)
		(end 119.311928 -282.506674)
		(width 0.1143)
		(layer "In13.Cu")
		(net "P5E_CPU1_P2_TX_DP<7>")
	)
	(arc
		(start 119.275352 -277.670006)
		(mid 119.268203 -277.674906)
		(end 119.261128 -277.679912)
		(width 0.1143)
		(layer "In13.Cu")
		(net "P5E_CPU1_P2_TX_DP<7>")
	)
	(arc
		(start 119.261128 -280.2128)
		(mid 119.268202 -280.217807)
		(end 119.275352 -280.222706)
		(width 0.1143)
		(layer "In13.Cu")
		(net "P5E_CPU1_P2_TX_DP<7>")
	)
	(arc
		(start 119.343424 -273.782028)
		(mid 119.499352 -274.08632)
		(end 119.343424 -274.390612)
		(width 0.1143)
		(layer "In13.Cu")
		(net "P5E_CPU1_P2_TX_DP<7>")
	)
	(arc
		(start 119.261128 -272.819876)
		(mid 119.033745 -273.276314)
		(end 119.261128 -273.732752)
		(width 0.1143)
		(layer "In13.Cu")
		(net "P5E_CPU1_P2_TX_DP<7>")
	)
	(arc
		(start 119.343424 -294.84193)
		(mid 119.4581 -294.975264)
		(end 119.49938 -295.146222)
		(width 0.1143)
		(layer "In13.Cu")
		(net "P5E_CPU1_P2_TX_DP<7>")
	)
	(arc
		(start 119.343424 -272.162016)
		(mid 119.499352 -272.466308)
		(end 119.343424 -272.7706)
		(width 0.1143)
		(layer "In13.Cu")
		(net "P5E_CPU1_P2_TX_DP<7>")
	)
	(arc
		(start 119.261128 -275.352764)
		(mid 119.268202 -275.357771)
		(end 119.275352 -275.36267)
		(width 0.1143)
		(layer "In13.Cu")
		(net "P5E_CPU1_P2_TX_DP<7>")
	)
	(arc
		(start 119.275352 -274.429982)
		(mid 119.268203 -274.434882)
		(end 119.261128 -274.439888)
		(width 0.1143)
		(layer "In13.Cu")
		(net "P5E_CPU1_P2_TX_DP<7>")
	)
	(arc
		(start 119.261128 -276.972776)
		(mid 119.268202 -276.977783)
		(end 119.275352 -276.982682)
		(width 0.1143)
		(layer "In13.Cu")
		(net "P5E_CPU1_P2_TX_DP<7>")
	)
	(arc
		(start 119.499634 -295.146222)
		(mid 119.563869 -295.407968)
		(end 119.74195 -295.61028)
		(width 0.1143)
		(layer "In13.Cu")
		(net "P5E_CPU1_P2_TX_DP<7>")
	)
	(arc
		(start 154.165554 -370.411502)
		(mid 154.228269 -370.424866)
		(end 154.281378 -370.460778)
		(width 0.14224)
		(layer "In13.Cu")
		(net "P5E_CPU1_P2_TX_DP<7>")
	)
	(arc
		(start 119.261128 -273.732752)
		(mid 119.268202 -273.737759)
		(end 119.275352 -273.742658)
		(width 0.1143)
		(layer "In13.Cu")
		(net "P5E_CPU1_P2_TX_DP<7>")
	)
	(arc
		(start 119.310658 -287.366964)
		(mid 119.104804 -287.574195)
		(end 119.02948 -287.856422)
		(width 0.1143)
		(layer "In13.Cu")
		(net "P5E_CPU1_P2_TX_DP<7>")
	)
	(arc
		(start 119.261128 -279.299924)
		(mid 119.033745 -279.756362)
		(end 119.261128 -280.2128)
		(width 0.1143)
		(layer "In13.Cu")
		(net "P5E_CPU1_P2_TX_DP<7>")
	)
	(arc
		(start 119.345202 -288.363406)
		(mid 119.458609 -288.496295)
		(end 119.49938 -288.666174)
		(width 0.1143)
		(layer "In13.Cu")
		(net "P5E_CPU1_P2_TX_DP<7>")
	)
	(arc
		(start 153.120852 -368.790982)
		(mid 153.13758 -368.851959)
		(end 153.143204 -368.914934)
		(width 0.14224)
		(layer "In13.Cu")
		(net "P5E_CPU1_P2_TX_DP<7>")
	)
	(arc
		(start 119.261128 -277.679912)
		(mid 119.033745 -278.13635)
		(end 119.261128 -278.592788)
		(width 0.1143)
		(layer "In13.Cu")
		(net "P5E_CPU1_P2_TX_DP<7>")
	)
	(arc
		(start 119.275352 -272.80997)
		(mid 119.268203 -272.81487)
		(end 119.261128 -272.819876)
		(width 0.1143)
		(layer "In13.Cu")
		(net "P5E_CPU1_P2_TX_DP<7>")
	)
	(arc
		(start 119.343424 -280.262076)
		(mid 119.499352 -280.566368)
		(end 119.343424 -280.87066)
		(width 0.1143)
		(layer "In13.Cu")
		(net "P5E_CPU1_P2_TX_DP<7>")
	)
	(arc
		(start 119.334026 -285.116778)
		(mid 119.511876 -285.426797)
		(end 119.333264 -285.736284)
		(width 0.1143)
		(layer "In13.Cu")
		(net "P5E_CPU1_P2_TX_DP<7>")
	)
	(arc
		(start 153.143204 -369.515136)
		(mid 153.154573 -369.632943)
		(end 153.18867 -369.746276)
		(width 0.14224)
		(layer "In13.Cu")
		(net "P5E_CPU1_P2_TX_DP<7>")
	)
	(arc
		(start 119.261128 -278.592788)
		(mid 119.268202 -278.597795)
		(end 119.275352 -278.602694)
		(width 0.1143)
		(layer "In13.Cu")
		(net "P5E_CPU1_P2_TX_DP<7>")
	)
	(arc
		(start 119.31142 -292.229032)
		(mid 119.030773 -292.716394)
		(end 119.31142 -293.20363)
		(width 0.1143)
		(layer "In13.Cu")
		(net "P5E_CPU1_P2_TX_DP<7>")
	)
	(arc
		(start 119.49938 -287.046162)
		(mid 119.450106 -287.229853)
		(end 119.315484 -287.36417)
		(width 0.1143)
		(layer "In13.Cu")
		(net "P5E_CPU1_P2_TX_DP<7>")
	)
	(arc
		(start 119.343424 -293.221918)
		(mid 119.499352 -293.52621)
		(end 119.343424 -293.830502)
		(width 0.1143)
		(layer "In13.Cu")
		(net "P5E_CPU1_P2_TX_DP<7>")
	)
	(arc
		(start 119.261128 -272.11274)
		(mid 119.268202 -272.117747)
		(end 119.275352 -272.122646)
		(width 0.1143)
		(layer "In13.Cu")
		(net "P5E_CPU1_P2_TX_DP<7>")
	)
	(arc
		(start 119.311674 -290.608766)
		(mid 119.031027 -291.096192)
		(end 119.311674 -291.583618)
		(width 0.1143)
		(layer "In13.Cu")
		(net "P5E_CPU1_P2_TX_DP<7>")
	)
	(arc
		(start 119.742712 -270.38173)
		(mid 119.563899 -270.58408)
		(end 119.49938 -270.846296)
		(width 0.1143)
		(layer "In13.Cu")
		(net "P5E_CPU1_P2_TX_DP<7>")
	)
	(arc
		(start 119.49938 -288.666174)
		(mid 119.458125 -288.837145)
		(end 119.343424 -288.970466)
		(width 0.1143)
		(layer "In13.Cu")
		(net "P5E_CPU1_P2_TX_DP<7>")
	)
	(arc
		(start 119.813578 -295.651936)
		(mid 119.928254 -295.78527)
		(end 119.969534 -295.956228)
		(width 0.1143)
		(layer "In13.Cu")
		(net "P5E_CPU1_P2_TX_DP<7>")
	)
	(arc
		(start 152.63368 -367.54435)
		(mid 152.670512 -367.595728)
		(end 152.697688 -367.652808)
		(width 0.14224)
		(layer "In13.Cu")
		(net "P5E_CPU1_P2_TX_DP<7>")
	)
	(arc
		(start 119.310912 -282.507182)
		(mid 119.029843 -282.975133)
		(end 119.275352 -283.46273)
		(width 0.1143)
		(layer "In13.Cu")
		(net "P5E_CPU1_P2_TX_DP<7>")
	)
	(arc
		(start 153.99258 -370.393468)
		(mid 154.078688 -370.406119)
		(end 154.165554 -370.411502)
		(width 0.14224)
		(layer "In13.Cu")
		(net "P5E_CPU1_P2_TX_DP<7>")
	)
	(arc
		(start 119.310912 -284.127194)
		(mid 119.307859 -284.128963)
		(end 119.304816 -284.13075)
		(width 0.1143)
		(layer "In13.Cu")
		(net "P5E_CPU1_P2_TX_DP<7>")
	)
	(arc
		(start 148.261324 -362.46308)
		(mid 148.297798 -362.514728)
		(end 148.337524 -362.563918)
		(width 0.14224)
		(layer "In13.Cu")
		(net "P5E_CPU1_P2_TX_DP<7>")
	)
	(arc
		(start 119.343424 -291.601906)
		(mid 119.499352 -291.906198)
		(end 119.343424 -292.21049)
		(width 0.1143)
		(layer "In13.Cu")
		(net "P5E_CPU1_P2_TX_DP<7>")
	)
	(arc
		(start 119.02948 -287.856422)
		(mid 119.094716 -288.120013)
		(end 119.275352 -288.322766)
		(width 0.1143)
		(layer "In13.Cu")
		(net "P5E_CPU1_P2_TX_DP<7>")
	)
	(segment
		(start 151.151844 -369.03533)
		(end 151.422354 -369.30584)
		(width 0.12954)
		(layer "F.Cu")
		(net "P5E_CPU1_P2_TX_DP<6>")
	)
	(segment
		(start 151.422354 -370.00942)
		(end 151.126444 -370.30533)
		(width 0.12954)
		(layer "F.Cu")
		(net "P5E_CPU1_P2_TX_DP<6>")
	)
	(segment
		(start 151.422354 -369.30584)
		(end 151.422354 -370.00942)
		(width 0.12954)
		(layer "F.Cu")
		(net "P5E_CPU1_P2_TX_DP<6>")
	)
	(segment
		(start 116.30787 -271.390364)
		(end 116.774722 -271.656302)
		(width 0.12954)
		(layer "F.Cu")
		(net "P5E_CPU1_P2_TX_DP<6>")
	)
	(segment
		(start 118.371874 -284.128972)
		(end 118.332758 -284.151832)
		(width 0.1143)
		(layer "In13.Cu")
		(net "P5E_CPU1_P2_TX_DP<6>")
	)
	(segment
		(start 118.332758 -276.980904)
		(end 118.371874 -277.003764)
		(width 0.1143)
		(layer "In13.Cu")
		(net "P5E_CPU1_P2_TX_DP<6>")
	)
	(segment
		(start 118.371874 -285.748984)
		(end 118.332758 -285.771844)
		(width 0.1143)
		(layer "In13.Cu")
		(net "P5E_CPU1_P2_TX_DP<6>")
	)
	(segment
		(start 117.902482 -272.954242)
		(end 117.905276 -272.955766)
		(width 0.1143)
		(layer "In13.Cu")
		(net "P5E_CPU1_P2_TX_DP<6>")
	)
	(segment
		(start 118.332758 -280.220928)
		(end 118.371874 -280.243788)
		(width 0.1143)
		(layer "In13.Cu")
		(net "P5E_CPU1_P2_TX_DP<6>")
	)
	(segment
		(start 119.029734 -295.956228)
		(end 119.029734 -296.2529)
		(width 0.1143)
		(layer "In13.Cu")
		(net "P5E_CPU1_P2_TX_DP<6>")
	)
	(segment
		(start 118.332758 -281.84094)
		(end 118.371874 -281.8638)
		(width 0.1143)
		(layer "In13.Cu")
		(net "P5E_CPU1_P2_TX_DP<6>")
	)
	(segment
		(start 118.371874 -279.268936)
		(end 118.332758 -279.291796)
		(width 0.1143)
		(layer "In13.Cu")
		(net "P5E_CPU1_P2_TX_DP<6>")
	)
	(segment
		(start 118.402354 -293.83101)
		(end 118.371874 -293.84879)
		(width 0.1143)
		(layer "In13.Cu")
		(net "P5E_CPU1_P2_TX_DP<6>")
	)
	(segment
		(start 118.332758 -289.940746)
		(end 118.371874 -289.963606)
		(width 0.1143)
		(layer "In13.Cu")
		(net "P5E_CPU1_P2_TX_DP<6>")
	)
	(segment
		(start 118.371874 -294.823642)
		(end 118.402354 -294.841422)
		(width 0.1143)
		(layer "In13.Cu")
		(net "P5E_CPU1_P2_TX_DP<6>")
	)
	(segment
		(start 117.90934 -272.958052)
		(end 117.93347 -272.972022)
		(width 0.1143)
		(layer "In13.Cu")
		(net "P5E_CPU1_P2_TX_DP<6>")
	)
	(segment
		(start 118.371874 -288.343848)
		(end 118.404386 -288.362644)
		(width 0.1143)
		(layer "In13.Cu")
		(net "P5E_CPU1_P2_TX_DP<6>")
	)
	(segment
		(start 118.846092 -295.636188)
		(end 118.847616 -295.63695)
		(width 0.1143)
		(layer "In13.Cu")
		(net "P5E_CPU1_P2_TX_DP<6>")
	)
	(segment
		(start 118.984014 -296.29862)
		(end 118.984014 -296.327068)
		(width 0.1143)
		(layer "In13.Cu")
		(net "P5E_CPU1_P2_TX_DP<6>")
	)
	(segment
		(start 118.984014 -296.327068)
		(end 118.984014 -296.97807)
		(width 0.14224)
		(layer "In13.Cu")
		(net "P5E_CPU1_P2_TX_DP<6>")
	)
	(segment
		(start 118.402354 -290.590986)
		(end 118.371874 -290.608766)
		(width 0.1143)
		(layer "In13.Cu")
		(net "P5E_CPU1_P2_TX_DP<6>")
	)
	(segment
		(start 117.870224 -272.935446)
		(end 117.90172 -272.953734)
		(width 0.1143)
		(layer "In13.Cu")
		(net "P5E_CPU1_P2_TX_DP<6>")
	)
	(segment
		(start 140.797534 -350.15551)
		(end 145.883122 -360.57459)
		(width 0.14224)
		(layer "In13.Cu")
		(net "P5E_CPU1_P2_TX_DP<6>")
	)
	(segment
		(start 118.371874 -281.8638)
		(end 118.402354 -281.88158)
		(width 0.1143)
		(layer "In13.Cu")
		(net "P5E_CPU1_P2_TX_DP<6>")
	)
	(segment
		(start 118.371874 -286.723836)
		(end 118.404386 -286.742632)
		(width 0.1143)
		(layer "In13.Cu")
		(net "P5E_CPU1_P2_TX_DP<6>")
	)
	(segment
		(start 149.48154 -366.031272)
		(end 150.847806 -367.614962)
		(width 0.14224)
		(layer "In13.Cu")
		(net "P5E_CPU1_P2_TX_DP<6>")
	)
	(segment
		(start 118.402354 -279.251156)
		(end 118.371874 -279.268936)
		(width 0.1143)
		(layer "In13.Cu")
		(net "P5E_CPU1_P2_TX_DP<6>")
	)
	(segment
		(start 118.371874 -277.003764)
		(end 118.402354 -277.021544)
		(width 0.1143)
		(layer "In13.Cu")
		(net "P5E_CPU1_P2_TX_DP<6>")
	)
	(segment
		(start 118.371874 -280.243788)
		(end 118.402354 -280.261568)
		(width 0.1143)
		(layer "In13.Cu")
		(net "P5E_CPU1_P2_TX_DP<6>")
	)
	(segment
		(start 117.905276 -272.955766)
		(end 117.906038 -272.956274)
		(width 0.1143)
		(layer "In13.Cu")
		(net "P5E_CPU1_P2_TX_DP<6>")
	)
	(segment
		(start 118.332758 -291.560758)
		(end 118.371874 -291.583618)
		(width 0.1143)
		(layer "In13.Cu")
		(net "P5E_CPU1_P2_TX_DP<6>")
	)
	(segment
		(start 118.402354 -280.871168)
		(end 118.371874 -280.888948)
		(width 0.1143)
		(layer "In13.Cu")
		(net "P5E_CPU1_P2_TX_DP<6>")
	)
	(segment
		(start 118.332758 -285.080964)
		(end 118.371874 -285.103824)
		(width 0.1143)
		(layer "In13.Cu")
		(net "P5E_CPU1_P2_TX_DP<6>")
	)
	(segment
		(start 118.984268 -296.978324)
		(end 118.984268 -297.608498)
		(width 0.14224)
		(layer "In13.Cu")
		(net "P5E_CPU1_P2_TX_DP<6>")
	)
	(segment
		(start 118.984268 -297.608498)
		(end 120.05945 -300.204378)
		(width 0.14224)
		(layer "In13.Cu")
		(net "P5E_CPU1_P2_TX_DP<6>")
	)
	(segment
		(start 120.872758 -301.560992)
		(end 130.124962 -314.03544)
		(width 0.14224)
		(layer "In13.Cu")
		(net "P5E_CPU1_P2_TX_DP<6>")
	)
	(segment
		(start 131.965446 -316.789816)
		(end 135.352536 -323.126608)
		(width 0.14224)
		(layer "In13.Cu")
		(net "P5E_CPU1_P2_TX_DP<6>")
	)
	(segment
		(start 118.333266 -280.911554)
		(end 118.332758 -280.911808)
		(width 0.1143)
		(layer "In13.Cu")
		(net "P5E_CPU1_P2_TX_DP<6>")
	)
	(segment
		(start 118.371874 -274.4089)
		(end 118.332758 -274.43176)
		(width 0.1143)
		(layer "In13.Cu")
		(net "P5E_CPU1_P2_TX_DP<6>")
	)
	(segment
		(start 118.402354 -274.39112)
		(end 118.371874 -274.4089)
		(width 0.1143)
		(layer "In13.Cu")
		(net "P5E_CPU1_P2_TX_DP<6>")
	)
	(segment
		(start 118.402354 -287.350962)
		(end 118.335298 -287.390078)
		(width 0.1143)
		(layer "In13.Cu")
		(net "P5E_CPU1_P2_TX_DP<6>")
	)
	(segment
		(start 151.442674 -368.364262)
		(end 151.442674 -368.7445)
		(width 0.14224)
		(layer "In13.Cu")
		(net "P5E_CPU1_P2_TX_DP<6>")
	)
	(segment
		(start 118.402354 -276.011132)
		(end 118.371874 -276.028912)
		(width 0.1143)
		(layer "In13.Cu")
		(net "P5E_CPU1_P2_TX_DP<6>")
	)
	(segment
		(start 118.371874 -290.608766)
		(end 118.332758 -290.631626)
		(width 0.1143)
		(layer "In13.Cu")
		(net "P5E_CPU1_P2_TX_DP<6>")
	)
	(segment
		(start 117.90172 -272.953734)
		(end 117.902482 -272.954242)
		(width 0.1143)
		(layer "In13.Cu")
		(net "P5E_CPU1_P2_TX_DP<6>")
	)
	(segment
		(start 145.883122 -360.57459)
		(end 149.48154 -366.031272)
		(width 0.14224)
		(layer "In13.Cu")
		(net "P5E_CPU1_P2_TX_DP<6>")
	)
	(segment
		(start 118.332758 -283.460952)
		(end 118.371874 -283.483812)
		(width 0.1143)
		(layer "In13.Cu")
		(net "P5E_CPU1_P2_TX_DP<6>")
	)
	(segment
		(start 117.392704 -272.120868)
		(end 117.43182 -272.143728)
		(width 0.1143)
		(layer "In13.Cu")
		(net "P5E_CPU1_P2_TX_DP<6>")
	)
	(segment
		(start 118.402354 -285.731204)
		(end 118.371874 -285.748984)
		(width 0.1143)
		(layer "In13.Cu")
		(net "P5E_CPU1_P2_TX_DP<6>")
	)
	(segment
		(start 118.402354 -292.210998)
		(end 118.371874 -292.228778)
		(width 0.1143)
		(layer "In13.Cu")
		(net "P5E_CPU1_P2_TX_DP<6>")
	)
	(segment
		(start 118.402354 -282.49118)
		(end 118.371874 -282.50896)
		(width 0.1143)
		(layer "In13.Cu")
		(net "P5E_CPU1_P2_TX_DP<6>")
	)
	(segment
		(start 118.841774 -295.633648)
		(end 118.842536 -295.634156)
		(width 0.1143)
		(layer "In13.Cu")
		(net "P5E_CPU1_P2_TX_DP<6>")
	)
	(segment
		(start 119.029734 -296.2529)
		(end 118.984014 -296.29862)
		(width 0.1143)
		(layer "In13.Cu")
		(net "P5E_CPU1_P2_TX_DP<6>")
	)
	(segment
		(start 118.402354 -284.111192)
		(end 118.371874 -284.128972)
		(width 0.1143)
		(layer "In13.Cu")
		(net "P5E_CPU1_P2_TX_DP<6>")
	)
	(segment
		(start 118.332758 -288.320988)
		(end 118.371874 -288.343848)
		(width 0.1143)
		(layer "In13.Cu")
		(net "P5E_CPU1_P2_TX_DP<6>")
	)
	(segment
		(start 117.906038 -272.956274)
		(end 117.907562 -272.957036)
		(width 0.1143)
		(layer "In13.Cu")
		(net "P5E_CPU1_P2_TX_DP<6>")
	)
	(segment
		(start 118.371874 -273.76374)
		(end 118.402354 -273.78152)
		(width 0.1143)
		(layer "In13.Cu")
		(net "P5E_CPU1_P2_TX_DP<6>")
	)
	(segment
		(start 118.332758 -294.800782)
		(end 118.371874 -294.823642)
		(width 0.1143)
		(layer "In13.Cu")
		(net "P5E_CPU1_P2_TX_DP<6>")
	)
	(segment
		(start 118.371874 -293.20363)
		(end 118.402354 -293.22141)
		(width 0.1143)
		(layer "In13.Cu")
		(net "P5E_CPU1_P2_TX_DP<6>")
	)
	(segment
		(start 118.984014 -296.97807)
		(end 118.984268 -296.978324)
		(width 0.14224)
		(layer "In13.Cu")
		(net "P5E_CPU1_P2_TX_DP<6>")
	)
	(segment
		(start 118.840758 -295.63314)
		(end 118.841774 -295.633648)
		(width 0.1143)
		(layer "In13.Cu")
		(net "P5E_CPU1_P2_TX_DP<6>")
	)
	(segment
		(start 117.908324 -272.957544)
		(end 117.90934 -272.958052)
		(width 0.1143)
		(layer "In13.Cu")
		(net "P5E_CPU1_P2_TX_DP<6>")
	)
	(segment
		(start 118.848378 -295.637458)
		(end 118.849394 -295.637966)
		(width 0.1143)
		(layer "In13.Cu")
		(net "P5E_CPU1_P2_TX_DP<6>")
	)
	(segment
		(start 130.124962 -314.03544)
		(end 131.965446 -316.789816)
		(width 0.14224)
		(layer "In13.Cu")
		(net "P5E_CPU1_P2_TX_DP<6>")
	)
	(segment
		(start 151.043132 -367.745772)
		(end 151.287734 -367.990374)
		(width 0.14224)
		(layer "In13.Cu")
		(net "P5E_CPU1_P2_TX_DP<6>")
	)
	(segment
		(start 117.862604 -272.930874)
		(end 117.869462 -272.934938)
		(width 0.1143)
		(layer "In13.Cu")
		(net "P5E_CPU1_P2_TX_DP<6>")
	)
	(segment
		(start 117.869462 -272.934938)
		(end 117.870224 -272.935446)
		(width 0.1143)
		(layer "In13.Cu")
		(net "P5E_CPU1_P2_TX_DP<6>")
	)
	(segment
		(start 118.842536 -295.634156)
		(end 118.84533 -295.63568)
		(width 0.1143)
		(layer "In13.Cu")
		(net "P5E_CPU1_P2_TX_DP<6>")
	)
	(segment
		(start 116.774722 -271.656302)
		(end 117.072664 -271.656302)
		(width 0.1143)
		(layer "In13.Cu")
		(net "P5E_CPU1_P2_TX_DP<6>")
	)
	(segment
		(start 118.847616 -295.63695)
		(end 118.848378 -295.637458)
		(width 0.1143)
		(layer "In13.Cu")
		(net "P5E_CPU1_P2_TX_DP<6>")
	)
	(segment
		(start 118.332758 -278.600916)
		(end 118.371874 -278.623776)
		(width 0.1143)
		(layer "In13.Cu")
		(net "P5E_CPU1_P2_TX_DP<6>")
	)
	(segment
		(start 118.371874 -291.583618)
		(end 118.402354 -291.601398)
		(width 0.1143)
		(layer "In13.Cu")
		(net "P5E_CPU1_P2_TX_DP<6>")
	)
	(segment
		(start 118.802658 -295.610788)
		(end 118.840758 -295.63314)
		(width 0.1143)
		(layer "In13.Cu")
		(net "P5E_CPU1_P2_TX_DP<6>")
	)
	(segment
		(start 150.847806 -367.614962)
		(end 151.043132 -367.745772)
		(width 0.14224)
		(layer "In13.Cu")
		(net "P5E_CPU1_P2_TX_DP<6>")
	)
	(segment
		(start 118.371874 -282.50896)
		(end 118.332758 -282.53182)
		(width 0.1143)
		(layer "In13.Cu")
		(net "P5E_CPU1_P2_TX_DP<6>")
	)
	(segment
		(start 135.352536 -323.126608)
		(end 135.484362 -323.44487)
		(width 0.14224)
		(layer "In13.Cu")
		(net "P5E_CPU1_P2_TX_DP<6>")
	)
	(segment
		(start 120.05945 -300.204378)
		(end 120.872758 -301.560992)
		(width 0.14224)
		(layer "In13.Cu")
		(net "P5E_CPU1_P2_TX_DP<6>")
	)
	(segment
		(start 117.43182 -272.143728)
		(end 117.4623 -272.161508)
		(width 0.1143)
		(layer "In13.Cu")
		(net "P5E_CPU1_P2_TX_DP<6>")
	)
	(segment
		(start 118.332758 -275.360892)
		(end 118.371874 -275.383752)
		(width 0.1143)
		(layer "In13.Cu")
		(net "P5E_CPU1_P2_TX_DP<6>")
	)
	(segment
		(start 118.371874 -280.888948)
		(end 118.333266 -280.911554)
		(width 0.1143)
		(layer "In13.Cu")
		(net "P5E_CPU1_P2_TX_DP<6>")
	)
	(segment
		(start 118.84533 -295.63568)
		(end 118.846092 -295.636188)
		(width 0.1143)
		(layer "In13.Cu")
		(net "P5E_CPU1_P2_TX_DP<6>")
	)
	(segment
		(start 135.484362 -323.44487)
		(end 140.797534 -350.15551)
		(width 0.14224)
		(layer "In13.Cu")
		(net "P5E_CPU1_P2_TX_DP<6>")
	)
	(segment
		(start 118.371874 -277.648924)
		(end 118.332758 -277.671784)
		(width 0.1143)
		(layer "In13.Cu")
		(net "P5E_CPU1_P2_TX_DP<6>")
	)
	(segment
		(start 118.371874 -283.483812)
		(end 118.402354 -283.501592)
		(width 0.1143)
		(layer "In13.Cu")
		(net "P5E_CPU1_P2_TX_DP<6>")
	)
	(segment
		(start 118.371874 -285.103824)
		(end 118.402354 -285.121604)
		(width 0.1143)
		(layer "In13.Cu")
		(net "P5E_CPU1_P2_TX_DP<6>")
	)
	(segment
		(start 118.371874 -276.028912)
		(end 118.332758 -276.051772)
		(width 0.1143)
		(layer "In13.Cu")
		(net "P5E_CPU1_P2_TX_DP<6>")
	)
	(segment
		(start 118.332758 -273.74088)
		(end 118.371874 -273.76374)
		(width 0.1143)
		(layer "In13.Cu")
		(net "P5E_CPU1_P2_TX_DP<6>")
	)
	(segment
		(start 117.072664 -271.656302)
		(end 117.155468 -271.739106)
		(width 0.1143)
		(layer "In13.Cu")
		(net "P5E_CPU1_P2_TX_DP<6>")
	)
	(segment
		(start 118.402354 -288.970974)
		(end 118.371874 -288.988754)
		(width 0.1143)
		(layer "In13.Cu")
		(net "P5E_CPU1_P2_TX_DP<6>")
	)
	(segment
		(start 118.332758 -286.700976)
		(end 118.371874 -286.723836)
		(width 0.1143)
		(layer "In13.Cu")
		(net "P5E_CPU1_P2_TX_DP<6>")
	)
	(segment
		(start 118.371874 -293.84879)
		(end 118.332758 -293.87165)
		(width 0.1143)
		(layer "In13.Cu")
		(net "P5E_CPU1_P2_TX_DP<6>")
	)
	(segment
		(start 117.907562 -272.957036)
		(end 117.908324 -272.957544)
		(width 0.1143)
		(layer "In13.Cu")
		(net "P5E_CPU1_P2_TX_DP<6>")
	)
	(segment
		(start 118.371874 -289.963606)
		(end 118.402354 -289.981386)
		(width 0.1143)
		(layer "In13.Cu")
		(net "P5E_CPU1_P2_TX_DP<6>")
	)
	(segment
		(start 118.371874 -292.228778)
		(end 118.332758 -292.251638)
		(width 0.1143)
		(layer "In13.Cu")
		(net "P5E_CPU1_P2_TX_DP<6>")
	)
	(segment
		(start 118.849394 -295.637966)
		(end 118.873524 -295.651936)
		(width 0.1143)
		(layer "In13.Cu")
		(net "P5E_CPU1_P2_TX_DP<6>")
	)
	(segment
		(start 151.442674 -368.7445)
		(end 151.151844 -369.03533)
		(width 0.14224)
		(layer "In13.Cu")
		(net "P5E_CPU1_P2_TX_DP<6>")
	)
	(segment
		(start 118.402354 -277.631144)
		(end 118.371874 -277.648924)
		(width 0.1143)
		(layer "In13.Cu")
		(net "P5E_CPU1_P2_TX_DP<6>")
	)
	(segment
		(start 118.371874 -288.988754)
		(end 118.332758 -289.011614)
		(width 0.1143)
		(layer "In13.Cu")
		(net "P5E_CPU1_P2_TX_DP<6>")
	)
	(segment
		(start 118.332758 -293.18077)
		(end 118.371874 -293.20363)
		(width 0.1143)
		(layer "In13.Cu")
		(net "P5E_CPU1_P2_TX_DP<6>")
	)
	(segment
		(start 118.371874 -278.623776)
		(end 118.402354 -278.641556)
		(width 0.1143)
		(layer "In13.Cu")
		(net "P5E_CPU1_P2_TX_DP<6>")
	)
	(segment
		(start 118.371874 -275.383752)
		(end 118.402354 -275.401532)
		(width 0.1143)
		(layer "In13.Cu")
		(net "P5E_CPU1_P2_TX_DP<6>")
	)
	(arc
		(start 118.332758 -293.87165)
		(mid 118.089431 -294.336216)
		(end 118.332758 -294.800782)
		(width 0.1143)
		(layer "In13.Cu")
		(net "P5E_CPU1_P2_TX_DP<6>")
	)
	(arc
		(start 118.96344 -295.743884)
		(mid 119.01276 -295.845013)
		(end 119.029734 -295.956228)
		(width 0.1143)
		(layer "In13.Cu")
		(net "P5E_CPU1_P2_TX_DP<6>")
	)
	(arc
		(start 118.402354 -278.641556)
		(mid 118.559331 -278.946356)
		(end 118.402354 -279.251156)
		(width 0.1143)
		(layer "In13.Cu")
		(net "P5E_CPU1_P2_TX_DP<6>")
	)
	(arc
		(start 118.559326 -287.046162)
		(mid 118.517777 -287.217584)
		(end 118.402354 -287.350962)
		(width 0.1143)
		(layer "In13.Cu")
		(net "P5E_CPU1_P2_TX_DP<6>")
	)
	(arc
		(start 117.159278 -271.761966)
		(mid 117.240711 -271.964364)
		(end 117.392704 -272.120868)
		(width 0.1143)
		(layer "In13.Cu")
		(net "P5E_CPU1_P2_TX_DP<6>")
	)
	(arc
		(start 117.619272 -272.466308)
		(mid 117.683787 -272.728527)
		(end 117.862604 -272.930874)
		(width 0.1143)
		(layer "In13.Cu")
		(net "P5E_CPU1_P2_TX_DP<6>")
	)
	(arc
		(start 151.287734 -367.990374)
		(mid 151.402408 -368.161901)
		(end 151.442674 -368.364262)
		(width 0.14224)
		(layer "In13.Cu")
		(net "P5E_CPU1_P2_TX_DP<6>")
	)
	(arc
		(start 118.332758 -290.631626)
		(mid 118.089431 -291.096192)
		(end 118.332758 -291.560758)
		(width 0.1143)
		(layer "In13.Cu")
		(net "P5E_CPU1_P2_TX_DP<6>")
	)
	(arc
		(start 118.402354 -293.22141)
		(mid 118.559331 -293.52621)
		(end 118.402354 -293.83101)
		(width 0.1143)
		(layer "In13.Cu")
		(net "P5E_CPU1_P2_TX_DP<6>")
	)
	(arc
		(start 118.404386 -286.742632)
		(mid 118.518315 -286.875779)
		(end 118.559326 -287.046162)
		(width 0.1143)
		(layer "In13.Cu")
		(net "P5E_CPU1_P2_TX_DP<6>")
	)
	(arc
		(start 118.402354 -291.601398)
		(mid 118.559331 -291.906198)
		(end 118.402354 -292.210998)
		(width 0.1143)
		(layer "In13.Cu")
		(net "P5E_CPU1_P2_TX_DP<6>")
	)
	(arc
		(start 118.404386 -288.362644)
		(mid 118.518315 -288.495791)
		(end 118.559326 -288.666174)
		(width 0.1143)
		(layer "In13.Cu")
		(net "P5E_CPU1_P2_TX_DP<6>")
	)
	(arc
		(start 118.089426 -287.856422)
		(mid 118.153941 -288.118641)
		(end 118.332758 -288.320988)
		(width 0.1143)
		(layer "In13.Cu")
		(net "P5E_CPU1_P2_TX_DP<6>")
	)
	(arc
		(start 118.402354 -275.401532)
		(mid 118.559331 -275.706332)
		(end 118.402354 -276.011132)
		(width 0.1143)
		(layer "In13.Cu")
		(net "P5E_CPU1_P2_TX_DP<6>")
	)
	(arc
		(start 118.332758 -282.53182)
		(mid 118.089431 -282.996386)
		(end 118.332758 -283.460952)
		(width 0.1143)
		(layer "In13.Cu")
		(net "P5E_CPU1_P2_TX_DP<6>")
	)
	(arc
		(start 118.332758 -292.251638)
		(mid 118.089431 -292.716204)
		(end 118.332758 -293.18077)
		(width 0.1143)
		(layer "In13.Cu")
		(net "P5E_CPU1_P2_TX_DP<6>")
	)
	(arc
		(start 117.93347 -272.972022)
		(mid 118.048146 -273.105356)
		(end 118.089426 -273.276314)
		(width 0.1143)
		(layer "In13.Cu")
		(net "P5E_CPU1_P2_TX_DP<6>")
	)
	(arc
		(start 118.332758 -279.291796)
		(mid 118.089431 -279.756362)
		(end 118.332758 -280.220928)
		(width 0.1143)
		(layer "In13.Cu")
		(net "P5E_CPU1_P2_TX_DP<6>")
	)
	(arc
		(start 118.335298 -287.390078)
		(mid 118.154646 -287.592823)
		(end 118.089426 -287.856422)
		(width 0.1143)
		(layer "In13.Cu")
		(net "P5E_CPU1_P2_TX_DP<6>")
	)
	(arc
		(start 117.4623 -272.161508)
		(mid 117.577727 -272.294884)
		(end 117.619272 -272.466308)
		(width 0.1143)
		(layer "In13.Cu")
		(net "P5E_CPU1_P2_TX_DP<6>")
	)
	(arc
		(start 118.089426 -273.276314)
		(mid 118.153941 -273.538533)
		(end 118.332758 -273.74088)
		(width 0.1143)
		(layer "In13.Cu")
		(net "P5E_CPU1_P2_TX_DP<6>")
	)
	(arc
		(start 118.332758 -280.911808)
		(mid 118.089431 -281.376374)
		(end 118.332758 -281.84094)
		(width 0.1143)
		(layer "In13.Cu")
		(net "P5E_CPU1_P2_TX_DP<6>")
	)
	(arc
		(start 118.402354 -283.501592)
		(mid 118.559331 -283.806392)
		(end 118.402354 -284.111192)
		(width 0.1143)
		(layer "In13.Cu")
		(net "P5E_CPU1_P2_TX_DP<6>")
	)
	(arc
		(start 118.402354 -294.841422)
		(mid 118.517781 -294.974798)
		(end 118.559326 -295.146222)
		(width 0.1143)
		(layer "In13.Cu")
		(net "P5E_CPU1_P2_TX_DP<6>")
	)
	(arc
		(start 118.402354 -273.78152)
		(mid 118.559331 -274.08632)
		(end 118.402354 -274.39112)
		(width 0.1143)
		(layer "In13.Cu")
		(net "P5E_CPU1_P2_TX_DP<6>")
	)
	(arc
		(start 118.559326 -295.146222)
		(mid 118.623841 -295.408441)
		(end 118.802658 -295.610788)
		(width 0.1143)
		(layer "In13.Cu")
		(net "P5E_CPU1_P2_TX_DP<6>")
	)
	(arc
		(start 118.332758 -289.011614)
		(mid 118.089431 -289.47618)
		(end 118.332758 -289.940746)
		(width 0.1143)
		(layer "In13.Cu")
		(net "P5E_CPU1_P2_TX_DP<6>")
	)
	(arc
		(start 118.332758 -276.051772)
		(mid 118.089431 -276.516338)
		(end 118.332758 -276.980904)
		(width 0.1143)
		(layer "In13.Cu")
		(net "P5E_CPU1_P2_TX_DP<6>")
	)
	(arc
		(start 118.332758 -277.671784)
		(mid 118.089431 -278.13635)
		(end 118.332758 -278.600916)
		(width 0.1143)
		(layer "In13.Cu")
		(net "P5E_CPU1_P2_TX_DP<6>")
	)
	(arc
		(start 118.332758 -285.771844)
		(mid 118.089431 -286.23641)
		(end 118.332758 -286.700976)
		(width 0.1143)
		(layer "In13.Cu")
		(net "P5E_CPU1_P2_TX_DP<6>")
	)
	(arc
		(start 117.155468 -271.739106)
		(mid 117.157256 -271.750555)
		(end 117.159278 -271.761966)
		(width 0.1143)
		(layer "In13.Cu")
		(net "P5E_CPU1_P2_TX_DP<6>")
	)
	(arc
		(start 118.402354 -281.88158)
		(mid 118.559331 -282.18638)
		(end 118.402354 -282.49118)
		(width 0.1143)
		(layer "In13.Cu")
		(net "P5E_CPU1_P2_TX_DP<6>")
	)
	(arc
		(start 118.332758 -284.151832)
		(mid 118.089431 -284.616398)
		(end 118.332758 -285.080964)
		(width 0.1143)
		(layer "In13.Cu")
		(net "P5E_CPU1_P2_TX_DP<6>")
	)
	(arc
		(start 118.332758 -274.43176)
		(mid 118.089431 -274.896326)
		(end 118.332758 -275.360892)
		(width 0.1143)
		(layer "In13.Cu")
		(net "P5E_CPU1_P2_TX_DP<6>")
	)
	(arc
		(start 118.402354 -289.981386)
		(mid 118.559331 -290.286186)
		(end 118.402354 -290.590986)
		(width 0.1143)
		(layer "In13.Cu")
		(net "P5E_CPU1_P2_TX_DP<6>")
	)
	(arc
		(start 118.873524 -295.651936)
		(mid 118.922456 -295.694024)
		(end 118.96344 -295.743884)
		(width 0.1143)
		(layer "In13.Cu")
		(net "P5E_CPU1_P2_TX_DP<6>")
	)
	(arc
		(start 118.402354 -285.121604)
		(mid 118.559331 -285.426404)
		(end 118.402354 -285.731204)
		(width 0.1143)
		(layer "In13.Cu")
		(net "P5E_CPU1_P2_TX_DP<6>")
	)
	(arc
		(start 118.402354 -277.021544)
		(mid 118.559331 -277.326344)
		(end 118.402354 -277.631144)
		(width 0.1143)
		(layer "In13.Cu")
		(net "P5E_CPU1_P2_TX_DP<6>")
	)
	(arc
		(start 118.559326 -288.666174)
		(mid 118.517777 -288.837596)
		(end 118.402354 -288.970974)
		(width 0.1143)
		(layer "In13.Cu")
		(net "P5E_CPU1_P2_TX_DP<6>")
	)
	(arc
		(start 118.402354 -280.261568)
		(mid 118.559331 -280.566368)
		(end 118.402354 -280.871168)
		(width 0.1143)
		(layer "In13.Cu")
		(net "P5E_CPU1_P2_TX_DP<6>")
	)
	(segment
		(start 116.30787 -273.010376)
		(end 116.774722 -273.276314)
		(width 0.12954)
		(layer "F.Cu")
		(net "P5E_CPU1_P2_TX_DP<5>")
	)
	(segment
		(start 149.720554 -371.76964)
		(end 149.720554 -372.47322)
		(width 0.12954)
		(layer "F.Cu")
		(net "P5E_CPU1_P2_TX_DP<5>")
	)
	(segment
		(start 149.450044 -371.49913)
		(end 149.720554 -371.76964)
		(width 0.12954)
		(layer "F.Cu")
		(net "P5E_CPU1_P2_TX_DP<5>")
	)
	(segment
		(start 149.720554 -372.47322)
		(end 149.424644 -372.76913)
		(width 0.12954)
		(layer "F.Cu")
		(net "P5E_CPU1_P2_TX_DP<5>")
	)
	(segment
		(start 149.74062 -368.910616)
		(end 149.740874 -368.91087)
		(width 0.14224)
		(layer "In13.Cu")
		(net "P5E_CPU1_P2_TX_DP<5>")
	)
	(segment
		(start 117.392704 -285.080964)
		(end 117.430804 -285.103316)
		(width 0.1143)
		(layer "In13.Cu")
		(net "P5E_CPU1_P2_TX_DP<5>")
	)
	(segment
		(start 129.356866 -314.57392)
		(end 131.113784 -317.203328)
		(width 0.14224)
		(layer "In13.Cu")
		(net "P5E_CPU1_P2_TX_DP<5>")
	)
	(segment
		(start 117.908324 -295.637458)
		(end 117.909594 -295.63822)
		(width 0.1143)
		(layer "In13.Cu")
		(net "P5E_CPU1_P2_TX_DP<5>")
	)
	(segment
		(start 117.392704 -294.800782)
		(end 117.430804 -294.823134)
		(width 0.1143)
		(layer "In13.Cu")
		(net "P5E_CPU1_P2_TX_DP<5>")
	)
	(segment
		(start 117.43182 -283.483812)
		(end 117.432582 -283.48432)
		(width 0.1143)
		(layer "In13.Cu")
		(net "P5E_CPU1_P2_TX_DP<5>")
	)
	(segment
		(start 117.430804 -293.203122)
		(end 117.43182 -293.20363)
		(width 0.1143)
		(layer "In13.Cu")
		(net "P5E_CPU1_P2_TX_DP<5>")
	)
	(segment
		(start 117.434868 -293.847012)
		(end 117.432582 -293.848536)
		(width 0.1143)
		(layer "In13.Cu")
		(net "P5E_CPU1_P2_TX_DP<5>")
	)
	(segment
		(start 149.740874 -371.2083)
		(end 149.450044 -371.49913)
		(width 0.14224)
		(layer "In13.Cu")
		(net "P5E_CPU1_P2_TX_DP<5>")
	)
	(segment
		(start 134.485888 -323.511418)
		(end 134.60349 -323.79666)
		(width 0.14224)
		(layer "In13.Cu")
		(net "P5E_CPU1_P2_TX_DP<5>")
	)
	(segment
		(start 117.392704 -293.18077)
		(end 117.430804 -293.203122)
		(width 0.1143)
		(layer "In13.Cu")
		(net "P5E_CPU1_P2_TX_DP<5>")
	)
	(segment
		(start 117.46865 -292.206934)
		(end 117.46357 -292.21049)
		(width 0.1143)
		(layer "In13.Cu")
		(net "P5E_CPU1_P2_TX_DP<5>")
	)
	(segment
		(start 117.4623 -279.251156)
		(end 117.43182 -279.268936)
		(width 0.1143)
		(layer "In13.Cu")
		(net "P5E_CPU1_P2_TX_DP<5>")
	)
	(segment
		(start 117.430804 -284.12948)
		(end 117.392704 -284.151832)
		(width 0.1143)
		(layer "In13.Cu")
		(net "P5E_CPU1_P2_TX_DP<5>")
	)
	(segment
		(start 117.3988 -288.324544)
		(end 117.399054 -288.324544)
		(width 0.1143)
		(layer "In13.Cu")
		(net "P5E_CPU1_P2_TX_DP<5>")
	)
	(segment
		(start 117.434614 -289.965384)
		(end 117.435122 -289.965384)
		(width 0.1143)
		(layer "In13.Cu")
		(net "P5E_CPU1_P2_TX_DP<5>")
	)
	(segment
		(start 117.912134 -295.63949)
		(end 117.93347 -295.651936)
		(width 0.1143)
		(layer "In13.Cu")
		(net "P5E_CPU1_P2_TX_DP<5>")
	)
	(segment
		(start 117.392704 -286.700976)
		(end 117.465348 -286.743394)
		(width 0.1143)
		(layer "In13.Cu")
		(net "P5E_CPU1_P2_TX_DP<5>")
	)
	(segment
		(start 117.426232 -292.23208)
		(end 117.392704 -292.251638)
		(width 0.1143)
		(layer "In13.Cu")
		(net "P5E_CPU1_P2_TX_DP<5>")
	)
	(segment
		(start 118.04396 -297.775376)
		(end 119.224044 -300.625764)
		(width 0.14224)
		(layer "In13.Cu")
		(net "P5E_CPU1_P2_TX_DP<5>")
	)
	(segment
		(start 117.619526 -295.141904)
		(end 117.619526 -295.146222)
		(width 0.1143)
		(layer "In13.Cu")
		(net "P5E_CPU1_P2_TX_DP<5>")
	)
	(segment
		(start 117.619526 -287.046162)
		(end 117.619526 -287.050734)
		(width 0.1143)
		(layer "In13.Cu")
		(net "P5E_CPU1_P2_TX_DP<5>")
	)
	(segment
		(start 117.432582 -293.848536)
		(end 117.43182 -293.84879)
		(width 0.1143)
		(layer "In13.Cu")
		(net "P5E_CPU1_P2_TX_DP<5>")
	)
	(segment
		(start 117.434868 -288.345372)
		(end 117.435122 -288.345372)
		(width 0.1143)
		(layer "In13.Cu")
		(net "P5E_CPU1_P2_TX_DP<5>")
	)
	(segment
		(start 117.432582 -284.128718)
		(end 117.43182 -284.128972)
		(width 0.1143)
		(layer "In13.Cu")
		(net "P5E_CPU1_P2_TX_DP<5>")
	)
	(segment
		(start 117.902482 -295.634156)
		(end 117.905276 -295.63568)
		(width 0.1143)
		(layer "In13.Cu")
		(net "P5E_CPU1_P2_TX_DP<5>")
	)
	(segment
		(start 117.392704 -278.600916)
		(end 117.43182 -278.623776)
		(width 0.1143)
		(layer "In13.Cu")
		(net "P5E_CPU1_P2_TX_DP<5>")
	)
	(segment
		(start 117.432582 -283.48432)
		(end 117.434614 -283.48559)
		(width 0.1143)
		(layer "In13.Cu")
		(net "P5E_CPU1_P2_TX_DP<5>")
	)
	(segment
		(start 118.04396 -296.29862)
		(end 118.04396 -296.327068)
		(width 0.1143)
		(layer "In13.Cu")
		(net "P5E_CPU1_P2_TX_DP<5>")
	)
	(segment
		(start 117.435376 -284.127194)
		(end 117.434868 -284.127194)
		(width 0.1143)
		(layer "In13.Cu")
		(net "P5E_CPU1_P2_TX_DP<5>")
	)
	(segment
		(start 117.432582 -292.22827)
		(end 117.43182 -292.228778)
		(width 0.1143)
		(layer "In13.Cu")
		(net "P5E_CPU1_P2_TX_DP<5>")
	)
	(segment
		(start 117.392704 -280.220928)
		(end 117.43182 -280.243788)
		(width 0.1143)
		(layer "In13.Cu")
		(net "P5E_CPU1_P2_TX_DP<5>")
	)
	(segment
		(start 117.4623 -276.011132)
		(end 117.43182 -276.028912)
		(width 0.1143)
		(layer "In13.Cu")
		(net "P5E_CPU1_P2_TX_DP<5>")
	)
	(segment
		(start 117.434868 -290.606988)
		(end 117.432582 -290.608512)
		(width 0.1143)
		(layer "In13.Cu")
		(net "P5E_CPU1_P2_TX_DP<5>")
	)
	(segment
		(start 117.43182 -285.103824)
		(end 117.432582 -285.104332)
		(width 0.1143)
		(layer "In13.Cu")
		(net "P5E_CPU1_P2_TX_DP<5>")
	)
	(segment
		(start 117.432582 -289.964114)
		(end 117.434614 -289.965384)
		(width 0.1143)
		(layer "In13.Cu")
		(net "P5E_CPU1_P2_TX_DP<5>")
	)
	(segment
		(start 117.43182 -276.028912)
		(end 117.392704 -276.051772)
		(width 0.1143)
		(layer "In13.Cu")
		(net "P5E_CPU1_P2_TX_DP<5>")
	)
	(segment
		(start 117.392704 -289.940746)
		(end 117.430804 -289.963098)
		(width 0.1143)
		(layer "In13.Cu")
		(net "P5E_CPU1_P2_TX_DP<5>")
	)
	(segment
		(start 149.740874 -368.91087)
		(end 149.740874 -371.2083)
		(width 0.14224)
		(layer "In13.Cu")
		(net "P5E_CPU1_P2_TX_DP<5>")
	)
	(segment
		(start 117.46357 -287.350454)
		(end 117.395244 -287.390078)
		(width 0.1143)
		(layer "In13.Cu")
		(net "P5E_CPU1_P2_TX_DP<5>")
	)
	(segment
		(start 117.427248 -292.231572)
		(end 117.426232 -292.23208)
		(width 0.1143)
		(layer "In13.Cu")
		(net "P5E_CPU1_P2_TX_DP<5>")
	)
	(segment
		(start 118.08968 -296.2529)
		(end 118.04396 -296.29862)
		(width 0.1143)
		(layer "In13.Cu")
		(net "P5E_CPU1_P2_TX_DP<5>")
	)
	(segment
		(start 117.428772 -292.230556)
		(end 117.427248 -292.231572)
		(width 0.1143)
		(layer "In13.Cu")
		(net "P5E_CPU1_P2_TX_DP<5>")
	)
	(segment
		(start 117.392704 -288.320988)
		(end 117.3988 -288.324544)
		(width 0.1143)
		(layer "In13.Cu")
		(net "P5E_CPU1_P2_TX_DP<5>")
	)
	(segment
		(start 117.430804 -294.823134)
		(end 117.43436 -294.824912)
		(width 0.1143)
		(layer "In13.Cu")
		(net "P5E_CPU1_P2_TX_DP<5>")
	)
	(segment
		(start 117.432582 -282.508706)
		(end 117.43182 -282.50896)
		(width 0.1143)
		(layer "In13.Cu")
		(net "P5E_CPU1_P2_TX_DP<5>")
	)
	(segment
		(start 117.435376 -285.747206)
		(end 117.434868 -285.747206)
		(width 0.1143)
		(layer "In13.Cu")
		(net "P5E_CPU1_P2_TX_DP<5>")
	)
	(segment
		(start 117.430804 -281.863292)
		(end 117.43182 -281.8638)
		(width 0.1143)
		(layer "In13.Cu")
		(net "P5E_CPU1_P2_TX_DP<5>")
	)
	(segment
		(start 117.434868 -285.747206)
		(end 117.432582 -285.74873)
		(width 0.1143)
		(layer "In13.Cu")
		(net "P5E_CPU1_P2_TX_DP<5>")
	)
	(segment
		(start 120.117108 -302.114966)
		(end 129.356866 -314.57392)
		(width 0.14224)
		(layer "In13.Cu")
		(net "P5E_CPU1_P2_TX_DP<5>")
	)
	(segment
		(start 117.43182 -278.623776)
		(end 117.4623 -278.641556)
		(width 0.1143)
		(layer "In13.Cu")
		(net "P5E_CPU1_P2_TX_DP<5>")
	)
	(segment
		(start 117.072664 -273.276314)
		(end 117.155468 -273.359118)
		(width 0.1143)
		(layer "In13.Cu")
		(net "P5E_CPU1_P2_TX_DP<5>")
	)
	(segment
		(start 117.862604 -295.610788)
		(end 117.900704 -295.63314)
		(width 0.1143)
		(layer "In13.Cu")
		(net "P5E_CPU1_P2_TX_DP<5>")
	)
	(segment
		(start 117.43182 -285.748984)
		(end 117.430804 -285.749492)
		(width 0.1143)
		(layer "In13.Cu")
		(net "P5E_CPU1_P2_TX_DP<5>")
	)
	(segment
		(start 117.43182 -293.84879)
		(end 117.430804 -293.849298)
		(width 0.1143)
		(layer "In13.Cu")
		(net "P5E_CPU1_P2_TX_DP<5>")
	)
	(segment
		(start 117.43182 -282.50896)
		(end 117.430804 -282.509468)
		(width 0.1143)
		(layer "In13.Cu")
		(net "P5E_CPU1_P2_TX_DP<5>")
	)
	(segment
		(start 117.434868 -288.986976)
		(end 117.432582 -288.9885)
		(width 0.1143)
		(layer "In13.Cu")
		(net "P5E_CPU1_P2_TX_DP<5>")
	)
	(segment
		(start 134.60349 -323.79666)
		(end 139.930124 -350.57461)
		(width 0.14224)
		(layer "In13.Cu")
		(net "P5E_CPU1_P2_TX_DP<5>")
	)
	(segment
		(start 117.43182 -288.988754)
		(end 117.430804 -288.989262)
		(width 0.1143)
		(layer "In13.Cu")
		(net "P5E_CPU1_P2_TX_DP<5>")
	)
	(segment
		(start 117.43182 -277.003764)
		(end 117.4623 -277.021544)
		(width 0.1143)
		(layer "In13.Cu")
		(net "P5E_CPU1_P2_TX_DP<5>")
	)
	(segment
		(start 117.43182 -277.648924)
		(end 117.392704 -277.671784)
		(width 0.1143)
		(layer "In13.Cu")
		(net "P5E_CPU1_P2_TX_DP<5>")
	)
	(segment
		(start 117.432582 -293.204138)
		(end 117.434614 -293.205408)
		(width 0.1143)
		(layer "In13.Cu")
		(net "P5E_CPU1_P2_TX_DP<5>")
	)
	(segment
		(start 117.43182 -284.128972)
		(end 117.430804 -284.12948)
		(width 0.1143)
		(layer "In13.Cu")
		(net "P5E_CPU1_P2_TX_DP<5>")
	)
	(segment
		(start 117.434614 -293.205408)
		(end 117.435122 -293.205408)
		(width 0.1143)
		(layer "In13.Cu")
		(net "P5E_CPU1_P2_TX_DP<5>")
	)
	(segment
		(start 117.430804 -285.103316)
		(end 117.43182 -285.103824)
		(width 0.1143)
		(layer "In13.Cu")
		(net "P5E_CPU1_P2_TX_DP<5>")
	)
	(segment
		(start 117.430804 -288.989262)
		(end 117.392704 -289.011614)
		(width 0.1143)
		(layer "In13.Cu")
		(net "P5E_CPU1_P2_TX_DP<5>")
	)
	(segment
		(start 117.43182 -280.888948)
		(end 117.393212 -280.911554)
		(width 0.1143)
		(layer "In13.Cu")
		(net "P5E_CPU1_P2_TX_DP<5>")
	)
	(segment
		(start 117.46357 -292.21049)
		(end 117.432582 -292.22827)
		(width 0.1143)
		(layer "In13.Cu")
		(net "P5E_CPU1_P2_TX_DP<5>")
	)
	(segment
		(start 117.43182 -274.4089)
		(end 117.392704 -274.43176)
		(width 0.1143)
		(layer "In13.Cu")
		(net "P5E_CPU1_P2_TX_DP<5>")
	)
	(segment
		(start 117.434614 -281.865578)
		(end 117.435122 -281.865578)
		(width 0.1143)
		(layer "In13.Cu")
		(net "P5E_CPU1_P2_TX_DP<5>")
	)
	(segment
		(start 145.123154 -361.410504)
		(end 149.11705 -367.232438)
		(width 0.14224)
		(layer "In13.Cu")
		(net "P5E_CPU1_P2_TX_DP<5>")
	)
	(segment
		(start 118.04396 -296.327068)
		(end 118.04396 -297.775376)
		(width 0.14224)
		(layer "In13.Cu")
		(net "P5E_CPU1_P2_TX_DP<5>")
	)
	(segment
		(start 117.434868 -282.507182)
		(end 117.432582 -282.508706)
		(width 0.1143)
		(layer "In13.Cu")
		(net "P5E_CPU1_P2_TX_DP<5>")
	)
	(segment
		(start 117.434868 -284.127194)
		(end 117.432582 -284.128718)
		(width 0.1143)
		(layer "In13.Cu")
		(net "P5E_CPU1_P2_TX_DP<5>")
	)
	(segment
		(start 117.399054 -288.324544)
		(end 117.434868 -288.345372)
		(width 0.1143)
		(layer "In13.Cu")
		(net "P5E_CPU1_P2_TX_DP<5>")
	)
	(segment
		(start 117.430804 -292.229286)
		(end 117.428772 -292.230556)
		(width 0.1143)
		(layer "In13.Cu")
		(net "P5E_CPU1_P2_TX_DP<5>")
	)
	(segment
		(start 117.435376 -290.606988)
		(end 117.434868 -290.606988)
		(width 0.1143)
		(layer "In13.Cu")
		(net "P5E_CPU1_P2_TX_DP<5>")
	)
	(segment
		(start 117.906038 -295.636188)
		(end 117.907562 -295.63695)
		(width 0.1143)
		(layer "In13.Cu")
		(net "P5E_CPU1_P2_TX_DP<5>")
	)
	(segment
		(start 117.392704 -273.74088)
		(end 117.43182 -273.76374)
		(width 0.1143)
		(layer "In13.Cu")
		(net "P5E_CPU1_P2_TX_DP<5>")
	)
	(segment
		(start 117.900704 -295.63314)
		(end 117.90172 -295.633648)
		(width 0.1143)
		(layer "In13.Cu")
		(net "P5E_CPU1_P2_TX_DP<5>")
	)
	(segment
		(start 117.432582 -285.74873)
		(end 117.43182 -285.748984)
		(width 0.1143)
		(layer "In13.Cu")
		(net "P5E_CPU1_P2_TX_DP<5>")
	)
	(segment
		(start 117.435376 -293.847012)
		(end 117.434868 -293.847012)
		(width 0.1143)
		(layer "In13.Cu")
		(net "P5E_CPU1_P2_TX_DP<5>")
	)
	(segment
		(start 117.43182 -281.8638)
		(end 117.432582 -281.864308)
		(width 0.1143)
		(layer "In13.Cu")
		(net "P5E_CPU1_P2_TX_DP<5>")
	)
	(segment
		(start 117.435376 -282.507182)
		(end 117.434868 -282.507182)
		(width 0.1143)
		(layer "In13.Cu")
		(net "P5E_CPU1_P2_TX_DP<5>")
	)
	(segment
		(start 117.43182 -289.963606)
		(end 117.432582 -289.964114)
		(width 0.1143)
		(layer "In13.Cu")
		(net "P5E_CPU1_P2_TX_DP<5>")
	)
	(segment
		(start 117.907562 -295.63695)
		(end 117.908324 -295.637458)
		(width 0.1143)
		(layer "In13.Cu")
		(net "P5E_CPU1_P2_TX_DP<5>")
	)
	(segment
		(start 118.08968 -295.956228)
		(end 118.08968 -296.2529)
		(width 0.1143)
		(layer "In13.Cu")
		(net "P5E_CPU1_P2_TX_DP<5>")
	)
	(segment
		(start 117.399562 -283.465016)
		(end 117.400324 -283.465524)
		(width 0.1143)
		(layer "In13.Cu")
		(net "P5E_CPU1_P2_TX_DP<5>")
	)
	(segment
		(start 117.43182 -280.243788)
		(end 117.4623 -280.261568)
		(width 0.1143)
		(layer "In13.Cu")
		(net "P5E_CPU1_P2_TX_DP<5>")
	)
	(segment
		(start 117.432582 -290.608512)
		(end 117.43182 -290.608766)
		(width 0.1143)
		(layer "In13.Cu")
		(net "P5E_CPU1_P2_TX_DP<5>")
	)
	(segment
		(start 117.392704 -276.980904)
		(end 117.43182 -277.003764)
		(width 0.1143)
		(layer "In13.Cu")
		(net "P5E_CPU1_P2_TX_DP<5>")
	)
	(segment
		(start 117.392704 -281.84094)
		(end 117.430804 -281.863292)
		(width 0.1143)
		(layer "In13.Cu")
		(net "P5E_CPU1_P2_TX_DP<5>")
	)
	(segment
		(start 117.43182 -291.583618)
		(end 117.432582 -291.584126)
		(width 0.1143)
		(layer "In13.Cu")
		(net "P5E_CPU1_P2_TX_DP<5>")
	)
	(segment
		(start 117.392704 -283.460952)
		(end 117.399562 -283.465016)
		(width 0.1143)
		(layer "In13.Cu")
		(net "P5E_CPU1_P2_TX_DP<5>")
	)
	(segment
		(start 117.434614 -285.105602)
		(end 117.435122 -285.105602)
		(width 0.1143)
		(layer "In13.Cu")
		(net "P5E_CPU1_P2_TX_DP<5>")
	)
	(segment
		(start 117.430804 -290.609274)
		(end 117.392704 -290.631626)
		(width 0.1143)
		(layer "In13.Cu")
		(net "P5E_CPU1_P2_TX_DP<5>")
	)
	(segment
		(start 117.430804 -291.58311)
		(end 117.43182 -291.583618)
		(width 0.1143)
		(layer "In13.Cu")
		(net "P5E_CPU1_P2_TX_DP<5>")
	)
	(segment
		(start 117.432582 -291.584126)
		(end 117.46357 -291.601906)
		(width 0.1143)
		(layer "In13.Cu")
		(net "P5E_CPU1_P2_TX_DP<5>")
	)
	(segment
		(start 117.4623 -274.39112)
		(end 117.43182 -274.4089)
		(width 0.1143)
		(layer "In13.Cu")
		(net "P5E_CPU1_P2_TX_DP<5>")
	)
	(segment
		(start 117.432582 -281.864308)
		(end 117.434614 -281.865578)
		(width 0.1143)
		(layer "In13.Cu")
		(net "P5E_CPU1_P2_TX_DP<5>")
	)
	(segment
		(start 117.90172 -295.633648)
		(end 117.902482 -295.634156)
		(width 0.1143)
		(layer "In13.Cu")
		(net "P5E_CPU1_P2_TX_DP<5>")
	)
	(segment
		(start 139.930124 -350.57461)
		(end 142.837154 -357.133144)
		(width 0.14224)
		(layer "In13.Cu")
		(net "P5E_CPU1_P2_TX_DP<5>")
	)
	(segment
		(start 117.393212 -280.911554)
		(end 117.392704 -280.911808)
		(width 0.1143)
		(layer "In13.Cu")
		(net "P5E_CPU1_P2_TX_DP<5>")
	)
	(segment
		(start 117.46738 -287.34766)
		(end 117.46357 -287.350454)
		(width 0.1143)
		(layer "In13.Cu")
		(net "P5E_CPU1_P2_TX_DP<5>")
	)
	(segment
		(start 117.434614 -283.48559)
		(end 117.435122 -283.48559)
		(width 0.1143)
		(layer "In13.Cu")
		(net "P5E_CPU1_P2_TX_DP<5>")
	)
	(segment
		(start 149.11705 -367.232438)
		(end 149.74062 -368.910616)
		(width 0.14224)
		(layer "In13.Cu")
		(net "P5E_CPU1_P2_TX_DP<5>")
	)
	(segment
		(start 117.43182 -290.608766)
		(end 117.430804 -290.609274)
		(width 0.1143)
		(layer "In13.Cu")
		(net "P5E_CPU1_P2_TX_DP<5>")
	)
	(segment
		(start 117.43182 -275.383752)
		(end 117.4623 -275.401532)
		(width 0.1143)
		(layer "In13.Cu")
		(net "P5E_CPU1_P2_TX_DP<5>")
	)
	(segment
		(start 117.43182 -293.20363)
		(end 117.432582 -293.204138)
		(width 0.1143)
		(layer "In13.Cu")
		(net "P5E_CPU1_P2_TX_DP<5>")
	)
	(segment
		(start 117.392704 -291.560758)
		(end 117.430804 -291.58311)
		(width 0.1143)
		(layer "In13.Cu")
		(net "P5E_CPU1_P2_TX_DP<5>")
	)
	(segment
		(start 117.909594 -295.63822)
		(end 117.912134 -295.63949)
		(width 0.1143)
		(layer "In13.Cu")
		(net "P5E_CPU1_P2_TX_DP<5>")
	)
	(segment
		(start 142.837154 -357.133144)
		(end 145.123154 -361.410504)
		(width 0.14224)
		(layer "In13.Cu")
		(net "P5E_CPU1_P2_TX_DP<5>")
	)
	(segment
		(start 117.46357 -291.601906)
		(end 117.46865 -291.605462)
		(width 0.1143)
		(layer "In13.Cu")
		(net "P5E_CPU1_P2_TX_DP<5>")
	)
	(segment
		(start 117.430804 -289.963098)
		(end 117.43182 -289.963606)
		(width 0.1143)
		(layer "In13.Cu")
		(net "P5E_CPU1_P2_TX_DP<5>")
	)
	(segment
		(start 117.4623 -277.631144)
		(end 117.43182 -277.648924)
		(width 0.1143)
		(layer "In13.Cu")
		(net "P5E_CPU1_P2_TX_DP<5>")
	)
	(segment
		(start 119.224044 -300.625764)
		(end 120.117108 -302.114966)
		(width 0.14224)
		(layer "In13.Cu")
		(net "P5E_CPU1_P2_TX_DP<5>")
	)
	(segment
		(start 117.43182 -273.76374)
		(end 117.4623 -273.78152)
		(width 0.1143)
		(layer "In13.Cu")
		(net "P5E_CPU1_P2_TX_DP<5>")
	)
	(segment
		(start 116.774722 -273.276314)
		(end 117.072664 -273.276314)
		(width 0.1143)
		(layer "In13.Cu")
		(net "P5E_CPU1_P2_TX_DP<5>")
	)
	(segment
		(start 117.43182 -279.268936)
		(end 117.392704 -279.291796)
		(width 0.1143)
		(layer "In13.Cu")
		(net "P5E_CPU1_P2_TX_DP<5>")
	)
	(segment
		(start 117.4623 -280.871168)
		(end 117.43182 -280.888948)
		(width 0.1143)
		(layer "In13.Cu")
		(net "P5E_CPU1_P2_TX_DP<5>")
	)
	(segment
		(start 117.430804 -285.749492)
		(end 117.392704 -285.771844)
		(width 0.1143)
		(layer "In13.Cu")
		(net "P5E_CPU1_P2_TX_DP<5>")
	)
	(segment
		(start 117.43182 -292.228778)
		(end 117.430804 -292.229286)
		(width 0.1143)
		(layer "In13.Cu")
		(net "P5E_CPU1_P2_TX_DP<5>")
	)
	(segment
		(start 117.905276 -295.63568)
		(end 117.906038 -295.636188)
		(width 0.1143)
		(layer "In13.Cu")
		(net "P5E_CPU1_P2_TX_DP<5>")
	)
	(segment
		(start 117.435376 -288.986976)
		(end 117.434868 -288.986976)
		(width 0.1143)
		(layer "In13.Cu")
		(net "P5E_CPU1_P2_TX_DP<5>")
	)
	(segment
		(start 131.113784 -317.203328)
		(end 134.485888 -323.511418)
		(width 0.14224)
		(layer "In13.Cu")
		(net "P5E_CPU1_P2_TX_DP<5>")
	)
	(segment
		(start 117.43436 -294.824912)
		(end 117.464586 -294.842946)
		(width 0.1143)
		(layer "In13.Cu")
		(net "P5E_CPU1_P2_TX_DP<5>")
	)
	(segment
		(start 117.619526 -295.146222)
		(end 117.619272 -295.146222)
		(width 0.1143)
		(layer "In13.Cu")
		(net "P5E_CPU1_P2_TX_DP<5>")
	)
	(segment
		(start 117.392704 -275.360892)
		(end 117.43182 -275.383752)
		(width 0.1143)
		(layer "In13.Cu")
		(net "P5E_CPU1_P2_TX_DP<5>")
	)
	(segment
		(start 117.400324 -283.465524)
		(end 117.43182 -283.483812)
		(width 0.1143)
		(layer "In13.Cu")
		(net "P5E_CPU1_P2_TX_DP<5>")
	)
	(segment
		(start 117.430804 -282.509468)
		(end 117.392704 -282.53182)
		(width 0.1143)
		(layer "In13.Cu")
		(net "P5E_CPU1_P2_TX_DP<5>")
	)
	(segment
		(start 117.432582 -288.9885)
		(end 117.43182 -288.988754)
		(width 0.1143)
		(layer "In13.Cu")
		(net "P5E_CPU1_P2_TX_DP<5>")
	)
	(segment
		(start 117.432582 -285.104332)
		(end 117.434614 -285.105602)
		(width 0.1143)
		(layer "In13.Cu")
		(net "P5E_CPU1_P2_TX_DP<5>")
	)
	(segment
		(start 117.430804 -293.849298)
		(end 117.392704 -293.87165)
		(width 0.1143)
		(layer "In13.Cu")
		(net "P5E_CPU1_P2_TX_DP<5>")
	)
	(arc
		(start 117.435122 -288.345372)
		(mid 117.619855 -288.666064)
		(end 117.435376 -288.986976)
		(width 0.1143)
		(layer "In13.Cu")
		(net "P5E_CPU1_P2_TX_DP<5>")
	)
	(arc
		(start 117.392704 -290.631626)
		(mid 117.149377 -291.096192)
		(end 117.392704 -291.560758)
		(width 0.1143)
		(layer "In13.Cu")
		(net "P5E_CPU1_P2_TX_DP<5>")
	)
	(arc
		(start 117.619526 -287.050734)
		(mid 117.579271 -287.217547)
		(end 117.46738 -287.34766)
		(width 0.1143)
		(layer "In13.Cu")
		(net "P5E_CPU1_P2_TX_DP<5>")
	)
	(arc
		(start 118.023386 -295.743884)
		(mid 118.072706 -295.845013)
		(end 118.08968 -295.956228)
		(width 0.1143)
		(layer "In13.Cu")
		(net "P5E_CPU1_P2_TX_DP<5>")
	)
	(arc
		(start 117.435122 -293.205408)
		(mid 117.619855 -293.5261)
		(end 117.435376 -293.847012)
		(width 0.1143)
		(layer "In13.Cu")
		(net "P5E_CPU1_P2_TX_DP<5>")
	)
	(arc
		(start 117.155468 -273.359118)
		(mid 117.157256 -273.370567)
		(end 117.159278 -273.381978)
		(width 0.1143)
		(layer "In13.Cu")
		(net "P5E_CPU1_P2_TX_DP<5>")
	)
	(arc
		(start 117.435122 -289.965384)
		(mid 117.619855 -290.286076)
		(end 117.435376 -290.606988)
		(width 0.1143)
		(layer "In13.Cu")
		(net "P5E_CPU1_P2_TX_DP<5>")
	)
	(arc
		(start 117.159278 -273.381978)
		(mid 117.240711 -273.584376)
		(end 117.392704 -273.74088)
		(width 0.1143)
		(layer "In13.Cu")
		(net "P5E_CPU1_P2_TX_DP<5>")
	)
	(arc
		(start 117.392704 -292.251638)
		(mid 117.149377 -292.716204)
		(end 117.392704 -293.18077)
		(width 0.1143)
		(layer "In13.Cu")
		(net "P5E_CPU1_P2_TX_DP<5>")
	)
	(arc
		(start 117.4623 -278.641556)
		(mid 117.619277 -278.946356)
		(end 117.4623 -279.251156)
		(width 0.1143)
		(layer "In13.Cu")
		(net "P5E_CPU1_P2_TX_DP<5>")
	)
	(arc
		(start 117.392704 -274.43176)
		(mid 117.149377 -274.896326)
		(end 117.392704 -275.360892)
		(width 0.1143)
		(layer "In13.Cu")
		(net "P5E_CPU1_P2_TX_DP<5>")
	)
	(arc
		(start 117.392704 -280.911808)
		(mid 117.149377 -281.376374)
		(end 117.392704 -281.84094)
		(width 0.1143)
		(layer "In13.Cu")
		(net "P5E_CPU1_P2_TX_DP<5>")
	)
	(arc
		(start 117.46865 -291.605462)
		(mid 117.622748 -291.906198)
		(end 117.46865 -292.206934)
		(width 0.1143)
		(layer "In13.Cu")
		(net "P5E_CPU1_P2_TX_DP<5>")
	)
	(arc
		(start 117.392704 -277.671784)
		(mid 117.149377 -278.13635)
		(end 117.392704 -278.600916)
		(width 0.1143)
		(layer "In13.Cu")
		(net "P5E_CPU1_P2_TX_DP<5>")
	)
	(arc
		(start 117.464586 -294.842946)
		(mid 117.578469 -294.97356)
		(end 117.619526 -295.141904)
		(width 0.1143)
		(layer "In13.Cu")
		(net "P5E_CPU1_P2_TX_DP<5>")
	)
	(arc
		(start 117.392704 -293.87165)
		(mid 117.149377 -294.336216)
		(end 117.392704 -294.800782)
		(width 0.1143)
		(layer "In13.Cu")
		(net "P5E_CPU1_P2_TX_DP<5>")
	)
	(arc
		(start 117.392704 -276.051772)
		(mid 117.149377 -276.516338)
		(end 117.392704 -276.980904)
		(width 0.1143)
		(layer "In13.Cu")
		(net "P5E_CPU1_P2_TX_DP<5>")
	)
	(arc
		(start 117.4623 -275.401532)
		(mid 117.619277 -275.706332)
		(end 117.4623 -276.011132)
		(width 0.1143)
		(layer "In13.Cu")
		(net "P5E_CPU1_P2_TX_DP<5>")
	)
	(arc
		(start 117.392704 -279.291796)
		(mid 117.149377 -279.756362)
		(end 117.392704 -280.220928)
		(width 0.1143)
		(layer "In13.Cu")
		(net "P5E_CPU1_P2_TX_DP<5>")
	)
	(arc
		(start 117.392704 -282.53182)
		(mid 117.149377 -282.996386)
		(end 117.392704 -283.460952)
		(width 0.1143)
		(layer "In13.Cu")
		(net "P5E_CPU1_P2_TX_DP<5>")
	)
	(arc
		(start 117.4623 -273.78152)
		(mid 117.619277 -274.08632)
		(end 117.4623 -274.39112)
		(width 0.1143)
		(layer "In13.Cu")
		(net "P5E_CPU1_P2_TX_DP<5>")
	)
	(arc
		(start 117.392704 -285.771844)
		(mid 117.149377 -286.23641)
		(end 117.392704 -286.700976)
		(width 0.1143)
		(layer "In13.Cu")
		(net "P5E_CPU1_P2_TX_DP<5>")
	)
	(arc
		(start 117.435122 -285.105602)
		(mid 117.619855 -285.426294)
		(end 117.435376 -285.747206)
		(width 0.1143)
		(layer "In13.Cu")
		(net "P5E_CPU1_P2_TX_DP<5>")
	)
	(arc
		(start 117.4623 -280.261568)
		(mid 117.619277 -280.566368)
		(end 117.4623 -280.871168)
		(width 0.1143)
		(layer "In13.Cu")
		(net "P5E_CPU1_P2_TX_DP<5>")
	)
	(arc
		(start 117.392704 -284.151832)
		(mid 117.149377 -284.616398)
		(end 117.392704 -285.080964)
		(width 0.1143)
		(layer "In13.Cu")
		(net "P5E_CPU1_P2_TX_DP<5>")
	)
	(arc
		(start 117.4623 -277.021544)
		(mid 117.619277 -277.326344)
		(end 117.4623 -277.631144)
		(width 0.1143)
		(layer "In13.Cu")
		(net "P5E_CPU1_P2_TX_DP<5>")
	)
	(arc
		(start 117.435122 -281.865578)
		(mid 117.619855 -282.18627)
		(end 117.435376 -282.507182)
		(width 0.1143)
		(layer "In13.Cu")
		(net "P5E_CPU1_P2_TX_DP<5>")
	)
	(arc
		(start 117.465348 -286.743394)
		(mid 117.578755 -286.876283)
		(end 117.619526 -287.046162)
		(width 0.1143)
		(layer "In13.Cu")
		(net "P5E_CPU1_P2_TX_DP<5>")
	)
	(arc
		(start 117.392704 -289.011614)
		(mid 117.149377 -289.47618)
		(end 117.392704 -289.940746)
		(width 0.1143)
		(layer "In13.Cu")
		(net "P5E_CPU1_P2_TX_DP<5>")
	)
	(arc
		(start 117.149372 -287.856422)
		(mid 117.213887 -288.118641)
		(end 117.392704 -288.320988)
		(width 0.1143)
		(layer "In13.Cu")
		(net "P5E_CPU1_P2_TX_DP<5>")
	)
	(arc
		(start 117.395244 -287.390078)
		(mid 117.214592 -287.592823)
		(end 117.149372 -287.856422)
		(width 0.1143)
		(layer "In13.Cu")
		(net "P5E_CPU1_P2_TX_DP<5>")
	)
	(arc
		(start 117.619272 -295.146222)
		(mid 117.683787 -295.408441)
		(end 117.862604 -295.610788)
		(width 0.1143)
		(layer "In13.Cu")
		(net "P5E_CPU1_P2_TX_DP<5>")
	)
	(arc
		(start 117.93347 -295.651936)
		(mid 117.982402 -295.694024)
		(end 118.023386 -295.743884)
		(width 0.1143)
		(layer "In13.Cu")
		(net "P5E_CPU1_P2_TX_DP<5>")
	)
	(arc
		(start 117.435122 -283.48559)
		(mid 117.619855 -283.806282)
		(end 117.435376 -284.127194)
		(width 0.1143)
		(layer "In13.Cu")
		(net "P5E_CPU1_P2_TX_DP<5>")
	)
	(segment
		(start 148.018754 -374.23344)
		(end 148.018754 -374.93702)
		(width 0.12954)
		(layer "F.Cu")
		(net "P5E_CPU1_P2_TX_DP<4>")
	)
	(segment
		(start 147.748244 -373.96293)
		(end 148.018754 -374.23344)
		(width 0.12954)
		(layer "F.Cu")
		(net "P5E_CPU1_P2_TX_DP<4>")
	)
	(segment
		(start 148.018754 -374.93702)
		(end 147.722844 -375.23293)
		(width 0.12954)
		(layer "F.Cu")
		(net "P5E_CPU1_P2_TX_DP<4>")
	)
	(segment
		(start 116.30787 -269.770352)
		(end 116.774722 -270.03629)
		(width 0.12954)
		(layer "F.Cu")
		(net "P5E_CPU1_P2_TX_DP<4>")
	)
	(segment
		(start 116.491766 -288.343594)
		(end 116.492782 -288.344102)
		(width 0.1143)
		(layer "In13.Cu")
		(net "P5E_CPU1_P2_TX_DP<4>")
	)
	(segment
		(start 116.523516 -280.262076)
		(end 116.543328 -280.2763)
		(width 0.1143)
		(layer "In13.Cu")
		(net "P5E_CPU1_P2_TX_DP<4>")
	)
	(segment
		(start 116.49075 -274.409408)
		(end 116.489226 -274.410424)
		(width 0.1143)
		(layer "In13.Cu")
		(net "P5E_CPU1_P2_TX_DP<4>")
	)
	(segment
		(start 116.489226 -276.030436)
		(end 116.45265 -276.051772)
		(width 0.1143)
		(layer "In13.Cu")
		(net "P5E_CPU1_P2_TX_DP<4>")
	)
	(segment
		(start 116.46027 -273.745452)
		(end 116.491766 -273.76374)
		(width 0.1143)
		(layer "In13.Cu")
		(net "P5E_CPU1_P2_TX_DP<4>")
	)
	(segment
		(start 116.45265 -288.320988)
		(end 116.458238 -288.323782)
		(width 0.1143)
		(layer "In13.Cu")
		(net "P5E_CPU1_P2_TX_DP<4>")
	)
	(segment
		(start 116.46027 -281.845512)
		(end 116.491766 -281.8638)
		(width 0.1143)
		(layer "In13.Cu")
		(net "P5E_CPU1_P2_TX_DP<4>")
	)
	(segment
		(start 116.494814 -282.507182)
		(end 116.492528 -282.508706)
		(width 0.1143)
		(layer "In13.Cu")
		(net "P5E_CPU1_P2_TX_DP<4>")
	)
	(segment
		(start 139.083796 -351.028)
		(end 145.530316 -365.572802)
		(width 0.14224)
		(layer "In13.Cu")
		(net "P5E_CPU1_P2_TX_DP<4>")
	)
	(segment
		(start 116.491766 -278.623776)
		(end 116.492528 -278.624284)
		(width 0.1143)
		(layer "In13.Cu")
		(net "P5E_CPU1_P2_TX_DP<4>")
	)
	(segment
		(start 148.039074 -371.414548)
		(end 148.039074 -373.6721)
		(width 0.14224)
		(layer "In13.Cu")
		(net "P5E_CPU1_P2_TX_DP<4>")
	)
	(segment
		(start 116.491766 -293.203376)
		(end 116.492274 -293.20363)
		(width 0.1143)
		(layer "In13.Cu")
		(net "P5E_CPU1_P2_TX_DP<4>")
	)
	(segment
		(start 116.492528 -282.508452)
		(end 116.491766 -282.50896)
		(width 0.1143)
		(layer "In13.Cu")
		(net "P5E_CPU1_P2_TX_DP<4>")
	)
	(segment
		(start 116.50599 -284.120844)
		(end 116.505228 -284.121352)
		(width 0.1143)
		(layer "In13.Cu")
		(net "P5E_CPU1_P2_TX_DP<4>")
	)
	(segment
		(start 116.476018 -287.377886)
		(end 116.475256 -287.378394)
		(width 0.1143)
		(layer "In13.Cu")
		(net "P5E_CPU1_P2_TX_DP<4>")
	)
	(segment
		(start 116.492274 -292.228778)
		(end 116.491766 -292.229032)
		(width 0.1143)
		(layer "In13.Cu")
		(net "P5E_CPU1_P2_TX_DP<4>")
	)
	(segment
		(start 116.510054 -284.118304)
		(end 116.509292 -284.118812)
		(width 0.1143)
		(layer "In13.Cu")
		(net "P5E_CPU1_P2_TX_DP<4>")
	)
	(segment
		(start 116.489226 -285.750508)
		(end 116.45265 -285.771844)
		(width 0.1143)
		(layer "In13.Cu")
		(net "P5E_CPU1_P2_TX_DP<4>")
	)
	(segment
		(start 116.491766 -293.849044)
		(end 116.491766 -293.84879)
		(width 0.1143)
		(layer "In13.Cu")
		(net "P5E_CPU1_P2_TX_DP<4>")
	)
	(segment
		(start 116.491766 -285.748984)
		(end 116.49075 -285.749492)
		(width 0.1143)
		(layer "In13.Cu")
		(net "P5E_CPU1_P2_TX_DP<4>")
	)
	(segment
		(start 116.491766 -280.243788)
		(end 116.492528 -280.244296)
		(width 0.1143)
		(layer "In13.Cu")
		(net "P5E_CPU1_P2_TX_DP<4>")
	)
	(segment
		(start 116.491766 -274.4089)
		(end 116.49075 -274.409408)
		(width 0.1143)
		(layer "In13.Cu")
		(net "P5E_CPU1_P2_TX_DP<4>")
	)
	(segment
		(start 116.523516 -277.022052)
		(end 116.543328 -277.036276)
		(width 0.1143)
		(layer "In13.Cu")
		(net "P5E_CPU1_P2_TX_DP<4>")
	)
	(segment
		(start 116.492528 -278.624284)
		(end 116.523516 -278.642064)
		(width 0.1143)
		(layer "In13.Cu")
		(net "P5E_CPU1_P2_TX_DP<4>")
	)
	(segment
		(start 116.492528 -279.268428)
		(end 116.491766 -279.268936)
		(width 0.1143)
		(layer "In13.Cu")
		(net "P5E_CPU1_P2_TX_DP<4>")
	)
	(segment
		(start 116.491766 -292.229032)
		(end 116.491766 -292.228778)
		(width 0.1143)
		(layer "In13.Cu")
		(net "P5E_CPU1_P2_TX_DP<4>")
	)
	(segment
		(start 116.923566 -295.61155)
		(end 116.94668 -295.625012)
		(width 0.1143)
		(layer "In13.Cu")
		(net "P5E_CPU1_P2_TX_DP<4>")
	)
	(segment
		(start 116.455444 -280.909776)
		(end 116.45265 -280.911808)
		(width 0.1143)
		(layer "In13.Cu")
		(net "P5E_CPU1_P2_TX_DP<4>")
	)
	(segment
		(start 116.491766 -291.583618)
		(end 116.491766 -291.583364)
		(width 0.1143)
		(layer "In13.Cu")
		(net "P5E_CPU1_P2_TX_DP<4>")
	)
	(segment
		(start 116.492528 -274.408392)
		(end 116.491766 -274.4089)
		(width 0.1143)
		(layer "In13.Cu")
		(net "P5E_CPU1_P2_TX_DP<4>")
	)
	(segment
		(start 116.49075 -284.12948)
		(end 116.488464 -284.131004)
		(width 0.1143)
		(layer "In13.Cu")
		(net "P5E_CPU1_P2_TX_DP<4>")
	)
	(segment
		(start 116.489226 -290.61029)
		(end 116.45265 -290.631626)
		(width 0.1143)
		(layer "In13.Cu")
		(net "P5E_CPU1_P2_TX_DP<4>")
	)
	(segment
		(start 116.475256 -287.378394)
		(end 116.45519 -287.390078)
		(width 0.1143)
		(layer "In13.Cu")
		(net "P5E_CPU1_P2_TX_DP<4>")
	)
	(segment
		(start 133.743446 -324.25259)
		(end 139.045696 -350.907604)
		(width 0.14224)
		(layer "In13.Cu")
		(net "P5E_CPU1_P2_TX_DP<4>")
	)
	(segment
		(start 116.491766 -279.268936)
		(end 116.49075 -279.269444)
		(width 0.1143)
		(layer "In13.Cu")
		(net "P5E_CPU1_P2_TX_DP<4>")
	)
	(segment
		(start 116.50218 -294.836596)
		(end 116.511832 -294.836596)
		(width 0.1143)
		(layer "In13.Cu")
		(net "P5E_CPU1_P2_TX_DP<4>")
	)
	(segment
		(start 116.488718 -283.482034)
		(end 116.489734 -283.482542)
		(width 0.1143)
		(layer "In13.Cu")
		(net "P5E_CPU1_P2_TX_DP<4>")
	)
	(segment
		(start 116.491766 -291.583364)
		(end 116.492274 -291.583618)
		(width 0.1143)
		(layer "In13.Cu")
		(net "P5E_CPU1_P2_TX_DP<4>")
	)
	(segment
		(start 116.491766 -292.228778)
		(end 116.49075 -292.229286)
		(width 0.1143)
		(layer "In13.Cu")
		(net "P5E_CPU1_P2_TX_DP<4>")
	)
	(segment
		(start 145.553176 -365.63681)
		(end 146.31543 -368.68354)
		(width 0.14224)
		(layer "In13.Cu")
		(net "P5E_CPU1_P2_TX_DP<4>")
	)
	(segment
		(start 116.489226 -277.650448)
		(end 116.45265 -277.671784)
		(width 0.1143)
		(layer "In13.Cu")
		(net "P5E_CPU1_P2_TX_DP<4>")
	)
	(segment
		(start 116.489988 -285.102808)
		(end 116.49075 -285.103316)
		(width 0.1143)
		(layer "In13.Cu")
		(net "P5E_CPU1_P2_TX_DP<4>")
	)
	(segment
		(start 116.491766 -277.648924)
		(end 116.49075 -277.649432)
		(width 0.1143)
		(layer "In13.Cu")
		(net "P5E_CPU1_P2_TX_DP<4>")
	)
	(segment
		(start 116.49075 -292.229286)
		(end 116.489226 -292.230302)
		(width 0.1143)
		(layer "In13.Cu")
		(net "P5E_CPU1_P2_TX_DP<4>")
	)
	(segment
		(start 116.491766 -272.788888)
		(end 116.49075 -272.789396)
		(width 0.1143)
		(layer "In13.Cu")
		(net "P5E_CPU1_P2_TX_DP<4>")
	)
	(segment
		(start 116.491766 -293.84879)
		(end 116.49075 -293.849298)
		(width 0.1143)
		(layer "In13.Cu")
		(net "P5E_CPU1_P2_TX_DP<4>")
	)
	(segment
		(start 116.46027 -291.56533)
		(end 116.491766 -291.583618)
		(width 0.1143)
		(layer "In13.Cu")
		(net "P5E_CPU1_P2_TX_DP<4>")
	)
	(segment
		(start 116.679218 -287.036002)
		(end 116.677948 -287.04921)
		(width 0.1143)
		(layer "In13.Cu")
		(net "P5E_CPU1_P2_TX_DP<4>")
	)
	(segment
		(start 116.491766 -289.963606)
		(end 116.491766 -289.963352)
		(width 0.1143)
		(layer "In13.Cu")
		(net "P5E_CPU1_P2_TX_DP<4>")
	)
	(segment
		(start 116.489226 -274.410424)
		(end 116.45265 -274.43176)
		(width 0.1143)
		(layer "In13.Cu")
		(net "P5E_CPU1_P2_TX_DP<4>")
	)
	(segment
		(start 116.49075 -277.649432)
		(end 116.489226 -277.650448)
		(width 0.1143)
		(layer "In13.Cu")
		(net "P5E_CPU1_P2_TX_DP<4>")
	)
	(segment
		(start 116.46027 -275.365464)
		(end 116.491766 -275.383752)
		(width 0.1143)
		(layer "In13.Cu")
		(net "P5E_CPU1_P2_TX_DP<4>")
	)
	(segment
		(start 116.45265 -273.74088)
		(end 116.459508 -273.744944)
		(width 0.1143)
		(layer "In13.Cu")
		(net "P5E_CPU1_P2_TX_DP<4>")
	)
	(segment
		(start 116.46027 -293.185342)
		(end 116.491766 -293.20363)
		(width 0.1143)
		(layer "In13.Cu")
		(net "P5E_CPU1_P2_TX_DP<4>")
	)
	(segment
		(start 116.45265 -291.560758)
		(end 116.459508 -291.564822)
		(width 0.1143)
		(layer "In13.Cu")
		(net "P5E_CPU1_P2_TX_DP<4>")
	)
	(segment
		(start 116.491766 -282.50896)
		(end 116.48821 -282.510992)
		(width 0.1143)
		(layer "In13.Cu")
		(net "P5E_CPU1_P2_TX_DP<4>")
	)
	(segment
		(start 116.993416 -270.340582)
		(end 116.951252 -270.364966)
		(width 0.1143)
		(layer "In13.Cu")
		(net "P5E_CPU1_P2_TX_DP<4>")
	)
	(segment
		(start 147.27428 -370.408708)
		(end 147.274534 -370.408962)
		(width 0.14224)
		(layer "In13.Cu")
		(net "P5E_CPU1_P2_TX_DP<4>")
	)
	(segment
		(start 116.94668 -295.625012)
		(end 116.951252 -295.627806)
		(width 0.1143)
		(layer "In13.Cu")
		(net "P5E_CPU1_P2_TX_DP<4>")
	)
	(segment
		(start 116.489226 -279.27046)
		(end 116.45265 -279.291796)
		(width 0.1143)
		(layer "In13.Cu")
		(net "P5E_CPU1_P2_TX_DP<4>")
	)
	(segment
		(start 116.489226 -288.990278)
		(end 116.45265 -289.011614)
		(width 0.1143)
		(layer "In13.Cu")
		(net "P5E_CPU1_P2_TX_DP<4>")
	)
	(segment
		(start 116.46027 -289.945318)
		(end 116.491766 -289.963606)
		(width 0.1143)
		(layer "In13.Cu")
		(net "P5E_CPU1_P2_TX_DP<4>")
	)
	(segment
		(start 116.505228 -284.121352)
		(end 116.494306 -284.127702)
		(width 0.1143)
		(layer "In13.Cu")
		(net "P5E_CPU1_P2_TX_DP<4>")
	)
	(segment
		(start 116.492528 -281.864308)
		(end 116.49456 -281.865578)
		(width 0.1143)
		(layer "In13.Cu")
		(net "P5E_CPU1_P2_TX_DP<4>")
	)
	(segment
		(start 116.45265 -280.220928)
		(end 116.459508 -280.224992)
		(width 0.1143)
		(layer "In13.Cu")
		(net "P5E_CPU1_P2_TX_DP<4>")
	)
	(segment
		(start 116.491766 -290.608766)
		(end 116.49075 -290.609274)
		(width 0.1143)
		(layer "In13.Cu")
		(net "P5E_CPU1_P2_TX_DP<4>")
	)
	(segment
		(start 116.491766 -281.8638)
		(end 116.492528 -281.864308)
		(width 0.1143)
		(layer "In13.Cu")
		(net "P5E_CPU1_P2_TX_DP<4>")
	)
	(segment
		(start 116.492528 -277.004272)
		(end 116.523516 -277.022052)
		(width 0.1143)
		(layer "In13.Cu")
		(net "P5E_CPU1_P2_TX_DP<4>")
	)
	(segment
		(start 117.149626 -296.2529)
		(end 117.103906 -296.29862)
		(width 0.1143)
		(layer "In13.Cu")
		(net "P5E_CPU1_P2_TX_DP<4>")
	)
	(segment
		(start 147.670266 -370.608098)
		(end 147.758404 -370.68379)
		(width 0.14224)
		(layer "In13.Cu")
		(net "P5E_CPU1_P2_TX_DP<4>")
	)
	(segment
		(start 116.489226 -293.850314)
		(end 116.487956 -293.851076)
		(width 0.1143)
		(layer "In13.Cu")
		(net "P5E_CPU1_P2_TX_DP<4>")
	)
	(segment
		(start 116.459508 -272.124932)
		(end 116.46027 -272.12544)
		(width 0.1143)
		(layer "In13.Cu")
		(net "P5E_CPU1_P2_TX_DP<4>")
	)
	(segment
		(start 116.523516 -277.630636)
		(end 116.492528 -277.648416)
		(width 0.1143)
		(layer "In13.Cu")
		(net "P5E_CPU1_P2_TX_DP<4>")
	)
	(segment
		(start 116.48567 -294.820086)
		(end 116.50218 -294.836596)
		(width 0.1143)
		(layer "In13.Cu")
		(net "P5E_CPU1_P2_TX_DP<4>")
	)
	(segment
		(start 116.492528 -277.648416)
		(end 116.491766 -277.648924)
		(width 0.1143)
		(layer "In13.Cu")
		(net "P5E_CPU1_P2_TX_DP<4>")
	)
	(segment
		(start 116.491766 -271.168876)
		(end 116.45265 -271.191736)
		(width 0.1143)
		(layer "In13.Cu")
		(net "P5E_CPU1_P2_TX_DP<4>")
	)
	(segment
		(start 116.492528 -271.168368)
		(end 116.491766 -271.168876)
		(width 0.1143)
		(layer "In13.Cu")
		(net "P5E_CPU1_P2_TX_DP<4>")
	)
	(segment
		(start 117.072664 -270.03629)
		(end 117.142514 -270.10614)
		(width 0.1143)
		(layer "In13.Cu")
		(net "P5E_CPU1_P2_TX_DP<4>")
	)
	(segment
		(start 116.491766 -290.60902)
		(end 116.491766 -290.608766)
		(width 0.1143)
		(layer "In13.Cu")
		(net "P5E_CPU1_P2_TX_DP<4>")
	)
	(segment
		(start 146.330924 -368.808762)
		(end 146.330924 -369.440206)
		(width 0.14224)
		(layer "In13.Cu")
		(net "P5E_CPU1_P2_TX_DP<4>")
	)
	(segment
		(start 116.49075 -288.989262)
		(end 116.489226 -288.990278)
		(width 0.1143)
		(layer "In13.Cu")
		(net "P5E_CPU1_P2_TX_DP<4>")
	)
	(segment
		(start 116.523516 -280.87066)
		(end 116.455444 -280.909776)
		(width 0.1143)
		(layer "In13.Cu")
		(net "P5E_CPU1_P2_TX_DP<4>")
	)
	(segment
		(start 116.492528 -272.144236)
		(end 116.523516 -272.162016)
		(width 0.1143)
		(layer "In13.Cu")
		(net "P5E_CPU1_P2_TX_DP<4>")
	)
	(segment
		(start 116.774722 -270.03629)
		(end 117.072664 -270.03629)
		(width 0.1143)
		(layer "In13.Cu")
		(net "P5E_CPU1_P2_TX_DP<4>")
	)
	(segment
		(start 116.492528 -280.244296)
		(end 116.523516 -280.262076)
		(width 0.1143)
		(layer "In13.Cu")
		(net "P5E_CPU1_P2_TX_DP<4>")
	)
	(segment
		(start 116.509292 -284.118812)
		(end 116.50599 -284.120844)
		(width 0.1143)
		(layer "In13.Cu")
		(net "P5E_CPU1_P2_TX_DP<4>")
	)
	(segment
		(start 116.48821 -285.101792)
		(end 116.489988 -285.102808)
		(width 0.1143)
		(layer "In13.Cu")
		(net "P5E_CPU1_P2_TX_DP<4>")
	)
	(segment
		(start 117.103906 -296.29862)
		(end 117.103906 -296.327068)
		(width 0.1143)
		(layer "In13.Cu")
		(net "P5E_CPU1_P2_TX_DP<4>")
	)
	(segment
		(start 116.46027 -276.985476)
		(end 116.491766 -277.003764)
		(width 0.1143)
		(layer "In13.Cu")
		(net "P5E_CPU1_P2_TX_DP<4>")
	)
	(segment
		(start 116.459508 -289.94481)
		(end 116.46027 -289.945318)
		(width 0.1143)
		(layer "In13.Cu")
		(net "P5E_CPU1_P2_TX_DP<4>")
	)
	(segment
		(start 116.492274 -290.608766)
		(end 116.491766 -290.60902)
		(width 0.1143)
		(layer "In13.Cu")
		(net "P5E_CPU1_P2_TX_DP<4>")
	)
	(segment
		(start 116.48821 -282.510992)
		(end 116.487194 -282.5115)
		(width 0.1143)
		(layer "In13.Cu")
		(net "P5E_CPU1_P2_TX_DP<4>")
	)
	(segment
		(start 116.459508 -281.845004)
		(end 116.46027 -281.845512)
		(width 0.1143)
		(layer "In13.Cu")
		(net "P5E_CPU1_P2_TX_DP<4>")
	)
	(segment
		(start 118.379748 -301.032164)
		(end 119.340376 -302.635158)
		(width 0.14224)
		(layer "In13.Cu")
		(net "P5E_CPU1_P2_TX_DP<4>")
	)
	(segment
		(start 116.523516 -272.7706)
		(end 116.492528 -272.78838)
		(width 0.1143)
		(layer "In13.Cu")
		(net "P5E_CPU1_P2_TX_DP<4>")
	)
	(segment
		(start 146.785584 -370.169948)
		(end 147.27428 -370.408708)
		(width 0.14224)
		(layer "In13.Cu")
		(net "P5E_CPU1_P2_TX_DP<4>")
	)
	(segment
		(start 116.45265 -293.18077)
		(end 116.459508 -293.184834)
		(width 0.1143)
		(layer "In13.Cu")
		(net "P5E_CPU1_P2_TX_DP<4>")
	)
	(segment
		(start 116.492528 -273.764248)
		(end 116.523516 -273.782028)
		(width 0.1143)
		(layer "In13.Cu")
		(net "P5E_CPU1_P2_TX_DP<4>")
	)
	(segment
		(start 116.458238 -288.323782)
		(end 116.48694 -288.340546)
		(width 0.1143)
		(layer "In13.Cu")
		(net "P5E_CPU1_P2_TX_DP<4>")
	)
	(segment
		(start 116.487702 -288.341054)
		(end 116.491766 -288.343594)
		(width 0.1143)
		(layer "In13.Cu")
		(net "P5E_CPU1_P2_TX_DP<4>")
	)
	(segment
		(start 116.489226 -272.790412)
		(end 116.45265 -272.811748)
		(width 0.1143)
		(layer "In13.Cu")
		(net "P5E_CPU1_P2_TX_DP<4>")
	)
	(segment
		(start 116.49075 -290.609274)
		(end 116.489226 -290.61029)
		(width 0.1143)
		(layer "In13.Cu")
		(net "P5E_CPU1_P2_TX_DP<4>")
	)
	(segment
		(start 116.49075 -279.269444)
		(end 116.489226 -279.27046)
		(width 0.1143)
		(layer "In13.Cu")
		(net "P5E_CPU1_P2_TX_DP<4>")
	)
	(segment
		(start 116.487194 -282.5115)
		(end 116.48567 -282.512516)
		(width 0.1143)
		(layer "In13.Cu")
		(net "P5E_CPU1_P2_TX_DP<4>")
	)
	(segment
		(start 116.523516 -285.730696)
		(end 116.492528 -285.748476)
		(width 0.1143)
		(layer "In13.Cu")
		(net "P5E_CPU1_P2_TX_DP<4>")
	)
	(segment
		(start 116.49075 -285.749492)
		(end 116.489226 -285.750508)
		(width 0.1143)
		(layer "In13.Cu")
		(net "P5E_CPU1_P2_TX_DP<4>")
	)
	(segment
		(start 116.491766 -293.20363)
		(end 116.491766 -293.203376)
		(width 0.1143)
		(layer "In13.Cu")
		(net "P5E_CPU1_P2_TX_DP<4>")
	)
	(segment
		(start 128.5621 -315.068966)
		(end 129.922778 -317.105538)
		(width 0.14224)
		(layer "In13.Cu")
		(net "P5E_CPU1_P2_TX_DP<4>")
	)
	(segment
		(start 119.340376 -302.635158)
		(end 128.5621 -315.068966)
		(width 0.14224)
		(layer "In13.Cu")
		(net "P5E_CPU1_P2_TX_DP<4>")
	)
	(segment
		(start 117.103906 -296.327068)
		(end 117.103906 -297.951652)
		(width 0.14224)
		(layer "In13.Cu")
		(net "P5E_CPU1_P2_TX_DP<4>")
	)
	(segment
		(start 116.487194 -285.101284)
		(end 116.48821 -285.101792)
		(width 0.1143)
		(layer "In13.Cu")
		(net "P5E_CPU1_P2_TX_DP<4>")
	)
	(segment
		(start 116.486686 -283.480764)
		(end 116.488718 -283.482034)
		(width 0.1143)
		(layer "In13.Cu")
		(net "P5E_CPU1_P2_TX_DP<4>")
	)
	(segment
		(start 116.45265 -289.940746)
		(end 116.459508 -289.94481)
		(width 0.1143)
		(layer "In13.Cu")
		(net "P5E_CPU1_P2_TX_DP<4>")
	)
	(segment
		(start 116.491766 -273.76374)
		(end 116.492528 -273.764248)
		(width 0.1143)
		(layer "In13.Cu")
		(net "P5E_CPU1_P2_TX_DP<4>")
	)
	(segment
		(start 116.491766 -277.003764)
		(end 116.492528 -277.004272)
		(width 0.1143)
		(layer "In13.Cu")
		(net "P5E_CPU1_P2_TX_DP<4>")
	)
	(segment
		(start 116.50853 -283.493464)
		(end 116.510054 -283.49448)
		(width 0.1143)
		(layer "In13.Cu")
		(net "P5E_CPU1_P2_TX_DP<4>")
	)
	(segment
		(start 116.491766 -272.143728)
		(end 116.492528 -272.144236)
		(width 0.1143)
		(layer "In13.Cu")
		(net "P5E_CPU1_P2_TX_DP<4>")
	)
	(segment
		(start 116.470684 -283.47162)
		(end 116.486686 -283.480764)
		(width 0.1143)
		(layer "In13.Cu")
		(net "P5E_CPU1_P2_TX_DP<4>")
	)
	(segment
		(start 116.492274 -283.484066)
		(end 116.493036 -283.484574)
		(width 0.1143)
		(layer "In13.Cu")
		(net "P5E_CPU1_P2_TX_DP<4>")
	)
	(segment
		(start 116.510054 -283.49448)
		(end 116.510308 -283.49448)
		(width 0.1143)
		(layer "In13.Cu")
		(net "P5E_CPU1_P2_TX_DP<4>")
	)
	(segment
		(start 116.459508 -293.184834)
		(end 116.46027 -293.185342)
		(width 0.1143)
		(layer "In13.Cu")
		(net "P5E_CPU1_P2_TX_DP<4>")
	)
	(segment
		(start 116.495322 -282.507182)
		(end 116.494814 -282.507182)
		(width 0.1143)
		(layer "In13.Cu")
		(net "P5E_CPU1_P2_TX_DP<4>")
	)
	(segment
		(start 116.951252 -295.627806)
		(end 116.952268 -295.628314)
		(width 0.1143)
		(layer "In13.Cu")
		(net "P5E_CPU1_P2_TX_DP<4>")
	)
	(segment
		(start 116.491766 -275.383752)
		(end 116.492528 -275.38426)
		(width 0.1143)
		(layer "In13.Cu")
		(net "P5E_CPU1_P2_TX_DP<4>")
	)
	(segment
		(start 116.492528 -275.38426)
		(end 116.523516 -275.40204)
		(width 0.1143)
		(layer "In13.Cu")
		(net "P5E_CPU1_P2_TX_DP<4>")
	)
	(segment
		(start 116.459508 -291.564822)
		(end 116.46027 -291.56533)
		(width 0.1143)
		(layer "In13.Cu")
		(net "P5E_CPU1_P2_TX_DP<4>")
	)
	(segment
		(start 116.45265 -275.360892)
		(end 116.459508 -275.364956)
		(width 0.1143)
		(layer "In13.Cu")
		(net "P5E_CPU1_P2_TX_DP<4>")
	)
	(segment
		(start 116.493036 -283.484574)
		(end 116.50853 -283.493464)
		(width 0.1143)
		(layer "In13.Cu")
		(net "P5E_CPU1_P2_TX_DP<4>")
	)
	(segment
		(start 116.494306 -284.127702)
		(end 116.49075 -284.12948)
		(width 0.1143)
		(layer "In13.Cu")
		(net "P5E_CPU1_P2_TX_DP<4>")
	)
	(segment
		(start 116.543328 -280.856436)
		(end 116.523516 -280.87066)
		(width 0.1143)
		(layer "In13.Cu")
		(net "P5E_CPU1_P2_TX_DP<4>")
	)
	(segment
		(start 116.491766 -289.963352)
		(end 116.492274 -289.963606)
		(width 0.1143)
		(layer "In13.Cu")
		(net "P5E_CPU1_P2_TX_DP<4>")
	)
	(segment
		(start 148.039074 -373.6721)
		(end 147.748244 -373.96293)
		(width 0.14224)
		(layer "In13.Cu")
		(net "P5E_CPU1_P2_TX_DP<4>")
	)
	(segment
		(start 116.523516 -274.390612)
		(end 116.492528 -274.408392)
		(width 0.1143)
		(layer "In13.Cu")
		(net "P5E_CPU1_P2_TX_DP<4>")
	)
	(segment
		(start 116.5225 -287.348168)
		(end 116.51234 -287.356804)
		(width 0.1143)
		(layer "In13.Cu")
		(net "P5E_CPU1_P2_TX_DP<4>")
	)
	(segment
		(start 116.49075 -276.02942)
		(end 116.489226 -276.030436)
		(width 0.1143)
		(layer "In13.Cu")
		(net "P5E_CPU1_P2_TX_DP<4>")
	)
	(segment
		(start 116.45265 -276.980904)
		(end 116.459508 -276.984968)
		(width 0.1143)
		(layer "In13.Cu")
		(net "P5E_CPU1_P2_TX_DP<4>")
	)
	(segment
		(start 116.51234 -287.356804)
		(end 116.476018 -287.377886)
		(width 0.1143)
		(layer "In13.Cu")
		(net "P5E_CPU1_P2_TX_DP<4>")
	)
	(segment
		(start 116.45265 -278.600916)
		(end 116.49075 -278.623268)
		(width 0.1143)
		(layer "In13.Cu")
		(net "P5E_CPU1_P2_TX_DP<4>")
	)
	(segment
		(start 116.49075 -285.103316)
		(end 116.491766 -285.103824)
		(width 0.1143)
		(layer "In13.Cu")
		(net "P5E_CPU1_P2_TX_DP<4>")
	)
	(segment
		(start 116.45265 -272.120868)
		(end 116.459508 -272.124932)
		(width 0.1143)
		(layer "In13.Cu")
		(net "P5E_CPU1_P2_TX_DP<4>")
	)
	(segment
		(start 117.103906 -297.951652)
		(end 118.379748 -301.032164)
		(width 0.14224)
		(layer "In13.Cu")
		(net "P5E_CPU1_P2_TX_DP<4>")
	)
	(segment
		(start 117.149626 -295.956228)
		(end 117.149626 -296.2529)
		(width 0.1143)
		(layer "In13.Cu")
		(net "P5E_CPU1_P2_TX_DP<4>")
	)
	(segment
		(start 146.407632 -369.709446)
		(end 146.577304 -369.982242)
		(width 0.14224)
		(layer "In13.Cu")
		(net "P5E_CPU1_P2_TX_DP<4>")
	)
	(segment
		(start 116.48694 -288.340546)
		(end 116.487702 -288.341054)
		(width 0.1143)
		(layer "In13.Cu")
		(net "P5E_CPU1_P2_TX_DP<4>")
	)
	(segment
		(start 116.491766 -276.028912)
		(end 116.49075 -276.02942)
		(width 0.1143)
		(layer "In13.Cu")
		(net "P5E_CPU1_P2_TX_DP<4>")
	)
	(segment
		(start 116.49075 -293.849298)
		(end 116.489226 -293.850314)
		(width 0.1143)
		(layer "In13.Cu")
		(net "P5E_CPU1_P2_TX_DP<4>")
	)
	(segment
		(start 116.952268 -295.628314)
		(end 116.993416 -295.651936)
		(width 0.1143)
		(layer "In13.Cu")
		(net "P5E_CPU1_P2_TX_DP<4>")
	)
	(segment
		(start 116.492528 -282.508706)
		(end 116.492528 -282.508452)
		(width 0.1143)
		(layer "In13.Cu")
		(net "P5E_CPU1_P2_TX_DP<4>")
	)
	(segment
		(start 116.489226 -292.230302)
		(end 116.45265 -292.251638)
		(width 0.1143)
		(layer "In13.Cu")
		(net "P5E_CPU1_P2_TX_DP<4>")
	)
	(segment
		(start 116.510562 -284.118304)
		(end 116.510054 -284.118304)
		(width 0.1143)
		(layer "In13.Cu")
		(net "P5E_CPU1_P2_TX_DP<4>")
	)
	(segment
		(start 116.46027 -280.2255)
		(end 116.491766 -280.243788)
		(width 0.1143)
		(layer "In13.Cu")
		(net "P5E_CPU1_P2_TX_DP<4>")
	)
	(segment
		(start 116.45265 -286.700976)
		(end 116.520976 -286.740346)
		(width 0.1143)
		(layer "In13.Cu")
		(net "P5E_CPU1_P2_TX_DP<4>")
	)
	(segment
		(start 116.492528 -272.78838)
		(end 116.491766 -272.788888)
		(width 0.1143)
		(layer "In13.Cu")
		(net "P5E_CPU1_P2_TX_DP<4>")
	)
	(segment
		(start 116.489734 -283.482542)
		(end 116.490496 -283.48305)
		(width 0.1143)
		(layer "In13.Cu")
		(net "P5E_CPU1_P2_TX_DP<4>")
	)
	(segment
		(start 116.523516 -279.250648)
		(end 116.492528 -279.268428)
		(width 0.1143)
		(layer "In13.Cu")
		(net "P5E_CPU1_P2_TX_DP<4>")
	)
	(segment
		(start 116.523516 -276.010624)
		(end 116.492528 -276.028404)
		(width 0.1143)
		(layer "In13.Cu")
		(net "P5E_CPU1_P2_TX_DP<4>")
	)
	(segment
		(start 116.48567 -282.512516)
		(end 116.4717 -282.520644)
		(width 0.1143)
		(layer "In13.Cu")
		(net "P5E_CPU1_P2_TX_DP<4>")
	)
	(segment
		(start 116.49456 -281.865578)
		(end 116.495068 -281.865578)
		(width 0.1143)
		(layer "In13.Cu")
		(net "P5E_CPU1_P2_TX_DP<4>")
	)
	(segment
		(start 116.45265 -281.84094)
		(end 116.459508 -281.845004)
		(width 0.1143)
		(layer "In13.Cu")
		(net "P5E_CPU1_P2_TX_DP<4>")
	)
	(segment
		(start 116.492274 -293.84879)
		(end 116.491766 -293.849044)
		(width 0.1143)
		(layer "In13.Cu")
		(net "P5E_CPU1_P2_TX_DP<4>")
	)
	(segment
		(start 116.459508 -275.364956)
		(end 116.46027 -275.365464)
		(width 0.1143)
		(layer "In13.Cu")
		(net "P5E_CPU1_P2_TX_DP<4>")
	)
	(segment
		(start 116.492528 -285.748476)
		(end 116.491766 -285.748984)
		(width 0.1143)
		(layer "In13.Cu")
		(net "P5E_CPU1_P2_TX_DP<4>")
	)
	(segment
		(start 116.493036 -288.988246)
		(end 116.491766 -288.988754)
		(width 0.1143)
		(layer "In13.Cu")
		(net "P5E_CPU1_P2_TX_DP<4>")
	)
	(segment
		(start 116.459508 -273.744944)
		(end 116.46027 -273.745452)
		(width 0.1143)
		(layer "In13.Cu")
		(net "P5E_CPU1_P2_TX_DP<4>")
	)
	(segment
		(start 116.49075 -272.789396)
		(end 116.489226 -272.790412)
		(width 0.1143)
		(layer "In13.Cu")
		(net "P5E_CPU1_P2_TX_DP<4>")
	)
	(segment
		(start 116.49075 -278.623268)
		(end 116.491766 -278.623776)
		(width 0.1143)
		(layer "In13.Cu")
		(net "P5E_CPU1_P2_TX_DP<4>")
	)
	(segment
		(start 116.459508 -276.984968)
		(end 116.46027 -276.985476)
		(width 0.1143)
		(layer "In13.Cu")
		(net "P5E_CPU1_P2_TX_DP<4>")
	)
	(segment
		(start 116.490496 -283.48305)
		(end 116.492274 -283.484066)
		(width 0.1143)
		(layer "In13.Cu")
		(net "P5E_CPU1_P2_TX_DP<4>")
	)
	(segment
		(start 116.543328 -277.616412)
		(end 116.523516 -277.630636)
		(width 0.1143)
		(layer "In13.Cu")
		(net "P5E_CPU1_P2_TX_DP<4>")
	)
	(segment
		(start 116.492528 -276.028404)
		(end 116.491766 -276.028912)
		(width 0.1143)
		(layer "In13.Cu")
		(net "P5E_CPU1_P2_TX_DP<4>")
	)
	(segment
		(start 116.46027 -272.12544)
		(end 116.491766 -272.143728)
		(width 0.1143)
		(layer "In13.Cu")
		(net "P5E_CPU1_P2_TX_DP<4>")
	)
	(segment
		(start 116.492528 -285.104332)
		(end 116.523516 -285.122112)
		(width 0.1143)
		(layer "In13.Cu")
		(net "P5E_CPU1_P2_TX_DP<4>")
	)
	(segment
		(start 116.491766 -285.103824)
		(end 116.492528 -285.104332)
		(width 0.1143)
		(layer "In13.Cu")
		(net "P5E_CPU1_P2_TX_DP<4>")
	)
	(segment
		(start 116.66982 -270.853916)
		(end 116.66982 -270.862298)
		(width 0.1143)
		(layer "In13.Cu")
		(net "P5E_CPU1_P2_TX_DP<4>")
	)
	(segment
		(start 129.922778 -317.105538)
		(end 133.743446 -324.25259)
		(width 0.14224)
		(layer "In13.Cu")
		(net "P5E_CPU1_P2_TX_DP<4>")
	)
	(segment
		(start 116.459508 -280.224992)
		(end 116.46027 -280.2255)
		(width 0.1143)
		(layer "In13.Cu")
		(net "P5E_CPU1_P2_TX_DP<4>")
	)
	(segment
		(start 116.491766 -288.988754)
		(end 116.49075 -288.989262)
		(width 0.1143)
		(layer "In13.Cu")
		(net "P5E_CPU1_P2_TX_DP<4>")
	)
	(arc
		(start 116.45265 -277.671784)
		(mid 116.209323 -278.13635)
		(end 116.45265 -278.600916)
		(width 0.1143)
		(layer "In13.Cu")
		(net "P5E_CPU1_P2_TX_DP<4>")
	)
	(arc
		(start 116.523516 -278.642064)
		(mid 116.673901 -278.946356)
		(end 116.523516 -279.250648)
		(width 0.1143)
		(layer "In13.Cu")
		(net "P5E_CPU1_P2_TX_DP<4>")
	)
	(arc
		(start 116.45265 -285.771844)
		(mid 116.209323 -286.23641)
		(end 116.45265 -286.700976)
		(width 0.1143)
		(layer "In13.Cu")
		(net "P5E_CPU1_P2_TX_DP<4>")
	)
	(arc
		(start 147.274534 -370.408962)
		(mid 147.355634 -370.445344)
		(end 147.438872 -370.476526)
		(width 0.14224)
		(layer "In13.Cu")
		(net "P5E_CPU1_P2_TX_DP<4>")
	)
	(arc
		(start 116.510308 -283.49448)
		(mid 116.689882 -283.806282)
		(end 116.510562 -284.118304)
		(width 0.1143)
		(layer "In13.Cu")
		(net "P5E_CPU1_P2_TX_DP<4>")
	)
	(arc
		(start 116.4717 -282.520644)
		(mid 116.198627 -282.995819)
		(end 116.470684 -283.47162)
		(width 0.1143)
		(layer "In13.Cu")
		(net "P5E_CPU1_P2_TX_DP<4>")
	)
	(arc
		(start 116.487956 -293.851076)
		(mid 116.209412 -294.334909)
		(end 116.48567 -294.820086)
		(width 0.1143)
		(layer "In13.Cu")
		(net "P5E_CPU1_P2_TX_DP<4>")
	)
	(arc
		(start 116.45265 -292.251638)
		(mid 116.209323 -292.716204)
		(end 116.45265 -293.18077)
		(width 0.1143)
		(layer "In13.Cu")
		(net "P5E_CPU1_P2_TX_DP<4>")
	)
	(arc
		(start 116.543328 -277.036276)
		(mid 116.692042 -277.326344)
		(end 116.543328 -277.616412)
		(width 0.1143)
		(layer "In13.Cu")
		(net "P5E_CPU1_P2_TX_DP<4>")
	)
	(arc
		(start 116.45265 -271.191736)
		(mid 116.209323 -271.656302)
		(end 116.45265 -272.120868)
		(width 0.1143)
		(layer "In13.Cu")
		(net "P5E_CPU1_P2_TX_DP<4>")
	)
	(arc
		(start 117.142514 -270.10614)
		(mid 117.090465 -270.237659)
		(end 116.993416 -270.340582)
		(width 0.1143)
		(layer "In13.Cu")
		(net "P5E_CPU1_P2_TX_DP<4>")
	)
	(arc
		(start 116.488464 -284.131004)
		(mid 116.2097 -284.615722)
		(end 116.487194 -285.101284)
		(width 0.1143)
		(layer "In13.Cu")
		(net "P5E_CPU1_P2_TX_DP<4>")
	)
	(arc
		(start 116.45265 -274.43176)
		(mid 116.209323 -274.896326)
		(end 116.45265 -275.360892)
		(width 0.1143)
		(layer "In13.Cu")
		(net "P5E_CPU1_P2_TX_DP<4>")
	)
	(arc
		(start 145.530316 -365.572802)
		(mid 145.542941 -365.604379)
		(end 145.553176 -365.63681)
		(width 0.14224)
		(layer "In13.Cu")
		(net "P5E_CPU1_P2_TX_DP<4>")
	)
	(arc
		(start 116.492274 -291.583618)
		(mid 116.677912 -291.906198)
		(end 116.492274 -292.228778)
		(width 0.1143)
		(layer "In13.Cu")
		(net "P5E_CPU1_P2_TX_DP<4>")
	)
	(arc
		(start 116.523516 -275.40204)
		(mid 116.675105 -275.706332)
		(end 116.523516 -276.010624)
		(width 0.1143)
		(layer "In13.Cu")
		(net "P5E_CPU1_P2_TX_DP<4>")
	)
	(arc
		(start 146.577304 -369.982242)
		(mid 146.668258 -370.090723)
		(end 146.785584 -370.169948)
		(width 0.14224)
		(layer "In13.Cu")
		(net "P5E_CPU1_P2_TX_DP<4>")
	)
	(arc
		(start 116.677948 -287.04921)
		(mid 116.62877 -287.213525)
		(end 116.5225 -287.348168)
		(width 0.1143)
		(layer "In13.Cu")
		(net "P5E_CPU1_P2_TX_DP<4>")
	)
	(arc
		(start 116.209318 -287.856422)
		(mid 116.273833 -288.118641)
		(end 116.45265 -288.320988)
		(width 0.1143)
		(layer "In13.Cu")
		(net "P5E_CPU1_P2_TX_DP<4>")
	)
	(arc
		(start 146.330924 -369.440206)
		(mid 146.3504 -369.580207)
		(end 146.407632 -369.709446)
		(width 0.14224)
		(layer "In13.Cu")
		(net "P5E_CPU1_P2_TX_DP<4>")
	)
	(arc
		(start 116.492274 -289.963606)
		(mid 116.677912 -290.286186)
		(end 116.492274 -290.608766)
		(width 0.1143)
		(layer "In13.Cu")
		(net "P5E_CPU1_P2_TX_DP<4>")
	)
	(arc
		(start 116.520976 -286.740346)
		(mid 116.522885 -286.741737)
		(end 116.524786 -286.74314)
		(width 0.1143)
		(layer "In13.Cu")
		(net "P5E_CPU1_P2_TX_DP<4>")
	)
	(arc
		(start 117.083332 -295.743884)
		(mid 117.132652 -295.845013)
		(end 117.149626 -295.956228)
		(width 0.1143)
		(layer "In13.Cu")
		(net "P5E_CPU1_P2_TX_DP<4>")
	)
	(arc
		(start 148.024342 -371.288818)
		(mid 148.035387 -371.351252)
		(end 148.039074 -371.414548)
		(width 0.14224)
		(layer "In13.Cu")
		(net "P5E_CPU1_P2_TX_DP<4>")
	)
	(arc
		(start 116.45265 -289.011614)
		(mid 116.209323 -289.47618)
		(end 116.45265 -289.940746)
		(width 0.1143)
		(layer "In13.Cu")
		(net "P5E_CPU1_P2_TX_DP<4>")
	)
	(arc
		(start 147.758404 -370.68379)
		(mid 147.802473 -370.729634)
		(end 147.83689 -370.783104)
		(width 0.14224)
		(layer "In13.Cu")
		(net "P5E_CPU1_P2_TX_DP<4>")
	)
	(arc
		(start 147.83689 -370.783104)
		(mid 147.945918 -371.030289)
		(end 148.024342 -371.288818)
		(width 0.14224)
		(layer "In13.Cu")
		(net "P5E_CPU1_P2_TX_DP<4>")
	)
	(arc
		(start 116.951252 -270.364966)
		(mid 116.745184 -270.571829)
		(end 116.66982 -270.853916)
		(width 0.1143)
		(layer "In13.Cu")
		(net "P5E_CPU1_P2_TX_DP<4>")
	)
	(arc
		(start 116.993416 -295.651936)
		(mid 117.042348 -295.694024)
		(end 117.083332 -295.743884)
		(width 0.1143)
		(layer "In13.Cu")
		(net "P5E_CPU1_P2_TX_DP<4>")
	)
	(arc
		(start 116.679472 -295.146222)
		(mid 116.744194 -295.408961)
		(end 116.923566 -295.61155)
		(width 0.1143)
		(layer "In13.Cu")
		(net "P5E_CPU1_P2_TX_DP<4>")
	)
	(arc
		(start 116.524786 -286.74314)
		(mid 116.636224 -286.871541)
		(end 116.679218 -287.036002)
		(width 0.1143)
		(layer "In13.Cu")
		(net "P5E_CPU1_P2_TX_DP<4>")
	)
	(arc
		(start 147.438872 -370.476526)
		(mid 147.560872 -370.53123)
		(end 147.670266 -370.608098)
		(width 0.14224)
		(layer "In13.Cu")
		(net "P5E_CPU1_P2_TX_DP<4>")
	)
	(arc
		(start 116.45265 -280.911808)
		(mid 116.209323 -281.376374)
		(end 116.45265 -281.84094)
		(width 0.1143)
		(layer "In13.Cu")
		(net "P5E_CPU1_P2_TX_DP<4>")
	)
	(arc
		(start 116.495068 -281.865578)
		(mid 116.679801 -282.18627)
		(end 116.495322 -282.507182)
		(width 0.1143)
		(layer "In13.Cu")
		(net "P5E_CPU1_P2_TX_DP<4>")
	)
	(arc
		(start 116.45265 -279.291796)
		(mid 116.209323 -279.756362)
		(end 116.45265 -280.220928)
		(width 0.1143)
		(layer "In13.Cu")
		(net "P5E_CPU1_P2_TX_DP<4>")
	)
	(arc
		(start 116.492782 -288.344102)
		(mid 116.678234 -288.666064)
		(end 116.493036 -288.988246)
		(width 0.1143)
		(layer "In13.Cu")
		(net "P5E_CPU1_P2_TX_DP<4>")
	)
	(arc
		(start 116.492274 -293.20363)
		(mid 116.677912 -293.52621)
		(end 116.492274 -293.84879)
		(width 0.1143)
		(layer "In13.Cu")
		(net "P5E_CPU1_P2_TX_DP<4>")
	)
	(arc
		(start 116.523516 -272.162016)
		(mid 116.675105 -272.466308)
		(end 116.523516 -272.7706)
		(width 0.1143)
		(layer "In13.Cu")
		(net "P5E_CPU1_P2_TX_DP<4>")
	)
	(arc
		(start 139.045696 -350.907604)
		(mid 139.061424 -350.968853)
		(end 139.083796 -351.028)
		(width 0.14224)
		(layer "In13.Cu")
		(net "P5E_CPU1_P2_TX_DP<4>")
	)
	(arc
		(start 116.523516 -273.782028)
		(mid 116.675105 -274.08632)
		(end 116.523516 -274.390612)
		(width 0.1143)
		(layer "In13.Cu")
		(net "P5E_CPU1_P2_TX_DP<4>")
	)
	(arc
		(start 116.45265 -276.051772)
		(mid 116.209323 -276.516338)
		(end 116.45265 -276.980904)
		(width 0.1143)
		(layer "In13.Cu")
		(net "P5E_CPU1_P2_TX_DP<4>")
	)
	(arc
		(start 116.511832 -294.836596)
		(mid 116.63485 -294.970182)
		(end 116.679472 -295.146222)
		(width 0.1143)
		(layer "In13.Cu")
		(net "P5E_CPU1_P2_TX_DP<4>")
	)
	(arc
		(start 116.66982 -270.862298)
		(mid 116.622294 -271.039149)
		(end 116.492528 -271.168368)
		(width 0.1143)
		(layer "In13.Cu")
		(net "P5E_CPU1_P2_TX_DP<4>")
	)
	(arc
		(start 116.45265 -290.631626)
		(mid 116.209323 -291.096192)
		(end 116.45265 -291.560758)
		(width 0.1143)
		(layer "In13.Cu")
		(net "P5E_CPU1_P2_TX_DP<4>")
	)
	(arc
		(start 116.45519 -287.390078)
		(mid 116.274538 -287.592823)
		(end 116.209318 -287.856422)
		(width 0.1143)
		(layer "In13.Cu")
		(net "P5E_CPU1_P2_TX_DP<4>")
	)
	(arc
		(start 116.543328 -280.2763)
		(mid 116.692042 -280.566368)
		(end 116.543328 -280.856436)
		(width 0.1143)
		(layer "In13.Cu")
		(net "P5E_CPU1_P2_TX_DP<4>")
	)
	(arc
		(start 116.45265 -272.811748)
		(mid 116.209323 -273.276314)
		(end 116.45265 -273.74088)
		(width 0.1143)
		(layer "In13.Cu")
		(net "P5E_CPU1_P2_TX_DP<4>")
	)
	(arc
		(start 146.31543 -368.68354)
		(mid 146.327008 -368.745676)
		(end 146.330924 -368.808762)
		(width 0.14224)
		(layer "In13.Cu")
		(net "P5E_CPU1_P2_TX_DP<4>")
	)
	(arc
		(start 116.523516 -285.122112)
		(mid 116.673901 -285.426404)
		(end 116.523516 -285.730696)
		(width 0.1143)
		(layer "In13.Cu")
		(net "P5E_CPU1_P2_TX_DP<4>")
	)
	(segment
		(start 144.615154 -369.30584)
		(end 144.615154 -370.00942)
		(width 0.12954)
		(layer "F.Cu")
		(net "P5E_CPU1_P2_TX_DP<3>")
	)
	(segment
		(start 144.344644 -369.03533)
		(end 144.615154 -369.30584)
		(width 0.12954)
		(layer "F.Cu")
		(net "P5E_CPU1_P2_TX_DP<3>")
	)
	(segment
		(start 113.957862 -272.20037)
		(end 114.424714 -272.466308)
		(width 0.12954)
		(layer "F.Cu")
		(net "P5E_CPU1_P2_TX_DP<3>")
	)
	(segment
		(start 144.615154 -370.00942)
		(end 144.319244 -370.30533)
		(width 0.12954)
		(layer "F.Cu")
		(net "P5E_CPU1_P2_TX_DP<3>")
	)
	(segment
		(start 115.552474 -283.48432)
		(end 115.553744 -283.485082)
		(width 0.1143)
		(layer "In13.Cu")
		(net "P5E_CPU1_P2_TX_DP<3>")
	)
	(segment
		(start 115.551712 -280.888948)
		(end 115.51539 -280.909776)
		(width 0.1143)
		(layer "In13.Cu")
		(net "P5E_CPU1_P2_TX_DP<3>")
	)
	(segment
		(start 115.550696 -282.509468)
		(end 115.549172 -282.510484)
		(width 0.1143)
		(layer "In13.Cu")
		(net "P5E_CPU1_P2_TX_DP<3>")
	)
	(segment
		(start 115.512596 -294.800782)
		(end 115.519454 -294.804846)
		(width 0.1143)
		(layer "In13.Cu")
		(net "P5E_CPU1_P2_TX_DP<3>")
	)
	(segment
		(start 115.551712 -286.723836)
		(end 115.58524 -286.743394)
		(width 0.1143)
		(layer "In13.Cu")
		(net "P5E_CPU1_P2_TX_DP<3>")
	)
	(segment
		(start 115.549172 -277.650448)
		(end 115.512596 -277.671784)
		(width 0.1143)
		(layer "In13.Cu")
		(net "P5E_CPU1_P2_TX_DP<3>")
	)
	(segment
		(start 115.552474 -294.82415)
		(end 115.553744 -294.824912)
		(width 0.1143)
		(layer "In13.Cu")
		(net "P5E_CPU1_P2_TX_DP<3>")
	)
	(segment
		(start 115.553744 -282.50769)
		(end 115.552474 -282.508452)
		(width 0.1143)
		(layer "In13.Cu")
		(net "P5E_CPU1_P2_TX_DP<3>")
	)
	(segment
		(start 115.551712 -290.608766)
		(end 115.550696 -290.609274)
		(width 0.1143)
		(layer "In13.Cu")
		(net "P5E_CPU1_P2_TX_DP<3>")
	)
	(segment
		(start 115.551712 -282.50896)
		(end 115.550696 -282.509468)
		(width 0.1143)
		(layer "In13.Cu")
		(net "P5E_CPU1_P2_TX_DP<3>")
	)
	(segment
		(start 115.512596 -280.220928)
		(end 115.519454 -280.224992)
		(width 0.1143)
		(layer "In13.Cu")
		(net "P5E_CPU1_P2_TX_DP<3>")
	)
	(segment
		(start 116.163852 -296.327068)
		(end 116.163852 -298.133262)
		(width 0.14224)
		(layer "In13.Cu")
		(net "P5E_CPU1_P2_TX_DP<3>")
	)
	(segment
		(start 115.519454 -293.184834)
		(end 115.520216 -293.185342)
		(width 0.1143)
		(layer "In13.Cu")
		(net "P5E_CPU1_P2_TX_DP<3>")
	)
	(segment
		(start 115.551712 -287.368742)
		(end 115.515136 -287.390078)
		(width 0.1143)
		(layer "In13.Cu")
		(net "P5E_CPU1_P2_TX_DP<3>")
	)
	(segment
		(start 115.553744 -291.584888)
		(end 115.583462 -291.601906)
		(width 0.1143)
		(layer "In13.Cu")
		(net "P5E_CPU1_P2_TX_DP<3>")
	)
	(segment
		(start 115.520216 -283.465524)
		(end 115.551712 -283.483812)
		(width 0.1143)
		(layer "In13.Cu")
		(net "P5E_CPU1_P2_TX_DP<3>")
	)
	(segment
		(start 144.635474 -368.7445)
		(end 144.344644 -369.03533)
		(width 0.14224)
		(layer "In13.Cu")
		(net "P5E_CPU1_P2_TX_DP<3>")
	)
	(segment
		(start 115.553744 -273.76501)
		(end 115.583462 -273.782028)
		(width 0.1143)
		(layer "In13.Cu")
		(net "P5E_CPU1_P2_TX_DP<3>")
	)
	(segment
		(start 115.552474 -285.748476)
		(end 115.551712 -285.748984)
		(width 0.1143)
		(layer "In13.Cu")
		(net "P5E_CPU1_P2_TX_DP<3>")
	)
	(segment
		(start 115.549172 -285.750508)
		(end 115.512596 -285.771844)
		(width 0.1143)
		(layer "In13.Cu")
		(net "P5E_CPU1_P2_TX_DP<3>")
	)
	(segment
		(start 115.552474 -279.268428)
		(end 115.551712 -279.268936)
		(width 0.1143)
		(layer "In13.Cu")
		(net "P5E_CPU1_P2_TX_DP<3>")
	)
	(segment
		(start 115.512596 -275.360892)
		(end 115.519454 -275.364956)
		(width 0.1143)
		(layer "In13.Cu")
		(net "P5E_CPU1_P2_TX_DP<3>")
	)
	(segment
		(start 115.552474 -293.204138)
		(end 115.553744 -293.2049)
		(width 0.1143)
		(layer "In13.Cu")
		(net "P5E_CPU1_P2_TX_DP<3>")
	)
	(segment
		(start 115.549172 -279.27046)
		(end 115.512596 -279.291796)
		(width 0.1143)
		(layer "In13.Cu")
		(net "P5E_CPU1_P2_TX_DP<3>")
	)
	(segment
		(start 115.583462 -288.970466)
		(end 115.553744 -288.987484)
		(width 0.1143)
		(layer "In13.Cu")
		(net "P5E_CPU1_P2_TX_DP<3>")
	)
	(segment
		(start 115.551712 -284.128972)
		(end 115.550696 -284.12948)
		(width 0.1143)
		(layer "In13.Cu")
		(net "P5E_CPU1_P2_TX_DP<3>")
	)
	(segment
		(start 115.519454 -275.364956)
		(end 115.520216 -275.365464)
		(width 0.1143)
		(layer "In13.Cu")
		(net "P5E_CPU1_P2_TX_DP<3>")
	)
	(segment
		(start 115.512596 -293.18077)
		(end 115.519454 -293.184834)
		(width 0.1143)
		(layer "In13.Cu")
		(net "P5E_CPU1_P2_TX_DP<3>")
	)
	(segment
		(start 115.550696 -288.989262)
		(end 115.549172 -288.990278)
		(width 0.1143)
		(layer "In13.Cu")
		(net "P5E_CPU1_P2_TX_DP<3>")
	)
	(segment
		(start 115.583462 -280.87066)
		(end 115.551712 -280.888948)
		(width 0.1143)
		(layer "In13.Cu")
		(net "P5E_CPU1_P2_TX_DP<3>")
	)
	(segment
		(start 115.550696 -293.849298)
		(end 115.549172 -293.850314)
		(width 0.1143)
		(layer "In13.Cu")
		(net "P5E_CPU1_P2_TX_DP<3>")
	)
	(segment
		(start 115.552474 -285.104332)
		(end 115.553744 -285.105094)
		(width 0.1143)
		(layer "In13.Cu")
		(net "P5E_CPU1_P2_TX_DP<3>")
	)
	(segment
		(start 115.549172 -284.130496)
		(end 115.512596 -284.151832)
		(width 0.1143)
		(layer "In13.Cu")
		(net "P5E_CPU1_P2_TX_DP<3>")
	)
	(segment
		(start 115.551712 -278.623776)
		(end 115.552474 -278.624284)
		(width 0.1143)
		(layer "In13.Cu")
		(net "P5E_CPU1_P2_TX_DP<3>")
	)
	(segment
		(start 115.551712 -273.76374)
		(end 115.552474 -273.764248)
		(width 0.1143)
		(layer "In13.Cu")
		(net "P5E_CPU1_P2_TX_DP<3>")
	)
	(segment
		(start 115.520216 -273.745452)
		(end 115.551712 -273.76374)
		(width 0.1143)
		(layer "In13.Cu")
		(net "P5E_CPU1_P2_TX_DP<3>")
	)
	(segment
		(start 116.209572 -295.956228)
		(end 116.209572 -296.2529)
		(width 0.1143)
		(layer "In13.Cu")
		(net "P5E_CPU1_P2_TX_DP<3>")
	)
	(segment
		(start 115.551712 -276.028912)
		(end 115.550696 -276.02942)
		(width 0.1143)
		(layer "In13.Cu")
		(net "P5E_CPU1_P2_TX_DP<3>")
	)
	(segment
		(start 115.512596 -285.080964)
		(end 115.519454 -285.085028)
		(width 0.1143)
		(layer "In13.Cu")
		(net "P5E_CPU1_P2_TX_DP<3>")
	)
	(segment
		(start 115.551712 -288.988754)
		(end 115.550696 -288.989262)
		(width 0.1143)
		(layer "In13.Cu")
		(net "P5E_CPU1_P2_TX_DP<3>")
	)
	(segment
		(start 115.520216 -281.845512)
		(end 115.551712 -281.8638)
		(width 0.1143)
		(layer "In13.Cu")
		(net "P5E_CPU1_P2_TX_DP<3>")
	)
	(segment
		(start 115.520216 -293.185342)
		(end 115.551712 -293.20363)
		(width 0.1143)
		(layer "In13.Cu")
		(net "P5E_CPU1_P2_TX_DP<3>")
	)
	(segment
		(start 115.583462 -293.830502)
		(end 115.553744 -293.84752)
		(width 0.1143)
		(layer "In13.Cu")
		(net "P5E_CPU1_P2_TX_DP<3>")
	)
	(segment
		(start 115.520216 -285.085536)
		(end 115.551712 -285.103824)
		(width 0.1143)
		(layer "In13.Cu")
		(net "P5E_CPU1_P2_TX_DP<3>")
	)
	(segment
		(start 117.53215 -301.43704)
		(end 118.569994 -303.168558)
		(width 0.14224)
		(layer "In13.Cu")
		(net "P5E_CPU1_P2_TX_DP<3>")
	)
	(segment
		(start 115.550696 -274.409408)
		(end 115.549172 -274.410424)
		(width 0.1143)
		(layer "In13.Cu")
		(net "P5E_CPU1_P2_TX_DP<3>")
	)
	(segment
		(start 115.551712 -288.343848)
		(end 115.58524 -288.363406)
		(width 0.1143)
		(layer "In13.Cu")
		(net "P5E_CPU1_P2_TX_DP<3>")
	)
	(segment
		(start 115.551712 -293.84879)
		(end 115.550696 -293.849298)
		(width 0.1143)
		(layer "In13.Cu")
		(net "P5E_CPU1_P2_TX_DP<3>")
	)
	(segment
		(start 115.583462 -277.630636)
		(end 115.552474 -277.648416)
		(width 0.1143)
		(layer "In13.Cu")
		(net "P5E_CPU1_P2_TX_DP<3>")
	)
	(segment
		(start 115.552474 -281.864308)
		(end 115.553744 -281.86507)
		(width 0.1143)
		(layer "In13.Cu")
		(net "P5E_CPU1_P2_TX_DP<3>")
	)
	(segment
		(start 115.552474 -276.028404)
		(end 115.551712 -276.028912)
		(width 0.1143)
		(layer "In13.Cu")
		(net "P5E_CPU1_P2_TX_DP<3>")
	)
	(segment
		(start 115.550696 -277.649432)
		(end 115.549172 -277.650448)
		(width 0.1143)
		(layer "In13.Cu")
		(net "P5E_CPU1_P2_TX_DP<3>")
	)
	(segment
		(start 115.553744 -288.987484)
		(end 115.552474 -288.988246)
		(width 0.1143)
		(layer "In13.Cu")
		(net "P5E_CPU1_P2_TX_DP<3>")
	)
	(segment
		(start 115.583462 -284.110684)
		(end 115.553744 -284.127702)
		(width 0.1143)
		(layer "In13.Cu")
		(net "P5E_CPU1_P2_TX_DP<3>")
	)
	(segment
		(start 115.512596 -283.460952)
		(end 115.519454 -283.465016)
		(width 0.1143)
		(layer "In13.Cu")
		(net "P5E_CPU1_P2_TX_DP<3>")
	)
	(segment
		(start 115.551712 -275.383752)
		(end 115.552474 -275.38426)
		(width 0.1143)
		(layer "In13.Cu")
		(net "P5E_CPU1_P2_TX_DP<3>")
	)
	(segment
		(start 115.583462 -274.390612)
		(end 115.552474 -274.408392)
		(width 0.1143)
		(layer "In13.Cu")
		(net "P5E_CPU1_P2_TX_DP<3>")
	)
	(segment
		(start 115.553744 -275.385022)
		(end 115.583462 -275.40204)
		(width 0.1143)
		(layer "In13.Cu")
		(net "P5E_CPU1_P2_TX_DP<3>")
	)
	(segment
		(start 115.51539 -280.909776)
		(end 115.512596 -280.911808)
		(width 0.1143)
		(layer "In13.Cu")
		(net "P5E_CPU1_P2_TX_DP<3>")
	)
	(segment
		(start 115.553744 -284.127702)
		(end 115.552474 -284.128464)
		(width 0.1143)
		(layer "In13.Cu")
		(net "P5E_CPU1_P2_TX_DP<3>")
	)
	(segment
		(start 115.551712 -280.243788)
		(end 115.583462 -280.262076)
		(width 0.1143)
		(layer "In13.Cu")
		(net "P5E_CPU1_P2_TX_DP<3>")
	)
	(segment
		(start 115.552474 -293.848282)
		(end 115.551712 -293.84879)
		(width 0.1143)
		(layer "In13.Cu")
		(net "P5E_CPU1_P2_TX_DP<3>")
	)
	(segment
		(start 115.519454 -278.60498)
		(end 115.520216 -278.605488)
		(width 0.1143)
		(layer "In13.Cu")
		(net "P5E_CPU1_P2_TX_DP<3>")
	)
	(segment
		(start 128.955546 -317.343282)
		(end 132.878322 -324.682866)
		(width 0.14224)
		(layer "In13.Cu")
		(net "P5E_CPU1_P2_TX_DP<3>")
	)
	(segment
		(start 116.163852 -298.133262)
		(end 117.53215 -301.43704)
		(width 0.14224)
		(layer "In13.Cu")
		(net "P5E_CPU1_P2_TX_DP<3>")
	)
	(segment
		(start 115.519454 -280.224992)
		(end 115.520216 -280.2255)
		(width 0.1143)
		(layer "In13.Cu")
		(net "P5E_CPU1_P2_TX_DP<3>")
	)
	(segment
		(start 115.553744 -281.86507)
		(end 115.583462 -281.882088)
		(width 0.1143)
		(layer "In13.Cu")
		(net "P5E_CPU1_P2_TX_DP<3>")
	)
	(segment
		(start 115.519454 -276.984968)
		(end 115.520216 -276.985476)
		(width 0.1143)
		(layer "In13.Cu")
		(net "P5E_CPU1_P2_TX_DP<3>")
	)
	(segment
		(start 115.512596 -281.84094)
		(end 115.519454 -281.845004)
		(width 0.1143)
		(layer "In13.Cu")
		(net "P5E_CPU1_P2_TX_DP<3>")
	)
	(segment
		(start 115.520216 -294.805354)
		(end 115.551712 -294.823642)
		(width 0.1143)
		(layer "In13.Cu")
		(net "P5E_CPU1_P2_TX_DP<3>")
	)
	(segment
		(start 115.583462 -287.350454)
		(end 115.551712 -287.368742)
		(width 0.1143)
		(layer "In13.Cu")
		(net "P5E_CPU1_P2_TX_DP<3>")
	)
	(segment
		(start 116.209572 -296.2529)
		(end 116.163852 -296.29862)
		(width 0.1143)
		(layer "In13.Cu")
		(net "P5E_CPU1_P2_TX_DP<3>")
	)
	(segment
		(start 115.551712 -294.823642)
		(end 115.552474 -294.82415)
		(width 0.1143)
		(layer "In13.Cu")
		(net "P5E_CPU1_P2_TX_DP<3>")
	)
	(segment
		(start 115.512596 -291.560758)
		(end 115.519454 -291.564822)
		(width 0.1143)
		(layer "In13.Cu")
		(net "P5E_CPU1_P2_TX_DP<3>")
	)
	(segment
		(start 116.163852 -296.29862)
		(end 116.163852 -296.327068)
		(width 0.1143)
		(layer "In13.Cu")
		(net "P5E_CPU1_P2_TX_DP<3>")
	)
	(segment
		(start 115.553744 -285.105094)
		(end 115.583462 -285.122112)
		(width 0.1143)
		(layer "In13.Cu")
		(net "P5E_CPU1_P2_TX_DP<3>")
	)
	(segment
		(start 115.549172 -293.850314)
		(end 115.512596 -293.87165)
		(width 0.1143)
		(layer "In13.Cu")
		(net "P5E_CPU1_P2_TX_DP<3>")
	)
	(segment
		(start 115.553744 -290.607496)
		(end 115.552474 -290.608258)
		(width 0.1143)
		(layer "In13.Cu")
		(net "P5E_CPU1_P2_TX_DP<3>")
	)
	(segment
		(start 115.552474 -277.648416)
		(end 115.551712 -277.648924)
		(width 0.1143)
		(layer "In13.Cu")
		(net "P5E_CPU1_P2_TX_DP<3>")
	)
	(segment
		(start 144.169638 -366.16259)
		(end 144.635474 -368.023648)
		(width 0.14224)
		(layer "In13.Cu")
		(net "P5E_CPU1_P2_TX_DP<3>")
	)
	(segment
		(start 115.519454 -273.744944)
		(end 115.520216 -273.745452)
		(width 0.1143)
		(layer "In13.Cu")
		(net "P5E_CPU1_P2_TX_DP<3>")
	)
	(segment
		(start 115.550696 -276.02942)
		(end 115.549172 -276.030436)
		(width 0.1143)
		(layer "In13.Cu")
		(net "P5E_CPU1_P2_TX_DP<3>")
	)
	(segment
		(start 115.512596 -288.320988)
		(end 115.551712 -288.343848)
		(width 0.1143)
		(layer "In13.Cu")
		(net "P5E_CPU1_P2_TX_DP<3>")
	)
	(segment
		(start 115.551712 -277.003764)
		(end 115.552474 -277.004272)
		(width 0.1143)
		(layer "In13.Cu")
		(net "P5E_CPU1_P2_TX_DP<3>")
	)
	(segment
		(start 115.512596 -276.980904)
		(end 115.519454 -276.984968)
		(width 0.1143)
		(layer "In13.Cu")
		(net "P5E_CPU1_P2_TX_DP<3>")
	)
	(segment
		(start 115.550696 -284.12948)
		(end 115.549172 -284.130496)
		(width 0.1143)
		(layer "In13.Cu")
		(net "P5E_CPU1_P2_TX_DP<3>")
	)
	(segment
		(start 115.512596 -286.700976)
		(end 115.551712 -286.723836)
		(width 0.1143)
		(layer "In13.Cu")
		(net "P5E_CPU1_P2_TX_DP<3>")
	)
	(segment
		(start 144.635474 -368.023648)
		(end 144.635474 -368.7445)
		(width 0.14224)
		(layer "In13.Cu")
		(net "P5E_CPU1_P2_TX_DP<3>")
	)
	(segment
		(start 115.551712 -292.228778)
		(end 115.550696 -292.229286)
		(width 0.1143)
		(layer "In13.Cu")
		(net "P5E_CPU1_P2_TX_DP<3>")
	)
	(segment
		(start 115.553744 -293.84752)
		(end 115.552474 -293.848282)
		(width 0.1143)
		(layer "In13.Cu")
		(net "P5E_CPU1_P2_TX_DP<3>")
	)
	(segment
		(start 115.551712 -277.648924)
		(end 115.550696 -277.649432)
		(width 0.1143)
		(layer "In13.Cu")
		(net "P5E_CPU1_P2_TX_DP<3>")
	)
	(segment
		(start 115.519454 -294.804846)
		(end 115.520216 -294.805354)
		(width 0.1143)
		(layer "In13.Cu")
		(net "P5E_CPU1_P2_TX_DP<3>")
	)
	(segment
		(start 115.552474 -288.988246)
		(end 115.551712 -288.988754)
		(width 0.1143)
		(layer "In13.Cu")
		(net "P5E_CPU1_P2_TX_DP<3>")
	)
	(segment
		(start 115.553744 -293.2049)
		(end 115.583462 -293.221918)
		(width 0.1143)
		(layer "In13.Cu")
		(net "P5E_CPU1_P2_TX_DP<3>")
	)
	(segment
		(start 115.552474 -278.624284)
		(end 115.553744 -278.625046)
		(width 0.1143)
		(layer "In13.Cu")
		(net "P5E_CPU1_P2_TX_DP<3>")
	)
	(segment
		(start 115.512596 -273.74088)
		(end 115.519454 -273.744944)
		(width 0.1143)
		(layer "In13.Cu")
		(net "P5E_CPU1_P2_TX_DP<3>")
	)
	(segment
		(start 115.552474 -291.584126)
		(end 115.553744 -291.584888)
		(width 0.1143)
		(layer "In13.Cu")
		(net "P5E_CPU1_P2_TX_DP<3>")
	)
	(segment
		(start 115.519454 -291.564822)
		(end 115.520216 -291.56533)
		(width 0.1143)
		(layer "In13.Cu")
		(net "P5E_CPU1_P2_TX_DP<3>")
	)
	(segment
		(start 115.081812 -272.953734)
		(end 115.112292 -272.971514)
		(width 0.1143)
		(layer "In13.Cu")
		(net "P5E_CPU1_P2_TX_DP<3>")
	)
	(segment
		(start 115.583462 -285.730696)
		(end 115.553744 -285.747714)
		(width 0.1143)
		(layer "In13.Cu")
		(net "P5E_CPU1_P2_TX_DP<3>")
	)
	(segment
		(start 115.551712 -291.583618)
		(end 115.552474 -291.584126)
		(width 0.1143)
		(layer "In13.Cu")
		(net "P5E_CPU1_P2_TX_DP<3>")
	)
	(segment
		(start 142.10538 -360.162602)
		(end 144.169638 -366.16259)
		(width 0.14224)
		(layer "In13.Cu")
		(net "P5E_CPU1_P2_TX_DP<3>")
	)
	(segment
		(start 115.551712 -279.268936)
		(end 115.550696 -279.269444)
		(width 0.1143)
		(layer "In13.Cu")
		(net "P5E_CPU1_P2_TX_DP<3>")
	)
	(segment
		(start 115.553744 -289.964876)
		(end 115.583462 -289.981894)
		(width 0.1143)
		(layer "In13.Cu")
		(net "P5E_CPU1_P2_TX_DP<3>")
	)
	(segment
		(start 115.520216 -291.56533)
		(end 115.551712 -291.583618)
		(width 0.1143)
		(layer "In13.Cu")
		(net "P5E_CPU1_P2_TX_DP<3>")
	)
	(segment
		(start 115.551712 -289.963606)
		(end 115.552474 -289.964114)
		(width 0.1143)
		(layer "In13.Cu")
		(net "P5E_CPU1_P2_TX_DP<3>")
	)
	(segment
		(start 115.549172 -274.410424)
		(end 115.512596 -274.43176)
		(width 0.1143)
		(layer "In13.Cu")
		(net "P5E_CPU1_P2_TX_DP<3>")
	)
	(segment
		(start 115.549172 -290.61029)
		(end 115.512596 -290.631626)
		(width 0.1143)
		(layer "In13.Cu")
		(net "P5E_CPU1_P2_TX_DP<3>")
	)
	(segment
		(start 115.519454 -285.085028)
		(end 115.520216 -285.085536)
		(width 0.1143)
		(layer "In13.Cu")
		(net "P5E_CPU1_P2_TX_DP<3>")
	)
	(segment
		(start 115.552474 -282.508452)
		(end 115.551712 -282.50896)
		(width 0.1143)
		(layer "In13.Cu")
		(net "P5E_CPU1_P2_TX_DP<3>")
	)
	(segment
		(start 115.519454 -283.465016)
		(end 115.520216 -283.465524)
		(width 0.1143)
		(layer "In13.Cu")
		(net "P5E_CPU1_P2_TX_DP<3>")
	)
	(segment
		(start 115.583462 -276.010624)
		(end 115.552474 -276.028404)
		(width 0.1143)
		(layer "In13.Cu")
		(net "P5E_CPU1_P2_TX_DP<3>")
	)
	(segment
		(start 115.520216 -278.605488)
		(end 115.551712 -278.623776)
		(width 0.1143)
		(layer "In13.Cu")
		(net "P5E_CPU1_P2_TX_DP<3>")
	)
	(segment
		(start 115.519454 -281.845004)
		(end 115.520216 -281.845512)
		(width 0.1143)
		(layer "In13.Cu")
		(net "P5E_CPU1_P2_TX_DP<3>")
	)
	(segment
		(start 115.583462 -292.21049)
		(end 115.553744 -292.227508)
		(width 0.1143)
		(layer "In13.Cu")
		(net "P5E_CPU1_P2_TX_DP<3>")
	)
	(segment
		(start 115.550696 -279.269444)
		(end 115.549172 -279.27046)
		(width 0.1143)
		(layer "In13.Cu")
		(net "P5E_CPU1_P2_TX_DP<3>")
	)
	(segment
		(start 115.552474 -275.38426)
		(end 115.553744 -275.385022)
		(width 0.1143)
		(layer "In13.Cu")
		(net "P5E_CPU1_P2_TX_DP<3>")
	)
	(segment
		(start 115.583462 -282.490672)
		(end 115.553744 -282.50769)
		(width 0.1143)
		(layer "In13.Cu")
		(net "P5E_CPU1_P2_TX_DP<3>")
	)
	(segment
		(start 115.552474 -292.22827)
		(end 115.551712 -292.228778)
		(width 0.1143)
		(layer "In13.Cu")
		(net "P5E_CPU1_P2_TX_DP<3>")
	)
	(segment
		(start 115.553744 -277.005034)
		(end 115.583462 -277.022052)
		(width 0.1143)
		(layer "In13.Cu")
		(net "P5E_CPU1_P2_TX_DP<3>")
	)
	(segment
		(start 115.551712 -281.8638)
		(end 115.552474 -281.864308)
		(width 0.1143)
		(layer "In13.Cu")
		(net "P5E_CPU1_P2_TX_DP<3>")
	)
	(segment
		(start 115.520216 -280.2255)
		(end 115.551712 -280.243788)
		(width 0.1143)
		(layer "In13.Cu")
		(net "P5E_CPU1_P2_TX_DP<3>")
	)
	(segment
		(start 115.583462 -279.250648)
		(end 115.552474 -279.268428)
		(width 0.1143)
		(layer "In13.Cu")
		(net "P5E_CPU1_P2_TX_DP<3>")
	)
	(segment
		(start 115.553744 -294.824912)
		(end 115.583462 -294.84193)
		(width 0.1143)
		(layer "In13.Cu")
		(net "P5E_CPU1_P2_TX_DP<3>")
	)
	(segment
		(start 115.551712 -285.103824)
		(end 115.552474 -285.104332)
		(width 0.1143)
		(layer "In13.Cu")
		(net "P5E_CPU1_P2_TX_DP<3>")
	)
	(segment
		(start 114.722656 -272.466308)
		(end 114.80546 -272.549112)
		(width 0.1143)
		(layer "In13.Cu")
		(net "P5E_CPU1_P2_TX_DP<3>")
	)
	(segment
		(start 138.16965 -351.28454)
		(end 142.10538 -360.162602)
		(width 0.14224)
		(layer "In13.Cu")
		(net "P5E_CPU1_P2_TX_DP<3>")
	)
	(segment
		(start 115.550696 -285.749492)
		(end 115.549172 -285.750508)
		(width 0.1143)
		(layer "In13.Cu")
		(net "P5E_CPU1_P2_TX_DP<3>")
	)
	(segment
		(start 115.520216 -276.985476)
		(end 115.551712 -277.003764)
		(width 0.1143)
		(layer "In13.Cu")
		(net "P5E_CPU1_P2_TX_DP<3>")
	)
	(segment
		(start 114.424714 -272.466308)
		(end 114.722656 -272.466308)
		(width 0.1143)
		(layer "In13.Cu")
		(net "P5E_CPU1_P2_TX_DP<3>")
	)
	(segment
		(start 115.550696 -290.609274)
		(end 115.549172 -290.61029)
		(width 0.1143)
		(layer "In13.Cu")
		(net "P5E_CPU1_P2_TX_DP<3>")
	)
	(segment
		(start 115.512596 -289.940746)
		(end 115.550696 -289.963098)
		(width 0.1143)
		(layer "In13.Cu")
		(net "P5E_CPU1_P2_TX_DP<3>")
	)
	(segment
		(start 115.552474 -290.608258)
		(end 115.551712 -290.608766)
		(width 0.1143)
		(layer "In13.Cu")
		(net "P5E_CPU1_P2_TX_DP<3>")
	)
	(segment
		(start 115.520216 -275.365464)
		(end 115.551712 -275.383752)
		(width 0.1143)
		(layer "In13.Cu")
		(net "P5E_CPU1_P2_TX_DP<3>")
	)
	(segment
		(start 115.512596 -278.600916)
		(end 115.519454 -278.60498)
		(width 0.1143)
		(layer "In13.Cu")
		(net "P5E_CPU1_P2_TX_DP<3>")
	)
	(segment
		(start 115.549172 -288.990278)
		(end 115.512596 -289.011614)
		(width 0.1143)
		(layer "In13.Cu")
		(net "P5E_CPU1_P2_TX_DP<3>")
	)
	(segment
		(start 127.785622 -315.592968)
		(end 128.955546 -317.343282)
		(width 0.14224)
		(layer "In13.Cu")
		(net "P5E_CPU1_P2_TX_DP<3>")
	)
	(segment
		(start 115.98275 -295.610788)
		(end 116.052346 -295.651428)
		(width 0.1143)
		(layer "In13.Cu")
		(net "P5E_CPU1_P2_TX_DP<3>")
	)
	(segment
		(start 115.549172 -282.510484)
		(end 115.512596 -282.53182)
		(width 0.1143)
		(layer "In13.Cu")
		(net "P5E_CPU1_P2_TX_DP<3>")
	)
	(segment
		(start 115.552474 -273.764248)
		(end 115.553744 -273.76501)
		(width 0.1143)
		(layer "In13.Cu")
		(net "P5E_CPU1_P2_TX_DP<3>")
	)
	(segment
		(start 132.878322 -324.682866)
		(end 138.16965 -351.28454)
		(width 0.14224)
		(layer "In13.Cu")
		(net "P5E_CPU1_P2_TX_DP<3>")
	)
	(segment
		(start 115.042696 -272.930874)
		(end 115.081812 -272.953734)
		(width 0.1143)
		(layer "In13.Cu")
		(net "P5E_CPU1_P2_TX_DP<3>")
	)
	(segment
		(start 115.553744 -285.747714)
		(end 115.552474 -285.748476)
		(width 0.1143)
		(layer "In13.Cu")
		(net "P5E_CPU1_P2_TX_DP<3>")
	)
	(segment
		(start 115.551712 -274.4089)
		(end 115.550696 -274.409408)
		(width 0.1143)
		(layer "In13.Cu")
		(net "P5E_CPU1_P2_TX_DP<3>")
	)
	(segment
		(start 115.549172 -276.030436)
		(end 115.512596 -276.051772)
		(width 0.1143)
		(layer "In13.Cu")
		(net "P5E_CPU1_P2_TX_DP<3>")
	)
	(segment
		(start 115.552474 -289.964114)
		(end 115.553744 -289.964876)
		(width 0.1143)
		(layer "In13.Cu")
		(net "P5E_CPU1_P2_TX_DP<3>")
	)
	(segment
		(start 115.552474 -277.004272)
		(end 115.553744 -277.005034)
		(width 0.1143)
		(layer "In13.Cu")
		(net "P5E_CPU1_P2_TX_DP<3>")
	)
	(segment
		(start 115.551712 -293.20363)
		(end 115.552474 -293.204138)
		(width 0.1143)
		(layer "In13.Cu")
		(net "P5E_CPU1_P2_TX_DP<3>")
	)
	(segment
		(start 115.551712 -283.483812)
		(end 115.552474 -283.48432)
		(width 0.1143)
		(layer "In13.Cu")
		(net "P5E_CPU1_P2_TX_DP<3>")
	)
	(segment
		(start 115.550696 -292.229286)
		(end 115.549172 -292.230302)
		(width 0.1143)
		(layer "In13.Cu")
		(net "P5E_CPU1_P2_TX_DP<3>")
	)
	(segment
		(start 115.550696 -289.963098)
		(end 115.551712 -289.963606)
		(width 0.1143)
		(layer "In13.Cu")
		(net "P5E_CPU1_P2_TX_DP<3>")
	)
	(segment
		(start 115.553744 -278.625046)
		(end 115.583462 -278.642064)
		(width 0.1143)
		(layer "In13.Cu")
		(net "P5E_CPU1_P2_TX_DP<3>")
	)
	(segment
		(start 115.552474 -284.128464)
		(end 115.551712 -284.128972)
		(width 0.1143)
		(layer "In13.Cu")
		(net "P5E_CPU1_P2_TX_DP<3>")
	)
	(segment
		(start 118.569994 -303.168558)
		(end 127.785622 -315.592968)
		(width 0.14224)
		(layer "In13.Cu")
		(net "P5E_CPU1_P2_TX_DP<3>")
	)
	(segment
		(start 115.553744 -292.227508)
		(end 115.552474 -292.22827)
		(width 0.1143)
		(layer "In13.Cu")
		(net "P5E_CPU1_P2_TX_DP<3>")
	)
	(segment
		(start 115.583462 -290.590478)
		(end 115.553744 -290.607496)
		(width 0.1143)
		(layer "In13.Cu")
		(net "P5E_CPU1_P2_TX_DP<3>")
	)
	(segment
		(start 115.549172 -292.230302)
		(end 115.512596 -292.251638)
		(width 0.1143)
		(layer "In13.Cu")
		(net "P5E_CPU1_P2_TX_DP<3>")
	)
	(segment
		(start 115.552474 -274.408392)
		(end 115.551712 -274.4089)
		(width 0.1143)
		(layer "In13.Cu")
		(net "P5E_CPU1_P2_TX_DP<3>")
	)
	(segment
		(start 115.553744 -283.485082)
		(end 115.583462 -283.5021)
		(width 0.1143)
		(layer "In13.Cu")
		(net "P5E_CPU1_P2_TX_DP<3>")
	)
	(segment
		(start 115.551712 -285.748984)
		(end 115.550696 -285.749492)
		(width 0.1143)
		(layer "In13.Cu")
		(net "P5E_CPU1_P2_TX_DP<3>")
	)
	(arc
		(start 115.512596 -280.911808)
		(mid 115.269269 -281.376374)
		(end 115.512596 -281.84094)
		(width 0.1143)
		(layer "In13.Cu")
		(net "P5E_CPU1_P2_TX_DP<3>")
	)
	(arc
		(start 114.80927 -272.571972)
		(mid 114.890703 -272.77437)
		(end 115.042696 -272.930874)
		(width 0.1143)
		(layer "In13.Cu")
		(net "P5E_CPU1_P2_TX_DP<3>")
	)
	(arc
		(start 115.739418 -295.146222)
		(mid 115.803933 -295.408441)
		(end 115.98275 -295.610788)
		(width 0.1143)
		(layer "In13.Cu")
		(net "P5E_CPU1_P2_TX_DP<3>")
	)
	(arc
		(start 115.739418 -287.046162)
		(mid 115.698163 -287.217133)
		(end 115.583462 -287.350454)
		(width 0.1143)
		(layer "In13.Cu")
		(net "P5E_CPU1_P2_TX_DP<3>")
	)
	(arc
		(start 115.512596 -282.53182)
		(mid 115.269269 -282.996386)
		(end 115.512596 -283.460952)
		(width 0.1143)
		(layer "In13.Cu")
		(net "P5E_CPU1_P2_TX_DP<3>")
	)
	(arc
		(start 115.512596 -292.251638)
		(mid 115.269269 -292.716204)
		(end 115.512596 -293.18077)
		(width 0.1143)
		(layer "In13.Cu")
		(net "P5E_CPU1_P2_TX_DP<3>")
	)
	(arc
		(start 115.512596 -276.051772)
		(mid 115.269269 -276.516338)
		(end 115.512596 -276.980904)
		(width 0.1143)
		(layer "In13.Cu")
		(net "P5E_CPU1_P2_TX_DP<3>")
	)
	(arc
		(start 115.512596 -293.87165)
		(mid 115.269269 -294.336216)
		(end 115.512596 -294.800782)
		(width 0.1143)
		(layer "In13.Cu")
		(net "P5E_CPU1_P2_TX_DP<3>")
	)
	(arc
		(start 115.512596 -289.011614)
		(mid 115.269269 -289.47618)
		(end 115.512596 -289.940746)
		(width 0.1143)
		(layer "In13.Cu")
		(net "P5E_CPU1_P2_TX_DP<3>")
	)
	(arc
		(start 115.58524 -286.743394)
		(mid 115.698647 -286.876283)
		(end 115.739418 -287.046162)
		(width 0.1143)
		(layer "In13.Cu")
		(net "P5E_CPU1_P2_TX_DP<3>")
	)
	(arc
		(start 115.739418 -288.666174)
		(mid 115.698163 -288.837145)
		(end 115.583462 -288.970466)
		(width 0.1143)
		(layer "In13.Cu")
		(net "P5E_CPU1_P2_TX_DP<3>")
	)
	(arc
		(start 115.583462 -291.601906)
		(mid 115.73939 -291.906198)
		(end 115.583462 -292.21049)
		(width 0.1143)
		(layer "In13.Cu")
		(net "P5E_CPU1_P2_TX_DP<3>")
	)
	(arc
		(start 116.052346 -295.651428)
		(mid 116.067368 -295.662746)
		(end 116.08181 -295.674796)
		(width 0.1143)
		(layer "In13.Cu")
		(net "P5E_CPU1_P2_TX_DP<3>")
	)
	(arc
		(start 115.583462 -273.782028)
		(mid 115.73939 -274.08632)
		(end 115.583462 -274.390612)
		(width 0.1143)
		(layer "In13.Cu")
		(net "P5E_CPU1_P2_TX_DP<3>")
	)
	(arc
		(start 115.512596 -285.771844)
		(mid 115.269269 -286.23641)
		(end 115.512596 -286.700976)
		(width 0.1143)
		(layer "In13.Cu")
		(net "P5E_CPU1_P2_TX_DP<3>")
	)
	(arc
		(start 115.58524 -288.363406)
		(mid 115.698647 -288.496295)
		(end 115.739418 -288.666174)
		(width 0.1143)
		(layer "In13.Cu")
		(net "P5E_CPU1_P2_TX_DP<3>")
	)
	(arc
		(start 115.583462 -289.981894)
		(mid 115.73939 -290.286186)
		(end 115.583462 -290.590478)
		(width 0.1143)
		(layer "In13.Cu")
		(net "P5E_CPU1_P2_TX_DP<3>")
	)
	(arc
		(start 115.583462 -277.022052)
		(mid 115.73939 -277.326344)
		(end 115.583462 -277.630636)
		(width 0.1143)
		(layer "In13.Cu")
		(net "P5E_CPU1_P2_TX_DP<3>")
	)
	(arc
		(start 115.583462 -294.84193)
		(mid 115.698138 -294.975264)
		(end 115.739418 -295.146222)
		(width 0.1143)
		(layer "In13.Cu")
		(net "P5E_CPU1_P2_TX_DP<3>")
	)
	(arc
		(start 116.08181 -295.674796)
		(mid 116.176089 -295.801713)
		(end 116.209572 -295.956228)
		(width 0.1143)
		(layer "In13.Cu")
		(net "P5E_CPU1_P2_TX_DP<3>")
	)
	(arc
		(start 115.512596 -274.43176)
		(mid 115.269269 -274.896326)
		(end 115.512596 -275.360892)
		(width 0.1143)
		(layer "In13.Cu")
		(net "P5E_CPU1_P2_TX_DP<3>")
	)
	(arc
		(start 115.583462 -285.122112)
		(mid 115.73939 -285.426404)
		(end 115.583462 -285.730696)
		(width 0.1143)
		(layer "In13.Cu")
		(net "P5E_CPU1_P2_TX_DP<3>")
	)
	(arc
		(start 115.583462 -278.642064)
		(mid 115.73939 -278.946356)
		(end 115.583462 -279.250648)
		(width 0.1143)
		(layer "In13.Cu")
		(net "P5E_CPU1_P2_TX_DP<3>")
	)
	(arc
		(start 115.512596 -277.671784)
		(mid 115.269269 -278.13635)
		(end 115.512596 -278.600916)
		(width 0.1143)
		(layer "In13.Cu")
		(net "P5E_CPU1_P2_TX_DP<3>")
	)
	(arc
		(start 115.583462 -283.5021)
		(mid 115.73939 -283.806392)
		(end 115.583462 -284.110684)
		(width 0.1143)
		(layer "In13.Cu")
		(net "P5E_CPU1_P2_TX_DP<3>")
	)
	(arc
		(start 115.269264 -273.276314)
		(mid 115.333779 -273.538533)
		(end 115.512596 -273.74088)
		(width 0.1143)
		(layer "In13.Cu")
		(net "P5E_CPU1_P2_TX_DP<3>")
	)
	(arc
		(start 115.269264 -287.856422)
		(mid 115.333779 -288.118641)
		(end 115.512596 -288.320988)
		(width 0.1143)
		(layer "In13.Cu")
		(net "P5E_CPU1_P2_TX_DP<3>")
	)
	(arc
		(start 114.80546 -272.549112)
		(mid 114.807248 -272.560561)
		(end 114.80927 -272.571972)
		(width 0.1143)
		(layer "In13.Cu")
		(net "P5E_CPU1_P2_TX_DP<3>")
	)
	(arc
		(start 115.112292 -272.971514)
		(mid 115.227719 -273.10489)
		(end 115.269264 -273.276314)
		(width 0.1143)
		(layer "In13.Cu")
		(net "P5E_CPU1_P2_TX_DP<3>")
	)
	(arc
		(start 115.583462 -280.262076)
		(mid 115.73939 -280.566368)
		(end 115.583462 -280.87066)
		(width 0.1143)
		(layer "In13.Cu")
		(net "P5E_CPU1_P2_TX_DP<3>")
	)
	(arc
		(start 115.515136 -287.390078)
		(mid 115.334484 -287.592823)
		(end 115.269264 -287.856422)
		(width 0.1143)
		(layer "In13.Cu")
		(net "P5E_CPU1_P2_TX_DP<3>")
	)
	(arc
		(start 115.583462 -275.40204)
		(mid 115.73939 -275.706332)
		(end 115.583462 -276.010624)
		(width 0.1143)
		(layer "In13.Cu")
		(net "P5E_CPU1_P2_TX_DP<3>")
	)
	(arc
		(start 115.583462 -281.882088)
		(mid 115.73939 -282.18638)
		(end 115.583462 -282.490672)
		(width 0.1143)
		(layer "In13.Cu")
		(net "P5E_CPU1_P2_TX_DP<3>")
	)
	(arc
		(start 115.583462 -293.221918)
		(mid 115.73939 -293.52621)
		(end 115.583462 -293.830502)
		(width 0.1143)
		(layer "In13.Cu")
		(net "P5E_CPU1_P2_TX_DP<3>")
	)
	(arc
		(start 115.512596 -290.631626)
		(mid 115.269269 -291.096192)
		(end 115.512596 -291.560758)
		(width 0.1143)
		(layer "In13.Cu")
		(net "P5E_CPU1_P2_TX_DP<3>")
	)
	(arc
		(start 115.512596 -279.291796)
		(mid 115.269269 -279.756362)
		(end 115.512596 -280.220928)
		(width 0.1143)
		(layer "In13.Cu")
		(net "P5E_CPU1_P2_TX_DP<3>")
	)
	(arc
		(start 115.512596 -284.151832)
		(mid 115.269269 -284.616398)
		(end 115.512596 -285.080964)
		(width 0.1143)
		(layer "In13.Cu")
		(net "P5E_CPU1_P2_TX_DP<3>")
	)
	(segment
		(start 142.913354 -372.47322)
		(end 142.617444 -372.76913)
		(width 0.12954)
		(layer "F.Cu")
		(net "P5E_CPU1_P2_TX_DP<2>")
	)
	(segment
		(start 142.913354 -371.76964)
		(end 142.913354 -372.47322)
		(width 0.12954)
		(layer "F.Cu")
		(net "P5E_CPU1_P2_TX_DP<2>")
	)
	(segment
		(start 113.957862 -273.820382)
		(end 114.424714 -274.08632)
		(width 0.12954)
		(layer "F.Cu")
		(net "P5E_CPU1_P2_TX_DP<2>")
	)
	(segment
		(start 142.642844 -371.49913)
		(end 142.913354 -371.76964)
		(width 0.12954)
		(layer "F.Cu")
		(net "P5E_CPU1_P2_TX_DP<2>")
	)
	(segment
		(start 114.643408 -285.122112)
		(end 114.643916 -285.122366)
		(width 0.1143)
		(layer "In13.Cu")
		(net "P5E_CPU1_P2_TX_DP<2>")
	)
	(segment
		(start 114.614452 -284.127448)
		(end 114.613436 -284.127956)
		(width 0.1143)
		(layer "In13.Cu")
		(net "P5E_CPU1_P2_TX_DP<2>")
	)
	(segment
		(start 114.612928 -283.484574)
		(end 114.61496 -283.485844)
		(width 0.1143)
		(layer "In13.Cu")
		(net "P5E_CPU1_P2_TX_DP<2>")
	)
	(segment
		(start 114.612674 -284.128464)
		(end 114.609626 -284.129988)
		(width 0.1143)
		(layer "In13.Cu")
		(net "P5E_CPU1_P2_TX_DP<2>")
	)
	(segment
		(start 114.611658 -293.20363)
		(end 114.61242 -293.204138)
		(width 0.1143)
		(layer "In13.Cu")
		(net "P5E_CPU1_P2_TX_DP<2>")
	)
	(segment
		(start 114.643154 -289.981894)
		(end 114.643408 -289.981894)
		(width 0.1143)
		(layer "In13.Cu")
		(net "P5E_CPU1_P2_TX_DP<2>")
	)
	(segment
		(start 114.645948 -285.728918)
		(end 114.610134 -285.749492)
		(width 0.1143)
		(layer "In13.Cu")
		(net "P5E_CPU1_P2_TX_DP<2>")
	)
	(segment
		(start 114.643916 -285.122366)
		(end 114.644678 -285.122874)
		(width 0.1143)
		(layer "In13.Cu")
		(net "P5E_CPU1_P2_TX_DP<2>")
	)
	(segment
		(start 114.580162 -293.185342)
		(end 114.611658 -293.20363)
		(width 0.1143)
		(layer "In13.Cu")
		(net "P5E_CPU1_P2_TX_DP<2>")
	)
	(segment
		(start 114.608102 -283.482034)
		(end 114.610388 -283.483304)
		(width 0.1143)
		(layer "In13.Cu")
		(net "P5E_CPU1_P2_TX_DP<2>")
	)
	(segment
		(start 114.572542 -293.18077)
		(end 114.5794 -293.184834)
		(width 0.1143)
		(layer "In13.Cu")
		(net "P5E_CPU1_P2_TX_DP<2>")
	)
	(segment
		(start 127.475742 -316.818264)
		(end 128.059688 -317.692024)
		(width 0.14224)
		(layer "In13.Cu")
		(net "P5E_CPU1_P2_TX_DP<2>")
	)
	(segment
		(start 114.595148 -294.81399)
		(end 114.640614 -294.840406)
		(width 0.1143)
		(layer "In13.Cu")
		(net "P5E_CPU1_P2_TX_DP<2>")
	)
	(segment
		(start 115.223798 -298.302426)
		(end 116.715794 -301.905416)
		(width 0.14224)
		(layer "In13.Cu")
		(net "P5E_CPU1_P2_TX_DP<2>")
	)
	(segment
		(start 114.611658 -290.608766)
		(end 114.575336 -290.629848)
		(width 0.1143)
		(layer "In13.Cu")
		(net "P5E_CPU1_P2_TX_DP<2>")
	)
	(segment
		(start 114.615976 -293.20617)
		(end 114.6175 -293.206932)
		(width 0.1143)
		(layer "In13.Cu")
		(net "P5E_CPU1_P2_TX_DP<2>")
	)
	(segment
		(start 114.604546 -292.232842)
		(end 114.572542 -292.251638)
		(width 0.1143)
		(layer "In13.Cu")
		(net "P5E_CPU1_P2_TX_DP<2>")
	)
	(segment
		(start 114.610388 -293.837106)
		(end 114.608864 -293.837868)
		(width 0.1143)
		(layer "In13.Cu")
		(net "P5E_CPU1_P2_TX_DP<2>")
	)
	(segment
		(start 114.575336 -280.222706)
		(end 114.611658 -280.243788)
		(width 0.1143)
		(layer "In13.Cu")
		(net "P5E_CPU1_P2_TX_DP<2>")
	)
	(segment
		(start 114.610134 -285.749492)
		(end 114.609372 -285.75)
		(width 0.1143)
		(layer "In13.Cu")
		(net "P5E_CPU1_P2_TX_DP<2>")
	)
	(segment
		(start 128.059688 -317.692024)
		(end 131.977384 -325.020432)
		(width 0.14224)
		(layer "In13.Cu")
		(net "P5E_CPU1_P2_TX_DP<2>")
	)
	(segment
		(start 114.611658 -279.268936)
		(end 114.575336 -279.290018)
		(width 0.1143)
		(layer "In13.Cu")
		(net "P5E_CPU1_P2_TX_DP<2>")
	)
	(segment
		(start 131.977384 -325.020432)
		(end 137.277856 -351.666048)
		(width 0.14224)
		(layer "In13.Cu")
		(net "P5E_CPU1_P2_TX_DP<2>")
	)
	(segment
		(start 115.269518 -295.956228)
		(end 115.269518 -296.2529)
		(width 0.1143)
		(layer "In13.Cu")
		(net "P5E_CPU1_P2_TX_DP<2>")
	)
	(segment
		(start 114.643408 -282.490672)
		(end 114.611658 -282.50896)
		(width 0.1143)
		(layer "In13.Cu")
		(net "P5E_CPU1_P2_TX_DP<2>")
	)
	(segment
		(start 114.611658 -277.003764)
		(end 114.643408 -277.022052)
		(width 0.1143)
		(layer "In13.Cu")
		(net "P5E_CPU1_P2_TX_DP<2>")
	)
	(segment
		(start 114.643408 -274.390612)
		(end 114.611658 -274.4089)
		(width 0.1143)
		(layer "In13.Cu")
		(net "P5E_CPU1_P2_TX_DP<2>")
	)
	(segment
		(start 115.223798 -296.327068)
		(end 115.223798 -298.302426)
		(width 0.14224)
		(layer "In13.Cu")
		(net "P5E_CPU1_P2_TX_DP<2>")
	)
	(segment
		(start 114.611658 -278.623776)
		(end 114.643408 -278.642064)
		(width 0.1143)
		(layer "In13.Cu")
		(net "P5E_CPU1_P2_TX_DP<2>")
	)
	(segment
		(start 115.223798 -296.29862)
		(end 115.223798 -296.327068)
		(width 0.1143)
		(layer "In13.Cu")
		(net "P5E_CPU1_P2_TX_DP<2>")
	)
	(segment
		(start 114.611658 -288.343848)
		(end 114.645186 -288.363406)
		(width 0.1143)
		(layer "In13.Cu")
		(net "P5E_CPU1_P2_TX_DP<2>")
	)
	(segment
		(start 114.6175 -293.206932)
		(end 114.618262 -293.20744)
		(width 0.1143)
		(layer "In13.Cu")
		(net "P5E_CPU1_P2_TX_DP<2>")
	)
	(segment
		(start 114.61242 -292.22827)
		(end 114.611658 -292.228778)
		(width 0.1143)
		(layer "In13.Cu")
		(net "P5E_CPU1_P2_TX_DP<2>")
	)
	(segment
		(start 114.611658 -277.648924)
		(end 114.575336 -277.670006)
		(width 0.1143)
		(layer "In13.Cu")
		(net "P5E_CPU1_P2_TX_DP<2>")
	)
	(segment
		(start 114.609626 -285.102808)
		(end 114.612674 -285.104332)
		(width 0.1143)
		(layer "In13.Cu")
		(net "P5E_CPU1_P2_TX_DP<2>")
	)
	(segment
		(start 114.613436 -285.10484)
		(end 114.643408 -285.122112)
		(width 0.1143)
		(layer "In13.Cu")
		(net "P5E_CPU1_P2_TX_DP<2>")
	)
	(segment
		(start 114.609118 -292.230302)
		(end 114.604546 -292.232842)
		(width 0.1143)
		(layer "In13.Cu")
		(net "P5E_CPU1_P2_TX_DP<2>")
	)
	(segment
		(start 114.643408 -290.590478)
		(end 114.611658 -290.608766)
		(width 0.1143)
		(layer "In13.Cu")
		(net "P5E_CPU1_P2_TX_DP<2>")
	)
	(segment
		(start 114.611658 -286.723836)
		(end 114.645186 -286.743394)
		(width 0.1143)
		(layer "In13.Cu")
		(net "P5E_CPU1_P2_TX_DP<2>")
	)
	(segment
		(start 114.643408 -284.110684)
		(end 114.615214 -284.12694)
		(width 0.1143)
		(layer "In13.Cu")
		(net "P5E_CPU1_P2_TX_DP<2>")
	)
	(segment
		(start 114.64163 -287.351724)
		(end 114.572034 -287.39211)
		(width 0.1143)
		(layer "In13.Cu")
		(net "P5E_CPU1_P2_TX_DP<2>")
	)
	(segment
		(start 114.5794 -293.184834)
		(end 114.580162 -293.185342)
		(width 0.1143)
		(layer "In13.Cu")
		(net "P5E_CPU1_P2_TX_DP<2>")
	)
	(segment
		(start 114.643408 -277.630636)
		(end 114.611658 -277.648924)
		(width 0.1143)
		(layer "In13.Cu")
		(net "P5E_CPU1_P2_TX_DP<2>")
	)
	(segment
		(start 114.424714 -274.08632)
		(end 114.722656 -274.08632)
		(width 0.1143)
		(layer "In13.Cu")
		(net "P5E_CPU1_P2_TX_DP<2>")
	)
	(segment
		(start 114.643408 -292.21049)
		(end 114.61369 -292.227508)
		(width 0.1143)
		(layer "In13.Cu")
		(net "P5E_CPU1_P2_TX_DP<2>")
	)
	(segment
		(start 114.606324 -293.839392)
		(end 114.604292 -293.840662)
		(width 0.1143)
		(layer "In13.Cu")
		(net "P5E_CPU1_P2_TX_DP<2>")
	)
	(segment
		(start 114.618262 -293.20744)
		(end 114.619278 -293.207948)
		(width 0.1143)
		(layer "In13.Cu")
		(net "P5E_CPU1_P2_TX_DP<2>")
	)
	(segment
		(start 114.611658 -280.888948)
		(end 114.60099 -280.895044)
		(width 0.1143)
		(layer "In13.Cu")
		(net "P5E_CPU1_P2_TX_DP<2>")
	)
	(segment
		(start 114.611658 -275.383752)
		(end 114.643408 -275.40204)
		(width 0.1143)
		(layer "In13.Cu")
		(net "P5E_CPU1_P2_TX_DP<2>")
	)
	(segment
		(start 114.609372 -286.722566)
		(end 114.611658 -286.723836)
		(width 0.1143)
		(layer "In13.Cu")
		(net "P5E_CPU1_P2_TX_DP<2>")
	)
	(segment
		(start 114.573304 -289.011106)
		(end 114.561112 -289.019742)
		(width 0.1143)
		(layer "In13.Cu")
		(net "P5E_CPU1_P2_TX_DP<2>")
	)
	(segment
		(start 114.615214 -284.12694)
		(end 114.614452 -284.127448)
		(width 0.1143)
		(layer "In13.Cu")
		(net "P5E_CPU1_P2_TX_DP<2>")
	)
	(segment
		(start 115.269518 -296.2529)
		(end 115.223798 -296.29862)
		(width 0.1143)
		(layer "In13.Cu")
		(net "P5E_CPU1_P2_TX_DP<2>")
	)
	(segment
		(start 114.611658 -274.4089)
		(end 114.575336 -274.429982)
		(width 0.1143)
		(layer "In13.Cu")
		(net "P5E_CPU1_P2_TX_DP<2>")
	)
	(segment
		(start 114.643408 -293.221918)
		(end 114.657886 -293.232332)
		(width 0.1143)
		(layer "In13.Cu")
		(net "P5E_CPU1_P2_TX_DP<2>")
	)
	(segment
		(start 116.715794 -301.905416)
		(end 117.986556 -304.024792)
		(width 0.14224)
		(layer "In13.Cu")
		(net "P5E_CPU1_P2_TX_DP<2>")
	)
	(segment
		(start 114.61496 -283.485844)
		(end 114.615722 -283.486352)
		(width 0.1143)
		(layer "In13.Cu")
		(net "P5E_CPU1_P2_TX_DP<2>")
	)
	(segment
		(start 114.60099 -281.857704)
		(end 114.643408 -281.882088)
		(width 0.1143)
		(layer "In13.Cu")
		(net "P5E_CPU1_P2_TX_DP<2>")
	)
	(segment
		(start 114.59591 -293.845996)
		(end 114.564922 -293.866824)
		(width 0.1143)
		(layer "In13.Cu")
		(net "P5E_CPU1_P2_TX_DP<2>")
	)
	(segment
		(start 114.611658 -292.228778)
		(end 114.610642 -292.229286)
		(width 0.1143)
		(layer "In13.Cu")
		(net "P5E_CPU1_P2_TX_DP<2>")
	)
	(segment
		(start 114.611658 -282.50896)
		(end 114.604038 -282.513278)
		(width 0.1143)
		(layer "In13.Cu")
		(net "P5E_CPU1_P2_TX_DP<2>")
	)
	(segment
		(start 114.722656 -274.08632)
		(end 114.792506 -274.15617)
		(width 0.1143)
		(layer "In13.Cu")
		(net "P5E_CPU1_P2_TX_DP<2>")
	)
	(segment
		(start 114.619278 -293.207948)
		(end 114.643408 -293.221918)
		(width 0.1143)
		(layer "In13.Cu")
		(net "P5E_CPU1_P2_TX_DP<2>")
	)
	(segment
		(start 114.611658 -280.243788)
		(end 114.643408 -280.262076)
		(width 0.1143)
		(layer "In13.Cu")
		(net "P5E_CPU1_P2_TX_DP<2>")
	)
	(segment
		(start 114.329464 -287.853628)
		(end 114.329464 -287.856422)
		(width 0.1143)
		(layer "In13.Cu")
		(net "P5E_CPU1_P2_TX_DP<2>")
	)
	(segment
		(start 114.643408 -287.350454)
		(end 114.64163 -287.351724)
		(width 0.1143)
		(layer "In13.Cu")
		(net "P5E_CPU1_P2_TX_DP<2>")
	)
	(segment
		(start 114.608102 -293.838376)
		(end 114.606324 -293.839392)
		(width 0.1143)
		(layer "In13.Cu")
		(net "P5E_CPU1_P2_TX_DP<2>")
	)
	(segment
		(start 114.627914 -293.826946)
		(end 114.610388 -293.837106)
		(width 0.1143)
		(layer "In13.Cu")
		(net "P5E_CPU1_P2_TX_DP<2>")
	)
	(segment
		(start 114.575336 -276.982682)
		(end 114.611658 -277.003764)
		(width 0.1143)
		(layer "In13.Cu")
		(net "P5E_CPU1_P2_TX_DP<2>")
	)
	(segment
		(start 115.042696 -295.610788)
		(end 115.112292 -295.651428)
		(width 0.1143)
		(layer "In13.Cu")
		(net "P5E_CPU1_P2_TX_DP<2>")
	)
	(segment
		(start 114.612674 -285.104332)
		(end 114.613436 -285.10484)
		(width 0.1143)
		(layer "In13.Cu")
		(net "P5E_CPU1_P2_TX_DP<2>")
	)
	(segment
		(start 114.611658 -276.028912)
		(end 114.575336 -276.049994)
		(width 0.1143)
		(layer "In13.Cu")
		(net "P5E_CPU1_P2_TX_DP<2>")
	)
	(segment
		(start 114.575336 -291.562536)
		(end 114.611658 -291.583618)
		(width 0.1143)
		(layer "In13.Cu")
		(net "P5E_CPU1_P2_TX_DP<2>")
	)
	(segment
		(start 114.608864 -293.837868)
		(end 114.608102 -293.838376)
		(width 0.1143)
		(layer "In13.Cu")
		(net "P5E_CPU1_P2_TX_DP<2>")
	)
	(segment
		(start 114.613436 -284.127956)
		(end 114.612674 -284.128464)
		(width 0.1143)
		(layer "In13.Cu")
		(net "P5E_CPU1_P2_TX_DP<2>")
	)
	(segment
		(start 114.575336 -275.36267)
		(end 114.611658 -275.383752)
		(width 0.1143)
		(layer "In13.Cu")
		(net "P5E_CPU1_P2_TX_DP<2>")
	)
	(segment
		(start 114.575336 -278.602694)
		(end 114.611658 -278.623776)
		(width 0.1143)
		(layer "In13.Cu")
		(net "P5E_CPU1_P2_TX_DP<2>")
	)
	(segment
		(start 114.640614 -294.840406)
		(end 114.643408 -294.84193)
		(width 0.1143)
		(layer "In13.Cu")
		(net "P5E_CPU1_P2_TX_DP<2>")
	)
	(segment
		(start 114.610642 -292.229286)
		(end 114.609118 -292.230302)
		(width 0.1143)
		(layer "In13.Cu")
		(net "P5E_CPU1_P2_TX_DP<2>")
	)
	(segment
		(start 114.570002 -288.31921)
		(end 114.611912 -288.343594)
		(width 0.1143)
		(layer "In13.Cu")
		(net "P5E_CPU1_P2_TX_DP<2>")
	)
	(segment
		(start 114.615722 -283.486352)
		(end 114.643408 -283.5021)
		(width 0.1143)
		(layer "In13.Cu")
		(net "P5E_CPU1_P2_TX_DP<2>")
	)
	(segment
		(start 114.609372 -285.75)
		(end 114.609372 -285.750254)
		(width 0.1143)
		(layer "In13.Cu")
		(net "P5E_CPU1_P2_TX_DP<2>")
	)
	(segment
		(start 114.643408 -280.87066)
		(end 114.611658 -280.888948)
		(width 0.1143)
		(layer "In13.Cu")
		(net "P5E_CPU1_P2_TX_DP<2>")
	)
	(segment
		(start 114.611658 -291.583618)
		(end 114.643408 -291.601906)
		(width 0.1143)
		(layer "In13.Cu")
		(net "P5E_CPU1_P2_TX_DP<2>")
	)
	(segment
		(start 114.643408 -276.010624)
		(end 114.611658 -276.028912)
		(width 0.1143)
		(layer "In13.Cu")
		(net "P5E_CPU1_P2_TX_DP<2>")
	)
	(segment
		(start 114.643408 -279.250648)
		(end 114.611658 -279.268936)
		(width 0.1143)
		(layer "In13.Cu")
		(net "P5E_CPU1_P2_TX_DP<2>")
	)
	(segment
		(start 137.277856 -351.666048)
		(end 142.933674 -370.310664)
		(width 0.14224)
		(layer "In13.Cu")
		(net "P5E_CPU1_P2_TX_DP<2>")
	)
	(segment
		(start 114.61242 -293.204138)
		(end 114.615214 -293.205662)
		(width 0.1143)
		(layer "In13.Cu")
		(net "P5E_CPU1_P2_TX_DP<2>")
	)
	(segment
		(start 114.561112 -289.932618)
		(end 114.573304 -289.941254)
		(width 0.1143)
		(layer "In13.Cu")
		(net "P5E_CPU1_P2_TX_DP<2>")
	)
	(segment
		(start 114.61369 -292.227508)
		(end 114.61242 -292.22827)
		(width 0.1143)
		(layer "In13.Cu")
		(net "P5E_CPU1_P2_TX_DP<2>")
	)
	(segment
		(start 142.933674 -371.2083)
		(end 142.642844 -371.49913)
		(width 0.14224)
		(layer "In13.Cu")
		(net "P5E_CPU1_P2_TX_DP<2>")
	)
	(segment
		(start 114.610388 -283.483304)
		(end 114.612928 -283.484574)
		(width 0.1143)
		(layer "In13.Cu")
		(net "P5E_CPU1_P2_TX_DP<2>")
	)
	(segment
		(start 114.615214 -293.205662)
		(end 114.615976 -293.20617)
		(width 0.1143)
		(layer "In13.Cu")
		(net "P5E_CPU1_P2_TX_DP<2>")
	)
	(segment
		(start 117.986556 -304.024792)
		(end 127.475742 -316.818264)
		(width 0.14224)
		(layer "In13.Cu")
		(net "P5E_CPU1_P2_TX_DP<2>")
	)
	(segment
		(start 114.643408 -288.970466)
		(end 114.573304 -289.011106)
		(width 0.1143)
		(layer "In13.Cu")
		(net "P5E_CPU1_P2_TX_DP<2>")
	)
	(segment
		(start 142.933674 -370.310664)
		(end 142.933674 -371.2083)
		(width 0.14224)
		(layer "In13.Cu")
		(net "P5E_CPU1_P2_TX_DP<2>")
	)
	(segment
		(start 114.573304 -289.941254)
		(end 114.643154 -289.981894)
		(width 0.1143)
		(layer "In13.Cu")
		(net "P5E_CPU1_P2_TX_DP<2>")
	)
	(segment
		(start 114.604038 -283.479494)
		(end 114.608102 -283.482034)
		(width 0.1143)
		(layer "In13.Cu")
		(net "P5E_CPU1_P2_TX_DP<2>")
	)
	(segment
		(start 114.572034 -287.39211)
		(end 114.561112 -287.39973)
		(width 0.1143)
		(layer "In13.Cu")
		(net "P5E_CPU1_P2_TX_DP<2>")
	)
	(segment
		(start 114.611912 -288.343594)
		(end 114.611658 -288.343848)
		(width 0.1143)
		(layer "In13.Cu")
		(net "P5E_CPU1_P2_TX_DP<2>")
	)
	(arc
		(start 114.643408 -281.882088)
		(mid 114.799336 -282.18638)
		(end 114.643408 -282.490672)
		(width 0.1143)
		(layer "In13.Cu")
		(net "P5E_CPU1_P2_TX_DP<2>")
	)
	(arc
		(start 114.643408 -291.601906)
		(mid 114.799336 -291.906198)
		(end 114.643408 -292.21049)
		(width 0.1143)
		(layer "In13.Cu")
		(net "P5E_CPU1_P2_TX_DP<2>")
	)
	(arc
		(start 114.561112 -287.39973)
		(mid 114.390569 -287.598751)
		(end 114.329464 -287.853628)
		(width 0.1143)
		(layer "In13.Cu")
		(net "P5E_CPU1_P2_TX_DP<2>")
	)
	(arc
		(start 114.561112 -276.0599)
		(mid 114.333729 -276.516338)
		(end 114.561112 -276.972776)
		(width 0.1143)
		(layer "In13.Cu")
		(net "P5E_CPU1_P2_TX_DP<2>")
	)
	(arc
		(start 114.799364 -288.666174)
		(mid 114.758109 -288.837145)
		(end 114.643408 -288.970466)
		(width 0.1143)
		(layer "In13.Cu")
		(net "P5E_CPU1_P2_TX_DP<2>")
	)
	(arc
		(start 114.609626 -284.129988)
		(mid 114.329605 -284.616398)
		(end 114.609626 -285.102808)
		(width 0.1143)
		(layer "In13.Cu")
		(net "P5E_CPU1_P2_TX_DP<2>")
	)
	(arc
		(start 114.643408 -280.262076)
		(mid 114.799336 -280.566368)
		(end 114.643408 -280.87066)
		(width 0.1143)
		(layer "In13.Cu")
		(net "P5E_CPU1_P2_TX_DP<2>")
	)
	(arc
		(start 114.561112 -277.679912)
		(mid 114.333729 -278.13635)
		(end 114.561112 -278.592788)
		(width 0.1143)
		(layer "In13.Cu")
		(net "P5E_CPU1_P2_TX_DP<2>")
	)
	(arc
		(start 115.112292 -295.651428)
		(mid 115.127314 -295.662746)
		(end 115.141756 -295.674796)
		(width 0.1143)
		(layer "In13.Cu")
		(net "P5E_CPU1_P2_TX_DP<2>")
	)
	(arc
		(start 114.609372 -285.750254)
		(mid 114.329444 -286.23641)
		(end 114.609372 -286.722566)
		(width 0.1143)
		(layer "In13.Cu")
		(net "P5E_CPU1_P2_TX_DP<2>")
	)
	(arc
		(start 114.792506 -274.15617)
		(mid 114.740457 -274.287689)
		(end 114.643408 -274.390612)
		(width 0.1143)
		(layer "In13.Cu")
		(net "P5E_CPU1_P2_TX_DP<2>")
	)
	(arc
		(start 114.561112 -279.299924)
		(mid 114.333729 -279.756362)
		(end 114.561112 -280.2128)
		(width 0.1143)
		(layer "In13.Cu")
		(net "P5E_CPU1_P2_TX_DP<2>")
	)
	(arc
		(start 114.575336 -276.049994)
		(mid 114.568187 -276.054894)
		(end 114.561112 -276.0599)
		(width 0.1143)
		(layer "In13.Cu")
		(net "P5E_CPU1_P2_TX_DP<2>")
	)
	(arc
		(start 114.643408 -277.022052)
		(mid 114.799336 -277.326344)
		(end 114.643408 -277.630636)
		(width 0.1143)
		(layer "In13.Cu")
		(net "P5E_CPU1_P2_TX_DP<2>")
	)
	(arc
		(start 114.575336 -279.290018)
		(mid 114.568187 -279.294918)
		(end 114.561112 -279.299924)
		(width 0.1143)
		(layer "In13.Cu")
		(net "P5E_CPU1_P2_TX_DP<2>")
	)
	(arc
		(start 114.55908 -290.641278)
		(mid 114.336196 -291.096192)
		(end 114.55908 -291.551106)
		(width 0.1143)
		(layer "In13.Cu")
		(net "P5E_CPU1_P2_TX_DP<2>")
	)
	(arc
		(start 114.643408 -275.40204)
		(mid 114.799336 -275.706332)
		(end 114.643408 -276.010624)
		(width 0.1143)
		(layer "In13.Cu")
		(net "P5E_CPU1_P2_TX_DP<2>")
	)
	(arc
		(start 114.604292 -293.840662)
		(mid 114.600089 -293.843311)
		(end 114.59591 -293.845996)
		(width 0.1143)
		(layer "In13.Cu")
		(net "P5E_CPU1_P2_TX_DP<2>")
	)
	(arc
		(start 114.561112 -274.439888)
		(mid 114.333729 -274.896326)
		(end 114.561112 -275.352764)
		(width 0.1143)
		(layer "In13.Cu")
		(net "P5E_CPU1_P2_TX_DP<2>")
	)
	(arc
		(start 114.561112 -278.592788)
		(mid 114.568186 -278.597795)
		(end 114.575336 -278.602694)
		(width 0.1143)
		(layer "In13.Cu")
		(net "P5E_CPU1_P2_TX_DP<2>")
	)
	(arc
		(start 114.60099 -280.895044)
		(mid 114.323844 -281.376374)
		(end 114.60099 -281.857704)
		(width 0.1143)
		(layer "In13.Cu")
		(net "P5E_CPU1_P2_TX_DP<2>")
	)
	(arc
		(start 115.141756 -295.674796)
		(mid 115.236035 -295.801713)
		(end 115.269518 -295.956228)
		(width 0.1143)
		(layer "In13.Cu")
		(net "P5E_CPU1_P2_TX_DP<2>")
	)
	(arc
		(start 114.561112 -280.2128)
		(mid 114.568186 -280.217807)
		(end 114.575336 -280.222706)
		(width 0.1143)
		(layer "In13.Cu")
		(net "P5E_CPU1_P2_TX_DP<2>")
	)
	(arc
		(start 114.643408 -294.84193)
		(mid 114.758084 -294.975264)
		(end 114.799364 -295.146222)
		(width 0.1143)
		(layer "In13.Cu")
		(net "P5E_CPU1_P2_TX_DP<2>")
	)
	(arc
		(start 114.799364 -295.146222)
		(mid 114.863879 -295.408441)
		(end 115.042696 -295.610788)
		(width 0.1143)
		(layer "In13.Cu")
		(net "P5E_CPU1_P2_TX_DP<2>")
	)
	(arc
		(start 114.561112 -276.972776)
		(mid 114.568186 -276.977783)
		(end 114.575336 -276.982682)
		(width 0.1143)
		(layer "In13.Cu")
		(net "P5E_CPU1_P2_TX_DP<2>")
	)
	(arc
		(start 114.643408 -283.5021)
		(mid 114.799336 -283.806392)
		(end 114.643408 -284.110684)
		(width 0.1143)
		(layer "In13.Cu")
		(net "P5E_CPU1_P2_TX_DP<2>")
	)
	(arc
		(start 114.561112 -289.019742)
		(mid 114.326691 -289.47618)
		(end 114.561112 -289.932618)
		(width 0.1143)
		(layer "In13.Cu")
		(net "P5E_CPU1_P2_TX_DP<2>")
	)
	(arc
		(start 114.564922 -293.866824)
		(mid 114.317191 -294.348743)
		(end 114.595148 -294.81399)
		(width 0.1143)
		(layer "In13.Cu")
		(net "P5E_CPU1_P2_TX_DP<2>")
	)
	(arc
		(start 114.575336 -274.429982)
		(mid 114.568187 -274.434882)
		(end 114.561112 -274.439888)
		(width 0.1143)
		(layer "In13.Cu")
		(net "P5E_CPU1_P2_TX_DP<2>")
	)
	(arc
		(start 114.575336 -277.670006)
		(mid 114.568187 -277.674906)
		(end 114.561112 -277.679912)
		(width 0.1143)
		(layer "In13.Cu")
		(net "P5E_CPU1_P2_TX_DP<2>")
	)
	(arc
		(start 114.575336 -290.629848)
		(mid 114.567158 -290.635491)
		(end 114.55908 -290.641278)
		(width 0.1143)
		(layer "In13.Cu")
		(net "P5E_CPU1_P2_TX_DP<2>")
	)
	(arc
		(start 114.645186 -286.743394)
		(mid 114.758593 -286.876283)
		(end 114.799364 -287.046162)
		(width 0.1143)
		(layer "In13.Cu")
		(net "P5E_CPU1_P2_TX_DP<2>")
	)
	(arc
		(start 114.604038 -282.513278)
		(mid 114.325861 -282.996386)
		(end 114.604038 -283.479494)
		(width 0.1143)
		(layer "In13.Cu")
		(net "P5E_CPU1_P2_TX_DP<2>")
	)
	(arc
		(start 114.643408 -289.981894)
		(mid 114.799336 -290.286186)
		(end 114.643408 -290.590478)
		(width 0.1143)
		(layer "In13.Cu")
		(net "P5E_CPU1_P2_TX_DP<2>")
	)
	(arc
		(start 114.643408 -278.642064)
		(mid 114.799336 -278.946356)
		(end 114.643408 -279.250648)
		(width 0.1143)
		(layer "In13.Cu")
		(net "P5E_CPU1_P2_TX_DP<2>")
	)
	(arc
		(start 114.572542 -292.251638)
		(mid 114.329215 -292.716204)
		(end 114.572542 -293.18077)
		(width 0.1143)
		(layer "In13.Cu")
		(net "P5E_CPU1_P2_TX_DP<2>")
	)
	(arc
		(start 114.644678 -285.122874)
		(mid 114.800834 -285.425592)
		(end 114.645948 -285.728918)
		(width 0.1143)
		(layer "In13.Cu")
		(net "P5E_CPU1_P2_TX_DP<2>")
	)
	(arc
		(start 114.799364 -287.046162)
		(mid 114.758109 -287.217133)
		(end 114.643408 -287.350454)
		(width 0.1143)
		(layer "In13.Cu")
		(net "P5E_CPU1_P2_TX_DP<2>")
	)
	(arc
		(start 114.657886 -293.232332)
		(mid 114.80472 -293.53775)
		(end 114.627914 -293.826946)
		(width 0.1143)
		(layer "In13.Cu")
		(net "P5E_CPU1_P2_TX_DP<2>")
	)
	(arc
		(start 114.561112 -275.352764)
		(mid 114.568186 -275.357771)
		(end 114.575336 -275.36267)
		(width 0.1143)
		(layer "In13.Cu")
		(net "P5E_CPU1_P2_TX_DP<2>")
	)
	(arc
		(start 114.645186 -288.363406)
		(mid 114.758593 -288.496295)
		(end 114.799364 -288.666174)
		(width 0.1143)
		(layer "In13.Cu")
		(net "P5E_CPU1_P2_TX_DP<2>")
	)
	(arc
		(start 114.329464 -287.856422)
		(mid 114.39314 -288.117226)
		(end 114.570002 -288.31921)
		(width 0.1143)
		(layer "In13.Cu")
		(net "P5E_CPU1_P2_TX_DP<2>")
	)
	(arc
		(start 114.55908 -291.551106)
		(mid 114.567158 -291.556892)
		(end 114.575336 -291.562536)
		(width 0.1143)
		(layer "In13.Cu")
		(net "P5E_CPU1_P2_TX_DP<2>")
	)
	(segment
		(start 142.032482 -376.23877)
		(end 142.328392 -375.94286)
		(width 0.12954)
		(layer "F.Cu")
		(net "P5E_CPU1_P2_TX_DP<1>")
	)
	(segment
		(start 141.328902 -376.23877)
		(end 142.032482 -376.23877)
		(width 0.12954)
		(layer "F.Cu")
		(net "P5E_CPU1_P2_TX_DP<1>")
	)
	(segment
		(start 141.058392 -375.96826)
		(end 141.328902 -376.23877)
		(width 0.12954)
		(layer "F.Cu")
		(net "P5E_CPU1_P2_TX_DP<1>")
	)
	(segment
		(start 113.957862 -270.580358)
		(end 114.424714 -270.846296)
		(width 0.12954)
		(layer "F.Cu")
		(net "P5E_CPU1_P2_TX_DP<1>")
	)
	(segment
		(start 113.702338 -280.871168)
		(end 113.671858 -280.888948)
		(width 0.1143)
		(layer "In13.Cu")
		(net "P5E_CPU1_P2_TX_DP<1>")
	)
	(segment
		(start 113.672874 -282.508452)
		(end 113.671858 -282.50896)
		(width 0.1143)
		(layer "In13.Cu")
		(net "P5E_CPU1_P2_TX_DP<1>")
	)
	(segment
		(start 141.02715 -367.88344)
		(end 140.88999 -368.0206)
		(width 0.14224)
		(layer "In13.Cu")
		(net "P5E_CPU1_P2_TX_DP<1>")
	)
	(segment
		(start 140.88999 -369.57508)
		(end 141.02715 -369.71224)
		(width 0.14224)
		(layer "In13.Cu")
		(net "P5E_CPU1_P2_TX_DP<1>")
	)
	(segment
		(start 113.702338 -276.011132)
		(end 113.671858 -276.028912)
		(width 0.1143)
		(layer "In13.Cu")
		(net "P5E_CPU1_P2_TX_DP<1>")
	)
	(segment
		(start 113.671858 -289.963606)
		(end 113.702338 -289.981386)
		(width 0.1143)
		(layer "In13.Cu")
		(net "P5E_CPU1_P2_TX_DP<1>")
	)
	(segment
		(start 114.643408 -271.150588)
		(end 114.61242 -271.168368)
		(width 0.1143)
		(layer "In13.Cu")
		(net "P5E_CPU1_P2_TX_DP<1>")
	)
	(segment
		(start 114.141758 -271.978882)
		(end 114.140742 -271.97939)
		(width 0.1143)
		(layer "In13.Cu")
		(net "P5E_CPU1_P2_TX_DP<1>")
	)
	(segment
		(start 114.283744 -296.327068)
		(end 114.283744 -298.470066)
		(width 0.14224)
		(layer "In13.Cu")
		(net "P5E_CPU1_P2_TX_DP<1>")
	)
	(segment
		(start 114.611658 -271.168876)
		(end 114.61115 -271.16913)
		(width 0.1143)
		(layer "In13.Cu")
		(net "P5E_CPU1_P2_TX_DP<1>")
	)
	(segment
		(start 113.702338 -293.83101)
		(end 113.671858 -293.84879)
		(width 0.1143)
		(layer "In13.Cu")
		(net "P5E_CPU1_P2_TX_DP<1>")
	)
	(segment
		(start 141.779498 -374.022112)
		(end 141.958822 -374.09628)
		(width 0.14224)
		(layer "In13.Cu")
		(net "P5E_CPU1_P2_TX_DP<1>")
	)
	(segment
		(start 113.702338 -272.771108)
		(end 113.671858 -272.788888)
		(width 0.1143)
		(layer "In13.Cu")
		(net "P5E_CPU1_P2_TX_DP<1>")
	)
	(segment
		(start 114.134138 -271.983454)
		(end 114.102642 -272.001742)
		(width 0.1143)
		(layer "In13.Cu")
		(net "P5E_CPU1_P2_TX_DP<1>")
	)
	(segment
		(start 113.671858 -282.50896)
		(end 113.668048 -282.511246)
		(width 0.1143)
		(layer "In13.Cu")
		(net "P5E_CPU1_P2_TX_DP<1>")
	)
	(segment
		(start 113.635536 -288.322766)
		(end 113.67135 -288.34334)
		(width 0.1143)
		(layer "In13.Cu")
		(net "P5E_CPU1_P2_TX_DP<1>")
	)
	(segment
		(start 114.61115 -271.16913)
		(end 114.575336 -271.189958)
		(width 0.1143)
		(layer "In13.Cu")
		(net "P5E_CPU1_P2_TX_DP<1>")
	)
	(segment
		(start 114.140742 -271.97939)
		(end 114.139218 -271.980406)
		(width 0.1143)
		(layer "In13.Cu")
		(net "P5E_CPU1_P2_TX_DP<1>")
	)
	(segment
		(start 113.67516 -293.205662)
		(end 113.676176 -293.20617)
		(width 0.1143)
		(layer "In13.Cu")
		(net "P5E_CPU1_P2_TX_DP<1>")
	)
	(segment
		(start 113.702338 -280.261822)
		(end 113.702338 -280.261568)
		(width 0.1143)
		(layer "In13.Cu")
		(net "P5E_CPU1_P2_TX_DP<1>")
	)
	(segment
		(start 113.668048 -283.481526)
		(end 113.67262 -283.48432)
		(width 0.1143)
		(layer "In13.Cu")
		(net "P5E_CPU1_P2_TX_DP<1>")
	)
	(segment
		(start 113.671858 -276.028912)
		(end 113.632742 -276.051772)
		(width 0.1143)
		(layer "In13.Cu")
		(net "P5E_CPU1_P2_TX_DP<1>")
	)
	(segment
		(start 113.672366 -288.9885)
		(end 113.634266 -289.010598)
		(width 0.1143)
		(layer "In13.Cu")
		(net "P5E_CPU1_P2_TX_DP<1>")
	)
	(segment
		(start 114.102642 -295.610788)
		(end 114.172238 -295.651428)
		(width 0.1143)
		(layer "In13.Cu")
		(net "P5E_CPU1_P2_TX_DP<1>")
	)
	(segment
		(start 113.686082 -288.980118)
		(end 113.673382 -288.987992)
		(width 0.1143)
		(layer "In13.Cu")
		(net "P5E_CPU1_P2_TX_DP<1>")
	)
	(segment
		(start 113.673382 -293.204646)
		(end 113.674398 -293.205154)
		(width 0.1143)
		(layer "In13.Cu")
		(net "P5E_CPU1_P2_TX_DP<1>")
	)
	(segment
		(start 141.984476 -376.25909)
		(end 141.349222 -376.25909)
		(width 0.14224)
		(layer "In13.Cu")
		(net "P5E_CPU1_P2_TX_DP<1>")
	)
	(segment
		(start 140.88999 -368.0206)
		(end 140.88999 -368.44732)
		(width 0.14224)
		(layer "In13.Cu")
		(net "P5E_CPU1_P2_TX_DP<1>")
	)
	(segment
		(start 113.671858 -273.76374)
		(end 113.702338 -273.78152)
		(width 0.1143)
		(layer "In13.Cu")
		(net "P5E_CPU1_P2_TX_DP<1>")
	)
	(segment
		(start 113.702338 -274.39112)
		(end 113.671858 -274.4089)
		(width 0.1143)
		(layer "In13.Cu")
		(net "P5E_CPU1_P2_TX_DP<1>")
	)
	(segment
		(start 141.349222 -376.25909)
		(end 141.058392 -375.96826)
		(width 0.14224)
		(layer "In13.Cu")
		(net "P5E_CPU1_P2_TX_DP<1>")
	)
	(segment
		(start 140.88999 -370.70284)
		(end 141.02715 -370.84)
		(width 0.14224)
		(layer "In13.Cu")
		(net "P5E_CPU1_P2_TX_DP<1>")
	)
	(segment
		(start 114.329464 -296.2529)
		(end 114.283744 -296.29862)
		(width 0.1143)
		(layer "In13.Cu")
		(net "P5E_CPU1_P2_TX_DP<1>")
	)
	(segment
		(start 113.67262 -283.48432)
		(end 113.702338 -283.501592)
		(width 0.1143)
		(layer "In13.Cu")
		(net "P5E_CPU1_P2_TX_DP<1>")
	)
	(segment
		(start 113.671858 -272.788888)
		(end 113.632742 -272.811748)
		(width 0.1143)
		(layer "In13.Cu")
		(net "P5E_CPU1_P2_TX_DP<1>")
	)
	(segment
		(start 113.635536 -289.942524)
		(end 113.671858 -289.963606)
		(width 0.1143)
		(layer "In13.Cu")
		(net "P5E_CPU1_P2_TX_DP<1>")
	)
	(segment
		(start 141.02715 -368.58448)
		(end 141.02715 -369.0112)
		(width 0.14224)
		(layer "In13.Cu")
		(net "P5E_CPU1_P2_TX_DP<1>")
	)
	(segment
		(start 113.632742 -273.74088)
		(end 113.671858 -273.76374)
		(width 0.1143)
		(layer "In13.Cu")
		(net "P5E_CPU1_P2_TX_DP<1>")
	)
	(segment
		(start 113.671858 -285.103824)
		(end 113.702338 -285.121604)
		(width 0.1143)
		(layer "In13.Cu")
		(net "P5E_CPU1_P2_TX_DP<1>")
	)
	(segment
		(start 114.139218 -271.980406)
		(end 114.138202 -271.980914)
		(width 0.1143)
		(layer "In13.Cu")
		(net "P5E_CPU1_P2_TX_DP<1>")
	)
	(segment
		(start 113.673382 -292.227762)
		(end 113.67262 -292.22827)
		(width 0.1143)
		(layer "In13.Cu")
		(net "P5E_CPU1_P2_TX_DP<1>")
	)
	(segment
		(start 140.88999 -369.14836)
		(end 140.88999 -369.57508)
		(width 0.14224)
		(layer "In13.Cu")
		(net "P5E_CPU1_P2_TX_DP<1>")
	)
	(segment
		(start 113.702338 -284.111192)
		(end 113.67262 -284.128464)
		(width 0.1143)
		(layer "In13.Cu")
		(net "P5E_CPU1_P2_TX_DP<1>")
	)
	(segment
		(start 127.30353 -318.262)
		(end 131.09321 -325.355458)
		(width 0.14224)
		(layer "In13.Cu")
		(net "P5E_CPU1_P2_TX_DP<1>")
	)
	(segment
		(start 113.67262 -293.204138)
		(end 113.673382 -293.204646)
		(width 0.1143)
		(layer "In13.Cu")
		(net "P5E_CPU1_P2_TX_DP<1>")
	)
	(segment
		(start 113.668048 -281.861514)
		(end 113.67262 -281.864308)
		(width 0.1143)
		(layer "In13.Cu")
		(net "P5E_CPU1_P2_TX_DP<1>")
	)
	(segment
		(start 131.09321 -325.355458)
		(end 136.395206 -352.008948)
		(width 0.14224)
		(layer "In13.Cu")
		(net "P5E_CPU1_P2_TX_DP<1>")
	)
	(segment
		(start 113.669572 -293.202614)
		(end 113.67262 -293.204138)
		(width 0.1143)
		(layer "In13.Cu")
		(net "P5E_CPU1_P2_TX_DP<1>")
	)
	(segment
		(start 114.283744 -296.29862)
		(end 114.283744 -296.327068)
		(width 0.1143)
		(layer "In13.Cu")
		(net "P5E_CPU1_P2_TX_DP<1>")
	)
	(segment
		(start 113.671604 -285.103824)
		(end 113.671858 -285.103824)
		(width 0.1143)
		(layer "In13.Cu")
		(net "P5E_CPU1_P2_TX_DP<1>")
	)
	(segment
		(start 113.67262 -284.128464)
		(end 113.671858 -284.128972)
		(width 0.1143)
		(layer "In13.Cu")
		(net "P5E_CPU1_P2_TX_DP<1>")
	)
	(segment
		(start 140.88999 -370.27612)
		(end 140.88999 -370.70284)
		(width 0.14224)
		(layer "In13.Cu")
		(net "P5E_CPU1_P2_TX_DP<1>")
	)
	(segment
		(start 141.958822 -374.09628)
		(end 142.173452 -374.614694)
		(width 0.14224)
		(layer "In13.Cu")
		(net "P5E_CPU1_P2_TX_DP<1>")
	)
	(segment
		(start 113.635536 -291.562536)
		(end 113.671858 -291.583618)
		(width 0.1143)
		(layer "In13.Cu")
		(net "P5E_CPU1_P2_TX_DP<1>")
	)
	(segment
		(start 141.248892 -372.382288)
		(end 141.690344 -373.448326)
		(width 0.14224)
		(layer "In13.Cu")
		(net "P5E_CPU1_P2_TX_DP<1>")
	)
	(segment
		(start 113.671858 -291.583618)
		(end 113.702338 -291.601398)
		(width 0.1143)
		(layer "In13.Cu")
		(net "P5E_CPU1_P2_TX_DP<1>")
	)
	(segment
		(start 141.690344 -373.448326)
		(end 141.616176 -373.62765)
		(width 0.14224)
		(layer "In13.Cu")
		(net "P5E_CPU1_P2_TX_DP<1>")
	)
	(segment
		(start 114.14252 -271.978374)
		(end 114.141758 -271.978882)
		(width 0.1143)
		(layer "In13.Cu")
		(net "P5E_CPU1_P2_TX_DP<1>")
	)
	(segment
		(start 142.362428 -375.564146)
		(end 142.362428 -376.049286)
		(width 0.14224)
		(layer "In13.Cu")
		(net "P5E_CPU1_P2_TX_DP<1>")
	)
	(segment
		(start 113.671858 -294.823642)
		(end 113.702338 -294.841422)
		(width 0.1143)
		(layer "In13.Cu")
		(net "P5E_CPU1_P2_TX_DP<1>")
	)
	(segment
		(start 114.138202 -271.980914)
		(end 114.135662 -271.982438)
		(width 0.1143)
		(layer "In13.Cu")
		(net "P5E_CPU1_P2_TX_DP<1>")
	)
	(segment
		(start 141.02715 -370.13896)
		(end 140.88999 -370.27612)
		(width 0.14224)
		(layer "In13.Cu")
		(net "P5E_CPU1_P2_TX_DP<1>")
	)
	(segment
		(start 114.722656 -270.846296)
		(end 114.792506 -270.916146)
		(width 0.1143)
		(layer "In13.Cu")
		(net "P5E_CPU1_P2_TX_DP<1>")
	)
	(segment
		(start 141.02715 -370.84)
		(end 141.02715 -371.26672)
		(width 0.14224)
		(layer "In13.Cu")
		(net "P5E_CPU1_P2_TX_DP<1>")
	)
	(segment
		(start 113.676176 -293.20617)
		(end 113.703354 -293.221918)
		(width 0.1143)
		(layer "In13.Cu")
		(net "P5E_CPU1_P2_TX_DP<1>")
	)
	(segment
		(start 113.671858 -275.383752)
		(end 113.702338 -275.401532)
		(width 0.1143)
		(layer "In13.Cu")
		(net "P5E_CPU1_P2_TX_DP<1>")
	)
	(segment
		(start 113.674398 -293.205154)
		(end 113.67516 -293.205662)
		(width 0.1143)
		(layer "In13.Cu")
		(net "P5E_CPU1_P2_TX_DP<1>")
	)
	(segment
		(start 113.671858 -280.888948)
		(end 113.668048 -280.891234)
		(width 0.1143)
		(layer "In13.Cu")
		(net "P5E_CPU1_P2_TX_DP<1>")
	)
	(segment
		(start 113.632742 -276.980904)
		(end 113.671858 -277.003764)
		(width 0.1143)
		(layer "In13.Cu")
		(net "P5E_CPU1_P2_TX_DP<1>")
	)
	(segment
		(start 113.674398 -292.227254)
		(end 113.673382 -292.227762)
		(width 0.1143)
		(layer "In13.Cu")
		(net "P5E_CPU1_P2_TX_DP<1>")
	)
	(segment
		(start 113.67516 -292.226746)
		(end 113.674398 -292.227254)
		(width 0.1143)
		(layer "In13.Cu")
		(net "P5E_CPU1_P2_TX_DP<1>")
	)
	(segment
		(start 113.702338 -287.350962)
		(end 113.63833 -287.3883)
		(width 0.1143)
		(layer "In13.Cu")
		(net "P5E_CPU1_P2_TX_DP<1>")
	)
	(segment
		(start 113.671858 -274.4089)
		(end 113.632742 -274.43176)
		(width 0.1143)
		(layer "In13.Cu")
		(net "P5E_CPU1_P2_TX_DP<1>")
	)
	(segment
		(start 113.702338 -290.590986)
		(end 113.671858 -290.608766)
		(width 0.1143)
		(layer "In13.Cu")
		(net "P5E_CPU1_P2_TX_DP<1>")
	)
	(segment
		(start 126.599442 -317.208408)
		(end 127.30353 -318.262)
		(width 0.14224)
		(layer "In13.Cu")
		(net "P5E_CPU1_P2_TX_DP<1>")
	)
	(segment
		(start 113.702338 -279.251156)
		(end 113.62944 -279.293574)
		(width 0.1143)
		(layer "In13.Cu")
		(net "P5E_CPU1_P2_TX_DP<1>")
	)
	(segment
		(start 140.88999 -368.44732)
		(end 141.02715 -368.58448)
		(width 0.14224)
		(layer "In13.Cu")
		(net "P5E_CPU1_P2_TX_DP<1>")
	)
	(segment
		(start 114.424714 -270.846296)
		(end 114.722656 -270.846296)
		(width 0.1143)
		(layer "In13.Cu")
		(net "P5E_CPU1_P2_TX_DP<1>")
	)
	(segment
		(start 136.395206 -352.008948)
		(end 141.02715 -367.277142)
		(width 0.14224)
		(layer "In13.Cu")
		(net "P5E_CPU1_P2_TX_DP<1>")
	)
	(segment
		(start 113.702338 -282.49118)
		(end 113.672874 -282.508452)
		(width 0.1143)
		(layer "In13.Cu")
		(net "P5E_CPU1_P2_TX_DP<1>")
	)
	(segment
		(start 114.283744 -298.470066)
		(end 115.89639 -302.363886)
		(width 0.14224)
		(layer "In13.Cu")
		(net "P5E_CPU1_P2_TX_DP<1>")
	)
	(segment
		(start 113.671858 -284.128972)
		(end 113.671604 -284.129226)
		(width 0.1143)
		(layer "In13.Cu")
		(net "P5E_CPU1_P2_TX_DP<1>")
	)
	(segment
		(start 114.61242 -271.168368)
		(end 114.611658 -271.168876)
		(width 0.1143)
		(layer "In13.Cu")
		(net "P5E_CPU1_P2_TX_DP<1>")
	)
	(segment
		(start 113.671858 -293.84879)
		(end 113.635536 -293.869872)
		(width 0.1143)
		(layer "In13.Cu")
		(net "P5E_CPU1_P2_TX_DP<1>")
	)
	(segment
		(start 113.671858 -277.003764)
		(end 113.702338 -277.021544)
		(width 0.1143)
		(layer "In13.Cu")
		(net "P5E_CPU1_P2_TX_DP<1>")
	)
	(segment
		(start 141.02715 -369.0112)
		(end 140.88999 -369.14836)
		(width 0.14224)
		(layer "In13.Cu")
		(net "P5E_CPU1_P2_TX_DP<1>")
	)
	(segment
		(start 113.703354 -292.21049)
		(end 113.67516 -292.226746)
		(width 0.1143)
		(layer "In13.Cu")
		(net "P5E_CPU1_P2_TX_DP<1>")
	)
	(segment
		(start 113.632742 -278.600916)
		(end 113.671858 -278.623776)
		(width 0.1143)
		(layer "In13.Cu")
		(net "P5E_CPU1_P2_TX_DP<1>")
	)
	(segment
		(start 114.329464 -295.956228)
		(end 114.329464 -296.2529)
		(width 0.1143)
		(layer "In13.Cu")
		(net "P5E_CPU1_P2_TX_DP<1>")
	)
	(segment
		(start 114.135662 -271.982438)
		(end 114.134138 -271.983454)
		(width 0.1143)
		(layer "In13.Cu")
		(net "P5E_CPU1_P2_TX_DP<1>")
	)
	(segment
		(start 113.673382 -288.987992)
		(end 113.672366 -288.9885)
		(width 0.1143)
		(layer "In13.Cu")
		(net "P5E_CPU1_P2_TX_DP<1>")
	)
	(segment
		(start 114.173508 -271.960594)
		(end 114.14252 -271.978374)
		(width 0.1143)
		(layer "In13.Cu")
		(net "P5E_CPU1_P2_TX_DP<1>")
	)
	(segment
		(start 113.702338 -277.631144)
		(end 113.671858 -277.648924)
		(width 0.1143)
		(layer "In13.Cu")
		(net "P5E_CPU1_P2_TX_DP<1>")
	)
	(segment
		(start 113.619534 -280.211784)
		(end 113.62944 -280.21915)
		(width 0.1143)
		(layer "In13.Cu")
		(net "P5E_CPU1_P2_TX_DP<1>")
	)
	(segment
		(start 141.02715 -367.277142)
		(end 141.02715 -367.88344)
		(width 0.14224)
		(layer "In13.Cu")
		(net "P5E_CPU1_P2_TX_DP<1>")
	)
	(segment
		(start 141.616176 -373.62765)
		(end 141.779498 -374.022112)
		(width 0.14224)
		(layer "In13.Cu")
		(net "P5E_CPU1_P2_TX_DP<1>")
	)
	(segment
		(start 113.635536 -294.80256)
		(end 113.671858 -294.823642)
		(width 0.1143)
		(layer "In13.Cu")
		(net "P5E_CPU1_P2_TX_DP<1>")
	)
	(segment
		(start 113.67262 -292.22827)
		(end 113.669572 -292.229794)
		(width 0.1143)
		(layer "In13.Cu")
		(net "P5E_CPU1_P2_TX_DP<1>")
	)
	(segment
		(start 117.192552 -304.526188)
		(end 126.599442 -317.208408)
		(width 0.14224)
		(layer "In13.Cu")
		(net "P5E_CPU1_P2_TX_DP<1>")
	)
	(segment
		(start 113.67135 -288.34334)
		(end 113.67643 -288.346388)
		(width 0.1143)
		(layer "In13.Cu")
		(net "P5E_CPU1_P2_TX_DP<1>")
	)
	(segment
		(start 113.671858 -278.623776)
		(end 113.702338 -278.641556)
		(width 0.1143)
		(layer "In13.Cu")
		(net "P5E_CPU1_P2_TX_DP<1>")
	)
	(segment
		(start 113.389664 -286.23641)
		(end 113.389664 -286.239204)
		(width 0.1143)
		(layer "In13.Cu")
		(net "P5E_CPU1_P2_TX_DP<1>")
	)
	(segment
		(start 113.63325 -286.70123)
		(end 113.70437 -286.742632)
		(width 0.1143)
		(layer "In13.Cu")
		(net "P5E_CPU1_P2_TX_DP<1>")
	)
	(segment
		(start 115.89639 -302.363886)
		(end 117.192552 -304.526188)
		(width 0.14224)
		(layer "In13.Cu")
		(net "P5E_CPU1_P2_TX_DP<1>")
	)
	(segment
		(start 113.67262 -281.864308)
		(end 113.702338 -281.88158)
		(width 0.1143)
		(layer "In13.Cu")
		(net "P5E_CPU1_P2_TX_DP<1>")
	)
	(segment
		(start 113.632742 -275.360892)
		(end 113.671858 -275.383752)
		(width 0.1143)
		(layer "In13.Cu")
		(net "P5E_CPU1_P2_TX_DP<1>")
	)
	(segment
		(start 113.62944 -279.293574)
		(end 113.619534 -279.30094)
		(width 0.1143)
		(layer "In13.Cu")
		(net "P5E_CPU1_P2_TX_DP<1>")
	)
	(segment
		(start 113.671858 -290.608766)
		(end 113.635536 -290.629848)
		(width 0.1143)
		(layer "In13.Cu")
		(net "P5E_CPU1_P2_TX_DP<1>")
	)
	(segment
		(start 113.671858 -277.648924)
		(end 113.632742 -277.671784)
		(width 0.1143)
		(layer "In13.Cu")
		(net "P5E_CPU1_P2_TX_DP<1>")
	)
	(segment
		(start 113.62944 -280.21915)
		(end 113.702338 -280.261822)
		(width 0.1143)
		(layer "In13.Cu")
		(net "P5E_CPU1_P2_TX_DP<1>")
	)
	(segment
		(start 113.38941 -286.23641)
		(end 113.389664 -286.23641)
		(width 0.1143)
		(layer "In13.Cu")
		(net "P5E_CPU1_P2_TX_DP<1>")
	)
	(segment
		(start 141.02715 -369.71224)
		(end 141.02715 -370.13896)
		(width 0.14224)
		(layer "In13.Cu")
		(net "P5E_CPU1_P2_TX_DP<1>")
	)
	(segment
		(start 113.702338 -285.731204)
		(end 113.632742 -285.771844)
		(width 0.1143)
		(layer "In13.Cu")
		(net "P5E_CPU1_P2_TX_DP<1>")
	)
	(arc
		(start 114.552476 -271.206722)
		(mid 114.39818 -271.401011)
		(end 114.329972 -271.639538)
		(width 0.1143)
		(layer "In13.Cu")
		(net "P5E_CPU1_P2_TX_DP<1>")
	)
	(arc
		(start 113.668048 -282.511246)
		(mid 113.389629 -282.996386)
		(end 113.668048 -283.481526)
		(width 0.1143)
		(layer "In13.Cu")
		(net "P5E_CPU1_P2_TX_DP<1>")
	)
	(arc
		(start 113.634266 -289.010598)
		(mid 113.389446 -289.476919)
		(end 113.635536 -289.942524)
		(width 0.1143)
		(layer "In13.Cu")
		(net "P5E_CPU1_P2_TX_DP<1>")
	)
	(arc
		(start 113.702338 -285.121604)
		(mid 113.859315 -285.426404)
		(end 113.702338 -285.731204)
		(width 0.1143)
		(layer "In13.Cu")
		(net "P5E_CPU1_P2_TX_DP<1>")
	)
	(arc
		(start 113.389664 -287.856422)
		(mid 113.4549 -288.120013)
		(end 113.635536 -288.322766)
		(width 0.1143)
		(layer "In13.Cu")
		(net "P5E_CPU1_P2_TX_DP<1>")
	)
	(arc
		(start 113.702338 -278.641556)
		(mid 113.859315 -278.946356)
		(end 113.702338 -279.251156)
		(width 0.1143)
		(layer "In13.Cu")
		(net "P5E_CPU1_P2_TX_DP<1>")
	)
	(arc
		(start 113.85931 -291.906198)
		(mid 113.818055 -292.077169)
		(end 113.703354 -292.21049)
		(width 0.1143)
		(layer "In13.Cu")
		(net "P5E_CPU1_P2_TX_DP<1>")
	)
	(arc
		(start 113.702338 -291.601398)
		(mid 113.817765 -291.734774)
		(end 113.85931 -291.906198)
		(width 0.1143)
		(layer "In13.Cu")
		(net "P5E_CPU1_P2_TX_DP<1>")
	)
	(arc
		(start 113.632742 -277.671784)
		(mid 113.389415 -278.13635)
		(end 113.632742 -278.600916)
		(width 0.1143)
		(layer "In13.Cu")
		(net "P5E_CPU1_P2_TX_DP<1>")
	)
	(arc
		(start 114.792506 -270.916146)
		(mid 114.740457 -271.047665)
		(end 114.643408 -271.150588)
		(width 0.1143)
		(layer "In13.Cu")
		(net "P5E_CPU1_P2_TX_DP<1>")
	)
	(arc
		(start 113.67643 -288.346388)
		(mid 113.860115 -288.660533)
		(end 113.686082 -288.980118)
		(width 0.1143)
		(layer "In13.Cu")
		(net "P5E_CPU1_P2_TX_DP<1>")
	)
	(arc
		(start 113.389664 -286.239204)
		(mid 113.454282 -286.500366)
		(end 113.63325 -286.70123)
		(width 0.1143)
		(layer "In13.Cu")
		(net "P5E_CPU1_P2_TX_DP<1>")
	)
	(arc
		(start 113.668048 -280.891234)
		(mid 113.389629 -281.376374)
		(end 113.668048 -281.861514)
		(width 0.1143)
		(layer "In13.Cu")
		(net "P5E_CPU1_P2_TX_DP<1>")
	)
	(arc
		(start 114.575336 -271.189958)
		(mid 114.563801 -271.198197)
		(end 114.552476 -271.206722)
		(width 0.1143)
		(layer "In13.Cu")
		(net "P5E_CPU1_P2_TX_DP<1>")
	)
	(arc
		(start 113.85931 -287.046162)
		(mid 113.817761 -287.217584)
		(end 113.702338 -287.350962)
		(width 0.1143)
		(layer "In13.Cu")
		(net "P5E_CPU1_P2_TX_DP<1>")
	)
	(arc
		(start 114.329972 -271.639538)
		(mid 114.329398 -271.648165)
		(end 114.32921 -271.65681)
		(width 0.1143)
		(layer "In13.Cu")
		(net "P5E_CPU1_P2_TX_DP<1>")
	)
	(arc
		(start 113.63833 -287.3883)
		(mid 113.455668 -287.591381)
		(end 113.389664 -287.856422)
		(width 0.1143)
		(layer "In13.Cu")
		(net "P5E_CPU1_P2_TX_DP<1>")
	)
	(arc
		(start 114.102642 -272.001742)
		(mid 113.923829 -272.204092)
		(end 113.85931 -272.466308)
		(width 0.1143)
		(layer "In13.Cu")
		(net "P5E_CPU1_P2_TX_DP<1>")
	)
	(arc
		(start 113.702338 -283.501592)
		(mid 113.859315 -283.806392)
		(end 113.702338 -284.111192)
		(width 0.1143)
		(layer "In13.Cu")
		(net "P5E_CPU1_P2_TX_DP<1>")
	)
	(arc
		(start 142.295626 -376.1613)
		(mid 142.204433 -376.204739)
		(end 142.109698 -376.239786)
		(width 0.14224)
		(layer "In13.Cu")
		(net "P5E_CPU1_P2_TX_DP<1>")
	)
	(arc
		(start 113.632742 -285.771844)
		(mid 113.453929 -285.974194)
		(end 113.38941 -286.23641)
		(width 0.1143)
		(layer "In13.Cu")
		(net "P5E_CPU1_P2_TX_DP<1>")
	)
	(arc
		(start 113.632742 -272.811748)
		(mid 113.389415 -273.276314)
		(end 113.632742 -273.74088)
		(width 0.1143)
		(layer "In13.Cu")
		(net "P5E_CPU1_P2_TX_DP<1>")
	)
	(arc
		(start 142.362428 -376.049286)
		(mid 142.344583 -376.114573)
		(end 142.295626 -376.1613)
		(width 0.14224)
		(layer "In13.Cu")
		(net "P5E_CPU1_P2_TX_DP<1>")
	)
	(arc
		(start 142.173452 -374.614694)
		(mid 142.314704 -375.080112)
		(end 142.362428 -375.564146)
		(width 0.14224)
		(layer "In13.Cu")
		(net "P5E_CPU1_P2_TX_DP<1>")
	)
	(arc
		(start 142.109698 -376.239786)
		(mid 142.047836 -376.254287)
		(end 141.984476 -376.25909)
		(width 0.14224)
		(layer "In13.Cu")
		(net "P5E_CPU1_P2_TX_DP<1>")
	)
	(arc
		(start 113.619534 -279.30094)
		(mid 113.387935 -279.756362)
		(end 113.619534 -280.211784)
		(width 0.1143)
		(layer "In13.Cu")
		(net "P5E_CPU1_P2_TX_DP<1>")
	)
	(arc
		(start 114.172238 -295.651428)
		(mid 114.18726 -295.662746)
		(end 114.201702 -295.674796)
		(width 0.1143)
		(layer "In13.Cu")
		(net "P5E_CPU1_P2_TX_DP<1>")
	)
	(arc
		(start 113.669572 -292.229794)
		(mid 113.389551 -292.716204)
		(end 113.669572 -293.202614)
		(width 0.1143)
		(layer "In13.Cu")
		(net "P5E_CPU1_P2_TX_DP<1>")
	)
	(arc
		(start 113.635536 -290.629848)
		(mid 113.389646 -291.096192)
		(end 113.635536 -291.562536)
		(width 0.1143)
		(layer "In13.Cu")
		(net "P5E_CPU1_P2_TX_DP<1>")
	)
	(arc
		(start 113.702338 -273.78152)
		(mid 113.859315 -274.08632)
		(end 113.702338 -274.39112)
		(width 0.1143)
		(layer "In13.Cu")
		(net "P5E_CPU1_P2_TX_DP<1>")
	)
	(arc
		(start 113.85931 -295.146222)
		(mid 113.923825 -295.408441)
		(end 114.102642 -295.610788)
		(width 0.1143)
		(layer "In13.Cu")
		(net "P5E_CPU1_P2_TX_DP<1>")
	)
	(arc
		(start 114.201702 -295.674796)
		(mid 114.295981 -295.801713)
		(end 114.329464 -295.956228)
		(width 0.1143)
		(layer "In13.Cu")
		(net "P5E_CPU1_P2_TX_DP<1>")
	)
	(arc
		(start 113.702338 -280.261568)
		(mid 113.859315 -280.566368)
		(end 113.702338 -280.871168)
		(width 0.1143)
		(layer "In13.Cu")
		(net "P5E_CPU1_P2_TX_DP<1>")
	)
	(arc
		(start 113.632742 -276.051772)
		(mid 113.389415 -276.516338)
		(end 113.632742 -276.980904)
		(width 0.1143)
		(layer "In13.Cu")
		(net "P5E_CPU1_P2_TX_DP<1>")
	)
	(arc
		(start 113.70437 -286.742632)
		(mid 113.818299 -286.875779)
		(end 113.85931 -287.046162)
		(width 0.1143)
		(layer "In13.Cu")
		(net "P5E_CPU1_P2_TX_DP<1>")
	)
	(arc
		(start 113.702338 -281.88158)
		(mid 113.859315 -282.18638)
		(end 113.702338 -282.49118)
		(width 0.1143)
		(layer "In13.Cu")
		(net "P5E_CPU1_P2_TX_DP<1>")
	)
	(arc
		(start 113.85931 -293.52621)
		(mid 113.817761 -293.697632)
		(end 113.702338 -293.83101)
		(width 0.1143)
		(layer "In13.Cu")
		(net "P5E_CPU1_P2_TX_DP<1>")
	)
	(arc
		(start 113.632742 -274.43176)
		(mid 113.389415 -274.896326)
		(end 113.632742 -275.360892)
		(width 0.1143)
		(layer "In13.Cu")
		(net "P5E_CPU1_P2_TX_DP<1>")
	)
	(arc
		(start 113.702338 -289.981386)
		(mid 113.859315 -290.286186)
		(end 113.702338 -290.590986)
		(width 0.1143)
		(layer "In13.Cu")
		(net "P5E_CPU1_P2_TX_DP<1>")
	)
	(arc
		(start 113.702338 -277.021544)
		(mid 113.859315 -277.326344)
		(end 113.702338 -277.631144)
		(width 0.1143)
		(layer "In13.Cu")
		(net "P5E_CPU1_P2_TX_DP<1>")
	)
	(arc
		(start 113.85931 -272.466308)
		(mid 113.817761 -272.63773)
		(end 113.702338 -272.771108)
		(width 0.1143)
		(layer "In13.Cu")
		(net "P5E_CPU1_P2_TX_DP<1>")
	)
	(arc
		(start 113.703354 -293.221918)
		(mid 113.81803 -293.355252)
		(end 113.85931 -293.52621)
		(width 0.1143)
		(layer "In13.Cu")
		(net "P5E_CPU1_P2_TX_DP<1>")
	)
	(arc
		(start 113.671604 -284.129226)
		(mid 113.39184 -284.616588)
		(end 113.671604 -285.103824)
		(width 0.1143)
		(layer "In13.Cu")
		(net "P5E_CPU1_P2_TX_DP<1>")
	)
	(arc
		(start 113.702338 -275.401532)
		(mid 113.859315 -275.706332)
		(end 113.702338 -276.011132)
		(width 0.1143)
		(layer "In13.Cu")
		(net "P5E_CPU1_P2_TX_DP<1>")
	)
	(arc
		(start 114.32921 -271.65681)
		(mid 114.285065 -271.825961)
		(end 114.173508 -271.960594)
		(width 0.1143)
		(layer "In13.Cu")
		(net "P5E_CPU1_P2_TX_DP<1>")
	)
	(arc
		(start 113.635536 -293.869872)
		(mid 113.389646 -294.336216)
		(end 113.635536 -294.80256)
		(width 0.1143)
		(layer "In13.Cu")
		(net "P5E_CPU1_P2_TX_DP<1>")
	)
	(arc
		(start 141.02715 -371.26672)
		(mid 141.083104 -371.835418)
		(end 141.248892 -372.382288)
		(width 0.14224)
		(layer "In13.Cu")
		(net "P5E_CPU1_P2_TX_DP<1>")
	)
	(arc
		(start 113.702338 -294.841422)
		(mid 113.817765 -294.974798)
		(end 113.85931 -295.146222)
		(width 0.1143)
		(layer "In13.Cu")
		(net "P5E_CPU1_P2_TX_DP<1>")
	)
	(segment
		(start 124.767848 -271.390364)
		(end 125.2347 -271.656302)
		(width 0.12954)
		(layer "F.Cu")
		(net "P5E_CPU1_P2_TX_DP<15>")
	)
	(segment
		(start 170.634914 -379.767338)
		(end 169.931334 -379.767338)
		(width 0.12954)
		(layer "F.Cu")
		(net "P5E_CPU1_P2_TX_DP<15>")
	)
	(segment
		(start 169.931334 -379.767338)
		(end 169.635424 -379.471428)
		(width 0.12954)
		(layer "F.Cu")
		(net "P5E_CPU1_P2_TX_DP<15>")
	)
	(segment
		(start 170.905424 -379.496828)
		(end 170.634914 -379.767338)
		(width 0.12954)
		(layer "F.Cu")
		(net "P5E_CPU1_P2_TX_DP<15>")
	)
	(segment
		(start 165.03396 -363.85627)
		(end 165.213284 -363.782102)
		(width 0.14224)
		(layer "In13.Cu")
		(net "P5E_CPU1_P2_TX_DP<15>")
	)
	(segment
		(start 126.862332 -290.590986)
		(end 126.831852 -290.608766)
		(width 0.1143)
		(layer "In13.Cu")
		(net "P5E_CPU1_P2_TX_DP<15>")
	)
	(segment
		(start 126.831852 -283.483812)
		(end 126.862332 -283.501592)
		(width 0.1143)
		(layer "In13.Cu")
		(net "P5E_CPU1_P2_TX_DP<15>")
	)
	(segment
		(start 172.872908 -378.684536)
		(end 172.653452 -379.21438)
		(width 0.14224)
		(layer "In13.Cu")
		(net "P5E_CPU1_P2_TX_DP<15>")
	)
	(segment
		(start 154.359356 -357.094028)
		(end 157.454346 -360.509058)
		(width 0.14224)
		(layer "In13.Cu")
		(net "P5E_CPU1_P2_TX_DP<15>")
	)
	(segment
		(start 126.831852 -276.028912)
		(end 126.792736 -276.051772)
		(width 0.1143)
		(layer "In13.Cu")
		(net "P5E_CPU1_P2_TX_DP<15>")
	)
	(segment
		(start 126.792736 -294.800782)
		(end 126.831852 -294.823642)
		(width 0.1143)
		(layer "In13.Cu")
		(net "P5E_CPU1_P2_TX_DP<15>")
	)
	(segment
		(start 126.792736 -275.360892)
		(end 126.831852 -275.383752)
		(width 0.1143)
		(layer "In13.Cu")
		(net "P5E_CPU1_P2_TX_DP<15>")
	)
	(segment
		(start 166.348918 -364.4011)
		(end 166.527988 -364.326932)
		(width 0.14224)
		(layer "In13.Cu")
		(net "P5E_CPU1_P2_TX_DP<15>")
	)
	(segment
		(start 126.361698 -272.953734)
		(end 126.393448 -272.972022)
		(width 0.1143)
		(layer "In13.Cu")
		(net "P5E_CPU1_P2_TX_DP<15>")
	)
	(segment
		(start 126.862332 -276.011132)
		(end 126.831852 -276.028912)
		(width 0.1143)
		(layer "In13.Cu")
		(net "P5E_CPU1_P2_TX_DP<15>")
	)
	(segment
		(start 126.831852 -293.20363)
		(end 126.862332 -293.22141)
		(width 0.1143)
		(layer "In13.Cu")
		(net "P5E_CPU1_P2_TX_DP<15>")
	)
	(segment
		(start 163.44011 -363.196124)
		(end 163.834572 -363.359446)
		(width 0.14224)
		(layer "In13.Cu")
		(net "P5E_CPU1_P2_TX_DP<15>")
	)
	(segment
		(start 127.301752 -295.633648)
		(end 127.333502 -295.651936)
		(width 0.1143)
		(layer "In13.Cu")
		(net "P5E_CPU1_P2_TX_DP<15>")
	)
	(segment
		(start 127.977392 -296.696638)
		(end 127.997458 -296.716704)
		(width 0.1143)
		(layer "In13.Cu")
		(net "P5E_CPU1_P2_TX_DP<15>")
	)
	(segment
		(start 172.480732 -370.206778)
		(end 172.952918 -371.347746)
		(width 0.14224)
		(layer "In13.Cu")
		(net "P5E_CPU1_P2_TX_DP<15>")
	)
	(segment
		(start 126.862332 -293.83101)
		(end 126.831852 -293.84879)
		(width 0.1143)
		(layer "In13.Cu")
		(net "P5E_CPU1_P2_TX_DP<15>")
	)
	(segment
		(start 126.792736 -276.980904)
		(end 126.831852 -277.003764)
		(width 0.1143)
		(layer "In13.Cu")
		(net "P5E_CPU1_P2_TX_DP<15>")
	)
	(segment
		(start 126.831852 -280.888948)
		(end 126.792736 -280.911808)
		(width 0.1143)
		(layer "In13.Cu")
		(net "P5E_CPU1_P2_TX_DP<15>")
	)
	(segment
		(start 170.591226 -367.35639)
		(end 172.421042 -370.095272)
		(width 0.14224)
		(layer "In13.Cu")
		(net "P5E_CPU1_P2_TX_DP<15>")
	)
	(segment
		(start 163.834572 -363.359446)
		(end 164.013896 -363.285278)
		(width 0.14224)
		(layer "In13.Cu")
		(net "P5E_CPU1_P2_TX_DP<15>")
	)
	(segment
		(start 126.792736 -286.700976)
		(end 126.831852 -286.723836)
		(width 0.1143)
		(layer "In13.Cu")
		(net "P5E_CPU1_P2_TX_DP<15>")
	)
	(segment
		(start 153.872946 -356.4001)
		(end 154.281124 -356.994968)
		(width 0.14224)
		(layer "In13.Cu")
		(net "P5E_CPU1_P2_TX_DP<15>")
	)
	(segment
		(start 126.831852 -282.50896)
		(end 126.792736 -282.53182)
		(width 0.1143)
		(layer "In13.Cu")
		(net "P5E_CPU1_P2_TX_DP<15>")
	)
	(segment
		(start 126.831852 -292.228778)
		(end 126.792736 -292.251638)
		(width 0.1143)
		(layer "In13.Cu")
		(net "P5E_CPU1_P2_TX_DP<15>")
	)
	(segment
		(start 126.862332 -274.39112)
		(end 126.831852 -274.4089)
		(width 0.1143)
		(layer "In13.Cu")
		(net "P5E_CPU1_P2_TX_DP<15>")
	)
	(segment
		(start 126.862332 -280.871168)
		(end 126.831852 -280.888948)
		(width 0.1143)
		(layer "In13.Cu")
		(net "P5E_CPU1_P2_TX_DP<15>")
	)
	(segment
		(start 162.699446 -362.889292)
		(end 162.87877 -362.815124)
		(width 0.14224)
		(layer "In13.Cu")
		(net "P5E_CPU1_P2_TX_DP<15>")
	)
	(segment
		(start 143.322294 -320.013838)
		(end 144.132046 -321.968368)
		(width 0.14224)
		(layer "In13.Cu")
		(net "P5E_CPU1_P2_TX_DP<15>")
	)
	(segment
		(start 126.831852 -280.243788)
		(end 126.862332 -280.261568)
		(width 0.1143)
		(layer "In13.Cu")
		(net "P5E_CPU1_P2_TX_DP<15>")
	)
	(segment
		(start 162.87877 -362.815124)
		(end 163.365942 -363.0168)
		(width 0.14224)
		(layer "In13.Cu")
		(net "P5E_CPU1_P2_TX_DP<15>")
	)
	(segment
		(start 172.735748 -377.648978)
		(end 172.735748 -378.075698)
		(width 0.14224)
		(layer "In13.Cu")
		(net "P5E_CPU1_P2_TX_DP<15>")
	)
	(segment
		(start 169.578782 -366.263936)
		(end 170.200574 -366.885728)
		(width 0.14224)
		(layer "In13.Cu")
		(net "P5E_CPU1_P2_TX_DP<15>")
	)
	(segment
		(start 165.213284 -363.782102)
		(end 165.880034 -364.0582)
		(width 0.14224)
		(layer "In13.Cu")
		(net "P5E_CPU1_P2_TX_DP<15>")
	)
	(segment
		(start 172.977556 -371.47119)
		(end 172.977556 -372.65737)
		(width 0.14224)
		(layer "In13.Cu")
		(net "P5E_CPU1_P2_TX_DP<15>")
	)
	(segment
		(start 126.831852 -277.003764)
		(end 126.862332 -277.021544)
		(width 0.1143)
		(layer "In13.Cu")
		(net "P5E_CPU1_P2_TX_DP<15>")
	)
	(segment
		(start 172.872908 -378.212858)
		(end 172.872908 -378.684536)
		(width 0.14224)
		(layer "In13.Cu")
		(net "P5E_CPU1_P2_TX_DP<15>")
	)
	(segment
		(start 163.365942 -363.0168)
		(end 163.44011 -363.196124)
		(width 0.14224)
		(layer "In13.Cu")
		(net "P5E_CPU1_P2_TX_DP<15>")
	)
	(segment
		(start 172.872908 -373.235728)
		(end 172.872908 -377.511818)
		(width 0.14224)
		(layer "In13.Cu")
		(net "P5E_CPU1_P2_TX_DP<15>")
	)
	(segment
		(start 126.831852 -288.343848)
		(end 126.864364 -288.362644)
		(width 0.1143)
		(layer "In13.Cu")
		(net "P5E_CPU1_P2_TX_DP<15>")
	)
	(segment
		(start 126.862332 -282.49118)
		(end 126.831852 -282.50896)
		(width 0.1143)
		(layer "In13.Cu")
		(net "P5E_CPU1_P2_TX_DP<15>")
	)
	(segment
		(start 134.87019 -305.696874)
		(end 138.866372 -311.67705)
		(width 0.14224)
		(layer "In13.Cu")
		(net "P5E_CPU1_P2_TX_DP<15>")
	)
	(segment
		(start 126.792736 -273.74088)
		(end 126.831852 -273.76374)
		(width 0.1143)
		(layer "In13.Cu")
		(net "P5E_CPU1_P2_TX_DP<15>")
	)
	(segment
		(start 126.862332 -285.731204)
		(end 126.831852 -285.748984)
		(width 0.1143)
		(layer "In13.Cu")
		(net "P5E_CPU1_P2_TX_DP<15>")
	)
	(segment
		(start 126.831852 -286.723836)
		(end 126.864364 -286.742632)
		(width 0.1143)
		(layer "In13.Cu")
		(net "P5E_CPU1_P2_TX_DP<15>")
	)
	(segment
		(start 126.831852 -277.648924)
		(end 126.792736 -277.671784)
		(width 0.1143)
		(layer "In13.Cu")
		(net "P5E_CPU1_P2_TX_DP<15>")
	)
	(segment
		(start 127.997458 -296.716704)
		(end 128.208786 -296.928032)
		(width 0.14224)
		(layer "In13.Cu")
		(net "P5E_CPU1_P2_TX_DP<15>")
	)
	(segment
		(start 126.792736 -291.560758)
		(end 126.831852 -291.583618)
		(width 0.1143)
		(layer "In13.Cu")
		(net "P5E_CPU1_P2_TX_DP<15>")
	)
	(segment
		(start 166.527988 -364.326932)
		(end 166.922196 -364.49)
		(width 0.14224)
		(layer "In13.Cu")
		(net "P5E_CPU1_P2_TX_DP<15>")
	)
	(segment
		(start 126.862332 -287.350962)
		(end 126.795276 -287.390078)
		(width 0.1143)
		(layer "In13.Cu")
		(net "P5E_CPU1_P2_TX_DP<15>")
	)
	(segment
		(start 126.792736 -288.320988)
		(end 126.831852 -288.343848)
		(width 0.1143)
		(layer "In13.Cu")
		(net "P5E_CPU1_P2_TX_DP<15>")
	)
	(segment
		(start 127.977392 -296.631614)
		(end 127.977392 -296.696638)
		(width 0.1143)
		(layer "In13.Cu")
		(net "P5E_CPU1_P2_TX_DP<15>")
	)
	(segment
		(start 149.090634 -346.898722)
		(end 153.872946 -356.4001)
		(width 0.14224)
		(layer "In13.Cu")
		(net "P5E_CPU1_P2_TX_DP<15>")
	)
	(segment
		(start 126.831852 -273.76374)
		(end 126.862332 -273.78152)
		(width 0.1143)
		(layer "In13.Cu")
		(net "P5E_CPU1_P2_TX_DP<15>")
	)
	(segment
		(start 126.792736 -293.18077)
		(end 126.831852 -293.20363)
		(width 0.1143)
		(layer "In13.Cu")
		(net "P5E_CPU1_P2_TX_DP<15>")
	)
	(segment
		(start 126.831852 -291.583618)
		(end 126.862332 -291.601398)
		(width 0.1143)
		(layer "In13.Cu")
		(net "P5E_CPU1_P2_TX_DP<15>")
	)
	(segment
		(start 126.831852 -293.84879)
		(end 126.792736 -293.87165)
		(width 0.1143)
		(layer "In13.Cu")
		(net "P5E_CPU1_P2_TX_DP<15>")
	)
	(segment
		(start 144.132046 -321.968368)
		(end 149.090634 -346.898722)
		(width 0.14224)
		(layer "In13.Cu")
		(net "P5E_CPU1_P2_TX_DP<15>")
	)
	(segment
		(start 126.831852 -290.608766)
		(end 126.792736 -290.631626)
		(width 0.1143)
		(layer "In13.Cu")
		(net "P5E_CPU1_P2_TX_DP<15>")
	)
	(segment
		(start 126.831852 -281.8638)
		(end 126.862332 -281.88158)
		(width 0.1143)
		(layer "In13.Cu")
		(net "P5E_CPU1_P2_TX_DP<15>")
	)
	(segment
		(start 172.872908 -377.511818)
		(end 172.735748 -377.648978)
		(width 0.14224)
		(layer "In13.Cu")
		(net "P5E_CPU1_P2_TX_DP<15>")
	)
	(segment
		(start 162.230816 -362.546646)
		(end 162.304984 -362.72597)
		(width 0.14224)
		(layer "In13.Cu")
		(net "P5E_CPU1_P2_TX_DP<15>")
	)
	(segment
		(start 127.848106 -296.502328)
		(end 127.977392 -296.631614)
		(width 0.1143)
		(layer "In13.Cu")
		(net "P5E_CPU1_P2_TX_DP<15>")
	)
	(segment
		(start 138.866372 -311.67705)
		(end 143.322294 -320.013838)
		(width 0.14224)
		(layer "In13.Cu")
		(net "P5E_CPU1_P2_TX_DP<15>")
	)
	(segment
		(start 157.658054 -360.652568)
		(end 162.230816 -362.546646)
		(width 0.14224)
		(layer "In13.Cu")
		(net "P5E_CPU1_P2_TX_DP<15>")
	)
	(segment
		(start 162.304984 -362.72597)
		(end 162.699446 -362.889292)
		(width 0.14224)
		(layer "In13.Cu")
		(net "P5E_CPU1_P2_TX_DP<15>")
	)
	(segment
		(start 126.862332 -284.111192)
		(end 126.831852 -284.128972)
		(width 0.1143)
		(layer "In13.Cu")
		(net "P5E_CPU1_P2_TX_DP<15>")
	)
	(segment
		(start 125.2347 -271.656302)
		(end 125.532642 -271.656302)
		(width 0.1143)
		(layer "In13.Cu")
		(net "P5E_CPU1_P2_TX_DP<15>")
	)
	(segment
		(start 126.831852 -285.103824)
		(end 126.862332 -285.121604)
		(width 0.1143)
		(layer "In13.Cu")
		(net "P5E_CPU1_P2_TX_DP<15>")
	)
	(segment
		(start 126.077472 -272.442178)
		(end 126.077472 -272.46326)
		(width 0.1143)
		(layer "In13.Cu")
		(net "P5E_CPU1_P2_TX_DP<15>")
	)
	(segment
		(start 172.32503 -379.542802)
		(end 171.733972 -379.787658)
		(width 0.14224)
		(layer "In13.Cu")
		(net "P5E_CPU1_P2_TX_DP<15>")
	)
	(segment
		(start 128.208786 -296.928032)
		(end 134.87019 -305.696874)
		(width 0.14224)
		(layer "In13.Cu")
		(net "P5E_CPU1_P2_TX_DP<15>")
	)
	(segment
		(start 164.56533 -363.513624)
		(end 164.639498 -363.692948)
		(width 0.14224)
		(layer "In13.Cu")
		(net "P5E_CPU1_P2_TX_DP<15>")
	)
	(segment
		(start 165.880034 -364.0582)
		(end 165.954456 -364.237778)
		(width 0.14224)
		(layer "In13.Cu")
		(net "P5E_CPU1_P2_TX_DP<15>")
	)
	(segment
		(start 126.831852 -285.748984)
		(end 126.792736 -285.771844)
		(width 0.1143)
		(layer "In13.Cu")
		(net "P5E_CPU1_P2_TX_DP<15>")
	)
	(segment
		(start 126.862332 -279.251156)
		(end 126.831852 -279.268936)
		(width 0.1143)
		(layer "In13.Cu")
		(net "P5E_CPU1_P2_TX_DP<15>")
	)
	(segment
		(start 126.792736 -278.600916)
		(end 126.831852 -278.623776)
		(width 0.1143)
		(layer "In13.Cu")
		(net "P5E_CPU1_P2_TX_DP<15>")
	)
	(segment
		(start 127.26543 -295.61282)
		(end 127.301752 -295.633648)
		(width 0.1143)
		(layer "In13.Cu")
		(net "P5E_CPU1_P2_TX_DP<15>")
	)
	(segment
		(start 172.735748 -378.075698)
		(end 172.872908 -378.212858)
		(width 0.14224)
		(layer "In13.Cu")
		(net "P5E_CPU1_P2_TX_DP<15>")
	)
	(segment
		(start 125.852682 -272.120868)
		(end 125.91161 -272.155158)
		(width 0.1143)
		(layer "In13.Cu")
		(net "P5E_CPU1_P2_TX_DP<15>")
	)
	(segment
		(start 126.831852 -284.128972)
		(end 126.792736 -284.151832)
		(width 0.1143)
		(layer "In13.Cu")
		(net "P5E_CPU1_P2_TX_DP<15>")
	)
	(segment
		(start 125.532642 -271.656302)
		(end 125.615446 -271.739106)
		(width 0.1143)
		(layer "In13.Cu")
		(net "P5E_CPU1_P2_TX_DP<15>")
	)
	(segment
		(start 126.831852 -278.623776)
		(end 126.862332 -278.641556)
		(width 0.1143)
		(layer "In13.Cu")
		(net "P5E_CPU1_P2_TX_DP<15>")
	)
	(segment
		(start 126.792736 -289.940746)
		(end 126.831852 -289.963606)
		(width 0.1143)
		(layer "In13.Cu")
		(net "P5E_CPU1_P2_TX_DP<15>")
	)
	(segment
		(start 164.639498 -363.692948)
		(end 165.03396 -363.85627)
		(width 0.14224)
		(layer "In13.Cu")
		(net "P5E_CPU1_P2_TX_DP<15>")
	)
	(segment
		(start 165.954456 -364.237778)
		(end 166.348918 -364.4011)
		(width 0.14224)
		(layer "In13.Cu")
		(net "P5E_CPU1_P2_TX_DP<15>")
	)
	(segment
		(start 126.862332 -292.210998)
		(end 126.831852 -292.228778)
		(width 0.1143)
		(layer "In13.Cu")
		(net "P5E_CPU1_P2_TX_DP<15>")
	)
	(segment
		(start 172.960792 -372.7831)
		(end 172.960538 -372.784116)
		(width 0.14224)
		(layer "In13.Cu")
		(net "P5E_CPU1_P2_TX_DP<15>")
	)
	(segment
		(start 126.792736 -283.460952)
		(end 126.831852 -283.483812)
		(width 0.1143)
		(layer "In13.Cu")
		(net "P5E_CPU1_P2_TX_DP<15>")
	)
	(segment
		(start 126.831852 -275.383752)
		(end 126.862332 -275.401532)
		(width 0.1143)
		(layer "In13.Cu")
		(net "P5E_CPU1_P2_TX_DP<15>")
	)
	(segment
		(start 126.358904 -272.95221)
		(end 126.361698 -272.953734)
		(width 0.1143)
		(layer "In13.Cu")
		(net "P5E_CPU1_P2_TX_DP<15>")
	)
	(segment
		(start 126.792736 -285.080964)
		(end 126.831852 -285.103824)
		(width 0.1143)
		(layer "In13.Cu")
		(net "P5E_CPU1_P2_TX_DP<15>")
	)
	(segment
		(start 127.262636 -295.610788)
		(end 127.26543 -295.61282)
		(width 0.1143)
		(layer "In13.Cu")
		(net "P5E_CPU1_P2_TX_DP<15>")
	)
	(segment
		(start 126.831852 -289.963606)
		(end 126.862332 -289.981386)
		(width 0.1143)
		(layer "In13.Cu")
		(net "P5E_CPU1_P2_TX_DP<15>")
	)
	(segment
		(start 126.862332 -288.970974)
		(end 126.831852 -288.988754)
		(width 0.1143)
		(layer "In13.Cu")
		(net "P5E_CPU1_P2_TX_DP<15>")
	)
	(segment
		(start 126.831852 -279.268936)
		(end 126.792736 -279.291796)
		(width 0.1143)
		(layer "In13.Cu")
		(net "P5E_CPU1_P2_TX_DP<15>")
	)
	(segment
		(start 164.013896 -363.285278)
		(end 164.56533 -363.513624)
		(width 0.14224)
		(layer "In13.Cu")
		(net "P5E_CPU1_P2_TX_DP<15>")
	)
	(segment
		(start 126.792736 -280.220928)
		(end 126.831852 -280.243788)
		(width 0.1143)
		(layer "In13.Cu")
		(net "P5E_CPU1_P2_TX_DP<15>")
	)
	(segment
		(start 126.831852 -274.4089)
		(end 126.792736 -274.43176)
		(width 0.1143)
		(layer "In13.Cu")
		(net "P5E_CPU1_P2_TX_DP<15>")
	)
	(segment
		(start 126.862332 -277.631144)
		(end 126.831852 -277.648924)
		(width 0.1143)
		(layer "In13.Cu")
		(net "P5E_CPU1_P2_TX_DP<15>")
	)
	(segment
		(start 126.831852 -294.823642)
		(end 126.862332 -294.841422)
		(width 0.1143)
		(layer "In13.Cu")
		(net "P5E_CPU1_P2_TX_DP<15>")
	)
	(segment
		(start 171.196254 -379.787658)
		(end 170.905424 -379.496828)
		(width 0.14224)
		(layer "In13.Cu")
		(net "P5E_CPU1_P2_TX_DP<15>")
	)
	(segment
		(start 171.733972 -379.787658)
		(end 171.196254 -379.787658)
		(width 0.14224)
		(layer "In13.Cu")
		(net "P5E_CPU1_P2_TX_DP<15>")
	)
	(segment
		(start 127.73406 -296.42181)
		(end 127.771652 -296.443654)
		(width 0.1143)
		(layer "In13.Cu")
		(net "P5E_CPU1_P2_TX_DP<15>")
	)
	(segment
		(start 126.831852 -288.988754)
		(end 126.792736 -289.011614)
		(width 0.1143)
		(layer "In13.Cu")
		(net "P5E_CPU1_P2_TX_DP<15>")
	)
	(segment
		(start 126.792736 -281.84094)
		(end 126.831852 -281.8638)
		(width 0.1143)
		(layer "In13.Cu")
		(net "P5E_CPU1_P2_TX_DP<15>")
	)
	(arc
		(start 126.792736 -276.051772)
		(mid 126.549409 -276.516338)
		(end 126.792736 -276.980904)
		(width 0.1143)
		(layer "In13.Cu")
		(net "P5E_CPU1_P2_TX_DP<15>")
	)
	(arc
		(start 126.864364 -288.362644)
		(mid 126.978293 -288.495791)
		(end 127.019304 -288.666174)
		(width 0.1143)
		(layer "In13.Cu")
		(net "P5E_CPU1_P2_TX_DP<15>")
	)
	(arc
		(start 126.792736 -285.771844)
		(mid 126.549409 -286.23641)
		(end 126.792736 -286.700976)
		(width 0.1143)
		(layer "In13.Cu")
		(net "P5E_CPU1_P2_TX_DP<15>")
	)
	(arc
		(start 126.792736 -277.671784)
		(mid 126.549409 -278.13635)
		(end 126.792736 -278.600916)
		(width 0.1143)
		(layer "In13.Cu")
		(net "P5E_CPU1_P2_TX_DP<15>")
	)
	(arc
		(start 127.019304 -295.146222)
		(mid 127.083819 -295.408441)
		(end 127.262636 -295.610788)
		(width 0.1143)
		(layer "In13.Cu")
		(net "P5E_CPU1_P2_TX_DP<15>")
	)
	(arc
		(start 127.81534 -296.473372)
		(mid 127.832145 -296.487372)
		(end 127.848106 -296.502328)
		(width 0.1143)
		(layer "In13.Cu")
		(net "P5E_CPU1_P2_TX_DP<15>")
	)
	(arc
		(start 172.94479 -372.833646)
		(mid 172.891063 -373.031507)
		(end 172.872908 -373.235728)
		(width 0.14224)
		(layer "In13.Cu")
		(net "P5E_CPU1_P2_TX_DP<15>")
	)
	(arc
		(start 125.615446 -271.739106)
		(mid 125.617234 -271.750555)
		(end 125.619256 -271.761966)
		(width 0.1143)
		(layer "In13.Cu")
		(net "P5E_CPU1_P2_TX_DP<15>")
	)
	(arc
		(start 126.549404 -273.276314)
		(mid 126.613919 -273.538533)
		(end 126.792736 -273.74088)
		(width 0.1143)
		(layer "In13.Cu")
		(net "P5E_CPU1_P2_TX_DP<15>")
	)
	(arc
		(start 126.862332 -283.501592)
		(mid 127.019309 -283.806392)
		(end 126.862332 -284.111192)
		(width 0.1143)
		(layer "In13.Cu")
		(net "P5E_CPU1_P2_TX_DP<15>")
	)
	(arc
		(start 172.977556 -372.65737)
		(mid 172.973388 -372.720798)
		(end 172.960792 -372.7831)
		(width 0.14224)
		(layer "In13.Cu")
		(net "P5E_CPU1_P2_TX_DP<15>")
	)
	(arc
		(start 126.792736 -282.53182)
		(mid 126.549409 -282.996386)
		(end 126.792736 -283.460952)
		(width 0.1143)
		(layer "In13.Cu")
		(net "P5E_CPU1_P2_TX_DP<15>")
	)
	(arc
		(start 127.019304 -287.046162)
		(mid 126.977755 -287.217584)
		(end 126.862332 -287.350962)
		(width 0.1143)
		(layer "In13.Cu")
		(net "P5E_CPU1_P2_TX_DP<15>")
	)
	(arc
		(start 126.862332 -281.88158)
		(mid 127.019309 -282.18638)
		(end 126.862332 -282.49118)
		(width 0.1143)
		(layer "In13.Cu")
		(net "P5E_CPU1_P2_TX_DP<15>")
	)
	(arc
		(start 154.281124 -356.994968)
		(mid 154.31857 -357.045817)
		(end 154.359356 -357.094028)
		(width 0.14224)
		(layer "In13.Cu")
		(net "P5E_CPU1_P2_TX_DP<15>")
	)
	(arc
		(start 125.619256 -271.761966)
		(mid 125.700689 -271.964364)
		(end 125.852682 -272.120868)
		(width 0.1143)
		(layer "In13.Cu")
		(net "P5E_CPU1_P2_TX_DP<15>")
	)
	(arc
		(start 127.489458 -295.956228)
		(mid 127.55433 -296.219191)
		(end 127.73406 -296.42181)
		(width 0.1143)
		(layer "In13.Cu")
		(net "P5E_CPU1_P2_TX_DP<15>")
	)
	(arc
		(start 172.952918 -371.347746)
		(mid 172.971326 -371.408254)
		(end 172.977556 -371.47119)
		(width 0.14224)
		(layer "In13.Cu")
		(net "P5E_CPU1_P2_TX_DP<15>")
	)
	(arc
		(start 126.862332 -273.78152)
		(mid 127.019309 -274.08632)
		(end 126.862332 -274.39112)
		(width 0.1143)
		(layer "In13.Cu")
		(net "P5E_CPU1_P2_TX_DP<15>")
	)
	(arc
		(start 172.960538 -372.784116)
		(mid 172.9532 -372.809052)
		(end 172.94479 -372.833646)
		(width 0.14224)
		(layer "In13.Cu")
		(net "P5E_CPU1_P2_TX_DP<15>")
	)
	(arc
		(start 126.862332 -293.22141)
		(mid 127.019309 -293.52621)
		(end 126.862332 -293.83101)
		(width 0.1143)
		(layer "In13.Cu")
		(net "P5E_CPU1_P2_TX_DP<15>")
	)
	(arc
		(start 126.549404 -287.856422)
		(mid 126.613919 -288.118641)
		(end 126.792736 -288.320988)
		(width 0.1143)
		(layer "In13.Cu")
		(net "P5E_CPU1_P2_TX_DP<15>")
	)
	(arc
		(start 126.862332 -294.841422)
		(mid 126.977759 -294.974798)
		(end 127.019304 -295.146222)
		(width 0.1143)
		(layer "In13.Cu")
		(net "P5E_CPU1_P2_TX_DP<15>")
	)
	(arc
		(start 166.922196 -364.49)
		(mid 168.337717 -365.246339)
		(end 169.578782 -366.263936)
		(width 0.14224)
		(layer "In13.Cu")
		(net "P5E_CPU1_P2_TX_DP<15>")
	)
	(arc
		(start 126.862332 -277.021544)
		(mid 127.019309 -277.326344)
		(end 126.862332 -277.631144)
		(width 0.1143)
		(layer "In13.Cu")
		(net "P5E_CPU1_P2_TX_DP<15>")
	)
	(arc
		(start 126.864364 -286.742632)
		(mid 126.978293 -286.875779)
		(end 127.019304 -287.046162)
		(width 0.1143)
		(layer "In13.Cu")
		(net "P5E_CPU1_P2_TX_DP<15>")
	)
	(arc
		(start 127.019304 -288.666174)
		(mid 126.977755 -288.837596)
		(end 126.862332 -288.970974)
		(width 0.1143)
		(layer "In13.Cu")
		(net "P5E_CPU1_P2_TX_DP<15>")
	)
	(arc
		(start 126.862332 -285.121604)
		(mid 127.019309 -285.426404)
		(end 126.862332 -285.731204)
		(width 0.1143)
		(layer "In13.Cu")
		(net "P5E_CPU1_P2_TX_DP<15>")
	)
	(arc
		(start 172.421042 -370.095272)
		(mid 172.453633 -370.149555)
		(end 172.480732 -370.206778)
		(width 0.14224)
		(layer "In13.Cu")
		(net "P5E_CPU1_P2_TX_DP<15>")
	)
	(arc
		(start 170.200574 -366.885728)
		(mid 170.406746 -367.112056)
		(end 170.591226 -367.35639)
		(width 0.14224)
		(layer "In13.Cu")
		(net "P5E_CPU1_P2_TX_DP<15>")
	)
	(arc
		(start 126.862332 -278.641556)
		(mid 127.019309 -278.946356)
		(end 126.862332 -279.251156)
		(width 0.1143)
		(layer "In13.Cu")
		(net "P5E_CPU1_P2_TX_DP<15>")
	)
	(arc
		(start 126.792736 -293.87165)
		(mid 126.549409 -294.336216)
		(end 126.792736 -294.800782)
		(width 0.1143)
		(layer "In13.Cu")
		(net "P5E_CPU1_P2_TX_DP<15>")
	)
	(arc
		(start 127.771652 -296.443654)
		(mid 127.794024 -296.457737)
		(end 127.81534 -296.473372)
		(width 0.1143)
		(layer "In13.Cu")
		(net "P5E_CPU1_P2_TX_DP<15>")
	)
	(arc
		(start 126.862332 -280.261568)
		(mid 127.019309 -280.566368)
		(end 126.862332 -280.871168)
		(width 0.1143)
		(layer "In13.Cu")
		(net "P5E_CPU1_P2_TX_DP<15>")
	)
	(arc
		(start 127.333502 -295.651936)
		(mid 127.448178 -295.78527)
		(end 127.489458 -295.956228)
		(width 0.1143)
		(layer "In13.Cu")
		(net "P5E_CPU1_P2_TX_DP<15>")
	)
	(arc
		(start 126.792736 -284.151832)
		(mid 126.549409 -284.616398)
		(end 126.792736 -285.080964)
		(width 0.1143)
		(layer "In13.Cu")
		(net "P5E_CPU1_P2_TX_DP<15>")
	)
	(arc
		(start 125.91161 -272.155158)
		(mid 126.033044 -272.276422)
		(end 126.077472 -272.442178)
		(width 0.1143)
		(layer "In13.Cu")
		(net "P5E_CPU1_P2_TX_DP<15>")
	)
	(arc
		(start 126.393448 -272.972022)
		(mid 126.508124 -273.105356)
		(end 126.549404 -273.276314)
		(width 0.1143)
		(layer "In13.Cu")
		(net "P5E_CPU1_P2_TX_DP<15>")
	)
	(arc
		(start 126.792736 -274.43176)
		(mid 126.549409 -274.896326)
		(end 126.792736 -275.360892)
		(width 0.1143)
		(layer "In13.Cu")
		(net "P5E_CPU1_P2_TX_DP<15>")
	)
	(arc
		(start 126.792736 -292.251638)
		(mid 126.549409 -292.716204)
		(end 126.792736 -293.18077)
		(width 0.1143)
		(layer "In13.Cu")
		(net "P5E_CPU1_P2_TX_DP<15>")
	)
	(arc
		(start 126.862332 -275.401532)
		(mid 127.019309 -275.706332)
		(end 126.862332 -276.011132)
		(width 0.1143)
		(layer "In13.Cu")
		(net "P5E_CPU1_P2_TX_DP<15>")
	)
	(arc
		(start 126.792736 -289.011614)
		(mid 126.549409 -289.47618)
		(end 126.792736 -289.940746)
		(width 0.1143)
		(layer "In13.Cu")
		(net "P5E_CPU1_P2_TX_DP<15>")
	)
	(arc
		(start 126.862332 -291.601398)
		(mid 127.019309 -291.906198)
		(end 126.862332 -292.210998)
		(width 0.1143)
		(layer "In13.Cu")
		(net "P5E_CPU1_P2_TX_DP<15>")
	)
	(arc
		(start 126.792736 -280.911808)
		(mid 126.549409 -281.376374)
		(end 126.792736 -281.84094)
		(width 0.1143)
		(layer "In13.Cu")
		(net "P5E_CPU1_P2_TX_DP<15>")
	)
	(arc
		(start 126.795276 -287.390078)
		(mid 126.614624 -287.592823)
		(end 126.549404 -287.856422)
		(width 0.1143)
		(layer "In13.Cu")
		(net "P5E_CPU1_P2_TX_DP<15>")
	)
	(arc
		(start 126.792736 -290.631626)
		(mid 126.549409 -291.096192)
		(end 126.792736 -291.560758)
		(width 0.1143)
		(layer "In13.Cu")
		(net "P5E_CPU1_P2_TX_DP<15>")
	)
	(arc
		(start 157.454346 -360.509058)
		(mid 157.548239 -360.592115)
		(end 157.658054 -360.652568)
		(width 0.14224)
		(layer "In13.Cu")
		(net "P5E_CPU1_P2_TX_DP<15>")
	)
	(arc
		(start 126.077472 -272.46326)
		(mid 126.152859 -272.745333)
		(end 126.358904 -272.95221)
		(width 0.1143)
		(layer "In13.Cu")
		(net "P5E_CPU1_P2_TX_DP<15>")
	)
	(arc
		(start 172.653452 -379.21438)
		(mid 172.52191 -379.41126)
		(end 172.32503 -379.542802)
		(width 0.14224)
		(layer "In13.Cu")
		(net "P5E_CPU1_P2_TX_DP<15>")
	)
	(arc
		(start 126.792736 -279.291796)
		(mid 126.549409 -279.756362)
		(end 126.792736 -280.220928)
		(width 0.1143)
		(layer "In13.Cu")
		(net "P5E_CPU1_P2_TX_DP<15>")
	)
	(arc
		(start 126.862332 -289.981386)
		(mid 127.019309 -290.286186)
		(end 126.862332 -290.590986)
		(width 0.1143)
		(layer "In13.Cu")
		(net "P5E_CPU1_P2_TX_DP<15>")
	)
	(segment
		(start 169.931334 -376.363738)
		(end 169.635424 -376.067828)
		(width 0.12954)
		(layer "F.Cu")
		(net "P5E_CPU1_P2_TX_DP<14>")
	)
	(segment
		(start 124.767848 -273.010376)
		(end 125.2347 -273.276314)
		(width 0.12954)
		(layer "F.Cu")
		(net "P5E_CPU1_P2_TX_DP<14>")
	)
	(segment
		(start 170.905424 -376.093228)
		(end 170.634914 -376.363738)
		(width 0.12954)
		(layer "F.Cu")
		(net "P5E_CPU1_P2_TX_DP<14>")
	)
	(segment
		(start 170.634914 -376.363738)
		(end 169.931334 -376.363738)
		(width 0.12954)
		(layer "F.Cu")
		(net "P5E_CPU1_P2_TX_DP<14>")
	)
	(segment
		(start 125.94336 -279.236424)
		(end 125.923548 -279.250648)
		(width 0.1143)
		(layer "In13.Cu")
		(net "P5E_CPU1_P2_TX_DP<14>")
	)
	(segment
		(start 125.890782 -293.849298)
		(end 125.852682 -293.87165)
		(width 0.1143)
		(layer "In13.Cu")
		(net "P5E_CPU1_P2_TX_DP<14>")
	)
	(segment
		(start 125.891798 -282.50896)
		(end 125.890782 -282.509468)
		(width 0.1143)
		(layer "In13.Cu")
		(net "P5E_CPU1_P2_TX_DP<14>")
	)
	(segment
		(start 125.891798 -293.20363)
		(end 125.89256 -293.204138)
		(width 0.1143)
		(layer "In13.Cu")
		(net "P5E_CPU1_P2_TX_DP<14>")
	)
	(segment
		(start 125.890782 -285.103316)
		(end 125.891798 -285.103824)
		(width 0.1143)
		(layer "In13.Cu")
		(net "P5E_CPU1_P2_TX_DP<14>")
	)
	(segment
		(start 125.89256 -282.508706)
		(end 125.891798 -282.50896)
		(width 0.1143)
		(layer "In13.Cu")
		(net "P5E_CPU1_P2_TX_DP<14>")
	)
	(segment
		(start 125.890782 -276.02942)
		(end 125.889258 -276.030436)
		(width 0.1143)
		(layer "In13.Cu")
		(net "P5E_CPU1_P2_TX_DP<14>")
	)
	(segment
		(start 125.858778 -288.324544)
		(end 125.859032 -288.324544)
		(width 0.1143)
		(layer "In13.Cu")
		(net "P5E_CPU1_P2_TX_DP<14>")
	)
	(segment
		(start 125.923548 -287.350454)
		(end 125.855222 -287.390078)
		(width 0.1143)
		(layer "In13.Cu")
		(net "P5E_CPU1_P2_TX_DP<14>")
	)
	(segment
		(start 125.852682 -283.460952)
		(end 125.85954 -283.465016)
		(width 0.1143)
		(layer "In13.Cu")
		(net "P5E_CPU1_P2_TX_DP<14>")
	)
	(segment
		(start 125.852682 -276.980904)
		(end 125.85954 -276.984968)
		(width 0.1143)
		(layer "In13.Cu")
		(net "P5E_CPU1_P2_TX_DP<14>")
	)
	(segment
		(start 125.855476 -280.22296)
		(end 125.891798 -280.243788)
		(width 0.1143)
		(layer "In13.Cu")
		(net "P5E_CPU1_P2_TX_DP<14>")
	)
	(segment
		(start 163.024566 -364.1852)
		(end 163.418774 -364.348268)
		(width 0.14224)
		(layer "In13.Cu")
		(net "P5E_CPU1_P2_TX_DP<14>")
	)
	(segment
		(start 125.88621 -292.23208)
		(end 125.852682 -292.251638)
		(width 0.1143)
		(layer "In13.Cu")
		(net "P5E_CPU1_P2_TX_DP<14>")
	)
	(segment
		(start 126.86284 -296.85996)
		(end 126.863348 -296.860468)
		(width 0.14224)
		(layer "In13.Cu")
		(net "P5E_CPU1_P2_TX_DP<14>")
	)
	(segment
		(start 125.894592 -293.205408)
		(end 125.8951 -293.205408)
		(width 0.1143)
		(layer "In13.Cu")
		(net "P5E_CPU1_P2_TX_DP<14>")
	)
	(segment
		(start 125.852682 -281.84094)
		(end 125.890782 -281.863292)
		(width 0.1143)
		(layer "In13.Cu")
		(net "P5E_CPU1_P2_TX_DP<14>")
	)
	(segment
		(start 125.89256 -293.204138)
		(end 125.894592 -293.205408)
		(width 0.1143)
		(layer "In13.Cu")
		(net "P5E_CPU1_P2_TX_DP<14>")
	)
	(segment
		(start 125.852682 -273.74088)
		(end 125.85954 -273.744944)
		(width 0.1143)
		(layer "In13.Cu")
		(net "P5E_CPU1_P2_TX_DP<14>")
	)
	(segment
		(start 162.845496 -364.259368)
		(end 163.024566 -364.1852)
		(width 0.14224)
		(layer "In13.Cu")
		(net "P5E_CPU1_P2_TX_DP<14>")
	)
	(segment
		(start 148.265134 -347.528134)
		(end 152.856438 -356.649528)
		(width 0.14224)
		(layer "In13.Cu")
		(net "P5E_CPU1_P2_TX_DP<14>")
	)
	(segment
		(start 125.889258 -274.410424)
		(end 125.852682 -274.43176)
		(width 0.1143)
		(layer "In13.Cu")
		(net "P5E_CPU1_P2_TX_DP<14>")
	)
	(segment
		(start 125.89256 -293.848536)
		(end 125.891798 -293.84879)
		(width 0.1143)
		(layer "In13.Cu")
		(net "P5E_CPU1_P2_TX_DP<14>")
	)
	(segment
		(start 125.89256 -273.764248)
		(end 125.923548 -273.782028)
		(width 0.1143)
		(layer "In13.Cu")
		(net "P5E_CPU1_P2_TX_DP<14>")
	)
	(segment
		(start 152.856438 -356.649528)
		(end 153.939748 -358.228392)
		(width 0.14224)
		(layer "In13.Cu")
		(net "P5E_CPU1_P2_TX_DP<14>")
	)
	(segment
		(start 125.890782 -294.823134)
		(end 125.894338 -294.824912)
		(width 0.1143)
		(layer "In13.Cu")
		(net "P5E_CPU1_P2_TX_DP<14>")
	)
	(segment
		(start 125.852682 -294.800782)
		(end 125.890782 -294.823134)
		(width 0.1143)
		(layer "In13.Cu")
		(net "P5E_CPU1_P2_TX_DP<14>")
	)
	(segment
		(start 125.89256 -290.608512)
		(end 125.891798 -290.608766)
		(width 0.1143)
		(layer "In13.Cu")
		(net "P5E_CPU1_P2_TX_DP<14>")
	)
	(segment
		(start 164.066728 -364.616746)
		(end 165.060376 -365.028226)
		(width 0.14224)
		(layer "In13.Cu")
		(net "P5E_CPU1_P2_TX_DP<14>")
	)
	(segment
		(start 125.94336 -277.616412)
		(end 125.923548 -277.630636)
		(width 0.1143)
		(layer "In13.Cu")
		(net "P5E_CPU1_P2_TX_DP<14>")
	)
	(segment
		(start 128.320038 -298.814744)
		(end 136.548368 -309.908956)
		(width 0.14224)
		(layer "In13.Cu")
		(net "P5E_CPU1_P2_TX_DP<14>")
	)
	(segment
		(start 125.89256 -277.648416)
		(end 125.891798 -277.648924)
		(width 0.1143)
		(layer "In13.Cu")
		(net "P5E_CPU1_P2_TX_DP<14>")
	)
	(segment
		(start 125.891798 -292.228778)
		(end 125.890782 -292.229286)
		(width 0.1143)
		(layer "In13.Cu")
		(net "P5E_CPU1_P2_TX_DP<14>")
	)
	(segment
		(start 125.923548 -274.390612)
		(end 125.89256 -274.408392)
		(width 0.1143)
		(layer "In13.Cu")
		(net "P5E_CPU1_P2_TX_DP<14>")
	)
	(segment
		(start 125.891798 -278.623776)
		(end 125.89256 -278.624284)
		(width 0.1143)
		(layer "In13.Cu")
		(net "P5E_CPU1_P2_TX_DP<14>")
	)
	(segment
		(start 165.52926 -365.370872)
		(end 165.70833 -365.296704)
		(width 0.14224)
		(layer "In13.Cu")
		(net "P5E_CPU1_P2_TX_DP<14>")
	)
	(segment
		(start 125.927358 -287.34766)
		(end 125.923548 -287.350454)
		(width 0.1143)
		(layer "In13.Cu")
		(net "P5E_CPU1_P2_TX_DP<14>")
	)
	(segment
		(start 160.138872 -363.138212)
		(end 160.533334 -363.301534)
		(width 0.14224)
		(layer "In13.Cu")
		(net "P5E_CPU1_P2_TX_DP<14>")
	)
	(segment
		(start 125.890782 -281.863292)
		(end 125.891798 -281.8638)
		(width 0.1143)
		(layer "In13.Cu")
		(net "P5E_CPU1_P2_TX_DP<14>")
	)
	(segment
		(start 125.891798 -293.84879)
		(end 125.890782 -293.849298)
		(width 0.1143)
		(layer "In13.Cu")
		(net "P5E_CPU1_P2_TX_DP<14>")
	)
	(segment
		(start 125.894592 -281.865578)
		(end 125.8951 -281.865578)
		(width 0.1143)
		(layer "In13.Cu")
		(net "P5E_CPU1_P2_TX_DP<14>")
	)
	(segment
		(start 125.894846 -288.986976)
		(end 125.89256 -288.9885)
		(width 0.1143)
		(layer "In13.Cu")
		(net "P5E_CPU1_P2_TX_DP<14>")
	)
	(segment
		(start 125.895354 -288.986976)
		(end 125.894846 -288.986976)
		(width 0.1143)
		(layer "In13.Cu")
		(net "P5E_CPU1_P2_TX_DP<14>")
	)
	(segment
		(start 125.860302 -278.605488)
		(end 125.891798 -278.623776)
		(width 0.1143)
		(layer "In13.Cu")
		(net "P5E_CPU1_P2_TX_DP<14>")
	)
	(segment
		(start 125.891798 -273.76374)
		(end 125.89256 -273.764248)
		(width 0.1143)
		(layer "In13.Cu")
		(net "P5E_CPU1_P2_TX_DP<14>")
	)
	(segment
		(start 125.923548 -291.601906)
		(end 125.928628 -291.605462)
		(width 0.1143)
		(layer "In13.Cu")
		(net "P5E_CPU1_P2_TX_DP<14>")
	)
	(segment
		(start 125.891798 -283.483812)
		(end 125.89256 -283.48432)
		(width 0.1143)
		(layer "In13.Cu")
		(net "P5E_CPU1_P2_TX_DP<14>")
	)
	(segment
		(start 125.890782 -274.409408)
		(end 125.889258 -274.410424)
		(width 0.1143)
		(layer "In13.Cu")
		(net "P5E_CPU1_P2_TX_DP<14>")
	)
	(segment
		(start 172.025818 -371.627146)
		(end 172.025818 -371.88902)
		(width 0.14224)
		(layer "In13.Cu")
		(net "P5E_CPU1_P2_TX_DP<14>")
	)
	(segment
		(start 125.923548 -280.87066)
		(end 125.891798 -280.888948)
		(width 0.1143)
		(layer "In13.Cu")
		(net "P5E_CPU1_P2_TX_DP<14>")
	)
	(segment
		(start 125.890782 -277.649432)
		(end 125.889258 -277.650448)
		(width 0.1143)
		(layer "In13.Cu")
		(net "P5E_CPU1_P2_TX_DP<14>")
	)
	(segment
		(start 125.2347 -273.276314)
		(end 125.532642 -273.276314)
		(width 0.1143)
		(layer "In13.Cu")
		(net "P5E_CPU1_P2_TX_DP<14>")
	)
	(segment
		(start 125.889258 -277.650448)
		(end 125.852682 -277.671784)
		(width 0.1143)
		(layer "In13.Cu")
		(net "P5E_CPU1_P2_TX_DP<14>")
	)
	(segment
		(start 162.376612 -363.916468)
		(end 162.451034 -364.096046)
		(width 0.14224)
		(layer "In13.Cu")
		(net "P5E_CPU1_P2_TX_DP<14>")
	)
	(segment
		(start 125.928628 -292.206934)
		(end 125.923548 -292.21049)
		(width 0.1143)
		(layer "In13.Cu")
		(net "P5E_CPU1_P2_TX_DP<14>")
	)
	(segment
		(start 125.852682 -286.700976)
		(end 125.925326 -286.743394)
		(width 0.1143)
		(layer "In13.Cu")
		(net "P5E_CPU1_P2_TX_DP<14>")
	)
	(segment
		(start 127.01524 -297.224958)
		(end 128.320038 -298.814744)
		(width 0.14224)
		(layer "In13.Cu")
		(net "P5E_CPU1_P2_TX_DP<14>")
	)
	(segment
		(start 125.923548 -278.642064)
		(end 125.94336 -278.656288)
		(width 0.1143)
		(layer "In13.Cu")
		(net "P5E_CPU1_P2_TX_DP<14>")
	)
	(segment
		(start 125.891798 -277.648924)
		(end 125.890782 -277.649432)
		(width 0.1143)
		(layer "In13.Cu")
		(net "P5E_CPU1_P2_TX_DP<14>")
	)
	(segment
		(start 126.86284 -296.850816)
		(end 126.86284 -296.85996)
		(width 0.14224)
		(layer "In13.Cu")
		(net "P5E_CPU1_P2_TX_DP<14>")
	)
	(segment
		(start 125.860302 -273.745452)
		(end 125.891798 -273.76374)
		(width 0.1143)
		(layer "In13.Cu")
		(net "P5E_CPU1_P2_TX_DP<14>")
	)
	(segment
		(start 126.86284 -296.822368)
		(end 126.86284 -296.850816)
		(width 0.1143)
		(layer "In13.Cu")
		(net "P5E_CPU1_P2_TX_DP<14>")
	)
	(segment
		(start 166.48557 -365.618522)
		(end 168.83507 -366.874044)
		(width 0.14224)
		(layer "In13.Cu")
		(net "P5E_CPU1_P2_TX_DP<14>")
	)
	(segment
		(start 165.134798 -365.207804)
		(end 165.52926 -365.370872)
		(width 0.14224)
		(layer "In13.Cu")
		(net "P5E_CPU1_P2_TX_DP<14>")
	)
	(segment
		(start 171.642786 -376.384058)
		(end 171.196254 -376.384058)
		(width 0.14224)
		(layer "In13.Cu")
		(net "P5E_CPU1_P2_TX_DP<14>")
	)
	(segment
		(start 163.418774 -364.348268)
		(end 163.492942 -364.527592)
		(width 0.14224)
		(layer "In13.Cu")
		(net "P5E_CPU1_P2_TX_DP<14>")
	)
	(segment
		(start 153.939748 -358.228392)
		(end 157.122622 -361.74045)
		(width 0.14224)
		(layer "In13.Cu")
		(net "P5E_CPU1_P2_TX_DP<14>")
	)
	(segment
		(start 125.860302 -276.985476)
		(end 125.891798 -277.003764)
		(width 0.1143)
		(layer "In13.Cu")
		(net "P5E_CPU1_P2_TX_DP<14>")
	)
	(segment
		(start 125.891798 -275.383752)
		(end 125.89256 -275.38426)
		(width 0.1143)
		(layer "In13.Cu")
		(net "P5E_CPU1_P2_TX_DP<14>")
	)
	(segment
		(start 125.89256 -291.584126)
		(end 125.923548 -291.601906)
		(width 0.1143)
		(layer "In13.Cu")
		(net "P5E_CPU1_P2_TX_DP<14>")
	)
	(segment
		(start 125.890782 -289.963098)
		(end 125.891798 -289.963606)
		(width 0.1143)
		(layer "In13.Cu")
		(net "P5E_CPU1_P2_TX_DP<14>")
	)
	(segment
		(start 125.89256 -285.74873)
		(end 125.891798 -285.748984)
		(width 0.1143)
		(layer "In13.Cu")
		(net "P5E_CPU1_P2_TX_DP<14>")
	)
	(segment
		(start 125.852682 -288.320988)
		(end 125.858778 -288.324544)
		(width 0.1143)
		(layer "In13.Cu")
		(net "P5E_CPU1_P2_TX_DP<14>")
	)
	(segment
		(start 125.891798 -279.268936)
		(end 125.890782 -279.269444)
		(width 0.1143)
		(layer "In13.Cu")
		(net "P5E_CPU1_P2_TX_DP<14>")
	)
	(segment
		(start 125.88875 -292.230556)
		(end 125.887226 -292.231572)
		(width 0.1143)
		(layer "In13.Cu")
		(net "P5E_CPU1_P2_TX_DP<14>")
	)
	(segment
		(start 125.89256 -289.964114)
		(end 125.894592 -289.965384)
		(width 0.1143)
		(layer "In13.Cu")
		(net "P5E_CPU1_P2_TX_DP<14>")
	)
	(segment
		(start 126.897384 -297.016932)
		(end 127.01524 -297.224958)
		(width 0.14224)
		(layer "In13.Cu")
		(net "P5E_CPU1_P2_TX_DP<14>")
	)
	(segment
		(start 125.890782 -288.989262)
		(end 125.852682 -289.011614)
		(width 0.1143)
		(layer "In13.Cu")
		(net "P5E_CPU1_P2_TX_DP<14>")
	)
	(segment
		(start 125.852682 -278.600916)
		(end 125.85954 -278.60498)
		(width 0.1143)
		(layer "In13.Cu")
		(net "P5E_CPU1_P2_TX_DP<14>")
	)
	(segment
		(start 125.860302 -283.465524)
		(end 125.891798 -283.483812)
		(width 0.1143)
		(layer "In13.Cu")
		(net "P5E_CPU1_P2_TX_DP<14>")
	)
	(segment
		(start 125.890782 -292.229286)
		(end 125.88875 -292.230556)
		(width 0.1143)
		(layer "In13.Cu")
		(net "P5E_CPU1_P2_TX_DP<14>")
	)
	(segment
		(start 171.930568 -375.732802)
		(end 171.930568 -376.09653)
		(width 0.14224)
		(layer "In13.Cu")
		(net "P5E_CPU1_P2_TX_DP<14>")
	)
	(segment
		(start 125.895354 -293.847012)
		(end 125.894846 -293.847012)
		(width 0.1143)
		(layer "In13.Cu")
		(net "P5E_CPU1_P2_TX_DP<14>")
	)
	(segment
		(start 125.891798 -288.988754)
		(end 125.890782 -288.989262)
		(width 0.1143)
		(layer "In13.Cu")
		(net "P5E_CPU1_P2_TX_DP<14>")
	)
	(segment
		(start 125.891798 -277.003764)
		(end 125.89256 -277.004272)
		(width 0.1143)
		(layer "In13.Cu")
		(net "P5E_CPU1_P2_TX_DP<14>")
	)
	(segment
		(start 125.855476 -280.909776)
		(end 125.852682 -280.911808)
		(width 0.1143)
		(layer "In13.Cu")
		(net "P5E_CPU1_P2_TX_DP<14>")
	)
	(segment
		(start 125.923548 -276.010624)
		(end 125.89256 -276.028404)
		(width 0.1143)
		(layer "In13.Cu")
		(net "P5E_CPU1_P2_TX_DP<14>")
	)
	(segment
		(start 163.492942 -364.527592)
		(end 163.887404 -364.690914)
		(width 0.14224)
		(layer "In13.Cu")
		(net "P5E_CPU1_P2_TX_DP<14>")
	)
	(segment
		(start 168.83507 -366.874044)
		(end 169.589196 -367.627916)
		(width 0.14224)
		(layer "In13.Cu")
		(net "P5E_CPU1_P2_TX_DP<14>")
	)
	(segment
		(start 125.890782 -284.12948)
		(end 125.852682 -284.151832)
		(width 0.1143)
		(layer "In13.Cu")
		(net "P5E_CPU1_P2_TX_DP<14>")
	)
	(segment
		(start 125.891798 -285.748984)
		(end 125.890782 -285.749492)
		(width 0.1143)
		(layer "In13.Cu")
		(net "P5E_CPU1_P2_TX_DP<14>")
	)
	(segment
		(start 125.891798 -274.4089)
		(end 125.890782 -274.409408)
		(width 0.1143)
		(layer "In13.Cu")
		(net "P5E_CPU1_P2_TX_DP<14>")
	)
	(segment
		(start 125.894592 -283.48559)
		(end 125.8951 -283.48559)
		(width 0.1143)
		(layer "In13.Cu")
		(net "P5E_CPU1_P2_TX_DP<14>")
	)
	(segment
		(start 125.923548 -277.630636)
		(end 125.89256 -277.648416)
		(width 0.1143)
		(layer "In13.Cu")
		(net "P5E_CPU1_P2_TX_DP<14>")
	)
	(segment
		(start 125.852682 -280.220928)
		(end 125.855476 -280.22296)
		(width 0.1143)
		(layer "In13.Cu")
		(net "P5E_CPU1_P2_TX_DP<14>")
	)
	(segment
		(start 126.863348 -296.860468)
		(end 126.863348 -296.921682)
		(width 0.14224)
		(layer "In13.Cu")
		(net "P5E_CPU1_P2_TX_DP<14>")
	)
	(segment
		(start 125.889258 -276.030436)
		(end 125.852682 -276.051772)
		(width 0.1143)
		(layer "In13.Cu")
		(net "P5E_CPU1_P2_TX_DP<14>")
	)
	(segment
		(start 171.54144 -373.05869)
		(end 171.54144 -374.099074)
		(width 0.14224)
		(layer "In13.Cu")
		(net "P5E_CPU1_P2_TX_DP<14>")
	)
	(segment
		(start 125.89256 -292.22827)
		(end 125.891798 -292.228778)
		(width 0.1143)
		(layer "In13.Cu")
		(net "P5E_CPU1_P2_TX_DP<14>")
	)
	(segment
		(start 125.89256 -281.864308)
		(end 125.894592 -281.865578)
		(width 0.1143)
		(layer "In13.Cu")
		(net "P5E_CPU1_P2_TX_DP<14>")
	)
	(segment
		(start 125.89256 -279.268428)
		(end 125.891798 -279.268936)
		(width 0.1143)
		(layer "In13.Cu")
		(net "P5E_CPU1_P2_TX_DP<14>")
	)
	(segment
		(start 125.852682 -289.940746)
		(end 125.890782 -289.963098)
		(width 0.1143)
		(layer "In13.Cu")
		(net "P5E_CPU1_P2_TX_DP<14>")
	)
	(segment
		(start 125.891798 -285.103824)
		(end 125.89256 -285.104332)
		(width 0.1143)
		(layer "In13.Cu")
		(net "P5E_CPU1_P2_TX_DP<14>")
	)
	(segment
		(start 125.891798 -281.8638)
		(end 125.89256 -281.864308)
		(width 0.1143)
		(layer "In13.Cu")
		(net "P5E_CPU1_P2_TX_DP<14>")
	)
	(segment
		(start 125.89256 -283.48432)
		(end 125.894592 -283.48559)
		(width 0.1143)
		(layer "In13.Cu")
		(net "P5E_CPU1_P2_TX_DP<14>")
	)
	(segment
		(start 125.85954 -283.465016)
		(end 125.860302 -283.465524)
		(width 0.1143)
		(layer "In13.Cu")
		(net "P5E_CPU1_P2_TX_DP<14>")
	)
	(segment
		(start 125.85954 -276.984968)
		(end 125.860302 -276.985476)
		(width 0.1143)
		(layer "In13.Cu")
		(net "P5E_CPU1_P2_TX_DP<14>")
	)
	(segment
		(start 125.894592 -285.105602)
		(end 125.8951 -285.105602)
		(width 0.1143)
		(layer "In13.Cu")
		(net "P5E_CPU1_P2_TX_DP<14>")
	)
	(segment
		(start 169.90695 -368.01679)
		(end 171.607226 -370.582698)
		(width 0.14224)
		(layer "In13.Cu")
		(net "P5E_CPU1_P2_TX_DP<14>")
	)
	(segment
		(start 136.548368 -309.908956)
		(end 138.12012 -312.261504)
		(width 0.14224)
		(layer "In13.Cu")
		(net "P5E_CPU1_P2_TX_DP<14>")
	)
	(segment
		(start 125.891798 -291.583618)
		(end 125.89256 -291.584126)
		(width 0.1143)
		(layer "In13.Cu")
		(net "P5E_CPU1_P2_TX_DP<14>")
	)
	(segment
		(start 125.852682 -275.360892)
		(end 125.85954 -275.364956)
		(width 0.1143)
		(layer "In13.Cu")
		(net "P5E_CPU1_P2_TX_DP<14>")
	)
	(segment
		(start 165.70833 -365.296704)
		(end 166.48557 -365.618522)
		(width 0.14224)
		(layer "In13.Cu")
		(net "P5E_CPU1_P2_TX_DP<14>")
	)
	(segment
		(start 125.859032 -288.324544)
		(end 125.894846 -288.345372)
		(width 0.1143)
		(layer "In13.Cu")
		(net "P5E_CPU1_P2_TX_DP<14>")
	)
	(segment
		(start 126.863348 -296.921682)
		(end 126.897384 -297.016932)
		(width 0.14224)
		(layer "In13.Cu")
		(net "P5E_CPU1_P2_TX_DP<14>")
	)
	(segment
		(start 125.89256 -276.028404)
		(end 125.891798 -276.028912)
		(width 0.1143)
		(layer "In13.Cu")
		(net "P5E_CPU1_P2_TX_DP<14>")
	)
	(segment
		(start 126.549658 -295.956228)
		(end 126.549658 -296.2021)
		(width 0.1143)
		(layer "In13.Cu")
		(net "P5E_CPU1_P2_TX_DP<14>")
	)
	(segment
		(start 125.894846 -285.747206)
		(end 125.89256 -285.74873)
		(width 0.1143)
		(layer "In13.Cu")
		(net "P5E_CPU1_P2_TX_DP<14>")
	)
	(segment
		(start 125.891798 -280.243788)
		(end 125.923548 -280.262076)
		(width 0.1143)
		(layer "In13.Cu")
		(net "P5E_CPU1_P2_TX_DP<14>")
	)
	(segment
		(start 125.923548 -279.250648)
		(end 125.89256 -279.268428)
		(width 0.1143)
		(layer "In13.Cu")
		(net "P5E_CPU1_P2_TX_DP<14>")
	)
	(segment
		(start 125.890782 -279.269444)
		(end 125.889258 -279.27046)
		(width 0.1143)
		(layer "In13.Cu")
		(net "P5E_CPU1_P2_TX_DP<14>")
	)
	(segment
		(start 125.889258 -279.27046)
		(end 125.852682 -279.291796)
		(width 0.1143)
		(layer "In13.Cu")
		(net "P5E_CPU1_P2_TX_DP<14>")
	)
	(segment
		(start 125.895354 -285.747206)
		(end 125.894846 -285.747206)
		(width 0.1143)
		(layer "In13.Cu")
		(net "P5E_CPU1_P2_TX_DP<14>")
	)
	(segment
		(start 125.891798 -284.128972)
		(end 125.890782 -284.12948)
		(width 0.1143)
		(layer "In13.Cu")
		(net "P5E_CPU1_P2_TX_DP<14>")
	)
	(segment
		(start 125.891798 -276.028912)
		(end 125.890782 -276.02942)
		(width 0.1143)
		(layer "In13.Cu")
		(net "P5E_CPU1_P2_TX_DP<14>")
	)
	(segment
		(start 165.060376 -365.028226)
		(end 165.134798 -365.207804)
		(width 0.14224)
		(layer "In13.Cu")
		(net "P5E_CPU1_P2_TX_DP<14>")
	)
	(segment
		(start 125.532642 -273.276314)
		(end 125.615446 -273.359118)
		(width 0.1143)
		(layer "In13.Cu")
		(net "P5E_CPU1_P2_TX_DP<14>")
	)
	(segment
		(start 160.533334 -363.301534)
		(end 160.712658 -363.227366)
		(width 0.14224)
		(layer "In13.Cu")
		(net "P5E_CPU1_P2_TX_DP<14>")
	)
	(segment
		(start 125.895354 -282.507182)
		(end 125.894846 -282.507182)
		(width 0.1143)
		(layer "In13.Cu")
		(net "P5E_CPU1_P2_TX_DP<14>")
	)
	(segment
		(start 125.852682 -293.18077)
		(end 125.890782 -293.203122)
		(width 0.1143)
		(layer "In13.Cu")
		(net "P5E_CPU1_P2_TX_DP<14>")
	)
	(segment
		(start 125.89256 -275.38426)
		(end 125.923548 -275.40204)
		(width 0.1143)
		(layer "In13.Cu")
		(net "P5E_CPU1_P2_TX_DP<14>")
	)
	(segment
		(start 125.89256 -288.9885)
		(end 125.891798 -288.988754)
		(width 0.1143)
		(layer "In13.Cu")
		(net "P5E_CPU1_P2_TX_DP<14>")
	)
	(segment
		(start 125.891798 -289.963606)
		(end 125.89256 -289.964114)
		(width 0.1143)
		(layer "In13.Cu")
		(net "P5E_CPU1_P2_TX_DP<14>")
	)
	(segment
		(start 125.852682 -291.560758)
		(end 125.890782 -291.58311)
		(width 0.1143)
		(layer "In13.Cu")
		(net "P5E_CPU1_P2_TX_DP<14>")
	)
	(segment
		(start 125.894846 -290.606988)
		(end 125.89256 -290.608512)
		(width 0.1143)
		(layer "In13.Cu")
		(net "P5E_CPU1_P2_TX_DP<14>")
	)
	(segment
		(start 125.894846 -282.507182)
		(end 125.89256 -282.508706)
		(width 0.1143)
		(layer "In13.Cu")
		(net "P5E_CPU1_P2_TX_DP<14>")
	)
	(segment
		(start 142.426182 -320.317622)
		(end 143.246348 -322.297806)
		(width 0.14224)
		(layer "In13.Cu")
		(net "P5E_CPU1_P2_TX_DP<14>")
	)
	(segment
		(start 143.246348 -322.297806)
		(end 148.265134 -347.528134)
		(width 0.14224)
		(layer "In13.Cu")
		(net "P5E_CPU1_P2_TX_DP<14>")
	)
	(segment
		(start 125.89256 -278.624284)
		(end 125.923548 -278.642064)
		(width 0.1143)
		(layer "In13.Cu")
		(net "P5E_CPU1_P2_TX_DP<14>")
	)
	(segment
		(start 125.923548 -292.21049)
		(end 125.89256 -292.22827)
		(width 0.1143)
		(layer "In13.Cu")
		(net "P5E_CPU1_P2_TX_DP<14>")
	)
	(segment
		(start 125.890782 -293.203122)
		(end 125.891798 -293.20363)
		(width 0.1143)
		(layer "In13.Cu")
		(net "P5E_CPU1_P2_TX_DP<14>")
	)
	(segment
		(start 125.894338 -294.824912)
		(end 125.924564 -294.842946)
		(width 0.1143)
		(layer "In13.Cu")
		(net "P5E_CPU1_P2_TX_DP<14>")
	)
	(segment
		(start 125.891798 -290.608766)
		(end 125.890782 -290.609274)
		(width 0.1143)
		(layer "In13.Cu")
		(net "P5E_CPU1_P2_TX_DP<14>")
	)
	(segment
		(start 125.89256 -274.408392)
		(end 125.891798 -274.4089)
		(width 0.1143)
		(layer "In13.Cu")
		(net "P5E_CPU1_P2_TX_DP<14>")
	)
	(segment
		(start 125.89256 -285.104332)
		(end 125.894592 -285.105602)
		(width 0.1143)
		(layer "In13.Cu")
		(net "P5E_CPU1_P2_TX_DP<14>")
	)
	(segment
		(start 163.887404 -364.690914)
		(end 164.066728 -364.616746)
		(width 0.14224)
		(layer "In13.Cu")
		(net "P5E_CPU1_P2_TX_DP<14>")
	)
	(segment
		(start 125.860302 -275.365464)
		(end 125.891798 -275.383752)
		(width 0.1143)
		(layer "In13.Cu")
		(net "P5E_CPU1_P2_TX_DP<14>")
	)
	(segment
		(start 125.852682 -285.080964)
		(end 125.890782 -285.103316)
		(width 0.1143)
		(layer "In13.Cu")
		(net "P5E_CPU1_P2_TX_DP<14>")
	)
	(segment
		(start 160.712658 -363.227366)
		(end 162.376612 -363.916468)
		(width 0.14224)
		(layer "In13.Cu")
		(net "P5E_CPU1_P2_TX_DP<14>")
	)
	(segment
		(start 125.85954 -273.744944)
		(end 125.860302 -273.745452)
		(width 0.1143)
		(layer "In13.Cu")
		(net "P5E_CPU1_P2_TX_DP<14>")
	)
	(segment
		(start 125.85954 -275.364956)
		(end 125.860302 -275.365464)
		(width 0.1143)
		(layer "In13.Cu")
		(net "P5E_CPU1_P2_TX_DP<14>")
	)
	(segment
		(start 126.36373 -295.634664)
		(end 126.393448 -295.651936)
		(width 0.1143)
		(layer "In13.Cu")
		(net "P5E_CPU1_P2_TX_DP<14>")
	)
	(segment
		(start 162.451034 -364.096046)
		(end 162.845496 -364.259368)
		(width 0.14224)
		(layer "In13.Cu")
		(net "P5E_CPU1_P2_TX_DP<14>")
	)
	(segment
		(start 138.12012 -312.261504)
		(end 142.426182 -320.317622)
		(width 0.14224)
		(layer "In13.Cu")
		(net "P5E_CPU1_P2_TX_DP<14>")
	)
	(segment
		(start 125.89256 -284.128718)
		(end 125.891798 -284.128972)
		(width 0.1143)
		(layer "In13.Cu")
		(net "P5E_CPU1_P2_TX_DP<14>")
	)
	(segment
		(start 125.894846 -288.345372)
		(end 125.8951 -288.345372)
		(width 0.1143)
		(layer "In13.Cu")
		(net "P5E_CPU1_P2_TX_DP<14>")
	)
	(segment
		(start 125.890782 -290.609274)
		(end 125.852682 -290.631626)
		(width 0.1143)
		(layer "In13.Cu")
		(net "P5E_CPU1_P2_TX_DP<14>")
	)
	(segment
		(start 125.894846 -284.127194)
		(end 125.89256 -284.128718)
		(width 0.1143)
		(layer "In13.Cu")
		(net "P5E_CPU1_P2_TX_DP<14>")
	)
	(segment
		(start 126.549658 -296.2021)
		(end 126.90856 -296.561002)
		(width 0.1143)
		(layer "In13.Cu")
		(net "P5E_CPU1_P2_TX_DP<14>")
	)
	(segment
		(start 125.890782 -285.749492)
		(end 125.852682 -285.771844)
		(width 0.1143)
		(layer "In13.Cu")
		(net "P5E_CPU1_P2_TX_DP<14>")
	)
	(segment
		(start 125.891798 -280.888948)
		(end 125.855476 -280.909776)
		(width 0.1143)
		(layer "In13.Cu")
		(net "P5E_CPU1_P2_TX_DP<14>")
	)
	(segment
		(start 125.85954 -278.60498)
		(end 125.860302 -278.605488)
		(width 0.1143)
		(layer "In13.Cu")
		(net "P5E_CPU1_P2_TX_DP<14>")
	)
	(segment
		(start 126.90856 -296.561002)
		(end 126.90856 -296.776648)
		(width 0.1143)
		(layer "In13.Cu")
		(net "P5E_CPU1_P2_TX_DP<14>")
	)
	(segment
		(start 125.89256 -277.004272)
		(end 125.923548 -277.022052)
		(width 0.1143)
		(layer "In13.Cu")
		(net "P5E_CPU1_P2_TX_DP<14>")
	)
	(segment
		(start 125.894592 -289.965384)
		(end 125.8951 -289.965384)
		(width 0.1143)
		(layer "In13.Cu")
		(net "P5E_CPU1_P2_TX_DP<14>")
	)
	(segment
		(start 126.079504 -287.046162)
		(end 126.079504 -287.050734)
		(width 0.1143)
		(layer "In13.Cu")
		(net "P5E_CPU1_P2_TX_DP<14>")
	)
	(segment
		(start 125.923548 -277.022052)
		(end 125.94336 -277.036276)
		(width 0.1143)
		(layer "In13.Cu")
		(net "P5E_CPU1_P2_TX_DP<14>")
	)
	(segment
		(start 125.894846 -293.847012)
		(end 125.89256 -293.848536)
		(width 0.1143)
		(layer "In13.Cu")
		(net "P5E_CPU1_P2_TX_DP<14>")
	)
	(segment
		(start 171.666662 -370.694204)
		(end 172.001434 -371.503702)
		(width 0.14224)
		(layer "In13.Cu")
		(net "P5E_CPU1_P2_TX_DP<14>")
	)
	(segment
		(start 160.064704 -362.958888)
		(end 160.138872 -363.138212)
		(width 0.14224)
		(layer "In13.Cu")
		(net "P5E_CPU1_P2_TX_DP<14>")
	)
	(segment
		(start 125.895354 -290.606988)
		(end 125.894846 -290.606988)
		(width 0.1143)
		(layer "In13.Cu")
		(net "P5E_CPU1_P2_TX_DP<14>")
	)
	(segment
		(start 126.90856 -296.776648)
		(end 126.86284 -296.822368)
		(width 0.1143)
		(layer "In13.Cu")
		(net "P5E_CPU1_P2_TX_DP<14>")
	)
	(segment
		(start 157.122622 -361.74045)
		(end 160.064704 -362.958888)
		(width 0.14224)
		(layer "In13.Cu")
		(net "P5E_CPU1_P2_TX_DP<14>")
	)
	(segment
		(start 125.890782 -291.58311)
		(end 125.891798 -291.583618)
		(width 0.1143)
		(layer "In13.Cu")
		(net "P5E_CPU1_P2_TX_DP<14>")
	)
	(segment
		(start 171.196254 -376.384058)
		(end 170.905424 -376.093228)
		(width 0.14224)
		(layer "In13.Cu")
		(net "P5E_CPU1_P2_TX_DP<14>")
	)
	(segment
		(start 125.895354 -284.127194)
		(end 125.894846 -284.127194)
		(width 0.1143)
		(layer "In13.Cu")
		(net "P5E_CPU1_P2_TX_DP<14>")
	)
	(segment
		(start 125.887226 -292.231572)
		(end 125.88621 -292.23208)
		(width 0.1143)
		(layer "In13.Cu")
		(net "P5E_CPU1_P2_TX_DP<14>")
	)
	(segment
		(start 125.890782 -282.509468)
		(end 125.852682 -282.53182)
		(width 0.1143)
		(layer "In13.Cu")
		(net "P5E_CPU1_P2_TX_DP<14>")
	)
	(arc
		(start 125.852682 -290.631626)
		(mid 125.609355 -291.096192)
		(end 125.852682 -291.560758)
		(width 0.1143)
		(layer "In13.Cu")
		(net "P5E_CPU1_P2_TX_DP<14>")
	)
	(arc
		(start 125.60935 -287.856422)
		(mid 125.673865 -288.118641)
		(end 125.852682 -288.320988)
		(width 0.1143)
		(layer "In13.Cu")
		(net "P5E_CPU1_P2_TX_DP<14>")
	)
	(arc
		(start 125.8951 -289.965384)
		(mid 126.079833 -290.286076)
		(end 125.895354 -290.606988)
		(width 0.1143)
		(layer "In13.Cu")
		(net "P5E_CPU1_P2_TX_DP<14>")
	)
	(arc
		(start 125.852682 -289.011614)
		(mid 125.609355 -289.47618)
		(end 125.852682 -289.940746)
		(width 0.1143)
		(layer "In13.Cu")
		(net "P5E_CPU1_P2_TX_DP<14>")
	)
	(arc
		(start 172.025818 -371.88902)
		(mid 171.939605 -372.322442)
		(end 171.694094 -372.689882)
		(width 0.14224)
		(layer "In13.Cu")
		(net "P5E_CPU1_P2_TX_DP<14>")
	)
	(arc
		(start 125.615446 -273.359118)
		(mid 125.617234 -273.370567)
		(end 125.619256 -273.381978)
		(width 0.1143)
		(layer "In13.Cu")
		(net "P5E_CPU1_P2_TX_DP<14>")
	)
	(arc
		(start 126.393448 -295.651936)
		(mid 126.429311 -295.681328)
		(end 126.461266 -295.714928)
		(width 0.1143)
		(layer "In13.Cu")
		(net "P5E_CPU1_P2_TX_DP<14>")
	)
	(arc
		(start 125.852682 -284.151832)
		(mid 125.609355 -284.616398)
		(end 125.852682 -285.080964)
		(width 0.1143)
		(layer "In13.Cu")
		(net "P5E_CPU1_P2_TX_DP<14>")
	)
	(arc
		(start 125.8951 -285.105602)
		(mid 126.079833 -285.426294)
		(end 125.895354 -285.747206)
		(width 0.1143)
		(layer "In13.Cu")
		(net "P5E_CPU1_P2_TX_DP<14>")
	)
	(arc
		(start 126.461266 -295.714928)
		(mid 126.526797 -295.827759)
		(end 126.549658 -295.956228)
		(width 0.1143)
		(layer "In13.Cu")
		(net "P5E_CPU1_P2_TX_DP<14>")
	)
	(arc
		(start 125.928628 -291.605462)
		(mid 126.082726 -291.906198)
		(end 125.928628 -292.206934)
		(width 0.1143)
		(layer "In13.Cu")
		(net "P5E_CPU1_P2_TX_DP<14>")
	)
	(arc
		(start 125.852682 -282.53182)
		(mid 125.609355 -282.996386)
		(end 125.852682 -283.460952)
		(width 0.1143)
		(layer "In13.Cu")
		(net "P5E_CPU1_P2_TX_DP<14>")
	)
	(arc
		(start 171.76623 -375.042684)
		(mid 171.888924 -375.378093)
		(end 171.930568 -375.732802)
		(width 0.14224)
		(layer "In13.Cu")
		(net "P5E_CPU1_P2_TX_DP<14>")
	)
	(arc
		(start 125.619256 -273.381978)
		(mid 125.700689 -273.584376)
		(end 125.852682 -273.74088)
		(width 0.1143)
		(layer "In13.Cu")
		(net "P5E_CPU1_P2_TX_DP<14>")
	)
	(arc
		(start 126.079504 -295.141904)
		(mid 126.155658 -295.426326)
		(end 126.36373 -295.634664)
		(width 0.1143)
		(layer "In13.Cu")
		(net "P5E_CPU1_P2_TX_DP<14>")
	)
	(arc
		(start 125.8951 -281.865578)
		(mid 126.079833 -282.18627)
		(end 125.895354 -282.507182)
		(width 0.1143)
		(layer "In13.Cu")
		(net "P5E_CPU1_P2_TX_DP<14>")
	)
	(arc
		(start 125.852682 -292.251638)
		(mid 125.609355 -292.716204)
		(end 125.852682 -293.18077)
		(width 0.1143)
		(layer "In13.Cu")
		(net "P5E_CPU1_P2_TX_DP<14>")
	)
	(arc
		(start 125.8951 -283.48559)
		(mid 126.079833 -283.806282)
		(end 125.895354 -284.127194)
		(width 0.1143)
		(layer "In13.Cu")
		(net "P5E_CPU1_P2_TX_DP<14>")
	)
	(arc
		(start 125.852682 -274.43176)
		(mid 125.609355 -274.896326)
		(end 125.852682 -275.360892)
		(width 0.1143)
		(layer "In13.Cu")
		(net "P5E_CPU1_P2_TX_DP<14>")
	)
	(arc
		(start 171.930568 -376.09653)
		(mid 171.846189 -376.299858)
		(end 171.642786 -376.384058)
		(width 0.14224)
		(layer "In13.Cu")
		(net "P5E_CPU1_P2_TX_DP<14>")
	)
	(arc
		(start 125.8951 -293.205408)
		(mid 126.079833 -293.5261)
		(end 125.895354 -293.847012)
		(width 0.1143)
		(layer "In13.Cu")
		(net "P5E_CPU1_P2_TX_DP<14>")
	)
	(arc
		(start 125.852682 -285.771844)
		(mid 125.609355 -286.23641)
		(end 125.852682 -286.700976)
		(width 0.1143)
		(layer "In13.Cu")
		(net "P5E_CPU1_P2_TX_DP<14>")
	)
	(arc
		(start 125.94336 -278.656288)
		(mid 126.092074 -278.946356)
		(end 125.94336 -279.236424)
		(width 0.1143)
		(layer "In13.Cu")
		(net "P5E_CPU1_P2_TX_DP<14>")
	)
	(arc
		(start 125.925326 -286.743394)
		(mid 126.038733 -286.876283)
		(end 126.079504 -287.046162)
		(width 0.1143)
		(layer "In13.Cu")
		(net "P5E_CPU1_P2_TX_DP<14>")
	)
	(arc
		(start 172.001434 -371.503702)
		(mid 172.019704 -371.564224)
		(end 172.025818 -371.627146)
		(width 0.14224)
		(layer "In13.Cu")
		(net "P5E_CPU1_P2_TX_DP<14>")
	)
	(arc
		(start 125.923548 -273.782028)
		(mid 126.073933 -274.08632)
		(end 125.923548 -274.390612)
		(width 0.1143)
		(layer "In13.Cu")
		(net "P5E_CPU1_P2_TX_DP<14>")
	)
	(arc
		(start 125.852682 -276.051772)
		(mid 125.609355 -276.516338)
		(end 125.852682 -276.980904)
		(width 0.1143)
		(layer "In13.Cu")
		(net "P5E_CPU1_P2_TX_DP<14>")
	)
	(arc
		(start 125.852682 -280.911808)
		(mid 125.609355 -281.376374)
		(end 125.852682 -281.84094)
		(width 0.1143)
		(layer "In13.Cu")
		(net "P5E_CPU1_P2_TX_DP<14>")
	)
	(arc
		(start 125.8951 -288.345372)
		(mid 126.079833 -288.666064)
		(end 125.895354 -288.986976)
		(width 0.1143)
		(layer "In13.Cu")
		(net "P5E_CPU1_P2_TX_DP<14>")
	)
	(arc
		(start 171.607226 -370.582698)
		(mid 171.639628 -370.63702)
		(end 171.666662 -370.694204)
		(width 0.14224)
		(layer "In13.Cu")
		(net "P5E_CPU1_P2_TX_DP<14>")
	)
	(arc
		(start 125.923548 -280.262076)
		(mid 126.073933 -280.566368)
		(end 125.923548 -280.87066)
		(width 0.1143)
		(layer "In13.Cu")
		(net "P5E_CPU1_P2_TX_DP<14>")
	)
	(arc
		(start 125.852682 -279.291796)
		(mid 125.609355 -279.756362)
		(end 125.852682 -280.220928)
		(width 0.1143)
		(layer "In13.Cu")
		(net "P5E_CPU1_P2_TX_DP<14>")
	)
	(arc
		(start 125.852682 -277.671784)
		(mid 125.609355 -278.13635)
		(end 125.852682 -278.600916)
		(width 0.1143)
		(layer "In13.Cu")
		(net "P5E_CPU1_P2_TX_DP<14>")
	)
	(arc
		(start 125.855222 -287.390078)
		(mid 125.67457 -287.592823)
		(end 125.60935 -287.856422)
		(width 0.1143)
		(layer "In13.Cu")
		(net "P5E_CPU1_P2_TX_DP<14>")
	)
	(arc
		(start 125.924564 -294.842946)
		(mid 126.038447 -294.97356)
		(end 126.079504 -295.141904)
		(width 0.1143)
		(layer "In13.Cu")
		(net "P5E_CPU1_P2_TX_DP<14>")
	)
	(arc
		(start 171.54144 -374.099074)
		(mid 171.598436 -374.584078)
		(end 171.76623 -375.042684)
		(width 0.14224)
		(layer "In13.Cu")
		(net "P5E_CPU1_P2_TX_DP<14>")
	)
	(arc
		(start 125.94336 -277.036276)
		(mid 126.092074 -277.326344)
		(end 125.94336 -277.616412)
		(width 0.1143)
		(layer "In13.Cu")
		(net "P5E_CPU1_P2_TX_DP<14>")
	)
	(arc
		(start 169.589196 -367.627916)
		(mid 169.75779 -367.814413)
		(end 169.90695 -368.01679)
		(width 0.14224)
		(layer "In13.Cu")
		(net "P5E_CPU1_P2_TX_DP<14>")
	)
	(arc
		(start 171.694094 -372.689882)
		(mid 171.581085 -372.859107)
		(end 171.54144 -373.05869)
		(width 0.14224)
		(layer "In13.Cu")
		(net "P5E_CPU1_P2_TX_DP<14>")
	)
	(arc
		(start 125.923548 -275.40204)
		(mid 126.075137 -275.706332)
		(end 125.923548 -276.010624)
		(width 0.1143)
		(layer "In13.Cu")
		(net "P5E_CPU1_P2_TX_DP<14>")
	)
	(arc
		(start 126.079504 -287.050734)
		(mid 126.039249 -287.217547)
		(end 125.927358 -287.34766)
		(width 0.1143)
		(layer "In13.Cu")
		(net "P5E_CPU1_P2_TX_DP<14>")
	)
	(arc
		(start 125.852682 -293.87165)
		(mid 125.609355 -294.336216)
		(end 125.852682 -294.800782)
		(width 0.1143)
		(layer "In13.Cu")
		(net "P5E_CPU1_P2_TX_DP<14>")
	)
	(segment
		(start 168.440354 -370.00942)
		(end 168.144444 -370.30533)
		(width 0.12954)
		(layer "F.Cu")
		(net "P5E_CPU1_P2_TX_DP<13>")
	)
	(segment
		(start 168.440354 -369.30584)
		(end 168.440354 -370.00942)
		(width 0.12954)
		(layer "F.Cu")
		(net "P5E_CPU1_P2_TX_DP<13>")
	)
	(segment
		(start 124.767848 -269.770352)
		(end 125.2347 -270.03629)
		(width 0.12954)
		(layer "F.Cu")
		(net "P5E_CPU1_P2_TX_DP<13>")
	)
	(segment
		(start 168.169844 -369.03533)
		(end 168.440354 -369.30584)
		(width 0.12954)
		(layer "F.Cu")
		(net "P5E_CPU1_P2_TX_DP<13>")
	)
	(segment
		(start 124.951744 -293.20363)
		(end 124.952506 -293.204138)
		(width 0.1143)
		(layer "In13.Cu")
		(net "P5E_CPU1_P2_TX_DP<13>")
	)
	(segment
		(start 124.959618 -293.208202)
		(end 124.962158 -293.209472)
		(width 0.1143)
		(layer "In13.Cu")
		(net "P5E_CPU1_P2_TX_DP<13>")
	)
	(segment
		(start 124.953776 -272.144998)
		(end 124.983494 -272.162016)
		(width 0.1143)
		(layer "In13.Cu")
		(net "P5E_CPU1_P2_TX_DP<13>")
	)
	(segment
		(start 124.983494 -277.630636)
		(end 124.952506 -277.648416)
		(width 0.1143)
		(layer "In13.Cu")
		(net "P5E_CPU1_P2_TX_DP<13>")
	)
	(segment
		(start 124.920248 -275.365464)
		(end 124.951744 -275.383752)
		(width 0.1143)
		(layer "In13.Cu")
		(net "P5E_CPU1_P2_TX_DP<13>")
	)
	(segment
		(start 124.945394 -279.272746)
		(end 124.912628 -279.291796)
		(width 0.1143)
		(layer "In13.Cu")
		(net "P5E_CPU1_P2_TX_DP<13>")
	)
	(segment
		(start 147.346416 -347.852492)
		(end 152.142952 -357.381048)
		(width 0.14224)
		(layer "In13.Cu")
		(net "P5E_CPU1_P2_TX_DP<13>")
	)
	(segment
		(start 124.95657 -281.866594)
		(end 124.957332 -281.867102)
		(width 0.1143)
		(layer "In13.Cu")
		(net "P5E_CPU1_P2_TX_DP<13>")
	)
	(segment
		(start 124.948188 -290.610798)
		(end 124.947426 -290.611306)
		(width 0.1143)
		(layer "In13.Cu")
		(net "P5E_CPU1_P2_TX_DP<13>")
	)
	(segment
		(start 124.947426 -274.41144)
		(end 124.946156 -274.412202)
		(width 0.1143)
		(layer "In13.Cu")
		(net "P5E_CPU1_P2_TX_DP<13>")
	)
	(segment
		(start 125.421644 -295.633648)
		(end 125.421898 -295.633648)
		(width 0.1143)
		(layer "In13.Cu")
		(net "P5E_CPU1_P2_TX_DP<13>")
	)
	(segment
		(start 124.950728 -290.609274)
		(end 124.949204 -290.61029)
		(width 0.1143)
		(layer "In13.Cu")
		(net "P5E_CPU1_P2_TX_DP<13>")
	)
	(segment
		(start 124.945394 -272.792698)
		(end 124.912628 -272.811748)
		(width 0.1143)
		(layer "In13.Cu")
		(net "P5E_CPU1_P2_TX_DP<13>")
	)
	(segment
		(start 124.949204 -290.61029)
		(end 124.948188 -290.610798)
		(width 0.1143)
		(layer "In13.Cu")
		(net "P5E_CPU1_P2_TX_DP<13>")
	)
	(segment
		(start 126.33198 -297.913552)
		(end 127.335026 -299.136308)
		(width 0.14224)
		(layer "In13.Cu")
		(net "P5E_CPU1_P2_TX_DP<13>")
	)
	(segment
		(start 124.952506 -275.38426)
		(end 124.953776 -275.385022)
		(width 0.1143)
		(layer "In13.Cu")
		(net "P5E_CPU1_P2_TX_DP<13>")
	)
	(segment
		(start 124.952506 -284.128464)
		(end 124.951744 -284.128972)
		(width 0.1143)
		(layer "In13.Cu")
		(net "P5E_CPU1_P2_TX_DP<13>")
	)
	(segment
		(start 124.953776 -278.625046)
		(end 124.983494 -278.642064)
		(width 0.1143)
		(layer "In13.Cu")
		(net "P5E_CPU1_P2_TX_DP<13>")
	)
	(segment
		(start 125.883924 -296.458386)
		(end 125.883924 -296.792396)
		(width 0.1143)
		(layer "In13.Cu")
		(net "P5E_CPU1_P2_TX_DP<13>")
	)
	(segment
		(start 124.951744 -280.243788)
		(end 124.983494 -280.262076)
		(width 0.1143)
		(layer "In13.Cu")
		(net "P5E_CPU1_P2_TX_DP<13>")
	)
	(segment
		(start 124.952506 -285.748476)
		(end 124.951744 -285.748984)
		(width 0.1143)
		(layer "In13.Cu")
		(net "P5E_CPU1_P2_TX_DP<13>")
	)
	(segment
		(start 124.951744 -285.103824)
		(end 124.952506 -285.104332)
		(width 0.1143)
		(layer "In13.Cu")
		(net "P5E_CPU1_P2_TX_DP<13>")
	)
	(segment
		(start 142.294356 -322.452746)
		(end 147.346416 -347.852492)
		(width 0.14224)
		(layer "In13.Cu")
		(net "P5E_CPU1_P2_TX_DP<13>")
	)
	(segment
		(start 124.947426 -282.5115)
		(end 124.944886 -282.513024)
		(width 0.1143)
		(layer "In13.Cu")
		(net "P5E_CPU1_P2_TX_DP<13>")
	)
	(segment
		(start 124.950728 -280.24328)
		(end 124.951744 -280.243788)
		(width 0.1143)
		(layer "In13.Cu")
		(net "P5E_CPU1_P2_TX_DP<13>")
	)
	(segment
		(start 124.944886 -292.232842)
		(end 124.944124 -292.23335)
		(width 0.1143)
		(layer "In13.Cu")
		(net "P5E_CPU1_P2_TX_DP<13>")
	)
	(segment
		(start 125.838712 -297.043348)
		(end 126.33198 -297.913552)
		(width 0.14224)
		(layer "In13.Cu")
		(net "P5E_CPU1_P2_TX_DP<13>")
	)
	(segment
		(start 124.947426 -277.651464)
		(end 124.946156 -277.652226)
		(width 0.1143)
		(layer "In13.Cu")
		(net "P5E_CPU1_P2_TX_DP<13>")
	)
	(segment
		(start 124.983494 -282.490672)
		(end 124.953776 -282.50769)
		(width 0.1143)
		(layer "In13.Cu")
		(net "P5E_CPU1_P2_TX_DP<13>")
	)
	(segment
		(start 124.912628 -288.320988)
		(end 124.951744 -288.343848)
		(width 0.1143)
		(layer "In13.Cu")
		(net "P5E_CPU1_P2_TX_DP<13>")
	)
	(segment
		(start 124.920248 -289.945318)
		(end 124.951744 -289.963606)
		(width 0.1143)
		(layer "In13.Cu")
		(net "P5E_CPU1_P2_TX_DP<13>")
	)
	(segment
		(start 124.919486 -278.60498)
		(end 124.920248 -278.605488)
		(width 0.1143)
		(layer "In13.Cu")
		(net "P5E_CPU1_P2_TX_DP<13>")
	)
	(segment
		(start 124.950728 -272.789396)
		(end 124.949204 -272.790412)
		(width 0.1143)
		(layer "In13.Cu")
		(net "P5E_CPU1_P2_TX_DP<13>")
	)
	(segment
		(start 124.95657 -293.206424)
		(end 124.957332 -293.206932)
		(width 0.1143)
		(layer "In13.Cu")
		(net "P5E_CPU1_P2_TX_DP<13>")
	)
	(segment
		(start 152.142952 -357.381048)
		(end 153.33345 -359.116122)
		(width 0.14224)
		(layer "In13.Cu")
		(net "P5E_CPU1_P2_TX_DP<13>")
	)
	(segment
		(start 124.946156 -271.172178)
		(end 124.945394 -271.172686)
		(width 0.1143)
		(layer "In13.Cu")
		(net "P5E_CPU1_P2_TX_DP<13>")
	)
	(segment
		(start 124.944124 -285.753556)
		(end 124.912628 -285.771844)
		(width 0.1143)
		(layer "In13.Cu")
		(net "P5E_CPU1_P2_TX_DP<13>")
	)
	(segment
		(start 124.983494 -279.250648)
		(end 124.952506 -279.268428)
		(width 0.1143)
		(layer "In13.Cu")
		(net "P5E_CPU1_P2_TX_DP<13>")
	)
	(segment
		(start 124.952506 -292.22827)
		(end 124.951744 -292.228778)
		(width 0.1143)
		(layer "In13.Cu")
		(net "P5E_CPU1_P2_TX_DP<13>")
	)
	(segment
		(start 124.912628 -272.120868)
		(end 124.919486 -272.124932)
		(width 0.1143)
		(layer "In13.Cu")
		(net "P5E_CPU1_P2_TX_DP<13>")
	)
	(segment
		(start 124.951744 -271.168876)
		(end 124.950728 -271.169384)
		(width 0.1143)
		(layer "In13.Cu")
		(net "P5E_CPU1_P2_TX_DP<13>")
	)
	(segment
		(start 124.950728 -282.509468)
		(end 124.949204 -282.510484)
		(width 0.1143)
		(layer "In13.Cu")
		(net "P5E_CPU1_P2_TX_DP<13>")
	)
	(segment
		(start 124.952506 -285.104332)
		(end 124.953776 -285.105094)
		(width 0.1143)
		(layer "In13.Cu")
		(net "P5E_CPU1_P2_TX_DP<13>")
	)
	(segment
		(start 124.951744 -278.623776)
		(end 124.952506 -278.624284)
		(width 0.1143)
		(layer "In13.Cu")
		(net "P5E_CPU1_P2_TX_DP<13>")
	)
	(segment
		(start 124.952506 -278.624284)
		(end 124.953776 -278.625046)
		(width 0.1143)
		(layer "In13.Cu")
		(net "P5E_CPU1_P2_TX_DP<13>")
	)
	(segment
		(start 124.952506 -294.82415)
		(end 124.953776 -294.824912)
		(width 0.1143)
		(layer "In13.Cu")
		(net "P5E_CPU1_P2_TX_DP<13>")
	)
	(segment
		(start 125.838204 -296.838116)
		(end 125.838204 -296.866056)
		(width 0.1143)
		(layer "In13.Cu")
		(net "P5E_CPU1_P2_TX_DP<13>")
	)
	(segment
		(start 124.920248 -281.845512)
		(end 124.951744 -281.8638)
		(width 0.1143)
		(layer "In13.Cu")
		(net "P5E_CPU1_P2_TX_DP<13>")
	)
	(segment
		(start 124.948188 -282.510992)
		(end 124.947426 -282.5115)
		(width 0.1143)
		(layer "In13.Cu")
		(net "P5E_CPU1_P2_TX_DP<13>")
	)
	(segment
		(start 124.953776 -284.127702)
		(end 124.952506 -284.128464)
		(width 0.1143)
		(layer "In13.Cu")
		(net "P5E_CPU1_P2_TX_DP<13>")
	)
	(segment
		(start 124.953776 -281.86507)
		(end 124.9553 -281.865832)
		(width 0.1143)
		(layer "In13.Cu")
		(net "P5E_CPU1_P2_TX_DP<13>")
	)
	(segment
		(start 124.919486 -289.94481)
		(end 124.920248 -289.945318)
		(width 0.1143)
		(layer "In13.Cu")
		(net "P5E_CPU1_P2_TX_DP<13>")
	)
	(segment
		(start 124.951744 -280.888948)
		(end 124.915422 -280.909776)
		(width 0.1143)
		(layer "In13.Cu")
		(net "P5E_CPU1_P2_TX_DP<13>")
	)
	(segment
		(start 124.912628 -278.600916)
		(end 124.919486 -278.60498)
		(width 0.1143)
		(layer "In13.Cu")
		(net "P5E_CPU1_P2_TX_DP<13>")
	)
	(segment
		(start 124.952506 -277.004272)
		(end 124.953776 -277.005034)
		(width 0.1143)
		(layer "In13.Cu")
		(net "P5E_CPU1_P2_TX_DP<13>")
	)
	(segment
		(start 124.945394 -274.41271)
		(end 124.912628 -274.43176)
		(width 0.1143)
		(layer "In13.Cu")
		(net "P5E_CPU1_P2_TX_DP<13>")
	)
	(segment
		(start 124.919486 -293.184834)
		(end 124.920248 -293.185342)
		(width 0.1143)
		(layer "In13.Cu")
		(net "P5E_CPU1_P2_TX_DP<13>")
	)
	(segment
		(start 124.949966 -280.242772)
		(end 124.950728 -280.24328)
		(width 0.1143)
		(layer "In13.Cu")
		(net "P5E_CPU1_P2_TX_DP<13>")
	)
	(segment
		(start 124.957332 -294.826944)
		(end 124.958348 -294.827452)
		(width 0.1143)
		(layer "In13.Cu")
		(net "P5E_CPU1_P2_TX_DP<13>")
	)
	(segment
		(start 124.949204 -271.1704)
		(end 124.947426 -271.171416)
		(width 0.1143)
		(layer "In13.Cu")
		(net "P5E_CPU1_P2_TX_DP<13>")
	)
	(segment
		(start 124.951744 -288.343848)
		(end 124.985272 -288.363406)
		(width 0.1143)
		(layer "In13.Cu")
		(net "P5E_CPU1_P2_TX_DP<13>")
	)
	(segment
		(start 124.983494 -292.21049)
		(end 124.953776 -292.227508)
		(width 0.1143)
		(layer "In13.Cu")
		(net "P5E_CPU1_P2_TX_DP<13>")
	)
	(segment
		(start 168.081706 -367.611914)
		(end 168.35247 -367.882678)
		(width 0.14224)
		(layer "In13.Cu")
		(net "P5E_CPU1_P2_TX_DP<13>")
	)
	(segment
		(start 124.953776 -288.987484)
		(end 124.952506 -288.988246)
		(width 0.1143)
		(layer "In13.Cu")
		(net "P5E_CPU1_P2_TX_DP<13>")
	)
	(segment
		(start 156.394912 -362.494068)
		(end 157.464506 -363.208824)
		(width 0.14224)
		(layer "In13.Cu")
		(net "P5E_CPU1_P2_TX_DP<13>")
	)
	(segment
		(start 124.912628 -293.18077)
		(end 124.919486 -293.184834)
		(width 0.1143)
		(layer "In13.Cu")
		(net "P5E_CPU1_P2_TX_DP<13>")
	)
	(segment
		(start 124.920248 -278.605488)
		(end 124.951744 -278.623776)
		(width 0.1143)
		(layer "In13.Cu")
		(net "P5E_CPU1_P2_TX_DP<13>")
	)
	(segment
		(start 168.460674 -368.144044)
		(end 168.460674 -368.7445)
		(width 0.14224)
		(layer "In13.Cu")
		(net "P5E_CPU1_P2_TX_DP<13>")
	)
	(segment
		(start 125.883924 -296.792396)
		(end 125.838204 -296.838116)
		(width 0.1143)
		(layer "In13.Cu")
		(net "P5E_CPU1_P2_TX_DP<13>")
	)
	(segment
		(start 124.959618 -294.828214)
		(end 124.962158 -294.829484)
		(width 0.1143)
		(layer "In13.Cu")
		(net "P5E_CPU1_P2_TX_DP<13>")
	)
	(segment
		(start 124.947426 -284.131512)
		(end 124.944886 -284.133036)
		(width 0.1143)
		(layer "In13.Cu")
		(net "P5E_CPU1_P2_TX_DP<13>")
	)
	(segment
		(start 124.947426 -279.271476)
		(end 124.946156 -279.272238)
		(width 0.1143)
		(layer "In13.Cu")
		(net "P5E_CPU1_P2_TX_DP<13>")
	)
	(segment
		(start 124.946156 -279.272238)
		(end 124.945394 -279.272746)
		(width 0.1143)
		(layer "In13.Cu")
		(net "P5E_CPU1_P2_TX_DP<13>")
	)
	(segment
		(start 124.948188 -288.990786)
		(end 124.947426 -288.991294)
		(width 0.1143)
		(layer "In13.Cu")
		(net "P5E_CPU1_P2_TX_DP<13>")
	)
	(segment
		(start 124.951744 -284.128972)
		(end 124.950728 -284.12948)
		(width 0.1143)
		(layer "In13.Cu")
		(net "P5E_CPU1_P2_TX_DP<13>")
	)
	(segment
		(start 157.464506 -363.208824)
		(end 164.640514 -366.181386)
		(width 0.14224)
		(layer "In13.Cu")
		(net "P5E_CPU1_P2_TX_DP<13>")
	)
	(segment
		(start 124.949204 -277.650448)
		(end 124.947426 -277.651464)
		(width 0.1143)
		(layer "In13.Cu")
		(net "P5E_CPU1_P2_TX_DP<13>")
	)
	(segment
		(start 124.951744 -286.723836)
		(end 124.985272 -286.743394)
		(width 0.1143)
		(layer "In13.Cu")
		(net "P5E_CPU1_P2_TX_DP<13>")
	)
	(segment
		(start 124.944886 -282.513024)
		(end 124.944124 -282.513532)
		(width 0.1143)
		(layer "In13.Cu")
		(net "P5E_CPU1_P2_TX_DP<13>")
	)
	(segment
		(start 124.945394 -276.032722)
		(end 124.912628 -276.051772)
		(width 0.1143)
		(layer "In13.Cu")
		(net "P5E_CPU1_P2_TX_DP<13>")
	)
	(segment
		(start 124.952506 -291.584126)
		(end 124.953776 -291.584888)
		(width 0.1143)
		(layer "In13.Cu")
		(net "P5E_CPU1_P2_TX_DP<13>")
	)
	(segment
		(start 124.952506 -293.204138)
		(end 124.953776 -293.2049)
		(width 0.1143)
		(layer "In13.Cu")
		(net "P5E_CPU1_P2_TX_DP<13>")
	)
	(segment
		(start 167.68064 -367.31448)
		(end 168.081706 -367.611914)
		(width 0.14224)
		(layer "In13.Cu")
		(net "P5E_CPU1_P2_TX_DP<13>")
	)
	(segment
		(start 125.421898 -295.633648)
		(end 125.452378 -295.651428)
		(width 0.1143)
		(layer "In13.Cu")
		(net "P5E_CPU1_P2_TX_DP<13>")
	)
	(segment
		(start 124.950728 -285.749492)
		(end 124.949204 -285.750508)
		(width 0.1143)
		(layer "In13.Cu")
		(net "P5E_CPU1_P2_TX_DP<13>")
	)
	(segment
		(start 124.912628 -281.84094)
		(end 124.919486 -281.845004)
		(width 0.1143)
		(layer "In13.Cu")
		(net "P5E_CPU1_P2_TX_DP<13>")
	)
	(segment
		(start 124.9553 -289.965638)
		(end 124.95657 -289.9664)
		(width 0.1143)
		(layer "In13.Cu")
		(net "P5E_CPU1_P2_TX_DP<13>")
	)
	(segment
		(start 124.951744 -282.50896)
		(end 124.950728 -282.509468)
		(width 0.1143)
		(layer "In13.Cu")
		(net "P5E_CPU1_P2_TX_DP<13>")
	)
	(segment
		(start 124.951744 -275.383752)
		(end 124.952506 -275.38426)
		(width 0.1143)
		(layer "In13.Cu")
		(net "P5E_CPU1_P2_TX_DP<13>")
	)
	(segment
		(start 124.983494 -290.590478)
		(end 124.953776 -290.607496)
		(width 0.1143)
		(layer "In13.Cu")
		(net "P5E_CPU1_P2_TX_DP<13>")
	)
	(segment
		(start 124.951744 -288.988754)
		(end 124.950728 -288.989262)
		(width 0.1143)
		(layer "In13.Cu")
		(net "P5E_CPU1_P2_TX_DP<13>")
	)
	(segment
		(start 124.945394 -277.652734)
		(end 124.912628 -277.671784)
		(width 0.1143)
		(layer "In13.Cu")
		(net "P5E_CPU1_P2_TX_DP<13>")
	)
	(segment
		(start 125.838204 -296.866056)
		(end 125.838712 -296.866564)
		(width 0.1143)
		(layer "In13.Cu")
		(net "P5E_CPU1_P2_TX_DP<13>")
	)
	(segment
		(start 124.951744 -287.368742)
		(end 124.915168 -287.390078)
		(width 0.1143)
		(layer "In13.Cu")
		(net "P5E_CPU1_P2_TX_DP<13>")
	)
	(segment
		(start 124.920248 -272.12544)
		(end 124.951744 -272.143728)
		(width 0.1143)
		(layer "In13.Cu")
		(net "P5E_CPU1_P2_TX_DP<13>")
	)
	(segment
		(start 124.948188 -292.23081)
		(end 124.947426 -292.231318)
		(width 0.1143)
		(layer "In13.Cu")
		(net "P5E_CPU1_P2_TX_DP<13>")
	)
	(segment
		(start 124.947426 -272.791428)
		(end 124.946156 -272.79219)
		(width 0.1143)
		(layer "In13.Cu")
		(net "P5E_CPU1_P2_TX_DP<13>")
	)
	(segment
		(start 124.959618 -289.968178)
		(end 124.962158 -289.969448)
		(width 0.1143)
		(layer "In13.Cu")
		(net "P5E_CPU1_P2_TX_DP<13>")
	)
	(segment
		(start 125.838712 -296.866564)
		(end 125.838712 -297.043348)
		(width 0.14224)
		(layer "In13.Cu")
		(net "P5E_CPU1_P2_TX_DP<13>")
	)
	(segment
		(start 124.951744 -283.483812)
		(end 124.952506 -283.48432)
		(width 0.1143)
		(layer "In13.Cu")
		(net "P5E_CPU1_P2_TX_DP<13>")
	)
	(segment
		(start 124.950728 -288.989262)
		(end 124.949204 -288.990278)
		(width 0.1143)
		(layer "In13.Cu")
		(net "P5E_CPU1_P2_TX_DP<13>")
	)
	(segment
		(start 124.952506 -283.48432)
		(end 124.953776 -283.485082)
		(width 0.1143)
		(layer "In13.Cu")
		(net "P5E_CPU1_P2_TX_DP<13>")
	)
	(segment
		(start 124.962158 -293.209472)
		(end 124.983494 -293.221918)
		(width 0.1143)
		(layer "In13.Cu")
		(net "P5E_CPU1_P2_TX_DP<13>")
	)
	(segment
		(start 124.919486 -294.804846)
		(end 124.920248 -294.805354)
		(width 0.1143)
		(layer "In13.Cu")
		(net "P5E_CPU1_P2_TX_DP<13>")
	)
	(segment
		(start 124.9553 -293.205662)
		(end 124.95657 -293.206424)
		(width 0.1143)
		(layer "In13.Cu")
		(net "P5E_CPU1_P2_TX_DP<13>")
	)
	(segment
		(start 124.949204 -272.790412)
		(end 124.947426 -272.791428)
		(width 0.1143)
		(layer "In13.Cu")
		(net "P5E_CPU1_P2_TX_DP<13>")
	)
	(segment
		(start 124.958348 -294.827452)
		(end 124.959618 -294.828214)
		(width 0.1143)
		(layer "In13.Cu")
		(net "P5E_CPU1_P2_TX_DP<13>")
	)
	(segment
		(start 124.951744 -277.003764)
		(end 124.952506 -277.004272)
		(width 0.1143)
		(layer "In13.Cu")
		(net "P5E_CPU1_P2_TX_DP<13>")
	)
	(segment
		(start 124.952506 -272.78838)
		(end 124.951744 -272.788888)
		(width 0.1143)
		(layer "In13.Cu")
		(net "P5E_CPU1_P2_TX_DP<13>")
	)
	(segment
		(start 124.983494 -272.7706)
		(end 124.952506 -272.78838)
		(width 0.1143)
		(layer "In13.Cu")
		(net "P5E_CPU1_P2_TX_DP<13>")
	)
	(segment
		(start 124.953776 -273.76501)
		(end 124.983494 -273.782028)
		(width 0.1143)
		(layer "In13.Cu")
		(net "P5E_CPU1_P2_TX_DP<13>")
	)
	(segment
		(start 124.951744 -272.143728)
		(end 124.952506 -272.144236)
		(width 0.1143)
		(layer "In13.Cu")
		(net "P5E_CPU1_P2_TX_DP<13>")
	)
	(segment
		(start 124.944124 -292.23335)
		(end 124.912628 -292.251638)
		(width 0.1143)
		(layer "In13.Cu")
		(net "P5E_CPU1_P2_TX_DP<13>")
	)
	(segment
		(start 124.951744 -274.4089)
		(end 124.950728 -274.409408)
		(width 0.1143)
		(layer "In13.Cu")
		(net "P5E_CPU1_P2_TX_DP<13>")
	)
	(segment
		(start 137.29843 -312.746898)
		(end 141.631924 -320.853816)
		(width 0.14224)
		(layer "In13.Cu")
		(net "P5E_CPU1_P2_TX_DP<13>")
	)
	(segment
		(start 124.953776 -282.50769)
		(end 124.952506 -282.508452)
		(width 0.1143)
		(layer "In13.Cu")
		(net "P5E_CPU1_P2_TX_DP<13>")
	)
	(segment
		(start 124.953776 -290.607496)
		(end 124.952506 -290.608258)
		(width 0.1143)
		(layer "In13.Cu")
		(net "P5E_CPU1_P2_TX_DP<13>")
	)
	(segment
		(start 124.944124 -282.513532)
		(end 124.912628 -282.53182)
		(width 0.1143)
		(layer "In13.Cu")
		(net "P5E_CPU1_P2_TX_DP<13>")
	)
	(segment
		(start 124.953776 -292.227508)
		(end 124.952506 -292.22827)
		(width 0.1143)
		(layer "In13.Cu")
		(net "P5E_CPU1_P2_TX_DP<13>")
	)
	(segment
		(start 124.952506 -277.648416)
		(end 124.951744 -277.648924)
		(width 0.1143)
		(layer "In13.Cu")
		(net "P5E_CPU1_P2_TX_DP<13>")
	)
	(segment
		(start 124.983494 -271.150588)
		(end 124.952506 -271.168368)
		(width 0.1143)
		(layer "In13.Cu")
		(net "P5E_CPU1_P2_TX_DP<13>")
	)
	(segment
		(start 124.952506 -282.508452)
		(end 124.951744 -282.50896)
		(width 0.1143)
		(layer "In13.Cu")
		(net "P5E_CPU1_P2_TX_DP<13>")
	)
	(segment
		(start 124.951744 -289.963606)
		(end 124.952506 -289.964114)
		(width 0.1143)
		(layer "In13.Cu")
		(net "P5E_CPU1_P2_TX_DP<13>")
	)
	(segment
		(start 124.951744 -292.228778)
		(end 124.950728 -292.229286)
		(width 0.1143)
		(layer "In13.Cu")
		(net "P5E_CPU1_P2_TX_DP<13>")
	)
	(segment
		(start 124.959618 -281.868372)
		(end 124.962158 -281.869642)
		(width 0.1143)
		(layer "In13.Cu")
		(net "P5E_CPU1_P2_TX_DP<13>")
	)
	(segment
		(start 124.947426 -276.031452)
		(end 124.946156 -276.032214)
		(width 0.1143)
		(layer "In13.Cu")
		(net "P5E_CPU1_P2_TX_DP<13>")
	)
	(segment
		(start 124.983494 -287.350454)
		(end 124.951744 -287.368742)
		(width 0.1143)
		(layer "In13.Cu")
		(net "P5E_CPU1_P2_TX_DP<13>")
	)
	(segment
		(start 124.951744 -294.823642)
		(end 124.952506 -294.82415)
		(width 0.1143)
		(layer "In13.Cu")
		(net "P5E_CPU1_P2_TX_DP<13>")
	)
	(segment
		(start 124.912628 -294.800782)
		(end 124.919486 -294.804846)
		(width 0.1143)
		(layer "In13.Cu")
		(net "P5E_CPU1_P2_TX_DP<13>")
	)
	(segment
		(start 125.452378 -270.34109)
		(end 125.421898 -270.35887)
		(width 0.1143)
		(layer "In13.Cu")
		(net "P5E_CPU1_P2_TX_DP<13>")
	)
	(segment
		(start 124.919486 -273.744944)
		(end 124.920248 -273.745452)
		(width 0.1143)
		(layer "In13.Cu")
		(net "P5E_CPU1_P2_TX_DP<13>")
	)
	(segment
		(start 124.951744 -290.608766)
		(end 124.950728 -290.609274)
		(width 0.1143)
		(layer "In13.Cu")
		(net "P5E_CPU1_P2_TX_DP<13>")
	)
	(segment
		(start 124.951744 -273.76374)
		(end 124.952506 -273.764248)
		(width 0.1143)
		(layer "In13.Cu")
		(net "P5E_CPU1_P2_TX_DP<13>")
	)
	(segment
		(start 124.944124 -288.993326)
		(end 124.912628 -289.011614)
		(width 0.1143)
		(layer "In13.Cu")
		(net "P5E_CPU1_P2_TX_DP<13>")
	)
	(segment
		(start 124.983494 -288.970466)
		(end 124.953776 -288.987484)
		(width 0.1143)
		(layer "In13.Cu")
		(net "P5E_CPU1_P2_TX_DP<13>")
	)
	(segment
		(start 124.944124 -284.133544)
		(end 124.912628 -284.151832)
		(width 0.1143)
		(layer "In13.Cu")
		(net "P5E_CPU1_P2_TX_DP<13>")
	)
	(segment
		(start 127.335026 -299.136308)
		(end 136.10336 -310.958738)
		(width 0.14224)
		(layer "In13.Cu")
		(net "P5E_CPU1_P2_TX_DP<13>")
	)
	(segment
		(start 124.950728 -276.02942)
		(end 124.949204 -276.030436)
		(width 0.1143)
		(layer "In13.Cu")
		(net "P5E_CPU1_P2_TX_DP<13>")
	)
	(segment
		(start 124.949204 -276.030436)
		(end 124.947426 -276.031452)
		(width 0.1143)
		(layer "In13.Cu")
		(net "P5E_CPU1_P2_TX_DP<13>")
	)
	(segment
		(start 124.953776 -293.2049)
		(end 124.9553 -293.205662)
		(width 0.1143)
		(layer "In13.Cu")
		(net "P5E_CPU1_P2_TX_DP<13>")
	)
	(segment
		(start 124.919486 -272.124932)
		(end 124.920248 -272.12544)
		(width 0.1143)
		(layer "In13.Cu")
		(net "P5E_CPU1_P2_TX_DP<13>")
	)
	(segment
		(start 124.951744 -272.788888)
		(end 124.950728 -272.789396)
		(width 0.1143)
		(layer "In13.Cu")
		(net "P5E_CPU1_P2_TX_DP<13>")
	)
	(segment
		(start 124.920248 -276.985476)
		(end 124.951744 -277.003764)
		(width 0.1143)
		(layer "In13.Cu")
		(net "P5E_CPU1_P2_TX_DP<13>")
	)
	(segment
		(start 124.949204 -279.27046)
		(end 124.947426 -279.271476)
		(width 0.1143)
		(layer "In13.Cu")
		(net "P5E_CPU1_P2_TX_DP<13>")
	)
	(segment
		(start 124.944886 -288.992818)
		(end 124.944124 -288.993326)
		(width 0.1143)
		(layer "In13.Cu")
		(net "P5E_CPU1_P2_TX_DP<13>")
	)
	(segment
		(start 124.950728 -292.229286)
		(end 124.949204 -292.230302)
		(width 0.1143)
		(layer "In13.Cu")
		(net "P5E_CPU1_P2_TX_DP<13>")
	)
	(segment
		(start 124.983494 -284.110684)
		(end 124.953776 -284.127702)
		(width 0.1143)
		(layer "In13.Cu")
		(net "P5E_CPU1_P2_TX_DP<13>")
	)
	(segment
		(start 125.421898 -270.35887)
		(end 125.382782 -270.38173)
		(width 0.1143)
		(layer "In13.Cu")
		(net "P5E_CPU1_P2_TX_DP<13>")
	)
	(segment
		(start 124.953776 -277.005034)
		(end 124.983494 -277.022052)
		(width 0.1143)
		(layer "In13.Cu")
		(net "P5E_CPU1_P2_TX_DP<13>")
	)
	(segment
		(start 124.952506 -276.028404)
		(end 124.951744 -276.028912)
		(width 0.1143)
		(layer "In13.Cu")
		(net "P5E_CPU1_P2_TX_DP<13>")
	)
	(segment
		(start 124.95657 -294.826436)
		(end 124.957332 -294.826944)
		(width 0.1143)
		(layer "In13.Cu")
		(net "P5E_CPU1_P2_TX_DP<13>")
	)
	(segment
		(start 124.950728 -283.483304)
		(end 124.951744 -283.483812)
		(width 0.1143)
		(layer "In13.Cu")
		(net "P5E_CPU1_P2_TX_DP<13>")
	)
	(segment
		(start 124.919486 -281.845004)
		(end 124.920248 -281.845512)
		(width 0.1143)
		(layer "In13.Cu")
		(net "P5E_CPU1_P2_TX_DP<13>")
	)
	(segment
		(start 124.944124 -290.613338)
		(end 124.912628 -290.631626)
		(width 0.1143)
		(layer "In13.Cu")
		(net "P5E_CPU1_P2_TX_DP<13>")
	)
	(segment
		(start 124.912628 -275.360892)
		(end 124.919486 -275.364956)
		(width 0.1143)
		(layer "In13.Cu")
		(net "P5E_CPU1_P2_TX_DP<13>")
	)
	(segment
		(start 124.951744 -291.583618)
		(end 124.952506 -291.584126)
		(width 0.1143)
		(layer "In13.Cu")
		(net "P5E_CPU1_P2_TX_DP<13>")
	)
	(segment
		(start 124.950728 -279.269444)
		(end 124.949204 -279.27046)
		(width 0.1143)
		(layer "In13.Cu")
		(net "P5E_CPU1_P2_TX_DP<13>")
	)
	(segment
		(start 124.953776 -294.824912)
		(end 124.9553 -294.825674)
		(width 0.1143)
		(layer "In13.Cu")
		(net "P5E_CPU1_P2_TX_DP<13>")
	)
	(segment
		(start 124.951744 -281.8638)
		(end 124.952506 -281.864308)
		(width 0.1143)
		(layer "In13.Cu")
		(net "P5E_CPU1_P2_TX_DP<13>")
	)
	(segment
		(start 124.912628 -286.700976)
		(end 124.951744 -286.723836)
		(width 0.1143)
		(layer "In13.Cu")
		(net "P5E_CPU1_P2_TX_DP<13>")
	)
	(segment
		(start 124.952506 -272.144236)
		(end 124.953776 -272.144998)
		(width 0.1143)
		(layer "In13.Cu")
		(net "P5E_CPU1_P2_TX_DP<13>")
	)
	(segment
		(start 124.983494 -274.390612)
		(end 124.952506 -274.408392)
		(width 0.1143)
		(layer "In13.Cu")
		(net "P5E_CPU1_P2_TX_DP<13>")
	)
	(segment
		(start 125.532642 -270.03629)
		(end 125.602492 -270.10614)
		(width 0.1143)
		(layer "In13.Cu")
		(net "P5E_CPU1_P2_TX_DP<13>")
	)
	(segment
		(start 124.950728 -274.409408)
		(end 124.949204 -274.410424)
		(width 0.1143)
		(layer "In13.Cu")
		(net "P5E_CPU1_P2_TX_DP<13>")
	)
	(segment
		(start 124.920248 -273.745452)
		(end 124.951744 -273.76374)
		(width 0.1143)
		(layer "In13.Cu")
		(net "P5E_CPU1_P2_TX_DP<13>")
	)
	(segment
		(start 124.952506 -273.764248)
		(end 124.953776 -273.76501)
		(width 0.1143)
		(layer "In13.Cu")
		(net "P5E_CPU1_P2_TX_DP<13>")
	)
	(segment
		(start 124.912628 -283.460952)
		(end 124.950728 -283.483304)
		(width 0.1143)
		(layer "In13.Cu")
		(net "P5E_CPU1_P2_TX_DP<13>")
	)
	(segment
		(start 124.952506 -279.268428)
		(end 124.951744 -279.268936)
		(width 0.1143)
		(layer "In13.Cu")
		(net "P5E_CPU1_P2_TX_DP<13>")
	)
	(segment
		(start 124.962158 -289.969448)
		(end 124.983494 -289.981894)
		(width 0.1143)
		(layer "In13.Cu")
		(net "P5E_CPU1_P2_TX_DP<13>")
	)
	(segment
		(start 124.912628 -280.220928)
		(end 124.949966 -280.242772)
		(width 0.1143)
		(layer "In13.Cu")
		(net "P5E_CPU1_P2_TX_DP<13>")
	)
	(segment
		(start 124.947426 -285.751524)
		(end 124.944886 -285.753048)
		(width 0.1143)
		(layer "In13.Cu")
		(net "P5E_CPU1_P2_TX_DP<13>")
	)
	(segment
		(start 124.958348 -289.967416)
		(end 124.959618 -289.968178)
		(width 0.1143)
		(layer "In13.Cu")
		(net "P5E_CPU1_P2_TX_DP<13>")
	)
	(segment
		(start 124.983494 -276.010624)
		(end 124.952506 -276.028404)
		(width 0.1143)
		(layer "In13.Cu")
		(net "P5E_CPU1_P2_TX_DP<13>")
	)
	(segment
		(start 124.951744 -279.268936)
		(end 124.950728 -279.269444)
		(width 0.1143)
		(layer "In13.Cu")
		(net "P5E_CPU1_P2_TX_DP<13>")
	)
	(segment
		(start 124.946156 -272.79219)
		(end 124.945394 -272.792698)
		(width 0.1143)
		(layer "In13.Cu")
		(net "P5E_CPU1_P2_TX_DP<13>")
	)
	(segment
		(start 168.460674 -368.7445)
		(end 168.169844 -369.03533)
		(width 0.14224)
		(layer "In13.Cu")
		(net "P5E_CPU1_P2_TX_DP<13>")
	)
	(segment
		(start 124.912628 -291.560758)
		(end 124.950728 -291.58311)
		(width 0.1143)
		(layer "In13.Cu")
		(net "P5E_CPU1_P2_TX_DP<13>")
	)
	(segment
		(start 124.950728 -271.169384)
		(end 124.949204 -271.1704)
		(width 0.1143)
		(layer "In13.Cu")
		(net "P5E_CPU1_P2_TX_DP<13>")
	)
	(segment
		(start 124.912628 -273.74088)
		(end 124.919486 -273.744944)
		(width 0.1143)
		(layer "In13.Cu")
		(net "P5E_CPU1_P2_TX_DP<13>")
	)
	(segment
		(start 124.953776 -291.584888)
		(end 124.983494 -291.601906)
		(width 0.1143)
		(layer "In13.Cu")
		(net "P5E_CPU1_P2_TX_DP<13>")
	)
	(segment
		(start 124.952506 -281.864308)
		(end 124.953776 -281.86507)
		(width 0.1143)
		(layer "In13.Cu")
		(net "P5E_CPU1_P2_TX_DP<13>")
	)
	(segment
		(start 124.952506 -271.168368)
		(end 124.951744 -271.168876)
		(width 0.1143)
		(layer "In13.Cu")
		(net "P5E_CPU1_P2_TX_DP<13>")
	)
	(segment
		(start 124.951744 -276.028912)
		(end 124.950728 -276.02942)
		(width 0.1143)
		(layer "In13.Cu")
		(net "P5E_CPU1_P2_TX_DP<13>")
	)
	(segment
		(start 124.950728 -293.849298)
		(end 124.949204 -293.850314)
		(width 0.1143)
		(layer "In13.Cu")
		(net "P5E_CPU1_P2_TX_DP<13>")
	)
	(segment
		(start 124.950728 -285.103316)
		(end 124.951744 -285.103824)
		(width 0.1143)
		(layer "In13.Cu")
		(net "P5E_CPU1_P2_TX_DP<13>")
	)
	(segment
		(start 164.640514 -366.181386)
		(end 167.42537 -367.178082)
		(width 0.14224)
		(layer "In13.Cu")
		(net "P5E_CPU1_P2_TX_DP<13>")
	)
	(segment
		(start 124.962158 -281.869642)
		(end 124.983494 -281.882088)
		(width 0.1143)
		(layer "In13.Cu")
		(net "P5E_CPU1_P2_TX_DP<13>")
	)
	(segment
		(start 124.9553 -281.865832)
		(end 124.95657 -281.866594)
		(width 0.1143)
		(layer "In13.Cu")
		(net "P5E_CPU1_P2_TX_DP<13>")
	)
	(segment
		(start 167.42537 -367.178082)
		(end 167.68064 -367.31448)
		(width 0.14224)
		(layer "In13.Cu")
		(net "P5E_CPU1_P2_TX_DP<13>")
	)
	(segment
		(start 124.952506 -289.964114)
		(end 124.953776 -289.964876)
		(width 0.1143)
		(layer "In13.Cu")
		(net "P5E_CPU1_P2_TX_DP<13>")
	)
	(segment
		(start 124.958348 -281.86761)
		(end 124.959618 -281.868372)
		(width 0.1143)
		(layer "In13.Cu")
		(net "P5E_CPU1_P2_TX_DP<13>")
	)
	(segment
		(start 124.946156 -274.412202)
		(end 124.945394 -274.41271)
		(width 0.1143)
		(layer "In13.Cu")
		(net "P5E_CPU1_P2_TX_DP<13>")
	)
	(segment
		(start 124.958348 -293.20744)
		(end 124.959618 -293.208202)
		(width 0.1143)
		(layer "In13.Cu")
		(net "P5E_CPU1_P2_TX_DP<13>")
	)
	(segment
		(start 124.949204 -274.410424)
		(end 124.947426 -274.41144)
		(width 0.1143)
		(layer "In13.Cu")
		(net "P5E_CPU1_P2_TX_DP<13>")
	)
	(segment
		(start 124.920248 -294.805354)
		(end 124.951744 -294.823642)
		(width 0.1143)
		(layer "In13.Cu")
		(net "P5E_CPU1_P2_TX_DP<13>")
	)
	(segment
		(start 124.946156 -276.032214)
		(end 124.945394 -276.032722)
		(width 0.1143)
		(layer "In13.Cu")
		(net "P5E_CPU1_P2_TX_DP<13>")
	)
	(segment
		(start 124.920248 -293.185342)
		(end 124.951744 -293.20363)
		(width 0.1143)
		(layer "In13.Cu")
		(net "P5E_CPU1_P2_TX_DP<13>")
	)
	(segment
		(start 124.95657 -289.9664)
		(end 124.957332 -289.966908)
		(width 0.1143)
		(layer "In13.Cu")
		(net "P5E_CPU1_P2_TX_DP<13>")
	)
	(segment
		(start 124.9553 -294.825674)
		(end 124.95657 -294.826436)
		(width 0.1143)
		(layer "In13.Cu")
		(net "P5E_CPU1_P2_TX_DP<13>")
	)
	(segment
		(start 124.948188 -284.131004)
		(end 124.947426 -284.131512)
		(width 0.1143)
		(layer "In13.Cu")
		(net "P5E_CPU1_P2_TX_DP<13>")
	)
	(segment
		(start 124.947426 -271.171416)
		(end 124.946156 -271.172178)
		(width 0.1143)
		(layer "In13.Cu")
		(net "P5E_CPU1_P2_TX_DP<13>")
	)
	(segment
		(start 124.944886 -290.61283)
		(end 124.944124 -290.613338)
		(width 0.1143)
		(layer "In13.Cu")
		(net "P5E_CPU1_P2_TX_DP<13>")
	)
	(segment
		(start 124.953776 -283.485082)
		(end 124.983494 -283.5021)
		(width 0.1143)
		(layer "In13.Cu")
		(net "P5E_CPU1_P2_TX_DP<13>")
	)
	(segment
		(start 124.948188 -285.751016)
		(end 124.947426 -285.751524)
		(width 0.1143)
		(layer "In13.Cu")
		(net "P5E_CPU1_P2_TX_DP<13>")
	)
	(segment
		(start 124.949204 -285.750508)
		(end 124.948188 -285.751016)
		(width 0.1143)
		(layer "In13.Cu")
		(net "P5E_CPU1_P2_TX_DP<13>")
	)
	(segment
		(start 124.949204 -284.130496)
		(end 124.948188 -284.131004)
		(width 0.1143)
		(layer "In13.Cu")
		(net "P5E_CPU1_P2_TX_DP<13>")
	)
	(segment
		(start 141.631924 -320.853816)
		(end 142.294356 -322.452746)
		(width 0.14224)
		(layer "In13.Cu")
		(net "P5E_CPU1_P2_TX_DP<13>")
	)
	(segment
		(start 124.919486 -275.364956)
		(end 124.920248 -275.365464)
		(width 0.1143)
		(layer "In13.Cu")
		(net "P5E_CPU1_P2_TX_DP<13>")
	)
	(segment
		(start 124.953776 -289.964876)
		(end 124.9553 -289.965638)
		(width 0.1143)
		(layer "In13.Cu")
		(net "P5E_CPU1_P2_TX_DP<13>")
	)
	(segment
		(start 125.609604 -296.184066)
		(end 125.883924 -296.458386)
		(width 0.1143)
		(layer "In13.Cu")
		(net "P5E_CPU1_P2_TX_DP<13>")
	)
	(segment
		(start 153.33345 -359.116122)
		(end 156.394912 -362.494068)
		(width 0.14224)
		(layer "In13.Cu")
		(net "P5E_CPU1_P2_TX_DP<13>")
	)
	(segment
		(start 124.944886 -285.753048)
		(end 124.944124 -285.753556)
		(width 0.1143)
		(layer "In13.Cu")
		(net "P5E_CPU1_P2_TX_DP<13>")
	)
	(segment
		(start 124.912628 -276.980904)
		(end 124.919486 -276.984968)
		(width 0.1143)
		(layer "In13.Cu")
		(net "P5E_CPU1_P2_TX_DP<13>")
	)
	(segment
		(start 124.949204 -293.850314)
		(end 124.912628 -293.87165)
		(width 0.1143)
		(layer "In13.Cu")
		(net "P5E_CPU1_P2_TX_DP<13>")
	)
	(segment
		(start 124.983494 -285.730696)
		(end 124.953776 -285.747714)
		(width 0.1143)
		(layer "In13.Cu")
		(net "P5E_CPU1_P2_TX_DP<13>")
	)
	(segment
		(start 124.983494 -293.830502)
		(end 124.951744 -293.84879)
		(width 0.1143)
		(layer "In13.Cu")
		(net "P5E_CPU1_P2_TX_DP<13>")
	)
	(segment
		(start 124.957332 -281.867102)
		(end 124.958348 -281.86761)
		(width 0.1143)
		(layer "In13.Cu")
		(net "P5E_CPU1_P2_TX_DP<13>")
	)
	(segment
		(start 124.947426 -290.611306)
		(end 124.944886 -290.61283)
		(width 0.1143)
		(layer "In13.Cu")
		(net "P5E_CPU1_P2_TX_DP<13>")
	)
	(segment
		(start 125.2347 -270.03629)
		(end 125.532642 -270.03629)
		(width 0.1143)
		(layer "In13.Cu")
		(net "P5E_CPU1_P2_TX_DP<13>")
	)
	(segment
		(start 124.950728 -284.12948)
		(end 124.949204 -284.130496)
		(width 0.1143)
		(layer "In13.Cu")
		(net "P5E_CPU1_P2_TX_DP<13>")
	)
	(segment
		(start 124.912628 -289.940746)
		(end 124.919486 -289.94481)
		(width 0.1143)
		(layer "In13.Cu")
		(net "P5E_CPU1_P2_TX_DP<13>")
	)
	(segment
		(start 124.951744 -293.84879)
		(end 124.950728 -293.849298)
		(width 0.1143)
		(layer "In13.Cu")
		(net "P5E_CPU1_P2_TX_DP<13>")
	)
	(segment
		(start 124.949204 -288.990278)
		(end 124.948188 -288.990786)
		(width 0.1143)
		(layer "In13.Cu")
		(net "P5E_CPU1_P2_TX_DP<13>")
	)
	(segment
		(start 124.957332 -289.966908)
		(end 124.958348 -289.967416)
		(width 0.1143)
		(layer "In13.Cu")
		(net "P5E_CPU1_P2_TX_DP<13>")
	)
	(segment
		(start 124.946156 -277.652226)
		(end 124.945394 -277.652734)
		(width 0.1143)
		(layer "In13.Cu")
		(net "P5E_CPU1_P2_TX_DP<13>")
	)
	(segment
		(start 124.952506 -274.408392)
		(end 124.951744 -274.4089)
		(width 0.1143)
		(layer "In13.Cu")
		(net "P5E_CPU1_P2_TX_DP<13>")
	)
	(segment
		(start 124.915422 -280.909776)
		(end 124.912628 -280.911808)
		(width 0.1143)
		(layer "In13.Cu")
		(net "P5E_CPU1_P2_TX_DP<13>")
	)
	(segment
		(start 124.983494 -280.87066)
		(end 124.951744 -280.888948)
		(width 0.1143)
		(layer "In13.Cu")
		(net "P5E_CPU1_P2_TX_DP<13>")
	)
	(segment
		(start 136.10336 -310.958738)
		(end 137.29843 -312.746898)
		(width 0.14224)
		(layer "In13.Cu")
		(net "P5E_CPU1_P2_TX_DP<13>")
	)
	(segment
		(start 124.945394 -271.172686)
		(end 124.912628 -271.191736)
		(width 0.1143)
		(layer "In13.Cu")
		(net "P5E_CPU1_P2_TX_DP<13>")
	)
	(segment
		(start 124.912628 -285.080964)
		(end 124.950728 -285.103316)
		(width 0.1143)
		(layer "In13.Cu")
		(net "P5E_CPU1_P2_TX_DP<13>")
	)
	(segment
		(start 124.952506 -290.608258)
		(end 124.951744 -290.608766)
		(width 0.1143)
		(layer "In13.Cu")
		(net "P5E_CPU1_P2_TX_DP<13>")
	)
	(segment
		(start 124.949204 -292.230302)
		(end 124.948188 -292.23081)
		(width 0.1143)
		(layer "In13.Cu")
		(net "P5E_CPU1_P2_TX_DP<13>")
	)
	(segment
		(start 125.609604 -295.956228)
		(end 125.609604 -296.184066)
		(width 0.1143)
		(layer "In13.Cu")
		(net "P5E_CPU1_P2_TX_DP<13>")
	)
	(segment
		(start 124.953776 -275.385022)
		(end 124.983494 -275.40204)
		(width 0.1143)
		(layer "In13.Cu")
		(net "P5E_CPU1_P2_TX_DP<13>")
	)
	(segment
		(start 124.949204 -282.510484)
		(end 124.948188 -282.510992)
		(width 0.1143)
		(layer "In13.Cu")
		(net "P5E_CPU1_P2_TX_DP<13>")
	)
	(segment
		(start 124.919486 -276.984968)
		(end 124.920248 -276.985476)
		(width 0.1143)
		(layer "In13.Cu")
		(net "P5E_CPU1_P2_TX_DP<13>")
	)
	(segment
		(start 124.952506 -288.988246)
		(end 124.951744 -288.988754)
		(width 0.1143)
		(layer "In13.Cu")
		(net "P5E_CPU1_P2_TX_DP<13>")
	)
	(segment
		(start 124.944886 -284.133036)
		(end 124.944124 -284.133544)
		(width 0.1143)
		(layer "In13.Cu")
		(net "P5E_CPU1_P2_TX_DP<13>")
	)
	(segment
		(start 124.950728 -291.58311)
		(end 124.951744 -291.583618)
		(width 0.1143)
		(layer "In13.Cu")
		(net "P5E_CPU1_P2_TX_DP<13>")
	)
	(segment
		(start 124.953776 -285.105094)
		(end 124.983494 -285.122112)
		(width 0.1143)
		(layer "In13.Cu")
		(net "P5E_CPU1_P2_TX_DP<13>")
	)
	(segment
		(start 124.947426 -288.991294)
		(end 124.944886 -288.992818)
		(width 0.1143)
		(layer "In13.Cu")
		(net "P5E_CPU1_P2_TX_DP<13>")
	)
	(segment
		(start 124.957332 -293.206932)
		(end 124.958348 -293.20744)
		(width 0.1143)
		(layer "In13.Cu")
		(net "P5E_CPU1_P2_TX_DP<13>")
	)
	(segment
		(start 124.953776 -285.747714)
		(end 124.952506 -285.748476)
		(width 0.1143)
		(layer "In13.Cu")
		(net "P5E_CPU1_P2_TX_DP<13>")
	)
	(segment
		(start 125.384052 -295.611804)
		(end 125.421644 -295.633648)
		(width 0.1143)
		(layer "In13.Cu")
		(net "P5E_CPU1_P2_TX_DP<13>")
	)
	(segment
		(start 124.950728 -277.649432)
		(end 124.949204 -277.650448)
		(width 0.1143)
		(layer "In13.Cu")
		(net "P5E_CPU1_P2_TX_DP<13>")
	)
	(segment
		(start 124.951744 -285.748984)
		(end 124.950728 -285.749492)
		(width 0.1143)
		(layer "In13.Cu")
		(net "P5E_CPU1_P2_TX_DP<13>")
	)
	(segment
		(start 124.947426 -292.231318)
		(end 124.944886 -292.232842)
		(width 0.1143)
		(layer "In13.Cu")
		(net "P5E_CPU1_P2_TX_DP<13>")
	)
	(segment
		(start 124.962158 -294.829484)
		(end 124.983494 -294.84193)
		(width 0.1143)
		(layer "In13.Cu")
		(net "P5E_CPU1_P2_TX_DP<13>")
	)
	(segment
		(start 124.951744 -277.648924)
		(end 124.950728 -277.649432)
		(width 0.1143)
		(layer "In13.Cu")
		(net "P5E_CPU1_P2_TX_DP<13>")
	)
	(arc
		(start 124.912628 -271.191736)
		(mid 124.669301 -271.656302)
		(end 124.912628 -272.120868)
		(width 0.1143)
		(layer "In13.Cu")
		(net "P5E_CPU1_P2_TX_DP<13>")
	)
	(arc
		(start 124.912628 -293.87165)
		(mid 124.669301 -294.336216)
		(end 124.912628 -294.800782)
		(width 0.1143)
		(layer "In13.Cu")
		(net "P5E_CPU1_P2_TX_DP<13>")
	)
	(arc
		(start 124.912628 -289.011614)
		(mid 124.669301 -289.47618)
		(end 124.912628 -289.940746)
		(width 0.1143)
		(layer "In13.Cu")
		(net "P5E_CPU1_P2_TX_DP<13>")
	)
	(arc
		(start 125.382782 -270.38173)
		(mid 125.203969 -270.58408)
		(end 125.13945 -270.846296)
		(width 0.1143)
		(layer "In13.Cu")
		(net "P5E_CPU1_P2_TX_DP<13>")
	)
	(arc
		(start 125.13945 -287.046162)
		(mid 125.098195 -287.217133)
		(end 124.983494 -287.350454)
		(width 0.1143)
		(layer "In13.Cu")
		(net "P5E_CPU1_P2_TX_DP<13>")
	)
	(arc
		(start 124.983494 -291.601906)
		(mid 125.139422 -291.906198)
		(end 124.983494 -292.21049)
		(width 0.1143)
		(layer "In13.Cu")
		(net "P5E_CPU1_P2_TX_DP<13>")
	)
	(arc
		(start 124.983494 -289.981894)
		(mid 125.139422 -290.286186)
		(end 124.983494 -290.590478)
		(width 0.1143)
		(layer "In13.Cu")
		(net "P5E_CPU1_P2_TX_DP<13>")
	)
	(arc
		(start 124.912628 -290.631626)
		(mid 124.669301 -291.096192)
		(end 124.912628 -291.560758)
		(width 0.1143)
		(layer "In13.Cu")
		(net "P5E_CPU1_P2_TX_DP<13>")
	)
	(arc
		(start 124.985272 -288.363406)
		(mid 125.098679 -288.496295)
		(end 125.13945 -288.666174)
		(width 0.1143)
		(layer "In13.Cu")
		(net "P5E_CPU1_P2_TX_DP<13>")
	)
	(arc
		(start 124.915168 -287.390078)
		(mid 124.734516 -287.592823)
		(end 124.669296 -287.856422)
		(width 0.1143)
		(layer "In13.Cu")
		(net "P5E_CPU1_P2_TX_DP<13>")
	)
	(arc
		(start 125.602492 -270.10614)
		(mid 125.550075 -270.238071)
		(end 125.452378 -270.34109)
		(width 0.1143)
		(layer "In13.Cu")
		(net "P5E_CPU1_P2_TX_DP<13>")
	)
	(arc
		(start 124.912628 -272.811748)
		(mid 124.669301 -273.276314)
		(end 124.912628 -273.74088)
		(width 0.1143)
		(layer "In13.Cu")
		(net "P5E_CPU1_P2_TX_DP<13>")
	)
	(arc
		(start 124.983494 -273.782028)
		(mid 125.139422 -274.08632)
		(end 124.983494 -274.390612)
		(width 0.1143)
		(layer "In13.Cu")
		(net "P5E_CPU1_P2_TX_DP<13>")
	)
	(arc
		(start 124.669296 -287.856422)
		(mid 124.733811 -288.118641)
		(end 124.912628 -288.320988)
		(width 0.1143)
		(layer "In13.Cu")
		(net "P5E_CPU1_P2_TX_DP<13>")
	)
	(arc
		(start 125.468888 -295.664128)
		(mid 125.572538 -295.794149)
		(end 125.609604 -295.956228)
		(width 0.1143)
		(layer "In13.Cu")
		(net "P5E_CPU1_P2_TX_DP<13>")
	)
	(arc
		(start 125.13945 -270.846296)
		(mid 125.098195 -271.017267)
		(end 124.983494 -271.150588)
		(width 0.1143)
		(layer "In13.Cu")
		(net "P5E_CPU1_P2_TX_DP<13>")
	)
	(arc
		(start 125.13945 -288.666174)
		(mid 125.098195 -288.837145)
		(end 124.983494 -288.970466)
		(width 0.1143)
		(layer "In13.Cu")
		(net "P5E_CPU1_P2_TX_DP<13>")
	)
	(arc
		(start 124.983494 -272.162016)
		(mid 125.139422 -272.466308)
		(end 124.983494 -272.7706)
		(width 0.1143)
		(layer "In13.Cu")
		(net "P5E_CPU1_P2_TX_DP<13>")
	)
	(arc
		(start 124.983494 -283.5021)
		(mid 125.139422 -283.806392)
		(end 124.983494 -284.110684)
		(width 0.1143)
		(layer "In13.Cu")
		(net "P5E_CPU1_P2_TX_DP<13>")
	)
	(arc
		(start 124.912628 -274.43176)
		(mid 124.669301 -274.896326)
		(end 124.912628 -275.360892)
		(width 0.1143)
		(layer "In13.Cu")
		(net "P5E_CPU1_P2_TX_DP<13>")
	)
	(arc
		(start 124.983494 -275.40204)
		(mid 125.139422 -275.706332)
		(end 124.983494 -276.010624)
		(width 0.1143)
		(layer "In13.Cu")
		(net "P5E_CPU1_P2_TX_DP<13>")
	)
	(arc
		(start 124.912628 -277.671784)
		(mid 124.669301 -278.13635)
		(end 124.912628 -278.600916)
		(width 0.1143)
		(layer "In13.Cu")
		(net "P5E_CPU1_P2_TX_DP<13>")
	)
	(arc
		(start 125.452378 -295.651428)
		(mid 125.460721 -295.657663)
		(end 125.468888 -295.664128)
		(width 0.1143)
		(layer "In13.Cu")
		(net "P5E_CPU1_P2_TX_DP<13>")
	)
	(arc
		(start 124.912628 -285.771844)
		(mid 124.669301 -286.23641)
		(end 124.912628 -286.700976)
		(width 0.1143)
		(layer "In13.Cu")
		(net "P5E_CPU1_P2_TX_DP<13>")
	)
	(arc
		(start 124.983494 -294.84193)
		(mid 125.09817 -294.975264)
		(end 125.13945 -295.146222)
		(width 0.1143)
		(layer "In13.Cu")
		(net "P5E_CPU1_P2_TX_DP<13>")
	)
	(arc
		(start 124.912628 -280.911808)
		(mid 124.669301 -281.376374)
		(end 124.912628 -281.84094)
		(width 0.1143)
		(layer "In13.Cu")
		(net "P5E_CPU1_P2_TX_DP<13>")
	)
	(arc
		(start 124.983494 -293.221918)
		(mid 125.139422 -293.52621)
		(end 124.983494 -293.830502)
		(width 0.1143)
		(layer "In13.Cu")
		(net "P5E_CPU1_P2_TX_DP<13>")
	)
	(arc
		(start 124.912628 -279.291796)
		(mid 124.669301 -279.756362)
		(end 124.912628 -280.220928)
		(width 0.1143)
		(layer "In13.Cu")
		(net "P5E_CPU1_P2_TX_DP<13>")
	)
	(arc
		(start 124.983494 -277.022052)
		(mid 125.139422 -277.326344)
		(end 124.983494 -277.630636)
		(width 0.1143)
		(layer "In13.Cu")
		(net "P5E_CPU1_P2_TX_DP<13>")
	)
	(arc
		(start 124.983494 -281.882088)
		(mid 125.139422 -282.18638)
		(end 124.983494 -282.490672)
		(width 0.1143)
		(layer "In13.Cu")
		(net "P5E_CPU1_P2_TX_DP<13>")
	)
	(arc
		(start 168.35247 -367.882678)
		(mid 168.432541 -368.002608)
		(end 168.460674 -368.144044)
		(width 0.14224)
		(layer "In13.Cu")
		(net "P5E_CPU1_P2_TX_DP<13>")
	)
	(arc
		(start 124.912628 -284.151832)
		(mid 124.669301 -284.616398)
		(end 124.912628 -285.080964)
		(width 0.1143)
		(layer "In13.Cu")
		(net "P5E_CPU1_P2_TX_DP<13>")
	)
	(arc
		(start 124.912628 -282.53182)
		(mid 124.669301 -282.996386)
		(end 124.912628 -283.460952)
		(width 0.1143)
		(layer "In13.Cu")
		(net "P5E_CPU1_P2_TX_DP<13>")
	)
	(arc
		(start 124.983494 -278.642064)
		(mid 125.139422 -278.946356)
		(end 124.983494 -279.250648)
		(width 0.1143)
		(layer "In13.Cu")
		(net "P5E_CPU1_P2_TX_DP<13>")
	)
	(arc
		(start 124.985272 -286.743394)
		(mid 125.098679 -286.876283)
		(end 125.13945 -287.046162)
		(width 0.1143)
		(layer "In13.Cu")
		(net "P5E_CPU1_P2_TX_DP<13>")
	)
	(arc
		(start 124.983494 -285.122112)
		(mid 125.139422 -285.426404)
		(end 124.983494 -285.730696)
		(width 0.1143)
		(layer "In13.Cu")
		(net "P5E_CPU1_P2_TX_DP<13>")
	)
	(arc
		(start 124.912628 -276.051772)
		(mid 124.669301 -276.516338)
		(end 124.912628 -276.980904)
		(width 0.1143)
		(layer "In13.Cu")
		(net "P5E_CPU1_P2_TX_DP<13>")
	)
	(arc
		(start 124.912628 -292.251638)
		(mid 124.669301 -292.716204)
		(end 124.912628 -293.18077)
		(width 0.1143)
		(layer "In13.Cu")
		(net "P5E_CPU1_P2_TX_DP<13>")
	)
	(arc
		(start 125.13945 -295.146222)
		(mid 125.204322 -295.409185)
		(end 125.384052 -295.611804)
		(width 0.1143)
		(layer "In13.Cu")
		(net "P5E_CPU1_P2_TX_DP<13>")
	)
	(arc
		(start 124.983494 -280.262076)
		(mid 125.139422 -280.566368)
		(end 124.983494 -280.87066)
		(width 0.1143)
		(layer "In13.Cu")
		(net "P5E_CPU1_P2_TX_DP<13>")
	)
	(segment
		(start 165.036754 -369.30584)
		(end 165.036754 -370.00942)
		(width 0.12954)
		(layer "F.Cu")
		(net "P5E_CPU1_P2_TX_DP<12>")
	)
	(segment
		(start 165.036754 -370.00942)
		(end 164.740844 -370.30533)
		(width 0.12954)
		(layer "F.Cu")
		(net "P5E_CPU1_P2_TX_DP<12>")
	)
	(segment
		(start 164.766244 -369.03533)
		(end 165.036754 -369.30584)
		(width 0.12954)
		(layer "F.Cu")
		(net "P5E_CPU1_P2_TX_DP<12>")
	)
	(segment
		(start 121.94794 -271.390364)
		(end 122.414792 -271.656302)
		(width 0.12954)
		(layer "F.Cu")
		(net "P5E_CPU1_P2_TX_DP<12>")
	)
	(segment
		(start 124.011944 -288.343848)
		(end 124.044456 -288.362644)
		(width 0.1143)
		(layer "In13.Cu")
		(net "P5E_CPU1_P2_TX_DP<12>")
	)
	(segment
		(start 123.972828 -281.84094)
		(end 124.011944 -281.8638)
		(width 0.1143)
		(layer "In13.Cu")
		(net "P5E_CPU1_P2_TX_DP<12>")
	)
	(segment
		(start 124.042424 -282.49118)
		(end 124.011944 -282.50896)
		(width 0.1143)
		(layer "In13.Cu")
		(net "P5E_CPU1_P2_TX_DP<12>")
	)
	(segment
		(start 124.91847 -296.457116)
		(end 124.91847 -296.792396)
		(width 0.1143)
		(layer "In13.Cu")
		(net "P5E_CPU1_P2_TX_DP<12>")
	)
	(segment
		(start 123.972828 -283.460952)
		(end 124.011944 -283.483812)
		(width 0.1143)
		(layer "In13.Cu")
		(net "P5E_CPU1_P2_TX_DP<12>")
	)
	(segment
		(start 124.87275 -296.875708)
		(end 124.873258 -296.876216)
		(width 0.14224)
		(layer "In13.Cu")
		(net "P5E_CPU1_P2_TX_DP<12>")
	)
	(segment
		(start 124.01169 -277.648924)
		(end 123.975368 -277.670006)
		(width 0.1143)
		(layer "In13.Cu")
		(net "P5E_CPU1_P2_TX_DP<12>")
	)
	(segment
		(start 124.042424 -293.83101)
		(end 124.011944 -293.84879)
		(width 0.1143)
		(layer "In13.Cu")
		(net "P5E_CPU1_P2_TX_DP<12>")
	)
	(segment
		(start 123.975368 -276.982682)
		(end 124.01169 -277.003764)
		(width 0.1143)
		(layer "In13.Cu")
		(net "P5E_CPU1_P2_TX_DP<12>")
	)
	(segment
		(start 124.011944 -286.723836)
		(end 124.044456 -286.742632)
		(width 0.1143)
		(layer "In13.Cu")
		(net "P5E_CPU1_P2_TX_DP<12>")
	)
	(segment
		(start 151.341328 -357.99141)
		(end 153.017982 -360.435398)
		(width 0.14224)
		(layer "In13.Cu")
		(net "P5E_CPU1_P2_TX_DP<12>")
	)
	(segment
		(start 123.07189 -272.143728)
		(end 123.10237 -272.161508)
		(width 0.1143)
		(layer "In13.Cu")
		(net "P5E_CPU1_P2_TX_DP<12>")
	)
	(segment
		(start 124.042424 -288.970974)
		(end 124.011944 -288.988754)
		(width 0.1143)
		(layer "In13.Cu")
		(net "P5E_CPU1_P2_TX_DP<12>")
	)
	(segment
		(start 123.972828 -285.080964)
		(end 124.011944 -285.103824)
		(width 0.1143)
		(layer "In13.Cu")
		(net "P5E_CPU1_P2_TX_DP<12>")
	)
	(segment
		(start 155.301188 -362.95457)
		(end 156.795978 -363.953552)
		(width 0.14224)
		(layer "In13.Cu")
		(net "P5E_CPU1_P2_TX_DP<12>")
	)
	(segment
		(start 124.011944 -285.103824)
		(end 124.042424 -285.121604)
		(width 0.1143)
		(layer "In13.Cu")
		(net "P5E_CPU1_P2_TX_DP<12>")
	)
	(segment
		(start 124.91847 -296.792396)
		(end 124.87275 -296.838116)
		(width 0.1143)
		(layer "In13.Cu")
		(net "P5E_CPU1_P2_TX_DP<12>")
	)
	(segment
		(start 125.55982 -298.441872)
		(end 136.047226 -312.583322)
		(width 0.14224)
		(layer "In13.Cu")
		(net "P5E_CPU1_P2_TX_DP<12>")
	)
	(segment
		(start 124.987558 -297.432476)
		(end 125.55982 -298.441872)
		(width 0.14224)
		(layer "In13.Cu")
		(net "P5E_CPU1_P2_TX_DP<12>")
	)
	(segment
		(start 124.011944 -281.8638)
		(end 124.042424 -281.88158)
		(width 0.1143)
		(layer "In13.Cu")
		(net "P5E_CPU1_P2_TX_DP<12>")
	)
	(segment
		(start 122.414792 -271.656302)
		(end 122.712734 -271.656302)
		(width 0.1143)
		(layer "In13.Cu")
		(net "P5E_CPU1_P2_TX_DP<12>")
	)
	(segment
		(start 124.011944 -284.128972)
		(end 123.972828 -284.151832)
		(width 0.1143)
		(layer "In13.Cu")
		(net "P5E_CPU1_P2_TX_DP<12>")
	)
	(segment
		(start 123.975368 -280.222706)
		(end 124.01169 -280.243788)
		(width 0.1143)
		(layer "In13.Cu")
		(net "P5E_CPU1_P2_TX_DP<12>")
	)
	(segment
		(start 123.54179 -272.953734)
		(end 123.57354 -272.972022)
		(width 0.1143)
		(layer "In13.Cu")
		(net "P5E_CPU1_P2_TX_DP<12>")
	)
	(segment
		(start 124.042424 -284.111192)
		(end 124.011944 -284.128972)
		(width 0.1143)
		(layer "In13.Cu")
		(net "P5E_CPU1_P2_TX_DP<12>")
	)
	(segment
		(start 165.057074 -368.213132)
		(end 165.057074 -368.7445)
		(width 0.14224)
		(layer "In13.Cu")
		(net "P5E_CPU1_P2_TX_DP<12>")
	)
	(segment
		(start 124.04344 -280.87066)
		(end 124.01169 -280.888948)
		(width 0.1143)
		(layer "In13.Cu")
		(net "P5E_CPU1_P2_TX_DP<12>")
	)
	(segment
		(start 124.04344 -274.390612)
		(end 123.973336 -274.431252)
		(width 0.1143)
		(layer "In13.Cu")
		(net "P5E_CPU1_P2_TX_DP<12>")
	)
	(segment
		(start 124.442728 -295.610788)
		(end 124.512324 -295.651428)
		(width 0.1143)
		(layer "In13.Cu")
		(net "P5E_CPU1_P2_TX_DP<12>")
	)
	(segment
		(start 153.017982 -360.435398)
		(end 155.301188 -362.95457)
		(width 0.14224)
		(layer "In13.Cu")
		(net "P5E_CPU1_P2_TX_DP<12>")
	)
	(segment
		(start 124.011944 -291.583618)
		(end 124.042424 -291.601398)
		(width 0.1143)
		(layer "In13.Cu")
		(net "P5E_CPU1_P2_TX_DP<12>")
	)
	(segment
		(start 124.011944 -293.20363)
		(end 124.042424 -293.22141)
		(width 0.1143)
		(layer "In13.Cu")
		(net "P5E_CPU1_P2_TX_DP<12>")
	)
	(segment
		(start 124.011944 -283.483812)
		(end 124.042424 -283.501592)
		(width 0.1143)
		(layer "In13.Cu")
		(net "P5E_CPU1_P2_TX_DP<12>")
	)
	(segment
		(start 124.04344 -276.010624)
		(end 124.01169 -276.028912)
		(width 0.1143)
		(layer "In13.Cu")
		(net "P5E_CPU1_P2_TX_DP<12>")
	)
	(segment
		(start 124.669296 -295.956482)
		(end 124.669296 -296.207942)
		(width 0.1143)
		(layer "In13.Cu")
		(net "P5E_CPU1_P2_TX_DP<12>")
	)
	(segment
		(start 124.04344 -279.250648)
		(end 124.01169 -279.268936)
		(width 0.1143)
		(layer "In13.Cu")
		(net "P5E_CPU1_P2_TX_DP<12>")
	)
	(segment
		(start 156.795978 -363.953552)
		(end 162.760914 -366.424464)
		(width 0.14224)
		(layer "In13.Cu")
		(net "P5E_CPU1_P2_TX_DP<12>")
	)
	(segment
		(start 162.760914 -366.424464)
		(end 164.681154 -367.707672)
		(width 0.14224)
		(layer "In13.Cu")
		(net "P5E_CPU1_P2_TX_DP<12>")
	)
	(segment
		(start 124.04344 -277.630636)
		(end 124.01169 -277.648924)
		(width 0.1143)
		(layer "In13.Cu")
		(net "P5E_CPU1_P2_TX_DP<12>")
	)
	(segment
		(start 136.522968 -313.29503)
		(end 140.80109 -321.298062)
		(width 0.14224)
		(layer "In13.Cu")
		(net "P5E_CPU1_P2_TX_DP<12>")
	)
	(segment
		(start 124.011944 -285.748984)
		(end 123.972828 -285.771844)
		(width 0.1143)
		(layer "In13.Cu")
		(net "P5E_CPU1_P2_TX_DP<12>")
	)
	(segment
		(start 123.973336 -274.431252)
		(end 123.956826 -274.442936)
		(width 0.1143)
		(layer "In13.Cu")
		(net "P5E_CPU1_P2_TX_DP<12>")
	)
	(segment
		(start 124.042424 -292.210998)
		(end 124.011944 -292.228778)
		(width 0.1143)
		(layer "In13.Cu")
		(net "P5E_CPU1_P2_TX_DP<12>")
	)
	(segment
		(start 124.011944 -290.608766)
		(end 123.972828 -290.631626)
		(width 0.1143)
		(layer "In13.Cu")
		(net "P5E_CPU1_P2_TX_DP<12>")
	)
	(segment
		(start 124.011944 -289.963606)
		(end 124.042424 -289.981386)
		(width 0.1143)
		(layer "In13.Cu")
		(net "P5E_CPU1_P2_TX_DP<12>")
	)
	(segment
		(start 124.01169 -279.268936)
		(end 123.975368 -279.290018)
		(width 0.1143)
		(layer "In13.Cu")
		(net "P5E_CPU1_P2_TX_DP<12>")
	)
	(segment
		(start 124.873258 -296.876216)
		(end 124.873258 -297.113198)
		(width 0.14224)
		(layer "In13.Cu")
		(net "P5E_CPU1_P2_TX_DP<12>")
	)
	(segment
		(start 124.01169 -280.243788)
		(end 124.04344 -280.262076)
		(width 0.1143)
		(layer "In13.Cu")
		(net "P5E_CPU1_P2_TX_DP<12>")
	)
	(segment
		(start 123.972828 -286.700976)
		(end 124.011944 -286.723836)
		(width 0.1143)
		(layer "In13.Cu")
		(net "P5E_CPU1_P2_TX_DP<12>")
	)
	(segment
		(start 124.011944 -292.228778)
		(end 123.972828 -292.251638)
		(width 0.1143)
		(layer "In13.Cu")
		(net "P5E_CPU1_P2_TX_DP<12>")
	)
	(segment
		(start 141.336776 -322.591176)
		(end 146.44116 -348.25686)
		(width 0.14224)
		(layer "In13.Cu")
		(net "P5E_CPU1_P2_TX_DP<12>")
	)
	(segment
		(start 124.011944 -294.823642)
		(end 124.042424 -294.841422)
		(width 0.1143)
		(layer "In13.Cu")
		(net "P5E_CPU1_P2_TX_DP<12>")
	)
	(segment
		(start 123.956826 -275.349716)
		(end 123.973336 -275.3614)
		(width 0.1143)
		(layer "In13.Cu")
		(net "P5E_CPU1_P2_TX_DP<12>")
	)
	(segment
		(start 123.972828 -289.940746)
		(end 124.011944 -289.963606)
		(width 0.1143)
		(layer "In13.Cu")
		(net "P5E_CPU1_P2_TX_DP<12>")
	)
	(segment
		(start 124.01169 -278.623776)
		(end 124.04344 -278.642064)
		(width 0.1143)
		(layer "In13.Cu")
		(net "P5E_CPU1_P2_TX_DP<12>")
	)
	(segment
		(start 124.87275 -296.866564)
		(end 124.87275 -296.875708)
		(width 0.14224)
		(layer "In13.Cu")
		(net "P5E_CPU1_P2_TX_DP<12>")
	)
	(segment
		(start 136.047226 -312.583322)
		(end 136.522968 -313.29503)
		(width 0.14224)
		(layer "In13.Cu")
		(net "P5E_CPU1_P2_TX_DP<12>")
	)
	(segment
		(start 124.011944 -282.50896)
		(end 123.972828 -282.53182)
		(width 0.1143)
		(layer "In13.Cu")
		(net "P5E_CPU1_P2_TX_DP<12>")
	)
	(segment
		(start 124.042424 -290.590986)
		(end 124.011944 -290.608766)
		(width 0.1143)
		(layer "In13.Cu")
		(net "P5E_CPU1_P2_TX_DP<12>")
	)
	(segment
		(start 140.80109 -321.298062)
		(end 141.336776 -322.591176)
		(width 0.14224)
		(layer "In13.Cu")
		(net "P5E_CPU1_P2_TX_DP<12>")
	)
	(segment
		(start 124.042424 -287.350962)
		(end 123.975368 -287.390078)
		(width 0.1143)
		(layer "In13.Cu")
		(net "P5E_CPU1_P2_TX_DP<12>")
	)
	(segment
		(start 124.011944 -288.988754)
		(end 123.972828 -289.011614)
		(width 0.1143)
		(layer "In13.Cu")
		(net "P5E_CPU1_P2_TX_DP<12>")
	)
	(segment
		(start 146.44116 -348.25686)
		(end 151.341328 -357.99141)
		(width 0.14224)
		(layer "In13.Cu")
		(net "P5E_CPU1_P2_TX_DP<12>")
	)
	(segment
		(start 124.87275 -296.838116)
		(end 124.87275 -296.866564)
		(width 0.1143)
		(layer "In13.Cu")
		(net "P5E_CPU1_P2_TX_DP<12>")
	)
	(segment
		(start 165.057074 -368.7445)
		(end 164.766244 -369.03533)
		(width 0.14224)
		(layer "In13.Cu")
		(net "P5E_CPU1_P2_TX_DP<12>")
	)
	(segment
		(start 123.973336 -275.3614)
		(end 124.043186 -275.40204)
		(width 0.1143)
		(layer "In13.Cu")
		(net "P5E_CPU1_P2_TX_DP<12>")
	)
	(segment
		(start 124.011944 -293.84879)
		(end 123.972828 -293.87165)
		(width 0.1143)
		(layer "In13.Cu")
		(net "P5E_CPU1_P2_TX_DP<12>")
	)
	(segment
		(start 123.032774 -272.120868)
		(end 123.07189 -272.143728)
		(width 0.1143)
		(layer "In13.Cu")
		(net "P5E_CPU1_P2_TX_DP<12>")
	)
	(segment
		(start 123.502674 -272.930874)
		(end 123.54179 -272.953734)
		(width 0.1143)
		(layer "In13.Cu")
		(net "P5E_CPU1_P2_TX_DP<12>")
	)
	(segment
		(start 123.975368 -278.602694)
		(end 124.01169 -278.623776)
		(width 0.1143)
		(layer "In13.Cu")
		(net "P5E_CPU1_P2_TX_DP<12>")
	)
	(segment
		(start 124.01169 -276.028912)
		(end 123.975368 -276.049994)
		(width 0.1143)
		(layer "In13.Cu")
		(net "P5E_CPU1_P2_TX_DP<12>")
	)
	(segment
		(start 124.01169 -277.003764)
		(end 124.04344 -277.022052)
		(width 0.1143)
		(layer "In13.Cu")
		(net "P5E_CPU1_P2_TX_DP<12>")
	)
	(segment
		(start 124.669296 -296.207942)
		(end 124.91847 -296.457116)
		(width 0.1143)
		(layer "In13.Cu")
		(net "P5E_CPU1_P2_TX_DP<12>")
	)
	(segment
		(start 124.873258 -297.113198)
		(end 124.987558 -297.432476)
		(width 0.14224)
		(layer "In13.Cu")
		(net "P5E_CPU1_P2_TX_DP<12>")
	)
	(segment
		(start 164.681154 -367.707672)
		(end 164.96538 -367.991898)
		(width 0.14224)
		(layer "In13.Cu")
		(net "P5E_CPU1_P2_TX_DP<12>")
	)
	(segment
		(start 124.01169 -280.888948)
		(end 123.976892 -280.909014)
		(width 0.1143)
		(layer "In13.Cu")
		(net "P5E_CPU1_P2_TX_DP<12>")
	)
	(segment
		(start 124.042424 -285.731204)
		(end 124.011944 -285.748984)
		(width 0.1143)
		(layer "In13.Cu")
		(net "P5E_CPU1_P2_TX_DP<12>")
	)
	(segment
		(start 123.972828 -294.800782)
		(end 124.011944 -294.823642)
		(width 0.1143)
		(layer "In13.Cu")
		(net "P5E_CPU1_P2_TX_DP<12>")
	)
	(segment
		(start 123.972828 -291.560758)
		(end 124.011944 -291.583618)
		(width 0.1143)
		(layer "In13.Cu")
		(net "P5E_CPU1_P2_TX_DP<12>")
	)
	(segment
		(start 123.976892 -280.909014)
		(end 123.972828 -280.911808)
		(width 0.1143)
		(layer "In13.Cu")
		(net "P5E_CPU1_P2_TX_DP<12>")
	)
	(segment
		(start 123.972828 -288.320988)
		(end 124.011944 -288.343848)
		(width 0.1143)
		(layer "In13.Cu")
		(net "P5E_CPU1_P2_TX_DP<12>")
	)
	(segment
		(start 123.975368 -273.742658)
		(end 124.04344 -273.782028)
		(width 0.1143)
		(layer "In13.Cu")
		(net "P5E_CPU1_P2_TX_DP<12>")
	)
	(segment
		(start 124.66955 -295.956228)
		(end 124.669296 -295.956482)
		(width 0.1143)
		(layer "In13.Cu")
		(net "P5E_CPU1_P2_TX_DP<12>")
	)
	(segment
		(start 122.712734 -271.656302)
		(end 122.795538 -271.739106)
		(width 0.1143)
		(layer "In13.Cu")
		(net "P5E_CPU1_P2_TX_DP<12>")
	)
	(segment
		(start 124.043186 -275.40204)
		(end 124.04344 -275.40204)
		(width 0.1143)
		(layer "In13.Cu")
		(net "P5E_CPU1_P2_TX_DP<12>")
	)
	(segment
		(start 123.972828 -293.18077)
		(end 124.011944 -293.20363)
		(width 0.1143)
		(layer "In13.Cu")
		(net "P5E_CPU1_P2_TX_DP<12>")
	)
	(arc
		(start 123.975368 -287.390078)
		(mid 123.794716 -287.592823)
		(end 123.729496 -287.856422)
		(width 0.1143)
		(layer "In13.Cu")
		(net "P5E_CPU1_P2_TX_DP<12>")
	)
	(arc
		(start 123.10237 -272.161508)
		(mid 123.217797 -272.294884)
		(end 123.259342 -272.466308)
		(width 0.1143)
		(layer "In13.Cu")
		(net "P5E_CPU1_P2_TX_DP<12>")
	)
	(arc
		(start 124.512324 -295.651428)
		(mid 124.520667 -295.657663)
		(end 124.528834 -295.664128)
		(width 0.1143)
		(layer "In13.Cu")
		(net "P5E_CPU1_P2_TX_DP<12>")
	)
	(arc
		(start 124.199396 -295.146222)
		(mid 124.263911 -295.408441)
		(end 124.442728 -295.610788)
		(width 0.1143)
		(layer "In13.Cu")
		(net "P5E_CPU1_P2_TX_DP<12>")
	)
	(arc
		(start 124.528834 -295.664128)
		(mid 124.632484 -295.794149)
		(end 124.66955 -295.956228)
		(width 0.1143)
		(layer "In13.Cu")
		(net "P5E_CPU1_P2_TX_DP<12>")
	)
	(arc
		(start 124.042424 -289.981386)
		(mid 124.199401 -290.286186)
		(end 124.042424 -290.590986)
		(width 0.1143)
		(layer "In13.Cu")
		(net "P5E_CPU1_P2_TX_DP<12>")
	)
	(arc
		(start 124.042424 -283.501592)
		(mid 124.199401 -283.806392)
		(end 124.042424 -284.111192)
		(width 0.1143)
		(layer "In13.Cu")
		(net "P5E_CPU1_P2_TX_DP<12>")
	)
	(arc
		(start 123.972828 -290.631626)
		(mid 123.729501 -291.096192)
		(end 123.972828 -291.560758)
		(width 0.1143)
		(layer "In13.Cu")
		(net "P5E_CPU1_P2_TX_DP<12>")
	)
	(arc
		(start 123.961144 -276.0599)
		(mid 123.733761 -276.516338)
		(end 123.961144 -276.972776)
		(width 0.1143)
		(layer "In13.Cu")
		(net "P5E_CPU1_P2_TX_DP<12>")
	)
	(arc
		(start 124.042424 -291.601398)
		(mid 124.199401 -291.906198)
		(end 124.042424 -292.210998)
		(width 0.1143)
		(layer "In13.Cu")
		(net "P5E_CPU1_P2_TX_DP<12>")
	)
	(arc
		(start 122.795538 -271.739106)
		(mid 122.797326 -271.750555)
		(end 122.799348 -271.761966)
		(width 0.1143)
		(layer "In13.Cu")
		(net "P5E_CPU1_P2_TX_DP<12>")
	)
	(arc
		(start 124.199396 -287.046162)
		(mid 124.157847 -287.217584)
		(end 124.042424 -287.350962)
		(width 0.1143)
		(layer "In13.Cu")
		(net "P5E_CPU1_P2_TX_DP<12>")
	)
	(arc
		(start 124.199396 -288.666174)
		(mid 124.157847 -288.837596)
		(end 124.042424 -288.970974)
		(width 0.1143)
		(layer "In13.Cu")
		(net "P5E_CPU1_P2_TX_DP<12>")
	)
	(arc
		(start 123.961144 -278.592788)
		(mid 123.968218 -278.597795)
		(end 123.975368 -278.602694)
		(width 0.1143)
		(layer "In13.Cu")
		(net "P5E_CPU1_P2_TX_DP<12>")
	)
	(arc
		(start 124.042424 -294.841422)
		(mid 124.157851 -294.974798)
		(end 124.199396 -295.146222)
		(width 0.1143)
		(layer "In13.Cu")
		(net "P5E_CPU1_P2_TX_DP<12>")
	)
	(arc
		(start 123.73356 -273.312128)
		(mid 123.814228 -273.55)
		(end 123.975368 -273.742658)
		(width 0.1143)
		(layer "In13.Cu")
		(net "P5E_CPU1_P2_TX_DP<12>")
	)
	(arc
		(start 123.57354 -272.972022)
		(mid 123.684982 -273.098664)
		(end 123.72975 -273.261328)
		(width 0.1143)
		(layer "In13.Cu")
		(net "P5E_CPU1_P2_TX_DP<12>")
	)
	(arc
		(start 124.044456 -286.742632)
		(mid 124.158385 -286.875779)
		(end 124.199396 -287.046162)
		(width 0.1143)
		(layer "In13.Cu")
		(net "P5E_CPU1_P2_TX_DP<12>")
	)
	(arc
		(start 124.04344 -277.022052)
		(mid 124.199368 -277.326344)
		(end 124.04344 -277.630636)
		(width 0.1143)
		(layer "In13.Cu")
		(net "P5E_CPU1_P2_TX_DP<12>")
	)
	(arc
		(start 124.04344 -278.642064)
		(mid 124.199368 -278.946356)
		(end 124.04344 -279.250648)
		(width 0.1143)
		(layer "In13.Cu")
		(net "P5E_CPU1_P2_TX_DP<12>")
	)
	(arc
		(start 123.956826 -274.442936)
		(mid 123.723928 -274.896326)
		(end 123.956826 -275.349716)
		(width 0.1143)
		(layer "In13.Cu")
		(net "P5E_CPU1_P2_TX_DP<12>")
	)
	(arc
		(start 124.044456 -288.362644)
		(mid 124.158385 -288.495791)
		(end 124.199396 -288.666174)
		(width 0.1143)
		(layer "In13.Cu")
		(net "P5E_CPU1_P2_TX_DP<12>")
	)
	(arc
		(start 122.799348 -271.761966)
		(mid 122.880781 -271.964364)
		(end 123.032774 -272.120868)
		(width 0.1143)
		(layer "In13.Cu")
		(net "P5E_CPU1_P2_TX_DP<12>")
	)
	(arc
		(start 123.975368 -277.670006)
		(mid 123.968219 -277.674906)
		(end 123.961144 -277.679912)
		(width 0.1143)
		(layer "In13.Cu")
		(net "P5E_CPU1_P2_TX_DP<12>")
	)
	(arc
		(start 123.961144 -280.2128)
		(mid 123.968218 -280.217807)
		(end 123.975368 -280.222706)
		(width 0.1143)
		(layer "In13.Cu")
		(net "P5E_CPU1_P2_TX_DP<12>")
	)
	(arc
		(start 123.975368 -276.049994)
		(mid 123.968219 -276.054894)
		(end 123.961144 -276.0599)
		(width 0.1143)
		(layer "In13.Cu")
		(net "P5E_CPU1_P2_TX_DP<12>")
	)
	(arc
		(start 123.972828 -282.53182)
		(mid 123.729501 -282.996386)
		(end 123.972828 -283.460952)
		(width 0.1143)
		(layer "In13.Cu")
		(net "P5E_CPU1_P2_TX_DP<12>")
	)
	(arc
		(start 123.972828 -292.251638)
		(mid 123.729501 -292.716204)
		(end 123.972828 -293.18077)
		(width 0.1143)
		(layer "In13.Cu")
		(net "P5E_CPU1_P2_TX_DP<12>")
	)
	(arc
		(start 123.972828 -289.011614)
		(mid 123.729501 -289.47618)
		(end 123.972828 -289.940746)
		(width 0.1143)
		(layer "In13.Cu")
		(net "P5E_CPU1_P2_TX_DP<12>")
	)
	(arc
		(start 123.975368 -279.290018)
		(mid 123.968219 -279.294918)
		(end 123.961144 -279.299924)
		(width 0.1143)
		(layer "In13.Cu")
		(net "P5E_CPU1_P2_TX_DP<12>")
	)
	(arc
		(start 123.729496 -287.856422)
		(mid 123.794011 -288.118641)
		(end 123.972828 -288.320988)
		(width 0.1143)
		(layer "In13.Cu")
		(net "P5E_CPU1_P2_TX_DP<12>")
	)
	(arc
		(start 123.972828 -284.151832)
		(mid 123.729501 -284.616398)
		(end 123.972828 -285.080964)
		(width 0.1143)
		(layer "In13.Cu")
		(net "P5E_CPU1_P2_TX_DP<12>")
	)
	(arc
		(start 123.961144 -279.299924)
		(mid 123.733761 -279.756362)
		(end 123.961144 -280.2128)
		(width 0.1143)
		(layer "In13.Cu")
		(net "P5E_CPU1_P2_TX_DP<12>")
	)
	(arc
		(start 123.972828 -280.911808)
		(mid 123.729501 -281.376374)
		(end 123.972828 -281.84094)
		(width 0.1143)
		(layer "In13.Cu")
		(net "P5E_CPU1_P2_TX_DP<12>")
	)
	(arc
		(start 124.042424 -281.88158)
		(mid 124.199401 -282.18638)
		(end 124.042424 -282.49118)
		(width 0.1143)
		(layer "In13.Cu")
		(net "P5E_CPU1_P2_TX_DP<12>")
	)
	(arc
		(start 123.961144 -276.972776)
		(mid 123.968218 -276.977783)
		(end 123.975368 -276.982682)
		(width 0.1143)
		(layer "In13.Cu")
		(net "P5E_CPU1_P2_TX_DP<12>")
	)
	(arc
		(start 123.972828 -293.87165)
		(mid 123.729501 -294.336216)
		(end 123.972828 -294.800782)
		(width 0.1143)
		(layer "In13.Cu")
		(net "P5E_CPU1_P2_TX_DP<12>")
	)
	(arc
		(start 123.72975 -273.261328)
		(mid 123.730922 -273.286783)
		(end 123.73356 -273.312128)
		(width 0.1143)
		(layer "In13.Cu")
		(net "P5E_CPU1_P2_TX_DP<12>")
	)
	(arc
		(start 124.04344 -275.40204)
		(mid 124.199368 -275.706332)
		(end 124.04344 -276.010624)
		(width 0.1143)
		(layer "In13.Cu")
		(net "P5E_CPU1_P2_TX_DP<12>")
	)
	(arc
		(start 124.042424 -293.22141)
		(mid 124.199401 -293.52621)
		(end 124.042424 -293.83101)
		(width 0.1143)
		(layer "In13.Cu")
		(net "P5E_CPU1_P2_TX_DP<12>")
	)
	(arc
		(start 124.042424 -285.121604)
		(mid 124.199401 -285.426404)
		(end 124.042424 -285.731204)
		(width 0.1143)
		(layer "In13.Cu")
		(net "P5E_CPU1_P2_TX_DP<12>")
	)
	(arc
		(start 123.259342 -272.466308)
		(mid 123.323857 -272.728527)
		(end 123.502674 -272.930874)
		(width 0.1143)
		(layer "In13.Cu")
		(net "P5E_CPU1_P2_TX_DP<12>")
	)
	(arc
		(start 123.972828 -285.771844)
		(mid 123.729501 -286.23641)
		(end 123.972828 -286.700976)
		(width 0.1143)
		(layer "In13.Cu")
		(net "P5E_CPU1_P2_TX_DP<12>")
	)
	(arc
		(start 124.04344 -280.262076)
		(mid 124.199368 -280.566368)
		(end 124.04344 -280.87066)
		(width 0.1143)
		(layer "In13.Cu")
		(net "P5E_CPU1_P2_TX_DP<12>")
	)
	(arc
		(start 164.96538 -367.991898)
		(mid 165.033256 -368.093387)
		(end 165.057074 -368.213132)
		(width 0.14224)
		(layer "In13.Cu")
		(net "P5E_CPU1_P2_TX_DP<12>")
	)
	(arc
		(start 124.04344 -273.782028)
		(mid 124.199368 -274.08632)
		(end 124.04344 -274.390612)
		(width 0.1143)
		(layer "In13.Cu")
		(net "P5E_CPU1_P2_TX_DP<12>")
	)
	(arc
		(start 123.961144 -277.679912)
		(mid 123.733761 -278.13635)
		(end 123.961144 -278.592788)
		(width 0.1143)
		(layer "In13.Cu")
		(net "P5E_CPU1_P2_TX_DP<12>")
	)
	(segment
		(start 163.334954 -371.76964)
		(end 163.334954 -372.47322)
		(width 0.12954)
		(layer "F.Cu")
		(net "P5E_CPU1_P2_TX_DP<11>")
	)
	(segment
		(start 163.064444 -371.49913)
		(end 163.334954 -371.76964)
		(width 0.12954)
		(layer "F.Cu")
		(net "P5E_CPU1_P2_TX_DP<11>")
	)
	(segment
		(start 163.334954 -372.47322)
		(end 163.039044 -372.76913)
		(width 0.12954)
		(layer "F.Cu")
		(net "P5E_CPU1_P2_TX_DP<11>")
	)
	(segment
		(start 121.94794 -273.010376)
		(end 122.414792 -273.276314)
		(width 0.12954)
		(layer "F.Cu")
		(net "P5E_CPU1_P2_TX_DP<11>")
	)
	(segment
		(start 123.032774 -276.980904)
		(end 123.07189 -277.003764)
		(width 0.1143)
		(layer "In13.Cu")
		(net "P5E_CPU1_P2_TX_DP<11>")
	)
	(segment
		(start 123.03887 -288.324544)
		(end 123.039124 -288.324544)
		(width 0.1143)
		(layer "In13.Cu")
		(net "P5E_CPU1_P2_TX_DP<11>")
	)
	(segment
		(start 123.075446 -284.127194)
		(end 123.074938 -284.127194)
		(width 0.1143)
		(layer "In13.Cu")
		(net "P5E_CPU1_P2_TX_DP<11>")
	)
	(segment
		(start 123.10237 -279.251156)
		(end 123.07189 -279.268936)
		(width 0.1143)
		(layer "In13.Cu")
		(net "P5E_CPU1_P2_TX_DP<11>")
	)
	(segment
		(start 123.032774 -280.220928)
		(end 123.07189 -280.243788)
		(width 0.1143)
		(layer "In13.Cu")
		(net "P5E_CPU1_P2_TX_DP<11>")
	)
	(segment
		(start 123.074938 -285.747206)
		(end 123.072652 -285.74873)
		(width 0.1143)
		(layer "In13.Cu")
		(net "P5E_CPU1_P2_TX_DP<11>")
	)
	(segment
		(start 123.070874 -282.509468)
		(end 123.032774 -282.53182)
		(width 0.1143)
		(layer "In13.Cu")
		(net "P5E_CPU1_P2_TX_DP<11>")
	)
	(segment
		(start 123.066302 -292.23208)
		(end 123.032774 -292.251638)
		(width 0.1143)
		(layer "In13.Cu")
		(net "P5E_CPU1_P2_TX_DP<11>")
	)
	(segment
		(start 123.92787 -296.866564)
		(end 123.92787 -296.885614)
		(width 0.14224)
		(layer "In13.Cu")
		(net "P5E_CPU1_P2_TX_DP<11>")
	)
	(segment
		(start 123.10237 -280.871168)
		(end 123.07189 -280.888948)
		(width 0.1143)
		(layer "In13.Cu")
		(net "P5E_CPU1_P2_TX_DP<11>")
	)
	(segment
		(start 123.072652 -288.9885)
		(end 123.07189 -288.988754)
		(width 0.1143)
		(layer "In13.Cu")
		(net "P5E_CPU1_P2_TX_DP<11>")
	)
	(segment
		(start 123.928378 -296.886122)
		(end 123.928378 -297.340528)
		(width 0.14224)
		(layer "In13.Cu")
		(net "P5E_CPU1_P2_TX_DP<11>")
	)
	(segment
		(start 123.07443 -294.824912)
		(end 123.104656 -294.842946)
		(width 0.1143)
		(layer "In13.Cu")
		(net "P5E_CPU1_P2_TX_DP<11>")
	)
	(segment
		(start 154.371294 -363.50829)
		(end 156.18714 -364.721902)
		(width 0.14224)
		(layer "In13.Cu")
		(net "P5E_CPU1_P2_TX_DP<11>")
	)
	(segment
		(start 123.07189 -289.963606)
		(end 123.072652 -289.964114)
		(width 0.1143)
		(layer "In13.Cu")
		(net "P5E_CPU1_P2_TX_DP<11>")
	)
	(segment
		(start 123.074684 -293.205408)
		(end 123.075192 -293.205408)
		(width 0.1143)
		(layer "In13.Cu")
		(net "P5E_CPU1_P2_TX_DP<11>")
	)
	(segment
		(start 123.07189 -292.228778)
		(end 123.070874 -292.229286)
		(width 0.1143)
		(layer "In13.Cu")
		(net "P5E_CPU1_P2_TX_DP<11>")
	)
	(segment
		(start 123.072652 -285.74873)
		(end 123.07189 -285.748984)
		(width 0.1143)
		(layer "In13.Cu")
		(net "P5E_CPU1_P2_TX_DP<11>")
	)
	(segment
		(start 123.07189 -290.608766)
		(end 123.070874 -290.609274)
		(width 0.1143)
		(layer "In13.Cu")
		(net "P5E_CPU1_P2_TX_DP<11>")
	)
	(segment
		(start 152.266396 -361.187746)
		(end 154.371294 -363.50829)
		(width 0.14224)
		(layer "In13.Cu")
		(net "P5E_CPU1_P2_TX_DP<11>")
	)
	(segment
		(start 123.259596 -287.046162)
		(end 123.259596 -287.050734)
		(width 0.1143)
		(layer "In13.Cu")
		(net "P5E_CPU1_P2_TX_DP<11>")
	)
	(segment
		(start 123.07189 -281.8638)
		(end 123.072652 -281.864308)
		(width 0.1143)
		(layer "In13.Cu")
		(net "P5E_CPU1_P2_TX_DP<11>")
	)
	(segment
		(start 123.072652 -285.104332)
		(end 123.074684 -285.105602)
		(width 0.1143)
		(layer "In13.Cu")
		(net "P5E_CPU1_P2_TX_DP<11>")
	)
	(segment
		(start 123.070874 -293.849298)
		(end 123.032774 -293.87165)
		(width 0.1143)
		(layer "In13.Cu")
		(net "P5E_CPU1_P2_TX_DP<11>")
	)
	(segment
		(start 123.070874 -290.609274)
		(end 123.032774 -290.631626)
		(width 0.1143)
		(layer "In13.Cu")
		(net "P5E_CPU1_P2_TX_DP<11>")
	)
	(segment
		(start 123.07189 -274.4089)
		(end 123.032774 -274.43176)
		(width 0.1143)
		(layer "In13.Cu")
		(net "P5E_CPU1_P2_TX_DP<11>")
	)
	(segment
		(start 123.502674 -295.610788)
		(end 123.540774 -295.63314)
		(width 0.1143)
		(layer "In13.Cu")
		(net "P5E_CPU1_P2_TX_DP<11>")
	)
	(segment
		(start 123.259596 -295.146222)
		(end 123.259342 -295.146222)
		(width 0.1143)
		(layer "In13.Cu")
		(net "P5E_CPU1_P2_TX_DP<11>")
	)
	(segment
		(start 123.10237 -277.631144)
		(end 123.07189 -277.648924)
		(width 0.1143)
		(layer "In13.Cu")
		(net "P5E_CPU1_P2_TX_DP<11>")
	)
	(segment
		(start 123.10364 -287.350454)
		(end 123.035314 -287.390078)
		(width 0.1143)
		(layer "In13.Cu")
		(net "P5E_CPU1_P2_TX_DP<11>")
	)
	(segment
		(start 123.10237 -276.011132)
		(end 123.07189 -276.028912)
		(width 0.1143)
		(layer "In13.Cu")
		(net "P5E_CPU1_P2_TX_DP<11>")
	)
	(segment
		(start 123.070874 -284.12948)
		(end 123.032774 -284.151832)
		(width 0.1143)
		(layer "In13.Cu")
		(net "P5E_CPU1_P2_TX_DP<11>")
	)
	(segment
		(start 123.07189 -278.623776)
		(end 123.10237 -278.641556)
		(width 0.1143)
		(layer "In13.Cu")
		(net "P5E_CPU1_P2_TX_DP<11>")
	)
	(segment
		(start 123.10237 -274.39112)
		(end 123.07189 -274.4089)
		(width 0.1143)
		(layer "In13.Cu")
		(net "P5E_CPU1_P2_TX_DP<11>")
	)
	(segment
		(start 123.259596 -295.141904)
		(end 123.259596 -295.146222)
		(width 0.1143)
		(layer "In13.Cu")
		(net "P5E_CPU1_P2_TX_DP<11>")
	)
	(segment
		(start 123.032774 -289.940746)
		(end 123.070874 -289.963098)
		(width 0.1143)
		(layer "In13.Cu")
		(net "P5E_CPU1_P2_TX_DP<11>")
	)
	(segment
		(start 122.414792 -273.276314)
		(end 122.712734 -273.276314)
		(width 0.1143)
		(layer "In13.Cu")
		(net "P5E_CPU1_P2_TX_DP<11>")
	)
	(segment
		(start 123.97359 -296.45229)
		(end 123.97359 -296.792396)
		(width 0.1143)
		(layer "In13.Cu")
		(net "P5E_CPU1_P2_TX_DP<11>")
	)
	(segment
		(start 163.355274 -368.784124)
		(end 163.355274 -371.2083)
		(width 0.14224)
		(layer "In13.Cu")
		(net "P5E_CPU1_P2_TX_DP<11>")
	)
	(segment
		(start 123.040394 -283.465524)
		(end 123.07189 -283.483812)
		(width 0.1143)
		(layer "In13.Cu")
		(net "P5E_CPU1_P2_TX_DP<11>")
	)
	(segment
		(start 123.070874 -291.58311)
		(end 123.07189 -291.583618)
		(width 0.1143)
		(layer "In13.Cu")
		(net "P5E_CPU1_P2_TX_DP<11>")
	)
	(segment
		(start 123.072652 -281.864308)
		(end 123.074684 -281.865578)
		(width 0.1143)
		(layer "In13.Cu")
		(net "P5E_CPU1_P2_TX_DP<11>")
	)
	(segment
		(start 123.072652 -293.204138)
		(end 123.074684 -293.205408)
		(width 0.1143)
		(layer "In13.Cu")
		(net "P5E_CPU1_P2_TX_DP<11>")
	)
	(segment
		(start 123.10364 -292.21049)
		(end 123.072652 -292.22827)
		(width 0.1143)
		(layer "In13.Cu")
		(net "P5E_CPU1_P2_TX_DP<11>")
	)
	(segment
		(start 123.07189 -293.20363)
		(end 123.072652 -293.204138)
		(width 0.1143)
		(layer "In13.Cu")
		(net "P5E_CPU1_P2_TX_DP<11>")
	)
	(segment
		(start 123.075446 -293.847012)
		(end 123.074938 -293.847012)
		(width 0.1143)
		(layer "In13.Cu")
		(net "P5E_CPU1_P2_TX_DP<11>")
	)
	(segment
		(start 123.07189 -293.84879)
		(end 123.070874 -293.849298)
		(width 0.1143)
		(layer "In13.Cu")
		(net "P5E_CPU1_P2_TX_DP<11>")
	)
	(segment
		(start 123.07189 -273.76374)
		(end 123.10237 -273.78152)
		(width 0.1143)
		(layer "In13.Cu")
		(net "P5E_CPU1_P2_TX_DP<11>")
	)
	(segment
		(start 156.18714 -364.721902)
		(end 161.435542 -366.896142)
		(width 0.14224)
		(layer "In13.Cu")
		(net "P5E_CPU1_P2_TX_DP<11>")
	)
	(segment
		(start 123.070874 -289.963098)
		(end 123.07189 -289.963606)
		(width 0.1143)
		(layer "In13.Cu")
		(net "P5E_CPU1_P2_TX_DP<11>")
	)
	(segment
		(start 123.07189 -285.748984)
		(end 123.070874 -285.749492)
		(width 0.1143)
		(layer "In13.Cu")
		(net "P5E_CPU1_P2_TX_DP<11>")
	)
	(segment
		(start 123.032774 -288.320988)
		(end 123.03887 -288.324544)
		(width 0.1143)
		(layer "In13.Cu")
		(net "P5E_CPU1_P2_TX_DP<11>")
	)
	(segment
		(start 123.729496 -296.208196)
		(end 123.97359 -296.45229)
		(width 0.1143)
		(layer "In13.Cu")
		(net "P5E_CPU1_P2_TX_DP<11>")
	)
	(segment
		(start 123.070874 -292.229286)
		(end 123.068842 -292.230556)
		(width 0.1143)
		(layer "In13.Cu")
		(net "P5E_CPU1_P2_TX_DP<11>")
	)
	(segment
		(start 123.072652 -292.22827)
		(end 123.07189 -292.228778)
		(width 0.1143)
		(layer "In13.Cu")
		(net "P5E_CPU1_P2_TX_DP<11>")
	)
	(segment
		(start 123.074938 -284.127194)
		(end 123.072652 -284.128718)
		(width 0.1143)
		(layer "In13.Cu")
		(net "P5E_CPU1_P2_TX_DP<11>")
	)
	(segment
		(start 123.074684 -285.105602)
		(end 123.075192 -285.105602)
		(width 0.1143)
		(layer "In13.Cu")
		(net "P5E_CPU1_P2_TX_DP<11>")
	)
	(segment
		(start 123.074684 -283.48559)
		(end 123.075192 -283.48559)
		(width 0.1143)
		(layer "In13.Cu")
		(net "P5E_CPU1_P2_TX_DP<11>")
	)
	(segment
		(start 123.54179 -295.633648)
		(end 123.542552 -295.634156)
		(width 0.1143)
		(layer "In13.Cu")
		(net "P5E_CPU1_P2_TX_DP<11>")
	)
	(segment
		(start 123.070874 -285.103316)
		(end 123.07189 -285.103824)
		(width 0.1143)
		(layer "In13.Cu")
		(net "P5E_CPU1_P2_TX_DP<11>")
	)
	(segment
		(start 123.072652 -291.584126)
		(end 123.10364 -291.601906)
		(width 0.1143)
		(layer "In13.Cu")
		(net "P5E_CPU1_P2_TX_DP<11>")
	)
	(segment
		(start 145.585688 -348.759272)
		(end 150.736046 -358.961436)
		(width 0.14224)
		(layer "In13.Cu")
		(net "P5E_CPU1_P2_TX_DP<11>")
	)
	(segment
		(start 150.736046 -358.961436)
		(end 152.266396 -361.187746)
		(width 0.14224)
		(layer "In13.Cu")
		(net "P5E_CPU1_P2_TX_DP<11>")
	)
	(segment
		(start 123.032774 -291.560758)
		(end 123.070874 -291.58311)
		(width 0.1143)
		(layer "In13.Cu")
		(net "P5E_CPU1_P2_TX_DP<11>")
	)
	(segment
		(start 123.067318 -292.231572)
		(end 123.066302 -292.23208)
		(width 0.1143)
		(layer "In13.Cu")
		(net "P5E_CPU1_P2_TX_DP<11>")
	)
	(segment
		(start 124.186696 -297.96486)
		(end 124.815092 -299.013626)
		(width 0.14224)
		(layer "In13.Cu")
		(net "P5E_CPU1_P2_TX_DP<11>")
	)
	(segment
		(start 140.261086 -322.53174)
		(end 140.424916 -323.069966)
		(width 0.14224)
		(layer "In13.Cu")
		(net "P5E_CPU1_P2_TX_DP<11>")
	)
	(segment
		(start 123.032774 -281.84094)
		(end 123.070874 -281.863292)
		(width 0.1143)
		(layer "In13.Cu")
		(net "P5E_CPU1_P2_TX_DP<11>")
	)
	(segment
		(start 123.039632 -283.465016)
		(end 123.040394 -283.465524)
		(width 0.1143)
		(layer "In13.Cu")
		(net "P5E_CPU1_P2_TX_DP<11>")
	)
	(segment
		(start 123.032774 -286.700976)
		(end 123.105418 -286.743394)
		(width 0.1143)
		(layer "In13.Cu")
		(net "P5E_CPU1_P2_TX_DP<11>")
	)
	(segment
		(start 123.07189 -288.988754)
		(end 123.070874 -288.989262)
		(width 0.1143)
		(layer "In13.Cu")
		(net "P5E_CPU1_P2_TX_DP<11>")
	)
	(segment
		(start 123.032774 -294.800782)
		(end 123.070874 -294.823134)
		(width 0.1143)
		(layer "In13.Cu")
		(net "P5E_CPU1_P2_TX_DP<11>")
	)
	(segment
		(start 123.07189 -283.483812)
		(end 123.072652 -283.48432)
		(width 0.1143)
		(layer "In13.Cu")
		(net "P5E_CPU1_P2_TX_DP<11>")
	)
	(segment
		(start 123.07189 -282.50896)
		(end 123.070874 -282.509468)
		(width 0.1143)
		(layer "In13.Cu")
		(net "P5E_CPU1_P2_TX_DP<11>")
	)
	(segment
		(start 123.075446 -290.606988)
		(end 123.074938 -290.606988)
		(width 0.1143)
		(layer "In13.Cu")
		(net "P5E_CPU1_P2_TX_DP<11>")
	)
	(segment
		(start 124.815092 -299.013626)
		(end 134.646162 -312.269632)
		(width 0.14224)
		(layer "In13.Cu")
		(net "P5E_CPU1_P2_TX_DP<11>")
	)
	(segment
		(start 123.033282 -280.911554)
		(end 123.032774 -280.911808)
		(width 0.1143)
		(layer "In13.Cu")
		(net "P5E_CPU1_P2_TX_DP<11>")
	)
	(segment
		(start 123.10872 -292.206934)
		(end 123.10364 -292.21049)
		(width 0.1143)
		(layer "In13.Cu")
		(net "P5E_CPU1_P2_TX_DP<11>")
	)
	(segment
		(start 123.92787 -296.885614)
		(end 123.928378 -296.886122)
		(width 0.14224)
		(layer "In13.Cu")
		(net "P5E_CPU1_P2_TX_DP<11>")
	)
	(segment
		(start 123.07189 -280.243788)
		(end 123.10237 -280.261568)
		(width 0.1143)
		(layer "In13.Cu")
		(net "P5E_CPU1_P2_TX_DP<11>")
	)
	(segment
		(start 123.070874 -285.749492)
		(end 123.032774 -285.771844)
		(width 0.1143)
		(layer "In13.Cu")
		(net "P5E_CPU1_P2_TX_DP<11>")
	)
	(segment
		(start 123.97359 -296.792396)
		(end 123.92787 -296.838116)
		(width 0.1143)
		(layer "In13.Cu")
		(net "P5E_CPU1_P2_TX_DP<11>")
	)
	(segment
		(start 123.070874 -294.823134)
		(end 123.07443 -294.824912)
		(width 0.1143)
		(layer "In13.Cu")
		(net "P5E_CPU1_P2_TX_DP<11>")
	)
	(segment
		(start 123.07189 -277.648924)
		(end 123.032774 -277.671784)
		(width 0.1143)
		(layer "In13.Cu")
		(net "P5E_CPU1_P2_TX_DP<11>")
	)
	(segment
		(start 123.032774 -285.080964)
		(end 123.070874 -285.103316)
		(width 0.1143)
		(layer "In13.Cu")
		(net "P5E_CPU1_P2_TX_DP<11>")
	)
	(segment
		(start 123.074684 -281.865578)
		(end 123.075192 -281.865578)
		(width 0.1143)
		(layer "In13.Cu")
		(net "P5E_CPU1_P2_TX_DP<11>")
	)
	(segment
		(start 135.973058 -314.25515)
		(end 139.793472 -321.402964)
		(width 0.14224)
		(layer "In13.Cu")
		(net "P5E_CPU1_P2_TX_DP<11>")
	)
	(segment
		(start 123.068842 -292.230556)
		(end 123.067318 -292.231572)
		(width 0.1143)
		(layer "In13.Cu")
		(net "P5E_CPU1_P2_TX_DP<11>")
	)
	(segment
		(start 123.070874 -293.203122)
		(end 123.07189 -293.20363)
		(width 0.1143)
		(layer "In13.Cu")
		(net "P5E_CPU1_P2_TX_DP<11>")
	)
	(segment
		(start 123.070874 -281.863292)
		(end 123.07189 -281.8638)
		(width 0.1143)
		(layer "In13.Cu")
		(net "P5E_CPU1_P2_TX_DP<11>")
	)
	(segment
		(start 123.072652 -290.608512)
		(end 123.07189 -290.608766)
		(width 0.1143)
		(layer "In13.Cu")
		(net "P5E_CPU1_P2_TX_DP<11>")
	)
	(segment
		(start 123.072652 -284.128718)
		(end 123.07189 -284.128972)
		(width 0.1143)
		(layer "In13.Cu")
		(net "P5E_CPU1_P2_TX_DP<11>")
	)
	(segment
		(start 123.07189 -275.383752)
		(end 123.10237 -275.401532)
		(width 0.1143)
		(layer "In13.Cu")
		(net "P5E_CPU1_P2_TX_DP<11>")
	)
	(segment
		(start 139.793472 -321.402964)
		(end 140.261086 -322.53174)
		(width 0.14224)
		(layer "In13.Cu")
		(net "P5E_CPU1_P2_TX_DP<11>")
	)
	(segment
		(start 123.92787 -296.838116)
		(end 123.92787 -296.866564)
		(width 0.1143)
		(layer "In13.Cu")
		(net "P5E_CPU1_P2_TX_DP<11>")
	)
	(segment
		(start 140.424916 -323.069966)
		(end 145.585688 -348.759272)
		(width 0.14224)
		(layer "In13.Cu")
		(net "P5E_CPU1_P2_TX_DP<11>")
	)
	(segment
		(start 123.039124 -288.324544)
		(end 123.074938 -288.345372)
		(width 0.1143)
		(layer "In13.Cu")
		(net "P5E_CPU1_P2_TX_DP<11>")
	)
	(segment
		(start 123.10364 -291.601906)
		(end 123.10872 -291.605462)
		(width 0.1143)
		(layer "In13.Cu")
		(net "P5E_CPU1_P2_TX_DP<11>")
	)
	(segment
		(start 162.683698 -367.730024)
		(end 163.084764 -368.13109)
		(width 0.14224)
		(layer "In13.Cu")
		(net "P5E_CPU1_P2_TX_DP<11>")
	)
	(segment
		(start 123.072652 -289.964114)
		(end 123.074684 -289.965384)
		(width 0.1143)
		(layer "In13.Cu")
		(net "P5E_CPU1_P2_TX_DP<11>")
	)
	(segment
		(start 123.729496 -295.956228)
		(end 123.729496 -296.208196)
		(width 0.1143)
		(layer "In13.Cu")
		(net "P5E_CPU1_P2_TX_DP<11>")
	)
	(segment
		(start 123.032774 -275.360892)
		(end 123.07189 -275.383752)
		(width 0.1143)
		(layer "In13.Cu")
		(net "P5E_CPU1_P2_TX_DP<11>")
	)
	(segment
		(start 123.074938 -293.847012)
		(end 123.072652 -293.848536)
		(width 0.1143)
		(layer "In13.Cu")
		(net "P5E_CPU1_P2_TX_DP<11>")
	)
	(segment
		(start 123.07189 -284.128972)
		(end 123.070874 -284.12948)
		(width 0.1143)
		(layer "In13.Cu")
		(net "P5E_CPU1_P2_TX_DP<11>")
	)
	(segment
		(start 123.072652 -293.848536)
		(end 123.07189 -293.84879)
		(width 0.1143)
		(layer "In13.Cu")
		(net "P5E_CPU1_P2_TX_DP<11>")
	)
	(segment
		(start 123.07189 -276.028912)
		(end 123.032774 -276.051772)
		(width 0.1143)
		(layer "In13.Cu")
		(net "P5E_CPU1_P2_TX_DP<11>")
	)
	(segment
		(start 123.074938 -288.345372)
		(end 123.075192 -288.345372)
		(width 0.1143)
		(layer "In13.Cu")
		(net "P5E_CPU1_P2_TX_DP<11>")
	)
	(segment
		(start 123.07189 -280.888948)
		(end 123.033282 -280.911554)
		(width 0.1143)
		(layer "In13.Cu")
		(net "P5E_CPU1_P2_TX_DP<11>")
	)
	(segment
		(start 123.07189 -285.103824)
		(end 123.072652 -285.104332)
		(width 0.1143)
		(layer "In13.Cu")
		(net "P5E_CPU1_P2_TX_DP<11>")
	)
	(segment
		(start 123.072652 -282.508706)
		(end 123.07189 -282.50896)
		(width 0.1143)
		(layer "In13.Cu")
		(net "P5E_CPU1_P2_TX_DP<11>")
	)
	(segment
		(start 123.10745 -287.34766)
		(end 123.10364 -287.350454)
		(width 0.1143)
		(layer "In13.Cu")
		(net "P5E_CPU1_P2_TX_DP<11>")
	)
	(segment
		(start 123.542552 -295.634156)
		(end 123.57354 -295.651936)
		(width 0.1143)
		(layer "In13.Cu")
		(net "P5E_CPU1_P2_TX_DP<11>")
	)
	(segment
		(start 123.540774 -295.63314)
		(end 123.54179 -295.633648)
		(width 0.1143)
		(layer "In13.Cu")
		(net "P5E_CPU1_P2_TX_DP<11>")
	)
	(segment
		(start 123.032774 -283.460952)
		(end 123.039632 -283.465016)
		(width 0.1143)
		(layer "In13.Cu")
		(net "P5E_CPU1_P2_TX_DP<11>")
	)
	(segment
		(start 123.928378 -297.340528)
		(end 124.186696 -297.96486)
		(width 0.14224)
		(layer "In13.Cu")
		(net "P5E_CPU1_P2_TX_DP<11>")
	)
	(segment
		(start 123.074938 -290.606988)
		(end 123.072652 -290.608512)
		(width 0.1143)
		(layer "In13.Cu")
		(net "P5E_CPU1_P2_TX_DP<11>")
	)
	(segment
		(start 123.072652 -283.48432)
		(end 123.074684 -283.48559)
		(width 0.1143)
		(layer "In13.Cu")
		(net "P5E_CPU1_P2_TX_DP<11>")
	)
	(segment
		(start 163.355274 -371.2083)
		(end 163.064444 -371.49913)
		(width 0.14224)
		(layer "In13.Cu")
		(net "P5E_CPU1_P2_TX_DP<11>")
	)
	(segment
		(start 123.07189 -279.268936)
		(end 123.032774 -279.291796)
		(width 0.1143)
		(layer "In13.Cu")
		(net "P5E_CPU1_P2_TX_DP<11>")
	)
	(segment
		(start 123.074684 -289.965384)
		(end 123.075192 -289.965384)
		(width 0.1143)
		(layer "In13.Cu")
		(net "P5E_CPU1_P2_TX_DP<11>")
	)
	(segment
		(start 123.075446 -282.507182)
		(end 123.074938 -282.507182)
		(width 0.1143)
		(layer "In13.Cu")
		(net "P5E_CPU1_P2_TX_DP<11>")
	)
	(segment
		(start 123.074938 -282.507182)
		(end 123.072652 -282.508706)
		(width 0.1143)
		(layer "In13.Cu")
		(net "P5E_CPU1_P2_TX_DP<11>")
	)
	(segment
		(start 123.075446 -285.747206)
		(end 123.074938 -285.747206)
		(width 0.1143)
		(layer "In13.Cu")
		(net "P5E_CPU1_P2_TX_DP<11>")
	)
	(segment
		(start 123.032774 -293.18077)
		(end 123.070874 -293.203122)
		(width 0.1143)
		(layer "In13.Cu")
		(net "P5E_CPU1_P2_TX_DP<11>")
	)
	(segment
		(start 123.070874 -288.989262)
		(end 123.032774 -289.011614)
		(width 0.1143)
		(layer "In13.Cu")
		(net "P5E_CPU1_P2_TX_DP<11>")
	)
	(segment
		(start 123.032774 -273.74088)
		(end 123.07189 -273.76374)
		(width 0.1143)
		(layer "In13.Cu")
		(net "P5E_CPU1_P2_TX_DP<11>")
	)
	(segment
		(start 123.074938 -288.986976)
		(end 123.072652 -288.9885)
		(width 0.1143)
		(layer "In13.Cu")
		(net "P5E_CPU1_P2_TX_DP<11>")
	)
	(segment
		(start 134.646162 -312.269632)
		(end 135.973058 -314.25515)
		(width 0.14224)
		(layer "In13.Cu")
		(net "P5E_CPU1_P2_TX_DP<11>")
	)
	(segment
		(start 161.435542 -366.896142)
		(end 162.683698 -367.730024)
		(width 0.14224)
		(layer "In13.Cu")
		(net "P5E_CPU1_P2_TX_DP<11>")
	)
	(segment
		(start 123.075446 -288.986976)
		(end 123.074938 -288.986976)
		(width 0.1143)
		(layer "In13.Cu")
		(net "P5E_CPU1_P2_TX_DP<11>")
	)
	(segment
		(start 122.712734 -273.276314)
		(end 122.795538 -273.359118)
		(width 0.1143)
		(layer "In13.Cu")
		(net "P5E_CPU1_P2_TX_DP<11>")
	)
	(segment
		(start 123.07189 -277.003764)
		(end 123.10237 -277.021544)
		(width 0.1143)
		(layer "In13.Cu")
		(net "P5E_CPU1_P2_TX_DP<11>")
	)
	(segment
		(start 123.032774 -278.600916)
		(end 123.07189 -278.623776)
		(width 0.1143)
		(layer "In13.Cu")
		(net "P5E_CPU1_P2_TX_DP<11>")
	)
	(segment
		(start 123.07189 -291.583618)
		(end 123.072652 -291.584126)
		(width 0.1143)
		(layer "In13.Cu")
		(net "P5E_CPU1_P2_TX_DP<11>")
	)
	(arc
		(start 123.032774 -282.53182)
		(mid 122.789447 -282.996386)
		(end 123.032774 -283.460952)
		(width 0.1143)
		(layer "In13.Cu")
		(net "P5E_CPU1_P2_TX_DP<11>")
	)
	(arc
		(start 123.032774 -284.151832)
		(mid 122.789447 -284.616398)
		(end 123.032774 -285.080964)
		(width 0.1143)
		(layer "In13.Cu")
		(net "P5E_CPU1_P2_TX_DP<11>")
	)
	(arc
		(start 123.075192 -289.965384)
		(mid 123.259925 -290.286076)
		(end 123.075446 -290.606988)
		(width 0.1143)
		(layer "In13.Cu")
		(net "P5E_CPU1_P2_TX_DP<11>")
	)
	(arc
		(start 122.795538 -273.359118)
		(mid 122.797326 -273.370567)
		(end 122.799348 -273.381978)
		(width 0.1143)
		(layer "In13.Cu")
		(net "P5E_CPU1_P2_TX_DP<11>")
	)
	(arc
		(start 123.032774 -279.291796)
		(mid 122.789447 -279.756362)
		(end 123.032774 -280.220928)
		(width 0.1143)
		(layer "In13.Cu")
		(net "P5E_CPU1_P2_TX_DP<11>")
	)
	(arc
		(start 123.10237 -273.78152)
		(mid 123.259347 -274.08632)
		(end 123.10237 -274.39112)
		(width 0.1143)
		(layer "In13.Cu")
		(net "P5E_CPU1_P2_TX_DP<11>")
	)
	(arc
		(start 123.032774 -285.771844)
		(mid 122.789447 -286.23641)
		(end 123.032774 -286.700976)
		(width 0.1143)
		(layer "In13.Cu")
		(net "P5E_CPU1_P2_TX_DP<11>")
	)
	(arc
		(start 123.10237 -275.401532)
		(mid 123.259347 -275.706332)
		(end 123.10237 -276.011132)
		(width 0.1143)
		(layer "In13.Cu")
		(net "P5E_CPU1_P2_TX_DP<11>")
	)
	(arc
		(start 123.259342 -295.146222)
		(mid 123.323857 -295.408441)
		(end 123.502674 -295.610788)
		(width 0.1143)
		(layer "In13.Cu")
		(net "P5E_CPU1_P2_TX_DP<11>")
	)
	(arc
		(start 123.032774 -280.911808)
		(mid 122.789447 -281.376374)
		(end 123.032774 -281.84094)
		(width 0.1143)
		(layer "In13.Cu")
		(net "P5E_CPU1_P2_TX_DP<11>")
	)
	(arc
		(start 123.032774 -292.251638)
		(mid 122.789447 -292.716204)
		(end 123.032774 -293.18077)
		(width 0.1143)
		(layer "In13.Cu")
		(net "P5E_CPU1_P2_TX_DP<11>")
	)
	(arc
		(start 123.032774 -274.43176)
		(mid 122.789447 -274.896326)
		(end 123.032774 -275.360892)
		(width 0.1143)
		(layer "In13.Cu")
		(net "P5E_CPU1_P2_TX_DP<11>")
	)
	(arc
		(start 123.10237 -280.261568)
		(mid 123.259347 -280.566368)
		(end 123.10237 -280.871168)
		(width 0.1143)
		(layer "In13.Cu")
		(net "P5E_CPU1_P2_TX_DP<11>")
	)
	(arc
		(start 123.104656 -294.842946)
		(mid 123.218539 -294.97356)
		(end 123.259596 -295.141904)
		(width 0.1143)
		(layer "In13.Cu")
		(net "P5E_CPU1_P2_TX_DP<11>")
	)
	(arc
		(start 123.075192 -281.865578)
		(mid 123.259925 -282.18627)
		(end 123.075446 -282.507182)
		(width 0.1143)
		(layer "In13.Cu")
		(net "P5E_CPU1_P2_TX_DP<11>")
	)
	(arc
		(start 123.032774 -290.631626)
		(mid 122.789447 -291.096192)
		(end 123.032774 -291.560758)
		(width 0.1143)
		(layer "In13.Cu")
		(net "P5E_CPU1_P2_TX_DP<11>")
	)
	(arc
		(start 123.032774 -293.87165)
		(mid 122.789447 -294.336216)
		(end 123.032774 -294.800782)
		(width 0.1143)
		(layer "In13.Cu")
		(net "P5E_CPU1_P2_TX_DP<11>")
	)
	(arc
		(start 123.032774 -276.051772)
		(mid 122.789447 -276.516338)
		(end 123.032774 -276.980904)
		(width 0.1143)
		(layer "In13.Cu")
		(net "P5E_CPU1_P2_TX_DP<11>")
	)
	(arc
		(start 123.075192 -288.345372)
		(mid 123.259925 -288.666064)
		(end 123.075446 -288.986976)
		(width 0.1143)
		(layer "In13.Cu")
		(net "P5E_CPU1_P2_TX_DP<11>")
	)
	(arc
		(start 123.032774 -289.011614)
		(mid 122.789447 -289.47618)
		(end 123.032774 -289.940746)
		(width 0.1143)
		(layer "In13.Cu")
		(net "P5E_CPU1_P2_TX_DP<11>")
	)
	(arc
		(start 123.035314 -287.390078)
		(mid 122.854662 -287.592823)
		(end 122.789442 -287.856422)
		(width 0.1143)
		(layer "In13.Cu")
		(net "P5E_CPU1_P2_TX_DP<11>")
	)
	(arc
		(start 163.084764 -368.13109)
		(mid 163.28496 -368.430705)
		(end 163.355274 -368.784124)
		(width 0.14224)
		(layer "In13.Cu")
		(net "P5E_CPU1_P2_TX_DP<11>")
	)
	(arc
		(start 123.075192 -283.48559)
		(mid 123.259925 -283.806282)
		(end 123.075446 -284.127194)
		(width 0.1143)
		(layer "In13.Cu")
		(net "P5E_CPU1_P2_TX_DP<11>")
	)
	(arc
		(start 123.105418 -286.743394)
		(mid 123.218825 -286.876283)
		(end 123.259596 -287.046162)
		(width 0.1143)
		(layer "In13.Cu")
		(net "P5E_CPU1_P2_TX_DP<11>")
	)
	(arc
		(start 122.799348 -273.381978)
		(mid 122.880781 -273.584376)
		(end 123.032774 -273.74088)
		(width 0.1143)
		(layer "In13.Cu")
		(net "P5E_CPU1_P2_TX_DP<11>")
	)
	(arc
		(start 123.259596 -287.050734)
		(mid 123.219341 -287.217547)
		(end 123.10745 -287.34766)
		(width 0.1143)
		(layer "In13.Cu")
		(net "P5E_CPU1_P2_TX_DP<11>")
	)
	(arc
		(start 123.032774 -277.671784)
		(mid 122.789447 -278.13635)
		(end 123.032774 -278.600916)
		(width 0.1143)
		(layer "In13.Cu")
		(net "P5E_CPU1_P2_TX_DP<11>")
	)
	(arc
		(start 123.075192 -293.205408)
		(mid 123.259925 -293.5261)
		(end 123.075446 -293.847012)
		(width 0.1143)
		(layer "In13.Cu")
		(net "P5E_CPU1_P2_TX_DP<11>")
	)
	(arc
		(start 122.789442 -287.856422)
		(mid 122.853957 -288.118641)
		(end 123.032774 -288.320988)
		(width 0.1143)
		(layer "In13.Cu")
		(net "P5E_CPU1_P2_TX_DP<11>")
	)
	(arc
		(start 123.075192 -285.105602)
		(mid 123.259925 -285.426294)
		(end 123.075446 -285.747206)
		(width 0.1143)
		(layer "In13.Cu")
		(net "P5E_CPU1_P2_TX_DP<11>")
	)
	(arc
		(start 123.10872 -291.605462)
		(mid 123.262818 -291.906198)
		(end 123.10872 -292.206934)
		(width 0.1143)
		(layer "In13.Cu")
		(net "P5E_CPU1_P2_TX_DP<11>")
	)
	(arc
		(start 123.57354 -295.651936)
		(mid 123.688216 -295.78527)
		(end 123.729496 -295.956228)
		(width 0.1143)
		(layer "In13.Cu")
		(net "P5E_CPU1_P2_TX_DP<11>")
	)
	(arc
		(start 123.10237 -277.021544)
		(mid 123.259347 -277.326344)
		(end 123.10237 -277.631144)
		(width 0.1143)
		(layer "In13.Cu")
		(net "P5E_CPU1_P2_TX_DP<11>")
	)
	(arc
		(start 123.10237 -278.641556)
		(mid 123.259347 -278.946356)
		(end 123.10237 -279.251156)
		(width 0.1143)
		(layer "In13.Cu")
		(net "P5E_CPU1_P2_TX_DP<11>")
	)
	(segment
		(start 161.633154 -374.93702)
		(end 161.337244 -375.23293)
		(width 0.12954)
		(layer "F.Cu")
		(net "P5E_CPU1_P2_TX_DP<10>")
	)
	(segment
		(start 161.633154 -374.23344)
		(end 161.633154 -374.93702)
		(width 0.12954)
		(layer "F.Cu")
		(net "P5E_CPU1_P2_TX_DP<10>")
	)
	(segment
		(start 161.362644 -373.96293)
		(end 161.633154 -374.23344)
		(width 0.12954)
		(layer "F.Cu")
		(net "P5E_CPU1_P2_TX_DP<10>")
	)
	(segment
		(start 121.94794 -269.770352)
		(end 122.414792 -270.03629)
		(width 0.12954)
		(layer "F.Cu")
		(net "P5E_CPU1_P2_TX_DP<10>")
	)
	(segment
		(start 122.132598 -281.864308)
		(end 122.133868 -281.86507)
		(width 0.1143)
		(layer "In13.Cu")
		(net "P5E_CPU1_P2_TX_DP<10>")
	)
	(segment
		(start 122.124216 -292.23335)
		(end 122.09272 -292.251638)
		(width 0.1143)
		(layer "In13.Cu")
		(net "P5E_CPU1_P2_TX_DP<10>")
	)
	(segment
		(start 122.127518 -290.611306)
		(end 122.124978 -290.61283)
		(width 0.1143)
		(layer "In13.Cu")
		(net "P5E_CPU1_P2_TX_DP<10>")
	)
	(segment
		(start 122.136662 -293.206424)
		(end 122.137424 -293.206932)
		(width 0.1143)
		(layer "In13.Cu")
		(net "P5E_CPU1_P2_TX_DP<10>")
	)
	(segment
		(start 122.87631 -296.28846)
		(end 122.87631 -296.538396)
		(width 0.1143)
		(layer "In13.Cu")
		(net "P5E_CPU1_P2_TX_DP<10>")
	)
	(segment
		(start 122.133868 -285.105094)
		(end 122.163586 -285.122112)
		(width 0.1143)
		(layer "In13.Cu")
		(net "P5E_CPU1_P2_TX_DP<10>")
	)
	(segment
		(start 122.831098 -297.131486)
		(end 123.353576 -298.393866)
		(width 0.14224)
		(layer "In13.Cu")
		(net "P5E_CPU1_P2_TX_DP<10>")
	)
	(segment
		(start 122.133868 -283.485082)
		(end 122.163586 -283.5021)
		(width 0.1143)
		(layer "In13.Cu")
		(net "P5E_CPU1_P2_TX_DP<10>")
	)
	(segment
		(start 122.09272 -273.74088)
		(end 122.131836 -273.76374)
		(width 0.1143)
		(layer "In13.Cu")
		(net "P5E_CPU1_P2_TX_DP<10>")
	)
	(segment
		(start 122.136662 -281.866594)
		(end 122.137424 -281.867102)
		(width 0.1143)
		(layer "In13.Cu")
		(net "P5E_CPU1_P2_TX_DP<10>")
	)
	(segment
		(start 161.453322 -370.713508)
		(end 161.621978 -371.015514)
		(width 0.14224)
		(layer "In13.Cu")
		(net "P5E_CPU1_P2_TX_DP<10>")
	)
	(segment
		(start 122.602498 -270.358362)
		(end 122.601736 -270.35887)
		(width 0.1143)
		(layer "In13.Cu")
		(net "P5E_CPU1_P2_TX_DP<10>")
	)
	(segment
		(start 122.09272 -288.320988)
		(end 122.131836 -288.343848)
		(width 0.1143)
		(layer "In13.Cu")
		(net "P5E_CPU1_P2_TX_DP<10>")
	)
	(segment
		(start 133.35381 -312.096404)
		(end 135.238998 -314.917074)
		(width 0.14224)
		(layer "In13.Cu")
		(net "P5E_CPU1_P2_TX_DP<10>")
	)
	(segment
		(start 122.127518 -292.231318)
		(end 122.124978 -292.232842)
		(width 0.1143)
		(layer "In13.Cu")
		(net "P5E_CPU1_P2_TX_DP<10>")
	)
	(segment
		(start 122.13082 -282.509468)
		(end 122.129296 -282.510484)
		(width 0.1143)
		(layer "In13.Cu")
		(net "P5E_CPU1_P2_TX_DP<10>")
	)
	(segment
		(start 122.12828 -284.131004)
		(end 122.127518 -284.131512)
		(width 0.1143)
		(layer "In13.Cu")
		(net "P5E_CPU1_P2_TX_DP<10>")
	)
	(segment
		(start 122.135392 -281.865832)
		(end 122.136662 -281.866594)
		(width 0.1143)
		(layer "In13.Cu")
		(net "P5E_CPU1_P2_TX_DP<10>")
	)
	(segment
		(start 122.09272 -276.980904)
		(end 122.131836 -277.003764)
		(width 0.1143)
		(layer "In13.Cu")
		(net "P5E_CPU1_P2_TX_DP<10>")
	)
	(segment
		(start 138.916156 -321.795394)
		(end 139.4333 -323.043804)
		(width 0.14224)
		(layer "In13.Cu")
		(net "P5E_CPU1_P2_TX_DP<10>")
	)
	(segment
		(start 122.133868 -284.127702)
		(end 122.132598 -284.128464)
		(width 0.1143)
		(layer "In13.Cu")
		(net "P5E_CPU1_P2_TX_DP<10>")
	)
	(segment
		(start 122.12828 -290.610798)
		(end 122.127518 -290.611306)
		(width 0.1143)
		(layer "In13.Cu")
		(net "P5E_CPU1_P2_TX_DP<10>")
	)
	(segment
		(start 122.133868 -293.2049)
		(end 122.135392 -293.205662)
		(width 0.1143)
		(layer "In13.Cu")
		(net "P5E_CPU1_P2_TX_DP<10>")
	)
	(segment
		(start 122.09272 -275.360892)
		(end 122.131836 -275.383752)
		(width 0.1143)
		(layer "In13.Cu")
		(net "P5E_CPU1_P2_TX_DP<10>")
	)
	(segment
		(start 122.131836 -294.823642)
		(end 122.132598 -294.82415)
		(width 0.1143)
		(layer "In13.Cu")
		(net "P5E_CPU1_P2_TX_DP<10>")
	)
	(segment
		(start 122.099578 -294.804846)
		(end 122.10034 -294.805354)
		(width 0.1143)
		(layer "In13.Cu")
		(net "P5E_CPU1_P2_TX_DP<10>")
	)
	(segment
		(start 122.09272 -281.84094)
		(end 122.099578 -281.845004)
		(width 0.1143)
		(layer "In13.Cu")
		(net "P5E_CPU1_P2_TX_DP<10>")
	)
	(segment
		(start 122.132598 -285.104332)
		(end 122.133868 -285.105094)
		(width 0.1143)
		(layer "In13.Cu")
		(net "P5E_CPU1_P2_TX_DP<10>")
	)
	(segment
		(start 122.13082 -283.483304)
		(end 122.131836 -283.483812)
		(width 0.1143)
		(layer "In13.Cu")
		(net "P5E_CPU1_P2_TX_DP<10>")
	)
	(segment
		(start 122.162316 -280.871168)
		(end 122.131836 -280.888948)
		(width 0.1143)
		(layer "In13.Cu")
		(net "P5E_CPU1_P2_TX_DP<10>")
	)
	(segment
		(start 122.163586 -290.590478)
		(end 122.133868 -290.607496)
		(width 0.1143)
		(layer "In13.Cu")
		(net "P5E_CPU1_P2_TX_DP<10>")
	)
	(segment
		(start 122.133868 -281.86507)
		(end 122.135392 -281.865832)
		(width 0.1143)
		(layer "In13.Cu")
		(net "P5E_CPU1_P2_TX_DP<10>")
	)
	(segment
		(start 122.124978 -288.992818)
		(end 122.124216 -288.993326)
		(width 0.1143)
		(layer "In13.Cu")
		(net "P5E_CPU1_P2_TX_DP<10>")
	)
	(segment
		(start 122.163586 -282.490672)
		(end 122.133868 -282.50769)
		(width 0.1143)
		(layer "In13.Cu")
		(net "P5E_CPU1_P2_TX_DP<10>")
	)
	(segment
		(start 122.13844 -289.967416)
		(end 122.13971 -289.968178)
		(width 0.1143)
		(layer "In13.Cu")
		(net "P5E_CPU1_P2_TX_DP<10>")
	)
	(segment
		(start 122.10034 -289.945318)
		(end 122.131836 -289.963606)
		(width 0.1143)
		(layer "In13.Cu")
		(net "P5E_CPU1_P2_TX_DP<10>")
	)
	(segment
		(start 122.124978 -282.513024)
		(end 122.124216 -282.513532)
		(width 0.1143)
		(layer "In13.Cu")
		(net "P5E_CPU1_P2_TX_DP<10>")
	)
	(segment
		(start 122.133868 -294.824912)
		(end 122.135392 -294.825674)
		(width 0.1143)
		(layer "In13.Cu")
		(net "P5E_CPU1_P2_TX_DP<10>")
	)
	(segment
		(start 122.131836 -274.4089)
		(end 122.09272 -274.43176)
		(width 0.1143)
		(layer "In13.Cu")
		(net "P5E_CPU1_P2_TX_DP<10>")
	)
	(segment
		(start 122.135392 -294.825674)
		(end 122.136662 -294.826436)
		(width 0.1143)
		(layer "In13.Cu")
		(net "P5E_CPU1_P2_TX_DP<10>")
	)
	(segment
		(start 122.13971 -294.828214)
		(end 122.14225 -294.829484)
		(width 0.1143)
		(layer "In13.Cu")
		(net "P5E_CPU1_P2_TX_DP<10>")
	)
	(segment
		(start 122.13082 -293.849298)
		(end 122.129296 -293.850314)
		(width 0.1143)
		(layer "In13.Cu")
		(net "P5E_CPU1_P2_TX_DP<10>")
	)
	(segment
		(start 122.602498 -295.634156)
		(end 122.605292 -295.63568)
		(width 0.1143)
		(layer "In13.Cu")
		(net "P5E_CPU1_P2_TX_DP<10>")
	)
	(segment
		(start 122.87631 -296.538396)
		(end 122.83059 -296.584116)
		(width 0.1143)
		(layer "In13.Cu")
		(net "P5E_CPU1_P2_TX_DP<10>")
	)
	(segment
		(start 122.124978 -292.232842)
		(end 122.124216 -292.23335)
		(width 0.1143)
		(layer "In13.Cu")
		(net "P5E_CPU1_P2_TX_DP<10>")
	)
	(segment
		(start 122.13082 -285.749492)
		(end 122.129296 -285.750508)
		(width 0.1143)
		(layer "In13.Cu")
		(net "P5E_CPU1_P2_TX_DP<10>")
	)
	(segment
		(start 122.162316 -274.39112)
		(end 122.131836 -274.4089)
		(width 0.1143)
		(layer "In13.Cu")
		(net "P5E_CPU1_P2_TX_DP<10>")
	)
	(segment
		(start 122.131836 -288.988754)
		(end 122.13082 -288.989262)
		(width 0.1143)
		(layer "In13.Cu")
		(net "P5E_CPU1_P2_TX_DP<10>")
	)
	(segment
		(start 144.60982 -349.069406)
		(end 149.70252 -359.186988)
		(width 0.14224)
		(layer "In13.Cu")
		(net "P5E_CPU1_P2_TX_DP<10>")
	)
	(segment
		(start 122.14225 -293.209472)
		(end 122.163586 -293.221918)
		(width 0.1143)
		(layer "In13.Cu")
		(net "P5E_CPU1_P2_TX_DP<10>")
	)
	(segment
		(start 122.131836 -289.963606)
		(end 122.132598 -289.964114)
		(width 0.1143)
		(layer "In13.Cu")
		(net "P5E_CPU1_P2_TX_DP<10>")
	)
	(segment
		(start 122.607578 -295.63695)
		(end 122.60834 -295.637458)
		(width 0.1143)
		(layer "In13.Cu")
		(net "P5E_CPU1_P2_TX_DP<10>")
	)
	(segment
		(start 122.13082 -291.58311)
		(end 122.131836 -291.583618)
		(width 0.1143)
		(layer "In13.Cu")
		(net "P5E_CPU1_P2_TX_DP<10>")
	)
	(segment
		(start 122.13082 -284.12948)
		(end 122.129296 -284.130496)
		(width 0.1143)
		(layer "In13.Cu")
		(net "P5E_CPU1_P2_TX_DP<10>")
	)
	(segment
		(start 139.4333 -323.043804)
		(end 144.60982 -349.069406)
		(width 0.14224)
		(layer "In13.Cu")
		(net "P5E_CPU1_P2_TX_DP<10>")
	)
	(segment
		(start 122.132598 -288.988246)
		(end 122.131836 -288.988754)
		(width 0.1143)
		(layer "In13.Cu")
		(net "P5E_CPU1_P2_TX_DP<10>")
	)
	(segment
		(start 122.099578 -293.184834)
		(end 122.10034 -293.185342)
		(width 0.1143)
		(layer "In13.Cu")
		(net "P5E_CPU1_P2_TX_DP<10>")
	)
	(segment
		(start 122.093228 -280.911554)
		(end 122.09272 -280.911808)
		(width 0.1143)
		(layer "In13.Cu")
		(net "P5E_CPU1_P2_TX_DP<10>")
	)
	(segment
		(start 122.162316 -277.631144)
		(end 122.131836 -277.648924)
		(width 0.1143)
		(layer "In13.Cu")
		(net "P5E_CPU1_P2_TX_DP<10>")
	)
	(segment
		(start 122.129296 -292.230302)
		(end 122.12828 -292.23081)
		(width 0.1143)
		(layer "In13.Cu")
		(net "P5E_CPU1_P2_TX_DP<10>")
	)
	(segment
		(start 122.09272 -286.700976)
		(end 122.131836 -286.723836)
		(width 0.1143)
		(layer "In13.Cu")
		(net "P5E_CPU1_P2_TX_DP<10>")
	)
	(segment
		(start 122.099578 -289.94481)
		(end 122.10034 -289.945318)
		(width 0.1143)
		(layer "In13.Cu")
		(net "P5E_CPU1_P2_TX_DP<10>")
	)
	(segment
		(start 122.137424 -294.826944)
		(end 122.13844 -294.827452)
		(width 0.1143)
		(layer "In13.Cu")
		(net "P5E_CPU1_P2_TX_DP<10>")
	)
	(segment
		(start 122.127518 -288.991294)
		(end 122.124978 -288.992818)
		(width 0.1143)
		(layer "In13.Cu")
		(net "P5E_CPU1_P2_TX_DP<10>")
	)
	(segment
		(start 122.597418 -270.36141)
		(end 122.595386 -270.36268)
		(width 0.1143)
		(layer "In13.Cu")
		(net "P5E_CPU1_P2_TX_DP<10>")
	)
	(segment
		(start 122.09272 -285.080964)
		(end 122.13082 -285.103316)
		(width 0.1143)
		(layer "In13.Cu")
		(net "P5E_CPU1_P2_TX_DP<10>")
	)
	(segment
		(start 122.131836 -280.243788)
		(end 122.162316 -280.261568)
		(width 0.1143)
		(layer "In13.Cu")
		(net "P5E_CPU1_P2_TX_DP<10>")
	)
	(segment
		(start 122.131836 -272.143728)
		(end 122.162316 -272.161508)
		(width 0.1143)
		(layer "In13.Cu")
		(net "P5E_CPU1_P2_TX_DP<10>")
	)
	(segment
		(start 122.12828 -288.990786)
		(end 122.127518 -288.991294)
		(width 0.1143)
		(layer "In13.Cu")
		(net "P5E_CPU1_P2_TX_DP<10>")
	)
	(segment
		(start 159.955738 -367.914174)
		(end 159.955738 -369.394232)
		(width 0.14224)
		(layer "In13.Cu")
		(net "P5E_CPU1_P2_TX_DP<10>")
	)
	(segment
		(start 122.131836 -271.168876)
		(end 122.09272 -271.191736)
		(width 0.1143)
		(layer "In13.Cu")
		(net "P5E_CPU1_P2_TX_DP<10>")
	)
	(segment
		(start 122.133868 -282.50769)
		(end 122.132598 -282.508452)
		(width 0.1143)
		(layer "In13.Cu")
		(net "P5E_CPU1_P2_TX_DP<10>")
	)
	(segment
		(start 122.132598 -285.748476)
		(end 122.131836 -285.748984)
		(width 0.1143)
		(layer "In13.Cu")
		(net "P5E_CPU1_P2_TX_DP<10>")
	)
	(segment
		(start 122.127518 -284.131512)
		(end 122.124978 -284.133036)
		(width 0.1143)
		(layer "In13.Cu")
		(net "P5E_CPU1_P2_TX_DP<10>")
	)
	(segment
		(start 122.132598 -294.82415)
		(end 122.133868 -294.824912)
		(width 0.1143)
		(layer "In13.Cu")
		(net "P5E_CPU1_P2_TX_DP<10>")
	)
	(segment
		(start 122.09272 -283.460952)
		(end 122.13082 -283.483304)
		(width 0.1143)
		(layer "In13.Cu")
		(net "P5E_CPU1_P2_TX_DP<10>")
	)
	(segment
		(start 122.131836 -282.50896)
		(end 122.13082 -282.509468)
		(width 0.1143)
		(layer "In13.Cu")
		(net "P5E_CPU1_P2_TX_DP<10>")
	)
	(segment
		(start 122.83059 -296.584116)
		(end 122.83059 -296.612564)
		(width 0.1143)
		(layer "In13.Cu")
		(net "P5E_CPU1_P2_TX_DP<10>")
	)
	(segment
		(start 158.300166 -366.646206)
		(end 159.64027 -367.54181)
		(width 0.14224)
		(layer "In13.Cu")
		(net "P5E_CPU1_P2_TX_DP<10>")
	)
	(segment
		(start 122.414792 -270.03629)
		(end 122.712734 -270.03629)
		(width 0.1143)
		(layer "In13.Cu")
		(net "P5E_CPU1_P2_TX_DP<10>")
	)
	(segment
		(start 122.13971 -289.968178)
		(end 122.14225 -289.969448)
		(width 0.1143)
		(layer "In13.Cu")
		(net "P5E_CPU1_P2_TX_DP<10>")
	)
	(segment
		(start 122.131836 -293.84879)
		(end 122.13082 -293.849298)
		(width 0.1143)
		(layer "In13.Cu")
		(net "P5E_CPU1_P2_TX_DP<10>")
	)
	(segment
		(start 149.70252 -359.186988)
		(end 151.387048 -361.642406)
		(width 0.14224)
		(layer "In13.Cu")
		(net "P5E_CPU1_P2_TX_DP<10>")
	)
	(segment
		(start 122.13082 -285.103316)
		(end 122.131836 -285.103824)
		(width 0.1143)
		(layer "In13.Cu")
		(net "P5E_CPU1_P2_TX_DP<10>")
	)
	(segment
		(start 122.131836 -276.028912)
		(end 122.09272 -276.051772)
		(width 0.1143)
		(layer "In13.Cu")
		(net "P5E_CPU1_P2_TX_DP<10>")
	)
	(segment
		(start 122.789696 -296.201846)
		(end 122.87631 -296.28846)
		(width 0.1143)
		(layer "In13.Cu")
		(net "P5E_CPU1_P2_TX_DP<10>")
	)
	(segment
		(start 122.12828 -285.751016)
		(end 122.127518 -285.751524)
		(width 0.1143)
		(layer "In13.Cu")
		(net "P5E_CPU1_P2_TX_DP<10>")
	)
	(segment
		(start 122.127518 -282.5115)
		(end 122.124978 -282.513024)
		(width 0.1143)
		(layer "In13.Cu")
		(net "P5E_CPU1_P2_TX_DP<10>")
	)
	(segment
		(start 161.60623 -373.719344)
		(end 161.362644 -373.96293)
		(width 0.14224)
		(layer "In13.Cu")
		(net "P5E_CPU1_P2_TX_DP<10>")
	)
	(segment
		(start 122.131836 -286.723836)
		(end 122.165364 -286.743394)
		(width 0.1143)
		(layer "In13.Cu")
		(net "P5E_CPU1_P2_TX_DP<10>")
	)
	(segment
		(start 123.353576 -298.393866)
		(end 124.03963 -299.538644)
		(width 0.14224)
		(layer "In13.Cu")
		(net "P5E_CPU1_P2_TX_DP<10>")
	)
	(segment
		(start 122.124216 -282.513532)
		(end 122.09272 -282.53182)
		(width 0.1143)
		(layer "In13.Cu")
		(net "P5E_CPU1_P2_TX_DP<10>")
	)
	(segment
		(start 122.10034 -293.185342)
		(end 122.131836 -293.20363)
		(width 0.1143)
		(layer "In13.Cu")
		(net "P5E_CPU1_P2_TX_DP<10>")
	)
	(segment
		(start 122.09272 -272.120868)
		(end 122.131836 -272.143728)
		(width 0.1143)
		(layer "In13.Cu")
		(net "P5E_CPU1_P2_TX_DP<10>")
	)
	(segment
		(start 122.124216 -288.993326)
		(end 122.09272 -289.011614)
		(width 0.1143)
		(layer "In13.Cu")
		(net "P5E_CPU1_P2_TX_DP<10>")
	)
	(segment
		(start 122.09272 -293.18077)
		(end 122.099578 -293.184834)
		(width 0.1143)
		(layer "In13.Cu")
		(net "P5E_CPU1_P2_TX_DP<10>")
	)
	(segment
		(start 122.124216 -285.753556)
		(end 122.09272 -285.771844)
		(width 0.1143)
		(layer "In13.Cu")
		(net "P5E_CPU1_P2_TX_DP<10>")
	)
	(segment
		(start 122.131836 -275.383752)
		(end 122.162316 -275.401532)
		(width 0.1143)
		(layer "In13.Cu")
		(net "P5E_CPU1_P2_TX_DP<10>")
	)
	(segment
		(start 122.129296 -293.850314)
		(end 122.09272 -293.87165)
		(width 0.1143)
		(layer "In13.Cu")
		(net "P5E_CPU1_P2_TX_DP<10>")
	)
	(segment
		(start 122.09272 -278.600916)
		(end 122.131836 -278.623776)
		(width 0.1143)
		(layer "In13.Cu")
		(net "P5E_CPU1_P2_TX_DP<10>")
	)
	(segment
		(start 122.132598 -290.608258)
		(end 122.131836 -290.608766)
		(width 0.1143)
		(layer "In13.Cu")
		(net "P5E_CPU1_P2_TX_DP<10>")
	)
	(segment
		(start 122.129296 -290.61029)
		(end 122.12828 -290.610798)
		(width 0.1143)
		(layer "In13.Cu")
		(net "P5E_CPU1_P2_TX_DP<10>")
	)
	(segment
		(start 122.605292 -295.63568)
		(end 122.606054 -295.636188)
		(width 0.1143)
		(layer "In13.Cu")
		(net "P5E_CPU1_P2_TX_DP<10>")
	)
	(segment
		(start 122.135392 -293.205662)
		(end 122.136662 -293.206424)
		(width 0.1143)
		(layer "In13.Cu")
		(net "P5E_CPU1_P2_TX_DP<10>")
	)
	(segment
		(start 122.56262 -295.610788)
		(end 122.60072 -295.63314)
		(width 0.1143)
		(layer "In13.Cu")
		(net "P5E_CPU1_P2_TX_DP<10>")
	)
	(segment
		(start 135.238998 -314.917074)
		(end 138.916156 -321.795394)
		(width 0.14224)
		(layer "In13.Cu")
		(net "P5E_CPU1_P2_TX_DP<10>")
	)
	(segment
		(start 122.133868 -288.987484)
		(end 122.132598 -288.988246)
		(width 0.1143)
		(layer "In13.Cu")
		(net "P5E_CPU1_P2_TX_DP<10>")
	)
	(segment
		(start 122.133868 -289.964876)
		(end 122.135392 -289.965638)
		(width 0.1143)
		(layer "In13.Cu")
		(net "P5E_CPU1_P2_TX_DP<10>")
	)
	(segment
		(start 122.09272 -291.560758)
		(end 122.13082 -291.58311)
		(width 0.1143)
		(layer "In13.Cu")
		(net "P5E_CPU1_P2_TX_DP<10>")
	)
	(segment
		(start 122.131836 -272.788888)
		(end 122.09272 -272.811748)
		(width 0.1143)
		(layer "In13.Cu")
		(net "P5E_CPU1_P2_TX_DP<10>")
	)
	(segment
		(start 122.12828 -292.23081)
		(end 122.127518 -292.231318)
		(width 0.1143)
		(layer "In13.Cu")
		(net "P5E_CPU1_P2_TX_DP<10>")
	)
	(segment
		(start 122.133868 -290.607496)
		(end 122.132598 -290.608258)
		(width 0.1143)
		(layer "In13.Cu")
		(net "P5E_CPU1_P2_TX_DP<10>")
	)
	(segment
		(start 122.132598 -284.128464)
		(end 122.131836 -284.128972)
		(width 0.1143)
		(layer "In13.Cu")
		(net "P5E_CPU1_P2_TX_DP<10>")
	)
	(segment
		(start 122.131836 -273.76374)
		(end 122.162316 -273.78152)
		(width 0.1143)
		(layer "In13.Cu")
		(net "P5E_CPU1_P2_TX_DP<10>")
	)
	(segment
		(start 122.099578 -281.845004)
		(end 122.10034 -281.845512)
		(width 0.1143)
		(layer "In13.Cu")
		(net "P5E_CPU1_P2_TX_DP<10>")
	)
	(segment
		(start 122.163586 -288.970466)
		(end 122.133868 -288.987484)
		(width 0.1143)
		(layer "In13.Cu")
		(net "P5E_CPU1_P2_TX_DP<10>")
	)
	(segment
		(start 122.131836 -293.20363)
		(end 122.132598 -293.204138)
		(width 0.1143)
		(layer "In13.Cu")
		(net "P5E_CPU1_P2_TX_DP<10>")
	)
	(segment
		(start 122.163586 -284.110684)
		(end 122.133868 -284.127702)
		(width 0.1143)
		(layer "In13.Cu")
		(net "P5E_CPU1_P2_TX_DP<10>")
	)
	(segment
		(start 122.633486 -270.340582)
		(end 122.602498 -270.358362)
		(width 0.1143)
		(layer "In13.Cu")
		(net "P5E_CPU1_P2_TX_DP<10>")
	)
	(segment
		(start 122.131836 -279.268936)
		(end 122.09272 -279.291796)
		(width 0.1143)
		(layer "In13.Cu")
		(net "P5E_CPU1_P2_TX_DP<10>")
	)
	(segment
		(start 122.129296 -284.130496)
		(end 122.12828 -284.131004)
		(width 0.1143)
		(layer "In13.Cu")
		(net "P5E_CPU1_P2_TX_DP<10>")
	)
	(segment
		(start 122.14225 -294.829484)
		(end 122.163586 -294.84193)
		(width 0.1143)
		(layer "In13.Cu")
		(net "P5E_CPU1_P2_TX_DP<10>")
	)
	(segment
		(start 153.902156 -364.417864)
		(end 155.450794 -365.45266)
		(width 0.14224)
		(layer "In13.Cu")
		(net "P5E_CPU1_P2_TX_DP<10>")
	)
	(segment
		(start 122.131836 -277.648924)
		(end 122.09272 -277.671784)
		(width 0.1143)
		(layer "In13.Cu")
		(net "P5E_CPU1_P2_TX_DP<10>")
	)
	(segment
		(start 122.129296 -282.510484)
		(end 122.12828 -282.510992)
		(width 0.1143)
		(layer "In13.Cu")
		(net "P5E_CPU1_P2_TX_DP<10>")
	)
	(segment
		(start 122.131836 -285.103824)
		(end 122.132598 -285.104332)
		(width 0.1143)
		(layer "In13.Cu")
		(net "P5E_CPU1_P2_TX_DP<10>")
	)
	(segment
		(start 122.789696 -295.956482)
		(end 122.789696 -296.201846)
		(width 0.1143)
		(layer "In13.Cu")
		(net "P5E_CPU1_P2_TX_DP<10>")
	)
	(segment
		(start 122.131836 -280.888948)
		(end 122.093228 -280.911554)
		(width 0.1143)
		(layer "In13.Cu")
		(net "P5E_CPU1_P2_TX_DP<10>")
	)
	(segment
		(start 122.131836 -285.748984)
		(end 122.13082 -285.749492)
		(width 0.1143)
		(layer "In13.Cu")
		(net "P5E_CPU1_P2_TX_DP<10>")
	)
	(segment
		(start 122.124978 -290.61283)
		(end 122.124216 -290.613338)
		(width 0.1143)
		(layer "In13.Cu")
		(net "P5E_CPU1_P2_TX_DP<10>")
	)
	(segment
		(start 122.162316 -271.151096)
		(end 122.131836 -271.168876)
		(width 0.1143)
		(layer "In13.Cu")
		(net "P5E_CPU1_P2_TX_DP<10>")
	)
	(segment
		(start 161.653474 -371.136672)
		(end 161.653474 -373.605298)
		(width 0.14224)
		(layer "In13.Cu")
		(net "P5E_CPU1_P2_TX_DP<10>")
	)
	(segment
		(start 122.163586 -292.21049)
		(end 122.133868 -292.227508)
		(width 0.1143)
		(layer "In13.Cu")
		(net "P5E_CPU1_P2_TX_DP<10>")
	)
	(segment
		(start 122.599196 -270.360394)
		(end 122.597418 -270.36141)
		(width 0.1143)
		(layer "In13.Cu")
		(net "P5E_CPU1_P2_TX_DP<10>")
	)
	(segment
		(start 122.132598 -283.48432)
		(end 122.133868 -283.485082)
		(width 0.1143)
		(layer "In13.Cu")
		(net "P5E_CPU1_P2_TX_DP<10>")
	)
	(segment
		(start 122.137424 -289.966908)
		(end 122.13844 -289.967416)
		(width 0.1143)
		(layer "In13.Cu")
		(net "P5E_CPU1_P2_TX_DP<10>")
	)
	(segment
		(start 122.124978 -285.753048)
		(end 122.124216 -285.753556)
		(width 0.1143)
		(layer "In13.Cu")
		(net "P5E_CPU1_P2_TX_DP<10>")
	)
	(segment
		(start 122.131836 -283.483812)
		(end 122.132598 -283.48432)
		(width 0.1143)
		(layer "In13.Cu")
		(net "P5E_CPU1_P2_TX_DP<10>")
	)
	(segment
		(start 122.60072 -295.63314)
		(end 122.601736 -295.633648)
		(width 0.1143)
		(layer "In13.Cu")
		(net "P5E_CPU1_P2_TX_DP<10>")
	)
	(segment
		(start 122.162316 -279.251156)
		(end 122.131836 -279.268936)
		(width 0.1143)
		(layer "In13.Cu")
		(net "P5E_CPU1_P2_TX_DP<10>")
	)
	(segment
		(start 122.136662 -289.9664)
		(end 122.137424 -289.966908)
		(width 0.1143)
		(layer "In13.Cu")
		(net "P5E_CPU1_P2_TX_DP<10>")
	)
	(segment
		(start 122.137424 -281.867102)
		(end 122.13844 -281.86761)
		(width 0.1143)
		(layer "In13.Cu")
		(net "P5E_CPU1_P2_TX_DP<10>")
	)
	(segment
		(start 122.595386 -270.36268)
		(end 122.56262 -270.38173)
		(width 0.1143)
		(layer "In13.Cu")
		(net "P5E_CPU1_P2_TX_DP<10>")
	)
	(segment
		(start 155.450794 -365.45266)
		(end 158.18866 -366.586516)
		(width 0.14224)
		(layer "In13.Cu")
		(net "P5E_CPU1_P2_TX_DP<10>")
	)
	(segment
		(start 122.131836 -287.368742)
		(end 122.09526 -287.390078)
		(width 0.1143)
		(layer "In13.Cu")
		(net "P5E_CPU1_P2_TX_DP<10>")
	)
	(segment
		(start 122.133868 -291.584888)
		(end 122.163586 -291.601906)
		(width 0.1143)
		(layer "In13.Cu")
		(net "P5E_CPU1_P2_TX_DP<10>")
	)
	(segment
		(start 122.10034 -294.805354)
		(end 122.131836 -294.823642)
		(width 0.1143)
		(layer "In13.Cu")
		(net "P5E_CPU1_P2_TX_DP<10>")
	)
	(segment
		(start 122.129296 -288.990278)
		(end 122.12828 -288.990786)
		(width 0.1143)
		(layer "In13.Cu")
		(net "P5E_CPU1_P2_TX_DP<10>")
	)
	(segment
		(start 122.131836 -288.343848)
		(end 122.165364 -288.363406)
		(width 0.1143)
		(layer "In13.Cu")
		(net "P5E_CPU1_P2_TX_DP<10>")
	)
	(segment
		(start 122.131836 -290.608766)
		(end 122.13082 -290.609274)
		(width 0.1143)
		(layer "In13.Cu")
		(net "P5E_CPU1_P2_TX_DP<10>")
	)
	(segment
		(start 122.135392 -289.965638)
		(end 122.136662 -289.9664)
		(width 0.1143)
		(layer "In13.Cu")
		(net "P5E_CPU1_P2_TX_DP<10>")
	)
	(segment
		(start 122.14225 -289.969448)
		(end 122.163586 -289.981894)
		(width 0.1143)
		(layer "In13.Cu")
		(net "P5E_CPU1_P2_TX_DP<10>")
	)
	(segment
		(start 122.124216 -290.613338)
		(end 122.09272 -290.631626)
		(width 0.1143)
		(layer "In13.Cu")
		(net "P5E_CPU1_P2_TX_DP<10>")
	)
	(segment
		(start 122.606054 -295.636188)
		(end 122.607578 -295.63695)
		(width 0.1143)
		(layer "In13.Cu")
		(net "P5E_CPU1_P2_TX_DP<10>")
	)
	(segment
		(start 122.133868 -285.747714)
		(end 122.132598 -285.748476)
		(width 0.1143)
		(layer "In13.Cu")
		(net "P5E_CPU1_P2_TX_DP<10>")
	)
	(segment
		(start 122.13082 -290.609274)
		(end 122.129296 -290.61029)
		(width 0.1143)
		(layer "In13.Cu")
		(net "P5E_CPU1_P2_TX_DP<10>")
	)
	(segment
		(start 122.14225 -281.869642)
		(end 122.163586 -281.882088)
		(width 0.1143)
		(layer "In13.Cu")
		(net "P5E_CPU1_P2_TX_DP<10>")
	)
	(segment
		(start 122.162316 -272.771108)
		(end 122.131836 -272.788888)
		(width 0.1143)
		(layer "In13.Cu")
		(net "P5E_CPU1_P2_TX_DP<10>")
	)
	(segment
		(start 122.132598 -292.22827)
		(end 122.131836 -292.228778)
		(width 0.1143)
		(layer "In13.Cu")
		(net "P5E_CPU1_P2_TX_DP<10>")
	)
	(segment
		(start 122.133868 -292.227508)
		(end 122.132598 -292.22827)
		(width 0.1143)
		(layer "In13.Cu")
		(net "P5E_CPU1_P2_TX_DP<10>")
	)
	(segment
		(start 122.163586 -293.830502)
		(end 122.131836 -293.84879)
		(width 0.1143)
		(layer "In13.Cu")
		(net "P5E_CPU1_P2_TX_DP<10>")
	)
	(segment
		(start 122.131836 -281.8638)
		(end 122.132598 -281.864308)
		(width 0.1143)
		(layer "In13.Cu")
		(net "P5E_CPU1_P2_TX_DP<10>")
	)
	(segment
		(start 122.131836 -292.228778)
		(end 122.13082 -292.229286)
		(width 0.1143)
		(layer "In13.Cu")
		(net "P5E_CPU1_P2_TX_DP<10>")
	)
	(segment
		(start 122.13844 -293.20744)
		(end 122.13971 -293.208202)
		(width 0.1143)
		(layer "In13.Cu")
		(net "P5E_CPU1_P2_TX_DP<10>")
	)
	(segment
		(start 122.131836 -277.003764)
		(end 122.162316 -277.021544)
		(width 0.1143)
		(layer "In13.Cu")
		(net "P5E_CPU1_P2_TX_DP<10>")
	)
	(segment
		(start 122.09272 -280.220928)
		(end 122.131836 -280.243788)
		(width 0.1143)
		(layer "In13.Cu")
		(net "P5E_CPU1_P2_TX_DP<10>")
	)
	(segment
		(start 124.03963 -299.538644)
		(end 133.35381 -312.096404)
		(width 0.14224)
		(layer "In13.Cu")
		(net "P5E_CPU1_P2_TX_DP<10>")
	)
	(segment
		(start 122.12828 -282.510992)
		(end 122.127518 -282.5115)
		(width 0.1143)
		(layer "In13.Cu")
		(net "P5E_CPU1_P2_TX_DP<10>")
	)
	(segment
		(start 122.13971 -281.868372)
		(end 122.14225 -281.869642)
		(width 0.1143)
		(layer "In13.Cu")
		(net "P5E_CPU1_P2_TX_DP<10>")
	)
	(segment
		(start 122.131836 -291.583618)
		(end 122.132598 -291.584126)
		(width 0.1143)
		(layer "In13.Cu")
		(net "P5E_CPU1_P2_TX_DP<10>")
	)
	(segment
		(start 122.124978 -284.133036)
		(end 122.124216 -284.133544)
		(width 0.1143)
		(layer "In13.Cu")
		(net "P5E_CPU1_P2_TX_DP<10>")
	)
	(segment
		(start 122.319542 -295.146222)
		(end 122.319288 -295.146222)
		(width 0.1143)
		(layer "In13.Cu")
		(net "P5E_CPU1_P2_TX_DP<10>")
	)
	(segment
		(start 122.09272 -289.940746)
		(end 122.099578 -289.94481)
		(width 0.1143)
		(layer "In13.Cu")
		(net "P5E_CPU1_P2_TX_DP<10>")
	)
	(segment
		(start 122.129296 -285.750508)
		(end 122.12828 -285.751016)
		(width 0.1143)
		(layer "In13.Cu")
		(net "P5E_CPU1_P2_TX_DP<10>")
	)
	(segment
		(start 122.60072 -270.359378)
		(end 122.599196 -270.360394)
		(width 0.1143)
		(layer "In13.Cu")
		(net "P5E_CPU1_P2_TX_DP<10>")
	)
	(segment
		(start 122.163586 -285.730696)
		(end 122.133868 -285.747714)
		(width 0.1143)
		(layer "In13.Cu")
		(net "P5E_CPU1_P2_TX_DP<10>")
	)
	(segment
		(start 122.127518 -285.751524)
		(end 122.124978 -285.753048)
		(width 0.1143)
		(layer "In13.Cu")
		(net "P5E_CPU1_P2_TX_DP<10>")
	)
	(segment
		(start 122.13844 -294.827452)
		(end 122.13971 -294.828214)
		(width 0.1143)
		(layer "In13.Cu")
		(net "P5E_CPU1_P2_TX_DP<10>")
	)
	(segment
		(start 122.162316 -276.011132)
		(end 122.131836 -276.028912)
		(width 0.1143)
		(layer "In13.Cu")
		(net "P5E_CPU1_P2_TX_DP<10>")
	)
	(segment
		(start 122.13082 -292.229286)
		(end 122.129296 -292.230302)
		(width 0.1143)
		(layer "In13.Cu")
		(net "P5E_CPU1_P2_TX_DP<10>")
	)
	(segment
		(start 122.13844 -281.86761)
		(end 122.13971 -281.868372)
		(width 0.1143)
		(layer "In13.Cu")
		(net "P5E_CPU1_P2_TX_DP<10>")
	)
	(segment
		(start 122.609864 -295.63822)
		(end 122.63374 -295.652444)
		(width 0.1143)
		(layer "In13.Cu")
		(net "P5E_CPU1_P2_TX_DP<10>")
	)
	(segment
		(start 122.131836 -284.128972)
		(end 122.13082 -284.12948)
		(width 0.1143)
		(layer "In13.Cu")
		(net "P5E_CPU1_P2_TX_DP<10>")
	)
	(segment
		(start 122.831098 -296.984928)
		(end 122.831098 -297.131486)
		(width 0.14224)
		(layer "In13.Cu")
		(net "P5E_CPU1_P2_TX_DP<10>")
	)
	(segment
		(start 122.83059 -296.612564)
		(end 122.83059 -296.98442)
		(width 0.14224)
		(layer "In13.Cu")
		(net "P5E_CPU1_P2_TX_DP<10>")
	)
	(segment
		(start 122.132598 -291.584126)
		(end 122.133868 -291.584888)
		(width 0.1143)
		(layer "In13.Cu")
		(net "P5E_CPU1_P2_TX_DP<10>")
	)
	(segment
		(start 122.712734 -270.03629)
		(end 122.782584 -270.10614)
		(width 0.1143)
		(layer "In13.Cu")
		(net "P5E_CPU1_P2_TX_DP<10>")
	)
	(segment
		(start 122.132598 -293.204138)
		(end 122.133868 -293.2049)
		(width 0.1143)
		(layer "In13.Cu")
		(net "P5E_CPU1_P2_TX_DP<10>")
	)
	(segment
		(start 122.13971 -293.208202)
		(end 122.14225 -293.209472)
		(width 0.1143)
		(layer "In13.Cu")
		(net "P5E_CPU1_P2_TX_DP<10>")
	)
	(segment
		(start 122.601736 -295.633648)
		(end 122.602498 -295.634156)
		(width 0.1143)
		(layer "In13.Cu")
		(net "P5E_CPU1_P2_TX_DP<10>")
	)
	(segment
		(start 122.163586 -287.350454)
		(end 122.131836 -287.368742)
		(width 0.1143)
		(layer "In13.Cu")
		(net "P5E_CPU1_P2_TX_DP<10>")
	)
	(segment
		(start 159.695388 -367.587022)
		(end 159.908494 -367.800128)
		(width 0.14224)
		(layer "In13.Cu")
		(net "P5E_CPU1_P2_TX_DP<10>")
	)
	(segment
		(start 122.124216 -284.133544)
		(end 122.09272 -284.151832)
		(width 0.1143)
		(layer "In13.Cu")
		(net "P5E_CPU1_P2_TX_DP<10>")
	)
	(segment
		(start 122.136662 -294.826436)
		(end 122.137424 -294.826944)
		(width 0.1143)
		(layer "In13.Cu")
		(net "P5E_CPU1_P2_TX_DP<10>")
	)
	(segment
		(start 122.13082 -288.989262)
		(end 122.129296 -288.990278)
		(width 0.1143)
		(layer "In13.Cu")
		(net "P5E_CPU1_P2_TX_DP<10>")
	)
	(segment
		(start 122.10034 -281.845512)
		(end 122.131836 -281.8638)
		(width 0.1143)
		(layer "In13.Cu")
		(net "P5E_CPU1_P2_TX_DP<10>")
	)
	(segment
		(start 122.83059 -296.98442)
		(end 122.831098 -296.984928)
		(width 0.14224)
		(layer "In13.Cu")
		(net "P5E_CPU1_P2_TX_DP<10>")
	)
	(segment
		(start 160.166812 -369.902486)
		(end 160.17113 -369.906804)
		(width 0.14224)
		(layer "In13.Cu")
		(net "P5E_CPU1_P2_TX_DP<10>")
	)
	(segment
		(start 122.09272 -294.800782)
		(end 122.099578 -294.804846)
		(width 0.1143)
		(layer "In13.Cu")
		(net "P5E_CPU1_P2_TX_DP<10>")
	)
	(segment
		(start 122.601736 -270.35887)
		(end 122.60072 -270.359378)
		(width 0.1143)
		(layer "In13.Cu")
		(net "P5E_CPU1_P2_TX_DP<10>")
	)
	(segment
		(start 151.387048 -361.642406)
		(end 153.902156 -364.417864)
		(width 0.14224)
		(layer "In13.Cu")
		(net "P5E_CPU1_P2_TX_DP<10>")
	)
	(segment
		(start 122.131836 -278.623776)
		(end 122.162316 -278.641556)
		(width 0.1143)
		(layer "In13.Cu")
		(net "P5E_CPU1_P2_TX_DP<10>")
	)
	(segment
		(start 122.137424 -293.206932)
		(end 122.13844 -293.20744)
		(width 0.1143)
		(layer "In13.Cu")
		(net "P5E_CPU1_P2_TX_DP<10>")
	)
	(segment
		(start 122.132598 -289.964114)
		(end 122.133868 -289.964876)
		(width 0.1143)
		(layer "In13.Cu")
		(net "P5E_CPU1_P2_TX_DP<10>")
	)
	(segment
		(start 122.60834 -295.637458)
		(end 122.609864 -295.63822)
		(width 0.1143)
		(layer "In13.Cu")
		(net "P5E_CPU1_P2_TX_DP<10>")
	)
	(segment
		(start 122.132598 -282.508452)
		(end 122.131836 -282.50896)
		(width 0.1143)
		(layer "In13.Cu")
		(net "P5E_CPU1_P2_TX_DP<10>")
	)
	(arc
		(start 122.319542 -287.046162)
		(mid 122.278287 -287.217133)
		(end 122.163586 -287.350454)
		(width 0.1143)
		(layer "In13.Cu")
		(net "P5E_CPU1_P2_TX_DP<10>")
	)
	(arc
		(start 161.653474 -373.605298)
		(mid 161.641197 -373.667021)
		(end 161.60623 -373.719344)
		(width 0.14224)
		(layer "In13.Cu")
		(net "P5E_CPU1_P2_TX_DP<10>")
	)
	(arc
		(start 122.09272 -293.87165)
		(mid 121.849393 -294.336216)
		(end 122.09272 -294.800782)
		(width 0.1143)
		(layer "In13.Cu")
		(net "P5E_CPU1_P2_TX_DP<10>")
	)
	(arc
		(start 122.09272 -271.191736)
		(mid 121.849393 -271.656302)
		(end 122.09272 -272.120868)
		(width 0.1143)
		(layer "In13.Cu")
		(net "P5E_CPU1_P2_TX_DP<10>")
	)
	(arc
		(start 122.162316 -273.78152)
		(mid 122.319293 -274.08632)
		(end 122.162316 -274.39112)
		(width 0.1143)
		(layer "In13.Cu")
		(net "P5E_CPU1_P2_TX_DP<10>")
	)
	(arc
		(start 122.09272 -280.911808)
		(mid 121.849393 -281.376374)
		(end 122.09272 -281.84094)
		(width 0.1143)
		(layer "In13.Cu")
		(net "P5E_CPU1_P2_TX_DP<10>")
	)
	(arc
		(start 121.849388 -287.856422)
		(mid 121.913903 -288.118641)
		(end 122.09272 -288.320988)
		(width 0.1143)
		(layer "In13.Cu")
		(net "P5E_CPU1_P2_TX_DP<10>")
	)
	(arc
		(start 122.09526 -287.390078)
		(mid 121.914608 -287.592823)
		(end 121.849388 -287.856422)
		(width 0.1143)
		(layer "In13.Cu")
		(net "P5E_CPU1_P2_TX_DP<10>")
	)
	(arc
		(start 122.09272 -284.151832)
		(mid 121.849393 -284.616398)
		(end 122.09272 -285.080964)
		(width 0.1143)
		(layer "In13.Cu")
		(net "P5E_CPU1_P2_TX_DP<10>")
	)
	(arc
		(start 122.162316 -280.261568)
		(mid 122.319293 -280.566368)
		(end 122.162316 -280.871168)
		(width 0.1143)
		(layer "In13.Cu")
		(net "P5E_CPU1_P2_TX_DP<10>")
	)
	(arc
		(start 122.163586 -289.981894)
		(mid 122.319514 -290.286186)
		(end 122.163586 -290.590478)
		(width 0.1143)
		(layer "In13.Cu")
		(net "P5E_CPU1_P2_TX_DP<10>")
	)
	(arc
		(start 122.09272 -276.051772)
		(mid 121.849393 -276.516338)
		(end 122.09272 -276.980904)
		(width 0.1143)
		(layer "In13.Cu")
		(net "P5E_CPU1_P2_TX_DP<10>")
	)
	(arc
		(start 122.319288 -295.146222)
		(mid 122.383803 -295.408441)
		(end 122.56262 -295.610788)
		(width 0.1143)
		(layer "In13.Cu")
		(net "P5E_CPU1_P2_TX_DP<10>")
	)
	(arc
		(start 122.09272 -285.771844)
		(mid 121.849393 -286.23641)
		(end 122.09272 -286.700976)
		(width 0.1143)
		(layer "In13.Cu")
		(net "P5E_CPU1_P2_TX_DP<10>")
	)
	(arc
		(start 122.165364 -286.743394)
		(mid 122.278771 -286.876283)
		(end 122.319542 -287.046162)
		(width 0.1143)
		(layer "In13.Cu")
		(net "P5E_CPU1_P2_TX_DP<10>")
	)
	(arc
		(start 122.163586 -291.601906)
		(mid 122.319514 -291.906198)
		(end 122.163586 -292.21049)
		(width 0.1143)
		(layer "In13.Cu")
		(net "P5E_CPU1_P2_TX_DP<10>")
	)
	(arc
		(start 122.165364 -288.363406)
		(mid 122.278771 -288.496295)
		(end 122.319542 -288.666174)
		(width 0.1143)
		(layer "In13.Cu")
		(net "P5E_CPU1_P2_TX_DP<10>")
	)
	(arc
		(start 122.162316 -272.161508)
		(mid 122.319293 -272.466308)
		(end 122.162316 -272.771108)
		(width 0.1143)
		(layer "In13.Cu")
		(net "P5E_CPU1_P2_TX_DP<10>")
	)
	(arc
		(start 122.09272 -282.53182)
		(mid 121.849393 -282.996386)
		(end 122.09272 -283.460952)
		(width 0.1143)
		(layer "In13.Cu")
		(net "P5E_CPU1_P2_TX_DP<10>")
	)
	(arc
		(start 161.16554 -370.546122)
		(mid 161.263847 -370.584911)
		(end 161.360612 -370.627402)
		(width 0.14224)
		(layer "In13.Cu")
		(net "P5E_CPU1_P2_TX_DP<10>")
	)
	(arc
		(start 122.09272 -279.291796)
		(mid 121.849393 -279.756362)
		(end 122.09272 -280.220928)
		(width 0.1143)
		(layer "In13.Cu")
		(net "P5E_CPU1_P2_TX_DP<10>")
	)
	(arc
		(start 122.163586 -293.221918)
		(mid 122.319514 -293.52621)
		(end 122.163586 -293.830502)
		(width 0.1143)
		(layer "In13.Cu")
		(net "P5E_CPU1_P2_TX_DP<10>")
	)
	(arc
		(start 122.319542 -288.666174)
		(mid 122.278287 -288.837145)
		(end 122.163586 -288.970466)
		(width 0.1143)
		(layer "In13.Cu")
		(net "P5E_CPU1_P2_TX_DP<10>")
	)
	(arc
		(start 122.319288 -270.846296)
		(mid 122.277739 -271.017718)
		(end 122.162316 -271.151096)
		(width 0.1143)
		(layer "In13.Cu")
		(net "P5E_CPU1_P2_TX_DP<10>")
	)
	(arc
		(start 159.64027 -367.54181)
		(mid 159.668939 -367.563063)
		(end 159.695388 -367.587022)
		(width 0.14224)
		(layer "In13.Cu")
		(net "P5E_CPU1_P2_TX_DP<10>")
	)
	(arc
		(start 158.18866 -366.586516)
		(mid 158.245879 -366.613622)
		(end 158.300166 -366.646206)
		(width 0.14224)
		(layer "In13.Cu")
		(net "P5E_CPU1_P2_TX_DP<10>")
	)
	(arc
		(start 122.163586 -294.84193)
		(mid 122.278262 -294.975264)
		(end 122.319542 -295.146222)
		(width 0.1143)
		(layer "In13.Cu")
		(net "P5E_CPU1_P2_TX_DP<10>")
	)
	(arc
		(start 122.09272 -277.671784)
		(mid 121.849393 -278.13635)
		(end 122.09272 -278.600916)
		(width 0.1143)
		(layer "In13.Cu")
		(net "P5E_CPU1_P2_TX_DP<10>")
	)
	(arc
		(start 122.162316 -275.401532)
		(mid 122.319293 -275.706332)
		(end 122.162316 -276.011132)
		(width 0.1143)
		(layer "In13.Cu")
		(net "P5E_CPU1_P2_TX_DP<10>")
	)
	(arc
		(start 122.09272 -289.011614)
		(mid 121.849393 -289.47618)
		(end 122.09272 -289.940746)
		(width 0.1143)
		(layer "In13.Cu")
		(net "P5E_CPU1_P2_TX_DP<10>")
	)
	(arc
		(start 122.163586 -281.882088)
		(mid 122.319514 -282.18638)
		(end 122.163586 -282.490672)
		(width 0.1143)
		(layer "In13.Cu")
		(net "P5E_CPU1_P2_TX_DP<10>")
	)
	(arc
		(start 161.360612 -370.627402)
		(mid 161.413788 -370.663111)
		(end 161.453322 -370.713508)
		(width 0.14224)
		(layer "In13.Cu")
		(net "P5E_CPU1_P2_TX_DP<10>")
	)
	(arc
		(start 159.955738 -369.394232)
		(mid 160.013737 -369.668097)
		(end 160.166812 -369.902486)
		(width 0.14224)
		(layer "In13.Cu")
		(net "P5E_CPU1_P2_TX_DP<10>")
	)
	(arc
		(start 159.908494 -367.800128)
		(mid 159.943456 -367.852453)
		(end 159.955738 -367.914174)
		(width 0.14224)
		(layer "In13.Cu")
		(net "P5E_CPU1_P2_TX_DP<10>")
	)
	(arc
		(start 122.09272 -274.43176)
		(mid 121.849393 -274.896326)
		(end 122.09272 -275.360892)
		(width 0.1143)
		(layer "In13.Cu")
		(net "P5E_CPU1_P2_TX_DP<10>")
	)
	(arc
		(start 161.621978 -371.015514)
		(mid 161.645482 -371.074078)
		(end 161.653474 -371.136672)
		(width 0.14224)
		(layer "In13.Cu")
		(net "P5E_CPU1_P2_TX_DP<10>")
	)
	(arc
		(start 122.56262 -270.38173)
		(mid 122.383807 -270.58408)
		(end 122.319288 -270.846296)
		(width 0.1143)
		(layer "In13.Cu")
		(net "P5E_CPU1_P2_TX_DP<10>")
	)
	(arc
		(start 122.163586 -285.122112)
		(mid 122.319514 -285.426404)
		(end 122.163586 -285.730696)
		(width 0.1143)
		(layer "In13.Cu")
		(net "P5E_CPU1_P2_TX_DP<10>")
	)
	(arc
		(start 122.09272 -292.251638)
		(mid 121.849393 -292.716204)
		(end 122.09272 -293.18077)
		(width 0.1143)
		(layer "In13.Cu")
		(net "P5E_CPU1_P2_TX_DP<10>")
	)
	(arc
		(start 122.09272 -272.811748)
		(mid 121.849393 -273.276314)
		(end 122.09272 -273.74088)
		(width 0.1143)
		(layer "In13.Cu")
		(net "P5E_CPU1_P2_TX_DP<10>")
	)
	(arc
		(start 122.09272 -290.631626)
		(mid 121.849393 -291.096192)
		(end 122.09272 -291.560758)
		(width 0.1143)
		(layer "In13.Cu")
		(net "P5E_CPU1_P2_TX_DP<10>")
	)
	(arc
		(start 122.163586 -283.5021)
		(mid 122.319514 -283.806392)
		(end 122.163586 -284.110684)
		(width 0.1143)
		(layer "In13.Cu")
		(net "P5E_CPU1_P2_TX_DP<10>")
	)
	(arc
		(start 122.162316 -278.641556)
		(mid 122.319293 -278.946356)
		(end 122.162316 -279.251156)
		(width 0.1143)
		(layer "In13.Cu")
		(net "P5E_CPU1_P2_TX_DP<10>")
	)
	(arc
		(start 122.782584 -270.10614)
		(mid 122.730535 -270.237659)
		(end 122.633486 -270.340582)
		(width 0.1143)
		(layer "In13.Cu")
		(net "P5E_CPU1_P2_TX_DP<10>")
	)
	(arc
		(start 160.17113 -369.906804)
		(mid 160.633951 -370.27995)
		(end 161.16554 -370.546122)
		(width 0.14224)
		(layer "In13.Cu")
		(net "P5E_CPU1_P2_TX_DP<10>")
	)
	(arc
		(start 122.63374 -295.652444)
		(mid 122.748341 -295.78566)
		(end 122.789696 -295.956482)
		(width 0.1143)
		(layer "In13.Cu")
		(net "P5E_CPU1_P2_TX_DP<10>")
	)
	(arc
		(start 122.162316 -277.021544)
		(mid 122.319293 -277.326344)
		(end 122.162316 -277.631144)
		(width 0.1143)
		(layer "In13.Cu")
		(net "P5E_CPU1_P2_TX_DP<10>")
	)
	(segment
		(start 142.032482 -382.09855)
		(end 142.328392 -382.39446)
		(width 0.12954)
		(layer "F.Cu")
		(net "P5E_CPU1_P2_TX_DP<0>")
	)
	(segment
		(start 141.328902 -382.09855)
		(end 142.032482 -382.09855)
		(width 0.12954)
		(layer "F.Cu")
		(net "P5E_CPU1_P2_TX_DP<0>")
	)
	(segment
		(start 113.957862 -268.960346)
		(end 114.424714 -269.226284)
		(width 0.12954)
		(layer "F.Cu")
		(net "P5E_CPU1_P2_TX_DP<0>")
	)
	(segment
		(start 141.058392 -382.36906)
		(end 141.328902 -382.09855)
		(width 0.12954)
		(layer "F.Cu")
		(net "P5E_CPU1_P2_TX_DP<0>")
	)
	(segment
		(start 116.469922 -305.283362)
		(end 126.492508 -318.7954)
		(width 0.14224)
		(layer "In13.Cu")
		(net "P5E_CPU1_P2_TX_DP<0>")
	)
	(segment
		(start 114.141758 -270.35887)
		(end 114.102642 -270.38173)
		(width 0.1143)
		(layer "In13.Cu")
		(net "P5E_CPU1_P2_TX_DP<0>")
	)
	(segment
		(start 112.723422 -272.037302)
		(end 112.624616 -272.53565)
		(width 0.14224)
		(layer "In13.Cu")
		(net "P5E_CPU1_P2_TX_DP<0>")
	)
	(segment
		(start 135.645398 -353.025964)
		(end 139.611354 -366.100868)
		(width 0.14224)
		(layer "In13.Cu")
		(net "P5E_CPU1_P2_TX_DP<0>")
	)
	(segment
		(start 113.635536 -271.189958)
		(end 112.999012 -271.826482)
		(width 0.1143)
		(layer "In13.Cu")
		(net "P5E_CPU1_P2_TX_DP<0>")
	)
	(segment
		(start 114.643408 -269.530576)
		(end 114.611658 -269.548864)
		(width 0.1143)
		(layer "In13.Cu")
		(net "P5E_CPU1_P2_TX_DP<0>")
	)
	(segment
		(start 113.702338 -271.151096)
		(end 113.671858 -271.168876)
		(width 0.1143)
		(layer "In13.Cu")
		(net "P5E_CPU1_P2_TX_DP<0>")
	)
	(segment
		(start 114.14379 -270.3576)
		(end 114.14252 -270.358362)
		(width 0.1143)
		(layer "In13.Cu")
		(net "P5E_CPU1_P2_TX_DP<0>")
	)
	(segment
		(start 130.2131 -325.717916)
		(end 135.645398 -353.025964)
		(width 0.14224)
		(layer "In13.Cu")
		(net "P5E_CPU1_P2_TX_DP<0>")
	)
	(segment
		(start 113.671858 -271.168876)
		(end 113.635536 -271.189958)
		(width 0.1143)
		(layer "In13.Cu")
		(net "P5E_CPU1_P2_TX_DP<0>")
	)
	(segment
		(start 139.73683 -381.898144)
		(end 139.797028 -381.958342)
		(width 0.14224)
		(layer "In13.Cu")
		(net "P5E_CPU1_P2_TX_DP<0>")
	)
	(segment
		(start 112.624616 -272.53565)
		(end 112.701578 -295.25087)
		(width 0.14224)
		(layer "In13.Cu")
		(net "P5E_CPU1_P2_TX_DP<0>")
	)
	(segment
		(start 114.611658 -269.548864)
		(end 114.609626 -269.550134)
		(width 0.1143)
		(layer "In13.Cu")
		(net "P5E_CPU1_P2_TX_DP<0>")
	)
	(segment
		(start 112.933988 -271.826482)
		(end 112.913922 -271.846548)
		(width 0.1143)
		(layer "In13.Cu")
		(net "P5E_CPU1_P2_TX_DP<0>")
	)
	(segment
		(start 140.767562 -382.07823)
		(end 141.058392 -382.36906)
		(width 0.14224)
		(layer "In13.Cu")
		(net "P5E_CPU1_P2_TX_DP<0>")
	)
	(segment
		(start 112.913922 -271.846548)
		(end 112.723422 -272.037302)
		(width 0.14224)
		(layer "In13.Cu")
		(net "P5E_CPU1_P2_TX_DP<0>")
	)
	(segment
		(start 114.722656 -269.226284)
		(end 114.792506 -269.296134)
		(width 0.1143)
		(layer "In13.Cu")
		(net "P5E_CPU1_P2_TX_DP<0>")
	)
	(segment
		(start 126.492508 -318.7954)
		(end 130.2131 -325.717916)
		(width 0.14224)
		(layer "In13.Cu")
		(net "P5E_CPU1_P2_TX_DP<0>")
	)
	(segment
		(start 115.256056 -303.258728)
		(end 116.469922 -305.283362)
		(width 0.14224)
		(layer "In13.Cu")
		(net "P5E_CPU1_P2_TX_DP<0>")
	)
	(segment
		(start 112.701578 -295.25087)
		(end 113.263426 -298.446444)
		(width 0.14224)
		(layer "In13.Cu")
		(net "P5E_CPU1_P2_TX_DP<0>")
	)
	(segment
		(start 139.616942 -366.137698)
		(end 139.616942 -381.608838)
		(width 0.14224)
		(layer "In13.Cu")
		(net "P5E_CPU1_P2_TX_DP<0>")
	)
	(segment
		(start 114.424714 -269.226284)
		(end 114.722656 -269.226284)
		(width 0.1143)
		(layer "In13.Cu")
		(net "P5E_CPU1_P2_TX_DP<0>")
	)
	(segment
		(start 112.999012 -271.826482)
		(end 112.933988 -271.826482)
		(width 0.1143)
		(layer "In13.Cu")
		(net "P5E_CPU1_P2_TX_DP<0>")
	)
	(segment
		(start 114.14252 -270.358362)
		(end 114.141758 -270.35887)
		(width 0.1143)
		(layer "In13.Cu")
		(net "P5E_CPU1_P2_TX_DP<0>")
	)
	(segment
		(start 113.263426 -298.446444)
		(end 115.256056 -303.258728)
		(width 0.14224)
		(layer "In13.Cu")
		(net "P5E_CPU1_P2_TX_DP<0>")
	)
	(segment
		(start 140.086334 -382.07823)
		(end 140.767562 -382.07823)
		(width 0.14224)
		(layer "In13.Cu")
		(net "P5E_CPU1_P2_TX_DP<0>")
	)
	(arc
		(start 114.609626 -269.550134)
		(mid 114.403558 -269.756997)
		(end 114.328194 -270.039084)
		(width 0.1143)
		(layer "In13.Cu")
		(net "P5E_CPU1_P2_TX_DP<0>")
	)
	(arc
		(start 139.611354 -366.100868)
		(mid 139.6155 -366.119078)
		(end 139.616942 -366.137698)
		(width 0.14224)
		(layer "In13.Cu")
		(net "P5E_CPU1_P2_TX_DP<0>")
	)
	(arc
		(start 114.792506 -269.296134)
		(mid 114.740457 -269.427653)
		(end 114.643408 -269.530576)
		(width 0.1143)
		(layer "In13.Cu")
		(net "P5E_CPU1_P2_TX_DP<0>")
	)
	(arc
		(start 113.85931 -270.846296)
		(mid 113.817761 -271.017718)
		(end 113.702338 -271.151096)
		(width 0.1143)
		(layer "In13.Cu")
		(net "P5E_CPU1_P2_TX_DP<0>")
	)
	(arc
		(start 114.328194 -270.039084)
		(mid 114.278767 -270.223107)
		(end 114.14379 -270.3576)
		(width 0.1143)
		(layer "In13.Cu")
		(net "P5E_CPU1_P2_TX_DP<0>")
	)
	(arc
		(start 139.797028 -381.958342)
		(mid 139.929748 -382.047086)
		(end 140.086334 -382.07823)
		(width 0.14224)
		(layer "In13.Cu")
		(net "P5E_CPU1_P2_TX_DP<0>")
	)
	(arc
		(start 139.616942 -381.608838)
		(mid 139.648105 -381.765416)
		(end 139.73683 -381.898144)
		(width 0.14224)
		(layer "In13.Cu")
		(net "P5E_CPU1_P2_TX_DP<0>")
	)
	(arc
		(start 114.102642 -270.38173)
		(mid 113.923829 -270.58408)
		(end 113.85931 -270.846296)
		(width 0.1143)
		(layer "In13.Cu")
		(net "P5E_CPU1_P2_TX_DP<0>")
	)
	(segment
		(start 120.067832 -271.390364)
		(end 120.534684 -271.656302)
		(width 0.12954)
		(layer "F.Cu")
		(net "P5E_CPU1_P2_TX_DN<9>")
	)
	(segment
		(start 158.822644 -369.03533)
		(end 158.552134 -369.30584)
		(width 0.12954)
		(layer "F.Cu")
		(net "P5E_CPU1_P2_TX_DN<9>")
	)
	(segment
		(start 158.552134 -370.00942)
		(end 158.848044 -370.30533)
		(width 0.12954)
		(layer "F.Cu")
		(net "P5E_CPU1_P2_TX_DN<9>")
	)
	(segment
		(start 158.552134 -369.30584)
		(end 158.552134 -370.00942)
		(width 0.12954)
		(layer "F.Cu")
		(net "P5E_CPU1_P2_TX_DN<9>")
	)
	(segment
		(start 122.040142 -295.956228)
		(end 122.040142 -296.099738)
		(width 0.1143)
		(layer "In13.Cu")
		(net "P5E_CPU1_P2_TX_DN<9>")
	)
	(segment
		(start 158.531814 -368.009932)
		(end 158.531814 -368.7445)
		(width 0.14224)
		(layer "In13.Cu")
		(net "P5E_CPU1_P2_TX_DN<9>")
	)
	(segment
		(start 121.285762 -279.435052)
		(end 121.256044 -279.45207)
		(width 0.1143)
		(layer "In13.Cu")
		(net "P5E_CPU1_P2_TX_DN<9>")
	)
	(segment
		(start 121.287794 -273.598894)
		(end 121.324116 -273.619976)
		(width 0.1143)
		(layer "In13.Cu")
		(net "P5E_CPU1_P2_TX_DN<9>")
	)
	(segment
		(start 121.258838 -281.070304)
		(end 121.25706 -281.071574)
		(width 0.1143)
		(layer "In13.Cu")
		(net "P5E_CPU1_P2_TX_DN<9>")
	)
	(segment
		(start 121.28754 -291.418772)
		(end 121.326656 -291.441632)
		(width 0.1143)
		(layer "In13.Cu")
		(net "P5E_CPU1_P2_TX_DN<9>")
	)
	(segment
		(start 120.353836 -271.982438)
		(end 120.35536 -271.983454)
		(width 0.1143)
		(layer "In13.Cu")
		(net "P5E_CPU1_P2_TX_DN<9>")
	)
	(segment
		(start 121.326656 -278.481536)
		(end 121.354596 -278.501602)
		(width 0.1143)
		(layer "In13.Cu")
		(net "P5E_CPU1_P2_TX_DN<9>")
	)
	(segment
		(start 120.351296 -271.980914)
		(end 120.353836 -271.982438)
		(width 0.1143)
		(layer "In13.Cu")
		(net "P5E_CPU1_P2_TX_DN<9>")
	)
	(segment
		(start 121.285762 -276.195028)
		(end 121.256044 -276.212046)
		(width 0.1143)
		(layer "In13.Cu")
		(net "P5E_CPU1_P2_TX_DN<9>")
	)
	(segment
		(start 120.34774 -271.978882)
		(end 120.348756 -271.97939)
		(width 0.1143)
		(layer "In13.Cu")
		(net "P5E_CPU1_P2_TX_DN<9>")
	)
	(segment
		(start 121.28754 -289.79876)
		(end 121.326656 -289.82162)
		(width 0.1143)
		(layer "In13.Cu")
		(net "P5E_CPU1_P2_TX_DN<9>")
	)
	(segment
		(start 157.455616 -367.01095)
		(end 158.360618 -367.753392)
		(width 0.14224)
		(layer "In13.Cu")
		(net "P5E_CPU1_P2_TX_DN<9>")
	)
	(segment
		(start 122.167396 -296.584116)
		(end 122.167396 -296.612564)
		(width 0.1143)
		(layer "In13.Cu")
		(net "P5E_CPU1_P2_TX_DN<9>")
	)
	(segment
		(start 121.28754 -289.1536)
		(end 121.25706 -289.17138)
		(width 0.1143)
		(layer "In13.Cu")
		(net "P5E_CPU1_P2_TX_DN<9>")
	)
	(segment
		(start 121.28754 -283.318966)
		(end 121.326656 -283.341826)
		(width 0.1143)
		(layer "In13.Cu")
		(net "P5E_CPU1_P2_TX_DN<9>")
	)
	(segment
		(start 121.326656 -289.13074)
		(end 121.28754 -289.1536)
		(width 0.1143)
		(layer "In13.Cu")
		(net "P5E_CPU1_P2_TX_DN<9>")
	)
	(segment
		(start 122.040142 -296.099738)
		(end 122.121676 -296.181272)
		(width 0.1143)
		(layer "In13.Cu")
		(net "P5E_CPU1_P2_TX_DN<9>")
	)
	(segment
		(start 121.287032 -274.574254)
		(end 121.285762 -274.575016)
		(width 0.1143)
		(layer "In13.Cu")
		(net "P5E_CPU1_P2_TX_DN<9>")
	)
	(segment
		(start 121.28754 -294.013636)
		(end 121.25706 -294.031416)
		(width 0.1143)
		(layer "In13.Cu")
		(net "P5E_CPU1_P2_TX_DN<9>")
	)
	(segment
		(start 121.326656 -293.990776)
		(end 121.28754 -294.013636)
		(width 0.1143)
		(layer "In13.Cu")
		(net "P5E_CPU1_P2_TX_DN<9>")
	)
	(segment
		(start 121.326656 -284.270958)
		(end 121.28754 -284.293818)
		(width 0.1143)
		(layer "In13.Cu")
		(net "P5E_CPU1_P2_TX_DN<9>")
	)
	(segment
		(start 121.32691 -281.031188)
		(end 121.258838 -281.070304)
		(width 0.1143)
		(layer "In13.Cu")
		(net "P5E_CPU1_P2_TX_DN<9>")
	)
	(segment
		(start 121.287032 -277.814278)
		(end 121.285762 -277.81504)
		(width 0.1143)
		(layer "In13.Cu")
		(net "P5E_CPU1_P2_TX_DN<9>")
	)
	(segment
		(start 122.766582 -298.686474)
		(end 123.494292 -299.900594)
		(width 0.14224)
		(layer "In13.Cu")
		(net "P5E_CPU1_P2_TX_DN<9>")
	)
	(segment
		(start 121.287794 -280.078942)
		(end 121.290588 -280.08072)
		(width 0.1143)
		(layer "In13.Cu")
		(net "P5E_CPU1_P2_TX_DN<9>")
	)
	(segment
		(start 121.256044 -273.580606)
		(end 121.287032 -273.598386)
		(width 0.1143)
		(layer "In13.Cu")
		(net "P5E_CPU1_P2_TX_DN<9>")
	)
	(segment
		(start 120.346978 -271.978374)
		(end 120.34774 -271.978882)
		(width 0.1143)
		(layer "In13.Cu")
		(net "P5E_CPU1_P2_TX_DN<9>")
	)
	(segment
		(start 121.28754 -294.658796)
		(end 121.326656 -294.681656)
		(width 0.1143)
		(layer "In13.Cu")
		(net "P5E_CPU1_P2_TX_DN<9>")
	)
	(segment
		(start 120.35536 -271.983454)
		(end 120.386856 -272.001742)
		(width 0.1143)
		(layer "In13.Cu")
		(net "P5E_CPU1_P2_TX_DN<9>")
	)
	(segment
		(start 121.256044 -280.060654)
		(end 121.287032 -280.078434)
		(width 0.1143)
		(layer "In13.Cu")
		(net "P5E_CPU1_P2_TX_DN<9>")
	)
	(segment
		(start 121.28754 -292.393624)
		(end 121.25706 -292.411404)
		(width 0.1143)
		(layer "In13.Cu")
		(net "P5E_CPU1_P2_TX_DN<9>")
	)
	(segment
		(start 121.28754 -290.773612)
		(end 121.25706 -290.791392)
		(width 0.1143)
		(layer "In13.Cu")
		(net "P5E_CPU1_P2_TX_DN<9>")
	)
	(segment
		(start 121.289318 -279.432766)
		(end 121.287032 -279.43429)
		(width 0.1143)
		(layer "In13.Cu")
		(net "P5E_CPU1_P2_TX_DN<9>")
	)
	(segment
		(start 121.28754 -282.673806)
		(end 121.25706 -282.691586)
		(width 0.1143)
		(layer "In13.Cu")
		(net "P5E_CPU1_P2_TX_DN<9>")
	)
	(segment
		(start 121.28754 -288.178748)
		(end 121.326656 -288.201608)
		(width 0.1143)
		(layer "In13.Cu")
		(net "P5E_CPU1_P2_TX_DN<9>")
	)
	(segment
		(start 121.287032 -278.458422)
		(end 121.287794 -278.45893)
		(width 0.1143)
		(layer "In13.Cu")
		(net "P5E_CPU1_P2_TX_DN<9>")
	)
	(segment
		(start 121.28754 -285.91383)
		(end 121.25706 -285.93161)
		(width 0.1143)
		(layer "In13.Cu")
		(net "P5E_CPU1_P2_TX_DN<9>")
	)
	(segment
		(start 121.287032 -276.83841)
		(end 121.287794 -276.838918)
		(width 0.1143)
		(layer "In13.Cu")
		(net "P5E_CPU1_P2_TX_DN<9>")
	)
	(segment
		(start 158.360618 -367.753392)
		(end 158.531814 -368.009932)
		(width 0.14224)
		(layer "In13.Cu")
		(net "P5E_CPU1_P2_TX_DN<9>")
	)
	(segment
		(start 121.285762 -274.575016)
		(end 121.256044 -274.592034)
		(width 0.1143)
		(layer "In13.Cu")
		(net "P5E_CPU1_P2_TX_DN<9>")
	)
	(segment
		(start 121.727468 -295.451276)
		(end 121.79681 -295.491662)
		(width 0.1143)
		(layer "In13.Cu")
		(net "P5E_CPU1_P2_TX_DN<9>")
	)
	(segment
		(start 153.42616 -364.927388)
		(end 155.057856 -366.01781)
		(width 0.14224)
		(layer "In13.Cu")
		(net "P5E_CPU1_P2_TX_DN<9>")
	)
	(segment
		(start 144.018762 -349.43161)
		(end 149.153372 -359.631742)
		(width 0.14224)
		(layer "In13.Cu")
		(net "P5E_CPU1_P2_TX_DN<9>")
	)
	(segment
		(start 121.28754 -286.558736)
		(end 121.326656 -286.581596)
		(width 0.1143)
		(layer "In13.Cu")
		(net "P5E_CPU1_P2_TX_DN<9>")
	)
	(segment
		(start 121.324116 -274.552664)
		(end 121.287794 -274.573746)
		(width 0.1143)
		(layer "In13.Cu")
		(net "P5E_CPU1_P2_TX_DN<9>")
	)
	(segment
		(start 155.057856 -366.01781)
		(end 157.455616 -367.01095)
		(width 0.14224)
		(layer "In13.Cu")
		(net "P5E_CPU1_P2_TX_DN<9>")
	)
	(segment
		(start 121.287794 -276.838918)
		(end 121.324116 -276.86)
		(width 0.1143)
		(layer "In13.Cu")
		(net "P5E_CPU1_P2_TX_DN<9>")
	)
	(segment
		(start 121.326656 -285.89097)
		(end 121.28754 -285.91383)
		(width 0.1143)
		(layer "In13.Cu")
		(net "P5E_CPU1_P2_TX_DN<9>")
	)
	(segment
		(start 138.315954 -322.06057)
		(end 138.813286 -323.260212)
		(width 0.14224)
		(layer "In13.Cu")
		(net "P5E_CPU1_P2_TX_DN<9>")
	)
	(segment
		(start 121.326656 -282.650946)
		(end 121.28754 -282.673806)
		(width 0.1143)
		(layer "In13.Cu")
		(net "P5E_CPU1_P2_TX_DN<9>")
	)
	(segment
		(start 120.236742 -271.656302)
		(end 120.166892 -271.726152)
		(width 0.1143)
		(layer "In13.Cu")
		(net "P5E_CPU1_P2_TX_DN<9>")
	)
	(segment
		(start 121.256044 -276.82063)
		(end 121.287032 -276.83841)
		(width 0.1143)
		(layer "In13.Cu")
		(net "P5E_CPU1_P2_TX_DN<9>")
	)
	(segment
		(start 120.534684 -271.656302)
		(end 120.236742 -271.656302)
		(width 0.1143)
		(layer "In13.Cu")
		(net "P5E_CPU1_P2_TX_DN<9>")
	)
	(segment
		(start 121.324116 -276.172676)
		(end 121.287794 -276.193758)
		(width 0.1143)
		(layer "In13.Cu")
		(net "P5E_CPU1_P2_TX_DN<9>")
	)
	(segment
		(start 121.255028 -286.53994)
		(end 121.28754 -286.558736)
		(width 0.1143)
		(layer "In13.Cu")
		(net "P5E_CPU1_P2_TX_DN<9>")
	)
	(segment
		(start 121.326656 -280.101548)
		(end 121.354596 -280.121614)
		(width 0.1143)
		(layer "In13.Cu")
		(net "P5E_CPU1_P2_TX_DN<9>")
	)
	(segment
		(start 121.28754 -284.293818)
		(end 121.25706 -284.311598)
		(width 0.1143)
		(layer "In13.Cu")
		(net "P5E_CPU1_P2_TX_DN<9>")
	)
	(segment
		(start 121.287794 -275.218906)
		(end 121.324116 -275.239988)
		(width 0.1143)
		(layer "In13.Cu")
		(net "P5E_CPU1_P2_TX_DN<9>")
	)
	(segment
		(start 121.287794 -274.573746)
		(end 121.287032 -274.574254)
		(width 0.1143)
		(layer "In13.Cu")
		(net "P5E_CPU1_P2_TX_DN<9>")
	)
	(segment
		(start 121.287794 -278.45893)
		(end 121.290588 -278.460708)
		(width 0.1143)
		(layer "In13.Cu")
		(net "P5E_CPU1_P2_TX_DN<9>")
	)
	(segment
		(start 121.25706 -281.681174)
		(end 121.28754 -281.698954)
		(width 0.1143)
		(layer "In13.Cu")
		(net "P5E_CPU1_P2_TX_DN<9>")
	)
	(segment
		(start 123.494292 -299.900594)
		(end 132.811012 -312.462418)
		(width 0.14224)
		(layer "In13.Cu")
		(net "P5E_CPU1_P2_TX_DN<9>")
	)
	(segment
		(start 121.25706 -283.301186)
		(end 121.28754 -283.318966)
		(width 0.1143)
		(layer "In13.Cu")
		(net "P5E_CPU1_P2_TX_DN<9>")
	)
	(segment
		(start 121.25706 -291.400992)
		(end 121.28754 -291.418772)
		(width 0.1143)
		(layer "In13.Cu")
		(net "P5E_CPU1_P2_TX_DN<9>")
	)
	(segment
		(start 121.25706 -294.641016)
		(end 121.28754 -294.658796)
		(width 0.1143)
		(layer "In13.Cu")
		(net "P5E_CPU1_P2_TX_DN<9>")
	)
	(segment
		(start 121.326656 -290.750752)
		(end 121.28754 -290.773612)
		(width 0.1143)
		(layer "In13.Cu")
		(net "P5E_CPU1_P2_TX_DN<9>")
	)
	(segment
		(start 121.287794 -276.193758)
		(end 121.287032 -276.194266)
		(width 0.1143)
		(layer "In13.Cu")
		(net "P5E_CPU1_P2_TX_DN<9>")
	)
	(segment
		(start 121.354596 -279.39111)
		(end 121.326656 -279.411176)
		(width 0.1143)
		(layer "In13.Cu")
		(net "P5E_CPU1_P2_TX_DN<9>")
	)
	(segment
		(start 158.531814 -368.7445)
		(end 158.822644 -369.03533)
		(width 0.14224)
		(layer "In13.Cu")
		(net "P5E_CPU1_P2_TX_DN<9>")
	)
	(segment
		(start 122.121676 -296.181272)
		(end 122.121676 -296.538396)
		(width 0.1143)
		(layer "In13.Cu")
		(net "P5E_CPU1_P2_TX_DN<9>")
	)
	(segment
		(start 121.287032 -275.218398)
		(end 121.287794 -275.218906)
		(width 0.1143)
		(layer "In13.Cu")
		(net "P5E_CPU1_P2_TX_DN<9>")
	)
	(segment
		(start 120.78716 -272.771108)
		(end 120.81764 -272.788888)
		(width 0.1143)
		(layer "In13.Cu")
		(net "P5E_CPU1_P2_TX_DN<9>")
	)
	(segment
		(start 121.287032 -273.598386)
		(end 121.287794 -273.598894)
		(width 0.1143)
		(layer "In13.Cu")
		(net "P5E_CPU1_P2_TX_DN<9>")
	)
	(segment
		(start 121.326656 -279.411176)
		(end 121.289318 -279.432766)
		(width 0.1143)
		(layer "In13.Cu")
		(net "P5E_CPU1_P2_TX_DN<9>")
	)
	(segment
		(start 121.28754 -281.698954)
		(end 121.326656 -281.721814)
		(width 0.1143)
		(layer "In13.Cu")
		(net "P5E_CPU1_P2_TX_DN<9>")
	)
	(segment
		(start 121.256044 -275.200618)
		(end 121.287032 -275.218398)
		(width 0.1143)
		(layer "In13.Cu")
		(net "P5E_CPU1_P2_TX_DN<9>")
	)
	(segment
		(start 121.25706 -284.921198)
		(end 121.28754 -284.938978)
		(width 0.1143)
		(layer "In13.Cu")
		(net "P5E_CPU1_P2_TX_DN<9>")
	)
	(segment
		(start 150.795228 -362.024676)
		(end 153.42616 -364.927388)
		(width 0.14224)
		(layer "In13.Cu")
		(net "P5E_CPU1_P2_TX_DN<9>")
	)
	(segment
		(start 122.167904 -297.240706)
		(end 122.766582 -298.686474)
		(width 0.14224)
		(layer "In13.Cu")
		(net "P5E_CPU1_P2_TX_DN<9>")
	)
	(segment
		(start 121.255028 -288.159952)
		(end 121.28754 -288.178748)
		(width 0.1143)
		(layer "In13.Cu")
		(net "P5E_CPU1_P2_TX_DN<9>")
	)
	(segment
		(start 122.121676 -296.538396)
		(end 122.167396 -296.584116)
		(width 0.1143)
		(layer "In13.Cu")
		(net "P5E_CPU1_P2_TX_DN<9>")
	)
	(segment
		(start 121.287032 -279.43429)
		(end 121.285762 -279.435052)
		(width 0.1143)
		(layer "In13.Cu")
		(net "P5E_CPU1_P2_TX_DN<9>")
	)
	(segment
		(start 149.153372 -359.631742)
		(end 150.795228 -362.024676)
		(width 0.14224)
		(layer "In13.Cu")
		(net "P5E_CPU1_P2_TX_DN<9>")
	)
	(segment
		(start 122.167904 -296.926762)
		(end 122.167904 -297.240706)
		(width 0.14224)
		(layer "In13.Cu")
		(net "P5E_CPU1_P2_TX_DN<9>")
	)
	(segment
		(start 120.31599 -271.960594)
		(end 120.346978 -271.978374)
		(width 0.1143)
		(layer "In13.Cu")
		(net "P5E_CPU1_P2_TX_DN<9>")
	)
	(segment
		(start 121.354596 -281.011122)
		(end 121.32691 -281.031188)
		(width 0.1143)
		(layer "In13.Cu")
		(net "P5E_CPU1_P2_TX_DN<9>")
	)
	(segment
		(start 121.326656 -292.370764)
		(end 121.28754 -292.393624)
		(width 0.1143)
		(layer "In13.Cu")
		(net "P5E_CPU1_P2_TX_DN<9>")
	)
	(segment
		(start 121.25706 -289.78098)
		(end 121.28754 -289.79876)
		(width 0.1143)
		(layer "In13.Cu")
		(net "P5E_CPU1_P2_TX_DN<9>")
	)
	(segment
		(start 121.324116 -277.792688)
		(end 121.287794 -277.81377)
		(width 0.1143)
		(layer "In13.Cu")
		(net "P5E_CPU1_P2_TX_DN<9>")
	)
	(segment
		(start 121.287032 -276.194266)
		(end 121.285762 -276.195028)
		(width 0.1143)
		(layer "In13.Cu")
		(net "P5E_CPU1_P2_TX_DN<9>")
	)
	(segment
		(start 120.348756 -271.97939)
		(end 120.35028 -271.980406)
		(width 0.1143)
		(layer "In13.Cu")
		(net "P5E_CPU1_P2_TX_DN<9>")
	)
	(segment
		(start 134.68223 -315.263022)
		(end 138.315954 -322.06057)
		(width 0.14224)
		(layer "In13.Cu")
		(net "P5E_CPU1_P2_TX_DN<9>")
	)
	(segment
		(start 121.256044 -278.440642)
		(end 121.287032 -278.458422)
		(width 0.1143)
		(layer "In13.Cu")
		(net "P5E_CPU1_P2_TX_DN<9>")
	)
	(segment
		(start 121.287032 -280.078434)
		(end 121.287794 -280.078942)
		(width 0.1143)
		(layer "In13.Cu")
		(net "P5E_CPU1_P2_TX_DN<9>")
	)
	(segment
		(start 121.290588 -280.08072)
		(end 121.326656 -280.101548)
		(width 0.1143)
		(layer "In13.Cu")
		(net "P5E_CPU1_P2_TX_DN<9>")
	)
	(segment
		(start 132.811012 -312.462418)
		(end 134.68223 -315.263022)
		(width 0.14224)
		(layer "In13.Cu")
		(net "P5E_CPU1_P2_TX_DN<9>")
	)
	(segment
		(start 121.324116 -287.512506)
		(end 121.25706 -287.551622)
		(width 0.1143)
		(layer "In13.Cu")
		(net "P5E_CPU1_P2_TX_DN<9>")
	)
	(segment
		(start 121.285762 -277.81504)
		(end 121.256044 -277.832058)
		(width 0.1143)
		(layer "In13.Cu")
		(net "P5E_CPU1_P2_TX_DN<9>")
	)
	(segment
		(start 121.28754 -284.938978)
		(end 121.326656 -284.961838)
		(width 0.1143)
		(layer "In13.Cu")
		(net "P5E_CPU1_P2_TX_DN<9>")
	)
	(segment
		(start 120.35028 -271.980406)
		(end 120.351296 -271.980914)
		(width 0.1143)
		(layer "In13.Cu")
		(net "P5E_CPU1_P2_TX_DN<9>")
	)
	(segment
		(start 138.813286 -323.260212)
		(end 144.018762 -349.43161)
		(width 0.14224)
		(layer "In13.Cu")
		(net "P5E_CPU1_P2_TX_DN<9>")
	)
	(segment
		(start 121.28754 -293.038784)
		(end 121.326656 -293.061644)
		(width 0.1143)
		(layer "In13.Cu")
		(net "P5E_CPU1_P2_TX_DN<9>")
	)
	(segment
		(start 121.25706 -293.021004)
		(end 121.28754 -293.038784)
		(width 0.1143)
		(layer "In13.Cu")
		(net "P5E_CPU1_P2_TX_DN<9>")
	)
	(segment
		(start 122.167396 -296.926254)
		(end 122.167904 -296.926762)
		(width 0.14224)
		(layer "In13.Cu")
		(net "P5E_CPU1_P2_TX_DN<9>")
	)
	(segment
		(start 120.81764 -272.788888)
		(end 120.856756 -272.811748)
		(width 0.1143)
		(layer "In13.Cu")
		(net "P5E_CPU1_P2_TX_DN<9>")
	)
	(segment
		(start 121.290588 -278.460708)
		(end 121.326656 -278.481536)
		(width 0.1143)
		(layer "In13.Cu")
		(net "P5E_CPU1_P2_TX_DN<9>")
	)
	(segment
		(start 122.167396 -296.612564)
		(end 122.167396 -296.926254)
		(width 0.14224)
		(layer "In13.Cu")
		(net "P5E_CPU1_P2_TX_DN<9>")
	)
	(segment
		(start 121.287794 -277.81377)
		(end 121.287032 -277.814278)
		(width 0.1143)
		(layer "In13.Cu")
		(net "P5E_CPU1_P2_TX_DN<9>")
	)
	(arc
		(start 121.33834 -273.629882)
		(mid 121.565723 -274.08632)
		(end 121.33834 -274.542758)
		(width 0.1143)
		(layer "In13.Cu")
		(net "P5E_CPU1_P2_TX_DN<9>")
	)
	(arc
		(start 121.100088 -287.856422)
		(mid 121.141054 -288.026828)
		(end 121.255028 -288.159952)
		(width 0.1143)
		(layer "In13.Cu")
		(net "P5E_CPU1_P2_TX_DN<9>")
	)
	(arc
		(start 120.386856 -272.001742)
		(mid 120.565669 -272.204092)
		(end 120.630188 -272.466308)
		(width 0.1143)
		(layer "In13.Cu")
		(net "P5E_CPU1_P2_TX_DN<9>")
	)
	(arc
		(start 121.25706 -287.551622)
		(mid 121.141633 -287.684998)
		(end 121.100088 -287.856422)
		(width 0.1143)
		(layer "In13.Cu")
		(net "P5E_CPU1_P2_TX_DN<9>")
	)
	(arc
		(start 121.100088 -273.276314)
		(mid 121.141343 -273.447285)
		(end 121.256044 -273.580606)
		(width 0.1143)
		(layer "In13.Cu")
		(net "P5E_CPU1_P2_TX_DN<9>")
	)
	(arc
		(start 120.630188 -272.466308)
		(mid 120.671737 -272.63773)
		(end 120.78716 -272.771108)
		(width 0.1143)
		(layer "In13.Cu")
		(net "P5E_CPU1_P2_TX_DN<9>")
	)
	(arc
		(start 122.040142 -295.948354)
		(mid 122.040157 -295.952291)
		(end 122.040142 -295.956228)
		(width 0.1143)
		(layer "In13.Cu")
		(net "P5E_CPU1_P2_TX_DN<9>")
	)
	(arc
		(start 121.25706 -282.691586)
		(mid 121.100083 -282.996386)
		(end 121.25706 -283.301186)
		(width 0.1143)
		(layer "In13.Cu")
		(net "P5E_CPU1_P2_TX_DN<9>")
	)
	(arc
		(start 121.25706 -294.031416)
		(mid 121.100083 -294.336216)
		(end 121.25706 -294.641016)
		(width 0.1143)
		(layer "In13.Cu")
		(net "P5E_CPU1_P2_TX_DN<9>")
	)
	(arc
		(start 121.25706 -281.071574)
		(mid 121.100083 -281.376374)
		(end 121.25706 -281.681174)
		(width 0.1143)
		(layer "In13.Cu")
		(net "P5E_CPU1_P2_TX_DN<9>")
	)
	(arc
		(start 121.25706 -292.411404)
		(mid 121.100083 -292.716204)
		(end 121.25706 -293.021004)
		(width 0.1143)
		(layer "In13.Cu")
		(net "P5E_CPU1_P2_TX_DN<9>")
	)
	(arc
		(start 121.79681 -295.491662)
		(mid 121.858061 -295.540855)
		(end 121.911872 -295.598088)
		(width 0.1143)
		(layer "In13.Cu")
		(net "P5E_CPU1_P2_TX_DN<9>")
	)
	(arc
		(start 121.25706 -284.311598)
		(mid 121.100083 -284.616398)
		(end 121.25706 -284.921198)
		(width 0.1143)
		(layer "In13.Cu")
		(net "P5E_CPU1_P2_TX_DN<9>")
	)
	(arc
		(start 121.326656 -289.82162)
		(mid 121.569983 -290.286186)
		(end 121.326656 -290.750752)
		(width 0.1143)
		(layer "In13.Cu")
		(net "P5E_CPU1_P2_TX_DN<9>")
	)
	(arc
		(start 121.339356 -276.162008)
		(mid 121.33178 -276.167404)
		(end 121.324116 -276.172676)
		(width 0.1143)
		(layer "In13.Cu")
		(net "P5E_CPU1_P2_TX_DN<9>")
	)
	(arc
		(start 121.326656 -294.681656)
		(mid 121.505469 -294.884006)
		(end 121.569988 -295.146222)
		(width 0.1143)
		(layer "In13.Cu")
		(net "P5E_CPU1_P2_TX_DN<9>")
	)
	(arc
		(start 121.25706 -290.791392)
		(mid 121.100083 -291.096192)
		(end 121.25706 -291.400992)
		(width 0.1143)
		(layer "In13.Cu")
		(net "P5E_CPU1_P2_TX_DN<9>")
	)
	(arc
		(start 121.354596 -278.501602)
		(mid 121.582596 -278.946356)
		(end 121.354596 -279.39111)
		(width 0.1143)
		(layer "In13.Cu")
		(net "P5E_CPU1_P2_TX_DN<9>")
	)
	(arc
		(start 121.326656 -284.961838)
		(mid 121.569983 -285.426404)
		(end 121.326656 -285.89097)
		(width 0.1143)
		(layer "In13.Cu")
		(net "P5E_CPU1_P2_TX_DN<9>")
	)
	(arc
		(start 121.256044 -276.212046)
		(mid 121.100116 -276.516338)
		(end 121.256044 -276.82063)
		(width 0.1143)
		(layer "In13.Cu")
		(net "P5E_CPU1_P2_TX_DN<9>")
	)
	(arc
		(start 121.33834 -276.869906)
		(mid 121.565723 -277.326344)
		(end 121.33834 -277.782782)
		(width 0.1143)
		(layer "In13.Cu")
		(net "P5E_CPU1_P2_TX_DN<9>")
	)
	(arc
		(start 121.354596 -280.121614)
		(mid 121.582596 -280.566368)
		(end 121.354596 -281.011122)
		(width 0.1143)
		(layer "In13.Cu")
		(net "P5E_CPU1_P2_TX_DN<9>")
	)
	(arc
		(start 121.326656 -293.061644)
		(mid 121.569983 -293.52621)
		(end 121.326656 -293.990776)
		(width 0.1143)
		(layer "In13.Cu")
		(net "P5E_CPU1_P2_TX_DN<9>")
	)
	(arc
		(start 121.33834 -277.782782)
		(mid 121.331266 -277.787789)
		(end 121.324116 -277.792688)
		(width 0.1143)
		(layer "In13.Cu")
		(net "P5E_CPU1_P2_TX_DN<9>")
	)
	(arc
		(start 121.326656 -288.201608)
		(mid 121.569983 -288.666174)
		(end 121.326656 -289.13074)
		(width 0.1143)
		(layer "In13.Cu")
		(net "P5E_CPU1_P2_TX_DN<9>")
	)
	(arc
		(start 121.324116 -275.239988)
		(mid 121.33178 -275.245259)
		(end 121.339356 -275.250656)
		(width 0.1143)
		(layer "In13.Cu")
		(net "P5E_CPU1_P2_TX_DN<9>")
	)
	(arc
		(start 121.324116 -276.86)
		(mid 121.331265 -276.8649)
		(end 121.33834 -276.869906)
		(width 0.1143)
		(layer "In13.Cu")
		(net "P5E_CPU1_P2_TX_DN<9>")
	)
	(arc
		(start 121.326656 -283.341826)
		(mid 121.569983 -283.806392)
		(end 121.326656 -284.270958)
		(width 0.1143)
		(layer "In13.Cu")
		(net "P5E_CPU1_P2_TX_DN<9>")
	)
	(arc
		(start 121.324116 -273.619976)
		(mid 121.331265 -273.624876)
		(end 121.33834 -273.629882)
		(width 0.1143)
		(layer "In13.Cu")
		(net "P5E_CPU1_P2_TX_DN<9>")
	)
	(arc
		(start 121.911872 -295.598088)
		(mid 122.003265 -295.763235)
		(end 122.040142 -295.948354)
		(width 0.1143)
		(layer "In13.Cu")
		(net "P5E_CPU1_P2_TX_DN<9>")
	)
	(arc
		(start 121.569988 -295.146222)
		(mid 121.611739 -295.317842)
		(end 121.727468 -295.451276)
		(width 0.1143)
		(layer "In13.Cu")
		(net "P5E_CPU1_P2_TX_DN<9>")
	)
	(arc
		(start 121.326656 -291.441632)
		(mid 121.569983 -291.906198)
		(end 121.326656 -292.370764)
		(width 0.1143)
		(layer "In13.Cu")
		(net "P5E_CPU1_P2_TX_DN<9>")
	)
	(arc
		(start 121.100088 -286.23641)
		(mid 121.141054 -286.406816)
		(end 121.255028 -286.53994)
		(width 0.1143)
		(layer "In13.Cu")
		(net "P5E_CPU1_P2_TX_DN<9>")
	)
	(arc
		(start 121.256044 -277.832058)
		(mid 121.100116 -278.13635)
		(end 121.256044 -278.440642)
		(width 0.1143)
		(layer "In13.Cu")
		(net "P5E_CPU1_P2_TX_DN<9>")
	)
	(arc
		(start 121.256044 -274.592034)
		(mid 121.100116 -274.896326)
		(end 121.256044 -275.200618)
		(width 0.1143)
		(layer "In13.Cu")
		(net "P5E_CPU1_P2_TX_DN<9>")
	)
	(arc
		(start 121.25706 -285.93161)
		(mid 121.141633 -286.064986)
		(end 121.100088 -286.23641)
		(width 0.1143)
		(layer "In13.Cu")
		(net "P5E_CPU1_P2_TX_DN<9>")
	)
	(arc
		(start 121.256044 -279.45207)
		(mid 121.100116 -279.756362)
		(end 121.256044 -280.060654)
		(width 0.1143)
		(layer "In13.Cu")
		(net "P5E_CPU1_P2_TX_DN<9>")
	)
	(arc
		(start 121.25706 -289.17138)
		(mid 121.100083 -289.47618)
		(end 121.25706 -289.78098)
		(width 0.1143)
		(layer "In13.Cu")
		(net "P5E_CPU1_P2_TX_DN<9>")
	)
	(arc
		(start 120.856756 -272.811748)
		(mid 121.035569 -273.014098)
		(end 121.100088 -273.276314)
		(width 0.1143)
		(layer "In13.Cu")
		(net "P5E_CPU1_P2_TX_DN<9>")
	)
	(arc
		(start 121.569988 -287.046162)
		(mid 121.504752 -287.309753)
		(end 121.324116 -287.512506)
		(width 0.1143)
		(layer "In13.Cu")
		(net "P5E_CPU1_P2_TX_DN<9>")
	)
	(arc
		(start 121.326656 -286.581596)
		(mid 121.505469 -286.783946)
		(end 121.569988 -287.046162)
		(width 0.1143)
		(layer "In13.Cu")
		(net "P5E_CPU1_P2_TX_DN<9>")
	)
	(arc
		(start 121.326656 -281.721814)
		(mid 121.569983 -282.18638)
		(end 121.326656 -282.650946)
		(width 0.1143)
		(layer "In13.Cu")
		(net "P5E_CPU1_P2_TX_DN<9>")
	)
	(arc
		(start 121.339356 -275.250656)
		(mid 121.564527 -275.706332)
		(end 121.339356 -276.162008)
		(width 0.1143)
		(layer "In13.Cu")
		(net "P5E_CPU1_P2_TX_DN<9>")
	)
	(arc
		(start 120.166892 -271.726152)
		(mid 120.218941 -271.857671)
		(end 120.31599 -271.960594)
		(width 0.1143)
		(layer "In13.Cu")
		(net "P5E_CPU1_P2_TX_DN<9>")
	)
	(arc
		(start 121.33834 -274.542758)
		(mid 121.331266 -274.547765)
		(end 121.324116 -274.552664)
		(width 0.1143)
		(layer "In13.Cu")
		(net "P5E_CPU1_P2_TX_DN<9>")
	)
	(segment
		(start 156.850334 -371.76964)
		(end 156.850334 -372.47322)
		(width 0.12954)
		(layer "F.Cu")
		(net "P5E_CPU1_P2_TX_DN<8>")
	)
	(segment
		(start 156.850334 -372.47322)
		(end 157.146244 -372.76913)
		(width 0.12954)
		(layer "F.Cu")
		(net "P5E_CPU1_P2_TX_DN<8>")
	)
	(segment
		(start 120.067832 -273.010376)
		(end 120.534684 -273.276314)
		(width 0.12954)
		(layer "F.Cu")
		(net "P5E_CPU1_P2_TX_DN<8>")
	)
	(segment
		(start 157.120844 -371.49913)
		(end 156.850334 -371.76964)
		(width 0.12954)
		(layer "F.Cu")
		(net "P5E_CPU1_P2_TX_DN<8>")
	)
	(segment
		(start 120.350788 -285.912052)
		(end 120.31599 -285.932118)
		(width 0.1143)
		(layer "In13.Cu")
		(net "P5E_CPU1_P2_TX_DN<8>")
	)
	(segment
		(start 120.38584 -291.440616)
		(end 120.398794 -291.450014)
		(width 0.1143)
		(layer "In13.Cu")
		(net "P5E_CPU1_P2_TX_DN<8>")
	)
	(segment
		(start 120.345708 -276.195028)
		(end 120.31599 -276.212046)
		(width 0.1143)
		(layer "In13.Cu")
		(net "P5E_CPU1_P2_TX_DN<8>")
	)
	(segment
		(start 120.34774 -281.053794)
		(end 120.31599 -281.072082)
		(width 0.1143)
		(layer "In13.Cu")
		(net "P5E_CPU1_P2_TX_DN<8>")
	)
	(segment
		(start 120.534684 -273.276314)
		(end 120.236742 -273.276314)
		(width 0.1143)
		(layer "In13.Cu")
		(net "P5E_CPU1_P2_TX_DN<8>")
	)
	(segment
		(start 120.348756 -274.573238)
		(end 120.34774 -274.573746)
		(width 0.1143)
		(layer "In13.Cu")
		(net "P5E_CPU1_P2_TX_DN<8>")
	)
	(segment
		(start 120.35028 -276.840442)
		(end 120.386856 -276.861778)
		(width 0.1143)
		(layer "In13.Cu")
		(net "P5E_CPU1_P2_TX_DN<8>")
	)
	(segment
		(start 120.31599 -276.82063)
		(end 120.346978 -276.83841)
		(width 0.1143)
		(layer "In13.Cu")
		(net "P5E_CPU1_P2_TX_DN<8>")
	)
	(segment
		(start 120.34774 -273.598894)
		(end 120.348756 -273.599402)
		(width 0.1143)
		(layer "In13.Cu")
		(net "P5E_CPU1_P2_TX_DN<8>")
	)
	(segment
		(start 120.346978 -280.078434)
		(end 120.34774 -280.078942)
		(width 0.1143)
		(layer "In13.Cu")
		(net "P5E_CPU1_P2_TX_DN<8>")
	)
	(segment
		(start 120.346978 -274.574254)
		(end 120.345708 -274.575016)
		(width 0.1143)
		(layer "In13.Cu")
		(net "P5E_CPU1_P2_TX_DN<8>")
	)
	(segment
		(start 120.34774 -276.838918)
		(end 120.348756 -276.839426)
		(width 0.1143)
		(layer "In13.Cu")
		(net "P5E_CPU1_P2_TX_DN<8>")
	)
	(segment
		(start 120.348756 -273.599402)
		(end 120.35028 -273.600418)
		(width 0.1143)
		(layer "In13.Cu")
		(net "P5E_CPU1_P2_TX_DN<8>")
	)
	(segment
		(start 121.940574 -299.129704)
		(end 122.714004 -300.420024)
		(width 0.14224)
		(layer "In13.Cu")
		(net "P5E_CPU1_P2_TX_DN<8>")
	)
	(segment
		(start 120.34774 -291.419026)
		(end 120.38584 -291.440616)
		(width 0.1143)
		(layer "In13.Cu")
		(net "P5E_CPU1_P2_TX_DN<8>")
	)
	(segment
		(start 137.396728 -322.334382)
		(end 137.926064 -323.612256)
		(width 0.14224)
		(layer "In13.Cu")
		(net "P5E_CPU1_P2_TX_DN<8>")
	)
	(segment
		(start 122.714004 -300.420024)
		(end 131.892802 -312.795158)
		(width 0.14224)
		(layer "In13.Cu")
		(net "P5E_CPU1_P2_TX_DN<8>")
	)
	(segment
		(start 131.892802 -312.795158)
		(end 133.918706 -315.826902)
		(width 0.14224)
		(layer "In13.Cu")
		(net "P5E_CPU1_P2_TX_DN<8>")
	)
	(segment
		(start 120.31599 -280.060654)
		(end 120.344946 -280.077164)
		(width 0.1143)
		(layer "In13.Cu")
		(net "P5E_CPU1_P2_TX_DN<8>")
	)
	(segment
		(start 120.346978 -279.43429)
		(end 120.345708 -279.435052)
		(width 0.1143)
		(layer "In13.Cu")
		(net "P5E_CPU1_P2_TX_DN<8>")
	)
	(segment
		(start 120.346978 -275.218398)
		(end 120.34774 -275.218906)
		(width 0.1143)
		(layer "In13.Cu")
		(net "P5E_CPU1_P2_TX_DN<8>")
	)
	(segment
		(start 120.386856 -281.030934)
		(end 120.34774 -281.053794)
		(width 0.1143)
		(layer "In13.Cu")
		(net "P5E_CPU1_P2_TX_DN<8>")
	)
	(segment
		(start 120.34774 -279.433782)
		(end 120.346978 -279.43429)
		(width 0.1143)
		(layer "In13.Cu")
		(net "P5E_CPU1_P2_TX_DN<8>")
	)
	(segment
		(start 120.386856 -277.79091)
		(end 120.348756 -277.813262)
		(width 0.1143)
		(layer "In13.Cu")
		(net "P5E_CPU1_P2_TX_DN<8>")
	)
	(segment
		(start 120.348756 -276.19325)
		(end 120.34774 -276.193758)
		(width 0.1143)
		(layer "In13.Cu")
		(net "P5E_CPU1_P2_TX_DN<8>")
	)
	(segment
		(start 120.78716 -295.451022)
		(end 120.856756 -295.491662)
		(width 0.1143)
		(layer "In13.Cu")
		(net "P5E_CPU1_P2_TX_DN<8>")
	)
	(segment
		(start 156.499052 -368.098578)
		(end 156.688282 -368.381788)
		(width 0.14224)
		(layer "In13.Cu")
		(net "P5E_CPU1_P2_TX_DN<8>")
	)
	(segment
		(start 120.34774 -280.078942)
		(end 120.348756 -280.07945)
		(width 0.1143)
		(layer "In13.Cu")
		(net "P5E_CPU1_P2_TX_DN<8>")
	)
	(segment
		(start 156.830014 -371.2083)
		(end 157.120844 -371.49913)
		(width 0.14224)
		(layer "In13.Cu")
		(net "P5E_CPU1_P2_TX_DN<8>")
	)
	(segment
		(start 137.926064 -323.612256)
		(end 143.119348 -349.720662)
		(width 0.14224)
		(layer "In13.Cu")
		(net "P5E_CPU1_P2_TX_DN<8>")
	)
	(segment
		(start 120.31599 -283.300678)
		(end 120.346978 -283.318458)
		(width 0.1143)
		(layer "In13.Cu")
		(net "P5E_CPU1_P2_TX_DN<8>")
	)
	(segment
		(start 120.350788 -289.151822)
		(end 120.31599 -289.171888)
		(width 0.1143)
		(layer "In13.Cu")
		(net "P5E_CPU1_P2_TX_DN<8>")
	)
	(segment
		(start 121.22277 -297.3959)
		(end 121.940574 -299.129704)
		(width 0.14224)
		(layer "In13.Cu")
		(net "P5E_CPU1_P2_TX_DN<8>")
	)
	(segment
		(start 120.386856 -274.550886)
		(end 120.348756 -274.573238)
		(width 0.1143)
		(layer "In13.Cu")
		(net "P5E_CPU1_P2_TX_DN<8>")
	)
	(segment
		(start 120.346978 -277.814278)
		(end 120.345708 -277.81504)
		(width 0.1143)
		(layer "In13.Cu")
		(net "P5E_CPU1_P2_TX_DN<8>")
	)
	(segment
		(start 120.34774 -283.318966)
		(end 120.350788 -283.320744)
		(width 0.1143)
		(layer "In13.Cu")
		(net "P5E_CPU1_P2_TX_DN<8>")
	)
	(segment
		(start 152.869392 -365.752126)
		(end 154.467052 -366.819688)
		(width 0.14224)
		(layer "In13.Cu")
		(net "P5E_CPU1_P2_TX_DN<8>")
	)
	(segment
		(start 156.830014 -368.849402)
		(end 156.830014 -371.2083)
		(width 0.14224)
		(layer "In13.Cu")
		(net "P5E_CPU1_P2_TX_DN<8>")
	)
	(segment
		(start 120.34774 -274.573746)
		(end 120.346978 -274.574254)
		(width 0.1143)
		(layer "In13.Cu")
		(net "P5E_CPU1_P2_TX_DN<8>")
	)
	(segment
		(start 121.222262 -296.612564)
		(end 121.22277 -296.613072)
		(width 0.14224)
		(layer "In13.Cu")
		(net "P5E_CPU1_P2_TX_DN<8>")
	)
	(segment
		(start 120.34774 -289.79876)
		(end 120.350788 -289.800538)
		(width 0.1143)
		(layer "In13.Cu")
		(net "P5E_CPU1_P2_TX_DN<8>")
	)
	(segment
		(start 120.34774 -276.193758)
		(end 120.346978 -276.194266)
		(width 0.1143)
		(layer "In13.Cu")
		(net "P5E_CPU1_P2_TX_DN<8>")
	)
	(segment
		(start 120.629934 -287.046162)
		(end 120.629934 -287.050734)
		(width 0.1143)
		(layer "In13.Cu")
		(net "P5E_CPU1_P2_TX_DN<8>")
	)
	(segment
		(start 120.314212 -288.15919)
		(end 120.314974 -288.159698)
		(width 0.1143)
		(layer "In13.Cu")
		(net "P5E_CPU1_P2_TX_DN<8>")
	)
	(segment
		(start 120.386856 -279.410922)
		(end 120.348756 -279.433274)
		(width 0.1143)
		(layer "In13.Cu")
		(net "P5E_CPU1_P2_TX_DN<8>")
	)
	(segment
		(start 120.31599 -291.400484)
		(end 120.34774 -291.418772)
		(width 0.1143)
		(layer "In13.Cu")
		(net "P5E_CPU1_P2_TX_DN<8>")
	)
	(segment
		(start 120.31599 -275.200618)
		(end 120.346978 -275.218398)
		(width 0.1143)
		(layer "In13.Cu")
		(net "P5E_CPU1_P2_TX_DN<8>")
	)
	(segment
		(start 120.34774 -278.45893)
		(end 120.348756 -278.459438)
		(width 0.1143)
		(layer "In13.Cu")
		(net "P5E_CPU1_P2_TX_DN<8>")
	)
	(segment
		(start 120.350788 -294.011858)
		(end 120.31599 -294.031924)
		(width 0.1143)
		(layer "In13.Cu")
		(net "P5E_CPU1_P2_TX_DN<8>")
	)
	(segment
		(start 120.34774 -291.418772)
		(end 120.34774 -291.419026)
		(width 0.1143)
		(layer "In13.Cu")
		(net "P5E_CPU1_P2_TX_DN<8>")
	)
	(segment
		(start 120.386856 -276.170898)
		(end 120.348756 -276.19325)
		(width 0.1143)
		(layer "In13.Cu")
		(net "P5E_CPU1_P2_TX_DN<8>")
	)
	(segment
		(start 120.34774 -281.698954)
		(end 120.350788 -281.700732)
		(width 0.1143)
		(layer "In13.Cu")
		(net "P5E_CPU1_P2_TX_DN<8>")
	)
	(segment
		(start 120.34774 -277.81377)
		(end 120.346978 -277.814278)
		(width 0.1143)
		(layer "In13.Cu")
		(net "P5E_CPU1_P2_TX_DN<8>")
	)
	(segment
		(start 120.314974 -288.159698)
		(end 120.34774 -288.178748)
		(width 0.1143)
		(layer "In13.Cu")
		(net "P5E_CPU1_P2_TX_DN<8>")
	)
	(segment
		(start 120.34774 -288.178748)
		(end 120.350788 -288.180526)
		(width 0.1143)
		(layer "In13.Cu")
		(net "P5E_CPU1_P2_TX_DN<8>")
	)
	(segment
		(start 120.350788 -290.771834)
		(end 120.31599 -290.7919)
		(width 0.1143)
		(layer "In13.Cu")
		(net "P5E_CPU1_P2_TX_DN<8>")
	)
	(segment
		(start 120.345708 -277.81504)
		(end 120.31599 -277.832058)
		(width 0.1143)
		(layer "In13.Cu")
		(net "P5E_CPU1_P2_TX_DN<8>")
	)
	(segment
		(start 121.100088 -296.098468)
		(end 121.176542 -296.174922)
		(width 0.1143)
		(layer "In13.Cu")
		(net "P5E_CPU1_P2_TX_DN<8>")
	)
	(segment
		(start 120.34774 -294.658796)
		(end 120.387618 -294.682418)
		(width 0.1143)
		(layer "In13.Cu")
		(net "P5E_CPU1_P2_TX_DN<8>")
	)
	(segment
		(start 120.31599 -293.020496)
		(end 120.34774 -293.038784)
		(width 0.1143)
		(layer "In13.Cu")
		(net "P5E_CPU1_P2_TX_DN<8>")
	)
	(segment
		(start 120.348756 -280.07945)
		(end 120.386856 -280.101802)
		(width 0.1143)
		(layer "In13.Cu")
		(net "P5E_CPU1_P2_TX_DN<8>")
	)
	(segment
		(start 120.35028 -273.600418)
		(end 120.386856 -273.621754)
		(width 0.1143)
		(layer "In13.Cu")
		(net "P5E_CPU1_P2_TX_DN<8>")
	)
	(segment
		(start 120.35028 -278.460454)
		(end 120.386856 -278.48179)
		(width 0.1143)
		(layer "In13.Cu")
		(net "P5E_CPU1_P2_TX_DN<8>")
	)
	(segment
		(start 120.348756 -275.219414)
		(end 120.35028 -275.22043)
		(width 0.1143)
		(layer "In13.Cu")
		(net "P5E_CPU1_P2_TX_DN<8>")
	)
	(segment
		(start 120.34774 -275.218906)
		(end 120.348756 -275.219414)
		(width 0.1143)
		(layer "In13.Cu")
		(net "P5E_CPU1_P2_TX_DN<8>")
	)
	(segment
		(start 120.346978 -276.194266)
		(end 120.345708 -276.195028)
		(width 0.1143)
		(layer "In13.Cu")
		(net "P5E_CPU1_P2_TX_DN<8>")
	)
	(segment
		(start 120.31599 -289.780472)
		(end 120.34774 -289.79876)
		(width 0.1143)
		(layer "In13.Cu")
		(net "P5E_CPU1_P2_TX_DN<8>")
	)
	(segment
		(start 155.422346 -367.215166)
		(end 156.499052 -368.098578)
		(width 0.14224)
		(layer "In13.Cu")
		(net "P5E_CPU1_P2_TX_DN<8>")
	)
	(segment
		(start 120.31599 -273.580606)
		(end 120.346978 -273.598386)
		(width 0.1143)
		(layer "In13.Cu")
		(net "P5E_CPU1_P2_TX_DN<8>")
	)
	(segment
		(start 150.137622 -362.737654)
		(end 152.869392 -365.752126)
		(width 0.14224)
		(layer "In13.Cu")
		(net "P5E_CPU1_P2_TX_DN<8>")
	)
	(segment
		(start 120.31599 -278.440642)
		(end 120.34774 -278.45893)
		(width 0.1143)
		(layer "In13.Cu")
		(net "P5E_CPU1_P2_TX_DN<8>")
	)
	(segment
		(start 120.35028 -275.22043)
		(end 120.386856 -275.241766)
		(width 0.1143)
		(layer "In13.Cu")
		(net "P5E_CPU1_P2_TX_DN<8>")
	)
	(segment
		(start 120.314212 -286.539178)
		(end 120.388888 -286.58312)
		(width 0.1143)
		(layer "In13.Cu")
		(net "P5E_CPU1_P2_TX_DN<8>")
	)
	(segment
		(start 120.236742 -273.276314)
		(end 120.166892 -273.346164)
		(width 0.1143)
		(layer "In13.Cu")
		(net "P5E_CPU1_P2_TX_DN<8>")
	)
	(segment
		(start 120.399302 -287.501838)
		(end 120.387872 -287.510474)
		(width 0.1143)
		(layer "In13.Cu")
		(net "P5E_CPU1_P2_TX_DN<8>")
	)
	(segment
		(start 154.467052 -366.819688)
		(end 155.422346 -367.215166)
		(width 0.14224)
		(layer "In13.Cu")
		(net "P5E_CPU1_P2_TX_DN<8>")
	)
	(segment
		(start 121.176542 -296.174922)
		(end 121.176542 -296.538396)
		(width 0.1143)
		(layer "In13.Cu")
		(net "P5E_CPU1_P2_TX_DN<8>")
	)
	(segment
		(start 120.350788 -284.29204)
		(end 120.31599 -284.312106)
		(width 0.1143)
		(layer "In13.Cu")
		(net "P5E_CPU1_P2_TX_DN<8>")
	)
	(segment
		(start 120.345708 -279.435052)
		(end 120.31599 -279.45207)
		(width 0.1143)
		(layer "In13.Cu")
		(net "P5E_CPU1_P2_TX_DN<8>")
	)
	(segment
		(start 120.629934 -295.146222)
		(end 120.630188 -295.146222)
		(width 0.1143)
		(layer "In13.Cu")
		(net "P5E_CPU1_P2_TX_DN<8>")
	)
	(segment
		(start 120.31599 -294.640508)
		(end 120.34774 -294.658796)
		(width 0.1143)
		(layer "In13.Cu")
		(net "P5E_CPU1_P2_TX_DN<8>")
	)
	(segment
		(start 120.348756 -279.433274)
		(end 120.34774 -279.433782)
		(width 0.1143)
		(layer "In13.Cu")
		(net "P5E_CPU1_P2_TX_DN<8>")
	)
	(segment
		(start 120.348756 -276.839426)
		(end 120.35028 -276.840442)
		(width 0.1143)
		(layer "In13.Cu")
		(net "P5E_CPU1_P2_TX_DN<8>")
	)
	(segment
		(start 120.387872 -287.510474)
		(end 120.31599 -287.55213)
		(width 0.1143)
		(layer "In13.Cu")
		(net "P5E_CPU1_P2_TX_DN<8>")
	)
	(segment
		(start 133.918706 -315.826902)
		(end 137.396728 -322.334382)
		(width 0.14224)
		(layer "In13.Cu")
		(net "P5E_CPU1_P2_TX_DN<8>")
	)
	(segment
		(start 120.629934 -295.141904)
		(end 120.629934 -295.146222)
		(width 0.1143)
		(layer "In13.Cu")
		(net "P5E_CPU1_P2_TX_DN<8>")
	)
	(segment
		(start 120.34774 -293.038784)
		(end 120.350788 -293.040562)
		(width 0.1143)
		(layer "In13.Cu")
		(net "P5E_CPU1_P2_TX_DN<8>")
	)
	(segment
		(start 120.348756 -278.459438)
		(end 120.35028 -278.460454)
		(width 0.1143)
		(layer "In13.Cu")
		(net "P5E_CPU1_P2_TX_DN<8>")
	)
	(segment
		(start 120.346978 -273.598386)
		(end 120.34774 -273.598894)
		(width 0.1143)
		(layer "In13.Cu")
		(net "P5E_CPU1_P2_TX_DN<8>")
	)
	(segment
		(start 120.345708 -274.575016)
		(end 120.31599 -274.592034)
		(width 0.1143)
		(layer "In13.Cu")
		(net "P5E_CPU1_P2_TX_DN<8>")
	)
	(segment
		(start 120.348756 -277.813262)
		(end 120.34774 -277.81377)
		(width 0.1143)
		(layer "In13.Cu")
		(net "P5E_CPU1_P2_TX_DN<8>")
	)
	(segment
		(start 121.222262 -296.584116)
		(end 121.222262 -296.612564)
		(width 0.1143)
		(layer "In13.Cu")
		(net "P5E_CPU1_P2_TX_DN<8>")
	)
	(segment
		(start 120.344946 -280.077164)
		(end 120.346978 -280.078434)
		(width 0.1143)
		(layer "In13.Cu")
		(net "P5E_CPU1_P2_TX_DN<8>")
	)
	(segment
		(start 121.176542 -296.538396)
		(end 121.222262 -296.584116)
		(width 0.1143)
		(layer "In13.Cu")
		(net "P5E_CPU1_P2_TX_DN<8>")
	)
	(segment
		(start 120.346978 -283.318458)
		(end 120.34774 -283.318966)
		(width 0.1143)
		(layer "In13.Cu")
		(net "P5E_CPU1_P2_TX_DN<8>")
	)
	(segment
		(start 121.22277 -296.613072)
		(end 121.22277 -297.3959)
		(width 0.14224)
		(layer "In13.Cu")
		(net "P5E_CPU1_P2_TX_DN<8>")
	)
	(segment
		(start 121.100088 -295.956228)
		(end 121.100088 -296.098468)
		(width 0.1143)
		(layer "In13.Cu")
		(net "P5E_CPU1_P2_TX_DN<8>")
	)
	(segment
		(start 120.34774 -284.938978)
		(end 120.350788 -284.940756)
		(width 0.1143)
		(layer "In13.Cu")
		(net "P5E_CPU1_P2_TX_DN<8>")
	)
	(segment
		(start 120.38584 -292.37178)
		(end 120.31599 -292.411912)
		(width 0.1143)
		(layer "In13.Cu")
		(net "P5E_CPU1_P2_TX_DN<8>")
	)
	(segment
		(start 143.119348 -349.720662)
		(end 148.385784 -360.184192)
		(width 0.14224)
		(layer "In13.Cu")
		(net "P5E_CPU1_P2_TX_DN<8>")
	)
	(segment
		(start 148.385784 -360.184192)
		(end 150.137622 -362.737654)
		(width 0.14224)
		(layer "In13.Cu")
		(net "P5E_CPU1_P2_TX_DN<8>")
	)
	(segment
		(start 120.31599 -284.92069)
		(end 120.34774 -284.938978)
		(width 0.1143)
		(layer "In13.Cu")
		(net "P5E_CPU1_P2_TX_DN<8>")
	)
	(segment
		(start 120.398794 -292.362382)
		(end 120.38584 -292.37178)
		(width 0.1143)
		(layer "In13.Cu")
		(net "P5E_CPU1_P2_TX_DN<8>")
	)
	(segment
		(start 120.350788 -282.672028)
		(end 120.31599 -282.692094)
		(width 0.1143)
		(layer "In13.Cu")
		(net "P5E_CPU1_P2_TX_DN<8>")
	)
	(segment
		(start 120.31599 -281.680666)
		(end 120.34774 -281.698954)
		(width 0.1143)
		(layer "In13.Cu")
		(net "P5E_CPU1_P2_TX_DN<8>")
	)
	(segment
		(start 120.346978 -276.83841)
		(end 120.34774 -276.838918)
		(width 0.1143)
		(layer "In13.Cu")
		(net "P5E_CPU1_P2_TX_DN<8>")
	)
	(arc
		(start 120.350788 -284.940756)
		(mid 120.630403 -285.426404)
		(end 120.350788 -285.912052)
		(width 0.1143)
		(layer "In13.Cu")
		(net "P5E_CPU1_P2_TX_DN<8>")
	)
	(arc
		(start 120.31599 -281.072082)
		(mid 120.160062 -281.376374)
		(end 120.31599 -281.680666)
		(width 0.1143)
		(layer "In13.Cu")
		(net "P5E_CPU1_P2_TX_DN<8>")
	)
	(arc
		(start 120.31599 -284.312106)
		(mid 120.160062 -284.616398)
		(end 120.31599 -284.92069)
		(width 0.1143)
		(layer "In13.Cu")
		(net "P5E_CPU1_P2_TX_DN<8>")
	)
	(arc
		(start 120.31599 -277.832058)
		(mid 120.160062 -278.13635)
		(end 120.31599 -278.440642)
		(width 0.1143)
		(layer "In13.Cu")
		(net "P5E_CPU1_P2_TX_DN<8>")
	)
	(arc
		(start 120.31599 -290.7919)
		(mid 120.160062 -291.096192)
		(end 120.31599 -291.400484)
		(width 0.1143)
		(layer "In13.Cu")
		(net "P5E_CPU1_P2_TX_DN<8>")
	)
	(arc
		(start 120.166892 -273.346164)
		(mid 120.218941 -273.477683)
		(end 120.31599 -273.580606)
		(width 0.1143)
		(layer "In13.Cu")
		(net "P5E_CPU1_P2_TX_DN<8>")
	)
	(arc
		(start 120.160034 -287.856422)
		(mid 120.200796 -288.026306)
		(end 120.314212 -288.15919)
		(width 0.1143)
		(layer "In13.Cu")
		(net "P5E_CPU1_P2_TX_DN<8>")
	)
	(arc
		(start 120.386856 -276.861778)
		(mid 120.630183 -277.326344)
		(end 120.386856 -277.79091)
		(width 0.1143)
		(layer "In13.Cu")
		(net "P5E_CPU1_P2_TX_DN<8>")
	)
	(arc
		(start 120.31599 -282.692094)
		(mid 120.160062 -282.996386)
		(end 120.31599 -283.300678)
		(width 0.1143)
		(layer "In13.Cu")
		(net "P5E_CPU1_P2_TX_DN<8>")
	)
	(arc
		(start 120.386856 -273.621754)
		(mid 120.630183 -274.08632)
		(end 120.386856 -274.550886)
		(width 0.1143)
		(layer "In13.Cu")
		(net "P5E_CPU1_P2_TX_DN<8>")
	)
	(arc
		(start 120.350788 -281.700732)
		(mid 120.630403 -282.18638)
		(end 120.350788 -282.672028)
		(width 0.1143)
		(layer "In13.Cu")
		(net "P5E_CPU1_P2_TX_DN<8>")
	)
	(arc
		(start 120.31599 -294.031924)
		(mid 120.160062 -294.336216)
		(end 120.31599 -294.640508)
		(width 0.1143)
		(layer "In13.Cu")
		(net "P5E_CPU1_P2_TX_DN<8>")
	)
	(arc
		(start 120.350788 -293.040562)
		(mid 120.630403 -293.52621)
		(end 120.350788 -294.011858)
		(width 0.1143)
		(layer "In13.Cu")
		(net "P5E_CPU1_P2_TX_DN<8>")
	)
	(arc
		(start 120.31599 -287.55213)
		(mid 120.201314 -287.685464)
		(end 120.160034 -287.856422)
		(width 0.1143)
		(layer "In13.Cu")
		(net "P5E_CPU1_P2_TX_DN<8>")
	)
	(arc
		(start 156.688282 -368.381788)
		(mid 156.793887 -368.605067)
		(end 156.830014 -368.849402)
		(width 0.14224)
		(layer "In13.Cu")
		(net "P5E_CPU1_P2_TX_DN<8>")
	)
	(arc
		(start 120.350788 -288.180526)
		(mid 120.630403 -288.666174)
		(end 120.350788 -289.151822)
		(width 0.1143)
		(layer "In13.Cu")
		(net "P5E_CPU1_P2_TX_DN<8>")
	)
	(arc
		(start 120.31599 -279.45207)
		(mid 120.160062 -279.756362)
		(end 120.31599 -280.060654)
		(width 0.1143)
		(layer "In13.Cu")
		(net "P5E_CPU1_P2_TX_DN<8>")
	)
	(arc
		(start 120.31599 -274.592034)
		(mid 120.160062 -274.896326)
		(end 120.31599 -275.200618)
		(width 0.1143)
		(layer "In13.Cu")
		(net "P5E_CPU1_P2_TX_DN<8>")
	)
	(arc
		(start 120.398794 -291.450014)
		(mid 120.633221 -291.906198)
		(end 120.398794 -292.362382)
		(width 0.1143)
		(layer "In13.Cu")
		(net "P5E_CPU1_P2_TX_DN<8>")
	)
	(arc
		(start 120.160034 -286.23641)
		(mid 120.200796 -286.406294)
		(end 120.314212 -286.539178)
		(width 0.1143)
		(layer "In13.Cu")
		(net "P5E_CPU1_P2_TX_DN<8>")
	)
	(arc
		(start 120.386856 -280.101802)
		(mid 120.630183 -280.566368)
		(end 120.386856 -281.030934)
		(width 0.1143)
		(layer "In13.Cu")
		(net "P5E_CPU1_P2_TX_DN<8>")
	)
	(arc
		(start 120.387618 -294.682418)
		(mid 120.565654 -294.882168)
		(end 120.629934 -295.141904)
		(width 0.1143)
		(layer "In13.Cu")
		(net "P5E_CPU1_P2_TX_DN<8>")
	)
	(arc
		(start 120.31599 -292.411912)
		(mid 120.160062 -292.716204)
		(end 120.31599 -293.020496)
		(width 0.1143)
		(layer "In13.Cu")
		(net "P5E_CPU1_P2_TX_DN<8>")
	)
	(arc
		(start 120.31599 -289.171888)
		(mid 120.160062 -289.47618)
		(end 120.31599 -289.780472)
		(width 0.1143)
		(layer "In13.Cu")
		(net "P5E_CPU1_P2_TX_DN<8>")
	)
	(arc
		(start 120.388888 -286.58312)
		(mid 120.566084 -286.785132)
		(end 120.629934 -287.046162)
		(width 0.1143)
		(layer "In13.Cu")
		(net "P5E_CPU1_P2_TX_DN<8>")
	)
	(arc
		(start 120.856756 -295.491662)
		(mid 121.035569 -295.694012)
		(end 121.100088 -295.956228)
		(width 0.1143)
		(layer "In13.Cu")
		(net "P5E_CPU1_P2_TX_DN<8>")
	)
	(arc
		(start 120.630188 -295.146222)
		(mid 120.671737 -295.317644)
		(end 120.78716 -295.451022)
		(width 0.1143)
		(layer "In13.Cu")
		(net "P5E_CPU1_P2_TX_DN<8>")
	)
	(arc
		(start 120.386856 -278.48179)
		(mid 120.630183 -278.946356)
		(end 120.386856 -279.410922)
		(width 0.1143)
		(layer "In13.Cu")
		(net "P5E_CPU1_P2_TX_DN<8>")
	)
	(arc
		(start 120.31599 -276.212046)
		(mid 120.160062 -276.516338)
		(end 120.31599 -276.82063)
		(width 0.1143)
		(layer "In13.Cu")
		(net "P5E_CPU1_P2_TX_DN<8>")
	)
	(arc
		(start 120.629934 -287.050734)
		(mid 120.568935 -287.304058)
		(end 120.399302 -287.501838)
		(width 0.1143)
		(layer "In13.Cu")
		(net "P5E_CPU1_P2_TX_DN<8>")
	)
	(arc
		(start 120.31599 -285.932118)
		(mid 120.201314 -286.065452)
		(end 120.160034 -286.23641)
		(width 0.1143)
		(layer "In13.Cu")
		(net "P5E_CPU1_P2_TX_DN<8>")
	)
	(arc
		(start 120.350788 -283.320744)
		(mid 120.630403 -283.806392)
		(end 120.350788 -284.29204)
		(width 0.1143)
		(layer "In13.Cu")
		(net "P5E_CPU1_P2_TX_DN<8>")
	)
	(arc
		(start 120.386856 -275.241766)
		(mid 120.630183 -275.706332)
		(end 120.386856 -276.170898)
		(width 0.1143)
		(layer "In13.Cu")
		(net "P5E_CPU1_P2_TX_DN<8>")
	)
	(arc
		(start 120.350788 -289.800538)
		(mid 120.630403 -290.286186)
		(end 120.350788 -290.771834)
		(width 0.1143)
		(layer "In13.Cu")
		(net "P5E_CPU1_P2_TX_DN<8>")
	)
	(segment
		(start 155.419044 -373.96293)
		(end 155.148534 -374.23344)
		(width 0.12954)
		(layer "F.Cu")
		(net "P5E_CPU1_P2_TX_DN<7>")
	)
	(segment
		(start 155.148534 -374.23344)
		(end 155.148534 -374.93702)
		(width 0.12954)
		(layer "F.Cu")
		(net "P5E_CPU1_P2_TX_DN<7>")
	)
	(segment
		(start 120.067832 -269.770352)
		(end 120.534684 -270.03629)
		(width 0.12954)
		(layer "F.Cu")
		(net "P5E_CPU1_P2_TX_DN<7>")
	)
	(segment
		(start 155.148534 -374.93702)
		(end 155.444444 -375.23293)
		(width 0.12954)
		(layer "F.Cu")
		(net "P5E_CPU1_P2_TX_DN<7>")
	)
	(segment
		(start 119.407686 -278.45893)
		(end 119.446802 -278.48179)
		(width 0.1143)
		(layer "In13.Cu")
		(net "P5E_CPU1_P2_TX_DN<7>")
	)
	(segment
		(start 119.407178 -286.55899)
		(end 119.407686 -286.559244)
		(width 0.1143)
		(layer "In13.Cu")
		(net "P5E_CPU1_P2_TX_DN<7>")
	)
	(segment
		(start 119.410226 -281.05227)
		(end 119.408702 -281.053286)
		(width 0.1143)
		(layer "In13.Cu")
		(net "P5E_CPU1_P2_TX_DN<7>")
	)
	(segment
		(start 155.128214 -373.6721)
		(end 155.419044 -373.96293)
		(width 0.14224)
		(layer "In13.Cu")
		(net "P5E_CPU1_P2_TX_DN<7>")
	)
	(segment
		(start 119.446802 -289.13074)
		(end 119.404892 -289.155124)
		(width 0.1143)
		(layer "In13.Cu")
		(net "P5E_CPU1_P2_TX_DN<7>")
	)
	(segment
		(start 155.128214 -371.51183)
		(end 155.128214 -373.6721)
		(width 0.14224)
		(layer "In13.Cu")
		(net "P5E_CPU1_P2_TX_DN<7>")
	)
	(segment
		(start 119.446802 -281.030934)
		(end 119.410226 -281.05227)
		(width 0.1143)
		(layer "In13.Cu")
		(net "P5E_CPU1_P2_TX_DN<7>")
	)
	(segment
		(start 119.84609 -295.450514)
		(end 119.916194 -295.491154)
		(width 0.1143)
		(layer "In13.Cu")
		(net "P5E_CPU1_P2_TX_DN<7>")
	)
	(segment
		(start 119.428768 -285.901384)
		(end 119.4054 -285.914846)
		(width 0.1143)
		(layer "In13.Cu")
		(net "P5E_CPU1_P2_TX_DN<7>")
	)
	(segment
		(start 119.407178 -288.179002)
		(end 119.407686 -288.178748)
		(width 0.1143)
		(layer "In13.Cu")
		(net "P5E_CPU1_P2_TX_DN<7>")
	)
	(segment
		(start 119.425974 -288.189416)
		(end 119.446802 -288.201608)
		(width 0.1143)
		(layer "In13.Cu")
		(net "P5E_CPU1_P2_TX_DN<7>")
	)
	(segment
		(start 119.446802 -271.310862)
		(end 119.407686 -271.333722)
		(width 0.1143)
		(layer "In13.Cu")
		(net "P5E_CPU1_P2_TX_DN<7>")
	)
	(segment
		(start 119.407686 -280.078942)
		(end 119.408702 -280.07945)
		(width 0.1143)
		(layer "In13.Cu")
		(net "P5E_CPU1_P2_TX_DN<7>")
	)
	(segment
		(start 119.377968 -284.921706)
		(end 119.430038 -284.952186)
		(width 0.1143)
		(layer "In13.Cu")
		(net "P5E_CPU1_P2_TX_DN<7>")
	)
	(segment
		(start 119.407686 -279.433782)
		(end 119.375936 -279.45207)
		(width 0.1143)
		(layer "In13.Cu")
		(net "P5E_CPU1_P2_TX_DN<7>")
	)
	(segment
		(start 119.403622 -286.556958)
		(end 119.405908 -286.558228)
		(width 0.1143)
		(layer "In13.Cu")
		(net "P5E_CPU1_P2_TX_DN<7>")
	)
	(segment
		(start 119.375936 -280.060654)
		(end 119.406924 -280.078434)
		(width 0.1143)
		(layer "In13.Cu")
		(net "P5E_CPU1_P2_TX_DN<7>")
	)
	(segment
		(start 119.407686 -274.573746)
		(end 119.375936 -274.592034)
		(width 0.1143)
		(layer "In13.Cu")
		(net "P5E_CPU1_P2_TX_DN<7>")
	)
	(segment
		(start 141.915388 -349.549974)
		(end 147.103592 -360.17962)
		(width 0.14224)
		(layer "In13.Cu")
		(net "P5E_CPU1_P2_TX_DN<7>")
	)
	(segment
		(start 154.044904 -370.116354)
		(end 154.045158 -370.116354)
		(width 0.14224)
		(layer "In13.Cu")
		(net "P5E_CPU1_P2_TX_DN<7>")
	)
	(segment
		(start 119.414798 -293.042848)
		(end 119.416322 -293.043864)
		(width 0.1143)
		(layer "In13.Cu")
		(net "P5E_CPU1_P2_TX_DN<7>")
	)
	(segment
		(start 119.416322 -293.043864)
		(end 119.44604 -293.061136)
		(width 0.1143)
		(layer "In13.Cu")
		(net "P5E_CPU1_P2_TX_DN<7>")
	)
	(segment
		(start 119.407686 -286.559244)
		(end 119.448834 -286.58312)
		(width 0.1143)
		(layer "In13.Cu")
		(net "P5E_CPU1_P2_TX_DN<7>")
	)
	(segment
		(start 119.407686 -273.598894)
		(end 119.446802 -273.621754)
		(width 0.1143)
		(layer "In13.Cu")
		(net "P5E_CPU1_P2_TX_DN<7>")
	)
	(segment
		(start 119.410734 -287.52927)
		(end 119.40667 -287.53181)
		(width 0.1143)
		(layer "In13.Cu")
		(net "P5E_CPU1_P2_TX_DN<7>")
	)
	(segment
		(start 119.446802 -274.550886)
		(end 119.407686 -274.573746)
		(width 0.1143)
		(layer "In13.Cu")
		(net "P5E_CPU1_P2_TX_DN<7>")
	)
	(segment
		(start 119.446802 -292.370764)
		(end 119.408702 -292.393116)
		(width 0.1143)
		(layer "In13.Cu")
		(net "P5E_CPU1_P2_TX_DN<7>")
	)
	(segment
		(start 119.446802 -279.410922)
		(end 119.407686 -279.433782)
		(width 0.1143)
		(layer "In13.Cu")
		(net "P5E_CPU1_P2_TX_DN<7>")
	)
	(segment
		(start 119.408702 -280.07945)
		(end 119.446802 -280.101802)
		(width 0.1143)
		(layer "In13.Cu")
		(net "P5E_CPU1_P2_TX_DN<7>")
	)
	(segment
		(start 119.377714 -281.681682)
		(end 119.446294 -281.721306)
		(width 0.1143)
		(layer "In13.Cu")
		(net "P5E_CPU1_P2_TX_DN<7>")
	)
	(segment
		(start 119.389652 -294.648636)
		(end 119.44604 -294.681148)
		(width 0.1143)
		(layer "In13.Cu")
		(net "P5E_CPU1_P2_TX_DN<7>")
	)
	(segment
		(start 119.407686 -291.418772)
		(end 119.408702 -291.41928)
		(width 0.1143)
		(layer "In13.Cu")
		(net "P5E_CPU1_P2_TX_DN<7>")
	)
	(segment
		(start 119.408702 -289.799268)
		(end 119.410226 -289.800284)
		(width 0.1143)
		(layer "In13.Cu")
		(net "P5E_CPU1_P2_TX_DN<7>")
	)
	(segment
		(start 119.407686 -281.053794)
		(end 119.406416 -281.054302)
		(width 0.1143)
		(layer "In13.Cu")
		(net "P5E_CPU1_P2_TX_DN<7>")
	)
	(segment
		(start 120.205754 -296.29862)
		(end 120.205754 -296.327068)
		(width 0.1143)
		(layer "In13.Cu")
		(net "P5E_CPU1_P2_TX_DN<7>")
	)
	(segment
		(start 119.877586 -270.523716)
		(end 119.847106 -270.541496)
		(width 0.1143)
		(layer "In13.Cu")
		(net "P5E_CPU1_P2_TX_DN<7>")
	)
	(segment
		(start 119.410226 -289.800284)
		(end 119.446802 -289.82162)
		(width 0.1143)
		(layer "In13.Cu")
		(net "P5E_CPU1_P2_TX_DN<7>")
	)
	(segment
		(start 119.406924 -280.078434)
		(end 119.407686 -280.078942)
		(width 0.1143)
		(layer "In13.Cu")
		(net "P5E_CPU1_P2_TX_DN<7>")
	)
	(segment
		(start 119.377714 -283.301694)
		(end 119.446294 -283.341318)
		(width 0.1143)
		(layer "In13.Cu")
		(net "P5E_CPU1_P2_TX_DN<7>")
	)
	(segment
		(start 119.4054 -285.914846)
		(end 119.403876 -285.915862)
		(width 0.1143)
		(layer "In13.Cu")
		(net "P5E_CPU1_P2_TX_DN<7>")
	)
	(segment
		(start 121.148602 -299.655738)
		(end 121.879106 -300.87443)
		(width 0.14224)
		(layer "In13.Cu")
		(net "P5E_CPU1_P2_TX_DN<7>")
	)
	(segment
		(start 120.205754 -297.379136)
		(end 121.148602 -299.655738)
		(width 0.14224)
		(layer "In13.Cu")
		(net "P5E_CPU1_P2_TX_DN<7>")
	)
	(segment
		(start 119.404892 -289.155124)
		(end 119.40286 -289.156394)
		(width 0.1143)
		(layer "In13.Cu")
		(net "P5E_CPU1_P2_TX_DN<7>")
	)
	(segment
		(start 119.916702 -270.500856)
		(end 119.877586 -270.523716)
		(width 0.1143)
		(layer "In13.Cu")
		(net "P5E_CPU1_P2_TX_DN<7>")
	)
	(segment
		(start 120.160034 -295.956228)
		(end 120.160034 -296.2529)
		(width 0.1143)
		(layer "In13.Cu")
		(net "P5E_CPU1_P2_TX_DN<7>")
	)
	(segment
		(start 121.879106 -300.87443)
		(end 131.099306 -313.304682)
		(width 0.14224)
		(layer "In13.Cu")
		(net "P5E_CPU1_P2_TX_DN<7>")
	)
	(segment
		(start 119.399812 -293.034212)
		(end 119.414798 -293.042848)
		(width 0.1143)
		(layer "In13.Cu")
		(net "P5E_CPU1_P2_TX_DN<7>")
	)
	(segment
		(start 133.028436 -316.192154)
		(end 136.587484 -322.849494)
		(width 0.14224)
		(layer "In13.Cu")
		(net "P5E_CPU1_P2_TX_DN<7>")
	)
	(segment
		(start 119.377968 -288.161984)
		(end 119.407178 -288.179002)
		(width 0.1143)
		(layer "In13.Cu")
		(net "P5E_CPU1_P2_TX_DN<7>")
	)
	(segment
		(start 136.587484 -322.849494)
		(end 136.619996 -322.927726)
		(width 0.14224)
		(layer "In13.Cu")
		(net "P5E_CPU1_P2_TX_DN<7>")
	)
	(segment
		(start 119.446802 -276.170898)
		(end 119.407686 -276.193758)
		(width 0.1143)
		(layer "In13.Cu")
		(net "P5E_CPU1_P2_TX_DN<7>")
	)
	(segment
		(start 147.166076 -360.289348)
		(end 148.496782 -362.307886)
		(width 0.14224)
		(layer "In13.Cu")
		(net "P5E_CPU1_P2_TX_DN<7>")
	)
	(segment
		(start 119.407178 -291.418772)
		(end 119.407686 -291.418772)
		(width 0.1143)
		(layer "In13.Cu")
		(net "P5E_CPU1_P2_TX_DN<7>")
	)
	(segment
		(start 119.407686 -276.838918)
		(end 119.446802 -276.861778)
		(width 0.1143)
		(layer "In13.Cu")
		(net "P5E_CPU1_P2_TX_DN<7>")
	)
	(segment
		(start 119.407686 -275.218906)
		(end 119.446802 -275.241766)
		(width 0.1143)
		(layer "In13.Cu")
		(net "P5E_CPU1_P2_TX_DN<7>")
	)
	(segment
		(start 119.405908 -286.558228)
		(end 119.407178 -286.55899)
		(width 0.1143)
		(layer "In13.Cu")
		(net "P5E_CPU1_P2_TX_DN<7>")
	)
	(segment
		(start 119.407686 -276.193758)
		(end 119.375936 -276.212046)
		(width 0.1143)
		(layer "In13.Cu")
		(net "P5E_CPU1_P2_TX_DN<7>")
	)
	(segment
		(start 153.425144 -368.91468)
		(end 153.425144 -369.515136)
		(width 0.14224)
		(layer "In13.Cu")
		(net "P5E_CPU1_P2_TX_DN<7>")
	)
	(segment
		(start 119.446802 -290.750752)
		(end 119.407178 -290.773866)
		(width 0.1143)
		(layer "In13.Cu")
		(net "P5E_CPU1_P2_TX_DN<7>")
	)
	(segment
		(start 119.375936 -271.960594)
		(end 119.407686 -271.978882)
		(width 0.1143)
		(layer "In13.Cu")
		(net "P5E_CPU1_P2_TX_DN<7>")
	)
	(segment
		(start 119.446802 -293.990776)
		(end 119.389906 -294.023796)
		(width 0.1143)
		(layer "In13.Cu")
		(net "P5E_CPU1_P2_TX_DN<7>")
	)
	(segment
		(start 119.375936 -276.82063)
		(end 119.407686 -276.838918)
		(width 0.1143)
		(layer "In13.Cu")
		(net "P5E_CPU1_P2_TX_DN<7>")
	)
	(segment
		(start 120.534684 -270.03629)
		(end 120.236742 -270.03629)
		(width 0.1143)
		(layer "In13.Cu")
		(net "P5E_CPU1_P2_TX_DN<7>")
	)
	(segment
		(start 119.407686 -277.81377)
		(end 119.375936 -277.832058)
		(width 0.1143)
		(layer "In13.Cu")
		(net "P5E_CPU1_P2_TX_DN<7>")
	)
	(segment
		(start 119.446802 -277.79091)
		(end 119.407686 -277.81377)
		(width 0.1143)
		(layer "In13.Cu")
		(net "P5E_CPU1_P2_TX_DN<7>")
	)
	(segment
		(start 153.449528 -369.63858)
		(end 153.52141 -369.81257)
		(width 0.14224)
		(layer "In13.Cu")
		(net "P5E_CPU1_P2_TX_DN<7>")
	)
	(segment
		(start 119.408702 -292.393116)
		(end 119.407178 -292.393878)
		(width 0.1143)
		(layer "In13.Cu")
		(net "P5E_CPU1_P2_TX_DN<7>")
	)
	(segment
		(start 119.408702 -281.053286)
		(end 119.407686 -281.053794)
		(width 0.1143)
		(layer "In13.Cu")
		(net "P5E_CPU1_P2_TX_DN<7>")
	)
	(segment
		(start 154.480768 -370.261388)
		(end 154.701748 -370.482368)
		(width 0.14224)
		(layer "In13.Cu")
		(net "P5E_CPU1_P2_TX_DN<7>")
	)
	(segment
		(start 136.619996 -322.927726)
		(end 141.915388 -349.549974)
		(width 0.14224)
		(layer "In13.Cu")
		(net "P5E_CPU1_P2_TX_DN<7>")
	)
	(segment
		(start 119.408702 -291.41928)
		(end 119.410226 -291.420296)
		(width 0.1143)
		(layer "In13.Cu")
		(net "P5E_CPU1_P2_TX_DN<7>")
	)
	(segment
		(start 119.410226 -291.420296)
		(end 119.446802 -291.441632)
		(width 0.1143)
		(layer "In13.Cu")
		(net "P5E_CPU1_P2_TX_DN<7>")
	)
	(segment
		(start 120.205754 -296.327068)
		(end 120.205754 -297.379136)
		(width 0.14224)
		(layer "In13.Cu")
		(net "P5E_CPU1_P2_TX_DN<7>")
	)
	(segment
		(start 119.407686 -271.333722)
		(end 119.375936 -271.35201)
		(width 0.1143)
		(layer "In13.Cu")
		(net "P5E_CPU1_P2_TX_DN<7>")
	)
	(segment
		(start 120.236742 -270.03629)
		(end 120.153938 -270.119094)
		(width 0.1143)
		(layer "In13.Cu")
		(net "P5E_CPU1_P2_TX_DN<7>")
	)
	(segment
		(start 119.375936 -278.440642)
		(end 119.407686 -278.45893)
		(width 0.1143)
		(layer "In13.Cu")
		(net "P5E_CPU1_P2_TX_DN<7>")
	)
	(segment
		(start 119.407686 -289.79876)
		(end 119.408702 -289.799268)
		(width 0.1143)
		(layer "In13.Cu")
		(net "P5E_CPU1_P2_TX_DN<7>")
	)
	(segment
		(start 119.375936 -275.200618)
		(end 119.407686 -275.218906)
		(width 0.1143)
		(layer "In13.Cu")
		(net "P5E_CPU1_P2_TX_DN<7>")
	)
	(segment
		(start 152.962102 -367.554764)
		(end 153.385266 -368.692684)
		(width 0.14224)
		(layer "In13.Cu")
		(net "P5E_CPU1_P2_TX_DN<7>")
	)
	(segment
		(start 119.375936 -273.580606)
		(end 119.407686 -273.598894)
		(width 0.1143)
		(layer "In13.Cu")
		(net "P5E_CPU1_P2_TX_DN<7>")
	)
	(segment
		(start 119.407686 -288.178748)
		(end 119.425974 -288.189416)
		(width 0.1143)
		(layer "In13.Cu")
		(net "P5E_CPU1_P2_TX_DN<7>")
	)
	(segment
		(start 119.446802 -272.930874)
		(end 119.407686 -272.953734)
		(width 0.1143)
		(layer "In13.Cu")
		(net "P5E_CPU1_P2_TX_DN<7>")
	)
	(segment
		(start 119.407686 -271.978882)
		(end 119.446802 -272.001742)
		(width 0.1143)
		(layer "In13.Cu")
		(net "P5E_CPU1_P2_TX_DN<7>")
	)
	(segment
		(start 120.160034 -296.2529)
		(end 120.205754 -296.29862)
		(width 0.1143)
		(layer "In13.Cu")
		(net "P5E_CPU1_P2_TX_DN<7>")
	)
	(segment
		(start 131.099306 -313.304682)
		(end 133.028436 -316.192154)
		(width 0.14224)
		(layer "In13.Cu")
		(net "P5E_CPU1_P2_TX_DN<7>")
	)
	(segment
		(start 119.407686 -272.953734)
		(end 119.375936 -272.972022)
		(width 0.1143)
		(layer "In13.Cu")
		(net "P5E_CPU1_P2_TX_DN<7>")
	)
	(segment
		(start 148.551138 -362.379768)
		(end 152.847294 -367.3602)
		(width 0.14224)
		(layer "In13.Cu")
		(net "P5E_CPU1_P2_TX_DN<7>")
	)
	(segment
		(start 119.402606 -289.795966)
		(end 119.407686 -289.79876)
		(width 0.1143)
		(layer "In13.Cu")
		(net "P5E_CPU1_P2_TX_DN<7>")
	)
	(arc
		(start 119.446802 -293.061644)
		(mid 119.690129 -293.52621)
		(end 119.446802 -293.990776)
		(width 0.1143)
		(layer "In13.Cu")
		(net "P5E_CPU1_P2_TX_DN<7>")
	)
	(arc
		(start 119.375936 -271.35201)
		(mid 119.224347 -271.656302)
		(end 119.375936 -271.960594)
		(width 0.1143)
		(layer "In13.Cu")
		(net "P5E_CPU1_P2_TX_DN<7>")
	)
	(arc
		(start 119.44604 -293.061136)
		(mid 119.446421 -293.06139)
		(end 119.446802 -293.061644)
		(width 0.1143)
		(layer "In13.Cu")
		(net "P5E_CPU1_P2_TX_DN<7>")
	)
	(arc
		(start 119.446802 -275.241766)
		(mid 119.690129 -275.706332)
		(end 119.446802 -276.170898)
		(width 0.1143)
		(layer "In13.Cu")
		(net "P5E_CPU1_P2_TX_DN<7>")
	)
	(arc
		(start 119.389906 -294.023796)
		(mid 119.210019 -294.336106)
		(end 119.389652 -294.648636)
		(width 0.1143)
		(layer "In13.Cu")
		(net "P5E_CPU1_P2_TX_DN<7>")
	)
	(arc
		(start 119.847106 -270.541496)
		(mid 119.731679 -270.674872)
		(end 119.690134 -270.846296)
		(width 0.1143)
		(layer "In13.Cu")
		(net "P5E_CPU1_P2_TX_DN<7>")
	)
	(arc
		(start 119.446802 -278.48179)
		(mid 119.690129 -278.946356)
		(end 119.446802 -279.410922)
		(width 0.1143)
		(layer "In13.Cu")
		(net "P5E_CPU1_P2_TX_DN<7>")
	)
	(arc
		(start 119.446802 -280.101802)
		(mid 119.690129 -280.566368)
		(end 119.446802 -281.030934)
		(width 0.1143)
		(layer "In13.Cu")
		(net "P5E_CPU1_P2_TX_DN<7>")
	)
	(arc
		(start 153.597864 -369.913662)
		(mid 153.809258 -370.04175)
		(end 154.044904 -370.116354)
		(width 0.14224)
		(layer "In13.Cu")
		(net "P5E_CPU1_P2_TX_DN<7>")
	)
	(arc
		(start 119.21998 -287.856422)
		(mid 119.26182 -288.028408)
		(end 119.377968 -288.161984)
		(width 0.1143)
		(layer "In13.Cu")
		(net "P5E_CPU1_P2_TX_DN<7>")
	)
	(arc
		(start 119.446802 -288.201608)
		(mid 119.690129 -288.666174)
		(end 119.446802 -289.13074)
		(width 0.1143)
		(layer "In13.Cu")
		(net "P5E_CPU1_P2_TX_DN<7>")
	)
	(arc
		(start 119.446802 -276.861778)
		(mid 119.690129 -277.326344)
		(end 119.446802 -277.79091)
		(width 0.1143)
		(layer "In13.Cu")
		(net "P5E_CPU1_P2_TX_DN<7>")
	)
	(arc
		(start 119.44604 -294.681148)
		(mid 119.446421 -294.681402)
		(end 119.446802 -294.681656)
		(width 0.1143)
		(layer "In13.Cu")
		(net "P5E_CPU1_P2_TX_DN<7>")
	)
	(arc
		(start 147.103592 -360.17962)
		(mid 147.13307 -360.235489)
		(end 147.166076 -360.289348)
		(width 0.14224)
		(layer "In13.Cu")
		(net "P5E_CPU1_P2_TX_DN<7>")
	)
	(arc
		(start 119.40286 -289.156394)
		(mid 119.220011 -289.476071)
		(end 119.402606 -289.795966)
		(width 0.1143)
		(layer "In13.Cu")
		(net "P5E_CPU1_P2_TX_DN<7>")
	)
	(arc
		(start 119.407178 -290.773866)
		(mid 119.22154 -291.096382)
		(end 119.407178 -291.418772)
		(width 0.1143)
		(layer "In13.Cu")
		(net "P5E_CPU1_P2_TX_DN<7>")
	)
	(arc
		(start 119.407178 -292.393878)
		(mid 119.221658 -292.711935)
		(end 119.399812 -293.034212)
		(width 0.1143)
		(layer "In13.Cu")
		(net "P5E_CPU1_P2_TX_DN<7>")
	)
	(arc
		(start 119.446802 -294.681656)
		(mid 119.625615 -294.884006)
		(end 119.690134 -295.146222)
		(width 0.1143)
		(layer "In13.Cu")
		(net "P5E_CPU1_P2_TX_DN<7>")
	)
	(arc
		(start 119.403876 -285.915862)
		(mid 119.220119 -286.2363)
		(end 119.403622 -286.556958)
		(width 0.1143)
		(layer "In13.Cu")
		(net "P5E_CPU1_P2_TX_DN<7>")
	)
	(arc
		(start 119.375936 -276.212046)
		(mid 119.224347 -276.516338)
		(end 119.375936 -276.82063)
		(width 0.1143)
		(layer "In13.Cu")
		(net "P5E_CPU1_P2_TX_DN<7>")
	)
	(arc
		(start 119.40667 -287.53181)
		(mid 119.270012 -287.669212)
		(end 119.21998 -287.856422)
		(width 0.1143)
		(layer "In13.Cu")
		(net "P5E_CPU1_P2_TX_DN<7>")
	)
	(arc
		(start 119.690134 -295.146222)
		(mid 119.731389 -295.317193)
		(end 119.84609 -295.450514)
		(width 0.1143)
		(layer "In13.Cu")
		(net "P5E_CPU1_P2_TX_DN<7>")
	)
	(arc
		(start 119.375936 -274.592034)
		(mid 119.224347 -274.896326)
		(end 119.375936 -275.200618)
		(width 0.1143)
		(layer "In13.Cu")
		(net "P5E_CPU1_P2_TX_DN<7>")
	)
	(arc
		(start 119.690134 -270.846296)
		(mid 119.625619 -271.108515)
		(end 119.446802 -271.310862)
		(width 0.1143)
		(layer "In13.Cu")
		(net "P5E_CPU1_P2_TX_DN<7>")
	)
	(arc
		(start 148.496782 -362.307886)
		(mid 148.522799 -362.344705)
		(end 148.551138 -362.379768)
		(width 0.14224)
		(layer "In13.Cu")
		(net "P5E_CPU1_P2_TX_DN<7>")
	)
	(arc
		(start 154.701748 -370.482368)
		(mid 155.017397 -370.954675)
		(end 155.128214 -371.51183)
		(width 0.14224)
		(layer "In13.Cu")
		(net "P5E_CPU1_P2_TX_DN<7>")
	)
	(arc
		(start 119.68988 -287.046162)
		(mid 119.615069 -287.325129)
		(end 119.410734 -287.52927)
		(width 0.1143)
		(layer "In13.Cu")
		(net "P5E_CPU1_P2_TX_DN<7>")
	)
	(arc
		(start 120.153938 -270.119094)
		(mid 120.15215 -270.130543)
		(end 120.150128 -270.141954)
		(width 0.1143)
		(layer "In13.Cu")
		(net "P5E_CPU1_P2_TX_DN<7>")
	)
	(arc
		(start 153.52141 -369.81257)
		(mid 153.553058 -369.868097)
		(end 153.597864 -369.913662)
		(width 0.14224)
		(layer "In13.Cu")
		(net "P5E_CPU1_P2_TX_DN<7>")
	)
	(arc
		(start 119.446294 -281.721306)
		(mid 119.688333 -282.209885)
		(end 119.402606 -282.674314)
		(width 0.1143)
		(layer "In13.Cu")
		(net "P5E_CPU1_P2_TX_DN<7>")
	)
	(arc
		(start 152.847294 -367.3602)
		(mid 152.913383 -367.452356)
		(end 152.962102 -367.554764)
		(width 0.14224)
		(layer "In13.Cu")
		(net "P5E_CPU1_P2_TX_DN<7>")
	)
	(arc
		(start 119.402606 -284.294326)
		(mid 119.220291 -284.601382)
		(end 119.377968 -284.921706)
		(width 0.1143)
		(layer "In13.Cu")
		(net "P5E_CPU1_P2_TX_DN<7>")
	)
	(arc
		(start 120.150128 -270.141954)
		(mid 120.068695 -270.344352)
		(end 119.916702 -270.500856)
		(width 0.1143)
		(layer "In13.Cu")
		(net "P5E_CPU1_P2_TX_DN<7>")
	)
	(arc
		(start 119.446802 -273.621754)
		(mid 119.690129 -274.08632)
		(end 119.446802 -274.550886)
		(width 0.1143)
		(layer "In13.Cu")
		(net "P5E_CPU1_P2_TX_DN<7>")
	)
	(arc
		(start 119.446802 -291.441632)
		(mid 119.690129 -291.906198)
		(end 119.446802 -292.370764)
		(width 0.1143)
		(layer "In13.Cu")
		(net "P5E_CPU1_P2_TX_DN<7>")
	)
	(arc
		(start 119.406416 -281.054302)
		(mid 119.221073 -281.360123)
		(end 119.377714 -281.681682)
		(width 0.1143)
		(layer "In13.Cu")
		(net "P5E_CPU1_P2_TX_DN<7>")
	)
	(arc
		(start 119.446294 -283.341318)
		(mid 119.688333 -283.829897)
		(end 119.402606 -284.294326)
		(width 0.1143)
		(layer "In13.Cu")
		(net "P5E_CPU1_P2_TX_DN<7>")
	)
	(arc
		(start 154.045158 -370.116354)
		(mid 154.107999 -370.125609)
		(end 154.171396 -370.129562)
		(width 0.14224)
		(layer "In13.Cu")
		(net "P5E_CPU1_P2_TX_DN<7>")
	)
	(arc
		(start 119.402606 -282.674314)
		(mid 119.220295 -282.981267)
		(end 119.377714 -283.301694)
		(width 0.1143)
		(layer "In13.Cu")
		(net "P5E_CPU1_P2_TX_DN<7>")
	)
	(arc
		(start 119.448834 -286.58312)
		(mid 119.62603 -286.785132)
		(end 119.68988 -287.046162)
		(width 0.1143)
		(layer "In13.Cu")
		(net "P5E_CPU1_P2_TX_DN<7>")
	)
	(arc
		(start 119.446802 -289.82162)
		(mid 119.690129 -290.286186)
		(end 119.446802 -290.750752)
		(width 0.1143)
		(layer "In13.Cu")
		(net "P5E_CPU1_P2_TX_DN<7>")
	)
	(arc
		(start 119.446802 -272.001742)
		(mid 119.690129 -272.466308)
		(end 119.446802 -272.930874)
		(width 0.1143)
		(layer "In13.Cu")
		(net "P5E_CPU1_P2_TX_DN<7>")
	)
	(arc
		(start 153.425144 -369.515136)
		(mid 153.43127 -369.578057)
		(end 153.449528 -369.63858)
		(width 0.14224)
		(layer "In13.Cu")
		(net "P5E_CPU1_P2_TX_DN<7>")
	)
	(arc
		(start 119.375936 -277.832058)
		(mid 119.224347 -278.13635)
		(end 119.375936 -278.440642)
		(width 0.1143)
		(layer "In13.Cu")
		(net "P5E_CPU1_P2_TX_DN<7>")
	)
	(arc
		(start 119.430038 -284.952186)
		(mid 119.702425 -285.427144)
		(end 119.428768 -285.901384)
		(width 0.1143)
		(layer "In13.Cu")
		(net "P5E_CPU1_P2_TX_DN<7>")
	)
	(arc
		(start 153.385266 -368.692684)
		(mid 153.415098 -368.801905)
		(end 153.425144 -368.91468)
		(width 0.14224)
		(layer "In13.Cu")
		(net "P5E_CPU1_P2_TX_DN<7>")
	)
	(arc
		(start 119.375936 -279.45207)
		(mid 119.224347 -279.756362)
		(end 119.375936 -280.060654)
		(width 0.1143)
		(layer "In13.Cu")
		(net "P5E_CPU1_P2_TX_DN<7>")
	)
	(arc
		(start 154.171396 -370.129562)
		(mid 154.338827 -370.165543)
		(end 154.480768 -370.261388)
		(width 0.14224)
		(layer "In13.Cu")
		(net "P5E_CPU1_P2_TX_DN<7>")
	)
	(arc
		(start 119.375936 -272.972022)
		(mid 119.224347 -273.276314)
		(end 119.375936 -273.580606)
		(width 0.1143)
		(layer "In13.Cu")
		(net "P5E_CPU1_P2_TX_DN<7>")
	)
	(arc
		(start 119.916194 -295.491154)
		(mid 120.095387 -295.693664)
		(end 120.160034 -295.956228)
		(width 0.1143)
		(layer "In13.Cu")
		(net "P5E_CPU1_P2_TX_DN<7>")
	)
	(segment
		(start 151.744934 -369.30584)
		(end 151.744934 -370.00942)
		(width 0.12954)
		(layer "F.Cu")
		(net "P5E_CPU1_P2_TX_DN<6>")
	)
	(segment
		(start 151.744934 -370.00942)
		(end 152.040844 -370.30533)
		(width 0.12954)
		(layer "F.Cu")
		(net "P5E_CPU1_P2_TX_DN<6>")
	)
	(segment
		(start 152.015444 -369.03533)
		(end 151.744934 -369.30584)
		(width 0.12954)
		(layer "F.Cu")
		(net "P5E_CPU1_P2_TX_DN<6>")
	)
	(segment
		(start 117.247924 -271.390364)
		(end 117.714776 -271.656302)
		(width 0.12954)
		(layer "F.Cu")
		(net "P5E_CPU1_P2_TX_DN<6>")
	)
	(segment
		(start 119.266208 -297.552364)
		(end 120.31218 -300.077124)
		(width 0.14224)
		(layer "In13.Cu")
		(net "P5E_CPU1_P2_TX_DN<6>")
	)
	(segment
		(start 118.467632 -289.1536)
		(end 118.437152 -289.17138)
		(width 0.1143)
		(layer "In13.Cu")
		(net "P5E_CPU1_P2_TX_DN<6>")
	)
	(segment
		(start 118.437152 -280.061162)
		(end 118.467632 -280.078942)
		(width 0.1143)
		(layer "In13.Cu")
		(net "P5E_CPU1_P2_TX_DN<6>")
	)
	(segment
		(start 132.207762 -316.644528)
		(end 135.607806 -323.005958)
		(width 0.14224)
		(layer "In13.Cu")
		(net "P5E_CPU1_P2_TX_DN<6>")
	)
	(segment
		(start 117.997732 -272.788888)
		(end 117.998748 -272.789396)
		(width 0.1143)
		(layer "In13.Cu")
		(net "P5E_CPU1_P2_TX_DN<6>")
	)
	(segment
		(start 118.506748 -281.030934)
		(end 118.467632 -281.053794)
		(width 0.1143)
		(layer "In13.Cu")
		(net "P5E_CPU1_P2_TX_DN<6>")
	)
	(segment
		(start 117.416834 -271.656302)
		(end 117.346984 -271.726152)
		(width 0.1143)
		(layer "In13.Cu")
		(net "P5E_CPU1_P2_TX_DN<6>")
	)
	(segment
		(start 118.506748 -279.410922)
		(end 118.467632 -279.433782)
		(width 0.1143)
		(layer "In13.Cu")
		(net "P5E_CPU1_P2_TX_DN<6>")
	)
	(segment
		(start 118.506748 -284.270958)
		(end 118.467632 -284.293818)
		(width 0.1143)
		(layer "In13.Cu")
		(net "P5E_CPU1_P2_TX_DN<6>")
	)
	(segment
		(start 118.467632 -281.698954)
		(end 118.506748 -281.721814)
		(width 0.1143)
		(layer "In13.Cu")
		(net "P5E_CPU1_P2_TX_DN<6>")
	)
	(segment
		(start 118.437152 -281.681174)
		(end 118.467632 -281.698954)
		(width 0.1143)
		(layer "In13.Cu")
		(net "P5E_CPU1_P2_TX_DN<6>")
	)
	(segment
		(start 118.467632 -283.318966)
		(end 118.506748 -283.341826)
		(width 0.1143)
		(layer "In13.Cu")
		(net "P5E_CPU1_P2_TX_DN<6>")
	)
	(segment
		(start 118.467632 -284.293818)
		(end 118.437152 -284.311598)
		(width 0.1143)
		(layer "In13.Cu")
		(net "P5E_CPU1_P2_TX_DN<6>")
	)
	(segment
		(start 118.467632 -276.838918)
		(end 118.506748 -276.861778)
		(width 0.1143)
		(layer "In13.Cu")
		(net "P5E_CPU1_P2_TX_DN<6>")
	)
	(segment
		(start 118.437152 -278.44115)
		(end 118.467632 -278.45893)
		(width 0.1143)
		(layer "In13.Cu")
		(net "P5E_CPU1_P2_TX_DN<6>")
	)
	(segment
		(start 117.965982 -272.7706)
		(end 117.99697 -272.78838)
		(width 0.1143)
		(layer "In13.Cu")
		(net "P5E_CPU1_P2_TX_DN<6>")
	)
	(segment
		(start 118.467632 -294.658796)
		(end 118.506748 -294.681656)
		(width 0.1143)
		(layer "In13.Cu")
		(net "P5E_CPU1_P2_TX_DN<6>")
	)
	(segment
		(start 119.220234 -296.2529)
		(end 119.265954 -296.29862)
		(width 0.1143)
		(layer "In13.Cu")
		(net "P5E_CPU1_P2_TX_DN<6>")
	)
	(segment
		(start 117.527578 -271.978882)
		(end 117.566694 -272.001742)
		(width 0.1143)
		(layer "In13.Cu")
		(net "P5E_CPU1_P2_TX_DN<6>")
	)
	(segment
		(start 151.036528 -367.401856)
		(end 151.222964 -367.526824)
		(width 0.14224)
		(layer "In13.Cu")
		(net "P5E_CPU1_P2_TX_DN<6>")
	)
	(segment
		(start 118.001288 -272.79092)
		(end 118.003828 -272.792444)
		(width 0.1143)
		(layer "In13.Cu")
		(net "P5E_CPU1_P2_TX_DN<6>")
	)
	(segment
		(start 118.437152 -275.201126)
		(end 118.467632 -275.218906)
		(width 0.1143)
		(layer "In13.Cu")
		(net "P5E_CPU1_P2_TX_DN<6>")
	)
	(segment
		(start 118.000272 -272.790412)
		(end 118.001288 -272.79092)
		(width 0.1143)
		(layer "In13.Cu")
		(net "P5E_CPU1_P2_TX_DN<6>")
	)
	(segment
		(start 118.506748 -293.990776)
		(end 118.467632 -294.013636)
		(width 0.1143)
		(layer "In13.Cu")
		(net "P5E_CPU1_P2_TX_DN<6>")
	)
	(segment
		(start 118.467632 -290.773612)
		(end 118.437152 -290.791392)
		(width 0.1143)
		(layer "In13.Cu")
		(net "P5E_CPU1_P2_TX_DN<6>")
	)
	(segment
		(start 117.99697 -272.78838)
		(end 117.997732 -272.788888)
		(width 0.1143)
		(layer "In13.Cu")
		(net "P5E_CPU1_P2_TX_DN<6>")
	)
	(segment
		(start 118.506748 -292.370764)
		(end 118.467632 -292.393624)
		(width 0.1143)
		(layer "In13.Cu")
		(net "P5E_CPU1_P2_TX_DN<6>")
	)
	(segment
		(start 118.43512 -288.159952)
		(end 118.467632 -288.178748)
		(width 0.1143)
		(layer "In13.Cu")
		(net "P5E_CPU1_P2_TX_DN<6>")
	)
	(segment
		(start 121.107708 -301.40402)
		(end 130.355848 -313.87288)
		(width 0.14224)
		(layer "In13.Cu")
		(net "P5E_CPU1_P2_TX_DN<6>")
	)
	(segment
		(start 119.266208 -296.907966)
		(end 119.266208 -297.552364)
		(width 0.14224)
		(layer "In13.Cu")
		(net "P5E_CPU1_P2_TX_DN<6>")
	)
	(segment
		(start 118.437152 -283.301186)
		(end 118.467632 -283.318966)
		(width 0.1143)
		(layer "In13.Cu")
		(net "P5E_CPU1_P2_TX_DN<6>")
	)
	(segment
		(start 118.506748 -277.79091)
		(end 118.467632 -277.81377)
		(width 0.1143)
		(layer "In13.Cu")
		(net "P5E_CPU1_P2_TX_DN<6>")
	)
	(segment
		(start 118.937786 -295.468802)
		(end 118.938802 -295.46931)
		(width 0.1143)
		(layer "In13.Cu")
		(net "P5E_CPU1_P2_TX_DN<6>")
	)
	(segment
		(start 119.220234 -295.956228)
		(end 119.220234 -296.2529)
		(width 0.1143)
		(layer "In13.Cu")
		(net "P5E_CPU1_P2_TX_DN<6>")
	)
	(segment
		(start 118.506748 -289.13074)
		(end 118.467632 -289.1536)
		(width 0.1143)
		(layer "In13.Cu")
		(net "P5E_CPU1_P2_TX_DN<6>")
	)
	(segment
		(start 146.12874 -360.434382)
		(end 149.707092 -365.860838)
		(width 0.14224)
		(layer "In13.Cu")
		(net "P5E_CPU1_P2_TX_DN<6>")
	)
	(segment
		(start 118.940326 -295.470326)
		(end 118.941342 -295.470834)
		(width 0.1143)
		(layer "In13.Cu")
		(net "P5E_CPU1_P2_TX_DN<6>")
	)
	(segment
		(start 118.467632 -292.393624)
		(end 118.437152 -292.411404)
		(width 0.1143)
		(layer "In13.Cu")
		(net "P5E_CPU1_P2_TX_DN<6>")
	)
	(segment
		(start 120.31218 -300.077124)
		(end 121.107708 -301.40402)
		(width 0.14224)
		(layer "In13.Cu")
		(net "P5E_CPU1_P2_TX_DN<6>")
	)
	(segment
		(start 118.467632 -282.673806)
		(end 118.437152 -282.691586)
		(width 0.1143)
		(layer "In13.Cu")
		(net "P5E_CPU1_P2_TX_DN<6>")
	)
	(segment
		(start 118.437152 -293.021004)
		(end 118.467632 -293.038784)
		(width 0.1143)
		(layer "In13.Cu")
		(net "P5E_CPU1_P2_TX_DN<6>")
	)
	(segment
		(start 118.467632 -286.558736)
		(end 118.506748 -286.581596)
		(width 0.1143)
		(layer "In13.Cu")
		(net "P5E_CPU1_P2_TX_DN<6>")
	)
	(segment
		(start 118.467632 -281.053794)
		(end 118.437152 -281.071574)
		(width 0.1143)
		(layer "In13.Cu")
		(net "P5E_CPU1_P2_TX_DN<6>")
	)
	(segment
		(start 135.607806 -323.005958)
		(end 135.755634 -323.362574)
		(width 0.14224)
		(layer "In13.Cu")
		(net "P5E_CPU1_P2_TX_DN<6>")
	)
	(segment
		(start 118.945406 -295.473374)
		(end 118.976902 -295.491662)
		(width 0.1143)
		(layer "In13.Cu")
		(net "P5E_CPU1_P2_TX_DN<6>")
	)
	(segment
		(start 118.943882 -295.472358)
		(end 118.945406 -295.473374)
		(width 0.1143)
		(layer "In13.Cu")
		(net "P5E_CPU1_P2_TX_DN<6>")
	)
	(segment
		(start 117.714776 -271.656302)
		(end 117.416834 -271.656302)
		(width 0.1143)
		(layer "In13.Cu")
		(net "P5E_CPU1_P2_TX_DN<6>")
	)
	(segment
		(start 118.467632 -274.573746)
		(end 118.437152 -274.591526)
		(width 0.1143)
		(layer "In13.Cu")
		(net "P5E_CPU1_P2_TX_DN<6>")
	)
	(segment
		(start 151.724614 -368.7445)
		(end 152.015444 -369.03533)
		(width 0.14224)
		(layer "In13.Cu")
		(net "P5E_CPU1_P2_TX_DN<6>")
	)
	(segment
		(start 118.938802 -295.46931)
		(end 118.940326 -295.470326)
		(width 0.1143)
		(layer "In13.Cu")
		(net "P5E_CPU1_P2_TX_DN<6>")
	)
	(segment
		(start 118.467632 -284.938978)
		(end 118.506748 -284.961838)
		(width 0.1143)
		(layer "In13.Cu")
		(net "P5E_CPU1_P2_TX_DN<6>")
	)
	(segment
		(start 118.003828 -272.792444)
		(end 118.005352 -272.79346)
		(width 0.1143)
		(layer "In13.Cu")
		(net "P5E_CPU1_P2_TX_DN<6>")
	)
	(segment
		(start 118.467632 -294.013636)
		(end 118.437152 -294.031416)
		(width 0.1143)
		(layer "In13.Cu")
		(net "P5E_CPU1_P2_TX_DN<6>")
	)
	(segment
		(start 118.467632 -273.598894)
		(end 118.506748 -273.621754)
		(width 0.1143)
		(layer "In13.Cu")
		(net "P5E_CPU1_P2_TX_DN<6>")
	)
	(segment
		(start 118.467632 -280.078942)
		(end 118.506748 -280.101802)
		(width 0.1143)
		(layer "In13.Cu")
		(net "P5E_CPU1_P2_TX_DN<6>")
	)
	(segment
		(start 118.437152 -284.921198)
		(end 118.467632 -284.938978)
		(width 0.1143)
		(layer "In13.Cu")
		(net "P5E_CPU1_P2_TX_DN<6>")
	)
	(segment
		(start 151.222964 -367.526824)
		(end 151.487124 -367.790984)
		(width 0.14224)
		(layer "In13.Cu")
		(net "P5E_CPU1_P2_TX_DN<6>")
	)
	(segment
		(start 135.755634 -323.362574)
		(end 141.067028 -350.064578)
		(width 0.14224)
		(layer "In13.Cu")
		(net "P5E_CPU1_P2_TX_DN<6>")
	)
	(segment
		(start 118.506748 -282.650946)
		(end 118.467632 -282.673806)
		(width 0.1143)
		(layer "In13.Cu")
		(net "P5E_CPU1_P2_TX_DN<6>")
	)
	(segment
		(start 118.467632 -277.81377)
		(end 118.437152 -277.83155)
		(width 0.1143)
		(layer "In13.Cu")
		(net "P5E_CPU1_P2_TX_DN<6>")
	)
	(segment
		(start 118.467632 -285.91383)
		(end 118.437152 -285.93161)
		(width 0.1143)
		(layer "In13.Cu")
		(net "P5E_CPU1_P2_TX_DN<6>")
	)
	(segment
		(start 118.506748 -290.750752)
		(end 118.467632 -290.773612)
		(width 0.1143)
		(layer "In13.Cu")
		(net "P5E_CPU1_P2_TX_DN<6>")
	)
	(segment
		(start 118.467632 -278.45893)
		(end 118.506748 -278.48179)
		(width 0.1143)
		(layer "In13.Cu")
		(net "P5E_CPU1_P2_TX_DN<6>")
	)
	(segment
		(start 118.467632 -276.193758)
		(end 118.437152 -276.211538)
		(width 0.1143)
		(layer "In13.Cu")
		(net "P5E_CPU1_P2_TX_DN<6>")
	)
	(segment
		(start 118.437152 -273.581114)
		(end 118.467632 -273.598894)
		(width 0.1143)
		(layer "In13.Cu")
		(net "P5E_CPU1_P2_TX_DN<6>")
	)
	(segment
		(start 118.941342 -295.470834)
		(end 118.943882 -295.472358)
		(width 0.1143)
		(layer "In13.Cu")
		(net "P5E_CPU1_P2_TX_DN<6>")
	)
	(segment
		(start 118.43512 -286.53994)
		(end 118.467632 -286.558736)
		(width 0.1143)
		(layer "In13.Cu")
		(net "P5E_CPU1_P2_TX_DN<6>")
	)
	(segment
		(start 118.467632 -293.038784)
		(end 118.506748 -293.061644)
		(width 0.1143)
		(layer "In13.Cu")
		(net "P5E_CPU1_P2_TX_DN<6>")
	)
	(segment
		(start 118.906036 -295.450514)
		(end 118.937786 -295.468802)
		(width 0.1143)
		(layer "In13.Cu")
		(net "P5E_CPU1_P2_TX_DN<6>")
	)
	(segment
		(start 118.437152 -294.641016)
		(end 118.467632 -294.658796)
		(width 0.1143)
		(layer "In13.Cu")
		(net "P5E_CPU1_P2_TX_DN<6>")
	)
	(segment
		(start 118.437152 -289.78098)
		(end 118.467632 -289.79876)
		(width 0.1143)
		(layer "In13.Cu")
		(net "P5E_CPU1_P2_TX_DN<6>")
	)
	(segment
		(start 141.067028 -350.064578)
		(end 146.12874 -360.434382)
		(width 0.14224)
		(layer "In13.Cu")
		(net "P5E_CPU1_P2_TX_DN<6>")
	)
	(segment
		(start 117.998748 -272.789396)
		(end 118.000272 -272.790412)
		(width 0.1143)
		(layer "In13.Cu")
		(net "P5E_CPU1_P2_TX_DN<6>")
	)
	(segment
		(start 119.265954 -296.29862)
		(end 119.265954 -296.327068)
		(width 0.1143)
		(layer "In13.Cu")
		(net "P5E_CPU1_P2_TX_DN<6>")
	)
	(segment
		(start 118.506748 -285.89097)
		(end 118.467632 -285.91383)
		(width 0.1143)
		(layer "In13.Cu")
		(net "P5E_CPU1_P2_TX_DN<6>")
	)
	(segment
		(start 130.355848 -313.87288)
		(end 132.207762 -316.644528)
		(width 0.14224)
		(layer "In13.Cu")
		(net "P5E_CPU1_P2_TX_DN<6>")
	)
	(segment
		(start 118.504208 -287.512506)
		(end 118.437152 -287.551622)
		(width 0.1143)
		(layer "In13.Cu")
		(net "P5E_CPU1_P2_TX_DN<6>")
	)
	(segment
		(start 117.497098 -271.961102)
		(end 117.527578 -271.978882)
		(width 0.1143)
		(layer "In13.Cu")
		(net "P5E_CPU1_P2_TX_DN<6>")
	)
	(segment
		(start 119.265954 -296.907966)
		(end 119.266208 -296.907966)
		(width 0.14224)
		(layer "In13.Cu")
		(net "P5E_CPU1_P2_TX_DN<6>")
	)
	(segment
		(start 149.707092 -365.860838)
		(end 151.036528 -367.401856)
		(width 0.14224)
		(layer "In13.Cu")
		(net "P5E_CPU1_P2_TX_DN<6>")
	)
	(segment
		(start 118.467632 -288.178748)
		(end 118.506748 -288.201608)
		(width 0.1143)
		(layer "In13.Cu")
		(net "P5E_CPU1_P2_TX_DN<6>")
	)
	(segment
		(start 118.437152 -276.821138)
		(end 118.467632 -276.838918)
		(width 0.1143)
		(layer "In13.Cu")
		(net "P5E_CPU1_P2_TX_DN<6>")
	)
	(segment
		(start 151.724614 -368.364262)
		(end 151.724614 -368.7445)
		(width 0.14224)
		(layer "In13.Cu")
		(net "P5E_CPU1_P2_TX_DN<6>")
	)
	(segment
		(start 118.437152 -291.400992)
		(end 118.467632 -291.418772)
		(width 0.1143)
		(layer "In13.Cu")
		(net "P5E_CPU1_P2_TX_DN<6>")
	)
	(segment
		(start 118.467632 -291.418772)
		(end 118.506748 -291.441632)
		(width 0.1143)
		(layer "In13.Cu")
		(net "P5E_CPU1_P2_TX_DN<6>")
	)
	(segment
		(start 118.005352 -272.79346)
		(end 118.036848 -272.811748)
		(width 0.1143)
		(layer "In13.Cu")
		(net "P5E_CPU1_P2_TX_DN<6>")
	)
	(segment
		(start 118.467632 -289.79876)
		(end 118.506748 -289.82162)
		(width 0.1143)
		(layer "In13.Cu")
		(net "P5E_CPU1_P2_TX_DN<6>")
	)
	(segment
		(start 118.506748 -276.170898)
		(end 118.467632 -276.193758)
		(width 0.1143)
		(layer "In13.Cu")
		(net "P5E_CPU1_P2_TX_DN<6>")
	)
	(segment
		(start 118.467632 -275.218906)
		(end 118.506748 -275.241766)
		(width 0.1143)
		(layer "In13.Cu")
		(net "P5E_CPU1_P2_TX_DN<6>")
	)
	(segment
		(start 118.506748 -274.550886)
		(end 118.467632 -274.573746)
		(width 0.1143)
		(layer "In13.Cu")
		(net "P5E_CPU1_P2_TX_DN<6>")
	)
	(segment
		(start 118.467632 -279.433782)
		(end 118.437152 -279.451562)
		(width 0.1143)
		(layer "In13.Cu")
		(net "P5E_CPU1_P2_TX_DN<6>")
	)
	(segment
		(start 119.265954 -296.327068)
		(end 119.265954 -296.907966)
		(width 0.14224)
		(layer "In13.Cu")
		(net "P5E_CPU1_P2_TX_DN<6>")
	)
	(arc
		(start 151.487124 -367.790984)
		(mid 151.66287 -368.054006)
		(end 151.724614 -368.364262)
		(width 0.14224)
		(layer "In13.Cu")
		(net "P5E_CPU1_P2_TX_DN<6>")
	)
	(arc
		(start 118.506748 -291.441632)
		(mid 118.750075 -291.906198)
		(end 118.506748 -292.370764)
		(width 0.1143)
		(layer "In13.Cu")
		(net "P5E_CPU1_P2_TX_DN<6>")
	)
	(arc
		(start 118.437152 -294.031416)
		(mid 118.280175 -294.336216)
		(end 118.437152 -294.641016)
		(width 0.1143)
		(layer "In13.Cu")
		(net "P5E_CPU1_P2_TX_DN<6>")
	)
	(arc
		(start 118.506748 -289.82162)
		(mid 118.750075 -290.286186)
		(end 118.506748 -290.750752)
		(width 0.1143)
		(layer "In13.Cu")
		(net "P5E_CPU1_P2_TX_DN<6>")
	)
	(arc
		(start 118.437152 -290.791392)
		(mid 118.280175 -291.096192)
		(end 118.437152 -291.400992)
		(width 0.1143)
		(layer "In13.Cu")
		(net "P5E_CPU1_P2_TX_DN<6>")
	)
	(arc
		(start 118.036848 -272.811748)
		(mid 118.215661 -273.014098)
		(end 118.28018 -273.276314)
		(width 0.1143)
		(layer "In13.Cu")
		(net "P5E_CPU1_P2_TX_DN<6>")
	)
	(arc
		(start 118.506748 -286.581596)
		(mid 118.685561 -286.783946)
		(end 118.75008 -287.046162)
		(width 0.1143)
		(layer "In13.Cu")
		(net "P5E_CPU1_P2_TX_DN<6>")
	)
	(arc
		(start 118.506748 -276.861778)
		(mid 118.750075 -277.326344)
		(end 118.506748 -277.79091)
		(width 0.1143)
		(layer "In13.Cu")
		(net "P5E_CPU1_P2_TX_DN<6>")
	)
	(arc
		(start 118.437152 -276.211538)
		(mid 118.280175 -276.516338)
		(end 118.437152 -276.821138)
		(width 0.1143)
		(layer "In13.Cu")
		(net "P5E_CPU1_P2_TX_DN<6>")
	)
	(arc
		(start 118.437152 -282.691586)
		(mid 118.280175 -282.996386)
		(end 118.437152 -283.301186)
		(width 0.1143)
		(layer "In13.Cu")
		(net "P5E_CPU1_P2_TX_DN<6>")
	)
	(arc
		(start 117.346984 -271.726152)
		(mid 117.399401 -271.858083)
		(end 117.497098 -271.961102)
		(width 0.1143)
		(layer "In13.Cu")
		(net "P5E_CPU1_P2_TX_DN<6>")
	)
	(arc
		(start 118.28018 -286.23641)
		(mid 118.321146 -286.406816)
		(end 118.43512 -286.53994)
		(width 0.1143)
		(layer "In13.Cu")
		(net "P5E_CPU1_P2_TX_DN<6>")
	)
	(arc
		(start 117.810026 -272.466308)
		(mid 117.851281 -272.637279)
		(end 117.965982 -272.7706)
		(width 0.1143)
		(layer "In13.Cu")
		(net "P5E_CPU1_P2_TX_DN<6>")
	)
	(arc
		(start 118.437152 -289.17138)
		(mid 118.280175 -289.47618)
		(end 118.437152 -289.78098)
		(width 0.1143)
		(layer "In13.Cu")
		(net "P5E_CPU1_P2_TX_DN<6>")
	)
	(arc
		(start 118.437152 -292.411404)
		(mid 118.280175 -292.716204)
		(end 118.437152 -293.021004)
		(width 0.1143)
		(layer "In13.Cu")
		(net "P5E_CPU1_P2_TX_DN<6>")
	)
	(arc
		(start 118.506748 -281.721814)
		(mid 118.750075 -282.18638)
		(end 118.506748 -282.650946)
		(width 0.1143)
		(layer "In13.Cu")
		(net "P5E_CPU1_P2_TX_DN<6>")
	)
	(arc
		(start 119.120666 -295.63568)
		(mid 119.19478 -295.788394)
		(end 119.220234 -295.956228)
		(width 0.1143)
		(layer "In13.Cu")
		(net "P5E_CPU1_P2_TX_DN<6>")
	)
	(arc
		(start 118.437152 -287.551622)
		(mid 118.321725 -287.684998)
		(end 118.28018 -287.856422)
		(width 0.1143)
		(layer "In13.Cu")
		(net "P5E_CPU1_P2_TX_DN<6>")
	)
	(arc
		(start 118.506748 -280.101802)
		(mid 118.750075 -280.566368)
		(end 118.506748 -281.030934)
		(width 0.1143)
		(layer "In13.Cu")
		(net "P5E_CPU1_P2_TX_DN<6>")
	)
	(arc
		(start 118.28018 -287.856422)
		(mid 118.321146 -288.026828)
		(end 118.43512 -288.159952)
		(width 0.1143)
		(layer "In13.Cu")
		(net "P5E_CPU1_P2_TX_DN<6>")
	)
	(arc
		(start 118.75008 -287.046162)
		(mid 118.684844 -287.309753)
		(end 118.504208 -287.512506)
		(width 0.1143)
		(layer "In13.Cu")
		(net "P5E_CPU1_P2_TX_DN<6>")
	)
	(arc
		(start 118.506748 -283.341826)
		(mid 118.750075 -283.806392)
		(end 118.506748 -284.270958)
		(width 0.1143)
		(layer "In13.Cu")
		(net "P5E_CPU1_P2_TX_DN<6>")
	)
	(arc
		(start 118.506748 -294.681656)
		(mid 118.685561 -294.884006)
		(end 118.75008 -295.146222)
		(width 0.1143)
		(layer "In13.Cu")
		(net "P5E_CPU1_P2_TX_DN<6>")
	)
	(arc
		(start 118.437152 -281.071574)
		(mid 118.280175 -281.376374)
		(end 118.437152 -281.681174)
		(width 0.1143)
		(layer "In13.Cu")
		(net "P5E_CPU1_P2_TX_DN<6>")
	)
	(arc
		(start 118.506748 -288.201608)
		(mid 118.750075 -288.666174)
		(end 118.506748 -289.13074)
		(width 0.1143)
		(layer "In13.Cu")
		(net "P5E_CPU1_P2_TX_DN<6>")
	)
	(arc
		(start 118.506748 -278.48179)
		(mid 118.750075 -278.946356)
		(end 118.506748 -279.410922)
		(width 0.1143)
		(layer "In13.Cu")
		(net "P5E_CPU1_P2_TX_DN<6>")
	)
	(arc
		(start 117.566694 -272.001742)
		(mid 117.745507 -272.204092)
		(end 117.810026 -272.466308)
		(width 0.1143)
		(layer "In13.Cu")
		(net "P5E_CPU1_P2_TX_DN<6>")
	)
	(arc
		(start 118.506748 -293.061644)
		(mid 118.750075 -293.52621)
		(end 118.506748 -293.990776)
		(width 0.1143)
		(layer "In13.Cu")
		(net "P5E_CPU1_P2_TX_DN<6>")
	)
	(arc
		(start 118.28018 -273.276314)
		(mid 118.321729 -273.447736)
		(end 118.437152 -273.581114)
		(width 0.1143)
		(layer "In13.Cu")
		(net "P5E_CPU1_P2_TX_DN<6>")
	)
	(arc
		(start 118.437152 -274.591526)
		(mid 118.280175 -274.896326)
		(end 118.437152 -275.201126)
		(width 0.1143)
		(layer "In13.Cu")
		(net "P5E_CPU1_P2_TX_DN<6>")
	)
	(arc
		(start 118.976902 -295.491662)
		(mid 119.055325 -295.557143)
		(end 119.120666 -295.63568)
		(width 0.1143)
		(layer "In13.Cu")
		(net "P5E_CPU1_P2_TX_DN<6>")
	)
	(arc
		(start 118.437152 -277.83155)
		(mid 118.280175 -278.13635)
		(end 118.437152 -278.44115)
		(width 0.1143)
		(layer "In13.Cu")
		(net "P5E_CPU1_P2_TX_DN<6>")
	)
	(arc
		(start 118.437152 -284.311598)
		(mid 118.280175 -284.616398)
		(end 118.437152 -284.921198)
		(width 0.1143)
		(layer "In13.Cu")
		(net "P5E_CPU1_P2_TX_DN<6>")
	)
	(arc
		(start 118.75008 -295.146222)
		(mid 118.791335 -295.317193)
		(end 118.906036 -295.450514)
		(width 0.1143)
		(layer "In13.Cu")
		(net "P5E_CPU1_P2_TX_DN<6>")
	)
	(arc
		(start 118.437152 -285.93161)
		(mid 118.321725 -286.064986)
		(end 118.28018 -286.23641)
		(width 0.1143)
		(layer "In13.Cu")
		(net "P5E_CPU1_P2_TX_DN<6>")
	)
	(arc
		(start 118.506748 -273.621754)
		(mid 118.750075 -274.08632)
		(end 118.506748 -274.550886)
		(width 0.1143)
		(layer "In13.Cu")
		(net "P5E_CPU1_P2_TX_DN<6>")
	)
	(arc
		(start 118.437152 -279.451562)
		(mid 118.280175 -279.756362)
		(end 118.437152 -280.061162)
		(width 0.1143)
		(layer "In13.Cu")
		(net "P5E_CPU1_P2_TX_DN<6>")
	)
	(arc
		(start 118.506748 -275.241766)
		(mid 118.750075 -275.706332)
		(end 118.506748 -276.170898)
		(width 0.1143)
		(layer "In13.Cu")
		(net "P5E_CPU1_P2_TX_DN<6>")
	)
	(arc
		(start 118.506748 -284.961838)
		(mid 118.750075 -285.426404)
		(end 118.506748 -285.89097)
		(width 0.1143)
		(layer "In13.Cu")
		(net "P5E_CPU1_P2_TX_DN<6>")
	)
	(segment
		(start 150.043134 -371.76964)
		(end 150.043134 -372.47322)
		(width 0.12954)
		(layer "F.Cu")
		(net "P5E_CPU1_P2_TX_DN<5>")
	)
	(segment
		(start 150.043134 -372.47322)
		(end 150.339044 -372.76913)
		(width 0.12954)
		(layer "F.Cu")
		(net "P5E_CPU1_P2_TX_DN<5>")
	)
	(segment
		(start 150.313644 -371.49913)
		(end 150.043134 -371.76964)
		(width 0.12954)
		(layer "F.Cu")
		(net "P5E_CPU1_P2_TX_DN<5>")
	)
	(segment
		(start 117.247924 -273.010376)
		(end 117.714776 -273.276314)
		(width 0.12954)
		(layer "F.Cu")
		(net "P5E_CPU1_P2_TX_DN<5>")
	)
	(segment
		(start 117.53088 -294.011858)
		(end 117.496082 -294.031924)
		(width 0.1143)
		(layer "In13.Cu")
		(net "P5E_CPU1_P2_TX_DN<5>")
	)
	(segment
		(start 117.810026 -287.046162)
		(end 117.810026 -287.050734)
		(width 0.1143)
		(layer "In13.Cu")
		(net "P5E_CPU1_P2_TX_DN<5>")
	)
	(segment
		(start 117.52707 -283.318458)
		(end 117.527832 -283.318966)
		(width 0.1143)
		(layer "In13.Cu")
		(net "P5E_CPU1_P2_TX_DN<5>")
	)
	(segment
		(start 117.997732 -295.468802)
		(end 117.998748 -295.46931)
		(width 0.1143)
		(layer "In13.Cu")
		(net "P5E_CPU1_P2_TX_DN<5>")
	)
	(segment
		(start 117.965982 -295.450514)
		(end 117.997732 -295.468802)
		(width 0.1143)
		(layer "In13.Cu")
		(net "P5E_CPU1_P2_TX_DN<5>")
	)
	(segment
		(start 117.566694 -274.550886)
		(end 117.527578 -274.573746)
		(width 0.1143)
		(layer "In13.Cu")
		(net "P5E_CPU1_P2_TX_DN<5>")
	)
	(segment
		(start 117.527578 -274.573746)
		(end 117.497098 -274.591526)
		(width 0.1143)
		(layer "In13.Cu")
		(net "P5E_CPU1_P2_TX_DN<5>")
	)
	(segment
		(start 145.364708 -361.263692)
		(end 149.369272 -367.101628)
		(width 0.14224)
		(layer "In13.Cu")
		(net "P5E_CPU1_P2_TX_DN<5>")
	)
	(segment
		(start 117.527578 -276.193758)
		(end 117.497098 -276.211538)
		(width 0.1143)
		(layer "In13.Cu")
		(net "P5E_CPU1_P2_TX_DN<5>")
	)
	(segment
		(start 117.527578 -273.598894)
		(end 117.566694 -273.621754)
		(width 0.1143)
		(layer "In13.Cu")
		(net "P5E_CPU1_P2_TX_DN<5>")
	)
	(segment
		(start 117.998748 -295.46931)
		(end 118.000272 -295.470326)
		(width 0.1143)
		(layer "In13.Cu")
		(net "P5E_CPU1_P2_TX_DN<5>")
	)
	(segment
		(start 117.527578 -281.053794)
		(end 117.496082 -281.072082)
		(width 0.1143)
		(layer "In13.Cu")
		(net "P5E_CPU1_P2_TX_DN<5>")
	)
	(segment
		(start 119.476774 -300.49851)
		(end 120.351804 -301.957994)
		(width 0.14224)
		(layer "In13.Cu")
		(net "P5E_CPU1_P2_TX_DN<5>")
	)
	(segment
		(start 129.587752 -314.41136)
		(end 131.3561 -317.05804)
		(width 0.14224)
		(layer "In13.Cu")
		(net "P5E_CPU1_P2_TX_DN<5>")
	)
	(segment
		(start 140.200634 -350.489012)
		(end 143.0909 -357.009192)
		(width 0.14224)
		(layer "In13.Cu")
		(net "P5E_CPU1_P2_TX_DN<5>")
	)
	(segment
		(start 117.566694 -277.79091)
		(end 117.527578 -277.81377)
		(width 0.1143)
		(layer "In13.Cu")
		(net "P5E_CPU1_P2_TX_DN<5>")
	)
	(segment
		(start 117.527832 -291.418772)
		(end 117.527832 -291.419026)
		(width 0.1143)
		(layer "In13.Cu")
		(net "P5E_CPU1_P2_TX_DN<5>")
	)
	(segment
		(start 117.53088 -285.912052)
		(end 117.496082 -285.932118)
		(width 0.1143)
		(layer "In13.Cu")
		(net "P5E_CPU1_P2_TX_DN<5>")
	)
	(segment
		(start 117.527832 -289.79876)
		(end 117.53088 -289.800538)
		(width 0.1143)
		(layer "In13.Cu")
		(net "P5E_CPU1_P2_TX_DN<5>")
	)
	(segment
		(start 118.001288 -295.470834)
		(end 118.036848 -295.491662)
		(width 0.1143)
		(layer "In13.Cu")
		(net "P5E_CPU1_P2_TX_DN<5>")
	)
	(segment
		(start 143.0909 -357.009192)
		(end 145.364708 -361.263692)
		(width 0.14224)
		(layer "In13.Cu")
		(net "P5E_CPU1_P2_TX_DN<5>")
	)
	(segment
		(start 118.3259 -296.327068)
		(end 118.3259 -297.719242)
		(width 0.14224)
		(layer "In13.Cu")
		(net "P5E_CPU1_P2_TX_DN<5>")
	)
	(segment
		(start 117.527832 -288.178748)
		(end 117.53088 -288.180526)
		(width 0.1143)
		(layer "In13.Cu")
		(net "P5E_CPU1_P2_TX_DN<5>")
	)
	(segment
		(start 117.495066 -288.159698)
		(end 117.527832 -288.178748)
		(width 0.1143)
		(layer "In13.Cu")
		(net "P5E_CPU1_P2_TX_DN<5>")
	)
	(segment
		(start 117.527578 -275.218906)
		(end 117.566694 -275.241766)
		(width 0.1143)
		(layer "In13.Cu")
		(net "P5E_CPU1_P2_TX_DN<5>")
	)
	(segment
		(start 117.527832 -293.038784)
		(end 117.53088 -293.040562)
		(width 0.1143)
		(layer "In13.Cu")
		(net "P5E_CPU1_P2_TX_DN<5>")
	)
	(segment
		(start 117.494304 -288.15919)
		(end 117.495066 -288.159698)
		(width 0.1143)
		(layer "In13.Cu")
		(net "P5E_CPU1_P2_TX_DN<5>")
	)
	(segment
		(start 117.527832 -281.698954)
		(end 117.53088 -281.700732)
		(width 0.1143)
		(layer "In13.Cu")
		(net "P5E_CPU1_P2_TX_DN<5>")
	)
	(segment
		(start 117.53088 -284.29204)
		(end 117.496082 -284.312106)
		(width 0.1143)
		(layer "In13.Cu")
		(net "P5E_CPU1_P2_TX_DN<5>")
	)
	(segment
		(start 117.527578 -278.45893)
		(end 117.566694 -278.48179)
		(width 0.1143)
		(layer "In13.Cu")
		(net "P5E_CPU1_P2_TX_DN<5>")
	)
	(segment
		(start 118.3259 -296.29862)
		(end 118.3259 -296.327068)
		(width 0.1143)
		(layer "In13.Cu")
		(net "P5E_CPU1_P2_TX_DN<5>")
	)
	(segment
		(start 131.3561 -317.05804)
		(end 134.741158 -323.390768)
		(width 0.14224)
		(layer "In13.Cu")
		(net "P5E_CPU1_P2_TX_DN<5>")
	)
	(segment
		(start 117.496082 -293.020496)
		(end 117.527832 -293.038784)
		(width 0.1143)
		(layer "In13.Cu")
		(net "P5E_CPU1_P2_TX_DN<5>")
	)
	(segment
		(start 117.496082 -289.780472)
		(end 117.527832 -289.79876)
		(width 0.1143)
		(layer "In13.Cu")
		(net "P5E_CPU1_P2_TX_DN<5>")
	)
	(segment
		(start 150.022814 -368.859816)
		(end 150.022814 -371.2083)
		(width 0.14224)
		(layer "In13.Cu")
		(net "P5E_CPU1_P2_TX_DN<5>")
	)
	(segment
		(start 118.28018 -296.2529)
		(end 118.3259 -296.29862)
		(width 0.1143)
		(layer "In13.Cu")
		(net "P5E_CPU1_P2_TX_DN<5>")
	)
	(segment
		(start 117.527578 -276.838918)
		(end 117.566694 -276.861778)
		(width 0.1143)
		(layer "In13.Cu")
		(net "P5E_CPU1_P2_TX_DN<5>")
	)
	(segment
		(start 117.496082 -283.300678)
		(end 117.52707 -283.318458)
		(width 0.1143)
		(layer "In13.Cu")
		(net "P5E_CPU1_P2_TX_DN<5>")
	)
	(segment
		(start 117.527832 -291.419026)
		(end 117.565932 -291.440616)
		(width 0.1143)
		(layer "In13.Cu")
		(net "P5E_CPU1_P2_TX_DN<5>")
	)
	(segment
		(start 117.496082 -294.640508)
		(end 117.527832 -294.658796)
		(width 0.1143)
		(layer "In13.Cu")
		(net "P5E_CPU1_P2_TX_DN<5>")
	)
	(segment
		(start 134.874508 -323.71284)
		(end 140.200634 -350.489012)
		(width 0.14224)
		(layer "In13.Cu")
		(net "P5E_CPU1_P2_TX_DN<5>")
	)
	(segment
		(start 117.567964 -287.510474)
		(end 117.496082 -287.55213)
		(width 0.1143)
		(layer "In13.Cu")
		(net "P5E_CPU1_P2_TX_DN<5>")
	)
	(segment
		(start 117.566694 -276.170898)
		(end 117.527578 -276.193758)
		(width 0.1143)
		(layer "In13.Cu")
		(net "P5E_CPU1_P2_TX_DN<5>")
	)
	(segment
		(start 117.565932 -292.37178)
		(end 117.496082 -292.411912)
		(width 0.1143)
		(layer "In13.Cu")
		(net "P5E_CPU1_P2_TX_DN<5>")
	)
	(segment
		(start 150.022814 -371.2083)
		(end 150.313644 -371.49913)
		(width 0.14224)
		(layer "In13.Cu")
		(net "P5E_CPU1_P2_TX_DN<5>")
	)
	(segment
		(start 117.714776 -273.276314)
		(end 117.416834 -273.276314)
		(width 0.1143)
		(layer "In13.Cu")
		(net "P5E_CPU1_P2_TX_DN<5>")
	)
	(segment
		(start 117.566694 -279.410922)
		(end 117.527578 -279.433782)
		(width 0.1143)
		(layer "In13.Cu")
		(net "P5E_CPU1_P2_TX_DN<5>")
	)
	(segment
		(start 117.810026 -295.141904)
		(end 117.810026 -295.146222)
		(width 0.1143)
		(layer "In13.Cu")
		(net "P5E_CPU1_P2_TX_DN<5>")
	)
	(segment
		(start 117.578886 -292.362382)
		(end 117.565932 -292.37178)
		(width 0.1143)
		(layer "In13.Cu")
		(net "P5E_CPU1_P2_TX_DN<5>")
	)
	(segment
		(start 117.416834 -273.276314)
		(end 117.346984 -273.346164)
		(width 0.1143)
		(layer "In13.Cu")
		(net "P5E_CPU1_P2_TX_DN<5>")
	)
	(segment
		(start 117.496082 -281.680666)
		(end 117.527832 -281.698954)
		(width 0.1143)
		(layer "In13.Cu")
		(net "P5E_CPU1_P2_TX_DN<5>")
	)
	(segment
		(start 117.497098 -278.44115)
		(end 117.527578 -278.45893)
		(width 0.1143)
		(layer "In13.Cu")
		(net "P5E_CPU1_P2_TX_DN<5>")
	)
	(segment
		(start 117.53088 -282.672028)
		(end 117.496082 -282.692094)
		(width 0.1143)
		(layer "In13.Cu")
		(net "P5E_CPU1_P2_TX_DN<5>")
	)
	(segment
		(start 118.000272 -295.470326)
		(end 118.001288 -295.470834)
		(width 0.1143)
		(layer "In13.Cu")
		(net "P5E_CPU1_P2_TX_DN<5>")
	)
	(segment
		(start 120.351804 -301.957994)
		(end 129.587752 -314.41136)
		(width 0.14224)
		(layer "In13.Cu")
		(net "P5E_CPU1_P2_TX_DN<5>")
	)
	(segment
		(start 117.527578 -277.81377)
		(end 117.497098 -277.83155)
		(width 0.1143)
		(layer "In13.Cu")
		(net "P5E_CPU1_P2_TX_DN<5>")
	)
	(segment
		(start 117.494304 -286.539178)
		(end 117.56898 -286.58312)
		(width 0.1143)
		(layer "In13.Cu")
		(net "P5E_CPU1_P2_TX_DN<5>")
	)
	(segment
		(start 117.527832 -283.318966)
		(end 117.53088 -283.320744)
		(width 0.1143)
		(layer "In13.Cu")
		(net "P5E_CPU1_P2_TX_DN<5>")
	)
	(segment
		(start 117.566694 -281.030934)
		(end 117.527578 -281.053794)
		(width 0.1143)
		(layer "In13.Cu")
		(net "P5E_CPU1_P2_TX_DN<5>")
	)
	(segment
		(start 117.527578 -279.433782)
		(end 117.497098 -279.451562)
		(width 0.1143)
		(layer "In13.Cu")
		(net "P5E_CPU1_P2_TX_DN<5>")
	)
	(segment
		(start 117.496082 -291.400484)
		(end 117.527832 -291.418772)
		(width 0.1143)
		(layer "In13.Cu")
		(net "P5E_CPU1_P2_TX_DN<5>")
	)
	(segment
		(start 117.565932 -291.440616)
		(end 117.578886 -291.450014)
		(width 0.1143)
		(layer "In13.Cu")
		(net "P5E_CPU1_P2_TX_DN<5>")
	)
	(segment
		(start 117.497098 -276.821138)
		(end 117.527578 -276.838918)
		(width 0.1143)
		(layer "In13.Cu")
		(net "P5E_CPU1_P2_TX_DN<5>")
	)
	(segment
		(start 118.28018 -295.956228)
		(end 118.28018 -296.2529)
		(width 0.1143)
		(layer "In13.Cu")
		(net "P5E_CPU1_P2_TX_DN<5>")
	)
	(segment
		(start 117.53088 -289.151822)
		(end 117.496082 -289.171888)
		(width 0.1143)
		(layer "In13.Cu")
		(net "P5E_CPU1_P2_TX_DN<5>")
	)
	(segment
		(start 117.497098 -275.201126)
		(end 117.527578 -275.218906)
		(width 0.1143)
		(layer "In13.Cu")
		(net "P5E_CPU1_P2_TX_DN<5>")
	)
	(segment
		(start 117.527832 -294.658796)
		(end 117.56771 -294.682418)
		(width 0.1143)
		(layer "In13.Cu")
		(net "P5E_CPU1_P2_TX_DN<5>")
	)
	(segment
		(start 117.527832 -284.938978)
		(end 117.53088 -284.940756)
		(width 0.1143)
		(layer "In13.Cu")
		(net "P5E_CPU1_P2_TX_DN<5>")
	)
	(segment
		(start 117.53088 -290.771834)
		(end 117.496082 -290.7919)
		(width 0.1143)
		(layer "In13.Cu")
		(net "P5E_CPU1_P2_TX_DN<5>")
	)
	(segment
		(start 117.579394 -287.501838)
		(end 117.567964 -287.510474)
		(width 0.1143)
		(layer "In13.Cu")
		(net "P5E_CPU1_P2_TX_DN<5>")
	)
	(segment
		(start 134.741158 -323.390768)
		(end 134.874508 -323.71284)
		(width 0.14224)
		(layer "In13.Cu")
		(net "P5E_CPU1_P2_TX_DN<5>")
	)
	(segment
		(start 118.3259 -297.719242)
		(end 119.476774 -300.49851)
		(width 0.14224)
		(layer "In13.Cu")
		(net "P5E_CPU1_P2_TX_DN<5>")
	)
	(segment
		(start 117.497098 -273.581114)
		(end 117.527578 -273.598894)
		(width 0.1143)
		(layer "In13.Cu")
		(net "P5E_CPU1_P2_TX_DN<5>")
	)
	(segment
		(start 117.527578 -280.078942)
		(end 117.566694 -280.101802)
		(width 0.1143)
		(layer "In13.Cu")
		(net "P5E_CPU1_P2_TX_DN<5>")
	)
	(segment
		(start 149.369272 -367.101628)
		(end 150.022814 -368.859816)
		(width 0.14224)
		(layer "In13.Cu")
		(net "P5E_CPU1_P2_TX_DN<5>")
	)
	(segment
		(start 117.497098 -280.061162)
		(end 117.527578 -280.078942)
		(width 0.1143)
		(layer "In13.Cu")
		(net "P5E_CPU1_P2_TX_DN<5>")
	)
	(segment
		(start 117.496082 -284.92069)
		(end 117.527832 -284.938978)
		(width 0.1143)
		(layer "In13.Cu")
		(net "P5E_CPU1_P2_TX_DN<5>")
	)
	(arc
		(start 117.496082 -294.031924)
		(mid 117.340154 -294.336216)
		(end 117.496082 -294.640508)
		(width 0.1143)
		(layer "In13.Cu")
		(net "P5E_CPU1_P2_TX_DN<5>")
	)
	(arc
		(start 117.566694 -280.101802)
		(mid 117.810021 -280.566368)
		(end 117.566694 -281.030934)
		(width 0.1143)
		(layer "In13.Cu")
		(net "P5E_CPU1_P2_TX_DN<5>")
	)
	(arc
		(start 117.578886 -291.450014)
		(mid 117.813313 -291.906198)
		(end 117.578886 -292.362382)
		(width 0.1143)
		(layer "In13.Cu")
		(net "P5E_CPU1_P2_TX_DN<5>")
	)
	(arc
		(start 117.566694 -278.48179)
		(mid 117.810021 -278.946356)
		(end 117.566694 -279.410922)
		(width 0.1143)
		(layer "In13.Cu")
		(net "P5E_CPU1_P2_TX_DN<5>")
	)
	(arc
		(start 117.53088 -284.940756)
		(mid 117.810495 -285.426404)
		(end 117.53088 -285.912052)
		(width 0.1143)
		(layer "In13.Cu")
		(net "P5E_CPU1_P2_TX_DN<5>")
	)
	(arc
		(start 117.497098 -276.211538)
		(mid 117.340121 -276.516338)
		(end 117.497098 -276.821138)
		(width 0.1143)
		(layer "In13.Cu")
		(net "P5E_CPU1_P2_TX_DN<5>")
	)
	(arc
		(start 117.497098 -279.451562)
		(mid 117.340121 -279.756362)
		(end 117.497098 -280.061162)
		(width 0.1143)
		(layer "In13.Cu")
		(net "P5E_CPU1_P2_TX_DN<5>")
	)
	(arc
		(start 117.53088 -283.320744)
		(mid 117.810495 -283.806392)
		(end 117.53088 -284.29204)
		(width 0.1143)
		(layer "In13.Cu")
		(net "P5E_CPU1_P2_TX_DN<5>")
	)
	(arc
		(start 117.497098 -277.83155)
		(mid 117.340121 -278.13635)
		(end 117.497098 -278.44115)
		(width 0.1143)
		(layer "In13.Cu")
		(net "P5E_CPU1_P2_TX_DN<5>")
	)
	(arc
		(start 117.496082 -282.692094)
		(mid 117.340154 -282.996386)
		(end 117.496082 -283.300678)
		(width 0.1143)
		(layer "In13.Cu")
		(net "P5E_CPU1_P2_TX_DN<5>")
	)
	(arc
		(start 117.810026 -287.050734)
		(mid 117.749027 -287.304058)
		(end 117.579394 -287.501838)
		(width 0.1143)
		(layer "In13.Cu")
		(net "P5E_CPU1_P2_TX_DN<5>")
	)
	(arc
		(start 117.497098 -274.591526)
		(mid 117.340121 -274.896326)
		(end 117.497098 -275.201126)
		(width 0.1143)
		(layer "In13.Cu")
		(net "P5E_CPU1_P2_TX_DN<5>")
	)
	(arc
		(start 117.496082 -287.55213)
		(mid 117.381406 -287.685464)
		(end 117.340126 -287.856422)
		(width 0.1143)
		(layer "In13.Cu")
		(net "P5E_CPU1_P2_TX_DN<5>")
	)
	(arc
		(start 117.53088 -288.180526)
		(mid 117.810495 -288.666174)
		(end 117.53088 -289.151822)
		(width 0.1143)
		(layer "In13.Cu")
		(net "P5E_CPU1_P2_TX_DN<5>")
	)
	(arc
		(start 117.53088 -293.040562)
		(mid 117.810495 -293.52621)
		(end 117.53088 -294.011858)
		(width 0.1143)
		(layer "In13.Cu")
		(net "P5E_CPU1_P2_TX_DN<5>")
	)
	(arc
		(start 117.340126 -286.23641)
		(mid 117.380888 -286.406294)
		(end 117.494304 -286.539178)
		(width 0.1143)
		(layer "In13.Cu")
		(net "P5E_CPU1_P2_TX_DN<5>")
	)
	(arc
		(start 118.036848 -295.491662)
		(mid 118.115271 -295.557143)
		(end 118.180612 -295.63568)
		(width 0.1143)
		(layer "In13.Cu")
		(net "P5E_CPU1_P2_TX_DN<5>")
	)
	(arc
		(start 117.53088 -281.700732)
		(mid 117.810495 -282.18638)
		(end 117.53088 -282.672028)
		(width 0.1143)
		(layer "In13.Cu")
		(net "P5E_CPU1_P2_TX_DN<5>")
	)
	(arc
		(start 117.810026 -295.146222)
		(mid 117.851281 -295.317193)
		(end 117.965982 -295.450514)
		(width 0.1143)
		(layer "In13.Cu")
		(net "P5E_CPU1_P2_TX_DN<5>")
	)
	(arc
		(start 118.180612 -295.63568)
		(mid 118.254726 -295.788394)
		(end 118.28018 -295.956228)
		(width 0.1143)
		(layer "In13.Cu")
		(net "P5E_CPU1_P2_TX_DN<5>")
	)
	(arc
		(start 117.346984 -273.346164)
		(mid 117.399401 -273.478095)
		(end 117.497098 -273.581114)
		(width 0.1143)
		(layer "In13.Cu")
		(net "P5E_CPU1_P2_TX_DN<5>")
	)
	(arc
		(start 117.53088 -289.800538)
		(mid 117.810495 -290.286186)
		(end 117.53088 -290.771834)
		(width 0.1143)
		(layer "In13.Cu")
		(net "P5E_CPU1_P2_TX_DN<5>")
	)
	(arc
		(start 117.496082 -290.7919)
		(mid 117.340154 -291.096192)
		(end 117.496082 -291.400484)
		(width 0.1143)
		(layer "In13.Cu")
		(net "P5E_CPU1_P2_TX_DN<5>")
	)
	(arc
		(start 117.56898 -286.58312)
		(mid 117.746176 -286.785132)
		(end 117.810026 -287.046162)
		(width 0.1143)
		(layer "In13.Cu")
		(net "P5E_CPU1_P2_TX_DN<5>")
	)
	(arc
		(start 117.496082 -284.312106)
		(mid 117.340154 -284.616398)
		(end 117.496082 -284.92069)
		(width 0.1143)
		(layer "In13.Cu")
		(net "P5E_CPU1_P2_TX_DN<5>")
	)
	(arc
		(start 117.496082 -285.932118)
		(mid 117.381406 -286.065452)
		(end 117.340126 -286.23641)
		(width 0.1143)
		(layer "In13.Cu")
		(net "P5E_CPU1_P2_TX_DN<5>")
	)
	(arc
		(start 117.496082 -281.072082)
		(mid 117.340154 -281.376374)
		(end 117.496082 -281.680666)
		(width 0.1143)
		(layer "In13.Cu")
		(net "P5E_CPU1_P2_TX_DN<5>")
	)
	(arc
		(start 117.340126 -287.856422)
		(mid 117.380888 -288.026306)
		(end 117.494304 -288.15919)
		(width 0.1143)
		(layer "In13.Cu")
		(net "P5E_CPU1_P2_TX_DN<5>")
	)
	(arc
		(start 117.496082 -292.411912)
		(mid 117.340154 -292.716204)
		(end 117.496082 -293.020496)
		(width 0.1143)
		(layer "In13.Cu")
		(net "P5E_CPU1_P2_TX_DN<5>")
	)
	(arc
		(start 117.56771 -294.682418)
		(mid 117.745746 -294.882168)
		(end 117.810026 -295.141904)
		(width 0.1143)
		(layer "In13.Cu")
		(net "P5E_CPU1_P2_TX_DN<5>")
	)
	(arc
		(start 117.566694 -275.241766)
		(mid 117.810021 -275.706332)
		(end 117.566694 -276.170898)
		(width 0.1143)
		(layer "In13.Cu")
		(net "P5E_CPU1_P2_TX_DN<5>")
	)
	(arc
		(start 117.496082 -289.171888)
		(mid 117.340154 -289.47618)
		(end 117.496082 -289.780472)
		(width 0.1143)
		(layer "In13.Cu")
		(net "P5E_CPU1_P2_TX_DN<5>")
	)
	(arc
		(start 117.566694 -273.621754)
		(mid 117.810021 -274.08632)
		(end 117.566694 -274.550886)
		(width 0.1143)
		(layer "In13.Cu")
		(net "P5E_CPU1_P2_TX_DN<5>")
	)
	(arc
		(start 117.566694 -276.861778)
		(mid 117.810021 -277.326344)
		(end 117.566694 -277.79091)
		(width 0.1143)
		(layer "In13.Cu")
		(net "P5E_CPU1_P2_TX_DN<5>")
	)
	(segment
		(start 117.247924 -269.770352)
		(end 117.714776 -270.03629)
		(width 0.12954)
		(layer "F.Cu")
		(net "P5E_CPU1_P2_TX_DN<4>")
	)
	(segment
		(start 148.341334 -374.23344)
		(end 148.341334 -374.93702)
		(width 0.12954)
		(layer "F.Cu")
		(net "P5E_CPU1_P2_TX_DN<4>")
	)
	(segment
		(start 148.341334 -374.93702)
		(end 148.637244 -375.23293)
		(width 0.12954)
		(layer "F.Cu")
		(net "P5E_CPU1_P2_TX_DN<4>")
	)
	(segment
		(start 148.611844 -373.96293)
		(end 148.341334 -374.23344)
		(width 0.12954)
		(layer "F.Cu")
		(net "P5E_CPU1_P2_TX_DN<4>")
	)
	(segment
		(start 146.647154 -369.560348)
		(end 146.816826 -369.83289)
		(width 0.14224)
		(layer "In13.Cu")
		(net "P5E_CPU1_P2_TX_DN<4>")
	)
	(segment
		(start 116.59997 -284.28696)
		(end 116.596922 -284.288738)
		(width 0.1143)
		(layer "In13.Cu")
		(net "P5E_CPU1_P2_TX_DN<4>")
	)
	(segment
		(start 146.612864 -368.808508)
		(end 146.612864 -369.440206)
		(width 0.14224)
		(layer "In13.Cu")
		(net "P5E_CPU1_P2_TX_DN<4>")
	)
	(segment
		(start 116.62664 -276.861524)
		(end 116.65458 -276.88159)
		(width 0.1143)
		(layer "In13.Cu")
		(net "P5E_CPU1_P2_TX_DN<4>")
	)
	(segment
		(start 116.604034 -284.28442)
		(end 116.603272 -284.284928)
		(width 0.1143)
		(layer "In13.Cu")
		(net "P5E_CPU1_P2_TX_DN<4>")
	)
	(segment
		(start 116.55425 -288.15919)
		(end 116.587778 -288.178748)
		(width 0.1143)
		(layer "In13.Cu")
		(net "P5E_CPU1_P2_TX_DN<4>")
	)
	(segment
		(start 116.587778 -284.938978)
		(end 116.6241 -284.96006)
		(width 0.1143)
		(layer "In13.Cu")
		(net "P5E_CPU1_P2_TX_DN<4>")
	)
	(segment
		(start 116.587016 -285.914338)
		(end 116.585746 -285.9151)
		(width 0.1143)
		(layer "In13.Cu")
		(net "P5E_CPU1_P2_TX_DN<4>")
	)
	(segment
		(start 116.646706 -287.492948)
		(end 116.623084 -287.51276)
		(width 0.1143)
		(layer "In13.Cu")
		(net "P5E_CPU1_P2_TX_DN<4>")
	)
	(segment
		(start 116.590572 -280.08072)
		(end 116.62664 -280.101548)
		(width 0.1143)
		(layer "In13.Cu")
		(net "P5E_CPU1_P2_TX_DN<4>")
	)
	(segment
		(start 116.587016 -279.43429)
		(end 116.585746 -279.435052)
		(width 0.1143)
		(layer "In13.Cu")
		(net "P5E_CPU1_P2_TX_DN<4>")
	)
	(segment
		(start 116.6241 -272.932652)
		(end 116.587778 -272.953734)
		(width 0.1143)
		(layer "In13.Cu")
		(net "P5E_CPU1_P2_TX_DN<4>")
	)
	(segment
		(start 116.58473 -284.9372)
		(end 116.587778 -284.938978)
		(width 0.1143)
		(layer "In13.Cu")
		(net "P5E_CPU1_P2_TX_DN<4>")
	)
	(segment
		(start 117.096794 -270.500856)
		(end 117.047264 -270.529558)
		(width 0.1143)
		(layer "In13.Cu")
		(net "P5E_CPU1_P2_TX_DN<4>")
	)
	(segment
		(start 116.587778 -276.838918)
		(end 116.590572 -276.840696)
		(width 0.1143)
		(layer "In13.Cu")
		(net "P5E_CPU1_P2_TX_DN<4>")
	)
	(segment
		(start 116.587016 -294.658288)
		(end 116.587778 -294.658796)
		(width 0.1143)
		(layer "In13.Cu")
		(net "P5E_CPU1_P2_TX_DN<4>")
	)
	(segment
		(start 116.577364 -284.933136)
		(end 116.580412 -284.934914)
		(width 0.1143)
		(layer "In13.Cu")
		(net "P5E_CPU1_P2_TX_DN<4>")
	)
	(segment
		(start 116.556028 -293.020496)
		(end 116.587016 -293.038276)
		(width 0.1143)
		(layer "In13.Cu")
		(net "P5E_CPU1_P2_TX_DN<4>")
	)
	(segment
		(start 116.601494 -284.285944)
		(end 116.59997 -284.28696)
		(width 0.1143)
		(layer "In13.Cu")
		(net "P5E_CPU1_P2_TX_DN<4>")
	)
	(segment
		(start 116.593366 -271.330166)
		(end 116.592858 -271.330674)
		(width 0.1143)
		(layer "In13.Cu")
		(net "P5E_CPU1_P2_TX_DN<4>")
	)
	(segment
		(start 116.587016 -283.318712)
		(end 116.587016 -283.318458)
		(width 0.1143)
		(layer "In13.Cu")
		(net "P5E_CPU1_P2_TX_DN<4>")
	)
	(segment
		(start 116.587778 -290.773612)
		(end 116.587016 -290.77412)
		(width 0.1143)
		(layer "In13.Cu")
		(net "P5E_CPU1_P2_TX_DN<4>")
	)
	(segment
		(start 117.340126 -295.956228)
		(end 117.340126 -296.2529)
		(width 0.1143)
		(layer "In13.Cu")
		(net "P5E_CPU1_P2_TX_DN<4>")
	)
	(segment
		(start 148.321014 -373.6721)
		(end 148.611844 -373.96293)
		(width 0.14224)
		(layer "In13.Cu")
		(net "P5E_CPU1_P2_TX_DN<4>")
	)
	(segment
		(start 116.587016 -289.798252)
		(end 116.587778 -289.79876)
		(width 0.1143)
		(layer "In13.Cu")
		(net "P5E_CPU1_P2_TX_DN<4>")
	)
	(segment
		(start 116.587778 -281.698954)
		(end 116.590826 -281.700732)
		(width 0.1143)
		(layer "In13.Cu")
		(net "P5E_CPU1_P2_TX_DN<4>")
	)
	(segment
		(start 116.587778 -276.193758)
		(end 116.587016 -276.194266)
		(width 0.1143)
		(layer "In13.Cu")
		(net "P5E_CPU1_P2_TX_DN<4>")
	)
	(segment
		(start 116.582952 -294.656256)
		(end 116.585492 -294.65778)
		(width 0.1143)
		(layer "In13.Cu")
		(net "P5E_CPU1_P2_TX_DN<4>")
	)
	(segment
		(start 116.587016 -281.698446)
		(end 116.587778 -281.698954)
		(width 0.1143)
		(layer "In13.Cu")
		(net "P5E_CPU1_P2_TX_DN<4>")
	)
	(segment
		(start 117.025928 -295.450514)
		(end 117.096794 -295.491662)
		(width 0.1143)
		(layer "In13.Cu")
		(net "P5E_CPU1_P2_TX_DN<4>")
	)
	(segment
		(start 116.587778 -273.598894)
		(end 116.6241 -273.619976)
		(width 0.1143)
		(layer "In13.Cu")
		(net "P5E_CPU1_P2_TX_DN<4>")
	)
	(segment
		(start 116.571268 -287.543494)
		(end 116.56949 -287.54451)
		(width 0.1143)
		(layer "In13.Cu")
		(net "P5E_CPU1_P2_TX_DN<4>")
	)
	(segment
		(start 116.587016 -293.038276)
		(end 116.587778 -293.038784)
		(width 0.1143)
		(layer "In13.Cu")
		(net "P5E_CPU1_P2_TX_DN<4>")
	)
	(segment
		(start 116.587778 -274.573746)
		(end 116.587016 -274.574254)
		(width 0.1143)
		(layer "In13.Cu")
		(net "P5E_CPU1_P2_TX_DN<4>")
	)
	(segment
		(start 116.6241 -274.552664)
		(end 116.587778 -274.573746)
		(width 0.1143)
		(layer "In13.Cu")
		(net "P5E_CPU1_P2_TX_DN<4>")
	)
	(segment
		(start 118.632478 -300.90491)
		(end 119.575326 -302.478186)
		(width 0.14224)
		(layer "In13.Cu")
		(net "P5E_CPU1_P2_TX_DN<4>")
	)
	(segment
		(start 146.909536 -369.916456)
		(end 147.398232 -370.15547)
		(width 0.14224)
		(layer "In13.Cu")
		(net "P5E_CPU1_P2_TX_DN<4>")
	)
	(segment
		(start 116.86032 -270.853916)
		(end 116.86032 -270.862298)
		(width 0.1143)
		(layer "In13.Cu")
		(net "P5E_CPU1_P2_TX_DN<4>")
	)
	(segment
		(start 116.580666 -283.314902)
		(end 116.581936 -283.315664)
		(width 0.1143)
		(layer "In13.Cu")
		(net "P5E_CPU1_P2_TX_DN<4>")
	)
	(segment
		(start 116.58219 -284.935676)
		(end 116.58473 -284.9372)
		(width 0.1143)
		(layer "In13.Cu")
		(net "P5E_CPU1_P2_TX_DN<4>")
	)
	(segment
		(start 117.416834 -270.03629)
		(end 117.33403 -270.119094)
		(width 0.1143)
		(layer "In13.Cu")
		(net "P5E_CPU1_P2_TX_DN<4>")
	)
	(segment
		(start 117.385846 -296.327068)
		(end 117.385846 -297.895518)
		(width 0.14224)
		(layer "In13.Cu")
		(net "P5E_CPU1_P2_TX_DN<4>")
	)
	(segment
		(start 116.590826 -282.672028)
		(end 116.587778 -282.673806)
		(width 0.1143)
		(layer "In13.Cu")
		(net "P5E_CPU1_P2_TX_DN<4>")
	)
	(segment
		(start 116.587016 -289.154108)
		(end 116.585746 -289.15487)
		(width 0.1143)
		(layer "In13.Cu")
		(net "P5E_CPU1_P2_TX_DN<4>")
	)
	(segment
		(start 116.605304 -283.329126)
		(end 116.606066 -283.329634)
		(width 0.1143)
		(layer "In13.Cu")
		(net "P5E_CPU1_P2_TX_DN<4>")
	)
	(segment
		(start 116.587016 -276.83841)
		(end 116.587778 -276.838918)
		(width 0.1143)
		(layer "In13.Cu")
		(net "P5E_CPU1_P2_TX_DN<4>")
	)
	(segment
		(start 116.587778 -272.953734)
		(end 116.587016 -272.954242)
		(width 0.1143)
		(layer "In13.Cu")
		(net "P5E_CPU1_P2_TX_DN<4>")
	)
	(segment
		(start 116.556028 -273.580606)
		(end 116.587016 -273.598386)
		(width 0.1143)
		(layer "In13.Cu")
		(net "P5E_CPU1_P2_TX_DN<4>")
	)
	(segment
		(start 116.6241 -285.892748)
		(end 116.587778 -285.91383)
		(width 0.1143)
		(layer "In13.Cu")
		(net "P5E_CPU1_P2_TX_DN<4>")
	)
	(segment
		(start 116.556028 -278.440642)
		(end 116.587778 -278.45893)
		(width 0.1143)
		(layer "In13.Cu")
		(net "P5E_CPU1_P2_TX_DN<4>")
	)
	(segment
		(start 116.587016 -273.598386)
		(end 116.587778 -273.598894)
		(width 0.1143)
		(layer "In13.Cu")
		(net "P5E_CPU1_P2_TX_DN<4>")
	)
	(segment
		(start 116.587778 -278.45893)
		(end 116.6241 -278.480012)
		(width 0.1143)
		(layer "In13.Cu")
		(net "P5E_CPU1_P2_TX_DN<4>")
	)
	(segment
		(start 116.606066 -284.28315)
		(end 116.604034 -284.28442)
		(width 0.1143)
		(layer "In13.Cu")
		(net "P5E_CPU1_P2_TX_DN<4>")
	)
	(segment
		(start 148.321014 -371.414802)
		(end 148.321014 -373.6721)
		(width 0.14224)
		(layer "In13.Cu")
		(net "P5E_CPU1_P2_TX_DN<4>")
	)
	(segment
		(start 116.62664 -277.791164)
		(end 116.589302 -277.812754)
		(width 0.1143)
		(layer "In13.Cu")
		(net "P5E_CPU1_P2_TX_DN<4>")
	)
	(segment
		(start 116.6241 -279.4127)
		(end 116.587778 -279.433782)
		(width 0.1143)
		(layer "In13.Cu")
		(net "P5E_CPU1_P2_TX_DN<4>")
	)
	(segment
		(start 116.556028 -271.960594)
		(end 116.587016 -271.978374)
		(width 0.1143)
		(layer "In13.Cu")
		(net "P5E_CPU1_P2_TX_DN<4>")
	)
	(segment
		(start 116.587778 -292.393624)
		(end 116.587016 -292.394132)
		(width 0.1143)
		(layer "In13.Cu")
		(net "P5E_CPU1_P2_TX_DN<4>")
	)
	(segment
		(start 147.853908 -370.393976)
		(end 147.9423 -370.469668)
		(width 0.14224)
		(layer "In13.Cu")
		(net "P5E_CPU1_P2_TX_DN<4>")
	)
	(segment
		(start 128.792986 -314.906406)
		(end 130.165094 -316.96025)
		(width 0.14224)
		(layer "In13.Cu")
		(net "P5E_CPU1_P2_TX_DN<4>")
	)
	(segment
		(start 116.587016 -294.014144)
		(end 116.584222 -294.015668)
		(width 0.1143)
		(layer "In13.Cu")
		(net "P5E_CPU1_P2_TX_DN<4>")
	)
	(segment
		(start 116.592858 -271.330674)
		(end 116.557552 -271.351248)
		(width 0.1143)
		(layer "In13.Cu")
		(net "P5E_CPU1_P2_TX_DN<4>")
	)
	(segment
		(start 116.596922 -284.288738)
		(end 116.59616 -284.289246)
		(width 0.1143)
		(layer "In13.Cu")
		(net "P5E_CPU1_P2_TX_DN<4>")
	)
	(segment
		(start 130.165094 -316.96025)
		(end 134.011924 -324.156578)
		(width 0.14224)
		(layer "In13.Cu")
		(net "P5E_CPU1_P2_TX_DN<4>")
	)
	(segment
		(start 116.556028 -280.060654)
		(end 116.587016 -280.078434)
		(width 0.1143)
		(layer "In13.Cu")
		(net "P5E_CPU1_P2_TX_DN<4>")
	)
	(segment
		(start 116.56949 -287.54451)
		(end 116.567458 -287.54578)
		(width 0.1143)
		(layer "In13.Cu")
		(net "P5E_CPU1_P2_TX_DN<4>")
	)
	(segment
		(start 116.587778 -294.658796)
		(end 116.615718 -294.67683)
		(width 0.1143)
		(layer "In13.Cu")
		(net "P5E_CPU1_P2_TX_DN<4>")
	)
	(segment
		(start 116.587016 -272.954242)
		(end 116.585746 -272.955004)
		(width 0.1143)
		(layer "In13.Cu")
		(net "P5E_CPU1_P2_TX_DN<4>")
	)
	(segment
		(start 139.328652 -350.884236)
		(end 145.788126 -365.458502)
		(width 0.14224)
		(layer "In13.Cu")
		(net "P5E_CPU1_P2_TX_DN<4>")
	)
	(segment
		(start 116.587016 -283.318458)
		(end 116.58854 -283.319474)
		(width 0.1143)
		(layer "In13.Cu")
		(net "P5E_CPU1_P2_TX_DN<4>")
	)
	(segment
		(start 116.581174 -282.677362)
		(end 116.567712 -282.685236)
		(width 0.1143)
		(layer "In13.Cu")
		(net "P5E_CPU1_P2_TX_DN<4>")
	)
	(segment
		(start 116.581936 -283.315664)
		(end 116.58346 -283.316426)
		(width 0.1143)
		(layer "In13.Cu")
		(net "P5E_CPU1_P2_TX_DN<4>")
	)
	(segment
		(start 116.556028 -291.400484)
		(end 116.587016 -291.418264)
		(width 0.1143)
		(layer "In13.Cu")
		(net "P5E_CPU1_P2_TX_DN<4>")
	)
	(segment
		(start 116.58346 -283.316426)
		(end 116.584222 -283.316934)
		(width 0.1143)
		(layer "In13.Cu")
		(net "P5E_CPU1_P2_TX_DN<4>")
	)
	(segment
		(start 116.585746 -272.955004)
		(end 116.556028 -272.972022)
		(width 0.1143)
		(layer "In13.Cu")
		(net "P5E_CPU1_P2_TX_DN<4>")
	)
	(segment
		(start 116.587016 -276.194266)
		(end 116.585746 -276.195028)
		(width 0.1143)
		(layer "In13.Cu")
		(net "P5E_CPU1_P2_TX_DN<4>")
	)
	(segment
		(start 116.62664 -280.101548)
		(end 116.65458 -280.121614)
		(width 0.1143)
		(layer "In13.Cu")
		(net "P5E_CPU1_P2_TX_DN<4>")
	)
	(segment
		(start 116.58854 -283.319474)
		(end 116.605304 -283.329126)
		(width 0.1143)
		(layer "In13.Cu")
		(net "P5E_CPU1_P2_TX_DN<4>")
	)
	(segment
		(start 116.585746 -277.81504)
		(end 116.556028 -277.832058)
		(width 0.1143)
		(layer "In13.Cu")
		(net "P5E_CPU1_P2_TX_DN<4>")
	)
	(segment
		(start 117.340126 -296.2529)
		(end 117.385846 -296.29862)
		(width 0.1143)
		(layer "In13.Cu")
		(net "P5E_CPU1_P2_TX_DN<4>")
	)
	(segment
		(start 116.65458 -277.771098)
		(end 116.62664 -277.791164)
		(width 0.1143)
		(layer "In13.Cu")
		(net "P5E_CPU1_P2_TX_DN<4>")
	)
	(segment
		(start 116.567458 -287.54578)
		(end 116.556028 -287.55213)
		(width 0.1143)
		(layer "In13.Cu")
		(net "P5E_CPU1_P2_TX_DN<4>")
	)
	(segment
		(start 116.869972 -287.043876)
		(end 116.867686 -287.068006)
		(width 0.1143)
		(layer "In13.Cu")
		(net "P5E_CPU1_P2_TX_DN<4>")
	)
	(segment
		(start 116.65458 -281.011122)
		(end 116.626894 -281.031188)
		(width 0.1143)
		(layer "In13.Cu")
		(net "P5E_CPU1_P2_TX_DN<4>")
	)
	(segment
		(start 116.556028 -281.680666)
		(end 116.587016 -281.698446)
		(width 0.1143)
		(layer "In13.Cu")
		(net "P5E_CPU1_P2_TX_DN<4>")
	)
	(segment
		(start 116.585746 -276.195028)
		(end 116.556028 -276.212046)
		(width 0.1143)
		(layer "In13.Cu")
		(net "P5E_CPU1_P2_TX_DN<4>")
	)
	(segment
		(start 145.829274 -365.578136)
		(end 146.588988 -368.615214)
		(width 0.14224)
		(layer "In13.Cu")
		(net "P5E_CPU1_P2_TX_DN<4>")
	)
	(segment
		(start 116.587778 -279.433782)
		(end 116.587016 -279.43429)
		(width 0.1143)
		(layer "In13.Cu")
		(net "P5E_CPU1_P2_TX_DN<4>")
	)
	(segment
		(start 116.587016 -277.814278)
		(end 116.585746 -277.81504)
		(width 0.1143)
		(layer "In13.Cu")
		(net "P5E_CPU1_P2_TX_DN<4>")
	)
	(segment
		(start 116.6241 -276.172676)
		(end 116.587778 -276.193758)
		(width 0.1143)
		(layer "In13.Cu")
		(net "P5E_CPU1_P2_TX_DN<4>")
	)
	(segment
		(start 116.556028 -276.82063)
		(end 116.587016 -276.83841)
		(width 0.1143)
		(layer "In13.Cu")
		(net "P5E_CPU1_P2_TX_DN<4>")
	)
	(segment
		(start 116.57203 -287.542732)
		(end 116.571268 -287.54324)
		(width 0.1143)
		(layer "In13.Cu")
		(net "P5E_CPU1_P2_TX_DN<4>")
	)
	(segment
		(start 116.587016 -292.394132)
		(end 116.585746 -292.394894)
		(width 0.1143)
		(layer "In13.Cu")
		(net "P5E_CPU1_P2_TX_DN<4>")
	)
	(segment
		(start 116.585746 -285.9151)
		(end 116.556028 -285.932118)
		(width 0.1143)
		(layer "In13.Cu")
		(net "P5E_CPU1_P2_TX_DN<4>")
	)
	(segment
		(start 117.047264 -270.529558)
		(end 117.04701 -270.529812)
		(width 0.1143)
		(layer "In13.Cu")
		(net "P5E_CPU1_P2_TX_DN<4>")
	)
	(segment
		(start 116.603272 -284.284928)
		(end 116.601494 -284.285944)
		(width 0.1143)
		(layer "In13.Cu")
		(net "P5E_CPU1_P2_TX_DN<4>")
	)
	(segment
		(start 116.583968 -282.675838)
		(end 116.581174 -282.677362)
		(width 0.1143)
		(layer "In13.Cu")
		(net "P5E_CPU1_P2_TX_DN<4>")
	)
	(segment
		(start 134.011924 -324.156578)
		(end 139.328652 -350.884236)
		(width 0.14224)
		(layer "In13.Cu")
		(net "P5E_CPU1_P2_TX_DN<4>")
	)
	(segment
		(start 116.585492 -294.65778)
		(end 116.585746 -294.657526)
		(width 0.1143)
		(layer "In13.Cu")
		(net "P5E_CPU1_P2_TX_DN<4>")
	)
	(segment
		(start 119.575326 -302.478186)
		(end 128.792986 -314.906406)
		(width 0.14224)
		(layer "In13.Cu")
		(net "P5E_CPU1_P2_TX_DN<4>")
	)
	(segment
		(start 116.557552 -271.351248)
		(end 116.556028 -271.35201)
		(width 0.1143)
		(layer "In13.Cu")
		(net "P5E_CPU1_P2_TX_DN<4>")
	)
	(segment
		(start 117.385846 -296.29862)
		(end 117.385846 -296.327068)
		(width 0.1143)
		(layer "In13.Cu")
		(net "P5E_CPU1_P2_TX_DN<4>")
	)
	(segment
		(start 116.587778 -275.218906)
		(end 116.6241 -275.239988)
		(width 0.1143)
		(layer "In13.Cu")
		(net "P5E_CPU1_P2_TX_DN<4>")
	)
	(segment
		(start 116.587016 -291.418264)
		(end 116.587778 -291.418772)
		(width 0.1143)
		(layer "In13.Cu")
		(net "P5E_CPU1_P2_TX_DN<4>")
	)
	(segment
		(start 116.585746 -279.435052)
		(end 116.556028 -279.45207)
		(width 0.1143)
		(layer "In13.Cu")
		(net "P5E_CPU1_P2_TX_DN<4>")
	)
	(segment
		(start 116.59616 -284.289246)
		(end 116.587778 -284.293818)
		(width 0.1143)
		(layer "In13.Cu")
		(net "P5E_CPU1_P2_TX_DN<4>")
	)
	(segment
		(start 116.587778 -284.293818)
		(end 116.584476 -284.295596)
		(width 0.1143)
		(layer "In13.Cu")
		(net "P5E_CPU1_P2_TX_DN<4>")
	)
	(segment
		(start 116.585746 -294.657526)
		(end 116.587016 -294.658288)
		(width 0.1143)
		(layer "In13.Cu")
		(net "P5E_CPU1_P2_TX_DN<4>")
	)
	(segment
		(start 116.623084 -287.51276)
		(end 116.57203 -287.542732)
		(width 0.1143)
		(layer "In13.Cu")
		(net "P5E_CPU1_P2_TX_DN<4>")
	)
	(segment
		(start 116.587778 -285.91383)
		(end 116.587016 -285.914338)
		(width 0.1143)
		(layer "In13.Cu")
		(net "P5E_CPU1_P2_TX_DN<4>")
	)
	(segment
		(start 116.585746 -292.394894)
		(end 116.556028 -292.411912)
		(width 0.1143)
		(layer "In13.Cu")
		(net "P5E_CPU1_P2_TX_DN<4>")
	)
	(segment
		(start 116.587016 -280.078434)
		(end 116.587778 -280.078942)
		(width 0.1143)
		(layer "In13.Cu")
		(net "P5E_CPU1_P2_TX_DN<4>")
	)
	(segment
		(start 116.587778 -294.013636)
		(end 116.587016 -294.014144)
		(width 0.1143)
		(layer "In13.Cu")
		(net "P5E_CPU1_P2_TX_DN<4>")
	)
	(segment
		(start 116.586254 -283.318204)
		(end 116.587016 -283.318712)
		(width 0.1143)
		(layer "In13.Cu")
		(net "P5E_CPU1_P2_TX_DN<4>")
	)
	(segment
		(start 116.587778 -282.673806)
		(end 116.587524 -282.67406)
		(width 0.1143)
		(layer "In13.Cu")
		(net "P5E_CPU1_P2_TX_DN<4>")
	)
	(segment
		(start 116.585746 -289.15487)
		(end 116.556028 -289.171888)
		(width 0.1143)
		(layer "In13.Cu")
		(net "P5E_CPU1_P2_TX_DN<4>")
	)
	(segment
		(start 116.587016 -275.218398)
		(end 116.587778 -275.218906)
		(width 0.1143)
		(layer "In13.Cu")
		(net "P5E_CPU1_P2_TX_DN<4>")
	)
	(segment
		(start 116.587016 -290.77412)
		(end 116.585746 -290.774882)
		(width 0.1143)
		(layer "In13.Cu")
		(net "P5E_CPU1_P2_TX_DN<4>")
	)
	(segment
		(start 116.58854 -289.153092)
		(end 116.587016 -289.154108)
		(width 0.1143)
		(layer "In13.Cu")
		(net "P5E_CPU1_P2_TX_DN<4>")
	)
	(segment
		(start 117.385846 -297.895518)
		(end 118.632478 -300.90491)
		(width 0.14224)
		(layer "In13.Cu")
		(net "P5E_CPU1_P2_TX_DN<4>")
	)
	(segment
		(start 116.587016 -271.978374)
		(end 116.587778 -271.978882)
		(width 0.1143)
		(layer "In13.Cu")
		(net "P5E_CPU1_P2_TX_DN<4>")
	)
	(segment
		(start 116.587778 -271.978882)
		(end 116.6241 -271.999964)
		(width 0.1143)
		(layer "In13.Cu")
		(net "P5E_CPU1_P2_TX_DN<4>")
	)
	(segment
		(start 116.626894 -281.031188)
		(end 116.556028 -281.072082)
		(width 0.1143)
		(layer "In13.Cu")
		(net "P5E_CPU1_P2_TX_DN<4>")
	)
	(segment
		(start 116.556028 -289.780472)
		(end 116.587016 -289.798252)
		(width 0.1143)
		(layer "In13.Cu")
		(net "P5E_CPU1_P2_TX_DN<4>")
	)
	(segment
		(start 116.587778 -288.178748)
		(end 116.58854 -288.179256)
		(width 0.1143)
		(layer "In13.Cu")
		(net "P5E_CPU1_P2_TX_DN<4>")
	)
	(segment
		(start 116.587524 -282.67406)
		(end 116.583968 -282.675838)
		(width 0.1143)
		(layer "In13.Cu")
		(net "P5E_CPU1_P2_TX_DN<4>")
	)
	(segment
		(start 116.587016 -274.574254)
		(end 116.585746 -274.575016)
		(width 0.1143)
		(layer "In13.Cu")
		(net "P5E_CPU1_P2_TX_DN<4>")
	)
	(segment
		(start 116.566696 -283.307028)
		(end 116.580666 -283.314902)
		(width 0.1143)
		(layer "In13.Cu")
		(net "P5E_CPU1_P2_TX_DN<4>")
	)
	(segment
		(start 117.714776 -270.03629)
		(end 117.416834 -270.03629)
		(width 0.1143)
		(layer "In13.Cu")
		(net "P5E_CPU1_P2_TX_DN<4>")
	)
	(segment
		(start 116.580412 -284.934914)
		(end 116.58219 -284.935676)
		(width 0.1143)
		(layer "In13.Cu")
		(net "P5E_CPU1_P2_TX_DN<4>")
	)
	(segment
		(start 116.584222 -283.316934)
		(end 116.586254 -283.318204)
		(width 0.1143)
		(layer "In13.Cu")
		(net "P5E_CPU1_P2_TX_DN<4>")
	)
	(segment
		(start 116.585746 -274.575016)
		(end 116.556028 -274.592034)
		(width 0.1143)
		(layer "In13.Cu")
		(net "P5E_CPU1_P2_TX_DN<4>")
	)
	(segment
		(start 116.590572 -276.840696)
		(end 116.62664 -276.861524)
		(width 0.1143)
		(layer "In13.Cu")
		(net "P5E_CPU1_P2_TX_DN<4>")
	)
	(segment
		(start 116.585746 -290.774882)
		(end 116.556028 -290.7919)
		(width 0.1143)
		(layer "In13.Cu")
		(net "P5E_CPU1_P2_TX_DN<4>")
	)
	(segment
		(start 116.556028 -275.200618)
		(end 116.587016 -275.218398)
		(width 0.1143)
		(layer "In13.Cu")
		(net "P5E_CPU1_P2_TX_DN<4>")
	)
	(segment
		(start 116.587778 -280.078942)
		(end 116.590572 -280.08072)
		(width 0.1143)
		(layer "In13.Cu")
		(net "P5E_CPU1_P2_TX_DN<4>")
	)
	(segment
		(start 116.55425 -286.539178)
		(end 116.624862 -286.580072)
		(width 0.1143)
		(layer "In13.Cu")
		(net "P5E_CPU1_P2_TX_DN<4>")
	)
	(segment
		(start 116.589302 -277.812754)
		(end 116.587016 -277.814278)
		(width 0.1143)
		(layer "In13.Cu")
		(net "P5E_CPU1_P2_TX_DN<4>")
	)
	(segment
		(start 116.571268 -287.54324)
		(end 116.571268 -287.543494)
		(width 0.1143)
		(layer "In13.Cu")
		(net "P5E_CPU1_P2_TX_DN<4>")
	)
	(arc
		(start 116.63934 -279.402032)
		(mid 116.631764 -279.407428)
		(end 116.6241 -279.4127)
		(width 0.1143)
		(layer "In13.Cu")
		(net "P5E_CPU1_P2_TX_DN<4>")
	)
	(arc
		(start 116.556028 -274.592034)
		(mid 116.4001 -274.896326)
		(end 116.556028 -275.200618)
		(width 0.1143)
		(layer "In13.Cu")
		(net "P5E_CPU1_P2_TX_DN<4>")
	)
	(arc
		(start 147.529296 -370.209318)
		(mid 147.700453 -370.28609)
		(end 147.853908 -370.393976)
		(width 0.14224)
		(layer "In13.Cu")
		(net "P5E_CPU1_P2_TX_DN<4>")
	)
	(arc
		(start 146.816826 -369.83289)
		(mid 146.857315 -369.881179)
		(end 146.909536 -369.916456)
		(width 0.14224)
		(layer "In13.Cu")
		(net "P5E_CPU1_P2_TX_DN<4>")
	)
	(arc
		(start 116.587778 -293.038784)
		(mid 116.868425 -293.52621)
		(end 116.587778 -294.013636)
		(width 0.1143)
		(layer "In13.Cu")
		(net "P5E_CPU1_P2_TX_DN<4>")
	)
	(arc
		(start 116.556028 -271.35201)
		(mid 116.4001 -271.656302)
		(end 116.556028 -271.960594)
		(width 0.1143)
		(layer "In13.Cu")
		(net "P5E_CPU1_P2_TX_DN<4>")
	)
	(arc
		(start 116.556028 -277.832058)
		(mid 116.4001 -278.13635)
		(end 116.556028 -278.440642)
		(width 0.1143)
		(layer "In13.Cu")
		(net "P5E_CPU1_P2_TX_DN<4>")
	)
	(arc
		(start 116.615718 -294.67683)
		(mid 116.802354 -294.879298)
		(end 116.869972 -295.146222)
		(width 0.1143)
		(layer "In13.Cu")
		(net "P5E_CPU1_P2_TX_DN<4>")
	)
	(arc
		(start 116.567712 -282.685236)
		(mid 116.389176 -282.995819)
		(end 116.566696 -283.307028)
		(width 0.1143)
		(layer "In13.Cu")
		(net "P5E_CPU1_P2_TX_DN<4>")
	)
	(arc
		(start 116.556028 -276.212046)
		(mid 116.4001 -276.516338)
		(end 116.556028 -276.82063)
		(width 0.1143)
		(layer "In13.Cu")
		(net "P5E_CPU1_P2_TX_DN<4>")
	)
	(arc
		(start 116.587778 -291.418772)
		(mid 116.868425 -291.906198)
		(end 116.587778 -292.393624)
		(width 0.1143)
		(layer "In13.Cu")
		(net "P5E_CPU1_P2_TX_DN<4>")
	)
	(arc
		(start 116.638324 -275.249894)
		(mid 116.865707 -275.706332)
		(end 116.638324 -276.16277)
		(width 0.1143)
		(layer "In13.Cu")
		(net "P5E_CPU1_P2_TX_DN<4>")
	)
	(arc
		(start 116.63934 -284.970728)
		(mid 116.864511 -285.426404)
		(end 116.63934 -285.88208)
		(width 0.1143)
		(layer "In13.Cu")
		(net "P5E_CPU1_P2_TX_DN<4>")
	)
	(arc
		(start 116.638324 -276.16277)
		(mid 116.63125 -276.167777)
		(end 116.6241 -276.172676)
		(width 0.1143)
		(layer "In13.Cu")
		(net "P5E_CPU1_P2_TX_DN<4>")
	)
	(arc
		(start 116.65458 -280.121614)
		(mid 116.88258 -280.566368)
		(end 116.65458 -281.011122)
		(width 0.1143)
		(layer "In13.Cu")
		(net "P5E_CPU1_P2_TX_DN<4>")
	)
	(arc
		(start 116.6241 -284.96006)
		(mid 116.631764 -284.965331)
		(end 116.63934 -284.970728)
		(width 0.1143)
		(layer "In13.Cu")
		(net "P5E_CPU1_P2_TX_DN<4>")
	)
	(arc
		(start 116.556028 -279.45207)
		(mid 116.4001 -279.756362)
		(end 116.556028 -280.060654)
		(width 0.1143)
		(layer "In13.Cu")
		(net "P5E_CPU1_P2_TX_DN<4>")
	)
	(arc
		(start 116.400072 -286.23641)
		(mid 116.440834 -286.406294)
		(end 116.55425 -286.539178)
		(width 0.1143)
		(layer "In13.Cu")
		(net "P5E_CPU1_P2_TX_DN<4>")
	)
	(arc
		(start 117.04701 -270.529812)
		(mid 116.910321 -270.666899)
		(end 116.86032 -270.853916)
		(width 0.1143)
		(layer "In13.Cu")
		(net "P5E_CPU1_P2_TX_DN<4>")
	)
	(arc
		(start 147.9423 -370.469668)
		(mid 148.023865 -370.554839)
		(end 148.087588 -370.654072)
		(width 0.14224)
		(layer "In13.Cu")
		(net "P5E_CPU1_P2_TX_DN<4>")
	)
	(arc
		(start 147.398232 -370.15547)
		(mid 147.462914 -370.184463)
		(end 147.529296 -370.209318)
		(width 0.14224)
		(layer "In13.Cu")
		(net "P5E_CPU1_P2_TX_DN<4>")
	)
	(arc
		(start 148.298662 -371.22354)
		(mid 148.31546 -371.318515)
		(end 148.321014 -371.414802)
		(width 0.14224)
		(layer "In13.Cu")
		(net "P5E_CPU1_P2_TX_DN<4>")
	)
	(arc
		(start 116.584222 -294.015668)
		(mid 116.400088 -294.33554)
		(end 116.582952 -294.656256)
		(width 0.1143)
		(layer "In13.Cu")
		(net "P5E_CPU1_P2_TX_DN<4>")
	)
	(arc
		(start 116.6241 -275.239988)
		(mid 116.631249 -275.244888)
		(end 116.638324 -275.249894)
		(width 0.1143)
		(layer "In13.Cu")
		(net "P5E_CPU1_P2_TX_DN<4>")
	)
	(arc
		(start 116.6241 -271.999964)
		(mid 116.631249 -272.004864)
		(end 116.638324 -272.00987)
		(width 0.1143)
		(layer "In13.Cu")
		(net "P5E_CPU1_P2_TX_DN<4>")
	)
	(arc
		(start 116.556028 -289.171888)
		(mid 116.4001 -289.47618)
		(end 116.556028 -289.780472)
		(width 0.1143)
		(layer "In13.Cu")
		(net "P5E_CPU1_P2_TX_DN<4>")
	)
	(arc
		(start 116.556028 -285.932118)
		(mid 116.441352 -286.065452)
		(end 116.400072 -286.23641)
		(width 0.1143)
		(layer "In13.Cu")
		(net "P5E_CPU1_P2_TX_DN<4>")
	)
	(arc
		(start 116.867686 -287.068006)
		(mid 116.797943 -287.301668)
		(end 116.646706 -287.492948)
		(width 0.1143)
		(layer "In13.Cu")
		(net "P5E_CPU1_P2_TX_DN<4>")
	)
	(arc
		(start 116.556028 -287.55213)
		(mid 116.441352 -287.685464)
		(end 116.400072 -287.856422)
		(width 0.1143)
		(layer "In13.Cu")
		(net "P5E_CPU1_P2_TX_DN<4>")
	)
	(arc
		(start 117.33403 -270.119094)
		(mid 117.254951 -270.334539)
		(end 117.096794 -270.500856)
		(width 0.1143)
		(layer "In13.Cu")
		(net "P5E_CPU1_P2_TX_DN<4>")
	)
	(arc
		(start 116.638324 -272.922746)
		(mid 116.63125 -272.927753)
		(end 116.6241 -272.932652)
		(width 0.1143)
		(layer "In13.Cu")
		(net "P5E_CPU1_P2_TX_DN<4>")
	)
	(arc
		(start 117.240558 -295.63568)
		(mid 117.314672 -295.788394)
		(end 117.340126 -295.956228)
		(width 0.1143)
		(layer "In13.Cu")
		(net "P5E_CPU1_P2_TX_DN<4>")
	)
	(arc
		(start 146.588988 -368.615214)
		(mid 146.606845 -368.71113)
		(end 146.612864 -368.808508)
		(width 0.14224)
		(layer "In13.Cu")
		(net "P5E_CPU1_P2_TX_DN<4>")
	)
	(arc
		(start 117.096794 -295.491662)
		(mid 117.175217 -295.557143)
		(end 117.240558 -295.63568)
		(width 0.1143)
		(layer "In13.Cu")
		(net "P5E_CPU1_P2_TX_DN<4>")
	)
	(arc
		(start 116.63934 -278.49068)
		(mid 116.864511 -278.946356)
		(end 116.63934 -279.402032)
		(width 0.1143)
		(layer "In13.Cu")
		(net "P5E_CPU1_P2_TX_DN<4>")
	)
	(arc
		(start 145.788126 -365.458502)
		(mid 145.811274 -365.517434)
		(end 145.829274 -365.578136)
		(width 0.14224)
		(layer "In13.Cu")
		(net "P5E_CPU1_P2_TX_DN<4>")
	)
	(arc
		(start 116.556028 -272.972022)
		(mid 116.4001 -273.276314)
		(end 116.556028 -273.580606)
		(width 0.1143)
		(layer "In13.Cu")
		(net "P5E_CPU1_P2_TX_DN<4>")
	)
	(arc
		(start 116.590826 -281.700732)
		(mid 116.870441 -282.18638)
		(end 116.590826 -282.672028)
		(width 0.1143)
		(layer "In13.Cu")
		(net "P5E_CPU1_P2_TX_DN<4>")
	)
	(arc
		(start 146.612864 -369.440206)
		(mid 146.621614 -369.50267)
		(end 146.647154 -369.560348)
		(width 0.14224)
		(layer "In13.Cu")
		(net "P5E_CPU1_P2_TX_DN<4>")
	)
	(arc
		(start 116.638324 -274.542758)
		(mid 116.63125 -274.547765)
		(end 116.6241 -274.552664)
		(width 0.1143)
		(layer "In13.Cu")
		(net "P5E_CPU1_P2_TX_DN<4>")
	)
	(arc
		(start 116.65458 -276.88159)
		(mid 116.88258 -277.326344)
		(end 116.65458 -277.771098)
		(width 0.1143)
		(layer "In13.Cu")
		(net "P5E_CPU1_P2_TX_DN<4>")
	)
	(arc
		(start 116.58854 -288.179256)
		(mid 116.868874 -288.666174)
		(end 116.58854 -289.153092)
		(width 0.1143)
		(layer "In13.Cu")
		(net "P5E_CPU1_P2_TX_DN<4>")
	)
	(arc
		(start 116.86032 -270.862298)
		(mid 116.788894 -271.131643)
		(end 116.593366 -271.330166)
		(width 0.1143)
		(layer "In13.Cu")
		(net "P5E_CPU1_P2_TX_DN<4>")
	)
	(arc
		(start 116.400072 -287.856422)
		(mid 116.440834 -288.026306)
		(end 116.55425 -288.15919)
		(width 0.1143)
		(layer "In13.Cu")
		(net "P5E_CPU1_P2_TX_DN<4>")
	)
	(arc
		(start 116.606066 -283.329634)
		(mid 116.880649 -283.806392)
		(end 116.606066 -284.28315)
		(width 0.1143)
		(layer "In13.Cu")
		(net "P5E_CPU1_P2_TX_DN<4>")
	)
	(arc
		(start 116.638324 -273.629882)
		(mid 116.865707 -274.08632)
		(end 116.638324 -274.542758)
		(width 0.1143)
		(layer "In13.Cu")
		(net "P5E_CPU1_P2_TX_DN<4>")
	)
	(arc
		(start 116.63934 -285.88208)
		(mid 116.631764 -285.887476)
		(end 116.6241 -285.892748)
		(width 0.1143)
		(layer "In13.Cu")
		(net "P5E_CPU1_P2_TX_DN<4>")
	)
	(arc
		(start 116.556028 -290.7919)
		(mid 116.4001 -291.096192)
		(end 116.556028 -291.400484)
		(width 0.1143)
		(layer "In13.Cu")
		(net "P5E_CPU1_P2_TX_DN<4>")
	)
	(arc
		(start 116.869972 -295.146222)
		(mid 116.911227 -295.317193)
		(end 117.025928 -295.450514)
		(width 0.1143)
		(layer "In13.Cu")
		(net "P5E_CPU1_P2_TX_DN<4>")
	)
	(arc
		(start 116.556028 -292.411912)
		(mid 116.4001 -292.716204)
		(end 116.556028 -293.020496)
		(width 0.1143)
		(layer "In13.Cu")
		(net "P5E_CPU1_P2_TX_DN<4>")
	)
	(arc
		(start 148.087588 -370.654072)
		(mid 148.210344 -370.932423)
		(end 148.298662 -371.22354)
		(width 0.14224)
		(layer "In13.Cu")
		(net "P5E_CPU1_P2_TX_DN<4>")
	)
	(arc
		(start 116.6241 -278.480012)
		(mid 116.631764 -278.485283)
		(end 116.63934 -278.49068)
		(width 0.1143)
		(layer "In13.Cu")
		(net "P5E_CPU1_P2_TX_DN<4>")
	)
	(arc
		(start 116.637562 -286.58947)
		(mid 116.808087 -286.788905)
		(end 116.869972 -287.043876)
		(width 0.1143)
		(layer "In13.Cu")
		(net "P5E_CPU1_P2_TX_DN<4>")
	)
	(arc
		(start 116.638324 -272.00987)
		(mid 116.865707 -272.466308)
		(end 116.638324 -272.922746)
		(width 0.1143)
		(layer "In13.Cu")
		(net "P5E_CPU1_P2_TX_DN<4>")
	)
	(arc
		(start 116.584476 -284.295596)
		(mid 116.400271 -284.612304)
		(end 116.577364 -284.933136)
		(width 0.1143)
		(layer "In13.Cu")
		(net "P5E_CPU1_P2_TX_DN<4>")
	)
	(arc
		(start 116.587778 -289.79876)
		(mid 116.868425 -290.286186)
		(end 116.587778 -290.773612)
		(width 0.1143)
		(layer "In13.Cu")
		(net "P5E_CPU1_P2_TX_DN<4>")
	)
	(arc
		(start 116.6241 -273.619976)
		(mid 116.631249 -273.624876)
		(end 116.638324 -273.629882)
		(width 0.1143)
		(layer "In13.Cu")
		(net "P5E_CPU1_P2_TX_DN<4>")
	)
	(arc
		(start 116.556028 -281.072082)
		(mid 116.4001 -281.376374)
		(end 116.556028 -281.680666)
		(width 0.1143)
		(layer "In13.Cu")
		(net "P5E_CPU1_P2_TX_DN<4>")
	)
	(arc
		(start 116.624862 -286.580072)
		(mid 116.631244 -286.584728)
		(end 116.637562 -286.58947)
		(width 0.1143)
		(layer "In13.Cu")
		(net "P5E_CPU1_P2_TX_DN<4>")
	)
	(segment
		(start 145.208244 -369.03533)
		(end 144.937734 -369.30584)
		(width 0.12954)
		(layer "F.Cu")
		(net "P5E_CPU1_P2_TX_DN<3>")
	)
	(segment
		(start 144.937734 -370.00942)
		(end 145.233644 -370.30533)
		(width 0.12954)
		(layer "F.Cu")
		(net "P5E_CPU1_P2_TX_DN<3>")
	)
	(segment
		(start 144.937734 -369.30584)
		(end 144.937734 -370.00942)
		(width 0.12954)
		(layer "F.Cu")
		(net "P5E_CPU1_P2_TX_DN<3>")
	)
	(segment
		(start 114.897916 -272.20037)
		(end 115.364768 -272.466308)
		(width 0.12954)
		(layer "F.Cu")
		(net "P5E_CPU1_P2_TX_DN<3>")
	)
	(segment
		(start 115.646962 -289.154108)
		(end 115.645692 -289.15487)
		(width 0.1143)
		(layer "In13.Cu")
		(net "P5E_CPU1_P2_TX_DN<3>")
	)
	(segment
		(start 115.646962 -273.598386)
		(end 115.647724 -273.598894)
		(width 0.1143)
		(layer "In13.Cu")
		(net "P5E_CPU1_P2_TX_DN<3>")
	)
	(segment
		(start 115.647724 -283.318966)
		(end 115.64874 -283.319474)
		(width 0.1143)
		(layer "In13.Cu")
		(net "P5E_CPU1_P2_TX_DN<3>")
	)
	(segment
		(start 115.364768 -272.466308)
		(end 115.066826 -272.466308)
		(width 0.1143)
		(layer "In13.Cu")
		(net "P5E_CPU1_P2_TX_DN<3>")
	)
	(segment
		(start 115.650264 -292.3921)
		(end 115.64874 -292.393116)
		(width 0.1143)
		(layer "In13.Cu")
		(net "P5E_CPU1_P2_TX_DN<3>")
	)
	(segment
		(start 115.646962 -294.014144)
		(end 115.645692 -294.014906)
		(width 0.1143)
		(layer "In13.Cu")
		(net "P5E_CPU1_P2_TX_DN<3>")
	)
	(segment
		(start 115.615974 -280.060654)
		(end 115.646962 -280.078434)
		(width 0.1143)
		(layer "In13.Cu")
		(net "P5E_CPU1_P2_TX_DN<3>")
	)
	(segment
		(start 118.804944 -303.011586)
		(end 128.016508 -315.430408)
		(width 0.14224)
		(layer "In13.Cu")
		(net "P5E_CPU1_P2_TX_DN<3>")
	)
	(segment
		(start 115.647724 -274.573746)
		(end 115.646962 -274.574254)
		(width 0.1143)
		(layer "In13.Cu")
		(net "P5E_CPU1_P2_TX_DN<3>")
	)
	(segment
		(start 115.64874 -289.799268)
		(end 115.650264 -289.800284)
		(width 0.1143)
		(layer "In13.Cu")
		(net "P5E_CPU1_P2_TX_DN<3>")
	)
	(segment
		(start 115.646962 -293.038276)
		(end 115.647724 -293.038784)
		(width 0.1143)
		(layer "In13.Cu")
		(net "P5E_CPU1_P2_TX_DN<3>")
	)
	(segment
		(start 115.64874 -285.913322)
		(end 115.647724 -285.91383)
		(width 0.1143)
		(layer "In13.Cu")
		(net "P5E_CPU1_P2_TX_DN<3>")
	)
	(segment
		(start 115.645692 -284.295088)
		(end 115.615974 -284.312106)
		(width 0.1143)
		(layer "In13.Cu")
		(net "P5E_CPU1_P2_TX_DN<3>")
	)
	(segment
		(start 115.68684 -281.030934)
		(end 115.647724 -281.053794)
		(width 0.1143)
		(layer "In13.Cu")
		(net "P5E_CPU1_P2_TX_DN<3>")
	)
	(segment
		(start 115.646962 -283.318458)
		(end 115.647724 -283.318966)
		(width 0.1143)
		(layer "In13.Cu")
		(net "P5E_CPU1_P2_TX_DN<3>")
	)
	(segment
		(start 144.436592 -366.070896)
		(end 144.440402 -366.082326)
		(width 0.14224)
		(layer "In13.Cu")
		(net "P5E_CPU1_P2_TX_DN<3>")
	)
	(segment
		(start 115.650264 -284.292294)
		(end 115.64874 -284.29331)
		(width 0.1143)
		(layer "In13.Cu")
		(net "P5E_CPU1_P2_TX_DN<3>")
	)
	(segment
		(start 144.917414 -367.98885)
		(end 144.917414 -368.7445)
		(width 0.14224)
		(layer "In13.Cu")
		(net "P5E_CPU1_P2_TX_DN<3>")
	)
	(segment
		(start 115.646962 -278.458422)
		(end 115.647724 -278.45893)
		(width 0.1143)
		(layer "In13.Cu")
		(net "P5E_CPU1_P2_TX_DN<3>")
	)
	(segment
		(start 115.64874 -280.07945)
		(end 115.68684 -280.101802)
		(width 0.1143)
		(layer "In13.Cu")
		(net "P5E_CPU1_P2_TX_DN<3>")
	)
	(segment
		(start 115.646962 -284.294326)
		(end 115.645692 -284.295088)
		(width 0.1143)
		(layer "In13.Cu")
		(net "P5E_CPU1_P2_TX_DN<3>")
	)
	(segment
		(start 115.64874 -273.599402)
		(end 115.650264 -273.600418)
		(width 0.1143)
		(layer "In13.Cu")
		(net "P5E_CPU1_P2_TX_DN<3>")
	)
	(segment
		(start 115.615974 -276.82063)
		(end 115.646962 -276.83841)
		(width 0.1143)
		(layer "In13.Cu")
		(net "P5E_CPU1_P2_TX_DN<3>")
	)
	(segment
		(start 144.917414 -368.7445)
		(end 145.208244 -369.03533)
		(width 0.14224)
		(layer "In13.Cu")
		(net "P5E_CPU1_P2_TX_DN<3>")
	)
	(segment
		(start 115.64874 -289.153092)
		(end 115.647724 -289.1536)
		(width 0.1143)
		(layer "In13.Cu")
		(net "P5E_CPU1_P2_TX_DN<3>")
	)
	(segment
		(start 115.650264 -289.800284)
		(end 115.68684 -289.82162)
		(width 0.1143)
		(layer "In13.Cu")
		(net "P5E_CPU1_P2_TX_DN<3>")
	)
	(segment
		(start 115.650264 -282.672282)
		(end 115.64874 -282.673298)
		(width 0.1143)
		(layer "In13.Cu")
		(net "P5E_CPU1_P2_TX_DN<3>")
	)
	(segment
		(start 115.646962 -274.574254)
		(end 115.645692 -274.575016)
		(width 0.1143)
		(layer "In13.Cu")
		(net "P5E_CPU1_P2_TX_DN<3>")
	)
	(segment
		(start 115.64874 -278.459438)
		(end 115.650264 -278.460454)
		(width 0.1143)
		(layer "In13.Cu")
		(net "P5E_CPU1_P2_TX_DN<3>")
	)
	(segment
		(start 115.646962 -276.83841)
		(end 115.647724 -276.838918)
		(width 0.1143)
		(layer "In13.Cu")
		(net "P5E_CPU1_P2_TX_DN<3>")
	)
	(segment
		(start 115.615974 -284.92069)
		(end 115.646962 -284.93847)
		(width 0.1143)
		(layer "In13.Cu")
		(net "P5E_CPU1_P2_TX_DN<3>")
	)
	(segment
		(start 115.646962 -294.658288)
		(end 115.647724 -294.658796)
		(width 0.1143)
		(layer "In13.Cu")
		(net "P5E_CPU1_P2_TX_DN<3>")
	)
	(segment
		(start 115.647724 -289.1536)
		(end 115.646962 -289.154108)
		(width 0.1143)
		(layer "In13.Cu")
		(net "P5E_CPU1_P2_TX_DN<3>")
	)
	(segment
		(start 115.646962 -282.674314)
		(end 115.645692 -282.675076)
		(width 0.1143)
		(layer "In13.Cu")
		(net "P5E_CPU1_P2_TX_DN<3>")
	)
	(segment
		(start 115.64874 -283.319474)
		(end 115.650264 -283.32049)
		(width 0.1143)
		(layer "In13.Cu")
		(net "P5E_CPU1_P2_TX_DN<3>")
	)
	(segment
		(start 129.197862 -317.197994)
		(end 133.1468 -324.586854)
		(width 0.14224)
		(layer "In13.Cu")
		(net "P5E_CPU1_P2_TX_DN<3>")
	)
	(segment
		(start 115.17757 -272.788888)
		(end 115.216686 -272.811748)
		(width 0.1143)
		(layer "In13.Cu")
		(net "P5E_CPU1_P2_TX_DN<3>")
	)
	(segment
		(start 115.650264 -275.22043)
		(end 115.68684 -275.241766)
		(width 0.1143)
		(layer "In13.Cu")
		(net "P5E_CPU1_P2_TX_DN<3>")
	)
	(segment
		(start 133.1468 -324.586854)
		(end 138.44016 -351.198942)
		(width 0.14224)
		(layer "In13.Cu")
		(net "P5E_CPU1_P2_TX_DN<3>")
	)
	(segment
		(start 115.615974 -293.020496)
		(end 115.646962 -293.038276)
		(width 0.1143)
		(layer "In13.Cu")
		(net "P5E_CPU1_P2_TX_DN<3>")
	)
	(segment
		(start 115.64874 -290.773104)
		(end 115.647724 -290.773612)
		(width 0.1143)
		(layer "In13.Cu")
		(net "P5E_CPU1_P2_TX_DN<3>")
	)
	(segment
		(start 115.64874 -284.939486)
		(end 115.650264 -284.940502)
		(width 0.1143)
		(layer "In13.Cu")
		(net "P5E_CPU1_P2_TX_DN<3>")
	)
	(segment
		(start 115.646962 -292.394132)
		(end 115.645692 -292.394894)
		(width 0.1143)
		(layer "In13.Cu")
		(net "P5E_CPU1_P2_TX_DN<3>")
	)
	(segment
		(start 115.647724 -282.673806)
		(end 115.646962 -282.674314)
		(width 0.1143)
		(layer "In13.Cu")
		(net "P5E_CPU1_P2_TX_DN<3>")
	)
	(segment
		(start 115.647724 -293.038784)
		(end 115.64874 -293.039292)
		(width 0.1143)
		(layer "In13.Cu")
		(net "P5E_CPU1_P2_TX_DN<3>")
	)
	(segment
		(start 115.646962 -284.93847)
		(end 115.647724 -284.938978)
		(width 0.1143)
		(layer "In13.Cu")
		(net "P5E_CPU1_P2_TX_DN<3>")
	)
	(segment
		(start 115.647724 -277.81377)
		(end 115.646962 -277.814278)
		(width 0.1143)
		(layer "In13.Cu")
		(net "P5E_CPU1_P2_TX_DN<3>")
	)
	(segment
		(start 115.647724 -289.79876)
		(end 115.64874 -289.799268)
		(width 0.1143)
		(layer "In13.Cu")
		(net "P5E_CPU1_P2_TX_DN<3>")
	)
	(segment
		(start 115.615974 -278.440642)
		(end 115.646962 -278.458422)
		(width 0.1143)
		(layer "In13.Cu")
		(net "P5E_CPU1_P2_TX_DN<3>")
	)
	(segment
		(start 115.14709 -272.771108)
		(end 115.17757 -272.788888)
		(width 0.1143)
		(layer "In13.Cu")
		(net "P5E_CPU1_P2_TX_DN<3>")
	)
	(segment
		(start 115.645692 -277.81504)
		(end 115.615974 -277.832058)
		(width 0.1143)
		(layer "In13.Cu")
		(net "P5E_CPU1_P2_TX_DN<3>")
	)
	(segment
		(start 115.64874 -294.013128)
		(end 115.647724 -294.013636)
		(width 0.1143)
		(layer "In13.Cu")
		(net "P5E_CPU1_P2_TX_DN<3>")
	)
	(segment
		(start 115.68684 -277.79091)
		(end 115.647724 -277.81377)
		(width 0.1143)
		(layer "In13.Cu")
		(net "P5E_CPU1_P2_TX_DN<3>")
	)
	(segment
		(start 116.400072 -295.95572)
		(end 116.400072 -296.2529)
		(width 0.1143)
		(layer "In13.Cu")
		(net "P5E_CPU1_P2_TX_DN<3>")
	)
	(segment
		(start 115.64874 -284.29331)
		(end 115.647724 -284.293818)
		(width 0.1143)
		(layer "In13.Cu")
		(net "P5E_CPU1_P2_TX_DN<3>")
	)
	(segment
		(start 115.645692 -289.15487)
		(end 115.615974 -289.171888)
		(width 0.1143)
		(layer "In13.Cu")
		(net "P5E_CPU1_P2_TX_DN<3>")
	)
	(segment
		(start 115.646962 -290.77412)
		(end 115.645692 -290.774882)
		(width 0.1143)
		(layer "In13.Cu")
		(net "P5E_CPU1_P2_TX_DN<3>")
	)
	(segment
		(start 115.647724 -291.418772)
		(end 115.64874 -291.41928)
		(width 0.1143)
		(layer "In13.Cu")
		(net "P5E_CPU1_P2_TX_DN<3>")
	)
	(segment
		(start 115.68684 -274.550886)
		(end 115.647724 -274.573746)
		(width 0.1143)
		(layer "In13.Cu")
		(net "P5E_CPU1_P2_TX_DN<3>")
	)
	(segment
		(start 115.615974 -291.400484)
		(end 115.646962 -291.418264)
		(width 0.1143)
		(layer "In13.Cu")
		(net "P5E_CPU1_P2_TX_DN<3>")
	)
	(segment
		(start 117.78488 -301.309786)
		(end 118.804944 -303.011586)
		(width 0.14224)
		(layer "In13.Cu")
		(net "P5E_CPU1_P2_TX_DN<3>")
	)
	(segment
		(start 115.646962 -281.698446)
		(end 115.647724 -281.698954)
		(width 0.1143)
		(layer "In13.Cu")
		(net "P5E_CPU1_P2_TX_DN<3>")
	)
	(segment
		(start 115.647724 -292.393624)
		(end 115.646962 -292.394132)
		(width 0.1143)
		(layer "In13.Cu")
		(net "P5E_CPU1_P2_TX_DN<3>")
	)
	(segment
		(start 115.615974 -289.780472)
		(end 115.647724 -289.79876)
		(width 0.1143)
		(layer "In13.Cu")
		(net "P5E_CPU1_P2_TX_DN<3>")
	)
	(segment
		(start 144.440402 -366.082326)
		(end 144.917414 -367.98885)
		(width 0.14224)
		(layer "In13.Cu")
		(net "P5E_CPU1_P2_TX_DN<3>")
	)
	(segment
		(start 115.68684 -284.270958)
		(end 115.650264 -284.292294)
		(width 0.1143)
		(layer "In13.Cu")
		(net "P5E_CPU1_P2_TX_DN<3>")
	)
	(segment
		(start 115.650264 -291.420296)
		(end 115.68684 -291.441632)
		(width 0.1143)
		(layer "In13.Cu")
		(net "P5E_CPU1_P2_TX_DN<3>")
	)
	(segment
		(start 115.615974 -294.640508)
		(end 115.646962 -294.658288)
		(width 0.1143)
		(layer "In13.Cu")
		(net "P5E_CPU1_P2_TX_DN<3>")
	)
	(segment
		(start 115.066826 -272.466308)
		(end 114.996976 -272.536158)
		(width 0.1143)
		(layer "In13.Cu")
		(net "P5E_CPU1_P2_TX_DN<3>")
	)
	(segment
		(start 115.615974 -283.300678)
		(end 115.646962 -283.318458)
		(width 0.1143)
		(layer "In13.Cu")
		(net "P5E_CPU1_P2_TX_DN<3>")
	)
	(segment
		(start 116.400072 -296.2529)
		(end 116.445792 -296.29862)
		(width 0.1143)
		(layer "In13.Cu")
		(net "P5E_CPU1_P2_TX_DN<3>")
	)
	(segment
		(start 116.445792 -298.077128)
		(end 117.78488 -301.309786)
		(width 0.14224)
		(layer "In13.Cu")
		(net "P5E_CPU1_P2_TX_DN<3>")
	)
	(segment
		(start 115.650264 -283.32049)
		(end 115.68684 -283.341826)
		(width 0.1143)
		(layer "In13.Cu")
		(net "P5E_CPU1_P2_TX_DN<3>")
	)
	(segment
		(start 115.650264 -278.460454)
		(end 115.68684 -278.48179)
		(width 0.1143)
		(layer "In13.Cu")
		(net "P5E_CPU1_P2_TX_DN<3>")
	)
	(segment
		(start 115.645692 -292.394894)
		(end 115.615974 -292.411912)
		(width 0.1143)
		(layer "In13.Cu")
		(net "P5E_CPU1_P2_TX_DN<3>")
	)
	(segment
		(start 115.615974 -281.680666)
		(end 115.646962 -281.698446)
		(width 0.1143)
		(layer "In13.Cu")
		(net "P5E_CPU1_P2_TX_DN<3>")
	)
	(segment
		(start 115.647724 -276.193758)
		(end 115.646962 -276.194266)
		(width 0.1143)
		(layer "In13.Cu")
		(net "P5E_CPU1_P2_TX_DN<3>")
	)
	(segment
		(start 115.650264 -293.040308)
		(end 115.68684 -293.061644)
		(width 0.1143)
		(layer "In13.Cu")
		(net "P5E_CPU1_P2_TX_DN<3>")
	)
	(segment
		(start 128.016508 -315.430408)
		(end 129.197862 -317.197994)
		(width 0.14224)
		(layer "In13.Cu")
		(net "P5E_CPU1_P2_TX_DN<3>")
	)
	(segment
		(start 115.646962 -285.914338)
		(end 115.645692 -285.9151)
		(width 0.1143)
		(layer "In13.Cu")
		(net "P5E_CPU1_P2_TX_DN<3>")
	)
	(segment
		(start 115.68684 -289.13074)
		(end 115.650264 -289.152076)
		(width 0.1143)
		(layer "In13.Cu")
		(net "P5E_CPU1_P2_TX_DN<3>")
	)
	(segment
		(start 115.68684 -276.170898)
		(end 115.647724 -276.193758)
		(width 0.1143)
		(layer "In13.Cu")
		(net "P5E_CPU1_P2_TX_DN<3>")
	)
	(segment
		(start 115.64874 -281.699462)
		(end 115.650264 -281.700478)
		(width 0.1143)
		(layer "In13.Cu")
		(net "P5E_CPU1_P2_TX_DN<3>")
	)
	(segment
		(start 115.64874 -294.659304)
		(end 115.650264 -294.66032)
		(width 0.1143)
		(layer "In13.Cu")
		(net "P5E_CPU1_P2_TX_DN<3>")
	)
	(segment
		(start 115.64874 -276.839426)
		(end 115.650264 -276.840442)
		(width 0.1143)
		(layer "In13.Cu")
		(net "P5E_CPU1_P2_TX_DN<3>")
	)
	(segment
		(start 115.68684 -279.410922)
		(end 115.647724 -279.433782)
		(width 0.1143)
		(layer "In13.Cu")
		(net "P5E_CPU1_P2_TX_DN<3>")
	)
	(segment
		(start 115.64874 -282.673298)
		(end 115.647724 -282.673806)
		(width 0.1143)
		(layer "In13.Cu")
		(net "P5E_CPU1_P2_TX_DN<3>")
	)
	(segment
		(start 115.647724 -284.293818)
		(end 115.646962 -284.294326)
		(width 0.1143)
		(layer "In13.Cu")
		(net "P5E_CPU1_P2_TX_DN<3>")
	)
	(segment
		(start 116.445792 -296.29862)
		(end 116.445792 -296.327068)
		(width 0.1143)
		(layer "In13.Cu")
		(net "P5E_CPU1_P2_TX_DN<3>")
	)
	(segment
		(start 115.647724 -273.598894)
		(end 115.64874 -273.599402)
		(width 0.1143)
		(layer "In13.Cu")
		(net "P5E_CPU1_P2_TX_DN<3>")
	)
	(segment
		(start 115.645692 -276.195028)
		(end 115.615974 -276.212046)
		(width 0.1143)
		(layer "In13.Cu")
		(net "P5E_CPU1_P2_TX_DN<3>")
	)
	(segment
		(start 115.647724 -281.053794)
		(end 115.615974 -281.072082)
		(width 0.1143)
		(layer "In13.Cu")
		(net "P5E_CPU1_P2_TX_DN<3>")
	)
	(segment
		(start 142.36827 -360.059224)
		(end 144.436338 -366.070896)
		(width 0.14224)
		(layer "In13.Cu")
		(net "P5E_CPU1_P2_TX_DN<3>")
	)
	(segment
		(start 115.647724 -288.178748)
		(end 115.68684 -288.201608)
		(width 0.1143)
		(layer "In13.Cu")
		(net "P5E_CPU1_P2_TX_DN<3>")
	)
	(segment
		(start 115.646962 -277.814278)
		(end 115.645692 -277.81504)
		(width 0.1143)
		(layer "In13.Cu")
		(net "P5E_CPU1_P2_TX_DN<3>")
	)
	(segment
		(start 115.647724 -290.773612)
		(end 115.646962 -290.77412)
		(width 0.1143)
		(layer "In13.Cu")
		(net "P5E_CPU1_P2_TX_DN<3>")
	)
	(segment
		(start 115.647724 -286.558736)
		(end 115.68684 -286.581596)
		(width 0.1143)
		(layer "In13.Cu")
		(net "P5E_CPU1_P2_TX_DN<3>")
	)
	(segment
		(start 115.647724 -294.658796)
		(end 115.64874 -294.659304)
		(width 0.1143)
		(layer "In13.Cu")
		(net "P5E_CPU1_P2_TX_DN<3>")
	)
	(segment
		(start 115.650264 -276.840442)
		(end 115.68684 -276.861778)
		(width 0.1143)
		(layer "In13.Cu")
		(net "P5E_CPU1_P2_TX_DN<3>")
	)
	(segment
		(start 115.64874 -275.219414)
		(end 115.650264 -275.22043)
		(width 0.1143)
		(layer "In13.Cu")
		(net "P5E_CPU1_P2_TX_DN<3>")
	)
	(segment
		(start 115.64874 -293.039292)
		(end 115.650264 -293.040308)
		(width 0.1143)
		(layer "In13.Cu")
		(net "P5E_CPU1_P2_TX_DN<3>")
	)
	(segment
		(start 115.650264 -281.700478)
		(end 115.68684 -281.721814)
		(width 0.1143)
		(layer "In13.Cu")
		(net "P5E_CPU1_P2_TX_DN<3>")
	)
	(segment
		(start 115.68684 -282.650946)
		(end 115.650264 -282.672282)
		(width 0.1143)
		(layer "In13.Cu")
		(net "P5E_CPU1_P2_TX_DN<3>")
	)
	(segment
		(start 115.650264 -285.912306)
		(end 115.64874 -285.913322)
		(width 0.1143)
		(layer "In13.Cu")
		(net "P5E_CPU1_P2_TX_DN<3>")
	)
	(segment
		(start 115.614196 -288.15919)
		(end 115.647724 -288.178748)
		(width 0.1143)
		(layer "In13.Cu")
		(net "P5E_CPU1_P2_TX_DN<3>")
	)
	(segment
		(start 115.645692 -282.675076)
		(end 115.615974 -282.692094)
		(width 0.1143)
		(layer "In13.Cu")
		(net "P5E_CPU1_P2_TX_DN<3>")
	)
	(segment
		(start 115.647724 -276.838918)
		(end 115.64874 -276.839426)
		(width 0.1143)
		(layer "In13.Cu")
		(net "P5E_CPU1_P2_TX_DN<3>")
	)
	(segment
		(start 115.646962 -275.218398)
		(end 115.647724 -275.218906)
		(width 0.1143)
		(layer "In13.Cu")
		(net "P5E_CPU1_P2_TX_DN<3>")
	)
	(segment
		(start 115.64874 -292.393116)
		(end 115.647724 -292.393624)
		(width 0.1143)
		(layer "In13.Cu")
		(net "P5E_CPU1_P2_TX_DN<3>")
	)
	(segment
		(start 115.647724 -281.698954)
		(end 115.64874 -281.699462)
		(width 0.1143)
		(layer "In13.Cu")
		(net "P5E_CPU1_P2_TX_DN<3>")
	)
	(segment
		(start 116.445792 -296.327068)
		(end 116.445792 -298.077128)
		(width 0.14224)
		(layer "In13.Cu")
		(net "P5E_CPU1_P2_TX_DN<3>")
	)
	(segment
		(start 115.647724 -287.533842)
		(end 115.615974 -287.55213)
		(width 0.1143)
		(layer "In13.Cu")
		(net "P5E_CPU1_P2_TX_DN<3>")
	)
	(segment
		(start 115.650264 -289.152076)
		(end 115.64874 -289.153092)
		(width 0.1143)
		(layer "In13.Cu")
		(net "P5E_CPU1_P2_TX_DN<3>")
	)
	(segment
		(start 144.436338 -366.070896)
		(end 144.436592 -366.070896)
		(width 0.14224)
		(layer "In13.Cu")
		(net "P5E_CPU1_P2_TX_DN<3>")
	)
	(segment
		(start 115.650264 -273.600418)
		(end 115.68684 -273.621754)
		(width 0.1143)
		(layer "In13.Cu")
		(net "P5E_CPU1_P2_TX_DN<3>")
	)
	(segment
		(start 115.646962 -279.43429)
		(end 115.645692 -279.435052)
		(width 0.1143)
		(layer "In13.Cu")
		(net "P5E_CPU1_P2_TX_DN<3>")
	)
	(segment
		(start 115.647724 -285.91383)
		(end 115.646962 -285.914338)
		(width 0.1143)
		(layer "In13.Cu")
		(net "P5E_CPU1_P2_TX_DN<3>")
	)
	(segment
		(start 115.645692 -290.774882)
		(end 115.615974 -290.7919)
		(width 0.1143)
		(layer "In13.Cu")
		(net "P5E_CPU1_P2_TX_DN<3>")
	)
	(segment
		(start 115.68684 -292.370764)
		(end 115.650264 -292.3921)
		(width 0.1143)
		(layer "In13.Cu")
		(net "P5E_CPU1_P2_TX_DN<3>")
	)
	(segment
		(start 115.650264 -294.66032)
		(end 115.68684 -294.681656)
		(width 0.1143)
		(layer "In13.Cu")
		(net "P5E_CPU1_P2_TX_DN<3>")
	)
	(segment
		(start 115.68684 -285.89097)
		(end 115.650264 -285.912306)
		(width 0.1143)
		(layer "In13.Cu")
		(net "P5E_CPU1_P2_TX_DN<3>")
	)
	(segment
		(start 115.650264 -290.772088)
		(end 115.64874 -290.773104)
		(width 0.1143)
		(layer "In13.Cu")
		(net "P5E_CPU1_P2_TX_DN<3>")
	)
	(segment
		(start 115.650264 -294.012112)
		(end 115.64874 -294.013128)
		(width 0.1143)
		(layer "In13.Cu")
		(net "P5E_CPU1_P2_TX_DN<3>")
	)
	(segment
		(start 115.647724 -279.433782)
		(end 115.646962 -279.43429)
		(width 0.1143)
		(layer "In13.Cu")
		(net "P5E_CPU1_P2_TX_DN<3>")
	)
	(segment
		(start 115.647724 -280.078942)
		(end 115.64874 -280.07945)
		(width 0.1143)
		(layer "In13.Cu")
		(net "P5E_CPU1_P2_TX_DN<3>")
	)
	(segment
		(start 115.68684 -290.750752)
		(end 115.650264 -290.772088)
		(width 0.1143)
		(layer "In13.Cu")
		(net "P5E_CPU1_P2_TX_DN<3>")
	)
	(segment
		(start 115.647724 -284.938978)
		(end 115.64874 -284.939486)
		(width 0.1143)
		(layer "In13.Cu")
		(net "P5E_CPU1_P2_TX_DN<3>")
	)
	(segment
		(start 115.614196 -286.539178)
		(end 115.647724 -286.558736)
		(width 0.1143)
		(layer "In13.Cu")
		(net "P5E_CPU1_P2_TX_DN<3>")
	)
	(segment
		(start 115.615974 -273.580606)
		(end 115.646962 -273.598386)
		(width 0.1143)
		(layer "In13.Cu")
		(net "P5E_CPU1_P2_TX_DN<3>")
	)
	(segment
		(start 115.64874 -291.41928)
		(end 115.650264 -291.420296)
		(width 0.1143)
		(layer "In13.Cu")
		(net "P5E_CPU1_P2_TX_DN<3>")
	)
	(segment
		(start 115.68684 -293.990776)
		(end 115.650264 -294.012112)
		(width 0.1143)
		(layer "In13.Cu")
		(net "P5E_CPU1_P2_TX_DN<3>")
	)
	(segment
		(start 138.44016 -351.198942)
		(end 142.36827 -360.059224)
		(width 0.14224)
		(layer "In13.Cu")
		(net "P5E_CPU1_P2_TX_DN<3>")
	)
	(segment
		(start 115.647724 -294.013636)
		(end 115.646962 -294.014144)
		(width 0.1143)
		(layer "In13.Cu")
		(net "P5E_CPU1_P2_TX_DN<3>")
	)
	(segment
		(start 115.647724 -278.45893)
		(end 115.64874 -278.459438)
		(width 0.1143)
		(layer "In13.Cu")
		(net "P5E_CPU1_P2_TX_DN<3>")
	)
	(segment
		(start 115.646962 -276.194266)
		(end 115.645692 -276.195028)
		(width 0.1143)
		(layer "In13.Cu")
		(net "P5E_CPU1_P2_TX_DN<3>")
	)
	(segment
		(start 115.645692 -285.9151)
		(end 115.615974 -285.932118)
		(width 0.1143)
		(layer "In13.Cu")
		(net "P5E_CPU1_P2_TX_DN<3>")
	)
	(segment
		(start 115.650264 -284.940502)
		(end 115.68684 -284.961838)
		(width 0.1143)
		(layer "In13.Cu")
		(net "P5E_CPU1_P2_TX_DN<3>")
	)
	(segment
		(start 115.646962 -291.418264)
		(end 115.647724 -291.418772)
		(width 0.1143)
		(layer "In13.Cu")
		(net "P5E_CPU1_P2_TX_DN<3>")
	)
	(segment
		(start 115.646962 -280.078434)
		(end 115.647724 -280.078942)
		(width 0.1143)
		(layer "In13.Cu")
		(net "P5E_CPU1_P2_TX_DN<3>")
	)
	(segment
		(start 115.645692 -274.575016)
		(end 115.615974 -274.592034)
		(width 0.1143)
		(layer "In13.Cu")
		(net "P5E_CPU1_P2_TX_DN<3>")
	)
	(segment
		(start 115.647724 -275.218906)
		(end 115.64874 -275.219414)
		(width 0.1143)
		(layer "In13.Cu")
		(net "P5E_CPU1_P2_TX_DN<3>")
	)
	(segment
		(start 115.615974 -275.200618)
		(end 115.646962 -275.218398)
		(width 0.1143)
		(layer "In13.Cu")
		(net "P5E_CPU1_P2_TX_DN<3>")
	)
	(segment
		(start 115.645692 -279.435052)
		(end 115.615974 -279.45207)
		(width 0.1143)
		(layer "In13.Cu")
		(net "P5E_CPU1_P2_TX_DN<3>")
	)
	(segment
		(start 116.087144 -295.451022)
		(end 116.15674 -295.491662)
		(width 0.1143)
		(layer "In13.Cu")
		(net "P5E_CPU1_P2_TX_DN<3>")
	)
	(segment
		(start 115.645692 -294.014906)
		(end 115.615974 -294.031924)
		(width 0.1143)
		(layer "In13.Cu")
		(net "P5E_CPU1_P2_TX_DN<3>")
	)
	(segment
		(start 115.6843 -287.512506)
		(end 115.647724 -287.533842)
		(width 0.1143)
		(layer "In13.Cu")
		(net "P5E_CPU1_P2_TX_DN<3>")
	)
	(arc
		(start 115.615974 -292.411912)
		(mid 115.460046 -292.716204)
		(end 115.615974 -293.020496)
		(width 0.1143)
		(layer "In13.Cu")
		(net "P5E_CPU1_P2_TX_DN<3>")
	)
	(arc
		(start 115.615974 -285.932118)
		(mid 115.501298 -286.065452)
		(end 115.460018 -286.23641)
		(width 0.1143)
		(layer "In13.Cu")
		(net "P5E_CPU1_P2_TX_DN<3>")
	)
	(arc
		(start 115.615974 -274.592034)
		(mid 115.460046 -274.896326)
		(end 115.615974 -275.200618)
		(width 0.1143)
		(layer "In13.Cu")
		(net "P5E_CPU1_P2_TX_DN<3>")
	)
	(arc
		(start 115.68684 -275.241766)
		(mid 115.930167 -275.706332)
		(end 115.68684 -276.170898)
		(width 0.1143)
		(layer "In13.Cu")
		(net "P5E_CPU1_P2_TX_DN<3>")
	)
	(arc
		(start 115.68684 -278.48179)
		(mid 115.930167 -278.946356)
		(end 115.68684 -279.410922)
		(width 0.1143)
		(layer "In13.Cu")
		(net "P5E_CPU1_P2_TX_DN<3>")
	)
	(arc
		(start 115.68684 -284.961838)
		(mid 115.930167 -285.426404)
		(end 115.68684 -285.89097)
		(width 0.1143)
		(layer "In13.Cu")
		(net "P5E_CPU1_P2_TX_DN<3>")
	)
	(arc
		(start 115.68684 -288.201608)
		(mid 115.930167 -288.666174)
		(end 115.68684 -289.13074)
		(width 0.1143)
		(layer "In13.Cu")
		(net "P5E_CPU1_P2_TX_DN<3>")
	)
	(arc
		(start 115.460018 -286.23641)
		(mid 115.50078 -286.406294)
		(end 115.614196 -286.539178)
		(width 0.1143)
		(layer "In13.Cu")
		(net "P5E_CPU1_P2_TX_DN<3>")
	)
	(arc
		(start 115.216686 -272.811748)
		(mid 115.395499 -273.014098)
		(end 115.460018 -273.276314)
		(width 0.1143)
		(layer "In13.Cu")
		(net "P5E_CPU1_P2_TX_DN<3>")
	)
	(arc
		(start 115.68684 -283.341826)
		(mid 115.930167 -283.806392)
		(end 115.68684 -284.270958)
		(width 0.1143)
		(layer "In13.Cu")
		(net "P5E_CPU1_P2_TX_DN<3>")
	)
	(arc
		(start 114.996976 -272.536158)
		(mid 115.049393 -272.668089)
		(end 115.14709 -272.771108)
		(width 0.1143)
		(layer "In13.Cu")
		(net "P5E_CPU1_P2_TX_DN<3>")
	)
	(arc
		(start 115.68684 -289.82162)
		(mid 115.930167 -290.286186)
		(end 115.68684 -290.750752)
		(width 0.1143)
		(layer "In13.Cu")
		(net "P5E_CPU1_P2_TX_DN<3>")
	)
	(arc
		(start 115.930172 -295.146222)
		(mid 115.971721 -295.317644)
		(end 116.087144 -295.451022)
		(width 0.1143)
		(layer "In13.Cu")
		(net "P5E_CPU1_P2_TX_DN<3>")
	)
	(arc
		(start 115.68684 -276.861778)
		(mid 115.930167 -277.326344)
		(end 115.68684 -277.79091)
		(width 0.1143)
		(layer "In13.Cu")
		(net "P5E_CPU1_P2_TX_DN<3>")
	)
	(arc
		(start 115.615974 -290.7919)
		(mid 115.460046 -291.096192)
		(end 115.615974 -291.400484)
		(width 0.1143)
		(layer "In13.Cu")
		(net "P5E_CPU1_P2_TX_DN<3>")
	)
	(arc
		(start 115.615974 -279.45207)
		(mid 115.460046 -279.756362)
		(end 115.615974 -280.060654)
		(width 0.1143)
		(layer "In13.Cu")
		(net "P5E_CPU1_P2_TX_DN<3>")
	)
	(arc
		(start 115.68684 -293.061644)
		(mid 115.930167 -293.52621)
		(end 115.68684 -293.990776)
		(width 0.1143)
		(layer "In13.Cu")
		(net "P5E_CPU1_P2_TX_DN<3>")
	)
	(arc
		(start 115.615974 -281.072082)
		(mid 115.460046 -281.376374)
		(end 115.615974 -281.680666)
		(width 0.1143)
		(layer "In13.Cu")
		(net "P5E_CPU1_P2_TX_DN<3>")
	)
	(arc
		(start 115.460018 -273.276314)
		(mid 115.501273 -273.447285)
		(end 115.615974 -273.580606)
		(width 0.1143)
		(layer "In13.Cu")
		(net "P5E_CPU1_P2_TX_DN<3>")
	)
	(arc
		(start 115.460018 -287.856422)
		(mid 115.50078 -288.026306)
		(end 115.614196 -288.15919)
		(width 0.1143)
		(layer "In13.Cu")
		(net "P5E_CPU1_P2_TX_DN<3>")
	)
	(arc
		(start 116.15674 -295.491662)
		(mid 116.335497 -295.693755)
		(end 116.400072 -295.95572)
		(width 0.1143)
		(layer "In13.Cu")
		(net "P5E_CPU1_P2_TX_DN<3>")
	)
	(arc
		(start 115.68684 -273.621754)
		(mid 115.930167 -274.08632)
		(end 115.68684 -274.550886)
		(width 0.1143)
		(layer "In13.Cu")
		(net "P5E_CPU1_P2_TX_DN<3>")
	)
	(arc
		(start 115.615974 -289.171888)
		(mid 115.460046 -289.47618)
		(end 115.615974 -289.780472)
		(width 0.1143)
		(layer "In13.Cu")
		(net "P5E_CPU1_P2_TX_DN<3>")
	)
	(arc
		(start 115.68684 -281.721814)
		(mid 115.930167 -282.18638)
		(end 115.68684 -282.650946)
		(width 0.1143)
		(layer "In13.Cu")
		(net "P5E_CPU1_P2_TX_DN<3>")
	)
	(arc
		(start 115.615974 -294.031924)
		(mid 115.460046 -294.336216)
		(end 115.615974 -294.640508)
		(width 0.1143)
		(layer "In13.Cu")
		(net "P5E_CPU1_P2_TX_DN<3>")
	)
	(arc
		(start 115.68684 -294.681656)
		(mid 115.865653 -294.884006)
		(end 115.930172 -295.146222)
		(width 0.1143)
		(layer "In13.Cu")
		(net "P5E_CPU1_P2_TX_DN<3>")
	)
	(arc
		(start 115.615974 -276.212046)
		(mid 115.460046 -276.516338)
		(end 115.615974 -276.82063)
		(width 0.1143)
		(layer "In13.Cu")
		(net "P5E_CPU1_P2_TX_DN<3>")
	)
	(arc
		(start 115.615974 -282.692094)
		(mid 115.460046 -282.996386)
		(end 115.615974 -283.300678)
		(width 0.1143)
		(layer "In13.Cu")
		(net "P5E_CPU1_P2_TX_DN<3>")
	)
	(arc
		(start 115.68684 -280.101802)
		(mid 115.930167 -280.566368)
		(end 115.68684 -281.030934)
		(width 0.1143)
		(layer "In13.Cu")
		(net "P5E_CPU1_P2_TX_DN<3>")
	)
	(arc
		(start 115.68684 -286.581596)
		(mid 115.865653 -286.783946)
		(end 115.930172 -287.046162)
		(width 0.1143)
		(layer "In13.Cu")
		(net "P5E_CPU1_P2_TX_DN<3>")
	)
	(arc
		(start 115.68684 -291.441632)
		(mid 115.930167 -291.906198)
		(end 115.68684 -292.370764)
		(width 0.1143)
		(layer "In13.Cu")
		(net "P5E_CPU1_P2_TX_DN<3>")
	)
	(arc
		(start 115.615974 -284.312106)
		(mid 115.460046 -284.616398)
		(end 115.615974 -284.92069)
		(width 0.1143)
		(layer "In13.Cu")
		(net "P5E_CPU1_P2_TX_DN<3>")
	)
	(arc
		(start 115.615974 -287.55213)
		(mid 115.501298 -287.685464)
		(end 115.460018 -287.856422)
		(width 0.1143)
		(layer "In13.Cu")
		(net "P5E_CPU1_P2_TX_DN<3>")
	)
	(arc
		(start 115.615974 -277.832058)
		(mid 115.460046 -278.13635)
		(end 115.615974 -278.440642)
		(width 0.1143)
		(layer "In13.Cu")
		(net "P5E_CPU1_P2_TX_DN<3>")
	)
	(arc
		(start 115.930172 -287.046162)
		(mid 115.864936 -287.309753)
		(end 115.6843 -287.512506)
		(width 0.1143)
		(layer "In13.Cu")
		(net "P5E_CPU1_P2_TX_DN<3>")
	)
	(segment
		(start 143.235934 -372.47322)
		(end 143.531844 -372.76913)
		(width 0.12954)
		(layer "F.Cu")
		(net "P5E_CPU1_P2_TX_DN<2>")
	)
	(segment
		(start 114.897916 -273.820382)
		(end 115.364768 -274.08632)
		(width 0.12954)
		(layer "F.Cu")
		(net "P5E_CPU1_P2_TX_DN<2>")
	)
	(segment
		(start 143.506444 -371.49913)
		(end 143.235934 -371.76964)
		(width 0.12954)
		(layer "F.Cu")
		(net "P5E_CPU1_P2_TX_DN<2>")
	)
	(segment
		(start 143.235934 -371.76964)
		(end 143.235934 -372.47322)
		(width 0.12954)
		(layer "F.Cu")
		(net "P5E_CPU1_P2_TX_DN<2>")
	)
	(segment
		(start 114.701574 -292.39718)
		(end 114.700558 -292.397688)
		(width 0.1143)
		(layer "In13.Cu")
		(net "P5E_CPU1_P2_TX_DN<2>")
	)
	(segment
		(start 115.066826 -274.08632)
		(end 114.984022 -274.169124)
		(width 0.1143)
		(layer "In13.Cu")
		(net "P5E_CPU1_P2_TX_DN<2>")
	)
	(segment
		(start 114.711226 -293.040816)
		(end 114.713766 -293.04234)
		(width 0.1143)
		(layer "In13.Cu")
		(net "P5E_CPU1_P2_TX_DN<2>")
	)
	(segment
		(start 114.746786 -279.410922)
		(end 114.70767 -279.433782)
		(width 0.1143)
		(layer "In13.Cu")
		(net "P5E_CPU1_P2_TX_DN<2>")
	)
	(segment
		(start 114.746786 -277.79091)
		(end 114.70767 -277.81377)
		(width 0.1143)
		(layer "In13.Cu")
		(net "P5E_CPU1_P2_TX_DN<2>")
	)
	(segment
		(start 114.70767 -287.533842)
		(end 114.67592 -287.55213)
		(width 0.1143)
		(layer "In13.Cu")
		(net "P5E_CPU1_P2_TX_DN<2>")
	)
	(segment
		(start 114.746786 -292.370764)
		(end 114.71021 -292.3921)
		(width 0.1143)
		(layer "In13.Cu")
		(net "P5E_CPU1_P2_TX_DN<2>")
	)
	(segment
		(start 114.67592 -289.171888)
		(end 114.671602 -289.174936)
		(width 0.1143)
		(layer "In13.Cu")
		(net "P5E_CPU1_P2_TX_DN<2>")
	)
	(segment
		(start 114.70767 -293.038784)
		(end 114.708686 -293.039292)
		(width 0.1143)
		(layer "In13.Cu")
		(net "P5E_CPU1_P2_TX_DN<2>")
	)
	(segment
		(start 114.700558 -294.005254)
		(end 114.671094 -294.025066)
		(width 0.1143)
		(layer "In13.Cu")
		(net "P5E_CPU1_P2_TX_DN<2>")
	)
	(segment
		(start 114.703352 -292.396164)
		(end 114.702336 -292.396672)
		(width 0.1143)
		(layer "In13.Cu")
		(net "P5E_CPU1_P2_TX_DN<2>")
	)
	(segment
		(start 114.71021 -293.040308)
		(end 114.711226 -293.040816)
		(width 0.1143)
		(layer "In13.Cu")
		(net "P5E_CPU1_P2_TX_DN<2>")
	)
	(segment
		(start 114.746786 -274.550886)
		(end 114.70767 -274.573746)
		(width 0.1143)
		(layer "In13.Cu")
		(net "P5E_CPU1_P2_TX_DN<2>")
	)
	(segment
		(start 114.708686 -292.393116)
		(end 114.70767 -292.393624)
		(width 0.1143)
		(layer "In13.Cu")
		(net "P5E_CPU1_P2_TX_DN<2>")
	)
	(segment
		(start 114.748818 -285.8897)
		(end 114.705384 -285.914846)
		(width 0.1143)
		(layer "In13.Cu")
		(net "P5E_CPU1_P2_TX_DN<2>")
	)
	(segment
		(start 114.710464 -283.320744)
		(end 114.738658 -283.337)
		(width 0.1143)
		(layer "In13.Cu")
		(net "P5E_CPU1_P2_TX_DN<2>")
	)
	(segment
		(start 114.70767 -278.45893)
		(end 114.746786 -278.48179)
		(width 0.1143)
		(layer "In13.Cu")
		(net "P5E_CPU1_P2_TX_DN<2>")
	)
	(segment
		(start 114.713766 -293.04234)
		(end 114.71529 -293.043356)
		(width 0.1143)
		(layer "In13.Cu")
		(net "P5E_CPU1_P2_TX_DN<2>")
	)
	(segment
		(start 114.706908 -280.078434)
		(end 114.70767 -280.078942)
		(width 0.1143)
		(layer "In13.Cu")
		(net "P5E_CPU1_P2_TX_DN<2>")
	)
	(segment
		(start 137.551922 -351.597468)
		(end 143.215614 -370.268754)
		(width 0.14224)
		(layer "In13.Cu")
		(net "P5E_CPU1_P2_TX_DN<2>")
	)
	(segment
		(start 115.14709 -295.451022)
		(end 115.17757 -295.468802)
		(width 0.1143)
		(layer "In13.Cu")
		(net "P5E_CPU1_P2_TX_DN<2>")
	)
	(segment
		(start 114.746786 -282.650946)
		(end 114.7064 -282.674568)
		(width 0.1143)
		(layer "In13.Cu")
		(net "P5E_CPU1_P2_TX_DN<2>")
	)
	(segment
		(start 118.221506 -303.86782)
		(end 127.706628 -316.655704)
		(width 0.14224)
		(layer "In13.Cu")
		(net "P5E_CPU1_P2_TX_DN<2>")
	)
	(segment
		(start 114.700812 -284.935168)
		(end 114.702082 -284.935676)
		(width 0.1143)
		(layer "In13.Cu")
		(net "P5E_CPU1_P2_TX_DN<2>")
	)
	(segment
		(start 114.73942 -283.337508)
		(end 114.746024 -283.341318)
		(width 0.1143)
		(layer "In13.Cu")
		(net "P5E_CPU1_P2_TX_DN<2>")
	)
	(segment
		(start 114.702082 -284.29712)
		(end 114.700812 -284.297628)
		(width 0.1143)
		(layer "In13.Cu")
		(net "P5E_CPU1_P2_TX_DN<2>")
	)
	(segment
		(start 143.215614 -371.2083)
		(end 143.506444 -371.49913)
		(width 0.14224)
		(layer "In13.Cu")
		(net "P5E_CPU1_P2_TX_DN<2>")
	)
	(segment
		(start 114.71529 -293.043356)
		(end 114.74704 -293.061644)
		(width 0.1143)
		(layer "In13.Cu")
		(net "P5E_CPU1_P2_TX_DN<2>")
	)
	(segment
		(start 114.67592 -278.440642)
		(end 114.70767 -278.45893)
		(width 0.1143)
		(layer "In13.Cu")
		(net "P5E_CPU1_P2_TX_DN<2>")
	)
	(segment
		(start 114.7064 -282.674568)
		(end 114.699034 -282.678632)
		(width 0.1143)
		(layer "In13.Cu")
		(net "P5E_CPU1_P2_TX_DN<2>")
	)
	(segment
		(start 114.705384 -285.914846)
		(end 114.70386 -285.915862)
		(width 0.1143)
		(layer "In13.Cu")
		(net "P5E_CPU1_P2_TX_DN<2>")
	)
	(segment
		(start 114.7064 -283.318204)
		(end 114.70894 -283.319728)
		(width 0.1143)
		(layer "In13.Cu")
		(net "P5E_CPU1_P2_TX_DN<2>")
	)
	(segment
		(start 114.70767 -276.193758)
		(end 114.67592 -276.212046)
		(width 0.1143)
		(layer "In13.Cu")
		(net "P5E_CPU1_P2_TX_DN<2>")
	)
	(segment
		(start 115.505738 -296.327068)
		(end 115.505738 -298.246292)
		(width 0.14224)
		(layer "In13.Cu")
		(net "P5E_CPU1_P2_TX_DN<2>")
	)
	(segment
		(start 132.245862 -324.92442)
		(end 137.551922 -351.597468)
		(width 0.14224)
		(layer "In13.Cu")
		(net "P5E_CPU1_P2_TX_DN<2>")
	)
	(segment
		(start 114.67592 -280.060654)
		(end 114.706908 -280.078434)
		(width 0.1143)
		(layer "In13.Cu")
		(net "P5E_CPU1_P2_TX_DN<2>")
	)
	(segment
		(start 114.67592 -293.020496)
		(end 114.706908 -293.038276)
		(width 0.1143)
		(layer "In13.Cu")
		(net "P5E_CPU1_P2_TX_DN<2>")
	)
	(segment
		(start 114.706908 -292.394132)
		(end 114.705638 -292.394894)
		(width 0.1143)
		(layer "In13.Cu")
		(net "P5E_CPU1_P2_TX_DN<2>")
	)
	(segment
		(start 114.708686 -280.07945)
		(end 114.746786 -280.101802)
		(width 0.1143)
		(layer "In13.Cu")
		(net "P5E_CPU1_P2_TX_DN<2>")
	)
	(segment
		(start 115.364768 -274.08632)
		(end 115.066826 -274.08632)
		(width 0.1143)
		(layer "In13.Cu")
		(net "P5E_CPU1_P2_TX_DN<2>")
	)
	(segment
		(start 114.746786 -281.030934)
		(end 114.70767 -281.053794)
		(width 0.1143)
		(layer "In13.Cu")
		(net "P5E_CPU1_P2_TX_DN<2>")
	)
	(segment
		(start 114.70767 -281.053794)
		(end 114.69624 -281.060144)
		(width 0.1143)
		(layer "In13.Cu")
		(net "P5E_CPU1_P2_TX_DN<2>")
	)
	(segment
		(start 114.70767 -292.393624)
		(end 114.706908 -292.394132)
		(width 0.1143)
		(layer "In13.Cu")
		(net "P5E_CPU1_P2_TX_DN<2>")
	)
	(segment
		(start 114.690652 -294.649144)
		(end 114.746024 -294.681148)
		(width 0.1143)
		(layer "In13.Cu")
		(net "P5E_CPU1_P2_TX_DN<2>")
	)
	(segment
		(start 114.70767 -289.1536)
		(end 114.67592 -289.171888)
		(width 0.1143)
		(layer "In13.Cu")
		(net "P5E_CPU1_P2_TX_DN<2>")
	)
	(segment
		(start 114.701066 -294.005)
		(end 114.700558 -294.005254)
		(width 0.1143)
		(layer "In13.Cu")
		(net "P5E_CPU1_P2_TX_DN<2>")
	)
	(segment
		(start 114.744246 -287.512506)
		(end 114.70767 -287.533842)
		(width 0.1143)
		(layer "In13.Cu")
		(net "P5E_CPU1_P2_TX_DN<2>")
	)
	(segment
		(start 114.705638 -292.394894)
		(end 114.704114 -292.395656)
		(width 0.1143)
		(layer "In13.Cu")
		(net "P5E_CPU1_P2_TX_DN<2>")
	)
	(segment
		(start 114.674142 -288.15919)
		(end 114.746786 -288.201608)
		(width 0.1143)
		(layer "In13.Cu")
		(net "P5E_CPU1_P2_TX_DN<2>")
	)
	(segment
		(start 114.70767 -275.218906)
		(end 114.746786 -275.241766)
		(width 0.1143)
		(layer "In13.Cu")
		(net "P5E_CPU1_P2_TX_DN<2>")
	)
	(segment
		(start 114.738658 -283.337)
		(end 114.73942 -283.337508)
		(width 0.1143)
		(layer "In13.Cu")
		(net "P5E_CPU1_P2_TX_DN<2>")
	)
	(segment
		(start 114.70767 -276.838918)
		(end 114.746786 -276.861778)
		(width 0.1143)
		(layer "In13.Cu")
		(net "P5E_CPU1_P2_TX_DN<2>")
	)
	(segment
		(start 114.70767 -277.81377)
		(end 114.67592 -277.832058)
		(width 0.1143)
		(layer "In13.Cu")
		(net "P5E_CPU1_P2_TX_DN<2>")
	)
	(segment
		(start 114.702336 -292.396672)
		(end 114.701574 -292.39718)
		(width 0.1143)
		(layer "In13.Cu")
		(net "P5E_CPU1_P2_TX_DN<2>")
	)
	(segment
		(start 114.67592 -291.400484)
		(end 114.70767 -291.418772)
		(width 0.1143)
		(layer "In13.Cu")
		(net "P5E_CPU1_P2_TX_DN<2>")
	)
	(segment
		(start 115.17757 -295.468802)
		(end 115.216686 -295.491662)
		(width 0.1143)
		(layer "In13.Cu")
		(net "P5E_CPU1_P2_TX_DN<2>")
	)
	(segment
		(start 114.67592 -275.200618)
		(end 114.70767 -275.218906)
		(width 0.1143)
		(layer "In13.Cu")
		(net "P5E_CPU1_P2_TX_DN<2>")
	)
	(segment
		(start 114.70767 -279.433782)
		(end 114.67592 -279.45207)
		(width 0.1143)
		(layer "In13.Cu")
		(net "P5E_CPU1_P2_TX_DN<2>")
	)
	(segment
		(start 143.215614 -370.268754)
		(end 143.215614 -371.2083)
		(width 0.14224)
		(layer "In13.Cu")
		(net "P5E_CPU1_P2_TX_DN<2>")
	)
	(segment
		(start 114.70894 -283.319728)
		(end 114.710464 -283.320744)
		(width 0.1143)
		(layer "In13.Cu")
		(net "P5E_CPU1_P2_TX_DN<2>")
	)
	(segment
		(start 115.505738 -296.29862)
		(end 115.505738 -296.327068)
		(width 0.1143)
		(layer "In13.Cu")
		(net "P5E_CPU1_P2_TX_DN<2>")
	)
	(segment
		(start 114.702082 -284.935676)
		(end 114.746024 -284.96133)
		(width 0.1143)
		(layer "In13.Cu")
		(net "P5E_CPU1_P2_TX_DN<2>")
	)
	(segment
		(start 114.70767 -290.773612)
		(end 114.67592 -290.7919)
		(width 0.1143)
		(layer "In13.Cu")
		(net "P5E_CPU1_P2_TX_DN<2>")
	)
	(segment
		(start 114.746786 -276.170898)
		(end 114.70767 -276.193758)
		(width 0.1143)
		(layer "In13.Cu")
		(net "P5E_CPU1_P2_TX_DN<2>")
	)
	(segment
		(start 114.710718 -284.29204)
		(end 114.702082 -284.29712)
		(width 0.1143)
		(layer "In13.Cu")
		(net "P5E_CPU1_P2_TX_DN<2>")
	)
	(segment
		(start 114.519964 -287.853374)
		(end 114.519964 -287.856422)
		(width 0.1143)
		(layer "In13.Cu")
		(net "P5E_CPU1_P2_TX_DN<2>")
	)
	(segment
		(start 114.700558 -292.397688)
		(end 114.67592 -292.411912)
		(width 0.1143)
		(layer "In13.Cu")
		(net "P5E_CPU1_P2_TX_DN<2>")
	)
	(segment
		(start 114.708686 -293.039292)
		(end 114.71021 -293.040308)
		(width 0.1143)
		(layer "In13.Cu")
		(net "P5E_CPU1_P2_TX_DN<2>")
	)
	(segment
		(start 114.71021 -292.3921)
		(end 114.708686 -292.393116)
		(width 0.1143)
		(layer "In13.Cu")
		(net "P5E_CPU1_P2_TX_DN<2>")
	)
	(segment
		(start 114.704114 -292.395656)
		(end 114.703352 -292.396164)
		(width 0.1143)
		(layer "In13.Cu")
		(net "P5E_CPU1_P2_TX_DN<2>")
	)
	(segment
		(start 114.69624 -281.692604)
		(end 114.746024 -281.721306)
		(width 0.1143)
		(layer "In13.Cu")
		(net "P5E_CPU1_P2_TX_DN<2>")
	)
	(segment
		(start 114.746786 -289.13074)
		(end 114.70767 -289.1536)
		(width 0.1143)
		(layer "In13.Cu")
		(net "P5E_CPU1_P2_TX_DN<2>")
	)
	(segment
		(start 114.748818 -286.58312)
		(end 114.748818 -286.582866)
		(width 0.1143)
		(layer "In13.Cu")
		(net "P5E_CPU1_P2_TX_DN<2>")
	)
	(segment
		(start 115.460018 -295.956228)
		(end 115.460018 -296.2529)
		(width 0.1143)
		(layer "In13.Cu")
		(net "P5E_CPU1_P2_TX_DN<2>")
	)
	(segment
		(start 114.67592 -276.82063)
		(end 114.70767 -276.838918)
		(width 0.1143)
		(layer "In13.Cu")
		(net "P5E_CPU1_P2_TX_DN<2>")
	)
	(segment
		(start 115.505738 -298.246292)
		(end 116.968524 -301.778162)
		(width 0.14224)
		(layer "In13.Cu")
		(net "P5E_CPU1_P2_TX_DN<2>")
	)
	(segment
		(start 114.70767 -291.418772)
		(end 114.746786 -291.441632)
		(width 0.1143)
		(layer "In13.Cu")
		(net "P5E_CPU1_P2_TX_DN<2>")
	)
	(segment
		(start 115.460018 -296.2529)
		(end 115.505738 -296.29862)
		(width 0.1143)
		(layer "In13.Cu")
		(net "P5E_CPU1_P2_TX_DN<2>")
	)
	(segment
		(start 114.67592 -289.780472)
		(end 114.746786 -289.82162)
		(width 0.1143)
		(layer "In13.Cu")
		(net "P5E_CPU1_P2_TX_DN<2>")
	)
	(segment
		(start 114.699034 -283.31414)
		(end 114.7064 -283.318204)
		(width 0.1143)
		(layer "In13.Cu")
		(net "P5E_CPU1_P2_TX_DN<2>")
	)
	(segment
		(start 114.746786 -290.750752)
		(end 114.70767 -290.773612)
		(width 0.1143)
		(layer "In13.Cu")
		(net "P5E_CPU1_P2_TX_DN<2>")
	)
	(segment
		(start 114.706146 -294.001952)
		(end 114.701066 -294.005)
		(width 0.1143)
		(layer "In13.Cu")
		(net "P5E_CPU1_P2_TX_DN<2>")
	)
	(segment
		(start 114.705892 -286.558228)
		(end 114.748818 -286.58312)
		(width 0.1143)
		(layer "In13.Cu")
		(net "P5E_CPU1_P2_TX_DN<2>")
	)
	(segment
		(start 114.70767 -274.573746)
		(end 114.67592 -274.592034)
		(width 0.1143)
		(layer "In13.Cu")
		(net "P5E_CPU1_P2_TX_DN<2>")
	)
	(segment
		(start 114.703606 -286.556958)
		(end 114.705892 -286.558228)
		(width 0.1143)
		(layer "In13.Cu")
		(net "P5E_CPU1_P2_TX_DN<2>")
	)
	(segment
		(start 114.723418 -293.992046)
		(end 114.706146 -294.001952)
		(width 0.1143)
		(layer "In13.Cu")
		(net "P5E_CPU1_P2_TX_DN<2>")
	)
	(segment
		(start 128.302004 -317.546736)
		(end 132.245862 -324.92442)
		(width 0.14224)
		(layer "In13.Cu")
		(net "P5E_CPU1_P2_TX_DN<2>")
	)
	(segment
		(start 114.67592 -287.55213)
		(end 114.673126 -287.554162)
		(width 0.1143)
		(layer "In13.Cu")
		(net "P5E_CPU1_P2_TX_DN<2>")
	)
	(segment
		(start 114.706908 -293.038276)
		(end 114.70767 -293.038784)
		(width 0.1143)
		(layer "In13.Cu")
		(net "P5E_CPU1_P2_TX_DN<2>")
	)
	(segment
		(start 114.746786 -284.961838)
		(end 114.748818 -284.963108)
		(width 0.1143)
		(layer "In13.Cu")
		(net "P5E_CPU1_P2_TX_DN<2>")
	)
	(segment
		(start 114.712242 -284.291024)
		(end 114.710718 -284.29204)
		(width 0.1143)
		(layer "In13.Cu")
		(net "P5E_CPU1_P2_TX_DN<2>")
	)
	(segment
		(start 114.746786 -284.270958)
		(end 114.712242 -284.291024)
		(width 0.1143)
		(layer "In13.Cu")
		(net "P5E_CPU1_P2_TX_DN<2>")
	)
	(segment
		(start 127.706628 -316.655704)
		(end 128.302004 -317.546736)
		(width 0.14224)
		(layer "In13.Cu")
		(net "P5E_CPU1_P2_TX_DN<2>")
	)
	(segment
		(start 114.74704 -293.061644)
		(end 114.769138 -293.077392)
		(width 0.1143)
		(layer "In13.Cu")
		(net "P5E_CPU1_P2_TX_DN<2>")
	)
	(segment
		(start 114.671602 -289.777424)
		(end 114.67592 -289.780472)
		(width 0.1143)
		(layer "In13.Cu")
		(net "P5E_CPU1_P2_TX_DN<2>")
	)
	(segment
		(start 116.968524 -301.778162)
		(end 118.221506 -303.86782)
		(width 0.14224)
		(layer "In13.Cu")
		(net "P5E_CPU1_P2_TX_DN<2>")
	)
	(segment
		(start 114.70767 -280.078942)
		(end 114.708686 -280.07945)
		(width 0.1143)
		(layer "In13.Cu")
		(net "P5E_CPU1_P2_TX_DN<2>")
	)
	(arc
		(start 114.980212 -274.191984)
		(mid 114.898779 -274.394382)
		(end 114.746786 -274.550886)
		(width 0.1143)
		(layer "In13.Cu")
		(net "P5E_CPU1_P2_TX_DN<2>")
	)
	(arc
		(start 114.519964 -287.856422)
		(mid 114.560726 -288.026306)
		(end 114.674142 -288.15919)
		(width 0.1143)
		(layer "In13.Cu")
		(net "P5E_CPU1_P2_TX_DN<2>")
	)
	(arc
		(start 114.746024 -281.721306)
		(mid 114.746405 -281.72156)
		(end 114.746786 -281.721814)
		(width 0.1143)
		(layer "In13.Cu")
		(net "P5E_CPU1_P2_TX_DN<2>")
	)
	(arc
		(start 114.746786 -280.101802)
		(mid 114.990113 -280.566368)
		(end 114.746786 -281.030934)
		(width 0.1143)
		(layer "In13.Cu")
		(net "P5E_CPU1_P2_TX_DN<2>")
	)
	(arc
		(start 114.67592 -277.832058)
		(mid 114.524331 -278.13635)
		(end 114.67592 -278.440642)
		(width 0.1143)
		(layer "In13.Cu")
		(net "P5E_CPU1_P2_TX_DN<2>")
	)
	(arc
		(start 115.216686 -295.491662)
		(mid 115.395561 -295.69398)
		(end 115.460018 -295.956228)
		(width 0.1143)
		(layer "In13.Cu")
		(net "P5E_CPU1_P2_TX_DN<2>")
	)
	(arc
		(start 114.746786 -278.48179)
		(mid 114.990113 -278.946356)
		(end 114.746786 -279.410922)
		(width 0.1143)
		(layer "In13.Cu")
		(net "P5E_CPU1_P2_TX_DN<2>")
	)
	(arc
		(start 114.700812 -284.297628)
		(mid 114.520327 -284.616398)
		(end 114.700812 -284.935168)
		(width 0.1143)
		(layer "In13.Cu")
		(net "P5E_CPU1_P2_TX_DN<2>")
	)
	(arc
		(start 114.748818 -284.963108)
		(mid 114.991538 -285.426404)
		(end 114.748818 -285.8897)
		(width 0.1143)
		(layer "In13.Cu")
		(net "P5E_CPU1_P2_TX_DN<2>")
	)
	(arc
		(start 114.67592 -276.212046)
		(mid 114.524331 -276.516338)
		(end 114.67592 -276.82063)
		(width 0.1143)
		(layer "In13.Cu")
		(net "P5E_CPU1_P2_TX_DN<2>")
	)
	(arc
		(start 114.746024 -294.681148)
		(mid 114.746405 -294.681402)
		(end 114.746786 -294.681656)
		(width 0.1143)
		(layer "In13.Cu")
		(net "P5E_CPU1_P2_TX_DN<2>")
	)
	(arc
		(start 114.984022 -274.169124)
		(mid 114.982234 -274.180573)
		(end 114.980212 -274.191984)
		(width 0.1143)
		(layer "In13.Cu")
		(net "P5E_CPU1_P2_TX_DN<2>")
	)
	(arc
		(start 114.746786 -289.82162)
		(mid 114.990113 -290.286186)
		(end 114.746786 -290.750752)
		(width 0.1143)
		(layer "In13.Cu")
		(net "P5E_CPU1_P2_TX_DN<2>")
	)
	(arc
		(start 114.746786 -275.241766)
		(mid 114.990113 -275.706332)
		(end 114.746786 -276.170898)
		(width 0.1143)
		(layer "In13.Cu")
		(net "P5E_CPU1_P2_TX_DN<2>")
	)
	(arc
		(start 114.746024 -283.341318)
		(mid 114.746405 -283.341572)
		(end 114.746786 -283.341826)
		(width 0.1143)
		(layer "In13.Cu")
		(net "P5E_CPU1_P2_TX_DN<2>")
	)
	(arc
		(start 114.673126 -287.554162)
		(mid 114.560485 -287.685298)
		(end 114.519964 -287.853374)
		(width 0.1143)
		(layer "In13.Cu")
		(net "P5E_CPU1_P2_TX_DN<2>")
	)
	(arc
		(start 114.67592 -290.7919)
		(mid 114.526823 -291.096192)
		(end 114.67592 -291.400484)
		(width 0.1143)
		(layer "In13.Cu")
		(net "P5E_CPU1_P2_TX_DN<2>")
	)
	(arc
		(start 114.746786 -294.681656)
		(mid 114.925599 -294.884006)
		(end 114.990118 -295.146222)
		(width 0.1143)
		(layer "In13.Cu")
		(net "P5E_CPU1_P2_TX_DN<2>")
	)
	(arc
		(start 114.699034 -282.678632)
		(mid 114.516557 -282.996386)
		(end 114.699034 -283.31414)
		(width 0.1143)
		(layer "In13.Cu")
		(net "P5E_CPU1_P2_TX_DN<2>")
	)
	(arc
		(start 114.69624 -281.060144)
		(mid 114.514449 -281.376374)
		(end 114.69624 -281.692604)
		(width 0.1143)
		(layer "In13.Cu")
		(net "P5E_CPU1_P2_TX_DN<2>")
	)
	(arc
		(start 114.769138 -293.077392)
		(mid 114.995339 -293.54712)
		(end 114.723418 -293.992046)
		(width 0.1143)
		(layer "In13.Cu")
		(net "P5E_CPU1_P2_TX_DN<2>")
	)
	(arc
		(start 114.748818 -286.582866)
		(mid 114.990116 -287.048909)
		(end 114.744246 -287.512506)
		(width 0.1143)
		(layer "In13.Cu")
		(net "P5E_CPU1_P2_TX_DN<2>")
	)
	(arc
		(start 114.70386 -285.915862)
		(mid 114.520103 -286.2363)
		(end 114.703606 -286.556958)
		(width 0.1143)
		(layer "In13.Cu")
		(net "P5E_CPU1_P2_TX_DN<2>")
	)
	(arc
		(start 114.671094 -294.025066)
		(mid 114.507431 -294.342595)
		(end 114.690652 -294.649144)
		(width 0.1143)
		(layer "In13.Cu")
		(net "P5E_CPU1_P2_TX_DN<2>")
	)
	(arc
		(start 114.671602 -289.174936)
		(mid 114.517197 -289.47618)
		(end 114.671602 -289.777424)
		(width 0.1143)
		(layer "In13.Cu")
		(net "P5E_CPU1_P2_TX_DN<2>")
	)
	(arc
		(start 114.67592 -274.592034)
		(mid 114.524331 -274.896326)
		(end 114.67592 -275.200618)
		(width 0.1143)
		(layer "In13.Cu")
		(net "P5E_CPU1_P2_TX_DN<2>")
	)
	(arc
		(start 114.746786 -281.721814)
		(mid 114.990113 -282.18638)
		(end 114.746786 -282.650946)
		(width 0.1143)
		(layer "In13.Cu")
		(net "P5E_CPU1_P2_TX_DN<2>")
	)
	(arc
		(start 114.746786 -276.861778)
		(mid 114.990113 -277.326344)
		(end 114.746786 -277.79091)
		(width 0.1143)
		(layer "In13.Cu")
		(net "P5E_CPU1_P2_TX_DN<2>")
	)
	(arc
		(start 114.67592 -279.45207)
		(mid 114.524331 -279.756362)
		(end 114.67592 -280.060654)
		(width 0.1143)
		(layer "In13.Cu")
		(net "P5E_CPU1_P2_TX_DN<2>")
	)
	(arc
		(start 114.746786 -291.441632)
		(mid 114.990113 -291.906198)
		(end 114.746786 -292.370764)
		(width 0.1143)
		(layer "In13.Cu")
		(net "P5E_CPU1_P2_TX_DN<2>")
	)
	(arc
		(start 114.990118 -295.146222)
		(mid 115.031667 -295.317644)
		(end 115.14709 -295.451022)
		(width 0.1143)
		(layer "In13.Cu")
		(net "P5E_CPU1_P2_TX_DN<2>")
	)
	(arc
		(start 114.746024 -284.96133)
		(mid 114.746405 -284.961584)
		(end 114.746786 -284.961838)
		(width 0.1143)
		(layer "In13.Cu")
		(net "P5E_CPU1_P2_TX_DN<2>")
	)
	(arc
		(start 114.746786 -283.341826)
		(mid 114.990113 -283.806392)
		(end 114.746786 -284.270958)
		(width 0.1143)
		(layer "In13.Cu")
		(net "P5E_CPU1_P2_TX_DN<2>")
	)
	(arc
		(start 114.746786 -288.201608)
		(mid 114.990113 -288.666174)
		(end 114.746786 -289.13074)
		(width 0.1143)
		(layer "In13.Cu")
		(net "P5E_CPU1_P2_TX_DN<2>")
	)
	(arc
		(start 114.67592 -292.411912)
		(mid 114.519992 -292.716204)
		(end 114.67592 -293.020496)
		(width 0.1143)
		(layer "In13.Cu")
		(net "P5E_CPU1_P2_TX_DN<2>")
	)
	(segment
		(start 114.897916 -270.580358)
		(end 115.364768 -270.846296)
		(width 0.12954)
		(layer "F.Cu")
		(net "P5E_CPU1_P2_TX_DN<1>")
	)
	(segment
		(start 141.058392 -376.83186)
		(end 141.328902 -376.56135)
		(width 0.12954)
		(layer "F.Cu")
		(net "P5E_CPU1_P2_TX_DN<1>")
	)
	(segment
		(start 141.328902 -376.56135)
		(end 142.032482 -376.56135)
		(width 0.12954)
		(layer "F.Cu")
		(net "P5E_CPU1_P2_TX_DN<1>")
	)
	(segment
		(start 142.032482 -376.56135)
		(end 142.328392 -376.85726)
		(width 0.12954)
		(layer "F.Cu")
		(net "P5E_CPU1_P2_TX_DN<1>")
	)
	(segment
		(start 113.767616 -294.658796)
		(end 113.806732 -294.681656)
		(width 0.1143)
		(layer "In13.Cu")
		(net "P5E_CPU1_P2_TX_DN<1>")
	)
	(segment
		(start 114.233452 -272.146268)
		(end 114.231928 -272.14703)
		(width 0.1143)
		(layer "In13.Cu")
		(net "P5E_CPU1_P2_TX_DN<1>")
	)
	(segment
		(start 114.231928 -272.14703)
		(end 114.231166 -272.147538)
		(width 0.1143)
		(layer "In13.Cu")
		(net "P5E_CPU1_P2_TX_DN<1>")
	)
	(segment
		(start 113.806732 -293.990776)
		(end 113.767616 -294.013636)
		(width 0.1143)
		(layer "In13.Cu")
		(net "P5E_CPU1_P2_TX_DN<1>")
	)
	(segment
		(start 113.767616 -294.013636)
		(end 113.737136 -294.031416)
		(width 0.1143)
		(layer "In13.Cu")
		(net "P5E_CPU1_P2_TX_DN<1>")
	)
	(segment
		(start 113.76533 -282.67533)
		(end 113.764314 -282.675838)
		(width 0.1143)
		(layer "In13.Cu")
		(net "P5E_CPU1_P2_TX_DN<1>")
	)
	(segment
		(start 113.76406 -281.696922)
		(end 113.76533 -281.69743)
		(width 0.1143)
		(layer "In13.Cu")
		(net "P5E_CPU1_P2_TX_DN<1>")
	)
	(segment
		(start 115.066826 -270.846296)
		(end 114.984022 -270.9291)
		(width 0.1143)
		(layer "In13.Cu")
		(net "P5E_CPU1_P2_TX_DN<1>")
	)
	(segment
		(start 113.767616 -291.418772)
		(end 113.806732 -291.441632)
		(width 0.1143)
		(layer "In13.Cu")
		(net "P5E_CPU1_P2_TX_DN<1>")
	)
	(segment
		(start 113.73485 -280.059892)
		(end 113.806732 -280.101802)
		(width 0.1143)
		(layer "In13.Cu")
		(net "P5E_CPU1_P2_TX_DN<1>")
	)
	(segment
		(start 141.30909 -367.235232)
		(end 141.30909 -371.26672)
		(width 0.14224)
		(layer "In13.Cu")
		(net "P5E_CPU1_P2_TX_DN<1>")
	)
	(segment
		(start 113.806732 -290.750752)
		(end 113.767616 -290.773612)
		(width 0.1143)
		(layer "In13.Cu")
		(net "P5E_CPU1_P2_TX_DN<1>")
	)
	(segment
		(start 113.73612 -286.540448)
		(end 113.806732 -286.581596)
		(width 0.1143)
		(layer "In13.Cu")
		(net "P5E_CPU1_P2_TX_DN<1>")
	)
	(segment
		(start 113.732818 -280.058368)
		(end 113.73485 -280.059892)
		(width 0.1143)
		(layer "In13.Cu")
		(net "P5E_CPU1_P2_TX_DN<1>")
	)
	(segment
		(start 113.771426 -292.391338)
		(end 113.762028 -292.396926)
		(width 0.1143)
		(layer "In13.Cu")
		(net "P5E_CPU1_P2_TX_DN<1>")
	)
	(segment
		(start 141.983968 -376.54103)
		(end 141.349222 -376.54103)
		(width 0.14224)
		(layer "In13.Cu")
		(net "P5E_CPU1_P2_TX_DN<1>")
	)
	(segment
		(start 113.770664 -293.040562)
		(end 113.771426 -293.04107)
		(width 0.1143)
		(layer "In13.Cu")
		(net "P5E_CPU1_P2_TX_DN<1>")
	)
	(segment
		(start 113.760758 -293.034974)
		(end 113.762028 -293.035482)
		(width 0.1143)
		(layer "In13.Cu")
		(net "P5E_CPU1_P2_TX_DN<1>")
	)
	(segment
		(start 113.772188 -289.151314)
		(end 113.772188 -289.15106)
		(width 0.1143)
		(layer "In13.Cu")
		(net "P5E_CPU1_P2_TX_DN<1>")
	)
	(segment
		(start 113.787174 -289.141662)
		(end 113.786666 -289.141916)
		(width 0.1143)
		(layer "In13.Cu")
		(net "P5E_CPU1_P2_TX_DN<1>")
	)
	(segment
		(start 113.767616 -276.193758)
		(end 113.737136 -276.211538)
		(width 0.1143)
		(layer "In13.Cu")
		(net "P5E_CPU1_P2_TX_DN<1>")
	)
	(segment
		(start 113.76533 -283.317442)
		(end 113.768886 -283.319728)
		(width 0.1143)
		(layer "In13.Cu")
		(net "P5E_CPU1_P2_TX_DN<1>")
	)
	(segment
		(start 113.804192 -287.512506)
		(end 113.740184 -287.54959)
		(width 0.1143)
		(layer "In13.Cu")
		(net "P5E_CPU1_P2_TX_DN<1>")
	)
	(segment
		(start 113.737136 -291.400992)
		(end 113.767616 -291.418772)
		(width 0.1143)
		(layer "In13.Cu")
		(net "P5E_CPU1_P2_TX_DN<1>")
	)
	(segment
		(start 113.737136 -273.581114)
		(end 113.767616 -273.598894)
		(width 0.1143)
		(layer "In13.Cu")
		(net "P5E_CPU1_P2_TX_DN<1>")
	)
	(segment
		(start 113.762028 -292.396926)
		(end 113.760758 -292.397434)
		(width 0.1143)
		(layer "In13.Cu")
		(net "P5E_CPU1_P2_TX_DN<1>")
	)
	(segment
		(start 114.746786 -271.310862)
		(end 114.70767 -271.333722)
		(width 0.1143)
		(layer "In13.Cu")
		(net "P5E_CPU1_P2_TX_DN<1>")
	)
	(segment
		(start 114.519964 -296.2529)
		(end 114.565684 -296.29862)
		(width 0.1143)
		(layer "In13.Cu")
		(net "P5E_CPU1_P2_TX_DN<1>")
	)
	(segment
		(start 114.23015 -272.148046)
		(end 114.20602 -272.162016)
		(width 0.1143)
		(layer "In13.Cu")
		(net "P5E_CPU1_P2_TX_DN<1>")
	)
	(segment
		(start 116.14912 -302.236632)
		(end 117.427502 -304.369216)
		(width 0.14224)
		(layer "In13.Cu")
		(net "P5E_CPU1_P2_TX_DN<1>")
	)
	(segment
		(start 117.427502 -304.369216)
		(end 126.830328 -317.045848)
		(width 0.14224)
		(layer "In13.Cu")
		(net "P5E_CPU1_P2_TX_DN<1>")
	)
	(segment
		(start 114.207036 -295.451022)
		(end 114.237516 -295.468802)
		(width 0.1143)
		(layer "In13.Cu")
		(net "P5E_CPU1_P2_TX_DN<1>")
	)
	(segment
		(start 113.806732 -272.930874)
		(end 113.767616 -272.953734)
		(width 0.1143)
		(layer "In13.Cu")
		(net "P5E_CPU1_P2_TX_DN<1>")
	)
	(segment
		(start 113.786666 -289.141916)
		(end 113.772188 -289.151314)
		(width 0.1143)
		(layer "In13.Cu")
		(net "P5E_CPU1_P2_TX_DN<1>")
	)
	(segment
		(start 113.768886 -282.673044)
		(end 113.76533 -282.67533)
		(width 0.1143)
		(layer "In13.Cu")
		(net "P5E_CPU1_P2_TX_DN<1>")
	)
	(segment
		(start 113.767616 -274.573746)
		(end 113.737136 -274.591526)
		(width 0.1143)
		(layer "In13.Cu")
		(net "P5E_CPU1_P2_TX_DN<1>")
	)
	(segment
		(start 114.23777 -272.143728)
		(end 114.237008 -272.144236)
		(width 0.1143)
		(layer "In13.Cu")
		(net "P5E_CPU1_P2_TX_DN<1>")
	)
	(segment
		(start 113.772188 -289.15106)
		(end 113.767616 -289.1536)
		(width 0.1143)
		(layer "In13.Cu")
		(net "P5E_CPU1_P2_TX_DN<1>")
	)
	(segment
		(start 113.767616 -275.218906)
		(end 113.806732 -275.241766)
		(width 0.1143)
		(layer "In13.Cu")
		(net "P5E_CPU1_P2_TX_DN<1>")
	)
	(segment
		(start 113.767616 -272.953734)
		(end 113.737136 -272.971514)
		(width 0.1143)
		(layer "In13.Cu")
		(net "P5E_CPU1_P2_TX_DN<1>")
	)
	(segment
		(start 113.76533 -281.69743)
		(end 113.768886 -281.699716)
		(width 0.1143)
		(layer "In13.Cu")
		(net "P5E_CPU1_P2_TX_DN<1>")
	)
	(segment
		(start 113.759742 -284.934152)
		(end 113.805208 -284.960822)
		(width 0.1143)
		(layer "In13.Cu")
		(net "P5E_CPU1_P2_TX_DN<1>")
	)
	(segment
		(start 113.767616 -281.053794)
		(end 113.764314 -281.055826)
		(width 0.1143)
		(layer "In13.Cu")
		(net "P5E_CPU1_P2_TX_DN<1>")
	)
	(segment
		(start 113.806732 -281.030934)
		(end 113.767616 -281.053794)
		(width 0.1143)
		(layer "In13.Cu")
		(net "P5E_CPU1_P2_TX_DN<1>")
	)
	(segment
		(start 113.737136 -278.44115)
		(end 113.767616 -278.45893)
		(width 0.1143)
		(layer "In13.Cu")
		(net "P5E_CPU1_P2_TX_DN<1>")
	)
	(segment
		(start 113.76406 -283.316934)
		(end 113.76533 -283.317442)
		(width 0.1143)
		(layer "In13.Cu")
		(net "P5E_CPU1_P2_TX_DN<1>")
	)
	(segment
		(start 114.565684 -296.327068)
		(end 114.565684 -298.413932)
		(width 0.14224)
		(layer "In13.Cu")
		(net "P5E_CPU1_P2_TX_DN<1>")
	)
	(segment
		(start 113.806732 -282.650946)
		(end 113.768886 -282.673044)
		(width 0.1143)
		(layer "In13.Cu")
		(net "P5E_CPU1_P2_TX_DN<1>")
	)
	(segment
		(start 127.545846 -318.116712)
		(end 131.361688 -325.259446)
		(width 0.14224)
		(layer "In13.Cu")
		(net "P5E_CPU1_P2_TX_DN<1>")
	)
	(segment
		(start 113.762028 -293.035482)
		(end 113.770664 -293.040562)
		(width 0.1143)
		(layer "In13.Cu")
		(net "P5E_CPU1_P2_TX_DN<1>")
	)
	(segment
		(start 113.806732 -285.89097)
		(end 113.73612 -285.932372)
		(width 0.1143)
		(layer "In13.Cu")
		(net "P5E_CPU1_P2_TX_DN<1>")
	)
	(segment
		(start 141.509496 -372.274338)
		(end 142.434056 -374.506744)
		(width 0.14224)
		(layer "In13.Cu")
		(net "P5E_CPU1_P2_TX_DN<1>")
	)
	(segment
		(start 113.767616 -276.838918)
		(end 113.806732 -276.861778)
		(width 0.1143)
		(layer "In13.Cu")
		(net "P5E_CPU1_P2_TX_DN<1>")
	)
	(segment
		(start 141.349222 -376.54103)
		(end 141.058392 -376.83186)
		(width 0.14224)
		(layer "In13.Cu")
		(net "P5E_CPU1_P2_TX_DN<1>")
	)
	(segment
		(start 114.237516 -295.468802)
		(end 114.276632 -295.491662)
		(width 0.1143)
		(layer "In13.Cu")
		(net "P5E_CPU1_P2_TX_DN<1>")
	)
	(segment
		(start 114.231166 -272.147538)
		(end 114.23015 -272.148046)
		(width 0.1143)
		(layer "In13.Cu")
		(net "P5E_CPU1_P2_TX_DN<1>")
	)
	(segment
		(start 113.737644 -288.161476)
		(end 113.773712 -288.182304)
		(width 0.1143)
		(layer "In13.Cu")
		(net "P5E_CPU1_P2_TX_DN<1>")
	)
	(segment
		(start 114.234214 -272.14576)
		(end 114.233452 -272.146268)
		(width 0.1143)
		(layer "In13.Cu")
		(net "P5E_CPU1_P2_TX_DN<1>")
	)
	(segment
		(start 142.644368 -375.563892)
		(end 142.644368 -376.049032)
		(width 0.14224)
		(layer "In13.Cu")
		(net "P5E_CPU1_P2_TX_DN<1>")
	)
	(segment
		(start 113.767616 -289.1536)
		(end 113.737136 -289.17138)
		(width 0.1143)
		(layer "In13.Cu")
		(net "P5E_CPU1_P2_TX_DN<1>")
	)
	(segment
		(start 126.830328 -317.045848)
		(end 127.545846 -318.116712)
		(width 0.14224)
		(layer "In13.Cu")
		(net "P5E_CPU1_P2_TX_DN<1>")
	)
	(segment
		(start 113.737136 -289.78098)
		(end 113.767616 -289.79876)
		(width 0.1143)
		(layer "In13.Cu")
		(net "P5E_CPU1_P2_TX_DN<1>")
	)
	(segment
		(start 113.737136 -276.821138)
		(end 113.767616 -276.838918)
		(width 0.1143)
		(layer "In13.Cu")
		(net "P5E_CPU1_P2_TX_DN<1>")
	)
	(segment
		(start 113.737136 -294.641016)
		(end 113.767616 -294.658796)
		(width 0.1143)
		(layer "In13.Cu")
		(net "P5E_CPU1_P2_TX_DN<1>")
	)
	(segment
		(start 114.274092 -272.122646)
		(end 114.23777 -272.143728)
		(width 0.1143)
		(layer "In13.Cu")
		(net "P5E_CPU1_P2_TX_DN<1>")
	)
	(segment
		(start 113.806732 -276.170898)
		(end 113.767616 -276.193758)
		(width 0.1143)
		(layer "In13.Cu")
		(net "P5E_CPU1_P2_TX_DN<1>")
	)
	(segment
		(start 113.767616 -277.81377)
		(end 113.737136 -277.83155)
		(width 0.1143)
		(layer "In13.Cu")
		(net "P5E_CPU1_P2_TX_DN<1>")
	)
	(segment
		(start 113.73485 -279.452832)
		(end 113.732818 -279.454356)
		(width 0.1143)
		(layer "In13.Cu")
		(net "P5E_CPU1_P2_TX_DN<1>")
	)
	(segment
		(start 113.580164 -286.222694)
		(end 113.580164 -286.239204)
		(width 0.1143)
		(layer "In13.Cu")
		(net "P5E_CPU1_P2_TX_DN<1>")
	)
	(segment
		(start 113.767616 -290.773612)
		(end 113.737136 -290.791392)
		(width 0.1143)
		(layer "In13.Cu")
		(net "P5E_CPU1_P2_TX_DN<1>")
	)
	(segment
		(start 136.669272 -351.940368)
		(end 141.30909 -367.235232)
		(width 0.14224)
		(layer "In13.Cu")
		(net "P5E_CPU1_P2_TX_DN<1>")
	)
	(segment
		(start 113.806732 -292.370764)
		(end 113.772188 -292.39083)
		(width 0.1143)
		(layer "In13.Cu")
		(net "P5E_CPU1_P2_TX_DN<1>")
	)
	(segment
		(start 113.806732 -284.270958)
		(end 113.768632 -284.29331)
		(width 0.1143)
		(layer "In13.Cu")
		(net "P5E_CPU1_P2_TX_DN<1>")
	)
	(segment
		(start 113.737136 -275.201126)
		(end 113.767616 -275.218906)
		(width 0.1143)
		(layer "In13.Cu")
		(net "P5E_CPU1_P2_TX_DN<1>")
	)
	(segment
		(start 114.565684 -298.413932)
		(end 116.14912 -302.236632)
		(width 0.14224)
		(layer "In13.Cu")
		(net "P5E_CPU1_P2_TX_DN<1>")
	)
	(segment
		(start 114.519964 -295.956228)
		(end 114.519964 -296.2529)
		(width 0.1143)
		(layer "In13.Cu")
		(net "P5E_CPU1_P2_TX_DN<1>")
	)
	(segment
		(start 113.767616 -279.433782)
		(end 113.73485 -279.452832)
		(width 0.1143)
		(layer "In13.Cu")
		(net "P5E_CPU1_P2_TX_DN<1>")
	)
	(segment
		(start 113.767616 -278.45893)
		(end 113.806732 -278.48179)
		(width 0.1143)
		(layer "In13.Cu")
		(net "P5E_CPU1_P2_TX_DN<1>")
	)
	(segment
		(start 131.361688 -325.259446)
		(end 136.669272 -351.940368)
		(width 0.14224)
		(layer "In13.Cu")
		(net "P5E_CPU1_P2_TX_DN<1>")
	)
	(segment
		(start 113.767616 -273.598894)
		(end 113.806732 -273.621754)
		(width 0.1143)
		(layer "In13.Cu")
		(net "P5E_CPU1_P2_TX_DN<1>")
	)
	(segment
		(start 113.771426 -293.04107)
		(end 113.80597 -293.061136)
		(width 0.1143)
		(layer "In13.Cu")
		(net "P5E_CPU1_P2_TX_DN<1>")
	)
	(segment
		(start 114.70767 -271.333722)
		(end 114.707162 -271.333722)
		(width 0.1143)
		(layer "In13.Cu")
		(net "P5E_CPU1_P2_TX_DN<1>")
	)
	(segment
		(start 115.364768 -270.846296)
		(end 115.066826 -270.846296)
		(width 0.1143)
		(layer "In13.Cu")
		(net "P5E_CPU1_P2_TX_DN<1>")
	)
	(segment
		(start 113.806732 -277.79091)
		(end 113.767616 -277.81377)
		(width 0.1143)
		(layer "In13.Cu")
		(net "P5E_CPU1_P2_TX_DN<1>")
	)
	(segment
		(start 113.768632 -284.29331)
		(end 113.76787 -284.293818)
		(width 0.1143)
		(layer "In13.Cu")
		(net "P5E_CPU1_P2_TX_DN<1>")
	)
	(segment
		(start 113.768886 -281.699716)
		(end 113.805208 -281.720798)
		(width 0.1143)
		(layer "In13.Cu")
		(net "P5E_CPU1_P2_TX_DN<1>")
	)
	(segment
		(start 113.768886 -283.319728)
		(end 113.805208 -283.34081)
		(width 0.1143)
		(layer "In13.Cu")
		(net "P5E_CPU1_P2_TX_DN<1>")
	)
	(segment
		(start 113.806732 -274.550886)
		(end 113.767616 -274.573746)
		(width 0.1143)
		(layer "In13.Cu")
		(net "P5E_CPU1_P2_TX_DN<1>")
	)
	(segment
		(start 114.237008 -272.144236)
		(end 114.234214 -272.14576)
		(width 0.1143)
		(layer "In13.Cu")
		(net "P5E_CPU1_P2_TX_DN<1>")
	)
	(segment
		(start 114.707162 -271.333722)
		(end 114.67846 -271.350486)
		(width 0.1143)
		(layer "In13.Cu")
		(net "P5E_CPU1_P2_TX_DN<1>")
	)
	(segment
		(start 113.767616 -289.79876)
		(end 113.806732 -289.82162)
		(width 0.1143)
		(layer "In13.Cu")
		(net "P5E_CPU1_P2_TX_DN<1>")
	)
	(segment
		(start 113.772188 -292.39083)
		(end 113.771426 -292.391338)
		(width 0.1143)
		(layer "In13.Cu")
		(net "P5E_CPU1_P2_TX_DN<1>")
	)
	(segment
		(start 113.806732 -279.410922)
		(end 113.767616 -279.433782)
		(width 0.1143)
		(layer "In13.Cu")
		(net "P5E_CPU1_P2_TX_DN<1>")
	)
	(segment
		(start 114.565684 -296.29862)
		(end 114.565684 -296.327068)
		(width 0.1143)
		(layer "In13.Cu")
		(net "P5E_CPU1_P2_TX_DN<1>")
	)
	(arc
		(start 113.806732 -283.341826)
		(mid 114.050059 -283.806392)
		(end 113.806732 -284.270958)
		(width 0.1143)
		(layer "In13.Cu")
		(net "P5E_CPU1_P2_TX_DN<1>")
	)
	(arc
		(start 113.806732 -293.061644)
		(mid 114.050059 -293.52621)
		(end 113.806732 -293.990776)
		(width 0.1143)
		(layer "In13.Cu")
		(net "P5E_CPU1_P2_TX_DN<1>")
	)
	(arc
		(start 142.644368 -376.049032)
		(mid 142.586547 -376.259617)
		(end 142.428468 -376.41022)
		(width 0.14224)
		(layer "In13.Cu")
		(net "P5E_CPU1_P2_TX_DN<1>")
	)
	(arc
		(start 113.73612 -285.932372)
		(mid 113.62454 -286.059473)
		(end 113.580164 -286.222694)
		(width 0.1143)
		(layer "In13.Cu")
		(net "P5E_CPU1_P2_TX_DN<1>")
	)
	(arc
		(start 114.20602 -272.162016)
		(mid 114.091344 -272.29535)
		(end 114.050064 -272.466308)
		(width 0.1143)
		(layer "In13.Cu")
		(net "P5E_CPU1_P2_TX_DN<1>")
	)
	(arc
		(start 113.760758 -292.397434)
		(mid 113.580273 -292.716204)
		(end 113.760758 -293.034974)
		(width 0.1143)
		(layer "In13.Cu")
		(net "P5E_CPU1_P2_TX_DN<1>")
	)
	(arc
		(start 114.672618 -271.355058)
		(mid 114.566808 -271.49019)
		(end 114.519964 -271.655286)
		(width 0.1143)
		(layer "In13.Cu")
		(net "P5E_CPU1_P2_TX_DN<1>")
	)
	(arc
		(start 113.806732 -294.681656)
		(mid 113.985545 -294.884006)
		(end 114.050064 -295.146222)
		(width 0.1143)
		(layer "In13.Cu")
		(net "P5E_CPU1_P2_TX_DN<1>")
	)
	(arc
		(start 113.806732 -284.961838)
		(mid 114.050059 -285.426404)
		(end 113.806732 -285.89097)
		(width 0.1143)
		(layer "In13.Cu")
		(net "P5E_CPU1_P2_TX_DN<1>")
	)
	(arc
		(start 142.195296 -376.508518)
		(mid 142.090895 -376.532978)
		(end 141.983968 -376.54103)
		(width 0.14224)
		(layer "In13.Cu")
		(net "P5E_CPU1_P2_TX_DN<1>")
	)
	(arc
		(start 141.30909 -371.26672)
		(mid 141.359679 -371.780397)
		(end 141.509496 -372.274338)
		(width 0.14224)
		(layer "In13.Cu")
		(net "P5E_CPU1_P2_TX_DN<1>")
	)
	(arc
		(start 113.805208 -281.720798)
		(mid 113.80597 -281.721305)
		(end 113.806732 -281.721814)
		(width 0.1143)
		(layer "In13.Cu")
		(net "P5E_CPU1_P2_TX_DN<1>")
	)
	(arc
		(start 113.580164 -286.239204)
		(mid 113.621527 -286.408777)
		(end 113.73612 -286.540448)
		(width 0.1143)
		(layer "In13.Cu")
		(net "P5E_CPU1_P2_TX_DN<1>")
	)
	(arc
		(start 113.806732 -278.48179)
		(mid 114.050059 -278.946356)
		(end 113.806732 -279.410922)
		(width 0.1143)
		(layer "In13.Cu")
		(net "P5E_CPU1_P2_TX_DN<1>")
	)
	(arc
		(start 113.764314 -281.055826)
		(mid 113.580432 -281.376264)
		(end 113.76406 -281.696922)
		(width 0.1143)
		(layer "In13.Cu")
		(net "P5E_CPU1_P2_TX_DN<1>")
	)
	(arc
		(start 113.80597 -293.061136)
		(mid 113.806351 -293.06139)
		(end 113.806732 -293.061644)
		(width 0.1143)
		(layer "In13.Cu")
		(net "P5E_CPU1_P2_TX_DN<1>")
	)
	(arc
		(start 113.76787 -284.293818)
		(mid 113.582892 -284.611672)
		(end 113.759742 -284.934152)
		(width 0.1143)
		(layer "In13.Cu")
		(net "P5E_CPU1_P2_TX_DN<1>")
	)
	(arc
		(start 113.806732 -291.441632)
		(mid 114.050059 -291.906198)
		(end 113.806732 -292.370764)
		(width 0.1143)
		(layer "In13.Cu")
		(net "P5E_CPU1_P2_TX_DN<1>")
	)
	(arc
		(start 114.290348 -272.111216)
		(mid 114.28227 -272.117002)
		(end 114.274092 -272.122646)
		(width 0.1143)
		(layer "In13.Cu")
		(net "P5E_CPU1_P2_TX_DN<1>")
	)
	(arc
		(start 113.806732 -280.101802)
		(mid 114.050059 -280.566368)
		(end 113.806732 -281.030934)
		(width 0.1143)
		(layer "In13.Cu")
		(net "P5E_CPU1_P2_TX_DN<1>")
	)
	(arc
		(start 114.984022 -270.9291)
		(mid 114.982234 -270.940549)
		(end 114.980212 -270.95196)
		(width 0.1143)
		(layer "In13.Cu")
		(net "P5E_CPU1_P2_TX_DN<1>")
	)
	(arc
		(start 142.428468 -376.41022)
		(mid 142.314105 -376.464645)
		(end 142.195296 -376.508518)
		(width 0.14224)
		(layer "In13.Cu")
		(net "P5E_CPU1_P2_TX_DN<1>")
	)
	(arc
		(start 114.050064 -287.046162)
		(mid 113.984828 -287.309753)
		(end 113.804192 -287.512506)
		(width 0.1143)
		(layer "In13.Cu")
		(net "P5E_CPU1_P2_TX_DN<1>")
	)
	(arc
		(start 114.050064 -272.466308)
		(mid 113.985549 -272.728527)
		(end 113.806732 -272.930874)
		(width 0.1143)
		(layer "In13.Cu")
		(net "P5E_CPU1_P2_TX_DN<1>")
	)
	(arc
		(start 113.806732 -281.721814)
		(mid 114.050059 -282.18638)
		(end 113.806732 -282.650946)
		(width 0.1143)
		(layer "In13.Cu")
		(net "P5E_CPU1_P2_TX_DN<1>")
	)
	(arc
		(start 113.805208 -283.34081)
		(mid 113.80597 -283.341317)
		(end 113.806732 -283.341826)
		(width 0.1143)
		(layer "In13.Cu")
		(net "P5E_CPU1_P2_TX_DN<1>")
	)
	(arc
		(start 113.773712 -288.182304)
		(mid 114.050853 -288.658244)
		(end 113.787174 -289.141662)
		(width 0.1143)
		(layer "In13.Cu")
		(net "P5E_CPU1_P2_TX_DN<1>")
	)
	(arc
		(start 113.737136 -290.791392)
		(mid 113.580159 -291.096192)
		(end 113.737136 -291.400992)
		(width 0.1143)
		(layer "In13.Cu")
		(net "P5E_CPU1_P2_TX_DN<1>")
	)
	(arc
		(start 113.806732 -275.241766)
		(mid 114.050059 -275.706332)
		(end 113.806732 -276.170898)
		(width 0.1143)
		(layer "In13.Cu")
		(net "P5E_CPU1_P2_TX_DN<1>")
	)
	(arc
		(start 114.980212 -270.95196)
		(mid 114.898779 -271.154358)
		(end 114.746786 -271.310862)
		(width 0.1143)
		(layer "In13.Cu")
		(net "P5E_CPU1_P2_TX_DN<1>")
	)
	(arc
		(start 113.806732 -276.861778)
		(mid 114.050059 -277.326344)
		(end 113.806732 -277.79091)
		(width 0.1143)
		(layer "In13.Cu")
		(net "P5E_CPU1_P2_TX_DN<1>")
	)
	(arc
		(start 113.737136 -289.17138)
		(mid 113.580159 -289.47618)
		(end 113.737136 -289.78098)
		(width 0.1143)
		(layer "In13.Cu")
		(net "P5E_CPU1_P2_TX_DN<1>")
	)
	(arc
		(start 113.737136 -274.591526)
		(mid 113.580159 -274.896326)
		(end 113.737136 -275.201126)
		(width 0.1143)
		(layer "In13.Cu")
		(net "P5E_CPU1_P2_TX_DN<1>")
	)
	(arc
		(start 113.806732 -289.82162)
		(mid 114.050059 -290.286186)
		(end 113.806732 -290.750752)
		(width 0.1143)
		(layer "In13.Cu")
		(net "P5E_CPU1_P2_TX_DN<1>")
	)
	(arc
		(start 113.732818 -279.454356)
		(mid 113.578638 -279.756362)
		(end 113.732818 -280.058368)
		(width 0.1143)
		(layer "In13.Cu")
		(net "P5E_CPU1_P2_TX_DN<1>")
	)
	(arc
		(start 113.805208 -284.960822)
		(mid 113.80597 -284.961329)
		(end 113.806732 -284.961838)
		(width 0.1143)
		(layer "In13.Cu")
		(net "P5E_CPU1_P2_TX_DN<1>")
	)
	(arc
		(start 142.434056 -374.506744)
		(mid 142.591289 -375.02496)
		(end 142.644368 -375.563892)
		(width 0.14224)
		(layer "In13.Cu")
		(net "P5E_CPU1_P2_TX_DN<1>")
	)
	(arc
		(start 113.737136 -276.211538)
		(mid 113.580159 -276.516338)
		(end 113.737136 -276.821138)
		(width 0.1143)
		(layer "In13.Cu")
		(net "P5E_CPU1_P2_TX_DN<1>")
	)
	(arc
		(start 114.050064 -295.146222)
		(mid 114.091613 -295.317644)
		(end 114.207036 -295.451022)
		(width 0.1143)
		(layer "In13.Cu")
		(net "P5E_CPU1_P2_TX_DN<1>")
	)
	(arc
		(start 113.737136 -277.83155)
		(mid 113.580159 -278.13635)
		(end 113.737136 -278.44115)
		(width 0.1143)
		(layer "In13.Cu")
		(net "P5E_CPU1_P2_TX_DN<1>")
	)
	(arc
		(start 113.806732 -273.621754)
		(mid 114.050059 -274.08632)
		(end 113.806732 -274.550886)
		(width 0.1143)
		(layer "In13.Cu")
		(net "P5E_CPU1_P2_TX_DN<1>")
	)
	(arc
		(start 114.276632 -295.491662)
		(mid 114.455507 -295.69398)
		(end 114.519964 -295.956228)
		(width 0.1143)
		(layer "In13.Cu")
		(net "P5E_CPU1_P2_TX_DN<1>")
	)
	(arc
		(start 114.519964 -271.655286)
		(mid 114.456709 -271.909222)
		(end 114.290348 -272.111216)
		(width 0.1143)
		(layer "In13.Cu")
		(net "P5E_CPU1_P2_TX_DN<1>")
	)
	(arc
		(start 113.580164 -287.856422)
		(mid 113.621915 -288.028042)
		(end 113.737644 -288.161476)
		(width 0.1143)
		(layer "In13.Cu")
		(net "P5E_CPU1_P2_TX_DN<1>")
	)
	(arc
		(start 114.67846 -271.350486)
		(mid 114.675527 -271.352757)
		(end 114.672618 -271.355058)
		(width 0.1143)
		(layer "In13.Cu")
		(net "P5E_CPU1_P2_TX_DN<1>")
	)
	(arc
		(start 113.806732 -286.581596)
		(mid 113.985545 -286.783946)
		(end 114.050064 -287.046162)
		(width 0.1143)
		(layer "In13.Cu")
		(net "P5E_CPU1_P2_TX_DN<1>")
	)
	(arc
		(start 113.737136 -294.031416)
		(mid 113.580159 -294.336216)
		(end 113.737136 -294.641016)
		(width 0.1143)
		(layer "In13.Cu")
		(net "P5E_CPU1_P2_TX_DN<1>")
	)
	(arc
		(start 113.740184 -287.54959)
		(mid 113.622561 -287.683392)
		(end 113.580164 -287.856422)
		(width 0.1143)
		(layer "In13.Cu")
		(net "P5E_CPU1_P2_TX_DN<1>")
	)
	(arc
		(start 113.764314 -282.675838)
		(mid 113.580432 -282.996276)
		(end 113.76406 -283.316934)
		(width 0.1143)
		(layer "In13.Cu")
		(net "P5E_CPU1_P2_TX_DN<1>")
	)
	(arc
		(start 113.737136 -272.971514)
		(mid 113.580159 -273.276314)
		(end 113.737136 -273.581114)
		(width 0.1143)
		(layer "In13.Cu")
		(net "P5E_CPU1_P2_TX_DN<1>")
	)
	(segment
		(start 125.707902 -271.390364)
		(end 126.174754 -271.656302)
		(width 0.12954)
		(layer "F.Cu")
		(net "P5E_CPU1_P2_TX_DN<15>")
	)
	(segment
		(start 169.931334 -380.089918)
		(end 169.635424 -380.385828)
		(width 0.12954)
		(layer "F.Cu")
		(net "P5E_CPU1_P2_TX_DN<15>")
	)
	(segment
		(start 170.634914 -380.089918)
		(end 169.931334 -380.089918)
		(width 0.12954)
		(layer "F.Cu")
		(net "P5E_CPU1_P2_TX_DN<15>")
	)
	(segment
		(start 170.905424 -380.360428)
		(end 170.634914 -380.089918)
		(width 0.12954)
		(layer "F.Cu")
		(net "P5E_CPU1_P2_TX_DN<15>")
	)
	(segment
		(start 126.964186 -287.512506)
		(end 126.89713 -287.551622)
		(width 0.1143)
		(layer "In13.Cu")
		(net "P5E_CPU1_P2_TX_DN<15>")
	)
	(segment
		(start 126.454916 -272.787364)
		(end 126.496064 -272.81124)
		(width 0.1143)
		(layer "In13.Cu")
		(net "P5E_CPU1_P2_TX_DN<15>")
	)
	(segment
		(start 126.92761 -279.433782)
		(end 126.89713 -279.451562)
		(width 0.1143)
		(layer "In13.Cu")
		(net "P5E_CPU1_P2_TX_DN<15>")
	)
	(segment
		(start 128.176528 -296.497248)
		(end 128.196594 -296.517314)
		(width 0.1143)
		(layer "In13.Cu")
		(net "P5E_CPU1_P2_TX_DN<15>")
	)
	(segment
		(start 127.982726 -296.367454)
		(end 128.11252 -296.497248)
		(width 0.1143)
		(layer "In13.Cu")
		(net "P5E_CPU1_P2_TX_DN<15>")
	)
	(segment
		(start 171.790106 -380.069598)
		(end 171.196254 -380.069598)
		(width 0.14224)
		(layer "In13.Cu")
		(net "P5E_CPU1_P2_TX_DN<15>")
	)
	(segment
		(start 164.673026 -363.25302)
		(end 167.030146 -364.229396)
		(width 0.14224)
		(layer "In13.Cu")
		(net "P5E_CPU1_P2_TX_DN<15>")
	)
	(segment
		(start 126.966726 -290.750752)
		(end 126.92761 -290.773612)
		(width 0.1143)
		(layer "In13.Cu")
		(net "P5E_CPU1_P2_TX_DN<15>")
	)
	(segment
		(start 149.359874 -346.806012)
		(end 154.08783 -356.199694)
		(width 0.14224)
		(layer "In13.Cu")
		(net "P5E_CPU1_P2_TX_DN<15>")
	)
	(segment
		(start 142.456916 -317.796418)
		(end 143.577564 -319.893188)
		(width 0.14224)
		(layer "In13.Cu")
		(net "P5E_CPU1_P2_TX_DN<15>")
	)
	(segment
		(start 126.92761 -288.178748)
		(end 126.966726 -288.201608)
		(width 0.1143)
		(layer "In13.Cu")
		(net "P5E_CPU1_P2_TX_DN<15>")
	)
	(segment
		(start 126.92761 -293.038784)
		(end 126.966726 -293.061644)
		(width 0.1143)
		(layer "In13.Cu")
		(net "P5E_CPU1_P2_TX_DN<15>")
	)
	(segment
		(start 126.92761 -280.078942)
		(end 126.966726 -280.101802)
		(width 0.1143)
		(layer "In13.Cu")
		(net "P5E_CPU1_P2_TX_DN<15>")
	)
	(segment
		(start 126.92761 -283.318966)
		(end 126.966726 -283.341826)
		(width 0.1143)
		(layer "In13.Cu")
		(net "P5E_CPU1_P2_TX_DN<15>")
	)
	(segment
		(start 126.89713 -276.821138)
		(end 126.92761 -276.838918)
		(width 0.1143)
		(layer "In13.Cu")
		(net "P5E_CPU1_P2_TX_DN<15>")
	)
	(segment
		(start 126.966726 -281.030934)
		(end 126.92761 -281.053794)
		(width 0.1143)
		(layer "In13.Cu")
		(net "P5E_CPU1_P2_TX_DN<15>")
	)
	(segment
		(start 126.92761 -284.293818)
		(end 126.89713 -284.311598)
		(width 0.1143)
		(layer "In13.Cu")
		(net "P5E_CPU1_P2_TX_DN<15>")
	)
	(segment
		(start 126.92761 -273.598894)
		(end 126.966726 -273.621754)
		(width 0.1143)
		(layer "In13.Cu")
		(net "P5E_CPU1_P2_TX_DN<15>")
	)
	(segment
		(start 126.92761 -277.81377)
		(end 126.89713 -277.83155)
		(width 0.1143)
		(layer "In13.Cu")
		(net "P5E_CPU1_P2_TX_DN<15>")
	)
	(segment
		(start 126.89713 -275.201126)
		(end 126.92761 -275.218906)
		(width 0.1143)
		(layer "In13.Cu")
		(net "P5E_CPU1_P2_TX_DN<15>")
	)
	(segment
		(start 126.966726 -285.89097)
		(end 126.92761 -285.91383)
		(width 0.1143)
		(layer "In13.Cu")
		(net "P5E_CPU1_P2_TX_DN<15>")
	)
	(segment
		(start 126.92761 -282.673806)
		(end 126.89713 -282.691586)
		(width 0.1143)
		(layer "In13.Cu")
		(net "P5E_CPU1_P2_TX_DN<15>")
	)
	(segment
		(start 144.403318 -321.886072)
		(end 149.359874 -346.806012)
		(width 0.14224)
		(layer "In13.Cu")
		(net "P5E_CPU1_P2_TX_DN<15>")
	)
	(segment
		(start 126.895098 -286.53994)
		(end 126.92761 -286.558736)
		(width 0.1143)
		(layer "In13.Cu")
		(net "P5E_CPU1_P2_TX_DN<15>")
	)
	(segment
		(start 127.366014 -295.450514)
		(end 127.397764 -295.468802)
		(width 0.1143)
		(layer "In13.Cu")
		(net "P5E_CPU1_P2_TX_DN<15>")
	)
	(segment
		(start 126.92761 -289.1536)
		(end 126.89713 -289.17138)
		(width 0.1143)
		(layer "In13.Cu")
		(net "P5E_CPU1_P2_TX_DN<15>")
	)
	(segment
		(start 126.92761 -286.558736)
		(end 126.966726 -286.581596)
		(width 0.1143)
		(layer "In13.Cu")
		(net "P5E_CPU1_P2_TX_DN<15>")
	)
	(segment
		(start 170.824906 -367.198402)
		(end 172.655484 -369.938554)
		(width 0.14224)
		(layer "In13.Cu")
		(net "P5E_CPU1_P2_TX_DN<15>")
	)
	(segment
		(start 126.89713 -278.44115)
		(end 126.92761 -278.45893)
		(width 0.1143)
		(layer "In13.Cu")
		(net "P5E_CPU1_P2_TX_DN<15>")
	)
	(segment
		(start 126.92761 -278.45893)
		(end 126.966726 -278.48179)
		(width 0.1143)
		(layer "In13.Cu")
		(net "P5E_CPU1_P2_TX_DN<15>")
	)
	(segment
		(start 127.837184 -296.261028)
		(end 127.867664 -296.278808)
		(width 0.1143)
		(layer "In13.Cu")
		(net "P5E_CPU1_P2_TX_DN<15>")
	)
	(segment
		(start 126.966726 -293.990776)
		(end 126.92761 -294.013636)
		(width 0.1143)
		(layer "In13.Cu")
		(net "P5E_CPU1_P2_TX_DN<15>")
	)
	(segment
		(start 126.92761 -285.91383)
		(end 126.89713 -285.93161)
		(width 0.1143)
		(layer "In13.Cu")
		(net "P5E_CPU1_P2_TX_DN<15>")
	)
	(segment
		(start 173.154848 -378.74067)
		(end 172.914056 -379.32233)
		(width 0.14224)
		(layer "In13.Cu")
		(net "P5E_CPU1_P2_TX_DN<15>")
	)
	(segment
		(start 141.343126 -315.712348)
		(end 142.456916 -317.796164)
		(width 0.14224)
		(layer "In13.Cu")
		(net "P5E_CPU1_P2_TX_DN<15>")
	)
	(segment
		(start 126.966726 -277.79091)
		(end 126.92761 -277.81377)
		(width 0.1143)
		(layer "In13.Cu")
		(net "P5E_CPU1_P2_TX_DN<15>")
	)
	(segment
		(start 126.89713 -284.921198)
		(end 126.92761 -284.938978)
		(width 0.1143)
		(layer "In13.Cu")
		(net "P5E_CPU1_P2_TX_DN<15>")
	)
	(segment
		(start 126.895098 -288.159952)
		(end 126.92761 -288.178748)
		(width 0.1143)
		(layer "In13.Cu")
		(net "P5E_CPU1_P2_TX_DN<15>")
	)
	(segment
		(start 126.966726 -274.550886)
		(end 126.92761 -274.573746)
		(width 0.1143)
		(layer "In13.Cu")
		(net "P5E_CPU1_P2_TX_DN<15>")
	)
	(segment
		(start 139.108688 -311.531762)
		(end 141.343126 -315.712094)
		(width 0.14224)
		(layer "In13.Cu")
		(net "P5E_CPU1_P2_TX_DN<15>")
	)
	(segment
		(start 126.92761 -284.938978)
		(end 126.966726 -284.961838)
		(width 0.1143)
		(layer "In13.Cu")
		(net "P5E_CPU1_P2_TX_DN<15>")
	)
	(segment
		(start 126.89713 -280.061162)
		(end 126.92761 -280.078942)
		(width 0.1143)
		(layer "In13.Cu")
		(net "P5E_CPU1_P2_TX_DN<15>")
	)
	(segment
		(start 126.89713 -294.641016)
		(end 126.92761 -294.658796)
		(width 0.1143)
		(layer "In13.Cu")
		(net "P5E_CPU1_P2_TX_DN<15>")
	)
	(segment
		(start 126.92761 -281.053794)
		(end 126.89713 -281.071574)
		(width 0.1143)
		(layer "In13.Cu")
		(net "P5E_CPU1_P2_TX_DN<15>")
	)
	(segment
		(start 128.196594 -296.517314)
		(end 128.421638 -296.742104)
		(width 0.14224)
		(layer "In13.Cu")
		(net "P5E_CPU1_P2_TX_DN<15>")
	)
	(segment
		(start 126.966726 -279.410922)
		(end 126.92761 -279.433782)
		(width 0.1143)
		(layer "In13.Cu")
		(net "P5E_CPU1_P2_TX_DN<15>")
	)
	(segment
		(start 171.196254 -380.069598)
		(end 170.905424 -380.360428)
		(width 0.14224)
		(layer "In13.Cu")
		(net "P5E_CPU1_P2_TX_DN<15>")
	)
	(segment
		(start 126.89713 -273.581114)
		(end 126.92761 -273.598894)
		(width 0.1143)
		(layer "In13.Cu")
		(net "P5E_CPU1_P2_TX_DN<15>")
	)
	(segment
		(start 126.966726 -292.370764)
		(end 126.92761 -292.393624)
		(width 0.1143)
		(layer "In13.Cu")
		(net "P5E_CPU1_P2_TX_DN<15>")
	)
	(segment
		(start 126.92761 -276.838918)
		(end 126.966726 -276.861778)
		(width 0.1143)
		(layer "In13.Cu")
		(net "P5E_CPU1_P2_TX_DN<15>")
	)
	(segment
		(start 142.456916 -317.796164)
		(end 142.456916 -317.796418)
		(width 0.14224)
		(layer "In13.Cu")
		(net "P5E_CPU1_P2_TX_DN<15>")
	)
	(segment
		(start 126.89713 -281.681174)
		(end 126.92761 -281.698954)
		(width 0.1143)
		(layer "In13.Cu")
		(net "P5E_CPU1_P2_TX_DN<15>")
	)
	(segment
		(start 125.95606 -271.960594)
		(end 126.00686 -271.990058)
		(width 0.1143)
		(layer "In13.Cu")
		(net "P5E_CPU1_P2_TX_DN<15>")
	)
	(segment
		(start 126.89713 -289.78098)
		(end 126.92761 -289.79876)
		(width 0.1143)
		(layer "In13.Cu")
		(net "P5E_CPU1_P2_TX_DN<15>")
	)
	(segment
		(start 126.89713 -291.400992)
		(end 126.92761 -291.418772)
		(width 0.1143)
		(layer "In13.Cu")
		(net "P5E_CPU1_P2_TX_DN<15>")
	)
	(segment
		(start 173.154848 -373.235982)
		(end 173.154848 -378.74067)
		(width 0.14224)
		(layer "In13.Cu")
		(net "P5E_CPU1_P2_TX_DN<15>")
	)
	(segment
		(start 173.259496 -371.470936)
		(end 173.259496 -372.657116)
		(width 0.14224)
		(layer "In13.Cu")
		(net "P5E_CPU1_P2_TX_DN<15>")
	)
	(segment
		(start 172.43298 -379.803406)
		(end 171.790106 -380.069598)
		(width 0.14224)
		(layer "In13.Cu")
		(net "P5E_CPU1_P2_TX_DN<15>")
	)
	(segment
		(start 169.778172 -366.064546)
		(end 170.399964 -366.686338)
		(width 0.14224)
		(layer "In13.Cu")
		(net "P5E_CPU1_P2_TX_DN<15>")
	)
	(segment
		(start 128.421638 -296.742104)
		(end 135.10006 -305.533044)
		(width 0.14224)
		(layer "In13.Cu")
		(net "P5E_CPU1_P2_TX_DN<15>")
	)
	(segment
		(start 126.267972 -272.442178)
		(end 126.267972 -272.46326)
		(width 0.1143)
		(layer "In13.Cu")
		(net "P5E_CPU1_P2_TX_DN<15>")
	)
	(segment
		(start 126.174754 -271.656302)
		(end 125.876812 -271.656302)
		(width 0.1143)
		(layer "In13.Cu")
		(net "P5E_CPU1_P2_TX_DN<15>")
	)
	(segment
		(start 127.397764 -295.468802)
		(end 127.43688 -295.491662)
		(width 0.1143)
		(layer "In13.Cu")
		(net "P5E_CPU1_P2_TX_DN<15>")
	)
	(segment
		(start 126.89713 -293.021004)
		(end 126.92761 -293.038784)
		(width 0.1143)
		(layer "In13.Cu")
		(net "P5E_CPU1_P2_TX_DN<15>")
	)
	(segment
		(start 126.92761 -294.013636)
		(end 126.89713 -294.031416)
		(width 0.1143)
		(layer "In13.Cu")
		(net "P5E_CPU1_P2_TX_DN<15>")
	)
	(segment
		(start 126.92761 -281.698954)
		(end 126.966726 -281.721814)
		(width 0.1143)
		(layer "In13.Cu")
		(net "P5E_CPU1_P2_TX_DN<15>")
	)
	(segment
		(start 126.92761 -276.193758)
		(end 126.89713 -276.211538)
		(width 0.1143)
		(layer "In13.Cu")
		(net "P5E_CPU1_P2_TX_DN<15>")
	)
	(segment
		(start 126.966726 -284.270958)
		(end 126.92761 -284.293818)
		(width 0.1143)
		(layer "In13.Cu")
		(net "P5E_CPU1_P2_TX_DN<15>")
	)
	(segment
		(start 154.56789 -356.904036)
		(end 157.663134 -360.319574)
		(width 0.14224)
		(layer "In13.Cu")
		(net "P5E_CPU1_P2_TX_DN<15>")
	)
	(segment
		(start 126.92761 -289.79876)
		(end 126.966726 -289.82162)
		(width 0.1143)
		(layer "In13.Cu")
		(net "P5E_CPU1_P2_TX_DN<15>")
	)
	(segment
		(start 154.152092 -356.308406)
		(end 154.513788 -356.83571)
		(width 0.14224)
		(layer "In13.Cu")
		(net "P5E_CPU1_P2_TX_DN<15>")
	)
	(segment
		(start 126.966726 -282.650946)
		(end 126.92761 -282.673806)
		(width 0.1143)
		(layer "In13.Cu")
		(net "P5E_CPU1_P2_TX_DN<15>")
	)
	(segment
		(start 126.92761 -294.658796)
		(end 126.966726 -294.681656)
		(width 0.1143)
		(layer "In13.Cu")
		(net "P5E_CPU1_P2_TX_DN<15>")
	)
	(segment
		(start 126.92761 -275.218906)
		(end 126.966726 -275.241766)
		(width 0.1143)
		(layer "In13.Cu")
		(net "P5E_CPU1_P2_TX_DN<15>")
	)
	(segment
		(start 126.966726 -276.170898)
		(end 126.92761 -276.193758)
		(width 0.1143)
		(layer "In13.Cu")
		(net "P5E_CPU1_P2_TX_DN<15>")
	)
	(segment
		(start 128.11252 -296.497248)
		(end 128.176528 -296.497248)
		(width 0.1143)
		(layer "In13.Cu")
		(net "P5E_CPU1_P2_TX_DN<15>")
	)
	(segment
		(start 126.92761 -290.773612)
		(end 126.89713 -290.791392)
		(width 0.1143)
		(layer "In13.Cu")
		(net "P5E_CPU1_P2_TX_DN<15>")
	)
	(segment
		(start 126.45263 -272.786094)
		(end 126.454916 -272.787364)
		(width 0.1143)
		(layer "In13.Cu")
		(net "P5E_CPU1_P2_TX_DN<15>")
	)
	(segment
		(start 141.343126 -315.712094)
		(end 141.343126 -315.712348)
		(width 0.14224)
		(layer "In13.Cu")
		(net "P5E_CPU1_P2_TX_DN<15>")
	)
	(segment
		(start 126.966726 -289.13074)
		(end 126.92761 -289.1536)
		(width 0.1143)
		(layer "In13.Cu")
		(net "P5E_CPU1_P2_TX_DN<15>")
	)
	(segment
		(start 125.876812 -271.656302)
		(end 125.806962 -271.726152)
		(width 0.1143)
		(layer "In13.Cu")
		(net "P5E_CPU1_P2_TX_DN<15>")
	)
	(segment
		(start 135.10006 -305.533044)
		(end 139.108688 -311.531762)
		(width 0.14224)
		(layer "In13.Cu")
		(net "P5E_CPU1_P2_TX_DN<15>")
	)
	(segment
		(start 126.92761 -292.393624)
		(end 126.89713 -292.411404)
		(width 0.1143)
		(layer "In13.Cu")
		(net "P5E_CPU1_P2_TX_DN<15>")
	)
	(segment
		(start 143.577564 -319.893188)
		(end 144.403318 -321.886072)
		(width 0.14224)
		(layer "In13.Cu")
		(net "P5E_CPU1_P2_TX_DN<15>")
	)
	(segment
		(start 126.89713 -283.301186)
		(end 126.92761 -283.318966)
		(width 0.1143)
		(layer "In13.Cu")
		(net "P5E_CPU1_P2_TX_DN<15>")
	)
	(segment
		(start 157.766004 -360.391964)
		(end 164.673026 -363.25302)
		(width 0.14224)
		(layer "In13.Cu")
		(net "P5E_CPU1_P2_TX_DN<15>")
	)
	(segment
		(start 126.92761 -274.573746)
		(end 126.89713 -274.591526)
		(width 0.1143)
		(layer "In13.Cu")
		(net "P5E_CPU1_P2_TX_DN<15>")
	)
	(segment
		(start 126.92761 -291.418772)
		(end 126.966726 -291.441632)
		(width 0.1143)
		(layer "In13.Cu")
		(net "P5E_CPU1_P2_TX_DN<15>")
	)
	(segment
		(start 172.741336 -370.098828)
		(end 173.213522 -371.239796)
		(width 0.14224)
		(layer "In13.Cu")
		(net "P5E_CPU1_P2_TX_DN<15>")
	)
	(arc
		(start 126.89713 -292.411404)
		(mid 126.740153 -292.716204)
		(end 126.89713 -293.021004)
		(width 0.1143)
		(layer "In13.Cu")
		(net "P5E_CPU1_P2_TX_DN<15>")
	)
	(arc
		(start 126.966726 -294.681656)
		(mid 127.145539 -294.884006)
		(end 127.210058 -295.146222)
		(width 0.1143)
		(layer "In13.Cu")
		(net "P5E_CPU1_P2_TX_DN<15>")
	)
	(arc
		(start 126.966726 -278.48179)
		(mid 127.210053 -278.946356)
		(end 126.966726 -279.410922)
		(width 0.1143)
		(layer "In13.Cu")
		(net "P5E_CPU1_P2_TX_DN<15>")
	)
	(arc
		(start 126.89713 -282.691586)
		(mid 126.740153 -282.996386)
		(end 126.89713 -283.301186)
		(width 0.1143)
		(layer "In13.Cu")
		(net "P5E_CPU1_P2_TX_DN<15>")
	)
	(arc
		(start 126.267972 -272.46326)
		(mid 126.317462 -272.649175)
		(end 126.45263 -272.786094)
		(width 0.1143)
		(layer "In13.Cu")
		(net "P5E_CPU1_P2_TX_DN<15>")
	)
	(arc
		(start 173.232826 -372.857268)
		(mid 173.221951 -372.894355)
		(end 173.209458 -372.930928)
		(width 0.14224)
		(layer "In13.Cu")
		(net "P5E_CPU1_P2_TX_DN<15>")
	)
	(arc
		(start 172.655484 -369.938554)
		(mid 172.702351 -370.01658)
		(end 172.741336 -370.098828)
		(width 0.14224)
		(layer "In13.Cu")
		(net "P5E_CPU1_P2_TX_DN<15>")
	)
	(arc
		(start 127.210058 -287.046162)
		(mid 127.144822 -287.309753)
		(end 126.964186 -287.512506)
		(width 0.1143)
		(layer "In13.Cu")
		(net "P5E_CPU1_P2_TX_DN<15>")
	)
	(arc
		(start 127.43688 -295.491662)
		(mid 127.615693 -295.694012)
		(end 127.680212 -295.956228)
		(width 0.1143)
		(layer "In13.Cu")
		(net "P5E_CPU1_P2_TX_DN<15>")
	)
	(arc
		(start 154.08783 -356.199694)
		(mid 154.118134 -356.25513)
		(end 154.152092 -356.308406)
		(width 0.14224)
		(layer "In13.Cu")
		(net "P5E_CPU1_P2_TX_DN<15>")
	)
	(arc
		(start 126.740158 -286.23641)
		(mid 126.781124 -286.406816)
		(end 126.895098 -286.53994)
		(width 0.1143)
		(layer "In13.Cu")
		(net "P5E_CPU1_P2_TX_DN<15>")
	)
	(arc
		(start 127.210058 -295.146222)
		(mid 127.251313 -295.317193)
		(end 127.366014 -295.450514)
		(width 0.1143)
		(layer "In13.Cu")
		(net "P5E_CPU1_P2_TX_DN<15>")
	)
	(arc
		(start 173.209458 -372.930928)
		(mid 173.16866 -373.081038)
		(end 173.154848 -373.235982)
		(width 0.14224)
		(layer "In13.Cu")
		(net "P5E_CPU1_P2_TX_DN<15>")
	)
	(arc
		(start 126.966726 -291.441632)
		(mid 127.210053 -291.906198)
		(end 126.966726 -292.370764)
		(width 0.1143)
		(layer "In13.Cu")
		(net "P5E_CPU1_P2_TX_DN<15>")
	)
	(arc
		(start 126.89713 -294.031416)
		(mid 126.740153 -294.336216)
		(end 126.89713 -294.641016)
		(width 0.1143)
		(layer "In13.Cu")
		(net "P5E_CPU1_P2_TX_DN<15>")
	)
	(arc
		(start 126.00686 -271.990058)
		(mid 126.198009 -272.181125)
		(end 126.267972 -272.442178)
		(width 0.1143)
		(layer "In13.Cu")
		(net "P5E_CPU1_P2_TX_DN<15>")
	)
	(arc
		(start 126.966726 -280.101802)
		(mid 127.210053 -280.566368)
		(end 126.966726 -281.030934)
		(width 0.1143)
		(layer "In13.Cu")
		(net "P5E_CPU1_P2_TX_DN<15>")
	)
	(arc
		(start 173.259496 -372.657116)
		(mid 173.252852 -372.758084)
		(end 173.232826 -372.857268)
		(width 0.14224)
		(layer "In13.Cu")
		(net "P5E_CPU1_P2_TX_DN<15>")
	)
	(arc
		(start 126.966726 -275.241766)
		(mid 127.210053 -275.706332)
		(end 126.966726 -276.170898)
		(width 0.1143)
		(layer "In13.Cu")
		(net "P5E_CPU1_P2_TX_DN<15>")
	)
	(arc
		(start 126.89713 -290.791392)
		(mid 126.740153 -291.096192)
		(end 126.89713 -291.400992)
		(width 0.1143)
		(layer "In13.Cu")
		(net "P5E_CPU1_P2_TX_DN<15>")
	)
	(arc
		(start 126.89713 -284.311598)
		(mid 126.740153 -284.616398)
		(end 126.89713 -284.921198)
		(width 0.1143)
		(layer "In13.Cu")
		(net "P5E_CPU1_P2_TX_DN<15>")
	)
	(arc
		(start 126.496064 -272.81124)
		(mid 126.496445 -272.811494)
		(end 126.496826 -272.811748)
		(width 0.1143)
		(layer "In13.Cu")
		(net "P5E_CPU1_P2_TX_DN<15>")
	)
	(arc
		(start 126.89713 -277.83155)
		(mid 126.740153 -278.13635)
		(end 126.89713 -278.44115)
		(width 0.1143)
		(layer "In13.Cu")
		(net "P5E_CPU1_P2_TX_DN<15>")
	)
	(arc
		(start 127.867664 -296.278808)
		(mid 127.90135 -296.299994)
		(end 127.93345 -296.323512)
		(width 0.1143)
		(layer "In13.Cu")
		(net "P5E_CPU1_P2_TX_DN<15>")
	)
	(arc
		(start 172.914056 -379.32233)
		(mid 172.721369 -379.610719)
		(end 172.43298 -379.803406)
		(width 0.14224)
		(layer "In13.Cu")
		(net "P5E_CPU1_P2_TX_DN<15>")
	)
	(arc
		(start 126.89713 -279.451562)
		(mid 126.740153 -279.756362)
		(end 126.89713 -280.061162)
		(width 0.1143)
		(layer "In13.Cu")
		(net "P5E_CPU1_P2_TX_DN<15>")
	)
	(arc
		(start 126.89713 -281.071574)
		(mid 126.740153 -281.376374)
		(end 126.89713 -281.681174)
		(width 0.1143)
		(layer "In13.Cu")
		(net "P5E_CPU1_P2_TX_DN<15>")
	)
	(arc
		(start 170.399964 -366.686338)
		(mid 170.624285 -366.932537)
		(end 170.824906 -367.198402)
		(width 0.14224)
		(layer "In13.Cu")
		(net "P5E_CPU1_P2_TX_DN<15>")
	)
	(arc
		(start 125.806962 -271.726152)
		(mid 125.859011 -271.857671)
		(end 125.95606 -271.960594)
		(width 0.1143)
		(layer "In13.Cu")
		(net "P5E_CPU1_P2_TX_DN<15>")
	)
	(arc
		(start 157.663134 -360.319574)
		(mid 157.710553 -360.361474)
		(end 157.766004 -360.391964)
		(width 0.14224)
		(layer "In13.Cu")
		(net "P5E_CPU1_P2_TX_DN<15>")
	)
	(arc
		(start 126.966726 -276.861778)
		(mid 127.210053 -277.326344)
		(end 126.966726 -277.79091)
		(width 0.1143)
		(layer "In13.Cu")
		(net "P5E_CPU1_P2_TX_DN<15>")
	)
	(arc
		(start 126.740158 -273.276314)
		(mid 126.781707 -273.447736)
		(end 126.89713 -273.581114)
		(width 0.1143)
		(layer "In13.Cu")
		(net "P5E_CPU1_P2_TX_DN<15>")
	)
	(arc
		(start 126.740158 -287.856422)
		(mid 126.781124 -288.026828)
		(end 126.895098 -288.159952)
		(width 0.1143)
		(layer "In13.Cu")
		(net "P5E_CPU1_P2_TX_DN<15>")
	)
	(arc
		(start 154.513788 -356.83571)
		(mid 154.539697 -356.870778)
		(end 154.56789 -356.904036)
		(width 0.14224)
		(layer "In13.Cu")
		(net "P5E_CPU1_P2_TX_DN<15>")
	)
	(arc
		(start 126.966726 -281.721814)
		(mid 127.210053 -282.18638)
		(end 126.966726 -282.650946)
		(width 0.1143)
		(layer "In13.Cu")
		(net "P5E_CPU1_P2_TX_DN<15>")
	)
	(arc
		(start 126.966726 -283.341826)
		(mid 127.210053 -283.806392)
		(end 126.966726 -284.270958)
		(width 0.1143)
		(layer "In13.Cu")
		(net "P5E_CPU1_P2_TX_DN<15>")
	)
	(arc
		(start 167.030146 -364.229396)
		(mid 168.494404 -365.011835)
		(end 169.778172 -366.064546)
		(width 0.14224)
		(layer "In13.Cu")
		(net "P5E_CPU1_P2_TX_DN<15>")
	)
	(arc
		(start 126.966726 -286.581596)
		(mid 127.145539 -286.783946)
		(end 127.210058 -287.046162)
		(width 0.1143)
		(layer "In13.Cu")
		(net "P5E_CPU1_P2_TX_DN<15>")
	)
	(arc
		(start 126.89713 -287.551622)
		(mid 126.781703 -287.684998)
		(end 126.740158 -287.856422)
		(width 0.1143)
		(layer "In13.Cu")
		(net "P5E_CPU1_P2_TX_DN<15>")
	)
	(arc
		(start 126.89713 -285.93161)
		(mid 126.781703 -286.064986)
		(end 126.740158 -286.23641)
		(width 0.1143)
		(layer "In13.Cu")
		(net "P5E_CPU1_P2_TX_DN<15>")
	)
	(arc
		(start 126.966726 -288.201608)
		(mid 127.210053 -288.666174)
		(end 126.966726 -289.13074)
		(width 0.1143)
		(layer "In13.Cu")
		(net "P5E_CPU1_P2_TX_DN<15>")
	)
	(arc
		(start 127.680212 -295.956228)
		(mid 127.721761 -296.12765)
		(end 127.837184 -296.261028)
		(width 0.1143)
		(layer "In13.Cu")
		(net "P5E_CPU1_P2_TX_DN<15>")
	)
	(arc
		(start 126.966726 -293.061644)
		(mid 127.210053 -293.52621)
		(end 126.966726 -293.990776)
		(width 0.1143)
		(layer "In13.Cu")
		(net "P5E_CPU1_P2_TX_DN<15>")
	)
	(arc
		(start 126.89713 -276.211538)
		(mid 126.740153 -276.516338)
		(end 126.89713 -276.821138)
		(width 0.1143)
		(layer "In13.Cu")
		(net "P5E_CPU1_P2_TX_DN<15>")
	)
	(arc
		(start 126.89713 -274.591526)
		(mid 126.740153 -274.896326)
		(end 126.89713 -275.201126)
		(width 0.1143)
		(layer "In13.Cu")
		(net "P5E_CPU1_P2_TX_DN<15>")
	)
	(arc
		(start 126.89713 -289.17138)
		(mid 126.740153 -289.47618)
		(end 126.89713 -289.78098)
		(width 0.1143)
		(layer "In13.Cu")
		(net "P5E_CPU1_P2_TX_DN<15>")
	)
	(arc
		(start 173.213522 -371.239796)
		(mid 173.247863 -371.353106)
		(end 173.259496 -371.470936)
		(width 0.14224)
		(layer "In13.Cu")
		(net "P5E_CPU1_P2_TX_DN<15>")
	)
	(arc
		(start 126.966726 -289.82162)
		(mid 127.210053 -290.286186)
		(end 126.966726 -290.750752)
		(width 0.1143)
		(layer "In13.Cu")
		(net "P5E_CPU1_P2_TX_DN<15>")
	)
	(arc
		(start 126.966726 -273.621754)
		(mid 127.210053 -274.08632)
		(end 126.966726 -274.550886)
		(width 0.1143)
		(layer "In13.Cu")
		(net "P5E_CPU1_P2_TX_DN<15>")
	)
	(arc
		(start 127.93345 -296.323512)
		(mid 127.958728 -296.344765)
		(end 127.982726 -296.367454)
		(width 0.1143)
		(layer "In13.Cu")
		(net "P5E_CPU1_P2_TX_DN<15>")
	)
	(arc
		(start 126.496826 -272.811748)
		(mid 126.675639 -273.014098)
		(end 126.740158 -273.276314)
		(width 0.1143)
		(layer "In13.Cu")
		(net "P5E_CPU1_P2_TX_DN<15>")
	)
	(arc
		(start 126.966726 -284.961838)
		(mid 127.210053 -285.426404)
		(end 126.966726 -285.89097)
		(width 0.1143)
		(layer "In13.Cu")
		(net "P5E_CPU1_P2_TX_DN<15>")
	)
	(segment
		(start 125.707902 -273.010376)
		(end 126.174754 -273.276314)
		(width 0.12954)
		(layer "F.Cu")
		(net "P5E_CPU1_P2_TX_DN<14>")
	)
	(segment
		(start 170.905424 -376.956828)
		(end 170.634914 -376.686318)
		(width 0.12954)
		(layer "F.Cu")
		(net "P5E_CPU1_P2_TX_DN<14>")
	)
	(segment
		(start 170.634914 -376.686318)
		(end 169.931334 -376.686318)
		(width 0.12954)
		(layer "F.Cu")
		(net "P5E_CPU1_P2_TX_DN<14>")
	)
	(segment
		(start 169.931334 -376.686318)
		(end 169.635424 -376.982228)
		(width 0.12954)
		(layer "F.Cu")
		(net "P5E_CPU1_P2_TX_DN<14>")
	)
	(segment
		(start 125.95606 -273.580606)
		(end 125.987048 -273.598386)
		(width 0.1143)
		(layer "In13.Cu")
		(net "P5E_CPU1_P2_TX_DN<14>")
	)
	(segment
		(start 125.95606 -280.060654)
		(end 125.98781 -280.078942)
		(width 0.1143)
		(layer "In13.Cu")
		(net "P5E_CPU1_P2_TX_DN<14>")
	)
	(segment
		(start 126.740158 -296.123106)
		(end 127.09906 -296.482008)
		(width 0.1143)
		(layer "In13.Cu")
		(net "P5E_CPU1_P2_TX_DN<14>")
	)
	(segment
		(start 171.927266 -370.586254)
		(end 172.262038 -371.396006)
		(width 0.14224)
		(layer "In13.Cu")
		(net "P5E_CPU1_P2_TX_DN<14>")
	)
	(segment
		(start 125.987048 -279.43429)
		(end 125.985778 -279.435052)
		(width 0.1143)
		(layer "In13.Cu")
		(net "P5E_CPU1_P2_TX_DN<14>")
	)
	(segment
		(start 125.95606 -289.780472)
		(end 125.98781 -289.79876)
		(width 0.1143)
		(layer "In13.Cu")
		(net "P5E_CPU1_P2_TX_DN<14>")
	)
	(segment
		(start 125.990604 -278.460708)
		(end 126.026672 -278.481536)
		(width 0.1143)
		(layer "In13.Cu")
		(net "P5E_CPU1_P2_TX_DN<14>")
	)
	(segment
		(start 126.02591 -292.37178)
		(end 125.95606 -292.411912)
		(width 0.1143)
		(layer "In13.Cu")
		(net "P5E_CPU1_P2_TX_DN<14>")
	)
	(segment
		(start 125.990858 -294.011858)
		(end 125.95606 -294.031924)
		(width 0.1143)
		(layer "In13.Cu")
		(net "P5E_CPU1_P2_TX_DN<14>")
	)
	(segment
		(start 170.142154 -367.860834)
		(end 171.842176 -370.426742)
		(width 0.14224)
		(layer "In13.Cu")
		(net "P5E_CPU1_P2_TX_DN<14>")
	)
	(segment
		(start 125.98781 -291.419026)
		(end 126.02591 -291.440616)
		(width 0.1143)
		(layer "In13.Cu")
		(net "P5E_CPU1_P2_TX_DN<14>")
	)
	(segment
		(start 126.027942 -287.510474)
		(end 125.95606 -287.55213)
		(width 0.1143)
		(layer "In13.Cu")
		(net "P5E_CPU1_P2_TX_DN<14>")
	)
	(segment
		(start 125.989334 -279.432766)
		(end 125.987048 -279.43429)
		(width 0.1143)
		(layer "In13.Cu")
		(net "P5E_CPU1_P2_TX_DN<14>")
	)
	(segment
		(start 125.95606 -283.300678)
		(end 125.987048 -283.318458)
		(width 0.1143)
		(layer "In13.Cu")
		(net "P5E_CPU1_P2_TX_DN<14>")
	)
	(segment
		(start 125.991366 -294.660828)
		(end 125.992128 -294.661336)
		(width 0.1143)
		(layer "In13.Cu")
		(net "P5E_CPU1_P2_TX_DN<14>")
	)
	(segment
		(start 136.779254 -309.746396)
		(end 138.362436 -312.116216)
		(width 0.14224)
		(layer "In13.Cu")
		(net "P5E_CPU1_P2_TX_DN<14>")
	)
	(segment
		(start 125.98781 -280.078942)
		(end 126.024132 -280.100024)
		(width 0.1143)
		(layer "In13.Cu")
		(net "P5E_CPU1_P2_TX_DN<14>")
	)
	(segment
		(start 128.542542 -298.641008)
		(end 136.779254 -309.746396)
		(width 0.14224)
		(layer "In13.Cu")
		(net "P5E_CPU1_P2_TX_DN<14>")
	)
	(segment
		(start 125.876812 -273.276314)
		(end 125.806962 -273.346164)
		(width 0.1143)
		(layer "In13.Cu")
		(net "P5E_CPU1_P2_TX_DN<14>")
	)
	(segment
		(start 125.954282 -286.539178)
		(end 126.028958 -286.58312)
		(width 0.1143)
		(layer "In13.Cu")
		(net "P5E_CPU1_P2_TX_DN<14>")
	)
	(segment
		(start 125.987048 -275.218398)
		(end 125.98781 -275.218906)
		(width 0.1143)
		(layer "In13.Cu")
		(net "P5E_CPU1_P2_TX_DN<14>")
	)
	(segment
		(start 125.985778 -277.81504)
		(end 125.95606 -277.832058)
		(width 0.1143)
		(layer "In13.Cu")
		(net "P5E_CPU1_P2_TX_DN<14>")
	)
	(segment
		(start 127.14478 -296.850308)
		(end 127.145288 -296.850816)
		(width 0.1143)
		(layer "In13.Cu")
		(net "P5E_CPU1_P2_TX_DN<14>")
	)
	(segment
		(start 127.14478 -296.822368)
		(end 127.14478 -296.850308)
		(width 0.1143)
		(layer "In13.Cu")
		(net "P5E_CPU1_P2_TX_DN<14>")
	)
	(segment
		(start 126.459234 -295.469818)
		(end 126.496572 -295.491154)
		(width 0.1143)
		(layer "In13.Cu")
		(net "P5E_CPU1_P2_TX_DN<14>")
	)
	(segment
		(start 125.992128 -294.661336)
		(end 126.027942 -294.682418)
		(width 0.1143)
		(layer "In13.Cu")
		(net "P5E_CPU1_P2_TX_DN<14>")
	)
	(segment
		(start 125.987048 -274.574254)
		(end 125.985778 -274.575016)
		(width 0.1143)
		(layer "In13.Cu")
		(net "P5E_CPU1_P2_TX_DN<14>")
	)
	(segment
		(start 125.990858 -289.151822)
		(end 125.95606 -289.171888)
		(width 0.1143)
		(layer "In13.Cu")
		(net "P5E_CPU1_P2_TX_DN<14>")
	)
	(segment
		(start 125.987048 -273.598386)
		(end 125.98781 -273.598894)
		(width 0.1143)
		(layer "In13.Cu")
		(net "P5E_CPU1_P2_TX_DN<14>")
	)
	(segment
		(start 171.82338 -373.05869)
		(end 171.82338 -374.09882)
		(width 0.14224)
		(layer "In13.Cu")
		(net "P5E_CPU1_P2_TX_DN<14>")
	)
	(segment
		(start 127.09906 -296.776648)
		(end 127.14478 -296.822368)
		(width 0.1143)
		(layer "In13.Cu")
		(net "P5E_CPU1_P2_TX_DN<14>")
	)
	(segment
		(start 125.985778 -279.435052)
		(end 125.95606 -279.45207)
		(width 0.1143)
		(layer "In13.Cu")
		(net "P5E_CPU1_P2_TX_DN<14>")
	)
	(segment
		(start 127.145288 -296.87266)
		(end 127.155194 -296.899584)
		(width 0.14224)
		(layer "In13.Cu")
		(net "P5E_CPU1_P2_TX_DN<14>")
	)
	(segment
		(start 125.98781 -294.658796)
		(end 125.991366 -294.660828)
		(width 0.1143)
		(layer "In13.Cu")
		(net "P5E_CPU1_P2_TX_DN<14>")
	)
	(segment
		(start 125.98781 -288.178748)
		(end 125.990858 -288.180526)
		(width 0.1143)
		(layer "In13.Cu")
		(net "P5E_CPU1_P2_TX_DN<14>")
	)
	(segment
		(start 169.004996 -366.644936)
		(end 169.788586 -367.428526)
		(width 0.14224)
		(layer "In13.Cu")
		(net "P5E_CPU1_P2_TX_DN<14>")
	)
	(segment
		(start 126.054612 -277.771098)
		(end 126.026672 -277.791164)
		(width 0.1143)
		(layer "In13.Cu")
		(net "P5E_CPU1_P2_TX_DN<14>")
	)
	(segment
		(start 125.98781 -273.598894)
		(end 126.024132 -273.619976)
		(width 0.1143)
		(layer "In13.Cu")
		(net "P5E_CPU1_P2_TX_DN<14>")
	)
	(segment
		(start 126.024132 -281.032712)
		(end 125.98781 -281.053794)
		(width 0.1143)
		(layer "In13.Cu")
		(net "P5E_CPU1_P2_TX_DN<14>")
	)
	(segment
		(start 125.955044 -288.159698)
		(end 125.98781 -288.178748)
		(width 0.1143)
		(layer "In13.Cu")
		(net "P5E_CPU1_P2_TX_DN<14>")
	)
	(segment
		(start 125.987048 -276.83841)
		(end 125.98781 -276.838918)
		(width 0.1143)
		(layer "In13.Cu")
		(net "P5E_CPU1_P2_TX_DN<14>")
	)
	(segment
		(start 125.985778 -276.195028)
		(end 125.95606 -276.212046)
		(width 0.1143)
		(layer "In13.Cu")
		(net "P5E_CPU1_P2_TX_DN<14>")
	)
	(segment
		(start 126.174754 -273.276314)
		(end 125.876812 -273.276314)
		(width 0.1143)
		(layer "In13.Cu")
		(net "P5E_CPU1_P2_TX_DN<14>")
	)
	(segment
		(start 126.054612 -279.39111)
		(end 126.026672 -279.411176)
		(width 0.1143)
		(layer "In13.Cu")
		(net "P5E_CPU1_P2_TX_DN<14>")
	)
	(segment
		(start 125.95606 -281.680666)
		(end 125.98781 -281.698954)
		(width 0.1143)
		(layer "In13.Cu")
		(net "P5E_CPU1_P2_TX_DN<14>")
	)
	(segment
		(start 171.196254 -376.665998)
		(end 170.905424 -376.956828)
		(width 0.14224)
		(layer "In13.Cu")
		(net "P5E_CPU1_P2_TX_DN<14>")
	)
	(segment
		(start 172.307758 -371.6274)
		(end 172.307758 -371.88902)
		(width 0.14224)
		(layer "In13.Cu")
		(net "P5E_CPU1_P2_TX_DN<14>")
	)
	(segment
		(start 125.987048 -277.814278)
		(end 125.985778 -277.81504)
		(width 0.1143)
		(layer "In13.Cu")
		(net "P5E_CPU1_P2_TX_DN<14>")
	)
	(segment
		(start 127.145288 -296.850816)
		(end 127.145288 -296.87266)
		(width 0.14224)
		(layer "In13.Cu")
		(net "P5E_CPU1_P2_TX_DN<14>")
	)
	(segment
		(start 126.039372 -287.501838)
		(end 126.027942 -287.510474)
		(width 0.1143)
		(layer "In13.Cu")
		(net "P5E_CPU1_P2_TX_DN<14>")
	)
	(segment
		(start 126.02591 -291.440616)
		(end 126.038864 -291.450014)
		(width 0.1143)
		(layer "In13.Cu")
		(net "P5E_CPU1_P2_TX_DN<14>")
	)
	(segment
		(start 125.987048 -278.458422)
		(end 125.98781 -278.45893)
		(width 0.1143)
		(layer "In13.Cu")
		(net "P5E_CPU1_P2_TX_DN<14>")
	)
	(segment
		(start 125.985778 -274.575016)
		(end 125.95606 -274.592034)
		(width 0.1143)
		(layer "In13.Cu")
		(net "P5E_CPU1_P2_TX_DN<14>")
	)
	(segment
		(start 125.95606 -276.82063)
		(end 125.987048 -276.83841)
		(width 0.1143)
		(layer "In13.Cu")
		(net "P5E_CPU1_P2_TX_DN<14>")
	)
	(segment
		(start 125.990858 -290.771834)
		(end 125.95606 -290.7919)
		(width 0.1143)
		(layer "In13.Cu")
		(net "P5E_CPU1_P2_TX_DN<14>")
	)
	(segment
		(start 125.98781 -283.318966)
		(end 125.990858 -283.320744)
		(width 0.1143)
		(layer "In13.Cu")
		(net "P5E_CPU1_P2_TX_DN<14>")
	)
	(segment
		(start 125.987048 -283.318458)
		(end 125.98781 -283.318966)
		(width 0.1143)
		(layer "In13.Cu")
		(net "P5E_CPU1_P2_TX_DN<14>")
	)
	(segment
		(start 126.024132 -274.552664)
		(end 125.98781 -274.573746)
		(width 0.1143)
		(layer "In13.Cu")
		(net "P5E_CPU1_P2_TX_DN<14>")
	)
	(segment
		(start 142.681452 -320.196972)
		(end 143.51762 -322.21551)
		(width 0.14224)
		(layer "In13.Cu")
		(net "P5E_CPU1_P2_TX_DN<14>")
	)
	(segment
		(start 125.95606 -275.200618)
		(end 125.987048 -275.218398)
		(width 0.1143)
		(layer "In13.Cu")
		(net "P5E_CPU1_P2_TX_DN<14>")
	)
	(segment
		(start 125.98781 -289.79876)
		(end 125.990858 -289.800538)
		(width 0.1143)
		(layer "In13.Cu")
		(net "P5E_CPU1_P2_TX_DN<14>")
	)
	(segment
		(start 126.026672 -278.481536)
		(end 126.054612 -278.501602)
		(width 0.1143)
		(layer "In13.Cu")
		(net "P5E_CPU1_P2_TX_DN<14>")
	)
	(segment
		(start 125.990604 -276.840696)
		(end 126.026672 -276.861524)
		(width 0.1143)
		(layer "In13.Cu")
		(net "P5E_CPU1_P2_TX_DN<14>")
	)
	(segment
		(start 127.248666 -297.064938)
		(end 128.542542 -298.641008)
		(width 0.14224)
		(layer "In13.Cu")
		(net "P5E_CPU1_P2_TX_DN<14>")
	)
	(segment
		(start 125.987048 -276.194266)
		(end 125.985778 -276.195028)
		(width 0.1143)
		(layer "In13.Cu")
		(net "P5E_CPU1_P2_TX_DN<14>")
	)
	(segment
		(start 126.026672 -277.791164)
		(end 125.989334 -277.812754)
		(width 0.1143)
		(layer "In13.Cu")
		(net "P5E_CPU1_P2_TX_DN<14>")
	)
	(segment
		(start 125.990858 -285.912052)
		(end 125.95606 -285.932118)
		(width 0.1143)
		(layer "In13.Cu")
		(net "P5E_CPU1_P2_TX_DN<14>")
	)
	(segment
		(start 125.98781 -281.053794)
		(end 125.95606 -281.072082)
		(width 0.1143)
		(layer "In13.Cu")
		(net "P5E_CPU1_P2_TX_DN<14>")
	)
	(segment
		(start 125.95606 -293.020496)
		(end 125.98781 -293.038784)
		(width 0.1143)
		(layer "In13.Cu")
		(net "P5E_CPU1_P2_TX_DN<14>")
	)
	(segment
		(start 125.98781 -293.038784)
		(end 125.990858 -293.040562)
		(width 0.1143)
		(layer "In13.Cu")
		(net "P5E_CPU1_P2_TX_DN<14>")
	)
	(segment
		(start 126.270004 -287.046162)
		(end 126.270004 -287.050734)
		(width 0.1143)
		(layer "In13.Cu")
		(net "P5E_CPU1_P2_TX_DN<14>")
	)
	(segment
		(start 125.98781 -291.418772)
		(end 125.98781 -291.419026)
		(width 0.1143)
		(layer "In13.Cu")
		(net "P5E_CPU1_P2_TX_DN<14>")
	)
	(segment
		(start 154.16149 -358.053132)
		(end 157.289246 -361.503976)
		(width 0.14224)
		(layer "In13.Cu")
		(net "P5E_CPU1_P2_TX_DN<14>")
	)
	(segment
		(start 140.521944 -316.156594)
		(end 142.681452 -320.196972)
		(width 0.14224)
		(layer "In13.Cu")
		(net "P5E_CPU1_P2_TX_DN<14>")
	)
	(segment
		(start 125.98781 -276.838918)
		(end 125.990604 -276.840696)
		(width 0.1143)
		(layer "In13.Cu")
		(net "P5E_CPU1_P2_TX_DN<14>")
	)
	(segment
		(start 140.521944 -316.15634)
		(end 140.521944 -316.156594)
		(width 0.14224)
		(layer "In13.Cu")
		(net "P5E_CPU1_P2_TX_DN<14>")
	)
	(segment
		(start 166.60622 -365.363252)
		(end 169.004996 -366.644936)
		(width 0.14224)
		(layer "In13.Cu")
		(net "P5E_CPU1_P2_TX_DN<14>")
	)
	(segment
		(start 125.989334 -277.812754)
		(end 125.987048 -277.814278)
		(width 0.1143)
		(layer "In13.Cu")
		(net "P5E_CPU1_P2_TX_DN<14>")
	)
	(segment
		(start 138.362436 -312.116216)
		(end 140.521944 -316.15634)
		(width 0.14224)
		(layer "In13.Cu")
		(net "P5E_CPU1_P2_TX_DN<14>")
	)
	(segment
		(start 153.09977 -356.505764)
		(end 154.16149 -358.053132)
		(width 0.14224)
		(layer "In13.Cu")
		(net "P5E_CPU1_P2_TX_DN<14>")
	)
	(segment
		(start 127.09906 -296.482008)
		(end 127.09906 -296.776648)
		(width 0.1143)
		(layer "In13.Cu")
		(net "P5E_CPU1_P2_TX_DN<14>")
	)
	(segment
		(start 172.212508 -375.732802)
		(end 172.212508 -376.096784)
		(width 0.14224)
		(layer "In13.Cu")
		(net "P5E_CPU1_P2_TX_DN<14>")
	)
	(segment
		(start 127.155194 -296.899584)
		(end 127.248666 -297.064938)
		(width 0.14224)
		(layer "In13.Cu")
		(net "P5E_CPU1_P2_TX_DN<14>")
	)
	(segment
		(start 125.95606 -278.440642)
		(end 125.987048 -278.458422)
		(width 0.1143)
		(layer "In13.Cu")
		(net "P5E_CPU1_P2_TX_DN<14>")
	)
	(segment
		(start 125.990858 -282.672028)
		(end 125.95606 -282.692094)
		(width 0.1143)
		(layer "In13.Cu")
		(net "P5E_CPU1_P2_TX_DN<14>")
	)
	(segment
		(start 125.95606 -291.400484)
		(end 125.98781 -291.418772)
		(width 0.1143)
		(layer "In13.Cu")
		(net "P5E_CPU1_P2_TX_DN<14>")
	)
	(segment
		(start 125.990858 -284.29204)
		(end 125.95606 -284.312106)
		(width 0.1143)
		(layer "In13.Cu")
		(net "P5E_CPU1_P2_TX_DN<14>")
	)
	(segment
		(start 125.98781 -281.698954)
		(end 125.990858 -281.700732)
		(width 0.1143)
		(layer "In13.Cu")
		(net "P5E_CPU1_P2_TX_DN<14>")
	)
	(segment
		(start 125.95606 -284.92069)
		(end 125.98781 -284.938978)
		(width 0.1143)
		(layer "In13.Cu")
		(net "P5E_CPU1_P2_TX_DN<14>")
	)
	(segment
		(start 125.98781 -278.45893)
		(end 125.990604 -278.460708)
		(width 0.1143)
		(layer "In13.Cu")
		(net "P5E_CPU1_P2_TX_DN<14>")
	)
	(segment
		(start 157.289246 -361.503976)
		(end 166.60622 -365.363252)
		(width 0.14224)
		(layer "In13.Cu")
		(net "P5E_CPU1_P2_TX_DN<14>")
	)
	(segment
		(start 126.740158 -295.955974)
		(end 126.740158 -296.123106)
		(width 0.1143)
		(layer "In13.Cu")
		(net "P5E_CPU1_P2_TX_DN<14>")
	)
	(segment
		(start 126.026672 -279.411176)
		(end 125.989334 -279.432766)
		(width 0.1143)
		(layer "In13.Cu")
		(net "P5E_CPU1_P2_TX_DN<14>")
	)
	(segment
		(start 125.98781 -274.573746)
		(end 125.987048 -274.574254)
		(width 0.1143)
		(layer "In13.Cu")
		(net "P5E_CPU1_P2_TX_DN<14>")
	)
	(segment
		(start 125.95606 -294.640508)
		(end 125.98781 -294.658796)
		(width 0.1143)
		(layer "In13.Cu")
		(net "P5E_CPU1_P2_TX_DN<14>")
	)
	(segment
		(start 125.98781 -276.193758)
		(end 125.987048 -276.194266)
		(width 0.1143)
		(layer "In13.Cu")
		(net "P5E_CPU1_P2_TX_DN<14>")
	)
	(segment
		(start 125.98781 -275.218906)
		(end 126.024132 -275.239988)
		(width 0.1143)
		(layer "In13.Cu")
		(net "P5E_CPU1_P2_TX_DN<14>")
	)
	(segment
		(start 126.026672 -276.861524)
		(end 126.054612 -276.88159)
		(width 0.1143)
		(layer "In13.Cu")
		(net "P5E_CPU1_P2_TX_DN<14>")
	)
	(segment
		(start 126.024132 -276.172676)
		(end 125.98781 -276.193758)
		(width 0.1143)
		(layer "In13.Cu")
		(net "P5E_CPU1_P2_TX_DN<14>")
	)
	(segment
		(start 143.51762 -322.21551)
		(end 148.534374 -347.435424)
		(width 0.14224)
		(layer "In13.Cu")
		(net "P5E_CPU1_P2_TX_DN<14>")
	)
	(segment
		(start 125.954282 -288.15919)
		(end 125.955044 -288.159698)
		(width 0.1143)
		(layer "In13.Cu")
		(net "P5E_CPU1_P2_TX_DN<14>")
	)
	(segment
		(start 125.98781 -284.938978)
		(end 125.990858 -284.940756)
		(width 0.1143)
		(layer "In13.Cu")
		(net "P5E_CPU1_P2_TX_DN<14>")
	)
	(segment
		(start 126.038864 -292.362382)
		(end 126.02591 -292.37178)
		(width 0.1143)
		(layer "In13.Cu")
		(net "P5E_CPU1_P2_TX_DN<14>")
	)
	(segment
		(start 171.642532 -376.665998)
		(end 171.196254 -376.665998)
		(width 0.14224)
		(layer "In13.Cu")
		(net "P5E_CPU1_P2_TX_DN<14>")
	)
	(segment
		(start 148.534374 -347.435424)
		(end 153.09977 -356.505764)
		(width 0.14224)
		(layer "In13.Cu")
		(net "P5E_CPU1_P2_TX_DN<14>")
	)
	(arc
		(start 125.990858 -288.180526)
		(mid 126.270473 -288.666174)
		(end 125.990858 -289.151822)
		(width 0.1143)
		(layer "In13.Cu")
		(net "P5E_CPU1_P2_TX_DN<14>")
	)
	(arc
		(start 125.95606 -285.932118)
		(mid 125.841384 -286.065452)
		(end 125.800104 -286.23641)
		(width 0.1143)
		(layer "In13.Cu")
		(net "P5E_CPU1_P2_TX_DN<14>")
	)
	(arc
		(start 125.95606 -281.072082)
		(mid 125.800132 -281.376374)
		(end 125.95606 -281.680666)
		(width 0.1143)
		(layer "In13.Cu")
		(net "P5E_CPU1_P2_TX_DN<14>")
	)
	(arc
		(start 126.038356 -275.249894)
		(mid 126.265739 -275.706332)
		(end 126.038356 -276.16277)
		(width 0.1143)
		(layer "In13.Cu")
		(net "P5E_CPU1_P2_TX_DN<14>")
	)
	(arc
		(start 125.95606 -279.45207)
		(mid 125.800132 -279.756362)
		(end 125.95606 -280.060654)
		(width 0.1143)
		(layer "In13.Cu")
		(net "P5E_CPU1_P2_TX_DN<14>")
	)
	(arc
		(start 171.842176 -370.426742)
		(mid 171.88858 -370.50444)
		(end 171.927266 -370.586254)
		(width 0.14224)
		(layer "In13.Cu")
		(net "P5E_CPU1_P2_TX_DN<14>")
	)
	(arc
		(start 172.307758 -371.88902)
		(mid 172.200099 -372.43035)
		(end 171.893484 -372.889272)
		(width 0.14224)
		(layer "In13.Cu")
		(net "P5E_CPU1_P2_TX_DN<14>")
	)
	(arc
		(start 169.788586 -367.428526)
		(mid 169.976182 -367.635838)
		(end 170.142154 -367.860834)
		(width 0.14224)
		(layer "In13.Cu")
		(net "P5E_CPU1_P2_TX_DN<14>")
	)
	(arc
		(start 126.039372 -280.110692)
		(mid 126.264543 -280.566368)
		(end 126.039372 -281.022044)
		(width 0.1143)
		(layer "In13.Cu")
		(net "P5E_CPU1_P2_TX_DN<14>")
	)
	(arc
		(start 125.95606 -276.212046)
		(mid 125.800132 -276.516338)
		(end 125.95606 -276.82063)
		(width 0.1143)
		(layer "In13.Cu")
		(net "P5E_CPU1_P2_TX_DN<14>")
	)
	(arc
		(start 126.027942 -294.682418)
		(mid 126.2059 -294.882193)
		(end 126.270258 -295.141904)
		(width 0.1143)
		(layer "In13.Cu")
		(net "P5E_CPU1_P2_TX_DN<14>")
	)
	(arc
		(start 172.212508 -376.096784)
		(mid 172.045371 -376.4994)
		(end 171.642532 -376.665998)
		(width 0.14224)
		(layer "In13.Cu")
		(net "P5E_CPU1_P2_TX_DN<14>")
	)
	(arc
		(start 172.017944 -374.91543)
		(mid 172.163231 -375.312689)
		(end 172.212508 -375.732802)
		(width 0.14224)
		(layer "In13.Cu")
		(net "P5E_CPU1_P2_TX_DN<14>")
	)
	(arc
		(start 125.990858 -284.940756)
		(mid 126.270473 -285.426404)
		(end 125.990858 -285.912052)
		(width 0.1143)
		(layer "In13.Cu")
		(net "P5E_CPU1_P2_TX_DN<14>")
	)
	(arc
		(start 125.806962 -273.346164)
		(mid 125.859011 -273.477683)
		(end 125.95606 -273.580606)
		(width 0.1143)
		(layer "In13.Cu")
		(net "P5E_CPU1_P2_TX_DN<14>")
	)
	(arc
		(start 125.95606 -294.031924)
		(mid 125.800132 -294.336216)
		(end 125.95606 -294.640508)
		(width 0.1143)
		(layer "In13.Cu")
		(net "P5E_CPU1_P2_TX_DN<14>")
	)
	(arc
		(start 126.038864 -291.450014)
		(mid 126.273291 -291.906198)
		(end 126.038864 -292.362382)
		(width 0.1143)
		(layer "In13.Cu")
		(net "P5E_CPU1_P2_TX_DN<14>")
	)
	(arc
		(start 126.024132 -273.619976)
		(mid 126.031796 -273.625247)
		(end 126.039372 -273.630644)
		(width 0.1143)
		(layer "In13.Cu")
		(net "P5E_CPU1_P2_TX_DN<14>")
	)
	(arc
		(start 126.054612 -278.501602)
		(mid 126.282612 -278.946356)
		(end 126.054612 -279.39111)
		(width 0.1143)
		(layer "In13.Cu")
		(net "P5E_CPU1_P2_TX_DN<14>")
	)
	(arc
		(start 126.039372 -273.630644)
		(mid 126.264543 -274.08632)
		(end 126.039372 -274.541996)
		(width 0.1143)
		(layer "In13.Cu")
		(net "P5E_CPU1_P2_TX_DN<14>")
	)
	(arc
		(start 125.95606 -284.312106)
		(mid 125.800132 -284.616398)
		(end 125.95606 -284.92069)
		(width 0.1143)
		(layer "In13.Cu")
		(net "P5E_CPU1_P2_TX_DN<14>")
	)
	(arc
		(start 125.800104 -286.23641)
		(mid 125.840866 -286.406294)
		(end 125.954282 -286.539178)
		(width 0.1143)
		(layer "In13.Cu")
		(net "P5E_CPU1_P2_TX_DN<14>")
	)
	(arc
		(start 125.990858 -293.040562)
		(mid 126.270473 -293.52621)
		(end 125.990858 -294.011858)
		(width 0.1143)
		(layer "In13.Cu")
		(net "P5E_CPU1_P2_TX_DN<14>")
	)
	(arc
		(start 125.95606 -289.171888)
		(mid 125.800132 -289.47618)
		(end 125.95606 -289.780472)
		(width 0.1143)
		(layer "In13.Cu")
		(net "P5E_CPU1_P2_TX_DN<14>")
	)
	(arc
		(start 126.270258 -295.141904)
		(mid 126.320811 -295.331194)
		(end 126.459234 -295.469818)
		(width 0.1143)
		(layer "In13.Cu")
		(net "P5E_CPU1_P2_TX_DN<14>")
	)
	(arc
		(start 126.039372 -274.541996)
		(mid 126.031796 -274.547392)
		(end 126.024132 -274.552664)
		(width 0.1143)
		(layer "In13.Cu")
		(net "P5E_CPU1_P2_TX_DN<14>")
	)
	(arc
		(start 125.800104 -287.856422)
		(mid 125.840866 -288.026306)
		(end 125.954282 -288.15919)
		(width 0.1143)
		(layer "In13.Cu")
		(net "P5E_CPU1_P2_TX_DN<14>")
	)
	(arc
		(start 126.607062 -295.592246)
		(mid 126.705762 -295.762346)
		(end 126.740158 -295.955974)
		(width 0.1143)
		(layer "In13.Cu")
		(net "P5E_CPU1_P2_TX_DN<14>")
	)
	(arc
		(start 126.038356 -276.16277)
		(mid 126.031282 -276.167777)
		(end 126.024132 -276.172676)
		(width 0.1143)
		(layer "In13.Cu")
		(net "P5E_CPU1_P2_TX_DN<14>")
	)
	(arc
		(start 125.95606 -290.7919)
		(mid 125.800132 -291.096192)
		(end 125.95606 -291.400484)
		(width 0.1143)
		(layer "In13.Cu")
		(net "P5E_CPU1_P2_TX_DN<14>")
	)
	(arc
		(start 125.95606 -282.692094)
		(mid 125.800132 -282.996386)
		(end 125.95606 -283.300678)
		(width 0.1143)
		(layer "In13.Cu")
		(net "P5E_CPU1_P2_TX_DN<14>")
	)
	(arc
		(start 126.054612 -276.88159)
		(mid 126.282612 -277.326344)
		(end 126.054612 -277.771098)
		(width 0.1143)
		(layer "In13.Cu")
		(net "P5E_CPU1_P2_TX_DN<14>")
	)
	(arc
		(start 171.82338 -374.09882)
		(mid 171.872716 -374.51855)
		(end 172.017944 -374.91543)
		(width 0.14224)
		(layer "In13.Cu")
		(net "P5E_CPU1_P2_TX_DN<14>")
	)
	(arc
		(start 125.95606 -292.411912)
		(mid 125.800132 -292.716204)
		(end 125.95606 -293.020496)
		(width 0.1143)
		(layer "In13.Cu")
		(net "P5E_CPU1_P2_TX_DN<14>")
	)
	(arc
		(start 126.270004 -287.050734)
		(mid 126.209005 -287.304058)
		(end 126.039372 -287.501838)
		(width 0.1143)
		(layer "In13.Cu")
		(net "P5E_CPU1_P2_TX_DN<14>")
	)
	(arc
		(start 125.990858 -283.320744)
		(mid 126.270473 -283.806392)
		(end 125.990858 -284.29204)
		(width 0.1143)
		(layer "In13.Cu")
		(net "P5E_CPU1_P2_TX_DN<14>")
	)
	(arc
		(start 172.262038 -371.396006)
		(mid 172.296266 -371.509455)
		(end 172.307758 -371.6274)
		(width 0.14224)
		(layer "In13.Cu")
		(net "P5E_CPU1_P2_TX_DN<14>")
	)
	(arc
		(start 126.496572 -295.491154)
		(mid 126.555179 -295.538025)
		(end 126.607062 -295.592246)
		(width 0.1143)
		(layer "In13.Cu")
		(net "P5E_CPU1_P2_TX_DN<14>")
	)
	(arc
		(start 125.95606 -277.832058)
		(mid 125.800132 -278.13635)
		(end 125.95606 -278.440642)
		(width 0.1143)
		(layer "In13.Cu")
		(net "P5E_CPU1_P2_TX_DN<14>")
	)
	(arc
		(start 126.024132 -275.239988)
		(mid 126.031281 -275.244888)
		(end 126.038356 -275.249894)
		(width 0.1143)
		(layer "In13.Cu")
		(net "P5E_CPU1_P2_TX_DN<14>")
	)
	(arc
		(start 125.990858 -281.700732)
		(mid 126.270473 -282.18638)
		(end 125.990858 -282.672028)
		(width 0.1143)
		(layer "In13.Cu")
		(net "P5E_CPU1_P2_TX_DN<14>")
	)
	(arc
		(start 125.95606 -287.55213)
		(mid 125.841384 -287.685464)
		(end 125.800104 -287.856422)
		(width 0.1143)
		(layer "In13.Cu")
		(net "P5E_CPU1_P2_TX_DN<14>")
	)
	(arc
		(start 126.039372 -281.022044)
		(mid 126.031796 -281.02744)
		(end 126.024132 -281.032712)
		(width 0.1143)
		(layer "In13.Cu")
		(net "P5E_CPU1_P2_TX_DN<14>")
	)
	(arc
		(start 126.024132 -280.100024)
		(mid 126.031796 -280.105295)
		(end 126.039372 -280.110692)
		(width 0.1143)
		(layer "In13.Cu")
		(net "P5E_CPU1_P2_TX_DN<14>")
	)
	(arc
		(start 125.95606 -274.592034)
		(mid 125.800132 -274.896326)
		(end 125.95606 -275.200618)
		(width 0.1143)
		(layer "In13.Cu")
		(net "P5E_CPU1_P2_TX_DN<14>")
	)
	(arc
		(start 171.893484 -372.889272)
		(mid 171.8416 -372.967016)
		(end 171.82338 -373.05869)
		(width 0.14224)
		(layer "In13.Cu")
		(net "P5E_CPU1_P2_TX_DN<14>")
	)
	(arc
		(start 125.990858 -289.800538)
		(mid 126.270473 -290.286186)
		(end 125.990858 -290.771834)
		(width 0.1143)
		(layer "In13.Cu")
		(net "P5E_CPU1_P2_TX_DN<14>")
	)
	(arc
		(start 126.028958 -286.58312)
		(mid 126.206154 -286.785132)
		(end 126.270004 -287.046162)
		(width 0.1143)
		(layer "In13.Cu")
		(net "P5E_CPU1_P2_TX_DN<14>")
	)
	(segment
		(start 169.033444 -369.03533)
		(end 168.762934 -369.30584)
		(width 0.12954)
		(layer "F.Cu")
		(net "P5E_CPU1_P2_TX_DN<13>")
	)
	(segment
		(start 168.762934 -369.30584)
		(end 168.762934 -370.00942)
		(width 0.12954)
		(layer "F.Cu")
		(net "P5E_CPU1_P2_TX_DN<13>")
	)
	(segment
		(start 125.707902 -269.770352)
		(end 126.174754 -270.03629)
		(width 0.12954)
		(layer "F.Cu")
		(net "P5E_CPU1_P2_TX_DN<13>")
	)
	(segment
		(start 168.762934 -370.00942)
		(end 169.058844 -370.30533)
		(width 0.12954)
		(layer "F.Cu")
		(net "P5E_CPU1_P2_TX_DN<13>")
	)
	(segment
		(start 126.174754 -270.03629)
		(end 125.876812 -270.03629)
		(width 0.1143)
		(layer "In13.Cu")
		(net "P5E_CPU1_P2_TX_DN<13>")
	)
	(segment
		(start 168.266364 -367.397792)
		(end 168.55186 -367.683288)
		(width 0.14224)
		(layer "In13.Cu")
		(net "P5E_CPU1_P2_TX_DN<13>")
	)
	(segment
		(start 125.800104 -296.105072)
		(end 126.074424 -296.379392)
		(width 0.1143)
		(layer "In13.Cu")
		(net "P5E_CPU1_P2_TX_DN<13>")
	)
	(segment
		(start 125.047756 -274.573746)
		(end 125.046994 -274.574254)
		(width 0.1143)
		(layer "In13.Cu")
		(net "P5E_CPU1_P2_TX_DN<13>")
	)
	(segment
		(start 125.047756 -280.078942)
		(end 125.048772 -280.07945)
		(width 0.1143)
		(layer "In13.Cu")
		(net "P5E_CPU1_P2_TX_DN<13>")
	)
	(segment
		(start 125.050296 -282.672282)
		(end 125.048772 -282.673298)
		(width 0.1143)
		(layer "In13.Cu")
		(net "P5E_CPU1_P2_TX_DN<13>")
	)
	(segment
		(start 125.047756 -290.773612)
		(end 125.046994 -290.77412)
		(width 0.1143)
		(layer "In13.Cu")
		(net "P5E_CPU1_P2_TX_DN<13>")
	)
	(segment
		(start 125.047756 -285.91383)
		(end 125.046994 -285.914338)
		(width 0.1143)
		(layer "In13.Cu")
		(net "P5E_CPU1_P2_TX_DN<13>")
	)
	(segment
		(start 125.046994 -293.038276)
		(end 125.047756 -293.038784)
		(width 0.1143)
		(layer "In13.Cu")
		(net "P5E_CPU1_P2_TX_DN<13>")
	)
	(segment
		(start 125.047756 -284.293818)
		(end 125.046994 -284.294326)
		(width 0.1143)
		(layer "In13.Cu")
		(net "P5E_CPU1_P2_TX_DN<13>")
	)
	(segment
		(start 125.050296 -275.22043)
		(end 125.086872 -275.241766)
		(width 0.1143)
		(layer "In13.Cu")
		(net "P5E_CPU1_P2_TX_DN<13>")
	)
	(segment
		(start 125.047756 -278.45893)
		(end 125.048772 -278.459438)
		(width 0.1143)
		(layer "In13.Cu")
		(net "P5E_CPU1_P2_TX_DN<13>")
	)
	(segment
		(start 125.048772 -289.153092)
		(end 125.047756 -289.1536)
		(width 0.1143)
		(layer "In13.Cu")
		(net "P5E_CPU1_P2_TX_DN<13>")
	)
	(segment
		(start 125.041152 -289.15741)
		(end 125.040136 -289.157918)
		(width 0.1143)
		(layer "In13.Cu")
		(net "P5E_CPU1_P2_TX_DN<13>")
	)
	(segment
		(start 125.043438 -292.396164)
		(end 125.041914 -292.396926)
		(width 0.1143)
		(layer "In13.Cu")
		(net "P5E_CPU1_P2_TX_DN<13>")
	)
	(segment
		(start 125.046994 -289.154108)
		(end 125.045724 -289.15487)
		(width 0.1143)
		(layer "In13.Cu")
		(net "P5E_CPU1_P2_TX_DN<13>")
	)
	(segment
		(start 125.047756 -288.178748)
		(end 125.086872 -288.201608)
		(width 0.1143)
		(layer "In13.Cu")
		(net "P5E_CPU1_P2_TX_DN<13>")
	)
	(segment
		(start 125.045724 -292.394894)
		(end 125.0442 -292.395656)
		(width 0.1143)
		(layer "In13.Cu")
		(net "P5E_CPU1_P2_TX_DN<13>")
	)
	(segment
		(start 125.016006 -289.780472)
		(end 125.046994 -289.798252)
		(width 0.1143)
		(layer "In13.Cu")
		(net "P5E_CPU1_P2_TX_DN<13>")
	)
	(segment
		(start 125.086872 -290.750752)
		(end 125.050296 -290.772088)
		(width 0.1143)
		(layer "In13.Cu")
		(net "P5E_CPU1_P2_TX_DN<13>")
	)
	(segment
		(start 125.043438 -277.81631)
		(end 125.041406 -277.817326)
		(width 0.1143)
		(layer "In13.Cu")
		(net "P5E_CPU1_P2_TX_DN<13>")
	)
	(segment
		(start 125.047756 -292.393624)
		(end 125.046994 -292.394132)
		(width 0.1143)
		(layer "In13.Cu")
		(net "P5E_CPU1_P2_TX_DN<13>")
	)
	(segment
		(start 125.086872 -289.13074)
		(end 125.050296 -289.152076)
		(width 0.1143)
		(layer "In13.Cu")
		(net "P5E_CPU1_P2_TX_DN<13>")
	)
	(segment
		(start 125.047756 -291.418772)
		(end 125.048772 -291.41928)
		(width 0.1143)
		(layer "In13.Cu")
		(net "P5E_CPU1_P2_TX_DN<13>")
	)
	(segment
		(start 167.83177 -367.075466)
		(end 168.266364 -367.397792)
		(width 0.14224)
		(layer "In13.Cu")
		(net "P5E_CPU1_P2_TX_DN<13>")
	)
	(segment
		(start 125.046994 -285.914338)
		(end 125.045724 -285.9151)
		(width 0.1143)
		(layer "In13.Cu")
		(net "P5E_CPU1_P2_TX_DN<13>")
	)
	(segment
		(start 125.046994 -274.574254)
		(end 125.0442 -274.575778)
		(width 0.1143)
		(layer "In13.Cu")
		(net "P5E_CPU1_P2_TX_DN<13>")
	)
	(segment
		(start 125.040136 -282.678124)
		(end 125.016006 -282.692094)
		(width 0.1143)
		(layer "In13.Cu")
		(net "P5E_CPU1_P2_TX_DN<13>")
	)
	(segment
		(start 153.555192 -358.940862)
		(end 156.580586 -362.27893)
		(width 0.14224)
		(layer "In13.Cu")
		(net "P5E_CPU1_P2_TX_DN<13>")
	)
	(segment
		(start 125.041406 -279.437338)
		(end 125.016006 -279.45207)
		(width 0.1143)
		(layer "In13.Cu")
		(net "P5E_CPU1_P2_TX_DN<13>")
	)
	(segment
		(start 125.051312 -289.800792)
		(end 125.086872 -289.82162)
		(width 0.1143)
		(layer "In13.Cu")
		(net "P5E_CPU1_P2_TX_DN<13>")
	)
	(segment
		(start 126.074424 -296.792396)
		(end 126.120144 -296.838116)
		(width 0.1143)
		(layer "In13.Cu")
		(net "P5E_CPU1_P2_TX_DN<13>")
	)
	(segment
		(start 125.800104 -295.956228)
		(end 125.800104 -296.105072)
		(width 0.1143)
		(layer "In13.Cu")
		(net "P5E_CPU1_P2_TX_DN<13>")
	)
	(segment
		(start 125.041406 -274.577302)
		(end 125.016006 -274.592034)
		(width 0.1143)
		(layer "In13.Cu")
		(net "P5E_CPU1_P2_TX_DN<13>")
	)
	(segment
		(start 125.046994 -278.458422)
		(end 125.047756 -278.45893)
		(width 0.1143)
		(layer "In13.Cu")
		(net "P5E_CPU1_P2_TX_DN<13>")
	)
	(segment
		(start 125.047756 -275.218906)
		(end 125.048772 -275.219414)
		(width 0.1143)
		(layer "In13.Cu")
		(net "P5E_CPU1_P2_TX_DN<13>")
	)
	(segment
		(start 125.043438 -271.336262)
		(end 125.041406 -271.337278)
		(width 0.1143)
		(layer "In13.Cu")
		(net "P5E_CPU1_P2_TX_DN<13>")
	)
	(segment
		(start 125.041152 -290.777422)
		(end 125.040136 -290.77793)
		(width 0.1143)
		(layer "In13.Cu")
		(net "P5E_CPU1_P2_TX_DN<13>")
	)
	(segment
		(start 152.386284 -357.237284)
		(end 153.555192 -358.940862)
		(width 0.14224)
		(layer "In13.Cu")
		(net "P5E_CPU1_P2_TX_DN<13>")
	)
	(segment
		(start 125.046994 -284.294326)
		(end 125.045724 -284.295088)
		(width 0.1143)
		(layer "In13.Cu")
		(net "P5E_CPU1_P2_TX_DN<13>")
	)
	(segment
		(start 125.041152 -282.677616)
		(end 125.040136 -282.678124)
		(width 0.1143)
		(layer "In13.Cu")
		(net "P5E_CPU1_P2_TX_DN<13>")
	)
	(segment
		(start 125.041914 -284.29712)
		(end 125.041152 -284.297628)
		(width 0.1143)
		(layer "In13.Cu")
		(net "P5E_CPU1_P2_TX_DN<13>")
	)
	(segment
		(start 125.050296 -291.420296)
		(end 125.086872 -291.441632)
		(width 0.1143)
		(layer "In13.Cu")
		(net "P5E_CPU1_P2_TX_DN<13>")
	)
	(segment
		(start 125.046994 -276.194266)
		(end 125.0442 -276.19579)
		(width 0.1143)
		(layer "In13.Cu")
		(net "P5E_CPU1_P2_TX_DN<13>")
	)
	(segment
		(start 125.050296 -283.32049)
		(end 125.086872 -283.341826)
		(width 0.1143)
		(layer "In13.Cu")
		(net "P5E_CPU1_P2_TX_DN<13>")
	)
	(segment
		(start 168.742614 -368.144044)
		(end 168.742614 -368.7445)
		(width 0.14224)
		(layer "In13.Cu")
		(net "P5E_CPU1_P2_TX_DN<13>")
	)
	(segment
		(start 125.047756 -273.598894)
		(end 125.048772 -273.599402)
		(width 0.1143)
		(layer "In13.Cu")
		(net "P5E_CPU1_P2_TX_DN<13>")
	)
	(segment
		(start 125.046994 -271.33423)
		(end 125.0442 -271.335754)
		(width 0.1143)
		(layer "In13.Cu")
		(net "P5E_CPU1_P2_TX_DN<13>")
	)
	(segment
		(start 125.086872 -279.410922)
		(end 125.047756 -279.433782)
		(width 0.1143)
		(layer "In13.Cu")
		(net "P5E_CPU1_P2_TX_DN<13>")
	)
	(segment
		(start 125.0442 -274.575778)
		(end 125.043438 -274.576286)
		(width 0.1143)
		(layer "In13.Cu")
		(net "P5E_CPU1_P2_TX_DN<13>")
	)
	(segment
		(start 125.0442 -282.675838)
		(end 125.043438 -282.676346)
		(width 0.1143)
		(layer "In13.Cu")
		(net "P5E_CPU1_P2_TX_DN<13>")
	)
	(segment
		(start 125.041914 -282.677108)
		(end 125.041152 -282.677616)
		(width 0.1143)
		(layer "In13.Cu")
		(net "P5E_CPU1_P2_TX_DN<13>")
	)
	(segment
		(start 126.074424 -296.379392)
		(end 126.074424 -296.792396)
		(width 0.1143)
		(layer "In13.Cu")
		(net "P5E_CPU1_P2_TX_DN<13>")
	)
	(segment
		(start 125.016006 -271.960594)
		(end 125.046994 -271.978374)
		(width 0.1143)
		(layer "In13.Cu")
		(net "P5E_CPU1_P2_TX_DN<13>")
	)
	(segment
		(start 125.047756 -289.1536)
		(end 125.046994 -289.154108)
		(width 0.1143)
		(layer "In13.Cu")
		(net "P5E_CPU1_P2_TX_DN<13>")
	)
	(segment
		(start 125.517656 -270.523716)
		(end 125.487176 -270.541496)
		(width 0.1143)
		(layer "In13.Cu")
		(net "P5E_CPU1_P2_TX_DN<13>")
	)
	(segment
		(start 125.047756 -272.953734)
		(end 125.046994 -272.954242)
		(width 0.1143)
		(layer "In13.Cu")
		(net "P5E_CPU1_P2_TX_DN<13>")
	)
	(segment
		(start 125.0442 -290.775644)
		(end 125.043438 -290.776152)
		(width 0.1143)
		(layer "In13.Cu")
		(net "P5E_CPU1_P2_TX_DN<13>")
	)
	(segment
		(start 125.050296 -281.700478)
		(end 125.051312 -281.700986)
		(width 0.1143)
		(layer "In13.Cu")
		(net "P5E_CPU1_P2_TX_DN<13>")
	)
	(segment
		(start 125.048772 -292.393116)
		(end 125.047756 -292.393624)
		(width 0.1143)
		(layer "In13.Cu")
		(net "P5E_CPU1_P2_TX_DN<13>")
	)
	(segment
		(start 125.048772 -285.913322)
		(end 125.047756 -285.91383)
		(width 0.1143)
		(layer "In13.Cu")
		(net "P5E_CPU1_P2_TX_DN<13>")
	)
	(segment
		(start 125.051312 -293.040816)
		(end 125.086872 -293.061644)
		(width 0.1143)
		(layer "In13.Cu")
		(net "P5E_CPU1_P2_TX_DN<13>")
	)
	(segment
		(start 125.050296 -273.600418)
		(end 125.086872 -273.621754)
		(width 0.1143)
		(layer "In13.Cu")
		(net "P5E_CPU1_P2_TX_DN<13>")
	)
	(segment
		(start 125.046994 -279.43429)
		(end 125.0442 -279.435814)
		(width 0.1143)
		(layer "In13.Cu")
		(net "P5E_CPU1_P2_TX_DN<13>")
	)
	(segment
		(start 125.556772 -270.500856)
		(end 125.517656 -270.523716)
		(width 0.1143)
		(layer "In13.Cu")
		(net "P5E_CPU1_P2_TX_DN<13>")
	)
	(segment
		(start 125.041914 -285.917132)
		(end 125.041152 -285.91764)
		(width 0.1143)
		(layer "In13.Cu")
		(net "P5E_CPU1_P2_TX_DN<13>")
	)
	(segment
		(start 125.048772 -273.599402)
		(end 125.050296 -273.600418)
		(width 0.1143)
		(layer "In13.Cu")
		(net "P5E_CPU1_P2_TX_DN<13>")
	)
	(segment
		(start 125.047756 -277.81377)
		(end 125.046994 -277.814278)
		(width 0.1143)
		(layer "In13.Cu")
		(net "P5E_CPU1_P2_TX_DN<13>")
	)
	(segment
		(start 125.086872 -284.270958)
		(end 125.050296 -284.292294)
		(width 0.1143)
		(layer "In13.Cu")
		(net "P5E_CPU1_P2_TX_DN<13>")
	)
	(segment
		(start 125.043438 -289.15614)
		(end 125.041914 -289.156902)
		(width 0.1143)
		(layer "In13.Cu")
		(net "P5E_CPU1_P2_TX_DN<13>")
	)
	(segment
		(start 125.046994 -275.218398)
		(end 125.047756 -275.218906)
		(width 0.1143)
		(layer "In13.Cu")
		(net "P5E_CPU1_P2_TX_DN<13>")
	)
	(segment
		(start 125.086872 -281.030934)
		(end 125.047756 -281.053794)
		(width 0.1143)
		(layer "In13.Cu")
		(net "P5E_CPU1_P2_TX_DN<13>")
	)
	(segment
		(start 125.048772 -294.659304)
		(end 125.050296 -294.66032)
		(width 0.1143)
		(layer "In13.Cu")
		(net "P5E_CPU1_P2_TX_DN<13>")
	)
	(segment
		(start 125.048772 -276.839426)
		(end 125.050296 -276.840442)
		(width 0.1143)
		(layer "In13.Cu")
		(net "P5E_CPU1_P2_TX_DN<13>")
	)
	(segment
		(start 125.0442 -292.395656)
		(end 125.043438 -292.396164)
		(width 0.1143)
		(layer "In13.Cu")
		(net "P5E_CPU1_P2_TX_DN<13>")
	)
	(segment
		(start 125.043438 -276.196298)
		(end 125.041406 -276.197314)
		(width 0.1143)
		(layer "In13.Cu")
		(net "P5E_CPU1_P2_TX_DN<13>")
	)
	(segment
		(start 125.016006 -294.640508)
		(end 125.046994 -294.658288)
		(width 0.1143)
		(layer "In13.Cu")
		(net "P5E_CPU1_P2_TX_DN<13>")
	)
	(segment
		(start 125.086872 -276.170898)
		(end 125.047756 -276.193758)
		(width 0.1143)
		(layer "In13.Cu")
		(net "P5E_CPU1_P2_TX_DN<13>")
	)
	(segment
		(start 125.041406 -276.197314)
		(end 125.016006 -276.212046)
		(width 0.1143)
		(layer "In13.Cu")
		(net "P5E_CPU1_P2_TX_DN<13>")
	)
	(segment
		(start 125.050296 -289.800284)
		(end 125.051312 -289.800792)
		(width 0.1143)
		(layer "In13.Cu")
		(net "P5E_CPU1_P2_TX_DN<13>")
	)
	(segment
		(start 125.016006 -273.580606)
		(end 125.046994 -273.598386)
		(width 0.1143)
		(layer "In13.Cu")
		(net "P5E_CPU1_P2_TX_DN<13>")
	)
	(segment
		(start 125.040136 -290.77793)
		(end 125.016006 -290.7919)
		(width 0.1143)
		(layer "In13.Cu")
		(net "P5E_CPU1_P2_TX_DN<13>")
	)
	(segment
		(start 125.046994 -289.798252)
		(end 125.047756 -289.79876)
		(width 0.1143)
		(layer "In13.Cu")
		(net "P5E_CPU1_P2_TX_DN<13>")
	)
	(segment
		(start 125.048772 -271.97939)
		(end 125.050296 -271.980406)
		(width 0.1143)
		(layer "In13.Cu")
		(net "P5E_CPU1_P2_TX_DN<13>")
	)
	(segment
		(start 125.043438 -290.776152)
		(end 125.041914 -290.776914)
		(width 0.1143)
		(layer "In13.Cu")
		(net "P5E_CPU1_P2_TX_DN<13>")
	)
	(segment
		(start 125.048772 -294.013128)
		(end 125.047756 -294.013636)
		(width 0.1143)
		(layer "In13.Cu")
		(net "P5E_CPU1_P2_TX_DN<13>")
	)
	(segment
		(start 125.0442 -272.955766)
		(end 125.043438 -272.956274)
		(width 0.1143)
		(layer "In13.Cu")
		(net "P5E_CPU1_P2_TX_DN<13>")
	)
	(segment
		(start 125.014228 -286.539178)
		(end 125.047756 -286.558736)
		(width 0.1143)
		(layer "In13.Cu")
		(net "P5E_CPU1_P2_TX_DN<13>")
	)
	(segment
		(start 125.048772 -291.41928)
		(end 125.050296 -291.420296)
		(width 0.1143)
		(layer "In13.Cu")
		(net "P5E_CPU1_P2_TX_DN<13>")
	)
	(segment
		(start 125.048772 -293.039292)
		(end 125.050296 -293.040308)
		(width 0.1143)
		(layer "In13.Cu")
		(net "P5E_CPU1_P2_TX_DN<13>")
	)
	(segment
		(start 125.046994 -272.954242)
		(end 125.0442 -272.955766)
		(width 0.1143)
		(layer "In13.Cu")
		(net "P5E_CPU1_P2_TX_DN<13>")
	)
	(segment
		(start 125.016006 -280.060654)
		(end 125.046994 -280.078434)
		(width 0.1143)
		(layer "In13.Cu")
		(net "P5E_CPU1_P2_TX_DN<13>")
	)
	(segment
		(start 147.615656 -347.759782)
		(end 152.386284 -357.237284)
		(width 0.14224)
		(layer "In13.Cu")
		(net "P5E_CPU1_P2_TX_DN<13>")
	)
	(segment
		(start 125.047756 -271.978882)
		(end 125.048772 -271.97939)
		(width 0.1143)
		(layer "In13.Cu")
		(net "P5E_CPU1_P2_TX_DN<13>")
	)
	(segment
		(start 125.040136 -292.397942)
		(end 125.016006 -292.411912)
		(width 0.1143)
		(layer "In13.Cu")
		(net "P5E_CPU1_P2_TX_DN<13>")
	)
	(segment
		(start 125.876812 -270.03629)
		(end 125.794008 -270.119094)
		(width 0.1143)
		(layer "In13.Cu")
		(net "P5E_CPU1_P2_TX_DN<13>")
	)
	(segment
		(start 126.120144 -296.838116)
		(end 126.120144 -296.866056)
		(width 0.1143)
		(layer "In13.Cu")
		(net "P5E_CPU1_P2_TX_DN<13>")
	)
	(segment
		(start 125.0442 -285.915862)
		(end 125.043438 -285.91637)
		(width 0.1143)
		(layer "In13.Cu")
		(net "P5E_CPU1_P2_TX_DN<13>")
	)
	(segment
		(start 125.086872 -277.79091)
		(end 125.047756 -277.81377)
		(width 0.1143)
		(layer "In13.Cu")
		(net "P5E_CPU1_P2_TX_DN<13>")
	)
	(segment
		(start 125.050296 -271.980406)
		(end 125.086872 -272.001742)
		(width 0.1143)
		(layer "In13.Cu")
		(net "P5E_CPU1_P2_TX_DN<13>")
	)
	(segment
		(start 125.043438 -272.956274)
		(end 125.041406 -272.95729)
		(width 0.1143)
		(layer "In13.Cu")
		(net "P5E_CPU1_P2_TX_DN<13>")
	)
	(segment
		(start 125.048772 -289.799268)
		(end 125.050296 -289.800284)
		(width 0.1143)
		(layer "In13.Cu")
		(net "P5E_CPU1_P2_TX_DN<13>")
	)
	(segment
		(start 136.334246 -310.796178)
		(end 137.540746 -312.60161)
		(width 0.14224)
		(layer "In13.Cu")
		(net "P5E_CPU1_P2_TX_DN<13>")
	)
	(segment
		(start 125.048772 -284.29331)
		(end 125.047756 -284.293818)
		(width 0.1143)
		(layer "In13.Cu")
		(net "P5E_CPU1_P2_TX_DN<13>")
	)
	(segment
		(start 125.050296 -290.772088)
		(end 125.048772 -290.773104)
		(width 0.1143)
		(layer "In13.Cu")
		(net "P5E_CPU1_P2_TX_DN<13>")
	)
	(segment
		(start 125.046994 -290.77412)
		(end 125.045724 -290.774882)
		(width 0.1143)
		(layer "In13.Cu")
		(net "P5E_CPU1_P2_TX_DN<13>")
	)
	(segment
		(start 125.050296 -285.912306)
		(end 125.048772 -285.913322)
		(width 0.1143)
		(layer "In13.Cu")
		(net "P5E_CPU1_P2_TX_DN<13>")
	)
	(segment
		(start 125.047756 -282.673806)
		(end 125.046994 -282.674314)
		(width 0.1143)
		(layer "In13.Cu")
		(net "P5E_CPU1_P2_TX_DN<13>")
	)
	(segment
		(start 125.040136 -284.298136)
		(end 125.016006 -284.312106)
		(width 0.1143)
		(layer "In13.Cu")
		(net "P5E_CPU1_P2_TX_DN<13>")
	)
	(segment
		(start 125.047756 -284.938978)
		(end 125.048772 -284.939486)
		(width 0.1143)
		(layer "In13.Cu")
		(net "P5E_CPU1_P2_TX_DN<13>")
	)
	(segment
		(start 126.120652 -296.968926)
		(end 126.565406 -297.753532)
		(width 0.14224)
		(layer "In13.Cu")
		(net "P5E_CPU1_P2_TX_DN<13>")
	)
	(segment
		(start 125.050296 -278.460454)
		(end 125.086872 -278.48179)
		(width 0.1143)
		(layer "In13.Cu")
		(net "P5E_CPU1_P2_TX_DN<13>")
	)
	(segment
		(start 157.59811 -362.958888)
		(end 164.742114 -365.918242)
		(width 0.14224)
		(layer "In13.Cu")
		(net "P5E_CPU1_P2_TX_DN<13>")
	)
	(segment
		(start 125.048772 -282.673298)
		(end 125.047756 -282.673806)
		(width 0.1143)
		(layer "In13.Cu")
		(net "P5E_CPU1_P2_TX_DN<13>")
	)
	(segment
		(start 125.040136 -289.157918)
		(end 125.016006 -289.171888)
		(width 0.1143)
		(layer "In13.Cu")
		(net "P5E_CPU1_P2_TX_DN<13>")
	)
	(segment
		(start 125.016006 -281.680666)
		(end 125.046994 -281.698446)
		(width 0.1143)
		(layer "In13.Cu")
		(net "P5E_CPU1_P2_TX_DN<13>")
	)
	(segment
		(start 125.047756 -289.79876)
		(end 125.048772 -289.799268)
		(width 0.1143)
		(layer "In13.Cu")
		(net "P5E_CPU1_P2_TX_DN<13>")
	)
	(segment
		(start 125.046994 -280.078434)
		(end 125.047756 -280.078942)
		(width 0.1143)
		(layer "In13.Cu")
		(net "P5E_CPU1_P2_TX_DN<13>")
	)
	(segment
		(start 125.041914 -292.396926)
		(end 125.041152 -292.397434)
		(width 0.1143)
		(layer "In13.Cu")
		(net "P5E_CPU1_P2_TX_DN<13>")
	)
	(segment
		(start 156.580586 -362.27893)
		(end 157.59811 -362.958888)
		(width 0.14224)
		(layer "In13.Cu")
		(net "P5E_CPU1_P2_TX_DN<13>")
	)
	(segment
		(start 125.086872 -285.89097)
		(end 125.050296 -285.912306)
		(width 0.1143)
		(layer "In13.Cu")
		(net "P5E_CPU1_P2_TX_DN<13>")
	)
	(segment
		(start 125.046994 -271.978374)
		(end 125.047756 -271.978882)
		(width 0.1143)
		(layer "In13.Cu")
		(net "P5E_CPU1_P2_TX_DN<13>")
	)
	(segment
		(start 125.0442 -276.19579)
		(end 125.043438 -276.196298)
		(width 0.1143)
		(layer "In13.Cu")
		(net "P5E_CPU1_P2_TX_DN<13>")
	)
	(segment
		(start 125.016006 -293.020496)
		(end 125.046994 -293.038276)
		(width 0.1143)
		(layer "In13.Cu")
		(net "P5E_CPU1_P2_TX_DN<13>")
	)
	(segment
		(start 125.050296 -289.152076)
		(end 125.048772 -289.153092)
		(width 0.1143)
		(layer "In13.Cu")
		(net "P5E_CPU1_P2_TX_DN<13>")
	)
	(segment
		(start 125.041152 -284.297628)
		(end 125.040136 -284.298136)
		(width 0.1143)
		(layer "In13.Cu")
		(net "P5E_CPU1_P2_TX_DN<13>")
	)
	(segment
		(start 125.086872 -271.310862)
		(end 125.047756 -271.333722)
		(width 0.1143)
		(layer "In13.Cu")
		(net "P5E_CPU1_P2_TX_DN<13>")
	)
	(segment
		(start 125.048772 -290.773104)
		(end 125.047756 -290.773612)
		(width 0.1143)
		(layer "In13.Cu")
		(net "P5E_CPU1_P2_TX_DN<13>")
	)
	(segment
		(start 126.120144 -296.866056)
		(end 126.120652 -296.866564)
		(width 0.1143)
		(layer "In13.Cu")
		(net "P5E_CPU1_P2_TX_DN<13>")
	)
	(segment
		(start 125.046994 -276.83841)
		(end 125.047756 -276.838918)
		(width 0.1143)
		(layer "In13.Cu")
		(net "P5E_CPU1_P2_TX_DN<13>")
	)
	(segment
		(start 125.047756 -279.433782)
		(end 125.046994 -279.43429)
		(width 0.1143)
		(layer "In13.Cu")
		(net "P5E_CPU1_P2_TX_DN<13>")
	)
	(segment
		(start 141.887194 -320.733166)
		(end 142.565628 -322.37045)
		(width 0.14224)
		(layer "In13.Cu")
		(net "P5E_CPU1_P2_TX_DN<13>")
	)
	(segment
		(start 125.045724 -284.295088)
		(end 125.0442 -284.29585)
		(width 0.1143)
		(layer "In13.Cu")
		(net "P5E_CPU1_P2_TX_DN<13>")
	)
	(segment
		(start 125.048772 -278.459438)
		(end 125.050296 -278.460454)
		(width 0.1143)
		(layer "In13.Cu")
		(net "P5E_CPU1_P2_TX_DN<13>")
	)
	(segment
		(start 125.047756 -287.533842)
		(end 125.016006 -287.55213)
		(width 0.1143)
		(layer "In13.Cu")
		(net "P5E_CPU1_P2_TX_DN<13>")
	)
	(segment
		(start 125.041152 -285.91764)
		(end 125.040136 -285.918148)
		(width 0.1143)
		(layer "In13.Cu")
		(net "P5E_CPU1_P2_TX_DN<13>")
	)
	(segment
		(start 125.045724 -290.774882)
		(end 125.0442 -290.775644)
		(width 0.1143)
		(layer "In13.Cu")
		(net "P5E_CPU1_P2_TX_DN<13>")
	)
	(segment
		(start 167.540178 -366.91951)
		(end 167.83177 -367.075466)
		(width 0.14224)
		(layer "In13.Cu")
		(net "P5E_CPU1_P2_TX_DN<13>")
	)
	(segment
		(start 125.045724 -282.675076)
		(end 125.0442 -282.675838)
		(width 0.1143)
		(layer "In13.Cu")
		(net "P5E_CPU1_P2_TX_DN<13>")
	)
	(segment
		(start 125.047756 -286.558736)
		(end 125.086872 -286.581596)
		(width 0.1143)
		(layer "In13.Cu")
		(net "P5E_CPU1_P2_TX_DN<13>")
	)
	(segment
		(start 125.016006 -276.82063)
		(end 125.046994 -276.83841)
		(width 0.1143)
		(layer "In13.Cu")
		(net "P5E_CPU1_P2_TX_DN<13>")
	)
	(segment
		(start 125.048772 -281.699462)
		(end 125.050296 -281.700478)
		(width 0.1143)
		(layer "In13.Cu")
		(net "P5E_CPU1_P2_TX_DN<13>")
	)
	(segment
		(start 125.040136 -285.918148)
		(end 125.016006 -285.932118)
		(width 0.1143)
		(layer "In13.Cu")
		(net "P5E_CPU1_P2_TX_DN<13>")
	)
	(segment
		(start 125.045724 -285.9151)
		(end 125.0442 -285.915862)
		(width 0.1143)
		(layer "In13.Cu")
		(net "P5E_CPU1_P2_TX_DN<13>")
	)
	(segment
		(start 164.742114 -365.918242)
		(end 167.540178 -366.91951)
		(width 0.14224)
		(layer "In13.Cu")
		(net "P5E_CPU1_P2_TX_DN<13>")
	)
	(segment
		(start 125.050296 -294.66032)
		(end 125.051312 -294.660828)
		(width 0.1143)
		(layer "In13.Cu")
		(net "P5E_CPU1_P2_TX_DN<13>")
	)
	(segment
		(start 125.016006 -275.200618)
		(end 125.046994 -275.218398)
		(width 0.1143)
		(layer "In13.Cu")
		(net "P5E_CPU1_P2_TX_DN<13>")
	)
	(segment
		(start 125.043438 -285.91637)
		(end 125.041914 -285.917132)
		(width 0.1143)
		(layer "In13.Cu")
		(net "P5E_CPU1_P2_TX_DN<13>")
	)
	(segment
		(start 137.540746 -312.60161)
		(end 141.887194 -320.733166)
		(width 0.14224)
		(layer "In13.Cu")
		(net "P5E_CPU1_P2_TX_DN<13>")
	)
	(segment
		(start 125.046994 -292.394132)
		(end 125.045724 -292.394894)
		(width 0.1143)
		(layer "In13.Cu")
		(net "P5E_CPU1_P2_TX_DN<13>")
	)
	(segment
		(start 125.0442 -277.815802)
		(end 125.043438 -277.81631)
		(width 0.1143)
		(layer "In13.Cu")
		(net "P5E_CPU1_P2_TX_DN<13>")
	)
	(segment
		(start 125.086872 -292.370764)
		(end 125.050296 -292.3921)
		(width 0.1143)
		(layer "In13.Cu")
		(net "P5E_CPU1_P2_TX_DN<13>")
	)
	(segment
		(start 125.086872 -293.990776)
		(end 125.048772 -294.013128)
		(width 0.1143)
		(layer "In13.Cu")
		(net "P5E_CPU1_P2_TX_DN<13>")
	)
	(segment
		(start 125.051312 -281.700986)
		(end 125.086872 -281.721814)
		(width 0.1143)
		(layer "In13.Cu")
		(net "P5E_CPU1_P2_TX_DN<13>")
	)
	(segment
		(start 125.047756 -293.038784)
		(end 125.048772 -293.039292)
		(width 0.1143)
		(layer "In13.Cu")
		(net "P5E_CPU1_P2_TX_DN<13>")
	)
	(segment
		(start 125.487176 -295.451022)
		(end 125.517656 -295.468802)
		(width 0.1143)
		(layer "In13.Cu")
		(net "P5E_CPU1_P2_TX_DN<13>")
	)
	(segment
		(start 125.045724 -294.014906)
		(end 125.016006 -294.031924)
		(width 0.1143)
		(layer "In13.Cu")
		(net "P5E_CPU1_P2_TX_DN<13>")
	)
	(segment
		(start 125.0442 -271.335754)
		(end 125.043438 -271.336262)
		(width 0.1143)
		(layer "In13.Cu")
		(net "P5E_CPU1_P2_TX_DN<13>")
	)
	(segment
		(start 125.041406 -272.95729)
		(end 125.016006 -272.972022)
		(width 0.1143)
		(layer "In13.Cu")
		(net "P5E_CPU1_P2_TX_DN<13>")
	)
	(segment
		(start 127.55753 -298.962572)
		(end 136.334246 -310.796178)
		(width 0.14224)
		(layer "In13.Cu")
		(net "P5E_CPU1_P2_TX_DN<13>")
	)
	(segment
		(start 125.045724 -289.15487)
		(end 125.0442 -289.155632)
		(width 0.1143)
		(layer "In13.Cu")
		(net "P5E_CPU1_P2_TX_DN<13>")
	)
	(segment
		(start 125.048772 -280.07945)
		(end 125.086872 -280.101802)
		(width 0.1143)
		(layer "In13.Cu")
		(net "P5E_CPU1_P2_TX_DN<13>")
	)
	(segment
		(start 125.517656 -295.468802)
		(end 125.556772 -295.491662)
		(width 0.1143)
		(layer "In13.Cu")
		(net "P5E_CPU1_P2_TX_DN<13>")
	)
	(segment
		(start 125.043438 -284.296358)
		(end 125.041914 -284.29712)
		(width 0.1143)
		(layer "In13.Cu")
		(net "P5E_CPU1_P2_TX_DN<13>")
	)
	(segment
		(start 125.0442 -279.435814)
		(end 125.043438 -279.436322)
		(width 0.1143)
		(layer "In13.Cu")
		(net "P5E_CPU1_P2_TX_DN<13>")
	)
	(segment
		(start 125.047756 -276.193758)
		(end 125.046994 -276.194266)
		(width 0.1143)
		(layer "In13.Cu")
		(net "P5E_CPU1_P2_TX_DN<13>")
	)
	(segment
		(start 125.086872 -282.650946)
		(end 125.050296 -282.672282)
		(width 0.1143)
		(layer "In13.Cu")
		(net "P5E_CPU1_P2_TX_DN<13>")
	)
	(segment
		(start 125.043438 -279.436322)
		(end 125.041406 -279.437338)
		(width 0.1143)
		(layer "In13.Cu")
		(net "P5E_CPU1_P2_TX_DN<13>")
	)
	(segment
		(start 125.086872 -274.550886)
		(end 125.047756 -274.573746)
		(width 0.1143)
		(layer "In13.Cu")
		(net "P5E_CPU1_P2_TX_DN<13>")
	)
	(segment
		(start 125.016006 -291.400484)
		(end 125.047756 -291.418772)
		(width 0.1143)
		(layer "In13.Cu")
		(net "P5E_CPU1_P2_TX_DN<13>")
	)
	(segment
		(start 125.046994 -281.698446)
		(end 125.047756 -281.698954)
		(width 0.1143)
		(layer "In13.Cu")
		(net "P5E_CPU1_P2_TX_DN<13>")
	)
	(segment
		(start 125.046994 -294.658288)
		(end 125.047756 -294.658796)
		(width 0.1143)
		(layer "In13.Cu")
		(net "P5E_CPU1_P2_TX_DN<13>")
	)
	(segment
		(start 125.047756 -281.053794)
		(end 125.016006 -281.072082)
		(width 0.1143)
		(layer "In13.Cu")
		(net "P5E_CPU1_P2_TX_DN<13>")
	)
	(segment
		(start 125.041406 -277.817326)
		(end 125.016006 -277.832058)
		(width 0.1143)
		(layer "In13.Cu")
		(net "P5E_CPU1_P2_TX_DN<13>")
	)
	(segment
		(start 125.041914 -289.156902)
		(end 125.041152 -289.15741)
		(width 0.1143)
		(layer "In13.Cu")
		(net "P5E_CPU1_P2_TX_DN<13>")
	)
	(segment
		(start 125.050296 -276.840442)
		(end 125.086872 -276.861778)
		(width 0.1143)
		(layer "In13.Cu")
		(net "P5E_CPU1_P2_TX_DN<13>")
	)
	(segment
		(start 125.084332 -287.512506)
		(end 125.047756 -287.533842)
		(width 0.1143)
		(layer "In13.Cu")
		(net "P5E_CPU1_P2_TX_DN<13>")
	)
	(segment
		(start 125.043438 -282.676346)
		(end 125.041914 -282.677108)
		(width 0.1143)
		(layer "In13.Cu")
		(net "P5E_CPU1_P2_TX_DN<13>")
	)
	(segment
		(start 125.050296 -292.3921)
		(end 125.048772 -292.393116)
		(width 0.1143)
		(layer "In13.Cu")
		(net "P5E_CPU1_P2_TX_DN<13>")
	)
	(segment
		(start 125.041152 -292.397434)
		(end 125.040136 -292.397942)
		(width 0.1143)
		(layer "In13.Cu")
		(net "P5E_CPU1_P2_TX_DN<13>")
	)
	(segment
		(start 142.565628 -322.37045)
		(end 147.615656 -347.759782)
		(width 0.14224)
		(layer "In13.Cu")
		(net "P5E_CPU1_P2_TX_DN<13>")
	)
	(segment
		(start 125.048772 -275.219414)
		(end 125.050296 -275.22043)
		(width 0.1143)
		(layer "In13.Cu")
		(net "P5E_CPU1_P2_TX_DN<13>")
	)
	(segment
		(start 125.048772 -283.319474)
		(end 125.050296 -283.32049)
		(width 0.1143)
		(layer "In13.Cu")
		(net "P5E_CPU1_P2_TX_DN<13>")
	)
	(segment
		(start 125.050296 -293.040308)
		(end 125.051312 -293.040816)
		(width 0.1143)
		(layer "In13.Cu")
		(net "P5E_CPU1_P2_TX_DN<13>")
	)
	(segment
		(start 125.0442 -284.29585)
		(end 125.043438 -284.296358)
		(width 0.1143)
		(layer "In13.Cu")
		(net "P5E_CPU1_P2_TX_DN<13>")
	)
	(segment
		(start 168.742614 -368.7445)
		(end 169.033444 -369.03533)
		(width 0.14224)
		(layer "In13.Cu")
		(net "P5E_CPU1_P2_TX_DN<13>")
	)
	(segment
		(start 125.047756 -283.318966)
		(end 125.048772 -283.319474)
		(width 0.1143)
		(layer "In13.Cu")
		(net "P5E_CPU1_P2_TX_DN<13>")
	)
	(segment
		(start 125.016006 -284.92069)
		(end 125.047756 -284.938978)
		(width 0.1143)
		(layer "In13.Cu")
		(net "P5E_CPU1_P2_TX_DN<13>")
	)
	(segment
		(start 125.050296 -284.292294)
		(end 125.048772 -284.29331)
		(width 0.1143)
		(layer "In13.Cu")
		(net "P5E_CPU1_P2_TX_DN<13>")
	)
	(segment
		(start 125.047756 -294.013636)
		(end 125.046994 -294.014144)
		(width 0.1143)
		(layer "In13.Cu")
		(net "P5E_CPU1_P2_TX_DN<13>")
	)
	(segment
		(start 125.043438 -274.576286)
		(end 125.041406 -274.577302)
		(width 0.1143)
		(layer "In13.Cu")
		(net "P5E_CPU1_P2_TX_DN<13>")
	)
	(segment
		(start 125.047756 -271.333722)
		(end 125.046994 -271.33423)
		(width 0.1143)
		(layer "In13.Cu")
		(net "P5E_CPU1_P2_TX_DN<13>")
	)
	(segment
		(start 125.086872 -272.930874)
		(end 125.047756 -272.953734)
		(width 0.1143)
		(layer "In13.Cu")
		(net "P5E_CPU1_P2_TX_DN<13>")
	)
	(segment
		(start 125.014228 -288.15919)
		(end 125.047756 -288.178748)
		(width 0.1143)
		(layer "In13.Cu")
		(net "P5E_CPU1_P2_TX_DN<13>")
	)
	(segment
		(start 126.120652 -296.866564)
		(end 126.120652 -296.968926)
		(width 0.14224)
		(layer "In13.Cu")
		(net "P5E_CPU1_P2_TX_DN<13>")
	)
	(segment
		(start 125.041914 -290.776914)
		(end 125.041152 -290.777422)
		(width 0.1143)
		(layer "In13.Cu")
		(net "P5E_CPU1_P2_TX_DN<13>")
	)
	(segment
		(start 125.046994 -273.598386)
		(end 125.047756 -273.598894)
		(width 0.1143)
		(layer "In13.Cu")
		(net "P5E_CPU1_P2_TX_DN<13>")
	)
	(segment
		(start 125.046994 -282.674314)
		(end 125.045724 -282.675076)
		(width 0.1143)
		(layer "In13.Cu")
		(net "P5E_CPU1_P2_TX_DN<13>")
	)
	(segment
		(start 125.016006 -283.300678)
		(end 125.047756 -283.318966)
		(width 0.1143)
		(layer "In13.Cu")
		(net "P5E_CPU1_P2_TX_DN<13>")
	)
	(segment
		(start 125.046994 -277.814278)
		(end 125.0442 -277.815802)
		(width 0.1143)
		(layer "In13.Cu")
		(net "P5E_CPU1_P2_TX_DN<13>")
	)
	(segment
		(start 126.565406 -297.753532)
		(end 127.55753 -298.962572)
		(width 0.14224)
		(layer "In13.Cu")
		(net "P5E_CPU1_P2_TX_DN<13>")
	)
	(segment
		(start 125.047756 -276.838918)
		(end 125.048772 -276.839426)
		(width 0.1143)
		(layer "In13.Cu")
		(net "P5E_CPU1_P2_TX_DN<13>")
	)
	(segment
		(start 125.047756 -294.658796)
		(end 125.048772 -294.659304)
		(width 0.1143)
		(layer "In13.Cu")
		(net "P5E_CPU1_P2_TX_DN<13>")
	)
	(segment
		(start 125.047756 -281.698954)
		(end 125.048772 -281.699462)
		(width 0.1143)
		(layer "In13.Cu")
		(net "P5E_CPU1_P2_TX_DN<13>")
	)
	(segment
		(start 125.051312 -294.660828)
		(end 125.086872 -294.681656)
		(width 0.1143)
		(layer "In13.Cu")
		(net "P5E_CPU1_P2_TX_DN<13>")
	)
	(segment
		(start 125.041406 -271.337278)
		(end 125.016006 -271.35201)
		(width 0.1143)
		(layer "In13.Cu")
		(net "P5E_CPU1_P2_TX_DN<13>")
	)
	(segment
		(start 125.016006 -278.440642)
		(end 125.046994 -278.458422)
		(width 0.1143)
		(layer "In13.Cu")
		(net "P5E_CPU1_P2_TX_DN<13>")
	)
	(segment
		(start 125.046994 -294.014144)
		(end 125.045724 -294.014906)
		(width 0.1143)
		(layer "In13.Cu")
		(net "P5E_CPU1_P2_TX_DN<13>")
	)
	(segment
		(start 125.050296 -284.940502)
		(end 125.086872 -284.961838)
		(width 0.1143)
		(layer "In13.Cu")
		(net "P5E_CPU1_P2_TX_DN<13>")
	)
	(segment
		(start 125.0442 -289.155632)
		(end 125.043438 -289.15614)
		(width 0.1143)
		(layer "In13.Cu")
		(net "P5E_CPU1_P2_TX_DN<13>")
	)
	(segment
		(start 125.048772 -284.939486)
		(end 125.050296 -284.940502)
		(width 0.1143)
		(layer "In13.Cu")
		(net "P5E_CPU1_P2_TX_DN<13>")
	)
	(arc
		(start 125.330204 -295.146222)
		(mid 125.371753 -295.317644)
		(end 125.487176 -295.451022)
		(width 0.1143)
		(layer "In13.Cu")
		(net "P5E_CPU1_P2_TX_DN<13>")
	)
	(arc
		(start 125.016006 -277.832058)
		(mid 124.860078 -278.13635)
		(end 125.016006 -278.440642)
		(width 0.1143)
		(layer "In13.Cu")
		(net "P5E_CPU1_P2_TX_DN<13>")
	)
	(arc
		(start 125.086872 -288.201608)
		(mid 125.330199 -288.666174)
		(end 125.086872 -289.13074)
		(width 0.1143)
		(layer "In13.Cu")
		(net "P5E_CPU1_P2_TX_DN<13>")
	)
	(arc
		(start 125.086872 -281.721814)
		(mid 125.330199 -282.18638)
		(end 125.086872 -282.650946)
		(width 0.1143)
		(layer "In13.Cu")
		(net "P5E_CPU1_P2_TX_DN<13>")
	)
	(arc
		(start 125.086872 -291.441632)
		(mid 125.330199 -291.906198)
		(end 125.086872 -292.370764)
		(width 0.1143)
		(layer "In13.Cu")
		(net "P5E_CPU1_P2_TX_DN<13>")
	)
	(arc
		(start 125.016006 -289.171888)
		(mid 124.860078 -289.47618)
		(end 125.016006 -289.780472)
		(width 0.1143)
		(layer "In13.Cu")
		(net "P5E_CPU1_P2_TX_DN<13>")
	)
	(arc
		(start 125.016006 -281.072082)
		(mid 124.860078 -281.376374)
		(end 125.016006 -281.680666)
		(width 0.1143)
		(layer "In13.Cu")
		(net "P5E_CPU1_P2_TX_DN<13>")
	)
	(arc
		(start 124.86005 -287.856422)
		(mid 124.900812 -288.026306)
		(end 125.014228 -288.15919)
		(width 0.1143)
		(layer "In13.Cu")
		(net "P5E_CPU1_P2_TX_DN<13>")
	)
	(arc
		(start 125.086872 -289.82162)
		(mid 125.330199 -290.286186)
		(end 125.086872 -290.750752)
		(width 0.1143)
		(layer "In13.Cu")
		(net "P5E_CPU1_P2_TX_DN<13>")
	)
	(arc
		(start 125.330204 -287.046162)
		(mid 125.264968 -287.309753)
		(end 125.084332 -287.512506)
		(width 0.1143)
		(layer "In13.Cu")
		(net "P5E_CPU1_P2_TX_DN<13>")
	)
	(arc
		(start 125.016006 -272.972022)
		(mid 124.860078 -273.276314)
		(end 125.016006 -273.580606)
		(width 0.1143)
		(layer "In13.Cu")
		(net "P5E_CPU1_P2_TX_DN<13>")
	)
	(arc
		(start 125.016006 -271.35201)
		(mid 124.860078 -271.656302)
		(end 125.016006 -271.960594)
		(width 0.1143)
		(layer "In13.Cu")
		(net "P5E_CPU1_P2_TX_DN<13>")
	)
	(arc
		(start 125.086872 -293.061644)
		(mid 125.330199 -293.52621)
		(end 125.086872 -293.990776)
		(width 0.1143)
		(layer "In13.Cu")
		(net "P5E_CPU1_P2_TX_DN<13>")
	)
	(arc
		(start 125.016006 -276.212046)
		(mid 124.860078 -276.516338)
		(end 125.016006 -276.82063)
		(width 0.1143)
		(layer "In13.Cu")
		(net "P5E_CPU1_P2_TX_DN<13>")
	)
	(arc
		(start 125.086872 -278.48179)
		(mid 125.330199 -278.946356)
		(end 125.086872 -279.410922)
		(width 0.1143)
		(layer "In13.Cu")
		(net "P5E_CPU1_P2_TX_DN<13>")
	)
	(arc
		(start 125.016006 -279.45207)
		(mid 124.860078 -279.756362)
		(end 125.016006 -280.060654)
		(width 0.1143)
		(layer "In13.Cu")
		(net "P5E_CPU1_P2_TX_DN<13>")
	)
	(arc
		(start 125.016006 -287.55213)
		(mid 124.90133 -287.685464)
		(end 124.86005 -287.856422)
		(width 0.1143)
		(layer "In13.Cu")
		(net "P5E_CPU1_P2_TX_DN<13>")
	)
	(arc
		(start 124.86005 -286.23641)
		(mid 124.900812 -286.406294)
		(end 125.014228 -286.539178)
		(width 0.1143)
		(layer "In13.Cu")
		(net "P5E_CPU1_P2_TX_DN<13>")
	)
	(arc
		(start 125.794008 -270.119094)
		(mid 125.79222 -270.130543)
		(end 125.790198 -270.141954)
		(width 0.1143)
		(layer "In13.Cu")
		(net "P5E_CPU1_P2_TX_DN<13>")
	)
	(arc
		(start 125.487176 -270.541496)
		(mid 125.371749 -270.674872)
		(end 125.330204 -270.846296)
		(width 0.1143)
		(layer "In13.Cu")
		(net "P5E_CPU1_P2_TX_DN<13>")
	)
	(arc
		(start 168.55186 -367.683288)
		(mid 168.693057 -367.894699)
		(end 168.742614 -368.144044)
		(width 0.14224)
		(layer "In13.Cu")
		(net "P5E_CPU1_P2_TX_DN<13>")
	)
	(arc
		(start 125.086872 -272.001742)
		(mid 125.330199 -272.466308)
		(end 125.086872 -272.930874)
		(width 0.1143)
		(layer "In13.Cu")
		(net "P5E_CPU1_P2_TX_DN<13>")
	)
	(arc
		(start 125.086872 -275.241766)
		(mid 125.330199 -275.706332)
		(end 125.086872 -276.170898)
		(width 0.1143)
		(layer "In13.Cu")
		(net "P5E_CPU1_P2_TX_DN<13>")
	)
	(arc
		(start 125.086872 -294.681656)
		(mid 125.265685 -294.884006)
		(end 125.330204 -295.146222)
		(width 0.1143)
		(layer "In13.Cu")
		(net "P5E_CPU1_P2_TX_DN<13>")
	)
	(arc
		(start 125.016006 -282.692094)
		(mid 124.860078 -282.996386)
		(end 125.016006 -283.300678)
		(width 0.1143)
		(layer "In13.Cu")
		(net "P5E_CPU1_P2_TX_DN<13>")
	)
	(arc
		(start 125.086872 -283.341826)
		(mid 125.330199 -283.806392)
		(end 125.086872 -284.270958)
		(width 0.1143)
		(layer "In13.Cu")
		(net "P5E_CPU1_P2_TX_DN<13>")
	)
	(arc
		(start 125.016006 -290.7919)
		(mid 124.860078 -291.096192)
		(end 125.016006 -291.400484)
		(width 0.1143)
		(layer "In13.Cu")
		(net "P5E_CPU1_P2_TX_DN<13>")
	)
	(arc
		(start 125.086872 -286.581596)
		(mid 125.265685 -286.783946)
		(end 125.330204 -287.046162)
		(width 0.1143)
		(layer "In13.Cu")
		(net "P5E_CPU1_P2_TX_DN<13>")
	)
	(arc
		(start 125.016006 -274.592034)
		(mid 124.860078 -274.896326)
		(end 125.016006 -275.200618)
		(width 0.1143)
		(layer "In13.Cu")
		(net "P5E_CPU1_P2_TX_DN<13>")
	)
	(arc
		(start 125.016006 -294.031924)
		(mid 124.860078 -294.336216)
		(end 125.016006 -294.640508)
		(width 0.1143)
		(layer "In13.Cu")
		(net "P5E_CPU1_P2_TX_DN<13>")
	)
	(arc
		(start 125.086872 -280.101802)
		(mid 125.330199 -280.566368)
		(end 125.086872 -281.030934)
		(width 0.1143)
		(layer "In13.Cu")
		(net "P5E_CPU1_P2_TX_DN<13>")
	)
	(arc
		(start 125.016006 -292.411912)
		(mid 124.860078 -292.716204)
		(end 125.016006 -293.020496)
		(width 0.1143)
		(layer "In13.Cu")
		(net "P5E_CPU1_P2_TX_DN<13>")
	)
	(arc
		(start 125.086872 -284.961838)
		(mid 125.330199 -285.426404)
		(end 125.086872 -285.89097)
		(width 0.1143)
		(layer "In13.Cu")
		(net "P5E_CPU1_P2_TX_DN<13>")
	)
	(arc
		(start 125.556772 -295.491662)
		(mid 125.572723 -295.503072)
		(end 125.588268 -295.51503)
		(width 0.1143)
		(layer "In13.Cu")
		(net "P5E_CPU1_P2_TX_DN<13>")
	)
	(arc
		(start 125.790198 -270.141954)
		(mid 125.708765 -270.344352)
		(end 125.556772 -270.500856)
		(width 0.1143)
		(layer "In13.Cu")
		(net "P5E_CPU1_P2_TX_DN<13>")
	)
	(arc
		(start 125.016006 -285.932118)
		(mid 124.90133 -286.065452)
		(end 124.86005 -286.23641)
		(width 0.1143)
		(layer "In13.Cu")
		(net "P5E_CPU1_P2_TX_DN<13>")
	)
	(arc
		(start 125.330204 -270.846296)
		(mid 125.265689 -271.108515)
		(end 125.086872 -271.310862)
		(width 0.1143)
		(layer "In13.Cu")
		(net "P5E_CPU1_P2_TX_DN<13>")
	)
	(arc
		(start 125.016006 -284.312106)
		(mid 124.860078 -284.616398)
		(end 125.016006 -284.92069)
		(width 0.1143)
		(layer "In13.Cu")
		(net "P5E_CPU1_P2_TX_DN<13>")
	)
	(arc
		(start 125.086872 -276.861778)
		(mid 125.330199 -277.326344)
		(end 125.086872 -277.79091)
		(width 0.1143)
		(layer "In13.Cu")
		(net "P5E_CPU1_P2_TX_DN<13>")
	)
	(arc
		(start 125.086872 -273.621754)
		(mid 125.330199 -274.08632)
		(end 125.086872 -274.550886)
		(width 0.1143)
		(layer "In13.Cu")
		(net "P5E_CPU1_P2_TX_DN<13>")
	)
	(arc
		(start 125.588268 -295.51503)
		(mid 125.744391 -295.711522)
		(end 125.800104 -295.956228)
		(width 0.1143)
		(layer "In13.Cu")
		(net "P5E_CPU1_P2_TX_DN<13>")
	)
	(segment
		(start 165.629844 -369.03533)
		(end 165.359334 -369.30584)
		(width 0.12954)
		(layer "F.Cu")
		(net "P5E_CPU1_P2_TX_DN<12>")
	)
	(segment
		(start 165.359334 -370.00942)
		(end 165.655244 -370.30533)
		(width 0.12954)
		(layer "F.Cu")
		(net "P5E_CPU1_P2_TX_DN<12>")
	)
	(segment
		(start 122.887994 -271.390364)
		(end 123.354846 -271.656302)
		(width 0.12954)
		(layer "F.Cu")
		(net "P5E_CPU1_P2_TX_DN<12>")
	)
	(segment
		(start 165.359334 -369.30584)
		(end 165.359334 -370.00942)
		(width 0.12954)
		(layer "F.Cu")
		(net "P5E_CPU1_P2_TX_DN<12>")
	)
	(segment
		(start 141.608048 -322.50888)
		(end 146.7104 -348.16415)
		(width 0.14224)
		(layer "In13.Cu")
		(net "P5E_CPU1_P2_TX_DN<12>")
	)
	(segment
		(start 124.107702 -281.698954)
		(end 124.146818 -281.721814)
		(width 0.1143)
		(layer "In13.Cu")
		(net "P5E_CPU1_P2_TX_DN<12>")
	)
	(segment
		(start 124.107702 -278.45893)
		(end 124.146818 -278.48179)
		(width 0.1143)
		(layer "In13.Cu")
		(net "P5E_CPU1_P2_TX_DN<12>")
	)
	(segment
		(start 153.239724 -360.260138)
		(end 155.486862 -362.739432)
		(width 0.14224)
		(layer "In13.Cu")
		(net "P5E_CPU1_P2_TX_DN<12>")
	)
	(segment
		(start 136.765284 -313.149742)
		(end 141.05636 -321.177412)
		(width 0.14224)
		(layer "In13.Cu")
		(net "P5E_CPU1_P2_TX_DN<12>")
	)
	(segment
		(start 124.146818 -290.750752)
		(end 124.107702 -290.773612)
		(width 0.1143)
		(layer "In13.Cu")
		(net "P5E_CPU1_P2_TX_DN<12>")
	)
	(segment
		(start 125.15469 -296.866056)
		(end 125.155198 -296.866564)
		(width 0.1143)
		(layer "In13.Cu")
		(net "P5E_CPU1_P2_TX_DN<12>")
	)
	(segment
		(start 124.146818 -276.170898)
		(end 124.107702 -276.193758)
		(width 0.1143)
		(layer "In13.Cu")
		(net "P5E_CPU1_P2_TX_DN<12>")
	)
	(segment
		(start 123.137168 -271.961102)
		(end 123.167648 -271.978882)
		(width 0.1143)
		(layer "In13.Cu")
		(net "P5E_CPU1_P2_TX_DN<12>")
	)
	(segment
		(start 124.078746 -281.070558)
		(end 124.077222 -281.071574)
		(width 0.1143)
		(layer "In13.Cu")
		(net "P5E_CPU1_P2_TX_DN<12>")
	)
	(segment
		(start 124.146818 -285.89097)
		(end 124.107702 -285.91383)
		(width 0.1143)
		(layer "In13.Cu")
		(net "P5E_CPU1_P2_TX_DN<12>")
	)
	(segment
		(start 124.146818 -282.650946)
		(end 124.107702 -282.673806)
		(width 0.1143)
		(layer "In13.Cu")
		(net "P5E_CPU1_P2_TX_DN<12>")
	)
	(segment
		(start 141.05636 -321.177412)
		(end 141.608048 -322.50888)
		(width 0.14224)
		(layer "In13.Cu")
		(net "P5E_CPU1_P2_TX_DN<12>")
	)
	(segment
		(start 124.108718 -280.07945)
		(end 124.146818 -280.101802)
		(width 0.1143)
		(layer "In13.Cu")
		(net "P5E_CPU1_P2_TX_DN<12>")
	)
	(segment
		(start 155.486862 -362.739432)
		(end 156.929582 -363.703616)
		(width 0.14224)
		(layer "In13.Cu")
		(net "P5E_CPU1_P2_TX_DN<12>")
	)
	(segment
		(start 124.077222 -284.921198)
		(end 124.107702 -284.938978)
		(width 0.1143)
		(layer "In13.Cu")
		(net "P5E_CPU1_P2_TX_DN<12>")
	)
	(segment
		(start 124.146818 -274.550886)
		(end 124.107702 -274.573746)
		(width 0.1143)
		(layer "In13.Cu")
		(net "P5E_CPU1_P2_TX_DN<12>")
	)
	(segment
		(start 125.10897 -296.792396)
		(end 125.15469 -296.838116)
		(width 0.1143)
		(layer "In13.Cu")
		(net "P5E_CPU1_P2_TX_DN<12>")
	)
	(segment
		(start 124.146818 -279.410922)
		(end 124.107702 -279.433782)
		(width 0.1143)
		(layer "In13.Cu")
		(net "P5E_CPU1_P2_TX_DN<12>")
	)
	(segment
		(start 124.077222 -293.021004)
		(end 124.107702 -293.038784)
		(width 0.1143)
		(layer "In13.Cu")
		(net "P5E_CPU1_P2_TX_DN<12>")
	)
	(segment
		(start 124.107702 -290.773612)
		(end 124.077222 -290.791392)
		(width 0.1143)
		(layer "In13.Cu")
		(net "P5E_CPU1_P2_TX_DN<12>")
	)
	(segment
		(start 124.067316 -275.194522)
		(end 124.075952 -275.200618)
		(width 0.1143)
		(layer "In13.Cu")
		(net "P5E_CPU1_P2_TX_DN<12>")
	)
	(segment
		(start 124.075952 -278.440642)
		(end 124.107702 -278.45893)
		(width 0.1143)
		(layer "In13.Cu")
		(net "P5E_CPU1_P2_TX_DN<12>")
	)
	(segment
		(start 124.107702 -291.418772)
		(end 124.146818 -291.441632)
		(width 0.1143)
		(layer "In13.Cu")
		(net "P5E_CPU1_P2_TX_DN<12>")
	)
	(segment
		(start 124.146818 -284.270958)
		(end 124.107702 -284.293818)
		(width 0.1143)
		(layer "In13.Cu")
		(net "P5E_CPU1_P2_TX_DN<12>")
	)
	(segment
		(start 124.107702 -284.293818)
		(end 124.077222 -284.311598)
		(width 0.1143)
		(layer "In13.Cu")
		(net "P5E_CPU1_P2_TX_DN<12>")
	)
	(segment
		(start 124.077222 -283.301186)
		(end 124.107702 -283.318966)
		(width 0.1143)
		(layer "In13.Cu")
		(net "P5E_CPU1_P2_TX_DN<12>")
	)
	(segment
		(start 124.107702 -276.193758)
		(end 124.075952 -276.212046)
		(width 0.1143)
		(layer "In13.Cu")
		(net "P5E_CPU1_P2_TX_DN<12>")
	)
	(segment
		(start 124.07519 -286.53994)
		(end 124.107702 -286.558736)
		(width 0.1143)
		(layer "In13.Cu")
		(net "P5E_CPU1_P2_TX_DN<12>")
	)
	(segment
		(start 124.077222 -291.400992)
		(end 124.107702 -291.418772)
		(width 0.1143)
		(layer "In13.Cu")
		(net "P5E_CPU1_P2_TX_DN<12>")
	)
	(segment
		(start 124.075952 -276.82063)
		(end 124.107702 -276.838918)
		(width 0.1143)
		(layer "In13.Cu")
		(net "P5E_CPU1_P2_TX_DN<12>")
	)
	(segment
		(start 124.077222 -294.641016)
		(end 124.107702 -294.658796)
		(width 0.1143)
		(layer "In13.Cu")
		(net "P5E_CPU1_P2_TX_DN<12>")
	)
	(segment
		(start 124.10694 -280.078434)
		(end 124.107702 -280.078942)
		(width 0.1143)
		(layer "In13.Cu")
		(net "P5E_CPU1_P2_TX_DN<12>")
	)
	(segment
		(start 124.146818 -277.79091)
		(end 124.107702 -277.81377)
		(width 0.1143)
		(layer "In13.Cu")
		(net "P5E_CPU1_P2_TX_DN<12>")
	)
	(segment
		(start 124.146818 -281.030934)
		(end 124.107702 -281.053794)
		(width 0.1143)
		(layer "In13.Cu")
		(net "P5E_CPU1_P2_TX_DN<12>")
	)
	(segment
		(start 124.107702 -288.178748)
		(end 124.146818 -288.201608)
		(width 0.1143)
		(layer "In13.Cu")
		(net "P5E_CPU1_P2_TX_DN<12>")
	)
	(segment
		(start 125.155198 -297.064176)
		(end 125.24486 -297.31462)
		(width 0.14224)
		(layer "In13.Cu")
		(net "P5E_CPU1_P2_TX_DN<12>")
	)
	(segment
		(start 124.107702 -292.393624)
		(end 124.077222 -292.411404)
		(width 0.1143)
		(layer "In13.Cu")
		(net "P5E_CPU1_P2_TX_DN<12>")
	)
	(segment
		(start 146.7104 -348.16415)
		(end 151.58466 -357.847646)
		(width 0.14224)
		(layer "In13.Cu")
		(net "P5E_CPU1_P2_TX_DN<12>")
	)
	(segment
		(start 125.796548 -298.287694)
		(end 136.278112 -312.420762)
		(width 0.14224)
		(layer "In13.Cu")
		(net "P5E_CPU1_P2_TX_DN<12>")
	)
	(segment
		(start 124.547122 -295.451022)
		(end 124.577602 -295.468802)
		(width 0.1143)
		(layer "In13.Cu")
		(net "P5E_CPU1_P2_TX_DN<12>")
	)
	(segment
		(start 124.107702 -284.938978)
		(end 124.146818 -284.961838)
		(width 0.1143)
		(layer "In13.Cu")
		(net "P5E_CPU1_P2_TX_DN<12>")
	)
	(segment
		(start 123.63704 -272.788634)
		(end 123.676156 -272.810986)
		(width 0.1143)
		(layer "In13.Cu")
		(net "P5E_CPU1_P2_TX_DN<12>")
	)
	(segment
		(start 124.146818 -293.990776)
		(end 124.107702 -294.013636)
		(width 0.1143)
		(layer "In13.Cu")
		(net "P5E_CPU1_P2_TX_DN<12>")
	)
	(segment
		(start 123.167648 -271.978882)
		(end 123.206764 -272.001742)
		(width 0.1143)
		(layer "In13.Cu")
		(net "P5E_CPU1_P2_TX_DN<12>")
	)
	(segment
		(start 124.107702 -282.673806)
		(end 124.077222 -282.691586)
		(width 0.1143)
		(layer "In13.Cu")
		(net "P5E_CPU1_P2_TX_DN<12>")
	)
	(segment
		(start 124.577602 -295.468802)
		(end 124.616718 -295.491662)
		(width 0.1143)
		(layer "In13.Cu")
		(net "P5E_CPU1_P2_TX_DN<12>")
	)
	(segment
		(start 124.107702 -280.078942)
		(end 124.108718 -280.07945)
		(width 0.1143)
		(layer "In13.Cu")
		(net "P5E_CPU1_P2_TX_DN<12>")
	)
	(segment
		(start 124.107702 -289.79876)
		(end 124.146818 -289.82162)
		(width 0.1143)
		(layer "In13.Cu")
		(net "P5E_CPU1_P2_TX_DN<12>")
	)
	(segment
		(start 124.075952 -275.200618)
		(end 124.146818 -275.241766)
		(width 0.1143)
		(layer "In13.Cu")
		(net "P5E_CPU1_P2_TX_DN<12>")
	)
	(segment
		(start 124.144278 -287.512506)
		(end 124.077222 -287.551622)
		(width 0.1143)
		(layer "In13.Cu")
		(net "P5E_CPU1_P2_TX_DN<12>")
	)
	(segment
		(start 125.155198 -296.866564)
		(end 125.155198 -297.064176)
		(width 0.14224)
		(layer "In13.Cu")
		(net "P5E_CPU1_P2_TX_DN<12>")
	)
	(segment
		(start 124.075952 -274.592034)
		(end 124.067316 -274.59813)
		(width 0.1143)
		(layer "In13.Cu")
		(net "P5E_CPU1_P2_TX_DN<12>")
	)
	(segment
		(start 125.24486 -297.31462)
		(end 125.796548 -298.287694)
		(width 0.14224)
		(layer "In13.Cu")
		(net "P5E_CPU1_P2_TX_DN<12>")
	)
	(segment
		(start 124.077222 -289.78098)
		(end 124.107702 -289.79876)
		(width 0.1143)
		(layer "In13.Cu")
		(net "P5E_CPU1_P2_TX_DN<12>")
	)
	(segment
		(start 125.15469 -296.838116)
		(end 125.15469 -296.866056)
		(width 0.1143)
		(layer "In13.Cu")
		(net "P5E_CPU1_P2_TX_DN<12>")
	)
	(segment
		(start 124.146818 -292.370764)
		(end 124.107702 -292.393624)
		(width 0.1143)
		(layer "In13.Cu")
		(net "P5E_CPU1_P2_TX_DN<12>")
	)
	(segment
		(start 124.107702 -283.318966)
		(end 124.146818 -283.341826)
		(width 0.1143)
		(layer "In13.Cu")
		(net "P5E_CPU1_P2_TX_DN<12>")
	)
	(segment
		(start 164.860986 -367.488724)
		(end 165.16477 -367.792508)
		(width 0.14224)
		(layer "In13.Cu")
		(net "P5E_CPU1_P2_TX_DN<12>")
	)
	(segment
		(start 124.859796 -296.128948)
		(end 125.10897 -296.378122)
		(width 0.1143)
		(layer "In13.Cu")
		(net "P5E_CPU1_P2_TX_DN<12>")
	)
	(segment
		(start 124.107702 -277.81377)
		(end 124.075952 -277.832058)
		(width 0.1143)
		(layer "In13.Cu")
		(net "P5E_CPU1_P2_TX_DN<12>")
	)
	(segment
		(start 124.107702 -286.558736)
		(end 124.146818 -286.581596)
		(width 0.1143)
		(layer "In13.Cu")
		(net "P5E_CPU1_P2_TX_DN<12>")
	)
	(segment
		(start 124.107702 -276.838918)
		(end 124.146818 -276.861778)
		(width 0.1143)
		(layer "In13.Cu")
		(net "P5E_CPU1_P2_TX_DN<12>")
	)
	(segment
		(start 124.107702 -274.573746)
		(end 124.075952 -274.592034)
		(width 0.1143)
		(layer "In13.Cu")
		(net "P5E_CPU1_P2_TX_DN<12>")
	)
	(segment
		(start 124.107702 -294.013636)
		(end 124.077222 -294.031416)
		(width 0.1143)
		(layer "In13.Cu")
		(net "P5E_CPU1_P2_TX_DN<12>")
	)
	(segment
		(start 165.339014 -368.213132)
		(end 165.339014 -368.7445)
		(width 0.14224)
		(layer "In13.Cu")
		(net "P5E_CPU1_P2_TX_DN<12>")
	)
	(segment
		(start 136.278112 -312.420762)
		(end 136.765284 -313.149742)
		(width 0.14224)
		(layer "In13.Cu")
		(net "P5E_CPU1_P2_TX_DN<12>")
	)
	(segment
		(start 124.085096 -273.585686)
		(end 124.146818 -273.621754)
		(width 0.1143)
		(layer "In13.Cu")
		(net "P5E_CPU1_P2_TX_DN<12>")
	)
	(segment
		(start 124.107702 -279.433782)
		(end 124.075952 -279.45207)
		(width 0.1143)
		(layer "In13.Cu")
		(net "P5E_CPU1_P2_TX_DN<12>")
	)
	(segment
		(start 124.107702 -281.053794)
		(end 124.078746 -281.070558)
		(width 0.1143)
		(layer "In13.Cu")
		(net "P5E_CPU1_P2_TX_DN<12>")
	)
	(segment
		(start 124.075952 -280.060654)
		(end 124.10694 -280.078434)
		(width 0.1143)
		(layer "In13.Cu")
		(net "P5E_CPU1_P2_TX_DN<12>")
	)
	(segment
		(start 156.929582 -363.703616)
		(end 162.894518 -366.174528)
		(width 0.14224)
		(layer "In13.Cu")
		(net "P5E_CPU1_P2_TX_DN<12>")
	)
	(segment
		(start 124.107702 -293.038784)
		(end 124.146818 -293.061644)
		(width 0.1143)
		(layer "In13.Cu")
		(net "P5E_CPU1_P2_TX_DN<12>")
	)
	(segment
		(start 124.86005 -295.956228)
		(end 124.86005 -296.128948)
		(width 0.1143)
		(layer "In13.Cu")
		(net "P5E_CPU1_P2_TX_DN<12>")
	)
	(segment
		(start 124.107702 -294.658796)
		(end 124.146818 -294.681656)
		(width 0.1143)
		(layer "In13.Cu")
		(net "P5E_CPU1_P2_TX_DN<12>")
	)
	(segment
		(start 124.86005 -296.128948)
		(end 124.859796 -296.128948)
		(width 0.1143)
		(layer "In13.Cu")
		(net "P5E_CPU1_P2_TX_DN<12>")
	)
	(segment
		(start 124.077222 -281.681174)
		(end 124.107702 -281.698954)
		(width 0.1143)
		(layer "In13.Cu")
		(net "P5E_CPU1_P2_TX_DN<12>")
	)
	(segment
		(start 162.894518 -366.174528)
		(end 164.860986 -367.488724)
		(width 0.14224)
		(layer "In13.Cu")
		(net "P5E_CPU1_P2_TX_DN<12>")
	)
	(segment
		(start 123.606052 -272.7706)
		(end 123.63704 -272.788634)
		(width 0.1143)
		(layer "In13.Cu")
		(net "P5E_CPU1_P2_TX_DN<12>")
	)
	(segment
		(start 165.339014 -368.7445)
		(end 165.629844 -369.03533)
		(width 0.14224)
		(layer "In13.Cu")
		(net "P5E_CPU1_P2_TX_DN<12>")
	)
	(segment
		(start 124.146818 -289.13074)
		(end 124.107702 -289.1536)
		(width 0.1143)
		(layer "In13.Cu")
		(net "P5E_CPU1_P2_TX_DN<12>")
	)
	(segment
		(start 124.107702 -285.91383)
		(end 124.077222 -285.93161)
		(width 0.1143)
		(layer "In13.Cu")
		(net "P5E_CPU1_P2_TX_DN<12>")
	)
	(segment
		(start 151.58466 -357.847646)
		(end 153.239724 -360.260138)
		(width 0.14224)
		(layer "In13.Cu")
		(net "P5E_CPU1_P2_TX_DN<12>")
	)
	(segment
		(start 124.07519 -288.159952)
		(end 124.107702 -288.178748)
		(width 0.1143)
		(layer "In13.Cu")
		(net "P5E_CPU1_P2_TX_DN<12>")
	)
	(segment
		(start 123.056904 -271.656302)
		(end 122.987054 -271.726152)
		(width 0.1143)
		(layer "In13.Cu")
		(net "P5E_CPU1_P2_TX_DN<12>")
	)
	(segment
		(start 123.354846 -271.656302)
		(end 123.056904 -271.656302)
		(width 0.1143)
		(layer "In13.Cu")
		(net "P5E_CPU1_P2_TX_DN<12>")
	)
	(segment
		(start 124.107702 -289.1536)
		(end 124.077222 -289.17138)
		(width 0.1143)
		(layer "In13.Cu")
		(net "P5E_CPU1_P2_TX_DN<12>")
	)
	(segment
		(start 125.10897 -296.378122)
		(end 125.10897 -296.792396)
		(width 0.1143)
		(layer "In13.Cu")
		(net "P5E_CPU1_P2_TX_DN<12>")
	)
	(arc
		(start 122.987054 -271.726152)
		(mid 123.039471 -271.858083)
		(end 123.137168 -271.961102)
		(width 0.1143)
		(layer "In13.Cu")
		(net "P5E_CPU1_P2_TX_DN<12>")
	)
	(arc
		(start 124.146818 -294.681656)
		(mid 124.325631 -294.884006)
		(end 124.39015 -295.146222)
		(width 0.1143)
		(layer "In13.Cu")
		(net "P5E_CPU1_P2_TX_DN<12>")
	)
	(arc
		(start 124.146818 -286.581596)
		(mid 124.325631 -286.783946)
		(end 124.39015 -287.046162)
		(width 0.1143)
		(layer "In13.Cu")
		(net "P5E_CPU1_P2_TX_DN<12>")
	)
	(arc
		(start 124.077222 -282.691586)
		(mid 123.920245 -282.996386)
		(end 124.077222 -283.301186)
		(width 0.1143)
		(layer "In13.Cu")
		(net "P5E_CPU1_P2_TX_DN<12>")
	)
	(arc
		(start 124.077222 -289.17138)
		(mid 123.920245 -289.47618)
		(end 124.077222 -289.78098)
		(width 0.1143)
		(layer "In13.Cu")
		(net "P5E_CPU1_P2_TX_DN<12>")
	)
	(arc
		(start 124.077222 -284.311598)
		(mid 123.920245 -284.616398)
		(end 124.077222 -284.921198)
		(width 0.1143)
		(layer "In13.Cu")
		(net "P5E_CPU1_P2_TX_DN<12>")
	)
	(arc
		(start 124.146818 -273.621754)
		(mid 124.390145 -274.08632)
		(end 124.146818 -274.550886)
		(width 0.1143)
		(layer "In13.Cu")
		(net "P5E_CPU1_P2_TX_DN<12>")
	)
	(arc
		(start 124.146818 -291.441632)
		(mid 124.390145 -291.906198)
		(end 124.146818 -292.370764)
		(width 0.1143)
		(layer "In13.Cu")
		(net "P5E_CPU1_P2_TX_DN<12>")
	)
	(arc
		(start 124.075952 -277.832058)
		(mid 123.924363 -278.13635)
		(end 124.075952 -278.440642)
		(width 0.1143)
		(layer "In13.Cu")
		(net "P5E_CPU1_P2_TX_DN<12>")
	)
	(arc
		(start 124.146818 -280.101802)
		(mid 124.390145 -280.566368)
		(end 124.146818 -281.030934)
		(width 0.1143)
		(layer "In13.Cu")
		(net "P5E_CPU1_P2_TX_DN<12>")
	)
	(arc
		(start 124.146818 -288.201608)
		(mid 124.390145 -288.666174)
		(end 124.146818 -289.13074)
		(width 0.1143)
		(layer "In13.Cu")
		(net "P5E_CPU1_P2_TX_DN<12>")
	)
	(arc
		(start 124.075952 -276.212046)
		(mid 123.924363 -276.516338)
		(end 124.075952 -276.82063)
		(width 0.1143)
		(layer "In13.Cu")
		(net "P5E_CPU1_P2_TX_DN<12>")
	)
	(arc
		(start 123.92025 -273.256248)
		(mid 123.920823 -273.271137)
		(end 123.922282 -273.285966)
		(width 0.1143)
		(layer "In13.Cu")
		(net "P5E_CPU1_P2_TX_DN<12>")
	)
	(arc
		(start 123.206764 -272.001742)
		(mid 123.385577 -272.204092)
		(end 123.450096 -272.466308)
		(width 0.1143)
		(layer "In13.Cu")
		(net "P5E_CPU1_P2_TX_DN<12>")
	)
	(arc
		(start 124.39015 -287.046162)
		(mid 124.324914 -287.309753)
		(end 124.144278 -287.512506)
		(width 0.1143)
		(layer "In13.Cu")
		(net "P5E_CPU1_P2_TX_DN<12>")
	)
	(arc
		(start 124.146818 -276.861778)
		(mid 124.390145 -277.326344)
		(end 124.146818 -277.79091)
		(width 0.1143)
		(layer "In13.Cu")
		(net "P5E_CPU1_P2_TX_DN<12>")
	)
	(arc
		(start 123.450096 -272.466308)
		(mid 123.491351 -272.637279)
		(end 123.606052 -272.7706)
		(width 0.1143)
		(layer "In13.Cu")
		(net "P5E_CPU1_P2_TX_DN<12>")
	)
	(arc
		(start 124.077222 -290.791392)
		(mid 123.920245 -291.096192)
		(end 124.077222 -291.400992)
		(width 0.1143)
		(layer "In13.Cu")
		(net "P5E_CPU1_P2_TX_DN<12>")
	)
	(arc
		(start 123.676156 -272.810986)
		(mid 123.850927 -273.004703)
		(end 123.92025 -273.256248)
		(width 0.1143)
		(layer "In13.Cu")
		(net "P5E_CPU1_P2_TX_DN<12>")
	)
	(arc
		(start 124.648214 -295.51503)
		(mid 124.804337 -295.711522)
		(end 124.86005 -295.956228)
		(width 0.1143)
		(layer "In13.Cu")
		(net "P5E_CPU1_P2_TX_DN<12>")
	)
	(arc
		(start 123.922282 -273.285966)
		(mid 123.976965 -273.450343)
		(end 124.085096 -273.585686)
		(width 0.1143)
		(layer "In13.Cu")
		(net "P5E_CPU1_P2_TX_DN<12>")
	)
	(arc
		(start 124.077222 -292.411404)
		(mid 123.920245 -292.716204)
		(end 124.077222 -293.021004)
		(width 0.1143)
		(layer "In13.Cu")
		(net "P5E_CPU1_P2_TX_DN<12>")
	)
	(arc
		(start 124.077222 -281.071574)
		(mid 123.920245 -281.376374)
		(end 124.077222 -281.681174)
		(width 0.1143)
		(layer "In13.Cu")
		(net "P5E_CPU1_P2_TX_DN<12>")
	)
	(arc
		(start 124.39015 -295.146222)
		(mid 124.431699 -295.317644)
		(end 124.547122 -295.451022)
		(width 0.1143)
		(layer "In13.Cu")
		(net "P5E_CPU1_P2_TX_DN<12>")
	)
	(arc
		(start 124.067316 -274.59813)
		(mid 123.914435 -274.896326)
		(end 124.067316 -275.194522)
		(width 0.1143)
		(layer "In13.Cu")
		(net "P5E_CPU1_P2_TX_DN<12>")
	)
	(arc
		(start 124.146818 -275.241766)
		(mid 124.390145 -275.706332)
		(end 124.146818 -276.170898)
		(width 0.1143)
		(layer "In13.Cu")
		(net "P5E_CPU1_P2_TX_DN<12>")
	)
	(arc
		(start 124.616718 -295.491662)
		(mid 124.632669 -295.503072)
		(end 124.648214 -295.51503)
		(width 0.1143)
		(layer "In13.Cu")
		(net "P5E_CPU1_P2_TX_DN<12>")
	)
	(arc
		(start 124.077222 -294.031416)
		(mid 123.920245 -294.336216)
		(end 124.077222 -294.641016)
		(width 0.1143)
		(layer "In13.Cu")
		(net "P5E_CPU1_P2_TX_DN<12>")
	)
	(arc
		(start 124.077222 -285.93161)
		(mid 123.961795 -286.064986)
		(end 123.92025 -286.23641)
		(width 0.1143)
		(layer "In13.Cu")
		(net "P5E_CPU1_P2_TX_DN<12>")
	)
	(arc
		(start 124.146818 -278.48179)
		(mid 124.390145 -278.946356)
		(end 124.146818 -279.410922)
		(width 0.1143)
		(layer "In13.Cu")
		(net "P5E_CPU1_P2_TX_DN<12>")
	)
	(arc
		(start 123.92025 -286.23641)
		(mid 123.961216 -286.406816)
		(end 124.07519 -286.53994)
		(width 0.1143)
		(layer "In13.Cu")
		(net "P5E_CPU1_P2_TX_DN<12>")
	)
	(arc
		(start 124.146818 -289.82162)
		(mid 124.390145 -290.286186)
		(end 124.146818 -290.750752)
		(width 0.1143)
		(layer "In13.Cu")
		(net "P5E_CPU1_P2_TX_DN<12>")
	)
	(arc
		(start 123.92025 -287.856422)
		(mid 123.961216 -288.026828)
		(end 124.07519 -288.159952)
		(width 0.1143)
		(layer "In13.Cu")
		(net "P5E_CPU1_P2_TX_DN<12>")
	)
	(arc
		(start 124.146818 -281.721814)
		(mid 124.390145 -282.18638)
		(end 124.146818 -282.650946)
		(width 0.1143)
		(layer "In13.Cu")
		(net "P5E_CPU1_P2_TX_DN<12>")
	)
	(arc
		(start 124.146818 -283.341826)
		(mid 124.390145 -283.806392)
		(end 124.146818 -284.270958)
		(width 0.1143)
		(layer "In13.Cu")
		(net "P5E_CPU1_P2_TX_DN<12>")
	)
	(arc
		(start 124.075952 -279.45207)
		(mid 123.924363 -279.756362)
		(end 124.075952 -280.060654)
		(width 0.1143)
		(layer "In13.Cu")
		(net "P5E_CPU1_P2_TX_DN<12>")
	)
	(arc
		(start 124.146818 -293.061644)
		(mid 124.390145 -293.52621)
		(end 124.146818 -293.990776)
		(width 0.1143)
		(layer "In13.Cu")
		(net "P5E_CPU1_P2_TX_DN<12>")
	)
	(arc
		(start 124.146818 -284.961838)
		(mid 124.390145 -285.426404)
		(end 124.146818 -285.89097)
		(width 0.1143)
		(layer "In13.Cu")
		(net "P5E_CPU1_P2_TX_DN<12>")
	)
	(arc
		(start 124.077222 -287.551622)
		(mid 123.961795 -287.684998)
		(end 123.92025 -287.856422)
		(width 0.1143)
		(layer "In13.Cu")
		(net "P5E_CPU1_P2_TX_DN<12>")
	)
	(arc
		(start 165.16477 -367.792508)
		(mid 165.293718 -367.985492)
		(end 165.339014 -368.213132)
		(width 0.14224)
		(layer "In13.Cu")
		(net "P5E_CPU1_P2_TX_DN<12>")
	)
	(segment
		(start 163.657534 -372.47322)
		(end 163.953444 -372.76913)
		(width 0.12954)
		(layer "F.Cu")
		(net "P5E_CPU1_P2_TX_DN<11>")
	)
	(segment
		(start 163.928044 -371.49913)
		(end 163.657534 -371.76964)
		(width 0.12954)
		(layer "F.Cu")
		(net "P5E_CPU1_P2_TX_DN<11>")
	)
	(segment
		(start 163.657534 -371.76964)
		(end 163.657534 -372.47322)
		(width 0.12954)
		(layer "F.Cu")
		(net "P5E_CPU1_P2_TX_DN<11>")
	)
	(segment
		(start 122.887994 -273.010376)
		(end 123.354846 -273.276314)
		(width 0.12954)
		(layer "F.Cu")
		(net "P5E_CPU1_P2_TX_DN<11>")
	)
	(segment
		(start 140.048742 -321.282314)
		(end 140.527024 -322.43649)
		(width 0.14224)
		(layer "In13.Cu")
		(net "P5E_CPU1_P2_TX_DN<11>")
	)
	(segment
		(start 123.135136 -288.159698)
		(end 123.167902 -288.178748)
		(width 0.1143)
		(layer "In13.Cu")
		(net "P5E_CPU1_P2_TX_DN<11>")
	)
	(segment
		(start 163.637214 -368.784124)
		(end 163.637214 -371.2083)
		(width 0.14224)
		(layer "In13.Cu")
		(net "P5E_CPU1_P2_TX_DN<11>")
	)
	(segment
		(start 123.919996 -296.128948)
		(end 124.16409 -296.373042)
		(width 0.1143)
		(layer "In13.Cu")
		(net "P5E_CPU1_P2_TX_DN<11>")
	)
	(segment
		(start 152.488138 -361.012232)
		(end 154.556968 -363.292898)
		(width 0.14224)
		(layer "In13.Cu")
		(net "P5E_CPU1_P2_TX_DN<11>")
	)
	(segment
		(start 123.167902 -294.658796)
		(end 123.20778 -294.682418)
		(width 0.1143)
		(layer "In13.Cu")
		(net "P5E_CPU1_P2_TX_DN<11>")
	)
	(segment
		(start 124.210318 -296.866564)
		(end 124.210318 -297.284394)
		(width 0.14224)
		(layer "In13.Cu")
		(net "P5E_CPU1_P2_TX_DN<11>")
	)
	(segment
		(start 123.206764 -279.410922)
		(end 123.167648 -279.433782)
		(width 0.1143)
		(layer "In13.Cu")
		(net "P5E_CPU1_P2_TX_DN<11>")
	)
	(segment
		(start 136.215374 -314.109862)
		(end 140.048742 -321.282314)
		(width 0.14224)
		(layer "In13.Cu")
		(net "P5E_CPU1_P2_TX_DN<11>")
	)
	(segment
		(start 123.136152 -281.680666)
		(end 123.167902 -281.698954)
		(width 0.1143)
		(layer "In13.Cu")
		(net "P5E_CPU1_P2_TX_DN<11>")
	)
	(segment
		(start 123.137168 -275.201126)
		(end 123.167648 -275.218906)
		(width 0.1143)
		(layer "In13.Cu")
		(net "P5E_CPU1_P2_TX_DN<11>")
	)
	(segment
		(start 123.208034 -287.510474)
		(end 123.136152 -287.55213)
		(width 0.1143)
		(layer "In13.Cu")
		(net "P5E_CPU1_P2_TX_DN<11>")
	)
	(segment
		(start 123.167648 -277.81377)
		(end 123.137168 -277.83155)
		(width 0.1143)
		(layer "In13.Cu")
		(net "P5E_CPU1_P2_TX_DN<11>")
	)
	(segment
		(start 123.167902 -293.038784)
		(end 123.17095 -293.040562)
		(width 0.1143)
		(layer "In13.Cu")
		(net "P5E_CPU1_P2_TX_DN<11>")
	)
	(segment
		(start 123.167902 -291.418772)
		(end 123.167902 -291.419026)
		(width 0.1143)
		(layer "In13.Cu")
		(net "P5E_CPU1_P2_TX_DN<11>")
	)
	(segment
		(start 145.854674 -348.666308)
		(end 150.979378 -358.817164)
		(width 0.14224)
		(layer "In13.Cu")
		(net "P5E_CPU1_P2_TX_DN<11>")
	)
	(segment
		(start 162.86353 -367.511076)
		(end 163.284154 -367.9317)
		(width 0.14224)
		(layer "In13.Cu")
		(net "P5E_CPU1_P2_TX_DN<11>")
	)
	(segment
		(start 123.167648 -275.218906)
		(end 123.206764 -275.241766)
		(width 0.1143)
		(layer "In13.Cu")
		(net "P5E_CPU1_P2_TX_DN<11>")
	)
	(segment
		(start 123.136152 -283.300678)
		(end 123.16714 -283.318458)
		(width 0.1143)
		(layer "In13.Cu")
		(net "P5E_CPU1_P2_TX_DN<11>")
	)
	(segment
		(start 123.218956 -292.362382)
		(end 123.206002 -292.37178)
		(width 0.1143)
		(layer "In13.Cu")
		(net "P5E_CPU1_P2_TX_DN<11>")
	)
	(segment
		(start 123.167902 -288.178748)
		(end 123.17095 -288.180526)
		(width 0.1143)
		(layer "In13.Cu")
		(net "P5E_CPU1_P2_TX_DN<11>")
	)
	(segment
		(start 123.17095 -290.771834)
		(end 123.136152 -290.7919)
		(width 0.1143)
		(layer "In13.Cu")
		(net "P5E_CPU1_P2_TX_DN<11>")
	)
	(segment
		(start 156.320744 -364.471966)
		(end 161.569146 -366.646206)
		(width 0.14224)
		(layer "In13.Cu")
		(net "P5E_CPU1_P2_TX_DN<11>")
	)
	(segment
		(start 123.137168 -273.581114)
		(end 123.167648 -273.598894)
		(width 0.1143)
		(layer "In13.Cu")
		(net "P5E_CPU1_P2_TX_DN<11>")
	)
	(segment
		(start 123.637802 -295.468802)
		(end 123.676156 -295.4909)
		(width 0.1143)
		(layer "In13.Cu")
		(net "P5E_CPU1_P2_TX_DN<11>")
	)
	(segment
		(start 123.137168 -276.821138)
		(end 123.167648 -276.838918)
		(width 0.1143)
		(layer "In13.Cu")
		(net "P5E_CPU1_P2_TX_DN<11>")
	)
	(segment
		(start 123.206764 -274.550886)
		(end 123.167648 -274.573746)
		(width 0.1143)
		(layer "In13.Cu")
		(net "P5E_CPU1_P2_TX_DN<11>")
	)
	(segment
		(start 123.206764 -277.79091)
		(end 123.167648 -277.81377)
		(width 0.1143)
		(layer "In13.Cu")
		(net "P5E_CPU1_P2_TX_DN<11>")
	)
	(segment
		(start 124.20981 -296.838116)
		(end 124.20981 -296.866056)
		(width 0.1143)
		(layer "In13.Cu")
		(net "P5E_CPU1_P2_TX_DN<11>")
	)
	(segment
		(start 123.167648 -274.573746)
		(end 123.137168 -274.591526)
		(width 0.1143)
		(layer "In13.Cu")
		(net "P5E_CPU1_P2_TX_DN<11>")
	)
	(segment
		(start 123.919996 -295.956228)
		(end 123.919996 -296.128948)
		(width 0.1143)
		(layer "In13.Cu")
		(net "P5E_CPU1_P2_TX_DN<11>")
	)
	(segment
		(start 123.136152 -294.640508)
		(end 123.167902 -294.658796)
		(width 0.1143)
		(layer "In13.Cu")
		(net "P5E_CPU1_P2_TX_DN<11>")
	)
	(segment
		(start 123.134374 -286.539178)
		(end 123.20905 -286.58312)
		(width 0.1143)
		(layer "In13.Cu")
		(net "P5E_CPU1_P2_TX_DN<11>")
	)
	(segment
		(start 124.16409 -296.373042)
		(end 124.16409 -296.792396)
		(width 0.1143)
		(layer "In13.Cu")
		(net "P5E_CPU1_P2_TX_DN<11>")
	)
	(segment
		(start 123.206002 -291.440616)
		(end 123.218956 -291.450014)
		(width 0.1143)
		(layer "In13.Cu")
		(net "P5E_CPU1_P2_TX_DN<11>")
	)
	(segment
		(start 123.137168 -280.061162)
		(end 123.167648 -280.078942)
		(width 0.1143)
		(layer "In13.Cu")
		(net "P5E_CPU1_P2_TX_DN<11>")
	)
	(segment
		(start 150.979378 -358.817164)
		(end 152.488138 -361.012232)
		(width 0.14224)
		(layer "In13.Cu")
		(net "P5E_CPU1_P2_TX_DN<11>")
	)
	(segment
		(start 125.050042 -298.856654)
		(end 134.877048 -312.107072)
		(width 0.14224)
		(layer "In13.Cu")
		(net "P5E_CPU1_P2_TX_DN<11>")
	)
	(segment
		(start 134.877048 -312.107072)
		(end 136.215374 -314.109862)
		(width 0.14224)
		(layer "In13.Cu")
		(net "P5E_CPU1_P2_TX_DN<11>")
	)
	(segment
		(start 123.167902 -283.318966)
		(end 123.17095 -283.320744)
		(width 0.1143)
		(layer "In13.Cu")
		(net "P5E_CPU1_P2_TX_DN<11>")
	)
	(segment
		(start 123.056904 -273.276314)
		(end 122.987054 -273.346164)
		(width 0.1143)
		(layer "In13.Cu")
		(net "P5E_CPU1_P2_TX_DN<11>")
	)
	(segment
		(start 124.439426 -297.837606)
		(end 125.050042 -298.856654)
		(width 0.14224)
		(layer "In13.Cu")
		(net "P5E_CPU1_P2_TX_DN<11>")
	)
	(segment
		(start 123.17095 -294.011858)
		(end 123.136152 -294.031924)
		(width 0.1143)
		(layer "In13.Cu")
		(net "P5E_CPU1_P2_TX_DN<11>")
	)
	(segment
		(start 123.16714 -283.318458)
		(end 123.167902 -283.318966)
		(width 0.1143)
		(layer "In13.Cu")
		(net "P5E_CPU1_P2_TX_DN<11>")
	)
	(segment
		(start 123.206002 -292.37178)
		(end 123.136152 -292.411912)
		(width 0.1143)
		(layer "In13.Cu")
		(net "P5E_CPU1_P2_TX_DN<11>")
	)
	(segment
		(start 140.698728 -323.000878)
		(end 145.854674 -348.666308)
		(width 0.14224)
		(layer "In13.Cu")
		(net "P5E_CPU1_P2_TX_DN<11>")
	)
	(segment
		(start 123.137168 -278.44115)
		(end 123.167648 -278.45893)
		(width 0.1143)
		(layer "In13.Cu")
		(net "P5E_CPU1_P2_TX_DN<11>")
	)
	(segment
		(start 123.167902 -291.419026)
		(end 123.206002 -291.440616)
		(width 0.1143)
		(layer "In13.Cu")
		(net "P5E_CPU1_P2_TX_DN<11>")
	)
	(segment
		(start 123.167648 -273.598894)
		(end 123.206764 -273.621754)
		(width 0.1143)
		(layer "In13.Cu")
		(net "P5E_CPU1_P2_TX_DN<11>")
	)
	(segment
		(start 123.167648 -279.433782)
		(end 123.137168 -279.451562)
		(width 0.1143)
		(layer "In13.Cu")
		(net "P5E_CPU1_P2_TX_DN<11>")
	)
	(segment
		(start 123.167902 -281.698954)
		(end 123.17095 -281.700732)
		(width 0.1143)
		(layer "In13.Cu")
		(net "P5E_CPU1_P2_TX_DN<11>")
	)
	(segment
		(start 123.167648 -280.078942)
		(end 123.206764 -280.101802)
		(width 0.1143)
		(layer "In13.Cu")
		(net "P5E_CPU1_P2_TX_DN<11>")
	)
	(segment
		(start 124.16409 -296.792396)
		(end 124.20981 -296.838116)
		(width 0.1143)
		(layer "In13.Cu")
		(net "P5E_CPU1_P2_TX_DN<11>")
	)
	(segment
		(start 123.136152 -293.020496)
		(end 123.167902 -293.038784)
		(width 0.1143)
		(layer "In13.Cu")
		(net "P5E_CPU1_P2_TX_DN<11>")
	)
	(segment
		(start 123.206764 -276.170898)
		(end 123.167648 -276.193758)
		(width 0.1143)
		(layer "In13.Cu")
		(net "P5E_CPU1_P2_TX_DN<11>")
	)
	(segment
		(start 123.450096 -295.141904)
		(end 123.450096 -295.146222)
		(width 0.1143)
		(layer "In13.Cu")
		(net "P5E_CPU1_P2_TX_DN<11>")
	)
	(segment
		(start 163.637214 -371.2083)
		(end 163.928044 -371.49913)
		(width 0.14224)
		(layer "In13.Cu")
		(net "P5E_CPU1_P2_TX_DN<11>")
	)
	(segment
		(start 123.167902 -289.79876)
		(end 123.17095 -289.800538)
		(width 0.1143)
		(layer "In13.Cu")
		(net "P5E_CPU1_P2_TX_DN<11>")
	)
	(segment
		(start 123.167648 -281.053794)
		(end 123.136152 -281.072082)
		(width 0.1143)
		(layer "In13.Cu")
		(net "P5E_CPU1_P2_TX_DN<11>")
	)
	(segment
		(start 123.206764 -281.030934)
		(end 123.167648 -281.053794)
		(width 0.1143)
		(layer "In13.Cu")
		(net "P5E_CPU1_P2_TX_DN<11>")
	)
	(segment
		(start 124.210318 -297.284394)
		(end 124.439426 -297.837606)
		(width 0.14224)
		(layer "In13.Cu")
		(net "P5E_CPU1_P2_TX_DN<11>")
	)
	(segment
		(start 123.136152 -289.780472)
		(end 123.167902 -289.79876)
		(width 0.1143)
		(layer "In13.Cu")
		(net "P5E_CPU1_P2_TX_DN<11>")
	)
	(segment
		(start 123.136152 -284.92069)
		(end 123.167902 -284.938978)
		(width 0.1143)
		(layer "In13.Cu")
		(net "P5E_CPU1_P2_TX_DN<11>")
	)
	(segment
		(start 123.167648 -278.45893)
		(end 123.206764 -278.48179)
		(width 0.1143)
		(layer "In13.Cu")
		(net "P5E_CPU1_P2_TX_DN<11>")
	)
	(segment
		(start 123.167648 -276.838918)
		(end 123.206764 -276.861778)
		(width 0.1143)
		(layer "In13.Cu")
		(net "P5E_CPU1_P2_TX_DN<11>")
	)
	(segment
		(start 123.17095 -285.912052)
		(end 123.136152 -285.932118)
		(width 0.1143)
		(layer "In13.Cu")
		(net "P5E_CPU1_P2_TX_DN<11>")
	)
	(segment
		(start 123.136152 -291.400484)
		(end 123.167902 -291.418772)
		(width 0.1143)
		(layer "In13.Cu")
		(net "P5E_CPU1_P2_TX_DN<11>")
	)
	(segment
		(start 123.219464 -287.501838)
		(end 123.208034 -287.510474)
		(width 0.1143)
		(layer "In13.Cu")
		(net "P5E_CPU1_P2_TX_DN<11>")
	)
	(segment
		(start 123.354846 -273.276314)
		(end 123.056904 -273.276314)
		(width 0.1143)
		(layer "In13.Cu")
		(net "P5E_CPU1_P2_TX_DN<11>")
	)
	(segment
		(start 161.569146 -366.646206)
		(end 162.86353 -367.511076)
		(width 0.14224)
		(layer "In13.Cu")
		(net "P5E_CPU1_P2_TX_DN<11>")
	)
	(segment
		(start 123.17095 -282.672028)
		(end 123.136152 -282.692094)
		(width 0.1143)
		(layer "In13.Cu")
		(net "P5E_CPU1_P2_TX_DN<11>")
	)
	(segment
		(start 123.606052 -295.450514)
		(end 123.637802 -295.468802)
		(width 0.1143)
		(layer "In13.Cu")
		(net "P5E_CPU1_P2_TX_DN<11>")
	)
	(segment
		(start 123.17095 -289.151822)
		(end 123.136152 -289.171888)
		(width 0.1143)
		(layer "In13.Cu")
		(net "P5E_CPU1_P2_TX_DN<11>")
	)
	(segment
		(start 123.450096 -287.046162)
		(end 123.450096 -287.050734)
		(width 0.1143)
		(layer "In13.Cu")
		(net "P5E_CPU1_P2_TX_DN<11>")
	)
	(segment
		(start 124.20981 -296.866056)
		(end 124.210318 -296.866564)
		(width 0.1143)
		(layer "In13.Cu")
		(net "P5E_CPU1_P2_TX_DN<11>")
	)
	(segment
		(start 154.556968 -363.292898)
		(end 156.320744 -364.471966)
		(width 0.14224)
		(layer "In13.Cu")
		(net "P5E_CPU1_P2_TX_DN<11>")
	)
	(segment
		(start 123.167648 -276.193758)
		(end 123.137168 -276.211538)
		(width 0.1143)
		(layer "In13.Cu")
		(net "P5E_CPU1_P2_TX_DN<11>")
	)
	(segment
		(start 123.134374 -288.15919)
		(end 123.135136 -288.159698)
		(width 0.1143)
		(layer "In13.Cu")
		(net "P5E_CPU1_P2_TX_DN<11>")
	)
	(segment
		(start 123.17095 -284.29204)
		(end 123.136152 -284.312106)
		(width 0.1143)
		(layer "In13.Cu")
		(net "P5E_CPU1_P2_TX_DN<11>")
	)
	(segment
		(start 123.167902 -284.938978)
		(end 123.17095 -284.940756)
		(width 0.1143)
		(layer "In13.Cu")
		(net "P5E_CPU1_P2_TX_DN<11>")
	)
	(segment
		(start 140.527024 -322.43649)
		(end 140.698728 -323.000878)
		(width 0.14224)
		(layer "In13.Cu")
		(net "P5E_CPU1_P2_TX_DN<11>")
	)
	(arc
		(start 123.450096 -295.146222)
		(mid 123.491351 -295.317193)
		(end 123.606052 -295.450514)
		(width 0.1143)
		(layer "In13.Cu")
		(net "P5E_CPU1_P2_TX_DN<11>")
	)
	(arc
		(start 123.17095 -281.700732)
		(mid 123.450565 -282.18638)
		(end 123.17095 -282.672028)
		(width 0.1143)
		(layer "In13.Cu")
		(net "P5E_CPU1_P2_TX_DN<11>")
	)
	(arc
		(start 123.137168 -274.591526)
		(mid 122.980191 -274.896326)
		(end 123.137168 -275.201126)
		(width 0.1143)
		(layer "In13.Cu")
		(net "P5E_CPU1_P2_TX_DN<11>")
	)
	(arc
		(start 123.136152 -289.171888)
		(mid 122.980224 -289.47618)
		(end 123.136152 -289.780472)
		(width 0.1143)
		(layer "In13.Cu")
		(net "P5E_CPU1_P2_TX_DN<11>")
	)
	(arc
		(start 123.17095 -288.180526)
		(mid 123.450565 -288.666174)
		(end 123.17095 -289.151822)
		(width 0.1143)
		(layer "In13.Cu")
		(net "P5E_CPU1_P2_TX_DN<11>")
	)
	(arc
		(start 123.17095 -284.940756)
		(mid 123.450565 -285.426404)
		(end 123.17095 -285.912052)
		(width 0.1143)
		(layer "In13.Cu")
		(net "P5E_CPU1_P2_TX_DN<11>")
	)
	(arc
		(start 123.136152 -282.692094)
		(mid 122.980224 -282.996386)
		(end 123.136152 -283.300678)
		(width 0.1143)
		(layer "In13.Cu")
		(net "P5E_CPU1_P2_TX_DN<11>")
	)
	(arc
		(start 122.980196 -287.856422)
		(mid 123.020958 -288.026306)
		(end 123.134374 -288.15919)
		(width 0.1143)
		(layer "In13.Cu")
		(net "P5E_CPU1_P2_TX_DN<11>")
	)
	(arc
		(start 123.136152 -285.932118)
		(mid 123.021476 -286.065452)
		(end 122.980196 -286.23641)
		(width 0.1143)
		(layer "In13.Cu")
		(net "P5E_CPU1_P2_TX_DN<11>")
	)
	(arc
		(start 123.136152 -284.312106)
		(mid 122.980224 -284.616398)
		(end 123.136152 -284.92069)
		(width 0.1143)
		(layer "In13.Cu")
		(net "P5E_CPU1_P2_TX_DN<11>")
	)
	(arc
		(start 123.17095 -289.800538)
		(mid 123.450565 -290.286186)
		(end 123.17095 -290.771834)
		(width 0.1143)
		(layer "In13.Cu")
		(net "P5E_CPU1_P2_TX_DN<11>")
	)
	(arc
		(start 123.136152 -281.072082)
		(mid 122.980224 -281.376374)
		(end 123.136152 -281.680666)
		(width 0.1143)
		(layer "In13.Cu")
		(net "P5E_CPU1_P2_TX_DN<11>")
	)
	(arc
		(start 123.206764 -275.241766)
		(mid 123.450091 -275.706332)
		(end 123.206764 -276.170898)
		(width 0.1143)
		(layer "In13.Cu")
		(net "P5E_CPU1_P2_TX_DN<11>")
	)
	(arc
		(start 122.980196 -286.23641)
		(mid 123.020958 -286.406294)
		(end 123.134374 -286.539178)
		(width 0.1143)
		(layer "In13.Cu")
		(net "P5E_CPU1_P2_TX_DN<11>")
	)
	(arc
		(start 123.136152 -294.031924)
		(mid 122.980224 -294.336216)
		(end 123.136152 -294.640508)
		(width 0.1143)
		(layer "In13.Cu")
		(net "P5E_CPU1_P2_TX_DN<11>")
	)
	(arc
		(start 123.206764 -278.48179)
		(mid 123.450091 -278.946356)
		(end 123.206764 -279.410922)
		(width 0.1143)
		(layer "In13.Cu")
		(net "P5E_CPU1_P2_TX_DN<11>")
	)
	(arc
		(start 123.206764 -276.861778)
		(mid 123.450091 -277.326344)
		(end 123.206764 -277.79091)
		(width 0.1143)
		(layer "In13.Cu")
		(net "P5E_CPU1_P2_TX_DN<11>")
	)
	(arc
		(start 123.17095 -283.320744)
		(mid 123.450565 -283.806392)
		(end 123.17095 -284.29204)
		(width 0.1143)
		(layer "In13.Cu")
		(net "P5E_CPU1_P2_TX_DN<11>")
	)
	(arc
		(start 122.987054 -273.346164)
		(mid 123.039471 -273.478095)
		(end 123.137168 -273.581114)
		(width 0.1143)
		(layer "In13.Cu")
		(net "P5E_CPU1_P2_TX_DN<11>")
	)
	(arc
		(start 123.20905 -286.58312)
		(mid 123.386246 -286.785132)
		(end 123.450096 -287.046162)
		(width 0.1143)
		(layer "In13.Cu")
		(net "P5E_CPU1_P2_TX_DN<11>")
	)
	(arc
		(start 123.136152 -290.7919)
		(mid 122.980224 -291.096192)
		(end 123.136152 -291.400484)
		(width 0.1143)
		(layer "In13.Cu")
		(net "P5E_CPU1_P2_TX_DN<11>")
	)
	(arc
		(start 123.17095 -293.040562)
		(mid 123.450565 -293.52621)
		(end 123.17095 -294.011858)
		(width 0.1143)
		(layer "In13.Cu")
		(net "P5E_CPU1_P2_TX_DN<11>")
	)
	(arc
		(start 163.284154 -367.9317)
		(mid 163.545476 -368.322795)
		(end 163.637214 -368.784124)
		(width 0.14224)
		(layer "In13.Cu")
		(net "P5E_CPU1_P2_TX_DN<11>")
	)
	(arc
		(start 123.136152 -287.55213)
		(mid 123.021476 -287.685464)
		(end 122.980196 -287.856422)
		(width 0.1143)
		(layer "In13.Cu")
		(net "P5E_CPU1_P2_TX_DN<11>")
	)
	(arc
		(start 123.137168 -279.451562)
		(mid 122.980191 -279.756362)
		(end 123.137168 -280.061162)
		(width 0.1143)
		(layer "In13.Cu")
		(net "P5E_CPU1_P2_TX_DN<11>")
	)
	(arc
		(start 123.206764 -273.621754)
		(mid 123.450091 -274.08632)
		(end 123.206764 -274.550886)
		(width 0.1143)
		(layer "In13.Cu")
		(net "P5E_CPU1_P2_TX_DN<11>")
	)
	(arc
		(start 123.137168 -276.211538)
		(mid 122.980191 -276.516338)
		(end 123.137168 -276.821138)
		(width 0.1143)
		(layer "In13.Cu")
		(net "P5E_CPU1_P2_TX_DN<11>")
	)
	(arc
		(start 123.137168 -277.83155)
		(mid 122.980191 -278.13635)
		(end 123.137168 -278.44115)
		(width 0.1143)
		(layer "In13.Cu")
		(net "P5E_CPU1_P2_TX_DN<11>")
	)
	(arc
		(start 123.218956 -291.450014)
		(mid 123.453383 -291.906198)
		(end 123.218956 -292.362382)
		(width 0.1143)
		(layer "In13.Cu")
		(net "P5E_CPU1_P2_TX_DN<11>")
	)
	(arc
		(start 123.450096 -287.050734)
		(mid 123.389097 -287.304058)
		(end 123.219464 -287.501838)
		(width 0.1143)
		(layer "In13.Cu")
		(net "P5E_CPU1_P2_TX_DN<11>")
	)
	(arc
		(start 123.206764 -280.101802)
		(mid 123.450091 -280.566368)
		(end 123.206764 -281.030934)
		(width 0.1143)
		(layer "In13.Cu")
		(net "P5E_CPU1_P2_TX_DN<11>")
	)
	(arc
		(start 123.136152 -292.411912)
		(mid 122.980224 -292.716204)
		(end 123.136152 -293.020496)
		(width 0.1143)
		(layer "In13.Cu")
		(net "P5E_CPU1_P2_TX_DN<11>")
	)
	(arc
		(start 123.20778 -294.682418)
		(mid 123.385816 -294.882168)
		(end 123.450096 -295.141904)
		(width 0.1143)
		(layer "In13.Cu")
		(net "P5E_CPU1_P2_TX_DN<11>")
	)
	(arc
		(start 123.676156 -295.4909)
		(mid 123.855408 -295.693523)
		(end 123.919996 -295.956228)
		(width 0.1143)
		(layer "In13.Cu")
		(net "P5E_CPU1_P2_TX_DN<11>")
	)
	(segment
		(start 162.226244 -373.96293)
		(end 161.955734 -374.23344)
		(width 0.12954)
		(layer "F.Cu")
		(net "P5E_CPU1_P2_TX_DN<10>")
	)
	(segment
		(start 161.955734 -374.23344)
		(end 161.955734 -374.93702)
		(width 0.12954)
		(layer "F.Cu")
		(net "P5E_CPU1_P2_TX_DN<10>")
	)
	(segment
		(start 122.887994 -269.770352)
		(end 123.354846 -270.03629)
		(width 0.12954)
		(layer "F.Cu")
		(net "P5E_CPU1_P2_TX_DN<10>")
	)
	(segment
		(start 161.955734 -374.93702)
		(end 162.251644 -375.23293)
		(width 0.12954)
		(layer "F.Cu")
		(net "P5E_CPU1_P2_TX_DN<10>")
	)
	(segment
		(start 123.06681 -296.538396)
		(end 123.11253 -296.584116)
		(width 0.1143)
		(layer "In13.Cu")
		(net "P5E_CPU1_P2_TX_DN<10>")
	)
	(segment
		(start 122.266964 -293.990776)
		(end 122.228864 -294.013128)
		(width 0.1143)
		(layer "In13.Cu")
		(net "P5E_CPU1_P2_TX_DN<10>")
	)
	(segment
		(start 124.27458 -299.381672)
		(end 133.584696 -311.933844)
		(width 0.14224)
		(layer "In13.Cu")
		(net "P5E_CPU1_P2_TX_DN<10>")
	)
	(segment
		(start 122.224292 -289.155632)
		(end 122.22353 -289.15614)
		(width 0.1143)
		(layer "In13.Cu")
		(net "P5E_CPU1_P2_TX_DN<10>")
	)
	(segment
		(start 122.196098 -289.780472)
		(end 122.227086 -289.798252)
		(width 0.1143)
		(layer "In13.Cu")
		(net "P5E_CPU1_P2_TX_DN<10>")
	)
	(segment
		(start 122.220228 -289.157918)
		(end 122.196098 -289.171888)
		(width 0.1143)
		(layer "In13.Cu")
		(net "P5E_CPU1_P2_TX_DN<10>")
	)
	(segment
		(start 122.230388 -290.772088)
		(end 122.228864 -290.773104)
		(width 0.1143)
		(layer "In13.Cu")
		(net "P5E_CPU1_P2_TX_DN<10>")
	)
	(segment
		(start 122.980196 -296.122852)
		(end 123.06681 -296.209466)
		(width 0.1143)
		(layer "In13.Cu")
		(net "P5E_CPU1_P2_TX_DN<10>")
	)
	(segment
		(start 122.230388 -285.912306)
		(end 122.228864 -285.913322)
		(width 0.1143)
		(layer "In13.Cu")
		(net "P5E_CPU1_P2_TX_DN<10>")
	)
	(segment
		(start 122.230388 -284.940502)
		(end 122.266964 -284.961838)
		(width 0.1143)
		(layer "In13.Cu")
		(net "P5E_CPU1_P2_TX_DN<10>")
	)
	(segment
		(start 122.19432 -286.539178)
		(end 122.227848 -286.558736)
		(width 0.1143)
		(layer "In13.Cu")
		(net "P5E_CPU1_P2_TX_DN<10>")
	)
	(segment
		(start 122.227594 -276.838918)
		(end 122.26671 -276.861778)
		(width 0.1143)
		(layer "In13.Cu")
		(net "P5E_CPU1_P2_TX_DN<10>")
	)
	(segment
		(start 160.237678 -367.914428)
		(end 160.237678 -369.390422)
		(width 0.14224)
		(layer "In13.Cu")
		(net "P5E_CPU1_P2_TX_DN<10>")
	)
	(segment
		(start 123.11253 -296.612564)
		(end 123.11253 -296.926254)
		(width 0.14224)
		(layer "In13.Cu")
		(net "P5E_CPU1_P2_TX_DN<10>")
	)
	(segment
		(start 122.227086 -294.658288)
		(end 122.227848 -294.658796)
		(width 0.1143)
		(layer "In13.Cu")
		(net "P5E_CPU1_P2_TX_DN<10>")
	)
	(segment
		(start 122.197114 -275.201126)
		(end 122.227594 -275.218906)
		(width 0.1143)
		(layer "In13.Cu")
		(net "P5E_CPU1_P2_TX_DN<10>")
	)
	(segment
		(start 122.26671 -274.550886)
		(end 122.227594 -274.573746)
		(width 0.1143)
		(layer "In13.Cu")
		(net "P5E_CPU1_P2_TX_DN<10>")
	)
	(segment
		(start 122.222006 -289.156902)
		(end 122.221244 -289.15741)
		(width 0.1143)
		(layer "In13.Cu")
		(net "P5E_CPU1_P2_TX_DN<10>")
	)
	(segment
		(start 122.228864 -294.013128)
		(end 122.227848 -294.013636)
		(width 0.1143)
		(layer "In13.Cu")
		(net "P5E_CPU1_P2_TX_DN<10>")
	)
	(segment
		(start 122.227086 -281.698446)
		(end 122.227848 -281.698954)
		(width 0.1143)
		(layer "In13.Cu")
		(net "P5E_CPU1_P2_TX_DN<10>")
	)
	(segment
		(start 122.221244 -285.91764)
		(end 122.220228 -285.918148)
		(width 0.1143)
		(layer "In13.Cu")
		(net "P5E_CPU1_P2_TX_DN<10>")
	)
	(segment
		(start 122.227594 -271.978882)
		(end 122.26671 -272.001742)
		(width 0.1143)
		(layer "In13.Cu")
		(net "P5E_CPU1_P2_TX_DN<10>")
	)
	(segment
		(start 122.22353 -289.15614)
		(end 122.222006 -289.156902)
		(width 0.1143)
		(layer "In13.Cu")
		(net "P5E_CPU1_P2_TX_DN<10>")
	)
	(segment
		(start 149.945852 -359.043224)
		(end 151.60879 -361.467146)
		(width 0.14224)
		(layer "In13.Cu")
		(net "P5E_CPU1_P2_TX_DN<10>")
	)
	(segment
		(start 122.227594 -275.218906)
		(end 122.26671 -275.241766)
		(width 0.1143)
		(layer "In13.Cu")
		(net "P5E_CPU1_P2_TX_DN<10>")
	)
	(segment
		(start 122.22353 -290.776152)
		(end 122.222006 -290.776914)
		(width 0.1143)
		(layer "In13.Cu")
		(net "P5E_CPU1_P2_TX_DN<10>")
	)
	(segment
		(start 122.222006 -290.776914)
		(end 122.221244 -290.777422)
		(width 0.1143)
		(layer "In13.Cu")
		(net "P5E_CPU1_P2_TX_DN<10>")
	)
	(segment
		(start 122.266964 -282.650946)
		(end 122.230388 -282.672282)
		(width 0.1143)
		(layer "In13.Cu")
		(net "P5E_CPU1_P2_TX_DN<10>")
	)
	(segment
		(start 122.222006 -284.29712)
		(end 122.221244 -284.297628)
		(width 0.1143)
		(layer "In13.Cu")
		(net "P5E_CPU1_P2_TX_DN<10>")
	)
	(segment
		(start 122.230388 -294.66032)
		(end 122.231404 -294.660828)
		(width 0.1143)
		(layer "In13.Cu")
		(net "P5E_CPU1_P2_TX_DN<10>")
	)
	(segment
		(start 122.227086 -289.798252)
		(end 122.227848 -289.79876)
		(width 0.1143)
		(layer "In13.Cu")
		(net "P5E_CPU1_P2_TX_DN<10>")
	)
	(segment
		(start 122.228864 -289.153092)
		(end 122.227848 -289.1536)
		(width 0.1143)
		(layer "In13.Cu")
		(net "P5E_CPU1_P2_TX_DN<10>")
	)
	(segment
		(start 122.227848 -285.91383)
		(end 122.227086 -285.914338)
		(width 0.1143)
		(layer "In13.Cu")
		(net "P5E_CPU1_P2_TX_DN<10>")
	)
	(segment
		(start 122.705368 -295.473374)
		(end 122.736864 -295.491662)
		(width 0.1143)
		(layer "In13.Cu")
		(net "P5E_CPU1_P2_TX_DN<10>")
	)
	(segment
		(start 122.227594 -280.078942)
		(end 122.26671 -280.101802)
		(width 0.1143)
		(layer "In13.Cu")
		(net "P5E_CPU1_P2_TX_DN<10>")
	)
	(segment
		(start 122.230388 -281.700478)
		(end 122.231404 -281.700986)
		(width 0.1143)
		(layer "In13.Cu")
		(net "P5E_CPU1_P2_TX_DN<10>")
	)
	(segment
		(start 122.227848 -289.79876)
		(end 122.228864 -289.799268)
		(width 0.1143)
		(layer "In13.Cu")
		(net "P5E_CPU1_P2_TX_DN<10>")
	)
	(segment
		(start 122.231404 -294.660828)
		(end 122.266964 -294.681656)
		(width 0.1143)
		(layer "In13.Cu")
		(net "P5E_CPU1_P2_TX_DN<10>")
	)
	(segment
		(start 144.87906 -348.976696)
		(end 149.945852 -359.043224)
		(width 0.14224)
		(layer "In13.Cu")
		(net "P5E_CPU1_P2_TX_DN<10>")
	)
	(segment
		(start 158.380938 -366.360964)
		(end 159.796988 -367.307368)
		(width 0.14224)
		(layer "In13.Cu")
		(net "P5E_CPU1_P2_TX_DN<10>")
	)
	(segment
		(start 122.227594 -271.333722)
		(end 122.197114 -271.351502)
		(width 0.1143)
		(layer "In13.Cu")
		(net "P5E_CPU1_P2_TX_DN<10>")
	)
	(segment
		(start 123.606306 -298.266612)
		(end 124.27458 -299.381672)
		(width 0.14224)
		(layer "In13.Cu")
		(net "P5E_CPU1_P2_TX_DN<10>")
	)
	(segment
		(start 122.230388 -289.152076)
		(end 122.228864 -289.153092)
		(width 0.1143)
		(layer "In13.Cu")
		(net "P5E_CPU1_P2_TX_DN<10>")
	)
	(segment
		(start 122.197114 -278.44115)
		(end 122.227594 -278.45893)
		(width 0.1143)
		(layer "In13.Cu")
		(net "P5E_CPU1_P2_TX_DN<10>")
	)
	(segment
		(start 122.221244 -292.397434)
		(end 122.220228 -292.397942)
		(width 0.1143)
		(layer "In13.Cu")
		(net "P5E_CPU1_P2_TX_DN<10>")
	)
	(segment
		(start 122.220228 -284.298136)
		(end 122.196098 -284.312106)
		(width 0.1143)
		(layer "In13.Cu")
		(net "P5E_CPU1_P2_TX_DN<10>")
	)
	(segment
		(start 122.696986 -270.524224)
		(end 122.694192 -270.525748)
		(width 0.1143)
		(layer "In13.Cu")
		(net "P5E_CPU1_P2_TX_DN<10>")
	)
	(segment
		(start 122.224292 -285.915862)
		(end 122.22353 -285.91637)
		(width 0.1143)
		(layer "In13.Cu")
		(net "P5E_CPU1_P2_TX_DN<10>")
	)
	(segment
		(start 122.224292 -292.395656)
		(end 122.22353 -292.396164)
		(width 0.1143)
		(layer "In13.Cu")
		(net "P5E_CPU1_P2_TX_DN<10>")
	)
	(segment
		(start 122.230388 -291.420296)
		(end 122.266964 -291.441632)
		(width 0.1143)
		(layer "In13.Cu")
		(net "P5E_CPU1_P2_TX_DN<10>")
	)
	(segment
		(start 122.227848 -286.558736)
		(end 122.266964 -286.581596)
		(width 0.1143)
		(layer "In13.Cu")
		(net "P5E_CPU1_P2_TX_DN<10>")
	)
	(segment
		(start 122.227848 -281.698954)
		(end 122.228864 -281.699462)
		(width 0.1143)
		(layer "In13.Cu")
		(net "P5E_CPU1_P2_TX_DN<10>")
	)
	(segment
		(start 122.220228 -285.918148)
		(end 122.196098 -285.932118)
		(width 0.1143)
		(layer "In13.Cu")
		(net "P5E_CPU1_P2_TX_DN<10>")
	)
	(segment
		(start 122.196098 -281.680666)
		(end 122.227086 -281.698446)
		(width 0.1143)
		(layer "In13.Cu")
		(net "P5E_CPU1_P2_TX_DN<10>")
	)
	(segment
		(start 122.736864 -270.500856)
		(end 122.697748 -270.523716)
		(width 0.1143)
		(layer "In13.Cu")
		(net "P5E_CPU1_P2_TX_DN<10>")
	)
	(segment
		(start 122.220228 -292.397942)
		(end 122.196098 -292.411912)
		(width 0.1143)
		(layer "In13.Cu")
		(net "P5E_CPU1_P2_TX_DN<10>")
	)
	(segment
		(start 122.225816 -282.675076)
		(end 122.224292 -282.675838)
		(width 0.1143)
		(layer "In13.Cu")
		(net "P5E_CPU1_P2_TX_DN<10>")
	)
	(segment
		(start 122.228864 -292.393116)
		(end 122.227848 -292.393624)
		(width 0.1143)
		(layer "In13.Cu")
		(net "P5E_CPU1_P2_TX_DN<10>")
	)
	(segment
		(start 122.227848 -292.393624)
		(end 122.227086 -292.394132)
		(width 0.1143)
		(layer "In13.Cu")
		(net "P5E_CPU1_P2_TX_DN<10>")
	)
	(segment
		(start 155.584398 -365.202724)
		(end 158.380938 -366.360964)
		(width 0.14224)
		(layer "In13.Cu")
		(net "P5E_CPU1_P2_TX_DN<10>")
	)
	(segment
		(start 123.06681 -296.209466)
		(end 123.06681 -296.538396)
		(width 0.1143)
		(layer "In13.Cu")
		(net "P5E_CPU1_P2_TX_DN<10>")
	)
	(segment
		(start 122.227848 -282.673806)
		(end 122.227086 -282.674314)
		(width 0.1143)
		(layer "In13.Cu")
		(net "P5E_CPU1_P2_TX_DN<10>")
	)
	(segment
		(start 122.227594 -273.598894)
		(end 122.26671 -273.621754)
		(width 0.1143)
		(layer "In13.Cu")
		(net "P5E_CPU1_P2_TX_DN<10>")
	)
	(segment
		(start 122.196098 -283.300678)
		(end 122.227848 -283.318966)
		(width 0.1143)
		(layer "In13.Cu")
		(net "P5E_CPU1_P2_TX_DN<10>")
	)
	(segment
		(start 122.222006 -285.917132)
		(end 122.221244 -285.91764)
		(width 0.1143)
		(layer "In13.Cu")
		(net "P5E_CPU1_P2_TX_DN<10>")
	)
	(segment
		(start 122.220228 -290.77793)
		(end 122.196098 -290.7919)
		(width 0.1143)
		(layer "In13.Cu")
		(net "P5E_CPU1_P2_TX_DN<10>")
	)
	(segment
		(start 122.264424 -287.512506)
		(end 122.227848 -287.533842)
		(width 0.1143)
		(layer "In13.Cu")
		(net "P5E_CPU1_P2_TX_DN<10>")
	)
	(segment
		(start 122.26671 -272.930874)
		(end 122.227594 -272.953734)
		(width 0.1143)
		(layer "In13.Cu")
		(net "P5E_CPU1_P2_TX_DN<10>")
	)
	(segment
		(start 159.894778 -367.387632)
		(end 160.107884 -367.600738)
		(width 0.14224)
		(layer "In13.Cu")
		(net "P5E_CPU1_P2_TX_DN<10>")
	)
	(segment
		(start 122.221244 -290.777422)
		(end 122.220228 -290.77793)
		(width 0.1143)
		(layer "In13.Cu")
		(net "P5E_CPU1_P2_TX_DN<10>")
	)
	(segment
		(start 122.228864 -284.939486)
		(end 122.230388 -284.940502)
		(width 0.1143)
		(layer "In13.Cu")
		(net "P5E_CPU1_P2_TX_DN<10>")
	)
	(segment
		(start 122.225816 -289.15487)
		(end 122.224292 -289.155632)
		(width 0.1143)
		(layer "In13.Cu")
		(net "P5E_CPU1_P2_TX_DN<10>")
	)
	(segment
		(start 123.113038 -296.926762)
		(end 123.113038 -297.075352)
		(width 0.14224)
		(layer "In13.Cu")
		(net "P5E_CPU1_P2_TX_DN<10>")
	)
	(segment
		(start 122.701304 -295.470834)
		(end 122.703844 -295.472358)
		(width 0.1143)
		(layer "In13.Cu")
		(net "P5E_CPU1_P2_TX_DN<10>")
	)
	(segment
		(start 122.196098 -293.020496)
		(end 122.227086 -293.038276)
		(width 0.1143)
		(layer "In13.Cu")
		(net "P5E_CPU1_P2_TX_DN<10>")
	)
	(segment
		(start 122.231404 -293.040816)
		(end 122.266964 -293.061644)
		(width 0.1143)
		(layer "In13.Cu")
		(net "P5E_CPU1_P2_TX_DN<10>")
	)
	(segment
		(start 122.228864 -289.799268)
		(end 122.230388 -289.800284)
		(width 0.1143)
		(layer "In13.Cu")
		(net "P5E_CPU1_P2_TX_DN<10>")
	)
	(segment
		(start 122.230388 -283.32049)
		(end 122.266964 -283.341826)
		(width 0.1143)
		(layer "In13.Cu")
		(net "P5E_CPU1_P2_TX_DN<10>")
	)
	(segment
		(start 122.26671 -276.170898)
		(end 122.227594 -276.193758)
		(width 0.1143)
		(layer "In13.Cu")
		(net "P5E_CPU1_P2_TX_DN<10>")
	)
	(segment
		(start 122.227848 -290.773612)
		(end 122.227086 -290.77412)
		(width 0.1143)
		(layer "In13.Cu")
		(net "P5E_CPU1_P2_TX_DN<10>")
	)
	(segment
		(start 122.228864 -281.699462)
		(end 122.230388 -281.700478)
		(width 0.1143)
		(layer "In13.Cu")
		(net "P5E_CPU1_P2_TX_DN<10>")
	)
	(segment
		(start 122.221244 -284.297628)
		(end 122.220228 -284.298136)
		(width 0.1143)
		(layer "In13.Cu")
		(net "P5E_CPU1_P2_TX_DN<10>")
	)
	(segment
		(start 122.228864 -294.659304)
		(end 122.230388 -294.66032)
		(width 0.1143)
		(layer "In13.Cu")
		(net "P5E_CPU1_P2_TX_DN<10>")
	)
	(segment
		(start 122.227594 -274.573746)
		(end 122.197114 -274.591526)
		(width 0.1143)
		(layer "In13.Cu")
		(net "P5E_CPU1_P2_TX_DN<10>")
	)
	(segment
		(start 123.113038 -297.075352)
		(end 123.606306 -298.266612)
		(width 0.14224)
		(layer "In13.Cu")
		(net "P5E_CPU1_P2_TX_DN<10>")
	)
	(segment
		(start 122.227848 -284.938978)
		(end 122.228864 -284.939486)
		(width 0.1143)
		(layer "In13.Cu")
		(net "P5E_CPU1_P2_TX_DN<10>")
	)
	(segment
		(start 122.197114 -276.821138)
		(end 122.227594 -276.838918)
		(width 0.1143)
		(layer "In13.Cu")
		(net "P5E_CPU1_P2_TX_DN<10>")
	)
	(segment
		(start 122.980196 -295.956228)
		(end 122.980196 -296.122852)
		(width 0.1143)
		(layer "In13.Cu")
		(net "P5E_CPU1_P2_TX_DN<10>")
	)
	(segment
		(start 133.584696 -311.933844)
		(end 135.481314 -314.771786)
		(width 0.14224)
		(layer "In13.Cu")
		(net "P5E_CPU1_P2_TX_DN<10>")
	)
	(segment
		(start 122.197114 -280.061162)
		(end 122.227594 -280.078942)
		(width 0.1143)
		(layer "In13.Cu")
		(net "P5E_CPU1_P2_TX_DN<10>")
	)
	(segment
		(start 122.266964 -290.750752)
		(end 122.230388 -290.772088)
		(width 0.1143)
		(layer "In13.Cu")
		(net "P5E_CPU1_P2_TX_DN<10>")
	)
	(segment
		(start 122.227086 -292.394132)
		(end 122.225816 -292.394894)
		(width 0.1143)
		(layer "In13.Cu")
		(net "P5E_CPU1_P2_TX_DN<10>")
	)
	(segment
		(start 122.230388 -284.292294)
		(end 122.228864 -284.29331)
		(width 0.1143)
		(layer "In13.Cu")
		(net "P5E_CPU1_P2_TX_DN<10>")
	)
	(segment
		(start 122.227594 -272.953734)
		(end 122.197114 -272.971514)
		(width 0.1143)
		(layer "In13.Cu")
		(net "P5E_CPU1_P2_TX_DN<10>")
	)
	(segment
		(start 122.230388 -292.3921)
		(end 122.228864 -292.393116)
		(width 0.1143)
		(layer "In13.Cu")
		(net "P5E_CPU1_P2_TX_DN<10>")
	)
	(segment
		(start 122.231404 -281.700986)
		(end 122.266964 -281.721814)
		(width 0.1143)
		(layer "In13.Cu")
		(net "P5E_CPU1_P2_TX_DN<10>")
	)
	(segment
		(start 122.196098 -284.92069)
		(end 122.227848 -284.938978)
		(width 0.1143)
		(layer "In13.Cu")
		(net "P5E_CPU1_P2_TX_DN<10>")
	)
	(segment
		(start 122.225816 -284.295088)
		(end 122.224292 -284.29585)
		(width 0.1143)
		(layer "In13.Cu")
		(net "P5E_CPU1_P2_TX_DN<10>")
	)
	(segment
		(start 122.227594 -281.053794)
		(end 122.196098 -281.072082)
		(width 0.1143)
		(layer "In13.Cu")
		(net "P5E_CPU1_P2_TX_DN<10>")
	)
	(segment
		(start 122.22353 -285.91637)
		(end 122.222006 -285.917132)
		(width 0.1143)
		(layer "In13.Cu")
		(net "P5E_CPU1_P2_TX_DN<10>")
	)
	(segment
		(start 122.703844 -295.472358)
		(end 122.705368 -295.473374)
		(width 0.1143)
		(layer "In13.Cu")
		(net "P5E_CPU1_P2_TX_DN<10>")
	)
	(segment
		(start 122.227848 -294.013636)
		(end 122.227086 -294.014144)
		(width 0.1143)
		(layer "In13.Cu")
		(net "P5E_CPU1_P2_TX_DN<10>")
	)
	(segment
		(start 122.665998 -295.450514)
		(end 122.697748 -295.468802)
		(width 0.1143)
		(layer "In13.Cu")
		(net "P5E_CPU1_P2_TX_DN<10>")
	)
	(segment
		(start 122.225816 -292.394894)
		(end 122.224292 -292.395656)
		(width 0.1143)
		(layer "In13.Cu")
		(net "P5E_CPU1_P2_TX_DN<10>")
	)
	(segment
		(start 122.227848 -287.533842)
		(end 122.196098 -287.55213)
		(width 0.1143)
		(layer "In13.Cu")
		(net "P5E_CPU1_P2_TX_DN<10>")
	)
	(segment
		(start 122.228864 -290.773104)
		(end 122.227848 -290.773612)
		(width 0.1143)
		(layer "In13.Cu")
		(net "P5E_CPU1_P2_TX_DN<10>")
	)
	(segment
		(start 122.225816 -285.9151)
		(end 122.224292 -285.915862)
		(width 0.1143)
		(layer "In13.Cu")
		(net "P5E_CPU1_P2_TX_DN<10>")
	)
	(segment
		(start 122.230388 -289.800284)
		(end 122.231404 -289.800792)
		(width 0.1143)
		(layer "In13.Cu")
		(net "P5E_CPU1_P2_TX_DN<10>")
	)
	(segment
		(start 122.227594 -276.193758)
		(end 122.197114 -276.211538)
		(width 0.1143)
		(layer "In13.Cu")
		(net "P5E_CPU1_P2_TX_DN<10>")
	)
	(segment
		(start 122.228864 -293.039292)
		(end 122.230388 -293.040308)
		(width 0.1143)
		(layer "In13.Cu")
		(net "P5E_CPU1_P2_TX_DN<10>")
	)
	(segment
		(start 122.227848 -294.658796)
		(end 122.228864 -294.659304)
		(width 0.1143)
		(layer "In13.Cu")
		(net "P5E_CPU1_P2_TX_DN<10>")
	)
	(segment
		(start 122.69343 -270.526256)
		(end 122.691398 -270.527272)
		(width 0.1143)
		(layer "In13.Cu")
		(net "P5E_CPU1_P2_TX_DN<10>")
	)
	(segment
		(start 122.227086 -293.038276)
		(end 122.227848 -293.038784)
		(width 0.1143)
		(layer "In13.Cu")
		(net "P5E_CPU1_P2_TX_DN<10>")
	)
	(segment
		(start 122.266964 -292.370764)
		(end 122.230388 -292.3921)
		(width 0.1143)
		(layer "In13.Cu")
		(net "P5E_CPU1_P2_TX_DN<10>")
	)
	(segment
		(start 122.224292 -282.675838)
		(end 122.22353 -282.676346)
		(width 0.1143)
		(layer "In13.Cu")
		(net "P5E_CPU1_P2_TX_DN<10>")
	)
	(segment
		(start 161.935414 -371.136926)
		(end 161.935414 -373.605298)
		(width 0.14224)
		(layer "In13.Cu")
		(net "P5E_CPU1_P2_TX_DN<10>")
	)
	(segment
		(start 122.227594 -279.433782)
		(end 122.197114 -279.451562)
		(width 0.1143)
		(layer "In13.Cu")
		(net "P5E_CPU1_P2_TX_DN<10>")
	)
	(segment
		(start 122.228864 -283.319474)
		(end 122.230388 -283.32049)
		(width 0.1143)
		(layer "In13.Cu")
		(net "P5E_CPU1_P2_TX_DN<10>")
	)
	(segment
		(start 122.22353 -284.296358)
		(end 122.222006 -284.29712)
		(width 0.1143)
		(layer "In13.Cu")
		(net "P5E_CPU1_P2_TX_DN<10>")
	)
	(segment
		(start 122.230388 -293.040308)
		(end 122.231404 -293.040816)
		(width 0.1143)
		(layer "In13.Cu")
		(net "P5E_CPU1_P2_TX_DN<10>")
	)
	(segment
		(start 122.228864 -285.913322)
		(end 122.227848 -285.91383)
		(width 0.1143)
		(layer "In13.Cu")
		(net "P5E_CPU1_P2_TX_DN<10>")
	)
	(segment
		(start 122.227848 -283.318966)
		(end 122.228864 -283.319474)
		(width 0.1143)
		(layer "In13.Cu")
		(net "P5E_CPU1_P2_TX_DN<10>")
	)
	(segment
		(start 122.691398 -270.527272)
		(end 122.665998 -270.542004)
		(width 0.1143)
		(layer "In13.Cu")
		(net "P5E_CPU1_P2_TX_DN<10>")
	)
	(segment
		(start 122.510296 -295.146222)
		(end 122.510042 -295.146222)
		(width 0.1143)
		(layer "In13.Cu")
		(net "P5E_CPU1_P2_TX_DN<10>")
	)
	(segment
		(start 122.224292 -284.29585)
		(end 122.22353 -284.296358)
		(width 0.1143)
		(layer "In13.Cu")
		(net "P5E_CPU1_P2_TX_DN<10>")
	)
	(segment
		(start 122.26671 -279.410922)
		(end 122.227594 -279.433782)
		(width 0.1143)
		(layer "In13.Cu")
		(net "P5E_CPU1_P2_TX_DN<10>")
	)
	(segment
		(start 122.26671 -281.030934)
		(end 122.227594 -281.053794)
		(width 0.1143)
		(layer "In13.Cu")
		(net "P5E_CPU1_P2_TX_DN<10>")
	)
	(segment
		(start 122.227086 -294.014144)
		(end 122.225816 -294.014906)
		(width 0.1143)
		(layer "In13.Cu")
		(net "P5E_CPU1_P2_TX_DN<10>")
	)
	(segment
		(start 122.225816 -294.014906)
		(end 122.196098 -294.031924)
		(width 0.1143)
		(layer "In13.Cu")
		(net "P5E_CPU1_P2_TX_DN<10>")
	)
	(segment
		(start 139.171426 -321.674744)
		(end 139.704572 -322.961508)
		(width 0.14224)
		(layer "In13.Cu")
		(net "P5E_CPU1_P2_TX_DN<10>")
	)
	(segment
		(start 123.056904 -270.03629)
		(end 122.9741 -270.119094)
		(width 0.1143)
		(layer "In13.Cu")
		(net "P5E_CPU1_P2_TX_DN<10>")
	)
	(segment
		(start 122.22353 -282.676346)
		(end 122.222006 -282.677108)
		(width 0.1143)
		(layer "In13.Cu")
		(net "P5E_CPU1_P2_TX_DN<10>")
	)
	(segment
		(start 122.26671 -277.79091)
		(end 122.227594 -277.81377)
		(width 0.1143)
		(layer "In13.Cu")
		(net "P5E_CPU1_P2_TX_DN<10>")
	)
	(segment
		(start 122.225816 -290.774882)
		(end 122.224292 -290.775644)
		(width 0.1143)
		(layer "In13.Cu")
		(net "P5E_CPU1_P2_TX_DN<10>")
	)
	(segment
		(start 122.196098 -294.640508)
		(end 122.227086 -294.658288)
		(width 0.1143)
		(layer "In13.Cu")
		(net "P5E_CPU1_P2_TX_DN<10>")
	)
	(segment
		(start 122.227086 -285.914338)
		(end 122.225816 -285.9151)
		(width 0.1143)
		(layer "In13.Cu")
		(net "P5E_CPU1_P2_TX_DN<10>")
	)
	(segment
		(start 122.228864 -291.41928)
		(end 122.230388 -291.420296)
		(width 0.1143)
		(layer "In13.Cu")
		(net "P5E_CPU1_P2_TX_DN<10>")
	)
	(segment
		(start 122.227848 -293.038784)
		(end 122.228864 -293.039292)
		(width 0.1143)
		(layer "In13.Cu")
		(net "P5E_CPU1_P2_TX_DN<10>")
	)
	(segment
		(start 135.481314 -314.771786)
		(end 139.171426 -321.674744)
		(width 0.14224)
		(layer "In13.Cu")
		(net "P5E_CPU1_P2_TX_DN<10>")
	)
	(segment
		(start 151.60879 -361.467146)
		(end 154.08783 -364.202726)
		(width 0.14224)
		(layer "In13.Cu")
		(net "P5E_CPU1_P2_TX_DN<10>")
	)
	(segment
		(start 122.227848 -288.178748)
		(end 122.266964 -288.201608)
		(width 0.1143)
		(layer "In13.Cu")
		(net "P5E_CPU1_P2_TX_DN<10>")
	)
	(segment
		(start 123.11253 -296.584116)
		(end 123.11253 -296.612564)
		(width 0.1143)
		(layer "In13.Cu")
		(net "P5E_CPU1_P2_TX_DN<10>")
	)
	(segment
		(start 122.196098 -291.400484)
		(end 122.227848 -291.418772)
		(width 0.1143)
		(layer "In13.Cu")
		(net "P5E_CPU1_P2_TX_DN<10>")
	)
	(segment
		(start 122.231404 -289.800792)
		(end 122.266964 -289.82162)
		(width 0.1143)
		(layer "In13.Cu")
		(net "P5E_CPU1_P2_TX_DN<10>")
	)
	(segment
		(start 122.227086 -284.294326)
		(end 122.225816 -284.295088)
		(width 0.1143)
		(layer "In13.Cu")
		(net "P5E_CPU1_P2_TX_DN<10>")
	)
	(segment
		(start 123.11253 -296.926254)
		(end 123.113038 -296.926762)
		(width 0.14224)
		(layer "In13.Cu")
		(net "P5E_CPU1_P2_TX_DN<10>")
	)
	(segment
		(start 122.22353 -292.396164)
		(end 122.222006 -292.396926)
		(width 0.1143)
		(layer "In13.Cu")
		(net "P5E_CPU1_P2_TX_DN<10>")
	)
	(segment
		(start 122.197114 -273.581114)
		(end 122.227594 -273.598894)
		(width 0.1143)
		(layer "In13.Cu")
		(net "P5E_CPU1_P2_TX_DN<10>")
	)
	(segment
		(start 122.227594 -277.81377)
		(end 122.197114 -277.83155)
		(width 0.1143)
		(layer "In13.Cu")
		(net "P5E_CPU1_P2_TX_DN<10>")
	)
	(segment
		(start 122.228864 -284.29331)
		(end 122.227848 -284.293818)
		(width 0.1143)
		(layer "In13.Cu")
		(net "P5E_CPU1_P2_TX_DN<10>")
	)
	(segment
		(start 122.266964 -284.270958)
		(end 122.230388 -284.292294)
		(width 0.1143)
		(layer "In13.Cu")
		(net "P5E_CPU1_P2_TX_DN<10>")
	)
	(segment
		(start 122.221244 -289.15741)
		(end 122.220228 -289.157918)
		(width 0.1143)
		(layer "In13.Cu")
		(net "P5E_CPU1_P2_TX_DN<10>")
	)
	(segment
		(start 122.230388 -282.672282)
		(end 122.228864 -282.673298)
		(width 0.1143)
		(layer "In13.Cu")
		(net "P5E_CPU1_P2_TX_DN<10>")
	)
	(segment
		(start 161.699702 -370.576094)
		(end 161.868358 -370.8781)
		(width 0.14224)
		(layer "In13.Cu")
		(net "P5E_CPU1_P2_TX_DN<10>")
	)
	(segment
		(start 122.227848 -289.1536)
		(end 122.227086 -289.154108)
		(width 0.1143)
		(layer "In13.Cu")
		(net "P5E_CPU1_P2_TX_DN<10>")
	)
	(segment
		(start 139.704572 -322.961508)
		(end 144.87906 -348.976696)
		(width 0.14224)
		(layer "In13.Cu")
		(net "P5E_CPU1_P2_TX_DN<10>")
	)
	(segment
		(start 122.222006 -282.677108)
		(end 122.221244 -282.677616)
		(width 0.1143)
		(layer "In13.Cu")
		(net "P5E_CPU1_P2_TX_DN<10>")
	)
	(segment
		(start 122.227086 -290.77412)
		(end 122.225816 -290.774882)
		(width 0.1143)
		(layer "In13.Cu")
		(net "P5E_CPU1_P2_TX_DN<10>")
	)
	(segment
		(start 122.222006 -292.396926)
		(end 122.221244 -292.397434)
		(width 0.1143)
		(layer "In13.Cu")
		(net "P5E_CPU1_P2_TX_DN<10>")
	)
	(segment
		(start 122.697748 -270.523716)
		(end 122.696986 -270.524224)
		(width 0.1143)
		(layer "In13.Cu")
		(net "P5E_CPU1_P2_TX_DN<10>")
	)
	(segment
		(start 161.982658 -373.719344)
		(end 162.226244 -373.96293)
		(width 0.14224)
		(layer "In13.Cu")
		(net "P5E_CPU1_P2_TX_DN<10>")
	)
	(segment
		(start 122.697748 -295.468802)
		(end 122.698764 -295.46931)
		(width 0.1143)
		(layer "In13.Cu")
		(net "P5E_CPU1_P2_TX_DN<10>")
	)
	(segment
		(start 122.227848 -284.293818)
		(end 122.227086 -284.294326)
		(width 0.1143)
		(layer "In13.Cu")
		(net "P5E_CPU1_P2_TX_DN<10>")
	)
	(segment
		(start 122.698764 -295.46931)
		(end 122.700288 -295.470326)
		(width 0.1143)
		(layer "In13.Cu")
		(net "P5E_CPU1_P2_TX_DN<10>")
	)
	(segment
		(start 122.266964 -285.89097)
		(end 122.230388 -285.912306)
		(width 0.1143)
		(layer "In13.Cu")
		(net "P5E_CPU1_P2_TX_DN<10>")
	)
	(segment
		(start 122.227086 -289.154108)
		(end 122.225816 -289.15487)
		(width 0.1143)
		(layer "In13.Cu")
		(net "P5E_CPU1_P2_TX_DN<10>")
	)
	(segment
		(start 122.19432 -288.15919)
		(end 122.227848 -288.178748)
		(width 0.1143)
		(layer "In13.Cu")
		(net "P5E_CPU1_P2_TX_DN<10>")
	)
	(segment
		(start 122.227086 -282.674314)
		(end 122.225816 -282.675076)
		(width 0.1143)
		(layer "In13.Cu")
		(net "P5E_CPU1_P2_TX_DN<10>")
	)
	(segment
		(start 122.197114 -271.961102)
		(end 122.227594 -271.978882)
		(width 0.1143)
		(layer "In13.Cu")
		(net "P5E_CPU1_P2_TX_DN<10>")
	)
	(segment
		(start 122.26671 -271.310862)
		(end 122.227594 -271.333722)
		(width 0.1143)
		(layer "In13.Cu")
		(net "P5E_CPU1_P2_TX_DN<10>")
	)
	(segment
		(start 122.227848 -291.418772)
		(end 122.228864 -291.41928)
		(width 0.1143)
		(layer "In13.Cu")
		(net "P5E_CPU1_P2_TX_DN<10>")
	)
	(segment
		(start 154.08783 -364.202726)
		(end 155.584398 -365.202724)
		(width 0.14224)
		(layer "In13.Cu")
		(net "P5E_CPU1_P2_TX_DN<10>")
	)
	(segment
		(start 122.224292 -290.775644)
		(end 122.22353 -290.776152)
		(width 0.1143)
		(layer "In13.Cu")
		(net "P5E_CPU1_P2_TX_DN<10>")
	)
	(segment
		(start 122.266964 -289.13074)
		(end 122.230388 -289.152076)
		(width 0.1143)
		(layer "In13.Cu")
		(net "P5E_CPU1_P2_TX_DN<10>")
	)
	(segment
		(start 122.694192 -270.525748)
		(end 122.69343 -270.526256)
		(width 0.1143)
		(layer "In13.Cu")
		(net "P5E_CPU1_P2_TX_DN<10>")
	)
	(segment
		(start 122.221244 -282.677616)
		(end 122.220228 -282.678124)
		(width 0.1143)
		(layer "In13.Cu")
		(net "P5E_CPU1_P2_TX_DN<10>")
	)
	(segment
		(start 122.220228 -282.678124)
		(end 122.196098 -282.692094)
		(width 0.1143)
		(layer "In13.Cu")
		(net "P5E_CPU1_P2_TX_DN<10>")
	)
	(segment
		(start 123.354846 -270.03629)
		(end 123.056904 -270.03629)
		(width 0.1143)
		(layer "In13.Cu")
		(net "P5E_CPU1_P2_TX_DN<10>")
	)
	(segment
		(start 122.227594 -278.45893)
		(end 122.26671 -278.48179)
		(width 0.1143)
		(layer "In13.Cu")
		(net "P5E_CPU1_P2_TX_DN<10>")
	)
	(segment
		(start 122.228864 -282.673298)
		(end 122.227848 -282.673806)
		(width 0.1143)
		(layer "In13.Cu")
		(net "P5E_CPU1_P2_TX_DN<10>")
	)
	(segment
		(start 122.700288 -295.470326)
		(end 122.701304 -295.470834)
		(width 0.1143)
		(layer "In13.Cu")
		(net "P5E_CPU1_P2_TX_DN<10>")
	)
	(arc
		(start 122.197114 -276.211538)
		(mid 122.040137 -276.516338)
		(end 122.197114 -276.821138)
		(width 0.1143)
		(layer "In13.Cu")
		(net "P5E_CPU1_P2_TX_DN<10>")
	)
	(arc
		(start 122.266964 -286.581596)
		(mid 122.445777 -286.783946)
		(end 122.510296 -287.046162)
		(width 0.1143)
		(layer "In13.Cu")
		(net "P5E_CPU1_P2_TX_DN<10>")
	)
	(arc
		(start 160.107884 -367.600738)
		(mid 160.20402 -367.744661)
		(end 160.237678 -367.914428)
		(width 0.14224)
		(layer "In13.Cu")
		(net "P5E_CPU1_P2_TX_DN<10>")
	)
	(arc
		(start 122.510042 -295.146222)
		(mid 122.551297 -295.317193)
		(end 122.665998 -295.450514)
		(width 0.1143)
		(layer "In13.Cu")
		(net "P5E_CPU1_P2_TX_DN<10>")
	)
	(arc
		(start 122.196098 -290.7919)
		(mid 122.04017 -291.096192)
		(end 122.196098 -291.400484)
		(width 0.1143)
		(layer "In13.Cu")
		(net "P5E_CPU1_P2_TX_DN<10>")
	)
	(arc
		(start 122.196098 -292.411912)
		(mid 122.04017 -292.716204)
		(end 122.196098 -293.020496)
		(width 0.1143)
		(layer "In13.Cu")
		(net "P5E_CPU1_P2_TX_DN<10>")
	)
	(arc
		(start 122.196098 -289.171888)
		(mid 122.04017 -289.47618)
		(end 122.196098 -289.780472)
		(width 0.1143)
		(layer "In13.Cu")
		(net "P5E_CPU1_P2_TX_DN<10>")
	)
	(arc
		(start 122.196098 -282.692094)
		(mid 122.04017 -282.996386)
		(end 122.196098 -283.300678)
		(width 0.1143)
		(layer "In13.Cu")
		(net "P5E_CPU1_P2_TX_DN<10>")
	)
	(arc
		(start 122.510042 -270.846296)
		(mid 122.445527 -271.108515)
		(end 122.26671 -271.310862)
		(width 0.1143)
		(layer "In13.Cu")
		(net "P5E_CPU1_P2_TX_DN<10>")
	)
	(arc
		(start 122.665998 -270.542004)
		(mid 122.551322 -270.675338)
		(end 122.510042 -270.846296)
		(width 0.1143)
		(layer "In13.Cu")
		(net "P5E_CPU1_P2_TX_DN<10>")
	)
	(arc
		(start 122.9741 -270.119094)
		(mid 122.972312 -270.130543)
		(end 122.97029 -270.141954)
		(width 0.1143)
		(layer "In13.Cu")
		(net "P5E_CPU1_P2_TX_DN<10>")
	)
	(arc
		(start 122.196098 -284.312106)
		(mid 122.04017 -284.616398)
		(end 122.196098 -284.92069)
		(width 0.1143)
		(layer "In13.Cu")
		(net "P5E_CPU1_P2_TX_DN<10>")
	)
	(arc
		(start 122.26671 -272.001742)
		(mid 122.510037 -272.466308)
		(end 122.26671 -272.930874)
		(width 0.1143)
		(layer "In13.Cu")
		(net "P5E_CPU1_P2_TX_DN<10>")
	)
	(arc
		(start 161.868358 -370.8781)
		(mid 161.918425 -371.003224)
		(end 161.935414 -371.136926)
		(width 0.14224)
		(layer "In13.Cu")
		(net "P5E_CPU1_P2_TX_DN<10>")
	)
	(arc
		(start 122.266964 -294.681656)
		(mid 122.445777 -294.884006)
		(end 122.510296 -295.146222)
		(width 0.1143)
		(layer "In13.Cu")
		(net "P5E_CPU1_P2_TX_DN<10>")
	)
	(arc
		(start 122.266964 -289.82162)
		(mid 122.510291 -290.286186)
		(end 122.266964 -290.750752)
		(width 0.1143)
		(layer "In13.Cu")
		(net "P5E_CPU1_P2_TX_DN<10>")
	)
	(arc
		(start 159.796988 -367.307368)
		(mid 159.847859 -367.345093)
		(end 159.894778 -367.387632)
		(width 0.14224)
		(layer "In13.Cu")
		(net "P5E_CPU1_P2_TX_DN<10>")
	)
	(arc
		(start 122.26671 -278.48179)
		(mid 122.510037 -278.946356)
		(end 122.26671 -279.410922)
		(width 0.1143)
		(layer "In13.Cu")
		(net "P5E_CPU1_P2_TX_DN<10>")
	)
	(arc
		(start 122.040142 -287.856422)
		(mid 122.080904 -288.026306)
		(end 122.19432 -288.15919)
		(width 0.1143)
		(layer "In13.Cu")
		(net "P5E_CPU1_P2_TX_DN<10>")
	)
	(arc
		(start 160.237678 -369.390422)
		(mid 160.27466 -369.561261)
		(end 160.37052 -369.707414)
		(width 0.14224)
		(layer "In13.Cu")
		(net "P5E_CPU1_P2_TX_DN<10>")
	)
	(arc
		(start 122.266964 -281.721814)
		(mid 122.510291 -282.18638)
		(end 122.266964 -282.650946)
		(width 0.1143)
		(layer "In13.Cu")
		(net "P5E_CPU1_P2_TX_DN<10>")
	)
	(arc
		(start 160.37052 -369.707414)
		(mid 160.78641 -370.04274)
		(end 161.264092 -370.281962)
		(width 0.14224)
		(layer "In13.Cu")
		(net "P5E_CPU1_P2_TX_DN<10>")
	)
	(arc
		(start 122.510296 -287.046162)
		(mid 122.44506 -287.309753)
		(end 122.264424 -287.512506)
		(width 0.1143)
		(layer "In13.Cu")
		(net "P5E_CPU1_P2_TX_DN<10>")
	)
	(arc
		(start 122.266964 -291.441632)
		(mid 122.510291 -291.906198)
		(end 122.266964 -292.370764)
		(width 0.1143)
		(layer "In13.Cu")
		(net "P5E_CPU1_P2_TX_DN<10>")
	)
	(arc
		(start 122.196098 -294.031924)
		(mid 122.04017 -294.336216)
		(end 122.196098 -294.640508)
		(width 0.1143)
		(layer "In13.Cu")
		(net "P5E_CPU1_P2_TX_DN<10>")
	)
	(arc
		(start 122.26671 -275.241766)
		(mid 122.510037 -275.706332)
		(end 122.26671 -276.170898)
		(width 0.1143)
		(layer "In13.Cu")
		(net "P5E_CPU1_P2_TX_DN<10>")
	)
	(arc
		(start 122.26671 -276.861778)
		(mid 122.510037 -277.326344)
		(end 122.26671 -277.79091)
		(width 0.1143)
		(layer "In13.Cu")
		(net "P5E_CPU1_P2_TX_DN<10>")
	)
	(arc
		(start 161.264092 -370.281962)
		(mid 161.372515 -370.324744)
		(end 161.47923 -370.371624)
		(width 0.14224)
		(layer "In13.Cu")
		(net "P5E_CPU1_P2_TX_DN<10>")
	)
	(arc
		(start 122.97029 -270.141954)
		(mid 122.888857 -270.344352)
		(end 122.736864 -270.500856)
		(width 0.1143)
		(layer "In13.Cu")
		(net "P5E_CPU1_P2_TX_DN<10>")
	)
	(arc
		(start 122.196098 -285.932118)
		(mid 122.081422 -286.065452)
		(end 122.040142 -286.23641)
		(width 0.1143)
		(layer "In13.Cu")
		(net "P5E_CPU1_P2_TX_DN<10>")
	)
	(arc
		(start 122.736864 -295.491662)
		(mid 122.915677 -295.694012)
		(end 122.980196 -295.956228)
		(width 0.1143)
		(layer "In13.Cu")
		(net "P5E_CPU1_P2_TX_DN<10>")
	)
	(arc
		(start 122.197114 -277.83155)
		(mid 122.040137 -278.13635)
		(end 122.197114 -278.44115)
		(width 0.1143)
		(layer "In13.Cu")
		(net "P5E_CPU1_P2_TX_DN<10>")
	)
	(arc
		(start 161.935414 -373.605298)
		(mid 161.947691 -373.667021)
		(end 161.982658 -373.719344)
		(width 0.14224)
		(layer "In13.Cu")
		(net "P5E_CPU1_P2_TX_DN<10>")
	)
	(arc
		(start 122.197114 -271.351502)
		(mid 122.040137 -271.656302)
		(end 122.197114 -271.961102)
		(width 0.1143)
		(layer "In13.Cu")
		(net "P5E_CPU1_P2_TX_DN<10>")
	)
	(arc
		(start 122.197114 -272.971514)
		(mid 122.040137 -273.276314)
		(end 122.197114 -273.581114)
		(width 0.1143)
		(layer "In13.Cu")
		(net "P5E_CPU1_P2_TX_DN<10>")
	)
	(arc
		(start 122.196098 -287.55213)
		(mid 122.081422 -287.685464)
		(end 122.040142 -287.856422)
		(width 0.1143)
		(layer "In13.Cu")
		(net "P5E_CPU1_P2_TX_DN<10>")
	)
	(arc
		(start 122.040142 -286.23641)
		(mid 122.080904 -286.406294)
		(end 122.19432 -286.539178)
		(width 0.1143)
		(layer "In13.Cu")
		(net "P5E_CPU1_P2_TX_DN<10>")
	)
	(arc
		(start 122.266964 -293.061644)
		(mid 122.510291 -293.52621)
		(end 122.266964 -293.990776)
		(width 0.1143)
		(layer "In13.Cu")
		(net "P5E_CPU1_P2_TX_DN<10>")
	)
	(arc
		(start 161.47923 -370.371624)
		(mid 161.605675 -370.456388)
		(end 161.699702 -370.576094)
		(width 0.14224)
		(layer "In13.Cu")
		(net "P5E_CPU1_P2_TX_DN<10>")
	)
	(arc
		(start 122.197114 -279.451562)
		(mid 122.040137 -279.756362)
		(end 122.197114 -280.061162)
		(width 0.1143)
		(layer "In13.Cu")
		(net "P5E_CPU1_P2_TX_DN<10>")
	)
	(arc
		(start 122.197114 -274.591526)
		(mid 122.040137 -274.896326)
		(end 122.197114 -275.201126)
		(width 0.1143)
		(layer "In13.Cu")
		(net "P5E_CPU1_P2_TX_DN<10>")
	)
	(arc
		(start 122.266964 -283.341826)
		(mid 122.510291 -283.806392)
		(end 122.266964 -284.270958)
		(width 0.1143)
		(layer "In13.Cu")
		(net "P5E_CPU1_P2_TX_DN<10>")
	)
	(arc
		(start 122.266964 -284.961838)
		(mid 122.510291 -285.426404)
		(end 122.266964 -285.89097)
		(width 0.1143)
		(layer "In13.Cu")
		(net "P5E_CPU1_P2_TX_DN<10>")
	)
	(arc
		(start 122.26671 -280.101802)
		(mid 122.510037 -280.566368)
		(end 122.26671 -281.030934)
		(width 0.1143)
		(layer "In13.Cu")
		(net "P5E_CPU1_P2_TX_DN<10>")
	)
	(arc
		(start 122.266964 -288.201608)
		(mid 122.510291 -288.666174)
		(end 122.266964 -289.13074)
		(width 0.1143)
		(layer "In13.Cu")
		(net "P5E_CPU1_P2_TX_DN<10>")
	)
	(arc
		(start 122.196098 -281.072082)
		(mid 122.04017 -281.376374)
		(end 122.196098 -281.680666)
		(width 0.1143)
		(layer "In13.Cu")
		(net "P5E_CPU1_P2_TX_DN<10>")
	)
	(arc
		(start 122.26671 -273.621754)
		(mid 122.510037 -274.08632)
		(end 122.26671 -274.550886)
		(width 0.1143)
		(layer "In13.Cu")
		(net "P5E_CPU1_P2_TX_DN<10>")
	)
	(segment
		(start 141.328902 -381.77597)
		(end 142.032482 -381.77597)
		(width 0.12954)
		(layer "F.Cu")
		(net "P5E_CPU1_P2_TX_DN<0>")
	)
	(segment
		(start 114.897916 -268.960346)
		(end 115.364768 -269.226284)
		(width 0.12954)
		(layer "F.Cu")
		(net "P5E_CPU1_P2_TX_DN<0>")
	)
	(segment
		(start 141.058392 -381.50546)
		(end 141.328902 -381.77597)
		(width 0.12954)
		(layer "F.Cu")
		(net "P5E_CPU1_P2_TX_DN<0>")
	)
	(segment
		(start 142.032482 -381.77597)
		(end 142.328392 -381.48006)
		(width 0.12954)
		(layer "F.Cu")
		(net "P5E_CPU1_P2_TX_DN<0>")
	)
	(segment
		(start 140.036042 -370.552472)
		(end 140.036042 -370.979192)
		(width 0.14224)
		(layer "In13.Cu")
		(net "P5E_CPU1_P2_TX_DN<0>")
	)
	(segment
		(start 114.207544 -270.541242)
		(end 114.20602 -270.542004)
		(width 0.1143)
		(layer "In13.Cu")
		(net "P5E_CPU1_P2_TX_DN<0>")
	)
	(segment
		(start 114.239294 -270.5227)
		(end 114.23777 -270.523716)
		(width 0.1143)
		(layer "In13.Cu")
		(net "P5E_CPU1_P2_TX_DN<0>")
	)
	(segment
		(start 115.508786 -303.131474)
		(end 116.704618 -305.12639)
		(width 0.14224)
		(layer "In13.Cu")
		(net "P5E_CPU1_P2_TX_DN<0>")
	)
	(segment
		(start 115.066826 -269.226284)
		(end 114.984022 -269.309088)
		(width 0.1143)
		(layer "In13.Cu")
		(net "P5E_CPU1_P2_TX_DN<0>")
	)
	(segment
		(start 139.898882 -366.137952)
		(end 139.898882 -367.859564)
		(width 0.14224)
		(layer "In13.Cu")
		(net "P5E_CPU1_P2_TX_DN<0>")
	)
	(segment
		(start 113.752376 -271.342612)
		(end 113.133124 -271.961864)
		(width 0.1143)
		(layer "In13.Cu")
		(net "P5E_CPU1_P2_TX_DN<0>")
	)
	(segment
		(start 112.983518 -295.225724)
		(end 113.535968 -298.367196)
		(width 0.14224)
		(layer "In13.Cu")
		(net "P5E_CPU1_P2_TX_DN<0>")
	)
	(segment
		(start 139.898882 -371.543072)
		(end 140.036042 -371.680232)
		(width 0.14224)
		(layer "In13.Cu")
		(net "P5E_CPU1_P2_TX_DN<0>")
	)
	(segment
		(start 139.898882 -371.116352)
		(end 139.898882 -371.543072)
		(width 0.14224)
		(layer "In13.Cu")
		(net "P5E_CPU1_P2_TX_DN<0>")
	)
	(segment
		(start 113.133124 -272.025872)
		(end 113.113058 -272.045938)
		(width 0.1143)
		(layer "In13.Cu")
		(net "P5E_CPU1_P2_TX_DN<0>")
	)
	(segment
		(start 139.898882 -367.859564)
		(end 140.036042 -367.996724)
		(width 0.14224)
		(layer "In13.Cu")
		(net "P5E_CPU1_P2_TX_DN<0>")
	)
	(segment
		(start 139.898882 -369.97513)
		(end 139.898882 -370.415312)
		(width 0.14224)
		(layer "In13.Cu")
		(net "P5E_CPU1_P2_TX_DN<0>")
	)
	(segment
		(start 114.708178 -269.713456)
		(end 114.705384 -269.71498)
		(width 0.1143)
		(layer "In13.Cu")
		(net "P5E_CPU1_P2_TX_DN<0>")
	)
	(segment
		(start 113.113058 -272.045938)
		(end 113.113312 -272.045938)
		(width 0.14224)
		(layer "In13.Cu")
		(net "P5E_CPU1_P2_TX_DN<0>")
	)
	(segment
		(start 114.24285 -270.520668)
		(end 114.239294 -270.5227)
		(width 0.1143)
		(layer "In13.Cu")
		(net "P5E_CPU1_P2_TX_DN<0>")
	)
	(segment
		(start 135.919464 -352.957384)
		(end 139.881356 -366.01908)
		(width 0.14224)
		(layer "In13.Cu")
		(net "P5E_CPU1_P2_TX_DN<0>")
	)
	(segment
		(start 130.481578 -325.621396)
		(end 135.919464 -352.957384)
		(width 0.14224)
		(layer "In13.Cu")
		(net "P5E_CPU1_P2_TX_DN<0>")
	)
	(segment
		(start 115.364768 -269.226284)
		(end 115.066826 -269.226284)
		(width 0.1143)
		(layer "In13.Cu")
		(net "P5E_CPU1_P2_TX_DN<0>")
	)
	(segment
		(start 113.806732 -271.310862)
		(end 113.752376 -271.342612)
		(width 0.1143)
		(layer "In13.Cu")
		(net "P5E_CPU1_P2_TX_DN<0>")
	)
	(segment
		(start 140.767562 -381.79629)
		(end 141.058392 -381.50546)
		(width 0.14224)
		(layer "In13.Cu")
		(net "P5E_CPU1_P2_TX_DN<0>")
	)
	(segment
		(start 139.898882 -368.560604)
		(end 139.898882 -369.27409)
		(width 0.14224)
		(layer "In13.Cu")
		(net "P5E_CPU1_P2_TX_DN<0>")
	)
	(segment
		(start 113.113312 -272.045938)
		(end 112.983518 -272.17624)
		(width 0.14224)
		(layer "In13.Cu")
		(net "P5E_CPU1_P2_TX_DN<0>")
	)
	(segment
		(start 126.731268 -318.643762)
		(end 130.481578 -325.621396)
		(width 0.14224)
		(layer "In13.Cu")
		(net "P5E_CPU1_P2_TX_DN<0>")
	)
	(segment
		(start 139.898882 -369.27409)
		(end 140.036042 -369.41125)
		(width 0.14224)
		(layer "In13.Cu")
		(net "P5E_CPU1_P2_TX_DN<0>")
	)
	(segment
		(start 140.036042 -371.680232)
		(end 140.036042 -372.106952)
		(width 0.14224)
		(layer "In13.Cu")
		(net "P5E_CPU1_P2_TX_DN<0>")
	)
	(segment
		(start 114.243866 -270.52016)
		(end 114.24285 -270.520668)
		(width 0.1143)
		(layer "In13.Cu")
		(net "P5E_CPU1_P2_TX_DN<0>")
	)
	(segment
		(start 140.036042 -369.41125)
		(end 140.036042 -369.83797)
		(width 0.14224)
		(layer "In13.Cu")
		(net "P5E_CPU1_P2_TX_DN<0>")
	)
	(segment
		(start 114.746786 -269.69085)
		(end 114.708178 -269.713456)
		(width 0.1143)
		(layer "In13.Cu")
		(net "P5E_CPU1_P2_TX_DN<0>")
	)
	(segment
		(start 139.898882 -372.244112)
		(end 139.898882 -381.608838)
		(width 0.14224)
		(layer "In13.Cu")
		(net "P5E_CPU1_P2_TX_DN<0>")
	)
	(segment
		(start 140.036042 -370.979192)
		(end 139.898882 -371.116352)
		(width 0.14224)
		(layer "In13.Cu")
		(net "P5E_CPU1_P2_TX_DN<0>")
	)
	(segment
		(start 113.133124 -271.961864)
		(end 113.133124 -272.025872)
		(width 0.1143)
		(layer "In13.Cu")
		(net "P5E_CPU1_P2_TX_DN<0>")
	)
	(segment
		(start 112.983518 -272.17624)
		(end 112.90681 -272.562828)
		(width 0.14224)
		(layer "In13.Cu")
		(net "P5E_CPU1_P2_TX_DN<0>")
	)
	(segment
		(start 113.535968 -298.367196)
		(end 115.508786 -303.131474)
		(width 0.14224)
		(layer "In13.Cu")
		(net "P5E_CPU1_P2_TX_DN<0>")
	)
	(segment
		(start 112.90681 -272.562828)
		(end 112.983518 -295.225724)
		(width 0.14224)
		(layer "In13.Cu")
		(net "P5E_CPU1_P2_TX_DN<0>")
	)
	(segment
		(start 140.036042 -367.996724)
		(end 140.036042 -368.423444)
		(width 0.14224)
		(layer "In13.Cu")
		(net "P5E_CPU1_P2_TX_DN<0>")
	)
	(segment
		(start 114.23777 -270.523716)
		(end 114.207544 -270.541242)
		(width 0.1143)
		(layer "In13.Cu")
		(net "P5E_CPU1_P2_TX_DN<0>")
	)
	(segment
		(start 140.086334 -381.79629)
		(end 140.767562 -381.79629)
		(width 0.14224)
		(layer "In13.Cu")
		(net "P5E_CPU1_P2_TX_DN<0>")
	)
	(segment
		(start 140.036042 -372.106952)
		(end 139.898882 -372.244112)
		(width 0.14224)
		(layer "In13.Cu")
		(net "P5E_CPU1_P2_TX_DN<0>")
	)
	(segment
		(start 139.898882 -370.415312)
		(end 140.036042 -370.552472)
		(width 0.14224)
		(layer "In13.Cu")
		(net "P5E_CPU1_P2_TX_DN<0>")
	)
	(segment
		(start 140.036042 -369.83797)
		(end 139.898882 -369.97513)
		(width 0.14224)
		(layer "In13.Cu")
		(net "P5E_CPU1_P2_TX_DN<0>")
	)
	(segment
		(start 139.93622 -381.698754)
		(end 139.996418 -381.758952)
		(width 0.14224)
		(layer "In13.Cu")
		(net "P5E_CPU1_P2_TX_DN<0>")
	)
	(segment
		(start 116.704618 -305.12639)
		(end 126.731268 -318.643762)
		(width 0.14224)
		(layer "In13.Cu")
		(net "P5E_CPU1_P2_TX_DN<0>")
	)
	(segment
		(start 140.036042 -368.423444)
		(end 139.898882 -368.560604)
		(width 0.14224)
		(layer "In13.Cu")
		(net "P5E_CPU1_P2_TX_DN<0>")
	)
	(arc
		(start 114.518694 -270.039084)
		(mid 114.445204 -270.316141)
		(end 114.243866 -270.52016)
		(width 0.1143)
		(layer "In13.Cu")
		(net "P5E_CPU1_P2_TX_DN<0>")
	)
	(arc
		(start 139.881356 -366.01908)
		(mid 139.894519 -366.077868)
		(end 139.898882 -366.137952)
		(width 0.14224)
		(layer "In13.Cu")
		(net "P5E_CPU1_P2_TX_DN<0>")
	)
	(arc
		(start 139.898882 -381.608838)
		(mid 139.908584 -381.657522)
		(end 139.93622 -381.698754)
		(width 0.14224)
		(layer "In13.Cu")
		(net "P5E_CPU1_P2_TX_DN<0>")
	)
	(arc
		(start 114.705384 -269.71498)
		(mid 114.568695 -269.852067)
		(end 114.518694 -270.039084)
		(width 0.1143)
		(layer "In13.Cu")
		(net "P5E_CPU1_P2_TX_DN<0>")
	)
	(arc
		(start 114.980212 -269.331948)
		(mid 114.898779 -269.534346)
		(end 114.746786 -269.69085)
		(width 0.1143)
		(layer "In13.Cu")
		(net "P5E_CPU1_P2_TX_DN<0>")
	)
	(arc
		(start 139.996418 -381.758952)
		(mid 140.037658 -381.786571)
		(end 140.086334 -381.79629)
		(width 0.14224)
		(layer "In13.Cu")
		(net "P5E_CPU1_P2_TX_DN<0>")
	)
	(arc
		(start 114.050064 -270.846296)
		(mid 113.985549 -271.108515)
		(end 113.806732 -271.310862)
		(width 0.1143)
		(layer "In13.Cu")
		(net "P5E_CPU1_P2_TX_DN<0>")
	)
	(arc
		(start 114.984022 -269.309088)
		(mid 114.982234 -269.320537)
		(end 114.980212 -269.331948)
		(width 0.1143)
		(layer "In13.Cu")
		(net "P5E_CPU1_P2_TX_DN<0>")
	)
	(arc
		(start 114.20602 -270.542004)
		(mid 114.091344 -270.675338)
		(end 114.050064 -270.846296)
		(width 0.1143)
		(layer "In13.Cu")
		(net "P5E_CPU1_P2_TX_DN<0>")
	)
	(segment
		(start 122.887994 -281.110436)
		(end 123.354846 -281.376374)
		(width 0.12954)
		(layer "F.Cu")
		(net "P5E_CPU1_P2_RX_DP<9>")
	)
	(segment
		(start 158.098236 -386.003292)
		(end 158.618936 -386.003292)
		(width 0.127)
		(layer "F.Cu")
		(net "P5E_CPU1_P2_RX_DP<9>")
	)
	(segment
		(start 123.056904 -281.376374)
		(end 123.354846 -281.376374)
		(width 0.1143)
		(layer "In6.Cu")
		(net "P5E_CPU1_P2_RX_DP<9>")
	)
	(segment
		(start 121.280428 -293.034466)
		(end 121.279158 -293.033704)
		(width 0.1143)
		(layer "In6.Cu")
		(net "P5E_CPU1_P2_RX_DP<9>")
	)
	(segment
		(start 121.256044 -287.55213)
		(end 121.322338 -287.513522)
		(width 0.1143)
		(layer "In6.Cu")
		(net "P5E_CPU1_P2_RX_DP<9>")
	)
	(segment
		(start 122.799094 -299.30217)
		(end 122.139964 -297.710606)
		(width 0.14224)
		(layer "In6.Cu")
		(net "P5E_CPU1_P2_RX_DP<9>")
	)
	(segment
		(start 122.697748 -281.8638)
		(end 122.698764 -281.863292)
		(width 0.1143)
		(layer "In6.Cu")
		(net "P5E_CPU1_P2_RX_DP<9>")
	)
	(segment
		(start 158.888176 -385.548632)
		(end 158.976314 -385.460494)
		(width 0.14224)
		(layer "In6.Cu")
		(net "P5E_CPU1_P2_RX_DP<9>")
	)
	(segment
		(start 121.288302 -293.038784)
		(end 121.287794 -293.038784)
		(width 0.1143)
		(layer "In6.Cu")
		(net "P5E_CPU1_P2_RX_DP<9>")
	)
	(segment
		(start 158.976314 -385.046982)
		(end 158.660338 -384.731006)
		(width 0.14224)
		(layer "In6.Cu")
		(net "P5E_CPU1_P2_RX_DP<9>")
	)
	(segment
		(start 158.618936 -386.003292)
		(end 158.713932 -385.649216)
		(width 0.14224)
		(layer "In6.Cu")
		(net "P5E_CPU1_P2_RX_DP<9>")
	)
	(segment
		(start 122.08637 -296.32529)
		(end 122.04065 -296.27957)
		(width 0.1143)
		(layer "In6.Cu")
		(net "P5E_CPU1_P2_RX_DP<9>")
	)
	(segment
		(start 139.077954 -323.642228)
		(end 134.458202 -314.998862)
		(width 0.14224)
		(layer "In6.Cu")
		(net "P5E_CPU1_P2_RX_DP<9>")
	)
	(segment
		(start 141.808454 -337.369658)
		(end 140.358368 -330.079096)
		(width 0.14224)
		(layer "In6.Cu")
		(net "P5E_CPU1_P2_RX_DP<9>")
	)
	(segment
		(start 121.289318 -289.799522)
		(end 121.286778 -289.798252)
		(width 0.1143)
		(layer "In6.Cu")
		(net "P5E_CPU1_P2_RX_DP<9>")
	)
	(segment
		(start 125.79985 -303.793144)
		(end 122.799094 -299.30217)
		(width 0.14224)
		(layer "In6.Cu")
		(net "P5E_CPU1_P2_RX_DP<9>")
	)
	(segment
		(start 143.377666 -343.271094)
		(end 142.592806 -340.610698)
		(width 0.14224)
		(layer "In6.Cu")
		(net "P5E_CPU1_P2_RX_DP<9>")
	)
	(segment
		(start 160.09874 -368.231928)
		(end 151.093932 -357.260144)
		(width 0.14224)
		(layer "In6.Cu")
		(net "P5E_CPU1_P2_RX_DP<9>")
	)
	(segment
		(start 121.283984 -293.036498)
		(end 121.282206 -293.035482)
		(width 0.1143)
		(layer "In6.Cu")
		(net "P5E_CPU1_P2_RX_DP<9>")
	)
	(segment
		(start 121.28119 -293.034974)
		(end 121.280428 -293.034466)
		(width 0.1143)
		(layer "In6.Cu")
		(net "P5E_CPU1_P2_RX_DP<9>")
	)
	(segment
		(start 146.276822 -349.68688)
		(end 145.05686 -347.552518)
		(width 0.14224)
		(layer "In6.Cu")
		(net "P5E_CPU1_P2_RX_DP<9>")
	)
	(segment
		(start 121.281698 -294.017192)
		(end 121.28246 -294.016684)
		(width 0.1143)
		(layer "In6.Cu")
		(net "P5E_CPU1_P2_RX_DP<9>")
	)
	(segment
		(start 121.79681 -295.491662)
		(end 121.724928 -295.449752)
		(width 0.1143)
		(layer "In6.Cu")
		(net "P5E_CPU1_P2_RX_DP<9>")
	)
	(segment
		(start 121.287794 -294.013636)
		(end 121.288302 -294.013636)
		(width 0.1143)
		(layer "In6.Cu")
		(net "P5E_CPU1_P2_RX_DP<9>")
	)
	(segment
		(start 146.321272 -349.770954)
		(end 146.276822 -349.68688)
		(width 0.14224)
		(layer "In6.Cu")
		(net "P5E_CPU1_P2_RX_DP<9>")
	)
	(segment
		(start 122.197114 -282.691586)
		(end 122.26671 -282.650946)
		(width 0.1143)
		(layer "In6.Cu")
		(net "P5E_CPU1_P2_RX_DP<9>")
	)
	(segment
		(start 121.282206 -293.035482)
		(end 121.28119 -293.034974)
		(width 0.1143)
		(layer "In6.Cu")
		(net "P5E_CPU1_P2_RX_DP<9>")
	)
	(segment
		(start 121.327926 -294.680386)
		(end 121.256044 -294.640508)
		(width 0.1143)
		(layer "In6.Cu")
		(net "P5E_CPU1_P2_RX_DP<9>")
	)
	(segment
		(start 145.05686 -347.552518)
		(end 144.440402 -346.0877)
		(width 0.14224)
		(layer "In6.Cu")
		(net "P5E_CPU1_P2_RX_DP<9>")
	)
	(segment
		(start 122.705368 -281.859228)
		(end 122.70613 -281.85872)
		(width 0.1143)
		(layer "In6.Cu")
		(net "P5E_CPU1_P2_RX_DP<9>")
	)
	(segment
		(start 122.696986 -281.864308)
		(end 122.697748 -281.8638)
		(width 0.1143)
		(layer "In6.Cu")
		(net "P5E_CPU1_P2_RX_DP<9>")
	)
	(segment
		(start 122.701812 -281.86126)
		(end 122.702828 -281.860752)
		(width 0.1143)
		(layer "In6.Cu")
		(net "P5E_CPU1_P2_RX_DP<9>")
	)
	(segment
		(start 121.76633 -283.478986)
		(end 121.796048 -283.46146)
		(width 0.1143)
		(layer "In6.Cu")
		(net "P5E_CPU1_P2_RX_DP<9>")
	)
	(segment
		(start 122.702828 -281.860752)
		(end 122.705368 -281.859228)
		(width 0.1143)
		(layer "In6.Cu")
		(net "P5E_CPU1_P2_RX_DP<9>")
	)
	(segment
		(start 151.093932 -357.260144)
		(end 148.544534 -353.474274)
		(width 0.14224)
		(layer "In6.Cu")
		(net "P5E_CPU1_P2_RX_DP<9>")
	)
	(segment
		(start 121.328942 -294.682418)
		(end 121.327926 -294.680386)
		(width 0.1143)
		(layer "In6.Cu")
		(net "P5E_CPU1_P2_RX_DP<9>")
	)
	(segment
		(start 121.256044 -289.171888)
		(end 121.313956 -289.138106)
		(width 0.1143)
		(layer "In6.Cu")
		(net "P5E_CPU1_P2_RX_DP<9>")
	)
	(segment
		(start 122.70613 -281.85872)
		(end 122.709432 -281.856942)
		(width 0.1143)
		(layer "In6.Cu")
		(net "P5E_CPU1_P2_RX_DP<9>")
	)
	(segment
		(start 158.976314 -385.460494)
		(end 158.976314 -385.046982)
		(width 0.14224)
		(layer "In6.Cu")
		(net "P5E_CPU1_P2_RX_DP<9>")
	)
	(segment
		(start 121.285254 -293.03726)
		(end 121.283984 -293.036498)
		(width 0.1143)
		(layer "In6.Cu")
		(net "P5E_CPU1_P2_RX_DP<9>")
	)
	(segment
		(start 121.757694 -283.483812)
		(end 121.75871 -283.483304)
		(width 0.1143)
		(layer "In6.Cu")
		(net "P5E_CPU1_P2_RX_DP<9>")
	)
	(segment
		(start 121.256044 -292.411912)
		(end 121.287794 -292.393624)
		(width 0.1143)
		(layer "In6.Cu")
		(net "P5E_CPU1_P2_RX_DP<9>")
	)
	(segment
		(start 141.808454 -337.369404)
		(end 141.808454 -337.369658)
		(width 0.14224)
		(layer "In6.Cu")
		(net "P5E_CPU1_P2_RX_DP<9>")
	)
	(segment
		(start 158.968186 -384.048254)
		(end 158.968186 -382.002792)
		(width 0.14224)
		(layer "In6.Cu")
		(net "P5E_CPU1_P2_RX_DP<9>")
	)
	(segment
		(start 121.75871 -283.483304)
		(end 121.761758 -283.481272)
		(width 0.1143)
		(layer "In6.Cu")
		(net "P5E_CPU1_P2_RX_DP<9>")
	)
	(segment
		(start 121.761758 -283.481272)
		(end 121.762774 -283.480764)
		(width 0.1143)
		(layer "In6.Cu")
		(net "P5E_CPU1_P2_RX_DP<9>")
	)
	(segment
		(start 122.694192 -281.865832)
		(end 122.696986 -281.864308)
		(width 0.1143)
		(layer "In6.Cu")
		(net "P5E_CPU1_P2_RX_DP<9>")
	)
	(segment
		(start 121.256044 -284.312106)
		(end 121.287032 -284.294072)
		(width 0.1143)
		(layer "In6.Cu")
		(net "P5E_CPU1_P2_RX_DP<9>")
	)
	(segment
		(start 121.285 -290.775136)
		(end 121.286016 -290.774628)
		(width 0.1143)
		(layer "In6.Cu")
		(net "P5E_CPU1_P2_RX_DP<9>")
	)
	(segment
		(start 121.30913 -291.431218)
		(end 121.256044 -291.400484)
		(width 0.1143)
		(layer "In6.Cu")
		(net "P5E_CPU1_P2_RX_DP<9>")
	)
	(segment
		(start 121.286016 -290.774628)
		(end 121.286778 -290.77412)
		(width 0.1143)
		(layer "In6.Cu")
		(net "P5E_CPU1_P2_RX_DP<9>")
	)
	(segment
		(start 121.287032 -294.014144)
		(end 121.287794 -294.013636)
		(width 0.1143)
		(layer "In6.Cu")
		(net "P5E_CPU1_P2_RX_DP<9>")
	)
	(segment
		(start 121.279158 -293.033704)
		(end 121.278142 -293.033196)
		(width 0.1143)
		(layer "In6.Cu")
		(net "P5E_CPU1_P2_RX_DP<9>")
	)
	(segment
		(start 140.358368 -330.079096)
		(end 139.077954 -323.642228)
		(width 0.14224)
		(layer "In6.Cu")
		(net "P5E_CPU1_P2_RX_DP<9>")
	)
	(segment
		(start 121.324116 -288.19983)
		(end 121.321322 -288.198306)
		(width 0.1143)
		(layer "In6.Cu")
		(net "P5E_CPU1_P2_RX_DP<9>")
	)
	(segment
		(start 121.280682 -294.0177)
		(end 121.281698 -294.017192)
		(width 0.1143)
		(layer "In6.Cu")
		(net "P5E_CPU1_P2_RX_DP<9>")
	)
	(segment
		(start 132.101844 -311.471818)
		(end 125.79985 -303.793144)
		(width 0.14224)
		(layer "In6.Cu")
		(net "P5E_CPU1_P2_RX_DP<9>")
	)
	(segment
		(start 142.592806 -340.610698)
		(end 142.545816 -340.437724)
		(width 0.14224)
		(layer "In6.Cu")
		(net "P5E_CPU1_P2_RX_DP<9>")
	)
	(segment
		(start 122.69343 -281.86634)
		(end 122.694192 -281.865832)
		(width 0.1143)
		(layer "In6.Cu")
		(net "P5E_CPU1_P2_RX_DP<9>")
	)
	(segment
		(start 121.283222 -289.79622)
		(end 121.28246 -289.795712)
		(width 0.1143)
		(layer "In6.Cu")
		(net "P5E_CPU1_P2_RX_DP<9>")
	)
	(segment
		(start 122.691398 -281.867356)
		(end 122.69343 -281.86634)
		(width 0.1143)
		(layer "In6.Cu")
		(net "P5E_CPU1_P2_RX_DP<9>")
	)
	(segment
		(start 121.284238 -294.015668)
		(end 121.285254 -294.01516)
		(width 0.1143)
		(layer "In6.Cu")
		(net "P5E_CPU1_P2_RX_DP<9>")
	)
	(segment
		(start 121.27992 -294.018208)
		(end 121.280682 -294.0177)
		(width 0.1143)
		(layer "In6.Cu")
		(net "P5E_CPU1_P2_RX_DP<9>")
	)
	(segment
		(start 121.273316 -293.030402)
		(end 121.256806 -293.021004)
		(width 0.1143)
		(layer "In6.Cu")
		(net "P5E_CPU1_P2_RX_DP<9>")
	)
	(segment
		(start 143.595598 -343.892886)
		(end 143.377666 -343.271094)
		(width 0.14224)
		(layer "In6.Cu")
		(net "P5E_CPU1_P2_RX_DP<9>")
	)
	(segment
		(start 122.709432 -281.856942)
		(end 122.736864 -281.84094)
		(width 0.1143)
		(layer "In6.Cu")
		(net "P5E_CPU1_P2_RX_DP<9>")
	)
	(segment
		(start 121.285254 -294.01516)
		(end 121.286016 -294.014652)
		(width 0.1143)
		(layer "In6.Cu")
		(net "P5E_CPU1_P2_RX_DP<9>")
	)
	(segment
		(start 121.286016 -289.797744)
		(end 121.285 -289.797236)
		(width 0.1143)
		(layer "In6.Cu")
		(net "P5E_CPU1_P2_RX_DP<9>")
	)
	(segment
		(start 121.569988 -295.149778)
		(end 121.569988 -295.14292)
		(width 0.1143)
		(layer "In6.Cu")
		(net "P5E_CPU1_P2_RX_DP<9>")
	)
	(segment
		(start 121.284238 -289.796728)
		(end 121.283222 -289.79622)
		(width 0.1143)
		(layer "In6.Cu")
		(net "P5E_CPU1_P2_RX_DP<9>")
	)
	(segment
		(start 147.7645 -352.263456)
		(end 147.023328 -351.028508)
		(width 0.14224)
		(layer "In6.Cu")
		(net "P5E_CPU1_P2_RX_DP<9>")
	)
	(segment
		(start 122.04065 -296.27957)
		(end 122.04065 -296.007536)
		(width 0.1143)
		(layer "In6.Cu")
		(net "P5E_CPU1_P2_RX_DP<9>")
	)
	(segment
		(start 121.278142 -293.033196)
		(end 121.275602 -293.031672)
		(width 0.1143)
		(layer "In6.Cu")
		(net "P5E_CPU1_P2_RX_DP<9>")
	)
	(segment
		(start 122.08637 -296.353738)
		(end 122.08637 -296.32529)
		(width 0.1143)
		(layer "In6.Cu")
		(net "P5E_CPU1_P2_RX_DP<9>")
	)
	(segment
		(start 121.308368 -292.381686)
		(end 121.30913 -292.381178)
		(width 0.1143)
		(layer "In6.Cu")
		(net "P5E_CPU1_P2_RX_DP<9>")
	)
	(segment
		(start 121.324116 -284.96006)
		(end 121.256044 -284.92069)
		(width 0.1143)
		(layer "In6.Cu")
		(net "P5E_CPU1_P2_RX_DP<9>")
	)
	(segment
		(start 122.04065 -296.007536)
		(end 122.040142 -296.007028)
		(width 0.1143)
		(layer "In6.Cu")
		(net "P5E_CPU1_P2_RX_DP<9>")
	)
	(segment
		(start 147.023328 -351.028508)
		(end 146.321272 -349.770954)
		(width 0.14224)
		(layer "In6.Cu")
		(net "P5E_CPU1_P2_RX_DP<9>")
	)
	(segment
		(start 121.321322 -288.198306)
		(end 121.31675 -288.195766)
		(width 0.1143)
		(layer "In6.Cu")
		(net "P5E_CPU1_P2_RX_DP<9>")
	)
	(segment
		(start 121.278142 -294.019224)
		(end 121.278904 -294.018716)
		(width 0.1143)
		(layer "In6.Cu")
		(net "P5E_CPU1_P2_RX_DP<9>")
	)
	(segment
		(start 144.440402 -346.0877)
		(end 143.595598 -343.892886)
		(width 0.14224)
		(layer "In6.Cu")
		(net "P5E_CPU1_P2_RX_DP<9>")
	)
	(segment
		(start 121.287794 -293.038784)
		(end 121.287032 -293.038276)
		(width 0.1143)
		(layer "In6.Cu")
		(net "P5E_CPU1_P2_RX_DP<9>")
	)
	(segment
		(start 121.765314 -283.47924)
		(end 121.766076 -283.478732)
		(width 0.1143)
		(layer "In6.Cu")
		(net "P5E_CPU1_P2_RX_DP<9>")
	)
	(segment
		(start 121.313956 -289.138106)
		(end 121.324116 -289.132518)
		(width 0.1143)
		(layer "In6.Cu")
		(net "P5E_CPU1_P2_RX_DP<9>")
	)
	(segment
		(start 121.27484 -293.031164)
		(end 121.273316 -293.030402)
		(width 0.1143)
		(layer "In6.Cu")
		(net "P5E_CPU1_P2_RX_DP<9>")
	)
	(segment
		(start 121.256044 -294.031924)
		(end 121.27611 -294.02024)
		(width 0.1143)
		(layer "In6.Cu")
		(net "P5E_CPU1_P2_RX_DP<9>")
	)
	(segment
		(start 121.256806 -293.021004)
		(end 121.256044 -293.020496)
		(width 0.1143)
		(layer "In6.Cu")
		(net "P5E_CPU1_P2_RX_DP<9>")
	)
	(segment
		(start 121.285 -289.797236)
		(end 121.284238 -289.796728)
		(width 0.1143)
		(layer "In6.Cu")
		(net "P5E_CPU1_P2_RX_DP<9>")
	)
	(segment
		(start 121.286016 -294.014652)
		(end 121.287032 -294.014144)
		(width 0.1143)
		(layer "In6.Cu")
		(net "P5E_CPU1_P2_RX_DP<9>")
	)
	(segment
		(start 121.275602 -293.031672)
		(end 121.27484 -293.031164)
		(width 0.1143)
		(layer "In6.Cu")
		(net "P5E_CPU1_P2_RX_DP<9>")
	)
	(segment
		(start 121.281444 -289.795204)
		(end 121.256044 -289.780472)
		(width 0.1143)
		(layer "In6.Cu")
		(net "P5E_CPU1_P2_RX_DP<9>")
	)
	(segment
		(start 121.27611 -294.02024)
		(end 121.278142 -294.019224)
		(width 0.1143)
		(layer "In6.Cu")
		(net "P5E_CPU1_P2_RX_DP<9>")
	)
	(segment
		(start 158.968186 -382.002792)
		(end 159.08655 -373.646192)
		(width 0.14224)
		(layer "In6.Cu")
		(net "P5E_CPU1_P2_RX_DP<9>")
	)
	(segment
		(start 121.31675 -288.195766)
		(end 121.254266 -288.15919)
		(width 0.1143)
		(layer "In6.Cu")
		(net "P5E_CPU1_P2_RX_DP<9>")
	)
	(segment
		(start 121.756932 -283.48432)
		(end 121.757694 -283.483812)
		(width 0.1143)
		(layer "In6.Cu")
		(net "P5E_CPU1_P2_RX_DP<9>")
	)
	(segment
		(start 158.660338 -384.731006)
		(end 158.663386 -384.3528)
		(width 0.14224)
		(layer "In6.Cu")
		(net "P5E_CPU1_P2_RX_DP<9>")
	)
	(segment
		(start 142.545816 -340.437724)
		(end 141.808454 -337.369404)
		(width 0.14224)
		(layer "In6.Cu")
		(net "P5E_CPU1_P2_RX_DP<9>")
	)
	(segment
		(start 148.544534 -353.474274)
		(end 147.7645 -352.263202)
		(width 0.14224)
		(layer "In6.Cu")
		(net "P5E_CPU1_P2_RX_DP<9>")
	)
	(segment
		(start 121.79681 -285.771844)
		(end 121.725944 -285.730696)
		(width 0.1143)
		(layer "In6.Cu")
		(net "P5E_CPU1_P2_RX_DP<9>")
	)
	(segment
		(start 160.235646 -371.06479)
		(end 160.237424 -369.314476)
		(width 0.14224)
		(layer "In6.Cu")
		(net "P5E_CPU1_P2_RX_DP<9>")
	)
	(segment
		(start 122.698764 -281.863292)
		(end 122.701812 -281.86126)
		(width 0.1143)
		(layer "In6.Cu")
		(net "P5E_CPU1_P2_RX_DP<9>")
	)
	(segment
		(start 121.286778 -289.798252)
		(end 121.286016 -289.797744)
		(width 0.1143)
		(layer "In6.Cu")
		(net "P5E_CPU1_P2_RX_DP<9>")
	)
	(segment
		(start 121.256044 -290.7919)
		(end 121.285 -290.775136)
		(width 0.1143)
		(layer "In6.Cu")
		(net "P5E_CPU1_P2_RX_DP<9>")
	)
	(segment
		(start 121.278904 -294.018716)
		(end 121.27992 -294.018208)
		(width 0.1143)
		(layer "In6.Cu")
		(net "P5E_CPU1_P2_RX_DP<9>")
	)
	(segment
		(start 121.28246 -289.795712)
		(end 121.281444 -289.795204)
		(width 0.1143)
		(layer "In6.Cu")
		(net "P5E_CPU1_P2_RX_DP<9>")
	)
	(segment
		(start 160.237424 -369.314476)
		(end 160.237424 -368.620802)
		(width 0.14224)
		(layer "In6.Cu")
		(net "P5E_CPU1_P2_RX_DP<9>")
	)
	(segment
		(start 121.286778 -290.77412)
		(end 121.289318 -290.77285)
		(width 0.1143)
		(layer "In6.Cu")
		(net "P5E_CPU1_P2_RX_DP<9>")
	)
	(segment
		(start 121.735088 -283.49702)
		(end 121.756932 -283.48432)
		(width 0.1143)
		(layer "In6.Cu")
		(net "P5E_CPU1_P2_RX_DP<9>")
	)
	(segment
		(start 121.287794 -292.393624)
		(end 121.308368 -292.381686)
		(width 0.1143)
		(layer "In6.Cu")
		(net "P5E_CPU1_P2_RX_DP<9>")
	)
	(segment
		(start 158.713932 -385.649216)
		(end 158.888176 -385.548632)
		(width 0.14224)
		(layer "In6.Cu")
		(net "P5E_CPU1_P2_RX_DP<9>")
	)
	(segment
		(start 121.283476 -294.016176)
		(end 121.284238 -294.015668)
		(width 0.1143)
		(layer "In6.Cu")
		(net "P5E_CPU1_P2_RX_DP<9>")
	)
	(segment
		(start 121.287032 -293.038276)
		(end 121.286016 -293.037768)
		(width 0.1143)
		(layer "In6.Cu")
		(net "P5E_CPU1_P2_RX_DP<9>")
	)
	(segment
		(start 121.766076 -283.478732)
		(end 121.76633 -283.478986)
		(width 0.1143)
		(layer "In6.Cu")
		(net "P5E_CPU1_P2_RX_DP<9>")
	)
	(segment
		(start 122.040142 -296.007028)
		(end 122.040142 -295.956228)
		(width 0.1143)
		(layer "In6.Cu")
		(net "P5E_CPU1_P2_RX_DP<9>")
	)
	(segment
		(start 121.28246 -294.016684)
		(end 121.283476 -294.016176)
		(width 0.1143)
		(layer "In6.Cu")
		(net "P5E_CPU1_P2_RX_DP<9>")
	)
	(segment
		(start 122.665998 -281.882088)
		(end 122.691398 -281.867356)
		(width 0.1143)
		(layer "In6.Cu")
		(net "P5E_CPU1_P2_RX_DP<9>")
	)
	(segment
		(start 158.663386 -384.3528)
		(end 158.968186 -384.048254)
		(width 0.14224)
		(layer "In6.Cu")
		(net "P5E_CPU1_P2_RX_DP<9>")
	)
	(segment
		(start 122.9741 -281.459178)
		(end 123.056904 -281.376374)
		(width 0.1143)
		(layer "In6.Cu")
		(net "P5E_CPU1_P2_RX_DP<9>")
	)
	(segment
		(start 121.724166 -286.743394)
		(end 121.79681 -286.700976)
		(width 0.1143)
		(layer "In6.Cu")
		(net "P5E_CPU1_P2_RX_DP<9>")
	)
	(segment
		(start 134.458202 -314.998862)
		(end 132.101844 -311.471818)
		(width 0.14224)
		(layer "In6.Cu")
		(net "P5E_CPU1_P2_RX_DP<9>")
	)
	(segment
		(start 159.143192 -373.407686)
		(end 160.194498 -371.243098)
		(width 0.14224)
		(layer "In6.Cu")
		(net "P5E_CPU1_P2_RX_DP<9>")
	)
	(segment
		(start 121.762774 -283.480764)
		(end 121.765314 -283.47924)
		(width 0.1143)
		(layer "In6.Cu")
		(net "P5E_CPU1_P2_RX_DP<9>")
	)
	(segment
		(start 147.7645 -352.263202)
		(end 147.7645 -352.263456)
		(width 0.14224)
		(layer "In6.Cu")
		(net "P5E_CPU1_P2_RX_DP<9>")
	)
	(segment
		(start 121.286016 -293.037768)
		(end 121.285254 -293.03726)
		(width 0.1143)
		(layer "In6.Cu")
		(net "P5E_CPU1_P2_RX_DP<9>")
	)
	(segment
		(start 122.08637 -297.441874)
		(end 122.08637 -296.353738)
		(width 0.14224)
		(layer "In6.Cu")
		(net "P5E_CPU1_P2_RX_DP<9>")
	)
	(segment
		(start 121.287032 -284.294072)
		(end 121.326148 -284.27172)
		(width 0.1143)
		(layer "In6.Cu")
		(net "P5E_CPU1_P2_RX_DP<9>")
	)
	(arc
		(start 121.256044 -284.92069)
		(mid 121.100116 -284.616398)
		(end 121.256044 -284.312106)
		(width 0.1143)
		(layer "In6.Cu")
		(net "P5E_CPU1_P2_RX_DP<9>")
	)
	(arc
		(start 121.30913 -292.381178)
		(mid 121.582681 -291.906198)
		(end 121.30913 -291.431218)
		(width 0.1143)
		(layer "In6.Cu")
		(net "P5E_CPU1_P2_RX_DP<9>")
	)
	(arc
		(start 121.796048 -283.46146)
		(mid 121.796429 -283.461206)
		(end 121.79681 -283.460952)
		(width 0.1143)
		(layer "In6.Cu")
		(net "P5E_CPU1_P2_RX_DP<9>")
	)
	(arc
		(start 121.569988 -287.036764)
		(mid 121.612803 -286.87205)
		(end 121.724166 -286.743394)
		(width 0.1143)
		(layer "In6.Cu")
		(net "P5E_CPU1_P2_RX_DP<9>")
	)
	(arc
		(start 121.322338 -287.513522)
		(mid 121.485128 -287.320514)
		(end 121.566432 -287.081468)
		(width 0.1143)
		(layer "In6.Cu")
		(net "P5E_CPU1_P2_RX_DP<9>")
	)
	(arc
		(start 121.572528 -283.795216)
		(mid 121.597316 -283.698564)
		(end 121.640854 -283.60878)
		(width 0.1143)
		(layer "In6.Cu")
		(net "P5E_CPU1_P2_RX_DP<9>")
	)
	(arc
		(start 121.725944 -285.730696)
		(mid 121.614502 -285.604054)
		(end 121.569734 -285.44139)
		(width 0.1143)
		(layer "In6.Cu")
		(net "P5E_CPU1_P2_RX_DP<9>")
	)
	(arc
		(start 121.341388 -289.119056)
		(mid 121.557378 -288.655225)
		(end 121.324116 -288.19983)
		(width 0.1143)
		(layer "In6.Cu")
		(net "P5E_CPU1_P2_RX_DP<9>")
	)
	(arc
		(start 121.640854 -283.60878)
		(mid 121.683841 -283.549417)
		(end 121.735088 -283.49702)
		(width 0.1143)
		(layer "In6.Cu")
		(net "P5E_CPU1_P2_RX_DP<9>")
	)
	(arc
		(start 121.256044 -293.020496)
		(mid 121.100116 -292.716204)
		(end 121.256044 -292.411912)
		(width 0.1143)
		(layer "In6.Cu")
		(net "P5E_CPU1_P2_RX_DP<9>")
	)
	(arc
		(start 121.565924 -285.39059)
		(mid 121.485256 -285.152718)
		(end 121.324116 -284.96006)
		(width 0.1143)
		(layer "In6.Cu")
		(net "P5E_CPU1_P2_RX_DP<9>")
	)
	(arc
		(start 121.100088 -287.856422)
		(mid 121.141343 -287.685451)
		(end 121.256044 -287.55213)
		(width 0.1143)
		(layer "In6.Cu")
		(net "P5E_CPU1_P2_RX_DP<9>")
	)
	(arc
		(start 121.79681 -286.700976)
		(mid 122.040137 -286.23641)
		(end 121.79681 -285.771844)
		(width 0.1143)
		(layer "In6.Cu")
		(net "P5E_CPU1_P2_RX_DP<9>")
	)
	(arc
		(start 121.254266 -288.15919)
		(mid 121.140859 -288.026301)
		(end 121.100088 -287.856422)
		(width 0.1143)
		(layer "In6.Cu")
		(net "P5E_CPU1_P2_RX_DP<9>")
	)
	(arc
		(start 121.569734 -285.44139)
		(mid 121.568562 -285.415935)
		(end 121.565924 -285.39059)
		(width 0.1143)
		(layer "In6.Cu")
		(net "P5E_CPU1_P2_RX_DP<9>")
	)
	(arc
		(start 121.724928 -295.449752)
		(mid 121.610992 -295.318597)
		(end 121.569988 -295.149778)
		(width 0.1143)
		(layer "In6.Cu")
		(net "P5E_CPU1_P2_RX_DP<9>")
	)
	(arc
		(start 122.26671 -282.650946)
		(mid 122.445523 -282.448596)
		(end 122.510042 -282.18638)
		(width 0.1143)
		(layer "In6.Cu")
		(net "P5E_CPU1_P2_RX_DP<9>")
	)
	(arc
		(start 121.256044 -291.400484)
		(mid 121.100116 -291.096192)
		(end 121.256044 -290.7919)
		(width 0.1143)
		(layer "In6.Cu")
		(net "P5E_CPU1_P2_RX_DP<9>")
	)
	(arc
		(start 160.237424 -368.620802)
		(mid 160.201852 -368.414317)
		(end 160.09874 -368.231928)
		(width 0.14224)
		(layer "In6.Cu")
		(net "P5E_CPU1_P2_RX_DP<9>")
	)
	(arc
		(start 160.194498 -371.243098)
		(mid 160.225182 -371.156276)
		(end 160.235646 -371.06479)
		(width 0.14224)
		(layer "In6.Cu")
		(net "P5E_CPU1_P2_RX_DP<9>")
	)
	(arc
		(start 122.736864 -281.84094)
		(mid 122.888851 -281.684432)
		(end 122.97029 -281.482038)
		(width 0.1143)
		(layer "In6.Cu")
		(net "P5E_CPU1_P2_RX_DP<9>")
	)
	(arc
		(start 122.040142 -282.996386)
		(mid 122.081691 -282.824964)
		(end 122.197114 -282.691586)
		(width 0.1143)
		(layer "In6.Cu")
		(net "P5E_CPU1_P2_RX_DP<9>")
	)
	(arc
		(start 122.510042 -282.18638)
		(mid 122.551297 -282.015409)
		(end 122.665998 -281.882088)
		(width 0.1143)
		(layer "In6.Cu")
		(net "P5E_CPU1_P2_RX_DP<9>")
	)
	(arc
		(start 121.570242 -283.82595)
		(mid 121.570909 -283.810548)
		(end 121.572528 -283.795216)
		(width 0.1143)
		(layer "In6.Cu")
		(net "P5E_CPU1_P2_RX_DP<9>")
	)
	(arc
		(start 121.289318 -290.77285)
		(mid 121.569559 -290.286186)
		(end 121.289318 -289.799522)
		(width 0.1143)
		(layer "In6.Cu")
		(net "P5E_CPU1_P2_RX_DP<9>")
	)
	(arc
		(start 121.256044 -289.780472)
		(mid 121.100116 -289.47618)
		(end 121.256044 -289.171888)
		(width 0.1143)
		(layer "In6.Cu")
		(net "P5E_CPU1_P2_RX_DP<9>")
	)
	(arc
		(start 121.326148 -284.27172)
		(mid 121.501041 -284.07778)
		(end 121.570242 -283.82595)
		(width 0.1143)
		(layer "In6.Cu")
		(net "P5E_CPU1_P2_RX_DP<9>")
	)
	(arc
		(start 122.97029 -281.482038)
		(mid 122.972313 -281.470628)
		(end 122.9741 -281.459178)
		(width 0.1143)
		(layer "In6.Cu")
		(net "P5E_CPU1_P2_RX_DP<9>")
	)
	(arc
		(start 121.288302 -294.013636)
		(mid 121.568949 -293.52621)
		(end 121.288302 -293.038784)
		(width 0.1143)
		(layer "In6.Cu")
		(net "P5E_CPU1_P2_RX_DP<9>")
	)
	(arc
		(start 121.79681 -283.460952)
		(mid 121.975623 -283.258602)
		(end 122.040142 -282.996386)
		(width 0.1143)
		(layer "In6.Cu")
		(net "P5E_CPU1_P2_RX_DP<9>")
	)
	(arc
		(start 121.256044 -294.640508)
		(mid 121.100116 -294.336216)
		(end 121.256044 -294.031924)
		(width 0.1143)
		(layer "In6.Cu")
		(net "P5E_CPU1_P2_RX_DP<9>")
	)
	(arc
		(start 121.324116 -289.132518)
		(mid 121.332814 -289.125867)
		(end 121.341388 -289.119056)
		(width 0.1143)
		(layer "In6.Cu")
		(net "P5E_CPU1_P2_RX_DP<9>")
	)
	(arc
		(start 121.569988 -295.14292)
		(mid 121.502633 -294.884844)
		(end 121.328942 -294.682418)
		(width 0.1143)
		(layer "In6.Cu")
		(net "P5E_CPU1_P2_RX_DP<9>")
	)
	(arc
		(start 121.566432 -287.081468)
		(mid 121.568787 -287.059162)
		(end 121.569988 -287.036764)
		(width 0.1143)
		(layer "In6.Cu")
		(net "P5E_CPU1_P2_RX_DP<9>")
	)
	(arc
		(start 122.040142 -295.956228)
		(mid 121.975574 -295.694036)
		(end 121.79681 -295.491662)
		(width 0.1143)
		(layer "In6.Cu")
		(net "P5E_CPU1_P2_RX_DP<9>")
	)
	(arc
		(start 159.08655 -373.646192)
		(mid 159.101736 -373.523817)
		(end 159.143192 -373.407686)
		(width 0.14224)
		(layer "In6.Cu")
		(net "P5E_CPU1_P2_RX_DP<9>")
	)
	(arc
		(start 122.139964 -297.710606)
		(mid 122.099952 -297.578877)
		(end 122.08637 -297.441874)
		(width 0.14224)
		(layer "In6.Cu")
		(net "P5E_CPU1_P2_RX_DP<9>")
	)
	(segment
		(start 120.067832 -284.35046)
		(end 120.534684 -284.616398)
		(width 0.12954)
		(layer "F.Cu")
		(net "P5E_CPU1_P2_RX_DP<8>")
	)
	(segment
		(start 156.89834 -386.003292)
		(end 157.41904 -386.003292)
		(width 0.127)
		(layer "F.Cu")
		(net "P5E_CPU1_P2_RX_DP<8>")
	)
	(segment
		(start 143.665956 -347.001846)
		(end 142.223998 -342.884252)
		(width 0.14224)
		(layer "In6.Cu")
		(net "P5E_CPU1_P2_RX_DP<8>")
	)
	(segment
		(start 128.23444 -308.247288)
		(end 128.234186 -308.247288)
		(width 0.14224)
		(layer "In6.Cu")
		(net "P5E_CPU1_P2_RX_DP<8>")
	)
	(segment
		(start 120.856756 -285.771844)
		(end 120.78716 -285.731204)
		(width 0.1143)
		(layer "In6.Cu")
		(net "P5E_CPU1_P2_RX_DP<8>")
	)
	(segment
		(start 120.339866 -284.934406)
		(end 120.337326 -284.933136)
		(width 0.1143)
		(layer "In6.Cu")
		(net "P5E_CPU1_P2_RX_DP<8>")
	)
	(segment
		(start 120.344184 -287.535874)
		(end 120.345708 -287.535112)
		(width 0.1143)
		(layer "In6.Cu")
		(net "P5E_CPU1_P2_RX_DP<8>")
	)
	(segment
		(start 157.776418 -385.460494)
		(end 157.776418 -385.046982)
		(width 0.14224)
		(layer "In6.Cu")
		(net "P5E_CPU1_P2_RX_DP<8>")
	)
	(segment
		(start 120.343422 -284.936438)
		(end 120.341898 -284.935676)
		(width 0.1143)
		(layer "In6.Cu")
		(net "P5E_CPU1_P2_RX_DP<8>")
	)
	(segment
		(start 120.84812 -286.70631)
		(end 120.848882 -286.705802)
		(width 0.1143)
		(layer "In6.Cu")
		(net "P5E_CPU1_P2_RX_DP<8>")
	)
	(segment
		(start 120.35282 -287.530794)
		(end 120.384316 -287.512506)
		(width 0.1143)
		(layer "In6.Cu")
		(net "P5E_CPU1_P2_RX_DP<8>")
	)
	(segment
		(start 157.776418 -385.046982)
		(end 157.460442 -384.731006)
		(width 0.14224)
		(layer "In6.Cu")
		(net "P5E_CPU1_P2_RX_DP<8>")
	)
	(segment
		(start 120.348756 -287.533334)
		(end 120.350026 -287.532572)
		(width 0.1143)
		(layer "In6.Cu")
		(net "P5E_CPU1_P2_RX_DP<8>")
	)
	(segment
		(start 120.348756 -284.939486)
		(end 120.34774 -284.938978)
		(width 0.1143)
		(layer "In6.Cu")
		(net "P5E_CPU1_P2_RX_DP<8>")
	)
	(segment
		(start 158.046928 -373.75592)
		(end 158.571946 -371.731032)
		(width 0.14224)
		(layer "In6.Cu")
		(net "P5E_CPU1_P2_RX_DP<8>")
	)
	(segment
		(start 120.236742 -284.616398)
		(end 120.534684 -284.616398)
		(width 0.1143)
		(layer "In6.Cu")
		(net "P5E_CPU1_P2_RX_DP<8>")
	)
	(segment
		(start 120.354598 -284.943042)
		(end 120.353074 -284.942026)
		(width 0.1143)
		(layer "In6.Cu")
		(net "P5E_CPU1_P2_RX_DP<8>")
	)
	(segment
		(start 157.41904 -386.003292)
		(end 157.514036 -385.649216)
		(width 0.14224)
		(layer "In6.Cu")
		(net "P5E_CPU1_P2_RX_DP<8>")
	)
	(segment
		(start 146.167094 -351.443798)
		(end 145.466308 -350.188276)
		(width 0.14224)
		(layer "In6.Cu")
		(net "P5E_CPU1_P2_RX_DP<8>")
	)
	(segment
		(start 120.341898 -284.935676)
		(end 120.341136 -284.935168)
		(width 0.1143)
		(layer "In6.Cu")
		(net "P5E_CPU1_P2_RX_DP<8>")
	)
	(segment
		(start 120.317006 -292.411404)
		(end 120.386602 -292.370764)
		(width 0.1143)
		(layer "In6.Cu")
		(net "P5E_CPU1_P2_RX_DP<8>")
	)
	(segment
		(start 120.386602 -293.061644)
		(end 120.317006 -293.021004)
		(width 0.1143)
		(layer "In6.Cu")
		(net "P5E_CPU1_P2_RX_DP<8>")
	)
	(segment
		(start 120.350026 -287.532572)
		(end 120.350788 -287.532064)
		(width 0.1143)
		(layer "In6.Cu")
		(net "P5E_CPU1_P2_RX_DP<8>")
	)
	(segment
		(start 120.856756 -295.491662)
		(end 120.78716 -295.451022)
		(width 0.1143)
		(layer "In6.Cu")
		(net "P5E_CPU1_P2_RX_DP<8>")
	)
	(segment
		(start 121.102628 -296.27957)
		(end 121.102628 -296.009568)
		(width 0.1143)
		(layer "In6.Cu")
		(net "P5E_CPU1_P2_RX_DP<8>")
	)
	(segment
		(start 145.466308 -350.188276)
		(end 145.444972 -350.147636)
		(width 0.14224)
		(layer "In6.Cu")
		(net "P5E_CPU1_P2_RX_DP<8>")
	)
	(segment
		(start 156.761434 -367.625884)
		(end 148.294852 -354.955348)
		(width 0.14224)
		(layer "In6.Cu")
		(net "P5E_CPU1_P2_RX_DP<8>")
	)
	(segment
		(start 120.346978 -287.53435)
		(end 120.34774 -287.533842)
		(width 0.1143)
		(layer "In6.Cu")
		(net "P5E_CPU1_P2_RX_DP<8>")
	)
	(segment
		(start 120.386602 -289.82162)
		(end 120.317006 -289.78098)
		(width 0.1143)
		(layer "In6.Cu")
		(net "P5E_CPU1_P2_RX_DP<8>")
	)
	(segment
		(start 121.148348 -296.32529)
		(end 121.102628 -296.27957)
		(width 0.1143)
		(layer "In6.Cu")
		(net "P5E_CPU1_P2_RX_DP<8>")
	)
	(segment
		(start 157.76829 -384.048)
		(end 157.76829 -380.322328)
		(width 0.14224)
		(layer "In6.Cu")
		(net "P5E_CPU1_P2_RX_DP<8>")
	)
	(segment
		(start 146.868134 -352.699574)
		(end 146.167094 -351.443798)
		(width 0.14224)
		(layer "In6.Cu")
		(net "P5E_CPU1_P2_RX_DP<8>")
	)
	(segment
		(start 157.460442 -384.731006)
		(end 157.46349 -384.3528)
		(width 0.14224)
		(layer "In6.Cu")
		(net "P5E_CPU1_P2_RX_DP<8>")
	)
	(segment
		(start 131.409694 -312.11647)
		(end 128.23444 -308.247288)
		(width 0.14224)
		(layer "In6.Cu")
		(net "P5E_CPU1_P2_RX_DP<8>")
	)
	(segment
		(start 120.846342 -286.707326)
		(end 120.847104 -286.706818)
		(width 0.1143)
		(layer "In6.Cu")
		(net "P5E_CPU1_P2_RX_DP<8>")
	)
	(segment
		(start 120.386602 -288.201608)
		(end 120.347486 -288.178748)
		(width 0.1143)
		(layer "In6.Cu")
		(net "P5E_CPU1_P2_RX_DP<8>")
	)
	(segment
		(start 120.350788 -287.532064)
		(end 120.352058 -287.531302)
		(width 0.1143)
		(layer "In6.Cu")
		(net "P5E_CPU1_P2_RX_DP<8>")
	)
	(segment
		(start 120.344184 -284.936946)
		(end 120.343422 -284.936438)
		(width 0.1143)
		(layer "In6.Cu")
		(net "P5E_CPU1_P2_RX_DP<8>")
	)
	(segment
		(start 156.830014 -369.416584)
		(end 156.830014 -367.853214)
		(width 0.14224)
		(layer "In6.Cu")
		(net "P5E_CPU1_P2_RX_DP<8>")
	)
	(segment
		(start 120.785128 -286.742632)
		(end 120.81764 -286.723836)
		(width 0.1143)
		(layer "In6.Cu")
		(net "P5E_CPU1_P2_RX_DP<8>")
	)
	(segment
		(start 121.100088 -296.007028)
		(end 121.100088 -295.956228)
		(width 0.1143)
		(layer "In6.Cu")
		(net "P5E_CPU1_P2_RX_DP<8>")
	)
	(segment
		(start 120.630188 -295.146222)
		(end 120.629934 -295.146222)
		(width 0.1143)
		(layer "In6.Cu")
		(net "P5E_CPU1_P2_RX_DP<8>")
	)
	(segment
		(start 157.514036 -385.649216)
		(end 157.68828 -385.548632)
		(width 0.14224)
		(layer "In6.Cu")
		(net "P5E_CPU1_P2_RX_DP<8>")
	)
	(segment
		(start 120.317006 -289.17138)
		(end 120.386602 -289.13074)
		(width 0.1143)
		(layer "In6.Cu")
		(net "P5E_CPU1_P2_RX_DP<8>")
	)
	(segment
		(start 120.386856 -284.961838)
		(end 120.379998 -284.957774)
		(width 0.1143)
		(layer "In6.Cu")
		(net "P5E_CPU1_P2_RX_DP<8>")
	)
	(segment
		(start 120.386602 -291.441632)
		(end 120.317006 -291.400992)
		(width 0.1143)
		(layer "In6.Cu")
		(net "P5E_CPU1_P2_RX_DP<8>")
	)
	(segment
		(start 120.379998 -284.957774)
		(end 120.379236 -284.957266)
		(width 0.1143)
		(layer "In6.Cu")
		(net "P5E_CPU1_P2_RX_DP<8>")
	)
	(segment
		(start 138.16838 -323.934582)
		(end 133.620764 -315.42736)
		(width 0.14224)
		(layer "In6.Cu")
		(net "P5E_CPU1_P2_RX_DP<8>")
	)
	(segment
		(start 120.317006 -290.791392)
		(end 120.386602 -290.750752)
		(width 0.1143)
		(layer "In6.Cu")
		(net "P5E_CPU1_P2_RX_DP<8>")
	)
	(segment
		(start 158.288736 -370.727732)
		(end 157.917896 -370.357146)
		(width 0.14224)
		(layer "In6.Cu")
		(net "P5E_CPU1_P2_RX_DP<8>")
	)
	(segment
		(start 121.148348 -296.353738)
		(end 121.148348 -296.32529)
		(width 0.1143)
		(layer "In6.Cu")
		(net "P5E_CPU1_P2_RX_DP<8>")
	)
	(segment
		(start 157.309058 -370.006626)
		(end 157.109668 -369.888516)
		(width 0.14224)
		(layer "In6.Cu")
		(net "P5E_CPU1_P2_RX_DP<8>")
	)
	(segment
		(start 120.341136 -284.935168)
		(end 120.339866 -284.934406)
		(width 0.1143)
		(layer "In6.Cu")
		(net "P5E_CPU1_P2_RX_DP<8>")
	)
	(segment
		(start 120.848882 -286.705802)
		(end 120.854724 -286.7025)
		(width 0.1143)
		(layer "In6.Cu")
		(net "P5E_CPU1_P2_RX_DP<8>")
	)
	(segment
		(start 157.569154 -370.124228)
		(end 157.422088 -370.063268)
		(width 0.14224)
		(layer "In6.Cu")
		(net "P5E_CPU1_P2_RX_DP<8>")
	)
	(segment
		(start 141.664436 -340.862158)
		(end 141.076426 -338.551774)
		(width 0.14224)
		(layer "In6.Cu")
		(net "P5E_CPU1_P2_RX_DP<8>")
	)
	(segment
		(start 120.345708 -287.535112)
		(end 120.346978 -287.53435)
		(width 0.1143)
		(layer "In6.Cu")
		(net "P5E_CPU1_P2_RX_DP<8>")
	)
	(segment
		(start 120.386602 -294.681656)
		(end 120.317006 -294.641016)
		(width 0.1143)
		(layer "In6.Cu")
		(net "P5E_CPU1_P2_RX_DP<8>")
	)
	(segment
		(start 120.350534 -284.940502)
		(end 120.348756 -284.939486)
		(width 0.1143)
		(layer "In6.Cu")
		(net "P5E_CPU1_P2_RX_DP<8>")
	)
	(segment
		(start 145.444972 -350.147636)
		(end 143.665956 -347.001846)
		(width 0.14224)
		(layer "In6.Cu")
		(net "P5E_CPU1_P2_RX_DP<8>")
	)
	(segment
		(start 121.928128 -299.687742)
		(end 121.266204 -298.089828)
		(width 0.14224)
		(layer "In6.Cu")
		(net "P5E_CPU1_P2_RX_DP<8>")
	)
	(segment
		(start 158.566612 -371.474746)
		(end 158.391098 -370.898166)
		(width 0.14224)
		(layer "In6.Cu")
		(net "P5E_CPU1_P2_RX_DP<8>")
	)
	(segment
		(start 125.076966 -304.400204)
		(end 121.928128 -299.687742)
		(width 0.14224)
		(layer "In6.Cu")
		(net "P5E_CPU1_P2_RX_DP<8>")
	)
	(segment
		(start 120.352058 -284.941518)
		(end 120.350534 -284.940502)
		(width 0.1143)
		(layer "In6.Cu")
		(net "P5E_CPU1_P2_RX_DP<8>")
	)
	(segment
		(start 120.854724 -286.7025)
		(end 120.856756 -286.700976)
		(width 0.1143)
		(layer "In6.Cu")
		(net "P5E_CPU1_P2_RX_DP<8>")
	)
	(segment
		(start 120.337326 -284.933136)
		(end 120.31599 -284.92069)
		(width 0.1143)
		(layer "In6.Cu")
		(net "P5E_CPU1_P2_RX_DP<8>")
	)
	(segment
		(start 120.346978 -284.93847)
		(end 120.344184 -284.936946)
		(width 0.1143)
		(layer "In6.Cu")
		(net "P5E_CPU1_P2_RX_DP<8>")
	)
	(segment
		(start 157.76829 -380.322328)
		(end 158.046928 -373.75592)
		(width 0.14224)
		(layer "In6.Cu")
		(net "P5E_CPU1_P2_RX_DP<8>")
	)
	(segment
		(start 142.223998 -342.884252)
		(end 141.664436 -340.862158)
		(width 0.14224)
		(layer "In6.Cu")
		(net "P5E_CPU1_P2_RX_DP<8>")
	)
	(segment
		(start 133.620764 -315.42736)
		(end 131.409694 -312.11647)
		(width 0.14224)
		(layer "In6.Cu")
		(net "P5E_CPU1_P2_RX_DP<8>")
	)
	(segment
		(start 120.847104 -286.706818)
		(end 120.84812 -286.70631)
		(width 0.1143)
		(layer "In6.Cu")
		(net "P5E_CPU1_P2_RX_DP<8>")
	)
	(segment
		(start 128.234186 -308.247288)
		(end 125.076966 -304.400204)
		(width 0.14224)
		(layer "In6.Cu")
		(net "P5E_CPU1_P2_RX_DP<8>")
	)
	(segment
		(start 120.317006 -294.031416)
		(end 120.386602 -293.990776)
		(width 0.1143)
		(layer "In6.Cu")
		(net "P5E_CPU1_P2_RX_DP<8>")
	)
	(segment
		(start 120.379236 -284.957266)
		(end 120.354598 -284.943042)
		(width 0.1143)
		(layer "In6.Cu")
		(net "P5E_CPU1_P2_RX_DP<8>")
	)
	(segment
		(start 120.352058 -287.531302)
		(end 120.35282 -287.530794)
		(width 0.1143)
		(layer "In6.Cu")
		(net "P5E_CPU1_P2_RX_DP<8>")
	)
	(segment
		(start 157.46349 -384.3528)
		(end 157.76829 -384.048)
		(width 0.14224)
		(layer "In6.Cu")
		(net "P5E_CPU1_P2_RX_DP<8>")
	)
	(segment
		(start 120.166892 -284.686248)
		(end 120.236742 -284.616398)
		(width 0.1143)
		(layer "In6.Cu")
		(net "P5E_CPU1_P2_RX_DP<8>")
	)
	(segment
		(start 120.353074 -284.942026)
		(end 120.352058 -284.941518)
		(width 0.1143)
		(layer "In6.Cu")
		(net "P5E_CPU1_P2_RX_DP<8>")
	)
	(segment
		(start 141.076426 -338.551774)
		(end 138.16838 -323.934582)
		(width 0.14224)
		(layer "In6.Cu")
		(net "P5E_CPU1_P2_RX_DP<8>")
	)
	(segment
		(start 120.34774 -284.938978)
		(end 120.346978 -284.93847)
		(width 0.1143)
		(layer "In6.Cu")
		(net "P5E_CPU1_P2_RX_DP<8>")
	)
	(segment
		(start 120.31599 -287.55213)
		(end 120.344184 -287.535874)
		(width 0.1143)
		(layer "In6.Cu")
		(net "P5E_CPU1_P2_RX_DP<8>")
	)
	(segment
		(start 120.81764 -286.723836)
		(end 120.846342 -286.707326)
		(width 0.1143)
		(layer "In6.Cu")
		(net "P5E_CPU1_P2_RX_DP<8>")
	)
	(segment
		(start 120.34774 -287.533842)
		(end 120.348756 -287.533334)
		(width 0.1143)
		(layer "In6.Cu")
		(net "P5E_CPU1_P2_RX_DP<8>")
	)
	(segment
		(start 121.102628 -296.009568)
		(end 121.100088 -296.007028)
		(width 0.1143)
		(layer "In6.Cu")
		(net "P5E_CPU1_P2_RX_DP<8>")
	)
	(segment
		(start 157.68828 -385.548632)
		(end 157.776418 -385.460494)
		(width 0.14224)
		(layer "In6.Cu")
		(net "P5E_CPU1_P2_RX_DP<8>")
	)
	(segment
		(start 121.148348 -297.498008)
		(end 121.148348 -296.353738)
		(width 0.14224)
		(layer "In6.Cu")
		(net "P5E_CPU1_P2_RX_DP<8>")
	)
	(segment
		(start 120.347486 -288.178748)
		(end 120.314974 -288.159952)
		(width 0.1143)
		(layer "In6.Cu")
		(net "P5E_CPU1_P2_RX_DP<8>")
	)
	(segment
		(start 148.294852 -354.955348)
		(end 146.868134 -352.699574)
		(width 0.14224)
		(layer "In6.Cu")
		(net "P5E_CPU1_P2_RX_DP<8>")
	)
	(arc
		(start 121.100088 -295.956228)
		(mid 121.035627 -295.693983)
		(end 120.856756 -295.491662)
		(width 0.1143)
		(layer "In6.Cu")
		(net "P5E_CPU1_P2_RX_DP<8>")
	)
	(arc
		(start 157.012386 -369.807236)
		(mid 156.923747 -369.684515)
		(end 156.855922 -369.549172)
		(width 0.14224)
		(layer "In6.Cu")
		(net "P5E_CPU1_P2_RX_DP<8>")
	)
	(arc
		(start 120.31599 -284.92069)
		(mid 120.218855 -284.817821)
		(end 120.166892 -284.686248)
		(width 0.1143)
		(layer "In6.Cu")
		(net "P5E_CPU1_P2_RX_DP<8>")
	)
	(arc
		(start 120.386602 -289.13074)
		(mid 120.629929 -288.666174)
		(end 120.386602 -288.201608)
		(width 0.1143)
		(layer "In6.Cu")
		(net "P5E_CPU1_P2_RX_DP<8>")
	)
	(arc
		(start 156.830014 -367.853214)
		(mid 156.812561 -367.734472)
		(end 156.761434 -367.625884)
		(width 0.14224)
		(layer "In6.Cu")
		(net "P5E_CPU1_P2_RX_DP<8>")
	)
	(arc
		(start 157.422088 -370.063268)
		(mid 157.364561 -370.036965)
		(end 157.309058 -370.006626)
		(width 0.14224)
		(layer "In6.Cu")
		(net "P5E_CPU1_P2_RX_DP<8>")
	)
	(arc
		(start 120.630188 -287.046162)
		(mid 120.671154 -286.875756)
		(end 120.785128 -286.742632)
		(width 0.1143)
		(layer "In6.Cu")
		(net "P5E_CPU1_P2_RX_DP<8>")
	)
	(arc
		(start 120.856756 -286.700976)
		(mid 121.100083 -286.23641)
		(end 120.856756 -285.771844)
		(width 0.1143)
		(layer "In6.Cu")
		(net "P5E_CPU1_P2_RX_DP<8>")
	)
	(arc
		(start 120.386602 -290.750752)
		(mid 120.629929 -290.286186)
		(end 120.386602 -289.82162)
		(width 0.1143)
		(layer "In6.Cu")
		(net "P5E_CPU1_P2_RX_DP<8>")
	)
	(arc
		(start 121.266204 -298.089828)
		(mid 121.178121 -297.799724)
		(end 121.148348 -297.498008)
		(width 0.14224)
		(layer "In6.Cu")
		(net "P5E_CPU1_P2_RX_DP<8>")
	)
	(arc
		(start 120.317006 -291.400992)
		(mid 120.160029 -291.096192)
		(end 120.317006 -290.791392)
		(width 0.1143)
		(layer "In6.Cu")
		(net "P5E_CPU1_P2_RX_DP<8>")
	)
	(arc
		(start 120.384316 -287.512506)
		(mid 120.564968 -287.309761)
		(end 120.630188 -287.046162)
		(width 0.1143)
		(layer "In6.Cu")
		(net "P5E_CPU1_P2_RX_DP<8>")
	)
	(arc
		(start 120.317006 -294.641016)
		(mid 120.160029 -294.336216)
		(end 120.317006 -294.031416)
		(width 0.1143)
		(layer "In6.Cu")
		(net "P5E_CPU1_P2_RX_DP<8>")
	)
	(arc
		(start 120.78716 -295.451022)
		(mid 120.671733 -295.317646)
		(end 120.630188 -295.146222)
		(width 0.1143)
		(layer "In6.Cu")
		(net "P5E_CPU1_P2_RX_DP<8>")
	)
	(arc
		(start 158.391098 -370.898166)
		(mid 158.350395 -370.806658)
		(end 158.288736 -370.727732)
		(width 0.14224)
		(layer "In6.Cu")
		(net "P5E_CPU1_P2_RX_DP<8>")
	)
	(arc
		(start 120.317006 -289.78098)
		(mid 120.160029 -289.47618)
		(end 120.317006 -289.17138)
		(width 0.1143)
		(layer "In6.Cu")
		(net "P5E_CPU1_P2_RX_DP<8>")
	)
	(arc
		(start 120.314974 -288.159952)
		(mid 120.201045 -288.026805)
		(end 120.160034 -287.856422)
		(width 0.1143)
		(layer "In6.Cu")
		(net "P5E_CPU1_P2_RX_DP<8>")
	)
	(arc
		(start 157.109668 -369.888516)
		(mid 157.057679 -369.851884)
		(end 157.012386 -369.807236)
		(width 0.14224)
		(layer "In6.Cu")
		(net "P5E_CPU1_P2_RX_DP<8>")
	)
	(arc
		(start 120.386602 -293.990776)
		(mid 120.629929 -293.52621)
		(end 120.386602 -293.061644)
		(width 0.1143)
		(layer "In6.Cu")
		(net "P5E_CPU1_P2_RX_DP<8>")
	)
	(arc
		(start 120.160034 -287.856422)
		(mid 120.201289 -287.685451)
		(end 120.31599 -287.55213)
		(width 0.1143)
		(layer "In6.Cu")
		(net "P5E_CPU1_P2_RX_DP<8>")
	)
	(arc
		(start 156.855922 -369.549172)
		(mid 156.83657 -369.484129)
		(end 156.830014 -369.416584)
		(width 0.14224)
		(layer "In6.Cu")
		(net "P5E_CPU1_P2_RX_DP<8>")
	)
	(arc
		(start 120.78716 -285.731204)
		(mid 120.671733 -285.597828)
		(end 120.630188 -285.426404)
		(width 0.1143)
		(layer "In6.Cu")
		(net "P5E_CPU1_P2_RX_DP<8>")
	)
	(arc
		(start 120.629934 -295.146222)
		(mid 120.565419 -294.884003)
		(end 120.386602 -294.681656)
		(width 0.1143)
		(layer "In6.Cu")
		(net "P5E_CPU1_P2_RX_DP<8>")
	)
	(arc
		(start 157.917896 -370.357146)
		(mid 157.75502 -370.223474)
		(end 157.569154 -370.124228)
		(width 0.14224)
		(layer "In6.Cu")
		(net "P5E_CPU1_P2_RX_DP<8>")
	)
	(arc
		(start 120.317006 -293.021004)
		(mid 120.160029 -292.716204)
		(end 120.317006 -292.411404)
		(width 0.1143)
		(layer "In6.Cu")
		(net "P5E_CPU1_P2_RX_DP<8>")
	)
	(arc
		(start 158.571946 -371.731032)
		(mid 158.586971 -371.602523)
		(end 158.566612 -371.474746)
		(width 0.14224)
		(layer "In6.Cu")
		(net "P5E_CPU1_P2_RX_DP<8>")
	)
	(arc
		(start 120.386602 -292.370764)
		(mid 120.629929 -291.906198)
		(end 120.386602 -291.441632)
		(width 0.1143)
		(layer "In6.Cu")
		(net "P5E_CPU1_P2_RX_DP<8>")
	)
	(arc
		(start 120.630188 -285.426404)
		(mid 120.565673 -285.164185)
		(end 120.386856 -284.961838)
		(width 0.1143)
		(layer "In6.Cu")
		(net "P5E_CPU1_P2_RX_DP<8>")
	)
	(segment
		(start 120.067832 -285.970472)
		(end 120.534684 -286.23641)
		(width 0.12954)
		(layer "F.Cu")
		(net "P5E_CPU1_P2_RX_DP<7>")
	)
	(segment
		(start 155.69819 -386.003292)
		(end 156.21889 -386.003292)
		(width 0.127)
		(layer "F.Cu")
		(net "P5E_CPU1_P2_RX_DP<7>")
	)
	(segment
		(start 119.401336 -287.537398)
		(end 119.402098 -287.53689)
		(width 0.1143)
		(layer "In6.Cu")
		(net "P5E_CPU1_P2_RX_DP<7>")
	)
	(segment
		(start 120.216168 -296.353738)
		(end 120.216168 -296.32529)
		(width 0.1143)
		(layer "In6.Cu")
		(net "P5E_CPU1_P2_RX_DP<7>")
	)
	(segment
		(start 119.446548 -289.82162)
		(end 119.376952 -289.78098)
		(width 0.1143)
		(layer "In6.Cu")
		(net "P5E_CPU1_P2_RX_DP<7>")
	)
	(segment
		(start 119.378984 -289.170364)
		(end 119.380508 -289.169348)
		(width 0.1143)
		(layer "In6.Cu")
		(net "P5E_CPU1_P2_RX_DP<7>")
	)
	(segment
		(start 119.385334 -289.166554)
		(end 119.38762 -289.16503)
		(width 0.1143)
		(layer "In6.Cu")
		(net "P5E_CPU1_P2_RX_DP<7>")
	)
	(segment
		(start 156.48813 -385.548632)
		(end 156.576268 -385.460494)
		(width 0.14224)
		(layer "In6.Cu")
		(net "P5E_CPU1_P2_RX_DP<7>")
	)
	(segment
		(start 119.376952 -289.17138)
		(end 119.378984 -289.170364)
		(width 0.1143)
		(layer "In6.Cu")
		(net "P5E_CPU1_P2_RX_DP<7>")
	)
	(segment
		(start 120.983502 -299.952918)
		(end 120.37822 -298.491402)
		(width 0.14224)
		(layer "In6.Cu")
		(net "P5E_CPU1_P2_RX_DP<7>")
	)
	(segment
		(start 156.26334 -384.3528)
		(end 156.56814 -384.048)
		(width 0.14224)
		(layer "In6.Cu")
		(net "P5E_CPU1_P2_RX_DP<7>")
	)
	(segment
		(start 120.216168 -297.676316)
		(end 120.216168 -296.353738)
		(width 0.14224)
		(layer "In6.Cu")
		(net "P5E_CPU1_P2_RX_DP<7>")
	)
	(segment
		(start 156.56814 -384.048)
		(end 156.56814 -381.775208)
		(width 0.14224)
		(layer "In6.Cu")
		(net "P5E_CPU1_P2_RX_DP<7>")
	)
	(segment
		(start 119.690134 -295.146222)
		(end 119.68988 -295.146222)
		(width 0.1143)
		(layer "In6.Cu")
		(net "P5E_CPU1_P2_RX_DP<7>")
	)
	(segment
		(start 119.38254 -289.168332)
		(end 119.384064 -289.167316)
		(width 0.1143)
		(layer "In6.Cu")
		(net "P5E_CPU1_P2_RX_DP<7>")
	)
	(segment
		(start 119.446802 -288.201608)
		(end 119.374158 -288.15919)
		(width 0.1143)
		(layer "In6.Cu")
		(net "P5E_CPU1_P2_RX_DP<7>")
	)
	(segment
		(start 156.576268 -385.046982)
		(end 156.260292 -384.731006)
		(width 0.14224)
		(layer "In6.Cu")
		(net "P5E_CPU1_P2_RX_DP<7>")
	)
	(segment
		(start 119.407686 -287.533842)
		(end 119.408702 -287.533334)
		(width 0.1143)
		(layer "In6.Cu")
		(net "P5E_CPU1_P2_RX_DP<7>")
	)
	(segment
		(start 119.877586 -295.468802)
		(end 119.847106 -295.451022)
		(width 0.1143)
		(layer "In6.Cu")
		(net "P5E_CPU1_P2_RX_DP<7>")
	)
	(segment
		(start 119.405654 -287.535112)
		(end 119.406924 -287.53435)
		(width 0.1143)
		(layer "In6.Cu")
		(net "P5E_CPU1_P2_RX_DP<7>")
	)
	(segment
		(start 119.376952 -292.411404)
		(end 119.446548 -292.370764)
		(width 0.1143)
		(layer "In6.Cu")
		(net "P5E_CPU1_P2_RX_DP<7>")
	)
	(segment
		(start 156.576268 -385.460494)
		(end 156.576268 -385.046982)
		(width 0.14224)
		(layer "In6.Cu")
		(net "P5E_CPU1_P2_RX_DP<7>")
	)
	(segment
		(start 119.412766 -287.530794)
		(end 119.444262 -287.512506)
		(width 0.1143)
		(layer "In6.Cu")
		(net "P5E_CPU1_P2_RX_DP<7>")
	)
	(segment
		(start 132.804916 -315.924946)
		(end 130.73888 -312.833004)
		(width 0.14224)
		(layer "In6.Cu")
		(net "P5E_CPU1_P2_RX_DP<7>")
	)
	(segment
		(start 119.914162 -295.489884)
		(end 119.878602 -295.46931)
		(width 0.1143)
		(layer "In6.Cu")
		(net "P5E_CPU1_P2_RX_DP<7>")
	)
	(segment
		(start 139.737084 -337.443318)
		(end 137.028936 -323.828156)
		(width 0.14224)
		(layer "In6.Cu")
		(net "P5E_CPU1_P2_RX_DP<7>")
	)
	(segment
		(start 156.771594 -373.519954)
		(end 156.521658 -373.161052)
		(width 0.14224)
		(layer "In6.Cu")
		(net "P5E_CPU1_P2_RX_DP<7>")
	)
	(segment
		(start 137.028936 -323.828156)
		(end 132.804916 -315.924946)
		(width 0.14224)
		(layer "In6.Cu")
		(net "P5E_CPU1_P2_RX_DP<7>")
	)
	(segment
		(start 119.403368 -287.536382)
		(end 119.40413 -287.535874)
		(width 0.1143)
		(layer "In6.Cu")
		(net "P5E_CPU1_P2_RX_DP<7>")
	)
	(segment
		(start 120.16994 -296.007028)
		(end 120.16994 -295.966134)
		(width 0.1143)
		(layer "In6.Cu")
		(net "P5E_CPU1_P2_RX_DP<7>")
	)
	(segment
		(start 142.057882 -345.614244)
		(end 141.12748 -342.80475)
		(width 0.14224)
		(layer "In6.Cu")
		(net "P5E_CPU1_P2_RX_DP<7>")
	)
	(segment
		(start 154.727656 -367.468912)
		(end 147.569428 -355.839776)
		(width 0.14224)
		(layer "In6.Cu")
		(net "P5E_CPU1_P2_RX_DP<7>")
	)
	(segment
		(start 120.170448 -296.007536)
		(end 120.16994 -296.007028)
		(width 0.1143)
		(layer "In6.Cu")
		(net "P5E_CPU1_P2_RX_DP<7>")
	)
	(segment
		(start 130.73888 -312.833004)
		(end 124.55525 -305.298094)
		(width 0.14224)
		(layer "In6.Cu")
		(net "P5E_CPU1_P2_RX_DP<7>")
	)
	(segment
		(start 155.117292 -371.925342)
		(end 154.8003 -371.243606)
		(width 0.14224)
		(layer "In6.Cu")
		(net "P5E_CPU1_P2_RX_DP<7>")
	)
	(segment
		(start 142.842488 -347.545914)
		(end 142.057882 -345.614244)
		(width 0.14224)
		(layer "In6.Cu")
		(net "P5E_CPU1_P2_RX_DP<7>")
	)
	(segment
		(start 120.153938 -286.319214)
		(end 120.236742 -286.23641)
		(width 0.1143)
		(layer "In6.Cu")
		(net "P5E_CPU1_P2_RX_DP<7>")
	)
	(segment
		(start 119.446548 -293.061644)
		(end 119.376952 -293.021004)
		(width 0.1143)
		(layer "In6.Cu")
		(net "P5E_CPU1_P2_RX_DP<7>")
	)
	(segment
		(start 119.406924 -287.53435)
		(end 119.407686 -287.533842)
		(width 0.1143)
		(layer "In6.Cu")
		(net "P5E_CPU1_P2_RX_DP<7>")
	)
	(segment
		(start 120.236742 -286.23641)
		(end 120.534684 -286.23641)
		(width 0.1143)
		(layer "In6.Cu")
		(net "P5E_CPU1_P2_RX_DP<7>")
	)
	(segment
		(start 119.412004 -287.531302)
		(end 119.412766 -287.530794)
		(width 0.1143)
		(layer "In6.Cu")
		(net "P5E_CPU1_P2_RX_DP<7>")
	)
	(segment
		(start 156.033216 -372.696994)
		(end 155.516326 -372.375684)
		(width 0.14224)
		(layer "In6.Cu")
		(net "P5E_CPU1_P2_RX_DP<7>")
	)
	(segment
		(start 156.313886 -385.649216)
		(end 156.48813 -385.548632)
		(width 0.14224)
		(layer "In6.Cu")
		(net "P5E_CPU1_P2_RX_DP<7>")
	)
	(segment
		(start 119.380508 -289.169348)
		(end 119.38254 -289.168332)
		(width 0.1143)
		(layer "In6.Cu")
		(net "P5E_CPU1_P2_RX_DP<7>")
	)
	(segment
		(start 119.409972 -287.532572)
		(end 119.410734 -287.532064)
		(width 0.1143)
		(layer "In6.Cu")
		(net "P5E_CPU1_P2_RX_DP<7>")
	)
	(segment
		(start 119.446548 -294.681656)
		(end 119.376952 -294.641016)
		(width 0.1143)
		(layer "In6.Cu")
		(net "P5E_CPU1_P2_RX_DP<7>")
	)
	(segment
		(start 156.260292 -384.731006)
		(end 156.26334 -384.3528)
		(width 0.14224)
		(layer "In6.Cu")
		(net "P5E_CPU1_P2_RX_DP<7>")
	)
	(segment
		(start 119.375936 -287.55213)
		(end 119.401336 -287.537398)
		(width 0.1143)
		(layer "In6.Cu")
		(net "P5E_CPU1_P2_RX_DP<7>")
	)
	(segment
		(start 119.384064 -289.167316)
		(end 119.385334 -289.166554)
		(width 0.1143)
		(layer "In6.Cu")
		(net "P5E_CPU1_P2_RX_DP<7>")
	)
	(segment
		(start 119.38762 -289.16503)
		(end 119.446802 -289.13074)
		(width 0.1143)
		(layer "In6.Cu")
		(net "P5E_CPU1_P2_RX_DP<7>")
	)
	(segment
		(start 119.410734 -287.532064)
		(end 119.412004 -287.531302)
		(width 0.1143)
		(layer "In6.Cu")
		(net "P5E_CPU1_P2_RX_DP<7>")
	)
	(segment
		(start 119.878602 -295.46931)
		(end 119.87784 -295.468802)
		(width 0.1143)
		(layer "In6.Cu")
		(net "P5E_CPU1_P2_RX_DP<7>")
	)
	(segment
		(start 141.12748 -342.80475)
		(end 139.737084 -337.443318)
		(width 0.14224)
		(layer "In6.Cu")
		(net "P5E_CPU1_P2_RX_DP<7>")
	)
	(segment
		(start 119.376952 -290.791392)
		(end 119.446548 -290.750752)
		(width 0.1143)
		(layer "In6.Cu")
		(net "P5E_CPU1_P2_RX_DP<7>")
	)
	(segment
		(start 147.569428 -355.839776)
		(end 142.842488 -347.545914)
		(width 0.14224)
		(layer "In6.Cu")
		(net "P5E_CPU1_P2_RX_DP<7>")
	)
	(segment
		(start 119.446548 -291.441632)
		(end 119.376952 -291.400992)
		(width 0.1143)
		(layer "In6.Cu")
		(net "P5E_CPU1_P2_RX_DP<7>")
	)
	(segment
		(start 119.402098 -287.53689)
		(end 119.403368 -287.536382)
		(width 0.1143)
		(layer "In6.Cu")
		(net "P5E_CPU1_P2_RX_DP<7>")
	)
	(segment
		(start 119.376952 -294.031416)
		(end 119.446548 -293.990776)
		(width 0.1143)
		(layer "In6.Cu")
		(net "P5E_CPU1_P2_RX_DP<7>")
	)
	(segment
		(start 154.788362 -371.190012)
		(end 154.788362 -367.683542)
		(width 0.14224)
		(layer "In6.Cu")
		(net "P5E_CPU1_P2_RX_DP<7>")
	)
	(segment
		(start 119.408702 -287.533334)
		(end 119.409972 -287.532572)
		(width 0.1143)
		(layer "In6.Cu")
		(net "P5E_CPU1_P2_RX_DP<7>")
	)
	(segment
		(start 124.55525 -305.298094)
		(end 120.983502 -299.952918)
		(width 0.14224)
		(layer "In6.Cu")
		(net "P5E_CPU1_P2_RX_DP<7>")
	)
	(segment
		(start 119.845074 -286.742632)
		(end 119.916702 -286.700976)
		(width 0.1143)
		(layer "In6.Cu")
		(net "P5E_CPU1_P2_RX_DP<7>")
	)
	(segment
		(start 156.56814 -381.775208)
		(end 156.904182 -373.9769)
		(width 0.14224)
		(layer "In6.Cu")
		(net "P5E_CPU1_P2_RX_DP<7>")
	)
	(segment
		(start 120.216168 -296.32529)
		(end 120.170448 -296.27957)
		(width 0.1143)
		(layer "In6.Cu")
		(net "P5E_CPU1_P2_RX_DP<7>")
	)
	(segment
		(start 119.40413 -287.535874)
		(end 119.405654 -287.535112)
		(width 0.1143)
		(layer "In6.Cu")
		(net "P5E_CPU1_P2_RX_DP<7>")
	)
	(segment
		(start 120.170448 -296.27957)
		(end 120.170448 -296.007536)
		(width 0.1143)
		(layer "In6.Cu")
		(net "P5E_CPU1_P2_RX_DP<7>")
	)
	(segment
		(start 156.21889 -386.003292)
		(end 156.313886 -385.649216)
		(width 0.14224)
		(layer "In6.Cu")
		(net "P5E_CPU1_P2_RX_DP<7>")
	)
	(segment
		(start 119.87784 -295.468802)
		(end 119.877586 -295.468802)
		(width 0.1143)
		(layer "In6.Cu")
		(net "P5E_CPU1_P2_RX_DP<7>")
	)
	(arc
		(start 119.376952 -294.641016)
		(mid 119.219975 -294.336216)
		(end 119.376952 -294.031416)
		(width 0.1143)
		(layer "In6.Cu")
		(net "P5E_CPU1_P2_RX_DP<7>")
	)
	(arc
		(start 119.68988 -295.146222)
		(mid 119.625365 -294.884003)
		(end 119.446548 -294.681656)
		(width 0.1143)
		(layer "In6.Cu")
		(net "P5E_CPU1_P2_RX_DP<7>")
	)
	(arc
		(start 120.37822 -298.491402)
		(mid 120.257041 -298.09184)
		(end 120.216168 -297.676316)
		(width 0.14224)
		(layer "In6.Cu")
		(net "P5E_CPU1_P2_RX_DP<7>")
	)
	(arc
		(start 119.21998 -287.856422)
		(mid 119.262112 -287.685917)
		(end 119.375936 -287.55213)
		(width 0.1143)
		(layer "In6.Cu")
		(net "P5E_CPU1_P2_RX_DP<7>")
	)
	(arc
		(start 119.376952 -291.400992)
		(mid 119.219975 -291.096192)
		(end 119.376952 -290.791392)
		(width 0.1143)
		(layer "In6.Cu")
		(net "P5E_CPU1_P2_RX_DP<7>")
	)
	(arc
		(start 120.16994 -295.966134)
		(mid 120.10196 -295.702043)
		(end 119.923052 -295.496234)
		(width 0.1143)
		(layer "In6.Cu")
		(net "P5E_CPU1_P2_RX_DP<7>")
	)
	(arc
		(start 154.8003 -371.243606)
		(mid 154.791381 -371.217464)
		(end 154.788362 -371.190012)
		(width 0.14224)
		(layer "In6.Cu")
		(net "P5E_CPU1_P2_RX_DP<7>")
	)
	(arc
		(start 119.446802 -289.13074)
		(mid 119.690129 -288.666174)
		(end 119.446802 -288.201608)
		(width 0.1143)
		(layer "In6.Cu")
		(net "P5E_CPU1_P2_RX_DP<7>")
	)
	(arc
		(start 119.376952 -293.021004)
		(mid 119.219975 -292.716204)
		(end 119.376952 -292.411404)
		(width 0.1143)
		(layer "In6.Cu")
		(net "P5E_CPU1_P2_RX_DP<7>")
	)
	(arc
		(start 119.444262 -287.512506)
		(mid 119.624914 -287.309761)
		(end 119.690134 -287.046162)
		(width 0.1143)
		(layer "In6.Cu")
		(net "P5E_CPU1_P2_RX_DP<7>")
	)
	(arc
		(start 156.904182 -373.9769)
		(mid 156.875381 -373.737555)
		(end 156.771594 -373.519954)
		(width 0.14224)
		(layer "In6.Cu")
		(net "P5E_CPU1_P2_RX_DP<7>")
	)
	(arc
		(start 119.923052 -295.496234)
		(mid 119.918623 -295.493037)
		(end 119.914162 -295.489884)
		(width 0.1143)
		(layer "In6.Cu")
		(net "P5E_CPU1_P2_RX_DP<7>")
	)
	(arc
		(start 119.847106 -295.451022)
		(mid 119.731679 -295.317646)
		(end 119.690134 -295.146222)
		(width 0.1143)
		(layer "In6.Cu")
		(net "P5E_CPU1_P2_RX_DP<7>")
	)
	(arc
		(start 156.521658 -373.161052)
		(mid 156.301088 -372.904129)
		(end 156.033216 -372.696994)
		(width 0.14224)
		(layer "In6.Cu")
		(net "P5E_CPU1_P2_RX_DP<7>")
	)
	(arc
		(start 120.150128 -286.342074)
		(mid 120.152151 -286.330664)
		(end 120.153938 -286.319214)
		(width 0.1143)
		(layer "In6.Cu")
		(net "P5E_CPU1_P2_RX_DP<7>")
	)
	(arc
		(start 154.788362 -367.683542)
		(mid 154.772883 -367.572024)
		(end 154.727656 -367.468912)
		(width 0.14224)
		(layer "In6.Cu")
		(net "P5E_CPU1_P2_RX_DP<7>")
	)
	(arc
		(start 119.446548 -290.750752)
		(mid 119.689875 -290.286186)
		(end 119.446548 -289.82162)
		(width 0.1143)
		(layer "In6.Cu")
		(net "P5E_CPU1_P2_RX_DP<7>")
	)
	(arc
		(start 119.690134 -287.046162)
		(mid 119.7311 -286.875756)
		(end 119.845074 -286.742632)
		(width 0.1143)
		(layer "In6.Cu")
		(net "P5E_CPU1_P2_RX_DP<7>")
	)
	(arc
		(start 119.916702 -286.700976)
		(mid 120.068689 -286.544468)
		(end 120.150128 -286.342074)
		(width 0.1143)
		(layer "In6.Cu")
		(net "P5E_CPU1_P2_RX_DP<7>")
	)
	(arc
		(start 119.446548 -293.990776)
		(mid 119.689875 -293.52621)
		(end 119.446548 -293.061644)
		(width 0.1143)
		(layer "In6.Cu")
		(net "P5E_CPU1_P2_RX_DP<7>")
	)
	(arc
		(start 155.516326 -372.375684)
		(mid 155.283979 -372.179603)
		(end 155.117292 -371.925342)
		(width 0.14224)
		(layer "In6.Cu")
		(net "P5E_CPU1_P2_RX_DP<7>")
	)
	(arc
		(start 119.374158 -288.15919)
		(mid 119.260751 -288.026301)
		(end 119.21998 -287.856422)
		(width 0.1143)
		(layer "In6.Cu")
		(net "P5E_CPU1_P2_RX_DP<7>")
	)
	(arc
		(start 119.376952 -289.78098)
		(mid 119.219975 -289.47618)
		(end 119.376952 -289.17138)
		(width 0.1143)
		(layer "In6.Cu")
		(net "P5E_CPU1_P2_RX_DP<7>")
	)
	(arc
		(start 119.446548 -292.370764)
		(mid 119.689875 -291.906198)
		(end 119.446548 -291.441632)
		(width 0.1143)
		(layer "In6.Cu")
		(net "P5E_CPU1_P2_RX_DP<7>")
	)
	(segment
		(start 154.498294 -386.003292)
		(end 155.018994 -386.003292)
		(width 0.127)
		(layer "F.Cu")
		(net "P5E_CPU1_P2_RX_DP<6>")
	)
	(segment
		(start 120.067832 -282.730448)
		(end 120.534684 -282.996386)
		(width 0.12954)
		(layer "F.Cu")
		(net "P5E_CPU1_P2_RX_DP<6>")
	)
	(segment
		(start 119.2657 -296.32529)
		(end 119.21998 -296.27957)
		(width 0.1143)
		(layer "In6.Cu")
		(net "P5E_CPU1_P2_RX_DP<6>")
	)
	(segment
		(start 118.506748 -289.82162)
		(end 118.437152 -289.78098)
		(width 0.1143)
		(layer "In6.Cu")
		(net "P5E_CPU1_P2_RX_DP<6>")
	)
	(segment
		(start 139.580366 -341.65286)
		(end 136.100312 -324.153276)
		(width 0.14224)
		(layer "In6.Cu")
		(net "P5E_CPU1_P2_RX_DP<6>")
	)
	(segment
		(start 118.437152 -294.031416)
		(end 118.506748 -293.990776)
		(width 0.1143)
		(layer "In6.Cu")
		(net "P5E_CPU1_P2_RX_DP<6>")
	)
	(segment
		(start 130.191256 -313.703208)
		(end 123.910344 -306.042314)
		(width 0.14224)
		(layer "In6.Cu")
		(net "P5E_CPU1_P2_RX_DP<6>")
	)
	(segment
		(start 118.94312 -295.47185)
		(end 118.942104 -295.471342)
		(width 0.1143)
		(layer "In6.Cu")
		(net "P5E_CPU1_P2_RX_DP<6>")
	)
	(segment
		(start 118.506748 -293.061644)
		(end 118.437152 -293.021004)
		(width 0.1143)
		(layer "In6.Cu")
		(net "P5E_CPU1_P2_RX_DP<6>")
	)
	(segment
		(start 153.442416 -367.964212)
		(end 142.627858 -349.387414)
		(width 0.14224)
		(layer "In6.Cu")
		(net "P5E_CPU1_P2_RX_DP<6>")
	)
	(segment
		(start 155.060396 -384.731006)
		(end 155.063444 -384.3528)
		(width 0.14224)
		(layer "In6.Cu")
		(net "P5E_CPU1_P2_RX_DP<6>")
	)
	(segment
		(start 119.406924 -284.294326)
		(end 119.407686 -284.293818)
		(width 0.1143)
		(layer "In6.Cu")
		(net "P5E_CPU1_P2_RX_DP<6>")
	)
	(segment
		(start 119.22379 -284.628336)
		(end 119.22379 -284.610556)
		(width 0.1143)
		(layer "In6.Cu")
		(net "P5E_CPU1_P2_RX_DP<6>")
	)
	(segment
		(start 153.386282 -373.700802)
		(end 153.53792 -371.272562)
		(width 0.14224)
		(layer "In6.Cu")
		(net "P5E_CPU1_P2_RX_DP<6>")
	)
	(segment
		(start 119.2657 -297.944286)
		(end 119.2657 -296.353738)
		(width 0.14224)
		(layer "In6.Cu")
		(net "P5E_CPU1_P2_RX_DP<6>")
	)
	(segment
		(start 141.306804 -346.721938)
		(end 139.580366 -341.65286)
		(width 0.14224)
		(layer "In6.Cu")
		(net "P5E_CPU1_P2_RX_DP<6>")
	)
	(segment
		(start 118.938802 -295.46931)
		(end 118.937786 -295.468802)
		(width 0.1143)
		(layer "In6.Cu")
		(net "P5E_CPU1_P2_RX_DP<6>")
	)
	(segment
		(start 118.437152 -289.17138)
		(end 118.506748 -289.13074)
		(width 0.1143)
		(layer "In6.Cu")
		(net "P5E_CPU1_P2_RX_DP<6>")
	)
	(segment
		(start 118.970044 -295.487598)
		(end 118.969282 -295.48709)
		(width 0.1143)
		(layer "In6.Cu")
		(net "P5E_CPU1_P2_RX_DP<6>")
	)
	(segment
		(start 118.942104 -295.471342)
		(end 118.94058 -295.470326)
		(width 0.1143)
		(layer "In6.Cu")
		(net "P5E_CPU1_P2_RX_DP<6>")
	)
	(segment
		(start 155.356814 -382.070356)
		(end 153.420826 -374.093486)
		(width 0.14224)
		(layer "In6.Cu")
		(net "P5E_CPU1_P2_RX_DP<6>")
	)
	(segment
		(start 118.437152 -292.411404)
		(end 118.506748 -292.370764)
		(width 0.1143)
		(layer "In6.Cu")
		(net "P5E_CPU1_P2_RX_DP<6>")
	)
	(segment
		(start 155.063444 -384.3528)
		(end 155.368244 -384.048254)
		(width 0.14224)
		(layer "In6.Cu")
		(net "P5E_CPU1_P2_RX_DP<6>")
	)
	(segment
		(start 118.937786 -285.104586)
		(end 118.956074 -285.093156)
		(width 0.1143)
		(layer "In6.Cu")
		(net "P5E_CPU1_P2_RX_DP<6>")
	)
	(segment
		(start 119.410734 -284.29204)
		(end 119.412512 -284.291024)
		(width 0.1143)
		(layer "In6.Cu")
		(net "P5E_CPU1_P2_RX_DP<6>")
	)
	(segment
		(start 118.944644 -295.472866)
		(end 118.94312 -295.47185)
		(width 0.1143)
		(layer "In6.Cu")
		(net "P5E_CPU1_P2_RX_DP<6>")
	)
	(segment
		(start 155.368244 -384.048254)
		(end 155.368244 -382.166622)
		(width 0.14224)
		(layer "In6.Cu")
		(net "P5E_CPU1_P2_RX_DP<6>")
	)
	(segment
		(start 118.467632 -288.178748)
		(end 118.43512 -288.159952)
		(width 0.1143)
		(layer "In6.Cu")
		(net "P5E_CPU1_P2_RX_DP<6>")
	)
	(segment
		(start 123.910344 -306.042314)
		(end 120.107202 -300.33849)
		(width 0.14224)
		(layer "In6.Cu")
		(net "P5E_CPU1_P2_RX_DP<6>")
	)
	(segment
		(start 119.409718 -284.292548)
		(end 119.410734 -284.29204)
		(width 0.1143)
		(layer "In6.Cu")
		(net "P5E_CPU1_P2_RX_DP<6>")
	)
	(segment
		(start 118.506748 -291.441632)
		(end 118.437152 -291.400992)
		(width 0.1143)
		(layer "In6.Cu")
		(net "P5E_CPU1_P2_RX_DP<6>")
	)
	(segment
		(start 118.936516 -285.105348)
		(end 118.937786 -285.104586)
		(width 0.1143)
		(layer "In6.Cu")
		(net "P5E_CPU1_P2_RX_DP<6>")
	)
	(segment
		(start 155.11399 -385.649216)
		(end 155.288234 -385.548632)
		(width 0.14224)
		(layer "In6.Cu")
		(net "P5E_CPU1_P2_RX_DP<6>")
	)
	(segment
		(start 153.53792 -371.272562)
		(end 153.53792 -368.318542)
		(width 0.14224)
		(layer "In6.Cu")
		(net "P5E_CPU1_P2_RX_DP<6>")
	)
	(segment
		(start 118.969282 -295.48709)
		(end 118.944644 -295.472866)
		(width 0.1143)
		(layer "In6.Cu")
		(net "P5E_CPU1_P2_RX_DP<6>")
	)
	(segment
		(start 119.220234 -296.086022)
		(end 119.220234 -295.956228)
		(width 0.1143)
		(layer "In6.Cu")
		(net "P5E_CPU1_P2_RX_DP<6>")
	)
	(segment
		(start 120.153938 -283.07919)
		(end 120.236742 -282.996386)
		(width 0.1143)
		(layer "In6.Cu")
		(net "P5E_CPU1_P2_RX_DP<6>")
	)
	(segment
		(start 155.288234 -385.548632)
		(end 155.376372 -385.460494)
		(width 0.14224)
		(layer "In6.Cu")
		(net "P5E_CPU1_P2_RX_DP<6>")
	)
	(segment
		(start 119.2657 -296.353738)
		(end 119.2657 -296.32529)
		(width 0.1143)
		(layer "In6.Cu")
		(net "P5E_CPU1_P2_RX_DP<6>")
	)
	(segment
		(start 119.21998 -296.086276)
		(end 119.220234 -296.086022)
		(width 0.1143)
		(layer "In6.Cu")
		(net "P5E_CPU1_P2_RX_DP<6>")
	)
	(segment
		(start 120.236742 -282.996386)
		(end 120.534684 -282.996386)
		(width 0.1143)
		(layer "In6.Cu")
		(net "P5E_CPU1_P2_RX_DP<6>")
	)
	(segment
		(start 118.506748 -294.681656)
		(end 118.437152 -294.641016)
		(width 0.1143)
		(layer "In6.Cu")
		(net "P5E_CPU1_P2_RX_DP<6>")
	)
	(segment
		(start 155.376372 -385.460494)
		(end 155.376372 -385.046982)
		(width 0.14224)
		(layer "In6.Cu")
		(net "P5E_CPU1_P2_RX_DP<6>")
	)
	(segment
		(start 119.847106 -283.501592)
		(end 119.916702 -283.460952)
		(width 0.1143)
		(layer "In6.Cu")
		(net "P5E_CPU1_P2_RX_DP<6>")
	)
	(segment
		(start 118.506748 -288.201608)
		(end 118.467632 -288.178748)
		(width 0.1143)
		(layer "In6.Cu")
		(net "P5E_CPU1_P2_RX_DP<6>")
	)
	(segment
		(start 118.938548 -285.747206)
		(end 118.937532 -285.746698)
		(width 0.1143)
		(layer "In6.Cu")
		(net "P5E_CPU1_P2_RX_DP<6>")
	)
	(segment
		(start 118.437152 -287.551622)
		(end 118.504208 -287.512506)
		(width 0.1143)
		(layer "In6.Cu")
		(net "P5E_CPU1_P2_RX_DP<6>")
	)
	(segment
		(start 118.94058 -295.470326)
		(end 118.938802 -295.46931)
		(width 0.1143)
		(layer "In6.Cu")
		(net "P5E_CPU1_P2_RX_DP<6>")
	)
	(segment
		(start 118.937786 -295.468802)
		(end 118.906036 -295.450514)
		(width 0.1143)
		(layer "In6.Cu")
		(net "P5E_CPU1_P2_RX_DP<6>")
	)
	(segment
		(start 142.627858 -349.387414)
		(end 141.306804 -346.721938)
		(width 0.14224)
		(layer "In6.Cu")
		(net "P5E_CPU1_P2_RX_DP<6>")
	)
	(segment
		(start 136.01573 -323.916802)
		(end 132.0165 -316.43574)
		(width 0.14224)
		(layer "In6.Cu")
		(net "P5E_CPU1_P2_RX_DP<6>")
	)
	(segment
		(start 155.376372 -385.046982)
		(end 155.060396 -384.731006)
		(width 0.14224)
		(layer "In6.Cu")
		(net "P5E_CPU1_P2_RX_DP<6>")
	)
	(segment
		(start 118.976902 -295.491662)
		(end 118.970044 -295.487598)
		(width 0.1143)
		(layer "In6.Cu")
		(net "P5E_CPU1_P2_RX_DP<6>")
	)
	(segment
		(start 155.018994 -386.003292)
		(end 155.11399 -385.649216)
		(width 0.14224)
		(layer "In6.Cu")
		(net "P5E_CPU1_P2_RX_DP<6>")
	)
	(segment
		(start 118.904258 -286.743394)
		(end 118.974108 -286.702754)
		(width 0.1143)
		(layer "In6.Cu")
		(net "P5E_CPU1_P2_RX_DP<6>")
	)
	(segment
		(start 118.437152 -290.791392)
		(end 118.506748 -290.750752)
		(width 0.1143)
		(layer "In6.Cu")
		(net "P5E_CPU1_P2_RX_DP<6>")
	)
	(segment
		(start 119.408702 -284.29331)
		(end 119.409718 -284.292548)
		(width 0.1143)
		(layer "In6.Cu")
		(net "P5E_CPU1_P2_RX_DP<6>")
	)
	(segment
		(start 119.407686 -284.293818)
		(end 119.408702 -284.29331)
		(width 0.1143)
		(layer "In6.Cu")
		(net "P5E_CPU1_P2_RX_DP<6>")
	)
	(segment
		(start 119.21998 -296.27957)
		(end 119.21998 -296.086276)
		(width 0.1143)
		(layer "In6.Cu")
		(net "P5E_CPU1_P2_RX_DP<6>")
	)
	(segment
		(start 120.107202 -300.33849)
		(end 119.399304 -298.619164)
		(width 0.14224)
		(layer "In6.Cu")
		(net "P5E_CPU1_P2_RX_DP<6>")
	)
	(segment
		(start 132.0165 -316.43574)
		(end 130.191256 -313.703208)
		(width 0.14224)
		(layer "In6.Cu")
		(net "P5E_CPU1_P2_RX_DP<6>")
	)
	(arc
		(start 118.437152 -293.021004)
		(mid 118.280175 -292.716204)
		(end 118.437152 -292.411404)
		(width 0.1143)
		(layer "In6.Cu")
		(net "P5E_CPU1_P2_RX_DP<6>")
	)
	(arc
		(start 119.412512 -284.291024)
		(mid 119.6158 -284.085646)
		(end 119.690134 -283.806392)
		(width 0.1143)
		(layer "In6.Cu")
		(net "P5E_CPU1_P2_RX_DP<6>")
	)
	(arc
		(start 118.43512 -288.159952)
		(mid 118.321191 -288.026805)
		(end 118.28018 -287.856422)
		(width 0.1143)
		(layer "In6.Cu")
		(net "P5E_CPU1_P2_RX_DP<6>")
	)
	(arc
		(start 119.399304 -298.619164)
		(mid 119.299436 -298.28827)
		(end 119.2657 -297.944286)
		(width 0.14224)
		(layer "In6.Cu")
		(net "P5E_CPU1_P2_RX_DP<6>")
	)
	(arc
		(start 153.53792 -368.318542)
		(mid 153.513665 -368.135042)
		(end 153.442416 -367.964212)
		(width 0.14224)
		(layer "In6.Cu")
		(net "P5E_CPU1_P2_RX_DP<6>")
	)
	(arc
		(start 119.120666 -295.63568)
		(mid 119.055314 -295.557153)
		(end 118.976902 -295.491662)
		(width 0.1143)
		(layer "In6.Cu")
		(net "P5E_CPU1_P2_RX_DP<6>")
	)
	(arc
		(start 118.75008 -287.046162)
		(mid 118.790842 -286.876278)
		(end 118.904258 -286.743394)
		(width 0.1143)
		(layer "In6.Cu")
		(net "P5E_CPU1_P2_RX_DP<6>")
	)
	(arc
		(start 119.690134 -283.806392)
		(mid 119.731683 -283.63497)
		(end 119.847106 -283.501592)
		(width 0.1143)
		(layer "In6.Cu")
		(net "P5E_CPU1_P2_RX_DP<6>")
	)
	(arc
		(start 118.75008 -295.146222)
		(mid 118.685565 -294.884003)
		(end 118.506748 -294.681656)
		(width 0.1143)
		(layer "In6.Cu")
		(net "P5E_CPU1_P2_RX_DP<6>")
	)
	(arc
		(start 118.506748 -290.750752)
		(mid 118.750075 -290.286186)
		(end 118.506748 -289.82162)
		(width 0.1143)
		(layer "In6.Cu")
		(net "P5E_CPU1_P2_RX_DP<6>")
	)
	(arc
		(start 118.28018 -287.856422)
		(mid 118.321729 -287.685)
		(end 118.437152 -287.551622)
		(width 0.1143)
		(layer "In6.Cu")
		(net "P5E_CPU1_P2_RX_DP<6>")
	)
	(arc
		(start 118.906036 -295.450514)
		(mid 118.79136 -295.31718)
		(end 118.75008 -295.146222)
		(width 0.1143)
		(layer "In6.Cu")
		(net "P5E_CPU1_P2_RX_DP<6>")
	)
	(arc
		(start 153.420826 -374.093486)
		(mid 153.388789 -373.898444)
		(end 153.386282 -373.700802)
		(width 0.14224)
		(layer "In6.Cu")
		(net "P5E_CPU1_P2_RX_DP<6>")
	)
	(arc
		(start 119.22379 -284.610556)
		(mid 119.272887 -284.427854)
		(end 119.406924 -284.294326)
		(width 0.1143)
		(layer "In6.Cu")
		(net "P5E_CPU1_P2_RX_DP<6>")
	)
	(arc
		(start 118.437152 -289.78098)
		(mid 118.280175 -289.47618)
		(end 118.437152 -289.17138)
		(width 0.1143)
		(layer "In6.Cu")
		(net "P5E_CPU1_P2_RX_DP<6>")
	)
	(arc
		(start 120.150128 -283.10205)
		(mid 120.152151 -283.09064)
		(end 120.153938 -283.07919)
		(width 0.1143)
		(layer "In6.Cu")
		(net "P5E_CPU1_P2_RX_DP<6>")
	)
	(arc
		(start 118.437152 -294.641016)
		(mid 118.280175 -294.336216)
		(end 118.437152 -294.031416)
		(width 0.1143)
		(layer "In6.Cu")
		(net "P5E_CPU1_P2_RX_DP<6>")
	)
	(arc
		(start 136.100312 -324.153276)
		(mid 136.066733 -324.031922)
		(end 136.01573 -323.916802)
		(width 0.14224)
		(layer "In6.Cu")
		(net "P5E_CPU1_P2_RX_DP<6>")
	)
	(arc
		(start 118.974108 -286.702754)
		(mid 119.219707 -286.215154)
		(end 118.938548 -285.747206)
		(width 0.1143)
		(layer "In6.Cu")
		(net "P5E_CPU1_P2_RX_DP<6>")
	)
	(arc
		(start 118.506748 -292.370764)
		(mid 118.750075 -291.906198)
		(end 118.506748 -291.441632)
		(width 0.1143)
		(layer "In6.Cu")
		(net "P5E_CPU1_P2_RX_DP<6>")
	)
	(arc
		(start 118.504208 -287.512506)
		(mid 118.68486 -287.309761)
		(end 118.75008 -287.046162)
		(width 0.1143)
		(layer "In6.Cu")
		(net "P5E_CPU1_P2_RX_DP<6>")
	)
	(arc
		(start 118.437152 -291.400992)
		(mid 118.280175 -291.096192)
		(end 118.437152 -290.791392)
		(width 0.1143)
		(layer "In6.Cu")
		(net "P5E_CPU1_P2_RX_DP<6>")
	)
	(arc
		(start 119.220234 -295.956228)
		(mid 119.194814 -295.788383)
		(end 119.120666 -295.63568)
		(width 0.1143)
		(layer "In6.Cu")
		(net "P5E_CPU1_P2_RX_DP<6>")
	)
	(arc
		(start 118.956074 -285.093156)
		(mid 119.152046 -284.896527)
		(end 119.22379 -284.628336)
		(width 0.1143)
		(layer "In6.Cu")
		(net "P5E_CPU1_P2_RX_DP<6>")
	)
	(arc
		(start 118.506748 -293.990776)
		(mid 118.750075 -293.52621)
		(end 118.506748 -293.061644)
		(width 0.1143)
		(layer "In6.Cu")
		(net "P5E_CPU1_P2_RX_DP<6>")
	)
	(arc
		(start 118.937532 -285.746698)
		(mid 118.751946 -285.426273)
		(end 118.936516 -285.105348)
		(width 0.1143)
		(layer "In6.Cu")
		(net "P5E_CPU1_P2_RX_DP<6>")
	)
	(arc
		(start 155.368244 -382.166622)
		(mid 155.365391 -382.118149)
		(end 155.356814 -382.070356)
		(width 0.14224)
		(layer "In6.Cu")
		(net "P5E_CPU1_P2_RX_DP<6>")
	)
	(arc
		(start 119.916702 -283.460952)
		(mid 120.068689 -283.304444)
		(end 120.150128 -283.10205)
		(width 0.1143)
		(layer "In6.Cu")
		(net "P5E_CPU1_P2_RX_DP<6>")
	)
	(arc
		(start 118.506748 -289.13074)
		(mid 118.750075 -288.666174)
		(end 118.506748 -288.201608)
		(width 0.1143)
		(layer "In6.Cu")
		(net "P5E_CPU1_P2_RX_DP<6>")
	)
	(segment
		(start 117.247924 -284.35046)
		(end 117.714776 -284.616398)
		(width 0.12954)
		(layer "F.Cu")
		(net "P5E_CPU1_P2_RX_DP<5>")
	)
	(segment
		(start 153.298398 -386.003292)
		(end 153.819098 -386.003292)
		(width 0.127)
		(layer "F.Cu")
		(net "P5E_CPU1_P2_RX_DP<5>")
	)
	(segment
		(start 154.112214 -381.766064)
		(end 151.724614 -373.515128)
		(width 0.14224)
		(layer "In6.Cu")
		(net "P5E_CPU1_P2_RX_DP<5>")
	)
	(segment
		(start 118.003066 -295.47185)
		(end 118.00205 -295.471342)
		(width 0.1143)
		(layer "In6.Cu")
		(net "P5E_CPU1_P2_RX_DP<5>")
	)
	(segment
		(start 119.314468 -300.900338)
		(end 118.47195 -298.865036)
		(width 0.14224)
		(layer "In6.Cu")
		(net "P5E_CPU1_P2_RX_DP<5>")
	)
	(segment
		(start 117.566694 -289.82162)
		(end 117.497098 -289.78098)
		(width 0.1143)
		(layer "In6.Cu")
		(net "P5E_CPU1_P2_RX_DP<5>")
	)
	(segment
		(start 153.8605 -384.731006)
		(end 153.863548 -384.3528)
		(width 0.14224)
		(layer "In6.Cu")
		(net "P5E_CPU1_P2_RX_DP<5>")
	)
	(segment
		(start 117.566694 -284.961838)
		(end 117.497098 -284.921198)
		(width 0.1143)
		(layer "In6.Cu")
		(net "P5E_CPU1_P2_RX_DP<5>")
	)
	(segment
		(start 117.497098 -287.551622)
		(end 117.564154 -287.512506)
		(width 0.1143)
		(layer "In6.Cu")
		(net "P5E_CPU1_P2_RX_DP<5>")
	)
	(segment
		(start 117.566694 -291.441632)
		(end 117.497098 -291.400992)
		(width 0.1143)
		(layer "In6.Cu")
		(net "P5E_CPU1_P2_RX_DP<5>")
	)
	(segment
		(start 118.000526 -295.470326)
		(end 117.998748 -295.46931)
		(width 0.1143)
		(layer "In6.Cu")
		(net "P5E_CPU1_P2_RX_DP<5>")
	)
	(segment
		(start 129.461514 -314.308236)
		(end 123.06808 -306.517802)
		(width 0.14224)
		(layer "In6.Cu")
		(net "P5E_CPU1_P2_RX_DP<5>")
	)
	(segment
		(start 118.3259 -296.353738)
		(end 118.3259 -296.32529)
		(width 0.1143)
		(layer "In6.Cu")
		(net "P5E_CPU1_P2_RX_DP<5>")
	)
	(segment
		(start 151.724614 -373.515128)
		(end 151.724614 -371.211856)
		(width 0.14224)
		(layer "In6.Cu")
		(net "P5E_CPU1_P2_RX_DP<5>")
	)
	(segment
		(start 154.088338 -385.548632)
		(end 154.176476 -385.460494)
		(width 0.14224)
		(layer "In6.Cu")
		(net "P5E_CPU1_P2_RX_DP<5>")
	)
	(segment
		(start 149.855428 -366.094264)
		(end 140.78331 -348.300548)
		(width 0.14224)
		(layer "In6.Cu")
		(net "P5E_CPU1_P2_RX_DP<5>")
	)
	(segment
		(start 154.176476 -385.460494)
		(end 154.176476 -385.046982)
		(width 0.14224)
		(layer "In6.Cu")
		(net "P5E_CPU1_P2_RX_DP<5>")
	)
	(segment
		(start 121.191274 -303.70907)
		(end 121.19102 -303.708816)
		(width 0.14224)
		(layer "In6.Cu")
		(net "P5E_CPU1_P2_RX_DP<5>")
	)
	(segment
		(start 151.554434 -370.800884)
		(end 151.110696 -370.357146)
		(width 0.14224)
		(layer "In6.Cu")
		(net "P5E_CPU1_P2_RX_DP<5>")
	)
	(segment
		(start 135.053832 -324.104762)
		(end 131.24307 -316.974728)
		(width 0.14224)
		(layer "In6.Cu")
		(net "P5E_CPU1_P2_RX_DP<5>")
	)
	(segment
		(start 117.497098 -289.17138)
		(end 117.566694 -289.13074)
		(width 0.1143)
		(layer "In6.Cu")
		(net "P5E_CPU1_P2_RX_DP<5>")
	)
	(segment
		(start 150.022814 -369.316762)
		(end 150.022814 -366.79124)
		(width 0.14224)
		(layer "In6.Cu")
		(net "P5E_CPU1_P2_RX_DP<5>")
	)
	(segment
		(start 118.029228 -295.48709)
		(end 118.00459 -295.472866)
		(width 0.1143)
		(layer "In6.Cu")
		(net "P5E_CPU1_P2_RX_DP<5>")
	)
	(segment
		(start 117.997732 -295.468802)
		(end 117.965982 -295.450514)
		(width 0.1143)
		(layer "In6.Cu")
		(net "P5E_CPU1_P2_RX_DP<5>")
	)
	(segment
		(start 117.527578 -288.178748)
		(end 117.495066 -288.159952)
		(width 0.1143)
		(layer "In6.Cu")
		(net "P5E_CPU1_P2_RX_DP<5>")
	)
	(segment
		(start 117.566694 -288.201608)
		(end 117.527578 -288.178748)
		(width 0.1143)
		(layer "In6.Cu")
		(net "P5E_CPU1_P2_RX_DP<5>")
	)
	(segment
		(start 117.497098 -290.791392)
		(end 117.566694 -290.750752)
		(width 0.1143)
		(layer "In6.Cu")
		(net "P5E_CPU1_P2_RX_DP<5>")
	)
	(segment
		(start 135.05434 -324.105778)
		(end 135.053832 -324.104762)
		(width 0.14224)
		(layer "In6.Cu")
		(net "P5E_CPU1_P2_RX_DP<5>")
	)
	(segment
		(start 118.3259 -296.32529)
		(end 118.28018 -296.27957)
		(width 0.1143)
		(layer "In6.Cu")
		(net "P5E_CPU1_P2_RX_DP<5>")
	)
	(segment
		(start 154.168348 -384.048254)
		(end 154.168348 -382.164082)
		(width 0.14224)
		(layer "In6.Cu")
		(net "P5E_CPU1_P2_RX_DP<5>")
	)
	(segment
		(start 117.497098 -292.411404)
		(end 117.566694 -292.370764)
		(width 0.1143)
		(layer "In6.Cu")
		(net "P5E_CPU1_P2_RX_DP<5>")
	)
	(segment
		(start 153.914094 -385.649216)
		(end 154.088338 -385.548632)
		(width 0.14224)
		(layer "In6.Cu")
		(net "P5E_CPU1_P2_RX_DP<5>")
	)
	(segment
		(start 117.346984 -284.686248)
		(end 117.416834 -284.616398)
		(width 0.1143)
		(layer "In6.Cu")
		(net "P5E_CPU1_P2_RX_DP<5>")
	)
	(segment
		(start 150.226268 -369.788186)
		(end 150.066756 -369.491514)
		(width 0.14224)
		(layer "In6.Cu")
		(net "P5E_CPU1_P2_RX_DP<5>")
	)
	(segment
		(start 117.964204 -286.743394)
		(end 118.034054 -286.702754)
		(width 0.1143)
		(layer "In6.Cu")
		(net "P5E_CPU1_P2_RX_DP<5>")
	)
	(segment
		(start 117.998748 -295.46931)
		(end 117.997732 -295.468802)
		(width 0.1143)
		(layer "In6.Cu")
		(net "P5E_CPU1_P2_RX_DP<5>")
	)
	(segment
		(start 118.00205 -295.471342)
		(end 118.000526 -295.470326)
		(width 0.1143)
		(layer "In6.Cu")
		(net "P5E_CPU1_P2_RX_DP<5>")
	)
	(segment
		(start 140.013944 -346.548964)
		(end 138.75004 -342.535764)
		(width 0.14224)
		(layer "In6.Cu")
		(net "P5E_CPU1_P2_RX_DP<5>")
	)
	(segment
		(start 118.28018 -296.27957)
		(end 118.28018 -295.956228)
		(width 0.1143)
		(layer "In6.Cu")
		(net "P5E_CPU1_P2_RX_DP<5>")
	)
	(segment
		(start 118.02999 -295.487598)
		(end 118.029228 -295.48709)
		(width 0.1143)
		(layer "In6.Cu")
		(net "P5E_CPU1_P2_RX_DP<5>")
	)
	(segment
		(start 118.036848 -295.491662)
		(end 118.02999 -295.487598)
		(width 0.1143)
		(layer "In6.Cu")
		(net "P5E_CPU1_P2_RX_DP<5>")
	)
	(segment
		(start 153.819098 -386.003292)
		(end 153.914094 -385.649216)
		(width 0.14224)
		(layer "In6.Cu")
		(net "P5E_CPU1_P2_RX_DP<5>")
	)
	(segment
		(start 121.19102 -303.708816)
		(end 119.314468 -300.900338)
		(width 0.14224)
		(layer "In6.Cu")
		(net "P5E_CPU1_P2_RX_DP<5>")
	)
	(segment
		(start 153.863548 -384.3528)
		(end 154.168348 -384.048254)
		(width 0.14224)
		(layer "In6.Cu")
		(net "P5E_CPU1_P2_RX_DP<5>")
	)
	(segment
		(start 140.78331 -348.300548)
		(end 140.013944 -346.548964)
		(width 0.14224)
		(layer "In6.Cu")
		(net "P5E_CPU1_P2_RX_DP<5>")
	)
	(segment
		(start 117.566694 -294.681656)
		(end 117.497098 -294.641016)
		(width 0.1143)
		(layer "In6.Cu")
		(net "P5E_CPU1_P2_RX_DP<5>")
	)
	(segment
		(start 154.176476 -385.046982)
		(end 153.8605 -384.731006)
		(width 0.14224)
		(layer "In6.Cu")
		(net "P5E_CPU1_P2_RX_DP<5>")
	)
	(segment
		(start 118.3259 -298.130722)
		(end 118.3259 -296.353738)
		(width 0.14224)
		(layer "In6.Cu")
		(net "P5E_CPU1_P2_RX_DP<5>")
	)
	(segment
		(start 117.497098 -294.031416)
		(end 117.566694 -293.990776)
		(width 0.1143)
		(layer "In6.Cu")
		(net "P5E_CPU1_P2_RX_DP<5>")
	)
	(segment
		(start 131.24307 -316.974728)
		(end 129.461514 -314.308236)
		(width 0.14224)
		(layer "In6.Cu")
		(net "P5E_CPU1_P2_RX_DP<5>")
	)
	(segment
		(start 150.762208 -370.124228)
		(end 150.45944 -369.999006)
		(width 0.14224)
		(layer "In6.Cu")
		(net "P5E_CPU1_P2_RX_DP<5>")
	)
	(segment
		(start 117.998494 -285.747206)
		(end 117.993922 -285.744666)
		(width 0.1143)
		(layer "In6.Cu")
		(net "P5E_CPU1_P2_RX_DP<5>")
	)
	(segment
		(start 123.06808 -306.517802)
		(end 121.191274 -303.70907)
		(width 0.14224)
		(layer "In6.Cu")
		(net "P5E_CPU1_P2_RX_DP<5>")
	)
	(segment
		(start 117.416834 -284.616398)
		(end 117.714776 -284.616398)
		(width 0.1143)
		(layer "In6.Cu")
		(net "P5E_CPU1_P2_RX_DP<5>")
	)
	(segment
		(start 118.00459 -295.472866)
		(end 118.003066 -295.47185)
		(width 0.1143)
		(layer "In6.Cu")
		(net "P5E_CPU1_P2_RX_DP<5>")
	)
	(segment
		(start 117.566694 -293.061644)
		(end 117.497098 -293.021004)
		(width 0.1143)
		(layer "In6.Cu")
		(net "P5E_CPU1_P2_RX_DP<5>")
	)
	(segment
		(start 138.75004 -342.535764)
		(end 135.122412 -324.298056)
		(width 0.14224)
		(layer "In6.Cu")
		(net "P5E_CPU1_P2_RX_DP<5>")
	)
	(arc
		(start 151.724614 -371.211856)
		(mid 151.680444 -370.989419)
		(end 151.554434 -370.800884)
		(width 0.14224)
		(layer "In6.Cu")
		(net "P5E_CPU1_P2_RX_DP<5>")
	)
	(arc
		(start 117.497098 -294.641016)
		(mid 117.340121 -294.336216)
		(end 117.497098 -294.031416)
		(width 0.1143)
		(layer "In6.Cu")
		(net "P5E_CPU1_P2_RX_DP<5>")
	)
	(arc
		(start 117.993922 -285.744666)
		(mid 117.859282 -285.610198)
		(end 117.810026 -285.426404)
		(width 0.1143)
		(layer "In6.Cu")
		(net "P5E_CPU1_P2_RX_DP<5>")
	)
	(arc
		(start 117.340126 -287.856422)
		(mid 117.381675 -287.685)
		(end 117.497098 -287.551622)
		(width 0.1143)
		(layer "In6.Cu")
		(net "P5E_CPU1_P2_RX_DP<5>")
	)
	(arc
		(start 117.495066 -288.159952)
		(mid 117.381137 -288.026805)
		(end 117.340126 -287.856422)
		(width 0.1143)
		(layer "In6.Cu")
		(net "P5E_CPU1_P2_RX_DP<5>")
	)
	(arc
		(start 117.497098 -284.921198)
		(mid 117.399333 -284.818222)
		(end 117.346984 -284.686248)
		(width 0.1143)
		(layer "In6.Cu")
		(net "P5E_CPU1_P2_RX_DP<5>")
	)
	(arc
		(start 117.497098 -293.021004)
		(mid 117.340121 -292.716204)
		(end 117.497098 -292.411404)
		(width 0.1143)
		(layer "In6.Cu")
		(net "P5E_CPU1_P2_RX_DP<5>")
	)
	(arc
		(start 150.022814 -366.79124)
		(mid 149.980379 -366.432844)
		(end 149.855428 -366.094264)
		(width 0.14224)
		(layer "In6.Cu")
		(net "P5E_CPU1_P2_RX_DP<5>")
	)
	(arc
		(start 151.110696 -370.357146)
		(mid 150.947935 -370.223505)
		(end 150.762208 -370.124228)
		(width 0.14224)
		(layer "In6.Cu")
		(net "P5E_CPU1_P2_RX_DP<5>")
	)
	(arc
		(start 154.168348 -382.164082)
		(mid 154.154313 -381.963095)
		(end 154.112214 -381.766064)
		(width 0.14224)
		(layer "In6.Cu")
		(net "P5E_CPU1_P2_RX_DP<5>")
	)
	(arc
		(start 150.066756 -369.491514)
		(mid 150.033978 -369.406856)
		(end 150.022814 -369.316762)
		(width 0.14224)
		(layer "In6.Cu")
		(net "P5E_CPU1_P2_RX_DP<5>")
	)
	(arc
		(start 117.810026 -285.426404)
		(mid 117.745511 -285.164185)
		(end 117.566694 -284.961838)
		(width 0.1143)
		(layer "In6.Cu")
		(net "P5E_CPU1_P2_RX_DP<5>")
	)
	(arc
		(start 117.965982 -295.450514)
		(mid 117.851306 -295.31718)
		(end 117.810026 -295.146222)
		(width 0.1143)
		(layer "In6.Cu")
		(net "P5E_CPU1_P2_RX_DP<5>")
	)
	(arc
		(start 117.566694 -289.13074)
		(mid 117.810021 -288.666174)
		(end 117.566694 -288.201608)
		(width 0.1143)
		(layer "In6.Cu")
		(net "P5E_CPU1_P2_RX_DP<5>")
	)
	(arc
		(start 117.566694 -290.750752)
		(mid 117.810021 -290.286186)
		(end 117.566694 -289.82162)
		(width 0.1143)
		(layer "In6.Cu")
		(net "P5E_CPU1_P2_RX_DP<5>")
	)
	(arc
		(start 117.566694 -292.370764)
		(mid 117.810021 -291.906198)
		(end 117.566694 -291.441632)
		(width 0.1143)
		(layer "In6.Cu")
		(net "P5E_CPU1_P2_RX_DP<5>")
	)
	(arc
		(start 118.47195 -298.865036)
		(mid 118.362759 -298.50507)
		(end 118.3259 -298.130722)
		(width 0.14224)
		(layer "In6.Cu")
		(net "P5E_CPU1_P2_RX_DP<5>")
	)
	(arc
		(start 117.566694 -293.990776)
		(mid 117.810021 -293.52621)
		(end 117.566694 -293.061644)
		(width 0.1143)
		(layer "In6.Cu")
		(net "P5E_CPU1_P2_RX_DP<5>")
	)
	(arc
		(start 118.180612 -295.63568)
		(mid 118.11526 -295.557153)
		(end 118.036848 -295.491662)
		(width 0.1143)
		(layer "In6.Cu")
		(net "P5E_CPU1_P2_RX_DP<5>")
	)
	(arc
		(start 118.034054 -286.702754)
		(mid 118.279653 -286.215154)
		(end 117.998494 -285.747206)
		(width 0.1143)
		(layer "In6.Cu")
		(net "P5E_CPU1_P2_RX_DP<5>")
	)
	(arc
		(start 117.497098 -289.78098)
		(mid 117.340121 -289.47618)
		(end 117.497098 -289.17138)
		(width 0.1143)
		(layer "In6.Cu")
		(net "P5E_CPU1_P2_RX_DP<5>")
	)
	(arc
		(start 117.810026 -287.046162)
		(mid 117.850788 -286.876278)
		(end 117.964204 -286.743394)
		(width 0.1143)
		(layer "In6.Cu")
		(net "P5E_CPU1_P2_RX_DP<5>")
	)
	(arc
		(start 118.28018 -295.956228)
		(mid 118.25476 -295.788383)
		(end 118.180612 -295.63568)
		(width 0.1143)
		(layer "In6.Cu")
		(net "P5E_CPU1_P2_RX_DP<5>")
	)
	(arc
		(start 117.564154 -287.512506)
		(mid 117.744806 -287.309761)
		(end 117.810026 -287.046162)
		(width 0.1143)
		(layer "In6.Cu")
		(net "P5E_CPU1_P2_RX_DP<5>")
	)
	(arc
		(start 117.497098 -291.400992)
		(mid 117.340121 -291.096192)
		(end 117.497098 -290.791392)
		(width 0.1143)
		(layer "In6.Cu")
		(net "P5E_CPU1_P2_RX_DP<5>")
	)
	(arc
		(start 150.45944 -369.999006)
		(mid 150.324584 -369.913793)
		(end 150.226268 -369.788186)
		(width 0.14224)
		(layer "In6.Cu")
		(net "P5E_CPU1_P2_RX_DP<5>")
	)
	(arc
		(start 135.122412 -324.298056)
		(mid 135.095307 -324.199463)
		(end 135.05434 -324.105778)
		(width 0.14224)
		(layer "In6.Cu")
		(net "P5E_CPU1_P2_RX_DP<5>")
	)
	(arc
		(start 117.810026 -295.146222)
		(mid 117.745511 -294.884003)
		(end 117.566694 -294.681656)
		(width 0.1143)
		(layer "In6.Cu")
		(net "P5E_CPU1_P2_RX_DP<5>")
	)
	(segment
		(start 152.098248 -386.003292)
		(end 152.618948 -386.003292)
		(width 0.127)
		(layer "F.Cu")
		(net "P5E_CPU1_P2_RX_DP<4>")
	)
	(segment
		(start 117.247924 -285.970472)
		(end 117.714776 -286.23641)
		(width 0.12954)
		(layer "F.Cu")
		(net "P5E_CPU1_P2_RX_DP<4>")
	)
	(segment
		(start 116.62664 -291.441632)
		(end 116.557044 -291.400992)
		(width 0.1143)
		(layer "In6.Cu")
		(net "P5E_CPU1_P2_RX_DP<4>")
	)
	(segment
		(start 152.890474 -381.863092)
		(end 150.582884 -374.325134)
		(width 0.14224)
		(layer "In6.Cu")
		(net "P5E_CPU1_P2_RX_DP<4>")
	)
	(segment
		(start 152.888188 -385.548632)
		(end 152.976326 -385.460494)
		(width 0.14224)
		(layer "In6.Cu")
		(net "P5E_CPU1_P2_RX_DP<4>")
	)
	(segment
		(start 117.340126 -296.086022)
		(end 117.340126 -295.952926)
		(width 0.1143)
		(layer "In6.Cu")
		(net "P5E_CPU1_P2_RX_DP<4>")
	)
	(segment
		(start 116.585746 -287.535112)
		(end 116.587016 -287.53435)
		(width 0.1143)
		(layer "In6.Cu")
		(net "P5E_CPU1_P2_RX_DP<4>")
	)
	(segment
		(start 116.557044 -292.411404)
		(end 116.62664 -292.370764)
		(width 0.1143)
		(layer "In6.Cu")
		(net "P5E_CPU1_P2_RX_DP<4>")
	)
	(segment
		(start 116.557044 -290.791392)
		(end 116.62664 -290.750752)
		(width 0.1143)
		(layer "In6.Cu")
		(net "P5E_CPU1_P2_RX_DP<4>")
	)
	(segment
		(start 134.14756 -324.438772)
		(end 134.096506 -324.299326)
		(width 0.14224)
		(layer "In6.Cu")
		(net "P5E_CPU1_P2_RX_DP<4>")
	)
	(segment
		(start 150.582884 -374.325134)
		(end 149.707854 -372.966996)
		(width 0.14224)
		(layer "In6.Cu")
		(net "P5E_CPU1_P2_RX_DP<4>")
	)
	(segment
		(start 152.618948 -386.003292)
		(end 152.713944 -385.649216)
		(width 0.14224)
		(layer "In6.Cu")
		(net "P5E_CPU1_P2_RX_DP<4>")
	)
	(segment
		(start 152.976326 -385.046982)
		(end 152.66035 -384.731006)
		(width 0.14224)
		(layer "In6.Cu")
		(net "P5E_CPU1_P2_RX_DP<4>")
	)
	(segment
		(start 116.62664 -293.061644)
		(end 116.557044 -293.021004)
		(width 0.1143)
		(layer "In6.Cu")
		(net "P5E_CPU1_P2_RX_DP<4>")
	)
	(segment
		(start 149.55012 -372.824248)
		(end 149.12848 -372.608856)
		(width 0.14224)
		(layer "In6.Cu")
		(net "P5E_CPU1_P2_RX_DP<4>")
	)
	(segment
		(start 116.587778 -287.533842)
		(end 116.588794 -287.533334)
		(width 0.1143)
		(layer "In6.Cu")
		(net "P5E_CPU1_P2_RX_DP<4>")
	)
	(segment
		(start 117.335554 -296.090594)
		(end 117.340126 -296.086022)
		(width 0.1143)
		(layer "In6.Cu")
		(net "P5E_CPU1_P2_RX_DP<4>")
	)
	(segment
		(start 117.33403 -286.319214)
		(end 117.416834 -286.23641)
		(width 0.1143)
		(layer "In6.Cu")
		(net "P5E_CPU1_P2_RX_DP<4>")
	)
	(segment
		(start 117.381274 -296.32529)
		(end 117.335554 -296.27957)
		(width 0.1143)
		(layer "In6.Cu")
		(net "P5E_CPU1_P2_RX_DP<4>")
	)
	(segment
		(start 148.542756 -372.158768)
		(end 148.488908 -372.098824)
		(width 0.14224)
		(layer "In6.Cu")
		(net "P5E_CPU1_P2_RX_DP<4>")
	)
	(segment
		(start 116.557044 -294.031416)
		(end 116.62664 -293.990776)
		(width 0.1143)
		(layer "In6.Cu")
		(net "P5E_CPU1_P2_RX_DP<4>")
	)
	(segment
		(start 137.907014 -343.328244)
		(end 134.15137 -324.449186)
		(width 0.14224)
		(layer "In6.Cu")
		(net "P5E_CPU1_P2_RX_DP<4>")
	)
	(segment
		(start 122.30608 -307.062124)
		(end 120.363234 -304.154078)
		(width 0.14224)
		(layer "In6.Cu")
		(net "P5E_CPU1_P2_RX_DP<4>")
	)
	(segment
		(start 147.86102 -366.943386)
		(end 139.090654 -347.074998)
		(width 0.14224)
		(layer "In6.Cu")
		(net "P5E_CPU1_P2_RX_DP<4>")
	)
	(segment
		(start 134.096506 -324.299326)
		(end 130.473196 -317.520574)
		(width 0.14224)
		(layer "In6.Cu")
		(net "P5E_CPU1_P2_RX_DP<4>")
	)
	(segment
		(start 128.650492 -314.792106)
		(end 122.30608 -307.062124)
		(width 0.14224)
		(layer "In6.Cu")
		(net "P5E_CPU1_P2_RX_DP<4>")
	)
	(segment
		(start 116.588794 -287.533334)
		(end 116.590064 -287.532572)
		(width 0.1143)
		(layer "In6.Cu")
		(net "P5E_CPU1_P2_RX_DP<4>")
	)
	(segment
		(start 152.663398 -384.3528)
		(end 152.968198 -384.048254)
		(width 0.14224)
		(layer "In6.Cu")
		(net "P5E_CPU1_P2_RX_DP<4>")
	)
	(segment
		(start 120.363234 -304.154078)
		(end 120.36298 -304.154078)
		(width 0.14224)
		(layer "In6.Cu")
		(net "P5E_CPU1_P2_RX_DP<4>")
	)
	(segment
		(start 116.590064 -287.532572)
		(end 116.58981 -287.532318)
		(width 0.1143)
		(layer "In6.Cu")
		(net "P5E_CPU1_P2_RX_DP<4>")
	)
	(segment
		(start 117.416834 -286.23641)
		(end 117.714776 -286.23641)
		(width 0.1143)
		(layer "In6.Cu")
		(net "P5E_CPU1_P2_RX_DP<4>")
	)
	(segment
		(start 116.62664 -288.201608)
		(end 116.555012 -288.159952)
		(width 0.1143)
		(layer "In6.Cu")
		(net "P5E_CPU1_P2_RX_DP<4>")
	)
	(segment
		(start 117.381274 -296.353738)
		(end 117.381274 -296.32529)
		(width 0.1143)
		(layer "In6.Cu")
		(net "P5E_CPU1_P2_RX_DP<4>")
	)
	(segment
		(start 130.473196 -317.520574)
		(end 128.650492 -314.792106)
		(width 0.14224)
		(layer "In6.Cu")
		(net "P5E_CPU1_P2_RX_DP<4>")
	)
	(segment
		(start 117.096286 -286.70123)
		(end 117.096794 -286.700976)
		(width 0.1143)
		(layer "In6.Cu")
		(net "P5E_CPU1_P2_RX_DP<4>")
	)
	(segment
		(start 117.054884 -286.725106)
		(end 117.056154 -286.724598)
		(width 0.1143)
		(layer "In6.Cu")
		(net "P5E_CPU1_P2_RX_DP<4>")
	)
	(segment
		(start 117.335554 -296.27957)
		(end 117.335554 -296.090594)
		(width 0.1143)
		(layer "In6.Cu")
		(net "P5E_CPU1_P2_RX_DP<4>")
	)
	(segment
		(start 118.419626 -301.245524)
		(end 117.516148 -299.06468)
		(width 0.14224)
		(layer "In6.Cu")
		(net "P5E_CPU1_P2_RX_DP<4>")
	)
	(segment
		(start 116.556028 -287.55213)
		(end 116.584222 -287.535874)
		(width 0.1143)
		(layer "In6.Cu")
		(net "P5E_CPU1_P2_RX_DP<4>")
	)
	(segment
		(start 152.976326 -385.460494)
		(end 152.976326 -385.046982)
		(width 0.14224)
		(layer "In6.Cu")
		(net "P5E_CPU1_P2_RX_DP<4>")
	)
	(segment
		(start 116.62664 -289.82162)
		(end 116.557044 -289.78098)
		(width 0.1143)
		(layer "In6.Cu")
		(net "P5E_CPU1_P2_RX_DP<4>")
	)
	(segment
		(start 152.968198 -384.048254)
		(end 152.968198 -382.3843)
		(width 0.14224)
		(layer "In6.Cu")
		(net "P5E_CPU1_P2_RX_DP<4>")
	)
	(segment
		(start 116.587016 -287.53435)
		(end 116.587778 -287.533842)
		(width 0.1143)
		(layer "In6.Cu")
		(net "P5E_CPU1_P2_RX_DP<4>")
	)
	(segment
		(start 148.287232 -371.668802)
		(end 147.86102 -368.7445)
		(width 0.14224)
		(layer "In6.Cu")
		(net "P5E_CPU1_P2_RX_DP<4>")
	)
	(segment
		(start 116.584222 -287.535874)
		(end 116.585746 -287.535112)
		(width 0.1143)
		(layer "In6.Cu")
		(net "P5E_CPU1_P2_RX_DP<4>")
	)
	(segment
		(start 117.056154 -286.724598)
		(end 117.096286 -286.70123)
		(width 0.1143)
		(layer "In6.Cu")
		(net "P5E_CPU1_P2_RX_DP<4>")
	)
	(segment
		(start 117.06479 -295.472866)
		(end 117.025928 -295.450514)
		(width 0.1143)
		(layer "In6.Cu")
		(net "P5E_CPU1_P2_RX_DP<4>")
	)
	(segment
		(start 134.15137 -324.449186)
		(end 134.14756 -324.438772)
		(width 0.14224)
		(layer "In6.Cu")
		(net "P5E_CPU1_P2_RX_DP<4>")
	)
	(segment
		(start 120.36298 -304.154078)
		(end 118.419626 -301.245524)
		(width 0.14224)
		(layer "In6.Cu")
		(net "P5E_CPU1_P2_RX_DP<4>")
	)
	(segment
		(start 117.381274 -298.385992)
		(end 117.381274 -296.353738)
		(width 0.14224)
		(layer "In6.Cu")
		(net "P5E_CPU1_P2_RX_DP<4>")
	)
	(segment
		(start 147.86102 -368.7445)
		(end 147.86102 -366.943386)
		(width 0.14224)
		(layer "In6.Cu")
		(net "P5E_CPU1_P2_RX_DP<4>")
	)
	(segment
		(start 152.713944 -385.649216)
		(end 152.888188 -385.548632)
		(width 0.14224)
		(layer "In6.Cu")
		(net "P5E_CPU1_P2_RX_DP<4>")
	)
	(segment
		(start 152.66035 -384.731006)
		(end 152.663398 -384.3528)
		(width 0.14224)
		(layer "In6.Cu")
		(net "P5E_CPU1_P2_RX_DP<4>")
	)
	(segment
		(start 116.62664 -294.681656)
		(end 116.557044 -294.641016)
		(width 0.1143)
		(layer "In6.Cu")
		(net "P5E_CPU1_P2_RX_DP<4>")
	)
	(segment
		(start 116.557044 -289.17138)
		(end 116.62664 -289.13074)
		(width 0.1143)
		(layer "In6.Cu")
		(net "P5E_CPU1_P2_RX_DP<4>")
	)
	(segment
		(start 139.090654 -347.074998)
		(end 137.907014 -343.328244)
		(width 0.14224)
		(layer "In6.Cu")
		(net "P5E_CPU1_P2_RX_DP<4>")
	)
	(arc
		(start 116.557044 -293.021004)
		(mid 116.400067 -292.716204)
		(end 116.557044 -292.411404)
		(width 0.1143)
		(layer "In6.Cu")
		(net "P5E_CPU1_P2_RX_DP<4>")
	)
	(arc
		(start 116.555012 -288.159952)
		(mid 116.400124 -287.855787)
		(end 116.556028 -287.55213)
		(width 0.1143)
		(layer "In6.Cu")
		(net "P5E_CPU1_P2_RX_DP<4>")
	)
	(arc
		(start 116.557044 -294.641016)
		(mid 116.400067 -294.336216)
		(end 116.557044 -294.031416)
		(width 0.1143)
		(layer "In6.Cu")
		(net "P5E_CPU1_P2_RX_DP<4>")
	)
	(arc
		(start 116.62664 -292.370764)
		(mid 116.869967 -291.906198)
		(end 116.62664 -291.441632)
		(width 0.1143)
		(layer "In6.Cu")
		(net "P5E_CPU1_P2_RX_DP<4>")
	)
	(arc
		(start 117.516148 -299.06468)
		(mid 117.415277 -298.731979)
		(end 117.381274 -298.385992)
		(width 0.14224)
		(layer "In6.Cu")
		(net "P5E_CPU1_P2_RX_DP<4>")
	)
	(arc
		(start 116.869972 -295.146222)
		(mid 116.805457 -294.884003)
		(end 116.62664 -294.681656)
		(width 0.1143)
		(layer "In6.Cu")
		(net "P5E_CPU1_P2_RX_DP<4>")
	)
	(arc
		(start 116.62664 -290.750752)
		(mid 116.869967 -290.286186)
		(end 116.62664 -289.82162)
		(width 0.1143)
		(layer "In6.Cu")
		(net "P5E_CPU1_P2_RX_DP<4>")
	)
	(arc
		(start 116.869718 -287.046416)
		(mid 116.919323 -286.860995)
		(end 117.054884 -286.725106)
		(width 0.1143)
		(layer "In6.Cu")
		(net "P5E_CPU1_P2_RX_DP<4>")
	)
	(arc
		(start 116.62664 -293.990776)
		(mid 116.869967 -293.52621)
		(end 116.62664 -293.061644)
		(width 0.1143)
		(layer "In6.Cu")
		(net "P5E_CPU1_P2_RX_DP<4>")
	)
	(arc
		(start 116.557044 -289.78098)
		(mid 116.400067 -289.47618)
		(end 116.557044 -289.17138)
		(width 0.1143)
		(layer "In6.Cu")
		(net "P5E_CPU1_P2_RX_DP<4>")
	)
	(arc
		(start 116.62664 -289.13074)
		(mid 116.869967 -288.666174)
		(end 116.62664 -288.201608)
		(width 0.1143)
		(layer "In6.Cu")
		(net "P5E_CPU1_P2_RX_DP<4>")
	)
	(arc
		(start 148.488908 -372.098824)
		(mid 148.356281 -371.898724)
		(end 148.287232 -371.668802)
		(width 0.14224)
		(layer "In6.Cu")
		(net "P5E_CPU1_P2_RX_DP<4>")
	)
	(arc
		(start 117.025928 -295.450514)
		(mid 116.911252 -295.31718)
		(end 116.869972 -295.146222)
		(width 0.1143)
		(layer "In6.Cu")
		(net "P5E_CPU1_P2_RX_DP<4>")
	)
	(arc
		(start 117.340126 -295.952926)
		(mid 117.266414 -295.676208)
		(end 117.06479 -295.472866)
		(width 0.1143)
		(layer "In6.Cu")
		(net "P5E_CPU1_P2_RX_DP<4>")
	)
	(arc
		(start 117.33022 -286.342074)
		(mid 117.332243 -286.330664)
		(end 117.33403 -286.319214)
		(width 0.1143)
		(layer "In6.Cu")
		(net "P5E_CPU1_P2_RX_DP<4>")
	)
	(arc
		(start 116.58981 -287.532318)
		(mid 116.794774 -287.326808)
		(end 116.869718 -287.046416)
		(width 0.1143)
		(layer "In6.Cu")
		(net "P5E_CPU1_P2_RX_DP<4>")
	)
	(arc
		(start 116.557044 -291.400992)
		(mid 116.400067 -291.096192)
		(end 116.557044 -290.791392)
		(width 0.1143)
		(layer "In6.Cu")
		(net "P5E_CPU1_P2_RX_DP<4>")
	)
	(arc
		(start 149.12848 -372.608856)
		(mid 148.814979 -372.410672)
		(end 148.542756 -372.158768)
		(width 0.14224)
		(layer "In6.Cu")
		(net "P5E_CPU1_P2_RX_DP<4>")
	)
	(arc
		(start 152.968198 -382.3843)
		(mid 152.948708 -382.120809)
		(end 152.890474 -381.863092)
		(width 0.14224)
		(layer "In6.Cu")
		(net "P5E_CPU1_P2_RX_DP<4>")
	)
	(arc
		(start 117.096794 -286.700976)
		(mid 117.248781 -286.544468)
		(end 117.33022 -286.342074)
		(width 0.1143)
		(layer "In6.Cu")
		(net "P5E_CPU1_P2_RX_DP<4>")
	)
	(arc
		(start 149.707854 -372.966996)
		(mid 149.63843 -372.885187)
		(end 149.55012 -372.824248)
		(width 0.14224)
		(layer "In6.Cu")
		(net "P5E_CPU1_P2_RX_DP<4>")
	)
	(segment
		(start 117.247924 -282.730448)
		(end 117.714776 -282.996386)
		(width 0.12954)
		(layer "F.Cu")
		(net "P5E_CPU1_P2_RX_DP<3>")
	)
	(segment
		(start 150.898352 -386.003292)
		(end 151.419052 -386.003292)
		(width 0.127)
		(layer "F.Cu")
		(net "P5E_CPU1_P2_RX_DP<3>")
	)
	(segment
		(start 115.650518 -291.420296)
		(end 115.64874 -291.41928)
		(width 0.1143)
		(layer "In6.Cu")
		(net "P5E_CPU1_P2_RX_DP<3>")
	)
	(segment
		(start 115.64239 -289.795712)
		(end 115.641628 -289.795204)
		(width 0.1143)
		(layer "In6.Cu")
		(net "P5E_CPU1_P2_RX_DP<3>")
	)
	(segment
		(start 115.68684 -289.132518)
		(end 115.68684 -289.13074)
		(width 0.1143)
		(layer "In6.Cu")
		(net "P5E_CPU1_P2_RX_DP<3>")
	)
	(segment
		(start 151.77643 -385.046982)
		(end 151.460454 -384.731006)
		(width 0.14224)
		(layer "In6.Cu")
		(net "P5E_CPU1_P2_RX_DP<3>")
	)
	(segment
		(start 121.532904 -307.589682)
		(end 117.540532 -301.614586)
		(width 0.14224)
		(layer "In6.Cu")
		(net "P5E_CPU1_P2_RX_DP<3>")
	)
	(segment
		(start 115.64239 -293.035736)
		(end 115.641628 -293.035228)
		(width 0.1143)
		(layer "In6.Cu")
		(net "P5E_CPU1_P2_RX_DP<3>")
	)
	(segment
		(start 115.68684 -294.681656)
		(end 115.679982 -294.677592)
		(width 0.1143)
		(layer "In6.Cu")
		(net "P5E_CPU1_P2_RX_DP<3>")
	)
	(segment
		(start 115.654582 -289.802824)
		(end 115.653058 -289.801808)
		(width 0.1143)
		(layer "In6.Cu")
		(net "P5E_CPU1_P2_RX_DP<3>")
	)
	(segment
		(start 115.647724 -291.418772)
		(end 115.646962 -291.418264)
		(width 0.1143)
		(layer "In6.Cu")
		(net "P5E_CPU1_P2_RX_DP<3>")
	)
	(segment
		(start 115.652042 -291.421312)
		(end 115.650518 -291.420296)
		(width 0.1143)
		(layer "In6.Cu")
		(net "P5E_CPU1_P2_RX_DP<3>")
	)
	(segment
		(start 115.646962 -293.038276)
		(end 115.644168 -293.036752)
		(width 0.1143)
		(layer "In6.Cu")
		(net "P5E_CPU1_P2_RX_DP<3>")
	)
	(segment
		(start 115.64874 -293.039292)
		(end 115.647724 -293.038784)
		(width 0.1143)
		(layer "In6.Cu")
		(net "P5E_CPU1_P2_RX_DP<3>")
	)
	(segment
		(start 115.646962 -292.394132)
		(end 115.647724 -292.393624)
		(width 0.1143)
		(layer "In6.Cu")
		(net "P5E_CPU1_P2_RX_DP<3>")
	)
	(segment
		(start 151.688292 -385.548632)
		(end 151.77643 -385.460494)
		(width 0.14224)
		(layer "In6.Cu")
		(net "P5E_CPU1_P2_RX_DP<3>")
	)
	(segment
		(start 115.650518 -293.040308)
		(end 115.64874 -293.039292)
		(width 0.1143)
		(layer "In6.Cu")
		(net "P5E_CPU1_P2_RX_DP<3>")
	)
	(segment
		(start 115.643406 -294.656256)
		(end 115.64239 -294.655748)
		(width 0.1143)
		(layer "In6.Cu")
		(net "P5E_CPU1_P2_RX_DP<3>")
	)
	(segment
		(start 116.401088 -296.279316)
		(end 116.401088 -296.200576)
		(width 0.1143)
		(layer "In6.Cu")
		(net "P5E_CPU1_P2_RX_DP<3>")
	)
	(segment
		(start 138.078972 -347.361256)
		(end 137.091166 -344.104214)
		(width 0.14224)
		(layer "In6.Cu")
		(net "P5E_CPU1_P2_RX_DP<3>")
	)
	(segment
		(start 115.645184 -292.395148)
		(end 115.646962 -292.394132)
		(width 0.1143)
		(layer "In6.Cu")
		(net "P5E_CPU1_P2_RX_DP<3>")
	)
	(segment
		(start 115.643406 -293.036244)
		(end 115.64239 -293.035736)
		(width 0.1143)
		(layer "In6.Cu")
		(net "P5E_CPU1_P2_RX_DP<3>")
	)
	(segment
		(start 117.056916 -283.48432)
		(end 117.057678 -283.483812)
		(width 0.1143)
		(layer "In6.Cu")
		(net "P5E_CPU1_P2_RX_DP<3>")
	)
	(segment
		(start 146.473418 -367.625884)
		(end 138.078972 -347.361256)
		(width 0.14224)
		(layer "In6.Cu")
		(net "P5E_CPU1_P2_RX_DP<3>")
	)
	(segment
		(start 115.679982 -291.437568)
		(end 115.67922 -291.43706)
		(width 0.1143)
		(layer "In6.Cu")
		(net "P5E_CPU1_P2_RX_DP<3>")
	)
	(segment
		(start 151.463502 -384.3528)
		(end 151.768302 -384.048254)
		(width 0.14224)
		(layer "In6.Cu")
		(net "P5E_CPU1_P2_RX_DP<3>")
	)
	(segment
		(start 116.446554 -296.353738)
		(end 116.446554 -296.32529)
		(width 0.1143)
		(layer "In6.Cu")
		(net "P5E_CPU1_P2_RX_DP<3>")
	)
	(segment
		(start 115.643406 -291.416232)
		(end 115.64239 -291.415724)
		(width 0.1143)
		(layer "In6.Cu")
		(net "P5E_CPU1_P2_RX_DP<3>")
	)
	(segment
		(start 116.400072 -296.19956)
		(end 116.400072 -295.955974)
		(width 0.1143)
		(layer "In6.Cu")
		(net "P5E_CPU1_P2_RX_DP<3>")
	)
	(segment
		(start 117.540532 -301.614586)
		(end 116.569998 -299.271182)
		(width 0.14224)
		(layer "In6.Cu")
		(net "P5E_CPU1_P2_RX_DP<3>")
	)
	(segment
		(start 115.64874 -294.659304)
		(end 115.647724 -294.658796)
		(width 0.1143)
		(layer "In6.Cu")
		(net "P5E_CPU1_P2_RX_DP<3>")
	)
	(segment
		(start 115.653058 -291.42182)
		(end 115.652042 -291.421312)
		(width 0.1143)
		(layer "In6.Cu")
		(net "P5E_CPU1_P2_RX_DP<3>")
	)
	(segment
		(start 115.646962 -291.418264)
		(end 115.644168 -291.41674)
		(width 0.1143)
		(layer "In6.Cu")
		(net "P5E_CPU1_P2_RX_DP<3>")
	)
	(segment
		(start 129.652522 -317.986664)
		(end 127.840232 -315.274706)
		(width 0.14224)
		(layer "In6.Cu")
		(net "P5E_CPU1_P2_RX_DP<3>")
	)
	(segment
		(start 115.64239 -291.415724)
		(end 115.641628 -291.415216)
		(width 0.1143)
		(layer "In6.Cu")
		(net "P5E_CPU1_P2_RX_DP<3>")
	)
	(segment
		(start 151.419052 -386.003292)
		(end 151.514048 -385.649216)
		(width 0.14224)
		(layer "In6.Cu")
		(net "P5E_CPU1_P2_RX_DP<3>")
	)
	(segment
		(start 115.641628 -293.035228)
		(end 115.639088 -293.033958)
		(width 0.1143)
		(layer "In6.Cu")
		(net "P5E_CPU1_P2_RX_DP<3>")
	)
	(segment
		(start 115.641628 -289.795204)
		(end 115.639088 -289.793934)
		(width 0.1143)
		(layer "In6.Cu")
		(net "P5E_CPU1_P2_RX_DP<3>")
	)
	(segment
		(start 116.446554 -296.32529)
		(end 116.400834 -296.27957)
		(width 0.1143)
		(layer "In6.Cu")
		(net "P5E_CPU1_P2_RX_DP<3>")
	)
	(segment
		(start 133.22554 -324.669658)
		(end 129.652522 -317.986664)
		(width 0.14224)
		(layer "In6.Cu")
		(net "P5E_CPU1_P2_RX_DP<3>")
	)
	(segment
		(start 115.664488 -289.14471)
		(end 115.665504 -289.144202)
		(width 0.1143)
		(layer "In6.Cu")
		(net "P5E_CPU1_P2_RX_DP<3>")
	)
	(segment
		(start 115.652042 -293.041324)
		(end 115.650518 -293.040308)
		(width 0.1143)
		(layer "In6.Cu")
		(net "P5E_CPU1_P2_RX_DP<3>")
	)
	(segment
		(start 116.556028 -284.312106)
		(end 116.624862 -284.272228)
		(width 0.1143)
		(layer "In6.Cu")
		(net "P5E_CPU1_P2_RX_DP<3>")
	)
	(segment
		(start 151.460454 -384.731006)
		(end 151.463502 -384.3528)
		(width 0.14224)
		(layer "In6.Cu")
		(net "P5E_CPU1_P2_RX_DP<3>")
	)
	(segment
		(start 127.840232 -315.274706)
		(end 121.532904 -307.589682)
		(width 0.14224)
		(layer "In6.Cu")
		(net "P5E_CPU1_P2_RX_DP<3>")
	)
	(segment
		(start 115.639088 -294.65397)
		(end 115.615974 -294.640508)
		(width 0.1143)
		(layer "In6.Cu")
		(net "P5E_CPU1_P2_RX_DP<3>")
	)
	(segment
		(start 151.77643 -385.460494)
		(end 151.77643 -385.046982)
		(width 0.14224)
		(layer "In6.Cu")
		(net "P5E_CPU1_P2_RX_DP<3>")
	)
	(segment
		(start 115.641882 -292.39718)
		(end 115.643152 -292.396418)
		(width 0.1143)
		(layer "In6.Cu")
		(net "P5E_CPU1_P2_RX_DP<3>")
	)
	(segment
		(start 116.401088 -296.200576)
		(end 116.400072 -296.19956)
		(width 0.1143)
		(layer "In6.Cu")
		(net "P5E_CPU1_P2_RX_DP<3>")
	)
	(segment
		(start 115.641628 -291.415216)
		(end 115.639088 -291.413946)
		(width 0.1143)
		(layer "In6.Cu")
		(net "P5E_CPU1_P2_RX_DP<3>")
	)
	(segment
		(start 146.451066 -373.640096)
		(end 146.619214 -369.66652)
		(width 0.14224)
		(layer "In6.Cu")
		(net "P5E_CPU1_P2_RX_DP<3>")
	)
	(segment
		(start 116.15674 -295.491662)
		(end 116.087144 -295.451022)
		(width 0.1143)
		(layer "In6.Cu")
		(net "P5E_CPU1_P2_RX_DP<3>")
	)
	(segment
		(start 146.609562 -374.322086)
		(end 146.609308 -374.321324)
		(width 0.14224)
		(layer "In6.Cu")
		(net "P5E_CPU1_P2_RX_DP<3>")
	)
	(segment
		(start 151.768302 -384.048254)
		(end 151.768302 -382.04013)
		(width 0.14224)
		(layer "In6.Cu")
		(net "P5E_CPU1_P2_RX_DP<3>")
	)
	(segment
		(start 115.643406 -289.79622)
		(end 115.64239 -289.795712)
		(width 0.1143)
		(layer "In6.Cu")
		(net "P5E_CPU1_P2_RX_DP<3>")
	)
	(segment
		(start 115.67922 -289.817048)
		(end 115.654582 -289.802824)
		(width 0.1143)
		(layer "In6.Cu")
		(net "P5E_CPU1_P2_RX_DP<3>")
	)
	(segment
		(start 115.653058 -289.801808)
		(end 115.652042 -289.8013)
		(width 0.1143)
		(layer "In6.Cu")
		(net "P5E_CPU1_P2_RX_DP<3>")
	)
	(segment
		(start 115.68684 -289.82162)
		(end 115.679982 -289.817556)
		(width 0.1143)
		(layer "In6.Cu")
		(net "P5E_CPU1_P2_RX_DP<3>")
	)
	(segment
		(start 116.446046 -298.240704)
		(end 116.446554 -298.240704)
		(width 0.14224)
		(layer "In6.Cu")
		(net "P5E_CPU1_P2_RX_DP<3>")
	)
	(segment
		(start 116.087144 -285.121604)
		(end 116.15674 -285.080964)
		(width 0.1143)
		(layer "In6.Cu")
		(net "P5E_CPU1_P2_RX_DP<3>")
	)
	(segment
		(start 115.615974 -292.411912)
		(end 115.641882 -292.39718)
		(width 0.1143)
		(layer "In6.Cu")
		(net "P5E_CPU1_P2_RX_DP<3>")
	)
	(segment
		(start 115.644168 -294.656764)
		(end 115.643406 -294.656256)
		(width 0.1143)
		(layer "In6.Cu")
		(net "P5E_CPU1_P2_RX_DP<3>")
	)
	(segment
		(start 115.639088 -289.793934)
		(end 115.615974 -289.780472)
		(width 0.1143)
		(layer "In6.Cu")
		(net "P5E_CPU1_P2_RX_DP<3>")
	)
	(segment
		(start 115.68176 -293.993824)
		(end 115.68684 -293.990776)
		(width 0.1143)
		(layer "In6.Cu")
		(net "P5E_CPU1_P2_RX_DP<3>")
	)
	(segment
		(start 115.650518 -289.800284)
		(end 115.64874 -289.799268)
		(width 0.1143)
		(layer "In6.Cu")
		(net "P5E_CPU1_P2_RX_DP<3>")
	)
	(segment
		(start 117.060218 -283.482288)
		(end 117.096794 -283.460952)
		(width 0.1143)
		(layer "In6.Cu")
		(net "P5E_CPU1_P2_RX_DP<3>")
	)
	(segment
		(start 115.644168 -289.796728)
		(end 115.643406 -289.79622)
		(width 0.1143)
		(layer "In6.Cu")
		(net "P5E_CPU1_P2_RX_DP<3>")
	)
	(segment
		(start 115.669314 -285.90113)
		(end 115.68684 -285.89097)
		(width 0.1143)
		(layer "In6.Cu")
		(net "P5E_CPU1_P2_RX_DP<3>")
	)
	(segment
		(start 137.091166 -344.104214)
		(end 133.22554 -324.669658)
		(width 0.14224)
		(layer "In6.Cu")
		(net "P5E_CPU1_P2_RX_DP<3>")
	)
	(segment
		(start 117.416834 -282.996386)
		(end 117.714776 -282.996386)
		(width 0.1143)
		(layer "In6.Cu")
		(net "P5E_CPU1_P2_RX_DP<3>")
	)
	(segment
		(start 115.67922 -293.057072)
		(end 115.654582 -293.042848)
		(width 0.1143)
		(layer "In6.Cu")
		(net "P5E_CPU1_P2_RX_DP<3>")
	)
	(segment
		(start 151.69642 -381.808482)
		(end 151.696166 -381.808228)
		(width 0.14224)
		(layer "In6.Cu")
		(net "P5E_CPU1_P2_RX_DP<3>")
	)
	(segment
		(start 115.64874 -289.799268)
		(end 115.647724 -289.79876)
		(width 0.1143)
		(layer "In6.Cu")
		(net "P5E_CPU1_P2_RX_DP<3>")
	)
	(segment
		(start 115.679982 -293.05758)
		(end 115.67922 -293.057072)
		(width 0.1143)
		(layer "In6.Cu")
		(net "P5E_CPU1_P2_RX_DP<3>")
	)
	(segment
		(start 115.646962 -289.798252)
		(end 115.644168 -289.796728)
		(width 0.1143)
		(layer "In6.Cu")
		(net "P5E_CPU1_P2_RX_DP<3>")
	)
	(segment
		(start 115.64239 -294.655748)
		(end 115.641628 -294.65524)
		(width 0.1143)
		(layer "In6.Cu")
		(net "P5E_CPU1_P2_RX_DP<3>")
	)
	(segment
		(start 117.058694 -283.483304)
		(end 117.060218 -283.482288)
		(width 0.1143)
		(layer "In6.Cu")
		(net "P5E_CPU1_P2_RX_DP<3>")
	)
	(segment
		(start 115.615974 -294.031924)
		(end 115.678458 -293.995856)
		(width 0.1143)
		(layer "In6.Cu")
		(net "P5E_CPU1_P2_RX_DP<3>")
	)
	(segment
		(start 115.68684 -293.061644)
		(end 115.679982 -293.05758)
		(width 0.1143)
		(layer "In6.Cu")
		(net "P5E_CPU1_P2_RX_DP<3>")
	)
	(segment
		(start 151.696166 -381.808228)
		(end 146.791426 -374.66397)
		(width 0.14224)
		(layer "In6.Cu")
		(net "P5E_CPU1_P2_RX_DP<3>")
	)
	(segment
		(start 115.646962 -294.658288)
		(end 115.644168 -294.656764)
		(width 0.1143)
		(layer "In6.Cu")
		(net "P5E_CPU1_P2_RX_DP<3>")
	)
	(segment
		(start 115.647724 -292.393624)
		(end 115.64874 -292.393116)
		(width 0.1143)
		(layer "In6.Cu")
		(net "P5E_CPU1_P2_RX_DP<3>")
	)
	(segment
		(start 115.650264 -292.3921)
		(end 115.68684 -292.370764)
		(width 0.1143)
		(layer "In6.Cu")
		(net "P5E_CPU1_P2_RX_DP<3>")
	)
	(segment
		(start 115.615974 -290.7919)
		(end 115.68557 -290.751514)
		(width 0.1143)
		(layer "In6.Cu")
		(net "P5E_CPU1_P2_RX_DP<3>")
	)
	(segment
		(start 115.615974 -287.55213)
		(end 115.647724 -287.533842)
		(width 0.1143)
		(layer "In6.Cu")
		(net "P5E_CPU1_P2_RX_DP<3>")
	)
	(segment
		(start 115.647724 -294.658796)
		(end 115.646962 -294.658288)
		(width 0.1143)
		(layer "In6.Cu")
		(net "P5E_CPU1_P2_RX_DP<3>")
	)
	(segment
		(start 115.68684 -288.201608)
		(end 115.614196 -288.15919)
		(width 0.1143)
		(layer "In6.Cu")
		(net "P5E_CPU1_P2_RX_DP<3>")
	)
	(segment
		(start 115.68684 -286.581596)
		(end 115.614196 -286.539178)
		(width 0.1143)
		(layer "In6.Cu")
		(net "P5E_CPU1_P2_RX_DP<3>")
	)
	(segment
		(start 117.33403 -283.07919)
		(end 117.416834 -282.996386)
		(width 0.1143)
		(layer "In6.Cu")
		(net "P5E_CPU1_P2_RX_DP<3>")
	)
	(segment
		(start 151.514048 -385.649216)
		(end 151.688292 -385.548632)
		(width 0.14224)
		(layer "In6.Cu")
		(net "P5E_CPU1_P2_RX_DP<3>")
	)
	(segment
		(start 115.679982 -294.677592)
		(end 115.67922 -294.677084)
		(width 0.1143)
		(layer "In6.Cu")
		(net "P5E_CPU1_P2_RX_DP<3>")
	)
	(segment
		(start 115.615974 -285.932118)
		(end 115.669314 -285.90113)
		(width 0.1143)
		(layer "In6.Cu")
		(net "P5E_CPU1_P2_RX_DP<3>")
	)
	(segment
		(start 115.615974 -289.171888)
		(end 115.664488 -289.14471)
		(width 0.1143)
		(layer "In6.Cu")
		(net "P5E_CPU1_P2_RX_DP<3>")
	)
	(segment
		(start 115.679982 -289.817556)
		(end 115.67922 -289.817048)
		(width 0.1143)
		(layer "In6.Cu")
		(net "P5E_CPU1_P2_RX_DP<3>")
	)
	(segment
		(start 115.654582 -293.042848)
		(end 115.653058 -293.041832)
		(width 0.1143)
		(layer "In6.Cu")
		(net "P5E_CPU1_P2_RX_DP<3>")
	)
	(segment
		(start 115.644168 -293.036752)
		(end 115.643406 -293.036244)
		(width 0.1143)
		(layer "In6.Cu")
		(net "P5E_CPU1_P2_RX_DP<3>")
	)
	(segment
		(start 115.652042 -289.8013)
		(end 115.650518 -289.800284)
		(width 0.1143)
		(layer "In6.Cu")
		(net "P5E_CPU1_P2_RX_DP<3>")
	)
	(segment
		(start 115.643152 -292.396418)
		(end 115.645184 -292.395148)
		(width 0.1143)
		(layer "In6.Cu")
		(net "P5E_CPU1_P2_RX_DP<3>")
	)
	(segment
		(start 146.726656 -374.555258)
		(end 146.61642 -374.33758)
		(width 0.14224)
		(layer "In6.Cu")
		(net "P5E_CPU1_P2_RX_DP<3>")
	)
	(segment
		(start 117.057678 -283.483812)
		(end 117.058694 -283.483304)
		(width 0.1143)
		(layer "In6.Cu")
		(net "P5E_CPU1_P2_RX_DP<3>")
	)
	(segment
		(start 115.647724 -289.79876)
		(end 115.646962 -289.798252)
		(width 0.1143)
		(layer "In6.Cu")
		(net "P5E_CPU1_P2_RX_DP<3>")
	)
	(segment
		(start 115.654582 -291.422836)
		(end 115.653058 -291.42182)
		(width 0.1143)
		(layer "In6.Cu")
		(net "P5E_CPU1_P2_RX_DP<3>")
	)
	(segment
		(start 115.644168 -291.41674)
		(end 115.643406 -291.416232)
		(width 0.1143)
		(layer "In6.Cu")
		(net "P5E_CPU1_P2_RX_DP<3>")
	)
	(segment
		(start 115.650518 -294.66032)
		(end 115.64874 -294.659304)
		(width 0.1143)
		(layer "In6.Cu")
		(net "P5E_CPU1_P2_RX_DP<3>")
	)
	(segment
		(start 115.67922 -294.677084)
		(end 115.654582 -294.66286)
		(width 0.1143)
		(layer "In6.Cu")
		(net "P5E_CPU1_P2_RX_DP<3>")
	)
	(segment
		(start 115.68684 -291.441632)
		(end 115.679982 -291.437568)
		(width 0.1143)
		(layer "In6.Cu")
		(net "P5E_CPU1_P2_RX_DP<3>")
	)
	(segment
		(start 115.64874 -291.41928)
		(end 115.647724 -291.418772)
		(width 0.1143)
		(layer "In6.Cu")
		(net "P5E_CPU1_P2_RX_DP<3>")
	)
	(segment
		(start 115.647724 -287.533842)
		(end 115.6843 -287.512506)
		(width 0.1143)
		(layer "In6.Cu")
		(net "P5E_CPU1_P2_RX_DP<3>")
	)
	(segment
		(start 146.619214 -369.66652)
		(end 146.619214 -368.358674)
		(width 0.14224)
		(layer "In6.Cu")
		(net "P5E_CPU1_P2_RX_DP<3>")
	)
	(segment
		(start 115.68557 -290.751514)
		(end 115.68684 -290.750752)
		(width 0.1143)
		(layer "In6.Cu")
		(net "P5E_CPU1_P2_RX_DP<3>")
	)
	(segment
		(start 116.446554 -298.240704)
		(end 116.446554 -296.353738)
		(width 0.14224)
		(layer "In6.Cu")
		(net "P5E_CPU1_P2_RX_DP<3>")
	)
	(segment
		(start 115.654582 -294.66286)
		(end 115.653058 -294.661844)
		(width 0.1143)
		(layer "In6.Cu")
		(net "P5E_CPU1_P2_RX_DP<3>")
	)
	(segment
		(start 115.64874 -292.393116)
		(end 115.650264 -292.3921)
		(width 0.1143)
		(layer "In6.Cu")
		(net "P5E_CPU1_P2_RX_DP<3>")
	)
	(segment
		(start 117.025928 -283.5021)
		(end 117.056916 -283.48432)
		(width 0.1143)
		(layer "In6.Cu")
		(net "P5E_CPU1_P2_RX_DP<3>")
	)
	(segment
		(start 116.400834 -296.27957)
		(end 116.401088 -296.279316)
		(width 0.1143)
		(layer "In6.Cu")
		(net "P5E_CPU1_P2_RX_DP<3>")
	)
	(segment
		(start 115.639088 -293.033958)
		(end 115.615974 -293.020496)
		(width 0.1143)
		(layer "In6.Cu")
		(net "P5E_CPU1_P2_RX_DP<3>")
	)
	(segment
		(start 115.653058 -294.661844)
		(end 115.652042 -294.661336)
		(width 0.1143)
		(layer "In6.Cu")
		(net "P5E_CPU1_P2_RX_DP<3>")
	)
	(segment
		(start 146.609308 -374.321324)
		(end 146.520154 -374.095264)
		(width 0.14224)
		(layer "In6.Cu")
		(net "P5E_CPU1_P2_RX_DP<3>")
	)
	(segment
		(start 115.653058 -293.041832)
		(end 115.652042 -293.041324)
		(width 0.1143)
		(layer "In6.Cu")
		(net "P5E_CPU1_P2_RX_DP<3>")
	)
	(segment
		(start 115.641628 -294.65524)
		(end 115.639088 -294.65397)
		(width 0.1143)
		(layer "In6.Cu")
		(net "P5E_CPU1_P2_RX_DP<3>")
	)
	(segment
		(start 115.678458 -293.995856)
		(end 115.68176 -293.993824)
		(width 0.1143)
		(layer "In6.Cu")
		(net "P5E_CPU1_P2_RX_DP<3>")
	)
	(segment
		(start 115.639088 -291.413946)
		(end 115.615974 -291.400484)
		(width 0.1143)
		(layer "In6.Cu")
		(net "P5E_CPU1_P2_RX_DP<3>")
	)
	(segment
		(start 115.647724 -293.038784)
		(end 115.646962 -293.038276)
		(width 0.1143)
		(layer "In6.Cu")
		(net "P5E_CPU1_P2_RX_DP<3>")
	)
	(segment
		(start 115.665504 -289.144202)
		(end 115.68684 -289.132518)
		(width 0.1143)
		(layer "In6.Cu")
		(net "P5E_CPU1_P2_RX_DP<3>")
	)
	(segment
		(start 115.652042 -294.661336)
		(end 115.650518 -294.66032)
		(width 0.1143)
		(layer "In6.Cu")
		(net "P5E_CPU1_P2_RX_DP<3>")
	)
	(segment
		(start 115.67922 -291.43706)
		(end 115.654582 -291.422836)
		(width 0.1143)
		(layer "In6.Cu")
		(net "P5E_CPU1_P2_RX_DP<3>")
	)
	(segment
		(start 116.446046 -298.64812)
		(end 116.446046 -298.240704)
		(width 0.14224)
		(layer "In6.Cu")
		(net "P5E_CPU1_P2_RX_DP<3>")
	)
	(arc
		(start 116.15674 -285.080964)
		(mid 116.335553 -284.878614)
		(end 116.400072 -284.616398)
		(width 0.1143)
		(layer "In6.Cu")
		(net "P5E_CPU1_P2_RX_DP<3>")
	)
	(arc
		(start 146.791426 -374.66397)
		(mid 146.757241 -374.610687)
		(end 146.726656 -374.555258)
		(width 0.14224)
		(layer "In6.Cu")
		(net "P5E_CPU1_P2_RX_DP<3>")
	)
	(arc
		(start 151.768302 -382.04013)
		(mid 151.749928 -381.918851)
		(end 151.69642 -381.808482)
		(width 0.14224)
		(layer "In6.Cu")
		(net "P5E_CPU1_P2_RX_DP<3>")
	)
	(arc
		(start 115.930172 -295.146222)
		(mid 115.865657 -294.884003)
		(end 115.68684 -294.681656)
		(width 0.1143)
		(layer "In6.Cu")
		(net "P5E_CPU1_P2_RX_DP<3>")
	)
	(arc
		(start 116.624862 -284.272228)
		(mid 116.786076 -284.07937)
		(end 116.866416 -283.84119)
		(width 0.1143)
		(layer "In6.Cu")
		(net "P5E_CPU1_P2_RX_DP<3>")
	)
	(arc
		(start 115.460018 -287.856422)
		(mid 115.501273 -287.685451)
		(end 115.615974 -287.55213)
		(width 0.1143)
		(layer "In6.Cu")
		(net "P5E_CPU1_P2_RX_DP<3>")
	)
	(arc
		(start 116.400072 -284.616398)
		(mid 116.441327 -284.445427)
		(end 116.556028 -284.312106)
		(width 0.1143)
		(layer "In6.Cu")
		(net "P5E_CPU1_P2_RX_DP<3>")
	)
	(arc
		(start 115.615974 -289.780472)
		(mid 115.460046 -289.47618)
		(end 115.615974 -289.171888)
		(width 0.1143)
		(layer "In6.Cu")
		(net "P5E_CPU1_P2_RX_DP<3>")
	)
	(arc
		(start 115.68684 -293.990776)
		(mid 115.930167 -293.52621)
		(end 115.68684 -293.061644)
		(width 0.1143)
		(layer "In6.Cu")
		(net "P5E_CPU1_P2_RX_DP<3>")
	)
	(arc
		(start 115.68684 -289.13074)
		(mid 115.930167 -288.666174)
		(end 115.68684 -288.201608)
		(width 0.1143)
		(layer "In6.Cu")
		(net "P5E_CPU1_P2_RX_DP<3>")
	)
	(arc
		(start 117.096794 -283.460952)
		(mid 117.248781 -283.304444)
		(end 117.33022 -283.10205)
		(width 0.1143)
		(layer "In6.Cu")
		(net "P5E_CPU1_P2_RX_DP<3>")
	)
	(arc
		(start 115.930172 -287.046162)
		(mid 115.865657 -286.783943)
		(end 115.68684 -286.581596)
		(width 0.1143)
		(layer "In6.Cu")
		(net "P5E_CPU1_P2_RX_DP<3>")
	)
	(arc
		(start 146.61642 -374.33758)
		(mid 146.612817 -374.32991)
		(end 146.609562 -374.322086)
		(width 0.14224)
		(layer "In6.Cu")
		(net "P5E_CPU1_P2_RX_DP<3>")
	)
	(arc
		(start 115.615974 -291.400484)
		(mid 115.460046 -291.096192)
		(end 115.615974 -290.7919)
		(width 0.1143)
		(layer "In6.Cu")
		(net "P5E_CPU1_P2_RX_DP<3>")
	)
	(arc
		(start 115.614196 -288.15919)
		(mid 115.500789 -288.026301)
		(end 115.460018 -287.856422)
		(width 0.1143)
		(layer "In6.Cu")
		(net "P5E_CPU1_P2_RX_DP<3>")
	)
	(arc
		(start 116.087144 -295.451022)
		(mid 115.971717 -295.317646)
		(end 115.930172 -295.146222)
		(width 0.1143)
		(layer "In6.Cu")
		(net "P5E_CPU1_P2_RX_DP<3>")
	)
	(arc
		(start 115.615974 -294.640508)
		(mid 115.460046 -294.336216)
		(end 115.615974 -294.031924)
		(width 0.1143)
		(layer "In6.Cu")
		(net "P5E_CPU1_P2_RX_DP<3>")
	)
	(arc
		(start 116.569998 -299.271182)
		(mid 116.477332 -298.965756)
		(end 116.446046 -298.64812)
		(width 0.14224)
		(layer "In6.Cu")
		(net "P5E_CPU1_P2_RX_DP<3>")
	)
	(arc
		(start 115.68684 -292.370764)
		(mid 115.930167 -291.906198)
		(end 115.68684 -291.441632)
		(width 0.1143)
		(layer "In6.Cu")
		(net "P5E_CPU1_P2_RX_DP<3>")
	)
	(arc
		(start 115.68684 -290.750752)
		(mid 115.930167 -290.286186)
		(end 115.68684 -289.82162)
		(width 0.1143)
		(layer "In6.Cu")
		(net "P5E_CPU1_P2_RX_DP<3>")
	)
	(arc
		(start 116.869972 -283.79674)
		(mid 116.913365 -283.631108)
		(end 117.025928 -283.5021)
		(width 0.1143)
		(layer "In6.Cu")
		(net "P5E_CPU1_P2_RX_DP<3>")
	)
	(arc
		(start 116.866416 -283.84119)
		(mid 116.86876 -283.81901)
		(end 116.869972 -283.79674)
		(width 0.1143)
		(layer "In6.Cu")
		(net "P5E_CPU1_P2_RX_DP<3>")
	)
	(arc
		(start 117.33022 -283.10205)
		(mid 117.332243 -283.09064)
		(end 117.33403 -283.07919)
		(width 0.1143)
		(layer "In6.Cu")
		(net "P5E_CPU1_P2_RX_DP<3>")
	)
	(arc
		(start 115.460018 -286.23641)
		(mid 115.501273 -286.065439)
		(end 115.615974 -285.932118)
		(width 0.1143)
		(layer "In6.Cu")
		(net "P5E_CPU1_P2_RX_DP<3>")
	)
	(arc
		(start 115.68684 -285.89097)
		(mid 115.865653 -285.68862)
		(end 115.930172 -285.426404)
		(width 0.1143)
		(layer "In6.Cu")
		(net "P5E_CPU1_P2_RX_DP<3>")
	)
	(arc
		(start 146.520154 -374.095264)
		(mid 146.463554 -373.871026)
		(end 146.451066 -373.640096)
		(width 0.14224)
		(layer "In6.Cu")
		(net "P5E_CPU1_P2_RX_DP<3>")
	)
	(arc
		(start 115.930172 -285.426404)
		(mid 115.971721 -285.254982)
		(end 116.087144 -285.121604)
		(width 0.1143)
		(layer "In6.Cu")
		(net "P5E_CPU1_P2_RX_DP<3>")
	)
	(arc
		(start 146.619214 -368.358674)
		(mid 146.58241 -367.985098)
		(end 146.473418 -367.625884)
		(width 0.14224)
		(layer "In6.Cu")
		(net "P5E_CPU1_P2_RX_DP<3>")
	)
	(arc
		(start 116.400072 -295.955974)
		(mid 116.335552 -295.69387)
		(end 116.15674 -295.491662)
		(width 0.1143)
		(layer "In6.Cu")
		(net "P5E_CPU1_P2_RX_DP<3>")
	)
	(arc
		(start 115.615974 -293.020496)
		(mid 115.460046 -292.716204)
		(end 115.615974 -292.411912)
		(width 0.1143)
		(layer "In6.Cu")
		(net "P5E_CPU1_P2_RX_DP<3>")
	)
	(arc
		(start 115.614196 -286.539178)
		(mid 115.500789 -286.406289)
		(end 115.460018 -286.23641)
		(width 0.1143)
		(layer "In6.Cu")
		(net "P5E_CPU1_P2_RX_DP<3>")
	)
	(arc
		(start 115.6843 -287.512506)
		(mid 115.864952 -287.309761)
		(end 115.930172 -287.046162)
		(width 0.1143)
		(layer "In6.Cu")
		(net "P5E_CPU1_P2_RX_DP<3>")
	)
	(segment
		(start 114.897916 -285.160466)
		(end 115.364768 -285.426404)
		(width 0.12954)
		(layer "F.Cu")
		(net "P5E_CPU1_P2_RX_DP<2>")
	)
	(segment
		(start 149.698202 -386.003292)
		(end 150.218902 -386.003292)
		(width 0.127)
		(layer "F.Cu")
		(net "P5E_CPU1_P2_RX_DP<2>")
	)
	(segment
		(start 150.57628 -385.046982)
		(end 150.260304 -384.731006)
		(width 0.14224)
		(layer "In6.Cu")
		(net "P5E_CPU1_P2_RX_DP<2>")
	)
	(segment
		(start 114.71529 -285.909258)
		(end 114.716052 -285.90875)
		(width 0.1143)
		(layer "In6.Cu")
		(net "P5E_CPU1_P2_RX_DP<2>")
	)
	(segment
		(start 114.70132 -293.035228)
		(end 114.699796 -293.034212)
		(width 0.1143)
		(layer "In6.Cu")
		(net "P5E_CPU1_P2_RX_DP<2>")
	)
	(segment
		(start 114.71275 -290.770564)
		(end 114.71529 -290.76904)
		(width 0.1143)
		(layer "In6.Cu")
		(net "P5E_CPU1_P2_RX_DP<2>")
	)
	(segment
		(start 143.138398 -369.4176)
		(end 143.138398 -368.116104)
		(width 0.14224)
		(layer "In6.Cu")
		(net "P5E_CPU1_P2_RX_DP<2>")
	)
	(segment
		(start 114.67592 -287.55213)
		(end 114.744246 -287.512506)
		(width 0.1143)
		(layer "In6.Cu")
		(net "P5E_CPU1_P2_RX_DP<2>")
	)
	(segment
		(start 115.216686 -295.491662)
		(end 115.14709 -295.451022)
		(width 0.1143)
		(layer "In6.Cu")
		(net "P5E_CPU1_P2_RX_DP<2>")
	)
	(segment
		(start 114.67592 -290.7919)
		(end 114.706908 -290.77412)
		(width 0.1143)
		(layer "In6.Cu")
		(net "P5E_CPU1_P2_RX_DP<2>")
	)
	(segment
		(start 116.720112 -302.085248)
		(end 115.53698 -299.227748)
		(width 0.14224)
		(layer "In6.Cu")
		(net "P5E_CPU1_P2_RX_DP<2>")
	)
	(segment
		(start 114.706908 -285.914338)
		(end 114.708686 -285.913322)
		(width 0.1143)
		(layer "In6.Cu")
		(net "P5E_CPU1_P2_RX_DP<2>")
	)
	(segment
		(start 143.975836 -370.137944)
		(end 143.806672 -370.06784)
		(width 0.14224)
		(layer "In6.Cu")
		(net "P5E_CPU1_P2_RX_DP<2>")
	)
	(segment
		(start 114.716052 -285.90875)
		(end 114.719354 -285.906972)
		(width 0.1143)
		(layer "In6.Cu")
		(net "P5E_CPU1_P2_RX_DP<2>")
	)
	(segment
		(start 115.50523 -296.32529)
		(end 115.45951 -296.27957)
		(width 0.1143)
		(layer "In6.Cu")
		(net "P5E_CPU1_P2_RX_DP<2>")
	)
	(segment
		(start 115.50523 -297.299888)
		(end 115.505738 -297.299888)
		(width 0.14224)
		(layer "In6.Cu")
		(net "P5E_CPU1_P2_RX_DP<2>")
	)
	(segment
		(start 150.488142 -385.548632)
		(end 150.57628 -385.460494)
		(width 0.14224)
		(layer "In6.Cu")
		(net "P5E_CPU1_P2_RX_DP<2>")
	)
	(segment
		(start 114.746786 -291.441632)
		(end 114.714528 -291.422836)
		(width 0.1143)
		(layer "In6.Cu")
		(net "P5E_CPU1_P2_RX_DP<2>")
	)
	(segment
		(start 143.473678 -369.805712)
		(end 143.175736 -369.50777)
		(width 0.14224)
		(layer "In6.Cu")
		(net "P5E_CPU1_P2_RX_DP<2>")
	)
	(segment
		(start 114.708686 -285.913322)
		(end 114.711734 -285.91129)
		(width 0.1143)
		(layer "In6.Cu")
		(net "P5E_CPU1_P2_RX_DP<2>")
	)
	(segment
		(start 114.711734 -290.771072)
		(end 114.71275 -290.770564)
		(width 0.1143)
		(layer "In6.Cu")
		(net "P5E_CPU1_P2_RX_DP<2>")
	)
	(segment
		(start 115.50523 -297.29938)
		(end 115.50523 -296.353738)
		(width 0.14224)
		(layer "In6.Cu")
		(net "P5E_CPU1_P2_RX_DP<2>")
	)
	(segment
		(start 132.28701 -324.915276)
		(end 128.845564 -318.476884)
		(width 0.14224)
		(layer "In6.Cu")
		(net "P5E_CPU1_P2_RX_DP<2>")
	)
	(segment
		(start 114.71529 -290.76904)
		(end 114.716052 -290.768532)
		(width 0.1143)
		(layer "In6.Cu")
		(net "P5E_CPU1_P2_RX_DP<2>")
	)
	(segment
		(start 114.698272 -292.398958)
		(end 114.699034 -292.39845)
		(width 0.1143)
		(layer "In6.Cu")
		(net "P5E_CPU1_P2_RX_DP<2>")
	)
	(segment
		(start 114.746786 -289.82162)
		(end 114.714528 -289.802824)
		(width 0.1143)
		(layer "In6.Cu")
		(net "P5E_CPU1_P2_RX_DP<2>")
	)
	(segment
		(start 137.057638 -348.070424)
		(end 136.259062 -344.882724)
		(width 0.14224)
		(layer "In6.Cu")
		(net "P5E_CPU1_P2_RX_DP<2>")
	)
	(segment
		(start 114.709956 -293.040054)
		(end 114.708686 -293.039546)
		(width 0.1143)
		(layer "In6.Cu")
		(net "P5E_CPU1_P2_RX_DP<2>")
	)
	(segment
		(start 150.218902 -386.003292)
		(end 150.313898 -385.649216)
		(width 0.14224)
		(layer "In6.Cu")
		(net "P5E_CPU1_P2_RX_DP<2>")
	)
	(segment
		(start 120.746774 -308.111398)
		(end 116.720112 -302.085248)
		(width 0.14224)
		(layer "In6.Cu")
		(net "P5E_CPU1_P2_RX_DP<2>")
	)
	(segment
		(start 114.711734 -285.91129)
		(end 114.71275 -285.910782)
		(width 0.1143)
		(layer "In6.Cu")
		(net "P5E_CPU1_P2_RX_DP<2>")
	)
	(segment
		(start 114.714528 -291.422836)
		(end 114.713766 -291.422328)
		(width 0.1143)
		(layer "In6.Cu")
		(net "P5E_CPU1_P2_RX_DP<2>")
	)
	(segment
		(start 150.263352 -384.3528)
		(end 150.568152 -384.048254)
		(width 0.14224)
		(layer "In6.Cu")
		(net "P5E_CPU1_P2_RX_DP<2>")
	)
	(segment
		(start 114.71275 -294.010588)
		(end 114.71529 -294.009064)
		(width 0.1143)
		(layer "In6.Cu")
		(net "P5E_CPU1_P2_RX_DP<2>")
	)
	(segment
		(start 115.45951 -296.27957)
		(end 115.460018 -296.279062)
		(width 0.1143)
		(layer "In6.Cu")
		(net "P5E_CPU1_P2_RX_DP<2>")
	)
	(segment
		(start 114.984022 -285.509208)
		(end 115.066826 -285.426404)
		(width 0.1143)
		(layer "In6.Cu")
		(net "P5E_CPU1_P2_RX_DP<2>")
	)
	(segment
		(start 145.465038 -374.563386)
		(end 145.072862 -373.75211)
		(width 0.14224)
		(layer "In6.Cu")
		(net "P5E_CPU1_P2_RX_DP<2>")
	)
	(segment
		(start 114.719354 -285.906972)
		(end 114.746786 -285.89097)
		(width 0.1143)
		(layer "In6.Cu")
		(net "P5E_CPU1_P2_RX_DP<2>")
	)
	(segment
		(start 144.917414 -373.072914)
		(end 144.917414 -371.211856)
		(width 0.14224)
		(layer "In6.Cu")
		(net "P5E_CPU1_P2_RX_DP<2>")
	)
	(segment
		(start 114.719354 -292.386766)
		(end 114.746786 -292.370764)
		(width 0.1143)
		(layer "In6.Cu")
		(net "P5E_CPU1_P2_RX_DP<2>")
	)
	(segment
		(start 114.716052 -294.008556)
		(end 114.719354 -294.006778)
		(width 0.1143)
		(layer "In6.Cu")
		(net "P5E_CPU1_P2_RX_DP<2>")
	)
	(segment
		(start 114.714528 -289.802824)
		(end 114.70386 -289.796728)
		(width 0.1143)
		(layer "In6.Cu")
		(net "P5E_CPU1_P2_RX_DP<2>")
	)
	(segment
		(start 114.70386 -292.39591)
		(end 114.704876 -292.395402)
		(width 0.1143)
		(layer "In6.Cu")
		(net "P5E_CPU1_P2_RX_DP<2>")
	)
	(segment
		(start 114.704622 -293.03726)
		(end 114.70132 -293.035228)
		(width 0.1143)
		(layer "In6.Cu")
		(net "P5E_CPU1_P2_RX_DP<2>")
	)
	(segment
		(start 114.671602 -290.795202)
		(end 114.67592 -290.7919)
		(width 0.1143)
		(layer "In6.Cu")
		(net "P5E_CPU1_P2_RX_DP<2>")
	)
	(segment
		(start 114.708686 -290.773104)
		(end 114.711734 -290.771072)
		(width 0.1143)
		(layer "In6.Cu")
		(net "P5E_CPU1_P2_RX_DP<2>")
	)
	(segment
		(start 114.719354 -294.006778)
		(end 114.746786 -293.990776)
		(width 0.1143)
		(layer "In6.Cu")
		(net "P5E_CPU1_P2_RX_DP<2>")
	)
	(segment
		(start 115.505738 -297.299888)
		(end 115.50523 -297.29938)
		(width 0.14224)
		(layer "In6.Cu")
		(net "P5E_CPU1_P2_RX_DP<2>")
	)
	(segment
		(start 114.71021 -291.420296)
		(end 114.671602 -291.397182)
		(width 0.1143)
		(layer "In6.Cu")
		(net "P5E_CPU1_P2_RX_DP<2>")
	)
	(segment
		(start 114.703606 -294.015668)
		(end 114.704876 -294.01516)
		(width 0.1143)
		(layer "In6.Cu")
		(net "P5E_CPU1_P2_RX_DP<2>")
	)
	(segment
		(start 114.71275 -292.390576)
		(end 114.71529 -292.389052)
		(width 0.1143)
		(layer "In6.Cu")
		(net "P5E_CPU1_P2_RX_DP<2>")
	)
	(segment
		(start 114.67592 -285.932118)
		(end 114.706908 -285.914338)
		(width 0.1143)
		(layer "In6.Cu")
		(net "P5E_CPU1_P2_RX_DP<2>")
	)
	(segment
		(start 114.711734 -294.011096)
		(end 114.71275 -294.010588)
		(width 0.1143)
		(layer "In6.Cu")
		(net "P5E_CPU1_P2_RX_DP<2>")
	)
	(segment
		(start 114.707416 -294.01389)
		(end 114.708686 -294.013128)
		(width 0.1143)
		(layer "In6.Cu")
		(net "P5E_CPU1_P2_RX_DP<2>")
	)
	(segment
		(start 114.73053 -288.19221)
		(end 114.674142 -288.15919)
		(width 0.1143)
		(layer "In6.Cu")
		(net "P5E_CPU1_P2_RX_DP<2>")
	)
	(segment
		(start 150.57628 -385.460494)
		(end 150.57628 -385.046982)
		(width 0.14224)
		(layer "In6.Cu")
		(net "P5E_CPU1_P2_RX_DP<2>")
	)
	(segment
		(start 114.714528 -294.66286)
		(end 114.70386 -294.656764)
		(width 0.1143)
		(layer "In6.Cu")
		(net "P5E_CPU1_P2_RX_DP<2>")
	)
	(segment
		(start 150.492206 -381.803656)
		(end 146.191986 -375.788936)
		(width 0.14224)
		(layer "In6.Cu")
		(net "P5E_CPU1_P2_RX_DP<2>")
	)
	(segment
		(start 114.706908 -290.77412)
		(end 114.708686 -290.773104)
		(width 0.1143)
		(layer "In6.Cu")
		(net "P5E_CPU1_P2_RX_DP<2>")
	)
	(segment
		(start 114.708686 -294.013128)
		(end 114.711734 -294.011096)
		(width 0.1143)
		(layer "In6.Cu")
		(net "P5E_CPU1_P2_RX_DP<2>")
	)
	(segment
		(start 114.719354 -290.766754)
		(end 114.746786 -290.750752)
		(width 0.1143)
		(layer "In6.Cu")
		(net "P5E_CPU1_P2_RX_DP<2>")
	)
	(segment
		(start 144.747234 -370.800884)
		(end 144.303496 -370.357146)
		(width 0.14224)
		(layer "In6.Cu")
		(net "P5E_CPU1_P2_RX_DP<2>")
	)
	(segment
		(start 128.845564 -318.476884)
		(end 127.058674 -315.802264)
		(width 0.14224)
		(layer "In6.Cu")
		(net "P5E_CPU1_P2_RX_DP<2>")
	)
	(segment
		(start 114.716052 -290.768532)
		(end 114.719354 -290.766754)
		(width 0.1143)
		(layer "In6.Cu")
		(net "P5E_CPU1_P2_RX_DP<2>")
	)
	(segment
		(start 143.138398 -368.116104)
		(end 137.057638 -348.070424)
		(width 0.14224)
		(layer "In6.Cu")
		(net "P5E_CPU1_P2_RX_DP<2>")
	)
	(segment
		(start 114.708686 -292.393116)
		(end 114.711734 -292.391084)
		(width 0.1143)
		(layer "In6.Cu")
		(net "P5E_CPU1_P2_RX_DP<2>")
	)
	(segment
		(start 114.699034 -292.39845)
		(end 114.70386 -292.39591)
		(width 0.1143)
		(layer "In6.Cu")
		(net "P5E_CPU1_P2_RX_DP<2>")
	)
	(segment
		(start 114.746786 -294.681656)
		(end 114.739928 -294.677592)
		(width 0.1143)
		(layer "In6.Cu")
		(net "P5E_CPU1_P2_RX_DP<2>")
	)
	(segment
		(start 114.739928 -294.677592)
		(end 114.739166 -294.677084)
		(width 0.1143)
		(layer "In6.Cu")
		(net "P5E_CPU1_P2_RX_DP<2>")
	)
	(segment
		(start 136.259062 -344.882724)
		(end 132.28701 -324.915276)
		(width 0.14224)
		(layer "In6.Cu")
		(net "P5E_CPU1_P2_RX_DP<2>")
	)
	(segment
		(start 114.708686 -293.039546)
		(end 114.704622 -293.03726)
		(width 0.1143)
		(layer "In6.Cu")
		(net "P5E_CPU1_P2_RX_DP<2>")
	)
	(segment
		(start 150.313898 -385.649216)
		(end 150.488142 -385.548632)
		(width 0.14224)
		(layer "In6.Cu")
		(net "P5E_CPU1_P2_RX_DP<2>")
	)
	(segment
		(start 114.713766 -291.422328)
		(end 114.71021 -291.420296)
		(width 0.1143)
		(layer "In6.Cu")
		(net "P5E_CPU1_P2_RX_DP<2>")
	)
	(segment
		(start 114.716052 -292.388544)
		(end 114.719354 -292.386766)
		(width 0.1143)
		(layer "In6.Cu")
		(net "P5E_CPU1_P2_RX_DP<2>")
	)
	(segment
		(start 114.706146 -292.394386)
		(end 114.708686 -292.393116)
		(width 0.1143)
		(layer "In6.Cu")
		(net "P5E_CPU1_P2_RX_DP<2>")
	)
	(segment
		(start 114.704876 -294.01516)
		(end 114.707416 -294.01389)
		(width 0.1143)
		(layer "In6.Cu")
		(net "P5E_CPU1_P2_RX_DP<2>")
	)
	(segment
		(start 150.568152 -384.048254)
		(end 150.568152 -382.041654)
		(width 0.14224)
		(layer "In6.Cu")
		(net "P5E_CPU1_P2_RX_DP<2>")
	)
	(segment
		(start 114.714528 -293.042848)
		(end 114.709956 -293.040054)
		(width 0.1143)
		(layer "In6.Cu")
		(net "P5E_CPU1_P2_RX_DP<2>")
	)
	(segment
		(start 150.260304 -384.731006)
		(end 150.263352 -384.3528)
		(width 0.14224)
		(layer "In6.Cu")
		(net "P5E_CPU1_P2_RX_DP<2>")
	)
	(segment
		(start 114.739166 -294.677084)
		(end 114.714528 -294.66286)
		(width 0.1143)
		(layer "In6.Cu")
		(net "P5E_CPU1_P2_RX_DP<2>")
	)
	(segment
		(start 127.058674 -315.802264)
		(end 120.746774 -308.111398)
		(width 0.14224)
		(layer "In6.Cu")
		(net "P5E_CPU1_P2_RX_DP<2>")
	)
	(segment
		(start 114.697256 -293.032942)
		(end 114.67592 -293.020496)
		(width 0.1143)
		(layer "In6.Cu")
		(net "P5E_CPU1_P2_RX_DP<2>")
	)
	(segment
		(start 114.71275 -285.910782)
		(end 114.71529 -285.909258)
		(width 0.1143)
		(layer "In6.Cu")
		(net "P5E_CPU1_P2_RX_DP<2>")
	)
	(segment
		(start 115.460018 -296.279062)
		(end 115.460018 -295.956228)
		(width 0.1143)
		(layer "In6.Cu")
		(net "P5E_CPU1_P2_RX_DP<2>")
	)
	(segment
		(start 114.703606 -289.155632)
		(end 114.7064 -289.154108)
		(width 0.1143)
		(layer "In6.Cu")
		(net "P5E_CPU1_P2_RX_DP<2>")
	)
	(segment
		(start 114.746786 -293.061644)
		(end 114.714528 -293.042848)
		(width 0.1143)
		(layer "In6.Cu")
		(net "P5E_CPU1_P2_RX_DP<2>")
	)
	(segment
		(start 114.71529 -292.389052)
		(end 114.716052 -292.388544)
		(width 0.1143)
		(layer "In6.Cu")
		(net "P5E_CPU1_P2_RX_DP<2>")
	)
	(segment
		(start 114.699796 -293.034212)
		(end 114.697256 -293.032942)
		(width 0.1143)
		(layer "In6.Cu")
		(net "P5E_CPU1_P2_RX_DP<2>")
	)
	(segment
		(start 114.746786 -286.581596)
		(end 114.674142 -286.539178)
		(width 0.1143)
		(layer "In6.Cu")
		(net "P5E_CPU1_P2_RX_DP<2>")
	)
	(segment
		(start 115.50523 -299.068744)
		(end 115.50523 -297.299888)
		(width 0.14224)
		(layer "In6.Cu")
		(net "P5E_CPU1_P2_RX_DP<2>")
	)
	(segment
		(start 114.694208 -292.401244)
		(end 114.698272 -292.398958)
		(width 0.1143)
		(layer "In6.Cu")
		(net "P5E_CPU1_P2_RX_DP<2>")
	)
	(segment
		(start 115.066826 -285.426404)
		(end 115.364768 -285.426404)
		(width 0.1143)
		(layer "In6.Cu")
		(net "P5E_CPU1_P2_RX_DP<2>")
	)
	(segment
		(start 114.71529 -294.009064)
		(end 114.716052 -294.008556)
		(width 0.1143)
		(layer "In6.Cu")
		(net "P5E_CPU1_P2_RX_DP<2>")
	)
	(segment
		(start 114.67592 -292.411912)
		(end 114.694208 -292.401244)
		(width 0.1143)
		(layer "In6.Cu")
		(net "P5E_CPU1_P2_RX_DP<2>")
	)
	(segment
		(start 115.50523 -296.353738)
		(end 115.50523 -296.32529)
		(width 0.1143)
		(layer "In6.Cu")
		(net "P5E_CPU1_P2_RX_DP<2>")
	)
	(segment
		(start 114.7064 -289.154108)
		(end 114.733578 -289.138614)
		(width 0.1143)
		(layer "In6.Cu")
		(net "P5E_CPU1_P2_RX_DP<2>")
	)
	(segment
		(start 114.711734 -292.391084)
		(end 114.71275 -292.390576)
		(width 0.1143)
		(layer "In6.Cu")
		(net "P5E_CPU1_P2_RX_DP<2>")
	)
	(segment
		(start 114.704876 -292.395402)
		(end 114.706146 -292.394386)
		(width 0.1143)
		(layer "In6.Cu")
		(net "P5E_CPU1_P2_RX_DP<2>")
	)
	(arc
		(start 114.746786 -290.750752)
		(mid 114.990113 -290.286186)
		(end 114.746786 -289.82162)
		(width 0.1143)
		(layer "In6.Cu")
		(net "P5E_CPU1_P2_RX_DP<2>")
	)
	(arc
		(start 114.738404 -288.197036)
		(mid 114.734477 -288.194606)
		(end 114.73053 -288.19221)
		(width 0.1143)
		(layer "In6.Cu")
		(net "P5E_CPU1_P2_RX_DP<2>")
	)
	(arc
		(start 115.14709 -295.451022)
		(mid 115.031663 -295.317646)
		(end 114.990118 -295.146222)
		(width 0.1143)
		(layer "In6.Cu")
		(net "P5E_CPU1_P2_RX_DP<2>")
	)
	(arc
		(start 114.674142 -286.539178)
		(mid 114.560735 -286.406289)
		(end 114.519964 -286.23641)
		(width 0.1143)
		(layer "In6.Cu")
		(net "P5E_CPU1_P2_RX_DP<2>")
	)
	(arc
		(start 115.53698 -299.227748)
		(mid 115.513255 -299.149812)
		(end 115.50523 -299.068744)
		(width 0.14224)
		(layer "In6.Cu")
		(net "P5E_CPU1_P2_RX_DP<2>")
	)
	(arc
		(start 114.519964 -286.23641)
		(mid 114.564035 -286.066874)
		(end 114.67592 -285.932118)
		(width 0.1143)
		(layer "In6.Cu")
		(net "P5E_CPU1_P2_RX_DP<2>")
	)
	(arc
		(start 114.746786 -285.89097)
		(mid 114.898773 -285.734462)
		(end 114.980212 -285.532068)
		(width 0.1143)
		(layer "In6.Cu")
		(net "P5E_CPU1_P2_RX_DP<2>")
	)
	(arc
		(start 143.806672 -370.06784)
		(mid 143.671788 -369.997857)
		(end 143.550894 -369.905788)
		(width 0.14224)
		(layer "In6.Cu")
		(net "P5E_CPU1_P2_RX_DP<2>")
	)
	(arc
		(start 115.460018 -295.956228)
		(mid 115.395523 -295.693984)
		(end 115.216686 -295.491662)
		(width 0.1143)
		(layer "In6.Cu")
		(net "P5E_CPU1_P2_RX_DP<2>")
	)
	(arc
		(start 144.917414 -371.211856)
		(mid 144.873244 -370.989419)
		(end 144.747234 -370.800884)
		(width 0.14224)
		(layer "In6.Cu")
		(net "P5E_CPU1_P2_RX_DP<2>")
	)
	(arc
		(start 145.072862 -373.75211)
		(mid 144.956737 -373.4213)
		(end 144.917414 -373.072914)
		(width 0.14224)
		(layer "In6.Cu")
		(net "P5E_CPU1_P2_RX_DP<2>")
	)
	(arc
		(start 146.191986 -375.788936)
		(mid 145.802389 -375.191656)
		(end 145.465038 -374.563386)
		(width 0.14224)
		(layer "In6.Cu")
		(net "P5E_CPU1_P2_RX_DP<2>")
	)
	(arc
		(start 114.744246 -287.512506)
		(mid 114.990134 -287.047712)
		(end 114.746786 -286.581596)
		(width 0.1143)
		(layer "In6.Cu")
		(net "P5E_CPU1_P2_RX_DP<2>")
	)
	(arc
		(start 114.746786 -292.370764)
		(mid 114.990113 -291.906198)
		(end 114.746786 -291.441632)
		(width 0.1143)
		(layer "In6.Cu")
		(net "P5E_CPU1_P2_RX_DP<2>")
	)
	(arc
		(start 144.303496 -370.357146)
		(mid 144.150445 -370.231437)
		(end 143.975836 -370.137944)
		(width 0.14224)
		(layer "In6.Cu")
		(net "P5E_CPU1_P2_RX_DP<2>")
	)
	(arc
		(start 114.67592 -293.020496)
		(mid 114.519992 -292.716204)
		(end 114.67592 -292.411912)
		(width 0.1143)
		(layer "In6.Cu")
		(net "P5E_CPU1_P2_RX_DP<2>")
	)
	(arc
		(start 143.175736 -369.50777)
		(mid 143.148093 -369.4664)
		(end 143.138398 -369.4176)
		(width 0.14224)
		(layer "In6.Cu")
		(net "P5E_CPU1_P2_RX_DP<2>")
	)
	(arc
		(start 143.550894 -369.905788)
		(mid 143.507831 -369.859186)
		(end 143.473678 -369.805712)
		(width 0.14224)
		(layer "In6.Cu")
		(net "P5E_CPU1_P2_RX_DP<2>")
	)
	(arc
		(start 114.674142 -288.15919)
		(mid 114.560735 -288.026301)
		(end 114.519964 -287.856422)
		(width 0.1143)
		(layer "In6.Cu")
		(net "P5E_CPU1_P2_RX_DP<2>")
	)
	(arc
		(start 114.980212 -285.532068)
		(mid 114.982235 -285.520658)
		(end 114.984022 -285.509208)
		(width 0.1143)
		(layer "In6.Cu")
		(net "P5E_CPU1_P2_RX_DP<2>")
	)
	(arc
		(start 114.70386 -294.656764)
		(mid 114.520103 -294.336326)
		(end 114.703606 -294.015668)
		(width 0.1143)
		(layer "In6.Cu")
		(net "P5E_CPU1_P2_RX_DP<2>")
	)
	(arc
		(start 114.70386 -289.796728)
		(mid 114.520103 -289.47629)
		(end 114.703606 -289.155632)
		(width 0.1143)
		(layer "In6.Cu")
		(net "P5E_CPU1_P2_RX_DP<2>")
	)
	(arc
		(start 150.568152 -382.041654)
		(mid 150.548777 -381.916722)
		(end 150.492206 -381.803656)
		(width 0.14224)
		(layer "In6.Cu")
		(net "P5E_CPU1_P2_RX_DP<2>")
	)
	(arc
		(start 114.746786 -293.990776)
		(mid 114.990113 -293.52621)
		(end 114.746786 -293.061644)
		(width 0.1143)
		(layer "In6.Cu")
		(net "P5E_CPU1_P2_RX_DP<2>")
	)
	(arc
		(start 114.733578 -289.138614)
		(mid 114.992285 -288.669097)
		(end 114.738404 -288.197036)
		(width 0.1143)
		(layer "In6.Cu")
		(net "P5E_CPU1_P2_RX_DP<2>")
	)
	(arc
		(start 114.671602 -291.397182)
		(mid 114.517298 -291.096192)
		(end 114.671602 -290.795202)
		(width 0.1143)
		(layer "In6.Cu")
		(net "P5E_CPU1_P2_RX_DP<2>")
	)
	(arc
		(start 114.519964 -287.856422)
		(mid 114.563024 -287.686367)
		(end 114.67592 -287.55213)
		(width 0.1143)
		(layer "In6.Cu")
		(net "P5E_CPU1_P2_RX_DP<2>")
	)
	(arc
		(start 114.990118 -295.146222)
		(mid 114.925603 -294.884003)
		(end 114.746786 -294.681656)
		(width 0.1143)
		(layer "In6.Cu")
		(net "P5E_CPU1_P2_RX_DP<2>")
	)
	(segment
		(start 148.498306 -386.003292)
		(end 149.019006 -386.003292)
		(width 0.127)
		(layer "F.Cu")
		(net "P5E_CPU1_P2_RX_DP<1>")
	)
	(segment
		(start 114.897916 -283.540454)
		(end 115.364768 -283.806392)
		(width 0.12954)
		(layer "F.Cu")
		(net "P5E_CPU1_P2_RX_DP<1>")
	)
	(segment
		(start 144.837658 -376.373898)
		(end 142.07236 -372.983252)
		(width 0.14224)
		(layer "In6.Cu")
		(net "P5E_CPU1_P2_RX_DP<1>")
	)
	(segment
		(start 114.565684 -299.216064)
		(end 114.565684 -296.353738)
		(width 0.14224)
		(layer "In6.Cu")
		(net "P5E_CPU1_P2_RX_DP<1>")
	)
	(segment
		(start 113.737136 -287.551622)
		(end 113.804192 -287.512506)
		(width 0.1143)
		(layer "In6.Cu")
		(net "P5E_CPU1_P2_RX_DP<1>")
	)
	(segment
		(start 149.063456 -384.3528)
		(end 149.368256 -384.048)
		(width 0.14224)
		(layer "In6.Cu")
		(net "P5E_CPU1_P2_RX_DP<1>")
	)
	(segment
		(start 113.737136 -294.031416)
		(end 113.806732 -293.990776)
		(width 0.1143)
		(layer "In6.Cu")
		(net "P5E_CPU1_P2_RX_DP<1>")
	)
	(segment
		(start 113.767616 -293.038784)
		(end 113.766854 -293.038276)
		(width 0.1143)
		(layer "In6.Cu")
		(net "P5E_CPU1_P2_RX_DP<1>")
	)
	(segment
		(start 113.772188 -288.181288)
		(end 113.735104 -288.159952)
		(width 0.1143)
		(layer "In6.Cu")
		(net "P5E_CPU1_P2_RX_DP<1>")
	)
	(segment
		(start 113.763806 -285.915862)
		(end 113.767108 -285.914084)
		(width 0.1143)
		(layer "In6.Cu")
		(net "P5E_CPU1_P2_RX_DP<1>")
	)
	(segment
		(start 113.735866 -293.020496)
		(end 113.731548 -293.017194)
		(width 0.1143)
		(layer "In6.Cu")
		(net "P5E_CPU1_P2_RX_DP<1>")
	)
	(segment
		(start 113.768632 -292.393116)
		(end 113.770156 -292.3921)
		(width 0.1143)
		(layer "In6.Cu")
		(net "P5E_CPU1_P2_RX_DP<1>")
	)
	(segment
		(start 114.276632 -295.491662)
		(end 114.207036 -295.451022)
		(width 0.1143)
		(layer "In6.Cu")
		(net "P5E_CPU1_P2_RX_DP<1>")
	)
	(segment
		(start 113.770156 -292.3921)
		(end 113.806732 -292.370764)
		(width 0.1143)
		(layer "In6.Cu")
		(net "P5E_CPU1_P2_RX_DP<1>")
	)
	(segment
		(start 113.766854 -292.394132)
		(end 113.767616 -292.393624)
		(width 0.1143)
		(layer "In6.Cu")
		(net "P5E_CPU1_P2_RX_DP<1>")
	)
	(segment
		(start 113.76787 -285.913576)
		(end 113.805208 -285.891986)
		(width 0.1143)
		(layer "In6.Cu")
		(net "P5E_CPU1_P2_RX_DP<1>")
	)
	(segment
		(start 131.341622 -325.162926)
		(end 131.341114 -325.162926)
		(width 0.14224)
		(layer "In6.Cu")
		(net "P5E_CPU1_P2_RX_DP<1>")
	)
	(segment
		(start 113.766854 -293.038276)
		(end 113.735866 -293.020496)
		(width 0.1143)
		(layer "In6.Cu")
		(net "P5E_CPU1_P2_RX_DP<1>")
	)
	(segment
		(start 149.019006 -386.003292)
		(end 149.114002 -385.649216)
		(width 0.14224)
		(layer "In6.Cu")
		(net "P5E_CPU1_P2_RX_DP<1>")
	)
	(segment
		(start 113.806732 -289.82162)
		(end 113.737136 -289.78098)
		(width 0.1143)
		(layer "In6.Cu")
		(net "P5E_CPU1_P2_RX_DP<1>")
	)
	(segment
		(start 115.066826 -283.806392)
		(end 115.364768 -283.806392)
		(width 0.1143)
		(layer "In6.Cu")
		(net "P5E_CPU1_P2_RX_DP<1>")
	)
	(segment
		(start 149.368256 -384.048)
		(end 149.368256 -382.075436)
		(width 0.14224)
		(layer "In6.Cu")
		(net "P5E_CPU1_P2_RX_DP<1>")
	)
	(segment
		(start 113.767616 -289.1536)
		(end 113.772188 -289.15106)
		(width 0.1143)
		(layer "In6.Cu")
		(net "P5E_CPU1_P2_RX_DP<1>")
	)
	(segment
		(start 126.33579 -316.412372)
		(end 120.067832 -308.7751)
		(width 0.14224)
		(layer "In6.Cu")
		(net "P5E_CPU1_P2_RX_DP<1>")
	)
	(segment
		(start 114.684048 -284.307534)
		(end 114.706908 -284.294326)
		(width 0.1143)
		(layer "In6.Cu")
		(net "P5E_CPU1_P2_RX_DP<1>")
	)
	(segment
		(start 135.821928 -347.692726)
		(end 131.341622 -325.162926)
		(width 0.14224)
		(layer "In6.Cu")
		(net "P5E_CPU1_P2_RX_DP<1>")
	)
	(segment
		(start 114.984022 -283.889196)
		(end 115.066826 -283.806392)
		(width 0.1143)
		(layer "In6.Cu")
		(net "P5E_CPU1_P2_RX_DP<1>")
	)
	(segment
		(start 149.276308 -381.817118)
		(end 149.276054 -381.816864)
		(width 0.14224)
		(layer "In6.Cu")
		(net "P5E_CPU1_P2_RX_DP<1>")
	)
	(segment
		(start 113.731548 -292.415214)
		(end 113.735866 -292.411912)
		(width 0.1143)
		(layer "In6.Cu")
		(net "P5E_CPU1_P2_RX_DP<1>")
	)
	(segment
		(start 141.527276 -372.093998)
		(end 141.524736 -372.08841)
		(width 0.14224)
		(layer "In6.Cu")
		(net "P5E_CPU1_P2_RX_DP<1>")
	)
	(segment
		(start 113.806732 -291.441632)
		(end 113.737136 -291.400992)
		(width 0.1143)
		(layer "In6.Cu")
		(net "P5E_CPU1_P2_RX_DP<1>")
	)
	(segment
		(start 149.060408 -384.731006)
		(end 149.063456 -384.3528)
		(width 0.14224)
		(layer "In6.Cu")
		(net "P5E_CPU1_P2_RX_DP<1>")
	)
	(segment
		(start 113.799874 -286.577786)
		(end 113.76406 -286.556958)
		(width 0.1143)
		(layer "In6.Cu")
		(net "P5E_CPU1_P2_RX_DP<1>")
	)
	(segment
		(start 114.237008 -285.104078)
		(end 114.276124 -285.081726)
		(width 0.1143)
		(layer "In6.Cu")
		(net "P5E_CPU1_P2_RX_DP<1>")
	)
	(segment
		(start 141.329156 -371.335808)
		(end 141.07795 -368.672364)
		(width 0.14224)
		(layer "In6.Cu")
		(net "P5E_CPU1_P2_RX_DP<1>")
	)
	(segment
		(start 113.737136 -289.17138)
		(end 113.767616 -289.1536)
		(width 0.1143)
		(layer "In6.Cu")
		(net "P5E_CPU1_P2_RX_DP<1>")
	)
	(segment
		(start 114.565684 -296.353738)
		(end 114.565684 -296.32529)
		(width 0.1143)
		(layer "In6.Cu")
		(net "P5E_CPU1_P2_RX_DP<1>")
	)
	(segment
		(start 149.114002 -385.649216)
		(end 149.288246 -385.548632)
		(width 0.14224)
		(layer "In6.Cu")
		(net "P5E_CPU1_P2_RX_DP<1>")
	)
	(segment
		(start 114.20602 -285.122112)
		(end 114.237008 -285.104078)
		(width 0.1143)
		(layer "In6.Cu")
		(net "P5E_CPU1_P2_RX_DP<1>")
	)
	(segment
		(start 113.768632 -293.039292)
		(end 113.767616 -293.038784)
		(width 0.1143)
		(layer "In6.Cu")
		(net "P5E_CPU1_P2_RX_DP<1>")
	)
	(segment
		(start 141.07795 -368.672364)
		(end 135.821928 -347.692726)
		(width 0.14224)
		(layer "In6.Cu")
		(net "P5E_CPU1_P2_RX_DP<1>")
	)
	(segment
		(start 113.806732 -294.681656)
		(end 113.737136 -294.641016)
		(width 0.1143)
		(layer "In6.Cu")
		(net "P5E_CPU1_P2_RX_DP<1>")
	)
	(segment
		(start 127.982218 -318.87668)
		(end 126.33579 -316.412372)
		(width 0.14224)
		(layer "In6.Cu")
		(net "P5E_CPU1_P2_RX_DP<1>")
	)
	(segment
		(start 114.706908 -284.294326)
		(end 114.709194 -284.292802)
		(width 0.1143)
		(layer "In6.Cu")
		(net "P5E_CPU1_P2_RX_DP<1>")
	)
	(segment
		(start 114.709194 -284.292802)
		(end 114.746786 -284.270958)
		(width 0.1143)
		(layer "In6.Cu")
		(net "P5E_CPU1_P2_RX_DP<1>")
	)
	(segment
		(start 114.519964 -296.27957)
		(end 114.519964 -295.956228)
		(width 0.1143)
		(layer "In6.Cu")
		(net "P5E_CPU1_P2_RX_DP<1>")
	)
	(segment
		(start 113.806732 -293.061644)
		(end 113.770156 -293.040308)
		(width 0.1143)
		(layer "In6.Cu")
		(net "P5E_CPU1_P2_RX_DP<1>")
	)
	(segment
		(start 113.737136 -290.791392)
		(end 113.806732 -290.750752)
		(width 0.1143)
		(layer "In6.Cu")
		(net "P5E_CPU1_P2_RX_DP<1>")
	)
	(segment
		(start 149.288246 -385.548632)
		(end 149.376384 -385.460494)
		(width 0.14224)
		(layer "In6.Cu")
		(net "P5E_CPU1_P2_RX_DP<1>")
	)
	(segment
		(start 113.767108 -285.914084)
		(end 113.76787 -285.913576)
		(width 0.1143)
		(layer "In6.Cu")
		(net "P5E_CPU1_P2_RX_DP<1>")
	)
	(segment
		(start 113.806732 -286.581596)
		(end 113.799874 -286.577786)
		(width 0.1143)
		(layer "In6.Cu")
		(net "P5E_CPU1_P2_RX_DP<1>")
	)
	(segment
		(start 120.067832 -308.7751)
		(end 115.810792 -302.403764)
		(width 0.14224)
		(layer "In6.Cu")
		(net "P5E_CPU1_P2_RX_DP<1>")
	)
	(segment
		(start 113.770156 -293.040308)
		(end 113.768632 -293.039292)
		(width 0.1143)
		(layer "In6.Cu")
		(net "P5E_CPU1_P2_RX_DP<1>")
	)
	(segment
		(start 149.376384 -385.046982)
		(end 149.060408 -384.731006)
		(width 0.14224)
		(layer "In6.Cu")
		(net "P5E_CPU1_P2_RX_DP<1>")
	)
	(segment
		(start 114.565684 -296.32529)
		(end 114.519964 -296.27957)
		(width 0.1143)
		(layer "In6.Cu")
		(net "P5E_CPU1_P2_RX_DP<1>")
	)
	(segment
		(start 149.376384 -385.460494)
		(end 149.376384 -385.046982)
		(width 0.14224)
		(layer "In6.Cu")
		(net "P5E_CPU1_P2_RX_DP<1>")
	)
	(segment
		(start 113.767616 -292.393624)
		(end 113.768632 -292.393116)
		(width 0.1143)
		(layer "In6.Cu")
		(net "P5E_CPU1_P2_RX_DP<1>")
	)
	(segment
		(start 115.810792 -302.403764)
		(end 114.63528 -299.565314)
		(width 0.14224)
		(layer "In6.Cu")
		(net "P5E_CPU1_P2_RX_DP<1>")
	)
	(segment
		(start 113.735866 -292.411912)
		(end 113.766854 -292.394132)
		(width 0.1143)
		(layer "In6.Cu")
		(net "P5E_CPU1_P2_RX_DP<1>")
	)
	(segment
		(start 131.341114 -325.162926)
		(end 127.982218 -318.87668)
		(width 0.14224)
		(layer "In6.Cu")
		(net "P5E_CPU1_P2_RX_DP<1>")
	)
	(segment
		(start 149.276054 -381.816864)
		(end 144.837658 -376.373898)
		(width 0.14224)
		(layer "In6.Cu")
		(net "P5E_CPU1_P2_RX_DP<1>")
	)
	(arc
		(start 113.806732 -290.750752)
		(mid 114.050059 -290.286186)
		(end 113.806732 -289.82162)
		(width 0.1143)
		(layer "In6.Cu")
		(net "P5E_CPU1_P2_RX_DP<1>")
	)
	(arc
		(start 114.660934 -284.32887)
		(mid 114.672313 -284.318009)
		(end 114.684048 -284.307534)
		(width 0.1143)
		(layer "In6.Cu")
		(net "P5E_CPU1_P2_RX_DP<1>")
	)
	(arc
		(start 114.519964 -295.956228)
		(mid 114.455503 -295.693983)
		(end 114.276632 -295.491662)
		(width 0.1143)
		(layer "In6.Cu")
		(net "P5E_CPU1_P2_RX_DP<1>")
	)
	(arc
		(start 113.804192 -287.512506)
		(mid 113.984844 -287.309761)
		(end 114.050064 -287.046162)
		(width 0.1143)
		(layer "In6.Cu")
		(net "P5E_CPU1_P2_RX_DP<1>")
	)
	(arc
		(start 113.580164 -287.856422)
		(mid 113.621713 -287.685)
		(end 113.737136 -287.551622)
		(width 0.1143)
		(layer "In6.Cu")
		(net "P5E_CPU1_P2_RX_DP<1>")
	)
	(arc
		(start 113.735104 -288.159952)
		(mid 113.621175 -288.026805)
		(end 113.580164 -287.856422)
		(width 0.1143)
		(layer "In6.Cu")
		(net "P5E_CPU1_P2_RX_DP<1>")
	)
	(arc
		(start 113.76406 -286.556958)
		(mid 113.580303 -286.23652)
		(end 113.763806 -285.915862)
		(width 0.1143)
		(layer "In6.Cu")
		(net "P5E_CPU1_P2_RX_DP<1>")
	)
	(arc
		(start 113.731548 -293.017194)
		(mid 113.577244 -292.716204)
		(end 113.731548 -292.415214)
		(width 0.1143)
		(layer "In6.Cu")
		(net "P5E_CPU1_P2_RX_DP<1>")
	)
	(arc
		(start 113.806732 -285.89097)
		(mid 113.985545 -285.68862)
		(end 114.050064 -285.426404)
		(width 0.1143)
		(layer "In6.Cu")
		(net "P5E_CPU1_P2_RX_DP<1>")
	)
	(arc
		(start 142.07236 -372.983252)
		(mid 141.769902 -372.556961)
		(end 141.527276 -372.093998)
		(width 0.14224)
		(layer "In6.Cu")
		(net "P5E_CPU1_P2_RX_DP<1>")
	)
	(arc
		(start 114.050064 -295.146222)
		(mid 113.985549 -294.884003)
		(end 113.806732 -294.681656)
		(width 0.1143)
		(layer "In6.Cu")
		(net "P5E_CPU1_P2_RX_DP<1>")
	)
	(arc
		(start 113.737136 -289.78098)
		(mid 113.580159 -289.47618)
		(end 113.737136 -289.17138)
		(width 0.1143)
		(layer "In6.Cu")
		(net "P5E_CPU1_P2_RX_DP<1>")
	)
	(arc
		(start 114.980212 -283.912056)
		(mid 114.982235 -283.900646)
		(end 114.984022 -283.889196)
		(width 0.1143)
		(layer "In6.Cu")
		(net "P5E_CPU1_P2_RX_DP<1>")
	)
	(arc
		(start 113.805208 -285.891986)
		(mid 113.80597 -285.891479)
		(end 113.806732 -285.89097)
		(width 0.1143)
		(layer "In6.Cu")
		(net "P5E_CPU1_P2_RX_DP<1>")
	)
	(arc
		(start 149.368256 -382.075436)
		(mid 149.344601 -381.938325)
		(end 149.276308 -381.817118)
		(width 0.14224)
		(layer "In6.Cu")
		(net "P5E_CPU1_P2_RX_DP<1>")
	)
	(arc
		(start 114.207036 -295.451022)
		(mid 114.091609 -295.317646)
		(end 114.050064 -295.146222)
		(width 0.1143)
		(layer "In6.Cu")
		(net "P5E_CPU1_P2_RX_DP<1>")
	)
	(arc
		(start 114.521742 -284.606492)
		(mid 114.568087 -284.456028)
		(end 114.660934 -284.32887)
		(width 0.1143)
		(layer "In6.Cu")
		(net "P5E_CPU1_P2_RX_DP<1>")
	)
	(arc
		(start 114.520218 -284.633416)
		(mid 114.5206 -284.619933)
		(end 114.521742 -284.606492)
		(width 0.1143)
		(layer "In6.Cu")
		(net "P5E_CPU1_P2_RX_DP<1>")
	)
	(arc
		(start 113.737136 -291.400992)
		(mid 113.580159 -291.096192)
		(end 113.737136 -290.791392)
		(width 0.1143)
		(layer "In6.Cu")
		(net "P5E_CPU1_P2_RX_DP<1>")
	)
	(arc
		(start 114.63528 -299.565314)
		(mid 114.583262 -299.39412)
		(end 114.565684 -299.216064)
		(width 0.14224)
		(layer "In6.Cu")
		(net "P5E_CPU1_P2_RX_DP<1>")
	)
	(arc
		(start 114.276124 -285.081726)
		(mid 114.451625 -284.886672)
		(end 114.520218 -284.633416)
		(width 0.1143)
		(layer "In6.Cu")
		(net "P5E_CPU1_P2_RX_DP<1>")
	)
	(arc
		(start 114.050064 -285.426404)
		(mid 114.091319 -285.255433)
		(end 114.20602 -285.122112)
		(width 0.1143)
		(layer "In6.Cu")
		(net "P5E_CPU1_P2_RX_DP<1>")
	)
	(arc
		(start 114.050064 -287.046162)
		(mid 113.985549 -286.783943)
		(end 113.806732 -286.581596)
		(width 0.1143)
		(layer "In6.Cu")
		(net "P5E_CPU1_P2_RX_DP<1>")
	)
	(arc
		(start 113.806732 -293.990776)
		(mid 114.050059 -293.52621)
		(end 113.806732 -293.061644)
		(width 0.1143)
		(layer "In6.Cu")
		(net "P5E_CPU1_P2_RX_DP<1>")
	)
	(arc
		(start 114.746786 -284.270958)
		(mid 114.898773 -284.11445)
		(end 114.980212 -283.912056)
		(width 0.1143)
		(layer "In6.Cu")
		(net "P5E_CPU1_P2_RX_DP<1>")
	)
	(arc
		(start 113.806732 -292.370764)
		(mid 114.050059 -291.906198)
		(end 113.806732 -291.441632)
		(width 0.1143)
		(layer "In6.Cu")
		(net "P5E_CPU1_P2_RX_DP<1>")
	)
	(arc
		(start 113.737136 -294.641016)
		(mid 113.580159 -294.336216)
		(end 113.737136 -294.031416)
		(width 0.1143)
		(layer "In6.Cu")
		(net "P5E_CPU1_P2_RX_DP<1>")
	)
	(arc
		(start 141.524736 -372.08841)
		(mid 141.396721 -371.719965)
		(end 141.329156 -371.335808)
		(width 0.14224)
		(layer "In6.Cu")
		(net "P5E_CPU1_P2_RX_DP<1>")
	)
	(arc
		(start 113.772188 -289.15106)
		(mid 114.050388 -288.666174)
		(end 113.772188 -288.181288)
		(width 0.1143)
		(layer "In6.Cu")
		(net "P5E_CPU1_P2_RX_DP<1>")
	)
	(segment
		(start 165.298374 -386.003292)
		(end 165.819074 -386.003292)
		(width 0.127)
		(layer "F.Cu")
		(net "P5E_CPU1_P2_RX_DP<15>")
	)
	(segment
		(start 125.707902 -282.730448)
		(end 126.174754 -282.996386)
		(width 0.12954)
		(layer "F.Cu")
		(net "P5E_CPU1_P2_RX_DP<15>")
	)
	(segment
		(start 126.966726 -288.201608)
		(end 126.895098 -288.159952)
		(width 0.1143)
		(layer "In6.Cu")
		(net "P5E_CPU1_P2_RX_DP<15>")
	)
	(segment
		(start 126.89713 -292.411404)
		(end 126.966726 -292.370764)
		(width 0.1143)
		(layer "In6.Cu")
		(net "P5E_CPU1_P2_RX_DP<15>")
	)
	(segment
		(start 126.4539 -284.126686)
		(end 126.453138 -284.126178)
		(width 0.1143)
		(layer "In6.Cu")
		(net "P5E_CPU1_P2_RX_DP<15>")
	)
	(segment
		(start 127.386334 -285.74238)
		(end 127.38481 -285.741618)
		(width 0.1143)
		(layer "In6.Cu")
		(net "P5E_CPU1_P2_RX_DP<15>")
	)
	(segment
		(start 125.806962 -283.066236)
		(end 125.876812 -282.996386)
		(width 0.1143)
		(layer "In6.Cu")
		(net "P5E_CPU1_P2_RX_DP<15>")
	)
	(segment
		(start 126.89713 -289.17138)
		(end 126.966726 -289.13074)
		(width 0.1143)
		(layer "In6.Cu")
		(net "P5E_CPU1_P2_RX_DP<15>")
	)
	(segment
		(start 126.024132 -283.340048)
		(end 125.95606 -283.300678)
		(width 0.1143)
		(layer "In6.Cu")
		(net "P5E_CPU1_P2_RX_DP<15>")
	)
	(segment
		(start 127.39624 -285.747968)
		(end 127.393446 -285.746444)
		(width 0.1143)
		(layer "In6.Cu")
		(net "P5E_CPU1_P2_RX_DP<15>")
	)
	(segment
		(start 168.453562 -382.29413)
		(end 169.541444 -375.865898)
		(width 0.14224)
		(layer "In6.Cu")
		(net "P5E_CPU1_P2_RX_DP<15>")
	)
	(segment
		(start 126.966726 -284.961838)
		(end 126.89713 -284.921198)
		(width 0.1143)
		(layer "In6.Cu")
		(net "P5E_CPU1_P2_RX_DP<15>")
	)
	(segment
		(start 170.96867 -366.022128)
		(end 165.858952 -363.290104)
		(width 0.14224)
		(layer "In6.Cu")
		(net "P5E_CPU1_P2_RX_DP<15>")
	)
	(segment
		(start 130.81508 -300.997874)
		(end 127.72898 -296.380408)
		(width 0.14224)
		(layer "In6.Cu")
		(net "P5E_CPU1_P2_RX_DP<15>")
	)
	(segment
		(start 127.392684 -285.745936)
		(end 127.391414 -285.745174)
		(width 0.1143)
		(layer "In6.Cu")
		(net "P5E_CPU1_P2_RX_DP<15>")
	)
	(segment
		(start 172.207936 -372.056406)
		(end 172.676312 -370.392452)
		(width 0.14224)
		(layer "In6.Cu")
		(net "P5E_CPU1_P2_RX_DP<15>")
	)
	(segment
		(start 166.786814 -384.334512)
		(end 167.569134 -383.62255)
		(width 0.14224)
		(layer "In6.Cu")
		(net "P5E_CPU1_P2_RX_DP<15>")
	)
	(segment
		(start 127.397764 -285.748984)
		(end 127.39624 -285.747968)
		(width 0.1143)
		(layer "In6.Cu")
		(net "P5E_CPU1_P2_RX_DP<15>")
	)
	(segment
		(start 169.682922 -375.531888)
		(end 172.143674 -372.187978)
		(width 0.14224)
		(layer "In6.Cu")
		(net "P5E_CPU1_P2_RX_DP<15>")
	)
	(segment
		(start 127.387604 -285.743142)
		(end 127.386334 -285.74238)
		(width 0.1143)
		(layer "In6.Cu")
		(net "P5E_CPU1_P2_RX_DP<15>")
	)
	(segment
		(start 126.456948 -284.128464)
		(end 126.4539 -284.126686)
		(width 0.1143)
		(layer "In6.Cu")
		(net "P5E_CPU1_P2_RX_DP<15>")
	)
	(segment
		(start 126.460504 -284.130496)
		(end 126.456948 -284.128464)
		(width 0.1143)
		(layer "In6.Cu")
		(net "P5E_CPU1_P2_RX_DP<15>")
	)
	(segment
		(start 126.496826 -284.151832)
		(end 126.489968 -284.147768)
		(width 0.1143)
		(layer "In6.Cu")
		(net "P5E_CPU1_P2_RX_DP<15>")
	)
	(segment
		(start 166.088314 -385.548632)
		(end 166.176452 -385.460494)
		(width 0.14224)
		(layer "In6.Cu")
		(net "P5E_CPU1_P2_RX_DP<15>")
	)
	(segment
		(start 127.40005 -285.750254)
		(end 127.397764 -285.748984)
		(width 0.1143)
		(layer "In6.Cu")
		(net "P5E_CPU1_P2_RX_DP<15>")
	)
	(segment
		(start 165.539928 -363.05363)
		(end 156.204158 -353.71786)
		(width 0.14224)
		(layer "In6.Cu")
		(net "P5E_CPU1_P2_RX_DP<15>")
	)
	(segment
		(start 127.391414 -285.745174)
		(end 127.388366 -285.74365)
		(width 0.1143)
		(layer "In6.Cu")
		(net "P5E_CPU1_P2_RX_DP<15>")
	)
	(segment
		(start 144.48409 -321.62877)
		(end 138.387582 -310.224678)
		(width 0.14224)
		(layer "In6.Cu")
		(net "P5E_CPU1_P2_RX_DP<15>")
	)
	(segment
		(start 126.966726 -289.82162)
		(end 126.89713 -289.78098)
		(width 0.1143)
		(layer "In6.Cu")
		(net "P5E_CPU1_P2_RX_DP<15>")
	)
	(segment
		(start 167.624506 -383.56159)
		(end 168.32199 -382.606042)
		(width 0.14224)
		(layer "In6.Cu")
		(net "P5E_CPU1_P2_RX_DP<15>")
	)
	(segment
		(start 126.489968 -284.147768)
		(end 126.489206 -284.14726)
		(width 0.1143)
		(layer "In6.Cu")
		(net "P5E_CPU1_P2_RX_DP<15>")
	)
	(segment
		(start 126.966726 -293.061644)
		(end 126.89713 -293.021004)
		(width 0.1143)
		(layer "In6.Cu")
		(net "P5E_CPU1_P2_RX_DP<15>")
	)
	(segment
		(start 126.89713 -294.031416)
		(end 126.966726 -293.990776)
		(width 0.1143)
		(layer "In6.Cu")
		(net "P5E_CPU1_P2_RX_DP<15>")
	)
	(segment
		(start 138.387582 -310.224678)
		(end 130.81508 -300.997874)
		(width 0.14224)
		(layer "In6.Cu")
		(net "P5E_CPU1_P2_RX_DP<15>")
	)
	(segment
		(start 126.966726 -294.681656)
		(end 126.89713 -294.641016)
		(width 0.1143)
		(layer "In6.Cu")
		(net "P5E_CPU1_P2_RX_DP<15>")
	)
	(segment
		(start 127.393446 -285.746444)
		(end 127.392684 -285.745936)
		(width 0.1143)
		(layer "In6.Cu")
		(net "P5E_CPU1_P2_RX_DP<15>")
	)
	(segment
		(start 126.89713 -287.551622)
		(end 126.964186 -287.512506)
		(width 0.1143)
		(layer "In6.Cu")
		(net "P5E_CPU1_P2_RX_DP<15>")
	)
	(segment
		(start 126.453138 -284.126178)
		(end 126.450344 -284.124654)
		(width 0.1143)
		(layer "In6.Cu")
		(net "P5E_CPU1_P2_RX_DP<15>")
	)
	(segment
		(start 172.309282 -367.252758)
		(end 171.395898 -366.339374)
		(width 0.14224)
		(layer "In6.Cu")
		(net "P5E_CPU1_P2_RX_DP<15>")
	)
	(segment
		(start 127.68326 -296.22115)
		(end 127.68326 -295.94048)
		(width 0.1143)
		(layer "In6.Cu")
		(net "P5E_CPU1_P2_RX_DP<15>")
	)
	(segment
		(start 165.91407 -385.649216)
		(end 166.088314 -385.548632)
		(width 0.14224)
		(layer "In6.Cu")
		(net "P5E_CPU1_P2_RX_DP<15>")
	)
	(segment
		(start 127.364236 -286.743394)
		(end 127.43688 -286.700976)
		(width 0.1143)
		(layer "In6.Cu")
		(net "P5E_CPU1_P2_RX_DP<15>")
	)
	(segment
		(start 125.876812 -282.996386)
		(end 126.174754 -282.996386)
		(width 0.1143)
		(layer "In6.Cu")
		(net "P5E_CPU1_P2_RX_DP<15>")
	)
	(segment
		(start 165.819074 -386.003292)
		(end 165.91407 -385.649216)
		(width 0.14224)
		(layer "In6.Cu")
		(net "P5E_CPU1_P2_RX_DP<15>")
	)
	(segment
		(start 127.388366 -285.74365)
		(end 127.387604 -285.743142)
		(width 0.1143)
		(layer "In6.Cu")
		(net "P5E_CPU1_P2_RX_DP<15>")
	)
	(segment
		(start 126.462028 -284.131512)
		(end 126.460504 -284.130496)
		(width 0.1143)
		(layer "In6.Cu")
		(net "P5E_CPU1_P2_RX_DP<15>")
	)
	(segment
		(start 127.38481 -285.741618)
		(end 127.384048 -285.74111)
		(width 0.1143)
		(layer "In6.Cu")
		(net "P5E_CPU1_P2_RX_DP<15>")
	)
	(segment
		(start 126.463044 -284.13202)
		(end 126.462028 -284.131512)
		(width 0.1143)
		(layer "In6.Cu")
		(net "P5E_CPU1_P2_RX_DP<15>")
	)
	(segment
		(start 147.07235 -334.333342)
		(end 145.394426 -325.08698)
		(width 0.14224)
		(layer "In6.Cu")
		(net "P5E_CPU1_P2_RX_DP<15>")
	)
	(segment
		(start 126.464568 -284.133036)
		(end 126.463044 -284.13202)
		(width 0.1143)
		(layer "In6.Cu")
		(net "P5E_CPU1_P2_RX_DP<15>")
	)
	(segment
		(start 127.36703 -295.451276)
		(end 127.366014 -295.450514)
		(width 0.1143)
		(layer "In6.Cu")
		(net "P5E_CPU1_P2_RX_DP<15>")
	)
	(segment
		(start 127.43688 -295.491916)
		(end 127.36703 -295.451276)
		(width 0.1143)
		(layer "In6.Cu")
		(net "P5E_CPU1_P2_RX_DP<15>")
	)
	(segment
		(start 127.43688 -285.771844)
		(end 127.404114 -285.75254)
		(width 0.1143)
		(layer "In6.Cu")
		(net "P5E_CPU1_P2_RX_DP<15>")
	)
	(segment
		(start 126.966726 -291.441632)
		(end 126.89713 -291.400992)
		(width 0.1143)
		(layer "In6.Cu")
		(net "P5E_CPU1_P2_RX_DP<15>")
	)
	(segment
		(start 126.450344 -284.124654)
		(end 126.42596 -284.110684)
		(width 0.1143)
		(layer "In6.Cu")
		(net "P5E_CPU1_P2_RX_DP<15>")
	)
	(segment
		(start 166.176452 -385.460494)
		(end 166.176452 -384.9878)
		(width 0.14224)
		(layer "In6.Cu")
		(net "P5E_CPU1_P2_RX_DP<15>")
	)
	(segment
		(start 126.89713 -290.791392)
		(end 126.966726 -290.750752)
		(width 0.1143)
		(layer "In6.Cu")
		(net "P5E_CPU1_P2_RX_DP<15>")
	)
	(segment
		(start 127.384048 -285.74111)
		(end 127.366014 -285.730696)
		(width 0.1143)
		(layer "In6.Cu")
		(net "P5E_CPU1_P2_RX_DP<15>")
	)
	(segment
		(start 127.404114 -285.75254)
		(end 127.40005 -285.750254)
		(width 0.1143)
		(layer "In6.Cu")
		(net "P5E_CPU1_P2_RX_DP<15>")
	)
	(segment
		(start 166.176452 -384.9878)
		(end 166.786814 -384.334512)
		(width 0.14224)
		(layer "In6.Cu")
		(net "P5E_CPU1_P2_RX_DP<15>")
	)
	(segment
		(start 172.69714 -370.173504)
		(end 172.413422 -367.470944)
		(width 0.14224)
		(layer "In6.Cu")
		(net "P5E_CPU1_P2_RX_DP<15>")
	)
	(segment
		(start 127.72898 -296.26687)
		(end 127.68326 -296.22115)
		(width 0.1143)
		(layer "In6.Cu")
		(net "P5E_CPU1_P2_RX_DP<15>")
	)
	(segment
		(start 127.72898 -296.380408)
		(end 127.72898 -296.295318)
		(width 0.14224)
		(layer "In6.Cu")
		(net "P5E_CPU1_P2_RX_DP<15>")
	)
	(segment
		(start 145.394426 -325.08698)
		(end 144.48409 -321.62877)
		(width 0.14224)
		(layer "In6.Cu")
		(net "P5E_CPU1_P2_RX_DP<15>")
	)
	(segment
		(start 127.72898 -296.295318)
		(end 127.72898 -296.26687)
		(width 0.1143)
		(layer "In6.Cu")
		(net "P5E_CPU1_P2_RX_DP<15>")
	)
	(segment
		(start 126.489206 -284.14726)
		(end 126.464568 -284.133036)
		(width 0.1143)
		(layer "In6.Cu")
		(net "P5E_CPU1_P2_RX_DP<15>")
	)
	(arc
		(start 172.413422 -367.470944)
		(mid 172.380128 -367.352883)
		(end 172.309282 -367.252758)
		(width 0.14224)
		(layer "In6.Cu")
		(net "P5E_CPU1_P2_RX_DP<15>")
	)
	(arc
		(start 126.89713 -289.78098)
		(mid 126.740153 -289.47618)
		(end 126.89713 -289.17138)
		(width 0.1143)
		(layer "In6.Cu")
		(net "P5E_CPU1_P2_RX_DP<15>")
	)
	(arc
		(start 156.160216 -353.671886)
		(mid 156.138997 -353.648242)
		(end 156.118306 -353.624134)
		(width 0.14224)
		(layer "In6.Cu")
		(net "P5E_CPU1_P2_RX_DP<15>")
	)
	(arc
		(start 156.204158 -353.71786)
		(mid 156.181933 -353.695116)
		(end 156.160216 -353.671886)
		(width 0.14224)
		(layer "In6.Cu")
		(net "P5E_CPU1_P2_RX_DP<15>")
	)
	(arc
		(start 126.89713 -294.641016)
		(mid 126.740153 -294.336216)
		(end 126.89713 -294.031416)
		(width 0.1143)
		(layer "In6.Cu")
		(net "P5E_CPU1_P2_RX_DP<15>")
	)
	(arc
		(start 126.895098 -288.159952)
		(mid 126.781169 -288.026805)
		(end 126.740158 -287.856422)
		(width 0.1143)
		(layer "In6.Cu")
		(net "P5E_CPU1_P2_RX_DP<15>")
	)
	(arc
		(start 171.395898 -366.339374)
		(mid 171.193989 -366.164987)
		(end 170.96867 -366.022128)
		(width 0.14224)
		(layer "In6.Cu")
		(net "P5E_CPU1_P2_RX_DP<15>")
	)
	(arc
		(start 127.68326 -295.94048)
		(mid 127.617692 -295.684527)
		(end 127.43688 -295.491916)
		(width 0.1143)
		(layer "In6.Cu")
		(net "P5E_CPU1_P2_RX_DP<15>")
	)
	(arc
		(start 126.269242 -283.79674)
		(mid 126.267729 -283.783007)
		(end 126.26594 -283.769308)
		(width 0.1143)
		(layer "In6.Cu")
		(net "P5E_CPU1_P2_RX_DP<15>")
	)
	(arc
		(start 126.89713 -291.400992)
		(mid 126.740153 -291.096192)
		(end 126.89713 -290.791392)
		(width 0.1143)
		(layer "In6.Cu")
		(net "P5E_CPU1_P2_RX_DP<15>")
	)
	(arc
		(start 127.366014 -295.450514)
		(mid 127.251338 -295.31718)
		(end 127.210058 -295.146222)
		(width 0.1143)
		(layer "In6.Cu")
		(net "P5E_CPU1_P2_RX_DP<15>")
	)
	(arc
		(start 126.966726 -292.370764)
		(mid 127.210053 -291.906198)
		(end 126.966726 -291.441632)
		(width 0.1143)
		(layer "In6.Cu")
		(net "P5E_CPU1_P2_RX_DP<15>")
	)
	(arc
		(start 125.95606 -283.300678)
		(mid 125.858925 -283.197809)
		(end 125.806962 -283.066236)
		(width 0.1143)
		(layer "In6.Cu")
		(net "P5E_CPU1_P2_RX_DP<15>")
	)
	(arc
		(start 127.210058 -287.046162)
		(mid 127.25082 -286.876278)
		(end 127.364236 -286.743394)
		(width 0.1143)
		(layer "In6.Cu")
		(net "P5E_CPU1_P2_RX_DP<15>")
	)
	(arc
		(start 126.740158 -287.856422)
		(mid 126.781707 -287.685)
		(end 126.89713 -287.551622)
		(width 0.1143)
		(layer "In6.Cu")
		(net "P5E_CPU1_P2_RX_DP<15>")
	)
	(arc
		(start 126.270004 -283.812996)
		(mid 126.269794 -283.80486)
		(end 126.269242 -283.79674)
		(width 0.1143)
		(layer "In6.Cu")
		(net "P5E_CPU1_P2_RX_DP<15>")
	)
	(arc
		(start 126.740158 -284.616398)
		(mid 126.675643 -284.354179)
		(end 126.496826 -284.151832)
		(width 0.1143)
		(layer "In6.Cu")
		(net "P5E_CPU1_P2_RX_DP<15>")
	)
	(arc
		(start 172.143674 -372.187978)
		(mid 172.181731 -372.125088)
		(end 172.207936 -372.056406)
		(width 0.14224)
		(layer "In6.Cu")
		(net "P5E_CPU1_P2_RX_DP<15>")
	)
	(arc
		(start 127.43688 -286.700976)
		(mid 127.680207 -286.23641)
		(end 127.43688 -285.771844)
		(width 0.1143)
		(layer "In6.Cu")
		(net "P5E_CPU1_P2_RX_DP<15>")
	)
	(arc
		(start 167.569134 -383.62255)
		(mid 167.598354 -383.593463)
		(end 167.624506 -383.56159)
		(width 0.14224)
		(layer "In6.Cu")
		(net "P5E_CPU1_P2_RX_DP<15>")
	)
	(arc
		(start 126.89713 -293.021004)
		(mid 126.740153 -292.716204)
		(end 126.89713 -292.411404)
		(width 0.1143)
		(layer "In6.Cu")
		(net "P5E_CPU1_P2_RX_DP<15>")
	)
	(arc
		(start 126.966726 -293.990776)
		(mid 127.210053 -293.52621)
		(end 126.966726 -293.061644)
		(width 0.1143)
		(layer "In6.Cu")
		(net "P5E_CPU1_P2_RX_DP<15>")
	)
	(arc
		(start 127.366014 -285.730696)
		(mid 127.251338 -285.597362)
		(end 127.210058 -285.426404)
		(width 0.1143)
		(layer "In6.Cu")
		(net "P5E_CPU1_P2_RX_DP<15>")
	)
	(arc
		(start 126.964186 -287.512506)
		(mid 127.144838 -287.309761)
		(end 127.210058 -287.046162)
		(width 0.1143)
		(layer "In6.Cu")
		(net "P5E_CPU1_P2_RX_DP<15>")
	)
	(arc
		(start 168.32199 -382.606042)
		(mid 168.405914 -382.457736)
		(end 168.453562 -382.29413)
		(width 0.14224)
		(layer "In6.Cu")
		(net "P5E_CPU1_P2_RX_DP<15>")
	)
	(arc
		(start 126.42596 -284.110684)
		(mid 126.312802 -283.980282)
		(end 126.270004 -283.812996)
		(width 0.1143)
		(layer "In6.Cu")
		(net "P5E_CPU1_P2_RX_DP<15>")
	)
	(arc
		(start 127.210058 -285.426404)
		(mid 127.145543 -285.164185)
		(end 126.966726 -284.961838)
		(width 0.1143)
		(layer "In6.Cu")
		(net "P5E_CPU1_P2_RX_DP<15>")
	)
	(arc
		(start 126.26594 -283.769308)
		(mid 126.18503 -283.532147)
		(end 126.024132 -283.340048)
		(width 0.1143)
		(layer "In6.Cu")
		(net "P5E_CPU1_P2_RX_DP<15>")
	)
	(arc
		(start 172.676312 -370.392452)
		(mid 172.696574 -370.283915)
		(end 172.69714 -370.173504)
		(width 0.14224)
		(layer "In6.Cu")
		(net "P5E_CPU1_P2_RX_DP<15>")
	)
	(arc
		(start 165.858952 -363.290104)
		(mid 165.690681 -363.183682)
		(end 165.539928 -363.05363)
		(width 0.14224)
		(layer "In6.Cu")
		(net "P5E_CPU1_P2_RX_DP<15>")
	)
	(arc
		(start 127.210058 -295.146222)
		(mid 127.145543 -294.884003)
		(end 126.966726 -294.681656)
		(width 0.1143)
		(layer "In6.Cu")
		(net "P5E_CPU1_P2_RX_DP<15>")
	)
	(arc
		(start 156.118306 -353.624134)
		(mid 150.339377 -344.567689)
		(end 147.07235 -334.333342)
		(width 0.14224)
		(layer "In6.Cu")
		(net "P5E_CPU1_P2_RX_DP<15>")
	)
	(arc
		(start 126.89713 -284.921198)
		(mid 126.781703 -284.787822)
		(end 126.740158 -284.616398)
		(width 0.1143)
		(layer "In6.Cu")
		(net "P5E_CPU1_P2_RX_DP<15>")
	)
	(arc
		(start 169.541444 -375.865898)
		(mid 169.592594 -375.690593)
		(end 169.682922 -375.531888)
		(width 0.14224)
		(layer "In6.Cu")
		(net "P5E_CPU1_P2_RX_DP<15>")
	)
	(arc
		(start 126.966726 -289.13074)
		(mid 127.210053 -288.666174)
		(end 126.966726 -288.201608)
		(width 0.1143)
		(layer "In6.Cu")
		(net "P5E_CPU1_P2_RX_DP<15>")
	)
	(arc
		(start 126.966726 -290.750752)
		(mid 127.210053 -290.286186)
		(end 126.966726 -289.82162)
		(width 0.1143)
		(layer "In6.Cu")
		(net "P5E_CPU1_P2_RX_DP<15>")
	)
	(segment
		(start 125.707902 -284.35046)
		(end 126.174754 -284.616398)
		(width 0.12954)
		(layer "F.Cu")
		(net "P5E_CPU1_P2_RX_DP<14>")
	)
	(segment
		(start 164.098224 -386.003292)
		(end 164.618924 -386.003292)
		(width 0.127)
		(layer "F.Cu")
		(net "P5E_CPU1_P2_RX_DP<14>")
	)
	(segment
		(start 125.987048 -293.038276)
		(end 125.986032 -293.037768)
		(width 0.1143)
		(layer "In6.Cu")
		(net "P5E_CPU1_P2_RX_DP<14>")
	)
	(segment
		(start 126.458726 -285.749492)
		(end 126.45771 -285.748984)
		(width 0.1143)
		(layer "In6.Cu")
		(net "P5E_CPU1_P2_RX_DP<14>")
	)
	(segment
		(start 127.017018 -297.066462)
		(end 126.876556 -296.72788)
		(width 0.14224)
		(layer "In6.Cu")
		(net "P5E_CPU1_P2_RX_DP<14>")
	)
	(segment
		(start 126.496826 -295.491662)
		(end 126.45771 -295.468802)
		(width 0.1143)
		(layer "In6.Cu")
		(net "P5E_CPU1_P2_RX_DP<14>")
	)
	(segment
		(start 164.968174 -384.048)
		(end 164.968174 -382.2827)
		(width 0.14224)
		(layer "In6.Cu")
		(net "P5E_CPU1_P2_RX_DP<14>")
	)
	(segment
		(start 126.830328 -296.424096)
		(end 126.740158 -296.206164)
		(width 0.1143)
		(layer "In6.Cu")
		(net "P5E_CPU1_P2_RX_DP<14>")
	)
	(segment
		(start 125.806962 -284.686248)
		(end 125.876812 -284.616398)
		(width 0.1143)
		(layer "In6.Cu")
		(net "P5E_CPU1_P2_RX_DP<14>")
	)
	(segment
		(start 125.95606 -294.031924)
		(end 125.98146 -294.017192)
		(width 0.1143)
		(layer "In6.Cu")
		(net "P5E_CPU1_P2_RX_DP<14>")
	)
	(segment
		(start 125.986032 -294.014652)
		(end 125.987048 -294.014144)
		(width 0.1143)
		(layer "In6.Cu")
		(net "P5E_CPU1_P2_RX_DP<14>")
	)
	(segment
		(start 126.876048 -296.55643)
		(end 126.876048 -296.52849)
		(width 0.1143)
		(layer "In6.Cu")
		(net "P5E_CPU1_P2_RX_DP<14>")
	)
	(segment
		(start 164.976302 -385.046982)
		(end 164.660326 -384.731006)
		(width 0.14224)
		(layer "In6.Cu")
		(net "P5E_CPU1_P2_RX_DP<14>")
	)
	(segment
		(start 126.424182 -286.743394)
		(end 126.496826 -286.700976)
		(width 0.1143)
		(layer "In6.Cu")
		(net "P5E_CPU1_P2_RX_DP<14>")
	)
	(segment
		(start 126.740158 -296.206164)
		(end 126.740158 -295.956228)
		(width 0.1143)
		(layer "In6.Cu")
		(net "P5E_CPU1_P2_RX_DP<14>")
	)
	(segment
		(start 171.409106 -371.405404)
		(end 171.64939 -370.48948)
		(width 0.14224)
		(layer "In6.Cu")
		(net "P5E_CPU1_P2_RX_DP<14>")
	)
	(segment
		(start 168.547034 -365.89589)
		(end 168.54678 -365.895636)
		(width 0.14224)
		(layer "In6.Cu")
		(net "P5E_CPU1_P2_RX_DP<14>")
	)
	(segment
		(start 137.595356 -310.82107)
		(end 137.2743 -310.340502)
		(width 0.14224)
		(layer "In6.Cu")
		(net "P5E_CPU1_P2_RX_DP<14>")
	)
	(segment
		(start 165.042342 -381.99187)
		(end 168.82237 -375.06021)
		(width 0.14224)
		(layer "In6.Cu")
		(net "P5E_CPU1_P2_RX_DP<14>")
	)
	(segment
		(start 126.830328 -296.48277)
		(end 126.830328 -296.424096)
		(width 0.1143)
		(layer "In6.Cu")
		(net "P5E_CPU1_P2_RX_DP<14>")
	)
	(segment
		(start 164.618924 -386.003292)
		(end 164.71392 -385.649216)
		(width 0.14224)
		(layer "In6.Cu")
		(net "P5E_CPU1_P2_RX_DP<14>")
	)
	(segment
		(start 125.98781 -294.013636)
		(end 125.988318 -294.013636)
		(width 0.1143)
		(layer "In6.Cu")
		(net "P5E_CPU1_P2_RX_DP<14>")
	)
	(segment
		(start 146.304 -335.456784)
		(end 143.66113 -322.170044)
		(width 0.14224)
		(layer "In6.Cu")
		(net "P5E_CPU1_P2_RX_DP<14>")
	)
	(segment
		(start 125.987048 -294.014144)
		(end 125.98781 -294.013636)
		(width 0.1143)
		(layer "In6.Cu")
		(net "P5E_CPU1_P2_RX_DP<14>")
	)
	(segment
		(start 125.991366 -294.660828)
		(end 125.95606 -294.640508)
		(width 0.1143)
		(layer "In6.Cu")
		(net "P5E_CPU1_P2_RX_DP<14>")
	)
	(segment
		(start 125.988318 -289.79876)
		(end 125.98781 -289.79876)
		(width 0.1143)
		(layer "In6.Cu")
		(net "P5E_CPU1_P2_RX_DP<14>")
	)
	(segment
		(start 163.95065 -362.980986)
		(end 157.318456 -356.348792)
		(width 0.14224)
		(layer "In6.Cu")
		(net "P5E_CPU1_P2_RX_DP<14>")
	)
	(segment
		(start 171.237402 -371.771418)
		(end 171.409106 -371.405404)
		(width 0.14224)
		(layer "In6.Cu")
		(net "P5E_CPU1_P2_RX_DP<14>")
	)
	(segment
		(start 125.98527 -293.03726)
		(end 125.984254 -293.036752)
		(width 0.1143)
		(layer "In6.Cu")
		(net "P5E_CPU1_P2_RX_DP<14>")
	)
	(segment
		(start 168.54678 -365.895636)
		(end 164.81552 -363.774228)
		(width 0.14224)
		(layer "In6.Cu")
		(net "P5E_CPU1_P2_RX_DP<14>")
	)
	(segment
		(start 169.613834 -374.046496)
		(end 171.237402 -371.771418)
		(width 0.14224)
		(layer "In6.Cu")
		(net "P5E_CPU1_P2_RX_DP<14>")
	)
	(segment
		(start 125.955806 -290.792154)
		(end 125.971046 -290.783264)
		(width 0.1143)
		(layer "In6.Cu")
		(net "P5E_CPU1_P2_RX_DP<14>")
	)
	(segment
		(start 126.024132 -288.19983)
		(end 126.021338 -288.198306)
		(width 0.1143)
		(layer "In6.Cu")
		(net "P5E_CPU1_P2_RX_DP<14>")
	)
	(segment
		(start 125.987556 -289.155886)
		(end 125.988572 -289.155378)
		(width 0.1143)
		(layer "In6.Cu")
		(net "P5E_CPU1_P2_RX_DP<14>")
	)
	(segment
		(start 126.5047 -295.497504)
		(end 126.496826 -295.491662)
		(width 0.1143)
		(layer "In6.Cu")
		(net "P5E_CPU1_P2_RX_DP<14>")
	)
	(segment
		(start 126.45771 -285.748984)
		(end 126.456948 -285.748476)
		(width 0.1143)
		(layer "In6.Cu")
		(net "P5E_CPU1_P2_RX_DP<14>")
	)
	(segment
		(start 125.98527 -294.01516)
		(end 125.986032 -294.014652)
		(width 0.1143)
		(layer "In6.Cu")
		(net "P5E_CPU1_P2_RX_DP<14>")
	)
	(segment
		(start 171.661836 -370.358162)
		(end 171.498768 -367.952782)
		(width 0.14224)
		(layer "In6.Cu")
		(net "P5E_CPU1_P2_RX_DP<14>")
	)
	(segment
		(start 126.45771 -295.468802)
		(end 126.457202 -295.468548)
		(width 0.1143)
		(layer "In6.Cu")
		(net "P5E_CPU1_P2_RX_DP<14>")
	)
	(segment
		(start 125.987048 -290.77412)
		(end 125.98781 -290.773612)
		(width 0.1143)
		(layer "In6.Cu")
		(net "P5E_CPU1_P2_RX_DP<14>")
	)
	(segment
		(start 125.987048 -289.798252)
		(end 125.95606 -289.780472)
		(width 0.1143)
		(layer "In6.Cu")
		(net "P5E_CPU1_P2_RX_DP<14>")
	)
	(segment
		(start 125.95606 -287.55213)
		(end 126.022354 -287.513522)
		(width 0.1143)
		(layer "In6.Cu")
		(net "P5E_CPU1_P2_RX_DP<14>")
	)
	(segment
		(start 125.984254 -294.015668)
		(end 125.98527 -294.01516)
		(width 0.1143)
		(layer "In6.Cu")
		(net "P5E_CPU1_P2_RX_DP<14>")
	)
	(segment
		(start 164.663374 -384.3528)
		(end 164.968174 -384.048)
		(width 0.14224)
		(layer "In6.Cu")
		(net "P5E_CPU1_P2_RX_DP<14>")
	)
	(segment
		(start 125.983492 -294.016176)
		(end 125.984254 -294.015668)
		(width 0.1143)
		(layer "In6.Cu")
		(net "P5E_CPU1_P2_RX_DP<14>")
	)
	(segment
		(start 126.021338 -288.198306)
		(end 125.954282 -288.15919)
		(width 0.1143)
		(layer "In6.Cu")
		(net "P5E_CPU1_P2_RX_DP<14>")
	)
	(segment
		(start 126.876556 -296.72788)
		(end 126.876556 -296.556938)
		(width 0.14224)
		(layer "In6.Cu")
		(net "P5E_CPU1_P2_RX_DP<14>")
	)
	(segment
		(start 125.98781 -289.79876)
		(end 125.987048 -289.798252)
		(width 0.1143)
		(layer "In6.Cu")
		(net "P5E_CPU1_P2_RX_DP<14>")
	)
	(segment
		(start 137.2743 -310.340502)
		(end 129.8067 -301.241206)
		(width 0.14224)
		(layer "In6.Cu")
		(net "P5E_CPU1_P2_RX_DP<14>")
	)
	(segment
		(start 126.496826 -285.771844)
		(end 126.46025 -285.750508)
		(width 0.1143)
		(layer "In6.Cu")
		(net "P5E_CPU1_P2_RX_DP<14>")
	)
	(segment
		(start 164.660326 -384.731006)
		(end 164.663374 -384.3528)
		(width 0.14224)
		(layer "In6.Cu")
		(net "P5E_CPU1_P2_RX_DP<14>")
	)
	(segment
		(start 171.379642 -367.691162)
		(end 170.990768 -367.302542)
		(width 0.14224)
		(layer "In6.Cu")
		(net "P5E_CPU1_P2_RX_DP<14>")
	)
	(segment
		(start 125.98146 -294.017192)
		(end 125.983492 -294.016176)
		(width 0.1143)
		(layer "In6.Cu")
		(net "P5E_CPU1_P2_RX_DP<14>")
	)
	(segment
		(start 164.71392 -385.649216)
		(end 164.888164 -385.548632)
		(width 0.14224)
		(layer "In6.Cu")
		(net "P5E_CPU1_P2_RX_DP<14>")
	)
	(segment
		(start 126.456948 -285.748476)
		(end 126.42596 -285.730696)
		(width 0.1143)
		(layer "In6.Cu")
		(net "P5E_CPU1_P2_RX_DP<14>")
	)
	(segment
		(start 126.46025 -285.750508)
		(end 126.458726 -285.749492)
		(width 0.1143)
		(layer "In6.Cu")
		(net "P5E_CPU1_P2_RX_DP<14>")
	)
	(segment
		(start 170.903646 -367.23574)
		(end 168.547034 -365.89589)
		(width 0.14224)
		(layer "In6.Cu")
		(net "P5E_CPU1_P2_RX_DP<14>")
	)
	(segment
		(start 125.876812 -284.616398)
		(end 126.174754 -284.616398)
		(width 0.1143)
		(layer "In6.Cu")
		(net "P5E_CPU1_P2_RX_DP<14>")
	)
	(segment
		(start 125.98781 -293.038784)
		(end 125.987048 -293.038276)
		(width 0.1143)
		(layer "In6.Cu")
		(net "P5E_CPU1_P2_RX_DP<14>")
	)
	(segment
		(start 125.98781 -290.773612)
		(end 125.988318 -290.773612)
		(width 0.1143)
		(layer "In6.Cu")
		(net "P5E_CPU1_P2_RX_DP<14>")
	)
	(segment
		(start 126.876048 -296.52849)
		(end 126.830328 -296.48277)
		(width 0.1143)
		(layer "In6.Cu")
		(net "P5E_CPU1_P2_RX_DP<14>")
	)
	(segment
		(start 126.024132 -284.96006)
		(end 125.95606 -284.92069)
		(width 0.1143)
		(layer "In6.Cu")
		(net "P5E_CPU1_P2_RX_DP<14>")
	)
	(segment
		(start 125.988318 -293.038784)
		(end 125.98781 -293.038784)
		(width 0.1143)
		(layer "In6.Cu")
		(net "P5E_CPU1_P2_RX_DP<14>")
	)
	(segment
		(start 164.976302 -385.460494)
		(end 164.976302 -385.046982)
		(width 0.14224)
		(layer "In6.Cu")
		(net "P5E_CPU1_P2_RX_DP<14>")
	)
	(segment
		(start 164.888164 -385.548632)
		(end 164.976302 -385.460494)
		(width 0.14224)
		(layer "In6.Cu")
		(net "P5E_CPU1_P2_RX_DP<14>")
	)
	(segment
		(start 125.971046 -290.783264)
		(end 125.987048 -290.77412)
		(width 0.1143)
		(layer "In6.Cu")
		(net "P5E_CPU1_P2_RX_DP<14>")
	)
	(segment
		(start 168.82237 -375.06021)
		(end 169.613834 -374.046496)
		(width 0.14224)
		(layer "In6.Cu")
		(net "P5E_CPU1_P2_RX_DP<14>")
	)
	(segment
		(start 126.876556 -296.556938)
		(end 126.876048 -296.55643)
		(width 0.1143)
		(layer "In6.Cu")
		(net "P5E_CPU1_P2_RX_DP<14>")
	)
	(segment
		(start 125.986032 -293.037768)
		(end 125.98527 -293.03726)
		(width 0.1143)
		(layer "In6.Cu")
		(net "P5E_CPU1_P2_RX_DP<14>")
	)
	(segment
		(start 125.984254 -293.036752)
		(end 125.95606 -293.020496)
		(width 0.1143)
		(layer "In6.Cu")
		(net "P5E_CPU1_P2_RX_DP<14>")
	)
	(segment
		(start 143.66113 -322.170044)
		(end 137.595356 -310.82107)
		(width 0.14224)
		(layer "In6.Cu")
		(net "P5E_CPU1_P2_RX_DP<14>")
	)
	(segment
		(start 125.99035 -291.42563)
		(end 125.985778 -291.422836)
		(width 0.1143)
		(layer "In6.Cu")
		(net "P5E_CPU1_P2_RX_DP<14>")
	)
	(segment
		(start 129.8067 -301.241206)
		(end 127.017018 -297.066462)
		(width 0.14224)
		(layer "In6.Cu")
		(net "P5E_CPU1_P2_RX_DP<14>")
	)
	(segment
		(start 125.95606 -292.411912)
		(end 126.026164 -292.371272)
		(width 0.1143)
		(layer "In6.Cu")
		(net "P5E_CPU1_P2_RX_DP<14>")
	)
	(arc
		(start 126.496826 -286.700976)
		(mid 126.740153 -286.23641)
		(end 126.496826 -285.771844)
		(width 0.1143)
		(layer "In6.Cu")
		(net "P5E_CPU1_P2_RX_DP<14>")
	)
	(arc
		(start 125.800104 -287.856422)
		(mid 125.841359 -287.685451)
		(end 125.95606 -287.55213)
		(width 0.1143)
		(layer "In6.Cu")
		(net "P5E_CPU1_P2_RX_DP<14>")
	)
	(arc
		(start 125.954282 -288.15919)
		(mid 125.840875 -288.026301)
		(end 125.800104 -287.856422)
		(width 0.1143)
		(layer "In6.Cu")
		(net "P5E_CPU1_P2_RX_DP<14>")
	)
	(arc
		(start 164.795708 -363.760258)
		(mid 164.365287 -363.37918)
		(end 163.95065 -362.980986)
		(width 0.14224)
		(layer "In6.Cu")
		(net "P5E_CPU1_P2_RX_DP<14>")
	)
	(arc
		(start 125.988318 -294.013636)
		(mid 126.268965 -293.52621)
		(end 125.988318 -293.038784)
		(width 0.1143)
		(layer "In6.Cu")
		(net "P5E_CPU1_P2_RX_DP<14>")
	)
	(arc
		(start 125.988572 -289.155378)
		(mid 126.269641 -288.687427)
		(end 126.024132 -288.19983)
		(width 0.1143)
		(layer "In6.Cu")
		(net "P5E_CPU1_P2_RX_DP<14>")
	)
	(arc
		(start 126.266448 -287.081468)
		(mid 126.268803 -287.059162)
		(end 126.270004 -287.036764)
		(width 0.1143)
		(layer "In6.Cu")
		(net "P5E_CPU1_P2_RX_DP<14>")
	)
	(arc
		(start 155.157932 -353.98329)
		(mid 149.56955 -345.275087)
		(end 146.304 -335.456784)
		(width 0.14224)
		(layer "In6.Cu")
		(net "P5E_CPU1_P2_RX_DP<14>")
	)
	(arc
		(start 164.968174 -382.2827)
		(mid 164.987007 -382.132631)
		(end 165.042342 -381.99187)
		(width 0.14224)
		(layer "In6.Cu")
		(net "P5E_CPU1_P2_RX_DP<14>")
	)
	(arc
		(start 125.95606 -284.92069)
		(mid 125.858925 -284.817821)
		(end 125.806962 -284.686248)
		(width 0.1143)
		(layer "In6.Cu")
		(net "P5E_CPU1_P2_RX_DP<14>")
	)
	(arc
		(start 164.81552 -363.774228)
		(mid 164.805281 -363.767716)
		(end 164.795708 -363.760258)
		(width 0.14224)
		(layer "In6.Cu")
		(net "P5E_CPU1_P2_RX_DP<14>")
	)
	(arc
		(start 171.64939 -370.48948)
		(mid 171.660942 -370.424327)
		(end 171.661836 -370.358162)
		(width 0.14224)
		(layer "In6.Cu")
		(net "P5E_CPU1_P2_RX_DP<14>")
	)
	(arc
		(start 171.498768 -367.952782)
		(mid 171.462953 -367.811152)
		(end 171.379642 -367.691162)
		(width 0.14224)
		(layer "In6.Cu")
		(net "P5E_CPU1_P2_RX_DP<14>")
	)
	(arc
		(start 126.26975 -285.44139)
		(mid 126.268578 -285.415935)
		(end 126.26594 -285.39059)
		(width 0.1143)
		(layer "In6.Cu")
		(net "P5E_CPU1_P2_RX_DP<14>")
	)
	(arc
		(start 125.95606 -294.640508)
		(mid 125.800132 -294.336216)
		(end 125.95606 -294.031924)
		(width 0.1143)
		(layer "In6.Cu")
		(net "P5E_CPU1_P2_RX_DP<14>")
	)
	(arc
		(start 126.457202 -295.468548)
		(mid 126.321121 -295.3327)
		(end 126.271274 -295.146984)
		(width 0.1143)
		(layer "In6.Cu")
		(net "P5E_CPU1_P2_RX_DP<14>")
	)
	(arc
		(start 125.95606 -293.020496)
		(mid 125.800132 -292.716204)
		(end 125.95606 -292.411912)
		(width 0.1143)
		(layer "In6.Cu")
		(net "P5E_CPU1_P2_RX_DP<14>")
	)
	(arc
		(start 126.270004 -287.036764)
		(mid 126.312819 -286.87205)
		(end 126.424182 -286.743394)
		(width 0.1143)
		(layer "In6.Cu")
		(net "P5E_CPU1_P2_RX_DP<14>")
	)
	(arc
		(start 126.26594 -285.39059)
		(mid 126.185272 -285.152718)
		(end 126.024132 -284.96006)
		(width 0.1143)
		(layer "In6.Cu")
		(net "P5E_CPU1_P2_RX_DP<14>")
	)
	(arc
		(start 157.318456 -356.348792)
		(mid 156.211425 -355.190491)
		(end 155.157932 -353.98329)
		(width 0.14224)
		(layer "In6.Cu")
		(net "P5E_CPU1_P2_RX_DP<14>")
	)
	(arc
		(start 125.988318 -290.773612)
		(mid 126.268965 -290.286186)
		(end 125.988318 -289.79876)
		(width 0.1143)
		(layer "In6.Cu")
		(net "P5E_CPU1_P2_RX_DP<14>")
	)
	(arc
		(start 126.42596 -285.730696)
		(mid 126.314518 -285.604054)
		(end 126.26975 -285.44139)
		(width 0.1143)
		(layer "In6.Cu")
		(net "P5E_CPU1_P2_RX_DP<14>")
	)
	(arc
		(start 125.95606 -289.780472)
		(mid 125.801724 -289.459662)
		(end 125.987556 -289.155886)
		(width 0.1143)
		(layer "In6.Cu")
		(net "P5E_CPU1_P2_RX_DP<14>")
	)
	(arc
		(start 126.022354 -287.513522)
		(mid 126.185144 -287.320514)
		(end 126.266448 -287.081468)
		(width 0.1143)
		(layer "In6.Cu")
		(net "P5E_CPU1_P2_RX_DP<14>")
	)
	(arc
		(start 125.985778 -291.422836)
		(mid 125.799632 -291.115612)
		(end 125.955806 -290.792154)
		(width 0.1143)
		(layer "In6.Cu")
		(net "P5E_CPU1_P2_RX_DP<14>")
	)
	(arc
		(start 126.026164 -292.371272)
		(mid 126.267898 -291.888575)
		(end 125.99035 -291.42563)
		(width 0.1143)
		(layer "In6.Cu")
		(net "P5E_CPU1_P2_RX_DP<14>")
	)
	(arc
		(start 126.271274 -295.146984)
		(mid 126.196294 -294.8665)
		(end 125.991366 -294.660828)
		(width 0.1143)
		(layer "In6.Cu")
		(net "P5E_CPU1_P2_RX_DP<14>")
	)
	(arc
		(start 170.990768 -367.302542)
		(mid 170.949454 -367.26621)
		(end 170.903646 -367.23574)
		(width 0.14224)
		(layer "In6.Cu")
		(net "P5E_CPU1_P2_RX_DP<14>")
	)
	(arc
		(start 126.740158 -295.956228)
		(mid 126.677807 -295.698437)
		(end 126.5047 -295.497504)
		(width 0.1143)
		(layer "In6.Cu")
		(net "P5E_CPU1_P2_RX_DP<14>")
	)
	(segment
		(start 162.898328 -386.003292)
		(end 163.419028 -386.003292)
		(width 0.127)
		(layer "F.Cu")
		(net "P5E_CPU1_P2_RX_DP<13>")
	)
	(segment
		(start 125.707902 -281.110436)
		(end 126.174754 -281.376374)
		(width 0.12954)
		(layer "F.Cu")
		(net "P5E_CPU1_P2_RX_DP<13>")
	)
	(segment
		(start 125.048772 -284.939486)
		(end 125.047756 -284.938978)
		(width 0.1143)
		(layer "In6.Cu")
		(net "P5E_CPU1_P2_RX_DP<13>")
	)
	(segment
		(start 125.846332 -296.486326)
		(end 125.845824 -296.486326)
		(width 0.14224)
		(layer "In6.Cu")
		(net "P5E_CPU1_P2_RX_DP<13>")
	)
	(segment
		(start 125.043438 -294.656256)
		(end 125.041914 -294.655494)
		(width 0.1143)
		(layer "In6.Cu")
		(net "P5E_CPU1_P2_RX_DP<13>")
	)
	(segment
		(start 167.983916 -374.551194)
		(end 169.791126 -371.98935)
		(width 0.14224)
		(layer "In6.Cu")
		(net "P5E_CPU1_P2_RX_DP<13>")
	)
	(segment
		(start 125.016006 -289.171888)
		(end 125.045724 -289.15487)
		(width 0.1143)
		(layer "In6.Cu")
		(net "P5E_CPU1_P2_RX_DP<13>")
	)
	(segment
		(start 125.041152 -283.315156)
		(end 125.039882 -283.314394)
		(width 0.1143)
		(layer "In6.Cu")
		(net "P5E_CPU1_P2_RX_DP<13>")
	)
	(segment
		(start 125.047756 -293.038784)
		(end 125.016006 -293.020496)
		(width 0.1143)
		(layer "In6.Cu")
		(net "P5E_CPU1_P2_RX_DP<13>")
	)
	(segment
		(start 125.047756 -288.178748)
		(end 125.014228 -288.15919)
		(width 0.1143)
		(layer "In6.Cu")
		(net "P5E_CPU1_P2_RX_DP<13>")
	)
	(segment
		(start 125.086872 -294.681656)
		(end 125.050296 -294.66032)
		(width 0.1143)
		(layer "In6.Cu")
		(net "P5E_CPU1_P2_RX_DP<13>")
	)
	(segment
		(start 170.650916 -369.532154)
		(end 170.563032 -368.472212)
		(width 0.14224)
		(layer "In6.Cu")
		(net "P5E_CPU1_P2_RX_DP<13>")
	)
	(segment
		(start 125.050296 -292.3921)
		(end 125.086872 -292.370764)
		(width 0.1143)
		(layer "In6.Cu")
		(net "P5E_CPU1_P2_RX_DP<13>")
	)
	(segment
		(start 125.03785 -284.933136)
		(end 125.036834 -284.932628)
		(width 0.1143)
		(layer "In6.Cu")
		(net "P5E_CPU1_P2_RX_DP<13>")
	)
	(segment
		(start 129.057654 -301.841916)
		(end 129.057654 -301.84217)
		(width 0.14224)
		(layer "In6.Cu")
		(net "P5E_CPU1_P2_RX_DP<13>")
	)
	(segment
		(start 125.045724 -290.774882)
		(end 125.046994 -290.77412)
		(width 0.1143)
		(layer "In6.Cu")
		(net "P5E_CPU1_P2_RX_DP<13>")
	)
	(segment
		(start 125.048772 -282.673298)
		(end 125.050296 -282.672282)
		(width 0.1143)
		(layer "In6.Cu")
		(net "P5E_CPU1_P2_RX_DP<13>")
	)
	(segment
		(start 125.050296 -284.292294)
		(end 125.086872 -284.270958)
		(width 0.1143)
		(layer "In6.Cu")
		(net "P5E_CPU1_P2_RX_DP<13>")
	)
	(segment
		(start 170.42892 -368.202464)
		(end 170.216068 -368.010694)
		(width 0.14224)
		(layer "In6.Cu")
		(net "P5E_CPU1_P2_RX_DP<13>")
	)
	(segment
		(start 125.800104 -296.29862)
		(end 125.800104 -295.956228)
		(width 0.1143)
		(layer "In6.Cu")
		(net "P5E_CPU1_P2_RX_DP<13>")
	)
	(segment
		(start 125.0442 -291.41674)
		(end 125.043438 -291.416232)
		(width 0.1143)
		(layer "In6.Cu")
		(net "P5E_CPU1_P2_RX_DP<13>")
	)
	(segment
		(start 125.048772 -292.393116)
		(end 125.050296 -292.3921)
		(width 0.1143)
		(layer "In6.Cu")
		(net "P5E_CPU1_P2_RX_DP<13>")
	)
	(segment
		(start 125.045724 -282.675076)
		(end 125.046994 -282.674314)
		(width 0.1143)
		(layer "In6.Cu")
		(net "P5E_CPU1_P2_RX_DP<13>")
	)
	(segment
		(start 125.036834 -284.932628)
		(end 125.035564 -284.931866)
		(width 0.1143)
		(layer "In6.Cu")
		(net "P5E_CPU1_P2_RX_DP<13>")
	)
	(segment
		(start 125.016006 -294.031924)
		(end 125.045724 -294.014906)
		(width 0.1143)
		(layer "In6.Cu")
		(net "P5E_CPU1_P2_RX_DP<13>")
	)
	(segment
		(start 125.048772 -290.773104)
		(end 125.050296 -290.772088)
		(width 0.1143)
		(layer "In6.Cu")
		(net "P5E_CPU1_P2_RX_DP<13>")
	)
	(segment
		(start 125.046994 -292.394132)
		(end 125.047756 -292.393624)
		(width 0.1143)
		(layer "In6.Cu")
		(net "P5E_CPU1_P2_RX_DP<13>")
	)
	(segment
		(start 125.050296 -290.772088)
		(end 125.086872 -290.750752)
		(width 0.1143)
		(layer "In6.Cu")
		(net "P5E_CPU1_P2_RX_DP<13>")
	)
	(segment
		(start 125.517656 -281.8638)
		(end 125.556772 -281.84094)
		(width 0.1143)
		(layer "In6.Cu")
		(net "P5E_CPU1_P2_RX_DP<13>")
	)
	(segment
		(start 125.046994 -291.418264)
		(end 125.0442 -291.41674)
		(width 0.1143)
		(layer "In6.Cu")
		(net "P5E_CPU1_P2_RX_DP<13>")
	)
	(segment
		(start 125.517656 -285.748984)
		(end 125.487176 -285.731204)
		(width 0.1143)
		(layer "In6.Cu")
		(net "P5E_CPU1_P2_RX_DP<13>")
	)
	(segment
		(start 163.768278 -384.048)
		(end 163.768278 -382.6256)
		(width 0.14224)
		(layer "In6.Cu")
		(net "P5E_CPU1_P2_RX_DP<13>")
	)
	(segment
		(start 125.046994 -294.014144)
		(end 125.047756 -294.013636)
		(width 0.1143)
		(layer "In6.Cu")
		(net "P5E_CPU1_P2_RX_DP<13>")
	)
	(segment
		(start 125.048772 -294.013128)
		(end 125.050296 -294.012112)
		(width 0.1143)
		(layer "In6.Cu")
		(net "P5E_CPU1_P2_RX_DP<13>")
	)
	(segment
		(start 125.487176 -281.88158)
		(end 125.517656 -281.8638)
		(width 0.1143)
		(layer "In6.Cu")
		(net "P5E_CPU1_P2_RX_DP<13>")
	)
	(segment
		(start 125.047756 -284.293818)
		(end 125.048772 -284.29331)
		(width 0.1143)
		(layer "In6.Cu")
		(net "P5E_CPU1_P2_RX_DP<13>")
	)
	(segment
		(start 125.845824 -296.372788)
		(end 125.845824 -296.34434)
		(width 0.1143)
		(layer "In6.Cu")
		(net "P5E_CPU1_P2_RX_DP<13>")
	)
	(segment
		(start 163.776406 -385.046982)
		(end 163.46043 -384.731006)
		(width 0.14224)
		(layer "In6.Cu")
		(net "P5E_CPU1_P2_RX_DP<13>")
	)
	(segment
		(start 125.045724 -294.014906)
		(end 125.046994 -294.014144)
		(width 0.1143)
		(layer "In6.Cu")
		(net "P5E_CPU1_P2_RX_DP<13>")
	)
	(segment
		(start 125.041152 -291.414962)
		(end 125.039882 -291.4142)
		(width 0.1143)
		(layer "In6.Cu")
		(net "P5E_CPU1_P2_RX_DP<13>")
	)
	(segment
		(start 125.045724 -284.295088)
		(end 125.046994 -284.294326)
		(width 0.1143)
		(layer "In6.Cu")
		(net "P5E_CPU1_P2_RX_DP<13>")
	)
	(segment
		(start 136.637522 -311.078372)
		(end 129.057654 -301.841916)
		(width 0.14224)
		(layer "In6.Cu")
		(net "P5E_CPU1_P2_RX_DP<13>")
	)
	(segment
		(start 125.047756 -289.1536)
		(end 125.048772 -289.153092)
		(width 0.1143)
		(layer "In6.Cu")
		(net "P5E_CPU1_P2_RX_DP<13>")
	)
	(segment
		(start 125.876812 -281.376374)
		(end 126.174754 -281.376374)
		(width 0.1143)
		(layer "In6.Cu")
		(net "P5E_CPU1_P2_RX_DP<13>")
	)
	(segment
		(start 125.043438 -291.416232)
		(end 125.041914 -291.41547)
		(width 0.1143)
		(layer "In6.Cu")
		(net "P5E_CPU1_P2_RX_DP<13>")
	)
	(segment
		(start 125.041914 -283.315664)
		(end 125.041152 -283.315156)
		(width 0.1143)
		(layer "In6.Cu")
		(net "P5E_CPU1_P2_RX_DP<13>")
	)
	(segment
		(start 125.086872 -284.961838)
		(end 125.050296 -284.940502)
		(width 0.1143)
		(layer "In6.Cu")
		(net "P5E_CPU1_P2_RX_DP<13>")
	)
	(segment
		(start 125.047756 -282.673806)
		(end 125.048772 -282.673298)
		(width 0.1143)
		(layer "In6.Cu")
		(net "P5E_CPU1_P2_RX_DP<13>")
	)
	(segment
		(start 125.03785 -294.652954)
		(end 125.036834 -294.652446)
		(width 0.1143)
		(layer "In6.Cu")
		(net "P5E_CPU1_P2_RX_DP<13>")
	)
	(segment
		(start 125.0442 -284.936946)
		(end 125.043438 -284.936438)
		(width 0.1143)
		(layer "In6.Cu")
		(net "P5E_CPU1_P2_RX_DP<13>")
	)
	(segment
		(start 125.048772 -289.799268)
		(end 125.047756 -289.79876)
		(width 0.1143)
		(layer "In6.Cu")
		(net "P5E_CPU1_P2_RX_DP<13>")
	)
	(segment
		(start 125.048772 -289.153092)
		(end 125.050296 -289.152076)
		(width 0.1143)
		(layer "In6.Cu")
		(net "P5E_CPU1_P2_RX_DP<13>")
	)
	(segment
		(start 125.086872 -293.061644)
		(end 125.050296 -293.040308)
		(width 0.1143)
		(layer "In6.Cu")
		(net "P5E_CPU1_P2_RX_DP<13>")
	)
	(segment
		(start 125.045724 -289.15487)
		(end 125.046994 -289.154108)
		(width 0.1143)
		(layer "In6.Cu")
		(net "P5E_CPU1_P2_RX_DP<13>")
	)
	(segment
		(start 125.035564 -284.931866)
		(end 125.016006 -284.92069)
		(width 0.1143)
		(layer "In6.Cu")
		(net "P5E_CPU1_P2_RX_DP<13>")
	)
	(segment
		(start 125.046994 -284.93847)
		(end 125.0442 -284.936946)
		(width 0.1143)
		(layer "In6.Cu")
		(net "P5E_CPU1_P2_RX_DP<13>")
	)
	(segment
		(start 125.050296 -294.012112)
		(end 125.086872 -293.990776)
		(width 0.1143)
		(layer "In6.Cu")
		(net "P5E_CPU1_P2_RX_DP<13>")
	)
	(segment
		(start 125.0442 -283.316934)
		(end 125.043438 -283.316426)
		(width 0.1143)
		(layer "In6.Cu")
		(net "P5E_CPU1_P2_RX_DP<13>")
	)
	(segment
		(start 125.03785 -291.41293)
		(end 125.036834 -291.412422)
		(width 0.1143)
		(layer "In6.Cu")
		(net "P5E_CPU1_P2_RX_DP<13>")
	)
	(segment
		(start 125.047756 -292.393624)
		(end 125.048772 -292.393116)
		(width 0.1143)
		(layer "In6.Cu")
		(net "P5E_CPU1_P2_RX_DP<13>")
	)
	(segment
		(start 125.046994 -283.318458)
		(end 125.0442 -283.316934)
		(width 0.1143)
		(layer "In6.Cu")
		(net "P5E_CPU1_P2_RX_DP<13>")
	)
	(segment
		(start 163.514024 -385.649216)
		(end 163.688268 -385.548632)
		(width 0.14224)
		(layer "In6.Cu")
		(net "P5E_CPU1_P2_RX_DP<13>")
	)
	(segment
		(start 170.650916 -369.532916)
		(end 170.650916 -369.532154)
		(width 0.14224)
		(layer "In6.Cu")
		(net "P5E_CPU1_P2_RX_DP<13>")
	)
	(segment
		(start 125.050296 -291.420296)
		(end 125.048772 -291.41928)
		(width 0.1143)
		(layer "In6.Cu")
		(net "P5E_CPU1_P2_RX_DP<13>")
	)
	(segment
		(start 125.050296 -289.800284)
		(end 125.048772 -289.799268)
		(width 0.1143)
		(layer "In6.Cu")
		(net "P5E_CPU1_P2_RX_DP<13>")
	)
	(segment
		(start 125.036834 -283.312616)
		(end 125.035564 -283.311854)
		(width 0.1143)
		(layer "In6.Cu")
		(net "P5E_CPU1_P2_RX_DP<13>")
	)
	(segment
		(start 126.180088 -297.535854)
		(end 125.846332 -296.730166)
		(width 0.14224)
		(layer "In6.Cu")
		(net "P5E_CPU1_P2_RX_DP<13>")
	)
	(segment
		(start 125.036834 -294.652446)
		(end 125.035564 -294.651684)
		(width 0.1143)
		(layer "In6.Cu")
		(net "P5E_CPU1_P2_RX_DP<13>")
	)
	(segment
		(start 125.016006 -287.55213)
		(end 125.047756 -287.533842)
		(width 0.1143)
		(layer "In6.Cu")
		(net "P5E_CPU1_P2_RX_DP<13>")
	)
	(segment
		(start 125.041152 -284.935168)
		(end 125.039882 -284.934406)
		(width 0.1143)
		(layer "In6.Cu")
		(net "P5E_CPU1_P2_RX_DP<13>")
	)
	(segment
		(start 125.086872 -283.341826)
		(end 125.050296 -283.32049)
		(width 0.1143)
		(layer "In6.Cu")
		(net "P5E_CPU1_P2_RX_DP<13>")
	)
	(segment
		(start 125.517656 -295.468802)
		(end 125.487176 -295.451022)
		(width 0.1143)
		(layer "In6.Cu")
		(net "P5E_CPU1_P2_RX_DP<13>")
	)
	(segment
		(start 125.047756 -289.79876)
		(end 125.016006 -289.780472)
		(width 0.1143)
		(layer "In6.Cu")
		(net "P5E_CPU1_P2_RX_DP<13>")
	)
	(segment
		(start 125.041152 -294.654986)
		(end 125.039882 -294.654224)
		(width 0.1143)
		(layer "In6.Cu")
		(net "P5E_CPU1_P2_RX_DP<13>")
	)
	(segment
		(start 163.463478 -384.3528)
		(end 163.768278 -384.048)
		(width 0.14224)
		(layer "In6.Cu")
		(net "P5E_CPU1_P2_RX_DP<13>")
	)
	(segment
		(start 125.048772 -294.659304)
		(end 125.047756 -294.658796)
		(width 0.1143)
		(layer "In6.Cu")
		(net "P5E_CPU1_P2_RX_DP<13>")
	)
	(segment
		(start 163.688268 -385.548632)
		(end 163.776406 -385.460494)
		(width 0.14224)
		(layer "In6.Cu")
		(net "P5E_CPU1_P2_RX_DP<13>")
	)
	(segment
		(start 125.047756 -283.318966)
		(end 125.046994 -283.318458)
		(width 0.1143)
		(layer "In6.Cu")
		(net "P5E_CPU1_P2_RX_DP<13>")
	)
	(segment
		(start 125.039882 -284.934406)
		(end 125.03785 -284.933136)
		(width 0.1143)
		(layer "In6.Cu")
		(net "P5E_CPU1_P2_RX_DP<13>")
	)
	(segment
		(start 125.016006 -292.411912)
		(end 125.045724 -292.394894)
		(width 0.1143)
		(layer "In6.Cu")
		(net "P5E_CPU1_P2_RX_DP<13>")
	)
	(segment
		(start 125.048772 -293.039292)
		(end 125.047756 -293.038784)
		(width 0.1143)
		(layer "In6.Cu")
		(net "P5E_CPU1_P2_RX_DP<13>")
	)
	(segment
		(start 125.036834 -291.412422)
		(end 125.035564 -291.41166)
		(width 0.1143)
		(layer "In6.Cu")
		(net "P5E_CPU1_P2_RX_DP<13>")
	)
	(segment
		(start 125.048772 -291.41928)
		(end 125.047756 -291.418772)
		(width 0.1143)
		(layer "In6.Cu")
		(net "P5E_CPU1_P2_RX_DP<13>")
	)
	(segment
		(start 125.050296 -282.672282)
		(end 125.086872 -282.650946)
		(width 0.1143)
		(layer "In6.Cu")
		(net "P5E_CPU1_P2_RX_DP<13>")
	)
	(segment
		(start 145.37563 -335.681066)
		(end 142.724124 -322.464176)
		(width 0.14224)
		(layer "In6.Cu")
		(net "P5E_CPU1_P2_RX_DP<13>")
	)
	(segment
		(start 125.041914 -291.41547)
		(end 125.041152 -291.414962)
		(width 0.1143)
		(layer "In6.Cu")
		(net "P5E_CPU1_P2_RX_DP<13>")
	)
	(segment
		(start 125.794008 -281.459178)
		(end 125.876812 -281.376374)
		(width 0.1143)
		(layer "In6.Cu")
		(net "P5E_CPU1_P2_RX_DP<13>")
	)
	(segment
		(start 163.46043 -384.731006)
		(end 163.463478 -384.3528)
		(width 0.14224)
		(layer "In6.Cu")
		(net "P5E_CPU1_P2_RX_DP<13>")
	)
	(segment
		(start 170.355768 -370.768626)
		(end 170.639486 -369.668044)
		(width 0.14224)
		(layer "In6.Cu")
		(net "P5E_CPU1_P2_RX_DP<13>")
	)
	(segment
		(start 125.047756 -294.658796)
		(end 125.046994 -294.658288)
		(width 0.1143)
		(layer "In6.Cu")
		(net "P5E_CPU1_P2_RX_DP<13>")
	)
	(segment
		(start 125.556772 -295.491662)
		(end 125.517656 -295.468802)
		(width 0.1143)
		(layer "In6.Cu")
		(net "P5E_CPU1_P2_RX_DP<13>")
	)
	(segment
		(start 125.845824 -296.34434)
		(end 125.800104 -296.29862)
		(width 0.1143)
		(layer "In6.Cu")
		(net "P5E_CPU1_P2_RX_DP<13>")
	)
	(segment
		(start 163.776406 -385.460494)
		(end 163.776406 -385.046982)
		(width 0.14224)
		(layer "In6.Cu")
		(net "P5E_CPU1_P2_RX_DP<13>")
	)
	(segment
		(start 125.039882 -283.314394)
		(end 125.03785 -283.313124)
		(width 0.1143)
		(layer "In6.Cu")
		(net "P5E_CPU1_P2_RX_DP<13>")
	)
	(segment
		(start 164.015166 -381.675132)
		(end 167.983916 -374.551194)
		(width 0.14224)
		(layer "In6.Cu")
		(net "P5E_CPU1_P2_RX_DP<13>")
	)
	(segment
		(start 125.046994 -289.154108)
		(end 125.047756 -289.1536)
		(width 0.1143)
		(layer "In6.Cu")
		(net "P5E_CPU1_P2_RX_DP<13>")
	)
	(segment
		(start 125.047756 -291.418772)
		(end 125.046994 -291.418264)
		(width 0.1143)
		(layer "In6.Cu")
		(net "P5E_CPU1_P2_RX_DP<13>")
	)
	(segment
		(start 125.047756 -294.013636)
		(end 125.048772 -294.013128)
		(width 0.1143)
		(layer "In6.Cu")
		(net "P5E_CPU1_P2_RX_DP<13>")
	)
	(segment
		(start 125.050296 -294.66032)
		(end 125.048772 -294.659304)
		(width 0.1143)
		(layer "In6.Cu")
		(net "P5E_CPU1_P2_RX_DP<13>")
	)
	(segment
		(start 125.086872 -291.441632)
		(end 125.050296 -291.420296)
		(width 0.1143)
		(layer "In6.Cu")
		(net "P5E_CPU1_P2_RX_DP<13>")
	)
	(segment
		(start 125.086872 -288.201608)
		(end 125.047756 -288.178748)
		(width 0.1143)
		(layer "In6.Cu")
		(net "P5E_CPU1_P2_RX_DP<13>")
	)
	(segment
		(start 170.216068 -368.010694)
		(end 168.280842 -367.11763)
		(width 0.14224)
		(layer "In6.Cu")
		(net "P5E_CPU1_P2_RX_DP<13>")
	)
	(segment
		(start 125.046994 -290.77412)
		(end 125.047756 -290.773612)
		(width 0.1143)
		(layer "In6.Cu")
		(net "P5E_CPU1_P2_RX_DP<13>")
	)
	(segment
		(start 125.045724 -292.394894)
		(end 125.046994 -292.394132)
		(width 0.1143)
		(layer "In6.Cu")
		(net "P5E_CPU1_P2_RX_DP<13>")
	)
	(segment
		(start 125.845824 -296.486326)
		(end 125.845824 -296.372788)
		(width 0.14224)
		(layer "In6.Cu")
		(net "P5E_CPU1_P2_RX_DP<13>")
	)
	(segment
		(start 125.050296 -283.32049)
		(end 125.048772 -283.319474)
		(width 0.1143)
		(layer "In6.Cu")
		(net "P5E_CPU1_P2_RX_DP<13>")
	)
	(segment
		(start 125.03785 -283.313124)
		(end 125.036834 -283.312616)
		(width 0.1143)
		(layer "In6.Cu")
		(net "P5E_CPU1_P2_RX_DP<13>")
	)
	(segment
		(start 125.035564 -291.41166)
		(end 125.016006 -291.400484)
		(width 0.1143)
		(layer "In6.Cu")
		(net "P5E_CPU1_P2_RX_DP<13>")
	)
	(segment
		(start 162.701224 -363.255814)
		(end 162.701224 -363.25556)
		(width 0.14224)
		(layer "In6.Cu")
		(net "P5E_CPU1_P2_RX_DP<13>")
	)
	(segment
		(start 125.047756 -290.773612)
		(end 125.048772 -290.773104)
		(width 0.1143)
		(layer "In6.Cu")
		(net "P5E_CPU1_P2_RX_DP<13>")
	)
	(segment
		(start 125.047756 -287.533842)
		(end 125.084332 -287.512506)
		(width 0.1143)
		(layer "In6.Cu")
		(net "P5E_CPU1_P2_RX_DP<13>")
	)
	(segment
		(start 125.0442 -294.656764)
		(end 125.043438 -294.656256)
		(width 0.1143)
		(layer "In6.Cu")
		(net "P5E_CPU1_P2_RX_DP<13>")
	)
	(segment
		(start 162.649916 -363.205014)
		(end 157.197806 -357.755444)
		(width 0.14224)
		(layer "In6.Cu")
		(net "P5E_CPU1_P2_RX_DP<13>")
	)
	(segment
		(start 125.041914 -294.655494)
		(end 125.041152 -294.654986)
		(width 0.1143)
		(layer "In6.Cu")
		(net "P5E_CPU1_P2_RX_DP<13>")
	)
	(segment
		(start 125.050296 -284.940502)
		(end 125.048772 -284.939486)
		(width 0.1143)
		(layer "In6.Cu")
		(net "P5E_CPU1_P2_RX_DP<13>")
	)
	(segment
		(start 125.016006 -284.312106)
		(end 125.045724 -284.295088)
		(width 0.1143)
		(layer "In6.Cu")
		(net "P5E_CPU1_P2_RX_DP<13>")
	)
	(segment
		(start 125.048772 -283.319474)
		(end 125.047756 -283.318966)
		(width 0.1143)
		(layer "In6.Cu")
		(net "P5E_CPU1_P2_RX_DP<13>")
	)
	(segment
		(start 125.016006 -282.692094)
		(end 125.045724 -282.675076)
		(width 0.1143)
		(layer "In6.Cu")
		(net "P5E_CPU1_P2_RX_DP<13>")
	)
	(segment
		(start 125.485144 -286.742632)
		(end 125.517656 -286.723836)
		(width 0.1143)
		(layer "In6.Cu")
		(net "P5E_CPU1_P2_RX_DP<13>")
	)
	(segment
		(start 125.050296 -289.152076)
		(end 125.086872 -289.13074)
		(width 0.1143)
		(layer "In6.Cu")
		(net "P5E_CPU1_P2_RX_DP<13>")
	)
	(segment
		(start 125.039882 -291.4142)
		(end 125.03785 -291.41293)
		(width 0.1143)
		(layer "In6.Cu")
		(net "P5E_CPU1_P2_RX_DP<13>")
	)
	(segment
		(start 125.041914 -284.935676)
		(end 125.041152 -284.935168)
		(width 0.1143)
		(layer "In6.Cu")
		(net "P5E_CPU1_P2_RX_DP<13>")
	)
	(segment
		(start 125.043438 -283.316426)
		(end 125.041914 -283.315664)
		(width 0.1143)
		(layer "In6.Cu")
		(net "P5E_CPU1_P2_RX_DP<13>")
	)
	(segment
		(start 125.086872 -289.82162)
		(end 125.050296 -289.800284)
		(width 0.1143)
		(layer "In6.Cu")
		(net "P5E_CPU1_P2_RX_DP<13>")
	)
	(segment
		(start 125.043438 -284.936438)
		(end 125.041914 -284.935676)
		(width 0.1143)
		(layer "In6.Cu")
		(net "P5E_CPU1_P2_RX_DP<13>")
	)
	(segment
		(start 129.057654 -301.84217)
		(end 126.180088 -297.535854)
		(width 0.14224)
		(layer "In6.Cu")
		(net "P5E_CPU1_P2_RX_DP<13>")
	)
	(segment
		(start 125.039882 -294.654224)
		(end 125.03785 -294.652954)
		(width 0.1143)
		(layer "In6.Cu")
		(net "P5E_CPU1_P2_RX_DP<13>")
	)
	(segment
		(start 125.035564 -283.311854)
		(end 125.016006 -283.300678)
		(width 0.1143)
		(layer "In6.Cu")
		(net "P5E_CPU1_P2_RX_DP<13>")
	)
	(segment
		(start 142.724124 -322.464176)
		(end 136.637522 -311.078372)
		(width 0.14224)
		(layer "In6.Cu")
		(net "P5E_CPU1_P2_RX_DP<13>")
	)
	(segment
		(start 125.035564 -294.651684)
		(end 125.016006 -294.640508)
		(width 0.1143)
		(layer "In6.Cu")
		(net "P5E_CPU1_P2_RX_DP<13>")
	)
	(segment
		(start 125.048772 -284.29331)
		(end 125.050296 -284.292294)
		(width 0.1143)
		(layer "In6.Cu")
		(net "P5E_CPU1_P2_RX_DP<13>")
	)
	(segment
		(start 125.556772 -285.771844)
		(end 125.517656 -285.748984)
		(width 0.1143)
		(layer "In6.Cu")
		(net "P5E_CPU1_P2_RX_DP<13>")
	)
	(segment
		(start 163.419028 -386.003292)
		(end 163.514024 -385.649216)
		(width 0.14224)
		(layer "In6.Cu")
		(net "P5E_CPU1_P2_RX_DP<13>")
	)
	(segment
		(start 125.050296 -293.040308)
		(end 125.048772 -293.039292)
		(width 0.1143)
		(layer "In6.Cu")
		(net "P5E_CPU1_P2_RX_DP<13>")
	)
	(segment
		(start 125.047756 -284.938978)
		(end 125.046994 -284.93847)
		(width 0.1143)
		(layer "In6.Cu")
		(net "P5E_CPU1_P2_RX_DP<13>")
	)
	(segment
		(start 125.517656 -286.723836)
		(end 125.556772 -286.700976)
		(width 0.1143)
		(layer "In6.Cu")
		(net "P5E_CPU1_P2_RX_DP<13>")
	)
	(segment
		(start 125.046994 -282.674314)
		(end 125.047756 -282.673806)
		(width 0.1143)
		(layer "In6.Cu")
		(net "P5E_CPU1_P2_RX_DP<13>")
	)
	(segment
		(start 125.046994 -284.294326)
		(end 125.047756 -284.293818)
		(width 0.1143)
		(layer "In6.Cu")
		(net "P5E_CPU1_P2_RX_DP<13>")
	)
	(segment
		(start 125.016006 -290.7919)
		(end 125.045724 -290.774882)
		(width 0.1143)
		(layer "In6.Cu")
		(net "P5E_CPU1_P2_RX_DP<13>")
	)
	(segment
		(start 125.846332 -296.730166)
		(end 125.846332 -296.486326)
		(width 0.14224)
		(layer "In6.Cu")
		(net "P5E_CPU1_P2_RX_DP<13>")
	)
	(segment
		(start 125.046994 -294.658288)
		(end 125.0442 -294.656764)
		(width 0.1143)
		(layer "In6.Cu")
		(net "P5E_CPU1_P2_RX_DP<13>")
	)
	(arc
		(start 125.016006 -293.020496)
		(mid 124.860078 -292.716204)
		(end 125.016006 -292.411912)
		(width 0.1143)
		(layer "In6.Cu")
		(net "P5E_CPU1_P2_RX_DP<13>")
	)
	(arc
		(start 125.790198 -281.482038)
		(mid 125.792221 -281.470628)
		(end 125.794008 -281.459178)
		(width 0.1143)
		(layer "In6.Cu")
		(net "P5E_CPU1_P2_RX_DP<13>")
	)
	(arc
		(start 125.086872 -282.650946)
		(mid 125.265685 -282.448596)
		(end 125.330204 -282.18638)
		(width 0.1143)
		(layer "In6.Cu")
		(net "P5E_CPU1_P2_RX_DP<13>")
	)
	(arc
		(start 170.639486 -369.668044)
		(mid 170.650846 -369.600957)
		(end 170.650916 -369.532916)
		(width 0.14224)
		(layer "In6.Cu")
		(net "P5E_CPU1_P2_RX_DP<13>")
	)
	(arc
		(start 125.800104 -295.956228)
		(mid 125.744404 -295.711516)
		(end 125.588268 -295.51503)
		(width 0.1143)
		(layer "In6.Cu")
		(net "P5E_CPU1_P2_RX_DP<13>")
	)
	(arc
		(start 125.014228 -288.15919)
		(mid 124.900821 -288.026301)
		(end 124.86005 -287.856422)
		(width 0.1143)
		(layer "In6.Cu")
		(net "P5E_CPU1_P2_RX_DP<13>")
	)
	(arc
		(start 125.086872 -290.750752)
		(mid 125.330199 -290.286186)
		(end 125.086872 -289.82162)
		(width 0.1143)
		(layer "In6.Cu")
		(net "P5E_CPU1_P2_RX_DP<13>")
	)
	(arc
		(start 125.086872 -289.13074)
		(mid 125.330199 -288.666174)
		(end 125.086872 -288.201608)
		(width 0.1143)
		(layer "In6.Cu")
		(net "P5E_CPU1_P2_RX_DP<13>")
	)
	(arc
		(start 125.556772 -281.84094)
		(mid 125.708759 -281.684432)
		(end 125.790198 -281.482038)
		(width 0.1143)
		(layer "In6.Cu")
		(net "P5E_CPU1_P2_RX_DP<13>")
	)
	(arc
		(start 124.86005 -287.856422)
		(mid 124.901305 -287.685451)
		(end 125.016006 -287.55213)
		(width 0.1143)
		(layer "In6.Cu")
		(net "P5E_CPU1_P2_RX_DP<13>")
	)
	(arc
		(start 125.330204 -287.046162)
		(mid 125.37117 -286.875756)
		(end 125.485144 -286.742632)
		(width 0.1143)
		(layer "In6.Cu")
		(net "P5E_CPU1_P2_RX_DP<13>")
	)
	(arc
		(start 125.016006 -283.300678)
		(mid 124.860078 -282.996386)
		(end 125.016006 -282.692094)
		(width 0.1143)
		(layer "In6.Cu")
		(net "P5E_CPU1_P2_RX_DP<13>")
	)
	(arc
		(start 125.487176 -285.731204)
		(mid 125.371749 -285.597828)
		(end 125.330204 -285.426404)
		(width 0.1143)
		(layer "In6.Cu")
		(net "P5E_CPU1_P2_RX_DP<13>")
	)
	(arc
		(start 125.016006 -294.640508)
		(mid 124.860078 -294.336216)
		(end 125.016006 -294.031924)
		(width 0.1143)
		(layer "In6.Cu")
		(net "P5E_CPU1_P2_RX_DP<13>")
	)
	(arc
		(start 125.086872 -293.990776)
		(mid 125.330199 -293.52621)
		(end 125.086872 -293.061644)
		(width 0.1143)
		(layer "In6.Cu")
		(net "P5E_CPU1_P2_RX_DP<13>")
	)
	(arc
		(start 125.086872 -284.270958)
		(mid 125.330199 -283.806392)
		(end 125.086872 -283.341826)
		(width 0.1143)
		(layer "In6.Cu")
		(net "P5E_CPU1_P2_RX_DP<13>")
	)
	(arc
		(start 125.330204 -295.146222)
		(mid 125.265689 -294.884003)
		(end 125.086872 -294.681656)
		(width 0.1143)
		(layer "In6.Cu")
		(net "P5E_CPU1_P2_RX_DP<13>")
	)
	(arc
		(start 170.563032 -368.472212)
		(mid 170.521686 -368.324561)
		(end 170.42892 -368.202464)
		(width 0.14224)
		(layer "In6.Cu")
		(net "P5E_CPU1_P2_RX_DP<13>")
	)
	(arc
		(start 163.768278 -382.6256)
		(mid 163.831007 -382.134595)
		(end 164.015166 -381.675132)
		(width 0.14224)
		(layer "In6.Cu")
		(net "P5E_CPU1_P2_RX_DP<13>")
	)
	(arc
		(start 168.280842 -367.11763)
		(mid 165.323644 -365.428567)
		(end 162.701224 -363.255814)
		(width 0.14224)
		(layer "In6.Cu")
		(net "P5E_CPU1_P2_RX_DP<13>")
	)
	(arc
		(start 162.701224 -363.25556)
		(mid 162.675546 -363.230311)
		(end 162.649916 -363.205014)
		(width 0.14224)
		(layer "In6.Cu")
		(net "P5E_CPU1_P2_RX_DP<13>")
	)
	(arc
		(start 125.330204 -285.426404)
		(mid 125.265689 -285.164185)
		(end 125.086872 -284.961838)
		(width 0.1143)
		(layer "In6.Cu")
		(net "P5E_CPU1_P2_RX_DP<13>")
	)
	(arc
		(start 157.197806 -357.755444)
		(mid 149.654094 -347.59262)
		(end 145.37563 -335.681066)
		(width 0.14224)
		(layer "In6.Cu")
		(net "P5E_CPU1_P2_RX_DP<13>")
	)
	(arc
		(start 125.330204 -282.18638)
		(mid 125.371753 -282.014958)
		(end 125.487176 -281.88158)
		(width 0.1143)
		(layer "In6.Cu")
		(net "P5E_CPU1_P2_RX_DP<13>")
	)
	(arc
		(start 125.016006 -284.92069)
		(mid 124.860078 -284.616398)
		(end 125.016006 -284.312106)
		(width 0.1143)
		(layer "In6.Cu")
		(net "P5E_CPU1_P2_RX_DP<13>")
	)
	(arc
		(start 125.016006 -291.400484)
		(mid 124.860078 -291.096192)
		(end 125.016006 -290.7919)
		(width 0.1143)
		(layer "In6.Cu")
		(net "P5E_CPU1_P2_RX_DP<13>")
	)
	(arc
		(start 125.556772 -286.700976)
		(mid 125.800099 -286.23641)
		(end 125.556772 -285.771844)
		(width 0.1143)
		(layer "In6.Cu")
		(net "P5E_CPU1_P2_RX_DP<13>")
	)
	(arc
		(start 169.791126 -371.98935)
		(mid 170.128864 -371.404622)
		(end 170.355768 -370.768626)
		(width 0.14224)
		(layer "In6.Cu")
		(net "P5E_CPU1_P2_RX_DP<13>")
	)
	(arc
		(start 125.086872 -292.370764)
		(mid 125.330199 -291.906198)
		(end 125.086872 -291.441632)
		(width 0.1143)
		(layer "In6.Cu")
		(net "P5E_CPU1_P2_RX_DP<13>")
	)
	(arc
		(start 125.016006 -289.780472)
		(mid 124.860078 -289.47618)
		(end 125.016006 -289.171888)
		(width 0.1143)
		(layer "In6.Cu")
		(net "P5E_CPU1_P2_RX_DP<13>")
	)
	(arc
		(start 125.588268 -295.51503)
		(mid 125.572722 -295.503073)
		(end 125.556772 -295.491662)
		(width 0.1143)
		(layer "In6.Cu")
		(net "P5E_CPU1_P2_RX_DP<13>")
	)
	(arc
		(start 125.084332 -287.512506)
		(mid 125.264984 -287.309761)
		(end 125.330204 -287.046162)
		(width 0.1143)
		(layer "In6.Cu")
		(net "P5E_CPU1_P2_RX_DP<13>")
	)
	(arc
		(start 125.487176 -295.451022)
		(mid 125.371749 -295.317646)
		(end 125.330204 -295.146222)
		(width 0.1143)
		(layer "In6.Cu")
		(net "P5E_CPU1_P2_RX_DP<13>")
	)
	(segment
		(start 161.698178 -386.003292)
		(end 162.218878 -386.003292)
		(width 0.127)
		(layer "F.Cu")
		(net "P5E_CPU1_P2_RX_DP<12>")
	)
	(segment
		(start 122.887994 -282.730448)
		(end 123.354846 -282.996386)
		(width 0.12954)
		(layer "F.Cu")
		(net "P5E_CPU1_P2_RX_DP<12>")
	)
	(segment
		(start 124.906278 -296.831766)
		(end 124.906278 -296.37736)
		(width 0.14224)
		(layer "In6.Cu")
		(net "P5E_CPU1_P2_RX_DP<12>")
	)
	(segment
		(start 162.488118 -385.548632)
		(end 162.576256 -385.460494)
		(width 0.14224)
		(layer "In6.Cu")
		(net "P5E_CPU1_P2_RX_DP<12>")
	)
	(segment
		(start 124.571506 -285.745174)
		(end 124.569474 -285.744158)
		(width 0.1143)
		(layer "In6.Cu")
		(net "P5E_CPU1_P2_RX_DP<12>")
	)
	(segment
		(start 124.146818 -291.441632)
		(end 124.077222 -291.400992)
		(width 0.1143)
		(layer "In6.Cu")
		(net "P5E_CPU1_P2_RX_DP<12>")
	)
	(segment
		(start 124.146818 -294.681656)
		(end 124.077222 -294.641016)
		(width 0.1143)
		(layer "In6.Cu")
		(net "P5E_CPU1_P2_RX_DP<12>")
	)
	(segment
		(start 162.26028 -384.731006)
		(end 162.263328 -384.3528)
		(width 0.14224)
		(layer "In6.Cu")
		(net "P5E_CPU1_P2_RX_DP<12>")
	)
	(segment
		(start 128.335024 -302.440594)
		(end 125.303026 -297.903138)
		(width 0.14224)
		(layer "In6.Cu")
		(net "P5E_CPU1_P2_RX_DP<12>")
	)
	(segment
		(start 122.987054 -283.066236)
		(end 123.056904 -282.996386)
		(width 0.1143)
		(layer "In6.Cu")
		(net "P5E_CPU1_P2_RX_DP<12>")
	)
	(segment
		(start 124.580142 -285.750254)
		(end 124.577094 -285.748476)
		(width 0.1143)
		(layer "In6.Cu")
		(net "P5E_CPU1_P2_RX_DP<12>")
	)
	(segment
		(start 123.64466 -284.133036)
		(end 123.643136 -284.13202)
		(width 0.1143)
		(layer "In6.Cu")
		(net "P5E_CPU1_P2_RX_DP<12>")
	)
	(segment
		(start 141.804136 -322.723764)
		(end 136.653778 -313.087766)
		(width 0.14224)
		(layer "In6.Cu")
		(net "P5E_CPU1_P2_RX_DP<12>")
	)
	(segment
		(start 123.67006 -284.147768)
		(end 123.669298 -284.14726)
		(width 0.1143)
		(layer "In6.Cu")
		(net "P5E_CPU1_P2_RX_DP<12>")
	)
	(segment
		(start 124.077222 -292.411404)
		(end 124.146818 -292.370764)
		(width 0.1143)
		(layer "In6.Cu")
		(net "P5E_CPU1_P2_RX_DP<12>")
	)
	(segment
		(start 124.544328 -286.743394)
		(end 124.616972 -286.700976)
		(width 0.1143)
		(layer "In6.Cu")
		(net "P5E_CPU1_P2_RX_DP<12>")
	)
	(segment
		(start 162.313874 -385.649216)
		(end 162.488118 -385.548632)
		(width 0.14224)
		(layer "In6.Cu")
		(net "P5E_CPU1_P2_RX_DP<12>")
	)
	(segment
		(start 123.640596 -284.130496)
		(end 123.63704 -284.128464)
		(width 0.1143)
		(layer "In6.Cu")
		(net "P5E_CPU1_P2_RX_DP<12>")
	)
	(segment
		(start 162.568128 -384.048)
		(end 162.568128 -382.30175)
		(width 0.14224)
		(layer "In6.Cu")
		(net "P5E_CPU1_P2_RX_DP<12>")
	)
	(segment
		(start 124.577094 -285.748476)
		(end 124.573538 -285.746444)
		(width 0.1143)
		(layer "In6.Cu")
		(net "P5E_CPU1_P2_RX_DP<12>")
	)
	(segment
		(start 166.287196 -367.433352)
		(end 165.485318 -367.101374)
		(width 0.14224)
		(layer "In6.Cu")
		(net "P5E_CPU1_P2_RX_DP<12>")
	)
	(segment
		(start 124.146818 -288.201608)
		(end 124.07519 -288.159952)
		(width 0.1143)
		(layer "In6.Cu")
		(net "P5E_CPU1_P2_RX_DP<12>")
	)
	(segment
		(start 124.860558 -295.956736)
		(end 124.86005 -295.956228)
		(width 0.1143)
		(layer "In6.Cu")
		(net "P5E_CPU1_P2_RX_DP<12>")
	)
	(segment
		(start 123.676918 -284.151832)
		(end 123.67006 -284.147768)
		(width 0.1143)
		(layer "In6.Cu")
		(net "P5E_CPU1_P2_RX_DP<12>")
	)
	(segment
		(start 124.146818 -289.82162)
		(end 124.077222 -289.78098)
		(width 0.1143)
		(layer "In6.Cu")
		(net "P5E_CPU1_P2_RX_DP<12>")
	)
	(segment
		(start 162.576256 -385.460494)
		(end 162.576256 -385.046982)
		(width 0.14224)
		(layer "In6.Cu")
		(net "P5E_CPU1_P2_RX_DP<12>")
	)
	(segment
		(start 124.146818 -284.961838)
		(end 124.077222 -284.921198)
		(width 0.1143)
		(layer "In6.Cu")
		(net "P5E_CPU1_P2_RX_DP<12>")
	)
	(segment
		(start 123.64212 -284.131512)
		(end 123.640596 -284.130496)
		(width 0.1143)
		(layer "In6.Cu")
		(net "P5E_CPU1_P2_RX_DP<12>")
	)
	(segment
		(start 123.204224 -283.340048)
		(end 123.136152 -283.300678)
		(width 0.1143)
		(layer "In6.Cu")
		(net "P5E_CPU1_P2_RX_DP<12>")
	)
	(segment
		(start 124.077222 -287.551622)
		(end 124.144278 -287.512506)
		(width 0.1143)
		(layer "In6.Cu")
		(net "P5E_CPU1_P2_RX_DP<12>")
	)
	(segment
		(start 162.713924 -381.580644)
		(end 167.008556 -371.404896)
		(width 0.14224)
		(layer "In6.Cu")
		(net "P5E_CPU1_P2_RX_DP<12>")
	)
	(segment
		(start 124.860558 -296.303192)
		(end 124.860558 -295.956736)
		(width 0.1143)
		(layer "In6.Cu")
		(net "P5E_CPU1_P2_RX_DP<12>")
	)
	(segment
		(start 124.572776 -285.745936)
		(end 124.571506 -285.745174)
		(width 0.1143)
		(layer "In6.Cu")
		(net "P5E_CPU1_P2_RX_DP<12>")
	)
	(segment
		(start 124.906278 -296.348912)
		(end 124.860558 -296.303192)
		(width 0.1143)
		(layer "In6.Cu")
		(net "P5E_CPU1_P2_RX_DP<12>")
	)
	(segment
		(start 124.569474 -285.744158)
		(end 124.546106 -285.730696)
		(width 0.1143)
		(layer "In6.Cu")
		(net "P5E_CPU1_P2_RX_DP<12>")
	)
	(segment
		(start 124.077222 -294.031416)
		(end 124.146818 -293.990776)
		(width 0.1143)
		(layer "In6.Cu")
		(net "P5E_CPU1_P2_RX_DP<12>")
	)
	(segment
		(start 124.077222 -290.791392)
		(end 124.146818 -290.750752)
		(width 0.1143)
		(layer "In6.Cu")
		(net "P5E_CPU1_P2_RX_DP<12>")
	)
	(segment
		(start 124.573538 -285.746444)
		(end 124.572776 -285.745936)
		(width 0.1143)
		(layer "In6.Cu")
		(net "P5E_CPU1_P2_RX_DP<12>")
	)
	(segment
		(start 136.653778 -313.087766)
		(end 134.81304 -310.334406)
		(width 0.14224)
		(layer "In6.Cu")
		(net "P5E_CPU1_P2_RX_DP<12>")
	)
	(segment
		(start 123.056904 -282.996386)
		(end 123.354846 -282.996386)
		(width 0.1143)
		(layer "In6.Cu")
		(net "P5E_CPU1_P2_RX_DP<12>")
	)
	(segment
		(start 162.263328 -384.3528)
		(end 162.568128 -384.048)
		(width 0.14224)
		(layer "In6.Cu")
		(net "P5E_CPU1_P2_RX_DP<12>")
	)
	(segment
		(start 162.576256 -385.046982)
		(end 162.26028 -384.731006)
		(width 0.14224)
		(layer "In6.Cu")
		(net "P5E_CPU1_P2_RX_DP<12>")
	)
	(segment
		(start 167.040814 -371.245892)
		(end 167.040814 -368.561112)
		(width 0.14224)
		(layer "In6.Cu")
		(net "P5E_CPU1_P2_RX_DP<12>")
	)
	(segment
		(start 124.584206 -285.75254)
		(end 124.580142 -285.750254)
		(width 0.1143)
		(layer "In6.Cu")
		(net "P5E_CPU1_P2_RX_DP<12>")
	)
	(segment
		(start 123.643136 -284.13202)
		(end 123.64212 -284.131512)
		(width 0.1143)
		(layer "In6.Cu")
		(net "P5E_CPU1_P2_RX_DP<12>")
	)
	(segment
		(start 124.906278 -296.37736)
		(end 124.906278 -296.348912)
		(width 0.1143)
		(layer "In6.Cu")
		(net "P5E_CPU1_P2_RX_DP<12>")
	)
	(segment
		(start 123.63704 -284.128464)
		(end 123.606052 -284.110684)
		(width 0.1143)
		(layer "In6.Cu")
		(net "P5E_CPU1_P2_RX_DP<12>")
	)
	(segment
		(start 162.218878 -386.003292)
		(end 162.313874 -385.649216)
		(width 0.14224)
		(layer "In6.Cu")
		(net "P5E_CPU1_P2_RX_DP<12>")
	)
	(segment
		(start 124.616972 -285.771844)
		(end 124.584206 -285.75254)
		(width 0.1143)
		(layer "In6.Cu")
		(net "P5E_CPU1_P2_RX_DP<12>")
	)
	(segment
		(start 124.616718 -295.491662)
		(end 124.547122 -295.451022)
		(width 0.1143)
		(layer "In6.Cu")
		(net "P5E_CPU1_P2_RX_DP<12>")
	)
	(segment
		(start 144.370806 -335.628742)
		(end 141.804136 -322.723764)
		(width 0.14224)
		(layer "In6.Cu")
		(net "P5E_CPU1_P2_RX_DP<12>")
	)
	(segment
		(start 124.146818 -293.061644)
		(end 124.077222 -293.021004)
		(width 0.1143)
		(layer "In6.Cu")
		(net "P5E_CPU1_P2_RX_DP<12>")
	)
	(segment
		(start 123.669298 -284.14726)
		(end 123.64466 -284.133036)
		(width 0.1143)
		(layer "In6.Cu")
		(net "P5E_CPU1_P2_RX_DP<12>")
	)
	(segment
		(start 124.077222 -289.17138)
		(end 124.146818 -289.13074)
		(width 0.1143)
		(layer "In6.Cu")
		(net "P5E_CPU1_P2_RX_DP<12>")
	)
	(segment
		(start 125.303026 -297.903138)
		(end 124.949712 -297.050206)
		(width 0.14224)
		(layer "In6.Cu")
		(net "P5E_CPU1_P2_RX_DP<12>")
	)
	(segment
		(start 164.100002 -366.175798)
		(end 156.791914 -358.86771)
		(width 0.14224)
		(layer "In6.Cu")
		(net "P5E_CPU1_P2_RX_DP<12>")
	)
	(segment
		(start 134.81304 -310.334406)
		(end 128.335024 -302.440594)
		(width 0.14224)
		(layer "In6.Cu")
		(net "P5E_CPU1_P2_RX_DP<12>")
	)
	(arc
		(start 124.616972 -286.700976)
		(mid 124.860299 -286.23641)
		(end 124.616972 -285.771844)
		(width 0.1143)
		(layer "In6.Cu")
		(net "P5E_CPU1_P2_RX_DP<12>")
	)
	(arc
		(start 124.077222 -291.400992)
		(mid 123.920245 -291.096192)
		(end 124.077222 -290.791392)
		(width 0.1143)
		(layer "In6.Cu")
		(net "P5E_CPU1_P2_RX_DP<12>")
	)
	(arc
		(start 124.077222 -294.641016)
		(mid 123.920245 -294.336216)
		(end 124.077222 -294.031416)
		(width 0.1143)
		(layer "In6.Cu")
		(net "P5E_CPU1_P2_RX_DP<12>")
	)
	(arc
		(start 124.39015 -285.426404)
		(mid 124.325635 -285.164185)
		(end 124.146818 -284.961838)
		(width 0.1143)
		(layer "In6.Cu")
		(net "P5E_CPU1_P2_RX_DP<12>")
	)
	(arc
		(start 124.146818 -293.990776)
		(mid 124.390145 -293.52621)
		(end 124.146818 -293.061644)
		(width 0.1143)
		(layer "In6.Cu")
		(net "P5E_CPU1_P2_RX_DP<12>")
	)
	(arc
		(start 124.146818 -292.370764)
		(mid 124.390145 -291.906198)
		(end 124.146818 -291.441632)
		(width 0.1143)
		(layer "In6.Cu")
		(net "P5E_CPU1_P2_RX_DP<12>")
	)
	(arc
		(start 123.136152 -283.300678)
		(mid 123.039017 -283.197809)
		(end 122.987054 -283.066236)
		(width 0.1143)
		(layer "In6.Cu")
		(net "P5E_CPU1_P2_RX_DP<12>")
	)
	(arc
		(start 124.547122 -295.451022)
		(mid 124.431695 -295.317646)
		(end 124.39015 -295.146222)
		(width 0.1143)
		(layer "In6.Cu")
		(net "P5E_CPU1_P2_RX_DP<12>")
	)
	(arc
		(start 167.008556 -371.404896)
		(mid 167.032662 -371.327011)
		(end 167.040814 -371.245892)
		(width 0.14224)
		(layer "In6.Cu")
		(net "P5E_CPU1_P2_RX_DP<12>")
	)
	(arc
		(start 124.077222 -289.78098)
		(mid 123.920245 -289.47618)
		(end 124.077222 -289.17138)
		(width 0.1143)
		(layer "In6.Cu")
		(net "P5E_CPU1_P2_RX_DP<12>")
	)
	(arc
		(start 123.92025 -284.616398)
		(mid 123.855735 -284.354179)
		(end 123.676918 -284.151832)
		(width 0.1143)
		(layer "In6.Cu")
		(net "P5E_CPU1_P2_RX_DP<12>")
	)
	(arc
		(start 123.92025 -287.856422)
		(mid 123.961799 -287.685)
		(end 124.077222 -287.551622)
		(width 0.1143)
		(layer "In6.Cu")
		(net "P5E_CPU1_P2_RX_DP<12>")
	)
	(arc
		(start 156.791914 -358.86771)
		(mid 148.857689 -348.169517)
		(end 144.370806 -335.628742)
		(width 0.14224)
		(layer "In6.Cu")
		(net "P5E_CPU1_P2_RX_DP<12>")
	)
	(arc
		(start 124.648214 -295.51503)
		(mid 124.632668 -295.503073)
		(end 124.616718 -295.491662)
		(width 0.1143)
		(layer "In6.Cu")
		(net "P5E_CPU1_P2_RX_DP<12>")
	)
	(arc
		(start 124.077222 -293.021004)
		(mid 123.920245 -292.716204)
		(end 124.077222 -292.411404)
		(width 0.1143)
		(layer "In6.Cu")
		(net "P5E_CPU1_P2_RX_DP<12>")
	)
	(arc
		(start 162.568128 -382.30175)
		(mid 162.604926 -381.9339)
		(end 162.713924 -381.580644)
		(width 0.14224)
		(layer "In6.Cu")
		(net "P5E_CPU1_P2_RX_DP<12>")
	)
	(arc
		(start 165.485318 -367.101374)
		(mid 164.747058 -366.706837)
		(end 164.100002 -366.175798)
		(width 0.14224)
		(layer "In6.Cu")
		(net "P5E_CPU1_P2_RX_DP<12>")
	)
	(arc
		(start 124.39015 -295.146222)
		(mid 124.325635 -294.884003)
		(end 124.146818 -294.681656)
		(width 0.1143)
		(layer "In6.Cu")
		(net "P5E_CPU1_P2_RX_DP<12>")
	)
	(arc
		(start 124.39015 -287.046162)
		(mid 124.430912 -286.876278)
		(end 124.544328 -286.743394)
		(width 0.1143)
		(layer "In6.Cu")
		(net "P5E_CPU1_P2_RX_DP<12>")
	)
	(arc
		(start 167.040814 -368.561112)
		(mid 166.835078 -367.882904)
		(end 166.287196 -367.433352)
		(width 0.14224)
		(layer "In6.Cu")
		(net "P5E_CPU1_P2_RX_DP<12>")
	)
	(arc
		(start 124.146818 -289.13074)
		(mid 124.390145 -288.666174)
		(end 124.146818 -288.201608)
		(width 0.1143)
		(layer "In6.Cu")
		(net "P5E_CPU1_P2_RX_DP<12>")
	)
	(arc
		(start 124.07519 -288.159952)
		(mid 123.961261 -288.026805)
		(end 123.92025 -287.856422)
		(width 0.1143)
		(layer "In6.Cu")
		(net "P5E_CPU1_P2_RX_DP<12>")
	)
	(arc
		(start 123.606052 -284.110684)
		(mid 123.492894 -283.980282)
		(end 123.450096 -283.812996)
		(width 0.1143)
		(layer "In6.Cu")
		(net "P5E_CPU1_P2_RX_DP<12>")
	)
	(arc
		(start 124.077222 -284.921198)
		(mid 123.961795 -284.787822)
		(end 123.92025 -284.616398)
		(width 0.1143)
		(layer "In6.Cu")
		(net "P5E_CPU1_P2_RX_DP<12>")
	)
	(arc
		(start 124.86005 -295.956228)
		(mid 124.80435 -295.711516)
		(end 124.648214 -295.51503)
		(width 0.1143)
		(layer "In6.Cu")
		(net "P5E_CPU1_P2_RX_DP<12>")
	)
	(arc
		(start 124.146818 -290.750752)
		(mid 124.390145 -290.286186)
		(end 124.146818 -289.82162)
		(width 0.1143)
		(layer "In6.Cu")
		(net "P5E_CPU1_P2_RX_DP<12>")
	)
	(arc
		(start 123.450096 -283.812996)
		(mid 123.449886 -283.80486)
		(end 123.449334 -283.79674)
		(width 0.1143)
		(layer "In6.Cu")
		(net "P5E_CPU1_P2_RX_DP<12>")
	)
	(arc
		(start 124.949712 -297.050206)
		(mid 124.917241 -296.943124)
		(end 124.906278 -296.831766)
		(width 0.14224)
		(layer "In6.Cu")
		(net "P5E_CPU1_P2_RX_DP<12>")
	)
	(arc
		(start 123.449334 -283.79674)
		(mid 123.447821 -283.783007)
		(end 123.446032 -283.769308)
		(width 0.1143)
		(layer "In6.Cu")
		(net "P5E_CPU1_P2_RX_DP<12>")
	)
	(arc
		(start 124.144278 -287.512506)
		(mid 124.32493 -287.309761)
		(end 124.39015 -287.046162)
		(width 0.1143)
		(layer "In6.Cu")
		(net "P5E_CPU1_P2_RX_DP<12>")
	)
	(arc
		(start 123.446032 -283.769308)
		(mid 123.365122 -283.532147)
		(end 123.204224 -283.340048)
		(width 0.1143)
		(layer "In6.Cu")
		(net "P5E_CPU1_P2_RX_DP<12>")
	)
	(arc
		(start 124.546106 -285.730696)
		(mid 124.43143 -285.597362)
		(end 124.39015 -285.426404)
		(width 0.1143)
		(layer "In6.Cu")
		(net "P5E_CPU1_P2_RX_DP<12>")
	)
	(segment
		(start 160.498282 -386.003292)
		(end 161.018982 -386.003292)
		(width 0.127)
		(layer "F.Cu")
		(net "P5E_CPU1_P2_RX_DP<11>")
	)
	(segment
		(start 122.887994 -284.35046)
		(end 123.354846 -284.616398)
		(width 0.12954)
		(layer "F.Cu")
		(net "P5E_CPU1_P2_RX_DP<11>")
	)
	(segment
		(start 161.018982 -386.003292)
		(end 161.113978 -385.649216)
		(width 0.14224)
		(layer "In6.Cu")
		(net "P5E_CPU1_P2_RX_DP<11>")
	)
	(segment
		(start 123.637802 -295.468802)
		(end 123.606052 -295.450514)
		(width 0.1143)
		(layer "In6.Cu")
		(net "P5E_CPU1_P2_RX_DP<11>")
	)
	(segment
		(start 164.376608 -370.124228)
		(end 164.229288 -370.063268)
		(width 0.14224)
		(layer "In6.Cu")
		(net "P5E_CPU1_P2_RX_DP<11>")
	)
	(segment
		(start 123.674124 -285.770066)
		(end 123.637802 -285.748984)
		(width 0.1143)
		(layer "In6.Cu")
		(net "P5E_CPU1_P2_RX_DP<11>")
	)
	(segment
		(start 161.37636 -385.046982)
		(end 161.060384 -384.731006)
		(width 0.14224)
		(layer "In6.Cu")
		(net "P5E_CPU1_P2_RX_DP<11>")
	)
	(segment
		(start 123.167648 -288.178748)
		(end 123.135136 -288.159952)
		(width 0.1143)
		(layer "In6.Cu")
		(net "P5E_CPU1_P2_RX_DP<11>")
	)
	(segment
		(start 127.377444 -302.750982)
		(end 124.508514 -298.457874)
		(width 0.14224)
		(layer "In6.Cu")
		(net "P5E_CPU1_P2_RX_DP<11>")
	)
	(segment
		(start 123.206764 -288.201608)
		(end 123.167648 -288.178748)
		(width 0.1143)
		(layer "In6.Cu")
		(net "P5E_CPU1_P2_RX_DP<11>")
	)
	(segment
		(start 161.288222 -385.548632)
		(end 161.37636 -385.460494)
		(width 0.14224)
		(layer "In6.Cu")
		(net "P5E_CPU1_P2_RX_DP<11>")
	)
	(segment
		(start 123.919996 -296.007028)
		(end 123.919996 -295.956228)
		(width 0.1143)
		(layer "In6.Cu")
		(net "P5E_CPU1_P2_RX_DP<11>")
	)
	(segment
		(start 123.966224 -296.353738)
		(end 123.966224 -296.32529)
		(width 0.1143)
		(layer "In6.Cu")
		(net "P5E_CPU1_P2_RX_DP<11>")
	)
	(segment
		(start 123.206764 -293.061644)
		(end 123.137168 -293.021004)
		(width 0.1143)
		(layer "In6.Cu")
		(net "P5E_CPU1_P2_RX_DP<11>")
	)
	(segment
		(start 123.637802 -285.748984)
		(end 123.606052 -285.730696)
		(width 0.1143)
		(layer "In6.Cu")
		(net "P5E_CPU1_P2_RX_DP<11>")
	)
	(segment
		(start 161.368232 -384.048)
		(end 161.368232 -382.121664)
		(width 0.14224)
		(layer "In6.Cu")
		(net "P5E_CPU1_P2_RX_DP<11>")
	)
	(segment
		(start 161.3916 -381.997966)
		(end 165.273228 -372.053612)
		(width 0.14224)
		(layer "In6.Cu")
		(net "P5E_CPU1_P2_RX_DP<11>")
	)
	(segment
		(start 163.50742 -367.154968)
		(end 156.581856 -360.229404)
		(width 0.14224)
		(layer "In6.Cu")
		(net "P5E_CPU1_P2_RX_DP<11>")
	)
	(segment
		(start 123.137168 -289.17138)
		(end 123.206764 -289.13074)
		(width 0.1143)
		(layer "In6.Cu")
		(net "P5E_CPU1_P2_RX_DP<11>")
	)
	(segment
		(start 124.508514 -298.457874)
		(end 124.016516 -297.27017)
		(width 0.14224)
		(layer "In6.Cu")
		(net "P5E_CPU1_P2_RX_DP<11>")
	)
	(segment
		(start 123.920504 -296.27957)
		(end 123.920504 -296.007536)
		(width 0.1143)
		(layer "In6.Cu")
		(net "P5E_CPU1_P2_RX_DP<11>")
	)
	(segment
		(start 123.206764 -291.441632)
		(end 123.137168 -291.400992)
		(width 0.1143)
		(layer "In6.Cu")
		(net "P5E_CPU1_P2_RX_DP<11>")
	)
	(segment
		(start 140.88237 -323.012562)
		(end 135.820658 -313.543696)
		(width 0.14224)
		(layer "In6.Cu")
		(net "P5E_CPU1_P2_RX_DP<11>")
	)
	(segment
		(start 123.674124 -295.489884)
		(end 123.637802 -295.468802)
		(width 0.1143)
		(layer "In6.Cu")
		(net "P5E_CPU1_P2_RX_DP<11>")
	)
	(segment
		(start 135.820658 -313.543696)
		(end 133.997446 -310.817768)
		(width 0.14224)
		(layer "In6.Cu")
		(net "P5E_CPU1_P2_RX_DP<11>")
	)
	(segment
		(start 163.637214 -369.41633)
		(end 163.637214 -367.468404)
		(width 0.14224)
		(layer "In6.Cu")
		(net "P5E_CPU1_P2_RX_DP<11>")
	)
	(segment
		(start 123.137168 -290.791392)
		(end 123.206764 -290.750752)
		(width 0.1143)
		(layer "In6.Cu")
		(net "P5E_CPU1_P2_RX_DP<11>")
	)
	(segment
		(start 122.987054 -284.686248)
		(end 123.056904 -284.616398)
		(width 0.1143)
		(layer "In6.Cu")
		(net "P5E_CPU1_P2_RX_DP<11>")
	)
	(segment
		(start 165.168834 -370.800884)
		(end 164.725096 -370.357146)
		(width 0.14224)
		(layer "In6.Cu")
		(net "P5E_CPU1_P2_RX_DP<11>")
	)
	(segment
		(start 142.267686 -329.976988)
		(end 140.88237 -323.012562)
		(width 0.14224)
		(layer "In6.Cu")
		(net "P5E_CPU1_P2_RX_DP<11>")
	)
	(segment
		(start 123.206764 -294.681656)
		(end 123.137168 -294.641016)
		(width 0.1143)
		(layer "In6.Cu")
		(net "P5E_CPU1_P2_RX_DP<11>")
	)
	(segment
		(start 164.116258 -370.006626)
		(end 163.916868 -369.888516)
		(width 0.14224)
		(layer "In6.Cu")
		(net "P5E_CPU1_P2_RX_DP<11>")
	)
	(segment
		(start 123.056904 -284.616398)
		(end 123.354846 -284.616398)
		(width 0.1143)
		(layer "In6.Cu")
		(net "P5E_CPU1_P2_RX_DP<11>")
	)
	(segment
		(start 133.997446 -310.817768)
		(end 127.377444 -302.750982)
		(width 0.14224)
		(layer "In6.Cu")
		(net "P5E_CPU1_P2_RX_DP<11>")
	)
	(segment
		(start 165.34384 -371.678962)
		(end 165.34384 -371.22354)
		(width 0.14224)
		(layer "In6.Cu")
		(net "P5E_CPU1_P2_RX_DP<11>")
	)
	(segment
		(start 123.137168 -292.411404)
		(end 123.206764 -292.370764)
		(width 0.1143)
		(layer "In6.Cu")
		(net "P5E_CPU1_P2_RX_DP<11>")
	)
	(segment
		(start 123.966224 -296.32529)
		(end 123.920504 -296.27957)
		(width 0.1143)
		(layer "In6.Cu")
		(net "P5E_CPU1_P2_RX_DP<11>")
	)
	(segment
		(start 123.966224 -297.016932)
		(end 123.966224 -296.353738)
		(width 0.14224)
		(layer "In6.Cu")
		(net "P5E_CPU1_P2_RX_DP<11>")
	)
	(segment
		(start 123.137168 -294.031416)
		(end 123.206764 -293.990776)
		(width 0.1143)
		(layer "In6.Cu")
		(net "P5E_CPU1_P2_RX_DP<11>")
	)
	(segment
		(start 161.113978 -385.649216)
		(end 161.288222 -385.548632)
		(width 0.14224)
		(layer "In6.Cu")
		(net "P5E_CPU1_P2_RX_DP<11>")
	)
	(segment
		(start 123.604274 -286.743394)
		(end 123.674124 -286.702754)
		(width 0.1143)
		(layer "In6.Cu")
		(net "P5E_CPU1_P2_RX_DP<11>")
	)
	(segment
		(start 161.060384 -384.731006)
		(end 161.063432 -384.3528)
		(width 0.14224)
		(layer "In6.Cu")
		(net "P5E_CPU1_P2_RX_DP<11>")
	)
	(segment
		(start 161.37636 -385.460494)
		(end 161.37636 -385.046982)
		(width 0.14224)
		(layer "In6.Cu")
		(net "P5E_CPU1_P2_RX_DP<11>")
	)
	(segment
		(start 161.063432 -384.3528)
		(end 161.368232 -384.048)
		(width 0.14224)
		(layer "In6.Cu")
		(net "P5E_CPU1_P2_RX_DP<11>")
	)
	(segment
		(start 142.267432 -329.976988)
		(end 142.267686 -329.976988)
		(width 0.14224)
		(layer "In6.Cu")
		(net "P5E_CPU1_P2_RX_DP<11>")
	)
	(segment
		(start 143.36776 -335.508092)
		(end 142.267432 -329.976988)
		(width 0.14224)
		(layer "In6.Cu")
		(net "P5E_CPU1_P2_RX_DP<11>")
	)
	(segment
		(start 123.206764 -284.961838)
		(end 123.137168 -284.921198)
		(width 0.1143)
		(layer "In6.Cu")
		(net "P5E_CPU1_P2_RX_DP<11>")
	)
	(segment
		(start 123.137168 -287.551622)
		(end 123.204224 -287.512506)
		(width 0.1143)
		(layer "In6.Cu")
		(net "P5E_CPU1_P2_RX_DP<11>")
	)
	(segment
		(start 123.920504 -296.007536)
		(end 123.919996 -296.007028)
		(width 0.1143)
		(layer "In6.Cu")
		(net "P5E_CPU1_P2_RX_DP<11>")
	)
	(segment
		(start 123.206764 -289.82162)
		(end 123.137168 -289.78098)
		(width 0.1143)
		(layer "In6.Cu")
		(net "P5E_CPU1_P2_RX_DP<11>")
	)
	(arc
		(start 122.980196 -287.856422)
		(mid 123.021745 -287.685)
		(end 123.137168 -287.551622)
		(width 0.1143)
		(layer "In6.Cu")
		(net "P5E_CPU1_P2_RX_DP<11>")
	)
	(arc
		(start 123.69038 -285.781496)
		(mid 123.682302 -285.77571)
		(end 123.674124 -285.770066)
		(width 0.1143)
		(layer "In6.Cu")
		(net "P5E_CPU1_P2_RX_DP<11>")
	)
	(arc
		(start 123.206764 -290.750752)
		(mid 123.450091 -290.286186)
		(end 123.206764 -289.82162)
		(width 0.1143)
		(layer "In6.Cu")
		(net "P5E_CPU1_P2_RX_DP<11>")
	)
	(arc
		(start 165.273228 -372.053612)
		(mid 165.32602 -371.869583)
		(end 165.34384 -371.678962)
		(width 0.14224)
		(layer "In6.Cu")
		(net "P5E_CPU1_P2_RX_DP<11>")
	)
	(arc
		(start 123.449842 -287.046162)
		(mid 123.490742 -286.876261)
		(end 123.604274 -286.743394)
		(width 0.1143)
		(layer "In6.Cu")
		(net "P5E_CPU1_P2_RX_DP<11>")
	)
	(arc
		(start 123.137168 -293.021004)
		(mid 122.980191 -292.716204)
		(end 123.137168 -292.411404)
		(width 0.1143)
		(layer "In6.Cu")
		(net "P5E_CPU1_P2_RX_DP<11>")
	)
	(arc
		(start 123.204224 -287.512506)
		(mid 123.384706 -287.309716)
		(end 123.449842 -287.046162)
		(width 0.1143)
		(layer "In6.Cu")
		(net "P5E_CPU1_P2_RX_DP<11>")
	)
	(arc
		(start 123.674124 -286.702754)
		(mid 123.856308 -286.497084)
		(end 123.919996 -286.229806)
		(width 0.1143)
		(layer "In6.Cu")
		(net "P5E_CPU1_P2_RX_DP<11>")
	)
	(arc
		(start 123.137168 -289.78098)
		(mid 122.980191 -289.47618)
		(end 123.137168 -289.17138)
		(width 0.1143)
		(layer "In6.Cu")
		(net "P5E_CPU1_P2_RX_DP<11>")
	)
	(arc
		(start 163.916868 -369.888516)
		(mid 163.864879 -369.851884)
		(end 163.819586 -369.807236)
		(width 0.14224)
		(layer "In6.Cu")
		(net "P5E_CPU1_P2_RX_DP<11>")
	)
	(arc
		(start 123.135136 -288.159952)
		(mid 123.021207 -288.026805)
		(end 122.980196 -287.856422)
		(width 0.1143)
		(layer "In6.Cu")
		(net "P5E_CPU1_P2_RX_DP<11>")
	)
	(arc
		(start 124.016516 -297.27017)
		(mid 123.978907 -297.146027)
		(end 123.966224 -297.016932)
		(width 0.14224)
		(layer "In6.Cu")
		(net "P5E_CPU1_P2_RX_DP<11>")
	)
	(arc
		(start 163.663122 -369.549172)
		(mid 163.643745 -369.484005)
		(end 163.637214 -369.41633)
		(width 0.14224)
		(layer "In6.Cu")
		(net "P5E_CPU1_P2_RX_DP<11>")
	)
	(arc
		(start 123.606052 -295.450514)
		(mid 123.491376 -295.31718)
		(end 123.450096 -295.146222)
		(width 0.1143)
		(layer "In6.Cu")
		(net "P5E_CPU1_P2_RX_DP<11>")
	)
	(arc
		(start 123.206764 -293.990776)
		(mid 123.450091 -293.52621)
		(end 123.206764 -293.061644)
		(width 0.1143)
		(layer "In6.Cu")
		(net "P5E_CPU1_P2_RX_DP<11>")
	)
	(arc
		(start 123.137168 -284.921198)
		(mid 123.039403 -284.818222)
		(end 122.987054 -284.686248)
		(width 0.1143)
		(layer "In6.Cu")
		(net "P5E_CPU1_P2_RX_DP<11>")
	)
	(arc
		(start 164.229288 -370.063268)
		(mid 164.171761 -370.036965)
		(end 164.116258 -370.006626)
		(width 0.14224)
		(layer "In6.Cu")
		(net "P5E_CPU1_P2_RX_DP<11>")
	)
	(arc
		(start 156.581856 -360.229404)
		(mid 148.141372 -348.848766)
		(end 143.36776 -335.508092)
		(width 0.14224)
		(layer "In6.Cu")
		(net "P5E_CPU1_P2_RX_DP<11>")
	)
	(arc
		(start 163.637214 -367.468404)
		(mid 163.603475 -367.298787)
		(end 163.50742 -367.154968)
		(width 0.14224)
		(layer "In6.Cu")
		(net "P5E_CPU1_P2_RX_DP<11>")
	)
	(arc
		(start 123.606052 -285.730696)
		(mid 123.491376 -285.597362)
		(end 123.450096 -285.426404)
		(width 0.1143)
		(layer "In6.Cu")
		(net "P5E_CPU1_P2_RX_DP<11>")
	)
	(arc
		(start 165.34384 -371.22354)
		(mid 165.298346 -370.994825)
		(end 165.168834 -370.800884)
		(width 0.14224)
		(layer "In6.Cu")
		(net "P5E_CPU1_P2_RX_DP<11>")
	)
	(arc
		(start 123.206764 -289.13074)
		(mid 123.450091 -288.666174)
		(end 123.206764 -288.201608)
		(width 0.1143)
		(layer "In6.Cu")
		(net "P5E_CPU1_P2_RX_DP<11>")
	)
	(arc
		(start 123.137168 -291.400992)
		(mid 122.980191 -291.096192)
		(end 123.137168 -290.791392)
		(width 0.1143)
		(layer "In6.Cu")
		(net "P5E_CPU1_P2_RX_DP<11>")
	)
	(arc
		(start 161.368232 -382.121664)
		(mid 161.374154 -382.058727)
		(end 161.3916 -381.997966)
		(width 0.14224)
		(layer "In6.Cu")
		(net "P5E_CPU1_P2_RX_DP<11>")
	)
	(arc
		(start 164.725096 -370.357146)
		(mid 164.562335 -370.223505)
		(end 164.376608 -370.124228)
		(width 0.14224)
		(layer "In6.Cu")
		(net "P5E_CPU1_P2_RX_DP<11>")
	)
	(arc
		(start 123.919996 -295.956228)
		(mid 123.85476 -295.692637)
		(end 123.674124 -295.489884)
		(width 0.1143)
		(layer "In6.Cu")
		(net "P5E_CPU1_P2_RX_DP<11>")
	)
	(arc
		(start 123.919996 -286.229806)
		(mid 123.855124 -285.980064)
		(end 123.69038 -285.781496)
		(width 0.1143)
		(layer "In6.Cu")
		(net "P5E_CPU1_P2_RX_DP<11>")
	)
	(arc
		(start 123.450096 -295.146222)
		(mid 123.385581 -294.884003)
		(end 123.206764 -294.681656)
		(width 0.1143)
		(layer "In6.Cu")
		(net "P5E_CPU1_P2_RX_DP<11>")
	)
	(arc
		(start 123.137168 -294.641016)
		(mid 122.980191 -294.336216)
		(end 123.137168 -294.031416)
		(width 0.1143)
		(layer "In6.Cu")
		(net "P5E_CPU1_P2_RX_DP<11>")
	)
	(arc
		(start 123.450096 -285.426404)
		(mid 123.385581 -285.164185)
		(end 123.206764 -284.961838)
		(width 0.1143)
		(layer "In6.Cu")
		(net "P5E_CPU1_P2_RX_DP<11>")
	)
	(arc
		(start 163.819586 -369.807236)
		(mid 163.730947 -369.684515)
		(end 163.663122 -369.549172)
		(width 0.14224)
		(layer "In6.Cu")
		(net "P5E_CPU1_P2_RX_DP<11>")
	)
	(arc
		(start 123.206764 -292.370764)
		(mid 123.450091 -291.906198)
		(end 123.206764 -291.441632)
		(width 0.1143)
		(layer "In6.Cu")
		(net "P5E_CPU1_P2_RX_DP<11>")
	)
	(segment
		(start 159.298386 -386.003292)
		(end 159.819086 -386.003292)
		(width 0.127)
		(layer "F.Cu")
		(net "P5E_CPU1_P2_RX_DP<10>")
	)
	(segment
		(start 122.887994 -285.970472)
		(end 123.354846 -286.23641)
		(width 0.12954)
		(layer "F.Cu")
		(net "P5E_CPU1_P2_RX_DP<10>")
	)
	(segment
		(start 122.66422 -286.743394)
		(end 122.736864 -286.700976)
		(width 0.1143)
		(layer "In6.Cu")
		(net "P5E_CPU1_P2_RX_DP<10>")
	)
	(segment
		(start 159.863536 -384.3528)
		(end 160.168336 -384.048)
		(width 0.14224)
		(layer "In6.Cu")
		(net "P5E_CPU1_P2_RX_DP<10>")
	)
	(segment
		(start 159.914082 -385.649216)
		(end 160.088326 -385.548632)
		(width 0.14224)
		(layer "In6.Cu")
		(net "P5E_CPU1_P2_RX_DP<10>")
	)
	(segment
		(start 122.704606 -295.472866)
		(end 122.703082 -295.47185)
		(width 0.1143)
		(layer "In6.Cu")
		(net "P5E_CPU1_P2_RX_DP<10>")
	)
	(segment
		(start 122.980196 -296.007028)
		(end 122.980196 -295.956228)
		(width 0.1143)
		(layer "In6.Cu")
		(net "P5E_CPU1_P2_RX_DP<10>")
	)
	(segment
		(start 123.056904 -286.23641)
		(end 123.354846 -286.23641)
		(width 0.1143)
		(layer "In6.Cu")
		(net "P5E_CPU1_P2_RX_DP<10>")
	)
	(segment
		(start 140.005562 -323.398642)
		(end 135.179054 -314.36818)
		(width 0.14224)
		(layer "In6.Cu")
		(net "P5E_CPU1_P2_RX_DP<10>")
	)
	(segment
		(start 122.730006 -295.487598)
		(end 122.729244 -295.48709)
		(width 0.1143)
		(layer "In6.Cu")
		(net "P5E_CPU1_P2_RX_DP<10>")
	)
	(segment
		(start 122.26671 -288.201608)
		(end 122.227594 -288.178748)
		(width 0.1143)
		(layer "In6.Cu")
		(net "P5E_CPU1_P2_RX_DP<10>")
	)
	(segment
		(start 160.088326 -385.548632)
		(end 160.176464 -385.460494)
		(width 0.14224)
		(layer "In6.Cu")
		(net "P5E_CPU1_P2_RX_DP<10>")
	)
	(segment
		(start 122.702066 -295.471342)
		(end 122.700542 -295.470326)
		(width 0.1143)
		(layer "In6.Cu")
		(net "P5E_CPU1_P2_RX_DP<10>")
	)
	(segment
		(start 122.197114 -287.551622)
		(end 122.26417 -287.512506)
		(width 0.1143)
		(layer "In6.Cu")
		(net "P5E_CPU1_P2_RX_DP<10>")
	)
	(segment
		(start 122.697748 -295.468802)
		(end 122.665998 -295.450514)
		(width 0.1143)
		(layer "In6.Cu")
		(net "P5E_CPU1_P2_RX_DP<10>")
	)
	(segment
		(start 122.980704 -296.007536)
		(end 122.980196 -296.007028)
		(width 0.1143)
		(layer "In6.Cu")
		(net "P5E_CPU1_P2_RX_DP<10>")
	)
	(segment
		(start 134.562342 -313.339734)
		(end 132.786628 -310.819292)
		(width 0.14224)
		(layer "In6.Cu")
		(net "P5E_CPU1_P2_RX_DP<10>")
	)
	(segment
		(start 160.168336 -384.048)
		(end 160.168336 -374.180862)
		(width 0.14224)
		(layer "In6.Cu")
		(net "P5E_CPU1_P2_RX_DP<10>")
	)
	(segment
		(start 122.197114 -294.031416)
		(end 122.26671 -293.990776)
		(width 0.1143)
		(layer "In6.Cu")
		(net "P5E_CPU1_P2_RX_DP<10>")
	)
	(segment
		(start 160.176464 -385.046982)
		(end 159.860488 -384.731006)
		(width 0.14224)
		(layer "In6.Cu")
		(net "P5E_CPU1_P2_RX_DP<10>")
	)
	(segment
		(start 122.227594 -288.178748)
		(end 122.195082 -288.159952)
		(width 0.1143)
		(layer "In6.Cu")
		(net "P5E_CPU1_P2_RX_DP<10>")
	)
	(segment
		(start 122.26671 -293.061644)
		(end 122.197114 -293.021004)
		(width 0.1143)
		(layer "In6.Cu")
		(net "P5E_CPU1_P2_RX_DP<10>")
	)
	(segment
		(start 126.625604 -303.312068)
		(end 123.630182 -298.829222)
		(width 0.14224)
		(layer "In6.Cu")
		(net "P5E_CPU1_P2_RX_DP<10>")
	)
	(segment
		(start 142.66291 -336.759042)
		(end 142.351506 -335.194148)
		(width 0.14224)
		(layer "In6.Cu")
		(net "P5E_CPU1_P2_RX_DP<10>")
	)
	(segment
		(start 135.179054 -314.36818)
		(end 134.562342 -313.339734)
		(width 0.14224)
		(layer "In6.Cu")
		(net "P5E_CPU1_P2_RX_DP<10>")
	)
	(segment
		(start 122.700542 -295.470326)
		(end 122.698764 -295.46931)
		(width 0.1143)
		(layer "In6.Cu")
		(net "P5E_CPU1_P2_RX_DP<10>")
	)
	(segment
		(start 160.176464 -385.460494)
		(end 160.176464 -385.046982)
		(width 0.14224)
		(layer "In6.Cu")
		(net "P5E_CPU1_P2_RX_DP<10>")
	)
	(segment
		(start 159.819086 -386.003292)
		(end 159.914082 -385.649216)
		(width 0.14224)
		(layer "In6.Cu")
		(net "P5E_CPU1_P2_RX_DP<10>")
	)
	(segment
		(start 122.980704 -296.27957)
		(end 122.980704 -296.007536)
		(width 0.1143)
		(layer "In6.Cu")
		(net "P5E_CPU1_P2_RX_DP<10>")
	)
	(segment
		(start 122.197114 -292.411404)
		(end 122.26671 -292.370764)
		(width 0.1143)
		(layer "In6.Cu")
		(net "P5E_CPU1_P2_RX_DP<10>")
	)
	(segment
		(start 123.026424 -297.2308)
		(end 123.026424 -296.353738)
		(width 0.14224)
		(layer "In6.Cu")
		(net "P5E_CPU1_P2_RX_DP<10>")
	)
	(segment
		(start 123.026424 -296.32529)
		(end 122.980704 -296.27957)
		(width 0.1143)
		(layer "In6.Cu")
		(net "P5E_CPU1_P2_RX_DP<10>")
	)
	(segment
		(start 160.292796 -373.628412)
		(end 161.412936 -371.268498)
		(width 0.14224)
		(layer "In6.Cu")
		(net "P5E_CPU1_P2_RX_DP<10>")
	)
	(segment
		(start 142.35176 -335.194148)
		(end 142.351506 -335.193386)
		(width 0.14224)
		(layer "In6.Cu")
		(net "P5E_CPU1_P2_RX_DP<10>")
	)
	(segment
		(start 122.26671 -294.681656)
		(end 122.197114 -294.641016)
		(width 0.1143)
		(layer "In6.Cu")
		(net "P5E_CPU1_P2_RX_DP<10>")
	)
	(segment
		(start 159.860488 -384.731006)
		(end 159.863536 -384.3528)
		(width 0.14224)
		(layer "In6.Cu")
		(net "P5E_CPU1_P2_RX_DP<10>")
	)
	(segment
		(start 122.26671 -289.82162)
		(end 122.197114 -289.78098)
		(width 0.1143)
		(layer "In6.Cu")
		(net "P5E_CPU1_P2_RX_DP<10>")
	)
	(segment
		(start 122.703082 -295.47185)
		(end 122.702066 -295.471342)
		(width 0.1143)
		(layer "In6.Cu")
		(net "P5E_CPU1_P2_RX_DP<10>")
	)
	(segment
		(start 123.026424 -296.353738)
		(end 123.026424 -296.32529)
		(width 0.1143)
		(layer "In6.Cu")
		(net "P5E_CPU1_P2_RX_DP<10>")
	)
	(segment
		(start 122.698764 -295.46931)
		(end 122.697748 -295.468802)
		(width 0.1143)
		(layer "In6.Cu")
		(net "P5E_CPU1_P2_RX_DP<10>")
	)
	(segment
		(start 122.729244 -295.48709)
		(end 122.704606 -295.472866)
		(width 0.1143)
		(layer "In6.Cu")
		(net "P5E_CPU1_P2_RX_DP<10>")
	)
	(segment
		(start 161.45256 -371.092984)
		(end 161.45256 -367.258854)
		(width 0.14224)
		(layer "In6.Cu")
		(net "P5E_CPU1_P2_RX_DP<10>")
	)
	(segment
		(start 161.335212 -366.954562)
		(end 153.523188 -358.334056)
		(width 0.14224)
		(layer "In6.Cu")
		(net "P5E_CPU1_P2_RX_DP<10>")
	)
	(segment
		(start 142.351506 -335.194148)
		(end 142.35176 -335.194148)
		(width 0.14224)
		(layer "In6.Cu")
		(net "P5E_CPU1_P2_RX_DP<10>")
	)
	(segment
		(start 142.351506 -335.193386)
		(end 140.005562 -323.398642)
		(width 0.14224)
		(layer "In6.Cu")
		(net "P5E_CPU1_P2_RX_DP<10>")
	)
	(segment
		(start 122.26671 -291.441632)
		(end 122.197114 -291.400992)
		(width 0.1143)
		(layer "In6.Cu")
		(net "P5E_CPU1_P2_RX_DP<10>")
	)
	(segment
		(start 123.630182 -298.829222)
		(end 123.080272 -297.501056)
		(width 0.14224)
		(layer "In6.Cu")
		(net "P5E_CPU1_P2_RX_DP<10>")
	)
	(segment
		(start 132.786628 -310.819292)
		(end 126.625604 -303.312068)
		(width 0.14224)
		(layer "In6.Cu")
		(net "P5E_CPU1_P2_RX_DP<10>")
	)
	(segment
		(start 122.736864 -295.491662)
		(end 122.730006 -295.487598)
		(width 0.1143)
		(layer "In6.Cu")
		(net "P5E_CPU1_P2_RX_DP<10>")
	)
	(segment
		(start 122.197114 -289.17138)
		(end 122.26671 -289.13074)
		(width 0.1143)
		(layer "In6.Cu")
		(net "P5E_CPU1_P2_RX_DP<10>")
	)
	(segment
		(start 122.9741 -286.319214)
		(end 123.056904 -286.23641)
		(width 0.1143)
		(layer "In6.Cu")
		(net "P5E_CPU1_P2_RX_DP<10>")
	)
	(segment
		(start 122.197114 -290.791392)
		(end 122.26671 -290.750752)
		(width 0.1143)
		(layer "In6.Cu")
		(net "P5E_CPU1_P2_RX_DP<10>")
	)
	(arc
		(start 122.197114 -294.641016)
		(mid 122.040137 -294.336216)
		(end 122.197114 -294.031416)
		(width 0.1143)
		(layer "In6.Cu")
		(net "P5E_CPU1_P2_RX_DP<10>")
	)
	(arc
		(start 122.26671 -290.750752)
		(mid 122.510037 -290.286186)
		(end 122.26671 -289.82162)
		(width 0.1143)
		(layer "In6.Cu")
		(net "P5E_CPU1_P2_RX_DP<10>")
	)
	(arc
		(start 122.26671 -292.370764)
		(mid 122.510037 -291.906198)
		(end 122.26671 -291.441632)
		(width 0.1143)
		(layer "In6.Cu")
		(net "P5E_CPU1_P2_RX_DP<10>")
	)
	(arc
		(start 122.195082 -288.159952)
		(mid 122.081153 -288.026805)
		(end 122.040142 -287.856422)
		(width 0.1143)
		(layer "In6.Cu")
		(net "P5E_CPU1_P2_RX_DP<10>")
	)
	(arc
		(start 122.26671 -289.13074)
		(mid 122.510037 -288.666174)
		(end 122.26671 -288.201608)
		(width 0.1143)
		(layer "In6.Cu")
		(net "P5E_CPU1_P2_RX_DP<10>")
	)
	(arc
		(start 161.45256 -367.258854)
		(mid 161.422165 -367.095802)
		(end 161.335212 -366.954562)
		(width 0.14224)
		(layer "In6.Cu")
		(net "P5E_CPU1_P2_RX_DP<10>")
	)
	(arc
		(start 122.510042 -295.146222)
		(mid 122.445527 -294.884003)
		(end 122.26671 -294.681656)
		(width 0.1143)
		(layer "In6.Cu")
		(net "P5E_CPU1_P2_RX_DP<10>")
	)
	(arc
		(start 122.736864 -286.700976)
		(mid 122.888851 -286.544468)
		(end 122.97029 -286.342074)
		(width 0.1143)
		(layer "In6.Cu")
		(net "P5E_CPU1_P2_RX_DP<10>")
	)
	(arc
		(start 122.197114 -293.021004)
		(mid 122.040137 -292.716204)
		(end 122.197114 -292.411404)
		(width 0.1143)
		(layer "In6.Cu")
		(net "P5E_CPU1_P2_RX_DP<10>")
	)
	(arc
		(start 122.26417 -287.512506)
		(mid 122.444822 -287.309761)
		(end 122.510042 -287.046162)
		(width 0.1143)
		(layer "In6.Cu")
		(net "P5E_CPU1_P2_RX_DP<10>")
	)
	(arc
		(start 122.197114 -291.400992)
		(mid 122.040137 -291.096192)
		(end 122.197114 -290.791392)
		(width 0.1143)
		(layer "In6.Cu")
		(net "P5E_CPU1_P2_RX_DP<10>")
	)
	(arc
		(start 153.523188 -358.334056)
		(mid 146.628194 -348.283917)
		(end 142.66291 -336.759042)
		(width 0.14224)
		(layer "In6.Cu")
		(net "P5E_CPU1_P2_RX_DP<10>")
	)
	(arc
		(start 160.168336 -374.180862)
		(mid 160.199837 -373.897714)
		(end 160.292796 -373.628412)
		(width 0.14224)
		(layer "In6.Cu")
		(net "P5E_CPU1_P2_RX_DP<10>")
	)
	(arc
		(start 161.412936 -371.268498)
		(mid 161.442518 -371.182946)
		(end 161.45256 -371.092984)
		(width 0.14224)
		(layer "In6.Cu")
		(net "P5E_CPU1_P2_RX_DP<10>")
	)
	(arc
		(start 122.665998 -295.450514)
		(mid 122.551322 -295.31718)
		(end 122.510042 -295.146222)
		(width 0.1143)
		(layer "In6.Cu")
		(net "P5E_CPU1_P2_RX_DP<10>")
	)
	(arc
		(start 122.510042 -287.046162)
		(mid 122.550804 -286.876278)
		(end 122.66422 -286.743394)
		(width 0.1143)
		(layer "In6.Cu")
		(net "P5E_CPU1_P2_RX_DP<10>")
	)
	(arc
		(start 122.980196 -295.956228)
		(mid 122.915608 -295.694061)
		(end 122.736864 -295.491662)
		(width 0.1143)
		(layer "In6.Cu")
		(net "P5E_CPU1_P2_RX_DP<10>")
	)
	(arc
		(start 122.26671 -293.990776)
		(mid 122.510037 -293.52621)
		(end 122.26671 -293.061644)
		(width 0.1143)
		(layer "In6.Cu")
		(net "P5E_CPU1_P2_RX_DP<10>")
	)
	(arc
		(start 123.080272 -297.501056)
		(mid 123.040069 -297.368576)
		(end 123.026424 -297.2308)
		(width 0.14224)
		(layer "In6.Cu")
		(net "P5E_CPU1_P2_RX_DP<10>")
	)
	(arc
		(start 122.97029 -286.342074)
		(mid 122.972313 -286.330664)
		(end 122.9741 -286.319214)
		(width 0.1143)
		(layer "In6.Cu")
		(net "P5E_CPU1_P2_RX_DP<10>")
	)
	(arc
		(start 122.197114 -289.78098)
		(mid 122.040137 -289.47618)
		(end 122.197114 -289.17138)
		(width 0.1143)
		(layer "In6.Cu")
		(net "P5E_CPU1_P2_RX_DP<10>")
	)
	(arc
		(start 122.040142 -287.856422)
		(mid 122.081691 -287.685)
		(end 122.197114 -287.551622)
		(width 0.1143)
		(layer "In6.Cu")
		(net "P5E_CPU1_P2_RX_DP<10>")
	)
	(segment
		(start 147.29841 -386.003292)
		(end 147.81911 -386.003292)
		(width 0.127)
		(layer "F.Cu")
		(net "P5E_CPU1_P2_RX_DP<0>")
	)
	(segment
		(start 114.897916 -281.920442)
		(end 115.364768 -282.18638)
		(width 0.12954)
		(layer "F.Cu")
		(net "P5E_CPU1_P2_RX_DP<0>")
	)
	(segment
		(start 140.12545 -368.769138)
		(end 134.696708 -347.096842)
		(width 0.14224)
		(layer "In6.Cu")
		(net "P5E_CPU1_P2_RX_DP<0>")
	)
	(segment
		(start 114.737134 -282.656534)
		(end 114.746786 -282.650946)
		(width 0.1143)
		(layer "In6.Cu")
		(net "P5E_CPU1_P2_RX_DP<0>")
	)
	(segment
		(start 112.95634 -296.053764)
		(end 112.95634 -285.152592)
		(width 0.14224)
		(layer "In6.Cu")
		(net "P5E_CPU1_P2_RX_DP<0>")
	)
	(segment
		(start 112.95634 -285.152592)
		(end 113.266728 -284.842204)
		(width 0.14224)
		(layer "In6.Cu")
		(net "P5E_CPU1_P2_RX_DP<0>")
	)
	(segment
		(start 127.183388 -319.361566)
		(end 125.586744 -316.972188)
		(width 0.14224)
		(layer "In6.Cu")
		(net "P5E_CPU1_P2_RX_DP<0>")
	)
	(segment
		(start 114.984022 -282.269184)
		(end 115.066826 -282.18638)
		(width 0.1143)
		(layer "In6.Cu")
		(net "P5E_CPU1_P2_RX_DP<0>")
	)
	(segment
		(start 113.266728 -284.842204)
		(end 113.286794 -284.822138)
		(width 0.1143)
		(layer "In6.Cu")
		(net "P5E_CPU1_P2_RX_DP<0>")
	)
	(segment
		(start 114.611404 -282.738576)
		(end 114.67592 -282.692094)
		(width 0.1143)
		(layer "In6.Cu")
		(net "P5E_CPU1_P2_RX_DP<0>")
	)
	(segment
		(start 147.81911 -386.003292)
		(end 147.914106 -385.649216)
		(width 0.14224)
		(layer "In6.Cu")
		(net "P5E_CPU1_P2_RX_DP<0>")
	)
	(segment
		(start 114.519964 -283.000704)
		(end 114.519964 -282.917138)
		(width 0.1143)
		(layer "In6.Cu")
		(net "P5E_CPU1_P2_RX_DP<0>")
	)
	(segment
		(start 148.176488 -385.046982)
		(end 147.860512 -384.731006)
		(width 0.14224)
		(layer "In6.Cu")
		(net "P5E_CPU1_P2_RX_DP<0>")
	)
	(segment
		(start 113.286794 -284.757114)
		(end 113.691162 -284.352746)
		(width 0.1143)
		(layer "In6.Cu")
		(net "P5E_CPU1_P2_RX_DP<0>")
	)
	(segment
		(start 147.914106 -385.649216)
		(end 148.08835 -385.548632)
		(width 0.14224)
		(layer "In6.Cu")
		(net "P5E_CPU1_P2_RX_DP<0>")
	)
	(segment
		(start 148.08835 -385.548632)
		(end 148.176488 -385.460494)
		(width 0.14224)
		(layer "In6.Cu")
		(net "P5E_CPU1_P2_RX_DP<0>")
	)
	(segment
		(start 148.16836 -384.048)
		(end 148.16836 -382.408176)
		(width 0.14224)
		(layer "In6.Cu")
		(net "P5E_CPU1_P2_RX_DP<0>")
	)
	(segment
		(start 113.286794 -284.822138)
		(end 113.286794 -284.757114)
		(width 0.1143)
		(layer "In6.Cu")
		(net "P5E_CPU1_P2_RX_DP<0>")
	)
	(segment
		(start 114.67592 -282.692094)
		(end 114.70767 -282.673806)
		(width 0.1143)
		(layer "In6.Cu")
		(net "P5E_CPU1_P2_RX_DP<0>")
	)
	(segment
		(start 113.767616 -284.293818)
		(end 113.806732 -284.270958)
		(width 0.1143)
		(layer "In6.Cu")
		(net "P5E_CPU1_P2_RX_DP<0>")
	)
	(segment
		(start 114.70767 -282.673806)
		(end 114.737134 -282.656534)
		(width 0.1143)
		(layer "In6.Cu")
		(net "P5E_CPU1_P2_RX_DP<0>")
	)
	(segment
		(start 113.740946 -299.997114)
		(end 112.95634 -296.053764)
		(width 0.14224)
		(layer "In6.Cu")
		(net "P5E_CPU1_P2_RX_DP<0>")
	)
	(segment
		(start 140.787374 -373.278146)
		(end 140.50772 -372.590314)
		(width 0.14224)
		(layer "In6.Cu")
		(net "P5E_CPU1_P2_RX_DP<0>")
	)
	(segment
		(start 148.176488 -385.460494)
		(end 148.176488 -385.046982)
		(width 0.14224)
		(layer "In6.Cu")
		(net "P5E_CPU1_P2_RX_DP<0>")
	)
	(segment
		(start 114.907314 -302.811434)
		(end 113.740946 -299.997114)
		(width 0.14224)
		(layer "In6.Cu")
		(net "P5E_CPU1_P2_RX_DP<0>")
	)
	(segment
		(start 134.696708 -347.096842)
		(end 130.364738 -325.315072)
		(width 0.14224)
		(layer "In6.Cu")
		(net "P5E_CPU1_P2_RX_DP<0>")
	)
	(segment
		(start 125.586744 -316.972188)
		(end 119.03329 -308.986682)
		(width 0.14224)
		(layer "In6.Cu")
		(net "P5E_CPU1_P2_RX_DP<0>")
	)
	(segment
		(start 114.20602 -283.5021)
		(end 114.23777 -283.483812)
		(width 0.1143)
		(layer "In6.Cu")
		(net "P5E_CPU1_P2_RX_DP<0>")
	)
	(segment
		(start 140.383006 -372.063264)
		(end 140.12545 -368.769138)
		(width 0.14224)
		(layer "In6.Cu")
		(net "P5E_CPU1_P2_RX_DP<0>")
	)
	(segment
		(start 147.860512 -384.731006)
		(end 147.86356 -384.3528)
		(width 0.14224)
		(layer "In6.Cu")
		(net "P5E_CPU1_P2_RX_DP<0>")
	)
	(segment
		(start 147.982178 -381.895096)
		(end 140.807694 -373.311674)
		(width 0.14224)
		(layer "In6.Cu")
		(net "P5E_CPU1_P2_RX_DP<0>")
	)
	(segment
		(start 147.86356 -384.3528)
		(end 148.16836 -384.048)
		(width 0.14224)
		(layer "In6.Cu")
		(net "P5E_CPU1_P2_RX_DP<0>")
	)
	(segment
		(start 115.066826 -282.18638)
		(end 115.364768 -282.18638)
		(width 0.1143)
		(layer "In6.Cu")
		(net "P5E_CPU1_P2_RX_DP<0>")
	)
	(segment
		(start 114.23777 -283.483812)
		(end 114.277648 -283.46019)
		(width 0.1143)
		(layer "In6.Cu")
		(net "P5E_CPU1_P2_RX_DP<0>")
	)
	(segment
		(start 119.03329 -308.986682)
		(end 114.907314 -302.811434)
		(width 0.14224)
		(layer "In6.Cu")
		(net "P5E_CPU1_P2_RX_DP<0>")
	)
	(segment
		(start 130.364738 -325.315072)
		(end 127.183388 -319.361566)
		(width 0.14224)
		(layer "In6.Cu")
		(net "P5E_CPU1_P2_RX_DP<0>")
	)
	(arc
		(start 114.050064 -283.806392)
		(mid 114.091319 -283.635421)
		(end 114.20602 -283.5021)
		(width 0.1143)
		(layer "In6.Cu")
		(net "P5E_CPU1_P2_RX_DP<0>")
	)
	(arc
		(start 114.84356 -282.565856)
		(mid 114.930782 -282.438378)
		(end 114.980212 -282.292044)
		(width 0.1143)
		(layer "In6.Cu")
		(net "P5E_CPU1_P2_RX_DP<0>")
	)
	(arc
		(start 114.980212 -282.292044)
		(mid 114.982235 -282.280634)
		(end 114.984022 -282.269184)
		(width 0.1143)
		(layer "In6.Cu")
		(net "P5E_CPU1_P2_RX_DP<0>")
	)
	(arc
		(start 140.50772 -372.590314)
		(mid 140.425022 -372.331603)
		(end 140.383006 -372.063264)
		(width 0.14224)
		(layer "In6.Cu")
		(net "P5E_CPU1_P2_RX_DP<0>")
	)
	(arc
		(start 113.806732 -284.270958)
		(mid 113.985545 -284.068608)
		(end 114.050064 -283.806392)
		(width 0.1143)
		(layer "In6.Cu")
		(net "P5E_CPU1_P2_RX_DP<0>")
	)
	(arc
		(start 148.16836 -382.408176)
		(mid 148.120377 -382.135267)
		(end 147.982178 -381.895096)
		(width 0.14224)
		(layer "In6.Cu")
		(net "P5E_CPU1_P2_RX_DP<0>")
	)
	(arc
		(start 140.807694 -373.311674)
		(mid 140.796224 -373.295703)
		(end 140.787374 -373.278146)
		(width 0.14224)
		(layer "In6.Cu")
		(net "P5E_CPU1_P2_RX_DP<0>")
	)
	(arc
		(start 113.691162 -284.352746)
		(mid 113.727477 -284.320802)
		(end 113.767616 -284.293818)
		(width 0.1143)
		(layer "In6.Cu")
		(net "P5E_CPU1_P2_RX_DP<0>")
	)
	(arc
		(start 114.277648 -283.46019)
		(mid 114.455684 -283.26044)
		(end 114.519964 -283.000704)
		(width 0.1143)
		(layer "In6.Cu")
		(net "P5E_CPU1_P2_RX_DP<0>")
	)
	(arc
		(start 114.746786 -282.650946)
		(mid 114.797598 -282.61116)
		(end 114.84356 -282.565856)
		(width 0.1143)
		(layer "In6.Cu")
		(net "P5E_CPU1_P2_RX_DP<0>")
	)
	(arc
		(start 114.519964 -282.917138)
		(mid 114.544161 -282.816841)
		(end 114.611404 -282.738576)
		(width 0.1143)
		(layer "In6.Cu")
		(net "P5E_CPU1_P2_RX_DP<0>")
	)
	(segment
		(start 121.94794 -281.110436)
		(end 122.414792 -281.376374)
		(width 0.12954)
		(layer "F.Cu")
		(net "P5E_CPU1_P2_RX_DN<9>")
	)
	(segment
		(start 157.698186 -385.31038)
		(end 158.218886 -385.31038)
		(width 0.127)
		(layer "F.Cu")
		(net "P5E_CPU1_P2_RX_DN<9>")
	)
	(segment
		(start 121.160286 -293.185342)
		(end 121.153428 -293.181278)
		(width 0.1143)
		(layer "In6.Cu")
		(net "P5E_CPU1_P2_RX_DN<9>")
	)
	(segment
		(start 146.073368 -349.905574)
		(end 146.02968 -349.82277)
		(width 0.14224)
		(layer "In6.Cu")
		(net "P5E_CPU1_P2_RX_DN<9>")
	)
	(segment
		(start 158.694374 -385.163822)
		(end 158.377382 -384.84683)
		(width 0.14224)
		(layer "In6.Cu")
		(net "P5E_CPU1_P2_RX_DN<9>")
	)
	(segment
		(start 121.217436 -294.837104)
		(end 121.169938 -294.810688)
		(width 0.1143)
		(layer "In6.Cu")
		(net "P5E_CPU1_P2_RX_DN<9>")
	)
	(segment
		(start 134.215886 -315.14415)
		(end 131.87553 -311.640982)
		(width 0.14224)
		(layer "In6.Cu")
		(net "P5E_CPU1_P2_RX_DN<9>")
	)
	(segment
		(start 158.5722 -385.405376)
		(end 158.572708 -385.404868)
		(width 0.14224)
		(layer "In6.Cu")
		(net "P5E_CPU1_P2_RX_DN<9>")
	)
	(segment
		(start 121.152666 -284.151832)
		(end 121.191782 -284.128972)
		(width 0.1143)
		(layer "In6.Cu")
		(net "P5E_CPU1_P2_RX_DN<9>")
	)
	(segment
		(start 121.152666 -293.87165)
		(end 121.203212 -293.842186)
		(width 0.1143)
		(layer "In6.Cu")
		(net "P5E_CPU1_P2_RX_DN<9>")
	)
	(segment
		(start 159.955484 -369.314222)
		(end 159.955484 -368.620548)
		(width 0.14224)
		(layer "In6.Cu")
		(net "P5E_CPU1_P2_RX_DN<9>")
	)
	(segment
		(start 121.152412 -294.800782)
		(end 121.152666 -294.800782)
		(width 0.1143)
		(layer "In6.Cu")
		(net "P5E_CPU1_P2_RX_DN<9>")
	)
	(segment
		(start 121.80443 -296.353738)
		(end 121.80443 -296.32529)
		(width 0.1143)
		(layer "In6.Cu")
		(net "P5E_CPU1_P2_RX_DN<9>")
	)
	(segment
		(start 121.669556 -283.314394)
		(end 121.670318 -283.313886)
		(width 0.1143)
		(layer "In6.Cu")
		(net "P5E_CPU1_P2_RX_DN<9>")
	)
	(segment
		(start 121.152666 -292.251638)
		(end 121.212356 -292.21684)
		(width 0.1143)
		(layer "In6.Cu")
		(net "P5E_CPU1_P2_RX_DN<9>")
	)
	(segment
		(start 121.213118 -292.216332)
		(end 121.213372 -292.216332)
		(width 0.1143)
		(layer "In6.Cu")
		(net "P5E_CPU1_P2_RX_DN<9>")
	)
	(segment
		(start 147.524978 -352.4123)
		(end 146.779234 -351.169732)
		(width 0.14224)
		(layer "In6.Cu")
		(net "P5E_CPU1_P2_RX_DN<9>")
	)
	(segment
		(start 122.60072 -281.699462)
		(end 122.601736 -281.698954)
		(width 0.1143)
		(layer "In6.Cu")
		(net "P5E_CPU1_P2_RX_DN<9>")
	)
	(segment
		(start 121.212356 -292.21684)
		(end 121.213118 -292.216332)
		(width 0.1143)
		(layer "In6.Cu")
		(net "P5E_CPU1_P2_RX_DN<9>")
	)
	(segment
		(start 148.309076 -353.629468)
		(end 147.524978 -352.4123)
		(width 0.14224)
		(layer "In6.Cu")
		(net "P5E_CPU1_P2_RX_DN<9>")
	)
	(segment
		(start 121.217944 -288.973514)
		(end 121.2215 -288.97072)
		(width 0.1143)
		(layer "In6.Cu")
		(net "P5E_CPU1_P2_RX_DN<9>")
	)
	(segment
		(start 122.608086 -281.695144)
		(end 122.60961 -281.694382)
		(width 0.1143)
		(layer "In6.Cu")
		(net "P5E_CPU1_P2_RX_DN<9>")
	)
	(segment
		(start 121.85015 -296.08653)
		(end 121.849642 -296.086022)
		(width 0.1143)
		(layer "In6.Cu")
		(net "P5E_CPU1_P2_RX_DN<9>")
	)
	(segment
		(start 158.705296 -380.644654)
		(end 158.711392 -380.218188)
		(width 0.14224)
		(layer "In6.Cu")
		(net "P5E_CPU1_P2_RX_DN<9>")
	)
	(segment
		(start 121.152158 -287.391856)
		(end 121.212864 -287.35655)
		(width 0.1143)
		(layer "In6.Cu")
		(net "P5E_CPU1_P2_RX_DN<9>")
	)
	(segment
		(start 121.176796 -293.19474)
		(end 121.160286 -293.185342)
		(width 0.1143)
		(layer "In6.Cu")
		(net "P5E_CPU1_P2_RX_DN<9>")
	)
	(segment
		(start 121.85015 -296.27957)
		(end 121.85015 -296.08653)
		(width 0.1143)
		(layer "In6.Cu")
		(net "P5E_CPU1_P2_RX_DN<9>")
	)
	(segment
		(start 121.186956 -289.960812)
		(end 121.186194 -289.960304)
		(width 0.1143)
		(layer "In6.Cu")
		(net "P5E_CPU1_P2_RX_DN<9>")
	)
	(segment
		(start 131.87553 -311.640982)
		(end 131.87426 -311.639204)
		(width 0.14224)
		(layer "In6.Cu")
		(net "P5E_CPU1_P2_RX_DN<9>")
	)
	(segment
		(start 146.02968 -349.82277)
		(end 144.803368 -347.67774)
		(width 0.14224)
		(layer "In6.Cu")
		(net "P5E_CPU1_P2_RX_DN<9>")
	)
	(segment
		(start 140.104114 -330.248514)
		(end 140.104368 -330.248514)
		(width 0.14224)
		(layer "In6.Cu")
		(net "P5E_CPU1_P2_RX_DN<9>")
	)
	(segment
		(start 158.382208 -384.234944)
		(end 158.686246 -383.930906)
		(width 0.14224)
		(layer "In6.Cu")
		(net "P5E_CPU1_P2_RX_DN<9>")
	)
	(segment
		(start 121.671588 -283.313124)
		(end 121.67362 -283.312108)
		(width 0.1143)
		(layer "In6.Cu")
		(net "P5E_CPU1_P2_RX_DN<9>")
	)
	(segment
		(start 158.218886 -385.31038)
		(end 158.5722 -385.405376)
		(width 0.14224)
		(layer "In6.Cu")
		(net "P5E_CPU1_P2_RX_DN<9>")
	)
	(segment
		(start 121.693432 -285.932118)
		(end 121.693178 -285.932372)
		(width 0.1143)
		(layer "In6.Cu")
		(net "P5E_CPU1_P2_RX_DN<9>")
	)
	(segment
		(start 158.721298 -379.516894)
		(end 158.727394 -379.090428)
		(width 0.14224)
		(layer "In6.Cu")
		(net "P5E_CPU1_P2_RX_DN<9>")
	)
	(segment
		(start 121.19737 -290.605464)
		(end 121.198132 -290.60521)
		(width 0.1143)
		(layer "In6.Cu")
		(net "P5E_CPU1_P2_RX_DN<9>")
	)
	(segment
		(start 143.33093 -343.990168)
		(end 143.109188 -343.357708)
		(width 0.14224)
		(layer "In6.Cu")
		(net "P5E_CPU1_P2_RX_DN<9>")
	)
	(segment
		(start 121.181114 -293.19728)
		(end 121.180098 -293.196772)
		(width 0.1143)
		(layer "In6.Cu")
		(net "P5E_CPU1_P2_RX_DN<9>")
	)
	(segment
		(start 159.953706 -371.064536)
		(end 159.955484 -369.314222)
		(width 0.14224)
		(layer "In6.Cu")
		(net "P5E_CPU1_P2_RX_DN<9>")
	)
	(segment
		(start 146.779234 -351.169732)
		(end 146.073368 -349.905574)
		(width 0.14224)
		(layer "In6.Cu")
		(net "P5E_CPU1_P2_RX_DN<9>")
	)
	(segment
		(start 121.670318 -283.313886)
		(end 121.671588 -283.313124)
		(width 0.1143)
		(layer "In6.Cu")
		(net "P5E_CPU1_P2_RX_DN<9>")
	)
	(segment
		(start 138.809476 -323.73824)
		(end 134.215886 -315.14415)
		(width 0.14224)
		(layer "In6.Cu")
		(net "P5E_CPU1_P2_RX_DN<9>")
	)
	(segment
		(start 121.668032 -283.315156)
		(end 121.669556 -283.314394)
		(width 0.1143)
		(layer "In6.Cu")
		(net "P5E_CPU1_P2_RX_DN<9>")
	)
	(segment
		(start 143.109188 -343.357708)
		(end 142.32128 -340.68766)
		(width 0.14224)
		(layer "In6.Cu")
		(net "P5E_CPU1_P2_RX_DN<9>")
	)
	(segment
		(start 121.80443 -296.32529)
		(end 121.85015 -296.27957)
		(width 0.1143)
		(layer "In6.Cu")
		(net "P5E_CPU1_P2_RX_DN<9>")
	)
	(segment
		(start 158.566358 -380.779782)
		(end 158.70555 -380.644654)
		(width 0.14224)
		(layer "In6.Cu")
		(net "P5E_CPU1_P2_RX_DN<9>")
	)
	(segment
		(start 122.603768 -281.697684)
		(end 122.608086 -281.695144)
		(width 0.1143)
		(layer "In6.Cu")
		(net "P5E_CPU1_P2_RX_DN<9>")
	)
	(segment
		(start 158.889446 -373.284496)
		(end 159.940752 -371.119654)
		(width 0.14224)
		(layer "In6.Cu")
		(net "P5E_CPU1_P2_RX_DN<9>")
	)
	(segment
		(start 121.184162 -293.199312)
		(end 121.181114 -293.19728)
		(width 0.1143)
		(layer "In6.Cu")
		(net "P5E_CPU1_P2_RX_DN<9>")
	)
	(segment
		(start 158.721552 -379.516894)
		(end 158.721298 -379.516894)
		(width 0.14224)
		(layer "In6.Cu")
		(net "P5E_CPU1_P2_RX_DN<9>")
	)
	(segment
		(start 150.867364 -357.4288)
		(end 148.309076 -353.629468)
		(width 0.14224)
		(layer "In6.Cu")
		(net "P5E_CPU1_P2_RX_DN<9>")
	)
	(segment
		(start 121.185178 -293.19982)
		(end 121.184162 -293.199312)
		(width 0.1143)
		(layer "In6.Cu")
		(net "P5E_CPU1_P2_RX_DN<9>")
	)
	(segment
		(start 122.56262 -281.721814)
		(end 122.599196 -281.700478)
		(width 0.1143)
		(layer "In6.Cu")
		(net "P5E_CPU1_P2_RX_DN<9>")
	)
	(segment
		(start 158.58236 -379.652022)
		(end 158.721552 -379.516894)
		(width 0.14224)
		(layer "In6.Cu")
		(net "P5E_CPU1_P2_RX_DN<9>")
	)
	(segment
		(start 158.598362 -378.524262)
		(end 158.737554 -378.389134)
		(width 0.14224)
		(layer "In6.Cu")
		(net "P5E_CPU1_P2_RX_DN<9>")
	)
	(segment
		(start 158.686246 -382.00076)
		(end 158.69539 -381.345948)
		(width 0.14224)
		(layer "In6.Cu")
		(net "P5E_CPU1_P2_RX_DN<9>")
	)
	(segment
		(start 121.67616 -283.310584)
		(end 121.67743 -283.309822)
		(width 0.1143)
		(layer "In6.Cu")
		(net "P5E_CPU1_P2_RX_DN<9>")
	)
	(segment
		(start 121.693178 -285.932372)
		(end 121.623328 -285.891732)
		(width 0.1143)
		(layer "In6.Cu")
		(net "P5E_CPU1_P2_RX_DN<9>")
	)
	(segment
		(start 121.18975 -290.610036)
		(end 121.19737 -290.605464)
		(width 0.1143)
		(layer "In6.Cu")
		(net "P5E_CPU1_P2_RX_DN<9>")
	)
	(segment
		(start 158.737554 -378.389134)
		(end 158.7373 -378.389134)
		(width 0.14224)
		(layer "In6.Cu")
		(net "P5E_CPU1_P2_RX_DN<9>")
	)
	(segment
		(start 144.178782 -346.19311)
		(end 143.33093 -343.990168)
		(width 0.14224)
		(layer "In6.Cu")
		(net "P5E_CPU1_P2_RX_DN<9>")
	)
	(segment
		(start 158.711392 -380.218188)
		(end 158.576264 -380.078996)
		(width 0.14224)
		(layer "In6.Cu")
		(net "P5E_CPU1_P2_RX_DN<9>")
	)
	(segment
		(start 159.880554 -368.410998)
		(end 150.867364 -357.4288)
		(width 0.14224)
		(layer "In6.Cu")
		(net "P5E_CPU1_P2_RX_DN<9>")
	)
	(segment
		(start 121.67362 -283.312108)
		(end 121.675398 -283.311092)
		(width 0.1143)
		(layer "In6.Cu")
		(net "P5E_CPU1_P2_RX_DN<9>")
	)
	(segment
		(start 121.198132 -289.967162)
		(end 121.19737 -289.966908)
		(width 0.1143)
		(layer "In6.Cu")
		(net "P5E_CPU1_P2_RX_DN<9>")
	)
	(segment
		(start 122.601736 -281.698954)
		(end 122.602498 -281.698446)
		(width 0.1143)
		(layer "In6.Cu")
		(net "P5E_CPU1_P2_RX_DN<9>")
	)
	(segment
		(start 128.727962 -307.805836)
		(end 128.728216 -307.805836)
		(width 0.14224)
		(layer "In6.Cu")
		(net "P5E_CPU1_P2_RX_DN<9>")
	)
	(segment
		(start 122.602498 -281.698446)
		(end 122.603768 -281.697684)
		(width 0.1143)
		(layer "In6.Cu")
		(net "P5E_CPU1_P2_RX_DN<9>")
	)
	(segment
		(start 121.177558 -293.195248)
		(end 121.176796 -293.19474)
		(width 0.1143)
		(layer "In6.Cu")
		(net "P5E_CPU1_P2_RX_DN<9>")
	)
	(segment
		(start 121.849642 -296.086022)
		(end 121.849642 -295.956228)
		(width 0.1143)
		(layer "In6.Cu")
		(net "P5E_CPU1_P2_RX_DN<9>")
	)
	(segment
		(start 121.186194 -289.960304)
		(end 121.153428 -289.941254)
		(width 0.1143)
		(layer "In6.Cu")
		(net "P5E_CPU1_P2_RX_DN<9>")
	)
	(segment
		(start 121.80443 -297.442128)
		(end 121.80443 -296.353738)
		(width 0.14224)
		(layer "In6.Cu")
		(net "P5E_CPU1_P2_RX_DN<9>")
	)
	(segment
		(start 121.623328 -285.891732)
		(end 121.623582 -285.891732)
		(width 0.1143)
		(layer "In6.Cu")
		(net "P5E_CPU1_P2_RX_DN<9>")
	)
	(segment
		(start 140.104368 -330.248514)
		(end 138.809476 -323.73824)
		(width 0.14224)
		(layer "In6.Cu")
		(net "P5E_CPU1_P2_RX_DN<9>")
	)
	(segment
		(start 122.549158 -299.435774)
		(end 121.87936 -297.818556)
		(width 0.14224)
		(layer "In6.Cu")
		(net "P5E_CPU1_P2_RX_DN<9>")
	)
	(segment
		(start 121.661682 -283.318966)
		(end 121.662444 -283.318458)
		(width 0.1143)
		(layer "In6.Cu")
		(net "P5E_CPU1_P2_RX_DN<9>")
	)
	(segment
		(start 122.712734 -281.376374)
		(end 122.414792 -281.376374)
		(width 0.1143)
		(layer "In6.Cu")
		(net "P5E_CPU1_P2_RX_DN<9>")
	)
	(segment
		(start 140.104368 -330.248768)
		(end 140.104114 -330.248768)
		(width 0.14224)
		(layer "In6.Cu")
		(net "P5E_CPU1_P2_RX_DN<9>")
	)
	(segment
		(start 122.09272 -282.53182)
		(end 122.162316 -282.49118)
		(width 0.1143)
		(layer "In6.Cu")
		(net "P5E_CPU1_P2_RX_DN<9>")
	)
	(segment
		(start 158.7373 -378.389134)
		(end 158.80461 -373.642128)
		(width 0.14224)
		(layer "In6.Cu")
		(net "P5E_CPU1_P2_RX_DN<9>")
	)
	(segment
		(start 140.104114 -330.248768)
		(end 140.104114 -330.248514)
		(width 0.14224)
		(layer "In6.Cu")
		(net "P5E_CPU1_P2_RX_DN<9>")
	)
	(segment
		(start 158.576264 -380.078996)
		(end 158.58236 -379.652022)
		(width 0.14224)
		(layer "In6.Cu")
		(net "P5E_CPU1_P2_RX_DN<9>")
	)
	(segment
		(start 128.728216 -307.805836)
		(end 125.573028 -303.961292)
		(width 0.14224)
		(layer "In6.Cu")
		(net "P5E_CPU1_P2_RX_DN<9>")
	)
	(segment
		(start 122.782584 -281.446224)
		(end 122.712734 -281.376374)
		(width 0.1143)
		(layer "In6.Cu")
		(net "P5E_CPU1_P2_RX_DN<9>")
	)
	(segment
		(start 122.613674 -281.692096)
		(end 122.633486 -281.680666)
		(width 0.1143)
		(layer "In6.Cu")
		(net "P5E_CPU1_P2_RX_DN<9>")
	)
	(segment
		(start 121.152666 -289.011614)
		(end 121.217944 -288.973514)
		(width 0.1143)
		(layer "In6.Cu")
		(net "P5E_CPU1_P2_RX_DN<9>")
	)
	(segment
		(start 121.220484 -288.360612)
		(end 121.152666 -288.320988)
		(width 0.1143)
		(layer "In6.Cu")
		(net "P5E_CPU1_P2_RX_DN<9>")
	)
	(segment
		(start 121.188988 -293.202106)
		(end 121.187464 -293.20109)
		(width 0.1143)
		(layer "In6.Cu")
		(net "P5E_CPU1_P2_RX_DN<9>")
	)
	(segment
		(start 125.573028 -303.961292)
		(end 122.549158 -299.435774)
		(width 0.14224)
		(layer "In6.Cu")
		(net "P5E_CPU1_P2_RX_DN<9>")
	)
	(segment
		(start 121.15546 -285.082996)
		(end 121.152666 -285.080964)
		(width 0.1143)
		(layer "In6.Cu")
		(net "P5E_CPU1_P2_RX_DN<9>")
	)
	(segment
		(start 121.62536 -286.579818)
		(end 121.628154 -286.578294)
		(width 0.1143)
		(layer "In6.Cu")
		(net "P5E_CPU1_P2_RX_DN<9>")
	)
	(segment
		(start 122.610372 -281.693874)
		(end 122.611642 -281.693112)
		(width 0.1143)
		(layer "In6.Cu")
		(net "P5E_CPU1_P2_RX_DN<9>")
	)
	(segment
		(start 121.628154 -286.578294)
		(end 121.69521 -286.539178)
		(width 0.1143)
		(layer "In6.Cu")
		(net "P5E_CPU1_P2_RX_DN<9>")
	)
	(segment
		(start 158.70555 -380.644654)
		(end 158.705296 -380.644654)
		(width 0.14224)
		(layer "In6.Cu")
		(net "P5E_CPU1_P2_RX_DN<9>")
	)
	(segment
		(start 121.213118 -291.596064)
		(end 121.153428 -291.561266)
		(width 0.1143)
		(layer "In6.Cu")
		(net "P5E_CPU1_P2_RX_DN<9>")
	)
	(segment
		(start 131.87426 -311.639204)
		(end 128.727962 -307.805836)
		(width 0.14224)
		(layer "In6.Cu")
		(net "P5E_CPU1_P2_RX_DN<9>")
	)
	(segment
		(start 121.379488 -295.149778)
		(end 121.379488 -295.145968)
		(width 0.1143)
		(layer "In6.Cu")
		(net "P5E_CPU1_P2_RX_DN<9>")
	)
	(segment
		(start 121.67743 -283.309822)
		(end 121.693432 -283.300678)
		(width 0.1143)
		(layer "In6.Cu")
		(net "P5E_CPU1_P2_RX_DN<9>")
	)
	(segment
		(start 142.32128 -340.68766)
		(end 142.272512 -340.507574)
		(width 0.14224)
		(layer "In6.Cu")
		(net "P5E_CPU1_P2_RX_DN<9>")
	)
	(segment
		(start 142.272512 -340.507574)
		(end 141.532864 -337.43011)
		(width 0.14224)
		(layer "In6.Cu")
		(net "P5E_CPU1_P2_RX_DN<9>")
	)
	(segment
		(start 158.694374 -385.334764)
		(end 158.694374 -385.163822)
		(width 0.14224)
		(layer "In6.Cu")
		(net "P5E_CPU1_P2_RX_DN<9>")
	)
	(segment
		(start 122.611642 -281.693112)
		(end 122.613674 -281.692096)
		(width 0.1143)
		(layer "In6.Cu")
		(net "P5E_CPU1_P2_RX_DN<9>")
	)
	(segment
		(start 121.203212 -293.210234)
		(end 121.188988 -293.202106)
		(width 0.1143)
		(layer "In6.Cu")
		(net "P5E_CPU1_P2_RX_DN<9>")
	)
	(segment
		(start 158.560262 -381.206756)
		(end 158.566358 -380.779782)
		(width 0.14224)
		(layer "In6.Cu")
		(net "P5E_CPU1_P2_RX_DN<9>")
	)
	(segment
		(start 121.693432 -295.651936)
		(end 121.622312 -295.610534)
		(width 0.1143)
		(layer "In6.Cu")
		(net "P5E_CPU1_P2_RX_DN<9>")
	)
	(segment
		(start 121.169176 -294.81018)
		(end 121.158508 -294.804846)
		(width 0.1143)
		(layer "In6.Cu")
		(net "P5E_CPU1_P2_RX_DN<9>")
	)
	(segment
		(start 121.188988 -290.610544)
		(end 121.18975 -290.610036)
		(width 0.1143)
		(layer "In6.Cu")
		(net "P5E_CPU1_P2_RX_DN<9>")
	)
	(segment
		(start 144.803368 -347.67774)
		(end 144.178782 -346.19311)
		(width 0.14224)
		(layer "In6.Cu")
		(net "P5E_CPU1_P2_RX_DN<9>")
	)
	(segment
		(start 122.60961 -281.694382)
		(end 122.610372 -281.693874)
		(width 0.1143)
		(layer "In6.Cu")
		(net "P5E_CPU1_P2_RX_DN<9>")
	)
	(segment
		(start 121.666 -283.316426)
		(end 121.668032 -283.315156)
		(width 0.1143)
		(layer "In6.Cu")
		(net "P5E_CPU1_P2_RX_DN<9>")
	)
	(segment
		(start 122.599196 -281.700478)
		(end 122.60072 -281.699462)
		(width 0.1143)
		(layer "In6.Cu")
		(net "P5E_CPU1_P2_RX_DN<9>")
	)
	(segment
		(start 158.686246 -383.930906)
		(end 158.686246 -382.00076)
		(width 0.14224)
		(layer "In6.Cu")
		(net "P5E_CPU1_P2_RX_DN<9>")
	)
	(segment
		(start 141.532864 -337.43011)
		(end 140.104368 -330.248768)
		(width 0.14224)
		(layer "In6.Cu")
		(net "P5E_CPU1_P2_RX_DN<9>")
	)
	(segment
		(start 121.663714 -283.317696)
		(end 121.666 -283.316426)
		(width 0.1143)
		(layer "In6.Cu")
		(net "P5E_CPU1_P2_RX_DN<9>")
	)
	(segment
		(start 158.69539 -381.345948)
		(end 158.560262 -381.206756)
		(width 0.14224)
		(layer "In6.Cu")
		(net "P5E_CPU1_P2_RX_DN<9>")
	)
	(segment
		(start 121.16054 -285.086044)
		(end 121.15546 -285.082996)
		(width 0.1143)
		(layer "In6.Cu")
		(net "P5E_CPU1_P2_RX_DN<9>")
	)
	(segment
		(start 158.727394 -379.090428)
		(end 158.592266 -378.951236)
		(width 0.14224)
		(layer "In6.Cu")
		(net "P5E_CPU1_P2_RX_DN<9>")
	)
	(segment
		(start 121.214388 -285.117032)
		(end 121.16054 -285.086044)
		(width 0.1143)
		(layer "In6.Cu")
		(net "P5E_CPU1_P2_RX_DN<9>")
	)
	(segment
		(start 121.213626 -291.596064)
		(end 121.213118 -291.596064)
		(width 0.1143)
		(layer "In6.Cu")
		(net "P5E_CPU1_P2_RX_DN<9>")
	)
	(segment
		(start 121.62536 -283.340048)
		(end 121.661682 -283.318966)
		(width 0.1143)
		(layer "In6.Cu")
		(net "P5E_CPU1_P2_RX_DN<9>")
	)
	(segment
		(start 121.19737 -289.966908)
		(end 121.186956 -289.960812)
		(width 0.1143)
		(layer "In6.Cu")
		(net "P5E_CPU1_P2_RX_DN<9>")
	)
	(segment
		(start 121.191782 -284.128972)
		(end 121.223532 -284.110684)
		(width 0.1143)
		(layer "In6.Cu")
		(net "P5E_CPU1_P2_RX_DN<9>")
	)
	(segment
		(start 121.675398 -283.311092)
		(end 121.67616 -283.310584)
		(width 0.1143)
		(layer "In6.Cu")
		(net "P5E_CPU1_P2_RX_DN<9>")
	)
	(segment
		(start 121.180098 -293.196772)
		(end 121.177558 -293.195248)
		(width 0.1143)
		(layer "In6.Cu")
		(net "P5E_CPU1_P2_RX_DN<9>")
	)
	(segment
		(start 121.662444 -283.318458)
		(end 121.663714 -283.317696)
		(width 0.1143)
		(layer "In6.Cu")
		(net "P5E_CPU1_P2_RX_DN<9>")
	)
	(segment
		(start 158.572708 -385.404868)
		(end 158.694374 -385.334764)
		(width 0.14224)
		(layer "In6.Cu")
		(net "P5E_CPU1_P2_RX_DN<9>")
	)
	(segment
		(start 158.377382 -384.84683)
		(end 158.382208 -384.234944)
		(width 0.14224)
		(layer "In6.Cu")
		(net "P5E_CPU1_P2_RX_DN<9>")
	)
	(segment
		(start 121.169938 -294.810688)
		(end 121.169176 -294.81018)
		(width 0.1143)
		(layer "In6.Cu")
		(net "P5E_CPU1_P2_RX_DN<9>")
	)
	(segment
		(start 121.152666 -290.631626)
		(end 121.188988 -290.610544)
		(width 0.1143)
		(layer "In6.Cu")
		(net "P5E_CPU1_P2_RX_DN<9>")
	)
	(segment
		(start 158.592266 -378.951236)
		(end 158.598362 -378.524262)
		(width 0.14224)
		(layer "In6.Cu")
		(net "P5E_CPU1_P2_RX_DN<9>")
	)
	(segment
		(start 121.187464 -293.20109)
		(end 121.185178 -293.19982)
		(width 0.1143)
		(layer "In6.Cu")
		(net "P5E_CPU1_P2_RX_DN<9>")
	)
	(arc
		(start 122.633486 -281.680666)
		(mid 122.730621 -281.577797)
		(end 122.782584 -281.446224)
		(width 0.1143)
		(layer "In6.Cu")
		(net "P5E_CPU1_P2_RX_DN<9>")
	)
	(arc
		(start 121.377456 -287.05556)
		(mid 121.378766 -287.043647)
		(end 121.379488 -287.031684)
		(width 0.1143)
		(layer "In6.Cu")
		(net "P5E_CPU1_P2_RX_DN<9>")
	)
	(arc
		(start 121.849642 -295.956228)
		(mid 121.826814 -295.827747)
		(end 121.76125 -295.714928)
		(width 0.1143)
		(layer "In6.Cu")
		(net "P5E_CPU1_P2_RX_DN<9>")
	)
	(arc
		(start 121.152666 -293.18077)
		(mid 120.909339 -292.716204)
		(end 121.152666 -292.251638)
		(width 0.1143)
		(layer "In6.Cu")
		(net "P5E_CPU1_P2_RX_DN<9>")
	)
	(arc
		(start 121.69521 -286.539178)
		(mid 121.808617 -286.406289)
		(end 121.849388 -286.23641)
		(width 0.1143)
		(layer "In6.Cu")
		(net "P5E_CPU1_P2_RX_DN<9>")
	)
	(arc
		(start 121.153428 -291.561266)
		(mid 121.153047 -291.561012)
		(end 121.152666 -291.560758)
		(width 0.1143)
		(layer "In6.Cu")
		(net "P5E_CPU1_P2_RX_DN<9>")
	)
	(arc
		(start 121.622312 -295.610534)
		(mid 121.443907 -295.410192)
		(end 121.379488 -295.149778)
		(width 0.1143)
		(layer "In6.Cu")
		(net "P5E_CPU1_P2_RX_DN<9>")
	)
	(arc
		(start 158.80461 -373.642128)
		(mid 158.827398 -373.458658)
		(end 158.889446 -373.284496)
		(width 0.14224)
		(layer "In6.Cu")
		(net "P5E_CPU1_P2_RX_DN<9>")
	)
	(arc
		(start 121.379488 -287.031684)
		(mid 121.444195 -286.783302)
		(end 121.612152 -286.589216)
		(width 0.1143)
		(layer "In6.Cu")
		(net "P5E_CPU1_P2_RX_DN<9>")
	)
	(arc
		(start 121.152666 -294.800782)
		(mid 120.909339 -294.336216)
		(end 121.152666 -293.87165)
		(width 0.1143)
		(layer "In6.Cu")
		(net "P5E_CPU1_P2_RX_DN<9>")
	)
	(arc
		(start 120.909334 -287.856422)
		(mid 120.973713 -287.594338)
		(end 121.152158 -287.391856)
		(width 0.1143)
		(layer "In6.Cu")
		(net "P5E_CPU1_P2_RX_DN<9>")
	)
	(arc
		(start 121.379234 -285.44647)
		(mid 121.378661 -285.431581)
		(end 121.377202 -285.416752)
		(width 0.1143)
		(layer "In6.Cu")
		(net "P5E_CPU1_P2_RX_DN<9>")
	)
	(arc
		(start 121.153428 -289.941254)
		(mid 121.153047 -289.941)
		(end 121.152666 -289.940746)
		(width 0.1143)
		(layer "In6.Cu")
		(net "P5E_CPU1_P2_RX_DN<9>")
	)
	(arc
		(start 121.612152 -286.589216)
		(mid 121.618722 -286.584469)
		(end 121.62536 -286.579818)
		(width 0.1143)
		(layer "In6.Cu")
		(net "P5E_CPU1_P2_RX_DN<9>")
	)
	(arc
		(start 121.153428 -293.181278)
		(mid 121.153047 -293.181024)
		(end 121.152666 -293.18077)
		(width 0.1143)
		(layer "In6.Cu")
		(net "P5E_CPU1_P2_RX_DN<9>")
	)
	(arc
		(start 121.223532 -284.110684)
		(mid 121.335034 -283.983931)
		(end 121.379742 -283.821124)
		(width 0.1143)
		(layer "In6.Cu")
		(net "P5E_CPU1_P2_RX_DN<9>")
	)
	(arc
		(start 121.203212 -293.842186)
		(mid 121.378162 -293.52621)
		(end 121.203212 -293.210234)
		(width 0.1143)
		(layer "In6.Cu")
		(net "P5E_CPU1_P2_RX_DN<9>")
	)
	(arc
		(start 121.478548 -283.508704)
		(mid 121.545042 -283.418357)
		(end 121.62536 -283.340048)
		(width 0.1143)
		(layer "In6.Cu")
		(net "P5E_CPU1_P2_RX_DN<9>")
	)
	(arc
		(start 121.213372 -292.216332)
		(mid 121.391914 -291.906308)
		(end 121.213626 -291.596064)
		(width 0.1143)
		(layer "In6.Cu")
		(net "P5E_CPU1_P2_RX_DN<9>")
	)
	(arc
		(start 122.319288 -282.18638)
		(mid 122.383803 -281.924161)
		(end 122.56262 -281.721814)
		(width 0.1143)
		(layer "In6.Cu")
		(net "P5E_CPU1_P2_RX_DN<9>")
	)
	(arc
		(start 121.623582 -285.891732)
		(mid 121.448646 -285.698058)
		(end 121.379234 -285.44647)
		(width 0.1143)
		(layer "In6.Cu")
		(net "P5E_CPU1_P2_RX_DN<9>")
	)
	(arc
		(start 121.152666 -291.560758)
		(mid 120.909339 -291.096192)
		(end 121.152666 -290.631626)
		(width 0.1143)
		(layer "In6.Cu")
		(net "P5E_CPU1_P2_RX_DN<9>")
	)
	(arc
		(start 121.849388 -282.996386)
		(mid 121.913903 -282.734167)
		(end 122.09272 -282.53182)
		(width 0.1143)
		(layer "In6.Cu")
		(net "P5E_CPU1_P2_RX_DN<9>")
	)
	(arc
		(start 121.76125 -295.714928)
		(mid 121.729291 -295.681333)
		(end 121.693432 -295.651936)
		(width 0.1143)
		(layer "In6.Cu")
		(net "P5E_CPU1_P2_RX_DN<9>")
	)
	(arc
		(start 159.955484 -368.620548)
		(mid 159.936199 -368.509267)
		(end 159.880554 -368.410998)
		(width 0.14224)
		(layer "In6.Cu")
		(net "P5E_CPU1_P2_RX_DN<9>")
	)
	(arc
		(start 122.162316 -282.49118)
		(mid 122.277743 -282.357804)
		(end 122.319288 -282.18638)
		(width 0.1143)
		(layer "In6.Cu")
		(net "P5E_CPU1_P2_RX_DN<9>")
	)
	(arc
		(start 121.198132 -290.60521)
		(mid 121.378834 -290.286186)
		(end 121.198132 -289.967162)
		(width 0.1143)
		(layer "In6.Cu")
		(net "P5E_CPU1_P2_RX_DN<9>")
	)
	(arc
		(start 121.87936 -297.818556)
		(mid 121.823367 -297.63403)
		(end 121.80443 -297.442128)
		(width 0.14224)
		(layer "In6.Cu")
		(net "P5E_CPU1_P2_RX_DN<9>")
	)
	(arc
		(start 121.152666 -285.080964)
		(mid 120.909339 -284.616398)
		(end 121.152666 -284.151832)
		(width 0.1143)
		(layer "In6.Cu")
		(net "P5E_CPU1_P2_RX_DN<9>")
	)
	(arc
		(start 121.212864 -287.35655)
		(mid 121.32233 -287.22091)
		(end 121.377456 -287.05556)
		(width 0.1143)
		(layer "In6.Cu")
		(net "P5E_CPU1_P2_RX_DN<9>")
	)
	(arc
		(start 121.379742 -283.821124)
		(mid 121.380965 -283.794519)
		(end 121.383806 -283.768038)
		(width 0.1143)
		(layer "In6.Cu")
		(net "P5E_CPU1_P2_RX_DN<9>")
	)
	(arc
		(start 159.940752 -371.119654)
		(mid 159.950339 -371.092826)
		(end 159.953706 -371.064536)
		(width 0.14224)
		(layer "In6.Cu")
		(net "P5E_CPU1_P2_RX_DN<9>")
	)
	(arc
		(start 121.849388 -286.23641)
		(mid 121.808133 -286.065439)
		(end 121.693432 -285.932118)
		(width 0.1143)
		(layer "In6.Cu")
		(net "P5E_CPU1_P2_RX_DN<9>")
	)
	(arc
		(start 121.152666 -289.940746)
		(mid 120.909339 -289.47618)
		(end 121.152666 -289.011614)
		(width 0.1143)
		(layer "In6.Cu")
		(net "P5E_CPU1_P2_RX_DN<9>")
	)
	(arc
		(start 121.158508 -294.804846)
		(mid 121.155454 -294.802823)
		(end 121.152412 -294.800782)
		(width 0.1143)
		(layer "In6.Cu")
		(net "P5E_CPU1_P2_RX_DN<9>")
	)
	(arc
		(start 121.152666 -288.320988)
		(mid 120.973853 -288.118638)
		(end 120.909334 -287.856422)
		(width 0.1143)
		(layer "In6.Cu")
		(net "P5E_CPU1_P2_RX_DN<9>")
	)
	(arc
		(start 121.377202 -285.416752)
		(mid 121.322519 -285.252375)
		(end 121.214388 -285.117032)
		(width 0.1143)
		(layer "In6.Cu")
		(net "P5E_CPU1_P2_RX_DN<9>")
	)
	(arc
		(start 121.383806 -283.768038)
		(mid 121.41802 -283.633562)
		(end 121.478548 -283.508704)
		(width 0.1143)
		(layer "In6.Cu")
		(net "P5E_CPU1_P2_RX_DN<9>")
	)
	(arc
		(start 121.693432 -283.300678)
		(mid 121.808108 -283.167344)
		(end 121.849388 -282.996386)
		(width 0.1143)
		(layer "In6.Cu")
		(net "P5E_CPU1_P2_RX_DN<9>")
	)
	(arc
		(start 121.2215 -288.97072)
		(mid 121.366754 -288.66546)
		(end 121.220484 -288.360612)
		(width 0.1143)
		(layer "In6.Cu")
		(net "P5E_CPU1_P2_RX_DN<9>")
	)
	(arc
		(start 121.379488 -295.145968)
		(mid 121.333735 -294.973026)
		(end 121.217436 -294.837104)
		(width 0.1143)
		(layer "In6.Cu")
		(net "P5E_CPU1_P2_RX_DN<9>")
	)
	(segment
		(start 156.49829 -385.31038)
		(end 157.01899 -385.31038)
		(width 0.127)
		(layer "F.Cu")
		(net "P5E_CPU1_P2_RX_DN<8>")
	)
	(segment
		(start 119.127778 -284.35046)
		(end 119.59463 -284.616398)
		(width 0.12954)
		(layer "F.Cu")
		(net "P5E_CPU1_P2_RX_DN<8>")
	)
	(segment
		(start 119.975376 -284.699202)
		(end 119.892572 -284.616398)
		(width 0.1143)
		(layer "In6.Cu")
		(net "P5E_CPU1_P2_RX_DN<8>")
	)
	(segment
		(start 120.909588 -296.086022)
		(end 120.909588 -295.956228)
		(width 0.1143)
		(layer "In6.Cu")
		(net "P5E_CPU1_P2_RX_DN<8>")
	)
	(segment
		(start 133.378448 -315.572648)
		(end 131.182872 -312.284618)
		(width 0.14224)
		(layer "In6.Cu")
		(net "P5E_CPU1_P2_RX_DN<8>")
	)
	(segment
		(start 157.494478 -385.334764)
		(end 157.494478 -385.163822)
		(width 0.14224)
		(layer "In6.Cu")
		(net "P5E_CPU1_P2_RX_DN<8>")
	)
	(segment
		(start 120.752362 -295.651428)
		(end 120.682766 -295.610788)
		(width 0.1143)
		(layer "In6.Cu")
		(net "P5E_CPU1_P2_RX_DN<8>")
	)
	(segment
		(start 120.751854 -286.541464)
		(end 120.753632 -286.540448)
		(width 0.1143)
		(layer "In6.Cu")
		(net "P5E_CPU1_P2_RX_DN<8>")
	)
	(segment
		(start 157.766512 -373.71401)
		(end 158.298896 -371.660166)
		(width 0.14224)
		(layer "In6.Cu")
		(net "P5E_CPU1_P2_RX_DN<8>")
	)
	(segment
		(start 120.866408 -296.32529)
		(end 120.912128 -296.27957)
		(width 0.1143)
		(layer "In6.Cu")
		(net "P5E_CPU1_P2_RX_DN<8>")
	)
	(segment
		(start 146.625564 -352.843846)
		(end 145.218404 -350.322642)
		(width 0.14224)
		(layer "In6.Cu")
		(net "P5E_CPU1_P2_RX_DN<8>")
	)
	(segment
		(start 120.212612 -290.631626)
		(end 120.282208 -290.590986)
		(width 0.1143)
		(layer "In6.Cu")
		(net "P5E_CPU1_P2_RX_DN<8>")
	)
	(segment
		(start 157.48635 -380.316232)
		(end 157.504638 -379.88494)
		(width 0.14224)
		(layer "In6.Cu")
		(net "P5E_CPU1_P2_RX_DN<8>")
	)
	(segment
		(start 120.25884 -285.107888)
		(end 120.2563 -285.106364)
		(width 0.1143)
		(layer "In6.Cu")
		(net "P5E_CPU1_P2_RX_DN<8>")
	)
	(segment
		(start 157.605984 -377.49099)
		(end 157.606238 -377.49099)
		(width 0.14224)
		(layer "In6.Cu")
		(net "P5E_CPU1_P2_RX_DN<8>")
	)
	(segment
		(start 120.28424 -288.362644)
		(end 120.212612 -288.320988)
		(width 0.1143)
		(layer "In6.Cu")
		(net "P5E_CPU1_P2_RX_DN<8>")
	)
	(segment
		(start 141.391894 -340.934548)
		(end 140.80109 -338.614258)
		(width 0.14224)
		(layer "In6.Cu")
		(net "P5E_CPU1_P2_RX_DN<8>")
	)
	(segment
		(start 157.47492 -377.347988)
		(end 157.492954 -376.921522)
		(width 0.14224)
		(layer "In6.Cu")
		(net "P5E_CPU1_P2_RX_DN<8>")
	)
	(segment
		(start 120.682766 -286.581596)
		(end 120.751854 -286.541464)
		(width 0.1143)
		(layer "In6.Cu")
		(net "P5E_CPU1_P2_RX_DN<8>")
	)
	(segment
		(start 157.177486 -384.84683)
		(end 157.182312 -384.234944)
		(width 0.14224)
		(layer "In6.Cu")
		(net "P5E_CPU1_P2_RX_DN<8>")
	)
	(segment
		(start 120.282208 -289.981386)
		(end 120.212612 -289.940746)
		(width 0.1143)
		(layer "In6.Cu")
		(net "P5E_CPU1_P2_RX_DN<8>")
	)
	(segment
		(start 120.250712 -285.103316)
		(end 120.249188 -285.1023)
		(width 0.1143)
		(layer "In6.Cu")
		(net "P5E_CPU1_P2_RX_DN<8>")
	)
	(segment
		(start 157.165294 -370.249196)
		(end 156.966158 -370.13134)
		(width 0.14224)
		(layer "In6.Cu")
		(net "P5E_CPU1_P2_RX_DN<8>")
	)
	(segment
		(start 120.25757 -287.36544)
		(end 120.283478 -287.350454)
		(width 0.1143)
		(layer "In6.Cu")
		(net "P5E_CPU1_P2_RX_DN<8>")
	)
	(segment
		(start 120.866408 -296.353738)
		(end 120.866408 -296.32529)
		(width 0.1143)
		(layer "In6.Cu")
		(net "P5E_CPU1_P2_RX_DN<8>")
	)
	(segment
		(start 157.63621 -376.790204)
		(end 157.635702 -376.78995)
		(width 0.14224)
		(layer "In6.Cu")
		(net "P5E_CPU1_P2_RX_DN<8>")
	)
	(segment
		(start 120.251728 -285.103824)
		(end 120.250712 -285.103316)
		(width 0.1143)
		(layer "In6.Cu")
		(net "P5E_CPU1_P2_RX_DN<8>")
	)
	(segment
		(start 157.48635 -383.93116)
		(end 157.48635 -380.316232)
		(width 0.14224)
		(layer "In6.Cu")
		(net "P5E_CPU1_P2_RX_DN<8>")
	)
	(segment
		(start 143.407892 -347.11894)
		(end 141.954758 -342.96858)
		(width 0.14224)
		(layer "In6.Cu")
		(net "P5E_CPU1_P2_RX_DN<8>")
	)
	(segment
		(start 120.212612 -292.251638)
		(end 120.282208 -292.210998)
		(width 0.1143)
		(layer "In6.Cu")
		(net "P5E_CPU1_P2_RX_DN<8>")
	)
	(segment
		(start 157.182312 -384.234944)
		(end 157.48635 -383.93116)
		(width 0.14224)
		(layer "In6.Cu")
		(net "P5E_CPU1_P2_RX_DN<8>")
	)
	(segment
		(start 157.492954 -376.921522)
		(end 157.63621 -376.790204)
		(width 0.14224)
		(layer "In6.Cu")
		(net "P5E_CPU1_P2_RX_DN<8>")
	)
	(segment
		(start 157.37332 -379.741938)
		(end 157.391354 -379.315472)
		(width 0.14224)
		(layer "In6.Cu")
		(net "P5E_CPU1_P2_RX_DN<8>")
	)
	(segment
		(start 156.548074 -369.416838)
		(end 156.548074 -367.853214)
		(width 0.14224)
		(layer "In6.Cu")
		(net "P5E_CPU1_P2_RX_DN<8>")
	)
	(segment
		(start 120.912128 -296.27957)
		(end 120.912128 -296.088562)
		(width 0.1143)
		(layer "In6.Cu")
		(net "P5E_CPU1_P2_RX_DN<8>")
	)
	(segment
		(start 120.282208 -291.601398)
		(end 120.212612 -291.560758)
		(width 0.1143)
		(layer "In6.Cu")
		(net "P5E_CPU1_P2_RX_DN<8>")
	)
	(segment
		(start 120.212612 -293.87165)
		(end 120.282208 -293.83101)
		(width 0.1143)
		(layer "In6.Cu")
		(net "P5E_CPU1_P2_RX_DN<8>")
	)
	(segment
		(start 157.534356 -379.184154)
		(end 157.55239 -378.757942)
		(width 0.14224)
		(layer "In6.Cu")
		(net "P5E_CPU1_P2_RX_DN<8>")
	)
	(segment
		(start 120.912128 -296.088562)
		(end 120.909588 -296.086022)
		(width 0.1143)
		(layer "In6.Cu")
		(net "P5E_CPU1_P2_RX_DN<8>")
	)
	(segment
		(start 120.2563 -285.106364)
		(end 120.25376 -285.105094)
		(width 0.1143)
		(layer "In6.Cu")
		(net "P5E_CPU1_P2_RX_DN<8>")
	)
	(segment
		(start 131.182872 -312.284618)
		(end 124.850144 -304.568352)
		(width 0.14224)
		(layer "In6.Cu")
		(net "P5E_CPU1_P2_RX_DN<8>")
	)
	(segment
		(start 137.899902 -324.030594)
		(end 133.378448 -315.572648)
		(width 0.14224)
		(layer "In6.Cu")
		(net "P5E_CPU1_P2_RX_DN<8>")
	)
	(segment
		(start 120.753632 -286.540448)
		(end 120.754394 -286.53994)
		(width 0.1143)
		(layer "In6.Cu")
		(net "P5E_CPU1_P2_RX_DN<8>")
	)
	(segment
		(start 141.954758 -342.96858)
		(end 141.391894 -340.934548)
		(width 0.14224)
		(layer "In6.Cu")
		(net "P5E_CPU1_P2_RX_DN<8>")
	)
	(segment
		(start 157.372304 -385.405376)
		(end 157.372812 -385.404868)
		(width 0.14224)
		(layer "In6.Cu")
		(net "P5E_CPU1_P2_RX_DN<8>")
	)
	(segment
		(start 119.892572 -284.616398)
		(end 119.59463 -284.616398)
		(width 0.1143)
		(layer "In6.Cu")
		(net "P5E_CPU1_P2_RX_DN<8>")
	)
	(segment
		(start 157.635702 -376.78995)
		(end 157.766512 -373.71401)
		(width 0.14224)
		(layer "In6.Cu")
		(net "P5E_CPU1_P2_RX_DN<8>")
	)
	(segment
		(start 157.494478 -385.163822)
		(end 157.177486 -384.84683)
		(width 0.14224)
		(layer "In6.Cu")
		(net "P5E_CPU1_P2_RX_DN<8>")
	)
	(segment
		(start 157.582362 -378.057156)
		(end 157.581854 -378.056902)
		(width 0.14224)
		(layer "In6.Cu")
		(net "P5E_CPU1_P2_RX_DN<8>")
	)
	(segment
		(start 120.212612 -289.011614)
		(end 120.282208 -288.970974)
		(width 0.1143)
		(layer "In6.Cu")
		(net "P5E_CPU1_P2_RX_DN<8>")
	)
	(segment
		(start 148.058378 -355.109018)
		(end 146.625564 -352.843846)
		(width 0.14224)
		(layer "In6.Cu")
		(net "P5E_CPU1_P2_RX_DN<8>")
	)
	(segment
		(start 157.01899 -385.31038)
		(end 157.372304 -385.405376)
		(width 0.14224)
		(layer "In6.Cu")
		(net "P5E_CPU1_P2_RX_DN<8>")
	)
	(segment
		(start 120.248172 -287.370774)
		(end 120.25757 -287.36544)
		(width 0.1143)
		(layer "In6.Cu")
		(net "P5E_CPU1_P2_RX_DN<8>")
	)
	(segment
		(start 157.606238 -377.49099)
		(end 157.47492 -377.347988)
		(width 0.14224)
		(layer "In6.Cu")
		(net "P5E_CPU1_P2_RX_DN<8>")
	)
	(segment
		(start 120.283478 -285.122112)
		(end 120.25884 -285.107888)
		(width 0.1143)
		(layer "In6.Cu")
		(net "P5E_CPU1_P2_RX_DN<8>")
	)
	(segment
		(start 157.581854 -378.056902)
		(end 157.605984 -377.49099)
		(width 0.14224)
		(layer "In6.Cu")
		(net "P5E_CPU1_P2_RX_DN<8>")
	)
	(segment
		(start 124.850144 -304.568352)
		(end 121.678192 -299.821346)
		(width 0.14224)
		(layer "In6.Cu")
		(net "P5E_CPU1_P2_RX_DN<8>")
	)
	(segment
		(start 120.25249 -285.104332)
		(end 120.251728 -285.103824)
		(width 0.1143)
		(layer "In6.Cu")
		(net "P5E_CPU1_P2_RX_DN<8>")
	)
	(segment
		(start 120.282208 -294.841422)
		(end 120.212612 -294.800782)
		(width 0.1143)
		(layer "In6.Cu")
		(net "P5E_CPU1_P2_RX_DN<8>")
	)
	(segment
		(start 157.461458 -370.384832)
		(end 157.314138 -370.323872)
		(width 0.14224)
		(layer "In6.Cu")
		(net "P5E_CPU1_P2_RX_DN<8>")
	)
	(segment
		(start 120.752362 -285.93161)
		(end 120.682766 -285.89097)
		(width 0.1143)
		(layer "In6.Cu")
		(net "P5E_CPU1_P2_RX_DN<8>")
	)
	(segment
		(start 120.215152 -287.390078)
		(end 120.248172 -287.370774)
		(width 0.1143)
		(layer "In6.Cu")
		(net "P5E_CPU1_P2_RX_DN<8>")
	)
	(segment
		(start 121.678192 -299.821346)
		(end 121.0056 -298.197778)
		(width 0.14224)
		(layer "In6.Cu")
		(net "P5E_CPU1_P2_RX_DN<8>")
	)
	(segment
		(start 145.218404 -350.322642)
		(end 145.197576 -350.283018)
		(width 0.14224)
		(layer "In6.Cu")
		(net "P5E_CPU1_P2_RX_DN<8>")
	)
	(segment
		(start 157.391354 -379.315472)
		(end 157.534356 -379.184154)
		(width 0.14224)
		(layer "In6.Cu")
		(net "P5E_CPU1_P2_RX_DN<8>")
	)
	(segment
		(start 120.248172 -285.101792)
		(end 120.212612 -285.080964)
		(width 0.1143)
		(layer "In6.Cu")
		(net "P5E_CPU1_P2_RX_DN<8>")
	)
	(segment
		(start 157.504638 -379.88494)
		(end 157.37332 -379.741938)
		(width 0.14224)
		(layer "In6.Cu")
		(net "P5E_CPU1_P2_RX_DN<8>")
	)
	(segment
		(start 156.526738 -367.782602)
		(end 148.058378 -355.109018)
		(width 0.14224)
		(layer "In6.Cu")
		(net "P5E_CPU1_P2_RX_DN<8>")
	)
	(segment
		(start 145.197576 -350.283018)
		(end 143.407892 -347.11894)
		(width 0.14224)
		(layer "In6.Cu")
		(net "P5E_CPU1_P2_RX_DN<8>")
	)
	(segment
		(start 120.866408 -297.498262)
		(end 120.866408 -296.353738)
		(width 0.14224)
		(layer "In6.Cu")
		(net "P5E_CPU1_P2_RX_DN<8>")
	)
	(segment
		(start 120.25376 -285.105094)
		(end 120.25249 -285.104332)
		(width 0.1143)
		(layer "In6.Cu")
		(net "P5E_CPU1_P2_RX_DN<8>")
	)
	(segment
		(start 157.421072 -378.61494)
		(end 157.439106 -378.188474)
		(width 0.14224)
		(layer "In6.Cu")
		(net "P5E_CPU1_P2_RX_DN<8>")
	)
	(segment
		(start 140.80109 -338.614258)
		(end 137.899902 -324.030594)
		(width 0.14224)
		(layer "In6.Cu")
		(net "P5E_CPU1_P2_RX_DN<8>")
	)
	(segment
		(start 120.282208 -293.22141)
		(end 120.212612 -293.18077)
		(width 0.1143)
		(layer "In6.Cu")
		(net "P5E_CPU1_P2_RX_DN<8>")
	)
	(segment
		(start 120.249188 -285.1023)
		(end 120.248172 -285.101792)
		(width 0.1143)
		(layer "In6.Cu")
		(net "P5E_CPU1_P2_RX_DN<8>")
	)
	(segment
		(start 120.439434 -295.146222)
		(end 120.43918 -295.146222)
		(width 0.1143)
		(layer "In6.Cu")
		(net "P5E_CPU1_P2_RX_DN<8>")
	)
	(segment
		(start 157.372812 -385.404868)
		(end 157.494478 -385.334764)
		(width 0.14224)
		(layer "In6.Cu")
		(net "P5E_CPU1_P2_RX_DN<8>")
	)
	(segment
		(start 157.55239 -378.757942)
		(end 157.421072 -378.61494)
		(width 0.14224)
		(layer "In6.Cu")
		(net "P5E_CPU1_P2_RX_DN<8>")
	)
	(segment
		(start 157.439106 -378.188474)
		(end 157.582362 -378.057156)
		(width 0.14224)
		(layer "In6.Cu")
		(net "P5E_CPU1_P2_RX_DN<8>")
	)
	(segment
		(start 158.296864 -371.556788)
		(end 158.12135 -370.980462)
		(width 0.14224)
		(layer "In6.Cu")
		(net "P5E_CPU1_P2_RX_DN<8>")
	)
	(segment
		(start 158.089346 -370.927376)
		(end 157.718506 -370.556536)
		(width 0.14224)
		(layer "In6.Cu")
		(net "P5E_CPU1_P2_RX_DN<8>")
	)
	(arc
		(start 158.12135 -370.980462)
		(mid 158.108593 -370.951966)
		(end 158.089346 -370.927376)
		(width 0.14224)
		(layer "In6.Cu")
		(net "P5E_CPU1_P2_RX_DN<8>")
	)
	(arc
		(start 157.718506 -370.556536)
		(mid 157.598456 -370.457996)
		(end 157.461458 -370.384832)
		(width 0.14224)
		(layer "In6.Cu")
		(net "P5E_CPU1_P2_RX_DN<8>")
	)
	(arc
		(start 156.966158 -370.13134)
		(mid 156.876576 -370.068125)
		(end 156.798518 -369.991132)
		(width 0.14224)
		(layer "In6.Cu")
		(net "P5E_CPU1_P2_RX_DN<8>")
	)
	(arc
		(start 156.594556 -369.65509)
		(mid 156.559838 -369.538205)
		(end 156.548074 -369.416838)
		(width 0.14224)
		(layer "In6.Cu")
		(net "P5E_CPU1_P2_RX_DN<8>")
	)
	(arc
		(start 120.212612 -293.18077)
		(mid 119.969285 -292.716204)
		(end 120.212612 -292.251638)
		(width 0.1143)
		(layer "In6.Cu")
		(net "P5E_CPU1_P2_RX_DN<8>")
	)
	(arc
		(start 120.43918 -288.666174)
		(mid 120.398214 -288.495768)
		(end 120.28424 -288.362644)
		(width 0.1143)
		(layer "In6.Cu")
		(net "P5E_CPU1_P2_RX_DN<8>")
	)
	(arc
		(start 157.314138 -370.323872)
		(mid 157.238385 -370.289186)
		(end 157.165294 -370.249196)
		(width 0.14224)
		(layer "In6.Cu")
		(net "P5E_CPU1_P2_RX_DN<8>")
	)
	(arc
		(start 120.283478 -287.350454)
		(mid 120.398154 -287.21712)
		(end 120.439434 -287.046162)
		(width 0.1143)
		(layer "In6.Cu")
		(net "P5E_CPU1_P2_RX_DN<8>")
	)
	(arc
		(start 120.212612 -294.800782)
		(mid 119.969285 -294.336216)
		(end 120.212612 -293.87165)
		(width 0.1143)
		(layer "In6.Cu")
		(net "P5E_CPU1_P2_RX_DN<8>")
	)
	(arc
		(start 120.682766 -295.610788)
		(mid 120.503953 -295.408438)
		(end 120.439434 -295.146222)
		(width 0.1143)
		(layer "In6.Cu")
		(net "P5E_CPU1_P2_RX_DN<8>")
	)
	(arc
		(start 120.212612 -291.560758)
		(mid 119.969285 -291.096192)
		(end 120.212612 -290.631626)
		(width 0.1143)
		(layer "In6.Cu")
		(net "P5E_CPU1_P2_RX_DN<8>")
	)
	(arc
		(start 156.798518 -369.991132)
		(mid 156.682954 -369.831356)
		(end 156.594556 -369.65509)
		(width 0.14224)
		(layer "In6.Cu")
		(net "P5E_CPU1_P2_RX_DN<8>")
	)
	(arc
		(start 120.781826 -295.674796)
		(mid 120.767391 -295.662737)
		(end 120.752362 -295.651428)
		(width 0.1143)
		(layer "In6.Cu")
		(net "P5E_CPU1_P2_RX_DN<8>")
	)
	(arc
		(start 120.212612 -285.080964)
		(mid 120.060625 -284.924456)
		(end 119.979186 -284.722062)
		(width 0.1143)
		(layer "In6.Cu")
		(net "P5E_CPU1_P2_RX_DN<8>")
	)
	(arc
		(start 120.682766 -285.89097)
		(mid 120.503953 -285.68862)
		(end 120.439434 -285.426404)
		(width 0.1143)
		(layer "In6.Cu")
		(net "P5E_CPU1_P2_RX_DN<8>")
	)
	(arc
		(start 120.754394 -286.53994)
		(mid 120.868323 -286.406793)
		(end 120.909334 -286.23641)
		(width 0.1143)
		(layer "In6.Cu")
		(net "P5E_CPU1_P2_RX_DN<8>")
	)
	(arc
		(start 121.0056 -298.197778)
		(mid 120.901551 -297.854874)
		(end 120.866408 -297.498262)
		(width 0.14224)
		(layer "In6.Cu")
		(net "P5E_CPU1_P2_RX_DN<8>")
	)
	(arc
		(start 120.212612 -288.320988)
		(mid 119.969288 -287.854872)
		(end 120.215152 -287.390078)
		(width 0.1143)
		(layer "In6.Cu")
		(net "P5E_CPU1_P2_RX_DN<8>")
	)
	(arc
		(start 119.979186 -284.722062)
		(mid 119.977163 -284.710652)
		(end 119.975376 -284.699202)
		(width 0.1143)
		(layer "In6.Cu")
		(net "P5E_CPU1_P2_RX_DN<8>")
	)
	(arc
		(start 156.548074 -367.853214)
		(mid 156.542672 -367.816313)
		(end 156.526738 -367.782602)
		(width 0.14224)
		(layer "In6.Cu")
		(net "P5E_CPU1_P2_RX_DN<8>")
	)
	(arc
		(start 120.909334 -286.23641)
		(mid 120.867785 -286.064988)
		(end 120.752362 -285.93161)
		(width 0.1143)
		(layer "In6.Cu")
		(net "P5E_CPU1_P2_RX_DN<8>")
	)
	(arc
		(start 120.439434 -287.046162)
		(mid 120.503949 -286.783943)
		(end 120.682766 -286.581596)
		(width 0.1143)
		(layer "In6.Cu")
		(net "P5E_CPU1_P2_RX_DN<8>")
	)
	(arc
		(start 120.439434 -285.426404)
		(mid 120.398179 -285.255433)
		(end 120.283478 -285.122112)
		(width 0.1143)
		(layer "In6.Cu")
		(net "P5E_CPU1_P2_RX_DN<8>")
	)
	(arc
		(start 158.298896 -371.660166)
		(mid 158.305004 -371.60834)
		(end 158.296864 -371.556788)
		(width 0.14224)
		(layer "In6.Cu")
		(net "P5E_CPU1_P2_RX_DN<8>")
	)
	(arc
		(start 120.282208 -293.83101)
		(mid 120.439185 -293.52621)
		(end 120.282208 -293.22141)
		(width 0.1143)
		(layer "In6.Cu")
		(net "P5E_CPU1_P2_RX_DN<8>")
	)
	(arc
		(start 120.282208 -292.210998)
		(mid 120.439185 -291.906198)
		(end 120.282208 -291.601398)
		(width 0.1143)
		(layer "In6.Cu")
		(net "P5E_CPU1_P2_RX_DN<8>")
	)
	(arc
		(start 120.43918 -295.146222)
		(mid 120.397631 -294.9748)
		(end 120.282208 -294.841422)
		(width 0.1143)
		(layer "In6.Cu")
		(net "P5E_CPU1_P2_RX_DN<8>")
	)
	(arc
		(start 120.212612 -289.940746)
		(mid 119.969285 -289.47618)
		(end 120.212612 -289.011614)
		(width 0.1143)
		(layer "In6.Cu")
		(net "P5E_CPU1_P2_RX_DN<8>")
	)
	(arc
		(start 120.909588 -295.956228)
		(mid 120.876102 -295.801714)
		(end 120.781826 -295.674796)
		(width 0.1143)
		(layer "In6.Cu")
		(net "P5E_CPU1_P2_RX_DN<8>")
	)
	(arc
		(start 120.282208 -290.590986)
		(mid 120.439185 -290.286186)
		(end 120.282208 -289.981386)
		(width 0.1143)
		(layer "In6.Cu")
		(net "P5E_CPU1_P2_RX_DN<8>")
	)
	(arc
		(start 120.282208 -288.970974)
		(mid 120.397635 -288.837598)
		(end 120.43918 -288.666174)
		(width 0.1143)
		(layer "In6.Cu")
		(net "P5E_CPU1_P2_RX_DN<8>")
	)
	(segment
		(start 119.127778 -285.970472)
		(end 119.59463 -286.23641)
		(width 0.12954)
		(layer "F.Cu")
		(net "P5E_CPU1_P2_RX_DN<7>")
	)
	(segment
		(start 155.298394 -385.31038)
		(end 155.819094 -385.31038)
		(width 0.127)
		(layer "F.Cu")
		(net "P5E_CPU1_P2_RX_DN<7>")
	)
	(segment
		(start 156.172154 -385.405376)
		(end 156.172662 -385.404868)
		(width 0.14224)
		(layer "In6.Cu")
		(net "P5E_CPU1_P2_RX_DN<7>")
	)
	(segment
		(start 119.290846 -289.000692)
		(end 119.291862 -289.000184)
		(width 0.1143)
		(layer "In6.Cu")
		(net "P5E_CPU1_P2_RX_DN<7>")
	)
	(segment
		(start 119.308626 -287.370266)
		(end 119.311674 -287.368742)
		(width 0.1143)
		(layer "In6.Cu")
		(net "P5E_CPU1_P2_RX_DN<7>")
	)
	(segment
		(start 119.979948 -296.27957)
		(end 119.979948 -296.08653)
		(width 0.1143)
		(layer "In6.Cu")
		(net "P5E_CPU1_P2_RX_DN<7>")
	)
	(segment
		(start 142.588234 -347.669358)
		(end 141.79296 -345.71178)
		(width 0.14224)
		(layer "In6.Cu")
		(net "P5E_CPU1_P2_RX_DN<7>")
	)
	(segment
		(start 155.819094 -385.31038)
		(end 156.172154 -385.405376)
		(width 0.14224)
		(layer "In6.Cu")
		(net "P5E_CPU1_P2_RX_DN<7>")
	)
	(segment
		(start 156.2862 -381.769112)
		(end 156.313632 -381.131572)
		(width 0.14224)
		(layer "In6.Cu")
		(net "P5E_CPU1_P2_RX_DN<7>")
	)
	(segment
		(start 119.345202 -288.363406)
		(end 119.34444 -288.362898)
		(width 0.1143)
		(layer "In6.Cu")
		(net "P5E_CPU1_P2_RX_DN<7>")
	)
	(segment
		(start 147.326604 -355.98354)
		(end 142.588234 -347.669358)
		(width 0.14224)
		(layer "In6.Cu")
		(net "P5E_CPU1_P2_RX_DN<7>")
	)
	(segment
		(start 119.962422 -286.30626)
		(end 119.892572 -286.23641)
		(width 0.1143)
		(layer "In6.Cu")
		(net "P5E_CPU1_P2_RX_DN<7>")
	)
	(segment
		(start 156.313632 -381.131572)
		(end 156.182314 -380.98857)
		(width 0.14224)
		(layer "In6.Cu")
		(net "P5E_CPU1_P2_RX_DN<7>")
	)
	(segment
		(start 119.342154 -291.601398)
		(end 119.272558 -291.560758)
		(width 0.1143)
		(layer "In6.Cu")
		(net "P5E_CPU1_P2_RX_DN<7>")
	)
	(segment
		(start 119.282718 -289.005264)
		(end 119.283988 -289.004502)
		(width 0.1143)
		(layer "In6.Cu")
		(net "P5E_CPU1_P2_RX_DN<7>")
	)
	(segment
		(start 156.298138 -378.308362)
		(end 156.44114 -378.177298)
		(width 0.14224)
		(layer "In6.Cu")
		(net "P5E_CPU1_P2_RX_DN<7>")
	)
	(segment
		(start 119.287544 -289.00247)
		(end 119.290084 -289.0012)
		(width 0.1143)
		(layer "In6.Cu")
		(net "P5E_CPU1_P2_RX_DN<7>")
	)
	(segment
		(start 119.285512 -289.00374)
		(end 119.286274 -289.003232)
		(width 0.1143)
		(layer "In6.Cu")
		(net "P5E_CPU1_P2_RX_DN<7>")
	)
	(segment
		(start 119.286274 -289.003232)
		(end 119.287544 -289.00247)
		(width 0.1143)
		(layer "In6.Cu")
		(net "P5E_CPU1_P2_RX_DN<7>")
	)
	(segment
		(start 119.342154 -294.841422)
		(end 119.272558 -294.800782)
		(width 0.1143)
		(layer "In6.Cu")
		(net "P5E_CPU1_P2_RX_DN<7>")
	)
	(segment
		(start 156.410914 -378.87783)
		(end 156.279596 -378.734828)
		(width 0.14224)
		(layer "In6.Cu")
		(net "P5E_CPU1_P2_RX_DN<7>")
	)
	(segment
		(start 154.506422 -367.683288)
		(end 154.506168 -367.683542)
		(width 0.14224)
		(layer "In6.Cu")
		(net "P5E_CPU1_P2_RX_DN<7>")
	)
	(segment
		(start 119.979948 -296.08653)
		(end 119.97944 -296.086022)
		(width 0.1143)
		(layer "In6.Cu")
		(net "P5E_CPU1_P2_RX_DN<7>")
	)
	(segment
		(start 119.934228 -297.676062)
		(end 119.934228 -296.353738)
		(width 0.14224)
		(layer "In6.Cu")
		(net "P5E_CPU1_P2_RX_DN<7>")
	)
	(segment
		(start 119.278146 -287.3883)
		(end 119.279416 -287.387538)
		(width 0.1143)
		(layer "In6.Cu")
		(net "P5E_CPU1_P2_RX_DN<7>")
	)
	(segment
		(start 119.272558 -290.631626)
		(end 119.342154 -290.590986)
		(width 0.1143)
		(layer "In6.Cu")
		(net "P5E_CPU1_P2_RX_DN<7>")
	)
	(segment
		(start 119.934228 -296.32529)
		(end 119.979948 -296.27957)
		(width 0.1143)
		(layer "In6.Cu")
		(net "P5E_CPU1_P2_RX_DN<7>")
	)
	(segment
		(start 156.172662 -385.404868)
		(end 156.294328 -385.334764)
		(width 0.14224)
		(layer "In6.Cu")
		(net "P5E_CPU1_P2_RX_DN<7>")
	)
	(segment
		(start 156.41066 -378.87783)
		(end 156.410914 -378.87783)
		(width 0.14224)
		(layer "In6.Cu")
		(net "P5E_CPU1_P2_RX_DN<7>")
	)
	(segment
		(start 130.512058 -313.001152)
		(end 124.328428 -305.466242)
		(width 0.14224)
		(layer "In6.Cu")
		(net "P5E_CPU1_P2_RX_DN<7>")
	)
	(segment
		(start 119.3165 -287.365948)
		(end 119.317516 -287.36544)
		(width 0.1143)
		(layer "In6.Cu")
		(net "P5E_CPU1_P2_RX_DN<7>")
	)
	(segment
		(start 136.760458 -323.924168)
		(end 132.5626 -316.070234)
		(width 0.14224)
		(layer "In6.Cu")
		(net "P5E_CPU1_P2_RX_DN<7>")
	)
	(segment
		(start 156.279596 -378.734828)
		(end 156.298138 -378.308362)
		(width 0.14224)
		(layer "In6.Cu")
		(net "P5E_CPU1_P2_RX_DN<7>")
	)
	(segment
		(start 156.200856 -380.562104)
		(end 156.344112 -380.430786)
		(width 0.14224)
		(layer "In6.Cu")
		(net "P5E_CPU1_P2_RX_DN<7>")
	)
	(segment
		(start 156.182314 -380.98857)
		(end 156.200856 -380.562104)
		(width 0.14224)
		(layer "In6.Cu")
		(net "P5E_CPU1_P2_RX_DN<7>")
	)
	(segment
		(start 156.440886 -378.177298)
		(end 156.622496 -373.964708)
		(width 0.14224)
		(layer "In6.Cu")
		(net "P5E_CPU1_P2_RX_DN<7>")
	)
	(segment
		(start 119.342154 -289.981386)
		(end 119.272558 -289.940746)
		(width 0.1143)
		(layer "In6.Cu")
		(net "P5E_CPU1_P2_RX_DN<7>")
	)
	(segment
		(start 119.742712 -286.581596)
		(end 119.81434 -286.53994)
		(width 0.1143)
		(layer "In6.Cu")
		(net "P5E_CPU1_P2_RX_DN<7>")
	)
	(segment
		(start 156.539946 -373.681244)
		(end 156.29001 -373.322342)
		(width 0.14224)
		(layer "In6.Cu")
		(net "P5E_CPU1_P2_RX_DN<7>")
	)
	(segment
		(start 155.884372 -372.936516)
		(end 155.367482 -372.615206)
		(width 0.14224)
		(layer "In6.Cu")
		(net "P5E_CPU1_P2_RX_DN<7>")
	)
	(segment
		(start 156.2862 -383.930906)
		(end 156.2862 -381.769112)
		(width 0.14224)
		(layer "In6.Cu")
		(net "P5E_CPU1_P2_RX_DN<7>")
	)
	(segment
		(start 119.34444 -288.362898)
		(end 119.275352 -288.322766)
		(width 0.1143)
		(layer "In6.Cu")
		(net "P5E_CPU1_P2_RX_DN<7>")
	)
	(segment
		(start 119.317516 -287.36544)
		(end 119.343424 -287.350454)
		(width 0.1143)
		(layer "In6.Cu")
		(net "P5E_CPU1_P2_RX_DN<7>")
	)
	(segment
		(start 156.343858 -380.430786)
		(end 156.362146 -380.004574)
		(width 0.14224)
		(layer "In6.Cu")
		(net "P5E_CPU1_P2_RX_DN<7>")
	)
	(segment
		(start 140.856716 -342.884506)
		(end 139.462002 -337.50631)
		(width 0.14224)
		(layer "In6.Cu")
		(net "P5E_CPU1_P2_RX_DN<7>")
	)
	(segment
		(start 119.934228 -296.353738)
		(end 119.934228 -296.32529)
		(width 0.1143)
		(layer "In6.Cu")
		(net "P5E_CPU1_P2_RX_DN<7>")
	)
	(segment
		(start 132.5626 -316.070234)
		(end 130.512058 -313.001152)
		(width 0.14224)
		(layer "In6.Cu")
		(net "P5E_CPU1_P2_RX_DN<7>")
	)
	(segment
		(start 156.362146 -380.004574)
		(end 156.3624 -380.004574)
		(width 0.14224)
		(layer "In6.Cu")
		(net "P5E_CPU1_P2_RX_DN<7>")
	)
	(segment
		(start 155.982162 -384.234944)
		(end 156.2862 -383.930906)
		(width 0.14224)
		(layer "In6.Cu")
		(net "P5E_CPU1_P2_RX_DN<7>")
	)
	(segment
		(start 119.280178 -287.38703)
		(end 119.308626 -287.370266)
		(width 0.1143)
		(layer "In6.Cu")
		(net "P5E_CPU1_P2_RX_DN<7>")
	)
	(segment
		(start 156.249624 -379.435106)
		(end 156.392626 -379.304042)
		(width 0.14224)
		(layer "In6.Cu")
		(net "P5E_CPU1_P2_RX_DN<7>")
	)
	(segment
		(start 119.279416 -287.387538)
		(end 119.280178 -287.38703)
		(width 0.1143)
		(layer "In6.Cu")
		(net "P5E_CPU1_P2_RX_DN<7>")
	)
	(segment
		(start 119.892572 -286.23641)
		(end 119.59463 -286.23641)
		(width 0.1143)
		(layer "In6.Cu")
		(net "P5E_CPU1_P2_RX_DN<7>")
	)
	(segment
		(start 156.344112 -380.430786)
		(end 156.343858 -380.430786)
		(width 0.14224)
		(layer "In6.Cu")
		(net "P5E_CPU1_P2_RX_DN<7>")
	)
	(segment
		(start 119.342154 -293.22141)
		(end 119.272558 -293.18077)
		(width 0.1143)
		(layer "In6.Cu")
		(net "P5E_CPU1_P2_RX_DN<7>")
	)
	(segment
		(start 119.275352 -289.009582)
		(end 119.281956 -289.005772)
		(width 0.1143)
		(layer "In6.Cu")
		(net "P5E_CPU1_P2_RX_DN<7>")
	)
	(segment
		(start 156.231082 -379.861572)
		(end 156.249624 -379.435106)
		(width 0.14224)
		(layer "In6.Cu")
		(net "P5E_CPU1_P2_RX_DN<7>")
	)
	(segment
		(start 119.781828 -295.633648)
		(end 119.743982 -295.611804)
		(width 0.1143)
		(layer "In6.Cu")
		(net "P5E_CPU1_P2_RX_DN<7>")
	)
	(segment
		(start 119.312436 -287.368234)
		(end 119.315738 -287.366456)
		(width 0.1143)
		(layer "In6.Cu")
		(net "P5E_CPU1_P2_RX_DN<7>")
	)
	(segment
		(start 156.44114 -378.177298)
		(end 156.440886 -378.177298)
		(width 0.14224)
		(layer "In6.Cu")
		(net "P5E_CPU1_P2_RX_DN<7>")
	)
	(segment
		(start 119.97944 -296.086022)
		(end 119.97944 -295.978072)
		(width 0.1143)
		(layer "In6.Cu")
		(net "P5E_CPU1_P2_RX_DN<7>")
	)
	(segment
		(start 156.294328 -385.334764)
		(end 156.294328 -385.163822)
		(width 0.14224)
		(layer "In6.Cu")
		(net "P5E_CPU1_P2_RX_DN<7>")
	)
	(segment
		(start 119.272558 -293.87165)
		(end 119.342154 -293.83101)
		(width 0.1143)
		(layer "In6.Cu")
		(net "P5E_CPU1_P2_RX_DN<7>")
	)
	(segment
		(start 119.291862 -289.000184)
		(end 119.343424 -288.970466)
		(width 0.1143)
		(layer "In6.Cu")
		(net "P5E_CPU1_P2_RX_DN<7>")
	)
	(segment
		(start 139.462002 -337.50631)
		(end 136.760458 -323.924168)
		(width 0.14224)
		(layer "In6.Cu")
		(net "P5E_CPU1_P2_RX_DN<7>")
	)
	(segment
		(start 119.281956 -289.005772)
		(end 119.282718 -289.005264)
		(width 0.1143)
		(layer "In6.Cu")
		(net "P5E_CPU1_P2_RX_DN<7>")
	)
	(segment
		(start 119.315738 -287.366456)
		(end 119.3165 -287.365948)
		(width 0.1143)
		(layer "In6.Cu")
		(net "P5E_CPU1_P2_RX_DN<7>")
	)
	(segment
		(start 119.8118 -295.65092)
		(end 119.783606 -295.634664)
		(width 0.1143)
		(layer "In6.Cu")
		(net "P5E_CPU1_P2_RX_DN<7>")
	)
	(segment
		(start 120.733566 -300.086522)
		(end 120.117616 -298.599352)
		(width 0.14224)
		(layer "In6.Cu")
		(net "P5E_CPU1_P2_RX_DN<7>")
	)
	(segment
		(start 154.487372 -367.61674)
		(end 147.326604 -355.98354)
		(width 0.14224)
		(layer "In6.Cu")
		(net "P5E_CPU1_P2_RX_DN<7>")
	)
	(segment
		(start 141.79296 -345.71178)
		(end 140.856716 -342.884506)
		(width 0.14224)
		(layer "In6.Cu")
		(net "P5E_CPU1_P2_RX_DN<7>")
	)
	(segment
		(start 154.861514 -372.044468)
		(end 154.544522 -371.362732)
		(width 0.14224)
		(layer "In6.Cu")
		(net "P5E_CPU1_P2_RX_DN<7>")
	)
	(segment
		(start 124.328428 -305.466242)
		(end 120.733566 -300.086522)
		(width 0.14224)
		(layer "In6.Cu")
		(net "P5E_CPU1_P2_RX_DN<7>")
	)
	(segment
		(start 119.311674 -287.368742)
		(end 119.312436 -287.368234)
		(width 0.1143)
		(layer "In6.Cu")
		(net "P5E_CPU1_P2_RX_DN<7>")
	)
	(segment
		(start 119.290084 -289.0012)
		(end 119.290846 -289.000692)
		(width 0.1143)
		(layer "In6.Cu")
		(net "P5E_CPU1_P2_RX_DN<7>")
	)
	(segment
		(start 156.294328 -385.163822)
		(end 155.977336 -384.84683)
		(width 0.14224)
		(layer "In6.Cu")
		(net "P5E_CPU1_P2_RX_DN<7>")
	)
	(segment
		(start 155.977336 -384.84683)
		(end 155.982162 -384.234944)
		(width 0.14224)
		(layer "In6.Cu")
		(net "P5E_CPU1_P2_RX_DN<7>")
	)
	(segment
		(start 119.283988 -289.004502)
		(end 119.285512 -289.00374)
		(width 0.1143)
		(layer "In6.Cu")
		(net "P5E_CPU1_P2_RX_DN<7>")
	)
	(segment
		(start 119.272558 -289.011614)
		(end 119.275352 -289.009582)
		(width 0.1143)
		(layer "In6.Cu")
		(net "P5E_CPU1_P2_RX_DN<7>")
	)
	(segment
		(start 156.392626 -379.304042)
		(end 156.392372 -379.304042)
		(width 0.14224)
		(layer "In6.Cu")
		(net "P5E_CPU1_P2_RX_DN<7>")
	)
	(segment
		(start 119.272558 -292.251638)
		(end 119.342154 -292.210998)
		(width 0.1143)
		(layer "In6.Cu")
		(net "P5E_CPU1_P2_RX_DN<7>")
	)
	(segment
		(start 154.506422 -371.190266)
		(end 154.506422 -367.683288)
		(width 0.14224)
		(layer "In6.Cu")
		(net "P5E_CPU1_P2_RX_DN<7>")
	)
	(segment
		(start 156.392372 -379.304042)
		(end 156.41066 -378.87783)
		(width 0.14224)
		(layer "In6.Cu")
		(net "P5E_CPU1_P2_RX_DN<7>")
	)
	(segment
		(start 119.783606 -295.634664)
		(end 119.781828 -295.633648)
		(width 0.1143)
		(layer "In6.Cu")
		(net "P5E_CPU1_P2_RX_DN<7>")
	)
	(segment
		(start 119.49938 -295.146222)
		(end 119.499126 -295.146222)
		(width 0.1143)
		(layer "In6.Cu")
		(net "P5E_CPU1_P2_RX_DN<7>")
	)
	(segment
		(start 156.3624 -380.004574)
		(end 156.231082 -379.861572)
		(width 0.14224)
		(layer "In6.Cu")
		(net "P5E_CPU1_P2_RX_DN<7>")
	)
	(arc
		(start 119.342154 -290.590986)
		(mid 119.499131 -290.286186)
		(end 119.342154 -289.981386)
		(width 0.1143)
		(layer "In6.Cu")
		(net "P5E_CPU1_P2_RX_DN<7>")
	)
	(arc
		(start 119.02948 -287.856422)
		(mid 119.02948 -287.855533)
		(end 119.02948 -287.854644)
		(width 0.1143)
		(layer "In6.Cu")
		(net "P5E_CPU1_P2_RX_DN<7>")
	)
	(arc
		(start 119.499126 -295.146222)
		(mid 119.457577 -294.9748)
		(end 119.342154 -294.841422)
		(width 0.1143)
		(layer "In6.Cu")
		(net "P5E_CPU1_P2_RX_DN<7>")
	)
	(arc
		(start 155.367482 -372.615206)
		(mid 155.072914 -372.366708)
		(end 154.861514 -372.044468)
		(width 0.14224)
		(layer "In6.Cu")
		(net "P5E_CPU1_P2_RX_DN<7>")
	)
	(arc
		(start 156.622496 -373.964708)
		(mid 156.604531 -373.816181)
		(end 156.539946 -373.681244)
		(width 0.14224)
		(layer "In6.Cu")
		(net "P5E_CPU1_P2_RX_DN<7>")
	)
	(arc
		(start 120.117616 -298.599352)
		(mid 119.980454 -298.146739)
		(end 119.934228 -297.676062)
		(width 0.14224)
		(layer "In6.Cu")
		(net "P5E_CPU1_P2_RX_DN<7>")
	)
	(arc
		(start 119.272558 -289.940746)
		(mid 119.029231 -289.47618)
		(end 119.272558 -289.011614)
		(width 0.1143)
		(layer "In6.Cu")
		(net "P5E_CPU1_P2_RX_DN<7>")
	)
	(arc
		(start 119.272558 -293.18077)
		(mid 119.029231 -292.716204)
		(end 119.272558 -292.251638)
		(width 0.1143)
		(layer "In6.Cu")
		(net "P5E_CPU1_P2_RX_DN<7>")
	)
	(arc
		(start 119.342154 -292.210998)
		(mid 119.499131 -291.906198)
		(end 119.342154 -291.601398)
		(width 0.1143)
		(layer "In6.Cu")
		(net "P5E_CPU1_P2_RX_DN<7>")
	)
	(arc
		(start 119.02948 -287.854644)
		(mid 119.092394 -287.599128)
		(end 119.262906 -287.398714)
		(width 0.1143)
		(layer "In6.Cu")
		(net "P5E_CPU1_P2_RX_DN<7>")
	)
	(arc
		(start 119.97944 -295.978072)
		(mid 119.935075 -295.794289)
		(end 119.8118 -295.65092)
		(width 0.1143)
		(layer "In6.Cu")
		(net "P5E_CPU1_P2_RX_DN<7>")
	)
	(arc
		(start 119.343424 -288.970466)
		(mid 119.4581 -288.837132)
		(end 119.49938 -288.666174)
		(width 0.1143)
		(layer "In6.Cu")
		(net "P5E_CPU1_P2_RX_DN<7>")
	)
	(arc
		(start 156.29001 -373.322342)
		(mid 156.10686 -373.108748)
		(end 155.884372 -372.936516)
		(width 0.14224)
		(layer "In6.Cu")
		(net "P5E_CPU1_P2_RX_DN<7>")
	)
	(arc
		(start 119.81434 -286.53994)
		(mid 119.91078 -286.437285)
		(end 119.962422 -286.30626)
		(width 0.1143)
		(layer "In6.Cu")
		(net "P5E_CPU1_P2_RX_DN<7>")
	)
	(arc
		(start 154.506168 -367.683542)
		(mid 154.501415 -367.648833)
		(end 154.487372 -367.61674)
		(width 0.14224)
		(layer "In6.Cu")
		(net "P5E_CPU1_P2_RX_DN<7>")
	)
	(arc
		(start 154.544522 -371.362732)
		(mid 154.516046 -371.27858)
		(end 154.506422 -371.190266)
		(width 0.14224)
		(layer "In6.Cu")
		(net "P5E_CPU1_P2_RX_DN<7>")
	)
	(arc
		(start 119.49938 -287.046162)
		(mid 119.563895 -286.783943)
		(end 119.742712 -286.581596)
		(width 0.1143)
		(layer "In6.Cu")
		(net "P5E_CPU1_P2_RX_DN<7>")
	)
	(arc
		(start 119.272558 -294.800782)
		(mid 119.029231 -294.336216)
		(end 119.272558 -293.87165)
		(width 0.1143)
		(layer "In6.Cu")
		(net "P5E_CPU1_P2_RX_DN<7>")
	)
	(arc
		(start 119.343424 -287.350454)
		(mid 119.4581 -287.21712)
		(end 119.49938 -287.046162)
		(width 0.1143)
		(layer "In6.Cu")
		(net "P5E_CPU1_P2_RX_DN<7>")
	)
	(arc
		(start 119.262906 -287.398714)
		(mid 119.270483 -287.393445)
		(end 119.278146 -287.3883)
		(width 0.1143)
		(layer "In6.Cu")
		(net "P5E_CPU1_P2_RX_DN<7>")
	)
	(arc
		(start 119.342154 -293.83101)
		(mid 119.499131 -293.52621)
		(end 119.342154 -293.22141)
		(width 0.1143)
		(layer "In6.Cu")
		(net "P5E_CPU1_P2_RX_DN<7>")
	)
	(arc
		(start 119.49938 -288.666174)
		(mid 119.458618 -288.49629)
		(end 119.345202 -288.363406)
		(width 0.1143)
		(layer "In6.Cu")
		(net "P5E_CPU1_P2_RX_DN<7>")
	)
	(arc
		(start 119.272558 -291.560758)
		(mid 119.029231 -291.096192)
		(end 119.272558 -290.631626)
		(width 0.1143)
		(layer "In6.Cu")
		(net "P5E_CPU1_P2_RX_DN<7>")
	)
	(arc
		(start 119.275352 -288.322766)
		(mid 119.0947 -288.120021)
		(end 119.02948 -287.856422)
		(width 0.1143)
		(layer "In6.Cu")
		(net "P5E_CPU1_P2_RX_DN<7>")
	)
	(arc
		(start 119.743982 -295.611804)
		(mid 119.564253 -295.409184)
		(end 119.49938 -295.146222)
		(width 0.1143)
		(layer "In6.Cu")
		(net "P5E_CPU1_P2_RX_DN<7>")
	)
	(segment
		(start 119.127778 -282.730448)
		(end 119.59463 -282.996386)
		(width 0.12954)
		(layer "F.Cu")
		(net "P5E_CPU1_P2_RX_DN<6>")
	)
	(segment
		(start 154.098244 -385.31038)
		(end 154.618944 -385.31038)
		(width 0.127)
		(layer "F.Cu")
		(net "P5E_CPU1_P2_RX_DN<6>")
	)
	(segment
		(start 118.802658 -286.581596)
		(end 118.871746 -286.541718)
		(width 0.1143)
		(layer "In6.Cu")
		(net "P5E_CPU1_P2_RX_DN<6>")
	)
	(segment
		(start 133.77037 -320.315336)
		(end 131.774184 -316.581028)
		(width 0.14224)
		(layer "In6.Cu")
		(net "P5E_CPU1_P2_RX_DN<6>")
	)
	(segment
		(start 142.379192 -349.521272)
		(end 141.045692 -346.83065)
		(width 0.14224)
		(layer "In6.Cu")
		(net "P5E_CPU1_P2_RX_DN<6>")
	)
	(segment
		(start 119.03329 -284.628336)
		(end 119.03329 -284.610556)
		(width 0.1143)
		(layer "In6.Cu")
		(net "P5E_CPU1_P2_RX_DN<6>")
	)
	(segment
		(start 118.854982 -284.931358)
		(end 118.860062 -284.92831)
		(width 0.1143)
		(layer "In6.Cu")
		(net "P5E_CPU1_P2_RX_DN<6>")
	)
	(segment
		(start 118.846346 -295.636188)
		(end 118.843806 -295.634918)
		(width 0.1143)
		(layer "In6.Cu")
		(net "P5E_CPU1_P2_RX_DN<6>")
	)
	(segment
		(start 118.84787 -295.637204)
		(end 118.846346 -295.636188)
		(width 0.1143)
		(layer "In6.Cu")
		(net "P5E_CPU1_P2_RX_DN<6>")
	)
	(segment
		(start 141.045692 -346.83065)
		(end 139.313412 -341.743792)
		(width 0.14224)
		(layer "In6.Cu")
		(net "P5E_CPU1_P2_RX_DN<6>")
	)
	(segment
		(start 154.343608 -379.673104)
		(end 154.444446 -379.507496)
		(width 0.14224)
		(layer "In6.Cu")
		(net "P5E_CPU1_P2_RX_DN<6>")
	)
	(segment
		(start 119.02948 -296.27957)
		(end 119.02948 -296.007282)
		(width 0.1143)
		(layer "In6.Cu")
		(net "P5E_CPU1_P2_RX_DN<6>")
	)
	(segment
		(start 119.315738 -284.126686)
		(end 119.315992 -284.126432)
		(width 0.1143)
		(layer "In6.Cu")
		(net "P5E_CPU1_P2_RX_DN<6>")
	)
	(segment
		(start 118.98376 -297.94454)
		(end 118.98376 -296.353738)
		(width 0.14224)
		(layer "In6.Cu")
		(net "P5E_CPU1_P2_RX_DN<6>")
	)
	(segment
		(start 155.094432 -385.334764)
		(end 155.094432 -385.163822)
		(width 0.14224)
		(layer "In6.Cu")
		(net "P5E_CPU1_P2_RX_DN<6>")
	)
	(segment
		(start 153.10485 -373.683276)
		(end 153.25598 -371.263672)
		(width 0.14224)
		(layer "In6.Cu")
		(net "P5E_CPU1_P2_RX_DN<6>")
	)
	(segment
		(start 155.086304 -383.93116)
		(end 155.086304 -382.166368)
		(width 0.14224)
		(layer "In6.Cu")
		(net "P5E_CPU1_P2_RX_DN<6>")
	)
	(segment
		(start 118.843806 -295.634918)
		(end 118.842536 -295.634156)
		(width 0.1143)
		(layer "In6.Cu")
		(net "P5E_CPU1_P2_RX_DN<6>")
	)
	(segment
		(start 118.842536 -295.634156)
		(end 118.841774 -295.633648)
		(width 0.1143)
		(layer "In6.Cu")
		(net "P5E_CPU1_P2_RX_DN<6>")
	)
	(segment
		(start 118.332758 -290.631626)
		(end 118.402354 -290.590986)
		(width 0.1143)
		(layer "In6.Cu")
		(net "P5E_CPU1_P2_RX_DN<6>")
	)
	(segment
		(start 119.962422 -283.066236)
		(end 119.892572 -282.996386)
		(width 0.1143)
		(layer "In6.Cu")
		(net "P5E_CPU1_P2_RX_DN<6>")
	)
	(segment
		(start 154.618944 -385.31038)
		(end 154.972258 -385.405376)
		(width 0.14224)
		(layer "In6.Cu")
		(net "P5E_CPU1_P2_RX_DN<6>")
	)
	(segment
		(start 119.857012 -300.471586)
		(end 119.138446 -298.726606)
		(width 0.14224)
		(layer "In6.Cu")
		(net "P5E_CPU1_P2_RX_DN<6>")
	)
	(segment
		(start 154.71013 -381.183896)
		(end 154.609546 -380.769114)
		(width 0.14224)
		(layer "In6.Cu")
		(net "P5E_CPU1_P2_RX_DN<6>")
	)
	(segment
		(start 154.972258 -385.405376)
		(end 154.972766 -385.404868)
		(width 0.14224)
		(layer "In6.Cu")
		(net "P5E_CPU1_P2_RX_DN<6>")
	)
	(segment
		(start 154.876246 -381.284988)
		(end 154.71013 -381.183896)
		(width 0.14224)
		(layer "In6.Cu")
		(net "P5E_CPU1_P2_RX_DN<6>")
	)
	(segment
		(start 119.744236 -283.34081)
		(end 119.812308 -283.301186)
		(width 0.1143)
		(layer "In6.Cu")
		(net "P5E_CPU1_P2_RX_DN<6>")
	)
	(segment
		(start 118.332758 -292.251638)
		(end 118.402354 -292.210998)
		(width 0.1143)
		(layer "In6.Cu")
		(net "P5E_CPU1_P2_RX_DN<6>")
	)
	(segment
		(start 119.892572 -282.996386)
		(end 119.59463 -282.996386)
		(width 0.1143)
		(layer "In6.Cu")
		(net "P5E_CPU1_P2_RX_DN<6>")
	)
	(segment
		(start 118.841774 -295.633648)
		(end 118.840758 -295.63314)
		(width 0.1143)
		(layer "In6.Cu")
		(net "P5E_CPU1_P2_RX_DN<6>")
	)
	(segment
		(start 118.402354 -293.22141)
		(end 118.332758 -293.18077)
		(width 0.1143)
		(layer "In6.Cu")
		(net "P5E_CPU1_P2_RX_DN<6>")
	)
	(segment
		(start 119.02948 -296.007282)
		(end 119.029734 -296.007028)
		(width 0.1143)
		(layer "In6.Cu")
		(net "P5E_CPU1_P2_RX_DN<6>")
	)
	(segment
		(start 118.839488 -284.941264)
		(end 118.854982 -284.931612)
		(width 0.1143)
		(layer "In6.Cu")
		(net "P5E_CPU1_P2_RX_DN<6>")
	)
	(segment
		(start 154.178 -378.991876)
		(end 154.077416 -378.577094)
		(width 0.14224)
		(layer "In6.Cu")
		(net "P5E_CPU1_P2_RX_DN<6>")
	)
	(segment
		(start 155.094432 -385.163822)
		(end 154.77744 -384.84683)
		(width 0.14224)
		(layer "In6.Cu")
		(net "P5E_CPU1_P2_RX_DN<6>")
	)
	(segment
		(start 154.610054 -380.188978)
		(end 154.444192 -380.087886)
		(width 0.14224)
		(layer "In6.Cu")
		(net "P5E_CPU1_P2_RX_DN<6>")
	)
	(segment
		(start 118.402354 -294.841422)
		(end 118.332758 -294.800782)
		(width 0.1143)
		(layer "In6.Cu")
		(net "P5E_CPU1_P2_RX_DN<6>")
	)
	(segment
		(start 154.343862 -379.092968)
		(end 154.178 -378.991876)
		(width 0.14224)
		(layer "In6.Cu")
		(net "P5E_CPU1_P2_RX_DN<6>")
	)
	(segment
		(start 139.313412 -341.743792)
		(end 139.313158 -341.743792)
		(width 0.14224)
		(layer "In6.Cu")
		(net "P5E_CPU1_P2_RX_DN<6>")
	)
	(segment
		(start 118.98376 -296.32529)
		(end 119.02948 -296.27957)
		(width 0.1143)
		(layer "In6.Cu")
		(net "P5E_CPU1_P2_RX_DN<6>")
	)
	(segment
		(start 118.332758 -293.87165)
		(end 118.402354 -293.83101)
		(width 0.1143)
		(layer "In6.Cu")
		(net "P5E_CPU1_P2_RX_DN<6>")
	)
	(segment
		(start 118.402354 -289.981386)
		(end 118.332758 -289.940746)
		(width 0.1143)
		(layer "In6.Cu")
		(net "P5E_CPU1_P2_RX_DN<6>")
	)
	(segment
		(start 118.335298 -287.390078)
		(end 118.402354 -287.350962)
		(width 0.1143)
		(layer "In6.Cu")
		(net "P5E_CPU1_P2_RX_DN<6>")
	)
	(segment
		(start 133.770116 -320.315336)
		(end 133.77037 -320.315336)
		(width 0.14224)
		(layer "In6.Cu")
		(net "P5E_CPU1_P2_RX_DN<6>")
	)
	(segment
		(start 139.313158 -341.743792)
		(end 139.307316 -341.726266)
		(width 0.14224)
		(layer "In6.Cu")
		(net "P5E_CPU1_P2_RX_DN<6>")
	)
	(segment
		(start 154.077416 -378.577094)
		(end 154.178254 -378.411486)
		(width 0.14224)
		(layer "In6.Cu")
		(net "P5E_CPU1_P2_RX_DN<6>")
	)
	(segment
		(start 154.444446 -379.507496)
		(end 154.343862 -379.092968)
		(width 0.14224)
		(layer "In6.Cu")
		(net "P5E_CPU1_P2_RX_DN<6>")
	)
	(segment
		(start 154.609546 -380.769114)
		(end 154.710638 -380.603506)
		(width 0.14224)
		(layer "In6.Cu")
		(net "P5E_CPU1_P2_RX_DN<6>")
	)
	(segment
		(start 118.860062 -284.92831)
		(end 118.860316 -284.92831)
		(width 0.1143)
		(layer "In6.Cu")
		(net "P5E_CPU1_P2_RX_DN<6>")
	)
	(segment
		(start 129.964434 -313.871356)
		(end 123.683268 -306.210462)
		(width 0.14224)
		(layer "In6.Cu")
		(net "P5E_CPU1_P2_RX_DN<6>")
	)
	(segment
		(start 153.25598 -371.263672)
		(end 153.25598 -368.318288)
		(width 0.14224)
		(layer "In6.Cu")
		(net "P5E_CPU1_P2_RX_DN<6>")
	)
	(segment
		(start 118.402354 -291.601398)
		(end 118.332758 -291.560758)
		(width 0.1143)
		(layer "In6.Cu")
		(net "P5E_CPU1_P2_RX_DN<6>")
	)
	(segment
		(start 118.371874 -288.343848)
		(end 118.332758 -288.320988)
		(width 0.1143)
		(layer "In6.Cu")
		(net "P5E_CPU1_P2_RX_DN<6>")
	)
	(segment
		(start 118.873524 -295.651936)
		(end 118.84787 -295.637204)
		(width 0.1143)
		(layer "In6.Cu")
		(net "P5E_CPU1_P2_RX_DN<6>")
	)
	(segment
		(start 153.198576 -368.106198)
		(end 142.379192 -349.521272)
		(width 0.14224)
		(layer "In6.Cu")
		(net "P5E_CPU1_P2_RX_DN<6>")
	)
	(segment
		(start 118.404386 -288.362644)
		(end 118.371874 -288.343848)
		(width 0.1143)
		(layer "In6.Cu")
		(net "P5E_CPU1_P2_RX_DN<6>")
	)
	(segment
		(start 154.178254 -378.411486)
		(end 153.14676 -374.160034)
		(width 0.14224)
		(layer "In6.Cu")
		(net "P5E_CPU1_P2_RX_DN<6>")
	)
	(segment
		(start 155.086304 -382.166368)
		(end 155.08605 -382.166368)
		(width 0.14224)
		(layer "In6.Cu")
		(net "P5E_CPU1_P2_RX_DN<6>")
	)
	(segment
		(start 154.710638 -380.603506)
		(end 154.610054 -380.188978)
		(width 0.14224)
		(layer "In6.Cu")
		(net "P5E_CPU1_P2_RX_DN<6>")
	)
	(segment
		(start 119.312436 -284.128464)
		(end 119.313706 -284.127702)
		(width 0.1143)
		(layer "In6.Cu")
		(net "P5E_CPU1_P2_RX_DN<6>")
	)
	(segment
		(start 118.854982 -284.931612)
		(end 118.854982 -284.931358)
		(width 0.1143)
		(layer "In6.Cu")
		(net "P5E_CPU1_P2_RX_DN<6>")
	)
	(segment
		(start 119.313706 -284.127702)
		(end 119.315738 -284.126686)
		(width 0.1143)
		(layer "In6.Cu")
		(net "P5E_CPU1_P2_RX_DN<6>")
	)
	(segment
		(start 118.840758 -295.63314)
		(end 118.802658 -295.610788)
		(width 0.1143)
		(layer "In6.Cu")
		(net "P5E_CPU1_P2_RX_DN<6>")
	)
	(segment
		(start 154.782266 -384.234944)
		(end 155.086304 -383.93116)
		(width 0.14224)
		(layer "In6.Cu")
		(net "P5E_CPU1_P2_RX_DN<6>")
	)
	(segment
		(start 154.444192 -380.087886)
		(end 154.343608 -379.673104)
		(width 0.14224)
		(layer "In6.Cu")
		(net "P5E_CPU1_P2_RX_DN<6>")
	)
	(segment
		(start 122.724672 -304.772568)
		(end 119.857012 -300.471586)
		(width 0.14224)
		(layer "In6.Cu")
		(net "P5E_CPU1_P2_RX_DN<6>")
	)
	(segment
		(start 119.029734 -295.955974)
		(end 119.02948 -295.956228)
		(width 0.1143)
		(layer "In6.Cu")
		(net "P5E_CPU1_P2_RX_DN<6>")
	)
	(segment
		(start 119.311674 -284.128972)
		(end 119.312436 -284.128464)
		(width 0.1143)
		(layer "In6.Cu")
		(net "P5E_CPU1_P2_RX_DN<6>")
	)
	(segment
		(start 154.972766 -385.404868)
		(end 155.094432 -385.334764)
		(width 0.14224)
		(layer "In6.Cu")
		(net "P5E_CPU1_P2_RX_DN<6>")
	)
	(segment
		(start 131.774184 -316.581028)
		(end 129.964434 -313.871356)
		(width 0.14224)
		(layer "In6.Cu")
		(net "P5E_CPU1_P2_RX_DN<6>")
	)
	(segment
		(start 135.76681 -324.049898)
		(end 133.770116 -320.315336)
		(width 0.14224)
		(layer "In6.Cu")
		(net "P5E_CPU1_P2_RX_DN<6>")
	)
	(segment
		(start 153.25598 -368.318288)
		(end 153.255726 -368.318542)
		(width 0.14224)
		(layer "In6.Cu")
		(net "P5E_CPU1_P2_RX_DN<6>")
	)
	(segment
		(start 122.724672 -304.772822)
		(end 122.724672 -304.772568)
		(width 0.14224)
		(layer "In6.Cu")
		(net "P5E_CPU1_P2_RX_DN<6>")
	)
	(segment
		(start 119.029734 -296.007028)
		(end 119.029734 -295.955974)
		(width 0.1143)
		(layer "In6.Cu")
		(net "P5E_CPU1_P2_RX_DN<6>")
	)
	(segment
		(start 119.301768 -284.135068)
		(end 119.311674 -284.128972)
		(width 0.1143)
		(layer "In6.Cu")
		(net "P5E_CPU1_P2_RX_DN<6>")
	)
	(segment
		(start 154.77744 -384.84683)
		(end 154.782266 -384.234944)
		(width 0.14224)
		(layer "In6.Cu")
		(net "P5E_CPU1_P2_RX_DN<6>")
	)
	(segment
		(start 118.98376 -296.353738)
		(end 118.98376 -296.32529)
		(width 0.1143)
		(layer "In6.Cu")
		(net "P5E_CPU1_P2_RX_DN<6>")
	)
	(segment
		(start 154.875992 -381.284988)
		(end 154.876246 -381.284988)
		(width 0.14224)
		(layer "In6.Cu")
		(net "P5E_CPU1_P2_RX_DN<6>")
	)
	(segment
		(start 123.683268 -306.210462)
		(end 122.724672 -304.772822)
		(width 0.14224)
		(layer "In6.Cu")
		(net "P5E_CPU1_P2_RX_DN<6>")
	)
	(segment
		(start 155.082748 -382.13665)
		(end 154.875992 -381.284988)
		(width 0.14224)
		(layer "In6.Cu")
		(net "P5E_CPU1_P2_RX_DN<6>")
	)
	(segment
		(start 139.307316 -341.726266)
		(end 135.823706 -324.208394)
		(width 0.14224)
		(layer "In6.Cu")
		(net "P5E_CPU1_P2_RX_DN<6>")
	)
	(segment
		(start 118.332758 -289.011614)
		(end 118.402354 -288.970974)
		(width 0.1143)
		(layer "In6.Cu")
		(net "P5E_CPU1_P2_RX_DN<6>")
	)
	(arc
		(start 153.255726 -368.318542)
		(mid 153.241222 -368.208583)
		(end 153.198576 -368.106198)
		(width 0.14224)
		(layer "In6.Cu")
		(net "P5E_CPU1_P2_RX_DN<6>")
	)
	(arc
		(start 118.846854 -285.914338)
		(mid 118.561413 -285.429911)
		(end 118.839488 -284.941264)
		(width 0.1143)
		(layer "In6.Cu")
		(net "P5E_CPU1_P2_RX_DN<6>")
	)
	(arc
		(start 119.02948 -295.956228)
		(mid 119.025445 -295.901664)
		(end 119.013478 -295.848278)
		(width 0.1143)
		(layer "In6.Cu")
		(net "P5E_CPU1_P2_RX_DN<6>")
	)
	(arc
		(start 119.315992 -284.126432)
		(mid 119.450418 -283.990856)
		(end 119.499634 -283.806392)
		(width 0.1143)
		(layer "In6.Cu")
		(net "P5E_CPU1_P2_RX_DN<6>")
	)
	(arc
		(start 119.013478 -295.848278)
		(mid 118.99252 -295.794134)
		(end 118.96344 -295.743884)
		(width 0.1143)
		(layer "In6.Cu")
		(net "P5E_CPU1_P2_RX_DN<6>")
	)
	(arc
		(start 118.871746 -286.541718)
		(mid 119.029156 -286.221291)
		(end 118.846854 -285.914338)
		(width 0.1143)
		(layer "In6.Cu")
		(net "P5E_CPU1_P2_RX_DN<6>")
	)
	(arc
		(start 119.03329 -284.610556)
		(mid 119.10505 -284.337538)
		(end 119.301768 -284.135068)
		(width 0.1143)
		(layer "In6.Cu")
		(net "P5E_CPU1_P2_RX_DN<6>")
	)
	(arc
		(start 118.802658 -295.610788)
		(mid 118.623845 -295.408438)
		(end 118.559326 -295.146222)
		(width 0.1143)
		(layer "In6.Cu")
		(net "P5E_CPU1_P2_RX_DN<6>")
	)
	(arc
		(start 155.08605 -382.166368)
		(mid 155.085286 -382.15141)
		(end 155.082748 -382.13665)
		(width 0.14224)
		(layer "In6.Cu")
		(net "P5E_CPU1_P2_RX_DN<6>")
	)
	(arc
		(start 118.332758 -289.940746)
		(mid 118.089431 -289.47618)
		(end 118.332758 -289.011614)
		(width 0.1143)
		(layer "In6.Cu")
		(net "P5E_CPU1_P2_RX_DN<6>")
	)
	(arc
		(start 118.860316 -284.92831)
		(mid 118.986909 -284.801458)
		(end 119.03329 -284.628336)
		(width 0.1143)
		(layer "In6.Cu")
		(net "P5E_CPU1_P2_RX_DN<6>")
	)
	(arc
		(start 118.96344 -295.743884)
		(mid 118.922457 -295.694022)
		(end 118.873524 -295.651936)
		(width 0.1143)
		(layer "In6.Cu")
		(net "P5E_CPU1_P2_RX_DN<6>")
	)
	(arc
		(start 118.089426 -287.856422)
		(mid 118.154662 -287.592831)
		(end 118.335298 -287.390078)
		(width 0.1143)
		(layer "In6.Cu")
		(net "P5E_CPU1_P2_RX_DN<6>")
	)
	(arc
		(start 119.138446 -298.726606)
		(mid 119.022803 -298.343148)
		(end 118.98376 -297.94454)
		(width 0.14224)
		(layer "In6.Cu")
		(net "P5E_CPU1_P2_RX_DN<6>")
	)
	(arc
		(start 118.402354 -290.590986)
		(mid 118.559331 -290.286186)
		(end 118.402354 -289.981386)
		(width 0.1143)
		(layer "In6.Cu")
		(net "P5E_CPU1_P2_RX_DN<6>")
	)
	(arc
		(start 118.402354 -287.350962)
		(mid 118.517781 -287.217586)
		(end 118.559326 -287.046162)
		(width 0.1143)
		(layer "In6.Cu")
		(net "P5E_CPU1_P2_RX_DN<6>")
	)
	(arc
		(start 118.402354 -292.210998)
		(mid 118.559331 -291.906198)
		(end 118.402354 -291.601398)
		(width 0.1143)
		(layer "In6.Cu")
		(net "P5E_CPU1_P2_RX_DN<6>")
	)
	(arc
		(start 118.332758 -291.560758)
		(mid 118.089431 -291.096192)
		(end 118.332758 -290.631626)
		(width 0.1143)
		(layer "In6.Cu")
		(net "P5E_CPU1_P2_RX_DN<6>")
	)
	(arc
		(start 135.823706 -324.208394)
		(mid 135.801091 -324.127052)
		(end 135.76681 -324.049898)
		(width 0.14224)
		(layer "In6.Cu")
		(net "P5E_CPU1_P2_RX_DN<6>")
	)
	(arc
		(start 118.332758 -293.18077)
		(mid 118.089431 -292.716204)
		(end 118.332758 -292.251638)
		(width 0.1143)
		(layer "In6.Cu")
		(net "P5E_CPU1_P2_RX_DN<6>")
	)
	(arc
		(start 118.332758 -294.800782)
		(mid 118.089431 -294.336216)
		(end 118.332758 -293.87165)
		(width 0.1143)
		(layer "In6.Cu")
		(net "P5E_CPU1_P2_RX_DN<6>")
	)
	(arc
		(start 118.332758 -288.320988)
		(mid 118.153945 -288.118638)
		(end 118.089426 -287.856422)
		(width 0.1143)
		(layer "In6.Cu")
		(net "P5E_CPU1_P2_RX_DN<6>")
	)
	(arc
		(start 118.559326 -288.666174)
		(mid 118.51836 -288.495768)
		(end 118.404386 -288.362644)
		(width 0.1143)
		(layer "In6.Cu")
		(net "P5E_CPU1_P2_RX_DN<6>")
	)
	(arc
		(start 119.499634 -283.806392)
		(mid 119.564452 -283.543403)
		(end 119.744236 -283.34081)
		(width 0.1143)
		(layer "In6.Cu")
		(net "P5E_CPU1_P2_RX_DN<6>")
	)
	(arc
		(start 118.559326 -287.046162)
		(mid 118.623841 -286.783943)
		(end 118.802658 -286.581596)
		(width 0.1143)
		(layer "In6.Cu")
		(net "P5E_CPU1_P2_RX_DN<6>")
	)
	(arc
		(start 119.812308 -283.301186)
		(mid 119.910073 -283.19821)
		(end 119.962422 -283.066236)
		(width 0.1143)
		(layer "In6.Cu")
		(net "P5E_CPU1_P2_RX_DN<6>")
	)
	(arc
		(start 118.402354 -288.970974)
		(mid 118.517781 -288.837598)
		(end 118.559326 -288.666174)
		(width 0.1143)
		(layer "In6.Cu")
		(net "P5E_CPU1_P2_RX_DN<6>")
	)
	(arc
		(start 153.14676 -374.160034)
		(mid 153.10785 -373.923232)
		(end 153.10485 -373.683276)
		(width 0.14224)
		(layer "In6.Cu")
		(net "P5E_CPU1_P2_RX_DN<6>")
	)
	(arc
		(start 118.402354 -293.83101)
		(mid 118.559331 -293.52621)
		(end 118.402354 -293.22141)
		(width 0.1143)
		(layer "In6.Cu")
		(net "P5E_CPU1_P2_RX_DN<6>")
	)
	(arc
		(start 118.559326 -295.146222)
		(mid 118.517777 -294.9748)
		(end 118.402354 -294.841422)
		(width 0.1143)
		(layer "In6.Cu")
		(net "P5E_CPU1_P2_RX_DN<6>")
	)
	(segment
		(start 152.898348 -385.31038)
		(end 153.419048 -385.31038)
		(width 0.127)
		(layer "F.Cu")
		(net "P5E_CPU1_P2_RX_DN<5>")
	)
	(segment
		(start 116.30787 -284.35046)
		(end 116.774722 -284.616398)
		(width 0.12954)
		(layer "F.Cu")
		(net "P5E_CPU1_P2_RX_DN<5>")
	)
	(segment
		(start 138.476482 -342.605868)
		(end 134.845806 -324.353174)
		(width 0.14224)
		(layer "In6.Cu")
		(net "P5E_CPU1_P2_RX_DN<5>")
	)
	(segment
		(start 117.4623 -293.22141)
		(end 117.392704 -293.18077)
		(width 0.1143)
		(layer "In6.Cu")
		(net "P5E_CPU1_P2_RX_DN<5>")
	)
	(segment
		(start 151.355044 -371.000274)
		(end 150.911306 -370.556536)
		(width 0.14224)
		(layer "In6.Cu")
		(net "P5E_CPU1_P2_RX_DN<5>")
	)
	(segment
		(start 152.863804 -378.46762)
		(end 151.442674 -373.55526)
		(width 0.14224)
		(layer "In6.Cu")
		(net "P5E_CPU1_P2_RX_DN<5>")
	)
	(segment
		(start 117.90172 -295.633648)
		(end 117.900704 -295.63314)
		(width 0.1143)
		(layer "In6.Cu")
		(net "P5E_CPU1_P2_RX_DN<5>")
	)
	(segment
		(start 117.862604 -286.581596)
		(end 117.931438 -286.541718)
		(width 0.1143)
		(layer "In6.Cu")
		(net "P5E_CPU1_P2_RX_DN<5>")
	)
	(segment
		(start 153.577544 -384.84683)
		(end 153.58237 -384.234944)
		(width 0.14224)
		(layer "In6.Cu")
		(net "P5E_CPU1_P2_RX_DN<5>")
	)
	(segment
		(start 140.528294 -348.421452)
		(end 139.74953 -346.648278)
		(width 0.14224)
		(layer "In6.Cu")
		(net "P5E_CPU1_P2_RX_DN<5>")
	)
	(segment
		(start 150.654258 -370.384832)
		(end 150.351744 -370.25961)
		(width 0.14224)
		(layer "In6.Cu")
		(net "P5E_CPU1_P2_RX_DN<5>")
	)
	(segment
		(start 117.4623 -294.841422)
		(end 117.392704 -294.800782)
		(width 0.1143)
		(layer "In6.Cu")
		(net "P5E_CPU1_P2_RX_DN<5>")
	)
	(segment
		(start 117.90426 -285.912814)
		(end 117.900196 -285.910528)
		(width 0.1143)
		(layer "In6.Cu")
		(net "P5E_CPU1_P2_RX_DN<5>")
	)
	(segment
		(start 149.740874 -369.316762)
		(end 149.740874 -366.79124)
		(width 0.14224)
		(layer "In6.Cu")
		(net "P5E_CPU1_P2_RX_DN<5>")
	)
	(segment
		(start 117.392704 -293.87165)
		(end 117.4623 -293.83101)
		(width 0.1143)
		(layer "In6.Cu")
		(net "P5E_CPU1_P2_RX_DN<5>")
	)
	(segment
		(start 117.392704 -292.251638)
		(end 117.4623 -292.210998)
		(width 0.1143)
		(layer "In6.Cu")
		(net "P5E_CPU1_P2_RX_DN<5>")
	)
	(segment
		(start 153.841196 -381.84455)
		(end 153.686256 -381.308356)
		(width 0.14224)
		(layer "In6.Cu")
		(net "P5E_CPU1_P2_RX_DN<5>")
	)
	(segment
		(start 152.770332 -378.637546)
		(end 152.863804 -378.46762)
		(width 0.14224)
		(layer "In6.Cu")
		(net "P5E_CPU1_P2_RX_DN<5>")
	)
	(segment
		(start 119.064532 -301.033942)
		(end 118.211346 -298.972986)
		(width 0.14224)
		(layer "In6.Cu")
		(net "P5E_CPU1_P2_RX_DN<5>")
	)
	(segment
		(start 153.177494 -379.551184)
		(end 153.05913 -379.141482)
		(width 0.14224)
		(layer "In6.Cu")
		(net "P5E_CPU1_P2_RX_DN<5>")
	)
	(segment
		(start 120.956832 -303.865788)
		(end 120.956578 -303.865534)
		(width 0.14224)
		(layer "In6.Cu")
		(net "P5E_CPU1_P2_RX_DN<5>")
	)
	(segment
		(start 153.49093 -380.634748)
		(end 153.372566 -380.225046)
		(width 0.14224)
		(layer "In6.Cu")
		(net "P5E_CPU1_P2_RX_DN<5>")
	)
	(segment
		(start 117.900704 -295.63314)
		(end 117.862604 -295.610788)
		(width 0.1143)
		(layer "In6.Cu")
		(net "P5E_CPU1_P2_RX_DN<5>")
	)
	(segment
		(start 132.902706 -320.67881)
		(end 131.000754 -317.120016)
		(width 0.14224)
		(layer "In6.Cu")
		(net "P5E_CPU1_P2_RX_DN<5>")
	)
	(segment
		(start 118.04396 -298.130976)
		(end 118.04396 -296.353738)
		(width 0.14224)
		(layer "In6.Cu")
		(net "P5E_CPU1_P2_RX_DN<5>")
	)
	(segment
		(start 117.902482 -295.634156)
		(end 117.90172 -295.633648)
		(width 0.1143)
		(layer "In6.Cu")
		(net "P5E_CPU1_P2_RX_DN<5>")
	)
	(segment
		(start 129.234692 -314.476384)
		(end 122.841258 -306.68595)
		(width 0.14224)
		(layer "In6.Cu")
		(net "P5E_CPU1_P2_RX_DN<5>")
	)
	(segment
		(start 153.894536 -385.334764)
		(end 153.894536 -385.163822)
		(width 0.14224)
		(layer "In6.Cu")
		(net "P5E_CPU1_P2_RX_DN<5>")
	)
	(segment
		(start 153.083768 -379.72111)
		(end 153.177494 -379.551184)
		(width 0.14224)
		(layer "In6.Cu")
		(net "P5E_CPU1_P2_RX_DN<5>")
	)
	(segment
		(start 139.74953 -346.648278)
		(end 138.476482 -342.605868)
		(width 0.14224)
		(layer "In6.Cu")
		(net "P5E_CPU1_P2_RX_DN<5>")
	)
	(segment
		(start 151.442674 -373.55526)
		(end 151.442674 -371.211856)
		(width 0.14224)
		(layer "In6.Cu")
		(net "P5E_CPU1_P2_RX_DN<5>")
	)
	(segment
		(start 149.604222 -366.22228)
		(end 140.528294 -348.421452)
		(width 0.14224)
		(layer "In6.Cu")
		(net "P5E_CPU1_P2_RX_DN<5>")
	)
	(segment
		(start 117.392704 -289.011614)
		(end 117.4623 -288.970974)
		(width 0.1143)
		(layer "In6.Cu")
		(net "P5E_CPU1_P2_RX_DN<5>")
	)
	(segment
		(start 153.686256 -381.308356)
		(end 153.516076 -381.214884)
		(width 0.14224)
		(layer "In6.Cu")
		(net "P5E_CPU1_P2_RX_DN<5>")
	)
	(segment
		(start 152.88895 -379.047756)
		(end 152.770332 -378.637546)
		(width 0.14224)
		(layer "In6.Cu")
		(net "P5E_CPU1_P2_RX_DN<5>")
	)
	(segment
		(start 131.000754 -317.120016)
		(end 129.234692 -314.476384)
		(width 0.14224)
		(layer "In6.Cu")
		(net "P5E_CPU1_P2_RX_DN<5>")
	)
	(segment
		(start 117.395244 -287.390078)
		(end 117.4623 -287.350962)
		(width 0.1143)
		(layer "In6.Cu")
		(net "P5E_CPU1_P2_RX_DN<5>")
	)
	(segment
		(start 117.906292 -295.636188)
		(end 117.903752 -295.634918)
		(width 0.1143)
		(layer "In6.Cu")
		(net "P5E_CPU1_P2_RX_DN<5>")
	)
	(segment
		(start 153.397458 -380.804674)
		(end 153.49093 -380.634748)
		(width 0.14224)
		(layer "In6.Cu")
		(net "P5E_CPU1_P2_RX_DN<5>")
	)
	(segment
		(start 153.372566 -380.225046)
		(end 153.202386 -380.13132)
		(width 0.14224)
		(layer "In6.Cu")
		(net "P5E_CPU1_P2_RX_DN<5>")
	)
	(segment
		(start 153.202386 -380.13132)
		(end 153.083768 -379.72111)
		(width 0.14224)
		(layer "In6.Cu")
		(net "P5E_CPU1_P2_RX_DN<5>")
	)
	(segment
		(start 153.77287 -385.404868)
		(end 153.894536 -385.334764)
		(width 0.14224)
		(layer "In6.Cu")
		(net "P5E_CPU1_P2_RX_DN<5>")
	)
	(segment
		(start 117.903752 -295.634918)
		(end 117.902482 -295.634156)
		(width 0.1143)
		(layer "In6.Cu")
		(net "P5E_CPU1_P2_RX_DN<5>")
	)
	(segment
		(start 117.4623 -289.981386)
		(end 117.392704 -289.940746)
		(width 0.1143)
		(layer "In6.Cu")
		(net "P5E_CPU1_P2_RX_DN<5>")
	)
	(segment
		(start 153.516076 -381.214884)
		(end 153.397458 -380.804674)
		(width 0.14224)
		(layer "In6.Cu")
		(net "P5E_CPU1_P2_RX_DN<5>")
	)
	(segment
		(start 117.155468 -284.699202)
		(end 117.072664 -284.616398)
		(width 0.1143)
		(layer "In6.Cu")
		(net "P5E_CPU1_P2_RX_DN<5>")
	)
	(segment
		(start 153.886408 -383.93116)
		(end 153.886408 -382.164082)
		(width 0.14224)
		(layer "In6.Cu")
		(net "P5E_CPU1_P2_RX_DN<5>")
	)
	(segment
		(start 117.43182 -288.343848)
		(end 117.392704 -288.320988)
		(width 0.1143)
		(layer "In6.Cu")
		(net "P5E_CPU1_P2_RX_DN<5>")
	)
	(segment
		(start 118.08968 -296.27957)
		(end 118.08968 -295.956228)
		(width 0.1143)
		(layer "In6.Cu")
		(net "P5E_CPU1_P2_RX_DN<5>")
	)
	(segment
		(start 117.4623 -291.601398)
		(end 117.392704 -291.560758)
		(width 0.1143)
		(layer "In6.Cu")
		(net "P5E_CPU1_P2_RX_DN<5>")
	)
	(segment
		(start 117.93347 -295.651936)
		(end 117.907816 -295.637204)
		(width 0.1143)
		(layer "In6.Cu")
		(net "P5E_CPU1_P2_RX_DN<5>")
	)
	(segment
		(start 153.419048 -385.31038)
		(end 153.772362 -385.405376)
		(width 0.14224)
		(layer "In6.Cu")
		(net "P5E_CPU1_P2_RX_DN<5>")
	)
	(segment
		(start 117.907816 -295.637204)
		(end 117.906292 -295.636188)
		(width 0.1143)
		(layer "In6.Cu")
		(net "P5E_CPU1_P2_RX_DN<5>")
	)
	(segment
		(start 134.804912 -324.237858)
		(end 132.902706 -320.67881)
		(width 0.14224)
		(layer "In6.Cu")
		(net "P5E_CPU1_P2_RX_DN<5>")
	)
	(segment
		(start 117.46357 -285.122366)
		(end 117.392704 -285.080964)
		(width 0.1143)
		(layer "In6.Cu")
		(net "P5E_CPU1_P2_RX_DN<5>")
	)
	(segment
		(start 120.956578 -303.865534)
		(end 119.064532 -301.033942)
		(width 0.14224)
		(layer "In6.Cu")
		(net "P5E_CPU1_P2_RX_DN<5>")
	)
	(segment
		(start 153.58237 -384.234944)
		(end 153.886408 -383.93116)
		(width 0.14224)
		(layer "In6.Cu")
		(net "P5E_CPU1_P2_RX_DN<5>")
	)
	(segment
		(start 149.977856 -369.92179)
		(end 149.818344 -369.624864)
		(width 0.14224)
		(layer "In6.Cu")
		(net "P5E_CPU1_P2_RX_DN<5>")
	)
	(segment
		(start 153.894536 -385.163822)
		(end 153.577544 -384.84683)
		(width 0.14224)
		(layer "In6.Cu")
		(net "P5E_CPU1_P2_RX_DN<5>")
	)
	(segment
		(start 117.392704 -290.631626)
		(end 117.4623 -290.590986)
		(width 0.1143)
		(layer "In6.Cu")
		(net "P5E_CPU1_P2_RX_DN<5>")
	)
	(segment
		(start 122.841258 -306.68595)
		(end 120.956832 -303.865788)
		(width 0.14224)
		(layer "In6.Cu")
		(net "P5E_CPU1_P2_RX_DN<5>")
	)
	(segment
		(start 153.772362 -385.405376)
		(end 153.77287 -385.404868)
		(width 0.14224)
		(layer "In6.Cu")
		(net "P5E_CPU1_P2_RX_DN<5>")
	)
	(segment
		(start 117.072664 -284.616398)
		(end 116.774722 -284.616398)
		(width 0.1143)
		(layer "In6.Cu")
		(net "P5E_CPU1_P2_RX_DN<5>")
	)
	(segment
		(start 118.04396 -296.353738)
		(end 118.04396 -296.32529)
		(width 0.1143)
		(layer "In6.Cu")
		(net "P5E_CPU1_P2_RX_DN<5>")
	)
	(segment
		(start 118.04396 -296.32529)
		(end 118.08968 -296.27957)
		(width 0.1143)
		(layer "In6.Cu")
		(net "P5E_CPU1_P2_RX_DN<5>")
	)
	(segment
		(start 153.05913 -379.141482)
		(end 152.88895 -379.047756)
		(width 0.14224)
		(layer "In6.Cu")
		(net "P5E_CPU1_P2_RX_DN<5>")
	)
	(segment
		(start 117.464332 -288.362644)
		(end 117.43182 -288.343848)
		(width 0.1143)
		(layer "In6.Cu")
		(net "P5E_CPU1_P2_RX_DN<5>")
	)
	(arc
		(start 117.392704 -289.940746)
		(mid 117.149377 -289.47618)
		(end 117.392704 -289.011614)
		(width 0.1143)
		(layer "In6.Cu")
		(net "P5E_CPU1_P2_RX_DN<5>")
	)
	(arc
		(start 117.900196 -285.910528)
		(mid 117.694739 -285.706214)
		(end 117.619526 -285.426404)
		(width 0.1143)
		(layer "In6.Cu")
		(net "P5E_CPU1_P2_RX_DN<5>")
	)
	(arc
		(start 117.392704 -288.320988)
		(mid 117.213891 -288.118638)
		(end 117.149372 -287.856422)
		(width 0.1143)
		(layer "In6.Cu")
		(net "P5E_CPU1_P2_RX_DN<5>")
	)
	(arc
		(start 117.392704 -294.800782)
		(mid 117.149377 -294.336216)
		(end 117.392704 -293.87165)
		(width 0.1143)
		(layer "In6.Cu")
		(net "P5E_CPU1_P2_RX_DN<5>")
	)
	(arc
		(start 118.023386 -295.743884)
		(mid 117.982403 -295.694022)
		(end 117.93347 -295.651936)
		(width 0.1143)
		(layer "In6.Cu")
		(net "P5E_CPU1_P2_RX_DN<5>")
	)
	(arc
		(start 149.740874 -366.79124)
		(mid 149.706231 -366.49867)
		(end 149.604222 -366.22228)
		(width 0.14224)
		(layer "In6.Cu")
		(net "P5E_CPU1_P2_RX_DN<5>")
	)
	(arc
		(start 117.862604 -295.610788)
		(mid 117.683791 -295.408438)
		(end 117.619272 -295.146222)
		(width 0.1143)
		(layer "In6.Cu")
		(net "P5E_CPU1_P2_RX_DN<5>")
	)
	(arc
		(start 118.211346 -298.972986)
		(mid 118.086222 -298.560218)
		(end 118.04396 -298.130976)
		(width 0.14224)
		(layer "In6.Cu")
		(net "P5E_CPU1_P2_RX_DN<5>")
	)
	(arc
		(start 117.4623 -290.590986)
		(mid 117.619277 -290.286186)
		(end 117.4623 -289.981386)
		(width 0.1143)
		(layer "In6.Cu")
		(net "P5E_CPU1_P2_RX_DN<5>")
	)
	(arc
		(start 117.392704 -285.080964)
		(mid 117.240717 -284.924456)
		(end 117.159278 -284.722062)
		(width 0.1143)
		(layer "In6.Cu")
		(net "P5E_CPU1_P2_RX_DN<5>")
	)
	(arc
		(start 153.886408 -382.164082)
		(mid 153.875063 -382.002723)
		(end 153.841196 -381.84455)
		(width 0.14224)
		(layer "In6.Cu")
		(net "P5E_CPU1_P2_RX_DN<5>")
	)
	(arc
		(start 117.619272 -287.046162)
		(mid 117.683787 -286.783943)
		(end 117.862604 -286.581596)
		(width 0.1143)
		(layer "In6.Cu")
		(net "P5E_CPU1_P2_RX_DN<5>")
	)
	(arc
		(start 117.619272 -295.146222)
		(mid 117.577723 -294.9748)
		(end 117.4623 -294.841422)
		(width 0.1143)
		(layer "In6.Cu")
		(net "P5E_CPU1_P2_RX_DN<5>")
	)
	(arc
		(start 118.08968 -295.956228)
		(mid 118.07263 -295.845037)
		(end 118.023386 -295.743884)
		(width 0.1143)
		(layer "In6.Cu")
		(net "P5E_CPU1_P2_RX_DN<5>")
	)
	(arc
		(start 117.149372 -287.856422)
		(mid 117.214608 -287.592831)
		(end 117.395244 -287.390078)
		(width 0.1143)
		(layer "In6.Cu")
		(net "P5E_CPU1_P2_RX_DN<5>")
	)
	(arc
		(start 117.392704 -293.18077)
		(mid 117.149377 -292.716204)
		(end 117.392704 -292.251638)
		(width 0.1143)
		(layer "In6.Cu")
		(net "P5E_CPU1_P2_RX_DN<5>")
	)
	(arc
		(start 117.4623 -287.350962)
		(mid 117.577727 -287.217586)
		(end 117.619272 -287.046162)
		(width 0.1143)
		(layer "In6.Cu")
		(net "P5E_CPU1_P2_RX_DN<5>")
	)
	(arc
		(start 117.4623 -293.83101)
		(mid 117.619277 -293.52621)
		(end 117.4623 -293.22141)
		(width 0.1143)
		(layer "In6.Cu")
		(net "P5E_CPU1_P2_RX_DN<5>")
	)
	(arc
		(start 117.619526 -285.426404)
		(mid 117.578267 -285.255547)
		(end 117.46357 -285.122366)
		(width 0.1143)
		(layer "In6.Cu")
		(net "P5E_CPU1_P2_RX_DN<5>")
	)
	(arc
		(start 117.159278 -284.722062)
		(mid 117.157255 -284.710652)
		(end 117.155468 -284.699202)
		(width 0.1143)
		(layer "In6.Cu")
		(net "P5E_CPU1_P2_RX_DN<5>")
	)
	(arc
		(start 117.931438 -286.541718)
		(mid 118.088898 -286.219921)
		(end 117.90426 -285.912814)
		(width 0.1143)
		(layer "In6.Cu")
		(net "P5E_CPU1_P2_RX_DN<5>")
	)
	(arc
		(start 117.4623 -292.210998)
		(mid 117.619277 -291.906198)
		(end 117.4623 -291.601398)
		(width 0.1143)
		(layer "In6.Cu")
		(net "P5E_CPU1_P2_RX_DN<5>")
	)
	(arc
		(start 134.845806 -324.353174)
		(mid 134.829476 -324.294056)
		(end 134.804912 -324.237858)
		(width 0.14224)
		(layer "In6.Cu")
		(net "P5E_CPU1_P2_RX_DN<5>")
	)
	(arc
		(start 151.442674 -371.211856)
		(mid 151.419883 -371.097367)
		(end 151.355044 -371.000274)
		(width 0.14224)
		(layer "In6.Cu")
		(net "P5E_CPU1_P2_RX_DN<5>")
	)
	(arc
		(start 117.392704 -291.560758)
		(mid 117.149377 -291.096192)
		(end 117.392704 -290.631626)
		(width 0.1143)
		(layer "In6.Cu")
		(net "P5E_CPU1_P2_RX_DN<5>")
	)
	(arc
		(start 117.4623 -288.970974)
		(mid 117.577727 -288.837598)
		(end 117.619272 -288.666174)
		(width 0.1143)
		(layer "In6.Cu")
		(net "P5E_CPU1_P2_RX_DN<5>")
	)
	(arc
		(start 150.911306 -370.556536)
		(mid 150.791256 -370.457996)
		(end 150.654258 -370.384832)
		(width 0.14224)
		(layer "In6.Cu")
		(net "P5E_CPU1_P2_RX_DN<5>")
	)
	(arc
		(start 149.818344 -369.624864)
		(mid 149.760548 -369.475607)
		(end 149.740874 -369.316762)
		(width 0.14224)
		(layer "In6.Cu")
		(net "P5E_CPU1_P2_RX_DN<5>")
	)
	(arc
		(start 117.619272 -288.666174)
		(mid 117.578306 -288.495768)
		(end 117.464332 -288.362644)
		(width 0.1143)
		(layer "In6.Cu")
		(net "P5E_CPU1_P2_RX_DN<5>")
	)
	(arc
		(start 150.351744 -370.25961)
		(mid 150.135573 -370.123048)
		(end 149.977856 -369.92179)
		(width 0.14224)
		(layer "In6.Cu")
		(net "P5E_CPU1_P2_RX_DN<5>")
	)
	(segment
		(start 151.698198 -385.31038)
		(end 152.218898 -385.31038)
		(width 0.127)
		(layer "F.Cu")
		(net "P5E_CPU1_P2_RX_DN<4>")
	)
	(segment
		(start 116.30787 -285.970472)
		(end 116.774722 -286.23641)
		(width 0.12954)
		(layer "F.Cu")
		(net "P5E_CPU1_P2_RX_DN<4>")
	)
	(segment
		(start 152.38222 -384.234944)
		(end 152.686258 -383.93116)
		(width 0.14224)
		(layer "In6.Cu")
		(net "P5E_CPU1_P2_RX_DN<4>")
	)
	(segment
		(start 133.878828 -324.525386)
		(end 133.840728 -324.4215)
		(width 0.14224)
		(layer "In6.Cu")
		(net "P5E_CPU1_P2_RX_DN<4>")
	)
	(segment
		(start 116.969286 -295.637712)
		(end 116.923312 -295.611296)
		(width 0.1143)
		(layer "In6.Cu")
		(net "P5E_CPU1_P2_RX_DN<4>")
	)
	(segment
		(start 133.840728 -324.4215)
		(end 133.838442 -324.414896)
		(width 0.14224)
		(layer "In6.Cu")
		(net "P5E_CPU1_P2_RX_DN<4>")
	)
	(segment
		(start 116.48821 -287.370774)
		(end 116.493544 -287.367726)
		(width 0.1143)
		(layer "In6.Cu")
		(net "P5E_CPU1_P2_RX_DN<4>")
	)
	(segment
		(start 118.16969 -301.379128)
		(end 117.255544 -299.17263)
		(width 0.14224)
		(layer "In6.Cu")
		(net "P5E_CPU1_P2_RX_DN<4>")
	)
	(segment
		(start 151.38273 -378.371354)
		(end 151.258016 -377.962922)
		(width 0.14224)
		(layer "In6.Cu")
		(net "P5E_CPU1_P2_RX_DN<4>")
	)
	(segment
		(start 116.959126 -286.56026)
		(end 116.960142 -286.559752)
		(width 0.1143)
		(layer "In6.Cu")
		(net "P5E_CPU1_P2_RX_DN<4>")
	)
	(segment
		(start 116.522246 -294.841422)
		(end 116.45265 -294.800782)
		(width 0.1143)
		(layer "In6.Cu")
		(net "P5E_CPU1_P2_RX_DN<4>")
	)
	(segment
		(start 152.218898 -385.31038)
		(end 152.572212 -385.405376)
		(width 0.14224)
		(layer "In6.Cu")
		(net "P5E_CPU1_P2_RX_DN<4>")
	)
	(segment
		(start 117.149626 -296.007028)
		(end 117.149626 -295.952926)
		(width 0.1143)
		(layer "In6.Cu")
		(net "P5E_CPU1_P2_RX_DN<4>")
	)
	(segment
		(start 117.099334 -298.385738)
		(end 117.099334 -296.353738)
		(width 0.14224)
		(layer "In6.Cu")
		(net "P5E_CPU1_P2_RX_DN<4>")
	)
	(segment
		(start 152.686258 -383.93116)
		(end 152.686258 -382.384046)
		(width 0.14224)
		(layer "In6.Cu")
		(net "P5E_CPU1_P2_RX_DN<4>")
	)
	(segment
		(start 152.686258 -382.384046)
		(end 152.686004 -382.3843)
		(width 0.14224)
		(layer "In6.Cu")
		(net "P5E_CPU1_P2_RX_DN<4>")
	)
	(segment
		(start 116.45265 -290.631626)
		(end 116.522246 -290.590986)
		(width 0.1143)
		(layer "In6.Cu")
		(net "P5E_CPU1_P2_RX_DN<4>")
	)
	(segment
		(start 133.879082 -324.525894)
		(end 133.878828 -324.525386)
		(width 0.14224)
		(layer "In6.Cu")
		(net "P5E_CPU1_P2_RX_DN<4>")
	)
	(segment
		(start 137.633456 -343.398348)
		(end 133.879082 -324.525894)
		(width 0.14224)
		(layer "In6.Cu")
		(net "P5E_CPU1_P2_RX_DN<4>")
	)
	(segment
		(start 138.82624 -347.17482)
		(end 137.633456 -343.398348)
		(width 0.14224)
		(layer "In6.Cu")
		(net "P5E_CPU1_P2_RX_DN<4>")
	)
	(segment
		(start 116.45265 -292.251638)
		(end 116.522246 -292.210998)
		(width 0.1143)
		(layer "In6.Cu")
		(net "P5E_CPU1_P2_RX_DN<4>")
	)
	(segment
		(start 116.524278 -288.362644)
		(end 116.45265 -288.320988)
		(width 0.1143)
		(layer "In6.Cu")
		(net "P5E_CPU1_P2_RX_DN<4>")
	)
	(segment
		(start 151.71293 -379.449838)
		(end 151.588216 -379.041406)
		(width 0.14224)
		(layer "In6.Cu")
		(net "P5E_CPU1_P2_RX_DN<4>")
	)
	(segment
		(start 116.960142 -286.559752)
		(end 116.994432 -286.539686)
		(width 0.1143)
		(layer "In6.Cu")
		(net "P5E_CPU1_P2_RX_DN<4>")
	)
	(segment
		(start 152.572212 -385.405376)
		(end 152.57272 -385.404868)
		(width 0.14224)
		(layer "In6.Cu")
		(net "P5E_CPU1_P2_RX_DN<4>")
	)
	(segment
		(start 116.522246 -289.981386)
		(end 116.45265 -289.940746)
		(width 0.1143)
		(layer "In6.Cu")
		(net "P5E_CPU1_P2_RX_DN<4>")
	)
	(segment
		(start 152.694386 -385.163822)
		(end 152.377394 -384.84683)
		(width 0.14224)
		(layer "In6.Cu")
		(net "P5E_CPU1_P2_RX_DN<4>")
	)
	(segment
		(start 151.679148 -378.87021)
		(end 151.554434 -378.462286)
		(width 0.14224)
		(layer "In6.Cu")
		(net "P5E_CPU1_P2_RX_DN<4>")
	)
	(segment
		(start 117.099334 -296.353738)
		(end 117.099334 -296.32529)
		(width 0.1143)
		(layer "In6.Cu")
		(net "P5E_CPU1_P2_RX_DN<4>")
	)
	(segment
		(start 130.23088 -317.665862)
		(end 128.42367 -314.960254)
		(width 0.14224)
		(layer "In6.Cu")
		(net "P5E_CPU1_P2_RX_DN<4>")
	)
	(segment
		(start 116.45519 -287.390078)
		(end 116.48821 -287.370774)
		(width 0.1143)
		(layer "In6.Cu")
		(net "P5E_CPU1_P2_RX_DN<4>")
	)
	(segment
		(start 151.884634 -379.54077)
		(end 151.71293 -379.449838)
		(width 0.14224)
		(layer "In6.Cu")
		(net "P5E_CPU1_P2_RX_DN<4>")
	)
	(segment
		(start 117.072664 -286.23641)
		(end 116.774722 -286.23641)
		(width 0.1143)
		(layer "In6.Cu")
		(net "P5E_CPU1_P2_RX_DN<4>")
	)
	(segment
		(start 152.04313 -380.528322)
		(end 151.918162 -380.11989)
		(width 0.14224)
		(layer "In6.Cu")
		(net "P5E_CPU1_P2_RX_DN<4>")
	)
	(segment
		(start 117.145054 -296.0116)
		(end 117.149626 -296.007028)
		(width 0.1143)
		(layer "In6.Cu")
		(net "P5E_CPU1_P2_RX_DN<4>")
	)
	(segment
		(start 116.994432 -286.539686)
		(end 116.995194 -286.539178)
		(width 0.1143)
		(layer "In6.Cu")
		(net "P5E_CPU1_P2_RX_DN<4>")
	)
	(segment
		(start 117.099334 -296.32529)
		(end 117.145054 -296.27957)
		(width 0.1143)
		(layer "In6.Cu")
		(net "P5E_CPU1_P2_RX_DN<4>")
	)
	(segment
		(start 149.421596 -373.075454)
		(end 149.00021 -372.860062)
		(width 0.14224)
		(layer "In6.Cu")
		(net "P5E_CPU1_P2_RX_DN<4>")
	)
	(segment
		(start 116.45265 -289.011614)
		(end 116.522246 -288.970974)
		(width 0.1143)
		(layer "In6.Cu")
		(net "P5E_CPU1_P2_RX_DN<4>")
	)
	(segment
		(start 116.45265 -293.87165)
		(end 116.522246 -293.83101)
		(width 0.1143)
		(layer "In6.Cu")
		(net "P5E_CPU1_P2_RX_DN<4>")
	)
	(segment
		(start 152.009348 -379.948694)
		(end 151.884634 -379.54077)
		(width 0.14224)
		(layer "In6.Cu")
		(net "P5E_CPU1_P2_RX_DN<4>")
	)
	(segment
		(start 133.838442 -324.414896)
		(end 130.23088 -317.665862)
		(width 0.14224)
		(layer "In6.Cu")
		(net "P5E_CPU1_P2_RX_DN<4>")
	)
	(segment
		(start 148.332952 -372.34749)
		(end 148.279104 -372.287292)
		(width 0.14224)
		(layer "In6.Cu")
		(net "P5E_CPU1_P2_RX_DN<4>")
	)
	(segment
		(start 128.42367 -314.960254)
		(end 122.079258 -307.230272)
		(width 0.14224)
		(layer "In6.Cu")
		(net "P5E_CPU1_P2_RX_DN<4>")
	)
	(segment
		(start 116.679472 -295.146222)
		(end 116.679218 -295.146222)
		(width 0.1143)
		(layer "In6.Cu")
		(net "P5E_CPU1_P2_RX_DN<4>")
	)
	(segment
		(start 151.588216 -379.041406)
		(end 151.679148 -378.87021)
		(width 0.14224)
		(layer "In6.Cu")
		(net "P5E_CPU1_P2_RX_DN<4>")
	)
	(segment
		(start 147.57908 -368.765074)
		(end 147.57908 -367.003076)
		(width 0.14224)
		(layer "In6.Cu")
		(net "P5E_CPU1_P2_RX_DN<4>")
	)
	(segment
		(start 152.377394 -384.84683)
		(end 152.38222 -384.234944)
		(width 0.14224)
		(layer "In6.Cu")
		(net "P5E_CPU1_P2_RX_DN<4>")
	)
	(segment
		(start 152.694386 -385.334764)
		(end 152.694386 -385.163822)
		(width 0.14224)
		(layer "In6.Cu")
		(net "P5E_CPU1_P2_RX_DN<4>")
	)
	(segment
		(start 148.008086 -371.709442)
		(end 147.57908 -368.765074)
		(width 0.14224)
		(layer "In6.Cu")
		(net "P5E_CPU1_P2_RX_DN<4>")
	)
	(segment
		(start 150.324566 -374.445022)
		(end 149.470618 -373.119904)
		(width 0.14224)
		(layer "In6.Cu")
		(net "P5E_CPU1_P2_RX_DN<4>")
	)
	(segment
		(start 117.142514 -286.30626)
		(end 117.072664 -286.23641)
		(width 0.1143)
		(layer "In6.Cu")
		(net "P5E_CPU1_P2_RX_DN<4>")
	)
	(segment
		(start 147.57908 -367.003076)
		(end 138.82624 -347.17482)
		(width 0.14224)
		(layer "In6.Cu")
		(net "P5E_CPU1_P2_RX_DN<4>")
	)
	(segment
		(start 117.145054 -296.27957)
		(end 117.145054 -296.0116)
		(width 0.1143)
		(layer "In6.Cu")
		(net "P5E_CPU1_P2_RX_DN<4>")
	)
	(segment
		(start 122.079258 -307.230272)
		(end 118.16969 -301.379128)
		(width 0.14224)
		(layer "In6.Cu")
		(net "P5E_CPU1_P2_RX_DN<4>")
	)
	(segment
		(start 152.620726 -381.945642)
		(end 152.214834 -380.619254)
		(width 0.14224)
		(layer "In6.Cu")
		(net "P5E_CPU1_P2_RX_DN<4>")
	)
	(segment
		(start 151.348948 -377.791726)
		(end 150.324566 -374.445022)
		(width 0.14224)
		(layer "In6.Cu")
		(net "P5E_CPU1_P2_RX_DN<4>")
	)
	(segment
		(start 151.554434 -378.462286)
		(end 151.38273 -378.371354)
		(width 0.14224)
		(layer "In6.Cu")
		(net "P5E_CPU1_P2_RX_DN<4>")
	)
	(segment
		(start 152.57272 -385.404868)
		(end 152.694386 -385.334764)
		(width 0.14224)
		(layer "In6.Cu")
		(net "P5E_CPU1_P2_RX_DN<4>")
	)
	(segment
		(start 152.214834 -380.619254)
		(end 152.04313 -380.528322)
		(width 0.14224)
		(layer "In6.Cu")
		(net "P5E_CPU1_P2_RX_DN<4>")
	)
	(segment
		(start 116.522246 -293.22141)
		(end 116.45265 -293.18077)
		(width 0.1143)
		(layer "In6.Cu")
		(net "P5E_CPU1_P2_RX_DN<4>")
	)
	(segment
		(start 151.258016 -377.962922)
		(end 151.348948 -377.791726)
		(width 0.14224)
		(layer "In6.Cu")
		(net "P5E_CPU1_P2_RX_DN<4>")
	)
	(segment
		(start 151.918162 -380.11989)
		(end 152.009348 -379.948694)
		(width 0.14224)
		(layer "In6.Cu")
		(net "P5E_CPU1_P2_RX_DN<4>")
	)
	(segment
		(start 116.522246 -291.601398)
		(end 116.45265 -291.560758)
		(width 0.1143)
		(layer "In6.Cu")
		(net "P5E_CPU1_P2_RX_DN<4>")
	)
	(arc
		(start 149.00021 -372.860062)
		(mid 148.643076 -372.634375)
		(end 148.332952 -372.34749)
		(width 0.14224)
		(layer "In6.Cu")
		(net "P5E_CPU1_P2_RX_DN<4>")
	)
	(arc
		(start 116.679218 -295.146222)
		(mid 116.637669 -294.9748)
		(end 116.522246 -294.841422)
		(width 0.1143)
		(layer "In6.Cu")
		(net "P5E_CPU1_P2_RX_DN<4>")
	)
	(arc
		(start 116.45265 -289.940746)
		(mid 116.209323 -289.47618)
		(end 116.45265 -289.011614)
		(width 0.1143)
		(layer "In6.Cu")
		(net "P5E_CPU1_P2_RX_DN<4>")
	)
	(arc
		(start 116.522246 -290.590986)
		(mid 116.679223 -290.286186)
		(end 116.522246 -289.981386)
		(width 0.1143)
		(layer "In6.Cu")
		(net "P5E_CPU1_P2_RX_DN<4>")
	)
	(arc
		(start 116.995194 -286.539178)
		(mid 117.091082 -286.43677)
		(end 117.142514 -286.30626)
		(width 0.1143)
		(layer "In6.Cu")
		(net "P5E_CPU1_P2_RX_DN<4>")
	)
	(arc
		(start 116.522246 -292.210998)
		(mid 116.679223 -291.906198)
		(end 116.522246 -291.601398)
		(width 0.1143)
		(layer "In6.Cu")
		(net "P5E_CPU1_P2_RX_DN<4>")
	)
	(arc
		(start 116.45265 -293.18077)
		(mid 116.209323 -292.716204)
		(end 116.45265 -292.251638)
		(width 0.1143)
		(layer "In6.Cu")
		(net "P5E_CPU1_P2_RX_DN<4>")
	)
	(arc
		(start 149.470618 -373.119904)
		(mid 149.449062 -373.094417)
		(end 149.421596 -373.075454)
		(width 0.14224)
		(layer "In6.Cu")
		(net "P5E_CPU1_P2_RX_DN<4>")
	)
	(arc
		(start 116.45265 -288.320988)
		(mid 116.209326 -287.854872)
		(end 116.45519 -287.390078)
		(width 0.1143)
		(layer "In6.Cu")
		(net "P5E_CPU1_P2_RX_DN<4>")
	)
	(arc
		(start 116.493544 -287.367726)
		(mid 116.629466 -287.231967)
		(end 116.679218 -287.046416)
		(width 0.1143)
		(layer "In6.Cu")
		(net "P5E_CPU1_P2_RX_DN<4>")
	)
	(arc
		(start 117.149626 -295.952926)
		(mid 117.101364 -295.771334)
		(end 116.969286 -295.637712)
		(width 0.1143)
		(layer "In6.Cu")
		(net "P5E_CPU1_P2_RX_DN<4>")
	)
	(arc
		(start 116.522246 -293.83101)
		(mid 116.679223 -293.52621)
		(end 116.522246 -293.22141)
		(width 0.1143)
		(layer "In6.Cu")
		(net "P5E_CPU1_P2_RX_DN<4>")
	)
	(arc
		(start 152.686004 -382.3843)
		(mid 152.669695 -382.16254)
		(end 152.620726 -381.945642)
		(width 0.14224)
		(layer "In6.Cu")
		(net "P5E_CPU1_P2_RX_DN<4>")
	)
	(arc
		(start 116.679218 -287.046416)
		(mid 116.754198 -286.765932)
		(end 116.959126 -286.56026)
		(width 0.1143)
		(layer "In6.Cu")
		(net "P5E_CPU1_P2_RX_DN<4>")
	)
	(arc
		(start 116.45265 -294.800782)
		(mid 116.209323 -294.336216)
		(end 116.45265 -293.87165)
		(width 0.1143)
		(layer "In6.Cu")
		(net "P5E_CPU1_P2_RX_DN<4>")
	)
	(arc
		(start 116.45265 -291.560758)
		(mid 116.209323 -291.096192)
		(end 116.45265 -290.631626)
		(width 0.1143)
		(layer "In6.Cu")
		(net "P5E_CPU1_P2_RX_DN<4>")
	)
	(arc
		(start 116.522246 -288.970974)
		(mid 116.637673 -288.837598)
		(end 116.679218 -288.666174)
		(width 0.1143)
		(layer "In6.Cu")
		(net "P5E_CPU1_P2_RX_DN<4>")
	)
	(arc
		(start 148.279104 -372.287292)
		(mid 148.100866 -372.01841)
		(end 148.008086 -371.709442)
		(width 0.14224)
		(layer "In6.Cu")
		(net "P5E_CPU1_P2_RX_DN<4>")
	)
	(arc
		(start 116.923312 -295.611296)
		(mid 116.744119 -295.408786)
		(end 116.679472 -295.146222)
		(width 0.1143)
		(layer "In6.Cu")
		(net "P5E_CPU1_P2_RX_DN<4>")
	)
	(arc
		(start 116.679218 -288.666174)
		(mid 116.638252 -288.495768)
		(end 116.524278 -288.362644)
		(width 0.1143)
		(layer "In6.Cu")
		(net "P5E_CPU1_P2_RX_DN<4>")
	)
	(arc
		(start 117.255544 -299.17263)
		(mid 117.13869 -298.786878)
		(end 117.099334 -298.385738)
		(width 0.14224)
		(layer "In6.Cu")
		(net "P5E_CPU1_P2_RX_DN<4>")
	)
	(segment
		(start 150.498302 -385.31038)
		(end 151.019002 -385.31038)
		(width 0.127)
		(layer "F.Cu")
		(net "P5E_CPU1_P2_RX_DN<3>")
	)
	(segment
		(start 116.30787 -282.730448)
		(end 116.774722 -282.996386)
		(width 0.12954)
		(layer "F.Cu")
		(net "P5E_CPU1_P2_RX_DN<3>")
	)
	(segment
		(start 146.169126 -373.628158)
		(end 146.18716 -373.201946)
		(width 0.14224)
		(layer "In6.Cu")
		(net "P5E_CPU1_P2_RX_DN<3>")
	)
	(segment
		(start 146.121628 -371.50548)
		(end 146.264884 -371.374162)
		(width 0.14224)
		(layer "In6.Cu")
		(net "P5E_CPU1_P2_RX_DN<3>")
	)
	(segment
		(start 151.49449 -385.163822)
		(end 151.177498 -384.84683)
		(width 0.14224)
		(layer "In6.Cu")
		(net "P5E_CPU1_P2_RX_DN<3>")
	)
	(segment
		(start 124.468636 -311.611264)
		(end 121.306082 -307.75783)
		(width 0.14224)
		(layer "In6.Cu")
		(net "P5E_CPU1_P2_RX_DN<3>")
	)
	(segment
		(start 115.551712 -287.368742)
		(end 115.583462 -287.350454)
		(width 0.1143)
		(layer "In6.Cu")
		(net "P5E_CPU1_P2_RX_DN<3>")
	)
	(segment
		(start 115.543076 -292.233858)
		(end 115.544854 -292.232842)
		(width 0.1143)
		(layer "In6.Cu")
		(net "P5E_CPU1_P2_RX_DN<3>")
	)
	(segment
		(start 146.18716 -373.201946)
		(end 146.055842 -373.059198)
		(width 0.14224)
		(layer "In6.Cu")
		(net "P5E_CPU1_P2_RX_DN<3>")
	)
	(segment
		(start 115.545616 -292.232334)
		(end 115.54714 -292.231572)
		(width 0.1143)
		(layer "In6.Cu")
		(net "P5E_CPU1_P2_RX_DN<3>")
	)
	(segment
		(start 137.813034 -347.456506)
		(end 136.8171 -344.172794)
		(width 0.14224)
		(layer "In6.Cu")
		(net "P5E_CPU1_P2_RX_DN<3>")
	)
	(segment
		(start 115.557808 -293.207186)
		(end 115.556284 -293.20617)
		(width 0.1143)
		(layer "In6.Cu")
		(net "P5E_CPU1_P2_RX_DN<3>")
	)
	(segment
		(start 151.49449 -385.334764)
		(end 151.49449 -385.163822)
		(width 0.14224)
		(layer "In6.Cu")
		(net "P5E_CPU1_P2_RX_DN<3>")
	)
	(segment
		(start 116.164614 -296.353738)
		(end 116.164614 -296.32529)
		(width 0.1143)
		(layer "In6.Cu")
		(net "P5E_CPU1_P2_RX_DN<3>")
	)
	(segment
		(start 115.553744 -293.2049)
		(end 115.552474 -293.204138)
		(width 0.1143)
		(layer "In6.Cu")
		(net "P5E_CPU1_P2_RX_DN<3>")
	)
	(segment
		(start 146.212814 -367.733834)
		(end 137.813034 -347.456506)
		(width 0.14224)
		(layer "In6.Cu")
		(net "P5E_CPU1_P2_RX_DN<3>")
	)
	(segment
		(start 127.61341 -315.442854)
		(end 124.468382 -311.611264)
		(width 0.14224)
		(layer "In6.Cu")
		(net "P5E_CPU1_P2_RX_DN<3>")
	)
	(segment
		(start 115.543584 -291.578792)
		(end 115.512596 -291.560758)
		(width 0.1143)
		(layer "In6.Cu")
		(net "P5E_CPU1_P2_RX_DN<3>")
	)
	(segment
		(start 115.542314 -292.234366)
		(end 115.543076 -292.233858)
		(width 0.1143)
		(layer "In6.Cu")
		(net "P5E_CPU1_P2_RX_DN<3>")
	)
	(segment
		(start 115.543584 -294.818816)
		(end 115.512596 -294.800782)
		(width 0.1143)
		(layer "In6.Cu")
		(net "P5E_CPU1_P2_RX_DN<3>")
	)
	(segment
		(start 115.552474 -294.82415)
		(end 115.551712 -294.823642)
		(width 0.1143)
		(layer "In6.Cu")
		(net "P5E_CPU1_P2_RX_DN<3>")
	)
	(segment
		(start 146.234912 -372.074948)
		(end 146.103594 -371.9322)
		(width 0.14224)
		(layer "In6.Cu")
		(net "P5E_CPU1_P2_RX_DN<3>")
	)
	(segment
		(start 117.290596 -301.74819)
		(end 116.309394 -299.379132)
		(width 0.14224)
		(layer "In6.Cu")
		(net "P5E_CPU1_P2_RX_DN<3>")
	)
	(segment
		(start 115.553744 -294.824912)
		(end 115.552474 -294.82415)
		(width 0.1143)
		(layer "In6.Cu")
		(net "P5E_CPU1_P2_RX_DN<3>")
	)
	(segment
		(start 117.142514 -283.066236)
		(end 117.072664 -282.996386)
		(width 0.1143)
		(layer "In6.Cu")
		(net "P5E_CPU1_P2_RX_DN<3>")
	)
	(segment
		(start 151.463756 -381.968248)
		(end 146.559016 -374.823736)
		(width 0.14224)
		(layer "In6.Cu")
		(net "P5E_CPU1_P2_RX_DN<3>")
	)
	(segment
		(start 115.515136 -287.390078)
		(end 115.551712 -287.368742)
		(width 0.1143)
		(layer "In6.Cu")
		(net "P5E_CPU1_P2_RX_DN<3>")
	)
	(segment
		(start 115.552474 -291.584126)
		(end 115.551712 -291.583618)
		(width 0.1143)
		(layer "In6.Cu")
		(net "P5E_CPU1_P2_RX_DN<3>")
	)
	(segment
		(start 146.169634 -370.378482)
		(end 146.312636 -370.247164)
		(width 0.14224)
		(layer "In6.Cu")
		(net "P5E_CPU1_P2_RX_DN<3>")
	)
	(segment
		(start 115.512596 -293.87165)
		(end 115.512342 -293.87165)
		(width 0.1143)
		(layer "In6.Cu")
		(net "P5E_CPU1_P2_RX_DN<3>")
	)
	(segment
		(start 115.556284 -294.826182)
		(end 115.553744 -294.824912)
		(width 0.1143)
		(layer "In6.Cu")
		(net "P5E_CPU1_P2_RX_DN<3>")
	)
	(segment
		(start 116.164106 -297.958764)
		(end 116.164614 -297.958764)
		(width 0.14224)
		(layer "In6.Cu")
		(net "P5E_CPU1_P2_RX_DN<3>")
	)
	(segment
		(start 115.558824 -289.96767)
		(end 115.557808 -289.967162)
		(width 0.1143)
		(layer "In6.Cu")
		(net "P5E_CPU1_P2_RX_DN<3>")
	)
	(segment
		(start 115.513866 -292.250622)
		(end 115.542314 -292.234366)
		(width 0.1143)
		(layer "In6.Cu")
		(net "P5E_CPU1_P2_RX_DN<3>")
	)
	(segment
		(start 115.550696 -291.58311)
		(end 115.549172 -291.582094)
		(width 0.1143)
		(layer "In6.Cu")
		(net "P5E_CPU1_P2_RX_DN<3>")
	)
	(segment
		(start 115.573302 -288.977324)
		(end 115.578128 -288.974276)
		(width 0.1143)
		(layer "In6.Cu")
		(net "P5E_CPU1_P2_RX_DN<3>")
	)
	(segment
		(start 115.557808 -291.587174)
		(end 115.556284 -291.586158)
		(width 0.1143)
		(layer "In6.Cu")
		(net "P5E_CPU1_P2_RX_DN<3>")
	)
	(segment
		(start 146.055842 -373.059198)
		(end 146.073876 -372.632478)
		(width 0.14224)
		(layer "In6.Cu")
		(net "P5E_CPU1_P2_RX_DN<3>")
	)
	(segment
		(start 151.019002 -385.31038)
		(end 151.372316 -385.405376)
		(width 0.14224)
		(layer "In6.Cu")
		(net "P5E_CPU1_P2_RX_DN<3>")
	)
	(segment
		(start 115.512342 -290.631626)
		(end 115.513104 -290.631118)
		(width 0.1143)
		(layer "In6.Cu")
		(net "P5E_CPU1_P2_RX_DN<3>")
	)
	(segment
		(start 115.551712 -291.583618)
		(end 115.550696 -291.58311)
		(width 0.1143)
		(layer "In6.Cu")
		(net "P5E_CPU1_P2_RX_DN<3>")
	)
	(segment
		(start 115.543584 -289.95878)
		(end 115.512596 -289.940746)
		(width 0.1143)
		(layer "In6.Cu")
		(net "P5E_CPU1_P2_RX_DN<3>")
	)
	(segment
		(start 115.556284 -289.966146)
		(end 115.553744 -289.964876)
		(width 0.1143)
		(layer "In6.Cu")
		(net "P5E_CPU1_P2_RX_DN<3>")
	)
	(segment
		(start 146.26463 -371.371114)
		(end 146.28241 -370.94795)
		(width 0.14224)
		(layer "In6.Cu")
		(net "P5E_CPU1_P2_RX_DN<3>")
	)
	(segment
		(start 115.553744 -289.964876)
		(end 115.552474 -289.964114)
		(width 0.1143)
		(layer "In6.Cu")
		(net "P5E_CPU1_P2_RX_DN<3>")
	)
	(segment
		(start 115.546378 -291.58057)
		(end 115.545108 -291.579808)
		(width 0.1143)
		(layer "In6.Cu")
		(net "P5E_CPU1_P2_RX_DN<3>")
	)
	(segment
		(start 115.583462 -294.84193)
		(end 115.558824 -294.827706)
		(width 0.1143)
		(layer "In6.Cu")
		(net "P5E_CPU1_P2_RX_DN<3>")
	)
	(segment
		(start 115.551712 -289.963606)
		(end 115.550696 -289.963098)
		(width 0.1143)
		(layer "In6.Cu")
		(net "P5E_CPU1_P2_RX_DN<3>")
	)
	(segment
		(start 115.582954 -293.830756)
		(end 115.583208 -293.830502)
		(width 0.1143)
		(layer "In6.Cu")
		(net "P5E_CPU1_P2_RX_DN<3>")
	)
	(segment
		(start 116.210334 -296.27957)
		(end 116.209572 -296.278808)
		(width 0.1143)
		(layer "In6.Cu")
		(net "P5E_CPU1_P2_RX_DN<3>")
	)
	(segment
		(start 116.45265 -284.151578)
		(end 116.51488 -284.11551)
		(width 0.1143)
		(layer "In6.Cu")
		(net "P5E_CPU1_P2_RX_DN<3>")
	)
	(segment
		(start 151.177498 -384.84683)
		(end 151.182324 -384.234944)
		(width 0.14224)
		(layer "In6.Cu")
		(net "P5E_CPU1_P2_RX_DN<3>")
	)
	(segment
		(start 115.583462 -291.601906)
		(end 115.558824 -291.587682)
		(width 0.1143)
		(layer "In6.Cu")
		(net "P5E_CPU1_P2_RX_DN<3>")
	)
	(segment
		(start 115.546378 -294.820594)
		(end 115.545108 -294.819832)
		(width 0.1143)
		(layer "In6.Cu")
		(net "P5E_CPU1_P2_RX_DN<3>")
	)
	(segment
		(start 116.925344 -283.340048)
		(end 116.961666 -283.318966)
		(width 0.1143)
		(layer "In6.Cu")
		(net "P5E_CPU1_P2_RX_DN<3>")
	)
	(segment
		(start 151.486362 -383.93116)
		(end 151.486362 -382.040384)
		(width 0.14224)
		(layer "In6.Cu")
		(net "P5E_CPU1_P2_RX_DN<3>")
	)
	(segment
		(start 115.512342 -285.77159)
		(end 115.583462 -285.730696)
		(width 0.1143)
		(layer "In6.Cu")
		(net "P5E_CPU1_P2_RX_DN<3>")
	)
	(segment
		(start 115.512596 -289.011614)
		(end 115.512342 -289.01136)
		(width 0.1143)
		(layer "In6.Cu")
		(net "P5E_CPU1_P2_RX_DN<3>")
	)
	(segment
		(start 115.550696 -292.229286)
		(end 115.551712 -292.228778)
		(width 0.1143)
		(layer "In6.Cu")
		(net "P5E_CPU1_P2_RX_DN<3>")
	)
	(segment
		(start 117.072664 -282.996386)
		(end 116.774722 -282.996386)
		(width 0.1143)
		(layer "In6.Cu")
		(net "P5E_CPU1_P2_RX_DN<3>")
	)
	(segment
		(start 115.514374 -289.01009)
		(end 115.571524 -288.97834)
		(width 0.1143)
		(layer "In6.Cu")
		(net "P5E_CPU1_P2_RX_DN<3>")
	)
	(segment
		(start 115.512342 -293.87165)
		(end 115.513104 -293.871142)
		(width 0.1143)
		(layer "In6.Cu")
		(net "P5E_CPU1_P2_RX_DN<3>")
	)
	(segment
		(start 116.962428 -283.318458)
		(end 116.963698 -283.317696)
		(width 0.1143)
		(layer "In6.Cu")
		(net "P5E_CPU1_P2_RX_DN<3>")
	)
	(segment
		(start 115.545108 -291.579808)
		(end 115.543584 -291.578792)
		(width 0.1143)
		(layer "In6.Cu")
		(net "P5E_CPU1_P2_RX_DN<3>")
	)
	(segment
		(start 115.512596 -292.251638)
		(end 115.512342 -292.251638)
		(width 0.1143)
		(layer "In6.Cu")
		(net "P5E_CPU1_P2_RX_DN<3>")
	)
	(segment
		(start 115.549172 -293.202106)
		(end 115.546378 -293.200582)
		(width 0.1143)
		(layer "In6.Cu")
		(net "P5E_CPU1_P2_RX_DN<3>")
	)
	(segment
		(start 115.512342 -289.01136)
		(end 115.514374 -289.01009)
		(width 0.1143)
		(layer "In6.Cu")
		(net "P5E_CPU1_P2_RX_DN<3>")
	)
	(segment
		(start 146.282664 -370.94795)
		(end 146.1516 -370.805202)
		(width 0.14224)
		(layer "In6.Cu")
		(net "P5E_CPU1_P2_RX_DN<3>")
	)
	(segment
		(start 146.346926 -374.424956)
		(end 146.256248 -374.194832)
		(width 0.14224)
		(layer "In6.Cu")
		(net "P5E_CPU1_P2_RX_DN<3>")
	)
	(segment
		(start 146.312128 -370.24691)
		(end 146.337274 -369.660424)
		(width 0.14224)
		(layer "In6.Cu")
		(net "P5E_CPU1_P2_RX_DN<3>")
	)
	(segment
		(start 115.549172 -291.582094)
		(end 115.546378 -291.58057)
		(width 0.1143)
		(layer "In6.Cu")
		(net "P5E_CPU1_P2_RX_DN<3>")
	)
	(segment
		(start 115.584478 -290.589716)
		(end 115.586256 -290.588446)
		(width 0.1143)
		(layer "In6.Cu")
		(net "P5E_CPU1_P2_RX_DN<3>")
	)
	(segment
		(start 115.543584 -293.198804)
		(end 115.512596 -293.18077)
		(width 0.1143)
		(layer "In6.Cu")
		(net "P5E_CPU1_P2_RX_DN<3>")
	)
	(segment
		(start 115.551712 -294.823642)
		(end 115.550696 -294.823134)
		(width 0.1143)
		(layer "In6.Cu")
		(net "P5E_CPU1_P2_RX_DN<3>")
	)
	(segment
		(start 115.552474 -292.22827)
		(end 115.553744 -292.227508)
		(width 0.1143)
		(layer "In6.Cu")
		(net "P5E_CPU1_P2_RX_DN<3>")
	)
	(segment
		(start 115.583462 -293.221918)
		(end 115.558824 -293.207694)
		(width 0.1143)
		(layer "In6.Cu")
		(net "P5E_CPU1_P2_RX_DN<3>")
	)
	(segment
		(start 115.549172 -289.962082)
		(end 115.546378 -289.960558)
		(width 0.1143)
		(layer "In6.Cu")
		(net "P5E_CPU1_P2_RX_DN<3>")
	)
	(segment
		(start 132.957062 -324.76567)
		(end 129.631694 -318.546226)
		(width 0.14224)
		(layer "In6.Cu")
		(net "P5E_CPU1_P2_RX_DN<3>")
	)
	(segment
		(start 115.544854 -292.232842)
		(end 115.545616 -292.232334)
		(width 0.1143)
		(layer "In6.Cu")
		(net "P5E_CPU1_P2_RX_DN<3>")
	)
	(segment
		(start 116.164106 -298.64812)
		(end 116.164106 -297.958764)
		(width 0.14224)
		(layer "In6.Cu")
		(net "P5E_CPU1_P2_RX_DN<3>")
	)
	(segment
		(start 129.410206 -318.131952)
		(end 127.61341 -315.442854)
		(width 0.14224)
		(layer "In6.Cu")
		(net "P5E_CPU1_P2_RX_DN<3>")
	)
	(segment
		(start 124.468382 -311.611264)
		(end 124.468636 -311.611264)
		(width 0.14224)
		(layer "In6.Cu")
		(net "P5E_CPU1_P2_RX_DN<3>")
	)
	(segment
		(start 115.556284 -293.20617)
		(end 115.553744 -293.2049)
		(width 0.1143)
		(layer "In6.Cu")
		(net "P5E_CPU1_P2_RX_DN<3>")
	)
	(segment
		(start 115.98275 -284.961838)
		(end 116.052346 -284.921198)
		(width 0.1143)
		(layer "In6.Cu")
		(net "P5E_CPU1_P2_RX_DN<3>")
	)
	(segment
		(start 115.546378 -293.200582)
		(end 115.545108 -293.19982)
		(width 0.1143)
		(layer "In6.Cu")
		(net "P5E_CPU1_P2_RX_DN<3>")
	)
	(segment
		(start 146.073876 -372.632478)
		(end 146.216878 -372.50116)
		(width 0.14224)
		(layer "In6.Cu")
		(net "P5E_CPU1_P2_RX_DN<3>")
	)
	(segment
		(start 115.550696 -293.203122)
		(end 115.549172 -293.202106)
		(width 0.1143)
		(layer "In6.Cu")
		(net "P5E_CPU1_P2_RX_DN<3>")
	)
	(segment
		(start 115.545108 -294.819832)
		(end 115.543584 -294.818816)
		(width 0.1143)
		(layer "In6.Cu")
		(net "P5E_CPU1_P2_RX_DN<3>")
	)
	(segment
		(start 115.558824 -293.207694)
		(end 115.557808 -293.207186)
		(width 0.1143)
		(layer "In6.Cu")
		(net "P5E_CPU1_P2_RX_DN<3>")
	)
	(segment
		(start 146.1516 -370.805202)
		(end 146.169634 -370.378482)
		(width 0.14224)
		(layer "In6.Cu")
		(net "P5E_CPU1_P2_RX_DN<3>")
	)
	(segment
		(start 115.583716 -290.590224)
		(end 115.584478 -290.589716)
		(width 0.1143)
		(layer "In6.Cu")
		(net "P5E_CPU1_P2_RX_DN<3>")
	)
	(segment
		(start 115.571524 -288.97834)
		(end 115.573302 -288.977324)
		(width 0.1143)
		(layer "In6.Cu")
		(net "P5E_CPU1_P2_RX_DN<3>")
	)
	(segment
		(start 115.549172 -294.822118)
		(end 115.546378 -294.820594)
		(width 0.1143)
		(layer "In6.Cu")
		(net "P5E_CPU1_P2_RX_DN<3>")
	)
	(segment
		(start 151.372824 -385.404868)
		(end 151.49449 -385.334764)
		(width 0.14224)
		(layer "In6.Cu")
		(net "P5E_CPU1_P2_RX_DN<3>")
	)
	(segment
		(start 115.553744 -291.584888)
		(end 115.552474 -291.584126)
		(width 0.1143)
		(layer "In6.Cu")
		(net "P5E_CPU1_P2_RX_DN<3>")
	)
	(segment
		(start 115.58524 -288.363406)
		(end 115.512596 -288.320988)
		(width 0.1143)
		(layer "In6.Cu")
		(net "P5E_CPU1_P2_RX_DN<3>")
	)
	(segment
		(start 116.164614 -296.32529)
		(end 116.210334 -296.27957)
		(width 0.1143)
		(layer "In6.Cu")
		(net "P5E_CPU1_P2_RX_DN<3>")
	)
	(segment
		(start 146.103594 -371.9322)
		(end 146.121628 -371.50548)
		(width 0.14224)
		(layer "In6.Cu")
		(net "P5E_CPU1_P2_RX_DN<3>")
	)
	(segment
		(start 121.306082 -307.75783)
		(end 117.290596 -301.74819)
		(width 0.14224)
		(layer "In6.Cu")
		(net "P5E_CPU1_P2_RX_DN<3>")
	)
	(segment
		(start 115.558824 -294.827706)
		(end 115.557808 -294.827198)
		(width 0.1143)
		(layer "In6.Cu")
		(net "P5E_CPU1_P2_RX_DN<3>")
	)
	(segment
		(start 116.164614 -297.958764)
		(end 116.164614 -296.353738)
		(width 0.14224)
		(layer "In6.Cu")
		(net "P5E_CPU1_P2_RX_DN<3>")
	)
	(segment
		(start 115.58524 -286.743394)
		(end 115.512596 -286.700976)
		(width 0.1143)
		(layer "In6.Cu")
		(net "P5E_CPU1_P2_RX_DN<3>")
	)
	(segment
		(start 146.264376 -371.374162)
		(end 146.26463 -371.371114)
		(width 0.14224)
		(layer "In6.Cu")
		(net "P5E_CPU1_P2_RX_DN<3>")
	)
	(segment
		(start 115.550696 -289.963098)
		(end 115.549172 -289.962082)
		(width 0.1143)
		(layer "In6.Cu")
		(net "P5E_CPU1_P2_RX_DN<3>")
	)
	(segment
		(start 146.264884 -371.374162)
		(end 146.264376 -371.374162)
		(width 0.14224)
		(layer "In6.Cu")
		(net "P5E_CPU1_P2_RX_DN<3>")
	)
	(segment
		(start 146.216878 -372.50116)
		(end 146.234912 -372.074948)
		(width 0.14224)
		(layer "In6.Cu")
		(net "P5E_CPU1_P2_RX_DN<3>")
	)
	(segment
		(start 115.513104 -290.631118)
		(end 115.583716 -290.590224)
		(width 0.1143)
		(layer "In6.Cu")
		(net "P5E_CPU1_P2_RX_DN<3>")
	)
	(segment
		(start 151.372316 -385.405376)
		(end 151.372824 -385.404868)
		(width 0.14224)
		(layer "In6.Cu")
		(net "P5E_CPU1_P2_RX_DN<3>")
	)
	(segment
		(start 115.54714 -292.231572)
		(end 115.549172 -292.230302)
		(width 0.1143)
		(layer "In6.Cu")
		(net "P5E_CPU1_P2_RX_DN<3>")
	)
	(segment
		(start 115.552474 -289.964114)
		(end 115.551712 -289.963606)
		(width 0.1143)
		(layer "In6.Cu")
		(net "P5E_CPU1_P2_RX_DN<3>")
	)
	(segment
		(start 115.557808 -294.827198)
		(end 115.556284 -294.826182)
		(width 0.1143)
		(layer "In6.Cu")
		(net "P5E_CPU1_P2_RX_DN<3>")
	)
	(segment
		(start 115.545108 -293.19982)
		(end 115.543584 -293.198804)
		(width 0.1143)
		(layer "In6.Cu")
		(net "P5E_CPU1_P2_RX_DN<3>")
	)
	(segment
		(start 115.546378 -289.960558)
		(end 115.545108 -289.959796)
		(width 0.1143)
		(layer "In6.Cu")
		(net "P5E_CPU1_P2_RX_DN<3>")
	)
	(segment
		(start 136.8171 -344.172794)
		(end 132.957062 -324.76567)
		(width 0.14224)
		(layer "In6.Cu")
		(net "P5E_CPU1_P2_RX_DN<3>")
	)
	(segment
		(start 115.549172 -292.230302)
		(end 115.550696 -292.229286)
		(width 0.1143)
		(layer "In6.Cu")
		(net "P5E_CPU1_P2_RX_DN<3>")
	)
	(segment
		(start 115.551712 -292.228778)
		(end 115.552474 -292.22827)
		(width 0.1143)
		(layer "In6.Cu")
		(net "P5E_CPU1_P2_RX_DN<3>")
	)
	(segment
		(start 115.583208 -293.830502)
		(end 115.583462 -293.830502)
		(width 0.1143)
		(layer "In6.Cu")
		(net "P5E_CPU1_P2_RX_DN<3>")
	)
	(segment
		(start 115.557808 -289.967162)
		(end 115.556284 -289.966146)
		(width 0.1143)
		(layer "In6.Cu")
		(net "P5E_CPU1_P2_RX_DN<3>")
	)
	(segment
		(start 151.182324 -384.234944)
		(end 151.486362 -383.93116)
		(width 0.14224)
		(layer "In6.Cu")
		(net "P5E_CPU1_P2_RX_DN<3>")
	)
	(segment
		(start 115.512596 -285.771844)
		(end 115.512342 -285.77159)
		(width 0.1143)
		(layer "In6.Cu")
		(net "P5E_CPU1_P2_RX_DN<3>")
	)
	(segment
		(start 115.558824 -291.587682)
		(end 115.557808 -291.587174)
		(width 0.1143)
		(layer "In6.Cu")
		(net "P5E_CPU1_P2_RX_DN<3>")
	)
	(segment
		(start 115.513104 -293.871142)
		(end 115.582954 -293.830756)
		(width 0.1143)
		(layer "In6.Cu")
		(net "P5E_CPU1_P2_RX_DN<3>")
	)
	(segment
		(start 129.631694 -318.546226)
		(end 129.63144 -318.546226)
		(width 0.14224)
		(layer "In6.Cu")
		(net "P5E_CPU1_P2_RX_DN<3>")
	)
	(segment
		(start 146.312636 -370.247164)
		(end 146.312128 -370.24691)
		(width 0.14224)
		(layer "In6.Cu")
		(net "P5E_CPU1_P2_RX_DN<3>")
	)
	(segment
		(start 115.550696 -294.823134)
		(end 115.549172 -294.822118)
		(width 0.1143)
		(layer "In6.Cu")
		(net "P5E_CPU1_P2_RX_DN<3>")
	)
	(segment
		(start 146.28241 -370.94795)
		(end 146.282664 -370.94795)
		(width 0.14224)
		(layer "In6.Cu")
		(net "P5E_CPU1_P2_RX_DN<3>")
	)
	(segment
		(start 115.583462 -289.981894)
		(end 115.558824 -289.96767)
		(width 0.1143)
		(layer "In6.Cu")
		(net "P5E_CPU1_P2_RX_DN<3>")
	)
	(segment
		(start 115.545108 -289.959796)
		(end 115.543584 -289.95878)
		(width 0.1143)
		(layer "In6.Cu")
		(net "P5E_CPU1_P2_RX_DN<3>")
	)
	(segment
		(start 115.551712 -293.20363)
		(end 115.550696 -293.203122)
		(width 0.1143)
		(layer "In6.Cu")
		(net "P5E_CPU1_P2_RX_DN<3>")
	)
	(segment
		(start 116.961666 -283.318966)
		(end 116.962428 -283.318458)
		(width 0.1143)
		(layer "In6.Cu")
		(net "P5E_CPU1_P2_RX_DN<3>")
	)
	(segment
		(start 146.337274 -369.660424)
		(end 146.337274 -368.358674)
		(width 0.14224)
		(layer "In6.Cu")
		(net "P5E_CPU1_P2_RX_DN<3>")
	)
	(segment
		(start 129.63144 -318.546226)
		(end 129.410206 -318.131952)
		(width 0.14224)
		(layer "In6.Cu")
		(net "P5E_CPU1_P2_RX_DN<3>")
	)
	(segment
		(start 116.209572 -296.278808)
		(end 116.209572 -295.956228)
		(width 0.1143)
		(layer "In6.Cu")
		(net "P5E_CPU1_P2_RX_DN<3>")
	)
	(segment
		(start 115.512596 -290.631626)
		(end 115.512342 -290.631626)
		(width 0.1143)
		(layer "In6.Cu")
		(net "P5E_CPU1_P2_RX_DN<3>")
	)
	(segment
		(start 116.052346 -295.651428)
		(end 115.98275 -295.610788)
		(width 0.1143)
		(layer "In6.Cu")
		(net "P5E_CPU1_P2_RX_DN<3>")
	)
	(segment
		(start 146.475196 -374.68302)
		(end 146.364452 -374.46458)
		(width 0.14224)
		(layer "In6.Cu")
		(net "P5E_CPU1_P2_RX_DN<3>")
	)
	(segment
		(start 115.556284 -291.586158)
		(end 115.553744 -291.584888)
		(width 0.1143)
		(layer "In6.Cu")
		(net "P5E_CPU1_P2_RX_DN<3>")
	)
	(segment
		(start 116.963698 -283.317696)
		(end 116.993416 -283.300678)
		(width 0.1143)
		(layer "In6.Cu")
		(net "P5E_CPU1_P2_RX_DN<3>")
	)
	(segment
		(start 115.553744 -292.227508)
		(end 115.583462 -292.21049)
		(width 0.1143)
		(layer "In6.Cu")
		(net "P5E_CPU1_P2_RX_DN<3>")
	)
	(segment
		(start 115.552474 -293.204138)
		(end 115.551712 -293.20363)
		(width 0.1143)
		(layer "In6.Cu")
		(net "P5E_CPU1_P2_RX_DN<3>")
	)
	(arc
		(start 115.512596 -294.800782)
		(mid 115.269269 -294.336216)
		(end 115.512596 -293.87165)
		(width 0.1143)
		(layer "In6.Cu")
		(net "P5E_CPU1_P2_RX_DN<3>")
	)
	(arc
		(start 115.583462 -285.730696)
		(mid 115.698138 -285.597362)
		(end 115.739418 -285.426404)
		(width 0.1143)
		(layer "In6.Cu")
		(net "P5E_CPU1_P2_RX_DN<3>")
	)
	(arc
		(start 116.51488 -284.11551)
		(mid 116.62308 -283.980108)
		(end 116.67744 -283.815536)
		(width 0.1143)
		(layer "In6.Cu")
		(net "P5E_CPU1_P2_RX_DN<3>")
	)
	(arc
		(start 115.512596 -291.560758)
		(mid 115.269269 -291.096192)
		(end 115.512596 -290.631626)
		(width 0.1143)
		(layer "In6.Cu")
		(net "P5E_CPU1_P2_RX_DN<3>")
	)
	(arc
		(start 115.512596 -289.940746)
		(mid 115.269269 -289.47618)
		(end 115.512596 -289.011614)
		(width 0.1143)
		(layer "In6.Cu")
		(net "P5E_CPU1_P2_RX_DN<3>")
	)
	(arc
		(start 115.269264 -287.856422)
		(mid 115.3345 -287.592831)
		(end 115.515136 -287.390078)
		(width 0.1143)
		(layer "In6.Cu")
		(net "P5E_CPU1_P2_RX_DN<3>")
	)
	(arc
		(start 115.578128 -288.974276)
		(mid 115.696724 -288.84009)
		(end 115.739418 -288.666174)
		(width 0.1143)
		(layer "In6.Cu")
		(net "P5E_CPU1_P2_RX_DN<3>")
	)
	(arc
		(start 115.583462 -287.350454)
		(mid 115.698138 -287.21712)
		(end 115.739418 -287.046162)
		(width 0.1143)
		(layer "In6.Cu")
		(net "P5E_CPU1_P2_RX_DN<3>")
	)
	(arc
		(start 116.052346 -284.921198)
		(mid 116.167865 -284.787841)
		(end 116.209572 -284.616398)
		(width 0.1143)
		(layer "In6.Cu")
		(net "P5E_CPU1_P2_RX_DN<3>")
	)
	(arc
		(start 115.512596 -286.700976)
		(mid 115.269269 -286.23641)
		(end 115.512596 -285.771844)
		(width 0.1143)
		(layer "In6.Cu")
		(net "P5E_CPU1_P2_RX_DN<3>")
	)
	(arc
		(start 115.512342 -292.251638)
		(mid 115.513104 -292.251129)
		(end 115.513866 -292.250622)
		(width 0.1143)
		(layer "In6.Cu")
		(net "P5E_CPU1_P2_RX_DN<3>")
	)
	(arc
		(start 115.739418 -295.146222)
		(mid 115.698163 -294.975251)
		(end 115.583462 -294.84193)
		(width 0.1143)
		(layer "In6.Cu")
		(net "P5E_CPU1_P2_RX_DN<3>")
	)
	(arc
		(start 115.739418 -287.046162)
		(mid 115.698656 -286.876278)
		(end 115.58524 -286.743394)
		(width 0.1143)
		(layer "In6.Cu")
		(net "P5E_CPU1_P2_RX_DN<3>")
	)
	(arc
		(start 115.739418 -285.426404)
		(mid 115.803933 -285.164185)
		(end 115.98275 -284.961838)
		(width 0.1143)
		(layer "In6.Cu")
		(net "P5E_CPU1_P2_RX_DN<3>")
	)
	(arc
		(start 116.209572 -284.616398)
		(mid 116.27396 -284.354105)
		(end 116.45265 -284.151578)
		(width 0.1143)
		(layer "In6.Cu")
		(net "P5E_CPU1_P2_RX_DN<3>")
	)
	(arc
		(start 115.512596 -293.18077)
		(mid 115.269269 -292.716204)
		(end 115.512596 -292.251638)
		(width 0.1143)
		(layer "In6.Cu")
		(net "P5E_CPU1_P2_RX_DN<3>")
	)
	(arc
		(start 115.583462 -293.830502)
		(mid 115.73939 -293.52621)
		(end 115.583462 -293.221918)
		(width 0.1143)
		(layer "In6.Cu")
		(net "P5E_CPU1_P2_RX_DN<3>")
	)
	(arc
		(start 146.337274 -368.358674)
		(mid 146.30584 -368.040118)
		(end 146.212814 -367.733834)
		(width 0.14224)
		(layer "In6.Cu")
		(net "P5E_CPU1_P2_RX_DN<3>")
	)
	(arc
		(start 116.08181 -295.674796)
		(mid 116.067375 -295.662737)
		(end 116.052346 -295.651428)
		(width 0.1143)
		(layer "In6.Cu")
		(net "P5E_CPU1_P2_RX_DN<3>")
	)
	(arc
		(start 116.309394 -299.379132)
		(mid 116.200723 -299.020784)
		(end 116.164106 -298.64812)
		(width 0.14224)
		(layer "In6.Cu")
		(net "P5E_CPU1_P2_RX_DN<3>")
	)
	(arc
		(start 115.583462 -292.21049)
		(mid 115.73939 -291.906198)
		(end 115.583462 -291.601906)
		(width 0.1143)
		(layer "In6.Cu")
		(net "P5E_CPU1_P2_RX_DN<3>")
	)
	(arc
		(start 116.993416 -283.300678)
		(mid 117.090551 -283.197809)
		(end 117.142514 -283.066236)
		(width 0.1143)
		(layer "In6.Cu")
		(net "P5E_CPU1_P2_RX_DN<3>")
	)
	(arc
		(start 115.98275 -295.610788)
		(mid 115.803937 -295.408438)
		(end 115.739418 -295.146222)
		(width 0.1143)
		(layer "In6.Cu")
		(net "P5E_CPU1_P2_RX_DN<3>")
	)
	(arc
		(start 115.586256 -290.588446)
		(mid 115.739592 -290.284459)
		(end 115.583462 -289.981894)
		(width 0.1143)
		(layer "In6.Cu")
		(net "P5E_CPU1_P2_RX_DN<3>")
	)
	(arc
		(start 116.914676 -283.347414)
		(mid 116.91999 -283.343702)
		(end 116.925344 -283.340048)
		(width 0.1143)
		(layer "In6.Cu")
		(net "P5E_CPU1_P2_RX_DN<3>")
	)
	(arc
		(start 116.67744 -283.815536)
		(mid 116.678749 -283.803496)
		(end 116.679472 -283.791406)
		(width 0.1143)
		(layer "In6.Cu")
		(net "P5E_CPU1_P2_RX_DN<3>")
	)
	(arc
		(start 115.739418 -288.666174)
		(mid 115.698656 -288.49629)
		(end 115.58524 -288.363406)
		(width 0.1143)
		(layer "In6.Cu")
		(net "P5E_CPU1_P2_RX_DN<3>")
	)
	(arc
		(start 116.209572 -295.956228)
		(mid 116.176086 -295.801714)
		(end 116.08181 -295.674796)
		(width 0.1143)
		(layer "In6.Cu")
		(net "P5E_CPU1_P2_RX_DN<3>")
	)
	(arc
		(start 116.679472 -283.791406)
		(mid 116.745092 -283.541888)
		(end 116.914676 -283.347414)
		(width 0.1143)
		(layer "In6.Cu")
		(net "P5E_CPU1_P2_RX_DN<3>")
	)
	(arc
		(start 146.364452 -374.46458)
		(mid 146.355231 -374.444971)
		(end 146.346926 -374.424956)
		(width 0.14224)
		(layer "In6.Cu")
		(net "P5E_CPU1_P2_RX_DN<3>")
	)
	(arc
		(start 115.512596 -288.320988)
		(mid 115.333783 -288.118638)
		(end 115.269264 -287.856422)
		(width 0.1143)
		(layer "In6.Cu")
		(net "P5E_CPU1_P2_RX_DN<3>")
	)
	(arc
		(start 146.559016 -374.823736)
		(mid 146.514769 -374.75477)
		(end 146.475196 -374.68302)
		(width 0.14224)
		(layer "In6.Cu")
		(net "P5E_CPU1_P2_RX_DN<3>")
	)
	(arc
		(start 146.256248 -374.194832)
		(mid 146.185022 -373.915749)
		(end 146.169126 -373.628158)
		(width 0.14224)
		(layer "In6.Cu")
		(net "P5E_CPU1_P2_RX_DN<3>")
	)
	(arc
		(start 151.486362 -382.040384)
		(mid 151.480543 -382.002597)
		(end 151.463756 -381.968248)
		(width 0.14224)
		(layer "In6.Cu")
		(net "P5E_CPU1_P2_RX_DN<3>")
	)
	(segment
		(start 149.298406 -385.31038)
		(end 149.819106 -385.31038)
		(width 0.127)
		(layer "F.Cu")
		(net "P5E_CPU1_P2_RX_DN<2>")
	)
	(segment
		(start 113.957862 -285.160466)
		(end 114.424714 -285.426404)
		(width 0.12954)
		(layer "F.Cu")
		(net "P5E_CPU1_P2_RX_DN<2>")
	)
	(segment
		(start 135.983726 -344.9447)
		(end 132.018532 -325.011288)
		(width 0.14224)
		(layer "In6.Cu")
		(net "P5E_CPU1_P2_RX_DN<2>")
	)
	(segment
		(start 114.619532 -290.604194)
		(end 114.620294 -290.603686)
		(width 0.1143)
		(layer "In6.Cu")
		(net "P5E_CPU1_P2_RX_DN<2>")
	)
	(segment
		(start 114.61877 -289.96767)
		(end 114.61623 -289.966146)
		(width 0.1143)
		(layer "In6.Cu")
		(net "P5E_CPU1_P2_RX_DN<2>")
	)
	(segment
		(start 114.602006 -292.234366)
		(end 114.60353 -292.233604)
		(width 0.1143)
		(layer "In6.Cu")
		(net "P5E_CPU1_P2_RX_DN<2>")
	)
	(segment
		(start 114.609118 -293.202106)
		(end 114.608102 -293.201598)
		(width 0.1143)
		(layer "In6.Cu")
		(net "P5E_CPU1_P2_RX_DN<2>")
	)
	(segment
		(start 136.785604 -348.145608)
		(end 135.983726 -344.9447)
		(width 0.14224)
		(layer "In6.Cu")
		(net "P5E_CPU1_P2_RX_DN<2>")
	)
	(segment
		(start 114.615976 -292.226238)
		(end 114.618008 -292.224968)
		(width 0.1143)
		(layer "In6.Cu")
		(net "P5E_CPU1_P2_RX_DN<2>")
	)
	(segment
		(start 114.620294 -292.223698)
		(end 114.621564 -292.222936)
		(width 0.1143)
		(layer "In6.Cu")
		(net "P5E_CPU1_P2_RX_DN<2>")
	)
	(segment
		(start 114.60353 -292.233604)
		(end 114.604292 -292.233096)
		(width 0.1143)
		(layer "In6.Cu")
		(net "P5E_CPU1_P2_RX_DN<2>")
	)
	(segment
		(start 114.607594 -292.231064)
		(end 114.611658 -292.228778)
		(width 0.1143)
		(layer "In6.Cu")
		(net "P5E_CPU1_P2_RX_DN<2>")
	)
	(segment
		(start 115.268756 -296.279316)
		(end 115.268756 -296.200576)
		(width 0.1143)
		(layer "In6.Cu")
		(net "P5E_CPU1_P2_RX_DN<2>")
	)
	(segment
		(start 147.69973 -378.61875)
		(end 147.451318 -378.271278)
		(width 0.14224)
		(layer "In6.Cu")
		(net "P5E_CPU1_P2_RX_DN<2>")
	)
	(segment
		(start 115.269518 -296.199814)
		(end 115.269518 -295.955974)
		(width 0.1143)
		(layer "In6.Cu")
		(net "P5E_CPU1_P2_RX_DN<2>")
	)
	(segment
		(start 114.63401 -288.356548)
		(end 114.57051 -288.319464)
		(width 0.1143)
		(layer "In6.Cu")
		(net "P5E_CPU1_P2_RX_DN<2>")
	)
	(segment
		(start 114.608102 -293.201598)
		(end 114.572542 -293.18077)
		(width 0.1143)
		(layer "In6.Cu")
		(net "P5E_CPU1_P2_RX_DN<2>")
	)
	(segment
		(start 114.575336 -285.770066)
		(end 114.611658 -285.748984)
		(width 0.1143)
		(layer "In6.Cu")
		(net "P5E_CPU1_P2_RX_DN<2>")
	)
	(segment
		(start 143.867632 -370.398548)
		(end 143.698976 -370.328444)
		(width 0.14224)
		(layer "In6.Cu")
		(net "P5E_CPU1_P2_RX_DN<2>")
	)
	(segment
		(start 150.286212 -383.93116)
		(end 150.286212 -382.0414)
		(width 0.14224)
		(layer "In6.Cu")
		(net "P5E_CPU1_P2_RX_DN<2>")
	)
	(segment
		(start 114.61242 -293.204138)
		(end 114.611658 -293.20363)
		(width 0.1143)
		(layer "In6.Cu")
		(net "P5E_CPU1_P2_RX_DN<2>")
	)
	(segment
		(start 150.29434 -385.163822)
		(end 149.977348 -384.84683)
		(width 0.14224)
		(layer "In6.Cu")
		(net "P5E_CPU1_P2_RX_DN<2>")
	)
	(segment
		(start 114.611658 -289.963606)
		(end 114.609372 -289.962336)
		(width 0.1143)
		(layer "In6.Cu")
		(net "P5E_CPU1_P2_RX_DN<2>")
	)
	(segment
		(start 115.22329 -296.32529)
		(end 115.26901 -296.27957)
		(width 0.1143)
		(layer "In6.Cu")
		(net "P5E_CPU1_P2_RX_DN<2>")
	)
	(segment
		(start 150.26259 -381.967486)
		(end 148.547074 -379.567948)
		(width 0.14224)
		(layer "In6.Cu")
		(net "P5E_CPU1_P2_RX_DN<2>")
	)
	(segment
		(start 114.623596 -290.601908)
		(end 114.643408 -290.590478)
		(width 0.1143)
		(layer "In6.Cu")
		(net "P5E_CPU1_P2_RX_DN<2>")
	)
	(segment
		(start 128.603248 -318.622172)
		(end 126.831852 -315.970412)
		(width 0.14224)
		(layer "In6.Cu")
		(net "P5E_CPU1_P2_RX_DN<2>")
	)
	(segment
		(start 114.611658 -285.748984)
		(end 114.61242 -285.748476)
		(width 0.1143)
		(layer "In6.Cu")
		(net "P5E_CPU1_P2_RX_DN<2>")
	)
	(segment
		(start 146.795236 -377.35383)
		(end 146.826986 -377.162314)
		(width 0.14224)
		(layer "In6.Cu")
		(net "P5E_CPU1_P2_RX_DN<2>")
	)
	(segment
		(start 148.355812 -379.536198)
		(end 148.1074 -379.188726)
		(width 0.14224)
		(layer "In6.Cu")
		(net "P5E_CPU1_P2_RX_DN<2>")
	)
	(segment
		(start 114.61623 -294.826182)
		(end 114.61369 -294.824912)
		(width 0.1143)
		(layer "In6.Cu")
		(net "P5E_CPU1_P2_RX_DN<2>")
	)
	(segment
		(start 144.635474 -373.07266)
		(end 144.635474 -371.211602)
		(width 0.14224)
		(layer "In6.Cu")
		(net "P5E_CPU1_P2_RX_DN<2>")
	)
	(segment
		(start 115.112292 -295.651428)
		(end 115.042696 -295.610788)
		(width 0.1143)
		(layer "In6.Cu")
		(net "P5E_CPU1_P2_RX_DN<2>")
	)
	(segment
		(start 114.598704 -292.236398)
		(end 114.600228 -292.235382)
		(width 0.1143)
		(layer "In6.Cu")
		(net "P5E_CPU1_P2_RX_DN<2>")
	)
	(segment
		(start 114.61623 -293.20617)
		(end 114.61369 -293.2049)
		(width 0.1143)
		(layer "In6.Cu")
		(net "P5E_CPU1_P2_RX_DN<2>")
	)
	(segment
		(start 114.643408 -294.84193)
		(end 114.61877 -294.827706)
		(width 0.1143)
		(layer "In6.Cu")
		(net "P5E_CPU1_P2_RX_DN<2>")
	)
	(segment
		(start 114.600228 -292.235382)
		(end 114.602006 -292.234366)
		(width 0.1143)
		(layer "In6.Cu")
		(net "P5E_CPU1_P2_RX_DN<2>")
	)
	(segment
		(start 114.623596 -293.841932)
		(end 114.643408 -293.830502)
		(width 0.1143)
		(layer "In6.Cu")
		(net "P5E_CPU1_P2_RX_DN<2>")
	)
	(segment
		(start 115.269518 -295.955974)
		(end 115.269264 -295.956228)
		(width 0.1143)
		(layer "In6.Cu")
		(net "P5E_CPU1_P2_RX_DN<2>")
	)
	(segment
		(start 114.615976 -285.746444)
		(end 114.618008 -285.745174)
		(width 0.1143)
		(layer "In6.Cu")
		(net "P5E_CPU1_P2_RX_DN<2>")
	)
	(segment
		(start 114.620294 -293.84371)
		(end 114.621564 -293.842948)
		(width 0.1143)
		(layer "In6.Cu")
		(net "P5E_CPU1_P2_RX_DN<2>")
	)
	(segment
		(start 114.621564 -285.743142)
		(end 114.623596 -285.742126)
		(width 0.1143)
		(layer "In6.Cu")
		(net "P5E_CPU1_P2_RX_DN<2>")
	)
	(segment
		(start 114.61877 -294.827706)
		(end 114.61623 -294.826182)
		(width 0.1143)
		(layer "In6.Cu")
		(net "P5E_CPU1_P2_RX_DN<2>")
	)
	(segment
		(start 145.211038 -374.686068)
		(end 144.818862 -373.874792)
		(width 0.14224)
		(layer "In6.Cu")
		(net "P5E_CPU1_P2_RX_DN<2>")
	)
	(segment
		(start 114.618008 -290.604956)
		(end 114.619532 -290.604194)
		(width 0.1143)
		(layer "In6.Cu")
		(net "P5E_CPU1_P2_RX_DN<2>")
	)
	(segment
		(start 114.61369 -289.964876)
		(end 114.611658 -289.963606)
		(width 0.1143)
		(layer "In6.Cu")
		(net "P5E_CPU1_P2_RX_DN<2>")
	)
	(segment
		(start 114.611658 -293.20363)
		(end 114.610642 -293.203122)
		(width 0.1143)
		(layer "In6.Cu")
		(net "P5E_CPU1_P2_RX_DN<2>")
	)
	(segment
		(start 114.61242 -288.988246)
		(end 114.63401 -288.9758)
		(width 0.1143)
		(layer "In6.Cu")
		(net "P5E_CPU1_P2_RX_DN<2>")
	)
	(segment
		(start 116.470176 -302.218852)
		(end 115.276376 -299.335698)
		(width 0.14224)
		(layer "In6.Cu")
		(net "P5E_CPU1_P2_RX_DN<2>")
	)
	(segment
		(start 114.60607 -292.23208)
		(end 114.607594 -292.231064)
		(width 0.1143)
		(layer "In6.Cu")
		(net "P5E_CPU1_P2_RX_DN<2>")
	)
	(segment
		(start 148.547074 -379.567948)
		(end 148.355812 -379.536198)
		(width 0.14224)
		(layer "In6.Cu")
		(net "P5E_CPU1_P2_RX_DN<2>")
	)
	(segment
		(start 114.620294 -290.603686)
		(end 114.621564 -290.602924)
		(width 0.1143)
		(layer "In6.Cu")
		(net "P5E_CPU1_P2_RX_DN<2>")
	)
	(segment
		(start 114.61242 -293.848282)
		(end 114.61369 -293.84752)
		(width 0.1143)
		(layer "In6.Cu")
		(net "P5E_CPU1_P2_RX_DN<2>")
	)
	(segment
		(start 147.451318 -378.271278)
		(end 147.483068 -378.080016)
		(width 0.14224)
		(layer "In6.Cu")
		(net "P5E_CPU1_P2_RX_DN<2>")
	)
	(segment
		(start 114.620294 -285.743904)
		(end 114.621564 -285.743142)
		(width 0.1143)
		(layer "In6.Cu")
		(net "P5E_CPU1_P2_RX_DN<2>")
	)
	(segment
		(start 149.819106 -385.31038)
		(end 150.172166 -385.405376)
		(width 0.14224)
		(layer "In6.Cu")
		(net "P5E_CPU1_P2_RX_DN<2>")
	)
	(segment
		(start 114.615976 -290.606226)
		(end 114.618008 -290.604956)
		(width 0.1143)
		(layer "In6.Cu")
		(net "P5E_CPU1_P2_RX_DN<2>")
	)
	(segment
		(start 114.61242 -290.608258)
		(end 114.61369 -290.607496)
		(width 0.1143)
		(layer "In6.Cu")
		(net "P5E_CPU1_P2_RX_DN<2>")
	)
	(segment
		(start 148.1074 -379.188726)
		(end 148.13915 -378.997464)
		(width 0.14224)
		(layer "In6.Cu")
		(net "P5E_CPU1_P2_RX_DN<2>")
	)
	(segment
		(start 114.611658 -291.583618)
		(end 114.609118 -291.58184)
		(width 0.1143)
		(layer "In6.Cu")
		(net "P5E_CPU1_P2_RX_DN<2>")
	)
	(segment
		(start 114.609118 -291.58184)
		(end 114.570002 -291.559742)
		(width 0.1143)
		(layer "In6.Cu")
		(net "P5E_CPU1_P2_RX_DN<2>")
	)
	(segment
		(start 148.13915 -378.997464)
		(end 147.890992 -378.6505)
		(width 0.14224)
		(layer "In6.Cu")
		(net "P5E_CPU1_P2_RX_DN<2>")
	)
	(segment
		(start 114.643408 -291.601906)
		(end 114.61877 -291.587682)
		(width 0.1143)
		(layer "In6.Cu")
		(net "P5E_CPU1_P2_RX_DN<2>")
	)
	(segment
		(start 120.519952 -308.279546)
		(end 116.470176 -302.218852)
		(width 0.14224)
		(layer "In6.Cu")
		(net "P5E_CPU1_P2_RX_DN<2>")
	)
	(segment
		(start 114.61242 -291.584126)
		(end 114.611658 -291.583618)
		(width 0.1143)
		(layer "In6.Cu")
		(net "P5E_CPU1_P2_RX_DN<2>")
	)
	(segment
		(start 114.61369 -290.607496)
		(end 114.615976 -290.606226)
		(width 0.1143)
		(layer "In6.Cu")
		(net "P5E_CPU1_P2_RX_DN<2>")
	)
	(segment
		(start 147.890992 -378.6505)
		(end 147.69973 -378.61875)
		(width 0.14224)
		(layer "In6.Cu")
		(net "P5E_CPU1_P2_RX_DN<2>")
	)
	(segment
		(start 126.831852 -315.970412)
		(end 120.519952 -308.279546)
		(width 0.14224)
		(layer "In6.Cu")
		(net "P5E_CPU1_P2_RX_DN<2>")
	)
	(segment
		(start 114.604292 -292.233096)
		(end 114.60607 -292.23208)
		(width 0.1143)
		(layer "In6.Cu")
		(net "P5E_CPU1_P2_RX_DN<2>")
	)
	(segment
		(start 114.611658 -293.84879)
		(end 114.61242 -293.848282)
		(width 0.1143)
		(layer "In6.Cu")
		(net "P5E_CPU1_P2_RX_DN<2>")
	)
	(segment
		(start 114.619532 -285.744412)
		(end 114.620294 -285.743904)
		(width 0.1143)
		(layer "In6.Cu")
		(net "P5E_CPU1_P2_RX_DN<2>")
	)
	(segment
		(start 114.61877 -293.207694)
		(end 114.61623 -293.20617)
		(width 0.1143)
		(layer "In6.Cu")
		(net "P5E_CPU1_P2_RX_DN<2>")
	)
	(segment
		(start 114.61369 -292.227508)
		(end 114.615976 -292.226238)
		(width 0.1143)
		(layer "In6.Cu")
		(net "P5E_CPU1_P2_RX_DN<2>")
	)
	(segment
		(start 114.61369 -293.2049)
		(end 114.61242 -293.204138)
		(width 0.1143)
		(layer "In6.Cu")
		(net "P5E_CPU1_P2_RX_DN<2>")
	)
	(segment
		(start 114.643408 -293.221918)
		(end 114.61877 -293.207694)
		(width 0.1143)
		(layer "In6.Cu")
		(net "P5E_CPU1_P2_RX_DN<2>")
	)
	(segment
		(start 114.57813 -287.3883)
		(end 114.580162 -287.38703)
		(width 0.1143)
		(layer "In6.Cu")
		(net "P5E_CPU1_P2_RX_DN<2>")
	)
	(segment
		(start 114.792506 -285.496254)
		(end 114.722656 -285.426404)
		(width 0.1143)
		(layer "In6.Cu")
		(net "P5E_CPU1_P2_RX_DN<2>")
	)
	(segment
		(start 150.172166 -385.405376)
		(end 150.172674 -385.404868)
		(width 0.14224)
		(layer "In6.Cu")
		(net "P5E_CPU1_P2_RX_DN<2>")
	)
	(segment
		(start 146.826986 -377.162314)
		(end 145.962624 -375.95302)
		(width 0.14224)
		(layer "In6.Cu")
		(net "P5E_CPU1_P2_RX_DN<2>")
	)
	(segment
		(start 115.26901 -296.27957)
		(end 115.268756 -296.279316)
		(width 0.1143)
		(layer "In6.Cu")
		(net "P5E_CPU1_P2_RX_DN<2>")
	)
	(segment
		(start 114.618008 -285.745174)
		(end 114.619532 -285.744412)
		(width 0.1143)
		(layer "In6.Cu")
		(net "P5E_CPU1_P2_RX_DN<2>")
	)
	(segment
		(start 114.570002 -290.632642)
		(end 114.611658 -290.608766)
		(width 0.1143)
		(layer "In6.Cu")
		(net "P5E_CPU1_P2_RX_DN<2>")
	)
	(segment
		(start 114.61877 -291.587682)
		(end 114.61623 -291.586158)
		(width 0.1143)
		(layer "In6.Cu")
		(net "P5E_CPU1_P2_RX_DN<2>")
	)
	(segment
		(start 114.572542 -292.251638)
		(end 114.598704 -292.236398)
		(width 0.1143)
		(layer "In6.Cu")
		(net "P5E_CPU1_P2_RX_DN<2>")
	)
	(segment
		(start 114.623596 -292.22192)
		(end 114.643408 -292.21049)
		(width 0.1143)
		(layer "In6.Cu")
		(net "P5E_CPU1_P2_RX_DN<2>")
	)
	(segment
		(start 114.722656 -285.426404)
		(end 114.424714 -285.426404)
		(width 0.1143)
		(layer "In6.Cu")
		(net "P5E_CPU1_P2_RX_DN<2>")
	)
	(segment
		(start 114.61369 -285.747714)
		(end 114.615976 -285.746444)
		(width 0.1143)
		(layer "In6.Cu")
		(net "P5E_CPU1_P2_RX_DN<2>")
	)
	(segment
		(start 114.570002 -291.559742)
		(end 114.55781 -291.55009)
		(width 0.1143)
		(layer "In6.Cu")
		(net "P5E_CPU1_P2_RX_DN<2>")
	)
	(segment
		(start 114.615976 -293.84625)
		(end 114.618008 -293.84498)
		(width 0.1143)
		(layer "In6.Cu")
		(net "P5E_CPU1_P2_RX_DN<2>")
	)
	(segment
		(start 147.235164 -377.733052)
		(end 147.043648 -377.701302)
		(width 0.14224)
		(layer "In6.Cu")
		(net "P5E_CPU1_P2_RX_DN<2>")
	)
	(segment
		(start 114.61623 -289.966146)
		(end 114.61369 -289.964876)
		(width 0.1143)
		(layer "In6.Cu")
		(net "P5E_CPU1_P2_RX_DN<2>")
	)
	(segment
		(start 114.611658 -292.228778)
		(end 114.61242 -292.22827)
		(width 0.1143)
		(layer "In6.Cu")
		(net "P5E_CPU1_P2_RX_DN<2>")
	)
	(segment
		(start 114.611658 -294.823642)
		(end 114.609372 -294.822372)
		(width 0.1143)
		(layer "In6.Cu")
		(net "P5E_CPU1_P2_RX_DN<2>")
	)
	(segment
		(start 114.55781 -290.642294)
		(end 114.570002 -290.632642)
		(width 0.1143)
		(layer "In6.Cu")
		(net "P5E_CPU1_P2_RX_DN<2>")
	)
	(segment
		(start 114.609372 -293.85006)
		(end 114.611658 -293.84879)
		(width 0.1143)
		(layer "In6.Cu")
		(net "P5E_CPU1_P2_RX_DN<2>")
	)
	(segment
		(start 114.621564 -290.602924)
		(end 114.623596 -290.601908)
		(width 0.1143)
		(layer "In6.Cu")
		(net "P5E_CPU1_P2_RX_DN<2>")
	)
	(segment
		(start 150.172674 -385.404868)
		(end 150.29434 -385.334764)
		(width 0.14224)
		(layer "In6.Cu")
		(net "P5E_CPU1_P2_RX_DN<2>")
	)
	(segment
		(start 150.286212 -382.0414)
		(end 150.285958 -382.0414)
		(width 0.14224)
		(layer "In6.Cu")
		(net "P5E_CPU1_P2_RX_DN<2>")
	)
	(segment
		(start 149.982174 -384.234944)
		(end 150.286212 -383.93116)
		(width 0.14224)
		(layer "In6.Cu")
		(net "P5E_CPU1_P2_RX_DN<2>")
	)
	(segment
		(start 114.643408 -289.981894)
		(end 114.61877 -289.96767)
		(width 0.1143)
		(layer "In6.Cu")
		(net "P5E_CPU1_P2_RX_DN<2>")
	)
	(segment
		(start 114.611658 -290.608766)
		(end 114.61242 -290.608258)
		(width 0.1143)
		(layer "In6.Cu")
		(net "P5E_CPU1_P2_RX_DN<2>")
	)
	(segment
		(start 114.621564 -292.222936)
		(end 114.623596 -292.22192)
		(width 0.1143)
		(layer "In6.Cu")
		(net "P5E_CPU1_P2_RX_DN<2>")
	)
	(segment
		(start 114.580162 -287.38703)
		(end 114.643408 -287.350454)
		(width 0.1143)
		(layer "In6.Cu")
		(net "P5E_CPU1_P2_RX_DN<2>")
	)
	(segment
		(start 147.043648 -377.701302)
		(end 146.795236 -377.35383)
		(width 0.14224)
		(layer "In6.Cu")
		(net "P5E_CPU1_P2_RX_DN<2>")
	)
	(segment
		(start 115.22329 -299.068998)
		(end 115.22329 -296.353738)
		(width 0.14224)
		(layer "In6.Cu")
		(net "P5E_CPU1_P2_RX_DN<2>")
	)
	(segment
		(start 114.619532 -293.844218)
		(end 114.620294 -293.84371)
		(width 0.1143)
		(layer "In6.Cu")
		(net "P5E_CPU1_P2_RX_DN<2>")
	)
	(segment
		(start 114.61369 -293.84752)
		(end 114.615976 -293.84625)
		(width 0.1143)
		(layer "In6.Cu")
		(net "P5E_CPU1_P2_RX_DN<2>")
	)
	(segment
		(start 115.22329 -296.353738)
		(end 115.22329 -296.32529)
		(width 0.1143)
		(layer "In6.Cu")
		(net "P5E_CPU1_P2_RX_DN<2>")
	)
	(segment
		(start 114.611658 -288.988754)
		(end 114.61242 -288.988246)
		(width 0.1143)
		(layer "In6.Cu")
		(net "P5E_CPU1_P2_RX_DN<2>")
	)
	(segment
		(start 150.29434 -385.334764)
		(end 150.29434 -385.163822)
		(width 0.14224)
		(layer "In6.Cu")
		(net "P5E_CPU1_P2_RX_DN<2>")
	)
	(segment
		(start 114.623596 -285.742126)
		(end 114.643408 -285.730696)
		(width 0.1143)
		(layer "In6.Cu")
		(net "P5E_CPU1_P2_RX_DN<2>")
	)
	(segment
		(start 114.618008 -292.224968)
		(end 114.619532 -292.224206)
		(width 0.1143)
		(layer "In6.Cu")
		(net "P5E_CPU1_P2_RX_DN<2>")
	)
	(segment
		(start 144.547844 -371.000274)
		(end 144.104106 -370.556536)
		(width 0.14224)
		(layer "In6.Cu")
		(net "P5E_CPU1_P2_RX_DN<2>")
	)
	(segment
		(start 132.018532 -325.011288)
		(end 128.603248 -318.622172)
		(width 0.14224)
		(layer "In6.Cu")
		(net "P5E_CPU1_P2_RX_DN<2>")
	)
	(segment
		(start 114.619532 -292.224206)
		(end 114.620294 -292.223698)
		(width 0.1143)
		(layer "In6.Cu")
		(net "P5E_CPU1_P2_RX_DN<2>")
	)
	(segment
		(start 114.621564 -293.842948)
		(end 114.623596 -293.841932)
		(width 0.1143)
		(layer "In6.Cu")
		(net "P5E_CPU1_P2_RX_DN<2>")
	)
	(segment
		(start 114.61369 -294.824912)
		(end 114.611658 -294.823642)
		(width 0.1143)
		(layer "In6.Cu")
		(net "P5E_CPU1_P2_RX_DN<2>")
	)
	(segment
		(start 114.618008 -293.84498)
		(end 114.619532 -293.844218)
		(width 0.1143)
		(layer "In6.Cu")
		(net "P5E_CPU1_P2_RX_DN<2>")
	)
	(segment
		(start 114.61242 -292.22827)
		(end 114.61369 -292.227508)
		(width 0.1143)
		(layer "In6.Cu")
		(net "P5E_CPU1_P2_RX_DN<2>")
	)
	(segment
		(start 114.609372 -288.990024)
		(end 114.611658 -288.988754)
		(width 0.1143)
		(layer "In6.Cu")
		(net "P5E_CPU1_P2_RX_DN<2>")
	)
	(segment
		(start 114.610642 -293.203122)
		(end 114.609118 -293.202106)
		(width 0.1143)
		(layer "In6.Cu")
		(net "P5E_CPU1_P2_RX_DN<2>")
	)
	(segment
		(start 115.268756 -296.200576)
		(end 115.269518 -296.199814)
		(width 0.1143)
		(layer "In6.Cu")
		(net "P5E_CPU1_P2_RX_DN<2>")
	)
	(segment
		(start 114.61623 -291.586158)
		(end 114.61369 -291.584888)
		(width 0.1143)
		(layer "In6.Cu")
		(net "P5E_CPU1_P2_RX_DN<2>")
	)
	(segment
		(start 147.483068 -378.080016)
		(end 147.235164 -377.733052)
		(width 0.14224)
		(layer "In6.Cu")
		(net "P5E_CPU1_P2_RX_DN<2>")
	)
	(segment
		(start 144.635474 -371.211602)
		(end 144.63522 -371.211856)
		(width 0.14224)
		(layer "In6.Cu")
		(net "P5E_CPU1_P2_RX_DN<2>")
	)
	(segment
		(start 114.61242 -285.748476)
		(end 114.61369 -285.747714)
		(width 0.1143)
		(layer "In6.Cu")
		(net "P5E_CPU1_P2_RX_DN<2>")
	)
	(segment
		(start 142.856458 -368.158014)
		(end 136.785604 -348.145608)
		(width 0.14224)
		(layer "In6.Cu")
		(net "P5E_CPU1_P2_RX_DN<2>")
	)
	(segment
		(start 149.977348 -384.84683)
		(end 149.982174 -384.234944)
		(width 0.14224)
		(layer "In6.Cu")
		(net "P5E_CPU1_P2_RX_DN<2>")
	)
	(segment
		(start 114.61369 -291.584888)
		(end 114.61242 -291.584126)
		(width 0.1143)
		(layer "In6.Cu")
		(net "P5E_CPU1_P2_RX_DN<2>")
	)
	(segment
		(start 114.645186 -286.743394)
		(end 114.575336 -286.702754)
		(width 0.1143)
		(layer "In6.Cu")
		(net "P5E_CPU1_P2_RX_DN<2>")
	)
	(segment
		(start 142.856458 -369.4176)
		(end 142.856458 -368.158014)
		(width 0.14224)
		(layer "In6.Cu")
		(net "P5E_CPU1_P2_RX_DN<2>")
	)
	(segment
		(start 143.248126 -369.97894)
		(end 142.976346 -369.70716)
		(width 0.14224)
		(layer "In6.Cu")
		(net "P5E_CPU1_P2_RX_DN<2>")
	)
	(arc
		(start 114.329464 -287.856422)
		(mid 114.32946 -287.854263)
		(end 114.329464 -287.852104)
		(width 0.1143)
		(layer "In6.Cu")
		(net "P5E_CPU1_P2_RX_DN<2>")
	)
	(arc
		(start 144.818862 -373.874792)
		(mid 144.681795 -373.484097)
		(end 144.635474 -373.07266)
		(width 0.14224)
		(layer "In6.Cu")
		(net "P5E_CPU1_P2_RX_DN<2>")
	)
	(arc
		(start 114.799364 -287.046162)
		(mid 114.758602 -286.876278)
		(end 114.645186 -286.743394)
		(width 0.1143)
		(layer "In6.Cu")
		(net "P5E_CPU1_P2_RX_DN<2>")
	)
	(arc
		(start 114.643408 -285.730696)
		(mid 114.740543 -285.627827)
		(end 114.792506 -285.496254)
		(width 0.1143)
		(layer "In6.Cu")
		(net "P5E_CPU1_P2_RX_DN<2>")
	)
	(arc
		(start 114.55908 -285.781496)
		(mid 114.567158 -285.77571)
		(end 114.575336 -285.770066)
		(width 0.1143)
		(layer "In6.Cu")
		(net "P5E_CPU1_P2_RX_DN<2>")
	)
	(arc
		(start 114.329464 -286.23641)
		(mid 114.329454 -286.233108)
		(end 114.329464 -286.229806)
		(width 0.1143)
		(layer "In6.Cu")
		(net "P5E_CPU1_P2_RX_DN<2>")
	)
	(arc
		(start 114.609372 -294.822372)
		(mid 114.329444 -294.336216)
		(end 114.609372 -293.85006)
		(width 0.1143)
		(layer "In6.Cu")
		(net "P5E_CPU1_P2_RX_DN<2>")
	)
	(arc
		(start 114.799364 -295.146222)
		(mid 114.758109 -294.975251)
		(end 114.643408 -294.84193)
		(width 0.1143)
		(layer "In6.Cu")
		(net "P5E_CPU1_P2_RX_DN<2>")
	)
	(arc
		(start 114.63401 -288.9758)
		(mid 114.801389 -288.666174)
		(end 114.63401 -288.356548)
		(width 0.1143)
		(layer "In6.Cu")
		(net "P5E_CPU1_P2_RX_DN<2>")
	)
	(arc
		(start 114.561112 -287.399984)
		(mid 114.569569 -287.394066)
		(end 114.57813 -287.3883)
		(width 0.1143)
		(layer "In6.Cu")
		(net "P5E_CPU1_P2_RX_DN<2>")
	)
	(arc
		(start 114.329464 -287.852104)
		(mid 114.393441 -287.599474)
		(end 114.561112 -287.399984)
		(width 0.1143)
		(layer "In6.Cu")
		(net "P5E_CPU1_P2_RX_DN<2>")
	)
	(arc
		(start 114.643408 -293.830502)
		(mid 114.799336 -293.52621)
		(end 114.643408 -293.221918)
		(width 0.1143)
		(layer "In6.Cu")
		(net "P5E_CPU1_P2_RX_DN<2>")
	)
	(arc
		(start 114.643408 -290.590478)
		(mid 114.799336 -290.286186)
		(end 114.643408 -289.981894)
		(width 0.1143)
		(layer "In6.Cu")
		(net "P5E_CPU1_P2_RX_DN<2>")
	)
	(arc
		(start 114.55781 -291.55009)
		(mid 114.326712 -291.096192)
		(end 114.55781 -290.642294)
		(width 0.1143)
		(layer "In6.Cu")
		(net "P5E_CPU1_P2_RX_DN<2>")
	)
	(arc
		(start 114.643408 -292.21049)
		(mid 114.799336 -291.906198)
		(end 114.643408 -291.601906)
		(width 0.1143)
		(layer "In6.Cu")
		(net "P5E_CPU1_P2_RX_DN<2>")
	)
	(arc
		(start 114.643408 -287.350454)
		(mid 114.758084 -287.21712)
		(end 114.799364 -287.046162)
		(width 0.1143)
		(layer "In6.Cu")
		(net "P5E_CPU1_P2_RX_DN<2>")
	)
	(arc
		(start 115.236752 -295.803828)
		(mid 115.184707 -295.71931)
		(end 115.112292 -295.651428)
		(width 0.1143)
		(layer "In6.Cu")
		(net "P5E_CPU1_P2_RX_DN<2>")
	)
	(arc
		(start 115.276376 -299.335698)
		(mid 115.236685 -299.204963)
		(end 115.22329 -299.068998)
		(width 0.14224)
		(layer "In6.Cu")
		(net "P5E_CPU1_P2_RX_DN<2>")
	)
	(arc
		(start 114.329464 -286.229806)
		(mid 114.394336 -285.980064)
		(end 114.55908 -285.781496)
		(width 0.1143)
		(layer "In6.Cu")
		(net "P5E_CPU1_P2_RX_DN<2>")
	)
	(arc
		(start 114.575336 -286.702754)
		(mid 114.394684 -286.500009)
		(end 114.329464 -286.23641)
		(width 0.1143)
		(layer "In6.Cu")
		(net "P5E_CPU1_P2_RX_DN<2>")
	)
	(arc
		(start 115.269264 -295.956228)
		(mid 115.261015 -295.878321)
		(end 115.236752 -295.803828)
		(width 0.1143)
		(layer "In6.Cu")
		(net "P5E_CPU1_P2_RX_DN<2>")
	)
	(arc
		(start 145.962624 -375.95302)
		(mid 145.559824 -375.335565)
		(end 145.211038 -374.686068)
		(width 0.14224)
		(layer "In6.Cu")
		(net "P5E_CPU1_P2_RX_DN<2>")
	)
	(arc
		(start 150.285958 -382.0414)
		(mid 150.280054 -382.002615)
		(end 150.26259 -381.967486)
		(width 0.14224)
		(layer "In6.Cu")
		(net "P5E_CPU1_P2_RX_DN<2>")
	)
	(arc
		(start 114.57051 -288.319464)
		(mid 114.393314 -288.117452)
		(end 114.329464 -287.856422)
		(width 0.1143)
		(layer "In6.Cu")
		(net "P5E_CPU1_P2_RX_DN<2>")
	)
	(arc
		(start 114.609372 -289.962336)
		(mid 114.329444 -289.47618)
		(end 114.609372 -288.990024)
		(width 0.1143)
		(layer "In6.Cu")
		(net "P5E_CPU1_P2_RX_DN<2>")
	)
	(arc
		(start 142.976346 -369.70716)
		(mid 142.887631 -369.574295)
		(end 142.856458 -369.4176)
		(width 0.14224)
		(layer "In6.Cu")
		(net "P5E_CPU1_P2_RX_DN<2>")
	)
	(arc
		(start 143.698976 -370.328444)
		(mid 143.520961 -370.236085)
		(end 143.36141 -370.114576)
		(width 0.14224)
		(layer "In6.Cu")
		(net "P5E_CPU1_P2_RX_DN<2>")
	)
	(arc
		(start 144.63522 -371.211856)
		(mid 144.612629 -371.097342)
		(end 144.547844 -371.000274)
		(width 0.14224)
		(layer "In6.Cu")
		(net "P5E_CPU1_P2_RX_DN<2>")
	)
	(arc
		(start 115.042696 -295.610788)
		(mid 114.863883 -295.408438)
		(end 114.799364 -295.146222)
		(width 0.1143)
		(layer "In6.Cu")
		(net "P5E_CPU1_P2_RX_DN<2>")
	)
	(arc
		(start 143.36141 -370.114576)
		(mid 143.300069 -370.050683)
		(end 143.248126 -369.97894)
		(width 0.14224)
		(layer "In6.Cu")
		(net "P5E_CPU1_P2_RX_DN<2>")
	)
	(arc
		(start 114.572542 -293.18077)
		(mid 114.329215 -292.716204)
		(end 114.572542 -292.251638)
		(width 0.1143)
		(layer "In6.Cu")
		(net "P5E_CPU1_P2_RX_DN<2>")
	)
	(arc
		(start 144.104106 -370.556536)
		(mid 143.993653 -370.46589)
		(end 143.867632 -370.398548)
		(width 0.14224)
		(layer "In6.Cu")
		(net "P5E_CPU1_P2_RX_DN<2>")
	)
	(segment
		(start 113.957862 -283.540454)
		(end 114.424714 -283.806392)
		(width 0.12954)
		(layer "F.Cu")
		(net "P5E_CPU1_P2_RX_DN<1>")
	)
	(segment
		(start 148.098256 -385.31038)
		(end 148.618956 -385.31038)
		(width 0.127)
		(layer "F.Cu")
		(net "P5E_CPU1_P2_RX_DN<1>")
	)
	(segment
		(start 149.094444 -385.163822)
		(end 148.777452 -384.84683)
		(width 0.14224)
		(layer "In6.Cu")
		(net "P5E_CPU1_P2_RX_DN<1>")
	)
	(segment
		(start 113.641124 -289.006788)
		(end 113.673382 -288.987992)
		(width 0.1143)
		(layer "In6.Cu")
		(net "P5E_CPU1_P2_RX_DN<1>")
	)
	(segment
		(start 142.73022 -374.453404)
		(end 142.749778 -374.260618)
		(width 0.14224)
		(layer "In6.Cu")
		(net "P5E_CPU1_P2_RX_DN<1>")
	)
	(segment
		(start 144.426178 -376.532648)
		(end 144.156176 -376.201686)
		(width 0.14224)
		(layer "In6.Cu")
		(net "P5E_CPU1_P2_RX_DN<1>")
	)
	(segment
		(start 119.84101 -308.943248)
		(end 115.560856 -302.537368)
		(width 0.14224)
		(layer "In6.Cu")
		(net "P5E_CPU1_P2_RX_DN<1>")
	)
	(segment
		(start 113.671858 -290.608766)
		(end 113.702338 -290.590986)
		(width 0.1143)
		(layer "In6.Cu")
		(net "P5E_CPU1_P2_RX_DN<1>")
	)
	(segment
		(start 143.443198 -375.327672)
		(end 143.462756 -375.134632)
		(width 0.14224)
		(layer "In6.Cu")
		(net "P5E_CPU1_P2_RX_DN<1>")
	)
	(segment
		(start 114.283744 -299.216318)
		(end 114.283744 -296.353738)
		(width 0.14224)
		(layer "In6.Cu")
		(net "P5E_CPU1_P2_RX_DN<1>")
	)
	(segment
		(start 114.329464 -296.27957)
		(end 114.329464 -295.955974)
		(width 0.1143)
		(layer "In6.Cu")
		(net "P5E_CPU1_P2_RX_DN<1>")
	)
	(segment
		(start 144.619218 -376.552206)
		(end 144.426178 -376.532648)
		(width 0.14224)
		(layer "In6.Cu")
		(net "P5E_CPU1_P2_RX_DN<1>")
	)
	(segment
		(start 114.613182 -284.12821)
		(end 114.643408 -284.110684)
		(width 0.1143)
		(layer "In6.Cu")
		(net "P5E_CPU1_P2_RX_DN<1>")
	)
	(segment
		(start 114.722656 -283.806392)
		(end 114.424714 -283.806392)
		(width 0.1143)
		(layer "In6.Cu")
		(net "P5E_CPU1_P2_RX_DN<1>")
	)
	(segment
		(start 128.572768 -320.58102)
		(end 128.573022 -320.58102)
		(width 0.14224)
		(layer "In6.Cu")
		(net "P5E_CPU1_P2_RX_DN<1>")
	)
	(segment
		(start 148.97227 -385.405376)
		(end 148.972778 -385.404868)
		(width 0.14224)
		(layer "In6.Cu")
		(net "P5E_CPU1_P2_RX_DN<1>")
	)
	(segment
		(start 148.618956 -385.31038)
		(end 148.97227 -385.405376)
		(width 0.14224)
		(layer "In6.Cu")
		(net "P5E_CPU1_P2_RX_DN<1>")
	)
	(segment
		(start 113.70437 -286.742632)
		(end 113.671858 -286.723836)
		(width 0.1143)
		(layer "In6.Cu")
		(net "P5E_CPU1_P2_RX_DN<1>")
	)
	(segment
		(start 113.635536 -289.009836)
		(end 113.641124 -289.006788)
		(width 0.1143)
		(layer "In6.Cu")
		(net "P5E_CPU1_P2_RX_DN<1>")
	)
	(segment
		(start 113.671604 -292.228778)
		(end 113.672366 -292.22827)
		(width 0.1143)
		(layer "In6.Cu")
		(net "P5E_CPU1_P2_RX_DN<1>")
	)
	(segment
		(start 144.156176 -376.201686)
		(end 144.175734 -376.008646)
		(width 0.14224)
		(layer "In6.Cu")
		(net "P5E_CPU1_P2_RX_DN<1>")
	)
	(segment
		(start 115.560856 -302.537368)
		(end 114.374676 -299.673264)
		(width 0.14224)
		(layer "In6.Cu")
		(net "P5E_CPU1_P2_RX_DN<1>")
	)
	(segment
		(start 148.782278 -384.234944)
		(end 149.086316 -383.93116)
		(width 0.14224)
		(layer "In6.Cu")
		(net "P5E_CPU1_P2_RX_DN<1>")
	)
	(segment
		(start 113.672366 -292.22827)
		(end 113.673636 -292.227508)
		(width 0.1143)
		(layer "In6.Cu")
		(net "P5E_CPU1_P2_RX_DN<1>")
	)
	(segment
		(start 114.283744 -296.353738)
		(end 114.283744 -296.32529)
		(width 0.1143)
		(layer "In6.Cu")
		(net "P5E_CPU1_P2_RX_DN<1>")
	)
	(segment
		(start 113.702338 -291.601398)
		(end 113.671858 -291.583618)
		(width 0.1143)
		(layer "In6.Cu")
		(net "P5E_CPU1_P2_RX_DN<1>")
	)
	(segment
		(start 149.094444 -385.334764)
		(end 149.094444 -385.163822)
		(width 0.14224)
		(layer "In6.Cu")
		(net "P5E_CPU1_P2_RX_DN<1>")
	)
	(segment
		(start 135.546592 -347.754702)
		(end 131.07289 -325.2597)
		(width 0.14224)
		(layer "In6.Cu")
		(net "P5E_CPU1_P2_RX_DN<1>")
	)
	(segment
		(start 113.671604 -293.20363)
		(end 113.669064 -293.201852)
		(width 0.1143)
		(layer "In6.Cu")
		(net "P5E_CPU1_P2_RX_DN<1>")
	)
	(segment
		(start 114.612166 -284.128718)
		(end 114.613182 -284.12821)
		(width 0.1143)
		(layer "In6.Cu")
		(net "P5E_CPU1_P2_RX_DN<1>")
	)
	(segment
		(start 142.749778 -374.260618)
		(end 141.853666 -373.16156)
		(width 0.14224)
		(layer "In6.Cu")
		(net "P5E_CPU1_P2_RX_DN<1>")
	)
	(segment
		(start 113.677446 -288.346896)
		(end 113.673636 -288.34461)
		(width 0.1143)
		(layer "In6.Cu")
		(net "P5E_CPU1_P2_RX_DN<1>")
	)
	(segment
		(start 114.611404 -284.129226)
		(end 114.612166 -284.128718)
		(width 0.1143)
		(layer "In6.Cu")
		(net "P5E_CPU1_P2_RX_DN<1>")
	)
	(segment
		(start 131.07289 -325.2597)
		(end 131.072382 -325.258938)
		(width 0.14224)
		(layer "In6.Cu")
		(net "P5E_CPU1_P2_RX_DN<1>")
	)
	(segment
		(start 113.673636 -288.34461)
		(end 113.63198 -288.320734)
		(width 0.1143)
		(layer "In6.Cu")
		(net "P5E_CPU1_P2_RX_DN<1>")
	)
	(segment
		(start 113.671858 -291.583618)
		(end 113.635536 -291.562536)
		(width 0.1143)
		(layer "In6.Cu")
		(net "P5E_CPU1_P2_RX_DN<1>")
	)
	(segment
		(start 113.635536 -290.629848)
		(end 113.671858 -290.608766)
		(width 0.1143)
		(layer "In6.Cu")
		(net "P5E_CPU1_P2_RX_DN<1>")
	)
	(segment
		(start 143.7132 -375.658634)
		(end 143.443198 -375.327672)
		(width 0.14224)
		(layer "In6.Cu")
		(net "P5E_CPU1_P2_RX_DN<1>")
	)
	(segment
		(start 126.108968 -316.58052)
		(end 119.84101 -308.943248)
		(width 0.14224)
		(layer "In6.Cu")
		(net "P5E_CPU1_P2_RX_DN<1>")
	)
	(segment
		(start 113.701576 -285.731712)
		(end 113.702338 -285.731204)
		(width 0.1143)
		(layer "In6.Cu")
		(net "P5E_CPU1_P2_RX_DN<1>")
	)
	(segment
		(start 113.669064 -293.201852)
		(end 113.629948 -293.179754)
		(width 0.1143)
		(layer "In6.Cu")
		(net "P5E_CPU1_P2_RX_DN<1>")
	)
	(segment
		(start 113.673382 -288.987992)
		(end 113.677446 -288.985452)
		(width 0.1143)
		(layer "In6.Cu")
		(net "P5E_CPU1_P2_RX_DN<1>")
	)
	(segment
		(start 149.086316 -383.93116)
		(end 149.086316 -382.075182)
		(width 0.14224)
		(layer "In6.Cu")
		(net "P5E_CPU1_P2_RX_DN<1>")
	)
	(segment
		(start 113.63833 -287.3883)
		(end 113.702338 -287.350962)
		(width 0.1143)
		(layer "In6.Cu")
		(net "P5E_CPU1_P2_RX_DN<1>")
	)
	(segment
		(start 113.702338 -294.841422)
		(end 113.671858 -294.823642)
		(width 0.1143)
		(layer "In6.Cu")
		(net "P5E_CPU1_P2_RX_DN<1>")
	)
	(segment
		(start 114.792506 -283.876242)
		(end 114.722656 -283.806392)
		(width 0.1143)
		(layer "In6.Cu")
		(net "P5E_CPU1_P2_RX_DN<1>")
	)
	(segment
		(start 143.000222 -374.784366)
		(end 142.73022 -374.453404)
		(width 0.14224)
		(layer "In6.Cu")
		(net "P5E_CPU1_P2_RX_DN<1>")
	)
	(segment
		(start 140.799058 -368.720116)
		(end 135.546592 -347.754702)
		(width 0.14224)
		(layer "In6.Cu")
		(net "P5E_CPU1_P2_RX_DN<1>")
	)
	(segment
		(start 143.462756 -375.134632)
		(end 143.193262 -374.804178)
		(width 0.14224)
		(layer "In6.Cu")
		(net "P5E_CPU1_P2_RX_DN<1>")
	)
	(segment
		(start 141.048232 -371.362224)
		(end 140.799058 -368.720116)
		(width 0.14224)
		(layer "In6.Cu")
		(net "P5E_CPU1_P2_RX_DN<1>")
	)
	(segment
		(start 114.329464 -295.955974)
		(end 114.32921 -295.956228)
		(width 0.1143)
		(layer "In6.Cu")
		(net "P5E_CPU1_P2_RX_DN<1>")
	)
	(segment
		(start 113.673636 -292.227508)
		(end 113.703354 -292.21049)
		(width 0.1143)
		(layer "In6.Cu")
		(net "P5E_CPU1_P2_RX_DN<1>")
	)
	(segment
		(start 113.671858 -286.723836)
		(end 113.669572 -286.722566)
		(width 0.1143)
		(layer "In6.Cu")
		(net "P5E_CPU1_P2_RX_DN<1>")
	)
	(segment
		(start 144.175734 -376.008646)
		(end 143.90624 -375.678192)
		(width 0.14224)
		(layer "In6.Cu")
		(net "P5E_CPU1_P2_RX_DN<1>")
	)
	(segment
		(start 149.086316 -382.075182)
		(end 149.086062 -382.075436)
		(width 0.14224)
		(layer "In6.Cu")
		(net "P5E_CPU1_P2_RX_DN<1>")
	)
	(segment
		(start 113.671858 -294.823642)
		(end 113.635536 -294.80256)
		(width 0.1143)
		(layer "In6.Cu")
		(net "P5E_CPU1_P2_RX_DN<1>")
	)
	(segment
		(start 113.702338 -289.981386)
		(end 113.671858 -289.963606)
		(width 0.1143)
		(layer "In6.Cu")
		(net "P5E_CPU1_P2_RX_DN<1>")
	)
	(segment
		(start 114.172238 -295.651428)
		(end 114.102642 -295.610788)
		(width 0.1143)
		(layer "In6.Cu")
		(net "P5E_CPU1_P2_RX_DN<1>")
	)
	(segment
		(start 113.617756 -292.262306)
		(end 113.629948 -292.252654)
		(width 0.1143)
		(layer "In6.Cu")
		(net "P5E_CPU1_P2_RX_DN<1>")
	)
	(segment
		(start 127.739902 -319.021968)
		(end 126.108968 -316.58052)
		(width 0.14224)
		(layer "In6.Cu")
		(net "P5E_CPU1_P2_RX_DN<1>")
	)
	(segment
		(start 113.672366 -293.204138)
		(end 113.671604 -293.20363)
		(width 0.1143)
		(layer "In6.Cu")
		(net "P5E_CPU1_P2_RX_DN<1>")
	)
	(segment
		(start 114.141758 -284.938978)
		(end 114.173508 -284.92069)
		(width 0.1143)
		(layer "In6.Cu")
		(net "P5E_CPU1_P2_RX_DN<1>")
	)
	(segment
		(start 113.673636 -293.2049)
		(end 113.672366 -293.204138)
		(width 0.1143)
		(layer "In6.Cu")
		(net "P5E_CPU1_P2_RX_DN<1>")
	)
	(segment
		(start 131.072382 -325.258938)
		(end 128.572768 -320.58102)
		(width 0.14224)
		(layer "In6.Cu")
		(net "P5E_CPU1_P2_RX_DN<1>")
	)
	(segment
		(start 114.102642 -284.961838)
		(end 114.141758 -284.938978)
		(width 0.1143)
		(layer "In6.Cu")
		(net "P5E_CPU1_P2_RX_DN<1>")
	)
	(segment
		(start 113.671858 -289.963606)
		(end 113.635536 -289.942524)
		(width 0.1143)
		(layer "In6.Cu")
		(net "P5E_CPU1_P2_RX_DN<1>")
	)
	(segment
		(start 114.575336 -284.150054)
		(end 114.611404 -284.129226)
		(width 0.1143)
		(layer "In6.Cu")
		(net "P5E_CPU1_P2_RX_DN<1>")
	)
	(segment
		(start 148.777452 -384.84683)
		(end 148.782278 -384.234944)
		(width 0.14224)
		(layer "In6.Cu")
		(net "P5E_CPU1_P2_RX_DN<1>")
	)
	(segment
		(start 113.703354 -293.221918)
		(end 113.673636 -293.2049)
		(width 0.1143)
		(layer "In6.Cu")
		(net "P5E_CPU1_P2_RX_DN<1>")
	)
	(segment
		(start 113.629948 -293.179754)
		(end 113.617756 -293.170102)
		(width 0.1143)
		(layer "In6.Cu")
		(net "P5E_CPU1_P2_RX_DN<1>")
	)
	(segment
		(start 148.972778 -385.404868)
		(end 149.094444 -385.334764)
		(width 0.14224)
		(layer "In6.Cu")
		(net "P5E_CPU1_P2_RX_DN<1>")
	)
	(segment
		(start 113.671858 -293.84879)
		(end 113.702338 -293.83101)
		(width 0.1143)
		(layer "In6.Cu")
		(net "P5E_CPU1_P2_RX_DN<1>")
	)
	(segment
		(start 113.635536 -293.869872)
		(end 113.671858 -293.84879)
		(width 0.1143)
		(layer "In6.Cu")
		(net "P5E_CPU1_P2_RX_DN<1>")
	)
	(segment
		(start 143.90624 -375.678192)
		(end 143.7132 -375.658634)
		(width 0.14224)
		(layer "In6.Cu")
		(net "P5E_CPU1_P2_RX_DN<1>")
	)
	(segment
		(start 113.669572 -285.750254)
		(end 113.671858 -285.748984)
		(width 0.1143)
		(layer "In6.Cu")
		(net "P5E_CPU1_P2_RX_DN<1>")
	)
	(segment
		(start 113.671858 -285.748984)
		(end 113.701576 -285.731712)
		(width 0.1143)
		(layer "In6.Cu")
		(net "P5E_CPU1_P2_RX_DN<1>")
	)
	(segment
		(start 128.573022 -320.58102)
		(end 127.739902 -319.021968)
		(width 0.14224)
		(layer "In6.Cu")
		(net "P5E_CPU1_P2_RX_DN<1>")
	)
	(segment
		(start 149.057614 -381.995172)
		(end 144.619218 -376.552206)
		(width 0.14224)
		(layer "In6.Cu")
		(net "P5E_CPU1_P2_RX_DN<1>")
	)
	(segment
		(start 114.283744 -296.32529)
		(end 114.329464 -296.27957)
		(width 0.1143)
		(layer "In6.Cu")
		(net "P5E_CPU1_P2_RX_DN<1>")
	)
	(segment
		(start 113.629948 -292.252654)
		(end 113.671604 -292.228778)
		(width 0.1143)
		(layer "In6.Cu")
		(net "P5E_CPU1_P2_RX_DN<1>")
	)
	(segment
		(start 141.269212 -372.20779)
		(end 141.267688 -372.204488)
		(width 0.14224)
		(layer "In6.Cu")
		(net "P5E_CPU1_P2_RX_DN<1>")
	)
	(segment
		(start 143.193262 -374.804178)
		(end 143.000222 -374.784366)
		(width 0.14224)
		(layer "In6.Cu")
		(net "P5E_CPU1_P2_RX_DN<1>")
	)
	(arc
		(start 113.703354 -292.21049)
		(mid 113.81803 -292.077156)
		(end 113.85931 -291.906198)
		(width 0.1143)
		(layer "In6.Cu")
		(net "P5E_CPU1_P2_RX_DN<1>")
	)
	(arc
		(start 114.297968 -295.806622)
		(mid 114.245625 -295.720505)
		(end 114.172238 -295.651428)
		(width 0.1143)
		(layer "In6.Cu")
		(net "P5E_CPU1_P2_RX_DN<1>")
	)
	(arc
		(start 141.853666 -373.16156)
		(mid 141.52936 -372.704332)
		(end 141.269212 -372.20779)
		(width 0.14224)
		(layer "In6.Cu")
		(net "P5E_CPU1_P2_RX_DN<1>")
	)
	(arc
		(start 114.374676 -299.673264)
		(mid 114.306725 -299.449267)
		(end 114.283744 -299.216318)
		(width 0.14224)
		(layer "In6.Cu")
		(net "P5E_CPU1_P2_RX_DN<1>")
	)
	(arc
		(start 141.267688 -372.204488)
		(mid 141.124015 -371.792201)
		(end 141.048232 -371.362224)
		(width 0.14224)
		(layer "In6.Cu")
		(net "P5E_CPU1_P2_RX_DN<1>")
	)
	(arc
		(start 113.85931 -285.426404)
		(mid 113.923825 -285.164185)
		(end 114.102642 -284.961838)
		(width 0.1143)
		(layer "In6.Cu")
		(net "P5E_CPU1_P2_RX_DN<1>")
	)
	(arc
		(start 113.677446 -288.985452)
		(mid 113.859607 -288.666174)
		(end 113.677446 -288.346896)
		(width 0.1143)
		(layer "In6.Cu")
		(net "P5E_CPU1_P2_RX_DN<1>")
	)
	(arc
		(start 113.617756 -293.170102)
		(mid 113.386658 -292.716204)
		(end 113.617756 -292.262306)
		(width 0.1143)
		(layer "In6.Cu")
		(net "P5E_CPU1_P2_RX_DN<1>")
	)
	(arc
		(start 113.635536 -291.562536)
		(mid 113.389646 -291.096192)
		(end 113.635536 -290.629848)
		(width 0.1143)
		(layer "In6.Cu")
		(net "P5E_CPU1_P2_RX_DN<1>")
	)
	(arc
		(start 114.329718 -284.630114)
		(mid 114.330482 -284.606708)
		(end 114.332512 -284.583378)
		(width 0.1143)
		(layer "In6.Cu")
		(net "P5E_CPU1_P2_RX_DN<1>")
	)
	(arc
		(start 113.389664 -287.856422)
		(mid 113.455694 -287.591394)
		(end 113.63833 -287.3883)
		(width 0.1143)
		(layer "In6.Cu")
		(net "P5E_CPU1_P2_RX_DN<1>")
	)
	(arc
		(start 113.85931 -291.906198)
		(mid 113.817761 -291.734776)
		(end 113.702338 -291.601398)
		(width 0.1143)
		(layer "In6.Cu")
		(net "P5E_CPU1_P2_RX_DN<1>")
	)
	(arc
		(start 113.85931 -295.146222)
		(mid 113.817761 -294.9748)
		(end 113.702338 -294.841422)
		(width 0.1143)
		(layer "In6.Cu")
		(net "P5E_CPU1_P2_RX_DN<1>")
	)
	(arc
		(start 113.702338 -290.590986)
		(mid 113.859315 -290.286186)
		(end 113.702338 -289.981386)
		(width 0.1143)
		(layer "In6.Cu")
		(net "P5E_CPU1_P2_RX_DN<1>")
	)
	(arc
		(start 113.85931 -293.52621)
		(mid 113.818055 -293.355239)
		(end 113.703354 -293.221918)
		(width 0.1143)
		(layer "In6.Cu")
		(net "P5E_CPU1_P2_RX_DN<1>")
	)
	(arc
		(start 114.32921 -295.956228)
		(mid 114.321327 -295.879806)
		(end 114.297968 -295.806622)
		(width 0.1143)
		(layer "In6.Cu")
		(net "P5E_CPU1_P2_RX_DN<1>")
	)
	(arc
		(start 113.63198 -288.320734)
		(mid 113.453798 -288.118331)
		(end 113.389664 -287.856422)
		(width 0.1143)
		(layer "In6.Cu")
		(net "P5E_CPU1_P2_RX_DN<1>")
	)
	(arc
		(start 114.332512 -284.583378)
		(mid 114.412055 -284.343247)
		(end 114.575336 -284.150054)
		(width 0.1143)
		(layer "In6.Cu")
		(net "P5E_CPU1_P2_RX_DN<1>")
	)
	(arc
		(start 114.173508 -284.92069)
		(mid 114.285251 -284.79349)
		(end 114.329718 -284.630114)
		(width 0.1143)
		(layer "In6.Cu")
		(net "P5E_CPU1_P2_RX_DN<1>")
	)
	(arc
		(start 149.086062 -382.075436)
		(mid 149.078794 -382.032833)
		(end 149.057614 -381.995172)
		(width 0.14224)
		(layer "In6.Cu")
		(net "P5E_CPU1_P2_RX_DN<1>")
	)
	(arc
		(start 113.702338 -287.350962)
		(mid 113.817765 -287.217586)
		(end 113.85931 -287.046162)
		(width 0.1143)
		(layer "In6.Cu")
		(net "P5E_CPU1_P2_RX_DN<1>")
	)
	(arc
		(start 114.643408 -284.110684)
		(mid 114.740543 -284.007815)
		(end 114.792506 -283.876242)
		(width 0.1143)
		(layer "In6.Cu")
		(net "P5E_CPU1_P2_RX_DN<1>")
	)
	(arc
		(start 114.102642 -295.610788)
		(mid 113.923829 -295.408438)
		(end 113.85931 -295.146222)
		(width 0.1143)
		(layer "In6.Cu")
		(net "P5E_CPU1_P2_RX_DN<1>")
	)
	(arc
		(start 113.702338 -285.731204)
		(mid 113.817765 -285.597828)
		(end 113.85931 -285.426404)
		(width 0.1143)
		(layer "In6.Cu")
		(net "P5E_CPU1_P2_RX_DN<1>")
	)
	(arc
		(start 113.635536 -294.80256)
		(mid 113.389646 -294.336216)
		(end 113.635536 -293.869872)
		(width 0.1143)
		(layer "In6.Cu")
		(net "P5E_CPU1_P2_RX_DN<1>")
	)
	(arc
		(start 113.669572 -286.722566)
		(mid 113.389644 -286.23641)
		(end 113.669572 -285.750254)
		(width 0.1143)
		(layer "In6.Cu")
		(net "P5E_CPU1_P2_RX_DN<1>")
	)
	(arc
		(start 113.702338 -293.83101)
		(mid 113.817765 -293.697634)
		(end 113.85931 -293.52621)
		(width 0.1143)
		(layer "In6.Cu")
		(net "P5E_CPU1_P2_RX_DN<1>")
	)
	(arc
		(start 113.85931 -287.046162)
		(mid 113.818344 -286.875756)
		(end 113.70437 -286.742632)
		(width 0.1143)
		(layer "In6.Cu")
		(net "P5E_CPU1_P2_RX_DN<1>")
	)
	(arc
		(start 113.635536 -289.942524)
		(mid 113.389646 -289.47618)
		(end 113.635536 -289.009836)
		(width 0.1143)
		(layer "In6.Cu")
		(net "P5E_CPU1_P2_RX_DN<1>")
	)
	(segment
		(start 124.767848 -282.730448)
		(end 125.2347 -282.996386)
		(width 0.12954)
		(layer "F.Cu")
		(net "P5E_CPU1_P2_RX_DN<15>")
	)
	(segment
		(start 164.898324 -385.31038)
		(end 165.419024 -385.31038)
		(width 0.127)
		(layer "F.Cu")
		(net "P5E_CPU1_P2_RX_DN<15>")
	)
	(segment
		(start 126.393194 -284.312106)
		(end 126.389892 -284.310074)
		(width 0.1143)
		(layer "In6.Cu")
		(net "P5E_CPU1_P2_RX_DN<15>")
	)
	(segment
		(start 125.615446 -283.07919)
		(end 125.532642 -282.996386)
		(width 0.1143)
		(layer "In6.Cu")
		(net "P5E_CPU1_P2_RX_DN<15>")
	)
	(segment
		(start 168.393618 -380.135384)
		(end 168.55186 -380.023116)
		(width 0.14224)
		(layer "In6.Cu")
		(net "P5E_CPU1_P2_RX_DN<15>")
	)
	(segment
		(start 165.772846 -385.404868)
		(end 165.894512 -385.334764)
		(width 0.14224)
		(layer "In6.Cu")
		(net "P5E_CPU1_P2_RX_DN<15>")
	)
	(segment
		(start 172.109892 -367.452148)
		(end 171.196508 -366.538764)
		(width 0.14224)
		(layer "In6.Cu")
		(net "P5E_CPU1_P2_RX_DN<15>")
	)
	(segment
		(start 126.359412 -284.292548)
		(end 126.358142 -284.291786)
		(width 0.1143)
		(layer "In6.Cu")
		(net "P5E_CPU1_P2_RX_DN<15>")
	)
	(segment
		(start 138.15187 -310.382158)
		(end 134.36981 -305.774344)
		(width 0.14224)
		(layer "In6.Cu")
		(net "P5E_CPU1_P2_RX_DN<15>")
	)
	(segment
		(start 126.794006 -290.63061)
		(end 126.863602 -290.590224)
		(width 0.1143)
		(layer "In6.Cu")
		(net "P5E_CPU1_P2_RX_DN<15>")
	)
	(segment
		(start 127.309626 -285.918148)
		(end 127.305562 -285.915862)
		(width 0.1143)
		(layer "In6.Cu")
		(net "P5E_CPU1_P2_RX_DN<15>")
	)
	(segment
		(start 127.301752 -285.913576)
		(end 127.293116 -285.90875)
		(width 0.1143)
		(layer "In6.Cu")
		(net "P5E_CPU1_P2_RX_DN<15>")
	)
	(segment
		(start 168.246552 -381.826516)
		(end 168.134284 -381.668528)
		(width 0.14224)
		(layer "In6.Cu")
		(net "P5E_CPU1_P2_RX_DN<15>")
	)
	(segment
		(start 125.913896 -283.496512)
		(end 125.85319 -283.46146)
		(width 0.1143)
		(layer "In6.Cu")
		(net "P5E_CPU1_P2_RX_DN<15>")
	)
	(segment
		(start 127.44704 -296.466006)
		(end 127.44704 -296.295318)
		(width 0.14224)
		(layer "In6.Cu")
		(net "P5E_CPU1_P2_RX_DN<15>")
	)
	(segment
		(start 126.079504 -283.816298)
		(end 126.079504 -283.815536)
		(width 0.1143)
		(layer "In6.Cu")
		(net "P5E_CPU1_P2_RX_DN<15>")
	)
	(segment
		(start 126.393448 -284.312106)
		(end 126.393194 -284.312106)
		(width 0.1143)
		(layer "In6.Cu")
		(net "P5E_CPU1_P2_RX_DN<15>")
	)
	(segment
		(start 134.36981 -305.774344)
		(end 134.370064 -305.774344)
		(width 0.14224)
		(layer "In6.Cu")
		(net "P5E_CPU1_P2_RX_DN<15>")
	)
	(segment
		(start 126.388368 -284.309312)
		(end 126.386082 -284.307788)
		(width 0.1143)
		(layer "In6.Cu")
		(net "P5E_CPU1_P2_RX_DN<15>")
	)
	(segment
		(start 125.6157 -283.07919)
		(end 125.615446 -283.07919)
		(width 0.1143)
		(layer "In6.Cu")
		(net "P5E_CPU1_P2_RX_DN<15>")
	)
	(segment
		(start 127.44704 -296.295318)
		(end 127.44704 -296.26687)
		(width 0.1143)
		(layer "In6.Cu")
		(net "P5E_CPU1_P2_RX_DN<15>")
	)
	(segment
		(start 126.863602 -289.982148)
		(end 126.79426 -289.941762)
		(width 0.1143)
		(layer "In6.Cu")
		(net "P5E_CPU1_P2_RX_DN<15>")
	)
	(segment
		(start 126.794006 -289.010598)
		(end 126.863602 -288.970212)
		(width 0.1143)
		(layer "In6.Cu")
		(net "P5E_CPU1_P2_RX_DN<15>")
	)
	(segment
		(start 130.588258 -301.166022)
		(end 127.44704 -296.466006)
		(width 0.14224)
		(layer "In6.Cu")
		(net "P5E_CPU1_P2_RX_DN<15>")
	)
	(segment
		(start 127.337312 -295.654476)
		(end 127.26289 -295.611296)
		(width 0.1143)
		(layer "In6.Cu")
		(net "P5E_CPU1_P2_RX_DN<15>")
	)
	(segment
		(start 165.894512 -384.876548)
		(end 166.58844 -384.133598)
		(width 0.14224)
		(layer "In6.Cu")
		(net "P5E_CPU1_P2_RX_DN<15>")
	)
	(segment
		(start 126.863602 -291.60216)
		(end 126.79426 -291.561774)
		(width 0.1143)
		(layer "In6.Cu")
		(net "P5E_CPU1_P2_RX_DN<15>")
	)
	(segment
		(start 126.79426 -287.39084)
		(end 126.86157 -287.351724)
		(width 0.1143)
		(layer "In6.Cu")
		(net "P5E_CPU1_P2_RX_DN<15>")
	)
	(segment
		(start 126.357126 -284.291024)
		(end 126.355856 -284.290262)
		(width 0.1143)
		(layer "In6.Cu")
		(net "P5E_CPU1_P2_RX_DN<15>")
	)
	(segment
		(start 127.293116 -285.90875)
		(end 127.292862 -285.90875)
		(width 0.1143)
		(layer "In6.Cu")
		(net "P5E_CPU1_P2_RX_DN<15>")
	)
	(segment
		(start 127.305562 -285.915862)
		(end 127.301752 -285.913576)
		(width 0.1143)
		(layer "In6.Cu")
		(net "P5E_CPU1_P2_RX_DN<15>")
	)
	(segment
		(start 168.205404 -381.247396)
		(end 168.363646 -381.135128)
		(width 0.14224)
		(layer "In6.Cu")
		(net "P5E_CPU1_P2_RX_DN<15>")
	)
	(segment
		(start 126.794006 -293.870634)
		(end 126.863602 -293.830248)
		(width 0.1143)
		(layer "In6.Cu")
		(net "P5E_CPU1_P2_RX_DN<15>")
	)
	(segment
		(start 168.322244 -380.556516)
		(end 168.393618 -380.135384)
		(width 0.14224)
		(layer "In6.Cu")
		(net "P5E_CPU1_P2_RX_DN<15>")
	)
	(segment
		(start 171.93641 -371.980206)
		(end 172.404786 -370.316252)
		(width 0.14224)
		(layer "In6.Cu")
		(net "P5E_CPU1_P2_RX_DN<15>")
	)
	(segment
		(start 165.894512 -385.334764)
		(end 165.894512 -384.876548)
		(width 0.14224)
		(layer "In6.Cu")
		(net "P5E_CPU1_P2_RX_DN<15>")
	)
	(segment
		(start 170.835574 -366.271048)
		(end 165.725856 -363.539024)
		(width 0.14224)
		(layer "In6.Cu")
		(net "P5E_CPU1_P2_RX_DN<15>")
	)
	(segment
		(start 168.434766 -380.714504)
		(end 168.322244 -380.556516)
		(width 0.14224)
		(layer "In6.Cu")
		(net "P5E_CPU1_P2_RX_DN<15>")
	)
	(segment
		(start 127.49276 -296.22115)
		(end 127.49276 -295.94048)
		(width 0.1143)
		(layer "In6.Cu")
		(net "P5E_CPU1_P2_RX_DN<15>")
	)
	(segment
		(start 165.772338 -385.405376)
		(end 165.772846 -385.404868)
		(width 0.14224)
		(layer "In6.Cu")
		(net "P5E_CPU1_P2_RX_DN<15>")
	)
	(segment
		(start 126.863602 -288.36239)
		(end 126.79172 -288.32048)
		(width 0.1143)
		(layer "In6.Cu")
		(net "P5E_CPU1_P2_RX_DN<15>")
	)
	(segment
		(start 125.532642 -282.996386)
		(end 125.2347 -282.996386)
		(width 0.1143)
		(layer "In6.Cu")
		(net "P5E_CPU1_P2_RX_DN<15>")
	)
	(segment
		(start 144.219676 -321.732656)
		(end 138.15187 -310.382158)
		(width 0.14224)
		(layer "In6.Cu")
		(net "P5E_CPU1_P2_RX_DN<15>")
	)
	(segment
		(start 126.355856 -284.290262)
		(end 126.323344 -284.27172)
		(width 0.1143)
		(layer "In6.Cu")
		(net "P5E_CPU1_P2_RX_DN<15>")
	)
	(segment
		(start 165.340538 -363.25302)
		(end 156.004768 -353.91725)
		(width 0.14224)
		(layer "In6.Cu")
		(net "P5E_CPU1_P2_RX_DN<15>")
	)
	(segment
		(start 127.44704 -296.26687)
		(end 127.49276 -296.22115)
		(width 0.1143)
		(layer "In6.Cu")
		(net "P5E_CPU1_P2_RX_DN<15>")
	)
	(segment
		(start 127.333502 -285.932118)
		(end 127.309626 -285.918148)
		(width 0.1143)
		(layer "In6.Cu")
		(net "P5E_CPU1_P2_RX_DN<15>")
	)
	(segment
		(start 126.794006 -292.250622)
		(end 126.863602 -292.210236)
		(width 0.1143)
		(layer "In6.Cu")
		(net "P5E_CPU1_P2_RX_DN<15>")
	)
	(segment
		(start 146.794728 -334.383634)
		(end 145.118836 -325.148194)
		(width 0.14224)
		(layer "In6.Cu")
		(net "P5E_CPU1_P2_RX_DN<15>")
	)
	(segment
		(start 126.386082 -284.307788)
		(end 126.374144 -284.30093)
		(width 0.1143)
		(layer "In6.Cu")
		(net "P5E_CPU1_P2_RX_DN<15>")
	)
	(segment
		(start 127.292862 -285.90875)
		(end 127.289814 -285.906972)
		(width 0.1143)
		(layer "In6.Cu")
		(net "P5E_CPU1_P2_RX_DN<15>")
	)
	(segment
		(start 126.389892 -284.310074)
		(end 126.388368 -284.309312)
		(width 0.1143)
		(layer "In6.Cu")
		(net "P5E_CPU1_P2_RX_DN<15>")
	)
	(segment
		(start 126.863602 -293.222172)
		(end 126.79426 -293.181786)
		(width 0.1143)
		(layer "In6.Cu")
		(net "P5E_CPU1_P2_RX_DN<15>")
	)
	(segment
		(start 126.863602 -294.842184)
		(end 126.79426 -294.801798)
		(width 0.1143)
		(layer "In6.Cu")
		(net "P5E_CPU1_P2_RX_DN<15>")
	)
	(segment
		(start 126.358142 -284.291786)
		(end 126.357126 -284.291024)
		(width 0.1143)
		(layer "In6.Cu")
		(net "P5E_CPU1_P2_RX_DN<15>")
	)
	(segment
		(start 168.55186 -380.023116)
		(end 169.263314 -375.818908)
		(width 0.14224)
		(layer "In6.Cu")
		(net "P5E_CPU1_P2_RX_DN<15>")
	)
	(segment
		(start 127.289814 -285.906972)
		(end 127.28829 -285.905956)
		(width 0.1143)
		(layer "In6.Cu")
		(net "P5E_CPU1_P2_RX_DN<15>")
	)
	(segment
		(start 166.58844 -384.133598)
		(end 167.37965 -383.413762)
		(width 0.14224)
		(layer "In6.Cu")
		(net "P5E_CPU1_P2_RX_DN<15>")
	)
	(segment
		(start 167.396922 -383.394712)
		(end 168.094152 -382.439926)
		(width 0.14224)
		(layer "In6.Cu")
		(net "P5E_CPU1_P2_RX_DN<15>")
	)
	(segment
		(start 126.374144 -284.30093)
		(end 126.366016 -284.296866)
		(width 0.1143)
		(layer "In6.Cu")
		(net "P5E_CPU1_P2_RX_DN<15>")
	)
	(segment
		(start 169.455846 -375.364756)
		(end 171.916598 -372.020846)
		(width 0.14224)
		(layer "In6.Cu")
		(net "P5E_CPU1_P2_RX_DN<15>")
	)
	(segment
		(start 134.370064 -305.774344)
		(end 130.588258 -301.166022)
		(width 0.14224)
		(layer "In6.Cu")
		(net "P5E_CPU1_P2_RX_DN<15>")
	)
	(segment
		(start 168.134284 -381.668528)
		(end 168.205404 -381.247396)
		(width 0.14224)
		(layer "In6.Cu")
		(net "P5E_CPU1_P2_RX_DN<15>")
	)
	(segment
		(start 126.863602 -285.122366)
		(end 126.79426 -285.08198)
		(width 0.1143)
		(layer "In6.Cu")
		(net "P5E_CPU1_P2_RX_DN<15>")
	)
	(segment
		(start 127.260604 -286.58312)
		(end 127.333756 -286.540448)
		(width 0.1143)
		(layer "In6.Cu")
		(net "P5E_CPU1_P2_RX_DN<15>")
	)
	(segment
		(start 127.28829 -285.905956)
		(end 127.263398 -285.891478)
		(width 0.1143)
		(layer "In6.Cu")
		(net "P5E_CPU1_P2_RX_DN<15>")
	)
	(segment
		(start 126.366016 -284.296866)
		(end 126.359412 -284.292548)
		(width 0.1143)
		(layer "In6.Cu")
		(net "P5E_CPU1_P2_RX_DN<15>")
	)
	(segment
		(start 172.415454 -370.190776)
		(end 172.133006 -367.500408)
		(width 0.14224)
		(layer "In6.Cu")
		(net "P5E_CPU1_P2_RX_DN<15>")
	)
	(segment
		(start 168.175432 -382.24714)
		(end 168.246552 -381.826516)
		(width 0.14224)
		(layer "In6.Cu")
		(net "P5E_CPU1_P2_RX_DN<15>")
	)
	(segment
		(start 165.419024 -385.31038)
		(end 165.772338 -385.405376)
		(width 0.14224)
		(layer "In6.Cu")
		(net "P5E_CPU1_P2_RX_DN<15>")
	)
	(segment
		(start 145.118836 -325.148194)
		(end 144.219676 -321.732656)
		(width 0.14224)
		(layer "In6.Cu")
		(net "P5E_CPU1_P2_RX_DN<15>")
	)
	(segment
		(start 168.363646 -381.135128)
		(end 168.434766 -380.714504)
		(width 0.14224)
		(layer "In6.Cu")
		(net "P5E_CPU1_P2_RX_DN<15>")
	)
	(arc
		(start 127.333756 -286.540448)
		(mid 127.448432 -286.407257)
		(end 127.489712 -286.23641)
		(width 0.1143)
		(layer "In6.Cu")
		(net "P5E_CPU1_P2_RX_DN<15>")
	)
	(arc
		(start 126.077218 -283.79674)
		(mid 126.022385 -283.632028)
		(end 125.913896 -283.496512)
		(width 0.1143)
		(layer "In6.Cu")
		(net "P5E_CPU1_P2_RX_DN<15>")
	)
	(arc
		(start 126.549658 -287.856422)
		(mid 126.614476 -287.593433)
		(end 126.79426 -287.39084)
		(width 0.1143)
		(layer "In6.Cu")
		(net "P5E_CPU1_P2_RX_DN<15>")
	)
	(arc
		(start 155.902152 -353.805236)
		(mid 150.083952 -344.687396)
		(end 146.794728 -334.383634)
		(width 0.14224)
		(layer "In6.Cu")
		(net "P5E_CPU1_P2_RX_DN<15>")
	)
	(arc
		(start 126.863602 -288.970212)
		(mid 126.978278 -288.837021)
		(end 127.019558 -288.666174)
		(width 0.1143)
		(layer "In6.Cu")
		(net "P5E_CPU1_P2_RX_DN<15>")
	)
	(arc
		(start 125.85319 -283.46146)
		(mid 125.694776 -283.294972)
		(end 125.6157 -283.07919)
		(width 0.1143)
		(layer "In6.Cu")
		(net "P5E_CPU1_P2_RX_DN<15>")
	)
	(arc
		(start 127.019558 -295.146222)
		(mid 126.978299 -294.975365)
		(end 126.863602 -294.842184)
		(width 0.1143)
		(layer "In6.Cu")
		(net "P5E_CPU1_P2_RX_DN<15>")
	)
	(arc
		(start 126.79426 -289.941762)
		(mid 126.549329 -289.476285)
		(end 126.794006 -289.010598)
		(width 0.1143)
		(layer "In6.Cu")
		(net "P5E_CPU1_P2_RX_DN<15>")
	)
	(arc
		(start 127.26289 -295.611296)
		(mid 127.083944 -295.408715)
		(end 127.019558 -295.146222)
		(width 0.1143)
		(layer "In6.Cu")
		(net "P5E_CPU1_P2_RX_DN<15>")
	)
	(arc
		(start 167.37965 -383.413762)
		(mid 167.388768 -383.404674)
		(end 167.396922 -383.394712)
		(width 0.14224)
		(layer "In6.Cu")
		(net "P5E_CPU1_P2_RX_DN<15>")
	)
	(arc
		(start 156.004768 -353.91725)
		(mid 155.978175 -353.890109)
		(end 155.95219 -353.862386)
		(width 0.14224)
		(layer "In6.Cu")
		(net "P5E_CPU1_P2_RX_DN<15>")
	)
	(arc
		(start 127.019558 -287.046162)
		(mid 127.083364 -286.785109)
		(end 127.260604 -286.58312)
		(width 0.1143)
		(layer "In6.Cu")
		(net "P5E_CPU1_P2_RX_DN<15>")
	)
	(arc
		(start 172.404786 -370.316252)
		(mid 172.416057 -370.254021)
		(end 172.415454 -370.190776)
		(width 0.14224)
		(layer "In6.Cu")
		(net "P5E_CPU1_P2_RX_DN<15>")
	)
	(arc
		(start 168.094152 -382.439926)
		(mid 168.145985 -382.348254)
		(end 168.175432 -382.24714)
		(width 0.14224)
		(layer "In6.Cu")
		(net "P5E_CPU1_P2_RX_DN<15>")
	)
	(arc
		(start 126.79426 -291.561774)
		(mid 126.549329 -291.096297)
		(end 126.794006 -290.63061)
		(width 0.1143)
		(layer "In6.Cu")
		(net "P5E_CPU1_P2_RX_DN<15>")
	)
	(arc
		(start 169.263314 -375.818908)
		(mid 169.332941 -375.580536)
		(end 169.455846 -375.364756)
		(width 0.14224)
		(layer "In6.Cu")
		(net "P5E_CPU1_P2_RX_DN<15>")
	)
	(arc
		(start 127.019558 -285.426404)
		(mid 126.978299 -285.255547)
		(end 126.863602 -285.122366)
		(width 0.1143)
		(layer "In6.Cu")
		(net "P5E_CPU1_P2_RX_DN<15>")
	)
	(arc
		(start 126.79172 -288.32048)
		(mid 126.613766 -288.118145)
		(end 126.549658 -287.856422)
		(width 0.1143)
		(layer "In6.Cu")
		(net "P5E_CPU1_P2_RX_DN<15>")
	)
	(arc
		(start 126.86157 -287.351724)
		(mid 126.977751 -287.218165)
		(end 127.019558 -287.046162)
		(width 0.1143)
		(layer "In6.Cu")
		(net "P5E_CPU1_P2_RX_DN<15>")
	)
	(arc
		(start 165.725856 -363.539024)
		(mid 165.522627 -363.410264)
		(end 165.340538 -363.25302)
		(width 0.14224)
		(layer "In6.Cu")
		(net "P5E_CPU1_P2_RX_DN<15>")
	)
	(arc
		(start 126.863602 -293.830248)
		(mid 127.019429 -293.52621)
		(end 126.863602 -293.222172)
		(width 0.1143)
		(layer "In6.Cu")
		(net "P5E_CPU1_P2_RX_DN<15>")
	)
	(arc
		(start 171.916598 -372.020846)
		(mid 171.928311 -372.001409)
		(end 171.93641 -371.980206)
		(width 0.14224)
		(layer "In6.Cu")
		(net "P5E_CPU1_P2_RX_DN<15>")
	)
	(arc
		(start 126.863602 -290.590224)
		(mid 127.019429 -290.286186)
		(end 126.863602 -289.982148)
		(width 0.1143)
		(layer "In6.Cu")
		(net "P5E_CPU1_P2_RX_DN<15>")
	)
	(arc
		(start 126.549658 -284.616398)
		(mid 126.508318 -284.445383)
		(end 126.393448 -284.312106)
		(width 0.1143)
		(layer "In6.Cu")
		(net "P5E_CPU1_P2_RX_DN<15>")
	)
	(arc
		(start 127.019558 -288.666174)
		(mid 126.978241 -288.495458)
		(end 126.863602 -288.36239)
		(width 0.1143)
		(layer "In6.Cu")
		(net "P5E_CPU1_P2_RX_DN<15>")
	)
	(arc
		(start 127.49276 -295.94048)
		(mid 127.45137 -295.777744)
		(end 127.337312 -295.654476)
		(width 0.1143)
		(layer "In6.Cu")
		(net "P5E_CPU1_P2_RX_DN<15>")
	)
	(arc
		(start 126.79426 -285.08198)
		(mid 126.614468 -284.879392)
		(end 126.549658 -284.616398)
		(width 0.1143)
		(layer "In6.Cu")
		(net "P5E_CPU1_P2_RX_DN<15>")
	)
	(arc
		(start 126.079504 -283.815536)
		(mid 126.078454 -283.806127)
		(end 126.077218 -283.79674)
		(width 0.1143)
		(layer "In6.Cu")
		(net "P5E_CPU1_P2_RX_DN<15>")
	)
	(arc
		(start 155.95219 -353.862386)
		(mid 155.926855 -353.834088)
		(end 155.902152 -353.805236)
		(width 0.14224)
		(layer "In6.Cu")
		(net "P5E_CPU1_P2_RX_DN<15>")
	)
	(arc
		(start 126.323344 -284.27172)
		(mid 126.14641 -284.073474)
		(end 126.079504 -283.816298)
		(width 0.1143)
		(layer "In6.Cu")
		(net "P5E_CPU1_P2_RX_DN<15>")
	)
	(arc
		(start 172.133006 -367.500408)
		(mid 172.125633 -367.474265)
		(end 172.109892 -367.452148)
		(width 0.14224)
		(layer "In6.Cu")
		(net "P5E_CPU1_P2_RX_DN<15>")
	)
	(arc
		(start 127.263398 -285.891478)
		(mid 127.084205 -285.688968)
		(end 127.019558 -285.426404)
		(width 0.1143)
		(layer "In6.Cu")
		(net "P5E_CPU1_P2_RX_DN<15>")
	)
	(arc
		(start 126.79426 -294.801798)
		(mid 126.549329 -294.336321)
		(end 126.794006 -293.870634)
		(width 0.1143)
		(layer "In6.Cu")
		(net "P5E_CPU1_P2_RX_DN<15>")
	)
	(arc
		(start 126.863602 -292.210236)
		(mid 127.019429 -291.906198)
		(end 126.863602 -291.60216)
		(width 0.1143)
		(layer "In6.Cu")
		(net "P5E_CPU1_P2_RX_DN<15>")
	)
	(arc
		(start 126.79426 -293.181786)
		(mid 126.549329 -292.716309)
		(end 126.794006 -292.250622)
		(width 0.1143)
		(layer "In6.Cu")
		(net "P5E_CPU1_P2_RX_DN<15>")
	)
	(arc
		(start 171.196508 -366.538764)
		(mid 171.025912 -366.391597)
		(end 170.835574 -366.271048)
		(width 0.14224)
		(layer "In6.Cu")
		(net "P5E_CPU1_P2_RX_DN<15>")
	)
	(arc
		(start 127.489712 -286.23641)
		(mid 127.448372 -286.065395)
		(end 127.333502 -285.932118)
		(width 0.1143)
		(layer "In6.Cu")
		(net "P5E_CPU1_P2_RX_DN<15>")
	)
	(segment
		(start 163.698428 -385.31038)
		(end 164.219128 -385.31038)
		(width 0.127)
		(layer "F.Cu")
		(net "P5E_CPU1_P2_RX_DN<14>")
	)
	(segment
		(start 124.767848 -284.35046)
		(end 125.2347 -284.616398)
		(width 0.12954)
		(layer "F.Cu")
		(net "P5E_CPU1_P2_RX_DN<14>")
	)
	(segment
		(start 171.180252 -367.890806)
		(end 171.180252 -367.890552)
		(width 0.14224)
		(layer "In6.Cu")
		(net "P5E_CPU1_P2_RX_DN<14>")
	)
	(segment
		(start 126.32817 -286.578294)
		(end 126.395226 -286.539178)
		(width 0.1143)
		(layer "In6.Cu")
		(net "P5E_CPU1_P2_RX_DN<14>")
	)
	(segment
		(start 125.891798 -292.228778)
		(end 125.923548 -292.21049)
		(width 0.1143)
		(layer "In6.Cu")
		(net "P5E_CPU1_P2_RX_DN<14>")
	)
	(segment
		(start 125.852682 -290.631626)
		(end 125.903228 -290.602162)
		(width 0.1143)
		(layer "In6.Cu")
		(net "P5E_CPU1_P2_RX_DN<14>")
	)
	(segment
		(start 126.594616 -296.784014)
		(end 126.594616 -296.556938)
		(width 0.14224)
		(layer "In6.Cu")
		(net "P5E_CPU1_P2_RX_DN<14>")
	)
	(segment
		(start 126.36373 -285.9151)
		(end 126.36246 -285.914338)
		(width 0.1143)
		(layer "In6.Cu")
		(net "P5E_CPU1_P2_RX_DN<14>")
	)
	(segment
		(start 167.617394 -365.691928)
		(end 167.442388 -365.740188)
		(width 0.14224)
		(layer "In6.Cu")
		(net "P5E_CPU1_P2_RX_DN<14>")
	)
	(segment
		(start 164.382196 -384.234944)
		(end 164.686234 -383.93116)
		(width 0.14224)
		(layer "In6.Cu")
		(net "P5E_CPU1_P2_RX_DN<14>")
	)
	(segment
		(start 125.903228 -293.210234)
		(end 125.890782 -293.203122)
		(width 0.1143)
		(layer "In6.Cu")
		(net "P5E_CPU1_P2_RX_DN<14>")
	)
	(segment
		(start 137.35304 -310.966358)
		(end 137.047478 -310.50865)
		(width 0.14224)
		(layer "In6.Cu")
		(net "P5E_CPU1_P2_RX_DN<14>")
	)
	(segment
		(start 126.594108 -296.55643)
		(end 126.594108 -296.52849)
		(width 0.1143)
		(layer "In6.Cu")
		(net "P5E_CPU1_P2_RX_DN<14>")
	)
	(segment
		(start 125.615446 -284.699202)
		(end 125.532642 -284.616398)
		(width 0.1143)
		(layer "In6.Cu")
		(net "P5E_CPU1_P2_RX_DN<14>")
	)
	(segment
		(start 125.852682 -293.87165)
		(end 125.903228 -293.842186)
		(width 0.1143)
		(layer "In6.Cu")
		(net "P5E_CPU1_P2_RX_DN<14>")
	)
	(segment
		(start 125.908308 -288.3535)
		(end 125.852682 -288.320988)
		(width 0.1143)
		(layer "In6.Cu")
		(net "P5E_CPU1_P2_RX_DN<14>")
	)
	(segment
		(start 171.180252 -367.890552)
		(end 170.791124 -367.501678)
		(width 0.14224)
		(layer "In6.Cu")
		(net "P5E_CPU1_P2_RX_DN<14>")
	)
	(segment
		(start 125.922278 -288.361374)
		(end 125.908308 -288.353246)
		(width 0.1143)
		(layer "In6.Cu")
		(net "P5E_CPU1_P2_RX_DN<14>")
	)
	(segment
		(start 125.890782 -293.203122)
		(end 125.888496 -293.201598)
		(width 0.1143)
		(layer "In6.Cu")
		(net "P5E_CPU1_P2_RX_DN<14>")
	)
	(segment
		(start 125.892052 -291.588952)
		(end 125.889766 -291.587682)
		(width 0.1143)
		(layer "In6.Cu")
		(net "P5E_CPU1_P2_RX_DN<14>")
	)
	(segment
		(start 167.007794 -365.345218)
		(end 166.636954 -365.134398)
		(width 0.14224)
		(layer "In6.Cu")
		(net "P5E_CPU1_P2_RX_DN<14>")
	)
	(segment
		(start 125.914404 -285.117032)
		(end 125.852682 -285.080964)
		(width 0.1143)
		(layer "In6.Cu")
		(net "P5E_CPU1_P2_RX_DN<14>")
	)
	(segment
		(start 126.594108 -296.52849)
		(end 126.639828 -296.48277)
		(width 0.1143)
		(layer "In6.Cu")
		(net "P5E_CPU1_P2_RX_DN<14>")
	)
	(segment
		(start 126.361698 -285.91383)
		(end 126.323598 -285.891732)
		(width 0.1143)
		(layer "In6.Cu")
		(net "P5E_CPU1_P2_RX_DN<14>")
	)
	(segment
		(start 164.572188 -385.405376)
		(end 164.572696 -385.404868)
		(width 0.14224)
		(layer "In6.Cu")
		(net "P5E_CPU1_P2_RX_DN<14>")
	)
	(segment
		(start 166.636954 -365.134398)
		(end 166.461948 -365.182658)
		(width 0.14224)
		(layer "In6.Cu")
		(net "P5E_CPU1_P2_RX_DN<14>")
	)
	(segment
		(start 125.896116 -294.825928)
		(end 125.853444 -294.80129)
		(width 0.1143)
		(layer "In6.Cu")
		(net "P5E_CPU1_P2_RX_DN<14>")
	)
	(segment
		(start 166.027354 -364.787688)
		(end 165.656514 -364.576868)
		(width 0.14224)
		(layer "In6.Cu")
		(net "P5E_CPU1_P2_RX_DN<14>")
	)
	(segment
		(start 145.368518 -332.20025)
		(end 143.392652 -322.266056)
		(width 0.14224)
		(layer "In6.Cu")
		(net "P5E_CPU1_P2_RX_DN<14>")
	)
	(segment
		(start 125.908308 -288.353246)
		(end 125.908308 -288.3535)
		(width 0.1143)
		(layer "In6.Cu")
		(net "P5E_CPU1_P2_RX_DN<14>")
	)
	(segment
		(start 164.694362 -385.334764)
		(end 164.694362 -385.163822)
		(width 0.14224)
		(layer "In6.Cu")
		(net "P5E_CPU1_P2_RX_DN<14>")
	)
	(segment
		(start 125.532642 -284.616398)
		(end 125.2347 -284.616398)
		(width 0.1143)
		(layer "In6.Cu")
		(net "P5E_CPU1_P2_RX_DN<14>")
	)
	(segment
		(start 164.794692 -381.856742)
		(end 168.585642 -374.904762)
		(width 0.14224)
		(layer "In6.Cu")
		(net "P5E_CPU1_P2_RX_DN<14>")
	)
	(segment
		(start 171.142914 -371.308884)
		(end 171.376594 -370.417852)
		(width 0.14224)
		(layer "In6.Cu")
		(net "P5E_CPU1_P2_RX_DN<14>")
	)
	(segment
		(start 126.393448 -285.932118)
		(end 126.36373 -285.9151)
		(width 0.1143)
		(layer "In6.Cu")
		(net "P5E_CPU1_P2_RX_DN<14>")
	)
	(segment
		(start 169.387774 -373.87784)
		(end 170.993054 -371.628416)
		(width 0.14224)
		(layer "In6.Cu")
		(net "P5E_CPU1_P2_RX_DN<14>")
	)
	(segment
		(start 125.903228 -289.97021)
		(end 125.853444 -289.941508)
		(width 0.1143)
		(layer "In6.Cu")
		(net "P5E_CPU1_P2_RX_DN<14>")
	)
	(segment
		(start 137.047478 -310.50865)
		(end 129.579878 -301.409354)
		(width 0.14224)
		(layer "In6.Cu")
		(net "P5E_CPU1_P2_RX_DN<14>")
	)
	(segment
		(start 126.639828 -296.462196)
		(end 126.549658 -296.244264)
		(width 0.1143)
		(layer "In6.Cu")
		(net "P5E_CPU1_P2_RX_DN<14>")
	)
	(segment
		(start 126.549658 -296.244264)
		(end 126.549658 -295.956482)
		(width 0.1143)
		(layer "In6.Cu")
		(net "P5E_CPU1_P2_RX_DN<14>")
	)
	(segment
		(start 126.594616 -296.556938)
		(end 126.594108 -296.55643)
		(width 0.1143)
		(layer "In6.Cu")
		(net "P5E_CPU1_P2_RX_DN<14>")
	)
	(segment
		(start 167.442388 -365.740188)
		(end 167.0558 -365.520478)
		(width 0.14224)
		(layer "In6.Cu")
		(net "P5E_CPU1_P2_RX_DN<14>")
	)
	(segment
		(start 125.852682 -292.251638)
		(end 125.891798 -292.228778)
		(width 0.1143)
		(layer "In6.Cu")
		(net "P5E_CPU1_P2_RX_DN<14>")
	)
	(segment
		(start 164.572696 -385.404868)
		(end 164.694362 -385.334764)
		(width 0.14224)
		(layer "In6.Cu")
		(net "P5E_CPU1_P2_RX_DN<14>")
	)
	(segment
		(start 168.585642 -374.904762)
		(end 169.387774 -373.87784)
		(width 0.14224)
		(layer "In6.Cu")
		(net "P5E_CPU1_P2_RX_DN<14>")
	)
	(segment
		(start 165.481508 -364.625128)
		(end 165.09492 -364.405418)
		(width 0.14224)
		(layer "In6.Cu")
		(net "P5E_CPU1_P2_RX_DN<14>")
	)
	(segment
		(start 164.219128 -385.31038)
		(end 164.572188 -385.405376)
		(width 0.14224)
		(layer "In6.Cu")
		(net "P5E_CPU1_P2_RX_DN<14>")
	)
	(segment
		(start 166.461948 -365.182658)
		(end 166.07536 -364.962948)
		(width 0.14224)
		(layer "In6.Cu")
		(net "P5E_CPU1_P2_RX_DN<14>")
	)
	(segment
		(start 126.393448 -295.65219)
		(end 126.365 -295.635426)
		(width 0.1143)
		(layer "In6.Cu")
		(net "P5E_CPU1_P2_RX_DN<14>")
	)
	(segment
		(start 125.889766 -291.587682)
		(end 125.889512 -291.587428)
		(width 0.1143)
		(layer "In6.Cu")
		(net "P5E_CPU1_P2_RX_DN<14>")
	)
	(segment
		(start 164.37737 -384.84683)
		(end 164.382196 -384.234944)
		(width 0.14224)
		(layer "In6.Cu")
		(net "P5E_CPU1_P2_RX_DN<14>")
	)
	(segment
		(start 164.686234 -383.93116)
		(end 164.686234 -382.2827)
		(width 0.14224)
		(layer "In6.Cu")
		(net "P5E_CPU1_P2_RX_DN<14>")
	)
	(segment
		(start 125.888496 -293.201598)
		(end 125.853444 -293.181278)
		(width 0.1143)
		(layer "In6.Cu")
		(net "P5E_CPU1_P2_RX_DN<14>")
	)
	(segment
		(start 170.763946 -367.48085)
		(end 167.617394 -365.691928)
		(width 0.14224)
		(layer "In6.Cu")
		(net "P5E_CPU1_P2_RX_DN<14>")
	)
	(segment
		(start 126.767082 -297.200066)
		(end 126.594616 -296.784014)
		(width 0.14224)
		(layer "In6.Cu")
		(net "P5E_CPU1_P2_RX_DN<14>")
	)
	(segment
		(start 126.36246 -285.914338)
		(end 126.361698 -285.91383)
		(width 0.1143)
		(layer "In6.Cu")
		(net "P5E_CPU1_P2_RX_DN<14>")
	)
	(segment
		(start 164.694362 -385.163822)
		(end 164.37737 -384.84683)
		(width 0.14224)
		(layer "In6.Cu")
		(net "P5E_CPU1_P2_RX_DN<14>")
	)
	(segment
		(start 143.392652 -322.266056)
		(end 137.35304 -310.966358)
		(width 0.14224)
		(layer "In6.Cu")
		(net "P5E_CPU1_P2_RX_DN<14>")
	)
	(segment
		(start 165.656514 -364.576868)
		(end 165.481508 -364.625128)
		(width 0.14224)
		(layer "In6.Cu")
		(net "P5E_CPU1_P2_RX_DN<14>")
	)
	(segment
		(start 146.027394 -335.511902)
		(end 145.368518 -332.20025)
		(width 0.14224)
		(layer "In6.Cu")
		(net "P5E_CPU1_P2_RX_DN<14>")
	)
	(segment
		(start 167.0558 -365.520478)
		(end 167.007794 -365.345218)
		(width 0.14224)
		(layer "In6.Cu")
		(net "P5E_CPU1_P2_RX_DN<14>")
	)
	(segment
		(start 125.852174 -287.391856)
		(end 125.91288 -287.35655)
		(width 0.1143)
		(layer "In6.Cu")
		(net "P5E_CPU1_P2_RX_DN<14>")
	)
	(segment
		(start 171.380404 -370.377212)
		(end 171.217336 -367.972086)
		(width 0.14224)
		(layer "In6.Cu")
		(net "P5E_CPU1_P2_RX_DN<14>")
	)
	(segment
		(start 170.993054 -371.628416)
		(end 171.142914 -371.308884)
		(width 0.14224)
		(layer "In6.Cu")
		(net "P5E_CPU1_P2_RX_DN<14>")
	)
	(segment
		(start 165.09492 -364.405418)
		(end 165.046914 -364.230158)
		(width 0.14224)
		(layer "In6.Cu")
		(net "P5E_CPU1_P2_RX_DN<14>")
	)
	(segment
		(start 129.579878 -301.409354)
		(end 126.767082 -297.200066)
		(width 0.14224)
		(layer "In6.Cu")
		(net "P5E_CPU1_P2_RX_DN<14>")
	)
	(segment
		(start 126.639828 -296.48277)
		(end 126.639828 -296.462196)
		(width 0.1143)
		(layer "In6.Cu")
		(net "P5E_CPU1_P2_RX_DN<14>")
	)
	(segment
		(start 166.07536 -364.962948)
		(end 166.027354 -364.787688)
		(width 0.14224)
		(layer "In6.Cu")
		(net "P5E_CPU1_P2_RX_DN<14>")
	)
	(segment
		(start 126.325376 -286.579818)
		(end 126.32817 -286.578294)
		(width 0.1143)
		(layer "In6.Cu")
		(net "P5E_CPU1_P2_RX_DN<14>")
	)
	(segment
		(start 165.046914 -364.230158)
		(end 164.676074 -364.019338)
		(width 0.14224)
		(layer "In6.Cu")
		(net "P5E_CPU1_P2_RX_DN<14>")
	)
	(segment
		(start 163.75126 -363.180376)
		(end 157.119066 -356.548182)
		(width 0.14224)
		(layer "In6.Cu")
		(net "P5E_CPU1_P2_RX_DN<14>")
	)
	(arc
		(start 126.079504 -287.031684)
		(mid 126.144211 -286.783302)
		(end 126.312168 -286.589216)
		(width 0.1143)
		(layer "In6.Cu")
		(net "P5E_CPU1_P2_RX_DN<14>")
	)
	(arc
		(start 125.923548 -292.21049)
		(mid 126.07728 -291.891077)
		(end 125.892052 -291.588952)
		(width 0.1143)
		(layer "In6.Cu")
		(net "P5E_CPU1_P2_RX_DN<14>")
	)
	(arc
		(start 126.312168 -286.589216)
		(mid 126.318738 -286.584469)
		(end 126.325376 -286.579818)
		(width 0.1143)
		(layer "In6.Cu")
		(net "P5E_CPU1_P2_RX_DN<14>")
	)
	(arc
		(start 126.365 -295.635426)
		(mid 126.157017 -295.429538)
		(end 126.080774 -295.146984)
		(width 0.1143)
		(layer "In6.Cu")
		(net "P5E_CPU1_P2_RX_DN<14>")
	)
	(arc
		(start 125.619256 -284.722062)
		(mid 125.617233 -284.710652)
		(end 125.615446 -284.699202)
		(width 0.1143)
		(layer "In6.Cu")
		(net "P5E_CPU1_P2_RX_DN<14>")
	)
	(arc
		(start 126.07925 -285.44647)
		(mid 126.078677 -285.431581)
		(end 126.077218 -285.416752)
		(width 0.1143)
		(layer "In6.Cu")
		(net "P5E_CPU1_P2_RX_DN<14>")
	)
	(arc
		(start 126.080774 -295.146984)
		(mid 126.03131 -294.961808)
		(end 125.896116 -294.825928)
		(width 0.1143)
		(layer "In6.Cu")
		(net "P5E_CPU1_P2_RX_DN<14>")
	)
	(arc
		(start 164.676074 -364.019338)
		(mid 164.643404 -363.998603)
		(end 164.612828 -363.974888)
		(width 0.14224)
		(layer "In6.Cu")
		(net "P5E_CPU1_P2_RX_DN<14>")
	)
	(arc
		(start 125.91288 -287.35655)
		(mid 126.022346 -287.22091)
		(end 126.077472 -287.05556)
		(width 0.1143)
		(layer "In6.Cu")
		(net "P5E_CPU1_P2_RX_DN<14>")
	)
	(arc
		(start 126.549404 -286.23641)
		(mid 126.508149 -286.065439)
		(end 126.393448 -285.932118)
		(width 0.1143)
		(layer "In6.Cu")
		(net "P5E_CPU1_P2_RX_DN<14>")
	)
	(arc
		(start 126.395226 -286.539178)
		(mid 126.508633 -286.406289)
		(end 126.549404 -286.23641)
		(width 0.1143)
		(layer "In6.Cu")
		(net "P5E_CPU1_P2_RX_DN<14>")
	)
	(arc
		(start 126.077218 -285.416752)
		(mid 126.022535 -285.252375)
		(end 125.914404 -285.117032)
		(width 0.1143)
		(layer "In6.Cu")
		(net "P5E_CPU1_P2_RX_DN<14>")
	)
	(arc
		(start 125.853444 -289.941508)
		(mid 125.611078 -289.452848)
		(end 125.896878 -288.988246)
		(width 0.1143)
		(layer "In6.Cu")
		(net "P5E_CPU1_P2_RX_DN<14>")
	)
	(arc
		(start 125.852682 -293.18077)
		(mid 125.609355 -292.716204)
		(end 125.852682 -292.251638)
		(width 0.1143)
		(layer "In6.Cu")
		(net "P5E_CPU1_P2_RX_DN<14>")
	)
	(arc
		(start 125.852682 -288.320988)
		(mid 125.673869 -288.118638)
		(end 125.60935 -287.856422)
		(width 0.1143)
		(layer "In6.Cu")
		(net "P5E_CPU1_P2_RX_DN<14>")
	)
	(arc
		(start 126.323598 -285.891732)
		(mid 126.148662 -285.698058)
		(end 126.07925 -285.44647)
		(width 0.1143)
		(layer "In6.Cu")
		(net "P5E_CPU1_P2_RX_DN<14>")
	)
	(arc
		(start 125.60935 -287.856422)
		(mid 125.673729 -287.594338)
		(end 125.852174 -287.391856)
		(width 0.1143)
		(layer "In6.Cu")
		(net "P5E_CPU1_P2_RX_DN<14>")
	)
	(arc
		(start 171.376594 -370.417852)
		(mid 171.380153 -370.397687)
		(end 171.380404 -370.377212)
		(width 0.14224)
		(layer "In6.Cu")
		(net "P5E_CPU1_P2_RX_DN<14>")
	)
	(arc
		(start 171.217336 -367.972086)
		(mid 171.206145 -367.928095)
		(end 171.180252 -367.890806)
		(width 0.14224)
		(layer "In6.Cu")
		(net "P5E_CPU1_P2_RX_DN<14>")
	)
	(arc
		(start 125.853444 -294.80129)
		(mid 125.853063 -294.801036)
		(end 125.852682 -294.800782)
		(width 0.1143)
		(layer "In6.Cu")
		(net "P5E_CPU1_P2_RX_DN<14>")
	)
	(arc
		(start 164.612828 -363.974888)
		(mid 164.174002 -363.586353)
		(end 163.75126 -363.180376)
		(width 0.14224)
		(layer "In6.Cu")
		(net "P5E_CPU1_P2_RX_DN<14>")
	)
	(arc
		(start 164.686234 -382.2827)
		(mid 164.713756 -382.062924)
		(end 164.794692 -381.856742)
		(width 0.14224)
		(layer "In6.Cu")
		(net "P5E_CPU1_P2_RX_DN<14>")
	)
	(arc
		(start 157.119066 -356.548182)
		(mid 156.003185 -355.380679)
		(end 154.94127 -354.163884)
		(width 0.14224)
		(layer "In6.Cu")
		(net "P5E_CPU1_P2_RX_DN<14>")
	)
	(arc
		(start 125.852682 -294.800782)
		(mid 125.609355 -294.336216)
		(end 125.852682 -293.87165)
		(width 0.1143)
		(layer "In6.Cu")
		(net "P5E_CPU1_P2_RX_DN<14>")
	)
	(arc
		(start 125.903228 -293.842186)
		(mid 126.078178 -293.52621)
		(end 125.903228 -293.210234)
		(width 0.1143)
		(layer "In6.Cu")
		(net "P5E_CPU1_P2_RX_DN<14>")
	)
	(arc
		(start 170.791124 -367.501678)
		(mid 170.778236 -367.49035)
		(end 170.763946 -367.48085)
		(width 0.14224)
		(layer "In6.Cu")
		(net "P5E_CPU1_P2_RX_DN<14>")
	)
	(arc
		(start 126.549658 -295.956482)
		(mid 126.508337 -295.785443)
		(end 126.393448 -295.65219)
		(width 0.1143)
		(layer "In6.Cu")
		(net "P5E_CPU1_P2_RX_DN<14>")
	)
	(arc
		(start 125.853444 -293.181278)
		(mid 125.853063 -293.181024)
		(end 125.852682 -293.18077)
		(width 0.1143)
		(layer "In6.Cu")
		(net "P5E_CPU1_P2_RX_DN<14>")
	)
	(arc
		(start 125.896878 -288.988246)
		(mid 126.079174 -288.681647)
		(end 125.922278 -288.361374)
		(width 0.1143)
		(layer "In6.Cu")
		(net "P5E_CPU1_P2_RX_DN<14>")
	)
	(arc
		(start 154.94127 -354.163884)
		(mid 149.315055 -345.396698)
		(end 146.027394 -335.511902)
		(width 0.14224)
		(layer "In6.Cu")
		(net "P5E_CPU1_P2_RX_DN<14>")
	)
	(arc
		(start 125.903228 -290.602162)
		(mid 126.078178 -290.286186)
		(end 125.903228 -289.97021)
		(width 0.1143)
		(layer "In6.Cu")
		(net "P5E_CPU1_P2_RX_DN<14>")
	)
	(arc
		(start 125.889512 -291.587428)
		(mid 125.608952 -291.119595)
		(end 125.852682 -290.631626)
		(width 0.1143)
		(layer "In6.Cu")
		(net "P5E_CPU1_P2_RX_DN<14>")
	)
	(arc
		(start 125.852682 -285.080964)
		(mid 125.700695 -284.924456)
		(end 125.619256 -284.722062)
		(width 0.1143)
		(layer "In6.Cu")
		(net "P5E_CPU1_P2_RX_DN<14>")
	)
	(arc
		(start 126.077472 -287.05556)
		(mid 126.078784 -287.043647)
		(end 126.079504 -287.031684)
		(width 0.1143)
		(layer "In6.Cu")
		(net "P5E_CPU1_P2_RX_DN<14>")
	)
	(segment
		(start 162.498278 -385.31038)
		(end 163.018978 -385.31038)
		(width 0.127)
		(layer "F.Cu")
		(net "P5E_CPU1_P2_RX_DN<13>")
	)
	(segment
		(start 124.767848 -281.110436)
		(end 125.2347 -281.376374)
		(width 0.12954)
		(layer "F.Cu")
		(net "P5E_CPU1_P2_RX_DN<13>")
	)
	(segment
		(start 124.952506 -294.82415)
		(end 124.951744 -294.823642)
		(width 0.1143)
		(layer "In6.Cu")
		(net "P5E_CPU1_P2_RX_DN<13>")
	)
	(segment
		(start 124.953776 -293.2049)
		(end 124.952506 -293.204138)
		(width 0.1143)
		(layer "In6.Cu")
		(net "P5E_CPU1_P2_RX_DN<13>")
	)
	(segment
		(start 124.952506 -282.508452)
		(end 124.953776 -282.50769)
		(width 0.1143)
		(layer "In6.Cu")
		(net "P5E_CPU1_P2_RX_DN<13>")
	)
	(segment
		(start 124.950728 -288.989262)
		(end 124.951744 -288.988754)
		(width 0.1143)
		(layer "In6.Cu")
		(net "P5E_CPU1_P2_RX_DN<13>")
	)
	(segment
		(start 170.369738 -369.555522)
		(end 170.281854 -368.495834)
		(width 0.14224)
		(layer "In6.Cu")
		(net "P5E_CPU1_P2_RX_DN<13>")
	)
	(segment
		(start 124.950728 -284.12948)
		(end 124.951744 -284.128972)
		(width 0.1143)
		(layer "In6.Cu")
		(net "P5E_CPU1_P2_RX_DN<13>")
	)
	(segment
		(start 124.941838 -285.097982)
		(end 124.940822 -285.097474)
		(width 0.1143)
		(layer "In6.Cu")
		(net "P5E_CPU1_P2_RX_DN<13>")
	)
	(segment
		(start 124.949204 -283.482288)
		(end 124.948188 -283.48178)
		(width 0.1143)
		(layer "In6.Cu")
		(net "P5E_CPU1_P2_RX_DN<13>")
	)
	(segment
		(start 163.1823 -384.234944)
		(end 163.486338 -383.93116)
		(width 0.14224)
		(layer "In6.Cu")
		(net "P5E_CPU1_P2_RX_DN<13>")
	)
	(segment
		(start 124.912628 -284.151832)
		(end 124.949204 -284.130496)
		(width 0.1143)
		(layer "In6.Cu")
		(net "P5E_CPU1_P2_RX_DN<13>")
	)
	(segment
		(start 124.949204 -284.130496)
		(end 124.950728 -284.12948)
		(width 0.1143)
		(layer "In6.Cu")
		(net "P5E_CPU1_P2_RX_DN<13>")
	)
	(segment
		(start 125.421898 -286.558736)
		(end 125.45441 -286.53994)
		(width 0.1143)
		(layer "In6.Cu")
		(net "P5E_CPU1_P2_RX_DN<13>")
	)
	(segment
		(start 124.951744 -288.343848)
		(end 124.912628 -288.320988)
		(width 0.1143)
		(layer "In6.Cu")
		(net "P5E_CPU1_P2_RX_DN<13>")
	)
	(segment
		(start 124.950728 -282.509468)
		(end 124.951744 -282.50896)
		(width 0.1143)
		(layer "In6.Cu")
		(net "P5E_CPU1_P2_RX_DN<13>")
	)
	(segment
		(start 124.951744 -287.368742)
		(end 124.983494 -287.350454)
		(width 0.1143)
		(layer "In6.Cu")
		(net "P5E_CPU1_P2_RX_DN<13>")
	)
	(segment
		(start 124.952506 -285.104332)
		(end 124.951744 -285.103824)
		(width 0.1143)
		(layer "In6.Cu")
		(net "P5E_CPU1_P2_RX_DN<13>")
	)
	(segment
		(start 170.240198 -368.412014)
		(end 170.059096 -368.248946)
		(width 0.14224)
		(layer "In6.Cu")
		(net "P5E_CPU1_P2_RX_DN<13>")
	)
	(segment
		(start 125.602492 -281.446224)
		(end 125.532642 -281.376374)
		(width 0.1143)
		(layer "In6.Cu")
		(net "P5E_CPU1_P2_RX_DN<13>")
	)
	(segment
		(start 124.983494 -291.601906)
		(end 124.953776 -291.584888)
		(width 0.1143)
		(layer "In6.Cu")
		(net "P5E_CPU1_P2_RX_DN<13>")
	)
	(segment
		(start 124.953776 -293.84752)
		(end 124.983494 -293.830502)
		(width 0.1143)
		(layer "In6.Cu")
		(net "P5E_CPU1_P2_RX_DN<13>")
	)
	(segment
		(start 125.564392 -296.486326)
		(end 125.563884 -296.486326)
		(width 0.14224)
		(layer "In6.Cu")
		(net "P5E_CPU1_P2_RX_DN<13>")
	)
	(segment
		(start 164.724588 -379.822456)
		(end 164.932106 -379.449838)
		(width 0.14224)
		(layer "In6.Cu")
		(net "P5E_CPU1_P2_RX_DN<13>")
	)
	(segment
		(start 124.953776 -294.824912)
		(end 124.952506 -294.82415)
		(width 0.1143)
		(layer "In6.Cu")
		(net "P5E_CPU1_P2_RX_DN<13>")
	)
	(segment
		(start 124.949204 -292.230302)
		(end 124.950728 -292.229286)
		(width 0.1143)
		(layer "In6.Cu")
		(net "P5E_CPU1_P2_RX_DN<13>")
	)
	(segment
		(start 124.952506 -293.204138)
		(end 124.951744 -293.20363)
		(width 0.1143)
		(layer "In6.Cu")
		(net "P5E_CPU1_P2_RX_DN<13>")
	)
	(segment
		(start 124.953776 -285.105094)
		(end 124.952506 -285.104332)
		(width 0.1143)
		(layer "In6.Cu")
		(net "P5E_CPU1_P2_RX_DN<13>")
	)
	(segment
		(start 164.537644 -379.875542)
		(end 164.724588 -379.822456)
		(width 0.14224)
		(layer "In6.Cu")
		(net "P5E_CPU1_P2_RX_DN<13>")
	)
	(segment
		(start 124.952506 -283.48432)
		(end 124.951744 -283.483812)
		(width 0.1143)
		(layer "In6.Cu")
		(net "P5E_CPU1_P2_RX_DN<13>")
	)
	(segment
		(start 163.3728 -385.404868)
		(end 163.494466 -385.334764)
		(width 0.14224)
		(layer "In6.Cu")
		(net "P5E_CPU1_P2_RX_DN<13>")
	)
	(segment
		(start 124.943362 -285.098998)
		(end 124.941838 -285.097982)
		(width 0.1143)
		(layer "In6.Cu")
		(net "P5E_CPU1_P2_RX_DN<13>")
	)
	(segment
		(start 124.912628 -292.251638)
		(end 124.949204 -292.230302)
		(width 0.1143)
		(layer "In6.Cu")
		(net "P5E_CPU1_P2_RX_DN<13>")
	)
	(segment
		(start 164.932106 -379.449838)
		(end 164.87902 -379.263148)
		(width 0.14224)
		(layer "In6.Cu")
		(net "P5E_CPU1_P2_RX_DN<13>")
	)
	(segment
		(start 136.40181 -311.235852)
		(end 128.830832 -302.010318)
		(width 0.14224)
		(layer "In6.Cu")
		(net "P5E_CPU1_P2_RX_DN<13>")
	)
	(segment
		(start 124.951744 -282.50896)
		(end 124.952506 -282.508452)
		(width 0.1143)
		(layer "In6.Cu")
		(net "P5E_CPU1_P2_RX_DN<13>")
	)
	(segment
		(start 162.45078 -363.404658)
		(end 156.998416 -357.954834)
		(width 0.14224)
		(layer "In6.Cu")
		(net "P5E_CPU1_P2_RX_DN<13>")
	)
	(segment
		(start 124.948188 -283.48178)
		(end 124.943362 -283.478986)
		(width 0.1143)
		(layer "In6.Cu")
		(net "P5E_CPU1_P2_RX_DN<13>")
	)
	(segment
		(start 124.950728 -294.823134)
		(end 124.949204 -294.822118)
		(width 0.1143)
		(layer "In6.Cu")
		(net "P5E_CPU1_P2_RX_DN<13>")
	)
	(segment
		(start 124.953776 -284.127702)
		(end 124.983494 -284.110684)
		(width 0.1143)
		(layer "In6.Cu")
		(net "P5E_CPU1_P2_RX_DN<13>")
	)
	(segment
		(start 124.951744 -283.483812)
		(end 124.950728 -283.483304)
		(width 0.1143)
		(layer "In6.Cu")
		(net "P5E_CPU1_P2_RX_DN<13>")
	)
	(segment
		(start 124.951744 -288.988754)
		(end 124.952506 -288.988246)
		(width 0.1143)
		(layer "In6.Cu")
		(net "P5E_CPU1_P2_RX_DN<13>")
	)
	(segment
		(start 124.912628 -289.011614)
		(end 124.949204 -288.990278)
		(width 0.1143)
		(layer "In6.Cu")
		(net "P5E_CPU1_P2_RX_DN<13>")
	)
	(segment
		(start 124.912628 -282.53182)
		(end 124.949204 -282.510484)
		(width 0.1143)
		(layer "In6.Cu")
		(net "P5E_CPU1_P2_RX_DN<13>")
	)
	(segment
		(start 124.949204 -291.582094)
		(end 124.948188 -291.581586)
		(width 0.1143)
		(layer "In6.Cu")
		(net "P5E_CPU1_P2_RX_DN<13>")
	)
	(segment
		(start 124.953776 -283.485082)
		(end 124.952506 -283.48432)
		(width 0.1143)
		(layer "In6.Cu")
		(net "P5E_CPU1_P2_RX_DN<13>")
	)
	(segment
		(start 128.830832 -302.010318)
		(end 125.930152 -297.669458)
		(width 0.14224)
		(layer "In6.Cu")
		(net "P5E_CPU1_P2_RX_DN<13>")
	)
	(segment
		(start 124.949204 -288.990278)
		(end 124.950728 -288.989262)
		(width 0.1143)
		(layer "In6.Cu")
		(net "P5E_CPU1_P2_RX_DN<13>")
	)
	(segment
		(start 124.983494 -293.221918)
		(end 124.953776 -293.2049)
		(width 0.1143)
		(layer "In6.Cu")
		(net "P5E_CPU1_P2_RX_DN<13>")
	)
	(segment
		(start 163.177474 -384.84683)
		(end 163.1823 -384.234944)
		(width 0.14224)
		(layer "In6.Cu")
		(net "P5E_CPU1_P2_RX_DN<13>")
	)
	(segment
		(start 170.240198 -368.412268)
		(end 170.240198 -368.412014)
		(width 0.14224)
		(layer "In6.Cu")
		(net "P5E_CPU1_P2_RX_DN<13>")
	)
	(segment
		(start 124.950728 -290.609274)
		(end 124.951744 -290.608766)
		(width 0.1143)
		(layer "In6.Cu")
		(net "P5E_CPU1_P2_RX_DN<13>")
	)
	(segment
		(start 124.952506 -284.128464)
		(end 124.953776 -284.127702)
		(width 0.1143)
		(layer "In6.Cu")
		(net "P5E_CPU1_P2_RX_DN<13>")
	)
	(segment
		(start 124.950728 -291.58311)
		(end 124.949204 -291.582094)
		(width 0.1143)
		(layer "In6.Cu")
		(net "P5E_CPU1_P2_RX_DN<13>")
	)
	(segment
		(start 144.438116 -332.442312)
		(end 142.455646 -322.560442)
		(width 0.14224)
		(layer "In6.Cu")
		(net "P5E_CPU1_P2_RX_DN<13>")
	)
	(segment
		(start 124.941838 -294.8178)
		(end 124.940822 -294.817292)
		(width 0.1143)
		(layer "In6.Cu")
		(net "P5E_CPU1_P2_RX_DN<13>")
	)
	(segment
		(start 124.950728 -283.483304)
		(end 124.949204 -283.482288)
		(width 0.1143)
		(layer "In6.Cu")
		(net "P5E_CPU1_P2_RX_DN<13>")
	)
	(segment
		(start 124.985272 -288.363406)
		(end 124.951744 -288.343848)
		(width 0.1143)
		(layer "In6.Cu")
		(net "P5E_CPU1_P2_RX_DN<13>")
	)
	(segment
		(start 124.952506 -288.988246)
		(end 124.953776 -288.987484)
		(width 0.1143)
		(layer "In6.Cu")
		(net "P5E_CPU1_P2_RX_DN<13>")
	)
	(segment
		(start 167.744902 -374.400826)
		(end 169.560748 -371.82679)
		(width 0.14224)
		(layer "In6.Cu")
		(net "P5E_CPU1_P2_RX_DN<13>")
	)
	(segment
		(start 144.437862 -332.442312)
		(end 144.438116 -332.442312)
		(width 0.14224)
		(layer "In6.Cu")
		(net "P5E_CPU1_P2_RX_DN<13>")
	)
	(segment
		(start 170.059096 -368.248946)
		(end 168.162732 -367.373662)
		(width 0.14224)
		(layer "In6.Cu")
		(net "P5E_CPU1_P2_RX_DN<13>")
	)
	(segment
		(start 124.983494 -289.981894)
		(end 124.953776 -289.964876)
		(width 0.1143)
		(layer "In6.Cu")
		(net "P5E_CPU1_P2_RX_DN<13>")
	)
	(segment
		(start 124.940822 -294.817292)
		(end 124.912628 -294.800782)
		(width 0.1143)
		(layer "In6.Cu")
		(net "P5E_CPU1_P2_RX_DN<13>")
	)
	(segment
		(start 165.822122 -377.851924)
		(end 165.822376 -377.85167)
		(width 0.14224)
		(layer "In6.Cu")
		(net "P5E_CPU1_P2_RX_DN<13>")
	)
	(segment
		(start 125.421898 -295.633648)
		(end 125.421644 -295.633648)
		(width 0.1143)
		(layer "In6.Cu")
		(net "P5E_CPU1_P2_RX_DN<13>")
	)
	(segment
		(start 125.563884 -296.34434)
		(end 125.609604 -296.29862)
		(width 0.1143)
		(layer "In6.Cu")
		(net "P5E_CPU1_P2_RX_DN<13>")
	)
	(segment
		(start 170.369738 -369.555776)
		(end 170.369738 -369.555522)
		(width 0.14224)
		(layer "In6.Cu")
		(net "P5E_CPU1_P2_RX_DN<13>")
	)
	(segment
		(start 124.940822 -283.477462)
		(end 124.912628 -283.460952)
		(width 0.1143)
		(layer "In6.Cu")
		(net "P5E_CPU1_P2_RX_DN<13>")
	)
	(segment
		(start 125.564392 -296.786554)
		(end 125.564392 -296.486326)
		(width 0.14224)
		(layer "In6.Cu")
		(net "P5E_CPU1_P2_RX_DN<13>")
	)
	(segment
		(start 125.563884 -296.372788)
		(end 125.563884 -296.34434)
		(width 0.1143)
		(layer "In6.Cu")
		(net "P5E_CPU1_P2_RX_DN<13>")
	)
	(segment
		(start 125.421898 -285.91383)
		(end 125.382782 -285.89097)
		(width 0.1143)
		(layer "In6.Cu")
		(net "P5E_CPU1_P2_RX_DN<13>")
	)
	(segment
		(start 125.930152 -297.669458)
		(end 125.564392 -296.786554)
		(width 0.14224)
		(layer "In6.Cu")
		(net "P5E_CPU1_P2_RX_DN<13>")
	)
	(segment
		(start 124.951744 -294.823642)
		(end 124.950728 -294.823134)
		(width 0.1143)
		(layer "In6.Cu")
		(net "P5E_CPU1_P2_RX_DN<13>")
	)
	(segment
		(start 124.950728 -292.229286)
		(end 124.951744 -292.228778)
		(width 0.1143)
		(layer "In6.Cu")
		(net "P5E_CPU1_P2_RX_DN<13>")
	)
	(segment
		(start 124.949204 -290.61029)
		(end 124.950728 -290.609274)
		(width 0.1143)
		(layer "In6.Cu")
		(net "P5E_CPU1_P2_RX_DN<13>")
	)
	(segment
		(start 125.452378 -295.651428)
		(end 125.421898 -295.633648)
		(width 0.1143)
		(layer "In6.Cu")
		(net "P5E_CPU1_P2_RX_DN<13>")
	)
	(segment
		(start 124.948188 -291.581586)
		(end 124.943362 -291.578792)
		(width 0.1143)
		(layer "In6.Cu")
		(net "P5E_CPU1_P2_RX_DN<13>")
	)
	(segment
		(start 124.912628 -290.631626)
		(end 124.949204 -290.61029)
		(width 0.1143)
		(layer "In6.Cu")
		(net "P5E_CPU1_P2_RX_DN<13>")
	)
	(segment
		(start 165.086792 -378.890276)
		(end 165.273482 -378.83719)
		(width 0.14224)
		(layer "In6.Cu")
		(net "P5E_CPU1_P2_RX_DN<13>")
	)
	(segment
		(start 125.532642 -281.376374)
		(end 125.2347 -281.376374)
		(width 0.1143)
		(layer "In6.Cu")
		(net "P5E_CPU1_P2_RX_DN<13>")
	)
	(segment
		(start 124.952506 -291.584126)
		(end 124.951744 -291.583618)
		(width 0.1143)
		(layer "In6.Cu")
		(net "P5E_CPU1_P2_RX_DN<13>")
	)
	(segment
		(start 124.983494 -283.5021)
		(end 124.953776 -283.485082)
		(width 0.1143)
		(layer "In6.Cu")
		(net "P5E_CPU1_P2_RX_DN<13>")
	)
	(segment
		(start 125.563884 -296.486326)
		(end 125.563884 -296.372788)
		(width 0.14224)
		(layer "In6.Cu")
		(net "P5E_CPU1_P2_RX_DN<13>")
	)
	(segment
		(start 142.455646 -322.560442)
		(end 136.40181 -311.235852)
		(width 0.14224)
		(layer "In6.Cu")
		(net "P5E_CPU1_P2_RX_DN<13>")
	)
	(segment
		(start 124.943362 -294.818816)
		(end 124.941838 -294.8178)
		(width 0.1143)
		(layer "In6.Cu")
		(net "P5E_CPU1_P2_RX_DN<13>")
	)
	(segment
		(start 124.915168 -287.390078)
		(end 124.951744 -287.368742)
		(width 0.1143)
		(layer "In6.Cu")
		(net "P5E_CPU1_P2_RX_DN<13>")
	)
	(segment
		(start 124.953776 -282.50769)
		(end 124.983494 -282.490672)
		(width 0.1143)
		(layer "In6.Cu")
		(net "P5E_CPU1_P2_RX_DN<13>")
	)
	(segment
		(start 164.383212 -380.435104)
		(end 164.330126 -380.248668)
		(width 0.14224)
		(layer "In6.Cu")
		(net "P5E_CPU1_P2_RX_DN<13>")
	)
	(segment
		(start 125.382782 -281.721814)
		(end 125.421898 -281.698954)
		(width 0.1143)
		(layer "In6.Cu")
		(net "P5E_CPU1_P2_RX_DN<13>")
	)
	(segment
		(start 124.952506 -289.964114)
		(end 124.951744 -289.963606)
		(width 0.1143)
		(layer "In6.Cu")
		(net "P5E_CPU1_P2_RX_DN<13>")
	)
	(segment
		(start 165.822376 -377.85167)
		(end 167.744902 -374.400826)
		(width 0.14224)
		(layer "In6.Cu")
		(net "P5E_CPU1_P2_RX_DN<13>")
	)
	(segment
		(start 124.951744 -291.583618)
		(end 124.950728 -291.58311)
		(width 0.1143)
		(layer "In6.Cu")
		(net "P5E_CPU1_P2_RX_DN<13>")
	)
	(segment
		(start 163.768786 -381.537972)
		(end 164.383212 -380.435104)
		(width 0.14224)
		(layer "In6.Cu")
		(net "P5E_CPU1_P2_RX_DN<13>")
	)
	(segment
		(start 124.952506 -293.848282)
		(end 124.953776 -293.84752)
		(width 0.1143)
		(layer "In6.Cu")
		(net "P5E_CPU1_P2_RX_DN<13>")
	)
	(segment
		(start 124.943362 -291.578792)
		(end 124.941838 -291.577776)
		(width 0.1143)
		(layer "In6.Cu")
		(net "P5E_CPU1_P2_RX_DN<13>")
	)
	(segment
		(start 124.952506 -290.608258)
		(end 124.953776 -290.607496)
		(width 0.1143)
		(layer "In6.Cu")
		(net "P5E_CPU1_P2_RX_DN<13>")
	)
	(segment
		(start 165.822376 -377.851924)
		(end 165.822122 -377.851924)
		(width 0.14224)
		(layer "In6.Cu")
		(net "P5E_CPU1_P2_RX_DN<13>")
	)
	(segment
		(start 124.951744 -284.128972)
		(end 124.952506 -284.128464)
		(width 0.1143)
		(layer "In6.Cu")
		(net "P5E_CPU1_P2_RX_DN<13>")
	)
	(segment
		(start 165.635686 -377.90501)
		(end 165.822376 -377.851924)
		(width 0.14224)
		(layer "In6.Cu")
		(net "P5E_CPU1_P2_RX_DN<13>")
	)
	(segment
		(start 124.940822 -291.577268)
		(end 124.912628 -291.560758)
		(width 0.1143)
		(layer "In6.Cu")
		(net "P5E_CPU1_P2_RX_DN<13>")
	)
	(segment
		(start 125.421898 -281.698954)
		(end 125.452378 -281.681174)
		(width 0.1143)
		(layer "In6.Cu")
		(net "P5E_CPU1_P2_RX_DN<13>")
	)
	(segment
		(start 124.953776 -290.607496)
		(end 124.983494 -290.590478)
		(width 0.1143)
		(layer "In6.Cu")
		(net "P5E_CPU1_P2_RX_DN<13>")
	)
	(segment
		(start 124.941838 -291.577776)
		(end 124.940822 -291.577268)
		(width 0.1143)
		(layer "In6.Cu")
		(net "P5E_CPU1_P2_RX_DN<13>")
	)
	(segment
		(start 124.983494 -285.122112)
		(end 124.953776 -285.105094)
		(width 0.1143)
		(layer "In6.Cu")
		(net "P5E_CPU1_P2_RX_DN<13>")
	)
	(segment
		(start 124.952506 -292.22827)
		(end 124.953776 -292.227508)
		(width 0.1143)
		(layer "In6.Cu")
		(net "P5E_CPU1_P2_RX_DN<13>")
	)
	(segment
		(start 165.427914 -378.277882)
		(end 165.635686 -377.90501)
		(width 0.14224)
		(layer "In6.Cu")
		(net "P5E_CPU1_P2_RX_DN<13>")
	)
	(segment
		(start 163.372292 -385.405376)
		(end 163.3728 -385.404868)
		(width 0.14224)
		(layer "In6.Cu")
		(net "P5E_CPU1_P2_RX_DN<13>")
	)
	(segment
		(start 125.421644 -295.633648)
		(end 125.384052 -295.611804)
		(width 0.1143)
		(layer "In6.Cu")
		(net "P5E_CPU1_P2_RX_DN<13>")
	)
	(segment
		(start 124.948188 -285.101792)
		(end 124.943362 -285.098998)
		(width 0.1143)
		(layer "In6.Cu")
		(net "P5E_CPU1_P2_RX_DN<13>")
	)
	(segment
		(start 124.949204 -293.850314)
		(end 124.950728 -293.849298)
		(width 0.1143)
		(layer "In6.Cu")
		(net "P5E_CPU1_P2_RX_DN<13>")
	)
	(segment
		(start 124.953776 -291.584888)
		(end 124.952506 -291.584126)
		(width 0.1143)
		(layer "In6.Cu")
		(net "P5E_CPU1_P2_RX_DN<13>")
	)
	(segment
		(start 124.949204 -294.822118)
		(end 124.948188 -294.82161)
		(width 0.1143)
		(layer "In6.Cu")
		(net "P5E_CPU1_P2_RX_DN<13>")
	)
	(segment
		(start 124.950728 -293.203122)
		(end 124.912628 -293.18077)
		(width 0.1143)
		(layer "In6.Cu")
		(net "P5E_CPU1_P2_RX_DN<13>")
	)
	(segment
		(start 124.941838 -283.47797)
		(end 124.940822 -283.477462)
		(width 0.1143)
		(layer "In6.Cu")
		(net "P5E_CPU1_P2_RX_DN<13>")
	)
	(segment
		(start 124.950728 -289.963098)
		(end 124.912628 -289.940746)
		(width 0.1143)
		(layer "In6.Cu")
		(net "P5E_CPU1_P2_RX_DN<13>")
	)
	(segment
		(start 124.950728 -285.103316)
		(end 124.949204 -285.1023)
		(width 0.1143)
		(layer "In6.Cu")
		(net "P5E_CPU1_P2_RX_DN<13>")
	)
	(segment
		(start 124.953776 -292.227508)
		(end 124.983494 -292.21049)
		(width 0.1143)
		(layer "In6.Cu")
		(net "P5E_CPU1_P2_RX_DN<13>")
	)
	(segment
		(start 124.951744 -293.84879)
		(end 124.952506 -293.848282)
		(width 0.1143)
		(layer "In6.Cu")
		(net "P5E_CPU1_P2_RX_DN<13>")
	)
	(segment
		(start 124.951744 -289.963606)
		(end 124.950728 -289.963098)
		(width 0.1143)
		(layer "In6.Cu")
		(net "P5E_CPU1_P2_RX_DN<13>")
	)
	(segment
		(start 165.273482 -378.83719)
		(end 165.481 -378.464572)
		(width 0.14224)
		(layer "In6.Cu")
		(net "P5E_CPU1_P2_RX_DN<13>")
	)
	(segment
		(start 125.452378 -285.93161)
		(end 125.421898 -285.91383)
		(width 0.1143)
		(layer "In6.Cu")
		(net "P5E_CPU1_P2_RX_DN<13>")
	)
	(segment
		(start 164.87902 -379.263148)
		(end 165.086792 -378.890276)
		(width 0.14224)
		(layer "In6.Cu")
		(net "P5E_CPU1_P2_RX_DN<13>")
	)
	(segment
		(start 125.609604 -296.29862)
		(end 125.609604 -295.956228)
		(width 0.1143)
		(layer "In6.Cu")
		(net "P5E_CPU1_P2_RX_DN<13>")
	)
	(segment
		(start 163.494466 -385.163822)
		(end 163.177474 -384.84683)
		(width 0.14224)
		(layer "In6.Cu")
		(net "P5E_CPU1_P2_RX_DN<13>")
	)
	(segment
		(start 124.949204 -282.510484)
		(end 124.950728 -282.509468)
		(width 0.1143)
		(layer "In6.Cu")
		(net "P5E_CPU1_P2_RX_DN<13>")
	)
	(segment
		(start 124.950728 -293.849298)
		(end 124.951744 -293.84879)
		(width 0.1143)
		(layer "In6.Cu")
		(net "P5E_CPU1_P2_RX_DN<13>")
	)
	(segment
		(start 163.494466 -385.334764)
		(end 163.494466 -385.163822)
		(width 0.14224)
		(layer "In6.Cu")
		(net "P5E_CPU1_P2_RX_DN<13>")
	)
	(segment
		(start 145.099024 -335.736692)
		(end 144.437862 -332.442312)
		(width 0.14224)
		(layer "In6.Cu")
		(net "P5E_CPU1_P2_RX_DN<13>")
	)
	(segment
		(start 124.951744 -285.103824)
		(end 124.950728 -285.103316)
		(width 0.1143)
		(layer "In6.Cu")
		(net "P5E_CPU1_P2_RX_DN<13>")
	)
	(segment
		(start 164.330126 -380.248668)
		(end 164.537644 -379.875542)
		(width 0.14224)
		(layer "In6.Cu")
		(net "P5E_CPU1_P2_RX_DN<13>")
	)
	(segment
		(start 124.951744 -290.608766)
		(end 124.952506 -290.608258)
		(width 0.1143)
		(layer "In6.Cu")
		(net "P5E_CPU1_P2_RX_DN<13>")
	)
	(segment
		(start 124.953776 -289.964876)
		(end 124.952506 -289.964114)
		(width 0.1143)
		(layer "In6.Cu")
		(net "P5E_CPU1_P2_RX_DN<13>")
	)
	(segment
		(start 124.951744 -293.20363)
		(end 124.950728 -293.203122)
		(width 0.1143)
		(layer "In6.Cu")
		(net "P5E_CPU1_P2_RX_DN<13>")
	)
	(segment
		(start 125.382782 -286.581596)
		(end 125.421898 -286.558736)
		(width 0.1143)
		(layer "In6.Cu")
		(net "P5E_CPU1_P2_RX_DN<13>")
	)
	(segment
		(start 124.948188 -294.82161)
		(end 124.943362 -294.818816)
		(width 0.1143)
		(layer "In6.Cu")
		(net "P5E_CPU1_P2_RX_DN<13>")
	)
	(segment
		(start 124.951744 -292.228778)
		(end 124.952506 -292.22827)
		(width 0.1143)
		(layer "In6.Cu")
		(net "P5E_CPU1_P2_RX_DN<13>")
	)
	(segment
		(start 124.949204 -285.1023)
		(end 124.948188 -285.101792)
		(width 0.1143)
		(layer "In6.Cu")
		(net "P5E_CPU1_P2_RX_DN<13>")
	)
	(segment
		(start 163.486338 -383.93116)
		(end 163.486338 -382.6256)
		(width 0.14224)
		(layer "In6.Cu")
		(net "P5E_CPU1_P2_RX_DN<13>")
	)
	(segment
		(start 165.481 -378.464572)
		(end 165.427914 -378.277882)
		(width 0.14224)
		(layer "In6.Cu")
		(net "P5E_CPU1_P2_RX_DN<13>")
	)
	(segment
		(start 170.082718 -370.698268)
		(end 170.366182 -369.597686)
		(width 0.14224)
		(layer "In6.Cu")
		(net "P5E_CPU1_P2_RX_DN<13>")
	)
	(segment
		(start 124.983494 -294.84193)
		(end 124.953776 -294.824912)
		(width 0.1143)
		(layer "In6.Cu")
		(net "P5E_CPU1_P2_RX_DN<13>")
	)
	(segment
		(start 124.943362 -283.478986)
		(end 124.941838 -283.47797)
		(width 0.1143)
		(layer "In6.Cu")
		(net "P5E_CPU1_P2_RX_DN<13>")
	)
	(segment
		(start 124.940822 -285.097474)
		(end 124.912628 -285.080964)
		(width 0.1143)
		(layer "In6.Cu")
		(net "P5E_CPU1_P2_RX_DN<13>")
	)
	(segment
		(start 124.953776 -288.987484)
		(end 124.983494 -288.970466)
		(width 0.1143)
		(layer "In6.Cu")
		(net "P5E_CPU1_P2_RX_DN<13>")
	)
	(segment
		(start 124.912628 -293.87165)
		(end 124.949204 -293.850314)
		(width 0.1143)
		(layer "In6.Cu")
		(net "P5E_CPU1_P2_RX_DN<13>")
	)
	(segment
		(start 163.018978 -385.31038)
		(end 163.372292 -385.405376)
		(width 0.14224)
		(layer "In6.Cu")
		(net "P5E_CPU1_P2_RX_DN<13>")
	)
	(arc
		(start 124.912628 -283.460952)
		(mid 124.669301 -282.996386)
		(end 124.912628 -282.53182)
		(width 0.1143)
		(layer "In6.Cu")
		(net "P5E_CPU1_P2_RX_DN<13>")
	)
	(arc
		(start 125.13945 -287.046162)
		(mid 125.203965 -286.783943)
		(end 125.382782 -286.581596)
		(width 0.1143)
		(layer "In6.Cu")
		(net "P5E_CPU1_P2_RX_DN<13>")
	)
	(arc
		(start 125.609604 -295.956228)
		(mid 125.572474 -295.79418)
		(end 125.468888 -295.664128)
		(width 0.1143)
		(layer "In6.Cu")
		(net "P5E_CPU1_P2_RX_DN<13>")
	)
	(arc
		(start 124.912628 -288.320988)
		(mid 124.733815 -288.118638)
		(end 124.669296 -287.856422)
		(width 0.1143)
		(layer "In6.Cu")
		(net "P5E_CPU1_P2_RX_DN<13>")
	)
	(arc
		(start 124.912628 -291.560758)
		(mid 124.669301 -291.096192)
		(end 124.912628 -290.631626)
		(width 0.1143)
		(layer "In6.Cu")
		(net "P5E_CPU1_P2_RX_DN<13>")
	)
	(arc
		(start 125.13945 -295.146222)
		(mid 125.098195 -294.975251)
		(end 124.983494 -294.84193)
		(width 0.1143)
		(layer "In6.Cu")
		(net "P5E_CPU1_P2_RX_DN<13>")
	)
	(arc
		(start 170.366182 -369.597686)
		(mid 170.369702 -369.576879)
		(end 170.369738 -369.555776)
		(width 0.14224)
		(layer "In6.Cu")
		(net "P5E_CPU1_P2_RX_DN<13>")
	)
	(arc
		(start 125.382782 -285.89097)
		(mid 125.203969 -285.68862)
		(end 125.13945 -285.426404)
		(width 0.1143)
		(layer "In6.Cu")
		(net "P5E_CPU1_P2_RX_DN<13>")
	)
	(arc
		(start 124.983494 -288.970466)
		(mid 125.09817 -288.837132)
		(end 125.13945 -288.666174)
		(width 0.1143)
		(layer "In6.Cu")
		(net "P5E_CPU1_P2_RX_DN<13>")
	)
	(arc
		(start 124.912628 -294.800782)
		(mid 124.669301 -294.336216)
		(end 124.912628 -293.87165)
		(width 0.1143)
		(layer "In6.Cu")
		(net "P5E_CPU1_P2_RX_DN<13>")
	)
	(arc
		(start 124.983494 -284.110684)
		(mid 125.139422 -283.806392)
		(end 124.983494 -283.5021)
		(width 0.1143)
		(layer "In6.Cu")
		(net "P5E_CPU1_P2_RX_DN<13>")
	)
	(arc
		(start 125.13945 -288.666174)
		(mid 125.098688 -288.49629)
		(end 124.985272 -288.363406)
		(width 0.1143)
		(layer "In6.Cu")
		(net "P5E_CPU1_P2_RX_DN<13>")
	)
	(arc
		(start 165.169342 -365.66475)
		(mid 163.788345 -364.618418)
		(end 162.503104 -363.456474)
		(width 0.14224)
		(layer "In6.Cu")
		(net "P5E_CPU1_P2_RX_DN<13>")
	)
	(arc
		(start 170.281854 -368.495834)
		(mid 170.268977 -368.45009)
		(end 170.240198 -368.412268)
		(width 0.14224)
		(layer "In6.Cu")
		(net "P5E_CPU1_P2_RX_DN<13>")
	)
	(arc
		(start 124.983494 -293.830502)
		(mid 125.139422 -293.52621)
		(end 124.983494 -293.221918)
		(width 0.1143)
		(layer "In6.Cu")
		(net "P5E_CPU1_P2_RX_DN<13>")
	)
	(arc
		(start 125.13945 -285.426404)
		(mid 125.098195 -285.255433)
		(end 124.983494 -285.122112)
		(width 0.1143)
		(layer "In6.Cu")
		(net "P5E_CPU1_P2_RX_DN<13>")
	)
	(arc
		(start 125.384052 -295.611804)
		(mid 125.204323 -295.409184)
		(end 125.13945 -295.146222)
		(width 0.1143)
		(layer "In6.Cu")
		(net "P5E_CPU1_P2_RX_DN<13>")
	)
	(arc
		(start 163.486338 -382.6256)
		(mid 163.558112 -382.063753)
		(end 163.768786 -381.537972)
		(width 0.14224)
		(layer "In6.Cu")
		(net "P5E_CPU1_P2_RX_DN<13>")
	)
	(arc
		(start 156.998416 -357.954834)
		(mid 149.405492 -347.725826)
		(end 145.099024 -335.736692)
		(width 0.14224)
		(layer "In6.Cu")
		(net "P5E_CPU1_P2_RX_DN<13>")
	)
	(arc
		(start 169.560748 -371.82679)
		(mid 169.872968 -371.286227)
		(end 170.082718 -370.698268)
		(width 0.14224)
		(layer "In6.Cu")
		(net "P5E_CPU1_P2_RX_DN<13>")
	)
	(arc
		(start 168.162732 -367.373662)
		(mid 166.629151 -366.583817)
		(end 165.169342 -365.66475)
		(width 0.14224)
		(layer "In6.Cu")
		(net "P5E_CPU1_P2_RX_DN<13>")
	)
	(arc
		(start 125.60935 -286.23641)
		(mid 125.567801 -286.064988)
		(end 125.452378 -285.93161)
		(width 0.1143)
		(layer "In6.Cu")
		(net "P5E_CPU1_P2_RX_DN<13>")
	)
	(arc
		(start 124.983494 -290.590478)
		(mid 125.139422 -290.286186)
		(end 124.983494 -289.981894)
		(width 0.1143)
		(layer "In6.Cu")
		(net "P5E_CPU1_P2_RX_DN<13>")
	)
	(arc
		(start 124.669296 -287.856422)
		(mid 124.734532 -287.592831)
		(end 124.915168 -287.390078)
		(width 0.1143)
		(layer "In6.Cu")
		(net "P5E_CPU1_P2_RX_DN<13>")
	)
	(arc
		(start 162.503104 -363.456474)
		(mid 162.476917 -363.430591)
		(end 162.45078 -363.404658)
		(width 0.14224)
		(layer "In6.Cu")
		(net "P5E_CPU1_P2_RX_DN<13>")
	)
	(arc
		(start 124.983494 -292.21049)
		(mid 125.139422 -291.906198)
		(end 124.983494 -291.601906)
		(width 0.1143)
		(layer "In6.Cu")
		(net "P5E_CPU1_P2_RX_DN<13>")
	)
	(arc
		(start 125.45441 -286.53994)
		(mid 125.568339 -286.406793)
		(end 125.60935 -286.23641)
		(width 0.1143)
		(layer "In6.Cu")
		(net "P5E_CPU1_P2_RX_DN<13>")
	)
	(arc
		(start 124.983494 -287.350454)
		(mid 125.09817 -287.21712)
		(end 125.13945 -287.046162)
		(width 0.1143)
		(layer "In6.Cu")
		(net "P5E_CPU1_P2_RX_DN<13>")
	)
	(arc
		(start 124.912628 -289.940746)
		(mid 124.669301 -289.47618)
		(end 124.912628 -289.011614)
		(width 0.1143)
		(layer "In6.Cu")
		(net "P5E_CPU1_P2_RX_DN<13>")
	)
	(arc
		(start 124.912628 -293.18077)
		(mid 124.669301 -292.716204)
		(end 124.912628 -292.251638)
		(width 0.1143)
		(layer "In6.Cu")
		(net "P5E_CPU1_P2_RX_DN<13>")
	)
	(arc
		(start 125.13945 -282.18638)
		(mid 125.203965 -281.924161)
		(end 125.382782 -281.721814)
		(width 0.1143)
		(layer "In6.Cu")
		(net "P5E_CPU1_P2_RX_DN<13>")
	)
	(arc
		(start 125.452378 -281.681174)
		(mid 125.550143 -281.578198)
		(end 125.602492 -281.446224)
		(width 0.1143)
		(layer "In6.Cu")
		(net "P5E_CPU1_P2_RX_DN<13>")
	)
	(arc
		(start 124.983494 -282.490672)
		(mid 125.09817 -282.357338)
		(end 125.13945 -282.18638)
		(width 0.1143)
		(layer "In6.Cu")
		(net "P5E_CPU1_P2_RX_DN<13>")
	)
	(arc
		(start 124.912628 -285.080964)
		(mid 124.669301 -284.616398)
		(end 124.912628 -284.151832)
		(width 0.1143)
		(layer "In6.Cu")
		(net "P5E_CPU1_P2_RX_DN<13>")
	)
	(arc
		(start 125.468888 -295.664128)
		(mid 125.460721 -295.657663)
		(end 125.452378 -295.651428)
		(width 0.1143)
		(layer "In6.Cu")
		(net "P5E_CPU1_P2_RX_DN<13>")
	)
	(segment
		(start 161.298382 -385.31038)
		(end 161.819082 -385.31038)
		(width 0.127)
		(layer "F.Cu")
		(net "P5E_CPU1_P2_RX_DN<12>")
	)
	(segment
		(start 121.94794 -282.730448)
		(end 122.414792 -282.996386)
		(width 0.12954)
		(layer "F.Cu")
		(net "P5E_CPU1_P2_RX_DN<12>")
	)
	(segment
		(start 122.795538 -283.07919)
		(end 122.712734 -282.996386)
		(width 0.1143)
		(layer "In6.Cu")
		(net "P5E_CPU1_P2_RX_DN<12>")
	)
	(segment
		(start 131.35102 -306.560728)
		(end 131.351274 -306.560728)
		(width 0.14224)
		(layer "In6.Cu")
		(net "P5E_CPU1_P2_RX_DN<12>")
	)
	(segment
		(start 163.910772 -377.66625)
		(end 164.090858 -377.593352)
		(width 0.14224)
		(layer "In6.Cu")
		(net "P5E_CPU1_P2_RX_DN<12>")
	)
	(segment
		(start 123.57354 -284.312106)
		(end 123.548902 -284.297882)
		(width 0.1143)
		(layer "In6.Cu")
		(net "P5E_CPU1_P2_RX_DN<12>")
	)
	(segment
		(start 136.411462 -313.233054)
		(end 134.586726 -310.50357)
		(width 0.14224)
		(layer "In6.Cu")
		(net "P5E_CPU1_P2_RX_DN<12>")
	)
	(segment
		(start 123.543822 -284.295088)
		(end 123.542552 -284.294326)
		(width 0.1143)
		(layer "In6.Cu")
		(net "P5E_CPU1_P2_RX_DN<12>")
	)
	(segment
		(start 124.044456 -288.362644)
		(end 123.972828 -288.320988)
		(width 0.1143)
		(layer "In6.Cu")
		(net "P5E_CPU1_P2_RX_DN<12>")
	)
	(segment
		(start 124.473716 -285.909004)
		(end 124.442728 -285.89097)
		(width 0.1143)
		(layer "In6.Cu")
		(net "P5E_CPU1_P2_RX_DN<12>")
	)
	(segment
		(start 124.442728 -286.581596)
		(end 124.515372 -286.539178)
		(width 0.1143)
		(layer "In6.Cu")
		(net "P5E_CPU1_P2_RX_DN<12>")
	)
	(segment
		(start 124.482606 -285.914338)
		(end 124.480574 -285.913068)
		(width 0.1143)
		(layer "In6.Cu")
		(net "P5E_CPU1_P2_RX_DN<12>")
	)
	(segment
		(start 124.042424 -293.22141)
		(end 123.972828 -293.18077)
		(width 0.1143)
		(layer "In6.Cu")
		(net "P5E_CPU1_P2_RX_DN<12>")
	)
	(segment
		(start 124.479304 -285.912306)
		(end 124.477018 -285.910782)
		(width 0.1143)
		(layer "In6.Cu")
		(net "P5E_CPU1_P2_RX_DN<12>")
	)
	(segment
		(start 124.48794 -285.917132)
		(end 124.485908 -285.916116)
		(width 0.1143)
		(layer "In6.Cu")
		(net "P5E_CPU1_P2_RX_DN<12>")
	)
	(segment
		(start 124.042424 -285.121604)
		(end 123.972828 -285.080964)
		(width 0.1143)
		(layer "In6.Cu")
		(net "P5E_CPU1_P2_RX_DN<12>")
	)
	(segment
		(start 123.972828 -289.011614)
		(end 124.042424 -288.970974)
		(width 0.1143)
		(layer "In6.Cu")
		(net "P5E_CPU1_P2_RX_DN<12>")
	)
	(segment
		(start 163.6522 -378.632466)
		(end 163.651946 -378.632466)
		(width 0.14224)
		(layer "In6.Cu")
		(net "P5E_CPU1_P2_RX_DN<12>")
	)
	(segment
		(start 163.472114 -378.705364)
		(end 163.6522 -378.632466)
		(width 0.14224)
		(layer "In6.Cu")
		(net "P5E_CPU1_P2_RX_DN<12>")
	)
	(segment
		(start 123.972828 -293.87165)
		(end 124.042424 -293.83101)
		(width 0.1143)
		(layer "In6.Cu")
		(net "P5E_CPU1_P2_RX_DN<12>")
	)
	(segment
		(start 162.17265 -385.404868)
		(end 162.294316 -385.334764)
		(width 0.14224)
		(layer "In6.Cu")
		(net "P5E_CPU1_P2_RX_DN<12>")
	)
	(segment
		(start 124.624338 -296.831766)
		(end 124.624338 -296.37736)
		(width 0.14224)
		(layer "In6.Cu")
		(net "P5E_CPU1_P2_RX_DN<12>")
	)
	(segment
		(start 123.972828 -290.631626)
		(end 124.042424 -290.590986)
		(width 0.1143)
		(layer "In6.Cu")
		(net "P5E_CPU1_P2_RX_DN<12>")
	)
	(segment
		(start 124.670058 -296.303192)
		(end 124.670058 -296.03573)
		(width 0.1143)
		(layer "In6.Cu")
		(net "P5E_CPU1_P2_RX_DN<12>")
	)
	(segment
		(start 162.172142 -385.405376)
		(end 162.17265 -385.404868)
		(width 0.14224)
		(layer "In6.Cu")
		(net "P5E_CPU1_P2_RX_DN<12>")
	)
	(segment
		(start 124.042424 -291.601398)
		(end 123.972828 -291.560758)
		(width 0.1143)
		(layer "In6.Cu")
		(net "P5E_CPU1_P2_RX_DN<12>")
	)
	(segment
		(start 164.090858 -377.593352)
		(end 164.090604 -377.593098)
		(width 0.14224)
		(layer "In6.Cu")
		(net "P5E_CPU1_P2_RX_DN<12>")
	)
	(segment
		(start 128.108202 -302.608742)
		(end 125.05309 -298.036742)
		(width 0.14224)
		(layer "In6.Cu")
		(net "P5E_CPU1_P2_RX_DN<12>")
	)
	(segment
		(start 162.454082 -381.470916)
		(end 162.940746 -380.317756)
		(width 0.14224)
		(layer "In6.Cu")
		(net "P5E_CPU1_P2_RX_DN<12>")
	)
	(segment
		(start 163.306252 -379.09881)
		(end 163.472114 -378.705364)
		(width 0.14224)
		(layer "In6.Cu")
		(net "P5E_CPU1_P2_RX_DN<12>")
	)
	(segment
		(start 162.294316 -385.334764)
		(end 162.294316 -385.163822)
		(width 0.14224)
		(layer "In6.Cu")
		(net "P5E_CPU1_P2_RX_DN<12>")
	)
	(segment
		(start 163.651946 -378.632466)
		(end 163.817808 -378.239528)
		(width 0.14224)
		(layer "In6.Cu")
		(net "P5E_CPU1_P2_RX_DN<12>")
	)
	(segment
		(start 123.548902 -284.297882)
		(end 123.547886 -284.297374)
		(width 0.1143)
		(layer "In6.Cu")
		(net "P5E_CPU1_P2_RX_DN<12>")
	)
	(segment
		(start 124.670058 -296.03573)
		(end 124.66955 -296.035222)
		(width 0.1143)
		(layer "In6.Cu")
		(net "P5E_CPU1_P2_RX_DN<12>")
	)
	(segment
		(start 124.042424 -294.841422)
		(end 123.972828 -294.800782)
		(width 0.1143)
		(layer "In6.Cu")
		(net "P5E_CPU1_P2_RX_DN<12>")
	)
	(segment
		(start 124.66955 -296.035222)
		(end 124.66955 -295.956228)
		(width 0.1143)
		(layer "In6.Cu")
		(net "P5E_CPU1_P2_RX_DN<12>")
	)
	(segment
		(start 162.867594 -380.137924)
		(end 163.03371 -379.744732)
		(width 0.14224)
		(layer "In6.Cu")
		(net "P5E_CPU1_P2_RX_DN<12>")
	)
	(segment
		(start 124.624338 -296.348912)
		(end 124.670058 -296.303192)
		(width 0.1143)
		(layer "In6.Cu")
		(net "P5E_CPU1_P2_RX_DN<12>")
	)
	(segment
		(start 162.294316 -385.163822)
		(end 161.977324 -384.84683)
		(width 0.14224)
		(layer "In6.Cu")
		(net "P5E_CPU1_P2_RX_DN<12>")
	)
	(segment
		(start 162.940746 -380.317756)
		(end 162.867594 -380.137924)
		(width 0.14224)
		(layer "In6.Cu")
		(net "P5E_CPU1_P2_RX_DN<12>")
	)
	(segment
		(start 123.547886 -284.297374)
		(end 123.546362 -284.296358)
		(width 0.1143)
		(layer "In6.Cu")
		(net "P5E_CPU1_P2_RX_DN<12>")
	)
	(segment
		(start 161.977324 -384.84683)
		(end 161.98215 -384.234944)
		(width 0.14224)
		(layer "In6.Cu")
		(net "P5E_CPU1_P2_RX_DN<12>")
	)
	(segment
		(start 124.476002 -285.910274)
		(end 124.473716 -285.909004)
		(width 0.1143)
		(layer "In6.Cu")
		(net "P5E_CPU1_P2_RX_DN<12>")
	)
	(segment
		(start 163.817808 -378.239528)
		(end 163.818062 -378.239528)
		(width 0.14224)
		(layer "In6.Cu")
		(net "P5E_CPU1_P2_RX_DN<12>")
	)
	(segment
		(start 124.042424 -289.981386)
		(end 123.972828 -289.940746)
		(width 0.1143)
		(layer "In6.Cu")
		(net "P5E_CPU1_P2_RX_DN<12>")
	)
	(segment
		(start 163.03371 -379.744732)
		(end 163.213542 -379.67158)
		(width 0.14224)
		(layer "In6.Cu")
		(net "P5E_CPU1_P2_RX_DN<12>")
	)
	(segment
		(start 163.379404 -379.278642)
		(end 163.306252 -379.09881)
		(width 0.14224)
		(layer "In6.Cu")
		(net "P5E_CPU1_P2_RX_DN<12>")
	)
	(segment
		(start 134.585456 -310.501792)
		(end 131.35102 -306.560728)
		(width 0.14224)
		(layer "In6.Cu")
		(net "P5E_CPU1_P2_RX_DN<12>")
	)
	(segment
		(start 123.542552 -284.294326)
		(end 123.54179 -284.293818)
		(width 0.1143)
		(layer "In6.Cu")
		(net "P5E_CPU1_P2_RX_DN<12>")
	)
	(segment
		(start 124.513594 -285.932118)
		(end 124.48794 -285.917132)
		(width 0.1143)
		(layer "In6.Cu")
		(net "P5E_CPU1_P2_RX_DN<12>")
	)
	(segment
		(start 163.900612 -366.375188)
		(end 156.592524 -359.0671)
		(width 0.14224)
		(layer "In6.Cu")
		(net "P5E_CPU1_P2_RX_DN<12>")
	)
	(segment
		(start 125.05309 -298.036742)
		(end 124.689108 -297.158156)
		(width 0.14224)
		(layer "In6.Cu")
		(net "P5E_CPU1_P2_RX_DN<12>")
	)
	(segment
		(start 124.624338 -296.37736)
		(end 124.624338 -296.348912)
		(width 0.1143)
		(layer "In6.Cu")
		(net "P5E_CPU1_P2_RX_DN<12>")
	)
	(segment
		(start 161.98215 -384.234944)
		(end 162.286188 -383.93116)
		(width 0.14224)
		(layer "In6.Cu")
		(net "P5E_CPU1_P2_RX_DN<12>")
	)
	(segment
		(start 123.975368 -287.390078)
		(end 124.042424 -287.350962)
		(width 0.1143)
		(layer "In6.Cu")
		(net "P5E_CPU1_P2_RX_DN<12>")
	)
	(segment
		(start 124.485908 -285.916116)
		(end 124.485146 -285.915608)
		(width 0.1143)
		(layer "In6.Cu")
		(net "P5E_CPU1_P2_RX_DN<12>")
	)
	(segment
		(start 144.0942 -335.68386)
		(end 141.535658 -322.819776)
		(width 0.14224)
		(layer "In6.Cu")
		(net "P5E_CPU1_P2_RX_DN<12>")
	)
	(segment
		(start 134.586726 -310.50357)
		(end 134.585456 -310.501792)
		(width 0.14224)
		(layer "In6.Cu")
		(net "P5E_CPU1_P2_RX_DN<12>")
	)
	(segment
		(start 141.535658 -322.819776)
		(end 136.411462 -313.233054)
		(width 0.14224)
		(layer "In6.Cu")
		(net "P5E_CPU1_P2_RX_DN<12>")
	)
	(segment
		(start 122.712734 -282.996386)
		(end 122.414792 -282.996386)
		(width 0.1143)
		(layer "In6.Cu")
		(net "P5E_CPU1_P2_RX_DN<12>")
	)
	(segment
		(start 124.477018 -285.910782)
		(end 124.476002 -285.910274)
		(width 0.1143)
		(layer "In6.Cu")
		(net "P5E_CPU1_P2_RX_DN<12>")
	)
	(segment
		(start 161.819082 -385.31038)
		(end 162.172142 -385.405376)
		(width 0.14224)
		(layer "In6.Cu")
		(net "P5E_CPU1_P2_RX_DN<12>")
	)
	(segment
		(start 166.758874 -371.245638)
		(end 166.758874 -368.561112)
		(width 0.14224)
		(layer "In6.Cu")
		(net "P5E_CPU1_P2_RX_DN<12>")
	)
	(segment
		(start 123.546362 -284.296358)
		(end 123.543822 -284.295088)
		(width 0.1143)
		(layer "In6.Cu")
		(net "P5E_CPU1_P2_RX_DN<12>")
	)
	(segment
		(start 124.485146 -285.915608)
		(end 124.482606 -285.914338)
		(width 0.1143)
		(layer "In6.Cu")
		(net "P5E_CPU1_P2_RX_DN<12>")
	)
	(segment
		(start 123.54179 -284.293818)
		(end 123.505468 -284.272736)
		(width 0.1143)
		(layer "In6.Cu")
		(net "P5E_CPU1_P2_RX_DN<12>")
	)
	(segment
		(start 124.480574 -285.913068)
		(end 124.479304 -285.912306)
		(width 0.1143)
		(layer "In6.Cu")
		(net "P5E_CPU1_P2_RX_DN<12>")
	)
	(segment
		(start 163.818062 -378.239528)
		(end 163.74491 -378.059696)
		(width 0.14224)
		(layer "In6.Cu")
		(net "P5E_CPU1_P2_RX_DN<12>")
	)
	(segment
		(start 163.74491 -378.059696)
		(end 163.910772 -377.66625)
		(width 0.14224)
		(layer "In6.Cu")
		(net "P5E_CPU1_P2_RX_DN<12>")
	)
	(segment
		(start 163.213542 -379.67158)
		(end 163.379404 -379.278642)
		(width 0.14224)
		(layer "In6.Cu")
		(net "P5E_CPU1_P2_RX_DN<12>")
	)
	(segment
		(start 131.351274 -306.560728)
		(end 128.108202 -302.608742)
		(width 0.14224)
		(layer "In6.Cu")
		(net "P5E_CPU1_P2_RX_DN<12>")
	)
	(segment
		(start 124.512324 -295.651428)
		(end 124.442728 -295.610788)
		(width 0.1143)
		(layer "In6.Cu")
		(net "P5E_CPU1_P2_RX_DN<12>")
	)
	(segment
		(start 164.090604 -377.593098)
		(end 166.748714 -371.295168)
		(width 0.14224)
		(layer "In6.Cu")
		(net "P5E_CPU1_P2_RX_DN<12>")
	)
	(segment
		(start 166.179246 -367.693956)
		(end 165.377368 -367.361978)
		(width 0.14224)
		(layer "In6.Cu")
		(net "P5E_CPU1_P2_RX_DN<12>")
	)
	(segment
		(start 162.286188 -383.93116)
		(end 162.286188 -382.30175)
		(width 0.14224)
		(layer "In6.Cu")
		(net "P5E_CPU1_P2_RX_DN<12>")
	)
	(segment
		(start 123.972828 -292.251638)
		(end 124.042424 -292.210998)
		(width 0.1143)
		(layer "In6.Cu")
		(net "P5E_CPU1_P2_RX_DN<12>")
	)
	(segment
		(start 123.094242 -283.496766)
		(end 123.032774 -283.460952)
		(width 0.1143)
		(layer "In6.Cu")
		(net "P5E_CPU1_P2_RX_DN<12>")
	)
	(arc
		(start 124.199396 -287.046162)
		(mid 124.263911 -286.783943)
		(end 124.442728 -286.581596)
		(width 0.1143)
		(layer "In6.Cu")
		(net "P5E_CPU1_P2_RX_DN<12>")
	)
	(arc
		(start 124.528834 -295.664128)
		(mid 124.520667 -295.657663)
		(end 124.512324 -295.651428)
		(width 0.1143)
		(layer "In6.Cu")
		(net "P5E_CPU1_P2_RX_DN<12>")
	)
	(arc
		(start 124.442728 -285.89097)
		(mid 124.263915 -285.68862)
		(end 124.199396 -285.426404)
		(width 0.1143)
		(layer "In6.Cu")
		(net "P5E_CPU1_P2_RX_DN<12>")
	)
	(arc
		(start 123.505468 -284.272736)
		(mid 123.500112 -284.269085)
		(end 123.4948 -284.26537)
		(width 0.1143)
		(layer "In6.Cu")
		(net "P5E_CPU1_P2_RX_DN<12>")
	)
	(arc
		(start 123.25731 -283.79674)
		(mid 123.202542 -283.632206)
		(end 123.094242 -283.496766)
		(width 0.1143)
		(layer "In6.Cu")
		(net "P5E_CPU1_P2_RX_DN<12>")
	)
	(arc
		(start 123.972828 -294.800782)
		(mid 123.729501 -294.336216)
		(end 123.972828 -293.87165)
		(width 0.1143)
		(layer "In6.Cu")
		(net "P5E_CPU1_P2_RX_DN<12>")
	)
	(arc
		(start 122.799348 -283.10205)
		(mid 122.797325 -283.09064)
		(end 122.795538 -283.07919)
		(width 0.1143)
		(layer "In6.Cu")
		(net "P5E_CPU1_P2_RX_DN<12>")
	)
	(arc
		(start 124.66955 -286.23641)
		(mid 124.628295 -286.065439)
		(end 124.513594 -285.932118)
		(width 0.1143)
		(layer "In6.Cu")
		(net "P5E_CPU1_P2_RX_DN<12>")
	)
	(arc
		(start 162.286188 -382.30175)
		(mid 162.328497 -381.877917)
		(end 162.454082 -381.470916)
		(width 0.14224)
		(layer "In6.Cu")
		(net "P5E_CPU1_P2_RX_DN<12>")
	)
	(arc
		(start 124.199396 -295.146222)
		(mid 124.157847 -294.9748)
		(end 124.042424 -294.841422)
		(width 0.1143)
		(layer "In6.Cu")
		(net "P5E_CPU1_P2_RX_DN<12>")
	)
	(arc
		(start 123.729496 -284.616398)
		(mid 123.688241 -284.445427)
		(end 123.57354 -284.312106)
		(width 0.1143)
		(layer "In6.Cu")
		(net "P5E_CPU1_P2_RX_DN<12>")
	)
	(arc
		(start 156.592524 -359.0671)
		(mid 148.609027 -348.302483)
		(end 144.0942 -335.68386)
		(width 0.14224)
		(layer "In6.Cu")
		(net "P5E_CPU1_P2_RX_DN<12>")
	)
	(arc
		(start 165.377368 -367.361978)
		(mid 164.590371 -366.941341)
		(end 163.900612 -366.375188)
		(width 0.14224)
		(layer "In6.Cu")
		(net "P5E_CPU1_P2_RX_DN<12>")
	)
	(arc
		(start 124.515372 -286.539178)
		(mid 124.628779 -286.406289)
		(end 124.66955 -286.23641)
		(width 0.1143)
		(layer "In6.Cu")
		(net "P5E_CPU1_P2_RX_DN<12>")
	)
	(arc
		(start 123.259342 -283.824426)
		(mid 123.258723 -283.810554)
		(end 123.25731 -283.79674)
		(width 0.1143)
		(layer "In6.Cu")
		(net "P5E_CPU1_P2_RX_DN<12>")
	)
	(arc
		(start 123.972828 -293.18077)
		(mid 123.729501 -292.716204)
		(end 123.972828 -292.251638)
		(width 0.1143)
		(layer "In6.Cu")
		(net "P5E_CPU1_P2_RX_DN<12>")
	)
	(arc
		(start 124.689108 -297.158156)
		(mid 124.640631 -296.998152)
		(end 124.624338 -296.831766)
		(width 0.14224)
		(layer "In6.Cu")
		(net "P5E_CPU1_P2_RX_DN<12>")
	)
	(arc
		(start 124.042424 -287.350962)
		(mid 124.157851 -287.217586)
		(end 124.199396 -287.046162)
		(width 0.1143)
		(layer "In6.Cu")
		(net "P5E_CPU1_P2_RX_DN<12>")
	)
	(arc
		(start 123.972828 -289.940746)
		(mid 123.729501 -289.47618)
		(end 123.972828 -289.011614)
		(width 0.1143)
		(layer "In6.Cu")
		(net "P5E_CPU1_P2_RX_DN<12>")
	)
	(arc
		(start 124.442728 -295.610788)
		(mid 124.263915 -295.408438)
		(end 124.199396 -295.146222)
		(width 0.1143)
		(layer "In6.Cu")
		(net "P5E_CPU1_P2_RX_DN<12>")
	)
	(arc
		(start 123.4948 -284.26537)
		(mid 123.325667 -284.072337)
		(end 123.259342 -283.824426)
		(width 0.1143)
		(layer "In6.Cu")
		(net "P5E_CPU1_P2_RX_DN<12>")
	)
	(arc
		(start 123.032774 -283.460952)
		(mid 122.880787 -283.304444)
		(end 122.799348 -283.10205)
		(width 0.1143)
		(layer "In6.Cu")
		(net "P5E_CPU1_P2_RX_DN<12>")
	)
	(arc
		(start 166.748714 -371.295168)
		(mid 166.756286 -371.270914)
		(end 166.758874 -371.245638)
		(width 0.14224)
		(layer "In6.Cu")
		(net "P5E_CPU1_P2_RX_DN<12>")
	)
	(arc
		(start 124.66955 -295.956228)
		(mid 124.63242 -295.79418)
		(end 124.528834 -295.664128)
		(width 0.1143)
		(layer "In6.Cu")
		(net "P5E_CPU1_P2_RX_DN<12>")
	)
	(arc
		(start 166.758874 -368.561112)
		(mid 166.60063 -368.039583)
		(end 166.179246 -367.693956)
		(width 0.14224)
		(layer "In6.Cu")
		(net "P5E_CPU1_P2_RX_DN<12>")
	)
	(arc
		(start 123.972828 -288.320988)
		(mid 123.729504 -287.854872)
		(end 123.975368 -287.390078)
		(width 0.1143)
		(layer "In6.Cu")
		(net "P5E_CPU1_P2_RX_DN<12>")
	)
	(arc
		(start 124.042424 -290.590986)
		(mid 124.199401 -290.286186)
		(end 124.042424 -289.981386)
		(width 0.1143)
		(layer "In6.Cu")
		(net "P5E_CPU1_P2_RX_DN<12>")
	)
	(arc
		(start 124.042424 -288.970974)
		(mid 124.157851 -288.837598)
		(end 124.199396 -288.666174)
		(width 0.1143)
		(layer "In6.Cu")
		(net "P5E_CPU1_P2_RX_DN<12>")
	)
	(arc
		(start 124.042424 -292.210998)
		(mid 124.199401 -291.906198)
		(end 124.042424 -291.601398)
		(width 0.1143)
		(layer "In6.Cu")
		(net "P5E_CPU1_P2_RX_DN<12>")
	)
	(arc
		(start 123.972828 -291.560758)
		(mid 123.729501 -291.096192)
		(end 123.972828 -290.631626)
		(width 0.1143)
		(layer "In6.Cu")
		(net "P5E_CPU1_P2_RX_DN<12>")
	)
	(arc
		(start 123.972828 -285.080964)
		(mid 123.794015 -284.878614)
		(end 123.729496 -284.616398)
		(width 0.1143)
		(layer "In6.Cu")
		(net "P5E_CPU1_P2_RX_DN<12>")
	)
	(arc
		(start 124.199396 -285.426404)
		(mid 124.157847 -285.254982)
		(end 124.042424 -285.121604)
		(width 0.1143)
		(layer "In6.Cu")
		(net "P5E_CPU1_P2_RX_DN<12>")
	)
	(arc
		(start 124.199396 -288.666174)
		(mid 124.15843 -288.495768)
		(end 124.044456 -288.362644)
		(width 0.1143)
		(layer "In6.Cu")
		(net "P5E_CPU1_P2_RX_DN<12>")
	)
	(arc
		(start 124.042424 -293.83101)
		(mid 124.199401 -293.52621)
		(end 124.042424 -293.22141)
		(width 0.1143)
		(layer "In6.Cu")
		(net "P5E_CPU1_P2_RX_DN<12>")
	)
	(segment
		(start 121.94794 -284.35046)
		(end 122.414792 -284.616398)
		(width 0.12954)
		(layer "F.Cu")
		(net "P5E_CPU1_P2_RX_DN<11>")
	)
	(segment
		(start 160.098232 -385.31038)
		(end 160.618932 -385.31038)
		(width 0.127)
		(layer "F.Cu")
		(net "P5E_CPU1_P2_RX_DN<11>")
	)
	(segment
		(start 162.684968 -377.531884)
		(end 162.840162 -377.13412)
		(width 0.14224)
		(layer "In6.Cu")
		(net "P5E_CPU1_P2_RX_DN<11>")
	)
	(segment
		(start 163.017962 -377.056142)
		(end 163.017962 -377.055888)
		(width 0.14224)
		(layer "In6.Cu")
		(net "P5E_CPU1_P2_RX_DN<11>")
	)
	(segment
		(start 161.942272 -379.81128)
		(end 161.942526 -379.81128)
		(width 0.14224)
		(layer "In6.Cu")
		(net "P5E_CPU1_P2_RX_DN<11>")
	)
	(segment
		(start 124.258578 -298.591478)
		(end 123.755912 -297.37812)
		(width 0.14224)
		(layer "In6.Cu")
		(net "P5E_CPU1_P2_RX_DN<11>")
	)
	(segment
		(start 123.729496 -296.086022)
		(end 123.729496 -295.956228)
		(width 0.1143)
		(layer "In6.Cu")
		(net "P5E_CPU1_P2_RX_DN<11>")
	)
	(segment
		(start 163.017962 -377.055888)
		(end 165.010592 -371.950996)
		(width 0.14224)
		(layer "In6.Cu")
		(net "P5E_CPU1_P2_RX_DN<11>")
	)
	(segment
		(start 162.197542 -379.157738)
		(end 162.352482 -378.760228)
		(width 0.14224)
		(layer "In6.Cu")
		(net "P5E_CPU1_P2_RX_DN<11>")
	)
	(segment
		(start 140.613892 -323.108574)
		(end 135.578596 -313.688984)
		(width 0.14224)
		(layer "In6.Cu")
		(net "P5E_CPU1_P2_RX_DN<11>")
	)
	(segment
		(start 162.429952 -378.184918)
		(end 162.607752 -378.10694)
		(width 0.14224)
		(layer "In6.Cu")
		(net "P5E_CPU1_P2_RX_DN<11>")
	)
	(segment
		(start 123.540774 -295.63314)
		(end 123.502674 -295.610788)
		(width 0.1143)
		(layer "In6.Cu")
		(net "P5E_CPU1_P2_RX_DN<11>")
	)
	(segment
		(start 123.104402 -288.362644)
		(end 123.07189 -288.343848)
		(width 0.1143)
		(layer "In6.Cu")
		(net "P5E_CPU1_P2_RX_DN<11>")
	)
	(segment
		(start 123.684284 -296.353738)
		(end 123.684284 -296.32529)
		(width 0.1143)
		(layer "In6.Cu")
		(net "P5E_CPU1_P2_RX_DN<11>")
	)
	(segment
		(start 161.086292 -383.864358)
		(end 161.086292 -382.12141)
		(width 0.14224)
		(layer "In6.Cu")
		(net "P5E_CPU1_P2_RX_DN<11>")
	)
	(segment
		(start 164.969444 -371.000274)
		(end 164.525706 -370.556536)
		(width 0.14224)
		(layer "In6.Cu")
		(net "P5E_CPU1_P2_RX_DN<11>")
	)
	(segment
		(start 123.502674 -286.581596)
		(end 123.572524 -286.54121)
		(width 0.1143)
		(layer "In6.Cu")
		(net "P5E_CPU1_P2_RX_DN<11>")
	)
	(segment
		(start 163.30803 -367.354358)
		(end 156.382466 -360.428794)
		(width 0.14224)
		(layer "In6.Cu")
		(net "P5E_CPU1_P2_RX_DN<11>")
	)
	(segment
		(start 123.542552 -295.634156)
		(end 123.540774 -295.63314)
		(width 0.1143)
		(layer "In6.Cu")
		(net "P5E_CPU1_P2_RX_DN<11>")
	)
	(segment
		(start 141.92377 -329.695048)
		(end 141.924024 -329.695048)
		(width 0.14224)
		(layer "In6.Cu")
		(net "P5E_CPU1_P2_RX_DN<11>")
	)
	(segment
		(start 123.035314 -287.390078)
		(end 123.10237 -287.350962)
		(width 0.1143)
		(layer "In6.Cu")
		(net "P5E_CPU1_P2_RX_DN<11>")
	)
	(segment
		(start 165.0619 -371.223286)
		(end 165.061646 -371.22354)
		(width 0.14224)
		(layer "In6.Cu")
		(net "P5E_CPU1_P2_RX_DN<11>")
	)
	(segment
		(start 163.355274 -369.416076)
		(end 163.355274 -367.468404)
		(width 0.14224)
		(layer "In6.Cu")
		(net "P5E_CPU1_P2_RX_DN<11>")
	)
	(segment
		(start 123.572524 -286.54121)
		(end 123.575318 -286.539178)
		(width 0.1143)
		(layer "In6.Cu")
		(net "P5E_CPU1_P2_RX_DN<11>")
	)
	(segment
		(start 123.57354 -285.932118)
		(end 123.54179 -285.91383)
		(width 0.1143)
		(layer "In6.Cu")
		(net "P5E_CPU1_P2_RX_DN<11>")
	)
	(segment
		(start 123.10237 -294.841422)
		(end 123.032774 -294.800782)
		(width 0.1143)
		(layer "In6.Cu")
		(net "P5E_CPU1_P2_RX_DN<11>")
	)
	(segment
		(start 160.972754 -385.404868)
		(end 161.09442 -385.334764)
		(width 0.14224)
		(layer "In6.Cu")
		(net "P5E_CPU1_P2_RX_DN<11>")
	)
	(segment
		(start 160.618932 -385.31038)
		(end 160.972246 -385.405376)
		(width 0.14224)
		(layer "In6.Cu")
		(net "P5E_CPU1_P2_RX_DN<11>")
	)
	(segment
		(start 162.762692 -377.70943)
		(end 162.684968 -377.531884)
		(width 0.14224)
		(layer "In6.Cu")
		(net "P5E_CPU1_P2_RX_DN<11>")
	)
	(segment
		(start 123.032774 -290.631626)
		(end 123.10237 -290.590986)
		(width 0.1143)
		(layer "In6.Cu")
		(net "P5E_CPU1_P2_RX_DN<11>")
	)
	(segment
		(start 163.972494 -370.249196)
		(end 163.773358 -370.13134)
		(width 0.14224)
		(layer "In6.Cu")
		(net "P5E_CPU1_P2_RX_DN<11>")
	)
	(segment
		(start 123.730004 -296.08653)
		(end 123.729496 -296.086022)
		(width 0.1143)
		(layer "In6.Cu")
		(net "P5E_CPU1_P2_RX_DN<11>")
	)
	(segment
		(start 123.10237 -291.601398)
		(end 123.032774 -291.560758)
		(width 0.1143)
		(layer "In6.Cu")
		(net "P5E_CPU1_P2_RX_DN<11>")
	)
	(segment
		(start 123.684284 -296.32529)
		(end 123.730004 -296.27957)
		(width 0.1143)
		(layer "In6.Cu")
		(net "P5E_CPU1_P2_RX_DN<11>")
	)
	(segment
		(start 162.019742 -379.235716)
		(end 162.197542 -379.157738)
		(width 0.14224)
		(layer "In6.Cu")
		(net "P5E_CPU1_P2_RX_DN<11>")
	)
	(segment
		(start 123.730004 -296.27957)
		(end 123.730004 -296.08653)
		(width 0.1143)
		(layer "In6.Cu")
		(net "P5E_CPU1_P2_RX_DN<11>")
	)
	(segment
		(start 162.274758 -378.582682)
		(end 162.429952 -378.184918)
		(width 0.14224)
		(layer "In6.Cu")
		(net "P5E_CPU1_P2_RX_DN<11>")
	)
	(segment
		(start 162.607752 -378.10694)
		(end 162.762692 -377.70943)
		(width 0.14224)
		(layer "In6.Cu")
		(net "P5E_CPU1_P2_RX_DN<11>")
	)
	(segment
		(start 123.032774 -289.011614)
		(end 123.10237 -288.970974)
		(width 0.1143)
		(layer "In6.Cu")
		(net "P5E_CPU1_P2_RX_DN<11>")
	)
	(segment
		(start 160.782254 -384.234944)
		(end 161.039048 -383.978404)
		(width 0.14224)
		(layer "In6.Cu")
		(net "P5E_CPU1_P2_RX_DN<11>")
	)
	(segment
		(start 133.770624 -310.98617)
		(end 130.469132 -306.963318)
		(width 0.14224)
		(layer "In6.Cu")
		(net "P5E_CPU1_P2_RX_DN<11>")
	)
	(segment
		(start 161.128964 -381.89535)
		(end 161.942272 -379.81128)
		(width 0.14224)
		(layer "In6.Cu")
		(net "P5E_CPU1_P2_RX_DN<11>")
	)
	(segment
		(start 162.840162 -377.13412)
		(end 163.017962 -377.056142)
		(width 0.14224)
		(layer "In6.Cu")
		(net "P5E_CPU1_P2_RX_DN<11>")
	)
	(segment
		(start 123.571508 -295.65092)
		(end 123.542552 -295.634156)
		(width 0.1143)
		(layer "In6.Cu")
		(net "P5E_CPU1_P2_RX_DN<11>")
	)
	(segment
		(start 123.10237 -293.22141)
		(end 123.032774 -293.18077)
		(width 0.1143)
		(layer "In6.Cu")
		(net "P5E_CPU1_P2_RX_DN<11>")
	)
	(segment
		(start 130.469386 -306.963318)
		(end 127.150622 -302.91913)
		(width 0.14224)
		(layer "In6.Cu")
		(net "P5E_CPU1_P2_RX_DN<11>")
	)
	(segment
		(start 123.032774 -292.251638)
		(end 123.10237 -292.210998)
		(width 0.1143)
		(layer "In6.Cu")
		(net "P5E_CPU1_P2_RX_DN<11>")
	)
	(segment
		(start 160.777428 -384.84683)
		(end 160.782254 -384.234944)
		(width 0.14224)
		(layer "In6.Cu")
		(net "P5E_CPU1_P2_RX_DN<11>")
	)
	(segment
		(start 122.712734 -284.616398)
		(end 122.414792 -284.616398)
		(width 0.1143)
		(layer "In6.Cu")
		(net "P5E_CPU1_P2_RX_DN<11>")
	)
	(segment
		(start 161.12871 -381.895604)
		(end 161.128964 -381.89535)
		(width 0.14224)
		(layer "In6.Cu")
		(net "P5E_CPU1_P2_RX_DN<11>")
	)
	(segment
		(start 127.150622 -302.91913)
		(end 124.258578 -298.591478)
		(width 0.14224)
		(layer "In6.Cu")
		(net "P5E_CPU1_P2_RX_DN<11>")
	)
	(segment
		(start 122.795538 -284.699202)
		(end 122.712734 -284.616398)
		(width 0.1143)
		(layer "In6.Cu")
		(net "P5E_CPU1_P2_RX_DN<11>")
	)
	(segment
		(start 141.924024 -329.695048)
		(end 140.613892 -323.108574)
		(width 0.14224)
		(layer "In6.Cu")
		(net "P5E_CPU1_P2_RX_DN<11>")
	)
	(segment
		(start 161.864548 -379.63348)
		(end 162.019742 -379.235716)
		(width 0.14224)
		(layer "In6.Cu")
		(net "P5E_CPU1_P2_RX_DN<11>")
	)
	(segment
		(start 161.09442 -385.334764)
		(end 161.09442 -385.163822)
		(width 0.14224)
		(layer "In6.Cu")
		(net "P5E_CPU1_P2_RX_DN<11>")
	)
	(segment
		(start 123.032774 -293.87165)
		(end 123.10237 -293.83101)
		(width 0.1143)
		(layer "In6.Cu")
		(net "P5E_CPU1_P2_RX_DN<11>")
	)
	(segment
		(start 161.942526 -379.81128)
		(end 161.864548 -379.63348)
		(width 0.14224)
		(layer "In6.Cu")
		(net "P5E_CPU1_P2_RX_DN<11>")
	)
	(segment
		(start 162.352482 -378.760228)
		(end 162.274758 -378.582682)
		(width 0.14224)
		(layer "In6.Cu")
		(net "P5E_CPU1_P2_RX_DN<11>")
	)
	(segment
		(start 143.091154 -335.56321)
		(end 141.92377 -329.695048)
		(width 0.14224)
		(layer "In6.Cu")
		(net "P5E_CPU1_P2_RX_DN<11>")
	)
	(segment
		(start 123.54179 -285.91383)
		(end 123.502674 -285.89097)
		(width 0.1143)
		(layer "In6.Cu")
		(net "P5E_CPU1_P2_RX_DN<11>")
	)
	(segment
		(start 123.10237 -285.121604)
		(end 123.032774 -285.080964)
		(width 0.1143)
		(layer "In6.Cu")
		(net "P5E_CPU1_P2_RX_DN<11>")
	)
	(segment
		(start 164.268658 -370.384832)
		(end 164.121338 -370.323872)
		(width 0.14224)
		(layer "In6.Cu")
		(net "P5E_CPU1_P2_RX_DN<11>")
	)
	(segment
		(start 130.469132 -306.963318)
		(end 130.469386 -306.963318)
		(width 0.14224)
		(layer "In6.Cu")
		(net "P5E_CPU1_P2_RX_DN<11>")
	)
	(segment
		(start 123.07189 -288.343848)
		(end 123.032774 -288.320988)
		(width 0.1143)
		(layer "In6.Cu")
		(net "P5E_CPU1_P2_RX_DN<11>")
	)
	(segment
		(start 160.972246 -385.405376)
		(end 160.972754 -385.404868)
		(width 0.14224)
		(layer "In6.Cu")
		(net "P5E_CPU1_P2_RX_DN<11>")
	)
	(segment
		(start 165.0619 -371.678708)
		(end 165.0619 -371.223286)
		(width 0.14224)
		(layer "In6.Cu")
		(net "P5E_CPU1_P2_RX_DN<11>")
	)
	(segment
		(start 123.684284 -297.016678)
		(end 123.684284 -296.353738)
		(width 0.14224)
		(layer "In6.Cu")
		(net "P5E_CPU1_P2_RX_DN<11>")
	)
	(segment
		(start 161.09442 -385.163822)
		(end 160.777428 -384.84683)
		(width 0.14224)
		(layer "In6.Cu")
		(net "P5E_CPU1_P2_RX_DN<11>")
	)
	(segment
		(start 123.10237 -289.981386)
		(end 123.032774 -289.940746)
		(width 0.1143)
		(layer "In6.Cu")
		(net "P5E_CPU1_P2_RX_DN<11>")
	)
	(segment
		(start 135.578596 -313.688984)
		(end 133.770624 -310.98617)
		(width 0.14224)
		(layer "In6.Cu")
		(net "P5E_CPU1_P2_RX_DN<11>")
	)
	(arc
		(start 122.799348 -284.722062)
		(mid 122.797325 -284.710652)
		(end 122.795538 -284.699202)
		(width 0.1143)
		(layer "In6.Cu")
		(net "P5E_CPU1_P2_RX_DN<11>")
	)
	(arc
		(start 123.032774 -294.800782)
		(mid 122.789447 -294.336216)
		(end 123.032774 -293.87165)
		(width 0.1143)
		(layer "In6.Cu")
		(net "P5E_CPU1_P2_RX_DN<11>")
	)
	(arc
		(start 165.061646 -371.22354)
		(mid 165.03773 -371.102748)
		(end 164.969444 -371.000274)
		(width 0.14224)
		(layer "In6.Cu")
		(net "P5E_CPU1_P2_RX_DN<11>")
	)
	(arc
		(start 123.10237 -290.590986)
		(mid 123.259347 -290.286186)
		(end 123.10237 -289.981386)
		(width 0.1143)
		(layer "In6.Cu")
		(net "P5E_CPU1_P2_RX_DN<11>")
	)
	(arc
		(start 123.259342 -285.426404)
		(mid 123.217793 -285.254982)
		(end 123.10237 -285.121604)
		(width 0.1143)
		(layer "In6.Cu")
		(net "P5E_CPU1_P2_RX_DN<11>")
	)
	(arc
		(start 123.259342 -288.666174)
		(mid 123.218376 -288.495768)
		(end 123.104402 -288.362644)
		(width 0.1143)
		(layer "In6.Cu")
		(net "P5E_CPU1_P2_RX_DN<11>")
	)
	(arc
		(start 123.259342 -287.046162)
		(mid 123.323857 -286.783943)
		(end 123.502674 -286.581596)
		(width 0.1143)
		(layer "In6.Cu")
		(net "P5E_CPU1_P2_RX_DN<11>")
	)
	(arc
		(start 123.032774 -285.080964)
		(mid 122.880787 -284.924456)
		(end 122.799348 -284.722062)
		(width 0.1143)
		(layer "In6.Cu")
		(net "P5E_CPU1_P2_RX_DN<11>")
	)
	(arc
		(start 165.010592 -371.950996)
		(mid 165.048948 -371.817248)
		(end 165.0619 -371.678708)
		(width 0.14224)
		(layer "In6.Cu")
		(net "P5E_CPU1_P2_RX_DN<11>")
	)
	(arc
		(start 164.121338 -370.323872)
		(mid 164.045585 -370.289186)
		(end 163.972494 -370.249196)
		(width 0.14224)
		(layer "In6.Cu")
		(net "P5E_CPU1_P2_RX_DN<11>")
	)
	(arc
		(start 163.401756 -369.65509)
		(mid 163.366966 -369.537831)
		(end 163.355274 -369.416076)
		(width 0.14224)
		(layer "In6.Cu")
		(net "P5E_CPU1_P2_RX_DN<11>")
	)
	(arc
		(start 123.502674 -285.89097)
		(mid 123.323861 -285.68862)
		(end 123.259342 -285.426404)
		(width 0.1143)
		(layer "In6.Cu")
		(net "P5E_CPU1_P2_RX_DN<11>")
	)
	(arc
		(start 123.729496 -295.956228)
		(mid 123.687617 -295.784359)
		(end 123.571508 -295.65092)
		(width 0.1143)
		(layer "In6.Cu")
		(net "P5E_CPU1_P2_RX_DN<11>")
	)
	(arc
		(start 123.729496 -286.23641)
		(mid 123.685425 -286.066874)
		(end 123.57354 -285.932118)
		(width 0.1143)
		(layer "In6.Cu")
		(net "P5E_CPU1_P2_RX_DN<11>")
	)
	(arc
		(start 123.10237 -292.210998)
		(mid 123.259347 -291.906198)
		(end 123.10237 -291.601398)
		(width 0.1143)
		(layer "In6.Cu")
		(net "P5E_CPU1_P2_RX_DN<11>")
	)
	(arc
		(start 156.382466 -360.428794)
		(mid 147.892611 -348.981768)
		(end 143.091154 -335.56321)
		(width 0.14224)
		(layer "In6.Cu")
		(net "P5E_CPU1_P2_RX_DN<11>")
	)
	(arc
		(start 123.032774 -293.18077)
		(mid 122.789447 -292.716204)
		(end 123.032774 -292.251638)
		(width 0.1143)
		(layer "In6.Cu")
		(net "P5E_CPU1_P2_RX_DN<11>")
	)
	(arc
		(start 123.10237 -287.350962)
		(mid 123.217797 -287.217586)
		(end 123.259342 -287.046162)
		(width 0.1143)
		(layer "In6.Cu")
		(net "P5E_CPU1_P2_RX_DN<11>")
	)
	(arc
		(start 123.032774 -289.940746)
		(mid 122.789447 -289.47618)
		(end 123.032774 -289.011614)
		(width 0.1143)
		(layer "In6.Cu")
		(net "P5E_CPU1_P2_RX_DN<11>")
	)
	(arc
		(start 161.039048 -383.978404)
		(mid 161.074064 -383.926094)
		(end 161.086292 -383.864358)
		(width 0.14224)
		(layer "In6.Cu")
		(net "P5E_CPU1_P2_RX_DN<11>")
	)
	(arc
		(start 123.032774 -291.560758)
		(mid 122.789447 -291.096192)
		(end 123.032774 -290.631626)
		(width 0.1143)
		(layer "In6.Cu")
		(net "P5E_CPU1_P2_RX_DN<11>")
	)
	(arc
		(start 123.032774 -288.320988)
		(mid 122.853961 -288.118638)
		(end 122.789442 -287.856422)
		(width 0.1143)
		(layer "In6.Cu")
		(net "P5E_CPU1_P2_RX_DN<11>")
	)
	(arc
		(start 122.789442 -287.856422)
		(mid 122.854678 -287.592831)
		(end 123.035314 -287.390078)
		(width 0.1143)
		(layer "In6.Cu")
		(net "P5E_CPU1_P2_RX_DN<11>")
	)
	(arc
		(start 161.086292 -382.12141)
		(mid 161.096991 -382.006533)
		(end 161.12871 -381.895604)
		(width 0.14224)
		(layer "In6.Cu")
		(net "P5E_CPU1_P2_RX_DN<11>")
	)
	(arc
		(start 163.355274 -367.468404)
		(mid 163.342997 -367.406681)
		(end 163.30803 -367.354358)
		(width 0.14224)
		(layer "In6.Cu")
		(net "P5E_CPU1_P2_RX_DN<11>")
	)
	(arc
		(start 123.502674 -295.610788)
		(mid 123.323861 -295.408438)
		(end 123.259342 -295.146222)
		(width 0.1143)
		(layer "In6.Cu")
		(net "P5E_CPU1_P2_RX_DN<11>")
	)
	(arc
		(start 123.755912 -297.37812)
		(mid 123.702273 -297.20093)
		(end 123.684284 -297.016678)
		(width 0.14224)
		(layer "In6.Cu")
		(net "P5E_CPU1_P2_RX_DN<11>")
	)
	(arc
		(start 123.575318 -286.539178)
		(mid 123.688725 -286.406289)
		(end 123.729496 -286.23641)
		(width 0.1143)
		(layer "In6.Cu")
		(net "P5E_CPU1_P2_RX_DN<11>")
	)
	(arc
		(start 163.605718 -369.991132)
		(mid 163.490154 -369.831356)
		(end 163.401756 -369.65509)
		(width 0.14224)
		(layer "In6.Cu")
		(net "P5E_CPU1_P2_RX_DN<11>")
	)
	(arc
		(start 123.259342 -295.146222)
		(mid 123.217793 -294.9748)
		(end 123.10237 -294.841422)
		(width 0.1143)
		(layer "In6.Cu")
		(net "P5E_CPU1_P2_RX_DN<11>")
	)
	(arc
		(start 123.10237 -293.83101)
		(mid 123.259347 -293.52621)
		(end 123.10237 -293.22141)
		(width 0.1143)
		(layer "In6.Cu")
		(net "P5E_CPU1_P2_RX_DN<11>")
	)
	(arc
		(start 164.525706 -370.556536)
		(mid 164.405656 -370.457996)
		(end 164.268658 -370.384832)
		(width 0.14224)
		(layer "In6.Cu")
		(net "P5E_CPU1_P2_RX_DN<11>")
	)
	(arc
		(start 123.10237 -288.970974)
		(mid 123.217797 -288.837598)
		(end 123.259342 -288.666174)
		(width 0.1143)
		(layer "In6.Cu")
		(net "P5E_CPU1_P2_RX_DN<11>")
	)
	(arc
		(start 163.773358 -370.13134)
		(mid 163.683776 -370.068125)
		(end 163.605718 -369.991132)
		(width 0.14224)
		(layer "In6.Cu")
		(net "P5E_CPU1_P2_RX_DN<11>")
	)
	(segment
		(start 158.898336 -385.31038)
		(end 159.419036 -385.31038)
		(width 0.127)
		(layer "F.Cu")
		(net "P5E_CPU1_P2_RX_DN<10>")
	)
	(segment
		(start 121.94794 -285.970472)
		(end 122.414792 -286.23641)
		(width 0.12954)
		(layer "F.Cu")
		(net "P5E_CPU1_P2_RX_DN<10>")
	)
	(segment
		(start 122.744484 -297.2308)
		(end 122.744484 -296.353738)
		(width 0.14224)
		(layer "In6.Cu")
		(net "P5E_CPU1_P2_RX_DN<10>")
	)
	(segment
		(start 122.782584 -286.30626)
		(end 122.712734 -286.23641)
		(width 0.1143)
		(layer "In6.Cu")
		(net "P5E_CPU1_P2_RX_DN<10>")
	)
	(segment
		(start 132.562092 -310.990234)
		(end 126.398782 -303.480216)
		(width 0.14224)
		(layer "In6.Cu")
		(net "P5E_CPU1_P2_RX_DN<10>")
	)
	(segment
		(start 159.886396 -380.7841)
		(end 159.886396 -380.35738)
		(width 0.14224)
		(layer "In6.Cu")
		(net "P5E_CPU1_P2_RX_DN<10>")
	)
	(segment
		(start 159.886396 -381.48514)
		(end 159.749236 -381.34798)
		(width 0.14224)
		(layer "In6.Cu")
		(net "P5E_CPU1_P2_RX_DN<10>")
	)
	(segment
		(start 122.09526 -287.390078)
		(end 122.162316 -287.350962)
		(width 0.1143)
		(layer "In6.Cu")
		(net "P5E_CPU1_P2_RX_DN<10>")
	)
	(segment
		(start 123.380246 -298.962826)
		(end 122.819668 -297.609006)
		(width 0.14224)
		(layer "In6.Cu")
		(net "P5E_CPU1_P2_RX_DN<10>")
	)
	(segment
		(start 122.790204 -296.27957)
		(end 122.790204 -296.08653)
		(width 0.1143)
		(layer "In6.Cu")
		(net "P5E_CPU1_P2_RX_DN<10>")
	)
	(segment
		(start 159.77235 -385.405376)
		(end 159.772858 -385.404868)
		(width 0.14224)
		(layer "In6.Cu")
		(net "P5E_CPU1_P2_RX_DN<10>")
	)
	(segment
		(start 159.886396 -378.52858)
		(end 159.886396 -374.180862)
		(width 0.14224)
		(layer "In6.Cu")
		(net "P5E_CPU1_P2_RX_DN<10>")
	)
	(segment
		(start 122.162316 -293.22141)
		(end 122.09272 -293.18077)
		(width 0.1143)
		(layer "In6.Cu")
		(net "P5E_CPU1_P2_RX_DN<10>")
	)
	(segment
		(start 122.603768 -295.634918)
		(end 122.602498 -295.634156)
		(width 0.1143)
		(layer "In6.Cu")
		(net "P5E_CPU1_P2_RX_DN<10>")
	)
	(segment
		(start 122.633486 -295.651936)
		(end 122.607832 -295.637204)
		(width 0.1143)
		(layer "In6.Cu")
		(net "P5E_CPU1_P2_RX_DN<10>")
	)
	(segment
		(start 122.56262 -286.581596)
		(end 122.635264 -286.539178)
		(width 0.1143)
		(layer "In6.Cu")
		(net "P5E_CPU1_P2_RX_DN<10>")
	)
	(segment
		(start 122.131836 -288.343848)
		(end 122.09272 -288.320988)
		(width 0.1143)
		(layer "In6.Cu")
		(net "P5E_CPU1_P2_RX_DN<10>")
	)
	(segment
		(start 122.606308 -295.636188)
		(end 122.603768 -295.634918)
		(width 0.1143)
		(layer "In6.Cu")
		(net "P5E_CPU1_P2_RX_DN<10>")
	)
	(segment
		(start 159.577532 -384.84683)
		(end 159.582358 -384.234944)
		(width 0.14224)
		(layer "In6.Cu")
		(net "P5E_CPU1_P2_RX_DN<10>")
	)
	(segment
		(start 159.894524 -385.334764)
		(end 159.894524 -385.163822)
		(width 0.14224)
		(layer "In6.Cu")
		(net "P5E_CPU1_P2_RX_DN<10>")
	)
	(segment
		(start 159.886396 -380.35738)
		(end 159.749236 -380.22022)
		(width 0.14224)
		(layer "In6.Cu")
		(net "P5E_CPU1_P2_RX_DN<10>")
	)
	(segment
		(start 142.074646 -335.248758)
		(end 142.0749 -335.248758)
		(width 0.14224)
		(layer "In6.Cu")
		(net "P5E_CPU1_P2_RX_DN<10>")
	)
	(segment
		(start 159.749236 -379.7935)
		(end 159.886396 -379.65634)
		(width 0.14224)
		(layer "In6.Cu")
		(net "P5E_CPU1_P2_RX_DN<10>")
	)
	(segment
		(start 122.712734 -286.23641)
		(end 122.414792 -286.23641)
		(width 0.1143)
		(layer "In6.Cu")
		(net "P5E_CPU1_P2_RX_DN<10>")
	)
	(segment
		(start 134.325868 -313.493658)
		(end 132.562092 -310.990234)
		(width 0.14224)
		(layer "In6.Cu")
		(net "P5E_CPU1_P2_RX_DN<10>")
	)
	(segment
		(start 159.886396 -383.93116)
		(end 159.886396 -381.48514)
		(width 0.14224)
		(layer "In6.Cu")
		(net "P5E_CPU1_P2_RX_DN<10>")
	)
	(segment
		(start 139.737084 -323.494654)
		(end 134.933436 -314.507372)
		(width 0.14224)
		(layer "In6.Cu")
		(net "P5E_CPU1_P2_RX_DN<10>")
	)
	(segment
		(start 122.09272 -289.011614)
		(end 122.162316 -288.970974)
		(width 0.1143)
		(layer "In6.Cu")
		(net "P5E_CPU1_P2_RX_DN<10>")
	)
	(segment
		(start 142.386304 -336.81416)
		(end 142.0749 -335.249012)
		(width 0.14224)
		(layer "In6.Cu")
		(net "P5E_CPU1_P2_RX_DN<10>")
	)
	(segment
		(start 134.933436 -314.507372)
		(end 134.325868 -313.493658)
		(width 0.14224)
		(layer "In6.Cu")
		(net "P5E_CPU1_P2_RX_DN<10>")
	)
	(segment
		(start 159.749236 -380.92126)
		(end 159.886396 -380.7841)
		(width 0.14224)
		(layer "In6.Cu")
		(net "P5E_CPU1_P2_RX_DN<10>")
	)
	(segment
		(start 159.749236 -381.34798)
		(end 159.749236 -380.92126)
		(width 0.14224)
		(layer "In6.Cu")
		(net "P5E_CPU1_P2_RX_DN<10>")
	)
	(segment
		(start 159.886396 -379.65634)
		(end 159.886396 -379.22962)
		(width 0.14224)
		(layer "In6.Cu")
		(net "P5E_CPU1_P2_RX_DN<10>")
	)
	(segment
		(start 122.164348 -288.362644)
		(end 122.131836 -288.343848)
		(width 0.1143)
		(layer "In6.Cu")
		(net "P5E_CPU1_P2_RX_DN<10>")
	)
	(segment
		(start 159.749236 -378.66574)
		(end 159.886396 -378.52858)
		(width 0.14224)
		(layer "In6.Cu")
		(net "P5E_CPU1_P2_RX_DN<10>")
	)
	(segment
		(start 159.894524 -385.163822)
		(end 159.577532 -384.84683)
		(width 0.14224)
		(layer "In6.Cu")
		(net "P5E_CPU1_P2_RX_DN<10>")
	)
	(segment
		(start 122.744484 -296.32529)
		(end 122.790204 -296.27957)
		(width 0.1143)
		(layer "In6.Cu")
		(net "P5E_CPU1_P2_RX_DN<10>")
	)
	(segment
		(start 159.419036 -385.31038)
		(end 159.77235 -385.405376)
		(width 0.14224)
		(layer "In6.Cu")
		(net "P5E_CPU1_P2_RX_DN<10>")
	)
	(segment
		(start 122.09272 -290.631626)
		(end 122.162316 -290.590986)
		(width 0.1143)
		(layer "In6.Cu")
		(net "P5E_CPU1_P2_RX_DN<10>")
	)
	(segment
		(start 159.749236 -380.22022)
		(end 159.749236 -379.7935)
		(width 0.14224)
		(layer "In6.Cu")
		(net "P5E_CPU1_P2_RX_DN<10>")
	)
	(segment
		(start 122.162316 -289.981386)
		(end 122.09272 -289.940746)
		(width 0.1143)
		(layer "In6.Cu")
		(net "P5E_CPU1_P2_RX_DN<10>")
	)
	(segment
		(start 142.0749 -335.249012)
		(end 142.074646 -335.248758)
		(width 0.14224)
		(layer "In6.Cu")
		(net "P5E_CPU1_P2_RX_DN<10>")
	)
	(segment
		(start 122.607832 -295.637204)
		(end 122.606308 -295.636188)
		(width 0.1143)
		(layer "In6.Cu")
		(net "P5E_CPU1_P2_RX_DN<10>")
	)
	(segment
		(start 122.790204 -296.08653)
		(end 122.789696 -296.086022)
		(width 0.1143)
		(layer "In6.Cu")
		(net "P5E_CPU1_P2_RX_DN<10>")
	)
	(segment
		(start 142.0749 -335.248758)
		(end 139.737084 -323.494654)
		(width 0.14224)
		(layer "In6.Cu")
		(net "P5E_CPU1_P2_RX_DN<10>")
	)
	(segment
		(start 161.12617 -367.143792)
		(end 153.3144 -358.52354)
		(width 0.14224)
		(layer "In6.Cu")
		(net "P5E_CPU1_P2_RX_DN<10>")
	)
	(segment
		(start 153.3144 -358.52354)
		(end 153.314146 -358.52354)
		(width 0.14224)
		(layer "In6.Cu")
		(net "P5E_CPU1_P2_RX_DN<10>")
	)
	(segment
		(start 122.744484 -296.353738)
		(end 122.744484 -296.32529)
		(width 0.1143)
		(layer "In6.Cu")
		(net "P5E_CPU1_P2_RX_DN<10>")
	)
	(segment
		(start 122.09272 -292.251638)
		(end 122.162316 -292.210998)
		(width 0.1143)
		(layer "In6.Cu")
		(net "P5E_CPU1_P2_RX_DN<10>")
	)
	(segment
		(start 160.038034 -373.507508)
		(end 161.158174 -371.147594)
		(width 0.14224)
		(layer "In6.Cu")
		(net "P5E_CPU1_P2_RX_DN<10>")
	)
	(segment
		(start 159.582358 -384.234944)
		(end 159.886396 -383.93116)
		(width 0.14224)
		(layer "In6.Cu")
		(net "P5E_CPU1_P2_RX_DN<10>")
	)
	(segment
		(start 159.749236 -379.09246)
		(end 159.749236 -378.66574)
		(width 0.14224)
		(layer "In6.Cu")
		(net "P5E_CPU1_P2_RX_DN<10>")
	)
	(segment
		(start 161.17062 -371.09273)
		(end 161.17062 -367.259108)
		(width 0.14224)
		(layer "In6.Cu")
		(net "P5E_CPU1_P2_RX_DN<10>")
	)
	(segment
		(start 122.162316 -291.601398)
		(end 122.09272 -291.560758)
		(width 0.1143)
		(layer "In6.Cu")
		(net "P5E_CPU1_P2_RX_DN<10>")
	)
	(segment
		(start 122.601736 -295.633648)
		(end 122.60072 -295.63314)
		(width 0.1143)
		(layer "In6.Cu")
		(net "P5E_CPU1_P2_RX_DN<10>")
	)
	(segment
		(start 122.789696 -296.086022)
		(end 122.789696 -295.956228)
		(width 0.1143)
		(layer "In6.Cu")
		(net "P5E_CPU1_P2_RX_DN<10>")
	)
	(segment
		(start 159.772858 -385.404868)
		(end 159.894524 -385.334764)
		(width 0.14224)
		(layer "In6.Cu")
		(net "P5E_CPU1_P2_RX_DN<10>")
	)
	(segment
		(start 126.398782 -303.480216)
		(end 123.380246 -298.962826)
		(width 0.14224)
		(layer "In6.Cu")
		(net "P5E_CPU1_P2_RX_DN<10>")
	)
	(segment
		(start 122.09272 -293.87165)
		(end 122.162316 -293.83101)
		(width 0.1143)
		(layer "In6.Cu")
		(net "P5E_CPU1_P2_RX_DN<10>")
	)
	(segment
		(start 122.60072 -295.63314)
		(end 122.56262 -295.610788)
		(width 0.1143)
		(layer "In6.Cu")
		(net "P5E_CPU1_P2_RX_DN<10>")
	)
	(segment
		(start 122.602498 -295.634156)
		(end 122.601736 -295.633648)
		(width 0.1143)
		(layer "In6.Cu")
		(net "P5E_CPU1_P2_RX_DN<10>")
	)
	(segment
		(start 122.162316 -294.841422)
		(end 122.09272 -294.800782)
		(width 0.1143)
		(layer "In6.Cu")
		(net "P5E_CPU1_P2_RX_DN<10>")
	)
	(segment
		(start 159.886396 -379.22962)
		(end 159.749236 -379.09246)
		(width 0.14224)
		(layer "In6.Cu")
		(net "P5E_CPU1_P2_RX_DN<10>")
	)
	(arc
		(start 161.17062 -367.259108)
		(mid 161.159131 -367.197308)
		(end 161.12617 -367.143792)
		(width 0.14224)
		(layer "In6.Cu")
		(net "P5E_CPU1_P2_RX_DN<10>")
	)
	(arc
		(start 122.162316 -292.210998)
		(mid 122.319293 -291.906198)
		(end 122.162316 -291.601398)
		(width 0.1143)
		(layer "In6.Cu")
		(net "P5E_CPU1_P2_RX_DN<10>")
	)
	(arc
		(start 122.819668 -297.609006)
		(mid 122.76346 -297.423604)
		(end 122.744484 -297.2308)
		(width 0.14224)
		(layer "In6.Cu")
		(net "P5E_CPU1_P2_RX_DN<10>")
	)
	(arc
		(start 122.319288 -295.146222)
		(mid 122.277739 -294.9748)
		(end 122.162316 -294.841422)
		(width 0.1143)
		(layer "In6.Cu")
		(net "P5E_CPU1_P2_RX_DN<10>")
	)
	(arc
		(start 159.886396 -374.180862)
		(mid 159.924788 -373.83576)
		(end 160.038034 -373.507508)
		(width 0.14224)
		(layer "In6.Cu")
		(net "P5E_CPU1_P2_RX_DN<10>")
	)
	(arc
		(start 122.09272 -294.800782)
		(mid 121.849393 -294.336216)
		(end 122.09272 -293.87165)
		(width 0.1143)
		(layer "In6.Cu")
		(net "P5E_CPU1_P2_RX_DN<10>")
	)
	(arc
		(start 122.56262 -295.610788)
		(mid 122.383807 -295.408438)
		(end 122.319288 -295.146222)
		(width 0.1143)
		(layer "In6.Cu")
		(net "P5E_CPU1_P2_RX_DN<10>")
	)
	(arc
		(start 122.162316 -293.83101)
		(mid 122.319293 -293.52621)
		(end 122.162316 -293.22141)
		(width 0.1143)
		(layer "In6.Cu")
		(net "P5E_CPU1_P2_RX_DN<10>")
	)
	(arc
		(start 122.09272 -293.18077)
		(mid 121.849393 -292.716204)
		(end 122.09272 -292.251638)
		(width 0.1143)
		(layer "In6.Cu")
		(net "P5E_CPU1_P2_RX_DN<10>")
	)
	(arc
		(start 122.635264 -286.539178)
		(mid 122.731152 -286.43677)
		(end 122.782584 -286.30626)
		(width 0.1143)
		(layer "In6.Cu")
		(net "P5E_CPU1_P2_RX_DN<10>")
	)
	(arc
		(start 122.09272 -289.940746)
		(mid 121.849393 -289.47618)
		(end 122.09272 -289.011614)
		(width 0.1143)
		(layer "In6.Cu")
		(net "P5E_CPU1_P2_RX_DN<10>")
	)
	(arc
		(start 122.162316 -287.350962)
		(mid 122.277743 -287.217586)
		(end 122.319288 -287.046162)
		(width 0.1143)
		(layer "In6.Cu")
		(net "P5E_CPU1_P2_RX_DN<10>")
	)
	(arc
		(start 122.09272 -291.560758)
		(mid 121.849393 -291.096192)
		(end 122.09272 -290.631626)
		(width 0.1143)
		(layer "In6.Cu")
		(net "P5E_CPU1_P2_RX_DN<10>")
	)
	(arc
		(start 153.314146 -358.52354)
		(mid 146.376296 -348.410788)
		(end 142.386304 -336.81416)
		(width 0.14224)
		(layer "In6.Cu")
		(net "P5E_CPU1_P2_RX_DN<10>")
	)
	(arc
		(start 122.319288 -288.666174)
		(mid 122.278322 -288.495768)
		(end 122.164348 -288.362644)
		(width 0.1143)
		(layer "In6.Cu")
		(net "P5E_CPU1_P2_RX_DN<10>")
	)
	(arc
		(start 122.789696 -295.956228)
		(mid 122.766868 -295.827747)
		(end 122.701304 -295.714928)
		(width 0.1143)
		(layer "In6.Cu")
		(net "P5E_CPU1_P2_RX_DN<10>")
	)
	(arc
		(start 122.162316 -288.970974)
		(mid 122.277743 -288.837598)
		(end 122.319288 -288.666174)
		(width 0.1143)
		(layer "In6.Cu")
		(net "P5E_CPU1_P2_RX_DN<10>")
	)
	(arc
		(start 161.158174 -371.147594)
		(mid 161.167443 -371.120855)
		(end 161.17062 -371.09273)
		(width 0.14224)
		(layer "In6.Cu")
		(net "P5E_CPU1_P2_RX_DN<10>")
	)
	(arc
		(start 122.701304 -295.714928)
		(mid 122.669345 -295.681333)
		(end 122.633486 -295.651936)
		(width 0.1143)
		(layer "In6.Cu")
		(net "P5E_CPU1_P2_RX_DN<10>")
	)
	(arc
		(start 122.09272 -288.320988)
		(mid 121.913907 -288.118638)
		(end 121.849388 -287.856422)
		(width 0.1143)
		(layer "In6.Cu")
		(net "P5E_CPU1_P2_RX_DN<10>")
	)
	(arc
		(start 122.162316 -290.590986)
		(mid 122.319293 -290.286186)
		(end 122.162316 -289.981386)
		(width 0.1143)
		(layer "In6.Cu")
		(net "P5E_CPU1_P2_RX_DN<10>")
	)
	(arc
		(start 122.319288 -287.046162)
		(mid 122.383803 -286.783943)
		(end 122.56262 -286.581596)
		(width 0.1143)
		(layer "In6.Cu")
		(net "P5E_CPU1_P2_RX_DN<10>")
	)
	(arc
		(start 121.849388 -287.856422)
		(mid 121.914624 -287.592831)
		(end 122.09526 -287.390078)
		(width 0.1143)
		(layer "In6.Cu")
		(net "P5E_CPU1_P2_RX_DN<10>")
	)
	(segment
		(start 146.89836 -385.31038)
		(end 147.41906 -385.31038)
		(width 0.127)
		(layer "F.Cu")
		(net "P5E_CPU1_P2_RX_DN<0>")
	)
	(segment
		(start 113.957862 -281.920442)
		(end 114.424714 -282.18638)
		(width 0.12954)
		(layer "F.Cu")
		(net "P5E_CPU1_P2_RX_DN<0>")
	)
	(segment
		(start 114.638582 -282.493212)
		(end 114.639852 -282.49245)
		(width 0.1143)
		(layer "In6.Cu")
		(net "P5E_CPU1_P2_RX_DN<0>")
	)
	(segment
		(start 113.087404 -284.622748)
		(end 113.151412 -284.623002)
		(width 0.1143)
		(layer "In6.Cu")
		(net "P5E_CPU1_P2_RX_DN<0>")
	)
	(segment
		(start 147.492212 -381.748538)
		(end 147.298918 -381.731266)
		(width 0.14224)
		(layer "In6.Cu")
		(net "P5E_CPU1_P2_RX_DN<0>")
	)
	(segment
		(start 114.642392 -282.490926)
		(end 114.643408 -282.490418)
		(width 0.1143)
		(layer "In6.Cu")
		(net "P5E_CPU1_P2_RX_DN<0>")
	)
	(segment
		(start 140.101828 -372.085362)
		(end 139.84605 -368.814858)
		(width 0.14224)
		(layer "In6.Cu")
		(net "P5E_CPU1_P2_RX_DN<0>")
	)
	(segment
		(start 126.941072 -319.506854)
		(end 125.359922 -317.140336)
		(width 0.14224)
		(layer "In6.Cu")
		(net "P5E_CPU1_P2_RX_DN<0>")
	)
	(segment
		(start 122.091704 -313.158378)
		(end 122.091958 -313.158378)
		(width 0.14224)
		(layer "In6.Cu")
		(net "P5E_CPU1_P2_RX_DN<0>")
	)
	(segment
		(start 147.772374 -385.405376)
		(end 147.772882 -385.404868)
		(width 0.14224)
		(layer "In6.Cu")
		(net "P5E_CPU1_P2_RX_DN<0>")
	)
	(segment
		(start 147.88642 -383.93116)
		(end 147.88642 -382.408176)
		(width 0.14224)
		(layer "In6.Cu")
		(net "P5E_CPU1_P2_RX_DN<0>")
	)
	(segment
		(start 113.671604 -284.129226)
		(end 113.671858 -284.128972)
		(width 0.1143)
		(layer "In6.Cu")
		(net "P5E_CPU1_P2_RX_DN<0>")
	)
	(segment
		(start 147.41906 -385.31038)
		(end 147.772374 -385.405376)
		(width 0.14224)
		(layer "In6.Cu")
		(net "P5E_CPU1_P2_RX_DN<0>")
	)
	(segment
		(start 147.76577 -382.075944)
		(end 147.492212 -381.748538)
		(width 0.14224)
		(layer "In6.Cu")
		(net "P5E_CPU1_P2_RX_DN<0>")
	)
	(segment
		(start 112.6744 -285.035752)
		(end 113.067338 -284.642814)
		(width 0.14224)
		(layer "In6.Cu")
		(net "P5E_CPU1_P2_RX_DN<0>")
	)
	(segment
		(start 147.894548 -385.334764)
		(end 147.894548 -385.163822)
		(width 0.14224)
		(layer "In6.Cu")
		(net "P5E_CPU1_P2_RX_DN<0>")
	)
	(segment
		(start 139.84605 -368.814858)
		(end 134.421372 -347.158564)
		(width 0.14224)
		(layer "In6.Cu")
		(net "P5E_CPU1_P2_RX_DN<0>")
	)
	(segment
		(start 147.042378 -381.210566)
		(end 146.76882 -380.88316)
		(width 0.14224)
		(layer "In6.Cu")
		(net "P5E_CPU1_P2_RX_DN<0>")
	)
	(segment
		(start 114.102642 -283.341826)
		(end 114.174524 -283.299662)
		(width 0.1143)
		(layer "In6.Cu")
		(net "P5E_CPU1_P2_RX_DN<0>")
	)
	(segment
		(start 114.657378 -302.945038)
		(end 113.469674 -300.07941)
		(width 0.14224)
		(layer "In6.Cu")
		(net "P5E_CPU1_P2_RX_DN<0>")
	)
	(segment
		(start 114.329464 -283.000704)
		(end 114.329464 -282.917138)
		(width 0.1143)
		(layer "In6.Cu")
		(net "P5E_CPU1_P2_RX_DN<0>")
	)
	(segment
		(start 114.572288 -282.531566)
		(end 114.612166 -282.50896)
		(width 0.1143)
		(layer "In6.Cu")
		(net "P5E_CPU1_P2_RX_DN<0>")
	)
	(segment
		(start 114.640868 -282.491942)
		(end 114.642392 -282.490926)
		(width 0.1143)
		(layer "In6.Cu")
		(net "P5E_CPU1_P2_RX_DN<0>")
	)
	(segment
		(start 147.577556 -384.84683)
		(end 147.582382 -384.234944)
		(width 0.14224)
		(layer "In6.Cu")
		(net "P5E_CPU1_P2_RX_DN<0>")
	)
	(segment
		(start 147.298918 -381.731266)
		(end 147.025106 -381.403606)
		(width 0.14224)
		(layer "In6.Cu")
		(net "P5E_CPU1_P2_RX_DN<0>")
	)
	(segment
		(start 147.025106 -381.403606)
		(end 147.042378 -381.210566)
		(width 0.14224)
		(layer "In6.Cu")
		(net "P5E_CPU1_P2_RX_DN<0>")
	)
	(segment
		(start 114.612166 -282.50896)
		(end 114.638582 -282.493212)
		(width 0.1143)
		(layer "In6.Cu")
		(net "P5E_CPU1_P2_RX_DN<0>")
	)
	(segment
		(start 147.894548 -385.163822)
		(end 147.577556 -384.84683)
		(width 0.14224)
		(layer "In6.Cu")
		(net "P5E_CPU1_P2_RX_DN<0>")
	)
	(segment
		(start 146.301714 -380.538228)
		(end 146.318986 -380.345188)
		(width 0.14224)
		(layer "In6.Cu")
		(net "P5E_CPU1_P2_RX_DN<0>")
	)
	(segment
		(start 146.76882 -380.88316)
		(end 146.575526 -380.865888)
		(width 0.14224)
		(layer "In6.Cu")
		(net "P5E_CPU1_P2_RX_DN<0>")
	)
	(segment
		(start 140.526262 -373.384572)
		(end 140.246354 -372.69674)
		(width 0.14224)
		(layer "In6.Cu")
		(net "P5E_CPU1_P2_RX_DN<0>")
	)
	(segment
		(start 113.151412 -284.623002)
		(end 113.556288 -284.218126)
		(width 0.1143)
		(layer "In6.Cu")
		(net "P5E_CPU1_P2_RX_DN<0>")
	)
	(segment
		(start 130.09626 -325.411084)
		(end 126.941072 -319.506854)
		(width 0.14224)
		(layer "In6.Cu")
		(net "P5E_CPU1_P2_RX_DN<0>")
	)
	(segment
		(start 147.772882 -385.404868)
		(end 147.894548 -385.334764)
		(width 0.14224)
		(layer "In6.Cu")
		(net "P5E_CPU1_P2_RX_DN<0>")
	)
	(segment
		(start 113.067338 -284.642814)
		(end 113.087404 -284.622748)
		(width 0.1143)
		(layer "In6.Cu")
		(net "P5E_CPU1_P2_RX_DN<0>")
	)
	(segment
		(start 125.359922 -317.140336)
		(end 122.091704 -313.158378)
		(width 0.14224)
		(layer "In6.Cu")
		(net "P5E_CPU1_P2_RX_DN<0>")
	)
	(segment
		(start 146.575526 -380.865888)
		(end 146.301714 -380.538228)
		(width 0.14224)
		(layer "In6.Cu")
		(net "P5E_CPU1_P2_RX_DN<0>")
	)
	(segment
		(start 114.639852 -282.49245)
		(end 114.640868 -282.491942)
		(width 0.1143)
		(layer "In6.Cu")
		(net "P5E_CPU1_P2_RX_DN<0>")
	)
	(segment
		(start 114.500152 -282.58389)
		(end 114.572288 -282.531566)
		(width 0.1143)
		(layer "In6.Cu")
		(net "P5E_CPU1_P2_RX_DN<0>")
	)
	(segment
		(start 118.806468 -309.15483)
		(end 114.657378 -302.945038)
		(width 0.14224)
		(layer "In6.Cu")
		(net "P5E_CPU1_P2_RX_DN<0>")
	)
	(segment
		(start 113.671858 -284.128972)
		(end 113.702338 -284.111192)
		(width 0.1143)
		(layer "In6.Cu")
		(net "P5E_CPU1_P2_RX_DN<0>")
	)
	(segment
		(start 112.6744 -296.081704)
		(end 112.6744 -285.035752)
		(width 0.14224)
		(layer "In6.Cu")
		(net "P5E_CPU1_P2_RX_DN<0>")
	)
	(segment
		(start 134.421372 -347.158564)
		(end 130.09626 -325.411084)
		(width 0.14224)
		(layer "In6.Cu")
		(net "P5E_CPU1_P2_RX_DN<0>")
	)
	(segment
		(start 147.582382 -384.234944)
		(end 147.88642 -383.93116)
		(width 0.14224)
		(layer "In6.Cu")
		(net "P5E_CPU1_P2_RX_DN<0>")
	)
	(segment
		(start 114.792506 -282.25623)
		(end 114.722656 -282.18638)
		(width 0.1143)
		(layer "In6.Cu")
		(net "P5E_CPU1_P2_RX_DN<0>")
	)
	(segment
		(start 146.318986 -380.345188)
		(end 140.59154 -373.492776)
		(width 0.14224)
		(layer "In6.Cu")
		(net "P5E_CPU1_P2_RX_DN<0>")
	)
	(segment
		(start 114.722656 -282.18638)
		(end 114.424714 -282.18638)
		(width 0.1143)
		(layer "In6.Cu")
		(net "P5E_CPU1_P2_RX_DN<0>")
	)
	(segment
		(start 113.469674 -300.07941)
		(end 112.6744 -296.081704)
		(width 0.14224)
		(layer "In6.Cu")
		(net "P5E_CPU1_P2_RX_DN<0>")
	)
	(segment
		(start 122.091958 -313.158378)
		(end 118.806468 -309.15483)
		(width 0.14224)
		(layer "In6.Cu")
		(net "P5E_CPU1_P2_RX_DN<0>")
	)
	(arc
		(start 114.174524 -283.299662)
		(mid 114.288407 -283.169048)
		(end 114.329464 -283.000704)
		(width 0.1143)
		(layer "In6.Cu")
		(net "P5E_CPU1_P2_RX_DN<0>")
	)
	(arc
		(start 113.85931 -283.806392)
		(mid 113.923825 -283.544173)
		(end 114.102642 -283.341826)
		(width 0.1143)
		(layer "In6.Cu")
		(net "P5E_CPU1_P2_RX_DN<0>")
	)
	(arc
		(start 113.702338 -284.111192)
		(mid 113.817765 -283.977816)
		(end 113.85931 -283.806392)
		(width 0.1143)
		(layer "In6.Cu")
		(net "P5E_CPU1_P2_RX_DN<0>")
	)
	(arc
		(start 114.702336 -282.43784)
		(mid 114.759955 -282.353256)
		(end 114.792506 -282.25623)
		(width 0.1143)
		(layer "In6.Cu")
		(net "P5E_CPU1_P2_RX_DN<0>")
	)
	(arc
		(start 140.246354 -372.69674)
		(mid 140.15049 -372.396631)
		(end 140.101828 -372.085362)
		(width 0.14224)
		(layer "In6.Cu")
		(net "P5E_CPU1_P2_RX_DN<0>")
	)
	(arc
		(start 114.643408 -282.490418)
		(mid 114.674255 -282.465679)
		(end 114.702336 -282.43784)
		(width 0.1143)
		(layer "In6.Cu")
		(net "P5E_CPU1_P2_RX_DN<0>")
	)
	(arc
		(start 114.329464 -282.917138)
		(mid 114.374614 -282.729923)
		(end 114.500152 -282.58389)
		(width 0.1143)
		(layer "In6.Cu")
		(net "P5E_CPU1_P2_RX_DN<0>")
	)
	(arc
		(start 113.556288 -284.218126)
		(mid 113.611061 -284.169934)
		(end 113.671604 -284.129226)
		(width 0.1143)
		(layer "In6.Cu")
		(net "P5E_CPU1_P2_RX_DN<0>")
	)
	(arc
		(start 147.88642 -382.408176)
		(mid 147.855344 -382.23143)
		(end 147.76577 -382.075944)
		(width 0.14224)
		(layer "In6.Cu")
		(net "P5E_CPU1_P2_RX_DN<0>")
	)
	(arc
		(start 140.59154 -373.492776)
		(mid 140.554697 -373.44121)
		(end 140.526262 -373.384572)
		(width 0.14224)
		(layer "In6.Cu")
		(net "P5E_CPU1_P2_RX_DN<0>")
	)
	(segment
		(start 91.129612 -370.00942)
		(end 91.129612 -369.30584)
		(width 0.12954)
		(layer "F.Cu")
		(net "P5E_CPU1_P1_TX_DP<9>")
	)
	(segment
		(start 104.08793 -287.590484)
		(end 103.621078 -287.856422)
		(width 0.12954)
		(layer "F.Cu")
		(net "P5E_CPU1_P1_TX_DP<9>")
	)
	(segment
		(start 91.129612 -369.30584)
		(end 90.859102 -369.03533)
		(width 0.12954)
		(layer "F.Cu")
		(net "P5E_CPU1_P1_TX_DP<9>")
	)
	(segment
		(start 90.833702 -370.30533)
		(end 91.129612 -370.00942)
		(width 0.12954)
		(layer "F.Cu")
		(net "P5E_CPU1_P1_TX_DP<9>")
	)
	(segment
		(start 104.241092 -288.322512)
		(end 104.278176 -288.343848)
		(width 0.1143)
		(layer "In4.Cu")
		(net "P5E_CPU1_P1_TX_DP<9>")
	)
	(segment
		(start 124.084334 -348.504256)
		(end 124.084334 -348.50451)
		(width 0.14224)
		(layer "In4.Cu")
		(net "P5E_CPU1_P1_TX_DP<9>")
	)
	(segment
		(start 105.68813 -294.658796)
		(end 105.649014 -294.681656)
		(width 0.1143)
		(layer "In4.Cu")
		(net "P5E_CPU1_P1_TX_DP<9>")
	)
	(segment
		(start 104.23906 -288.320988)
		(end 104.241092 -288.322512)
		(width 0.1143)
		(layer "In4.Cu")
		(net "P5E_CPU1_P1_TX_DP<9>")
	)
	(segment
		(start 119.548656 -320.862706)
		(end 120.485154 -322.655438)
		(width 0.14224)
		(layer "In4.Cu")
		(net "P5E_CPU1_P1_TX_DP<9>")
	)
	(segment
		(start 105.220516 -291.585142)
		(end 105.221532 -291.58565)
		(width 0.1143)
		(layer "In4.Cu")
		(net "P5E_CPU1_P1_TX_DP<9>")
	)
	(segment
		(start 124.084334 -348.50451)
		(end 108.972096 -358.601772)
		(width 0.14224)
		(layer "In4.Cu")
		(net "P5E_CPU1_P1_TX_DP<9>")
	)
	(segment
		(start 105.01757 -295.919906)
		(end 105.01757 -296.03319)
		(width 0.1143)
		(layer "In4.Cu")
		(net "P5E_CPU1_P1_TX_DP<9>")
	)
	(segment
		(start 105.649014 -293.990776)
		(end 105.68813 -294.013636)
		(width 0.1143)
		(layer "In4.Cu")
		(net "P5E_CPU1_P1_TX_DP<9>")
	)
	(segment
		(start 91.867228 -367.18621)
		(end 91.300554 -367.752884)
		(width 0.14224)
		(layer "In4.Cu")
		(net "P5E_CPU1_P1_TX_DP<9>")
	)
	(segment
		(start 105.68813 -294.013636)
		(end 105.71861 -294.031416)
		(width 0.1143)
		(layer "In4.Cu")
		(net "P5E_CPU1_P1_TX_DP<9>")
	)
	(segment
		(start 105.222294 -291.586158)
		(end 105.22331 -291.586666)
		(width 0.1143)
		(layer "In4.Cu")
		(net "P5E_CPU1_P1_TX_DP<9>")
	)
	(segment
		(start 105.226612 -291.588444)
		(end 105.249726 -291.601906)
		(width 0.1143)
		(layer "In4.Cu")
		(net "P5E_CPU1_P1_TX_DP<9>")
	)
	(segment
		(start 104.278176 -288.343848)
		(end 104.310688 -288.362644)
		(width 0.1143)
		(layer "In4.Cu")
		(net "P5E_CPU1_P1_TX_DP<9>")
	)
	(segment
		(start 124.985018 -346.42425)
		(end 124.163582 -348.407736)
		(width 0.14224)
		(layer "In4.Cu")
		(net "P5E_CPU1_P1_TX_DP<9>")
	)
	(segment
		(start 105.32364 -295.482264)
		(end 105.110788 -295.695116)
		(width 0.1143)
		(layer "In4.Cu")
		(net "P5E_CPU1_P1_TX_DP<9>")
	)
	(segment
		(start 105.217976 -290.608766)
		(end 105.217722 -290.60902)
		(width 0.1143)
		(layer "In4.Cu")
		(net "P5E_CPU1_P1_TX_DP<9>")
	)
	(segment
		(start 105.239058 -290.596574)
		(end 105.217976 -290.608766)
		(width 0.1143)
		(layer "In4.Cu")
		(net "P5E_CPU1_P1_TX_DP<9>")
	)
	(segment
		(start 105.71861 -294.641016)
		(end 105.68813 -294.658796)
		(width 0.1143)
		(layer "In4.Cu")
		(net "P5E_CPU1_P1_TX_DP<9>")
	)
	(segment
		(start 105.221532 -291.58565)
		(end 105.222294 -291.586158)
		(width 0.1143)
		(layer "In4.Cu")
		(net "P5E_CPU1_P1_TX_DP<9>")
	)
	(segment
		(start 108.972096 -358.601772)
		(end 97.771458 -363.241082)
		(width 0.14224)
		(layer "In4.Cu")
		(net "P5E_CPU1_P1_TX_DP<9>")
	)
	(segment
		(start 104.97185 -296.07891)
		(end 104.97185 -296.107358)
		(width 0.1143)
		(layer "In4.Cu")
		(net "P5E_CPU1_P1_TX_DP<9>")
	)
	(segment
		(start 105.23982 -290.596066)
		(end 105.239058 -290.596574)
		(width 0.1143)
		(layer "In4.Cu")
		(net "P5E_CPU1_P1_TX_DP<9>")
	)
	(segment
		(start 105.218738 -291.584126)
		(end 105.219754 -291.584634)
		(width 0.1143)
		(layer "In4.Cu")
		(net "P5E_CPU1_P1_TX_DP<9>")
	)
	(segment
		(start 105.68813 -292.393624)
		(end 105.71861 -292.411404)
		(width 0.1143)
		(layer "In4.Cu")
		(net "P5E_CPU1_P1_TX_DP<9>")
	)
	(segment
		(start 104.70896 -289.13074)
		(end 104.715818 -289.134804)
		(width 0.1143)
		(layer "In4.Cu")
		(net "P5E_CPU1_P1_TX_DP<9>")
	)
	(segment
		(start 105.405682 -295.146222)
		(end 105.405682 -295.284398)
		(width 0.1143)
		(layer "In4.Cu")
		(net "P5E_CPU1_P1_TX_DP<9>")
	)
	(segment
		(start 105.205784 -289.95624)
		(end 105.249726 -289.982148)
		(width 0.1143)
		(layer "In4.Cu")
		(net "P5E_CPU1_P1_TX_DP<9>")
	)
	(segment
		(start 105.002838 -298.445682)
		(end 108.163106 -306.07508)
		(width 0.14224)
		(layer "In4.Cu")
		(net "P5E_CPU1_P1_TX_DP<9>")
	)
	(segment
		(start 105.219754 -291.584634)
		(end 105.220516 -291.585142)
		(width 0.1143)
		(layer "In4.Cu")
		(net "P5E_CPU1_P1_TX_DP<9>")
	)
	(segment
		(start 105.217722 -291.583618)
		(end 105.217976 -291.583618)
		(width 0.1143)
		(layer "In4.Cu")
		(net "P5E_CPU1_P1_TX_DP<9>")
	)
	(segment
		(start 108.163106 -306.07508)
		(end 111.454184 -311.00014)
		(width 0.14224)
		(layer "In4.Cu")
		(net "P5E_CPU1_P1_TX_DP<9>")
	)
	(segment
		(start 122.372628 -328.17054)
		(end 122.372882 -328.17054)
		(width 0.14224)
		(layer "In4.Cu")
		(net "P5E_CPU1_P1_TX_DP<9>")
	)
	(segment
		(start 105.71861 -293.021004)
		(end 105.68813 -293.038784)
		(width 0.1143)
		(layer "In4.Cu")
		(net "P5E_CPU1_P1_TX_DP<9>")
	)
	(segment
		(start 105.68813 -293.038784)
		(end 105.649014 -293.061644)
		(width 0.1143)
		(layer "In4.Cu")
		(net "P5E_CPU1_P1_TX_DP<9>")
	)
	(segment
		(start 104.97185 -296.107358)
		(end 104.97185 -298.289218)
		(width 0.14224)
		(layer "In4.Cu")
		(net "P5E_CPU1_P1_TX_DP<9>")
	)
	(segment
		(start 105.22331 -291.586666)
		(end 105.224072 -291.587174)
		(width 0.1143)
		(layer "In4.Cu")
		(net "P5E_CPU1_P1_TX_DP<9>")
	)
	(segment
		(start 120.485154 -322.655438)
		(end 122.372628 -328.17054)
		(width 0.14224)
		(layer "In4.Cu")
		(net "P5E_CPU1_P1_TX_DP<9>")
	)
	(segment
		(start 104.71658 -289.135312)
		(end 104.748076 -289.1536)
		(width 0.1143)
		(layer "In4.Cu")
		(net "P5E_CPU1_P1_TX_DP<9>")
	)
	(segment
		(start 91.149932 -368.7445)
		(end 90.859102 -369.03533)
		(width 0.14224)
		(layer "In4.Cu")
		(net "P5E_CPU1_P1_TX_DP<9>")
	)
	(segment
		(start 105.01757 -296.03319)
		(end 104.97185 -296.07891)
		(width 0.1143)
		(layer "In4.Cu")
		(net "P5E_CPU1_P1_TX_DP<9>")
	)
	(segment
		(start 103.621078 -287.856422)
		(end 103.91902 -287.856422)
		(width 0.1143)
		(layer "In4.Cu")
		(net "P5E_CPU1_P1_TX_DP<9>")
	)
	(segment
		(start 105.217976 -291.583618)
		(end 105.218738 -291.584126)
		(width 0.1143)
		(layer "In4.Cu")
		(net "P5E_CPU1_P1_TX_DP<9>")
	)
	(segment
		(start 104.923082 -289.432492)
		(end 104.923082 -289.466528)
		(width 0.1143)
		(layer "In4.Cu")
		(net "P5E_CPU1_P1_TX_DP<9>")
	)
	(segment
		(start 122.372882 -328.17054)
		(end 124.239528 -333.625444)
		(width 0.14224)
		(layer "In4.Cu")
		(net "P5E_CPU1_P1_TX_DP<9>")
	)
	(segment
		(start 111.454184 -311.00014)
		(end 119.548656 -320.862706)
		(width 0.14224)
		(layer "In4.Cu")
		(net "P5E_CPU1_P1_TX_DP<9>")
	)
	(segment
		(start 104.715818 -289.134804)
		(end 104.71658 -289.135312)
		(width 0.1143)
		(layer "In4.Cu")
		(net "P5E_CPU1_P1_TX_DP<9>")
	)
	(segment
		(start 105.224072 -291.587174)
		(end 105.226612 -291.588444)
		(width 0.1143)
		(layer "In4.Cu")
		(net "P5E_CPU1_P1_TX_DP<9>")
	)
	(segment
		(start 125.009656 -337.920584)
		(end 125.009656 -346.30106)
		(width 0.14224)
		(layer "In4.Cu")
		(net "P5E_CPU1_P1_TX_DP<9>")
	)
	(segment
		(start 91.149932 -368.116612)
		(end 91.149932 -368.7445)
		(width 0.14224)
		(layer "In4.Cu")
		(net "P5E_CPU1_P1_TX_DP<9>")
	)
	(segment
		(start 105.649014 -292.370764)
		(end 105.68813 -292.393624)
		(width 0.1143)
		(layer "In4.Cu")
		(net "P5E_CPU1_P1_TX_DP<9>")
	)
	(segment
		(start 124.271278 -333.747872)
		(end 124.99848 -337.7946)
		(width 0.14224)
		(layer "In4.Cu")
		(net "P5E_CPU1_P1_TX_DP<9>")
	)
	(segment
		(start 104.748076 -289.1536)
		(end 104.748076 -289.153346)
		(width 0.1143)
		(layer "In4.Cu")
		(net "P5E_CPU1_P1_TX_DP<9>")
	)
	(segment
		(start 104.748076 -289.153346)
		(end 104.751632 -289.155124)
		(width 0.1143)
		(layer "In4.Cu")
		(net "P5E_CPU1_P1_TX_DP<9>")
	)
	(segment
		(start 105.249726 -290.590478)
		(end 105.23982 -290.596066)
		(width 0.1143)
		(layer "In4.Cu")
		(net "P5E_CPU1_P1_TX_DP<9>")
	)
	(segment
		(start 103.91902 -287.856422)
		(end 104.001824 -287.939226)
		(width 0.1143)
		(layer "In4.Cu")
		(net "P5E_CPU1_P1_TX_DP<9>")
	)
	(arc
		(start 125.009656 -346.30106)
		(mid 125.003378 -346.363861)
		(end 124.985018 -346.42425)
		(width 0.14224)
		(layer "In4.Cu")
		(net "P5E_CPU1_P1_TX_DP<9>")
	)
	(arc
		(start 105.649014 -293.061644)
		(mid 105.405687 -293.52621)
		(end 105.649014 -293.990776)
		(width 0.1143)
		(layer "In4.Cu")
		(net "P5E_CPU1_P1_TX_DP<9>")
	)
	(arc
		(start 105.385362 -290.16452)
		(mid 105.387983 -290.399929)
		(end 105.249726 -290.590478)
		(width 0.1143)
		(layer "In4.Cu")
		(net "P5E_CPU1_P1_TX_DP<9>")
	)
	(arc
		(start 105.249726 -291.601906)
		(mid 105.364402 -291.73524)
		(end 105.405682 -291.906198)
		(width 0.1143)
		(layer "In4.Cu")
		(net "P5E_CPU1_P1_TX_DP<9>")
	)
	(arc
		(start 104.465628 -288.666174)
		(mid 104.530143 -288.928393)
		(end 104.70896 -289.13074)
		(width 0.1143)
		(layer "In4.Cu")
		(net "P5E_CPU1_P1_TX_DP<9>")
	)
	(arc
		(start 124.239528 -333.625444)
		(mid 124.257726 -333.686055)
		(end 124.271278 -333.747872)
		(width 0.14224)
		(layer "In4.Cu")
		(net "P5E_CPU1_P1_TX_DP<9>")
	)
	(arc
		(start 104.001824 -287.939226)
		(mid 104.003612 -287.950675)
		(end 104.005634 -287.962086)
		(width 0.1143)
		(layer "In4.Cu")
		(net "P5E_CPU1_P1_TX_DP<9>")
	)
	(arc
		(start 104.751632 -289.155124)
		(mid 104.876741 -289.269459)
		(end 104.923082 -289.432492)
		(width 0.1143)
		(layer "In4.Cu")
		(net "P5E_CPU1_P1_TX_DP<9>")
	)
	(arc
		(start 97.771458 -363.241082)
		(mid 94.625074 -364.922901)
		(end 91.867228 -367.18621)
		(width 0.14224)
		(layer "In4.Cu")
		(net "P5E_CPU1_P1_TX_DP<9>")
	)
	(arc
		(start 105.649014 -294.681656)
		(mid 105.470124 -294.88398)
		(end 105.405682 -295.146222)
		(width 0.1143)
		(layer "In4.Cu")
		(net "P5E_CPU1_P1_TX_DP<9>")
	)
	(arc
		(start 124.99848 -337.7946)
		(mid 125.006875 -337.857343)
		(end 125.009656 -337.920584)
		(width 0.14224)
		(layer "In4.Cu")
		(net "P5E_CPU1_P1_TX_DP<9>")
	)
	(arc
		(start 104.005634 -287.962086)
		(mid 104.087067 -288.164484)
		(end 104.23906 -288.320988)
		(width 0.1143)
		(layer "In4.Cu")
		(net "P5E_CPU1_P1_TX_DP<9>")
	)
	(arc
		(start 91.300554 -367.752884)
		(mid 91.189102 -367.919778)
		(end 91.149932 -368.116612)
		(width 0.14224)
		(layer "In4.Cu")
		(net "P5E_CPU1_P1_TX_DP<9>")
	)
	(arc
		(start 105.405682 -291.906198)
		(mid 105.470197 -292.168417)
		(end 105.649014 -292.370764)
		(width 0.1143)
		(layer "In4.Cu")
		(net "P5E_CPU1_P1_TX_DP<9>")
	)
	(arc
		(start 124.163582 -348.407736)
		(mid 124.13112 -348.461876)
		(end 124.084334 -348.504256)
		(width 0.14224)
		(layer "In4.Cu")
		(net "P5E_CPU1_P1_TX_DP<9>")
	)
	(arc
		(start 105.71861 -292.411404)
		(mid 105.875587 -292.716204)
		(end 105.71861 -293.021004)
		(width 0.1143)
		(layer "In4.Cu")
		(net "P5E_CPU1_P1_TX_DP<9>")
	)
	(arc
		(start 105.71861 -294.031416)
		(mid 105.875587 -294.336216)
		(end 105.71861 -294.641016)
		(width 0.1143)
		(layer "In4.Cu")
		(net "P5E_CPU1_P1_TX_DP<9>")
	)
	(arc
		(start 104.97185 -298.289218)
		(mid 104.979643 -298.368976)
		(end 105.002838 -298.445682)
		(width 0.14224)
		(layer "In4.Cu")
		(net "P5E_CPU1_P1_TX_DP<9>")
	)
	(arc
		(start 104.923082 -289.466528)
		(mid 104.998839 -289.749243)
		(end 105.205784 -289.95624)
		(width 0.1143)
		(layer "In4.Cu")
		(net "P5E_CPU1_P1_TX_DP<9>")
	)
	(arc
		(start 104.310688 -288.362644)
		(mid 104.424617 -288.495791)
		(end 104.465628 -288.666174)
		(width 0.1143)
		(layer "In4.Cu")
		(net "P5E_CPU1_P1_TX_DP<9>")
	)
	(arc
		(start 105.249726 -289.982148)
		(mid 105.331707 -290.062798)
		(end 105.385362 -290.16452)
		(width 0.1143)
		(layer "In4.Cu")
		(net "P5E_CPU1_P1_TX_DP<9>")
	)
	(arc
		(start 105.110788 -295.695116)
		(mid 105.041822 -295.798236)
		(end 105.01757 -295.919906)
		(width 0.1143)
		(layer "In4.Cu")
		(net "P5E_CPU1_P1_TX_DP<9>")
	)
	(arc
		(start 105.217722 -290.60902)
		(mid 104.937075 -291.096382)
		(end 105.217722 -291.583618)
		(width 0.1143)
		(layer "In4.Cu")
		(net "P5E_CPU1_P1_TX_DP<9>")
	)
	(arc
		(start 105.405682 -295.284398)
		(mid 105.38436 -295.3915)
		(end 105.32364 -295.482264)
		(width 0.1143)
		(layer "In4.Cu")
		(net "P5E_CPU1_P1_TX_DP<9>")
	)
	(segment
		(start 104.08793 -290.830254)
		(end 103.621078 -291.096192)
		(width 0.12954)
		(layer "F.Cu")
		(net "P5E_CPU1_P1_TX_DP<8>")
	)
	(segment
		(start 89.427812 -371.76964)
		(end 89.157302 -371.49913)
		(width 0.12954)
		(layer "F.Cu")
		(net "P5E_CPU1_P1_TX_DP<8>")
	)
	(segment
		(start 89.131902 -372.76913)
		(end 89.427812 -372.47322)
		(width 0.12954)
		(layer "F.Cu")
		(net "P5E_CPU1_P1_TX_DP<8>")
	)
	(segment
		(start 89.427812 -372.47322)
		(end 89.427812 -371.76964)
		(width 0.12954)
		(layer "F.Cu")
		(net "P5E_CPU1_P1_TX_DP<8>")
	)
	(segment
		(start 103.91902 -291.096192)
		(end 104.001824 -291.178996)
		(width 0.1143)
		(layer "In4.Cu")
		(net "P5E_CPU1_P1_TX_DP<8>")
	)
	(segment
		(start 104.070404 -298.631102)
		(end 107.338876 -306.521866)
		(width 0.14224)
		(layer "In4.Cu")
		(net "P5E_CPU1_P1_TX_DP<8>")
	)
	(segment
		(start 124.059188 -337.97494)
		(end 124.059188 -344.811604)
		(width 0.14224)
		(layer "In4.Cu")
		(net "P5E_CPU1_P1_TX_DP<8>")
	)
	(segment
		(start 104.245918 -291.564822)
		(end 104.24668 -291.56533)
		(width 0.1143)
		(layer "In4.Cu")
		(net "P5E_CPU1_P1_TX_DP<8>")
	)
	(segment
		(start 104.748076 -293.038784)
		(end 104.727502 -293.050722)
		(width 0.1143)
		(layer "In4.Cu")
		(net "P5E_CPU1_P1_TX_DP<8>")
	)
	(segment
		(start 89.448132 -371.2083)
		(end 89.157302 -371.49913)
		(width 0.14224)
		(layer "In4.Cu")
		(net "P5E_CPU1_P1_TX_DP<8>")
	)
	(segment
		(start 118.766082 -321.381882)
		(end 119.544084 -322.870322)
		(width 0.14224)
		(layer "In4.Cu")
		(net "P5E_CPU1_P1_TX_DP<8>")
	)
	(segment
		(start 104.779826 -293.020496)
		(end 104.748076 -293.038784)
		(width 0.1143)
		(layer "In4.Cu")
		(net "P5E_CPU1_P1_TX_DP<8>")
	)
	(segment
		(start 104.24668 -291.56533)
		(end 104.278176 -291.583618)
		(width 0.1143)
		(layer "In4.Cu")
		(net "P5E_CPU1_P1_TX_DP<8>")
	)
	(segment
		(start 110.70336 -311.557162)
		(end 118.766082 -321.381882)
		(width 0.14224)
		(layer "In4.Cu")
		(net "P5E_CPU1_P1_TX_DP<8>")
	)
	(segment
		(start 107.338876 -306.521866)
		(end 110.70336 -311.557162)
		(width 0.14224)
		(layer "In4.Cu")
		(net "P5E_CPU1_P1_TX_DP<8>")
	)
	(segment
		(start 104.748076 -292.393624)
		(end 104.779826 -292.411912)
		(width 0.1143)
		(layer "In4.Cu")
		(net "P5E_CPU1_P1_TX_DP<8>")
	)
	(segment
		(start 123.37034 -334.078326)
		(end 124.048012 -337.848956)
		(width 0.14224)
		(layer "In4.Cu")
		(net "P5E_CPU1_P1_TX_DP<8>")
	)
	(segment
		(start 104.428544 -295.43756)
		(end 104.165654 -295.699688)
		(width 0.1143)
		(layer "In4.Cu")
		(net "P5E_CPU1_P1_TX_DP<8>")
	)
	(segment
		(start 119.544084 -322.870322)
		(end 123.33859 -333.955898)
		(width 0.14224)
		(layer "In4.Cu")
		(net "P5E_CPU1_P1_TX_DP<8>")
	)
	(segment
		(start 103.621078 -291.096192)
		(end 103.91902 -291.096192)
		(width 0.1143)
		(layer "In4.Cu")
		(net "P5E_CPU1_P1_TX_DP<8>")
	)
	(segment
		(start 104.072436 -296.03319)
		(end 104.026716 -296.07891)
		(width 0.1143)
		(layer "In4.Cu")
		(net "P5E_CPU1_P1_TX_DP<8>")
	)
	(segment
		(start 104.072436 -295.924732)
		(end 104.072436 -296.03319)
		(width 0.1143)
		(layer "In4.Cu")
		(net "P5E_CPU1_P1_TX_DP<8>")
	)
	(segment
		(start 104.026716 -296.07891)
		(end 104.026716 -296.107358)
		(width 0.1143)
		(layer "In4.Cu")
		(net "P5E_CPU1_P1_TX_DP<8>")
	)
	(segment
		(start 89.448132 -368.4524)
		(end 89.448132 -371.2083)
		(width 0.14224)
		(layer "In4.Cu")
		(net "P5E_CPU1_P1_TX_DP<8>")
	)
	(segment
		(start 121.982484 -348.697296)
		(end 108.180124 -357.92029)
		(width 0.14224)
		(layer "In4.Cu")
		(net "P5E_CPU1_P1_TX_DP<8>")
	)
	(segment
		(start 104.026716 -296.107358)
		(end 104.026716 -298.410884)
		(width 0.14224)
		(layer "In4.Cu")
		(net "P5E_CPU1_P1_TX_DP<8>")
	)
	(segment
		(start 108.180124 -357.92029)
		(end 95.192088 -363.30001)
		(width 0.14224)
		(layer "In4.Cu")
		(net "P5E_CPU1_P1_TX_DP<8>")
	)
	(segment
		(start 104.727502 -293.050722)
		(end 104.72674 -293.05123)
		(width 0.1143)
		(layer "In4.Cu")
		(net "P5E_CPU1_P1_TX_DP<8>")
	)
	(segment
		(start 104.465882 -295.146222)
		(end 104.465882 -295.347644)
		(width 0.1143)
		(layer "In4.Cu")
		(net "P5E_CPU1_P1_TX_DP<8>")
	)
	(segment
		(start 91.464638 -365.790734)
		(end 89.904316 -367.351056)
		(width 0.14224)
		(layer "In4.Cu")
		(net "P5E_CPU1_P1_TX_DP<8>")
	)
	(segment
		(start 104.711754 -292.372542)
		(end 104.748076 -292.393624)
		(width 0.1143)
		(layer "In4.Cu")
		(net "P5E_CPU1_P1_TX_DP<8>")
	)
	(segment
		(start 104.72674 -294.00119)
		(end 104.777032 -294.0304)
		(width 0.1143)
		(layer "In4.Cu")
		(net "P5E_CPU1_P1_TX_DP<8>")
	)
	(segment
		(start 104.23906 -291.560758)
		(end 104.245918 -291.564822)
		(width 0.1143)
		(layer "In4.Cu")
		(net "P5E_CPU1_P1_TX_DP<8>")
	)
	(segment
		(start 104.278176 -291.583618)
		(end 104.300782 -291.59708)
		(width 0.1143)
		(layer "In4.Cu")
		(net "P5E_CPU1_P1_TX_DP<8>")
	)
	(segment
		(start 104.781604 -294.638984)
		(end 104.709214 -294.681402)
		(width 0.1143)
		(layer "In4.Cu")
		(net "P5E_CPU1_P1_TX_DP<8>")
	)
	(arc
		(start 104.001824 -291.178996)
		(mid 104.003612 -291.190445)
		(end 104.005634 -291.201856)
		(width 0.1143)
		(layer "In4.Cu")
		(net "P5E_CPU1_P1_TX_DP<8>")
	)
	(arc
		(start 104.165654 -295.699688)
		(mid 104.096664 -295.802939)
		(end 104.072436 -295.924732)
		(width 0.1143)
		(layer "In4.Cu")
		(net "P5E_CPU1_P1_TX_DP<8>")
	)
	(arc
		(start 104.005634 -291.201856)
		(mid 104.087067 -291.404254)
		(end 104.23906 -291.560758)
		(width 0.1143)
		(layer "In4.Cu")
		(net "P5E_CPU1_P1_TX_DP<8>")
	)
	(arc
		(start 104.300782 -291.59708)
		(mid 104.409242 -291.732431)
		(end 104.46385 -291.897054)
		(width 0.1143)
		(layer "In4.Cu")
		(net "P5E_CPU1_P1_TX_DP<8>")
	)
	(arc
		(start 104.465882 -291.921184)
		(mid 104.531502 -292.170702)
		(end 104.701086 -292.365176)
		(width 0.1143)
		(layer "In4.Cu")
		(net "P5E_CPU1_P1_TX_DP<8>")
	)
	(arc
		(start 104.777032 -294.0304)
		(mid 104.936877 -294.33347)
		(end 104.781604 -294.638984)
		(width 0.1143)
		(layer "In4.Cu")
		(net "P5E_CPU1_P1_TX_DP<8>")
	)
	(arc
		(start 104.72674 -293.05123)
		(mid 104.453189 -293.52621)
		(end 104.72674 -294.00119)
		(width 0.1143)
		(layer "In4.Cu")
		(net "P5E_CPU1_P1_TX_DP<8>")
	)
	(arc
		(start 124.048012 -337.848956)
		(mid 124.05641 -337.911699)
		(end 124.059188 -337.97494)
		(width 0.14224)
		(layer "In4.Cu")
		(net "P5E_CPU1_P1_TX_DP<8>")
	)
	(arc
		(start 89.904316 -367.351056)
		(mid 89.566685 -367.856357)
		(end 89.448132 -368.4524)
		(width 0.14224)
		(layer "In4.Cu")
		(net "P5E_CPU1_P1_TX_DP<8>")
	)
	(arc
		(start 104.46385 -291.897054)
		(mid 104.465159 -291.909094)
		(end 104.465882 -291.921184)
		(width 0.1143)
		(layer "In4.Cu")
		(net "P5E_CPU1_P1_TX_DP<8>")
	)
	(arc
		(start 104.465882 -295.347644)
		(mid 104.45618 -295.396328)
		(end 104.428544 -295.43756)
		(width 0.1143)
		(layer "In4.Cu")
		(net "P5E_CPU1_P1_TX_DP<8>")
	)
	(arc
		(start 95.192088 -363.30001)
		(mid 93.205707 -364.361812)
		(end 91.464638 -365.790734)
		(width 0.14224)
		(layer "In4.Cu")
		(net "P5E_CPU1_P1_TX_DP<8>")
	)
	(arc
		(start 104.701086 -292.365176)
		(mid 104.7064 -292.368888)
		(end 104.711754 -292.372542)
		(width 0.1143)
		(layer "In4.Cu")
		(net "P5E_CPU1_P1_TX_DP<8>")
	)
	(arc
		(start 104.709214 -294.681402)
		(mid 104.530405 -294.883896)
		(end 104.465882 -295.146222)
		(width 0.1143)
		(layer "In4.Cu")
		(net "P5E_CPU1_P1_TX_DP<8>")
	)
	(arc
		(start 124.059188 -344.811604)
		(mid 123.507518 -347.014572)
		(end 121.982484 -348.697296)
		(width 0.14224)
		(layer "In4.Cu")
		(net "P5E_CPU1_P1_TX_DP<8>")
	)
	(arc
		(start 104.779826 -292.411912)
		(mid 104.935754 -292.716204)
		(end 104.779826 -293.020496)
		(width 0.1143)
		(layer "In4.Cu")
		(net "P5E_CPU1_P1_TX_DP<8>")
	)
	(arc
		(start 123.33859 -333.955898)
		(mid 123.356799 -334.016507)
		(end 123.37034 -334.078326)
		(width 0.14224)
		(layer "In4.Cu")
		(net "P5E_CPU1_P1_TX_DP<8>")
	)
	(arc
		(start 104.026716 -298.410884)
		(mid 104.037728 -298.52314)
		(end 104.070404 -298.631102)
		(width 0.14224)
		(layer "In4.Cu")
		(net "P5E_CPU1_P1_TX_DP<8>")
	)
	(segment
		(start 87.726012 -374.93702)
		(end 87.726012 -374.23344)
		(width 0.12954)
		(layer "F.Cu")
		(net "P5E_CPU1_P1_TX_DP<7>")
	)
	(segment
		(start 104.08793 -289.210242)
		(end 103.621078 -289.47618)
		(width 0.12954)
		(layer "F.Cu")
		(net "P5E_CPU1_P1_TX_DP<7>")
	)
	(segment
		(start 87.430102 -375.23293)
		(end 87.726012 -374.93702)
		(width 0.12954)
		(layer "F.Cu")
		(net "P5E_CPU1_P1_TX_DP<7>")
	)
	(segment
		(start 87.726012 -374.23344)
		(end 87.455502 -373.96293)
		(width 0.12954)
		(layer "F.Cu")
		(net "P5E_CPU1_P1_TX_DP<7>")
	)
	(segment
		(start 103.840026 -289.780218)
		(end 103.810308 -289.79749)
		(width 0.1143)
		(layer "In4.Cu")
		(net "P5E_CPU1_P1_TX_DP<7>")
	)
	(segment
		(start 103.338122 -291.583618)
		(end 103.338884 -291.584126)
		(width 0.1143)
		(layer "In4.Cu")
		(net "P5E_CPU1_P1_TX_DP<7>")
	)
	(segment
		(start 103.340154 -290.60775)
		(end 103.33863 -290.608512)
		(width 0.1143)
		(layer "In4.Cu")
		(net "P5E_CPU1_P1_TX_DP<7>")
	)
	(segment
		(start 103.621078 -289.47618)
		(end 103.91902 -289.47618)
		(width 0.1143)
		(layer "In4.Cu")
		(net "P5E_CPU1_P1_TX_DP<7>")
	)
	(segment
		(start 103.525828 -295.146222)
		(end 103.525828 -295.262046)
		(width 0.1143)
		(layer "In4.Cu")
		(net "P5E_CPU1_P1_TX_DP<7>")
	)
	(segment
		(start 103.020114 -296.107358)
		(end 103.020114 -298.450254)
		(width 0.14224)
		(layer "In4.Cu")
		(net "P5E_CPU1_P1_TX_DP<7>")
	)
	(segment
		(start 103.428038 -295.498012)
		(end 103.159052 -295.766998)
		(width 0.1143)
		(layer "In4.Cu")
		(net "P5E_CPU1_P1_TX_DP<7>")
	)
	(segment
		(start 103.838756 -293.021004)
		(end 103.808276 -293.038784)
		(width 0.1143)
		(layer "In4.Cu")
		(net "P5E_CPU1_P1_TX_DP<7>")
	)
	(segment
		(start 103.337868 -290.60902)
		(end 103.299768 -290.631118)
		(width 0.1143)
		(layer "In4.Cu")
		(net "P5E_CPU1_P1_TX_DP<7>")
	)
	(segment
		(start 87.746332 -373.6721)
		(end 87.455502 -373.96293)
		(width 0.14224)
		(layer "In4.Cu")
		(net "P5E_CPU1_P1_TX_DP<7>")
	)
	(segment
		(start 103.020114 -296.07891)
		(end 103.020114 -296.107358)
		(width 0.1143)
		(layer "In4.Cu")
		(net "P5E_CPU1_P1_TX_DP<7>")
	)
	(segment
		(start 87.746332 -369.35791)
		(end 87.746332 -373.6721)
		(width 0.14224)
		(layer "In4.Cu")
		(net "P5E_CPU1_P1_TX_DP<7>")
	)
	(segment
		(start 122.338084 -334.02651)
		(end 123.10745 -338.306664)
		(width 0.14224)
		(layer "In4.Cu")
		(net "P5E_CPU1_P1_TX_DP<7>")
	)
	(segment
		(start 103.065834 -296.03319)
		(end 103.020114 -296.07891)
		(width 0.1143)
		(layer "In4.Cu")
		(net "P5E_CPU1_P1_TX_DP<7>")
	)
	(segment
		(start 107.653074 -357.129334)
		(end 93.743526 -362.890816)
		(width 0.14224)
		(layer "In4.Cu")
		(net "P5E_CPU1_P1_TX_DP<7>")
	)
	(segment
		(start 121.223278 -348.061788)
		(end 107.653074 -357.129334)
		(width 0.14224)
		(layer "In4.Cu")
		(net "P5E_CPU1_P1_TX_DP<7>")
	)
	(segment
		(start 103.76916 -293.990776)
		(end 103.808276 -294.013636)
		(width 0.1143)
		(layer "In4.Cu")
		(net "P5E_CPU1_P1_TX_DP<7>")
	)
	(segment
		(start 91.34475 -364.17631)
		(end 88.86571 -366.65535)
		(width 0.14224)
		(layer "In4.Cu")
		(net "P5E_CPU1_P1_TX_DP<7>")
	)
	(segment
		(start 109.964474 -312.133742)
		(end 117.987572 -321.90944)
		(width 0.14224)
		(layer "In4.Cu")
		(net "P5E_CPU1_P1_TX_DP<7>")
	)
	(segment
		(start 118.606316 -323.093588)
		(end 122.306334 -333.904082)
		(width 0.14224)
		(layer "In4.Cu")
		(net "P5E_CPU1_P1_TX_DP<7>")
	)
	(segment
		(start 103.338884 -291.584126)
		(end 103.369872 -291.601906)
		(width 0.1143)
		(layer "In4.Cu")
		(net "P5E_CPU1_P1_TX_DP<7>")
	)
	(segment
		(start 103.808276 -292.393624)
		(end 103.838756 -292.411404)
		(width 0.1143)
		(layer "In4.Cu")
		(net "P5E_CPU1_P1_TX_DP<7>")
	)
	(segment
		(start 103.305864 -291.564822)
		(end 103.306626 -291.56533)
		(width 0.1143)
		(layer "In4.Cu")
		(net "P5E_CPU1_P1_TX_DP<7>")
	)
	(segment
		(start 117.987572 -321.90944)
		(end 118.606316 -323.093588)
		(width 0.14224)
		(layer "In4.Cu")
		(net "P5E_CPU1_P1_TX_DP<7>")
	)
	(segment
		(start 106.516678 -306.973478)
		(end 109.964474 -312.133742)
		(width 0.14224)
		(layer "In4.Cu")
		(net "P5E_CPU1_P1_TX_DP<7>")
	)
	(segment
		(start 103.91902 -289.47618)
		(end 103.98887 -289.54603)
		(width 0.1143)
		(layer "In4.Cu")
		(net "P5E_CPU1_P1_TX_DP<7>")
	)
	(segment
		(start 103.838756 -294.641016)
		(end 103.808276 -294.658796)
		(width 0.1143)
		(layer "In4.Cu")
		(net "P5E_CPU1_P1_TX_DP<7>")
	)
	(segment
		(start 103.33863 -290.608512)
		(end 103.337868 -290.60902)
		(width 0.1143)
		(layer "In4.Cu")
		(net "P5E_CPU1_P1_TX_DP<7>")
	)
	(segment
		(start 103.808276 -293.038784)
		(end 103.76916 -293.061644)
		(width 0.1143)
		(layer "In4.Cu")
		(net "P5E_CPU1_P1_TX_DP<7>")
	)
	(segment
		(start 103.065834 -295.991788)
		(end 103.065834 -296.03319)
		(width 0.1143)
		(layer "In4.Cu")
		(net "P5E_CPU1_P1_TX_DP<7>")
	)
	(segment
		(start 103.808276 -294.013636)
		(end 103.838756 -294.031416)
		(width 0.1143)
		(layer "In4.Cu")
		(net "P5E_CPU1_P1_TX_DP<7>")
	)
	(segment
		(start 103.808276 -294.658796)
		(end 103.76916 -294.681656)
		(width 0.1143)
		(layer "In4.Cu")
		(net "P5E_CPU1_P1_TX_DP<7>")
	)
	(segment
		(start 123.118626 -338.432648)
		(end 123.118626 -344.515694)
		(width 0.14224)
		(layer "In4.Cu")
		(net "P5E_CPU1_P1_TX_DP<7>")
	)
	(segment
		(start 103.810308 -289.79749)
		(end 103.808276 -289.79876)
		(width 0.1143)
		(layer "In4.Cu")
		(net "P5E_CPU1_P1_TX_DP<7>")
	)
	(segment
		(start 103.76916 -292.370764)
		(end 103.808276 -292.393624)
		(width 0.1143)
		(layer "In4.Cu")
		(net "P5E_CPU1_P1_TX_DP<7>")
	)
	(segment
		(start 103.051102 -298.606718)
		(end 106.516678 -306.973478)
		(width 0.14224)
		(layer "In4.Cu")
		(net "P5E_CPU1_P1_TX_DP<7>")
	)
	(segment
		(start 103.299006 -291.560758)
		(end 103.305864 -291.564822)
		(width 0.1143)
		(layer "In4.Cu")
		(net "P5E_CPU1_P1_TX_DP<7>")
	)
	(segment
		(start 103.306626 -291.56533)
		(end 103.338122 -291.583618)
		(width 0.1143)
		(layer "In4.Cu")
		(net "P5E_CPU1_P1_TX_DP<7>")
	)
	(arc
		(start 103.299006 -290.631626)
		(mid 103.055679 -291.096192)
		(end 103.299006 -291.560758)
		(width 0.1143)
		(layer "In4.Cu")
		(net "P5E_CPU1_P1_TX_DP<7>")
	)
	(arc
		(start 103.76916 -294.681656)
		(mid 103.59027 -294.88398)
		(end 103.525828 -295.146222)
		(width 0.1143)
		(layer "In4.Cu")
		(net "P5E_CPU1_P1_TX_DP<7>")
	)
	(arc
		(start 93.743526 -362.890816)
		(mid 92.512219 -363.474002)
		(end 91.34475 -364.17631)
		(width 0.14224)
		(layer "In4.Cu")
		(net "P5E_CPU1_P1_TX_DP<7>")
	)
	(arc
		(start 122.306334 -333.904082)
		(mid 122.324532 -333.964693)
		(end 122.338084 -334.02651)
		(width 0.14224)
		(layer "In4.Cu")
		(net "P5E_CPU1_P1_TX_DP<7>")
	)
	(arc
		(start 103.808276 -289.79876)
		(mid 103.599281 -290.006035)
		(end 103.52278 -290.29025)
		(width 0.1143)
		(layer "In4.Cu")
		(net "P5E_CPU1_P1_TX_DP<7>")
	)
	(arc
		(start 103.52278 -290.29025)
		(mid 103.473939 -290.473443)
		(end 103.340154 -290.60775)
		(width 0.1143)
		(layer "In4.Cu")
		(net "P5E_CPU1_P1_TX_DP<7>")
	)
	(arc
		(start 103.369872 -291.601906)
		(mid 103.484548 -291.73524)
		(end 103.525828 -291.906198)
		(width 0.1143)
		(layer "In4.Cu")
		(net "P5E_CPU1_P1_TX_DP<7>")
	)
	(arc
		(start 123.10745 -338.306664)
		(mid 123.115848 -338.369407)
		(end 123.118626 -338.432648)
		(width 0.14224)
		(layer "In4.Cu")
		(net "P5E_CPU1_P1_TX_DP<7>")
	)
	(arc
		(start 103.98887 -289.54603)
		(mid 103.936916 -289.677399)
		(end 103.840026 -289.780218)
		(width 0.1143)
		(layer "In4.Cu")
		(net "P5E_CPU1_P1_TX_DP<7>")
	)
	(arc
		(start 88.86571 -366.65535)
		(mid 88.037259 -367.895309)
		(end 87.746332 -369.35791)
		(width 0.14224)
		(layer "In4.Cu")
		(net "P5E_CPU1_P1_TX_DP<7>")
	)
	(arc
		(start 103.020114 -298.450254)
		(mid 103.027907 -298.530012)
		(end 103.051102 -298.606718)
		(width 0.14224)
		(layer "In4.Cu")
		(net "P5E_CPU1_P1_TX_DP<7>")
	)
	(arc
		(start 103.525828 -291.906198)
		(mid 103.590343 -292.168417)
		(end 103.76916 -292.370764)
		(width 0.1143)
		(layer "In4.Cu")
		(net "P5E_CPU1_P1_TX_DP<7>")
	)
	(arc
		(start 103.838756 -294.031416)
		(mid 103.995733 -294.336216)
		(end 103.838756 -294.641016)
		(width 0.1143)
		(layer "In4.Cu")
		(net "P5E_CPU1_P1_TX_DP<7>")
	)
	(arc
		(start 103.838756 -292.411404)
		(mid 103.995733 -292.716204)
		(end 103.838756 -293.021004)
		(width 0.1143)
		(layer "In4.Cu")
		(net "P5E_CPU1_P1_TX_DP<7>")
	)
	(arc
		(start 123.118626 -344.515694)
		(mid 122.615058 -346.526109)
		(end 121.223278 -348.061788)
		(width 0.14224)
		(layer "In4.Cu")
		(net "P5E_CPU1_P1_TX_DP<7>")
	)
	(arc
		(start 103.525828 -295.262046)
		(mid 103.500407 -295.389755)
		(end 103.428038 -295.498012)
		(width 0.1143)
		(layer "In4.Cu")
		(net "P5E_CPU1_P1_TX_DP<7>")
	)
	(arc
		(start 103.159052 -295.766998)
		(mid 103.090086 -295.870118)
		(end 103.065834 -295.991788)
		(width 0.1143)
		(layer "In4.Cu")
		(net "P5E_CPU1_P1_TX_DP<7>")
	)
	(arc
		(start 103.299768 -290.631118)
		(mid 103.299387 -290.631372)
		(end 103.299006 -290.631626)
		(width 0.1143)
		(layer "In4.Cu")
		(net "P5E_CPU1_P1_TX_DP<7>")
	)
	(arc
		(start 103.76916 -293.061644)
		(mid 103.525833 -293.52621)
		(end 103.76916 -293.990776)
		(width 0.1143)
		(layer "In4.Cu")
		(net "P5E_CPU1_P1_TX_DP<7>")
	)
	(segment
		(start 84.026502 -370.30533)
		(end 84.322412 -370.00942)
		(width 0.12954)
		(layer "F.Cu")
		(net "P5E_CPU1_P1_TX_DP<6>")
	)
	(segment
		(start 84.322412 -370.00942)
		(end 84.322412 -369.30584)
		(width 0.12954)
		(layer "F.Cu")
		(net "P5E_CPU1_P1_TX_DP<6>")
	)
	(segment
		(start 101.268022 -287.590484)
		(end 100.80117 -287.856422)
		(width 0.12954)
		(layer "F.Cu")
		(net "P5E_CPU1_P1_TX_DP<6>")
	)
	(segment
		(start 84.322412 -369.30584)
		(end 84.051902 -369.03533)
		(width 0.12954)
		(layer "F.Cu")
		(net "P5E_CPU1_P1_TX_DP<6>")
	)
	(segment
		(start 101.928168 -289.153346)
		(end 101.928676 -289.1536)
		(width 0.1143)
		(layer "In4.Cu")
		(net "P5E_CPU1_P1_TX_DP<6>")
	)
	(segment
		(start 105.703116 -307.445918)
		(end 109.177836 -312.646314)
		(width 0.14224)
		(layer "In4.Cu")
		(net "P5E_CPU1_P1_TX_DP<6>")
	)
	(segment
		(start 101.458268 -288.343848)
		(end 101.49078 -288.362644)
		(width 0.1143)
		(layer "In4.Cu")
		(net "P5E_CPU1_P1_TX_DP<6>")
	)
	(segment
		(start 100.80117 -287.856422)
		(end 101.099112 -287.856422)
		(width 0.1143)
		(layer "In4.Cu")
		(net "P5E_CPU1_P1_TX_DP<6>")
	)
	(segment
		(start 102.83063 -292.37178)
		(end 102.899972 -292.412166)
		(width 0.1143)
		(layer "In4.Cu")
		(net "P5E_CPU1_P1_TX_DP<6>")
	)
	(segment
		(start 84.342732 -368.185446)
		(end 84.342732 -368.7445)
		(width 0.14224)
		(layer "In4.Cu")
		(net "P5E_CPU1_P1_TX_DP<6>")
	)
	(segment
		(start 102.075234 -296.21988)
		(end 102.075234 -296.234358)
		(width 0.1143)
		(layer "In4.Cu")
		(net "P5E_CPU1_P1_TX_DP<6>")
	)
	(segment
		(start 85.320378 -367.038128)
		(end 84.46262 -367.895886)
		(width 0.14224)
		(layer "In4.Cu")
		(net "P5E_CPU1_P1_TX_DP<6>")
	)
	(segment
		(start 102.658418 -294.869108)
		(end 102.578154 -295.011856)
		(width 0.1143)
		(layer "In4.Cu")
		(net "P5E_CPU1_P1_TX_DP<6>")
	)
	(segment
		(start 117.187218 -322.405248)
		(end 117.611906 -323.218302)
		(width 0.14224)
		(layer "In4.Cu")
		(net "P5E_CPU1_P1_TX_DP<6>")
	)
	(segment
		(start 102.40264 -291.586158)
		(end 102.403402 -291.586666)
		(width 0.1143)
		(layer "In4.Cu")
		(net "P5E_CPU1_P1_TX_DP<6>")
	)
	(segment
		(start 102.418642 -289.974274)
		(end 102.424738 -289.978338)
		(width 0.1143)
		(layer "In4.Cu")
		(net "P5E_CPU1_P1_TX_DP<6>")
	)
	(segment
		(start 102.397814 -290.60902)
		(end 102.39756 -290.60902)
		(width 0.1143)
		(layer "In4.Cu")
		(net "P5E_CPU1_P1_TX_DP<6>")
	)
	(segment
		(start 102.407466 -291.588952)
		(end 102.429818 -291.601906)
		(width 0.1143)
		(layer "In4.Cu")
		(net "P5E_CPU1_P1_TX_DP<6>")
	)
	(segment
		(start 101.099112 -287.856422)
		(end 101.181916 -287.939226)
		(width 0.1143)
		(layer "In4.Cu")
		(net "P5E_CPU1_P1_TX_DP<6>")
	)
	(segment
		(start 102.108762 -298.768262)
		(end 105.703116 -307.445918)
		(width 0.14224)
		(layer "In4.Cu")
		(net "P5E_CPU1_P1_TX_DP<6>")
	)
	(segment
		(start 102.548436 -295.437814)
		(end 102.213918 -295.772078)
		(width 0.1143)
		(layer "In4.Cu")
		(net "P5E_CPU1_P1_TX_DP<6>")
	)
	(segment
		(start 101.896672 -289.135312)
		(end 101.928168 -289.1536)
		(width 0.1143)
		(layer "In4.Cu")
		(net "P5E_CPU1_P1_TX_DP<6>")
	)
	(segment
		(start 102.899972 -293.020242)
		(end 102.83063 -293.060628)
		(width 0.1143)
		(layer "In4.Cu")
		(net "P5E_CPU1_P1_TX_DP<6>")
	)
	(segment
		(start 102.403402 -291.586666)
		(end 102.404418 -291.587174)
		(width 0.1143)
		(layer "In4.Cu")
		(net "P5E_CPU1_P1_TX_DP<6>")
	)
	(segment
		(start 102.581964 -290.341304)
		(end 102.512368 -290.542218)
		(width 0.1143)
		(layer "In4.Cu")
		(net "P5E_CPU1_P1_TX_DP<6>")
	)
	(segment
		(start 106.59237 -356.559358)
		(end 92.4306 -362.425488)
		(width 0.14224)
		(layer "In4.Cu")
		(net "P5E_CPU1_P1_TX_DP<6>")
	)
	(segment
		(start 102.385368 -289.955986)
		(end 102.38613 -289.956494)
		(width 0.1143)
		(layer "In4.Cu")
		(net "P5E_CPU1_P1_TX_DP<6>")
	)
	(segment
		(start 122.143012 -338.346542)
		(end 122.143012 -344.330274)
		(width 0.14224)
		(layer "In4.Cu")
		(net "P5E_CPU1_P1_TX_DP<6>")
	)
	(segment
		(start 84.342732 -368.7445)
		(end 84.051902 -369.03533)
		(width 0.14224)
		(layer "In4.Cu")
		(net "P5E_CPU1_P1_TX_DP<6>")
	)
	(segment
		(start 117.611906 -323.218302)
		(end 121.431304 -334.378046)
		(width 0.14224)
		(layer "In4.Cu")
		(net "P5E_CPU1_P1_TX_DP<6>")
	)
	(segment
		(start 121.463054 -334.50022)
		(end 122.131836 -338.220558)
		(width 0.14224)
		(layer "In4.Cu")
		(net "P5E_CPU1_P1_TX_DP<6>")
	)
	(segment
		(start 102.38613 -289.956494)
		(end 102.418642 -289.974274)
		(width 0.1143)
		(layer "In4.Cu")
		(net "P5E_CPU1_P1_TX_DP<6>")
	)
	(segment
		(start 101.928168 -289.1536)
		(end 101.928168 -289.153346)
		(width 0.1143)
		(layer "In4.Cu")
		(net "P5E_CPU1_P1_TX_DP<6>")
	)
	(segment
		(start 102.120954 -295.997122)
		(end 102.120954 -296.17416)
		(width 0.1143)
		(layer "In4.Cu")
		(net "P5E_CPU1_P1_TX_DP<6>")
	)
	(segment
		(start 120.606312 -347.203522)
		(end 120.606312 -347.203776)
		(width 0.14224)
		(layer "In4.Cu")
		(net "P5E_CPU1_P1_TX_DP<6>")
	)
	(segment
		(start 102.424738 -289.978338)
		(end 102.474776 -290.01339)
		(width 0.1143)
		(layer "In4.Cu")
		(net "P5E_CPU1_P1_TX_DP<6>")
	)
	(segment
		(start 120.606312 -347.203776)
		(end 106.59237 -356.559358)
		(width 0.14224)
		(layer "In4.Cu")
		(net "P5E_CPU1_P1_TX_DP<6>")
	)
	(segment
		(start 102.120954 -296.17416)
		(end 102.075234 -296.21988)
		(width 0.1143)
		(layer "In4.Cu")
		(net "P5E_CPU1_P1_TX_DP<6>")
	)
	(segment
		(start 102.386638 -291.57676)
		(end 102.40264 -291.586158)
		(width 0.1143)
		(layer "In4.Cu")
		(net "P5E_CPU1_P1_TX_DP<6>")
	)
	(segment
		(start 101.89591 -289.134804)
		(end 101.896672 -289.135312)
		(width 0.1143)
		(layer "In4.Cu")
		(net "P5E_CPU1_P1_TX_DP<6>")
	)
	(segment
		(start 102.39756 -290.60902)
		(end 102.397306 -290.609274)
		(width 0.1143)
		(layer "In4.Cu")
		(net "P5E_CPU1_P1_TX_DP<6>")
	)
	(segment
		(start 102.404418 -291.587174)
		(end 102.40518 -291.587682)
		(width 0.1143)
		(layer "In4.Cu")
		(net "P5E_CPU1_P1_TX_DP<6>")
	)
	(segment
		(start 88.159336 -364.708694)
		(end 88.15578 -364.711234)
		(width 0.14224)
		(layer "In4.Cu")
		(net "P5E_CPU1_P1_TX_DP<6>")
	)
	(segment
		(start 102.40518 -291.587682)
		(end 102.407466 -291.588952)
		(width 0.1143)
		(layer "In4.Cu")
		(net "P5E_CPU1_P1_TX_DP<6>")
	)
	(segment
		(start 102.83063 -293.991792)
		(end 102.899718 -294.032178)
		(width 0.1143)
		(layer "In4.Cu")
		(net "P5E_CPU1_P1_TX_DP<6>")
	)
	(segment
		(start 102.075234 -296.234358)
		(end 102.075234 -298.598844)
		(width 0.14224)
		(layer "In4.Cu")
		(net "P5E_CPU1_P1_TX_DP<6>")
	)
	(segment
		(start 101.889052 -289.13074)
		(end 101.89591 -289.134804)
		(width 0.1143)
		(layer "In4.Cu")
		(net "P5E_CPU1_P1_TX_DP<6>")
	)
	(segment
		(start 109.177836 -312.646314)
		(end 117.187218 -322.405248)
		(width 0.14224)
		(layer "In4.Cu")
		(net "P5E_CPU1_P1_TX_DP<6>")
	)
	(segment
		(start 102.103174 -289.456876)
		(end 102.103174 -289.466528)
		(width 0.1143)
		(layer "In4.Cu")
		(net "P5E_CPU1_P1_TX_DP<6>")
	)
	(segment
		(start 102.512368 -290.542218)
		(end 102.397814 -290.60902)
		(width 0.1143)
		(layer "In4.Cu")
		(net "P5E_CPU1_P1_TX_DP<6>")
	)
	(segment
		(start 102.578154 -295.011856)
		(end 102.578154 -295.36644)
		(width 0.1143)
		(layer "In4.Cu")
		(net "P5E_CPU1_P1_TX_DP<6>")
	)
	(segment
		(start 101.419152 -288.320988)
		(end 101.458268 -288.343848)
		(width 0.1143)
		(layer "In4.Cu")
		(net "P5E_CPU1_P1_TX_DP<6>")
	)
	(segment
		(start 102.899972 -294.640254)
		(end 102.830884 -294.68064)
		(width 0.1143)
		(layer "In4.Cu")
		(net "P5E_CPU1_P1_TX_DP<6>")
	)
	(arc
		(start 102.830884 -294.68064)
		(mid 102.733883 -294.765015)
		(end 102.658418 -294.869108)
		(width 0.1143)
		(layer "In4.Cu")
		(net "P5E_CPU1_P1_TX_DP<6>")
	)
	(arc
		(start 101.49078 -288.362644)
		(mid 101.604709 -288.495791)
		(end 101.64572 -288.666174)
		(width 0.1143)
		(layer "In4.Cu")
		(net "P5E_CPU1_P1_TX_DP<6>")
	)
	(arc
		(start 101.928676 -289.1536)
		(mid 102.056443 -289.281926)
		(end 102.103174 -289.456876)
		(width 0.1143)
		(layer "In4.Cu")
		(net "P5E_CPU1_P1_TX_DP<6>")
	)
	(arc
		(start 102.103174 -289.466528)
		(mid 102.178768 -289.749029)
		(end 102.385368 -289.955986)
		(width 0.1143)
		(layer "In4.Cu")
		(net "P5E_CPU1_P1_TX_DP<6>")
	)
	(arc
		(start 102.899972 -292.412166)
		(mid 103.055799 -292.716204)
		(end 102.899972 -293.020242)
		(width 0.1143)
		(layer "In4.Cu")
		(net "P5E_CPU1_P1_TX_DP<6>")
	)
	(arc
		(start 101.181916 -287.939226)
		(mid 101.183704 -287.950675)
		(end 101.185726 -287.962086)
		(width 0.1143)
		(layer "In4.Cu")
		(net "P5E_CPU1_P1_TX_DP<6>")
	)
	(arc
		(start 102.474776 -290.01339)
		(mid 102.583369 -290.159352)
		(end 102.581964 -290.341304)
		(width 0.1143)
		(layer "In4.Cu")
		(net "P5E_CPU1_P1_TX_DP<6>")
	)
	(arc
		(start 102.586028 -291.906198)
		(mid 102.650846 -292.169187)
		(end 102.83063 -292.37178)
		(width 0.1143)
		(layer "In4.Cu")
		(net "P5E_CPU1_P1_TX_DP<6>")
	)
	(arc
		(start 122.143012 -344.330274)
		(mid 121.734647 -345.959426)
		(end 120.606312 -347.203522)
		(width 0.14224)
		(layer "In4.Cu")
		(net "P5E_CPU1_P1_TX_DP<6>")
	)
	(arc
		(start 122.131836 -338.220558)
		(mid 122.140234 -338.283301)
		(end 122.143012 -338.346542)
		(width 0.14224)
		(layer "In4.Cu")
		(net "P5E_CPU1_P1_TX_DP<6>")
	)
	(arc
		(start 102.83063 -293.060628)
		(mid 102.585809 -293.52621)
		(end 102.83063 -293.991792)
		(width 0.1143)
		(layer "In4.Cu")
		(net "P5E_CPU1_P1_TX_DP<6>")
	)
	(arc
		(start 101.64572 -288.666174)
		(mid 101.710235 -288.928393)
		(end 101.889052 -289.13074)
		(width 0.1143)
		(layer "In4.Cu")
		(net "P5E_CPU1_P1_TX_DP<6>")
	)
	(arc
		(start 101.185726 -287.962086)
		(mid 101.267159 -288.164484)
		(end 101.419152 -288.320988)
		(width 0.1143)
		(layer "In4.Cu")
		(net "P5E_CPU1_P1_TX_DP<6>")
	)
	(arc
		(start 102.075234 -298.598844)
		(mid 102.083677 -298.685199)
		(end 102.108762 -298.768262)
		(width 0.14224)
		(layer "In4.Cu")
		(net "P5E_CPU1_P1_TX_DP<6>")
	)
	(arc
		(start 102.899718 -294.032178)
		(mid 103.055651 -294.336113)
		(end 102.899972 -294.640254)
		(width 0.1143)
		(layer "In4.Cu")
		(net "P5E_CPU1_P1_TX_DP<6>")
	)
	(arc
		(start 102.213918 -295.772078)
		(mid 102.145064 -295.875358)
		(end 102.120954 -295.997122)
		(width 0.1143)
		(layer "In4.Cu")
		(net "P5E_CPU1_P1_TX_DP<6>")
	)
	(arc
		(start 102.397306 -290.609274)
		(mid 102.117385 -291.089985)
		(end 102.386638 -291.57676)
		(width 0.1143)
		(layer "In4.Cu")
		(net "P5E_CPU1_P1_TX_DP<6>")
	)
	(arc
		(start 102.429818 -291.601906)
		(mid 102.544719 -291.735167)
		(end 102.586028 -291.906198)
		(width 0.1143)
		(layer "In4.Cu")
		(net "P5E_CPU1_P1_TX_DP<6>")
	)
	(arc
		(start 88.15578 -364.711234)
		(mid 86.680951 -365.805068)
		(end 85.320378 -367.038128)
		(width 0.14224)
		(layer "In4.Cu")
		(net "P5E_CPU1_P1_TX_DP<6>")
	)
	(arc
		(start 121.431304 -334.378046)
		(mid 121.449488 -334.438533)
		(end 121.463054 -334.50022)
		(width 0.14224)
		(layer "In4.Cu")
		(net "P5E_CPU1_P1_TX_DP<6>")
	)
	(arc
		(start 84.46262 -367.895886)
		(mid 84.373905 -368.028751)
		(end 84.342732 -368.185446)
		(width 0.14224)
		(layer "In4.Cu")
		(net "P5E_CPU1_P1_TX_DP<6>")
	)
	(arc
		(start 92.4306 -362.425488)
		(mid 90.238876 -363.462157)
		(end 88.159336 -364.708694)
		(width 0.14224)
		(layer "In4.Cu")
		(net "P5E_CPU1_P1_TX_DP<6>")
	)
	(arc
		(start 102.578154 -295.36644)
		(mid 102.570444 -295.405112)
		(end 102.548436 -295.437814)
		(width 0.1143)
		(layer "In4.Cu")
		(net "P5E_CPU1_P1_TX_DP<6>")
	)
	(segment
		(start 101.268022 -290.830254)
		(end 100.80117 -291.096192)
		(width 0.12954)
		(layer "F.Cu")
		(net "P5E_CPU1_P1_TX_DP<5>")
	)
	(segment
		(start 82.620612 -372.47322)
		(end 82.620612 -371.76964)
		(width 0.12954)
		(layer "F.Cu")
		(net "P5E_CPU1_P1_TX_DP<5>")
	)
	(segment
		(start 82.324702 -372.76913)
		(end 82.620612 -372.47322)
		(width 0.12954)
		(layer "F.Cu")
		(net "P5E_CPU1_P1_TX_DP<5>")
	)
	(segment
		(start 82.620612 -371.76964)
		(end 82.350102 -371.49913)
		(width 0.12954)
		(layer "F.Cu")
		(net "P5E_CPU1_P1_TX_DP<5>")
	)
	(segment
		(start 101.099112 -291.096192)
		(end 101.181916 -291.178996)
		(width 0.1143)
		(layer "In4.Cu")
		(net "P5E_CPU1_P1_TX_DP<5>")
	)
	(segment
		(start 101.161342 -298.91736)
		(end 104.99344 -308.16931)
		(width 0.14224)
		(layer "In4.Cu")
		(net "P5E_CPU1_P1_TX_DP<5>")
	)
	(segment
		(start 107.69727 -312.21553)
		(end 108.130594 -312.799476)
		(width 0.14224)
		(layer "In4.Cu")
		(net "P5E_CPU1_P1_TX_DP<5>")
	)
	(segment
		(start 118.62181 -329.096878)
		(end 118.622064 -329.096878)
		(width 0.14224)
		(layer "In4.Cu")
		(net "P5E_CPU1_P1_TX_DP<5>")
	)
	(segment
		(start 101.176074 -295.917874)
		(end 101.176074 -296.16019)
		(width 0.1143)
		(layer "In4.Cu")
		(net "P5E_CPU1_P1_TX_DP<5>")
	)
	(segment
		(start 101.924104 -292.391338)
		(end 101.958648 -292.411404)
		(width 0.1143)
		(layer "In4.Cu")
		(net "P5E_CPU1_P1_TX_DP<5>")
	)
	(segment
		(start 118.622064 -329.096878)
		(end 120.517412 -334.635094)
		(width 0.14224)
		(layer "In4.Cu")
		(net "P5E_CPU1_P1_TX_DP<5>")
	)
	(segment
		(start 82.640932 -369.004596)
		(end 82.640932 -371.2083)
		(width 0.14224)
		(layer "In4.Cu")
		(net "P5E_CPU1_P1_TX_DP<5>")
	)
	(segment
		(start 101.176074 -296.16019)
		(end 101.130354 -296.20591)
		(width 0.1143)
		(layer "In4.Cu")
		(net "P5E_CPU1_P1_TX_DP<5>")
	)
	(segment
		(start 101.906832 -294.00119)
		(end 101.957124 -294.0304)
		(width 0.1143)
		(layer "In4.Cu")
		(net "P5E_CPU1_P1_TX_DP<5>")
	)
	(segment
		(start 104.553766 -356.317804)
		(end 91.558618 -361.700318)
		(width 0.14224)
		(layer "In4.Cu")
		(net "P5E_CPU1_P1_TX_DP<5>")
	)
	(segment
		(start 101.130354 -296.20591)
		(end 101.130354 -296.234358)
		(width 0.1143)
		(layer "In4.Cu")
		(net "P5E_CPU1_P1_TX_DP<5>")
	)
	(segment
		(start 120.549162 -334.757522)
		(end 121.181368 -338.273644)
		(width 0.14224)
		(layer "In4.Cu")
		(net "P5E_CPU1_P1_TX_DP<5>")
	)
	(segment
		(start 108.567982 -313.38901)
		(end 116.428012 -322.966334)
		(width 0.14224)
		(layer "In4.Cu")
		(net "P5E_CPU1_P1_TX_DP<5>")
	)
	(segment
		(start 101.49078 -295.449752)
		(end 101.432106 -295.483534)
		(width 0.1143)
		(layer "In4.Cu")
		(net "P5E_CPU1_P1_TX_DP<5>")
	)
	(segment
		(start 120.327674 -345.778074)
		(end 104.553766 -356.317804)
		(width 0.14224)
		(layer "In4.Cu")
		(net "P5E_CPU1_P1_TX_DP<5>")
	)
	(segment
		(start 87.892636 -363.659928)
		(end 87.891874 -363.660436)
		(width 0.14224)
		(layer "In4.Cu")
		(net "P5E_CPU1_P1_TX_DP<5>")
	)
	(segment
		(start 101.421692 -291.562536)
		(end 101.458014 -291.583618)
		(width 0.1143)
		(layer "In4.Cu")
		(net "P5E_CPU1_P1_TX_DP<5>")
	)
	(segment
		(start 104.99344 -308.16931)
		(end 107.69727 -312.21553)
		(width 0.14224)
		(layer "In4.Cu")
		(net "P5E_CPU1_P1_TX_DP<5>")
	)
	(segment
		(start 100.80117 -291.096192)
		(end 101.099112 -291.096192)
		(width 0.1143)
		(layer "In4.Cu")
		(net "P5E_CPU1_P1_TX_DP<5>")
	)
	(segment
		(start 116.428012 -322.966334)
		(end 116.705634 -323.49821)
		(width 0.14224)
		(layer "In4.Cu")
		(net "P5E_CPU1_P1_TX_DP<5>")
	)
	(segment
		(start 101.130354 -296.234358)
		(end 101.130354 -298.760896)
		(width 0.14224)
		(layer "In4.Cu")
		(net "P5E_CPU1_P1_TX_DP<5>")
	)
	(segment
		(start 108.56341 -313.383676)
		(end 108.567982 -313.38901)
		(width 0.14224)
		(layer "In4.Cu")
		(net "P5E_CPU1_P1_TX_DP<5>")
	)
	(segment
		(start 116.705634 -323.49821)
		(end 118.62181 -329.096878)
		(width 0.14224)
		(layer "In4.Cu")
		(net "P5E_CPU1_P1_TX_DP<5>")
	)
	(segment
		(start 101.958648 -293.021004)
		(end 101.906832 -293.05123)
		(width 0.1143)
		(layer "In4.Cu")
		(net "P5E_CPU1_P1_TX_DP<5>")
	)
	(segment
		(start 108.130594 -312.799476)
		(end 108.130594 -312.79973)
		(width 0.14224)
		(layer "In4.Cu")
		(net "P5E_CPU1_P1_TX_DP<5>")
	)
	(segment
		(start 84.556854 -366.39754)
		(end 83.129628 -367.824766)
		(width 0.14224)
		(layer "In4.Cu")
		(net "P5E_CPU1_P1_TX_DP<5>")
	)
	(segment
		(start 101.432106 -295.483534)
		(end 101.301804 -295.613582)
		(width 0.1143)
		(layer "In4.Cu")
		(net "P5E_CPU1_P1_TX_DP<5>")
	)
	(segment
		(start 101.961696 -294.638984)
		(end 101.889814 -294.681148)
		(width 0.1143)
		(layer "In4.Cu")
		(net "P5E_CPU1_P1_TX_DP<5>")
	)
	(segment
		(start 82.640932 -371.2083)
		(end 82.350102 -371.49913)
		(width 0.14224)
		(layer "In4.Cu")
		(net "P5E_CPU1_P1_TX_DP<5>")
	)
	(segment
		(start 121.192544 -338.399628)
		(end 121.192544 -344.160348)
		(width 0.14224)
		(layer "In4.Cu")
		(net "P5E_CPU1_P1_TX_DP<5>")
	)
	(segment
		(start 108.130594 -312.79973)
		(end 108.56341 -313.383676)
		(width 0.14224)
		(layer "In4.Cu")
		(net "P5E_CPU1_P1_TX_DP<5>")
	)
	(segment
		(start 101.458014 -291.583618)
		(end 101.460046 -291.584888)
		(width 0.1143)
		(layer "In4.Cu")
		(net "P5E_CPU1_P1_TX_DP<5>")
	)
	(arc
		(start 101.130354 -298.760896)
		(mid 101.138147 -298.840654)
		(end 101.161342 -298.91736)
		(width 0.14224)
		(layer "In4.Cu")
		(net "P5E_CPU1_P1_TX_DP<5>")
	)
	(arc
		(start 120.517412 -334.635094)
		(mid 120.535604 -334.695707)
		(end 120.549162 -334.757522)
		(width 0.14224)
		(layer "In4.Cu")
		(net "P5E_CPU1_P1_TX_DP<5>")
	)
	(arc
		(start 101.301804 -295.613582)
		(mid 101.208656 -295.753222)
		(end 101.176074 -295.917874)
		(width 0.1143)
		(layer "In4.Cu")
		(net "P5E_CPU1_P1_TX_DP<5>")
	)
	(arc
		(start 87.891874 -363.660436)
		(mid 86.157137 -364.947075)
		(end 84.556854 -366.39754)
		(width 0.14224)
		(layer "In4.Cu")
		(net "P5E_CPU1_P1_TX_DP<5>")
	)
	(arc
		(start 101.906832 -293.05123)
		(mid 101.633281 -293.52621)
		(end 101.906832 -294.00119)
		(width 0.1143)
		(layer "In4.Cu")
		(net "P5E_CPU1_P1_TX_DP<5>")
	)
	(arc
		(start 83.129628 -367.824766)
		(mid 82.767936 -368.366077)
		(end 82.640932 -369.004596)
		(width 0.14224)
		(layer "In4.Cu")
		(net "P5E_CPU1_P1_TX_DP<5>")
	)
	(arc
		(start 101.958648 -292.411404)
		(mid 102.115625 -292.716204)
		(end 101.958648 -293.021004)
		(width 0.1143)
		(layer "In4.Cu")
		(net "P5E_CPU1_P1_TX_DP<5>")
	)
	(arc
		(start 121.192544 -344.160348)
		(mid 120.962754 -345.077548)
		(end 120.327674 -345.778074)
		(width 0.14224)
		(layer "In4.Cu")
		(net "P5E_CPU1_P1_TX_DP<5>")
	)
	(arc
		(start 101.889814 -294.681148)
		(mid 101.710621 -294.883658)
		(end 101.645974 -295.146222)
		(width 0.1143)
		(layer "In4.Cu")
		(net "P5E_CPU1_P1_TX_DP<5>")
	)
	(arc
		(start 101.645974 -291.906452)
		(mid 101.720433 -292.185961)
		(end 101.924104 -292.391338)
		(width 0.1143)
		(layer "In4.Cu")
		(net "P5E_CPU1_P1_TX_DP<5>")
	)
	(arc
		(start 101.645974 -295.146222)
		(mid 101.604924 -295.316672)
		(end 101.49078 -295.449752)
		(width 0.1143)
		(layer "In4.Cu")
		(net "P5E_CPU1_P1_TX_DP<5>")
	)
	(arc
		(start 101.957124 -294.0304)
		(mid 102.116969 -294.33347)
		(end 101.961696 -294.638984)
		(width 0.1143)
		(layer "In4.Cu")
		(net "P5E_CPU1_P1_TX_DP<5>")
	)
	(arc
		(start 101.460046 -291.584888)
		(mid 101.596127 -291.720736)
		(end 101.645974 -291.906452)
		(width 0.1143)
		(layer "In4.Cu")
		(net "P5E_CPU1_P1_TX_DP<5>")
	)
	(arc
		(start 121.181368 -338.273644)
		(mid 121.189769 -338.336387)
		(end 121.192544 -338.399628)
		(width 0.14224)
		(layer "In4.Cu")
		(net "P5E_CPU1_P1_TX_DP<5>")
	)
	(arc
		(start 101.181916 -291.178996)
		(mid 101.261718 -291.395833)
		(end 101.421692 -291.562536)
		(width 0.1143)
		(layer "In4.Cu")
		(net "P5E_CPU1_P1_TX_DP<5>")
	)
	(arc
		(start 91.558618 -361.700318)
		(mid 89.677509 -362.590104)
		(end 87.892636 -363.659928)
		(width 0.14224)
		(layer "In4.Cu")
		(net "P5E_CPU1_P1_TX_DP<5>")
	)
	(segment
		(start 80.918812 -374.23344)
		(end 80.648302 -373.96293)
		(width 0.12954)
		(layer "F.Cu")
		(net "P5E_CPU1_P1_TX_DP<4>")
	)
	(segment
		(start 101.268022 -289.210242)
		(end 100.80117 -289.47618)
		(width 0.12954)
		(layer "F.Cu")
		(net "P5E_CPU1_P1_TX_DP<4>")
	)
	(segment
		(start 80.918812 -374.93702)
		(end 80.918812 -374.23344)
		(width 0.12954)
		(layer "F.Cu")
		(net "P5E_CPU1_P1_TX_DP<4>")
	)
	(segment
		(start 80.622902 -375.23293)
		(end 80.918812 -374.93702)
		(width 0.12954)
		(layer "F.Cu")
		(net "P5E_CPU1_P1_TX_DP<4>")
	)
	(segment
		(start 100.525834 -291.587936)
		(end 100.549964 -291.601906)
		(width 0.1143)
		(layer "In4.Cu")
		(net "P5E_CPU1_P1_TX_DP<4>")
	)
	(segment
		(start 100.485956 -291.564822)
		(end 100.486718 -291.56533)
		(width 0.1143)
		(layer "In4.Cu")
		(net "P5E_CPU1_P1_TX_DP<4>")
	)
	(segment
		(start 100.893372 -294.72255)
		(end 100.891086 -294.722042)
		(width 0.1143)
		(layer "In4.Cu")
		(net "P5E_CPU1_P1_TX_DP<4>")
	)
	(segment
		(start 100.988368 -292.393624)
		(end 101.018848 -292.411404)
		(width 0.1143)
		(layer "In4.Cu")
		(net "P5E_CPU1_P1_TX_DP<4>")
	)
	(segment
		(start 103.820976 -355.567742)
		(end 103.82123 -355.567996)
		(width 0.14224)
		(layer "In4.Cu")
		(net "P5E_CPU1_P1_TX_DP<4>")
	)
	(segment
		(start 117.719856 -329.478386)
		(end 117.72011 -329.478386)
		(width 0.14224)
		(layer "In4.Cu")
		(net "P5E_CPU1_P1_TX_DP<4>")
	)
	(segment
		(start 101.073458 -294.599614)
		(end 101.036374 -294.629586)
		(width 0.1143)
		(layer "In4.Cu")
		(net "P5E_CPU1_P1_TX_DP<4>")
	)
	(segment
		(start 103.82123 -355.567996)
		(end 90.596212 -361.04576)
		(width 0.14224)
		(layer "In4.Cu")
		(net "P5E_CPU1_P1_TX_DP<4>")
	)
	(segment
		(start 100.515674 -290.61029)
		(end 100.479098 -290.631626)
		(width 0.1143)
		(layer "In4.Cu")
		(net "P5E_CPU1_P1_TX_DP<4>")
	)
	(segment
		(start 100.518214 -291.583618)
		(end 100.518976 -291.584126)
		(width 0.1143)
		(layer "In4.Cu")
		(net "P5E_CPU1_P1_TX_DP<4>")
	)
	(segment
		(start 100.524056 -291.58692)
		(end 100.524818 -291.587428)
		(width 0.1143)
		(layer "In4.Cu")
		(net "P5E_CPU1_P1_TX_DP<4>")
	)
	(segment
		(start 100.668836 -295.35882)
		(end 100.36175 -295.665652)
		(width 0.1143)
		(layer "In4.Cu")
		(net "P5E_CPU1_P1_TX_DP<4>")
	)
	(segment
		(start 107.213146 -313.208416)
		(end 115.645438 -323.48297)
		(width 0.14224)
		(layer "In4.Cu")
		(net "P5E_CPU1_P1_TX_DP<4>")
	)
	(segment
		(start 100.949252 -292.370764)
		(end 100.988368 -292.393624)
		(width 0.1143)
		(layer "In4.Cu")
		(net "P5E_CPU1_P1_TX_DP<4>")
	)
	(segment
		(start 100.522532 -291.586158)
		(end 100.524056 -291.58692)
		(width 0.1143)
		(layer "In4.Cu")
		(net "P5E_CPU1_P1_TX_DP<4>")
	)
	(segment
		(start 100.23094 -296.03319)
		(end 100.18522 -296.07891)
		(width 0.1143)
		(layer "In4.Cu")
		(net "P5E_CPU1_P1_TX_DP<4>")
	)
	(segment
		(start 100.80117 -289.47618)
		(end 101.099112 -289.47618)
		(width 0.1143)
		(layer "In4.Cu")
		(net "P5E_CPU1_P1_TX_DP<4>")
	)
	(segment
		(start 100.486718 -291.56533)
		(end 100.518214 -291.583618)
		(width 0.1143)
		(layer "In4.Cu")
		(net "P5E_CPU1_P1_TX_DP<4>")
	)
	(segment
		(start 100.518214 -290.608766)
		(end 100.517198 -290.609274)
		(width 0.1143)
		(layer "In4.Cu")
		(net "P5E_CPU1_P1_TX_DP<4>")
	)
	(segment
		(start 100.18522 -296.107358)
		(end 100.18522 -298.91609)
		(width 0.14224)
		(layer "In4.Cu")
		(net "P5E_CPU1_P1_TX_DP<4>")
	)
	(segment
		(start 84.309966 -364.731554)
		(end 81.956656 -367.084864)
		(width 0.14224)
		(layer "In4.Cu")
		(net "P5E_CPU1_P1_TX_DP<4>")
	)
	(segment
		(start 100.549964 -290.590478)
		(end 100.518976 -290.608258)
		(width 0.1143)
		(layer "In4.Cu")
		(net "P5E_CPU1_P1_TX_DP<4>")
	)
	(segment
		(start 100.216208 -299.072554)
		(end 104.209342 -308.71287)
		(width 0.14224)
		(layer "In4.Cu")
		(net "P5E_CPU1_P1_TX_DP<4>")
	)
	(segment
		(start 100.706174 -295.016682)
		(end 100.706174 -295.26865)
		(width 0.1143)
		(layer "In4.Cu")
		(net "P5E_CPU1_P1_TX_DP<4>")
	)
	(segment
		(start 104.209342 -308.71287)
		(end 107.213146 -313.208416)
		(width 0.14224)
		(layer "In4.Cu")
		(net "P5E_CPU1_P1_TX_DP<4>")
	)
	(segment
		(start 80.939132 -369.541298)
		(end 80.939132 -373.6721)
		(width 0.14224)
		(layer "In4.Cu")
		(net "P5E_CPU1_P1_TX_DP<4>")
	)
	(segment
		(start 120.234456 -338.410042)
		(end 120.234456 -343.724738)
		(width 0.14224)
		(layer "In4.Cu")
		(net "P5E_CPU1_P1_TX_DP<4>")
	)
	(segment
		(start 100.517198 -290.609274)
		(end 100.515674 -290.61029)
		(width 0.1143)
		(layer "In4.Cu")
		(net "P5E_CPU1_P1_TX_DP<4>")
	)
	(segment
		(start 117.72011 -329.478386)
		(end 119.657876 -335.139284)
		(width 0.14224)
		(layer "In4.Cu")
		(net "P5E_CPU1_P1_TX_DP<4>")
	)
	(segment
		(start 119.657876 -335.139284)
		(end 120.22328 -338.284566)
		(width 0.14224)
		(layer "In4.Cu")
		(net "P5E_CPU1_P1_TX_DP<4>")
	)
	(segment
		(start 100.518976 -290.608258)
		(end 100.518214 -290.608766)
		(width 0.1143)
		(layer "In4.Cu")
		(net "P5E_CPU1_P1_TX_DP<4>")
	)
	(segment
		(start 119.493792 -345.110308)
		(end 103.932482 -355.508306)
		(width 0.14224)
		(layer "In4.Cu")
		(net "P5E_CPU1_P1_TX_DP<4>")
	)
	(segment
		(start 100.891086 -294.722042)
		(end 100.842826 -294.75557)
		(width 0.1143)
		(layer "In4.Cu")
		(net "P5E_CPU1_P1_TX_DP<4>")
	)
	(segment
		(start 115.645438 -323.48297)
		(end 115.71097 -323.608192)
		(width 0.14224)
		(layer "In4.Cu")
		(net "P5E_CPU1_P1_TX_DP<4>")
	)
	(segment
		(start 100.518976 -291.584126)
		(end 100.52177 -291.58565)
		(width 0.1143)
		(layer "In4.Cu")
		(net "P5E_CPU1_P1_TX_DP<4>")
	)
	(segment
		(start 100.23094 -295.981882)
		(end 100.23094 -296.03319)
		(width 0.1143)
		(layer "In4.Cu")
		(net "P5E_CPU1_P1_TX_DP<4>")
	)
	(segment
		(start 100.524818 -291.587428)
		(end 100.525834 -291.587936)
		(width 0.1143)
		(layer "In4.Cu")
		(net "P5E_CPU1_P1_TX_DP<4>")
	)
	(segment
		(start 101.099112 -289.47618)
		(end 101.168962 -289.54603)
		(width 0.1143)
		(layer "In4.Cu")
		(net "P5E_CPU1_P1_TX_DP<4>")
	)
	(segment
		(start 100.988368 -289.79876)
		(end 100.949252 -289.82162)
		(width 0.1143)
		(layer "In4.Cu")
		(net "P5E_CPU1_P1_TX_DP<4>")
	)
	(segment
		(start 100.949252 -293.990776)
		(end 101.002084 -294.021764)
		(width 0.1143)
		(layer "In4.Cu")
		(net "P5E_CPU1_P1_TX_DP<4>")
	)
	(segment
		(start 115.71097 -323.608192)
		(end 117.719856 -329.478386)
		(width 0.14224)
		(layer "In4.Cu")
		(net "P5E_CPU1_P1_TX_DP<4>")
	)
	(segment
		(start 100.479098 -291.560758)
		(end 100.485956 -291.564822)
		(width 0.1143)
		(layer "In4.Cu")
		(net "P5E_CPU1_P1_TX_DP<4>")
	)
	(segment
		(start 101.018848 -289.78098)
		(end 100.988368 -289.79876)
		(width 0.1143)
		(layer "In4.Cu")
		(net "P5E_CPU1_P1_TX_DP<4>")
	)
	(segment
		(start 100.52177 -291.58565)
		(end 100.522532 -291.586158)
		(width 0.1143)
		(layer "In4.Cu")
		(net "P5E_CPU1_P1_TX_DP<4>")
	)
	(segment
		(start 101.036374 -294.629586)
		(end 100.893372 -294.72255)
		(width 0.1143)
		(layer "In4.Cu")
		(net "P5E_CPU1_P1_TX_DP<4>")
	)
	(segment
		(start 80.939132 -373.6721)
		(end 80.648302 -373.96293)
		(width 0.14224)
		(layer "In4.Cu")
		(net "P5E_CPU1_P1_TX_DP<4>")
	)
	(segment
		(start 101.018848 -293.021004)
		(end 100.949252 -293.061644)
		(width 0.1143)
		(layer "In4.Cu")
		(net "P5E_CPU1_P1_TX_DP<4>")
	)
	(segment
		(start 100.18522 -296.07891)
		(end 100.18522 -296.107358)
		(width 0.1143)
		(layer "In4.Cu")
		(net "P5E_CPU1_P1_TX_DP<4>")
	)
	(arc
		(start 100.70592 -291.906198)
		(mid 100.770435 -292.168417)
		(end 100.949252 -292.370764)
		(width 0.1143)
		(layer "In4.Cu")
		(net "P5E_CPU1_P1_TX_DP<4>")
	)
	(arc
		(start 101.168962 -289.54603)
		(mid 101.116545 -289.677961)
		(end 101.018848 -289.78098)
		(width 0.1143)
		(layer "In4.Cu")
		(net "P5E_CPU1_P1_TX_DP<4>")
	)
	(arc
		(start 101.018848 -292.411404)
		(mid 101.175825 -292.716204)
		(end 101.018848 -293.021004)
		(width 0.1143)
		(layer "In4.Cu")
		(net "P5E_CPU1_P1_TX_DP<4>")
	)
	(arc
		(start 103.932482 -355.508306)
		(mid 103.878192 -355.54077)
		(end 103.820976 -355.567742)
		(width 0.14224)
		(layer "In4.Cu")
		(net "P5E_CPU1_P1_TX_DP<4>")
	)
	(arc
		(start 84.912962 -364.217458)
		(mid 84.601136 -364.462392)
		(end 84.309966 -364.731554)
		(width 0.14224)
		(layer "In4.Cu")
		(net "P5E_CPU1_P1_TX_DP<4>")
	)
	(arc
		(start 100.842826 -294.75557)
		(mid 100.742314 -294.869299)
		(end 100.706174 -295.016682)
		(width 0.1143)
		(layer "In4.Cu")
		(net "P5E_CPU1_P1_TX_DP<4>")
	)
	(arc
		(start 100.18522 -298.91609)
		(mid 100.193013 -298.995848)
		(end 100.216208 -299.072554)
		(width 0.14224)
		(layer "In4.Cu")
		(net "P5E_CPU1_P1_TX_DP<4>")
	)
	(arc
		(start 120.234456 -343.724738)
		(mid 120.037663 -344.510283)
		(end 119.493792 -345.110308)
		(width 0.14224)
		(layer "In4.Cu")
		(net "P5E_CPU1_P1_TX_DP<4>")
	)
	(arc
		(start 100.706174 -295.26865)
		(mid 100.696483 -295.317459)
		(end 100.668836 -295.35882)
		(width 0.1143)
		(layer "In4.Cu")
		(net "P5E_CPU1_P1_TX_DP<4>")
	)
	(arc
		(start 100.36175 -295.665652)
		(mid 100.264889 -295.810755)
		(end 100.23094 -295.981882)
		(width 0.1143)
		(layer "In4.Cu")
		(net "P5E_CPU1_P1_TX_DP<4>")
	)
	(arc
		(start 100.479098 -290.631626)
		(mid 100.235771 -291.096192)
		(end 100.479098 -291.560758)
		(width 0.1143)
		(layer "In4.Cu")
		(net "P5E_CPU1_P1_TX_DP<4>")
	)
	(arc
		(start 100.70592 -290.286186)
		(mid 100.664665 -290.457157)
		(end 100.549964 -290.590478)
		(width 0.1143)
		(layer "In4.Cu")
		(net "P5E_CPU1_P1_TX_DP<4>")
	)
	(arc
		(start 100.549964 -291.601906)
		(mid 100.66464 -291.73524)
		(end 100.70592 -291.906198)
		(width 0.1143)
		(layer "In4.Cu")
		(net "P5E_CPU1_P1_TX_DP<4>")
	)
	(arc
		(start 120.22328 -338.284566)
		(mid 120.231658 -338.347056)
		(end 120.234456 -338.410042)
		(width 0.14224)
		(layer "In4.Cu")
		(net "P5E_CPU1_P1_TX_DP<4>")
	)
	(arc
		(start 90.596212 -361.04576)
		(mid 87.66222 -362.466101)
		(end 84.912962 -364.217458)
		(width 0.14224)
		(layer "In4.Cu")
		(net "P5E_CPU1_P1_TX_DP<4>")
	)
	(arc
		(start 81.956656 -367.084864)
		(mid 81.203604 -368.211885)
		(end 80.939132 -369.541298)
		(width 0.14224)
		(layer "In4.Cu")
		(net "P5E_CPU1_P1_TX_DP<4>")
	)
	(arc
		(start 100.949252 -293.061644)
		(mid 100.705925 -293.52621)
		(end 100.949252 -293.990776)
		(width 0.1143)
		(layer "In4.Cu")
		(net "P5E_CPU1_P1_TX_DP<4>")
	)
	(arc
		(start 100.949252 -289.82162)
		(mid 100.770439 -290.02397)
		(end 100.70592 -290.286186)
		(width 0.1143)
		(layer "In4.Cu")
		(net "P5E_CPU1_P1_TX_DP<4>")
	)
	(arc
		(start 101.002084 -294.021764)
		(mid 101.179392 -294.28179)
		(end 101.090476 -294.583612)
		(width 0.1143)
		(layer "In4.Cu")
		(net "P5E_CPU1_P1_TX_DP<4>")
	)
	(arc
		(start 101.090476 -294.583612)
		(mid 101.082316 -294.591983)
		(end 101.073458 -294.599614)
		(width 0.1143)
		(layer "In4.Cu")
		(net "P5E_CPU1_P1_TX_DP<4>")
	)
	(segment
		(start 77.515212 -370.00942)
		(end 77.515212 -369.30584)
		(width 0.12954)
		(layer "F.Cu")
		(net "P5E_CPU1_P1_TX_DP<3>")
	)
	(segment
		(start 77.219302 -370.30533)
		(end 77.515212 -370.00942)
		(width 0.12954)
		(layer "F.Cu")
		(net "P5E_CPU1_P1_TX_DP<3>")
	)
	(segment
		(start 77.515212 -369.30584)
		(end 77.244702 -369.03533)
		(width 0.12954)
		(layer "F.Cu")
		(net "P5E_CPU1_P1_TX_DP<3>")
	)
	(segment
		(start 98.44786 -287.590484)
		(end 97.981008 -287.856422)
		(width 0.12954)
		(layer "F.Cu")
		(net "P5E_CPU1_P1_TX_DP<3>")
	)
	(segment
		(start 100.07854 -294.641016)
		(end 100.04806 -294.658796)
		(width 0.1143)
		(layer "In4.Cu")
		(net "P5E_CPU1_P1_TX_DP<3>")
	)
	(segment
		(start 100.008944 -292.370764)
		(end 100.04806 -292.393624)
		(width 0.1143)
		(layer "In4.Cu")
		(net "P5E_CPU1_P1_TX_DP<3>")
	)
	(segment
		(start 100.04806 -292.393624)
		(end 100.07854 -292.411404)
		(width 0.1143)
		(layer "In4.Cu")
		(net "P5E_CPU1_P1_TX_DP<3>")
	)
	(segment
		(start 118.757954 -335.419446)
		(end 119.272812 -338.281772)
		(width 0.14224)
		(layer "In4.Cu")
		(net "P5E_CPU1_P1_TX_DP<3>")
	)
	(segment
		(start 99.29622 -296.03319)
		(end 99.2505 -296.07891)
		(width 0.1143)
		(layer "In4.Cu")
		(net "P5E_CPU1_P1_TX_DP<3>")
	)
	(segment
		(start 100.07854 -293.021004)
		(end 100.04806 -293.038784)
		(width 0.1143)
		(layer "In4.Cu")
		(net "P5E_CPU1_P1_TX_DP<3>")
	)
	(segment
		(start 99.2505 -296.107358)
		(end 99.2505 -299.177202)
		(width 0.14224)
		(layer "In4.Cu")
		(net "P5E_CPU1_P1_TX_DP<3>")
	)
	(segment
		(start 99.60864 -290.590986)
		(end 99.57816 -290.608766)
		(width 0.1143)
		(layer "In4.Cu")
		(net "P5E_CPU1_P1_TX_DP<3>")
	)
	(segment
		(start 106.440478 -313.745118)
		(end 114.86007 -324.00367)
		(width 0.14224)
		(layer "In4.Cu")
		(net "P5E_CPU1_P1_TX_DP<3>")
	)
	(segment
		(start 119.283988 -338.407502)
		(end 119.283988 -343.07272)
		(width 0.14224)
		(layer "In4.Cu")
		(net "P5E_CPU1_P1_TX_DP<3>")
	)
	(segment
		(start 103.398574 -309.192168)
		(end 106.440478 -313.745118)
		(width 0.14224)
		(layer "In4.Cu")
		(net "P5E_CPU1_P1_TX_DP<3>")
	)
	(segment
		(start 97.981008 -287.856422)
		(end 98.27895 -287.856422)
		(width 0.1143)
		(layer "In4.Cu")
		(net "P5E_CPU1_P1_TX_DP<3>")
	)
	(segment
		(start 114.86007 -324.00367)
		(end 118.726204 -335.297018)
		(width 0.14224)
		(layer "In4.Cu")
		(net "P5E_CPU1_P1_TX_DP<3>")
	)
	(segment
		(start 99.11588 -289.170364)
		(end 99.181158 -289.208464)
		(width 0.1143)
		(layer "In4.Cu")
		(net "P5E_CPU1_P1_TX_DP<3>")
	)
	(segment
		(start 99.2505 -296.07891)
		(end 99.2505 -296.107358)
		(width 0.1143)
		(layer "In4.Cu")
		(net "P5E_CPU1_P1_TX_DP<3>")
	)
	(segment
		(start 99.2505 -299.177202)
		(end 103.398574 -309.192168)
		(width 0.14224)
		(layer "In4.Cu")
		(net "P5E_CPU1_P1_TX_DP<3>")
	)
	(segment
		(start 99.539044 -291.560758)
		(end 99.57816 -291.583618)
		(width 0.1143)
		(layer "In4.Cu")
		(net "P5E_CPU1_P1_TX_DP<3>")
	)
	(segment
		(start 118.449852 -344.633296)
		(end 103.335328 -354.73259)
		(width 0.14224)
		(layer "In4.Cu")
		(net "P5E_CPU1_P1_TX_DP<3>")
	)
	(segment
		(start 100.04806 -293.038784)
		(end 100.008944 -293.061644)
		(width 0.1143)
		(layer "In4.Cu")
		(net "P5E_CPU1_P1_TX_DP<3>")
	)
	(segment
		(start 100.04806 -294.013636)
		(end 100.07854 -294.031416)
		(width 0.1143)
		(layer "In4.Cu")
		(net "P5E_CPU1_P1_TX_DP<3>")
	)
	(segment
		(start 103.335328 -354.73259)
		(end 85.267546 -362.216192)
		(width 0.14224)
		(layer "In4.Cu")
		(net "P5E_CPU1_P1_TX_DP<3>")
	)
	(segment
		(start 99.765612 -295.146222)
		(end 99.765612 -295.34739)
		(width 0.1143)
		(layer "In4.Cu")
		(net "P5E_CPU1_P1_TX_DP<3>")
	)
	(segment
		(start 77.535532 -368.267488)
		(end 77.535532 -368.7445)
		(width 0.14224)
		(layer "In4.Cu")
		(net "P5E_CPU1_P1_TX_DP<3>")
	)
	(segment
		(start 99.57816 -291.583618)
		(end 99.60864 -291.601398)
		(width 0.1143)
		(layer "In4.Cu")
		(net "P5E_CPU1_P1_TX_DP<3>")
	)
	(segment
		(start 77.535532 -368.7445)
		(end 77.244702 -369.03533)
		(width 0.14224)
		(layer "In4.Cu")
		(net "P5E_CPU1_P1_TX_DP<3>")
	)
	(segment
		(start 99.579938 -289.964622)
		(end 99.60864 -289.981386)
		(width 0.1143)
		(layer "In4.Cu")
		(net "P5E_CPU1_P1_TX_DP<3>")
	)
	(segment
		(start 99.728274 -295.43756)
		(end 99.389438 -295.776396)
		(width 0.1143)
		(layer "In4.Cu")
		(net "P5E_CPU1_P1_TX_DP<3>")
	)
	(segment
		(start 99.29622 -296.001186)
		(end 99.29622 -296.03319)
		(width 0.1143)
		(layer "In4.Cu")
		(net "P5E_CPU1_P1_TX_DP<3>")
	)
	(segment
		(start 79.642208 -365.975138)
		(end 77.66685 -367.950496)
		(width 0.14224)
		(layer "In4.Cu")
		(net "P5E_CPU1_P1_TX_DP<3>")
	)
	(segment
		(start 98.27895 -287.856422)
		(end 98.361754 -287.939226)
		(width 0.1143)
		(layer "In4.Cu")
		(net "P5E_CPU1_P1_TX_DP<3>")
	)
	(segment
		(start 100.008944 -293.990776)
		(end 100.04806 -294.013636)
		(width 0.1143)
		(layer "In4.Cu")
		(net "P5E_CPU1_P1_TX_DP<3>")
	)
	(segment
		(start 99.57816 -290.608766)
		(end 99.539044 -290.631626)
		(width 0.1143)
		(layer "In4.Cu")
		(net "P5E_CPU1_P1_TX_DP<3>")
	)
	(segment
		(start 98.59899 -288.320988)
		(end 98.671634 -288.363406)
		(width 0.1143)
		(layer "In4.Cu")
		(net "P5E_CPU1_P1_TX_DP<3>")
	)
	(segment
		(start 100.04806 -294.658796)
		(end 100.008944 -294.681656)
		(width 0.1143)
		(layer "In4.Cu")
		(net "P5E_CPU1_P1_TX_DP<3>")
	)
	(arc
		(start 99.765612 -295.34739)
		(mid 99.755906 -295.396185)
		(end 99.728274 -295.43756)
		(width 0.1143)
		(layer "In4.Cu")
		(net "P5E_CPU1_P1_TX_DP<3>")
	)
	(arc
		(start 99.60864 -291.601398)
		(mid 99.724067 -291.734774)
		(end 99.765612 -291.906198)
		(width 0.1143)
		(layer "In4.Cu")
		(net "P5E_CPU1_P1_TX_DP<3>")
	)
	(arc
		(start 100.07854 -292.411404)
		(mid 100.235517 -292.716204)
		(end 100.07854 -293.021004)
		(width 0.1143)
		(layer "In4.Cu")
		(net "P5E_CPU1_P1_TX_DP<3>")
	)
	(arc
		(start 98.361754 -287.939226)
		(mid 98.363542 -287.950675)
		(end 98.365564 -287.962086)
		(width 0.1143)
		(layer "In4.Cu")
		(net "P5E_CPU1_P1_TX_DP<3>")
	)
	(arc
		(start 100.008944 -293.061644)
		(mid 99.765617 -293.52621)
		(end 100.008944 -293.990776)
		(width 0.1143)
		(layer "In4.Cu")
		(net "P5E_CPU1_P1_TX_DP<3>")
	)
	(arc
		(start 99.389438 -295.776396)
		(mid 99.320472 -295.879516)
		(end 99.29622 -296.001186)
		(width 0.1143)
		(layer "In4.Cu")
		(net "P5E_CPU1_P1_TX_DP<3>")
	)
	(arc
		(start 119.283988 -343.07272)
		(mid 119.062363 -343.957467)
		(end 118.449852 -344.633296)
		(width 0.14224)
		(layer "In4.Cu")
		(net "P5E_CPU1_P1_TX_DP<3>")
	)
	(arc
		(start 119.272812 -338.281772)
		(mid 119.281205 -338.344388)
		(end 119.283988 -338.407502)
		(width 0.14224)
		(layer "In4.Cu")
		(net "P5E_CPU1_P1_TX_DP<3>")
	)
	(arc
		(start 99.765612 -291.906198)
		(mid 99.830127 -292.168417)
		(end 100.008944 -292.370764)
		(width 0.1143)
		(layer "In4.Cu")
		(net "P5E_CPU1_P1_TX_DP<3>")
	)
	(arc
		(start 98.365564 -287.962086)
		(mid 98.446997 -288.164484)
		(end 98.59899 -288.320988)
		(width 0.1143)
		(layer "In4.Cu")
		(net "P5E_CPU1_P1_TX_DP<3>")
	)
	(arc
		(start 77.66685 -367.950496)
		(mid 77.569672 -368.095933)
		(end 77.535532 -368.267488)
		(width 0.14224)
		(layer "In4.Cu")
		(net "P5E_CPU1_P1_TX_DP<3>")
	)
	(arc
		(start 99.60864 -289.981386)
		(mid 99.765617 -290.286186)
		(end 99.60864 -290.590986)
		(width 0.1143)
		(layer "In4.Cu")
		(net "P5E_CPU1_P1_TX_DP<3>")
	)
	(arc
		(start 100.07854 -294.031416)
		(mid 100.235517 -294.336216)
		(end 100.07854 -294.641016)
		(width 0.1143)
		(layer "In4.Cu")
		(net "P5E_CPU1_P1_TX_DP<3>")
	)
	(arc
		(start 99.539044 -290.631626)
		(mid 99.295717 -291.096192)
		(end 99.539044 -291.560758)
		(width 0.1143)
		(layer "In4.Cu")
		(net "P5E_CPU1_P1_TX_DP<3>")
	)
	(arc
		(start 98.825812 -288.666174)
		(mid 98.903507 -288.957008)
		(end 99.11588 -289.170364)
		(width 0.1143)
		(layer "In4.Cu")
		(net "P5E_CPU1_P1_TX_DP<3>")
	)
	(arc
		(start 99.181158 -289.208464)
		(mid 99.264698 -289.332863)
		(end 99.295712 -289.479482)
		(width 0.1143)
		(layer "In4.Cu")
		(net "P5E_CPU1_P1_TX_DP<3>")
	)
	(arc
		(start 99.295712 -289.479482)
		(mid 99.374178 -289.759351)
		(end 99.579938 -289.964622)
		(width 0.1143)
		(layer "In4.Cu")
		(net "P5E_CPU1_P1_TX_DP<3>")
	)
	(arc
		(start 98.671634 -288.363406)
		(mid 98.785041 -288.496295)
		(end 98.825812 -288.666174)
		(width 0.1143)
		(layer "In4.Cu")
		(net "P5E_CPU1_P1_TX_DP<3>")
	)
	(arc
		(start 118.726204 -335.297018)
		(mid 118.744402 -335.357629)
		(end 118.757954 -335.419446)
		(width 0.14224)
		(layer "In4.Cu")
		(net "P5E_CPU1_P1_TX_DP<3>")
	)
	(arc
		(start 100.008944 -294.681656)
		(mid 99.830054 -294.88398)
		(end 99.765612 -295.146222)
		(width 0.1143)
		(layer "In4.Cu")
		(net "P5E_CPU1_P1_TX_DP<3>")
	)
	(arc
		(start 85.267546 -362.216192)
		(mid 82.26974 -363.81861)
		(end 79.642208 -365.975138)
		(width 0.14224)
		(layer "In4.Cu")
		(net "P5E_CPU1_P1_TX_DP<3>")
	)
	(segment
		(start 98.44786 -290.830254)
		(end 97.981008 -291.096192)
		(width 0.12954)
		(layer "F.Cu")
		(net "P5E_CPU1_P1_TX_DP<2>")
	)
	(segment
		(start 75.813412 -372.47322)
		(end 75.813412 -371.76964)
		(width 0.12954)
		(layer "F.Cu")
		(net "P5E_CPU1_P1_TX_DP<2>")
	)
	(segment
		(start 75.517502 -372.76913)
		(end 75.813412 -372.47322)
		(width 0.12954)
		(layer "F.Cu")
		(net "P5E_CPU1_P1_TX_DP<2>")
	)
	(segment
		(start 75.813412 -371.76964)
		(end 75.542902 -371.49913)
		(width 0.12954)
		(layer "F.Cu")
		(net "P5E_CPU1_P1_TX_DP<2>")
	)
	(segment
		(start 98.638106 -291.583618)
		(end 98.638868 -291.584126)
		(width 0.1143)
		(layer "In4.Cu")
		(net "P5E_CPU1_P1_TX_DP<2>")
	)
	(segment
		(start 98.825812 -295.146222)
		(end 98.825812 -295.34739)
		(width 0.1143)
		(layer "In4.Cu")
		(net "P5E_CPU1_P1_TX_DP<2>")
	)
	(segment
		(start 97.981008 -291.096192)
		(end 98.27895 -291.096192)
		(width 0.1143)
		(layer "In4.Cu")
		(net "P5E_CPU1_P1_TX_DP<2>")
	)
	(segment
		(start 105.73512 -314.406534)
		(end 114.03584 -324.521322)
		(width 0.14224)
		(layer "In4.Cu")
		(net "P5E_CPU1_P1_TX_DP<2>")
	)
	(segment
		(start 98.788474 -295.43756)
		(end 98.44913 -295.776904)
		(width 0.1143)
		(layer "In4.Cu")
		(net "P5E_CPU1_P1_TX_DP<2>")
	)
	(segment
		(start 98.59899 -291.560758)
		(end 98.605848 -291.564822)
		(width 0.1143)
		(layer "In4.Cu")
		(net "P5E_CPU1_P1_TX_DP<2>")
	)
	(segment
		(start 114.03584 -324.521322)
		(end 117.821456 -335.578704)
		(width 0.14224)
		(layer "In4.Cu")
		(net "P5E_CPU1_P1_TX_DP<2>")
	)
	(segment
		(start 98.638868 -291.584126)
		(end 98.649028 -291.589968)
		(width 0.1143)
		(layer "In4.Cu")
		(net "P5E_CPU1_P1_TX_DP<2>")
	)
	(segment
		(start 99.141534 -294.638984)
		(end 99.069652 -294.681148)
		(width 0.1143)
		(layer "In4.Cu")
		(net "P5E_CPU1_P1_TX_DP<2>")
	)
	(segment
		(start 117.853206 -335.701132)
		(end 118.310406 -338.242656)
		(width 0.14224)
		(layer "In4.Cu")
		(net "P5E_CPU1_P1_TX_DP<2>")
	)
	(segment
		(start 117.598952 -344.05951)
		(end 102.832916 -353.925886)
		(width 0.14224)
		(layer "In4.Cu")
		(net "P5E_CPU1_P1_TX_DP<2>")
	)
	(segment
		(start 98.310192 -296.07891)
		(end 98.310192 -296.107358)
		(width 0.1143)
		(layer "In4.Cu")
		(net "P5E_CPU1_P1_TX_DP<2>")
	)
	(segment
		(start 98.60661 -291.56533)
		(end 98.638106 -291.583618)
		(width 0.1143)
		(layer "In4.Cu")
		(net "P5E_CPU1_P1_TX_DP<2>")
	)
	(segment
		(start 99.108006 -293.038784)
		(end 99.087432 -293.050722)
		(width 0.1143)
		(layer "In4.Cu")
		(net "P5E_CPU1_P1_TX_DP<2>")
	)
	(segment
		(start 98.341434 -299.420534)
		(end 102.615238 -309.737252)
		(width 0.14224)
		(layer "In4.Cu")
		(net "P5E_CPU1_P1_TX_DP<2>")
	)
	(segment
		(start 98.355912 -296.001694)
		(end 98.355912 -296.03319)
		(width 0.1143)
		(layer "In4.Cu")
		(net "P5E_CPU1_P1_TX_DP<2>")
	)
	(segment
		(start 98.310192 -296.107358)
		(end 98.310192 -299.262546)
		(width 0.14224)
		(layer "In4.Cu")
		(net "P5E_CPU1_P1_TX_DP<2>")
	)
	(segment
		(start 98.355912 -296.03319)
		(end 98.310192 -296.07891)
		(width 0.1143)
		(layer "In4.Cu")
		(net "P5E_CPU1_P1_TX_DP<2>")
	)
	(segment
		(start 99.087432 -293.050722)
		(end 99.08667 -293.05123)
		(width 0.1143)
		(layer "In4.Cu")
		(net "P5E_CPU1_P1_TX_DP<2>")
	)
	(segment
		(start 98.837242 -291.915088)
		(end 98.837242 -291.92347)
		(width 0.1143)
		(layer "In4.Cu")
		(net "P5E_CPU1_P1_TX_DP<2>")
	)
	(segment
		(start 99.139756 -293.020496)
		(end 99.108006 -293.038784)
		(width 0.1143)
		(layer "In4.Cu")
		(net "P5E_CPU1_P1_TX_DP<2>")
	)
	(segment
		(start 98.27895 -291.096192)
		(end 98.361754 -291.178996)
		(width 0.1143)
		(layer "In4.Cu")
		(net "P5E_CPU1_P1_TX_DP<2>")
	)
	(segment
		(start 75.833732 -371.2083)
		(end 75.542902 -371.49913)
		(width 0.14224)
		(layer "In4.Cu")
		(net "P5E_CPU1_P1_TX_DP<2>")
	)
	(segment
		(start 98.605848 -291.564822)
		(end 98.60661 -291.56533)
		(width 0.1143)
		(layer "In4.Cu")
		(net "P5E_CPU1_P1_TX_DP<2>")
	)
	(segment
		(start 75.833732 -368.623088)
		(end 75.833732 -371.2083)
		(width 0.14224)
		(layer "In4.Cu")
		(net "P5E_CPU1_P1_TX_DP<2>")
	)
	(segment
		(start 118.321582 -338.368386)
		(end 118.321582 -342.707722)
		(width 0.14224)
		(layer "In4.Cu")
		(net "P5E_CPU1_P1_TX_DP<2>")
	)
	(segment
		(start 102.615238 -309.737252)
		(end 105.73512 -314.406534)
		(width 0.14224)
		(layer "In4.Cu")
		(net "P5E_CPU1_P1_TX_DP<2>")
	)
	(segment
		(start 99.108006 -292.393624)
		(end 99.139756 -292.411912)
		(width 0.1143)
		(layer "In4.Cu")
		(net "P5E_CPU1_P1_TX_DP<2>")
	)
	(segment
		(start 99.08667 -294.00119)
		(end 99.136962 -294.0304)
		(width 0.1143)
		(layer "In4.Cu")
		(net "P5E_CPU1_P1_TX_DP<2>")
	)
	(segment
		(start 102.832916 -353.925886)
		(end 83.525614 -361.923076)
		(width 0.14224)
		(layer "In4.Cu")
		(net "P5E_CPU1_P1_TX_DP<2>")
	)
	(segment
		(start 80.010508 -364.271814)
		(end 75.95743 -368.324892)
		(width 0.14224)
		(layer "In4.Cu")
		(net "P5E_CPU1_P1_TX_DP<2>")
	)
	(arc
		(start 98.825812 -295.34739)
		(mid 98.816106 -295.396185)
		(end 98.788474 -295.43756)
		(width 0.1143)
		(layer "In4.Cu")
		(net "P5E_CPU1_P1_TX_DP<2>")
	)
	(arc
		(start 99.139756 -292.411912)
		(mid 99.295684 -292.716204)
		(end 99.139756 -293.020496)
		(width 0.1143)
		(layer "In4.Cu")
		(net "P5E_CPU1_P1_TX_DP<2>")
	)
	(arc
		(start 98.44913 -295.776904)
		(mid 98.380164 -295.880024)
		(end 98.355912 -296.001694)
		(width 0.1143)
		(layer "In4.Cu")
		(net "P5E_CPU1_P1_TX_DP<2>")
	)
	(arc
		(start 99.08667 -293.05123)
		(mid 98.813119 -293.52621)
		(end 99.08667 -294.00119)
		(width 0.1143)
		(layer "In4.Cu")
		(net "P5E_CPU1_P1_TX_DP<2>")
	)
	(arc
		(start 98.837242 -291.92347)
		(mid 98.909773 -292.194743)
		(end 99.108006 -292.393624)
		(width 0.1143)
		(layer "In4.Cu")
		(net "P5E_CPU1_P1_TX_DP<2>")
	)
	(arc
		(start 99.136962 -294.0304)
		(mid 99.296807 -294.33347)
		(end 99.141534 -294.638984)
		(width 0.1143)
		(layer "In4.Cu")
		(net "P5E_CPU1_P1_TX_DP<2>")
	)
	(arc
		(start 75.95743 -368.324892)
		(mid 75.865985 -368.461705)
		(end 75.833732 -368.623088)
		(width 0.14224)
		(layer "In4.Cu")
		(net "P5E_CPU1_P1_TX_DP<2>")
	)
	(arc
		(start 117.821456 -335.578704)
		(mid 117.839648 -335.639317)
		(end 117.853206 -335.701132)
		(width 0.14224)
		(layer "In4.Cu")
		(net "P5E_CPU1_P1_TX_DP<2>")
	)
	(arc
		(start 98.310192 -299.262546)
		(mid 98.318029 -299.343079)
		(end 98.341434 -299.420534)
		(width 0.14224)
		(layer "In4.Cu")
		(net "P5E_CPU1_P1_TX_DP<2>")
	)
	(arc
		(start 118.321582 -342.707722)
		(mid 118.129581 -343.474122)
		(end 117.598952 -344.05951)
		(width 0.14224)
		(layer "In4.Cu")
		(net "P5E_CPU1_P1_TX_DP<2>")
	)
	(arc
		(start 98.361754 -291.178996)
		(mid 98.363542 -291.190445)
		(end 98.365564 -291.201856)
		(width 0.1143)
		(layer "In4.Cu")
		(net "P5E_CPU1_P1_TX_DP<2>")
	)
	(arc
		(start 98.649028 -291.589968)
		(mid 98.786797 -291.727252)
		(end 98.837242 -291.915088)
		(width 0.1143)
		(layer "In4.Cu")
		(net "P5E_CPU1_P1_TX_DP<2>")
	)
	(arc
		(start 99.069652 -294.681148)
		(mid 98.890459 -294.883658)
		(end 98.825812 -295.146222)
		(width 0.1143)
		(layer "In4.Cu")
		(net "P5E_CPU1_P1_TX_DP<2>")
	)
	(arc
		(start 118.310406 -338.242656)
		(mid 118.318799 -338.305272)
		(end 118.321582 -338.368386)
		(width 0.14224)
		(layer "In4.Cu")
		(net "P5E_CPU1_P1_TX_DP<2>")
	)
	(arc
		(start 83.525614 -361.923076)
		(mid 81.652403 -362.924348)
		(end 80.010508 -364.271814)
		(width 0.14224)
		(layer "In4.Cu")
		(net "P5E_CPU1_P1_TX_DP<2>")
	)
	(arc
		(start 98.365564 -291.201856)
		(mid 98.446997 -291.404254)
		(end 98.59899 -291.560758)
		(width 0.1143)
		(layer "In4.Cu")
		(net "P5E_CPU1_P1_TX_DP<2>")
	)
	(segment
		(start 74.22896 -376.23877)
		(end 73.95845 -375.96826)
		(width 0.12954)
		(layer "F.Cu")
		(net "P5E_CPU1_P1_TX_DP<1>")
	)
	(segment
		(start 74.93254 -376.23877)
		(end 74.22896 -376.23877)
		(width 0.12954)
		(layer "F.Cu")
		(net "P5E_CPU1_P1_TX_DP<1>")
	)
	(segment
		(start 98.44786 -289.210242)
		(end 97.981008 -289.47618)
		(width 0.12954)
		(layer "F.Cu")
		(net "P5E_CPU1_P1_TX_DP<1>")
	)
	(segment
		(start 75.22845 -375.94286)
		(end 74.93254 -376.23877)
		(width 0.12954)
		(layer "F.Cu")
		(net "P5E_CPU1_P1_TX_DP<1>")
	)
	(segment
		(start 97.981008 -289.47618)
		(end 98.27895 -289.47618)
		(width 0.1143)
		(layer "In4.Cu")
		(net "P5E_CPU1_P1_TX_DP<1>")
	)
	(segment
		(start 75.154536 -374.8405)
		(end 75.043792 -374.951244)
		(width 0.14224)
		(layer "In4.Cu")
		(net "P5E_CPU1_P1_TX_DP<1>")
	)
	(segment
		(start 75.043792 -375.377964)
		(end 75.154536 -375.488708)
		(width 0.14224)
		(layer "In4.Cu")
		(net "P5E_CPU1_P1_TX_DP<1>")
	)
	(segment
		(start 98.168206 -292.393624)
		(end 98.198686 -292.411404)
		(width 0.1143)
		(layer "In4.Cu")
		(net "P5E_CPU1_P1_TX_DP<1>")
	)
	(segment
		(start 73.90511 -370.096796)
		(end 74.04227 -370.233956)
		(width 0.14224)
		(layer "In4.Cu")
		(net "P5E_CPU1_P1_TX_DP<1>")
	)
	(segment
		(start 102.905052 -352.689668)
		(end 82.949796 -360.95559)
		(width 0.14224)
		(layer "In4.Cu")
		(net "P5E_CPU1_P1_TX_DP<1>")
	)
	(segment
		(start 75.154536 -374.54332)
		(end 75.154536 -374.8405)
		(width 0.14224)
		(layer "In4.Cu")
		(net "P5E_CPU1_P1_TX_DP<1>")
	)
	(segment
		(start 97.695512 -290.61029)
		(end 97.658936 -290.631626)
		(width 0.1143)
		(layer "In4.Cu")
		(net "P5E_CPU1_P1_TX_DP<1>")
	)
	(segment
		(start 74.04227 -370.233956)
		(end 74.04227 -370.660676)
		(width 0.14224)
		(layer "In4.Cu")
		(net "P5E_CPU1_P1_TX_DP<1>")
	)
	(segment
		(start 73.90511 -370.797836)
		(end 73.90511 -371.224556)
		(width 0.14224)
		(layer "In4.Cu")
		(net "P5E_CPU1_P1_TX_DP<1>")
	)
	(segment
		(start 97.84842 -295.43756)
		(end 97.509076 -295.776904)
		(width 0.1143)
		(layer "In4.Cu")
		(net "P5E_CPU1_P1_TX_DP<1>")
	)
	(segment
		(start 74.04227 -370.660676)
		(end 73.90511 -370.797836)
		(width 0.14224)
		(layer "In4.Cu")
		(net "P5E_CPU1_P1_TX_DP<1>")
	)
	(segment
		(start 97.698052 -290.608766)
		(end 97.697036 -290.609274)
		(width 0.1143)
		(layer "In4.Cu")
		(net "P5E_CPU1_P1_TX_DP<1>")
	)
	(segment
		(start 97.415858 -296.03319)
		(end 97.370138 -296.07891)
		(width 0.1143)
		(layer "In4.Cu")
		(net "P5E_CPU1_P1_TX_DP<1>")
	)
	(segment
		(start 97.415858 -296.001694)
		(end 97.415858 -296.03319)
		(width 0.1143)
		(layer "In4.Cu")
		(net "P5E_CPU1_P1_TX_DP<1>")
	)
	(segment
		(start 73.90511 -369.670076)
		(end 73.90511 -370.096796)
		(width 0.14224)
		(layer "In4.Cu")
		(net "P5E_CPU1_P1_TX_DP<1>")
	)
	(segment
		(start 98.198686 -289.78098)
		(end 98.168206 -289.79876)
		(width 0.1143)
		(layer "In4.Cu")
		(net "P5E_CPU1_P1_TX_DP<1>")
	)
	(segment
		(start 98.168206 -294.658796)
		(end 98.12909 -294.681656)
		(width 0.1143)
		(layer "In4.Cu")
		(net "P5E_CPU1_P1_TX_DP<1>")
	)
	(segment
		(start 97.700084 -290.607496)
		(end 97.698814 -290.608258)
		(width 0.1143)
		(layer "In4.Cu")
		(net "P5E_CPU1_P1_TX_DP<1>")
	)
	(segment
		(start 97.70237 -291.586158)
		(end 97.703894 -291.58692)
		(width 0.1143)
		(layer "In4.Cu")
		(net "P5E_CPU1_P1_TX_DP<1>")
	)
	(segment
		(start 74.04227 -372.489476)
		(end 74.04227 -372.950486)
		(width 0.14224)
		(layer "In4.Cu")
		(net "P5E_CPU1_P1_TX_DP<1>")
	)
	(segment
		(start 75.117198 -376.137932)
		(end 75.07605 -376.17908)
		(width 0.14224)
		(layer "In4.Cu")
		(net "P5E_CPU1_P1_TX_DP<1>")
	)
	(segment
		(start 97.698814 -291.584126)
		(end 97.701608 -291.58565)
		(width 0.1143)
		(layer "In4.Cu")
		(net "P5E_CPU1_P1_TX_DP<1>")
	)
	(segment
		(start 97.729802 -290.590478)
		(end 97.700084 -290.607496)
		(width 0.1143)
		(layer "In4.Cu")
		(net "P5E_CPU1_P1_TX_DP<1>")
	)
	(segment
		(start 97.701608 -291.58565)
		(end 97.70237 -291.586158)
		(width 0.1143)
		(layer "In4.Cu")
		(net "P5E_CPU1_P1_TX_DP<1>")
	)
	(segment
		(start 98.12909 -293.990776)
		(end 98.168206 -294.013636)
		(width 0.1143)
		(layer "In4.Cu")
		(net "P5E_CPU1_P1_TX_DP<1>")
	)
	(segment
		(start 116.971826 -336.154522)
		(end 117.389402 -338.562696)
		(width 0.14224)
		(layer "In4.Cu")
		(net "P5E_CPU1_P1_TX_DP<1>")
	)
	(segment
		(start 97.697036 -291.58311)
		(end 97.698052 -291.583618)
		(width 0.1143)
		(layer "In4.Cu")
		(net "P5E_CPU1_P1_TX_DP<1>")
	)
	(segment
		(start 97.703894 -291.58692)
		(end 97.704656 -291.587428)
		(width 0.1143)
		(layer "In4.Cu")
		(net "P5E_CPU1_P1_TX_DP<1>")
	)
	(segment
		(start 97.705672 -291.587936)
		(end 97.729802 -291.601906)
		(width 0.1143)
		(layer "In4.Cu")
		(net "P5E_CPU1_P1_TX_DP<1>")
	)
	(segment
		(start 98.12909 -292.370764)
		(end 98.168206 -292.393624)
		(width 0.1143)
		(layer "In4.Cu")
		(net "P5E_CPU1_P1_TX_DP<1>")
	)
	(segment
		(start 73.90511 -371.925596)
		(end 73.90511 -372.352316)
		(width 0.14224)
		(layer "In4.Cu")
		(net "P5E_CPU1_P1_TX_DP<1>")
	)
	(segment
		(start 75.154536 -375.488708)
		(end 75.154536 -376.048016)
		(width 0.14224)
		(layer "In4.Cu")
		(net "P5E_CPU1_P1_TX_DP<1>")
	)
	(segment
		(start 98.168206 -293.038784)
		(end 98.12909 -293.061644)
		(width 0.1143)
		(layer "In4.Cu")
		(net "P5E_CPU1_P1_TX_DP<1>")
	)
	(segment
		(start 116.463826 -343.645236)
		(end 103.016812 -352.629978)
		(width 0.14224)
		(layer "In4.Cu")
		(net "P5E_CPU1_P1_TX_DP<1>")
	)
	(segment
		(start 98.168206 -294.013636)
		(end 98.198686 -294.031416)
		(width 0.1143)
		(layer "In4.Cu")
		(net "P5E_CPU1_P1_TX_DP<1>")
	)
	(segment
		(start 113.133632 -324.913498)
		(end 116.940076 -336.032094)
		(width 0.14224)
		(layer "In4.Cu")
		(net "P5E_CPU1_P1_TX_DP<1>")
	)
	(segment
		(start 82.949796 -360.955336)
		(end 82.949542 -360.95559)
		(width 0.14224)
		(layer "In4.Cu")
		(net "P5E_CPU1_P1_TX_DP<1>")
	)
	(segment
		(start 75.043792 -374.951244)
		(end 75.043792 -375.377964)
		(width 0.14224)
		(layer "In4.Cu")
		(net "P5E_CPU1_P1_TX_DP<1>")
	)
	(segment
		(start 97.370138 -296.07891)
		(end 97.370138 -296.107358)
		(width 0.1143)
		(layer "In4.Cu")
		(net "P5E_CPU1_P1_TX_DP<1>")
	)
	(segment
		(start 117.389402 -338.562696)
		(end 117.389402 -341.913972)
		(width 0.14224)
		(layer "In4.Cu")
		(net "P5E_CPU1_P1_TX_DP<1>")
	)
	(segment
		(start 97.698052 -291.583618)
		(end 97.698814 -291.584126)
		(width 0.1143)
		(layer "In4.Cu")
		(net "P5E_CPU1_P1_TX_DP<1>")
	)
	(segment
		(start 79.272892 -363.358684)
		(end 74.220832 -368.410744)
		(width 0.14224)
		(layer "In4.Cu")
		(net "P5E_CPU1_P1_TX_DP<1>")
	)
	(segment
		(start 97.697036 -290.609274)
		(end 97.695512 -290.61029)
		(width 0.1143)
		(layer "In4.Cu")
		(net "P5E_CPU1_P1_TX_DP<1>")
	)
	(segment
		(start 98.198686 -293.021004)
		(end 98.168206 -293.038784)
		(width 0.1143)
		(layer "In4.Cu")
		(net "P5E_CPU1_P1_TX_DP<1>")
	)
	(segment
		(start 105.05567 -315.07049)
		(end 109.094778 -319.992248)
		(width 0.14224)
		(layer "In4.Cu")
		(net "P5E_CPU1_P1_TX_DP<1>")
	)
	(segment
		(start 97.370138 -296.107358)
		(end 97.370138 -299.429424)
		(width 0.14224)
		(layer "In4.Cu")
		(net "P5E_CPU1_P1_TX_DP<1>")
	)
	(segment
		(start 98.168206 -289.79876)
		(end 98.12909 -289.82162)
		(width 0.1143)
		(layer "In4.Cu")
		(net "P5E_CPU1_P1_TX_DP<1>")
	)
	(segment
		(start 74.04227 -371.361716)
		(end 74.04227 -371.788436)
		(width 0.14224)
		(layer "In4.Cu")
		(net "P5E_CPU1_P1_TX_DP<1>")
	)
	(segment
		(start 74.24928 -376.25909)
		(end 73.95845 -375.96826)
		(width 0.14224)
		(layer "In4.Cu")
		(net "P5E_CPU1_P1_TX_DP<1>")
	)
	(segment
		(start 103.016812 -352.629978)
		(end 103.016558 -352.629978)
		(width 0.14224)
		(layer "In4.Cu")
		(net "P5E_CPU1_P1_TX_DP<1>")
	)
	(segment
		(start 74.243946 -373.437404)
		(end 75.01636 -374.209818)
		(width 0.14224)
		(layer "In4.Cu")
		(net "P5E_CPU1_P1_TX_DP<1>")
	)
	(segment
		(start 101.779324 -310.166766)
		(end 105.05567 -315.07049)
		(width 0.14224)
		(layer "In4.Cu")
		(net "P5E_CPU1_P1_TX_DP<1>")
	)
	(segment
		(start 73.90511 -371.224556)
		(end 74.04227 -371.361716)
		(width 0.14224)
		(layer "In4.Cu")
		(net "P5E_CPU1_P1_TX_DP<1>")
	)
	(segment
		(start 97.698814 -290.608258)
		(end 97.698052 -290.608766)
		(width 0.1143)
		(layer "In4.Cu")
		(net "P5E_CPU1_P1_TX_DP<1>")
	)
	(segment
		(start 98.198686 -294.641016)
		(end 98.168206 -294.658796)
		(width 0.1143)
		(layer "In4.Cu")
		(net "P5E_CPU1_P1_TX_DP<1>")
	)
	(segment
		(start 74.88301 -376.25909)
		(end 74.24928 -376.25909)
		(width 0.14224)
		(layer "In4.Cu")
		(net "P5E_CPU1_P1_TX_DP<1>")
	)
	(segment
		(start 74.04227 -369.532916)
		(end 73.90511 -369.670076)
		(width 0.14224)
		(layer "In4.Cu")
		(net "P5E_CPU1_P1_TX_DP<1>")
	)
	(segment
		(start 74.04227 -368.901472)
		(end 74.04227 -369.532916)
		(width 0.14224)
		(layer "In4.Cu")
		(net "P5E_CPU1_P1_TX_DP<1>")
	)
	(segment
		(start 97.658936 -291.560758)
		(end 97.697036 -291.58311)
		(width 0.1143)
		(layer "In4.Cu")
		(net "P5E_CPU1_P1_TX_DP<1>")
	)
	(segment
		(start 97.704656 -291.587428)
		(end 97.705672 -291.587936)
		(width 0.1143)
		(layer "In4.Cu")
		(net "P5E_CPU1_P1_TX_DP<1>")
	)
	(segment
		(start 82.949796 -360.95559)
		(end 82.949796 -360.955336)
		(width 0.14224)
		(layer "In4.Cu")
		(net "P5E_CPU1_P1_TX_DP<1>")
	)
	(segment
		(start 109.094778 -319.991994)
		(end 113.133632 -324.913498)
		(width 0.14224)
		(layer "In4.Cu")
		(net "P5E_CPU1_P1_TX_DP<1>")
	)
	(segment
		(start 97.40519 -299.606462)
		(end 101.779324 -310.166766)
		(width 0.14224)
		(layer "In4.Cu")
		(net "P5E_CPU1_P1_TX_DP<1>")
	)
	(segment
		(start 97.885758 -295.146222)
		(end 97.885758 -295.34739)
		(width 0.1143)
		(layer "In4.Cu")
		(net "P5E_CPU1_P1_TX_DP<1>")
	)
	(segment
		(start 98.27895 -289.47618)
		(end 98.3488 -289.54603)
		(width 0.1143)
		(layer "In4.Cu")
		(net "P5E_CPU1_P1_TX_DP<1>")
	)
	(segment
		(start 73.90511 -372.352316)
		(end 74.04227 -372.489476)
		(width 0.14224)
		(layer "In4.Cu")
		(net "P5E_CPU1_P1_TX_DP<1>")
	)
	(segment
		(start 74.04227 -371.788436)
		(end 73.90511 -371.925596)
		(width 0.14224)
		(layer "In4.Cu")
		(net "P5E_CPU1_P1_TX_DP<1>")
	)
	(segment
		(start 109.094778 -319.992248)
		(end 109.094778 -319.991994)
		(width 0.14224)
		(layer "In4.Cu")
		(net "P5E_CPU1_P1_TX_DP<1>")
	)
	(arc
		(start 98.3488 -289.54603)
		(mid 98.296383 -289.677961)
		(end 98.198686 -289.78098)
		(width 0.1143)
		(layer "In4.Cu")
		(net "P5E_CPU1_P1_TX_DP<1>")
	)
	(arc
		(start 97.658936 -290.631626)
		(mid 97.415609 -291.096192)
		(end 97.658936 -291.560758)
		(width 0.1143)
		(layer "In4.Cu")
		(net "P5E_CPU1_P1_TX_DP<1>")
	)
	(arc
		(start 97.885758 -290.286186)
		(mid 97.844503 -290.457157)
		(end 97.729802 -290.590478)
		(width 0.1143)
		(layer "In4.Cu")
		(net "P5E_CPU1_P1_TX_DP<1>")
	)
	(arc
		(start 97.509076 -295.776904)
		(mid 97.44011 -295.880024)
		(end 97.415858 -296.001694)
		(width 0.1143)
		(layer "In4.Cu")
		(net "P5E_CPU1_P1_TX_DP<1>")
	)
	(arc
		(start 74.04227 -372.950486)
		(mid 74.094686 -373.214)
		(end 74.243946 -373.437404)
		(width 0.14224)
		(layer "In4.Cu")
		(net "P5E_CPU1_P1_TX_DP<1>")
	)
	(arc
		(start 80.753458 -362.136944)
		(mid 79.983987 -362.712442)
		(end 79.272892 -363.358684)
		(width 0.14224)
		(layer "In4.Cu")
		(net "P5E_CPU1_P1_TX_DP<1>")
	)
	(arc
		(start 117.389402 -341.913972)
		(mid 117.143493 -342.89556)
		(end 116.463826 -343.645236)
		(width 0.14224)
		(layer "In4.Cu")
		(net "P5E_CPU1_P1_TX_DP<1>")
	)
	(arc
		(start 103.016558 -352.629978)
		(mid 102.962273 -352.662565)
		(end 102.905052 -352.689668)
		(width 0.14224)
		(layer "In4.Cu")
		(net "P5E_CPU1_P1_TX_DP<1>")
	)
	(arc
		(start 82.949542 -360.95559)
		(mid 81.82169 -361.49085)
		(end 80.753458 -362.136944)
		(width 0.14224)
		(layer "In4.Cu")
		(net "P5E_CPU1_P1_TX_DP<1>")
	)
	(arc
		(start 98.12909 -293.061644)
		(mid 97.885763 -293.52621)
		(end 98.12909 -293.990776)
		(width 0.1143)
		(layer "In4.Cu")
		(net "P5E_CPU1_P1_TX_DP<1>")
	)
	(arc
		(start 97.885758 -291.906198)
		(mid 97.950273 -292.168417)
		(end 98.12909 -292.370764)
		(width 0.1143)
		(layer "In4.Cu")
		(net "P5E_CPU1_P1_TX_DP<1>")
	)
	(arc
		(start 98.198686 -294.031416)
		(mid 98.355663 -294.336216)
		(end 98.198686 -294.641016)
		(width 0.1143)
		(layer "In4.Cu")
		(net "P5E_CPU1_P1_TX_DP<1>")
	)
	(arc
		(start 97.885758 -295.34739)
		(mid 97.876052 -295.396185)
		(end 97.84842 -295.43756)
		(width 0.1143)
		(layer "In4.Cu")
		(net "P5E_CPU1_P1_TX_DP<1>")
	)
	(arc
		(start 75.154536 -376.048016)
		(mid 75.144834 -376.0967)
		(end 75.117198 -376.137932)
		(width 0.14224)
		(layer "In4.Cu")
		(net "P5E_CPU1_P1_TX_DP<1>")
	)
	(arc
		(start 98.198686 -292.411404)
		(mid 98.355663 -292.716204)
		(end 98.198686 -293.021004)
		(width 0.1143)
		(layer "In4.Cu")
		(net "P5E_CPU1_P1_TX_DP<1>")
	)
	(arc
		(start 98.12909 -289.82162)
		(mid 97.950277 -290.02397)
		(end 97.885758 -290.286186)
		(width 0.1143)
		(layer "In4.Cu")
		(net "P5E_CPU1_P1_TX_DP<1>")
	)
	(arc
		(start 116.940076 -336.032094)
		(mid 116.958279 -336.092704)
		(end 116.971826 -336.154522)
		(width 0.14224)
		(layer "In4.Cu")
		(net "P5E_CPU1_P1_TX_DP<1>")
	)
	(arc
		(start 74.085958 -368.629184)
		(mid 74.053218 -368.763581)
		(end 74.04227 -368.901472)
		(width 0.14224)
		(layer "In4.Cu")
		(net "P5E_CPU1_P1_TX_DP<1>")
	)
	(arc
		(start 98.12909 -294.681656)
		(mid 97.950292 -294.884)
		(end 97.885758 -295.146222)
		(width 0.1143)
		(layer "In4.Cu")
		(net "P5E_CPU1_P1_TX_DP<1>")
	)
	(arc
		(start 97.729802 -291.601906)
		(mid 97.844478 -291.73524)
		(end 97.885758 -291.906198)
		(width 0.1143)
		(layer "In4.Cu")
		(net "P5E_CPU1_P1_TX_DP<1>")
	)
	(arc
		(start 97.370138 -299.429424)
		(mid 97.378966 -299.519664)
		(end 97.40519 -299.606462)
		(width 0.14224)
		(layer "In4.Cu")
		(net "P5E_CPU1_P1_TX_DP<1>")
	)
	(arc
		(start 75.01636 -374.209818)
		(mid 75.118599 -374.36283)
		(end 75.154536 -374.54332)
		(width 0.14224)
		(layer "In4.Cu")
		(net "P5E_CPU1_P1_TX_DP<1>")
	)
	(arc
		(start 74.220832 -368.410744)
		(mid 74.140631 -368.512079)
		(end 74.085958 -368.629184)
		(width 0.14224)
		(layer "In4.Cu")
		(net "P5E_CPU1_P1_TX_DP<1>")
	)
	(arc
		(start 75.07605 -376.17908)
		(mid 74.987497 -376.238313)
		(end 74.88301 -376.25909)
		(width 0.14224)
		(layer "In4.Cu")
		(net "P5E_CPU1_P1_TX_DP<1>")
	)
	(segment
		(start 102.831392 -379.767338)
		(end 103.534972 -379.767338)
		(width 0.12954)
		(layer "F.Cu")
		(net "P5E_CPU1_P1_TX_DP<15>")
	)
	(segment
		(start 102.535482 -379.471428)
		(end 102.831392 -379.767338)
		(width 0.12954)
		(layer "F.Cu")
		(net "P5E_CPU1_P1_TX_DP<15>")
	)
	(segment
		(start 109.257846 -286.780478)
		(end 108.790994 -287.046162)
		(width 0.12954)
		(layer "F.Cu")
		(net "P5E_CPU1_P1_TX_DP<15>")
	)
	(segment
		(start 103.534972 -379.767338)
		(end 103.805482 -379.496828)
		(width 0.12954)
		(layer "F.Cu")
		(net "P5E_CPU1_P1_TX_DP<15>")
	)
	(segment
		(start 115.72621 -307.272182)
		(end 124.241052 -317.646812)
		(width 0.14224)
		(layer "In4.Cu")
		(net "P5E_CPU1_P1_TX_DP<15>")
	)
	(segment
		(start 130.708908 -349.080074)
		(end 130.229102 -351.424494)
		(width 0.14224)
		(layer "In4.Cu")
		(net "P5E_CPU1_P1_TX_DP<15>")
	)
	(segment
		(start 105.427272 -376.967496)
		(end 105.290112 -377.104656)
		(width 0.14224)
		(layer "In4.Cu")
		(net "P5E_CPU1_P1_TX_DP<15>")
	)
	(segment
		(start 110.387892 -289.1536)
		(end 110.388146 -289.1536)
		(width 0.1143)
		(layer "In4.Cu")
		(net "P5E_CPU1_P1_TX_DP<15>")
	)
	(segment
		(start 105.290112 -375.264934)
		(end 105.427272 -375.402094)
		(width 0.14224)
		(layer "In4.Cu")
		(net "P5E_CPU1_P1_TX_DP<15>")
	)
	(segment
		(start 105.290112 -378.232416)
		(end 105.290112 -378.659136)
		(width 0.14224)
		(layer "In4.Cu")
		(net "P5E_CPU1_P1_TX_DP<15>")
	)
	(segment
		(start 105.427272 -378.095256)
		(end 105.290112 -378.232416)
		(width 0.14224)
		(layer "In4.Cu")
		(net "P5E_CPU1_P1_TX_DP<15>")
	)
	(segment
		(start 105.290112 -377.104656)
		(end 105.290112 -377.531376)
		(width 0.14224)
		(layer "In4.Cu")
		(net "P5E_CPU1_P1_TX_DP<15>")
	)
	(segment
		(start 110.472728 -289.220656)
		(end 111.245142 -289.854894)
		(width 0.1143)
		(layer "In4.Cu")
		(net "P5E_CPU1_P1_TX_DP<15>")
	)
	(segment
		(start 130.721608 -337.9216)
		(end 130.721608 -348.954344)
		(width 0.14224)
		(layer "In4.Cu")
		(net "P5E_CPU1_P1_TX_DP<15>")
	)
	(segment
		(start 105.427272 -374.701054)
		(end 105.290112 -374.838214)
		(width 0.14224)
		(layer "In4.Cu")
		(net "P5E_CPU1_P1_TX_DP<15>")
	)
	(segment
		(start 113.074196 -303.306734)
		(end 114.391948 -305.279044)
		(width 0.14224)
		(layer "In4.Cu")
		(net "P5E_CPU1_P1_TX_DP<15>")
	)
	(segment
		(start 105.290112 -375.976896)
		(end 105.290112 -376.403616)
		(width 0.14224)
		(layer "In4.Cu")
		(net "P5E_CPU1_P1_TX_DP<15>")
	)
	(segment
		(start 129.729484 -352.327972)
		(end 115.318794 -361.947968)
		(width 0.14224)
		(layer "In4.Cu")
		(net "P5E_CPU1_P1_TX_DP<15>")
	)
	(segment
		(start 105.427272 -379.223016)
		(end 104.86263 -379.787658)
		(width 0.14224)
		(layer "In4.Cu")
		(net "P5E_CPU1_P1_TX_DP<15>")
	)
	(segment
		(start 104.096312 -379.787658)
		(end 103.805482 -379.496828)
		(width 0.14224)
		(layer "In4.Cu")
		(net "P5E_CPU1_P1_TX_DP<15>")
	)
	(segment
		(start 129.679192 -332.055216)
		(end 130.710432 -337.795362)
		(width 0.14224)
		(layer "In4.Cu")
		(net "P5E_CPU1_P1_TX_DP<15>")
	)
	(segment
		(start 109.913928 -288.34207)
		(end 109.924342 -288.347404)
		(width 0.1143)
		(layer "In4.Cu")
		(net "P5E_CPU1_P1_TX_DP<15>")
	)
	(segment
		(start 105.290112 -377.531376)
		(end 105.427272 -377.668536)
		(width 0.14224)
		(layer "In4.Cu")
		(net "P5E_CPU1_P1_TX_DP<15>")
	)
	(segment
		(start 109.932978 -288.35223)
		(end 109.949742 -288.361882)
		(width 0.1143)
		(layer "In4.Cu")
		(net "P5E_CPU1_P1_TX_DP<15>")
	)
	(segment
		(start 124.25553 -317.668656)
		(end 125.70714 -320.446146)
		(width 0.14224)
		(layer "In4.Cu")
		(net "P5E_CPU1_P1_TX_DP<15>")
	)
	(segment
		(start 114.484404 -362.393992)
		(end 112.02924 -363.411008)
		(width 0.14224)
		(layer "In4.Cu")
		(net "P5E_CPU1_P1_TX_DP<15>")
	)
	(segment
		(start 108.26496 -366.50041)
		(end 106.594148 -369.00104)
		(width 0.14224)
		(layer "In4.Cu")
		(net "P5E_CPU1_P1_TX_DP<15>")
	)
	(segment
		(start 108.790994 -287.046162)
		(end 109.088936 -287.046162)
		(width 0.1143)
		(layer "In4.Cu")
		(net "P5E_CPU1_P1_TX_DP<15>")
	)
	(segment
		(start 111.245142 -290.207954)
		(end 111.199422 -290.253674)
		(width 0.1143)
		(layer "In4.Cu")
		(net "P5E_CPU1_P1_TX_DP<15>")
	)
	(segment
		(start 105.427272 -372.847616)
		(end 105.427272 -374.701054)
		(width 0.14224)
		(layer "In4.Cu")
		(net "P5E_CPU1_P1_TX_DP<15>")
	)
	(segment
		(start 109.924342 -288.347404)
		(end 109.932978 -288.35223)
		(width 0.1143)
		(layer "In4.Cu")
		(net "P5E_CPU1_P1_TX_DP<15>")
	)
	(segment
		(start 105.427272 -375.402094)
		(end 105.427272 -375.839736)
		(width 0.14224)
		(layer "In4.Cu")
		(net "P5E_CPU1_P1_TX_DP<15>")
	)
	(segment
		(start 105.290112 -378.659136)
		(end 105.427272 -378.796296)
		(width 0.14224)
		(layer "In4.Cu")
		(net "P5E_CPU1_P1_TX_DP<15>")
	)
	(segment
		(start 111.199422 -290.282122)
		(end 111.199422 -298.699174)
		(width 0.14224)
		(layer "In4.Cu")
		(net "P5E_CPU1_P1_TX_DP<15>")
	)
	(segment
		(start 124.241052 -317.646812)
		(end 124.241052 -317.647066)
		(width 0.14224)
		(layer "In4.Cu")
		(net "P5E_CPU1_P1_TX_DP<15>")
	)
	(segment
		(start 109.91342 -288.341308)
		(end 109.913928 -288.34207)
		(width 0.1143)
		(layer "In4.Cu")
		(net "P5E_CPU1_P1_TX_DP<15>")
	)
	(segment
		(start 105.427272 -377.668536)
		(end 105.427272 -378.095256)
		(width 0.14224)
		(layer "In4.Cu")
		(net "P5E_CPU1_P1_TX_DP<15>")
	)
	(segment
		(start 130.185922 -351.543112)
		(end 129.813558 -352.235262)
		(width 0.14224)
		(layer "In4.Cu")
		(net "P5E_CPU1_P1_TX_DP<15>")
	)
	(segment
		(start 114.391948 -305.279044)
		(end 115.693952 -307.227986)
		(width 0.14224)
		(layer "In4.Cu")
		(net "P5E_CPU1_P1_TX_DP<15>")
	)
	(segment
		(start 110.4646 -289.212528)
		(end 110.472728 -289.220656)
		(width 0.1143)
		(layer "In4.Cu")
		(net "P5E_CPU1_P1_TX_DP<15>")
	)
	(segment
		(start 105.290112 -374.838214)
		(end 105.290112 -375.264934)
		(width 0.14224)
		(layer "In4.Cu")
		(net "P5E_CPU1_P1_TX_DP<15>")
	)
	(segment
		(start 105.427272 -378.796296)
		(end 105.427272 -379.223016)
		(width 0.14224)
		(layer "In4.Cu")
		(net "P5E_CPU1_P1_TX_DP<15>")
	)
	(segment
		(start 105.427272 -376.540776)
		(end 105.427272 -376.967496)
		(width 0.14224)
		(layer "In4.Cu")
		(net "P5E_CPU1_P1_TX_DP<15>")
	)
	(segment
		(start 111.23041 -298.855638)
		(end 113.074196 -303.306734)
		(width 0.14224)
		(layer "In4.Cu")
		(net "P5E_CPU1_P1_TX_DP<15>")
	)
	(segment
		(start 109.40923 -287.510982)
		(end 109.468666 -287.54578)
		(width 0.1143)
		(layer "In4.Cu")
		(net "P5E_CPU1_P1_TX_DP<15>")
	)
	(segment
		(start 110.350554 -289.131756)
		(end 110.387892 -289.1536)
		(width 0.1143)
		(layer "In4.Cu")
		(net "P5E_CPU1_P1_TX_DP<15>")
	)
	(segment
		(start 104.86263 -379.787658)
		(end 104.096312 -379.787658)
		(width 0.14224)
		(layer "In4.Cu")
		(net "P5E_CPU1_P1_TX_DP<15>")
	)
	(segment
		(start 105.427272 -375.839736)
		(end 105.290112 -375.976896)
		(width 0.14224)
		(layer "In4.Cu")
		(net "P5E_CPU1_P1_TX_DP<15>")
	)
	(segment
		(start 105.290112 -376.403616)
		(end 105.427272 -376.540776)
		(width 0.14224)
		(layer "In4.Cu")
		(net "P5E_CPU1_P1_TX_DP<15>")
	)
	(segment
		(start 111.245142 -289.854894)
		(end 111.245142 -290.207954)
		(width 0.1143)
		(layer "In4.Cu")
		(net "P5E_CPU1_P1_TX_DP<15>")
	)
	(segment
		(start 125.70714 -320.446146)
		(end 125.707394 -320.4464)
		(width 0.14224)
		(layer "In4.Cu")
		(net "P5E_CPU1_P1_TX_DP<15>")
	)
	(segment
		(start 125.71476 -320.46418)
		(end 129.674366 -332.03642)
		(width 0.14224)
		(layer "In4.Cu")
		(net "P5E_CPU1_P1_TX_DP<15>")
	)
	(segment
		(start 111.199422 -290.253674)
		(end 111.199422 -290.282122)
		(width 0.1143)
		(layer "In4.Cu")
		(net "P5E_CPU1_P1_TX_DP<15>")
	)
	(segment
		(start 109.088936 -287.046162)
		(end 109.17174 -287.128966)
		(width 0.1143)
		(layer "In4.Cu")
		(net "P5E_CPU1_P1_TX_DP<15>")
	)
	(arc
		(start 115.318794 -361.947968)
		(mid 114.912536 -362.191442)
		(end 114.484404 -362.393992)
		(width 0.14224)
		(layer "In4.Cu")
		(net "P5E_CPU1_P1_TX_DP<15>")
	)
	(arc
		(start 130.721608 -348.954344)
		(mid 130.718442 -349.017531)
		(end 130.708908 -349.080074)
		(width 0.14224)
		(layer "In4.Cu")
		(net "P5E_CPU1_P1_TX_DP<15>")
	)
	(arc
		(start 109.633766 -287.847024)
		(mid 109.635078 -287.858937)
		(end 109.635798 -287.8709)
		(width 0.1143)
		(layer "In4.Cu")
		(net "P5E_CPU1_P1_TX_DP<15>")
	)
	(arc
		(start 112.02924 -363.411008)
		(mid 109.917999 -364.676557)
		(end 108.26496 -366.50041)
		(width 0.14224)
		(layer "In4.Cu")
		(net "P5E_CPU1_P1_TX_DP<15>")
	)
	(arc
		(start 115.693952 -307.227986)
		(mid 115.709609 -307.250429)
		(end 115.72621 -307.272182)
		(width 0.14224)
		(layer "In4.Cu")
		(net "P5E_CPU1_P1_TX_DP<15>")
	)
	(arc
		(start 130.710432 -337.795362)
		(mid 130.718835 -337.858232)
		(end 130.721608 -337.9216)
		(width 0.14224)
		(layer "In4.Cu")
		(net "P5E_CPU1_P1_TX_DP<15>")
	)
	(arc
		(start 109.17174 -287.128966)
		(mid 109.17343 -287.138761)
		(end 109.175296 -287.148524)
		(width 0.1143)
		(layer "In4.Cu")
		(net "P5E_CPU1_P1_TX_DP<15>")
	)
	(arc
		(start 129.813558 -352.235262)
		(mid 129.777224 -352.286794)
		(end 129.729484 -352.327972)
		(width 0.14224)
		(layer "In4.Cu")
		(net "P5E_CPU1_P1_TX_DP<15>")
	)
	(arc
		(start 109.175296 -287.148524)
		(mid 109.256323 -287.352951)
		(end 109.40923 -287.510982)
		(width 0.1143)
		(layer "In4.Cu")
		(net "P5E_CPU1_P1_TX_DP<15>")
	)
	(arc
		(start 125.707394 -320.4464)
		(mid 125.711412 -320.455151)
		(end 125.71476 -320.46418)
		(width 0.14224)
		(layer "In4.Cu")
		(net "P5E_CPU1_P1_TX_DP<15>")
	)
	(arc
		(start 106.594148 -369.00104)
		(mid 105.725413 -370.837782)
		(end 105.427272 -372.847616)
		(width 0.14224)
		(layer "In4.Cu")
		(net "P5E_CPU1_P1_TX_DP<15>")
	)
	(arc
		(start 109.468666 -287.54578)
		(mid 109.578438 -287.681479)
		(end 109.633766 -287.847024)
		(width 0.1143)
		(layer "In4.Cu")
		(net "P5E_CPU1_P1_TX_DP<15>")
	)
	(arc
		(start 111.199422 -298.699174)
		(mid 111.207215 -298.778932)
		(end 111.23041 -298.855638)
		(width 0.14224)
		(layer "In4.Cu")
		(net "P5E_CPU1_P1_TX_DP<15>")
	)
	(arc
		(start 124.241052 -317.647066)
		(mid 124.248853 -317.657485)
		(end 124.25553 -317.668656)
		(width 0.14224)
		(layer "In4.Cu")
		(net "P5E_CPU1_P1_TX_DP<15>")
	)
	(arc
		(start 110.105952 -288.666174)
		(mid 110.17077 -288.929163)
		(end 110.350554 -289.131756)
		(width 0.1143)
		(layer "In4.Cu")
		(net "P5E_CPU1_P1_TX_DP<15>")
	)
	(arc
		(start 110.388146 -289.1536)
		(mid 110.428291 -289.180576)
		(end 110.4646 -289.212528)
		(width 0.1143)
		(layer "In4.Cu")
		(net "P5E_CPU1_P1_TX_DP<15>")
	)
	(arc
		(start 109.949742 -288.361882)
		(mid 110.064643 -288.495143)
		(end 110.105952 -288.666174)
		(width 0.1143)
		(layer "In4.Cu")
		(net "P5E_CPU1_P1_TX_DP<15>")
	)
	(arc
		(start 130.229102 -351.424494)
		(mid 130.211868 -351.48539)
		(end 130.185922 -351.543112)
		(width 0.14224)
		(layer "In4.Cu")
		(net "P5E_CPU1_P1_TX_DP<15>")
	)
	(arc
		(start 109.635798 -287.8709)
		(mid 109.713604 -288.142124)
		(end 109.91342 -288.341308)
		(width 0.1143)
		(layer "In4.Cu")
		(net "P5E_CPU1_P1_TX_DP<15>")
	)
	(arc
		(start 129.674366 -332.03642)
		(mid 129.677137 -332.045726)
		(end 129.679192 -332.055216)
		(width 0.14224)
		(layer "In4.Cu")
		(net "P5E_CPU1_P1_TX_DP<15>")
	)
	(segment
		(start 109.257846 -288.400236)
		(end 108.790994 -288.666174)
		(width 0.12954)
		(layer "F.Cu")
		(net "P5E_CPU1_P1_TX_DP<14>")
	)
	(segment
		(start 102.831392 -376.686318)
		(end 103.534972 -376.686318)
		(width 0.12954)
		(layer "F.Cu")
		(net "P5E_CPU1_P1_TX_DP<14>")
	)
	(segment
		(start 102.535482 -376.982228)
		(end 102.831392 -376.686318)
		(width 0.12954)
		(layer "F.Cu")
		(net "P5E_CPU1_P1_TX_DP<14>")
	)
	(segment
		(start 103.534972 -376.686318)
		(end 103.805482 -376.956828)
		(width 0.12954)
		(layer "F.Cu")
		(net "P5E_CPU1_P1_TX_DP<14>")
	)
	(segment
		(start 109.408976 -289.130994)
		(end 109.471206 -289.167062)
		(width 0.1143)
		(layer "In4.Cu")
		(net "P5E_CPU1_P1_TX_DP<14>")
	)
	(segment
		(start 112.261142 -303.780444)
		(end 114.95151 -307.806852)
		(width 0.14224)
		(layer "In4.Cu")
		(net "P5E_CPU1_P1_TX_DP<14>")
	)
	(segment
		(start 110.575344 -292.702996)
		(end 110.575344 -292.730174)
		(width 0.1143)
		(layer "In4.Cu")
		(net "P5E_CPU1_P1_TX_DP<14>")
	)
	(segment
		(start 110.388146 -293.038784)
		(end 110.387892 -293.039038)
		(width 0.1143)
		(layer "In4.Cu")
		(net "P5E_CPU1_P1_TX_DP<14>")
	)
	(segment
		(start 128.568196 -351.950782)
		(end 128.534668 -351.98431)
		(width 0.14224)
		(layer "In4.Cu")
		(net "P5E_CPU1_P1_TX_DP<14>")
	)
	(segment
		(start 109.88167 -289.942524)
		(end 109.917992 -289.963606)
		(width 0.1143)
		(layer "In4.Cu")
		(net "P5E_CPU1_P1_TX_DP<14>")
	)
	(segment
		(start 128.772158 -332.279498)
		(end 129.776728 -337.873086)
		(width 0.14224)
		(layer "In4.Cu")
		(net "P5E_CPU1_P1_TX_DP<14>")
	)
	(segment
		(start 110.455964 -294.615362)
		(end 110.384844 -294.660828)
		(width 0.1143)
		(layer "In4.Cu")
		(net "P5E_CPU1_P1_TX_DP<14>")
	)
	(segment
		(start 128.534668 -351.98431)
		(end 114.85245 -361.126786)
		(width 0.14224)
		(layer "In4.Cu")
		(net "P5E_CPU1_P1_TX_DP<14>")
	)
	(segment
		(start 129.776728 -337.873086)
		(end 129.776728 -348.852236)
		(width 0.14224)
		(layer "In4.Cu")
		(net "P5E_CPU1_P1_TX_DP<14>")
	)
	(segment
		(start 110.419896 -294.032178)
		(end 110.45317 -294.055292)
		(width 0.1143)
		(layer "In4.Cu")
		(net "P5E_CPU1_P1_TX_DP<14>")
	)
	(segment
		(start 110.105698 -295.48328)
		(end 110.059978 -295.529)
		(width 0.1143)
		(layer "In4.Cu")
		(net "P5E_CPU1_P1_TX_DP<14>")
	)
	(segment
		(start 123.47956 -318.19723)
		(end 124.851922 -320.823082)
		(width 0.14224)
		(layer "In4.Cu")
		(net "P5E_CPU1_P1_TX_DP<14>")
	)
	(segment
		(start 102.28834 -373.64543)
		(end 102.28834 -376.015758)
		(width 0.14224)
		(layer "In4.Cu")
		(net "P5E_CPU1_P1_TX_DP<14>")
	)
	(segment
		(start 109.088936 -288.666174)
		(end 109.17174 -288.748978)
		(width 0.1143)
		(layer "In4.Cu")
		(net "P5E_CPU1_P1_TX_DP<14>")
	)
	(segment
		(start 110.384844 -294.660828)
		(end 110.350554 -294.680386)
		(width 0.1143)
		(layer "In4.Cu")
		(net "P5E_CPU1_P1_TX_DP<14>")
	)
	(segment
		(start 109.917992 -289.963606)
		(end 109.949742 -289.981894)
		(width 0.1143)
		(layer "In4.Cu")
		(net "P5E_CPU1_P1_TX_DP<14>")
	)
	(segment
		(start 110.388146 -294.013636)
		(end 110.419896 -294.032178)
		(width 0.1143)
		(layer "In4.Cu")
		(net "P5E_CPU1_P1_TX_DP<14>")
	)
	(segment
		(start 110.39602 -291.413946)
		(end 110.350554 -291.440616)
		(width 0.1143)
		(layer "In4.Cu")
		(net "P5E_CPU1_P1_TX_DP<14>")
	)
	(segment
		(start 110.42015 -293.019988)
		(end 110.419388 -293.020496)
		(width 0.1143)
		(layer "In4.Cu")
		(net "P5E_CPU1_P1_TX_DP<14>")
	)
	(segment
		(start 129.776728 -348.852236)
		(end 129.462276 -350.309942)
		(width 0.14224)
		(layer "In4.Cu")
		(net "P5E_CPU1_P1_TX_DP<14>")
	)
	(segment
		(start 110.387892 -294.013636)
		(end 110.388146 -294.013636)
		(width 0.1143)
		(layer "In4.Cu")
		(net "P5E_CPU1_P1_TX_DP<14>")
	)
	(segment
		(start 110.386622 -292.392608)
		(end 110.427516 -292.4175)
		(width 0.1143)
		(layer "In4.Cu")
		(net "P5E_CPU1_P1_TX_DP<14>")
	)
	(segment
		(start 108.790994 -288.666174)
		(end 109.088936 -288.666174)
		(width 0.1143)
		(layer "In4.Cu")
		(net "P5E_CPU1_P1_TX_DP<14>")
	)
	(segment
		(start 114.95151 -307.806852)
		(end 119.215662 -313.002422)
		(width 0.14224)
		(layer "In4.Cu")
		(net "P5E_CPU1_P1_TX_DP<14>")
	)
	(segment
		(start 106.558588 -366.643666)
		(end 102.63124 -372.516146)
		(width 0.14224)
		(layer "In4.Cu")
		(net "P5E_CPU1_P1_TX_DP<14>")
	)
	(segment
		(start 119.215662 -313.002168)
		(end 123.47956 -318.19723)
		(width 0.14224)
		(layer "In4.Cu")
		(net "P5E_CPU1_P1_TX_DP<14>")
	)
	(segment
		(start 110.059978 -295.557448)
		(end 110.059978 -298.306998)
		(width 0.14224)
		(layer "In4.Cu")
		(net "P5E_CPU1_P1_TX_DP<14>")
	)
	(segment
		(start 110.419388 -293.020496)
		(end 110.388146 -293.038784)
		(width 0.1143)
		(layer "In4.Cu")
		(net "P5E_CPU1_P1_TX_DP<14>")
	)
	(segment
		(start 110.38713 -290.773104)
		(end 110.387892 -290.773612)
		(width 0.1143)
		(layer "In4.Cu")
		(net "P5E_CPU1_P1_TX_DP<14>")
	)
	(segment
		(start 102.93858 -376.665998)
		(end 103.514652 -376.665998)
		(width 0.14224)
		(layer "In4.Cu")
		(net "P5E_CPU1_P1_TX_DP<14>")
	)
	(segment
		(start 124.851922 -320.823082)
		(end 128.772158 -332.279498)
		(width 0.14224)
		(layer "In4.Cu")
		(net "P5E_CPU1_P1_TX_DP<14>")
	)
	(segment
		(start 119.215662 -313.002422)
		(end 119.215662 -313.002168)
		(width 0.14224)
		(layer "In4.Cu")
		(net "P5E_CPU1_P1_TX_DP<14>")
	)
	(segment
		(start 102.408228 -376.305318)
		(end 102.649274 -376.54611)
		(width 0.14224)
		(layer "In4.Cu")
		(net "P5E_CPU1_P1_TX_DP<14>")
	)
	(segment
		(start 110.120684 -298.612814)
		(end 112.261142 -303.780444)
		(width 0.14224)
		(layer "In4.Cu")
		(net "P5E_CPU1_P1_TX_DP<14>")
	)
	(segment
		(start 114.048032 -361.556554)
		(end 111.446056 -362.633768)
		(width 0.14224)
		(layer "In4.Cu")
		(net "P5E_CPU1_P1_TX_DP<14>")
	)
	(segment
		(start 110.105698 -295.146222)
		(end 110.105698 -295.48328)
		(width 0.1143)
		(layer "In4.Cu")
		(net "P5E_CPU1_P1_TX_DP<14>")
	)
	(segment
		(start 110.34903 -290.750752)
		(end 110.38713 -290.773104)
		(width 0.1143)
		(layer "In4.Cu")
		(net "P5E_CPU1_P1_TX_DP<14>")
	)
	(segment
		(start 103.514652 -376.665998)
		(end 103.805482 -376.956828)
		(width 0.14224)
		(layer "In4.Cu")
		(net "P5E_CPU1_P1_TX_DP<14>")
	)
	(segment
		(start 110.34903 -292.370764)
		(end 110.386622 -292.392608)
		(width 0.1143)
		(layer "In4.Cu")
		(net "P5E_CPU1_P1_TX_DP<14>")
	)
	(segment
		(start 110.059978 -295.529)
		(end 110.059978 -295.557448)
		(width 0.1143)
		(layer "In4.Cu")
		(net "P5E_CPU1_P1_TX_DP<14>")
	)
	(arc
		(start 102.28834 -376.015758)
		(mid 102.319454 -376.172472)
		(end 102.408228 -376.305318)
		(width 0.14224)
		(layer "In4.Cu")
		(net "P5E_CPU1_P1_TX_DP<14>")
	)
	(arc
		(start 110.059978 -298.306998)
		(mid 110.075286 -298.46289)
		(end 110.120684 -298.612814)
		(width 0.14224)
		(layer "In4.Cu")
		(net "P5E_CPU1_P1_TX_DP<14>")
	)
	(arc
		(start 109.635798 -289.491166)
		(mid 109.701418 -289.740684)
		(end 109.871002 -289.935158)
		(width 0.1143)
		(layer "In4.Cu")
		(net "P5E_CPU1_P1_TX_DP<14>")
	)
	(arc
		(start 109.949742 -289.981894)
		(mid 110.064418 -290.115228)
		(end 110.105698 -290.286186)
		(width 0.1143)
		(layer "In4.Cu")
		(net "P5E_CPU1_P1_TX_DP<14>")
	)
	(arc
		(start 109.471206 -289.167062)
		(mid 109.579406 -289.302464)
		(end 109.633766 -289.467036)
		(width 0.1143)
		(layer "In4.Cu")
		(net "P5E_CPU1_P1_TX_DP<14>")
	)
	(arc
		(start 110.387892 -293.039038)
		(mid 110.108128 -293.5264)
		(end 110.387892 -294.013636)
		(width 0.1143)
		(layer "In4.Cu")
		(net "P5E_CPU1_P1_TX_DP<14>")
	)
	(arc
		(start 109.176058 -288.771584)
		(mid 109.257185 -288.97418)
		(end 109.408976 -289.130994)
		(width 0.1143)
		(layer "In4.Cu")
		(net "P5E_CPU1_P1_TX_DP<14>")
	)
	(arc
		(start 110.45317 -294.055292)
		(mid 110.600323 -294.334562)
		(end 110.455964 -294.615362)
		(width 0.1143)
		(layer "In4.Cu")
		(net "P5E_CPU1_P1_TX_DP<14>")
	)
	(arc
		(start 110.575344 -292.730174)
		(mid 110.531231 -292.893004)
		(end 110.42015 -293.019988)
		(width 0.1143)
		(layer "In4.Cu")
		(net "P5E_CPU1_P1_TX_DP<14>")
	)
	(arc
		(start 102.649274 -376.54611)
		(mid 102.781994 -376.634854)
		(end 102.93858 -376.665998)
		(width 0.14224)
		(layer "In4.Cu")
		(net "P5E_CPU1_P1_TX_DP<14>")
	)
	(arc
		(start 110.350554 -294.680386)
		(mid 110.17061 -294.883067)
		(end 110.105698 -295.146222)
		(width 0.1143)
		(layer "In4.Cu")
		(net "P5E_CPU1_P1_TX_DP<14>")
	)
	(arc
		(start 110.387892 -290.773612)
		(mid 110.57287 -291.091466)
		(end 110.39602 -291.413946)
		(width 0.1143)
		(layer "In4.Cu")
		(net "P5E_CPU1_P1_TX_DP<14>")
	)
	(arc
		(start 110.427516 -292.4175)
		(mid 110.536208 -292.542232)
		(end 110.575344 -292.702996)
		(width 0.1143)
		(layer "In4.Cu")
		(net "P5E_CPU1_P1_TX_DP<14>")
	)
	(arc
		(start 109.871002 -289.935158)
		(mid 109.876316 -289.93887)
		(end 109.88167 -289.942524)
		(width 0.1143)
		(layer "In4.Cu")
		(net "P5E_CPU1_P1_TX_DP<14>")
	)
	(arc
		(start 114.85245 -361.126786)
		(mid 114.460812 -361.361456)
		(end 114.048032 -361.556554)
		(width 0.14224)
		(layer "In4.Cu")
		(net "P5E_CPU1_P1_TX_DP<14>")
	)
	(arc
		(start 110.350554 -291.440616)
		(mid 110.349792 -291.441123)
		(end 110.34903 -291.441632)
		(width 0.1143)
		(layer "In4.Cu")
		(net "P5E_CPU1_P1_TX_DP<14>")
	)
	(arc
		(start 110.105698 -290.286186)
		(mid 110.170213 -290.548405)
		(end 110.34903 -290.750752)
		(width 0.1143)
		(layer "In4.Cu")
		(net "P5E_CPU1_P1_TX_DP<14>")
	)
	(arc
		(start 110.34903 -291.441632)
		(mid 110.105703 -291.906198)
		(end 110.34903 -292.370764)
		(width 0.1143)
		(layer "In4.Cu")
		(net "P5E_CPU1_P1_TX_DP<14>")
	)
	(arc
		(start 129.462276 -350.309942)
		(mid 129.133581 -351.194849)
		(end 128.568196 -351.950782)
		(width 0.14224)
		(layer "In4.Cu")
		(net "P5E_CPU1_P1_TX_DP<14>")
	)
	(arc
		(start 111.446056 -362.633768)
		(mid 108.704883 -364.276186)
		(end 106.558588 -366.643666)
		(width 0.14224)
		(layer "In4.Cu")
		(net "P5E_CPU1_P1_TX_DP<14>")
	)
	(arc
		(start 109.17174 -288.748978)
		(mid 109.173785 -288.760303)
		(end 109.176058 -288.771584)
		(width 0.1143)
		(layer "In4.Cu")
		(net "P5E_CPU1_P1_TX_DP<14>")
	)
	(arc
		(start 102.63124 -372.516146)
		(mid 102.376011 -373.055347)
		(end 102.28834 -373.64543)
		(width 0.14224)
		(layer "In4.Cu")
		(net "P5E_CPU1_P1_TX_DP<14>")
	)
	(arc
		(start 109.633766 -289.467036)
		(mid 109.635075 -289.479076)
		(end 109.635798 -289.491166)
		(width 0.1143)
		(layer "In4.Cu")
		(net "P5E_CPU1_P1_TX_DP<14>")
	)
	(segment
		(start 101.044502 -370.30533)
		(end 101.340412 -370.00942)
		(width 0.12954)
		(layer "F.Cu")
		(net "P5E_CPU1_P1_TX_DP<13>")
	)
	(segment
		(start 101.340412 -369.30584)
		(end 101.069902 -369.03533)
		(width 0.12954)
		(layer "F.Cu")
		(net "P5E_CPU1_P1_TX_DP<13>")
	)
	(segment
		(start 109.257846 -290.020248)
		(end 108.790994 -290.286186)
		(width 0.12954)
		(layer "F.Cu")
		(net "P5E_CPU1_P1_TX_DP<13>")
	)
	(segment
		(start 101.340412 -370.00942)
		(end 101.340412 -369.30584)
		(width 0.12954)
		(layer "F.Cu")
		(net "P5E_CPU1_P1_TX_DP<13>")
	)
	(segment
		(start 109.448092 -293.038784)
		(end 109.447838 -293.038784)
		(width 0.1143)
		(layer "In4.Cu")
		(net "P5E_CPU1_P1_TX_DP<13>")
	)
	(segment
		(start 101.354382 -366.776508)
		(end 101.354382 -368.75085)
		(width 0.14224)
		(layer "In4.Cu")
		(net "P5E_CPU1_P1_TX_DP<13>")
	)
	(segment
		(start 124.005086 -321.22872)
		(end 127.846328 -332.45552)
		(width 0.14224)
		(layer "In4.Cu")
		(net "P5E_CPU1_P1_TX_DP<13>")
	)
	(segment
		(start 109.448092 -291.418772)
		(end 109.447076 -291.41928)
		(width 0.1143)
		(layer "In4.Cu")
		(net "P5E_CPU1_P1_TX_DP<13>")
	)
	(segment
		(start 128.567434 -349.765112)
		(end 127.71628 -351.301812)
		(width 0.14224)
		(layer "In4.Cu")
		(net "P5E_CPU1_P1_TX_DP<13>")
	)
	(segment
		(start 122.70486 -318.741298)
		(end 124.005086 -321.22872)
		(width 0.14224)
		(layer "In4.Cu")
		(net "P5E_CPU1_P1_TX_DP<13>")
	)
	(segment
		(start 128.81737 -348.760796)
		(end 128.612646 -349.64751)
		(width 0.14224)
		(layer "In4.Cu")
		(net "P5E_CPU1_P1_TX_DP<13>")
	)
	(segment
		(start 127.631444 -351.394014)
		(end 113.800128 -360.635804)
		(width 0.14224)
		(layer "In4.Cu")
		(net "P5E_CPU1_P1_TX_DP<13>")
	)
	(segment
		(start 109.088936 -290.286186)
		(end 109.17174 -290.36899)
		(width 0.1143)
		(layer "In4.Cu")
		(net "P5E_CPU1_P1_TX_DP<13>")
	)
	(segment
		(start 109.448092 -294.013636)
		(end 109.448854 -294.014144)
		(width 0.1143)
		(layer "In4.Cu")
		(net "P5E_CPU1_P1_TX_DP<13>")
	)
	(segment
		(start 109.408976 -290.750752)
		(end 109.479842 -290.7919)
		(width 0.1143)
		(layer "In4.Cu")
		(net "P5E_CPU1_P1_TX_DP<13>")
	)
	(segment
		(start 103.595678 -364.874302)
		(end 102.299008 -365.54664)
		(width 0.14224)
		(layer "In4.Cu")
		(net "P5E_CPU1_P1_TX_DP<13>")
	)
	(segment
		(start 109.447076 -292.393116)
		(end 109.448092 -292.393624)
		(width 0.1143)
		(layer "In4.Cu")
		(net "P5E_CPU1_P1_TX_DP<13>")
	)
	(segment
		(start 128.831848 -337.95081)
		(end 128.831848 -348.63532)
		(width 0.14224)
		(layer "In4.Cu")
		(net "P5E_CPU1_P1_TX_DP<13>")
	)
	(segment
		(start 109.449616 -293.037768)
		(end 109.448092 -293.038784)
		(width 0.1143)
		(layer "In4.Cu")
		(net "P5E_CPU1_P1_TX_DP<13>")
	)
	(segment
		(start 109.119924 -295.529)
		(end 109.119924 -295.557448)
		(width 0.1143)
		(layer "In4.Cu")
		(net "P5E_CPU1_P1_TX_DP<13>")
	)
	(segment
		(start 109.447076 -291.41928)
		(end 109.408976 -291.441632)
		(width 0.1143)
		(layer "In4.Cu")
		(net "P5E_CPU1_P1_TX_DP<13>")
	)
	(segment
		(start 109.408976 -292.370764)
		(end 109.445552 -292.3921)
		(width 0.1143)
		(layer "In4.Cu")
		(net "P5E_CPU1_P1_TX_DP<13>")
	)
	(segment
		(start 109.447076 -294.013128)
		(end 109.448092 -294.013636)
		(width 0.1143)
		(layer "In4.Cu")
		(net "P5E_CPU1_P1_TX_DP<13>")
	)
	(segment
		(start 127.878078 -332.577948)
		(end 128.820418 -337.82508)
		(width 0.14224)
		(layer "In4.Cu")
		(net "P5E_CPU1_P1_TX_DP<13>")
	)
	(segment
		(start 109.421168 -294.67429)
		(end 109.413802 -294.678862)
		(width 0.1143)
		(layer "In4.Cu")
		(net "P5E_CPU1_P1_TX_DP<13>")
	)
	(segment
		(start 109.165644 -295.146222)
		(end 109.165644 -295.48328)
		(width 0.1143)
		(layer "In4.Cu")
		(net "P5E_CPU1_P1_TX_DP<13>")
	)
	(segment
		(start 111.439706 -304.239676)
		(end 114.231166 -308.417722)
		(width 0.14224)
		(layer "In4.Cu")
		(net "P5E_CPU1_P1_TX_DP<13>")
	)
	(segment
		(start 114.231166 -308.417722)
		(end 118.467886 -313.579764)
		(width 0.14224)
		(layer "In4.Cu")
		(net "P5E_CPU1_P1_TX_DP<13>")
	)
	(segment
		(start 118.46814 -313.57951)
		(end 122.70486 -318.741298)
		(width 0.14224)
		(layer "In4.Cu")
		(net "P5E_CPU1_P1_TX_DP<13>")
	)
	(segment
		(start 113.737644 -360.669332)
		(end 103.67518 -364.837472)
		(width 0.14224)
		(layer "In4.Cu")
		(net "P5E_CPU1_P1_TX_DP<13>")
	)
	(segment
		(start 102.09403 -365.696754)
		(end 101.59492 -366.195864)
		(width 0.14224)
		(layer "In4.Cu")
		(net "P5E_CPU1_P1_TX_DP<13>")
	)
	(segment
		(start 109.44987 -294.014652)
		(end 109.450632 -294.01516)
		(width 0.1143)
		(layer "In4.Cu")
		(net "P5E_CPU1_P1_TX_DP<13>")
	)
	(segment
		(start 109.452156 -294.656764)
		(end 109.421168 -294.67429)
		(width 0.1143)
		(layer "In4.Cu")
		(net "P5E_CPU1_P1_TX_DP<13>")
	)
	(segment
		(start 109.499654 -291.38626)
		(end 109.479842 -291.400484)
		(width 0.1143)
		(layer "In4.Cu")
		(net "P5E_CPU1_P1_TX_DP<13>")
	)
	(segment
		(start 109.119924 -295.557448)
		(end 109.119924 -298.557442)
		(width 0.14224)
		(layer "In4.Cu")
		(net "P5E_CPU1_P1_TX_DP<13>")
	)
	(segment
		(start 109.448854 -291.418264)
		(end 109.448092 -291.418772)
		(width 0.1143)
		(layer "In4.Cu")
		(net "P5E_CPU1_P1_TX_DP<13>")
	)
	(segment
		(start 109.448092 -292.393624)
		(end 109.448854 -292.394132)
		(width 0.1143)
		(layer "In4.Cu")
		(net "P5E_CPU1_P1_TX_DP<13>")
	)
	(segment
		(start 108.790994 -290.286186)
		(end 109.088936 -290.286186)
		(width 0.1143)
		(layer "In4.Cu")
		(net "P5E_CPU1_P1_TX_DP<13>")
	)
	(segment
		(start 109.165644 -295.48328)
		(end 109.119924 -295.529)
		(width 0.1143)
		(layer "In4.Cu")
		(net "P5E_CPU1_P1_TX_DP<13>")
	)
	(segment
		(start 109.452664 -293.036244)
		(end 109.449616 -293.037768)
		(width 0.1143)
		(layer "In4.Cu")
		(net "P5E_CPU1_P1_TX_DP<13>")
	)
	(segment
		(start 109.479842 -291.400484)
		(end 109.448854 -291.418264)
		(width 0.1143)
		(layer "In4.Cu")
		(net "P5E_CPU1_P1_TX_DP<13>")
	)
	(segment
		(start 109.479842 -290.7919)
		(end 109.499654 -290.806124)
		(width 0.1143)
		(layer "In4.Cu")
		(net "P5E_CPU1_P1_TX_DP<13>")
	)
	(segment
		(start 109.413802 -294.678862)
		(end 109.408976 -294.681656)
		(width 0.1143)
		(layer "In4.Cu")
		(net "P5E_CPU1_P1_TX_DP<13>")
	)
	(segment
		(start 109.150912 -298.713906)
		(end 111.439706 -304.239676)
		(width 0.14224)
		(layer "In4.Cu")
		(net "P5E_CPU1_P1_TX_DP<13>")
	)
	(segment
		(start 101.354382 -368.75085)
		(end 101.069902 -369.03533)
		(width 0.14224)
		(layer "In4.Cu")
		(net "P5E_CPU1_P1_TX_DP<13>")
	)
	(segment
		(start 118.467886 -313.579764)
		(end 118.46814 -313.57951)
		(width 0.14224)
		(layer "In4.Cu")
		(net "P5E_CPU1_P1_TX_DP<13>")
	)
	(segment
		(start 109.448854 -294.014144)
		(end 109.44987 -294.014652)
		(width 0.1143)
		(layer "In4.Cu")
		(net "P5E_CPU1_P1_TX_DP<13>")
	)
	(segment
		(start 109.445552 -292.3921)
		(end 109.447076 -292.393116)
		(width 0.1143)
		(layer "In4.Cu")
		(net "P5E_CPU1_P1_TX_DP<13>")
	)
	(arc
		(start 109.463078 -292.402514)
		(mid 109.636398 -292.722302)
		(end 109.452664 -293.036244)
		(width 0.1143)
		(layer "In4.Cu")
		(net "P5E_CPU1_P1_TX_DP<13>")
	)
	(arc
		(start 109.17555 -290.39185)
		(mid 109.256983 -290.594248)
		(end 109.408976 -290.750752)
		(width 0.1143)
		(layer "In4.Cu")
		(net "P5E_CPU1_P1_TX_DP<13>")
	)
	(arc
		(start 102.299008 -365.54664)
		(mid 102.190744 -365.613812)
		(end 102.09403 -365.696754)
		(width 0.14224)
		(layer "In4.Cu")
		(net "P5E_CPU1_P1_TX_DP<13>")
	)
	(arc
		(start 128.831848 -348.63532)
		(mid 128.828173 -348.698469)
		(end 128.81737 -348.760796)
		(width 0.14224)
		(layer "In4.Cu")
		(net "P5E_CPU1_P1_TX_DP<13>")
	)
	(arc
		(start 109.408976 -294.681656)
		(mid 109.318637 -294.759661)
		(end 109.24667 -294.854884)
		(width 0.1143)
		(layer "In4.Cu")
		(net "P5E_CPU1_P1_TX_DP<13>")
	)
	(arc
		(start 109.448854 -292.394132)
		(mid 109.456011 -292.398246)
		(end 109.463078 -292.402514)
		(width 0.1143)
		(layer "In4.Cu")
		(net "P5E_CPU1_P1_TX_DP<13>")
	)
	(arc
		(start 127.71628 -351.301812)
		(mid 127.679357 -351.352967)
		(end 127.631444 -351.394014)
		(width 0.14224)
		(layer "In4.Cu")
		(net "P5E_CPU1_P1_TX_DP<13>")
	)
	(arc
		(start 109.447838 -293.038784)
		(mid 109.1682 -293.525753)
		(end 109.447076 -294.013128)
		(width 0.1143)
		(layer "In4.Cu")
		(net "P5E_CPU1_P1_TX_DP<13>")
	)
	(arc
		(start 109.17174 -290.36899)
		(mid 109.173528 -290.380439)
		(end 109.17555 -290.39185)
		(width 0.1143)
		(layer "In4.Cu")
		(net "P5E_CPU1_P1_TX_DP<13>")
	)
	(arc
		(start 103.67518 -364.837472)
		(mid 103.635033 -364.855031)
		(end 103.595678 -364.874302)
		(width 0.14224)
		(layer "In4.Cu")
		(net "P5E_CPU1_P1_TX_DP<13>")
	)
	(arc
		(start 101.59492 -366.195864)
		(mid 101.416916 -366.462266)
		(end 101.354382 -366.776508)
		(width 0.14224)
		(layer "In4.Cu")
		(net "P5E_CPU1_P1_TX_DP<13>")
	)
	(arc
		(start 128.612646 -349.64751)
		(mid 128.594149 -349.707891)
		(end 128.567434 -349.765112)
		(width 0.14224)
		(layer "In4.Cu")
		(net "P5E_CPU1_P1_TX_DP<13>")
	)
	(arc
		(start 109.408976 -291.441632)
		(mid 109.165649 -291.906198)
		(end 109.408976 -292.370764)
		(width 0.1143)
		(layer "In4.Cu")
		(net "P5E_CPU1_P1_TX_DP<13>")
	)
	(arc
		(start 113.800128 -360.635804)
		(mid 113.769709 -360.654103)
		(end 113.737644 -360.669332)
		(width 0.14224)
		(layer "In4.Cu")
		(net "P5E_CPU1_P1_TX_DP<13>")
	)
	(arc
		(start 109.119924 -298.557442)
		(mid 109.127717 -298.6372)
		(end 109.150912 -298.713906)
		(width 0.14224)
		(layer "In4.Cu")
		(net "P5E_CPU1_P1_TX_DP<13>")
	)
	(arc
		(start 109.24667 -294.854884)
		(mid 109.186306 -294.995033)
		(end 109.165644 -295.146222)
		(width 0.1143)
		(layer "In4.Cu")
		(net "P5E_CPU1_P1_TX_DP<13>")
	)
	(arc
		(start 127.846328 -332.45552)
		(mid 127.864531 -332.51613)
		(end 127.878078 -332.577948)
		(width 0.14224)
		(layer "In4.Cu")
		(net "P5E_CPU1_P1_TX_DP<13>")
	)
	(arc
		(start 128.820418 -337.82508)
		(mid 128.828919 -337.887691)
		(end 128.831848 -337.95081)
		(width 0.14224)
		(layer "In4.Cu")
		(net "P5E_CPU1_P1_TX_DP<13>")
	)
	(arc
		(start 109.450632 -294.01516)
		(mid 109.635676 -294.335556)
		(end 109.452156 -294.656764)
		(width 0.1143)
		(layer "In4.Cu")
		(net "P5E_CPU1_P1_TX_DP<13>")
	)
	(arc
		(start 109.499654 -290.806124)
		(mid 109.648368 -291.096192)
		(end 109.499654 -291.38626)
		(width 0.1143)
		(layer "In4.Cu")
		(net "P5E_CPU1_P1_TX_DP<13>")
	)
	(segment
		(start 97.936812 -370.00942)
		(end 97.936812 -369.30584)
		(width 0.12954)
		(layer "F.Cu")
		(net "P5E_CPU1_P1_TX_DP<12>")
	)
	(segment
		(start 106.907838 -287.590484)
		(end 106.440986 -287.856422)
		(width 0.12954)
		(layer "F.Cu")
		(net "P5E_CPU1_P1_TX_DP<12>")
	)
	(segment
		(start 97.936812 -369.30584)
		(end 97.666302 -369.03533)
		(width 0.12954)
		(layer "F.Cu")
		(net "P5E_CPU1_P1_TX_DP<12>")
	)
	(segment
		(start 97.640902 -370.30533)
		(end 97.936812 -370.00942)
		(width 0.12954)
		(layer "F.Cu")
		(net "P5E_CPU1_P1_TX_DP<12>")
	)
	(segment
		(start 108.486956 -291.430964)
		(end 108.483654 -291.432996)
		(width 0.1143)
		(layer "In4.Cu")
		(net "P5E_CPU1_P1_TX_DP<12>")
	)
	(segment
		(start 108.518452 -292.399466)
		(end 108.539788 -292.411912)
		(width 0.1143)
		(layer "In4.Cu")
		(net "P5E_CPU1_P1_TX_DP<12>")
	)
	(segment
		(start 108.500418 -293.043102)
		(end 108.498894 -293.044118)
		(width 0.1143)
		(layer "In4.Cu")
		(net "P5E_CPU1_P1_TX_DP<12>")
	)
	(segment
		(start 108.502196 -291.422074)
		(end 108.500418 -291.42309)
		(width 0.1143)
		(layer "In4.Cu")
		(net "P5E_CPU1_P1_TX_DP<12>")
	)
	(segment
		(start 108.508038 -293.038784)
		(end 108.507022 -293.039292)
		(width 0.1143)
		(layer "In4.Cu")
		(net "P5E_CPU1_P1_TX_DP<12>")
	)
	(segment
		(start 107.567984 -289.1536)
		(end 107.570016 -289.15487)
		(width 0.1143)
		(layer "In4.Cu")
		(net "P5E_CPU1_P1_TX_DP<12>")
	)
	(segment
		(start 101.249226 -364.833154)
		(end 99.301046 -366.134904)
		(width 0.14224)
		(layer "In4.Cu")
		(net "P5E_CPU1_P1_TX_DP<12>")
	)
	(segment
		(start 108.511594 -291.41674)
		(end 108.5088 -291.418264)
		(width 0.1143)
		(layer "In4.Cu")
		(net "P5E_CPU1_P1_TX_DP<12>")
	)
	(segment
		(start 107.531662 -289.132518)
		(end 107.567984 -289.1536)
		(width 0.1143)
		(layer "In4.Cu")
		(net "P5E_CPU1_P1_TX_DP<12>")
	)
	(segment
		(start 108.483654 -291.432996)
		(end 108.48213 -291.433758)
		(width 0.1143)
		(layer "In4.Cu")
		(net "P5E_CPU1_P1_TX_DP<12>")
	)
	(segment
		(start 108.505498 -291.420296)
		(end 108.504482 -291.420804)
		(width 0.1143)
		(layer "In4.Cu")
		(net "P5E_CPU1_P1_TX_DP<12>")
	)
	(segment
		(start 108.496354 -294.6654)
		(end 108.495084 -294.666162)
		(width 0.1143)
		(layer "In4.Cu")
		(net "P5E_CPU1_P1_TX_DP<12>")
	)
	(segment
		(start 108.51388 -292.396926)
		(end 108.514642 -292.397434)
		(width 0.1143)
		(layer "In4.Cu")
		(net "P5E_CPU1_P1_TX_DP<12>")
	)
	(segment
		(start 108.034328 -289.96132)
		(end 108.0389 -289.964114)
		(width 0.1143)
		(layer "In4.Cu")
		(net "P5E_CPU1_P1_TX_DP<12>")
	)
	(segment
		(start 108.495084 -291.426138)
		(end 108.494322 -291.426646)
		(width 0.1143)
		(layer "In4.Cu")
		(net "P5E_CPU1_P1_TX_DP<12>")
	)
	(segment
		(start 127.866394 -337.854544)
		(end 127.866394 -348.458536)
		(width 0.14224)
		(layer "In4.Cu")
		(net "P5E_CPU1_P1_TX_DP<12>")
	)
	(segment
		(start 117.652292 -314.060078)
		(end 117.652546 -314.060078)
		(width 0.14224)
		(layer "In4.Cu")
		(net "P5E_CPU1_P1_TX_DP<12>")
	)
	(segment
		(start 108.490004 -291.429186)
		(end 108.489242 -291.429694)
		(width 0.1143)
		(layer "In4.Cu")
		(net "P5E_CPU1_P1_TX_DP<12>")
	)
	(segment
		(start 99.301046 -366.134904)
		(end 98.226118 -367.209832)
		(width 0.14224)
		(layer "In4.Cu")
		(net "P5E_CPU1_P1_TX_DP<12>")
	)
	(segment
		(start 111.888524 -360.426)
		(end 101.249226 -364.833154)
		(width 0.14224)
		(layer "In4.Cu")
		(net "P5E_CPU1_P1_TX_DP<12>")
	)
	(segment
		(start 108.5088 -293.038276)
		(end 108.508038 -293.038784)
		(width 0.1143)
		(layer "In4.Cu")
		(net "P5E_CPU1_P1_TX_DP<12>")
	)
	(segment
		(start 127.835152 -348.579948)
		(end 126.82728 -350.408748)
		(width 0.14224)
		(layer "In4.Cu")
		(net "P5E_CPU1_P1_TX_DP<12>")
	)
	(segment
		(start 108.5088 -290.77412)
		(end 108.511594 -290.775644)
		(width 0.1143)
		(layer "In4.Cu")
		(net "P5E_CPU1_P1_TX_DP<12>")
	)
	(segment
		(start 108.489242 -291.429694)
		(end 108.486956 -291.430964)
		(width 0.1143)
		(layer "In4.Cu")
		(net "P5E_CPU1_P1_TX_DP<12>")
	)
	(segment
		(start 108.0389 -289.964114)
		(end 108.068618 -289.981386)
		(width 0.1143)
		(layer "In4.Cu")
		(net "P5E_CPU1_P1_TX_DP<12>")
	)
	(segment
		(start 108.508038 -294.013636)
		(end 108.5088 -294.014144)
		(width 0.1143)
		(layer "In4.Cu")
		(net "P5E_CPU1_P1_TX_DP<12>")
	)
	(segment
		(start 108.483654 -294.67302)
		(end 108.48213 -294.673782)
		(width 0.1143)
		(layer "In4.Cu")
		(net "P5E_CPU1_P1_TX_DP<12>")
	)
	(segment
		(start 108.508038 -291.418772)
		(end 108.507022 -291.41928)
		(width 0.1143)
		(layer "In4.Cu")
		(net "P5E_CPU1_P1_TX_DP<12>")
	)
	(segment
		(start 108.502196 -294.662098)
		(end 108.500418 -294.663114)
		(width 0.1143)
		(layer "In4.Cu")
		(net "P5E_CPU1_P1_TX_DP<12>")
	)
	(segment
		(start 108.468922 -290.750752)
		(end 108.47578 -290.754816)
		(width 0.1143)
		(layer "In4.Cu")
		(net "P5E_CPU1_P1_TX_DP<12>")
	)
	(segment
		(start 108.507022 -291.41928)
		(end 108.505498 -291.420296)
		(width 0.1143)
		(layer "In4.Cu")
		(net "P5E_CPU1_P1_TX_DP<12>")
	)
	(segment
		(start 108.476542 -290.755324)
		(end 108.508038 -290.773612)
		(width 0.1143)
		(layer "In4.Cu")
		(net "P5E_CPU1_P1_TX_DP<12>")
	)
	(segment
		(start 108.515912 -294.018208)
		(end 108.518452 -294.019478)
		(width 0.1143)
		(layer "In4.Cu")
		(net "P5E_CPU1_P1_TX_DP<12>")
	)
	(segment
		(start 108.498894 -291.424106)
		(end 108.496354 -291.425376)
		(width 0.1143)
		(layer "In4.Cu")
		(net "P5E_CPU1_P1_TX_DP<12>")
	)
	(segment
		(start 108.47578 -292.374828)
		(end 108.476542 -292.375336)
		(width 0.1143)
		(layer "In4.Cu")
		(net "P5E_CPU1_P1_TX_DP<12>")
	)
	(segment
		(start 97.957132 -367.85931)
		(end 97.957132 -368.7445)
		(width 0.14224)
		(layer "In4.Cu")
		(net "P5E_CPU1_P1_TX_DP<12>")
	)
	(segment
		(start 106.738928 -287.856422)
		(end 106.821732 -287.939226)
		(width 0.1143)
		(layer "In4.Cu")
		(net "P5E_CPU1_P1_TX_DP<12>")
	)
	(segment
		(start 108.514642 -294.017446)
		(end 108.515912 -294.018208)
		(width 0.1143)
		(layer "In4.Cu")
		(net "P5E_CPU1_P1_TX_DP<12>")
	)
	(segment
		(start 108.5088 -292.394132)
		(end 108.511594 -292.395656)
		(width 0.1143)
		(layer "In4.Cu")
		(net "P5E_CPU1_P1_TX_DP<12>")
	)
	(segment
		(start 108.51388 -294.016938)
		(end 108.514642 -294.017446)
		(width 0.1143)
		(layer "In4.Cu")
		(net "P5E_CPU1_P1_TX_DP<12>")
	)
	(segment
		(start 108.468922 -293.990776)
		(end 108.47578 -293.99484)
		(width 0.1143)
		(layer "In4.Cu")
		(net "P5E_CPU1_P1_TX_DP<12>")
	)
	(segment
		(start 108.495084 -293.04615)
		(end 108.494322 -293.046658)
		(width 0.1143)
		(layer "In4.Cu")
		(net "P5E_CPU1_P1_TX_DP<12>")
	)
	(segment
		(start 108.511594 -293.036752)
		(end 108.5088 -293.038276)
		(width 0.1143)
		(layer "In4.Cu")
		(net "P5E_CPU1_P1_TX_DP<12>")
	)
	(segment
		(start 106.440986 -287.856422)
		(end 106.738928 -287.856422)
		(width 0.1143)
		(layer "In4.Cu")
		(net "P5E_CPU1_P1_TX_DP<12>")
	)
	(segment
		(start 108.518452 -294.019478)
		(end 108.539788 -294.031924)
		(width 0.1143)
		(layer "In4.Cu")
		(net "P5E_CPU1_P1_TX_DP<12>")
	)
	(segment
		(start 108.498894 -293.044118)
		(end 108.496354 -293.045388)
		(width 0.1143)
		(layer "In4.Cu")
		(net "P5E_CPU1_P1_TX_DP<12>")
	)
	(segment
		(start 108.22559 -295.146222)
		(end 108.22559 -295.48328)
		(width 0.1143)
		(layer "In4.Cu")
		(net "P5E_CPU1_P1_TX_DP<12>")
	)
	(segment
		(start 97.957132 -368.7445)
		(end 97.666302 -369.03533)
		(width 0.14224)
		(layer "In4.Cu")
		(net "P5E_CPU1_P1_TX_DP<12>")
	)
	(segment
		(start 126.742444 -350.501204)
		(end 111.888524 -360.426)
		(width 0.14224)
		(layer "In4.Cu")
		(net "P5E_CPU1_P1_TX_DP<12>")
	)
	(segment
		(start 108.489242 -294.669718)
		(end 108.486956 -294.670988)
		(width 0.1143)
		(layer "In4.Cu")
		(net "P5E_CPU1_P1_TX_DP<12>")
	)
	(segment
		(start 113.45164 -308.941978)
		(end 117.652292 -314.060078)
		(width 0.14224)
		(layer "In4.Cu")
		(net "P5E_CPU1_P1_TX_DP<12>")
	)
	(segment
		(start 108.489242 -293.049706)
		(end 108.486956 -293.050976)
		(width 0.1143)
		(layer "In4.Cu")
		(net "P5E_CPU1_P1_TX_DP<12>")
	)
	(segment
		(start 108.47578 -290.754816)
		(end 108.476542 -290.755324)
		(width 0.1143)
		(layer "In4.Cu")
		(net "P5E_CPU1_P1_TX_DP<12>")
	)
	(segment
		(start 108.210858 -298.881038)
		(end 110.627922 -304.71618)
		(width 0.14224)
		(layer "In4.Cu")
		(net "P5E_CPU1_P1_TX_DP<12>")
	)
	(segment
		(start 108.5088 -291.418264)
		(end 108.508038 -291.418772)
		(width 0.1143)
		(layer "In4.Cu")
		(net "P5E_CPU1_P1_TX_DP<12>")
	)
	(segment
		(start 108.483654 -293.053008)
		(end 108.48213 -293.05377)
		(width 0.1143)
		(layer "In4.Cu")
		(net "P5E_CPU1_P1_TX_DP<12>")
	)
	(segment
		(start 108.494322 -294.66667)
		(end 108.490004 -294.66921)
		(width 0.1143)
		(layer "In4.Cu")
		(net "P5E_CPU1_P1_TX_DP<12>")
	)
	(segment
		(start 108.476542 -292.375336)
		(end 108.508038 -292.393624)
		(width 0.1143)
		(layer "In4.Cu")
		(net "P5E_CPU1_P1_TX_DP<12>")
	)
	(segment
		(start 108.502196 -293.042086)
		(end 108.500418 -293.043102)
		(width 0.1143)
		(layer "In4.Cu")
		(net "P5E_CPU1_P1_TX_DP<12>")
	)
	(segment
		(start 117.652546 -314.060078)
		(end 121.853198 -319.177924)
		(width 0.14224)
		(layer "In4.Cu")
		(net "P5E_CPU1_P1_TX_DP<12>")
	)
	(segment
		(start 108.512356 -293.036244)
		(end 108.511594 -293.036752)
		(width 0.1143)
		(layer "In4.Cu")
		(net "P5E_CPU1_P1_TX_DP<12>")
	)
	(segment
		(start 108.512356 -290.776152)
		(end 108.51388 -290.776914)
		(width 0.1143)
		(layer "In4.Cu")
		(net "P5E_CPU1_P1_TX_DP<12>")
	)
	(segment
		(start 108.512356 -291.416232)
		(end 108.511594 -291.41674)
		(width 0.1143)
		(layer "In4.Cu")
		(net "P5E_CPU1_P1_TX_DP<12>")
	)
	(segment
		(start 108.486956 -293.050976)
		(end 108.483654 -293.053008)
		(width 0.1143)
		(layer "In4.Cu")
		(net "P5E_CPU1_P1_TX_DP<12>")
	)
	(segment
		(start 108.505498 -293.040308)
		(end 108.504482 -293.040816)
		(width 0.1143)
		(layer "In4.Cu")
		(net "P5E_CPU1_P1_TX_DP<12>")
	)
	(segment
		(start 108.17987 -295.529)
		(end 108.17987 -295.557448)
		(width 0.1143)
		(layer "In4.Cu")
		(net "P5E_CPU1_P1_TX_DP<12>")
	)
	(segment
		(start 108.498894 -294.66413)
		(end 108.496354 -294.6654)
		(width 0.1143)
		(layer "In4.Cu")
		(net "P5E_CPU1_P1_TX_DP<12>")
	)
	(segment
		(start 108.48213 -293.05377)
		(end 108.468922 -293.061644)
		(width 0.1143)
		(layer "In4.Cu")
		(net "P5E_CPU1_P1_TX_DP<12>")
	)
	(segment
		(start 108.476542 -293.995348)
		(end 108.508038 -294.013636)
		(width 0.1143)
		(layer "In4.Cu")
		(net "P5E_CPU1_P1_TX_DP<12>")
	)
	(segment
		(start 108.503212 -294.66159)
		(end 108.502196 -294.662098)
		(width 0.1143)
		(layer "In4.Cu")
		(net "P5E_CPU1_P1_TX_DP<12>")
	)
	(segment
		(start 108.511594 -294.656764)
		(end 108.5088 -294.658288)
		(width 0.1143)
		(layer "In4.Cu")
		(net "P5E_CPU1_P1_TX_DP<12>")
	)
	(segment
		(start 108.539788 -294.640508)
		(end 108.512356 -294.656256)
		(width 0.1143)
		(layer "In4.Cu")
		(net "P5E_CPU1_P1_TX_DP<12>")
	)
	(segment
		(start 108.495084 -294.666162)
		(end 108.494322 -294.66667)
		(width 0.1143)
		(layer "In4.Cu")
		(net "P5E_CPU1_P1_TX_DP<12>")
	)
	(segment
		(start 108.47578 -293.99484)
		(end 108.476542 -293.995348)
		(width 0.1143)
		(layer "In4.Cu")
		(net "P5E_CPU1_P1_TX_DP<12>")
	)
	(segment
		(start 108.508038 -292.393624)
		(end 108.5088 -292.394132)
		(width 0.1143)
		(layer "In4.Cu")
		(net "P5E_CPU1_P1_TX_DP<12>")
	)
	(segment
		(start 108.494322 -291.426646)
		(end 108.490004 -291.429186)
		(width 0.1143)
		(layer "In4.Cu")
		(net "P5E_CPU1_P1_TX_DP<12>")
	)
	(segment
		(start 121.853198 -319.177924)
		(end 123.238514 -321.868292)
		(width 0.14224)
		(layer "In4.Cu")
		(net "P5E_CPU1_P1_TX_DP<12>")
	)
	(segment
		(start 108.17987 -295.557448)
		(end 108.17987 -298.724574)
		(width 0.14224)
		(layer "In4.Cu")
		(net "P5E_CPU1_P1_TX_DP<12>")
	)
	(segment
		(start 108.51388 -290.776914)
		(end 108.514642 -290.777422)
		(width 0.1143)
		(layer "In4.Cu")
		(net "P5E_CPU1_P1_TX_DP<12>")
	)
	(segment
		(start 108.486956 -294.670988)
		(end 108.483654 -294.67302)
		(width 0.1143)
		(layer "In4.Cu")
		(net "P5E_CPU1_P1_TX_DP<12>")
	)
	(segment
		(start 108.512356 -292.396164)
		(end 108.51388 -292.396926)
		(width 0.1143)
		(layer "In4.Cu")
		(net "P5E_CPU1_P1_TX_DP<12>")
	)
	(segment
		(start 108.500418 -294.663114)
		(end 108.498894 -294.66413)
		(width 0.1143)
		(layer "In4.Cu")
		(net "P5E_CPU1_P1_TX_DP<12>")
	)
	(segment
		(start 108.514642 -290.777422)
		(end 108.515912 -290.778184)
		(width 0.1143)
		(layer "In4.Cu")
		(net "P5E_CPU1_P1_TX_DP<12>")
	)
	(segment
		(start 108.511594 -294.015668)
		(end 108.512356 -294.016176)
		(width 0.1143)
		(layer "In4.Cu")
		(net "P5E_CPU1_P1_TX_DP<12>")
	)
	(segment
		(start 108.468922 -292.370764)
		(end 108.47578 -292.374828)
		(width 0.1143)
		(layer "In4.Cu")
		(net "P5E_CPU1_P1_TX_DP<12>")
	)
	(segment
		(start 108.539788 -293.020496)
		(end 108.512356 -293.036244)
		(width 0.1143)
		(layer "In4.Cu")
		(net "P5E_CPU1_P1_TX_DP<12>")
	)
	(segment
		(start 108.503212 -291.421566)
		(end 108.502196 -291.422074)
		(width 0.1143)
		(layer "In4.Cu")
		(net "P5E_CPU1_P1_TX_DP<12>")
	)
	(segment
		(start 108.496354 -293.045388)
		(end 108.495084 -293.04615)
		(width 0.1143)
		(layer "In4.Cu")
		(net "P5E_CPU1_P1_TX_DP<12>")
	)
	(segment
		(start 108.504482 -291.420804)
		(end 108.503212 -291.421566)
		(width 0.1143)
		(layer "In4.Cu")
		(net "P5E_CPU1_P1_TX_DP<12>")
	)
	(segment
		(start 108.507022 -293.039292)
		(end 108.505498 -293.040308)
		(width 0.1143)
		(layer "In4.Cu")
		(net "P5E_CPU1_P1_TX_DP<12>")
	)
	(segment
		(start 108.539788 -291.400484)
		(end 108.512356 -291.416232)
		(width 0.1143)
		(layer "In4.Cu")
		(net "P5E_CPU1_P1_TX_DP<12>")
	)
	(segment
		(start 108.515912 -292.398196)
		(end 108.518452 -292.399466)
		(width 0.1143)
		(layer "In4.Cu")
		(net "P5E_CPU1_P1_TX_DP<12>")
	)
	(segment
		(start 108.490004 -294.66921)
		(end 108.489242 -294.669718)
		(width 0.1143)
		(layer "In4.Cu")
		(net "P5E_CPU1_P1_TX_DP<12>")
	)
	(segment
		(start 108.22559 -295.48328)
		(end 108.17987 -295.529)
		(width 0.1143)
		(layer "In4.Cu")
		(net "P5E_CPU1_P1_TX_DP<12>")
	)
	(segment
		(start 108.508038 -294.658796)
		(end 108.507022 -294.659304)
		(width 0.1143)
		(layer "In4.Cu")
		(net "P5E_CPU1_P1_TX_DP<12>")
	)
	(segment
		(start 108.511594 -290.775644)
		(end 108.512356 -290.776152)
		(width 0.1143)
		(layer "In4.Cu")
		(net "P5E_CPU1_P1_TX_DP<12>")
	)
	(segment
		(start 108.503212 -293.041578)
		(end 108.502196 -293.042086)
		(width 0.1143)
		(layer "In4.Cu")
		(net "P5E_CPU1_P1_TX_DP<12>")
	)
	(segment
		(start 123.238514 -321.868292)
		(end 126.981458 -332.917292)
		(width 0.14224)
		(layer "In4.Cu")
		(net "P5E_CPU1_P1_TX_DP<12>")
	)
	(segment
		(start 108.504482 -294.660828)
		(end 108.503212 -294.66159)
		(width 0.1143)
		(layer "In4.Cu")
		(net "P5E_CPU1_P1_TX_DP<12>")
	)
	(segment
		(start 108.505498 -294.66032)
		(end 108.504482 -294.660828)
		(width 0.1143)
		(layer "In4.Cu")
		(net "P5E_CPU1_P1_TX_DP<12>")
	)
	(segment
		(start 108.496354 -291.425376)
		(end 108.495084 -291.426138)
		(width 0.1143)
		(layer "In4.Cu")
		(net "P5E_CPU1_P1_TX_DP<12>")
	)
	(segment
		(start 108.494322 -293.046658)
		(end 108.490004 -293.049198)
		(width 0.1143)
		(layer "In4.Cu")
		(net "P5E_CPU1_P1_TX_DP<12>")
	)
	(segment
		(start 108.512356 -294.016176)
		(end 108.51388 -294.016938)
		(width 0.1143)
		(layer "In4.Cu")
		(net "P5E_CPU1_P1_TX_DP<12>")
	)
	(segment
		(start 108.48213 -291.433758)
		(end 108.468922 -291.441632)
		(width 0.1143)
		(layer "In4.Cu")
		(net "P5E_CPU1_P1_TX_DP<12>")
	)
	(segment
		(start 108.514642 -292.397434)
		(end 108.515912 -292.398196)
		(width 0.1143)
		(layer "In4.Cu")
		(net "P5E_CPU1_P1_TX_DP<12>")
	)
	(segment
		(start 108.500418 -291.42309)
		(end 108.498894 -291.424106)
		(width 0.1143)
		(layer "In4.Cu")
		(net "P5E_CPU1_P1_TX_DP<12>")
	)
	(segment
		(start 108.512356 -294.656256)
		(end 108.511594 -294.656764)
		(width 0.1143)
		(layer "In4.Cu")
		(net "P5E_CPU1_P1_TX_DP<12>")
	)
	(segment
		(start 108.518452 -290.779454)
		(end 108.539788 -290.7919)
		(width 0.1143)
		(layer "In4.Cu")
		(net "P5E_CPU1_P1_TX_DP<12>")
	)
	(segment
		(start 108.5088 -294.658288)
		(end 108.508038 -294.658796)
		(width 0.1143)
		(layer "In4.Cu")
		(net "P5E_CPU1_P1_TX_DP<12>")
	)
	(segment
		(start 108.5088 -294.014144)
		(end 108.511594 -294.015668)
		(width 0.1143)
		(layer "In4.Cu")
		(net "P5E_CPU1_P1_TX_DP<12>")
	)
	(segment
		(start 107.098084 -288.343848)
		(end 107.131612 -288.363406)
		(width 0.1143)
		(layer "In4.Cu")
		(net "P5E_CPU1_P1_TX_DP<12>")
	)
	(segment
		(start 108.511594 -292.395656)
		(end 108.512356 -292.396164)
		(width 0.1143)
		(layer "In4.Cu")
		(net "P5E_CPU1_P1_TX_DP<12>")
	)
	(segment
		(start 108.48213 -294.673782)
		(end 108.468922 -294.681656)
		(width 0.1143)
		(layer "In4.Cu")
		(net "P5E_CPU1_P1_TX_DP<12>")
	)
	(segment
		(start 108.515912 -290.778184)
		(end 108.518452 -290.779454)
		(width 0.1143)
		(layer "In4.Cu")
		(net "P5E_CPU1_P1_TX_DP<12>")
	)
	(segment
		(start 108.504482 -293.040816)
		(end 108.503212 -293.041578)
		(width 0.1143)
		(layer "In4.Cu")
		(net "P5E_CPU1_P1_TX_DP<12>")
	)
	(segment
		(start 107.058968 -288.320988)
		(end 107.098084 -288.343848)
		(width 0.1143)
		(layer "In4.Cu")
		(net "P5E_CPU1_P1_TX_DP<12>")
	)
	(segment
		(start 108.507022 -294.659304)
		(end 108.505498 -294.66032)
		(width 0.1143)
		(layer "In4.Cu")
		(net "P5E_CPU1_P1_TX_DP<12>")
	)
	(segment
		(start 108.508038 -290.773612)
		(end 108.5088 -290.77412)
		(width 0.1143)
		(layer "In4.Cu")
		(net "P5E_CPU1_P1_TX_DP<12>")
	)
	(segment
		(start 127.012954 -333.03972)
		(end 127.854964 -337.728814)
		(width 0.14224)
		(layer "In4.Cu")
		(net "P5E_CPU1_P1_TX_DP<12>")
	)
	(segment
		(start 110.627922 -304.71618)
		(end 113.45164 -308.941978)
		(width 0.14224)
		(layer "In4.Cu")
		(net "P5E_CPU1_P1_TX_DP<12>")
	)
	(segment
		(start 108.490004 -293.049198)
		(end 108.489242 -293.049706)
		(width 0.1143)
		(layer "In4.Cu")
		(net "P5E_CPU1_P1_TX_DP<12>")
	)
	(arc
		(start 107.570016 -289.15487)
		(mid 107.706712 -289.291226)
		(end 107.756706 -289.477704)
		(width 0.1143)
		(layer "In4.Cu")
		(net "P5E_CPU1_P1_TX_DP<12>")
	)
	(arc
		(start 98.226118 -367.209832)
		(mid 98.027012 -367.507815)
		(end 97.957132 -367.85931)
		(width 0.14224)
		(layer "In4.Cu")
		(net "P5E_CPU1_P1_TX_DP<12>")
	)
	(arc
		(start 108.22559 -290.286186)
		(mid 108.290105 -290.548405)
		(end 108.468922 -290.750752)
		(width 0.1143)
		(layer "In4.Cu")
		(net "P5E_CPU1_P1_TX_DP<12>")
	)
	(arc
		(start 108.539788 -292.411912)
		(mid 108.695716 -292.716204)
		(end 108.539788 -293.020496)
		(width 0.1143)
		(layer "In4.Cu")
		(net "P5E_CPU1_P1_TX_DP<12>")
	)
	(arc
		(start 108.468922 -291.441632)
		(mid 108.225595 -291.906198)
		(end 108.468922 -292.370764)
		(width 0.1143)
		(layer "In4.Cu")
		(net "P5E_CPU1_P1_TX_DP<12>")
	)
	(arc
		(start 127.854964 -337.728814)
		(mid 127.863462 -337.791426)
		(end 127.866394 -337.854544)
		(width 0.14224)
		(layer "In4.Cu")
		(net "P5E_CPU1_P1_TX_DP<12>")
	)
	(arc
		(start 107.756706 -289.477704)
		(mid 107.831043 -289.756526)
		(end 108.034328 -289.96132)
		(width 0.1143)
		(layer "In4.Cu")
		(net "P5E_CPU1_P1_TX_DP<12>")
	)
	(arc
		(start 108.068618 -289.981386)
		(mid 108.184045 -290.114762)
		(end 108.22559 -290.286186)
		(width 0.1143)
		(layer "In4.Cu")
		(net "P5E_CPU1_P1_TX_DP<12>")
	)
	(arc
		(start 108.17987 -298.724574)
		(mid 108.187663 -298.804332)
		(end 108.210858 -298.881038)
		(width 0.14224)
		(layer "In4.Cu")
		(net "P5E_CPU1_P1_TX_DP<12>")
	)
	(arc
		(start 108.539788 -294.031924)
		(mid 108.695716 -294.336216)
		(end 108.539788 -294.640508)
		(width 0.1143)
		(layer "In4.Cu")
		(net "P5E_CPU1_P1_TX_DP<12>")
	)
	(arc
		(start 106.825542 -287.962086)
		(mid 106.906975 -288.164484)
		(end 107.058968 -288.320988)
		(width 0.1143)
		(layer "In4.Cu")
		(net "P5E_CPU1_P1_TX_DP<12>")
	)
	(arc
		(start 108.325158 -294.825674)
		(mid 108.251044 -294.978388)
		(end 108.22559 -295.146222)
		(width 0.1143)
		(layer "In4.Cu")
		(net "P5E_CPU1_P1_TX_DP<12>")
	)
	(arc
		(start 108.468922 -293.061644)
		(mid 108.225595 -293.52621)
		(end 108.468922 -293.990776)
		(width 0.1143)
		(layer "In4.Cu")
		(net "P5E_CPU1_P1_TX_DP<12>")
	)
	(arc
		(start 106.821732 -287.939226)
		(mid 106.82352 -287.950675)
		(end 106.825542 -287.962086)
		(width 0.1143)
		(layer "In4.Cu")
		(net "P5E_CPU1_P1_TX_DP<12>")
	)
	(arc
		(start 126.981458 -332.917292)
		(mid 126.999495 -332.977918)
		(end 127.012954 -333.03972)
		(width 0.14224)
		(layer "In4.Cu")
		(net "P5E_CPU1_P1_TX_DP<12>")
	)
	(arc
		(start 126.82728 -350.408748)
		(mid 126.790404 -350.460058)
		(end 126.742444 -350.501204)
		(width 0.14224)
		(layer "In4.Cu")
		(net "P5E_CPU1_P1_TX_DP<12>")
	)
	(arc
		(start 127.866394 -348.458536)
		(mid 127.858449 -348.521214)
		(end 127.835152 -348.579948)
		(width 0.14224)
		(layer "In4.Cu")
		(net "P5E_CPU1_P1_TX_DP<12>")
	)
	(arc
		(start 107.28579 -288.666174)
		(mid 107.351026 -288.929765)
		(end 107.531662 -289.132518)
		(width 0.1143)
		(layer "In4.Cu")
		(net "P5E_CPU1_P1_TX_DP<12>")
	)
	(arc
		(start 107.131612 -288.363406)
		(mid 107.245019 -288.496295)
		(end 107.28579 -288.666174)
		(width 0.1143)
		(layer "In4.Cu")
		(net "P5E_CPU1_P1_TX_DP<12>")
	)
	(arc
		(start 108.539788 -290.7919)
		(mid 108.695716 -291.096192)
		(end 108.539788 -291.400484)
		(width 0.1143)
		(layer "In4.Cu")
		(net "P5E_CPU1_P1_TX_DP<12>")
	)
	(arc
		(start 108.468922 -294.681656)
		(mid 108.390499 -294.747137)
		(end 108.325158 -294.825674)
		(width 0.1143)
		(layer "In4.Cu")
		(net "P5E_CPU1_P1_TX_DP<12>")
	)
	(segment
		(start 96.235012 -372.47322)
		(end 96.235012 -371.76964)
		(width 0.12954)
		(layer "F.Cu")
		(net "P5E_CPU1_P1_TX_DP<11>")
	)
	(segment
		(start 96.235012 -371.76964)
		(end 95.964502 -371.49913)
		(width 0.12954)
		(layer "F.Cu")
		(net "P5E_CPU1_P1_TX_DP<11>")
	)
	(segment
		(start 95.939102 -372.76913)
		(end 96.235012 -372.47322)
		(width 0.12954)
		(layer "F.Cu")
		(net "P5E_CPU1_P1_TX_DP<11>")
	)
	(segment
		(start 106.907838 -290.830254)
		(end 106.440986 -291.096192)
		(width 0.12954)
		(layer "F.Cu")
		(net "P5E_CPU1_P1_TX_DP<11>")
	)
	(segment
		(start 106.440986 -291.096192)
		(end 106.738928 -291.096192)
		(width 0.1143)
		(layer "In4.Cu")
		(net "P5E_CPU1_P1_TX_DP<11>")
	)
	(segment
		(start 107.045252 -298.503086)
		(end 109.807756 -305.172872)
		(width 0.14224)
		(layer "In4.Cu")
		(net "P5E_CPU1_P1_TX_DP<11>")
	)
	(segment
		(start 107.59694 -294.0304)
		(end 107.599226 -294.032178)
		(width 0.1143)
		(layer "In4.Cu")
		(net "P5E_CPU1_P1_TX_DP<11>")
	)
	(segment
		(start 126.910592 -337.809078)
		(end 126.910592 -346.93479)
		(width 0.14224)
		(layer "In4.Cu")
		(net "P5E_CPU1_P1_TX_DP<11>")
	)
	(segment
		(start 106.980736 -296.345102)
		(end 107.022646 -296.387012)
		(width 0.1143)
		(layer "In4.Cu")
		(net "P5E_CPU1_P1_TX_DP<11>")
	)
	(segment
		(start 107.567984 -293.038784)
		(end 107.546648 -293.05123)
		(width 0.1143)
		(layer "In4.Cu")
		(net "P5E_CPU1_P1_TX_DP<11>")
	)
	(segment
		(start 107.60329 -294.035226)
		(end 107.606592 -294.037512)
		(width 0.1143)
		(layer "In4.Cu")
		(net "P5E_CPU1_P1_TX_DP<11>")
	)
	(segment
		(start 107.059984 -296.538396)
		(end 107.014264 -296.584116)
		(width 0.1143)
		(layer "In4.Cu")
		(net "P5E_CPU1_P1_TX_DP<11>")
	)
	(segment
		(start 100.700586 -364.050834)
		(end 97.91446 -365.9124)
		(width 0.14224)
		(layer "In4.Cu")
		(net "P5E_CPU1_P1_TX_DP<11>")
	)
	(segment
		(start 126.102618 -333.248762)
		(end 126.899416 -337.683348)
		(width 0.14224)
		(layer "In4.Cu")
		(net "P5E_CPU1_P1_TX_DP<11>")
	)
	(segment
		(start 107.129834 -291.601906)
		(end 107.131612 -291.603176)
		(width 0.1143)
		(layer "In4.Cu")
		(net "P5E_CPU1_P1_TX_DP<11>")
	)
	(segment
		(start 121.000266 -319.609978)
		(end 122.279664 -322.057014)
		(width 0.14224)
		(layer "In4.Cu")
		(net "P5E_CPU1_P1_TX_DP<11>")
	)
	(segment
		(start 122.279664 -322.057014)
		(end 126.081536 -333.16799)
		(width 0.14224)
		(layer "In4.Cu")
		(net "P5E_CPU1_P1_TX_DP<11>")
	)
	(segment
		(start 107.116626 -295.458896)
		(end 107.106212 -295.465754)
		(width 0.1143)
		(layer "In4.Cu")
		(net "P5E_CPU1_P1_TX_DP<11>")
	)
	(segment
		(start 107.059984 -296.476928)
		(end 107.059984 -296.538396)
		(width 0.1143)
		(layer "In4.Cu")
		(net "P5E_CPU1_P1_TX_DP<11>")
	)
	(segment
		(start 107.567984 -292.393624)
		(end 107.599734 -292.411912)
		(width 0.1143)
		(layer "In4.Cu")
		(net "P5E_CPU1_P1_TX_DP<11>")
	)
	(segment
		(start 107.065826 -291.564822)
		(end 107.066588 -291.56533)
		(width 0.1143)
		(layer "In4.Cu")
		(net "P5E_CPU1_P1_TX_DP<11>")
	)
	(segment
		(start 107.126786 -295.452292)
		(end 107.12577 -295.4528)
		(width 0.1143)
		(layer "In4.Cu")
		(net "P5E_CPU1_P1_TX_DP<11>")
	)
	(segment
		(start 107.12577 -295.4528)
		(end 107.124246 -295.453816)
		(width 0.1143)
		(layer "In4.Cu")
		(net "P5E_CPU1_P1_TX_DP<11>")
	)
	(segment
		(start 126.081536 -333.16799)
		(end 126.081536 -333.167736)
		(width 0.14224)
		(layer "In4.Cu")
		(net "P5E_CPU1_P1_TX_DP<11>")
	)
	(segment
		(start 107.599734 -293.020496)
		(end 107.567984 -293.038784)
		(width 0.1143)
		(layer "In4.Cu")
		(net "P5E_CPU1_P1_TX_DP<11>")
	)
	(segment
		(start 106.738928 -291.096192)
		(end 106.821732 -291.178996)
		(width 0.1143)
		(layer "In4.Cu")
		(net "P5E_CPU1_P1_TX_DP<11>")
	)
	(segment
		(start 107.066588 -291.56533)
		(end 107.098084 -291.583618)
		(width 0.1143)
		(layer "In4.Cu")
		(net "P5E_CPU1_P1_TX_DP<11>")
	)
	(segment
		(start 107.150408 -295.436544)
		(end 107.126786 -295.452292)
		(width 0.1143)
		(layer "In4.Cu")
		(net "P5E_CPU1_P1_TX_DP<11>")
	)
	(segment
		(start 112.681258 -309.472838)
		(end 121.000266 -319.609978)
		(width 0.14224)
		(layer "In4.Cu")
		(net "P5E_CPU1_P1_TX_DP<11>")
	)
	(segment
		(start 109.807756 -305.172872)
		(end 112.681258 -309.472838)
		(width 0.14224)
		(layer "In4.Cu")
		(net "P5E_CPU1_P1_TX_DP<11>")
	)
	(segment
		(start 126.242318 -349.083884)
		(end 125.642878 -349.95485)
		(width 0.14224)
		(layer "In4.Cu")
		(net "P5E_CPU1_P1_TX_DP<11>")
	)
	(segment
		(start 96.255332 -371.2083)
		(end 95.964502 -371.49913)
		(width 0.14224)
		(layer "In4.Cu")
		(net "P5E_CPU1_P1_TX_DP<11>")
	)
	(segment
		(start 107.28579 -291.904166)
		(end 107.28579 -291.906198)
		(width 0.1143)
		(layer "In4.Cu")
		(net "P5E_CPU1_P1_TX_DP<11>")
	)
	(segment
		(start 97.91446 -365.9124)
		(end 96.972882 -366.853978)
		(width 0.14224)
		(layer "In4.Cu")
		(net "P5E_CPU1_P1_TX_DP<11>")
	)
	(segment
		(start 107.531662 -292.372542)
		(end 107.567984 -292.393624)
		(width 0.1143)
		(layer "In4.Cu")
		(net "P5E_CPU1_P1_TX_DP<11>")
	)
	(segment
		(start 107.121706 -295.455086)
		(end 107.116626 -295.458896)
		(width 0.1143)
		(layer "In4.Cu")
		(net "P5E_CPU1_P1_TX_DP<11>")
	)
	(segment
		(start 96.255332 -368.586258)
		(end 96.255332 -371.2083)
		(width 0.14224)
		(layer "In4.Cu")
		(net "P5E_CPU1_P1_TX_DP<11>")
	)
	(segment
		(start 107.599226 -294.032178)
		(end 107.601766 -294.033956)
		(width 0.1143)
		(layer "In4.Cu")
		(net "P5E_CPU1_P1_TX_DP<11>")
	)
	(segment
		(start 107.601766 -294.033956)
		(end 107.60329 -294.035226)
		(width 0.1143)
		(layer "In4.Cu")
		(net "P5E_CPU1_P1_TX_DP<11>")
	)
	(segment
		(start 125.553216 -350.043496)
		(end 110.933484 -359.812336)
		(width 0.14224)
		(layer "In4.Cu")
		(net "P5E_CPU1_P1_TX_DP<11>")
	)
	(segment
		(start 107.098846 -291.584126)
		(end 107.129834 -291.601906)
		(width 0.1143)
		(layer "In4.Cu")
		(net "P5E_CPU1_P1_TX_DP<11>")
	)
	(segment
		(start 107.546648 -294.00119)
		(end 107.59694 -294.0304)
		(width 0.1143)
		(layer "In4.Cu")
		(net "P5E_CPU1_P1_TX_DP<11>")
	)
	(segment
		(start 107.124246 -295.453816)
		(end 107.121706 -295.455086)
		(width 0.1143)
		(layer "In4.Cu")
		(net "P5E_CPU1_P1_TX_DP<11>")
	)
	(segment
		(start 107.599988 -294.638984)
		(end 107.515406 -294.689784)
		(width 0.1143)
		(layer "In4.Cu")
		(net "P5E_CPU1_P1_TX_DP<11>")
	)
	(segment
		(start 110.933484 -359.812336)
		(end 100.700586 -364.050834)
		(width 0.14224)
		(layer "In4.Cu")
		(net "P5E_CPU1_P1_TX_DP<11>")
	)
	(segment
		(start 107.014264 -296.584116)
		(end 107.014264 -296.612564)
		(width 0.1143)
		(layer "In4.Cu")
		(net "P5E_CPU1_P1_TX_DP<11>")
	)
	(segment
		(start 107.058968 -291.560758)
		(end 107.065826 -291.564822)
		(width 0.1143)
		(layer "In4.Cu")
		(net "P5E_CPU1_P1_TX_DP<11>")
	)
	(segment
		(start 107.27309 -295.153842)
		(end 107.27309 -295.207182)
		(width 0.1143)
		(layer "In4.Cu")
		(net "P5E_CPU1_P1_TX_DP<11>")
	)
	(segment
		(start 107.098084 -291.583618)
		(end 107.098846 -291.584126)
		(width 0.1143)
		(layer "In4.Cu")
		(net "P5E_CPU1_P1_TX_DP<11>")
	)
	(segment
		(start 125.553216 -350.043242)
		(end 125.553216 -350.043496)
		(width 0.14224)
		(layer "In4.Cu")
		(net "P5E_CPU1_P1_TX_DP<11>")
	)
	(segment
		(start 107.014264 -296.612564)
		(end 107.014264 -298.346622)
		(width 0.14224)
		(layer "In4.Cu")
		(net "P5E_CPU1_P1_TX_DP<11>")
	)
	(arc
		(start 107.022646 -296.387012)
		(mid 107.050265 -296.428252)
		(end 107.059984 -296.476928)
		(width 0.1143)
		(layer "In4.Cu")
		(net "P5E_CPU1_P1_TX_DP<11>")
	)
	(arc
		(start 125.642878 -349.95485)
		(mid 125.602239 -350.003296)
		(end 125.553216 -350.043242)
		(width 0.14224)
		(layer "In4.Cu")
		(net "P5E_CPU1_P1_TX_DP<11>")
	)
	(arc
		(start 107.014264 -298.346622)
		(mid 107.022057 -298.42638)
		(end 107.045252 -298.503086)
		(width 0.14224)
		(layer "In4.Cu")
		(net "P5E_CPU1_P1_TX_DP<11>")
	)
	(arc
		(start 106.863642 -295.72839)
		(mid 106.860544 -295.735608)
		(end 106.857546 -295.742868)
		(width 0.1143)
		(layer "In4.Cu")
		(net "P5E_CPU1_P1_TX_DP<11>")
	)
	(arc
		(start 107.28579 -291.912802)
		(mid 107.350662 -292.162544)
		(end 107.515406 -292.361112)
		(width 0.1143)
		(layer "In4.Cu")
		(net "P5E_CPU1_P1_TX_DP<11>")
	)
	(arc
		(start 126.899416 -337.683348)
		(mid 126.9078 -337.745965)
		(end 126.910592 -337.809078)
		(width 0.14224)
		(layer "In4.Cu")
		(net "P5E_CPU1_P1_TX_DP<11>")
	)
	(arc
		(start 107.515406 -292.361112)
		(mid 107.523484 -292.366898)
		(end 107.531662 -292.372542)
		(width 0.1143)
		(layer "In4.Cu")
		(net "P5E_CPU1_P1_TX_DP<11>")
	)
	(arc
		(start 96.972882 -366.853978)
		(mid 96.441829 -367.648755)
		(end 96.255332 -368.586258)
		(width 0.14224)
		(layer "In4.Cu")
		(net "P5E_CPU1_P1_TX_DP<11>")
	)
	(arc
		(start 106.821732 -291.178996)
		(mid 106.82352 -291.190445)
		(end 106.825542 -291.201856)
		(width 0.1143)
		(layer "In4.Cu")
		(net "P5E_CPU1_P1_TX_DP<11>")
	)
	(arc
		(start 107.606592 -294.037512)
		(mid 107.755718 -294.339872)
		(end 107.599988 -294.638984)
		(width 0.1143)
		(layer "In4.Cu")
		(net "P5E_CPU1_P1_TX_DP<11>")
	)
	(arc
		(start 107.131612 -291.603176)
		(mid 107.245017 -291.735071)
		(end 107.28579 -291.904166)
		(width 0.1143)
		(layer "In4.Cu")
		(net "P5E_CPU1_P1_TX_DP<11>")
	)
	(arc
		(start 107.515406 -294.689784)
		(mid 107.337282 -294.892074)
		(end 107.27309 -295.153842)
		(width 0.1143)
		(layer "In4.Cu")
		(net "P5E_CPU1_P1_TX_DP<11>")
	)
	(arc
		(start 106.857546 -295.742868)
		(mid 106.828537 -296.062517)
		(end 106.980736 -296.345102)
		(width 0.1143)
		(layer "In4.Cu")
		(net "P5E_CPU1_P1_TX_DP<11>")
	)
	(arc
		(start 107.599734 -292.411912)
		(mid 107.755662 -292.716204)
		(end 107.599734 -293.020496)
		(width 0.1143)
		(layer "In4.Cu")
		(net "P5E_CPU1_P1_TX_DP<11>")
	)
	(arc
		(start 106.960162 -295.585134)
		(mid 106.905501 -295.65245)
		(end 106.863642 -295.72839)
		(width 0.1143)
		(layer "In4.Cu")
		(net "P5E_CPU1_P1_TX_DP<11>")
	)
	(arc
		(start 107.27309 -295.207182)
		(mid 107.2405 -295.337248)
		(end 107.150408 -295.436544)
		(width 0.1143)
		(layer "In4.Cu")
		(net "P5E_CPU1_P1_TX_DP<11>")
	)
	(arc
		(start 107.106212 -295.465754)
		(mid 107.086335 -295.475837)
		(end 107.067096 -295.48709)
		(width 0.1143)
		(layer "In4.Cu")
		(net "P5E_CPU1_P1_TX_DP<11>")
	)
	(arc
		(start 126.910592 -346.93479)
		(mid 126.739647 -348.060088)
		(end 126.242318 -349.083884)
		(width 0.14224)
		(layer "In4.Cu")
		(net "P5E_CPU1_P1_TX_DP<11>")
	)
	(arc
		(start 107.28579 -291.906198)
		(mid 107.28578 -291.9095)
		(end 107.28579 -291.912802)
		(width 0.1143)
		(layer "In4.Cu")
		(net "P5E_CPU1_P1_TX_DP<11>")
	)
	(arc
		(start 106.825542 -291.201856)
		(mid 106.906975 -291.404254)
		(end 107.058968 -291.560758)
		(width 0.1143)
		(layer "In4.Cu")
		(net "P5E_CPU1_P1_TX_DP<11>")
	)
	(arc
		(start 107.067096 -295.48709)
		(mid 107.051075 -295.497487)
		(end 107.0356 -295.50868)
		(width 0.1143)
		(layer "In4.Cu")
		(net "P5E_CPU1_P1_TX_DP<11>")
	)
	(arc
		(start 107.546648 -293.05123)
		(mid 107.273097 -293.52621)
		(end 107.546648 -294.00119)
		(width 0.1143)
		(layer "In4.Cu")
		(net "P5E_CPU1_P1_TX_DP<11>")
	)
	(arc
		(start 107.0356 -295.50868)
		(mid 106.997761 -295.546789)
		(end 106.960162 -295.585134)
		(width 0.1143)
		(layer "In4.Cu")
		(net "P5E_CPU1_P1_TX_DP<11>")
	)
	(arc
		(start 126.081536 -333.167736)
		(mid 126.093609 -333.20785)
		(end 126.102618 -333.248762)
		(width 0.14224)
		(layer "In4.Cu")
		(net "P5E_CPU1_P1_TX_DP<11>")
	)
	(segment
		(start 94.237302 -375.23293)
		(end 94.533212 -374.93702)
		(width 0.12954)
		(layer "F.Cu")
		(net "P5E_CPU1_P1_TX_DP<10>")
	)
	(segment
		(start 94.533212 -374.93702)
		(end 94.533212 -374.23344)
		(width 0.12954)
		(layer "F.Cu")
		(net "P5E_CPU1_P1_TX_DP<10>")
	)
	(segment
		(start 106.907838 -289.210242)
		(end 106.440986 -289.47618)
		(width 0.12954)
		(layer "F.Cu")
		(net "P5E_CPU1_P1_TX_DP<10>")
	)
	(segment
		(start 94.533212 -374.23344)
		(end 94.262702 -373.96293)
		(width 0.12954)
		(layer "F.Cu")
		(net "P5E_CPU1_P1_TX_DP<10>")
	)
	(segment
		(start 98.593656 -363.914436)
		(end 96.207834 -365.508794)
		(width 0.14224)
		(layer "In4.Cu")
		(net "P5E_CPU1_P1_TX_DP<10>")
	)
	(segment
		(start 110.092236 -359.151682)
		(end 98.593656 -363.914436)
		(width 0.14224)
		(layer "In4.Cu")
		(net "P5E_CPU1_P1_TX_DP<10>")
	)
	(segment
		(start 125.96749 -337.906868)
		(end 125.96749 -346.74175)
		(width 0.14224)
		(layer "In4.Cu")
		(net "P5E_CPU1_P1_TX_DP<10>")
	)
	(segment
		(start 106.15803 -291.583618)
		(end 106.158792 -291.584126)
		(width 0.1143)
		(layer "In4.Cu")
		(net "P5E_CPU1_P1_TX_DP<10>")
	)
	(segment
		(start 106.158792 -290.608258)
		(end 106.15803 -290.608766)
		(width 0.1143)
		(layer "In4.Cu")
		(net "P5E_CPU1_P1_TX_DP<10>")
	)
	(segment
		(start 106.160062 -290.607496)
		(end 106.158792 -290.608258)
		(width 0.1143)
		(layer "In4.Cu")
		(net "P5E_CPU1_P1_TX_DP<10>")
	)
	(segment
		(start 106.157014 -290.609274)
		(end 106.15549 -290.61029)
		(width 0.1143)
		(layer "In4.Cu")
		(net "P5E_CPU1_P1_TX_DP<10>")
	)
	(segment
		(start 121.402602 -322.39331)
		(end 125.141736 -333.302102)
		(width 0.14224)
		(layer "In4.Cu")
		(net "P5E_CPU1_P1_TX_DP<10>")
	)
	(segment
		(start 105.916984 -296.07891)
		(end 105.916984 -296.107358)
		(width 0.1143)
		(layer "In4.Cu")
		(net "P5E_CPU1_P1_TX_DP<10>")
	)
	(segment
		(start 106.158792 -291.584126)
		(end 106.161586 -291.58565)
		(width 0.1143)
		(layer "In4.Cu")
		(net "P5E_CPU1_P1_TX_DP<10>")
	)
	(segment
		(start 106.658664 -293.021004)
		(end 106.628184 -293.038784)
		(width 0.1143)
		(layer "In4.Cu")
		(net "P5E_CPU1_P1_TX_DP<10>")
	)
	(segment
		(start 125.173486 -333.424276)
		(end 125.956314 -337.780884)
		(width 0.14224)
		(layer "In4.Cu")
		(net "P5E_CPU1_P1_TX_DP<10>")
	)
	(segment
		(start 106.628184 -293.038784)
		(end 106.589068 -293.061644)
		(width 0.1143)
		(layer "In4.Cu")
		(net "P5E_CPU1_P1_TX_DP<10>")
	)
	(segment
		(start 105.916984 -296.107358)
		(end 105.916984 -298.134786)
		(width 0.14224)
		(layer "In4.Cu")
		(net "P5E_CPU1_P1_TX_DP<10>")
	)
	(segment
		(start 108.983272 -305.618896)
		(end 112.13973 -310.343296)
		(width 0.14224)
		(layer "In4.Cu")
		(net "P5E_CPU1_P1_TX_DP<10>")
	)
	(segment
		(start 94.553532 -373.6721)
		(end 94.262702 -373.96293)
		(width 0.14224)
		(layer "In4.Cu")
		(net "P5E_CPU1_P1_TX_DP<10>")
	)
	(segment
		(start 106.15803 -290.608766)
		(end 106.157014 -290.609274)
		(width 0.1143)
		(layer "In4.Cu")
		(net "P5E_CPU1_P1_TX_DP<10>")
	)
	(segment
		(start 112.13973 -310.343296)
		(end 120.301766 -320.28765)
		(width 0.14224)
		(layer "In4.Cu")
		(net "P5E_CPU1_P1_TX_DP<10>")
	)
	(segment
		(start 106.16565 -291.587936)
		(end 106.18978 -291.601906)
		(width 0.1143)
		(layer "In4.Cu")
		(net "P5E_CPU1_P1_TX_DP<10>")
	)
	(segment
		(start 106.589068 -293.990776)
		(end 106.628184 -294.013636)
		(width 0.1143)
		(layer "In4.Cu")
		(net "P5E_CPU1_P1_TX_DP<10>")
	)
	(segment
		(start 94.553532 -368.604292)
		(end 94.553532 -373.6721)
		(width 0.14224)
		(layer "In4.Cu")
		(net "P5E_CPU1_P1_TX_DP<10>")
	)
	(segment
		(start 106.628184 -294.013636)
		(end 106.658664 -294.031416)
		(width 0.1143)
		(layer "In4.Cu")
		(net "P5E_CPU1_P1_TX_DP<10>")
	)
	(segment
		(start 106.278426 -295.467532)
		(end 106.055922 -295.690036)
		(width 0.1143)
		(layer "In4.Cu")
		(net "P5E_CPU1_P1_TX_DP<10>")
	)
	(segment
		(start 106.15549 -290.61029)
		(end 106.118914 -290.631626)
		(width 0.1143)
		(layer "In4.Cu")
		(net "P5E_CPU1_P1_TX_DP<10>")
	)
	(segment
		(start 106.163872 -291.58692)
		(end 106.164634 -291.587428)
		(width 0.1143)
		(layer "In4.Cu")
		(net "P5E_CPU1_P1_TX_DP<10>")
	)
	(segment
		(start 106.162348 -291.586158)
		(end 106.163872 -291.58692)
		(width 0.1143)
		(layer "In4.Cu")
		(net "P5E_CPU1_P1_TX_DP<10>")
	)
	(segment
		(start 106.18978 -290.590478)
		(end 106.160062 -290.607496)
		(width 0.1143)
		(layer "In4.Cu")
		(net "P5E_CPU1_P1_TX_DP<10>")
	)
	(segment
		(start 106.589068 -292.370764)
		(end 106.628184 -292.393624)
		(width 0.1143)
		(layer "In4.Cu")
		(net "P5E_CPU1_P1_TX_DP<10>")
	)
	(segment
		(start 105.962704 -296.03319)
		(end 105.916984 -296.07891)
		(width 0.1143)
		(layer "In4.Cu")
		(net "P5E_CPU1_P1_TX_DP<10>")
	)
	(segment
		(start 106.164634 -291.587428)
		(end 106.16565 -291.587936)
		(width 0.1143)
		(layer "In4.Cu")
		(net "P5E_CPU1_P1_TX_DP<10>")
	)
	(segment
		(start 121.402094 -322.392294)
		(end 121.402602 -322.39331)
		(width 0.14224)
		(layer "In4.Cu")
		(net "P5E_CPU1_P1_TX_DP<10>")
	)
	(segment
		(start 106.738928 -289.47618)
		(end 106.808778 -289.54603)
		(width 0.1143)
		(layer "In4.Cu")
		(net "P5E_CPU1_P1_TX_DP<10>")
	)
	(segment
		(start 106.628184 -292.393624)
		(end 106.658664 -292.411404)
		(width 0.1143)
		(layer "In4.Cu")
		(net "P5E_CPU1_P1_TX_DP<10>")
	)
	(segment
		(start 106.658664 -294.641016)
		(end 106.628184 -294.658796)
		(width 0.1143)
		(layer "In4.Cu")
		(net "P5E_CPU1_P1_TX_DP<10>")
	)
	(segment
		(start 106.628184 -289.79876)
		(end 106.589068 -289.82162)
		(width 0.1143)
		(layer "In4.Cu")
		(net "P5E_CPU1_P1_TX_DP<10>")
	)
	(segment
		(start 120.301766 -320.28765)
		(end 121.402094 -322.392294)
		(width 0.14224)
		(layer "In4.Cu")
		(net "P5E_CPU1_P1_TX_DP<10>")
	)
	(segment
		(start 106.440986 -289.47618)
		(end 106.738928 -289.47618)
		(width 0.1143)
		(layer "In4.Cu")
		(net "P5E_CPU1_P1_TX_DP<10>")
	)
	(segment
		(start 106.628184 -294.658796)
		(end 106.589068 -294.681656)
		(width 0.1143)
		(layer "In4.Cu")
		(net "P5E_CPU1_P1_TX_DP<10>")
	)
	(segment
		(start 106.126534 -291.56533)
		(end 106.15803 -291.583618)
		(width 0.1143)
		(layer "In4.Cu")
		(net "P5E_CPU1_P1_TX_DP<10>")
	)
	(segment
		(start 125.942852 -346.86494)
		(end 124.996702 -349.148908)
		(width 0.14224)
		(layer "In4.Cu")
		(net "P5E_CPU1_P1_TX_DP<10>")
	)
	(segment
		(start 105.947972 -298.29125)
		(end 108.983272 -305.618896)
		(width 0.14224)
		(layer "In4.Cu")
		(net "P5E_CPU1_P1_TX_DP<10>")
	)
	(segment
		(start 124.917454 -349.245428)
		(end 110.092236 -359.151682)
		(width 0.14224)
		(layer "In4.Cu")
		(net "P5E_CPU1_P1_TX_DP<10>")
	)
	(segment
		(start 106.118914 -291.560758)
		(end 106.125772 -291.564822)
		(width 0.1143)
		(layer "In4.Cu")
		(net "P5E_CPU1_P1_TX_DP<10>")
	)
	(segment
		(start 106.658664 -289.78098)
		(end 106.628184 -289.79876)
		(width 0.1143)
		(layer "In4.Cu")
		(net "P5E_CPU1_P1_TX_DP<10>")
	)
	(segment
		(start 106.125772 -291.564822)
		(end 106.126534 -291.56533)
		(width 0.1143)
		(layer "In4.Cu")
		(net "P5E_CPU1_P1_TX_DP<10>")
	)
	(segment
		(start 105.962704 -295.914826)
		(end 105.962704 -296.03319)
		(width 0.1143)
		(layer "In4.Cu")
		(net "P5E_CPU1_P1_TX_DP<10>")
	)
	(segment
		(start 106.345736 -295.146222)
		(end 106.345736 -295.304972)
		(width 0.1143)
		(layer "In4.Cu")
		(net "P5E_CPU1_P1_TX_DP<10>")
	)
	(segment
		(start 106.161586 -291.58565)
		(end 106.162348 -291.586158)
		(width 0.1143)
		(layer "In4.Cu")
		(net "P5E_CPU1_P1_TX_DP<10>")
	)
	(arc
		(start 106.345736 -295.304972)
		(mid 106.328238 -295.392939)
		(end 106.278426 -295.467532)
		(width 0.1143)
		(layer "In4.Cu")
		(net "P5E_CPU1_P1_TX_DP<10>")
	)
	(arc
		(start 106.589068 -293.061644)
		(mid 106.345741 -293.52621)
		(end 106.589068 -293.990776)
		(width 0.1143)
		(layer "In4.Cu")
		(net "P5E_CPU1_P1_TX_DP<10>")
	)
	(arc
		(start 106.055922 -295.690036)
		(mid 105.986956 -295.793156)
		(end 105.962704 -295.914826)
		(width 0.1143)
		(layer "In4.Cu")
		(net "P5E_CPU1_P1_TX_DP<10>")
	)
	(arc
		(start 106.345736 -290.286186)
		(mid 106.304481 -290.457157)
		(end 106.18978 -290.590478)
		(width 0.1143)
		(layer "In4.Cu")
		(net "P5E_CPU1_P1_TX_DP<10>")
	)
	(arc
		(start 106.589068 -294.681656)
		(mid 106.410178 -294.88398)
		(end 106.345736 -295.146222)
		(width 0.1143)
		(layer "In4.Cu")
		(net "P5E_CPU1_P1_TX_DP<10>")
	)
	(arc
		(start 106.345736 -291.906198)
		(mid 106.410251 -292.168417)
		(end 106.589068 -292.370764)
		(width 0.1143)
		(layer "In4.Cu")
		(net "P5E_CPU1_P1_TX_DP<10>")
	)
	(arc
		(start 106.658664 -292.411404)
		(mid 106.815641 -292.716204)
		(end 106.658664 -293.021004)
		(width 0.1143)
		(layer "In4.Cu")
		(net "P5E_CPU1_P1_TX_DP<10>")
	)
	(arc
		(start 106.589068 -289.82162)
		(mid 106.410255 -290.02397)
		(end 106.345736 -290.286186)
		(width 0.1143)
		(layer "In4.Cu")
		(net "P5E_CPU1_P1_TX_DP<10>")
	)
	(arc
		(start 106.118914 -290.631626)
		(mid 105.875587 -291.096192)
		(end 106.118914 -291.560758)
		(width 0.1143)
		(layer "In4.Cu")
		(net "P5E_CPU1_P1_TX_DP<10>")
	)
	(arc
		(start 106.808778 -289.54603)
		(mid 106.756361 -289.677961)
		(end 106.658664 -289.78098)
		(width 0.1143)
		(layer "In4.Cu")
		(net "P5E_CPU1_P1_TX_DP<10>")
	)
	(arc
		(start 96.207834 -365.508794)
		(mid 94.993086 -366.849395)
		(end 94.553532 -368.604292)
		(width 0.14224)
		(layer "In4.Cu")
		(net "P5E_CPU1_P1_TX_DP<10>")
	)
	(arc
		(start 125.956314 -337.780884)
		(mid 125.964709 -337.843627)
		(end 125.96749 -337.906868)
		(width 0.14224)
		(layer "In4.Cu")
		(net "P5E_CPU1_P1_TX_DP<10>")
	)
	(arc
		(start 125.141736 -333.302102)
		(mid 125.15994 -333.362584)
		(end 125.173486 -333.424276)
		(width 0.14224)
		(layer "In4.Cu")
		(net "P5E_CPU1_P1_TX_DP<10>")
	)
	(arc
		(start 105.916984 -298.134786)
		(mid 105.924777 -298.214544)
		(end 105.947972 -298.29125)
		(width 0.14224)
		(layer "In4.Cu")
		(net "P5E_CPU1_P1_TX_DP<10>")
	)
	(arc
		(start 106.658664 -294.031416)
		(mid 106.815641 -294.336216)
		(end 106.658664 -294.641016)
		(width 0.1143)
		(layer "In4.Cu")
		(net "P5E_CPU1_P1_TX_DP<10>")
	)
	(arc
		(start 124.996702 -349.148908)
		(mid 124.96424 -349.203048)
		(end 124.917454 -349.245428)
		(width 0.14224)
		(layer "In4.Cu")
		(net "P5E_CPU1_P1_TX_DP<10>")
	)
	(arc
		(start 125.96749 -346.74175)
		(mid 125.961212 -346.804551)
		(end 125.942852 -346.86494)
		(width 0.14224)
		(layer "In4.Cu")
		(net "P5E_CPU1_P1_TX_DP<10>")
	)
	(arc
		(start 106.18978 -291.601906)
		(mid 106.304456 -291.73524)
		(end 106.345736 -291.906198)
		(width 0.1143)
		(layer "In4.Cu")
		(net "P5E_CPU1_P1_TX_DP<10>")
	)
	(segment
		(start 98.44786 -285.970472)
		(end 97.981008 -286.23641)
		(width 0.12954)
		(layer "F.Cu")
		(net "P5E_CPU1_P1_TX_DP<0>")
	)
	(segment
		(start 74.93254 -382.09855)
		(end 74.22896 -382.09855)
		(width 0.12954)
		(layer "F.Cu")
		(net "P5E_CPU1_P1_TX_DP<0>")
	)
	(segment
		(start 74.22896 -382.09855)
		(end 73.95845 -382.36906)
		(width 0.12954)
		(layer "F.Cu")
		(net "P5E_CPU1_P1_TX_DP<0>")
	)
	(segment
		(start 75.22845 -382.39446)
		(end 74.93254 -382.09855)
		(width 0.12954)
		(layer "F.Cu")
		(net "P5E_CPU1_P1_TX_DP<0>")
	)
	(segment
		(start 96.430084 -299.700442)
		(end 100.943664 -310.59755)
		(width 0.14224)
		(layer "In4.Cu")
		(net "P5E_CPU1_P1_TX_DP<0>")
	)
	(segment
		(start 115.951762 -336.056986)
		(end 116.415058 -338.6328)
		(width 0.14224)
		(layer "In4.Cu")
		(net "P5E_CPU1_P1_TX_DP<0>")
	)
	(segment
		(start 97.260664 -288.159952)
		(end 97.228152 -288.178748)
		(width 0.1143)
		(layer "In4.Cu")
		(net "P5E_CPU1_P1_TX_DP<0>")
	)
	(segment
		(start 96.430084 -296.234358)
		(end 96.430084 -299.700442)
		(width 0.14224)
		(layer "In4.Cu")
		(net "P5E_CPU1_P1_TX_DP<0>")
	)
	(segment
		(start 96.757998 -290.608766)
		(end 96.721676 -290.629848)
		(width 0.1143)
		(layer "In4.Cu")
		(net "P5E_CPU1_P1_TX_DP<0>")
	)
	(segment
		(start 97.228152 -294.658796)
		(end 97.189036 -294.681656)
		(width 0.1143)
		(layer "In4.Cu")
		(net "P5E_CPU1_P1_TX_DP<0>")
	)
	(segment
		(start 97.189036 -292.370764)
		(end 97.228152 -292.393624)
		(width 0.1143)
		(layer "In4.Cu")
		(net "P5E_CPU1_P1_TX_DP<0>")
	)
	(segment
		(start 73.046336 -382.07823)
		(end 73.66762 -382.07823)
		(width 0.14224)
		(layer "In4.Cu")
		(net "P5E_CPU1_P1_TX_DP<0>")
	)
	(segment
		(start 98.168206 -286.558736)
		(end 98.12909 -286.581596)
		(width 0.1143)
		(layer "In4.Cu")
		(net "P5E_CPU1_P1_TX_DP<0>")
	)
	(segment
		(start 97.228152 -289.1536)
		(end 97.258632 -289.17138)
		(width 0.1143)
		(layer "In4.Cu")
		(net "P5E_CPU1_P1_TX_DP<0>")
	)
	(segment
		(start 96.718882 -291.561012)
		(end 96.782128 -291.597588)
		(width 0.1143)
		(layer "In4.Cu")
		(net "P5E_CPU1_P1_TX_DP<0>")
	)
	(segment
		(start 97.228152 -292.393624)
		(end 97.258632 -292.411404)
		(width 0.1143)
		(layer "In4.Cu")
		(net "P5E_CPU1_P1_TX_DP<0>")
	)
	(segment
		(start 97.729802 -287.350454)
		(end 97.698052 -287.368742)
		(width 0.1143)
		(layer "In4.Cu")
		(net "P5E_CPU1_P1_TX_DP<0>")
	)
	(segment
		(start 96.945704 -295.146222)
		(end 96.945704 -295.34739)
		(width 0.1143)
		(layer "In4.Cu")
		(net "P5E_CPU1_P1_TX_DP<0>")
	)
	(segment
		(start 97.258632 -289.78098)
		(end 97.228152 -289.79876)
		(width 0.1143)
		(layer "In4.Cu")
		(net "P5E_CPU1_P1_TX_DP<0>")
	)
	(segment
		(start 97.228152 -288.178748)
		(end 97.189036 -288.201608)
		(width 0.1143)
		(layer "In4.Cu")
		(net "P5E_CPU1_P1_TX_DP<0>")
	)
	(segment
		(start 108.35132 -320.580258)
		(end 108.35132 -320.580004)
		(width 0.14224)
		(layer "In4.Cu")
		(net "P5E_CPU1_P1_TX_DP<0>")
	)
	(segment
		(start 96.908366 -295.43756)
		(end 96.569022 -295.776904)
		(width 0.1143)
		(layer "In4.Cu")
		(net "P5E_CPU1_P1_TX_DP<0>")
	)
	(segment
		(start 97.981008 -286.23641)
		(end 98.27895 -286.23641)
		(width 0.1143)
		(layer "In4.Cu")
		(net "P5E_CPU1_P1_TX_DP<0>")
	)
	(segment
		(start 97.258632 -293.021004)
		(end 97.228152 -293.038784)
		(width 0.1143)
		(layer "In4.Cu")
		(net "P5E_CPU1_P1_TX_DP<0>")
	)
	(segment
		(start 97.698052 -287.368742)
		(end 97.661476 -287.390078)
		(width 0.1143)
		(layer "In4.Cu")
		(net "P5E_CPU1_P1_TX_DP<0>")
	)
	(segment
		(start 102.390448 -351.860866)
		(end 80.968088 -360.733594)
		(width 0.14224)
		(layer "In4.Cu")
		(net "P5E_CPU1_P1_TX_DP<0>")
	)
	(segment
		(start 72.457818 -369.036854)
		(end 72.457818 -381.381254)
		(width 0.14224)
		(layer "In4.Cu")
		(net "P5E_CPU1_P1_TX_DP<0>")
	)
	(segment
		(start 100.943664 -310.59755)
		(end 104.382824 -315.744606)
		(width 0.14224)
		(layer "In4.Cu")
		(net "P5E_CPU1_P1_TX_DP<0>")
	)
	(segment
		(start 73.66762 -382.07823)
		(end 73.95845 -382.36906)
		(width 0.14224)
		(layer "In4.Cu")
		(net "P5E_CPU1_P1_TX_DP<0>")
	)
	(segment
		(start 115.19408 -343.321386)
		(end 102.502208 -351.801176)
		(width 0.14224)
		(layer "In4.Cu")
		(net "P5E_CPU1_P1_TX_DP<0>")
	)
	(segment
		(start 97.228152 -293.038784)
		(end 97.189036 -293.061644)
		(width 0.1143)
		(layer "In4.Cu")
		(net "P5E_CPU1_P1_TX_DP<0>")
	)
	(segment
		(start 98.27895 -286.23641)
		(end 98.3488 -286.30626)
		(width 0.1143)
		(layer "In4.Cu")
		(net "P5E_CPU1_P1_TX_DP<0>")
	)
	(segment
		(start 108.35132 -320.580004)
		(end 112.304322 -325.396352)
		(width 0.14224)
		(layer "In4.Cu")
		(net "P5E_CPU1_P1_TX_DP<0>")
	)
	(segment
		(start 98.200718 -286.53994)
		(end 98.168206 -286.558736)
		(width 0.1143)
		(layer "In4.Cu")
		(net "P5E_CPU1_P1_TX_DP<0>")
	)
	(segment
		(start 96.475804 -296.001694)
		(end 96.475804 -296.16019)
		(width 0.1143)
		(layer "In4.Cu")
		(net "P5E_CPU1_P1_TX_DP<0>")
	)
	(segment
		(start 79.785718 -361.52455)
		(end 72.587612 -368.723164)
		(width 0.14224)
		(layer "In4.Cu")
		(net "P5E_CPU1_P1_TX_DP<0>")
	)
	(segment
		(start 96.430084 -296.20591)
		(end 96.430084 -296.234358)
		(width 0.1143)
		(layer "In4.Cu")
		(net "P5E_CPU1_P1_TX_DP<0>")
	)
	(segment
		(start 97.189036 -293.990776)
		(end 97.228152 -294.013636)
		(width 0.1143)
		(layer "In4.Cu")
		(net "P5E_CPU1_P1_TX_DP<0>")
	)
	(segment
		(start 102.502208 -351.801176)
		(end 102.501954 -351.801176)
		(width 0.14224)
		(layer "In4.Cu")
		(net "P5E_CPU1_P1_TX_DP<0>")
	)
	(segment
		(start 97.228152 -289.79876)
		(end 97.189036 -289.82162)
		(width 0.1143)
		(layer "In4.Cu")
		(net "P5E_CPU1_P1_TX_DP<0>")
	)
	(segment
		(start 97.258632 -294.641016)
		(end 97.228152 -294.658796)
		(width 0.1143)
		(layer "In4.Cu")
		(net "P5E_CPU1_P1_TX_DP<0>")
	)
	(segment
		(start 97.189036 -289.13074)
		(end 97.228152 -289.1536)
		(width 0.1143)
		(layer "In4.Cu")
		(net "P5E_CPU1_P1_TX_DP<0>")
	)
	(segment
		(start 112.326166 -325.435722)
		(end 115.920012 -335.934558)
		(width 0.14224)
		(layer "In4.Cu")
		(net "P5E_CPU1_P1_TX_DP<0>")
	)
	(segment
		(start 72.654414 -381.855726)
		(end 72.75703 -381.958342)
		(width 0.14224)
		(layer "In4.Cu")
		(net "P5E_CPU1_P1_TX_DP<0>")
	)
	(segment
		(start 96.475804 -296.16019)
		(end 96.430084 -296.20591)
		(width 0.1143)
		(layer "In4.Cu")
		(net "P5E_CPU1_P1_TX_DP<0>")
	)
	(segment
		(start 97.228152 -294.013636)
		(end 97.258632 -294.031416)
		(width 0.1143)
		(layer "In4.Cu")
		(net "P5E_CPU1_P1_TX_DP<0>")
	)
	(segment
		(start 116.426234 -338.758784)
		(end 116.426234 -341.016336)
		(width 0.14224)
		(layer "In4.Cu")
		(net "P5E_CPU1_P1_TX_DP<0>")
	)
	(segment
		(start 104.382824 -315.744606)
		(end 108.35132 -320.580258)
		(width 0.14224)
		(layer "In4.Cu")
		(net "P5E_CPU1_P1_TX_DP<0>")
	)
	(segment
		(start 96.789748 -290.590478)
		(end 96.757998 -290.608766)
		(width 0.1143)
		(layer "In4.Cu")
		(net "P5E_CPU1_P1_TX_DP<0>")
	)
	(arc
		(start 97.189036 -289.82162)
		(mid 97.010223 -290.02397)
		(end 96.945704 -290.286186)
		(width 0.1143)
		(layer "In4.Cu")
		(net "P5E_CPU1_P1_TX_DP<0>")
	)
	(arc
		(start 96.711008 -290.637214)
		(mid 96.475502 -291.101201)
		(end 96.718882 -291.561012)
		(width 0.1143)
		(layer "In4.Cu")
		(net "P5E_CPU1_P1_TX_DP<0>")
	)
	(arc
		(start 97.661476 -287.390078)
		(mid 97.480824 -287.592823)
		(end 97.415604 -287.856422)
		(width 0.1143)
		(layer "In4.Cu")
		(net "P5E_CPU1_P1_TX_DP<0>")
	)
	(arc
		(start 96.945704 -295.34739)
		(mid 96.935998 -295.396185)
		(end 96.908366 -295.43756)
		(width 0.1143)
		(layer "In4.Cu")
		(net "P5E_CPU1_P1_TX_DP<0>")
	)
	(arc
		(start 112.304322 -325.396352)
		(mid 112.317024 -325.415051)
		(end 112.326166 -325.435722)
		(width 0.14224)
		(layer "In4.Cu")
		(net "P5E_CPU1_P1_TX_DP<0>")
	)
	(arc
		(start 97.189036 -288.201608)
		(mid 96.945709 -288.666174)
		(end 97.189036 -289.13074)
		(width 0.1143)
		(layer "In4.Cu")
		(net "P5E_CPU1_P1_TX_DP<0>")
	)
	(arc
		(start 96.943418 -291.895022)
		(mid 96.945088 -291.909083)
		(end 96.945958 -291.923216)
		(width 0.1143)
		(layer "In4.Cu")
		(net "P5E_CPU1_P1_TX_DP<0>")
	)
	(arc
		(start 97.885758 -287.046162)
		(mid 97.844503 -287.217133)
		(end 97.729802 -287.350454)
		(width 0.1143)
		(layer "In4.Cu")
		(net "P5E_CPU1_P1_TX_DP<0>")
	)
	(arc
		(start 96.569022 -295.776904)
		(mid 96.500056 -295.880024)
		(end 96.475804 -296.001694)
		(width 0.1143)
		(layer "In4.Cu")
		(net "P5E_CPU1_P1_TX_DP<0>")
	)
	(arc
		(start 97.189036 -294.681656)
		(mid 97.010238 -294.884)
		(end 96.945704 -295.146222)
		(width 0.1143)
		(layer "In4.Cu")
		(net "P5E_CPU1_P1_TX_DP<0>")
	)
	(arc
		(start 97.258632 -292.411404)
		(mid 97.415609 -292.716204)
		(end 97.258632 -293.021004)
		(width 0.1143)
		(layer "In4.Cu")
		(net "P5E_CPU1_P1_TX_DP<0>")
	)
	(arc
		(start 98.3488 -286.30626)
		(mid 98.297092 -286.437243)
		(end 98.200718 -286.53994)
		(width 0.1143)
		(layer "In4.Cu")
		(net "P5E_CPU1_P1_TX_DP<0>")
	)
	(arc
		(start 97.415604 -287.856422)
		(mid 97.374638 -288.026828)
		(end 97.260664 -288.159952)
		(width 0.1143)
		(layer "In4.Cu")
		(net "P5E_CPU1_P1_TX_DP<0>")
	)
	(arc
		(start 97.189036 -293.061644)
		(mid 96.945709 -293.52621)
		(end 97.189036 -293.990776)
		(width 0.1143)
		(layer "In4.Cu")
		(net "P5E_CPU1_P1_TX_DP<0>")
	)
	(arc
		(start 115.920012 -335.934558)
		(mid 115.938204 -335.995171)
		(end 115.951762 -336.056986)
		(width 0.14224)
		(layer "In4.Cu")
		(net "P5E_CPU1_P1_TX_DP<0>")
	)
	(arc
		(start 72.75703 -381.958342)
		(mid 72.88975 -382.047086)
		(end 73.046336 -382.07823)
		(width 0.14224)
		(layer "In4.Cu")
		(net "P5E_CPU1_P1_TX_DP<0>")
	)
	(arc
		(start 102.501954 -351.801176)
		(mid 102.447674 -351.833775)
		(end 102.390448 -351.860866)
		(width 0.14224)
		(layer "In4.Cu")
		(net "P5E_CPU1_P1_TX_DP<0>")
	)
	(arc
		(start 72.457818 -381.381254)
		(mid 72.508915 -381.638046)
		(end 72.654414 -381.855726)
		(width 0.14224)
		(layer "In4.Cu")
		(net "P5E_CPU1_P1_TX_DP<0>")
	)
	(arc
		(start 97.18294 -292.366192)
		(mid 97.18598 -292.368488)
		(end 97.189036 -292.370764)
		(width 0.1143)
		(layer "In4.Cu")
		(net "P5E_CPU1_P1_TX_DP<0>")
	)
	(arc
		(start 116.415058 -338.6328)
		(mid 116.423462 -338.695543)
		(end 116.426234 -338.758784)
		(width 0.14224)
		(layer "In4.Cu")
		(net "P5E_CPU1_P1_TX_DP<0>")
	)
	(arc
		(start 96.945958 -291.923216)
		(mid 97.012523 -292.172475)
		(end 97.18294 -292.366192)
		(width 0.1143)
		(layer "In4.Cu")
		(net "P5E_CPU1_P1_TX_DP<0>")
	)
	(arc
		(start 97.258632 -294.031416)
		(mid 97.415609 -294.336216)
		(end 97.258632 -294.641016)
		(width 0.1143)
		(layer "In4.Cu")
		(net "P5E_CPU1_P1_TX_DP<0>")
	)
	(arc
		(start 96.721676 -290.629848)
		(mid 96.71632 -290.633499)
		(end 96.711008 -290.637214)
		(width 0.1143)
		(layer "In4.Cu")
		(net "P5E_CPU1_P1_TX_DP<0>")
	)
	(arc
		(start 96.782128 -291.597588)
		(mid 96.888636 -291.732277)
		(end 96.943418 -291.895022)
		(width 0.1143)
		(layer "In4.Cu")
		(net "P5E_CPU1_P1_TX_DP<0>")
	)
	(arc
		(start 72.587612 -368.723164)
		(mid 72.491476 -368.867087)
		(end 72.457818 -369.036854)
		(width 0.14224)
		(layer "In4.Cu")
		(net "P5E_CPU1_P1_TX_DP<0>")
	)
	(arc
		(start 97.258632 -289.17138)
		(mid 97.415609 -289.47618)
		(end 97.258632 -289.78098)
		(width 0.1143)
		(layer "In4.Cu")
		(net "P5E_CPU1_P1_TX_DP<0>")
	)
	(arc
		(start 96.945704 -290.286186)
		(mid 96.904449 -290.457157)
		(end 96.789748 -290.590478)
		(width 0.1143)
		(layer "In4.Cu")
		(net "P5E_CPU1_P1_TX_DP<0>")
	)
	(arc
		(start 98.12909 -286.581596)
		(mid 97.950277 -286.783946)
		(end 97.885758 -287.046162)
		(width 0.1143)
		(layer "In4.Cu")
		(net "P5E_CPU1_P1_TX_DP<0>")
	)
	(arc
		(start 116.426234 -341.016336)
		(mid 116.098865 -342.323188)
		(end 115.19408 -343.321386)
		(width 0.14224)
		(layer "In4.Cu")
		(net "P5E_CPU1_P1_TX_DP<0>")
	)
	(arc
		(start 80.968088 -360.733594)
		(mid 80.337821 -361.070654)
		(end 79.785718 -361.52455)
		(width 0.14224)
		(layer "In4.Cu")
		(net "P5E_CPU1_P1_TX_DP<0>")
	)
	(segment
		(start 91.452192 -369.30584)
		(end 91.722702 -369.03533)
		(width 0.12954)
		(layer "F.Cu")
		(net "P5E_CPU1_P1_TX_DN<9>")
	)
	(segment
		(start 91.452192 -370.00942)
		(end 91.452192 -369.30584)
		(width 0.12954)
		(layer "F.Cu")
		(net "P5E_CPU1_P1_TX_DN<9>")
	)
	(segment
		(start 91.748102 -370.30533)
		(end 91.452192 -370.00942)
		(width 0.12954)
		(layer "F.Cu")
		(net "P5E_CPU1_P1_TX_DN<9>")
	)
	(segment
		(start 105.027984 -287.590484)
		(end 104.561132 -287.856422)
		(width 0.12954)
		(layer "F.Cu")
		(net "P5E_CPU1_P1_TX_DN<9>")
	)
	(segment
		(start 105.823004 -293.18077)
		(end 105.783888 -293.20363)
		(width 0.1143)
		(layer "In4.Cu")
		(net "P5E_CPU1_P1_TX_DN<9>")
	)
	(segment
		(start 105.25379 -296.107358)
		(end 105.25379 -298.289218)
		(width 0.14224)
		(layer "In4.Cu")
		(net "P5E_CPU1_P1_TX_DN<9>")
	)
	(segment
		(start 91.431872 -368.7445)
		(end 91.722702 -369.03533)
		(width 0.14224)
		(layer "In4.Cu")
		(net "P5E_CPU1_P1_TX_DN<9>")
	)
	(segment
		(start 104.561132 -287.856422)
		(end 104.26319 -287.856422)
		(width 0.1143)
		(layer "In4.Cu")
		(net "P5E_CPU1_P1_TX_DN<9>")
	)
	(segment
		(start 105.353104 -290.750752)
		(end 105.33507 -290.76142)
		(width 0.1143)
		(layer "In4.Cu")
		(net "P5E_CPU1_P1_TX_DN<9>")
	)
	(segment
		(start 109.1057 -358.851708)
		(end 97.879408 -363.501686)
		(width 0.14224)
		(layer "In4.Cu")
		(net "P5E_CPU1_P1_TX_DN<9>")
	)
	(segment
		(start 105.33507 -290.76142)
		(end 105.334816 -290.76142)
		(width 0.1143)
		(layer "In4.Cu")
		(net "P5E_CPU1_P1_TX_DN<9>")
	)
	(segment
		(start 104.373934 -288.178748)
		(end 104.41305 -288.201608)
		(width 0.1143)
		(layer "In4.Cu")
		(net "P5E_CPU1_P1_TX_DN<9>")
	)
	(segment
		(start 125.291596 -337.920584)
		(end 125.291596 -346.301314)
		(width 0.14224)
		(layer "In4.Cu")
		(net "P5E_CPU1_P1_TX_DN<9>")
	)
	(segment
		(start 105.322624 -291.423852)
		(end 105.352342 -291.441124)
		(width 0.1143)
		(layer "In4.Cu")
		(net "P5E_CPU1_P1_TX_DN<9>")
	)
	(segment
		(start 105.753408 -293.83101)
		(end 105.783888 -293.84879)
		(width 0.1143)
		(layer "In4.Cu")
		(net "P5E_CPU1_P1_TX_DN<9>")
	)
	(segment
		(start 120.74525 -322.543678)
		(end 124.506482 -333.534258)
		(width 0.14224)
		(layer "In4.Cu")
		(net "P5E_CPU1_P1_TX_DN<9>")
	)
	(segment
		(start 108.413042 -305.941476)
		(end 111.681006 -310.831992)
		(width 0.14224)
		(layer "In4.Cu")
		(net "P5E_CPU1_P1_TX_DN<9>")
	)
	(segment
		(start 92.066618 -367.3856)
		(end 91.499944 -367.952274)
		(width 0.14224)
		(layer "In4.Cu")
		(net "P5E_CPU1_P1_TX_DN<9>")
	)
	(segment
		(start 105.458514 -295.617138)
		(end 105.245408 -295.82999)
		(width 0.1143)
		(layer "In4.Cu")
		(net "P5E_CPU1_P1_TX_DN<9>")
	)
	(segment
		(start 105.20807 -295.919906)
		(end 105.20807 -296.03319)
		(width 0.1143)
		(layer "In4.Cu")
		(net "P5E_CPU1_P1_TX_DN<9>")
	)
	(segment
		(start 105.783888 -292.228778)
		(end 105.823004 -292.251638)
		(width 0.1143)
		(layer "In4.Cu")
		(net "P5E_CPU1_P1_TX_DN<9>")
	)
	(segment
		(start 105.596436 -295.146222)
		(end 105.596182 -295.145968)
		(width 0.1143)
		(layer "In4.Cu")
		(net "P5E_CPU1_P1_TX_DN<9>")
	)
	(segment
		(start 104.26319 -287.856422)
		(end 104.19334 -287.926272)
		(width 0.1143)
		(layer "In4.Cu")
		(net "P5E_CPU1_P1_TX_DN<9>")
	)
	(segment
		(start 124.5489 -333.698088)
		(end 125.276102 -337.744816)
		(width 0.14224)
		(layer "In4.Cu")
		(net "P5E_CPU1_P1_TX_DN<9>")
	)
	(segment
		(start 105.823004 -294.800782)
		(end 105.753408 -294.841422)
		(width 0.1143)
		(layer "In4.Cu")
		(net "P5E_CPU1_P1_TX_DN<9>")
	)
	(segment
		(start 105.301288 -289.791394)
		(end 105.353104 -289.82162)
		(width 0.1143)
		(layer "In4.Cu")
		(net "P5E_CPU1_P1_TX_DN<9>")
	)
	(segment
		(start 104.812338 -288.970466)
		(end 104.836722 -288.984436)
		(width 0.1143)
		(layer "In4.Cu")
		(net "P5E_CPU1_P1_TX_DN<9>")
	)
	(segment
		(start 104.341422 -288.159952)
		(end 104.373934 -288.178748)
		(width 0.1143)
		(layer "In4.Cu")
		(net "P5E_CPU1_P1_TX_DN<9>")
	)
	(segment
		(start 104.836722 -288.984436)
		(end 104.838246 -288.985198)
		(width 0.1143)
		(layer "In4.Cu")
		(net "P5E_CPU1_P1_TX_DN<9>")
	)
	(segment
		(start 105.783888 -293.20363)
		(end 105.753408 -293.22141)
		(width 0.1143)
		(layer "In4.Cu")
		(net "P5E_CPU1_P1_TX_DN<9>")
	)
	(segment
		(start 105.753408 -292.210998)
		(end 105.783888 -292.228778)
		(width 0.1143)
		(layer "In4.Cu")
		(net "P5E_CPU1_P1_TX_DN<9>")
	)
	(segment
		(start 105.113582 -289.432492)
		(end 105.113582 -289.466528)
		(width 0.1143)
		(layer "In4.Cu")
		(net "P5E_CPU1_P1_TX_DN<9>")
	)
	(segment
		(start 111.681006 -310.831992)
		(end 119.78513 -320.706242)
		(width 0.14224)
		(layer "In4.Cu")
		(net "P5E_CPU1_P1_TX_DN<9>")
	)
	(segment
		(start 105.20807 -296.03319)
		(end 105.25379 -296.07891)
		(width 0.1143)
		(layer "In4.Cu")
		(net "P5E_CPU1_P1_TX_DN<9>")
	)
	(segment
		(start 105.783888 -293.84879)
		(end 105.823004 -293.87165)
		(width 0.1143)
		(layer "In4.Cu")
		(net "P5E_CPU1_P1_TX_DN<9>")
	)
	(segment
		(start 105.306114 -291.4142)
		(end 105.3211 -291.422836)
		(width 0.1143)
		(layer "In4.Cu")
		(net "P5E_CPU1_P1_TX_DN<9>")
	)
	(segment
		(start 124.241052 -348.738952)
		(end 109.1057 -358.851708)
		(width 0.14224)
		(layer "In4.Cu")
		(net "P5E_CPU1_P1_TX_DN<9>")
	)
	(segment
		(start 119.78513 -320.706242)
		(end 120.74525 -322.543678)
		(width 0.14224)
		(layer "In4.Cu")
		(net "P5E_CPU1_P1_TX_DN<9>")
	)
	(segment
		(start 105.263442 -298.337986)
		(end 108.413042 -305.941476)
		(width 0.14224)
		(layer "In4.Cu")
		(net "P5E_CPU1_P1_TX_DN<9>")
	)
	(segment
		(start 125.245622 -346.5322)
		(end 124.424186 -348.515686)
		(width 0.14224)
		(layer "In4.Cu")
		(net "P5E_CPU1_P1_TX_DN<9>")
	)
	(segment
		(start 105.334816 -290.76142)
		(end 105.31348 -290.773866)
		(width 0.1143)
		(layer "In4.Cu")
		(net "P5E_CPU1_P1_TX_DN<9>")
	)
	(segment
		(start 105.3211 -291.422836)
		(end 105.322624 -291.423852)
		(width 0.1143)
		(layer "In4.Cu")
		(net "P5E_CPU1_P1_TX_DN<9>")
	)
	(segment
		(start 105.596182 -295.145968)
		(end 105.596182 -295.284398)
		(width 0.1143)
		(layer "In4.Cu")
		(net "P5E_CPU1_P1_TX_DN<9>")
	)
	(segment
		(start 91.431872 -368.116612)
		(end 91.431872 -368.7445)
		(width 0.14224)
		(layer "In4.Cu")
		(net "P5E_CPU1_P1_TX_DN<9>")
	)
	(segment
		(start 105.25379 -296.07891)
		(end 105.25379 -296.107358)
		(width 0.1143)
		(layer "In4.Cu")
		(net "P5E_CPU1_P1_TX_DN<9>")
	)
	(arc
		(start 105.823004 -292.251638)
		(mid 106.066331 -292.716204)
		(end 105.823004 -293.18077)
		(width 0.1143)
		(layer "In4.Cu")
		(net "P5E_CPU1_P1_TX_DN<9>")
	)
	(arc
		(start 104.838246 -288.985198)
		(mid 105.03927 -289.169855)
		(end 105.113582 -289.432492)
		(width 0.1143)
		(layer "In4.Cu")
		(net "P5E_CPU1_P1_TX_DN<9>")
	)
	(arc
		(start 91.499944 -367.952274)
		(mid 91.449564 -368.027673)
		(end 91.431872 -368.116612)
		(width 0.14224)
		(layer "In4.Cu")
		(net "P5E_CPU1_P1_TX_DN<9>")
	)
	(arc
		(start 105.753408 -293.22141)
		(mid 105.596431 -293.52621)
		(end 105.753408 -293.83101)
		(width 0.1143)
		(layer "In4.Cu")
		(net "P5E_CPU1_P1_TX_DN<9>")
	)
	(arc
		(start 104.41305 -288.201608)
		(mid 104.591863 -288.403958)
		(end 104.656382 -288.666174)
		(width 0.1143)
		(layer "In4.Cu")
		(net "P5E_CPU1_P1_TX_DN<9>")
	)
	(arc
		(start 105.596182 -295.284398)
		(mid 105.560442 -295.464455)
		(end 105.458514 -295.617138)
		(width 0.1143)
		(layer "In4.Cu")
		(net "P5E_CPU1_P1_TX_DN<9>")
	)
	(arc
		(start 104.656382 -288.666174)
		(mid 104.697637 -288.837145)
		(end 104.812338 -288.970466)
		(width 0.1143)
		(layer "In4.Cu")
		(net "P5E_CPU1_P1_TX_DN<9>")
	)
	(arc
		(start 105.25379 -298.289218)
		(mid 105.256236 -298.314071)
		(end 105.263442 -298.337986)
		(width 0.14224)
		(layer "In4.Cu")
		(net "P5E_CPU1_P1_TX_DN<9>")
	)
	(arc
		(start 105.353104 -291.441632)
		(mid 105.531917 -291.643982)
		(end 105.596436 -291.906198)
		(width 0.1143)
		(layer "In4.Cu")
		(net "P5E_CPU1_P1_TX_DN<9>")
	)
	(arc
		(start 105.31348 -290.773866)
		(mid 105.12796 -291.091923)
		(end 105.306114 -291.4142)
		(width 0.1143)
		(layer "In4.Cu")
		(net "P5E_CPU1_P1_TX_DN<9>")
	)
	(arc
		(start 105.352342 -291.441124)
		(mid 105.352723 -291.441378)
		(end 105.353104 -291.441632)
		(width 0.1143)
		(layer "In4.Cu")
		(net "P5E_CPU1_P1_TX_DN<9>")
	)
	(arc
		(start 125.276102 -337.744816)
		(mid 125.287749 -337.832356)
		(end 125.291596 -337.920584)
		(width 0.14224)
		(layer "In4.Cu")
		(net "P5E_CPU1_P1_TX_DN<9>")
	)
	(arc
		(start 105.753408 -294.841422)
		(mid 105.637981 -294.974798)
		(end 105.596436 -295.146222)
		(width 0.1143)
		(layer "In4.Cu")
		(net "P5E_CPU1_P1_TX_DN<9>")
	)
	(arc
		(start 105.245408 -295.82999)
		(mid 105.217789 -295.87123)
		(end 105.20807 -295.919906)
		(width 0.1143)
		(layer "In4.Cu")
		(net "P5E_CPU1_P1_TX_DN<9>")
	)
	(arc
		(start 125.291596 -346.301314)
		(mid 125.279971 -346.41902)
		(end 125.245622 -346.5322)
		(width 0.14224)
		(layer "In4.Cu")
		(net "P5E_CPU1_P1_TX_DN<9>")
	)
	(arc
		(start 104.19334 -287.926272)
		(mid 104.245048 -288.057255)
		(end 104.341422 -288.159952)
		(width 0.1143)
		(layer "In4.Cu")
		(net "P5E_CPU1_P1_TX_DN<9>")
	)
	(arc
		(start 124.506482 -333.534258)
		(mid 124.530805 -333.615367)
		(end 124.5489 -333.698088)
		(width 0.14224)
		(layer "In4.Cu")
		(net "P5E_CPU1_P1_TX_DN<9>")
	)
	(arc
		(start 105.596436 -291.906198)
		(mid 105.637985 -292.07762)
		(end 105.753408 -292.210998)
		(width 0.1143)
		(layer "In4.Cu")
		(net "P5E_CPU1_P1_TX_DN<9>")
	)
	(arc
		(start 105.113582 -289.466528)
		(mid 105.163888 -289.654116)
		(end 105.301288 -289.791394)
		(width 0.1143)
		(layer "In4.Cu")
		(net "P5E_CPU1_P1_TX_DN<9>")
	)
	(arc
		(start 105.823004 -293.87165)
		(mid 106.066331 -294.336216)
		(end 105.823004 -294.800782)
		(width 0.1143)
		(layer "In4.Cu")
		(net "P5E_CPU1_P1_TX_DN<9>")
	)
	(arc
		(start 97.879408 -363.501686)
		(mid 94.781747 -365.157386)
		(end 92.066618 -367.3856)
		(width 0.14224)
		(layer "In4.Cu")
		(net "P5E_CPU1_P1_TX_DN<9>")
	)
	(arc
		(start 105.353104 -289.82162)
		(mid 105.596321 -290.286186)
		(end 105.353104 -290.750752)
		(width 0.1143)
		(layer "In4.Cu")
		(net "P5E_CPU1_P1_TX_DN<9>")
	)
	(arc
		(start 124.424186 -348.515686)
		(mid 124.349185 -348.640905)
		(end 124.241052 -348.738952)
		(width 0.14224)
		(layer "In4.Cu")
		(net "P5E_CPU1_P1_TX_DN<9>")
	)
	(segment
		(start 89.750392 -372.47322)
		(end 89.750392 -371.76964)
		(width 0.12954)
		(layer "F.Cu")
		(net "P5E_CPU1_P1_TX_DN<8>")
	)
	(segment
		(start 105.027984 -290.830254)
		(end 104.561132 -291.096192)
		(width 0.12954)
		(layer "F.Cu")
		(net "P5E_CPU1_P1_TX_DN<8>")
	)
	(segment
		(start 90.046302 -372.76913)
		(end 89.750392 -372.47322)
		(width 0.12954)
		(layer "F.Cu")
		(net "P5E_CPU1_P1_TX_DN<8>")
	)
	(segment
		(start 89.750392 -371.76964)
		(end 90.020902 -371.49913)
		(width 0.12954)
		(layer "F.Cu")
		(net "P5E_CPU1_P1_TX_DN<8>")
	)
	(segment
		(start 91.664028 -365.990124)
		(end 90.103706 -367.550446)
		(width 0.14224)
		(layer "In4.Cu")
		(net "P5E_CPU1_P1_TX_DN<8>")
	)
	(segment
		(start 104.822752 -293.836344)
		(end 104.882442 -293.871142)
		(width 0.1143)
		(layer "In4.Cu")
		(net "P5E_CPU1_P1_TX_DN<8>")
	)
	(segment
		(start 104.262936 -295.924732)
		(end 104.262936 -296.03319)
		(width 0.1143)
		(layer "In4.Cu")
		(net "P5E_CPU1_P1_TX_DN<8>")
	)
	(segment
		(start 104.374188 -291.418772)
		(end 104.374188 -291.419026)
		(width 0.1143)
		(layer "In4.Cu")
		(net "P5E_CPU1_P1_TX_DN<8>")
	)
	(segment
		(start 123.647962 -334.028542)
		(end 124.325634 -337.799172)
		(width 0.14224)
		(layer "In4.Cu")
		(net "P5E_CPU1_P1_TX_DN<8>")
	)
	(segment
		(start 108.313728 -358.170226)
		(end 95.300038 -363.560614)
		(width 0.14224)
		(layer "In4.Cu")
		(net "P5E_CPU1_P1_TX_DN<8>")
	)
	(segment
		(start 104.563164 -295.572434)
		(end 104.300274 -295.834562)
		(width 0.1143)
		(layer "In4.Cu")
		(net "P5E_CPU1_P1_TX_DN<8>")
	)
	(segment
		(start 104.812338 -292.21049)
		(end 104.883204 -292.251638)
		(width 0.1143)
		(layer "In4.Cu")
		(net "P5E_CPU1_P1_TX_DN<8>")
	)
	(segment
		(start 124.341128 -337.975194)
		(end 124.341128 -344.811604)
		(width 0.14224)
		(layer "In4.Cu")
		(net "P5E_CPU1_P1_TX_DN<8>")
	)
	(segment
		(start 104.885236 -294.799258)
		(end 104.812338 -294.84193)
		(width 0.1143)
		(layer "In4.Cu")
		(net "P5E_CPU1_P1_TX_DN<8>")
	)
	(segment
		(start 104.822752 -293.216076)
		(end 104.822498 -293.216076)
		(width 0.1143)
		(layer "In4.Cu")
		(net "P5E_CPU1_P1_TX_DN<8>")
	)
	(segment
		(start 119.002556 -321.225418)
		(end 119.80418 -322.758562)
		(width 0.14224)
		(layer "In4.Cu")
		(net "P5E_CPU1_P1_TX_DN<8>")
	)
	(segment
		(start 104.262936 -296.03319)
		(end 104.308656 -296.07891)
		(width 0.1143)
		(layer "In4.Cu")
		(net "P5E_CPU1_P1_TX_DN<8>")
	)
	(segment
		(start 104.373426 -291.418264)
		(end 104.374188 -291.418772)
		(width 0.1143)
		(layer "In4.Cu")
		(net "P5E_CPU1_P1_TX_DN<8>")
	)
	(segment
		(start 122.139202 -348.931738)
		(end 108.313728 -358.170226)
		(width 0.14224)
		(layer "In4.Cu")
		(net "P5E_CPU1_P1_TX_DN<8>")
	)
	(segment
		(start 104.342438 -291.400484)
		(end 104.373426 -291.418264)
		(width 0.1143)
		(layer "In4.Cu")
		(net "P5E_CPU1_P1_TX_DN<8>")
	)
	(segment
		(start 104.823514 -293.215568)
		(end 104.822752 -293.216076)
		(width 0.1143)
		(layer "In4.Cu")
		(net "P5E_CPU1_P1_TX_DN<8>")
	)
	(segment
		(start 104.331008 -298.523152)
		(end 107.588812 -306.388262)
		(width 0.14224)
		(layer "In4.Cu")
		(net "P5E_CPU1_P1_TX_DN<8>")
	)
	(segment
		(start 89.730072 -368.4524)
		(end 89.730072 -371.2083)
		(width 0.14224)
		(layer "In4.Cu")
		(net "P5E_CPU1_P1_TX_DN<8>")
	)
	(segment
		(start 104.883204 -293.87165)
		(end 104.885236 -293.873174)
		(width 0.1143)
		(layer "In4.Cu")
		(net "P5E_CPU1_P1_TX_DN<8>")
	)
	(segment
		(start 104.26319 -291.096192)
		(end 104.19334 -291.166042)
		(width 0.1143)
		(layer "In4.Cu")
		(net "P5E_CPU1_P1_TX_DN<8>")
	)
	(segment
		(start 104.308656 -296.07891)
		(end 104.308656 -296.107358)
		(width 0.1143)
		(layer "In4.Cu")
		(net "P5E_CPU1_P1_TX_DN<8>")
	)
	(segment
		(start 104.656382 -295.146222)
		(end 104.656382 -295.347644)
		(width 0.1143)
		(layer "In4.Cu")
		(net "P5E_CPU1_P1_TX_DN<8>")
	)
	(segment
		(start 119.80418 -322.758562)
		(end 123.605544 -333.864712)
		(width 0.14224)
		(layer "In4.Cu")
		(net "P5E_CPU1_P1_TX_DN<8>")
	)
	(segment
		(start 104.561132 -291.096192)
		(end 104.26319 -291.096192)
		(width 0.1143)
		(layer "In4.Cu")
		(net "P5E_CPU1_P1_TX_DN<8>")
	)
	(segment
		(start 104.822244 -293.836344)
		(end 104.822752 -293.836344)
		(width 0.1143)
		(layer "In4.Cu")
		(net "P5E_CPU1_P1_TX_DN<8>")
	)
	(segment
		(start 110.930182 -311.389014)
		(end 119.002556 -321.225418)
		(width 0.14224)
		(layer "In4.Cu")
		(net "P5E_CPU1_P1_TX_DN<8>")
	)
	(segment
		(start 104.308656 -296.107358)
		(end 104.308656 -298.410884)
		(width 0.14224)
		(layer "In4.Cu")
		(net "P5E_CPU1_P1_TX_DN<8>")
	)
	(segment
		(start 104.883204 -293.18077)
		(end 104.823514 -293.215568)
		(width 0.1143)
		(layer "In4.Cu")
		(net "P5E_CPU1_P1_TX_DN<8>")
	)
	(segment
		(start 89.730072 -371.2083)
		(end 90.020902 -371.49913)
		(width 0.14224)
		(layer "In4.Cu")
		(net "P5E_CPU1_P1_TX_DN<8>")
	)
	(segment
		(start 104.374188 -291.419026)
		(end 104.411272 -291.440616)
		(width 0.1143)
		(layer "In4.Cu")
		(net "P5E_CPU1_P1_TX_DN<8>")
	)
	(segment
		(start 107.588812 -306.388262)
		(end 110.930182 -311.389014)
		(width 0.14224)
		(layer "In4.Cu")
		(net "P5E_CPU1_P1_TX_DN<8>")
	)
	(arc
		(start 104.411272 -291.440616)
		(mid 104.572424 -291.633364)
		(end 104.652826 -291.8714)
		(width 0.1143)
		(layer "In4.Cu")
		(net "P5E_CPU1_P1_TX_DN<8>")
	)
	(arc
		(start 104.885236 -293.873174)
		(mid 105.127747 -294.336216)
		(end 104.885236 -294.799258)
		(width 0.1143)
		(layer "In4.Cu")
		(net "P5E_CPU1_P1_TX_DN<8>")
	)
	(arc
		(start 104.656382 -291.91585)
		(mid 104.699775 -292.081482)
		(end 104.812338 -292.21049)
		(width 0.1143)
		(layer "In4.Cu")
		(net "P5E_CPU1_P1_TX_DN<8>")
	)
	(arc
		(start 104.656382 -295.347644)
		(mid 104.63216 -295.469326)
		(end 104.563164 -295.572434)
		(width 0.1143)
		(layer "In4.Cu")
		(net "P5E_CPU1_P1_TX_DN<8>")
	)
	(arc
		(start 124.325634 -337.799172)
		(mid 124.337295 -337.886838)
		(end 124.341128 -337.975194)
		(width 0.14224)
		(layer "In4.Cu")
		(net "P5E_CPU1_P1_TX_DN<8>")
	)
	(arc
		(start 104.19334 -291.166042)
		(mid 104.245389 -291.297561)
		(end 104.342438 -291.400484)
		(width 0.1143)
		(layer "In4.Cu")
		(net "P5E_CPU1_P1_TX_DN<8>")
	)
	(arc
		(start 123.605544 -333.864712)
		(mid 123.629872 -333.94582)
		(end 123.647962 -334.028542)
		(width 0.14224)
		(layer "In4.Cu")
		(net "P5E_CPU1_P1_TX_DN<8>")
	)
	(arc
		(start 104.300274 -295.834562)
		(mid 104.272631 -295.875932)
		(end 104.262936 -295.924732)
		(width 0.1143)
		(layer "In4.Cu")
		(net "P5E_CPU1_P1_TX_DN<8>")
	)
	(arc
		(start 104.812338 -294.84193)
		(mid 104.697662 -294.975264)
		(end 104.656382 -295.146222)
		(width 0.1143)
		(layer "In4.Cu")
		(net "P5E_CPU1_P1_TX_DN<8>")
	)
	(arc
		(start 104.652826 -291.8714)
		(mid 104.65517 -291.89358)
		(end 104.656382 -291.91585)
		(width 0.1143)
		(layer "In4.Cu")
		(net "P5E_CPU1_P1_TX_DN<8>")
	)
	(arc
		(start 104.308656 -298.410884)
		(mid 104.314298 -298.46812)
		(end 104.331008 -298.523152)
		(width 0.14224)
		(layer "In4.Cu")
		(net "P5E_CPU1_P1_TX_DN<8>")
	)
	(arc
		(start 95.300038 -363.560614)
		(mid 93.36238 -364.596298)
		(end 91.664028 -365.990124)
		(width 0.14224)
		(layer "In4.Cu")
		(net "P5E_CPU1_P1_TX_DN<8>")
	)
	(arc
		(start 124.341128 -344.811604)
		(mid 123.756181 -347.147452)
		(end 122.139202 -348.931738)
		(width 0.14224)
		(layer "In4.Cu")
		(net "P5E_CPU1_P1_TX_DN<8>")
	)
	(arc
		(start 104.822498 -293.216076)
		(mid 104.643956 -293.5261)
		(end 104.822244 -293.836344)
		(width 0.1143)
		(layer "In4.Cu")
		(net "P5E_CPU1_P1_TX_DN<8>")
	)
	(arc
		(start 104.883204 -292.251638)
		(mid 105.126531 -292.716204)
		(end 104.883204 -293.18077)
		(width 0.1143)
		(layer "In4.Cu")
		(net "P5E_CPU1_P1_TX_DN<8>")
	)
	(arc
		(start 90.103706 -367.550446)
		(mid 89.8272 -367.964266)
		(end 89.730072 -368.4524)
		(width 0.14224)
		(layer "In4.Cu")
		(net "P5E_CPU1_P1_TX_DN<8>")
	)
	(arc
		(start 104.882442 -293.871142)
		(mid 104.882823 -293.871396)
		(end 104.883204 -293.87165)
		(width 0.1143)
		(layer "In4.Cu")
		(net "P5E_CPU1_P1_TX_DN<8>")
	)
	(segment
		(start 88.048592 -374.23344)
		(end 88.319102 -373.96293)
		(width 0.12954)
		(layer "F.Cu")
		(net "P5E_CPU1_P1_TX_DN<7>")
	)
	(segment
		(start 88.048592 -374.93702)
		(end 88.048592 -374.23344)
		(width 0.12954)
		(layer "F.Cu")
		(net "P5E_CPU1_P1_TX_DN<7>")
	)
	(segment
		(start 88.344502 -375.23293)
		(end 88.048592 -374.93702)
		(width 0.12954)
		(layer "F.Cu")
		(net "P5E_CPU1_P1_TX_DN<7>")
	)
	(segment
		(start 105.027984 -289.210242)
		(end 104.561132 -289.47618)
		(width 0.12954)
		(layer "F.Cu")
		(net "P5E_CPU1_P1_TX_DN<7>")
	)
	(segment
		(start 103.434134 -291.418772)
		(end 103.470456 -291.4396)
		(width 0.1143)
		(layer "In4.Cu")
		(net "P5E_CPU1_P1_TX_DN<7>")
	)
	(segment
		(start 103.94315 -294.800782)
		(end 103.873554 -294.841422)
		(width 0.1143)
		(layer "In4.Cu")
		(net "P5E_CPU1_P1_TX_DN<7>")
	)
	(segment
		(start 88.028272 -373.6721)
		(end 88.319102 -373.96293)
		(width 0.14224)
		(layer "In4.Cu")
		(net "P5E_CPU1_P1_TX_DN<7>")
	)
	(segment
		(start 103.94315 -289.940746)
		(end 103.904034 -289.963606)
		(width 0.1143)
		(layer "In4.Cu")
		(net "P5E_CPU1_P1_TX_DN<7>")
	)
	(segment
		(start 104.561132 -289.47618)
		(end 104.26319 -289.47618)
		(width 0.1143)
		(layer "In4.Cu")
		(net "P5E_CPU1_P1_TX_DN<7>")
	)
	(segment
		(start 103.470456 -291.4396)
		(end 103.47325 -291.441632)
		(width 0.1143)
		(layer "In4.Cu")
		(net "P5E_CPU1_P1_TX_DN<7>")
	)
	(segment
		(start 118.224046 -321.752976)
		(end 118.866412 -322.981828)
		(width 0.14224)
		(layer "In4.Cu")
		(net "P5E_CPU1_P1_TX_DN<7>")
	)
	(segment
		(start 103.402384 -291.400484)
		(end 103.433372 -291.418264)
		(width 0.1143)
		(layer "In4.Cu")
		(net "P5E_CPU1_P1_TX_DN<7>")
	)
	(segment
		(start 103.311706 -298.499022)
		(end 106.766614 -306.839874)
		(width 0.14224)
		(layer "In4.Cu")
		(net "P5E_CPU1_P1_TX_DN<7>")
	)
	(segment
		(start 103.435658 -290.772596)
		(end 103.434134 -290.773612)
		(width 0.1143)
		(layer "In4.Cu")
		(net "P5E_CPU1_P1_TX_DN<7>")
	)
	(segment
		(start 88.028272 -369.35791)
		(end 88.028272 -373.6721)
		(width 0.14224)
		(layer "In4.Cu")
		(net "P5E_CPU1_P1_TX_DN<7>")
	)
	(segment
		(start 123.400566 -338.407248)
		(end 123.400566 -344.515694)
		(width 0.14224)
		(layer "In4.Cu")
		(net "P5E_CPU1_P1_TX_DN<7>")
	)
	(segment
		(start 107.786678 -357.37927)
		(end 93.851476 -363.15142)
		(width 0.14224)
		(layer "In4.Cu")
		(net "P5E_CPU1_P1_TX_DN<7>")
	)
	(segment
		(start 103.716582 -295.146222)
		(end 103.716328 -295.145968)
		(width 0.1143)
		(layer "In4.Cu")
		(net "P5E_CPU1_P1_TX_DN<7>")
	)
	(segment
		(start 103.302054 -296.07891)
		(end 103.302054 -296.107358)
		(width 0.1143)
		(layer "In4.Cu")
		(net "P5E_CPU1_P1_TX_DN<7>")
	)
	(segment
		(start 110.191296 -311.965594)
		(end 118.224046 -321.752976)
		(width 0.14224)
		(layer "In4.Cu")
		(net "P5E_CPU1_P1_TX_DN<7>")
	)
	(segment
		(start 103.256334 -295.991788)
		(end 103.256334 -296.03319)
		(width 0.1143)
		(layer "In4.Cu")
		(net "P5E_CPU1_P1_TX_DN<7>")
	)
	(segment
		(start 106.766614 -306.839874)
		(end 110.191296 -311.965594)
		(width 0.14224)
		(layer "In4.Cu")
		(net "P5E_CPU1_P1_TX_DN<7>")
	)
	(segment
		(start 104.26319 -289.47618)
		(end 104.180386 -289.558984)
		(width 0.1143)
		(layer "In4.Cu")
		(net "P5E_CPU1_P1_TX_DN<7>")
	)
	(segment
		(start 103.562912 -295.632886)
		(end 103.293672 -295.901872)
		(width 0.1143)
		(layer "In4.Cu")
		(net "P5E_CPU1_P1_TX_DN<7>")
	)
	(segment
		(start 103.904034 -289.963606)
		(end 103.90124 -289.96513)
		(width 0.1143)
		(layer "In4.Cu")
		(net "P5E_CPU1_P1_TX_DN<7>")
	)
	(segment
		(start 103.433372 -291.418264)
		(end 103.434134 -291.418772)
		(width 0.1143)
		(layer "In4.Cu")
		(net "P5E_CPU1_P1_TX_DN<7>")
	)
	(segment
		(start 103.94315 -293.18077)
		(end 103.904034 -293.20363)
		(width 0.1143)
		(layer "In4.Cu")
		(net "P5E_CPU1_P1_TX_DN<7>")
	)
	(segment
		(start 103.716328 -295.145968)
		(end 103.716328 -295.262046)
		(width 0.1143)
		(layer "In4.Cu")
		(net "P5E_CPU1_P1_TX_DN<7>")
	)
	(segment
		(start 103.904034 -292.228778)
		(end 103.94315 -292.251638)
		(width 0.1143)
		(layer "In4.Cu")
		(net "P5E_CPU1_P1_TX_DN<7>")
	)
	(segment
		(start 103.256334 -296.03319)
		(end 103.302054 -296.07891)
		(width 0.1143)
		(layer "In4.Cu")
		(net "P5E_CPU1_P1_TX_DN<7>")
	)
	(segment
		(start 103.433118 -290.77412)
		(end 103.402384 -290.7919)
		(width 0.1143)
		(layer "In4.Cu")
		(net "P5E_CPU1_P1_TX_DN<7>")
	)
	(segment
		(start 103.904034 -293.20363)
		(end 103.873554 -293.22141)
		(width 0.1143)
		(layer "In4.Cu")
		(net "P5E_CPU1_P1_TX_DN<7>")
	)
	(segment
		(start 103.434134 -290.773612)
		(end 103.433118 -290.77412)
		(width 0.1143)
		(layer "In4.Cu")
		(net "P5E_CPU1_P1_TX_DN<7>")
	)
	(segment
		(start 121.379996 -348.29623)
		(end 107.786678 -357.37927)
		(width 0.14224)
		(layer "In4.Cu")
		(net "P5E_CPU1_P1_TX_DN<7>")
	)
	(segment
		(start 118.866412 -322.981828)
		(end 122.580146 -333.832708)
		(width 0.14224)
		(layer "In4.Cu")
		(net "P5E_CPU1_P1_TX_DN<7>")
	)
	(segment
		(start 103.873554 -293.83101)
		(end 103.904034 -293.84879)
		(width 0.1143)
		(layer "In4.Cu")
		(net "P5E_CPU1_P1_TX_DN<7>")
	)
	(segment
		(start 103.873554 -292.210998)
		(end 103.904034 -292.228778)
		(width 0.1143)
		(layer "In4.Cu")
		(net "P5E_CPU1_P1_TX_DN<7>")
	)
	(segment
		(start 91.524582 -364.395258)
		(end 89.0651 -366.85474)
		(width 0.14224)
		(layer "In4.Cu")
		(net "P5E_CPU1_P1_TX_DN<7>")
	)
	(segment
		(start 103.904034 -293.84879)
		(end 103.94315 -293.87165)
		(width 0.1143)
		(layer "In4.Cu")
		(net "P5E_CPU1_P1_TX_DN<7>")
	)
	(segment
		(start 103.302054 -296.107358)
		(end 103.302054 -298.450254)
		(width 0.14224)
		(layer "In4.Cu")
		(net "P5E_CPU1_P1_TX_DN<7>")
	)
	(segment
		(start 122.611896 -333.955136)
		(end 123.38939 -338.281264)
		(width 0.14224)
		(layer "In4.Cu")
		(net "P5E_CPU1_P1_TX_DN<7>")
	)
	(arc
		(start 123.400566 -344.515694)
		(mid 122.86374 -346.659016)
		(end 121.379996 -348.29623)
		(width 0.14224)
		(layer "In4.Cu")
		(net "P5E_CPU1_P1_TX_DN<7>")
	)
	(arc
		(start 104.176576 -289.581844)
		(mid 104.095143 -289.784242)
		(end 103.94315 -289.940746)
		(width 0.1143)
		(layer "In4.Cu")
		(net "P5E_CPU1_P1_TX_DN<7>")
	)
	(arc
		(start 103.873554 -293.22141)
		(mid 103.716577 -293.52621)
		(end 103.873554 -293.83101)
		(width 0.1143)
		(layer "In4.Cu")
		(net "P5E_CPU1_P1_TX_DN<7>")
	)
	(arc
		(start 103.302054 -298.450254)
		(mid 103.3045 -298.475107)
		(end 103.311706 -298.499022)
		(width 0.14224)
		(layer "In4.Cu")
		(net "P5E_CPU1_P1_TX_DN<7>")
	)
	(arc
		(start 103.873554 -294.841422)
		(mid 103.758127 -294.974798)
		(end 103.716582 -295.146222)
		(width 0.1143)
		(layer "In4.Cu")
		(net "P5E_CPU1_P1_TX_DN<7>")
	)
	(arc
		(start 103.90124 -289.96513)
		(mid 103.763834 -290.102531)
		(end 103.713534 -290.29025)
		(width 0.1143)
		(layer "In4.Cu")
		(net "P5E_CPU1_P1_TX_DN<7>")
	)
	(arc
		(start 103.713534 -290.29025)
		(mid 103.639093 -290.568576)
		(end 103.435658 -290.772596)
		(width 0.1143)
		(layer "In4.Cu")
		(net "P5E_CPU1_P1_TX_DN<7>")
	)
	(arc
		(start 103.402384 -290.7919)
		(mid 103.246456 -291.096192)
		(end 103.402384 -291.400484)
		(width 0.1143)
		(layer "In4.Cu")
		(net "P5E_CPU1_P1_TX_DN<7>")
	)
	(arc
		(start 122.580146 -333.832708)
		(mid 122.598349 -333.893318)
		(end 122.611896 -333.955136)
		(width 0.14224)
		(layer "In4.Cu")
		(net "P5E_CPU1_P1_TX_DN<7>")
	)
	(arc
		(start 103.47325 -291.441632)
		(mid 103.652063 -291.643982)
		(end 103.716582 -291.906198)
		(width 0.1143)
		(layer "In4.Cu")
		(net "P5E_CPU1_P1_TX_DN<7>")
	)
	(arc
		(start 103.716328 -295.262046)
		(mid 103.676504 -295.462724)
		(end 103.562912 -295.632886)
		(width 0.1143)
		(layer "In4.Cu")
		(net "P5E_CPU1_P1_TX_DN<7>")
	)
	(arc
		(start 103.94315 -293.87165)
		(mid 104.186477 -294.336216)
		(end 103.94315 -294.800782)
		(width 0.1143)
		(layer "In4.Cu")
		(net "P5E_CPU1_P1_TX_DN<7>")
	)
	(arc
		(start 103.716582 -291.906198)
		(mid 103.758131 -292.07762)
		(end 103.873554 -292.210998)
		(width 0.1143)
		(layer "In4.Cu")
		(net "P5E_CPU1_P1_TX_DN<7>")
	)
	(arc
		(start 93.851476 -363.15142)
		(mid 92.657466 -363.716163)
		(end 91.524582 -364.395258)
		(width 0.14224)
		(layer "In4.Cu")
		(net "P5E_CPU1_P1_TX_DN<7>")
	)
	(arc
		(start 89.0651 -366.85474)
		(mid 88.297721 -368.003204)
		(end 88.028272 -369.35791)
		(width 0.14224)
		(layer "In4.Cu")
		(net "P5E_CPU1_P1_TX_DN<7>")
	)
	(arc
		(start 103.293672 -295.901872)
		(mid 103.266053 -295.943112)
		(end 103.256334 -295.991788)
		(width 0.1143)
		(layer "In4.Cu")
		(net "P5E_CPU1_P1_TX_DN<7>")
	)
	(arc
		(start 123.38939 -338.281264)
		(mid 123.397788 -338.344007)
		(end 123.400566 -338.407248)
		(width 0.14224)
		(layer "In4.Cu")
		(net "P5E_CPU1_P1_TX_DN<7>")
	)
	(arc
		(start 104.180386 -289.558984)
		(mid 104.178598 -289.570433)
		(end 104.176576 -289.581844)
		(width 0.1143)
		(layer "In4.Cu")
		(net "P5E_CPU1_P1_TX_DN<7>")
	)
	(arc
		(start 103.94315 -292.251638)
		(mid 104.186477 -292.716204)
		(end 103.94315 -293.18077)
		(width 0.1143)
		(layer "In4.Cu")
		(net "P5E_CPU1_P1_TX_DN<7>")
	)
	(segment
		(start 84.940902 -370.30533)
		(end 84.644992 -370.00942)
		(width 0.12954)
		(layer "F.Cu")
		(net "P5E_CPU1_P1_TX_DN<6>")
	)
	(segment
		(start 84.644992 -369.30584)
		(end 84.915502 -369.03533)
		(width 0.12954)
		(layer "F.Cu")
		(net "P5E_CPU1_P1_TX_DN<6>")
	)
	(segment
		(start 84.644992 -370.00942)
		(end 84.644992 -369.30584)
		(width 0.12954)
		(layer "F.Cu")
		(net "P5E_CPU1_P1_TX_DN<6>")
	)
	(segment
		(start 102.207822 -287.590484)
		(end 101.74097 -287.856422)
		(width 0.12954)
		(layer "F.Cu")
		(net "P5E_CPU1_P1_TX_DN<6>")
	)
	(segment
		(start 109.404658 -312.478166)
		(end 117.423692 -322.248784)
		(width 0.14224)
		(layer "In4.Cu")
		(net "P5E_CPU1_P1_TX_DN<6>")
	)
	(segment
		(start 102.518972 -289.811714)
		(end 102.53345 -289.821874)
		(width 0.1143)
		(layer "In4.Cu")
		(net "P5E_CPU1_P1_TX_DN<6>")
	)
	(segment
		(start 101.521514 -288.159952)
		(end 101.554026 -288.178748)
		(width 0.1143)
		(layer "In4.Cu")
		(net "P5E_CPU1_P1_TX_DN<6>")
	)
	(segment
		(start 102.480872 -289.79114)
		(end 102.518972 -289.811714)
		(width 0.1143)
		(layer "In4.Cu")
		(net "P5E_CPU1_P1_TX_DN<6>")
	)
	(segment
		(start 103.003096 -294.800782)
		(end 102.9335 -294.841422)
		(width 0.1143)
		(layer "In4.Cu")
		(net "P5E_CPU1_P1_TX_DN<6>")
	)
	(segment
		(start 103.003096 -293.18077)
		(end 102.96398 -293.20363)
		(width 0.1143)
		(layer "In4.Cu")
		(net "P5E_CPU1_P1_TX_DN<6>")
	)
	(segment
		(start 105.953052 -307.312314)
		(end 109.404658 -312.478166)
		(width 0.14224)
		(layer "In4.Cu")
		(net "P5E_CPU1_P1_TX_DN<6>")
	)
	(segment
		(start 102.96398 -293.84879)
		(end 103.003096 -293.87165)
		(width 0.1143)
		(layer "In4.Cu")
		(net "P5E_CPU1_P1_TX_DN<6>")
	)
	(segment
		(start 106.725974 -356.809294)
		(end 92.53855 -362.686092)
		(width 0.14224)
		(layer "In4.Cu")
		(net "P5E_CPU1_P1_TX_DN<6>")
	)
	(segment
		(start 113.755932 -352.116136)
		(end 106.725974 -356.809294)
		(width 0.14224)
		(layer "In4.Cu")
		(net "P5E_CPU1_P1_TX_DN<6>")
	)
	(segment
		(start 117.872002 -323.106542)
		(end 121.698258 -334.286606)
		(width 0.14224)
		(layer "In4.Cu")
		(net "P5E_CPU1_P1_TX_DN<6>")
	)
	(segment
		(start 102.486206 -291.4142)
		(end 102.501192 -291.422836)
		(width 0.1143)
		(layer "In4.Cu")
		(net "P5E_CPU1_P1_TX_DN<6>")
	)
	(segment
		(start 102.824534 -294.96258)
		(end 102.768654 -295.061894)
		(width 0.1143)
		(layer "In4.Cu")
		(net "P5E_CPU1_P1_TX_DN<6>")
	)
	(segment
		(start 102.023418 -288.988246)
		(end 102.02418 -288.988754)
		(width 0.1143)
		(layer "In4.Cu")
		(net "P5E_CPU1_P1_TX_DN<6>")
	)
	(segment
		(start 121.740676 -334.450182)
		(end 122.409458 -338.170774)
		(width 0.14224)
		(layer "In4.Cu")
		(net "P5E_CPU1_P1_TX_DN<6>")
	)
	(segment
		(start 101.74097 -287.856422)
		(end 101.443282 -287.856422)
		(width 0.1143)
		(layer "In4.Cu")
		(net "P5E_CPU1_P1_TX_DN<6>")
	)
	(segment
		(start 88.319864 -364.94085)
		(end 88.316308 -364.94339)
		(width 0.14224)
		(layer "In4.Cu")
		(net "P5E_CPU1_P1_TX_DN<6>")
	)
	(segment
		(start 102.357174 -296.20591)
		(end 102.357174 -296.234358)
		(width 0.1143)
		(layer "In4.Cu")
		(net "P5E_CPU1_P1_TX_DN<6>")
	)
	(segment
		(start 113.755932 -352.11639)
		(end 113.755932 -352.116136)
		(width 0.14224)
		(layer "In4.Cu")
		(net "P5E_CPU1_P1_TX_DN<6>")
	)
	(segment
		(start 85.519768 -367.237518)
		(end 84.66201 -368.095276)
		(width 0.14224)
		(layer "In4.Cu")
		(net "P5E_CPU1_P1_TX_DN<6>")
	)
	(segment
		(start 102.96398 -292.228778)
		(end 103.003096 -292.251638)
		(width 0.1143)
		(layer "In4.Cu")
		(net "P5E_CPU1_P1_TX_DN<6>")
	)
	(segment
		(start 117.423692 -322.248784)
		(end 117.872002 -323.106542)
		(width 0.14224)
		(layer "In4.Cu")
		(net "P5E_CPU1_P1_TX_DN<6>")
	)
	(segment
		(start 101.443282 -287.856422)
		(end 101.373432 -287.926272)
		(width 0.1143)
		(layer "In4.Cu")
		(net "P5E_CPU1_P1_TX_DN<6>")
	)
	(segment
		(start 102.53345 -289.821874)
		(end 102.583742 -289.856926)
		(width 0.1143)
		(layer "In4.Cu")
		(net "P5E_CPU1_P1_TX_DN<6>")
	)
	(segment
		(start 102.68331 -295.572434)
		(end 102.348792 -295.906952)
		(width 0.1143)
		(layer "In4.Cu")
		(net "P5E_CPU1_P1_TX_DN<6>")
	)
	(segment
		(start 102.293674 -289.456876)
		(end 102.293674 -289.466528)
		(width 0.1143)
		(layer "In4.Cu")
		(net "P5E_CPU1_P1_TX_DN<6>")
	)
	(segment
		(start 102.357174 -296.234358)
		(end 102.357174 -298.598844)
		(width 0.14224)
		(layer "In4.Cu")
		(net "P5E_CPU1_P1_TX_DN<6>")
	)
	(segment
		(start 102.502716 -291.423852)
		(end 102.532434 -291.441124)
		(width 0.1143)
		(layer "In4.Cu")
		(net "P5E_CPU1_P1_TX_DN<6>")
	)
	(segment
		(start 102.369366 -298.660566)
		(end 105.953052 -307.312314)
		(width 0.14224)
		(layer "In4.Cu")
		(net "P5E_CPU1_P1_TX_DN<6>")
	)
	(segment
		(start 101.554026 -288.178748)
		(end 101.593142 -288.201608)
		(width 0.1143)
		(layer "In4.Cu")
		(net "P5E_CPU1_P1_TX_DN<6>")
	)
	(segment
		(start 84.624672 -368.7445)
		(end 84.915502 -369.03533)
		(width 0.14224)
		(layer "In4.Cu")
		(net "P5E_CPU1_P1_TX_DN<6>")
	)
	(segment
		(start 101.99243 -288.970466)
		(end 102.023418 -288.988246)
		(width 0.1143)
		(layer "In4.Cu")
		(net "P5E_CPU1_P1_TX_DN<6>")
	)
	(segment
		(start 102.501192 -291.422836)
		(end 102.502716 -291.423852)
		(width 0.1143)
		(layer "In4.Cu")
		(net "P5E_CPU1_P1_TX_DN<6>")
	)
	(segment
		(start 102.9335 -293.83101)
		(end 102.96398 -293.84879)
		(width 0.1143)
		(layer "In4.Cu")
		(net "P5E_CPU1_P1_TX_DN<6>")
	)
	(segment
		(start 102.96398 -293.20363)
		(end 102.9335 -293.22141)
		(width 0.1143)
		(layer "In4.Cu")
		(net "P5E_CPU1_P1_TX_DN<6>")
	)
	(segment
		(start 88.316308 -364.94339)
		(end 88.312498 -364.945676)
		(width 0.14224)
		(layer "In4.Cu")
		(net "P5E_CPU1_P1_TX_DN<6>")
	)
	(segment
		(start 120.76303 -347.438218)
		(end 113.755932 -352.11639)
		(width 0.14224)
		(layer "In4.Cu")
		(net "P5E_CPU1_P1_TX_DN<6>")
	)
	(segment
		(start 102.9335 -292.210998)
		(end 102.96398 -292.228778)
		(width 0.1143)
		(layer "In4.Cu")
		(net "P5E_CPU1_P1_TX_DN<6>")
	)
	(segment
		(start 102.768654 -295.061894)
		(end 102.768654 -295.36644)
		(width 0.1143)
		(layer "In4.Cu")
		(net "P5E_CPU1_P1_TX_DN<6>")
	)
	(segment
		(start 102.669594 -290.671504)
		(end 102.493318 -290.773866)
		(width 0.1143)
		(layer "In4.Cu")
		(net "P5E_CPU1_P1_TX_DN<6>")
	)
	(segment
		(start 84.624672 -368.185446)
		(end 84.624672 -368.7445)
		(width 0.14224)
		(layer "In4.Cu")
		(net "P5E_CPU1_P1_TX_DN<6>")
	)
	(segment
		(start 102.311454 -296.16019)
		(end 102.357174 -296.20591)
		(width 0.1143)
		(layer "In4.Cu")
		(net "P5E_CPU1_P1_TX_DN<6>")
	)
	(segment
		(start 102.311454 -295.997122)
		(end 102.311454 -296.16019)
		(width 0.1143)
		(layer "In4.Cu")
		(net "P5E_CPU1_P1_TX_DN<6>")
	)
	(segment
		(start 102.76205 -290.403534)
		(end 102.669594 -290.671504)
		(width 0.1143)
		(layer "In4.Cu")
		(net "P5E_CPU1_P1_TX_DN<6>")
	)
	(segment
		(start 122.424952 -338.346796)
		(end 122.424952 -344.330274)
		(width 0.14224)
		(layer "In4.Cu")
		(net "P5E_CPU1_P1_TX_DN<6>")
	)
	(arc
		(start 102.9335 -293.22141)
		(mid 102.776523 -293.52621)
		(end 102.9335 -293.83101)
		(width 0.1143)
		(layer "In4.Cu")
		(net "P5E_CPU1_P1_TX_DN<6>")
	)
	(arc
		(start 101.593142 -288.201608)
		(mid 101.771955 -288.403958)
		(end 101.836474 -288.666174)
		(width 0.1143)
		(layer "In4.Cu")
		(net "P5E_CPU1_P1_TX_DN<6>")
	)
	(arc
		(start 102.533196 -291.441632)
		(mid 102.712009 -291.643982)
		(end 102.776528 -291.906198)
		(width 0.1143)
		(layer "In4.Cu")
		(net "P5E_CPU1_P1_TX_DN<6>")
	)
	(arc
		(start 88.312498 -364.945676)
		(mid 86.859861 -366.023028)
		(end 85.519768 -367.237518)
		(width 0.14224)
		(layer "In4.Cu")
		(net "P5E_CPU1_P1_TX_DN<6>")
	)
	(arc
		(start 103.003096 -293.87165)
		(mid 103.246423 -294.336216)
		(end 103.003096 -294.800782)
		(width 0.1143)
		(layer "In4.Cu")
		(net "P5E_CPU1_P1_TX_DN<6>")
	)
	(arc
		(start 102.776528 -291.906198)
		(mid 102.818077 -292.07762)
		(end 102.9335 -292.210998)
		(width 0.1143)
		(layer "In4.Cu")
		(net "P5E_CPU1_P1_TX_DN<6>")
	)
	(arc
		(start 102.02418 -288.988754)
		(mid 102.221504 -289.186794)
		(end 102.293674 -289.456876)
		(width 0.1143)
		(layer "In4.Cu")
		(net "P5E_CPU1_P1_TX_DN<6>")
	)
	(arc
		(start 103.003096 -292.251638)
		(mid 103.246423 -292.716204)
		(end 103.003096 -293.18077)
		(width 0.1143)
		(layer "In4.Cu")
		(net "P5E_CPU1_P1_TX_DN<6>")
	)
	(arc
		(start 102.493318 -290.773866)
		(mid 102.307923 -291.092032)
		(end 102.486206 -291.4142)
		(width 0.1143)
		(layer "In4.Cu")
		(net "P5E_CPU1_P1_TX_DN<6>")
	)
	(arc
		(start 102.357174 -298.598844)
		(mid 102.360222 -298.630308)
		(end 102.369366 -298.660566)
		(width 0.14224)
		(layer "In4.Cu")
		(net "P5E_CPU1_P1_TX_DN<6>")
	)
	(arc
		(start 102.583742 -289.856926)
		(mid 102.764663 -290.100302)
		(end 102.76205 -290.403534)
		(width 0.1143)
		(layer "In4.Cu")
		(net "P5E_CPU1_P1_TX_DN<6>")
	)
	(arc
		(start 92.53855 -362.686092)
		(mid 90.373859 -363.709914)
		(end 88.319864 -364.94085)
		(width 0.14224)
		(layer "In4.Cu")
		(net "P5E_CPU1_P1_TX_DN<6>")
	)
	(arc
		(start 102.532434 -291.441124)
		(mid 102.532815 -291.441378)
		(end 102.533196 -291.441632)
		(width 0.1143)
		(layer "In4.Cu")
		(net "P5E_CPU1_P1_TX_DN<6>")
	)
	(arc
		(start 122.424952 -344.330274)
		(mid 121.983389 -346.092475)
		(end 120.76303 -347.438218)
		(width 0.14224)
		(layer "In4.Cu")
		(net "P5E_CPU1_P1_TX_DN<6>")
	)
	(arc
		(start 101.836474 -288.666174)
		(mid 101.877729 -288.837145)
		(end 101.99243 -288.970466)
		(width 0.1143)
		(layer "In4.Cu")
		(net "P5E_CPU1_P1_TX_DN<6>")
	)
	(arc
		(start 101.373432 -287.926272)
		(mid 101.42514 -288.057255)
		(end 101.521514 -288.159952)
		(width 0.1143)
		(layer "In4.Cu")
		(net "P5E_CPU1_P1_TX_DN<6>")
	)
	(arc
		(start 121.698258 -334.286606)
		(mid 121.722567 -334.36759)
		(end 121.740676 -334.450182)
		(width 0.14224)
		(layer "In4.Cu")
		(net "P5E_CPU1_P1_TX_DN<6>")
	)
	(arc
		(start 122.409458 -338.170774)
		(mid 122.421119 -338.25844)
		(end 122.424952 -338.346796)
		(width 0.14224)
		(layer "In4.Cu")
		(net "P5E_CPU1_P1_TX_DN<6>")
	)
	(arc
		(start 102.293674 -289.466528)
		(mid 102.343818 -289.653902)
		(end 102.480872 -289.79114)
		(width 0.1143)
		(layer "In4.Cu")
		(net "P5E_CPU1_P1_TX_DN<6>")
	)
	(arc
		(start 84.66201 -368.095276)
		(mid 84.634367 -368.136646)
		(end 84.624672 -368.185446)
		(width 0.14224)
		(layer "In4.Cu")
		(net "P5E_CPU1_P1_TX_DN<6>")
	)
	(arc
		(start 102.348792 -295.906952)
		(mid 102.321149 -295.948322)
		(end 102.311454 -295.997122)
		(width 0.1143)
		(layer "In4.Cu")
		(net "P5E_CPU1_P1_TX_DN<6>")
	)
	(arc
		(start 102.768654 -295.36644)
		(mid 102.746477 -295.47793)
		(end 102.68331 -295.572434)
		(width 0.1143)
		(layer "In4.Cu")
		(net "P5E_CPU1_P1_TX_DN<6>")
	)
	(arc
		(start 102.9335 -294.841422)
		(mid 102.872356 -294.896008)
		(end 102.824534 -294.96258)
		(width 0.1143)
		(layer "In4.Cu")
		(net "P5E_CPU1_P1_TX_DN<6>")
	)
	(segment
		(start 102.207822 -290.830254)
		(end 101.74097 -291.096192)
		(width 0.12954)
		(layer "F.Cu")
		(net "P5E_CPU1_P1_TX_DN<5>")
	)
	(segment
		(start 83.239102 -372.76913)
		(end 82.943192 -372.47322)
		(width 0.12954)
		(layer "F.Cu")
		(net "P5E_CPU1_P1_TX_DN<5>")
	)
	(segment
		(start 82.943192 -371.76964)
		(end 83.213702 -371.49913)
		(width 0.12954)
		(layer "F.Cu")
		(net "P5E_CPU1_P1_TX_DN<5>")
	)
	(segment
		(start 82.943192 -372.47322)
		(end 82.943192 -371.76964)
		(width 0.12954)
		(layer "F.Cu")
		(net "P5E_CPU1_P1_TX_DN<5>")
	)
	(segment
		(start 102.002844 -293.836344)
		(end 102.062534 -293.871142)
		(width 0.1143)
		(layer "In4.Cu")
		(net "P5E_CPU1_P1_TX_DN<5>")
	)
	(segment
		(start 120.484392 -346.012516)
		(end 104.68737 -356.56774)
		(width 0.14224)
		(layer "In4.Cu")
		(net "P5E_CPU1_P1_TX_DN<5>")
	)
	(segment
		(start 101.412294 -296.234358)
		(end 101.412294 -298.760896)
		(width 0.14224)
		(layer "In4.Cu")
		(net "P5E_CPU1_P1_TX_DN<5>")
	)
	(segment
		(start 101.412294 -296.20591)
		(end 101.412294 -296.234358)
		(width 0.1143)
		(layer "In4.Cu")
		(net "P5E_CPU1_P1_TX_DN<5>")
	)
	(segment
		(start 102.002336 -293.836344)
		(end 102.002844 -293.836344)
		(width 0.1143)
		(layer "In4.Cu")
		(net "P5E_CPU1_P1_TX_DN<5>")
	)
	(segment
		(start 101.366574 -296.16019)
		(end 101.412294 -296.20591)
		(width 0.1143)
		(layer "In4.Cu")
		(net "P5E_CPU1_P1_TX_DN<5>")
	)
	(segment
		(start 116.96573 -323.38645)
		(end 120.784366 -334.543908)
		(width 0.14224)
		(layer "In4.Cu")
		(net "P5E_CPU1_P1_TX_DN<5>")
	)
	(segment
		(start 120.826784 -334.707484)
		(end 121.45899 -338.22386)
		(width 0.14224)
		(layer "In4.Cu")
		(net "P5E_CPU1_P1_TX_DN<5>")
	)
	(segment
		(start 116.664486 -322.80987)
		(end 116.96573 -323.38645)
		(width 0.14224)
		(layer "In4.Cu")
		(net "P5E_CPU1_P1_TX_DN<5>")
	)
	(segment
		(start 105.243376 -308.035706)
		(end 107.928156 -312.05297)
		(width 0.14224)
		(layer "In4.Cu")
		(net "P5E_CPU1_P1_TX_DN<5>")
	)
	(segment
		(start 101.524308 -291.4015)
		(end 101.556566 -291.420296)
		(width 0.1143)
		(layer "In4.Cu")
		(net "P5E_CPU1_P1_TX_DN<5>")
	)
	(segment
		(start 102.065328 -294.799258)
		(end 101.99243 -294.84193)
		(width 0.1143)
		(layer "In4.Cu")
		(net "P5E_CPU1_P1_TX_DN<5>")
	)
	(segment
		(start 102.023926 -293.20363)
		(end 102.008178 -293.213028)
		(width 0.1143)
		(layer "In4.Cu")
		(net "P5E_CPU1_P1_TX_DN<5>")
	)
	(segment
		(start 88.049354 -363.89437)
		(end 88.049354 -363.894624)
		(width 0.14224)
		(layer "In4.Cu")
		(net "P5E_CPU1_P1_TX_DN<5>")
	)
	(segment
		(start 102.063042 -293.18077)
		(end 102.023926 -293.20363)
		(width 0.1143)
		(layer "In4.Cu")
		(net "P5E_CPU1_P1_TX_DN<5>")
	)
	(segment
		(start 101.593142 -295.610788)
		(end 101.548946 -295.636188)
		(width 0.1143)
		(layer "In4.Cu")
		(net "P5E_CPU1_P1_TX_DN<5>")
	)
	(segment
		(start 108.785914 -313.20994)
		(end 116.664486 -322.80987)
		(width 0.14224)
		(layer "In4.Cu")
		(net "P5E_CPU1_P1_TX_DN<5>")
	)
	(segment
		(start 82.922872 -369.004596)
		(end 82.922872 -371.2083)
		(width 0.14224)
		(layer "In4.Cu")
		(net "P5E_CPU1_P1_TX_DN<5>")
	)
	(segment
		(start 102.008178 -293.213028)
		(end 102.00259 -293.216076)
		(width 0.1143)
		(layer "In4.Cu")
		(net "P5E_CPU1_P1_TX_DN<5>")
	)
	(segment
		(start 107.928156 -312.05297)
		(end 108.785914 -313.20994)
		(width 0.14224)
		(layer "In4.Cu")
		(net "P5E_CPU1_P1_TX_DN<5>")
	)
	(segment
		(start 101.443028 -291.096192)
		(end 101.373178 -291.166042)
		(width 0.1143)
		(layer "In4.Cu")
		(net "P5E_CPU1_P1_TX_DN<5>")
	)
	(segment
		(start 104.68737 -356.56774)
		(end 91.666568 -361.960922)
		(width 0.14224)
		(layer "In4.Cu")
		(net "P5E_CPU1_P1_TX_DN<5>")
	)
	(segment
		(start 101.74097 -291.096192)
		(end 101.443028 -291.096192)
		(width 0.1143)
		(layer "In4.Cu")
		(net "P5E_CPU1_P1_TX_DN<5>")
	)
	(segment
		(start 82.922872 -371.2083)
		(end 83.213702 -371.49913)
		(width 0.14224)
		(layer "In4.Cu")
		(net "P5E_CPU1_P1_TX_DN<5>")
	)
	(segment
		(start 101.548946 -295.636188)
		(end 101.436678 -295.748456)
		(width 0.1143)
		(layer "In4.Cu")
		(net "P5E_CPU1_P1_TX_DN<5>")
	)
	(segment
		(start 88.049354 -363.894624)
		(end 88.048592 -363.895132)
		(width 0.14224)
		(layer "In4.Cu")
		(net "P5E_CPU1_P1_TX_DN<5>")
	)
	(segment
		(start 101.366574 -295.917874)
		(end 101.366574 -296.16019)
		(width 0.1143)
		(layer "In4.Cu")
		(net "P5E_CPU1_P1_TX_DN<5>")
	)
	(segment
		(start 84.756244 -366.59693)
		(end 83.329018 -368.024156)
		(width 0.14224)
		(layer "In4.Cu")
		(net "P5E_CPU1_P1_TX_DN<5>")
	)
	(segment
		(start 102.063296 -293.87165)
		(end 102.065328 -293.873174)
		(width 0.1143)
		(layer "In4.Cu")
		(net "P5E_CPU1_P1_TX_DN<5>")
	)
	(segment
		(start 101.421946 -298.809664)
		(end 105.243376 -308.035706)
		(width 0.14224)
		(layer "In4.Cu")
		(net "P5E_CPU1_P1_TX_DN<5>")
	)
	(segment
		(start 101.556566 -291.420296)
		(end 101.558598 -291.421566)
		(width 0.1143)
		(layer "In4.Cu")
		(net "P5E_CPU1_P1_TX_DN<5>")
	)
	(segment
		(start 102.0191 -292.225984)
		(end 102.061518 -292.250622)
		(width 0.1143)
		(layer "In4.Cu")
		(net "P5E_CPU1_P1_TX_DN<5>")
	)
	(segment
		(start 121.474484 -338.399882)
		(end 121.474484 -344.160348)
		(width 0.14224)
		(layer "In4.Cu")
		(net "P5E_CPU1_P1_TX_DN<5>")
	)
	(arc
		(start 121.45899 -338.22386)
		(mid 121.470654 -338.311526)
		(end 121.474484 -338.399882)
		(width 0.14224)
		(layer "In4.Cu")
		(net "P5E_CPU1_P1_TX_DN<5>")
	)
	(arc
		(start 101.373178 -291.166042)
		(mid 101.425923 -291.298418)
		(end 101.524308 -291.4015)
		(width 0.1143)
		(layer "In4.Cu")
		(net "P5E_CPU1_P1_TX_DN<5>")
	)
	(arc
		(start 102.065328 -293.873174)
		(mid 102.307839 -294.336216)
		(end 102.065328 -294.799258)
		(width 0.1143)
		(layer "In4.Cu")
		(net "P5E_CPU1_P1_TX_DN<5>")
	)
	(arc
		(start 121.474484 -344.160348)
		(mid 121.211436 -345.210455)
		(end 120.484392 -346.012516)
		(width 0.14224)
		(layer "In4.Cu")
		(net "P5E_CPU1_P1_TX_DN<5>")
	)
	(arc
		(start 83.329018 -368.024156)
		(mid 83.028451 -368.473986)
		(end 82.922872 -369.004596)
		(width 0.14224)
		(layer "In4.Cu")
		(net "P5E_CPU1_P1_TX_DN<5>")
	)
	(arc
		(start 101.558598 -291.421566)
		(mid 101.762125 -291.626991)
		(end 101.836474 -291.906452)
		(width 0.1143)
		(layer "In4.Cu")
		(net "P5E_CPU1_P1_TX_DN<5>")
	)
	(arc
		(start 88.048592 -363.895132)
		(mid 86.336053 -365.165161)
		(end 84.756244 -366.59693)
		(width 0.14224)
		(layer "In4.Cu")
		(net "P5E_CPU1_P1_TX_DN<5>")
	)
	(arc
		(start 101.99243 -294.84193)
		(mid 101.877754 -294.975264)
		(end 101.836474 -295.146222)
		(width 0.1143)
		(layer "In4.Cu")
		(net "P5E_CPU1_P1_TX_DN<5>")
	)
	(arc
		(start 102.00259 -293.216076)
		(mid 101.824048 -293.5261)
		(end 102.002336 -293.836344)
		(width 0.1143)
		(layer "In4.Cu")
		(net "P5E_CPU1_P1_TX_DN<5>")
	)
	(arc
		(start 102.061518 -292.250622)
		(mid 102.06228 -292.251129)
		(end 102.063042 -292.251638)
		(width 0.1143)
		(layer "In4.Cu")
		(net "P5E_CPU1_P1_TX_DN<5>")
	)
	(arc
		(start 101.836474 -291.906452)
		(mid 101.885426 -292.090414)
		(end 102.0191 -292.225984)
		(width 0.1143)
		(layer "In4.Cu")
		(net "P5E_CPU1_P1_TX_DN<5>")
	)
	(arc
		(start 120.784366 -334.543908)
		(mid 120.80867 -334.624893)
		(end 120.826784 -334.707484)
		(width 0.14224)
		(layer "In4.Cu")
		(net "P5E_CPU1_P1_TX_DN<5>")
	)
	(arc
		(start 91.666568 -361.960922)
		(mid 89.810478 -362.838812)
		(end 88.049354 -363.89437)
		(width 0.14224)
		(layer "In4.Cu")
		(net "P5E_CPU1_P1_TX_DN<5>")
	)
	(arc
		(start 101.412294 -298.760896)
		(mid 101.41474 -298.785749)
		(end 101.421946 -298.809664)
		(width 0.14224)
		(layer "In4.Cu")
		(net "P5E_CPU1_P1_TX_DN<5>")
	)
	(arc
		(start 101.836474 -295.146222)
		(mid 101.771959 -295.408441)
		(end 101.593142 -295.610788)
		(width 0.1143)
		(layer "In4.Cu")
		(net "P5E_CPU1_P1_TX_DN<5>")
	)
	(arc
		(start 102.062534 -293.871142)
		(mid 102.062915 -293.871396)
		(end 102.063296 -293.87165)
		(width 0.1143)
		(layer "In4.Cu")
		(net "P5E_CPU1_P1_TX_DN<5>")
	)
	(arc
		(start 101.436678 -295.748456)
		(mid 101.384794 -295.8262)
		(end 101.366574 -295.917874)
		(width 0.1143)
		(layer "In4.Cu")
		(net "P5E_CPU1_P1_TX_DN<5>")
	)
	(arc
		(start 102.063042 -292.251638)
		(mid 102.306369 -292.716204)
		(end 102.063042 -293.18077)
		(width 0.1143)
		(layer "In4.Cu")
		(net "P5E_CPU1_P1_TX_DN<5>")
	)
	(segment
		(start 102.207822 -289.210242)
		(end 101.74097 -289.47618)
		(width 0.12954)
		(layer "F.Cu")
		(net "P5E_CPU1_P1_TX_DN<4>")
	)
	(segment
		(start 81.537302 -375.23293)
		(end 81.241392 -374.93702)
		(width 0.12954)
		(layer "F.Cu")
		(net "P5E_CPU1_P1_TX_DN<4>")
	)
	(segment
		(start 81.241392 -374.93702)
		(end 81.241392 -374.23344)
		(width 0.12954)
		(layer "F.Cu")
		(net "P5E_CPU1_P1_TX_DN<4>")
	)
	(segment
		(start 81.241392 -374.23344)
		(end 81.511902 -373.96293)
		(width 0.12954)
		(layer "F.Cu")
		(net "P5E_CPU1_P1_TX_DN<4>")
	)
	(segment
		(start 84.509356 -364.930944)
		(end 82.156046 -367.284254)
		(width 0.14224)
		(layer "In4.Cu")
		(net "P5E_CPU1_P1_TX_DN<4>")
	)
	(segment
		(start 100.621846 -291.423344)
		(end 100.653342 -291.441632)
		(width 0.1143)
		(layer "In4.Cu")
		(net "P5E_CPU1_P1_TX_DN<4>")
	)
	(segment
		(start 100.896674 -295.016428)
		(end 100.896674 -295.268904)
		(width 0.1143)
		(layer "In4.Cu")
		(net "P5E_CPU1_P1_TX_DN<4>")
	)
	(segment
		(start 115.970812 -323.496432)
		(end 119.911114 -335.00822)
		(width 0.14224)
		(layer "In4.Cu")
		(net "P5E_CPU1_P1_TX_DN<4>")
	)
	(segment
		(start 100.614226 -290.773612)
		(end 100.613464 -290.77412)
		(width 0.1143)
		(layer "In4.Cu")
		(net "P5E_CPU1_P1_TX_DN<4>")
	)
	(segment
		(start 81.221072 -373.6721)
		(end 81.511902 -373.96293)
		(width 0.14224)
		(layer "In4.Cu")
		(net "P5E_CPU1_P1_TX_DN<4>")
	)
	(segment
		(start 100.620322 -291.422328)
		(end 100.621846 -291.423344)
		(width 0.1143)
		(layer "In4.Cu")
		(net "P5E_CPU1_P1_TX_DN<4>")
	)
	(segment
		(start 100.997258 -294.88257)
		(end 100.951792 -294.912034)
		(width 0.1143)
		(layer "In4.Cu")
		(net "P5E_CPU1_P1_TX_DN<4>")
	)
	(segment
		(start 103.928926 -355.8286)
		(end 90.704162 -361.306364)
		(width 0.14224)
		(layer "In4.Cu")
		(net "P5E_CPU1_P1_TX_DN<4>")
	)
	(segment
		(start 101.74097 -289.47618)
		(end 101.443282 -289.47618)
		(width 0.1143)
		(layer "In4.Cu")
		(net "P5E_CPU1_P1_TX_DN<4>")
	)
	(segment
		(start 100.46716 -296.07891)
		(end 100.46716 -296.107358)
		(width 0.1143)
		(layer "In4.Cu")
		(net "P5E_CPU1_P1_TX_DN<4>")
	)
	(segment
		(start 100.613464 -290.77412)
		(end 100.612194 -290.774882)
		(width 0.1143)
		(layer "In4.Cu")
		(net "P5E_CPU1_P1_TX_DN<4>")
	)
	(segment
		(start 107.439968 -313.040268)
		(end 115.881912 -323.326506)
		(width 0.14224)
		(layer "In4.Cu")
		(net "P5E_CPU1_P1_TX_DN<4>")
	)
	(segment
		(start 100.653342 -290.750752)
		(end 100.615242 -290.773104)
		(width 0.1143)
		(layer "In4.Cu")
		(net "P5E_CPU1_P1_TX_DN<4>")
	)
	(segment
		(start 100.476812 -298.964858)
		(end 104.459278 -308.579266)
		(width 0.14224)
		(layer "In4.Cu")
		(net "P5E_CPU1_P1_TX_DN<4>")
	)
	(segment
		(start 100.42144 -295.981882)
		(end 100.42144 -296.03319)
		(width 0.1143)
		(layer "In4.Cu")
		(net "P5E_CPU1_P1_TX_DN<4>")
	)
	(segment
		(start 100.616766 -291.420296)
		(end 100.617782 -291.420804)
		(width 0.1143)
		(layer "In4.Cu")
		(net "P5E_CPU1_P1_TX_DN<4>")
	)
	(segment
		(start 120.516396 -338.410296)
		(end 120.516396 -343.724738)
		(width 0.14224)
		(layer "In4.Cu")
		(net "P5E_CPU1_P1_TX_DN<4>")
	)
	(segment
		(start 100.617782 -291.420804)
		(end 100.620322 -291.422328)
		(width 0.1143)
		(layer "In4.Cu")
		(net "P5E_CPU1_P1_TX_DN<4>")
	)
	(segment
		(start 100.582476 -291.400484)
		(end 100.613464 -291.418264)
		(width 0.1143)
		(layer "In4.Cu")
		(net "P5E_CPU1_P1_TX_DN<4>")
	)
	(segment
		(start 100.46716 -296.107358)
		(end 100.46716 -298.91609)
		(width 0.14224)
		(layer "In4.Cu")
		(net "P5E_CPU1_P1_TX_DN<4>")
	)
	(segment
		(start 101.123242 -289.940746)
		(end 101.084126 -289.963606)
		(width 0.1143)
		(layer "In4.Cu")
		(net "P5E_CPU1_P1_TX_DN<4>")
	)
	(segment
		(start 101.053646 -292.210998)
		(end 101.084126 -292.228778)
		(width 0.1143)
		(layer "In4.Cu")
		(net "P5E_CPU1_P1_TX_DN<4>")
	)
	(segment
		(start 100.615242 -291.41928)
		(end 100.616766 -291.420296)
		(width 0.1143)
		(layer "In4.Cu")
		(net "P5E_CPU1_P1_TX_DN<4>")
	)
	(segment
		(start 111.869728 -350.54413)
		(end 111.869728 -350.543876)
		(width 0.14224)
		(layer "In4.Cu")
		(net "P5E_CPU1_P1_TX_DN<4>")
	)
	(segment
		(start 100.80371 -295.49344)
		(end 100.496624 -295.800526)
		(width 0.1143)
		(layer "In4.Cu")
		(net "P5E_CPU1_P1_TX_DN<4>")
	)
	(segment
		(start 101.192584 -294.748458)
		(end 101.14788 -294.784526)
		(width 0.1143)
		(layer "In4.Cu")
		(net "P5E_CPU1_P1_TX_DN<4>")
	)
	(segment
		(start 100.951792 -294.912034)
		(end 100.951538 -294.912288)
		(width 0.1143)
		(layer "In4.Cu")
		(net "P5E_CPU1_P1_TX_DN<4>")
	)
	(segment
		(start 100.612194 -290.774882)
		(end 100.582476 -290.7919)
		(width 0.1143)
		(layer "In4.Cu")
		(net "P5E_CPU1_P1_TX_DN<4>")
	)
	(segment
		(start 119.65051 -345.34475)
		(end 111.869728 -350.54413)
		(width 0.14224)
		(layer "In4.Cu")
		(net "P5E_CPU1_P1_TX_DN<4>")
	)
	(segment
		(start 81.221072 -369.541298)
		(end 81.221072 -373.6721)
		(width 0.14224)
		(layer "In4.Cu")
		(net "P5E_CPU1_P1_TX_DN<4>")
	)
	(segment
		(start 101.084126 -289.963606)
		(end 101.053646 -289.981386)
		(width 0.1143)
		(layer "In4.Cu")
		(net "P5E_CPU1_P1_TX_DN<4>")
	)
	(segment
		(start 100.896928 -295.016682)
		(end 100.896674 -295.016428)
		(width 0.1143)
		(layer "In4.Cu")
		(net "P5E_CPU1_P1_TX_DN<4>")
	)
	(segment
		(start 100.614226 -291.418772)
		(end 100.615242 -291.41928)
		(width 0.1143)
		(layer "In4.Cu")
		(net "P5E_CPU1_P1_TX_DN<4>")
	)
	(segment
		(start 100.615242 -290.773104)
		(end 100.614226 -290.773612)
		(width 0.1143)
		(layer "In4.Cu")
		(net "P5E_CPU1_P1_TX_DN<4>")
	)
	(segment
		(start 111.869728 -350.543876)
		(end 104.0892 -355.742748)
		(width 0.14224)
		(layer "In4.Cu")
		(net "P5E_CPU1_P1_TX_DN<4>")
	)
	(segment
		(start 101.05263 -293.830248)
		(end 101.098858 -293.857426)
		(width 0.1143)
		(layer "In4.Cu")
		(net "P5E_CPU1_P1_TX_DN<4>")
	)
	(segment
		(start 119.942864 -335.130648)
		(end 120.500902 -338.234782)
		(width 0.14224)
		(layer "In4.Cu")
		(net "P5E_CPU1_P1_TX_DN<4>")
	)
	(segment
		(start 100.997258 -294.882316)
		(end 100.997258 -294.88257)
		(width 0.1143)
		(layer "In4.Cu")
		(net "P5E_CPU1_P1_TX_DN<4>")
	)
	(segment
		(start 101.443282 -289.47618)
		(end 101.360478 -289.558984)
		(width 0.1143)
		(layer "In4.Cu")
		(net "P5E_CPU1_P1_TX_DN<4>")
	)
	(segment
		(start 101.14788 -294.784526)
		(end 101.148134 -294.784272)
		(width 0.1143)
		(layer "In4.Cu")
		(net "P5E_CPU1_P1_TX_DN<4>")
	)
	(segment
		(start 115.881912 -323.326506)
		(end 115.970812 -323.496432)
		(width 0.14224)
		(layer "In4.Cu")
		(net "P5E_CPU1_P1_TX_DN<4>")
	)
	(segment
		(start 101.148134 -294.784272)
		(end 100.997258 -294.882316)
		(width 0.1143)
		(layer "In4.Cu")
		(net "P5E_CPU1_P1_TX_DN<4>")
	)
	(segment
		(start 101.084126 -292.228778)
		(end 101.123242 -292.251638)
		(width 0.1143)
		(layer "In4.Cu")
		(net "P5E_CPU1_P1_TX_DN<4>")
	)
	(segment
		(start 100.42144 -296.03319)
		(end 100.46716 -296.07891)
		(width 0.1143)
		(layer "In4.Cu")
		(net "P5E_CPU1_P1_TX_DN<4>")
	)
	(segment
		(start 104.459278 -308.579266)
		(end 107.439968 -313.040268)
		(width 0.14224)
		(layer "In4.Cu")
		(net "P5E_CPU1_P1_TX_DN<4>")
	)
	(segment
		(start 100.613464 -291.418264)
		(end 100.614226 -291.418772)
		(width 0.1143)
		(layer "In4.Cu")
		(net "P5E_CPU1_P1_TX_DN<4>")
	)
	(segment
		(start 101.123242 -293.18077)
		(end 101.052122 -293.222426)
		(width 0.1143)
		(layer "In4.Cu")
		(net "P5E_CPU1_P1_TX_DN<4>")
	)
	(arc
		(start 100.896674 -295.268904)
		(mid 100.872468 -295.390395)
		(end 100.80371 -295.49344)
		(width 0.1143)
		(layer "In4.Cu")
		(net "P5E_CPU1_P1_TX_DN<4>")
	)
	(arc
		(start 100.951538 -294.912288)
		(mid 100.911379 -294.957766)
		(end 100.896928 -295.016682)
		(width 0.1143)
		(layer "In4.Cu")
		(net "P5E_CPU1_P1_TX_DN<4>")
	)
	(arc
		(start 101.360478 -289.558984)
		(mid 101.35869 -289.570433)
		(end 101.356668 -289.581844)
		(width 0.1143)
		(layer "In4.Cu")
		(net "P5E_CPU1_P1_TX_DN<4>")
	)
	(arc
		(start 101.098858 -293.857426)
		(mid 101.367617 -294.252215)
		(end 101.232716 -294.710358)
		(width 0.1143)
		(layer "In4.Cu")
		(net "P5E_CPU1_P1_TX_DN<4>")
	)
	(arc
		(start 100.653342 -291.441632)
		(mid 100.832155 -291.643982)
		(end 100.896674 -291.906198)
		(width 0.1143)
		(layer "In4.Cu")
		(net "P5E_CPU1_P1_TX_DN<4>")
	)
	(arc
		(start 120.516396 -343.724738)
		(mid 120.286345 -344.64319)
		(end 119.65051 -345.34475)
		(width 0.14224)
		(layer "In4.Cu")
		(net "P5E_CPU1_P1_TX_DN<4>")
	)
	(arc
		(start 104.0892 -355.742748)
		(mid 104.011172 -355.789611)
		(end 103.928926 -355.8286)
		(width 0.14224)
		(layer "In4.Cu")
		(net "P5E_CPU1_P1_TX_DN<4>")
	)
	(arc
		(start 101.123242 -292.251638)
		(mid 101.366569 -292.716204)
		(end 101.123242 -293.18077)
		(width 0.1143)
		(layer "In4.Cu")
		(net "P5E_CPU1_P1_TX_DN<4>")
	)
	(arc
		(start 82.156046 -367.284254)
		(mid 81.464066 -368.31978)
		(end 81.221072 -369.541298)
		(width 0.14224)
		(layer "In4.Cu")
		(net "P5E_CPU1_P1_TX_DN<4>")
	)
	(arc
		(start 101.232716 -294.710358)
		(mid 101.213462 -294.730263)
		(end 101.192584 -294.748458)
		(width 0.1143)
		(layer "In4.Cu")
		(net "P5E_CPU1_P1_TX_DN<4>")
	)
	(arc
		(start 90.704162 -361.306364)
		(mid 87.799687 -362.712384)
		(end 85.078062 -364.446058)
		(width 0.14224)
		(layer "In4.Cu")
		(net "P5E_CPU1_P1_TX_DN<4>")
	)
	(arc
		(start 101.053646 -289.981386)
		(mid 100.938219 -290.114762)
		(end 100.896674 -290.286186)
		(width 0.1143)
		(layer "In4.Cu")
		(net "P5E_CPU1_P1_TX_DN<4>")
	)
	(arc
		(start 100.496624 -295.800526)
		(mid 100.440973 -295.883719)
		(end 100.42144 -295.981882)
		(width 0.1143)
		(layer "In4.Cu")
		(net "P5E_CPU1_P1_TX_DN<4>")
	)
	(arc
		(start 101.052122 -293.222426)
		(mid 100.896607 -293.52649)
		(end 101.05263 -293.830248)
		(width 0.1143)
		(layer "In4.Cu")
		(net "P5E_CPU1_P1_TX_DN<4>")
	)
	(arc
		(start 101.356668 -289.581844)
		(mid 101.275235 -289.784242)
		(end 101.123242 -289.940746)
		(width 0.1143)
		(layer "In4.Cu")
		(net "P5E_CPU1_P1_TX_DN<4>")
	)
	(arc
		(start 120.500902 -338.234782)
		(mid 120.512544 -338.322195)
		(end 120.516396 -338.410296)
		(width 0.14224)
		(layer "In4.Cu")
		(net "P5E_CPU1_P1_TX_DN<4>")
	)
	(arc
		(start 100.896674 -290.286186)
		(mid 100.832159 -290.548405)
		(end 100.653342 -290.750752)
		(width 0.1143)
		(layer "In4.Cu")
		(net "P5E_CPU1_P1_TX_DN<4>")
	)
	(arc
		(start 85.078062 -364.446058)
		(mid 84.783967 -364.677075)
		(end 84.509356 -364.930944)
		(width 0.14224)
		(layer "In4.Cu")
		(net "P5E_CPU1_P1_TX_DN<4>")
	)
	(arc
		(start 119.911114 -335.00822)
		(mid 119.929317 -335.06883)
		(end 119.942864 -335.130648)
		(width 0.14224)
		(layer "In4.Cu")
		(net "P5E_CPU1_P1_TX_DN<4>")
	)
	(arc
		(start 100.582476 -290.7919)
		(mid 100.426548 -291.096192)
		(end 100.582476 -291.400484)
		(width 0.1143)
		(layer "In4.Cu")
		(net "P5E_CPU1_P1_TX_DN<4>")
	)
	(arc
		(start 100.896674 -291.906198)
		(mid 100.938223 -292.07762)
		(end 101.053646 -292.210998)
		(width 0.1143)
		(layer "In4.Cu")
		(net "P5E_CPU1_P1_TX_DN<4>")
	)
	(arc
		(start 100.46716 -298.91609)
		(mid 100.469606 -298.940943)
		(end 100.476812 -298.964858)
		(width 0.14224)
		(layer "In4.Cu")
		(net "P5E_CPU1_P1_TX_DN<4>")
	)
	(segment
		(start 78.133702 -370.30533)
		(end 77.837792 -370.00942)
		(width 0.12954)
		(layer "F.Cu")
		(net "P5E_CPU1_P1_TX_DN<3>")
	)
	(segment
		(start 99.387914 -287.590484)
		(end 98.921062 -287.856422)
		(width 0.12954)
		(layer "F.Cu")
		(net "P5E_CPU1_P1_TX_DN<3>")
	)
	(segment
		(start 77.837792 -370.00942)
		(end 77.837792 -369.30584)
		(width 0.12954)
		(layer "F.Cu")
		(net "P5E_CPU1_P1_TX_DN<3>")
	)
	(segment
		(start 77.837792 -369.30584)
		(end 78.108302 -369.03533)
		(width 0.12954)
		(layer "F.Cu")
		(net "P5E_CPU1_P1_TX_DN<3>")
	)
	(segment
		(start 99.673918 -291.418772)
		(end 99.713034 -291.441632)
		(width 0.1143)
		(layer "In4.Cu")
		(net "P5E_CPU1_P1_TX_DN<3>")
	)
	(segment
		(start 98.70059 -288.15919)
		(end 98.775266 -288.203132)
		(width 0.1143)
		(layer "In4.Cu")
		(net "P5E_CPU1_P1_TX_DN<3>")
	)
	(segment
		(start 99.48672 -296.03319)
		(end 99.53244 -296.07891)
		(width 0.1143)
		(layer "In4.Cu")
		(net "P5E_CPU1_P1_TX_DN<3>")
	)
	(segment
		(start 119.565928 -338.407756)
		(end 119.565928 -343.07272)
		(width 0.14224)
		(layer "In4.Cu")
		(net "P5E_CPU1_P1_TX_DN<3>")
	)
	(segment
		(start 103.468932 -354.982526)
		(end 85.375496 -362.476796)
		(width 0.14224)
		(layer "In4.Cu")
		(net "P5E_CPU1_P1_TX_DN<3>")
	)
	(segment
		(start 105.158032 -311.317894)
		(end 106.6673 -313.57697)
		(width 0.14224)
		(layer "In4.Cu")
		(net "P5E_CPU1_P1_TX_DN<3>")
	)
	(segment
		(start 100.113338 -292.210998)
		(end 100.143818 -292.228778)
		(width 0.1143)
		(layer "In4.Cu")
		(net "P5E_CPU1_P1_TX_DN<3>")
	)
	(segment
		(start 99.643438 -291.400992)
		(end 99.673918 -291.418772)
		(width 0.1143)
		(layer "In4.Cu")
		(net "P5E_CPU1_P1_TX_DN<3>")
	)
	(segment
		(start 100.182934 -293.18077)
		(end 100.143818 -293.20363)
		(width 0.1143)
		(layer "In4.Cu")
		(net "P5E_CPU1_P1_TX_DN<3>")
	)
	(segment
		(start 118.60657 -344.867738)
		(end 103.468932 -354.982526)
		(width 0.14224)
		(layer "In4.Cu")
		(net "P5E_CPU1_P1_TX_DN<3>")
	)
	(segment
		(start 99.48672 -296.001186)
		(end 99.48672 -296.03319)
		(width 0.1143)
		(layer "In4.Cu")
		(net "P5E_CPU1_P1_TX_DN<3>")
	)
	(segment
		(start 99.211892 -289.005772)
		(end 99.296728 -289.055048)
		(width 0.1143)
		(layer "In4.Cu")
		(net "P5E_CPU1_P1_TX_DN<3>")
	)
	(segment
		(start 77.817472 -368.267488)
		(end 77.817472 -368.7445)
		(width 0.14224)
		(layer "In4.Cu")
		(net "P5E_CPU1_P1_TX_DN<3>")
	)
	(segment
		(start 99.956366 -295.146222)
		(end 99.956112 -295.145968)
		(width 0.1143)
		(layer "In4.Cu")
		(net "P5E_CPU1_P1_TX_DN<3>")
	)
	(segment
		(start 115.110514 -323.86397)
		(end 118.993158 -335.205832)
		(width 0.14224)
		(layer "In4.Cu")
		(net "P5E_CPU1_P1_TX_DN<3>")
	)
	(segment
		(start 106.6673 -313.57697)
		(end 115.110514 -323.86397)
		(width 0.14224)
		(layer "In4.Cu")
		(net "P5E_CPU1_P1_TX_DN<3>")
	)
	(segment
		(start 99.713034 -290.750752)
		(end 99.673918 -290.773612)
		(width 0.1143)
		(layer "In4.Cu")
		(net "P5E_CPU1_P1_TX_DN<3>")
	)
	(segment
		(start 99.53244 -296.107358)
		(end 99.53244 -299.121068)
		(width 0.14224)
		(layer "In4.Cu")
		(net "P5E_CPU1_P1_TX_DN<3>")
	)
	(segment
		(start 98.921062 -287.856422)
		(end 98.62312 -287.856422)
		(width 0.1143)
		(layer "In4.Cu")
		(net "P5E_CPU1_P1_TX_DN<3>")
	)
	(segment
		(start 99.863148 -295.572434)
		(end 99.524058 -295.91127)
		(width 0.1143)
		(layer "In4.Cu")
		(net "P5E_CPU1_P1_TX_DN<3>")
	)
	(segment
		(start 100.113338 -293.83101)
		(end 100.143818 -293.84879)
		(width 0.1143)
		(layer "In4.Cu")
		(net "P5E_CPU1_P1_TX_DN<3>")
	)
	(segment
		(start 99.53244 -296.07891)
		(end 99.53244 -296.107358)
		(width 0.1143)
		(layer "In4.Cu")
		(net "P5E_CPU1_P1_TX_DN<3>")
	)
	(segment
		(start 99.53244 -299.121068)
		(end 103.64851 -309.058564)
		(width 0.14224)
		(layer "In4.Cu")
		(net "P5E_CPU1_P1_TX_DN<3>")
	)
	(segment
		(start 100.143818 -293.20363)
		(end 100.113338 -293.22141)
		(width 0.1143)
		(layer "In4.Cu")
		(net "P5E_CPU1_P1_TX_DN<3>")
	)
	(segment
		(start 99.675696 -289.799776)
		(end 99.713034 -289.82162)
		(width 0.1143)
		(layer "In4.Cu")
		(net "P5E_CPU1_P1_TX_DN<3>")
	)
	(segment
		(start 103.64851 -309.058564)
		(end 105.158032 -311.317894)
		(width 0.14224)
		(layer "In4.Cu")
		(net "P5E_CPU1_P1_TX_DN<3>")
	)
	(segment
		(start 119.035576 -335.369408)
		(end 119.550434 -338.231988)
		(width 0.14224)
		(layer "In4.Cu")
		(net "P5E_CPU1_P1_TX_DN<3>")
	)
	(segment
		(start 100.143818 -292.228778)
		(end 100.182934 -292.251638)
		(width 0.1143)
		(layer "In4.Cu")
		(net "P5E_CPU1_P1_TX_DN<3>")
	)
	(segment
		(start 100.143818 -293.84879)
		(end 100.182934 -293.87165)
		(width 0.1143)
		(layer "In4.Cu")
		(net "P5E_CPU1_P1_TX_DN<3>")
	)
	(segment
		(start 79.841598 -366.174528)
		(end 77.86624 -368.149886)
		(width 0.14224)
		(layer "In4.Cu")
		(net "P5E_CPU1_P1_TX_DN<3>")
	)
	(segment
		(start 99.673918 -290.773612)
		(end 99.643438 -290.791392)
		(width 0.1143)
		(layer "In4.Cu")
		(net "P5E_CPU1_P1_TX_DN<3>")
	)
	(segment
		(start 99.211638 -289.005518)
		(end 99.211892 -289.005772)
		(width 0.1143)
		(layer "In4.Cu")
		(net "P5E_CPU1_P1_TX_DN<3>")
	)
	(segment
		(start 100.182934 -294.800782)
		(end 100.113338 -294.841422)
		(width 0.1143)
		(layer "In4.Cu")
		(net "P5E_CPU1_P1_TX_DN<3>")
	)
	(segment
		(start 99.956112 -295.145968)
		(end 99.956112 -295.34739)
		(width 0.1143)
		(layer "In4.Cu")
		(net "P5E_CPU1_P1_TX_DN<3>")
	)
	(segment
		(start 77.817472 -368.7445)
		(end 78.108302 -369.03533)
		(width 0.14224)
		(layer "In4.Cu")
		(net "P5E_CPU1_P1_TX_DN<3>")
	)
	(segment
		(start 98.62312 -287.856422)
		(end 98.55327 -287.926272)
		(width 0.1143)
		(layer "In4.Cu")
		(net "P5E_CPU1_P1_TX_DN<3>")
	)
	(arc
		(start 98.775266 -288.203132)
		(mid 98.952462 -288.405144)
		(end 99.016312 -288.666174)
		(width 0.1143)
		(layer "In4.Cu")
		(net "P5E_CPU1_P1_TX_DN<3>")
	)
	(arc
		(start 99.296728 -289.055048)
		(mid 99.434872 -289.246083)
		(end 99.486212 -289.47618)
		(width 0.1143)
		(layer "In4.Cu")
		(net "P5E_CPU1_P1_TX_DN<3>")
	)
	(arc
		(start 85.375496 -362.476796)
		(mid 82.426456 -364.053148)
		(end 79.841598 -366.174528)
		(width 0.14224)
		(layer "In4.Cu")
		(net "P5E_CPU1_P1_TX_DN<3>")
	)
	(arc
		(start 99.956112 -295.34739)
		(mid 99.932003 -295.469154)
		(end 99.863148 -295.572434)
		(width 0.1143)
		(layer "In4.Cu")
		(net "P5E_CPU1_P1_TX_DN<3>")
	)
	(arc
		(start 99.016312 -288.666174)
		(mid 99.068632 -288.861945)
		(end 99.211638 -289.005518)
		(width 0.1143)
		(layer "In4.Cu")
		(net "P5E_CPU1_P1_TX_DN<3>")
	)
	(arc
		(start 100.113338 -293.22141)
		(mid 99.956361 -293.52621)
		(end 100.113338 -293.83101)
		(width 0.1143)
		(layer "In4.Cu")
		(net "P5E_CPU1_P1_TX_DN<3>")
	)
	(arc
		(start 99.643438 -290.791392)
		(mid 99.486461 -291.096192)
		(end 99.643438 -291.400992)
		(width 0.1143)
		(layer "In4.Cu")
		(net "P5E_CPU1_P1_TX_DN<3>")
	)
	(arc
		(start 100.182934 -293.87165)
		(mid 100.426261 -294.336216)
		(end 100.182934 -294.800782)
		(width 0.1143)
		(layer "In4.Cu")
		(net "P5E_CPU1_P1_TX_DN<3>")
	)
	(arc
		(start 100.113338 -294.841422)
		(mid 99.997911 -294.974798)
		(end 99.956366 -295.146222)
		(width 0.1143)
		(layer "In4.Cu")
		(net "P5E_CPU1_P1_TX_DN<3>")
	)
	(arc
		(start 98.55327 -287.926272)
		(mid 98.60476 -288.056745)
		(end 98.70059 -288.15919)
		(width 0.1143)
		(layer "In4.Cu")
		(net "P5E_CPU1_P1_TX_DN<3>")
	)
	(arc
		(start 99.486212 -289.47618)
		(mid 99.53857 -289.662791)
		(end 99.675696 -289.799776)
		(width 0.1143)
		(layer "In4.Cu")
		(net "P5E_CPU1_P1_TX_DN<3>")
	)
	(arc
		(start 118.993158 -335.205832)
		(mid 119.017467 -335.286816)
		(end 119.035576 -335.369408)
		(width 0.14224)
		(layer "In4.Cu")
		(net "P5E_CPU1_P1_TX_DN<3>")
	)
	(arc
		(start 100.182934 -292.251638)
		(mid 100.426261 -292.716204)
		(end 100.182934 -293.18077)
		(width 0.1143)
		(layer "In4.Cu")
		(net "P5E_CPU1_P1_TX_DN<3>")
	)
	(arc
		(start 119.550434 -338.231988)
		(mid 119.56209 -338.319527)
		(end 119.565928 -338.407756)
		(width 0.14224)
		(layer "In4.Cu")
		(net "P5E_CPU1_P1_TX_DN<3>")
	)
	(arc
		(start 99.956366 -291.906198)
		(mid 99.997915 -292.07762)
		(end 100.113338 -292.210998)
		(width 0.1143)
		(layer "In4.Cu")
		(net "P5E_CPU1_P1_TX_DN<3>")
	)
	(arc
		(start 119.565928 -343.07272)
		(mid 119.311045 -344.090374)
		(end 118.60657 -344.867738)
		(width 0.14224)
		(layer "In4.Cu")
		(net "P5E_CPU1_P1_TX_DN<3>")
	)
	(arc
		(start 99.524058 -295.91127)
		(mid 99.496439 -295.95251)
		(end 99.48672 -296.001186)
		(width 0.1143)
		(layer "In4.Cu")
		(net "P5E_CPU1_P1_TX_DN<3>")
	)
	(arc
		(start 99.713034 -291.441632)
		(mid 99.891847 -291.643982)
		(end 99.956366 -291.906198)
		(width 0.1143)
		(layer "In4.Cu")
		(net "P5E_CPU1_P1_TX_DN<3>")
	)
	(arc
		(start 99.713034 -289.82162)
		(mid 99.956361 -290.286186)
		(end 99.713034 -290.750752)
		(width 0.1143)
		(layer "In4.Cu")
		(net "P5E_CPU1_P1_TX_DN<3>")
	)
	(arc
		(start 77.86624 -368.149886)
		(mid 77.830134 -368.203828)
		(end 77.817472 -368.267488)
		(width 0.14224)
		(layer "In4.Cu")
		(net "P5E_CPU1_P1_TX_DN<3>")
	)
	(segment
		(start 76.135992 -371.76964)
		(end 76.406502 -371.49913)
		(width 0.12954)
		(layer "F.Cu")
		(net "P5E_CPU1_P1_TX_DN<2>")
	)
	(segment
		(start 99.387914 -290.830254)
		(end 98.921062 -291.096192)
		(width 0.12954)
		(layer "F.Cu")
		(net "P5E_CPU1_P1_TX_DN<2>")
	)
	(segment
		(start 76.135992 -372.47322)
		(end 76.135992 -371.76964)
		(width 0.12954)
		(layer "F.Cu")
		(net "P5E_CPU1_P1_TX_DN<2>")
	)
	(segment
		(start 76.431902 -372.76913)
		(end 76.135992 -372.47322)
		(width 0.12954)
		(layer "F.Cu")
		(net "P5E_CPU1_P1_TX_DN<2>")
	)
	(segment
		(start 98.546412 -296.03319)
		(end 98.592132 -296.07891)
		(width 0.1143)
		(layer "In4.Cu")
		(net "P5E_CPU1_P1_TX_DN<2>")
	)
	(segment
		(start 80.209898 -364.471204)
		(end 76.15682 -368.524282)
		(width 0.14224)
		(layer "In4.Cu")
		(net "P5E_CPU1_P1_TX_DN<2>")
	)
	(segment
		(start 99.243134 -293.18077)
		(end 99.183444 -293.215568)
		(width 0.1143)
		(layer "In4.Cu")
		(net "P5E_CPU1_P1_TX_DN<2>")
	)
	(segment
		(start 118.130828 -335.651094)
		(end 118.588028 -338.192872)
		(width 0.14224)
		(layer "In4.Cu")
		(net "P5E_CPU1_P1_TX_DN<2>")
	)
	(segment
		(start 99.20351 -292.228524)
		(end 99.242372 -292.25113)
		(width 0.1143)
		(layer "In4.Cu")
		(net "P5E_CPU1_P1_TX_DN<2>")
	)
	(segment
		(start 98.546412 -296.001694)
		(end 98.546412 -296.03319)
		(width 0.1143)
		(layer "In4.Cu")
		(net "P5E_CPU1_P1_TX_DN<2>")
	)
	(segment
		(start 118.603522 -338.36864)
		(end 118.603522 -342.707722)
		(width 0.14224)
		(layer "In4.Cu")
		(net "P5E_CPU1_P1_TX_DN<2>")
	)
	(segment
		(start 99.243134 -293.87165)
		(end 99.245166 -293.873174)
		(width 0.1143)
		(layer "In4.Cu")
		(net "P5E_CPU1_P1_TX_DN<2>")
	)
	(segment
		(start 98.733356 -291.418264)
		(end 98.734118 -291.418772)
		(width 0.1143)
		(layer "In4.Cu")
		(net "P5E_CPU1_P1_TX_DN<2>")
	)
	(segment
		(start 98.592132 -296.107358)
		(end 98.592132 -299.262546)
		(width 0.14224)
		(layer "In4.Cu")
		(net "P5E_CPU1_P1_TX_DN<2>")
	)
	(segment
		(start 99.182682 -293.216076)
		(end 99.182428 -293.216076)
		(width 0.1143)
		(layer "In4.Cu")
		(net "P5E_CPU1_P1_TX_DN<2>")
	)
	(segment
		(start 76.115672 -371.2083)
		(end 76.406502 -371.49913)
		(width 0.14224)
		(layer "In4.Cu")
		(net "P5E_CPU1_P1_TX_DN<2>")
	)
	(segment
		(start 98.734118 -291.418772)
		(end 98.744024 -291.424614)
		(width 0.1143)
		(layer "In4.Cu")
		(net "P5E_CPU1_P1_TX_DN<2>")
	)
	(segment
		(start 76.115672 -368.623342)
		(end 76.115672 -371.2083)
		(width 0.14224)
		(layer "In4.Cu")
		(net "P5E_CPU1_P1_TX_DN<2>")
	)
	(segment
		(start 98.62312 -291.096192)
		(end 98.55327 -291.166042)
		(width 0.1143)
		(layer "In4.Cu")
		(net "P5E_CPU1_P1_TX_DN<2>")
	)
	(segment
		(start 102.96652 -354.175822)
		(end 83.633564 -362.18368)
		(width 0.14224)
		(layer "In4.Cu")
		(net "P5E_CPU1_P1_TX_DN<2>")
	)
	(segment
		(start 105.961942 -314.238386)
		(end 114.286284 -324.381622)
		(width 0.14224)
		(layer "In4.Cu")
		(net "P5E_CPU1_P1_TX_DN<2>")
	)
	(segment
		(start 98.602038 -299.312584)
		(end 102.865174 -309.603648)
		(width 0.14224)
		(layer "In4.Cu")
		(net "P5E_CPU1_P1_TX_DN<2>")
	)
	(segment
		(start 98.592132 -296.07891)
		(end 98.592132 -296.107358)
		(width 0.1143)
		(layer "In4.Cu")
		(net "P5E_CPU1_P1_TX_DN<2>")
	)
	(segment
		(start 114.286284 -324.381622)
		(end 118.08841 -335.487518)
		(width 0.14224)
		(layer "In4.Cu")
		(net "P5E_CPU1_P1_TX_DN<2>")
	)
	(segment
		(start 99.183444 -293.215568)
		(end 99.182682 -293.216076)
		(width 0.1143)
		(layer "In4.Cu")
		(net "P5E_CPU1_P1_TX_DN<2>")
	)
	(segment
		(start 99.182682 -293.836344)
		(end 99.242372 -293.871142)
		(width 0.1143)
		(layer "In4.Cu")
		(net "P5E_CPU1_P1_TX_DN<2>")
	)
	(segment
		(start 98.702368 -291.400484)
		(end 98.733356 -291.418264)
		(width 0.1143)
		(layer "In4.Cu")
		(net "P5E_CPU1_P1_TX_DN<2>")
	)
	(segment
		(start 98.923348 -295.572434)
		(end 98.58375 -295.911778)
		(width 0.1143)
		(layer "In4.Cu")
		(net "P5E_CPU1_P1_TX_DN<2>")
	)
	(segment
		(start 99.027742 -291.915088)
		(end 99.027742 -291.92347)
		(width 0.1143)
		(layer "In4.Cu")
		(net "P5E_CPU1_P1_TX_DN<2>")
	)
	(segment
		(start 99.016312 -295.146222)
		(end 99.016312 -295.34739)
		(width 0.1143)
		(layer "In4.Cu")
		(net "P5E_CPU1_P1_TX_DN<2>")
	)
	(segment
		(start 117.75567 -344.293952)
		(end 102.96652 -354.175822)
		(width 0.14224)
		(layer "In4.Cu")
		(net "P5E_CPU1_P1_TX_DN<2>")
	)
	(segment
		(start 102.865174 -309.603648)
		(end 105.961942 -314.238386)
		(width 0.14224)
		(layer "In4.Cu")
		(net "P5E_CPU1_P1_TX_DN<2>")
	)
	(segment
		(start 99.245166 -294.799258)
		(end 99.17303 -294.841676)
		(width 0.1143)
		(layer "In4.Cu")
		(net "P5E_CPU1_P1_TX_DN<2>")
	)
	(segment
		(start 98.921062 -291.096192)
		(end 98.62312 -291.096192)
		(width 0.1143)
		(layer "In4.Cu")
		(net "P5E_CPU1_P1_TX_DN<2>")
	)
	(segment
		(start 99.182174 -293.836344)
		(end 99.182682 -293.836344)
		(width 0.1143)
		(layer "In4.Cu")
		(net "P5E_CPU1_P1_TX_DN<2>")
	)
	(arc
		(start 99.243134 -292.251638)
		(mid 99.486461 -292.716204)
		(end 99.243134 -293.18077)
		(width 0.1143)
		(layer "In4.Cu")
		(net "P5E_CPU1_P1_TX_DN<2>")
	)
	(arc
		(start 99.242372 -292.25113)
		(mid 99.242753 -292.251384)
		(end 99.243134 -292.251638)
		(width 0.1143)
		(layer "In4.Cu")
		(net "P5E_CPU1_P1_TX_DN<2>")
	)
	(arc
		(start 98.55327 -291.166042)
		(mid 98.605319 -291.297561)
		(end 98.702368 -291.400484)
		(width 0.1143)
		(layer "In4.Cu")
		(net "P5E_CPU1_P1_TX_DN<2>")
	)
	(arc
		(start 98.744024 -291.424614)
		(mid 98.95175 -291.631747)
		(end 99.027742 -291.915088)
		(width 0.1143)
		(layer "In4.Cu")
		(net "P5E_CPU1_P1_TX_DN<2>")
	)
	(arc
		(start 99.182428 -293.216076)
		(mid 99.003886 -293.5261)
		(end 99.182174 -293.836344)
		(width 0.1143)
		(layer "In4.Cu")
		(net "P5E_CPU1_P1_TX_DN<2>")
	)
	(arc
		(start 99.242372 -293.871142)
		(mid 99.242753 -293.871396)
		(end 99.243134 -293.87165)
		(width 0.1143)
		(layer "In4.Cu")
		(net "P5E_CPU1_P1_TX_DN<2>")
	)
	(arc
		(start 99.17303 -294.841676)
		(mid 99.057887 -294.975012)
		(end 99.016312 -295.146222)
		(width 0.1143)
		(layer "In4.Cu")
		(net "P5E_CPU1_P1_TX_DN<2>")
	)
	(arc
		(start 118.08841 -335.487518)
		(mid 118.112719 -335.568502)
		(end 118.130828 -335.651094)
		(width 0.14224)
		(layer "In4.Cu")
		(net "P5E_CPU1_P1_TX_DN<2>")
	)
	(arc
		(start 98.592132 -299.262546)
		(mid 98.594599 -299.288059)
		(end 98.602038 -299.312584)
		(width 0.14224)
		(layer "In4.Cu")
		(net "P5E_CPU1_P1_TX_DN<2>")
	)
	(arc
		(start 76.15682 -368.524282)
		(mid 76.126369 -368.569716)
		(end 76.115672 -368.623342)
		(width 0.14224)
		(layer "In4.Cu")
		(net "P5E_CPU1_P1_TX_DN<2>")
	)
	(arc
		(start 99.245166 -293.873174)
		(mid 99.487677 -294.336216)
		(end 99.245166 -294.799258)
		(width 0.1143)
		(layer "In4.Cu")
		(net "P5E_CPU1_P1_TX_DN<2>")
	)
	(arc
		(start 99.016312 -295.34739)
		(mid 98.992203 -295.469154)
		(end 98.923348 -295.572434)
		(width 0.1143)
		(layer "In4.Cu")
		(net "P5E_CPU1_P1_TX_DN<2>")
	)
	(arc
		(start 99.027742 -291.92347)
		(mid 99.074832 -292.099498)
		(end 99.20351 -292.228524)
		(width 0.1143)
		(layer "In4.Cu")
		(net "P5E_CPU1_P1_TX_DN<2>")
	)
	(arc
		(start 118.588028 -338.192872)
		(mid 118.599684 -338.280411)
		(end 118.603522 -338.36864)
		(width 0.14224)
		(layer "In4.Cu")
		(net "P5E_CPU1_P1_TX_DN<2>")
	)
	(arc
		(start 118.603522 -342.707722)
		(mid 118.378263 -343.607029)
		(end 117.75567 -344.293952)
		(width 0.14224)
		(layer "In4.Cu")
		(net "P5E_CPU1_P1_TX_DN<2>")
	)
	(arc
		(start 83.633564 -362.18368)
		(mid 81.809075 -363.158834)
		(end 80.209898 -364.471204)
		(width 0.14224)
		(layer "In4.Cu")
		(net "P5E_CPU1_P1_TX_DN<2>")
	)
	(arc
		(start 98.58375 -295.911778)
		(mid 98.556131 -295.953018)
		(end 98.546412 -296.001694)
		(width 0.1143)
		(layer "In4.Cu")
		(net "P5E_CPU1_P1_TX_DN<2>")
	)
	(segment
		(start 99.387914 -289.210242)
		(end 98.921062 -289.47618)
		(width 0.12954)
		(layer "F.Cu")
		(net "P5E_CPU1_P1_TX_DN<1>")
	)
	(segment
		(start 74.22896 -376.56135)
		(end 73.95845 -376.83186)
		(width 0.12954)
		(layer "F.Cu")
		(net "P5E_CPU1_P1_TX_DN<1>")
	)
	(segment
		(start 75.22845 -376.85726)
		(end 74.93254 -376.56135)
		(width 0.12954)
		(layer "F.Cu")
		(net "P5E_CPU1_P1_TX_DN<1>")
	)
	(segment
		(start 74.93254 -376.56135)
		(end 74.22896 -376.56135)
		(width 0.12954)
		(layer "F.Cu")
		(net "P5E_CPU1_P1_TX_DN<1>")
	)
	(segment
		(start 97.79508 -290.773104)
		(end 97.794064 -290.773612)
		(width 0.1143)
		(layer "In4.Cu")
		(net "P5E_CPU1_P1_TX_DN<1>")
	)
	(segment
		(start 98.30308 -293.18077)
		(end 98.263964 -293.20363)
		(width 0.1143)
		(layer "In4.Cu")
		(net "P5E_CPU1_P1_TX_DN<1>")
	)
	(segment
		(start 97.80016 -291.422328)
		(end 97.801684 -291.423344)
		(width 0.1143)
		(layer "In4.Cu")
		(net "P5E_CPU1_P1_TX_DN<1>")
	)
	(segment
		(start 97.801684 -291.423344)
		(end 97.83318 -291.441632)
		(width 0.1143)
		(layer "In4.Cu")
		(net "P5E_CPU1_P1_TX_DN<1>")
	)
	(segment
		(start 98.62312 -289.47618)
		(end 98.540316 -289.558984)
		(width 0.1143)
		(layer "In4.Cu")
		(net "P5E_CPU1_P1_TX_DN<1>")
	)
	(segment
		(start 98.30308 -294.800782)
		(end 98.233484 -294.841422)
		(width 0.1143)
		(layer "In4.Cu")
		(net "P5E_CPU1_P1_TX_DN<1>")
	)
	(segment
		(start 97.79508 -291.41928)
		(end 97.796604 -291.420296)
		(width 0.1143)
		(layer "In4.Cu")
		(net "P5E_CPU1_P1_TX_DN<1>")
	)
	(segment
		(start 105.282492 -314.902342)
		(end 107.297728 -317.358014)
		(width 0.14224)
		(layer "In4.Cu")
		(net "P5E_CPU1_P1_TX_DN<1>")
	)
	(segment
		(start 97.792032 -290.774882)
		(end 97.762314 -290.7919)
		(width 0.1143)
		(layer "In4.Cu")
		(net "P5E_CPU1_P1_TX_DN<1>")
	)
	(segment
		(start 102.02926 -310.033162)
		(end 105.282492 -314.902342)
		(width 0.14224)
		(layer "In4.Cu")
		(net "P5E_CPU1_P1_TX_DN<1>")
	)
	(segment
		(start 97.794064 -291.418772)
		(end 97.79508 -291.41928)
		(width 0.1143)
		(layer "In4.Cu")
		(net "P5E_CPU1_P1_TX_DN<1>")
	)
	(segment
		(start 79.472282 -363.558074)
		(end 74.420222 -368.610134)
		(width 0.14224)
		(layer "In4.Cu")
		(net "P5E_CPU1_P1_TX_DN<1>")
	)
	(segment
		(start 98.233484 -293.83101)
		(end 98.263964 -293.84879)
		(width 0.1143)
		(layer "In4.Cu")
		(net "P5E_CPU1_P1_TX_DN<1>")
	)
	(segment
		(start 97.83318 -290.750752)
		(end 97.796604 -290.772088)
		(width 0.1143)
		(layer "In4.Cu")
		(net "P5E_CPU1_P1_TX_DN<1>")
	)
	(segment
		(start 103.013256 -352.950272)
		(end 83.057492 -361.216194)
		(width 0.14224)
		(layer "In4.Cu")
		(net "P5E_CPU1_P1_TX_DN<1>")
	)
	(segment
		(start 98.921062 -289.47618)
		(end 98.62312 -289.47618)
		(width 0.1143)
		(layer "In4.Cu")
		(net "P5E_CPU1_P1_TX_DN<1>")
	)
	(segment
		(start 117.671342 -338.601812)
		(end 117.671342 -341.913972)
		(width 0.14224)
		(layer "In4.Cu")
		(net "P5E_CPU1_P1_TX_DN<1>")
	)
	(segment
		(start 97.652078 -296.07891)
		(end 97.652078 -296.107358)
		(width 0.1143)
		(layer "In4.Cu")
		(net "P5E_CPU1_P1_TX_DN<1>")
	)
	(segment
		(start 97.762314 -291.400484)
		(end 97.794064 -291.418772)
		(width 0.1143)
		(layer "In4.Cu")
		(net "P5E_CPU1_P1_TX_DN<1>")
	)
	(segment
		(start 98.076512 -295.146222)
		(end 98.076258 -295.145968)
		(width 0.1143)
		(layer "In4.Cu")
		(net "P5E_CPU1_P1_TX_DN<1>")
	)
	(segment
		(start 98.263964 -293.20363)
		(end 98.233484 -293.22141)
		(width 0.1143)
		(layer "In4.Cu")
		(net "P5E_CPU1_P1_TX_DN<1>")
	)
	(segment
		(start 116.620544 -343.879678)
		(end 103.17353 -352.86442)
		(width 0.14224)
		(layer "In4.Cu")
		(net "P5E_CPU1_P1_TX_DN<1>")
	)
	(segment
		(start 97.606358 -296.001694)
		(end 97.606358 -296.03319)
		(width 0.1143)
		(layer "In4.Cu")
		(net "P5E_CPU1_P1_TX_DN<1>")
	)
	(segment
		(start 117.249702 -336.106516)
		(end 117.66042 -338.475574)
		(width 0.14224)
		(layer "In4.Cu")
		(net "P5E_CPU1_P1_TX_DN<1>")
	)
	(segment
		(start 98.263964 -293.84879)
		(end 98.30308 -293.87165)
		(width 0.1143)
		(layer "In4.Cu")
		(net "P5E_CPU1_P1_TX_DN<1>")
	)
	(segment
		(start 98.263964 -289.963606)
		(end 98.233484 -289.981386)
		(width 0.1143)
		(layer "In4.Cu")
		(net "P5E_CPU1_P1_TX_DN<1>")
	)
	(segment
		(start 75.316588 -376.337322)
		(end 75.27544 -376.37847)
		(width 0.14224)
		(layer "In4.Cu")
		(net "P5E_CPU1_P1_TX_DN<1>")
	)
	(segment
		(start 74.443336 -373.238014)
		(end 75.21575 -374.010428)
		(width 0.14224)
		(layer "In4.Cu")
		(net "P5E_CPU1_P1_TX_DN<1>")
	)
	(segment
		(start 98.233484 -292.210998)
		(end 98.263964 -292.228778)
		(width 0.1143)
		(layer "In4.Cu")
		(net "P5E_CPU1_P1_TX_DN<1>")
	)
	(segment
		(start 75.436476 -374.54332)
		(end 75.436476 -376.048016)
		(width 0.14224)
		(layer "In4.Cu")
		(net "P5E_CPU1_P1_TX_DN<1>")
	)
	(segment
		(start 97.665794 -299.498766)
		(end 102.02926 -310.033162)
		(width 0.14224)
		(layer "In4.Cu")
		(net "P5E_CPU1_P1_TX_DN<1>")
	)
	(segment
		(start 98.263964 -292.228778)
		(end 98.30308 -292.251638)
		(width 0.1143)
		(layer "In4.Cu")
		(net "P5E_CPU1_P1_TX_DN<1>")
	)
	(segment
		(start 74.32421 -368.901726)
		(end 74.32421 -372.950486)
		(width 0.14224)
		(layer "In4.Cu")
		(net "P5E_CPU1_P1_TX_DN<1>")
	)
	(segment
		(start 97.79762 -291.420804)
		(end 97.80016 -291.422328)
		(width 0.1143)
		(layer "In4.Cu")
		(net "P5E_CPU1_P1_TX_DN<1>")
	)
	(segment
		(start 74.24928 -376.54103)
		(end 73.95845 -376.83186)
		(width 0.14224)
		(layer "In4.Cu")
		(net "P5E_CPU1_P1_TX_DN<1>")
	)
	(segment
		(start 113.384076 -324.773798)
		(end 117.20703 -335.940654)
		(width 0.14224)
		(layer "In4.Cu")
		(net "P5E_CPU1_P1_TX_DN<1>")
	)
	(segment
		(start 117.249702 -336.1055)
		(end 117.249702 -336.106516)
		(width 0.14224)
		(layer "In4.Cu")
		(net "P5E_CPU1_P1_TX_DN<1>")
	)
	(segment
		(start 97.796604 -291.420296)
		(end 97.79762 -291.420804)
		(width 0.1143)
		(layer "In4.Cu")
		(net "P5E_CPU1_P1_TX_DN<1>")
	)
	(segment
		(start 74.883264 -376.54103)
		(end 74.24928 -376.54103)
		(width 0.14224)
		(layer "In4.Cu")
		(net "P5E_CPU1_P1_TX_DN<1>")
	)
	(segment
		(start 98.076258 -295.145968)
		(end 98.076258 -295.34739)
		(width 0.1143)
		(layer "In4.Cu")
		(net "P5E_CPU1_P1_TX_DN<1>")
	)
	(segment
		(start 97.793302 -290.77412)
		(end 97.792032 -290.774882)
		(width 0.1143)
		(layer "In4.Cu")
		(net "P5E_CPU1_P1_TX_DN<1>")
	)
	(segment
		(start 98.30308 -289.940746)
		(end 98.263964 -289.963606)
		(width 0.1143)
		(layer "In4.Cu")
		(net "P5E_CPU1_P1_TX_DN<1>")
	)
	(segment
		(start 97.794064 -290.773612)
		(end 97.793302 -290.77412)
		(width 0.1143)
		(layer "In4.Cu")
		(net "P5E_CPU1_P1_TX_DN<1>")
	)
	(segment
		(start 97.796604 -290.772088)
		(end 97.79508 -290.773104)
		(width 0.1143)
		(layer "In4.Cu")
		(net "P5E_CPU1_P1_TX_DN<1>")
	)
	(segment
		(start 97.983294 -295.572434)
		(end 97.643696 -295.911778)
		(width 0.1143)
		(layer "In4.Cu")
		(net "P5E_CPU1_P1_TX_DN<1>")
	)
	(segment
		(start 107.297728 -317.358014)
		(end 113.384076 -324.773798)
		(width 0.14224)
		(layer "In4.Cu")
		(net "P5E_CPU1_P1_TX_DN<1>")
	)
	(segment
		(start 97.606358 -296.03319)
		(end 97.652078 -296.07891)
		(width 0.1143)
		(layer "In4.Cu")
		(net "P5E_CPU1_P1_TX_DN<1>")
	)
	(segment
		(start 97.652078 -296.107358)
		(end 97.652078 -299.429424)
		(width 0.14224)
		(layer "In4.Cu")
		(net "P5E_CPU1_P1_TX_DN<1>")
	)
	(arc
		(start 98.076258 -295.34739)
		(mid 98.052149 -295.469154)
		(end 97.983294 -295.572434)
		(width 0.1143)
		(layer "In4.Cu")
		(net "P5E_CPU1_P1_TX_DN<1>")
	)
	(arc
		(start 75.21575 -374.010428)
		(mid 75.379115 -374.254921)
		(end 75.436476 -374.54332)
		(width 0.14224)
		(layer "In4.Cu")
		(net "P5E_CPU1_P1_TX_DN<1>")
	)
	(arc
		(start 75.436476 -376.048016)
		(mid 75.405313 -376.204594)
		(end 75.316588 -376.337322)
		(width 0.14224)
		(layer "In4.Cu")
		(net "P5E_CPU1_P1_TX_DN<1>")
	)
	(arc
		(start 98.536506 -289.581844)
		(mid 98.455073 -289.784242)
		(end 98.30308 -289.940746)
		(width 0.1143)
		(layer "In4.Cu")
		(net "P5E_CPU1_P1_TX_DN<1>")
	)
	(arc
		(start 98.30308 -293.87165)
		(mid 98.546407 -294.336216)
		(end 98.30308 -294.800782)
		(width 0.1143)
		(layer "In4.Cu")
		(net "P5E_CPU1_P1_TX_DN<1>")
	)
	(arc
		(start 74.353928 -368.71783)
		(mid 74.331699 -368.808589)
		(end 74.32421 -368.901726)
		(width 0.14224)
		(layer "In4.Cu")
		(net "P5E_CPU1_P1_TX_DN<1>")
	)
	(arc
		(start 98.540316 -289.558984)
		(mid 98.538528 -289.570433)
		(end 98.536506 -289.581844)
		(width 0.1143)
		(layer "In4.Cu")
		(net "P5E_CPU1_P1_TX_DN<1>")
	)
	(arc
		(start 97.643696 -295.911778)
		(mid 97.616077 -295.953018)
		(end 97.606358 -296.001694)
		(width 0.1143)
		(layer "In4.Cu")
		(net "P5E_CPU1_P1_TX_DN<1>")
	)
	(arc
		(start 98.233484 -289.981386)
		(mid 98.118057 -290.114762)
		(end 98.076512 -290.286186)
		(width 0.1143)
		(layer "In4.Cu")
		(net "P5E_CPU1_P1_TX_DN<1>")
	)
	(arc
		(start 97.762314 -290.7919)
		(mid 97.606386 -291.096192)
		(end 97.762314 -291.400484)
		(width 0.1143)
		(layer "In4.Cu")
		(net "P5E_CPU1_P1_TX_DN<1>")
	)
	(arc
		(start 97.652078 -299.429424)
		(mid 97.655511 -299.464773)
		(end 97.665794 -299.498766)
		(width 0.14224)
		(layer "In4.Cu")
		(net "P5E_CPU1_P1_TX_DN<1>")
	)
	(arc
		(start 98.30308 -292.251638)
		(mid 98.546407 -292.716204)
		(end 98.30308 -293.18077)
		(width 0.1143)
		(layer "In4.Cu")
		(net "P5E_CPU1_P1_TX_DN<1>")
	)
	(arc
		(start 117.671342 -341.913972)
		(mid 117.392155 -343.02844)
		(end 116.620544 -343.879678)
		(width 0.14224)
		(layer "In4.Cu")
		(net "P5E_CPU1_P1_TX_DN<1>")
	)
	(arc
		(start 97.83318 -291.441632)
		(mid 98.011993 -291.643982)
		(end 98.076512 -291.906198)
		(width 0.1143)
		(layer "In4.Cu")
		(net "P5E_CPU1_P1_TX_DN<1>")
	)
	(arc
		(start 117.66042 -338.475574)
		(mid 117.668602 -338.538458)
		(end 117.671342 -338.601812)
		(width 0.14224)
		(layer "In4.Cu")
		(net "P5E_CPU1_P1_TX_DN<1>")
	)
	(arc
		(start 74.420222 -368.610134)
		(mid 74.380784 -368.660107)
		(end 74.353928 -368.71783)
		(width 0.14224)
		(layer "In4.Cu")
		(net "P5E_CPU1_P1_TX_DN<1>")
	)
	(arc
		(start 75.27544 -376.37847)
		(mid 75.095523 -376.49878)
		(end 74.883264 -376.54103)
		(width 0.14224)
		(layer "In4.Cu")
		(net "P5E_CPU1_P1_TX_DN<1>")
	)
	(arc
		(start 98.076512 -290.286186)
		(mid 98.011997 -290.548405)
		(end 97.83318 -290.750752)
		(width 0.1143)
		(layer "In4.Cu")
		(net "P5E_CPU1_P1_TX_DN<1>")
	)
	(arc
		(start 80.911446 -362.370624)
		(mid 80.163481 -362.92995)
		(end 79.472282 -363.558074)
		(width 0.14224)
		(layer "In4.Cu")
		(net "P5E_CPU1_P1_TX_DN<1>")
	)
	(arc
		(start 98.233484 -294.841422)
		(mid 98.117981 -294.974774)
		(end 98.076512 -295.146222)
		(width 0.1143)
		(layer "In4.Cu")
		(net "P5E_CPU1_P1_TX_DN<1>")
	)
	(arc
		(start 98.076512 -291.906198)
		(mid 98.118061 -292.07762)
		(end 98.233484 -292.210998)
		(width 0.1143)
		(layer "In4.Cu")
		(net "P5E_CPU1_P1_TX_DN<1>")
	)
	(arc
		(start 74.32421 -372.950486)
		(mid 74.355165 -373.106106)
		(end 74.443336 -373.238014)
		(width 0.14224)
		(layer "In4.Cu")
		(net "P5E_CPU1_P1_TX_DN<1>")
	)
	(arc
		(start 117.20703 -335.940654)
		(mid 117.231507 -336.022264)
		(end 117.249702 -336.1055)
		(width 0.14224)
		(layer "In4.Cu")
		(net "P5E_CPU1_P1_TX_DN<1>")
	)
	(arc
		(start 103.17353 -352.86442)
		(mid 103.095502 -352.911283)
		(end 103.013256 -352.950272)
		(width 0.14224)
		(layer "In4.Cu")
		(net "P5E_CPU1_P1_TX_DN<1>")
	)
	(arc
		(start 83.057492 -361.216194)
		(mid 81.955333 -361.739247)
		(end 80.911446 -362.370624)
		(width 0.14224)
		(layer "In4.Cu")
		(net "P5E_CPU1_P1_TX_DN<1>")
	)
	(arc
		(start 98.233484 -293.22141)
		(mid 98.076507 -293.52621)
		(end 98.233484 -293.83101)
		(width 0.1143)
		(layer "In4.Cu")
		(net "P5E_CPU1_P1_TX_DN<1>")
	)
	(segment
		(start 102.831392 -380.089918)
		(end 103.534972 -380.089918)
		(width 0.12954)
		(layer "F.Cu")
		(net "P5E_CPU1_P1_TX_DN<15>")
	)
	(segment
		(start 103.534972 -380.089918)
		(end 103.805482 -380.360428)
		(width 0.12954)
		(layer "F.Cu")
		(net "P5E_CPU1_P1_TX_DN<15>")
	)
	(segment
		(start 102.535482 -380.385828)
		(end 102.831392 -380.089918)
		(width 0.12954)
		(layer "F.Cu")
		(net "P5E_CPU1_P1_TX_DN<15>")
	)
	(segment
		(start 110.1979 -286.780478)
		(end 109.731048 -287.046162)
		(width 0.12954)
		(layer "F.Cu")
		(net "P5E_CPU1_P1_TX_DN<15>")
	)
	(segment
		(start 110.453424 -288.970974)
		(end 110.483904 -288.988754)
		(width 0.1143)
		(layer "In4.Cu")
		(net "P5E_CPU1_P1_TX_DN<15>")
	)
	(segment
		(start 110.00994 -288.17697)
		(end 110.010956 -288.177478)
		(width 0.1143)
		(layer "In4.Cu")
		(net "P5E_CPU1_P1_TX_DN<15>")
	)
	(segment
		(start 125.981714 -320.372486)
		(end 129.94132 -331.945234)
		(width 0.14224)
		(layer "In4.Cu")
		(net "P5E_CPU1_P1_TX_DN<15>")
	)
	(segment
		(start 105.709212 -379.339856)
		(end 104.97947 -380.069598)
		(width 0.14224)
		(layer "In4.Cu")
		(net "P5E_CPU1_P1_TX_DN<15>")
	)
	(segment
		(start 111.481362 -290.253674)
		(end 111.481362 -290.282122)
		(width 0.1143)
		(layer "In4.Cu")
		(net "P5E_CPU1_P1_TX_DN<15>")
	)
	(segment
		(start 104.97947 -380.069598)
		(end 104.096312 -380.069598)
		(width 0.14224)
		(layer "In4.Cu")
		(net "P5E_CPU1_P1_TX_DN<15>")
	)
	(segment
		(start 129.94132 -331.945234)
		(end 129.94132 -331.945488)
		(width 0.14224)
		(layer "In4.Cu")
		(net "P5E_CPU1_P1_TX_DN<15>")
	)
	(segment
		(start 111.481362 -290.282122)
		(end 111.481362 -298.699174)
		(width 0.14224)
		(layer "In4.Cu")
		(net "P5E_CPU1_P1_TX_DN<15>")
	)
	(segment
		(start 130.98526 -349.136716)
		(end 130.505454 -351.481136)
		(width 0.14224)
		(layer "In4.Cu")
		(net "P5E_CPU1_P1_TX_DN<15>")
	)
	(segment
		(start 109.512354 -287.350454)
		(end 109.578648 -287.389062)
		(width 0.1143)
		(layer "In4.Cu")
		(net "P5E_CPU1_P1_TX_DN<15>")
	)
	(segment
		(start 111.435642 -290.207954)
		(end 111.481362 -290.253674)
		(width 0.1143)
		(layer "In4.Cu")
		(net "P5E_CPU1_P1_TX_DN<15>")
	)
	(segment
		(start 108.499402 -366.657128)
		(end 106.82859 -369.157758)
		(width 0.14224)
		(layer "In4.Cu")
		(net "P5E_CPU1_P1_TX_DN<15>")
	)
	(segment
		(start 124.505466 -317.537846)
		(end 125.957076 -320.315336)
		(width 0.14224)
		(layer "In4.Cu")
		(net "P5E_CPU1_P1_TX_DN<15>")
	)
	(segment
		(start 105.709212 -372.847616)
		(end 105.709212 -379.339856)
		(width 0.14224)
		(layer "In4.Cu")
		(net "P5E_CPU1_P1_TX_DN<15>")
	)
	(segment
		(start 109.433106 -287.046162)
		(end 109.363256 -287.116012)
		(width 0.1143)
		(layer "In4.Cu")
		(net "P5E_CPU1_P1_TX_DN<15>")
	)
	(segment
		(start 110.599474 -289.077654)
		(end 110.600998 -289.079178)
		(width 0.1143)
		(layer "In4.Cu")
		(net "P5E_CPU1_P1_TX_DN<15>")
	)
	(segment
		(start 113.324132 -303.17313)
		(end 115.938554 -307.086254)
		(width 0.14224)
		(layer "In4.Cu")
		(net "P5E_CPU1_P1_TX_DN<15>")
	)
	(segment
		(start 111.491014 -298.747942)
		(end 113.324132 -303.17313)
		(width 0.14224)
		(layer "In4.Cu")
		(net "P5E_CPU1_P1_TX_DN<15>")
	)
	(segment
		(start 104.096312 -380.069598)
		(end 103.805482 -380.360428)
		(width 0.14224)
		(layer "In4.Cu")
		(net "P5E_CPU1_P1_TX_DN<15>")
	)
	(segment
		(start 131.003548 -337.9216)
		(end 131.003548 -348.95409)
		(width 0.14224)
		(layer "In4.Cu")
		(net "P5E_CPU1_P1_TX_DN<15>")
	)
	(segment
		(start 129.956814 -332.005686)
		(end 130.988054 -337.745578)
		(width 0.14224)
		(layer "In4.Cu")
		(net "P5E_CPU1_P1_TX_DN<15>")
	)
	(segment
		(start 110.027212 -288.186368)
		(end 110.05312 -288.201608)
		(width 0.1143)
		(layer "In4.Cu")
		(net "P5E_CPU1_P1_TX_DN<15>")
	)
	(segment
		(start 114.592354 -362.654596)
		(end 112.13719 -363.671612)
		(width 0.14224)
		(layer "In4.Cu")
		(net "P5E_CPU1_P1_TX_DN<15>")
	)
	(segment
		(start 130.43408 -351.67697)
		(end 130.06197 -352.368866)
		(width 0.14224)
		(layer "In4.Cu")
		(net "P5E_CPU1_P1_TX_DN<15>")
	)
	(segment
		(start 110.600998 -289.079178)
		(end 111.435642 -289.764724)
		(width 0.1143)
		(layer "In4.Cu")
		(net "P5E_CPU1_P1_TX_DN<15>")
	)
	(segment
		(start 111.435642 -289.764724)
		(end 111.435642 -290.207954)
		(width 0.1143)
		(layer "In4.Cu")
		(net "P5E_CPU1_P1_TX_DN<15>")
	)
	(segment
		(start 110.010956 -288.177478)
		(end 110.027212 -288.186368)
		(width 0.1143)
		(layer "In4.Cu")
		(net "P5E_CPU1_P1_TX_DN<15>")
	)
	(segment
		(start 109.731048 -287.046162)
		(end 109.433106 -287.046162)
		(width 0.1143)
		(layer "In4.Cu")
		(net "P5E_CPU1_P1_TX_DN<15>")
	)
	(segment
		(start 129.886202 -352.562414)
		(end 115.475512 -362.182664)
		(width 0.14224)
		(layer "In4.Cu")
		(net "P5E_CPU1_P1_TX_DN<15>")
	)
	(segment
		(start 115.938554 -307.086254)
		(end 124.458984 -317.467742)
		(width 0.14224)
		(layer "In4.Cu")
		(net "P5E_CPU1_P1_TX_DN<15>")
	)
	(segment
		(start 110.483904 -288.988754)
		(end 110.484158 -288.989008)
		(width 0.1143)
		(layer "In4.Cu")
		(net "P5E_CPU1_P1_TX_DN<15>")
	)
	(arc
		(start 109.822742 -287.821116)
		(mid 109.825097 -287.843422)
		(end 109.826298 -287.86582)
		(width 0.1143)
		(layer "In4.Cu")
		(net "P5E_CPU1_P1_TX_DN<15>")
	)
	(arc
		(start 110.296452 -288.666174)
		(mid 110.338001 -288.837596)
		(end 110.453424 -288.970974)
		(width 0.1143)
		(layer "In4.Cu")
		(net "P5E_CPU1_P1_TX_DN<15>")
	)
	(arc
		(start 110.05312 -288.201608)
		(mid 110.231933 -288.403958)
		(end 110.296452 -288.666174)
		(width 0.1143)
		(layer "In4.Cu")
		(net "P5E_CPU1_P1_TX_DN<15>")
	)
	(arc
		(start 106.82859 -369.157758)
		(mid 105.99523 -370.919663)
		(end 105.709212 -372.847616)
		(width 0.14224)
		(layer "In4.Cu")
		(net "P5E_CPU1_P1_TX_DN<15>")
	)
	(arc
		(start 109.826298 -287.86582)
		(mid 109.877718 -288.04526)
		(end 110.00994 -288.17697)
		(width 0.1143)
		(layer "In4.Cu")
		(net "P5E_CPU1_P1_TX_DN<15>")
	)
	(arc
		(start 110.484158 -288.989008)
		(mid 110.544688 -289.029595)
		(end 110.599474 -289.077654)
		(width 0.1143)
		(layer "In4.Cu")
		(net "P5E_CPU1_P1_TX_DN<15>")
	)
	(arc
		(start 112.13719 -363.671612)
		(mid 110.096879 -364.894578)
		(end 108.499402 -366.657128)
		(width 0.14224)
		(layer "In4.Cu")
		(net "P5E_CPU1_P1_TX_DN<15>")
	)
	(arc
		(start 109.578648 -287.389062)
		(mid 109.741438 -287.58207)
		(end 109.822742 -287.821116)
		(width 0.1143)
		(layer "In4.Cu")
		(net "P5E_CPU1_P1_TX_DN<15>")
	)
	(arc
		(start 124.458984 -317.467742)
		(mid 124.484032 -317.501596)
		(end 124.505466 -317.537846)
		(width 0.14224)
		(layer "In4.Cu")
		(net "P5E_CPU1_P1_TX_DN<15>")
	)
	(arc
		(start 109.363256 -287.116012)
		(mid 109.415305 -287.247531)
		(end 109.512354 -287.350454)
		(width 0.1143)
		(layer "In4.Cu")
		(net "P5E_CPU1_P1_TX_DN<15>")
	)
	(arc
		(start 130.988054 -337.745578)
		(mid 130.999709 -337.833245)
		(end 131.003548 -337.9216)
		(width 0.14224)
		(layer "In4.Cu")
		(net "P5E_CPU1_P1_TX_DN<15>")
	)
	(arc
		(start 131.003548 -348.95409)
		(mid 130.999032 -349.045867)
		(end 130.98526 -349.136716)
		(width 0.14224)
		(layer "In4.Cu")
		(net "P5E_CPU1_P1_TX_DN<15>")
	)
	(arc
		(start 130.06197 -352.368866)
		(mid 129.985936 -352.476397)
		(end 129.886202 -352.562414)
		(width 0.14224)
		(layer "In4.Cu")
		(net "P5E_CPU1_P1_TX_DN<15>")
	)
	(arc
		(start 125.957076 -320.315336)
		(mid 125.97049 -320.343439)
		(end 125.981714 -320.372486)
		(width 0.14224)
		(layer "In4.Cu")
		(net "P5E_CPU1_P1_TX_DN<15>")
	)
	(arc
		(start 129.94132 -331.945488)
		(mid 129.950216 -331.975291)
		(end 129.956814 -332.005686)
		(width 0.14224)
		(layer "In4.Cu")
		(net "P5E_CPU1_P1_TX_DN<15>")
	)
	(arc
		(start 115.475512 -362.182664)
		(mid 115.045496 -362.440267)
		(end 114.592354 -362.654596)
		(width 0.14224)
		(layer "In4.Cu")
		(net "P5E_CPU1_P1_TX_DN<15>")
	)
	(arc
		(start 130.505454 -351.481136)
		(mid 130.47694 -351.581668)
		(end 130.43408 -351.67697)
		(width 0.14224)
		(layer "In4.Cu")
		(net "P5E_CPU1_P1_TX_DN<15>")
	)
	(arc
		(start 111.481362 -298.699174)
		(mid 111.483808 -298.724027)
		(end 111.491014 -298.747942)
		(width 0.14224)
		(layer "In4.Cu")
		(net "P5E_CPU1_P1_TX_DN<15>")
	)
	(segment
		(start 102.535482 -376.067828)
		(end 102.831392 -376.363738)
		(width 0.12954)
		(layer "F.Cu")
		(net "P5E_CPU1_P1_TX_DN<14>")
	)
	(segment
		(start 102.831392 -376.363738)
		(end 103.534972 -376.363738)
		(width 0.12954)
		(layer "F.Cu")
		(net "P5E_CPU1_P1_TX_DN<14>")
	)
	(segment
		(start 110.1979 -288.400236)
		(end 109.731048 -288.666174)
		(width 0.12954)
		(layer "F.Cu")
		(net "P5E_CPU1_P1_TX_DN<14>")
	)
	(segment
		(start 103.534972 -376.363738)
		(end 103.805482 -376.093228)
		(width 0.12954)
		(layer "F.Cu")
		(net "P5E_CPU1_P1_TX_DN<14>")
	)
	(segment
		(start 103.167942 -372.220998)
		(end 102.865682 -372.672864)
		(width 0.14224)
		(layer "In4.Cu")
		(net "P5E_CPU1_P1_TX_DN<14>")
	)
	(segment
		(start 110.479078 -297.316398)
		(end 110.479078 -297.743118)
		(width 0.14224)
		(layer "In4.Cu")
		(net "P5E_CPU1_P1_TX_DN<14>")
	)
	(segment
		(start 104.22255 -370.8908)
		(end 103.98506 -371.245638)
		(width 0.14224)
		(layer "In4.Cu")
		(net "P5E_CPU1_P1_TX_DN<14>")
	)
	(segment
		(start 110.505494 -293.191184)
		(end 110.50524 -293.191184)
		(width 0.1143)
		(layer "In4.Cu")
		(net "P5E_CPU1_P1_TX_DN<14>")
	)
	(segment
		(start 125.112018 -320.711322)
		(end 129.04597 -332.208632)
		(width 0.14224)
		(layer "In4.Cu")
		(net "P5E_CPU1_P1_TX_DN<14>")
	)
	(segment
		(start 110.561882 -294.773858)
		(end 110.483904 -294.823642)
		(width 0.1143)
		(layer "In4.Cu")
		(net "P5E_CPU1_P1_TX_DN<14>")
	)
	(segment
		(start 114.155982 -361.817158)
		(end 111.554006 -362.894372)
		(width 0.14224)
		(layer "In4.Cu")
		(net "P5E_CPU1_P1_TX_DN<14>")
	)
	(segment
		(start 109.731048 -288.666174)
		(end 109.433106 -288.666174)
		(width 0.1143)
		(layer "In4.Cu")
		(net "P5E_CPU1_P1_TX_DN<14>")
	)
	(segment
		(start 110.485174 -293.203122)
		(end 110.484158 -293.20363)
		(width 0.1143)
		(layer "In4.Cu")
		(net "P5E_CPU1_P1_TX_DN<14>")
	)
	(segment
		(start 104.812084 -369.76304)
		(end 104.849676 -369.953286)
		(width 0.14224)
		(layer "In4.Cu")
		(net "P5E_CPU1_P1_TX_DN<14>")
	)
	(segment
		(start 110.341918 -297.880278)
		(end 110.341918 -298.306998)
		(width 0.14224)
		(layer "In4.Cu")
		(net "P5E_CPU1_P1_TX_DN<14>")
	)
	(segment
		(start 103.357934 -372.183406)
		(end 103.167688 -372.220998)
		(width 0.14224)
		(layer "In4.Cu")
		(net "P5E_CPU1_P1_TX_DN<14>")
	)
	(segment
		(start 110.47603 -293.843964)
		(end 110.521496 -293.870634)
		(width 0.1143)
		(layer "In4.Cu")
		(net "P5E_CPU1_P1_TX_DN<14>")
	)
	(segment
		(start 103.514652 -376.384058)
		(end 103.805482 -376.093228)
		(width 0.14224)
		(layer "In4.Cu")
		(net "P5E_CPU1_P1_TX_DN<14>")
	)
	(segment
		(start 129.04597 -332.208632)
		(end 130.058668 -337.84794)
		(width 0.14224)
		(layer "In4.Cu")
		(net "P5E_CPU1_P1_TX_DN<14>")
	)
	(segment
		(start 109.512354 -288.970466)
		(end 109.581188 -289.010344)
		(width 0.1143)
		(layer "In4.Cu")
		(net "P5E_CPU1_P1_TX_DN<14>")
	)
	(segment
		(start 103.98506 -371.245638)
		(end 103.794814 -371.283484)
		(width 0.14224)
		(layer "In4.Cu")
		(net "P5E_CPU1_P1_TX_DN<14>")
	)
	(segment
		(start 110.479078 -297.743118)
		(end 110.341918 -297.880278)
		(width 0.14224)
		(layer "In4.Cu")
		(net "P5E_CPU1_P1_TX_DN<14>")
	)
	(segment
		(start 110.483904 -292.228778)
		(end 110.531402 -292.25748)
		(width 0.1143)
		(layer "In4.Cu")
		(net "P5E_CPU1_P1_TX_DN<14>")
	)
	(segment
		(start 130.058668 -337.84794)
		(end 130.058668 -348.882462)
		(width 0.14224)
		(layer "In4.Cu")
		(net "P5E_CPU1_P1_TX_DN<14>")
	)
	(segment
		(start 128.7145 -352.203258)
		(end 115.009168 -361.361228)
		(width 0.14224)
		(layer "In4.Cu")
		(net "P5E_CPU1_P1_TX_DN<14>")
	)
	(segment
		(start 110.296198 -295.48328)
		(end 110.341918 -295.529)
		(width 0.1143)
		(layer "In4.Cu")
		(net "P5E_CPU1_P1_TX_DN<14>")
	)
	(segment
		(start 130.058668 -348.882462)
		(end 129.73812 -350.369378)
		(width 0.14224)
		(layer "In4.Cu")
		(net "P5E_CPU1_P1_TX_DN<14>")
	)
	(segment
		(start 112.511078 -303.64684)
		(end 115.178332 -307.638704)
		(width 0.14224)
		(layer "In4.Cu")
		(net "P5E_CPU1_P1_TX_DN<14>")
	)
	(segment
		(start 110.516416 -293.18458)
		(end 110.505494 -293.191184)
		(width 0.1143)
		(layer "In4.Cu")
		(net "P5E_CPU1_P1_TX_DN<14>")
	)
	(segment
		(start 110.766098 -292.702996)
		(end 110.766098 -292.716204)
		(width 0.1143)
		(layer "In4.Cu")
		(net "P5E_CPU1_P1_TX_DN<14>")
	)
	(segment
		(start 106.79303 -366.800384)
		(end 104.812084 -369.76304)
		(width 0.14224)
		(layer "In4.Cu")
		(net "P5E_CPU1_P1_TX_DN<14>")
	)
	(segment
		(start 103.167688 -372.220998)
		(end 103.167942 -372.220998)
		(width 0.14224)
		(layer "In4.Cu")
		(net "P5E_CPU1_P1_TX_DN<14>")
	)
	(segment
		(start 110.453424 -292.210998)
		(end 110.483904 -292.228778)
		(width 0.1143)
		(layer "In4.Cu")
		(net "P5E_CPU1_P1_TX_DN<14>")
	)
	(segment
		(start 110.341918 -295.557448)
		(end 110.341918 -297.179238)
		(width 0.14224)
		(layer "In4.Cu")
		(net "P5E_CPU1_P1_TX_DN<14>")
	)
	(segment
		(start 103.557832 -371.638068)
		(end 103.595424 -371.828314)
		(width 0.14224)
		(layer "In4.Cu")
		(net "P5E_CPU1_P1_TX_DN<14>")
	)
	(segment
		(start 110.483142 -290.608258)
		(end 110.483904 -290.608766)
		(width 0.1143)
		(layer "In4.Cu")
		(net "P5E_CPU1_P1_TX_DN<14>")
	)
	(segment
		(start 110.50524 -293.191184)
		(end 110.485174 -293.203122)
		(width 0.1143)
		(layer "In4.Cu")
		(net "P5E_CPU1_P1_TX_DN<14>")
	)
	(segment
		(start 109.433106 -288.666174)
		(end 109.363256 -288.736024)
		(width 0.1143)
		(layer "In4.Cu")
		(net "P5E_CPU1_P1_TX_DN<14>")
	)
	(segment
		(start 110.52302 -293.87165)
		(end 110.561882 -293.898574)
		(width 0.1143)
		(layer "In4.Cu")
		(net "P5E_CPU1_P1_TX_DN<14>")
	)
	(segment
		(start 104.849676 -369.953286)
		(end 104.612186 -370.308124)
		(width 0.14224)
		(layer "In4.Cu")
		(net "P5E_CPU1_P1_TX_DN<14>")
	)
	(segment
		(start 115.178332 -307.638704)
		(end 123.716034 -318.040766)
		(width 0.14224)
		(layer "In4.Cu")
		(net "P5E_CPU1_P1_TX_DN<14>")
	)
	(segment
		(start 110.341918 -295.529)
		(end 110.341918 -295.557448)
		(width 0.1143)
		(layer "In4.Cu")
		(net "P5E_CPU1_P1_TX_DN<14>")
	)
	(segment
		(start 110.381288 -298.504864)
		(end 112.511078 -303.64684)
		(width 0.14224)
		(layer "In4.Cu")
		(net "P5E_CPU1_P1_TX_DN<14>")
	)
	(segment
		(start 110.52302 -293.18077)
		(end 110.516416 -293.18458)
		(width 0.1143)
		(layer "In4.Cu")
		(net "P5E_CPU1_P1_TX_DN<14>")
	)
	(segment
		(start 128.767586 -352.150172)
		(end 128.7145 -352.203258)
		(width 0.14224)
		(layer "In4.Cu")
		(net "P5E_CPU1_P1_TX_DN<14>")
	)
	(segment
		(start 110.341918 -297.179238)
		(end 110.479078 -297.316398)
		(width 0.14224)
		(layer "In4.Cu")
		(net "P5E_CPU1_P1_TX_DN<14>")
	)
	(segment
		(start 110.453424 -290.590986)
		(end 110.483142 -290.608258)
		(width 0.1143)
		(layer "In4.Cu")
		(net "P5E_CPU1_P1_TX_DN<14>")
	)
	(segment
		(start 104.184958 -370.700554)
		(end 104.22255 -370.8908)
		(width 0.14224)
		(layer "In4.Cu")
		(net "P5E_CPU1_P1_TX_DN<14>")
	)
	(segment
		(start 110.484158 -291.583618)
		(end 110.483904 -291.583618)
		(width 0.1143)
		(layer "In4.Cu")
		(net "P5E_CPU1_P1_TX_DN<14>")
	)
	(segment
		(start 104.612186 -370.308124)
		(end 104.42194 -370.34597)
		(width 0.14224)
		(layer "In4.Cu")
		(net "P5E_CPU1_P1_TX_DN<14>")
	)
	(segment
		(start 110.296198 -295.146222)
		(end 110.296198 -295.48328)
		(width 0.1143)
		(layer "In4.Cu")
		(net "P5E_CPU1_P1_TX_DN<14>")
	)
	(segment
		(start 110.766098 -292.716204)
		(end 110.766352 -292.716204)
		(width 0.1143)
		(layer "In4.Cu")
		(net "P5E_CPU1_P1_TX_DN<14>")
	)
	(segment
		(start 102.93858 -376.384058)
		(end 103.514652 -376.384058)
		(width 0.14224)
		(layer "In4.Cu")
		(net "P5E_CPU1_P1_TX_DN<14>")
	)
	(segment
		(start 110.483904 -291.583618)
		(end 110.453424 -291.601398)
		(width 0.1143)
		(layer "In4.Cu")
		(net "P5E_CPU1_P1_TX_DN<14>")
	)
	(segment
		(start 103.794814 -371.283484)
		(end 103.557832 -371.638068)
		(width 0.14224)
		(layer "In4.Cu")
		(net "P5E_CPU1_P1_TX_DN<14>")
	)
	(segment
		(start 123.716034 -318.040766)
		(end 125.112018 -320.711322)
		(width 0.14224)
		(layer "In4.Cu")
		(net "P5E_CPU1_P1_TX_DN<14>")
	)
	(segment
		(start 110.483904 -294.823642)
		(end 110.45317 -294.841422)
		(width 0.1143)
		(layer "In4.Cu")
		(net "P5E_CPU1_P1_TX_DN<14>")
	)
	(segment
		(start 104.42194 -370.34597)
		(end 104.184958 -370.700554)
		(width 0.14224)
		(layer "In4.Cu")
		(net "P5E_CPU1_P1_TX_DN<14>")
	)
	(segment
		(start 103.595424 -371.828314)
		(end 103.357934 -372.183406)
		(width 0.14224)
		(layer "In4.Cu")
		(net "P5E_CPU1_P1_TX_DN<14>")
	)
	(segment
		(start 109.982254 -289.780472)
		(end 110.05312 -289.82162)
		(width 0.1143)
		(layer "In4.Cu")
		(net "P5E_CPU1_P1_TX_DN<14>")
	)
	(segment
		(start 102.57028 -373.645684)
		(end 102.57028 -376.015758)
		(width 0.14224)
		(layer "In4.Cu")
		(net "P5E_CPU1_P1_TX_DN<14>")
	)
	(segment
		(start 102.607618 -376.105674)
		(end 102.848664 -376.34672)
		(width 0.14224)
		(layer "In4.Cu")
		(net "P5E_CPU1_P1_TX_DN<14>")
	)
	(segment
		(start 110.483904 -290.608766)
		(end 110.484158 -290.60902)
		(width 0.1143)
		(layer "In4.Cu")
		(net "P5E_CPU1_P1_TX_DN<14>")
	)
	(arc
		(start 110.766352 -292.716204)
		(mid 110.766197 -292.726747)
		(end 110.765844 -292.737286)
		(width 0.1143)
		(layer "In4.Cu")
		(net "P5E_CPU1_P1_TX_DN<14>")
	)
	(arc
		(start 110.561882 -293.898574)
		(mid 110.79106 -294.336216)
		(end 110.561882 -294.773858)
		(width 0.1143)
		(layer "In4.Cu")
		(net "P5E_CPU1_P1_TX_DN<14>")
	)
	(arc
		(start 111.554006 -362.894372)
		(mid 108.883811 -364.494252)
		(end 106.79303 -366.800384)
		(width 0.14224)
		(layer "In4.Cu")
		(net "P5E_CPU1_P1_TX_DN<14>")
	)
	(arc
		(start 110.453424 -291.601398)
		(mid 110.296447 -291.906198)
		(end 110.453424 -292.210998)
		(width 0.1143)
		(layer "In4.Cu")
		(net "P5E_CPU1_P1_TX_DN<14>")
	)
	(arc
		(start 110.45317 -294.841422)
		(mid 110.337743 -294.974798)
		(end 110.296198 -295.146222)
		(width 0.1143)
		(layer "In4.Cu")
		(net "P5E_CPU1_P1_TX_DN<14>")
	)
	(arc
		(start 109.581188 -289.010344)
		(mid 109.742402 -289.203202)
		(end 109.822742 -289.441382)
		(width 0.1143)
		(layer "In4.Cu")
		(net "P5E_CPU1_P1_TX_DN<14>")
	)
	(arc
		(start 109.822742 -289.441382)
		(mid 109.825086 -289.463562)
		(end 109.826298 -289.485832)
		(width 0.1143)
		(layer "In4.Cu")
		(net "P5E_CPU1_P1_TX_DN<14>")
	)
	(arc
		(start 110.484158 -293.20363)
		(mid 110.29918 -293.521484)
		(end 110.47603 -293.843964)
		(width 0.1143)
		(layer "In4.Cu")
		(net "P5E_CPU1_P1_TX_DN<14>")
	)
	(arc
		(start 109.826298 -289.485832)
		(mid 109.869691 -289.651464)
		(end 109.982254 -289.780472)
		(width 0.1143)
		(layer "In4.Cu")
		(net "P5E_CPU1_P1_TX_DN<14>")
	)
	(arc
		(start 129.73812 -350.369378)
		(mid 129.381298 -351.329779)
		(end 128.767586 -352.150172)
		(width 0.14224)
		(layer "In4.Cu")
		(net "P5E_CPU1_P1_TX_DN<14>")
	)
	(arc
		(start 110.484158 -290.60902)
		(mid 110.763922 -291.096382)
		(end 110.484158 -291.583618)
		(width 0.1143)
		(layer "In4.Cu")
		(net "P5E_CPU1_P1_TX_DN<14>")
	)
	(arc
		(start 110.521496 -293.870634)
		(mid 110.522258 -293.871141)
		(end 110.52302 -293.87165)
		(width 0.1143)
		(layer "In4.Cu")
		(net "P5E_CPU1_P1_TX_DN<14>")
	)
	(arc
		(start 102.848664 -376.34672)
		(mid 102.889904 -376.374339)
		(end 102.93858 -376.384058)
		(width 0.14224)
		(layer "In4.Cu")
		(net "P5E_CPU1_P1_TX_DN<14>")
	)
	(arc
		(start 110.765844 -292.737286)
		(mid 110.696757 -292.987663)
		(end 110.52302 -293.18077)
		(width 0.1143)
		(layer "In4.Cu")
		(net "P5E_CPU1_P1_TX_DN<14>")
	)
	(arc
		(start 109.363256 -288.736024)
		(mid 109.415305 -288.867543)
		(end 109.512354 -288.970466)
		(width 0.1143)
		(layer "In4.Cu")
		(net "P5E_CPU1_P1_TX_DN<14>")
	)
	(arc
		(start 110.05312 -289.82162)
		(mid 110.231933 -290.02397)
		(end 110.296452 -290.286186)
		(width 0.1143)
		(layer "In4.Cu")
		(net "P5E_CPU1_P1_TX_DN<14>")
	)
	(arc
		(start 102.57028 -376.015758)
		(mid 102.579982 -376.064442)
		(end 102.607618 -376.105674)
		(width 0.14224)
		(layer "In4.Cu")
		(net "P5E_CPU1_P1_TX_DN<14>")
	)
	(arc
		(start 110.341918 -298.306998)
		(mid 110.351856 -298.40787)
		(end 110.381288 -298.504864)
		(width 0.14224)
		(layer "In4.Cu")
		(net "P5E_CPU1_P1_TX_DN<14>")
	)
	(arc
		(start 115.009168 -361.361228)
		(mid 114.593787 -361.610174)
		(end 114.155982 -361.817158)
		(width 0.14224)
		(layer "In4.Cu")
		(net "P5E_CPU1_P1_TX_DN<14>")
	)
	(arc
		(start 102.865682 -372.672864)
		(mid 102.645754 -373.137346)
		(end 102.57028 -373.645684)
		(width 0.14224)
		(layer "In4.Cu")
		(net "P5E_CPU1_P1_TX_DN<14>")
	)
	(arc
		(start 110.531402 -292.25748)
		(mid 110.703882 -292.451193)
		(end 110.766098 -292.702996)
		(width 0.1143)
		(layer "In4.Cu")
		(net "P5E_CPU1_P1_TX_DN<14>")
	)
	(arc
		(start 110.296452 -290.286186)
		(mid 110.338001 -290.457608)
		(end 110.453424 -290.590986)
		(width 0.1143)
		(layer "In4.Cu")
		(net "P5E_CPU1_P1_TX_DN<14>")
	)
	(segment
		(start 101.662992 -369.30584)
		(end 101.933502 -369.03533)
		(width 0.12954)
		(layer "F.Cu")
		(net "P5E_CPU1_P1_TX_DN<13>")
	)
	(segment
		(start 101.662992 -370.00942)
		(end 101.662992 -369.30584)
		(width 0.12954)
		(layer "F.Cu")
		(net "P5E_CPU1_P1_TX_DN<13>")
	)
	(segment
		(start 110.1979 -290.020248)
		(end 109.731048 -290.286186)
		(width 0.12954)
		(layer "F.Cu")
		(net "P5E_CPU1_P1_TX_DN<13>")
	)
	(segment
		(start 101.958902 -370.30533)
		(end 101.662992 -370.00942)
		(width 0.12954)
		(layer "F.Cu")
		(net "P5E_CPU1_P1_TX_DN<13>")
	)
	(segment
		(start 109.544104 -291.583618)
		(end 109.512354 -291.601906)
		(width 0.1143)
		(layer "In4.Cu")
		(net "P5E_CPU1_P1_TX_DN<13>")
	)
	(segment
		(start 109.545882 -293.849806)
		(end 109.54639 -293.850314)
		(width 0.1143)
		(layer "In4.Cu")
		(net "P5E_CPU1_P1_TX_DN<13>")
	)
	(segment
		(start 122.941334 -318.584834)
		(end 124.235718 -321.060572)
		(width 0.14224)
		(layer "In4.Cu")
		(net "P5E_CPU1_P1_TX_DN<13>")
	)
	(segment
		(start 101.636322 -368.73815)
		(end 101.933502 -369.03533)
		(width 0.14224)
		(layer "In4.Cu")
		(net "P5E_CPU1_P1_TX_DN<13>")
	)
	(segment
		(start 103.725218 -365.124746)
		(end 102.428802 -365.797084)
		(width 0.14224)
		(layer "In4.Cu")
		(net "P5E_CPU1_P1_TX_DN<13>")
	)
	(segment
		(start 109.356144 -295.146222)
		(end 109.356144 -295.48328)
		(width 0.1143)
		(layer "In4.Cu")
		(net "P5E_CPU1_P1_TX_DN<13>")
	)
	(segment
		(start 111.689642 -304.106072)
		(end 114.457988 -308.249574)
		(width 0.14224)
		(layer "In4.Cu")
		(net "P5E_CPU1_P1_TX_DN<13>")
	)
	(segment
		(start 109.543342 -292.22827)
		(end 109.544104 -292.228778)
		(width 0.1143)
		(layer "In4.Cu")
		(net "P5E_CPU1_P1_TX_DN<13>")
	)
	(segment
		(start 109.548676 -293.200836)
		(end 109.54385 -293.203884)
		(width 0.1143)
		(layer "In4.Cu")
		(net "P5E_CPU1_P1_TX_DN<13>")
	)
	(segment
		(start 109.401864 -295.529)
		(end 109.401864 -295.557448)
		(width 0.1143)
		(layer "In4.Cu")
		(net "P5E_CPU1_P1_TX_DN<13>")
	)
	(segment
		(start 109.610906 -291.540946)
		(end 109.582966 -291.561012)
		(width 0.1143)
		(layer "In4.Cu")
		(net "P5E_CPU1_P1_TX_DN<13>")
	)
	(segment
		(start 109.512354 -292.21049)
		(end 109.542072 -292.227508)
		(width 0.1143)
		(layer "In4.Cu")
		(net "P5E_CPU1_P1_TX_DN<13>")
	)
	(segment
		(start 109.731048 -290.286186)
		(end 109.433106 -290.286186)
		(width 0.1143)
		(layer "In4.Cu")
		(net "P5E_CPU1_P1_TX_DN<13>")
	)
	(segment
		(start 109.54385 -293.203884)
		(end 109.5375 -293.20744)
		(width 0.1143)
		(layer "In4.Cu")
		(net "P5E_CPU1_P1_TX_DN<13>")
	)
	(segment
		(start 129.113788 -337.950302)
		(end 129.113788 -348.635574)
		(width 0.14224)
		(layer "In4.Cu")
		(net "P5E_CPU1_P1_TX_DN<13>")
	)
	(segment
		(start 109.433106 -290.286186)
		(end 109.363256 -290.356036)
		(width 0.1143)
		(layer "In4.Cu")
		(net "P5E_CPU1_P1_TX_DN<13>")
	)
	(segment
		(start 109.542072 -292.227508)
		(end 109.543342 -292.22827)
		(width 0.1143)
		(layer "In4.Cu")
		(net "P5E_CPU1_P1_TX_DN<13>")
	)
	(segment
		(start 109.516164 -294.839644)
		(end 109.512354 -294.84193)
		(width 0.1143)
		(layer "In4.Cu")
		(net "P5E_CPU1_P1_TX_DN<13>")
	)
	(segment
		(start 109.401864 -295.557448)
		(end 109.401864 -298.557442)
		(width 0.14224)
		(layer "In4.Cu")
		(net "P5E_CPU1_P1_TX_DN<13>")
	)
	(segment
		(start 101.636322 -366.776508)
		(end 101.636322 -368.73815)
		(width 0.14224)
		(layer "In4.Cu")
		(net "P5E_CPU1_P1_TX_DN<13>")
	)
	(segment
		(start 109.544104 -292.228778)
		(end 109.556804 -292.236398)
		(width 0.1143)
		(layer "In4.Cu")
		(net "P5E_CPU1_P1_TX_DN<13>")
	)
	(segment
		(start 109.512354 -290.590478)
		(end 109.58322 -290.631372)
		(width 0.1143)
		(layer "In4.Cu")
		(net "P5E_CPU1_P1_TX_DN<13>")
	)
	(segment
		(start 109.547914 -291.581078)
		(end 109.544104 -291.583618)
		(width 0.1143)
		(layer "In4.Cu")
		(net "P5E_CPU1_P1_TX_DN<13>")
	)
	(segment
		(start 109.356144 -295.48328)
		(end 109.401864 -295.529)
		(width 0.1143)
		(layer "In4.Cu")
		(net "P5E_CPU1_P1_TX_DN<13>")
	)
	(segment
		(start 109.54639 -294.822372)
		(end 109.516164 -294.839644)
		(width 0.1143)
		(layer "In4.Cu")
		(net "P5E_CPU1_P1_TX_DN<13>")
	)
	(segment
		(start 109.582966 -291.561012)
		(end 109.547914 -291.581078)
		(width 0.1143)
		(layer "In4.Cu")
		(net "P5E_CPU1_P1_TX_DN<13>")
	)
	(segment
		(start 129.092198 -348.82455)
		(end 128.887474 -349.71101)
		(width 0.14224)
		(layer "In4.Cu")
		(net "P5E_CPU1_P1_TX_DN<13>")
	)
	(segment
		(start 127.788162 -351.628456)
		(end 113.956846 -360.8705)
		(width 0.14224)
		(layer "In4.Cu")
		(net "P5E_CPU1_P1_TX_DN<13>")
	)
	(segment
		(start 128.1557 -332.528164)
		(end 129.09804 -337.775042)
		(width 0.14224)
		(layer "In4.Cu")
		(net "P5E_CPU1_P1_TX_DN<13>")
	)
	(segment
		(start 128.814068 -349.901764)
		(end 127.962914 -351.438464)
		(width 0.14224)
		(layer "In4.Cu")
		(net "P5E_CPU1_P1_TX_DN<13>")
	)
	(segment
		(start 124.285756 -321.177158)
		(end 128.113282 -332.364334)
		(width 0.14224)
		(layer "In4.Cu")
		(net "P5E_CPU1_P1_TX_DN<13>")
	)
	(segment
		(start 114.457988 -308.249574)
		(end 122.941334 -318.584834)
		(width 0.14224)
		(layer "In4.Cu")
		(net "P5E_CPU1_P1_TX_DN<13>")
	)
	(segment
		(start 109.58322 -290.631372)
		(end 109.610906 -290.651438)
		(width 0.1143)
		(layer "In4.Cu")
		(net "P5E_CPU1_P1_TX_DN<13>")
	)
	(segment
		(start 109.411516 -298.60621)
		(end 111.689642 -304.106072)
		(width 0.14224)
		(layer "In4.Cu")
		(net "P5E_CPU1_P1_TX_DN<13>")
	)
	(segment
		(start 102.29342 -365.896144)
		(end 101.79431 -366.395254)
		(width 0.14224)
		(layer "In4.Cu")
		(net "P5E_CPU1_P1_TX_DN<13>")
	)
	(segment
		(start 113.845594 -360.929936)
		(end 103.782876 -365.098076)
		(width 0.14224)
		(layer "In4.Cu")
		(net "P5E_CPU1_P1_TX_DN<13>")
	)
	(segment
		(start 109.53369 -293.842694)
		(end 109.545882 -293.849806)
		(width 0.1143)
		(layer "In4.Cu")
		(net "P5E_CPU1_P1_TX_DN<13>")
	)
	(arc
		(start 109.363256 -290.356036)
		(mid 109.415305 -290.487555)
		(end 109.512354 -290.590478)
		(width 0.1143)
		(layer "In4.Cu")
		(net "P5E_CPU1_P1_TX_DN<13>")
	)
	(arc
		(start 129.113788 -348.635574)
		(mid 129.108355 -348.730674)
		(end 129.092198 -348.82455)
		(width 0.14224)
		(layer "In4.Cu")
		(net "P5E_CPU1_P1_TX_DN<13>")
	)
	(arc
		(start 109.54639 -293.850314)
		(mid 109.826318 -294.336406)
		(end 109.54639 -294.822372)
		(width 0.1143)
		(layer "In4.Cu")
		(net "P5E_CPU1_P1_TX_DN<13>")
	)
	(arc
		(start 124.235718 -321.060572)
		(mid 124.262959 -321.117911)
		(end 124.285756 -321.177158)
		(width 0.14224)
		(layer "In4.Cu")
		(net "P5E_CPU1_P1_TX_DN<13>")
	)
	(arc
		(start 109.401864 -298.557442)
		(mid 109.40431 -298.582295)
		(end 109.411516 -298.60621)
		(width 0.14224)
		(layer "In4.Cu")
		(net "P5E_CPU1_P1_TX_DN<13>")
	)
	(arc
		(start 109.512354 -291.601906)
		(mid 109.356426 -291.906198)
		(end 109.512354 -292.21049)
		(width 0.1143)
		(layer "In4.Cu")
		(net "P5E_CPU1_P1_TX_DN<13>")
	)
	(arc
		(start 103.782876 -365.098076)
		(mid 103.753759 -365.110788)
		(end 103.725218 -365.124746)
		(width 0.14224)
		(layer "In4.Cu")
		(net "P5E_CPU1_P1_TX_DN<13>")
	)
	(arc
		(start 102.428802 -365.797084)
		(mid 102.357298 -365.841404)
		(end 102.29342 -365.896144)
		(width 0.14224)
		(layer "In4.Cu")
		(net "P5E_CPU1_P1_TX_DN<13>")
	)
	(arc
		(start 128.887474 -349.71101)
		(mid 128.857422 -349.808946)
		(end 128.814068 -349.901764)
		(width 0.14224)
		(layer "In4.Cu")
		(net "P5E_CPU1_P1_TX_DN<13>")
	)
	(arc
		(start 128.113282 -332.364334)
		(mid 128.137605 -332.445443)
		(end 128.1557 -332.528164)
		(width 0.14224)
		(layer "In4.Cu")
		(net "P5E_CPU1_P1_TX_DN<13>")
	)
	(arc
		(start 109.556804 -292.236398)
		(mid 109.827021 -292.72093)
		(end 109.548676 -293.200836)
		(width 0.1143)
		(layer "In4.Cu")
		(net "P5E_CPU1_P1_TX_DN<13>")
	)
	(arc
		(start 109.409992 -294.953182)
		(mid 109.369886 -295.046029)
		(end 109.356144 -295.146222)
		(width 0.1143)
		(layer "In4.Cu")
		(net "P5E_CPU1_P1_TX_DN<13>")
	)
	(arc
		(start 109.610906 -290.651438)
		(mid 109.838906 -291.096192)
		(end 109.610906 -291.540946)
		(width 0.1143)
		(layer "In4.Cu")
		(net "P5E_CPU1_P1_TX_DN<13>")
	)
	(arc
		(start 101.79431 -366.395254)
		(mid 101.677378 -366.570161)
		(end 101.636322 -366.776508)
		(width 0.14224)
		(layer "In4.Cu")
		(net "P5E_CPU1_P1_TX_DN<13>")
	)
	(arc
		(start 109.512354 -294.84193)
		(mid 109.455492 -294.892331)
		(end 109.409992 -294.953182)
		(width 0.1143)
		(layer "In4.Cu")
		(net "P5E_CPU1_P1_TX_DN<13>")
	)
	(arc
		(start 127.962914 -351.438464)
		(mid 127.886894 -351.543907)
		(end 127.788162 -351.628456)
		(width 0.14224)
		(layer "In4.Cu")
		(net "P5E_CPU1_P1_TX_DN<13>")
	)
	(arc
		(start 113.956846 -360.8705)
		(mid 113.902674 -360.902939)
		(end 113.845594 -360.929936)
		(width 0.14224)
		(layer "In4.Cu")
		(net "P5E_CPU1_P1_TX_DN<13>")
	)
	(arc
		(start 129.09804 -337.775042)
		(mid 129.109801 -337.862323)
		(end 129.113788 -337.950302)
		(width 0.14224)
		(layer "In4.Cu")
		(net "P5E_CPU1_P1_TX_DN<13>")
	)
	(arc
		(start 109.5375 -293.20744)
		(mid 109.358979 -293.523989)
		(end 109.53369 -293.842694)
		(width 0.1143)
		(layer "In4.Cu")
		(net "P5E_CPU1_P1_TX_DN<13>")
	)
	(segment
		(start 107.847892 -287.590484)
		(end 107.38104 -287.856422)
		(width 0.12954)
		(layer "F.Cu")
		(net "P5E_CPU1_P1_TX_DN<12>")
	)
	(segment
		(start 98.555302 -370.30533)
		(end 98.259392 -370.00942)
		(width 0.12954)
		(layer "F.Cu")
		(net "P5E_CPU1_P1_TX_DN<12>")
	)
	(segment
		(start 98.259392 -370.00942)
		(end 98.259392 -369.30584)
		(width 0.12954)
		(layer "F.Cu")
		(net "P5E_CPU1_P1_TX_DN<12>")
	)
	(segment
		(start 98.259392 -369.30584)
		(end 98.529902 -369.03533)
		(width 0.12954)
		(layer "F.Cu")
		(net "P5E_CPU1_P1_TX_DN<12>")
	)
	(segment
		(start 108.605066 -294.823134)
		(end 108.60405 -294.823642)
		(width 0.1143)
		(layer "In4.Cu")
		(net "P5E_CPU1_P1_TX_DN<12>")
	)
	(segment
		(start 108.58373 -291.595556)
		(end 108.579412 -291.598096)
		(width 0.1143)
		(layer "In4.Cu")
		(net "P5E_CPU1_P1_TX_DN<12>")
	)
	(segment
		(start 108.602018 -291.584888)
		(end 108.600494 -291.58565)
		(width 0.1143)
		(layer "In4.Cu")
		(net "P5E_CPU1_P1_TX_DN<12>")
	)
	(segment
		(start 108.605066 -293.203122)
		(end 108.60405 -293.20363)
		(width 0.1143)
		(layer "In4.Cu")
		(net "P5E_CPU1_P1_TX_DN<12>")
	)
	(segment
		(start 108.60659 -290.61029)
		(end 108.607606 -290.610798)
		(width 0.1143)
		(layer "In4.Cu")
		(net "P5E_CPU1_P1_TX_DN<12>")
	)
	(segment
		(start 110.877858 -304.582576)
		(end 113.678462 -308.77383)
		(width 0.14224)
		(layer "In4.Cu")
		(net "P5E_CPU1_P1_TX_DN<12>")
	)
	(segment
		(start 108.60405 -293.84879)
		(end 108.605066 -293.849298)
		(width 0.1143)
		(layer "In4.Cu")
		(net "P5E_CPU1_P1_TX_DN<12>")
	)
	(segment
		(start 108.603288 -293.204138)
		(end 108.602018 -293.2049)
		(width 0.1143)
		(layer "In4.Cu")
		(net "P5E_CPU1_P1_TX_DN<12>")
	)
	(segment
		(start 108.5977 -293.20744)
		(end 108.593382 -293.20998)
		(width 0.1143)
		(layer "In4.Cu")
		(net "P5E_CPU1_P1_TX_DN<12>")
	)
	(segment
		(start 108.60405 -293.20363)
		(end 108.603288 -293.204138)
		(width 0.1143)
		(layer "In4.Cu")
		(net "P5E_CPU1_P1_TX_DN<12>")
	)
	(segment
		(start 108.60659 -293.202106)
		(end 108.605066 -293.203122)
		(width 0.1143)
		(layer "In4.Cu")
		(net "P5E_CPU1_P1_TX_DN<12>")
	)
	(segment
		(start 108.585254 -293.214552)
		(end 108.58373 -293.215568)
		(width 0.1143)
		(layer "In4.Cu")
		(net "P5E_CPU1_P1_TX_DN<12>")
	)
	(segment
		(start 108.643166 -293.18077)
		(end 108.60659 -293.202106)
		(width 0.1143)
		(layer "In4.Cu")
		(net "P5E_CPU1_P1_TX_DN<12>")
	)
	(segment
		(start 108.59262 -294.8305)
		(end 108.589318 -294.832278)
		(width 0.1143)
		(layer "In4.Cu")
		(net "P5E_CPU1_P1_TX_DN<12>")
	)
	(segment
		(start 108.5723 -293.830502)
		(end 108.603288 -293.848282)
		(width 0.1143)
		(layer "In4.Cu")
		(net "P5E_CPU1_P1_TX_DN<12>")
	)
	(segment
		(start 128.148334 -337.854036)
		(end 128.148334 -348.458536)
		(width 0.14224)
		(layer "In4.Cu")
		(net "P5E_CPU1_P1_TX_DN<12>")
	)
	(segment
		(start 108.607606 -292.23081)
		(end 108.643166 -292.251638)
		(width 0.1143)
		(layer "In4.Cu")
		(net "P5E_CPU1_P1_TX_DN<12>")
	)
	(segment
		(start 108.579412 -293.218108)
		(end 108.5723 -293.221918)
		(width 0.1143)
		(layer "In4.Cu")
		(net "P5E_CPU1_P1_TX_DN<12>")
	)
	(segment
		(start 107.666536 -288.990278)
		(end 107.668568 -288.991548)
		(width 0.1143)
		(layer "In4.Cu")
		(net "P5E_CPU1_P1_TX_DN<12>")
	)
	(segment
		(start 108.589318 -294.832278)
		(end 108.587286 -294.833548)
		(width 0.1143)
		(layer "In4.Cu")
		(net "P5E_CPU1_P1_TX_DN<12>")
	)
	(segment
		(start 108.603288 -290.608258)
		(end 108.60405 -290.608766)
		(width 0.1143)
		(layer "In4.Cu")
		(net "P5E_CPU1_P1_TX_DN<12>")
	)
	(segment
		(start 108.60659 -294.822118)
		(end 108.605066 -294.823134)
		(width 0.1143)
		(layer "In4.Cu")
		(net "P5E_CPU1_P1_TX_DN<12>")
	)
	(segment
		(start 108.13161 -289.797236)
		(end 108.135166 -289.799522)
		(width 0.1143)
		(layer "In4.Cu")
		(net "P5E_CPU1_P1_TX_DN<12>")
	)
	(segment
		(start 108.5723 -292.21049)
		(end 108.603288 -292.22827)
		(width 0.1143)
		(layer "In4.Cu")
		(net "P5E_CPU1_P1_TX_DN<12>")
	)
	(segment
		(start 108.605066 -293.849298)
		(end 108.60659 -293.850314)
		(width 0.1143)
		(layer "In4.Cu")
		(net "P5E_CPU1_P1_TX_DN<12>")
	)
	(segment
		(start 108.643166 -294.800782)
		(end 108.60659 -294.822118)
		(width 0.1143)
		(layer "In4.Cu")
		(net "P5E_CPU1_P1_TX_DN<12>")
	)
	(segment
		(start 108.599224 -293.206424)
		(end 108.5977 -293.20744)
		(width 0.1143)
		(layer "In4.Cu")
		(net "P5E_CPU1_P1_TX_DN<12>")
	)
	(segment
		(start 108.605066 -291.58311)
		(end 108.60405 -291.583618)
		(width 0.1143)
		(layer "In4.Cu")
		(net "P5E_CPU1_P1_TX_DN<12>")
	)
	(segment
		(start 108.585254 -294.834564)
		(end 108.58373 -294.83558)
		(width 0.1143)
		(layer "In4.Cu")
		(net "P5E_CPU1_P1_TX_DN<12>")
	)
	(segment
		(start 108.603288 -293.848282)
		(end 108.60405 -293.84879)
		(width 0.1143)
		(layer "In4.Cu")
		(net "P5E_CPU1_P1_TX_DN<12>")
	)
	(segment
		(start 108.605066 -292.229286)
		(end 108.60659 -292.230302)
		(width 0.1143)
		(layer "In4.Cu")
		(net "P5E_CPU1_P1_TX_DN<12>")
	)
	(segment
		(start 108.599224 -291.586412)
		(end 108.5977 -291.587428)
		(width 0.1143)
		(layer "In4.Cu")
		(net "P5E_CPU1_P1_TX_DN<12>")
	)
	(segment
		(start 108.5977 -291.587428)
		(end 108.593382 -291.589968)
		(width 0.1143)
		(layer "In4.Cu")
		(net "P5E_CPU1_P1_TX_DN<12>")
	)
	(segment
		(start 108.46181 -295.529)
		(end 108.46181 -295.557448)
		(width 0.1143)
		(layer "In4.Cu")
		(net "P5E_CPU1_P1_TX_DN<12>")
	)
	(segment
		(start 108.60659 -292.230302)
		(end 108.607606 -292.23081)
		(width 0.1143)
		(layer "In4.Cu")
		(net "P5E_CPU1_P1_TX_DN<12>")
	)
	(segment
		(start 108.587286 -291.593524)
		(end 108.585254 -291.59454)
		(width 0.1143)
		(layer "In4.Cu")
		(net "P5E_CPU1_P1_TX_DN<12>")
	)
	(segment
		(start 108.60405 -291.583618)
		(end 108.603288 -291.584126)
		(width 0.1143)
		(layer "In4.Cu")
		(net "P5E_CPU1_P1_TX_DN<12>")
	)
	(segment
		(start 108.58373 -294.83558)
		(end 108.579412 -294.83812)
		(width 0.1143)
		(layer "In4.Cu")
		(net "P5E_CPU1_P1_TX_DN<12>")
	)
	(segment
		(start 108.46181 -295.557448)
		(end 108.46181 -298.724574)
		(width 0.14224)
		(layer "In4.Cu")
		(net "P5E_CPU1_P1_TX_DN<12>")
	)
	(segment
		(start 108.607606 -293.850822)
		(end 108.643166 -293.87165)
		(width 0.1143)
		(layer "In4.Cu")
		(net "P5E_CPU1_P1_TX_DN<12>")
	)
	(segment
		(start 126.899162 -350.735646)
		(end 112.022128 -360.675936)
		(width 0.14224)
		(layer "In4.Cu")
		(net "P5E_CPU1_P1_TX_DN<12>")
	)
	(segment
		(start 108.600494 -291.58565)
		(end 108.599224 -291.586412)
		(width 0.1143)
		(layer "In4.Cu")
		(net "P5E_CPU1_P1_TX_DN<12>")
	)
	(segment
		(start 108.5977 -294.827452)
		(end 108.593382 -294.829992)
		(width 0.1143)
		(layer "In4.Cu")
		(net "P5E_CPU1_P1_TX_DN<12>")
	)
	(segment
		(start 108.593382 -291.589968)
		(end 108.59262 -291.590476)
		(width 0.1143)
		(layer "In4.Cu")
		(net "P5E_CPU1_P1_TX_DN<12>")
	)
	(segment
		(start 108.579412 -291.598096)
		(end 108.5723 -291.601906)
		(width 0.1143)
		(layer "In4.Cu")
		(net "P5E_CPU1_P1_TX_DN<12>")
	)
	(segment
		(start 98.239072 -367.85931)
		(end 98.239072 -368.7445)
		(width 0.14224)
		(layer "In4.Cu")
		(net "P5E_CPU1_P1_TX_DN<12>")
	)
	(segment
		(start 127.290576 -332.989936)
		(end 128.132586 -337.678776)
		(width 0.14224)
		(layer "In4.Cu")
		(net "P5E_CPU1_P1_TX_DN<12>")
	)
	(segment
		(start 122.09018 -319.022222)
		(end 123.469908 -321.701668)
		(width 0.14224)
		(layer "In4.Cu")
		(net "P5E_CPU1_P1_TX_DN<12>")
	)
	(segment
		(start 108.600494 -294.825674)
		(end 108.599224 -294.826436)
		(width 0.1143)
		(layer "In4.Cu")
		(net "P5E_CPU1_P1_TX_DN<12>")
	)
	(segment
		(start 108.60405 -294.823642)
		(end 108.603288 -294.82415)
		(width 0.1143)
		(layer "In4.Cu")
		(net "P5E_CPU1_P1_TX_DN<12>")
	)
	(segment
		(start 108.13034 -289.796728)
		(end 108.13161 -289.797236)
		(width 0.1143)
		(layer "In4.Cu")
		(net "P5E_CPU1_P1_TX_DN<12>")
	)
	(segment
		(start 108.589318 -293.212266)
		(end 108.587286 -293.213536)
		(width 0.1143)
		(layer "In4.Cu")
		(net "P5E_CPU1_P1_TX_DN<12>")
	)
	(segment
		(start 107.634278 -288.971482)
		(end 107.666536 -288.990278)
		(width 0.1143)
		(layer "In4.Cu")
		(net "P5E_CPU1_P1_TX_DN<12>")
	)
	(segment
		(start 123.519184 -321.818)
		(end 127.248666 -332.827122)
		(width 0.14224)
		(layer "In4.Cu")
		(net "P5E_CPU1_P1_TX_DN<12>")
	)
	(segment
		(start 99.480878 -366.353852)
		(end 98.425508 -367.409222)
		(width 0.14224)
		(layer "In4.Cu")
		(net "P5E_CPU1_P1_TX_DN<12>")
	)
	(segment
		(start 108.60659 -291.582094)
		(end 108.605066 -291.58311)
		(width 0.1143)
		(layer "In4.Cu")
		(net "P5E_CPU1_P1_TX_DN<12>")
	)
	(segment
		(start 108.579412 -294.83812)
		(end 108.5723 -294.84193)
		(width 0.1143)
		(layer "In4.Cu")
		(net "P5E_CPU1_P1_TX_DN<12>")
	)
	(segment
		(start 107.083098 -287.856422)
		(end 107.013248 -287.926272)
		(width 0.1143)
		(layer "In4.Cu")
		(net "P5E_CPU1_P1_TX_DN<12>")
	)
	(segment
		(start 108.5723 -290.590478)
		(end 108.603288 -290.608258)
		(width 0.1143)
		(layer "In4.Cu")
		(net "P5E_CPU1_P1_TX_DN<12>")
	)
	(segment
		(start 108.60405 -292.228778)
		(end 108.605066 -292.229286)
		(width 0.1143)
		(layer "In4.Cu")
		(net "P5E_CPU1_P1_TX_DN<12>")
	)
	(segment
		(start 108.643166 -291.560758)
		(end 108.60659 -291.582094)
		(width 0.1143)
		(layer "In4.Cu")
		(net "P5E_CPU1_P1_TX_DN<12>")
	)
	(segment
		(start 108.587286 -293.213536)
		(end 108.585254 -293.214552)
		(width 0.1143)
		(layer "In4.Cu")
		(net "P5E_CPU1_P1_TX_DN<12>")
	)
	(segment
		(start 101.38283 -365.08309)
		(end 99.480878 -366.353852)
		(width 0.14224)
		(layer "In4.Cu")
		(net "P5E_CPU1_P1_TX_DN<12>")
	)
	(segment
		(start 108.41609 -295.48328)
		(end 108.46181 -295.529)
		(width 0.1143)
		(layer "In4.Cu")
		(net "P5E_CPU1_P1_TX_DN<12>")
	)
	(segment
		(start 108.605066 -290.609274)
		(end 108.60659 -290.61029)
		(width 0.1143)
		(layer "In4.Cu")
		(net "P5E_CPU1_P1_TX_DN<12>")
	)
	(segment
		(start 108.602018 -294.824912)
		(end 108.600494 -294.825674)
		(width 0.1143)
		(layer "In4.Cu")
		(net "P5E_CPU1_P1_TX_DN<12>")
	)
	(segment
		(start 108.607606 -290.610798)
		(end 108.643166 -290.631626)
		(width 0.1143)
		(layer "In4.Cu")
		(net "P5E_CPU1_P1_TX_DN<12>")
	)
	(segment
		(start 107.38104 -287.856422)
		(end 107.083098 -287.856422)
		(width 0.1143)
		(layer "In4.Cu")
		(net "P5E_CPU1_P1_TX_DN<12>")
	)
	(segment
		(start 108.60659 -293.850314)
		(end 108.607606 -293.850822)
		(width 0.1143)
		(layer "In4.Cu")
		(net "P5E_CPU1_P1_TX_DN<12>")
	)
	(segment
		(start 98.239072 -368.7445)
		(end 98.529902 -369.03533)
		(width 0.14224)
		(layer "In4.Cu")
		(net "P5E_CPU1_P1_TX_DN<12>")
	)
	(segment
		(start 128.082294 -348.716092)
		(end 127.074422 -350.544892)
		(width 0.14224)
		(layer "In4.Cu")
		(net "P5E_CPU1_P1_TX_DN<12>")
	)
	(segment
		(start 108.59262 -291.590476)
		(end 108.589318 -291.592254)
		(width 0.1143)
		(layer "In4.Cu")
		(net "P5E_CPU1_P1_TX_DN<12>")
	)
	(segment
		(start 108.593382 -294.829992)
		(end 108.59262 -294.8305)
		(width 0.1143)
		(layer "In4.Cu")
		(net "P5E_CPU1_P1_TX_DN<12>")
	)
	(segment
		(start 108.60405 -290.608766)
		(end 108.605066 -290.609274)
		(width 0.1143)
		(layer "In4.Cu")
		(net "P5E_CPU1_P1_TX_DN<12>")
	)
	(segment
		(start 108.58373 -293.215568)
		(end 108.579412 -293.218108)
		(width 0.1143)
		(layer "In4.Cu")
		(net "P5E_CPU1_P1_TX_DN<12>")
	)
	(segment
		(start 113.678462 -308.77383)
		(end 122.09018 -319.022222)
		(width 0.14224)
		(layer "In4.Cu")
		(net "P5E_CPU1_P1_TX_DN<12>")
	)
	(segment
		(start 107.194096 -288.178748)
		(end 107.230418 -288.19983)
		(width 0.1143)
		(layer "In4.Cu")
		(net "P5E_CPU1_P1_TX_DN<12>")
	)
	(segment
		(start 107.160568 -288.15919)
		(end 107.194096 -288.178748)
		(width 0.1143)
		(layer "In4.Cu")
		(net "P5E_CPU1_P1_TX_DN<12>")
	)
	(segment
		(start 108.599224 -294.826436)
		(end 108.5977 -294.827452)
		(width 0.1143)
		(layer "In4.Cu")
		(net "P5E_CPU1_P1_TX_DN<12>")
	)
	(segment
		(start 108.589318 -291.592254)
		(end 108.587286 -291.593524)
		(width 0.1143)
		(layer "In4.Cu")
		(net "P5E_CPU1_P1_TX_DN<12>")
	)
	(segment
		(start 108.135166 -289.799522)
		(end 108.171488 -289.820604)
		(width 0.1143)
		(layer "In4.Cu")
		(net "P5E_CPU1_P1_TX_DN<12>")
	)
	(segment
		(start 108.602018 -293.2049)
		(end 108.600494 -293.205662)
		(width 0.1143)
		(layer "In4.Cu")
		(net "P5E_CPU1_P1_TX_DN<12>")
	)
	(segment
		(start 108.59262 -293.210488)
		(end 108.589318 -293.212266)
		(width 0.1143)
		(layer "In4.Cu")
		(net "P5E_CPU1_P1_TX_DN<12>")
	)
	(segment
		(start 108.587286 -294.833548)
		(end 108.585254 -294.834564)
		(width 0.1143)
		(layer "In4.Cu")
		(net "P5E_CPU1_P1_TX_DN<12>")
	)
	(segment
		(start 108.600494 -293.205662)
		(end 108.599224 -293.206424)
		(width 0.1143)
		(layer "In4.Cu")
		(net "P5E_CPU1_P1_TX_DN<12>")
	)
	(segment
		(start 108.585254 -291.59454)
		(end 108.58373 -291.595556)
		(width 0.1143)
		(layer "In4.Cu")
		(net "P5E_CPU1_P1_TX_DN<12>")
	)
	(segment
		(start 108.471462 -298.773342)
		(end 110.877858 -304.582576)
		(width 0.14224)
		(layer "In4.Cu")
		(net "P5E_CPU1_P1_TX_DN<12>")
	)
	(segment
		(start 108.603288 -291.584126)
		(end 108.602018 -291.584888)
		(width 0.1143)
		(layer "In4.Cu")
		(net "P5E_CPU1_P1_TX_DN<12>")
	)
	(segment
		(start 108.603288 -292.22827)
		(end 108.60405 -292.228778)
		(width 0.1143)
		(layer "In4.Cu")
		(net "P5E_CPU1_P1_TX_DN<12>")
	)
	(segment
		(start 112.022128 -360.675936)
		(end 101.38283 -365.08309)
		(width 0.14224)
		(layer "In4.Cu")
		(net "P5E_CPU1_P1_TX_DN<12>")
	)
	(segment
		(start 108.41609 -295.146222)
		(end 108.41609 -295.48328)
		(width 0.1143)
		(layer "In4.Cu")
		(net "P5E_CPU1_P1_TX_DN<12>")
	)
	(segment
		(start 108.603288 -294.82415)
		(end 108.602018 -294.824912)
		(width 0.1143)
		(layer "In4.Cu")
		(net "P5E_CPU1_P1_TX_DN<12>")
	)
	(segment
		(start 108.593382 -293.20998)
		(end 108.59262 -293.210488)
		(width 0.1143)
		(layer "In4.Cu")
		(net "P5E_CPU1_P1_TX_DN<12>")
	)
	(arc
		(start 128.132586 -337.678776)
		(mid 128.144347 -337.766057)
		(end 128.148334 -337.854036)
		(width 0.14224)
		(layer "In4.Cu")
		(net "P5E_CPU1_P1_TX_DN<12>")
	)
	(arc
		(start 107.668568 -288.991548)
		(mid 107.872622 -289.197514)
		(end 107.947206 -289.477704)
		(width 0.1143)
		(layer "In4.Cu")
		(net "P5E_CPU1_P1_TX_DN<12>")
	)
	(arc
		(start 108.171488 -289.820604)
		(mid 108.17225 -289.821111)
		(end 108.173012 -289.82162)
		(width 0.1143)
		(layer "In4.Cu")
		(net "P5E_CPU1_P1_TX_DN<12>")
	)
	(arc
		(start 108.643166 -292.251638)
		(mid 108.886493 -292.716204)
		(end 108.643166 -293.18077)
		(width 0.1143)
		(layer "In4.Cu")
		(net "P5E_CPU1_P1_TX_DN<12>")
	)
	(arc
		(start 123.469908 -321.701668)
		(mid 123.496716 -321.758915)
		(end 123.519184 -321.818)
		(width 0.14224)
		(layer "In4.Cu")
		(net "P5E_CPU1_P1_TX_DN<12>")
	)
	(arc
		(start 108.482384 -294.933878)
		(mid 108.433064 -295.035007)
		(end 108.41609 -295.146222)
		(width 0.1143)
		(layer "In4.Cu")
		(net "P5E_CPU1_P1_TX_DN<12>")
	)
	(arc
		(start 107.230418 -288.19983)
		(mid 107.41107 -288.402575)
		(end 107.47629 -288.666174)
		(width 0.1143)
		(layer "In4.Cu")
		(net "P5E_CPU1_P1_TX_DN<12>")
	)
	(arc
		(start 108.46181 -298.724574)
		(mid 108.464256 -298.749427)
		(end 108.471462 -298.773342)
		(width 0.14224)
		(layer "In4.Cu")
		(net "P5E_CPU1_P1_TX_DN<12>")
	)
	(arc
		(start 108.5723 -294.84193)
		(mid 108.523368 -294.884018)
		(end 108.482384 -294.933878)
		(width 0.1143)
		(layer "In4.Cu")
		(net "P5E_CPU1_P1_TX_DN<12>")
	)
	(arc
		(start 107.47629 -288.666174)
		(mid 107.518169 -288.838043)
		(end 107.634278 -288.971482)
		(width 0.1143)
		(layer "In4.Cu")
		(net "P5E_CPU1_P1_TX_DN<12>")
	)
	(arc
		(start 108.643166 -290.631626)
		(mid 108.886493 -291.096192)
		(end 108.643166 -291.560758)
		(width 0.1143)
		(layer "In4.Cu")
		(net "P5E_CPU1_P1_TX_DN<12>")
	)
	(arc
		(start 128.148334 -348.458536)
		(mid 128.131627 -348.591498)
		(end 128.082294 -348.716092)
		(width 0.14224)
		(layer "In4.Cu")
		(net "P5E_CPU1_P1_TX_DN<12>")
	)
	(arc
		(start 127.074422 -350.544892)
		(mid 126.998233 -350.650776)
		(end 126.899162 -350.735646)
		(width 0.14224)
		(layer "In4.Cu")
		(net "P5E_CPU1_P1_TX_DN<12>")
	)
	(arc
		(start 107.013248 -287.926272)
		(mid 107.064738 -288.056745)
		(end 107.160568 -288.15919)
		(width 0.1143)
		(layer "In4.Cu")
		(net "P5E_CPU1_P1_TX_DN<12>")
	)
	(arc
		(start 108.5723 -293.221918)
		(mid 108.416372 -293.52621)
		(end 108.5723 -293.830502)
		(width 0.1143)
		(layer "In4.Cu")
		(net "P5E_CPU1_P1_TX_DN<12>")
	)
	(arc
		(start 127.248666 -332.827122)
		(mid 127.272656 -332.907748)
		(end 127.290576 -332.989936)
		(width 0.14224)
		(layer "In4.Cu")
		(net "P5E_CPU1_P1_TX_DN<12>")
	)
	(arc
		(start 108.5723 -291.601906)
		(mid 108.416372 -291.906198)
		(end 108.5723 -292.21049)
		(width 0.1143)
		(layer "In4.Cu")
		(net "P5E_CPU1_P1_TX_DN<12>")
	)
	(arc
		(start 108.416344 -290.286186)
		(mid 108.457599 -290.457157)
		(end 108.5723 -290.590478)
		(width 0.1143)
		(layer "In4.Cu")
		(net "P5E_CPU1_P1_TX_DN<12>")
	)
	(arc
		(start 98.425508 -367.409222)
		(mid 98.287528 -367.615724)
		(end 98.239072 -367.85931)
		(width 0.14224)
		(layer "In4.Cu")
		(net "P5E_CPU1_P1_TX_DN<12>")
	)
	(arc
		(start 108.643166 -293.87165)
		(mid 108.886493 -294.336216)
		(end 108.643166 -294.800782)
		(width 0.1143)
		(layer "In4.Cu")
		(net "P5E_CPU1_P1_TX_DN<12>")
	)
	(arc
		(start 107.947206 -289.477704)
		(mid 107.996254 -289.661614)
		(end 108.13034 -289.796728)
		(width 0.1143)
		(layer "In4.Cu")
		(net "P5E_CPU1_P1_TX_DN<12>")
	)
	(arc
		(start 108.173012 -289.82162)
		(mid 108.351825 -290.02397)
		(end 108.416344 -290.286186)
		(width 0.1143)
		(layer "In4.Cu")
		(net "P5E_CPU1_P1_TX_DN<12>")
	)
	(segment
		(start 96.557592 -372.47322)
		(end 96.557592 -371.76964)
		(width 0.12954)
		(layer "F.Cu")
		(net "P5E_CPU1_P1_TX_DN<11>")
	)
	(segment
		(start 96.853502 -372.76913)
		(end 96.557592 -372.47322)
		(width 0.12954)
		(layer "F.Cu")
		(net "P5E_CPU1_P1_TX_DN<11>")
	)
	(segment
		(start 96.557592 -371.76964)
		(end 96.828102 -371.49913)
		(width 0.12954)
		(layer "F.Cu")
		(net "P5E_CPU1_P1_TX_DN<11>")
	)
	(segment
		(start 107.847892 -290.830254)
		(end 107.38104 -291.096192)
		(width 0.12954)
		(layer "F.Cu")
		(net "P5E_CPU1_P1_TX_DN<11>")
	)
	(segment
		(start 107.083098 -291.096192)
		(end 107.013248 -291.166042)
		(width 0.1143)
		(layer "In4.Cu")
		(net "P5E_CPU1_P1_TX_DN<11>")
	)
	(segment
		(start 107.709462 -293.876222)
		(end 107.71251 -293.878508)
		(width 0.1143)
		(layer "In4.Cu")
		(net "P5E_CPU1_P1_TX_DN<11>")
	)
	(segment
		(start 107.46359 -295.153842)
		(end 107.46359 -295.207182)
		(width 0.1143)
		(layer "In4.Cu")
		(net "P5E_CPU1_P1_TX_DN<11>")
	)
	(segment
		(start 107.19689 -291.42055)
		(end 107.232958 -291.441378)
		(width 0.1143)
		(layer "In4.Cu")
		(net "P5E_CPU1_P1_TX_DN<11>")
	)
	(segment
		(start 107.47629 -291.904166)
		(end 107.47629 -291.907214)
		(width 0.1143)
		(layer "In4.Cu")
		(net "P5E_CPU1_P1_TX_DN<11>")
	)
	(segment
		(start 107.305856 -298.39539)
		(end 110.057692 -305.039268)
		(width 0.14224)
		(layer "In4.Cu")
		(net "P5E_CPU1_P1_TX_DN<11>")
	)
	(segment
		(start 107.162346 -291.400484)
		(end 107.193334 -291.418264)
		(width 0.1143)
		(layer "In4.Cu")
		(net "P5E_CPU1_P1_TX_DN<11>")
	)
	(segment
		(start 107.250484 -296.476928)
		(end 107.250484 -296.538396)
		(width 0.1143)
		(layer "In4.Cu")
		(net "P5E_CPU1_P1_TX_DN<11>")
	)
	(segment
		(start 107.250484 -296.538396)
		(end 107.296204 -296.584116)
		(width 0.1143)
		(layer "In4.Cu")
		(net "P5E_CPU1_P1_TX_DN<11>")
	)
	(segment
		(start 107.193334 -291.418264)
		(end 107.194096 -291.418772)
		(width 0.1143)
		(layer "In4.Cu")
		(net "P5E_CPU1_P1_TX_DN<11>")
	)
	(segment
		(start 107.717336 -293.882064)
		(end 107.721146 -293.885112)
		(width 0.1143)
		(layer "In4.Cu")
		(net "P5E_CPU1_P1_TX_DN<11>")
	)
	(segment
		(start 107.663996 -293.20363)
		(end 107.642406 -293.216076)
		(width 0.1143)
		(layer "In4.Cu")
		(net "P5E_CPU1_P1_TX_DN<11>")
	)
	(segment
		(start 96.537272 -368.586258)
		(end 96.537272 -371.2083)
		(width 0.14224)
		(layer "In4.Cu")
		(net "P5E_CPU1_P1_TX_DN<11>")
	)
	(segment
		(start 107.714034 -293.879524)
		(end 107.715304 -293.88054)
		(width 0.1143)
		(layer "In4.Cu")
		(net "P5E_CPU1_P1_TX_DN<11>")
	)
	(segment
		(start 107.663996 -292.228778)
		(end 107.703112 -292.251638)
		(width 0.1143)
		(layer "In4.Cu")
		(net "P5E_CPU1_P1_TX_DN<11>")
	)
	(segment
		(start 107.38104 -291.096192)
		(end 107.083098 -291.096192)
		(width 0.1143)
		(layer "In4.Cu")
		(net "P5E_CPU1_P1_TX_DN<11>")
	)
	(segment
		(start 107.222544 -295.617392)
		(end 107.17911 -295.646348)
		(width 0.1143)
		(layer "In4.Cu")
		(net "P5E_CPU1_P1_TX_DN<11>")
	)
	(segment
		(start 107.703874 -294.799004)
		(end 107.619546 -294.84955)
		(width 0.1143)
		(layer "In4.Cu")
		(net "P5E_CPU1_P1_TX_DN<11>")
	)
	(segment
		(start 107.17784 -295.64711)
		(end 107.173014 -295.64584)
		(width 0.1143)
		(layer "In4.Cu")
		(net "P5E_CPU1_P1_TX_DN<11>")
	)
	(segment
		(start 107.194096 -291.418772)
		(end 107.19689 -291.42055)
		(width 0.1143)
		(layer "In4.Cu")
		(net "P5E_CPU1_P1_TX_DN<11>")
	)
	(segment
		(start 110.057692 -305.039268)
		(end 112.90808 -309.30469)
		(width 0.14224)
		(layer "In4.Cu")
		(net "P5E_CPU1_P1_TX_DN<11>")
	)
	(segment
		(start 107.642152 -293.836344)
		(end 107.64266 -293.836344)
		(width 0.1143)
		(layer "In4.Cu")
		(net "P5E_CPU1_P1_TX_DN<11>")
	)
	(segment
		(start 98.094292 -366.131348)
		(end 97.172272 -367.053368)
		(width 0.14224)
		(layer "In4.Cu")
		(net "P5E_CPU1_P1_TX_DN<11>")
	)
	(segment
		(start 107.115356 -296.210228)
		(end 107.157266 -296.252138)
		(width 0.1143)
		(layer "In4.Cu")
		(net "P5E_CPU1_P1_TX_DN<11>")
	)
	(segment
		(start 100.83419 -364.30077)
		(end 98.094292 -366.131348)
		(width 0.14224)
		(layer "In4.Cu")
		(net "P5E_CPU1_P1_TX_DN<11>")
	)
	(segment
		(start 107.632246 -292.21049)
		(end 107.663996 -292.228778)
		(width 0.1143)
		(layer "In4.Cu")
		(net "P5E_CPU1_P1_TX_DN<11>")
	)
	(segment
		(start 96.537272 -371.2083)
		(end 96.828102 -371.49913)
		(width 0.14224)
		(layer "In4.Cu")
		(net "P5E_CPU1_P1_TX_DN<11>")
	)
	(segment
		(start 111.067088 -360.062272)
		(end 100.83419 -364.30077)
		(width 0.14224)
		(layer "In4.Cu")
		(net "P5E_CPU1_P1_TX_DN<11>")
	)
	(segment
		(start 122.53976 -321.945254)
		(end 126.34849 -333.07655)
		(width 0.14224)
		(layer "In4.Cu")
		(net "P5E_CPU1_P1_TX_DN<11>")
	)
	(segment
		(start 107.228894 -295.613582)
		(end 107.22864 -295.613836)
		(width 0.1143)
		(layer "In4.Cu")
		(net "P5E_CPU1_P1_TX_DN<11>")
	)
	(segment
		(start 107.296204 -296.584116)
		(end 107.296204 -296.612564)
		(width 0.1143)
		(layer "In4.Cu")
		(net "P5E_CPU1_P1_TX_DN<11>")
	)
	(segment
		(start 107.22864 -295.613836)
		(end 107.222544 -295.617392)
		(width 0.1143)
		(layer "In4.Cu")
		(net "P5E_CPU1_P1_TX_DN<11>")
	)
	(segment
		(start 107.47629 -291.907214)
		(end 107.476544 -291.908738)
		(width 0.1143)
		(layer "In4.Cu")
		(net "P5E_CPU1_P1_TX_DN<11>")
	)
	(segment
		(start 121.23674 -319.453514)
		(end 122.53976 -321.945254)
		(width 0.14224)
		(layer "In4.Cu")
		(net "P5E_CPU1_P1_TX_DN<11>")
	)
	(segment
		(start 107.703112 -293.87165)
		(end 107.709462 -293.876222)
		(width 0.1143)
		(layer "In4.Cu")
		(net "P5E_CPU1_P1_TX_DN<11>")
	)
	(segment
		(start 107.703112 -293.18077)
		(end 107.663996 -293.20363)
		(width 0.1143)
		(layer "In4.Cu")
		(net "P5E_CPU1_P1_TX_DN<11>")
	)
	(segment
		(start 112.90808 -309.30469)
		(end 121.23674 -319.453514)
		(width 0.14224)
		(layer "In4.Cu")
		(net "P5E_CPU1_P1_TX_DN<11>")
	)
	(segment
		(start 107.71251 -293.878508)
		(end 107.714034 -293.879524)
		(width 0.1143)
		(layer "In4.Cu")
		(net "P5E_CPU1_P1_TX_DN<11>")
	)
	(segment
		(start 107.232958 -291.441378)
		(end 107.24261 -291.448236)
		(width 0.1143)
		(layer "In4.Cu")
		(net "P5E_CPU1_P1_TX_DN<11>")
	)
	(segment
		(start 126.38024 -333.198978)
		(end 127.177038 -337.633564)
		(width 0.14224)
		(layer "In4.Cu")
		(net "P5E_CPU1_P1_TX_DN<11>")
	)
	(segment
		(start 127.192532 -337.809332)
		(end 127.192532 -346.93479)
		(width 0.14224)
		(layer "In4.Cu")
		(net "P5E_CPU1_P1_TX_DN<11>")
	)
	(segment
		(start 107.715304 -293.88054)
		(end 107.717336 -293.882064)
		(width 0.1143)
		(layer "In4.Cu")
		(net "P5E_CPU1_P1_TX_DN<11>")
	)
	(segment
		(start 126.474728 -349.243904)
		(end 125.87478 -350.115632)
		(width 0.14224)
		(layer "In4.Cu")
		(net "P5E_CPU1_P1_TX_DN<11>")
	)
	(segment
		(start 107.64266 -293.836344)
		(end 107.70235 -293.871142)
		(width 0.1143)
		(layer "In4.Cu")
		(net "P5E_CPU1_P1_TX_DN<11>")
	)
	(segment
		(start 107.296204 -296.612564)
		(end 107.296204 -298.346622)
		(width 0.14224)
		(layer "In4.Cu")
		(net "P5E_CPU1_P1_TX_DN<11>")
	)
	(segment
		(start 107.25658 -295.59504)
		(end 107.228894 -295.613582)
		(width 0.1143)
		(layer "In4.Cu")
		(net "P5E_CPU1_P1_TX_DN<11>")
	)
	(segment
		(start 107.17911 -295.646348)
		(end 107.17784 -295.64711)
		(width 0.1143)
		(layer "In4.Cu")
		(net "P5E_CPU1_P1_TX_DN<11>")
	)
	(segment
		(start 125.710442 -350.277684)
		(end 111.067088 -360.062272)
		(width 0.14224)
		(layer "In4.Cu")
		(net "P5E_CPU1_P1_TX_DN<11>")
	)
	(arc
		(start 107.24261 -291.448236)
		(mid 107.414475 -291.648)
		(end 107.47629 -291.904166)
		(width 0.1143)
		(layer "In4.Cu")
		(net "P5E_CPU1_P1_TX_DN<11>")
	)
	(arc
		(start 107.476544 -291.908738)
		(mid 107.521083 -292.076796)
		(end 107.632246 -292.21049)
		(width 0.1143)
		(layer "In4.Cu")
		(net "P5E_CPU1_P1_TX_DN<11>")
	)
	(arc
		(start 107.46359 -295.207182)
		(mid 107.408599 -295.427004)
		(end 107.25658 -295.59504)
		(width 0.1143)
		(layer "In4.Cu")
		(net "P5E_CPU1_P1_TX_DN<11>")
	)
	(arc
		(start 107.03433 -295.813988)
		(mid 107.015219 -296.0243)
		(end 107.115356 -296.210228)
		(width 0.1143)
		(layer "In4.Cu")
		(net "P5E_CPU1_P1_TX_DN<11>")
	)
	(arc
		(start 107.096814 -295.717976)
		(mid 107.060903 -295.762943)
		(end 107.03433 -295.813988)
		(width 0.1143)
		(layer "In4.Cu")
		(net "P5E_CPU1_P1_TX_DN<11>")
	)
	(arc
		(start 127.177038 -337.633564)
		(mid 127.188685 -337.721104)
		(end 127.192532 -337.809332)
		(width 0.14224)
		(layer "In4.Cu")
		(net "P5E_CPU1_P1_TX_DN<11>")
	)
	(arc
		(start 107.173014 -295.64584)
		(mid 107.166191 -295.650014)
		(end 107.159552 -295.654476)
		(width 0.1143)
		(layer "In4.Cu")
		(net "P5E_CPU1_P1_TX_DN<11>")
	)
	(arc
		(start 107.703112 -292.251638)
		(mid 107.946439 -292.716204)
		(end 107.703112 -293.18077)
		(width 0.1143)
		(layer "In4.Cu")
		(net "P5E_CPU1_P1_TX_DN<11>")
	)
	(arc
		(start 97.172272 -367.053368)
		(mid 96.702291 -367.75665)
		(end 96.537272 -368.586258)
		(width 0.14224)
		(layer "In4.Cu")
		(net "P5E_CPU1_P1_TX_DN<11>")
	)
	(arc
		(start 107.296204 -298.346622)
		(mid 107.29865 -298.371475)
		(end 107.305856 -298.39539)
		(width 0.14224)
		(layer "In4.Cu")
		(net "P5E_CPU1_P1_TX_DN<11>")
	)
	(arc
		(start 107.721146 -293.885112)
		(mid 107.946291 -294.346425)
		(end 107.703874 -294.799004)
		(width 0.1143)
		(layer "In4.Cu")
		(net "P5E_CPU1_P1_TX_DN<11>")
	)
	(arc
		(start 125.87478 -350.115632)
		(mid 125.800305 -350.20446)
		(end 125.710442 -350.277684)
		(width 0.14224)
		(layer "In4.Cu")
		(net "P5E_CPU1_P1_TX_DN<11>")
	)
	(arc
		(start 127.192532 -346.93479)
		(mid 127.008939 -348.143841)
		(end 126.474728 -349.243904)
		(width 0.14224)
		(layer "In4.Cu")
		(net "P5E_CPU1_P1_TX_DN<11>")
	)
	(arc
		(start 107.619546 -294.84955)
		(mid 107.50487 -294.982884)
		(end 107.46359 -295.153842)
		(width 0.1143)
		(layer "In4.Cu")
		(net "P5E_CPU1_P1_TX_DN<11>")
	)
	(arc
		(start 126.34849 -333.07655)
		(mid 126.366688 -333.137161)
		(end 126.38024 -333.198978)
		(width 0.14224)
		(layer "In4.Cu")
		(net "P5E_CPU1_P1_TX_DN<11>")
	)
	(arc
		(start 107.70235 -293.871142)
		(mid 107.702731 -293.871396)
		(end 107.703112 -293.87165)
		(width 0.1143)
		(layer "In4.Cu")
		(net "P5E_CPU1_P1_TX_DN<11>")
	)
	(arc
		(start 107.159552 -295.654476)
		(mid 107.128098 -295.686142)
		(end 107.096814 -295.717976)
		(width 0.1143)
		(layer "In4.Cu")
		(net "P5E_CPU1_P1_TX_DN<11>")
	)
	(arc
		(start 107.013248 -291.166042)
		(mid 107.065297 -291.297561)
		(end 107.162346 -291.400484)
		(width 0.1143)
		(layer "In4.Cu")
		(net "P5E_CPU1_P1_TX_DN<11>")
	)
	(arc
		(start 107.157266 -296.252138)
		(mid 107.226232 -296.355258)
		(end 107.250484 -296.476928)
		(width 0.1143)
		(layer "In4.Cu")
		(net "P5E_CPU1_P1_TX_DN<11>")
	)
	(arc
		(start 107.642406 -293.216076)
		(mid 107.463864 -293.5261)
		(end 107.642152 -293.836344)
		(width 0.1143)
		(layer "In4.Cu")
		(net "P5E_CPU1_P1_TX_DN<11>")
	)
	(segment
		(start 94.855792 -374.23344)
		(end 95.126302 -373.96293)
		(width 0.12954)
		(layer "F.Cu")
		(net "P5E_CPU1_P1_TX_DN<10>")
	)
	(segment
		(start 94.855792 -374.93702)
		(end 94.855792 -374.23344)
		(width 0.12954)
		(layer "F.Cu")
		(net "P5E_CPU1_P1_TX_DN<10>")
	)
	(segment
		(start 95.151702 -375.23293)
		(end 94.855792 -374.93702)
		(width 0.12954)
		(layer "F.Cu")
		(net "P5E_CPU1_P1_TX_DN<10>")
	)
	(segment
		(start 107.847892 -289.210242)
		(end 107.38104 -289.47618)
		(width 0.12954)
		(layer "F.Cu")
		(net "P5E_CPU1_P1_TX_DN<10>")
	)
	(segment
		(start 106.256582 -290.772088)
		(end 106.255058 -290.773104)
		(width 0.1143)
		(layer "In4.Cu")
		(net "P5E_CPU1_P1_TX_DN<10>")
	)
	(segment
		(start 106.53649 -295.146222)
		(end 106.536236 -295.145968)
		(width 0.1143)
		(layer "In4.Cu")
		(net "P5E_CPU1_P1_TX_DN<10>")
	)
	(segment
		(start 106.255058 -291.41928)
		(end 106.256582 -291.420296)
		(width 0.1143)
		(layer "In4.Cu")
		(net "P5E_CPU1_P1_TX_DN<10>")
	)
	(segment
		(start 110.22584 -359.401618)
		(end 98.72726 -364.164372)
		(width 0.14224)
		(layer "In4.Cu")
		(net "P5E_CPU1_P1_TX_DN<10>")
	)
	(segment
		(start 107.38104 -289.47618)
		(end 107.083098 -289.47618)
		(width 0.1143)
		(layer "In4.Cu")
		(net "P5E_CPU1_P1_TX_DN<10>")
	)
	(segment
		(start 106.198924 -296.07891)
		(end 106.198924 -296.107358)
		(width 0.1143)
		(layer "In4.Cu")
		(net "P5E_CPU1_P1_TX_DN<10>")
	)
	(segment
		(start 106.723942 -292.228778)
		(end 106.763058 -292.251638)
		(width 0.1143)
		(layer "In4.Cu")
		(net "P5E_CPU1_P1_TX_DN<10>")
	)
	(segment
		(start 106.723942 -293.20363)
		(end 106.693462 -293.22141)
		(width 0.1143)
		(layer "In4.Cu")
		(net "P5E_CPU1_P1_TX_DN<10>")
	)
	(segment
		(start 121.6533 -322.26377)
		(end 121.66346 -322.28409)
		(width 0.14224)
		(layer "In4.Cu")
		(net "P5E_CPU1_P1_TX_DN<10>")
	)
	(segment
		(start 125.451108 -333.374492)
		(end 126.233936 -337.7311)
		(width 0.14224)
		(layer "In4.Cu")
		(net "P5E_CPU1_P1_TX_DN<10>")
	)
	(segment
		(start 106.257598 -291.420804)
		(end 106.260138 -291.422328)
		(width 0.1143)
		(layer "In4.Cu")
		(net "P5E_CPU1_P1_TX_DN<10>")
	)
	(segment
		(start 121.66346 -322.28409)
		(end 125.408436 -333.210408)
		(width 0.14224)
		(layer "In4.Cu")
		(net "P5E_CPU1_P1_TX_DN<10>")
	)
	(segment
		(start 106.153204 -295.914826)
		(end 106.153204 -296.03319)
		(width 0.1143)
		(layer "In4.Cu")
		(net "P5E_CPU1_P1_TX_DN<10>")
	)
	(segment
		(start 106.723942 -289.963606)
		(end 106.693462 -289.981386)
		(width 0.1143)
		(layer "In4.Cu")
		(net "P5E_CPU1_P1_TX_DN<10>")
	)
	(segment
		(start 126.203456 -346.973144)
		(end 125.257306 -349.256858)
		(width 0.14224)
		(layer "In4.Cu")
		(net "P5E_CPU1_P1_TX_DN<10>")
	)
	(segment
		(start 98.72726 -364.164372)
		(end 96.364552 -365.743236)
		(width 0.14224)
		(layer "In4.Cu")
		(net "P5E_CPU1_P1_TX_DN<10>")
	)
	(segment
		(start 106.536236 -295.145968)
		(end 106.536236 -295.304972)
		(width 0.1143)
		(layer "In4.Cu")
		(net "P5E_CPU1_P1_TX_DN<10>")
	)
	(segment
		(start 106.763058 -294.800782)
		(end 106.693462 -294.841422)
		(width 0.1143)
		(layer "In4.Cu")
		(net "P5E_CPU1_P1_TX_DN<10>")
	)
	(segment
		(start 112.366552 -310.175148)
		(end 120.53824 -320.131186)
		(width 0.14224)
		(layer "In4.Cu")
		(net "P5E_CPU1_P1_TX_DN<10>")
	)
	(segment
		(start 106.261662 -291.423344)
		(end 106.293158 -291.441632)
		(width 0.1143)
		(layer "In4.Cu")
		(net "P5E_CPU1_P1_TX_DN<10>")
	)
	(segment
		(start 106.693462 -292.210998)
		(end 106.723942 -292.228778)
		(width 0.1143)
		(layer "In4.Cu")
		(net "P5E_CPU1_P1_TX_DN<10>")
	)
	(segment
		(start 106.256582 -291.420296)
		(end 106.257598 -291.420804)
		(width 0.1143)
		(layer "In4.Cu")
		(net "P5E_CPU1_P1_TX_DN<10>")
	)
	(segment
		(start 107.721146 -301.834804)
		(end 109.233208 -305.485292)
		(width 0.14224)
		(layer "In4.Cu")
		(net "P5E_CPU1_P1_TX_DN<10>")
	)
	(segment
		(start 106.208576 -298.183554)
		(end 107.720892 -301.83455)
		(width 0.14224)
		(layer "In4.Cu")
		(net "P5E_CPU1_P1_TX_DN<10>")
	)
	(segment
		(start 94.835472 -373.6721)
		(end 95.126302 -373.96293)
		(width 0.14224)
		(layer "In4.Cu")
		(net "P5E_CPU1_P1_TX_DN<10>")
	)
	(segment
		(start 106.763058 -289.940746)
		(end 106.723942 -289.963606)
		(width 0.1143)
		(layer "In4.Cu")
		(net "P5E_CPU1_P1_TX_DN<10>")
	)
	(segment
		(start 109.233208 -305.485292)
		(end 112.366552 -310.175148)
		(width 0.14224)
		(layer "In4.Cu")
		(net "P5E_CPU1_P1_TX_DN<10>")
	)
	(segment
		(start 106.255058 -290.773104)
		(end 106.254042 -290.773612)
		(width 0.1143)
		(layer "In4.Cu")
		(net "P5E_CPU1_P1_TX_DN<10>")
	)
	(segment
		(start 106.254042 -291.418772)
		(end 106.255058 -291.41928)
		(width 0.1143)
		(layer "In4.Cu")
		(net "P5E_CPU1_P1_TX_DN<10>")
	)
	(segment
		(start 107.720892 -301.83455)
		(end 107.721146 -301.834804)
		(width 0.14224)
		(layer "In4.Cu")
		(net "P5E_CPU1_P1_TX_DN<10>")
	)
	(segment
		(start 106.25328 -290.77412)
		(end 106.25201 -290.774882)
		(width 0.1143)
		(layer "In4.Cu")
		(net "P5E_CPU1_P1_TX_DN<10>")
	)
	(segment
		(start 94.835472 -368.604292)
		(end 94.835472 -373.6721)
		(width 0.14224)
		(layer "In4.Cu")
		(net "P5E_CPU1_P1_TX_DN<10>")
	)
	(segment
		(start 106.198924 -296.107358)
		(end 106.198924 -298.134786)
		(width 0.14224)
		(layer "In4.Cu")
		(net "P5E_CPU1_P1_TX_DN<10>")
	)
	(segment
		(start 125.074172 -349.47987)
		(end 110.22584 -359.401618)
		(width 0.14224)
		(layer "In4.Cu")
		(net "P5E_CPU1_P1_TX_DN<10>")
	)
	(segment
		(start 106.260138 -291.422328)
		(end 106.261662 -291.423344)
		(width 0.1143)
		(layer "In4.Cu")
		(net "P5E_CPU1_P1_TX_DN<10>")
	)
	(segment
		(start 106.293158 -290.750752)
		(end 106.256582 -290.772088)
		(width 0.1143)
		(layer "In4.Cu")
		(net "P5E_CPU1_P1_TX_DN<10>")
	)
	(segment
		(start 126.24943 -337.907122)
		(end 126.24943 -346.742004)
		(width 0.14224)
		(layer "In4.Cu")
		(net "P5E_CPU1_P1_TX_DN<10>")
	)
	(segment
		(start 106.222292 -291.400484)
		(end 106.25328 -291.418264)
		(width 0.1143)
		(layer "In4.Cu")
		(net "P5E_CPU1_P1_TX_DN<10>")
	)
	(segment
		(start 106.25201 -290.774882)
		(end 106.222292 -290.7919)
		(width 0.1143)
		(layer "In4.Cu")
		(net "P5E_CPU1_P1_TX_DN<10>")
	)
	(segment
		(start 107.083098 -289.47618)
		(end 107.000294 -289.558984)
		(width 0.1143)
		(layer "In4.Cu")
		(net "P5E_CPU1_P1_TX_DN<10>")
	)
	(segment
		(start 106.254042 -290.773612)
		(end 106.25328 -290.77412)
		(width 0.1143)
		(layer "In4.Cu")
		(net "P5E_CPU1_P1_TX_DN<10>")
	)
	(segment
		(start 106.693462 -293.83101)
		(end 106.723942 -293.84879)
		(width 0.1143)
		(layer "In4.Cu")
		(net "P5E_CPU1_P1_TX_DN<10>")
	)
	(segment
		(start 106.4133 -295.602406)
		(end 106.190542 -295.82491)
		(width 0.1143)
		(layer "In4.Cu")
		(net "P5E_CPU1_P1_TX_DN<10>")
	)
	(segment
		(start 106.763058 -293.18077)
		(end 106.723942 -293.20363)
		(width 0.1143)
		(layer "In4.Cu")
		(net "P5E_CPU1_P1_TX_DN<10>")
	)
	(segment
		(start 106.25328 -291.418264)
		(end 106.254042 -291.418772)
		(width 0.1143)
		(layer "In4.Cu")
		(net "P5E_CPU1_P1_TX_DN<10>")
	)
	(segment
		(start 106.723942 -293.84879)
		(end 106.763058 -293.87165)
		(width 0.1143)
		(layer "In4.Cu")
		(net "P5E_CPU1_P1_TX_DN<10>")
	)
	(segment
		(start 106.153204 -296.03319)
		(end 106.198924 -296.07891)
		(width 0.1143)
		(layer "In4.Cu")
		(net "P5E_CPU1_P1_TX_DN<10>")
	)
	(segment
		(start 120.53824 -320.131186)
		(end 121.6533 -322.26377)
		(width 0.14224)
		(layer "In4.Cu")
		(net "P5E_CPU1_P1_TX_DN<10>")
	)
	(arc
		(start 106.693462 -289.981386)
		(mid 106.578035 -290.114762)
		(end 106.53649 -290.286186)
		(width 0.1143)
		(layer "In4.Cu")
		(net "P5E_CPU1_P1_TX_DN<10>")
	)
	(arc
		(start 126.233936 -337.7311)
		(mid 126.245594 -337.818766)
		(end 126.24943 -337.907122)
		(width 0.14224)
		(layer "In4.Cu")
		(net "P5E_CPU1_P1_TX_DN<10>")
	)
	(arc
		(start 106.53649 -290.286186)
		(mid 106.471975 -290.548405)
		(end 106.293158 -290.750752)
		(width 0.1143)
		(layer "In4.Cu")
		(net "P5E_CPU1_P1_TX_DN<10>")
	)
	(arc
		(start 125.257306 -349.256858)
		(mid 125.18228 -349.381945)
		(end 125.074172 -349.47987)
		(width 0.14224)
		(layer "In4.Cu")
		(net "P5E_CPU1_P1_TX_DN<10>")
	)
	(arc
		(start 126.24943 -346.742004)
		(mid 126.237829 -346.85984)
		(end 126.203456 -346.973144)
		(width 0.14224)
		(layer "In4.Cu")
		(net "P5E_CPU1_P1_TX_DN<10>")
	)
	(arc
		(start 107.000294 -289.558984)
		(mid 106.998506 -289.570433)
		(end 106.996484 -289.581844)
		(width 0.1143)
		(layer "In4.Cu")
		(net "P5E_CPU1_P1_TX_DN<10>")
	)
	(arc
		(start 106.536236 -295.304972)
		(mid 106.504335 -295.465909)
		(end 106.4133 -295.602406)
		(width 0.1143)
		(layer "In4.Cu")
		(net "P5E_CPU1_P1_TX_DN<10>")
	)
	(arc
		(start 106.996484 -289.581844)
		(mid 106.915051 -289.784242)
		(end 106.763058 -289.940746)
		(width 0.1143)
		(layer "In4.Cu")
		(net "P5E_CPU1_P1_TX_DN<10>")
	)
	(arc
		(start 125.408436 -333.210408)
		(mid 125.432893 -333.291638)
		(end 125.451108 -333.374492)
		(width 0.14224)
		(layer "In4.Cu")
		(net "P5E_CPU1_P1_TX_DN<10>")
	)
	(arc
		(start 106.693462 -293.22141)
		(mid 106.536485 -293.52621)
		(end 106.693462 -293.83101)
		(width 0.1143)
		(layer "In4.Cu")
		(net "P5E_CPU1_P1_TX_DN<10>")
	)
	(arc
		(start 106.222292 -290.7919)
		(mid 106.066364 -291.096192)
		(end 106.222292 -291.400484)
		(width 0.1143)
		(layer "In4.Cu")
		(net "P5E_CPU1_P1_TX_DN<10>")
	)
	(arc
		(start 106.693462 -294.841422)
		(mid 106.578035 -294.974798)
		(end 106.53649 -295.146222)
		(width 0.1143)
		(layer "In4.Cu")
		(net "P5E_CPU1_P1_TX_DN<10>")
	)
	(arc
		(start 106.293158 -291.441632)
		(mid 106.471971 -291.643982)
		(end 106.53649 -291.906198)
		(width 0.1143)
		(layer "In4.Cu")
		(net "P5E_CPU1_P1_TX_DN<10>")
	)
	(arc
		(start 106.190542 -295.82491)
		(mid 106.162923 -295.86615)
		(end 106.153204 -295.914826)
		(width 0.1143)
		(layer "In4.Cu")
		(net "P5E_CPU1_P1_TX_DN<10>")
	)
	(arc
		(start 96.364552 -365.743236)
		(mid 95.241721 -366.982277)
		(end 94.835472 -368.604292)
		(width 0.14224)
		(layer "In4.Cu")
		(net "P5E_CPU1_P1_TX_DN<10>")
	)
	(arc
		(start 106.198924 -298.134786)
		(mid 106.20137 -298.159639)
		(end 106.208576 -298.183554)
		(width 0.14224)
		(layer "In4.Cu")
		(net "P5E_CPU1_P1_TX_DN<10>")
	)
	(arc
		(start 106.763058 -293.87165)
		(mid 107.006385 -294.336216)
		(end 106.763058 -294.800782)
		(width 0.1143)
		(layer "In4.Cu")
		(net "P5E_CPU1_P1_TX_DN<10>")
	)
	(arc
		(start 106.53649 -291.906198)
		(mid 106.578039 -292.07762)
		(end 106.693462 -292.210998)
		(width 0.1143)
		(layer "In4.Cu")
		(net "P5E_CPU1_P1_TX_DN<10>")
	)
	(arc
		(start 106.763058 -292.251638)
		(mid 107.006385 -292.716204)
		(end 106.763058 -293.18077)
		(width 0.1143)
		(layer "In4.Cu")
		(net "P5E_CPU1_P1_TX_DN<10>")
	)
	(segment
		(start 74.22896 -381.77597)
		(end 73.95845 -381.50546)
		(width 0.12954)
		(layer "F.Cu")
		(net "P5E_CPU1_P1_TX_DN<0>")
	)
	(segment
		(start 75.22845 -381.48006)
		(end 74.93254 -381.77597)
		(width 0.12954)
		(layer "F.Cu")
		(net "P5E_CPU1_P1_TX_DN<0>")
	)
	(segment
		(start 99.387914 -285.970472)
		(end 98.921062 -286.23641)
		(width 0.12954)
		(layer "F.Cu")
		(net "P5E_CPU1_P1_TX_DN<0>")
	)
	(segment
		(start 74.93254 -381.77597)
		(end 74.22896 -381.77597)
		(width 0.12954)
		(layer "F.Cu")
		(net "P5E_CPU1_P1_TX_DN<0>")
	)
	(segment
		(start 72.876918 -371.83314)
		(end 72.876918 -372.25986)
		(width 0.14224)
		(layer "In4.Cu")
		(net "P5E_CPU1_P1_TX_DN<0>")
	)
	(segment
		(start 112.59312 -325.344536)
		(end 116.186966 -335.843118)
		(width 0.14224)
		(layer "In4.Cu")
		(net "P5E_CPU1_P1_TX_DN<0>")
	)
	(segment
		(start 72.739758 -374.457722)
		(end 72.739758 -374.884442)
		(width 0.14224)
		(layer "In4.Cu")
		(net "P5E_CPU1_P1_TX_DN<0>")
	)
	(segment
		(start 96.85401 -290.773612)
		(end 96.82226 -290.7919)
		(width 0.1143)
		(layer "In4.Cu")
		(net "P5E_CPU1_P1_TX_DN<0>")
	)
	(segment
		(start 116.229384 -336.006948)
		(end 116.69268 -338.583016)
		(width 0.14224)
		(layer "In4.Cu")
		(net "P5E_CPU1_P1_TX_DN<0>")
	)
	(segment
		(start 96.666304 -296.16019)
		(end 96.712024 -296.20591)
		(width 0.1143)
		(layer "In4.Cu")
		(net "P5E_CPU1_P1_TX_DN<0>")
	)
	(segment
		(start 96.893126 -290.750752)
		(end 96.85401 -290.773612)
		(width 0.1143)
		(layer "In4.Cu")
		(net "P5E_CPU1_P1_TX_DN<0>")
	)
	(segment
		(start 96.712024 -296.20591)
		(end 96.712024 -296.234358)
		(width 0.1143)
		(layer "In4.Cu")
		(net "P5E_CPU1_P1_TX_DN<0>")
	)
	(segment
		(start 72.853804 -381.656336)
		(end 72.95642 -381.758952)
		(width 0.14224)
		(layer "In4.Cu")
		(net "P5E_CPU1_P1_TX_DN<0>")
	)
	(segment
		(start 72.876918 -373.893842)
		(end 72.876918 -374.320562)
		(width 0.14224)
		(layer "In4.Cu")
		(net "P5E_CPU1_P1_TX_DN<0>")
	)
	(segment
		(start 97.32391 -288.988754)
		(end 97.363026 -289.011614)
		(width 0.1143)
		(layer "In4.Cu")
		(net "P5E_CPU1_P1_TX_DN<0>")
	)
	(segment
		(start 115.350798 -343.555828)
		(end 102.658926 -352.035618)
		(width 0.14224)
		(layer "In4.Cu")
		(net "P5E_CPU1_P1_TX_DN<0>")
	)
	(segment
		(start 72.739758 -371.69598)
		(end 72.876918 -371.83314)
		(width 0.14224)
		(layer "In4.Cu")
		(net "P5E_CPU1_P1_TX_DN<0>")
	)
	(segment
		(start 72.739758 -375.585482)
		(end 72.739758 -377.960128)
		(width 0.14224)
		(layer "In4.Cu")
		(net "P5E_CPU1_P1_TX_DN<0>")
	)
	(segment
		(start 72.739758 -369.0366)
		(end 72.739758 -371.69598)
		(width 0.14224)
		(layer "In4.Cu")
		(net "P5E_CPU1_P1_TX_DN<0>")
	)
	(segment
		(start 97.29343 -292.210998)
		(end 97.363026 -292.251638)
		(width 0.1143)
		(layer "In4.Cu")
		(net "P5E_CPU1_P1_TX_DN<0>")
	)
	(segment
		(start 102.498652 -352.12147)
		(end 81.076038 -360.994198)
		(width 0.14224)
		(layer "In4.Cu")
		(net "P5E_CPU1_P1_TX_DN<0>")
	)
	(segment
		(start 104.609646 -315.576458)
		(end 108.06938 -319.792096)
		(width 0.14224)
		(layer "In4.Cu")
		(net "P5E_CPU1_P1_TX_DN<0>")
	)
	(segment
		(start 97.363026 -294.800782)
		(end 97.29343 -294.841422)
		(width 0.1143)
		(layer "In4.Cu")
		(net "P5E_CPU1_P1_TX_DN<0>")
	)
	(segment
		(start 96.712024 -299.644308)
		(end 101.1936 -310.463946)
		(width 0.14224)
		(layer "In4.Cu")
		(net "P5E_CPU1_P1_TX_DN<0>")
	)
	(segment
		(start 97.32391 -289.963606)
		(end 97.29343 -289.981386)
		(width 0.1143)
		(layer "In4.Cu")
		(net "P5E_CPU1_P1_TX_DN<0>")
	)
	(segment
		(start 73.66762 -381.79629)
		(end 73.95845 -381.50546)
		(width 0.14224)
		(layer "In4.Cu")
		(net "P5E_CPU1_P1_TX_DN<0>")
	)
	(segment
		(start 97.04324 -295.572434)
		(end 96.703642 -295.911778)
		(width 0.1143)
		(layer "In4.Cu")
		(net "P5E_CPU1_P1_TX_DN<0>")
	)
	(segment
		(start 97.136204 -295.145968)
		(end 97.136204 -295.34739)
		(width 0.1143)
		(layer "In4.Cu")
		(net "P5E_CPU1_P1_TX_DN<0>")
	)
	(segment
		(start 98.921062 -286.23641)
		(end 98.62312 -286.23641)
		(width 0.1143)
		(layer "In4.Cu")
		(net "P5E_CPU1_P1_TX_DN<0>")
	)
	(segment
		(start 96.712024 -296.234358)
		(end 96.712024 -299.644308)
		(width 0.14224)
		(layer "In4.Cu")
		(net "P5E_CPU1_P1_TX_DN<0>")
	)
	(segment
		(start 97.29343 -288.970974)
		(end 97.32391 -288.988754)
		(width 0.1143)
		(layer "In4.Cu")
		(net "P5E_CPU1_P1_TX_DN<0>")
	)
	(segment
		(start 98.30308 -286.700976)
		(end 98.263964 -286.723836)
		(width 0.1143)
		(layer "In4.Cu")
		(net "P5E_CPU1_P1_TX_DN<0>")
	)
	(segment
		(start 72.876918 -372.25986)
		(end 72.739758 -372.39702)
		(width 0.14224)
		(layer "In4.Cu")
		(net "P5E_CPU1_P1_TX_DN<0>")
	)
	(segment
		(start 97.32391 -293.84879)
		(end 97.363026 -293.87165)
		(width 0.1143)
		(layer "In4.Cu")
		(net "P5E_CPU1_P1_TX_DN<0>")
	)
	(segment
		(start 73.046336 -381.79629)
		(end 73.66762 -381.79629)
		(width 0.14224)
		(layer "In4.Cu")
		(net "P5E_CPU1_P1_TX_DN<0>")
	)
	(segment
		(start 79.985362 -361.723686)
		(end 79.985362 -361.72394)
		(width 0.14224)
		(layer "In4.Cu")
		(net "P5E_CPU1_P1_TX_DN<0>")
	)
	(segment
		(start 97.794064 -287.533842)
		(end 97.762314 -287.55213)
		(width 0.1143)
		(layer "In4.Cu")
		(net "P5E_CPU1_P1_TX_DN<0>")
	)
	(segment
		(start 72.876918 -375.448322)
		(end 72.739758 -375.585482)
		(width 0.14224)
		(layer "In4.Cu")
		(net "P5E_CPU1_P1_TX_DN<0>")
	)
	(segment
		(start 97.32391 -288.343848)
		(end 97.291398 -288.362644)
		(width 0.1143)
		(layer "In4.Cu")
		(net "P5E_CPU1_P1_TX_DN<0>")
	)
	(segment
		(start 96.666304 -296.001694)
		(end 96.666304 -296.16019)
		(width 0.1143)
		(layer "In4.Cu")
		(net "P5E_CPU1_P1_TX_DN<0>")
	)
	(segment
		(start 72.876918 -375.021602)
		(end 72.876918 -375.448322)
		(width 0.14224)
		(layer "In4.Cu")
		(net "P5E_CPU1_P1_TX_DN<0>")
	)
	(segment
		(start 97.136458 -295.146222)
		(end 97.136204 -295.145968)
		(width 0.1143)
		(layer "In4.Cu")
		(net "P5E_CPU1_P1_TX_DN<0>")
	)
	(segment
		(start 72.739758 -373.756682)
		(end 72.876918 -373.893842)
		(width 0.14224)
		(layer "In4.Cu")
		(net "P5E_CPU1_P1_TX_DN<0>")
	)
	(segment
		(start 72.739758 -372.39702)
		(end 72.739758 -373.756682)
		(width 0.14224)
		(layer "In4.Cu")
		(net "P5E_CPU1_P1_TX_DN<0>")
	)
	(segment
		(start 97.83064 -287.512506)
		(end 97.794064 -287.533842)
		(width 0.1143)
		(layer "In4.Cu")
		(net "P5E_CPU1_P1_TX_DN<0>")
	)
	(segment
		(start 96.82226 -291.400484)
		(end 96.893126 -291.441632)
		(width 0.1143)
		(layer "In4.Cu")
		(net "P5E_CPU1_P1_TX_DN<0>")
	)
	(segment
		(start 116.708174 -338.759038)
		(end 116.708174 -341.016336)
		(width 0.14224)
		(layer "In4.Cu")
		(net "P5E_CPU1_P1_TX_DN<0>")
	)
	(segment
		(start 72.739758 -378.661168)
		(end 72.739758 -381.381254)
		(width 0.14224)
		(layer "In4.Cu")
		(net "P5E_CPU1_P1_TX_DN<0>")
	)
	(segment
		(start 97.363026 -293.18077)
		(end 97.32391 -293.20363)
		(width 0.1143)
		(layer "In4.Cu")
		(net "P5E_CPU1_P1_TX_DN<0>")
	)
	(segment
		(start 98.62312 -286.23641)
		(end 98.540316 -286.319214)
		(width 0.1143)
		(layer "In4.Cu")
		(net "P5E_CPU1_P1_TX_DN<0>")
	)
	(segment
		(start 72.739758 -374.884442)
		(end 72.876918 -375.021602)
		(width 0.14224)
		(layer "In4.Cu")
		(net "P5E_CPU1_P1_TX_DN<0>")
	)
	(segment
		(start 97.32391 -293.20363)
		(end 97.29343 -293.22141)
		(width 0.1143)
		(layer "In4.Cu")
		(net "P5E_CPU1_P1_TX_DN<0>")
	)
	(segment
		(start 101.1936 -310.463946)
		(end 104.609646 -315.576458)
		(width 0.14224)
		(layer "In4.Cu")
		(net "P5E_CPU1_P1_TX_DN<0>")
	)
	(segment
		(start 98.263964 -286.723836)
		(end 98.231452 -286.742632)
		(width 0.1143)
		(layer "In4.Cu")
		(net "P5E_CPU1_P1_TX_DN<0>")
	)
	(segment
		(start 72.876918 -374.320562)
		(end 72.739758 -374.457722)
		(width 0.14224)
		(layer "In4.Cu")
		(net "P5E_CPU1_P1_TX_DN<0>")
	)
	(segment
		(start 79.985362 -361.72394)
		(end 72.787002 -368.922554)
		(width 0.14224)
		(layer "In4.Cu")
		(net "P5E_CPU1_P1_TX_DN<0>")
	)
	(segment
		(start 97.363026 -288.320988)
		(end 97.32391 -288.343848)
		(width 0.1143)
		(layer "In4.Cu")
		(net "P5E_CPU1_P1_TX_DN<0>")
	)
	(segment
		(start 108.06938 -319.791842)
		(end 112.522508 -325.217536)
		(width 0.14224)
		(layer "In4.Cu")
		(net "P5E_CPU1_P1_TX_DN<0>")
	)
	(segment
		(start 97.29343 -293.83101)
		(end 97.32391 -293.84879)
		(width 0.1143)
		(layer "In4.Cu")
		(net "P5E_CPU1_P1_TX_DN<0>")
	)
	(segment
		(start 108.06938 -319.792096)
		(end 108.06938 -319.791842)
		(width 0.14224)
		(layer "In4.Cu")
		(net "P5E_CPU1_P1_TX_DN<0>")
	)
	(segment
		(start 72.876918 -378.524008)
		(end 72.739758 -378.661168)
		(width 0.14224)
		(layer "In4.Cu")
		(net "P5E_CPU1_P1_TX_DN<0>")
	)
	(segment
		(start 97.363026 -289.940746)
		(end 97.32391 -289.963606)
		(width 0.1143)
		(layer "In4.Cu")
		(net "P5E_CPU1_P1_TX_DN<0>")
	)
	(segment
		(start 72.876918 -378.097288)
		(end 72.876918 -378.524008)
		(width 0.14224)
		(layer "In4.Cu")
		(net "P5E_CPU1_P1_TX_DN<0>")
	)
	(segment
		(start 72.739758 -377.960128)
		(end 72.876918 -378.097288)
		(width 0.14224)
		(layer "In4.Cu")
		(net "P5E_CPU1_P1_TX_DN<0>")
	)
	(arc
		(start 97.29343 -294.841422)
		(mid 97.177927 -294.974774)
		(end 97.136458 -295.146222)
		(width 0.1143)
		(layer "In4.Cu")
		(net "P5E_CPU1_P1_TX_DN<0>")
	)
	(arc
		(start 98.536506 -286.342074)
		(mid 98.455073 -286.544472)
		(end 98.30308 -286.700976)
		(width 0.1143)
		(layer "In4.Cu")
		(net "P5E_CPU1_P1_TX_DN<0>")
	)
	(arc
		(start 98.540316 -286.319214)
		(mid 98.538528 -286.330663)
		(end 98.536506 -286.342074)
		(width 0.1143)
		(layer "In4.Cu")
		(net "P5E_CPU1_P1_TX_DN<0>")
	)
	(arc
		(start 97.29343 -289.981386)
		(mid 97.178003 -290.114762)
		(end 97.136458 -290.286186)
		(width 0.1143)
		(layer "In4.Cu")
		(net "P5E_CPU1_P1_TX_DN<0>")
	)
	(arc
		(start 72.739758 -381.381254)
		(mid 72.769394 -381.530153)
		(end 72.853804 -381.656336)
		(width 0.14224)
		(layer "In4.Cu")
		(net "P5E_CPU1_P1_TX_DN<0>")
	)
	(arc
		(start 98.231452 -286.742632)
		(mid 98.117523 -286.875779)
		(end 98.076512 -287.046162)
		(width 0.1143)
		(layer "In4.Cu")
		(net "P5E_CPU1_P1_TX_DN<0>")
	)
	(arc
		(start 116.69268 -338.583016)
		(mid 116.704347 -338.670682)
		(end 116.708174 -338.759038)
		(width 0.14224)
		(layer "In4.Cu")
		(net "P5E_CPU1_P1_TX_DN<0>")
	)
	(arc
		(start 72.787002 -368.922554)
		(mid 72.75204 -368.974879)
		(end 72.739758 -369.0366)
		(width 0.14224)
		(layer "In4.Cu")
		(net "P5E_CPU1_P1_TX_DN<0>")
	)
	(arc
		(start 116.186966 -335.843118)
		(mid 116.203491 -335.895323)
		(end 116.217446 -335.948274)
		(width 0.14224)
		(layer "In4.Cu")
		(net "P5E_CPU1_P1_TX_DN<0>")
	)
	(arc
		(start 97.363026 -293.87165)
		(mid 97.606353 -294.336216)
		(end 97.363026 -294.800782)
		(width 0.1143)
		(layer "In4.Cu")
		(net "P5E_CPU1_P1_TX_DN<0>")
	)
	(arc
		(start 97.136458 -290.286186)
		(mid 97.071943 -290.548405)
		(end 96.893126 -290.750752)
		(width 0.1143)
		(layer "In4.Cu")
		(net "P5E_CPU1_P1_TX_DN<0>")
	)
	(arc
		(start 112.522508 -325.217536)
		(mid 112.563486 -325.27788)
		(end 112.59312 -325.344536)
		(width 0.14224)
		(layer "In4.Cu")
		(net "P5E_CPU1_P1_TX_DN<0>")
	)
	(arc
		(start 97.131886 -291.866574)
		(mid 97.134901 -291.891908)
		(end 97.136458 -291.917374)
		(width 0.1143)
		(layer "In4.Cu")
		(net "P5E_CPU1_P1_TX_DN<0>")
	)
	(arc
		(start 72.95642 -381.758952)
		(mid 72.99766 -381.786571)
		(end 73.046336 -381.79629)
		(width 0.14224)
		(layer "In4.Cu")
		(net "P5E_CPU1_P1_TX_DN<0>")
	)
	(arc
		(start 97.291398 -288.362644)
		(mid 97.177469 -288.495791)
		(end 97.136458 -288.666174)
		(width 0.1143)
		(layer "In4.Cu")
		(net "P5E_CPU1_P1_TX_DN<0>")
	)
	(arc
		(start 97.363026 -292.251638)
		(mid 97.606353 -292.716204)
		(end 97.363026 -293.18077)
		(width 0.1143)
		(layer "In4.Cu")
		(net "P5E_CPU1_P1_TX_DN<0>")
	)
	(arc
		(start 97.136204 -295.34739)
		(mid 97.112095 -295.469154)
		(end 97.04324 -295.572434)
		(width 0.1143)
		(layer "In4.Cu")
		(net "P5E_CPU1_P1_TX_DN<0>")
	)
	(arc
		(start 97.29343 -293.22141)
		(mid 97.136453 -293.52621)
		(end 97.29343 -293.83101)
		(width 0.1143)
		(layer "In4.Cu")
		(net "P5E_CPU1_P1_TX_DN<0>")
	)
	(arc
		(start 102.658926 -352.035618)
		(mid 102.580898 -352.082481)
		(end 102.498652 -352.12147)
		(width 0.14224)
		(layer "In4.Cu")
		(net "P5E_CPU1_P1_TX_DN<0>")
	)
	(arc
		(start 116.217446 -335.948274)
		(mid 116.223809 -335.977531)
		(end 116.229384 -336.006948)
		(width 0.14224)
		(layer "In4.Cu")
		(net "P5E_CPU1_P1_TX_DN<0>")
	)
	(arc
		(start 116.708174 -341.016336)
		(mid 116.347548 -342.456095)
		(end 115.350798 -343.555828)
		(width 0.14224)
		(layer "In4.Cu")
		(net "P5E_CPU1_P1_TX_DN<0>")
	)
	(arc
		(start 96.82226 -290.7919)
		(mid 96.666332 -291.096192)
		(end 96.82226 -291.400484)
		(width 0.1143)
		(layer "In4.Cu")
		(net "P5E_CPU1_P1_TX_DN<0>")
	)
	(arc
		(start 97.363026 -289.011614)
		(mid 97.606353 -289.47618)
		(end 97.363026 -289.940746)
		(width 0.1143)
		(layer "In4.Cu")
		(net "P5E_CPU1_P1_TX_DN<0>")
	)
	(arc
		(start 97.606358 -287.856422)
		(mid 97.541843 -288.118641)
		(end 97.363026 -288.320988)
		(width 0.1143)
		(layer "In4.Cu")
		(net "P5E_CPU1_P1_TX_DN<0>")
	)
	(arc
		(start 96.703642 -295.911778)
		(mid 96.676023 -295.953018)
		(end 96.666304 -296.001694)
		(width 0.1143)
		(layer "In4.Cu")
		(net "P5E_CPU1_P1_TX_DN<0>")
	)
	(arc
		(start 96.893126 -291.441632)
		(mid 97.051232 -291.632354)
		(end 97.131886 -291.866574)
		(width 0.1143)
		(layer "In4.Cu")
		(net "P5E_CPU1_P1_TX_DN<0>")
	)
	(arc
		(start 97.136458 -291.917374)
		(mid 97.180543 -292.082572)
		(end 97.29343 -292.210998)
		(width 0.1143)
		(layer "In4.Cu")
		(net "P5E_CPU1_P1_TX_DN<0>")
	)
	(arc
		(start 97.136458 -288.666174)
		(mid 97.178007 -288.837596)
		(end 97.29343 -288.970974)
		(width 0.1143)
		(layer "In4.Cu")
		(net "P5E_CPU1_P1_TX_DN<0>")
	)
	(arc
		(start 97.762314 -287.55213)
		(mid 97.647638 -287.685464)
		(end 97.606358 -287.856422)
		(width 0.1143)
		(layer "In4.Cu")
		(net "P5E_CPU1_P1_TX_DN<0>")
	)
	(arc
		(start 98.076512 -287.046162)
		(mid 98.011276 -287.309753)
		(end 97.83064 -287.512506)
		(width 0.1143)
		(layer "In4.Cu")
		(net "P5E_CPU1_P1_TX_DN<0>")
	)
	(arc
		(start 81.076038 -360.994198)
		(mid 80.494686 -361.305092)
		(end 79.985362 -361.723686)
		(width 0.14224)
		(layer "In4.Cu")
		(net "P5E_CPU1_P1_TX_DN<0>")
	)
	(segment
		(start 90.998294 -386.003292)
		(end 91.518994 -386.003292)
		(width 0.127)
		(layer "F.Cu")
		(net "P5E_CPU1_P1_RX_DP<9>")
	)
	(segment
		(start 107.847892 -276.2504)
		(end 107.38104 -276.516338)
		(width 0.12954)
		(layer "F.Cu")
		(net "P5E_CPU1_P1_RX_DP<9>")
	)
	(segment
		(start 105.823004 -282.53182)
		(end 105.753408 -282.49118)
		(width 0.1143)
		(layer "In11.Cu")
		(net "P5E_CPU1_P1_RX_DP<9>")
	)
	(segment
		(start 105.814876 -285.767018)
		(end 105.814114 -285.76651)
		(width 0.1143)
		(layer "In11.Cu")
		(net "P5E_CPU1_P1_RX_DP<9>")
	)
	(segment
		(start 105.285032 -280.058876)
		(end 105.283508 -280.061162)
		(width 0.1143)
		(layer "In11.Cu")
		(net "P5E_CPU1_P1_RX_DP<9>")
	)
	(segment
		(start 106.246168 -277.818342)
		(end 106.247438 -277.81758)
		(width 0.1143)
		(layer "In11.Cu")
		(net "P5E_CPU1_P1_RX_DP<9>")
	)
	(segment
		(start 107.000294 -276.599142)
		(end 107.083098 -276.516338)
		(width 0.1143)
		(layer "In11.Cu")
		(net "P5E_CPU1_P1_RX_DP<9>")
	)
	(segment
		(start 106.2482 -277.817072)
		(end 106.249724 -277.81631)
		(width 0.1143)
		(layer "In11.Cu")
		(net "P5E_CPU1_P1_RX_DP<9>")
	)
	(segment
		(start 125.599444 -342.112854)
		(end 125.599444 -339.54339)
		(width 0.14224)
		(layer "In11.Cu")
		(net "P5E_CPU1_P1_RX_DP<9>")
	)
	(segment
		(start 105.814114 -285.76651)
		(end 105.783888 -285.748984)
		(width 0.1143)
		(layer "In11.Cu")
		(net "P5E_CPU1_P1_RX_DP<9>")
	)
	(segment
		(start 107.083098 -276.516338)
		(end 107.38104 -276.516338)
		(width 0.1143)
		(layer "In11.Cu")
		(net "P5E_CPU1_P1_RX_DP<9>")
	)
	(segment
		(start 105.390696 -280.127964)
		(end 105.348786 -280.099516)
		(width 0.1143)
		(layer "In11.Cu")
		(net "P5E_CPU1_P1_RX_DP<9>")
	)
	(segment
		(start 91.563444 -384.3528)
		(end 91.868244 -384.048)
		(width 0.14224)
		(layer "In11.Cu")
		(net "P5E_CPU1_P1_RX_DP<9>")
	)
	(segment
		(start 105.823004 -289.011614)
		(end 105.753408 -288.970974)
		(width 0.1143)
		(layer "In11.Cu")
		(net "P5E_CPU1_P1_RX_DP<9>")
	)
	(segment
		(start 125.599444 -339.54339)
		(end 123.411488 -327.369678)
		(width 0.14224)
		(layer "In11.Cu")
		(net "P5E_CPU1_P1_RX_DP<9>")
	)
	(segment
		(start 105.823004 -293.87165)
		(end 105.753408 -293.83101)
		(width 0.1143)
		(layer "In11.Cu")
		(net "P5E_CPU1_P1_RX_DP<9>")
	)
	(segment
		(start 91.560396 -384.731006)
		(end 91.563444 -384.3528)
		(width 0.14224)
		(layer "In11.Cu")
		(net "P5E_CPU1_P1_RX_DP<9>")
	)
	(segment
		(start 106.256582 -277.812246)
		(end 106.293158 -277.79091)
		(width 0.1143)
		(layer "In11.Cu")
		(net "P5E_CPU1_P1_RX_DP<9>")
	)
	(segment
		(start 105.751376 -288.362644)
		(end 105.783888 -288.343848)
		(width 0.1143)
		(layer "In11.Cu")
		(net "P5E_CPU1_P1_RX_DP<9>")
	)
	(segment
		(start 105.753408 -294.841422)
		(end 105.823004 -294.800782)
		(width 0.1143)
		(layer "In11.Cu")
		(net "P5E_CPU1_P1_RX_DP<9>")
	)
	(segment
		(start 91.61399 -385.649216)
		(end 91.788234 -385.548632)
		(width 0.14224)
		(layer "In11.Cu")
		(net "P5E_CPU1_P1_RX_DP<9>")
	)
	(segment
		(start 105.753408 -278.641556)
		(end 105.823004 -278.600916)
		(width 0.1143)
		(layer "In11.Cu")
		(net "P5E_CPU1_P1_RX_DP<9>")
	)
	(segment
		(start 105.823004 -284.151832)
		(end 105.753408 -284.111192)
		(width 0.1143)
		(layer "In11.Cu")
		(net "P5E_CPU1_P1_RX_DP<9>")
	)
	(segment
		(start 105.753408 -285.121604)
		(end 105.823004 -285.080964)
		(width 0.1143)
		(layer "In11.Cu")
		(net "P5E_CPU1_P1_RX_DP<9>")
	)
	(segment
		(start 105.823004 -290.631626)
		(end 105.753408 -290.590986)
		(width 0.1143)
		(layer "In11.Cu")
		(net "P5E_CPU1_P1_RX_DP<9>")
	)
	(segment
		(start 108.392722 -305.892708)
		(end 105.25379 -298.314618)
		(width 0.14224)
		(layer "In11.Cu")
		(net "P5E_CPU1_P1_RX_DP<9>")
	)
	(segment
		(start 105.596436 -280.566368)
		(end 105.596436 -280.520648)
		(width 0.1143)
		(layer "In11.Cu")
		(net "P5E_CPU1_P1_RX_DP<9>")
	)
	(segment
		(start 105.783888 -285.748984)
		(end 105.753408 -285.731204)
		(width 0.1143)
		(layer "In11.Cu")
		(net "P5E_CPU1_P1_RX_DP<9>")
	)
	(segment
		(start 106.222292 -277.832058)
		(end 106.244644 -277.819104)
		(width 0.1143)
		(layer "In11.Cu")
		(net "P5E_CPU1_P1_RX_DP<9>")
	)
	(segment
		(start 102.19055 -362.559854)
		(end 122.1994 -349.157798)
		(width 0.14224)
		(layer "In11.Cu")
		(net "P5E_CPU1_P1_RX_DP<9>")
	)
	(segment
		(start 106.249724 -277.81631)
		(end 106.250486 -277.815802)
		(width 0.1143)
		(layer "In11.Cu")
		(net "P5E_CPU1_P1_RX_DP<9>")
	)
	(segment
		(start 105.820464 -287.390078)
		(end 105.753408 -287.350962)
		(width 0.1143)
		(layer "In11.Cu")
		(net "P5E_CPU1_P1_RX_DP<9>")
	)
	(segment
		(start 105.25379 -296.371264)
		(end 105.25379 -296.342816)
		(width 0.1143)
		(layer "In11.Cu")
		(net "P5E_CPU1_P1_RX_DP<9>")
	)
	(segment
		(start 105.596436 -295.242742)
		(end 105.596436 -295.146222)
		(width 0.1143)
		(layer "In11.Cu")
		(net "P5E_CPU1_P1_RX_DP<9>")
	)
	(segment
		(start 91.788234 -385.548632)
		(end 91.876372 -385.460494)
		(width 0.14224)
		(layer "In11.Cu")
		(net "P5E_CPU1_P1_RX_DP<9>")
	)
	(segment
		(start 105.283508 -279.451562)
		(end 105.313226 -279.43429)
		(width 0.1143)
		(layer "In11.Cu")
		(net "P5E_CPU1_P1_RX_DP<9>")
	)
	(segment
		(start 105.316528 -279.432258)
		(end 105.353104 -279.410922)
		(width 0.1143)
		(layer "In11.Cu")
		(net "P5E_CPU1_P1_RX_DP<9>")
	)
	(segment
		(start 105.823004 -292.251638)
		(end 105.753408 -292.210998)
		(width 0.1143)
		(layer "In11.Cu")
		(net "P5E_CPU1_P1_RX_DP<9>")
	)
	(segment
		(start 105.313226 -279.43429)
		(end 105.313988 -279.433782)
		(width 0.1143)
		(layer "In11.Cu")
		(net "P5E_CPU1_P1_RX_DP<9>")
	)
	(segment
		(start 92.101924 -373.168926)
		(end 96.375728 -367.274094)
		(width 0.14224)
		(layer "In11.Cu")
		(net "P5E_CPU1_P1_RX_DP<9>")
	)
	(segment
		(start 105.753408 -289.981386)
		(end 105.823004 -289.940746)
		(width 0.1143)
		(layer "In11.Cu")
		(net "P5E_CPU1_P1_RX_DP<9>")
	)
	(segment
		(start 105.751376 -286.742632)
		(end 105.783888 -286.723836)
		(width 0.1143)
		(layer "In11.Cu")
		(net "P5E_CPU1_P1_RX_DP<9>")
	)
	(segment
		(start 105.313988 -279.433782)
		(end 105.315004 -279.433274)
		(width 0.1143)
		(layer "In11.Cu")
		(net "P5E_CPU1_P1_RX_DP<9>")
	)
	(segment
		(start 105.315004 -279.433274)
		(end 105.316528 -279.432258)
		(width 0.1143)
		(layer "In11.Cu")
		(net "P5E_CPU1_P1_RX_DP<9>")
	)
	(segment
		(start 123.411488 -327.369678)
		(end 121.174002 -323.089016)
		(width 0.14224)
		(layer "In11.Cu")
		(net "P5E_CPU1_P1_RX_DP<9>")
	)
	(segment
		(start 121.174002 -323.089016)
		(end 114.227102 -314.624466)
		(width 0.14224)
		(layer "In11.Cu")
		(net "P5E_CPU1_P1_RX_DP<9>")
	)
	(segment
		(start 106.25328 -277.814278)
		(end 106.254042 -277.81377)
		(width 0.1143)
		(layer "In11.Cu")
		(net "P5E_CPU1_P1_RX_DP<9>")
	)
	(segment
		(start 91.876372 -385.046982)
		(end 91.560396 -384.731006)
		(width 0.14224)
		(layer "In11.Cu")
		(net "P5E_CPU1_P1_RX_DP<9>")
	)
	(segment
		(start 91.518994 -386.003292)
		(end 91.61399 -385.649216)
		(width 0.14224)
		(layer "In11.Cu")
		(net "P5E_CPU1_P1_RX_DP<9>")
	)
	(segment
		(start 105.20807 -296.297096)
		(end 105.20807 -295.956736)
		(width 0.1143)
		(layer "In11.Cu")
		(net "P5E_CPU1_P1_RX_DP<9>")
	)
	(segment
		(start 105.348532 -280.09977)
		(end 105.285032 -280.058876)
		(width 0.1143)
		(layer "In11.Cu")
		(net "P5E_CPU1_P1_RX_DP<9>")
	)
	(segment
		(start 91.868244 -382.4351)
		(end 92.00134 -373.47144)
		(width 0.14224)
		(layer "In11.Cu")
		(net "P5E_CPU1_P1_RX_DP<9>")
	)
	(segment
		(start 105.348786 -280.099516)
		(end 105.348532 -280.09977)
		(width 0.1143)
		(layer "In11.Cu")
		(net "P5E_CPU1_P1_RX_DP<9>")
	)
	(segment
		(start 106.247438 -277.81758)
		(end 106.2482 -277.817072)
		(width 0.1143)
		(layer "In11.Cu")
		(net "P5E_CPU1_P1_RX_DP<9>")
	)
	(segment
		(start 105.823004 -285.771844)
		(end 105.814876 -285.767018)
		(width 0.1143)
		(layer "In11.Cu")
		(net "P5E_CPU1_P1_RX_DP<9>")
	)
	(segment
		(start 106.250486 -277.815802)
		(end 106.25328 -277.814278)
		(width 0.1143)
		(layer "In11.Cu")
		(net "P5E_CPU1_P1_RX_DP<9>")
	)
	(segment
		(start 96.486472 -367.157508)
		(end 102.18166 -362.566458)
		(width 0.14224)
		(layer "In11.Cu")
		(net "P5E_CPU1_P1_RX_DP<9>")
	)
	(segment
		(start 105.823004 -280.911808)
		(end 105.753408 -280.871168)
		(width 0.1143)
		(layer "In11.Cu")
		(net "P5E_CPU1_P1_RX_DP<9>")
	)
	(segment
		(start 114.227102 -314.624466)
		(end 108.392722 -305.892708)
		(width 0.14224)
		(layer "In11.Cu")
		(net "P5E_CPU1_P1_RX_DP<9>")
	)
	(segment
		(start 105.25379 -298.314618)
		(end 105.25379 -296.371264)
		(width 0.14224)
		(layer "In11.Cu")
		(net "P5E_CPU1_P1_RX_DP<9>")
	)
	(segment
		(start 106.254042 -277.81377)
		(end 106.255058 -277.813262)
		(width 0.1143)
		(layer "In11.Cu")
		(net "P5E_CPU1_P1_RX_DP<9>")
	)
	(segment
		(start 106.693462 -277.021544)
		(end 106.763058 -276.980904)
		(width 0.1143)
		(layer "In11.Cu")
		(net "P5E_CPU1_P1_RX_DP<9>")
	)
	(segment
		(start 105.25379 -296.342816)
		(end 105.20807 -296.297096)
		(width 0.1143)
		(layer "In11.Cu")
		(net "P5E_CPU1_P1_RX_DP<9>")
	)
	(segment
		(start 123.515628 -347.513402)
		(end 125.599444 -342.112854)
		(width 0.14224)
		(layer "In11.Cu")
		(net "P5E_CPU1_P1_RX_DP<9>")
	)
	(segment
		(start 91.868244 -384.048)
		(end 91.868244 -382.4351)
		(width 0.14224)
		(layer "In11.Cu")
		(net "P5E_CPU1_P1_RX_DP<9>")
	)
	(segment
		(start 105.783888 -288.343848)
		(end 105.823004 -288.320988)
		(width 0.1143)
		(layer "In11.Cu")
		(net "P5E_CPU1_P1_RX_DP<9>")
	)
	(segment
		(start 105.783888 -286.723836)
		(end 105.823004 -286.700976)
		(width 0.1143)
		(layer "In11.Cu")
		(net "P5E_CPU1_P1_RX_DP<9>")
	)
	(segment
		(start 105.753408 -281.88158)
		(end 105.823004 -281.84094)
		(width 0.1143)
		(layer "In11.Cu")
		(net "P5E_CPU1_P1_RX_DP<9>")
	)
	(segment
		(start 106.255058 -277.813262)
		(end 106.256582 -277.812246)
		(width 0.1143)
		(layer "In11.Cu")
		(net "P5E_CPU1_P1_RX_DP<9>")
	)
	(segment
		(start 105.753408 -291.601398)
		(end 105.823004 -291.560758)
		(width 0.1143)
		(layer "In11.Cu")
		(net "P5E_CPU1_P1_RX_DP<9>")
	)
	(segment
		(start 105.325164 -295.674034)
		(end 105.483406 -295.515792)
		(width 0.1143)
		(layer "In11.Cu")
		(net "P5E_CPU1_P1_RX_DP<9>")
	)
	(segment
		(start 91.876372 -385.460494)
		(end 91.876372 -385.046982)
		(width 0.14224)
		(layer "In11.Cu")
		(net "P5E_CPU1_P1_RX_DP<9>")
	)
	(segment
		(start 105.753408 -283.501592)
		(end 105.823004 -283.460952)
		(width 0.1143)
		(layer "In11.Cu")
		(net "P5E_CPU1_P1_RX_DP<9>")
	)
	(segment
		(start 106.244644 -277.819104)
		(end 106.246168 -277.818342)
		(width 0.1143)
		(layer "In11.Cu")
		(net "P5E_CPU1_P1_RX_DP<9>")
	)
	(segment
		(start 105.753408 -293.22141)
		(end 105.823004 -293.18077)
		(width 0.1143)
		(layer "In11.Cu")
		(net "P5E_CPU1_P1_RX_DP<9>")
	)
	(arc
		(start 105.353104 -279.410922)
		(mid 105.531917 -279.208572)
		(end 105.596436 -278.946356)
		(width 0.1143)
		(layer "In11.Cu")
		(net "P5E_CPU1_P1_RX_DP<9>")
	)
	(arc
		(start 105.753408 -292.210998)
		(mid 105.596431 -291.906198)
		(end 105.753408 -291.601398)
		(width 0.1143)
		(layer "In11.Cu")
		(net "P5E_CPU1_P1_RX_DP<9>")
	)
	(arc
		(start 105.823004 -278.600916)
		(mid 106.001817 -278.398566)
		(end 106.066336 -278.13635)
		(width 0.1143)
		(layer "In11.Cu")
		(net "P5E_CPU1_P1_RX_DP<9>")
	)
	(arc
		(start 105.823004 -285.080964)
		(mid 106.066331 -284.616398)
		(end 105.823004 -284.151832)
		(width 0.1143)
		(layer "In11.Cu")
		(net "P5E_CPU1_P1_RX_DP<9>")
	)
	(arc
		(start 106.066336 -278.13635)
		(mid 106.107591 -277.965379)
		(end 106.222292 -277.832058)
		(width 0.1143)
		(layer "In11.Cu")
		(net "P5E_CPU1_P1_RX_DP<9>")
	)
	(arc
		(start 105.823004 -286.700976)
		(mid 106.066331 -286.23641)
		(end 105.823004 -285.771844)
		(width 0.1143)
		(layer "In11.Cu")
		(net "P5E_CPU1_P1_RX_DP<9>")
	)
	(arc
		(start 105.753408 -293.83101)
		(mid 105.596431 -293.52621)
		(end 105.753408 -293.22141)
		(width 0.1143)
		(layer "In11.Cu")
		(net "P5E_CPU1_P1_RX_DP<9>")
	)
	(arc
		(start 92.00134 -373.47144)
		(mid 92.028313 -373.312434)
		(end 92.101924 -373.168926)
		(width 0.14224)
		(layer "In11.Cu")
		(net "P5E_CPU1_P1_RX_DP<9>")
	)
	(arc
		(start 105.753408 -280.871168)
		(mid 105.637981 -280.737792)
		(end 105.596436 -280.566368)
		(width 0.1143)
		(layer "In11.Cu")
		(net "P5E_CPU1_P1_RX_DP<9>")
	)
	(arc
		(start 105.753408 -288.970974)
		(mid 105.637981 -288.837598)
		(end 105.596436 -288.666174)
		(width 0.1143)
		(layer "In11.Cu")
		(net "P5E_CPU1_P1_RX_DP<9>")
	)
	(arc
		(start 105.753408 -284.111192)
		(mid 105.596431 -283.806392)
		(end 105.753408 -283.501592)
		(width 0.1143)
		(layer "In11.Cu")
		(net "P5E_CPU1_P1_RX_DP<9>")
	)
	(arc
		(start 105.596436 -280.520648)
		(mid 105.541878 -280.298999)
		(end 105.390696 -280.127964)
		(width 0.1143)
		(layer "In11.Cu")
		(net "P5E_CPU1_P1_RX_DP<9>")
	)
	(arc
		(start 105.753408 -290.590986)
		(mid 105.596431 -290.286186)
		(end 105.753408 -289.981386)
		(width 0.1143)
		(layer "In11.Cu")
		(net "P5E_CPU1_P1_RX_DP<9>")
	)
	(arc
		(start 105.753408 -282.49118)
		(mid 105.596431 -282.18638)
		(end 105.753408 -281.88158)
		(width 0.1143)
		(layer "In11.Cu")
		(net "P5E_CPU1_P1_RX_DP<9>")
	)
	(arc
		(start 102.18166 -362.566458)
		(mid 102.18603 -362.563055)
		(end 102.19055 -362.559854)
		(width 0.14224)
		(layer "In11.Cu")
		(net "P5E_CPU1_P1_RX_DP<9>")
	)
	(arc
		(start 105.596436 -287.046162)
		(mid 105.637402 -286.875756)
		(end 105.751376 -286.742632)
		(width 0.1143)
		(layer "In11.Cu")
		(net "P5E_CPU1_P1_RX_DP<9>")
	)
	(arc
		(start 105.823004 -291.560758)
		(mid 106.066331 -291.096192)
		(end 105.823004 -290.631626)
		(width 0.1143)
		(layer "In11.Cu")
		(net "P5E_CPU1_P1_RX_DP<9>")
	)
	(arc
		(start 105.20807 -295.956736)
		(mid 105.238503 -295.803741)
		(end 105.325164 -295.674034)
		(width 0.1143)
		(layer "In11.Cu")
		(net "P5E_CPU1_P1_RX_DP<9>")
	)
	(arc
		(start 105.753408 -285.731204)
		(mid 105.596431 -285.426404)
		(end 105.753408 -285.121604)
		(width 0.1143)
		(layer "In11.Cu")
		(net "P5E_CPU1_P1_RX_DP<9>")
	)
	(arc
		(start 106.763058 -276.980904)
		(mid 106.915045 -276.824396)
		(end 106.996484 -276.622002)
		(width 0.1143)
		(layer "In11.Cu")
		(net "P5E_CPU1_P1_RX_DP<9>")
	)
	(arc
		(start 105.283508 -280.061162)
		(mid 105.138244 -279.756362)
		(end 105.283508 -279.451562)
		(width 0.1143)
		(layer "In11.Cu")
		(net "P5E_CPU1_P1_RX_DP<9>")
	)
	(arc
		(start 105.823004 -293.18077)
		(mid 106.066331 -292.716204)
		(end 105.823004 -292.251638)
		(width 0.1143)
		(layer "In11.Cu")
		(net "P5E_CPU1_P1_RX_DP<9>")
	)
	(arc
		(start 105.823004 -288.320988)
		(mid 106.001817 -288.118638)
		(end 106.066336 -287.856422)
		(width 0.1143)
		(layer "In11.Cu")
		(net "P5E_CPU1_P1_RX_DP<9>")
	)
	(arc
		(start 105.823004 -294.800782)
		(mid 106.066331 -294.336216)
		(end 105.823004 -293.87165)
		(width 0.1143)
		(layer "In11.Cu")
		(net "P5E_CPU1_P1_RX_DP<9>")
	)
	(arc
		(start 106.066336 -287.856422)
		(mid 106.0011 -287.592831)
		(end 105.820464 -287.390078)
		(width 0.1143)
		(layer "In11.Cu")
		(net "P5E_CPU1_P1_RX_DP<9>")
	)
	(arc
		(start 105.823004 -283.460952)
		(mid 106.066331 -282.996386)
		(end 105.823004 -282.53182)
		(width 0.1143)
		(layer "In11.Cu")
		(net "P5E_CPU1_P1_RX_DP<9>")
	)
	(arc
		(start 105.823004 -281.84094)
		(mid 106.066331 -281.376374)
		(end 105.823004 -280.911808)
		(width 0.1143)
		(layer "In11.Cu")
		(net "P5E_CPU1_P1_RX_DP<9>")
	)
	(arc
		(start 122.1994 -349.157798)
		(mid 122.984591 -348.437322)
		(end 123.515628 -347.513402)
		(width 0.14224)
		(layer "In11.Cu")
		(net "P5E_CPU1_P1_RX_DP<9>")
	)
	(arc
		(start 106.293158 -277.79091)
		(mid 106.471971 -277.58856)
		(end 106.53649 -277.326344)
		(width 0.1143)
		(layer "In11.Cu")
		(net "P5E_CPU1_P1_RX_DP<9>")
	)
	(arc
		(start 105.596436 -288.666174)
		(mid 105.637402 -288.495768)
		(end 105.751376 -288.362644)
		(width 0.1143)
		(layer "In11.Cu")
		(net "P5E_CPU1_P1_RX_DP<9>")
	)
	(arc
		(start 105.596436 -295.146222)
		(mid 105.637985 -294.9748)
		(end 105.753408 -294.841422)
		(width 0.1143)
		(layer "In11.Cu")
		(net "P5E_CPU1_P1_RX_DP<9>")
	)
	(arc
		(start 96.375728 -367.274094)
		(mid 96.427229 -367.212123)
		(end 96.486472 -367.157508)
		(width 0.14224)
		(layer "In11.Cu")
		(net "P5E_CPU1_P1_RX_DP<9>")
	)
	(arc
		(start 105.483406 -295.515792)
		(mid 105.567059 -295.390501)
		(end 105.596436 -295.242742)
		(width 0.1143)
		(layer "In11.Cu")
		(net "P5E_CPU1_P1_RX_DP<9>")
	)
	(arc
		(start 105.753408 -287.350962)
		(mid 105.637981 -287.217586)
		(end 105.596436 -287.046162)
		(width 0.1143)
		(layer "In11.Cu")
		(net "P5E_CPU1_P1_RX_DP<9>")
	)
	(arc
		(start 106.53649 -277.326344)
		(mid 106.578039 -277.154922)
		(end 106.693462 -277.021544)
		(width 0.1143)
		(layer "In11.Cu")
		(net "P5E_CPU1_P1_RX_DP<9>")
	)
	(arc
		(start 105.596436 -278.946356)
		(mid 105.637985 -278.774934)
		(end 105.753408 -278.641556)
		(width 0.1143)
		(layer "In11.Cu")
		(net "P5E_CPU1_P1_RX_DP<9>")
	)
	(arc
		(start 106.996484 -276.622002)
		(mid 106.998507 -276.610592)
		(end 107.000294 -276.599142)
		(width 0.1143)
		(layer "In11.Cu")
		(net "P5E_CPU1_P1_RX_DP<9>")
	)
	(arc
		(start 105.823004 -289.940746)
		(mid 106.066331 -289.47618)
		(end 105.823004 -289.011614)
		(width 0.1143)
		(layer "In11.Cu")
		(net "P5E_CPU1_P1_RX_DP<9>")
	)
	(segment
		(start 105.027984 -274.630388)
		(end 104.561132 -274.896326)
		(width 0.12954)
		(layer "F.Cu")
		(net "P5E_CPU1_P1_RX_DP<8>")
	)
	(segment
		(start 89.798398 -386.003292)
		(end 90.319098 -386.003292)
		(width 0.127)
		(layer "F.Cu")
		(net "P5E_CPU1_P1_RX_DP<8>")
	)
	(segment
		(start 104.844088 -290.608766)
		(end 104.843326 -290.608258)
		(width 0.1143)
		(layer "In11.Cu")
		(net "P5E_CPU1_P1_RX_DP<8>")
	)
	(segment
		(start 90.676476 -385.046982)
		(end 90.3605 -384.731006)
		(width 0.14224)
		(layer "In11.Cu")
		(net "P5E_CPU1_P1_RX_DP<8>")
	)
	(segment
		(start 104.572562 -295.563036)
		(end 104.656382 -295.360598)
		(width 0.1143)
		(layer "In11.Cu")
		(net "P5E_CPU1_P1_RX_DP<8>")
	)
	(segment
		(start 104.836214 -289.968178)
		(end 104.837484 -289.967416)
		(width 0.1143)
		(layer "In11.Cu")
		(net "P5E_CPU1_P1_RX_DP<8>")
	)
	(segment
		(start 104.88041 -285.770066)
		(end 104.812338 -285.730696)
		(width 0.1143)
		(layer "In11.Cu")
		(net "P5E_CPU1_P1_RX_DP<8>")
	)
	(segment
		(start 104.88041 -280.91003)
		(end 104.812338 -280.87066)
		(width 0.1143)
		(layer "In11.Cu")
		(net "P5E_CPU1_P1_RX_DP<8>")
	)
	(segment
		(start 104.88041 -276.049994)
		(end 104.812338 -276.010624)
		(width 0.1143)
		(layer "In11.Cu")
		(net "P5E_CPU1_P1_RX_DP<8>")
	)
	(segment
		(start 104.83977 -289.966146)
		(end 104.840532 -289.965638)
		(width 0.1143)
		(layer "In11.Cu")
		(net "P5E_CPU1_P1_RX_DP<8>")
	)
	(segment
		(start 104.833928 -293.209472)
		(end 104.83469 -293.208964)
		(width 0.1143)
		(layer "In11.Cu")
		(net "P5E_CPU1_P1_RX_DP<8>")
	)
	(segment
		(start 104.844088 -289.963606)
		(end 104.88041 -289.942524)
		(width 0.1143)
		(layer "In11.Cu")
		(net "P5E_CPU1_P1_RX_DP<8>")
	)
	(segment
		(start 104.844596 -287.369504)
		(end 104.844342 -287.368996)
		(width 0.1143)
		(layer "In11.Cu")
		(net "P5E_CPU1_P1_RX_DP<8>")
	)
	(segment
		(start 104.262936 -296.297096)
		(end 104.262936 -296.081196)
		(width 0.1143)
		(layer "In11.Cu")
		(net "P5E_CPU1_P1_RX_DP<8>")
	)
	(segment
		(start 104.844088 -291.583618)
		(end 104.88041 -291.562536)
		(width 0.1143)
		(layer "In11.Cu")
		(net "P5E_CPU1_P1_RX_DP<8>")
	)
	(segment
		(start 124.48286 -342.078564)
		(end 124.48286 -338.675472)
		(width 0.14224)
		(layer "In11.Cu")
		(net "P5E_CPU1_P1_RX_DP<8>")
	)
	(segment
		(start 104.81056 -288.363406)
		(end 104.88041 -288.322766)
		(width 0.1143)
		(layer "In11.Cu")
		(net "P5E_CPU1_P1_RX_DP<8>")
	)
	(segment
		(start 104.840532 -291.58565)
		(end 104.843326 -291.584126)
		(width 0.1143)
		(layer "In11.Cu")
		(net "P5E_CPU1_P1_RX_DP<8>")
	)
	(segment
		(start 104.812338 -277.022052)
		(end 104.88041 -276.982682)
		(width 0.1143)
		(layer "In11.Cu")
		(net "P5E_CPU1_P1_RX_DP<8>")
	)
	(segment
		(start 122.499628 -327.637902)
		(end 120.391936 -323.605906)
		(width 0.14224)
		(layer "In11.Cu")
		(net "P5E_CPU1_P1_RX_DP<8>")
	)
	(segment
		(start 104.656128 -287.046162)
		(end 104.656128 -286.992314)
		(width 0.1143)
		(layer "In11.Cu")
		(net "P5E_CPU1_P1_RX_DP<8>")
	)
	(segment
		(start 104.883204 -294.801036)
		(end 104.892602 -294.794178)
		(width 0.1143)
		(layer "In11.Cu")
		(net "P5E_CPU1_P1_RX_DP<8>")
	)
	(segment
		(start 104.840532 -287.36671)
		(end 104.812338 -287.350454)
		(width 0.1143)
		(layer "In11.Cu")
		(net "P5E_CPU1_P1_RX_DP<8>")
	)
	(segment
		(start 104.836214 -293.208202)
		(end 104.837484 -293.20744)
		(width 0.1143)
		(layer "In11.Cu")
		(net "P5E_CPU1_P1_RX_DP<8>")
	)
	(segment
		(start 104.83977 -291.586158)
		(end 104.840532 -291.58565)
		(width 0.1143)
		(layer "In11.Cu")
		(net "P5E_CPU1_P1_RX_DP<8>")
	)
	(segment
		(start 104.19334 -274.966176)
		(end 104.26319 -274.896326)
		(width 0.1143)
		(layer "In11.Cu")
		(net "P5E_CPU1_P1_RX_DP<8>")
	)
	(segment
		(start 104.840532 -289.965638)
		(end 104.843326 -289.964114)
		(width 0.1143)
		(layer "In11.Cu")
		(net "P5E_CPU1_P1_RX_DP<8>")
	)
	(segment
		(start 104.26319 -274.896326)
		(end 104.561132 -274.896326)
		(width 0.1143)
		(layer "In11.Cu")
		(net "P5E_CPU1_P1_RX_DP<8>")
	)
	(segment
		(start 104.833928 -289.969448)
		(end 104.83469 -289.96894)
		(width 0.1143)
		(layer "In11.Cu")
		(net "P5E_CPU1_P1_RX_DP<8>")
	)
	(segment
		(start 104.838246 -291.58692)
		(end 104.83977 -291.586158)
		(width 0.1143)
		(layer "In11.Cu")
		(net "P5E_CPU1_P1_RX_DP<8>")
	)
	(segment
		(start 104.83469 -291.588952)
		(end 104.836214 -291.58819)
		(width 0.1143)
		(layer "In11.Cu")
		(net "P5E_CPU1_P1_RX_DP<8>")
	)
	(segment
		(start 104.88041 -292.24986)
		(end 104.844088 -292.228778)
		(width 0.1143)
		(layer "In11.Cu")
		(net "P5E_CPU1_P1_RX_DP<8>")
	)
	(segment
		(start 104.812338 -281.882088)
		(end 104.88041 -281.842718)
		(width 0.1143)
		(layer "In11.Cu")
		(net "P5E_CPU1_P1_RX_DP<8>")
	)
	(segment
		(start 104.812338 -291.601906)
		(end 104.833928 -291.58946)
		(width 0.1143)
		(layer "In11.Cu")
		(net "P5E_CPU1_P1_RX_DP<8>")
	)
	(segment
		(start 90.668348 -384.048254)
		(end 90.668348 -382.077976)
		(width 0.14224)
		(layer "In11.Cu")
		(net "P5E_CPU1_P1_RX_DP<8>")
	)
	(segment
		(start 104.837484 -289.967416)
		(end 104.838246 -289.966908)
		(width 0.1143)
		(layer "In11.Cu")
		(net "P5E_CPU1_P1_RX_DP<8>")
	)
	(segment
		(start 104.812338 -293.221918)
		(end 104.833928 -293.209472)
		(width 0.1143)
		(layer "In11.Cu")
		(net "P5E_CPU1_P1_RX_DP<8>")
	)
	(segment
		(start 104.843326 -292.22827)
		(end 104.842056 -292.227508)
		(width 0.1143)
		(layer "In11.Cu")
		(net "P5E_CPU1_P1_RX_DP<8>")
	)
	(segment
		(start 120.391936 -323.605906)
		(end 113.478564 -315.18225)
		(width 0.14224)
		(layer "In11.Cu")
		(net "P5E_CPU1_P1_RX_DP<8>")
	)
	(segment
		(start 104.843326 -288.988246)
		(end 104.842056 -288.987484)
		(width 0.1143)
		(layer "In11.Cu")
		(net "P5E_CPU1_P1_RX_DP<8>")
	)
	(segment
		(start 90.3605 -384.731006)
		(end 90.363548 -384.3528)
		(width 0.14224)
		(layer "In11.Cu")
		(net "P5E_CPU1_P1_RX_DP<8>")
	)
	(segment
		(start 104.88041 -277.670006)
		(end 104.812338 -277.630636)
		(width 0.1143)
		(layer "In11.Cu")
		(net "P5E_CPU1_P1_RX_DP<8>")
	)
	(segment
		(start 113.478564 -315.18225)
		(end 107.56646 -306.334414)
		(width 0.14224)
		(layer "In11.Cu")
		(net "P5E_CPU1_P1_RX_DP<8>")
	)
	(segment
		(start 104.843326 -290.608258)
		(end 104.842056 -290.607496)
		(width 0.1143)
		(layer "In11.Cu")
		(net "P5E_CPU1_P1_RX_DP<8>")
	)
	(segment
		(start 104.844088 -292.228778)
		(end 104.843326 -292.22827)
		(width 0.1143)
		(layer "In11.Cu")
		(net "P5E_CPU1_P1_RX_DP<8>")
	)
	(segment
		(start 104.83469 -289.96894)
		(end 104.836214 -289.968178)
		(width 0.1143)
		(layer "In11.Cu")
		(net "P5E_CPU1_P1_RX_DP<8>")
	)
	(segment
		(start 104.343454 -279.451562)
		(end 104.41305 -279.410922)
		(width 0.1143)
		(layer "In11.Cu")
		(net "P5E_CPU1_P1_RX_DP<8>")
	)
	(segment
		(start 104.41305 -280.101802)
		(end 104.343454 -280.061162)
		(width 0.1143)
		(layer "In11.Cu")
		(net "P5E_CPU1_P1_RX_DP<8>")
	)
	(segment
		(start 122.545348 -346.756228)
		(end 124.48286 -342.078564)
		(width 0.14224)
		(layer "In11.Cu")
		(net "P5E_CPU1_P1_RX_DP<8>")
	)
	(segment
		(start 104.41305 -275.241766)
		(end 104.343454 -275.201126)
		(width 0.1143)
		(layer "In11.Cu")
		(net "P5E_CPU1_P1_RX_DP<8>")
	)
	(segment
		(start 104.892602 -293.878254)
		(end 104.883204 -293.871396)
		(width 0.1143)
		(layer "In11.Cu")
		(net "P5E_CPU1_P1_RX_DP<8>")
	)
	(segment
		(start 104.840532 -293.205662)
		(end 104.843326 -293.204138)
		(width 0.1143)
		(layer "In11.Cu")
		(net "P5E_CPU1_P1_RX_DP<8>")
	)
	(segment
		(start 104.844088 -288.988754)
		(end 104.843326 -288.988246)
		(width 0.1143)
		(layer "In11.Cu")
		(net "P5E_CPU1_P1_RX_DP<8>")
	)
	(segment
		(start 104.88041 -282.530042)
		(end 104.812338 -282.490672)
		(width 0.1143)
		(layer "In11.Cu")
		(net "P5E_CPU1_P1_RX_DP<8>")
	)
	(segment
		(start 90.676476 -385.460494)
		(end 90.676476 -385.046982)
		(width 0.14224)
		(layer "In11.Cu")
		(net "P5E_CPU1_P1_RX_DP<8>")
	)
	(segment
		(start 104.812084 -286.742378)
		(end 104.88041 -286.702754)
		(width 0.1143)
		(layer "In11.Cu")
		(net "P5E_CPU1_P1_RX_DP<8>")
	)
	(segment
		(start 95.646748 -366.520984)
		(end 101.06914 -362.148882)
		(width 0.14224)
		(layer "In11.Cu")
		(net "P5E_CPU1_P1_RX_DP<8>")
	)
	(segment
		(start 107.56646 -306.334414)
		(end 104.308656 -298.469304)
		(width 0.14224)
		(layer "In11.Cu")
		(net "P5E_CPU1_P1_RX_DP<8>")
	)
	(segment
		(start 104.838246 -293.206932)
		(end 104.83977 -293.20617)
		(width 0.1143)
		(layer "In11.Cu")
		(net "P5E_CPU1_P1_RX_DP<8>")
	)
	(segment
		(start 104.88041 -290.629848)
		(end 104.844088 -290.608766)
		(width 0.1143)
		(layer "In11.Cu")
		(net "P5E_CPU1_P1_RX_DP<8>")
	)
	(segment
		(start 104.843326 -287.368488)
		(end 104.840532 -287.36671)
		(width 0.1143)
		(layer "In11.Cu")
		(net "P5E_CPU1_P1_RX_DP<8>")
	)
	(segment
		(start 104.837484 -291.587428)
		(end 104.838246 -291.58692)
		(width 0.1143)
		(layer "In11.Cu")
		(net "P5E_CPU1_P1_RX_DP<8>")
	)
	(segment
		(start 104.812338 -283.5021)
		(end 104.88041 -283.46273)
		(width 0.1143)
		(layer "In11.Cu")
		(net "P5E_CPU1_P1_RX_DP<8>")
	)
	(segment
		(start 104.656382 -295.360598)
		(end 104.656382 -295.146222)
		(width 0.1143)
		(layer "In11.Cu")
		(net "P5E_CPU1_P1_RX_DP<8>")
	)
	(segment
		(start 104.41051 -295.725088)
		(end 104.572562 -295.563036)
		(width 0.1143)
		(layer "In11.Cu")
		(net "P5E_CPU1_P1_RX_DP<8>")
	)
	(segment
		(start 104.843326 -289.964114)
		(end 104.844088 -289.963606)
		(width 0.1143)
		(layer "In11.Cu")
		(net "P5E_CPU1_P1_RX_DP<8>")
	)
	(segment
		(start 104.765094 -286.776414)
		(end 104.812084 -286.742378)
		(width 0.1143)
		(layer "In11.Cu")
		(net "P5E_CPU1_P1_RX_DP<8>")
	)
	(segment
		(start 104.88041 -284.150054)
		(end 104.812338 -284.110684)
		(width 0.1143)
		(layer "In11.Cu")
		(net "P5E_CPU1_P1_RX_DP<8>")
	)
	(segment
		(start 104.88041 -289.009836)
		(end 104.844088 -288.988754)
		(width 0.1143)
		(layer "In11.Cu")
		(net "P5E_CPU1_P1_RX_DP<8>")
	)
	(segment
		(start 104.844342 -287.368996)
		(end 104.843326 -287.368488)
		(width 0.1143)
		(layer "In11.Cu")
		(net "P5E_CPU1_P1_RX_DP<8>")
	)
	(segment
		(start 104.883204 -293.871396)
		(end 104.812338 -293.830502)
		(width 0.1143)
		(layer "In11.Cu")
		(net "P5E_CPU1_P1_RX_DP<8>")
	)
	(segment
		(start 90.414094 -385.649216)
		(end 90.588338 -385.548632)
		(width 0.14224)
		(layer "In11.Cu")
		(net "P5E_CPU1_P1_RX_DP<8>")
	)
	(segment
		(start 90.668348 -382.077976)
		(end 91.076526 -373.008144)
		(width 0.14224)
		(layer "In11.Cu")
		(net "P5E_CPU1_P1_RX_DP<8>")
	)
	(segment
		(start 104.833928 -291.58946)
		(end 104.83469 -291.588952)
		(width 0.1143)
		(layer "In11.Cu")
		(net "P5E_CPU1_P1_RX_DP<8>")
	)
	(segment
		(start 104.844088 -293.20363)
		(end 104.88041 -293.182548)
		(width 0.1143)
		(layer "In11.Cu")
		(net "P5E_CPU1_P1_RX_DP<8>")
	)
	(segment
		(start 101.741478 -361.654598)
		(end 120.732804 -348.964758)
		(width 0.14224)
		(layer "In11.Cu")
		(net "P5E_CPU1_P1_RX_DP<8>")
	)
	(segment
		(start 104.843326 -293.204138)
		(end 104.844088 -293.20363)
		(width 0.1143)
		(layer "In11.Cu")
		(net "P5E_CPU1_P1_RX_DP<8>")
	)
	(segment
		(start 104.812338 -285.122112)
		(end 104.88041 -285.082742)
		(width 0.1143)
		(layer "In11.Cu")
		(net "P5E_CPU1_P1_RX_DP<8>")
	)
	(segment
		(start 104.837484 -293.20744)
		(end 104.838246 -293.206932)
		(width 0.1143)
		(layer "In11.Cu")
		(net "P5E_CPU1_P1_RX_DP<8>")
	)
	(segment
		(start 104.83469 -293.208964)
		(end 104.836214 -293.208202)
		(width 0.1143)
		(layer "In11.Cu")
		(net "P5E_CPU1_P1_RX_DP<8>")
	)
	(segment
		(start 90.363548 -384.3528)
		(end 90.668348 -384.048254)
		(width 0.14224)
		(layer "In11.Cu")
		(net "P5E_CPU1_P1_RX_DP<8>")
	)
	(segment
		(start 104.843326 -291.584126)
		(end 104.844088 -291.583618)
		(width 0.1143)
		(layer "In11.Cu")
		(net "P5E_CPU1_P1_RX_DP<8>")
	)
	(segment
		(start 104.308656 -296.371264)
		(end 104.308656 -296.342816)
		(width 0.1143)
		(layer "In11.Cu")
		(net "P5E_CPU1_P1_RX_DP<8>")
	)
	(segment
		(start 90.319098 -386.003292)
		(end 90.414094 -385.649216)
		(width 0.14224)
		(layer "In11.Cu")
		(net "P5E_CPU1_P1_RX_DP<8>")
	)
	(segment
		(start 124.48286 -338.675472)
		(end 122.499628 -327.637902)
		(width 0.14224)
		(layer "In11.Cu")
		(net "P5E_CPU1_P1_RX_DP<8>")
	)
	(segment
		(start 104.838246 -289.966908)
		(end 104.83977 -289.966146)
		(width 0.1143)
		(layer "In11.Cu")
		(net "P5E_CPU1_P1_RX_DP<8>")
	)
	(segment
		(start 104.836214 -291.58819)
		(end 104.837484 -291.587428)
		(width 0.1143)
		(layer "In11.Cu")
		(net "P5E_CPU1_P1_RX_DP<8>")
	)
	(segment
		(start 104.812338 -294.842184)
		(end 104.883204 -294.801036)
		(width 0.1143)
		(layer "In11.Cu")
		(net "P5E_CPU1_P1_RX_DP<8>")
	)
	(segment
		(start 104.842056 -290.607496)
		(end 104.812338 -290.590478)
		(width 0.1143)
		(layer "In11.Cu")
		(net "P5E_CPU1_P1_RX_DP<8>")
	)
	(segment
		(start 104.812338 -278.642064)
		(end 104.88041 -278.602694)
		(width 0.1143)
		(layer "In11.Cu")
		(net "P5E_CPU1_P1_RX_DP<8>")
	)
	(segment
		(start 104.842056 -288.987484)
		(end 104.812338 -288.970466)
		(width 0.1143)
		(layer "In11.Cu")
		(net "P5E_CPU1_P1_RX_DP<8>")
	)
	(segment
		(start 104.308656 -296.342816)
		(end 104.262936 -296.297096)
		(width 0.1143)
		(layer "In11.Cu")
		(net "P5E_CPU1_P1_RX_DP<8>")
	)
	(segment
		(start 90.588338 -385.548632)
		(end 90.676476 -385.460494)
		(width 0.14224)
		(layer "In11.Cu")
		(net "P5E_CPU1_P1_RX_DP<8>")
	)
	(segment
		(start 104.812338 -289.981894)
		(end 104.833928 -289.969448)
		(width 0.1143)
		(layer "In11.Cu")
		(net "P5E_CPU1_P1_RX_DP<8>")
	)
	(segment
		(start 104.83977 -293.20617)
		(end 104.840532 -293.205662)
		(width 0.1143)
		(layer "In11.Cu")
		(net "P5E_CPU1_P1_RX_DP<8>")
	)
	(segment
		(start 91.184476 -372.698518)
		(end 95.573088 -366.598962)
		(width 0.14224)
		(layer "In11.Cu")
		(net "P5E_CPU1_P1_RX_DP<8>")
	)
	(segment
		(start 104.842056 -292.227508)
		(end 104.812338 -292.21049)
		(width 0.1143)
		(layer "In11.Cu")
		(net "P5E_CPU1_P1_RX_DP<8>")
	)
	(segment
		(start 104.308656 -298.469304)
		(end 104.308656 -296.371264)
		(width 0.14224)
		(layer "In11.Cu")
		(net "P5E_CPU1_P1_RX_DP<8>")
	)
	(arc
		(start 104.894634 -282.539948)
		(mid 104.88756 -282.534941)
		(end 104.88041 -282.530042)
		(width 0.1143)
		(layer "In11.Cu")
		(net "P5E_CPU1_P1_RX_DP<8>")
	)
	(arc
		(start 104.343454 -275.201126)
		(mid 104.245689 -275.09815)
		(end 104.19334 -274.966176)
		(width 0.1143)
		(layer "In11.Cu")
		(net "P5E_CPU1_P1_RX_DP<8>")
	)
	(arc
		(start 104.812338 -285.730696)
		(mid 104.65641 -285.426404)
		(end 104.812338 -285.122112)
		(width 0.1143)
		(layer "In11.Cu")
		(net "P5E_CPU1_P1_RX_DP<8>")
	)
	(arc
		(start 105.126282 -286.229806)
		(mid 105.06141 -285.980064)
		(end 104.896666 -285.781496)
		(width 0.1143)
		(layer "In11.Cu")
		(net "P5E_CPU1_P1_RX_DP<8>")
	)
	(arc
		(start 104.894634 -276.0599)
		(mid 104.88756 -276.054893)
		(end 104.88041 -276.049994)
		(width 0.1143)
		(layer "In11.Cu")
		(net "P5E_CPU1_P1_RX_DP<8>")
	)
	(arc
		(start 104.812338 -276.010624)
		(mid 104.697662 -275.87729)
		(end 104.656382 -275.706332)
		(width 0.1143)
		(layer "In11.Cu")
		(net "P5E_CPU1_P1_RX_DP<8>")
	)
	(arc
		(start 104.812338 -280.87066)
		(mid 104.697662 -280.737326)
		(end 104.656382 -280.566368)
		(width 0.1143)
		(layer "In11.Cu")
		(net "P5E_CPU1_P1_RX_DP<8>")
	)
	(arc
		(start 104.88041 -283.46273)
		(mid 104.887559 -283.45783)
		(end 104.894634 -283.452824)
		(width 0.1143)
		(layer "In11.Cu")
		(net "P5E_CPU1_P1_RX_DP<8>")
	)
	(arc
		(start 104.88041 -281.842718)
		(mid 104.887559 -281.837818)
		(end 104.894634 -281.832812)
		(width 0.1143)
		(layer "In11.Cu")
		(net "P5E_CPU1_P1_RX_DP<8>")
	)
	(arc
		(start 104.812338 -277.630636)
		(mid 104.65641 -277.326344)
		(end 104.812338 -277.022052)
		(width 0.1143)
		(layer "In11.Cu")
		(net "P5E_CPU1_P1_RX_DP<8>")
	)
	(arc
		(start 95.573088 -366.598962)
		(mid 95.607303 -366.557504)
		(end 95.646748 -366.520984)
		(width 0.14224)
		(layer "In11.Cu")
		(net "P5E_CPU1_P1_RX_DP<8>")
	)
	(arc
		(start 104.88041 -291.562536)
		(mid 104.88756 -291.557638)
		(end 104.894634 -291.55263)
		(width 0.1143)
		(layer "In11.Cu")
		(net "P5E_CPU1_P1_RX_DP<8>")
	)
	(arc
		(start 104.41305 -279.410922)
		(mid 104.591863 -279.208572)
		(end 104.656382 -278.946356)
		(width 0.1143)
		(layer "In11.Cu")
		(net "P5E_CPU1_P1_RX_DP<8>")
	)
	(arc
		(start 104.894634 -277.679912)
		(mid 104.88756 -277.674905)
		(end 104.88041 -277.670006)
		(width 0.1143)
		(layer "In11.Cu")
		(net "P5E_CPU1_P1_RX_DP<8>")
	)
	(arc
		(start 104.894634 -283.452824)
		(mid 105.122017 -282.996386)
		(end 104.894634 -282.539948)
		(width 0.1143)
		(layer "In11.Cu")
		(net "P5E_CPU1_P1_RX_DP<8>")
	)
	(arc
		(start 104.894634 -291.55263)
		(mid 105.122017 -291.096192)
		(end 104.894634 -290.639754)
		(width 0.1143)
		(layer "In11.Cu")
		(net "P5E_CPU1_P1_RX_DP<8>")
	)
	(arc
		(start 91.076526 -373.008144)
		(mid 91.107925 -372.845456)
		(end 91.184476 -372.698518)
		(width 0.14224)
		(layer "In11.Cu")
		(net "P5E_CPU1_P1_RX_DP<8>")
	)
	(arc
		(start 104.812338 -284.110684)
		(mid 104.65641 -283.806392)
		(end 104.812338 -283.5021)
		(width 0.1143)
		(layer "In11.Cu")
		(net "P5E_CPU1_P1_RX_DP<8>")
	)
	(arc
		(start 104.89565 -284.160722)
		(mid 104.888074 -284.155326)
		(end 104.88041 -284.150054)
		(width 0.1143)
		(layer "In11.Cu")
		(net "P5E_CPU1_P1_RX_DP<8>")
	)
	(arc
		(start 104.656382 -295.146222)
		(mid 104.673253 -295.035021)
		(end 104.722422 -294.933878)
		(width 0.1143)
		(layer "In11.Cu")
		(net "P5E_CPU1_P1_RX_DP<8>")
	)
	(arc
		(start 104.894634 -292.259766)
		(mid 104.887561 -292.254757)
		(end 104.88041 -292.24986)
		(width 0.1143)
		(layer "In11.Cu")
		(net "P5E_CPU1_P1_RX_DP<8>")
	)
	(arc
		(start 104.88041 -276.982682)
		(mid 104.887559 -276.977782)
		(end 104.894634 -276.972776)
		(width 0.1143)
		(layer "In11.Cu")
		(net "P5E_CPU1_P1_RX_DP<8>")
	)
	(arc
		(start 105.126282 -287.856422)
		(mid 105.05078 -287.57517)
		(end 104.844596 -287.369504)
		(width 0.1143)
		(layer "In11.Cu")
		(net "P5E_CPU1_P1_RX_DP<8>")
	)
	(arc
		(start 104.894634 -290.639754)
		(mid 104.887561 -290.634745)
		(end 104.88041 -290.629848)
		(width 0.1143)
		(layer "In11.Cu")
		(net "P5E_CPU1_P1_RX_DP<8>")
	)
	(arc
		(start 104.812338 -282.490672)
		(mid 104.65641 -282.18638)
		(end 104.812338 -281.882088)
		(width 0.1143)
		(layer "In11.Cu")
		(net "P5E_CPU1_P1_RX_DP<8>")
	)
	(arc
		(start 104.812338 -288.970466)
		(mid 104.697662 -288.837132)
		(end 104.656382 -288.666174)
		(width 0.1143)
		(layer "In11.Cu")
		(net "P5E_CPU1_P1_RX_DP<8>")
	)
	(arc
		(start 104.656382 -275.706332)
		(mid 104.591867 -275.444113)
		(end 104.41305 -275.241766)
		(width 0.1143)
		(layer "In11.Cu")
		(net "P5E_CPU1_P1_RX_DP<8>")
	)
	(arc
		(start 104.656128 -286.992314)
		(mid 104.684852 -286.871357)
		(end 104.765094 -286.776414)
		(width 0.1143)
		(layer "In11.Cu")
		(net "P5E_CPU1_P1_RX_DP<8>")
	)
	(arc
		(start 104.88041 -293.182548)
		(mid 104.88756 -293.17765)
		(end 104.894634 -293.172642)
		(width 0.1143)
		(layer "In11.Cu")
		(net "P5E_CPU1_P1_RX_DP<8>")
	)
	(arc
		(start 104.88041 -278.602694)
		(mid 104.887559 -278.597794)
		(end 104.894634 -278.592788)
		(width 0.1143)
		(layer "In11.Cu")
		(net "P5E_CPU1_P1_RX_DP<8>")
	)
	(arc
		(start 104.894634 -293.172642)
		(mid 105.122017 -292.716204)
		(end 104.894634 -292.259766)
		(width 0.1143)
		(layer "In11.Cu")
		(net "P5E_CPU1_P1_RX_DP<8>")
	)
	(arc
		(start 104.88041 -289.942524)
		(mid 104.888588 -289.936881)
		(end 104.896666 -289.931094)
		(width 0.1143)
		(layer "In11.Cu")
		(net "P5E_CPU1_P1_RX_DP<8>")
	)
	(arc
		(start 104.89565 -285.072074)
		(mid 105.120821 -284.616398)
		(end 104.89565 -284.160722)
		(width 0.1143)
		(layer "In11.Cu")
		(net "P5E_CPU1_P1_RX_DP<8>")
	)
	(arc
		(start 104.722422 -294.933878)
		(mid 104.763411 -294.884137)
		(end 104.812338 -294.842184)
		(width 0.1143)
		(layer "In11.Cu")
		(net "P5E_CPU1_P1_RX_DP<8>")
	)
	(arc
		(start 104.894634 -281.832812)
		(mid 105.122017 -281.376374)
		(end 104.894634 -280.919936)
		(width 0.1143)
		(layer "In11.Cu")
		(net "P5E_CPU1_P1_RX_DP<8>")
	)
	(arc
		(start 104.812338 -290.590478)
		(mid 104.65641 -290.286186)
		(end 104.812338 -289.981894)
		(width 0.1143)
		(layer "In11.Cu")
		(net "P5E_CPU1_P1_RX_DP<8>")
	)
	(arc
		(start 104.894634 -278.592788)
		(mid 105.122017 -278.13635)
		(end 104.894634 -277.679912)
		(width 0.1143)
		(layer "In11.Cu")
		(net "P5E_CPU1_P1_RX_DP<8>")
	)
	(arc
		(start 101.400102 -361.89412)
		(mid 101.569451 -361.772451)
		(end 101.741478 -361.654598)
		(width 0.14224)
		(layer "In11.Cu")
		(net "P5E_CPU1_P1_RX_DP<8>")
	)
	(arc
		(start 120.732804 -348.964758)
		(mid 121.802885 -347.994929)
		(end 122.545348 -346.756228)
		(width 0.14224)
		(layer "In11.Cu")
		(net "P5E_CPU1_P1_RX_DP<8>")
	)
	(arc
		(start 104.896666 -289.021266)
		(mid 104.888588 -289.01548)
		(end 104.88041 -289.009836)
		(width 0.1143)
		(layer "In11.Cu")
		(net "P5E_CPU1_P1_RX_DP<8>")
	)
	(arc
		(start 104.896666 -285.781496)
		(mid 104.888588 -285.77571)
		(end 104.88041 -285.770066)
		(width 0.1143)
		(layer "In11.Cu")
		(net "P5E_CPU1_P1_RX_DP<8>")
	)
	(arc
		(start 104.812338 -292.21049)
		(mid 104.65641 -291.906198)
		(end 104.812338 -291.601906)
		(width 0.1143)
		(layer "In11.Cu")
		(net "P5E_CPU1_P1_RX_DP<8>")
	)
	(arc
		(start 104.88041 -285.082742)
		(mid 104.888074 -285.077471)
		(end 104.89565 -285.072074)
		(width 0.1143)
		(layer "In11.Cu")
		(net "P5E_CPU1_P1_RX_DP<8>")
	)
	(arc
		(start 101.06914 -362.148882)
		(mid 101.233195 -362.019648)
		(end 101.400102 -361.89412)
		(width 0.14224)
		(layer "In11.Cu")
		(net "P5E_CPU1_P1_RX_DP<8>")
	)
	(arc
		(start 104.656382 -288.666174)
		(mid 104.697144 -288.49629)
		(end 104.81056 -288.363406)
		(width 0.1143)
		(layer "In11.Cu")
		(net "P5E_CPU1_P1_RX_DP<8>")
	)
	(arc
		(start 104.262936 -296.081196)
		(mid 104.301292 -295.888459)
		(end 104.41051 -295.725088)
		(width 0.1143)
		(layer "In11.Cu")
		(net "P5E_CPU1_P1_RX_DP<8>")
	)
	(arc
		(start 104.656382 -278.946356)
		(mid 104.697637 -278.775385)
		(end 104.812338 -278.642064)
		(width 0.1143)
		(layer "In11.Cu")
		(net "P5E_CPU1_P1_RX_DP<8>")
	)
	(arc
		(start 104.892602 -294.794178)
		(mid 105.126255 -294.336216)
		(end 104.892602 -293.878254)
		(width 0.1143)
		(layer "In11.Cu")
		(net "P5E_CPU1_P1_RX_DP<8>")
	)
	(arc
		(start 104.896666 -289.931094)
		(mid 105.11955 -289.47618)
		(end 104.896666 -289.021266)
		(width 0.1143)
		(layer "In11.Cu")
		(net "P5E_CPU1_P1_RX_DP<8>")
	)
	(arc
		(start 104.812338 -287.350454)
		(mid 104.697495 -287.217164)
		(end 104.656128 -287.046162)
		(width 0.1143)
		(layer "In11.Cu")
		(net "P5E_CPU1_P1_RX_DP<8>")
	)
	(arc
		(start 104.343454 -280.061162)
		(mid 104.186477 -279.756362)
		(end 104.343454 -279.451562)
		(width 0.1143)
		(layer "In11.Cu")
		(net "P5E_CPU1_P1_RX_DP<8>")
	)
	(arc
		(start 104.812338 -293.830502)
		(mid 104.65641 -293.52621)
		(end 104.812338 -293.221918)
		(width 0.1143)
		(layer "In11.Cu")
		(net "P5E_CPU1_P1_RX_DP<8>")
	)
	(arc
		(start 104.88041 -288.322766)
		(mid 105.061062 -288.120021)
		(end 105.126282 -287.856422)
		(width 0.1143)
		(layer "In11.Cu")
		(net "P5E_CPU1_P1_RX_DP<8>")
	)
	(arc
		(start 104.656382 -280.566368)
		(mid 104.591867 -280.304149)
		(end 104.41305 -280.101802)
		(width 0.1143)
		(layer "In11.Cu")
		(net "P5E_CPU1_P1_RX_DP<8>")
	)
	(arc
		(start 104.88041 -286.702754)
		(mid 105.062594 -286.497084)
		(end 105.126282 -286.229806)
		(width 0.1143)
		(layer "In11.Cu")
		(net "P5E_CPU1_P1_RX_DP<8>")
	)
	(arc
		(start 104.894634 -280.919936)
		(mid 104.88756 -280.914929)
		(end 104.88041 -280.91003)
		(width 0.1143)
		(layer "In11.Cu")
		(net "P5E_CPU1_P1_RX_DP<8>")
	)
	(arc
		(start 104.894634 -276.972776)
		(mid 105.122017 -276.516338)
		(end 104.894634 -276.0599)
		(width 0.1143)
		(layer "In11.Cu")
		(net "P5E_CPU1_P1_RX_DP<8>")
	)
	(segment
		(start 88.598248 -386.003292)
		(end 89.118948 -386.003292)
		(width 0.127)
		(layer "F.Cu")
		(net "P5E_CPU1_P1_RX_DP<7>")
	)
	(segment
		(start 105.027984 -277.870412)
		(end 104.561132 -278.13635)
		(width 0.12954)
		(layer "F.Cu")
		(net "P5E_CPU1_P1_RX_DP<7>")
	)
	(segment
		(start 103.94315 -285.771844)
		(end 103.936292 -285.76778)
		(width 0.1143)
		(layer "In11.Cu")
		(net "P5E_CPU1_P1_RX_DP<7>")
	)
	(segment
		(start 103.903272 -293.848282)
		(end 103.872284 -293.830502)
		(width 0.1143)
		(layer "In11.Cu")
		(net "P5E_CPU1_P1_RX_DP<7>")
	)
	(segment
		(start 103.903272 -284.128464)
		(end 103.872284 -284.110684)
		(width 0.1143)
		(layer "In11.Cu")
		(net "P5E_CPU1_P1_RX_DP<7>")
	)
	(segment
		(start 103.872284 -281.882088)
		(end 103.903272 -281.864308)
		(width 0.1143)
		(layer "In11.Cu")
		(net "P5E_CPU1_P1_RX_DP<7>")
	)
	(segment
		(start 103.94315 -293.87165)
		(end 103.936292 -293.867586)
		(width 0.1143)
		(layer "In11.Cu")
		(net "P5E_CPU1_P1_RX_DP<7>")
	)
	(segment
		(start 103.93553 -292.247066)
		(end 103.910892 -292.232842)
		(width 0.1143)
		(layer "In11.Cu")
		(net "P5E_CPU1_P1_RX_DP<7>")
	)
	(segment
		(start 89.388188 -385.548632)
		(end 89.476326 -385.460494)
		(width 0.14224)
		(layer "In11.Cu")
		(net "P5E_CPU1_P1_RX_DP<7>")
	)
	(segment
		(start 103.904034 -289.963606)
		(end 103.90505 -289.963098)
		(width 0.1143)
		(layer "In11.Cu")
		(net "P5E_CPU1_P1_RX_DP<7>")
	)
	(segment
		(start 90.518488 -367.723166)
		(end 91.167204 -367.201958)
		(width 0.14224)
		(layer "In11.Cu")
		(net "P5E_CPU1_P1_RX_DP<7>")
	)
	(segment
		(start 103.906574 -281.862276)
		(end 103.94315 -281.84094)
		(width 0.1143)
		(layer "In11.Cu")
		(net "P5E_CPU1_P1_RX_DP<7>")
	)
	(segment
		(start 89.44102 -382.296162)
		(end 86.329012 -374.172734)
		(width 0.14224)
		(layer "In11.Cu")
		(net "P5E_CPU1_P1_RX_DP<7>")
	)
	(segment
		(start 103.90505 -289.963098)
		(end 103.906574 -289.962082)
		(width 0.1143)
		(layer "In11.Cu")
		(net "P5E_CPU1_P1_RX_DP<7>")
	)
	(segment
		(start 91.167204 -367.201958)
		(end 95.750888 -364.486952)
		(width 0.14224)
		(layer "In11.Cu")
		(net "P5E_CPU1_P1_RX_DP<7>")
	)
	(segment
		(start 103.872284 -285.122112)
		(end 103.903272 -285.104332)
		(width 0.1143)
		(layer "In11.Cu")
		(net "P5E_CPU1_P1_RX_DP<7>")
	)
	(segment
		(start 103.90505 -280.889456)
		(end 103.904034 -280.888948)
		(width 0.1143)
		(layer "In11.Cu")
		(net "P5E_CPU1_P1_RX_DP<7>")
	)
	(segment
		(start 89.476326 -385.460494)
		(end 89.476326 -385.046982)
		(width 0.14224)
		(layer "In11.Cu")
		(net "P5E_CPU1_P1_RX_DP<7>")
	)
	(segment
		(start 103.93553 -293.867078)
		(end 103.910892 -293.852854)
		(width 0.1143)
		(layer "In11.Cu")
		(net "P5E_CPU1_P1_RX_DP<7>")
	)
	(segment
		(start 103.904034 -284.128972)
		(end 103.903272 -284.128464)
		(width 0.1143)
		(layer "In11.Cu")
		(net "P5E_CPU1_P1_RX_DP<7>")
	)
	(segment
		(start 103.882698 -288.35604)
		(end 103.88346 -288.355532)
		(width 0.1143)
		(layer "In11.Cu")
		(net "P5E_CPU1_P1_RX_DP<7>")
	)
	(segment
		(start 103.903272 -291.584126)
		(end 103.904034 -291.583618)
		(width 0.1143)
		(layer "In11.Cu")
		(net "P5E_CPU1_P1_RX_DP<7>")
	)
	(segment
		(start 103.904034 -290.608766)
		(end 103.903272 -290.608258)
		(width 0.1143)
		(layer "In11.Cu")
		(net "P5E_CPU1_P1_RX_DP<7>")
	)
	(segment
		(start 103.903272 -285.748476)
		(end 103.872284 -285.730696)
		(width 0.1143)
		(layer "In11.Cu")
		(net "P5E_CPU1_P1_RX_DP<7>")
	)
	(segment
		(start 103.910892 -292.232842)
		(end 103.909368 -292.231826)
		(width 0.1143)
		(layer "In11.Cu")
		(net "P5E_CPU1_P1_RX_DP<7>")
	)
	(segment
		(start 103.936292 -285.76778)
		(end 103.93553 -285.767272)
		(width 0.1143)
		(layer "In11.Cu")
		(net "P5E_CPU1_P1_RX_DP<7>")
	)
	(segment
		(start 86.313772 -374.048528)
		(end 86.33841 -373.84609)
		(width 0.14224)
		(layer "In11.Cu")
		(net "P5E_CPU1_P1_RX_DP<7>")
	)
	(segment
		(start 103.314754 -295.806368)
		(end 103.602282 -295.51884)
		(width 0.1143)
		(layer "In11.Cu")
		(net "P5E_CPU1_P1_RX_DP<7>")
	)
	(segment
		(start 103.903272 -290.608258)
		(end 103.872284 -290.590478)
		(width 0.1143)
		(layer "In11.Cu")
		(net "P5E_CPU1_P1_RX_DP<7>")
	)
	(segment
		(start 89.468198 -384.048)
		(end 89.468198 -382.44272)
		(width 0.14224)
		(layer "In11.Cu")
		(net "P5E_CPU1_P1_RX_DP<7>")
	)
	(segment
		(start 103.872284 -293.221918)
		(end 103.903272 -293.204138)
		(width 0.1143)
		(layer "In11.Cu")
		(net "P5E_CPU1_P1_RX_DP<7>")
	)
	(segment
		(start 106.74096 -306.777644)
		(end 103.302054 -298.475654)
		(width 0.14224)
		(layer "In11.Cu")
		(net "P5E_CPU1_P1_RX_DP<7>")
	)
	(segment
		(start 103.90505 -294.823134)
		(end 103.94315 -294.800782)
		(width 0.1143)
		(layer "In11.Cu")
		(net "P5E_CPU1_P1_RX_DP<7>")
	)
	(segment
		(start 104.26319 -278.13635)
		(end 104.561132 -278.13635)
		(width 0.1143)
		(layer "In11.Cu")
		(net "P5E_CPU1_P1_RX_DP<7>")
	)
	(segment
		(start 103.94315 -290.631626)
		(end 103.936292 -290.627562)
		(width 0.1143)
		(layer "In11.Cu")
		(net "P5E_CPU1_P1_RX_DP<7>")
	)
	(segment
		(start 103.908352 -282.5115)
		(end 103.906828 -282.510484)
		(width 0.1143)
		(layer "In11.Cu")
		(net "P5E_CPU1_P1_RX_DP<7>")
	)
	(segment
		(start 103.401876 -279.452578)
		(end 103.446326 -279.426416)
		(width 0.1143)
		(layer "In11.Cu")
		(net "P5E_CPU1_P1_RX_DP<7>")
	)
	(segment
		(start 103.903272 -289.964114)
		(end 103.904034 -289.963606)
		(width 0.1143)
		(layer "In11.Cu")
		(net "P5E_CPU1_P1_RX_DP<7>")
	)
	(segment
		(start 103.903272 -292.22827)
		(end 103.872284 -292.21049)
		(width 0.1143)
		(layer "In11.Cu")
		(net "P5E_CPU1_P1_RX_DP<7>")
	)
	(segment
		(start 95.750888 -364.486952)
		(end 120.242076 -348.121732)
		(width 0.14224)
		(layer "In11.Cu")
		(net "P5E_CPU1_P1_RX_DP<7>")
	)
	(segment
		(start 103.302054 -296.390822)
		(end 103.256334 -296.345102)
		(width 0.1143)
		(layer "In11.Cu")
		(net "P5E_CPU1_P1_RX_DP<7>")
	)
	(segment
		(start 103.909368 -280.891996)
		(end 103.908352 -280.891488)
		(width 0.1143)
		(layer "In11.Cu")
		(net "P5E_CPU1_P1_RX_DP<7>")
	)
	(segment
		(start 103.90505 -282.509468)
		(end 103.904034 -282.50896)
		(width 0.1143)
		(layer "In11.Cu")
		(net "P5E_CPU1_P1_RX_DP<7>")
	)
	(segment
		(start 103.906574 -278.622252)
		(end 103.94315 -278.600916)
		(width 0.1143)
		(layer "In11.Cu")
		(net "P5E_CPU1_P1_RX_DP<7>")
	)
	(segment
		(start 123.50369 -341.864696)
		(end 123.50369 -338.918296)
		(width 0.14224)
		(layer "In11.Cu")
		(net "P5E_CPU1_P1_RX_DP<7>")
	)
	(segment
		(start 103.870506 -286.743394)
		(end 103.94315 -286.700976)
		(width 0.1143)
		(layer "In11.Cu")
		(net "P5E_CPU1_P1_RX_DP<7>")
	)
	(segment
		(start 103.936292 -292.247574)
		(end 103.93553 -292.247066)
		(width 0.1143)
		(layer "In11.Cu")
		(net "P5E_CPU1_P1_RX_DP<7>")
	)
	(segment
		(start 103.872284 -294.84193)
		(end 103.903272 -294.82415)
		(width 0.1143)
		(layer "In11.Cu")
		(net "P5E_CPU1_P1_RX_DP<7>")
	)
	(segment
		(start 103.90505 -281.863292)
		(end 103.906574 -281.862276)
		(width 0.1143)
		(layer "In11.Cu")
		(net "P5E_CPU1_P1_RX_DP<7>")
	)
	(segment
		(start 103.936292 -293.867586)
		(end 103.93553 -293.867078)
		(width 0.1143)
		(layer "In11.Cu")
		(net "P5E_CPU1_P1_RX_DP<7>")
	)
	(segment
		(start 103.872284 -289.981894)
		(end 103.903272 -289.964114)
		(width 0.1143)
		(layer "In11.Cu")
		(net "P5E_CPU1_P1_RX_DP<7>")
	)
	(segment
		(start 119.610124 -324.12305)
		(end 112.726978 -315.736478)
		(width 0.14224)
		(layer "In11.Cu")
		(net "P5E_CPU1_P1_RX_DP<7>")
	)
	(segment
		(start 103.903272 -293.204138)
		(end 103.904034 -293.20363)
		(width 0.1143)
		(layer "In11.Cu")
		(net "P5E_CPU1_P1_RX_DP<7>")
	)
	(segment
		(start 103.89997 -280.886662)
		(end 103.883206 -280.87701)
		(width 0.1143)
		(layer "In11.Cu")
		(net "P5E_CPU1_P1_RX_DP<7>")
	)
	(segment
		(start 103.904034 -293.84879)
		(end 103.903272 -293.848282)
		(width 0.1143)
		(layer "In11.Cu")
		(net "P5E_CPU1_P1_RX_DP<7>")
	)
	(segment
		(start 103.872284 -283.5021)
		(end 103.903272 -283.48432)
		(width 0.1143)
		(layer "In11.Cu")
		(net "P5E_CPU1_P1_RX_DP<7>")
	)
	(segment
		(start 103.94315 -280.911808)
		(end 103.936292 -280.907744)
		(width 0.1143)
		(layer "In11.Cu")
		(net "P5E_CPU1_P1_RX_DP<7>")
	)
	(segment
		(start 103.909368 -293.851838)
		(end 103.908352 -293.85133)
		(width 0.1143)
		(layer "In11.Cu")
		(net "P5E_CPU1_P1_RX_DP<7>")
	)
	(segment
		(start 103.906828 -290.61029)
		(end 103.90505 -290.609274)
		(width 0.1143)
		(layer "In11.Cu")
		(net "P5E_CPU1_P1_RX_DP<7>")
	)
	(segment
		(start 103.910892 -284.133036)
		(end 103.909368 -284.13202)
		(width 0.1143)
		(layer "In11.Cu")
		(net "P5E_CPU1_P1_RX_DP<7>")
	)
	(segment
		(start 103.443024 -280.084022)
		(end 103.402384 -280.060654)
		(width 0.1143)
		(layer "In11.Cu")
		(net "P5E_CPU1_P1_RX_DP<7>")
	)
	(segment
		(start 103.906828 -292.230302)
		(end 103.90505 -292.229286)
		(width 0.1143)
		(layer "In11.Cu")
		(net "P5E_CPU1_P1_RX_DP<7>")
	)
	(segment
		(start 103.90505 -284.12948)
		(end 103.904034 -284.128972)
		(width 0.1143)
		(layer "In11.Cu")
		(net "P5E_CPU1_P1_RX_DP<7>")
	)
	(segment
		(start 103.910892 -285.753048)
		(end 103.909368 -285.752032)
		(width 0.1143)
		(layer "In11.Cu")
		(net "P5E_CPU1_P1_RX_DP<7>")
	)
	(segment
		(start 103.93553 -282.527248)
		(end 103.910892 -282.513024)
		(width 0.1143)
		(layer "In11.Cu")
		(net "P5E_CPU1_P1_RX_DP<7>")
	)
	(segment
		(start 103.909368 -290.611814)
		(end 103.908352 -290.611306)
		(width 0.1143)
		(layer "In11.Cu")
		(net "P5E_CPU1_P1_RX_DP<7>")
	)
	(segment
		(start 103.90505 -285.103316)
		(end 103.906574 -285.1023)
		(width 0.1143)
		(layer "In11.Cu")
		(net "P5E_CPU1_P1_RX_DP<7>")
	)
	(segment
		(start 103.908352 -284.131512)
		(end 103.906828 -284.130496)
		(width 0.1143)
		(layer "In11.Cu")
		(net "P5E_CPU1_P1_RX_DP<7>")
	)
	(segment
		(start 103.904034 -285.748984)
		(end 103.903272 -285.748476)
		(width 0.1143)
		(layer "In11.Cu")
		(net "P5E_CPU1_P1_RX_DP<7>")
	)
	(segment
		(start 103.724456 -280.60269)
		(end 103.724456 -280.572972)
		(width 0.1143)
		(layer "In11.Cu")
		(net "P5E_CPU1_P1_RX_DP<7>")
	)
	(segment
		(start 103.906828 -284.130496)
		(end 103.90505 -284.12948)
		(width 0.1143)
		(layer "In11.Cu")
		(net "P5E_CPU1_P1_RX_DP<7>")
	)
	(segment
		(start 89.163398 -384.3528)
		(end 89.468198 -384.048)
		(width 0.14224)
		(layer "In11.Cu")
		(net "P5E_CPU1_P1_RX_DP<7>")
	)
	(segment
		(start 103.90505 -293.849298)
		(end 103.904034 -293.84879)
		(width 0.1143)
		(layer "In11.Cu")
		(net "P5E_CPU1_P1_RX_DP<7>")
	)
	(segment
		(start 103.90505 -291.58311)
		(end 103.906574 -291.582094)
		(width 0.1143)
		(layer "In11.Cu")
		(net "P5E_CPU1_P1_RX_DP<7>")
	)
	(segment
		(start 103.904034 -292.228778)
		(end 103.903272 -292.22827)
		(width 0.1143)
		(layer "In11.Cu")
		(net "P5E_CPU1_P1_RX_DP<7>")
	)
	(segment
		(start 103.716328 -295.243758)
		(end 103.716328 -295.14546)
		(width 0.1143)
		(layer "In11.Cu")
		(net "P5E_CPU1_P1_RX_DP<7>")
	)
	(segment
		(start 103.903272 -281.864308)
		(end 103.904034 -281.8638)
		(width 0.1143)
		(layer "In11.Cu")
		(net "P5E_CPU1_P1_RX_DP<7>")
	)
	(segment
		(start 103.909368 -284.13202)
		(end 103.908352 -284.131512)
		(width 0.1143)
		(layer "In11.Cu")
		(net "P5E_CPU1_P1_RX_DP<7>")
	)
	(segment
		(start 103.908352 -290.611306)
		(end 103.906828 -290.61029)
		(width 0.1143)
		(layer "In11.Cu")
		(net "P5E_CPU1_P1_RX_DP<7>")
	)
	(segment
		(start 103.936292 -284.147768)
		(end 103.93553 -284.14726)
		(width 0.1143)
		(layer "In11.Cu")
		(net "P5E_CPU1_P1_RX_DP<7>")
	)
	(segment
		(start 103.88346 -288.355532)
		(end 103.937562 -288.323782)
		(width 0.1143)
		(layer "In11.Cu")
		(net "P5E_CPU1_P1_RX_DP<7>")
	)
	(segment
		(start 103.906574 -289.962082)
		(end 103.94315 -289.940746)
		(width 0.1143)
		(layer "In11.Cu")
		(net "P5E_CPU1_P1_RX_DP<7>")
	)
	(segment
		(start 103.904034 -282.50896)
		(end 103.903272 -282.508452)
		(width 0.1143)
		(layer "In11.Cu")
		(net "P5E_CPU1_P1_RX_DP<7>")
	)
	(segment
		(start 103.910892 -290.61283)
		(end 103.909368 -290.611814)
		(width 0.1143)
		(layer "In11.Cu")
		(net "P5E_CPU1_P1_RX_DP<7>")
	)
	(segment
		(start 103.908352 -280.891488)
		(end 103.906828 -280.890472)
		(width 0.1143)
		(layer "In11.Cu")
		(net "P5E_CPU1_P1_RX_DP<7>")
	)
	(segment
		(start 103.903272 -285.104332)
		(end 103.904034 -285.103824)
		(width 0.1143)
		(layer "In11.Cu")
		(net "P5E_CPU1_P1_RX_DP<7>")
	)
	(segment
		(start 103.936292 -280.907744)
		(end 103.93553 -280.907236)
		(width 0.1143)
		(layer "In11.Cu")
		(net "P5E_CPU1_P1_RX_DP<7>")
	)
	(segment
		(start 103.906574 -285.1023)
		(end 103.94315 -285.080964)
		(width 0.1143)
		(layer "In11.Cu")
		(net "P5E_CPU1_P1_RX_DP<7>")
	)
	(segment
		(start 103.904034 -294.823642)
		(end 103.90505 -294.823134)
		(width 0.1143)
		(layer "In11.Cu")
		(net "P5E_CPU1_P1_RX_DP<7>")
	)
	(segment
		(start 103.908352 -293.85133)
		(end 103.906828 -293.850314)
		(width 0.1143)
		(layer "In11.Cu")
		(net "P5E_CPU1_P1_RX_DP<7>")
	)
	(segment
		(start 89.118948 -386.003292)
		(end 89.213944 -385.649216)
		(width 0.14224)
		(layer "In11.Cu")
		(net "P5E_CPU1_P1_RX_DP<7>")
	)
	(segment
		(start 103.906828 -280.890472)
		(end 103.90505 -280.889456)
		(width 0.1143)
		(layer "In11.Cu")
		(net "P5E_CPU1_P1_RX_DP<7>")
	)
	(segment
		(start 89.213944 -385.649216)
		(end 89.388188 -385.548632)
		(width 0.14224)
		(layer "In11.Cu")
		(net "P5E_CPU1_P1_RX_DP<7>")
	)
	(segment
		(start 103.909368 -292.231826)
		(end 103.908352 -292.231318)
		(width 0.1143)
		(layer "In11.Cu")
		(net "P5E_CPU1_P1_RX_DP<7>")
	)
	(segment
		(start 103.882698 -288.976308)
		(end 103.88219 -288.976308)
		(width 0.1143)
		(layer "In11.Cu")
		(net "P5E_CPU1_P1_RX_DP<7>")
	)
	(segment
		(start 103.903272 -280.88844)
		(end 103.89997 -280.886662)
		(width 0.1143)
		(layer "In11.Cu")
		(net "P5E_CPU1_P1_RX_DP<7>")
	)
	(segment
		(start 103.906828 -285.750508)
		(end 103.90505 -285.749492)
		(width 0.1143)
		(layer "In11.Cu")
		(net "P5E_CPU1_P1_RX_DP<7>")
	)
	(segment
		(start 103.93553 -285.767272)
		(end 103.910892 -285.753048)
		(width 0.1143)
		(layer "In11.Cu")
		(net "P5E_CPU1_P1_RX_DP<7>")
	)
	(segment
		(start 103.910892 -280.893012)
		(end 103.909368 -280.891996)
		(width 0.1143)
		(layer "In11.Cu")
		(net "P5E_CPU1_P1_RX_DP<7>")
	)
	(segment
		(start 121.49201 -327.723754)
		(end 119.610124 -324.12305)
		(width 0.14224)
		(layer "In11.Cu")
		(net "P5E_CPU1_P1_RX_DP<7>")
	)
	(segment
		(start 103.903272 -282.508452)
		(end 103.872284 -282.490672)
		(width 0.1143)
		(layer "In11.Cu")
		(net "P5E_CPU1_P1_RX_DP<7>")
	)
	(segment
		(start 103.909368 -285.752032)
		(end 103.908352 -285.751524)
		(width 0.1143)
		(layer "In11.Cu")
		(net "P5E_CPU1_P1_RX_DP<7>")
	)
	(segment
		(start 89.16035 -384.731006)
		(end 89.163398 -384.3528)
		(width 0.14224)
		(layer "In11.Cu")
		(net "P5E_CPU1_P1_RX_DP<7>")
	)
	(segment
		(start 103.942388 -289.011106)
		(end 103.882698 -288.976308)
		(width 0.1143)
		(layer "In11.Cu")
		(net "P5E_CPU1_P1_RX_DP<7>")
	)
	(segment
		(start 103.904034 -291.583618)
		(end 103.90505 -291.58311)
		(width 0.1143)
		(layer "In11.Cu")
		(net "P5E_CPU1_P1_RX_DP<7>")
	)
	(segment
		(start 103.908352 -285.751524)
		(end 103.906828 -285.750508)
		(width 0.1143)
		(layer "In11.Cu")
		(net "P5E_CPU1_P1_RX_DP<7>")
	)
	(segment
		(start 89.476326 -385.046982)
		(end 89.16035 -384.731006)
		(width 0.14224)
		(layer "In11.Cu")
		(net "P5E_CPU1_P1_RX_DP<7>")
	)
	(segment
		(start 103.906574 -283.482288)
		(end 103.94315 -283.460952)
		(width 0.1143)
		(layer "In11.Cu")
		(net "P5E_CPU1_P1_RX_DP<7>")
	)
	(segment
		(start 103.90505 -283.483304)
		(end 103.906574 -283.482288)
		(width 0.1143)
		(layer "In11.Cu")
		(net "P5E_CPU1_P1_RX_DP<7>")
	)
	(segment
		(start 103.93553 -290.627054)
		(end 103.910892 -290.61283)
		(width 0.1143)
		(layer "In11.Cu")
		(net "P5E_CPU1_P1_RX_DP<7>")
	)
	(segment
		(start 103.904034 -293.20363)
		(end 103.90505 -293.203122)
		(width 0.1143)
		(layer "In11.Cu")
		(net "P5E_CPU1_P1_RX_DP<7>")
	)
	(segment
		(start 103.906828 -293.850314)
		(end 103.90505 -293.849298)
		(width 0.1143)
		(layer "In11.Cu")
		(net "P5E_CPU1_P1_RX_DP<7>")
	)
	(segment
		(start 103.904034 -287.368742)
		(end 103.872284 -287.350454)
		(width 0.1143)
		(layer "In11.Cu")
		(net "P5E_CPU1_P1_RX_DP<7>")
	)
	(segment
		(start 103.909368 -282.512008)
		(end 103.908352 -282.5115)
		(width 0.1143)
		(layer "In11.Cu")
		(net "P5E_CPU1_P1_RX_DP<7>")
	)
	(segment
		(start 103.94315 -282.53182)
		(end 103.936292 -282.527756)
		(width 0.1143)
		(layer "In11.Cu")
		(net "P5E_CPU1_P1_RX_DP<7>")
	)
	(segment
		(start 103.729028 -278.936704)
		(end 103.729028 -278.927052)
		(width 0.1143)
		(layer "In11.Cu")
		(net "P5E_CPU1_P1_RX_DP<7>")
	)
	(segment
		(start 103.93553 -280.907236)
		(end 103.910892 -280.893012)
		(width 0.1143)
		(layer "In11.Cu")
		(net "P5E_CPU1_P1_RX_DP<7>")
	)
	(segment
		(start 103.90505 -293.203122)
		(end 103.906574 -293.202106)
		(width 0.1143)
		(layer "In11.Cu")
		(net "P5E_CPU1_P1_RX_DP<7>")
	)
	(segment
		(start 103.90505 -278.623268)
		(end 103.906574 -278.622252)
		(width 0.1143)
		(layer "In11.Cu")
		(net "P5E_CPU1_P1_RX_DP<7>")
	)
	(segment
		(start 103.936292 -282.527756)
		(end 103.93553 -282.527248)
		(width 0.1143)
		(layer "In11.Cu")
		(net "P5E_CPU1_P1_RX_DP<7>")
	)
	(segment
		(start 103.904034 -283.483812)
		(end 103.90505 -283.483304)
		(width 0.1143)
		(layer "In11.Cu")
		(net "P5E_CPU1_P1_RX_DP<7>")
	)
	(segment
		(start 121.59488 -346.473018)
		(end 123.50369 -341.864696)
		(width 0.14224)
		(layer "In11.Cu")
		(net "P5E_CPU1_P1_RX_DP<7>")
	)
	(segment
		(start 103.904034 -281.8638)
		(end 103.90505 -281.863292)
		(width 0.1143)
		(layer "In11.Cu")
		(net "P5E_CPU1_P1_RX_DP<7>")
	)
	(segment
		(start 103.937562 -288.323782)
		(end 103.94315 -288.320988)
		(width 0.1143)
		(layer "In11.Cu")
		(net "P5E_CPU1_P1_RX_DP<7>")
	)
	(segment
		(start 103.94315 -292.251638)
		(end 103.936292 -292.247574)
		(width 0.1143)
		(layer "In11.Cu")
		(net "P5E_CPU1_P1_RX_DP<7>")
	)
	(segment
		(start 103.910892 -282.513024)
		(end 103.909368 -282.512008)
		(width 0.1143)
		(layer "In11.Cu")
		(net "P5E_CPU1_P1_RX_DP<7>")
	)
	(segment
		(start 103.904034 -278.623776)
		(end 103.90505 -278.623268)
		(width 0.1143)
		(layer "In11.Cu")
		(net "P5E_CPU1_P1_RX_DP<7>")
	)
	(segment
		(start 103.936292 -290.627562)
		(end 103.93553 -290.627054)
		(width 0.1143)
		(layer "In11.Cu")
		(net "P5E_CPU1_P1_RX_DP<7>")
	)
	(segment
		(start 103.256334 -296.345102)
		(end 103.256334 -295.947338)
		(width 0.1143)
		(layer "In11.Cu")
		(net "P5E_CPU1_P1_RX_DP<7>")
	)
	(segment
		(start 103.94315 -284.151832)
		(end 103.936292 -284.147768)
		(width 0.1143)
		(layer "In11.Cu")
		(net "P5E_CPU1_P1_RX_DP<7>")
	)
	(segment
		(start 103.302054 -298.475654)
		(end 103.302054 -296.41927)
		(width 0.14224)
		(layer "In11.Cu")
		(net "P5E_CPU1_P1_RX_DP<7>")
	)
	(segment
		(start 103.906574 -293.202106)
		(end 103.94315 -293.18077)
		(width 0.1143)
		(layer "In11.Cu")
		(net "P5E_CPU1_P1_RX_DP<7>")
	)
	(segment
		(start 103.910892 -293.852854)
		(end 103.909368 -293.851838)
		(width 0.1143)
		(layer "In11.Cu")
		(net "P5E_CPU1_P1_RX_DP<7>")
	)
	(segment
		(start 103.93553 -284.14726)
		(end 103.910892 -284.133036)
		(width 0.1143)
		(layer "In11.Cu")
		(net "P5E_CPU1_P1_RX_DP<7>")
	)
	(segment
		(start 112.726978 -315.736478)
		(end 106.74096 -306.777644)
		(width 0.14224)
		(layer "In11.Cu")
		(net "P5E_CPU1_P1_RX_DP<7>")
	)
	(segment
		(start 103.904034 -280.888948)
		(end 103.903272 -280.88844)
		(width 0.1143)
		(layer "In11.Cu")
		(net "P5E_CPU1_P1_RX_DP<7>")
	)
	(segment
		(start 103.908352 -292.231318)
		(end 103.906828 -292.230302)
		(width 0.1143)
		(layer "In11.Cu")
		(net "P5E_CPU1_P1_RX_DP<7>")
	)
	(segment
		(start 103.903526 -278.623776)
		(end 103.904034 -278.623776)
		(width 0.1143)
		(layer "In11.Cu")
		(net "P5E_CPU1_P1_RX_DP<7>")
	)
	(segment
		(start 123.50369 -338.918296)
		(end 121.49201 -327.723754)
		(width 0.14224)
		(layer "In11.Cu")
		(net "P5E_CPU1_P1_RX_DP<7>")
	)
	(segment
		(start 86.493604 -373.485918)
		(end 90.518488 -367.723166)
		(width 0.14224)
		(layer "In11.Cu")
		(net "P5E_CPU1_P1_RX_DP<7>")
	)
	(segment
		(start 103.872284 -291.601906)
		(end 103.903272 -291.584126)
		(width 0.1143)
		(layer "In11.Cu")
		(net "P5E_CPU1_P1_RX_DP<7>")
	)
	(segment
		(start 103.906828 -282.510484)
		(end 103.90505 -282.509468)
		(width 0.1143)
		(layer "In11.Cu")
		(net "P5E_CPU1_P1_RX_DP<7>")
	)
	(segment
		(start 103.903272 -283.48432)
		(end 103.904034 -283.483812)
		(width 0.1143)
		(layer "In11.Cu")
		(net "P5E_CPU1_P1_RX_DP<7>")
	)
	(segment
		(start 104.180386 -278.219154)
		(end 104.26319 -278.13635)
		(width 0.1143)
		(layer "In11.Cu")
		(net "P5E_CPU1_P1_RX_DP<7>")
	)
	(segment
		(start 103.302054 -296.41927)
		(end 103.302054 -296.390822)
		(width 0.1143)
		(layer "In11.Cu")
		(net "P5E_CPU1_P1_RX_DP<7>")
	)
	(segment
		(start 103.90505 -292.229286)
		(end 103.904034 -292.228778)
		(width 0.1143)
		(layer "In11.Cu")
		(net "P5E_CPU1_P1_RX_DP<7>")
	)
	(segment
		(start 103.90505 -285.749492)
		(end 103.904034 -285.748984)
		(width 0.1143)
		(layer "In11.Cu")
		(net "P5E_CPU1_P1_RX_DP<7>")
	)
	(segment
		(start 103.903272 -294.82415)
		(end 103.904034 -294.823642)
		(width 0.1143)
		(layer "In11.Cu")
		(net "P5E_CPU1_P1_RX_DP<7>")
	)
	(segment
		(start 103.882444 -288.35604)
		(end 103.882698 -288.35604)
		(width 0.1143)
		(layer "In11.Cu")
		(net "P5E_CPU1_P1_RX_DP<7>")
	)
	(segment
		(start 103.906574 -291.582094)
		(end 103.94315 -291.560758)
		(width 0.1143)
		(layer "In11.Cu")
		(net "P5E_CPU1_P1_RX_DP<7>")
	)
	(segment
		(start 103.90505 -290.609274)
		(end 103.904034 -290.608766)
		(width 0.1143)
		(layer "In11.Cu")
		(net "P5E_CPU1_P1_RX_DP<7>")
	)
	(segment
		(start 103.904034 -285.103824)
		(end 103.90505 -285.103316)
		(width 0.1143)
		(layer "In11.Cu")
		(net "P5E_CPU1_P1_RX_DP<7>")
	)
	(segment
		(start 103.94061 -287.390078)
		(end 103.904034 -287.368742)
		(width 0.1143)
		(layer "In11.Cu")
		(net "P5E_CPU1_P1_RX_DP<7>")
	)
	(arc
		(start 103.88219 -288.976308)
		(mid 103.703774 -288.666064)
		(end 103.882444 -288.35604)
		(width 0.1143)
		(layer "In11.Cu")
		(net "P5E_CPU1_P1_RX_DP<7>")
	)
	(arc
		(start 103.94315 -283.460952)
		(mid 104.186477 -282.996386)
		(end 103.94315 -282.53182)
		(width 0.1143)
		(layer "In11.Cu")
		(net "P5E_CPU1_P1_RX_DP<7>")
	)
	(arc
		(start 103.94315 -281.84094)
		(mid 104.186477 -281.376374)
		(end 103.94315 -280.911808)
		(width 0.1143)
		(layer "In11.Cu")
		(net "P5E_CPU1_P1_RX_DP<7>")
	)
	(arc
		(start 103.94315 -288.320988)
		(mid 104.121963 -288.118638)
		(end 104.186482 -287.856422)
		(width 0.1143)
		(layer "In11.Cu")
		(net "P5E_CPU1_P1_RX_DP<7>")
	)
	(arc
		(start 103.872284 -284.110684)
		(mid 103.723187 -283.806392)
		(end 103.872284 -283.5021)
		(width 0.1143)
		(layer "In11.Cu")
		(net "P5E_CPU1_P1_RX_DP<7>")
	)
	(arc
		(start 103.872284 -282.490672)
		(mid 103.720695 -282.18638)
		(end 103.872284 -281.882088)
		(width 0.1143)
		(layer "In11.Cu")
		(net "P5E_CPU1_P1_RX_DP<7>")
	)
	(arc
		(start 103.716328 -295.14546)
		(mid 103.716328 -295.144952)
		(end 103.716328 -295.144444)
		(width 0.1143)
		(layer "In11.Cu")
		(net "P5E_CPU1_P1_RX_DP<7>")
	)
	(arc
		(start 103.716328 -287.046162)
		(mid 103.75709 -286.876278)
		(end 103.870506 -286.743394)
		(width 0.1143)
		(layer "In11.Cu")
		(net "P5E_CPU1_P1_RX_DP<7>")
	)
	(arc
		(start 103.872284 -287.350454)
		(mid 103.759476 -287.216172)
		(end 103.716328 -287.046162)
		(width 0.1143)
		(layer "In11.Cu")
		(net "P5E_CPU1_P1_RX_DP<7>")
	)
	(arc
		(start 103.446326 -279.426416)
		(mid 103.653314 -279.219444)
		(end 103.729028 -278.936704)
		(width 0.1143)
		(layer "In11.Cu")
		(net "P5E_CPU1_P1_RX_DP<7>")
	)
	(arc
		(start 103.872284 -285.730696)
		(mid 103.721899 -285.426404)
		(end 103.872284 -285.122112)
		(width 0.1143)
		(layer "In11.Cu")
		(net "P5E_CPU1_P1_RX_DP<7>")
	)
	(arc
		(start 103.94315 -291.560758)
		(mid 104.186477 -291.096192)
		(end 103.94315 -290.631626)
		(width 0.1143)
		(layer "In11.Cu")
		(net "P5E_CPU1_P1_RX_DP<7>")
	)
	(arc
		(start 103.94315 -294.800782)
		(mid 104.186477 -294.336216)
		(end 103.94315 -293.87165)
		(width 0.1143)
		(layer "In11.Cu")
		(net "P5E_CPU1_P1_RX_DP<7>")
	)
	(arc
		(start 86.329012 -374.172734)
		(mid 86.313806 -374.111564)
		(end 86.313772 -374.048528)
		(width 0.14224)
		(layer "In11.Cu")
		(net "P5E_CPU1_P1_RX_DP<7>")
	)
	(arc
		(start 103.402384 -280.060654)
		(mid 103.246456 -279.756717)
		(end 103.401876 -279.452578)
		(width 0.1143)
		(layer "In11.Cu")
		(net "P5E_CPU1_P1_RX_DP<7>")
	)
	(arc
		(start 103.602282 -295.51884)
		(mid 103.686666 -295.392646)
		(end 103.716328 -295.243758)
		(width 0.1143)
		(layer "In11.Cu")
		(net "P5E_CPU1_P1_RX_DP<7>")
	)
	(arc
		(start 103.94315 -278.600916)
		(mid 104.095137 -278.444408)
		(end 104.176576 -278.242014)
		(width 0.1143)
		(layer "In11.Cu")
		(net "P5E_CPU1_P1_RX_DP<7>")
	)
	(arc
		(start 120.242076 -348.121732)
		(mid 121.040749 -347.397703)
		(end 121.59488 -346.473018)
		(width 0.14224)
		(layer "In11.Cu")
		(net "P5E_CPU1_P1_RX_DP<7>")
	)
	(arc
		(start 103.256334 -295.947338)
		(mid 103.271512 -295.871035)
		(end 103.314754 -295.806368)
		(width 0.1143)
		(layer "In11.Cu")
		(net "P5E_CPU1_P1_RX_DP<7>")
	)
	(arc
		(start 103.872284 -292.21049)
		(mid 103.720695 -291.906198)
		(end 103.872284 -291.601906)
		(width 0.1143)
		(layer "In11.Cu")
		(net "P5E_CPU1_P1_RX_DP<7>")
	)
	(arc
		(start 103.724456 -280.572972)
		(mid 103.649069 -280.290899)
		(end 103.443024 -280.084022)
		(width 0.1143)
		(layer "In11.Cu")
		(net "P5E_CPU1_P1_RX_DP<7>")
	)
	(arc
		(start 103.94315 -289.011614)
		(mid 103.942769 -289.01136)
		(end 103.942388 -289.011106)
		(width 0.1143)
		(layer "In11.Cu")
		(net "P5E_CPU1_P1_RX_DP<7>")
	)
	(arc
		(start 103.883206 -280.87701)
		(mid 103.767038 -280.76115)
		(end 103.724456 -280.60269)
		(width 0.1143)
		(layer "In11.Cu")
		(net "P5E_CPU1_P1_RX_DP<7>")
	)
	(arc
		(start 103.872284 -293.830502)
		(mid 103.721899 -293.52621)
		(end 103.872284 -293.221918)
		(width 0.1143)
		(layer "In11.Cu")
		(net "P5E_CPU1_P1_RX_DP<7>")
	)
	(arc
		(start 104.186482 -287.856422)
		(mid 104.121246 -287.592831)
		(end 103.94061 -287.390078)
		(width 0.1143)
		(layer "In11.Cu")
		(net "P5E_CPU1_P1_RX_DP<7>")
	)
	(arc
		(start 104.176576 -278.242014)
		(mid 104.178599 -278.230604)
		(end 104.180386 -278.219154)
		(width 0.1143)
		(layer "In11.Cu")
		(net "P5E_CPU1_P1_RX_DP<7>")
	)
	(arc
		(start 86.368636 -373.723154)
		(mid 86.423682 -373.600619)
		(end 86.493604 -373.485918)
		(width 0.14224)
		(layer "In11.Cu")
		(net "P5E_CPU1_P1_RX_DP<7>")
	)
	(arc
		(start 103.94315 -285.080964)
		(mid 104.186477 -284.616398)
		(end 103.94315 -284.151832)
		(width 0.1143)
		(layer "In11.Cu")
		(net "P5E_CPU1_P1_RX_DP<7>")
	)
	(arc
		(start 103.729028 -278.927052)
		(mid 103.775768 -278.752107)
		(end 103.903526 -278.623776)
		(width 0.1143)
		(layer "In11.Cu")
		(net "P5E_CPU1_P1_RX_DP<7>")
	)
	(arc
		(start 103.94315 -293.18077)
		(mid 104.186477 -292.716204)
		(end 103.94315 -292.251638)
		(width 0.1143)
		(layer "In11.Cu")
		(net "P5E_CPU1_P1_RX_DP<7>")
	)
	(arc
		(start 103.716328 -295.144444)
		(mid 103.759842 -294.975426)
		(end 103.872284 -294.84193)
		(width 0.1143)
		(layer "In11.Cu")
		(net "P5E_CPU1_P1_RX_DP<7>")
	)
	(arc
		(start 89.468198 -382.44272)
		(mid 89.461317 -382.368198)
		(end 89.44102 -382.296162)
		(width 0.14224)
		(layer "In11.Cu")
		(net "P5E_CPU1_P1_RX_DP<7>")
	)
	(arc
		(start 103.94315 -286.700976)
		(mid 104.186477 -286.23641)
		(end 103.94315 -285.771844)
		(width 0.1143)
		(layer "In11.Cu")
		(net "P5E_CPU1_P1_RX_DP<7>")
	)
	(arc
		(start 103.94315 -289.940746)
		(mid 104.186477 -289.47618)
		(end 103.94315 -289.011614)
		(width 0.1143)
		(layer "In11.Cu")
		(net "P5E_CPU1_P1_RX_DP<7>")
	)
	(arc
		(start 103.872284 -290.590478)
		(mid 103.718343 -290.286186)
		(end 103.872284 -289.981894)
		(width 0.1143)
		(layer "In11.Cu")
		(net "P5E_CPU1_P1_RX_DP<7>")
	)
	(arc
		(start 86.33841 -373.84609)
		(mid 86.349866 -373.783723)
		(end 86.368636 -373.723154)
		(width 0.14224)
		(layer "In11.Cu")
		(net "P5E_CPU1_P1_RX_DP<7>")
	)
	(segment
		(start 87.398352 -386.003292)
		(end 87.919052 -386.003292)
		(width 0.127)
		(layer "F.Cu")
		(net "P5E_CPU1_P1_RX_DP<6>")
	)
	(segment
		(start 105.027984 -276.2504)
		(end 104.561132 -276.516338)
		(width 0.12954)
		(layer "F.Cu")
		(net "P5E_CPU1_P1_RX_DP<6>")
	)
	(segment
		(start 111.978948 -316.295024)
		(end 105.914698 -307.21935)
		(width 0.14224)
		(layer "In11.Cu")
		(net "P5E_CPU1_P1_RX_DP<6>")
	)
	(segment
		(start 103.003096 -284.151832)
		(end 102.9335 -284.111192)
		(width 0.1143)
		(layer "In11.Cu")
		(net "P5E_CPU1_P1_RX_DP<6>")
	)
	(segment
		(start 103.430578 -277.815802)
		(end 103.433372 -277.814278)
		(width 0.1143)
		(layer "In11.Cu")
		(net "P5E_CPU1_P1_RX_DP<6>")
	)
	(segment
		(start 102.493318 -280.078434)
		(end 102.490524 -280.07691)
		(width 0.1143)
		(layer "In11.Cu")
		(net "P5E_CPU1_P1_RX_DP<6>")
	)
	(segment
		(start 102.9335 -293.22141)
		(end 103.003096 -293.18077)
		(width 0.1143)
		(layer "In11.Cu")
		(net "P5E_CPU1_P1_RX_DP<6>")
	)
	(segment
		(start 105.914698 -307.21935)
		(end 102.357174 -298.630848)
		(width 0.14224)
		(layer "In11.Cu")
		(net "P5E_CPU1_P1_RX_DP<6>")
	)
	(segment
		(start 122.527822 -341.622888)
		(end 122.527822 -338.829904)
		(width 0.14224)
		(layer "In11.Cu")
		(net "P5E_CPU1_P1_RX_DP<6>")
	)
	(segment
		(start 102.311454 -296.345102)
		(end 102.311454 -296.113708)
		(width 0.1143)
		(layer "In11.Cu")
		(net "P5E_CPU1_P1_RX_DP<6>")
	)
	(segment
		(start 102.487476 -280.075132)
		(end 102.48646 -280.074624)
		(width 0.1143)
		(layer "In11.Cu")
		(net "P5E_CPU1_P1_RX_DP<6>")
	)
	(segment
		(start 87.963502 -384.352546)
		(end 88.268302 -384.047746)
		(width 0.14224)
		(layer "In11.Cu")
		(net "P5E_CPU1_P1_RX_DP<6>")
	)
	(segment
		(start 102.49408 -279.433782)
		(end 102.495096 -279.433274)
		(width 0.1143)
		(layer "In11.Cu")
		(net "P5E_CPU1_P1_RX_DP<6>")
	)
	(segment
		(start 102.525576 -280.09723)
		(end 102.495096 -280.07945)
		(width 0.1143)
		(layer "In11.Cu")
		(net "P5E_CPU1_P1_RX_DP<6>")
	)
	(segment
		(start 102.495096 -279.433274)
		(end 102.49662 -279.432258)
		(width 0.1143)
		(layer "In11.Cu")
		(net "P5E_CPU1_P1_RX_DP<6>")
	)
	(segment
		(start 102.96398 -286.723836)
		(end 103.003096 -286.700976)
		(width 0.1143)
		(layer "In11.Cu")
		(net "P5E_CPU1_P1_RX_DP<6>")
	)
	(segment
		(start 103.427784 -277.817326)
		(end 103.429816 -277.81631)
		(width 0.1143)
		(layer "In11.Cu")
		(net "P5E_CPU1_P1_RX_DP<6>")
	)
	(segment
		(start 102.96398 -288.343848)
		(end 103.003096 -288.320988)
		(width 0.1143)
		(layer "In11.Cu")
		(net "P5E_CPU1_P1_RX_DP<6>")
	)
	(segment
		(start 95.31477 -363.501432)
		(end 119.601234 -347.273372)
		(width 0.14224)
		(layer "In11.Cu")
		(net "P5E_CPU1_P1_RX_DP<6>")
	)
	(segment
		(start 102.49662 -279.432258)
		(end 102.533196 -279.410922)
		(width 0.1143)
		(layer "In11.Cu")
		(net "P5E_CPU1_P1_RX_DP<6>")
	)
	(segment
		(start 102.9335 -289.981386)
		(end 103.003096 -289.940746)
		(width 0.1143)
		(layer "In11.Cu")
		(net "P5E_CPU1_P1_RX_DP<6>")
	)
	(segment
		(start 88.188292 -385.548632)
		(end 88.27643 -385.460494)
		(width 0.14224)
		(layer "In11.Cu")
		(net "P5E_CPU1_P1_RX_DP<6>")
	)
	(segment
		(start 103.429816 -277.81631)
		(end 103.430578 -277.815802)
		(width 0.1143)
		(layer "In11.Cu")
		(net "P5E_CPU1_P1_RX_DP<6>")
	)
	(segment
		(start 102.48773 -279.437338)
		(end 102.489762 -279.436322)
		(width 0.1143)
		(layer "In11.Cu")
		(net "P5E_CPU1_P1_RX_DP<6>")
	)
	(segment
		(start 120.78462 -345.831668)
		(end 122.527822 -341.622888)
		(width 0.14224)
		(layer "In11.Cu")
		(net "P5E_CPU1_P1_RX_DP<6>")
	)
	(segment
		(start 102.49408 -280.078942)
		(end 102.493318 -280.078434)
		(width 0.1143)
		(layer "In11.Cu")
		(net "P5E_CPU1_P1_RX_DP<6>")
	)
	(segment
		(start 102.48646 -280.074624)
		(end 102.46233 -280.060654)
		(width 0.1143)
		(layer "In11.Cu")
		(net "P5E_CPU1_P1_RX_DP<6>")
	)
	(segment
		(start 103.8733 -277.021544)
		(end 103.94315 -276.980904)
		(width 0.1143)
		(layer "In11.Cu")
		(net "P5E_CPU1_P1_RX_DP<6>")
	)
	(segment
		(start 102.46233 -279.45207)
		(end 102.48773 -279.437338)
		(width 0.1143)
		(layer "In11.Cu")
		(net "P5E_CPU1_P1_RX_DP<6>")
	)
	(segment
		(start 103.000556 -287.390078)
		(end 102.9335 -287.350962)
		(width 0.1143)
		(layer "In11.Cu")
		(net "P5E_CPU1_P1_RX_DP<6>")
	)
	(segment
		(start 88.27643 -385.046982)
		(end 87.960454 -384.731006)
		(width 0.14224)
		(layer "In11.Cu")
		(net "P5E_CPU1_P1_RX_DP<6>")
	)
	(segment
		(start 120.579896 -327.991978)
		(end 119.700548 -326.309736)
		(width 0.14224)
		(layer "In11.Cu")
		(net "P5E_CPU1_P1_RX_DP<6>")
	)
	(segment
		(start 103.003096 -280.911808)
		(end 102.9335 -280.871168)
		(width 0.1143)
		(layer "In11.Cu")
		(net "P5E_CPU1_P1_RX_DP<6>")
	)
	(segment
		(start 88.268302 -384.047746)
		(end 88.268302 -382.342136)
		(width 0.14224)
		(layer "In11.Cu")
		(net "P5E_CPU1_P1_RX_DP<6>")
	)
	(segment
		(start 103.435658 -277.813008)
		(end 103.470456 -277.792688)
		(width 0.1143)
		(layer "In11.Cu")
		(net "P5E_CPU1_P1_RX_DP<6>")
	)
	(segment
		(start 85.358986 -374.286018)
		(end 85.447632 -373.090186)
		(width 0.14224)
		(layer "In11.Cu")
		(net "P5E_CPU1_P1_RX_DP<6>")
	)
	(segment
		(start 102.357174 -298.630848)
		(end 102.357174 -296.41927)
		(width 0.14224)
		(layer "In11.Cu")
		(net "P5E_CPU1_P1_RX_DP<6>")
	)
	(segment
		(start 102.931468 -286.742632)
		(end 102.96398 -286.723836)
		(width 0.1143)
		(layer "In11.Cu")
		(net "P5E_CPU1_P1_RX_DP<6>")
	)
	(segment
		(start 102.357174 -296.41927)
		(end 102.357174 -296.390822)
		(width 0.1143)
		(layer "In11.Cu")
		(net "P5E_CPU1_P1_RX_DP<6>")
	)
	(segment
		(start 103.003096 -292.251638)
		(end 102.9335 -292.210998)
		(width 0.1143)
		(layer "In11.Cu")
		(net "P5E_CPU1_P1_RX_DP<6>")
	)
	(segment
		(start 88.014048 -385.649216)
		(end 88.188292 -385.548632)
		(width 0.14224)
		(layer "In11.Cu")
		(net "P5E_CPU1_P1_RX_DP<6>")
	)
	(segment
		(start 102.489762 -280.076402)
		(end 102.488238 -280.07564)
		(width 0.1143)
		(layer "In11.Cu")
		(net "P5E_CPU1_P1_RX_DP<6>")
	)
	(segment
		(start 102.488238 -280.07564)
		(end 102.487476 -280.075132)
		(width 0.1143)
		(layer "In11.Cu")
		(net "P5E_CPU1_P1_RX_DP<6>")
	)
	(segment
		(start 88.27643 -385.460494)
		(end 88.27643 -385.046982)
		(width 0.14224)
		(layer "In11.Cu")
		(net "P5E_CPU1_P1_RX_DP<6>")
	)
	(segment
		(start 85.78342 -372.528338)
		(end 89.409016 -367.399316)
		(width 0.14224)
		(layer "In11.Cu")
		(net "P5E_CPU1_P1_RX_DP<6>")
	)
	(segment
		(start 103.003096 -290.631626)
		(end 102.9335 -290.590986)
		(width 0.1143)
		(layer "In11.Cu")
		(net "P5E_CPU1_P1_RX_DP<6>")
	)
	(segment
		(start 118.827804 -324.63994)
		(end 111.978948 -316.295024)
		(width 0.14224)
		(layer "In11.Cu")
		(net "P5E_CPU1_P1_RX_DP<6>")
	)
	(segment
		(start 89.409016 -367.399316)
		(end 91.37904 -365.825532)
		(width 0.14224)
		(layer "In11.Cu")
		(net "P5E_CPU1_P1_RX_DP<6>")
	)
	(segment
		(start 119.700548 -326.309482)
		(end 118.827804 -324.63994)
		(width 0.14224)
		(layer "In11.Cu")
		(net "P5E_CPU1_P1_RX_DP<6>")
	)
	(segment
		(start 102.493318 -279.43429)
		(end 102.49408 -279.433782)
		(width 0.1143)
		(layer "In11.Cu")
		(net "P5E_CPU1_P1_RX_DP<6>")
	)
	(segment
		(start 104.180386 -276.599142)
		(end 104.26319 -276.516338)
		(width 0.1143)
		(layer "In11.Cu")
		(net "P5E_CPU1_P1_RX_DP<6>")
	)
	(segment
		(start 102.9335 -291.601398)
		(end 103.003096 -291.560758)
		(width 0.1143)
		(layer "In11.Cu")
		(net "P5E_CPU1_P1_RX_DP<6>")
	)
	(segment
		(start 102.9335 -285.121604)
		(end 103.003096 -285.080964)
		(width 0.1143)
		(layer "In11.Cu")
		(net "P5E_CPU1_P1_RX_DP<6>")
	)
	(segment
		(start 88.17483 -381.82804)
		(end 85.372956 -374.383046)
		(width 0.14224)
		(layer "In11.Cu")
		(net "P5E_CPU1_P1_RX_DP<6>")
	)
	(segment
		(start 102.526338 -280.097738)
		(end 102.525576 -280.09723)
		(width 0.1143)
		(layer "In11.Cu")
		(net "P5E_CPU1_P1_RX_DP<6>")
	)
	(segment
		(start 102.9335 -283.501592)
		(end 103.003096 -283.460952)
		(width 0.1143)
		(layer "In11.Cu")
		(net "P5E_CPU1_P1_RX_DP<6>")
	)
	(segment
		(start 103.402384 -277.832058)
		(end 103.427784 -277.817326)
		(width 0.1143)
		(layer "In11.Cu")
		(net "P5E_CPU1_P1_RX_DP<6>")
	)
	(segment
		(start 102.495096 -280.07945)
		(end 102.49408 -280.078942)
		(width 0.1143)
		(layer "In11.Cu")
		(net "P5E_CPU1_P1_RX_DP<6>")
	)
	(segment
		(start 104.26319 -276.516338)
		(end 104.561132 -276.516338)
		(width 0.1143)
		(layer "In11.Cu")
		(net "P5E_CPU1_P1_RX_DP<6>")
	)
	(segment
		(start 102.357174 -296.390822)
		(end 102.311454 -296.345102)
		(width 0.1143)
		(layer "In11.Cu")
		(net "P5E_CPU1_P1_RX_DP<6>")
	)
	(segment
		(start 102.931468 -288.362644)
		(end 102.96398 -288.343848)
		(width 0.1143)
		(layer "In11.Cu")
		(net "P5E_CPU1_P1_RX_DP<6>")
	)
	(segment
		(start 103.434134 -277.81377)
		(end 103.435658 -277.813008)
		(width 0.1143)
		(layer "In11.Cu")
		(net "P5E_CPU1_P1_RX_DP<6>")
	)
	(segment
		(start 119.700548 -326.309736)
		(end 119.700548 -326.309482)
		(width 0.14224)
		(layer "In11.Cu")
		(net "P5E_CPU1_P1_RX_DP<6>")
	)
	(segment
		(start 85.589872 -372.80215)
		(end 85.78342 -372.528338)
		(width 0.14224)
		(layer "In11.Cu")
		(net "P5E_CPU1_P1_RX_DP<6>")
	)
	(segment
		(start 91.37904 -365.825532)
		(end 95.31477 -363.501432)
		(width 0.14224)
		(layer "In11.Cu")
		(net "P5E_CPU1_P1_RX_DP<6>")
	)
	(segment
		(start 103.003096 -293.87165)
		(end 102.9335 -293.83101)
		(width 0.1143)
		(layer "In11.Cu")
		(net "P5E_CPU1_P1_RX_DP<6>")
	)
	(segment
		(start 122.527822 -338.829904)
		(end 120.579896 -327.991978)
		(width 0.14224)
		(layer "In11.Cu")
		(net "P5E_CPU1_P1_RX_DP<6>")
	)
	(segment
		(start 102.9335 -281.88158)
		(end 103.003096 -281.84094)
		(width 0.1143)
		(layer "In11.Cu")
		(net "P5E_CPU1_P1_RX_DP<6>")
	)
	(segment
		(start 87.919052 -386.003292)
		(end 88.014048 -385.649216)
		(width 0.14224)
		(layer "In11.Cu")
		(net "P5E_CPU1_P1_RX_DP<6>")
	)
	(segment
		(start 102.776528 -295.155112)
		(end 102.776528 -295.146222)
		(width 0.1143)
		(layer "In11.Cu")
		(net "P5E_CPU1_P1_RX_DP<6>")
	)
	(segment
		(start 103.003096 -285.771844)
		(end 102.9335 -285.731204)
		(width 0.1143)
		(layer "In11.Cu")
		(net "P5E_CPU1_P1_RX_DP<6>")
	)
	(segment
		(start 102.431342 -295.824148)
		(end 102.54742 -295.70807)
		(width 0.1143)
		(layer "In11.Cu")
		(net "P5E_CPU1_P1_RX_DP<6>")
	)
	(segment
		(start 102.9335 -278.641556)
		(end 103.003096 -278.600916)
		(width 0.1143)
		(layer "In11.Cu")
		(net "P5E_CPU1_P1_RX_DP<6>")
	)
	(segment
		(start 102.533196 -280.101802)
		(end 102.526338 -280.097738)
		(width 0.1143)
		(layer "In11.Cu")
		(net "P5E_CPU1_P1_RX_DP<6>")
	)
	(segment
		(start 102.490524 -279.435814)
		(end 102.493318 -279.43429)
		(width 0.1143)
		(layer "In11.Cu")
		(net "P5E_CPU1_P1_RX_DP<6>")
	)
	(segment
		(start 87.960454 -384.731006)
		(end 87.963502 -384.352546)
		(width 0.14224)
		(layer "In11.Cu")
		(net "P5E_CPU1_P1_RX_DP<6>")
	)
	(segment
		(start 103.003096 -289.011614)
		(end 102.9335 -288.970974)
		(width 0.1143)
		(layer "In11.Cu")
		(net "P5E_CPU1_P1_RX_DP<6>")
	)
	(segment
		(start 102.490524 -280.07691)
		(end 102.489762 -280.076402)
		(width 0.1143)
		(layer "In11.Cu")
		(net "P5E_CPU1_P1_RX_DP<6>")
	)
	(segment
		(start 103.003096 -282.53182)
		(end 102.9335 -282.49118)
		(width 0.1143)
		(layer "In11.Cu")
		(net "P5E_CPU1_P1_RX_DP<6>")
	)
	(segment
		(start 103.433372 -277.814278)
		(end 103.434134 -277.81377)
		(width 0.1143)
		(layer "In11.Cu")
		(net "P5E_CPU1_P1_RX_DP<6>")
	)
	(segment
		(start 102.489762 -279.436322)
		(end 102.490524 -279.435814)
		(width 0.1143)
		(layer "In11.Cu")
		(net "P5E_CPU1_P1_RX_DP<6>")
	)
	(segment
		(start 102.9335 -294.841422)
		(end 103.003096 -294.800782)
		(width 0.1143)
		(layer "In11.Cu")
		(net "P5E_CPU1_P1_RX_DP<6>")
	)
	(arc
		(start 103.003096 -288.320988)
		(mid 103.181909 -288.118638)
		(end 103.246428 -287.856422)
		(width 0.1143)
		(layer "In11.Cu")
		(net "P5E_CPU1_P1_RX_DP<6>")
	)
	(arc
		(start 88.268302 -382.342136)
		(mid 88.244772 -382.080868)
		(end 88.17483 -381.82804)
		(width 0.14224)
		(layer "In11.Cu")
		(net "P5E_CPU1_P1_RX_DP<6>")
	)
	(arc
		(start 102.46233 -280.060654)
		(mid 102.306402 -279.756362)
		(end 102.46233 -279.45207)
		(width 0.1143)
		(layer "In11.Cu")
		(net "P5E_CPU1_P1_RX_DP<6>")
	)
	(arc
		(start 102.776528 -288.666174)
		(mid 102.817494 -288.495768)
		(end 102.931468 -288.362644)
		(width 0.1143)
		(layer "In11.Cu")
		(net "P5E_CPU1_P1_RX_DP<6>")
	)
	(arc
		(start 104.176576 -276.622002)
		(mid 104.178599 -276.610592)
		(end 104.180386 -276.599142)
		(width 0.1143)
		(layer "In11.Cu")
		(net "P5E_CPU1_P1_RX_DP<6>")
	)
	(arc
		(start 85.447632 -373.090186)
		(mid 85.507448 -372.940585)
		(end 85.589872 -372.80215)
		(width 0.14224)
		(layer "In11.Cu")
		(net "P5E_CPU1_P1_RX_DP<6>")
	)
	(arc
		(start 103.003096 -291.560758)
		(mid 103.246423 -291.096192)
		(end 103.003096 -290.631626)
		(width 0.1143)
		(layer "In11.Cu")
		(net "P5E_CPU1_P1_RX_DP<6>")
	)
	(arc
		(start 103.003096 -286.700976)
		(mid 103.246423 -286.23641)
		(end 103.003096 -285.771844)
		(width 0.1143)
		(layer "In11.Cu")
		(net "P5E_CPU1_P1_RX_DP<6>")
	)
	(arc
		(start 103.003096 -294.800782)
		(mid 103.246423 -294.336216)
		(end 103.003096 -293.87165)
		(width 0.1143)
		(layer "In11.Cu")
		(net "P5E_CPU1_P1_RX_DP<6>")
	)
	(arc
		(start 102.776528 -295.146222)
		(mid 102.818077 -294.9748)
		(end 102.9335 -294.841422)
		(width 0.1143)
		(layer "In11.Cu")
		(net "P5E_CPU1_P1_RX_DP<6>")
	)
	(arc
		(start 103.94315 -276.980904)
		(mid 104.095137 -276.824396)
		(end 104.176576 -276.622002)
		(width 0.1143)
		(layer "In11.Cu")
		(net "P5E_CPU1_P1_RX_DP<6>")
	)
	(arc
		(start 102.776528 -278.946356)
		(mid 102.818077 -278.774934)
		(end 102.9335 -278.641556)
		(width 0.1143)
		(layer "In11.Cu")
		(net "P5E_CPU1_P1_RX_DP<6>")
	)
	(arc
		(start 103.246428 -278.13635)
		(mid 103.287683 -277.965379)
		(end 103.402384 -277.832058)
		(width 0.1143)
		(layer "In11.Cu")
		(net "P5E_CPU1_P1_RX_DP<6>")
	)
	(arc
		(start 102.9335 -284.111192)
		(mid 102.776523 -283.806392)
		(end 102.9335 -283.501592)
		(width 0.1143)
		(layer "In11.Cu")
		(net "P5E_CPU1_P1_RX_DP<6>")
	)
	(arc
		(start 102.54742 -295.70807)
		(mid 102.71699 -295.454385)
		(end 102.776528 -295.155112)
		(width 0.1143)
		(layer "In11.Cu")
		(net "P5E_CPU1_P1_RX_DP<6>")
	)
	(arc
		(start 103.003096 -283.460952)
		(mid 103.246423 -282.996386)
		(end 103.003096 -282.53182)
		(width 0.1143)
		(layer "In11.Cu")
		(net "P5E_CPU1_P1_RX_DP<6>")
	)
	(arc
		(start 102.9335 -293.83101)
		(mid 102.776523 -293.52621)
		(end 102.9335 -293.22141)
		(width 0.1143)
		(layer "In11.Cu")
		(net "P5E_CPU1_P1_RX_DP<6>")
	)
	(arc
		(start 102.776528 -280.566368)
		(mid 102.712013 -280.304149)
		(end 102.533196 -280.101802)
		(width 0.1143)
		(layer "In11.Cu")
		(net "P5E_CPU1_P1_RX_DP<6>")
	)
	(arc
		(start 103.003096 -285.080964)
		(mid 103.246423 -284.616398)
		(end 103.003096 -284.151832)
		(width 0.1143)
		(layer "In11.Cu")
		(net "P5E_CPU1_P1_RX_DP<6>")
	)
	(arc
		(start 102.9335 -288.970974)
		(mid 102.818073 -288.837598)
		(end 102.776528 -288.666174)
		(width 0.1143)
		(layer "In11.Cu")
		(net "P5E_CPU1_P1_RX_DP<6>")
	)
	(arc
		(start 103.470456 -277.792688)
		(mid 103.486425 -277.780651)
		(end 103.501952 -277.76805)
		(width 0.1143)
		(layer "In11.Cu")
		(net "P5E_CPU1_P1_RX_DP<6>")
	)
	(arc
		(start 103.501952 -277.76805)
		(mid 103.63437 -277.594869)
		(end 103.708454 -277.389844)
		(width 0.1143)
		(layer "In11.Cu")
		(net "P5E_CPU1_P1_RX_DP<6>")
	)
	(arc
		(start 103.708454 -277.389844)
		(mid 103.713933 -277.352669)
		(end 103.716328 -277.315168)
		(width 0.1143)
		(layer "In11.Cu")
		(net "P5E_CPU1_P1_RX_DP<6>")
	)
	(arc
		(start 102.9335 -290.590986)
		(mid 102.776523 -290.286186)
		(end 102.9335 -289.981386)
		(width 0.1143)
		(layer "In11.Cu")
		(net "P5E_CPU1_P1_RX_DP<6>")
	)
	(arc
		(start 102.9335 -287.350962)
		(mid 102.818073 -287.217586)
		(end 102.776528 -287.046162)
		(width 0.1143)
		(layer "In11.Cu")
		(net "P5E_CPU1_P1_RX_DP<6>")
	)
	(arc
		(start 103.003096 -293.18077)
		(mid 103.246423 -292.716204)
		(end 103.003096 -292.251638)
		(width 0.1143)
		(layer "In11.Cu")
		(net "P5E_CPU1_P1_RX_DP<6>")
	)
	(arc
		(start 102.9335 -285.731204)
		(mid 102.776523 -285.426404)
		(end 102.9335 -285.121604)
		(width 0.1143)
		(layer "In11.Cu")
		(net "P5E_CPU1_P1_RX_DP<6>")
	)
	(arc
		(start 103.003096 -278.600916)
		(mid 103.181909 -278.398566)
		(end 103.246428 -278.13635)
		(width 0.1143)
		(layer "In11.Cu")
		(net "P5E_CPU1_P1_RX_DP<6>")
	)
	(arc
		(start 103.003096 -289.940746)
		(mid 103.246423 -289.47618)
		(end 103.003096 -289.011614)
		(width 0.1143)
		(layer "In11.Cu")
		(net "P5E_CPU1_P1_RX_DP<6>")
	)
	(arc
		(start 102.9335 -292.210998)
		(mid 102.776523 -291.906198)
		(end 102.9335 -291.601398)
		(width 0.1143)
		(layer "In11.Cu")
		(net "P5E_CPU1_P1_RX_DP<6>")
	)
	(arc
		(start 85.372956 -374.383046)
		(mid 85.360729 -374.335289)
		(end 85.358986 -374.286018)
		(width 0.14224)
		(layer "In11.Cu")
		(net "P5E_CPU1_P1_RX_DP<6>")
	)
	(arc
		(start 119.601234 -347.273372)
		(mid 120.299847 -346.640285)
		(end 120.78462 -345.831668)
		(width 0.14224)
		(layer "In11.Cu")
		(net "P5E_CPU1_P1_RX_DP<6>")
	)
	(arc
		(start 103.716328 -277.315168)
		(mid 103.760392 -277.149945)
		(end 103.8733 -277.021544)
		(width 0.1143)
		(layer "In11.Cu")
		(net "P5E_CPU1_P1_RX_DP<6>")
	)
	(arc
		(start 103.246428 -287.856422)
		(mid 103.181192 -287.592831)
		(end 103.000556 -287.390078)
		(width 0.1143)
		(layer "In11.Cu")
		(net "P5E_CPU1_P1_RX_DP<6>")
	)
	(arc
		(start 102.776528 -287.046162)
		(mid 102.817494 -286.875756)
		(end 102.931468 -286.742632)
		(width 0.1143)
		(layer "In11.Cu")
		(net "P5E_CPU1_P1_RX_DP<6>")
	)
	(arc
		(start 102.311454 -296.113708)
		(mid 102.342606 -295.957005)
		(end 102.431342 -295.824148)
		(width 0.1143)
		(layer "In11.Cu")
		(net "P5E_CPU1_P1_RX_DP<6>")
	)
	(arc
		(start 102.9335 -280.871168)
		(mid 102.818073 -280.737792)
		(end 102.776528 -280.566368)
		(width 0.1143)
		(layer "In11.Cu")
		(net "P5E_CPU1_P1_RX_DP<6>")
	)
	(arc
		(start 103.003096 -281.84094)
		(mid 103.246423 -281.376374)
		(end 103.003096 -280.911808)
		(width 0.1143)
		(layer "In11.Cu")
		(net "P5E_CPU1_P1_RX_DP<6>")
	)
	(arc
		(start 102.9335 -282.49118)
		(mid 102.776523 -282.18638)
		(end 102.9335 -281.88158)
		(width 0.1143)
		(layer "In11.Cu")
		(net "P5E_CPU1_P1_RX_DP<6>")
	)
	(arc
		(start 102.533196 -279.410922)
		(mid 102.712009 -279.208572)
		(end 102.776528 -278.946356)
		(width 0.1143)
		(layer "In11.Cu")
		(net "P5E_CPU1_P1_RX_DP<6>")
	)
	(segment
		(start 102.207822 -274.630388)
		(end 101.74097 -274.896326)
		(width 0.12954)
		(layer "F.Cu")
		(net "P5E_CPU1_P1_RX_DP<5>")
	)
	(segment
		(start 86.198456 -386.003292)
		(end 86.719156 -386.003292)
		(width 0.127)
		(layer "F.Cu")
		(net "P5E_CPU1_P1_RX_DP<5>")
	)
	(segment
		(start 102.063042 -292.251638)
		(end 101.993446 -292.210998)
		(width 0.1143)
		(layer "In11.Cu")
		(net "P5E_CPU1_P1_RX_DP<5>")
	)
	(segment
		(start 101.585522 -280.09723)
		(end 101.555042 -280.07945)
		(width 0.1143)
		(layer "In11.Cu")
		(net "P5E_CPU1_P1_RX_DP<5>")
	)
	(segment
		(start 101.554026 -279.433782)
		(end 101.555042 -279.433274)
		(width 0.1143)
		(layer "In11.Cu")
		(net "P5E_CPU1_P1_RX_DP<5>")
	)
	(segment
		(start 101.554026 -280.078942)
		(end 101.553264 -280.078434)
		(width 0.1143)
		(layer "In11.Cu")
		(net "P5E_CPU1_P1_RX_DP<5>")
	)
	(segment
		(start 121.531126 -341.414354)
		(end 121.531126 -338.625942)
		(width 0.14224)
		(layer "In11.Cu")
		(net "P5E_CPU1_P1_RX_DP<5>")
	)
	(segment
		(start 120.014492 -345.075002)
		(end 121.531126 -341.414354)
		(width 0.14224)
		(layer "In11.Cu")
		(net "P5E_CPU1_P1_RX_DP<5>")
	)
	(segment
		(start 87.076534 -385.046982)
		(end 86.760558 -384.731006)
		(width 0.14224)
		(layer "In11.Cu")
		(net "P5E_CPU1_P1_RX_DP<5>")
	)
	(segment
		(start 101.553264 -279.43429)
		(end 101.554026 -279.433782)
		(width 0.1143)
		(layer "In11.Cu")
		(net "P5E_CPU1_P1_RX_DP<5>")
	)
	(segment
		(start 101.522276 -280.060654)
		(end 101.502464 -280.04643)
		(width 0.1143)
		(layer "In11.Cu")
		(net "P5E_CPU1_P1_RX_DP<5>")
	)
	(segment
		(start 102.063042 -289.011614)
		(end 101.993446 -288.970974)
		(width 0.1143)
		(layer "In11.Cu")
		(net "P5E_CPU1_P1_RX_DP<5>")
	)
	(segment
		(start 102.063042 -290.631626)
		(end 101.993446 -290.590986)
		(width 0.1143)
		(layer "In11.Cu")
		(net "P5E_CPU1_P1_RX_DP<5>")
	)
	(segment
		(start 111.228378 -316.850268)
		(end 105.088944 -307.662072)
		(width 0.14224)
		(layer "In11.Cu")
		(net "P5E_CPU1_P1_RX_DP<5>")
	)
	(segment
		(start 101.55555 -275.2217)
		(end 101.547422 -275.216874)
		(width 0.1143)
		(layer "In11.Cu")
		(net "P5E_CPU1_P1_RX_DP<5>")
	)
	(segment
		(start 101.548946 -295.636188)
		(end 101.556058 -295.632124)
		(width 0.1143)
		(layer "In11.Cu")
		(net "P5E_CPU1_P1_RX_DP<5>")
	)
	(segment
		(start 84.79409 -372.056152)
		(end 88.52281 -366.785906)
		(width 0.14224)
		(layer "In11.Cu")
		(net "P5E_CPU1_P1_RX_DP<5>")
	)
	(segment
		(start 101.991414 -286.742632)
		(end 102.023926 -286.723836)
		(width 0.1143)
		(layer "In11.Cu")
		(net "P5E_CPU1_P1_RX_DP<5>")
	)
	(segment
		(start 85.584538 -377.836684)
		(end 84.41944 -374.593104)
		(width 0.14224)
		(layer "In11.Cu")
		(net "P5E_CPU1_P1_RX_DP<5>")
	)
	(segment
		(start 85.823552 -378.502672)
		(end 85.586824 -377.843542)
		(width 0.14224)
		(layer "In11.Cu")
		(net "P5E_CPU1_P1_RX_DP<5>")
	)
	(segment
		(start 101.993446 -278.641556)
		(end 102.063042 -278.600916)
		(width 0.1143)
		(layer "In11.Cu")
		(net "P5E_CPU1_P1_RX_DP<5>")
	)
	(segment
		(start 102.063042 -293.87165)
		(end 101.993446 -293.83101)
		(width 0.1143)
		(layer "In11.Cu")
		(net "P5E_CPU1_P1_RX_DP<5>")
	)
	(segment
		(start 91.290394 -364.575344)
		(end 96.9518 -361.233212)
		(width 0.14224)
		(layer "In11.Cu")
		(net "P5E_CPU1_P1_RX_DP<5>")
	)
	(segment
		(start 102.060502 -287.390078)
		(end 101.993446 -287.350962)
		(width 0.1143)
		(layer "In11.Cu")
		(net "P5E_CPU1_P1_RX_DP<5>")
	)
	(segment
		(start 101.993446 -281.88158)
		(end 102.063042 -281.84094)
		(width 0.1143)
		(layer "In11.Cu")
		(net "P5E_CPU1_P1_RX_DP<5>")
	)
	(segment
		(start 101.993446 -289.981386)
		(end 102.063042 -289.940746)
		(width 0.1143)
		(layer "In11.Cu")
		(net "P5E_CPU1_P1_RX_DP<5>")
	)
	(segment
		(start 88.52281 -366.785906)
		(end 91.290394 -364.575344)
		(width 0.14224)
		(layer "In11.Cu")
		(net "P5E_CPU1_P1_RX_DP<5>")
	)
	(segment
		(start 86.760558 -384.731006)
		(end 86.763606 -384.352546)
		(width 0.14224)
		(layer "In11.Cu")
		(net "P5E_CPU1_P1_RX_DP<5>")
	)
	(segment
		(start 101.993446 -294.841422)
		(end 102.063042 -294.800782)
		(width 0.1143)
		(layer "In11.Cu")
		(net "P5E_CPU1_P1_RX_DP<5>")
	)
	(segment
		(start 101.553264 -280.078434)
		(end 101.522276 -280.060654)
		(width 0.1143)
		(layer "In11.Cu")
		(net "P5E_CPU1_P1_RX_DP<5>")
	)
	(segment
		(start 87.076534 -385.460494)
		(end 87.076534 -385.046982)
		(width 0.14224)
		(layer "In11.Cu")
		(net "P5E_CPU1_P1_RX_DP<5>")
	)
	(segment
		(start 101.412294 -296.463974)
		(end 101.412294 -296.435526)
		(width 0.1143)
		(layer "In11.Cu")
		(net "P5E_CPU1_P1_RX_DP<5>")
	)
	(segment
		(start 101.993446 -291.601398)
		(end 102.063042 -291.560758)
		(width 0.1143)
		(layer "In11.Cu")
		(net "P5E_CPU1_P1_RX_DP<5>")
	)
	(segment
		(start 101.993446 -293.22141)
		(end 102.063042 -293.18077)
		(width 0.1143)
		(layer "In11.Cu")
		(net "P5E_CPU1_P1_RX_DP<5>")
	)
	(segment
		(start 102.063042 -285.771844)
		(end 101.993446 -285.731204)
		(width 0.1143)
		(layer "In11.Cu")
		(net "P5E_CPU1_P1_RX_DP<5>")
	)
	(segment
		(start 119.667782 -328.259694)
		(end 118.0465 -325.1581)
		(width 0.14224)
		(layer "In11.Cu")
		(net "P5E_CPU1_P1_RX_DP<5>")
	)
	(segment
		(start 101.522276 -279.45207)
		(end 101.553264 -279.43429)
		(width 0.1143)
		(layer "In11.Cu")
		(net "P5E_CPU1_P1_RX_DP<5>")
	)
	(segment
		(start 102.063042 -276.051772)
		(end 101.99243 -276.01037)
		(width 0.1143)
		(layer "In11.Cu")
		(net "P5E_CPU1_P1_RX_DP<5>")
	)
	(segment
		(start 101.452426 -295.732708)
		(end 101.548946 -295.636188)
		(width 0.1143)
		(layer "In11.Cu")
		(net "P5E_CPU1_P1_RX_DP<5>")
	)
	(segment
		(start 102.063042 -280.911808)
		(end 101.993446 -280.871168)
		(width 0.1143)
		(layer "In11.Cu")
		(net "P5E_CPU1_P1_RX_DP<5>")
	)
	(segment
		(start 86.814152 -385.649216)
		(end 86.988396 -385.548632)
		(width 0.14224)
		(layer "In11.Cu")
		(net "P5E_CPU1_P1_RX_DP<5>")
	)
	(segment
		(start 86.988396 -385.548632)
		(end 87.076534 -385.460494)
		(width 0.14224)
		(layer "In11.Cu")
		(net "P5E_CPU1_P1_RX_DP<5>")
	)
	(segment
		(start 102.023926 -288.343848)
		(end 102.063042 -288.320988)
		(width 0.1143)
		(layer "In11.Cu")
		(net "P5E_CPU1_P1_RX_DP<5>")
	)
	(segment
		(start 102.023926 -286.723836)
		(end 102.063042 -286.700976)
		(width 0.1143)
		(layer "In11.Cu")
		(net "P5E_CPU1_P1_RX_DP<5>")
	)
	(segment
		(start 101.366574 -296.389806)
		(end 101.366574 -295.939972)
		(width 0.1143)
		(layer "In11.Cu")
		(net "P5E_CPU1_P1_RX_DP<5>")
	)
	(segment
		(start 101.993446 -283.501592)
		(end 102.063042 -283.460952)
		(width 0.1143)
		(layer "In11.Cu")
		(net "P5E_CPU1_P1_RX_DP<5>")
	)
	(segment
		(start 101.993446 -285.121604)
		(end 102.063042 -285.080964)
		(width 0.1143)
		(layer "In11.Cu")
		(net "P5E_CPU1_P1_RX_DP<5>")
	)
	(segment
		(start 101.443028 -274.896326)
		(end 101.74097 -274.896326)
		(width 0.1143)
		(layer "In11.Cu")
		(net "P5E_CPU1_P1_RX_DP<5>")
	)
	(segment
		(start 101.555042 -280.07945)
		(end 101.554026 -280.078942)
		(width 0.1143)
		(layer "In11.Cu")
		(net "P5E_CPU1_P1_RX_DP<5>")
	)
	(segment
		(start 101.993446 -277.021544)
		(end 102.063042 -276.980904)
		(width 0.1143)
		(layer "In11.Cu")
		(net "P5E_CPU1_P1_RX_DP<5>")
	)
	(segment
		(start 102.063042 -282.53182)
		(end 101.993446 -282.49118)
		(width 0.1143)
		(layer "In11.Cu")
		(net "P5E_CPU1_P1_RX_DP<5>")
	)
	(segment
		(start 101.991414 -288.362644)
		(end 102.023926 -288.343848)
		(width 0.1143)
		(layer "In11.Cu")
		(net "P5E_CPU1_P1_RX_DP<5>")
	)
	(segment
		(start 87.068406 -384.047746)
		(end 87.068406 -382.374648)
		(width 0.14224)
		(layer "In11.Cu")
		(net "P5E_CPU1_P1_RX_DP<5>")
	)
	(segment
		(start 121.531126 -338.625942)
		(end 119.667782 -328.259694)
		(width 0.14224)
		(layer "In11.Cu")
		(net "P5E_CPU1_P1_RX_DP<5>")
	)
	(segment
		(start 101.373178 -274.966176)
		(end 101.443028 -274.896326)
		(width 0.1143)
		(layer "In11.Cu")
		(net "P5E_CPU1_P1_RX_DP<5>")
	)
	(segment
		(start 84.360004 -374.132094)
		(end 84.464906 -372.95201)
		(width 0.14224)
		(layer "In11.Cu")
		(net "P5E_CPU1_P1_RX_DP<5>")
	)
	(segment
		(start 101.556566 -279.432258)
		(end 101.593142 -279.410922)
		(width 0.1143)
		(layer "In11.Cu")
		(net "P5E_CPU1_P1_RX_DP<5>")
	)
	(segment
		(start 105.088944 -307.662072)
		(end 101.412294 -298.786296)
		(width 0.14224)
		(layer "In11.Cu")
		(net "P5E_CPU1_P1_RX_DP<5>")
	)
	(segment
		(start 101.412294 -298.786296)
		(end 101.412294 -296.463974)
		(width 0.14224)
		(layer "In11.Cu")
		(net "P5E_CPU1_P1_RX_DP<5>")
	)
	(segment
		(start 85.825584 -378.508768)
		(end 85.823552 -378.502672)
		(width 0.14224)
		(layer "In11.Cu")
		(net "P5E_CPU1_P1_RX_DP<5>")
	)
	(segment
		(start 96.9518 -361.233212)
		(end 118.655338 -346.731082)
		(width 0.14224)
		(layer "In11.Cu")
		(net "P5E_CPU1_P1_RX_DP<5>")
	)
	(segment
		(start 118.0465 -325.1581)
		(end 111.228378 -316.850268)
		(width 0.14224)
		(layer "In11.Cu")
		(net "P5E_CPU1_P1_RX_DP<5>")
	)
	(segment
		(start 101.555042 -279.433274)
		(end 101.556566 -279.432258)
		(width 0.1143)
		(layer "In11.Cu")
		(net "P5E_CPU1_P1_RX_DP<5>")
	)
	(segment
		(start 101.502464 -279.466294)
		(end 101.522276 -279.45207)
		(width 0.1143)
		(layer "In11.Cu")
		(net "P5E_CPU1_P1_RX_DP<5>")
	)
	(segment
		(start 86.763606 -384.352546)
		(end 87.068406 -384.047746)
		(width 0.14224)
		(layer "In11.Cu")
		(net "P5E_CPU1_P1_RX_DP<5>")
	)
	(segment
		(start 86.931754 -381.588518)
		(end 85.825584 -378.508768)
		(width 0.14224)
		(layer "In11.Cu")
		(net "P5E_CPU1_P1_RX_DP<5>")
	)
	(segment
		(start 85.586824 -377.843542)
		(end 85.584538 -377.836684)
		(width 0.14224)
		(layer "In11.Cu")
		(net "P5E_CPU1_P1_RX_DP<5>")
	)
	(segment
		(start 86.719156 -386.003292)
		(end 86.814152 -385.649216)
		(width 0.14224)
		(layer "In11.Cu")
		(net "P5E_CPU1_P1_RX_DP<5>")
	)
	(segment
		(start 101.586284 -280.097738)
		(end 101.585522 -280.09723)
		(width 0.1143)
		(layer "In11.Cu")
		(net "P5E_CPU1_P1_RX_DP<5>")
	)
	(segment
		(start 101.593142 -280.101802)
		(end 101.586284 -280.097738)
		(width 0.1143)
		(layer "In11.Cu")
		(net "P5E_CPU1_P1_RX_DP<5>")
	)
	(segment
		(start 102.063042 -284.151832)
		(end 101.993446 -284.111192)
		(width 0.1143)
		(layer "In11.Cu")
		(net "P5E_CPU1_P1_RX_DP<5>")
	)
	(segment
		(start 101.412294 -296.435526)
		(end 101.366574 -296.389806)
		(width 0.1143)
		(layer "In11.Cu")
		(net "P5E_CPU1_P1_RX_DP<5>")
	)
	(segment
		(start 102.063042 -277.671784)
		(end 101.993446 -277.631144)
		(width 0.1143)
		(layer "In11.Cu")
		(net "P5E_CPU1_P1_RX_DP<5>")
	)
	(arc
		(start 102.063042 -276.980904)
		(mid 102.306369 -276.516338)
		(end 102.063042 -276.051772)
		(width 0.1143)
		(layer "In11.Cu")
		(net "P5E_CPU1_P1_RX_DP<5>")
	)
	(arc
		(start 101.836474 -278.946356)
		(mid 101.878023 -278.774934)
		(end 101.993446 -278.641556)
		(width 0.1143)
		(layer "In11.Cu")
		(net "P5E_CPU1_P1_RX_DP<5>")
	)
	(arc
		(start 101.993446 -290.590986)
		(mid 101.836469 -290.286186)
		(end 101.993446 -289.981386)
		(width 0.1143)
		(layer "In11.Cu")
		(net "P5E_CPU1_P1_RX_DP<5>")
	)
	(arc
		(start 84.41944 -374.593104)
		(mid 84.364645 -374.365832)
		(end 84.360004 -374.132094)
		(width 0.14224)
		(layer "In11.Cu")
		(net "P5E_CPU1_P1_RX_DP<5>")
	)
	(arc
		(start 102.306374 -287.856422)
		(mid 102.241138 -287.592831)
		(end 102.060502 -287.390078)
		(width 0.1143)
		(layer "In11.Cu")
		(net "P5E_CPU1_P1_RX_DP<5>")
	)
	(arc
		(start 102.063042 -293.18077)
		(mid 102.306369 -292.716204)
		(end 102.063042 -292.251638)
		(width 0.1143)
		(layer "In11.Cu")
		(net "P5E_CPU1_P1_RX_DP<5>")
	)
	(arc
		(start 101.993446 -285.731204)
		(mid 101.836469 -285.426404)
		(end 101.993446 -285.121604)
		(width 0.1143)
		(layer "In11.Cu")
		(net "P5E_CPU1_P1_RX_DP<5>")
	)
	(arc
		(start 101.82352 -295.170606)
		(mid 101.86863 -294.985452)
		(end 101.993446 -294.841422)
		(width 0.1143)
		(layer "In11.Cu")
		(net "P5E_CPU1_P1_RX_DP<5>")
	)
	(arc
		(start 101.993446 -284.111192)
		(mid 101.836469 -283.806392)
		(end 101.993446 -283.501592)
		(width 0.1143)
		(layer "In11.Cu")
		(net "P5E_CPU1_P1_RX_DP<5>")
	)
	(arc
		(start 101.836474 -280.566368)
		(mid 101.771959 -280.304149)
		(end 101.593142 -280.101802)
		(width 0.1143)
		(layer "In11.Cu")
		(net "P5E_CPU1_P1_RX_DP<5>")
	)
	(arc
		(start 87.068406 -382.374648)
		(mid 87.034025 -381.975684)
		(end 86.931754 -381.588518)
		(width 0.14224)
		(layer "In11.Cu")
		(net "P5E_CPU1_P1_RX_DP<5>")
	)
	(arc
		(start 102.063042 -285.080964)
		(mid 102.306369 -284.616398)
		(end 102.063042 -284.151832)
		(width 0.1143)
		(layer "In11.Cu")
		(net "P5E_CPU1_P1_RX_DP<5>")
	)
	(arc
		(start 102.063042 -288.320988)
		(mid 102.241855 -288.118638)
		(end 102.306374 -287.856422)
		(width 0.1143)
		(layer "In11.Cu")
		(net "P5E_CPU1_P1_RX_DP<5>")
	)
	(arc
		(start 101.993446 -280.871168)
		(mid 101.878019 -280.737792)
		(end 101.836474 -280.566368)
		(width 0.1143)
		(layer "In11.Cu")
		(net "P5E_CPU1_P1_RX_DP<5>")
	)
	(arc
		(start 101.993446 -282.49118)
		(mid 101.836469 -282.18638)
		(end 101.993446 -281.88158)
		(width 0.1143)
		(layer "In11.Cu")
		(net "P5E_CPU1_P1_RX_DP<5>")
	)
	(arc
		(start 102.063042 -286.700976)
		(mid 102.306369 -286.23641)
		(end 102.063042 -285.771844)
		(width 0.1143)
		(layer "In11.Cu")
		(net "P5E_CPU1_P1_RX_DP<5>")
	)
	(arc
		(start 101.836474 -288.666174)
		(mid 101.87744 -288.495768)
		(end 101.991414 -288.362644)
		(width 0.1143)
		(layer "In11.Cu")
		(net "P5E_CPU1_P1_RX_DP<5>")
	)
	(arc
		(start 101.366574 -295.939972)
		(mid 101.388886 -295.827801)
		(end 101.452426 -295.732708)
		(width 0.1143)
		(layer "In11.Cu")
		(net "P5E_CPU1_P1_RX_DP<5>")
	)
	(arc
		(start 101.502464 -280.04643)
		(mid 101.35375 -279.756362)
		(end 101.502464 -279.466294)
		(width 0.1143)
		(layer "In11.Cu")
		(net "P5E_CPU1_P1_RX_DP<5>")
	)
	(arc
		(start 118.655338 -346.731082)
		(mid 119.457709 -346.003823)
		(end 120.014492 -345.075002)
		(width 0.14224)
		(layer "In11.Cu")
		(net "P5E_CPU1_P1_RX_DP<5>")
	)
	(arc
		(start 101.836474 -287.046162)
		(mid 101.87744 -286.875756)
		(end 101.991414 -286.742632)
		(width 0.1143)
		(layer "In11.Cu")
		(net "P5E_CPU1_P1_RX_DP<5>")
	)
	(arc
		(start 101.993446 -292.210998)
		(mid 101.836469 -291.906198)
		(end 101.993446 -291.601398)
		(width 0.1143)
		(layer "In11.Cu")
		(net "P5E_CPU1_P1_RX_DP<5>")
	)
	(arc
		(start 101.993446 -277.631144)
		(mid 101.836469 -277.326344)
		(end 101.993446 -277.021544)
		(width 0.1143)
		(layer "In11.Cu")
		(net "P5E_CPU1_P1_RX_DP<5>")
	)
	(arc
		(start 102.063042 -289.940746)
		(mid 102.306369 -289.47618)
		(end 102.063042 -289.011614)
		(width 0.1143)
		(layer "In11.Cu")
		(net "P5E_CPU1_P1_RX_DP<5>")
	)
	(arc
		(start 101.993446 -288.970974)
		(mid 101.878019 -288.837598)
		(end 101.836474 -288.666174)
		(width 0.1143)
		(layer "In11.Cu")
		(net "P5E_CPU1_P1_RX_DP<5>")
	)
	(arc
		(start 101.83622 -275.706332)
		(mid 101.760992 -275.426305)
		(end 101.55555 -275.2217)
		(width 0.1143)
		(layer "In11.Cu")
		(net "P5E_CPU1_P1_RX_DP<5>")
	)
	(arc
		(start 101.547422 -275.216874)
		(mid 101.433546 -275.110116)
		(end 101.373178 -274.966176)
		(width 0.1143)
		(layer "In11.Cu")
		(net "P5E_CPU1_P1_RX_DP<5>")
	)
	(arc
		(start 102.063042 -291.560758)
		(mid 102.306369 -291.096192)
		(end 102.063042 -290.631626)
		(width 0.1143)
		(layer "In11.Cu")
		(net "P5E_CPU1_P1_RX_DP<5>")
	)
	(arc
		(start 101.993446 -287.350962)
		(mid 101.878019 -287.217586)
		(end 101.836474 -287.046162)
		(width 0.1143)
		(layer "In11.Cu")
		(net "P5E_CPU1_P1_RX_DP<5>")
	)
	(arc
		(start 84.464906 -372.95201)
		(mid 84.570134 -372.48227)
		(end 84.79409 -372.056152)
		(width 0.14224)
		(layer "In11.Cu")
		(net "P5E_CPU1_P1_RX_DP<5>")
	)
	(arc
		(start 101.99243 -276.01037)
		(mid 101.877587 -275.877222)
		(end 101.83622 -275.706332)
		(width 0.1143)
		(layer "In11.Cu")
		(net "P5E_CPU1_P1_RX_DP<5>")
	)
	(arc
		(start 101.593142 -279.410922)
		(mid 101.771955 -279.208572)
		(end 101.836474 -278.946356)
		(width 0.1143)
		(layer "In11.Cu")
		(net "P5E_CPU1_P1_RX_DP<5>")
	)
	(arc
		(start 102.063042 -294.800782)
		(mid 102.306369 -294.336216)
		(end 102.063042 -293.87165)
		(width 0.1143)
		(layer "In11.Cu")
		(net "P5E_CPU1_P1_RX_DP<5>")
	)
	(arc
		(start 102.063042 -278.600916)
		(mid 102.306369 -278.13635)
		(end 102.063042 -277.671784)
		(width 0.1143)
		(layer "In11.Cu")
		(net "P5E_CPU1_P1_RX_DP<5>")
	)
	(arc
		(start 101.993446 -293.83101)
		(mid 101.836469 -293.52621)
		(end 101.993446 -293.22141)
		(width 0.1143)
		(layer "In11.Cu")
		(net "P5E_CPU1_P1_RX_DP<5>")
	)
	(arc
		(start 102.063042 -281.84094)
		(mid 102.306369 -281.376374)
		(end 102.063042 -280.911808)
		(width 0.1143)
		(layer "In11.Cu")
		(net "P5E_CPU1_P1_RX_DP<5>")
	)
	(arc
		(start 101.556058 -295.632124)
		(mid 101.751837 -295.43732)
		(end 101.82352 -295.170606)
		(width 0.1143)
		(layer "In11.Cu")
		(net "P5E_CPU1_P1_RX_DP<5>")
	)
	(arc
		(start 102.063042 -283.460952)
		(mid 102.306369 -282.996386)
		(end 102.063042 -282.53182)
		(width 0.1143)
		(layer "In11.Cu")
		(net "P5E_CPU1_P1_RX_DP<5>")
	)
	(segment
		(start 102.207822 -277.870412)
		(end 101.74097 -278.13635)
		(width 0.12954)
		(layer "F.Cu")
		(net "P5E_CPU1_P1_RX_DP<4>")
	)
	(segment
		(start 84.998306 -386.003292)
		(end 85.519006 -386.003292)
		(width 0.127)
		(layer "F.Cu")
		(net "P5E_CPU1_P1_RX_DP<4>")
	)
	(segment
		(start 101.084126 -282.50896)
		(end 101.052376 -282.490672)
		(width 0.1143)
		(layer "In11.Cu")
		(net "P5E_CPU1_P1_RX_DP<4>")
	)
	(segment
		(start 96.606614 -360.330242)
		(end 117.854222 -346.132912)
		(width 0.14224)
		(layer "In11.Cu")
		(net "P5E_CPU1_P1_RX_DP<4>")
	)
	(segment
		(start 101.443028 -278.13635)
		(end 101.74097 -278.13635)
		(width 0.1143)
		(layer "In11.Cu")
		(net "P5E_CPU1_P1_RX_DP<4>")
	)
	(segment
		(start 85.519006 -386.003292)
		(end 85.614002 -385.649216)
		(width 0.14224)
		(layer "In11.Cu")
		(net "P5E_CPU1_P1_RX_DP<4>")
	)
	(segment
		(start 101.084126 -288.343848)
		(end 101.120448 -288.322766)
		(width 0.1143)
		(layer "In11.Cu")
		(net "P5E_CPU1_P1_RX_DP<4>")
	)
	(segment
		(start 101.360224 -278.219154)
		(end 101.443028 -278.13635)
		(width 0.1143)
		(layer "In11.Cu")
		(net "P5E_CPU1_P1_RX_DP<4>")
	)
	(segment
		(start 85.788246 -385.548632)
		(end 85.876384 -385.460494)
		(width 0.14224)
		(layer "In11.Cu")
		(net "P5E_CPU1_P1_RX_DP<4>")
	)
	(segment
		(start 101.120448 -289.009836)
		(end 101.084126 -288.988754)
		(width 0.1143)
		(layer "In11.Cu")
		(net "P5E_CPU1_P1_RX_DP<4>")
	)
	(segment
		(start 101.084126 -293.84879)
		(end 101.083364 -293.848282)
		(width 0.1143)
		(layer "In11.Cu")
		(net "P5E_CPU1_P1_RX_DP<4>")
	)
	(segment
		(start 101.084126 -288.988754)
		(end 101.083364 -288.988246)
		(width 0.1143)
		(layer "In11.Cu")
		(net "P5E_CPU1_P1_RX_DP<4>")
	)
	(segment
		(start 101.084126 -280.888948)
		(end 101.052376 -280.87066)
		(width 0.1143)
		(layer "In11.Cu")
		(net "P5E_CPU1_P1_RX_DP<4>")
	)
	(segment
		(start 79.5147 -373.531638)
		(end 83.460844 -367.914428)
		(width 0.14224)
		(layer "In11.Cu")
		(net "P5E_CPU1_P1_RX_DP<4>")
	)
	(segment
		(start 85.868256 -384.048254)
		(end 85.868256 -381.703834)
		(width 0.14224)
		(layer "In11.Cu")
		(net "P5E_CPU1_P1_RX_DP<4>")
	)
	(segment
		(start 101.078538 -285.745682)
		(end 101.077522 -285.745174)
		(width 0.1143)
		(layer "In11.Cu")
		(net "P5E_CPU1_P1_RX_DP<4>")
	)
	(segment
		(start 101.077522 -285.745174)
		(end 101.052376 -285.730696)
		(width 0.1143)
		(layer "In11.Cu")
		(net "P5E_CPU1_P1_RX_DP<4>")
	)
	(segment
		(start 101.118924 -281.843734)
		(end 101.120448 -281.842718)
		(width 0.1143)
		(layer "In11.Cu")
		(net "P5E_CPU1_P1_RX_DP<4>")
	)
	(segment
		(start 101.083364 -290.608258)
		(end 101.052376 -290.590478)
		(width 0.1143)
		(layer "In11.Cu")
		(net "P5E_CPU1_P1_RX_DP<4>")
	)
	(segment
		(start 101.083364 -291.584126)
		(end 101.084126 -291.583618)
		(width 0.1143)
		(layer "In11.Cu")
		(net "P5E_CPU1_P1_RX_DP<4>")
	)
	(segment
		(start 101.084126 -291.583618)
		(end 101.120448 -291.562536)
		(width 0.1143)
		(layer "In11.Cu")
		(net "P5E_CPU1_P1_RX_DP<4>")
	)
	(segment
		(start 120.587516 -341.206836)
		(end 120.587516 -338.718652)
		(width 0.14224)
		(layer "In11.Cu")
		(net "P5E_CPU1_P1_RX_DP<4>")
	)
	(segment
		(start 104.26192 -308.103016)
		(end 100.46716 -298.94149)
		(width 0.14224)
		(layer "In11.Cu")
		(net "P5E_CPU1_P1_RX_DP<4>")
	)
	(segment
		(start 85.876384 -385.046982)
		(end 85.560408 -384.731006)
		(width 0.14224)
		(layer "In11.Cu")
		(net "P5E_CPU1_P1_RX_DP<4>")
	)
	(segment
		(start 101.120448 -280.91003)
		(end 101.084126 -280.888948)
		(width 0.1143)
		(layer "In11.Cu")
		(net "P5E_CPU1_P1_RX_DP<4>")
	)
	(segment
		(start 101.122988 -293.871396)
		(end 101.08692 -293.850568)
		(width 0.1143)
		(layer "In11.Cu")
		(net "P5E_CPU1_P1_RX_DP<4>")
	)
	(segment
		(start 101.13264 -293.878)
		(end 101.125782 -293.873428)
		(width 0.1143)
		(layer "In11.Cu")
		(net "P5E_CPU1_P1_RX_DP<4>")
	)
	(segment
		(start 101.120448 -284.150054)
		(end 101.084126 -284.128972)
		(width 0.1143)
		(layer "In11.Cu")
		(net "P5E_CPU1_P1_RX_DP<4>")
	)
	(segment
		(start 101.082094 -293.2049)
		(end 101.083364 -293.204138)
		(width 0.1143)
		(layer "In11.Cu")
		(net "P5E_CPU1_P1_RX_DP<4>")
	)
	(segment
		(start 101.052376 -281.882088)
		(end 101.084126 -281.8638)
		(width 0.1143)
		(layer "In11.Cu")
		(net "P5E_CPU1_P1_RX_DP<4>")
	)
	(segment
		(start 101.052376 -293.221918)
		(end 101.082094 -293.2049)
		(width 0.1143)
		(layer "In11.Cu")
		(net "P5E_CPU1_P1_RX_DP<4>")
	)
	(segment
		(start 101.083872 -287.368996)
		(end 101.084126 -287.368742)
		(width 0.1143)
		(layer "In11.Cu")
		(net "P5E_CPU1_P1_RX_DP<4>")
	)
	(segment
		(start 85.560408 -384.731006)
		(end 85.563456 -384.3528)
		(width 0.14224)
		(layer "In11.Cu")
		(net "P5E_CPU1_P1_RX_DP<4>")
	)
	(segment
		(start 101.052376 -291.601906)
		(end 101.082094 -291.584888)
		(width 0.1143)
		(layer "In11.Cu")
		(net "P5E_CPU1_P1_RX_DP<4>")
	)
	(segment
		(start 101.084888 -285.749492)
		(end 101.084126 -285.748984)
		(width 0.1143)
		(layer "In11.Cu")
		(net "P5E_CPU1_P1_RX_DP<4>")
	)
	(segment
		(start 83.67268 -367.69294)
		(end 96.606614 -360.330242)
		(width 0.14224)
		(layer "In11.Cu")
		(net "P5E_CPU1_P1_RX_DP<4>")
	)
	(segment
		(start 101.050598 -288.363406)
		(end 101.084126 -288.343848)
		(width 0.1143)
		(layer "In11.Cu")
		(net "P5E_CPU1_P1_RX_DP<4>")
	)
	(segment
		(start 100.42144 -296.389806)
		(end 100.42144 -295.928542)
		(width 0.1143)
		(layer "In11.Cu")
		(net "P5E_CPU1_P1_RX_DP<4>")
	)
	(segment
		(start 101.084126 -287.368742)
		(end 101.083364 -287.368234)
		(width 0.1143)
		(layer "In11.Cu")
		(net "P5E_CPU1_P1_RX_DP<4>")
	)
	(segment
		(start 101.084126 -285.748984)
		(end 101.0793 -285.74619)
		(width 0.1143)
		(layer "In11.Cu")
		(net "P5E_CPU1_P1_RX_DP<4>")
	)
	(segment
		(start 100.653088 -280.101802)
		(end 100.583492 -280.061162)
		(width 0.1143)
		(layer "In11.Cu")
		(net "P5E_CPU1_P1_RX_DP<4>")
	)
	(segment
		(start 101.052376 -289.981894)
		(end 101.082094 -289.964876)
		(width 0.1143)
		(layer "In11.Cu")
		(net "P5E_CPU1_P1_RX_DP<4>")
	)
	(segment
		(start 101.078538 -287.36544)
		(end 101.077522 -287.364932)
		(width 0.1143)
		(layer "In11.Cu")
		(net "P5E_CPU1_P1_RX_DP<4>")
	)
	(segment
		(start 118.00713 -327.095612)
		(end 117.265196 -325.67626)
		(width 0.14224)
		(layer "In11.Cu")
		(net "P5E_CPU1_P1_RX_DP<4>")
	)
	(segment
		(start 79.558134 -374.40743)
		(end 79.483204 -373.651272)
		(width 0.14224)
		(layer "In11.Cu")
		(net "P5E_CPU1_P1_RX_DP<4>")
	)
	(segment
		(start 101.084126 -284.128972)
		(end 101.052376 -284.110684)
		(width 0.1143)
		(layer "In11.Cu")
		(net "P5E_CPU1_P1_RX_DP<4>")
	)
	(segment
		(start 117.265196 -325.67626)
		(end 110.480602 -317.409576)
		(width 0.14224)
		(layer "In11.Cu")
		(net "P5E_CPU1_P1_RX_DP<4>")
	)
	(segment
		(start 101.083364 -293.848282)
		(end 101.052376 -293.830502)
		(width 0.1143)
		(layer "In11.Cu")
		(net "P5E_CPU1_P1_RX_DP<4>")
	)
	(segment
		(start 101.052376 -294.84193)
		(end 101.121718 -294.802052)
		(width 0.1143)
		(layer "In11.Cu")
		(net "P5E_CPU1_P1_RX_DP<4>")
	)
	(segment
		(start 101.084126 -285.103824)
		(end 101.120448 -285.082742)
		(width 0.1143)
		(layer "In11.Cu")
		(net "P5E_CPU1_P1_RX_DP<4>")
	)
	(segment
		(start 85.563456 -384.3528)
		(end 85.868256 -384.048254)
		(width 0.14224)
		(layer "In11.Cu")
		(net "P5E_CPU1_P1_RX_DP<4>")
	)
	(segment
		(start 85.738462 -381.363728)
		(end 79.566516 -374.452134)
		(width 0.14224)
		(layer "In11.Cu")
		(net "P5E_CPU1_P1_RX_DP<4>")
	)
	(segment
		(start 100.458778 -295.838372)
		(end 100.803202 -295.493948)
		(width 0.1143)
		(layer "In11.Cu")
		(net "P5E_CPU1_P1_RX_DP<4>")
	)
	(segment
		(start 100.89642 -295.269158)
		(end 100.89642 -295.146222)
		(width 0.1143)
		(layer "In11.Cu")
		(net "P5E_CPU1_P1_RX_DP<4>")
	)
	(segment
		(start 101.125782 -293.873428)
		(end 101.122988 -293.871396)
		(width 0.1143)
		(layer "In11.Cu")
		(net "P5E_CPU1_P1_RX_DP<4>")
	)
	(segment
		(start 119.253 -344.428318)
		(end 120.587516 -341.206836)
		(width 0.14224)
		(layer "In11.Cu")
		(net "P5E_CPU1_P1_RX_DP<4>")
	)
	(segment
		(start 101.083364 -287.368234)
		(end 101.081586 -287.367218)
		(width 0.1143)
		(layer "In11.Cu")
		(net "P5E_CPU1_P1_RX_DP<4>")
	)
	(segment
		(start 101.050598 -286.743394)
		(end 101.05136 -286.742886)
		(width 0.1143)
		(layer "In11.Cu")
		(net "P5E_CPU1_P1_RX_DP<4>")
	)
	(segment
		(start 100.46716 -296.435526)
		(end 100.42144 -296.389806)
		(width 0.1143)
		(layer "In11.Cu")
		(net "P5E_CPU1_P1_RX_DP<4>")
	)
	(segment
		(start 101.084126 -293.20363)
		(end 101.120448 -293.182548)
		(width 0.1143)
		(layer "In11.Cu")
		(net "P5E_CPU1_P1_RX_DP<4>")
	)
	(segment
		(start 101.08692 -293.850568)
		(end 101.084126 -293.84879)
		(width 0.1143)
		(layer "In11.Cu")
		(net "P5E_CPU1_P1_RX_DP<4>")
	)
	(segment
		(start 101.078792 -278.628094)
		(end 101.084634 -278.624792)
		(width 0.1143)
		(layer "In11.Cu")
		(net "P5E_CPU1_P1_RX_DP<4>")
	)
	(segment
		(start 101.084634 -287.369504)
		(end 101.083872 -287.368996)
		(width 0.1143)
		(layer "In11.Cu")
		(net "P5E_CPU1_P1_RX_DP<4>")
	)
	(segment
		(start 101.052376 -283.5021)
		(end 101.084126 -283.483812)
		(width 0.1143)
		(layer "In11.Cu")
		(net "P5E_CPU1_P1_RX_DP<4>")
	)
	(segment
		(start 101.083364 -292.22827)
		(end 101.052376 -292.21049)
		(width 0.1143)
		(layer "In11.Cu")
		(net "P5E_CPU1_P1_RX_DP<4>")
	)
	(segment
		(start 118.755668 -328.527918)
		(end 118.00713 -327.095866)
		(width 0.14224)
		(layer "In11.Cu")
		(net "P5E_CPU1_P1_RX_DP<4>")
	)
	(segment
		(start 101.083364 -293.204138)
		(end 101.084126 -293.20363)
		(width 0.1143)
		(layer "In11.Cu")
		(net "P5E_CPU1_P1_RX_DP<4>")
	)
	(segment
		(start 101.084126 -281.8638)
		(end 101.118924 -281.843734)
		(width 0.1143)
		(layer "In11.Cu")
		(net "P5E_CPU1_P1_RX_DP<4>")
	)
	(segment
		(start 101.05136 -286.742886)
		(end 101.084126 -286.723836)
		(width 0.1143)
		(layer "In11.Cu")
		(net "P5E_CPU1_P1_RX_DP<4>")
	)
	(segment
		(start 100.46716 -296.463974)
		(end 100.46716 -296.435526)
		(width 0.1143)
		(layer "In11.Cu")
		(net "P5E_CPU1_P1_RX_DP<4>")
	)
	(segment
		(start 101.0793 -285.74619)
		(end 101.078538 -285.745682)
		(width 0.1143)
		(layer "In11.Cu")
		(net "P5E_CPU1_P1_RX_DP<4>")
	)
	(segment
		(start 101.077522 -287.364932)
		(end 101.052376 -287.350454)
		(width 0.1143)
		(layer "In11.Cu")
		(net "P5E_CPU1_P1_RX_DP<4>")
	)
	(segment
		(start 101.082094 -291.584888)
		(end 101.083364 -291.584126)
		(width 0.1143)
		(layer "In11.Cu")
		(net "P5E_CPU1_P1_RX_DP<4>")
	)
	(segment
		(start 101.121718 -294.802052)
		(end 101.137974 -294.790368)
		(width 0.1143)
		(layer "In11.Cu")
		(net "P5E_CPU1_P1_RX_DP<4>")
	)
	(segment
		(start 118.00713 -327.095866)
		(end 118.00713 -327.095612)
		(width 0.14224)
		(layer "In11.Cu")
		(net "P5E_CPU1_P1_RX_DP<4>")
	)
	(segment
		(start 100.46716 -298.94149)
		(end 100.46716 -296.463974)
		(width 0.14224)
		(layer "In11.Cu")
		(net "P5E_CPU1_P1_RX_DP<4>")
	)
	(segment
		(start 85.614002 -385.649216)
		(end 85.788246 -385.548632)
		(width 0.14224)
		(layer "In11.Cu")
		(net "P5E_CPU1_P1_RX_DP<4>")
	)
	(segment
		(start 101.083364 -289.964114)
		(end 101.084126 -289.963606)
		(width 0.1143)
		(layer "In11.Cu")
		(net "P5E_CPU1_P1_RX_DP<4>")
	)
	(segment
		(start 101.084126 -283.483812)
		(end 101.120448 -283.46273)
		(width 0.1143)
		(layer "In11.Cu")
		(net "P5E_CPU1_P1_RX_DP<4>")
	)
	(segment
		(start 101.083364 -288.988246)
		(end 101.052376 -288.970466)
		(width 0.1143)
		(layer "In11.Cu")
		(net "P5E_CPU1_P1_RX_DP<4>")
	)
	(segment
		(start 100.583492 -279.451562)
		(end 100.651564 -279.411938)
		(width 0.1143)
		(layer "In11.Cu")
		(net "P5E_CPU1_P1_RX_DP<4>")
	)
	(segment
		(start 101.052376 -285.122112)
		(end 101.084126 -285.103824)
		(width 0.1143)
		(layer "In11.Cu")
		(net "P5E_CPU1_P1_RX_DP<4>")
	)
	(segment
		(start 101.0793 -287.365948)
		(end 101.078538 -287.36544)
		(width 0.1143)
		(layer "In11.Cu")
		(net "P5E_CPU1_P1_RX_DP<4>")
	)
	(segment
		(start 110.480602 -317.409576)
		(end 104.26192 -308.103016)
		(width 0.14224)
		(layer "In11.Cu")
		(net "P5E_CPU1_P1_RX_DP<4>")
	)
	(segment
		(start 101.084126 -290.608766)
		(end 101.083364 -290.608258)
		(width 0.1143)
		(layer "In11.Cu")
		(net "P5E_CPU1_P1_RX_DP<4>")
	)
	(segment
		(start 85.876384 -385.460494)
		(end 85.876384 -385.046982)
		(width 0.14224)
		(layer "In11.Cu")
		(net "P5E_CPU1_P1_RX_DP<4>")
	)
	(segment
		(start 101.081586 -287.367218)
		(end 101.080824 -287.36671)
		(width 0.1143)
		(layer "In11.Cu")
		(net "P5E_CPU1_P1_RX_DP<4>")
	)
	(segment
		(start 101.084126 -292.228778)
		(end 101.083364 -292.22827)
		(width 0.1143)
		(layer "In11.Cu")
		(net "P5E_CPU1_P1_RX_DP<4>")
	)
	(segment
		(start 101.120448 -290.629848)
		(end 101.084126 -290.608766)
		(width 0.1143)
		(layer "In11.Cu")
		(net "P5E_CPU1_P1_RX_DP<4>")
	)
	(segment
		(start 101.120448 -292.24986)
		(end 101.084126 -292.228778)
		(width 0.1143)
		(layer "In11.Cu")
		(net "P5E_CPU1_P1_RX_DP<4>")
	)
	(segment
		(start 120.587516 -338.718652)
		(end 118.755668 -328.527918)
		(width 0.14224)
		(layer "In11.Cu")
		(net "P5E_CPU1_P1_RX_DP<4>")
	)
	(segment
		(start 101.080824 -287.36671)
		(end 101.0793 -287.365948)
		(width 0.1143)
		(layer "In11.Cu")
		(net "P5E_CPU1_P1_RX_DP<4>")
	)
	(segment
		(start 101.084126 -286.723836)
		(end 101.084888 -286.723328)
		(width 0.1143)
		(layer "In11.Cu")
		(net "P5E_CPU1_P1_RX_DP<4>")
	)
	(segment
		(start 101.120448 -282.530042)
		(end 101.084126 -282.50896)
		(width 0.1143)
		(layer "In11.Cu")
		(net "P5E_CPU1_P1_RX_DP<4>")
	)
	(segment
		(start 101.084126 -289.963606)
		(end 101.120448 -289.942524)
		(width 0.1143)
		(layer "In11.Cu")
		(net "P5E_CPU1_P1_RX_DP<4>")
	)
	(segment
		(start 101.082094 -289.964876)
		(end 101.083364 -289.964114)
		(width 0.1143)
		(layer "In11.Cu")
		(net "P5E_CPU1_P1_RX_DP<4>")
	)
	(arc
		(start 101.120448 -288.322766)
		(mid 101.3011 -288.120021)
		(end 101.36632 -287.856422)
		(width 0.1143)
		(layer "In11.Cu")
		(net "P5E_CPU1_P1_RX_DP<4>")
	)
	(arc
		(start 101.36632 -287.856422)
		(mid 101.290818 -287.57517)
		(end 101.084634 -287.369504)
		(width 0.1143)
		(layer "In11.Cu")
		(net "P5E_CPU1_P1_RX_DP<4>")
	)
	(arc
		(start 100.896166 -278.946356)
		(mid 100.945072 -278.762897)
		(end 101.078792 -278.628094)
		(width 0.1143)
		(layer "In11.Cu")
		(net "P5E_CPU1_P1_RX_DP<4>")
	)
	(arc
		(start 101.134672 -280.919936)
		(mid 101.127598 -280.914929)
		(end 101.120448 -280.91003)
		(width 0.1143)
		(layer "In11.Cu")
		(net "P5E_CPU1_P1_RX_DP<4>")
	)
	(arc
		(start 100.42144 -295.928542)
		(mid 100.431146 -295.879747)
		(end 100.458778 -295.838372)
		(width 0.1143)
		(layer "In11.Cu")
		(net "P5E_CPU1_P1_RX_DP<4>")
	)
	(arc
		(start 101.052376 -293.830502)
		(mid 100.896448 -293.52621)
		(end 101.052376 -293.221918)
		(width 0.1143)
		(layer "In11.Cu")
		(net "P5E_CPU1_P1_RX_DP<4>")
	)
	(arc
		(start 101.134672 -292.259766)
		(mid 101.127599 -292.254757)
		(end 101.120448 -292.24986)
		(width 0.1143)
		(layer "In11.Cu")
		(net "P5E_CPU1_P1_RX_DP<4>")
	)
	(arc
		(start 79.566516 -374.452134)
		(mid 79.561323 -374.429969)
		(end 79.558134 -374.40743)
		(width 0.14224)
		(layer "In11.Cu")
		(net "P5E_CPU1_P1_RX_DP<4>")
	)
	(arc
		(start 101.052376 -285.730696)
		(mid 100.896448 -285.426404)
		(end 101.052376 -285.122112)
		(width 0.1143)
		(layer "In11.Cu")
		(net "P5E_CPU1_P1_RX_DP<4>")
	)
	(arc
		(start 101.134672 -281.832812)
		(mid 101.362055 -281.376374)
		(end 101.134672 -280.919936)
		(width 0.1143)
		(layer "In11.Cu")
		(net "P5E_CPU1_P1_RX_DP<4>")
	)
	(arc
		(start 101.052376 -280.87066)
		(mid 100.9377 -280.737326)
		(end 100.89642 -280.566368)
		(width 0.1143)
		(layer "In11.Cu")
		(net "P5E_CPU1_P1_RX_DP<4>")
	)
	(arc
		(start 101.052376 -284.110684)
		(mid 100.896448 -283.806392)
		(end 101.052376 -283.5021)
		(width 0.1143)
		(layer "In11.Cu")
		(net "P5E_CPU1_P1_RX_DP<4>")
	)
	(arc
		(start 101.120448 -281.842718)
		(mid 101.127597 -281.837818)
		(end 101.134672 -281.832812)
		(width 0.1143)
		(layer "In11.Cu")
		(net "P5E_CPU1_P1_RX_DP<4>")
	)
	(arc
		(start 101.134672 -293.172642)
		(mid 101.362055 -292.716204)
		(end 101.134672 -292.259766)
		(width 0.1143)
		(layer "In11.Cu")
		(net "P5E_CPU1_P1_RX_DP<4>")
	)
	(arc
		(start 83.460844 -367.914428)
		(mid 83.558447 -367.795731)
		(end 83.67268 -367.69294)
		(width 0.14224)
		(layer "In11.Cu")
		(net "P5E_CPU1_P1_RX_DP<4>")
	)
	(arc
		(start 85.868256 -381.703834)
		(mid 85.834565 -381.521876)
		(end 85.738462 -381.363728)
		(width 0.14224)
		(layer "In11.Cu")
		(net "P5E_CPU1_P1_RX_DP<4>")
	)
	(arc
		(start 100.89642 -287.046162)
		(mid 100.937182 -286.876278)
		(end 101.050598 -286.743394)
		(width 0.1143)
		(layer "In11.Cu")
		(net "P5E_CPU1_P1_RX_DP<4>")
	)
	(arc
		(start 101.136704 -289.021266)
		(mid 101.128626 -289.01548)
		(end 101.120448 -289.009836)
		(width 0.1143)
		(layer "In11.Cu")
		(net "P5E_CPU1_P1_RX_DP<4>")
	)
	(arc
		(start 101.084634 -278.624792)
		(mid 101.268847 -278.453514)
		(end 101.360224 -278.219154)
		(width 0.1143)
		(layer "In11.Cu")
		(net "P5E_CPU1_P1_RX_DP<4>")
	)
	(arc
		(start 101.132132 -282.53817)
		(mid 101.126316 -282.534069)
		(end 101.120448 -282.530042)
		(width 0.1143)
		(layer "In11.Cu")
		(net "P5E_CPU1_P1_RX_DP<4>")
	)
	(arc
		(start 101.052376 -288.970466)
		(mid 100.9377 -288.837132)
		(end 100.89642 -288.666174)
		(width 0.1143)
		(layer "In11.Cu")
		(net "P5E_CPU1_P1_RX_DP<4>")
	)
	(arc
		(start 101.137974 -294.790368)
		(mid 101.362423 -294.332863)
		(end 101.13264 -293.878)
		(width 0.1143)
		(layer "In11.Cu")
		(net "P5E_CPU1_P1_RX_DP<4>")
	)
	(arc
		(start 101.134672 -290.639754)
		(mid 101.127599 -290.634745)
		(end 101.120448 -290.629848)
		(width 0.1143)
		(layer "In11.Cu")
		(net "P5E_CPU1_P1_RX_DP<4>")
	)
	(arc
		(start 101.120448 -289.942524)
		(mid 101.128626 -289.936881)
		(end 101.136704 -289.931094)
		(width 0.1143)
		(layer "In11.Cu")
		(net "P5E_CPU1_P1_RX_DP<4>")
	)
	(arc
		(start 101.132132 -283.454602)
		(mid 101.365049 -282.996386)
		(end 101.132132 -282.53817)
		(width 0.1143)
		(layer "In11.Cu")
		(net "P5E_CPU1_P1_RX_DP<4>")
	)
	(arc
		(start 100.89642 -280.566368)
		(mid 100.831905 -280.304149)
		(end 100.653088 -280.101802)
		(width 0.1143)
		(layer "In11.Cu")
		(net "P5E_CPU1_P1_RX_DP<4>")
	)
	(arc
		(start 101.136704 -284.161484)
		(mid 101.128626 -284.155698)
		(end 101.120448 -284.150054)
		(width 0.1143)
		(layer "In11.Cu")
		(net "P5E_CPU1_P1_RX_DP<4>")
	)
	(arc
		(start 100.89642 -288.666174)
		(mid 100.937182 -288.49629)
		(end 101.050598 -288.363406)
		(width 0.1143)
		(layer "In11.Cu")
		(net "P5E_CPU1_P1_RX_DP<4>")
	)
	(arc
		(start 101.084888 -286.723328)
		(mid 101.365222 -286.23641)
		(end 101.084888 -285.749492)
		(width 0.1143)
		(layer "In11.Cu")
		(net "P5E_CPU1_P1_RX_DP<4>")
	)
	(arc
		(start 101.136704 -285.071312)
		(mid 101.359588 -284.616398)
		(end 101.136704 -284.161484)
		(width 0.1143)
		(layer "In11.Cu")
		(net "P5E_CPU1_P1_RX_DP<4>")
	)
	(arc
		(start 100.803202 -295.493948)
		(mid 100.872197 -295.390829)
		(end 100.89642 -295.269158)
		(width 0.1143)
		(layer "In11.Cu")
		(net "P5E_CPU1_P1_RX_DP<4>")
	)
	(arc
		(start 101.120448 -293.182548)
		(mid 101.127598 -293.17765)
		(end 101.134672 -293.172642)
		(width 0.1143)
		(layer "In11.Cu")
		(net "P5E_CPU1_P1_RX_DP<4>")
	)
	(arc
		(start 101.120448 -291.562536)
		(mid 101.127598 -291.557638)
		(end 101.134672 -291.55263)
		(width 0.1143)
		(layer "In11.Cu")
		(net "P5E_CPU1_P1_RX_DP<4>")
	)
	(arc
		(start 101.134672 -291.55263)
		(mid 101.362055 -291.096192)
		(end 101.134672 -290.639754)
		(width 0.1143)
		(layer "In11.Cu")
		(net "P5E_CPU1_P1_RX_DP<4>")
	)
	(arc
		(start 101.120448 -285.082742)
		(mid 101.128626 -285.077099)
		(end 101.136704 -285.071312)
		(width 0.1143)
		(layer "In11.Cu")
		(net "P5E_CPU1_P1_RX_DP<4>")
	)
	(arc
		(start 101.052376 -282.490672)
		(mid 100.896448 -282.18638)
		(end 101.052376 -281.882088)
		(width 0.1143)
		(layer "In11.Cu")
		(net "P5E_CPU1_P1_RX_DP<4>")
	)
	(arc
		(start 101.052376 -292.21049)
		(mid 100.896448 -291.906198)
		(end 101.052376 -291.601906)
		(width 0.1143)
		(layer "In11.Cu")
		(net "P5E_CPU1_P1_RX_DP<4>")
	)
	(arc
		(start 100.89642 -295.146222)
		(mid 100.937675 -294.975251)
		(end 101.052376 -294.84193)
		(width 0.1143)
		(layer "In11.Cu")
		(net "P5E_CPU1_P1_RX_DP<4>")
	)
	(arc
		(start 117.854222 -346.132912)
		(mid 118.680014 -345.384344)
		(end 119.253 -344.428318)
		(width 0.14224)
		(layer "In11.Cu")
		(net "P5E_CPU1_P1_RX_DP<4>")
	)
	(arc
		(start 79.483204 -373.651272)
		(mid 79.482646 -373.643407)
		(end 79.482442 -373.635524)
		(width 0.14224)
		(layer "In11.Cu")
		(net "P5E_CPU1_P1_RX_DP<4>")
	)
	(arc
		(start 100.583492 -280.061162)
		(mid 100.426515 -279.756362)
		(end 100.583492 -279.451562)
		(width 0.1143)
		(layer "In11.Cu")
		(net "P5E_CPU1_P1_RX_DP<4>")
	)
	(arc
		(start 101.136704 -289.931094)
		(mid 101.359588 -289.47618)
		(end 101.136704 -289.021266)
		(width 0.1143)
		(layer "In11.Cu")
		(net "P5E_CPU1_P1_RX_DP<4>")
	)
	(arc
		(start 101.052376 -290.590478)
		(mid 100.896448 -290.286186)
		(end 101.052376 -289.981894)
		(width 0.1143)
		(layer "In11.Cu")
		(net "P5E_CPU1_P1_RX_DP<4>")
	)
	(arc
		(start 101.120448 -283.46273)
		(mid 101.126316 -283.458703)
		(end 101.132132 -283.454602)
		(width 0.1143)
		(layer "In11.Cu")
		(net "P5E_CPU1_P1_RX_DP<4>")
	)
	(arc
		(start 100.651564 -279.411938)
		(mid 100.831356 -279.20935)
		(end 100.896166 -278.946356)
		(width 0.1143)
		(layer "In11.Cu")
		(net "P5E_CPU1_P1_RX_DP<4>")
	)
	(arc
		(start 101.052376 -287.350454)
		(mid 100.9377 -287.21712)
		(end 100.89642 -287.046162)
		(width 0.1143)
		(layer "In11.Cu")
		(net "P5E_CPU1_P1_RX_DP<4>")
	)
	(arc
		(start 79.482442 -373.635524)
		(mid 79.490412 -373.581042)
		(end 79.5147 -373.531638)
		(width 0.14224)
		(layer "In11.Cu")
		(net "P5E_CPU1_P1_RX_DP<4>")
	)
	(segment
		(start 102.207822 -276.2504)
		(end 101.74097 -276.516338)
		(width 0.12954)
		(layer "F.Cu")
		(net "P5E_CPU1_P1_RX_DP<3>")
	)
	(segment
		(start 83.79841 -386.003292)
		(end 84.31911 -386.003292)
		(width 0.127)
		(layer "F.Cu")
		(net "P5E_CPU1_P1_RX_DP<3>")
	)
	(segment
		(start 100.139754 -284.126432)
		(end 100.13823 -284.12567)
		(width 0.1143)
		(layer "In11.Cu")
		(net "P5E_CPU1_P1_RX_DP<3>")
	)
	(segment
		(start 100.15093 -282.513024)
		(end 100.149406 -282.512008)
		(width 0.1143)
		(layer "In11.Cu")
		(net "P5E_CPU1_P1_RX_DP<3>")
	)
	(segment
		(start 100.14331 -292.22827)
		(end 100.14204 -292.227508)
		(width 0.1143)
		(layer "In11.Cu")
		(net "P5E_CPU1_P1_RX_DP<3>")
	)
	(segment
		(start 100.139754 -283.486352)
		(end 100.140516 -283.485844)
		(width 0.1143)
		(layer "In11.Cu")
		(net "P5E_CPU1_P1_RX_DP<3>")
	)
	(segment
		(start 100.14331 -282.508452)
		(end 100.140516 -282.506928)
		(width 0.1143)
		(layer "In11.Cu")
		(net "P5E_CPU1_P1_RX_DP<3>")
	)
	(segment
		(start 100.14839 -292.231318)
		(end 100.146866 -292.230302)
		(width 0.1143)
		(layer "In11.Cu")
		(net "P5E_CPU1_P1_RX_DP<3>")
	)
	(segment
		(start 100.145088 -284.12948)
		(end 100.144072 -284.128972)
		(width 0.1143)
		(layer "In11.Cu")
		(net "P5E_CPU1_P1_RX_DP<3>")
	)
	(segment
		(start 100.14331 -290.608258)
		(end 100.14204 -290.607496)
		(width 0.1143)
		(layer "In11.Cu")
		(net "P5E_CPU1_P1_RX_DP<3>")
	)
	(segment
		(start 100.14331 -291.584126)
		(end 100.144072 -291.583618)
		(width 0.1143)
		(layer "In11.Cu")
		(net "P5E_CPU1_P1_RX_DP<3>")
	)
	(segment
		(start 99.673918 -279.433782)
		(end 99.713034 -279.410922)
		(width 0.1143)
		(layer "In11.Cu")
		(net "P5E_CPU1_P1_RX_DP<3>")
	)
	(segment
		(start 100.146866 -282.510484)
		(end 100.145088 -282.509468)
		(width 0.1143)
		(layer "In11.Cu")
		(net "P5E_CPU1_P1_RX_DP<3>")
	)
	(segment
		(start 100.13823 -284.12567)
		(end 100.137468 -284.125162)
		(width 0.1143)
		(layer "In11.Cu")
		(net "P5E_CPU1_P1_RX_DP<3>")
	)
	(segment
		(start 100.133658 -282.503118)
		(end 100.112322 -282.490672)
		(width 0.1143)
		(layer "In11.Cu")
		(net "P5E_CPU1_P1_RX_DP<3>")
	)
	(segment
		(start 100.145088 -280.889456)
		(end 100.144072 -280.888948)
		(width 0.1143)
		(layer "In11.Cu")
		(net "P5E_CPU1_P1_RX_DP<3>")
	)
	(segment
		(start 100.183188 -293.87165)
		(end 100.17633 -293.867586)
		(width 0.1143)
		(layer "In11.Cu")
		(net "P5E_CPU1_P1_RX_DP<3>")
	)
	(segment
		(start 100.137468 -285.745174)
		(end 100.136198 -285.744412)
		(width 0.1143)
		(layer "In11.Cu")
		(net "P5E_CPU1_P1_RX_DP<3>")
	)
	(segment
		(start 100.145088 -293.849298)
		(end 100.144072 -293.84879)
		(width 0.1143)
		(layer "In11.Cu")
		(net "P5E_CPU1_P1_RX_DP<3>")
	)
	(segment
		(start 100.145088 -285.103316)
		(end 100.146612 -285.1023)
		(width 0.1143)
		(layer "In11.Cu")
		(net "P5E_CPU1_P1_RX_DP<3>")
	)
	(segment
		(start 100.112322 -291.601906)
		(end 100.137722 -291.587174)
		(width 0.1143)
		(layer "In11.Cu")
		(net "P5E_CPU1_P1_RX_DP<3>")
	)
	(segment
		(start 99.53244 -299.121068)
		(end 99.53244 -296.463974)
		(width 0.14224)
		(layer "In11.Cu")
		(net "P5E_CPU1_P1_RX_DP<3>")
	)
	(segment
		(start 100.144072 -291.583618)
		(end 100.145088 -291.58311)
		(width 0.1143)
		(layer "In11.Cu")
		(net "P5E_CPU1_P1_RX_DP<3>")
	)
	(segment
		(start 99.53244 -296.435526)
		(end 99.48672 -296.389806)
		(width 0.1143)
		(layer "In11.Cu")
		(net "P5E_CPU1_P1_RX_DP<3>")
	)
	(segment
		(start 101.443028 -276.516338)
		(end 101.74097 -276.516338)
		(width 0.1143)
		(layer "In11.Cu")
		(net "P5E_CPU1_P1_RX_DP<3>")
	)
	(segment
		(start 100.17633 -285.76778)
		(end 100.175568 -285.767272)
		(width 0.1143)
		(layer "In11.Cu")
		(net "P5E_CPU1_P1_RX_DP<3>")
	)
	(segment
		(start 100.140516 -291.58565)
		(end 100.14331 -291.584126)
		(width 0.1143)
		(layer "In11.Cu")
		(net "P5E_CPU1_P1_RX_DP<3>")
	)
	(segment
		(start 84.676488 -385.460494)
		(end 84.676488 -385.046982)
		(width 0.14224)
		(layer "In11.Cu")
		(net "P5E_CPU1_P1_RX_DP<3>")
	)
	(segment
		(start 100.145088 -282.509468)
		(end 100.144072 -282.50896)
		(width 0.1143)
		(layer "In11.Cu")
		(net "P5E_CPU1_P1_RX_DP<3>")
	)
	(segment
		(start 100.140516 -278.625808)
		(end 100.14331 -278.624284)
		(width 0.1143)
		(layer "In11.Cu")
		(net "P5E_CPU1_P1_RX_DP<3>")
	)
	(segment
		(start 103.438452 -308.55158)
		(end 99.53244 -299.121068)
		(width 0.14224)
		(layer "In11.Cu")
		(net "P5E_CPU1_P1_RX_DP<3>")
	)
	(segment
		(start 100.136198 -280.884376)
		(end 100.133658 -280.883106)
		(width 0.1143)
		(layer "In11.Cu")
		(net "P5E_CPU1_P1_RX_DP<3>")
	)
	(segment
		(start 100.149406 -285.752032)
		(end 100.14839 -285.751524)
		(width 0.1143)
		(layer "In11.Cu")
		(net "P5E_CPU1_P1_RX_DP<3>")
	)
	(segment
		(start 100.175568 -280.907236)
		(end 100.15093 -280.893012)
		(width 0.1143)
		(layer "In11.Cu")
		(net "P5E_CPU1_P1_RX_DP<3>")
	)
	(segment
		(start 100.149406 -292.231826)
		(end 100.14839 -292.231318)
		(width 0.1143)
		(layer "In11.Cu")
		(net "P5E_CPU1_P1_RX_DP<3>")
	)
	(segment
		(start 100.14839 -288.991294)
		(end 100.146866 -288.990278)
		(width 0.1143)
		(layer "In11.Cu")
		(net "P5E_CPU1_P1_RX_DP<3>")
	)
	(segment
		(start 100.15093 -288.992818)
		(end 100.149406 -288.991802)
		(width 0.1143)
		(layer "In11.Cu")
		(net "P5E_CPU1_P1_RX_DP<3>")
	)
	(segment
		(start 100.137722 -283.487368)
		(end 100.139754 -283.486352)
		(width 0.1143)
		(layer "In11.Cu")
		(net "P5E_CPU1_P1_RX_DP<3>")
	)
	(segment
		(start 100.140516 -282.506928)
		(end 100.139754 -282.50642)
		(width 0.1143)
		(layer "In11.Cu")
		(net "P5E_CPU1_P1_RX_DP<3>")
	)
	(segment
		(start 100.144072 -293.84879)
		(end 100.14331 -293.848282)
		(width 0.1143)
		(layer "In11.Cu")
		(net "P5E_CPU1_P1_RX_DP<3>")
	)
	(segment
		(start 100.145088 -292.229286)
		(end 100.144072 -292.228778)
		(width 0.1143)
		(layer "In11.Cu")
		(net "P5E_CPU1_P1_RX_DP<3>")
	)
	(segment
		(start 119.619268 -338.615782)
		(end 117.862096 -328.840846)
		(width 0.14224)
		(layer "In11.Cu")
		(net "P5E_CPU1_P1_RX_DP<3>")
	)
	(segment
		(start 100.14839 -284.131512)
		(end 100.146866 -284.130496)
		(width 0.1143)
		(layer "In11.Cu")
		(net "P5E_CPU1_P1_RX_DP<3>")
	)
	(segment
		(start 100.175568 -292.247066)
		(end 100.15093 -292.232842)
		(width 0.1143)
		(layer "In11.Cu")
		(net "P5E_CPU1_P1_RX_DP<3>")
	)
	(segment
		(start 100.145088 -294.823134)
		(end 100.183188 -294.800782)
		(width 0.1143)
		(layer "In11.Cu")
		(net "P5E_CPU1_P1_RX_DP<3>")
	)
	(segment
		(start 100.137722 -281.867356)
		(end 100.139754 -281.86634)
		(width 0.1143)
		(layer "In11.Cu")
		(net "P5E_CPU1_P1_RX_DP<3>")
	)
	(segment
		(start 96.852994 -359.019856)
		(end 117.24894 -345.390978)
		(width 0.14224)
		(layer "In11.Cu")
		(net "P5E_CPU1_P1_RX_DP<3>")
	)
	(segment
		(start 100.139754 -280.886408)
		(end 100.13823 -280.885646)
		(width 0.1143)
		(layer "In11.Cu")
		(net "P5E_CPU1_P1_RX_DP<3>")
	)
	(segment
		(start 100.136198 -284.1244)
		(end 100.133658 -284.12313)
		(width 0.1143)
		(layer "In11.Cu")
		(net "P5E_CPU1_P1_RX_DP<3>")
	)
	(segment
		(start 100.140516 -285.746952)
		(end 100.139754 -285.746444)
		(width 0.1143)
		(layer "In11.Cu")
		(net "P5E_CPU1_P1_RX_DP<3>")
	)
	(segment
		(start 100.145088 -283.483304)
		(end 100.146612 -283.482288)
		(width 0.1143)
		(layer "In11.Cu")
		(net "P5E_CPU1_P1_RX_DP<3>")
	)
	(segment
		(start 100.145088 -285.749492)
		(end 100.144072 -285.748984)
		(width 0.1143)
		(layer "In11.Cu")
		(net "P5E_CPU1_P1_RX_DP<3>")
	)
	(segment
		(start 100.14204 -293.84752)
		(end 100.112322 -293.830502)
		(width 0.1143)
		(layer "In11.Cu")
		(net "P5E_CPU1_P1_RX_DP<3>")
	)
	(segment
		(start 100.139754 -289.966146)
		(end 100.140516 -289.965638)
		(width 0.1143)
		(layer "In11.Cu")
		(net "P5E_CPU1_P1_RX_DP<3>")
	)
	(segment
		(start 100.140516 -284.12694)
		(end 100.139754 -284.126432)
		(width 0.1143)
		(layer "In11.Cu")
		(net "P5E_CPU1_P1_RX_DP<3>")
	)
	(segment
		(start 100.137722 -291.587174)
		(end 100.139754 -291.586158)
		(width 0.1143)
		(layer "In11.Cu")
		(net "P5E_CPU1_P1_RX_DP<3>")
	)
	(segment
		(start 100.144072 -292.228778)
		(end 100.14331 -292.22827)
		(width 0.1143)
		(layer "In11.Cu")
		(net "P5E_CPU1_P1_RX_DP<3>")
	)
	(segment
		(start 100.139754 -285.106364)
		(end 100.140516 -285.105856)
		(width 0.1143)
		(layer "In11.Cu")
		(net "P5E_CPU1_P1_RX_DP<3>")
	)
	(segment
		(start 99.956112 -295.276778)
		(end 99.956112 -295.193212)
		(width 0.1143)
		(layer "In11.Cu")
		(net "P5E_CPU1_P1_RX_DP<3>")
	)
	(segment
		(start 100.145088 -291.58311)
		(end 100.146612 -291.582094)
		(width 0.1143)
		(layer "In11.Cu")
		(net "P5E_CPU1_P1_RX_DP<3>")
	)
	(segment
		(start 100.583492 -277.83155)
		(end 100.613972 -277.81377)
		(width 0.1143)
		(layer "In11.Cu")
		(net "P5E_CPU1_P1_RX_DP<3>")
	)
	(segment
		(start 100.137722 -293.207186)
		(end 100.139754 -293.20617)
		(width 0.1143)
		(layer "In11.Cu")
		(net "P5E_CPU1_P1_RX_DP<3>")
	)
	(segment
		(start 100.144072 -285.748984)
		(end 100.14331 -285.748476)
		(width 0.1143)
		(layer "In11.Cu")
		(net "P5E_CPU1_P1_RX_DP<3>")
	)
	(segment
		(start 100.146866 -284.130496)
		(end 100.145088 -284.12948)
		(width 0.1143)
		(layer "In11.Cu")
		(net "P5E_CPU1_P1_RX_DP<3>")
	)
	(segment
		(start 100.183188 -292.251638)
		(end 100.17633 -292.247574)
		(width 0.1143)
		(layer "In11.Cu")
		(net "P5E_CPU1_P1_RX_DP<3>")
	)
	(segment
		(start 99.713034 -280.101802)
		(end 99.673918 -280.078942)
		(width 0.1143)
		(layer "In11.Cu")
		(net "P5E_CPU1_P1_RX_DP<3>")
	)
	(segment
		(start 100.183188 -285.771844)
		(end 100.17633 -285.76778)
		(width 0.1143)
		(layer "In11.Cu")
		(net "P5E_CPU1_P1_RX_DP<3>")
	)
	(segment
		(start 100.112322 -285.122112)
		(end 100.137722 -285.10738)
		(width 0.1143)
		(layer "In11.Cu")
		(net "P5E_CPU1_P1_RX_DP<3>")
	)
	(segment
		(start 100.183188 -280.911808)
		(end 100.17633 -280.907744)
		(width 0.1143)
		(layer "In11.Cu")
		(net "P5E_CPU1_P1_RX_DP<3>")
	)
	(segment
		(start 100.144072 -282.50896)
		(end 100.14331 -282.508452)
		(width 0.1143)
		(layer "In11.Cu")
		(net "P5E_CPU1_P1_RX_DP<3>")
	)
	(segment
		(start 100.146866 -285.750508)
		(end 100.145088 -285.749492)
		(width 0.1143)
		(layer "In11.Cu")
		(net "P5E_CPU1_P1_RX_DP<3>")
	)
	(segment
		(start 100.140516 -285.105856)
		(end 100.14331 -285.104332)
		(width 0.1143)
		(layer "In11.Cu")
		(net "P5E_CPU1_P1_RX_DP<3>")
	)
	(segment
		(start 100.110544 -286.743394)
		(end 100.144072 -286.723836)
		(width 0.1143)
		(layer "In11.Cu")
		(net "P5E_CPU1_P1_RX_DP<3>")
	)
	(segment
		(start 100.13823 -282.505658)
		(end 100.137468 -282.50515)
		(width 0.1143)
		(layer "In11.Cu")
		(net "P5E_CPU1_P1_RX_DP<3>")
	)
	(segment
		(start 100.175568 -290.627054)
		(end 100.15093 -290.61283)
		(width 0.1143)
		(layer "In11.Cu")
		(net "P5E_CPU1_P1_RX_DP<3>")
	)
	(segment
		(start 100.14839 -280.891488)
		(end 100.146866 -280.890472)
		(width 0.1143)
		(layer "In11.Cu")
		(net "P5E_CPU1_P1_RX_DP<3>")
	)
	(segment
		(start 100.140516 -281.865832)
		(end 100.14331 -281.864308)
		(width 0.1143)
		(layer "In11.Cu")
		(net "P5E_CPU1_P1_RX_DP<3>")
	)
	(segment
		(start 116.593874 -326.407018)
		(end 110.004098 -318.377316)
		(width 0.14224)
		(layer "In11.Cu")
		(net "P5E_CPU1_P1_RX_DP<3>")
	)
	(segment
		(start 78.859888 -375.301002)
		(end 78.70444 -374.950736)
		(width 0.14224)
		(layer "In11.Cu")
		(net "P5E_CPU1_P1_RX_DP<3>")
	)
	(segment
		(start 100.14331 -281.864308)
		(end 100.144072 -281.8638)
		(width 0.1143)
		(layer "In11.Cu")
		(net "P5E_CPU1_P1_RX_DP<3>")
	)
	(segment
		(start 84.58835 -385.548632)
		(end 84.676488 -385.460494)
		(width 0.14224)
		(layer "In11.Cu")
		(net "P5E_CPU1_P1_RX_DP<3>")
	)
	(segment
		(start 100.146866 -293.850314)
		(end 100.145088 -293.849298)
		(width 0.1143)
		(layer "In11.Cu")
		(net "P5E_CPU1_P1_RX_DP<3>")
	)
	(segment
		(start 100.112322 -293.221918)
		(end 100.137722 -293.207186)
		(width 0.1143)
		(layer "In11.Cu")
		(net "P5E_CPU1_P1_RX_DP<3>")
	)
	(segment
		(start 100.15093 -293.852854)
		(end 100.149406 -293.851838)
		(width 0.1143)
		(layer "In11.Cu")
		(net "P5E_CPU1_P1_RX_DP<3>")
	)
	(segment
		(start 99.643438 -279.451562)
		(end 99.673918 -279.433782)
		(width 0.1143)
		(layer "In11.Cu")
		(net "P5E_CPU1_P1_RX_DP<3>")
	)
	(segment
		(start 100.140516 -293.205662)
		(end 100.14331 -293.204138)
		(width 0.1143)
		(layer "In11.Cu")
		(net "P5E_CPU1_P1_RX_DP<3>")
	)
	(segment
		(start 100.144072 -281.8638)
		(end 100.145088 -281.863292)
		(width 0.1143)
		(layer "In11.Cu")
		(net "P5E_CPU1_P1_RX_DP<3>")
	)
	(segment
		(start 84.36356 -384.3528)
		(end 84.66836 -384.048)
		(width 0.14224)
		(layer "In11.Cu")
		(net "P5E_CPU1_P1_RX_DP<3>")
	)
	(segment
		(start 100.14204 -290.607496)
		(end 100.112322 -290.590478)
		(width 0.1143)
		(layer "In11.Cu")
		(net "P5E_CPU1_P1_RX_DP<3>")
	)
	(segment
		(start 100.144072 -289.963606)
		(end 100.145088 -289.963098)
		(width 0.1143)
		(layer "In11.Cu")
		(net "P5E_CPU1_P1_RX_DP<3>")
	)
	(segment
		(start 100.137722 -285.10738)
		(end 100.139754 -285.106364)
		(width 0.1143)
		(layer "In11.Cu")
		(net "P5E_CPU1_P1_RX_DP<3>")
	)
	(segment
		(start 99.53244 -296.463974)
		(end 99.53244 -296.435526)
		(width 0.1143)
		(layer "In11.Cu")
		(net "P5E_CPU1_P1_RX_DP<3>")
	)
	(segment
		(start 100.14331 -283.48432)
		(end 100.144072 -283.483812)
		(width 0.1143)
		(layer "In11.Cu")
		(net "P5E_CPU1_P1_RX_DP<3>")
	)
	(segment
		(start 100.146612 -285.1023)
		(end 100.183188 -285.080964)
		(width 0.1143)
		(layer "In11.Cu")
		(net "P5E_CPU1_P1_RX_DP<3>")
	)
	(segment
		(start 100.144072 -280.888948)
		(end 100.14331 -280.88844)
		(width 0.1143)
		(layer "In11.Cu")
		(net "P5E_CPU1_P1_RX_DP<3>")
	)
	(segment
		(start 100.17633 -284.147768)
		(end 100.175568 -284.14726)
		(width 0.1143)
		(layer "In11.Cu")
		(net "P5E_CPU1_P1_RX_DP<3>")
	)
	(segment
		(start 100.112322 -283.5021)
		(end 100.137722 -283.487368)
		(width 0.1143)
		(layer "In11.Cu")
		(net "P5E_CPU1_P1_RX_DP<3>")
	)
	(segment
		(start 100.149406 -293.851838)
		(end 100.14839 -293.85133)
		(width 0.1143)
		(layer "In11.Cu")
		(net "P5E_CPU1_P1_RX_DP<3>")
	)
	(segment
		(start 100.144072 -294.823642)
		(end 100.145088 -294.823134)
		(width 0.1143)
		(layer "In11.Cu")
		(net "P5E_CPU1_P1_RX_DP<3>")
	)
	(segment
		(start 100.14331 -285.104332)
		(end 100.144072 -285.103824)
		(width 0.1143)
		(layer "In11.Cu")
		(net "P5E_CPU1_P1_RX_DP<3>")
	)
	(segment
		(start 100.144072 -288.343848)
		(end 100.183188 -288.320988)
		(width 0.1143)
		(layer "In11.Cu")
		(net "P5E_CPU1_P1_RX_DP<3>")
	)
	(segment
		(start 100.137722 -278.627332)
		(end 100.139754 -278.626316)
		(width 0.1143)
		(layer "In11.Cu")
		(net "P5E_CPU1_P1_RX_DP<3>")
	)
	(segment
		(start 100.140516 -294.825674)
		(end 100.14331 -294.82415)
		(width 0.1143)
		(layer "In11.Cu")
		(net "P5E_CPU1_P1_RX_DP<3>")
	)
	(segment
		(start 100.144072 -286.723836)
		(end 100.183188 -286.700976)
		(width 0.1143)
		(layer "In11.Cu")
		(net "P5E_CPU1_P1_RX_DP<3>")
	)
	(segment
		(start 99.673918 -280.078942)
		(end 99.643438 -280.061162)
		(width 0.1143)
		(layer "In11.Cu")
		(net "P5E_CPU1_P1_RX_DP<3>")
	)
	(segment
		(start 100.14331 -284.128464)
		(end 100.140516 -284.12694)
		(width 0.1143)
		(layer "In11.Cu")
		(net "P5E_CPU1_P1_RX_DP<3>")
	)
	(segment
		(start 100.145088 -278.623268)
		(end 100.146612 -278.622252)
		(width 0.1143)
		(layer "In11.Cu")
		(net "P5E_CPU1_P1_RX_DP<3>")
	)
	(segment
		(start 100.14331 -294.82415)
		(end 100.144072 -294.823642)
		(width 0.1143)
		(layer "In11.Cu")
		(net "P5E_CPU1_P1_RX_DP<3>")
	)
	(segment
		(start 84.66836 -384.048)
		(end 84.66836 -381.829056)
		(width 0.14224)
		(layer "In11.Cu")
		(net "P5E_CPU1_P1_RX_DP<3>")
	)
	(segment
		(start 100.144072 -290.608766)
		(end 100.14331 -290.608258)
		(width 0.1143)
		(layer "In11.Cu")
		(net "P5E_CPU1_P1_RX_DP<3>")
	)
	(segment
		(start 100.14839 -293.85133)
		(end 100.146866 -293.850314)
		(width 0.1143)
		(layer "In11.Cu")
		(net "P5E_CPU1_P1_RX_DP<3>")
	)
	(segment
		(start 100.149406 -288.991802)
		(end 100.14839 -288.991294)
		(width 0.1143)
		(layer "In11.Cu")
		(net "P5E_CPU1_P1_RX_DP<3>")
	)
	(segment
		(start 100.146612 -278.622252)
		(end 100.183188 -278.600916)
		(width 0.1143)
		(layer "In11.Cu")
		(net "P5E_CPU1_P1_RX_DP<3>")
	)
	(segment
		(start 100.149406 -290.611814)
		(end 100.14839 -290.611306)
		(width 0.1143)
		(layer "In11.Cu")
		(net "P5E_CPU1_P1_RX_DP<3>")
	)
	(segment
		(start 100.144072 -287.368742)
		(end 100.112322 -287.350454)
		(width 0.1143)
		(layer "In11.Cu")
		(net "P5E_CPU1_P1_RX_DP<3>")
	)
	(segment
		(start 84.503514 -381.408178)
		(end 78.859888 -375.301002)
		(width 0.14224)
		(layer "In11.Cu")
		(net "P5E_CPU1_P1_RX_DP<3>")
	)
	(segment
		(start 100.139754 -282.50642)
		(end 100.13823 -282.505658)
		(width 0.1143)
		(layer "In11.Cu")
		(net "P5E_CPU1_P1_RX_DP<3>")
	)
	(segment
		(start 100.146612 -281.862276)
		(end 100.183188 -281.84094)
		(width 0.1143)
		(layer "In11.Cu")
		(net "P5E_CPU1_P1_RX_DP<3>")
	)
	(segment
		(start 100.146866 -292.230302)
		(end 100.145088 -292.229286)
		(width 0.1143)
		(layer "In11.Cu")
		(net "P5E_CPU1_P1_RX_DP<3>")
	)
	(segment
		(start 100.145088 -290.609274)
		(end 100.144072 -290.608766)
		(width 0.1143)
		(layer "In11.Cu")
		(net "P5E_CPU1_P1_RX_DP<3>")
	)
	(segment
		(start 83.240626 -366.639602)
		(end 96.852994 -359.019856)
		(width 0.14224)
		(layer "In11.Cu")
		(net "P5E_CPU1_P1_RX_DP<3>")
	)
	(segment
		(start 100.144072 -283.483812)
		(end 100.145088 -283.483304)
		(width 0.1143)
		(layer "In11.Cu")
		(net "P5E_CPU1_P1_RX_DP<3>")
	)
	(segment
		(start 100.112322 -278.642064)
		(end 100.137722 -278.627332)
		(width 0.1143)
		(layer "In11.Cu")
		(net "P5E_CPU1_P1_RX_DP<3>")
	)
	(segment
		(start 100.146612 -291.582094)
		(end 100.183188 -291.560758)
		(width 0.1143)
		(layer "In11.Cu")
		(net "P5E_CPU1_P1_RX_DP<3>")
	)
	(segment
		(start 100.17633 -289.00755)
		(end 100.175568 -289.007042)
		(width 0.1143)
		(layer "In11.Cu")
		(net "P5E_CPU1_P1_RX_DP<3>")
	)
	(segment
		(start 101.052376 -277.022052)
		(end 101.087682 -277.001732)
		(width 0.1143)
		(layer "In11.Cu")
		(net "P5E_CPU1_P1_RX_DP<3>")
	)
	(segment
		(start 100.133658 -280.883106)
		(end 100.112322 -280.87066)
		(width 0.1143)
		(layer "In11.Cu")
		(net "P5E_CPU1_P1_RX_DP<3>")
	)
	(segment
		(start 99.603814 -295.831514)
		(end 99.812856 -295.622472)
		(width 0.1143)
		(layer "In11.Cu")
		(net "P5E_CPU1_P1_RX_DP<3>")
	)
	(segment
		(start 100.145088 -289.963098)
		(end 100.146612 -289.962082)
		(width 0.1143)
		(layer "In11.Cu")
		(net "P5E_CPU1_P1_RX_DP<3>")
	)
	(segment
		(start 100.15093 -292.232842)
		(end 100.149406 -292.231826)
		(width 0.1143)
		(layer "In11.Cu")
		(net "P5E_CPU1_P1_RX_DP<3>")
	)
	(segment
		(start 100.140516 -280.886916)
		(end 100.139754 -280.886408)
		(width 0.1143)
		(layer "In11.Cu")
		(net "P5E_CPU1_P1_RX_DP<3>")
	)
	(segment
		(start 84.414106 -385.649216)
		(end 84.58835 -385.548632)
		(width 0.14224)
		(layer "In11.Cu")
		(net "P5E_CPU1_P1_RX_DP<3>")
	)
	(segment
		(start 100.137722 -289.967162)
		(end 100.139754 -289.966146)
		(width 0.1143)
		(layer "In11.Cu")
		(net "P5E_CPU1_P1_RX_DP<3>")
	)
	(segment
		(start 100.14204 -292.227508)
		(end 100.112322 -292.21049)
		(width 0.1143)
		(layer "In11.Cu")
		(net "P5E_CPU1_P1_RX_DP<3>")
	)
	(segment
		(start 100.149406 -280.891996)
		(end 100.14839 -280.891488)
		(width 0.1143)
		(layer "In11.Cu")
		(net "P5E_CPU1_P1_RX_DP<3>")
	)
	(segment
		(start 84.360512 -384.731006)
		(end 84.36356 -384.3528)
		(width 0.14224)
		(layer "In11.Cu")
		(net "P5E_CPU1_P1_RX_DP<3>")
	)
	(segment
		(start 100.175568 -285.767272)
		(end 100.15093 -285.753048)
		(width 0.1143)
		(layer "In11.Cu")
		(net "P5E_CPU1_P1_RX_DP<3>")
	)
	(segment
		(start 100.175568 -284.14726)
		(end 100.15093 -284.133036)
		(width 0.1143)
		(layer "In11.Cu")
		(net "P5E_CPU1_P1_RX_DP<3>")
	)
	(segment
		(start 78.621382 -374.630188)
		(end 78.5114 -373.413274)
		(width 0.14224)
		(layer "In11.Cu")
		(net "P5E_CPU1_P1_RX_DP<3>")
	)
	(segment
		(start 100.144072 -278.623776)
		(end 100.145088 -278.623268)
		(width 0.1143)
		(layer "In11.Cu")
		(net "P5E_CPU1_P1_RX_DP<3>")
	)
	(segment
		(start 100.14331 -293.848282)
		(end 100.14204 -293.84752)
		(width 0.1143)
		(layer "In11.Cu")
		(net "P5E_CPU1_P1_RX_DP<3>")
	)
	(segment
		(start 100.137468 -280.885138)
		(end 100.136198 -280.884376)
		(width 0.1143)
		(layer "In11.Cu")
		(net "P5E_CPU1_P1_RX_DP<3>")
	)
	(segment
		(start 100.139754 -293.20617)
		(end 100.140516 -293.205662)
		(width 0.1143)
		(layer "In11.Cu")
		(net "P5E_CPU1_P1_RX_DP<3>")
	)
	(segment
		(start 100.17633 -292.247574)
		(end 100.175568 -292.247066)
		(width 0.1143)
		(layer "In11.Cu")
		(net "P5E_CPU1_P1_RX_DP<3>")
	)
	(segment
		(start 100.13823 -285.745682)
		(end 100.137468 -285.745174)
		(width 0.1143)
		(layer "In11.Cu")
		(net "P5E_CPU1_P1_RX_DP<3>")
	)
	(segment
		(start 100.146866 -288.990278)
		(end 100.145088 -288.989262)
		(width 0.1143)
		(layer "In11.Cu")
		(net "P5E_CPU1_P1_RX_DP<3>")
	)
	(segment
		(start 100.133658 -284.12313)
		(end 100.112322 -284.110684)
		(width 0.1143)
		(layer "In11.Cu")
		(net "P5E_CPU1_P1_RX_DP<3>")
	)
	(segment
		(start 100.14839 -285.751524)
		(end 100.146866 -285.750508)
		(width 0.1143)
		(layer "In11.Cu")
		(net "P5E_CPU1_P1_RX_DP<3>")
	)
	(segment
		(start 100.146612 -293.202106)
		(end 100.183188 -293.18077)
		(width 0.1143)
		(layer "In11.Cu")
		(net "P5E_CPU1_P1_RX_DP<3>")
	)
	(segment
		(start 84.676488 -385.046982)
		(end 84.360512 -384.731006)
		(width 0.14224)
		(layer "In11.Cu")
		(net "P5E_CPU1_P1_RX_DP<3>")
	)
	(segment
		(start 100.14331 -278.624284)
		(end 100.144072 -278.623776)
		(width 0.1143)
		(layer "In11.Cu")
		(net "P5E_CPU1_P1_RX_DP<3>")
	)
	(segment
		(start 100.145088 -288.989262)
		(end 100.144072 -288.988754)
		(width 0.1143)
		(layer "In11.Cu")
		(net "P5E_CPU1_P1_RX_DP<3>")
	)
	(segment
		(start 100.144072 -285.103824)
		(end 100.145088 -285.103316)
		(width 0.1143)
		(layer "In11.Cu")
		(net "P5E_CPU1_P1_RX_DP<3>")
	)
	(segment
		(start 100.137468 -282.50515)
		(end 100.136198 -282.504388)
		(width 0.1143)
		(layer "In11.Cu")
		(net "P5E_CPU1_P1_RX_DP<3>")
	)
	(segment
		(start 99.48672 -296.389806)
		(end 99.48672 -296.114216)
		(width 0.1143)
		(layer "In11.Cu")
		(net "P5E_CPU1_P1_RX_DP<3>")
	)
	(segment
		(start 100.15093 -290.61283)
		(end 100.149406 -290.611814)
		(width 0.1143)
		(layer "In11.Cu")
		(net "P5E_CPU1_P1_RX_DP<3>")
	)
	(segment
		(start 100.14204 -288.987484)
		(end 100.112322 -288.970466)
		(width 0.1143)
		(layer "In11.Cu")
		(net "P5E_CPU1_P1_RX_DP<3>")
	)
	(segment
		(start 100.110544 -288.363406)
		(end 100.144072 -288.343848)
		(width 0.1143)
		(layer "In11.Cu")
		(net "P5E_CPU1_P1_RX_DP<3>")
	)
	(segment
		(start 100.17633 -282.527756)
		(end 100.175568 -282.527248)
		(width 0.1143)
		(layer "In11.Cu")
		(net "P5E_CPU1_P1_RX_DP<3>")
	)
	(segment
		(start 100.144072 -293.20363)
		(end 100.145088 -293.203122)
		(width 0.1143)
		(layer "In11.Cu")
		(net "P5E_CPU1_P1_RX_DP<3>")
	)
	(segment
		(start 100.139754 -285.746444)
		(end 100.13823 -285.745682)
		(width 0.1143)
		(layer "In11.Cu")
		(net "P5E_CPU1_P1_RX_DP<3>")
	)
	(segment
		(start 100.139754 -294.826182)
		(end 100.140516 -294.825674)
		(width 0.1143)
		(layer "In11.Cu")
		(net "P5E_CPU1_P1_RX_DP<3>")
	)
	(segment
		(start 84.31911 -386.003292)
		(end 84.414106 -385.649216)
		(width 0.14224)
		(layer "In11.Cu")
		(net "P5E_CPU1_P1_RX_DP<3>")
	)
	(segment
		(start 100.146866 -280.890472)
		(end 100.145088 -280.889456)
		(width 0.1143)
		(layer "In11.Cu")
		(net "P5E_CPU1_P1_RX_DP<3>")
	)
	(segment
		(start 100.14331 -293.204138)
		(end 100.144072 -293.20363)
		(width 0.1143)
		(layer "In11.Cu")
		(net "P5E_CPU1_P1_RX_DP<3>")
	)
	(segment
		(start 118.413022 -343.972642)
		(end 119.619268 -341.060278)
		(width 0.14224)
		(layer "In11.Cu")
		(net "P5E_CPU1_P1_RX_DP<3>")
	)
	(segment
		(start 100.183188 -289.011614)
		(end 100.17633 -289.00755)
		(width 0.1143)
		(layer "In11.Cu")
		(net "P5E_CPU1_P1_RX_DP<3>")
	)
	(segment
		(start 100.139754 -291.586158)
		(end 100.140516 -291.58565)
		(width 0.1143)
		(layer "In11.Cu")
		(net "P5E_CPU1_P1_RX_DP<3>")
	)
	(segment
		(start 100.15093 -285.753048)
		(end 100.149406 -285.752032)
		(width 0.1143)
		(layer "In11.Cu")
		(net "P5E_CPU1_P1_RX_DP<3>")
	)
	(segment
		(start 100.137722 -294.827198)
		(end 100.139754 -294.826182)
		(width 0.1143)
		(layer "In11.Cu")
		(net "P5E_CPU1_P1_RX_DP<3>")
	)
	(segment
		(start 78.586076 -373.13108)
		(end 82.852514 -366.9919)
		(width 0.14224)
		(layer "In11.Cu")
		(net "P5E_CPU1_P1_RX_DP<3>")
	)
	(segment
		(start 100.14839 -290.611306)
		(end 100.146866 -290.61029)
		(width 0.1143)
		(layer "In11.Cu")
		(net "P5E_CPU1_P1_RX_DP<3>")
	)
	(segment
		(start 100.112322 -294.84193)
		(end 100.137722 -294.827198)
		(width 0.1143)
		(layer "In11.Cu")
		(net "P5E_CPU1_P1_RX_DP<3>")
	)
	(segment
		(start 110.004098 -318.377316)
		(end 103.438452 -308.55158)
		(width 0.14224)
		(layer "In11.Cu")
		(net "P5E_CPU1_P1_RX_DP<3>")
	)
	(segment
		(start 100.14331 -280.88844)
		(end 100.140516 -280.886916)
		(width 0.1143)
		(layer "In11.Cu")
		(net "P5E_CPU1_P1_RX_DP<3>")
	)
	(segment
		(start 100.15093 -284.133036)
		(end 100.149406 -284.13202)
		(width 0.1143)
		(layer "In11.Cu")
		(net "P5E_CPU1_P1_RX_DP<3>")
	)
	(segment
		(start 100.136198 -285.744412)
		(end 100.133658 -285.743142)
		(width 0.1143)
		(layer "In11.Cu")
		(net "P5E_CPU1_P1_RX_DP<3>")
	)
	(segment
		(start 100.140516 -289.965638)
		(end 100.14331 -289.964114)
		(width 0.1143)
		(layer "In11.Cu")
		(net "P5E_CPU1_P1_RX_DP<3>")
	)
	(segment
		(start 99.956112 -295.193212)
		(end 99.956366 -295.146222)
		(width 0.1143)
		(layer "In11.Cu")
		(net "P5E_CPU1_P1_RX_DP<3>")
	)
	(segment
		(start 100.17633 -280.907744)
		(end 100.175568 -280.907236)
		(width 0.1143)
		(layer "In11.Cu")
		(net "P5E_CPU1_P1_RX_DP<3>")
	)
	(segment
		(start 100.14331 -288.988246)
		(end 100.14204 -288.987484)
		(width 0.1143)
		(layer "In11.Cu")
		(net "P5E_CPU1_P1_RX_DP<3>")
	)
	(segment
		(start 100.137468 -284.125162)
		(end 100.136198 -284.1244)
		(width 0.1143)
		(layer "In11.Cu")
		(net "P5E_CPU1_P1_RX_DP<3>")
	)
	(segment
		(start 100.145088 -293.203122)
		(end 100.146612 -293.202106)
		(width 0.1143)
		(layer "In11.Cu")
		(net "P5E_CPU1_P1_RX_DP<3>")
	)
	(segment
		(start 100.112322 -289.981894)
		(end 100.137722 -289.967162)
		(width 0.1143)
		(layer "In11.Cu")
		(net "P5E_CPU1_P1_RX_DP<3>")
	)
	(segment
		(start 100.180648 -287.390078)
		(end 100.144072 -287.368742)
		(width 0.1143)
		(layer "In11.Cu")
		(net "P5E_CPU1_P1_RX_DP<3>")
	)
	(segment
		(start 100.146612 -283.482288)
		(end 100.183188 -283.460952)
		(width 0.1143)
		(layer "In11.Cu")
		(net "P5E_CPU1_P1_RX_DP<3>")
	)
	(segment
		(start 119.619268 -341.060278)
		(end 119.619268 -338.615782)
		(width 0.14224)
		(layer "In11.Cu")
		(net "P5E_CPU1_P1_RX_DP<3>")
	)
	(segment
		(start 100.613972 -277.81377)
		(end 100.653088 -277.79091)
		(width 0.1143)
		(layer "In11.Cu")
		(net "P5E_CPU1_P1_RX_DP<3>")
	)
	(segment
		(start 100.139754 -278.626316)
		(end 100.140516 -278.625808)
		(width 0.1143)
		(layer "In11.Cu")
		(net "P5E_CPU1_P1_RX_DP<3>")
	)
	(segment
		(start 100.183188 -284.151832)
		(end 100.17633 -284.147768)
		(width 0.1143)
		(layer "In11.Cu")
		(net "P5E_CPU1_P1_RX_DP<3>")
	)
	(segment
		(start 100.175568 -289.007042)
		(end 100.15093 -288.992818)
		(width 0.1143)
		(layer "In11.Cu")
		(net "P5E_CPU1_P1_RX_DP<3>")
	)
	(segment
		(start 100.136198 -282.504388)
		(end 100.133658 -282.503118)
		(width 0.1143)
		(layer "In11.Cu")
		(net "P5E_CPU1_P1_RX_DP<3>")
	)
	(segment
		(start 100.175568 -293.867078)
		(end 100.15093 -293.852854)
		(width 0.1143)
		(layer "In11.Cu")
		(net "P5E_CPU1_P1_RX_DP<3>")
	)
	(segment
		(start 100.14331 -289.964114)
		(end 100.144072 -289.963606)
		(width 0.1143)
		(layer "In11.Cu")
		(net "P5E_CPU1_P1_RX_DP<3>")
	)
	(segment
		(start 100.17633 -293.867586)
		(end 100.175568 -293.867078)
		(width 0.1143)
		(layer "In11.Cu")
		(net "P5E_CPU1_P1_RX_DP<3>")
	)
	(segment
		(start 100.149406 -284.13202)
		(end 100.14839 -284.131512)
		(width 0.1143)
		(layer "In11.Cu")
		(net "P5E_CPU1_P1_RX_DP<3>")
	)
	(segment
		(start 100.146612 -289.962082)
		(end 100.183188 -289.940746)
		(width 0.1143)
		(layer "In11.Cu")
		(net "P5E_CPU1_P1_RX_DP<3>")
	)
	(segment
		(start 100.144072 -284.128972)
		(end 100.14331 -284.128464)
		(width 0.1143)
		(layer "In11.Cu")
		(net "P5E_CPU1_P1_RX_DP<3>")
	)
	(segment
		(start 100.133658 -285.743142)
		(end 100.112322 -285.730696)
		(width 0.1143)
		(layer "In11.Cu")
		(net "P5E_CPU1_P1_RX_DP<3>")
	)
	(segment
		(start 100.149406 -282.512008)
		(end 100.14839 -282.5115)
		(width 0.1143)
		(layer "In11.Cu")
		(net "P5E_CPU1_P1_RX_DP<3>")
	)
	(segment
		(start 100.183188 -290.631626)
		(end 100.17633 -290.627562)
		(width 0.1143)
		(layer "In11.Cu")
		(net "P5E_CPU1_P1_RX_DP<3>")
	)
	(segment
		(start 100.145088 -281.863292)
		(end 100.146612 -281.862276)
		(width 0.1143)
		(layer "In11.Cu")
		(net "P5E_CPU1_P1_RX_DP<3>")
	)
	(segment
		(start 100.144072 -288.988754)
		(end 100.14331 -288.988246)
		(width 0.1143)
		(layer "In11.Cu")
		(net "P5E_CPU1_P1_RX_DP<3>")
	)
	(segment
		(start 100.17633 -290.627562)
		(end 100.175568 -290.627054)
		(width 0.1143)
		(layer "In11.Cu")
		(net "P5E_CPU1_P1_RX_DP<3>")
	)
	(segment
		(start 100.183188 -282.53182)
		(end 100.17633 -282.527756)
		(width 0.1143)
		(layer "In11.Cu")
		(net "P5E_CPU1_P1_RX_DP<3>")
	)
	(segment
		(start 100.13823 -280.885646)
		(end 100.137468 -280.885138)
		(width 0.1143)
		(layer "In11.Cu")
		(net "P5E_CPU1_P1_RX_DP<3>")
	)
	(segment
		(start 100.139754 -281.86634)
		(end 100.140516 -281.865832)
		(width 0.1143)
		(layer "In11.Cu")
		(net "P5E_CPU1_P1_RX_DP<3>")
	)
	(segment
		(start 100.112322 -281.882088)
		(end 100.137722 -281.867356)
		(width 0.1143)
		(layer "In11.Cu")
		(net "P5E_CPU1_P1_RX_DP<3>")
	)
	(segment
		(start 117.862096 -328.840846)
		(end 116.593874 -326.407018)
		(width 0.14224)
		(layer "In11.Cu")
		(net "P5E_CPU1_P1_RX_DP<3>")
	)
	(segment
		(start 101.359716 -276.603206)
		(end 101.443028 -276.516338)
		(width 0.1143)
		(layer "In11.Cu")
		(net "P5E_CPU1_P1_RX_DP<3>")
	)
	(segment
		(start 100.175568 -282.527248)
		(end 100.15093 -282.513024)
		(width 0.1143)
		(layer "In11.Cu")
		(net "P5E_CPU1_P1_RX_DP<3>")
	)
	(segment
		(start 100.15093 -280.893012)
		(end 100.149406 -280.891996)
		(width 0.1143)
		(layer "In11.Cu")
		(net "P5E_CPU1_P1_RX_DP<3>")
	)
	(segment
		(start 100.14839 -282.5115)
		(end 100.146866 -282.510484)
		(width 0.1143)
		(layer "In11.Cu")
		(net "P5E_CPU1_P1_RX_DP<3>")
	)
	(segment
		(start 100.146866 -290.61029)
		(end 100.145088 -290.609274)
		(width 0.1143)
		(layer "In11.Cu")
		(net "P5E_CPU1_P1_RX_DP<3>")
	)
	(segment
		(start 100.140516 -283.485844)
		(end 100.14331 -283.48432)
		(width 0.1143)
		(layer "In11.Cu")
		(net "P5E_CPU1_P1_RX_DP<3>")
	)
	(segment
		(start 100.14331 -285.748476)
		(end 100.140516 -285.746952)
		(width 0.1143)
		(layer "In11.Cu")
		(net "P5E_CPU1_P1_RX_DP<3>")
	)
	(arc
		(start 99.956366 -280.566368)
		(mid 99.891851 -280.304149)
		(end 99.713034 -280.101802)
		(width 0.1143)
		(layer "In11.Cu")
		(net "P5E_CPU1_P1_RX_DP<3>")
	)
	(arc
		(start 101.087682 -277.001732)
		(mid 101.26335 -276.841239)
		(end 101.356414 -276.622256)
		(width 0.1143)
		(layer "In11.Cu")
		(net "P5E_CPU1_P1_RX_DP<3>")
	)
	(arc
		(start 99.956366 -287.046162)
		(mid 99.997128 -286.876278)
		(end 100.110544 -286.743394)
		(width 0.1143)
		(layer "In11.Cu")
		(net "P5E_CPU1_P1_RX_DP<3>")
	)
	(arc
		(start 100.112322 -280.87066)
		(mid 99.997646 -280.737326)
		(end 99.956366 -280.566368)
		(width 0.1143)
		(layer "In11.Cu")
		(net "P5E_CPU1_P1_RX_DP<3>")
	)
	(arc
		(start 100.653088 -277.79091)
		(mid 100.831901 -277.58856)
		(end 100.89642 -277.326344)
		(width 0.1143)
		(layer "In11.Cu")
		(net "P5E_CPU1_P1_RX_DP<3>")
	)
	(arc
		(start 100.112322 -284.110684)
		(mid 99.956394 -283.806392)
		(end 100.112322 -283.5021)
		(width 0.1143)
		(layer "In11.Cu")
		(net "P5E_CPU1_P1_RX_DP<3>")
	)
	(arc
		(start 78.70444 -374.950736)
		(mid 78.649774 -374.793867)
		(end 78.621382 -374.630188)
		(width 0.14224)
		(layer "In11.Cu")
		(net "P5E_CPU1_P1_RX_DP<3>")
	)
	(arc
		(start 100.112322 -285.730696)
		(mid 99.956394 -285.426404)
		(end 100.112322 -285.122112)
		(width 0.1143)
		(layer "In11.Cu")
		(net "P5E_CPU1_P1_RX_DP<3>")
	)
	(arc
		(start 100.112322 -282.490672)
		(mid 99.956394 -282.18638)
		(end 100.112322 -281.882088)
		(width 0.1143)
		(layer "In11.Cu")
		(net "P5E_CPU1_P1_RX_DP<3>")
	)
	(arc
		(start 100.112322 -293.830502)
		(mid 99.956394 -293.52621)
		(end 100.112322 -293.221918)
		(width 0.1143)
		(layer "In11.Cu")
		(net "P5E_CPU1_P1_RX_DP<3>")
	)
	(arc
		(start 100.112322 -290.590478)
		(mid 99.956394 -290.286186)
		(end 100.112322 -289.981894)
		(width 0.1143)
		(layer "In11.Cu")
		(net "P5E_CPU1_P1_RX_DP<3>")
	)
	(arc
		(start 100.183188 -285.080964)
		(mid 100.426515 -284.616398)
		(end 100.183188 -284.151832)
		(width 0.1143)
		(layer "In11.Cu")
		(net "P5E_CPU1_P1_RX_DP<3>")
	)
	(arc
		(start 99.643438 -280.061162)
		(mid 99.486461 -279.756362)
		(end 99.643438 -279.451562)
		(width 0.1143)
		(layer "In11.Cu")
		(net "P5E_CPU1_P1_RX_DP<3>")
	)
	(arc
		(start 84.66836 -381.829056)
		(mid 84.625487 -381.603133)
		(end 84.503514 -381.408178)
		(width 0.14224)
		(layer "In11.Cu")
		(net "P5E_CPU1_P1_RX_DP<3>")
	)
	(arc
		(start 100.183188 -293.18077)
		(mid 100.426515 -292.716204)
		(end 100.183188 -292.251638)
		(width 0.1143)
		(layer "In11.Cu")
		(net "P5E_CPU1_P1_RX_DP<3>")
	)
	(arc
		(start 101.356414 -276.622256)
		(mid 101.358139 -276.612744)
		(end 101.359716 -276.603206)
		(width 0.1143)
		(layer "In11.Cu")
		(net "P5E_CPU1_P1_RX_DP<3>")
	)
	(arc
		(start 100.112322 -287.350454)
		(mid 99.997646 -287.21712)
		(end 99.956366 -287.046162)
		(width 0.1143)
		(layer "In11.Cu")
		(net "P5E_CPU1_P1_RX_DP<3>")
	)
	(arc
		(start 99.956366 -288.666174)
		(mid 99.997128 -288.49629)
		(end 100.110544 -288.363406)
		(width 0.1143)
		(layer "In11.Cu")
		(net "P5E_CPU1_P1_RX_DP<3>")
	)
	(arc
		(start 100.183188 -281.84094)
		(mid 100.426515 -281.376374)
		(end 100.183188 -280.911808)
		(width 0.1143)
		(layer "In11.Cu")
		(net "P5E_CPU1_P1_RX_DP<3>")
	)
	(arc
		(start 82.852514 -366.9919)
		(mid 83.02652 -366.793661)
		(end 83.240626 -366.639602)
		(width 0.14224)
		(layer "In11.Cu")
		(net "P5E_CPU1_P1_RX_DP<3>")
	)
	(arc
		(start 100.183188 -291.560758)
		(mid 100.426515 -291.096192)
		(end 100.183188 -290.631626)
		(width 0.1143)
		(layer "In11.Cu")
		(net "P5E_CPU1_P1_RX_DP<3>")
	)
	(arc
		(start 78.5114 -373.413274)
		(mid 78.523898 -373.265606)
		(end 78.586076 -373.13108)
		(width 0.14224)
		(layer "In11.Cu")
		(net "P5E_CPU1_P1_RX_DP<3>")
	)
	(arc
		(start 99.48672 -296.114216)
		(mid 99.517153 -295.961221)
		(end 99.603814 -295.831514)
		(width 0.1143)
		(layer "In11.Cu")
		(net "P5E_CPU1_P1_RX_DP<3>")
	)
	(arc
		(start 100.183188 -289.940746)
		(mid 100.426515 -289.47618)
		(end 100.183188 -289.011614)
		(width 0.1143)
		(layer "In11.Cu")
		(net "P5E_CPU1_P1_RX_DP<3>")
	)
	(arc
		(start 117.24894 -345.390978)
		(mid 117.936196 -344.768161)
		(end 118.413022 -343.972642)
		(width 0.14224)
		(layer "In11.Cu")
		(net "P5E_CPU1_P1_RX_DP<3>")
	)
	(arc
		(start 99.956366 -278.946356)
		(mid 99.997621 -278.775385)
		(end 100.112322 -278.642064)
		(width 0.1143)
		(layer "In11.Cu")
		(net "P5E_CPU1_P1_RX_DP<3>")
	)
	(arc
		(start 100.183188 -286.700976)
		(mid 100.426515 -286.23641)
		(end 100.183188 -285.771844)
		(width 0.1143)
		(layer "In11.Cu")
		(net "P5E_CPU1_P1_RX_DP<3>")
	)
	(arc
		(start 100.183188 -288.320988)
		(mid 100.362001 -288.118638)
		(end 100.42652 -287.856422)
		(width 0.1143)
		(layer "In11.Cu")
		(net "P5E_CPU1_P1_RX_DP<3>")
	)
	(arc
		(start 100.42652 -287.856422)
		(mid 100.361284 -287.592831)
		(end 100.180648 -287.390078)
		(width 0.1143)
		(layer "In11.Cu")
		(net "P5E_CPU1_P1_RX_DP<3>")
	)
	(arc
		(start 100.183188 -294.800782)
		(mid 100.426515 -294.336216)
		(end 100.183188 -293.87165)
		(width 0.1143)
		(layer "In11.Cu")
		(net "P5E_CPU1_P1_RX_DP<3>")
	)
	(arc
		(start 99.812856 -295.622472)
		(mid 99.918887 -295.46388)
		(end 99.956112 -295.276778)
		(width 0.1143)
		(layer "In11.Cu")
		(net "P5E_CPU1_P1_RX_DP<3>")
	)
	(arc
		(start 100.183188 -283.460952)
		(mid 100.426515 -282.996386)
		(end 100.183188 -282.53182)
		(width 0.1143)
		(layer "In11.Cu")
		(net "P5E_CPU1_P1_RX_DP<3>")
	)
	(arc
		(start 100.42652 -278.13635)
		(mid 100.468069 -277.964928)
		(end 100.583492 -277.83155)
		(width 0.1143)
		(layer "In11.Cu")
		(net "P5E_CPU1_P1_RX_DP<3>")
	)
	(arc
		(start 100.112322 -288.970466)
		(mid 99.997646 -288.837132)
		(end 99.956366 -288.666174)
		(width 0.1143)
		(layer "In11.Cu")
		(net "P5E_CPU1_P1_RX_DP<3>")
	)
	(arc
		(start 99.956366 -295.146222)
		(mid 99.997621 -294.975251)
		(end 100.112322 -294.84193)
		(width 0.1143)
		(layer "In11.Cu")
		(net "P5E_CPU1_P1_RX_DP<3>")
	)
	(arc
		(start 100.112322 -292.21049)
		(mid 99.956394 -291.906198)
		(end 100.112322 -291.601906)
		(width 0.1143)
		(layer "In11.Cu")
		(net "P5E_CPU1_P1_RX_DP<3>")
	)
	(arc
		(start 100.89642 -277.326344)
		(mid 100.937675 -277.155373)
		(end 101.052376 -277.022052)
		(width 0.1143)
		(layer "In11.Cu")
		(net "P5E_CPU1_P1_RX_DP<3>")
	)
	(arc
		(start 100.183188 -278.600916)
		(mid 100.362001 -278.398566)
		(end 100.42652 -278.13635)
		(width 0.1143)
		(layer "In11.Cu")
		(net "P5E_CPU1_P1_RX_DP<3>")
	)
	(arc
		(start 99.713034 -279.410922)
		(mid 99.891847 -279.208572)
		(end 99.956366 -278.946356)
		(width 0.1143)
		(layer "In11.Cu")
		(net "P5E_CPU1_P1_RX_DP<3>")
	)
	(segment
		(start 99.387914 -274.630388)
		(end 98.921062 -274.896326)
		(width 0.12954)
		(layer "F.Cu")
		(net "P5E_CPU1_P1_RX_DP<2>")
	)
	(segment
		(start 82.59826 -386.003292)
		(end 83.11896 -386.003292)
		(width 0.127)
		(layer "F.Cu")
		(net "P5E_CPU1_P1_RX_DP<2>")
	)
	(segment
		(start 98.592132 -296.463974)
		(end 98.592132 -296.435526)
		(width 0.1143)
		(layer "In11.Cu")
		(net "P5E_CPU1_P1_RX_DP<2>")
	)
	(segment
		(start 99.016312 -278.947626)
		(end 99.016312 -278.946102)
		(width 0.1143)
		(layer "In11.Cu")
		(net "P5E_CPU1_P1_RX_DP<2>")
	)
	(segment
		(start 115.843812 -326.99833)
		(end 109.381544 -319.124076)
		(width 0.14224)
		(layer "In11.Cu")
		(net "P5E_CPU1_P1_RX_DP<2>")
	)
	(segment
		(start 99.204018 -277.648924)
		(end 99.203256 -277.648416)
		(width 0.1143)
		(layer "In11.Cu")
		(net "P5E_CPU1_P1_RX_DP<2>")
	)
	(segment
		(start 83.16341 -384.3528)
		(end 83.46821 -384.048254)
		(width 0.14224)
		(layer "In11.Cu")
		(net "P5E_CPU1_P1_RX_DP<2>")
	)
	(segment
		(start 82.571082 -365.734092)
		(end 96.487234 -358.113076)
		(width 0.14224)
		(layer "In11.Cu")
		(net "P5E_CPU1_P1_RX_DP<2>")
	)
	(segment
		(start 83.476338 -385.046982)
		(end 83.160362 -384.731006)
		(width 0.14224)
		(layer "In11.Cu")
		(net "P5E_CPU1_P1_RX_DP<2>")
	)
	(segment
		(start 83.3882 -385.548632)
		(end 83.476338 -385.460494)
		(width 0.14224)
		(layer "In11.Cu")
		(net "P5E_CPU1_P1_RX_DP<2>")
	)
	(segment
		(start 99.203256 -277.004272)
		(end 99.205034 -277.003256)
		(width 0.1143)
		(layer "In11.Cu")
		(net "P5E_CPU1_P1_RX_DP<2>")
	)
	(segment
		(start 99.172268 -287.350454)
		(end 99.165918 -287.345882)
		(width 0.1143)
		(layer "In11.Cu")
		(net "P5E_CPU1_P1_RX_DP<2>")
	)
	(segment
		(start 99.243134 -289.011614)
		(end 99.203256 -288.988246)
		(width 0.1143)
		(layer "In11.Cu")
		(net "P5E_CPU1_P1_RX_DP<2>")
	)
	(segment
		(start 99.172268 -281.882088)
		(end 99.203256 -281.864308)
		(width 0.1143)
		(layer "In11.Cu")
		(net "P5E_CPU1_P1_RX_DP<2>")
	)
	(segment
		(start 98.745294 -280.085292)
		(end 98.731324 -280.07691)
		(width 0.1143)
		(layer "In11.Cu")
		(net "P5E_CPU1_P1_RX_DP<2>")
	)
	(segment
		(start 99.203256 -283.48432)
		(end 99.205034 -283.483304)
		(width 0.1143)
		(layer "In11.Cu")
		(net "P5E_CPU1_P1_RX_DP<2>")
	)
	(segment
		(start 99.205034 -287.369504)
		(end 99.172268 -287.350454)
		(width 0.1143)
		(layer "In11.Cu")
		(net "P5E_CPU1_P1_RX_DP<2>")
	)
	(segment
		(start 98.55327 -274.966176)
		(end 98.62312 -274.896326)
		(width 0.1143)
		(layer "In11.Cu")
		(net "P5E_CPU1_P1_RX_DP<2>")
	)
	(segment
		(start 99.206558 -278.622252)
		(end 99.243134 -278.600916)
		(width 0.1143)
		(layer "In11.Cu")
		(net "P5E_CPU1_P1_RX_DP<2>")
	)
	(segment
		(start 99.172268 -289.981894)
		(end 99.203256 -289.964114)
		(width 0.1143)
		(layer "In11.Cu")
		(net "P5E_CPU1_P1_RX_DP<2>")
	)
	(segment
		(start 118.67896 -340.860126)
		(end 118.67896 -338.699856)
		(width 0.14224)
		(layer "In11.Cu")
		(net "P5E_CPU1_P1_RX_DP<2>")
	)
	(segment
		(start 99.243134 -280.911808)
		(end 99.205034 -280.889456)
		(width 0.1143)
		(layer "In11.Cu")
		(net "P5E_CPU1_P1_RX_DP<2>")
	)
	(segment
		(start 99.205034 -277.003256)
		(end 99.206558 -277.00224)
		(width 0.1143)
		(layer "In11.Cu")
		(net "P5E_CPU1_P1_RX_DP<2>")
	)
	(segment
		(start 99.203256 -284.128464)
		(end 99.172268 -284.110684)
		(width 0.1143)
		(layer "In11.Cu")
		(net "P5E_CPU1_P1_RX_DP<2>")
	)
	(segment
		(start 98.702876 -280.060908)
		(end 98.702114 -280.0604)
		(width 0.1143)
		(layer "In11.Cu")
		(net "P5E_CPU1_P1_RX_DP<2>")
	)
	(segment
		(start 99.203256 -282.508452)
		(end 99.172268 -282.490672)
		(width 0.1143)
		(layer "In11.Cu")
		(net "P5E_CPU1_P1_RX_DP<2>")
	)
	(segment
		(start 99.243134 -285.771844)
		(end 99.236276 -285.76778)
		(width 0.1143)
		(layer "In11.Cu")
		(net "P5E_CPU1_P1_RX_DP<2>")
	)
	(segment
		(start 99.173284 -288.361374)
		(end 99.204526 -288.34334)
		(width 0.1143)
		(layer "In11.Cu")
		(net "P5E_CPU1_P1_RX_DP<2>")
	)
	(segment
		(start 99.243134 -293.87165)
		(end 99.203256 -293.848282)
		(width 0.1143)
		(layer "In11.Cu")
		(net "P5E_CPU1_P1_RX_DP<2>")
	)
	(segment
		(start 99.172268 -283.5021)
		(end 99.203256 -283.48432)
		(width 0.1143)
		(layer "In11.Cu")
		(net "P5E_CPU1_P1_RX_DP<2>")
	)
	(segment
		(start 99.203256 -285.748476)
		(end 99.172268 -285.730696)
		(width 0.1143)
		(layer "In11.Cu")
		(net "P5E_CPU1_P1_RX_DP<2>")
	)
	(segment
		(start 99.205034 -278.623268)
		(end 99.206558 -278.622252)
		(width 0.1143)
		(layer "In11.Cu")
		(net "P5E_CPU1_P1_RX_DP<2>")
	)
	(segment
		(start 99.203256 -290.608258)
		(end 99.172268 -290.590478)
		(width 0.1143)
		(layer "In11.Cu")
		(net "P5E_CPU1_P1_RX_DP<2>")
	)
	(segment
		(start 109.381544 -319.124076)
		(end 102.61219 -308.99354)
		(width 0.14224)
		(layer "In11.Cu")
		(net "P5E_CPU1_P1_RX_DP<2>")
	)
	(segment
		(start 83.46821 -384.048254)
		(end 83.46821 -381.958342)
		(width 0.14224)
		(layer "In11.Cu")
		(net "P5E_CPU1_P1_RX_DP<2>")
	)
	(segment
		(start 98.77044 -275.239988)
		(end 98.702368 -275.200618)
		(width 0.1143)
		(layer "In11.Cu")
		(net "P5E_CPU1_P1_RX_DP<2>")
	)
	(segment
		(start 83.476338 -385.460494)
		(end 83.476338 -385.046982)
		(width 0.14224)
		(layer "In11.Cu")
		(net "P5E_CPU1_P1_RX_DP<2>")
	)
	(segment
		(start 77.687932 -374.821196)
		(end 77.515466 -373.020336)
		(width 0.14224)
		(layer "In11.Cu")
		(net "P5E_CPU1_P1_RX_DP<2>")
	)
	(segment
		(start 99.243134 -282.53182)
		(end 99.203256 -282.508452)
		(width 0.1143)
		(layer "In11.Cu")
		(net "P5E_CPU1_P1_RX_DP<2>")
	)
	(segment
		(start 99.026726 -280.600658)
		(end 99.026726 -280.574242)
		(width 0.1143)
		(layer "In11.Cu")
		(net "P5E_CPU1_P1_RX_DP<2>")
	)
	(segment
		(start 98.546412 -296.389806)
		(end 98.546412 -296.135298)
		(width 0.1143)
		(layer "In11.Cu")
		(net "P5E_CPU1_P1_RX_DP<2>")
	)
	(segment
		(start 99.203256 -281.864308)
		(end 99.205034 -281.863292)
		(width 0.1143)
		(layer "In11.Cu")
		(net "P5E_CPU1_P1_RX_DP<2>")
	)
	(segment
		(start 99.243134 -277.671784)
		(end 99.206558 -277.650448)
		(width 0.1143)
		(layer "In11.Cu")
		(net "P5E_CPU1_P1_RX_DP<2>")
	)
	(segment
		(start 99.203256 -289.964114)
		(end 99.205034 -289.963098)
		(width 0.1143)
		(layer "In11.Cu")
		(net "P5E_CPU1_P1_RX_DP<2>")
	)
	(segment
		(start 99.203256 -294.82415)
		(end 99.205034 -294.823134)
		(width 0.1143)
		(layer "In11.Cu")
		(net "P5E_CPU1_P1_RX_DP<2>")
	)
	(segment
		(start 99.236276 -285.76778)
		(end 99.235514 -285.767272)
		(width 0.1143)
		(layer "In11.Cu")
		(net "P5E_CPU1_P1_RX_DP<2>")
	)
	(segment
		(start 98.732848 -279.428194)
		(end 98.809048 -279.383998)
		(width 0.1143)
		(layer "In11.Cu")
		(net "P5E_CPU1_P1_RX_DP<2>")
	)
	(segment
		(start 98.592132 -299.287946)
		(end 98.592132 -296.463974)
		(width 0.14224)
		(layer "In11.Cu")
		(net "P5E_CPU1_P1_RX_DP<2>")
	)
	(segment
		(start 117.686582 -343.2556)
		(end 118.67896 -340.860126)
		(width 0.14224)
		(layer "In11.Cu")
		(net "P5E_CPU1_P1_RX_DP<2>")
	)
	(segment
		(start 99.243134 -276.051772)
		(end 99.206558 -276.030436)
		(width 0.1143)
		(layer "In11.Cu")
		(net "P5E_CPU1_P1_RX_DP<2>")
	)
	(segment
		(start 99.172268 -294.84193)
		(end 99.203256 -294.82415)
		(width 0.1143)
		(layer "In11.Cu")
		(net "P5E_CPU1_P1_RX_DP<2>")
	)
	(segment
		(start 99.172268 -293.221918)
		(end 99.203256 -293.204138)
		(width 0.1143)
		(layer "In11.Cu")
		(net "P5E_CPU1_P1_RX_DP<2>")
	)
	(segment
		(start 99.206558 -289.962082)
		(end 99.243134 -289.940746)
		(width 0.1143)
		(layer "In11.Cu")
		(net "P5E_CPU1_P1_RX_DP<2>")
	)
	(segment
		(start 99.206558 -277.00224)
		(end 99.243134 -276.980904)
		(width 0.1143)
		(layer "In11.Cu")
		(net "P5E_CPU1_P1_RX_DP<2>")
	)
	(segment
		(start 99.206558 -291.582094)
		(end 99.243134 -291.560758)
		(width 0.1143)
		(layer "In11.Cu")
		(net "P5E_CPU1_P1_RX_DP<2>")
	)
	(segment
		(start 99.206558 -277.650448)
		(end 99.204018 -277.648924)
		(width 0.1143)
		(layer "In11.Cu")
		(net "P5E_CPU1_P1_RX_DP<2>")
	)
	(segment
		(start 118.67896 -338.699856)
		(end 116.958872 -329.130914)
		(width 0.14224)
		(layer "In11.Cu")
		(net "P5E_CPU1_P1_RX_DP<2>")
	)
	(segment
		(start 99.205034 -283.483304)
		(end 99.206558 -283.482288)
		(width 0.1143)
		(layer "In11.Cu")
		(net "P5E_CPU1_P1_RX_DP<2>")
	)
	(segment
		(start 98.731324 -280.07691)
		(end 98.702876 -280.060908)
		(width 0.1143)
		(layer "In11.Cu")
		(net "P5E_CPU1_P1_RX_DP<2>")
	)
	(segment
		(start 99.206558 -276.030436)
		(end 99.204018 -276.028912)
		(width 0.1143)
		(layer "In11.Cu")
		(net "P5E_CPU1_P1_RX_DP<2>")
	)
	(segment
		(start 99.016312 -287.053782)
		(end 99.016312 -287.046162)
		(width 0.1143)
		(layer "In11.Cu")
		(net "P5E_CPU1_P1_RX_DP<2>")
	)
	(segment
		(start 99.172268 -285.122112)
		(end 99.203256 -285.104332)
		(width 0.1143)
		(layer "In11.Cu")
		(net "P5E_CPU1_P1_RX_DP<2>")
	)
	(segment
		(start 83.160362 -384.731006)
		(end 83.16341 -384.3528)
		(width 0.14224)
		(layer "In11.Cu")
		(net "P5E_CPU1_P1_RX_DP<2>")
	)
	(segment
		(start 98.62312 -274.896326)
		(end 98.921062 -274.896326)
		(width 0.1143)
		(layer "In11.Cu")
		(net "P5E_CPU1_P1_RX_DP<2>")
	)
	(segment
		(start 102.61219 -308.99354)
		(end 98.592132 -299.287946)
		(width 0.14224)
		(layer "In11.Cu")
		(net "P5E_CPU1_P1_RX_DP<2>")
	)
	(segment
		(start 99.203256 -293.848282)
		(end 99.172268 -293.830502)
		(width 0.1143)
		(layer "In11.Cu")
		(net "P5E_CPU1_P1_RX_DP<2>")
	)
	(segment
		(start 99.206558 -293.202106)
		(end 99.243134 -293.18077)
		(width 0.1143)
		(layer "In11.Cu")
		(net "P5E_CPU1_P1_RX_DP<2>")
	)
	(segment
		(start 99.016312 -295.158922)
		(end 99.016312 -295.146222)
		(width 0.1143)
		(layer "In11.Cu")
		(net "P5E_CPU1_P1_RX_DP<2>")
	)
	(segment
		(start 99.206558 -285.1023)
		(end 99.243134 -285.080964)
		(width 0.1143)
		(layer "In11.Cu")
		(net "P5E_CPU1_P1_RX_DP<2>")
	)
	(segment
		(start 98.592132 -296.435526)
		(end 98.546412 -296.389806)
		(width 0.1143)
		(layer "In11.Cu")
		(net "P5E_CPU1_P1_RX_DP<2>")
	)
	(segment
		(start 99.203256 -278.624284)
		(end 99.205034 -278.623268)
		(width 0.1143)
		(layer "In11.Cu")
		(net "P5E_CPU1_P1_RX_DP<2>")
	)
	(segment
		(start 99.205034 -280.889456)
		(end 99.188524 -280.880058)
		(width 0.1143)
		(layer "In11.Cu")
		(net "P5E_CPU1_P1_RX_DP<2>")
	)
	(segment
		(start 99.203256 -291.584126)
		(end 99.205034 -291.58311)
		(width 0.1143)
		(layer "In11.Cu")
		(net "P5E_CPU1_P1_RX_DP<2>")
	)
	(segment
		(start 99.172268 -277.022052)
		(end 99.203256 -277.004272)
		(width 0.1143)
		(layer "In11.Cu")
		(net "P5E_CPU1_P1_RX_DP<2>")
	)
	(segment
		(start 99.243134 -284.151832)
		(end 99.203256 -284.128464)
		(width 0.1143)
		(layer "In11.Cu")
		(net "P5E_CPU1_P1_RX_DP<2>")
	)
	(segment
		(start 99.243134 -290.631626)
		(end 99.203256 -290.608258)
		(width 0.1143)
		(layer "In11.Cu")
		(net "P5E_CPU1_P1_RX_DP<2>")
	)
	(segment
		(start 83.26628 -381.451866)
		(end 78.088998 -375.991628)
		(width 0.14224)
		(layer "In11.Cu")
		(net "P5E_CPU1_P1_RX_DP<2>")
	)
	(segment
		(start 99.235514 -285.767272)
		(end 99.203256 -285.748476)
		(width 0.1143)
		(layer "In11.Cu")
		(net "P5E_CPU1_P1_RX_DP<2>")
	)
	(segment
		(start 99.172268 -278.642064)
		(end 99.203256 -278.624284)
		(width 0.1143)
		(layer "In11.Cu")
		(net "P5E_CPU1_P1_RX_DP<2>")
	)
	(segment
		(start 99.172268 -291.601906)
		(end 99.203256 -291.584126)
		(width 0.1143)
		(layer "In11.Cu")
		(net "P5E_CPU1_P1_RX_DP<2>")
	)
	(segment
		(start 98.678238 -295.81729)
		(end 98.789744 -295.705784)
		(width 0.1143)
		(layer "In11.Cu")
		(net "P5E_CPU1_P1_RX_DP<2>")
	)
	(segment
		(start 83.213956 -385.649216)
		(end 83.3882 -385.548632)
		(width 0.14224)
		(layer "In11.Cu")
		(net "P5E_CPU1_P1_RX_DP<2>")
	)
	(segment
		(start 99.203256 -293.204138)
		(end 99.205034 -293.203122)
		(width 0.1143)
		(layer "In11.Cu")
		(net "P5E_CPU1_P1_RX_DP<2>")
	)
	(segment
		(start 99.203256 -292.22827)
		(end 99.172268 -292.21049)
		(width 0.1143)
		(layer "In11.Cu")
		(net "P5E_CPU1_P1_RX_DP<2>")
	)
	(segment
		(start 99.204018 -276.028912)
		(end 99.203256 -276.028404)
		(width 0.1143)
		(layer "In11.Cu")
		(net "P5E_CPU1_P1_RX_DP<2>")
	)
	(segment
		(start 99.17049 -286.743394)
		(end 99.243134 -286.700976)
		(width 0.1143)
		(layer "In11.Cu")
		(net "P5E_CPU1_P1_RX_DP<2>")
	)
	(segment
		(start 99.205034 -294.823134)
		(end 99.243134 -294.800782)
		(width 0.1143)
		(layer "In11.Cu")
		(net "P5E_CPU1_P1_RX_DP<2>")
	)
	(segment
		(start 116.958872 -329.130914)
		(end 115.843812 -326.99833)
		(width 0.14224)
		(layer "In11.Cu")
		(net "P5E_CPU1_P1_RX_DP<2>")
	)
	(segment
		(start 99.203256 -277.648416)
		(end 99.172268 -277.630636)
		(width 0.1143)
		(layer "In11.Cu")
		(net "P5E_CPU1_P1_RX_DP<2>")
	)
	(segment
		(start 83.11896 -386.003292)
		(end 83.213956 -385.649216)
		(width 0.14224)
		(layer "In11.Cu")
		(net "P5E_CPU1_P1_RX_DP<2>")
	)
	(segment
		(start 99.203256 -288.988246)
		(end 99.172268 -288.970466)
		(width 0.1143)
		(layer "In11.Cu")
		(net "P5E_CPU1_P1_RX_DP<2>")
	)
	(segment
		(start 99.205034 -293.203122)
		(end 99.206558 -293.202106)
		(width 0.1143)
		(layer "In11.Cu")
		(net "P5E_CPU1_P1_RX_DP<2>")
	)
	(segment
		(start 99.205034 -281.863292)
		(end 99.206558 -281.862276)
		(width 0.1143)
		(layer "In11.Cu")
		(net "P5E_CPU1_P1_RX_DP<2>")
	)
	(segment
		(start 96.487234 -358.113076)
		(end 116.429536 -344.78722)
		(width 0.14224)
		(layer "In11.Cu")
		(net "P5E_CPU1_P1_RX_DP<2>")
	)
	(segment
		(start 99.205034 -285.103316)
		(end 99.206558 -285.1023)
		(width 0.1143)
		(layer "In11.Cu")
		(net "P5E_CPU1_P1_RX_DP<2>")
	)
	(segment
		(start 99.016312 -278.946102)
		(end 99.016566 -278.946356)
		(width 0.1143)
		(layer "In11.Cu")
		(net "P5E_CPU1_P1_RX_DP<2>")
	)
	(segment
		(start 99.206558 -283.482288)
		(end 99.243134 -283.460952)
		(width 0.1143)
		(layer "In11.Cu")
		(net "P5E_CPU1_P1_RX_DP<2>")
	)
	(segment
		(start 99.206558 -281.862276)
		(end 99.243134 -281.84094)
		(width 0.1143)
		(layer "In11.Cu")
		(net "P5E_CPU1_P1_RX_DP<2>")
	)
	(segment
		(start 99.203256 -285.104332)
		(end 99.205034 -285.103316)
		(width 0.1143)
		(layer "In11.Cu")
		(net "P5E_CPU1_P1_RX_DP<2>")
	)
	(segment
		(start 99.205034 -291.58311)
		(end 99.206558 -291.582094)
		(width 0.1143)
		(layer "In11.Cu")
		(net "P5E_CPU1_P1_RX_DP<2>")
	)
	(segment
		(start 99.17049 -288.363406)
		(end 99.173284 -288.361374)
		(width 0.1143)
		(layer "In11.Cu")
		(net "P5E_CPU1_P1_RX_DP<2>")
	)
	(segment
		(start 99.243134 -292.251638)
		(end 99.203256 -292.22827)
		(width 0.1143)
		(layer "In11.Cu")
		(net "P5E_CPU1_P1_RX_DP<2>")
	)
	(segment
		(start 77.603096 -372.69166)
		(end 82.437986 -365.853218)
		(width 0.14224)
		(layer "In11.Cu")
		(net "P5E_CPU1_P1_RX_DP<2>")
	)
	(segment
		(start 78.01864 -375.887234)
		(end 77.908404 -375.645172)
		(width 0.14224)
		(layer "In11.Cu")
		(net "P5E_CPU1_P1_RX_DP<2>")
	)
	(segment
		(start 99.205034 -289.963098)
		(end 99.206558 -289.962082)
		(width 0.1143)
		(layer "In11.Cu")
		(net "P5E_CPU1_P1_RX_DP<2>")
	)
	(arc
		(start 99.026726 -280.574242)
		(mid 98.951339 -280.292169)
		(end 98.745294 -280.085292)
		(width 0.1143)
		(layer "In11.Cu")
		(net "P5E_CPU1_P1_RX_DP<2>")
	)
	(arc
		(start 98.809048 -279.383998)
		(mid 98.961921 -279.189208)
		(end 99.016312 -278.947626)
		(width 0.1143)
		(layer "In11.Cu")
		(net "P5E_CPU1_P1_RX_DP<2>")
	)
	(arc
		(start 99.172268 -290.590478)
		(mid 99.023171 -290.286186)
		(end 99.172268 -289.981894)
		(width 0.1143)
		(layer "In11.Cu")
		(net "P5E_CPU1_P1_RX_DP<2>")
	)
	(arc
		(start 99.243134 -289.940746)
		(mid 99.486461 -289.47618)
		(end 99.243134 -289.011614)
		(width 0.1143)
		(layer "In11.Cu")
		(net "P5E_CPU1_P1_RX_DP<2>")
	)
	(arc
		(start 99.243134 -285.080964)
		(mid 99.486461 -284.616398)
		(end 99.243134 -284.151832)
		(width 0.1143)
		(layer "In11.Cu")
		(net "P5E_CPU1_P1_RX_DP<2>")
	)
	(arc
		(start 99.172268 -285.730696)
		(mid 99.023171 -285.426404)
		(end 99.172268 -285.122112)
		(width 0.1143)
		(layer "In11.Cu")
		(net "P5E_CPU1_P1_RX_DP<2>")
	)
	(arc
		(start 98.789744 -295.705784)
		(mid 98.957445 -295.454896)
		(end 99.016312 -295.158922)
		(width 0.1143)
		(layer "In11.Cu")
		(net "P5E_CPU1_P1_RX_DP<2>")
	)
	(arc
		(start 77.908404 -375.645172)
		(mid 77.763941 -375.242344)
		(end 77.687932 -374.821196)
		(width 0.14224)
		(layer "In11.Cu")
		(net "P5E_CPU1_P1_RX_DP<2>")
	)
	(arc
		(start 99.243134 -294.800782)
		(mid 99.486461 -294.336216)
		(end 99.243134 -293.87165)
		(width 0.1143)
		(layer "In11.Cu")
		(net "P5E_CPU1_P1_RX_DP<2>")
	)
	(arc
		(start 99.243134 -291.560758)
		(mid 99.486461 -291.096192)
		(end 99.243134 -290.631626)
		(width 0.1143)
		(layer "In11.Cu")
		(net "P5E_CPU1_P1_RX_DP<2>")
	)
	(arc
		(start 82.437986 -365.853218)
		(mid 82.497672 -365.785985)
		(end 82.571082 -365.734092)
		(width 0.14224)
		(layer "In11.Cu")
		(net "P5E_CPU1_P1_RX_DP<2>")
	)
	(arc
		(start 99.016312 -275.702776)
		(mid 99.016317 -275.70049)
		(end 99.016312 -275.698204)
		(width 0.1143)
		(layer "In11.Cu")
		(net "P5E_CPU1_P1_RX_DP<2>")
	)
	(arc
		(start 78.088998 -375.991628)
		(mid 78.049508 -375.942338)
		(end 78.01864 -375.887234)
		(width 0.14224)
		(layer "In11.Cu")
		(net "P5E_CPU1_P1_RX_DP<2>")
	)
	(arc
		(start 99.016312 -275.698204)
		(mid 98.944935 -275.441427)
		(end 98.77044 -275.239988)
		(width 0.1143)
		(layer "In11.Cu")
		(net "P5E_CPU1_P1_RX_DP<2>")
	)
	(arc
		(start 99.243134 -276.980904)
		(mid 99.486461 -276.516338)
		(end 99.243134 -276.051772)
		(width 0.1143)
		(layer "In11.Cu")
		(net "P5E_CPU1_P1_RX_DP<2>")
	)
	(arc
		(start 99.243134 -281.84094)
		(mid 99.486461 -281.376374)
		(end 99.243134 -280.911808)
		(width 0.1143)
		(layer "In11.Cu")
		(net "P5E_CPU1_P1_RX_DP<2>")
	)
	(arc
		(start 99.172268 -282.490672)
		(mid 99.021883 -282.18638)
		(end 99.172268 -281.882088)
		(width 0.1143)
		(layer "In11.Cu")
		(net "P5E_CPU1_P1_RX_DP<2>")
	)
	(arc
		(start 99.243134 -293.18077)
		(mid 99.486461 -292.716204)
		(end 99.243134 -292.251638)
		(width 0.1143)
		(layer "In11.Cu")
		(net "P5E_CPU1_P1_RX_DP<2>")
	)
	(arc
		(start 99.016312 -295.146222)
		(mid 99.060383 -294.976686)
		(end 99.172268 -294.84193)
		(width 0.1143)
		(layer "In11.Cu")
		(net "P5E_CPU1_P1_RX_DP<2>")
	)
	(arc
		(start 99.204526 -288.34334)
		(mid 99.485586 -287.856515)
		(end 99.205034 -287.369504)
		(width 0.1143)
		(layer "In11.Cu")
		(net "P5E_CPU1_P1_RX_DP<2>")
	)
	(arc
		(start 98.702368 -275.200618)
		(mid 98.605233 -275.097749)
		(end 98.55327 -274.966176)
		(width 0.1143)
		(layer "In11.Cu")
		(net "P5E_CPU1_P1_RX_DP<2>")
	)
	(arc
		(start 116.429536 -344.78722)
		(mid 117.171668 -344.114648)
		(end 117.686582 -343.2556)
		(width 0.14224)
		(layer "In11.Cu")
		(net "P5E_CPU1_P1_RX_DP<2>")
	)
	(arc
		(start 77.515466 -373.020336)
		(mid 77.529791 -372.848142)
		(end 77.603096 -372.69166)
		(width 0.14224)
		(layer "In11.Cu")
		(net "P5E_CPU1_P1_RX_DP<2>")
	)
	(arc
		(start 99.172268 -292.21049)
		(mid 99.020679 -291.906198)
		(end 99.172268 -291.601906)
		(width 0.1143)
		(layer "In11.Cu")
		(net "P5E_CPU1_P1_RX_DP<2>")
	)
	(arc
		(start 99.188524 -280.880058)
		(mid 99.070071 -280.7621)
		(end 99.026726 -280.600658)
		(width 0.1143)
		(layer "In11.Cu")
		(net "P5E_CPU1_P1_RX_DP<2>")
	)
	(arc
		(start 99.172268 -293.830502)
		(mid 99.023171 -293.52621)
		(end 99.172268 -293.221918)
		(width 0.1143)
		(layer "In11.Cu")
		(net "P5E_CPU1_P1_RX_DP<2>")
	)
	(arc
		(start 99.243134 -278.600916)
		(mid 99.486461 -278.13635)
		(end 99.243134 -277.671784)
		(width 0.1143)
		(layer "In11.Cu")
		(net "P5E_CPU1_P1_RX_DP<2>")
	)
	(arc
		(start 98.702114 -280.0604)
		(mid 98.545718 -279.735981)
		(end 98.732848 -279.428194)
		(width 0.1143)
		(layer "In11.Cu")
		(net "P5E_CPU1_P1_RX_DP<2>")
	)
	(arc
		(start 99.016312 -288.666174)
		(mid 99.057074 -288.49629)
		(end 99.17049 -288.363406)
		(width 0.1143)
		(layer "In11.Cu")
		(net "P5E_CPU1_P1_RX_DP<2>")
	)
	(arc
		(start 99.172268 -288.970466)
		(mid 99.060471 -288.835665)
		(end 99.016312 -288.666174)
		(width 0.1143)
		(layer "In11.Cu")
		(net "P5E_CPU1_P1_RX_DP<2>")
	)
	(arc
		(start 99.172268 -284.110684)
		(mid 99.021883 -283.806392)
		(end 99.172268 -283.5021)
		(width 0.1143)
		(layer "In11.Cu")
		(net "P5E_CPU1_P1_RX_DP<2>")
	)
	(arc
		(start 99.243134 -283.460952)
		(mid 99.486461 -282.996386)
		(end 99.243134 -282.53182)
		(width 0.1143)
		(layer "In11.Cu")
		(net "P5E_CPU1_P1_RX_DP<2>")
	)
	(arc
		(start 99.243134 -286.700976)
		(mid 99.486461 -286.23641)
		(end 99.243134 -285.771844)
		(width 0.1143)
		(layer "In11.Cu")
		(net "P5E_CPU1_P1_RX_DP<2>")
	)
	(arc
		(start 83.46821 -381.958342)
		(mid 83.415812 -381.685745)
		(end 83.26628 -381.451866)
		(width 0.14224)
		(layer "In11.Cu")
		(net "P5E_CPU1_P1_RX_DP<2>")
	)
	(arc
		(start 98.546412 -296.135298)
		(mid 98.580669 -295.963168)
		(end 98.678238 -295.81729)
		(width 0.1143)
		(layer "In11.Cu")
		(net "P5E_CPU1_P1_RX_DP<2>")
	)
	(arc
		(start 99.165918 -287.345882)
		(mid 99.055877 -287.217878)
		(end 99.016312 -287.053782)
		(width 0.1143)
		(layer "In11.Cu")
		(net "P5E_CPU1_P1_RX_DP<2>")
	)
	(arc
		(start 99.016312 -287.046162)
		(mid 99.057074 -286.876278)
		(end 99.17049 -286.743394)
		(width 0.1143)
		(layer "In11.Cu")
		(net "P5E_CPU1_P1_RX_DP<2>")
	)
	(arc
		(start 99.016566 -278.946356)
		(mid 99.057682 -278.775402)
		(end 99.172268 -278.642064)
		(width 0.1143)
		(layer "In11.Cu")
		(net "P5E_CPU1_P1_RX_DP<2>")
	)
	(arc
		(start 99.172268 -277.630636)
		(mid 99.020679 -277.326344)
		(end 99.172268 -277.022052)
		(width 0.1143)
		(layer "In11.Cu")
		(net "P5E_CPU1_P1_RX_DP<2>")
	)
	(arc
		(start 99.203256 -276.028404)
		(mid 99.071537 -275.887548)
		(end 99.016312 -275.702776)
		(width 0.1143)
		(layer "In11.Cu")
		(net "P5E_CPU1_P1_RX_DP<2>")
	)
	(segment
		(start 81.398364 -386.003292)
		(end 81.919064 -386.003292)
		(width 0.127)
		(layer "F.Cu")
		(net "P5E_CPU1_P1_RX_DP<1>")
	)
	(segment
		(start 99.387914 -277.870412)
		(end 98.921062 -278.13635)
		(width 0.12954)
		(layer "F.Cu")
		(net "P5E_CPU1_P1_RX_DP<1>")
	)
	(segment
		(start 98.30308 -290.631626)
		(end 98.233484 -290.590986)
		(width 0.1143)
		(layer "In11.Cu")
		(net "P5E_CPU1_P1_RX_DP<1>")
	)
	(segment
		(start 98.30308 -284.151832)
		(end 98.233484 -284.111192)
		(width 0.1143)
		(layer "In11.Cu")
		(net "P5E_CPU1_P1_RX_DP<1>")
	)
	(segment
		(start 97.725484 -295.82999)
		(end 97.84461 -295.710864)
		(width 0.1143)
		(layer "In11.Cu")
		(net "P5E_CPU1_P1_RX_DP<1>")
	)
	(segment
		(start 116.055648 -329.421236)
		(end 115.09248 -327.578974)
		(width 0.14224)
		(layer "In11.Cu")
		(net "P5E_CPU1_P1_RX_DP<1>")
	)
	(segment
		(start 97.794064 -279.433782)
		(end 97.79508 -279.433274)
		(width 0.1143)
		(layer "In11.Cu")
		(net "P5E_CPU1_P1_RX_DP<1>")
	)
	(segment
		(start 98.62312 -278.13635)
		(end 98.921062 -278.13635)
		(width 0.1143)
		(layer "In11.Cu")
		(net "P5E_CPU1_P1_RX_DP<1>")
	)
	(segment
		(start 98.233484 -285.121604)
		(end 98.30308 -285.080964)
		(width 0.1143)
		(layer "In11.Cu")
		(net "P5E_CPU1_P1_RX_DP<1>")
	)
	(segment
		(start 98.30308 -282.53182)
		(end 98.233484 -282.49118)
		(width 0.1143)
		(layer "In11.Cu")
		(net "P5E_CPU1_P1_RX_DP<1>")
	)
	(segment
		(start 74.472546 -370.92128)
		(end 76.562712 -368.026442)
		(width 0.14224)
		(layer "In11.Cu")
		(net "P5E_CPU1_P1_RX_DP<1>")
	)
	(segment
		(start 97.796604 -279.432258)
		(end 97.83318 -279.410922)
		(width 0.1143)
		(layer "In11.Cu")
		(net "P5E_CPU1_P1_RX_DP<1>")
	)
	(segment
		(start 81.960466 -384.731006)
		(end 81.962752 -384.452114)
		(width 0.14224)
		(layer "In11.Cu")
		(net "P5E_CPU1_P1_RX_DP<1>")
	)
	(segment
		(start 82.188304 -385.548632)
		(end 82.276442 -385.460494)
		(width 0.14224)
		(layer "In11.Cu")
		(net "P5E_CPU1_P1_RX_DP<1>")
	)
	(segment
		(start 96.046036 -357.283766)
		(end 115.7224 -344.136472)
		(width 0.14224)
		(layer "In11.Cu")
		(net "P5E_CPU1_P1_RX_DP<1>")
	)
	(segment
		(start 82.093054 -381.682498)
		(end 77.399134 -376.844052)
		(width 0.14224)
		(layer "In11.Cu")
		(net "P5E_CPU1_P1_RX_DP<1>")
	)
	(segment
		(start 98.231452 -288.362644)
		(end 98.263964 -288.343848)
		(width 0.1143)
		(layer "In11.Cu")
		(net "P5E_CPU1_P1_RX_DP<1>")
	)
	(segment
		(start 98.30308 -280.911808)
		(end 98.233484 -280.871168)
		(width 0.1143)
		(layer "In11.Cu")
		(net "P5E_CPU1_P1_RX_DP<1>")
	)
	(segment
		(start 97.788222 -280.07564)
		(end 97.78746 -280.075132)
		(width 0.1143)
		(layer "In11.Cu")
		(net "P5E_CPU1_P1_RX_DP<1>")
	)
	(segment
		(start 97.790508 -279.435814)
		(end 97.793302 -279.43429)
		(width 0.1143)
		(layer "In11.Cu")
		(net "P5E_CPU1_P1_RX_DP<1>")
	)
	(segment
		(start 117.720872 -338.6836)
		(end 116.055648 -329.421236)
		(width 0.14224)
		(layer "In11.Cu")
		(net "P5E_CPU1_P1_RX_DP<1>")
	)
	(segment
		(start 98.233484 -294.841422)
		(end 98.30308 -294.800782)
		(width 0.1143)
		(layer "In11.Cu")
		(net "P5E_CPU1_P1_RX_DP<1>")
	)
	(segment
		(start 97.789746 -280.076402)
		(end 97.788222 -280.07564)
		(width 0.1143)
		(layer "In11.Cu")
		(net "P5E_CPU1_P1_RX_DP<1>")
	)
	(segment
		(start 98.30308 -285.771844)
		(end 98.233484 -285.731204)
		(width 0.1143)
		(layer "In11.Cu")
		(net "P5E_CPU1_P1_RX_DP<1>")
	)
	(segment
		(start 98.233484 -291.601398)
		(end 98.30308 -291.560758)
		(width 0.1143)
		(layer "In11.Cu")
		(net "P5E_CPU1_P1_RX_DP<1>")
	)
	(segment
		(start 116.887498 -342.716358)
		(end 117.720872 -340.704678)
		(width 0.14224)
		(layer "In11.Cu")
		(net "P5E_CPU1_P1_RX_DP<1>")
	)
	(segment
		(start 97.826322 -280.097738)
		(end 97.82556 -280.09723)
		(width 0.1143)
		(layer "In11.Cu")
		(net "P5E_CPU1_P1_RX_DP<1>")
	)
	(segment
		(start 97.789746 -279.436322)
		(end 97.790508 -279.435814)
		(width 0.1143)
		(layer "In11.Cu")
		(net "P5E_CPU1_P1_RX_DP<1>")
	)
	(segment
		(start 98.233484 -278.641556)
		(end 98.30308 -278.600916)
		(width 0.1143)
		(layer "In11.Cu")
		(net "P5E_CPU1_P1_RX_DP<1>")
	)
	(segment
		(start 97.652078 -299.454824)
		(end 97.652078 -296.463974)
		(width 0.14224)
		(layer "In11.Cu")
		(net "P5E_CPU1_P1_RX_DP<1>")
	)
	(segment
		(start 77.399134 -376.844052)
		(end 77.399388 -376.844052)
		(width 0.14224)
		(layer "In11.Cu")
		(net "P5E_CPU1_P1_RX_DP<1>")
	)
	(segment
		(start 98.30308 -289.011614)
		(end 98.233484 -288.970974)
		(width 0.1143)
		(layer "In11.Cu")
		(net "P5E_CPU1_P1_RX_DP<1>")
	)
	(segment
		(start 101.810566 -309.494428)
		(end 97.652078 -299.454824)
		(width 0.14224)
		(layer "In11.Cu")
		(net "P5E_CPU1_P1_RX_DP<1>")
	)
	(segment
		(start 98.263964 -286.723836)
		(end 98.30308 -286.700976)
		(width 0.1143)
		(layer "In11.Cu")
		(net "P5E_CPU1_P1_RX_DP<1>")
	)
	(segment
		(start 82.268314 -383.86385)
		(end 82.268314 -382.11506)
		(width 0.14224)
		(layer "In11.Cu")
		(net "P5E_CPU1_P1_RX_DP<1>")
	)
	(segment
		(start 74.422254 -371.80774)
		(end 74.407268 -371.130322)
		(width 0.14224)
		(layer "In11.Cu")
		(net "P5E_CPU1_P1_RX_DP<1>")
	)
	(segment
		(start 98.30054 -287.390078)
		(end 98.233484 -287.350962)
		(width 0.1143)
		(layer "In11.Cu")
		(net "P5E_CPU1_P1_RX_DP<1>")
	)
	(segment
		(start 97.793302 -280.078434)
		(end 97.790508 -280.07691)
		(width 0.1143)
		(layer "In11.Cu")
		(net "P5E_CPU1_P1_RX_DP<1>")
	)
	(segment
		(start 97.82556 -280.09723)
		(end 97.794064 -280.078942)
		(width 0.1143)
		(layer "In11.Cu")
		(net "P5E_CPU1_P1_RX_DP<1>")
	)
	(segment
		(start 98.231452 -286.742632)
		(end 98.263964 -286.723836)
		(width 0.1143)
		(layer "In11.Cu")
		(net "P5E_CPU1_P1_RX_DP<1>")
	)
	(segment
		(start 76.63053 -367.96472)
		(end 88.014302 -361.281218)
		(width 0.14224)
		(layer "In11.Cu")
		(net "P5E_CPU1_P1_RX_DP<1>")
	)
	(segment
		(start 98.233484 -281.88158)
		(end 98.30308 -281.84094)
		(width 0.1143)
		(layer "In11.Cu")
		(net "P5E_CPU1_P1_RX_DP<1>")
	)
	(segment
		(start 81.919064 -386.003292)
		(end 82.01406 -385.649216)
		(width 0.14224)
		(layer "In11.Cu")
		(net "P5E_CPU1_P1_RX_DP<1>")
	)
	(segment
		(start 98.263964 -288.343848)
		(end 98.30308 -288.320988)
		(width 0.1143)
		(layer "In11.Cu")
		(net "P5E_CPU1_P1_RX_DP<1>")
	)
	(segment
		(start 97.793302 -279.43429)
		(end 97.794064 -279.433782)
		(width 0.1143)
		(layer "In11.Cu")
		(net "P5E_CPU1_P1_RX_DP<1>")
	)
	(segment
		(start 98.540316 -278.219154)
		(end 98.62312 -278.13635)
		(width 0.1143)
		(layer "In11.Cu")
		(net "P5E_CPU1_P1_RX_DP<1>")
	)
	(segment
		(start 97.790508 -280.07691)
		(end 97.789746 -280.076402)
		(width 0.1143)
		(layer "In11.Cu")
		(net "P5E_CPU1_P1_RX_DP<1>")
	)
	(segment
		(start 117.720872 -340.704678)
		(end 117.720872 -338.6836)
		(width 0.14224)
		(layer "In11.Cu")
		(net "P5E_CPU1_P1_RX_DP<1>")
	)
	(segment
		(start 98.30308 -293.87165)
		(end 98.233484 -293.83101)
		(width 0.1143)
		(layer "In11.Cu")
		(net "P5E_CPU1_P1_RX_DP<1>")
	)
	(segment
		(start 77.327506 -376.740674)
		(end 76.745592 -375.515632)
		(width 0.14224)
		(layer "In11.Cu")
		(net "P5E_CPU1_P1_RX_DP<1>")
	)
	(segment
		(start 97.78746 -280.075132)
		(end 97.786444 -280.074624)
		(width 0.1143)
		(layer "In11.Cu")
		(net "P5E_CPU1_P1_RX_DP<1>")
	)
	(segment
		(start 88.014302 -361.281218)
		(end 96.046036 -357.283766)
		(width 0.14224)
		(layer "In11.Cu")
		(net "P5E_CPU1_P1_RX_DP<1>")
	)
	(segment
		(start 97.79508 -279.433274)
		(end 97.796604 -279.432258)
		(width 0.1143)
		(layer "In11.Cu")
		(net "P5E_CPU1_P1_RX_DP<1>")
	)
	(segment
		(start 97.787714 -279.437338)
		(end 97.789746 -279.436322)
		(width 0.1143)
		(layer "In11.Cu")
		(net "P5E_CPU1_P1_RX_DP<1>")
	)
	(segment
		(start 82.01406 -385.649216)
		(end 82.188304 -385.548632)
		(width 0.14224)
		(layer "In11.Cu")
		(net "P5E_CPU1_P1_RX_DP<1>")
	)
	(segment
		(start 97.606358 -296.389806)
		(end 97.606358 -296.117518)
		(width 0.1143)
		(layer "In11.Cu")
		(net "P5E_CPU1_P1_RX_DP<1>")
	)
	(segment
		(start 97.652078 -296.463974)
		(end 97.652078 -296.435526)
		(width 0.1143)
		(layer "In11.Cu")
		(net "P5E_CPU1_P1_RX_DP<1>")
	)
	(segment
		(start 82.033872 -384.282188)
		(end 82.13852 -384.17754)
		(width 0.14224)
		(layer "In11.Cu")
		(net "P5E_CPU1_P1_RX_DP<1>")
	)
	(segment
		(start 115.09248 -327.578974)
		(end 108.642912 -319.71996)
		(width 0.14224)
		(layer "In11.Cu")
		(net "P5E_CPU1_P1_RX_DP<1>")
	)
	(segment
		(start 108.642912 -319.71996)
		(end 101.810566 -309.494428)
		(width 0.14224)
		(layer "In11.Cu")
		(net "P5E_CPU1_P1_RX_DP<1>")
	)
	(segment
		(start 82.276442 -385.046982)
		(end 81.960466 -384.731006)
		(width 0.14224)
		(layer "In11.Cu")
		(net "P5E_CPU1_P1_RX_DP<1>")
	)
	(segment
		(start 76.666598 -375.373646)
		(end 74.46899 -371.96014)
		(width 0.14224)
		(layer "In11.Cu")
		(net "P5E_CPU1_P1_RX_DP<1>")
	)
	(segment
		(start 98.233484 -283.501592)
		(end 98.30308 -283.460952)
		(width 0.1143)
		(layer "In11.Cu")
		(net "P5E_CPU1_P1_RX_DP<1>")
	)
	(segment
		(start 82.276442 -385.460494)
		(end 82.276442 -385.046982)
		(width 0.14224)
		(layer "In11.Cu")
		(net "P5E_CPU1_P1_RX_DP<1>")
	)
	(segment
		(start 98.233484 -293.22141)
		(end 98.30308 -293.18077)
		(width 0.1143)
		(layer "In11.Cu")
		(net "P5E_CPU1_P1_RX_DP<1>")
	)
	(segment
		(start 97.83318 -280.101802)
		(end 97.826322 -280.097738)
		(width 0.1143)
		(layer "In11.Cu")
		(net "P5E_CPU1_P1_RX_DP<1>")
	)
	(segment
		(start 97.652078 -296.435526)
		(end 97.606358 -296.389806)
		(width 0.1143)
		(layer "In11.Cu")
		(net "P5E_CPU1_P1_RX_DP<1>")
	)
	(segment
		(start 97.794064 -280.078942)
		(end 97.793302 -280.078434)
		(width 0.1143)
		(layer "In11.Cu")
		(net "P5E_CPU1_P1_RX_DP<1>")
	)
	(segment
		(start 98.233484 -289.981386)
		(end 98.30308 -289.940746)
		(width 0.1143)
		(layer "In11.Cu")
		(net "P5E_CPU1_P1_RX_DP<1>")
	)
	(segment
		(start 97.786444 -280.074624)
		(end 97.762314 -280.060654)
		(width 0.1143)
		(layer "In11.Cu")
		(net "P5E_CPU1_P1_RX_DP<1>")
	)
	(segment
		(start 98.30308 -292.251638)
		(end 98.233484 -292.210998)
		(width 0.1143)
		(layer "In11.Cu")
		(net "P5E_CPU1_P1_RX_DP<1>")
	)
	(segment
		(start 97.762314 -279.45207)
		(end 97.787714 -279.437338)
		(width 0.1143)
		(layer "In11.Cu")
		(net "P5E_CPU1_P1_RX_DP<1>")
	)
	(arc
		(start 97.606358 -296.117518)
		(mid 97.637313 -295.961898)
		(end 97.725484 -295.82999)
		(width 0.1143)
		(layer "In11.Cu")
		(net "P5E_CPU1_P1_RX_DP<1>")
	)
	(arc
		(start 98.536506 -278.242014)
		(mid 98.538529 -278.230604)
		(end 98.540316 -278.219154)
		(width 0.1143)
		(layer "In11.Cu")
		(net "P5E_CPU1_P1_RX_DP<1>")
	)
	(arc
		(start 98.233484 -290.590986)
		(mid 98.076507 -290.286186)
		(end 98.233484 -289.981386)
		(width 0.1143)
		(layer "In11.Cu")
		(net "P5E_CPU1_P1_RX_DP<1>")
	)
	(arc
		(start 98.30308 -288.320988)
		(mid 98.481893 -288.118638)
		(end 98.546412 -287.856422)
		(width 0.1143)
		(layer "In11.Cu")
		(net "P5E_CPU1_P1_RX_DP<1>")
	)
	(arc
		(start 98.076512 -278.946356)
		(mid 98.118061 -278.774934)
		(end 98.233484 -278.641556)
		(width 0.1143)
		(layer "In11.Cu")
		(net "P5E_CPU1_P1_RX_DP<1>")
	)
	(arc
		(start 98.076512 -287.046162)
		(mid 98.117478 -286.875756)
		(end 98.231452 -286.742632)
		(width 0.1143)
		(layer "In11.Cu")
		(net "P5E_CPU1_P1_RX_DP<1>")
	)
	(arc
		(start 98.233484 -288.970974)
		(mid 98.118057 -288.837598)
		(end 98.076512 -288.666174)
		(width 0.1143)
		(layer "In11.Cu")
		(net "P5E_CPU1_P1_RX_DP<1>")
	)
	(arc
		(start 98.076512 -288.666174)
		(mid 98.117478 -288.495768)
		(end 98.231452 -288.362644)
		(width 0.1143)
		(layer "In11.Cu")
		(net "P5E_CPU1_P1_RX_DP<1>")
	)
	(arc
		(start 76.562712 -368.026442)
		(mid 76.593409 -367.992051)
		(end 76.63053 -367.96472)
		(width 0.14224)
		(layer "In11.Cu")
		(net "P5E_CPU1_P1_RX_DP<1>")
	)
	(arc
		(start 98.233484 -287.350962)
		(mid 98.118057 -287.217586)
		(end 98.076512 -287.046162)
		(width 0.1143)
		(layer "In11.Cu")
		(net "P5E_CPU1_P1_RX_DP<1>")
	)
	(arc
		(start 115.7224 -344.136472)
		(mid 116.41027 -343.512825)
		(end 116.887498 -342.716358)
		(width 0.14224)
		(layer "In11.Cu")
		(net "P5E_CPU1_P1_RX_DP<1>")
	)
	(arc
		(start 98.076512 -295.146222)
		(mid 98.118061 -294.9748)
		(end 98.233484 -294.841422)
		(width 0.1143)
		(layer "In11.Cu")
		(net "P5E_CPU1_P1_RX_DP<1>")
	)
	(arc
		(start 76.745592 -375.515632)
		(mid 76.708372 -375.443373)
		(end 76.666598 -375.373646)
		(width 0.14224)
		(layer "In11.Cu")
		(net "P5E_CPU1_P1_RX_DP<1>")
	)
	(arc
		(start 97.84461 -295.710864)
		(mid 98.014986 -295.450893)
		(end 98.076512 -295.146222)
		(width 0.1143)
		(layer "In11.Cu")
		(net "P5E_CPU1_P1_RX_DP<1>")
	)
	(arc
		(start 98.30308 -294.800782)
		(mid 98.546407 -294.336216)
		(end 98.30308 -293.87165)
		(width 0.1143)
		(layer "In11.Cu")
		(net "P5E_CPU1_P1_RX_DP<1>")
	)
	(arc
		(start 81.962752 -384.452114)
		(mid 81.981572 -384.360144)
		(end 82.033872 -384.282188)
		(width 0.14224)
		(layer "In11.Cu")
		(net "P5E_CPU1_P1_RX_DP<1>")
	)
	(arc
		(start 74.46899 -371.96014)
		(mid 74.435075 -371.887174)
		(end 74.422254 -371.80774)
		(width 0.14224)
		(layer "In11.Cu")
		(net "P5E_CPU1_P1_RX_DP<1>")
	)
	(arc
		(start 98.30308 -291.560758)
		(mid 98.546407 -291.096192)
		(end 98.30308 -290.631626)
		(width 0.1143)
		(layer "In11.Cu")
		(net "P5E_CPU1_P1_RX_DP<1>")
	)
	(arc
		(start 98.30308 -281.84094)
		(mid 98.546407 -281.376374)
		(end 98.30308 -280.911808)
		(width 0.1143)
		(layer "In11.Cu")
		(net "P5E_CPU1_P1_RX_DP<1>")
	)
	(arc
		(start 98.30308 -286.700976)
		(mid 98.546407 -286.23641)
		(end 98.30308 -285.771844)
		(width 0.1143)
		(layer "In11.Cu")
		(net "P5E_CPU1_P1_RX_DP<1>")
	)
	(arc
		(start 98.546412 -287.856422)
		(mid 98.481176 -287.592831)
		(end 98.30054 -287.390078)
		(width 0.1143)
		(layer "In11.Cu")
		(net "P5E_CPU1_P1_RX_DP<1>")
	)
	(arc
		(start 97.762314 -280.060654)
		(mid 97.606386 -279.756362)
		(end 97.762314 -279.45207)
		(width 0.1143)
		(layer "In11.Cu")
		(net "P5E_CPU1_P1_RX_DP<1>")
	)
	(arc
		(start 98.30308 -283.460952)
		(mid 98.546407 -282.996386)
		(end 98.30308 -282.53182)
		(width 0.1143)
		(layer "In11.Cu")
		(net "P5E_CPU1_P1_RX_DP<1>")
	)
	(arc
		(start 82.13852 -384.17754)
		(mid 82.234656 -384.033617)
		(end 82.268314 -383.86385)
		(width 0.14224)
		(layer "In11.Cu")
		(net "P5E_CPU1_P1_RX_DP<1>")
	)
	(arc
		(start 98.30308 -293.18077)
		(mid 98.546407 -292.716204)
		(end 98.30308 -292.251638)
		(width 0.1143)
		(layer "In11.Cu")
		(net "P5E_CPU1_P1_RX_DP<1>")
	)
	(arc
		(start 77.399388 -376.844052)
		(mid 77.359235 -376.795294)
		(end 77.327506 -376.740674)
		(width 0.14224)
		(layer "In11.Cu")
		(net "P5E_CPU1_P1_RX_DP<1>")
	)
	(arc
		(start 74.407268 -371.130322)
		(mid 74.422804 -371.020454)
		(end 74.472546 -370.92128)
		(width 0.14224)
		(layer "In11.Cu")
		(net "P5E_CPU1_P1_RX_DP<1>")
	)
	(arc
		(start 98.233484 -280.871168)
		(mid 98.118057 -280.737792)
		(end 98.076512 -280.566368)
		(width 0.1143)
		(layer "In11.Cu")
		(net "P5E_CPU1_P1_RX_DP<1>")
	)
	(arc
		(start 98.30308 -278.600916)
		(mid 98.455067 -278.444408)
		(end 98.536506 -278.242014)
		(width 0.1143)
		(layer "In11.Cu")
		(net "P5E_CPU1_P1_RX_DP<1>")
	)
	(arc
		(start 98.233484 -293.83101)
		(mid 98.076507 -293.52621)
		(end 98.233484 -293.22141)
		(width 0.1143)
		(layer "In11.Cu")
		(net "P5E_CPU1_P1_RX_DP<1>")
	)
	(arc
		(start 98.076512 -280.566368)
		(mid 98.011997 -280.304149)
		(end 97.83318 -280.101802)
		(width 0.1143)
		(layer "In11.Cu")
		(net "P5E_CPU1_P1_RX_DP<1>")
	)
	(arc
		(start 98.233484 -284.111192)
		(mid 98.076507 -283.806392)
		(end 98.233484 -283.501592)
		(width 0.1143)
		(layer "In11.Cu")
		(net "P5E_CPU1_P1_RX_DP<1>")
	)
	(arc
		(start 97.83318 -279.410922)
		(mid 98.011993 -279.208572)
		(end 98.076512 -278.946356)
		(width 0.1143)
		(layer "In11.Cu")
		(net "P5E_CPU1_P1_RX_DP<1>")
	)
	(arc
		(start 98.233484 -285.731204)
		(mid 98.076507 -285.426404)
		(end 98.233484 -285.121604)
		(width 0.1143)
		(layer "In11.Cu")
		(net "P5E_CPU1_P1_RX_DP<1>")
	)
	(arc
		(start 98.233484 -282.49118)
		(mid 98.076507 -282.18638)
		(end 98.233484 -281.88158)
		(width 0.1143)
		(layer "In11.Cu")
		(net "P5E_CPU1_P1_RX_DP<1>")
	)
	(arc
		(start 98.30308 -285.080964)
		(mid 98.546407 -284.616398)
		(end 98.30308 -284.151832)
		(width 0.1143)
		(layer "In11.Cu")
		(net "P5E_CPU1_P1_RX_DP<1>")
	)
	(arc
		(start 82.268314 -382.11506)
		(mid 82.222841 -381.881695)
		(end 82.093054 -381.682498)
		(width 0.14224)
		(layer "In11.Cu")
		(net "P5E_CPU1_P1_RX_DP<1>")
	)
	(arc
		(start 98.233484 -292.210998)
		(mid 98.076507 -291.906198)
		(end 98.233484 -291.601398)
		(width 0.1143)
		(layer "In11.Cu")
		(net "P5E_CPU1_P1_RX_DP<1>")
	)
	(arc
		(start 98.30308 -289.940746)
		(mid 98.546407 -289.47618)
		(end 98.30308 -289.011614)
		(width 0.1143)
		(layer "In11.Cu")
		(net "P5E_CPU1_P1_RX_DP<1>")
	)
	(segment
		(start 98.198432 -386.003292)
		(end 98.719132 -386.003292)
		(width 0.127)
		(layer "F.Cu")
		(net "P5E_CPU1_P1_RX_DP<15>")
	)
	(segment
		(start 110.1979 -275.440394)
		(end 109.731048 -275.706332)
		(width 0.12954)
		(layer "F.Cu")
		(net "P5E_CPU1_P1_RX_DP<15>")
	)
	(segment
		(start 128.971548 -325.741538)
		(end 125.846332 -319.894712)
		(width 0.14224)
		(layer "In11.Cu")
		(net "P5E_CPU1_P1_RX_DP<15>")
	)
	(segment
		(start 110.534958 -277.678642)
		(end 110.514892 -277.666704)
		(width 0.1143)
		(layer "In11.Cu")
		(net "P5E_CPU1_P1_RX_DP<15>")
	)
	(segment
		(start 110.014004 -276.838918)
		(end 110.01248 -276.837902)
		(width 0.1143)
		(layer "In11.Cu")
		(net "P5E_CPU1_P1_RX_DP<15>")
	)
	(segment
		(start 99.07651 -384.852418)
		(end 100.806504 -383.122424)
		(width 0.14224)
		(layer "In11.Cu")
		(net "P5E_CPU1_P1_RX_DP<15>")
	)
	(segment
		(start 104.780588 -381.640588)
		(end 105.234232 -381.305054)
		(width 0.14224)
		(layer "In11.Cu")
		(net "P5E_CPU1_P1_RX_DP<15>")
	)
	(segment
		(start 98.814128 -385.649216)
		(end 99.07651 -385.497832)
		(width 0.14224)
		(layer "In11.Cu")
		(net "P5E_CPU1_P1_RX_DP<15>")
	)
	(segment
		(start 110.05312 -276.861778)
		(end 110.046262 -276.857714)
		(width 0.1143)
		(layer "In11.Cu")
		(net "P5E_CPU1_P1_RX_DP<15>")
	)
	(segment
		(start 105.62336 -376.050048)
		(end 105.623614 -376.050048)
		(width 0.14224)
		(layer "In11.Cu")
		(net "P5E_CPU1_P1_RX_DP<15>")
	)
	(segment
		(start 111.037878 -278.1173)
		(end 110.973616 -278.1173)
		(width 0.1143)
		(layer "In11.Cu")
		(net "P5E_CPU1_P1_RX_DP<15>")
	)
	(segment
		(start 131.441952 -339.023452)
		(end 129.146554 -326.245728)
		(width 0.14224)
		(layer "In11.Cu")
		(net "P5E_CPU1_P1_RX_DP<15>")
	)
	(segment
		(start 111.396272 -278.475694)
		(end 111.058198 -278.13762)
		(width 0.14224)
		(layer "In11.Cu")
		(net "P5E_CPU1_P1_RX_DP<15>")
	)
	(segment
		(start 98.719132 -386.003292)
		(end 98.814128 -385.649216)
		(width 0.14224)
		(layer "In11.Cu")
		(net "P5E_CPU1_P1_RX_DP<15>")
	)
	(segment
		(start 110.046262 -276.857714)
		(end 110.0455 -276.857206)
		(width 0.1143)
		(layer "In11.Cu")
		(net "P5E_CPU1_P1_RX_DP<15>")
	)
	(segment
		(start 105.621328 -377.122944)
		(end 105.62336 -376.050048)
		(width 0.14224)
		(layer "In11.Cu")
		(net "P5E_CPU1_P1_RX_DP<15>")
	)
	(segment
		(start 101.752654 -381.771398)
		(end 104.383078 -381.771398)
		(width 0.14224)
		(layer "In11.Cu")
		(net "P5E_CPU1_P1_RX_DP<15>")
	)
	(segment
		(start 111.396272 -279.262332)
		(end 111.396272 -278.475694)
		(width 0.14224)
		(layer "In11.Cu")
		(net "P5E_CPU1_P1_RX_DP<15>")
	)
	(segment
		(start 113.681002 -303.727612)
		(end 111.80191 -299.19041)
		(width 0.14224)
		(layer "In11.Cu")
		(net "P5E_CPU1_P1_RX_DP<15>")
	)
	(segment
		(start 111.619284 -298.711874)
		(end 111.488728 -295.33596)
		(width 0.14224)
		(layer "In11.Cu")
		(net "P5E_CPU1_P1_RX_DP<15>")
	)
	(segment
		(start 110.483904 -277.64867)
		(end 110.483142 -277.648162)
		(width 0.1143)
		(layer "In11.Cu")
		(net "P5E_CPU1_P1_RX_DP<15>")
	)
	(segment
		(start 110.483142 -277.648162)
		(end 110.453424 -277.631144)
		(width 0.1143)
		(layer "In11.Cu")
		(net "P5E_CPU1_P1_RX_DP<15>")
	)
	(segment
		(start 109.546136 -276.030182)
		(end 109.542072 -276.027642)
		(width 0.1143)
		(layer "In11.Cu")
		(net "P5E_CPU1_P1_RX_DP<15>")
	)
	(segment
		(start 110.514892 -277.666704)
		(end 110.483904 -277.64867)
		(width 0.1143)
		(layer "In11.Cu")
		(net "P5E_CPU1_P1_RX_DP<15>")
	)
	(segment
		(start 110.01502 -276.839426)
		(end 110.014004 -276.838918)
		(width 0.1143)
		(layer "In11.Cu")
		(net "P5E_CPU1_P1_RX_DP<15>")
	)
	(segment
		(start 111.80191 -299.19041)
		(end 111.619284 -298.711874)
		(width 0.14224)
		(layer "In11.Cu")
		(net "P5E_CPU1_P1_RX_DP<15>")
	)
	(segment
		(start 125.846332 -319.894712)
		(end 118.515638 -310.962802)
		(width 0.14224)
		(layer "In11.Cu")
		(net "P5E_CPU1_P1_RX_DP<15>")
	)
	(segment
		(start 109.158024 -364.948724)
		(end 111.18596 -363.593888)
		(width 0.14224)
		(layer "In11.Cu")
		(net "P5E_CPU1_P1_RX_DP<15>")
	)
	(segment
		(start 109.433106 -275.706332)
		(end 109.731048 -275.706332)
		(width 0.1143)
		(layer "In11.Cu")
		(net "P5E_CPU1_P1_RX_DP<15>")
	)
	(segment
		(start 109.54004 -276.026626)
		(end 109.512354 -276.010624)
		(width 0.1143)
		(layer "In11.Cu")
		(net "P5E_CPU1_P1_RX_DP<15>")
	)
	(segment
		(start 118.515638 -310.962802)
		(end 113.681002 -303.727612)
		(width 0.14224)
		(layer "In11.Cu")
		(net "P5E_CPU1_P1_RX_DP<15>")
	)
	(segment
		(start 129.146554 -326.245728)
		(end 128.971548 -325.741538)
		(width 0.14224)
		(layer "In11.Cu")
		(net "P5E_CPU1_P1_RX_DP<15>")
	)
	(segment
		(start 131.441952 -343.974928)
		(end 131.441952 -339.023452)
		(width 0.14224)
		(layer "In11.Cu")
		(net "P5E_CPU1_P1_RX_DP<15>")
	)
	(segment
		(start 111.18596 -363.593888)
		(end 111.352838 -363.493812)
		(width 0.14224)
		(layer "In11.Cu")
		(net "P5E_CPU1_P1_RX_DP<15>")
	)
	(segment
		(start 110.0455 -276.857206)
		(end 110.01502 -276.839426)
		(width 0.1143)
		(layer "In11.Cu")
		(net "P5E_CPU1_P1_RX_DP<15>")
	)
	(segment
		(start 108.31449 -365.772192)
		(end 108.485432 -365.561626)
		(width 0.14224)
		(layer "In11.Cu")
		(net "P5E_CPU1_P1_RX_DP<15>")
	)
	(segment
		(start 105.616248 -379.378464)
		(end 105.618788 -379.375924)
		(width 0.14224)
		(layer "In11.Cu")
		(net "P5E_CPU1_P1_RX_DP<15>")
	)
	(segment
		(start 105.623614 -376.050048)
		(end 106.30789 -370.489734)
		(width 0.14224)
		(layer "In11.Cu")
		(net "P5E_CPU1_P1_RX_DP<15>")
	)
	(segment
		(start 105.618788 -379.375924)
		(end 105.618788 -378.250704)
		(width 0.14224)
		(layer "In11.Cu")
		(net "P5E_CPU1_P1_RX_DP<15>")
	)
	(segment
		(start 100.958904 -382.754632)
		(end 100.958904 -382.698498)
		(width 0.14224)
		(layer "In11.Cu")
		(net "P5E_CPU1_P1_RX_DP<15>")
	)
	(segment
		(start 101.09073 -382.38049)
		(end 101.662484 -381.808736)
		(width 0.14224)
		(layer "In11.Cu")
		(net "P5E_CPU1_P1_RX_DP<15>")
	)
	(segment
		(start 109.363256 -275.776182)
		(end 109.433106 -275.706332)
		(width 0.1143)
		(layer "In11.Cu")
		(net "P5E_CPU1_P1_RX_DP<15>")
	)
	(segment
		(start 116.352066 -360.821224)
		(end 126.338584 -354.148898)
		(width 0.14224)
		(layer "In11.Cu")
		(net "P5E_CPU1_P1_RX_DP<15>")
	)
	(segment
		(start 105.621328 -378.248164)
		(end 105.621328 -377.122944)
		(width 0.14224)
		(layer "In11.Cu")
		(net "P5E_CPU1_P1_RX_DP<15>")
	)
	(segment
		(start 99.07651 -385.497832)
		(end 99.07651 -384.852418)
		(width 0.14224)
		(layer "In11.Cu")
		(net "P5E_CPU1_P1_RX_DP<15>")
	)
	(segment
		(start 105.618788 -378.250704)
		(end 105.621328 -378.248164)
		(width 0.14224)
		(layer "In11.Cu")
		(net "P5E_CPU1_P1_RX_DP<15>")
	)
	(segment
		(start 105.616248 -380.548642)
		(end 105.616248 -379.378464)
		(width 0.14224)
		(layer "In11.Cu")
		(net "P5E_CPU1_P1_RX_DP<15>")
	)
	(segment
		(start 105.613962 -380.550928)
		(end 105.616248 -380.548642)
		(width 0.14224)
		(layer "In11.Cu")
		(net "P5E_CPU1_P1_RX_DP<15>")
	)
	(segment
		(start 111.488728 -295.33596)
		(end 111.396272 -279.262332)
		(width 0.14224)
		(layer "In11.Cu")
		(net "P5E_CPU1_P1_RX_DP<15>")
	)
	(segment
		(start 111.058198 -278.13762)
		(end 111.037878 -278.1173)
		(width 0.1143)
		(layer "In11.Cu")
		(net "P5E_CPU1_P1_RX_DP<15>")
	)
	(segment
		(start 128.613154 -351.307146)
		(end 131.441952 -343.974928)
		(width 0.14224)
		(layer "In11.Cu")
		(net "P5E_CPU1_P1_RX_DP<15>")
	)
	(segment
		(start 109.542072 -276.027642)
		(end 109.54004 -276.026626)
		(width 0.1143)
		(layer "In11.Cu")
		(net "P5E_CPU1_P1_RX_DP<15>")
	)
	(segment
		(start 111.352838 -363.493812)
		(end 116.352066 -360.821224)
		(width 0.14224)
		(layer "In11.Cu")
		(net "P5E_CPU1_P1_RX_DP<15>")
	)
	(segment
		(start 110.973616 -278.1173)
		(end 110.534958 -277.678642)
		(width 0.1143)
		(layer "In11.Cu")
		(net "P5E_CPU1_P1_RX_DP<15>")
	)
	(arc
		(start 110.01248 -276.837902)
		(mid 109.875446 -276.701521)
		(end 109.825282 -276.514814)
		(width 0.1143)
		(layer "In11.Cu")
		(net "P5E_CPU1_P1_RX_DP<15>")
	)
	(arc
		(start 109.512354 -276.010624)
		(mid 109.415219 -275.907755)
		(end 109.363256 -275.776182)
		(width 0.1143)
		(layer "In11.Cu")
		(net "P5E_CPU1_P1_RX_DP<15>")
	)
	(arc
		(start 104.383078 -381.771398)
		(mid 104.592349 -381.73794)
		(end 104.780588 -381.640588)
		(width 0.14224)
		(layer "In11.Cu")
		(net "P5E_CPU1_P1_RX_DP<15>")
	)
	(arc
		(start 100.958904 -382.698498)
		(mid 100.993161 -382.526368)
		(end 101.09073 -382.38049)
		(width 0.14224)
		(layer "In11.Cu")
		(net "P5E_CPU1_P1_RX_DP<15>")
	)
	(arc
		(start 110.296452 -277.326344)
		(mid 110.231937 -277.064125)
		(end 110.05312 -276.861778)
		(width 0.1143)
		(layer "In11.Cu")
		(net "P5E_CPU1_P1_RX_DP<15>")
	)
	(arc
		(start 126.338584 -354.148898)
		(mid 127.695599 -352.903892)
		(end 128.613154 -351.307146)
		(width 0.14224)
		(layer "In11.Cu")
		(net "P5E_CPU1_P1_RX_DP<15>")
	)
	(arc
		(start 101.662484 -381.808736)
		(mid 101.703854 -381.781093)
		(end 101.752654 -381.771398)
		(width 0.14224)
		(layer "In11.Cu")
		(net "P5E_CPU1_P1_RX_DP<15>")
	)
	(arc
		(start 110.453424 -277.631144)
		(mid 110.337997 -277.497768)
		(end 110.296452 -277.326344)
		(width 0.1143)
		(layer "In11.Cu")
		(net "P5E_CPU1_P1_RX_DP<15>")
	)
	(arc
		(start 106.30789 -370.489734)
		(mid 106.55602 -369.216294)
		(end 106.979212 -367.989866)
		(width 0.14224)
		(layer "In11.Cu")
		(net "P5E_CPU1_P1_RX_DP<15>")
	)
	(arc
		(start 100.806504 -383.122424)
		(mid 100.919309 -382.953694)
		(end 100.958904 -382.754632)
		(width 0.14224)
		(layer "In11.Cu")
		(net "P5E_CPU1_P1_RX_DP<15>")
	)
	(arc
		(start 105.234232 -381.305054)
		(mid 105.513646 -380.973087)
		(end 105.613962 -380.550928)
		(width 0.14224)
		(layer "In11.Cu")
		(net "P5E_CPU1_P1_RX_DP<15>")
	)
	(arc
		(start 108.485432 -365.561626)
		(mid 108.79871 -365.229914)
		(end 109.158024 -364.948724)
		(width 0.14224)
		(layer "In11.Cu")
		(net "P5E_CPU1_P1_RX_DP<15>")
	)
	(arc
		(start 109.825282 -276.514814)
		(mid 109.75051 -276.235168)
		(end 109.546136 -276.030182)
		(width 0.1143)
		(layer "In11.Cu")
		(net "P5E_CPU1_P1_RX_DP<15>")
	)
	(arc
		(start 106.979212 -367.989866)
		(mid 107.569194 -366.834271)
		(end 108.31449 -365.772192)
		(width 0.14224)
		(layer "In11.Cu")
		(net "P5E_CPU1_P1_RX_DP<15>")
	)
	(segment
		(start 96.998282 -386.003292)
		(end 97.518982 -386.003292)
		(width 0.127)
		(layer "F.Cu")
		(net "P5E_CPU1_P1_RX_DP<14>")
	)
	(segment
		(start 110.1979 -277.060406)
		(end 109.731048 -277.326344)
		(width 0.12954)
		(layer "F.Cu")
		(net "P5E_CPU1_P1_RX_DP<14>")
	)
	(segment
		(start 128.260348 -349.529654)
		(end 128.260602 -349.528892)
		(width 0.14224)
		(layer "In11.Cu")
		(net "P5E_CPU1_P1_RX_DP<14>")
	)
	(segment
		(start 110.483904 -292.228778)
		(end 110.453424 -292.210998)
		(width 0.1143)
		(layer "In11.Cu")
		(net "P5E_CPU1_P1_RX_DP<14>")
	)
	(segment
		(start 109.55909 -277.65756)
		(end 109.55909 -277.657306)
		(width 0.1143)
		(layer "In11.Cu")
		(net "P5E_CPU1_P1_RX_DP<14>")
	)
	(segment
		(start 125.02007 -320.358008)
		(end 117.765068 -311.518046)
		(width 0.14224)
		(layer "In11.Cu")
		(net "P5E_CPU1_P1_RX_DP<14>")
	)
	(segment
		(start 112.520476 -303.669446)
		(end 110.341918 -298.409868)
		(width 0.14224)
		(layer "In11.Cu")
		(net "P5E_CPU1_P1_RX_DP<14>")
	)
	(segment
		(start 110.454186 -290.591494)
		(end 110.453424 -290.590986)
		(width 0.1143)
		(layer "In11.Cu")
		(net "P5E_CPU1_P1_RX_DP<14>")
	)
	(segment
		(start 97.887028 -382.56464)
		(end 104.127808 -372.386606)
		(width 0.14224)
		(layer "In11.Cu")
		(net "P5E_CPU1_P1_RX_DP<14>")
	)
	(segment
		(start 110.0455 -278.477218)
		(end 110.01502 -278.459438)
		(width 0.1143)
		(layer "In11.Cu")
		(net "P5E_CPU1_P1_RX_DP<14>")
	)
	(segment
		(start 110.453424 -289.981386)
		(end 110.483904 -289.963606)
		(width 0.1143)
		(layer "In11.Cu")
		(net "P5E_CPU1_P1_RX_DP<14>")
	)
	(segment
		(start 110.484158 -285.748984)
		(end 110.483904 -285.748984)
		(width 0.1143)
		(layer "In11.Cu")
		(net "P5E_CPU1_P1_RX_DP<14>")
	)
	(segment
		(start 110.014004 -278.45893)
		(end 109.939328 -278.411178)
		(width 0.1143)
		(layer "In11.Cu")
		(net "P5E_CPU1_P1_RX_DP<14>")
	)
	(segment
		(start 110.296198 -295.623234)
		(end 110.296198 -295.146222)
		(width 0.1143)
		(layer "In11.Cu")
		(net "P5E_CPU1_P1_RX_DP<14>")
	)
	(segment
		(start 110.520226 -279.290018)
		(end 110.483904 -279.268936)
		(width 0.1143)
		(layer "In11.Cu")
		(net "P5E_CPU1_P1_RX_DP<14>")
	)
	(segment
		(start 110.766098 -292.716204)
		(end 110.766098 -292.702996)
		(width 0.1143)
		(layer "In11.Cu")
		(net "P5E_CPU1_P1_RX_DP<14>")
	)
	(segment
		(start 110.485174 -293.203122)
		(end 110.50524 -293.191184)
		(width 0.1143)
		(layer "In11.Cu")
		(net "P5E_CPU1_P1_RX_DP<14>")
	)
	(segment
		(start 110.483904 -281.8638)
		(end 110.563406 -281.817318)
		(width 0.1143)
		(layer "In11.Cu")
		(net "P5E_CPU1_P1_RX_DP<14>")
	)
	(segment
		(start 110.766352 -292.716204)
		(end 110.766098 -292.716204)
		(width 0.1143)
		(layer "In11.Cu")
		(net "P5E_CPU1_P1_RX_DP<14>")
	)
	(segment
		(start 110.484158 -285.749238)
		(end 110.484158 -285.748984)
		(width 0.1143)
		(layer "In11.Cu")
		(net "P5E_CPU1_P1_RX_DP<14>")
	)
	(segment
		(start 109.55909 -277.657306)
		(end 109.55528 -277.65502)
		(width 0.1143)
		(layer "In11.Cu")
		(net "P5E_CPU1_P1_RX_DP<14>")
	)
	(segment
		(start 97.563432 -384.3528)
		(end 97.868232 -384.048)
		(width 0.14224)
		(layer "In11.Cu")
		(net "P5E_CPU1_P1_RX_DP<14>")
	)
	(segment
		(start 110.483904 -279.268936)
		(end 110.453424 -279.251156)
		(width 0.1143)
		(layer "In11.Cu")
		(net "P5E_CPU1_P1_RX_DP<14>")
	)
	(segment
		(start 110.453424 -280.261568)
		(end 110.52302 -280.220928)
		(width 0.1143)
		(layer "In11.Cu")
		(net "P5E_CPU1_P1_RX_DP<14>")
	)
	(segment
		(start 110.453424 -291.601398)
		(end 110.483904 -291.583618)
		(width 0.1143)
		(layer "In11.Cu")
		(net "P5E_CPU1_P1_RX_DP<14>")
	)
	(segment
		(start 110.484158 -288.34334)
		(end 110.523782 -288.320226)
		(width 0.1143)
		(layer "In11.Cu")
		(net "P5E_CPU1_P1_RX_DP<14>")
	)
	(segment
		(start 110.483904 -290.608766)
		(end 110.454186 -290.591494)
		(width 0.1143)
		(layer "In11.Cu")
		(net "P5E_CPU1_P1_RX_DP<14>")
	)
	(segment
		(start 110.451392 -286.742632)
		(end 110.537752 -286.69234)
		(width 0.1143)
		(layer "In11.Cu")
		(net "P5E_CPU1_P1_RX_DP<14>")
	)
	(segment
		(start 130.497072 -343.731088)
		(end 130.497072 -339.10778)
		(width 0.14224)
		(layer "In11.Cu")
		(net "P5E_CPU1_P1_RX_DP<14>")
	)
	(segment
		(start 110.563406 -280.93543)
		(end 110.453424 -280.871168)
		(width 0.1143)
		(layer "In11.Cu")
		(net "P5E_CPU1_P1_RX_DP<14>")
	)
	(segment
		(start 110.483904 -288.988754)
		(end 110.453424 -288.970974)
		(width 0.1143)
		(layer "In11.Cu")
		(net "P5E_CPU1_P1_RX_DP<14>")
	)
	(segment
		(start 97.518982 -386.003292)
		(end 97.613978 -385.649216)
		(width 0.14224)
		(layer "In11.Cu")
		(net "P5E_CPU1_P1_RX_DP<14>")
	)
	(segment
		(start 128.233678 -326.50684)
		(end 125.02007 -320.358008)
		(width 0.14224)
		(layer "In11.Cu")
		(net "P5E_CPU1_P1_RX_DP<14>")
	)
	(segment
		(start 110.516416 -293.18458)
		(end 110.52302 -293.18077)
		(width 0.1143)
		(layer "In11.Cu")
		(net "P5E_CPU1_P1_RX_DP<14>")
	)
	(segment
		(start 109.363256 -277.396194)
		(end 109.433106 -277.326344)
		(width 0.1143)
		(layer "In11.Cu")
		(net "P5E_CPU1_P1_RX_DP<14>")
	)
	(segment
		(start 117.765068 -311.518046)
		(end 112.520476 -303.669446)
		(width 0.14224)
		(layer "In11.Cu")
		(net "P5E_CPU1_P1_RX_DP<14>")
	)
	(segment
		(start 110.766352 -279.756362)
		(end 110.766098 -279.756362)
		(width 0.1143)
		(layer "In11.Cu")
		(net "P5E_CPU1_P1_RX_DP<14>")
	)
	(segment
		(start 110.483904 -289.963606)
		(end 110.520226 -289.942524)
		(width 0.1143)
		(layer "In11.Cu")
		(net "P5E_CPU1_P1_RX_DP<14>")
	)
	(segment
		(start 110.046262 -278.477726)
		(end 110.0455 -278.477218)
		(width 0.1143)
		(layer "In11.Cu")
		(net "P5E_CPU1_P1_RX_DP<14>")
	)
	(segment
		(start 97.87636 -385.460494)
		(end 97.87636 -385.046982)
		(width 0.14224)
		(layer "In11.Cu")
		(net "P5E_CPU1_P1_RX_DP<14>")
	)
	(segment
		(start 110.50524 -293.191184)
		(end 110.505494 -293.191184)
		(width 0.1143)
		(layer "In11.Cu")
		(net "P5E_CPU1_P1_RX_DP<14>")
	)
	(segment
		(start 110.52048 -287.390078)
		(end 110.453424 -287.350962)
		(width 0.1143)
		(layer "In11.Cu")
		(net "P5E_CPU1_P1_RX_DP<14>")
	)
	(segment
		(start 110.521496 -285.770828)
		(end 110.484158 -285.749238)
		(width 0.1143)
		(layer "In11.Cu")
		(net "P5E_CPU1_P1_RX_DP<14>")
	)
	(segment
		(start 110.341918 -298.409868)
		(end 110.341918 -295.697402)
		(width 0.14224)
		(layer "In11.Cu")
		(net "P5E_CPU1_P1_RX_DP<14>")
	)
	(segment
		(start 109.826298 -278.194516)
		(end 109.826298 -278.13635)
		(width 0.1143)
		(layer "In11.Cu")
		(net "P5E_CPU1_P1_RX_DP<14>")
	)
	(segment
		(start 110.520226 -290.629848)
		(end 110.483904 -290.608766)
		(width 0.1143)
		(layer "In11.Cu")
		(net "P5E_CPU1_P1_RX_DP<14>")
	)
	(segment
		(start 97.560384 -384.731006)
		(end 97.563432 -384.3528)
		(width 0.14224)
		(layer "In11.Cu")
		(net "P5E_CPU1_P1_RX_DP<14>")
	)
	(segment
		(start 110.483904 -291.583618)
		(end 110.520226 -291.562536)
		(width 0.1143)
		(layer "In11.Cu")
		(net "P5E_CPU1_P1_RX_DP<14>")
	)
	(segment
		(start 110.341918 -295.697402)
		(end 110.341918 -295.668954)
		(width 0.1143)
		(layer "In11.Cu")
		(net "P5E_CPU1_P1_RX_DP<14>")
	)
	(segment
		(start 97.613978 -385.649216)
		(end 97.788222 -385.548632)
		(width 0.14224)
		(layer "In11.Cu")
		(net "P5E_CPU1_P1_RX_DP<14>")
	)
	(segment
		(start 110.520226 -289.009836)
		(end 110.483904 -288.988754)
		(width 0.1143)
		(layer "In11.Cu")
		(net "P5E_CPU1_P1_RX_DP<14>")
	)
	(segment
		(start 109.433106 -277.326344)
		(end 109.731048 -277.326344)
		(width 0.1143)
		(layer "In11.Cu")
		(net "P5E_CPU1_P1_RX_DP<14>")
	)
	(segment
		(start 110.341918 -295.668954)
		(end 110.296198 -295.623234)
		(width 0.1143)
		(layer "In11.Cu")
		(net "P5E_CPU1_P1_RX_DP<14>")
	)
	(segment
		(start 110.483904 -294.823642)
		(end 110.561882 -294.773858)
		(width 0.1143)
		(layer "In11.Cu")
		(net "P5E_CPU1_P1_RX_DP<14>")
	)
	(segment
		(start 110.453424 -294.841422)
		(end 110.483904 -294.823642)
		(width 0.1143)
		(layer "In11.Cu")
		(net "P5E_CPU1_P1_RX_DP<14>")
	)
	(segment
		(start 110.766098 -284.628844)
		(end 110.766098 -284.616398)
		(width 0.1143)
		(layer "In11.Cu")
		(net "P5E_CPU1_P1_RX_DP<14>")
	)
	(segment
		(start 110.05312 -278.48179)
		(end 110.046262 -278.477726)
		(width 0.1143)
		(layer "In11.Cu")
		(net "P5E_CPU1_P1_RX_DP<14>")
	)
	(segment
		(start 127.881888 -350.51111)
		(end 128.260348 -349.529654)
		(width 0.14224)
		(layer "In11.Cu")
		(net "P5E_CPU1_P1_RX_DP<14>")
	)
	(segment
		(start 110.453424 -283.501592)
		(end 110.522766 -283.46146)
		(width 0.1143)
		(layer "In11.Cu")
		(net "P5E_CPU1_P1_RX_DP<14>")
	)
	(segment
		(start 105.238804 -370.042186)
		(end 105.99928 -367.856008)
		(width 0.14224)
		(layer "In11.Cu")
		(net "P5E_CPU1_P1_RX_DP<14>")
	)
	(segment
		(start 109.55528 -277.65502)
		(end 109.512354 -277.630636)
		(width 0.1143)
		(layer "In11.Cu")
		(net "P5E_CPU1_P1_RX_DP<14>")
	)
	(segment
		(start 110.766098 -286.236918)
		(end 110.766098 -286.23641)
		(width 0.1143)
		(layer "In11.Cu")
		(net "P5E_CPU1_P1_RX_DP<14>")
	)
	(segment
		(start 110.453424 -281.88158)
		(end 110.483904 -281.8638)
		(width 0.1143)
		(layer "In11.Cu")
		(net "P5E_CPU1_P1_RX_DP<14>")
	)
	(segment
		(start 128.260602 -349.528892)
		(end 130.497072 -343.731088)
		(width 0.14224)
		(layer "In11.Cu")
		(net "P5E_CPU1_P1_RX_DP<14>")
	)
	(segment
		(start 110.520226 -282.530042)
		(end 110.453424 -282.49118)
		(width 0.1143)
		(layer "In11.Cu")
		(net "P5E_CPU1_P1_RX_DP<14>")
	)
	(segment
		(start 110.483904 -285.748984)
		(end 110.453424 -285.731204)
		(width 0.1143)
		(layer "In11.Cu")
		(net "P5E_CPU1_P1_RX_DP<14>")
	)
	(segment
		(start 110.505494 -293.191184)
		(end 110.516416 -293.18458)
		(width 0.1143)
		(layer "In11.Cu")
		(net "P5E_CPU1_P1_RX_DP<14>")
	)
	(segment
		(start 109.582204 -277.671022)
		(end 109.55909 -277.65756)
		(width 0.1143)
		(layer "In11.Cu")
		(net "P5E_CPU1_P1_RX_DP<14>")
	)
	(segment
		(start 105.99928 -367.856008)
		(end 107.393994 -364.782608)
		(width 0.14224)
		(layer "In11.Cu")
		(net "P5E_CPU1_P1_RX_DP<14>")
	)
	(segment
		(start 110.483904 -288.343848)
		(end 110.484158 -288.34334)
		(width 0.1143)
		(layer "In11.Cu")
		(net "P5E_CPU1_P1_RX_DP<14>")
	)
	(segment
		(start 109.826552 -278.194262)
		(end 109.826298 -278.194516)
		(width 0.1143)
		(layer "In11.Cu")
		(net "P5E_CPU1_P1_RX_DP<14>")
	)
	(segment
		(start 97.788222 -385.548632)
		(end 97.87636 -385.460494)
		(width 0.14224)
		(layer "In11.Cu")
		(net "P5E_CPU1_P1_RX_DP<14>")
	)
	(segment
		(start 110.451392 -288.362644)
		(end 110.483904 -288.343848)
		(width 0.1143)
		(layer "In11.Cu")
		(net "P5E_CPU1_P1_RX_DP<14>")
	)
	(segment
		(start 97.87636 -385.046982)
		(end 97.560384 -384.731006)
		(width 0.14224)
		(layer "In11.Cu")
		(net "P5E_CPU1_P1_RX_DP<14>")
	)
	(segment
		(start 110.561882 -293.898574)
		(end 110.52302 -293.87165)
		(width 0.1143)
		(layer "In11.Cu")
		(net "P5E_CPU1_P1_RX_DP<14>")
	)
	(segment
		(start 110.537752 -286.69234)
		(end 110.546388 -286.683704)
		(width 0.1143)
		(layer "In11.Cu")
		(net "P5E_CPU1_P1_RX_DP<14>")
	)
	(segment
		(start 130.497072 -339.10778)
		(end 128.233678 -326.50684)
		(width 0.14224)
		(layer "In11.Cu")
		(net "P5E_CPU1_P1_RX_DP<14>")
	)
	(segment
		(start 107.439206 -364.729522)
		(end 127.326644 -351.440496)
		(width 0.14224)
		(layer "In11.Cu")
		(net "P5E_CPU1_P1_RX_DP<14>")
	)
	(segment
		(start 110.531402 -292.25748)
		(end 110.483904 -292.228778)
		(width 0.1143)
		(layer "In11.Cu")
		(net "P5E_CPU1_P1_RX_DP<14>")
	)
	(segment
		(start 110.520226 -284.150054)
		(end 110.453424 -284.111192)
		(width 0.1143)
		(layer "In11.Cu")
		(net "P5E_CPU1_P1_RX_DP<14>")
	)
	(segment
		(start 110.01502 -278.459438)
		(end 110.014004 -278.45893)
		(width 0.1143)
		(layer "In11.Cu")
		(net "P5E_CPU1_P1_RX_DP<14>")
	)
	(segment
		(start 110.484158 -293.20363)
		(end 110.485174 -293.203122)
		(width 0.1143)
		(layer "In11.Cu")
		(net "P5E_CPU1_P1_RX_DP<14>")
	)
	(segment
		(start 110.521496 -293.870634)
		(end 110.47603 -293.843964)
		(width 0.1143)
		(layer "In11.Cu")
		(net "P5E_CPU1_P1_RX_DP<14>")
	)
	(segment
		(start 110.452154 -285.12262)
		(end 110.52429 -285.080202)
		(width 0.1143)
		(layer "In11.Cu")
		(net "P5E_CPU1_P1_RX_DP<14>")
	)
	(segment
		(start 97.868232 -384.048)
		(end 97.868232 -382.631188)
		(width 0.14224)
		(layer "In11.Cu")
		(net "P5E_CPU1_P1_RX_DP<14>")
	)
	(segment
		(start 110.45317 -294.841422)
		(end 110.453424 -294.841422)
		(width 0.1143)
		(layer "In11.Cu")
		(net "P5E_CPU1_P1_RX_DP<14>")
	)
	(arc
		(start 110.522766 -283.46146)
		(mid 110.690732 -283.253285)
		(end 110.766098 -282.99664)
		(width 0.1143)
		(layer "In11.Cu")
		(net "P5E_CPU1_P1_RX_DP<14>")
	)
	(arc
		(start 109.939328 -278.411178)
		(mid 109.856423 -278.316516)
		(end 109.826552 -278.194262)
		(width 0.1143)
		(layer "In11.Cu")
		(net "P5E_CPU1_P1_RX_DP<14>")
	)
	(arc
		(start 110.563406 -281.817318)
		(mid 110.816377 -281.376374)
		(end 110.563406 -280.93543)
		(width 0.1143)
		(layer "In11.Cu")
		(net "P5E_CPU1_P1_RX_DP<14>")
	)
	(arc
		(start 109.826298 -278.13635)
		(mid 109.761576 -277.873611)
		(end 109.582204 -277.671022)
		(width 0.1143)
		(layer "In11.Cu")
		(net "P5E_CPU1_P1_RX_DP<14>")
	)
	(arc
		(start 110.296452 -287.046162)
		(mid 110.337418 -286.875756)
		(end 110.451392 -286.742632)
		(width 0.1143)
		(layer "In11.Cu")
		(net "P5E_CPU1_P1_RX_DP<14>")
	)
	(arc
		(start 97.868232 -382.631188)
		(mid 97.87302 -382.596611)
		(end 97.887028 -382.56464)
		(width 0.14224)
		(layer "In11.Cu")
		(net "P5E_CPU1_P1_RX_DP<14>")
	)
	(arc
		(start 110.52302 -293.18077)
		(mid 110.696853 -292.987716)
		(end 110.765844 -292.737286)
		(width 0.1143)
		(layer "In11.Cu")
		(net "P5E_CPU1_P1_RX_DP<14>")
	)
	(arc
		(start 110.520226 -291.562536)
		(mid 110.766116 -291.096192)
		(end 110.520226 -290.629848)
		(width 0.1143)
		(layer "In11.Cu")
		(net "P5E_CPU1_P1_RX_DP<14>")
	)
	(arc
		(start 110.52302 -280.220928)
		(mid 110.698765 -280.016975)
		(end 110.766352 -279.756362)
		(width 0.1143)
		(layer "In11.Cu")
		(net "P5E_CPU1_P1_RX_DP<14>")
	)
	(arc
		(start 110.453424 -284.111192)
		(mid 110.296447 -283.806392)
		(end 110.453424 -283.501592)
		(width 0.1143)
		(layer "In11.Cu")
		(net "P5E_CPU1_P1_RX_DP<14>")
	)
	(arc
		(start 110.52302 -293.87165)
		(mid 110.522258 -293.871141)
		(end 110.521496 -293.870634)
		(width 0.1143)
		(layer "In11.Cu")
		(net "P5E_CPU1_P1_RX_DP<14>")
	)
	(arc
		(start 110.762288 -287.790128)
		(mid 110.684724 -287.563893)
		(end 110.52048 -287.390078)
		(width 0.1143)
		(layer "In11.Cu")
		(net "P5E_CPU1_P1_RX_DP<14>")
	)
	(arc
		(start 110.766098 -292.702996)
		(mid 110.703894 -292.451187)
		(end 110.531402 -292.25748)
		(width 0.1143)
		(layer "In11.Cu")
		(net "P5E_CPU1_P1_RX_DP<14>")
	)
	(arc
		(start 110.766098 -286.23641)
		(mid 110.70128 -285.973421)
		(end 110.521496 -285.770828)
		(width 0.1143)
		(layer "In11.Cu")
		(net "P5E_CPU1_P1_RX_DP<14>")
	)
	(arc
		(start 104.127808 -372.386606)
		(mid 104.746394 -371.244292)
		(end 105.238804 -370.042186)
		(width 0.14224)
		(layer "In11.Cu")
		(net "P5E_CPU1_P1_RX_DP<14>")
	)
	(arc
		(start 110.453424 -288.970974)
		(mid 110.337997 -288.837598)
		(end 110.296452 -288.666174)
		(width 0.1143)
		(layer "In11.Cu")
		(net "P5E_CPU1_P1_RX_DP<14>")
	)
	(arc
		(start 110.766098 -279.756362)
		(mid 110.700862 -279.492771)
		(end 110.520226 -279.290018)
		(width 0.1143)
		(layer "In11.Cu")
		(net "P5E_CPU1_P1_RX_DP<14>")
	)
	(arc
		(start 110.296198 -295.146222)
		(mid 110.337747 -294.9748)
		(end 110.45317 -294.841422)
		(width 0.1143)
		(layer "In11.Cu")
		(net "P5E_CPU1_P1_RX_DP<14>")
	)
	(arc
		(start 110.453424 -292.210998)
		(mid 110.296447 -291.906198)
		(end 110.453424 -291.601398)
		(width 0.1143)
		(layer "In11.Cu")
		(net "P5E_CPU1_P1_RX_DP<14>")
	)
	(arc
		(start 110.47603 -293.843964)
		(mid 110.299122 -293.521483)
		(end 110.484158 -293.20363)
		(width 0.1143)
		(layer "In11.Cu")
		(net "P5E_CPU1_P1_RX_DP<14>")
	)
	(arc
		(start 110.296452 -288.666174)
		(mid 110.337418 -288.495768)
		(end 110.451392 -288.362644)
		(width 0.1143)
		(layer "In11.Cu")
		(net "P5E_CPU1_P1_RX_DP<14>")
	)
	(arc
		(start 110.765082 -282.961842)
		(mid 110.692605 -282.717614)
		(end 110.520226 -282.530042)
		(width 0.1143)
		(layer "In11.Cu")
		(net "P5E_CPU1_P1_RX_DP<14>")
	)
	(arc
		(start 110.523782 -288.320226)
		(mid 110.690348 -288.113318)
		(end 110.766098 -287.858708)
		(width 0.1143)
		(layer "In11.Cu")
		(net "P5E_CPU1_P1_RX_DP<14>")
	)
	(arc
		(start 110.766098 -287.858708)
		(mid 110.765238 -287.82436)
		(end 110.762288 -287.790128)
		(width 0.1143)
		(layer "In11.Cu")
		(net "P5E_CPU1_P1_RX_DP<14>")
	)
	(arc
		(start 109.512354 -277.630636)
		(mid 109.415219 -277.527767)
		(end 109.363256 -277.396194)
		(width 0.1143)
		(layer "In11.Cu")
		(net "P5E_CPU1_P1_RX_DP<14>")
	)
	(arc
		(start 110.561882 -294.773858)
		(mid 110.79106 -294.336216)
		(end 110.561882 -293.898574)
		(width 0.1143)
		(layer "In11.Cu")
		(net "P5E_CPU1_P1_RX_DP<14>")
	)
	(arc
		(start 127.326644 -351.440496)
		(mid 127.643975 -350.999524)
		(end 127.881888 -350.51111)
		(width 0.14224)
		(layer "In11.Cu")
		(net "P5E_CPU1_P1_RX_DP<14>")
	)
	(arc
		(start 110.453424 -282.49118)
		(mid 110.296447 -282.18638)
		(end 110.453424 -281.88158)
		(width 0.1143)
		(layer "In11.Cu")
		(net "P5E_CPU1_P1_RX_DP<14>")
	)
	(arc
		(start 110.453424 -280.871168)
		(mid 110.296447 -280.566368)
		(end 110.453424 -280.261568)
		(width 0.1143)
		(layer "In11.Cu")
		(net "P5E_CPU1_P1_RX_DP<14>")
	)
	(arc
		(start 110.453424 -279.251156)
		(mid 110.337997 -279.11778)
		(end 110.296452 -278.946356)
		(width 0.1143)
		(layer "In11.Cu")
		(net "P5E_CPU1_P1_RX_DP<14>")
	)
	(arc
		(start 110.544102 -285.06547)
		(mid 110.698661 -284.872044)
		(end 110.76559 -284.63367)
		(width 0.1143)
		(layer "In11.Cu")
		(net "P5E_CPU1_P1_RX_DP<14>")
	)
	(arc
		(start 110.546388 -286.683704)
		(mid 110.708198 -286.485861)
		(end 110.766098 -286.236918)
		(width 0.1143)
		(layer "In11.Cu")
		(net "P5E_CPU1_P1_RX_DP<14>")
	)
	(arc
		(start 110.453424 -285.731204)
		(mid 110.296554 -285.427216)
		(end 110.452154 -285.12262)
		(width 0.1143)
		(layer "In11.Cu")
		(net "P5E_CPU1_P1_RX_DP<14>")
	)
	(arc
		(start 110.453424 -287.350962)
		(mid 110.337997 -287.217586)
		(end 110.296452 -287.046162)
		(width 0.1143)
		(layer "In11.Cu")
		(net "P5E_CPU1_P1_RX_DP<14>")
	)
	(arc
		(start 110.766098 -284.616398)
		(mid 110.700862 -284.352807)
		(end 110.520226 -284.150054)
		(width 0.1143)
		(layer "In11.Cu")
		(net "P5E_CPU1_P1_RX_DP<14>")
	)
	(arc
		(start 110.52429 -285.080202)
		(mid 110.534277 -285.072945)
		(end 110.544102 -285.06547)
		(width 0.1143)
		(layer "In11.Cu")
		(net "P5E_CPU1_P1_RX_DP<14>")
	)
	(arc
		(start 110.766098 -282.99664)
		(mid 110.765861 -282.979233)
		(end 110.765082 -282.961842)
		(width 0.1143)
		(layer "In11.Cu")
		(net "P5E_CPU1_P1_RX_DP<14>")
	)
	(arc
		(start 110.296452 -278.946356)
		(mid 110.231937 -278.684137)
		(end 110.05312 -278.48179)
		(width 0.1143)
		(layer "In11.Cu")
		(net "P5E_CPU1_P1_RX_DP<14>")
	)
	(arc
		(start 110.453424 -290.590986)
		(mid 110.296447 -290.286186)
		(end 110.453424 -289.981386)
		(width 0.1143)
		(layer "In11.Cu")
		(net "P5E_CPU1_P1_RX_DP<14>")
	)
	(arc
		(start 110.76559 -284.63367)
		(mid 110.765849 -284.631258)
		(end 110.766098 -284.628844)
		(width 0.1143)
		(layer "In11.Cu")
		(net "P5E_CPU1_P1_RX_DP<14>")
	)
	(arc
		(start 107.393994 -364.782608)
		(mid 107.412917 -364.752936)
		(end 107.439206 -364.729522)
		(width 0.14224)
		(layer "In11.Cu")
		(net "P5E_CPU1_P1_RX_DP<14>")
	)
	(arc
		(start 110.520226 -289.942524)
		(mid 110.766116 -289.47618)
		(end 110.520226 -289.009836)
		(width 0.1143)
		(layer "In11.Cu")
		(net "P5E_CPU1_P1_RX_DP<14>")
	)
	(arc
		(start 110.765844 -292.737286)
		(mid 110.766196 -292.726747)
		(end 110.766352 -292.716204)
		(width 0.1143)
		(layer "In11.Cu")
		(net "P5E_CPU1_P1_RX_DP<14>")
	)
	(segment
		(start 95.798386 -386.003292)
		(end 96.319086 -386.003292)
		(width 0.127)
		(layer "F.Cu")
		(net "P5E_CPU1_P1_RX_DP<13>")
	)
	(segment
		(start 110.1979 -278.680418)
		(end 109.731048 -278.946356)
		(width 0.12954)
		(layer "F.Cu")
		(net "P5E_CPU1_P1_RX_DP<13>")
	)
	(segment
		(start 109.610906 -289.031426)
		(end 109.582966 -289.01136)
		(width 0.1143)
		(layer "In11.Cu")
		(net "P5E_CPU1_P1_RX_DP<13>")
	)
	(segment
		(start 109.543342 -288.988246)
		(end 109.542072 -288.987484)
		(width 0.1143)
		(layer "In11.Cu")
		(net "P5E_CPU1_P1_RX_DP<13>")
	)
	(segment
		(start 109.551724 -293.199312)
		(end 109.553248 -293.198296)
		(width 0.1143)
		(layer "In11.Cu")
		(net "P5E_CPU1_P1_RX_DP<13>")
	)
	(segment
		(start 109.539786 -288.986214)
		(end 109.53877 -288.985706)
		(width 0.1143)
		(layer "In11.Cu")
		(net "P5E_CPU1_P1_RX_DP<13>")
	)
	(segment
		(start 109.356144 -295.292272)
		(end 109.356398 -295.292018)
		(width 0.1143)
		(layer "In11.Cu")
		(net "P5E_CPU1_P1_RX_DP<13>")
	)
	(segment
		(start 109.544104 -284.128972)
		(end 109.512354 -284.110684)
		(width 0.1143)
		(layer "In11.Cu")
		(net "P5E_CPU1_P1_RX_DP<13>")
	)
	(segment
		(start 109.580426 -279.290018)
		(end 109.544104 -279.268936)
		(width 0.1143)
		(layer "In11.Cu")
		(net "P5E_CPU1_P1_RX_DP<13>")
	)
	(segment
		(start 109.580426 -282.530042)
		(end 109.544104 -282.50896)
		(width 0.1143)
		(layer "In11.Cu")
		(net "P5E_CPU1_P1_RX_DP<13>")
	)
	(segment
		(start 109.401864 -295.697402)
		(end 109.401864 -295.668954)
		(width 0.1143)
		(layer "In11.Cu")
		(net "P5E_CPU1_P1_RX_DP<13>")
	)
	(segment
		(start 109.527848 -293.21252)
		(end 109.54512 -293.202868)
		(width 0.1143)
		(layer "In11.Cu")
		(net "P5E_CPU1_P1_RX_DP<13>")
	)
	(segment
		(start 109.582966 -293.181024)
		(end 109.610906 -293.160958)
		(width 0.1143)
		(layer "In11.Cu")
		(net "P5E_CPU1_P1_RX_DP<13>")
	)
	(segment
		(start 109.543342 -291.584126)
		(end 109.544104 -291.583618)
		(width 0.1143)
		(layer "In11.Cu")
		(net "P5E_CPU1_P1_RX_DP<13>")
	)
	(segment
		(start 109.56544 -293.861236)
		(end 109.564678 -293.860728)
		(width 0.1143)
		(layer "In11.Cu")
		(net "P5E_CPU1_P1_RX_DP<13>")
	)
	(segment
		(start 109.65688 -287.459928)
		(end 109.518958 -287.36163)
		(width 0.1143)
		(layer "In11.Cu")
		(net "P5E_CPU1_P1_RX_DP<13>")
	)
	(segment
		(start 109.363256 -279.016206)
		(end 109.433106 -278.946356)
		(width 0.1143)
		(layer "In11.Cu")
		(net "P5E_CPU1_P1_RX_DP<13>")
	)
	(segment
		(start 96.414082 -385.649216)
		(end 96.588326 -385.548632)
		(width 0.14224)
		(layer "In11.Cu")
		(net "P5E_CPU1_P1_RX_DP<13>")
	)
	(segment
		(start 106.510836 -364.216696)
		(end 125.673358 -351.412556)
		(width 0.14224)
		(layer "In11.Cu")
		(net "P5E_CPU1_P1_RX_DP<13>")
	)
	(segment
		(start 109.544104 -290.608766)
		(end 109.512354 -290.590478)
		(width 0.1143)
		(layer "In11.Cu")
		(net "P5E_CPU1_P1_RX_DP<13>")
	)
	(segment
		(start 109.543342 -289.964114)
		(end 109.545628 -289.96259)
		(width 0.1143)
		(layer "In11.Cu")
		(net "P5E_CPU1_P1_RX_DP<13>")
	)
	(segment
		(start 109.356398 -287.046416)
		(end 109.356144 -287.046162)
		(width 0.1143)
		(layer "In11.Cu")
		(net "P5E_CPU1_P1_RX_DP<13>")
	)
	(segment
		(start 96.668336 -383.864104)
		(end 96.668336 -382.52146)
		(width 0.14224)
		(layer "In11.Cu")
		(net "P5E_CPU1_P1_RX_DP<13>")
	)
	(segment
		(start 109.535468 -292.223952)
		(end 109.533436 -292.222936)
		(width 0.1143)
		(layer "In11.Cu")
		(net "P5E_CPU1_P1_RX_DP<13>")
	)
	(segment
		(start 126.799848 -350.03994)
		(end 129.521204 -343.469976)
		(width 0.14224)
		(layer "In11.Cu")
		(net "P5E_CPU1_P1_RX_DP<13>")
	)
	(segment
		(start 109.546898 -288.990532)
		(end 109.544104 -288.988754)
		(width 0.1143)
		(layer "In11.Cu")
		(net "P5E_CPU1_P1_RX_DP<13>")
	)
	(segment
		(start 96.319086 -386.003292)
		(end 96.414082 -385.649216)
		(width 0.14224)
		(layer "In11.Cu")
		(net "P5E_CPU1_P1_RX_DP<13>")
	)
	(segment
		(start 109.540548 -288.986722)
		(end 109.539786 -288.986214)
		(width 0.1143)
		(layer "In11.Cu")
		(net "P5E_CPU1_P1_RX_DP<13>")
	)
	(segment
		(start 96.360488 -384.731006)
		(end 96.363028 -384.419602)
		(width 0.14224)
		(layer "In11.Cu")
		(net "P5E_CPU1_P1_RX_DP<13>")
	)
	(segment
		(start 109.544104 -288.343848)
		(end 109.54385 -288.343594)
		(width 0.1143)
		(layer "In11.Cu")
		(net "P5E_CPU1_P1_RX_DP<13>")
	)
	(segment
		(start 96.676464 -385.046982)
		(end 96.360488 -384.731006)
		(width 0.14224)
		(layer "In11.Cu")
		(net "P5E_CPU1_P1_RX_DP<13>")
	)
	(segment
		(start 109.512354 -281.882088)
		(end 109.544104 -281.8638)
		(width 0.1143)
		(layer "In11.Cu")
		(net "P5E_CPU1_P1_RX_DP<13>")
	)
	(segment
		(start 96.676464 -385.460494)
		(end 96.676464 -385.046982)
		(width 0.14224)
		(layer "In11.Cu")
		(net "P5E_CPU1_P1_RX_DP<13>")
	)
	(segment
		(start 109.433106 -278.946356)
		(end 109.731048 -278.946356)
		(width 0.1143)
		(layer "In11.Cu")
		(net "P5E_CPU1_P1_RX_DP<13>")
	)
	(segment
		(start 109.533436 -292.222936)
		(end 109.512354 -292.21049)
		(width 0.1143)
		(layer "In11.Cu")
		(net "P5E_CPU1_P1_RX_DP<13>")
	)
	(segment
		(start 109.544104 -279.268936)
		(end 109.512354 -279.250648)
		(width 0.1143)
		(layer "In11.Cu")
		(net "P5E_CPU1_P1_RX_DP<13>")
	)
	(segment
		(start 109.53877 -288.985706)
		(end 109.512354 -288.970466)
		(width 0.1143)
		(layer "In11.Cu")
		(net "P5E_CPU1_P1_RX_DP<13>")
	)
	(segment
		(start 109.544104 -280.243788)
		(end 109.580426 -280.222706)
		(width 0.1143)
		(layer "In11.Cu")
		(net "P5E_CPU1_P1_RX_DP<13>")
	)
	(segment
		(start 109.356144 -295.623234)
		(end 109.356144 -295.292272)
		(width 0.1143)
		(layer "In11.Cu")
		(net "P5E_CPU1_P1_RX_DP<13>")
	)
	(segment
		(start 109.401864 -298.582842)
		(end 109.401864 -295.697402)
		(width 0.14224)
		(layer "In11.Cu")
		(net "P5E_CPU1_P1_RX_DP<13>")
	)
	(segment
		(start 109.580426 -284.150054)
		(end 109.544104 -284.128972)
		(width 0.1143)
		(layer "In11.Cu")
		(net "P5E_CPU1_P1_RX_DP<13>")
	)
	(segment
		(start 109.54004 -292.226492)
		(end 109.5375 -292.225222)
		(width 0.1143)
		(layer "In11.Cu")
		(net "P5E_CPU1_P1_RX_DP<13>")
	)
	(segment
		(start 109.540802 -292.227)
		(end 109.54004 -292.226492)
		(width 0.1143)
		(layer "In11.Cu")
		(net "P5E_CPU1_P1_RX_DP<13>")
	)
	(segment
		(start 109.54258 -292.228016)
		(end 109.541818 -292.227508)
		(width 0.1143)
		(layer "In11.Cu")
		(net "P5E_CPU1_P1_RX_DP<13>")
	)
	(segment
		(start 109.564678 -293.860728)
		(end 109.512354 -293.830502)
		(width 0.1143)
		(layer "In11.Cu")
		(net "P5E_CPU1_P1_RX_DP<13>")
	)
	(segment
		(start 109.580426 -285.770066)
		(end 109.544104 -285.748984)
		(width 0.1143)
		(layer "In11.Cu")
		(net "P5E_CPU1_P1_RX_DP<13>")
	)
	(segment
		(start 109.5375 -292.225222)
		(end 109.536738 -292.224714)
		(width 0.1143)
		(layer "In11.Cu")
		(net "P5E_CPU1_P1_RX_DP<13>")
	)
	(segment
		(start 109.553248 -293.198296)
		(end 109.554264 -293.197788)
		(width 0.1143)
		(layer "In11.Cu")
		(net "P5E_CPU1_P1_RX_DP<13>")
	)
	(segment
		(start 104.318308 -369.62715)
		(end 105.202228 -366.985042)
		(width 0.14224)
		(layer "In11.Cu")
		(net "P5E_CPU1_P1_RX_DP<13>")
	)
	(segment
		(start 109.542072 -288.987484)
		(end 109.540548 -288.986722)
		(width 0.1143)
		(layer "In11.Cu")
		(net "P5E_CPU1_P1_RX_DP<13>")
	)
	(segment
		(start 109.541818 -292.227508)
		(end 109.540802 -292.227)
		(width 0.1143)
		(layer "In11.Cu")
		(net "P5E_CPU1_P1_RX_DP<13>")
	)
	(segment
		(start 109.542072 -289.964876)
		(end 109.543342 -289.964114)
		(width 0.1143)
		(layer "In11.Cu")
		(net "P5E_CPU1_P1_RX_DP<13>")
	)
	(segment
		(start 96.8248 -381.970534)
		(end 103.91648 -370.484146)
		(width 0.14224)
		(layer "In11.Cu")
		(net "P5E_CPU1_P1_RX_DP<13>")
	)
	(segment
		(start 109.544104 -280.888948)
		(end 109.512354 -280.87066)
		(width 0.1143)
		(layer "In11.Cu")
		(net "P5E_CPU1_P1_RX_DP<13>")
	)
	(segment
		(start 109.512354 -283.5021)
		(end 109.544104 -283.483812)
		(width 0.1143)
		(layer "In11.Cu")
		(net "P5E_CPU1_P1_RX_DP<13>")
	)
	(segment
		(start 109.512354 -285.122112)
		(end 109.544104 -285.103824)
		(width 0.1143)
		(layer "In11.Cu")
		(net "P5E_CPU1_P1_RX_DP<13>")
	)
	(segment
		(start 96.588326 -385.548632)
		(end 96.676464 -385.460494)
		(width 0.14224)
		(layer "In11.Cu")
		(net "P5E_CPU1_P1_RX_DP<13>")
	)
	(segment
		(start 96.41078 -384.305556)
		(end 96.538542 -384.177794)
		(width 0.14224)
		(layer "In11.Cu")
		(net "P5E_CPU1_P1_RX_DP<13>")
	)
	(segment
		(start 109.554264 -293.197788)
		(end 109.555788 -293.196772)
		(width 0.1143)
		(layer "In11.Cu")
		(net "P5E_CPU1_P1_RX_DP<13>")
	)
	(segment
		(start 109.610906 -292.27145)
		(end 109.582966 -292.251384)
		(width 0.1143)
		(layer "In11.Cu")
		(net "P5E_CPU1_P1_RX_DP<13>")
	)
	(segment
		(start 109.512354 -294.84193)
		(end 109.56544 -294.811196)
		(width 0.1143)
		(layer "In11.Cu")
		(net "P5E_CPU1_P1_RX_DP<13>")
	)
	(segment
		(start 109.544104 -291.583618)
		(end 109.580426 -291.562536)
		(width 0.1143)
		(layer "In11.Cu")
		(net "P5E_CPU1_P1_RX_DP<13>")
	)
	(segment
		(start 109.544104 -288.988754)
		(end 109.543342 -288.988246)
		(width 0.1143)
		(layer "In11.Cu")
		(net "P5E_CPU1_P1_RX_DP<13>")
	)
	(segment
		(start 109.356398 -295.292018)
		(end 109.356398 -295.146222)
		(width 0.1143)
		(layer "In11.Cu")
		(net "P5E_CPU1_P1_RX_DP<13>")
	)
	(segment
		(start 124.306838 -321.02679)
		(end 117.23497 -312.410348)
		(width 0.14224)
		(layer "In11.Cu")
		(net "P5E_CPU1_P1_RX_DP<13>")
	)
	(segment
		(start 109.580426 -280.91003)
		(end 109.544104 -280.888948)
		(width 0.1143)
		(layer "In11.Cu")
		(net "P5E_CPU1_P1_RX_DP<13>")
	)
	(segment
		(start 109.549438 -293.200582)
		(end 109.551724 -293.199312)
		(width 0.1143)
		(layer "In11.Cu")
		(net "P5E_CPU1_P1_RX_DP<13>")
	)
	(segment
		(start 109.544104 -283.483812)
		(end 109.580426 -283.46273)
		(width 0.1143)
		(layer "In11.Cu")
		(net "P5E_CPU1_P1_RX_DP<13>")
	)
	(segment
		(start 127.327406 -326.806052)
		(end 124.306838 -321.02679)
		(width 0.14224)
		(layer "In11.Cu")
		(net "P5E_CPU1_P1_RX_DP<13>")
	)
	(segment
		(start 109.510576 -288.363406)
		(end 109.544104 -288.343848)
		(width 0.1143)
		(layer "In11.Cu")
		(net "P5E_CPU1_P1_RX_DP<13>")
	)
	(segment
		(start 109.582966 -289.01136)
		(end 109.546898 -288.990532)
		(width 0.1143)
		(layer "In11.Cu")
		(net "P5E_CPU1_P1_RX_DP<13>")
	)
	(segment
		(start 109.542072 -291.584888)
		(end 109.543342 -291.584126)
		(width 0.1143)
		(layer "In11.Cu")
		(net "P5E_CPU1_P1_RX_DP<13>")
	)
	(segment
		(start 109.580426 -290.629848)
		(end 109.544104 -290.608766)
		(width 0.1143)
		(layer "In11.Cu")
		(net "P5E_CPU1_P1_RX_DP<13>")
	)
	(segment
		(start 109.544104 -281.8638)
		(end 109.580426 -281.842718)
		(width 0.1143)
		(layer "In11.Cu")
		(net "P5E_CPU1_P1_RX_DP<13>")
	)
	(segment
		(start 109.826298 -287.856422)
		(end 109.826298 -287.85439)
		(width 0.1143)
		(layer "In11.Cu")
		(net "P5E_CPU1_P1_RX_DP<13>")
	)
	(segment
		(start 109.512354 -291.601906)
		(end 109.542072 -291.584888)
		(width 0.1143)
		(layer "In11.Cu")
		(net "P5E_CPU1_P1_RX_DP<13>")
	)
	(segment
		(start 109.582966 -289.941)
		(end 109.610906 -289.920934)
		(width 0.1143)
		(layer "In11.Cu")
		(net "P5E_CPU1_P1_RX_DP<13>")
	)
	(segment
		(start 109.582966 -292.251384)
		(end 109.54258 -292.228016)
		(width 0.1143)
		(layer "In11.Cu")
		(net "P5E_CPU1_P1_RX_DP<13>")
	)
	(segment
		(start 109.512354 -293.221918)
		(end 109.527848 -293.21252)
		(width 0.1143)
		(layer "In11.Cu")
		(net "P5E_CPU1_P1_RX_DP<13>")
	)
	(segment
		(start 109.536738 -292.224714)
		(end 109.535468 -292.223952)
		(width 0.1143)
		(layer "In11.Cu")
		(net "P5E_CPU1_P1_RX_DP<13>")
	)
	(segment
		(start 109.545628 -289.96259)
		(end 109.582966 -289.941)
		(width 0.1143)
		(layer "In11.Cu")
		(net "P5E_CPU1_P1_RX_DP<13>")
	)
	(segment
		(start 105.202228 -366.985042)
		(end 106.42473 -364.317534)
		(width 0.14224)
		(layer "In11.Cu")
		(net "P5E_CPU1_P1_RX_DP<13>")
	)
	(segment
		(start 109.54385 -288.343594)
		(end 109.58576 -288.31921)
		(width 0.1143)
		(layer "In11.Cu")
		(net "P5E_CPU1_P1_RX_DP<13>")
	)
	(segment
		(start 109.401864 -295.668954)
		(end 109.356144 -295.623234)
		(width 0.1143)
		(layer "In11.Cu")
		(net "P5E_CPU1_P1_RX_DP<13>")
	)
	(segment
		(start 109.54512 -293.202868)
		(end 109.549438 -293.200582)
		(width 0.1143)
		(layer "In11.Cu")
		(net "P5E_CPU1_P1_RX_DP<13>")
	)
	(segment
		(start 111.695738 -304.120804)
		(end 109.401864 -298.582842)
		(width 0.14224)
		(layer "In11.Cu")
		(net "P5E_CPU1_P1_RX_DP<13>")
	)
	(segment
		(start 109.508798 -286.74441)
		(end 109.511338 -286.742886)
		(width 0.1143)
		(layer "In11.Cu")
		(net "P5E_CPU1_P1_RX_DP<13>")
	)
	(segment
		(start 109.555788 -293.196772)
		(end 109.582966 -293.181024)
		(width 0.1143)
		(layer "In11.Cu")
		(net "P5E_CPU1_P1_RX_DP<13>")
	)
	(segment
		(start 109.544104 -285.748984)
		(end 109.512354 -285.730696)
		(width 0.1143)
		(layer "In11.Cu")
		(net "P5E_CPU1_P1_RX_DP<13>")
	)
	(segment
		(start 109.544104 -285.103824)
		(end 109.580426 -285.082742)
		(width 0.1143)
		(layer "In11.Cu")
		(net "P5E_CPU1_P1_RX_DP<13>")
	)
	(segment
		(start 109.544104 -282.50896)
		(end 109.512354 -282.490672)
		(width 0.1143)
		(layer "In11.Cu")
		(net "P5E_CPU1_P1_RX_DP<13>")
	)
	(segment
		(start 129.521204 -339.019642)
		(end 127.327406 -326.806052)
		(width 0.14224)
		(layer "In11.Cu")
		(net "P5E_CPU1_P1_RX_DP<13>")
	)
	(segment
		(start 109.512354 -289.981894)
		(end 109.542072 -289.964876)
		(width 0.1143)
		(layer "In11.Cu")
		(net "P5E_CPU1_P1_RX_DP<13>")
	)
	(segment
		(start 117.23497 -312.410348)
		(end 111.695738 -304.120804)
		(width 0.14224)
		(layer "In11.Cu")
		(net "P5E_CPU1_P1_RX_DP<13>")
	)
	(segment
		(start 109.512354 -280.262076)
		(end 109.544104 -280.243788)
		(width 0.1143)
		(layer "In11.Cu")
		(net "P5E_CPU1_P1_RX_DP<13>")
	)
	(segment
		(start 129.521204 -343.469976)
		(end 129.521204 -339.019642)
		(width 0.14224)
		(layer "In11.Cu")
		(net "P5E_CPU1_P1_RX_DP<13>")
	)
	(segment
		(start 109.511338 -286.742886)
		(end 109.580426 -286.702754)
		(width 0.1143)
		(layer "In11.Cu")
		(net "P5E_CPU1_P1_RX_DP<13>")
	)
	(arc
		(start 109.59465 -280.919936)
		(mid 109.587576 -280.914929)
		(end 109.580426 -280.91003)
		(width 0.1143)
		(layer "In11.Cu")
		(net "P5E_CPU1_P1_RX_DP<13>")
	)
	(arc
		(start 109.610906 -293.160958)
		(mid 109.838906 -292.716204)
		(end 109.610906 -292.27145)
		(width 0.1143)
		(layer "In11.Cu")
		(net "P5E_CPU1_P1_RX_DP<13>")
	)
	(arc
		(start 109.512354 -293.830502)
		(mid 109.356426 -293.52621)
		(end 109.512354 -293.221918)
		(width 0.1143)
		(layer "In11.Cu")
		(net "P5E_CPU1_P1_RX_DP<13>")
	)
	(arc
		(start 109.512354 -284.110684)
		(mid 109.356426 -283.806392)
		(end 109.512354 -283.5021)
		(width 0.1143)
		(layer "In11.Cu")
		(net "P5E_CPU1_P1_RX_DP<13>")
	)
	(arc
		(start 96.668336 -382.52146)
		(mid 96.708254 -382.235119)
		(end 96.8248 -381.970534)
		(width 0.14224)
		(layer "In11.Cu")
		(net "P5E_CPU1_P1_RX_DP<13>")
	)
	(arc
		(start 125.673358 -351.412556)
		(mid 126.338393 -350.809789)
		(end 126.799848 -350.03994)
		(width 0.14224)
		(layer "In11.Cu")
		(net "P5E_CPU1_P1_RX_DP<13>")
	)
	(arc
		(start 109.595666 -290.640516)
		(mid 109.58809 -290.63512)
		(end 109.580426 -290.629848)
		(width 0.1143)
		(layer "In11.Cu")
		(net "P5E_CPU1_P1_RX_DP<13>")
	)
	(arc
		(start 109.580426 -280.222706)
		(mid 109.587575 -280.217806)
		(end 109.59465 -280.2128)
		(width 0.1143)
		(layer "In11.Cu")
		(net "P5E_CPU1_P1_RX_DP<13>")
	)
	(arc
		(start 109.512354 -288.970466)
		(mid 109.397678 -288.837132)
		(end 109.356398 -288.666174)
		(width 0.1143)
		(layer "In11.Cu")
		(net "P5E_CPU1_P1_RX_DP<13>")
	)
	(arc
		(start 109.610906 -289.920934)
		(mid 109.838906 -289.47618)
		(end 109.610906 -289.031426)
		(width 0.1143)
		(layer "In11.Cu")
		(net "P5E_CPU1_P1_RX_DP<13>")
	)
	(arc
		(start 109.59465 -283.452824)
		(mid 109.822033 -282.996386)
		(end 109.59465 -282.539948)
		(width 0.1143)
		(layer "In11.Cu")
		(net "P5E_CPU1_P1_RX_DP<13>")
	)
	(arc
		(start 103.91648 -370.484146)
		(mid 104.141979 -370.067175)
		(end 104.318308 -369.62715)
		(width 0.14224)
		(layer "In11.Cu")
		(net "P5E_CPU1_P1_RX_DP<13>")
	)
	(arc
		(start 109.580426 -286.702754)
		(mid 109.76261 -286.497084)
		(end 109.826298 -286.229806)
		(width 0.1143)
		(layer "In11.Cu")
		(net "P5E_CPU1_P1_RX_DP<13>")
	)
	(arc
		(start 109.512354 -279.250648)
		(mid 109.415219 -279.147779)
		(end 109.363256 -279.016206)
		(width 0.1143)
		(layer "In11.Cu")
		(net "P5E_CPU1_P1_RX_DP<13>")
	)
	(arc
		(start 109.595666 -285.072074)
		(mid 109.820837 -284.616398)
		(end 109.595666 -284.160722)
		(width 0.1143)
		(layer "In11.Cu")
		(net "P5E_CPU1_P1_RX_DP<13>")
	)
	(arc
		(start 109.595666 -291.551868)
		(mid 109.820837 -291.096192)
		(end 109.595666 -290.640516)
		(width 0.1143)
		(layer "In11.Cu")
		(net "P5E_CPU1_P1_RX_DP<13>")
	)
	(arc
		(start 109.59465 -280.2128)
		(mid 109.822033 -279.756362)
		(end 109.59465 -279.299924)
		(width 0.1143)
		(layer "In11.Cu")
		(net "P5E_CPU1_P1_RX_DP<13>")
	)
	(arc
		(start 109.512354 -282.490672)
		(mid 109.356426 -282.18638)
		(end 109.512354 -281.882088)
		(width 0.1143)
		(layer "In11.Cu")
		(net "P5E_CPU1_P1_RX_DP<13>")
	)
	(arc
		(start 109.580426 -283.46273)
		(mid 109.587575 -283.45783)
		(end 109.59465 -283.452824)
		(width 0.1143)
		(layer "In11.Cu")
		(net "P5E_CPU1_P1_RX_DP<13>")
	)
	(arc
		(start 96.538542 -384.177794)
		(mid 96.634732 -384.033885)
		(end 96.668336 -383.864104)
		(width 0.14224)
		(layer "In11.Cu")
		(net "P5E_CPU1_P1_RX_DP<13>")
	)
	(arc
		(start 109.59465 -282.539948)
		(mid 109.587576 -282.534941)
		(end 109.580426 -282.530042)
		(width 0.1143)
		(layer "In11.Cu")
		(net "P5E_CPU1_P1_RX_DP<13>")
	)
	(arc
		(start 109.595666 -284.160722)
		(mid 109.58809 -284.155326)
		(end 109.580426 -284.150054)
		(width 0.1143)
		(layer "In11.Cu")
		(net "P5E_CPU1_P1_RX_DP<13>")
	)
	(arc
		(start 96.363028 -384.419602)
		(mid 96.375696 -384.357895)
		(end 96.41078 -384.305556)
		(width 0.14224)
		(layer "In11.Cu")
		(net "P5E_CPU1_P1_RX_DP<13>")
	)
	(arc
		(start 109.512354 -292.21049)
		(mid 109.356426 -291.906198)
		(end 109.512354 -291.601906)
		(width 0.1143)
		(layer "In11.Cu")
		(net "P5E_CPU1_P1_RX_DP<13>")
	)
	(arc
		(start 109.512354 -285.730696)
		(mid 109.356426 -285.426404)
		(end 109.512354 -285.122112)
		(width 0.1143)
		(layer "In11.Cu")
		(net "P5E_CPU1_P1_RX_DP<13>")
	)
	(arc
		(start 109.356398 -295.146222)
		(mid 109.397653 -294.975251)
		(end 109.512354 -294.84193)
		(width 0.1143)
		(layer "In11.Cu")
		(net "P5E_CPU1_P1_RX_DP<13>")
	)
	(arc
		(start 109.512354 -290.590478)
		(mid 109.356426 -290.286186)
		(end 109.512354 -289.981894)
		(width 0.1143)
		(layer "In11.Cu")
		(net "P5E_CPU1_P1_RX_DP<13>")
	)
	(arc
		(start 109.58576 -288.31921)
		(mid 109.762652 -288.117242)
		(end 109.826298 -287.856422)
		(width 0.1143)
		(layer "In11.Cu")
		(net "P5E_CPU1_P1_RX_DP<13>")
	)
	(arc
		(start 109.518958 -287.36163)
		(mid 109.399476 -287.223722)
		(end 109.356398 -287.046416)
		(width 0.1143)
		(layer "In11.Cu")
		(net "P5E_CPU1_P1_RX_DP<13>")
	)
	(arc
		(start 109.356398 -288.666174)
		(mid 109.39716 -288.49629)
		(end 109.510576 -288.363406)
		(width 0.1143)
		(layer "In11.Cu")
		(net "P5E_CPU1_P1_RX_DP<13>")
	)
	(arc
		(start 109.826298 -286.229806)
		(mid 109.761426 -285.980064)
		(end 109.596682 -285.781496)
		(width 0.1143)
		(layer "In11.Cu")
		(net "P5E_CPU1_P1_RX_DP<13>")
	)
	(arc
		(start 109.596682 -285.781496)
		(mid 109.588604 -285.77571)
		(end 109.580426 -285.770066)
		(width 0.1143)
		(layer "In11.Cu")
		(net "P5E_CPU1_P1_RX_DP<13>")
	)
	(arc
		(start 106.42473 -364.317534)
		(mid 106.460791 -364.261148)
		(end 106.510836 -364.216696)
		(width 0.14224)
		(layer "In11.Cu")
		(net "P5E_CPU1_P1_RX_DP<13>")
	)
	(arc
		(start 109.56544 -294.811196)
		(mid 109.838991 -294.336216)
		(end 109.56544 -293.861236)
		(width 0.1143)
		(layer "In11.Cu")
		(net "P5E_CPU1_P1_RX_DP<13>")
	)
	(arc
		(start 109.356144 -287.046162)
		(mid 109.396473 -286.87707)
		(end 109.508798 -286.74441)
		(width 0.1143)
		(layer "In11.Cu")
		(net "P5E_CPU1_P1_RX_DP<13>")
	)
	(arc
		(start 109.59465 -279.299924)
		(mid 109.587576 -279.294917)
		(end 109.580426 -279.290018)
		(width 0.1143)
		(layer "In11.Cu")
		(net "P5E_CPU1_P1_RX_DP<13>")
	)
	(arc
		(start 109.512354 -280.87066)
		(mid 109.356426 -280.566368)
		(end 109.512354 -280.262076)
		(width 0.1143)
		(layer "In11.Cu")
		(net "P5E_CPU1_P1_RX_DP<13>")
	)
	(arc
		(start 109.580426 -285.082742)
		(mid 109.58809 -285.077471)
		(end 109.595666 -285.072074)
		(width 0.1143)
		(layer "In11.Cu")
		(net "P5E_CPU1_P1_RX_DP<13>")
	)
	(arc
		(start 109.826298 -287.85439)
		(mid 109.782145 -287.639745)
		(end 109.65688 -287.459928)
		(width 0.1143)
		(layer "In11.Cu")
		(net "P5E_CPU1_P1_RX_DP<13>")
	)
	(arc
		(start 109.580426 -281.842718)
		(mid 109.587575 -281.837818)
		(end 109.59465 -281.832812)
		(width 0.1143)
		(layer "In11.Cu")
		(net "P5E_CPU1_P1_RX_DP<13>")
	)
	(arc
		(start 109.580426 -291.562536)
		(mid 109.58809 -291.557265)
		(end 109.595666 -291.551868)
		(width 0.1143)
		(layer "In11.Cu")
		(net "P5E_CPU1_P1_RX_DP<13>")
	)
	(arc
		(start 109.59465 -281.832812)
		(mid 109.822033 -281.376374)
		(end 109.59465 -280.919936)
		(width 0.1143)
		(layer "In11.Cu")
		(net "P5E_CPU1_P1_RX_DP<13>")
	)
	(segment
		(start 94.598236 -386.003292)
		(end 95.118936 -386.003292)
		(width 0.127)
		(layer "F.Cu")
		(net "P5E_CPU1_P1_RX_DP<12>")
	)
	(segment
		(start 107.847892 -274.630388)
		(end 107.38104 -274.896326)
		(width 0.12954)
		(layer "F.Cu")
		(net "P5E_CPU1_P1_RX_DP<12>")
	)
	(segment
		(start 108.605066 -279.269444)
		(end 108.60405 -279.268936)
		(width 0.1143)
		(layer "In11.Cu")
		(net "P5E_CPU1_P1_RX_DP<12>")
	)
	(segment
		(start 108.608368 -294.821102)
		(end 108.609638 -294.82034)
		(width 0.1143)
		(layer "In11.Cu")
		(net "P5E_CPU1_P1_RX_DP<12>")
	)
	(segment
		(start 108.603288 -282.508452)
		(end 108.600494 -282.506928)
		(width 0.1143)
		(layer "In11.Cu")
		(net "P5E_CPU1_P1_RX_DP<12>")
	)
	(segment
		(start 108.643166 -285.771844)
		(end 108.636308 -285.76778)
		(width 0.1143)
		(layer "In11.Cu")
		(net "P5E_CPU1_P1_RX_DP<12>")
	)
	(segment
		(start 108.6358 -279.287478)
		(end 108.635038 -279.28697)
		(width 0.1143)
		(layer "In11.Cu")
		(net "P5E_CPU1_P1_RX_DP<12>")
	)
	(segment
		(start 108.587286 -280.25344)
		(end 108.588048 -280.252932)
		(width 0.1143)
		(layer "In11.Cu")
		(net "P5E_CPU1_P1_RX_DP<12>")
	)
	(segment
		(start 108.598716 -280.8859)
		(end 108.597954 -280.885392)
		(width 0.1143)
		(layer "In11.Cu")
		(net "P5E_CPU1_P1_RX_DP<12>")
	)
	(segment
		(start 128.567942 -342.751156)
		(end 128.586738 -342.702388)
		(width 0.14224)
		(layer "In11.Cu")
		(net "P5E_CPU1_P1_RX_DP<12>")
	)
	(segment
		(start 108.570522 -288.363406)
		(end 108.643166 -288.320988)
		(width 0.1143)
		(layer "In11.Cu")
		(net "P5E_CPU1_P1_RX_DP<12>")
	)
	(segment
		(start 108.572554 -293.222172)
		(end 108.600494 -293.205916)
		(width 0.1143)
		(layer "In11.Cu")
		(net "P5E_CPU1_P1_RX_DP<12>")
	)
	(segment
		(start 108.60405 -279.268936)
		(end 108.603288 -279.268428)
		(width 0.1143)
		(layer "In11.Cu")
		(net "P5E_CPU1_P1_RX_DP<12>")
	)
	(segment
		(start 123.523248 -321.542156)
		(end 116.482876 -312.96356)
		(width 0.14224)
		(layer "In11.Cu")
		(net "P5E_CPU1_P1_RX_DP<12>")
	)
	(segment
		(start 108.598716 -279.265888)
		(end 108.597954 -279.26538)
		(width 0.1143)
		(layer "In11.Cu")
		(net "P5E_CPU1_P1_RX_DP<12>")
	)
	(segment
		(start 108.41609 -295.623234)
		(end 108.41609 -295.42359)
		(width 0.1143)
		(layer "In11.Cu")
		(net "P5E_CPU1_P1_RX_DP<12>")
	)
	(segment
		(start 108.63326 -285.086806)
		(end 108.634022 -285.086298)
		(width 0.1143)
		(layer "In11.Cu")
		(net "P5E_CPU1_P1_RX_DP<12>")
	)
	(segment
		(start 108.612178 -281.858974)
		(end 108.625132 -281.851862)
		(width 0.1143)
		(layer "In11.Cu")
		(net "P5E_CPU1_P1_RX_DP<12>")
	)
	(segment
		(start 108.605066 -284.12948)
		(end 108.60405 -284.128972)
		(width 0.1143)
		(layer "In11.Cu")
		(net "P5E_CPU1_P1_RX_DP<12>")
	)
	(segment
		(start 95.552006 -381.815594)
		(end 103.338884 -369.44681)
		(width 0.14224)
		(layer "In11.Cu")
		(net "P5E_CPU1_P1_RX_DP<12>")
	)
	(segment
		(start 108.603288 -284.128464)
		(end 108.600494 -284.12694)
		(width 0.1143)
		(layer "In11.Cu")
		(net "P5E_CPU1_P1_RX_DP<12>")
	)
	(segment
		(start 108.6358 -280.90749)
		(end 108.635038 -280.906982)
		(width 0.1143)
		(layer "In11.Cu")
		(net "P5E_CPU1_P1_RX_DP<12>")
	)
	(segment
		(start 108.625894 -278.6126)
		(end 108.631482 -278.6126)
		(width 0.1143)
		(layer "In11.Cu")
		(net "P5E_CPU1_P1_RX_DP<12>")
	)
	(segment
		(start 108.603288 -280.88844)
		(end 108.600494 -280.886916)
		(width 0.1143)
		(layer "In11.Cu")
		(net "P5E_CPU1_P1_RX_DP<12>")
	)
	(segment
		(start 108.60659 -278.622252)
		(end 108.625894 -278.6126)
		(width 0.1143)
		(layer "In11.Cu")
		(net "P5E_CPU1_P1_RX_DP<12>")
	)
	(segment
		(start 108.643166 -282.53182)
		(end 108.636308 -282.527756)
		(width 0.1143)
		(layer "In11.Cu")
		(net "P5E_CPU1_P1_RX_DP<12>")
	)
	(segment
		(start 108.588048 -280.252932)
		(end 108.607606 -280.241756)
		(width 0.1143)
		(layer "In11.Cu")
		(net "P5E_CPU1_P1_RX_DP<12>")
	)
	(segment
		(start 108.60405 -282.50896)
		(end 108.603288 -282.508452)
		(width 0.1143)
		(layer "In11.Cu")
		(net "P5E_CPU1_P1_RX_DP<12>")
	)
	(segment
		(start 108.58754 -291.602922)
		(end 108.651548 -291.554916)
		(width 0.1143)
		(layer "In11.Cu")
		(net "P5E_CPU1_P1_RX_DP<12>")
	)
	(segment
		(start 108.60405 -284.128972)
		(end 108.603288 -284.128464)
		(width 0.1143)
		(layer "In11.Cu")
		(net "P5E_CPU1_P1_RX_DP<12>")
	)
	(segment
		(start 108.597954 -282.505404)
		(end 108.595414 -282.504134)
		(width 0.1143)
		(layer "In11.Cu")
		(net "P5E_CPU1_P1_RX_DP<12>")
	)
	(segment
		(start 108.41609 -295.42359)
		(end 108.416344 -295.423336)
		(width 0.1143)
		(layer "In11.Cu")
		(net "P5E_CPU1_P1_RX_DP<12>")
	)
	(segment
		(start 108.595414 -279.26411)
		(end 108.5723 -279.250648)
		(width 0.1143)
		(layer "In11.Cu")
		(net "P5E_CPU1_P1_RX_DP<12>")
	)
	(segment
		(start 108.5723 -281.882088)
		(end 108.5723 -281.882342)
		(width 0.1143)
		(layer "In11.Cu")
		(net "P5E_CPU1_P1_RX_DP<12>")
	)
	(segment
		(start 108.590842 -283.491432)
		(end 108.591858 -283.490924)
		(width 0.1143)
		(layer "In11.Cu")
		(net "P5E_CPU1_P1_RX_DP<12>")
	)
	(segment
		(start 108.643166 -292.251638)
		(end 108.5723 -292.21049)
		(width 0.1143)
		(layer "In11.Cu")
		(net "P5E_CPU1_P1_RX_DP<12>")
	)
	(segment
		(start 128.567688 -342.751156)
		(end 128.567942 -342.751156)
		(width 0.14224)
		(layer "In11.Cu")
		(net "P5E_CPU1_P1_RX_DP<12>")
	)
	(segment
		(start 108.636308 -285.76778)
		(end 108.635546 -285.767272)
		(width 0.1143)
		(layer "In11.Cu")
		(net "P5E_CPU1_P1_RX_DP<12>")
	)
	(segment
		(start 108.5723 -293.221918)
		(end 108.572554 -293.222172)
		(width 0.1143)
		(layer "In11.Cu")
		(net "P5E_CPU1_P1_RX_DP<12>")
	)
	(segment
		(start 108.5723 -294.84193)
		(end 108.596938 -294.827706)
		(width 0.1143)
		(layer "In11.Cu")
		(net "P5E_CPU1_P1_RX_DP<12>")
	)
	(segment
		(start 108.595414 -280.884122)
		(end 108.5723 -280.87066)
		(width 0.1143)
		(layer "In11.Cu")
		(net "P5E_CPU1_P1_RX_DP<12>")
	)
	(segment
		(start 108.62564 -285.091124)
		(end 108.62818 -285.089854)
		(width 0.1143)
		(layer "In11.Cu")
		(net "P5E_CPU1_P1_RX_DP<12>")
	)
	(segment
		(start 108.643166 -279.291796)
		(end 108.6358 -279.287478)
		(width 0.1143)
		(layer "In11.Cu")
		(net "P5E_CPU1_P1_RX_DP<12>")
	)
	(segment
		(start 108.643166 -289.011614)
		(end 108.5723 -288.970466)
		(width 0.1143)
		(layer "In11.Cu")
		(net "P5E_CPU1_P1_RX_DP<12>")
	)
	(segment
		(start 108.599732 -277.646384)
		(end 108.598716 -277.645876)
		(width 0.1143)
		(layer "In11.Cu")
		(net "P5E_CPU1_P1_RX_DP<12>")
	)
	(segment
		(start 108.605066 -285.749492)
		(end 108.60405 -285.748984)
		(width 0.1143)
		(layer "In11.Cu")
		(net "P5E_CPU1_P1_RX_DP<12>")
	)
	(segment
		(start 108.580174 -280.257504)
		(end 108.583222 -280.25598)
		(width 0.1143)
		(layer "In11.Cu")
		(net "P5E_CPU1_P1_RX_DP<12>")
	)
	(segment
		(start 108.643166 -283.463492)
		(end 108.643166 -283.460952)
		(width 0.1143)
		(layer "In11.Cu")
		(net "P5E_CPU1_P1_RX_DP<12>")
	)
	(segment
		(start 108.597954 -277.645368)
		(end 108.595414 -277.644098)
		(width 0.1143)
		(layer "In11.Cu")
		(net "P5E_CPU1_P1_RX_DP<12>")
	)
	(segment
		(start 95.163386 -384.3528)
		(end 95.468186 -384.048254)
		(width 0.14224)
		(layer "In11.Cu")
		(net "P5E_CPU1_P1_RX_DP<12>")
	)
	(segment
		(start 108.622084 -285.093156)
		(end 108.623608 -285.092394)
		(width 0.1143)
		(layer "In11.Cu")
		(net "P5E_CPU1_P1_RX_DP<12>")
	)
	(segment
		(start 108.595414 -285.744158)
		(end 108.5723 -285.730696)
		(width 0.1143)
		(layer "In11.Cu")
		(net "P5E_CPU1_P1_RX_DP<12>")
	)
	(segment
		(start 108.6358 -277.667466)
		(end 108.635038 -277.666958)
		(width 0.1143)
		(layer "In11.Cu")
		(net "P5E_CPU1_P1_RX_DP<12>")
	)
	(segment
		(start 108.598716 -285.745936)
		(end 108.597954 -285.745428)
		(width 0.1143)
		(layer "In11.Cu")
		(net "P5E_CPU1_P1_RX_DP<12>")
	)
	(segment
		(start 128.586738 -339.278214)
		(end 126.383796 -327.01484)
		(width 0.14224)
		(layer "In11.Cu")
		(net "P5E_CPU1_P1_RX_DP<12>")
	)
	(segment
		(start 108.5723 -285.122112)
		(end 108.620306 -285.094172)
		(width 0.1143)
		(layer "In11.Cu")
		(net "P5E_CPU1_P1_RX_DP<12>")
	)
	(segment
		(start 108.59008 -283.491686)
		(end 108.590842 -283.491432)
		(width 0.1143)
		(layer "In11.Cu")
		(net "P5E_CPU1_P1_RX_DP<12>")
	)
	(segment
		(start 108.600494 -294.825674)
		(end 108.602018 -294.824912)
		(width 0.1143)
		(layer "In11.Cu")
		(net "P5E_CPU1_P1_RX_DP<12>")
	)
	(segment
		(start 108.643166 -284.151832)
		(end 108.6358 -284.147514)
		(width 0.1143)
		(layer "In11.Cu")
		(net "P5E_CPU1_P1_RX_DP<12>")
	)
	(segment
		(start 108.607606 -280.241756)
		(end 108.60913 -280.240994)
		(width 0.1143)
		(layer "In11.Cu")
		(net "P5E_CPU1_P1_RX_DP<12>")
	)
	(segment
		(start 108.635546 -282.527248)
		(end 108.605066 -282.509468)
		(width 0.1143)
		(layer "In11.Cu")
		(net "P5E_CPU1_P1_RX_DP<12>")
	)
	(segment
		(start 108.636308 -282.527756)
		(end 108.635546 -282.527248)
		(width 0.1143)
		(layer "In11.Cu")
		(net "P5E_CPU1_P1_RX_DP<12>")
	)
	(segment
		(start 108.600494 -280.886916)
		(end 108.599732 -280.886408)
		(width 0.1143)
		(layer "In11.Cu")
		(net "P5E_CPU1_P1_RX_DP<12>")
	)
	(segment
		(start 108.605066 -280.889456)
		(end 108.60405 -280.888948)
		(width 0.1143)
		(layer "In11.Cu")
		(net "P5E_CPU1_P1_RX_DP<12>")
	)
	(segment
		(start 95.476314 -385.046982)
		(end 95.160338 -384.731006)
		(width 0.14224)
		(layer "In11.Cu")
		(net "P5E_CPU1_P1_RX_DP<12>")
	)
	(segment
		(start 108.640626 -287.390078)
		(end 108.5723 -287.350454)
		(width 0.1143)
		(layer "In11.Cu")
		(net "P5E_CPU1_P1_RX_DP<12>")
	)
	(segment
		(start 108.597954 -279.26538)
		(end 108.595414 -279.26411)
		(width 0.1143)
		(layer "In11.Cu")
		(net "P5E_CPU1_P1_RX_DP<12>")
	)
	(segment
		(start 108.625132 -281.851862)
		(end 108.625894 -281.851354)
		(width 0.1143)
		(layer "In11.Cu")
		(net "P5E_CPU1_P1_RX_DP<12>")
	)
	(segment
		(start 108.5723 -289.982148)
		(end 108.572554 -289.982402)
		(width 0.1143)
		(layer "In11.Cu")
		(net "P5E_CPU1_P1_RX_DP<12>")
	)
	(segment
		(start 108.621322 -285.093664)
		(end 108.622084 -285.093156)
		(width 0.1143)
		(layer "In11.Cu")
		(net "P5E_CPU1_P1_RX_DP<12>")
	)
	(segment
		(start 108.624878 -285.091632)
		(end 108.62564 -285.091124)
		(width 0.1143)
		(layer "In11.Cu")
		(net "P5E_CPU1_P1_RX_DP<12>")
	)
	(segment
		(start 108.651548 -290.647882)
		(end 108.565188 -290.595558)
		(width 0.1143)
		(layer "In11.Cu")
		(net "P5E_CPU1_P1_RX_DP<12>")
	)
	(segment
		(start 108.603288 -294.82415)
		(end 108.60405 -294.823642)
		(width 0.1143)
		(layer "In11.Cu")
		(net "P5E_CPU1_P1_RX_DP<12>")
	)
	(segment
		(start 108.595414 -277.644098)
		(end 108.5723 -277.630636)
		(width 0.1143)
		(layer "In11.Cu")
		(net "P5E_CPU1_P1_RX_DP<12>")
	)
	(segment
		(start 108.46181 -298.749974)
		(end 108.46181 -295.697402)
		(width 0.14224)
		(layer "In11.Cu")
		(net "P5E_CPU1_P1_RX_DP<12>")
	)
	(segment
		(start 108.5723 -278.642064)
		(end 108.60659 -278.622252)
		(width 0.1143)
		(layer "In11.Cu")
		(net "P5E_CPU1_P1_RX_DP<12>")
	)
	(segment
		(start 108.173012 -276.861778)
		(end 108.103416 -276.821138)
		(width 0.1143)
		(layer "In11.Cu")
		(net "P5E_CPU1_P1_RX_DP<12>")
	)
	(segment
		(start 108.60405 -280.888948)
		(end 108.603288 -280.88844)
		(width 0.1143)
		(layer "In11.Cu")
		(net "P5E_CPU1_P1_RX_DP<12>")
	)
	(segment
		(start 108.599732 -282.50642)
		(end 108.598716 -282.505912)
		(width 0.1143)
		(layer "In11.Cu")
		(net "P5E_CPU1_P1_RX_DP<12>")
	)
	(segment
		(start 126.383796 -327.01484)
		(end 123.523248 -321.542156)
		(width 0.14224)
		(layer "In11.Cu")
		(net "P5E_CPU1_P1_RX_DP<12>")
	)
	(segment
		(start 108.599732 -279.266396)
		(end 108.598716 -279.265888)
		(width 0.1143)
		(layer "In11.Cu")
		(net "P5E_CPU1_P1_RX_DP<12>")
	)
	(segment
		(start 108.584746 -280.254964)
		(end 108.587286 -280.25344)
		(width 0.1143)
		(layer "In11.Cu")
		(net "P5E_CPU1_P1_RX_DP<12>")
	)
	(segment
		(start 104.299004 -366.478566)
		(end 105.443528 -363.910372)
		(width 0.14224)
		(layer "In11.Cu")
		(net "P5E_CPU1_P1_RX_DP<12>")
	)
	(segment
		(start 108.5723 -291.601906)
		(end 108.58754 -291.602922)
		(width 0.1143)
		(layer "In11.Cu")
		(net "P5E_CPU1_P1_RX_DP<12>")
	)
	(segment
		(start 108.623608 -285.092394)
		(end 108.624878 -285.091632)
		(width 0.1143)
		(layer "In11.Cu")
		(net "P5E_CPU1_P1_RX_DP<12>")
	)
	(segment
		(start 108.597954 -285.745428)
		(end 108.595414 -285.744158)
		(width 0.1143)
		(layer "In11.Cu")
		(net "P5E_CPU1_P1_RX_DP<12>")
	)
	(segment
		(start 108.60405 -285.748984)
		(end 108.603288 -285.748476)
		(width 0.1143)
		(layer "In11.Cu")
		(net "P5E_CPU1_P1_RX_DP<12>")
	)
	(segment
		(start 108.600494 -293.205916)
		(end 108.600494 -293.205662)
		(width 0.1143)
		(layer "In11.Cu")
		(net "P5E_CPU1_P1_RX_DP<12>")
	)
	(segment
		(start 108.583222 -289.975544)
		(end 108.584238 -289.974782)
		(width 0.1143)
		(layer "In11.Cu")
		(net "P5E_CPU1_P1_RX_DP<12>")
	)
	(segment
		(start 108.600494 -284.12694)
		(end 108.599732 -284.126432)
		(width 0.1143)
		(layer "In11.Cu")
		(net "P5E_CPU1_P1_RX_DP<12>")
	)
	(segment
		(start 108.643166 -280.911808)
		(end 108.6358 -280.90749)
		(width 0.1143)
		(layer "In11.Cu")
		(net "P5E_CPU1_P1_RX_DP<12>")
	)
	(segment
		(start 108.605066 -294.823134)
		(end 108.60659 -294.822118)
		(width 0.1143)
		(layer "In11.Cu")
		(net "P5E_CPU1_P1_RX_DP<12>")
	)
	(segment
		(start 108.612432 -280.238962)
		(end 108.613956 -280.237946)
		(width 0.1143)
		(layer "In11.Cu")
		(net "P5E_CPU1_P1_RX_DP<12>")
	)
	(segment
		(start 108.596938 -294.827706)
		(end 108.599732 -294.826182)
		(width 0.1143)
		(layer "In11.Cu")
		(net "P5E_CPU1_P1_RX_DP<12>")
	)
	(segment
		(start 108.602018 -294.824912)
		(end 108.603288 -294.82415)
		(width 0.1143)
		(layer "In11.Cu")
		(net "P5E_CPU1_P1_RX_DP<12>")
	)
	(segment
		(start 108.46181 -295.668954)
		(end 108.41609 -295.623234)
		(width 0.1143)
		(layer "In11.Cu")
		(net "P5E_CPU1_P1_RX_DP<12>")
	)
	(segment
		(start 108.584238 -289.974782)
		(end 108.689648 -289.904424)
		(width 0.1143)
		(layer "In11.Cu")
		(net "P5E_CPU1_P1_RX_DP<12>")
	)
	(segment
		(start 108.620306 -285.094172)
		(end 108.621322 -285.093664)
		(width 0.1143)
		(layer "In11.Cu")
		(net "P5E_CPU1_P1_RX_DP<12>")
	)
	(segment
		(start 108.603288 -285.748476)
		(end 108.600494 -285.746952)
		(width 0.1143)
		(layer "In11.Cu")
		(net "P5E_CPU1_P1_RX_DP<12>")
	)
	(segment
		(start 108.60405 -277.648924)
		(end 108.603288 -277.648416)
		(width 0.1143)
		(layer "In11.Cu")
		(net "P5E_CPU1_P1_RX_DP<12>")
	)
	(segment
		(start 108.635546 -293.185342)
		(end 108.643166 -293.18077)
		(width 0.1143)
		(layer "In11.Cu")
		(net "P5E_CPU1_P1_RX_DP<12>")
	)
	(segment
		(start 108.630974 -285.088076)
		(end 108.63326 -285.086806)
		(width 0.1143)
		(layer "In11.Cu")
		(net "P5E_CPU1_P1_RX_DP<12>")
	)
	(segment
		(start 95.160338 -384.731006)
		(end 95.163386 -384.3528)
		(width 0.14224)
		(layer "In11.Cu")
		(net "P5E_CPU1_P1_RX_DP<12>")
	)
	(segment
		(start 108.570522 -286.743394)
		(end 108.643166 -286.700976)
		(width 0.1143)
		(layer "In11.Cu")
		(net "P5E_CPU1_P1_RX_DP<12>")
	)
	(segment
		(start 108.62818 -285.089854)
		(end 108.62945 -285.089092)
		(width 0.1143)
		(layer "In11.Cu")
		(net "P5E_CPU1_P1_RX_DP<12>")
	)
	(segment
		(start 95.118936 -386.003292)
		(end 95.213932 -385.649216)
		(width 0.14224)
		(layer "In11.Cu")
		(net "P5E_CPU1_P1_RX_DP<12>")
	)
	(segment
		(start 108.605066 -282.509468)
		(end 108.60405 -282.50896)
		(width 0.1143)
		(layer "In11.Cu")
		(net "P5E_CPU1_P1_RX_DP<12>")
	)
	(segment
		(start 108.643166 -281.841702)
		(end 108.643166 -281.84094)
		(width 0.1143)
		(layer "In11.Cu")
		(net "P5E_CPU1_P1_RX_DP<12>")
	)
	(segment
		(start 108.597954 -280.885392)
		(end 108.595414 -280.884122)
		(width 0.1143)
		(layer "In11.Cu")
		(net "P5E_CPU1_P1_RX_DP<12>")
	)
	(segment
		(start 108.599732 -284.126432)
		(end 108.598716 -284.125924)
		(width 0.1143)
		(layer "In11.Cu")
		(net "P5E_CPU1_P1_RX_DP<12>")
	)
	(segment
		(start 128.586738 -342.702388)
		(end 128.586738 -339.278214)
		(width 0.14224)
		(layer "In11.Cu")
		(net "P5E_CPU1_P1_RX_DP<12>")
	)
	(segment
		(start 95.476314 -385.460494)
		(end 95.476314 -385.046982)
		(width 0.14224)
		(layer "In11.Cu")
		(net "P5E_CPU1_P1_RX_DP<12>")
	)
	(segment
		(start 108.578904 -280.258266)
		(end 108.580174 -280.257504)
		(width 0.1143)
		(layer "In11.Cu")
		(net "P5E_CPU1_P1_RX_DP<12>")
	)
	(segment
		(start 108.635038 -279.28697)
		(end 108.605066 -279.269444)
		(width 0.1143)
		(layer "In11.Cu")
		(net "P5E_CPU1_P1_RX_DP<12>")
	)
	(segment
		(start 103.382318 -369.353338)
		(end 104.299004 -366.478566)
		(width 0.14224)
		(layer "In11.Cu")
		(net "P5E_CPU1_P1_RX_DP<12>")
	)
	(segment
		(start 108.60405 -294.823642)
		(end 108.605066 -294.823134)
		(width 0.1143)
		(layer "In11.Cu")
		(net "P5E_CPU1_P1_RX_DP<12>")
	)
	(segment
		(start 107.703112 -276.051772)
		(end 107.636564 -276.013164)
		(width 0.1143)
		(layer "In11.Cu")
		(net "P5E_CPU1_P1_RX_DP<12>")
	)
	(segment
		(start 108.600494 -282.506928)
		(end 108.599732 -282.50642)
		(width 0.1143)
		(layer "In11.Cu")
		(net "P5E_CPU1_P1_RX_DP<12>")
	)
	(segment
		(start 108.6358 -284.147514)
		(end 108.635038 -284.147006)
		(width 0.1143)
		(layer "In11.Cu")
		(net "P5E_CPU1_P1_RX_DP<12>")
	)
	(segment
		(start 95.388176 -385.548632)
		(end 95.476314 -385.460494)
		(width 0.14224)
		(layer "In11.Cu")
		(net "P5E_CPU1_P1_RX_DP<12>")
	)
	(segment
		(start 108.635038 -284.147006)
		(end 108.605066 -284.12948)
		(width 0.1143)
		(layer "In11.Cu")
		(net "P5E_CPU1_P1_RX_DP<12>")
	)
	(segment
		(start 108.60659 -294.822118)
		(end 108.608368 -294.821102)
		(width 0.1143)
		(layer "In11.Cu")
		(net "P5E_CPU1_P1_RX_DP<12>")
	)
	(segment
		(start 108.603288 -277.648416)
		(end 108.600494 -277.646892)
		(width 0.1143)
		(layer "In11.Cu")
		(net "P5E_CPU1_P1_RX_DP<12>")
	)
	(segment
		(start 108.599732 -280.886408)
		(end 108.598716 -280.8859)
		(width 0.1143)
		(layer "In11.Cu")
		(net "P5E_CPU1_P1_RX_DP<12>")
	)
	(segment
		(start 107.230418 -275.239988)
		(end 107.162346 -275.200618)
		(width 0.1143)
		(layer "In11.Cu")
		(net "P5E_CPU1_P1_RX_DP<12>")
	)
	(segment
		(start 108.597954 -284.125416)
		(end 108.595414 -284.124146)
		(width 0.1143)
		(layer "In11.Cu")
		(net "P5E_CPU1_P1_RX_DP<12>")
	)
	(segment
		(start 108.605066 -277.649432)
		(end 108.60405 -277.648924)
		(width 0.1143)
		(layer "In11.Cu")
		(net "P5E_CPU1_P1_RX_DP<12>")
	)
	(segment
		(start 105.721658 -363.580426)
		(end 124.519182 -351.020634)
		(width 0.14224)
		(layer "In11.Cu")
		(net "P5E_CPU1_P1_RX_DP<12>")
	)
	(segment
		(start 108.57738 -280.259282)
		(end 108.578904 -280.258266)
		(width 0.1143)
		(layer "In11.Cu")
		(net "P5E_CPU1_P1_RX_DP<12>")
	)
	(segment
		(start 108.635546 -285.767272)
		(end 108.605066 -285.749492)
		(width 0.1143)
		(layer "In11.Cu")
		(net "P5E_CPU1_P1_RX_DP<12>")
	)
	(segment
		(start 108.595414 -282.504134)
		(end 108.5723 -282.490672)
		(width 0.1143)
		(layer "In11.Cu")
		(net "P5E_CPU1_P1_RX_DP<12>")
	)
	(segment
		(start 108.598716 -284.125924)
		(end 108.597954 -284.125416)
		(width 0.1143)
		(layer "In11.Cu")
		(net "P5E_CPU1_P1_RX_DP<12>")
	)
	(segment
		(start 108.600494 -279.266904)
		(end 108.599732 -279.266396)
		(width 0.1143)
		(layer "In11.Cu")
		(net "P5E_CPU1_P1_RX_DP<12>")
	)
	(segment
		(start 108.600494 -277.646892)
		(end 108.599732 -277.646384)
		(width 0.1143)
		(layer "In11.Cu")
		(net "P5E_CPU1_P1_RX_DP<12>")
	)
	(segment
		(start 108.46181 -295.697402)
		(end 108.46181 -295.668954)
		(width 0.1143)
		(layer "In11.Cu")
		(net "P5E_CPU1_P1_RX_DP<12>")
	)
	(segment
		(start 108.572554 -289.982402)
		(end 108.577126 -289.979608)
		(width 0.1143)
		(layer "In11.Cu")
		(net "P5E_CPU1_P1_RX_DP<12>")
	)
	(segment
		(start 108.60913 -280.240994)
		(end 108.612432 -280.238962)
		(width 0.1143)
		(layer "In11.Cu")
		(net "P5E_CPU1_P1_RX_DP<12>")
	)
	(segment
		(start 95.213932 -385.649216)
		(end 95.388176 -385.548632)
		(width 0.14224)
		(layer "In11.Cu")
		(net "P5E_CPU1_P1_RX_DP<12>")
	)
	(segment
		(start 108.634022 -285.086298)
		(end 108.643166 -285.080964)
		(width 0.1143)
		(layer "In11.Cu")
		(net "P5E_CPU1_P1_RX_DP<12>")
	)
	(segment
		(start 108.6104 -294.819832)
		(end 108.643166 -294.800782)
		(width 0.1143)
		(layer "In11.Cu")
		(net "P5E_CPU1_P1_RX_DP<12>")
	)
	(segment
		(start 107.083098 -274.896326)
		(end 107.38104 -274.896326)
		(width 0.1143)
		(layer "In11.Cu")
		(net "P5E_CPU1_P1_RX_DP<12>")
	)
	(segment
		(start 95.468186 -384.048254)
		(end 95.468186 -382.10617)
		(width 0.14224)
		(layer "In11.Cu")
		(net "P5E_CPU1_P1_RX_DP<12>")
	)
	(segment
		(start 108.689648 -289.904424)
		(end 108.69041 -289.90417)
		(width 0.1143)
		(layer "In11.Cu")
		(net "P5E_CPU1_P1_RX_DP<12>")
	)
	(segment
		(start 108.598716 -277.645876)
		(end 108.597954 -277.645368)
		(width 0.1143)
		(layer "In11.Cu")
		(net "P5E_CPU1_P1_RX_DP<12>")
	)
	(segment
		(start 108.599732 -294.826182)
		(end 108.600494 -294.825674)
		(width 0.1143)
		(layer "In11.Cu")
		(net "P5E_CPU1_P1_RX_DP<12>")
	)
	(segment
		(start 108.599732 -285.746444)
		(end 108.598716 -285.745936)
		(width 0.1143)
		(layer "In11.Cu")
		(net "P5E_CPU1_P1_RX_DP<12>")
	)
	(segment
		(start 108.643166 -277.671784)
		(end 108.6358 -277.667466)
		(width 0.1143)
		(layer "In11.Cu")
		(net "P5E_CPU1_P1_RX_DP<12>")
	)
	(segment
		(start 108.577126 -289.979608)
		(end 108.583222 -289.975544)
		(width 0.1143)
		(layer "In11.Cu")
		(net "P5E_CPU1_P1_RX_DP<12>")
	)
	(segment
		(start 108.635038 -280.906982)
		(end 108.605066 -280.889456)
		(width 0.1143)
		(layer "In11.Cu")
		(net "P5E_CPU1_P1_RX_DP<12>")
	)
	(segment
		(start 108.598716 -282.505912)
		(end 108.597954 -282.505404)
		(width 0.1143)
		(layer "In11.Cu")
		(net "P5E_CPU1_P1_RX_DP<12>")
	)
	(segment
		(start 108.57865 -281.878024)
		(end 108.612178 -281.858974)
		(width 0.1143)
		(layer "In11.Cu")
		(net "P5E_CPU1_P1_RX_DP<12>")
	)
	(segment
		(start 107.013248 -274.966176)
		(end 107.083098 -274.896326)
		(width 0.1143)
		(layer "In11.Cu")
		(net "P5E_CPU1_P1_RX_DP<12>")
	)
	(segment
		(start 126.176532 -348.949772)
		(end 128.567688 -342.751156)
		(width 0.14224)
		(layer "In11.Cu")
		(net "P5E_CPU1_P1_RX_DP<12>")
	)
	(segment
		(start 108.583222 -280.25598)
		(end 108.584746 -280.254964)
		(width 0.1143)
		(layer "In11.Cu")
		(net "P5E_CPU1_P1_RX_DP<12>")
	)
	(segment
		(start 108.591858 -283.490924)
		(end 108.643166 -283.463492)
		(width 0.1143)
		(layer "In11.Cu")
		(net "P5E_CPU1_P1_RX_DP<12>")
	)
	(segment
		(start 108.625894 -281.851354)
		(end 108.643166 -281.841702)
		(width 0.1143)
		(layer "In11.Cu")
		(net "P5E_CPU1_P1_RX_DP<12>")
	)
	(segment
		(start 116.482876 -312.96356)
		(end 110.869984 -304.56378)
		(width 0.14224)
		(layer "In11.Cu")
		(net "P5E_CPU1_P1_RX_DP<12>")
	)
	(segment
		(start 110.869984 -304.56378)
		(end 108.46181 -298.749974)
		(width 0.14224)
		(layer "In11.Cu")
		(net "P5E_CPU1_P1_RX_DP<12>")
	)
	(segment
		(start 108.643166 -293.87165)
		(end 108.5723 -293.830502)
		(width 0.1143)
		(layer "In11.Cu")
		(net "P5E_CPU1_P1_RX_DP<12>")
	)
	(segment
		(start 108.635038 -277.666958)
		(end 108.605066 -277.649432)
		(width 0.1143)
		(layer "In11.Cu")
		(net "P5E_CPU1_P1_RX_DP<12>")
	)
	(segment
		(start 108.416344 -295.423336)
		(end 108.416344 -295.146222)
		(width 0.1143)
		(layer "In11.Cu")
		(net "P5E_CPU1_P1_RX_DP<12>")
	)
	(segment
		(start 108.62945 -285.089092)
		(end 108.630974 -285.088076)
		(width 0.1143)
		(layer "In11.Cu")
		(net "P5E_CPU1_P1_RX_DP<12>")
	)
	(segment
		(start 108.602526 -293.204646)
		(end 108.635546 -293.185342)
		(width 0.1143)
		(layer "In11.Cu")
		(net "P5E_CPU1_P1_RX_DP<12>")
	)
	(segment
		(start 108.600494 -285.746952)
		(end 108.599732 -285.746444)
		(width 0.1143)
		(layer "In11.Cu")
		(net "P5E_CPU1_P1_RX_DP<12>")
	)
	(segment
		(start 108.600494 -293.205662)
		(end 108.602526 -293.204646)
		(width 0.1143)
		(layer "In11.Cu")
		(net "P5E_CPU1_P1_RX_DP<12>")
	)
	(segment
		(start 108.595414 -284.124146)
		(end 108.5723 -284.110684)
		(width 0.1143)
		(layer "In11.Cu")
		(net "P5E_CPU1_P1_RX_DP<12>")
	)
	(segment
		(start 108.565188 -289.986974)
		(end 108.5723 -289.982148)
		(width 0.1143)
		(layer "In11.Cu")
		(net "P5E_CPU1_P1_RX_DP<12>")
	)
	(segment
		(start 108.5723 -280.262076)
		(end 108.57738 -280.259282)
		(width 0.1143)
		(layer "In11.Cu")
		(net "P5E_CPU1_P1_RX_DP<12>")
	)
	(segment
		(start 108.5723 -283.5021)
		(end 108.59008 -283.491686)
		(width 0.1143)
		(layer "In11.Cu")
		(net "P5E_CPU1_P1_RX_DP<12>")
	)
	(segment
		(start 108.613956 -280.237946)
		(end 108.643166 -280.220928)
		(width 0.1143)
		(layer "In11.Cu")
		(net "P5E_CPU1_P1_RX_DP<12>")
	)
	(segment
		(start 108.576618 -281.87904)
		(end 108.57865 -281.878024)
		(width 0.1143)
		(layer "In11.Cu")
		(net "P5E_CPU1_P1_RX_DP<12>")
	)
	(segment
		(start 108.631482 -278.6126)
		(end 108.643166 -278.600916)
		(width 0.1143)
		(layer "In11.Cu")
		(net "P5E_CPU1_P1_RX_DP<12>")
	)
	(segment
		(start 108.603288 -279.268428)
		(end 108.600494 -279.266904)
		(width 0.1143)
		(layer "In11.Cu")
		(net "P5E_CPU1_P1_RX_DP<12>")
	)
	(segment
		(start 108.609638 -294.82034)
		(end 108.6104 -294.819832)
		(width 0.1143)
		(layer "In11.Cu")
		(net "P5E_CPU1_P1_RX_DP<12>")
	)
	(arc
		(start 103.338884 -369.44681)
		(mid 103.363572 -369.401454)
		(end 103.382318 -369.353338)
		(width 0.14224)
		(layer "In11.Cu")
		(net "P5E_CPU1_P1_RX_DP<12>")
	)
	(arc
		(start 108.5723 -279.250648)
		(mid 108.416372 -278.946356)
		(end 108.5723 -278.642064)
		(width 0.1143)
		(layer "In11.Cu")
		(net "P5E_CPU1_P1_RX_DP<12>")
	)
	(arc
		(start 108.416344 -277.326344)
		(mid 108.351829 -277.064125)
		(end 108.173012 -276.861778)
		(width 0.1143)
		(layer "In11.Cu")
		(net "P5E_CPU1_P1_RX_DP<12>")
	)
	(arc
		(start 107.946444 -276.516338)
		(mid 107.881929 -276.254119)
		(end 107.703112 -276.051772)
		(width 0.1143)
		(layer "In11.Cu")
		(net "P5E_CPU1_P1_RX_DP<12>")
	)
	(arc
		(start 108.651548 -291.554916)
		(mid 108.888968 -291.101454)
		(end 108.651548 -290.647882)
		(width 0.1143)
		(layer "In11.Cu")
		(net "P5E_CPU1_P1_RX_DP<12>")
	)
	(arc
		(start 108.643166 -288.320988)
		(mid 108.88649 -287.854872)
		(end 108.640626 -287.390078)
		(width 0.1143)
		(layer "In11.Cu")
		(net "P5E_CPU1_P1_RX_DP<12>")
	)
	(arc
		(start 108.103416 -276.821138)
		(mid 107.987989 -276.687762)
		(end 107.946444 -276.516338)
		(width 0.1143)
		(layer "In11.Cu")
		(net "P5E_CPU1_P1_RX_DP<12>")
	)
	(arc
		(start 108.643166 -281.84094)
		(mid 108.886493 -281.376374)
		(end 108.643166 -280.911808)
		(width 0.1143)
		(layer "In11.Cu")
		(net "P5E_CPU1_P1_RX_DP<12>")
	)
	(arc
		(start 108.416344 -288.666174)
		(mid 108.457106 -288.49629)
		(end 108.570522 -288.363406)
		(width 0.1143)
		(layer "In11.Cu")
		(net "P5E_CPU1_P1_RX_DP<12>")
	)
	(arc
		(start 107.47629 -275.699728)
		(mid 107.411418 -275.449986)
		(end 107.246674 -275.251418)
		(width 0.1143)
		(layer "In11.Cu")
		(net "P5E_CPU1_P1_RX_DP<12>")
	)
	(arc
		(start 107.47629 -275.706332)
		(mid 107.4763 -275.70303)
		(end 107.47629 -275.699728)
		(width 0.1143)
		(layer "In11.Cu")
		(net "P5E_CPU1_P1_RX_DP<12>")
	)
	(arc
		(start 108.5723 -292.21049)
		(mid 108.416372 -291.906198)
		(end 108.5723 -291.601906)
		(width 0.1143)
		(layer "In11.Cu")
		(net "P5E_CPU1_P1_RX_DP<12>")
	)
	(arc
		(start 108.5723 -285.730696)
		(mid 108.416372 -285.426404)
		(end 108.5723 -285.122112)
		(width 0.1143)
		(layer "In11.Cu")
		(net "P5E_CPU1_P1_RX_DP<12>")
	)
	(arc
		(start 108.643166 -286.700976)
		(mid 108.886493 -286.23641)
		(end 108.643166 -285.771844)
		(width 0.1143)
		(layer "In11.Cu")
		(net "P5E_CPU1_P1_RX_DP<12>")
	)
	(arc
		(start 107.627674 -276.006052)
		(mid 107.527192 -275.868717)
		(end 107.47629 -275.706332)
		(width 0.1143)
		(layer "In11.Cu")
		(net "P5E_CPU1_P1_RX_DP<12>")
	)
	(arc
		(start 108.5723 -280.87066)
		(mid 108.416372 -280.566368)
		(end 108.5723 -280.262076)
		(width 0.1143)
		(layer "In11.Cu")
		(net "P5E_CPU1_P1_RX_DP<12>")
	)
	(arc
		(start 108.643166 -294.800782)
		(mid 108.886493 -294.336216)
		(end 108.643166 -293.87165)
		(width 0.1143)
		(layer "In11.Cu")
		(net "P5E_CPU1_P1_RX_DP<12>")
	)
	(arc
		(start 108.565188 -290.595558)
		(mid 108.40926 -290.291266)
		(end 108.565188 -289.986974)
		(width 0.1143)
		(layer "In11.Cu")
		(net "P5E_CPU1_P1_RX_DP<12>")
	)
	(arc
		(start 107.162346 -275.200618)
		(mid 107.065211 -275.097749)
		(end 107.013248 -274.966176)
		(width 0.1143)
		(layer "In11.Cu")
		(net "P5E_CPU1_P1_RX_DP<12>")
	)
	(arc
		(start 108.416344 -295.146222)
		(mid 108.457599 -294.975251)
		(end 108.5723 -294.84193)
		(width 0.1143)
		(layer "In11.Cu")
		(net "P5E_CPU1_P1_RX_DP<12>")
	)
	(arc
		(start 108.643166 -293.18077)
		(mid 108.886493 -292.716204)
		(end 108.643166 -292.251638)
		(width 0.1143)
		(layer "In11.Cu")
		(net "P5E_CPU1_P1_RX_DP<12>")
	)
	(arc
		(start 107.636564 -276.013164)
		(mid 107.632092 -276.009641)
		(end 107.627674 -276.006052)
		(width 0.1143)
		(layer "In11.Cu")
		(net "P5E_CPU1_P1_RX_DP<12>")
	)
	(arc
		(start 108.643166 -283.460952)
		(mid 108.886493 -282.996386)
		(end 108.643166 -282.53182)
		(width 0.1143)
		(layer "In11.Cu")
		(net "P5E_CPU1_P1_RX_DP<12>")
	)
	(arc
		(start 107.246674 -275.251418)
		(mid 107.238596 -275.245632)
		(end 107.230418 -275.239988)
		(width 0.1143)
		(layer "In11.Cu")
		(net "P5E_CPU1_P1_RX_DP<12>")
	)
	(arc
		(start 108.643166 -285.080964)
		(mid 108.886493 -284.616398)
		(end 108.643166 -284.151832)
		(width 0.1143)
		(layer "In11.Cu")
		(net "P5E_CPU1_P1_RX_DP<12>")
	)
	(arc
		(start 108.643166 -280.220928)
		(mid 108.886493 -279.756362)
		(end 108.643166 -279.291796)
		(width 0.1143)
		(layer "In11.Cu")
		(net "P5E_CPU1_P1_RX_DP<12>")
	)
	(arc
		(start 108.5723 -281.882342)
		(mid 108.574454 -281.880684)
		(end 108.576618 -281.87904)
		(width 0.1143)
		(layer "In11.Cu")
		(net "P5E_CPU1_P1_RX_DP<12>")
	)
	(arc
		(start 108.5723 -277.630636)
		(mid 108.457624 -277.497302)
		(end 108.416344 -277.326344)
		(width 0.1143)
		(layer "In11.Cu")
		(net "P5E_CPU1_P1_RX_DP<12>")
	)
	(arc
		(start 124.519182 -351.020634)
		(mid 125.507923 -350.113314)
		(end 126.176532 -348.949772)
		(width 0.14224)
		(layer "In11.Cu")
		(net "P5E_CPU1_P1_RX_DP<12>")
	)
	(arc
		(start 105.443528 -363.910372)
		(mid 105.559232 -363.725706)
		(end 105.721658 -363.580426)
		(width 0.14224)
		(layer "In11.Cu")
		(net "P5E_CPU1_P1_RX_DP<12>")
	)
	(arc
		(start 108.5723 -293.830502)
		(mid 108.416372 -293.52621)
		(end 108.5723 -293.221918)
		(width 0.1143)
		(layer "In11.Cu")
		(net "P5E_CPU1_P1_RX_DP<12>")
	)
	(arc
		(start 108.5723 -288.970466)
		(mid 108.457624 -288.837132)
		(end 108.416344 -288.666174)
		(width 0.1143)
		(layer "In11.Cu")
		(net "P5E_CPU1_P1_RX_DP<12>")
	)
	(arc
		(start 95.468186 -382.10617)
		(mid 95.489559 -381.954958)
		(end 95.552006 -381.815594)
		(width 0.14224)
		(layer "In11.Cu")
		(net "P5E_CPU1_P1_RX_DP<12>")
	)
	(arc
		(start 108.643166 -278.600916)
		(mid 108.886493 -278.13635)
		(end 108.643166 -277.671784)
		(width 0.1143)
		(layer "In11.Cu")
		(net "P5E_CPU1_P1_RX_DP<12>")
	)
	(arc
		(start 108.5723 -284.110684)
		(mid 108.416372 -283.806392)
		(end 108.5723 -283.5021)
		(width 0.1143)
		(layer "In11.Cu")
		(net "P5E_CPU1_P1_RX_DP<12>")
	)
	(arc
		(start 108.5723 -282.490672)
		(mid 108.416372 -282.18638)
		(end 108.5723 -281.882088)
		(width 0.1143)
		(layer "In11.Cu")
		(net "P5E_CPU1_P1_RX_DP<12>")
	)
	(arc
		(start 108.416344 -287.046162)
		(mid 108.457106 -286.876278)
		(end 108.570522 -286.743394)
		(width 0.1143)
		(layer "In11.Cu")
		(net "P5E_CPU1_P1_RX_DP<12>")
	)
	(arc
		(start 108.69041 -289.90417)
		(mid 108.885697 -289.446306)
		(end 108.643166 -289.011614)
		(width 0.1143)
		(layer "In11.Cu")
		(net "P5E_CPU1_P1_RX_DP<12>")
	)
	(arc
		(start 108.5723 -287.350454)
		(mid 108.457624 -287.21712)
		(end 108.416344 -287.046162)
		(width 0.1143)
		(layer "In11.Cu")
		(net "P5E_CPU1_P1_RX_DP<12>")
	)
	(segment
		(start 93.39834 -386.003292)
		(end 93.91904 -386.003292)
		(width 0.127)
		(layer "F.Cu")
		(net "P5E_CPU1_P1_RX_DP<11>")
	)
	(segment
		(start 107.847892 -279.490424)
		(end 107.38104 -279.756362)
		(width 0.12954)
		(layer "F.Cu")
		(net "P5E_CPU1_P1_RX_DP<11>")
	)
	(segment
		(start 107.161076 -295.652952)
		(end 107.162346 -295.651936)
		(width 0.1143)
		(layer "In11.Cu")
		(net "P5E_CPU1_P1_RX_DP<11>")
	)
	(segment
		(start 107.663996 -284.128972)
		(end 107.663234 -284.128464)
		(width 0.1143)
		(layer "In11.Cu")
		(net "P5E_CPU1_P1_RX_DP<11>")
	)
	(segment
		(start 107.703112 -285.771844)
		(end 107.666282 -285.750254)
		(width 0.1143)
		(layer "In11.Cu")
		(net "P5E_CPU1_P1_RX_DP<11>")
	)
	(segment
		(start 107.66933 -292.231826)
		(end 107.668568 -292.231318)
		(width 0.1143)
		(layer "In11.Cu")
		(net "P5E_CPU1_P1_RX_DP<11>")
	)
	(segment
		(start 107.666282 -284.130242)
		(end 107.663996 -284.128972)
		(width 0.1143)
		(layer "In11.Cu")
		(net "P5E_CPU1_P1_RX_DP<11>")
	)
	(segment
		(start 107.672632 -290.613846)
		(end 107.671108 -290.61283)
		(width 0.1143)
		(layer "In11.Cu")
		(net "P5E_CPU1_P1_RX_DP<11>")
	)
	(segment
		(start 107.665012 -283.483304)
		(end 107.666536 -283.482288)
		(width 0.1143)
		(layer "In11.Cu")
		(net "P5E_CPU1_P1_RX_DP<11>")
	)
	(segment
		(start 107.663996 -285.748984)
		(end 107.663234 -285.748476)
		(width 0.1143)
		(layer "In11.Cu")
		(net "P5E_CPU1_P1_RX_DP<11>")
	)
	(segment
		(start 107.663488 -289.96386)
		(end 107.684824 -289.951414)
		(width 0.1143)
		(layer "In11.Cu")
		(net "P5E_CPU1_P1_RX_DP<11>")
	)
	(segment
		(start 107.666536 -283.482288)
		(end 107.703112 -283.460952)
		(width 0.1143)
		(layer "In11.Cu")
		(net "P5E_CPU1_P1_RX_DP<11>")
	)
	(segment
		(start 107.663996 -282.50896)
		(end 107.663234 -282.508452)
		(width 0.1143)
		(layer "In11.Cu")
		(net "P5E_CPU1_P1_RX_DP<11>")
	)
	(segment
		(start 107.703112 -293.87165)
		(end 107.696254 -293.867586)
		(width 0.1143)
		(layer "In11.Cu")
		(net "P5E_CPU1_P1_RX_DP<11>")
	)
	(segment
		(start 99.938332 -369.27028)
		(end 99.938332 -368.641884)
		(width 0.14224)
		(layer "In11.Cu")
		(net "P5E_CPU1_P1_RX_DP<11>")
	)
	(segment
		(start 107.632246 -293.221918)
		(end 107.663996 -293.20363)
		(width 0.1143)
		(layer "In11.Cu")
		(net "P5E_CPU1_P1_RX_DP<11>")
	)
	(segment
		(start 107.296204 -296.584116)
		(end 107.250484 -296.538396)
		(width 0.1143)
		(layer "In11.Cu")
		(net "P5E_CPU1_P1_RX_DP<11>")
	)
	(segment
		(start 107.663996 -286.723836)
		(end 107.703112 -286.700976)
		(width 0.1143)
		(layer "In11.Cu")
		(net "P5E_CPU1_P1_RX_DP<11>")
	)
	(segment
		(start 107.632246 -281.882088)
		(end 107.663234 -281.864308)
		(width 0.1143)
		(layer "In11.Cu")
		(net "P5E_CPU1_P1_RX_DP<11>")
	)
	(segment
		(start 107.194096 -295.633648)
		(end 107.194096 -295.633394)
		(width 0.1143)
		(layer "In11.Cu")
		(net "P5E_CPU1_P1_RX_DP<11>")
	)
	(segment
		(start 93.960442 -384.731006)
		(end 93.96349 -384.3528)
		(width 0.14224)
		(layer "In11.Cu")
		(net "P5E_CPU1_P1_RX_DP<11>")
	)
	(segment
		(start 107.663234 -281.864308)
		(end 107.663996 -281.8638)
		(width 0.1143)
		(layer "In11.Cu")
		(net "P5E_CPU1_P1_RX_DP<11>")
	)
	(segment
		(start 107.632246 -282.490672)
		(end 107.612434 -282.476448)
		(width 0.1143)
		(layer "In11.Cu")
		(net "P5E_CPU1_P1_RX_DP<11>")
	)
	(segment
		(start 93.96349 -384.3528)
		(end 94.26829 -384.048)
		(width 0.14224)
		(layer "In11.Cu")
		(net "P5E_CPU1_P1_RX_DP<11>")
	)
	(segment
		(start 107.668568 -292.231318)
		(end 107.656122 -292.224206)
		(width 0.1143)
		(layer "In11.Cu")
		(net "P5E_CPU1_P1_RX_DP<11>")
	)
	(segment
		(start 122.738388 -322.05549)
		(end 115.729766 -313.515502)
		(width 0.14224)
		(layer "In11.Cu")
		(net "P5E_CPU1_P1_RX_DP<11>")
	)
	(segment
		(start 107.663996 -285.103824)
		(end 107.665012 -285.103316)
		(width 0.1143)
		(layer "In11.Cu")
		(net "P5E_CPU1_P1_RX_DP<11>")
	)
	(segment
		(start 107.666536 -281.862276)
		(end 107.703112 -281.84094)
		(width 0.1143)
		(layer "In11.Cu")
		(net "P5E_CPU1_P1_RX_DP<11>")
	)
	(segment
		(start 107.663996 -294.823642)
		(end 107.665012 -294.823134)
		(width 0.1143)
		(layer "In11.Cu")
		(net "P5E_CPU1_P1_RX_DP<11>")
	)
	(segment
		(start 107.70235 -287.391348)
		(end 107.688888 -287.383474)
		(width 0.1143)
		(layer "In11.Cu")
		(net "P5E_CPU1_P1_RX_DP<11>")
	)
	(segment
		(start 107.663996 -293.20363)
		(end 107.700318 -293.182802)
		(width 0.1143)
		(layer "In11.Cu")
		(net "P5E_CPU1_P1_RX_DP<11>")
	)
	(segment
		(start 107.194096 -295.633394)
		(end 107.222036 -295.617138)
		(width 0.1143)
		(layer "In11.Cu")
		(net "P5E_CPU1_P1_RX_DP<11>")
	)
	(segment
		(start 107.230418 -280.100024)
		(end 107.194096 -280.078942)
		(width 0.1143)
		(layer "In11.Cu")
		(net "P5E_CPU1_P1_RX_DP<11>")
	)
	(segment
		(start 107.663234 -293.848282)
		(end 107.632246 -293.830502)
		(width 0.1143)
		(layer "In11.Cu")
		(net "P5E_CPU1_P1_RX_DP<11>")
	)
	(segment
		(start 107.663996 -280.888948)
		(end 107.663234 -280.88844)
		(width 0.1143)
		(layer "In11.Cu")
		(net "P5E_CPU1_P1_RX_DP<11>")
	)
	(segment
		(start 107.632246 -283.5021)
		(end 107.663234 -283.48432)
		(width 0.1143)
		(layer "In11.Cu")
		(net "P5E_CPU1_P1_RX_DP<11>")
	)
	(segment
		(start 107.612434 -281.896312)
		(end 107.632246 -281.882088)
		(width 0.1143)
		(layer "In11.Cu")
		(net "P5E_CPU1_P1_RX_DP<11>")
	)
	(segment
		(start 107.651042 -288.981388)
		(end 107.650534 -288.981134)
		(width 0.1143)
		(layer "In11.Cu")
		(net "P5E_CPU1_P1_RX_DP<11>")
	)
	(segment
		(start 107.696254 -293.867586)
		(end 107.695492 -293.867078)
		(width 0.1143)
		(layer "In11.Cu")
		(net "P5E_CPU1_P1_RX_DP<11>")
	)
	(segment
		(start 107.632246 -285.122112)
		(end 107.663234 -285.104332)
		(width 0.1143)
		(layer "In11.Cu")
		(net "P5E_CPU1_P1_RX_DP<11>")
	)
	(segment
		(start 107.650788 -288.351214)
		(end 107.651042 -288.35096)
		(width 0.1143)
		(layer "In11.Cu")
		(net "P5E_CPU1_P1_RX_DP<11>")
	)
	(segment
		(start 99.97059 -368.431064)
		(end 100.08997 -368.051588)
		(width 0.14224)
		(layer "In11.Cu")
		(net "P5E_CPU1_P1_RX_DP<11>")
	)
	(segment
		(start 127.641858 -339.362542)
		(end 125.47219 -327.286112)
		(width 0.14224)
		(layer "In11.Cu")
		(net "P5E_CPU1_P1_RX_DP<11>")
	)
	(segment
		(start 107.703112 -280.911808)
		(end 107.666282 -280.890218)
		(width 0.1143)
		(layer "In11.Cu")
		(net "P5E_CPU1_P1_RX_DP<11>")
	)
	(segment
		(start 94.014036 -385.649216)
		(end 94.18828 -385.548632)
		(width 0.14224)
		(layer "In11.Cu")
		(net "P5E_CPU1_P1_RX_DP<11>")
	)
	(segment
		(start 107.663488 -291.583872)
		(end 107.684824 -291.571426)
		(width 0.1143)
		(layer "In11.Cu")
		(net "P5E_CPU1_P1_RX_DP<11>")
	)
	(segment
		(start 107.685078 -291.571426)
		(end 107.703112 -291.560758)
		(width 0.1143)
		(layer "In11.Cu")
		(net "P5E_CPU1_P1_RX_DP<11>")
	)
	(segment
		(start 127.641858 -342.11641)
		(end 127.641858 -339.362542)
		(width 0.14224)
		(layer "In11.Cu")
		(net "P5E_CPU1_P1_RX_DP<11>")
	)
	(segment
		(start 107.70235 -287.391094)
		(end 107.70235 -287.391348)
		(width 0.1143)
		(layer "In11.Cu")
		(net "P5E_CPU1_P1_RX_DP<11>")
	)
	(segment
		(start 107.663996 -283.483812)
		(end 107.665012 -283.483304)
		(width 0.1143)
		(layer "In11.Cu")
		(net "P5E_CPU1_P1_RX_DP<11>")
	)
	(segment
		(start 107.666282 -285.750254)
		(end 107.663996 -285.748984)
		(width 0.1143)
		(layer "In11.Cu")
		(net "P5E_CPU1_P1_RX_DP<11>")
	)
	(segment
		(start 107.663996 -281.8638)
		(end 107.665012 -281.863292)
		(width 0.1143)
		(layer "In11.Cu")
		(net "P5E_CPU1_P1_RX_DP<11>")
	)
	(segment
		(start 107.70235 -290.631118)
		(end 107.672632 -290.613846)
		(width 0.1143)
		(layer "In11.Cu")
		(net "P5E_CPU1_P1_RX_DP<11>")
	)
	(segment
		(start 107.630468 -286.743394)
		(end 107.663996 -286.723836)
		(width 0.1143)
		(layer "In11.Cu")
		(net "P5E_CPU1_P1_RX_DP<11>")
	)
	(segment
		(start 107.651042 -288.35096)
		(end 107.664504 -288.34334)
		(width 0.1143)
		(layer "In11.Cu")
		(net "P5E_CPU1_P1_RX_DP<11>")
	)
	(segment
		(start 107.250484 -296.538396)
		(end 107.250484 -296.476928)
		(width 0.1143)
		(layer "In11.Cu")
		(net "P5E_CPU1_P1_RX_DP<11>")
	)
	(segment
		(start 107.663234 -285.104332)
		(end 107.663996 -285.103824)
		(width 0.1143)
		(layer "In11.Cu")
		(net "P5E_CPU1_P1_RX_DP<11>")
	)
	(segment
		(start 115.729766 -313.515502)
		(end 110.044484 -305.007264)
		(width 0.14224)
		(layer "In11.Cu")
		(net "P5E_CPU1_P1_RX_DP<11>")
	)
	(segment
		(start 107.696 -292.24732)
		(end 107.672124 -292.233604)
		(width 0.1143)
		(layer "In11.Cu")
		(net "P5E_CPU1_P1_RX_DP<11>")
	)
	(segment
		(start 107.664504 -288.34334)
		(end 107.697524 -288.323782)
		(width 0.1143)
		(layer "In11.Cu")
		(net "P5E_CPU1_P1_RX_DP<11>")
	)
	(segment
		(start 93.91904 -386.003292)
		(end 94.014036 -385.649216)
		(width 0.14224)
		(layer "In11.Cu")
		(net "P5E_CPU1_P1_RX_DP<11>")
	)
	(segment
		(start 107.154472 -295.657524)
		(end 107.161076 -295.652952)
		(width 0.1143)
		(layer "In11.Cu")
		(net "P5E_CPU1_P1_RX_DP<11>")
	)
	(segment
		(start 107.296204 -296.612564)
		(end 107.296204 -296.584116)
		(width 0.1143)
		(layer "In11.Cu")
		(net "P5E_CPU1_P1_RX_DP<11>")
	)
	(segment
		(start 107.663234 -282.508452)
		(end 107.632246 -282.490672)
		(width 0.1143)
		(layer "In11.Cu")
		(net "P5E_CPU1_P1_RX_DP<11>")
	)
	(segment
		(start 107.157266 -296.252138)
		(end 107.0864 -296.181272)
		(width 0.1143)
		(layer "In11.Cu")
		(net "P5E_CPU1_P1_RX_DP<11>")
	)
	(segment
		(start 107.296204 -298.372022)
		(end 107.296204 -296.612564)
		(width 0.14224)
		(layer "In11.Cu")
		(net "P5E_CPU1_P1_RX_DP<11>")
	)
	(segment
		(start 107.665012 -293.849298)
		(end 107.663996 -293.84879)
		(width 0.1143)
		(layer "In11.Cu")
		(net "P5E_CPU1_P1_RX_DP<11>")
	)
	(segment
		(start 107.665012 -281.863292)
		(end 107.666536 -281.862276)
		(width 0.1143)
		(layer "In11.Cu")
		(net "P5E_CPU1_P1_RX_DP<11>")
	)
	(segment
		(start 107.684824 -289.951414)
		(end 107.685078 -289.951414)
		(width 0.1143)
		(layer "In11.Cu")
		(net "P5E_CPU1_P1_RX_DP<11>")
	)
	(segment
		(start 107.663234 -283.48432)
		(end 107.663996 -283.483812)
		(width 0.1143)
		(layer "In11.Cu")
		(net "P5E_CPU1_P1_RX_DP<11>")
	)
	(segment
		(start 107.695492 -293.867078)
		(end 107.665012 -293.849298)
		(width 0.1143)
		(layer "In11.Cu")
		(net "P5E_CPU1_P1_RX_DP<11>")
	)
	(segment
		(start 104.966262 -362.95711)
		(end 123.776232 -350.388936)
		(width 0.14224)
		(layer "In11.Cu")
		(net "P5E_CPU1_P1_RX_DP<11>")
	)
	(segment
		(start 107.663234 -284.128464)
		(end 107.632246 -284.110684)
		(width 0.1143)
		(layer "In11.Cu")
		(net "P5E_CPU1_P1_RX_DP<11>")
	)
	(segment
		(start 107.685078 -289.951414)
		(end 107.703112 -289.940746)
		(width 0.1143)
		(layer "In11.Cu")
		(net "P5E_CPU1_P1_RX_DP<11>")
	)
	(segment
		(start 94.276418 -385.046982)
		(end 93.960442 -384.731006)
		(width 0.14224)
		(layer "In11.Cu")
		(net "P5E_CPU1_P1_RX_DP<11>")
	)
	(segment
		(start 107.703112 -282.53182)
		(end 107.666282 -282.51023)
		(width 0.1143)
		(layer "In11.Cu")
		(net "P5E_CPU1_P1_RX_DP<11>")
	)
	(segment
		(start 100.254054 -367.768378)
		(end 103.714042 -364.02645)
		(width 0.14224)
		(layer "In11.Cu")
		(net "P5E_CPU1_P1_RX_DP<11>")
	)
	(segment
		(start 107.663234 -294.82415)
		(end 107.663996 -294.823642)
		(width 0.1143)
		(layer "In11.Cu")
		(net "P5E_CPU1_P1_RX_DP<11>")
	)
	(segment
		(start 107.013248 -279.826212)
		(end 107.083098 -279.756362)
		(width 0.1143)
		(layer "In11.Cu")
		(net "P5E_CPU1_P1_RX_DP<11>")
	)
	(segment
		(start 107.671108 -290.61283)
		(end 107.656122 -290.604194)
		(width 0.1143)
		(layer "In11.Cu")
		(net "P5E_CPU1_P1_RX_DP<11>")
	)
	(segment
		(start 125.47219 -327.286112)
		(end 122.738388 -322.05549)
		(width 0.14224)
		(layer "In11.Cu")
		(net "P5E_CPU1_P1_RX_DP<11>")
	)
	(segment
		(start 107.083098 -279.756362)
		(end 107.38104 -279.756362)
		(width 0.1143)
		(layer "In11.Cu")
		(net "P5E_CPU1_P1_RX_DP<11>")
	)
	(segment
		(start 107.666282 -282.51023)
		(end 107.663996 -282.50896)
		(width 0.1143)
		(layer "In11.Cu")
		(net "P5E_CPU1_P1_RX_DP<11>")
	)
	(segment
		(start 107.684824 -291.571426)
		(end 107.685078 -291.571426)
		(width 0.1143)
		(layer "In11.Cu")
		(net "P5E_CPU1_P1_RX_DP<11>")
	)
	(segment
		(start 94.18828 -385.548632)
		(end 94.276418 -385.460494)
		(width 0.14224)
		(layer "In11.Cu")
		(net "P5E_CPU1_P1_RX_DP<11>")
	)
	(segment
		(start 107.70235 -289.011106)
		(end 107.651042 -288.981388)
		(width 0.1143)
		(layer "In11.Cu")
		(net "P5E_CPU1_P1_RX_DP<11>")
	)
	(segment
		(start 107.697524 -288.323782)
		(end 107.703112 -288.320988)
		(width 0.1143)
		(layer "In11.Cu")
		(net "P5E_CPU1_P1_RX_DP<11>")
	)
	(segment
		(start 107.665012 -285.103316)
		(end 107.666536 -285.1023)
		(width 0.1143)
		(layer "In11.Cu")
		(net "P5E_CPU1_P1_RX_DP<11>")
	)
	(segment
		(start 94.320614 -381.747014)
		(end 99.807776 -369.864386)
		(width 0.14224)
		(layer "In11.Cu")
		(net "P5E_CPU1_P1_RX_DP<11>")
	)
	(segment
		(start 107.222036 -295.617138)
		(end 107.230418 -295.612566)
		(width 0.1143)
		(layer "In11.Cu")
		(net "P5E_CPU1_P1_RX_DP<11>")
	)
	(segment
		(start 107.703112 -284.151832)
		(end 107.666282 -284.130242)
		(width 0.1143)
		(layer "In11.Cu")
		(net "P5E_CPU1_P1_RX_DP<11>")
	)
	(segment
		(start 107.663996 -293.84879)
		(end 107.663234 -293.848282)
		(width 0.1143)
		(layer "In11.Cu")
		(net "P5E_CPU1_P1_RX_DP<11>")
	)
	(segment
		(start 107.666536 -294.822118)
		(end 107.703112 -294.800782)
		(width 0.1143)
		(layer "In11.Cu")
		(net "P5E_CPU1_P1_RX_DP<11>")
	)
	(segment
		(start 107.00639 -295.988232)
		(end 107.00639 -295.946576)
		(width 0.1143)
		(layer "In11.Cu")
		(net "P5E_CPU1_P1_RX_DP<11>")
	)
	(segment
		(start 94.276418 -385.460494)
		(end 94.276418 -385.046982)
		(width 0.14224)
		(layer "In11.Cu")
		(net "P5E_CPU1_P1_RX_DP<11>")
	)
	(segment
		(start 107.672124 -292.233604)
		(end 107.66933 -292.231826)
		(width 0.1143)
		(layer "In11.Cu")
		(net "P5E_CPU1_P1_RX_DP<11>")
	)
	(segment
		(start 107.700318 -293.182802)
		(end 107.703112 -293.18077)
		(width 0.1143)
		(layer "In11.Cu")
		(net "P5E_CPU1_P1_RX_DP<11>")
	)
	(segment
		(start 107.194096 -280.078942)
		(end 107.162346 -280.060654)
		(width 0.1143)
		(layer "In11.Cu")
		(net "P5E_CPU1_P1_RX_DP<11>")
	)
	(segment
		(start 107.162346 -295.651936)
		(end 107.194096 -295.633648)
		(width 0.1143)
		(layer "In11.Cu")
		(net "P5E_CPU1_P1_RX_DP<11>")
	)
	(segment
		(start 107.70235 -292.25113)
		(end 107.696 -292.24732)
		(width 0.1143)
		(layer "In11.Cu")
		(net "P5E_CPU1_P1_RX_DP<11>")
	)
	(segment
		(start 107.666282 -280.890218)
		(end 107.663996 -280.888948)
		(width 0.1143)
		(layer "In11.Cu")
		(net "P5E_CPU1_P1_RX_DP<11>")
	)
	(segment
		(start 107.663234 -285.748476)
		(end 107.632246 -285.730696)
		(width 0.1143)
		(layer "In11.Cu")
		(net "P5E_CPU1_P1_RX_DP<11>")
	)
	(segment
		(start 94.26829 -384.048)
		(end 94.26829 -381.984504)
		(width 0.14224)
		(layer "In11.Cu")
		(net "P5E_CPU1_P1_RX_DP<11>")
	)
	(segment
		(start 107.666536 -285.1023)
		(end 107.703112 -285.080964)
		(width 0.1143)
		(layer "In11.Cu")
		(net "P5E_CPU1_P1_RX_DP<11>")
	)
	(segment
		(start 107.665012 -294.823134)
		(end 107.666536 -294.822118)
		(width 0.1143)
		(layer "In11.Cu")
		(net "P5E_CPU1_P1_RX_DP<11>")
	)
	(segment
		(start 125.078236 -348.76232)
		(end 127.641858 -342.11641)
		(width 0.14224)
		(layer "In11.Cu")
		(net "P5E_CPU1_P1_RX_DP<11>")
	)
	(segment
		(start 110.044484 -305.007264)
		(end 107.296204 -298.372022)
		(width 0.14224)
		(layer "In11.Cu")
		(net "P5E_CPU1_P1_RX_DP<11>")
	)
	(arc
		(start 107.703112 -290.631626)
		(mid 107.702731 -290.631372)
		(end 107.70235 -290.631118)
		(width 0.1143)
		(layer "In11.Cu")
		(net "P5E_CPU1_P1_RX_DP<11>")
	)
	(arc
		(start 107.656122 -290.604194)
		(mid 107.477905 -290.281917)
		(end 107.663488 -289.96386)
		(width 0.1143)
		(layer "In11.Cu")
		(net "P5E_CPU1_P1_RX_DP<11>")
	)
	(arc
		(start 107.477052 -287.025588)
		(mid 107.521938 -286.86719)
		(end 107.630468 -286.743394)
		(width 0.1143)
		(layer "In11.Cu")
		(net "P5E_CPU1_P1_RX_DP<11>")
	)
	(arc
		(start 107.00639 -295.946576)
		(mid 107.045568 -295.784192)
		(end 107.154472 -295.657524)
		(width 0.1143)
		(layer "In11.Cu")
		(net "P5E_CPU1_P1_RX_DP<11>")
	)
	(arc
		(start 99.807776 -369.864386)
		(mid 99.905307 -369.574421)
		(end 99.938332 -369.27028)
		(width 0.14224)
		(layer "In11.Cu")
		(net "P5E_CPU1_P1_RX_DP<11>")
	)
	(arc
		(start 107.703112 -288.320988)
		(mid 107.946329 -287.855892)
		(end 107.70235 -287.391094)
		(width 0.1143)
		(layer "In11.Cu")
		(net "P5E_CPU1_P1_RX_DP<11>")
	)
	(arc
		(start 107.476036 -295.156382)
		(mid 107.529868 -294.967843)
		(end 107.663234 -294.82415)
		(width 0.1143)
		(layer "In11.Cu")
		(net "P5E_CPU1_P1_RX_DP<11>")
	)
	(arc
		(start 99.938332 -368.641884)
		(mid 99.946427 -368.535245)
		(end 99.97059 -368.431064)
		(width 0.14224)
		(layer "In11.Cu")
		(net "P5E_CPU1_P1_RX_DP<11>")
	)
	(arc
		(start 107.612434 -282.476448)
		(mid 107.46372 -282.18638)
		(end 107.612434 -281.896312)
		(width 0.1143)
		(layer "In11.Cu")
		(net "P5E_CPU1_P1_RX_DP<11>")
	)
	(arc
		(start 107.230418 -295.612566)
		(mid 107.405417 -295.412567)
		(end 107.476036 -295.156382)
		(width 0.1143)
		(layer "In11.Cu")
		(net "P5E_CPU1_P1_RX_DP<11>")
	)
	(arc
		(start 107.632246 -293.830502)
		(mid 107.480657 -293.52621)
		(end 107.632246 -293.221918)
		(width 0.1143)
		(layer "In11.Cu")
		(net "P5E_CPU1_P1_RX_DP<11>")
	)
	(arc
		(start 107.476036 -280.556208)
		(mid 107.40537 -280.300048)
		(end 107.230418 -280.100024)
		(width 0.1143)
		(layer "In11.Cu")
		(net "P5E_CPU1_P1_RX_DP<11>")
	)
	(arc
		(start 100.08997 -368.051588)
		(mid 100.156331 -367.9009)
		(end 100.254054 -367.768378)
		(width 0.14224)
		(layer "In11.Cu")
		(net "P5E_CPU1_P1_RX_DP<11>")
	)
	(arc
		(start 107.703112 -286.700976)
		(mid 107.946439 -286.23641)
		(end 107.703112 -285.771844)
		(width 0.1143)
		(layer "In11.Cu")
		(net "P5E_CPU1_P1_RX_DP<11>")
	)
	(arc
		(start 107.580684 -287.290764)
		(mid 107.513394 -287.179467)
		(end 107.478068 -287.05429)
		(width 0.1143)
		(layer "In11.Cu")
		(net "P5E_CPU1_P1_RX_DP<11>")
	)
	(arc
		(start 107.703112 -283.460952)
		(mid 107.946439 -282.996386)
		(end 107.703112 -282.53182)
		(width 0.1143)
		(layer "In11.Cu")
		(net "P5E_CPU1_P1_RX_DP<11>")
	)
	(arc
		(start 107.688888 -287.383474)
		(mid 107.630508 -287.342111)
		(end 107.580684 -287.290764)
		(width 0.1143)
		(layer "In11.Cu")
		(net "P5E_CPU1_P1_RX_DP<11>")
	)
	(arc
		(start 107.703112 -281.84094)
		(mid 107.946439 -281.376374)
		(end 107.703112 -280.911808)
		(width 0.1143)
		(layer "In11.Cu")
		(net "P5E_CPU1_P1_RX_DP<11>")
	)
	(arc
		(start 123.776232 -350.388936)
		(mid 124.552985 -349.676284)
		(end 125.078236 -348.76232)
		(width 0.14224)
		(layer "In11.Cu")
		(net "P5E_CPU1_P1_RX_DP<11>")
	)
	(arc
		(start 107.703112 -292.251638)
		(mid 107.702731 -292.251384)
		(end 107.70235 -292.25113)
		(width 0.1143)
		(layer "In11.Cu")
		(net "P5E_CPU1_P1_RX_DP<11>")
	)
	(arc
		(start 107.703112 -289.011614)
		(mid 107.702731 -289.01136)
		(end 107.70235 -289.011106)
		(width 0.1143)
		(layer "In11.Cu")
		(net "P5E_CPU1_P1_RX_DP<11>")
	)
	(arc
		(start 107.663234 -280.88844)
		(mid 107.529881 -280.744712)
		(end 107.476036 -280.556208)
		(width 0.1143)
		(layer "In11.Cu")
		(net "P5E_CPU1_P1_RX_DP<11>")
	)
	(arc
		(start 107.656122 -292.224206)
		(mid 107.477905 -291.901929)
		(end 107.663488 -291.583872)
		(width 0.1143)
		(layer "In11.Cu")
		(net "P5E_CPU1_P1_RX_DP<11>")
	)
	(arc
		(start 103.714042 -364.02645)
		(mid 104.308634 -363.454871)
		(end 104.966262 -362.95711)
		(width 0.14224)
		(layer "In11.Cu")
		(net "P5E_CPU1_P1_RX_DP<11>")
	)
	(arc
		(start 107.703112 -291.560758)
		(mid 107.946439 -291.096192)
		(end 107.703112 -290.631626)
		(width 0.1143)
		(layer "In11.Cu")
		(net "P5E_CPU1_P1_RX_DP<11>")
	)
	(arc
		(start 107.632246 -285.730696)
		(mid 107.481861 -285.426404)
		(end 107.632246 -285.122112)
		(width 0.1143)
		(layer "In11.Cu")
		(net "P5E_CPU1_P1_RX_DP<11>")
	)
	(arc
		(start 107.632246 -284.110684)
		(mid 107.480657 -283.806392)
		(end 107.632246 -283.5021)
		(width 0.1143)
		(layer "In11.Cu")
		(net "P5E_CPU1_P1_RX_DP<11>")
	)
	(arc
		(start 107.478068 -287.05429)
		(mid 107.476853 -287.039964)
		(end 107.477052 -287.025588)
		(width 0.1143)
		(layer "In11.Cu")
		(net "P5E_CPU1_P1_RX_DP<11>")
	)
	(arc
		(start 107.703112 -289.940746)
		(mid 107.946439 -289.47618)
		(end 107.703112 -289.011614)
		(width 0.1143)
		(layer "In11.Cu")
		(net "P5E_CPU1_P1_RX_DP<11>")
	)
	(arc
		(start 107.703112 -285.080964)
		(mid 107.946439 -284.616398)
		(end 107.703112 -284.151832)
		(width 0.1143)
		(layer "In11.Cu")
		(net "P5E_CPU1_P1_RX_DP<11>")
	)
	(arc
		(start 94.26829 -381.984504)
		(mid 94.28155 -381.862916)
		(end 94.320614 -381.747014)
		(width 0.14224)
		(layer "In11.Cu")
		(net "P5E_CPU1_P1_RX_DP<11>")
	)
	(arc
		(start 107.703112 -293.18077)
		(mid 107.946439 -292.716204)
		(end 107.703112 -292.251638)
		(width 0.1143)
		(layer "In11.Cu")
		(net "P5E_CPU1_P1_RX_DP<11>")
	)
	(arc
		(start 107.650534 -288.981134)
		(mid 107.469336 -288.666064)
		(end 107.650788 -288.351214)
		(width 0.1143)
		(layer "In11.Cu")
		(net "P5E_CPU1_P1_RX_DP<11>")
	)
	(arc
		(start 107.703112 -294.800782)
		(mid 107.946439 -294.336216)
		(end 107.703112 -293.87165)
		(width 0.1143)
		(layer "In11.Cu")
		(net "P5E_CPU1_P1_RX_DP<11>")
	)
	(arc
		(start 107.162346 -280.060654)
		(mid 107.065211 -279.957785)
		(end 107.013248 -279.826212)
		(width 0.1143)
		(layer "In11.Cu")
		(net "P5E_CPU1_P1_RX_DP<11>")
	)
	(arc
		(start 107.250484 -296.476928)
		(mid 107.226194 -296.355285)
		(end 107.157266 -296.252138)
		(width 0.1143)
		(layer "In11.Cu")
		(net "P5E_CPU1_P1_RX_DP<11>")
	)
	(arc
		(start 107.0864 -296.181272)
		(mid 107.027167 -296.092719)
		(end 107.00639 -295.988232)
		(width 0.1143)
		(layer "In11.Cu")
		(net "P5E_CPU1_P1_RX_DP<11>")
	)
	(segment
		(start 107.847892 -277.870412)
		(end 107.38104 -278.13635)
		(width 0.12954)
		(layer "F.Cu")
		(net "P5E_CPU1_P1_RX_DP<10>")
	)
	(segment
		(start 92.198444 -386.003292)
		(end 92.719144 -386.003292)
		(width 0.127)
		(layer "F.Cu")
		(net "P5E_CPU1_P1_RX_DP<10>")
	)
	(segment
		(start 106.247438 -280.075132)
		(end 106.246168 -280.07437)
		(width 0.1143)
		(layer "In11.Cu")
		(net "P5E_CPU1_P1_RX_DP<10>")
	)
	(segment
		(start 106.763058 -285.771844)
		(end 106.693462 -285.731204)
		(width 0.1143)
		(layer "In11.Cu")
		(net "P5E_CPU1_P1_RX_DP<10>")
	)
	(segment
		(start 106.25328 -280.078434)
		(end 106.250486 -280.07691)
		(width 0.1143)
		(layer "In11.Cu")
		(net "P5E_CPU1_P1_RX_DP<10>")
	)
	(segment
		(start 106.198924 -296.286936)
		(end 106.198924 -296.258488)
		(width 0.1143)
		(layer "In11.Cu")
		(net "P5E_CPU1_P1_RX_DP<10>")
	)
	(segment
		(start 102.762304 -363.306868)
		(end 123.248166 -349.617538)
		(width 0.14224)
		(layer "In11.Cu")
		(net "P5E_CPU1_P1_RX_DP<10>")
	)
	(segment
		(start 106.255058 -279.433274)
		(end 106.256328 -279.432512)
		(width 0.1143)
		(layer "In11.Cu")
		(net "P5E_CPU1_P1_RX_DP<10>")
	)
	(segment
		(start 106.249724 -280.076402)
		(end 106.2482 -280.07564)
		(width 0.1143)
		(layer "In11.Cu")
		(net "P5E_CPU1_P1_RX_DP<10>")
	)
	(segment
		(start 106.763058 -293.87165)
		(end 106.693462 -293.83101)
		(width 0.1143)
		(layer "In11.Cu")
		(net "P5E_CPU1_P1_RX_DP<10>")
	)
	(segment
		(start 106.256328 -279.432512)
		(end 106.258614 -279.430988)
		(width 0.1143)
		(layer "In11.Cu")
		(net "P5E_CPU1_P1_RX_DP<10>")
	)
	(segment
		(start 106.693462 -281.88158)
		(end 106.763058 -281.84094)
		(width 0.1143)
		(layer "In11.Cu")
		(net "P5E_CPU1_P1_RX_DP<10>")
	)
	(segment
		(start 92.760546 -384.731006)
		(end 92.763594 -384.3528)
		(width 0.14224)
		(layer "In11.Cu")
		(net "P5E_CPU1_P1_RX_DP<10>")
	)
	(segment
		(start 126.544578 -342.330786)
		(end 126.544578 -339.460586)
		(width 0.14224)
		(layer "In11.Cu")
		(net "P5E_CPU1_P1_RX_DP<10>")
	)
	(segment
		(start 106.254042 -279.433782)
		(end 106.255058 -279.433274)
		(width 0.1143)
		(layer "In11.Cu")
		(net "P5E_CPU1_P1_RX_DP<10>")
	)
	(segment
		(start 114.980212 -314.072524)
		(end 109.218476 -305.449732)
		(width 0.14224)
		(layer "In11.Cu")
		(net "P5E_CPU1_P1_RX_DP<10>")
	)
	(segment
		(start 106.69143 -288.362644)
		(end 106.723942 -288.343848)
		(width 0.1143)
		(layer "In11.Cu")
		(net "P5E_CPU1_P1_RX_DP<10>")
	)
	(segment
		(start 93.09227 -373.667782)
		(end 97.474024 -367.576354)
		(width 0.14224)
		(layer "In11.Cu")
		(net "P5E_CPU1_P1_RX_DP<10>")
	)
	(segment
		(start 106.763058 -280.911808)
		(end 106.693462 -280.871168)
		(width 0.1143)
		(layer "In11.Cu")
		(net "P5E_CPU1_P1_RX_DP<10>")
	)
	(segment
		(start 121.955814 -322.571618)
		(end 114.980212 -314.072524)
		(width 0.14224)
		(layer "In11.Cu")
		(net "P5E_CPU1_P1_RX_DP<10>")
	)
	(segment
		(start 109.218476 -305.449732)
		(end 106.198924 -298.160186)
		(width 0.14224)
		(layer "In11.Cu")
		(net "P5E_CPU1_P1_RX_DP<10>")
	)
	(segment
		(start 106.723942 -286.723836)
		(end 106.763058 -286.700976)
		(width 0.1143)
		(layer "In11.Cu")
		(net "P5E_CPU1_P1_RX_DP<10>")
	)
	(segment
		(start 124.184156 -348.448376)
		(end 126.544578 -342.330786)
		(width 0.14224)
		(layer "In11.Cu")
		(net "P5E_CPU1_P1_RX_DP<10>")
	)
	(segment
		(start 106.258614 -279.430988)
		(end 106.293158 -279.410922)
		(width 0.1143)
		(layer "In11.Cu")
		(net "P5E_CPU1_P1_RX_DP<10>")
	)
	(segment
		(start 124.32411 -327.102724)
		(end 121.955814 -322.571618)
		(width 0.14224)
		(layer "In11.Cu")
		(net "P5E_CPU1_P1_RX_DP<10>")
	)
	(segment
		(start 106.693462 -289.981386)
		(end 106.763058 -289.940746)
		(width 0.1143)
		(layer "In11.Cu")
		(net "P5E_CPU1_P1_RX_DP<10>")
	)
	(segment
		(start 92.81414 -385.649216)
		(end 92.988384 -385.548632)
		(width 0.14224)
		(layer "In11.Cu")
		(net "P5E_CPU1_P1_RX_DP<10>")
	)
	(segment
		(start 106.153204 -296.212768)
		(end 106.153204 -295.90619)
		(width 0.1143)
		(layer "In11.Cu")
		(net "P5E_CPU1_P1_RX_DP<10>")
	)
	(segment
		(start 106.256582 -280.080466)
		(end 106.255058 -280.07945)
		(width 0.1143)
		(layer "In11.Cu")
		(net "P5E_CPU1_P1_RX_DP<10>")
	)
	(segment
		(start 106.2482 -280.07564)
		(end 106.247438 -280.075132)
		(width 0.1143)
		(layer "In11.Cu")
		(net "P5E_CPU1_P1_RX_DP<10>")
	)
	(segment
		(start 107.000294 -278.219154)
		(end 107.083098 -278.13635)
		(width 0.1143)
		(layer "In11.Cu")
		(net "P5E_CPU1_P1_RX_DP<10>")
	)
	(segment
		(start 106.763058 -292.251638)
		(end 106.693462 -292.210998)
		(width 0.1143)
		(layer "In11.Cu")
		(net "P5E_CPU1_P1_RX_DP<10>")
	)
	(segment
		(start 106.693462 -291.601398)
		(end 106.763058 -291.560758)
		(width 0.1143)
		(layer "In11.Cu")
		(net "P5E_CPU1_P1_RX_DP<10>")
	)
	(segment
		(start 106.763058 -282.53182)
		(end 106.693462 -282.49118)
		(width 0.1143)
		(layer "In11.Cu")
		(net "P5E_CPU1_P1_RX_DP<10>")
	)
	(segment
		(start 106.293158 -280.101802)
		(end 106.256582 -280.080466)
		(width 0.1143)
		(layer "In11.Cu")
		(net "P5E_CPU1_P1_RX_DP<10>")
	)
	(segment
		(start 106.693462 -283.501592)
		(end 106.763058 -283.460952)
		(width 0.1143)
		(layer "In11.Cu")
		(net "P5E_CPU1_P1_RX_DP<10>")
	)
	(segment
		(start 106.763058 -284.151832)
		(end 106.693462 -284.111192)
		(width 0.1143)
		(layer "In11.Cu")
		(net "P5E_CPU1_P1_RX_DP<10>")
	)
	(segment
		(start 93.076522 -385.460494)
		(end 93.076522 -385.046982)
		(width 0.14224)
		(layer "In11.Cu")
		(net "P5E_CPU1_P1_RX_DP<10>")
	)
	(segment
		(start 92.719144 -386.003292)
		(end 92.81414 -385.649216)
		(width 0.14224)
		(layer "In11.Cu")
		(net "P5E_CPU1_P1_RX_DP<10>")
	)
	(segment
		(start 97.497392 -367.551716)
		(end 102.75316 -363.313726)
		(width 0.14224)
		(layer "In11.Cu")
		(net "P5E_CPU1_P1_RX_DP<10>")
	)
	(segment
		(start 92.988384 -385.548632)
		(end 93.076522 -385.460494)
		(width 0.14224)
		(layer "In11.Cu")
		(net "P5E_CPU1_P1_RX_DP<10>")
	)
	(segment
		(start 106.723942 -288.343848)
		(end 106.763058 -288.320988)
		(width 0.1143)
		(layer "In11.Cu")
		(net "P5E_CPU1_P1_RX_DP<10>")
	)
	(segment
		(start 106.198924 -298.160186)
		(end 106.198924 -296.286936)
		(width 0.14224)
		(layer "In11.Cu")
		(net "P5E_CPU1_P1_RX_DP<10>")
	)
	(segment
		(start 126.544578 -339.460586)
		(end 124.32411 -327.102724)
		(width 0.14224)
		(layer "In11.Cu")
		(net "P5E_CPU1_P1_RX_DP<10>")
	)
	(segment
		(start 106.25201 -279.435052)
		(end 106.25328 -279.43429)
		(width 0.1143)
		(layer "In11.Cu")
		(net "P5E_CPU1_P1_RX_DP<10>")
	)
	(segment
		(start 106.250486 -280.07691)
		(end 106.249724 -280.076402)
		(width 0.1143)
		(layer "In11.Cu")
		(net "P5E_CPU1_P1_RX_DP<10>")
	)
	(segment
		(start 106.246168 -280.07437)
		(end 106.243628 -280.0731)
		(width 0.1143)
		(layer "In11.Cu")
		(net "P5E_CPU1_P1_RX_DP<10>")
	)
	(segment
		(start 106.763058 -289.011614)
		(end 106.693462 -288.970974)
		(width 0.1143)
		(layer "In11.Cu")
		(net "P5E_CPU1_P1_RX_DP<10>")
	)
	(segment
		(start 92.763594 -384.3528)
		(end 93.068394 -384.048)
		(width 0.14224)
		(layer "In11.Cu")
		(net "P5E_CPU1_P1_RX_DP<10>")
	)
	(segment
		(start 106.255058 -280.07945)
		(end 106.254042 -280.078942)
		(width 0.1143)
		(layer "In11.Cu")
		(net "P5E_CPU1_P1_RX_DP<10>")
	)
	(segment
		(start 106.198924 -296.258488)
		(end 106.153204 -296.212768)
		(width 0.1143)
		(layer "In11.Cu")
		(net "P5E_CPU1_P1_RX_DP<10>")
	)
	(segment
		(start 106.693462 -285.121604)
		(end 106.763058 -285.080964)
		(width 0.1143)
		(layer "In11.Cu")
		(net "P5E_CPU1_P1_RX_DP<10>")
	)
	(segment
		(start 106.222292 -279.45207)
		(end 106.25201 -279.435052)
		(width 0.1143)
		(layer "In11.Cu")
		(net "P5E_CPU1_P1_RX_DP<10>")
	)
	(segment
		(start 106.763058 -290.631626)
		(end 106.693462 -290.590986)
		(width 0.1143)
		(layer "In11.Cu")
		(net "P5E_CPU1_P1_RX_DP<10>")
	)
	(segment
		(start 93.076522 -385.046982)
		(end 92.760546 -384.731006)
		(width 0.14224)
		(layer "In11.Cu")
		(net "P5E_CPU1_P1_RX_DP<10>")
	)
	(segment
		(start 107.083098 -278.13635)
		(end 107.38104 -278.13635)
		(width 0.1143)
		(layer "In11.Cu")
		(net "P5E_CPU1_P1_RX_DP<10>")
	)
	(segment
		(start 106.699304 -294.837866)
		(end 106.761534 -294.801798)
		(width 0.1143)
		(layer "In11.Cu")
		(net "P5E_CPU1_P1_RX_DP<10>")
	)
	(segment
		(start 106.230166 -295.720262)
		(end 106.326686 -295.623742)
		(width 0.1143)
		(layer "In11.Cu")
		(net "P5E_CPU1_P1_RX_DP<10>")
	)
	(segment
		(start 106.69143 -286.742632)
		(end 106.723942 -286.723836)
		(width 0.1143)
		(layer "In11.Cu")
		(net "P5E_CPU1_P1_RX_DP<10>")
	)
	(segment
		(start 106.243628 -280.0731)
		(end 106.222292 -280.060654)
		(width 0.1143)
		(layer "In11.Cu")
		(net "P5E_CPU1_P1_RX_DP<10>")
	)
	(segment
		(start 106.693462 -278.641556)
		(end 106.763058 -278.600916)
		(width 0.1143)
		(layer "In11.Cu")
		(net "P5E_CPU1_P1_RX_DP<10>")
	)
	(segment
		(start 106.25328 -279.43429)
		(end 106.254042 -279.433782)
		(width 0.1143)
		(layer "In11.Cu")
		(net "P5E_CPU1_P1_RX_DP<10>")
	)
	(segment
		(start 106.760518 -287.390078)
		(end 106.693462 -287.350962)
		(width 0.1143)
		(layer "In11.Cu")
		(net "P5E_CPU1_P1_RX_DP<10>")
	)
	(segment
		(start 106.254042 -280.078942)
		(end 106.25328 -280.078434)
		(width 0.1143)
		(layer "In11.Cu")
		(net "P5E_CPU1_P1_RX_DP<10>")
	)
	(segment
		(start 106.693462 -293.22141)
		(end 106.763058 -293.18077)
		(width 0.1143)
		(layer "In11.Cu")
		(net "P5E_CPU1_P1_RX_DP<10>")
	)
	(segment
		(start 93.068394 -384.048)
		(end 93.068394 -373.74195)
		(width 0.14224)
		(layer "In11.Cu")
		(net "P5E_CPU1_P1_RX_DP<10>")
	)
	(arc
		(start 106.53649 -278.946356)
		(mid 106.578039 -278.774934)
		(end 106.693462 -278.641556)
		(width 0.1143)
		(layer "In11.Cu")
		(net "P5E_CPU1_P1_RX_DP<10>")
	)
	(arc
		(start 106.293158 -279.410922)
		(mid 106.471971 -279.208572)
		(end 106.53649 -278.946356)
		(width 0.1143)
		(layer "In11.Cu")
		(net "P5E_CPU1_P1_RX_DP<10>")
	)
	(arc
		(start 106.763058 -285.080964)
		(mid 107.006385 -284.616398)
		(end 106.763058 -284.151832)
		(width 0.1143)
		(layer "In11.Cu")
		(net "P5E_CPU1_P1_RX_DP<10>")
	)
	(arc
		(start 106.693462 -293.83101)
		(mid 106.536485 -293.52621)
		(end 106.693462 -293.22141)
		(width 0.1143)
		(layer "In11.Cu")
		(net "P5E_CPU1_P1_RX_DP<10>")
	)
	(arc
		(start 106.763058 -283.460952)
		(mid 107.006385 -282.996386)
		(end 106.763058 -282.53182)
		(width 0.1143)
		(layer "In11.Cu")
		(net "P5E_CPU1_P1_RX_DP<10>")
	)
	(arc
		(start 106.693462 -287.350962)
		(mid 106.578035 -287.217586)
		(end 106.53649 -287.046162)
		(width 0.1143)
		(layer "In11.Cu")
		(net "P5E_CPU1_P1_RX_DP<10>")
	)
	(arc
		(start 106.693462 -282.49118)
		(mid 106.536485 -282.18638)
		(end 106.693462 -281.88158)
		(width 0.1143)
		(layer "In11.Cu")
		(net "P5E_CPU1_P1_RX_DP<10>")
	)
	(arc
		(start 106.693462 -280.871168)
		(mid 106.578035 -280.737792)
		(end 106.53649 -280.566368)
		(width 0.1143)
		(layer "In11.Cu")
		(net "P5E_CPU1_P1_RX_DP<10>")
	)
	(arc
		(start 106.763058 -288.320988)
		(mid 106.941871 -288.118638)
		(end 107.00639 -287.856422)
		(width 0.1143)
		(layer "In11.Cu")
		(net "P5E_CPU1_P1_RX_DP<10>")
	)
	(arc
		(start 106.693462 -285.731204)
		(mid 106.536485 -285.426404)
		(end 106.693462 -285.121604)
		(width 0.1143)
		(layer "In11.Cu")
		(net "P5E_CPU1_P1_RX_DP<10>")
	)
	(arc
		(start 106.53649 -287.046162)
		(mid 106.577456 -286.875756)
		(end 106.69143 -286.742632)
		(width 0.1143)
		(layer "In11.Cu")
		(net "P5E_CPU1_P1_RX_DP<10>")
	)
	(arc
		(start 106.763058 -293.18077)
		(mid 107.006385 -292.716204)
		(end 106.763058 -292.251638)
		(width 0.1143)
		(layer "In11.Cu")
		(net "P5E_CPU1_P1_RX_DP<10>")
	)
	(arc
		(start 102.75316 -363.313726)
		(mid 102.757656 -363.310195)
		(end 102.762304 -363.306868)
		(width 0.14224)
		(layer "In11.Cu")
		(net "P5E_CPU1_P1_RX_DP<10>")
	)
	(arc
		(start 106.763058 -291.560758)
		(mid 107.006385 -291.096192)
		(end 106.763058 -290.631626)
		(width 0.1143)
		(layer "In11.Cu")
		(net "P5E_CPU1_P1_RX_DP<10>")
	)
	(arc
		(start 106.693462 -292.210998)
		(mid 106.536485 -291.906198)
		(end 106.693462 -291.601398)
		(width 0.1143)
		(layer "In11.Cu")
		(net "P5E_CPU1_P1_RX_DP<10>")
	)
	(arc
		(start 106.763058 -286.700976)
		(mid 107.006385 -286.23641)
		(end 106.763058 -285.771844)
		(width 0.1143)
		(layer "In11.Cu")
		(net "P5E_CPU1_P1_RX_DP<10>")
	)
	(arc
		(start 106.693462 -290.590986)
		(mid 106.536485 -290.286186)
		(end 106.693462 -289.981386)
		(width 0.1143)
		(layer "In11.Cu")
		(net "P5E_CPU1_P1_RX_DP<10>")
	)
	(arc
		(start 106.761534 -294.801798)
		(mid 106.762296 -294.801291)
		(end 106.763058 -294.800782)
		(width 0.1143)
		(layer "In11.Cu")
		(net "P5E_CPU1_P1_RX_DP<10>")
	)
	(arc
		(start 106.763058 -278.600916)
		(mid 106.915045 -278.444408)
		(end 106.996484 -278.242014)
		(width 0.1143)
		(layer "In11.Cu")
		(net "P5E_CPU1_P1_RX_DP<10>")
	)
	(arc
		(start 93.068394 -373.74195)
		(mid 93.074505 -373.702988)
		(end 93.09227 -373.667782)
		(width 0.14224)
		(layer "In11.Cu")
		(net "P5E_CPU1_P1_RX_DP<10>")
	)
	(arc
		(start 106.53649 -288.666174)
		(mid 106.577456 -288.495768)
		(end 106.69143 -288.362644)
		(width 0.1143)
		(layer "In11.Cu")
		(net "P5E_CPU1_P1_RX_DP<10>")
	)
	(arc
		(start 106.326686 -295.623742)
		(mid 106.480339 -295.39347)
		(end 106.536236 -295.122346)
		(width 0.1143)
		(layer "In11.Cu")
		(net "P5E_CPU1_P1_RX_DP<10>")
	)
	(arc
		(start 123.248166 -349.617538)
		(mid 123.806534 -349.105304)
		(end 124.184156 -348.448376)
		(width 0.14224)
		(layer "In11.Cu")
		(net "P5E_CPU1_P1_RX_DP<10>")
	)
	(arc
		(start 106.763058 -294.800782)
		(mid 107.006385 -294.336216)
		(end 106.763058 -293.87165)
		(width 0.1143)
		(layer "In11.Cu")
		(net "P5E_CPU1_P1_RX_DP<10>")
	)
	(arc
		(start 106.222292 -280.060654)
		(mid 106.066364 -279.756362)
		(end 106.222292 -279.45207)
		(width 0.1143)
		(layer "In11.Cu")
		(net "P5E_CPU1_P1_RX_DP<10>")
	)
	(arc
		(start 106.693462 -284.111192)
		(mid 106.536485 -283.806392)
		(end 106.693462 -283.501592)
		(width 0.1143)
		(layer "In11.Cu")
		(net "P5E_CPU1_P1_RX_DP<10>")
	)
	(arc
		(start 106.153204 -295.90619)
		(mid 106.1732 -295.805572)
		(end 106.230166 -295.720262)
		(width 0.1143)
		(layer "In11.Cu")
		(net "P5E_CPU1_P1_RX_DP<10>")
	)
	(arc
		(start 97.474024 -367.576354)
		(mid 97.48488 -367.563249)
		(end 97.497392 -367.551716)
		(width 0.14224)
		(layer "In11.Cu")
		(net "P5E_CPU1_P1_RX_DP<10>")
	)
	(arc
		(start 106.693462 -288.970974)
		(mid 106.578035 -288.837598)
		(end 106.53649 -288.666174)
		(width 0.1143)
		(layer "In11.Cu")
		(net "P5E_CPU1_P1_RX_DP<10>")
	)
	(arc
		(start 106.763058 -281.84094)
		(mid 107.006385 -281.376374)
		(end 106.763058 -280.911808)
		(width 0.1143)
		(layer "In11.Cu")
		(net "P5E_CPU1_P1_RX_DP<10>")
	)
	(arc
		(start 106.53649 -280.566368)
		(mid 106.471975 -280.304149)
		(end 106.293158 -280.101802)
		(width 0.1143)
		(layer "In11.Cu")
		(net "P5E_CPU1_P1_RX_DP<10>")
	)
	(arc
		(start 107.00639 -287.856422)
		(mid 106.941154 -287.592831)
		(end 106.760518 -287.390078)
		(width 0.1143)
		(layer "In11.Cu")
		(net "P5E_CPU1_P1_RX_DP<10>")
	)
	(arc
		(start 106.536236 -295.122346)
		(mid 106.579893 -294.958393)
		(end 106.699304 -294.837866)
		(width 0.1143)
		(layer "In11.Cu")
		(net "P5E_CPU1_P1_RX_DP<10>")
	)
	(arc
		(start 106.763058 -289.940746)
		(mid 107.006385 -289.47618)
		(end 106.763058 -289.011614)
		(width 0.1143)
		(layer "In11.Cu")
		(net "P5E_CPU1_P1_RX_DP<10>")
	)
	(arc
		(start 106.996484 -278.242014)
		(mid 106.998507 -278.230604)
		(end 107.000294 -278.219154)
		(width 0.1143)
		(layer "In11.Cu")
		(net "P5E_CPU1_P1_RX_DP<10>")
	)
	(segment
		(start 99.387914 -276.2504)
		(end 98.921062 -276.516338)
		(width 0.12954)
		(layer "F.Cu")
		(net "P5E_CPU1_P1_RX_DP<0>")
	)
	(segment
		(start 80.198468 -386.003292)
		(end 80.719168 -386.003292)
		(width 0.127)
		(layer "F.Cu")
		(net "P5E_CPU1_P1_RX_DP<0>")
	)
	(segment
		(start 97.29343 -293.22141)
		(end 97.363026 -293.18077)
		(width 0.1143)
		(layer "In11.Cu")
		(net "P5E_CPU1_P1_RX_DP<0>")
	)
	(segment
		(start 80.94853 -381.99441)
		(end 76.73086 -377.77674)
		(width 0.14224)
		(layer "In11.Cu")
		(net "P5E_CPU1_P1_RX_DP<0>")
	)
	(segment
		(start 98.540316 -276.599142)
		(end 98.62312 -276.516338)
		(width 0.1143)
		(layer "In11.Cu")
		(net "P5E_CPU1_P1_RX_DP<0>")
	)
	(segment
		(start 80.76057 -384.731006)
		(end 80.763618 -384.3528)
		(width 0.14224)
		(layer "In11.Cu")
		(net "P5E_CPU1_P1_RX_DP<0>")
	)
	(segment
		(start 97.363026 -292.251638)
		(end 97.29343 -292.210998)
		(width 0.1143)
		(layer "In11.Cu")
		(net "P5E_CPU1_P1_RX_DP<0>")
	)
	(segment
		(start 97.29343 -283.501592)
		(end 97.363026 -283.460952)
		(width 0.1143)
		(layer "In11.Cu")
		(net "P5E_CPU1_P1_RX_DP<0>")
	)
	(segment
		(start 100.98405 -309.935626)
		(end 96.712024 -299.621702)
		(width 0.14224)
		(layer "In11.Cu")
		(net "P5E_CPU1_P1_RX_DP<0>")
	)
	(segment
		(start 80.719168 -386.003292)
		(end 80.814164 -385.649216)
		(width 0.14224)
		(layer "In11.Cu")
		(net "P5E_CPU1_P1_RX_DP<0>")
	)
	(segment
		(start 97.29343 -294.841422)
		(end 97.363026 -294.800782)
		(width 0.1143)
		(layer "In11.Cu")
		(net "P5E_CPU1_P1_RX_DP<0>")
	)
	(segment
		(start 97.291398 -286.742632)
		(end 97.294446 -286.7406)
		(width 0.1143)
		(layer "In11.Cu")
		(net "P5E_CPU1_P1_RX_DP<0>")
	)
	(segment
		(start 97.762314 -277.832058)
		(end 97.787714 -277.817326)
		(width 0.1143)
		(layer "In11.Cu")
		(net "P5E_CPU1_P1_RX_DP<0>")
	)
	(segment
		(start 98.62312 -276.516338)
		(end 98.921062 -276.516338)
		(width 0.1143)
		(layer "In11.Cu")
		(net "P5E_CPU1_P1_RX_DP<0>")
	)
	(segment
		(start 97.29343 -289.981386)
		(end 97.363026 -289.940746)
		(width 0.1143)
		(layer "In11.Cu")
		(net "P5E_CPU1_P1_RX_DP<0>")
	)
	(segment
		(start 114.303556 -328.08799)
		(end 107.894882 -320.27876)
		(width 0.14224)
		(layer "In11.Cu")
		(net "P5E_CPU1_P1_RX_DP<0>")
	)
	(segment
		(start 85.611462 -361.396788)
		(end 95.651828 -356.408482)
		(width 0.14224)
		(layer "In11.Cu")
		(net "P5E_CPU1_P1_RX_DP<0>")
	)
	(segment
		(start 97.29343 -281.88158)
		(end 97.363026 -281.84094)
		(width 0.1143)
		(layer "In11.Cu")
		(net "P5E_CPU1_P1_RX_DP<0>")
	)
	(segment
		(start 97.29343 -291.601398)
		(end 97.363026 -291.560758)
		(width 0.1143)
		(layer "In11.Cu")
		(net "P5E_CPU1_P1_RX_DP<0>")
	)
	(segment
		(start 97.29343 -285.121604)
		(end 97.363026 -285.080964)
		(width 0.1143)
		(layer "In11.Cu")
		(net "P5E_CPU1_P1_RX_DP<0>")
	)
	(segment
		(start 97.796604 -277.812246)
		(end 97.83318 -277.79091)
		(width 0.1143)
		(layer "In11.Cu")
		(net "P5E_CPU1_P1_RX_DP<0>")
	)
	(segment
		(start 81.068418 -384.048254)
		(end 81.068418 -382.283716)
		(width 0.14224)
		(layer "In11.Cu")
		(net "P5E_CPU1_P1_RX_DP<0>")
	)
	(segment
		(start 76.707238 -377.744228)
		(end 76.249784 -376.841258)
		(width 0.14224)
		(layer "In11.Cu")
		(net "P5E_CPU1_P1_RX_DP<0>")
	)
	(segment
		(start 97.291398 -288.362644)
		(end 97.363026 -288.320988)
		(width 0.1143)
		(layer "In11.Cu")
		(net "P5E_CPU1_P1_RX_DP<0>")
	)
	(segment
		(start 73.294494 -372.05285)
		(end 73.278492 -370.912898)
		(width 0.14224)
		(layer "In11.Cu")
		(net "P5E_CPU1_P1_RX_DP<0>")
	)
	(segment
		(start 97.789746 -277.81631)
		(end 97.790508 -277.815802)
		(width 0.1143)
		(layer "In11.Cu")
		(net "P5E_CPU1_P1_RX_DP<0>")
	)
	(segment
		(start 97.363026 -289.011614)
		(end 97.29343 -288.970974)
		(width 0.1143)
		(layer "In11.Cu")
		(net "P5E_CPU1_P1_RX_DP<0>")
	)
	(segment
		(start 96.666304 -296.389806)
		(end 96.666304 -296.236136)
		(width 0.1143)
		(layer "In11.Cu")
		(net "P5E_CPU1_P1_RX_DP<0>")
	)
	(segment
		(start 97.794064 -277.81377)
		(end 97.79508 -277.813262)
		(width 0.1143)
		(layer "In11.Cu")
		(net "P5E_CPU1_P1_RX_DP<0>")
	)
	(segment
		(start 97.360486 -287.390078)
		(end 97.29343 -287.350962)
		(width 0.1143)
		(layer "In11.Cu")
		(net "P5E_CPU1_P1_RX_DP<0>")
	)
	(segment
		(start 97.787714 -277.817326)
		(end 97.789746 -277.81631)
		(width 0.1143)
		(layer "In11.Cu")
		(net "P5E_CPU1_P1_RX_DP<0>")
	)
	(segment
		(start 96.893126 -280.101802)
		(end 96.833436 -280.067004)
		(width 0.1143)
		(layer "In11.Cu")
		(net "P5E_CPU1_P1_RX_DP<0>")
	)
	(segment
		(start 97.363026 -282.53182)
		(end 97.29343 -282.49118)
		(width 0.1143)
		(layer "In11.Cu")
		(net "P5E_CPU1_P1_RX_DP<0>")
	)
	(segment
		(start 96.832166 -279.446228)
		(end 96.832674 -279.446228)
		(width 0.1143)
		(layer "In11.Cu")
		(net "P5E_CPU1_P1_RX_DP<0>")
	)
	(segment
		(start 115.91163 -342.523318)
		(end 116.750084 -340.49843)
		(width 0.14224)
		(layer "In11.Cu")
		(net "P5E_CPU1_P1_RX_DP<0>")
	)
	(segment
		(start 97.363026 -293.87165)
		(end 97.29343 -293.83101)
		(width 0.1143)
		(layer "In11.Cu")
		(net "P5E_CPU1_P1_RX_DP<0>")
	)
	(segment
		(start 107.894882 -320.27876)
		(end 100.98405 -309.935626)
		(width 0.14224)
		(layer "In11.Cu")
		(net "P5E_CPU1_P1_RX_DP<0>")
	)
	(segment
		(start 97.363026 -280.911808)
		(end 97.29343 -280.871168)
		(width 0.1143)
		(layer "In11.Cu")
		(net "P5E_CPU1_P1_RX_DP<0>")
	)
	(segment
		(start 116.750084 -340.49843)
		(end 116.750084 -338.596732)
		(width 0.14224)
		(layer "In11.Cu")
		(net "P5E_CPU1_P1_RX_DP<0>")
	)
	(segment
		(start 75.752198 -367.39068)
		(end 76.742544 -366.612424)
		(width 0.14224)
		(layer "In11.Cu")
		(net "P5E_CPU1_P1_RX_DP<0>")
	)
	(segment
		(start 96.712024 -296.463974)
		(end 96.712024 -296.435526)
		(width 0.1143)
		(layer "In11.Cu")
		(net "P5E_CPU1_P1_RX_DP<0>")
	)
	(segment
		(start 96.712024 -296.435526)
		(end 96.666304 -296.389806)
		(width 0.1143)
		(layer "In11.Cu")
		(net "P5E_CPU1_P1_RX_DP<0>")
	)
	(segment
		(start 97.29343 -278.641556)
		(end 97.363026 -278.600916)
		(width 0.1143)
		(layer "In11.Cu")
		(net "P5E_CPU1_P1_RX_DP<0>")
	)
	(segment
		(start 95.651828 -356.408482)
		(end 115.279424 -343.293446)
		(width 0.14224)
		(layer "In11.Cu")
		(net "P5E_CPU1_P1_RX_DP<0>")
	)
	(segment
		(start 80.814164 -385.649216)
		(end 80.988408 -385.548632)
		(width 0.14224)
		(layer "In11.Cu")
		(net "P5E_CPU1_P1_RX_DP<0>")
	)
	(segment
		(start 75.172062 -375.002806)
		(end 73.385426 -372.343426)
		(width 0.14224)
		(layer "In11.Cu")
		(net "P5E_CPU1_P1_RX_DP<0>")
	)
	(segment
		(start 75.752198 -367.390934)
		(end 75.752198 -367.39068)
		(width 0.14224)
		(layer "In11.Cu")
		(net "P5E_CPU1_P1_RX_DP<0>")
	)
	(segment
		(start 97.790508 -277.815802)
		(end 97.793302 -277.814278)
		(width 0.1143)
		(layer "In11.Cu")
		(net "P5E_CPU1_P1_RX_DP<0>")
	)
	(segment
		(start 73.359772 -370.657628)
		(end 75.728068 -367.415826)
		(width 0.14224)
		(layer "In11.Cu")
		(net "P5E_CPU1_P1_RX_DP<0>")
	)
	(segment
		(start 97.363026 -284.151832)
		(end 97.29343 -284.111192)
		(width 0.1143)
		(layer "In11.Cu")
		(net "P5E_CPU1_P1_RX_DP<0>")
	)
	(segment
		(start 96.833436 -280.067004)
		(end 96.832674 -280.066496)
		(width 0.1143)
		(layer "In11.Cu")
		(net "P5E_CPU1_P1_RX_DP<0>")
	)
	(segment
		(start 97.136458 -295.160954)
		(end 97.136458 -295.146222)
		(width 0.1143)
		(layer "In11.Cu")
		(net "P5E_CPU1_P1_RX_DP<0>")
	)
	(segment
		(start 116.750084 -338.596732)
		(end 115.152424 -329.711812)
		(width 0.14224)
		(layer "In11.Cu")
		(net "P5E_CPU1_P1_RX_DP<0>")
	)
	(segment
		(start 96.712024 -299.621702)
		(end 96.712024 -296.463974)
		(width 0.14224)
		(layer "In11.Cu")
		(net "P5E_CPU1_P1_RX_DP<0>")
	)
	(segment
		(start 80.988408 -385.548632)
		(end 81.076546 -385.460494)
		(width 0.14224)
		(layer "In11.Cu")
		(net "P5E_CPU1_P1_RX_DP<0>")
	)
	(segment
		(start 97.363026 -290.631626)
		(end 97.29343 -290.590986)
		(width 0.1143)
		(layer "In11.Cu")
		(net "P5E_CPU1_P1_RX_DP<0>")
	)
	(segment
		(start 97.793302 -277.814278)
		(end 97.794064 -277.81377)
		(width 0.1143)
		(layer "In11.Cu")
		(net "P5E_CPU1_P1_RX_DP<0>")
	)
	(segment
		(start 81.076546 -385.460494)
		(end 81.076546 -385.046982)
		(width 0.14224)
		(layer "In11.Cu")
		(net "P5E_CPU1_P1_RX_DP<0>")
	)
	(segment
		(start 96.832674 -279.446228)
		(end 96.892364 -279.41143)
		(width 0.1143)
		(layer "In11.Cu")
		(net "P5E_CPU1_P1_RX_DP<0>")
	)
	(segment
		(start 96.832674 -280.066496)
		(end 96.83242 -280.066496)
		(width 0.1143)
		(layer "In11.Cu")
		(net "P5E_CPU1_P1_RX_DP<0>")
	)
	(segment
		(start 96.86925 -295.74617)
		(end 96.911414 -295.704006)
		(width 0.1143)
		(layer "In11.Cu")
		(net "P5E_CPU1_P1_RX_DP<0>")
	)
	(segment
		(start 77.005434 -366.433354)
		(end 85.611462 -361.396788)
		(width 0.14224)
		(layer "In11.Cu")
		(net "P5E_CPU1_P1_RX_DP<0>")
	)
	(segment
		(start 115.152424 -329.711812)
		(end 114.303556 -328.08799)
		(width 0.14224)
		(layer "In11.Cu")
		(net "P5E_CPU1_P1_RX_DP<0>")
	)
	(segment
		(start 97.294446 -286.7406)
		(end 97.363026 -286.700976)
		(width 0.1143)
		(layer "In11.Cu")
		(net "P5E_CPU1_P1_RX_DP<0>")
	)
	(segment
		(start 81.076546 -385.046982)
		(end 80.76057 -384.731006)
		(width 0.14224)
		(layer "In11.Cu")
		(net "P5E_CPU1_P1_RX_DP<0>")
	)
	(segment
		(start 98.233484 -277.021544)
		(end 98.30308 -276.980904)
		(width 0.1143)
		(layer "In11.Cu")
		(net "P5E_CPU1_P1_RX_DP<0>")
	)
	(segment
		(start 97.79508 -277.813262)
		(end 97.796604 -277.812246)
		(width 0.1143)
		(layer "In11.Cu")
		(net "P5E_CPU1_P1_RX_DP<0>")
	)
	(segment
		(start 80.763618 -384.3528)
		(end 81.068418 -384.048254)
		(width 0.14224)
		(layer "In11.Cu")
		(net "P5E_CPU1_P1_RX_DP<0>")
	)
	(segment
		(start 97.363026 -285.771844)
		(end 97.29343 -285.731204)
		(width 0.1143)
		(layer "In11.Cu")
		(net "P5E_CPU1_P1_RX_DP<0>")
	)
	(arc
		(start 97.136458 -287.046162)
		(mid 97.177424 -286.875756)
		(end 97.291398 -286.742632)
		(width 0.1143)
		(layer "In11.Cu")
		(net "P5E_CPU1_P1_RX_DP<0>")
	)
	(arc
		(start 97.29343 -285.731204)
		(mid 97.136453 -285.426404)
		(end 97.29343 -285.121604)
		(width 0.1143)
		(layer "In11.Cu")
		(net "P5E_CPU1_P1_RX_DP<0>")
	)
	(arc
		(start 97.29343 -288.970974)
		(mid 97.178003 -288.837598)
		(end 97.136458 -288.666174)
		(width 0.1143)
		(layer "In11.Cu")
		(net "P5E_CPU1_P1_RX_DP<0>")
	)
	(arc
		(start 96.911414 -295.704006)
		(mid 97.077947 -295.454866)
		(end 97.136458 -295.160954)
		(width 0.1143)
		(layer "In11.Cu")
		(net "P5E_CPU1_P1_RX_DP<0>")
	)
	(arc
		(start 97.606358 -278.13635)
		(mid 97.647613 -277.965379)
		(end 97.762314 -277.832058)
		(width 0.1143)
		(layer "In11.Cu")
		(net "P5E_CPU1_P1_RX_DP<0>")
	)
	(arc
		(start 97.29343 -292.210998)
		(mid 97.136453 -291.906198)
		(end 97.29343 -291.601398)
		(width 0.1143)
		(layer "In11.Cu")
		(net "P5E_CPU1_P1_RX_DP<0>")
	)
	(arc
		(start 97.29343 -284.111192)
		(mid 97.136453 -283.806392)
		(end 97.29343 -283.501592)
		(width 0.1143)
		(layer "In11.Cu")
		(net "P5E_CPU1_P1_RX_DP<0>")
	)
	(arc
		(start 96.893126 -279.410922)
		(mid 97.071939 -279.208572)
		(end 97.136458 -278.946356)
		(width 0.1143)
		(layer "In11.Cu")
		(net "P5E_CPU1_P1_RX_DP<0>")
	)
	(arc
		(start 97.83318 -277.79091)
		(mid 98.011993 -277.58856)
		(end 98.076512 -277.326344)
		(width 0.1143)
		(layer "In11.Cu")
		(net "P5E_CPU1_P1_RX_DP<0>")
	)
	(arc
		(start 97.136458 -295.146222)
		(mid 97.178007 -294.9748)
		(end 97.29343 -294.841422)
		(width 0.1143)
		(layer "In11.Cu")
		(net "P5E_CPU1_P1_RX_DP<0>")
	)
	(arc
		(start 73.385426 -372.343426)
		(mid 73.318823 -372.20475)
		(end 73.294494 -372.05285)
		(width 0.14224)
		(layer "In11.Cu")
		(net "P5E_CPU1_P1_RX_DP<0>")
	)
	(arc
		(start 96.666304 -296.236136)
		(mid 96.719049 -295.97097)
		(end 96.86925 -295.74617)
		(width 0.1143)
		(layer "In11.Cu")
		(net "P5E_CPU1_P1_RX_DP<0>")
	)
	(arc
		(start 76.249784 -376.841258)
		(mid 75.739107 -375.90551)
		(end 75.172062 -375.002806)
		(width 0.14224)
		(layer "In11.Cu")
		(net "P5E_CPU1_P1_RX_DP<0>")
	)
	(arc
		(start 96.892364 -279.41143)
		(mid 96.892745 -279.411176)
		(end 96.893126 -279.410922)
		(width 0.1143)
		(layer "In11.Cu")
		(net "P5E_CPU1_P1_RX_DP<0>")
	)
	(arc
		(start 97.29343 -282.49118)
		(mid 97.136453 -282.18638)
		(end 97.29343 -281.88158)
		(width 0.1143)
		(layer "In11.Cu")
		(net "P5E_CPU1_P1_RX_DP<0>")
	)
	(arc
		(start 97.363026 -291.560758)
		(mid 97.606353 -291.096192)
		(end 97.363026 -290.631626)
		(width 0.1143)
		(layer "In11.Cu")
		(net "P5E_CPU1_P1_RX_DP<0>")
	)
	(arc
		(start 97.29343 -287.350962)
		(mid 97.178003 -287.217586)
		(end 97.136458 -287.046162)
		(width 0.1143)
		(layer "In11.Cu")
		(net "P5E_CPU1_P1_RX_DP<0>")
	)
	(arc
		(start 97.29343 -280.871168)
		(mid 97.178003 -280.737792)
		(end 97.136458 -280.566368)
		(width 0.1143)
		(layer "In11.Cu")
		(net "P5E_CPU1_P1_RX_DP<0>")
	)
	(arc
		(start 97.363026 -289.940746)
		(mid 97.606353 -289.47618)
		(end 97.363026 -289.011614)
		(width 0.1143)
		(layer "In11.Cu")
		(net "P5E_CPU1_P1_RX_DP<0>")
	)
	(arc
		(start 97.363026 -294.800782)
		(mid 97.606353 -294.336216)
		(end 97.363026 -293.87165)
		(width 0.1143)
		(layer "In11.Cu")
		(net "P5E_CPU1_P1_RX_DP<0>")
	)
	(arc
		(start 97.363026 -285.080964)
		(mid 97.606353 -284.616398)
		(end 97.363026 -284.151832)
		(width 0.1143)
		(layer "In11.Cu")
		(net "P5E_CPU1_P1_RX_DP<0>")
	)
	(arc
		(start 76.742544 -366.612424)
		(mid 76.870928 -366.518396)
		(end 77.005434 -366.433354)
		(width 0.14224)
		(layer "In11.Cu")
		(net "P5E_CPU1_P1_RX_DP<0>")
	)
	(arc
		(start 73.278492 -370.912898)
		(mid 73.298356 -370.778647)
		(end 73.359772 -370.657628)
		(width 0.14224)
		(layer "In11.Cu")
		(net "P5E_CPU1_P1_RX_DP<0>")
	)
	(arc
		(start 98.076512 -277.326344)
		(mid 98.118061 -277.154922)
		(end 98.233484 -277.021544)
		(width 0.1143)
		(layer "In11.Cu")
		(net "P5E_CPU1_P1_RX_DP<0>")
	)
	(arc
		(start 97.363026 -278.600916)
		(mid 97.541839 -278.398566)
		(end 97.606358 -278.13635)
		(width 0.1143)
		(layer "In11.Cu")
		(net "P5E_CPU1_P1_RX_DP<0>")
	)
	(arc
		(start 75.728068 -367.415826)
		(mid 75.739271 -367.402543)
		(end 75.752198 -367.390934)
		(width 0.14224)
		(layer "In11.Cu")
		(net "P5E_CPU1_P1_RX_DP<0>")
	)
	(arc
		(start 97.363026 -293.18077)
		(mid 97.606353 -292.716204)
		(end 97.363026 -292.251638)
		(width 0.1143)
		(layer "In11.Cu")
		(net "P5E_CPU1_P1_RX_DP<0>")
	)
	(arc
		(start 98.536506 -276.622002)
		(mid 98.538529 -276.610592)
		(end 98.540316 -276.599142)
		(width 0.1143)
		(layer "In11.Cu")
		(net "P5E_CPU1_P1_RX_DP<0>")
	)
	(arc
		(start 97.363026 -283.460952)
		(mid 97.606353 -282.996386)
		(end 97.363026 -282.53182)
		(width 0.1143)
		(layer "In11.Cu")
		(net "P5E_CPU1_P1_RX_DP<0>")
	)
	(arc
		(start 97.136458 -278.946356)
		(mid 97.178007 -278.774934)
		(end 97.29343 -278.641556)
		(width 0.1143)
		(layer "In11.Cu")
		(net "P5E_CPU1_P1_RX_DP<0>")
	)
	(arc
		(start 97.29343 -293.83101)
		(mid 97.136453 -293.52621)
		(end 97.29343 -293.22141)
		(width 0.1143)
		(layer "In11.Cu")
		(net "P5E_CPU1_P1_RX_DP<0>")
	)
	(arc
		(start 81.068418 -382.283716)
		(mid 81.037255 -382.127138)
		(end 80.94853 -381.99441)
		(width 0.14224)
		(layer "In11.Cu")
		(net "P5E_CPU1_P1_RX_DP<0>")
	)
	(arc
		(start 115.279424 -343.293446)
		(mid 115.652672 -342.955289)
		(end 115.91163 -342.523318)
		(width 0.14224)
		(layer "In11.Cu")
		(net "P5E_CPU1_P1_RX_DP<0>")
	)
	(arc
		(start 97.29343 -290.590986)
		(mid 97.136453 -290.286186)
		(end 97.29343 -289.981386)
		(width 0.1143)
		(layer "In11.Cu")
		(net "P5E_CPU1_P1_RX_DP<0>")
	)
	(arc
		(start 97.136458 -288.666174)
		(mid 97.177424 -288.495768)
		(end 97.291398 -288.362644)
		(width 0.1143)
		(layer "In11.Cu")
		(net "P5E_CPU1_P1_RX_DP<0>")
	)
	(arc
		(start 97.363026 -288.320988)
		(mid 97.60635 -287.854872)
		(end 97.360486 -287.390078)
		(width 0.1143)
		(layer "In11.Cu")
		(net "P5E_CPU1_P1_RX_DP<0>")
	)
	(arc
		(start 76.73086 -377.77674)
		(mid 76.71778 -377.761408)
		(end 76.707238 -377.744228)
		(width 0.14224)
		(layer "In11.Cu")
		(net "P5E_CPU1_P1_RX_DP<0>")
	)
	(arc
		(start 97.363026 -286.700976)
		(mid 97.606353 -286.23641)
		(end 97.363026 -285.771844)
		(width 0.1143)
		(layer "In11.Cu")
		(net "P5E_CPU1_P1_RX_DP<0>")
	)
	(arc
		(start 97.363026 -281.84094)
		(mid 97.606353 -281.376374)
		(end 97.363026 -280.911808)
		(width 0.1143)
		(layer "In11.Cu")
		(net "P5E_CPU1_P1_RX_DP<0>")
	)
	(arc
		(start 96.83242 -280.066496)
		(mid 96.66311 -279.756469)
		(end 96.832166 -279.446228)
		(width 0.1143)
		(layer "In11.Cu")
		(net "P5E_CPU1_P1_RX_DP<0>")
	)
	(arc
		(start 98.30308 -276.980904)
		(mid 98.455067 -276.824396)
		(end 98.536506 -276.622002)
		(width 0.1143)
		(layer "In11.Cu")
		(net "P5E_CPU1_P1_RX_DP<0>")
	)
	(arc
		(start 97.136458 -280.566368)
		(mid 97.071943 -280.304149)
		(end 96.893126 -280.101802)
		(width 0.1143)
		(layer "In11.Cu")
		(net "P5E_CPU1_P1_RX_DP<0>")
	)
	(segment
		(start 106.907838 -276.2504)
		(end 106.440986 -276.516338)
		(width 0.12954)
		(layer "F.Cu")
		(net "P5E_CPU1_P1_RX_DN<9>")
	)
	(segment
		(start 90.598244 -385.31038)
		(end 91.118944 -385.31038)
		(width 0.127)
		(layer "F.Cu")
		(net "P5E_CPU1_P1_RX_DN<9>")
	)
	(segment
		(start 120.937528 -323.24548)
		(end 114.00028 -314.792614)
		(width 0.14224)
		(layer "In11.Cu")
		(net "P5E_CPU1_P1_RX_DN<9>")
	)
	(segment
		(start 91.621864 -380.022608)
		(end 91.48699 -379.883416)
		(width 0.14224)
		(layer "In11.Cu")
		(net "P5E_CPU1_P1_RX_DN<9>")
	)
	(segment
		(start 91.586304 -382.432814)
		(end 91.6051 -381.150114)
		(width 0.14224)
		(layer "In11.Cu")
		(net "P5E_CPU1_P1_RX_DN<9>")
	)
	(segment
		(start 106.738928 -276.516338)
		(end 106.440986 -276.516338)
		(width 0.1143)
		(layer "In11.Cu")
		(net "P5E_CPU1_P1_RX_DN<9>")
	)
	(segment
		(start 91.586304 -383.930906)
		(end 91.586304 -382.432814)
		(width 0.14224)
		(layer "In11.Cu")
		(net "P5E_CPU1_P1_RX_DN<9>")
	)
	(segment
		(start 91.282266 -384.234944)
		(end 91.586304 -383.930906)
		(width 0.14224)
		(layer "In11.Cu")
		(net "P5E_CPU1_P1_RX_DN<9>")
	)
	(segment
		(start 91.5035 -378.755656)
		(end 91.50985 -378.328682)
		(width 0.14224)
		(layer "In11.Cu")
		(net "P5E_CPU1_P1_RX_DN<9>")
	)
	(segment
		(start 105.719626 -289.172142)
		(end 105.687876 -289.153346)
		(width 0.1143)
		(layer "In11.Cu")
		(net "P5E_CPU1_P1_RX_DN<9>")
	)
	(segment
		(start 105.650538 -294.680894)
		(end 105.71988 -294.640254)
		(width 0.1143)
		(layer "In11.Cu")
		(net "P5E_CPU1_P1_RX_DN<9>")
	)
	(segment
		(start 105.650538 -284.960822)
		(end 105.687876 -284.939232)
		(width 0.1143)
		(layer "In11.Cu")
		(net "P5E_CPU1_P1_RX_DN<9>")
	)
	(segment
		(start 105.249218 -280.262584)
		(end 105.248202 -280.261822)
		(width 0.1143)
		(layer "In11.Cu")
		(net "P5E_CPU1_P1_RX_DN<9>")
	)
	(segment
		(start 105.19029 -295.53916)
		(end 105.348532 -295.380918)
		(width 0.1143)
		(layer "In11.Cu")
		(net "P5E_CPU1_P1_RX_DN<9>")
	)
	(segment
		(start 106.154474 -277.650956)
		(end 106.15803 -277.648416)
		(width 0.1143)
		(layer "In11.Cu")
		(net "P5E_CPU1_P1_RX_DN<9>")
	)
	(segment
		(start 105.648252 -288.201862)
		(end 105.68813 -288.179002)
		(width 0.1143)
		(layer "In11.Cu")
		(net "P5E_CPU1_P1_RX_DN<9>")
	)
	(segment
		(start 91.615768 -380.449074)
		(end 91.621864 -380.022608)
		(width 0.14224)
		(layer "In11.Cu")
		(net "P5E_CPU1_P1_RX_DN<9>")
	)
	(segment
		(start 91.50985 -378.328682)
		(end 91.649296 -378.193554)
		(width 0.14224)
		(layer "In11.Cu")
		(net "P5E_CPU1_P1_RX_DN<9>")
	)
	(segment
		(start 105.211372 -279.272746)
		(end 105.217976 -279.268428)
		(width 0.1143)
		(layer "In11.Cu")
		(net "P5E_CPU1_P1_RX_DN<9>")
	)
	(segment
		(start 125.31725 -342.060276)
		(end 125.317504 -342.060022)
		(width 0.14224)
		(layer "In11.Cu")
		(net "P5E_CPU1_P1_RX_DN<9>")
	)
	(segment
		(start 91.594432 -385.163822)
		(end 91.27744 -384.84683)
		(width 0.14224)
		(layer "In11.Cu")
		(net "P5E_CPU1_P1_RX_DN<9>")
	)
	(segment
		(start 91.118944 -385.31038)
		(end 91.472258 -385.405376)
		(width 0.14224)
		(layer "In11.Cu")
		(net "P5E_CPU1_P1_RX_DN<9>")
	)
	(segment
		(start 125.317504 -339.568536)
		(end 123.141486 -327.462134)
		(width 0.14224)
		(layer "In11.Cu")
		(net "P5E_CPU1_P1_RX_DN<9>")
	)
	(segment
		(start 91.6051 -381.150114)
		(end 91.470226 -381.010922)
		(width 0.14224)
		(layer "In11.Cu")
		(net "P5E_CPU1_P1_RX_DN<9>")
	)
	(segment
		(start 96.309434 -366.938052)
		(end 102.004114 -362.347002)
		(width 0.14224)
		(layer "In11.Cu")
		(net "P5E_CPU1_P1_RX_DN<9>")
	)
	(segment
		(start 105.719626 -292.412166)
		(end 105.687876 -292.39337)
		(width 0.1143)
		(layer "In11.Cu")
		(net "P5E_CPU1_P1_RX_DN<9>")
	)
	(segment
		(start 105.650538 -283.34081)
		(end 105.687876 -283.31922)
		(width 0.1143)
		(layer "In11.Cu")
		(net "P5E_CPU1_P1_RX_DN<9>")
	)
	(segment
		(start 105.687876 -282.673552)
		(end 105.650538 -282.651962)
		(width 0.1143)
		(layer "In11.Cu")
		(net "P5E_CPU1_P1_RX_DN<9>")
	)
	(segment
		(start 91.649296 -378.193554)
		(end 91.649042 -378.193554)
		(width 0.14224)
		(layer "In11.Cu")
		(net "P5E_CPU1_P1_RX_DN<9>")
	)
	(segment
		(start 106.119422 -277.671276)
		(end 106.153966 -277.65121)
		(width 0.1143)
		(layer "In11.Cu")
		(net "P5E_CPU1_P1_RX_DN<9>")
	)
	(segment
		(start 91.48699 -379.883416)
		(end 91.493086 -379.456442)
		(width 0.14224)
		(layer "In11.Cu")
		(net "P5E_CPU1_P1_RX_DN<9>")
	)
	(segment
		(start 105.405936 -280.566368)
		(end 105.405936 -280.520648)
		(width 0.1143)
		(layer "In11.Cu")
		(net "P5E_CPU1_P1_RX_DN<9>")
	)
	(segment
		(start 105.650538 -289.820604)
		(end 105.687876 -289.799014)
		(width 0.1143)
		(layer "In11.Cu")
		(net "P5E_CPU1_P1_RX_DN<9>")
	)
	(segment
		(start 105.650538 -281.720798)
		(end 105.687876 -281.699208)
		(width 0.1143)
		(layer "In11.Cu")
		(net "P5E_CPU1_P1_RX_DN<9>")
	)
	(segment
		(start 105.650538 -291.440616)
		(end 105.687876 -291.419026)
		(width 0.1143)
		(layer "In11.Cu")
		(net "P5E_CPU1_P1_RX_DN<9>")
	)
	(segment
		(start 91.470226 -381.010922)
		(end 91.476322 -380.583948)
		(width 0.14224)
		(layer "In11.Cu")
		(net "P5E_CPU1_P1_RX_DN<9>")
	)
	(segment
		(start 91.873578 -373.003318)
		(end 96.147382 -367.108486)
		(width 0.14224)
		(layer "In11.Cu")
		(net "P5E_CPU1_P1_RX_DN<9>")
	)
	(segment
		(start 106.15803 -277.648416)
		(end 106.16311 -277.645876)
		(width 0.1143)
		(layer "In11.Cu")
		(net "P5E_CPU1_P1_RX_DN<9>")
	)
	(segment
		(start 105.719372 -285.931864)
		(end 105.718356 -285.931356)
		(width 0.1143)
		(layer "In11.Cu")
		(net "P5E_CPU1_P1_RX_DN<9>")
	)
	(segment
		(start 105.251504 -280.264108)
		(end 105.250488 -280.263346)
		(width 0.1143)
		(layer "In11.Cu")
		(net "P5E_CPU1_P1_RX_DN<9>")
	)
	(segment
		(start 125.317504 -342.060022)
		(end 125.317504 -339.568536)
		(width 0.14224)
		(layer "In11.Cu")
		(net "P5E_CPU1_P1_RX_DN<9>")
	)
	(segment
		(start 105.719626 -281.072336)
		(end 105.692448 -281.056334)
		(width 0.1143)
		(layer "In11.Cu")
		(net "P5E_CPU1_P1_RX_DN<9>")
	)
	(segment
		(start 91.594432 -385.334764)
		(end 91.594432 -385.163822)
		(width 0.14224)
		(layer "In11.Cu")
		(net "P5E_CPU1_P1_RX_DN<9>")
	)
	(segment
		(start 105.252774 -280.26487)
		(end 105.251504 -280.264108)
		(width 0.1143)
		(layer "In11.Cu")
		(net "P5E_CPU1_P1_RX_DN<9>")
	)
	(segment
		(start 105.687876 -281.699208)
		(end 105.71988 -281.680412)
		(width 0.1143)
		(layer "In11.Cu")
		(net "P5E_CPU1_P1_RX_DN<9>")
	)
	(segment
		(start 105.248202 -280.261822)
		(end 105.246932 -280.26106)
		(width 0.1143)
		(layer "In11.Cu")
		(net "P5E_CPU1_P1_RX_DN<9>")
	)
	(segment
		(start 106.153966 -277.65121)
		(end 106.154474 -277.650956)
		(width 0.1143)
		(layer "In11.Cu")
		(net "P5E_CPU1_P1_RX_DN<9>")
	)
	(segment
		(start 104.97185 -298.370752)
		(end 104.97185 -296.371264)
		(width 0.14224)
		(layer "In11.Cu")
		(net "P5E_CPU1_P1_RX_DN<9>")
	)
	(segment
		(start 105.687876 -293.039038)
		(end 105.71988 -293.020242)
		(width 0.1143)
		(layer "In11.Cu")
		(net "P5E_CPU1_P1_RX_DN<9>")
	)
	(segment
		(start 102.03307 -362.325666)
		(end 122.042682 -348.923356)
		(width 0.14224)
		(layer "In11.Cu")
		(net "P5E_CPU1_P1_RX_DN<9>")
	)
	(segment
		(start 105.687876 -281.053794)
		(end 105.650538 -281.03195)
		(width 0.1143)
		(layer "In11.Cu")
		(net "P5E_CPU1_P1_RX_DN<9>")
	)
	(segment
		(start 105.282746 -280.284936)
		(end 105.254806 -280.266394)
		(width 0.1143)
		(layer "In11.Cu")
		(net "P5E_CPU1_P1_RX_DN<9>")
	)
	(segment
		(start 104.97185 -296.371264)
		(end 104.97185 -296.342816)
		(width 0.1143)
		(layer "In11.Cu")
		(net "P5E_CPU1_P1_RX_DN<9>")
	)
	(segment
		(start 105.650538 -278.480774)
		(end 105.687876 -278.459184)
		(width 0.1143)
		(layer "In11.Cu")
		(net "P5E_CPU1_P1_RX_DN<9>")
	)
	(segment
		(start 105.648252 -286.58185)
		(end 105.68813 -286.55899)
		(width 0.1143)
		(layer "In11.Cu")
		(net "P5E_CPU1_P1_RX_DN<9>")
	)
	(segment
		(start 105.692448 -281.056334)
		(end 105.687876 -281.053794)
		(width 0.1143)
		(layer "In11.Cu")
		(net "P5E_CPU1_P1_RX_DN<9>")
	)
	(segment
		(start 105.254806 -280.266394)
		(end 105.252774 -280.26487)
		(width 0.1143)
		(layer "In11.Cu")
		(net "P5E_CPU1_P1_RX_DN<9>")
	)
	(segment
		(start 105.687876 -290.773358)
		(end 105.650538 -290.751768)
		(width 0.1143)
		(layer "In11.Cu")
		(net "P5E_CPU1_P1_RX_DN<9>")
	)
	(segment
		(start 105.01757 -296.297096)
		(end 105.01757 -295.956736)
		(width 0.1143)
		(layer "In11.Cu")
		(net "P5E_CPU1_P1_RX_DN<9>")
	)
	(segment
		(start 105.250488 -280.263346)
		(end 105.249218 -280.262584)
		(width 0.1143)
		(layer "In11.Cu")
		(net "P5E_CPU1_P1_RX_DN<9>")
	)
	(segment
		(start 91.638628 -378.894848)
		(end 91.5035 -378.755656)
		(width 0.14224)
		(layer "In11.Cu")
		(net "P5E_CPU1_P1_RX_DN<9>")
	)
	(segment
		(start 105.687876 -294.013382)
		(end 105.650538 -293.991792)
		(width 0.1143)
		(layer "In11.Cu")
		(net "P5E_CPU1_P1_RX_DN<9>")
	)
	(segment
		(start 91.493086 -379.456442)
		(end 91.632532 -379.321314)
		(width 0.14224)
		(layer "In11.Cu")
		(net "P5E_CPU1_P1_RX_DN<9>")
	)
	(segment
		(start 105.687876 -289.153346)
		(end 105.650538 -289.131756)
		(width 0.1143)
		(layer "In11.Cu")
		(net "P5E_CPU1_P1_RX_DN<9>")
	)
	(segment
		(start 105.246932 -280.26106)
		(end 105.246678 -280.26106)
		(width 0.1143)
		(layer "In11.Cu")
		(net "P5E_CPU1_P1_RX_DN<9>")
	)
	(segment
		(start 123.252484 -347.411802)
		(end 125.31725 -342.060276)
		(width 0.14224)
		(layer "In11.Cu")
		(net "P5E_CPU1_P1_RX_DN<9>")
	)
	(segment
		(start 105.719626 -294.032178)
		(end 105.687876 -294.013382)
		(width 0.1143)
		(layer "In11.Cu")
		(net "P5E_CPU1_P1_RX_DN<9>")
	)
	(segment
		(start 105.217976 -279.268428)
		(end 105.224834 -279.265126)
		(width 0.1143)
		(layer "In11.Cu")
		(net "P5E_CPU1_P1_RX_DN<9>")
	)
	(segment
		(start 104.97185 -296.342816)
		(end 105.01757 -296.297096)
		(width 0.1143)
		(layer "In11.Cu")
		(net "P5E_CPU1_P1_RX_DN<9>")
	)
	(segment
		(start 105.719626 -290.792154)
		(end 105.687876 -290.773358)
		(width 0.1143)
		(layer "In11.Cu")
		(net "P5E_CPU1_P1_RX_DN<9>")
	)
	(segment
		(start 105.687876 -291.419026)
		(end 105.71988 -291.40023)
		(width 0.1143)
		(layer "In11.Cu")
		(net "P5E_CPU1_P1_RX_DN<9>")
	)
	(segment
		(start 91.632532 -379.321314)
		(end 91.638628 -378.894848)
		(width 0.14224)
		(layer "In11.Cu")
		(net "P5E_CPU1_P1_RX_DN<9>")
	)
	(segment
		(start 105.405936 -295.242742)
		(end 105.405936 -295.146222)
		(width 0.1143)
		(layer "In11.Cu")
		(net "P5E_CPU1_P1_RX_DN<9>")
	)
	(segment
		(start 105.687876 -283.31922)
		(end 105.71988 -283.300424)
		(width 0.1143)
		(layer "In11.Cu")
		(net "P5E_CPU1_P1_RX_DN<9>")
	)
	(segment
		(start 106.809032 -276.586442)
		(end 106.738928 -276.516338)
		(width 0.1143)
		(layer "In11.Cu")
		(net "P5E_CPU1_P1_RX_DN<9>")
	)
	(segment
		(start 105.224834 -279.265126)
		(end 105.24998 -279.250394)
		(width 0.1143)
		(layer "In11.Cu")
		(net "P5E_CPU1_P1_RX_DN<9>")
	)
	(segment
		(start 105.717848 -287.55086)
		(end 105.650538 -287.511744)
		(width 0.1143)
		(layer "In11.Cu")
		(net "P5E_CPU1_P1_RX_DN<9>")
	)
	(segment
		(start 106.62793 -276.839172)
		(end 106.659934 -276.820376)
		(width 0.1143)
		(layer "In11.Cu")
		(net "P5E_CPU1_P1_RX_DN<9>")
	)
	(segment
		(start 91.649296 -378.188728)
		(end 91.7194 -373.467376)
		(width 0.14224)
		(layer "In11.Cu")
		(net "P5E_CPU1_P1_RX_DN<9>")
	)
	(segment
		(start 105.687876 -285.913576)
		(end 105.650538 -285.891986)
		(width 0.1143)
		(layer "In11.Cu")
		(net "P5E_CPU1_P1_RX_DN<9>")
	)
	(segment
		(start 105.687876 -284.939232)
		(end 105.71988 -284.920436)
		(width 0.1143)
		(layer "In11.Cu")
		(net "P5E_CPU1_P1_RX_DN<9>")
	)
	(segment
		(start 105.718356 -285.931356)
		(end 105.687876 -285.913576)
		(width 0.1143)
		(layer "In11.Cu")
		(net "P5E_CPU1_P1_RX_DN<9>")
	)
	(segment
		(start 105.687876 -278.459184)
		(end 105.71988 -278.440388)
		(width 0.1143)
		(layer "In11.Cu")
		(net "P5E_CPU1_P1_RX_DN<9>")
	)
	(segment
		(start 91.7194 -373.467376)
		(end 91.7194 -373.467122)
		(width 0.14224)
		(layer "In11.Cu")
		(net "P5E_CPU1_P1_RX_DN<9>")
	)
	(segment
		(start 105.17759 -279.292304)
		(end 105.209594 -279.274016)
		(width 0.1143)
		(layer "In11.Cu")
		(net "P5E_CPU1_P1_RX_DN<9>")
	)
	(segment
		(start 91.27744 -384.84683)
		(end 91.282266 -384.234944)
		(width 0.14224)
		(layer "In11.Cu")
		(net "P5E_CPU1_P1_RX_DN<9>")
	)
	(segment
		(start 105.719626 -282.692348)
		(end 105.687876 -282.673552)
		(width 0.1143)
		(layer "In11.Cu")
		(net "P5E_CPU1_P1_RX_DN<9>")
	)
	(segment
		(start 91.649042 -378.193554)
		(end 91.649296 -378.188728)
		(width 0.14224)
		(layer "In11.Cu")
		(net "P5E_CPU1_P1_RX_DN<9>")
	)
	(segment
		(start 106.590592 -276.860762)
		(end 106.62793 -276.839172)
		(width 0.1143)
		(layer "In11.Cu")
		(net "P5E_CPU1_P1_RX_DN<9>")
	)
	(segment
		(start 105.687876 -292.39337)
		(end 105.650538 -292.37178)
		(width 0.1143)
		(layer "In11.Cu")
		(net "P5E_CPU1_P1_RX_DN<9>")
	)
	(segment
		(start 91.7194 -373.467122)
		(end 91.719146 -373.467122)
		(width 0.14224)
		(layer "In11.Cu")
		(net "P5E_CPU1_P1_RX_DN<9>")
	)
	(segment
		(start 105.650538 -293.060628)
		(end 105.687876 -293.039038)
		(width 0.1143)
		(layer "In11.Cu")
		(net "P5E_CPU1_P1_RX_DN<9>")
	)
	(segment
		(start 105.719626 -284.31236)
		(end 105.687876 -284.293564)
		(width 0.1143)
		(layer "In11.Cu")
		(net "P5E_CPU1_P1_RX_DN<9>")
	)
	(segment
		(start 105.687876 -289.799014)
		(end 105.71988 -289.780218)
		(width 0.1143)
		(layer "In11.Cu")
		(net "P5E_CPU1_P1_RX_DN<9>")
	)
	(segment
		(start 106.164888 -277.645114)
		(end 106.190034 -277.630382)
		(width 0.1143)
		(layer "In11.Cu")
		(net "P5E_CPU1_P1_RX_DN<9>")
	)
	(segment
		(start 114.00028 -314.792614)
		(end 108.142786 -306.026312)
		(width 0.14224)
		(layer "In11.Cu")
		(net "P5E_CPU1_P1_RX_DN<9>")
	)
	(segment
		(start 105.68813 -286.55899)
		(end 105.71988 -286.540448)
		(width 0.1143)
		(layer "In11.Cu")
		(net "P5E_CPU1_P1_RX_DN<9>")
	)
	(segment
		(start 91.472258 -385.405376)
		(end 91.472766 -385.404868)
		(width 0.14224)
		(layer "In11.Cu")
		(net "P5E_CPU1_P1_RX_DN<9>")
	)
	(segment
		(start 105.209594 -279.274016)
		(end 105.211372 -279.272746)
		(width 0.1143)
		(layer "In11.Cu")
		(net "P5E_CPU1_P1_RX_DN<9>")
	)
	(segment
		(start 106.16311 -277.645876)
		(end 106.164888 -277.645114)
		(width 0.1143)
		(layer "In11.Cu")
		(net "P5E_CPU1_P1_RX_DN<9>")
	)
	(segment
		(start 108.142786 -306.026312)
		(end 104.97185 -298.370752)
		(width 0.14224)
		(layer "In11.Cu")
		(net "P5E_CPU1_P1_RX_DN<9>")
	)
	(segment
		(start 105.68813 -288.179002)
		(end 105.71988 -288.16046)
		(width 0.1143)
		(layer "In11.Cu")
		(net "P5E_CPU1_P1_RX_DN<9>")
	)
	(segment
		(start 123.141486 -327.462134)
		(end 120.937528 -323.24548)
		(width 0.14224)
		(layer "In11.Cu")
		(net "P5E_CPU1_P1_RX_DN<9>")
	)
	(segment
		(start 91.472766 -385.404868)
		(end 91.594432 -385.334764)
		(width 0.14224)
		(layer "In11.Cu")
		(net "P5E_CPU1_P1_RX_DN<9>")
	)
	(segment
		(start 105.687876 -284.293564)
		(end 105.650538 -284.271974)
		(width 0.1143)
		(layer "In11.Cu")
		(net "P5E_CPU1_P1_RX_DN<9>")
	)
	(segment
		(start 105.246678 -280.26106)
		(end 105.17759 -280.22042)
		(width 0.1143)
		(layer "In11.Cu")
		(net "P5E_CPU1_P1_RX_DN<9>")
	)
	(segment
		(start 91.476322 -380.583948)
		(end 91.615768 -380.449074)
		(width 0.14224)
		(layer "In11.Cu")
		(net "P5E_CPU1_P1_RX_DN<9>")
	)
	(arc
		(start 105.71988 -281.680412)
		(mid 105.875707 -281.376271)
		(end 105.719626 -281.072336)
		(width 0.1143)
		(layer "In11.Cu")
		(net "P5E_CPU1_P1_RX_DN<9>")
	)
	(arc
		(start 106.34599 -277.326344)
		(mid 106.410808 -277.063355)
		(end 106.590592 -276.860762)
		(width 0.1143)
		(layer "In11.Cu")
		(net "P5E_CPU1_P1_RX_DN<9>")
	)
	(arc
		(start 105.71988 -294.640254)
		(mid 105.875707 -294.336113)
		(end 105.719626 -294.032178)
		(width 0.1143)
		(layer "In11.Cu")
		(net "P5E_CPU1_P1_RX_DN<9>")
	)
	(arc
		(start 105.650538 -292.37178)
		(mid 105.405717 -291.906198)
		(end 105.650538 -291.440616)
		(width 0.1143)
		(layer "In11.Cu")
		(net "P5E_CPU1_P1_RX_DN<9>")
	)
	(arc
		(start 105.650538 -290.751768)
		(mid 105.405717 -290.286186)
		(end 105.650538 -289.820604)
		(width 0.1143)
		(layer "In11.Cu")
		(net "P5E_CPU1_P1_RX_DN<9>")
	)
	(arc
		(start 106.659934 -276.820376)
		(mid 106.756935 -276.717718)
		(end 106.809032 -276.586442)
		(width 0.1143)
		(layer "In11.Cu")
		(net "P5E_CPU1_P1_RX_DN<9>")
	)
	(arc
		(start 105.71988 -286.540448)
		(mid 105.875707 -286.236056)
		(end 105.719372 -285.931864)
		(width 0.1143)
		(layer "In11.Cu")
		(net "P5E_CPU1_P1_RX_DN<9>")
	)
	(arc
		(start 105.650538 -281.03195)
		(mid 105.470746 -280.829362)
		(end 105.405936 -280.566368)
		(width 0.1143)
		(layer "In11.Cu")
		(net "P5E_CPU1_P1_RX_DN<9>")
	)
	(arc
		(start 105.71988 -284.920436)
		(mid 105.875707 -284.616295)
		(end 105.719626 -284.31236)
		(width 0.1143)
		(layer "In11.Cu")
		(net "P5E_CPU1_P1_RX_DN<9>")
	)
	(arc
		(start 105.405936 -288.666174)
		(mid 105.470112 -288.404287)
		(end 105.648252 -288.201862)
		(width 0.1143)
		(layer "In11.Cu")
		(net "P5E_CPU1_P1_RX_DN<9>")
	)
	(arc
		(start 105.405936 -295.146222)
		(mid 105.470813 -294.883374)
		(end 105.650538 -294.680894)
		(width 0.1143)
		(layer "In11.Cu")
		(net "P5E_CPU1_P1_RX_DN<9>")
	)
	(arc
		(start 105.875836 -287.856422)
		(mid 105.833996 -287.684436)
		(end 105.717848 -287.55086)
		(width 0.1143)
		(layer "In11.Cu")
		(net "P5E_CPU1_P1_RX_DN<9>")
	)
	(arc
		(start 105.650538 -285.891986)
		(mid 105.405717 -285.426404)
		(end 105.650538 -284.960822)
		(width 0.1143)
		(layer "In11.Cu")
		(net "P5E_CPU1_P1_RX_DN<9>")
	)
	(arc
		(start 105.650538 -293.991792)
		(mid 105.405717 -293.52621)
		(end 105.650538 -293.060628)
		(width 0.1143)
		(layer "In11.Cu")
		(net "P5E_CPU1_P1_RX_DN<9>")
	)
	(arc
		(start 96.147382 -367.108486)
		(mid 96.222747 -367.017885)
		(end 96.309434 -366.938052)
		(width 0.14224)
		(layer "In11.Cu")
		(net "P5E_CPU1_P1_RX_DN<9>")
	)
	(arc
		(start 105.650538 -287.511744)
		(mid 105.470746 -287.309156)
		(end 105.405936 -287.046162)
		(width 0.1143)
		(layer "In11.Cu")
		(net "P5E_CPU1_P1_RX_DN<9>")
	)
	(arc
		(start 105.650538 -289.131756)
		(mid 105.470746 -288.929168)
		(end 105.405936 -288.666174)
		(width 0.1143)
		(layer "In11.Cu")
		(net "P5E_CPU1_P1_RX_DN<9>")
	)
	(arc
		(start 105.24998 -279.250394)
		(mid 105.364656 -279.117203)
		(end 105.405936 -278.946356)
		(width 0.1143)
		(layer "In11.Cu")
		(net "P5E_CPU1_P1_RX_DN<9>")
	)
	(arc
		(start 105.405936 -280.520648)
		(mid 105.373275 -280.387675)
		(end 105.282746 -280.284936)
		(width 0.1143)
		(layer "In11.Cu")
		(net "P5E_CPU1_P1_RX_DN<9>")
	)
	(arc
		(start 105.348532 -295.380918)
		(mid 105.390975 -295.317537)
		(end 105.405936 -295.242742)
		(width 0.1143)
		(layer "In11.Cu")
		(net "P5E_CPU1_P1_RX_DN<9>")
	)
	(arc
		(start 105.71988 -293.020242)
		(mid 105.875707 -292.716101)
		(end 105.719626 -292.412166)
		(width 0.1143)
		(layer "In11.Cu")
		(net "P5E_CPU1_P1_RX_DN<9>")
	)
	(arc
		(start 102.004114 -362.347002)
		(mid 102.018358 -362.336016)
		(end 102.03307 -362.325666)
		(width 0.14224)
		(layer "In11.Cu")
		(net "P5E_CPU1_P1_RX_DN<9>")
	)
	(arc
		(start 91.719146 -373.467122)
		(mid 91.760605 -373.223319)
		(end 91.873578 -373.003318)
		(width 0.14224)
		(layer "In11.Cu")
		(net "P5E_CPU1_P1_RX_DN<9>")
	)
	(arc
		(start 105.71988 -291.40023)
		(mid 105.875707 -291.096089)
		(end 105.719626 -290.792154)
		(width 0.1143)
		(layer "In11.Cu")
		(net "P5E_CPU1_P1_RX_DN<9>")
	)
	(arc
		(start 105.01757 -295.956736)
		(mid 105.062406 -295.730772)
		(end 105.19029 -295.53916)
		(width 0.1143)
		(layer "In11.Cu")
		(net "P5E_CPU1_P1_RX_DN<9>")
	)
	(arc
		(start 105.17759 -280.22042)
		(mid 104.947454 -279.756362)
		(end 105.17759 -279.292304)
		(width 0.1143)
		(layer "In11.Cu")
		(net "P5E_CPU1_P1_RX_DN<9>")
	)
	(arc
		(start 106.190034 -277.630382)
		(mid 106.30471 -277.497191)
		(end 106.34599 -277.326344)
		(width 0.1143)
		(layer "In11.Cu")
		(net "P5E_CPU1_P1_RX_DN<9>")
	)
	(arc
		(start 105.71988 -283.300424)
		(mid 105.875707 -282.996283)
		(end 105.719626 -282.692348)
		(width 0.1143)
		(layer "In11.Cu")
		(net "P5E_CPU1_P1_RX_DN<9>")
	)
	(arc
		(start 105.405936 -287.046162)
		(mid 105.470112 -286.784275)
		(end 105.648252 -286.58185)
		(width 0.1143)
		(layer "In11.Cu")
		(net "P5E_CPU1_P1_RX_DN<9>")
	)
	(arc
		(start 105.71988 -278.440388)
		(mid 105.834556 -278.307197)
		(end 105.875836 -278.13635)
		(width 0.1143)
		(layer "In11.Cu")
		(net "P5E_CPU1_P1_RX_DN<9>")
	)
	(arc
		(start 105.405936 -278.946356)
		(mid 105.470754 -278.683367)
		(end 105.650538 -278.480774)
		(width 0.1143)
		(layer "In11.Cu")
		(net "P5E_CPU1_P1_RX_DN<9>")
	)
	(arc
		(start 122.042682 -348.923356)
		(mid 122.764433 -348.2611)
		(end 123.252484 -347.411802)
		(width 0.14224)
		(layer "In11.Cu")
		(net "P5E_CPU1_P1_RX_DN<9>")
	)
	(arc
		(start 105.71988 -288.16046)
		(mid 105.834556 -288.027269)
		(end 105.875836 -287.856422)
		(width 0.1143)
		(layer "In11.Cu")
		(net "P5E_CPU1_P1_RX_DN<9>")
	)
	(arc
		(start 105.71988 -289.780218)
		(mid 105.875707 -289.476077)
		(end 105.719626 -289.172142)
		(width 0.1143)
		(layer "In11.Cu")
		(net "P5E_CPU1_P1_RX_DN<9>")
	)
	(arc
		(start 105.875836 -278.13635)
		(mid 105.940354 -277.873808)
		(end 106.119422 -277.671276)
		(width 0.1143)
		(layer "In11.Cu")
		(net "P5E_CPU1_P1_RX_DN<9>")
	)
	(arc
		(start 105.650538 -282.651962)
		(mid 105.405717 -282.18638)
		(end 105.650538 -281.720798)
		(width 0.1143)
		(layer "In11.Cu")
		(net "P5E_CPU1_P1_RX_DN<9>")
	)
	(arc
		(start 105.650538 -284.271974)
		(mid 105.405717 -283.806392)
		(end 105.650538 -283.34081)
		(width 0.1143)
		(layer "In11.Cu")
		(net "P5E_CPU1_P1_RX_DN<9>")
	)
	(segment
		(start 104.08793 -274.630388)
		(end 103.621078 -274.896326)
		(width 0.12954)
		(layer "F.Cu")
		(net "P5E_CPU1_P1_RX_DN<8>")
	)
	(segment
		(start 89.398348 -385.31038)
		(end 89.919048 -385.31038)
		(width 0.127)
		(layer "F.Cu")
		(net "P5E_CPU1_P1_RX_DN<8>")
	)
	(segment
		(start 104.779064 -294.031416)
		(end 104.709468 -293.991284)
		(width 0.1143)
		(layer "In11.Cu")
		(net "P5E_CPU1_P1_RX_DN<8>")
	)
	(segment
		(start 90.311986 -380.66853)
		(end 90.455496 -380.53772)
		(width 0.14224)
		(layer "In11.Cu")
		(net "P5E_CPU1_P1_RX_DN<8>")
	)
	(segment
		(start 104.308656 -275.401532)
		(end 104.23906 -275.360892)
		(width 0.1143)
		(layer "In11.Cu")
		(net "P5E_CPU1_P1_RX_DN<8>")
	)
	(segment
		(start 95.46971 -366.301528)
		(end 100.892102 -361.929426)
		(width 0.14224)
		(layer "In11.Cu")
		(net "P5E_CPU1_P1_RX_DN<8>")
	)
	(segment
		(start 104.745536 -293.040308)
		(end 104.748076 -293.038784)
		(width 0.1143)
		(layer "In11.Cu")
		(net "P5E_CPU1_P1_RX_DN<8>")
	)
	(segment
		(start 104.70896 -293.061644)
		(end 104.7369 -293.045388)
		(width 0.1143)
		(layer "In11.Cu")
		(net "P5E_CPU1_P1_RX_DN<8>")
	)
	(segment
		(start 104.743504 -287.531048)
		(end 104.717088 -287.515554)
		(width 0.1143)
		(layer "In11.Cu")
		(net "P5E_CPU1_P1_RX_DN<8>")
	)
	(segment
		(start 103.91902 -274.896326)
		(end 103.621078 -274.896326)
		(width 0.1143)
		(layer "In11.Cu")
		(net "P5E_CPU1_P1_RX_DN<8>")
	)
	(segment
		(start 104.745536 -292.3921)
		(end 104.70896 -292.370764)
		(width 0.1143)
		(layer "In11.Cu")
		(net "P5E_CPU1_P1_RX_DN<8>")
	)
	(segment
		(start 104.779826 -282.692094)
		(end 104.70896 -282.650946)
		(width 0.1143)
		(layer "In11.Cu")
		(net "P5E_CPU1_P1_RX_DN<8>")
	)
	(segment
		(start 90.292936 -381.094996)
		(end 90.311986 -380.66853)
		(width 0.14224)
		(layer "In11.Cu")
		(net "P5E_CPU1_P1_RX_DN<8>")
	)
	(segment
		(start 104.779826 -290.7919)
		(end 104.748838 -290.77412)
		(width 0.1143)
		(layer "In11.Cu")
		(net "P5E_CPU1_P1_RX_DN<8>")
	)
	(segment
		(start 104.7369 -293.045388)
		(end 104.737662 -293.04488)
		(width 0.1143)
		(layer "In11.Cu")
		(net "P5E_CPU1_P1_RX_DN<8>")
	)
	(segment
		(start 104.70896 -283.341826)
		(end 104.779826 -283.300678)
		(width 0.1143)
		(layer "In11.Cu")
		(net "P5E_CPU1_P1_RX_DN<8>")
	)
	(segment
		(start 104.779826 -284.312106)
		(end 104.70896 -284.270958)
		(width 0.1143)
		(layer "In11.Cu")
		(net "P5E_CPU1_P1_RX_DN<8>")
	)
	(segment
		(start 104.026716 -296.342816)
		(end 104.072436 -296.297096)
		(width 0.1143)
		(layer "In11.Cu")
		(net "P5E_CPU1_P1_RX_DN<8>")
	)
	(segment
		(start 90.362786 -379.541786)
		(end 90.506296 -379.410976)
		(width 0.14224)
		(layer "In11.Cu")
		(net "P5E_CPU1_P1_RX_DN<8>")
	)
	(segment
		(start 122.229626 -327.730358)
		(end 121.192544 -325.74611)
		(width 0.14224)
		(layer "In11.Cu")
		(net "P5E_CPU1_P1_RX_DN<8>")
	)
	(segment
		(start 104.737662 -291.424868)
		(end 104.74452 -291.420804)
		(width 0.1143)
		(layer "In11.Cu")
		(net "P5E_CPU1_P1_RX_DN<8>")
	)
	(segment
		(start 104.745536 -290.772088)
		(end 104.70896 -290.750752)
		(width 0.1143)
		(layer "In11.Cu")
		(net "P5E_CPU1_P1_RX_DN<8>")
	)
	(segment
		(start 90.455242 -380.53772)
		(end 90.455496 -380.535942)
		(width 0.14224)
		(layer "In11.Cu")
		(net "P5E_CPU1_P1_RX_DN<8>")
	)
	(segment
		(start 104.23906 -279.291796)
		(end 104.308656 -279.251156)
		(width 0.1143)
		(layer "In11.Cu")
		(net "P5E_CPU1_P1_RX_DN<8>")
	)
	(segment
		(start 104.780588 -294.032686)
		(end 104.780588 -294.032432)
		(width 0.1143)
		(layer "In11.Cu")
		(net "P5E_CPU1_P1_RX_DN<8>")
	)
	(segment
		(start 104.74706 -292.393116)
		(end 104.745536 -292.3921)
		(width 0.1143)
		(layer "In11.Cu")
		(net "P5E_CPU1_P1_RX_DN<8>")
	)
	(segment
		(start 104.779826 -292.411912)
		(end 104.748838 -292.394132)
		(width 0.1143)
		(layer "In11.Cu")
		(net "P5E_CPU1_P1_RX_DN<8>")
	)
	(segment
		(start 90.343736 -379.968252)
		(end 90.362786 -379.541786)
		(width 0.14224)
		(layer "In11.Cu")
		(net "P5E_CPU1_P1_RX_DN<8>")
	)
	(segment
		(start 123.215146 -333.215234)
		(end 123.214892 -333.215234)
		(width 0.14224)
		(layer "In11.Cu")
		(net "P5E_CPU1_P1_RX_DN<8>")
	)
	(segment
		(start 104.748838 -290.77412)
		(end 104.74706 -290.773104)
		(width 0.1143)
		(layer "In11.Cu")
		(net "P5E_CPU1_P1_RX_DN<8>")
	)
	(segment
		(start 104.779826 -277.832058)
		(end 104.70896 -277.79091)
		(width 0.1143)
		(layer "In11.Cu")
		(net "P5E_CPU1_P1_RX_DN<8>")
	)
	(segment
		(start 104.70896 -284.961838)
		(end 104.779826 -284.92069)
		(width 0.1143)
		(layer "In11.Cu")
		(net "P5E_CPU1_P1_RX_DN<8>")
	)
	(segment
		(start 104.70896 -276.861778)
		(end 104.779826 -276.82063)
		(width 0.1143)
		(layer "In11.Cu")
		(net "P5E_CPU1_P1_RX_DN<8>")
	)
	(segment
		(start 104.74706 -287.533334)
		(end 104.745536 -287.532318)
		(width 0.1143)
		(layer "In11.Cu")
		(net "P5E_CPU1_P1_RX_DN<8>")
	)
	(segment
		(start 104.70896 -289.82162)
		(end 104.7369 -289.805364)
		(width 0.1143)
		(layer "In11.Cu")
		(net "P5E_CPU1_P1_RX_DN<8>")
	)
	(segment
		(start 104.411018 -295.454578)
		(end 104.465882 -295.322498)
		(width 0.1143)
		(layer "In11.Cu")
		(net "P5E_CPU1_P1_RX_DN<8>")
	)
	(segment
		(start 104.748076 -289.79876)
		(end 104.748838 -289.798252)
		(width 0.1143)
		(layer "In11.Cu")
		(net "P5E_CPU1_P1_RX_DN<8>")
	)
	(segment
		(start 104.70896 -294.681656)
		(end 104.780588 -294.64)
		(width 0.1143)
		(layer "In11.Cu")
		(net "P5E_CPU1_P1_RX_DN<8>")
	)
	(segment
		(start 104.745028 -287.532064)
		(end 104.743504 -287.531048)
		(width 0.1143)
		(layer "In11.Cu")
		(net "P5E_CPU1_P1_RX_DN<8>")
	)
	(segment
		(start 104.74452 -293.040816)
		(end 104.745536 -293.040308)
		(width 0.1143)
		(layer "In11.Cu")
		(net "P5E_CPU1_P1_RX_DN<8>")
	)
	(segment
		(start 104.70896 -288.201608)
		(end 104.781604 -288.15919)
		(width 0.1143)
		(layer "In11.Cu")
		(net "P5E_CPU1_P1_RX_DN<8>")
	)
	(segment
		(start 90.077544 -384.84683)
		(end 90.08237 -384.234944)
		(width 0.14224)
		(layer "In11.Cu")
		(net "P5E_CPU1_P1_RX_DN<8>")
	)
	(segment
		(start 104.708198 -286.582358)
		(end 104.777794 -286.541718)
		(width 0.1143)
		(layer "In11.Cu")
		(net "P5E_CPU1_P1_RX_DN<8>")
	)
	(segment
		(start 104.275636 -295.590468)
		(end 104.275636 -295.590214)
		(width 0.1143)
		(layer "In11.Cu")
		(net "P5E_CPU1_P1_RX_DN<8>")
	)
	(segment
		(start 104.70896 -278.48179)
		(end 104.779826 -278.440642)
		(width 0.1143)
		(layer "In11.Cu")
		(net "P5E_CPU1_P1_RX_DN<8>")
	)
	(segment
		(start 104.026716 -298.525438)
		(end 104.026716 -296.371264)
		(width 0.14224)
		(layer "In11.Cu")
		(net "P5E_CPU1_P1_RX_DN<8>")
	)
	(segment
		(start 90.955622 -372.533672)
		(end 95.34398 -366.434116)
		(width 0.14224)
		(layer "In11.Cu")
		(net "P5E_CPU1_P1_RX_DN<8>")
	)
	(segment
		(start 104.74452 -289.800792)
		(end 104.745536 -289.800284)
		(width 0.1143)
		(layer "In11.Cu")
		(net "P5E_CPU1_P1_RX_DN<8>")
	)
	(segment
		(start 90.474546 -380.111508)
		(end 90.343736 -379.968252)
		(width 0.14224)
		(layer "In11.Cu")
		(net "P5E_CPU1_P1_RX_DN<8>")
	)
	(segment
		(start 107.316524 -306.468018)
		(end 104.026716 -298.525438)
		(width 0.14224)
		(layer "In11.Cu")
		(net "P5E_CPU1_P1_RX_DN<8>")
	)
	(segment
		(start 90.556588 -378.284232)
		(end 90.556842 -378.283978)
		(width 0.14224)
		(layer "In11.Cu")
		(net "P5E_CPU1_P1_RX_DN<8>")
	)
	(segment
		(start 90.506296 -379.410976)
		(end 90.506042 -379.410976)
		(width 0.14224)
		(layer "In11.Cu")
		(net "P5E_CPU1_P1_RX_DN<8>")
	)
	(segment
		(start 104.308656 -280.261568)
		(end 104.23906 -280.220928)
		(width 0.1143)
		(layer "In11.Cu")
		(net "P5E_CPU1_P1_RX_DN<8>")
	)
	(segment
		(start 90.272362 -385.405376)
		(end 90.27287 -385.404868)
		(width 0.14224)
		(layer "In11.Cu")
		(net "P5E_CPU1_P1_RX_DN<8>")
	)
	(segment
		(start 104.748838 -293.038276)
		(end 104.779826 -293.020496)
		(width 0.1143)
		(layer "In11.Cu")
		(net "P5E_CPU1_P1_RX_DN<8>")
	)
	(segment
		(start 104.748838 -292.394132)
		(end 104.74706 -292.393116)
		(width 0.1143)
		(layer "In11.Cu")
		(net "P5E_CPU1_P1_RX_DN<8>")
	)
	(segment
		(start 124.20092 -338.700618)
		(end 123.215146 -333.215234)
		(width 0.14224)
		(layer "In11.Cu")
		(net "P5E_CPU1_P1_RX_DN<8>")
	)
	(segment
		(start 90.413586 -378.415042)
		(end 90.557096 -378.284232)
		(width 0.14224)
		(layer "In11.Cu")
		(net "P5E_CPU1_P1_RX_DN<8>")
	)
	(segment
		(start 104.717088 -287.515554)
		(end 104.709722 -287.511236)
		(width 0.1143)
		(layer "In11.Cu")
		(net "P5E_CPU1_P1_RX_DN<8>")
	)
	(segment
		(start 104.779826 -289.171888)
		(end 104.748838 -289.154108)
		(width 0.1143)
		(layer "In11.Cu")
		(net "P5E_CPU1_P1_RX_DN<8>")
	)
	(segment
		(start 104.748076 -293.038784)
		(end 104.748838 -293.038276)
		(width 0.1143)
		(layer "In11.Cu")
		(net "P5E_CPU1_P1_RX_DN<8>")
	)
	(segment
		(start 104.779826 -276.212046)
		(end 104.70896 -276.170898)
		(width 0.1143)
		(layer "In11.Cu")
		(net "P5E_CPU1_P1_RX_DN<8>")
	)
	(segment
		(start 104.652826 -286.62249)
		(end 104.708198 -286.582358)
		(width 0.1143)
		(layer "In11.Cu")
		(net "P5E_CPU1_P1_RX_DN<8>")
	)
	(segment
		(start 104.737662 -293.04488)
		(end 104.74452 -293.040816)
		(width 0.1143)
		(layer "In11.Cu")
		(net "P5E_CPU1_P1_RX_DN<8>")
	)
	(segment
		(start 104.465882 -295.322498)
		(end 104.465882 -295.145968)
		(width 0.1143)
		(layer "In11.Cu")
		(net "P5E_CPU1_P1_RX_DN<8>")
	)
	(segment
		(start 104.7369 -291.425376)
		(end 104.737662 -291.424868)
		(width 0.1143)
		(layer "In11.Cu")
		(net "P5E_CPU1_P1_RX_DN<8>")
	)
	(segment
		(start 104.74706 -289.153092)
		(end 104.745536 -289.152076)
		(width 0.1143)
		(layer "In11.Cu")
		(net "P5E_CPU1_P1_RX_DN<8>")
	)
	(segment
		(start 104.465628 -287.046416)
		(end 104.465628 -286.992314)
		(width 0.1143)
		(layer "In11.Cu")
		(net "P5E_CPU1_P1_RX_DN<8>")
	)
	(segment
		(start 104.001824 -274.97913)
		(end 103.91902 -274.896326)
		(width 0.1143)
		(layer "In11.Cu")
		(net "P5E_CPU1_P1_RX_DN<8>")
	)
	(segment
		(start 104.072436 -296.297096)
		(end 104.072436 -296.081196)
		(width 0.1143)
		(layer "In11.Cu")
		(net "P5E_CPU1_P1_RX_DN<8>")
	)
	(segment
		(start 90.386408 -383.93116)
		(end 90.386408 -382.071626)
		(width 0.14224)
		(layer "In11.Cu")
		(net "P5E_CPU1_P1_RX_DN<8>")
	)
	(segment
		(start 90.79484 -372.995444)
		(end 90.79484 -372.99519)
		(width 0.14224)
		(layer "In11.Cu")
		(net "P5E_CPU1_P1_RX_DN<8>")
	)
	(segment
		(start 104.748838 -291.418264)
		(end 104.779826 -291.400484)
		(width 0.1143)
		(layer "In11.Cu")
		(net "P5E_CPU1_P1_RX_DN<8>")
	)
	(segment
		(start 104.74706 -290.773104)
		(end 104.745536 -290.772088)
		(width 0.1143)
		(layer "In11.Cu")
		(net "P5E_CPU1_P1_RX_DN<8>")
	)
	(segment
		(start 90.79484 -372.99519)
		(end 90.794586 -372.99519)
		(width 0.14224)
		(layer "In11.Cu")
		(net "P5E_CPU1_P1_RX_DN<8>")
	)
	(segment
		(start 90.394536 -378.841508)
		(end 90.413586 -378.415042)
		(width 0.14224)
		(layer "In11.Cu")
		(net "P5E_CPU1_P1_RX_DN<8>")
	)
	(segment
		(start 90.394536 -385.334764)
		(end 90.394536 -385.163822)
		(width 0.14224)
		(layer "In11.Cu")
		(net "P5E_CPU1_P1_RX_DN<8>")
	)
	(segment
		(start 89.919048 -385.31038)
		(end 90.272362 -385.405376)
		(width 0.14224)
		(layer "In11.Cu")
		(net "P5E_CPU1_P1_RX_DN<8>")
	)
	(segment
		(start 104.780588 -294.64)
		(end 104.780588 -294.639746)
		(width 0.1143)
		(layer "In11.Cu")
		(net "P5E_CPU1_P1_RX_DN<8>")
	)
	(segment
		(start 104.275636 -295.590214)
		(end 104.411018 -295.454578)
		(width 0.1143)
		(layer "In11.Cu")
		(net "P5E_CPU1_P1_RX_DN<8>")
	)
	(segment
		(start 90.08237 -384.234944)
		(end 90.386408 -383.93116)
		(width 0.14224)
		(layer "In11.Cu")
		(net "P5E_CPU1_P1_RX_DN<8>")
	)
	(segment
		(start 104.749854 -287.534858)
		(end 104.74706 -287.533334)
		(width 0.1143)
		(layer "In11.Cu")
		(net "P5E_CPU1_P1_RX_DN<8>")
	)
	(segment
		(start 104.748076 -291.418772)
		(end 104.748838 -291.418264)
		(width 0.1143)
		(layer "In11.Cu")
		(net "P5E_CPU1_P1_RX_DN<8>")
	)
	(segment
		(start 90.525092 -378.984764)
		(end 90.525346 -378.984764)
		(width 0.14224)
		(layer "In11.Cu")
		(net "P5E_CPU1_P1_RX_DN<8>")
	)
	(segment
		(start 104.748838 -289.154108)
		(end 104.74706 -289.153092)
		(width 0.1143)
		(layer "In11.Cu")
		(net "P5E_CPU1_P1_RX_DN<8>")
	)
	(segment
		(start 120.155462 -323.76237)
		(end 113.251742 -315.350398)
		(width 0.14224)
		(layer "In11.Cu")
		(net "P5E_CPU1_P1_RX_DN<8>")
	)
	(segment
		(start 90.525346 -378.984764)
		(end 90.394536 -378.841508)
		(width 0.14224)
		(layer "In11.Cu")
		(net "P5E_CPU1_P1_RX_DN<8>")
	)
	(segment
		(start 113.251742 -315.350398)
		(end 107.316524 -306.468018)
		(width 0.14224)
		(layer "In11.Cu")
		(net "P5E_CPU1_P1_RX_DN<8>")
	)
	(segment
		(start 124.20092 -342.022176)
		(end 124.20092 -338.700618)
		(width 0.14224)
		(layer "In11.Cu")
		(net "P5E_CPU1_P1_RX_DN<8>")
	)
	(segment
		(start 104.745536 -289.152076)
		(end 104.70896 -289.13074)
		(width 0.1143)
		(layer "In11.Cu")
		(net "P5E_CPU1_P1_RX_DN<8>")
	)
	(segment
		(start 90.506042 -379.410976)
		(end 90.525092 -378.984764)
		(width 0.14224)
		(layer "In11.Cu")
		(net "P5E_CPU1_P1_RX_DN<8>")
	)
	(segment
		(start 90.394536 -385.163822)
		(end 90.077544 -384.84683)
		(width 0.14224)
		(layer "In11.Cu")
		(net "P5E_CPU1_P1_RX_DN<8>")
	)
	(segment
		(start 90.455496 -380.535942)
		(end 90.474546 -380.111508)
		(width 0.14224)
		(layer "In11.Cu")
		(net "P5E_CPU1_P1_RX_DN<8>")
	)
	(segment
		(start 104.745536 -291.420296)
		(end 104.748076 -291.418772)
		(width 0.1143)
		(layer "In11.Cu")
		(net "P5E_CPU1_P1_RX_DN<8>")
	)
	(segment
		(start 104.781604 -286.538924)
		(end 104.781604 -286.539178)
		(width 0.1143)
		(layer "In11.Cu")
		(net "P5E_CPU1_P1_RX_DN<8>")
	)
	(segment
		(start 101.58476 -361.420156)
		(end 120.576086 -348.730316)
		(width 0.14224)
		(layer "In11.Cu")
		(net "P5E_CPU1_P1_RX_DN<8>")
	)
	(segment
		(start 90.386408 -382.071626)
		(end 90.423746 -381.238252)
		(width 0.14224)
		(layer "In11.Cu")
		(net "P5E_CPU1_P1_RX_DN<8>")
	)
	(segment
		(start 104.779826 -281.072082)
		(end 104.70896 -281.030934)
		(width 0.1143)
		(layer "In11.Cu")
		(net "P5E_CPU1_P1_RX_DN<8>")
	)
	(segment
		(start 90.557096 -378.284232)
		(end 90.556588 -378.284232)
		(width 0.14224)
		(layer "In11.Cu")
		(net "P5E_CPU1_P1_RX_DN<8>")
	)
	(segment
		(start 104.56545 -294.825674)
		(end 104.565196 -294.825674)
		(width 0.1143)
		(layer "In11.Cu")
		(net "P5E_CPU1_P1_RX_DN<8>")
	)
	(segment
		(start 121.192544 -325.746364)
		(end 120.155462 -323.76237)
		(width 0.14224)
		(layer "In11.Cu")
		(net "P5E_CPU1_P1_RX_DN<8>")
	)
	(segment
		(start 104.779826 -285.932118)
		(end 104.70896 -285.89097)
		(width 0.1143)
		(layer "In11.Cu")
		(net "P5E_CPU1_P1_RX_DN<8>")
	)
	(segment
		(start 104.745536 -287.532318)
		(end 104.745028 -287.532064)
		(width 0.1143)
		(layer "In11.Cu")
		(net "P5E_CPU1_P1_RX_DN<8>")
	)
	(segment
		(start 124.200666 -342.02243)
		(end 124.20092 -342.022176)
		(width 0.14224)
		(layer "In11.Cu")
		(net "P5E_CPU1_P1_RX_DN<8>")
	)
	(segment
		(start 104.74452 -291.420804)
		(end 104.745536 -291.420296)
		(width 0.1143)
		(layer "In11.Cu")
		(net "P5E_CPU1_P1_RX_DN<8>")
	)
	(segment
		(start 104.026716 -296.371264)
		(end 104.026716 -296.342816)
		(width 0.1143)
		(layer "In11.Cu")
		(net "P5E_CPU1_P1_RX_DN<8>")
	)
	(segment
		(start 104.7369 -289.805364)
		(end 104.737662 -289.804856)
		(width 0.1143)
		(layer "In11.Cu")
		(net "P5E_CPU1_P1_RX_DN<8>")
	)
	(segment
		(start 104.70896 -291.441632)
		(end 104.7369 -291.425376)
		(width 0.1143)
		(layer "In11.Cu")
		(net "P5E_CPU1_P1_RX_DN<8>")
	)
	(segment
		(start 90.27287 -385.404868)
		(end 90.394536 -385.334764)
		(width 0.14224)
		(layer "In11.Cu")
		(net "P5E_CPU1_P1_RX_DN<8>")
	)
	(segment
		(start 123.214892 -333.215234)
		(end 122.229626 -327.730358)
		(width 0.14224)
		(layer "In11.Cu")
		(net "P5E_CPU1_P1_RX_DN<8>")
	)
	(segment
		(start 121.192544 -325.74611)
		(end 121.192544 -325.746364)
		(width 0.14224)
		(layer "In11.Cu")
		(net "P5E_CPU1_P1_RX_DN<8>")
	)
	(segment
		(start 104.737662 -289.804856)
		(end 104.74452 -289.800792)
		(width 0.1143)
		(layer "In11.Cu")
		(net "P5E_CPU1_P1_RX_DN<8>")
	)
	(segment
		(start 104.70896 -281.721814)
		(end 104.779826 -281.680666)
		(width 0.1143)
		(layer "In11.Cu")
		(net "P5E_CPU1_P1_RX_DN<8>")
	)
	(segment
		(start 90.455496 -380.53772)
		(end 90.455242 -380.53772)
		(width 0.14224)
		(layer "In11.Cu")
		(net "P5E_CPU1_P1_RX_DN<8>")
	)
	(segment
		(start 90.556842 -378.283978)
		(end 90.79484 -372.995444)
		(width 0.14224)
		(layer "In11.Cu")
		(net "P5E_CPU1_P1_RX_DN<8>")
	)
	(segment
		(start 104.748838 -289.798252)
		(end 104.779826 -289.780472)
		(width 0.1143)
		(layer "In11.Cu")
		(net "P5E_CPU1_P1_RX_DN<8>")
	)
	(segment
		(start 122.284744 -346.648278)
		(end 124.200666 -342.02243)
		(width 0.14224)
		(layer "In11.Cu")
		(net "P5E_CPU1_P1_RX_DN<8>")
	)
	(segment
		(start 104.745536 -289.800284)
		(end 104.748076 -289.79876)
		(width 0.1143)
		(layer "In11.Cu")
		(net "P5E_CPU1_P1_RX_DN<8>")
	)
	(segment
		(start 104.780588 -294.032432)
		(end 104.779064 -294.031416)
		(width 0.1143)
		(layer "In11.Cu")
		(net "P5E_CPU1_P1_RX_DN<8>")
	)
	(segment
		(start 90.423746 -381.238252)
		(end 90.292936 -381.094996)
		(width 0.14224)
		(layer "In11.Cu")
		(net "P5E_CPU1_P1_RX_DN<8>")
	)
	(arc
		(start 104.465882 -295.145968)
		(mid 104.49133 -294.97825)
		(end 104.56545 -294.825674)
		(width 0.1143)
		(layer "In11.Cu")
		(net "P5E_CPU1_P1_RX_DN<8>")
	)
	(arc
		(start 104.780588 -294.639746)
		(mid 104.935477 -294.336216)
		(end 104.780588 -294.032686)
		(width 0.1143)
		(layer "In11.Cu")
		(net "P5E_CPU1_P1_RX_DN<8>")
	)
	(arc
		(start 95.34398 -366.434116)
		(mid 95.402397 -366.363605)
		(end 95.46971 -366.301528)
		(width 0.14224)
		(layer "In11.Cu")
		(net "P5E_CPU1_P1_RX_DN<8>")
	)
	(arc
		(start 104.005634 -275.00199)
		(mid 104.003611 -274.99058)
		(end 104.001824 -274.97913)
		(width 0.1143)
		(layer "In11.Cu")
		(net "P5E_CPU1_P1_RX_DN<8>")
	)
	(arc
		(start 104.709722 -287.511236)
		(mid 104.530418 -287.308883)
		(end 104.465628 -287.046416)
		(width 0.1143)
		(layer "In11.Cu")
		(net "P5E_CPU1_P1_RX_DN<8>")
	)
	(arc
		(start 104.23906 -280.220928)
		(mid 103.995733 -279.756362)
		(end 104.23906 -279.291796)
		(width 0.1143)
		(layer "In11.Cu")
		(net "P5E_CPU1_P1_RX_DN<8>")
	)
	(arc
		(start 100.892102 -361.929426)
		(mid 101.232734 -361.667042)
		(end 101.58476 -361.420156)
		(width 0.14224)
		(layer "In11.Cu")
		(net "P5E_CPU1_P1_RX_DN<8>")
	)
	(arc
		(start 104.70896 -281.030934)
		(mid 104.530147 -280.828584)
		(end 104.465628 -280.566368)
		(width 0.1143)
		(layer "In11.Cu")
		(net "P5E_CPU1_P1_RX_DN<8>")
	)
	(arc
		(start 104.465628 -286.992314)
		(mid 104.515034 -286.785029)
		(end 104.652826 -286.62249)
		(width 0.1143)
		(layer "In11.Cu")
		(net "P5E_CPU1_P1_RX_DN<8>")
	)
	(arc
		(start 104.779826 -291.400484)
		(mid 104.931415 -291.096192)
		(end 104.779826 -290.7919)
		(width 0.1143)
		(layer "In11.Cu")
		(net "P5E_CPU1_P1_RX_DN<8>")
	)
	(arc
		(start 104.70896 -289.13074)
		(mid 104.465633 -288.666174)
		(end 104.70896 -288.201608)
		(width 0.1143)
		(layer "In11.Cu")
		(net "P5E_CPU1_P1_RX_DN<8>")
	)
	(arc
		(start 104.779826 -278.440642)
		(mid 104.931415 -278.13635)
		(end 104.779826 -277.832058)
		(width 0.1143)
		(layer "In11.Cu")
		(net "P5E_CPU1_P1_RX_DN<8>")
	)
	(arc
		(start 120.576086 -348.730316)
		(mid 121.584833 -347.816022)
		(end 122.284744 -346.648278)
		(width 0.14224)
		(layer "In11.Cu")
		(net "P5E_CPU1_P1_RX_DN<8>")
	)
	(arc
		(start 104.70896 -290.750752)
		(mid 104.465633 -290.286186)
		(end 104.70896 -289.82162)
		(width 0.1143)
		(layer "In11.Cu")
		(net "P5E_CPU1_P1_RX_DN<8>")
	)
	(arc
		(start 104.781604 -286.539178)
		(mid 104.895011 -286.406289)
		(end 104.935782 -286.23641)
		(width 0.1143)
		(layer "In11.Cu")
		(net "P5E_CPU1_P1_RX_DN<8>")
	)
	(arc
		(start 104.465628 -280.566368)
		(mid 104.424079 -280.394946)
		(end 104.308656 -280.261568)
		(width 0.1143)
		(layer "In11.Cu")
		(net "P5E_CPU1_P1_RX_DN<8>")
	)
	(arc
		(start 104.777794 -286.541718)
		(mid 104.779703 -286.540327)
		(end 104.781604 -286.538924)
		(width 0.1143)
		(layer "In11.Cu")
		(net "P5E_CPU1_P1_RX_DN<8>")
	)
	(arc
		(start 104.70896 -292.370764)
		(mid 104.465633 -291.906198)
		(end 104.70896 -291.441632)
		(width 0.1143)
		(layer "In11.Cu")
		(net "P5E_CPU1_P1_RX_DN<8>")
	)
	(arc
		(start 104.70896 -285.89097)
		(mid 104.465633 -285.426404)
		(end 104.70896 -284.961838)
		(width 0.1143)
		(layer "In11.Cu")
		(net "P5E_CPU1_P1_RX_DN<8>")
	)
	(arc
		(start 104.779826 -283.300678)
		(mid 104.931415 -282.996386)
		(end 104.779826 -282.692094)
		(width 0.1143)
		(layer "In11.Cu")
		(net "P5E_CPU1_P1_RX_DN<8>")
	)
	(arc
		(start 104.935782 -287.856422)
		(mid 104.885959 -287.670692)
		(end 104.749854 -287.534858)
		(width 0.1143)
		(layer "In11.Cu")
		(net "P5E_CPU1_P1_RX_DN<8>")
	)
	(arc
		(start 104.565196 -294.825674)
		(mid 104.630548 -294.747147)
		(end 104.70896 -294.681656)
		(width 0.1143)
		(layer "In11.Cu")
		(net "P5E_CPU1_P1_RX_DN<8>")
	)
	(arc
		(start 104.70896 -284.270958)
		(mid 104.465633 -283.806392)
		(end 104.70896 -283.341826)
		(width 0.1143)
		(layer "In11.Cu")
		(net "P5E_CPU1_P1_RX_DN<8>")
	)
	(arc
		(start 104.70896 -277.79091)
		(mid 104.465633 -277.326344)
		(end 104.70896 -276.861778)
		(width 0.1143)
		(layer "In11.Cu")
		(net "P5E_CPU1_P1_RX_DN<8>")
	)
	(arc
		(start 104.465628 -275.706332)
		(mid 104.424079 -275.53491)
		(end 104.308656 -275.401532)
		(width 0.1143)
		(layer "In11.Cu")
		(net "P5E_CPU1_P1_RX_DN<8>")
	)
	(arc
		(start 104.781604 -288.15919)
		(mid 104.895011 -288.026301)
		(end 104.935782 -287.856422)
		(width 0.1143)
		(layer "In11.Cu")
		(net "P5E_CPU1_P1_RX_DN<8>")
	)
	(arc
		(start 104.779826 -293.020496)
		(mid 104.931415 -292.716204)
		(end 104.779826 -292.411912)
		(width 0.1143)
		(layer "In11.Cu")
		(net "P5E_CPU1_P1_RX_DN<8>")
	)
	(arc
		(start 104.70896 -282.650946)
		(mid 104.465633 -282.18638)
		(end 104.70896 -281.721814)
		(width 0.1143)
		(layer "In11.Cu")
		(net "P5E_CPU1_P1_RX_DN<8>")
	)
	(arc
		(start 104.779826 -276.82063)
		(mid 104.931415 -276.516338)
		(end 104.779826 -276.212046)
		(width 0.1143)
		(layer "In11.Cu")
		(net "P5E_CPU1_P1_RX_DN<8>")
	)
	(arc
		(start 104.709468 -293.991284)
		(mid 104.465614 -293.526563)
		(end 104.70896 -293.061644)
		(width 0.1143)
		(layer "In11.Cu")
		(net "P5E_CPU1_P1_RX_DN<8>")
	)
	(arc
		(start 104.072436 -296.081196)
		(mid 104.125243 -295.815627)
		(end 104.275636 -295.590468)
		(width 0.1143)
		(layer "In11.Cu")
		(net "P5E_CPU1_P1_RX_DN<8>")
	)
	(arc
		(start 104.308656 -279.251156)
		(mid 104.424083 -279.11778)
		(end 104.465628 -278.946356)
		(width 0.1143)
		(layer "In11.Cu")
		(net "P5E_CPU1_P1_RX_DN<8>")
	)
	(arc
		(start 104.935782 -286.23641)
		(mid 104.891711 -286.066874)
		(end 104.779826 -285.932118)
		(width 0.1143)
		(layer "In11.Cu")
		(net "P5E_CPU1_P1_RX_DN<8>")
	)
	(arc
		(start 104.779826 -281.680666)
		(mid 104.931415 -281.376374)
		(end 104.779826 -281.072082)
		(width 0.1143)
		(layer "In11.Cu")
		(net "P5E_CPU1_P1_RX_DN<8>")
	)
	(arc
		(start 104.23906 -275.360892)
		(mid 104.087073 -275.204384)
		(end 104.005634 -275.00199)
		(width 0.1143)
		(layer "In11.Cu")
		(net "P5E_CPU1_P1_RX_DN<8>")
	)
	(arc
		(start 104.779826 -284.92069)
		(mid 104.930211 -284.616398)
		(end 104.779826 -284.312106)
		(width 0.1143)
		(layer "In11.Cu")
		(net "P5E_CPU1_P1_RX_DN<8>")
	)
	(arc
		(start 104.465628 -278.946356)
		(mid 104.530143 -278.684137)
		(end 104.70896 -278.48179)
		(width 0.1143)
		(layer "In11.Cu")
		(net "P5E_CPU1_P1_RX_DN<8>")
	)
	(arc
		(start 104.70896 -276.170898)
		(mid 104.530147 -275.968548)
		(end 104.465628 -275.706332)
		(width 0.1143)
		(layer "In11.Cu")
		(net "P5E_CPU1_P1_RX_DN<8>")
	)
	(arc
		(start 104.779826 -289.780472)
		(mid 104.928923 -289.47618)
		(end 104.779826 -289.171888)
		(width 0.1143)
		(layer "In11.Cu")
		(net "P5E_CPU1_P1_RX_DN<8>")
	)
	(arc
		(start 90.794586 -372.99519)
		(mid 90.84146 -372.752687)
		(end 90.955622 -372.533672)
		(width 0.14224)
		(layer "In11.Cu")
		(net "P5E_CPU1_P1_RX_DN<8>")
	)
	(segment
		(start 88.198452 -385.31038)
		(end 88.719152 -385.31038)
		(width 0.127)
		(layer "F.Cu")
		(net "P5E_CPU1_P1_RX_DN<7>")
	)
	(segment
		(start 104.08793 -277.870412)
		(end 103.621078 -278.13635)
		(width 0.12954)
		(layer "F.Cu")
		(net "P5E_CPU1_P1_RX_DN<7>")
	)
	(segment
		(start 103.810054 -283.317696)
		(end 103.839772 -283.300678)
		(width 0.1143)
		(layer "In11.Cu")
		(net "P5E_CPU1_P1_RX_DN<7>")
	)
	(segment
		(start 103.808022 -292.393624)
		(end 103.7717 -292.372542)
		(width 0.1143)
		(layer "In11.Cu")
		(net "P5E_CPU1_P1_RX_DN<7>")
	)
	(segment
		(start 103.839772 -289.171888)
		(end 103.786686 -289.141154)
		(width 0.1143)
		(layer "In11.Cu")
		(net "P5E_CPU1_P1_RX_DN<7>")
	)
	(segment
		(start 88.503252 -370.1161)
		(end 90.310462 -367.528602)
		(width 0.14224)
		(layer "In11.Cu")
		(net "P5E_CPU1_P1_RX_DN<7>")
	)
	(segment
		(start 103.808022 -285.91383)
		(end 103.7717 -285.892748)
		(width 0.1143)
		(layer "In11.Cu")
		(net "P5E_CPU1_P1_RX_DN<7>")
	)
	(segment
		(start 103.810054 -281.055064)
		(end 103.808784 -281.054302)
		(width 0.1143)
		(layer "In11.Cu")
		(net "P5E_CPU1_P1_RX_DN<7>")
	)
	(segment
		(start 106.491024 -306.911248)
		(end 103.020114 -298.531788)
		(width 0.14224)
		(layer "In11.Cu")
		(net "P5E_CPU1_P1_RX_DN<7>")
	)
	(segment
		(start 103.17988 -295.671494)
		(end 103.467662 -295.383966)
		(width 0.1143)
		(layer "In11.Cu")
		(net "P5E_CPU1_P1_RX_DN<7>")
	)
	(segment
		(start 88.877394 -384.84683)
		(end 88.88222 -384.234944)
		(width 0.14224)
		(layer "In11.Cu")
		(net "P5E_CPU1_P1_RX_DN<7>")
	)
	(segment
		(start 88.101424 -370.691156)
		(end 88.067642 -370.500148)
		(width 0.14224)
		(layer "In11.Cu")
		(net "P5E_CPU1_P1_RX_DN<7>")
	)
	(segment
		(start 122.221752 -333.379572)
		(end 122.221498 -333.379572)
		(width 0.14224)
		(layer "In11.Cu")
		(net "P5E_CPU1_P1_RX_DN<7>")
	)
	(segment
		(start 103.808784 -292.394132)
		(end 103.808022 -292.393624)
		(width 0.1143)
		(layer "In11.Cu")
		(net "P5E_CPU1_P1_RX_DN<7>")
	)
	(segment
		(start 103.808784 -284.93847)
		(end 103.810054 -284.937708)
		(width 0.1143)
		(layer "In11.Cu")
		(net "P5E_CPU1_P1_RX_DN<7>")
	)
	(segment
		(start 103.808784 -282.674314)
		(end 103.808022 -282.673806)
		(width 0.1143)
		(layer "In11.Cu")
		(net "P5E_CPU1_P1_RX_DN<7>")
	)
	(segment
		(start 103.839772 -282.692094)
		(end 103.814118 -282.677362)
		(width 0.1143)
		(layer "In11.Cu")
		(net "P5E_CPU1_P1_RX_DN<7>")
	)
	(segment
		(start 103.808784 -293.038276)
		(end 103.810054 -293.037514)
		(width 0.1143)
		(layer "In11.Cu")
		(net "P5E_CPU1_P1_RX_DN<7>")
	)
	(segment
		(start 90.310462 -367.528602)
		(end 91.006168 -366.969548)
		(width 0.14224)
		(layer "In11.Cu")
		(net "P5E_CPU1_P1_RX_DN<7>")
	)
	(segment
		(start 103.808784 -285.914338)
		(end 103.808022 -285.91383)
		(width 0.1143)
		(layer "In11.Cu")
		(net "P5E_CPU1_P1_RX_DN<7>")
	)
	(segment
		(start 103.808784 -284.294326)
		(end 103.808022 -284.293818)
		(width 0.1143)
		(layer "In11.Cu")
		(net "P5E_CPU1_P1_RX_DN<7>")
	)
	(segment
		(start 88.312244 -370.150136)
		(end 88.503252 -370.1161)
		(width 0.14224)
		(layer "In11.Cu")
		(net "P5E_CPU1_P1_RX_DN<7>")
	)
	(segment
		(start 103.020114 -296.41927)
		(end 103.020114 -296.390822)
		(width 0.1143)
		(layer "In11.Cu")
		(net "P5E_CPU1_P1_RX_DN<7>")
	)
	(segment
		(start 103.299006 -279.291796)
		(end 103.350822 -279.26157)
		(width 0.1143)
		(layer "In11.Cu")
		(net "P5E_CPU1_P1_RX_DN<7>")
	)
	(segment
		(start 103.525828 -295.243758)
		(end 103.525828 -295.14546)
		(width 0.1143)
		(layer "In11.Cu")
		(net "P5E_CPU1_P1_RX_DN<7>")
	)
	(segment
		(start 103.065834 -296.345102)
		(end 103.065834 -295.947338)
		(width 0.1143)
		(layer "In11.Cu")
		(net "P5E_CPU1_P1_RX_DN<7>")
	)
	(segment
		(start 122.221498 -333.379572)
		(end 121.222008 -327.81621)
		(width 0.14224)
		(layer "In11.Cu")
		(net "P5E_CPU1_P1_RX_DN<7>")
	)
	(segment
		(start 103.020114 -298.531788)
		(end 103.020114 -296.41927)
		(width 0.14224)
		(layer "In11.Cu")
		(net "P5E_CPU1_P1_RX_DN<7>")
	)
	(segment
		(start 103.7717 -284.96006)
		(end 103.808022 -284.938978)
		(width 0.1143)
		(layer "In11.Cu")
		(net "P5E_CPU1_P1_RX_DN<7>")
	)
	(segment
		(start 103.808022 -294.658796)
		(end 103.839772 -294.640508)
		(width 0.1143)
		(layer "In11.Cu")
		(net "P5E_CPU1_P1_RX_DN<7>")
	)
	(segment
		(start 103.808784 -290.77412)
		(end 103.808022 -290.773612)
		(width 0.1143)
		(layer "In11.Cu")
		(net "P5E_CPU1_P1_RX_DN<7>")
	)
	(segment
		(start 89.07272 -385.404868)
		(end 89.194386 -385.334764)
		(width 0.14224)
		(layer "In11.Cu")
		(net "P5E_CPU1_P1_RX_DN<7>")
	)
	(segment
		(start 103.814118 -294.017192)
		(end 103.812594 -294.016176)
		(width 0.1143)
		(layer "In11.Cu")
		(net "P5E_CPU1_P1_RX_DN<7>")
	)
	(segment
		(start 103.808784 -278.458422)
		(end 103.810054 -278.45766)
		(width 0.1143)
		(layer "In11.Cu")
		(net "P5E_CPU1_P1_RX_DN<7>")
	)
	(segment
		(start 88.719152 -385.31038)
		(end 89.072212 -385.405376)
		(width 0.14224)
		(layer "In11.Cu")
		(net "P5E_CPU1_P1_RX_DN<7>")
	)
	(segment
		(start 91.006168 -366.969548)
		(end 95.60052 -364.248192)
		(width 0.14224)
		(layer "In11.Cu")
		(net "P5E_CPU1_P1_RX_DN<7>")
	)
	(segment
		(start 103.812594 -285.91637)
		(end 103.810054 -285.9151)
		(width 0.1143)
		(layer "In11.Cu")
		(net "P5E_CPU1_P1_RX_DN<7>")
	)
	(segment
		(start 88.067642 -370.500148)
		(end 88.312244 -370.150136)
		(width 0.14224)
		(layer "In11.Cu")
		(net "P5E_CPU1_P1_RX_DN<7>")
	)
	(segment
		(start 112.500156 -315.904626)
		(end 106.491024 -306.911248)
		(width 0.14224)
		(layer "In11.Cu")
		(net "P5E_CPU1_P1_RX_DN<7>")
	)
	(segment
		(start 103.810054 -290.774882)
		(end 103.808784 -290.77412)
		(width 0.1143)
		(layer "In11.Cu")
		(net "P5E_CPU1_P1_RX_DN<7>")
	)
	(segment
		(start 103.839772 -290.7919)
		(end 103.814118 -290.777168)
		(width 0.1143)
		(layer "In11.Cu")
		(net "P5E_CPU1_P1_RX_DN<7>")
	)
	(segment
		(start 103.808022 -281.698954)
		(end 103.808784 -281.698446)
		(width 0.1143)
		(layer "In11.Cu")
		(net "P5E_CPU1_P1_RX_DN<7>")
	)
	(segment
		(start 89.194386 -385.163822)
		(end 88.877394 -384.84683)
		(width 0.14224)
		(layer "In11.Cu")
		(net "P5E_CPU1_P1_RX_DN<7>")
	)
	(segment
		(start 103.533956 -280.60269)
		(end 103.533956 -280.572972)
		(width 0.1143)
		(layer "In11.Cu")
		(net "P5E_CPU1_P1_RX_DN<7>")
	)
	(segment
		(start 103.814118 -290.777168)
		(end 103.812594 -290.776152)
		(width 0.1143)
		(layer "In11.Cu")
		(net "P5E_CPU1_P1_RX_DN<7>")
	)
	(segment
		(start 103.839772 -281.072082)
		(end 103.814118 -281.05735)
		(width 0.1143)
		(layer "In11.Cu")
		(net "P5E_CPU1_P1_RX_DN<7>")
	)
	(segment
		(start 103.810054 -294.014906)
		(end 103.808784 -294.014144)
		(width 0.1143)
		(layer "In11.Cu")
		(net "P5E_CPU1_P1_RX_DN<7>")
	)
	(segment
		(start 121.334276 -346.365068)
		(end 123.22175 -341.808562)
		(width 0.14224)
		(layer "In11.Cu")
		(net "P5E_CPU1_P1_RX_DN<7>")
	)
	(segment
		(start 103.808022 -284.938978)
		(end 103.808784 -284.93847)
		(width 0.1143)
		(layer "In11.Cu")
		(net "P5E_CPU1_P1_RX_DN<7>")
	)
	(segment
		(start 89.194386 -385.334764)
		(end 89.194386 -385.163822)
		(width 0.14224)
		(layer "In11.Cu")
		(net "P5E_CPU1_P1_RX_DN<7>")
	)
	(segment
		(start 103.98887 -278.2062)
		(end 103.91902 -278.13635)
		(width 0.1143)
		(layer "In11.Cu")
		(net "P5E_CPU1_P1_RX_DN<7>")
	)
	(segment
		(start 103.787448 -288.190686)
		(end 103.84155 -288.15919)
		(width 0.1143)
		(layer "In11.Cu")
		(net "P5E_CPU1_P1_RX_DN<7>")
	)
	(segment
		(start 103.814118 -284.297374)
		(end 103.812594 -284.296358)
		(width 0.1143)
		(layer "In11.Cu")
		(net "P5E_CPU1_P1_RX_DN<7>")
	)
	(segment
		(start 123.22175 -338.943442)
		(end 122.221752 -333.379572)
		(width 0.14224)
		(layer "In11.Cu")
		(net "P5E_CPU1_P1_RX_DN<7>")
	)
	(segment
		(start 119.37365 -324.279514)
		(end 112.500156 -315.904626)
		(width 0.14224)
		(layer "In11.Cu")
		(net "P5E_CPU1_P1_RX_DN<7>")
	)
	(segment
		(start 103.808022 -283.318966)
		(end 103.808784 -283.318458)
		(width 0.1143)
		(layer "In11.Cu")
		(net "P5E_CPU1_P1_RX_DN<7>")
	)
	(segment
		(start 103.814118 -282.677362)
		(end 103.812594 -282.676346)
		(width 0.1143)
		(layer "In11.Cu")
		(net "P5E_CPU1_P1_RX_DN<7>")
	)
	(segment
		(start 87.666322 -371.07495)
		(end 87.85733 -371.040914)
		(width 0.14224)
		(layer "In11.Cu")
		(net "P5E_CPU1_P1_RX_DN<7>")
	)
	(segment
		(start 87.0204 -371.999764)
		(end 87.211408 -371.965728)
		(width 0.14224)
		(layer "In11.Cu")
		(net "P5E_CPU1_P1_RX_DN<7>")
	)
	(segment
		(start 103.525574 -295.142666)
		(end 103.525828 -295.141904)
		(width 0.1143)
		(layer "In11.Cu")
		(net "P5E_CPU1_P1_RX_DN<7>")
	)
	(segment
		(start 103.810054 -285.9151)
		(end 103.808784 -285.914338)
		(width 0.1143)
		(layer "In11.Cu")
		(net "P5E_CPU1_P1_RX_DN<7>")
	)
	(segment
		(start 103.810054 -291.417502)
		(end 103.839772 -291.400484)
		(width 0.1143)
		(layer "In11.Cu")
		(net "P5E_CPU1_P1_RX_DN<7>")
	)
	(segment
		(start 103.808784 -294.014144)
		(end 103.808022 -294.013636)
		(width 0.1143)
		(layer "In11.Cu")
		(net "P5E_CPU1_P1_RX_DN<7>")
	)
	(segment
		(start 103.810054 -284.295088)
		(end 103.808784 -284.294326)
		(width 0.1143)
		(layer "In11.Cu")
		(net "P5E_CPU1_P1_RX_DN<7>")
	)
	(segment
		(start 103.808784 -281.054302)
		(end 103.805736 -281.05227)
		(width 0.1143)
		(layer "In11.Cu")
		(net "P5E_CPU1_P1_RX_DN<7>")
	)
	(segment
		(start 103.347774 -280.249122)
		(end 103.299768 -280.221436)
		(width 0.1143)
		(layer "In11.Cu")
		(net "P5E_CPU1_P1_RX_DN<7>")
	)
	(segment
		(start 103.812594 -284.296358)
		(end 103.810054 -284.295088)
		(width 0.1143)
		(layer "In11.Cu")
		(net "P5E_CPU1_P1_RX_DN<7>")
	)
	(segment
		(start 103.020114 -296.390822)
		(end 103.065834 -296.345102)
		(width 0.1143)
		(layer "In11.Cu")
		(net "P5E_CPU1_P1_RX_DN<7>")
	)
	(segment
		(start 103.808784 -281.698446)
		(end 103.810054 -281.697684)
		(width 0.1143)
		(layer "In11.Cu")
		(net "P5E_CPU1_P1_RX_DN<7>")
	)
	(segment
		(start 89.177622 -382.397254)
		(end 86.065614 -374.273318)
		(width 0.14224)
		(layer "In11.Cu")
		(net "P5E_CPU1_P1_RX_DN<7>")
	)
	(segment
		(start 103.808022 -294.013636)
		(end 103.7717 -293.992554)
		(width 0.1143)
		(layer "In11.Cu")
		(net "P5E_CPU1_P1_RX_DN<7>")
	)
	(segment
		(start 103.839772 -284.312106)
		(end 103.814118 -284.297374)
		(width 0.1143)
		(layer "In11.Cu")
		(net "P5E_CPU1_P1_RX_DN<7>")
	)
	(segment
		(start 103.808022 -289.79876)
		(end 103.808784 -289.798252)
		(width 0.1143)
		(layer "In11.Cu")
		(net "P5E_CPU1_P1_RX_DN<7>")
	)
	(segment
		(start 103.808022 -291.418772)
		(end 103.808784 -291.418264)
		(width 0.1143)
		(layer "In11.Cu")
		(net "P5E_CPU1_P1_RX_DN<7>")
	)
	(segment
		(start 87.85733 -371.040914)
		(end 88.101424 -370.691156)
		(width 0.14224)
		(layer "In11.Cu")
		(net "P5E_CPU1_P1_RX_DN<7>")
	)
	(segment
		(start 103.839772 -285.932118)
		(end 103.814118 -285.917386)
		(width 0.1143)
		(layer "In11.Cu")
		(net "P5E_CPU1_P1_RX_DN<7>")
	)
	(segment
		(start 103.808022 -290.773612)
		(end 103.7717 -290.75253)
		(width 0.1143)
		(layer "In11.Cu")
		(net "P5E_CPU1_P1_RX_DN<7>")
	)
	(segment
		(start 89.186258 -383.93116)
		(end 89.186258 -382.442974)
		(width 0.14224)
		(layer "In11.Cu")
		(net "P5E_CPU1_P1_RX_DN<7>")
	)
	(segment
		(start 103.814118 -281.05735)
		(end 103.812594 -281.056334)
		(width 0.1143)
		(layer "In11.Cu")
		(net "P5E_CPU1_P1_RX_DN<7>")
	)
	(segment
		(start 103.812594 -292.396164)
		(end 103.810054 -292.394894)
		(width 0.1143)
		(layer "In11.Cu")
		(net "P5E_CPU1_P1_RX_DN<7>")
	)
	(segment
		(start 103.808784 -291.418264)
		(end 103.810054 -291.417502)
		(width 0.1143)
		(layer "In11.Cu")
		(net "P5E_CPU1_P1_RX_DN<7>")
	)
	(segment
		(start 103.814118 -285.917386)
		(end 103.812594 -285.91637)
		(width 0.1143)
		(layer "In11.Cu")
		(net "P5E_CPU1_P1_RX_DN<7>")
	)
	(segment
		(start 103.7717 -283.340048)
		(end 103.808022 -283.318966)
		(width 0.1143)
		(layer "In11.Cu")
		(net "P5E_CPU1_P1_RX_DN<7>")
	)
	(segment
		(start 103.808784 -289.798252)
		(end 103.810054 -289.79749)
		(width 0.1143)
		(layer "In11.Cu")
		(net "P5E_CPU1_P1_RX_DN<7>")
	)
	(segment
		(start 123.22175 -341.808562)
		(end 123.22175 -338.943442)
		(width 0.14224)
		(layer "In11.Cu")
		(net "P5E_CPU1_P1_RX_DN<7>")
	)
	(segment
		(start 103.812594 -290.776152)
		(end 103.810054 -290.774882)
		(width 0.1143)
		(layer "In11.Cu")
		(net "P5E_CPU1_P1_RX_DN<7>")
	)
	(segment
		(start 103.7717 -286.579818)
		(end 103.808022 -286.558736)
		(width 0.1143)
		(layer "In11.Cu")
		(net "P5E_CPU1_P1_RX_DN<7>")
	)
	(segment
		(start 103.7717 -294.679878)
		(end 103.808022 -294.658796)
		(width 0.1143)
		(layer "In11.Cu")
		(net "P5E_CPU1_P1_RX_DN<7>")
	)
	(segment
		(start 103.7717 -289.819842)
		(end 103.808022 -289.79876)
		(width 0.1143)
		(layer "In11.Cu")
		(net "P5E_CPU1_P1_RX_DN<7>")
	)
	(segment
		(start 103.808022 -287.533842)
		(end 103.774494 -287.514284)
		(width 0.1143)
		(layer "In11.Cu")
		(net "P5E_CPU1_P1_RX_DN<7>")
	)
	(segment
		(start 121.222008 -327.81621)
		(end 119.37365 -324.279514)
		(width 0.14224)
		(layer "In11.Cu")
		(net "P5E_CPU1_P1_RX_DN<7>")
	)
	(segment
		(start 86.809834 -372.540784)
		(end 86.775798 -372.349776)
		(width 0.14224)
		(layer "In11.Cu")
		(net "P5E_CPU1_P1_RX_DN<7>")
	)
	(segment
		(start 103.808022 -284.293818)
		(end 103.7717 -284.272736)
		(width 0.1143)
		(layer "In11.Cu")
		(net "P5E_CPU1_P1_RX_DN<7>")
	)
	(segment
		(start 103.538528 -278.936704)
		(end 103.538528 -278.927052)
		(width 0.1143)
		(layer "In11.Cu")
		(net "P5E_CPU1_P1_RX_DN<7>")
	)
	(segment
		(start 103.810054 -282.675076)
		(end 103.808784 -282.674314)
		(width 0.1143)
		(layer "In11.Cu")
		(net "P5E_CPU1_P1_RX_DN<7>")
	)
	(segment
		(start 103.810054 -281.697684)
		(end 103.839772 -281.680666)
		(width 0.1143)
		(layer "In11.Cu")
		(net "P5E_CPU1_P1_RX_DN<7>")
	)
	(segment
		(start 103.808022 -286.558736)
		(end 103.84155 -286.539178)
		(width 0.1143)
		(layer "In11.Cu")
		(net "P5E_CPU1_P1_RX_DN<7>")
	)
	(segment
		(start 103.812594 -281.056334)
		(end 103.810054 -281.055064)
		(width 0.1143)
		(layer "In11.Cu")
		(net "P5E_CPU1_P1_RX_DN<7>")
	)
	(segment
		(start 103.812594 -282.676346)
		(end 103.810054 -282.675076)
		(width 0.1143)
		(layer "In11.Cu")
		(net "P5E_CPU1_P1_RX_DN<7>")
	)
	(segment
		(start 103.810054 -293.037514)
		(end 103.839772 -293.020496)
		(width 0.1143)
		(layer "In11.Cu")
		(net "P5E_CPU1_P1_RX_DN<7>")
	)
	(segment
		(start 103.525828 -295.14546)
		(end 103.525574 -295.142666)
		(width 0.1143)
		(layer "In11.Cu")
		(net "P5E_CPU1_P1_RX_DN<7>")
	)
	(segment
		(start 103.810054 -284.937708)
		(end 103.839772 -284.92069)
		(width 0.1143)
		(layer "In11.Cu")
		(net "P5E_CPU1_P1_RX_DN<7>")
	)
	(segment
		(start 103.810054 -292.394894)
		(end 103.808784 -292.394132)
		(width 0.1143)
		(layer "In11.Cu")
		(net "P5E_CPU1_P1_RX_DN<7>")
	)
	(segment
		(start 103.808022 -282.673806)
		(end 103.7717 -282.652724)
		(width 0.1143)
		(layer "In11.Cu")
		(net "P5E_CPU1_P1_RX_DN<7>")
	)
	(segment
		(start 103.7717 -281.720036)
		(end 103.808022 -281.698954)
		(width 0.1143)
		(layer "In11.Cu")
		(net "P5E_CPU1_P1_RX_DN<7>")
	)
	(segment
		(start 103.7717 -291.439854)
		(end 103.808022 -291.418772)
		(width 0.1143)
		(layer "In11.Cu")
		(net "P5E_CPU1_P1_RX_DN<7>")
	)
	(segment
		(start 103.812594 -294.016176)
		(end 103.810054 -294.014906)
		(width 0.1143)
		(layer "In11.Cu")
		(net "P5E_CPU1_P1_RX_DN<7>")
	)
	(segment
		(start 87.42172 -371.424962)
		(end 87.666322 -371.07495)
		(width 0.14224)
		(layer "In11.Cu")
		(net "P5E_CPU1_P1_RX_DN<7>")
	)
	(segment
		(start 103.808784 -283.318458)
		(end 103.810054 -283.317696)
		(width 0.1143)
		(layer "In11.Cu")
		(net "P5E_CPU1_P1_RX_DN<7>")
	)
	(segment
		(start 86.775798 -372.349776)
		(end 87.0204 -371.999764)
		(width 0.14224)
		(layer "In11.Cu")
		(net "P5E_CPU1_P1_RX_DN<7>")
	)
	(segment
		(start 87.211408 -371.965728)
		(end 87.455502 -371.61597)
		(width 0.14224)
		(layer "In11.Cu")
		(net "P5E_CPU1_P1_RX_DN<7>")
	)
	(segment
		(start 103.808022 -278.45893)
		(end 103.808784 -278.458422)
		(width 0.1143)
		(layer "In11.Cu")
		(net "P5E_CPU1_P1_RX_DN<7>")
	)
	(segment
		(start 103.839772 -292.411912)
		(end 103.814118 -292.39718)
		(width 0.1143)
		(layer "In11.Cu")
		(net "P5E_CPU1_P1_RX_DN<7>")
	)
	(segment
		(start 86.033864 -374.014492)
		(end 86.058502 -373.8118)
		(width 0.14224)
		(layer "In11.Cu")
		(net "P5E_CPU1_P1_RX_DN<7>")
	)
	(segment
		(start 103.839772 -287.55213)
		(end 103.808022 -287.533842)
		(width 0.1143)
		(layer "In11.Cu")
		(net "P5E_CPU1_P1_RX_DN<7>")
	)
	(segment
		(start 89.072212 -385.405376)
		(end 89.07272 -385.404868)
		(width 0.14224)
		(layer "In11.Cu")
		(net "P5E_CPU1_P1_RX_DN<7>")
	)
	(segment
		(start 103.805736 -281.05227)
		(end 103.788464 -281.042618)
		(width 0.1143)
		(layer "In11.Cu")
		(net "P5E_CPU1_P1_RX_DN<7>")
	)
	(segment
		(start 103.810054 -278.45766)
		(end 103.839772 -278.440642)
		(width 0.1143)
		(layer "In11.Cu")
		(net "P5E_CPU1_P1_RX_DN<7>")
	)
	(segment
		(start 103.814118 -292.39718)
		(end 103.812594 -292.396164)
		(width 0.1143)
		(layer "In11.Cu")
		(net "P5E_CPU1_P1_RX_DN<7>")
	)
	(segment
		(start 86.262464 -373.324374)
		(end 86.809834 -372.540784)
		(width 0.14224)
		(layer "In11.Cu")
		(net "P5E_CPU1_P1_RX_DN<7>")
	)
	(segment
		(start 103.839772 -294.031924)
		(end 103.814118 -294.017192)
		(width 0.1143)
		(layer "In11.Cu")
		(net "P5E_CPU1_P1_RX_DN<7>")
	)
	(segment
		(start 103.786686 -288.191194)
		(end 103.787448 -288.190686)
		(width 0.1143)
		(layer "In11.Cu")
		(net "P5E_CPU1_P1_RX_DN<7>")
	)
	(segment
		(start 103.91902 -278.13635)
		(end 103.621078 -278.13635)
		(width 0.1143)
		(layer "In11.Cu")
		(net "P5E_CPU1_P1_RX_DN<7>")
	)
	(segment
		(start 87.455502 -371.61597)
		(end 87.42172 -371.424962)
		(width 0.14224)
		(layer "In11.Cu")
		(net "P5E_CPU1_P1_RX_DN<7>")
	)
	(segment
		(start 103.810054 -289.79749)
		(end 103.839772 -289.780472)
		(width 0.1143)
		(layer "In11.Cu")
		(net "P5E_CPU1_P1_RX_DN<7>")
	)
	(segment
		(start 88.88222 -384.234944)
		(end 89.186258 -383.93116)
		(width 0.14224)
		(layer "In11.Cu")
		(net "P5E_CPU1_P1_RX_DN<7>")
	)
	(segment
		(start 103.7717 -293.059866)
		(end 103.808022 -293.038784)
		(width 0.1143)
		(layer "In11.Cu")
		(net "P5E_CPU1_P1_RX_DN<7>")
	)
	(segment
		(start 95.60052 -364.248192)
		(end 120.085358 -347.88729)
		(width 0.14224)
		(layer "In11.Cu")
		(net "P5E_CPU1_P1_RX_DN<7>")
	)
	(segment
		(start 103.808022 -293.038784)
		(end 103.808784 -293.038276)
		(width 0.1143)
		(layer "In11.Cu")
		(net "P5E_CPU1_P1_RX_DN<7>")
	)
	(arc
		(start 103.839772 -281.680666)
		(mid 103.9957 -281.376374)
		(end 103.839772 -281.072082)
		(width 0.1143)
		(layer "In11.Cu")
		(net "P5E_CPU1_P1_RX_DN<7>")
	)
	(arc
		(start 86.058502 -373.8118)
		(mid 86.073931 -373.724865)
		(end 86.098634 -373.640096)
		(width 0.14224)
		(layer "In11.Cu")
		(net "P5E_CPU1_P1_RX_DN<7>")
	)
	(arc
		(start 103.84155 -286.539178)
		(mid 103.954957 -286.406289)
		(end 103.995728 -286.23641)
		(width 0.1143)
		(layer "In11.Cu")
		(net "P5E_CPU1_P1_RX_DN<7>")
	)
	(arc
		(start 86.065614 -374.273318)
		(mid 86.033948 -374.145845)
		(end 86.033864 -374.014492)
		(width 0.14224)
		(layer "In11.Cu")
		(net "P5E_CPU1_P1_RX_DN<7>")
	)
	(arc
		(start 103.757476 -294.689784)
		(mid 103.764549 -294.684775)
		(end 103.7717 -294.679878)
		(width 0.1143)
		(layer "In11.Cu")
		(net "P5E_CPU1_P1_RX_DN<7>")
	)
	(arc
		(start 103.755444 -283.351478)
		(mid 103.763522 -283.345692)
		(end 103.7717 -283.340048)
		(width 0.1143)
		(layer "In11.Cu")
		(net "P5E_CPU1_P1_RX_DN<7>")
	)
	(arc
		(start 103.839772 -283.300678)
		(mid 103.9957 -282.996386)
		(end 103.839772 -282.692094)
		(width 0.1143)
		(layer "In11.Cu")
		(net "P5E_CPU1_P1_RX_DN<7>")
	)
	(arc
		(start 103.299768 -280.221436)
		(mid 103.299387 -280.221182)
		(end 103.299006 -280.220928)
		(width 0.1143)
		(layer "In11.Cu")
		(net "P5E_CPU1_P1_RX_DN<7>")
	)
	(arc
		(start 103.774494 -287.514284)
		(mid 103.76593 -287.508522)
		(end 103.757476 -287.5026)
		(width 0.1143)
		(layer "In11.Cu")
		(net "P5E_CPU1_P1_RX_DN<7>")
	)
	(arc
		(start 103.350822 -279.26157)
		(mid 103.488254 -279.124311)
		(end 103.538528 -278.936704)
		(width 0.1143)
		(layer "In11.Cu")
		(net "P5E_CPU1_P1_RX_DN<7>")
	)
	(arc
		(start 103.75646 -293.981886)
		(mid 103.531289 -293.52621)
		(end 103.75646 -293.070534)
		(width 0.1143)
		(layer "In11.Cu")
		(net "P5E_CPU1_P1_RX_DN<7>")
	)
	(arc
		(start 103.7717 -292.372542)
		(mid 103.76455 -292.367644)
		(end 103.757476 -292.362636)
		(width 0.1143)
		(layer "In11.Cu")
		(net "P5E_CPU1_P1_RX_DN<7>")
	)
	(arc
		(start 103.467662 -295.383966)
		(mid 103.510698 -295.319652)
		(end 103.525828 -295.243758)
		(width 0.1143)
		(layer "In11.Cu")
		(net "P5E_CPU1_P1_RX_DN<7>")
	)
	(arc
		(start 103.995728 -286.23641)
		(mid 103.954473 -286.065439)
		(end 103.839772 -285.932118)
		(width 0.1143)
		(layer "In11.Cu")
		(net "P5E_CPU1_P1_RX_DN<7>")
	)
	(arc
		(start 103.065834 -295.947338)
		(mid 103.09543 -295.79808)
		(end 103.17988 -295.671494)
		(width 0.1143)
		(layer "In11.Cu")
		(net "P5E_CPU1_P1_RX_DN<7>")
	)
	(arc
		(start 103.839772 -293.020496)
		(mid 103.9957 -292.716204)
		(end 103.839772 -292.411912)
		(width 0.1143)
		(layer "In11.Cu")
		(net "P5E_CPU1_P1_RX_DN<7>")
	)
	(arc
		(start 103.75646 -293.070534)
		(mid 103.764036 -293.065138)
		(end 103.7717 -293.059866)
		(width 0.1143)
		(layer "In11.Cu")
		(net "P5E_CPU1_P1_RX_DN<7>")
	)
	(arc
		(start 103.839772 -291.400484)
		(mid 103.9957 -291.096192)
		(end 103.839772 -290.7919)
		(width 0.1143)
		(layer "In11.Cu")
		(net "P5E_CPU1_P1_RX_DN<7>")
	)
	(arc
		(start 103.755444 -284.261306)
		(mid 103.53256 -283.806392)
		(end 103.755444 -283.351478)
		(width 0.1143)
		(layer "In11.Cu")
		(net "P5E_CPU1_P1_RX_DN<7>")
	)
	(arc
		(start 103.533956 -280.572972)
		(mid 103.484085 -280.386207)
		(end 103.347774 -280.249122)
		(width 0.1143)
		(layer "In11.Cu")
		(net "P5E_CPU1_P1_RX_DN<7>")
	)
	(arc
		(start 103.757476 -287.5026)
		(mid 103.589845 -287.303089)
		(end 103.525828 -287.05048)
		(width 0.1143)
		(layer "In11.Cu")
		(net "P5E_CPU1_P1_RX_DN<7>")
	)
	(arc
		(start 103.757476 -292.362636)
		(mid 103.530093 -291.906198)
		(end 103.757476 -291.44976)
		(width 0.1143)
		(layer "In11.Cu")
		(net "P5E_CPU1_P1_RX_DN<7>")
	)
	(arc
		(start 103.995728 -287.856422)
		(mid 103.954473 -287.685451)
		(end 103.839772 -287.55213)
		(width 0.1143)
		(layer "In11.Cu")
		(net "P5E_CPU1_P1_RX_DN<7>")
	)
	(arc
		(start 103.75646 -285.88208)
		(mid 103.531289 -285.426404)
		(end 103.75646 -284.970728)
		(width 0.1143)
		(layer "In11.Cu")
		(net "P5E_CPU1_P1_RX_DN<7>")
	)
	(arc
		(start 103.788464 -281.042618)
		(mid 103.602175 -280.856809)
		(end 103.533956 -280.60269)
		(width 0.1143)
		(layer "In11.Cu")
		(net "P5E_CPU1_P1_RX_DN<7>")
	)
	(arc
		(start 103.839772 -284.92069)
		(mid 103.9957 -284.616398)
		(end 103.839772 -284.312106)
		(width 0.1143)
		(layer "In11.Cu")
		(net "P5E_CPU1_P1_RX_DN<7>")
	)
	(arc
		(start 103.759254 -289.828478)
		(mid 103.765448 -289.824118)
		(end 103.7717 -289.819842)
		(width 0.1143)
		(layer "In11.Cu")
		(net "P5E_CPU1_P1_RX_DN<7>")
	)
	(arc
		(start 103.757476 -282.642818)
		(mid 103.530093 -282.18638)
		(end 103.757476 -281.729942)
		(width 0.1143)
		(layer "In11.Cu")
		(net "P5E_CPU1_P1_RX_DN<7>")
	)
	(arc
		(start 103.839772 -294.640508)
		(mid 103.9957 -294.336216)
		(end 103.839772 -294.031924)
		(width 0.1143)
		(layer "In11.Cu")
		(net "P5E_CPU1_P1_RX_DN<7>")
	)
	(arc
		(start 103.757476 -291.44976)
		(mid 103.764549 -291.444751)
		(end 103.7717 -291.439854)
		(width 0.1143)
		(layer "In11.Cu")
		(net "P5E_CPU1_P1_RX_DN<7>")
	)
	(arc
		(start 103.757476 -281.729942)
		(mid 103.76455 -281.724935)
		(end 103.7717 -281.720036)
		(width 0.1143)
		(layer "In11.Cu")
		(net "P5E_CPU1_P1_RX_DN<7>")
	)
	(arc
		(start 89.186258 -382.442974)
		(mid 89.18403 -382.41972)
		(end 89.177622 -382.397254)
		(width 0.14224)
		(layer "In11.Cu")
		(net "P5E_CPU1_P1_RX_DN<7>")
	)
	(arc
		(start 103.75646 -284.970728)
		(mid 103.764036 -284.965332)
		(end 103.7717 -284.96006)
		(width 0.1143)
		(layer "In11.Cu")
		(net "P5E_CPU1_P1_RX_DN<7>")
	)
	(arc
		(start 103.525828 -287.046162)
		(mid 103.591064 -286.782571)
		(end 103.7717 -286.579818)
		(width 0.1143)
		(layer "In11.Cu")
		(net "P5E_CPU1_P1_RX_DN<7>")
	)
	(arc
		(start 86.098634 -373.640096)
		(mid 86.17014 -373.476834)
		(end 86.262464 -373.324374)
		(width 0.14224)
		(layer "In11.Cu")
		(net "P5E_CPU1_P1_RX_DN<7>")
	)
	(arc
		(start 103.7717 -285.892748)
		(mid 103.764036 -285.887477)
		(end 103.75646 -285.88208)
		(width 0.1143)
		(layer "In11.Cu")
		(net "P5E_CPU1_P1_RX_DN<7>")
	)
	(arc
		(start 103.7717 -282.652724)
		(mid 103.764551 -282.647824)
		(end 103.757476 -282.642818)
		(width 0.1143)
		(layer "In11.Cu")
		(net "P5E_CPU1_P1_RX_DN<7>")
	)
	(arc
		(start 103.786686 -289.141154)
		(mid 103.513135 -288.666174)
		(end 103.786686 -288.191194)
		(width 0.1143)
		(layer "In11.Cu")
		(net "P5E_CPU1_P1_RX_DN<7>")
	)
	(arc
		(start 103.759254 -290.743894)
		(mid 103.527786 -290.286186)
		(end 103.759254 -289.828478)
		(width 0.1143)
		(layer "In11.Cu")
		(net "P5E_CPU1_P1_RX_DN<7>")
	)
	(arc
		(start 103.7717 -290.75253)
		(mid 103.765448 -290.748253)
		(end 103.759254 -290.743894)
		(width 0.1143)
		(layer "In11.Cu")
		(net "P5E_CPU1_P1_RX_DN<7>")
	)
	(arc
		(start 103.538528 -278.927052)
		(mid 103.610718 -278.656981)
		(end 103.808022 -278.45893)
		(width 0.1143)
		(layer "In11.Cu")
		(net "P5E_CPU1_P1_RX_DN<7>")
	)
	(arc
		(start 103.299006 -280.220928)
		(mid 103.055679 -279.756362)
		(end 103.299006 -279.291796)
		(width 0.1143)
		(layer "In11.Cu")
		(net "P5E_CPU1_P1_RX_DN<7>")
	)
	(arc
		(start 120.085358 -347.88729)
		(mid 120.822696 -347.218796)
		(end 121.334276 -346.365068)
		(width 0.14224)
		(layer "In11.Cu")
		(net "P5E_CPU1_P1_RX_DN<7>")
	)
	(arc
		(start 103.839772 -278.440642)
		(mid 103.936907 -278.337773)
		(end 103.98887 -278.2062)
		(width 0.1143)
		(layer "In11.Cu")
		(net "P5E_CPU1_P1_RX_DN<7>")
	)
	(arc
		(start 103.525828 -295.141904)
		(mid 103.589805 -294.889274)
		(end 103.757476 -294.689784)
		(width 0.1143)
		(layer "In11.Cu")
		(net "P5E_CPU1_P1_RX_DN<7>")
	)
	(arc
		(start 103.525828 -287.05048)
		(mid 103.525824 -287.048321)
		(end 103.525828 -287.046162)
		(width 0.1143)
		(layer "In11.Cu")
		(net "P5E_CPU1_P1_RX_DN<7>")
	)
	(arc
		(start 103.7717 -284.272736)
		(mid 103.763522 -284.267093)
		(end 103.755444 -284.261306)
		(width 0.1143)
		(layer "In11.Cu")
		(net "P5E_CPU1_P1_RX_DN<7>")
	)
	(arc
		(start 103.7717 -293.992554)
		(mid 103.764036 -293.987283)
		(end 103.75646 -293.981886)
		(width 0.1143)
		(layer "In11.Cu")
		(net "P5E_CPU1_P1_RX_DN<7>")
	)
	(arc
		(start 103.84155 -288.15919)
		(mid 103.954957 -288.026301)
		(end 103.995728 -287.856422)
		(width 0.1143)
		(layer "In11.Cu")
		(net "P5E_CPU1_P1_RX_DN<7>")
	)
	(arc
		(start 103.839772 -289.780472)
		(mid 103.9957 -289.47618)
		(end 103.839772 -289.171888)
		(width 0.1143)
		(layer "In11.Cu")
		(net "P5E_CPU1_P1_RX_DN<7>")
	)
	(segment
		(start 104.08793 -276.2504)
		(end 103.621078 -276.516338)
		(width 0.12954)
		(layer "F.Cu")
		(net "P5E_CPU1_P1_RX_DN<6>")
	)
	(segment
		(start 86.998302 -385.31038)
		(end 87.519002 -385.31038)
		(width 0.127)
		(layer "F.Cu")
		(net "P5E_CPU1_P1_RX_DN<6>")
	)
	(segment
		(start 87.910924 -381.927354)
		(end 85.10905 -374.48236)
		(width 0.14224)
		(layer "In11.Cu")
		(net "P5E_CPU1_P1_RX_DN<6>")
	)
	(segment
		(start 102.4001 -279.267666)
		(end 102.429818 -279.250648)
		(width 0.1143)
		(layer "In11.Cu")
		(net "P5E_CPU1_P1_RX_DN<6>")
	)
	(segment
		(start 103.364538 -277.633684)
		(end 103.3653 -277.633176)
		(width 0.1143)
		(layer "In11.Cu")
		(net "P5E_CPU1_P1_RX_DN<6>")
	)
	(segment
		(start 102.898702 -284.311598)
		(end 102.829106 -284.270958)
		(width 0.1143)
		(layer "In11.Cu")
		(net "P5E_CPU1_P1_RX_DN<6>")
	)
	(segment
		(start 102.358952 -279.291796)
		(end 102.395528 -279.27046)
		(width 0.1143)
		(layer "In11.Cu")
		(net "P5E_CPU1_P1_RX_DN<6>")
	)
	(segment
		(start 122.245882 -338.85505)
		(end 121.277634 -333.469742)
		(width 0.14224)
		(layer "In11.Cu")
		(net "P5E_CPU1_P1_RX_DN<6>")
	)
	(segment
		(start 111.752126 -316.463172)
		(end 105.664762 -307.352954)
		(width 0.14224)
		(layer "In11.Cu")
		(net "P5E_CPU1_P1_RX_DN<6>")
	)
	(segment
		(start 102.829106 -291.441632)
		(end 102.898702 -291.400992)
		(width 0.1143)
		(layer "In11.Cu")
		(net "P5E_CPU1_P1_RX_DN<6>")
	)
	(segment
		(start 102.831138 -286.580072)
		(end 102.868222 -286.558736)
		(width 0.1143)
		(layer "In11.Cu")
		(net "P5E_CPU1_P1_RX_DN<6>")
	)
	(segment
		(start 120.309894 -328.084434)
		(end 118.59133 -324.796404)
		(width 0.14224)
		(layer "In11.Cu")
		(net "P5E_CPU1_P1_RX_DN<6>")
	)
	(segment
		(start 121.277888 -333.469742)
		(end 120.309894 -328.084434)
		(width 0.14224)
		(layer "In11.Cu")
		(net "P5E_CPU1_P1_RX_DN<6>")
	)
	(segment
		(start 102.40264 -280.246328)
		(end 102.4001 -280.245058)
		(width 0.1143)
		(layer "In11.Cu")
		(net "P5E_CPU1_P1_RX_DN<6>")
	)
	(segment
		(start 122.245882 -341.566754)
		(end 122.245882 -338.85505)
		(width 0.14224)
		(layer "In11.Cu")
		(net "P5E_CPU1_P1_RX_DN<6>")
	)
	(segment
		(start 87.872316 -385.405376)
		(end 87.872824 -385.404868)
		(width 0.14224)
		(layer "In11.Cu")
		(net "P5E_CPU1_P1_RX_DN<6>")
	)
	(segment
		(start 103.98887 -276.586188)
		(end 103.91902 -276.516338)
		(width 0.1143)
		(layer "In11.Cu")
		(net "P5E_CPU1_P1_RX_DN<6>")
	)
	(segment
		(start 102.829106 -278.48179)
		(end 102.898702 -278.44115)
		(width 0.1143)
		(layer "In11.Cu")
		(net "P5E_CPU1_P1_RX_DN<6>")
	)
	(segment
		(start 102.829106 -284.961838)
		(end 102.898702 -284.921198)
		(width 0.1143)
		(layer "In11.Cu")
		(net "P5E_CPU1_P1_RX_DN<6>")
	)
	(segment
		(start 89.201752 -367.20399)
		(end 91.218512 -365.592868)
		(width 0.14224)
		(layer "In11.Cu")
		(net "P5E_CPU1_P1_RX_DN<6>")
	)
	(segment
		(start 85.74659 -372.091712)
		(end 85.713824 -371.90045)
		(width 0.14224)
		(layer "In11.Cu")
		(net "P5E_CPU1_P1_RX_DN<6>")
	)
	(segment
		(start 103.7717 -276.86)
		(end 103.808022 -276.838918)
		(width 0.1143)
		(layer "In11.Cu")
		(net "P5E_CPU1_P1_RX_DN<6>")
	)
	(segment
		(start 102.898702 -290.791392)
		(end 102.829106 -290.750752)
		(width 0.1143)
		(layer "In11.Cu")
		(net "P5E_CPU1_P1_RX_DN<6>")
	)
	(segment
		(start 102.39883 -279.268428)
		(end 102.4001 -279.267666)
		(width 0.1143)
		(layer "In11.Cu")
		(net "P5E_CPU1_P1_RX_DN<6>")
	)
	(segment
		(start 102.586028 -295.155112)
		(end 102.586028 -295.146222)
		(width 0.1143)
		(layer "In11.Cu")
		(net "P5E_CPU1_P1_RX_DN<6>")
	)
	(segment
		(start 102.898702 -294.031416)
		(end 102.829106 -293.990776)
		(width 0.1143)
		(layer "In11.Cu")
		(net "P5E_CPU1_P1_RX_DN<6>")
	)
	(segment
		(start 85.359494 -372.639336)
		(end 85.74659 -372.091712)
		(width 0.14224)
		(layer "In11.Cu")
		(net "P5E_CPU1_P1_RX_DN<6>")
	)
	(segment
		(start 102.829106 -286.581596)
		(end 102.831138 -286.580072)
		(width 0.1143)
		(layer "In11.Cu")
		(net "P5E_CPU1_P1_RX_DN<6>")
	)
	(segment
		(start 102.829106 -293.061644)
		(end 102.898702 -293.021004)
		(width 0.1143)
		(layer "In11.Cu")
		(net "P5E_CPU1_P1_RX_DN<6>")
	)
	(segment
		(start 121.277634 -333.469742)
		(end 121.277888 -333.469742)
		(width 0.14224)
		(layer "In11.Cu")
		(net "P5E_CPU1_P1_RX_DN<6>")
	)
	(segment
		(start 102.898702 -281.071574)
		(end 102.829106 -281.030934)
		(width 0.1143)
		(layer "In11.Cu")
		(net "P5E_CPU1_P1_RX_DN<6>")
	)
	(segment
		(start 103.337106 -277.649432)
		(end 103.338122 -277.648924)
		(width 0.1143)
		(layer "In11.Cu")
		(net "P5E_CPU1_P1_RX_DN<6>")
	)
	(segment
		(start 86.364826 -370.979446)
		(end 86.61146 -370.630704)
		(width 0.14224)
		(layer "In11.Cu")
		(net "P5E_CPU1_P1_RX_DN<6>")
	)
	(segment
		(start 102.394512 -280.241756)
		(end 102.391972 -280.240232)
		(width 0.1143)
		(layer "In11.Cu")
		(net "P5E_CPU1_P1_RX_DN<6>")
	)
	(segment
		(start 102.429818 -280.262076)
		(end 102.404164 -280.247344)
		(width 0.1143)
		(layer "In11.Cu")
		(net "P5E_CPU1_P1_RX_DN<6>")
	)
	(segment
		(start 95.164402 -363.262418)
		(end 119.444516 -347.03893)
		(width 0.14224)
		(layer "In11.Cu")
		(net "P5E_CPU1_P1_RX_DN<6>")
	)
	(segment
		(start 87.453724 -369.676934)
		(end 89.201752 -367.20399)
		(width 0.14224)
		(layer "In11.Cu")
		(net "P5E_CPU1_P1_RX_DN<6>")
	)
	(segment
		(start 102.829106 -288.201608)
		(end 102.868222 -288.178748)
		(width 0.1143)
		(layer "In11.Cu")
		(net "P5E_CPU1_P1_RX_DN<6>")
	)
	(segment
		(start 86.61146 -370.630704)
		(end 86.802468 -370.597938)
		(width 0.14224)
		(layer "In11.Cu")
		(net "P5E_CPU1_P1_RX_DN<6>")
	)
	(segment
		(start 102.868222 -286.558736)
		(end 102.900734 -286.53994)
		(width 0.1143)
		(layer "In11.Cu")
		(net "P5E_CPU1_P1_RX_DN<6>")
	)
	(segment
		(start 102.868222 -288.178748)
		(end 102.900734 -288.159952)
		(width 0.1143)
		(layer "In11.Cu")
		(net "P5E_CPU1_P1_RX_DN<6>")
	)
	(segment
		(start 102.398068 -279.268936)
		(end 102.39883 -279.268428)
		(width 0.1143)
		(layer "In11.Cu")
		(net "P5E_CPU1_P1_RX_DN<6>")
	)
	(segment
		(start 87.99449 -385.334764)
		(end 87.99449 -385.163822)
		(width 0.14224)
		(layer "In11.Cu")
		(net "P5E_CPU1_P1_RX_DN<6>")
	)
	(segment
		(start 102.829106 -289.82162)
		(end 102.898702 -289.78098)
		(width 0.1143)
		(layer "In11.Cu")
		(net "P5E_CPU1_P1_RX_DN<6>")
	)
	(segment
		(start 102.397052 -280.24328)
		(end 102.395528 -280.242264)
		(width 0.1143)
		(layer "In11.Cu")
		(net "P5E_CPU1_P1_RX_DN<6>")
	)
	(segment
		(start 103.525828 -277.310342)
		(end 103.525828 -277.310088)
		(width 0.1143)
		(layer "In11.Cu")
		(net "P5E_CPU1_P1_RX_DN<6>")
	)
	(segment
		(start 102.075234 -298.686982)
		(end 102.075234 -296.41927)
		(width 0.14224)
		(layer "In11.Cu")
		(net "P5E_CPU1_P1_RX_DN<6>")
	)
	(segment
		(start 86.151466 -371.518942)
		(end 86.397592 -371.170708)
		(width 0.14224)
		(layer "In11.Cu")
		(net "P5E_CPU1_P1_RX_DN<6>")
	)
	(segment
		(start 86.397592 -371.170708)
		(end 86.364826 -370.979446)
		(width 0.14224)
		(layer "In11.Cu")
		(net "P5E_CPU1_P1_RX_DN<6>")
	)
	(segment
		(start 105.664762 -307.352954)
		(end 102.075234 -298.686982)
		(width 0.14224)
		(layer "In11.Cu")
		(net "P5E_CPU1_P1_RX_DN<6>")
	)
	(segment
		(start 87.015828 -370.058442)
		(end 87.262462 -369.7097)
		(width 0.14224)
		(layer "In11.Cu")
		(net "P5E_CPU1_P1_RX_DN<6>")
	)
	(segment
		(start 118.59133 -324.796404)
		(end 111.752126 -316.463172)
		(width 0.14224)
		(layer "In11.Cu")
		(net "P5E_CPU1_P1_RX_DN<6>")
	)
	(segment
		(start 102.898702 -289.17138)
		(end 102.829106 -289.13074)
		(width 0.1143)
		(layer "In11.Cu")
		(net "P5E_CPU1_P1_RX_DN<6>")
	)
	(segment
		(start 102.395528 -280.242264)
		(end 102.394512 -280.241756)
		(width 0.1143)
		(layer "In11.Cu")
		(net "P5E_CPU1_P1_RX_DN<6>")
	)
	(segment
		(start 102.829106 -281.721814)
		(end 102.898702 -281.681174)
		(width 0.1143)
		(layer "In11.Cu")
		(net "P5E_CPU1_P1_RX_DN<6>")
	)
	(segment
		(start 102.397052 -279.269444)
		(end 102.398068 -279.268936)
		(width 0.1143)
		(layer "In11.Cu")
		(net "P5E_CPU1_P1_RX_DN<6>")
	)
	(segment
		(start 87.682324 -384.234944)
		(end 87.986362 -383.930906)
		(width 0.14224)
		(layer "In11.Cu")
		(net "P5E_CPU1_P1_RX_DN<6>")
	)
	(segment
		(start 87.677498 -384.84683)
		(end 87.682324 -384.234944)
		(width 0.14224)
		(layer "In11.Cu")
		(net "P5E_CPU1_P1_RX_DN<6>")
	)
	(segment
		(start 102.898702 -282.691586)
		(end 102.829106 -282.650946)
		(width 0.1143)
		(layer "In11.Cu")
		(net "P5E_CPU1_P1_RX_DN<6>")
	)
	(segment
		(start 87.872824 -385.404868)
		(end 87.99449 -385.334764)
		(width 0.14224)
		(layer "In11.Cu")
		(net "P5E_CPU1_P1_RX_DN<6>")
	)
	(segment
		(start 102.39883 -280.244296)
		(end 102.398068 -280.243788)
		(width 0.1143)
		(layer "In11.Cu")
		(net "P5E_CPU1_P1_RX_DN<6>")
	)
	(segment
		(start 120.524016 -345.723718)
		(end 122.245882 -341.566754)
		(width 0.14224)
		(layer "In11.Cu")
		(net "P5E_CPU1_P1_RX_DN<6>")
	)
	(segment
		(start 102.83063 -294.68064)
		(end 102.898702 -294.641016)
		(width 0.1143)
		(layer "In11.Cu")
		(net "P5E_CPU1_P1_RX_DN<6>")
	)
	(segment
		(start 103.299006 -277.671784)
		(end 103.335582 -277.650448)
		(width 0.1143)
		(layer "In11.Cu")
		(net "P5E_CPU1_P1_RX_DN<6>")
	)
	(segment
		(start 85.960204 -371.551962)
		(end 86.151466 -371.518942)
		(width 0.14224)
		(layer "In11.Cu")
		(net "P5E_CPU1_P1_RX_DN<6>")
	)
	(segment
		(start 103.338122 -277.648924)
		(end 103.33863 -277.648924)
		(width 0.1143)
		(layer "In11.Cu")
		(net "P5E_CPU1_P1_RX_DN<6>")
	)
	(segment
		(start 102.398068 -280.243788)
		(end 102.397052 -280.24328)
		(width 0.1143)
		(layer "In11.Cu")
		(net "P5E_CPU1_P1_RX_DN<6>")
	)
	(segment
		(start 102.075234 -296.41927)
		(end 102.075234 -296.390822)
		(width 0.1143)
		(layer "In11.Cu")
		(net "P5E_CPU1_P1_RX_DN<6>")
	)
	(segment
		(start 102.075234 -296.390822)
		(end 102.120954 -296.345102)
		(width 0.1143)
		(layer "In11.Cu")
		(net "P5E_CPU1_P1_RX_DN<6>")
	)
	(segment
		(start 103.91902 -276.516338)
		(end 103.621078 -276.516338)
		(width 0.1143)
		(layer "In11.Cu")
		(net "P5E_CPU1_P1_RX_DN<6>")
	)
	(segment
		(start 102.120954 -296.345102)
		(end 102.120954 -296.113708)
		(width 0.1143)
		(layer "In11.Cu")
		(net "P5E_CPU1_P1_RX_DN<6>")
	)
	(segment
		(start 102.395528 -279.27046)
		(end 102.397052 -279.269444)
		(width 0.1143)
		(layer "In11.Cu")
		(net "P5E_CPU1_P1_RX_DN<6>")
	)
	(segment
		(start 102.898702 -287.551622)
		(end 102.831646 -287.512506)
		(width 0.1143)
		(layer "In11.Cu")
		(net "P5E_CPU1_P1_RX_DN<6>")
	)
	(segment
		(start 102.296468 -295.689274)
		(end 102.412546 -295.573196)
		(width 0.1143)
		(layer "In11.Cu")
		(net "P5E_CPU1_P1_RX_DN<6>")
	)
	(segment
		(start 102.391972 -280.240232)
		(end 102.390448 -280.239216)
		(width 0.1143)
		(layer "In11.Cu")
		(net "P5E_CPU1_P1_RX_DN<6>")
	)
	(segment
		(start 87.519002 -385.31038)
		(end 87.872316 -385.405376)
		(width 0.14224)
		(layer "In11.Cu")
		(net "P5E_CPU1_P1_RX_DN<6>")
	)
	(segment
		(start 87.048594 -370.249704)
		(end 87.015828 -370.058442)
		(width 0.14224)
		(layer "In11.Cu")
		(net "P5E_CPU1_P1_RX_DN<6>")
	)
	(segment
		(start 103.33863 -277.648924)
		(end 103.364538 -277.633684)
		(width 0.1143)
		(layer "In11.Cu")
		(net "P5E_CPU1_P1_RX_DN<6>")
	)
	(segment
		(start 87.986362 -383.930906)
		(end 87.986362 -382.342136)
		(width 0.14224)
		(layer "In11.Cu")
		(net "P5E_CPU1_P1_RX_DN<6>")
	)
	(segment
		(start 102.404164 -280.247344)
		(end 102.40264 -280.246328)
		(width 0.1143)
		(layer "In11.Cu")
		(net "P5E_CPU1_P1_RX_DN<6>")
	)
	(segment
		(start 102.829106 -283.341826)
		(end 102.898702 -283.301186)
		(width 0.1143)
		(layer "In11.Cu")
		(net "P5E_CPU1_P1_RX_DN<6>")
	)
	(segment
		(start 102.390448 -280.239216)
		(end 102.358952 -280.220928)
		(width 0.1143)
		(layer "In11.Cu")
		(net "P5E_CPU1_P1_RX_DN<6>")
	)
	(segment
		(start 91.218512 -365.592868)
		(end 95.164402 -363.262418)
		(width 0.14224)
		(layer "In11.Cu")
		(net "P5E_CPU1_P1_RX_DN<6>")
	)
	(segment
		(start 86.802468 -370.597938)
		(end 87.048594 -370.249704)
		(width 0.14224)
		(layer "In11.Cu")
		(net "P5E_CPU1_P1_RX_DN<6>")
	)
	(segment
		(start 103.335582 -277.650448)
		(end 103.337106 -277.649432)
		(width 0.1143)
		(layer "In11.Cu")
		(net "P5E_CPU1_P1_RX_DN<6>")
	)
	(segment
		(start 102.4001 -280.245058)
		(end 102.39883 -280.244296)
		(width 0.1143)
		(layer "In11.Cu")
		(net "P5E_CPU1_P1_RX_DN<6>")
	)
	(segment
		(start 102.898702 -285.93161)
		(end 102.829106 -285.89097)
		(width 0.1143)
		(layer "In11.Cu")
		(net "P5E_CPU1_P1_RX_DN<6>")
	)
	(segment
		(start 103.808022 -276.838918)
		(end 103.839772 -276.82063)
		(width 0.1143)
		(layer "In11.Cu")
		(net "P5E_CPU1_P1_RX_DN<6>")
	)
	(segment
		(start 87.99449 -385.163822)
		(end 87.677498 -384.84683)
		(width 0.14224)
		(layer "In11.Cu")
		(net "P5E_CPU1_P1_RX_DN<6>")
	)
	(segment
		(start 102.898702 -292.411404)
		(end 102.829106 -292.370764)
		(width 0.1143)
		(layer "In11.Cu")
		(net "P5E_CPU1_P1_RX_DN<6>")
	)
	(segment
		(start 85.713824 -371.90045)
		(end 85.960204 -371.551962)
		(width 0.14224)
		(layer "In11.Cu")
		(net "P5E_CPU1_P1_RX_DN<6>")
	)
	(segment
		(start 87.262462 -369.7097)
		(end 87.453724 -369.676934)
		(width 0.14224)
		(layer "In11.Cu")
		(net "P5E_CPU1_P1_RX_DN<6>")
	)
	(segment
		(start 85.077808 -374.26519)
		(end 85.168486 -373.039132)
		(width 0.14224)
		(layer "In11.Cu")
		(net "P5E_CPU1_P1_RX_DN<6>")
	)
	(arc
		(start 102.898702 -294.641016)
		(mid 103.055679 -294.336216)
		(end 102.898702 -294.031416)
		(width 0.1143)
		(layer "In11.Cu")
		(net "P5E_CPU1_P1_RX_DN<6>")
	)
	(arc
		(start 102.585774 -278.946356)
		(mid 102.650289 -278.684137)
		(end 102.829106 -278.48179)
		(width 0.1143)
		(layer "In11.Cu")
		(net "P5E_CPU1_P1_RX_DN<6>")
	)
	(arc
		(start 102.829106 -290.750752)
		(mid 102.585779 -290.286186)
		(end 102.829106 -289.82162)
		(width 0.1143)
		(layer "In11.Cu")
		(net "P5E_CPU1_P1_RX_DN<6>")
	)
	(arc
		(start 102.829106 -292.370764)
		(mid 102.585779 -291.906198)
		(end 102.829106 -291.441632)
		(width 0.1143)
		(layer "In11.Cu")
		(net "P5E_CPU1_P1_RX_DN<6>")
	)
	(arc
		(start 102.829106 -284.270958)
		(mid 102.585779 -283.806392)
		(end 102.829106 -283.341826)
		(width 0.1143)
		(layer "In11.Cu")
		(net "P5E_CPU1_P1_RX_DN<6>")
	)
	(arc
		(start 102.829106 -281.030934)
		(mid 102.650293 -280.828584)
		(end 102.585774 -280.566368)
		(width 0.1143)
		(layer "In11.Cu")
		(net "P5E_CPU1_P1_RX_DN<6>")
	)
	(arc
		(start 102.358952 -280.220928)
		(mid 102.115625 -279.756362)
		(end 102.358952 -279.291796)
		(width 0.1143)
		(layer "In11.Cu")
		(net "P5E_CPU1_P1_RX_DN<6>")
	)
	(arc
		(start 85.168486 -373.039132)
		(mid 85.247006 -372.83112)
		(end 85.359494 -372.639336)
		(width 0.14224)
		(layer "In11.Cu")
		(net "P5E_CPU1_P1_RX_DN<6>")
	)
	(arc
		(start 103.839772 -276.82063)
		(mid 103.936907 -276.717761)
		(end 103.98887 -276.586188)
		(width 0.1143)
		(layer "In11.Cu")
		(net "P5E_CPU1_P1_RX_DN<6>")
	)
	(arc
		(start 102.831646 -287.512506)
		(mid 102.650994 -287.309761)
		(end 102.585774 -287.046162)
		(width 0.1143)
		(layer "In11.Cu")
		(net "P5E_CPU1_P1_RX_DN<6>")
	)
	(arc
		(start 85.10905 -374.48236)
		(mid 85.081633 -374.375473)
		(end 85.077808 -374.26519)
		(width 0.14224)
		(layer "In11.Cu")
		(net "P5E_CPU1_P1_RX_DN<6>")
	)
	(arc
		(start 102.898702 -293.021004)
		(mid 103.055679 -292.716204)
		(end 102.898702 -292.411404)
		(width 0.1143)
		(layer "In11.Cu")
		(net "P5E_CPU1_P1_RX_DN<6>")
	)
	(arc
		(start 102.898702 -289.78098)
		(mid 103.055679 -289.47618)
		(end 102.898702 -289.17138)
		(width 0.1143)
		(layer "In11.Cu")
		(net "P5E_CPU1_P1_RX_DN<6>")
	)
	(arc
		(start 87.986362 -382.342136)
		(mid 87.967342 -382.131346)
		(end 87.910924 -381.927354)
		(width 0.14224)
		(layer "In11.Cu")
		(net "P5E_CPU1_P1_RX_DN<6>")
	)
	(arc
		(start 102.120954 -296.113708)
		(mid 102.166524 -295.88405)
		(end 102.296468 -295.689274)
		(width 0.1143)
		(layer "In11.Cu")
		(net "P5E_CPU1_P1_RX_DN<6>")
	)
	(arc
		(start 103.525828 -277.310088)
		(mid 103.594789 -277.055557)
		(end 103.7717 -276.86)
		(width 0.1143)
		(layer "In11.Cu")
		(net "P5E_CPU1_P1_RX_DN<6>")
	)
	(arc
		(start 102.429818 -279.250648)
		(mid 102.544494 -279.117314)
		(end 102.585774 -278.946356)
		(width 0.1143)
		(layer "In11.Cu")
		(net "P5E_CPU1_P1_RX_DN<6>")
	)
	(arc
		(start 102.900734 -286.53994)
		(mid 103.014663 -286.406793)
		(end 103.055674 -286.23641)
		(width 0.1143)
		(layer "In11.Cu")
		(net "P5E_CPU1_P1_RX_DN<6>")
	)
	(arc
		(start 102.586028 -295.146222)
		(mid 102.650846 -294.883233)
		(end 102.83063 -294.68064)
		(width 0.1143)
		(layer "In11.Cu")
		(net "P5E_CPU1_P1_RX_DN<6>")
	)
	(arc
		(start 102.898702 -278.44115)
		(mid 103.014129 -278.307774)
		(end 103.055674 -278.13635)
		(width 0.1143)
		(layer "In11.Cu")
		(net "P5E_CPU1_P1_RX_DN<6>")
	)
	(arc
		(start 103.374444 -277.626064)
		(mid 103.468361 -277.50098)
		(end 103.521256 -277.353776)
		(width 0.1143)
		(layer "In11.Cu")
		(net "P5E_CPU1_P1_RX_DN<6>")
	)
	(arc
		(start 103.055674 -278.13635)
		(mid 103.120189 -277.874131)
		(end 103.299006 -277.671784)
		(width 0.1143)
		(layer "In11.Cu")
		(net "P5E_CPU1_P1_RX_DN<6>")
	)
	(arc
		(start 102.412546 -295.573196)
		(mid 102.540852 -295.381407)
		(end 102.586028 -295.155112)
		(width 0.1143)
		(layer "In11.Cu")
		(net "P5E_CPU1_P1_RX_DN<6>")
	)
	(arc
		(start 103.055674 -286.23641)
		(mid 103.014125 -286.064988)
		(end 102.898702 -285.93161)
		(width 0.1143)
		(layer "In11.Cu")
		(net "P5E_CPU1_P1_RX_DN<6>")
	)
	(arc
		(start 102.898702 -284.921198)
		(mid 103.055679 -284.616398)
		(end 102.898702 -284.311598)
		(width 0.1143)
		(layer "In11.Cu")
		(net "P5E_CPU1_P1_RX_DN<6>")
	)
	(arc
		(start 103.521256 -277.353776)
		(mid 103.524441 -277.332154)
		(end 103.525828 -277.310342)
		(width 0.1143)
		(layer "In11.Cu")
		(net "P5E_CPU1_P1_RX_DN<6>")
	)
	(arc
		(start 102.829106 -282.650946)
		(mid 102.585779 -282.18638)
		(end 102.829106 -281.721814)
		(width 0.1143)
		(layer "In11.Cu")
		(net "P5E_CPU1_P1_RX_DN<6>")
	)
	(arc
		(start 102.829106 -289.13074)
		(mid 102.585779 -288.666174)
		(end 102.829106 -288.201608)
		(width 0.1143)
		(layer "In11.Cu")
		(net "P5E_CPU1_P1_RX_DN<6>")
	)
	(arc
		(start 103.055674 -287.856422)
		(mid 103.014125 -287.685)
		(end 102.898702 -287.551622)
		(width 0.1143)
		(layer "In11.Cu")
		(net "P5E_CPU1_P1_RX_DN<6>")
	)
	(arc
		(start 103.3653 -277.633176)
		(mid 103.3699 -277.629655)
		(end 103.374444 -277.626064)
		(width 0.1143)
		(layer "In11.Cu")
		(net "P5E_CPU1_P1_RX_DN<6>")
	)
	(arc
		(start 102.898702 -281.681174)
		(mid 103.055679 -281.376374)
		(end 102.898702 -281.071574)
		(width 0.1143)
		(layer "In11.Cu")
		(net "P5E_CPU1_P1_RX_DN<6>")
	)
	(arc
		(start 119.444516 -347.03893)
		(mid 120.081795 -346.461377)
		(end 120.524016 -345.723718)
		(width 0.14224)
		(layer "In11.Cu")
		(net "P5E_CPU1_P1_RX_DN<6>")
	)
	(arc
		(start 102.900734 -288.159952)
		(mid 103.014663 -288.026805)
		(end 103.055674 -287.856422)
		(width 0.1143)
		(layer "In11.Cu")
		(net "P5E_CPU1_P1_RX_DN<6>")
	)
	(arc
		(start 102.585774 -287.046162)
		(mid 102.650289 -286.783943)
		(end 102.829106 -286.581596)
		(width 0.1143)
		(layer "In11.Cu")
		(net "P5E_CPU1_P1_RX_DN<6>")
	)
	(arc
		(start 102.898702 -283.301186)
		(mid 103.055679 -282.996386)
		(end 102.898702 -282.691586)
		(width 0.1143)
		(layer "In11.Cu")
		(net "P5E_CPU1_P1_RX_DN<6>")
	)
	(arc
		(start 102.829106 -293.990776)
		(mid 102.585779 -293.52621)
		(end 102.829106 -293.061644)
		(width 0.1143)
		(layer "In11.Cu")
		(net "P5E_CPU1_P1_RX_DN<6>")
	)
	(arc
		(start 102.829106 -285.89097)
		(mid 102.585779 -285.426404)
		(end 102.829106 -284.961838)
		(width 0.1143)
		(layer "In11.Cu")
		(net "P5E_CPU1_P1_RX_DN<6>")
	)
	(arc
		(start 102.898702 -291.400992)
		(mid 103.055679 -291.096192)
		(end 102.898702 -290.791392)
		(width 0.1143)
		(layer "In11.Cu")
		(net "P5E_CPU1_P1_RX_DN<6>")
	)
	(arc
		(start 102.585774 -280.566368)
		(mid 102.544519 -280.395397)
		(end 102.429818 -280.262076)
		(width 0.1143)
		(layer "In11.Cu")
		(net "P5E_CPU1_P1_RX_DN<6>")
	)
	(segment
		(start 101.268022 -274.630388)
		(end 100.80117 -274.896326)
		(width 0.12954)
		(layer "F.Cu")
		(net "P5E_CPU1_P1_RX_DN<5>")
	)
	(segment
		(start 85.798406 -385.31038)
		(end 86.319106 -385.31038)
		(width 0.127)
		(layer "F.Cu")
		(net "P5E_CPU1_P1_RX_DN<5>")
	)
	(segment
		(start 101.130354 -296.435526)
		(end 101.176074 -296.389806)
		(width 0.1143)
		(layer "In11.Cu")
		(net "P5E_CPU1_P1_RX_DN<5>")
	)
	(segment
		(start 86.320884 -380.721616)
		(end 86.145116 -380.638812)
		(width 0.14224)
		(layer "In11.Cu")
		(net "P5E_CPU1_P1_RX_DN<5>")
	)
	(segment
		(start 86.786466 -383.930906)
		(end 86.786466 -382.374648)
		(width 0.14224)
		(layer "In11.Cu")
		(net "P5E_CPU1_P1_RX_DN<5>")
	)
	(segment
		(start 101.889052 -281.721814)
		(end 101.958648 -281.681174)
		(width 0.1143)
		(layer "In11.Cu")
		(net "P5E_CPU1_P1_RX_DN<5>")
	)
	(segment
		(start 84.563712 -371.893084)
		(end 88.315546 -366.590326)
		(width 0.14224)
		(layer "In11.Cu")
		(net "P5E_CPU1_P1_RX_DN<5>")
	)
	(segment
		(start 101.46411 -280.247344)
		(end 101.462586 -280.246328)
		(width 0.1143)
		(layer "In11.Cu")
		(net "P5E_CPU1_P1_RX_DN<5>")
	)
	(segment
		(start 86.794594 -385.334764)
		(end 86.794594 -385.163822)
		(width 0.14224)
		(layer "In11.Cu")
		(net "P5E_CPU1_P1_RX_DN<5>")
	)
	(segment
		(start 101.419152 -280.221182)
		(end 101.391212 -280.201116)
		(width 0.1143)
		(layer "In11.Cu")
		(net "P5E_CPU1_P1_RX_DN<5>")
	)
	(segment
		(start 86.32063 -380.721616)
		(end 86.320884 -380.721616)
		(width 0.14224)
		(layer "In11.Cu")
		(net "P5E_CPU1_P1_RX_DN<5>")
	)
	(segment
		(start 101.958648 -282.691586)
		(end 101.889052 -282.650946)
		(width 0.1143)
		(layer "In11.Cu")
		(net "P5E_CPU1_P1_RX_DN<5>")
	)
	(segment
		(start 101.458014 -280.243788)
		(end 101.45522 -280.24201)
		(width 0.1143)
		(layer "In11.Cu")
		(net "P5E_CPU1_P1_RX_DN<5>")
	)
	(segment
		(start 85.93963 -379.659896)
		(end 85.763862 -379.577346)
		(width 0.14224)
		(layer "In11.Cu")
		(net "P5E_CPU1_P1_RX_DN<5>")
	)
	(segment
		(start 121.249186 -341.35822)
		(end 121.249186 -338.651088)
		(width 0.14224)
		(layer "In11.Cu")
		(net "P5E_CPU1_P1_RX_DN<5>")
	)
	(segment
		(start 86.083648 -380.061216)
		(end 85.939376 -379.659896)
		(width 0.14224)
		(layer "In11.Cu")
		(net "P5E_CPU1_P1_RX_DN<5>")
	)
	(segment
		(start 85.939376 -379.659896)
		(end 85.93963 -379.659896)
		(width 0.14224)
		(layer "In11.Cu")
		(net "P5E_CPU1_P1_RX_DN<5>")
	)
	(segment
		(start 101.958648 -277.83155)
		(end 101.889052 -277.79091)
		(width 0.1143)
		(layer "In11.Cu")
		(net "P5E_CPU1_P1_RX_DN<5>")
	)
	(segment
		(start 85.763862 -379.577346)
		(end 85.61959 -379.175518)
		(width 0.14224)
		(layer "In11.Cu")
		(net "P5E_CPU1_P1_RX_DN<5>")
	)
	(segment
		(start 85.702394 -378.99975)
		(end 85.5599 -378.603764)
		(width 0.14224)
		(layer "In11.Cu")
		(net "P5E_CPU1_P1_RX_DN<5>")
	)
	(segment
		(start 117.810026 -325.314564)
		(end 111.001556 -317.018416)
		(width 0.14224)
		(layer "In11.Cu")
		(net "P5E_CPU1_P1_RX_DN<5>")
	)
	(segment
		(start 101.458776 -279.268428)
		(end 101.460046 -279.267666)
		(width 0.1143)
		(layer "In11.Cu")
		(net "P5E_CPU1_P1_RX_DN<5>")
	)
	(segment
		(start 101.889052 -286.581596)
		(end 101.891084 -286.580072)
		(width 0.1143)
		(layer "In11.Cu")
		(net "P5E_CPU1_P1_RX_DN<5>")
	)
	(segment
		(start 101.45522 -280.24201)
		(end 101.419152 -280.221182)
		(width 0.1143)
		(layer "In11.Cu")
		(net "P5E_CPU1_P1_RX_DN<5>")
	)
	(segment
		(start 101.181916 -274.97913)
		(end 101.099112 -274.896326)
		(width 0.1143)
		(layer "In11.Cu")
		(net "P5E_CPU1_P1_RX_DN<5>")
	)
	(segment
		(start 86.320884 -380.72187)
		(end 86.32063 -380.721616)
		(width 0.14224)
		(layer "In11.Cu")
		(net "P5E_CPU1_P1_RX_DN<5>")
	)
	(segment
		(start 101.462586 -280.246328)
		(end 101.460046 -280.245058)
		(width 0.1143)
		(layer "In11.Cu")
		(net "P5E_CPU1_P1_RX_DN<5>")
	)
	(segment
		(start 101.889052 -293.061644)
		(end 101.958648 -293.021004)
		(width 0.1143)
		(layer "In11.Cu")
		(net "P5E_CPU1_P1_RX_DN<5>")
	)
	(segment
		(start 86.672928 -385.404868)
		(end 86.794594 -385.334764)
		(width 0.14224)
		(layer "In11.Cu")
		(net "P5E_CPU1_P1_RX_DN<5>")
	)
	(segment
		(start 101.958648 -289.17138)
		(end 101.889052 -289.13074)
		(width 0.1143)
		(layer "In11.Cu")
		(net "P5E_CPU1_P1_RX_DN<5>")
	)
	(segment
		(start 86.666324 -381.683768)
		(end 86.320884 -380.72187)
		(width 0.14224)
		(layer "In11.Cu")
		(net "P5E_CPU1_P1_RX_DN<5>")
	)
	(segment
		(start 101.458268 -279.268428)
		(end 101.458776 -279.268428)
		(width 0.1143)
		(layer "In11.Cu")
		(net "P5E_CPU1_P1_RX_DN<5>")
	)
	(segment
		(start 86.319106 -385.31038)
		(end 86.67242 -385.405376)
		(width 0.14224)
		(layer "In11.Cu")
		(net "P5E_CPU1_P1_RX_DN<5>")
	)
	(segment
		(start 101.889052 -284.961838)
		(end 101.958648 -284.921198)
		(width 0.1143)
		(layer "In11.Cu")
		(net "P5E_CPU1_P1_RX_DN<5>")
	)
	(segment
		(start 84.07908 -374.107202)
		(end 84.183982 -372.927118)
		(width 0.14224)
		(layer "In11.Cu")
		(net "P5E_CPU1_P1_RX_DN<5>")
	)
	(segment
		(start 101.099112 -274.896326)
		(end 100.80117 -274.896326)
		(width 0.1143)
		(layer "In11.Cu")
		(net "P5E_CPU1_P1_RX_DN<5>")
	)
	(segment
		(start 101.889052 -283.341826)
		(end 101.958648 -283.301186)
		(width 0.1143)
		(layer "In11.Cu")
		(net "P5E_CPU1_P1_RX_DN<5>")
	)
	(segment
		(start 101.457252 -275.385022)
		(end 101.456998 -275.385022)
		(width 0.1143)
		(layer "In11.Cu")
		(net "P5E_CPU1_P1_RX_DN<5>")
	)
	(segment
		(start 85.558376 -378.59843)
		(end 85.382608 -378.51588)
		(width 0.14224)
		(layer "In11.Cu")
		(net "P5E_CPU1_P1_RX_DN<5>")
	)
	(segment
		(start 101.489764 -280.262076)
		(end 101.46411 -280.247344)
		(width 0.1143)
		(layer "In11.Cu")
		(net "P5E_CPU1_P1_RX_DN<5>")
	)
	(segment
		(start 85.32114 -377.938538)
		(end 85.318854 -377.93168)
		(width 0.14224)
		(layer "In11.Cu")
		(net "P5E_CPU1_P1_RX_DN<5>")
	)
	(segment
		(start 86.67242 -385.405376)
		(end 86.672928 -385.404868)
		(width 0.14224)
		(layer "In11.Cu")
		(net "P5E_CPU1_P1_RX_DN<5>")
	)
	(segment
		(start 101.889052 -291.441632)
		(end 101.958648 -291.400992)
		(width 0.1143)
		(layer "In11.Cu")
		(net "P5E_CPU1_P1_RX_DN<5>")
	)
	(segment
		(start 86.145116 -380.638812)
		(end 86.000844 -380.236984)
		(width 0.14224)
		(layer "In11.Cu")
		(net "P5E_CPU1_P1_RX_DN<5>")
	)
	(segment
		(start 85.61959 -379.175518)
		(end 85.702394 -379.000004)
		(width 0.14224)
		(layer "In11.Cu")
		(net "P5E_CPU1_P1_RX_DN<5>")
	)
	(segment
		(start 85.238336 -378.114052)
		(end 85.32114 -377.938538)
		(width 0.14224)
		(layer "In11.Cu")
		(net "P5E_CPU1_P1_RX_DN<5>")
	)
	(segment
		(start 101.958648 -290.791392)
		(end 101.889052 -290.750752)
		(width 0.1143)
		(layer "In11.Cu")
		(net "P5E_CPU1_P1_RX_DN<5>")
	)
	(segment
		(start 101.419152 -279.291542)
		(end 101.436424 -279.281636)
		(width 0.1143)
		(layer "In11.Cu")
		(net "P5E_CPU1_P1_RX_DN<5>")
	)
	(segment
		(start 85.318854 -377.93168)
		(end 84.15401 -374.688354)
		(width 0.14224)
		(layer "In11.Cu")
		(net "P5E_CPU1_P1_RX_DN<5>")
	)
	(segment
		(start 101.317552 -295.597834)
		(end 101.432106 -295.48328)
		(width 0.1143)
		(layer "In11.Cu")
		(net "P5E_CPU1_P1_RX_DN<5>")
	)
	(segment
		(start 88.315546 -366.590326)
		(end 91.129866 -364.34268)
		(width 0.14224)
		(layer "In11.Cu")
		(net "P5E_CPU1_P1_RX_DN<5>")
	)
	(segment
		(start 101.889052 -289.82162)
		(end 101.958648 -289.78098)
		(width 0.1143)
		(layer "In11.Cu")
		(net "P5E_CPU1_P1_RX_DN<5>")
	)
	(segment
		(start 101.958648 -285.93161)
		(end 101.889052 -285.89097)
		(width 0.1143)
		(layer "In11.Cu")
		(net "P5E_CPU1_P1_RX_DN<5>")
	)
	(segment
		(start 101.460046 -280.245058)
		(end 101.458776 -280.244296)
		(width 0.1143)
		(layer "In11.Cu")
		(net "P5E_CPU1_P1_RX_DN<5>")
	)
	(segment
		(start 104.839008 -307.795676)
		(end 101.130354 -298.84243)
		(width 0.14224)
		(layer "In11.Cu")
		(net "P5E_CPU1_P1_RX_DN<5>")
	)
	(segment
		(start 101.460046 -279.267666)
		(end 101.489764 -279.250648)
		(width 0.1143)
		(layer "In11.Cu")
		(net "P5E_CPU1_P1_RX_DN<5>")
	)
	(segment
		(start 101.958648 -287.551622)
		(end 101.891592 -287.512506)
		(width 0.1143)
		(layer "In11.Cu")
		(net "P5E_CPU1_P1_RX_DN<5>")
	)
	(segment
		(start 101.461316 -275.387308)
		(end 101.457252 -275.385022)
		(width 0.1143)
		(layer "In11.Cu")
		(net "P5E_CPU1_P1_RX_DN<5>")
	)
	(segment
		(start 121.249186 -338.651088)
		(end 119.39778 -328.35215)
		(width 0.14224)
		(layer "In11.Cu")
		(net "P5E_CPU1_P1_RX_DN<5>")
	)
	(segment
		(start 85.558122 -378.59843)
		(end 85.558376 -378.59843)
		(width 0.14224)
		(layer "In11.Cu")
		(net "P5E_CPU1_P1_RX_DN<5>")
	)
	(segment
		(start 86.000844 -380.236984)
		(end 86.083648 -380.06147)
		(width 0.14224)
		(layer "In11.Cu")
		(net "P5E_CPU1_P1_RX_DN<5>")
	)
	(segment
		(start 101.958648 -292.411404)
		(end 101.889052 -292.370764)
		(width 0.1143)
		(layer "In11.Cu")
		(net "P5E_CPU1_P1_RX_DN<5>")
	)
	(segment
		(start 101.958648 -284.311598)
		(end 101.889052 -284.270958)
		(width 0.1143)
		(layer "In11.Cu")
		(net "P5E_CPU1_P1_RX_DN<5>")
	)
	(segment
		(start 101.958648 -294.031416)
		(end 101.889052 -293.990776)
		(width 0.1143)
		(layer "In11.Cu")
		(net "P5E_CPU1_P1_RX_DN<5>")
	)
	(segment
		(start 119.39778 -328.35215)
		(end 117.810026 -325.314564)
		(width 0.14224)
		(layer "In11.Cu")
		(net "P5E_CPU1_P1_RX_DN<5>")
	)
	(segment
		(start 101.889052 -278.48179)
		(end 101.958648 -278.44115)
		(width 0.1143)
		(layer "In11.Cu")
		(net "P5E_CPU1_P1_RX_DN<5>")
	)
	(segment
		(start 101.436424 -279.281636)
		(end 101.440488 -279.277318)
		(width 0.1143)
		(layer "In11.Cu")
		(net "P5E_CPU1_P1_RX_DN<5>")
	)
	(segment
		(start 101.928168 -286.558736)
		(end 101.96068 -286.53994)
		(width 0.1143)
		(layer "In11.Cu")
		(net "P5E_CPU1_P1_RX_DN<5>")
	)
	(segment
		(start 101.928168 -288.178748)
		(end 101.96068 -288.159952)
		(width 0.1143)
		(layer "In11.Cu")
		(net "P5E_CPU1_P1_RX_DN<5>")
	)
	(segment
		(start 86.482428 -384.234944)
		(end 86.786466 -383.930906)
		(width 0.14224)
		(layer "In11.Cu")
		(net "P5E_CPU1_P1_RX_DN<5>")
	)
	(segment
		(start 101.432106 -295.48328)
		(end 101.461316 -295.466516)
		(width 0.1143)
		(layer "In11.Cu")
		(net "P5E_CPU1_P1_RX_DN<5>")
	)
	(segment
		(start 86.794594 -385.163822)
		(end 86.477602 -384.84683)
		(width 0.14224)
		(layer "In11.Cu")
		(net "P5E_CPU1_P1_RX_DN<5>")
	)
	(segment
		(start 85.702394 -379.000004)
		(end 85.702394 -378.99975)
		(width 0.14224)
		(layer "In11.Cu")
		(net "P5E_CPU1_P1_RX_DN<5>")
	)
	(segment
		(start 91.129866 -364.34268)
		(end 96.801686 -360.994198)
		(width 0.14224)
		(layer "In11.Cu")
		(net "P5E_CPU1_P1_RX_DN<5>")
	)
	(segment
		(start 85.382608 -378.51588)
		(end 85.238336 -378.114052)
		(width 0.14224)
		(layer "In11.Cu")
		(net "P5E_CPU1_P1_RX_DN<5>")
	)
	(segment
		(start 85.5599 -378.603764)
		(end 85.558122 -378.59843)
		(width 0.14224)
		(layer "In11.Cu")
		(net "P5E_CPU1_P1_RX_DN<5>")
	)
	(segment
		(start 101.889052 -288.201608)
		(end 101.928168 -288.178748)
		(width 0.1143)
		(layer "In11.Cu")
		(net "P5E_CPU1_P1_RX_DN<5>")
	)
	(segment
		(start 111.001556 -317.018416)
		(end 104.839008 -307.795676)
		(width 0.14224)
		(layer "In11.Cu")
		(net "P5E_CPU1_P1_RX_DN<5>")
	)
	(segment
		(start 96.801686 -360.994198)
		(end 118.49862 -346.49664)
		(width 0.14224)
		(layer "In11.Cu")
		(net "P5E_CPU1_P1_RX_DN<5>")
	)
	(segment
		(start 119.753888 -344.967052)
		(end 121.249186 -341.35822)
		(width 0.14224)
		(layer "In11.Cu")
		(net "P5E_CPU1_P1_RX_DN<5>")
	)
	(segment
		(start 101.130354 -298.84243)
		(end 101.130354 -296.463974)
		(width 0.14224)
		(layer "In11.Cu")
		(net "P5E_CPU1_P1_RX_DN<5>")
	)
	(segment
		(start 101.889052 -294.681656)
		(end 101.958648 -294.641016)
		(width 0.1143)
		(layer "In11.Cu")
		(net "P5E_CPU1_P1_RX_DN<5>")
	)
	(segment
		(start 86.477602 -384.84683)
		(end 86.482428 -384.234944)
		(width 0.14224)
		(layer "In11.Cu")
		(net "P5E_CPU1_P1_RX_DN<5>")
	)
	(segment
		(start 86.083648 -380.06147)
		(end 86.083648 -380.061216)
		(width 0.14224)
		(layer "In11.Cu")
		(net "P5E_CPU1_P1_RX_DN<5>")
	)
	(segment
		(start 101.130354 -296.463974)
		(end 101.130354 -296.435526)
		(width 0.1143)
		(layer "In11.Cu")
		(net "P5E_CPU1_P1_RX_DN<5>")
	)
	(segment
		(start 101.891084 -286.580072)
		(end 101.928168 -286.558736)
		(width 0.1143)
		(layer "In11.Cu")
		(net "P5E_CPU1_P1_RX_DN<5>")
	)
	(segment
		(start 101.958648 -281.071574)
		(end 101.889052 -281.030934)
		(width 0.1143)
		(layer "In11.Cu")
		(net "P5E_CPU1_P1_RX_DN<5>")
	)
	(segment
		(start 101.958648 -276.211538)
		(end 101.889052 -276.170898)
		(width 0.1143)
		(layer "In11.Cu")
		(net "P5E_CPU1_P1_RX_DN<5>")
	)
	(segment
		(start 101.458776 -280.244296)
		(end 101.458014 -280.243788)
		(width 0.1143)
		(layer "In11.Cu")
		(net "P5E_CPU1_P1_RX_DN<5>")
	)
	(segment
		(start 101.440488 -279.277318)
		(end 101.458268 -279.268428)
		(width 0.1143)
		(layer "In11.Cu")
		(net "P5E_CPU1_P1_RX_DN<5>")
	)
	(segment
		(start 101.391212 -279.311608)
		(end 101.419152 -279.291542)
		(width 0.1143)
		(layer "In11.Cu")
		(net "P5E_CPU1_P1_RX_DN<5>")
	)
	(segment
		(start 101.176074 -296.389806)
		(end 101.176074 -295.939972)
		(width 0.1143)
		(layer "In11.Cu")
		(net "P5E_CPU1_P1_RX_DN<5>")
	)
	(segment
		(start 101.889052 -276.861778)
		(end 101.958648 -276.821138)
		(width 0.1143)
		(layer "In11.Cu")
		(net "P5E_CPU1_P1_RX_DN<5>")
	)
	(arc
		(start 101.958648 -283.301186)
		(mid 102.115625 -282.996386)
		(end 101.958648 -282.691586)
		(width 0.1143)
		(layer "In11.Cu")
		(net "P5E_CPU1_P1_RX_DN<5>")
	)
	(arc
		(start 101.958648 -284.921198)
		(mid 102.115625 -284.616398)
		(end 101.958648 -284.311598)
		(width 0.1143)
		(layer "In11.Cu")
		(net "P5E_CPU1_P1_RX_DN<5>")
	)
	(arc
		(start 101.64572 -275.706332)
		(mid 101.596293 -275.522104)
		(end 101.461316 -275.387308)
		(width 0.1143)
		(layer "In11.Cu")
		(net "P5E_CPU1_P1_RX_DN<5>")
	)
	(arc
		(start 101.889052 -292.370764)
		(mid 101.645725 -291.906198)
		(end 101.889052 -291.441632)
		(width 0.1143)
		(layer "In11.Cu")
		(net "P5E_CPU1_P1_RX_DN<5>")
	)
	(arc
		(start 101.461316 -295.466516)
		(mid 101.586794 -295.341597)
		(end 101.632766 -295.170606)
		(width 0.1143)
		(layer "In11.Cu")
		(net "P5E_CPU1_P1_RX_DN<5>")
	)
	(arc
		(start 101.391212 -280.201116)
		(mid 101.163212 -279.756362)
		(end 101.391212 -279.311608)
		(width 0.1143)
		(layer "In11.Cu")
		(net "P5E_CPU1_P1_RX_DN<5>")
	)
	(arc
		(start 101.891592 -287.512506)
		(mid 101.71094 -287.309761)
		(end 101.64572 -287.046162)
		(width 0.1143)
		(layer "In11.Cu")
		(net "P5E_CPU1_P1_RX_DN<5>")
	)
	(arc
		(start 101.889052 -281.030934)
		(mid 101.710239 -280.828584)
		(end 101.64572 -280.566368)
		(width 0.1143)
		(layer "In11.Cu")
		(net "P5E_CPU1_P1_RX_DN<5>")
	)
	(arc
		(start 118.49862 -346.49664)
		(mid 119.239703 -345.824946)
		(end 119.753888 -344.967052)
		(width 0.14224)
		(layer "In11.Cu")
		(net "P5E_CPU1_P1_RX_DN<5>")
	)
	(arc
		(start 102.11562 -286.23641)
		(mid 102.074071 -286.064988)
		(end 101.958648 -285.93161)
		(width 0.1143)
		(layer "In11.Cu")
		(net "P5E_CPU1_P1_RX_DN<5>")
	)
	(arc
		(start 101.889052 -282.650946)
		(mid 101.645725 -282.18638)
		(end 101.889052 -281.721814)
		(width 0.1143)
		(layer "In11.Cu")
		(net "P5E_CPU1_P1_RX_DN<5>")
	)
	(arc
		(start 86.786466 -382.374648)
		(mid 86.756255 -382.024015)
		(end 86.666324 -381.683768)
		(width 0.14224)
		(layer "In11.Cu")
		(net "P5E_CPU1_P1_RX_DN<5>")
	)
	(arc
		(start 101.889052 -276.170898)
		(mid 101.710239 -275.968548)
		(end 101.64572 -275.706332)
		(width 0.1143)
		(layer "In11.Cu")
		(net "P5E_CPU1_P1_RX_DN<5>")
	)
	(arc
		(start 101.489764 -279.250648)
		(mid 101.60444 -279.117314)
		(end 101.64572 -278.946356)
		(width 0.1143)
		(layer "In11.Cu")
		(net "P5E_CPU1_P1_RX_DN<5>")
	)
	(arc
		(start 84.15401 -374.688354)
		(mid 84.084952 -374.401852)
		(end 84.07908 -374.107202)
		(width 0.14224)
		(layer "In11.Cu")
		(net "P5E_CPU1_P1_RX_DN<5>")
	)
	(arc
		(start 101.958648 -276.821138)
		(mid 102.115625 -276.516338)
		(end 101.958648 -276.211538)
		(width 0.1143)
		(layer "In11.Cu")
		(net "P5E_CPU1_P1_RX_DN<5>")
	)
	(arc
		(start 101.889052 -277.79091)
		(mid 101.645725 -277.326344)
		(end 101.889052 -276.861778)
		(width 0.1143)
		(layer "In11.Cu")
		(net "P5E_CPU1_P1_RX_DN<5>")
	)
	(arc
		(start 101.96068 -286.53994)
		(mid 102.074609 -286.406793)
		(end 102.11562 -286.23641)
		(width 0.1143)
		(layer "In11.Cu")
		(net "P5E_CPU1_P1_RX_DN<5>")
	)
	(arc
		(start 101.456998 -275.385022)
		(mid 101.27312 -275.21348)
		(end 101.181916 -274.97913)
		(width 0.1143)
		(layer "In11.Cu")
		(net "P5E_CPU1_P1_RX_DN<5>")
	)
	(arc
		(start 101.632766 -295.170606)
		(mid 101.70077 -294.894604)
		(end 101.889052 -294.681656)
		(width 0.1143)
		(layer "In11.Cu")
		(net "P5E_CPU1_P1_RX_DN<5>")
	)
	(arc
		(start 102.11562 -287.856422)
		(mid 102.074071 -287.685)
		(end 101.958648 -287.551622)
		(width 0.1143)
		(layer "In11.Cu")
		(net "P5E_CPU1_P1_RX_DN<5>")
	)
	(arc
		(start 101.958648 -289.78098)
		(mid 102.115625 -289.47618)
		(end 101.958648 -289.17138)
		(width 0.1143)
		(layer "In11.Cu")
		(net "P5E_CPU1_P1_RX_DN<5>")
	)
	(arc
		(start 84.183982 -372.927118)
		(mid 84.305289 -372.384921)
		(end 84.563712 -371.893084)
		(width 0.14224)
		(layer "In11.Cu")
		(net "P5E_CPU1_P1_RX_DN<5>")
	)
	(arc
		(start 101.889052 -290.750752)
		(mid 101.645725 -290.286186)
		(end 101.889052 -289.82162)
		(width 0.1143)
		(layer "In11.Cu")
		(net "P5E_CPU1_P1_RX_DN<5>")
	)
	(arc
		(start 101.958648 -293.021004)
		(mid 102.115625 -292.716204)
		(end 101.958648 -292.411404)
		(width 0.1143)
		(layer "In11.Cu")
		(net "P5E_CPU1_P1_RX_DN<5>")
	)
	(arc
		(start 101.889052 -289.13074)
		(mid 101.645725 -288.666174)
		(end 101.889052 -288.201608)
		(width 0.1143)
		(layer "In11.Cu")
		(net "P5E_CPU1_P1_RX_DN<5>")
	)
	(arc
		(start 101.889052 -293.990776)
		(mid 101.645725 -293.52621)
		(end 101.889052 -293.061644)
		(width 0.1143)
		(layer "In11.Cu")
		(net "P5E_CPU1_P1_RX_DN<5>")
	)
	(arc
		(start 101.64572 -287.046162)
		(mid 101.710235 -286.783943)
		(end 101.889052 -286.581596)
		(width 0.1143)
		(layer "In11.Cu")
		(net "P5E_CPU1_P1_RX_DN<5>")
	)
	(arc
		(start 101.958648 -294.641016)
		(mid 102.115625 -294.336216)
		(end 101.958648 -294.031416)
		(width 0.1143)
		(layer "In11.Cu")
		(net "P5E_CPU1_P1_RX_DN<5>")
	)
	(arc
		(start 101.889052 -284.270958)
		(mid 101.645725 -283.806392)
		(end 101.889052 -283.341826)
		(width 0.1143)
		(layer "In11.Cu")
		(net "P5E_CPU1_P1_RX_DN<5>")
	)
	(arc
		(start 101.889052 -285.89097)
		(mid 101.645725 -285.426404)
		(end 101.889052 -284.961838)
		(width 0.1143)
		(layer "In11.Cu")
		(net "P5E_CPU1_P1_RX_DN<5>")
	)
	(arc
		(start 101.958648 -281.681174)
		(mid 102.115625 -281.376374)
		(end 101.958648 -281.071574)
		(width 0.1143)
		(layer "In11.Cu")
		(net "P5E_CPU1_P1_RX_DN<5>")
	)
	(arc
		(start 101.958648 -291.400992)
		(mid 102.115625 -291.096192)
		(end 101.958648 -290.791392)
		(width 0.1143)
		(layer "In11.Cu")
		(net "P5E_CPU1_P1_RX_DN<5>")
	)
	(arc
		(start 101.64572 -278.946356)
		(mid 101.710235 -278.684137)
		(end 101.889052 -278.48179)
		(width 0.1143)
		(layer "In11.Cu")
		(net "P5E_CPU1_P1_RX_DN<5>")
	)
	(arc
		(start 101.96068 -288.159952)
		(mid 102.074609 -288.026805)
		(end 102.11562 -287.856422)
		(width 0.1143)
		(layer "In11.Cu")
		(net "P5E_CPU1_P1_RX_DN<5>")
	)
	(arc
		(start 101.958648 -278.44115)
		(mid 102.115625 -278.13635)
		(end 101.958648 -277.83155)
		(width 0.1143)
		(layer "In11.Cu")
		(net "P5E_CPU1_P1_RX_DN<5>")
	)
	(arc
		(start 101.176074 -295.939972)
		(mid 101.212804 -295.754846)
		(end 101.317552 -295.597834)
		(width 0.1143)
		(layer "In11.Cu")
		(net "P5E_CPU1_P1_RX_DN<5>")
	)
	(arc
		(start 101.64572 -280.566368)
		(mid 101.604465 -280.395397)
		(end 101.489764 -280.262076)
		(width 0.1143)
		(layer "In11.Cu")
		(net "P5E_CPU1_P1_RX_DN<5>")
	)
	(segment
		(start 101.268022 -277.870412)
		(end 100.80117 -278.13635)
		(width 0.12954)
		(layer "F.Cu")
		(net "P5E_CPU1_P1_RX_DN<4>")
	)
	(segment
		(start 84.598256 -385.31038)
		(end 85.118956 -385.31038)
		(width 0.127)
		(layer "F.Cu")
		(net "P5E_CPU1_P1_RX_DN<4>")
	)
	(segment
		(start 100.955094 -286.57804)
		(end 100.955856 -286.57804)
		(width 0.1143)
		(layer "In11.Cu")
		(net "P5E_CPU1_P1_RX_DN<4>")
	)
	(segment
		(start 100.705666 -295.269158)
		(end 100.705666 -295.146222)
		(width 0.1143)
		(layer "In11.Cu")
		(net "P5E_CPU1_P1_RX_DN<4>")
	)
	(segment
		(start 100.948998 -288.201608)
		(end 101.021642 -288.15919)
		(width 0.1143)
		(layer "In11.Cu")
		(net "P5E_CPU1_P1_RX_DN<4>")
	)
	(segment
		(start 100.988114 -284.293818)
		(end 100.948998 -284.270958)
		(width 0.1143)
		(layer "In11.Cu")
		(net "P5E_CPU1_P1_RX_DN<4>")
	)
	(segment
		(start 100.948998 -289.82162)
		(end 100.985574 -289.800284)
		(width 0.1143)
		(layer "In11.Cu")
		(net "P5E_CPU1_P1_RX_DN<4>")
	)
	(segment
		(start 118.485666 -328.620374)
		(end 117.028722 -325.832724)
		(width 0.14224)
		(layer "In11.Cu")
		(net "P5E_CPU1_P1_RX_DN<4>")
	)
	(segment
		(start 110.25378 -317.577724)
		(end 104.011984 -308.23662)
		(width 0.14224)
		(layer "In11.Cu")
		(net "P5E_CPU1_P1_RX_DN<4>")
	)
	(segment
		(start 100.988114 -284.938978)
		(end 101.019864 -284.92069)
		(width 0.1143)
		(layer "In11.Cu")
		(net "P5E_CPU1_P1_RX_DN<4>")
	)
	(segment
		(start 100.948998 -284.961838)
		(end 100.988114 -284.938978)
		(width 0.1143)
		(layer "In11.Cu")
		(net "P5E_CPU1_P1_RX_DN<4>")
	)
	(segment
		(start 100.988876 -292.394132)
		(end 100.988114 -292.393624)
		(width 0.1143)
		(layer "In11.Cu")
		(net "P5E_CPU1_P1_RX_DN<4>")
	)
	(segment
		(start 87.339932 -365.122714)
		(end 87.52713 -365.174276)
		(width 0.14224)
		(layer "In11.Cu")
		(net "P5E_CPU1_P1_RX_DN<4>")
	)
	(segment
		(start 85.988652 -365.89208)
		(end 86.359746 -365.680752)
		(width 0.14224)
		(layer "In11.Cu")
		(net "P5E_CPU1_P1_RX_DN<4>")
	)
	(segment
		(start 100.94976 -294.681148)
		(end 101.010974 -294.645842)
		(width 0.1143)
		(layer "In11.Cu")
		(net "P5E_CPU1_P1_RX_DN<4>")
	)
	(segment
		(start 85.472778 -385.404868)
		(end 85.594444 -385.334764)
		(width 0.14224)
		(layer "In11.Cu")
		(net "P5E_CPU1_P1_RX_DN<4>")
	)
	(segment
		(start 100.988114 -289.79876)
		(end 100.988876 -289.798252)
		(width 0.1143)
		(layer "In11.Cu")
		(net "P5E_CPU1_P1_RX_DN<4>")
	)
	(segment
		(start 120.305576 -341.150702)
		(end 120.305576 -338.743798)
		(width 0.14224)
		(layer "In11.Cu")
		(net "P5E_CPU1_P1_RX_DN<4>")
	)
	(segment
		(start 100.98405 -285.91129)
		(end 100.983542 -285.911036)
		(width 0.1143)
		(layer "In11.Cu")
		(net "P5E_CPU1_P1_RX_DN<4>")
	)
	(segment
		(start 104.011984 -308.23662)
		(end 100.18522 -298.997624)
		(width 0.14224)
		(layer "In11.Cu")
		(net "P5E_CPU1_P1_RX_DN<4>")
	)
	(segment
		(start 100.988876 -291.418264)
		(end 101.019864 -291.400484)
		(width 0.1143)
		(layer "In11.Cu")
		(net "P5E_CPU1_P1_RX_DN<4>")
	)
	(segment
		(start 85.47227 -385.405376)
		(end 85.472778 -385.404868)
		(width 0.14224)
		(layer "In11.Cu")
		(net "P5E_CPU1_P1_RX_DN<4>")
	)
	(segment
		(start 100.948236 -294.682164)
		(end 100.94849 -294.68191)
		(width 0.1143)
		(layer "In11.Cu")
		(net "P5E_CPU1_P1_RX_DN<4>")
	)
	(segment
		(start 100.987098 -291.41928)
		(end 100.988114 -291.418772)
		(width 0.1143)
		(layer "In11.Cu")
		(net "P5E_CPU1_P1_RX_DN<4>")
	)
	(segment
		(start 100.989892 -287.534858)
		(end 100.987098 -287.533334)
		(width 0.1143)
		(layer "In11.Cu")
		(net "P5E_CPU1_P1_RX_DN<4>")
	)
	(segment
		(start 100.984812 -285.911798)
		(end 100.98405 -285.91129)
		(width 0.1143)
		(layer "In11.Cu")
		(net "P5E_CPU1_P1_RX_DN<4>")
	)
	(segment
		(start 100.988876 -290.77412)
		(end 100.988114 -290.773612)
		(width 0.1143)
		(layer "In11.Cu")
		(net "P5E_CPU1_P1_RX_DN<4>")
	)
	(segment
		(start 100.956618 -293.995348)
		(end 100.955856 -293.99484)
		(width 0.1143)
		(layer "In11.Cu")
		(net "P5E_CPU1_P1_RX_DN<4>")
	)
	(segment
		(start 100.988114 -291.418772)
		(end 100.988876 -291.418264)
		(width 0.1143)
		(layer "In11.Cu")
		(net "P5E_CPU1_P1_RX_DN<4>")
	)
	(segment
		(start 100.548694 -280.261568)
		(end 100.479098 -280.220928)
		(width 0.1143)
		(layer "In11.Cu")
		(net "P5E_CPU1_P1_RX_DN<4>")
	)
	(segment
		(start 100.988876 -294.014144)
		(end 100.988114 -294.013636)
		(width 0.1143)
		(layer "In11.Cu")
		(net "P5E_CPU1_P1_RX_DN<4>")
	)
	(segment
		(start 79.283814 -373.369332)
		(end 83.230212 -367.752122)
		(width 0.14224)
		(layer "In11.Cu")
		(net "P5E_CPU1_P1_RX_DN<4>")
	)
	(segment
		(start 100.987098 -293.039292)
		(end 100.988114 -293.038784)
		(width 0.1143)
		(layer "In11.Cu")
		(net "P5E_CPU1_P1_RX_DN<4>")
	)
	(segment
		(start 100.988114 -294.013636)
		(end 100.956618 -293.995348)
		(width 0.1143)
		(layer "In11.Cu")
		(net "P5E_CPU1_P1_RX_DN<4>")
	)
	(segment
		(start 100.479098 -279.291796)
		(end 100.548694 -279.251156)
		(width 0.1143)
		(layer "In11.Cu")
		(net "P5E_CPU1_P1_RX_DN<4>")
	)
	(segment
		(start 100.98278 -285.910528)
		(end 100.94976 -285.891478)
		(width 0.1143)
		(layer "In11.Cu")
		(net "P5E_CPU1_P1_RX_DN<4>")
	)
	(segment
		(start 101.168962 -278.2062)
		(end 101.099112 -278.13635)
		(width 0.1143)
		(layer "In11.Cu")
		(net "P5E_CPU1_P1_RX_DN<4>")
	)
	(segment
		(start 100.988114 -283.318966)
		(end 101.019864 -283.300678)
		(width 0.1143)
		(layer "In11.Cu")
		(net "P5E_CPU1_P1_RX_DN<4>")
	)
	(segment
		(start 85.008466 -366.449864)
		(end 85.37956 -366.23879)
		(width 0.14224)
		(layer "In11.Cu")
		(net "P5E_CPU1_P1_RX_DN<4>")
	)
	(segment
		(start 86.359746 -365.680752)
		(end 86.54669 -365.732314)
		(width 0.14224)
		(layer "In11.Cu")
		(net "P5E_CPU1_P1_RX_DN<4>")
	)
	(segment
		(start 100.948998 -293.061644)
		(end 100.985574 -293.040308)
		(width 0.1143)
		(layer "In11.Cu")
		(net "P5E_CPU1_P1_RX_DN<4>")
	)
	(segment
		(start 83.515962 -367.457736)
		(end 83.516978 -367.456974)
		(width 0.14224)
		(layer "In11.Cu")
		(net "P5E_CPU1_P1_RX_DN<4>")
	)
	(segment
		(start 85.566504 -366.290352)
		(end 85.937344 -366.079278)
		(width 0.14224)
		(layer "In11.Cu")
		(net "P5E_CPU1_P1_RX_DN<4>")
	)
	(segment
		(start 100.987098 -287.533334)
		(end 100.983288 -287.531048)
		(width 0.1143)
		(layer "In11.Cu")
		(net "P5E_CPU1_P1_RX_DN<4>")
	)
	(segment
		(start 100.18522 -296.435526)
		(end 100.23094 -296.389806)
		(width 0.1143)
		(layer "In11.Cu")
		(net "P5E_CPU1_P1_RX_DN<4>")
	)
	(segment
		(start 100.955856 -292.374828)
		(end 100.948998 -292.370764)
		(width 0.1143)
		(layer "In11.Cu")
		(net "P5E_CPU1_P1_RX_DN<4>")
	)
	(segment
		(start 100.948998 -281.721814)
		(end 100.988114 -281.698954)
		(width 0.1143)
		(layer "In11.Cu")
		(net "P5E_CPU1_P1_RX_DN<4>")
	)
	(segment
		(start 100.988114 -289.1536)
		(end 100.956618 -289.135312)
		(width 0.1143)
		(layer "In11.Cu")
		(net "P5E_CPU1_P1_RX_DN<4>")
	)
	(segment
		(start 101.019864 -282.692094)
		(end 100.988114 -282.673806)
		(width 0.1143)
		(layer "In11.Cu")
		(net "P5E_CPU1_P1_RX_DN<4>")
	)
	(segment
		(start 100.985574 -291.420296)
		(end 100.987098 -291.41928)
		(width 0.1143)
		(layer "In11.Cu")
		(net "P5E_CPU1_P1_RX_DN<4>")
	)
	(segment
		(start 100.988114 -293.038784)
		(end 100.988876 -293.038276)
		(width 0.1143)
		(layer "In11.Cu")
		(net "P5E_CPU1_P1_RX_DN<4>")
	)
	(segment
		(start 100.955856 -287.515046)
		(end 100.951538 -287.512506)
		(width 0.1143)
		(layer "In11.Cu")
		(net "P5E_CPU1_P1_RX_DN<4>")
	)
	(segment
		(start 100.98405 -286.56153)
		(end 100.986082 -286.56026)
		(width 0.1143)
		(layer "In11.Cu")
		(net "P5E_CPU1_P1_RX_DN<4>")
	)
	(segment
		(start 100.18522 -298.997624)
		(end 100.18522 -296.463974)
		(width 0.14224)
		(layer "In11.Cu")
		(net "P5E_CPU1_P1_RX_DN<4>")
	)
	(segment
		(start 100.955856 -293.99484)
		(end 100.948998 -293.990776)
		(width 0.1143)
		(layer "In11.Cu")
		(net "P5E_CPU1_P1_RX_DN<4>")
	)
	(segment
		(start 100.985574 -293.040308)
		(end 100.987098 -293.039292)
		(width 0.1143)
		(layer "In11.Cu")
		(net "P5E_CPU1_P1_RX_DN<4>")
	)
	(segment
		(start 100.956618 -289.135312)
		(end 100.955856 -289.134804)
		(width 0.1143)
		(layer "In11.Cu")
		(net "P5E_CPU1_P1_RX_DN<4>")
	)
	(segment
		(start 87.52713 -365.174276)
		(end 96.458278 -360.090212)
		(width 0.14224)
		(layer "In11.Cu")
		(net "P5E_CPU1_P1_RX_DN<4>")
	)
	(segment
		(start 85.282278 -384.234944)
		(end 85.586316 -383.93116)
		(width 0.14224)
		(layer "In11.Cu")
		(net "P5E_CPU1_P1_RX_DN<4>")
	)
	(segment
		(start 100.989384 -285.914338)
		(end 100.984812 -285.911798)
		(width 0.1143)
		(layer "In11.Cu")
		(net "P5E_CPU1_P1_RX_DN<4>")
	)
	(segment
		(start 100.18522 -296.463974)
		(end 100.18522 -296.435526)
		(width 0.1143)
		(layer "In11.Cu")
		(net "P5E_CPU1_P1_RX_DN<4>")
	)
	(segment
		(start 100.955856 -290.754816)
		(end 100.948998 -290.750752)
		(width 0.1143)
		(layer "In11.Cu")
		(net "P5E_CPU1_P1_RX_DN<4>")
	)
	(segment
		(start 85.586316 -383.93116)
		(end 85.586316 -381.704342)
		(width 0.14224)
		(layer "In11.Cu")
		(net "P5E_CPU1_P1_RX_DN<4>")
	)
	(segment
		(start 79.277464 -374.43537)
		(end 79.202534 -373.679212)
		(width 0.14224)
		(layer "In11.Cu")
		(net "P5E_CPU1_P1_RX_DN<4>")
	)
	(segment
		(start 100.988876 -289.798252)
		(end 101.019864 -289.780472)
		(width 0.1143)
		(layer "In11.Cu")
		(net "P5E_CPU1_P1_RX_DN<4>")
	)
	(segment
		(start 100.956618 -287.515554)
		(end 100.955856 -287.515046)
		(width 0.1143)
		(layer "In11.Cu")
		(net "P5E_CPU1_P1_RX_DN<4>")
	)
	(segment
		(start 100.955856 -286.57804)
		(end 100.983288 -286.562038)
		(width 0.1143)
		(layer "In11.Cu")
		(net "P5E_CPU1_P1_RX_DN<4>")
	)
	(segment
		(start 101.019864 -292.411912)
		(end 100.988876 -292.394132)
		(width 0.1143)
		(layer "In11.Cu")
		(net "P5E_CPU1_P1_RX_DN<4>")
	)
	(segment
		(start 101.019864 -281.072082)
		(end 100.988114 -281.053794)
		(width 0.1143)
		(layer "In11.Cu")
		(net "P5E_CPU1_P1_RX_DN<4>")
	)
	(segment
		(start 101.02215 -294.033448)
		(end 101.019864 -294.031924)
		(width 0.1143)
		(layer "In11.Cu")
		(net "P5E_CPU1_P1_RX_DN<4>")
	)
	(segment
		(start 96.458278 -360.090212)
		(end 117.697504 -345.89847)
		(width 0.14224)
		(layer "In11.Cu")
		(net "P5E_CPU1_P1_RX_DN<4>")
	)
	(segment
		(start 100.988114 -292.393624)
		(end 100.956618 -292.375336)
		(width 0.1143)
		(layer "In11.Cu")
		(net "P5E_CPU1_P1_RX_DN<4>")
	)
	(segment
		(start 100.988114 -281.698954)
		(end 101.019864 -281.680666)
		(width 0.1143)
		(layer "In11.Cu")
		(net "P5E_CPU1_P1_RX_DN<4>")
	)
	(segment
		(start 85.527896 -381.551688)
		(end 79.321152 -374.600724)
		(width 0.14224)
		(layer "In11.Cu")
		(net "P5E_CPU1_P1_RX_DN<4>")
	)
	(segment
		(start 101.019864 -290.7919)
		(end 100.988876 -290.77412)
		(width 0.1143)
		(layer "In11.Cu")
		(net "P5E_CPU1_P1_RX_DN<4>")
	)
	(segment
		(start 100.983288 -286.562038)
		(end 100.98405 -286.56153)
		(width 0.1143)
		(layer "In11.Cu")
		(net "P5E_CPU1_P1_RX_DN<4>")
	)
	(segment
		(start 100.988876 -289.154108)
		(end 100.988114 -289.1536)
		(width 0.1143)
		(layer "In11.Cu")
		(net "P5E_CPU1_P1_RX_DN<4>")
	)
	(segment
		(start 100.985574 -289.800284)
		(end 100.987098 -289.799268)
		(width 0.1143)
		(layer "In11.Cu")
		(net "P5E_CPU1_P1_RX_DN<4>")
	)
	(segment
		(start 101.019864 -284.312106)
		(end 100.988114 -284.293818)
		(width 0.1143)
		(layer "In11.Cu")
		(net "P5E_CPU1_P1_RX_DN<4>")
	)
	(segment
		(start 100.988114 -281.053794)
		(end 100.948998 -281.030934)
		(width 0.1143)
		(layer "In11.Cu")
		(net "P5E_CPU1_P1_RX_DN<4>")
	)
	(segment
		(start 100.955856 -289.134804)
		(end 100.948998 -289.13074)
		(width 0.1143)
		(layer "In11.Cu")
		(net "P5E_CPU1_P1_RX_DN<4>")
	)
	(segment
		(start 100.988876 -293.038276)
		(end 101.019864 -293.020496)
		(width 0.1143)
		(layer "In11.Cu")
		(net "P5E_CPU1_P1_RX_DN<4>")
	)
	(segment
		(start 85.594444 -385.163822)
		(end 85.277452 -384.84683)
		(width 0.14224)
		(layer "In11.Cu")
		(net "P5E_CPU1_P1_RX_DN<4>")
	)
	(segment
		(start 86.91753 -365.52124)
		(end 86.968838 -365.334042)
		(width 0.14224)
		(layer "In11.Cu")
		(net "P5E_CPU1_P1_RX_DN<4>")
	)
	(segment
		(start 101.019864 -294.031924)
		(end 100.988876 -294.014144)
		(width 0.1143)
		(layer "In11.Cu")
		(net "P5E_CPU1_P1_RX_DN<4>")
	)
	(segment
		(start 86.968838 -365.334042)
		(end 87.339932 -365.122714)
		(width 0.14224)
		(layer "In11.Cu")
		(net "P5E_CPU1_P1_RX_DN<4>")
	)
	(segment
		(start 84.957158 -366.637316)
		(end 85.008466 -366.449864)
		(width 0.14224)
		(layer "In11.Cu")
		(net "P5E_CPU1_P1_RX_DN<4>")
	)
	(segment
		(start 101.010974 -294.645842)
		(end 101.02215 -294.638984)
		(width 0.1143)
		(layer "In11.Cu")
		(net "P5E_CPU1_P1_RX_DN<4>")
	)
	(segment
		(start 100.982526 -287.53054)
		(end 100.956618 -287.515554)
		(width 0.1143)
		(layer "In11.Cu")
		(net "P5E_CPU1_P1_RX_DN<4>")
	)
	(segment
		(start 100.948998 -291.441632)
		(end 100.985574 -291.420296)
		(width 0.1143)
		(layer "In11.Cu")
		(net "P5E_CPU1_P1_RX_DN<4>")
	)
	(segment
		(start 100.988114 -282.673806)
		(end 100.948998 -282.650946)
		(width 0.1143)
		(layer "In11.Cu")
		(net "P5E_CPU1_P1_RX_DN<4>")
	)
	(segment
		(start 100.948998 -286.581596)
		(end 100.955094 -286.57804)
		(width 0.1143)
		(layer "In11.Cu")
		(net "P5E_CPU1_P1_RX_DN<4>")
	)
	(segment
		(start 100.948998 -283.341826)
		(end 100.951792 -283.339794)
		(width 0.1143)
		(layer "In11.Cu")
		(net "P5E_CPU1_P1_RX_DN<4>")
	)
	(segment
		(start 100.323904 -295.703498)
		(end 100.668328 -295.359074)
		(width 0.1143)
		(layer "In11.Cu")
		(net "P5E_CPU1_P1_RX_DN<4>")
	)
	(segment
		(start 86.54669 -365.732314)
		(end 86.91753 -365.52124)
		(width 0.14224)
		(layer "In11.Cu")
		(net "P5E_CPU1_P1_RX_DN<4>")
	)
	(segment
		(start 100.987098 -289.799268)
		(end 100.988114 -289.79876)
		(width 0.1143)
		(layer "In11.Cu")
		(net "P5E_CPU1_P1_RX_DN<4>")
	)
	(segment
		(start 100.23094 -296.389806)
		(end 100.23094 -295.928542)
		(width 0.1143)
		(layer "In11.Cu")
		(net "P5E_CPU1_P1_RX_DN<4>")
	)
	(segment
		(start 85.118956 -385.31038)
		(end 85.47227 -385.405376)
		(width 0.14224)
		(layer "In11.Cu")
		(net "P5E_CPU1_P1_RX_DN<4>")
	)
	(segment
		(start 120.305576 -338.743798)
		(end 118.485666 -328.620374)
		(width 0.14224)
		(layer "In11.Cu")
		(net "P5E_CPU1_P1_RX_DN<4>")
	)
	(segment
		(start 83.516978 -367.456974)
		(end 84.957158 -366.637316)
		(width 0.14224)
		(layer "In11.Cu")
		(net "P5E_CPU1_P1_RX_DN<4>")
	)
	(segment
		(start 117.028722 -325.832724)
		(end 110.25378 -317.577724)
		(width 0.14224)
		(layer "In11.Cu")
		(net "P5E_CPU1_P1_RX_DN<4>")
	)
	(segment
		(start 100.951792 -283.339794)
		(end 100.988114 -283.318966)
		(width 0.1143)
		(layer "In11.Cu")
		(net "P5E_CPU1_P1_RX_DN<4>")
	)
	(segment
		(start 85.277452 -384.84683)
		(end 85.282278 -384.234944)
		(width 0.14224)
		(layer "In11.Cu")
		(net "P5E_CPU1_P1_RX_DN<4>")
	)
	(segment
		(start 100.986082 -286.56026)
		(end 100.98913 -286.558482)
		(width 0.1143)
		(layer "In11.Cu")
		(net "P5E_CPU1_P1_RX_DN<4>")
	)
	(segment
		(start 100.956618 -292.375336)
		(end 100.955856 -292.374828)
		(width 0.1143)
		(layer "In11.Cu")
		(net "P5E_CPU1_P1_RX_DN<4>")
	)
	(segment
		(start 100.983542 -285.911036)
		(end 100.98278 -285.910528)
		(width 0.1143)
		(layer "In11.Cu")
		(net "P5E_CPU1_P1_RX_DN<4>")
	)
	(segment
		(start 100.988114 -290.773612)
		(end 100.956618 -290.755324)
		(width 0.1143)
		(layer "In11.Cu")
		(net "P5E_CPU1_P1_RX_DN<4>")
	)
	(segment
		(start 118.992396 -344.320368)
		(end 120.305576 -341.150702)
		(width 0.14224)
		(layer "In11.Cu")
		(net "P5E_CPU1_P1_RX_DN<4>")
	)
	(segment
		(start 85.594444 -385.334764)
		(end 85.594444 -385.163822)
		(width 0.14224)
		(layer "In11.Cu")
		(net "P5E_CPU1_P1_RX_DN<4>")
	)
	(segment
		(start 100.983288 -287.531048)
		(end 100.982526 -287.53054)
		(width 0.1143)
		(layer "In11.Cu")
		(net "P5E_CPU1_P1_RX_DN<4>")
	)
	(segment
		(start 100.98278 -278.463502)
		(end 100.988876 -278.459946)
		(width 0.1143)
		(layer "In11.Cu")
		(net "P5E_CPU1_P1_RX_DN<4>")
	)
	(segment
		(start 101.099112 -278.13635)
		(end 100.80117 -278.13635)
		(width 0.1143)
		(layer "In11.Cu")
		(net "P5E_CPU1_P1_RX_DN<4>")
	)
	(segment
		(start 85.937344 -366.079278)
		(end 85.988652 -365.89208)
		(width 0.14224)
		(layer "In11.Cu")
		(net "P5E_CPU1_P1_RX_DN<4>")
	)
	(segment
		(start 85.37956 -366.23879)
		(end 85.566504 -366.290352)
		(width 0.14224)
		(layer "In11.Cu")
		(net "P5E_CPU1_P1_RX_DN<4>")
	)
	(segment
		(start 101.019864 -289.171888)
		(end 100.988876 -289.154108)
		(width 0.1143)
		(layer "In11.Cu")
		(net "P5E_CPU1_P1_RX_DN<4>")
	)
	(segment
		(start 100.956618 -290.755324)
		(end 100.955856 -290.754816)
		(width 0.1143)
		(layer "In11.Cu")
		(net "P5E_CPU1_P1_RX_DN<4>")
	)
	(arc
		(start 100.23094 -295.928542)
		(mid 100.255049 -295.806778)
		(end 100.323904 -295.703498)
		(width 0.1143)
		(layer "In11.Cu")
		(net "P5E_CPU1_P1_RX_DN<4>")
	)
	(arc
		(start 100.668328 -295.359074)
		(mid 100.695976 -295.317835)
		(end 100.705666 -295.269158)
		(width 0.1143)
		(layer "In11.Cu")
		(net "P5E_CPU1_P1_RX_DN<4>")
	)
	(arc
		(start 100.948998 -292.370764)
		(mid 100.705671 -291.906198)
		(end 100.948998 -291.441632)
		(width 0.1143)
		(layer "In11.Cu")
		(net "P5E_CPU1_P1_RX_DN<4>")
	)
	(arc
		(start 100.948998 -282.650946)
		(mid 100.705671 -282.18638)
		(end 100.948998 -281.721814)
		(width 0.1143)
		(layer "In11.Cu")
		(net "P5E_CPU1_P1_RX_DN<4>")
	)
	(arc
		(start 79.200248 -373.638572)
		(mid 79.220896 -373.497392)
		(end 79.283814 -373.369332)
		(width 0.14224)
		(layer "In11.Cu")
		(net "P5E_CPU1_P1_RX_DN<4>")
	)
	(arc
		(start 100.951538 -287.512506)
		(mid 100.770886 -287.309761)
		(end 100.705666 -287.046162)
		(width 0.1143)
		(layer "In11.Cu")
		(net "P5E_CPU1_P1_RX_DN<4>")
	)
	(arc
		(start 100.705666 -278.946356)
		(mid 100.779861 -278.667985)
		(end 100.98278 -278.463502)
		(width 0.1143)
		(layer "In11.Cu")
		(net "P5E_CPU1_P1_RX_DN<4>")
	)
	(arc
		(start 100.548694 -279.251156)
		(mid 100.664121 -279.11778)
		(end 100.705666 -278.946356)
		(width 0.1143)
		(layer "In11.Cu")
		(net "P5E_CPU1_P1_RX_DN<4>")
	)
	(arc
		(start 101.019864 -291.400484)
		(mid 101.171453 -291.096192)
		(end 101.019864 -290.7919)
		(width 0.1143)
		(layer "In11.Cu")
		(net "P5E_CPU1_P1_RX_DN<4>")
	)
	(arc
		(start 101.17582 -287.856422)
		(mid 101.125997 -287.670692)
		(end 100.989892 -287.534858)
		(width 0.1143)
		(layer "In11.Cu")
		(net "P5E_CPU1_P1_RX_DN<4>")
	)
	(arc
		(start 100.705666 -280.566368)
		(mid 100.664117 -280.394946)
		(end 100.548694 -280.261568)
		(width 0.1143)
		(layer "In11.Cu")
		(net "P5E_CPU1_P1_RX_DN<4>")
	)
	(arc
		(start 79.321152 -374.600724)
		(mid 79.292725 -374.519788)
		(end 79.277464 -374.43537)
		(width 0.14224)
		(layer "In11.Cu")
		(net "P5E_CPU1_P1_RX_DN<4>")
	)
	(arc
		(start 100.94976 -285.891478)
		(mid 100.949379 -285.891224)
		(end 100.948998 -285.89097)
		(width 0.1143)
		(layer "In11.Cu")
		(net "P5E_CPU1_P1_RX_DN<4>")
	)
	(arc
		(start 100.948998 -281.030934)
		(mid 100.770185 -280.828584)
		(end 100.705666 -280.566368)
		(width 0.1143)
		(layer "In11.Cu")
		(net "P5E_CPU1_P1_RX_DN<4>")
	)
	(arc
		(start 101.019864 -293.020496)
		(mid 101.171453 -292.716204)
		(end 101.019864 -292.411912)
		(width 0.1143)
		(layer "In11.Cu")
		(net "P5E_CPU1_P1_RX_DN<4>")
	)
	(arc
		(start 101.021642 -288.15919)
		(mid 101.135049 -288.026301)
		(end 101.17582 -287.856422)
		(width 0.1143)
		(layer "In11.Cu")
		(net "P5E_CPU1_P1_RX_DN<4>")
	)
	(arc
		(start 101.019864 -283.300678)
		(mid 101.174532 -282.996386)
		(end 101.019864 -282.692094)
		(width 0.1143)
		(layer "In11.Cu")
		(net "P5E_CPU1_P1_RX_DN<4>")
	)
	(arc
		(start 100.948998 -290.750752)
		(mid 100.705671 -290.286186)
		(end 100.948998 -289.82162)
		(width 0.1143)
		(layer "In11.Cu")
		(net "P5E_CPU1_P1_RX_DN<4>")
	)
	(arc
		(start 100.705666 -287.046162)
		(mid 100.770181 -286.783943)
		(end 100.948998 -286.581596)
		(width 0.1143)
		(layer "In11.Cu")
		(net "P5E_CPU1_P1_RX_DN<4>")
	)
	(arc
		(start 100.479098 -280.220928)
		(mid 100.235771 -279.756362)
		(end 100.479098 -279.291796)
		(width 0.1143)
		(layer "In11.Cu")
		(net "P5E_CPU1_P1_RX_DN<4>")
	)
	(arc
		(start 79.202534 -373.679212)
		(mid 79.200937 -373.658917)
		(end 79.200248 -373.638572)
		(width 0.14224)
		(layer "In11.Cu")
		(net "P5E_CPU1_P1_RX_DN<4>")
	)
	(arc
		(start 101.02215 -294.638984)
		(mid 101.171723 -294.336216)
		(end 101.02215 -294.033448)
		(width 0.1143)
		(layer "In11.Cu")
		(net "P5E_CPU1_P1_RX_DN<4>")
	)
	(arc
		(start 100.705666 -295.146222)
		(mid 100.770041 -294.884461)
		(end 100.948236 -294.682164)
		(width 0.1143)
		(layer "In11.Cu")
		(net "P5E_CPU1_P1_RX_DN<4>")
	)
	(arc
		(start 101.019864 -284.92069)
		(mid 101.168961 -284.616398)
		(end 101.019864 -284.312106)
		(width 0.1143)
		(layer "In11.Cu")
		(net "P5E_CPU1_P1_RX_DN<4>")
	)
	(arc
		(start 117.697504 -345.89847)
		(mid 118.462009 -345.205466)
		(end 118.992396 -344.320368)
		(width 0.14224)
		(layer "In11.Cu")
		(net "P5E_CPU1_P1_RX_DN<4>")
	)
	(arc
		(start 100.98913 -286.558482)
		(mid 101.174582 -286.23652)
		(end 100.989384 -285.914338)
		(width 0.1143)
		(layer "In11.Cu")
		(net "P5E_CPU1_P1_RX_DN<4>")
	)
	(arc
		(start 100.94849 -294.68191)
		(mid 100.949125 -294.681529)
		(end 100.94976 -294.681148)
		(width 0.1143)
		(layer "In11.Cu")
		(net "P5E_CPU1_P1_RX_DN<4>")
	)
	(arc
		(start 100.988876 -278.459946)
		(mid 101.106641 -278.352755)
		(end 101.168962 -278.2062)
		(width 0.1143)
		(layer "In11.Cu")
		(net "P5E_CPU1_P1_RX_DN<4>")
	)
	(arc
		(start 101.019864 -281.680666)
		(mid 101.171453 -281.376374)
		(end 101.019864 -281.072082)
		(width 0.1143)
		(layer "In11.Cu")
		(net "P5E_CPU1_P1_RX_DN<4>")
	)
	(arc
		(start 100.948998 -289.13074)
		(mid 100.705671 -288.666174)
		(end 100.948998 -288.201608)
		(width 0.1143)
		(layer "In11.Cu")
		(net "P5E_CPU1_P1_RX_DN<4>")
	)
	(arc
		(start 100.948998 -284.270958)
		(mid 100.705671 -283.806392)
		(end 100.948998 -283.341826)
		(width 0.1143)
		(layer "In11.Cu")
		(net "P5E_CPU1_P1_RX_DN<4>")
	)
	(arc
		(start 85.586316 -381.704342)
		(mid 85.571133 -381.622644)
		(end 85.527896 -381.551688)
		(width 0.14224)
		(layer "In11.Cu")
		(net "P5E_CPU1_P1_RX_DN<4>")
	)
	(arc
		(start 100.948998 -293.990776)
		(mid 100.705671 -293.52621)
		(end 100.948998 -293.061644)
		(width 0.1143)
		(layer "In11.Cu")
		(net "P5E_CPU1_P1_RX_DN<4>")
	)
	(arc
		(start 100.948998 -285.89097)
		(mid 100.705671 -285.426404)
		(end 100.948998 -284.961838)
		(width 0.1143)
		(layer "In11.Cu")
		(net "P5E_CPU1_P1_RX_DN<4>")
	)
	(arc
		(start 83.230212 -367.752122)
		(mid 83.361478 -367.593661)
		(end 83.515962 -367.457736)
		(width 0.14224)
		(layer "In11.Cu")
		(net "P5E_CPU1_P1_RX_DN<4>")
	)
	(arc
		(start 101.019864 -289.780472)
		(mid 101.168961 -289.47618)
		(end 101.019864 -289.171888)
		(width 0.1143)
		(layer "In11.Cu")
		(net "P5E_CPU1_P1_RX_DN<4>")
	)
	(segment
		(start 101.268022 -276.2504)
		(end 100.80117 -276.516338)
		(width 0.12954)
		(layer "F.Cu")
		(net "P5E_CPU1_P1_RX_DN<3>")
	)
	(segment
		(start 83.39836 -385.31038)
		(end 83.91906 -385.31038)
		(width 0.127)
		(layer "F.Cu")
		(net "P5E_CPU1_P1_RX_DN<3>")
	)
	(segment
		(start 100.047044 -285.913322)
		(end 100.04552 -285.912306)
		(width 0.1143)
		(layer "In11.Cu")
		(net "P5E_CPU1_P1_RX_DN<3>")
	)
	(segment
		(start 100.048822 -281.054302)
		(end 100.04806 -281.053794)
		(width 0.1143)
		(layer "In11.Cu")
		(net "P5E_CPU1_P1_RX_DN<3>")
	)
	(segment
		(start 103.188516 -308.685184)
		(end 99.2505 -299.177202)
		(width 0.14224)
		(layer "In11.Cu")
		(net "P5E_CPU1_P1_RX_DN<3>")
	)
	(segment
		(start 100.047044 -292.393116)
		(end 100.04552 -292.3921)
		(width 0.1143)
		(layer "In11.Cu")
		(net "P5E_CPU1_P1_RX_DN<3>")
	)
	(segment
		(start 99.2505 -296.463974)
		(end 99.2505 -296.435526)
		(width 0.1143)
		(layer "In11.Cu")
		(net "P5E_CPU1_P1_RX_DN<3>")
	)
	(segment
		(start 100.055172 -289.157664)
		(end 100.054156 -289.157156)
		(width 0.1143)
		(layer "In11.Cu")
		(net "P5E_CPU1_P1_RX_DN<3>")
	)
	(segment
		(start 84.933282 -365.36884)
		(end 84.986114 -365.181896)
		(width 0.14224)
		(layer "In11.Cu")
		(net "P5E_CPU1_P1_RX_DN<3>")
	)
	(segment
		(start 100.050092 -283.317696)
		(end 100.07981 -283.300678)
		(width 0.1143)
		(layer "In11.Cu")
		(net "P5E_CPU1_P1_RX_DN<3>")
	)
	(segment
		(start 100.054156 -292.39718)
		(end 100.052632 -292.396164)
		(width 0.1143)
		(layer "In11.Cu")
		(net "P5E_CPU1_P1_RX_DN<3>")
	)
	(segment
		(start 100.050092 -281.697684)
		(end 100.07981 -281.680666)
		(width 0.1143)
		(layer "In11.Cu")
		(net "P5E_CPU1_P1_RX_DN<3>")
	)
	(segment
		(start 100.047044 -294.659304)
		(end 100.04806 -294.658796)
		(width 0.1143)
		(layer "In11.Cu")
		(net "P5E_CPU1_P1_RX_DN<3>")
	)
	(segment
		(start 84.001864 -365.732822)
		(end 84.374482 -365.524542)
		(width 0.14224)
		(layer "In11.Cu")
		(net "P5E_CPU1_P1_RX_DN<3>")
	)
	(segment
		(start 100.008944 -289.82162)
		(end 100.04552 -289.800284)
		(width 0.1143)
		(layer "In11.Cu")
		(net "P5E_CPU1_P1_RX_DN<3>")
	)
	(segment
		(start 100.048822 -292.394132)
		(end 100.04806 -292.393624)
		(width 0.1143)
		(layer "In11.Cu")
		(net "P5E_CPU1_P1_RX_DN<3>")
	)
	(segment
		(start 100.008944 -291.441632)
		(end 100.04552 -291.420296)
		(width 0.1143)
		(layer "In11.Cu")
		(net "P5E_CPU1_P1_RX_DN<3>")
	)
	(segment
		(start 100.047044 -284.29331)
		(end 100.04552 -284.292294)
		(width 0.1143)
		(layer "In11.Cu")
		(net "P5E_CPU1_P1_RX_DN<3>")
	)
	(segment
		(start 100.055172 -290.777676)
		(end 100.054156 -290.777168)
		(width 0.1143)
		(layer "In11.Cu")
		(net "P5E_CPU1_P1_RX_DN<3>")
	)
	(segment
		(start 100.054156 -284.297374)
		(end 100.052632 -284.296358)
		(width 0.1143)
		(layer "In11.Cu")
		(net "P5E_CPU1_P1_RX_DN<3>")
	)
	(segment
		(start 100.044504 -281.051762)
		(end 100.008944 -281.030934)
		(width 0.1143)
		(layer "In11.Cu")
		(net "P5E_CPU1_P1_RX_DN<3>")
	)
	(segment
		(start 100.04552 -290.772088)
		(end 100.008944 -290.750752)
		(width 0.1143)
		(layer "In11.Cu")
		(net "P5E_CPU1_P1_RX_DN<3>")
	)
	(segment
		(start 100.050092 -282.675076)
		(end 100.048822 -282.674314)
		(width 0.1143)
		(layer "In11.Cu")
		(net "P5E_CPU1_P1_RX_DN<3>")
	)
	(segment
		(start 100.048822 -284.93847)
		(end 100.050092 -284.937708)
		(width 0.1143)
		(layer "In11.Cu")
		(net "P5E_CPU1_P1_RX_DN<3>")
	)
	(segment
		(start 100.055172 -281.057858)
		(end 100.054156 -281.05735)
		(width 0.1143)
		(layer "In11.Cu")
		(net "P5E_CPU1_P1_RX_DN<3>")
	)
	(segment
		(start 100.04806 -287.533842)
		(end 100.011484 -287.512506)
		(width 0.1143)
		(layer "In11.Cu")
		(net "P5E_CPU1_P1_RX_DN<3>")
	)
	(segment
		(start 100.07981 -287.55213)
		(end 100.04806 -287.533842)
		(width 0.1143)
		(layer "In11.Cu")
		(net "P5E_CPU1_P1_RX_DN<3>")
	)
	(segment
		(start 83.102958 -366.393476)
		(end 83.949032 -365.919766)
		(width 0.14224)
		(layer "In11.Cu")
		(net "P5E_CPU1_P1_RX_DN<3>")
	)
	(segment
		(start 100.050092 -293.037514)
		(end 100.07981 -293.020496)
		(width 0.1143)
		(layer "In11.Cu")
		(net "P5E_CPU1_P1_RX_DN<3>")
	)
	(segment
		(start 84.561172 -365.57712)
		(end 84.933282 -365.36884)
		(width 0.14224)
		(layer "In11.Cu")
		(net "P5E_CPU1_P1_RX_DN<3>")
	)
	(segment
		(start 84.394548 -385.334764)
		(end 84.394548 -385.163822)
		(width 0.14224)
		(layer "In11.Cu")
		(net "P5E_CPU1_P1_RX_DN<3>")
	)
	(segment
		(start 100.050092 -278.45766)
		(end 100.07981 -278.440642)
		(width 0.1143)
		(layer "In11.Cu")
		(net "P5E_CPU1_P1_RX_DN<3>")
	)
	(segment
		(start 99.2505 -296.435526)
		(end 99.29622 -296.389806)
		(width 0.1143)
		(layer "In11.Cu")
		(net "P5E_CPU1_P1_RX_DN<3>")
	)
	(segment
		(start 100.008944 -294.681656)
		(end 100.04552 -294.66032)
		(width 0.1143)
		(layer "In11.Cu")
		(net "P5E_CPU1_P1_RX_DN<3>")
	)
	(segment
		(start 100.048822 -291.418264)
		(end 100.050092 -291.417502)
		(width 0.1143)
		(layer "In11.Cu")
		(net "P5E_CPU1_P1_RX_DN<3>")
	)
	(segment
		(start 100.04806 -289.1536)
		(end 100.047044 -289.153092)
		(width 0.1143)
		(layer "In11.Cu")
		(net "P5E_CPU1_P1_RX_DN<3>")
	)
	(segment
		(start 100.04552 -289.800284)
		(end 100.047044 -289.799268)
		(width 0.1143)
		(layer "In11.Cu")
		(net "P5E_CPU1_P1_RX_DN<3>")
	)
	(segment
		(start 85.970364 -364.63097)
		(end 86.342982 -364.422436)
		(width 0.14224)
		(layer "In11.Cu")
		(net "P5E_CPU1_P1_RX_DN<3>")
	)
	(segment
		(start 84.077556 -384.84683)
		(end 84.082382 -384.234944)
		(width 0.14224)
		(layer "In11.Cu")
		(net "P5E_CPU1_P1_RX_DN<3>")
	)
	(segment
		(start 100.054156 -282.677362)
		(end 100.052632 -282.676346)
		(width 0.1143)
		(layer "In11.Cu")
		(net "P5E_CPU1_P1_RX_DN<3>")
	)
	(segment
		(start 96.70542 -358.779064)
		(end 117.092222 -345.156536)
		(width 0.14224)
		(layer "In11.Cu")
		(net "P5E_CPU1_P1_RX_DN<3>")
	)
	(segment
		(start 100.04552 -282.672282)
		(end 100.044504 -282.671774)
		(width 0.1143)
		(layer "In11.Cu")
		(net "P5E_CPU1_P1_RX_DN<3>")
	)
	(segment
		(start 101.099112 -276.516338)
		(end 100.80117 -276.516338)
		(width 0.1143)
		(layer "In11.Cu")
		(net "P5E_CPU1_P1_RX_DN<3>")
	)
	(segment
		(start 100.07981 -290.7919)
		(end 100.055172 -290.777676)
		(width 0.1143)
		(layer "In11.Cu")
		(net "P5E_CPU1_P1_RX_DN<3>")
	)
	(segment
		(start 100.518214 -277.648924)
		(end 100.548694 -277.631144)
		(width 0.1143)
		(layer "In11.Cu")
		(net "P5E_CPU1_P1_RX_DN<3>")
	)
	(segment
		(start 100.008944 -278.48179)
		(end 100.04552 -278.460454)
		(width 0.1143)
		(layer "In11.Cu")
		(net "P5E_CPU1_P1_RX_DN<3>")
	)
	(segment
		(start 100.04806 -284.938978)
		(end 100.048822 -284.93847)
		(width 0.1143)
		(layer "In11.Cu")
		(net "P5E_CPU1_P1_RX_DN<3>")
	)
	(segment
		(start 100.008944 -288.201608)
		(end 100.04806 -288.178748)
		(width 0.1143)
		(layer "In11.Cu")
		(net "P5E_CPU1_P1_RX_DN<3>")
	)
	(segment
		(start 100.04552 -294.012112)
		(end 100.008944 -293.990776)
		(width 0.1143)
		(layer "In11.Cu")
		(net "P5E_CPU1_P1_RX_DN<3>")
	)
	(segment
		(start 100.04806 -289.79876)
		(end 100.048822 -289.798252)
		(width 0.1143)
		(layer "In11.Cu")
		(net "P5E_CPU1_P1_RX_DN<3>")
	)
	(segment
		(start 100.052632 -289.15614)
		(end 100.050092 -289.15487)
		(width 0.1143)
		(layer "In11.Cu")
		(net "P5E_CPU1_P1_RX_DN<3>")
	)
	(segment
		(start 100.048822 -290.77412)
		(end 100.04806 -290.773612)
		(width 0.1143)
		(layer "In11.Cu")
		(net "P5E_CPU1_P1_RX_DN<3>")
	)
	(segment
		(start 100.055172 -294.0177)
		(end 100.054156 -294.017192)
		(width 0.1143)
		(layer "In11.Cu")
		(net "P5E_CPU1_P1_RX_DN<3>")
	)
	(segment
		(start 100.04806 -281.698954)
		(end 100.048822 -281.698446)
		(width 0.1143)
		(layer "In11.Cu")
		(net "P5E_CPU1_P1_RX_DN<3>")
	)
	(segment
		(start 100.04552 -285.912306)
		(end 100.044504 -285.911798)
		(width 0.1143)
		(layer "In11.Cu")
		(net "P5E_CPU1_P1_RX_DN<3>")
	)
	(segment
		(start 116.357146 -326.563482)
		(end 109.777276 -318.545464)
		(width 0.14224)
		(layer "In11.Cu")
		(net "P5E_CPU1_P1_RX_DN<3>")
	)
	(segment
		(start 100.054156 -294.017192)
		(end 100.052632 -294.016176)
		(width 0.1143)
		(layer "In11.Cu")
		(net "P5E_CPU1_P1_RX_DN<3>")
	)
	(segment
		(start 100.04806 -290.773612)
		(end 100.047044 -290.773104)
		(width 0.1143)
		(layer "In11.Cu")
		(net "P5E_CPU1_P1_RX_DN<3>")
	)
	(segment
		(start 86.529672 -364.475268)
		(end 96.70542 -358.779064)
		(width 0.14224)
		(layer "In11.Cu")
		(net "P5E_CPU1_P1_RX_DN<3>")
	)
	(segment
		(start 100.048822 -284.294326)
		(end 100.04806 -284.293818)
		(width 0.1143)
		(layer "In11.Cu")
		(net "P5E_CPU1_P1_RX_DN<3>")
	)
	(segment
		(start 100.050092 -285.9151)
		(end 100.048822 -285.914338)
		(width 0.1143)
		(layer "In11.Cu")
		(net "P5E_CPU1_P1_RX_DN<3>")
	)
	(segment
		(start 100.054156 -281.05735)
		(end 100.052632 -281.056334)
		(width 0.1143)
		(layer "In11.Cu")
		(net "P5E_CPU1_P1_RX_DN<3>")
	)
	(segment
		(start 100.047044 -289.153092)
		(end 100.04552 -289.152076)
		(width 0.1143)
		(layer "In11.Cu")
		(net "P5E_CPU1_P1_RX_DN<3>")
	)
	(segment
		(start 100.055172 -284.297882)
		(end 100.054156 -284.297374)
		(width 0.1143)
		(layer "In11.Cu")
		(net "P5E_CPU1_P1_RX_DN<3>")
	)
	(segment
		(start 119.337328 -338.640928)
		(end 117.592094 -328.933048)
		(width 0.14224)
		(layer "In11.Cu")
		(net "P5E_CPU1_P1_RX_DN<3>")
	)
	(segment
		(start 100.04552 -281.700478)
		(end 100.047044 -281.699462)
		(width 0.1143)
		(layer "In11.Cu")
		(net "P5E_CPU1_P1_RX_DN<3>")
	)
	(segment
		(start 78.340458 -374.655588)
		(end 78.230476 -373.438674)
		(width 0.14224)
		(layer "In11.Cu")
		(net "P5E_CPU1_P1_RX_DN<3>")
	)
	(segment
		(start 100.04806 -284.293818)
		(end 100.047044 -284.29331)
		(width 0.1143)
		(layer "In11.Cu")
		(net "P5E_CPU1_P1_RX_DN<3>")
	)
	(segment
		(start 100.052632 -292.396164)
		(end 100.050092 -292.394894)
		(width 0.1143)
		(layer "In11.Cu")
		(net "P5E_CPU1_P1_RX_DN<3>")
	)
	(segment
		(start 100.050092 -281.055064)
		(end 100.048822 -281.054302)
		(width 0.1143)
		(layer "In11.Cu")
		(net "P5E_CPU1_P1_RX_DN<3>")
	)
	(segment
		(start 100.04806 -291.418772)
		(end 100.048822 -291.418264)
		(width 0.1143)
		(layer "In11.Cu")
		(net "P5E_CPU1_P1_RX_DN<3>")
	)
	(segment
		(start 100.050092 -294.014906)
		(end 100.048822 -294.014144)
		(width 0.1143)
		(layer "In11.Cu")
		(net "P5E_CPU1_P1_RX_DN<3>")
	)
	(segment
		(start 100.052632 -281.056334)
		(end 100.050092 -281.055064)
		(width 0.1143)
		(layer "In11.Cu")
		(net "P5E_CPU1_P1_RX_DN<3>")
	)
	(segment
		(start 99.57816 -279.268936)
		(end 99.60864 -279.251156)
		(width 0.1143)
		(layer "In11.Cu")
		(net "P5E_CPU1_P1_RX_DN<3>")
	)
	(segment
		(start 100.07981 -294.031924)
		(end 100.055172 -294.0177)
		(width 0.1143)
		(layer "In11.Cu")
		(net "P5E_CPU1_P1_RX_DN<3>")
	)
	(segment
		(start 118.152418 -343.864692)
		(end 119.337074 -341.004144)
		(width 0.14224)
		(layer "In11.Cu")
		(net "P5E_CPU1_P1_RX_DN<3>")
	)
	(segment
		(start 100.052632 -284.296358)
		(end 100.050092 -284.295088)
		(width 0.1143)
		(layer "In11.Cu")
		(net "P5E_CPU1_P1_RX_DN<3>")
	)
	(segment
		(start 100.044504 -282.671774)
		(end 100.008944 -282.650946)
		(width 0.1143)
		(layer "In11.Cu")
		(net "P5E_CPU1_P1_RX_DN<3>")
	)
	(segment
		(start 101.168962 -276.586188)
		(end 101.099112 -276.516338)
		(width 0.1143)
		(layer "In11.Cu")
		(net "P5E_CPU1_P1_RX_DN<3>")
	)
	(segment
		(start 100.04552 -281.05227)
		(end 100.044504 -281.051762)
		(width 0.1143)
		(layer "In11.Cu")
		(net "P5E_CPU1_P1_RX_DN<3>")
	)
	(segment
		(start 101.169216 -276.586696)
		(end 101.169216 -276.586188)
		(width 0.1143)
		(layer "In11.Cu")
		(net "P5E_CPU1_P1_RX_DN<3>")
	)
	(segment
		(start 100.04552 -293.040308)
		(end 100.047044 -293.039292)
		(width 0.1143)
		(layer "In11.Cu")
		(net "P5E_CPU1_P1_RX_DN<3>")
	)
	(segment
		(start 100.048822 -289.154108)
		(end 100.04806 -289.1536)
		(width 0.1143)
		(layer "In11.Cu")
		(net "P5E_CPU1_P1_RX_DN<3>")
	)
	(segment
		(start 117.592094 -328.933048)
		(end 116.357146 -326.563482)
		(width 0.14224)
		(layer "In11.Cu")
		(net "P5E_CPU1_P1_RX_DN<3>")
	)
	(segment
		(start 100.948998 -276.861778)
		(end 100.992432 -276.836632)
		(width 0.1143)
		(layer "In11.Cu")
		(net "P5E_CPU1_P1_RX_DN<3>")
	)
	(segment
		(start 100.008944 -286.581596)
		(end 100.04806 -286.558736)
		(width 0.1143)
		(layer "In11.Cu")
		(net "P5E_CPU1_P1_RX_DN<3>")
	)
	(segment
		(start 100.07981 -292.411912)
		(end 100.055172 -292.397688)
		(width 0.1143)
		(layer "In11.Cu")
		(net "P5E_CPU1_P1_RX_DN<3>")
	)
	(segment
		(start 100.04806 -294.658796)
		(end 100.07981 -294.640508)
		(width 0.1143)
		(layer "In11.Cu")
		(net "P5E_CPU1_P1_RX_DN<3>")
	)
	(segment
		(start 100.054156 -289.157156)
		(end 100.052632 -289.15614)
		(width 0.1143)
		(layer "In11.Cu")
		(net "P5E_CPU1_P1_RX_DN<3>")
	)
	(segment
		(start 84.29625 -381.599694)
		(end 78.621382 -375.458482)
		(width 0.14224)
		(layer "In11.Cu")
		(net "P5E_CPU1_P1_RX_DN<3>")
	)
	(segment
		(start 100.04552 -289.152076)
		(end 100.008944 -289.13074)
		(width 0.1143)
		(layer "In11.Cu")
		(net "P5E_CPU1_P1_RX_DN<3>")
	)
	(segment
		(start 84.082382 -384.234944)
		(end 84.38642 -383.930906)
		(width 0.14224)
		(layer "In11.Cu")
		(net "P5E_CPU1_P1_RX_DN<3>")
	)
	(segment
		(start 100.04806 -285.91383)
		(end 100.047044 -285.913322)
		(width 0.1143)
		(layer "In11.Cu")
		(net "P5E_CPU1_P1_RX_DN<3>")
	)
	(segment
		(start 100.048822 -283.318458)
		(end 100.050092 -283.317696)
		(width 0.1143)
		(layer "In11.Cu")
		(net "P5E_CPU1_P1_RX_DN<3>")
	)
	(segment
		(start 100.048822 -281.698446)
		(end 100.050092 -281.697684)
		(width 0.1143)
		(layer "In11.Cu")
		(net "P5E_CPU1_P1_RX_DN<3>")
	)
	(segment
		(start 100.04806 -288.178748)
		(end 100.081588 -288.15919)
		(width 0.1143)
		(layer "In11.Cu")
		(net "P5E_CPU1_P1_RX_DN<3>")
	)
	(segment
		(start 99.29622 -296.389806)
		(end 99.29622 -296.114216)
		(width 0.1143)
		(layer "In11.Cu")
		(net "P5E_CPU1_P1_RX_DN<3>")
	)
	(segment
		(start 100.008944 -293.061644)
		(end 100.04552 -293.040308)
		(width 0.1143)
		(layer "In11.Cu")
		(net "P5E_CPU1_P1_RX_DN<3>")
	)
	(segment
		(start 78.354174 -372.970298)
		(end 78.354428 -372.970298)
		(width 0.14224)
		(layer "In11.Cu")
		(net "P5E_CPU1_P1_RX_DN<3>")
	)
	(segment
		(start 109.777276 -318.545464)
		(end 103.188516 -308.685184)
		(width 0.14224)
		(layer "In11.Cu")
		(net "P5E_CPU1_P1_RX_DN<3>")
	)
	(segment
		(start 85.358732 -364.973362)
		(end 85.545422 -365.026194)
		(width 0.14224)
		(layer "In11.Cu")
		(net "P5E_CPU1_P1_RX_DN<3>")
	)
	(segment
		(start 100.047044 -289.799268)
		(end 100.04806 -289.79876)
		(width 0.1143)
		(layer "In11.Cu")
		(net "P5E_CPU1_P1_RX_DN<3>")
	)
	(segment
		(start 100.050092 -291.417502)
		(end 100.07981 -291.400484)
		(width 0.1143)
		(layer "In11.Cu")
		(net "P5E_CPU1_P1_RX_DN<3>")
	)
	(segment
		(start 100.047044 -284.939486)
		(end 100.04806 -284.938978)
		(width 0.1143)
		(layer "In11.Cu")
		(net "P5E_CPU1_P1_RX_DN<3>")
	)
	(segment
		(start 99.539044 -279.291796)
		(end 99.57816 -279.268936)
		(width 0.1143)
		(layer "In11.Cu")
		(net "P5E_CPU1_P1_RX_DN<3>")
	)
	(segment
		(start 100.055172 -285.917894)
		(end 100.054156 -285.917386)
		(width 0.1143)
		(layer "In11.Cu")
		(net "P5E_CPU1_P1_RX_DN<3>")
	)
	(segment
		(start 100.07981 -285.932118)
		(end 100.055172 -285.917894)
		(width 0.1143)
		(layer "In11.Cu")
		(net "P5E_CPU1_P1_RX_DN<3>")
	)
	(segment
		(start 100.04806 -294.013636)
		(end 100.047044 -294.013128)
		(width 0.1143)
		(layer "In11.Cu")
		(net "P5E_CPU1_P1_RX_DN<3>")
	)
	(segment
		(start 99.765612 -295.276778)
		(end 99.765612 -295.145714)
		(width 0.1143)
		(layer "In11.Cu")
		(net "P5E_CPU1_P1_RX_DN<3>")
	)
	(segment
		(start 100.04552 -292.3921)
		(end 100.008944 -292.370764)
		(width 0.1143)
		(layer "In11.Cu")
		(net "P5E_CPU1_P1_RX_DN<3>")
	)
	(segment
		(start 85.917532 -364.817914)
		(end 85.970364 -364.63097)
		(width 0.14224)
		(layer "In11.Cu")
		(net "P5E_CPU1_P1_RX_DN<3>")
	)
	(segment
		(start 86.342982 -364.422436)
		(end 86.529672 -364.475268)
		(width 0.14224)
		(layer "In11.Cu")
		(net "P5E_CPU1_P1_RX_DN<3>")
	)
	(segment
		(start 100.048822 -278.458422)
		(end 100.050092 -278.45766)
		(width 0.1143)
		(layer "In11.Cu")
		(net "P5E_CPU1_P1_RX_DN<3>")
	)
	(segment
		(start 100.047044 -291.41928)
		(end 100.04806 -291.418772)
		(width 0.1143)
		(layer "In11.Cu")
		(net "P5E_CPU1_P1_RX_DN<3>")
	)
	(segment
		(start 100.044504 -285.911798)
		(end 100.008944 -285.89097)
		(width 0.1143)
		(layer "In11.Cu")
		(net "P5E_CPU1_P1_RX_DN<3>")
	)
	(segment
		(start 84.38642 -383.930906)
		(end 84.38642 -381.829564)
		(width 0.14224)
		(layer "In11.Cu")
		(net "P5E_CPU1_P1_RX_DN<3>")
	)
	(segment
		(start 100.047044 -281.053286)
		(end 100.04552 -281.05227)
		(width 0.1143)
		(layer "In11.Cu")
		(net "P5E_CPU1_P1_RX_DN<3>")
	)
	(segment
		(start 100.052632 -290.776152)
		(end 100.050092 -290.774882)
		(width 0.1143)
		(layer "In11.Cu")
		(net "P5E_CPU1_P1_RX_DN<3>")
	)
	(segment
		(start 100.054156 -285.917386)
		(end 100.052632 -285.91637)
		(width 0.1143)
		(layer "In11.Cu")
		(net "P5E_CPU1_P1_RX_DN<3>")
	)
	(segment
		(start 84.986114 -365.181896)
		(end 85.358732 -364.973362)
		(width 0.14224)
		(layer "In11.Cu")
		(net "P5E_CPU1_P1_RX_DN<3>")
	)
	(segment
		(start 100.050092 -289.15487)
		(end 100.048822 -289.154108)
		(width 0.1143)
		(layer "In11.Cu")
		(net "P5E_CPU1_P1_RX_DN<3>")
	)
	(segment
		(start 100.050092 -292.394894)
		(end 100.048822 -292.394132)
		(width 0.1143)
		(layer "In11.Cu")
		(net "P5E_CPU1_P1_RX_DN<3>")
	)
	(segment
		(start 100.04552 -294.66032)
		(end 100.047044 -294.659304)
		(width 0.1143)
		(layer "In11.Cu")
		(net "P5E_CPU1_P1_RX_DN<3>")
	)
	(segment
		(start 100.048822 -294.014144)
		(end 100.04806 -294.013636)
		(width 0.1143)
		(layer "In11.Cu")
		(net "P5E_CPU1_P1_RX_DN<3>")
	)
	(segment
		(start 100.04806 -281.053794)
		(end 100.047044 -281.053286)
		(width 0.1143)
		(layer "In11.Cu")
		(net "P5E_CPU1_P1_RX_DN<3>")
	)
	(segment
		(start 100.044504 -284.291786)
		(end 100.008944 -284.270958)
		(width 0.1143)
		(layer "In11.Cu")
		(net "P5E_CPU1_P1_RX_DN<3>")
	)
	(segment
		(start 100.07981 -281.072082)
		(end 100.055172 -281.057858)
		(width 0.1143)
		(layer "In11.Cu")
		(net "P5E_CPU1_P1_RX_DN<3>")
	)
	(segment
		(start 119.337074 -341.004144)
		(end 119.337328 -341.00389)
		(width 0.14224)
		(layer "In11.Cu")
		(net "P5E_CPU1_P1_RX_DN<3>")
	)
	(segment
		(start 101.169216 -276.586188)
		(end 101.168962 -276.586188)
		(width 0.1143)
		(layer "In11.Cu")
		(net "P5E_CPU1_P1_RX_DN<3>")
	)
	(segment
		(start 100.047044 -278.459438)
		(end 100.04806 -278.45893)
		(width 0.1143)
		(layer "In11.Cu")
		(net "P5E_CPU1_P1_RX_DN<3>")
	)
	(segment
		(start 100.008944 -281.721814)
		(end 100.04552 -281.700478)
		(width 0.1143)
		(layer "In11.Cu")
		(net "P5E_CPU1_P1_RX_DN<3>")
	)
	(segment
		(start 100.048822 -282.674314)
		(end 100.04806 -282.673806)
		(width 0.1143)
		(layer "In11.Cu")
		(net "P5E_CPU1_P1_RX_DN<3>")
	)
	(segment
		(start 100.04806 -286.558736)
		(end 100.081588 -286.539178)
		(width 0.1143)
		(layer "In11.Cu")
		(net "P5E_CPU1_P1_RX_DN<3>")
	)
	(segment
		(start 100.048822 -285.914338)
		(end 100.04806 -285.91383)
		(width 0.1143)
		(layer "In11.Cu")
		(net "P5E_CPU1_P1_RX_DN<3>")
	)
	(segment
		(start 100.04552 -291.420296)
		(end 100.047044 -291.41928)
		(width 0.1143)
		(layer "In11.Cu")
		(net "P5E_CPU1_P1_RX_DN<3>")
	)
	(segment
		(start 100.04552 -278.460454)
		(end 100.047044 -278.459438)
		(width 0.1143)
		(layer "In11.Cu")
		(net "P5E_CPU1_P1_RX_DN<3>")
	)
	(segment
		(start 119.337328 -341.00389)
		(end 119.337328 -338.640928)
		(width 0.14224)
		(layer "In11.Cu")
		(net "P5E_CPU1_P1_RX_DN<3>")
	)
	(segment
		(start 84.374482 -365.524542)
		(end 84.561172 -365.57712)
		(width 0.14224)
		(layer "In11.Cu")
		(net "P5E_CPU1_P1_RX_DN<3>")
	)
	(segment
		(start 100.04552 -284.940502)
		(end 100.047044 -284.939486)
		(width 0.1143)
		(layer "In11.Cu")
		(net "P5E_CPU1_P1_RX_DN<3>")
	)
	(segment
		(start 100.047044 -281.699462)
		(end 100.04806 -281.698954)
		(width 0.1143)
		(layer "In11.Cu")
		(net "P5E_CPU1_P1_RX_DN<3>")
	)
	(segment
		(start 100.04806 -293.038784)
		(end 100.048822 -293.038276)
		(width 0.1143)
		(layer "In11.Cu")
		(net "P5E_CPU1_P1_RX_DN<3>")
	)
	(segment
		(start 100.050092 -284.937708)
		(end 100.07981 -284.92069)
		(width 0.1143)
		(layer "In11.Cu")
		(net "P5E_CPU1_P1_RX_DN<3>")
	)
	(segment
		(start 83.949032 -365.919766)
		(end 84.001864 -365.732822)
		(width 0.14224)
		(layer "In11.Cu")
		(net "P5E_CPU1_P1_RX_DN<3>")
	)
	(segment
		(start 100.055172 -292.397688)
		(end 100.054156 -292.39718)
		(width 0.1143)
		(layer "In11.Cu")
		(net "P5E_CPU1_P1_RX_DN<3>")
	)
	(segment
		(start 100.052632 -294.016176)
		(end 100.050092 -294.014906)
		(width 0.1143)
		(layer "In11.Cu")
		(net "P5E_CPU1_P1_RX_DN<3>")
	)
	(segment
		(start 84.272882 -385.404868)
		(end 84.394548 -385.334764)
		(width 0.14224)
		(layer "In11.Cu")
		(net "P5E_CPU1_P1_RX_DN<3>")
	)
	(segment
		(start 100.048822 -289.798252)
		(end 100.050092 -289.79749)
		(width 0.1143)
		(layer "In11.Cu")
		(net "P5E_CPU1_P1_RX_DN<3>")
	)
	(segment
		(start 100.07981 -282.692094)
		(end 100.055172 -282.67787)
		(width 0.1143)
		(layer "In11.Cu")
		(net "P5E_CPU1_P1_RX_DN<3>")
	)
	(segment
		(start 100.054156 -290.777168)
		(end 100.052632 -290.776152)
		(width 0.1143)
		(layer "In11.Cu")
		(net "P5E_CPU1_P1_RX_DN<3>")
	)
	(segment
		(start 85.545422 -365.026194)
		(end 85.917532 -364.817914)
		(width 0.14224)
		(layer "In11.Cu")
		(net "P5E_CPU1_P1_RX_DN<3>")
	)
	(segment
		(start 100.052632 -282.676346)
		(end 100.050092 -282.675076)
		(width 0.1143)
		(layer "In11.Cu")
		(net "P5E_CPU1_P1_RX_DN<3>")
	)
	(segment
		(start 100.047044 -283.319474)
		(end 100.04806 -283.318966)
		(width 0.1143)
		(layer "In11.Cu")
		(net "P5E_CPU1_P1_RX_DN<3>")
	)
	(segment
		(start 100.04806 -292.393624)
		(end 100.047044 -292.393116)
		(width 0.1143)
		(layer "In11.Cu")
		(net "P5E_CPU1_P1_RX_DN<3>")
	)
	(segment
		(start 100.047044 -293.039292)
		(end 100.04806 -293.038784)
		(width 0.1143)
		(layer "In11.Cu")
		(net "P5E_CPU1_P1_RX_DN<3>")
	)
	(segment
		(start 100.055172 -282.67787)
		(end 100.054156 -282.677362)
		(width 0.1143)
		(layer "In11.Cu")
		(net "P5E_CPU1_P1_RX_DN<3>")
	)
	(segment
		(start 100.04806 -282.673806)
		(end 100.047044 -282.673298)
		(width 0.1143)
		(layer "In11.Cu")
		(net "P5E_CPU1_P1_RX_DN<3>")
	)
	(segment
		(start 100.047044 -294.013128)
		(end 100.04552 -294.012112)
		(width 0.1143)
		(layer "In11.Cu")
		(net "P5E_CPU1_P1_RX_DN<3>")
	)
	(segment
		(start 99.46894 -295.69664)
		(end 99.677982 -295.487598)
		(width 0.1143)
		(layer "In11.Cu")
		(net "P5E_CPU1_P1_RX_DN<3>")
	)
	(segment
		(start 100.07981 -284.312106)
		(end 100.055172 -284.297882)
		(width 0.1143)
		(layer "In11.Cu")
		(net "P5E_CPU1_P1_RX_DN<3>")
	)
	(segment
		(start 99.60864 -280.261568)
		(end 99.57816 -280.243788)
		(width 0.1143)
		(layer "In11.Cu")
		(net "P5E_CPU1_P1_RX_DN<3>")
	)
	(segment
		(start 100.479098 -277.671784)
		(end 100.518214 -277.648924)
		(width 0.1143)
		(layer "In11.Cu")
		(net "P5E_CPU1_P1_RX_DN<3>")
	)
	(segment
		(start 78.354428 -372.970298)
		(end 82.620866 -366.831118)
		(width 0.14224)
		(layer "In11.Cu")
		(net "P5E_CPU1_P1_RX_DN<3>")
	)
	(segment
		(start 99.2505 -299.177202)
		(end 99.2505 -296.463974)
		(width 0.14224)
		(layer "In11.Cu")
		(net "P5E_CPU1_P1_RX_DN<3>")
	)
	(segment
		(start 100.04806 -283.318966)
		(end 100.048822 -283.318458)
		(width 0.1143)
		(layer "In11.Cu")
		(net "P5E_CPU1_P1_RX_DN<3>")
	)
	(segment
		(start 100.04806 -278.45893)
		(end 100.048822 -278.458422)
		(width 0.1143)
		(layer "In11.Cu")
		(net "P5E_CPU1_P1_RX_DN<3>")
	)
	(segment
		(start 100.050092 -284.295088)
		(end 100.048822 -284.294326)
		(width 0.1143)
		(layer "In11.Cu")
		(net "P5E_CPU1_P1_RX_DN<3>")
	)
	(segment
		(start 100.050092 -289.79749)
		(end 100.07981 -289.780472)
		(width 0.1143)
		(layer "In11.Cu")
		(net "P5E_CPU1_P1_RX_DN<3>")
	)
	(segment
		(start 100.052632 -285.91637)
		(end 100.050092 -285.9151)
		(width 0.1143)
		(layer "In11.Cu")
		(net "P5E_CPU1_P1_RX_DN<3>")
	)
	(segment
		(start 100.047044 -290.773104)
		(end 100.04552 -290.772088)
		(width 0.1143)
		(layer "In11.Cu")
		(net "P5E_CPU1_P1_RX_DN<3>")
	)
	(segment
		(start 83.91906 -385.31038)
		(end 84.272374 -385.405376)
		(width 0.14224)
		(layer "In11.Cu")
		(net "P5E_CPU1_P1_RX_DN<3>")
	)
	(segment
		(start 100.048822 -293.038276)
		(end 100.050092 -293.037514)
		(width 0.1143)
		(layer "In11.Cu")
		(net "P5E_CPU1_P1_RX_DN<3>")
	)
	(segment
		(start 100.047044 -282.673298)
		(end 100.04552 -282.672282)
		(width 0.1143)
		(layer "In11.Cu")
		(net "P5E_CPU1_P1_RX_DN<3>")
	)
	(segment
		(start 99.57816 -280.243788)
		(end 99.539044 -280.220928)
		(width 0.1143)
		(layer "In11.Cu")
		(net "P5E_CPU1_P1_RX_DN<3>")
	)
	(segment
		(start 78.617064 -375.449084)
		(end 78.44663 -375.065036)
		(width 0.14224)
		(layer "In11.Cu")
		(net "P5E_CPU1_P1_RX_DN<3>")
	)
	(segment
		(start 84.272374 -385.405376)
		(end 84.272882 -385.404868)
		(width 0.14224)
		(layer "In11.Cu")
		(net "P5E_CPU1_P1_RX_DN<3>")
	)
	(segment
		(start 100.008944 -284.961838)
		(end 100.04552 -284.940502)
		(width 0.1143)
		(layer "In11.Cu")
		(net "P5E_CPU1_P1_RX_DN<3>")
	)
	(segment
		(start 100.008944 -283.341826)
		(end 100.04552 -283.32049)
		(width 0.1143)
		(layer "In11.Cu")
		(net "P5E_CPU1_P1_RX_DN<3>")
	)
	(segment
		(start 84.394548 -385.163822)
		(end 84.077556 -384.84683)
		(width 0.14224)
		(layer "In11.Cu")
		(net "P5E_CPU1_P1_RX_DN<3>")
	)
	(segment
		(start 100.07981 -289.171888)
		(end 100.055172 -289.157664)
		(width 0.1143)
		(layer "In11.Cu")
		(net "P5E_CPU1_P1_RX_DN<3>")
	)
	(segment
		(start 100.050092 -290.774882)
		(end 100.048822 -290.77412)
		(width 0.1143)
		(layer "In11.Cu")
		(net "P5E_CPU1_P1_RX_DN<3>")
	)
	(segment
		(start 100.04552 -283.32049)
		(end 100.047044 -283.319474)
		(width 0.1143)
		(layer "In11.Cu")
		(net "P5E_CPU1_P1_RX_DN<3>")
	)
	(segment
		(start 100.04552 -284.292294)
		(end 100.044504 -284.291786)
		(width 0.1143)
		(layer "In11.Cu")
		(net "P5E_CPU1_P1_RX_DN<3>")
	)
	(arc
		(start 100.081588 -288.15919)
		(mid 100.194995 -288.026301)
		(end 100.235766 -287.856422)
		(width 0.1143)
		(layer "In11.Cu")
		(net "P5E_CPU1_P1_RX_DN<3>")
	)
	(arc
		(start 100.992432 -276.836632)
		(mid 101.107957 -276.73086)
		(end 101.169216 -276.586696)
		(width 0.1143)
		(layer "In11.Cu")
		(net "P5E_CPU1_P1_RX_DN<3>")
	)
	(arc
		(start 100.07981 -294.640508)
		(mid 100.235738 -294.336216)
		(end 100.07981 -294.031924)
		(width 0.1143)
		(layer "In11.Cu")
		(net "P5E_CPU1_P1_RX_DN<3>")
	)
	(arc
		(start 100.07981 -278.440642)
		(mid 100.194486 -278.307308)
		(end 100.235766 -278.13635)
		(width 0.1143)
		(layer "In11.Cu")
		(net "P5E_CPU1_P1_RX_DN<3>")
	)
	(arc
		(start 99.765612 -295.144952)
		(mid 99.83042 -294.88344)
		(end 100.008944 -294.681656)
		(width 0.1143)
		(layer "In11.Cu")
		(net "P5E_CPU1_P1_RX_DN<3>")
	)
	(arc
		(start 100.235766 -286.23641)
		(mid 100.194511 -286.065439)
		(end 100.07981 -285.932118)
		(width 0.1143)
		(layer "In11.Cu")
		(net "P5E_CPU1_P1_RX_DN<3>")
	)
	(arc
		(start 99.29622 -296.114216)
		(mid 99.341056 -295.888252)
		(end 99.46894 -295.69664)
		(width 0.1143)
		(layer "In11.Cu")
		(net "P5E_CPU1_P1_RX_DN<3>")
	)
	(arc
		(start 78.621382 -375.458482)
		(mid 78.619212 -375.453788)
		(end 78.617064 -375.449084)
		(width 0.14224)
		(layer "In11.Cu")
		(net "P5E_CPU1_P1_RX_DN<3>")
	)
	(arc
		(start 100.235766 -278.13635)
		(mid 100.300281 -277.874131)
		(end 100.479098 -277.671784)
		(width 0.1143)
		(layer "In11.Cu")
		(net "P5E_CPU1_P1_RX_DN<3>")
	)
	(arc
		(start 78.44663 -375.065036)
		(mid 78.376754 -374.864666)
		(end 78.340458 -374.655588)
		(width 0.14224)
		(layer "In11.Cu")
		(net "P5E_CPU1_P1_RX_DN<3>")
	)
	(arc
		(start 100.008944 -293.990776)
		(mid 99.765617 -293.52621)
		(end 100.008944 -293.061644)
		(width 0.1143)
		(layer "In11.Cu")
		(net "P5E_CPU1_P1_RX_DN<3>")
	)
	(arc
		(start 100.008944 -290.750752)
		(mid 99.765617 -290.286186)
		(end 100.008944 -289.82162)
		(width 0.1143)
		(layer "In11.Cu")
		(net "P5E_CPU1_P1_RX_DN<3>")
	)
	(arc
		(start 82.620866 -366.831118)
		(mid 82.837007 -366.584863)
		(end 83.102958 -366.393476)
		(width 0.14224)
		(layer "In11.Cu")
		(net "P5E_CPU1_P1_RX_DN<3>")
	)
	(arc
		(start 100.008944 -292.370764)
		(mid 99.765617 -291.906198)
		(end 100.008944 -291.441632)
		(width 0.1143)
		(layer "In11.Cu")
		(net "P5E_CPU1_P1_RX_DN<3>")
	)
	(arc
		(start 99.539044 -280.220928)
		(mid 99.295717 -279.756362)
		(end 99.539044 -279.291796)
		(width 0.1143)
		(layer "In11.Cu")
		(net "P5E_CPU1_P1_RX_DN<3>")
	)
	(arc
		(start 100.008944 -285.89097)
		(mid 99.765617 -285.426404)
		(end 100.008944 -284.961838)
		(width 0.1143)
		(layer "In11.Cu")
		(net "P5E_CPU1_P1_RX_DN<3>")
	)
	(arc
		(start 100.07981 -281.680666)
		(mid 100.235738 -281.376374)
		(end 100.07981 -281.072082)
		(width 0.1143)
		(layer "In11.Cu")
		(net "P5E_CPU1_P1_RX_DN<3>")
	)
	(arc
		(start 99.677982 -295.487598)
		(mid 99.742748 -295.390902)
		(end 99.765612 -295.276778)
		(width 0.1143)
		(layer "In11.Cu")
		(net "P5E_CPU1_P1_RX_DN<3>")
	)
	(arc
		(start 100.008944 -284.270958)
		(mid 99.765617 -283.806392)
		(end 100.008944 -283.341826)
		(width 0.1143)
		(layer "In11.Cu")
		(net "P5E_CPU1_P1_RX_DN<3>")
	)
	(arc
		(start 100.081588 -286.539178)
		(mid 100.194995 -286.406289)
		(end 100.235766 -286.23641)
		(width 0.1143)
		(layer "In11.Cu")
		(net "P5E_CPU1_P1_RX_DN<3>")
	)
	(arc
		(start 100.07981 -293.020496)
		(mid 100.235738 -292.716204)
		(end 100.07981 -292.411912)
		(width 0.1143)
		(layer "In11.Cu")
		(net "P5E_CPU1_P1_RX_DN<3>")
	)
	(arc
		(start 100.07981 -283.300678)
		(mid 100.235738 -282.996386)
		(end 100.07981 -282.692094)
		(width 0.1143)
		(layer "In11.Cu")
		(net "P5E_CPU1_P1_RX_DN<3>")
	)
	(arc
		(start 99.765612 -295.145714)
		(mid 99.765612 -295.145333)
		(end 99.765612 -295.144952)
		(width 0.1143)
		(layer "In11.Cu")
		(net "P5E_CPU1_P1_RX_DN<3>")
	)
	(arc
		(start 100.011484 -287.512506)
		(mid 99.830832 -287.309761)
		(end 99.765612 -287.046162)
		(width 0.1143)
		(layer "In11.Cu")
		(net "P5E_CPU1_P1_RX_DN<3>")
	)
	(arc
		(start 100.235766 -287.856422)
		(mid 100.194511 -287.685451)
		(end 100.07981 -287.55213)
		(width 0.1143)
		(layer "In11.Cu")
		(net "P5E_CPU1_P1_RX_DN<3>")
	)
	(arc
		(start 100.07981 -289.780472)
		(mid 100.235738 -289.47618)
		(end 100.07981 -289.171888)
		(width 0.1143)
		(layer "In11.Cu")
		(net "P5E_CPU1_P1_RX_DN<3>")
	)
	(arc
		(start 84.38642 -381.829564)
		(mid 84.362942 -381.706151)
		(end 84.29625 -381.599694)
		(width 0.14224)
		(layer "In11.Cu")
		(net "P5E_CPU1_P1_RX_DN<3>")
	)
	(arc
		(start 100.705666 -277.326344)
		(mid 100.770181 -277.064125)
		(end 100.948998 -276.861778)
		(width 0.1143)
		(layer "In11.Cu")
		(net "P5E_CPU1_P1_RX_DN<3>")
	)
	(arc
		(start 100.548694 -277.631144)
		(mid 100.664121 -277.497768)
		(end 100.705666 -277.326344)
		(width 0.1143)
		(layer "In11.Cu")
		(net "P5E_CPU1_P1_RX_DN<3>")
	)
	(arc
		(start 99.765612 -278.946356)
		(mid 99.830127 -278.684137)
		(end 100.008944 -278.48179)
		(width 0.1143)
		(layer "In11.Cu")
		(net "P5E_CPU1_P1_RX_DN<3>")
	)
	(arc
		(start 100.07981 -284.92069)
		(mid 100.235738 -284.616398)
		(end 100.07981 -284.312106)
		(width 0.1143)
		(layer "In11.Cu")
		(net "P5E_CPU1_P1_RX_DN<3>")
	)
	(arc
		(start 100.008944 -289.13074)
		(mid 99.765617 -288.666174)
		(end 100.008944 -288.201608)
		(width 0.1143)
		(layer "In11.Cu")
		(net "P5E_CPU1_P1_RX_DN<3>")
	)
	(arc
		(start 100.008944 -281.030934)
		(mid 99.830131 -280.828584)
		(end 99.765612 -280.566368)
		(width 0.1143)
		(layer "In11.Cu")
		(net "P5E_CPU1_P1_RX_DN<3>")
	)
	(arc
		(start 99.765612 -287.046162)
		(mid 99.830127 -286.783943)
		(end 100.008944 -286.581596)
		(width 0.1143)
		(layer "In11.Cu")
		(net "P5E_CPU1_P1_RX_DN<3>")
	)
	(arc
		(start 99.60864 -279.251156)
		(mid 99.724067 -279.11778)
		(end 99.765612 -278.946356)
		(width 0.1143)
		(layer "In11.Cu")
		(net "P5E_CPU1_P1_RX_DN<3>")
	)
	(arc
		(start 100.008944 -282.650946)
		(mid 99.765617 -282.18638)
		(end 100.008944 -281.721814)
		(width 0.1143)
		(layer "In11.Cu")
		(net "P5E_CPU1_P1_RX_DN<3>")
	)
	(arc
		(start 100.07981 -291.400484)
		(mid 100.235738 -291.096192)
		(end 100.07981 -290.7919)
		(width 0.1143)
		(layer "In11.Cu")
		(net "P5E_CPU1_P1_RX_DN<3>")
	)
	(arc
		(start 78.230476 -373.438674)
		(mid 78.251085 -373.193592)
		(end 78.354174 -372.970298)
		(width 0.14224)
		(layer "In11.Cu")
		(net "P5E_CPU1_P1_RX_DN<3>")
	)
	(arc
		(start 117.092222 -345.156536)
		(mid 117.718144 -344.589253)
		(end 118.152418 -343.864692)
		(width 0.14224)
		(layer "In11.Cu")
		(net "P5E_CPU1_P1_RX_DN<3>")
	)
	(arc
		(start 99.765612 -280.566368)
		(mid 99.724063 -280.394946)
		(end 99.60864 -280.261568)
		(width 0.1143)
		(layer "In11.Cu")
		(net "P5E_CPU1_P1_RX_DN<3>")
	)
	(segment
		(start 98.44786 -274.630388)
		(end 97.981008 -274.896326)
		(width 0.12954)
		(layer "F.Cu")
		(net "P5E_CPU1_P1_RX_DN<2>")
	)
	(segment
		(start 82.198464 -385.31038)
		(end 82.719164 -385.31038)
		(width 0.127)
		(layer "F.Cu")
		(net "P5E_CPU1_P1_RX_DN<2>")
	)
	(segment
		(start 99.110038 -289.79749)
		(end 99.139756 -289.780472)
		(width 0.1143)
		(layer "In11.Cu")
		(net "P5E_CPU1_P1_RX_DN<2>")
	)
	(segment
		(start 99.139756 -289.171888)
		(end 99.115372 -289.157918)
		(width 0.1143)
		(layer "In11.Cu")
		(net "P5E_CPU1_P1_RX_DN<2>")
	)
	(segment
		(start 99.073208 -281.71902)
		(end 99.108006 -281.698954)
		(width 0.1143)
		(layer "In11.Cu")
		(net "P5E_CPU1_P1_RX_DN<2>")
	)
	(segment
		(start 99.067112 -294.682418)
		(end 99.139756 -294.640508)
		(width 0.1143)
		(layer "In11.Cu")
		(net "P5E_CPU1_P1_RX_DN<2>")
	)
	(segment
		(start 99.071684 -283.340048)
		(end 99.108006 -283.318966)
		(width 0.1143)
		(layer "In11.Cu")
		(net "P5E_CPU1_P1_RX_DN<2>")
	)
	(segment
		(start 99.071684 -286.579818)
		(end 99.141534 -286.539178)
		(width 0.1143)
		(layer "In11.Cu")
		(net "P5E_CPU1_P1_RX_DN<2>")
	)
	(segment
		(start 99.108006 -289.1536)
		(end 99.071684 -289.132518)
		(width 0.1143)
		(layer "In11.Cu")
		(net "P5E_CPU1_P1_RX_DN<2>")
	)
	(segment
		(start 98.310192 -296.463974)
		(end 98.310192 -296.435526)
		(width 0.1143)
		(layer "In11.Cu")
		(net "P5E_CPU1_P1_RX_DN<2>")
	)
	(segment
		(start 99.108768 -293.038276)
		(end 99.110038 -293.037514)
		(width 0.1143)
		(layer "In11.Cu")
		(net "P5E_CPU1_P1_RX_DN<2>")
	)
	(segment
		(start 99.114102 -294.017192)
		(end 99.108006 -294.013636)
		(width 0.1143)
		(layer "In11.Cu")
		(net "P5E_CPU1_P1_RX_DN<2>")
	)
	(segment
		(start 77.372718 -372.528592)
		(end 80.057498 -368.731038)
		(width 0.14224)
		(layer "In11.Cu")
		(net "P5E_CPU1_P1_RX_DN<2>")
	)
	(segment
		(start 82.719164 -385.31038)
		(end 83.072224 -385.405376)
		(width 0.14224)
		(layer "In11.Cu")
		(net "P5E_CPU1_P1_RX_DN<2>")
	)
	(segment
		(start 99.139756 -292.411912)
		(end 99.115372 -292.397942)
		(width 0.1143)
		(layer "In11.Cu")
		(net "P5E_CPU1_P1_RX_DN<2>")
	)
	(segment
		(start 99.114102 -282.677362)
		(end 99.108006 -282.673806)
		(width 0.1143)
		(layer "In11.Cu")
		(net "P5E_CPU1_P1_RX_DN<2>")
	)
	(segment
		(start 99.115372 -284.298136)
		(end 99.114102 -284.297374)
		(width 0.1143)
		(layer "In11.Cu")
		(net "P5E_CPU1_P1_RX_DN<2>")
	)
	(segment
		(start 99.068382 -287.510474)
		(end 99.054412 -287.500568)
		(width 0.1143)
		(layer "In11.Cu")
		(net "P5E_CPU1_P1_RX_DN<2>")
	)
	(segment
		(start 81.764886 -366.316514)
		(end 82.207354 -365.690658)
		(width 0.14224)
		(layer "In11.Cu")
		(net "P5E_CPU1_P1_RX_DN<2>")
	)
	(segment
		(start 99.139756 -290.7919)
		(end 99.115372 -290.77793)
		(width 0.1143)
		(layer "In11.Cu")
		(net "P5E_CPU1_P1_RX_DN<2>")
	)
	(segment
		(start 99.139756 -282.692094)
		(end 99.115372 -282.678124)
		(width 0.1143)
		(layer "In11.Cu")
		(net "P5E_CPU1_P1_RX_DN<2>")
	)
	(segment
		(start 98.637344 -279.263348)
		(end 98.699066 -279.227534)
		(width 0.1143)
		(layer "In11.Cu")
		(net "P5E_CPU1_P1_RX_DN<2>")
	)
	(segment
		(start 80.024732 -368.54003)
		(end 80.271366 -368.191288)
		(width 0.14224)
		(layer "In11.Cu")
		(net "P5E_CPU1_P1_RX_DN<2>")
	)
	(segment
		(start 99.109276 -287.53435)
		(end 99.068382 -287.510474)
		(width 0.1143)
		(layer "In11.Cu")
		(net "P5E_CPU1_P1_RX_DN<2>")
	)
	(segment
		(start 99.108768 -283.318458)
		(end 99.110038 -283.317696)
		(width 0.1143)
		(layer "In11.Cu")
		(net "P5E_CPU1_P1_RX_DN<2>")
	)
	(segment
		(start 81.359756 -366.889284)
		(end 81.32699 -366.698022)
		(width 0.14224)
		(layer "In11.Cu")
		(net "P5E_CPU1_P1_RX_DN<2>")
	)
	(segment
		(start 81.32699 -366.698022)
		(end 81.573624 -366.34928)
		(width 0.14224)
		(layer "In11.Cu")
		(net "P5E_CPU1_P1_RX_DN<2>")
	)
	(segment
		(start 115.607338 -327.154794)
		(end 109.154722 -319.292224)
		(width 0.14224)
		(layer "In11.Cu")
		(net "P5E_CPU1_P1_RX_DN<2>")
	)
	(segment
		(start 80.7085 -367.810288)
		(end 80.675734 -367.619026)
		(width 0.14224)
		(layer "In11.Cu")
		(net "P5E_CPU1_P1_RX_DN<2>")
	)
	(segment
		(start 98.355912 -296.389806)
		(end 98.355912 -296.135298)
		(width 0.1143)
		(layer "In11.Cu")
		(net "P5E_CPU1_P1_RX_DN<2>")
	)
	(segment
		(start 98.825812 -287.053782)
		(end 98.825812 -287.046162)
		(width 0.1143)
		(layer "In11.Cu")
		(net "P5E_CPU1_P1_RX_DN<2>")
	)
	(segment
		(start 99.098608 -276.187916)
		(end 99.097338 -276.187154)
		(width 0.1143)
		(layer "In11.Cu")
		(net "P5E_CPU1_P1_RX_DN<2>")
	)
	(segment
		(start 77.7621 -376.004328)
		(end 77.65161 -375.762012)
		(width 0.14224)
		(layer "In11.Cu")
		(net "P5E_CPU1_P1_RX_DN<2>")
	)
	(segment
		(start 83.18627 -383.93116)
		(end 83.18627 -381.958596)
		(width 0.14224)
		(layer "In11.Cu")
		(net "P5E_CPU1_P1_RX_DN<2>")
	)
	(segment
		(start 80.271366 -368.191288)
		(end 80.462374 -368.158522)
		(width 0.14224)
		(layer "In11.Cu")
		(net "P5E_CPU1_P1_RX_DN<2>")
	)
	(segment
		(start 99.108006 -284.293818)
		(end 99.071684 -284.272736)
		(width 0.1143)
		(layer "In11.Cu")
		(net "P5E_CPU1_P1_RX_DN<2>")
	)
	(segment
		(start 82.4357 -365.486696)
		(end 96.340676 -357.871522)
		(width 0.14224)
		(layer "In11.Cu")
		(net "P5E_CPU1_P1_RX_DN<2>")
	)
	(segment
		(start 96.340676 -357.871522)
		(end 116.272818 -344.552778)
		(width 0.14224)
		(layer "In11.Cu")
		(net "P5E_CPU1_P1_RX_DN<2>")
	)
	(segment
		(start 99.110038 -276.837648)
		(end 99.139756 -276.82063)
		(width 0.1143)
		(layer "In11.Cu")
		(net "P5E_CPU1_P1_RX_DN<2>")
	)
	(segment
		(start 99.108006 -284.938978)
		(end 99.108768 -284.93847)
		(width 0.1143)
		(layer "In11.Cu")
		(net "P5E_CPU1_P1_RX_DN<2>")
	)
	(segment
		(start 98.27895 -274.896326)
		(end 97.981008 -274.896326)
		(width 0.1143)
		(layer "In11.Cu")
		(net "P5E_CPU1_P1_RX_DN<2>")
	)
	(segment
		(start 99.108006 -290.773612)
		(end 99.071684 -290.75253)
		(width 0.1143)
		(layer "In11.Cu")
		(net "P5E_CPU1_P1_RX_DN<2>")
	)
	(segment
		(start 99.114102 -285.917386)
		(end 99.108006 -285.91383)
		(width 0.1143)
		(layer "In11.Cu")
		(net "P5E_CPU1_P1_RX_DN<2>")
	)
	(segment
		(start 99.110038 -293.037514)
		(end 99.139756 -293.020496)
		(width 0.1143)
		(layer "In11.Cu")
		(net "P5E_CPU1_P1_RX_DN<2>")
	)
	(segment
		(start 99.108768 -281.698446)
		(end 99.110038 -281.697684)
		(width 0.1143)
		(layer "In11.Cu")
		(net "P5E_CPU1_P1_RX_DN<2>")
	)
	(segment
		(start 83.194398 -385.163822)
		(end 82.877406 -384.84683)
		(width 0.14224)
		(layer "In11.Cu")
		(net "P5E_CPU1_P1_RX_DN<2>")
	)
	(segment
		(start 98.825812 -278.94788)
		(end 98.825812 -278.946356)
		(width 0.1143)
		(layer "In11.Cu")
		(net "P5E_CPU1_P1_RX_DN<2>")
	)
	(segment
		(start 98.639376 -280.24455)
		(end 98.599752 -280.221436)
		(width 0.1143)
		(layer "In11.Cu")
		(net "P5E_CPU1_P1_RX_DN<2>")
	)
	(segment
		(start 99.108006 -285.91383)
		(end 99.071684 -285.892748)
		(width 0.1143)
		(layer "In11.Cu")
		(net "P5E_CPU1_P1_RX_DN<2>")
	)
	(segment
		(start 98.543364 -295.682416)
		(end 98.65487 -295.57091)
		(width 0.1143)
		(layer "In11.Cu")
		(net "P5E_CPU1_P1_RX_DN<2>")
	)
	(segment
		(start 99.115372 -292.397942)
		(end 99.114102 -292.39718)
		(width 0.1143)
		(layer "In11.Cu")
		(net "P5E_CPU1_P1_RX_DN<2>")
	)
	(segment
		(start 99.108006 -276.838918)
		(end 99.108768 -276.83841)
		(width 0.1143)
		(layer "In11.Cu")
		(net "P5E_CPU1_P1_RX_DN<2>")
	)
	(segment
		(start 117.425978 -343.14765)
		(end 117.911372 -341.975948)
		(width 0.14224)
		(layer "In11.Cu")
		(net "P5E_CPU1_P1_RX_DN<2>")
	)
	(segment
		(start 83.194398 -385.334764)
		(end 83.194398 -385.163822)
		(width 0.14224)
		(layer "In11.Cu")
		(net "P5E_CPU1_P1_RX_DN<2>")
	)
	(segment
		(start 98.836226 -280.600658)
		(end 98.836226 -280.574242)
		(width 0.1143)
		(layer "In11.Cu")
		(net "P5E_CPU1_P1_RX_DN<2>")
	)
	(segment
		(start 99.110546 -281.055572)
		(end 99.093782 -281.045666)
		(width 0.1143)
		(layer "In11.Cu")
		(net "P5E_CPU1_P1_RX_DN<2>")
	)
	(segment
		(start 109.154722 -319.292224)
		(end 102.362254 -309.127144)
		(width 0.14224)
		(layer "In11.Cu")
		(net "P5E_CPU1_P1_RX_DN<2>")
	)
	(segment
		(start 99.115372 -294.017954)
		(end 99.114102 -294.017192)
		(width 0.1143)
		(layer "In11.Cu")
		(net "P5E_CPU1_P1_RX_DN<2>")
	)
	(segment
		(start 99.108768 -278.458422)
		(end 99.110038 -278.45766)
		(width 0.1143)
		(layer "In11.Cu")
		(net "P5E_CPU1_P1_RX_DN<2>")
	)
	(segment
		(start 99.069652 -278.481028)
		(end 99.108006 -278.45893)
		(width 0.1143)
		(layer "In11.Cu")
		(net "P5E_CPU1_P1_RX_DN<2>")
	)
	(segment
		(start 99.071684 -288.19983)
		(end 99.109022 -288.17824)
		(width 0.1143)
		(layer "In11.Cu")
		(net "P5E_CPU1_P1_RX_DN<2>")
	)
	(segment
		(start 99.111562 -276.19579)
		(end 99.102164 -276.190456)
		(width 0.1143)
		(layer "In11.Cu")
		(net "P5E_CPU1_P1_RX_DN<2>")
	)
	(segment
		(start 99.114102 -289.157156)
		(end 99.108006 -289.1536)
		(width 0.1143)
		(layer "In11.Cu")
		(net "P5E_CPU1_P1_RX_DN<2>")
	)
	(segment
		(start 117.911372 -341.975694)
		(end 118.396766 -340.803992)
		(width 0.14224)
		(layer "In11.Cu")
		(net "P5E_CPU1_P1_RX_DN<2>")
	)
	(segment
		(start 118.396766 -340.803992)
		(end 118.39702 -340.803738)
		(width 0.14224)
		(layer "In11.Cu")
		(net "P5E_CPU1_P1_RX_DN<2>")
	)
	(segment
		(start 99.071684 -293.059866)
		(end 99.108006 -293.038784)
		(width 0.1143)
		(layer "In11.Cu")
		(net "P5E_CPU1_P1_RX_DN<2>")
	)
	(segment
		(start 99.110038 -278.45766)
		(end 99.139756 -278.440642)
		(width 0.1143)
		(layer "In11.Cu")
		(net "P5E_CPU1_P1_RX_DN<2>")
	)
	(segment
		(start 99.108768 -277.814278)
		(end 99.108006 -277.81377)
		(width 0.1143)
		(layer "In11.Cu")
		(net "P5E_CPU1_P1_RX_DN<2>")
	)
	(segment
		(start 99.10953 -287.53435)
		(end 99.109276 -287.53435)
		(width 0.1143)
		(layer "In11.Cu")
		(net "P5E_CPU1_P1_RX_DN<2>")
	)
	(segment
		(start 99.108006 -293.038784)
		(end 99.108768 -293.038276)
		(width 0.1143)
		(layer "In11.Cu")
		(net "P5E_CPU1_P1_RX_DN<2>")
	)
	(segment
		(start 80.675734 -367.619026)
		(end 80.922368 -367.270284)
		(width 0.14224)
		(layer "In11.Cu")
		(net "P5E_CPU1_P1_RX_DN<2>")
	)
	(segment
		(start 98.665792 -275.399754)
		(end 98.59899 -275.360892)
		(width 0.1143)
		(layer "In11.Cu")
		(net "P5E_CPU1_P1_RX_DN<2>")
	)
	(segment
		(start 99.139756 -276.212046)
		(end 99.114356 -276.197314)
		(width 0.1143)
		(layer "In11.Cu")
		(net "P5E_CPU1_P1_RX_DN<2>")
	)
	(segment
		(start 99.110038 -291.417502)
		(end 99.139756 -291.400484)
		(width 0.1143)
		(layer "In11.Cu")
		(net "P5E_CPU1_P1_RX_DN<2>")
	)
	(segment
		(start 99.071684 -281.720036)
		(end 99.073208 -281.71902)
		(width 0.1143)
		(layer "In11.Cu")
		(net "P5E_CPU1_P1_RX_DN<2>")
	)
	(segment
		(start 99.114356 -276.197314)
		(end 99.112324 -276.196298)
		(width 0.1143)
		(layer "In11.Cu")
		(net "P5E_CPU1_P1_RX_DN<2>")
	)
	(segment
		(start 99.108006 -277.81377)
		(end 99.071684 -277.792688)
		(width 0.1143)
		(layer "In11.Cu")
		(net "P5E_CPU1_P1_RX_DN<2>")
	)
	(segment
		(start 99.108006 -281.698954)
		(end 99.108768 -281.698446)
		(width 0.1143)
		(layer "In11.Cu")
		(net "P5E_CPU1_P1_RX_DN<2>")
	)
	(segment
		(start 99.108006 -292.393624)
		(end 99.071684 -292.372542)
		(width 0.1143)
		(layer "In11.Cu")
		(net "P5E_CPU1_P1_RX_DN<2>")
	)
	(segment
		(start 98.825558 -275.707348)
		(end 98.825812 -275.706332)
		(width 0.1143)
		(layer "In11.Cu")
		(net "P5E_CPU1_P1_RX_DN<2>")
	)
	(segment
		(start 83.072732 -385.404868)
		(end 83.194398 -385.334764)
		(width 0.14224)
		(layer "In11.Cu")
		(net "P5E_CPU1_P1_RX_DN<2>")
	)
	(segment
		(start 99.139756 -277.832058)
		(end 99.114356 -277.817326)
		(width 0.1143)
		(layer "In11.Cu")
		(net "P5E_CPU1_P1_RX_DN<2>")
	)
	(segment
		(start 99.071684 -289.819842)
		(end 99.108006 -289.79876)
		(width 0.1143)
		(layer "In11.Cu")
		(net "P5E_CPU1_P1_RX_DN<2>")
	)
	(segment
		(start 99.108006 -291.418772)
		(end 99.108768 -291.418264)
		(width 0.1143)
		(layer "In11.Cu")
		(net "P5E_CPU1_P1_RX_DN<2>")
	)
	(segment
		(start 102.362254 -309.127144)
		(end 98.310192 -299.34408)
		(width 0.14224)
		(layer "In11.Cu")
		(net "P5E_CPU1_P1_RX_DN<2>")
	)
	(segment
		(start 82.877406 -384.84683)
		(end 82.882232 -384.234944)
		(width 0.14224)
		(layer "In11.Cu")
		(net "P5E_CPU1_P1_RX_DN<2>")
	)
	(segment
		(start 99.112324 -277.81631)
		(end 99.111562 -277.815802)
		(width 0.1143)
		(layer "In11.Cu")
		(net "P5E_CPU1_P1_RX_DN<2>")
	)
	(segment
		(start 98.310192 -296.435526)
		(end 98.355912 -296.389806)
		(width 0.1143)
		(layer "In11.Cu")
		(net "P5E_CPU1_P1_RX_DN<2>")
	)
	(segment
		(start 83.061556 -381.645922)
		(end 77.884274 -376.185684)
		(width 0.14224)
		(layer "In11.Cu")
		(net "P5E_CPU1_P1_RX_DN<2>")
	)
	(segment
		(start 99.139756 -281.072082)
		(end 99.110546 -281.055572)
		(width 0.1143)
		(layer "In11.Cu")
		(net "P5E_CPU1_P1_RX_DN<2>")
	)
	(segment
		(start 99.110038 -283.317696)
		(end 99.139756 -283.300678)
		(width 0.1143)
		(layer "In11.Cu")
		(net "P5E_CPU1_P1_RX_DN<2>")
	)
	(segment
		(start 99.139756 -285.932118)
		(end 99.114102 -285.917386)
		(width 0.1143)
		(layer "In11.Cu")
		(net "P5E_CPU1_P1_RX_DN<2>")
	)
	(segment
		(start 99.071684 -284.96006)
		(end 99.108006 -284.938978)
		(width 0.1143)
		(layer "In11.Cu")
		(net "P5E_CPU1_P1_RX_DN<2>")
	)
	(segment
		(start 99.115372 -289.157918)
		(end 99.114102 -289.157156)
		(width 0.1143)
		(layer "In11.Cu")
		(net "P5E_CPU1_P1_RX_DN<2>")
	)
	(segment
		(start 118.39702 -338.725002)
		(end 116.68887 -329.22337)
		(width 0.14224)
		(layer "In11.Cu")
		(net "P5E_CPU1_P1_RX_DN<2>")
	)
	(segment
		(start 99.108768 -284.93847)
		(end 99.110038 -284.937708)
		(width 0.1143)
		(layer "In11.Cu")
		(net "P5E_CPU1_P1_RX_DN<2>")
	)
	(segment
		(start 81.573624 -366.34928)
		(end 81.764886 -366.316514)
		(width 0.14224)
		(layer "In11.Cu")
		(net "P5E_CPU1_P1_RX_DN<2>")
	)
	(segment
		(start 99.108768 -291.418264)
		(end 99.110038 -291.417502)
		(width 0.1143)
		(layer "In11.Cu")
		(net "P5E_CPU1_P1_RX_DN<2>")
	)
	(segment
		(start 116.68887 -329.22337)
		(end 115.607338 -327.154794)
		(width 0.14224)
		(layer "In11.Cu")
		(net "P5E_CPU1_P1_RX_DN<2>")
	)
	(segment
		(start 80.922368 -367.270284)
		(end 81.11363 -367.237518)
		(width 0.14224)
		(layer "In11.Cu")
		(net "P5E_CPU1_P1_RX_DN<2>")
	)
	(segment
		(start 77.407262 -374.84812)
		(end 77.234542 -373.047006)
		(width 0.14224)
		(layer "In11.Cu")
		(net "P5E_CPU1_P1_RX_DN<2>")
	)
	(segment
		(start 99.114102 -284.297374)
		(end 99.108006 -284.293818)
		(width 0.1143)
		(layer "In11.Cu")
		(net "P5E_CPU1_P1_RX_DN<2>")
	)
	(segment
		(start 80.057498 -368.731038)
		(end 80.024732 -368.54003)
		(width 0.14224)
		(layer "In11.Cu")
		(net "P5E_CPU1_P1_RX_DN<2>")
	)
	(segment
		(start 99.110038 -284.937708)
		(end 99.139756 -284.92069)
		(width 0.1143)
		(layer "In11.Cu")
		(net "P5E_CPU1_P1_RX_DN<2>")
	)
	(segment
		(start 117.911372 -341.975948)
		(end 117.911372 -341.975694)
		(width 0.14224)
		(layer "In11.Cu")
		(net "P5E_CPU1_P1_RX_DN<2>")
	)
	(segment
		(start 99.114102 -292.39718)
		(end 99.108006 -292.393624)
		(width 0.1143)
		(layer "In11.Cu")
		(net "P5E_CPU1_P1_RX_DN<2>")
	)
	(segment
		(start 118.39702 -340.803738)
		(end 118.39702 -338.725002)
		(width 0.14224)
		(layer "In11.Cu")
		(net "P5E_CPU1_P1_RX_DN<2>")
	)
	(segment
		(start 99.110038 -281.697684)
		(end 99.139756 -281.680666)
		(width 0.1143)
		(layer "In11.Cu")
		(net "P5E_CPU1_P1_RX_DN<2>")
	)
	(segment
		(start 99.108006 -278.45893)
		(end 99.108768 -278.458422)
		(width 0.1143)
		(layer "In11.Cu")
		(net "P5E_CPU1_P1_RX_DN<2>")
	)
	(segment
		(start 99.139756 -294.031924)
		(end 99.115372 -294.017954)
		(width 0.1143)
		(layer "In11.Cu")
		(net "P5E_CPU1_P1_RX_DN<2>")
	)
	(segment
		(start 99.115372 -282.678124)
		(end 99.114102 -282.677362)
		(width 0.1143)
		(layer "In11.Cu")
		(net "P5E_CPU1_P1_RX_DN<2>")
	)
	(segment
		(start 99.108006 -289.79876)
		(end 99.108768 -289.798252)
		(width 0.1143)
		(layer "In11.Cu")
		(net "P5E_CPU1_P1_RX_DN<2>")
	)
	(segment
		(start 99.071684 -291.439854)
		(end 99.108006 -291.418772)
		(width 0.1143)
		(layer "In11.Cu")
		(net "P5E_CPU1_P1_RX_DN<2>")
	)
	(segment
		(start 98.650298 -280.250646)
		(end 98.639376 -280.24455)
		(width 0.1143)
		(layer "In11.Cu")
		(net "P5E_CPU1_P1_RX_DN<2>")
	)
	(segment
		(start 80.462374 -368.158522)
		(end 80.7085 -367.810288)
		(width 0.14224)
		(layer "In11.Cu")
		(net "P5E_CPU1_P1_RX_DN<2>")
	)
	(segment
		(start 82.882232 -384.234944)
		(end 83.18627 -383.93116)
		(width 0.14224)
		(layer "In11.Cu")
		(net "P5E_CPU1_P1_RX_DN<2>")
	)
	(segment
		(start 81.11363 -367.237518)
		(end 81.359756 -366.889284)
		(width 0.14224)
		(layer "In11.Cu")
		(net "P5E_CPU1_P1_RX_DN<2>")
	)
	(segment
		(start 99.102164 -276.190456)
		(end 99.098608 -276.187916)
		(width 0.1143)
		(layer "In11.Cu")
		(net "P5E_CPU1_P1_RX_DN<2>")
	)
	(segment
		(start 83.072224 -385.405376)
		(end 83.072732 -385.404868)
		(width 0.14224)
		(layer "In11.Cu")
		(net "P5E_CPU1_P1_RX_DN<2>")
	)
	(segment
		(start 99.108006 -294.013636)
		(end 99.071684 -293.992554)
		(width 0.1143)
		(layer "In11.Cu")
		(net "P5E_CPU1_P1_RX_DN<2>")
	)
	(segment
		(start 99.114102 -290.777168)
		(end 99.108006 -290.773612)
		(width 0.1143)
		(layer "In11.Cu")
		(net "P5E_CPU1_P1_RX_DN<2>")
	)
	(segment
		(start 99.108768 -289.798252)
		(end 99.110038 -289.79749)
		(width 0.1143)
		(layer "In11.Cu")
		(net "P5E_CPU1_P1_RX_DN<2>")
	)
	(segment
		(start 99.111562 -277.815802)
		(end 99.108768 -277.814278)
		(width 0.1143)
		(layer "In11.Cu")
		(net "P5E_CPU1_P1_RX_DN<2>")
	)
	(segment
		(start 98.361754 -274.97913)
		(end 98.27895 -274.896326)
		(width 0.1143)
		(layer "In11.Cu")
		(net "P5E_CPU1_P1_RX_DN<2>")
	)
	(segment
		(start 99.139756 -284.312106)
		(end 99.115372 -284.298136)
		(width 0.1143)
		(layer "In11.Cu")
		(net "P5E_CPU1_P1_RX_DN<2>")
	)
	(segment
		(start 99.114356 -277.817326)
		(end 99.112324 -277.81631)
		(width 0.1143)
		(layer "In11.Cu")
		(net "P5E_CPU1_P1_RX_DN<2>")
	)
	(segment
		(start 99.071684 -276.86)
		(end 99.108006 -276.838918)
		(width 0.1143)
		(layer "In11.Cu")
		(net "P5E_CPU1_P1_RX_DN<2>")
	)
	(segment
		(start 99.115372 -290.77793)
		(end 99.114102 -290.777168)
		(width 0.1143)
		(layer "In11.Cu")
		(net "P5E_CPU1_P1_RX_DN<2>")
	)
	(segment
		(start 99.112324 -276.196298)
		(end 99.111562 -276.19579)
		(width 0.1143)
		(layer "In11.Cu")
		(net "P5E_CPU1_P1_RX_DN<2>")
	)
	(segment
		(start 98.310192 -299.34408)
		(end 98.310192 -296.463974)
		(width 0.14224)
		(layer "In11.Cu")
		(net "P5E_CPU1_P1_RX_DN<2>")
	)
	(segment
		(start 99.108006 -283.318966)
		(end 99.108768 -283.318458)
		(width 0.1143)
		(layer "In11.Cu")
		(net "P5E_CPU1_P1_RX_DN<2>")
	)
	(segment
		(start 99.108006 -282.673806)
		(end 99.071684 -282.652724)
		(width 0.1143)
		(layer "In11.Cu")
		(net "P5E_CPU1_P1_RX_DN<2>")
	)
	(segment
		(start 99.108768 -276.83841)
		(end 99.110038 -276.837648)
		(width 0.1143)
		(layer "In11.Cu")
		(net "P5E_CPU1_P1_RX_DN<2>")
	)
	(segment
		(start 98.825812 -295.158922)
		(end 98.825812 -295.14292)
		(width 0.1143)
		(layer "In11.Cu")
		(net "P5E_CPU1_P1_RX_DN<2>")
	)
	(arc
		(start 99.139756 -283.300678)
		(mid 99.295684 -282.996386)
		(end 99.139756 -282.692094)
		(width 0.1143)
		(layer "In11.Cu")
		(net "P5E_CPU1_P1_RX_DN<2>")
	)
	(arc
		(start 98.825812 -295.14292)
		(mid 98.893396 -294.884872)
		(end 99.067112 -294.682418)
		(width 0.1143)
		(layer "In11.Cu")
		(net "P5E_CPU1_P1_RX_DN<2>")
	)
	(arc
		(start 99.05746 -291.44976)
		(mid 99.064533 -291.444751)
		(end 99.071684 -291.439854)
		(width 0.1143)
		(layer "In11.Cu")
		(net "P5E_CPU1_P1_RX_DN<2>")
	)
	(arc
		(start 77.884274 -376.185684)
		(mid 77.815654 -376.100078)
		(end 77.7621 -376.004328)
		(width 0.14224)
		(layer "In11.Cu")
		(net "P5E_CPU1_P1_RX_DN<2>")
	)
	(arc
		(start 99.139756 -293.020496)
		(mid 99.295684 -292.716204)
		(end 99.139756 -292.411912)
		(width 0.1143)
		(layer "In11.Cu")
		(net "P5E_CPU1_P1_RX_DN<2>")
	)
	(arc
		(start 99.056444 -283.350716)
		(mid 99.06402 -283.34532)
		(end 99.071684 -283.340048)
		(width 0.1143)
		(layer "In11.Cu")
		(net "P5E_CPU1_P1_RX_DN<2>")
	)
	(arc
		(start 77.65161 -375.762012)
		(mid 77.491472 -375.315218)
		(end 77.407262 -374.84812)
		(width 0.14224)
		(layer "In11.Cu")
		(net "P5E_CPU1_P1_RX_DN<2>")
	)
	(arc
		(start 98.59899 -280.220928)
		(mid 98.355104 -279.731606)
		(end 98.637344 -279.263348)
		(width 0.1143)
		(layer "In11.Cu")
		(net "P5E_CPU1_P1_RX_DN<2>")
	)
	(arc
		(start 98.825812 -287.046162)
		(mid 98.891048 -286.782571)
		(end 99.071684 -286.579818)
		(width 0.1143)
		(layer "In11.Cu")
		(net "P5E_CPU1_P1_RX_DN<2>")
	)
	(arc
		(start 98.65487 -295.57091)
		(mid 98.781307 -295.381918)
		(end 98.825812 -295.158922)
		(width 0.1143)
		(layer "In11.Cu")
		(net "P5E_CPU1_P1_RX_DN<2>")
	)
	(arc
		(start 99.055428 -284.97149)
		(mid 99.063506 -284.965704)
		(end 99.071684 -284.96006)
		(width 0.1143)
		(layer "In11.Cu")
		(net "P5E_CPU1_P1_RX_DN<2>")
	)
	(arc
		(start 99.139756 -291.400484)
		(mid 99.295684 -291.096192)
		(end 99.139756 -290.7919)
		(width 0.1143)
		(layer "In11.Cu")
		(net "P5E_CPU1_P1_RX_DN<2>")
	)
	(arc
		(start 99.071684 -290.75253)
		(mid 99.063506 -290.746887)
		(end 99.055428 -290.7411)
		(width 0.1143)
		(layer "In11.Cu")
		(net "P5E_CPU1_P1_RX_DN<2>")
	)
	(arc
		(start 99.139756 -294.640508)
		(mid 99.295684 -294.336216)
		(end 99.139756 -294.031924)
		(width 0.1143)
		(layer "In11.Cu")
		(net "P5E_CPU1_P1_RX_DN<2>")
	)
	(arc
		(start 98.699066 -279.227534)
		(mid 98.79263 -279.101401)
		(end 98.825812 -278.94788)
		(width 0.1143)
		(layer "In11.Cu")
		(net "P5E_CPU1_P1_RX_DN<2>")
	)
	(arc
		(start 99.055428 -289.121088)
		(mid 98.890761 -288.922481)
		(end 98.825812 -288.672778)
		(width 0.1143)
		(layer "In11.Cu")
		(net "P5E_CPU1_P1_RX_DN<2>")
	)
	(arc
		(start 83.18627 -381.958596)
		(mid 83.153961 -381.790264)
		(end 83.061556 -381.645922)
		(width 0.14224)
		(layer "In11.Cu")
		(net "P5E_CPU1_P1_RX_DN<2>")
	)
	(arc
		(start 99.071684 -292.372542)
		(mid 99.064534 -292.367644)
		(end 99.05746 -292.362636)
		(width 0.1143)
		(layer "In11.Cu")
		(net "P5E_CPU1_P1_RX_DN<2>")
	)
	(arc
		(start 99.139756 -276.82063)
		(mid 99.295684 -276.516338)
		(end 99.139756 -276.212046)
		(width 0.1143)
		(layer "In11.Cu")
		(net "P5E_CPU1_P1_RX_DN<2>")
	)
	(arc
		(start 99.071684 -277.792688)
		(mid 99.064535 -277.787788)
		(end 99.05746 -277.782782)
		(width 0.1143)
		(layer "In11.Cu")
		(net "P5E_CPU1_P1_RX_DN<2>")
	)
	(arc
		(start 99.054412 -287.500568)
		(mid 98.886302 -287.304721)
		(end 98.825812 -287.053782)
		(width 0.1143)
		(layer "In11.Cu")
		(net "P5E_CPU1_P1_RX_DN<2>")
	)
	(arc
		(start 99.055428 -290.7411)
		(mid 98.832544 -290.286186)
		(end 99.055428 -289.831272)
		(width 0.1143)
		(layer "In11.Cu")
		(net "P5E_CPU1_P1_RX_DN<2>")
	)
	(arc
		(start 99.141534 -286.539178)
		(mid 99.254941 -286.406289)
		(end 99.295712 -286.23641)
		(width 0.1143)
		(layer "In11.Cu")
		(net "P5E_CPU1_P1_RX_DN<2>")
	)
	(arc
		(start 99.056444 -281.730704)
		(mid 99.06402 -281.725308)
		(end 99.071684 -281.720036)
		(width 0.1143)
		(layer "In11.Cu")
		(net "P5E_CPU1_P1_RX_DN<2>")
	)
	(arc
		(start 99.05746 -277.782782)
		(mid 98.830077 -277.326344)
		(end 99.05746 -276.869906)
		(width 0.1143)
		(layer "In11.Cu")
		(net "P5E_CPU1_P1_RX_DN<2>")
	)
	(arc
		(start 82.207354 -365.690658)
		(mid 82.309811 -365.575559)
		(end 82.4357 -365.486696)
		(width 0.14224)
		(layer "In11.Cu")
		(net "P5E_CPU1_P1_RX_DN<2>")
	)
	(arc
		(start 98.825812 -275.706332)
		(mid 98.779117 -275.535653)
		(end 98.665792 -275.399754)
		(width 0.1143)
		(layer "In11.Cu")
		(net "P5E_CPU1_P1_RX_DN<2>")
	)
	(arc
		(start 99.071684 -284.272736)
		(mid 99.06402 -284.267465)
		(end 99.056444 -284.262068)
		(width 0.1143)
		(layer "In11.Cu")
		(net "P5E_CPU1_P1_RX_DN<2>")
	)
	(arc
		(start 98.59899 -275.360892)
		(mid 98.447003 -275.204384)
		(end 98.365564 -275.00199)
		(width 0.1143)
		(layer "In11.Cu")
		(net "P5E_CPU1_P1_RX_DN<2>")
	)
	(arc
		(start 99.139756 -289.780472)
		(mid 99.295684 -289.47618)
		(end 99.139756 -289.171888)
		(width 0.1143)
		(layer "In11.Cu")
		(net "P5E_CPU1_P1_RX_DN<2>")
	)
	(arc
		(start 98.825812 -278.946356)
		(mid 98.890412 -278.683657)
		(end 99.069652 -278.481028)
		(width 0.1143)
		(layer "In11.Cu")
		(net "P5E_CPU1_P1_RX_DN<2>")
	)
	(arc
		(start 99.055428 -293.071296)
		(mid 99.063506 -293.06551)
		(end 99.071684 -293.059866)
		(width 0.1143)
		(layer "In11.Cu")
		(net "P5E_CPU1_P1_RX_DN<2>")
	)
	(arc
		(start 99.071684 -289.132518)
		(mid 99.063506 -289.126875)
		(end 99.055428 -289.121088)
		(width 0.1143)
		(layer "In11.Cu")
		(net "P5E_CPU1_P1_RX_DN<2>")
	)
	(arc
		(start 99.071684 -282.652724)
		(mid 99.06402 -282.647453)
		(end 99.056444 -282.642056)
		(width 0.1143)
		(layer "In11.Cu")
		(net "P5E_CPU1_P1_RX_DN<2>")
	)
	(arc
		(start 99.055428 -293.981124)
		(mid 98.832544 -293.52621)
		(end 99.055428 -293.071296)
		(width 0.1143)
		(layer "In11.Cu")
		(net "P5E_CPU1_P1_RX_DN<2>")
	)
	(arc
		(start 99.295712 -286.23641)
		(mid 99.254457 -286.065439)
		(end 99.139756 -285.932118)
		(width 0.1143)
		(layer "In11.Cu")
		(net "P5E_CPU1_P1_RX_DN<2>")
	)
	(arc
		(start 77.234542 -373.047006)
		(mid 77.257053 -372.775381)
		(end 77.372718 -372.528592)
		(width 0.14224)
		(layer "In11.Cu")
		(net "P5E_CPU1_P1_RX_DN<2>")
	)
	(arc
		(start 98.355912 -296.135298)
		(mid 98.404587 -295.890213)
		(end 98.543364 -295.682416)
		(width 0.1143)
		(layer "In11.Cu")
		(net "P5E_CPU1_P1_RX_DN<2>")
	)
	(arc
		(start 99.109022 -288.17824)
		(mid 99.294853 -287.856451)
		(end 99.10953 -287.53435)
		(width 0.1143)
		(layer "In11.Cu")
		(net "P5E_CPU1_P1_RX_DN<2>")
	)
	(arc
		(start 98.836226 -280.574242)
		(mid 98.786442 -280.387628)
		(end 98.650298 -280.250646)
		(width 0.1143)
		(layer "In11.Cu")
		(net "P5E_CPU1_P1_RX_DN<2>")
	)
	(arc
		(start 116.272818 -344.552778)
		(mid 116.953615 -343.935741)
		(end 117.425978 -343.14765)
		(width 0.14224)
		(layer "In11.Cu")
		(net "P5E_CPU1_P1_RX_DN<2>")
	)
	(arc
		(start 99.05746 -292.362636)
		(mid 98.830077 -291.906198)
		(end 99.05746 -291.44976)
		(width 0.1143)
		(layer "In11.Cu")
		(net "P5E_CPU1_P1_RX_DN<2>")
	)
	(arc
		(start 99.097338 -276.187154)
		(mid 98.904334 -275.979587)
		(end 98.825558 -275.707348)
		(width 0.1143)
		(layer "In11.Cu")
		(net "P5E_CPU1_P1_RX_DN<2>")
	)
	(arc
		(start 99.05746 -276.869906)
		(mid 99.064534 -276.864899)
		(end 99.071684 -276.86)
		(width 0.1143)
		(layer "In11.Cu")
		(net "P5E_CPU1_P1_RX_DN<2>")
	)
	(arc
		(start 99.139756 -278.440642)
		(mid 99.295684 -278.13635)
		(end 99.139756 -277.832058)
		(width 0.1143)
		(layer "In11.Cu")
		(net "P5E_CPU1_P1_RX_DN<2>")
	)
	(arc
		(start 99.055428 -289.831272)
		(mid 99.063506 -289.825486)
		(end 99.071684 -289.819842)
		(width 0.1143)
		(layer "In11.Cu")
		(net "P5E_CPU1_P1_RX_DN<2>")
	)
	(arc
		(start 98.825812 -288.672778)
		(mid 98.889482 -288.40549)
		(end 99.071684 -288.19983)
		(width 0.1143)
		(layer "In11.Cu")
		(net "P5E_CPU1_P1_RX_DN<2>")
	)
	(arc
		(start 99.139756 -281.680666)
		(mid 99.295684 -281.376374)
		(end 99.139756 -281.072082)
		(width 0.1143)
		(layer "In11.Cu")
		(net "P5E_CPU1_P1_RX_DN<2>")
	)
	(arc
		(start 99.056444 -284.262068)
		(mid 98.831273 -283.806392)
		(end 99.056444 -283.350716)
		(width 0.1143)
		(layer "In11.Cu")
		(net "P5E_CPU1_P1_RX_DN<2>")
	)
	(arc
		(start 98.365564 -275.00199)
		(mid 98.363541 -274.99058)
		(end 98.361754 -274.97913)
		(width 0.1143)
		(layer "In11.Cu")
		(net "P5E_CPU1_P1_RX_DN<2>")
	)
	(arc
		(start 99.093782 -281.045666)
		(mid 98.905213 -280.85777)
		(end 98.836226 -280.600658)
		(width 0.1143)
		(layer "In11.Cu")
		(net "P5E_CPU1_P1_RX_DN<2>")
	)
	(arc
		(start 99.071684 -285.892748)
		(mid 99.063506 -285.887105)
		(end 99.055428 -285.881318)
		(width 0.1143)
		(layer "In11.Cu")
		(net "P5E_CPU1_P1_RX_DN<2>")
	)
	(arc
		(start 99.139756 -284.92069)
		(mid 99.295684 -284.616398)
		(end 99.139756 -284.312106)
		(width 0.1143)
		(layer "In11.Cu")
		(net "P5E_CPU1_P1_RX_DN<2>")
	)
	(arc
		(start 99.055428 -285.881318)
		(mid 98.832544 -285.426404)
		(end 99.055428 -284.97149)
		(width 0.1143)
		(layer "In11.Cu")
		(net "P5E_CPU1_P1_RX_DN<2>")
	)
	(arc
		(start 99.056444 -282.642056)
		(mid 98.831273 -282.18638)
		(end 99.056444 -281.730704)
		(width 0.1143)
		(layer "In11.Cu")
		(net "P5E_CPU1_P1_RX_DN<2>")
	)
	(arc
		(start 98.599752 -280.221436)
		(mid 98.599371 -280.221182)
		(end 98.59899 -280.220928)
		(width 0.1143)
		(layer "In11.Cu")
		(net "P5E_CPU1_P1_RX_DN<2>")
	)
	(arc
		(start 99.071684 -293.992554)
		(mid 99.063506 -293.986911)
		(end 99.055428 -293.981124)
		(width 0.1143)
		(layer "In11.Cu")
		(net "P5E_CPU1_P1_RX_DN<2>")
	)
	(segment
		(start 98.44786 -277.870412)
		(end 97.981008 -278.13635)
		(width 0.12954)
		(layer "F.Cu")
		(net "P5E_CPU1_P1_RX_DN<1>")
	)
	(segment
		(start 80.998314 -385.31038)
		(end 81.519014 -385.31038)
		(width 0.127)
		(layer "F.Cu")
		(net "P5E_CPU1_P1_RX_DN<1>")
	)
	(segment
		(start 82.092038 -364.430818)
		(end 82.092546 -364.430818)
		(width 0.14224)
		(layer "In11.Cu")
		(net "P5E_CPU1_P1_RX_DN<1>")
	)
	(segment
		(start 98.198686 -284.311598)
		(end 98.12909 -284.270958)
		(width 0.1143)
		(layer "In11.Cu")
		(net "P5E_CPU1_P1_RX_DN<1>")
	)
	(segment
		(start 108.41609 -319.888108)
		(end 101.56063 -309.628032)
		(width 0.14224)
		(layer "In11.Cu")
		(net "P5E_CPU1_P1_RX_DN<1>")
	)
	(segment
		(start 81.487264 -364.78591)
		(end 81.536286 -364.59795)
		(width 0.14224)
		(layer "In11.Cu")
		(net "P5E_CPU1_P1_RX_DN<1>")
	)
	(segment
		(start 116.626894 -342.608408)
		(end 117.438932 -340.648544)
		(width 0.14224)
		(layer "In11.Cu")
		(net "P5E_CPU1_P1_RX_DN<1>")
	)
	(segment
		(start 77.196696 -377.040394)
		(end 77.19695 -377.040394)
		(width 0.14224)
		(layer "In11.Cu")
		(net "P5E_CPU1_P1_RX_DN<1>")
	)
	(segment
		(start 98.12909 -291.441632)
		(end 98.198686 -291.400992)
		(width 0.1143)
		(layer "In11.Cu")
		(net "P5E_CPU1_P1_RX_DN<1>")
	)
	(segment
		(start 97.59061 -295.69537)
		(end 97.70872 -295.57726)
		(width 0.1143)
		(layer "In11.Cu")
		(net "P5E_CPU1_P1_RX_DN<1>")
	)
	(segment
		(start 115.785646 -329.513692)
		(end 114.856006 -327.735438)
		(width 0.14224)
		(layer "In11.Cu")
		(net "P5E_CPU1_P1_RX_DN<1>")
	)
	(segment
		(start 98.12909 -283.341826)
		(end 98.198686 -283.301186)
		(width 0.1143)
		(layer "In11.Cu")
		(net "P5E_CPU1_P1_RX_DN<1>")
	)
	(segment
		(start 98.12909 -281.721814)
		(end 98.198686 -281.681174)
		(width 0.1143)
		(layer "In11.Cu")
		(net "P5E_CPU1_P1_RX_DN<1>")
	)
	(segment
		(start 87.879936 -361.03306)
		(end 95.904304 -357.039164)
		(width 0.14224)
		(layer "In11.Cu")
		(net "P5E_CPU1_P1_RX_DN<1>")
	)
	(segment
		(start 81.682336 -384.234944)
		(end 81.93913 -383.97815)
		(width 0.14224)
		(layer "In11.Cu")
		(net "P5E_CPU1_P1_RX_DN<1>")
	)
	(segment
		(start 97.698814 -279.268428)
		(end 97.700084 -279.267666)
		(width 0.1143)
		(layer "In11.Cu")
		(net "P5E_CPU1_P1_RX_DN<1>")
	)
	(segment
		(start 81.994502 -385.163822)
		(end 81.67751 -384.84683)
		(width 0.14224)
		(layer "In11.Cu")
		(net "P5E_CPU1_P1_RX_DN<1>")
	)
	(segment
		(start 80.514698 -365.357156)
		(end 80.563466 -365.169196)
		(width 0.14224)
		(layer "In11.Cu")
		(net "P5E_CPU1_P1_RX_DN<1>")
	)
	(segment
		(start 81.519014 -385.31038)
		(end 81.872328 -385.405376)
		(width 0.14224)
		(layer "In11.Cu")
		(net "P5E_CPU1_P1_RX_DN<1>")
	)
	(segment
		(start 97.415858 -296.389806)
		(end 97.415858 -296.117518)
		(width 0.1143)
		(layer "In11.Cu")
		(net "P5E_CPU1_P1_RX_DN<1>")
	)
	(segment
		(start 81.872328 -385.405376)
		(end 81.872836 -385.404868)
		(width 0.14224)
		(layer "In11.Cu")
		(net "P5E_CPU1_P1_RX_DN<1>")
	)
	(segment
		(start 98.3488 -278.2062)
		(end 98.27895 -278.13635)
		(width 0.1143)
		(layer "In11.Cu")
		(net "P5E_CPU1_P1_RX_DN<1>")
	)
	(segment
		(start 81.119472 -365.00181)
		(end 81.487264 -364.78591)
		(width 0.14224)
		(layer "In11.Cu")
		(net "P5E_CPU1_P1_RX_DN<1>")
	)
	(segment
		(start 95.904304 -357.039164)
		(end 115.565682 -343.90203)
		(width 0.14224)
		(layer "In11.Cu")
		(net "P5E_CPU1_P1_RX_DN<1>")
	)
	(segment
		(start 81.536286 -364.59795)
		(end 81.904332 -364.381796)
		(width 0.14224)
		(layer "In11.Cu")
		(net "P5E_CPU1_P1_RX_DN<1>")
	)
	(segment
		(start 98.198686 -289.17138)
		(end 98.12909 -289.13074)
		(width 0.1143)
		(layer "In11.Cu")
		(net "P5E_CPU1_P1_RX_DN<1>")
	)
	(segment
		(start 76.487528 -367.721388)
		(end 80.514698 -365.357156)
		(width 0.14224)
		(layer "In11.Cu")
		(net "P5E_CPU1_P1_RX_DN<1>")
	)
	(segment
		(start 97.698814 -280.244296)
		(end 97.698052 -280.243788)
		(width 0.1143)
		(layer "In11.Cu")
		(net "P5E_CPU1_P1_RX_DN<1>")
	)
	(segment
		(start 97.691956 -280.240232)
		(end 97.690432 -280.239216)
		(width 0.1143)
		(layer "In11.Cu")
		(net "P5E_CPU1_P1_RX_DN<1>")
	)
	(segment
		(start 97.695512 -280.242264)
		(end 97.694496 -280.241756)
		(width 0.1143)
		(layer "In11.Cu")
		(net "P5E_CPU1_P1_RX_DN<1>")
	)
	(segment
		(start 97.700084 -279.267666)
		(end 97.729802 -279.250648)
		(width 0.1143)
		(layer "In11.Cu")
		(net "P5E_CPU1_P1_RX_DN<1>")
	)
	(segment
		(start 80.931766 -364.953042)
		(end 81.119472 -365.00181)
		(width 0.14224)
		(layer "In11.Cu")
		(net "P5E_CPU1_P1_RX_DN<1>")
	)
	(segment
		(start 97.695512 -279.27046)
		(end 97.697036 -279.269444)
		(width 0.1143)
		(layer "In11.Cu")
		(net "P5E_CPU1_P1_RX_DN<1>")
	)
	(segment
		(start 97.729802 -280.262076)
		(end 97.698814 -280.244296)
		(width 0.1143)
		(layer "In11.Cu")
		(net "P5E_CPU1_P1_RX_DN<1>")
	)
	(segment
		(start 97.690432 -280.239216)
		(end 97.658936 -280.220928)
		(width 0.1143)
		(layer "In11.Cu")
		(net "P5E_CPU1_P1_RX_DN<1>")
	)
	(segment
		(start 98.12909 -294.681656)
		(end 98.198686 -294.641016)
		(width 0.1143)
		(layer "In11.Cu")
		(net "P5E_CPU1_P1_RX_DN<1>")
	)
	(segment
		(start 74.243946 -370.75618)
		(end 76.334112 -367.861342)
		(width 0.14224)
		(layer "In11.Cu")
		(net "P5E_CPU1_P1_RX_DN<1>")
	)
	(segment
		(start 97.698052 -279.268936)
		(end 97.698814 -279.268428)
		(width 0.1143)
		(layer "In11.Cu")
		(net "P5E_CPU1_P1_RX_DN<1>")
	)
	(segment
		(start 98.12909 -293.061644)
		(end 98.198686 -293.021004)
		(width 0.1143)
		(layer "In11.Cu")
		(net "P5E_CPU1_P1_RX_DN<1>")
	)
	(segment
		(start 97.370138 -296.435526)
		(end 97.415858 -296.389806)
		(width 0.1143)
		(layer "In11.Cu")
		(net "P5E_CPU1_P1_RX_DN<1>")
	)
	(segment
		(start 98.168206 -288.178748)
		(end 98.200718 -288.159952)
		(width 0.1143)
		(layer "In11.Cu")
		(net "P5E_CPU1_P1_RX_DN<1>")
	)
	(segment
		(start 98.198686 -290.791392)
		(end 98.12909 -290.750752)
		(width 0.1143)
		(layer "In11.Cu")
		(net "P5E_CPU1_P1_RX_DN<1>")
	)
	(segment
		(start 80.563466 -365.169196)
		(end 80.931766 -364.953042)
		(width 0.14224)
		(layer "In11.Cu")
		(net "P5E_CPU1_P1_RX_DN<1>")
	)
	(segment
		(start 81.890616 -381.87884)
		(end 77.196696 -377.040394)
		(width 0.14224)
		(layer "In11.Cu")
		(net "P5E_CPU1_P1_RX_DN<1>")
	)
	(segment
		(start 97.698052 -280.243788)
		(end 97.697036 -280.24328)
		(width 0.1143)
		(layer "In11.Cu")
		(net "P5E_CPU1_P1_RX_DN<1>")
	)
	(segment
		(start 97.658936 -279.291796)
		(end 97.695512 -279.27046)
		(width 0.1143)
		(layer "In11.Cu")
		(net "P5E_CPU1_P1_RX_DN<1>")
	)
	(segment
		(start 81.994502 -385.334764)
		(end 81.994502 -385.163822)
		(width 0.14224)
		(layer "In11.Cu")
		(net "P5E_CPU1_P1_RX_DN<1>")
	)
	(segment
		(start 101.56063 -309.628032)
		(end 97.370138 -299.510958)
		(width 0.14224)
		(layer "In11.Cu")
		(net "P5E_CPU1_P1_RX_DN<1>")
	)
	(segment
		(start 98.168206 -286.558736)
		(end 98.200718 -286.53994)
		(width 0.1143)
		(layer "In11.Cu")
		(net "P5E_CPU1_P1_RX_DN<1>")
	)
	(segment
		(start 97.370138 -296.463974)
		(end 97.370138 -296.435526)
		(width 0.1143)
		(layer "In11.Cu")
		(net "P5E_CPU1_P1_RX_DN<1>")
	)
	(segment
		(start 97.694496 -280.241756)
		(end 97.691956 -280.240232)
		(width 0.1143)
		(layer "In11.Cu")
		(net "P5E_CPU1_P1_RX_DN<1>")
	)
	(segment
		(start 98.27895 -278.13635)
		(end 97.981008 -278.13635)
		(width 0.1143)
		(layer "In11.Cu")
		(net "P5E_CPU1_P1_RX_DN<1>")
	)
	(segment
		(start 81.904332 -364.381796)
		(end 82.092038 -364.430818)
		(width 0.14224)
		(layer "In11.Cu")
		(net "P5E_CPU1_P1_RX_DN<1>")
	)
	(segment
		(start 98.12909 -288.201608)
		(end 98.168206 -288.178748)
		(width 0.1143)
		(layer "In11.Cu")
		(net "P5E_CPU1_P1_RX_DN<1>")
	)
	(segment
		(start 97.697036 -279.269444)
		(end 97.698052 -279.268936)
		(width 0.1143)
		(layer "In11.Cu")
		(net "P5E_CPU1_P1_RX_DN<1>")
	)
	(segment
		(start 97.370138 -299.510958)
		(end 97.370138 -296.463974)
		(width 0.14224)
		(layer "In11.Cu")
		(net "P5E_CPU1_P1_RX_DN<1>")
	)
	(segment
		(start 114.856006 -327.735438)
		(end 108.41609 -319.888108)
		(width 0.14224)
		(layer "In11.Cu")
		(net "P5E_CPU1_P1_RX_DN<1>")
	)
	(segment
		(start 98.12909 -278.48179)
		(end 98.198686 -278.44115)
		(width 0.1143)
		(layer "In11.Cu")
		(net "P5E_CPU1_P1_RX_DN<1>")
	)
	(segment
		(start 117.438932 -340.648544)
		(end 117.438932 -338.708746)
		(width 0.14224)
		(layer "In11.Cu")
		(net "P5E_CPU1_P1_RX_DN<1>")
	)
	(segment
		(start 77.072744 -376.861832)
		(end 76.49083 -375.636536)
		(width 0.14224)
		(layer "In11.Cu")
		(net "P5E_CPU1_P1_RX_DN<1>")
	)
	(segment
		(start 98.198686 -285.93161)
		(end 98.12909 -285.89097)
		(width 0.1143)
		(layer "In11.Cu")
		(net "P5E_CPU1_P1_RX_DN<1>")
	)
	(segment
		(start 98.12909 -289.82162)
		(end 98.198686 -289.78098)
		(width 0.1143)
		(layer "In11.Cu")
		(net "P5E_CPU1_P1_RX_DN<1>")
	)
	(segment
		(start 74.140314 -371.81409)
		(end 74.125328 -371.136418)
		(width 0.14224)
		(layer "In11.Cu")
		(net "P5E_CPU1_P1_RX_DN<1>")
	)
	(segment
		(start 81.986374 -383.864104)
		(end 81.986374 -382.11506)
		(width 0.14224)
		(layer "In11.Cu")
		(net "P5E_CPU1_P1_RX_DN<1>")
	)
	(segment
		(start 98.198686 -282.691586)
		(end 98.12909 -282.650946)
		(width 0.1143)
		(layer "In11.Cu")
		(net "P5E_CPU1_P1_RX_DN<1>")
	)
	(segment
		(start 76.429362 -375.526046)
		(end 74.231754 -372.11254)
		(width 0.14224)
		(layer "In11.Cu")
		(net "P5E_CPU1_P1_RX_DN<1>")
	)
	(segment
		(start 98.198686 -287.551622)
		(end 98.13163 -287.512506)
		(width 0.1143)
		(layer "In11.Cu")
		(net "P5E_CPU1_P1_RX_DN<1>")
	)
	(segment
		(start 82.092546 -364.430818)
		(end 87.879936 -361.03306)
		(width 0.14224)
		(layer "In11.Cu")
		(net "P5E_CPU1_P1_RX_DN<1>")
	)
	(segment
		(start 98.198686 -292.411404)
		(end 98.12909 -292.370764)
		(width 0.1143)
		(layer "In11.Cu")
		(net "P5E_CPU1_P1_RX_DN<1>")
	)
	(segment
		(start 117.438932 -338.708746)
		(end 115.785646 -329.513692)
		(width 0.14224)
		(layer "In11.Cu")
		(net "P5E_CPU1_P1_RX_DN<1>")
	)
	(segment
		(start 98.131122 -286.580072)
		(end 98.168206 -286.558736)
		(width 0.1143)
		(layer "In11.Cu")
		(net "P5E_CPU1_P1_RX_DN<1>")
	)
	(segment
		(start 98.198686 -281.071574)
		(end 98.12909 -281.030934)
		(width 0.1143)
		(layer "In11.Cu")
		(net "P5E_CPU1_P1_RX_DN<1>")
	)
	(segment
		(start 98.198686 -294.031416)
		(end 98.12909 -293.990776)
		(width 0.1143)
		(layer "In11.Cu")
		(net "P5E_CPU1_P1_RX_DN<1>")
	)
	(segment
		(start 81.67751 -384.84683)
		(end 81.682336 -384.234944)
		(width 0.14224)
		(layer "In11.Cu")
		(net "P5E_CPU1_P1_RX_DN<1>")
	)
	(segment
		(start 81.872836 -385.404868)
		(end 81.994502 -385.334764)
		(width 0.14224)
		(layer "In11.Cu")
		(net "P5E_CPU1_P1_RX_DN<1>")
	)
	(segment
		(start 98.12909 -286.581596)
		(end 98.131122 -286.580072)
		(width 0.1143)
		(layer "In11.Cu")
		(net "P5E_CPU1_P1_RX_DN<1>")
	)
	(segment
		(start 98.12909 -284.961838)
		(end 98.198686 -284.921198)
		(width 0.1143)
		(layer "In11.Cu")
		(net "P5E_CPU1_P1_RX_DN<1>")
	)
	(segment
		(start 97.697036 -280.24328)
		(end 97.695512 -280.242264)
		(width 0.1143)
		(layer "In11.Cu")
		(net "P5E_CPU1_P1_RX_DN<1>")
	)
	(arc
		(start 98.12909 -281.030934)
		(mid 97.950277 -280.828584)
		(end 97.885758 -280.566368)
		(width 0.1143)
		(layer "In11.Cu")
		(net "P5E_CPU1_P1_RX_DN<1>")
	)
	(arc
		(start 98.12909 -289.13074)
		(mid 97.885763 -288.666174)
		(end 98.12909 -288.201608)
		(width 0.1143)
		(layer "In11.Cu")
		(net "P5E_CPU1_P1_RX_DN<1>")
	)
	(arc
		(start 76.49083 -375.636536)
		(mid 76.46187 -375.580304)
		(end 76.429362 -375.526046)
		(width 0.14224)
		(layer "In11.Cu")
		(net "P5E_CPU1_P1_RX_DN<1>")
	)
	(arc
		(start 98.198686 -278.44115)
		(mid 98.296451 -278.338174)
		(end 98.3488 -278.2062)
		(width 0.1143)
		(layer "In11.Cu")
		(net "P5E_CPU1_P1_RX_DN<1>")
	)
	(arc
		(start 98.12909 -285.89097)
		(mid 97.885763 -285.426404)
		(end 98.12909 -284.961838)
		(width 0.1143)
		(layer "In11.Cu")
		(net "P5E_CPU1_P1_RX_DN<1>")
	)
	(arc
		(start 98.355658 -286.23641)
		(mid 98.314109 -286.064988)
		(end 98.198686 -285.93161)
		(width 0.1143)
		(layer "In11.Cu")
		(net "P5E_CPU1_P1_RX_DN<1>")
	)
	(arc
		(start 98.355658 -287.856422)
		(mid 98.314109 -287.685)
		(end 98.198686 -287.551622)
		(width 0.1143)
		(layer "In11.Cu")
		(net "P5E_CPU1_P1_RX_DN<1>")
	)
	(arc
		(start 98.198686 -283.301186)
		(mid 98.355663 -282.996386)
		(end 98.198686 -282.691586)
		(width 0.1143)
		(layer "In11.Cu")
		(net "P5E_CPU1_P1_RX_DN<1>")
	)
	(arc
		(start 98.200718 -286.53994)
		(mid 98.314647 -286.406793)
		(end 98.355658 -286.23641)
		(width 0.1143)
		(layer "In11.Cu")
		(net "P5E_CPU1_P1_RX_DN<1>")
	)
	(arc
		(start 74.125328 -371.136418)
		(mid 74.153628 -370.936631)
		(end 74.243946 -370.75618)
		(width 0.14224)
		(layer "In11.Cu")
		(net "P5E_CPU1_P1_RX_DN<1>")
	)
	(arc
		(start 74.231754 -372.11254)
		(mid 74.165431 -371.96963)
		(end 74.140314 -371.81409)
		(width 0.14224)
		(layer "In11.Cu")
		(net "P5E_CPU1_P1_RX_DN<1>")
	)
	(arc
		(start 98.13163 -287.512506)
		(mid 97.950978 -287.309761)
		(end 97.885758 -287.046162)
		(width 0.1143)
		(layer "In11.Cu")
		(net "P5E_CPU1_P1_RX_DN<1>")
	)
	(arc
		(start 97.885758 -287.046162)
		(mid 97.950273 -286.783943)
		(end 98.12909 -286.581596)
		(width 0.1143)
		(layer "In11.Cu")
		(net "P5E_CPU1_P1_RX_DN<1>")
	)
	(arc
		(start 77.19695 -377.040394)
		(mid 77.127552 -376.956188)
		(end 77.072744 -376.861832)
		(width 0.14224)
		(layer "In11.Cu")
		(net "P5E_CPU1_P1_RX_DN<1>")
	)
	(arc
		(start 98.12909 -290.750752)
		(mid 97.885763 -290.286186)
		(end 98.12909 -289.82162)
		(width 0.1143)
		(layer "In11.Cu")
		(net "P5E_CPU1_P1_RX_DN<1>")
	)
	(arc
		(start 98.12909 -293.990776)
		(mid 97.885763 -293.52621)
		(end 98.12909 -293.061644)
		(width 0.1143)
		(layer "In11.Cu")
		(net "P5E_CPU1_P1_RX_DN<1>")
	)
	(arc
		(start 97.885758 -295.146222)
		(mid 97.950273 -294.884003)
		(end 98.12909 -294.681656)
		(width 0.1143)
		(layer "In11.Cu")
		(net "P5E_CPU1_P1_RX_DN<1>")
	)
	(arc
		(start 98.198686 -294.641016)
		(mid 98.355663 -294.336216)
		(end 98.198686 -294.031416)
		(width 0.1143)
		(layer "In11.Cu")
		(net "P5E_CPU1_P1_RX_DN<1>")
	)
	(arc
		(start 98.12909 -282.650946)
		(mid 97.885763 -282.18638)
		(end 98.12909 -281.721814)
		(width 0.1143)
		(layer "In11.Cu")
		(net "P5E_CPU1_P1_RX_DN<1>")
	)
	(arc
		(start 98.198686 -281.681174)
		(mid 98.355663 -281.376374)
		(end 98.198686 -281.071574)
		(width 0.1143)
		(layer "In11.Cu")
		(net "P5E_CPU1_P1_RX_DN<1>")
	)
	(arc
		(start 81.986374 -382.11506)
		(mid 81.96153 -381.987609)
		(end 81.890616 -381.87884)
		(width 0.14224)
		(layer "In11.Cu")
		(net "P5E_CPU1_P1_RX_DN<1>")
	)
	(arc
		(start 76.334112 -367.861342)
		(mid 76.403556 -367.783405)
		(end 76.487528 -367.721388)
		(width 0.14224)
		(layer "In11.Cu")
		(net "P5E_CPU1_P1_RX_DN<1>")
	)
	(arc
		(start 98.198686 -284.921198)
		(mid 98.355663 -284.616398)
		(end 98.198686 -284.311598)
		(width 0.1143)
		(layer "In11.Cu")
		(net "P5E_CPU1_P1_RX_DN<1>")
	)
	(arc
		(start 81.93913 -383.97815)
		(mid 81.974092 -383.925825)
		(end 81.986374 -383.864104)
		(width 0.14224)
		(layer "In11.Cu")
		(net "P5E_CPU1_P1_RX_DN<1>")
	)
	(arc
		(start 97.729802 -279.250648)
		(mid 97.844478 -279.117314)
		(end 97.885758 -278.946356)
		(width 0.1143)
		(layer "In11.Cu")
		(net "P5E_CPU1_P1_RX_DN<1>")
	)
	(arc
		(start 115.565682 -343.90203)
		(mid 116.192265 -343.333947)
		(end 116.626894 -342.608408)
		(width 0.14224)
		(layer "In11.Cu")
		(net "P5E_CPU1_P1_RX_DN<1>")
	)
	(arc
		(start 98.198686 -293.021004)
		(mid 98.355663 -292.716204)
		(end 98.198686 -292.411404)
		(width 0.1143)
		(layer "In11.Cu")
		(net "P5E_CPU1_P1_RX_DN<1>")
	)
	(arc
		(start 97.885758 -280.566368)
		(mid 97.844503 -280.395397)
		(end 97.729802 -280.262076)
		(width 0.1143)
		(layer "In11.Cu")
		(net "P5E_CPU1_P1_RX_DN<1>")
	)
	(arc
		(start 97.885758 -278.946356)
		(mid 97.950273 -278.684137)
		(end 98.12909 -278.48179)
		(width 0.1143)
		(layer "In11.Cu")
		(net "P5E_CPU1_P1_RX_DN<1>")
	)
	(arc
		(start 98.198686 -289.78098)
		(mid 98.355663 -289.47618)
		(end 98.198686 -289.17138)
		(width 0.1143)
		(layer "In11.Cu")
		(net "P5E_CPU1_P1_RX_DN<1>")
	)
	(arc
		(start 98.198686 -291.400992)
		(mid 98.355663 -291.096192)
		(end 98.198686 -290.791392)
		(width 0.1143)
		(layer "In11.Cu")
		(net "P5E_CPU1_P1_RX_DN<1>")
	)
	(arc
		(start 98.200718 -288.159952)
		(mid 98.314647 -288.026805)
		(end 98.355658 -287.856422)
		(width 0.1143)
		(layer "In11.Cu")
		(net "P5E_CPU1_P1_RX_DN<1>")
	)
	(arc
		(start 98.12909 -284.270958)
		(mid 97.885763 -283.806392)
		(end 98.12909 -283.341826)
		(width 0.1143)
		(layer "In11.Cu")
		(net "P5E_CPU1_P1_RX_DN<1>")
	)
	(arc
		(start 97.658936 -280.220928)
		(mid 97.415609 -279.756362)
		(end 97.658936 -279.291796)
		(width 0.1143)
		(layer "In11.Cu")
		(net "P5E_CPU1_P1_RX_DN<1>")
	)
	(arc
		(start 98.12909 -292.370764)
		(mid 97.885763 -291.906198)
		(end 98.12909 -291.441632)
		(width 0.1143)
		(layer "In11.Cu")
		(net "P5E_CPU1_P1_RX_DN<1>")
	)
	(arc
		(start 97.415858 -296.117518)
		(mid 97.461279 -295.88908)
		(end 97.59061 -295.69537)
		(width 0.1143)
		(layer "In11.Cu")
		(net "P5E_CPU1_P1_RX_DN<1>")
	)
	(arc
		(start 97.70872 -295.57726)
		(mid 97.83854 -295.378701)
		(end 97.885758 -295.146222)
		(width 0.1143)
		(layer "In11.Cu")
		(net "P5E_CPU1_P1_RX_DN<1>")
	)
	(segment
		(start 97.798382 -385.31038)
		(end 98.319082 -385.31038)
		(width 0.127)
		(layer "F.Cu")
		(net "P5E_CPU1_P1_RX_DN<15>")
	)
	(segment
		(start 109.257846 -275.440394)
		(end 108.790994 -275.706332)
		(width 0.12954)
		(layer "F.Cu")
		(net "P5E_CPU1_P1_RX_DN<15>")
	)
	(segment
		(start 111.03483 -363.355382)
		(end 111.213646 -363.248194)
		(width 0.14224)
		(layer "In11.Cu")
		(net "P5E_CPU1_P1_RX_DN<15>")
	)
	(segment
		(start 98.79457 -385.335018)
		(end 98.79457 -384.735578)
		(width 0.14224)
		(layer "In11.Cu")
		(net "P5E_CPU1_P1_RX_DN<15>")
	)
	(segment
		(start 105.334308 -380.081028)
		(end 105.33253 -380.07925)
		(width 0.14224)
		(layer "In11.Cu")
		(net "P5E_CPU1_P1_RX_DN<15>")
	)
	(segment
		(start 105.336848 -379.375416)
		(end 105.336848 -378.953268)
		(width 0.14224)
		(layer "In11.Cu")
		(net "P5E_CPU1_P1_RX_DN<15>")
	)
	(segment
		(start 113.431066 -303.861216)
		(end 111.539782 -299.294804)
		(width 0.14224)
		(layer "In11.Cu")
		(net "P5E_CPU1_P1_RX_DN<15>")
	)
	(segment
		(start 110.41761 -277.830788)
		(end 110.3884 -277.81377)
		(width 0.1143)
		(layer "In11.Cu")
		(net "P5E_CPU1_P1_RX_DN<15>")
	)
	(segment
		(start 128.712214 -325.855076)
		(end 125.61062 -320.052192)
		(width 0.14224)
		(layer "In11.Cu")
		(net "P5E_CPU1_P1_RX_DN<15>")
	)
	(segment
		(start 105.332276 -380.550674)
		(end 105.334308 -380.548642)
		(width 0.14224)
		(layer "In11.Cu")
		(net "P5E_CPU1_P1_RX_DN<15>")
	)
	(segment
		(start 110.369858 -277.803102)
		(end 110.34903 -277.79091)
		(width 0.1143)
		(layer "In11.Cu")
		(net "P5E_CPU1_P1_RX_DN<15>")
	)
	(segment
		(start 109.922564 -277.006304)
		(end 109.920024 -277.005034)
		(width 0.1143)
		(layer "In11.Cu")
		(net "P5E_CPU1_P1_RX_DN<15>")
	)
	(segment
		(start 109.450632 -276.195028)
		(end 109.447838 -276.193504)
		(width 0.1143)
		(layer "In11.Cu")
		(net "P5E_CPU1_P1_RX_DN<15>")
	)
	(segment
		(start 128.35001 -351.205546)
		(end 131.160012 -343.92235)
		(width 0.14224)
		(layer "In11.Cu")
		(net "P5E_CPU1_P1_RX_DN<15>")
	)
	(segment
		(start 111.539782 -299.294804)
		(end 111.339122 -298.769024)
		(width 0.14224)
		(layer "In11.Cu")
		(net "P5E_CPU1_P1_RX_DN<15>")
	)
	(segment
		(start 109.41685 -276.175724)
		(end 109.416088 -276.175216)
		(width 0.1143)
		(layer "In11.Cu")
		(net "P5E_CPU1_P1_RX_DN<15>")
	)
	(segment
		(start 101.752654 -381.489458)
		(end 104.383078 -381.489458)
		(width 0.14224)
		(layer "In11.Cu")
		(net "P5E_CPU1_P1_RX_DN<15>")
	)
	(segment
		(start 110.385352 -277.811992)
		(end 110.369858 -277.803102)
		(width 0.1143)
		(layer "In11.Cu")
		(net "P5E_CPU1_P1_RX_DN<15>")
	)
	(segment
		(start 109.908086 -276.997668)
		(end 109.907832 -276.997668)
		(width 0.1143)
		(layer "In11.Cu")
		(net "P5E_CPU1_P1_RX_DN<15>")
	)
	(segment
		(start 105.20172 -377.259088)
		(end 105.339388 -377.122436)
		(width 0.14224)
		(layer "In11.Cu")
		(net "P5E_CPU1_P1_RX_DN<15>")
	)
	(segment
		(start 116.206778 -360.578908)
		(end 126.181866 -353.914456)
		(width 0.14224)
		(layer "In11.Cu")
		(net "P5E_CPU1_P1_RX_DN<15>")
	)
	(segment
		(start 98.673666 -385.40436)
		(end 98.79457 -385.335018)
		(width 0.14224)
		(layer "In11.Cu")
		(net "P5E_CPU1_P1_RX_DN<15>")
	)
	(segment
		(start 110.838742 -278.25192)
		(end 110.41761 -277.830788)
		(width 0.1143)
		(layer "In11.Cu")
		(net "P5E_CPU1_P1_RX_DN<15>")
	)
	(segment
		(start 111.114332 -278.592534)
		(end 110.858808 -278.33701)
		(width 0.14224)
		(layer "In11.Cu")
		(net "P5E_CPU1_P1_RX_DN<15>")
	)
	(segment
		(start 111.206788 -295.34231)
		(end 111.114332 -279.263348)
		(width 0.14224)
		(layer "In11.Cu")
		(net "P5E_CPU1_P1_RX_DN<15>")
	)
	(segment
		(start 111.114332 -279.263348)
		(end 111.114332 -278.592534)
		(width 0.14224)
		(layer "In11.Cu")
		(net "P5E_CPU1_P1_RX_DN<15>")
	)
	(segment
		(start 105.195624 -379.941836)
		(end 105.19664 -379.514862)
		(width 0.14224)
		(layer "In11.Cu")
		(net "P5E_CPU1_P1_RX_DN<15>")
	)
	(segment
		(start 110.386876 -277.813008)
		(end 110.385352 -277.811992)
		(width 0.1143)
		(layer "In11.Cu")
		(net "P5E_CPU1_P1_RX_DN<15>")
	)
	(segment
		(start 131.160012 -339.048598)
		(end 128.872742 -326.317356)
		(width 0.14224)
		(layer "In11.Cu")
		(net "P5E_CPU1_P1_RX_DN<15>")
	)
	(segment
		(start 105.331768 -380.550928)
		(end 105.331768 -380.550674)
		(width 0.14224)
		(layer "In11.Cu")
		(net "P5E_CPU1_P1_RX_DN<15>")
	)
	(segment
		(start 105.336848 -378.250196)
		(end 105.339388 -378.247656)
		(width 0.14224)
		(layer "In11.Cu")
		(net "P5E_CPU1_P1_RX_DN<15>")
	)
	(segment
		(start 109.949742 -277.022052)
		(end 109.922564 -277.006304)
		(width 0.1143)
		(layer "In11.Cu")
		(net "P5E_CPU1_P1_RX_DN<15>")
	)
	(segment
		(start 109.918754 -277.004272)
		(end 109.917992 -277.003764)
		(width 0.1143)
		(layer "In11.Cu")
		(net "P5E_CPU1_P1_RX_DN<15>")
	)
	(segment
		(start 105.198164 -378.813822)
		(end 105.19918 -378.386848)
		(width 0.14224)
		(layer "In11.Cu")
		(net "P5E_CPU1_P1_RX_DN<15>")
	)
	(segment
		(start 111.339122 -298.769024)
		(end 111.206788 -295.34231)
		(width 0.14224)
		(layer "In11.Cu")
		(net "P5E_CPU1_P1_RX_DN<15>")
	)
	(segment
		(start 109.001306 -364.714282)
		(end 111.03483 -363.355382)
		(width 0.14224)
		(layer "In11.Cu")
		(net "P5E_CPU1_P1_RX_DN<15>")
	)
	(segment
		(start 109.917992 -277.003764)
		(end 109.908086 -276.997668)
		(width 0.1143)
		(layer "In11.Cu")
		(net "P5E_CPU1_P1_RX_DN<15>")
	)
	(segment
		(start 105.331768 -380.550674)
		(end 105.332276 -380.550674)
		(width 0.14224)
		(layer "In11.Cu")
		(net "P5E_CPU1_P1_RX_DN<15>")
	)
	(segment
		(start 105.339388 -377.122436)
		(end 105.34142 -376.032522)
		(width 0.14224)
		(layer "In11.Cu")
		(net "P5E_CPU1_P1_RX_DN<15>")
	)
	(segment
		(start 105.33507 -378.95149)
		(end 105.198164 -378.813822)
		(width 0.14224)
		(layer "In11.Cu")
		(net "P5E_CPU1_P1_RX_DN<15>")
	)
	(segment
		(start 105.200704 -377.686062)
		(end 105.20172 -377.259088)
		(width 0.14224)
		(layer "In11.Cu")
		(net "P5E_CPU1_P1_RX_DN<15>")
	)
	(segment
		(start 109.416088 -276.175216)
		(end 109.409738 -276.171406)
		(width 0.1143)
		(layer "In11.Cu")
		(net "P5E_CPU1_P1_RX_DN<15>")
	)
	(segment
		(start 111.213646 -363.248194)
		(end 116.206778 -360.578908)
		(width 0.14224)
		(layer "In11.Cu")
		(net "P5E_CPU1_P1_RX_DN<15>")
	)
	(segment
		(start 105.34142 -376.032522)
		(end 106.027982 -370.45519)
		(width 0.14224)
		(layer "In11.Cu")
		(net "P5E_CPU1_P1_RX_DN<15>")
	)
	(segment
		(start 125.61062 -320.052192)
		(end 118.288816 -311.13095)
		(width 0.14224)
		(layer "In11.Cu")
		(net "P5E_CPU1_P1_RX_DN<15>")
	)
	(segment
		(start 98.79457 -384.735578)
		(end 100.607114 -382.923034)
		(width 0.14224)
		(layer "In11.Cu")
		(net "P5E_CPU1_P1_RX_DN<15>")
	)
	(segment
		(start 105.339388 -378.247656)
		(end 105.339388 -377.825508)
		(width 0.14224)
		(layer "In11.Cu")
		(net "P5E_CPU1_P1_RX_DN<15>")
	)
	(segment
		(start 108.095542 -365.594392)
		(end 108.266484 -365.383826)
		(width 0.14224)
		(layer "In11.Cu")
		(net "P5E_CPU1_P1_RX_DN<15>")
	)
	(segment
		(start 109.445806 -276.192488)
		(end 109.445044 -276.19198)
		(width 0.1143)
		(layer "In11.Cu")
		(net "P5E_CPU1_P1_RX_DN<15>")
	)
	(segment
		(start 110.3884 -277.81377)
		(end 110.388146 -277.81377)
		(width 0.1143)
		(layer "In11.Cu")
		(net "P5E_CPU1_P1_RX_DN<15>")
	)
	(segment
		(start 105.066084 -381.078486)
		(end 105.066338 -381.078486)
		(width 0.14224)
		(layer "In11.Cu")
		(net "P5E_CPU1_P1_RX_DN<15>")
	)
	(segment
		(start 105.334308 -380.548642)
		(end 105.334308 -380.081028)
		(width 0.14224)
		(layer "In11.Cu")
		(net "P5E_CPU1_P1_RX_DN<15>")
	)
	(segment
		(start 109.17174 -275.789136)
		(end 109.088936 -275.706332)
		(width 0.1143)
		(layer "In11.Cu")
		(net "P5E_CPU1_P1_RX_DN<15>")
	)
	(segment
		(start 105.33253 -380.07925)
		(end 105.195624 -379.941836)
		(width 0.14224)
		(layer "In11.Cu")
		(net "P5E_CPU1_P1_RX_DN<15>")
	)
	(segment
		(start 109.445044 -276.19198)
		(end 109.41685 -276.175724)
		(width 0.1143)
		(layer "In11.Cu")
		(net "P5E_CPU1_P1_RX_DN<15>")
	)
	(segment
		(start 105.339388 -377.825508)
		(end 105.33761 -377.82373)
		(width 0.14224)
		(layer "In11.Cu")
		(net "P5E_CPU1_P1_RX_DN<15>")
	)
	(segment
		(start 109.920024 -277.005034)
		(end 109.918754 -277.004272)
		(width 0.1143)
		(layer "In11.Cu")
		(net "P5E_CPU1_P1_RX_DN<15>")
	)
	(segment
		(start 100.676964 -382.754632)
		(end 100.676964 -382.698498)
		(width 0.14224)
		(layer "In11.Cu")
		(net "P5E_CPU1_P1_RX_DN<15>")
	)
	(segment
		(start 131.160012 -343.92235)
		(end 131.160012 -339.048598)
		(width 0.14224)
		(layer "In11.Cu")
		(net "P5E_CPU1_P1_RX_DN<15>")
	)
	(segment
		(start 105.33761 -377.82373)
		(end 105.200704 -377.686062)
		(width 0.14224)
		(layer "In11.Cu")
		(net "P5E_CPU1_P1_RX_DN<15>")
	)
	(segment
		(start 105.19918 -378.386848)
		(end 105.336848 -378.250196)
		(width 0.14224)
		(layer "In11.Cu")
		(net "P5E_CPU1_P1_RX_DN<15>")
	)
	(segment
		(start 104.612694 -381.413766)
		(end 105.066084 -381.078486)
		(width 0.14224)
		(layer "In11.Cu")
		(net "P5E_CPU1_P1_RX_DN<15>")
	)
	(segment
		(start 98.319082 -385.31038)
		(end 98.672396 -385.405376)
		(width 0.14224)
		(layer "In11.Cu")
		(net "P5E_CPU1_P1_RX_DN<15>")
	)
	(segment
		(start 105.334308 -379.377956)
		(end 105.336848 -379.375416)
		(width 0.14224)
		(layer "In11.Cu")
		(net "P5E_CPU1_P1_RX_DN<15>")
	)
	(segment
		(start 110.388146 -277.81377)
		(end 110.386876 -277.813008)
		(width 0.1143)
		(layer "In11.Cu")
		(net "P5E_CPU1_P1_RX_DN<15>")
	)
	(segment
		(start 110.858808 -278.33701)
		(end 110.838742 -278.316944)
		(width 0.1143)
		(layer "In11.Cu")
		(net "P5E_CPU1_P1_RX_DN<15>")
	)
	(segment
		(start 100.89134 -382.1811)
		(end 101.463094 -381.609346)
		(width 0.14224)
		(layer "In11.Cu")
		(net "P5E_CPU1_P1_RX_DN<15>")
	)
	(segment
		(start 118.288816 -311.13095)
		(end 113.431066 -303.861216)
		(width 0.14224)
		(layer "In11.Cu")
		(net "P5E_CPU1_P1_RX_DN<15>")
	)
	(segment
		(start 128.872742 -326.317356)
		(end 128.712214 -325.855076)
		(width 0.14224)
		(layer "In11.Cu")
		(net "P5E_CPU1_P1_RX_DN<15>")
	)
	(segment
		(start 98.672396 -385.405376)
		(end 98.672904 -385.404868)
		(width 0.14224)
		(layer "In11.Cu")
		(net "P5E_CPU1_P1_RX_DN<15>")
	)
	(segment
		(start 109.088936 -275.706332)
		(end 108.790994 -275.706332)
		(width 0.1143)
		(layer "In11.Cu")
		(net "P5E_CPU1_P1_RX_DN<15>")
	)
	(segment
		(start 105.336848 -378.953268)
		(end 105.33507 -378.95149)
		(width 0.14224)
		(layer "In11.Cu")
		(net "P5E_CPU1_P1_RX_DN<15>")
	)
	(segment
		(start 109.447838 -276.193504)
		(end 109.445806 -276.192488)
		(width 0.1143)
		(layer "In11.Cu")
		(net "P5E_CPU1_P1_RX_DN<15>")
	)
	(segment
		(start 105.19664 -379.514862)
		(end 105.334308 -379.377956)
		(width 0.14224)
		(layer "In11.Cu")
		(net "P5E_CPU1_P1_RX_DN<15>")
	)
	(segment
		(start 98.672904 -385.404868)
		(end 98.673666 -385.40436)
		(width 0.14224)
		(layer "In11.Cu")
		(net "P5E_CPU1_P1_RX_DN<15>")
	)
	(segment
		(start 110.838742 -278.316944)
		(end 110.838742 -278.25192)
		(width 0.1143)
		(layer "In11.Cu")
		(net "P5E_CPU1_P1_RX_DN<15>")
	)
	(arc
		(start 126.181866 -353.914456)
		(mid 127.475392 -352.727641)
		(end 128.35001 -351.205546)
		(width 0.14224)
		(layer "In11.Cu")
		(net "P5E_CPU1_P1_RX_DN<15>")
	)
	(arc
		(start 101.463094 -381.609346)
		(mid 101.595959 -381.520631)
		(end 101.752654 -381.489458)
		(width 0.14224)
		(layer "In11.Cu")
		(net "P5E_CPU1_P1_RX_DN<15>")
	)
	(arc
		(start 109.634782 -276.514814)
		(mid 109.585461 -276.330294)
		(end 109.450632 -276.195028)
		(width 0.1143)
		(layer "In11.Cu")
		(net "P5E_CPU1_P1_RX_DN<15>")
	)
	(arc
		(start 100.607114 -382.923034)
		(mid 100.658794 -382.845785)
		(end 100.676964 -382.754632)
		(width 0.14224)
		(layer "In11.Cu")
		(net "P5E_CPU1_P1_RX_DN<15>")
	)
	(arc
		(start 109.409738 -276.171406)
		(mid 109.409357 -276.171152)
		(end 109.408976 -276.170898)
		(width 0.1143)
		(layer "In11.Cu")
		(net "P5E_CPU1_P1_RX_DN<15>")
	)
	(arc
		(start 104.383078 -381.489458)
		(mid 104.503962 -381.470045)
		(end 104.612694 -381.413766)
		(width 0.14224)
		(layer "In11.Cu")
		(net "P5E_CPU1_P1_RX_DN<15>")
	)
	(arc
		(start 109.408976 -276.170898)
		(mid 109.256989 -276.01439)
		(end 109.17555 -275.811996)
		(width 0.1143)
		(layer "In11.Cu")
		(net "P5E_CPU1_P1_RX_DN<15>")
	)
	(arc
		(start 106.027982 -370.45519)
		(mid 106.71969 -367.879293)
		(end 108.095542 -365.594392)
		(width 0.14224)
		(layer "In11.Cu")
		(net "P5E_CPU1_P1_RX_DN<15>")
	)
	(arc
		(start 105.066338 -381.078486)
		(mid 105.261713 -380.846225)
		(end 105.331768 -380.550928)
		(width 0.14224)
		(layer "In11.Cu")
		(net "P5E_CPU1_P1_RX_DN<15>")
	)
	(arc
		(start 110.34903 -277.79091)
		(mid 110.170217 -277.58856)
		(end 110.105698 -277.326344)
		(width 0.1143)
		(layer "In11.Cu")
		(net "P5E_CPU1_P1_RX_DN<15>")
	)
	(arc
		(start 110.105698 -277.326344)
		(mid 110.064443 -277.155373)
		(end 109.949742 -277.022052)
		(width 0.1143)
		(layer "In11.Cu")
		(net "P5E_CPU1_P1_RX_DN<15>")
	)
	(arc
		(start 109.907832 -276.997668)
		(mid 109.707743 -276.79218)
		(end 109.634782 -276.514814)
		(width 0.1143)
		(layer "In11.Cu")
		(net "P5E_CPU1_P1_RX_DN<15>")
	)
	(arc
		(start 100.676964 -382.698498)
		(mid 100.732682 -382.418474)
		(end 100.89134 -382.1811)
		(width 0.14224)
		(layer "In11.Cu")
		(net "P5E_CPU1_P1_RX_DN<15>")
	)
	(arc
		(start 109.17555 -275.811996)
		(mid 109.173527 -275.800586)
		(end 109.17174 -275.789136)
		(width 0.1143)
		(layer "In11.Cu")
		(net "P5E_CPU1_P1_RX_DN<15>")
	)
	(arc
		(start 108.266484 -365.383826)
		(mid 108.608771 -365.021482)
		(end 109.001306 -364.714282)
		(width 0.14224)
		(layer "In11.Cu")
		(net "P5E_CPU1_P1_RX_DN<15>")
	)
	(segment
		(start 96.598486 -385.31038)
		(end 97.119186 -385.31038)
		(width 0.127)
		(layer "F.Cu")
		(net "P5E_CPU1_P1_RX_DN<14>")
	)
	(segment
		(start 109.257846 -277.060406)
		(end 108.790994 -277.326344)
		(width 0.12954)
		(layer "F.Cu")
		(net "P5E_CPU1_P1_RX_DN<14>")
	)
	(segment
		(start 110.34903 -280.101802)
		(end 110.417864 -280.06167)
		(width 0.1143)
		(layer "In11.Cu")
		(net "P5E_CPU1_P1_RX_DN<14>")
	)
	(segment
		(start 109.922564 -278.626316)
		(end 109.920024 -278.625046)
		(width 0.1143)
		(layer "In11.Cu")
		(net "P5E_CPU1_P1_RX_DN<14>")
	)
	(segment
		(start 110.059978 -295.668954)
		(end 110.105698 -295.623234)
		(width 0.1143)
		(layer "In11.Cu")
		(net "P5E_CPU1_P1_RX_DN<14>")
	)
	(segment
		(start 110.059978 -298.466002)
		(end 110.059978 -295.697402)
		(width 0.14224)
		(layer "In11.Cu")
		(net "P5E_CPU1_P1_RX_DN<14>")
	)
	(segment
		(start 97.472246 -385.405376)
		(end 97.472754 -385.404868)
		(width 0.14224)
		(layer "In11.Cu")
		(net "P5E_CPU1_P1_RX_DN<14>")
	)
	(segment
		(start 109.949742 -278.642064)
		(end 109.924088 -278.627332)
		(width 0.1143)
		(layer "In11.Cu")
		(net "P5E_CPU1_P1_RX_DN<14>")
	)
	(segment
		(start 130.215132 -339.132926)
		(end 127.963676 -326.599296)
		(width 0.14224)
		(layer "In11.Cu")
		(net "P5E_CPU1_P1_RX_DN<14>")
	)
	(segment
		(start 110.418626 -279.451562)
		(end 110.388146 -279.433782)
		(width 0.1143)
		(layer "In11.Cu")
		(net "P5E_CPU1_P1_RX_DN<14>")
	)
	(segment
		(start 110.419388 -293.020496)
		(end 110.42015 -293.019988)
		(width 0.1143)
		(layer "In11.Cu")
		(net "P5E_CPU1_P1_RX_DN<14>")
	)
	(segment
		(start 110.350554 -294.68064)
		(end 110.38459 -294.660828)
		(width 0.1143)
		(layer "In11.Cu")
		(net "P5E_CPU1_P1_RX_DN<14>")
	)
	(segment
		(start 109.635798 -278.194262)
		(end 109.635798 -278.13635)
		(width 0.1143)
		(layer "In11.Cu")
		(net "P5E_CPU1_P1_RX_DN<14>")
	)
	(segment
		(start 110.388146 -293.038784)
		(end 110.419388 -293.020496)
		(width 0.1143)
		(layer "In11.Cu")
		(net "P5E_CPU1_P1_RX_DN<14>")
	)
	(segment
		(start 104.972358 -369.949476)
		(end 105.737152 -367.751106)
		(width 0.14224)
		(layer "In11.Cu")
		(net "P5E_CPU1_P1_RX_DN<14>")
	)
	(segment
		(start 109.479842 -277.832058)
		(end 109.408976 -277.79091)
		(width 0.1143)
		(layer "In11.Cu")
		(net "P5E_CPU1_P1_RX_DN<14>")
	)
	(segment
		(start 110.418626 -290.791392)
		(end 110.388146 -290.773612)
		(width 0.1143)
		(layer "In11.Cu")
		(net "P5E_CPU1_P1_RX_DN<14>")
	)
	(segment
		(start 110.388146 -289.1536)
		(end 110.34903 -289.13074)
		(width 0.1143)
		(layer "In11.Cu")
		(net "P5E_CPU1_P1_RX_DN<14>")
	)
	(segment
		(start 110.34903 -286.581596)
		(end 110.388146 -286.558736)
		(width 0.1143)
		(layer "In11.Cu")
		(net "P5E_CPU1_P1_RX_DN<14>")
	)
	(segment
		(start 110.34903 -291.441632)
		(end 110.388146 -291.418772)
		(width 0.1143)
		(layer "In11.Cu")
		(net "P5E_CPU1_P1_RX_DN<14>")
	)
	(segment
		(start 110.427516 -292.4175)
		(end 110.386622 -292.392608)
		(width 0.1143)
		(layer "In11.Cu")
		(net "P5E_CPU1_P1_RX_DN<14>")
	)
	(segment
		(start 110.388146 -291.418772)
		(end 110.418626 -291.400992)
		(width 0.1143)
		(layer "In11.Cu")
		(net "P5E_CPU1_P1_RX_DN<14>")
	)
	(segment
		(start 97.472754 -385.404868)
		(end 97.59442 -385.334764)
		(width 0.14224)
		(layer "In11.Cu")
		(net "P5E_CPU1_P1_RX_DN<14>")
	)
	(segment
		(start 110.34903 -281.721814)
		(end 110.46714 -281.652726)
		(width 0.1143)
		(layer "In11.Cu")
		(net "P5E_CPU1_P1_RX_DN<14>")
	)
	(segment
		(start 109.91596 -278.622506)
		(end 109.911388 -278.619458)
		(width 0.1143)
		(layer "In11.Cu")
		(net "P5E_CPU1_P1_RX_DN<14>")
	)
	(segment
		(start 99.182174 -379.912372)
		(end 99.405186 -379.548644)
		(width 0.14224)
		(layer "In11.Cu")
		(net "P5E_CPU1_P1_RX_DN<14>")
	)
	(segment
		(start 110.418626 -289.17138)
		(end 110.388146 -289.1536)
		(width 0.1143)
		(layer "In11.Cu")
		(net "P5E_CPU1_P1_RX_DN<14>")
	)
	(segment
		(start 110.46714 -281.100022)
		(end 110.34903 -281.030934)
		(width 0.1143)
		(layer "In11.Cu")
		(net "P5E_CPU1_P1_RX_DN<14>")
	)
	(segment
		(start 110.34903 -289.82162)
		(end 110.388146 -289.79876)
		(width 0.1143)
		(layer "In11.Cu")
		(net "P5E_CPU1_P1_RX_DN<14>")
	)
	(segment
		(start 99.359974 -379.360176)
		(end 99.582986 -378.99594)
		(width 0.14224)
		(layer "In11.Cu")
		(net "P5E_CPU1_P1_RX_DN<14>")
	)
	(segment
		(start 110.105698 -295.623234)
		(end 110.105698 -295.146222)
		(width 0.1143)
		(layer "In11.Cu")
		(net "P5E_CPU1_P1_RX_DN<14>")
	)
	(segment
		(start 110.419896 -294.032178)
		(end 110.388146 -294.013636)
		(width 0.1143)
		(layer "In11.Cu")
		(net "P5E_CPU1_P1_RX_DN<14>")
	)
	(segment
		(start 109.918754 -278.624284)
		(end 109.91723 -278.623268)
		(width 0.1143)
		(layer "In11.Cu")
		(net "P5E_CPU1_P1_RX_DN<14>")
	)
	(segment
		(start 127.963676 -326.599296)
		(end 124.783596 -320.514472)
		(width 0.14224)
		(layer "In11.Cu")
		(net "P5E_CPU1_P1_RX_DN<14>")
	)
	(segment
		(start 98.180906 -381.28321)
		(end 98.403918 -380.919228)
		(width 0.14224)
		(layer "In11.Cu")
		(net "P5E_CPU1_P1_RX_DN<14>")
	)
	(segment
		(start 110.388146 -286.558736)
		(end 110.420658 -286.53994)
		(width 0.1143)
		(layer "In11.Cu")
		(net "P5E_CPU1_P1_RX_DN<14>")
	)
	(segment
		(start 127.997204 -349.4278)
		(end 127.997458 -349.427546)
		(width 0.14224)
		(layer "In11.Cu")
		(net "P5E_CPU1_P1_RX_DN<14>")
	)
	(segment
		(start 99.771708 -378.950728)
		(end 99.771962 -378.950728)
		(width 0.14224)
		(layer "In11.Cu")
		(net "P5E_CPU1_P1_RX_DN<14>")
	)
	(segment
		(start 99.405186 -379.548644)
		(end 99.359974 -379.360176)
		(width 0.14224)
		(layer "In11.Cu")
		(net "P5E_CPU1_P1_RX_DN<14>")
	)
	(segment
		(start 110.418626 -285.93161)
		(end 110.34903 -285.89097)
		(width 0.1143)
		(layer "In11.Cu")
		(net "P5E_CPU1_P1_RX_DN<14>")
	)
	(segment
		(start 110.34903 -284.961838)
		(end 110.419642 -284.92069)
		(width 0.1143)
		(layer "In11.Cu")
		(net "P5E_CPU1_P1_RX_DN<14>")
	)
	(segment
		(start 110.418626 -282.691586)
		(end 110.34903 -282.650946)
		(width 0.1143)
		(layer "In11.Cu")
		(net "P5E_CPU1_P1_RX_DN<14>")
	)
	(segment
		(start 127.618744 -350.409764)
		(end 127.997204 -349.428308)
		(width 0.14224)
		(layer "In11.Cu")
		(net "P5E_CPU1_P1_RX_DN<14>")
	)
	(segment
		(start 110.387892 -293.039038)
		(end 110.388146 -293.038784)
		(width 0.1143)
		(layer "In11.Cu")
		(net "P5E_CPU1_P1_RX_DN<14>")
	)
	(segment
		(start 110.45317 -294.055292)
		(end 110.419896 -294.032178)
		(width 0.1143)
		(layer "In11.Cu")
		(net "P5E_CPU1_P1_RX_DN<14>")
	)
	(segment
		(start 97.59442 -385.334764)
		(end 97.59442 -385.163822)
		(width 0.14224)
		(layer "In11.Cu")
		(net "P5E_CPU1_P1_RX_DN<14>")
	)
	(segment
		(start 112.27054 -303.80305)
		(end 110.059978 -298.466002)
		(width 0.14224)
		(layer "In11.Cu")
		(net "P5E_CPU1_P1_RX_DN<14>")
	)
	(segment
		(start 117.538246 -311.686194)
		(end 112.27054 -303.80305)
		(width 0.14224)
		(layer "In11.Cu")
		(net "P5E_CPU1_P1_RX_DN<14>")
	)
	(segment
		(start 110.418626 -287.551622)
		(end 110.35157 -287.512506)
		(width 0.1143)
		(layer "In11.Cu")
		(net "P5E_CPU1_P1_RX_DN<14>")
	)
	(segment
		(start 110.059978 -295.697402)
		(end 110.059978 -295.668954)
		(width 0.1143)
		(layer "In11.Cu")
		(net "P5E_CPU1_P1_RX_DN<14>")
	)
	(segment
		(start 107.282488 -364.494826)
		(end 127.136906 -351.227898)
		(width 0.14224)
		(layer "In11.Cu")
		(net "P5E_CPU1_P1_RX_DN<14>")
	)
	(segment
		(start 109.920024 -278.625046)
		(end 109.918754 -278.624284)
		(width 0.1143)
		(layer "In11.Cu")
		(net "P5E_CPU1_P1_RX_DN<14>")
	)
	(segment
		(start 110.575598 -286.236918)
		(end 110.575598 -286.23641)
		(width 0.1143)
		(layer "In11.Cu")
		(net "P5E_CPU1_P1_RX_DN<14>")
	)
	(segment
		(start 97.586292 -383.93116)
		(end 97.586292 -382.631188)
		(width 0.14224)
		(layer "In11.Cu")
		(net "P5E_CPU1_P1_RX_DN<14>")
	)
	(segment
		(start 110.388146 -284.293818)
		(end 110.34903 -284.270958)
		(width 0.1143)
		(layer "In11.Cu")
		(net "P5E_CPU1_P1_RX_DN<14>")
	)
	(segment
		(start 97.64649 -382.417066)
		(end 98.226118 -381.471678)
		(width 0.14224)
		(layer "In11.Cu")
		(net "P5E_CPU1_P1_RX_DN<14>")
	)
	(segment
		(start 99.582986 -378.99594)
		(end 99.771708 -378.950728)
		(width 0.14224)
		(layer "In11.Cu")
		(net "P5E_CPU1_P1_RX_DN<14>")
	)
	(segment
		(start 109.91723 -278.623268)
		(end 109.91596 -278.622506)
		(width 0.1143)
		(layer "In11.Cu")
		(net "P5E_CPU1_P1_RX_DN<14>")
	)
	(segment
		(start 97.59442 -385.163822)
		(end 97.277428 -384.84683)
		(width 0.14224)
		(layer "In11.Cu")
		(net "P5E_CPU1_P1_RX_DN<14>")
	)
	(segment
		(start 110.420658 -286.53994)
		(end 110.421166 -286.539432)
		(width 0.1143)
		(layer "In11.Cu")
		(net "P5E_CPU1_P1_RX_DN<14>")
	)
	(segment
		(start 98.59264 -380.874016)
		(end 98.815652 -380.510288)
		(width 0.14224)
		(layer "In11.Cu")
		(net "P5E_CPU1_P1_RX_DN<14>")
	)
	(segment
		(start 124.783596 -320.514472)
		(end 117.538246 -311.686194)
		(width 0.14224)
		(layer "In11.Cu")
		(net "P5E_CPU1_P1_RX_DN<14>")
	)
	(segment
		(start 99.771962 -378.950728)
		(end 103.88727 -372.239032)
		(width 0.14224)
		(layer "In11.Cu")
		(net "P5E_CPU1_P1_RX_DN<14>")
	)
	(segment
		(start 98.77044 -380.32182)
		(end 98.993452 -379.957584)
		(width 0.14224)
		(layer "In11.Cu")
		(net "P5E_CPU1_P1_RX_DN<14>")
	)
	(segment
		(start 110.34903 -283.341826)
		(end 110.412022 -283.304996)
		(width 0.1143)
		(layer "In11.Cu")
		(net "P5E_CPU1_P1_RX_DN<14>")
	)
	(segment
		(start 110.418626 -284.311598)
		(end 110.388146 -284.293818)
		(width 0.1143)
		(layer "In11.Cu")
		(net "P5E_CPU1_P1_RX_DN<14>")
	)
	(segment
		(start 98.993452 -379.957584)
		(end 99.182174 -379.912372)
		(width 0.14224)
		(layer "In11.Cu")
		(net "P5E_CPU1_P1_RX_DN<14>")
	)
	(segment
		(start 110.388146 -279.433782)
		(end 110.34903 -279.410922)
		(width 0.1143)
		(layer "In11.Cu")
		(net "P5E_CPU1_P1_RX_DN<14>")
	)
	(segment
		(start 97.282254 -384.234944)
		(end 97.586292 -383.93116)
		(width 0.14224)
		(layer "In11.Cu")
		(net "P5E_CPU1_P1_RX_DN<14>")
	)
	(segment
		(start 110.38459 -294.660828)
		(end 110.455964 -294.615362)
		(width 0.1143)
		(layer "In11.Cu")
		(net "P5E_CPU1_P1_RX_DN<14>")
	)
	(segment
		(start 110.386622 -292.392608)
		(end 110.34903 -292.370764)
		(width 0.1143)
		(layer "In11.Cu")
		(net "P5E_CPU1_P1_RX_DN<14>")
	)
	(segment
		(start 97.119186 -385.31038)
		(end 97.472246 -385.405376)
		(width 0.14224)
		(layer "In11.Cu")
		(net "P5E_CPU1_P1_RX_DN<14>")
	)
	(segment
		(start 110.575598 -284.6197)
		(end 110.575598 -284.616398)
		(width 0.1143)
		(layer "In11.Cu")
		(net "P5E_CPU1_P1_RX_DN<14>")
	)
	(segment
		(start 109.911388 -278.619458)
		(end 109.833664 -278.569928)
		(width 0.1143)
		(layer "In11.Cu")
		(net "P5E_CPU1_P1_RX_DN<14>")
	)
	(segment
		(start 98.403918 -380.919228)
		(end 98.59264 -380.874016)
		(width 0.14224)
		(layer "In11.Cu")
		(net "P5E_CPU1_P1_RX_DN<14>")
	)
	(segment
		(start 110.388146 -294.013636)
		(end 110.387892 -294.013636)
		(width 0.1143)
		(layer "In11.Cu")
		(net "P5E_CPU1_P1_RX_DN<14>")
	)
	(segment
		(start 110.388146 -290.773612)
		(end 110.34903 -290.750752)
		(width 0.1143)
		(layer "In11.Cu")
		(net "P5E_CPU1_P1_RX_DN<14>")
	)
	(segment
		(start 127.997204 -349.428308)
		(end 127.997204 -349.4278)
		(width 0.14224)
		(layer "In11.Cu")
		(net "P5E_CPU1_P1_RX_DN<14>")
	)
	(segment
		(start 109.924088 -278.627332)
		(end 109.922564 -278.626316)
		(width 0.1143)
		(layer "In11.Cu")
		(net "P5E_CPU1_P1_RX_DN<14>")
	)
	(segment
		(start 98.226118 -381.471678)
		(end 98.180906 -381.28321)
		(width 0.14224)
		(layer "In11.Cu")
		(net "P5E_CPU1_P1_RX_DN<14>")
	)
	(segment
		(start 110.34903 -288.201608)
		(end 110.388146 -288.178748)
		(width 0.1143)
		(layer "In11.Cu")
		(net "P5E_CPU1_P1_RX_DN<14>")
	)
	(segment
		(start 110.388146 -289.79876)
		(end 110.418626 -289.78098)
		(width 0.1143)
		(layer "In11.Cu")
		(net "P5E_CPU1_P1_RX_DN<14>")
	)
	(segment
		(start 110.575344 -292.730174)
		(end 110.575344 -292.702996)
		(width 0.1143)
		(layer "In11.Cu")
		(net "P5E_CPU1_P1_RX_DN<14>")
	)
	(segment
		(start 130.215132 -343.67851)
		(end 130.215132 -339.132926)
		(width 0.14224)
		(layer "In11.Cu")
		(net "P5E_CPU1_P1_RX_DN<14>")
	)
	(segment
		(start 127.997458 -349.427546)
		(end 130.215132 -343.67851)
		(width 0.14224)
		(layer "In11.Cu")
		(net "P5E_CPU1_P1_RX_DN<14>")
	)
	(segment
		(start 105.737152 -367.751106)
		(end 107.1372 -364.666022)
		(width 0.14224)
		(layer "In11.Cu")
		(net "P5E_CPU1_P1_RX_DN<14>")
	)
	(segment
		(start 109.17174 -277.409148)
		(end 109.088936 -277.326344)
		(width 0.1143)
		(layer "In11.Cu")
		(net "P5E_CPU1_P1_RX_DN<14>")
	)
	(segment
		(start 98.815652 -380.510288)
		(end 98.77044 -380.32182)
		(width 0.14224)
		(layer "In11.Cu")
		(net "P5E_CPU1_P1_RX_DN<14>")
	)
	(segment
		(start 97.277428 -384.84683)
		(end 97.282254 -384.234944)
		(width 0.14224)
		(layer "In11.Cu")
		(net "P5E_CPU1_P1_RX_DN<14>")
	)
	(segment
		(start 109.088936 -277.326344)
		(end 108.790994 -277.326344)
		(width 0.1143)
		(layer "In11.Cu")
		(net "P5E_CPU1_P1_RX_DN<14>")
	)
	(segment
		(start 110.388146 -288.178748)
		(end 110.41253 -288.164524)
		(width 0.1143)
		(layer "In11.Cu")
		(net "P5E_CPU1_P1_RX_DN<14>")
	)
	(arc
		(start 110.34903 -282.650946)
		(mid 110.105703 -282.18638)
		(end 110.34903 -281.721814)
		(width 0.1143)
		(layer "In11.Cu")
		(net "P5E_CPU1_P1_RX_DN<14>")
	)
	(arc
		(start 110.34903 -281.030934)
		(mid 110.105703 -280.566368)
		(end 110.34903 -280.101802)
		(width 0.1143)
		(layer "In11.Cu")
		(net "P5E_CPU1_P1_RX_DN<14>")
	)
	(arc
		(start 110.455964 -294.615362)
		(mid 110.600468 -294.334561)
		(end 110.45317 -294.055292)
		(width 0.1143)
		(layer "In11.Cu")
		(net "P5E_CPU1_P1_RX_DN<14>")
	)
	(arc
		(start 110.421166 -286.539432)
		(mid 110.534721 -286.406733)
		(end 110.575598 -286.236918)
		(width 0.1143)
		(layer "In11.Cu")
		(net "P5E_CPU1_P1_RX_DN<14>")
	)
	(arc
		(start 109.17555 -277.432008)
		(mid 109.173527 -277.420598)
		(end 109.17174 -277.409148)
		(width 0.1143)
		(layer "In11.Cu")
		(net "P5E_CPU1_P1_RX_DN<14>")
	)
	(arc
		(start 110.387892 -294.013636)
		(mid 110.108348 -293.5264)
		(end 110.387892 -293.039038)
		(width 0.1143)
		(layer "In11.Cu")
		(net "P5E_CPU1_P1_RX_DN<14>")
	)
	(arc
		(start 110.417864 -280.06167)
		(mid 110.530965 -279.926689)
		(end 110.575598 -279.756362)
		(width 0.1143)
		(layer "In11.Cu")
		(net "P5E_CPU1_P1_RX_DN<14>")
	)
	(arc
		(start 110.46714 -281.652726)
		(mid 110.625701 -281.376374)
		(end 110.46714 -281.100022)
		(width 0.1143)
		(layer "In11.Cu")
		(net "P5E_CPU1_P1_RX_DN<14>")
	)
	(arc
		(start 110.412022 -283.304996)
		(mid 110.523237 -283.161866)
		(end 110.575344 -282.988258)
		(width 0.1143)
		(layer "In11.Cu")
		(net "P5E_CPU1_P1_RX_DN<14>")
	)
	(arc
		(start 110.34903 -279.410922)
		(mid 110.170217 -279.208572)
		(end 110.105698 -278.946356)
		(width 0.1143)
		(layer "In11.Cu")
		(net "P5E_CPU1_P1_RX_DN<14>")
	)
	(arc
		(start 110.575598 -284.616398)
		(mid 110.534049 -284.444976)
		(end 110.418626 -284.311598)
		(width 0.1143)
		(layer "In11.Cu")
		(net "P5E_CPU1_P1_RX_DN<14>")
	)
	(arc
		(start 110.34903 -290.750752)
		(mid 110.105703 -290.286186)
		(end 110.34903 -289.82162)
		(width 0.1143)
		(layer "In11.Cu")
		(net "P5E_CPU1_P1_RX_DN<14>")
	)
	(arc
		(start 110.572804 -287.81248)
		(mid 110.523313 -287.665731)
		(end 110.418626 -287.551622)
		(width 0.1143)
		(layer "In11.Cu")
		(net "P5E_CPU1_P1_RX_DN<14>")
	)
	(arc
		(start 110.575344 -287.84931)
		(mid 110.574525 -287.830864)
		(end 110.572804 -287.81248)
		(width 0.1143)
		(layer "In11.Cu")
		(net "P5E_CPU1_P1_RX_DN<14>")
	)
	(arc
		(start 110.34903 -285.89097)
		(mid 110.105703 -285.426404)
		(end 110.34903 -284.961838)
		(width 0.1143)
		(layer "In11.Cu")
		(net "P5E_CPU1_P1_RX_DN<14>")
	)
	(arc
		(start 110.575344 -292.702996)
		(mid 110.536261 -292.542205)
		(end 110.427516 -292.4175)
		(width 0.1143)
		(layer "In11.Cu")
		(net "P5E_CPU1_P1_RX_DN<14>")
	)
	(arc
		(start 103.88727 -372.239032)
		(mid 104.491406 -371.123445)
		(end 104.972358 -369.949476)
		(width 0.14224)
		(layer "In11.Cu")
		(net "P5E_CPU1_P1_RX_DN<14>")
	)
	(arc
		(start 110.42396 -284.917388)
		(mid 110.529715 -284.7838)
		(end 110.575598 -284.6197)
		(width 0.1143)
		(layer "In11.Cu")
		(net "P5E_CPU1_P1_RX_DN<14>")
	)
	(arc
		(start 109.408976 -277.79091)
		(mid 109.256989 -277.634402)
		(end 109.17555 -277.432008)
		(width 0.1143)
		(layer "In11.Cu")
		(net "P5E_CPU1_P1_RX_DN<14>")
	)
	(arc
		(start 110.575598 -279.756362)
		(mid 110.534049 -279.58494)
		(end 110.418626 -279.451562)
		(width 0.1143)
		(layer "In11.Cu")
		(net "P5E_CPU1_P1_RX_DN<14>")
	)
	(arc
		(start 107.1372 -364.666022)
		(mid 107.197859 -364.57025)
		(end 107.282488 -364.494826)
		(width 0.14224)
		(layer "In11.Cu")
		(net "P5E_CPU1_P1_RX_DN<14>")
	)
	(arc
		(start 110.34903 -289.13074)
		(mid 110.105703 -288.666174)
		(end 110.34903 -288.201608)
		(width 0.1143)
		(layer "In11.Cu")
		(net "P5E_CPU1_P1_RX_DN<14>")
	)
	(arc
		(start 110.35157 -287.512506)
		(mid 110.170918 -287.309761)
		(end 110.105698 -287.046162)
		(width 0.1143)
		(layer "In11.Cu")
		(net "P5E_CPU1_P1_RX_DN<14>")
	)
	(arc
		(start 110.419642 -284.92069)
		(mid 110.421807 -284.919047)
		(end 110.42396 -284.917388)
		(width 0.1143)
		(layer "In11.Cu")
		(net "P5E_CPU1_P1_RX_DN<14>")
	)
	(arc
		(start 110.575344 -282.988258)
		(mid 110.575167 -282.980762)
		(end 110.574836 -282.973272)
		(width 0.1143)
		(layer "In11.Cu")
		(net "P5E_CPU1_P1_RX_DN<14>")
	)
	(arc
		(start 127.136906 -351.227898)
		(mid 127.411432 -350.838622)
		(end 127.618744 -350.409764)
		(width 0.14224)
		(layer "In11.Cu")
		(net "P5E_CPU1_P1_RX_DN<14>")
	)
	(arc
		(start 110.34903 -284.270958)
		(mid 110.105703 -283.806392)
		(end 110.34903 -283.341826)
		(width 0.1143)
		(layer "In11.Cu")
		(net "P5E_CPU1_P1_RX_DN<14>")
	)
	(arc
		(start 110.105698 -278.946356)
		(mid 110.064443 -278.775385)
		(end 109.949742 -278.642064)
		(width 0.1143)
		(layer "In11.Cu")
		(net "P5E_CPU1_P1_RX_DN<14>")
	)
	(arc
		(start 110.105698 -287.046162)
		(mid 110.170213 -286.783943)
		(end 110.34903 -286.581596)
		(width 0.1143)
		(layer "In11.Cu")
		(net "P5E_CPU1_P1_RX_DN<14>")
	)
	(arc
		(start 110.418626 -289.78098)
		(mid 110.575603 -289.47618)
		(end 110.418626 -289.17138)
		(width 0.1143)
		(layer "In11.Cu")
		(net "P5E_CPU1_P1_RX_DN<14>")
	)
	(arc
		(start 110.42015 -293.019988)
		(mid 110.531285 -292.893032)
		(end 110.575344 -292.730174)
		(width 0.1143)
		(layer "In11.Cu")
		(net "P5E_CPU1_P1_RX_DN<14>")
	)
	(arc
		(start 110.41253 -288.164524)
		(mid 110.523078 -288.021961)
		(end 110.575344 -287.84931)
		(width 0.1143)
		(layer "In11.Cu")
		(net "P5E_CPU1_P1_RX_DN<14>")
	)
	(arc
		(start 110.34903 -292.370764)
		(mid 110.105703 -291.906198)
		(end 110.34903 -291.441632)
		(width 0.1143)
		(layer "In11.Cu")
		(net "P5E_CPU1_P1_RX_DN<14>")
	)
	(arc
		(start 110.105698 -295.146222)
		(mid 110.170213 -294.884003)
		(end 110.34903 -294.681656)
		(width 0.1143)
		(layer "In11.Cu")
		(net "P5E_CPU1_P1_RX_DN<14>")
	)
	(arc
		(start 97.586292 -382.631188)
		(mid 97.601557 -382.519956)
		(end 97.64649 -382.417066)
		(width 0.14224)
		(layer "In11.Cu")
		(net "P5E_CPU1_P1_RX_DN<14>")
	)
	(arc
		(start 110.418626 -291.400992)
		(mid 110.575603 -291.096192)
		(end 110.418626 -290.791392)
		(width 0.1143)
		(layer "In11.Cu")
		(net "P5E_CPU1_P1_RX_DN<14>")
	)
	(arc
		(start 109.635798 -278.13635)
		(mid 109.594543 -277.965379)
		(end 109.479842 -277.832058)
		(width 0.1143)
		(layer "In11.Cu")
		(net "P5E_CPU1_P1_RX_DN<14>")
	)
	(arc
		(start 110.575598 -286.23641)
		(mid 110.534049 -286.064988)
		(end 110.418626 -285.93161)
		(width 0.1143)
		(layer "In11.Cu")
		(net "P5E_CPU1_P1_RX_DN<14>")
	)
	(arc
		(start 109.833664 -278.569928)
		(mid 109.688264 -278.406576)
		(end 109.635798 -278.194262)
		(width 0.1143)
		(layer "In11.Cu")
		(net "P5E_CPU1_P1_RX_DN<14>")
	)
	(arc
		(start 110.34903 -294.681656)
		(mid 110.349792 -294.681147)
		(end 110.350554 -294.68064)
		(width 0.1143)
		(layer "In11.Cu")
		(net "P5E_CPU1_P1_RX_DN<14>")
	)
	(arc
		(start 110.574836 -282.973272)
		(mid 110.528575 -282.814763)
		(end 110.418626 -282.691586)
		(width 0.1143)
		(layer "In11.Cu")
		(net "P5E_CPU1_P1_RX_DN<14>")
	)
	(segment
		(start 109.257846 -278.680418)
		(end 108.790994 -278.946356)
		(width 0.12954)
		(layer "F.Cu")
		(net "P5E_CPU1_P1_RX_DN<13>")
	)
	(segment
		(start 95.398336 -385.31038)
		(end 95.919036 -385.31038)
		(width 0.127)
		(layer "F.Cu")
		(net "P5E_CPU1_P1_RX_DN<13>")
	)
	(segment
		(start 109.441488 -292.390068)
		(end 109.440218 -292.389306)
		(width 0.1143)
		(layer "In11.Cu")
		(net "P5E_CPU1_P1_RX_DN<13>")
	)
	(segment
		(start 109.088936 -278.946356)
		(end 108.790994 -278.946356)
		(width 0.1143)
		(layer "In11.Cu")
		(net "P5E_CPU1_P1_RX_DN<13>")
	)
	(segment
		(start 96.58477 -381.822198)
		(end 96.910652 -381.294132)
		(width 0.14224)
		(layer "In11.Cu")
		(net "P5E_CPU1_P1_RX_DN<13>")
	)
	(segment
		(start 109.469428 -294.026082)
		(end 109.468666 -294.025574)
		(width 0.1143)
		(layer "In11.Cu")
		(net "P5E_CPU1_P1_RX_DN<13>")
	)
	(segment
		(start 97.682812 -379.782324)
		(end 97.871788 -379.737874)
		(width 0.14224)
		(layer "In11.Cu")
		(net "P5E_CPU1_P1_RX_DN<13>")
	)
	(segment
		(start 109.469682 -294.026082)
		(end 109.469428 -294.026082)
		(width 0.1143)
		(layer "In11.Cu")
		(net "P5E_CPU1_P1_RX_DN<13>")
	)
	(segment
		(start 109.408976 -281.721814)
		(end 109.448092 -281.698954)
		(width 0.1143)
		(layer "In11.Cu")
		(net "P5E_CPU1_P1_RX_DN<13>")
	)
	(segment
		(start 109.447076 -290.773104)
		(end 109.408976 -290.750752)
		(width 0.1143)
		(layer "In11.Cu")
		(net "P5E_CPU1_P1_RX_DN<13>")
	)
	(segment
		(start 109.445552 -289.800284)
		(end 109.447076 -289.799268)
		(width 0.1143)
		(layer "In11.Cu")
		(net "P5E_CPU1_P1_RX_DN<13>")
	)
	(segment
		(start 109.119924 -295.668954)
		(end 109.165644 -295.623234)
		(width 0.1143)
		(layer "In11.Cu")
		(net "P5E_CPU1_P1_RX_DN<13>")
	)
	(segment
		(start 109.448092 -282.673806)
		(end 109.408976 -282.650946)
		(width 0.1143)
		(layer "In11.Cu")
		(net "P5E_CPU1_P1_RX_DN<13>")
	)
	(segment
		(start 109.428534 -288.190178)
		(end 109.467904 -288.167318)
		(width 0.1143)
		(layer "In11.Cu")
		(net "P5E_CPU1_P1_RX_DN<13>")
	)
	(segment
		(start 109.455458 -293.034466)
		(end 109.457998 -293.032942)
		(width 0.1143)
		(layer "In11.Cu")
		(net "P5E_CPU1_P1_RX_DN<13>")
	)
	(segment
		(start 109.43209 -294.004492)
		(end 109.429804 -294.002968)
		(width 0.1143)
		(layer "In11.Cu")
		(net "P5E_CPU1_P1_RX_DN<13>")
	)
	(segment
		(start 109.534198 -287.606486)
		(end 109.408214 -287.516824)
		(width 0.1143)
		(layer "In11.Cu")
		(net "P5E_CPU1_P1_RX_DN<13>")
	)
	(segment
		(start 109.635798 -287.856676)
		(end 109.635798 -287.85439)
		(width 0.1143)
		(layer "In11.Cu")
		(net "P5E_CPU1_P1_RX_DN<13>")
	)
	(segment
		(start 109.448092 -280.078942)
		(end 109.479842 -280.060654)
		(width 0.1143)
		(layer "In11.Cu")
		(net "P5E_CPU1_P1_RX_DN<13>")
	)
	(segment
		(start 109.448092 -283.318966)
		(end 109.479842 -283.300678)
		(width 0.1143)
		(layer "In11.Cu")
		(net "P5E_CPU1_P1_RX_DN<13>")
	)
	(segment
		(start 109.478826 -286.54121)
		(end 109.48162 -286.539178)
		(width 0.1143)
		(layer "In11.Cu")
		(net "P5E_CPU1_P1_RX_DN<13>")
	)
	(segment
		(start 109.447076 -291.41928)
		(end 109.448092 -291.418772)
		(width 0.1143)
		(layer "In11.Cu")
		(net "P5E_CPU1_P1_RX_DN<13>")
	)
	(segment
		(start 109.415834 -289.134804)
		(end 109.408976 -289.13074)
		(width 0.1143)
		(layer "In11.Cu")
		(net "P5E_CPU1_P1_RX_DN<13>")
	)
	(segment
		(start 96.910652 -381.294132)
		(end 96.865948 -381.10541)
		(width 0.14224)
		(layer "In11.Cu")
		(net "P5E_CPU1_P1_RX_DN<13>")
	)
	(segment
		(start 109.448092 -285.91383)
		(end 109.408976 -285.89097)
		(width 0.1143)
		(layer "In11.Cu")
		(net "P5E_CPU1_P1_RX_DN<13>")
	)
	(segment
		(start 109.448854 -289.798252)
		(end 109.479842 -289.780472)
		(width 0.1143)
		(layer "In11.Cu")
		(net "P5E_CPU1_P1_RX_DN<13>")
	)
	(segment
		(start 117.008148 -312.578496)
		(end 111.445802 -304.254408)
		(width 0.14224)
		(layer "In11.Cu")
		(net "P5E_CPU1_P1_RX_DN<13>")
	)
	(segment
		(start 109.635544 -287.856422)
		(end 109.635798 -287.856676)
		(width 0.1143)
		(layer "In11.Cu")
		(net "P5E_CPU1_P1_RX_DN<13>")
	)
	(segment
		(start 109.408976 -289.82162)
		(end 109.445552 -289.800284)
		(width 0.1143)
		(layer "In11.Cu")
		(net "P5E_CPU1_P1_RX_DN<13>")
	)
	(segment
		(start 109.448092 -289.79876)
		(end 109.448854 -289.798252)
		(width 0.1143)
		(layer "In11.Cu")
		(net "P5E_CPU1_P1_RX_DN<13>")
	)
	(segment
		(start 98.051112 -379.186186)
		(end 98.275394 -378.822712)
		(width 0.14224)
		(layer "In11.Cu")
		(net "P5E_CPU1_P1_RX_DN<13>")
	)
	(segment
		(start 96.07804 -384.780028)
		(end 96.081088 -384.417824)
		(width 0.14224)
		(layer "In11.Cu")
		(net "P5E_CPU1_P1_RX_DN<13>")
	)
	(segment
		(start 109.457998 -293.032942)
		(end 109.459522 -293.03218)
		(width 0.1143)
		(layer "In11.Cu")
		(net "P5E_CPU1_P1_RX_DN<13>")
	)
	(segment
		(start 109.448092 -293.038784)
		(end 109.448854 -293.038276)
		(width 0.1143)
		(layer "In11.Cu")
		(net "P5E_CPU1_P1_RX_DN<13>")
	)
	(segment
		(start 109.407706 -293.062406)
		(end 109.432598 -293.04742)
		(width 0.1143)
		(layer "In11.Cu")
		(net "P5E_CPU1_P1_RX_DN<13>")
	)
	(segment
		(start 109.448854 -291.418264)
		(end 109.479842 -291.400484)
		(width 0.1143)
		(layer "In11.Cu")
		(net "P5E_CPU1_P1_RX_DN<13>")
	)
	(segment
		(start 104.939592 -366.881156)
		(end 106.168444 -364.199932)
		(width 0.14224)
		(layer "In11.Cu")
		(net "P5E_CPU1_P1_RX_DN<13>")
	)
	(segment
		(start 96.394524 -385.334764)
		(end 96.394524 -385.163822)
		(width 0.14224)
		(layer "In11.Cu")
		(net "P5E_CPU1_P1_RX_DN<13>")
	)
	(segment
		(start 109.469428 -294.64635)
		(end 109.469936 -294.64635)
		(width 0.1143)
		(layer "In11.Cu")
		(net "P5E_CPU1_P1_RX_DN<13>")
	)
	(segment
		(start 109.445552 -291.420296)
		(end 109.447076 -291.41928)
		(width 0.1143)
		(layer "In11.Cu")
		(net "P5E_CPU1_P1_RX_DN<13>")
	)
	(segment
		(start 96.394524 -385.163822)
		(end 96.124776 -384.894074)
		(width 0.14224)
		(layer "In11.Cu")
		(net "P5E_CPU1_P1_RX_DN<13>")
	)
	(segment
		(start 109.448092 -289.1536)
		(end 109.447076 -289.153092)
		(width 0.1143)
		(layer "In11.Cu")
		(net "P5E_CPU1_P1_RX_DN<13>")
	)
	(segment
		(start 109.408976 -283.341826)
		(end 109.448092 -283.318966)
		(width 0.1143)
		(layer "In11.Cu")
		(net "P5E_CPU1_P1_RX_DN<13>")
	)
	(segment
		(start 109.433106 -294.005)
		(end 109.43209 -294.004492)
		(width 0.1143)
		(layer "In11.Cu")
		(net "P5E_CPU1_P1_RX_DN<13>")
	)
	(segment
		(start 109.444536 -289.151568)
		(end 109.443774 -289.15106)
		(width 0.1143)
		(layer "In11.Cu")
		(net "P5E_CPU1_P1_RX_DN<13>")
	)
	(segment
		(start 109.409738 -294.681148)
		(end 109.469428 -294.64635)
		(width 0.1143)
		(layer "In11.Cu")
		(net "P5E_CPU1_P1_RX_DN<13>")
	)
	(segment
		(start 124.070364 -321.183254)
		(end 117.008148 -312.578496)
		(width 0.14224)
		(layer "In11.Cu")
		(net "P5E_CPU1_P1_RX_DN<13>")
	)
	(segment
		(start 103.67645 -370.336064)
		(end 103.67645 -370.33581)
		(width 0.14224)
		(layer "In11.Cu")
		(net "P5E_CPU1_P1_RX_DN<13>")
	)
	(segment
		(start 109.448092 -279.433782)
		(end 109.408976 -279.410922)
		(width 0.1143)
		(layer "In11.Cu")
		(net "P5E_CPU1_P1_RX_DN<13>")
	)
	(segment
		(start 109.416596 -289.135312)
		(end 109.415834 -289.134804)
		(width 0.1143)
		(layer "In11.Cu")
		(net "P5E_CPU1_P1_RX_DN<13>")
	)
	(segment
		(start 109.443774 -289.15106)
		(end 109.416596 -289.135312)
		(width 0.1143)
		(layer "In11.Cu")
		(net "P5E_CPU1_P1_RX_DN<13>")
	)
	(segment
		(start 96.386396 -383.864358)
		(end 96.386396 -382.521206)
		(width 0.14224)
		(layer "In11.Cu")
		(net "P5E_CPU1_P1_RX_DN<13>")
	)
	(segment
		(start 109.451394 -293.036752)
		(end 109.454696 -293.034974)
		(width 0.1143)
		(layer "In11.Cu")
		(net "P5E_CPU1_P1_RX_DN<13>")
	)
	(segment
		(start 109.448092 -291.418772)
		(end 109.448854 -291.418264)
		(width 0.1143)
		(layer "In11.Cu")
		(net "P5E_CPU1_P1_RX_DN<13>")
	)
	(segment
		(start 109.119924 -298.638976)
		(end 109.119924 -295.697402)
		(width 0.14224)
		(layer "In11.Cu")
		(net "P5E_CPU1_P1_RX_DN<13>")
	)
	(segment
		(start 96.21139 -384.106166)
		(end 96.339152 -383.978404)
		(width 0.14224)
		(layer "In11.Cu")
		(net "P5E_CPU1_P1_RX_DN<13>")
	)
	(segment
		(start 109.448092 -284.293818)
		(end 109.408976 -284.270958)
		(width 0.1143)
		(layer "In11.Cu")
		(net "P5E_CPU1_P1_RX_DN<13>")
	)
	(segment
		(start 96.272858 -385.404868)
		(end 96.394524 -385.334764)
		(width 0.14224)
		(layer "In11.Cu")
		(net "P5E_CPU1_P1_RX_DN<13>")
	)
	(segment
		(start 109.448092 -290.773612)
		(end 109.447076 -290.773104)
		(width 0.1143)
		(layer "In11.Cu")
		(net "P5E_CPU1_P1_RX_DN<13>")
	)
	(segment
		(start 97.871788 -379.737874)
		(end 98.095816 -379.374908)
		(width 0.14224)
		(layer "In11.Cu")
		(net "P5E_CPU1_P1_RX_DN<13>")
	)
	(segment
		(start 109.429804 -294.002968)
		(end 109.409992 -293.991538)
		(width 0.1143)
		(layer "In11.Cu")
		(net "P5E_CPU1_P1_RX_DN<13>")
	)
	(segment
		(start 109.119924 -295.697402)
		(end 109.119924 -295.668954)
		(width 0.1143)
		(layer "In11.Cu")
		(net "P5E_CPU1_P1_RX_DN<13>")
	)
	(segment
		(start 98.095816 -379.374908)
		(end 98.051112 -379.186186)
		(width 0.14224)
		(layer "In11.Cu")
		(net "P5E_CPU1_P1_RX_DN<13>")
	)
	(segment
		(start 109.448854 -289.154108)
		(end 109.448092 -289.1536)
		(width 0.1143)
		(layer "In11.Cu")
		(net "P5E_CPU1_P1_RX_DN<13>")
	)
	(segment
		(start 109.479842 -282.692094)
		(end 109.448092 -282.673806)
		(width 0.1143)
		(layer "In11.Cu")
		(net "P5E_CPU1_P1_RX_DN<13>")
	)
	(segment
		(start 111.445802 -304.254408)
		(end 109.119924 -298.638976)
		(width 0.14224)
		(layer "In11.Cu")
		(net "P5E_CPU1_P1_RX_DN<13>")
	)
	(segment
		(start 109.447076 -289.799268)
		(end 109.448092 -289.79876)
		(width 0.1143)
		(layer "In11.Cu")
		(net "P5E_CPU1_P1_RX_DN<13>")
	)
	(segment
		(start 109.17174 -279.02916)
		(end 109.088936 -278.946356)
		(width 0.1143)
		(layer "In11.Cu")
		(net "P5E_CPU1_P1_RX_DN<13>")
	)
	(segment
		(start 109.447076 -292.393116)
		(end 109.441488 -292.390068)
		(width 0.1143)
		(layer "In11.Cu")
		(net "P5E_CPU1_P1_RX_DN<13>")
	)
	(segment
		(start 109.439456 -292.388798)
		(end 109.43844 -292.38829)
		(width 0.1143)
		(layer "In11.Cu")
		(net "P5E_CPU1_P1_RX_DN<13>")
	)
	(segment
		(start 109.408976 -284.961838)
		(end 109.448092 -284.938978)
		(width 0.1143)
		(layer "In11.Cu")
		(net "P5E_CPU1_P1_RX_DN<13>")
	)
	(segment
		(start 109.479842 -281.072082)
		(end 109.448092 -281.053794)
		(width 0.1143)
		(layer "In11.Cu")
		(net "P5E_CPU1_P1_RX_DN<13>")
	)
	(segment
		(start 98.275394 -378.822712)
		(end 98.46437 -378.778262)
		(width 0.14224)
		(layer "In11.Cu")
		(net "P5E_CPU1_P1_RX_DN<13>")
	)
	(segment
		(start 109.467904 -288.167318)
		(end 109.482128 -288.158682)
		(width 0.1143)
		(layer "In11.Cu")
		(net "P5E_CPU1_P1_RX_DN<13>")
	)
	(segment
		(start 109.448854 -292.394132)
		(end 109.448092 -292.393624)
		(width 0.1143)
		(layer "In11.Cu")
		(net "P5E_CPU1_P1_RX_DN<13>")
	)
	(segment
		(start 109.459522 -293.03218)
		(end 109.479842 -293.020496)
		(width 0.1143)
		(layer "In11.Cu")
		(net "P5E_CPU1_P1_RX_DN<13>")
	)
	(segment
		(start 109.499654 -289.186112)
		(end 109.479842 -289.171888)
		(width 0.1143)
		(layer "In11.Cu")
		(net "P5E_CPU1_P1_RX_DN<13>")
	)
	(segment
		(start 109.479842 -292.411912)
		(end 109.448854 -292.394132)
		(width 0.1143)
		(layer "In11.Cu")
		(net "P5E_CPU1_P1_RX_DN<13>")
	)
	(segment
		(start 109.479842 -279.45207)
		(end 109.448092 -279.433782)
		(width 0.1143)
		(layer "In11.Cu")
		(net "P5E_CPU1_P1_RX_DN<13>")
	)
	(segment
		(start 109.408976 -288.201608)
		(end 109.428534 -288.190178)
		(width 0.1143)
		(layer "In11.Cu")
		(net "P5E_CPU1_P1_RX_DN<13>")
	)
	(segment
		(start 109.447076 -289.153092)
		(end 109.444536 -289.151568)
		(width 0.1143)
		(layer "In11.Cu")
		(net "P5E_CPU1_P1_RX_DN<13>")
	)
	(segment
		(start 96.27235 -385.405376)
		(end 96.272858 -385.404868)
		(width 0.14224)
		(layer "In11.Cu")
		(net "P5E_CPU1_P1_RX_DN<13>")
	)
	(segment
		(start 96.865948 -381.10541)
		(end 97.09023 -380.74219)
		(width 0.14224)
		(layer "In11.Cu")
		(net "P5E_CPU1_P1_RX_DN<13>")
	)
	(segment
		(start 129.239264 -343.413842)
		(end 129.239264 -339.044788)
		(width 0.14224)
		(layer "In11.Cu")
		(net "P5E_CPU1_P1_RX_DN<13>")
	)
	(segment
		(start 97.09023 -380.74219)
		(end 97.279206 -380.697486)
		(width 0.14224)
		(layer "In11.Cu")
		(net "P5E_CPU1_P1_RX_DN<13>")
	)
	(segment
		(start 95.919036 -385.31038)
		(end 96.27235 -385.405376)
		(width 0.14224)
		(layer "In11.Cu")
		(net "P5E_CPU1_P1_RX_DN<13>")
	)
	(segment
		(start 109.436916 -292.387274)
		(end 109.408976 -292.370764)
		(width 0.1143)
		(layer "In11.Cu")
		(net "P5E_CPU1_P1_RX_DN<13>")
	)
	(segment
		(start 109.479842 -289.780472)
		(end 109.499654 -289.766248)
		(width 0.1143)
		(layer "In11.Cu")
		(net "P5E_CPU1_P1_RX_DN<13>")
	)
	(segment
		(start 97.279206 -380.697486)
		(end 97.503234 -380.33452)
		(width 0.14224)
		(layer "In11.Cu")
		(net "P5E_CPU1_P1_RX_DN<13>")
	)
	(segment
		(start 106.354118 -363.982)
		(end 125.51664 -351.178114)
		(width 0.14224)
		(layer "In11.Cu")
		(net "P5E_CPU1_P1_RX_DN<13>")
	)
	(segment
		(start 109.479842 -289.171888)
		(end 109.448854 -289.154108)
		(width 0.1143)
		(layer "In11.Cu")
		(net "P5E_CPU1_P1_RX_DN<13>")
	)
	(segment
		(start 97.503234 -380.33452)
		(end 97.45853 -380.145798)
		(width 0.14224)
		(layer "In11.Cu")
		(net "P5E_CPU1_P1_RX_DN<13>")
	)
	(segment
		(start 98.464116 -378.778008)
		(end 103.67645 -370.336064)
		(width 0.14224)
		(layer "In11.Cu")
		(net "P5E_CPU1_P1_RX_DN<13>")
	)
	(segment
		(start 109.165644 -295.623234)
		(end 109.165644 -295.146222)
		(width 0.1143)
		(layer "In11.Cu")
		(net "P5E_CPU1_P1_RX_DN<13>")
	)
	(segment
		(start 109.499654 -292.426136)
		(end 109.479842 -292.411912)
		(width 0.1143)
		(layer "In11.Cu")
		(net "P5E_CPU1_P1_RX_DN<13>")
	)
	(segment
		(start 109.440218 -292.389306)
		(end 109.439456 -292.388798)
		(width 0.1143)
		(layer "In11.Cu")
		(net "P5E_CPU1_P1_RX_DN<13>")
	)
	(segment
		(start 109.448854 -293.038276)
		(end 109.451394 -293.036752)
		(width 0.1143)
		(layer "In11.Cu")
		(net "P5E_CPU1_P1_RX_DN<13>")
	)
	(segment
		(start 109.408976 -291.441632)
		(end 109.445552 -291.420296)
		(width 0.1143)
		(layer "In11.Cu")
		(net "P5E_CPU1_P1_RX_DN<13>")
	)
	(segment
		(start 109.448092 -292.393624)
		(end 109.447076 -292.393116)
		(width 0.1143)
		(layer "In11.Cu")
		(net "P5E_CPU1_P1_RX_DN<13>")
	)
	(segment
		(start 109.448092 -281.698954)
		(end 109.479842 -281.680666)
		(width 0.1143)
		(layer "In11.Cu")
		(net "P5E_CPU1_P1_RX_DN<13>")
	)
	(segment
		(start 98.46437 -378.778262)
		(end 98.464116 -378.778008)
		(width 0.14224)
		(layer "In11.Cu")
		(net "P5E_CPU1_P1_RX_DN<13>")
	)
	(segment
		(start 127.057404 -326.898508)
		(end 124.070364 -321.183254)
		(width 0.14224)
		(layer "In11.Cu")
		(net "P5E_CPU1_P1_RX_DN<13>")
	)
	(segment
		(start 109.43844 -292.38829)
		(end 109.436916 -292.387274)
		(width 0.1143)
		(layer "In11.Cu")
		(net "P5E_CPU1_P1_RX_DN<13>")
	)
	(segment
		(start 109.408976 -280.101802)
		(end 109.448092 -280.078942)
		(width 0.1143)
		(layer "In11.Cu")
		(net "P5E_CPU1_P1_RX_DN<13>")
	)
	(segment
		(start 109.479842 -284.312106)
		(end 109.448092 -284.293818)
		(width 0.1143)
		(layer "In11.Cu")
		(net "P5E_CPU1_P1_RX_DN<13>")
	)
	(segment
		(start 109.432598 -293.04742)
		(end 109.448092 -293.038784)
		(width 0.1143)
		(layer "In11.Cu")
		(net "P5E_CPU1_P1_RX_DN<13>")
	)
	(segment
		(start 109.468666 -294.025574)
		(end 109.4359 -294.006778)
		(width 0.1143)
		(layer "In11.Cu")
		(net "P5E_CPU1_P1_RX_DN<13>")
	)
	(segment
		(start 104.050846 -369.537488)
		(end 104.939592 -366.881156)
		(width 0.14224)
		(layer "In11.Cu")
		(net "P5E_CPU1_P1_RX_DN<13>")
	)
	(segment
		(start 109.408976 -286.581596)
		(end 109.478826 -286.54121)
		(width 0.1143)
		(layer "In11.Cu")
		(net "P5E_CPU1_P1_RX_DN<13>")
	)
	(segment
		(start 109.4359 -294.006778)
		(end 109.433106 -294.005)
		(width 0.1143)
		(layer "In11.Cu")
		(net "P5E_CPU1_P1_RX_DN<13>")
	)
	(segment
		(start 109.479842 -290.7919)
		(end 109.448854 -290.77412)
		(width 0.1143)
		(layer "In11.Cu")
		(net "P5E_CPU1_P1_RX_DN<13>")
	)
	(segment
		(start 109.448092 -284.938978)
		(end 109.479842 -284.92069)
		(width 0.1143)
		(layer "In11.Cu")
		(net "P5E_CPU1_P1_RX_DN<13>")
	)
	(segment
		(start 109.479842 -293.020496)
		(end 109.499654 -293.006272)
		(width 0.1143)
		(layer "In11.Cu")
		(net "P5E_CPU1_P1_RX_DN<13>")
	)
	(segment
		(start 126.539244 -349.93199)
		(end 129.239264 -343.413842)
		(width 0.14224)
		(layer "In11.Cu")
		(net "P5E_CPU1_P1_RX_DN<13>")
	)
	(segment
		(start 109.448092 -281.053794)
		(end 109.408976 -281.030934)
		(width 0.1143)
		(layer "In11.Cu")
		(net "P5E_CPU1_P1_RX_DN<13>")
	)
	(segment
		(start 97.45853 -380.145798)
		(end 97.682812 -379.782324)
		(width 0.14224)
		(layer "In11.Cu")
		(net "P5E_CPU1_P1_RX_DN<13>")
	)
	(segment
		(start 129.239264 -339.044788)
		(end 127.057404 -326.898508)
		(width 0.14224)
		(layer "In11.Cu")
		(net "P5E_CPU1_P1_RX_DN<13>")
	)
	(segment
		(start 109.448854 -290.77412)
		(end 109.448092 -290.773612)
		(width 0.1143)
		(layer "In11.Cu")
		(net "P5E_CPU1_P1_RX_DN<13>")
	)
	(segment
		(start 109.479842 -285.932118)
		(end 109.448092 -285.91383)
		(width 0.1143)
		(layer "In11.Cu")
		(net "P5E_CPU1_P1_RX_DN<13>")
	)
	(segment
		(start 109.454696 -293.034974)
		(end 109.455458 -293.034466)
		(width 0.1143)
		(layer "In11.Cu")
		(net "P5E_CPU1_P1_RX_DN<13>")
	)
	(arc
		(start 109.17555 -279.05202)
		(mid 109.173527 -279.04061)
		(end 109.17174 -279.02916)
		(width 0.1143)
		(layer "In11.Cu")
		(net "P5E_CPU1_P1_RX_DN<13>")
	)
	(arc
		(start 103.67645 -370.33581)
		(mid 103.886545 -369.947387)
		(end 104.050846 -369.537488)
		(width 0.14224)
		(layer "In11.Cu")
		(net "P5E_CPU1_P1_RX_DN<13>")
	)
	(arc
		(start 109.408976 -294.681656)
		(mid 109.409357 -294.681402)
		(end 109.409738 -294.681148)
		(width 0.1143)
		(layer "In11.Cu")
		(net "P5E_CPU1_P1_RX_DN<13>")
	)
	(arc
		(start 109.408976 -290.750752)
		(mid 109.165649 -290.286186)
		(end 109.408976 -289.82162)
		(width 0.1143)
		(layer "In11.Cu")
		(net "P5E_CPU1_P1_RX_DN<13>")
	)
	(arc
		(start 109.499654 -289.766248)
		(mid 109.648368 -289.47618)
		(end 109.499654 -289.186112)
		(width 0.1143)
		(layer "In11.Cu")
		(net "P5E_CPU1_P1_RX_DN<13>")
	)
	(arc
		(start 109.408976 -292.370764)
		(mid 109.165649 -291.906198)
		(end 109.408976 -291.441632)
		(width 0.1143)
		(layer "In11.Cu")
		(net "P5E_CPU1_P1_RX_DN<13>")
	)
	(arc
		(start 109.48162 -286.539178)
		(mid 109.595027 -286.406289)
		(end 109.635798 -286.23641)
		(width 0.1143)
		(layer "In11.Cu")
		(net "P5E_CPU1_P1_RX_DN<13>")
	)
	(arc
		(start 96.386396 -382.521206)
		(mid 96.436951 -382.157901)
		(end 96.58477 -381.822198)
		(width 0.14224)
		(layer "In11.Cu")
		(net "P5E_CPU1_P1_RX_DN<13>")
	)
	(arc
		(start 109.482128 -288.158682)
		(mid 109.595014 -288.025911)
		(end 109.635544 -287.856422)
		(width 0.1143)
		(layer "In11.Cu")
		(net "P5E_CPU1_P1_RX_DN<13>")
	)
	(arc
		(start 96.124776 -384.894074)
		(mid 96.089961 -384.841745)
		(end 96.07804 -384.780028)
		(width 0.14224)
		(layer "In11.Cu")
		(net "P5E_CPU1_P1_RX_DN<13>")
	)
	(arc
		(start 109.479842 -283.300678)
		(mid 109.631431 -282.996386)
		(end 109.479842 -282.692094)
		(width 0.1143)
		(layer "In11.Cu")
		(net "P5E_CPU1_P1_RX_DN<13>")
	)
	(arc
		(start 109.479842 -291.400484)
		(mid 109.630227 -291.096192)
		(end 109.479842 -290.7919)
		(width 0.1143)
		(layer "In11.Cu")
		(net "P5E_CPU1_P1_RX_DN<13>")
	)
	(arc
		(start 109.409992 -293.991538)
		(mid 109.165712 -293.527583)
		(end 109.407706 -293.062406)
		(width 0.1143)
		(layer "In11.Cu")
		(net "P5E_CPU1_P1_RX_DN<13>")
	)
	(arc
		(start 109.165644 -287.046162)
		(mid 109.230159 -286.783943)
		(end 109.408976 -286.581596)
		(width 0.1143)
		(layer "In11.Cu")
		(net "P5E_CPU1_P1_RX_DN<13>")
	)
	(arc
		(start 109.408976 -284.270958)
		(mid 109.165649 -283.806392)
		(end 109.408976 -283.341826)
		(width 0.1143)
		(layer "In11.Cu")
		(net "P5E_CPU1_P1_RX_DN<13>")
	)
	(arc
		(start 109.469936 -294.64635)
		(mid 109.648352 -294.336106)
		(end 109.469682 -294.026082)
		(width 0.1143)
		(layer "In11.Cu")
		(net "P5E_CPU1_P1_RX_DN<13>")
	)
	(arc
		(start 109.408976 -281.030934)
		(mid 109.165649 -280.566368)
		(end 109.408976 -280.101802)
		(width 0.1143)
		(layer "In11.Cu")
		(net "P5E_CPU1_P1_RX_DN<13>")
	)
	(arc
		(start 109.479842 -284.92069)
		(mid 109.630227 -284.616398)
		(end 109.479842 -284.312106)
		(width 0.1143)
		(layer "In11.Cu")
		(net "P5E_CPU1_P1_RX_DN<13>")
	)
	(arc
		(start 109.499654 -293.006272)
		(mid 109.648368 -292.716204)
		(end 109.499654 -292.426136)
		(width 0.1143)
		(layer "In11.Cu")
		(net "P5E_CPU1_P1_RX_DN<13>")
	)
	(arc
		(start 96.081088 -384.417824)
		(mid 96.115471 -384.249125)
		(end 96.21139 -384.106166)
		(width 0.14224)
		(layer "In11.Cu")
		(net "P5E_CPU1_P1_RX_DN<13>")
	)
	(arc
		(start 109.635798 -287.85439)
		(mid 109.609417 -287.720428)
		(end 109.534198 -287.606486)
		(width 0.1143)
		(layer "In11.Cu")
		(net "P5E_CPU1_P1_RX_DN<13>")
	)
	(arc
		(start 109.635798 -286.23641)
		(mid 109.591727 -286.066874)
		(end 109.479842 -285.932118)
		(width 0.1143)
		(layer "In11.Cu")
		(net "P5E_CPU1_P1_RX_DN<13>")
	)
	(arc
		(start 109.408976 -282.650946)
		(mid 109.165649 -282.18638)
		(end 109.408976 -281.721814)
		(width 0.1143)
		(layer "In11.Cu")
		(net "P5E_CPU1_P1_RX_DN<13>")
	)
	(arc
		(start 109.408976 -285.89097)
		(mid 109.165649 -285.426404)
		(end 109.408976 -284.961838)
		(width 0.1143)
		(layer "In11.Cu")
		(net "P5E_CPU1_P1_RX_DN<13>")
	)
	(arc
		(start 96.339152 -383.978404)
		(mid 96.374168 -383.926094)
		(end 96.386396 -383.864358)
		(width 0.14224)
		(layer "In11.Cu")
		(net "P5E_CPU1_P1_RX_DN<13>")
	)
	(arc
		(start 106.168444 -364.199932)
		(mid 106.246173 -364.078101)
		(end 106.354118 -363.982)
		(width 0.14224)
		(layer "In11.Cu")
		(net "P5E_CPU1_P1_RX_DN<13>")
	)
	(arc
		(start 125.51664 -351.178114)
		(mid 126.120387 -350.630911)
		(end 126.539244 -349.93199)
		(width 0.14224)
		(layer "In11.Cu")
		(net "P5E_CPU1_P1_RX_DN<13>")
	)
	(arc
		(start 109.408214 -287.516824)
		(mid 109.229914 -287.310889)
		(end 109.165644 -287.046162)
		(width 0.1143)
		(layer "In11.Cu")
		(net "P5E_CPU1_P1_RX_DN<13>")
	)
	(arc
		(start 109.479842 -280.060654)
		(mid 109.631431 -279.756362)
		(end 109.479842 -279.45207)
		(width 0.1143)
		(layer "In11.Cu")
		(net "P5E_CPU1_P1_RX_DN<13>")
	)
	(arc
		(start 109.408976 -279.410922)
		(mid 109.256989 -279.254414)
		(end 109.17555 -279.05202)
		(width 0.1143)
		(layer "In11.Cu")
		(net "P5E_CPU1_P1_RX_DN<13>")
	)
	(arc
		(start 109.479842 -281.680666)
		(mid 109.631431 -281.376374)
		(end 109.479842 -281.072082)
		(width 0.1143)
		(layer "In11.Cu")
		(net "P5E_CPU1_P1_RX_DN<13>")
	)
	(arc
		(start 109.165644 -295.146222)
		(mid 109.230159 -294.884003)
		(end 109.408976 -294.681656)
		(width 0.1143)
		(layer "In11.Cu")
		(net "P5E_CPU1_P1_RX_DN<13>")
	)
	(arc
		(start 109.408976 -289.13074)
		(mid 109.165649 -288.666174)
		(end 109.408976 -288.201608)
		(width 0.1143)
		(layer "In11.Cu")
		(net "P5E_CPU1_P1_RX_DN<13>")
	)
	(segment
		(start 106.907838 -274.630388)
		(end 106.440986 -274.896326)
		(width 0.12954)
		(layer "F.Cu")
		(net "P5E_CPU1_P1_RX_DN<12>")
	)
	(segment
		(start 94.19844 -385.31038)
		(end 94.71914 -385.31038)
		(width 0.127)
		(layer "F.Cu")
		(net "P5E_CPU1_P1_RX_DN<12>")
	)
	(segment
		(start 108.515912 -280.07437)
		(end 108.518452 -280.0731)
		(width 0.1143)
		(layer "In11.Cu")
		(net "P5E_CPU1_P1_RX_DN<12>")
	)
	(segment
		(start 108.514896 -282.67787)
		(end 108.512356 -282.676346)
		(width 0.1143)
		(layer "In11.Cu")
		(net "P5E_CPU1_P1_RX_DN<12>")
	)
	(segment
		(start 108.532676 -278.445214)
		(end 108.538518 -278.441404)
		(width 0.1143)
		(layer "In11.Cu")
		(net "P5E_CPU1_P1_RX_DN<12>")
	)
	(segment
		(start 108.4961 -280.085546)
		(end 108.505498 -280.080466)
		(width 0.1143)
		(layer "In11.Cu")
		(net "P5E_CPU1_P1_RX_DN<12>")
	)
	(segment
		(start 108.515912 -278.454358)
		(end 108.516928 -278.45385)
		(width 0.1143)
		(layer "In11.Cu")
		(net "P5E_CPU1_P1_RX_DN<12>")
	)
	(segment
		(start 108.51007 -281.055064)
		(end 108.5088 -281.054302)
		(width 0.1143)
		(layer "In11.Cu")
		(net "P5E_CPU1_P1_RX_DN<12>")
	)
	(segment
		(start 108.524294 -284.929072)
		(end 108.526326 -284.928056)
		(width 0.1143)
		(layer "In11.Cu")
		(net "P5E_CPU1_P1_RX_DN<12>")
	)
	(segment
		(start 108.50499 -294.660574)
		(end 108.505752 -294.660066)
		(width 0.1143)
		(layer "In11.Cu")
		(net "P5E_CPU1_P1_RX_DN<12>")
	)
	(segment
		(start 110.620048 -304.697384)
		(end 108.17987 -298.806108)
		(width 0.14224)
		(layer "In11.Cu")
		(net "P5E_CPU1_P1_RX_DN<12>")
	)
	(segment
		(start 108.511594 -280.07691)
		(end 108.512864 -280.076148)
		(width 0.1143)
		(layer "In11.Cu")
		(net "P5E_CPU1_P1_RX_DN<12>")
	)
	(segment
		(start 103.113586 -369.26774)
		(end 104.035098 -366.377982)
		(width 0.14224)
		(layer "In11.Cu")
		(net "P5E_CPU1_P1_RX_DN<12>")
	)
	(segment
		(start 95.313246 -381.665226)
		(end 96.28759 -380.117604)
		(width 0.14224)
		(layer "In11.Cu")
		(net "P5E_CPU1_P1_RX_DN<12>")
	)
	(segment
		(start 128.304544 -342.64981)
		(end 128.304798 -342.649556)
		(width 0.14224)
		(layer "In11.Cu")
		(net "P5E_CPU1_P1_RX_DN<12>")
	)
	(segment
		(start 95.194374 -385.334764)
		(end 95.194374 -385.163822)
		(width 0.14224)
		(layer "In11.Cu")
		(net "P5E_CPU1_P1_RX_DN<12>")
	)
	(segment
		(start 108.539788 -284.312106)
		(end 108.514896 -284.297882)
		(width 0.1143)
		(layer "In11.Cu")
		(net "P5E_CPU1_P1_RX_DN<12>")
	)
	(segment
		(start 108.512864 -280.076148)
		(end 108.513626 -280.07564)
		(width 0.1143)
		(layer "In11.Cu")
		(net "P5E_CPU1_P1_RX_DN<12>")
	)
	(segment
		(start 108.511086 -278.457406)
		(end 108.511594 -278.456898)
		(width 0.1143)
		(layer "In11.Cu")
		(net "P5E_CPU1_P1_RX_DN<12>")
	)
	(segment
		(start 108.513626 -280.07564)
		(end 108.514642 -280.075132)
		(width 0.1143)
		(layer "In11.Cu")
		(net "P5E_CPU1_P1_RX_DN<12>")
	)
	(segment
		(start 125.913388 -348.848426)
		(end 128.304544 -342.64981)
		(width 0.14224)
		(layer "In11.Cu")
		(net "P5E_CPU1_P1_RX_DN<12>")
	)
	(segment
		(start 108.524294 -291.407596)
		(end 108.529374 -291.40785)
		(width 0.1143)
		(layer "In11.Cu")
		(net "P5E_CPU1_P1_RX_DN<12>")
	)
	(segment
		(start 108.477304 -289.816794)
		(end 108.47832 -289.816286)
		(width 0.1143)
		(layer "In11.Cu")
		(net "P5E_CPU1_P1_RX_DN<12>")
	)
	(segment
		(start 108.507022 -281.053286)
		(end 108.505498 -281.05227)
		(width 0.1143)
		(layer "In11.Cu")
		(net "P5E_CPU1_P1_RX_DN<12>")
	)
	(segment
		(start 126.114556 -327.111106)
		(end 126.113794 -327.107296)
		(width 0.14224)
		(layer "In11.Cu")
		(net "P5E_CPU1_P1_RX_DN<12>")
	)
	(segment
		(start 108.539788 -277.832058)
		(end 108.514896 -277.817834)
		(width 0.1143)
		(layer "In11.Cu")
		(net "P5E_CPU1_P1_RX_DN<12>")
	)
	(segment
		(start 108.532676 -284.924246)
		(end 108.536994 -284.92196)
		(width 0.1143)
		(layer "In11.Cu")
		(net "P5E_CPU1_P1_RX_DN<12>")
	)
	(segment
		(start 108.539788 -279.45207)
		(end 108.514896 -279.437846)
		(width 0.1143)
		(layer "In11.Cu")
		(net "P5E_CPU1_P1_RX_DN<12>")
	)
	(segment
		(start 107.75569 -276.516338)
		(end 107.755944 -276.516338)
		(width 0.1143)
		(layer "In11.Cu")
		(net "P5E_CPU1_P1_RX_DN<12>")
	)
	(segment
		(start 108.507022 -280.07945)
		(end 108.508038 -280.078942)
		(width 0.1143)
		(layer "In11.Cu")
		(net "P5E_CPU1_P1_RX_DN<12>")
	)
	(segment
		(start 108.505498 -285.912306)
		(end 108.502704 -285.910782)
		(width 0.1143)
		(layer "In11.Cu")
		(net "P5E_CPU1_P1_RX_DN<12>")
	)
	(segment
		(start 108.531152 -284.925262)
		(end 108.532676 -284.924246)
		(width 0.1143)
		(layer "In11.Cu")
		(net "P5E_CPU1_P1_RX_DN<12>")
	)
	(segment
		(start 108.514896 -284.297882)
		(end 108.512356 -284.296358)
		(width 0.1143)
		(layer "In11.Cu")
		(net "P5E_CPU1_P1_RX_DN<12>")
	)
	(segment
		(start 108.514388 -294.65524)
		(end 108.539788 -294.640508)
		(width 0.1143)
		(layer "In11.Cu")
		(net "P5E_CPU1_P1_RX_DN<12>")
	)
	(segment
		(start 108.47832 -289.816286)
		(end 108.479082 -289.815778)
		(width 0.1143)
		(layer "In11.Cu")
		(net "P5E_CPU1_P1_RX_DN<12>")
	)
	(segment
		(start 108.505498 -279.432258)
		(end 108.502704 -279.430734)
		(width 0.1143)
		(layer "In11.Cu")
		(net "P5E_CPU1_P1_RX_DN<12>")
	)
	(segment
		(start 108.5088 -280.078434)
		(end 108.51007 -280.077672)
		(width 0.1143)
		(layer "In11.Cu")
		(net "P5E_CPU1_P1_RX_DN<12>")
	)
	(segment
		(start 95.186246 -383.93116)
		(end 95.186246 -382.10617)
		(width 0.14224)
		(layer "In11.Cu")
		(net "P5E_CPU1_P1_RX_DN<12>")
	)
	(segment
		(start 108.514896 -279.437846)
		(end 108.512356 -279.436322)
		(width 0.1143)
		(layer "In11.Cu")
		(net "P5E_CPU1_P1_RX_DN<12>")
	)
	(segment
		(start 108.476542 -289.817302)
		(end 108.477304 -289.816794)
		(width 0.1143)
		(layer "In11.Cu")
		(net "P5E_CPU1_P1_RX_DN<12>")
	)
	(segment
		(start 108.539788 -282.692094)
		(end 108.514896 -282.67787)
		(width 0.1143)
		(layer "In11.Cu")
		(net "P5E_CPU1_P1_RX_DN<12>")
	)
	(segment
		(start 108.51007 -285.9151)
		(end 108.5088 -285.914338)
		(width 0.1143)
		(layer "In11.Cu")
		(net "P5E_CPU1_P1_RX_DN<12>")
	)
	(segment
		(start 108.502704 -279.430734)
		(end 108.501434 -279.429972)
		(width 0.1143)
		(layer "In11.Cu")
		(net "P5E_CPU1_P1_RX_DN<12>")
	)
	(segment
		(start 108.482892 -280.09342)
		(end 108.483908 -280.092912)
		(width 0.1143)
		(layer "In11.Cu")
		(net "P5E_CPU1_P1_RX_DN<12>")
	)
	(segment
		(start 97.863152 -377.614942)
		(end 103.100124 -369.296442)
		(width 0.14224)
		(layer "In11.Cu")
		(net "P5E_CPU1_P1_RX_DN<12>")
	)
	(segment
		(start 108.49991 -281.048968)
		(end 108.468922 -281.030934)
		(width 0.1143)
		(layer "In11.Cu")
		(net "P5E_CPU1_P1_RX_DN<12>")
	)
	(segment
		(start 108.49991 -282.66898)
		(end 108.468922 -282.650946)
		(width 0.1143)
		(layer "In11.Cu")
		(net "P5E_CPU1_P1_RX_DN<12>")
	)
	(segment
		(start 96.471994 -379.566932)
		(end 96.661224 -379.524006)
		(width 0.14224)
		(layer "In11.Cu")
		(net "P5E_CPU1_P1_RX_DN<12>")
	)
	(segment
		(start 108.508038 -280.078942)
		(end 108.5088 -280.078434)
		(width 0.1143)
		(layer "In11.Cu")
		(net "P5E_CPU1_P1_RX_DN<12>")
	)
	(segment
		(start 108.51007 -282.675076)
		(end 108.5088 -282.674314)
		(width 0.1143)
		(layer "In11.Cu")
		(net "P5E_CPU1_P1_RX_DN<12>")
	)
	(segment
		(start 108.5088 -281.054302)
		(end 108.508038 -281.053794)
		(width 0.1143)
		(layer "In11.Cu")
		(net "P5E_CPU1_P1_RX_DN<12>")
	)
	(segment
		(start 108.50118 -294.66286)
		(end 108.50499 -294.660574)
		(width 0.1143)
		(layer "In11.Cu")
		(net "P5E_CPU1_P1_RX_DN<12>")
	)
	(segment
		(start 108.491782 -280.088086)
		(end 108.493306 -280.087324)
		(width 0.1143)
		(layer "In11.Cu")
		(net "P5E_CPU1_P1_RX_DN<12>")
	)
	(segment
		(start 108.575094 -289.751516)
		(end 108.575348 -289.751262)
		(width 0.1143)
		(layer "In11.Cu")
		(net "P5E_CPU1_P1_RX_DN<12>")
	)
	(segment
		(start 108.068618 -277.021544)
		(end 107.999022 -276.980904)
		(width 0.1143)
		(layer "In11.Cu")
		(net "P5E_CPU1_P1_RX_DN<12>")
	)
	(segment
		(start 108.512356 -282.676346)
		(end 108.511594 -282.675838)
		(width 0.1143)
		(layer "In11.Cu")
		(net "P5E_CPU1_P1_RX_DN<12>")
	)
	(segment
		(start 108.468922 -284.961838)
		(end 108.524294 -284.929072)
		(width 0.1143)
		(layer "In11.Cu")
		(net "P5E_CPU1_P1_RX_DN<12>")
	)
	(segment
		(start 108.501434 -277.80996)
		(end 108.49991 -277.808944)
		(width 0.1143)
		(layer "In11.Cu")
		(net "P5E_CPU1_P1_RX_DN<12>")
	)
	(segment
		(start 108.501434 -285.91002)
		(end 108.49991 -285.909004)
		(width 0.1143)
		(layer "In11.Cu")
		(net "P5E_CPU1_P1_RX_DN<12>")
	)
	(segment
		(start 108.511594 -278.456898)
		(end 108.512864 -278.456136)
		(width 0.1143)
		(layer "In11.Cu")
		(net "P5E_CPU1_P1_RX_DN<12>")
	)
	(segment
		(start 97.673668 -377.657868)
		(end 97.863152 -377.614942)
		(width 0.14224)
		(layer "In11.Cu")
		(net "P5E_CPU1_P1_RX_DN<12>")
	)
	(segment
		(start 108.479336 -289.815524)
		(end 108.575094 -289.751516)
		(width 0.1143)
		(layer "In11.Cu")
		(net "P5E_CPU1_P1_RX_DN<12>")
	)
	(segment
		(start 108.512356 -281.056334)
		(end 108.511594 -281.055826)
		(width 0.1143)
		(layer "In11.Cu")
		(net "P5E_CPU1_P1_RX_DN<12>")
	)
	(segment
		(start 94.882208 -384.234944)
		(end 95.186246 -383.93116)
		(width 0.14224)
		(layer "In11.Cu")
		(net "P5E_CPU1_P1_RX_DN<12>")
	)
	(segment
		(start 108.512356 -284.296358)
		(end 108.511594 -284.29585)
		(width 0.1143)
		(layer "In11.Cu")
		(net "P5E_CPU1_P1_RX_DN<12>")
	)
	(segment
		(start 108.49991 -277.808944)
		(end 108.468922 -277.79091)
		(width 0.1143)
		(layer "In11.Cu")
		(net "P5E_CPU1_P1_RX_DN<12>")
	)
	(segment
		(start 108.518452 -280.0731)
		(end 108.539788 -280.060654)
		(width 0.1143)
		(layer "In11.Cu")
		(net "P5E_CPU1_P1_RX_DN<12>")
	)
	(segment
		(start 108.453936 -289.832288)
		(end 108.458254 -289.82924)
		(width 0.1143)
		(layer "In11.Cu")
		(net "P5E_CPU1_P1_RX_DN<12>")
	)
	(segment
		(start 108.51007 -279.435052)
		(end 108.5088 -279.43429)
		(width 0.1143)
		(layer "In11.Cu")
		(net "P5E_CPU1_P1_RX_DN<12>")
	)
	(segment
		(start 108.507022 -285.913322)
		(end 108.505498 -285.912306)
		(width 0.1143)
		(layer "In11.Cu")
		(net "P5E_CPU1_P1_RX_DN<12>")
	)
	(segment
		(start 108.512356 -277.81631)
		(end 108.511594 -277.815802)
		(width 0.1143)
		(layer "In11.Cu")
		(net "P5E_CPU1_P1_RX_DN<12>")
	)
	(segment
		(start 108.539534 -284.920436)
		(end 108.539788 -284.92069)
		(width 0.1143)
		(layer "In11.Cu")
		(net "P5E_CPU1_P1_RX_DN<12>")
	)
	(segment
		(start 108.22559 -295.623234)
		(end 108.22559 -295.146222)
		(width 0.1143)
		(layer "In11.Cu")
		(net "P5E_CPU1_P1_RX_DN<12>")
	)
	(segment
		(start 108.521246 -283.304488)
		(end 108.534454 -283.304488)
		(width 0.1143)
		(layer "In11.Cu")
		(net "P5E_CPU1_P1_RX_DN<12>")
	)
	(segment
		(start 108.49991 -284.288992)
		(end 108.468922 -284.270958)
		(width 0.1143)
		(layer "In11.Cu")
		(net "P5E_CPU1_P1_RX_DN<12>")
	)
	(segment
		(start 108.511594 -284.29585)
		(end 108.51007 -284.295088)
		(width 0.1143)
		(layer "In11.Cu")
		(net "P5E_CPU1_P1_RX_DN<12>")
	)
	(segment
		(start 108.5088 -282.674314)
		(end 108.508038 -282.673806)
		(width 0.1143)
		(layer "In11.Cu")
		(net "P5E_CPU1_P1_RX_DN<12>")
	)
	(segment
		(start 108.501434 -284.290008)
		(end 108.49991 -284.288992)
		(width 0.1143)
		(layer "In11.Cu")
		(net "P5E_CPU1_P1_RX_DN<12>")
	)
	(segment
		(start 108.472478 -289.819588)
		(end 108.476542 -289.817302)
		(width 0.1143)
		(layer "In11.Cu")
		(net "P5E_CPU1_P1_RX_DN<12>")
	)
	(segment
		(start 108.493306 -280.087324)
		(end 108.495338 -280.086054)
		(width 0.1143)
		(layer "In11.Cu")
		(net "P5E_CPU1_P1_RX_DN<12>")
	)
	(segment
		(start 108.489242 -280.08961)
		(end 108.491782 -280.088086)
		(width 0.1143)
		(layer "In11.Cu")
		(net "P5E_CPU1_P1_RX_DN<12>")
	)
	(segment
		(start 108.505498 -282.672282)
		(end 108.502704 -282.670758)
		(width 0.1143)
		(layer "In11.Cu")
		(net "P5E_CPU1_P1_RX_DN<12>")
	)
	(segment
		(start 96.661224 -379.524006)
		(end 96.888554 -379.163072)
		(width 0.14224)
		(layer "In11.Cu")
		(net "P5E_CPU1_P1_RX_DN<12>")
	)
	(segment
		(start 108.539788 -285.932118)
		(end 108.514896 -285.917894)
		(width 0.1143)
		(layer "In11.Cu")
		(net "P5E_CPU1_P1_RX_DN<12>")
	)
	(segment
		(start 108.512356 -285.91637)
		(end 108.511594 -285.915862)
		(width 0.1143)
		(layer "In11.Cu")
		(net "P5E_CPU1_P1_RX_DN<12>")
	)
	(segment
		(start 108.536486 -281.680666)
		(end 108.539788 -281.680666)
		(width 0.1143)
		(layer "In11.Cu")
		(net "P5E_CPU1_P1_RX_DN<12>")
	)
	(segment
		(start 108.49991 -279.428956)
		(end 108.468922 -279.410922)
		(width 0.1143)
		(layer "In11.Cu")
		(net "P5E_CPU1_P1_RX_DN<12>")
	)
	(segment
		(start 108.468922 -288.201608)
		(end 108.541566 -288.15919)
		(width 0.1143)
		(layer "In11.Cu")
		(net "P5E_CPU1_P1_RX_DN<12>")
	)
	(segment
		(start 108.514896 -285.917894)
		(end 108.512356 -285.91637)
		(width 0.1143)
		(layer "In11.Cu")
		(net "P5E_CPU1_P1_RX_DN<12>")
	)
	(segment
		(start 108.505498 -281.05227)
		(end 108.502704 -281.050746)
		(width 0.1143)
		(layer "In11.Cu")
		(net "P5E_CPU1_P1_RX_DN<12>")
	)
	(segment
		(start 108.508038 -281.053794)
		(end 108.507022 -281.053286)
		(width 0.1143)
		(layer "In11.Cu")
		(net "P5E_CPU1_P1_RX_DN<12>")
	)
	(segment
		(start 108.516928 -278.45385)
		(end 108.532676 -278.445214)
		(width 0.1143)
		(layer "In11.Cu")
		(net "P5E_CPU1_P1_RX_DN<12>")
	)
	(segment
		(start 108.505498 -294.012112)
		(end 108.468922 -293.990776)
		(width 0.1143)
		(layer "In11.Cu")
		(net "P5E_CPU1_P1_RX_DN<12>")
	)
	(segment
		(start 108.52785 -284.92704)
		(end 108.529882 -284.926024)
		(width 0.1143)
		(layer "In11.Cu")
		(net "P5E_CPU1_P1_RX_DN<12>")
	)
	(segment
		(start 108.512356 -294.656256)
		(end 108.514388 -294.65524)
		(width 0.1143)
		(layer "In11.Cu")
		(net "P5E_CPU1_P1_RX_DN<12>")
	)
	(segment
		(start 108.511594 -279.435814)
		(end 108.51007 -279.435052)
		(width 0.1143)
		(layer "In11.Cu")
		(net "P5E_CPU1_P1_RX_DN<12>")
	)
	(segment
		(start 108.495338 -280.086054)
		(end 108.4961 -280.085546)
		(width 0.1143)
		(layer "In11.Cu")
		(net "P5E_CPU1_P1_RX_DN<12>")
	)
	(segment
		(start 108.502704 -282.670758)
		(end 108.501434 -282.669996)
		(width 0.1143)
		(layer "In11.Cu")
		(net "P5E_CPU1_P1_RX_DN<12>")
	)
	(segment
		(start 108.468922 -280.101802)
		(end 108.468668 -280.101802)
		(width 0.1143)
		(layer "In11.Cu")
		(net "P5E_CPU1_P1_RX_DN<12>")
	)
	(segment
		(start 108.513626 -278.455628)
		(end 108.514642 -278.45512)
		(width 0.1143)
		(layer "In11.Cu")
		(net "P5E_CPU1_P1_RX_DN<12>")
	)
	(segment
		(start 97.262188 -378.569474)
		(end 97.489518 -378.20854)
		(width 0.14224)
		(layer "In11.Cu")
		(net "P5E_CPU1_P1_RX_DN<12>")
	)
	(segment
		(start 108.468922 -286.581596)
		(end 108.541566 -286.539178)
		(width 0.1143)
		(layer "In11.Cu")
		(net "P5E_CPU1_P1_RX_DN<12>")
	)
	(segment
		(start 108.485178 -280.091642)
		(end 108.489242 -280.08961)
		(width 0.1143)
		(layer "In11.Cu")
		(net "P5E_CPU1_P1_RX_DN<12>")
	)
	(segment
		(start 108.536994 -284.92196)
		(end 108.539534 -284.920436)
		(width 0.1143)
		(layer "In11.Cu")
		(net "P5E_CPU1_P1_RX_DN<12>")
	)
	(segment
		(start 108.468668 -280.101802)
		(end 108.48213 -280.093928)
		(width 0.1143)
		(layer "In11.Cu")
		(net "P5E_CPU1_P1_RX_DN<12>")
	)
	(segment
		(start 108.507022 -282.673298)
		(end 108.505498 -282.672282)
		(width 0.1143)
		(layer "In11.Cu")
		(net "P5E_CPU1_P1_RX_DN<12>")
	)
	(segment
		(start 108.511594 -282.675838)
		(end 108.51007 -282.675076)
		(width 0.1143)
		(layer "In11.Cu")
		(net "P5E_CPU1_P1_RX_DN<12>")
	)
	(segment
		(start 108.483908 -280.092912)
		(end 108.485178 -280.091642)
		(width 0.1143)
		(layer "In11.Cu")
		(net "P5E_CPU1_P1_RX_DN<12>")
	)
	(segment
		(start 95.072708 -385.404868)
		(end 95.194374 -385.334764)
		(width 0.14224)
		(layer "In11.Cu")
		(net "P5E_CPU1_P1_RX_DN<12>")
	)
	(segment
		(start 108.547154 -290.807648)
		(end 108.46054 -290.75507)
		(width 0.1143)
		(layer "In11.Cu")
		(net "P5E_CPU1_P1_RX_DN<12>")
	)
	(segment
		(start 108.501434 -281.049984)
		(end 108.49991 -281.048968)
		(width 0.1143)
		(layer "In11.Cu")
		(net "P5E_CPU1_P1_RX_DN<12>")
	)
	(segment
		(start 104.035098 -366.377982)
		(end 105.185972 -363.795564)
		(width 0.14224)
		(layer "In11.Cu")
		(net "P5E_CPU1_P1_RX_DN<12>")
	)
	(segment
		(start 108.508038 -284.293818)
		(end 108.507022 -284.29331)
		(width 0.1143)
		(layer "In11.Cu")
		(net "P5E_CPU1_P1_RX_DN<12>")
	)
	(segment
		(start 108.511594 -277.815802)
		(end 108.51007 -277.81504)
		(width 0.1143)
		(layer "In11.Cu")
		(net "P5E_CPU1_P1_RX_DN<12>")
	)
	(segment
		(start 108.539788 -292.411912)
		(end 108.469176 -292.371272)
		(width 0.1143)
		(layer "In11.Cu")
		(net "P5E_CPU1_P1_RX_DN<12>")
	)
	(segment
		(start 108.507022 -284.29331)
		(end 108.505498 -284.292294)
		(width 0.1143)
		(layer "In11.Cu")
		(net "P5E_CPU1_P1_RX_DN<12>")
	)
	(segment
		(start 108.526326 -284.928056)
		(end 108.52785 -284.92704)
		(width 0.1143)
		(layer "In11.Cu")
		(net "P5E_CPU1_P1_RX_DN<12>")
	)
	(segment
		(start 94.877382 -384.84683)
		(end 94.882208 -384.234944)
		(width 0.14224)
		(layer "In11.Cu")
		(net "P5E_CPU1_P1_RX_DN<12>")
	)
	(segment
		(start 108.508038 -285.91383)
		(end 108.507022 -285.913322)
		(width 0.1143)
		(layer "In11.Cu")
		(net "P5E_CPU1_P1_RX_DN<12>")
	)
	(segment
		(start 108.51007 -277.81504)
		(end 108.5088 -277.814278)
		(width 0.1143)
		(layer "In11.Cu")
		(net "P5E_CPU1_P1_RX_DN<12>")
	)
	(segment
		(start 97.489518 -378.20854)
		(end 97.446338 -378.01931)
		(width 0.14224)
		(layer "In11.Cu")
		(net "P5E_CPU1_P1_RX_DN<12>")
	)
	(segment
		(start 108.529374 -291.40785)
		(end 108.542836 -291.398452)
		(width 0.1143)
		(layer "In11.Cu")
		(net "P5E_CPU1_P1_RX_DN<12>")
	)
	(segment
		(start 108.529882 -284.926024)
		(end 108.531152 -284.925262)
		(width 0.1143)
		(layer "In11.Cu")
		(net "P5E_CPU1_P1_RX_DN<12>")
	)
	(segment
		(start 108.479082 -289.815778)
		(end 108.479336 -289.815524)
		(width 0.1143)
		(layer "In11.Cu")
		(net "P5E_CPU1_P1_RX_DN<12>")
	)
	(segment
		(start 108.501434 -279.429972)
		(end 108.49991 -279.428956)
		(width 0.1143)
		(layer "In11.Cu")
		(net "P5E_CPU1_P1_RX_DN<12>")
	)
	(segment
		(start 107.600496 -276.212554)
		(end 107.531662 -276.172676)
		(width 0.1143)
		(layer "In11.Cu")
		(net "P5E_CPU1_P1_RX_DN<12>")
	)
	(segment
		(start 108.51007 -284.295088)
		(end 108.5088 -284.294326)
		(width 0.1143)
		(layer "In11.Cu")
		(net "P5E_CPU1_P1_RX_DN<12>")
	)
	(segment
		(start 96.845374 -378.973842)
		(end 97.072704 -378.6124)
		(width 0.14224)
		(layer "In11.Cu")
		(net "P5E_CPU1_P1_RX_DN<12>")
	)
	(segment
		(start 108.458254 -289.82924)
		(end 108.472478 -289.819588)
		(width 0.1143)
		(layer "In11.Cu")
		(net "P5E_CPU1_P1_RX_DN<12>")
	)
	(segment
		(start 108.540042 -289.172396)
		(end 108.476796 -289.135312)
		(width 0.1143)
		(layer "In11.Cu")
		(net "P5E_CPU1_P1_RX_DN<12>")
	)
	(segment
		(start 108.511594 -281.055826)
		(end 108.51007 -281.055064)
		(width 0.1143)
		(layer "In11.Cu")
		(net "P5E_CPU1_P1_RX_DN<12>")
	)
	(segment
		(start 108.539788 -281.072082)
		(end 108.514896 -281.057858)
		(width 0.1143)
		(layer "In11.Cu")
		(net "P5E_CPU1_P1_RX_DN<12>")
	)
	(segment
		(start 108.502704 -281.050746)
		(end 108.501434 -281.049984)
		(width 0.1143)
		(layer "In11.Cu")
		(net "P5E_CPU1_P1_RX_DN<12>")
	)
	(segment
		(start 108.5088 -285.914338)
		(end 108.508038 -285.91383)
		(width 0.1143)
		(layer "In11.Cu")
		(net "P5E_CPU1_P1_RX_DN<12>")
	)
	(segment
		(start 108.532168 -281.684984)
		(end 108.536486 -281.680666)
		(width 0.1143)
		(layer "In11.Cu")
		(net "P5E_CPU1_P1_RX_DN<12>")
	)
	(segment
		(start 108.507022 -277.813262)
		(end 108.505498 -277.812246)
		(width 0.1143)
		(layer "In11.Cu")
		(net "P5E_CPU1_P1_RX_DN<12>")
	)
	(segment
		(start 108.511594 -294.656764)
		(end 108.512356 -294.656256)
		(width 0.1143)
		(layer "In11.Cu")
		(net "P5E_CPU1_P1_RX_DN<12>")
	)
	(segment
		(start 108.508038 -279.433782)
		(end 108.507022 -279.433274)
		(width 0.1143)
		(layer "In11.Cu")
		(net "P5E_CPU1_P1_RX_DN<12>")
	)
	(segment
		(start 97.072704 -378.6124)
		(end 97.262188 -378.569474)
		(width 0.14224)
		(layer "In11.Cu")
		(net "P5E_CPU1_P1_RX_DN<12>")
	)
	(segment
		(start 108.505498 -284.292294)
		(end 108.502704 -284.29077)
		(width 0.1143)
		(layer "In11.Cu")
		(net "P5E_CPU1_P1_RX_DN<12>")
	)
	(segment
		(start 116.256054 -313.131708)
		(end 110.620048 -304.697384)
		(width 0.14224)
		(layer "In11.Cu")
		(net "P5E_CPU1_P1_RX_DN<12>")
	)
	(segment
		(start 108.468922 -281.721814)
		(end 108.468922 -281.721052)
		(width 0.1143)
		(layer "In11.Cu")
		(net "P5E_CPU1_P1_RX_DN<12>")
	)
	(segment
		(start 108.508038 -277.81377)
		(end 108.507022 -277.813262)
		(width 0.1143)
		(layer "In11.Cu")
		(net "P5E_CPU1_P1_RX_DN<12>")
	)
	(segment
		(start 108.501434 -282.669996)
		(end 108.49991 -282.66898)
		(width 0.1143)
		(layer "In11.Cu")
		(net "P5E_CPU1_P1_RX_DN<12>")
	)
	(segment
		(start 108.468922 -281.721052)
		(end 108.532168 -281.684984)
		(width 0.1143)
		(layer "In11.Cu")
		(net "P5E_CPU1_P1_RX_DN<12>")
	)
	(segment
		(start 108.476796 -289.135312)
		(end 108.476542 -289.135312)
		(width 0.1143)
		(layer "In11.Cu")
		(net "P5E_CPU1_P1_RX_DN<12>")
	)
	(segment
		(start 108.502704 -285.910782)
		(end 108.501434 -285.91002)
		(width 0.1143)
		(layer "In11.Cu")
		(net "P5E_CPU1_P1_RX_DN<12>")
	)
	(segment
		(start 96.244664 -379.928374)
		(end 96.471994 -379.566932)
		(width 0.14224)
		(layer "In11.Cu")
		(net "P5E_CPU1_P1_RX_DN<12>")
	)
	(segment
		(start 94.71914 -385.31038)
		(end 95.0722 -385.405376)
		(width 0.14224)
		(layer "In11.Cu")
		(net "P5E_CPU1_P1_RX_DN<12>")
	)
	(segment
		(start 108.505498 -277.812246)
		(end 108.502704 -277.810722)
		(width 0.1143)
		(layer "In11.Cu")
		(net "P5E_CPU1_P1_RX_DN<12>")
	)
	(segment
		(start 108.49991 -285.909004)
		(end 108.468922 -285.89097)
		(width 0.1143)
		(layer "In11.Cu")
		(net "P5E_CPU1_P1_RX_DN<12>")
	)
	(segment
		(start 108.539788 -294.031924)
		(end 108.505498 -294.012112)
		(width 0.1143)
		(layer "In11.Cu")
		(net "P5E_CPU1_P1_RX_DN<12>")
	)
	(segment
		(start 108.539788 -287.55213)
		(end 108.471462 -287.512506)
		(width 0.1143)
		(layer "In11.Cu")
		(net "P5E_CPU1_P1_RX_DN<12>")
	)
	(segment
		(start 108.514896 -277.817834)
		(end 108.512356 -277.81631)
		(width 0.1143)
		(layer "In11.Cu")
		(net "P5E_CPU1_P1_RX_DN<12>")
	)
	(segment
		(start 108.17987 -298.806108)
		(end 108.17987 -295.697402)
		(width 0.14224)
		(layer "In11.Cu")
		(net "P5E_CPU1_P1_RX_DN<12>")
	)
	(segment
		(start 95.194374 -385.163822)
		(end 94.877382 -384.84683)
		(width 0.14224)
		(layer "In11.Cu")
		(net "P5E_CPU1_P1_RX_DN<12>")
	)
	(segment
		(start 108.51007 -280.077672)
		(end 108.511594 -280.07691)
		(width 0.1143)
		(layer "In11.Cu")
		(net "P5E_CPU1_P1_RX_DN<12>")
	)
	(segment
		(start 108.17987 -295.697402)
		(end 108.17987 -295.668954)
		(width 0.1143)
		(layer "In11.Cu")
		(net "P5E_CPU1_P1_RX_DN<12>")
	)
	(segment
		(start 126.113794 -327.107296)
		(end 123.286774 -321.69862)
		(width 0.14224)
		(layer "In11.Cu")
		(net "P5E_CPU1_P1_RX_DN<12>")
	)
	(segment
		(start 108.512864 -278.456136)
		(end 108.513626 -278.455628)
		(width 0.1143)
		(layer "In11.Cu")
		(net "P5E_CPU1_P1_RX_DN<12>")
	)
	(segment
		(start 97.446338 -378.01931)
		(end 97.673668 -377.657868)
		(width 0.14224)
		(layer "In11.Cu")
		(net "P5E_CPU1_P1_RX_DN<12>")
	)
	(segment
		(start 108.5088 -284.294326)
		(end 108.508038 -284.293818)
		(width 0.1143)
		(layer "In11.Cu")
		(net "P5E_CPU1_P1_RX_DN<12>")
	)
	(segment
		(start 106.738928 -274.896326)
		(end 106.440986 -274.896326)
		(width 0.1143)
		(layer "In11.Cu")
		(net "P5E_CPU1_P1_RX_DN<12>")
	)
	(segment
		(start 108.511594 -285.915862)
		(end 108.51007 -285.9151)
		(width 0.1143)
		(layer "In11.Cu")
		(net "P5E_CPU1_P1_RX_DN<12>")
	)
	(segment
		(start 108.502704 -277.810722)
		(end 108.501434 -277.80996)
		(width 0.1143)
		(layer "In11.Cu")
		(net "P5E_CPU1_P1_RX_DN<12>")
	)
	(segment
		(start 108.512356 -279.436322)
		(end 108.511594 -279.435814)
		(width 0.1143)
		(layer "In11.Cu")
		(net "P5E_CPU1_P1_RX_DN<12>")
	)
	(segment
		(start 108.514642 -280.075132)
		(end 108.515912 -280.07437)
		(width 0.1143)
		(layer "In11.Cu")
		(net "P5E_CPU1_P1_RX_DN<12>")
	)
	(segment
		(start 108.502704 -284.29077)
		(end 108.501434 -284.290008)
		(width 0.1143)
		(layer "In11.Cu")
		(net "P5E_CPU1_P1_RX_DN<12>")
	)
	(segment
		(start 108.17987 -295.668954)
		(end 108.22559 -295.623234)
		(width 0.1143)
		(layer "In11.Cu")
		(net "P5E_CPU1_P1_RX_DN<12>")
	)
	(segment
		(start 108.468922 -293.061644)
		(end 108.539788 -293.020496)
		(width 0.1143)
		(layer "In11.Cu")
		(net "P5E_CPU1_P1_RX_DN<12>")
	)
	(segment
		(start 128.304798 -339.30336)
		(end 126.114556 -327.111106)
		(width 0.14224)
		(layer "In11.Cu")
		(net "P5E_CPU1_P1_RX_DN<12>")
	)
	(segment
		(start 108.508038 -282.673806)
		(end 108.507022 -282.673298)
		(width 0.1143)
		(layer "In11.Cu")
		(net "P5E_CPU1_P1_RX_DN<12>")
	)
	(segment
		(start 96.28759 -380.117604)
		(end 96.244664 -379.928374)
		(width 0.14224)
		(layer "In11.Cu")
		(net "P5E_CPU1_P1_RX_DN<12>")
	)
	(segment
		(start 108.5088 -279.43429)
		(end 108.508038 -279.433782)
		(width 0.1143)
		(layer "In11.Cu")
		(net "P5E_CPU1_P1_RX_DN<12>")
	)
	(segment
		(start 108.507022 -279.433274)
		(end 108.505498 -279.432258)
		(width 0.1143)
		(layer "In11.Cu")
		(net "P5E_CPU1_P1_RX_DN<12>")
	)
	(segment
		(start 107.129834 -275.40204)
		(end 107.058968 -275.360892)
		(width 0.1143)
		(layer "In11.Cu")
		(net "P5E_CPU1_P1_RX_DN<12>")
	)
	(segment
		(start 96.888554 -379.163072)
		(end 96.845374 -378.973842)
		(width 0.14224)
		(layer "In11.Cu")
		(net "P5E_CPU1_P1_RX_DN<12>")
	)
	(segment
		(start 123.286774 -321.69862)
		(end 116.256054 -313.131708)
		(width 0.14224)
		(layer "In11.Cu")
		(net "P5E_CPU1_P1_RX_DN<12>")
	)
	(segment
		(start 108.48213 -280.093928)
		(end 108.482892 -280.09342)
		(width 0.1143)
		(layer "In11.Cu")
		(net "P5E_CPU1_P1_RX_DN<12>")
	)
	(segment
		(start 108.539534 -278.440642)
		(end 108.539788 -278.440642)
		(width 0.1143)
		(layer "In11.Cu")
		(net "P5E_CPU1_P1_RX_DN<12>")
	)
	(segment
		(start 108.514642 -278.45512)
		(end 108.515912 -278.454358)
		(width 0.1143)
		(layer "In11.Cu")
		(net "P5E_CPU1_P1_RX_DN<12>")
	)
	(segment
		(start 108.469684 -278.481282)
		(end 108.511086 -278.457406)
		(width 0.1143)
		(layer "In11.Cu")
		(net "P5E_CPU1_P1_RX_DN<12>")
	)
	(segment
		(start 95.0722 -385.405376)
		(end 95.072708 -385.404868)
		(width 0.14224)
		(layer "In11.Cu")
		(net "P5E_CPU1_P1_RX_DN<12>")
	)
	(segment
		(start 128.304798 -342.649556)
		(end 128.304798 -339.30336)
		(width 0.14224)
		(layer "In11.Cu")
		(net "P5E_CPU1_P1_RX_DN<12>")
	)
	(segment
		(start 108.505498 -280.080466)
		(end 108.507022 -280.07945)
		(width 0.1143)
		(layer "In11.Cu")
		(net "P5E_CPU1_P1_RX_DN<12>")
	)
	(segment
		(start 106.821732 -274.97913)
		(end 106.738928 -274.896326)
		(width 0.1143)
		(layer "In11.Cu")
		(net "P5E_CPU1_P1_RX_DN<12>")
	)
	(segment
		(start 108.468922 -283.341826)
		(end 108.521246 -283.304488)
		(width 0.1143)
		(layer "In11.Cu")
		(net "P5E_CPU1_P1_RX_DN<12>")
	)
	(segment
		(start 105.56494 -363.345984)
		(end 124.362464 -350.786192)
		(width 0.14224)
		(layer "In11.Cu")
		(net "P5E_CPU1_P1_RX_DN<12>")
	)
	(segment
		(start 108.514896 -281.057858)
		(end 108.512356 -281.056334)
		(width 0.1143)
		(layer "In11.Cu")
		(net "P5E_CPU1_P1_RX_DN<12>")
	)
	(segment
		(start 108.476542 -289.135312)
		(end 108.468922 -289.13074)
		(width 0.1143)
		(layer "In11.Cu")
		(net "P5E_CPU1_P1_RX_DN<12>")
	)
	(segment
		(start 108.468922 -294.681656)
		(end 108.50118 -294.66286)
		(width 0.1143)
		(layer "In11.Cu")
		(net "P5E_CPU1_P1_RX_DN<12>")
	)
	(segment
		(start 108.505752 -294.660066)
		(end 108.511594 -294.656764)
		(width 0.1143)
		(layer "In11.Cu")
		(net "P5E_CPU1_P1_RX_DN<12>")
	)
	(segment
		(start 108.5088 -277.814278)
		(end 108.508038 -277.81377)
		(width 0.1143)
		(layer "In11.Cu")
		(net "P5E_CPU1_P1_RX_DN<12>")
	)
	(arc
		(start 108.539788 -278.440642)
		(mid 108.695716 -278.13635)
		(end 108.539788 -277.832058)
		(width 0.1143)
		(layer "In11.Cu")
		(net "P5E_CPU1_P1_RX_DN<12>")
	)
	(arc
		(start 107.531662 -276.172676)
		(mid 107.515826 -276.160759)
		(end 107.50042 -276.148292)
		(width 0.1143)
		(layer "In11.Cu")
		(net "P5E_CPU1_P1_RX_DN<12>")
	)
	(arc
		(start 107.058968 -275.360892)
		(mid 106.906981 -275.204384)
		(end 106.825542 -275.00199)
		(width 0.1143)
		(layer "In11.Cu")
		(net "P5E_CPU1_P1_RX_DN<12>")
	)
	(arc
		(start 105.185972 -363.795564)
		(mid 105.343636 -363.543952)
		(end 105.56494 -363.345984)
		(width 0.14224)
		(layer "In11.Cu")
		(net "P5E_CPU1_P1_RX_DN<12>")
	)
	(arc
		(start 108.534454 -283.304488)
		(mid 108.695955 -282.999664)
		(end 108.539788 -282.692094)
		(width 0.1143)
		(layer "In11.Cu")
		(net "P5E_CPU1_P1_RX_DN<12>")
	)
	(arc
		(start 107.287568 -275.732494)
		(mid 107.286228 -275.719444)
		(end 107.28579 -275.706332)
		(width 0.1143)
		(layer "In11.Cu")
		(net "P5E_CPU1_P1_RX_DN<12>")
	)
	(arc
		(start 108.539788 -284.92069)
		(mid 108.695716 -284.616398)
		(end 108.539788 -284.312106)
		(width 0.1143)
		(layer "In11.Cu")
		(net "P5E_CPU1_P1_RX_DN<12>")
	)
	(arc
		(start 95.186246 -382.10617)
		(mid 95.218548 -381.876709)
		(end 95.313246 -381.665226)
		(width 0.14224)
		(layer "In11.Cu")
		(net "P5E_CPU1_P1_RX_DN<12>")
	)
	(arc
		(start 108.541566 -288.15919)
		(mid 108.654973 -288.026301)
		(end 108.695744 -287.856422)
		(width 0.1143)
		(layer "In11.Cu")
		(net "P5E_CPU1_P1_RX_DN<12>")
	)
	(arc
		(start 108.539788 -281.680666)
		(mid 108.695716 -281.376374)
		(end 108.539788 -281.072082)
		(width 0.1143)
		(layer "In11.Cu")
		(net "P5E_CPU1_P1_RX_DN<12>")
	)
	(arc
		(start 108.469176 -292.371272)
		(mid 108.226353 -291.873938)
		(end 108.524294 -291.407596)
		(width 0.1143)
		(layer "In11.Cu")
		(net "P5E_CPU1_P1_RX_DN<12>")
	)
	(arc
		(start 108.695744 -286.23641)
		(mid 108.654489 -286.065439)
		(end 108.539788 -285.932118)
		(width 0.1143)
		(layer "In11.Cu")
		(net "P5E_CPU1_P1_RX_DN<12>")
	)
	(arc
		(start 103.100124 -369.296442)
		(mid 103.107761 -369.282516)
		(end 103.113586 -369.26774)
		(width 0.14224)
		(layer "In11.Cu")
		(net "P5E_CPU1_P1_RX_DN<12>")
	)
	(arc
		(start 108.468922 -293.990776)
		(mid 108.225595 -293.52621)
		(end 108.468922 -293.061644)
		(width 0.1143)
		(layer "In11.Cu")
		(net "P5E_CPU1_P1_RX_DN<12>")
	)
	(arc
		(start 108.22559 -277.326344)
		(mid 108.184041 -277.154922)
		(end 108.068618 -277.021544)
		(width 0.1143)
		(layer "In11.Cu")
		(net "P5E_CPU1_P1_RX_DN<12>")
	)
	(arc
		(start 107.28579 -275.706332)
		(mid 107.241719 -275.536796)
		(end 107.129834 -275.40204)
		(width 0.1143)
		(layer "In11.Cu")
		(net "P5E_CPU1_P1_RX_DN<12>")
	)
	(arc
		(start 107.755944 -276.516338)
		(mid 107.714832 -276.345706)
		(end 107.600496 -276.212554)
		(width 0.1143)
		(layer "In11.Cu")
		(net "P5E_CPU1_P1_RX_DN<12>")
	)
	(arc
		(start 106.825542 -275.00199)
		(mid 106.823519 -274.99058)
		(end 106.821732 -274.97913)
		(width 0.1143)
		(layer "In11.Cu")
		(net "P5E_CPU1_P1_RX_DN<12>")
	)
	(arc
		(start 108.539788 -293.020496)
		(mid 108.695716 -292.716204)
		(end 108.539788 -292.411912)
		(width 0.1143)
		(layer "In11.Cu")
		(net "P5E_CPU1_P1_RX_DN<12>")
	)
	(arc
		(start 108.468922 -277.79091)
		(mid 108.290109 -277.58856)
		(end 108.22559 -277.326344)
		(width 0.1143)
		(layer "In11.Cu")
		(net "P5E_CPU1_P1_RX_DN<12>")
	)
	(arc
		(start 108.539788 -280.060654)
		(mid 108.695716 -279.756362)
		(end 108.539788 -279.45207)
		(width 0.1143)
		(layer "In11.Cu")
		(net "P5E_CPU1_P1_RX_DN<12>")
	)
	(arc
		(start 108.541566 -286.539178)
		(mid 108.654973 -286.406289)
		(end 108.695744 -286.23641)
		(width 0.1143)
		(layer "In11.Cu")
		(net "P5E_CPU1_P1_RX_DN<12>")
	)
	(arc
		(start 108.695744 -287.856422)
		(mid 108.654489 -287.685451)
		(end 108.539788 -287.55213)
		(width 0.1143)
		(layer "In11.Cu")
		(net "P5E_CPU1_P1_RX_DN<12>")
	)
	(arc
		(start 108.468922 -284.270958)
		(mid 108.225595 -283.806392)
		(end 108.468922 -283.341826)
		(width 0.1143)
		(layer "In11.Cu")
		(net "P5E_CPU1_P1_RX_DN<12>")
	)
	(arc
		(start 108.468922 -278.48179)
		(mid 108.469303 -278.481536)
		(end 108.469684 -278.481282)
		(width 0.1143)
		(layer "In11.Cu")
		(net "P5E_CPU1_P1_RX_DN<12>")
	)
	(arc
		(start 124.362464 -350.786192)
		(mid 125.287691 -349.937185)
		(end 125.913388 -348.848426)
		(width 0.14224)
		(layer "In11.Cu")
		(net "P5E_CPU1_P1_RX_DN<12>")
	)
	(arc
		(start 108.468922 -285.89097)
		(mid 108.225595 -285.426404)
		(end 108.468922 -284.961838)
		(width 0.1143)
		(layer "In11.Cu")
		(net "P5E_CPU1_P1_RX_DN<12>")
	)
	(arc
		(start 107.999022 -276.980904)
		(mid 107.820209 -276.778554)
		(end 107.75569 -276.516338)
		(width 0.1143)
		(layer "In11.Cu")
		(net "P5E_CPU1_P1_RX_DN<12>")
	)
	(arc
		(start 107.50042 -276.148292)
		(mid 107.358899 -275.958359)
		(end 107.287568 -275.732494)
		(width 0.1143)
		(layer "In11.Cu")
		(net "P5E_CPU1_P1_RX_DN<12>")
	)
	(arc
		(start 108.575348 -289.751262)
		(mid 108.694989 -289.453426)
		(end 108.540042 -289.172396)
		(width 0.1143)
		(layer "In11.Cu")
		(net "P5E_CPU1_P1_RX_DN<12>")
	)
	(arc
		(start 108.22559 -295.146222)
		(mid 108.290105 -294.884003)
		(end 108.468922 -294.681656)
		(width 0.1143)
		(layer "In11.Cu")
		(net "P5E_CPU1_P1_RX_DN<12>")
	)
	(arc
		(start 108.46054 -290.75507)
		(mid 108.218617 -290.295356)
		(end 108.453936 -289.832288)
		(width 0.1143)
		(layer "In11.Cu")
		(net "P5E_CPU1_P1_RX_DN<12>")
	)
	(arc
		(start 108.468922 -281.030934)
		(mid 108.225595 -280.566368)
		(end 108.468922 -280.101802)
		(width 0.1143)
		(layer "In11.Cu")
		(net "P5E_CPU1_P1_RX_DN<12>")
	)
	(arc
		(start 108.471462 -287.512506)
		(mid 108.225574 -287.047712)
		(end 108.468922 -286.581596)
		(width 0.1143)
		(layer "In11.Cu")
		(net "P5E_CPU1_P1_RX_DN<12>")
	)
	(arc
		(start 108.538518 -278.441404)
		(mid 108.539026 -278.441023)
		(end 108.539534 -278.440642)
		(width 0.1143)
		(layer "In11.Cu")
		(net "P5E_CPU1_P1_RX_DN<12>")
	)
	(arc
		(start 108.542836 -291.398452)
		(mid 108.698435 -291.104169)
		(end 108.547154 -290.807648)
		(width 0.1143)
		(layer "In11.Cu")
		(net "P5E_CPU1_P1_RX_DN<12>")
	)
	(arc
		(start 108.468922 -289.13074)
		(mid 108.225595 -288.666174)
		(end 108.468922 -288.201608)
		(width 0.1143)
		(layer "In11.Cu")
		(net "P5E_CPU1_P1_RX_DN<12>")
	)
	(arc
		(start 108.539788 -294.640508)
		(mid 108.695716 -294.336216)
		(end 108.539788 -294.031924)
		(width 0.1143)
		(layer "In11.Cu")
		(net "P5E_CPU1_P1_RX_DN<12>")
	)
	(arc
		(start 108.468922 -279.410922)
		(mid 108.225595 -278.946356)
		(end 108.468922 -278.48179)
		(width 0.1143)
		(layer "In11.Cu")
		(net "P5E_CPU1_P1_RX_DN<12>")
	)
	(arc
		(start 108.468922 -282.650946)
		(mid 108.225595 -282.18638)
		(end 108.468922 -281.721814)
		(width 0.1143)
		(layer "In11.Cu")
		(net "P5E_CPU1_P1_RX_DN<12>")
	)
	(segment
		(start 106.907838 -279.490424)
		(end 106.440986 -279.756362)
		(width 0.12954)
		(layer "F.Cu")
		(net "P5E_CPU1_P1_RX_DN<11>")
	)
	(segment
		(start 92.99829 -385.31038)
		(end 93.51899 -385.31038)
		(width 0.127)
		(layer "F.Cu")
		(net "P5E_CPU1_P1_RX_DN<11>")
	)
	(segment
		(start 107.57154 -292.395656)
		(end 107.570524 -292.395148)
		(width 0.1143)
		(layer "In11.Cu")
		(net "P5E_CPU1_P1_RX_DN<11>")
	)
	(segment
		(start 93.98635 -383.93116)
		(end 93.98635 -381.98425)
		(width 0.14224)
		(layer "In11.Cu")
		(net "P5E_CPU1_P1_RX_DN<11>")
	)
	(segment
		(start 107.531662 -283.340048)
		(end 107.567984 -283.318966)
		(width 0.1143)
		(layer "In11.Cu")
		(net "P5E_CPU1_P1_RX_DN<11>")
	)
	(segment
		(start 107.059476 -295.4909)
		(end 107.126024 -295.452546)
		(width 0.1143)
		(layer "In11.Cu")
		(net "P5E_CPU1_P1_RX_DN<11>")
	)
	(segment
		(start 107.570016 -294.014906)
		(end 107.568746 -294.014144)
		(width 0.1143)
		(layer "In11.Cu")
		(net "P5E_CPU1_P1_RX_DN<11>")
	)
	(segment
		(start 107.57662 -290.778438)
		(end 107.57408 -290.777168)
		(width 0.1143)
		(layer "In11.Cu")
		(net "P5E_CPU1_P1_RX_DN<11>")
	)
	(segment
		(start 93.51899 -385.31038)
		(end 93.872304 -385.405376)
		(width 0.14224)
		(layer "In11.Cu")
		(net "P5E_CPU1_P1_RX_DN<11>")
	)
	(segment
		(start 94.918022 -379.7808)
		(end 94.850966 -379.598936)
		(width 0.14224)
		(layer "In11.Cu")
		(net "P5E_CPU1_P1_RX_DN<11>")
	)
	(segment
		(start 107.57408 -294.017192)
		(end 107.572556 -294.016176)
		(width 0.1143)
		(layer "In11.Cu")
		(net "P5E_CPU1_P1_RX_DN<11>")
	)
	(segment
		(start 107.57408 -292.39718)
		(end 107.573318 -292.396672)
		(width 0.1143)
		(layer "In11.Cu")
		(net "P5E_CPU1_P1_RX_DN<11>")
	)
	(segment
		(start 107.599734 -281.072082)
		(end 107.57281 -281.056588)
		(width 0.1143)
		(layer "In11.Cu")
		(net "P5E_CPU1_P1_RX_DN<11>")
	)
	(segment
		(start 107.570016 -285.9151)
		(end 107.568746 -285.914338)
		(width 0.1143)
		(layer "In11.Cu")
		(net "P5E_CPU1_P1_RX_DN<11>")
	)
	(segment
		(start 107.573318 -292.396672)
		(end 107.572302 -292.396164)
		(width 0.1143)
		(layer "In11.Cu")
		(net "P5E_CPU1_P1_RX_DN<11>")
	)
	(segment
		(start 99.701604 -368.346482)
		(end 99.820984 -367.967006)
		(width 0.14224)
		(layer "In11.Cu")
		(net "P5E_CPU1_P1_RX_DN<11>")
	)
	(segment
		(start 107.289346 -287.080706)
		(end 107.289092 -287.079436)
		(width 0.1143)
		(layer "In11.Cu")
		(net "P5E_CPU1_P1_RX_DN<11>")
	)
	(segment
		(start 107.572302 -290.776152)
		(end 107.57154 -290.775644)
		(width 0.1143)
		(layer "In11.Cu")
		(net "P5E_CPU1_P1_RX_DN<11>")
	)
	(segment
		(start 107.56646 -281.69997)
		(end 107.568746 -281.698446)
		(width 0.1143)
		(layer "In11.Cu")
		(net "P5E_CPU1_P1_RX_DN<11>")
	)
	(segment
		(start 107.589066 -289.786568)
		(end 107.589828 -289.78606)
		(width 0.1143)
		(layer "In11.Cu")
		(net "P5E_CPU1_P1_RX_DN<11>")
	)
	(segment
		(start 107.589828 -291.406072)
		(end 107.599734 -291.400484)
		(width 0.1143)
		(layer "In11.Cu")
		(net "P5E_CPU1_P1_RX_DN<11>")
	)
	(segment
		(start 107.570016 -284.295088)
		(end 107.568746 -284.294326)
		(width 0.1143)
		(layer "In11.Cu")
		(net "P5E_CPU1_P1_RX_DN<11>")
	)
	(segment
		(start 93.872304 -385.405376)
		(end 93.872812 -385.404868)
		(width 0.14224)
		(layer "In11.Cu")
		(net "P5E_CPU1_P1_RX_DN<11>")
	)
	(segment
		(start 107.56773 -289.799014)
		(end 107.567984 -289.79876)
		(width 0.1143)
		(layer "In11.Cu")
		(net "P5E_CPU1_P1_RX_DN<11>")
	)
	(segment
		(start 107.57154 -290.775644)
		(end 107.570524 -290.775136)
		(width 0.1143)
		(layer "In11.Cu")
		(net "P5E_CPU1_P1_RX_DN<11>")
	)
	(segment
		(start 107.570016 -283.317696)
		(end 107.599734 -283.300678)
		(width 0.1143)
		(layer "In11.Cu")
		(net "P5E_CPU1_P1_RX_DN<11>")
	)
	(segment
		(start 107.059984 -296.538396)
		(end 107.059984 -296.477182)
		(width 0.1143)
		(layer "In11.Cu")
		(net "P5E_CPU1_P1_RX_DN<11>")
	)
	(segment
		(start 107.567984 -288.178748)
		(end 107.601512 -288.15919)
		(width 0.1143)
		(layer "In11.Cu")
		(net "P5E_CPU1_P1_RX_DN<11>")
	)
	(segment
		(start 107.529122 -282.6512)
		(end 107.501182 -282.631134)
		(width 0.1143)
		(layer "In11.Cu")
		(net "P5E_CPU1_P1_RX_DN<11>")
	)
	(segment
		(start 95.685102 -378.120148)
		(end 95.684848 -378.120148)
		(width 0.14224)
		(layer "In11.Cu")
		(net "P5E_CPU1_P1_RX_DN<11>")
	)
	(segment
		(start 107.562142 -281.050492)
		(end 107.558586 -281.047952)
		(width 0.1143)
		(layer "In11.Cu")
		(net "P5E_CPU1_P1_RX_DN<11>")
	)
	(segment
		(start 107.014264 -296.584116)
		(end 107.059984 -296.538396)
		(width 0.1143)
		(layer "In11.Cu")
		(net "P5E_CPU1_P1_RX_DN<11>")
	)
	(segment
		(start 107.043728 -295.50233)
		(end 107.059222 -295.491154)
		(width 0.1143)
		(layer "In11.Cu")
		(net "P5E_CPU1_P1_RX_DN<11>")
	)
	(segment
		(start 95.029782 -379.211078)
		(end 95.212154 -379.144276)
		(width 0.14224)
		(layer "In11.Cu")
		(net "P5E_CPU1_P1_RX_DN<11>")
	)
	(segment
		(start 127.359918 -342.063832)
		(end 127.359918 -339.387688)
		(width 0.14224)
		(layer "In11.Cu")
		(net "P5E_CPU1_P1_RX_DN<11>")
	)
	(segment
		(start 107.570016 -281.055064)
		(end 107.568746 -281.054302)
		(width 0.1143)
		(layer "In11.Cu")
		(net "P5E_CPU1_P1_RX_DN<11>")
	)
	(segment
		(start 107.589066 -291.40658)
		(end 107.589828 -291.406072)
		(width 0.1143)
		(layer "In11.Cu")
		(net "P5E_CPU1_P1_RX_DN<11>")
	)
	(segment
		(start 107.568746 -290.77412)
		(end 107.567984 -290.773612)
		(width 0.1143)
		(layer "In11.Cu")
		(net "P5E_CPU1_P1_RX_DN<11>")
	)
	(segment
		(start 107.599734 -287.55213)
		(end 107.593384 -287.548574)
		(width 0.1143)
		(layer "In11.Cu")
		(net "P5E_CPU1_P1_RX_DN<11>")
	)
	(segment
		(start 107.568746 -284.93847)
		(end 107.570016 -284.937708)
		(width 0.1143)
		(layer "In11.Cu")
		(net "P5E_CPU1_P1_RX_DN<11>")
	)
	(segment
		(start 95.50273 -378.187204)
		(end 95.685102 -378.120148)
		(width 0.14224)
		(layer "In11.Cu")
		(net "P5E_CPU1_P1_RX_DN<11>")
	)
	(segment
		(start 107.572556 -294.016176)
		(end 107.570016 -294.014906)
		(width 0.1143)
		(layer "In11.Cu")
		(net "P5E_CPU1_P1_RX_DN<11>")
	)
	(segment
		(start 107.568746 -281.054302)
		(end 107.567984 -281.053794)
		(width 0.1143)
		(layer "In11.Cu")
		(net "P5E_CPU1_P1_RX_DN<11>")
	)
	(segment
		(start 107.573318 -290.77666)
		(end 107.572302 -290.776152)
		(width 0.1143)
		(layer "In11.Cu")
		(net "P5E_CPU1_P1_RX_DN<11>")
	)
	(segment
		(start 107.599734 -289.171888)
		(end 107.55503 -289.14598)
		(width 0.1143)
		(layer "In11.Cu")
		(net "P5E_CPU1_P1_RX_DN<11>")
	)
	(segment
		(start 127.359918 -339.387688)
		(end 125.202188 -327.378568)
		(width 0.14224)
		(layer "In11.Cu")
		(net "P5E_CPU1_P1_RX_DN<11>")
	)
	(segment
		(start 107.589828 -289.78606)
		(end 107.599734 -289.780472)
		(width 0.1143)
		(layer "In11.Cu")
		(net "P5E_CPU1_P1_RX_DN<11>")
	)
	(segment
		(start 94.739206 -380.167896)
		(end 94.917768 -379.7808)
		(width 0.14224)
		(layer "In11.Cu")
		(net "P5E_CPU1_P1_RX_DN<11>")
	)
	(segment
		(start 107.570524 -292.395148)
		(end 107.569762 -292.39464)
		(width 0.1143)
		(layer "In11.Cu")
		(net "P5E_CPU1_P1_RX_DN<11>")
	)
	(segment
		(start 107.568746 -285.914338)
		(end 107.567984 -285.91383)
		(width 0.1143)
		(layer "In11.Cu")
		(net "P5E_CPU1_P1_RX_DN<11>")
	)
	(segment
		(start 107.568746 -294.014144)
		(end 107.567984 -294.013636)
		(width 0.1143)
		(layer "In11.Cu")
		(net "P5E_CPU1_P1_RX_DN<11>")
	)
	(segment
		(start 94.445074 -380.804928)
		(end 94.378018 -380.62281)
		(width 0.14224)
		(layer "In11.Cu")
		(net "P5E_CPU1_P1_RX_DN<11>")
	)
	(segment
		(start 107.568746 -292.394132)
		(end 107.567984 -292.393624)
		(width 0.1143)
		(layer "In11.Cu")
		(net "P5E_CPU1_P1_RX_DN<11>")
	)
	(segment
		(start 107.570016 -281.697684)
		(end 107.599734 -281.680666)
		(width 0.1143)
		(layer "In11.Cu")
		(net "P5E_CPU1_P1_RX_DN<11>")
	)
	(segment
		(start 107.567984 -285.91383)
		(end 107.531662 -285.892748)
		(width 0.1143)
		(layer "In11.Cu")
		(net "P5E_CPU1_P1_RX_DN<11>")
	)
	(segment
		(start 107.57916 -292.399974)
		(end 107.57662 -292.398704)
		(width 0.1143)
		(layer "In11.Cu")
		(net "P5E_CPU1_P1_RX_DN<11>")
	)
	(segment
		(start 107.56519 -282.672028)
		(end 107.529122 -282.6512)
		(width 0.1143)
		(layer "In11.Cu")
		(net "P5E_CPU1_P1_RX_DN<11>")
	)
	(segment
		(start 107.014264 -296.612564)
		(end 107.014264 -296.584116)
		(width 0.1143)
		(layer "In11.Cu")
		(net "P5E_CPU1_P1_RX_DN<11>")
	)
	(segment
		(start 94.917768 -379.7808)
		(end 94.918022 -379.7808)
		(width 0.14224)
		(layer "In11.Cu")
		(net "P5E_CPU1_P1_RX_DN<11>")
	)
	(segment
		(start 94.556834 -380.235206)
		(end 94.739206 -380.16815)
		(width 0.14224)
		(layer "In11.Cu")
		(net "P5E_CPU1_P1_RX_DN<11>")
	)
	(segment
		(start 107.567984 -293.038784)
		(end 107.599734 -293.020496)
		(width 0.1143)
		(layer "In11.Cu")
		(net "P5E_CPU1_P1_RX_DN<11>")
	)
	(segment
		(start 125.202188 -327.378568)
		(end 122.501914 -322.211954)
		(width 0.14224)
		(layer "In11.Cu")
		(net "P5E_CPU1_P1_RX_DN<11>")
	)
	(segment
		(start 106.81589 -295.988232)
		(end 106.81589 -295.946576)
		(width 0.1143)
		(layer "In11.Cu")
		(net "P5E_CPU1_P1_RX_DN<11>")
	)
	(segment
		(start 107.599734 -285.932118)
		(end 107.57281 -285.916624)
		(width 0.1143)
		(layer "In11.Cu")
		(net "P5E_CPU1_P1_RX_DN<11>")
	)
	(segment
		(start 107.569762 -290.774628)
		(end 107.568746 -290.77412)
		(width 0.1143)
		(layer "In11.Cu")
		(net "P5E_CPU1_P1_RX_DN<11>")
	)
	(segment
		(start 94.850966 -379.598936)
		(end 95.029782 -379.211078)
		(width 0.14224)
		(layer "In11.Cu")
		(net "P5E_CPU1_P1_RX_DN<11>")
	)
	(segment
		(start 95.323914 -378.575062)
		(end 95.50273 -378.187204)
		(width 0.14224)
		(layer "In11.Cu")
		(net "P5E_CPU1_P1_RX_DN<11>")
	)
	(segment
		(start 107.57281 -281.056588)
		(end 107.57154 -281.055826)
		(width 0.1143)
		(layer "In11.Cu")
		(net "P5E_CPU1_P1_RX_DN<11>")
	)
	(segment
		(start 93.677486 -384.84683)
		(end 93.682312 -384.234944)
		(width 0.14224)
		(layer "In11.Cu")
		(net "P5E_CPU1_P1_RX_DN<11>")
	)
	(segment
		(start 107.059222 -295.491154)
		(end 107.059476 -295.4909)
		(width 0.1143)
		(layer "In11.Cu")
		(net "P5E_CPU1_P1_RX_DN<11>")
	)
	(segment
		(start 107.558586 -281.047952)
		(end 107.557316 -281.04719)
		(width 0.1143)
		(layer "In11.Cu")
		(net "P5E_CPU1_P1_RX_DN<11>")
	)
	(segment
		(start 107.570016 -282.675076)
		(end 107.568746 -282.674314)
		(width 0.1143)
		(layer "In11.Cu")
		(net "P5E_CPU1_P1_RX_DN<11>")
	)
	(segment
		(start 107.567984 -289.79876)
		(end 107.589066 -289.786568)
		(width 0.1143)
		(layer "In11.Cu")
		(net "P5E_CPU1_P1_RX_DN<11>")
	)
	(segment
		(start 107.567984 -281.053794)
		(end 107.562142 -281.050492)
		(width 0.1143)
		(layer "In11.Cu")
		(net "P5E_CPU1_P1_RX_DN<11>")
	)
	(segment
		(start 107.57281 -284.296612)
		(end 107.57154 -284.29585)
		(width 0.1143)
		(layer "In11.Cu")
		(net "P5E_CPU1_P1_RX_DN<11>")
	)
	(segment
		(start 107.022392 -296.387012)
		(end 106.951526 -296.316146)
		(width 0.1143)
		(layer "In11.Cu")
		(net "P5E_CPU1_P1_RX_DN<11>")
	)
	(segment
		(start 100.04679 -367.576862)
		(end 103.507032 -363.834934)
		(width 0.14224)
		(layer "In11.Cu")
		(net "P5E_CPU1_P1_RX_DN<11>")
	)
	(segment
		(start 107.568746 -284.294326)
		(end 107.567984 -284.293818)
		(width 0.1143)
		(layer "In11.Cu")
		(net "P5E_CPU1_P1_RX_DN<11>")
	)
	(segment
		(start 107.599734 -294.031924)
		(end 107.57408 -294.017192)
		(width 0.1143)
		(layer "In11.Cu")
		(net "P5E_CPU1_P1_RX_DN<11>")
	)
	(segment
		(start 107.57154 -281.055826)
		(end 107.570016 -281.055064)
		(width 0.1143)
		(layer "In11.Cu")
		(net "P5E_CPU1_P1_RX_DN<11>")
	)
	(segment
		(start 107.570016 -294.657526)
		(end 107.599734 -294.640508)
		(width 0.1143)
		(layer "In11.Cu")
		(net "P5E_CPU1_P1_RX_DN<11>")
	)
	(segment
		(start 107.501182 -281.741626)
		(end 107.529122 -281.72156)
		(width 0.1143)
		(layer "In11.Cu")
		(net "P5E_CPU1_P1_RX_DN<11>")
	)
	(segment
		(start 107.57662 -292.398704)
		(end 107.57408 -292.39718)
		(width 0.1143)
		(layer "In11.Cu")
		(net "P5E_CPU1_P1_RX_DN<11>")
	)
	(segment
		(start 107.567984 -284.938978)
		(end 107.568746 -284.93847)
		(width 0.1143)
		(layer "In11.Cu")
		(net "P5E_CPU1_P1_RX_DN<11>")
	)
	(segment
		(start 107.534456 -286.578294)
		(end 107.601512 -286.539178)
		(width 0.1143)
		(layer "In11.Cu")
		(net "P5E_CPU1_P1_RX_DN<11>")
	)
	(segment
		(start 107.531662 -284.96006)
		(end 107.567984 -284.938978)
		(width 0.1143)
		(layer "In11.Cu")
		(net "P5E_CPU1_P1_RX_DN<11>")
	)
	(segment
		(start 104.809544 -362.722668)
		(end 123.619514 -350.154494)
		(width 0.14224)
		(layer "In11.Cu")
		(net "P5E_CPU1_P1_RX_DN<11>")
	)
	(segment
		(start 107.57281 -282.6766)
		(end 107.57154 -282.675838)
		(width 0.1143)
		(layer "In11.Cu")
		(net "P5E_CPU1_P1_RX_DN<11>")
	)
	(segment
		(start 107.529122 -281.72156)
		(end 107.56646 -281.69997)
		(width 0.1143)
		(layer "In11.Cu")
		(net "P5E_CPU1_P1_RX_DN<11>")
	)
	(segment
		(start 107.599734 -284.312106)
		(end 107.57281 -284.296612)
		(width 0.1143)
		(layer "In11.Cu")
		(net "P5E_CPU1_P1_RX_DN<11>")
	)
	(segment
		(start 107.014264 -298.428156)
		(end 107.014264 -296.612564)
		(width 0.14224)
		(layer "In11.Cu")
		(net "P5E_CPU1_P1_RX_DN<11>")
	)
	(segment
		(start 93.994478 -385.334764)
		(end 93.994478 -385.163822)
		(width 0.14224)
		(layer "In11.Cu")
		(net "P5E_CPU1_P1_RX_DN<11>")
	)
	(segment
		(start 93.872812 -385.404868)
		(end 93.994478 -385.334764)
		(width 0.14224)
		(layer "In11.Cu")
		(net "P5E_CPU1_P1_RX_DN<11>")
	)
	(segment
		(start 107.570524 -290.775136)
		(end 107.569762 -290.774628)
		(width 0.1143)
		(layer "In11.Cu")
		(net "P5E_CPU1_P1_RX_DN<11>")
	)
	(segment
		(start 107.567984 -291.418772)
		(end 107.589066 -291.40658)
		(width 0.1143)
		(layer "In11.Cu")
		(net "P5E_CPU1_P1_RX_DN<11>")
	)
	(segment
		(start 107.568746 -281.698446)
		(end 107.570016 -281.697684)
		(width 0.1143)
		(layer "In11.Cu")
		(net "P5E_CPU1_P1_RX_DN<11>")
	)
	(segment
		(start 107.599734 -292.411912)
		(end 107.598972 -292.411404)
		(width 0.1143)
		(layer "In11.Cu")
		(net "P5E_CPU1_P1_RX_DN<11>")
	)
	(segment
		(start 109.794548 -305.140868)
		(end 107.014264 -298.428156)
		(width 0.14224)
		(layer "In11.Cu")
		(net "P5E_CPU1_P1_RX_DN<11>")
	)
	(segment
		(start 107.567984 -292.393624)
		(end 107.56773 -292.393624)
		(width 0.1143)
		(layer "In11.Cu")
		(net "P5E_CPU1_P1_RX_DN<11>")
	)
	(segment
		(start 93.682312 -384.234944)
		(end 93.98635 -383.93116)
		(width 0.14224)
		(layer "In11.Cu")
		(net "P5E_CPU1_P1_RX_DN<11>")
	)
	(segment
		(start 107.568746 -282.674314)
		(end 107.567984 -282.673806)
		(width 0.1143)
		(layer "In11.Cu")
		(net "P5E_CPU1_P1_RX_DN<11>")
	)
	(segment
		(start 107.568746 -294.658288)
		(end 107.570016 -294.657526)
		(width 0.1143)
		(layer "In11.Cu")
		(net "P5E_CPU1_P1_RX_DN<11>")
	)
	(segment
		(start 124.815092 -348.66072)
		(end 127.359918 -342.063832)
		(width 0.14224)
		(layer "In11.Cu")
		(net "P5E_CPU1_P1_RX_DN<11>")
	)
	(segment
		(start 94.739206 -380.16815)
		(end 94.739206 -380.167896)
		(width 0.14224)
		(layer "In11.Cu")
		(net "P5E_CPU1_P1_RX_DN<11>")
	)
	(segment
		(start 122.501914 -322.211954)
		(end 115.502944 -313.68365)
		(width 0.14224)
		(layer "In11.Cu")
		(net "P5E_CPU1_P1_RX_DN<11>")
	)
	(segment
		(start 107.569762 -292.39464)
		(end 107.568746 -292.394132)
		(width 0.1143)
		(layer "In11.Cu")
		(net "P5E_CPU1_P1_RX_DN<11>")
	)
	(segment
		(start 107.531662 -293.059866)
		(end 107.567984 -293.038784)
		(width 0.1143)
		(layer "In11.Cu")
		(net "P5E_CPU1_P1_RX_DN<11>")
	)
	(segment
		(start 107.599734 -290.7919)
		(end 107.57662 -290.778438)
		(width 0.1143)
		(layer "In11.Cu")
		(net "P5E_CPU1_P1_RX_DN<11>")
	)
	(segment
		(start 107.531662 -286.579818)
		(end 107.534456 -286.578294)
		(width 0.1143)
		(layer "In11.Cu")
		(net "P5E_CPU1_P1_RX_DN<11>")
	)
	(segment
		(start 107.57154 -284.29585)
		(end 107.570016 -284.295088)
		(width 0.1143)
		(layer "In11.Cu")
		(net "P5E_CPU1_P1_RX_DN<11>")
	)
	(segment
		(start 95.684848 -378.120148)
		(end 99.551744 -369.746276)
		(width 0.14224)
		(layer "In11.Cu")
		(net "P5E_CPU1_P1_RX_DN<11>")
	)
	(segment
		(start 107.57154 -282.675838)
		(end 107.570016 -282.675076)
		(width 0.1143)
		(layer "In11.Cu")
		(net "P5E_CPU1_P1_RX_DN<11>")
	)
	(segment
		(start 95.390716 -378.756926)
		(end 95.39097 -378.756926)
		(width 0.14224)
		(layer "In11.Cu")
		(net "P5E_CPU1_P1_RX_DN<11>")
	)
	(segment
		(start 107.570016 -284.937708)
		(end 107.599734 -284.92069)
		(width 0.1143)
		(layer "In11.Cu")
		(net "P5E_CPU1_P1_RX_DN<11>")
	)
	(segment
		(start 94.064582 -381.62865)
		(end 94.445074 -380.804928)
		(width 0.14224)
		(layer "In11.Cu")
		(net "P5E_CPU1_P1_RX_DN<11>")
	)
	(segment
		(start 99.656392 -369.27028)
		(end 99.656392 -368.641884)
		(width 0.14224)
		(layer "In11.Cu")
		(net "P5E_CPU1_P1_RX_DN<11>")
	)
	(segment
		(start 107.57408 -290.777168)
		(end 107.573318 -290.77666)
		(width 0.1143)
		(layer "In11.Cu")
		(net "P5E_CPU1_P1_RX_DN<11>")
	)
	(segment
		(start 107.57281 -285.916624)
		(end 107.57154 -285.915862)
		(width 0.1143)
		(layer "In11.Cu")
		(net "P5E_CPU1_P1_RX_DN<11>")
	)
	(segment
		(start 106.821732 -279.839166)
		(end 106.738928 -279.756362)
		(width 0.1143)
		(layer "In11.Cu")
		(net "P5E_CPU1_P1_RX_DN<11>")
	)
	(segment
		(start 107.572302 -292.396164)
		(end 107.57154 -292.395656)
		(width 0.1143)
		(layer "In11.Cu")
		(net "P5E_CPU1_P1_RX_DN<11>")
	)
	(segment
		(start 95.39097 -378.756926)
		(end 95.323914 -378.575062)
		(width 0.14224)
		(layer "In11.Cu")
		(net "P5E_CPU1_P1_RX_DN<11>")
	)
	(segment
		(start 107.567984 -282.673806)
		(end 107.56519 -282.672028)
		(width 0.1143)
		(layer "In11.Cu")
		(net "P5E_CPU1_P1_RX_DN<11>")
	)
	(segment
		(start 107.57154 -285.915862)
		(end 107.570016 -285.9151)
		(width 0.1143)
		(layer "In11.Cu")
		(net "P5E_CPU1_P1_RX_DN<11>")
	)
	(segment
		(start 107.567984 -290.773612)
		(end 107.56773 -290.773612)
		(width 0.1143)
		(layer "In11.Cu")
		(net "P5E_CPU1_P1_RX_DN<11>")
	)
	(segment
		(start 107.56773 -291.419026)
		(end 107.567984 -291.418772)
		(width 0.1143)
		(layer "In11.Cu")
		(net "P5E_CPU1_P1_RX_DN<11>")
	)
	(segment
		(start 95.2119 -379.144276)
		(end 95.390716 -378.756926)
		(width 0.14224)
		(layer "In11.Cu")
		(net "P5E_CPU1_P1_RX_DN<11>")
	)
	(segment
		(start 106.738928 -279.756362)
		(end 106.440986 -279.756362)
		(width 0.1143)
		(layer "In11.Cu")
		(net "P5E_CPU1_P1_RX_DN<11>")
	)
	(segment
		(start 107.126024 -280.260044)
		(end 107.058968 -280.220928)
		(width 0.1143)
		(layer "In11.Cu")
		(net "P5E_CPU1_P1_RX_DN<11>")
	)
	(segment
		(start 107.557316 -294.665654)
		(end 107.568746 -294.658288)
		(width 0.1143)
		(layer "In11.Cu")
		(net "P5E_CPU1_P1_RX_DN<11>")
	)
	(segment
		(start 115.502944 -313.68365)
		(end 109.794548 -305.140868)
		(width 0.14224)
		(layer "In11.Cu")
		(net "P5E_CPU1_P1_RX_DN<11>")
	)
	(segment
		(start 107.55503 -288.186368)
		(end 107.567984 -288.178748)
		(width 0.1143)
		(layer "In11.Cu")
		(net "P5E_CPU1_P1_RX_DN<11>")
	)
	(segment
		(start 93.994478 -385.163822)
		(end 93.677486 -384.84683)
		(width 0.14224)
		(layer "In11.Cu")
		(net "P5E_CPU1_P1_RX_DN<11>")
	)
	(segment
		(start 107.599734 -282.692094)
		(end 107.57281 -282.6766)
		(width 0.1143)
		(layer "In11.Cu")
		(net "P5E_CPU1_P1_RX_DN<11>")
	)
	(segment
		(start 94.378018 -380.62281)
		(end 94.556834 -380.235206)
		(width 0.14224)
		(layer "In11.Cu")
		(net "P5E_CPU1_P1_RX_DN<11>")
	)
	(segment
		(start 107.598972 -292.411404)
		(end 107.57916 -292.399974)
		(width 0.1143)
		(layer "In11.Cu")
		(net "P5E_CPU1_P1_RX_DN<11>")
	)
	(segment
		(start 107.567984 -283.318966)
		(end 107.568746 -283.318458)
		(width 0.1143)
		(layer "In11.Cu")
		(net "P5E_CPU1_P1_RX_DN<11>")
	)
	(segment
		(start 107.567984 -294.013636)
		(end 107.531662 -293.992554)
		(width 0.1143)
		(layer "In11.Cu")
		(net "P5E_CPU1_P1_RX_DN<11>")
	)
	(segment
		(start 107.568746 -283.318458)
		(end 107.570016 -283.317696)
		(width 0.1143)
		(layer "In11.Cu")
		(net "P5E_CPU1_P1_RX_DN<11>")
	)
	(segment
		(start 107.567984 -284.293818)
		(end 107.531662 -284.272736)
		(width 0.1143)
		(layer "In11.Cu")
		(net "P5E_CPU1_P1_RX_DN<11>")
	)
	(segment
		(start 95.212154 -379.144276)
		(end 95.2119 -379.144276)
		(width 0.14224)
		(layer "In11.Cu")
		(net "P5E_CPU1_P1_RX_DN<11>")
	)
	(arc
		(start 107.599734 -281.680666)
		(mid 107.755662 -281.376374)
		(end 107.599734 -281.072082)
		(width 0.1143)
		(layer "In11.Cu")
		(net "P5E_CPU1_P1_RX_DN<11>")
	)
	(arc
		(start 103.507032 -363.834934)
		(mid 104.125504 -363.240408)
		(end 104.809544 -362.722668)
		(width 0.14224)
		(layer "In11.Cu")
		(net "P5E_CPU1_P1_RX_DN<11>")
	)
	(arc
		(start 106.951526 -296.316146)
		(mid 106.851083 -296.165683)
		(end 106.81589 -295.988232)
		(width 0.1143)
		(layer "In11.Cu")
		(net "P5E_CPU1_P1_RX_DN<11>")
	)
	(arc
		(start 107.55503 -289.14598)
		(mid 107.278697 -288.666174)
		(end 107.55503 -288.186368)
		(width 0.1143)
		(layer "In11.Cu")
		(net "P5E_CPU1_P1_RX_DN<11>")
	)
	(arc
		(start 107.501182 -282.631134)
		(mid 107.273182 -282.18638)
		(end 107.501182 -281.741626)
		(width 0.1143)
		(layer "In11.Cu")
		(net "P5E_CPU1_P1_RX_DN<11>")
	)
	(arc
		(start 123.619514 -350.154494)
		(mid 124.332778 -349.500032)
		(end 124.815092 -348.66072)
		(width 0.14224)
		(layer "In11.Cu")
		(net "P5E_CPU1_P1_RX_DN<11>")
	)
	(arc
		(start 107.286806 -287.013904)
		(mid 107.354843 -286.775716)
		(end 107.5182 -286.58947)
		(width 0.1143)
		(layer "In11.Cu")
		(net "P5E_CPU1_P1_RX_DN<11>")
	)
	(arc
		(start 107.601512 -288.15919)
		(mid 107.714919 -288.026301)
		(end 107.75569 -287.856422)
		(width 0.1143)
		(layer "In11.Cu")
		(net "P5E_CPU1_P1_RX_DN<11>")
	)
	(arc
		(start 107.285536 -295.148)
		(mid 107.363822 -294.874389)
		(end 107.557316 -294.665654)
		(width 0.1143)
		(layer "In11.Cu")
		(net "P5E_CPU1_P1_RX_DN<11>")
	)
	(arc
		(start 107.516422 -284.970728)
		(mid 107.523998 -284.965332)
		(end 107.531662 -284.96006)
		(width 0.1143)
		(layer "In11.Cu")
		(net "P5E_CPU1_P1_RX_DN<11>")
	)
	(arc
		(start 107.517438 -284.26283)
		(mid 107.290055 -283.806392)
		(end 107.517438 -283.349954)
		(width 0.1143)
		(layer "In11.Cu")
		(net "P5E_CPU1_P1_RX_DN<11>")
	)
	(arc
		(start 107.75569 -286.23641)
		(mid 107.714435 -286.065439)
		(end 107.599734 -285.932118)
		(width 0.1143)
		(layer "In11.Cu")
		(net "P5E_CPU1_P1_RX_DN<11>")
	)
	(arc
		(start 107.599734 -289.780472)
		(mid 107.755662 -289.47618)
		(end 107.599734 -289.171888)
		(width 0.1143)
		(layer "In11.Cu")
		(net "P5E_CPU1_P1_RX_DN<11>")
	)
	(arc
		(start 107.56773 -292.393624)
		(mid 107.287303 -291.906388)
		(end 107.56773 -291.419026)
		(width 0.1143)
		(layer "In11.Cu")
		(net "P5E_CPU1_P1_RX_DN<11>")
	)
	(arc
		(start 107.599734 -293.020496)
		(mid 107.755662 -292.716204)
		(end 107.599734 -292.411912)
		(width 0.1143)
		(layer "In11.Cu")
		(net "P5E_CPU1_P1_RX_DN<11>")
	)
	(arc
		(start 107.593384 -287.548574)
		(mid 107.506499 -287.486907)
		(end 107.432348 -287.410398)
		(width 0.1143)
		(layer "In11.Cu")
		(net "P5E_CPU1_P1_RX_DN<11>")
	)
	(arc
		(start 107.601512 -286.539178)
		(mid 107.714919 -286.406289)
		(end 107.75569 -286.23641)
		(width 0.1143)
		(layer "In11.Cu")
		(net "P5E_CPU1_P1_RX_DN<11>")
	)
	(arc
		(start 107.599734 -284.92069)
		(mid 107.755662 -284.616398)
		(end 107.599734 -284.312106)
		(width 0.1143)
		(layer "In11.Cu")
		(net "P5E_CPU1_P1_RX_DN<11>")
	)
	(arc
		(start 107.599734 -294.640508)
		(mid 107.755662 -294.336216)
		(end 107.599734 -294.031924)
		(width 0.1143)
		(layer "In11.Cu")
		(net "P5E_CPU1_P1_RX_DN<11>")
	)
	(arc
		(start 107.599734 -291.400484)
		(mid 107.755662 -291.096192)
		(end 107.599734 -290.7919)
		(width 0.1143)
		(layer "In11.Cu")
		(net "P5E_CPU1_P1_RX_DN<11>")
	)
	(arc
		(start 107.058968 -280.220928)
		(mid 106.906981 -280.06442)
		(end 106.825542 -279.862026)
		(width 0.1143)
		(layer "In11.Cu")
		(net "P5E_CPU1_P1_RX_DN<11>")
	)
	(arc
		(start 107.432348 -287.410398)
		(mid 107.338536 -287.255234)
		(end 107.289346 -287.080706)
		(width 0.1143)
		(layer "In11.Cu")
		(net "P5E_CPU1_P1_RX_DN<11>")
	)
	(arc
		(start 107.557316 -281.04719)
		(mid 107.363712 -280.838386)
		(end 107.285536 -280.56459)
		(width 0.1143)
		(layer "In11.Cu")
		(net "P5E_CPU1_P1_RX_DN<11>")
	)
	(arc
		(start 107.285536 -280.56459)
		(mid 107.239666 -280.39457)
		(end 107.126024 -280.260044)
		(width 0.1143)
		(layer "In11.Cu")
		(net "P5E_CPU1_P1_RX_DN<11>")
	)
	(arc
		(start 107.56773 -290.773612)
		(mid 107.287303 -290.286376)
		(end 107.56773 -289.799014)
		(width 0.1143)
		(layer "In11.Cu")
		(net "P5E_CPU1_P1_RX_DN<11>")
	)
	(arc
		(start 107.531662 -293.992554)
		(mid 107.524513 -293.987654)
		(end 107.517438 -293.982648)
		(width 0.1143)
		(layer "In11.Cu")
		(net "P5E_CPU1_P1_RX_DN<11>")
	)
	(arc
		(start 107.516422 -285.88208)
		(mid 107.291251 -285.426404)
		(end 107.516422 -284.970728)
		(width 0.1143)
		(layer "In11.Cu")
		(net "P5E_CPU1_P1_RX_DN<11>")
	)
	(arc
		(start 106.825542 -279.862026)
		(mid 106.823519 -279.850616)
		(end 106.821732 -279.839166)
		(width 0.1143)
		(layer "In11.Cu")
		(net "P5E_CPU1_P1_RX_DN<11>")
	)
	(arc
		(start 107.531662 -284.272736)
		(mid 107.524513 -284.267836)
		(end 107.517438 -284.26283)
		(width 0.1143)
		(layer "In11.Cu")
		(net "P5E_CPU1_P1_RX_DN<11>")
	)
	(arc
		(start 107.517438 -293.982648)
		(mid 107.290055 -293.52621)
		(end 107.517438 -293.069772)
		(width 0.1143)
		(layer "In11.Cu")
		(net "P5E_CPU1_P1_RX_DN<11>")
	)
	(arc
		(start 99.656392 -368.641884)
		(mid 99.667714 -368.492455)
		(end 99.701604 -368.346482)
		(width 0.14224)
		(layer "In11.Cu")
		(net "P5E_CPU1_P1_RX_DN<11>")
	)
	(arc
		(start 107.531662 -285.892748)
		(mid 107.523998 -285.887477)
		(end 107.516422 -285.88208)
		(width 0.1143)
		(layer "In11.Cu")
		(net "P5E_CPU1_P1_RX_DN<11>")
	)
	(arc
		(start 107.517438 -293.069772)
		(mid 107.524512 -293.064765)
		(end 107.531662 -293.059866)
		(width 0.1143)
		(layer "In11.Cu")
		(net "P5E_CPU1_P1_RX_DN<11>")
	)
	(arc
		(start 107.289092 -287.079436)
		(mid 107.286356 -287.046726)
		(end 107.286806 -287.013904)
		(width 0.1143)
		(layer "In11.Cu")
		(net "P5E_CPU1_P1_RX_DN<11>")
	)
	(arc
		(start 107.75569 -287.856422)
		(mid 107.714435 -287.685451)
		(end 107.599734 -287.55213)
		(width 0.1143)
		(layer "In11.Cu")
		(net "P5E_CPU1_P1_RX_DN<11>")
	)
	(arc
		(start 107.126024 -295.452546)
		(mid 107.239679 -295.318026)
		(end 107.285536 -295.148)
		(width 0.1143)
		(layer "In11.Cu")
		(net "P5E_CPU1_P1_RX_DN<11>")
	)
	(arc
		(start 107.059984 -296.477182)
		(mid 107.050145 -296.428372)
		(end 107.022392 -296.387012)
		(width 0.1143)
		(layer "In11.Cu")
		(net "P5E_CPU1_P1_RX_DN<11>")
	)
	(arc
		(start 93.98635 -381.98425)
		(mid 94.006163 -381.802202)
		(end 94.064582 -381.62865)
		(width 0.14224)
		(layer "In11.Cu")
		(net "P5E_CPU1_P1_RX_DN<11>")
	)
	(arc
		(start 99.820984 -367.967006)
		(mid 99.912275 -367.759426)
		(end 100.04679 -367.576862)
		(width 0.14224)
		(layer "In11.Cu")
		(net "P5E_CPU1_P1_RX_DN<11>")
	)
	(arc
		(start 106.81589 -295.946576)
		(mid 106.87611 -295.696908)
		(end 107.043728 -295.50233)
		(width 0.1143)
		(layer "In11.Cu")
		(net "P5E_CPU1_P1_RX_DN<11>")
	)
	(arc
		(start 107.517438 -283.349954)
		(mid 107.524512 -283.344947)
		(end 107.531662 -283.340048)
		(width 0.1143)
		(layer "In11.Cu")
		(net "P5E_CPU1_P1_RX_DN<11>")
	)
	(arc
		(start 107.599734 -283.300678)
		(mid 107.755662 -282.996386)
		(end 107.599734 -282.692094)
		(width 0.1143)
		(layer "In11.Cu")
		(net "P5E_CPU1_P1_RX_DN<11>")
	)
	(arc
		(start 99.551744 -369.746276)
		(mid 99.629921 -369.513962)
		(end 99.656392 -369.27028)
		(width 0.14224)
		(layer "In11.Cu")
		(net "P5E_CPU1_P1_RX_DN<11>")
	)
	(arc
		(start 107.5182 -286.58947)
		(mid 107.524895 -286.584594)
		(end 107.531662 -286.579818)
		(width 0.1143)
		(layer "In11.Cu")
		(net "P5E_CPU1_P1_RX_DN<11>")
	)
	(segment
		(start 106.907838 -277.870412)
		(end 106.440986 -278.13635)
		(width 0.12954)
		(layer "F.Cu")
		(net "P5E_CPU1_P1_RX_DN<10>")
	)
	(segment
		(start 91.798394 -385.31038)
		(end 92.319094 -385.31038)
		(width 0.127)
		(layer "F.Cu")
		(net "P5E_CPU1_P1_RX_DN<10>")
	)
	(segment
		(start 105.916984 -298.21632)
		(end 105.916984 -296.286936)
		(width 0.14224)
		(layer "In11.Cu")
		(net "P5E_CPU1_P1_RX_DN<10>")
	)
	(segment
		(start 106.738928 -278.13635)
		(end 106.440986 -278.13635)
		(width 0.1143)
		(layer "In11.Cu")
		(net "P5E_CPU1_P1_RX_DN<10>")
	)
	(segment
		(start 106.589068 -288.201608)
		(end 106.628184 -288.178748)
		(width 0.1143)
		(layer "In11.Cu")
		(net "P5E_CPU1_P1_RX_DN<10>")
	)
	(segment
		(start 106.808778 -278.2062)
		(end 106.738928 -278.13635)
		(width 0.1143)
		(layer "In11.Cu")
		(net "P5E_CPU1_P1_RX_DN<10>")
	)
	(segment
		(start 106.589068 -281.721814)
		(end 106.658664 -281.681174)
		(width 0.1143)
		(layer "In11.Cu")
		(net "P5E_CPU1_P1_RX_DN<10>")
	)
	(segment
		(start 106.589068 -286.581596)
		(end 106.5911 -286.580072)
		(width 0.1143)
		(layer "In11.Cu")
		(net "P5E_CPU1_P1_RX_DN<10>")
	)
	(segment
		(start 106.160062 -279.267666)
		(end 106.162602 -279.266396)
		(width 0.1143)
		(layer "In11.Cu")
		(net "P5E_CPU1_P1_RX_DN<10>")
	)
	(segment
		(start 106.157014 -279.269444)
		(end 106.15803 -279.268936)
		(width 0.1143)
		(layer "In11.Cu")
		(net "P5E_CPU1_P1_RX_DN<10>")
	)
	(segment
		(start 92.786454 -378.27966)
		(end 92.786454 -373.74195)
		(width 0.14224)
		(layer "In11.Cu")
		(net "P5E_CPU1_P1_RX_DN<10>")
	)
	(segment
		(start 92.649294 -379.54458)
		(end 92.786454 -379.40742)
		(width 0.14224)
		(layer "In11.Cu")
		(net "P5E_CPU1_P1_RX_DN<10>")
	)
	(segment
		(start 106.589068 -283.341826)
		(end 106.658664 -283.301186)
		(width 0.1143)
		(layer "In11.Cu")
		(net "P5E_CPU1_P1_RX_DN<10>")
	)
	(segment
		(start 106.589068 -278.48179)
		(end 106.658664 -278.44115)
		(width 0.1143)
		(layer "In11.Cu")
		(net "P5E_CPU1_P1_RX_DN<10>")
	)
	(segment
		(start 106.158792 -279.268428)
		(end 106.160062 -279.267666)
		(width 0.1143)
		(layer "In11.Cu")
		(net "P5E_CPU1_P1_RX_DN<10>")
	)
	(segment
		(start 106.658664 -287.551622)
		(end 106.591608 -287.512506)
		(width 0.1143)
		(layer "In11.Cu")
		(net "P5E_CPU1_P1_RX_DN<10>")
	)
	(segment
		(start 106.658664 -294.031416)
		(end 106.589068 -293.990776)
		(width 0.1143)
		(layer "In11.Cu")
		(net "P5E_CPU1_P1_RX_DN<10>")
	)
	(segment
		(start 106.15803 -280.243788)
		(end 106.157014 -280.24328)
		(width 0.1143)
		(layer "In11.Cu")
		(net "P5E_CPU1_P1_RX_DN<10>")
	)
	(segment
		(start 106.658664 -290.791392)
		(end 106.589068 -290.750752)
		(width 0.1143)
		(layer "In11.Cu")
		(net "P5E_CPU1_P1_RX_DN<10>")
	)
	(segment
		(start 92.319094 -385.31038)
		(end 92.672408 -385.405376)
		(width 0.14224)
		(layer "In11.Cu")
		(net "P5E_CPU1_P1_RX_DN<10>")
	)
	(segment
		(start 92.863162 -373.502936)
		(end 97.24517 -367.411508)
		(width 0.14224)
		(layer "In11.Cu")
		(net "P5E_CPU1_P1_RX_DN<10>")
	)
	(segment
		(start 126.262384 -342.278208)
		(end 126.262638 -342.277954)
		(width 0.14224)
		(layer "In11.Cu")
		(net "P5E_CPU1_P1_RX_DN<10>")
	)
	(segment
		(start 106.095292 -295.585642)
		(end 106.191558 -295.489376)
		(width 0.1143)
		(layer "In11.Cu")
		(net "P5E_CPU1_P1_RX_DN<10>")
	)
	(segment
		(start 92.786454 -383.93116)
		(end 92.786454 -381.23622)
		(width 0.14224)
		(layer "In11.Cu")
		(net "P5E_CPU1_P1_RX_DN<10>")
	)
	(segment
		(start 106.162602 -279.266396)
		(end 106.18978 -279.250648)
		(width 0.1143)
		(layer "In11.Cu")
		(net "P5E_CPU1_P1_RX_DN<10>")
	)
	(segment
		(start 106.658664 -285.93161)
		(end 106.589068 -285.89097)
		(width 0.1143)
		(layer "In11.Cu")
		(net "P5E_CPU1_P1_RX_DN<10>")
	)
	(segment
		(start 92.672408 -385.405376)
		(end 92.672916 -385.404868)
		(width 0.14224)
		(layer "In11.Cu")
		(net "P5E_CPU1_P1_RX_DN<10>")
	)
	(segment
		(start 92.786454 -380.53518)
		(end 92.786454 -380.10846)
		(width 0.14224)
		(layer "In11.Cu")
		(net "P5E_CPU1_P1_RX_DN<10>")
	)
	(segment
		(start 124.60605 -330.266802)
		(end 124.605796 -330.266802)
		(width 0.14224)
		(layer "In11.Cu")
		(net "P5E_CPU1_P1_RX_DN<10>")
	)
	(segment
		(start 106.628184 -286.558736)
		(end 106.660696 -286.53994)
		(width 0.1143)
		(layer "In11.Cu")
		(net "P5E_CPU1_P1_RX_DN<10>")
	)
	(segment
		(start 126.262638 -339.485732)
		(end 124.60605 -330.266802)
		(width 0.14224)
		(layer "In11.Cu")
		(net "P5E_CPU1_P1_RX_DN<10>")
	)
	(segment
		(start 106.628184 -288.178748)
		(end 106.660696 -288.159952)
		(width 0.1143)
		(layer "In11.Cu")
		(net "P5E_CPU1_P1_RX_DN<10>")
	)
	(segment
		(start 92.47759 -384.84683)
		(end 92.482416 -384.234944)
		(width 0.14224)
		(layer "In11.Cu")
		(net "P5E_CPU1_P1_RX_DN<10>")
	)
	(segment
		(start 106.5911 -286.580072)
		(end 106.628184 -286.558736)
		(width 0.1143)
		(layer "In11.Cu")
		(net "P5E_CPU1_P1_RX_DN<10>")
	)
	(segment
		(start 106.658664 -289.17138)
		(end 106.589068 -289.13074)
		(width 0.1143)
		(layer "In11.Cu")
		(net "P5E_CPU1_P1_RX_DN<10>")
	)
	(segment
		(start 105.916984 -296.286936)
		(end 105.916984 -296.258488)
		(width 0.1143)
		(layer "In11.Cu")
		(net "P5E_CPU1_P1_RX_DN<10>")
	)
	(segment
		(start 92.649294 -380.67234)
		(end 92.786454 -380.53518)
		(width 0.14224)
		(layer "In11.Cu")
		(net "P5E_CPU1_P1_RX_DN<10>")
	)
	(segment
		(start 106.18978 -280.262076)
		(end 106.160062 -280.245058)
		(width 0.1143)
		(layer "In11.Cu")
		(net "P5E_CPU1_P1_RX_DN<10>")
	)
	(segment
		(start 105.962704 -296.212768)
		(end 105.962704 -295.90619)
		(width 0.1143)
		(layer "In11.Cu")
		(net "P5E_CPU1_P1_RX_DN<10>")
	)
	(segment
		(start 106.118914 -279.291796)
		(end 106.15549 -279.27046)
		(width 0.1143)
		(layer "In11.Cu")
		(net "P5E_CPU1_P1_RX_DN<10>")
	)
	(segment
		(start 106.158792 -280.244296)
		(end 106.15803 -280.243788)
		(width 0.1143)
		(layer "In11.Cu")
		(net "P5E_CPU1_P1_RX_DN<10>")
	)
	(segment
		(start 106.589068 -293.061644)
		(end 106.658664 -293.021004)
		(width 0.1143)
		(layer "In11.Cu")
		(net "P5E_CPU1_P1_RX_DN<10>")
	)
	(segment
		(start 126.262638 -342.277954)
		(end 126.262638 -339.485732)
		(width 0.14224)
		(layer "In11.Cu")
		(net "P5E_CPU1_P1_RX_DN<10>")
	)
	(segment
		(start 92.786454 -378.9807)
		(end 92.649294 -378.84354)
		(width 0.14224)
		(layer "In11.Cu")
		(net "P5E_CPU1_P1_RX_DN<10>")
	)
	(segment
		(start 123.921012 -348.346776)
		(end 126.262384 -342.278208)
		(width 0.14224)
		(layer "In11.Cu")
		(net "P5E_CPU1_P1_RX_DN<10>")
	)
	(segment
		(start 102.604824 -363.072934)
		(end 123.091448 -349.383096)
		(width 0.14224)
		(layer "In11.Cu")
		(net "P5E_CPU1_P1_RX_DN<10>")
	)
	(segment
		(start 92.786454 -379.40742)
		(end 92.786454 -378.9807)
		(width 0.14224)
		(layer "In11.Cu")
		(net "P5E_CPU1_P1_RX_DN<10>")
	)
	(segment
		(start 108.96854 -305.583336)
		(end 105.916984 -298.21632)
		(width 0.14224)
		(layer "In11.Cu")
		(net "P5E_CPU1_P1_RX_DN<10>")
	)
	(segment
		(start 106.603292 -294.673274)
		(end 106.658664 -294.641016)
		(width 0.1143)
		(layer "In11.Cu")
		(net "P5E_CPU1_P1_RX_DN<10>")
	)
	(segment
		(start 92.649294 -381.09906)
		(end 92.649294 -380.67234)
		(width 0.14224)
		(layer "In11.Cu")
		(net "P5E_CPU1_P1_RX_DN<10>")
	)
	(segment
		(start 106.589068 -289.82162)
		(end 106.658664 -289.78098)
		(width 0.1143)
		(layer "In11.Cu")
		(net "P5E_CPU1_P1_RX_DN<10>")
	)
	(segment
		(start 106.160062 -280.245058)
		(end 106.158792 -280.244296)
		(width 0.1143)
		(layer "In11.Cu")
		(net "P5E_CPU1_P1_RX_DN<10>")
	)
	(segment
		(start 106.658664 -292.411404)
		(end 106.589068 -292.370764)
		(width 0.1143)
		(layer "In11.Cu")
		(net "P5E_CPU1_P1_RX_DN<10>")
	)
	(segment
		(start 106.658664 -284.311598)
		(end 106.589068 -284.270958)
		(width 0.1143)
		(layer "In11.Cu")
		(net "P5E_CPU1_P1_RX_DN<10>")
	)
	(segment
		(start 92.786454 -380.10846)
		(end 92.649294 -379.9713)
		(width 0.14224)
		(layer "In11.Cu")
		(net "P5E_CPU1_P1_RX_DN<10>")
	)
	(segment
		(start 92.649294 -378.84354)
		(end 92.649294 -378.41682)
		(width 0.14224)
		(layer "In11.Cu")
		(net "P5E_CPU1_P1_RX_DN<10>")
	)
	(segment
		(start 121.71934 -322.728082)
		(end 114.75339 -314.240672)
		(width 0.14224)
		(layer "In11.Cu")
		(net "P5E_CPU1_P1_RX_DN<10>")
	)
	(segment
		(start 92.649294 -379.9713)
		(end 92.649294 -379.54458)
		(width 0.14224)
		(layer "In11.Cu")
		(net "P5E_CPU1_P1_RX_DN<10>")
	)
	(segment
		(start 124.605796 -330.266802)
		(end 124.054108 -327.19518)
		(width 0.14224)
		(layer "In11.Cu")
		(net "P5E_CPU1_P1_RX_DN<10>")
	)
	(segment
		(start 106.154474 -280.241756)
		(end 106.149648 -280.238962)
		(width 0.1143)
		(layer "In11.Cu")
		(net "P5E_CPU1_P1_RX_DN<10>")
	)
	(segment
		(start 92.482416 -384.234944)
		(end 92.786454 -383.93116)
		(width 0.14224)
		(layer "In11.Cu")
		(net "P5E_CPU1_P1_RX_DN<10>")
	)
	(segment
		(start 106.15549 -280.242264)
		(end 106.154474 -280.241756)
		(width 0.1143)
		(layer "In11.Cu")
		(net "P5E_CPU1_P1_RX_DN<10>")
	)
	(segment
		(start 106.658664 -282.691586)
		(end 106.589068 -282.650946)
		(width 0.1143)
		(layer "In11.Cu")
		(net "P5E_CPU1_P1_RX_DN<10>")
	)
	(segment
		(start 106.148124 -280.237946)
		(end 106.118914 -280.220928)
		(width 0.1143)
		(layer "In11.Cu")
		(net "P5E_CPU1_P1_RX_DN<10>")
	)
	(segment
		(start 106.157014 -280.24328)
		(end 106.15549 -280.242264)
		(width 0.1143)
		(layer "In11.Cu")
		(net "P5E_CPU1_P1_RX_DN<10>")
	)
	(segment
		(start 92.794582 -385.163822)
		(end 92.47759 -384.84683)
		(width 0.14224)
		(layer "In11.Cu")
		(net "P5E_CPU1_P1_RX_DN<10>")
	)
	(segment
		(start 106.15803 -279.268936)
		(end 106.158792 -279.268428)
		(width 0.1143)
		(layer "In11.Cu")
		(net "P5E_CPU1_P1_RX_DN<10>")
	)
	(segment
		(start 124.054108 -327.19518)
		(end 121.71934 -322.728082)
		(width 0.14224)
		(layer "In11.Cu")
		(net "P5E_CPU1_P1_RX_DN<10>")
	)
	(segment
		(start 92.786454 -381.23622)
		(end 92.649294 -381.09906)
		(width 0.14224)
		(layer "In11.Cu")
		(net "P5E_CPU1_P1_RX_DN<10>")
	)
	(segment
		(start 106.589068 -291.441632)
		(end 106.658664 -291.400992)
		(width 0.1143)
		(layer "In11.Cu")
		(net "P5E_CPU1_P1_RX_DN<10>")
	)
	(segment
		(start 106.149648 -280.238962)
		(end 106.148124 -280.237946)
		(width 0.1143)
		(layer "In11.Cu")
		(net "P5E_CPU1_P1_RX_DN<10>")
	)
	(segment
		(start 97.320354 -367.332006)
		(end 102.57536 -363.094778)
		(width 0.14224)
		(layer "In11.Cu")
		(net "P5E_CPU1_P1_RX_DN<10>")
	)
	(segment
		(start 106.658664 -281.071574)
		(end 106.589068 -281.030934)
		(width 0.1143)
		(layer "In11.Cu")
		(net "P5E_CPU1_P1_RX_DN<10>")
	)
	(segment
		(start 92.672916 -385.404868)
		(end 92.794582 -385.334764)
		(width 0.14224)
		(layer "In11.Cu")
		(net "P5E_CPU1_P1_RX_DN<10>")
	)
	(segment
		(start 105.916984 -296.258488)
		(end 105.962704 -296.212768)
		(width 0.1143)
		(layer "In11.Cu")
		(net "P5E_CPU1_P1_RX_DN<10>")
	)
	(segment
		(start 106.15549 -279.27046)
		(end 106.157014 -279.269444)
		(width 0.1143)
		(layer "In11.Cu")
		(net "P5E_CPU1_P1_RX_DN<10>")
	)
	(segment
		(start 106.589068 -284.961838)
		(end 106.658664 -284.921198)
		(width 0.1143)
		(layer "In11.Cu")
		(net "P5E_CPU1_P1_RX_DN<10>")
	)
	(segment
		(start 114.75339 -314.240672)
		(end 108.96854 -305.583336)
		(width 0.14224)
		(layer "In11.Cu")
		(net "P5E_CPU1_P1_RX_DN<10>")
	)
	(segment
		(start 92.794582 -385.334764)
		(end 92.794582 -385.163822)
		(width 0.14224)
		(layer "In11.Cu")
		(net "P5E_CPU1_P1_RX_DN<10>")
	)
	(segment
		(start 92.649294 -378.41682)
		(end 92.786454 -378.27966)
		(width 0.14224)
		(layer "In11.Cu")
		(net "P5E_CPU1_P1_RX_DN<10>")
	)
	(arc
		(start 106.589068 -293.990776)
		(mid 106.345741 -293.52621)
		(end 106.589068 -293.061644)
		(width 0.1143)
		(layer "In11.Cu")
		(net "P5E_CPU1_P1_RX_DN<10>")
	)
	(arc
		(start 92.786454 -373.74195)
		(mid 92.806023 -373.616413)
		(end 92.863162 -373.502936)
		(width 0.14224)
		(layer "In11.Cu")
		(net "P5E_CPU1_P1_RX_DN<10>")
	)
	(arc
		(start 106.191558 -295.489376)
		(mid 106.304571 -295.319855)
		(end 106.345736 -295.120314)
		(width 0.1143)
		(layer "In11.Cu")
		(net "P5E_CPU1_P1_RX_DN<10>")
	)
	(arc
		(start 123.091448 -349.383096)
		(mid 123.58633 -348.929057)
		(end 123.921012 -348.346776)
		(width 0.14224)
		(layer "In11.Cu")
		(net "P5E_CPU1_P1_RX_DN<10>")
	)
	(arc
		(start 106.815636 -286.23641)
		(mid 106.774087 -286.064988)
		(end 106.658664 -285.93161)
		(width 0.1143)
		(layer "In11.Cu")
		(net "P5E_CPU1_P1_RX_DN<10>")
	)
	(arc
		(start 106.345736 -280.566368)
		(mid 106.304481 -280.395397)
		(end 106.18978 -280.262076)
		(width 0.1143)
		(layer "In11.Cu")
		(net "P5E_CPU1_P1_RX_DN<10>")
	)
	(arc
		(start 106.658664 -293.021004)
		(mid 106.815641 -292.716204)
		(end 106.658664 -292.411404)
		(width 0.1143)
		(layer "In11.Cu")
		(net "P5E_CPU1_P1_RX_DN<10>")
	)
	(arc
		(start 106.118914 -280.220928)
		(mid 105.875587 -279.756362)
		(end 106.118914 -279.291796)
		(width 0.1143)
		(layer "In11.Cu")
		(net "P5E_CPU1_P1_RX_DN<10>")
	)
	(arc
		(start 106.658664 -289.78098)
		(mid 106.815641 -289.47618)
		(end 106.658664 -289.17138)
		(width 0.1143)
		(layer "In11.Cu")
		(net "P5E_CPU1_P1_RX_DN<10>")
	)
	(arc
		(start 106.658664 -281.681174)
		(mid 106.815641 -281.376374)
		(end 106.658664 -281.071574)
		(width 0.1143)
		(layer "In11.Cu")
		(net "P5E_CPU1_P1_RX_DN<10>")
	)
	(arc
		(start 106.345736 -287.046162)
		(mid 106.410251 -286.783943)
		(end 106.589068 -286.581596)
		(width 0.1143)
		(layer "In11.Cu")
		(net "P5E_CPU1_P1_RX_DN<10>")
	)
	(arc
		(start 106.589068 -285.89097)
		(mid 106.345741 -285.426404)
		(end 106.589068 -284.961838)
		(width 0.1143)
		(layer "In11.Cu")
		(net "P5E_CPU1_P1_RX_DN<10>")
	)
	(arc
		(start 106.345736 -295.120314)
		(mid 106.415205 -294.86263)
		(end 106.603292 -294.673274)
		(width 0.1143)
		(layer "In11.Cu")
		(net "P5E_CPU1_P1_RX_DN<10>")
	)
	(arc
		(start 97.24517 -367.411508)
		(mid 97.280098 -367.369239)
		(end 97.320354 -367.332006)
		(width 0.14224)
		(layer "In11.Cu")
		(net "P5E_CPU1_P1_RX_DN<10>")
	)
	(arc
		(start 106.660696 -286.53994)
		(mid 106.774625 -286.406793)
		(end 106.815636 -286.23641)
		(width 0.1143)
		(layer "In11.Cu")
		(net "P5E_CPU1_P1_RX_DN<10>")
	)
	(arc
		(start 106.345736 -278.946356)
		(mid 106.410251 -278.684137)
		(end 106.589068 -278.48179)
		(width 0.1143)
		(layer "In11.Cu")
		(net "P5E_CPU1_P1_RX_DN<10>")
	)
	(arc
		(start 105.962704 -295.90619)
		(mid 105.997167 -295.732754)
		(end 106.095292 -295.585642)
		(width 0.1143)
		(layer "In11.Cu")
		(net "P5E_CPU1_P1_RX_DN<10>")
	)
	(arc
		(start 106.589068 -284.270958)
		(mid 106.345741 -283.806392)
		(end 106.589068 -283.341826)
		(width 0.1143)
		(layer "In11.Cu")
		(net "P5E_CPU1_P1_RX_DN<10>")
	)
	(arc
		(start 106.591608 -287.512506)
		(mid 106.410956 -287.309761)
		(end 106.345736 -287.046162)
		(width 0.1143)
		(layer "In11.Cu")
		(net "P5E_CPU1_P1_RX_DN<10>")
	)
	(arc
		(start 106.660696 -288.159952)
		(mid 106.774625 -288.026805)
		(end 106.815636 -287.856422)
		(width 0.1143)
		(layer "In11.Cu")
		(net "P5E_CPU1_P1_RX_DN<10>")
	)
	(arc
		(start 106.658664 -278.44115)
		(mid 106.756429 -278.338174)
		(end 106.808778 -278.2062)
		(width 0.1143)
		(layer "In11.Cu")
		(net "P5E_CPU1_P1_RX_DN<10>")
	)
	(arc
		(start 106.658664 -283.301186)
		(mid 106.815641 -282.996386)
		(end 106.658664 -282.691586)
		(width 0.1143)
		(layer "In11.Cu")
		(net "P5E_CPU1_P1_RX_DN<10>")
	)
	(arc
		(start 106.815636 -287.856422)
		(mid 106.774087 -287.685)
		(end 106.658664 -287.551622)
		(width 0.1143)
		(layer "In11.Cu")
		(net "P5E_CPU1_P1_RX_DN<10>")
	)
	(arc
		(start 106.589068 -281.030934)
		(mid 106.410255 -280.828584)
		(end 106.345736 -280.566368)
		(width 0.1143)
		(layer "In11.Cu")
		(net "P5E_CPU1_P1_RX_DN<10>")
	)
	(arc
		(start 106.658664 -284.921198)
		(mid 106.815641 -284.616398)
		(end 106.658664 -284.311598)
		(width 0.1143)
		(layer "In11.Cu")
		(net "P5E_CPU1_P1_RX_DN<10>")
	)
	(arc
		(start 106.589068 -290.750752)
		(mid 106.345741 -290.286186)
		(end 106.589068 -289.82162)
		(width 0.1143)
		(layer "In11.Cu")
		(net "P5E_CPU1_P1_RX_DN<10>")
	)
	(arc
		(start 106.589068 -289.13074)
		(mid 106.345741 -288.666174)
		(end 106.589068 -288.201608)
		(width 0.1143)
		(layer "In11.Cu")
		(net "P5E_CPU1_P1_RX_DN<10>")
	)
	(arc
		(start 106.589068 -292.370764)
		(mid 106.345741 -291.906198)
		(end 106.589068 -291.441632)
		(width 0.1143)
		(layer "In11.Cu")
		(net "P5E_CPU1_P1_RX_DN<10>")
	)
	(arc
		(start 102.57536 -363.094778)
		(mid 102.589848 -363.083527)
		(end 102.604824 -363.072934)
		(width 0.14224)
		(layer "In11.Cu")
		(net "P5E_CPU1_P1_RX_DN<10>")
	)
	(arc
		(start 106.658664 -294.641016)
		(mid 106.815641 -294.336216)
		(end 106.658664 -294.031416)
		(width 0.1143)
		(layer "In11.Cu")
		(net "P5E_CPU1_P1_RX_DN<10>")
	)
	(arc
		(start 106.18978 -279.250648)
		(mid 106.304456 -279.117314)
		(end 106.345736 -278.946356)
		(width 0.1143)
		(layer "In11.Cu")
		(net "P5E_CPU1_P1_RX_DN<10>")
	)
	(arc
		(start 106.589068 -282.650946)
		(mid 106.345741 -282.18638)
		(end 106.589068 -281.721814)
		(width 0.1143)
		(layer "In11.Cu")
		(net "P5E_CPU1_P1_RX_DN<10>")
	)
	(arc
		(start 106.658664 -291.400992)
		(mid 106.815641 -291.096192)
		(end 106.658664 -290.791392)
		(width 0.1143)
		(layer "In11.Cu")
		(net "P5E_CPU1_P1_RX_DN<10>")
	)
	(segment
		(start 79.798418 -385.31038)
		(end 80.319118 -385.31038)
		(width 0.127)
		(layer "F.Cu")
		(net "P5E_CPU1_P1_RX_DN<0>")
	)
	(segment
		(start 98.44786 -276.2504)
		(end 97.981008 -276.516338)
		(width 0.12954)
		(layer "F.Cu")
		(net "P5E_CPU1_P1_RX_DN<0>")
	)
	(segment
		(start 80.48244 -384.234944)
		(end 80.786478 -383.93116)
		(width 0.14224)
		(layer "In11.Cu")
		(net "P5E_CPU1_P1_RX_DN<0>")
	)
	(segment
		(start 96.430084 -296.435526)
		(end 96.475804 -296.389806)
		(width 0.1143)
		(layer "In11.Cu")
		(net "P5E_CPU1_P1_RX_DN<0>")
	)
	(segment
		(start 100.734114 -310.06923)
		(end 96.430084 -299.677836)
		(width 0.14224)
		(layer "In11.Cu")
		(net "P5E_CPU1_P1_RX_DN<0>")
	)
	(segment
		(start 97.189036 -289.82162)
		(end 97.258632 -289.78098)
		(width 0.1143)
		(layer "In11.Cu")
		(net "P5E_CPU1_P1_RX_DN<0>")
	)
	(segment
		(start 97.191068 -286.580072)
		(end 97.196148 -286.577024)
		(width 0.1143)
		(layer "In11.Cu")
		(net "P5E_CPU1_P1_RX_DN<0>")
	)
	(segment
		(start 80.794606 -385.163822)
		(end 80.477614 -384.84683)
		(width 0.14224)
		(layer "In11.Cu")
		(net "P5E_CPU1_P1_RX_DN<0>")
	)
	(segment
		(start 97.258632 -287.551622)
		(end 97.191576 -287.512506)
		(width 0.1143)
		(layer "In11.Cu")
		(net "P5E_CPU1_P1_RX_DN<0>")
	)
	(segment
		(start 76.86294 -366.190022)
		(end 85.47735 -361.148376)
		(width 0.14224)
		(layer "In11.Cu")
		(net "P5E_CPU1_P1_RX_DN<0>")
	)
	(segment
		(start 97.258632 -289.17138)
		(end 97.189036 -289.13074)
		(width 0.1143)
		(layer "In11.Cu")
		(net "P5E_CPU1_P1_RX_DN<0>")
	)
	(segment
		(start 79.456026 -381.094742)
		(end 79.15402 -380.792736)
		(width 0.14224)
		(layer "In11.Cu")
		(net "P5E_CPU1_P1_RX_DN<0>")
	)
	(segment
		(start 97.196148 -286.577024)
		(end 97.19691 -286.576516)
		(width 0.1143)
		(layer "In11.Cu")
		(net "P5E_CPU1_P1_RX_DN<0>")
	)
	(segment
		(start 96.945958 -295.160954)
		(end 96.945958 -295.146222)
		(width 0.1143)
		(layer "In11.Cu")
		(net "P5E_CPU1_P1_RX_DN<0>")
	)
	(segment
		(start 107.66806 -320.446908)
		(end 100.734114 -310.06923)
		(width 0.14224)
		(layer "In11.Cu")
		(net "P5E_CPU1_P1_RX_DN<0>")
	)
	(segment
		(start 97.258632 -282.691586)
		(end 97.189036 -282.650946)
		(width 0.1143)
		(layer "In11.Cu")
		(net "P5E_CPU1_P1_RX_DN<0>")
	)
	(segment
		(start 79.650082 -381.094742)
		(end 79.456026 -381.094742)
		(width 0.14224)
		(layer "In11.Cu")
		(net "P5E_CPU1_P1_RX_DN<0>")
	)
	(segment
		(start 96.736662 -279.281382)
		(end 96.789748 -279.250648)
		(width 0.1143)
		(layer "In11.Cu")
		(net "P5E_CPU1_P1_RX_DN<0>")
	)
	(segment
		(start 97.700084 -277.647654)
		(end 97.729802 -277.630636)
		(width 0.1143)
		(layer "In11.Cu")
		(net "P5E_CPU1_P1_RX_DN<0>")
	)
	(segment
		(start 97.189036 -284.961838)
		(end 97.258632 -284.921198)
		(width 0.1143)
		(layer "In11.Cu")
		(net "P5E_CPU1_P1_RX_DN<0>")
	)
	(segment
		(start 79.95158 -381.39624)
		(end 79.650082 -381.094742)
		(width 0.14224)
		(layer "In11.Cu")
		(net "P5E_CPU1_P1_RX_DN<0>")
	)
	(segment
		(start 80.794606 -385.334764)
		(end 80.794606 -385.163822)
		(width 0.14224)
		(layer "In11.Cu")
		(net "P5E_CPU1_P1_RX_DN<0>")
	)
	(segment
		(start 85.47735 -361.148376)
		(end 95.510096 -356.16388)
		(width 0.14224)
		(layer "In11.Cu")
		(net "P5E_CPU1_P1_RX_DN<0>")
	)
	(segment
		(start 97.19691 -286.576516)
		(end 97.198688 -286.5755)
		(width 0.1143)
		(layer "In11.Cu")
		(net "P5E_CPU1_P1_RX_DN<0>")
	)
	(segment
		(start 97.258632 -284.311598)
		(end 97.189036 -284.270958)
		(width 0.1143)
		(layer "In11.Cu")
		(net "P5E_CPU1_P1_RX_DN<0>")
	)
	(segment
		(start 115.651026 -342.415368)
		(end 116.468144 -340.442296)
		(width 0.14224)
		(layer "In11.Cu")
		(net "P5E_CPU1_P1_RX_DN<0>")
	)
	(segment
		(start 96.789748 -280.262076)
		(end 96.737424 -280.23185)
		(width 0.1143)
		(layer "In11.Cu")
		(net "P5E_CPU1_P1_RX_DN<0>")
	)
	(segment
		(start 97.198688 -286.5755)
		(end 97.19945 -286.574992)
		(width 0.1143)
		(layer "In11.Cu")
		(net "P5E_CPU1_P1_RX_DN<0>")
	)
	(segment
		(start 80.447642 -381.892302)
		(end 80.253586 -381.892302)
		(width 0.14224)
		(layer "In11.Cu")
		(net "P5E_CPU1_P1_RX_DN<0>")
	)
	(segment
		(start 97.189036 -281.721814)
		(end 97.258632 -281.681174)
		(width 0.1143)
		(layer "In11.Cu")
		(net "P5E_CPU1_P1_RX_DN<0>")
	)
	(segment
		(start 80.672432 -385.405376)
		(end 80.67294 -385.404868)
		(width 0.14224)
		(layer "In11.Cu")
		(net "P5E_CPU1_P1_RX_DN<0>")
	)
	(segment
		(start 114.882422 -329.804268)
		(end 114.067082 -328.244454)
		(width 0.14224)
		(layer "In11.Cu")
		(net "P5E_CPU1_P1_RX_DN<0>")
	)
	(segment
		(start 97.698814 -277.648416)
		(end 97.700084 -277.647654)
		(width 0.1143)
		(layer "In11.Cu")
		(net "P5E_CPU1_P1_RX_DN<0>")
	)
	(segment
		(start 97.258632 -281.071574)
		(end 97.189036 -281.030934)
		(width 0.1143)
		(layer "In11.Cu")
		(net "P5E_CPU1_P1_RX_DN<0>")
	)
	(segment
		(start 80.786478 -383.93116)
		(end 80.786478 -382.283716)
		(width 0.14224)
		(layer "In11.Cu")
		(net "P5E_CPU1_P1_RX_DN<0>")
	)
	(segment
		(start 96.737424 -280.23185)
		(end 96.736662 -280.231342)
		(width 0.1143)
		(layer "In11.Cu")
		(net "P5E_CPU1_P1_RX_DN<0>")
	)
	(segment
		(start 78.35646 -379.995176)
		(end 78.35646 -379.80112)
		(width 0.14224)
		(layer "In11.Cu")
		(net "P5E_CPU1_P1_RX_DN<0>")
	)
	(segment
		(start 79.95158 -381.590296)
		(end 79.95158 -381.39624)
		(width 0.14224)
		(layer "In11.Cu")
		(net "P5E_CPU1_P1_RX_DN<0>")
	)
	(segment
		(start 80.477614 -384.84683)
		(end 80.48244 -384.234944)
		(width 0.14224)
		(layer "In11.Cu")
		(net "P5E_CPU1_P1_RX_DN<0>")
	)
	(segment
		(start 80.67294 -385.404868)
		(end 80.794606 -385.334764)
		(width 0.14224)
		(layer "In11.Cu")
		(net "P5E_CPU1_P1_RX_DN<0>")
	)
	(segment
		(start 97.258632 -292.411404)
		(end 97.189036 -292.370764)
		(width 0.1143)
		(layer "In11.Cu")
		(net "P5E_CPU1_P1_RX_DN<0>")
	)
	(segment
		(start 97.658936 -277.671784)
		(end 97.698052 -277.648924)
		(width 0.1143)
		(layer "In11.Cu")
		(net "P5E_CPU1_P1_RX_DN<0>")
	)
	(segment
		(start 73.131934 -370.491258)
		(end 75.50023 -367.249202)
		(width 0.14224)
		(layer "In11.Cu")
		(net "P5E_CPU1_P1_RX_DN<0>")
	)
	(segment
		(start 96.734376 -295.611296)
		(end 96.77654 -295.569132)
		(width 0.1143)
		(layer "In11.Cu")
		(net "P5E_CPU1_P1_RX_DN<0>")
	)
	(segment
		(start 78.852522 -380.297182)
		(end 78.658466 -380.297182)
		(width 0.14224)
		(layer "In11.Cu")
		(net "P5E_CPU1_P1_RX_DN<0>")
	)
	(segment
		(start 97.189036 -283.341826)
		(end 97.258632 -283.301186)
		(width 0.1143)
		(layer "In11.Cu")
		(net "P5E_CPU1_P1_RX_DN<0>")
	)
	(segment
		(start 80.74914 -382.1938)
		(end 80.447642 -381.892302)
		(width 0.14224)
		(layer "In11.Cu")
		(net "P5E_CPU1_P1_RX_DN<0>")
	)
	(segment
		(start 97.258632 -285.93161)
		(end 97.189036 -285.89097)
		(width 0.1143)
		(layer "In11.Cu")
		(net "P5E_CPU1_P1_RX_DN<0>")
	)
	(segment
		(start 78.658466 -380.297182)
		(end 78.35646 -379.995176)
		(width 0.14224)
		(layer "In11.Cu")
		(net "P5E_CPU1_P1_RX_DN<0>")
	)
	(segment
		(start 97.258632 -294.031416)
		(end 97.189036 -293.990776)
		(width 0.1143)
		(layer "In11.Cu")
		(net "P5E_CPU1_P1_RX_DN<0>")
	)
	(segment
		(start 97.19945 -286.574992)
		(end 97.260664 -286.53994)
		(width 0.1143)
		(layer "In11.Cu")
		(net "P5E_CPU1_P1_RX_DN<0>")
	)
	(segment
		(start 98.3488 -276.586188)
		(end 98.27895 -276.516338)
		(width 0.1143)
		(layer "In11.Cu")
		(net "P5E_CPU1_P1_RX_DN<0>")
	)
	(segment
		(start 96.430084 -296.463974)
		(end 96.430084 -296.435526)
		(width 0.1143)
		(layer "In11.Cu")
		(net "P5E_CPU1_P1_RX_DN<0>")
	)
	(segment
		(start 79.15402 -380.59868)
		(end 78.852522 -380.297182)
		(width 0.14224)
		(layer "In11.Cu")
		(net "P5E_CPU1_P1_RX_DN<0>")
	)
	(segment
		(start 97.698052 -277.648924)
		(end 97.698814 -277.648416)
		(width 0.1143)
		(layer "In11.Cu")
		(net "P5E_CPU1_P1_RX_DN<0>")
	)
	(segment
		(start 75.577954 -367.168938)
		(end 76.5683 -366.390682)
		(width 0.14224)
		(layer "In11.Cu")
		(net "P5E_CPU1_P1_RX_DN<0>")
	)
	(segment
		(start 98.27895 -276.516338)
		(end 97.981008 -276.516338)
		(width 0.1143)
		(layer "In11.Cu")
		(net "P5E_CPU1_P1_RX_DN<0>")
	)
	(segment
		(start 78.35646 -379.80112)
		(end 76.53147 -377.97613)
		(width 0.14224)
		(layer "In11.Cu")
		(net "P5E_CPU1_P1_RX_DN<0>")
	)
	(segment
		(start 116.468144 -340.442296)
		(end 116.468144 -338.622132)
		(width 0.14224)
		(layer "In11.Cu")
		(net "P5E_CPU1_P1_RX_DN<0>")
	)
	(segment
		(start 80.253586 -381.892302)
		(end 79.95158 -381.590296)
		(width 0.14224)
		(layer "In11.Cu")
		(net "P5E_CPU1_P1_RX_DN<0>")
	)
	(segment
		(start 79.15402 -380.792736)
		(end 79.15402 -380.59868)
		(width 0.14224)
		(layer "In11.Cu")
		(net "P5E_CPU1_P1_RX_DN<0>")
	)
	(segment
		(start 97.189036 -291.441632)
		(end 97.258632 -291.400992)
		(width 0.1143)
		(layer "In11.Cu")
		(net "P5E_CPU1_P1_RX_DN<0>")
	)
	(segment
		(start 95.510096 -356.16388)
		(end 115.122706 -343.059004)
		(width 0.14224)
		(layer "In11.Cu")
		(net "P5E_CPU1_P1_RX_DN<0>")
	)
	(segment
		(start 76.455778 -377.871736)
		(end 75.998324 -376.968766)
		(width 0.14224)
		(layer "In11.Cu")
		(net "P5E_CPU1_P1_RX_DN<0>")
	)
	(segment
		(start 96.430084 -299.677836)
		(end 96.430084 -296.463974)
		(width 0.14224)
		(layer "In11.Cu")
		(net "P5E_CPU1_P1_RX_DN<0>")
	)
	(segment
		(start 97.189036 -286.581596)
		(end 97.191068 -286.580072)
		(width 0.1143)
		(layer "In11.Cu")
		(net "P5E_CPU1_P1_RX_DN<0>")
	)
	(segment
		(start 98.12909 -276.861778)
		(end 98.198686 -276.821138)
		(width 0.1143)
		(layer "In11.Cu")
		(net "P5E_CPU1_P1_RX_DN<0>")
	)
	(segment
		(start 96.475804 -296.389806)
		(end 96.475804 -296.236136)
		(width 0.1143)
		(layer "In11.Cu")
		(net "P5E_CPU1_P1_RX_DN<0>")
	)
	(segment
		(start 97.189036 -288.201608)
		(end 97.260664 -288.159952)
		(width 0.1143)
		(layer "In11.Cu")
		(net "P5E_CPU1_P1_RX_DN<0>")
	)
	(segment
		(start 97.189036 -293.061644)
		(end 97.258632 -293.021004)
		(width 0.1143)
		(layer "In11.Cu")
		(net "P5E_CPU1_P1_RX_DN<0>")
	)
	(segment
		(start 73.012554 -372.056914)
		(end 72.996298 -370.916708)
		(width 0.14224)
		(layer "In11.Cu")
		(net "P5E_CPU1_P1_RX_DN<0>")
	)
	(segment
		(start 74.937874 -375.160286)
		(end 73.151238 -372.500906)
		(width 0.14224)
		(layer "In11.Cu")
		(net "P5E_CPU1_P1_RX_DN<0>")
	)
	(segment
		(start 116.468144 -338.622132)
		(end 114.882422 -329.804268)
		(width 0.14224)
		(layer "In11.Cu")
		(net "P5E_CPU1_P1_RX_DN<0>")
	)
	(segment
		(start 97.189036 -278.48179)
		(end 97.258632 -278.44115)
		(width 0.1143)
		(layer "In11.Cu")
		(net "P5E_CPU1_P1_RX_DN<0>")
	)
	(segment
		(start 80.319118 -385.31038)
		(end 80.672432 -385.405376)
		(width 0.14224)
		(layer "In11.Cu")
		(net "P5E_CPU1_P1_RX_DN<0>")
	)
	(segment
		(start 114.067082 -328.244454)
		(end 107.66806 -320.446908)
		(width 0.14224)
		(layer "In11.Cu")
		(net "P5E_CPU1_P1_RX_DN<0>")
	)
	(segment
		(start 97.19056 -294.68064)
		(end 97.258632 -294.641016)
		(width 0.1143)
		(layer "In11.Cu")
		(net "P5E_CPU1_P1_RX_DN<0>")
	)
	(segment
		(start 97.258632 -290.791392)
		(end 97.189036 -290.750752)
		(width 0.1143)
		(layer "In11.Cu")
		(net "P5E_CPU1_P1_RX_DN<0>")
	)
	(arc
		(start 96.789748 -279.250648)
		(mid 96.904424 -279.117314)
		(end 96.945704 -278.946356)
		(width 0.1143)
		(layer "In11.Cu")
		(net "P5E_CPU1_P1_RX_DN<0>")
	)
	(arc
		(start 96.945704 -278.946356)
		(mid 97.010219 -278.684137)
		(end 97.189036 -278.48179)
		(width 0.1143)
		(layer "In11.Cu")
		(net "P5E_CPU1_P1_RX_DN<0>")
	)
	(arc
		(start 96.729296 -280.22677)
		(mid 96.47241 -279.756469)
		(end 96.729042 -279.285954)
		(width 0.1143)
		(layer "In11.Cu")
		(net "P5E_CPU1_P1_RX_DN<0>")
	)
	(arc
		(start 97.415604 -278.13635)
		(mid 97.480119 -277.874131)
		(end 97.658936 -277.671784)
		(width 0.1143)
		(layer "In11.Cu")
		(net "P5E_CPU1_P1_RX_DN<0>")
	)
	(arc
		(start 96.77654 -295.569132)
		(mid 96.901863 -295.381902)
		(end 96.945958 -295.160954)
		(width 0.1143)
		(layer "In11.Cu")
		(net "P5E_CPU1_P1_RX_DN<0>")
	)
	(arc
		(start 97.189036 -281.030934)
		(mid 97.010223 -280.828584)
		(end 96.945704 -280.566368)
		(width 0.1143)
		(layer "In11.Cu")
		(net "P5E_CPU1_P1_RX_DN<0>")
	)
	(arc
		(start 80.786478 -382.283716)
		(mid 80.776776 -382.235032)
		(end 80.74914 -382.1938)
		(width 0.14224)
		(layer "In11.Cu")
		(net "P5E_CPU1_P1_RX_DN<0>")
	)
	(arc
		(start 97.258632 -289.78098)
		(mid 97.415609 -289.47618)
		(end 97.258632 -289.17138)
		(width 0.1143)
		(layer "In11.Cu")
		(net "P5E_CPU1_P1_RX_DN<0>")
	)
	(arc
		(start 97.258632 -284.921198)
		(mid 97.415609 -284.616398)
		(end 97.258632 -284.311598)
		(width 0.1143)
		(layer "In11.Cu")
		(net "P5E_CPU1_P1_RX_DN<0>")
	)
	(arc
		(start 96.729042 -279.285954)
		(mid 96.732843 -279.283653)
		(end 96.736662 -279.281382)
		(width 0.1143)
		(layer "In11.Cu")
		(net "P5E_CPU1_P1_RX_DN<0>")
	)
	(arc
		(start 97.258632 -278.44115)
		(mid 97.374059 -278.307774)
		(end 97.415604 -278.13635)
		(width 0.1143)
		(layer "In11.Cu")
		(net "P5E_CPU1_P1_RX_DN<0>")
	)
	(arc
		(start 97.189036 -285.89097)
		(mid 96.945709 -285.426404)
		(end 97.189036 -284.961838)
		(width 0.1143)
		(layer "In11.Cu")
		(net "P5E_CPU1_P1_RX_DN<0>")
	)
	(arc
		(start 72.996298 -370.916708)
		(mid 73.029542 -370.692964)
		(end 73.131934 -370.491258)
		(width 0.14224)
		(layer "In11.Cu")
		(net "P5E_CPU1_P1_RX_DN<0>")
	)
	(arc
		(start 97.189036 -282.650946)
		(mid 96.945709 -282.18638)
		(end 97.189036 -281.721814)
		(width 0.1143)
		(layer "In11.Cu")
		(net "P5E_CPU1_P1_RX_DN<0>")
	)
	(arc
		(start 97.189036 -289.13074)
		(mid 96.945709 -288.666174)
		(end 97.189036 -288.201608)
		(width 0.1143)
		(layer "In11.Cu")
		(net "P5E_CPU1_P1_RX_DN<0>")
	)
	(arc
		(start 97.260664 -288.159952)
		(mid 97.374593 -288.026805)
		(end 97.415604 -287.856422)
		(width 0.1143)
		(layer "In11.Cu")
		(net "P5E_CPU1_P1_RX_DN<0>")
	)
	(arc
		(start 97.258632 -294.641016)
		(mid 97.415609 -294.336216)
		(end 97.258632 -294.031416)
		(width 0.1143)
		(layer "In11.Cu")
		(net "P5E_CPU1_P1_RX_DN<0>")
	)
	(arc
		(start 97.189036 -293.990776)
		(mid 96.945709 -293.52621)
		(end 97.189036 -293.061644)
		(width 0.1143)
		(layer "In11.Cu")
		(net "P5E_CPU1_P1_RX_DN<0>")
	)
	(arc
		(start 76.53147 -377.97613)
		(mid 76.489492 -377.926929)
		(end 76.455778 -377.871736)
		(width 0.14224)
		(layer "In11.Cu")
		(net "P5E_CPU1_P1_RX_DN<0>")
	)
	(arc
		(start 75.998324 -376.968766)
		(mid 75.495821 -376.048271)
		(end 74.937874 -375.160286)
		(width 0.14224)
		(layer "In11.Cu")
		(net "P5E_CPU1_P1_RX_DN<0>")
	)
	(arc
		(start 96.736662 -280.231342)
		(mid 96.73297 -280.229071)
		(end 96.729296 -280.22677)
		(width 0.1143)
		(layer "In11.Cu")
		(net "P5E_CPU1_P1_RX_DN<0>")
	)
	(arc
		(start 75.50023 -367.249202)
		(mid 75.536328 -367.206392)
		(end 75.577954 -367.168938)
		(width 0.14224)
		(layer "In11.Cu")
		(net "P5E_CPU1_P1_RX_DN<0>")
	)
	(arc
		(start 97.885758 -277.326344)
		(mid 97.950273 -277.064125)
		(end 98.12909 -276.861778)
		(width 0.1143)
		(layer "In11.Cu")
		(net "P5E_CPU1_P1_RX_DN<0>")
	)
	(arc
		(start 97.189036 -290.750752)
		(mid 96.945709 -290.286186)
		(end 97.189036 -289.82162)
		(width 0.1143)
		(layer "In11.Cu")
		(net "P5E_CPU1_P1_RX_DN<0>")
	)
	(arc
		(start 97.191576 -287.512506)
		(mid 96.945688 -287.047712)
		(end 97.189036 -286.581596)
		(width 0.1143)
		(layer "In11.Cu")
		(net "P5E_CPU1_P1_RX_DN<0>")
	)
	(arc
		(start 97.258632 -281.681174)
		(mid 97.415609 -281.376374)
		(end 97.258632 -281.071574)
		(width 0.1143)
		(layer "In11.Cu")
		(net "P5E_CPU1_P1_RX_DN<0>")
	)
	(arc
		(start 97.189036 -292.370764)
		(mid 96.945709 -291.906198)
		(end 97.189036 -291.441632)
		(width 0.1143)
		(layer "In11.Cu")
		(net "P5E_CPU1_P1_RX_DN<0>")
	)
	(arc
		(start 98.198686 -276.821138)
		(mid 98.296451 -276.718162)
		(end 98.3488 -276.586188)
		(width 0.1143)
		(layer "In11.Cu")
		(net "P5E_CPU1_P1_RX_DN<0>")
	)
	(arc
		(start 97.258632 -283.301186)
		(mid 97.415609 -282.996386)
		(end 97.258632 -282.691586)
		(width 0.1143)
		(layer "In11.Cu")
		(net "P5E_CPU1_P1_RX_DN<0>")
	)
	(arc
		(start 97.415604 -287.856422)
		(mid 97.374055 -287.685)
		(end 97.258632 -287.551622)
		(width 0.1143)
		(layer "In11.Cu")
		(net "P5E_CPU1_P1_RX_DN<0>")
	)
	(arc
		(start 97.189036 -284.270958)
		(mid 96.945709 -283.806392)
		(end 97.189036 -283.341826)
		(width 0.1143)
		(layer "In11.Cu")
		(net "P5E_CPU1_P1_RX_DN<0>")
	)
	(arc
		(start 97.258632 -293.021004)
		(mid 97.415609 -292.716204)
		(end 97.258632 -292.411404)
		(width 0.1143)
		(layer "In11.Cu")
		(net "P5E_CPU1_P1_RX_DN<0>")
	)
	(arc
		(start 96.945958 -295.146222)
		(mid 97.010776 -294.883233)
		(end 97.19056 -294.68064)
		(width 0.1143)
		(layer "In11.Cu")
		(net "P5E_CPU1_P1_RX_DN<0>")
	)
	(arc
		(start 96.945704 -280.566368)
		(mid 96.904449 -280.395397)
		(end 96.789748 -280.262076)
		(width 0.1143)
		(layer "In11.Cu")
		(net "P5E_CPU1_P1_RX_DN<0>")
	)
	(arc
		(start 73.151238 -372.500906)
		(mid 73.049615 -372.288993)
		(end 73.012554 -372.056914)
		(width 0.14224)
		(layer "In11.Cu")
		(net "P5E_CPU1_P1_RX_DN<0>")
	)
	(arc
		(start 76.5683 -366.390682)
		(mid 76.712192 -366.285318)
		(end 76.86294 -366.190022)
		(width 0.14224)
		(layer "In11.Cu")
		(net "P5E_CPU1_P1_RX_DN<0>")
	)
	(arc
		(start 97.260664 -286.53994)
		(mid 97.374593 -286.406793)
		(end 97.415604 -286.23641)
		(width 0.1143)
		(layer "In11.Cu")
		(net "P5E_CPU1_P1_RX_DN<0>")
	)
	(arc
		(start 96.475804 -296.236136)
		(mid 96.542952 -295.898001)
		(end 96.734376 -295.611296)
		(width 0.1143)
		(layer "In11.Cu")
		(net "P5E_CPU1_P1_RX_DN<0>")
	)
	(arc
		(start 97.415604 -286.23641)
		(mid 97.374055 -286.064988)
		(end 97.258632 -285.93161)
		(width 0.1143)
		(layer "In11.Cu")
		(net "P5E_CPU1_P1_RX_DN<0>")
	)
	(arc
		(start 115.122706 -343.059004)
		(mid 115.434619 -342.776382)
		(end 115.651026 -342.415368)
		(width 0.14224)
		(layer "In11.Cu")
		(net "P5E_CPU1_P1_RX_DN<0>")
	)
	(arc
		(start 97.258632 -291.400992)
		(mid 97.415609 -291.096192)
		(end 97.258632 -290.791392)
		(width 0.1143)
		(layer "In11.Cu")
		(net "P5E_CPU1_P1_RX_DN<0>")
	)
	(arc
		(start 97.729802 -277.630636)
		(mid 97.844478 -277.497302)
		(end 97.885758 -277.326344)
		(width 0.1143)
		(layer "In11.Cu")
		(net "P5E_CPU1_P1_RX_DN<0>")
	)
	(segment
		(start 58.601864 -370.00942)
		(end 58.305954 -370.30533)
		(width 0.12954)
		(layer "F.Cu")
		(net "P5E_CPU1_P0_TX_DP<9>")
	)
	(segment
		(start 104.08793 -282.730448)
		(end 103.621078 -282.996386)
		(width 0.12954)
		(layer "F.Cu")
		(net "P5E_CPU1_P0_TX_DP<9>")
	)
	(segment
		(start 58.601864 -369.30584)
		(end 58.601864 -370.00942)
		(width 0.12954)
		(layer "F.Cu")
		(net "P5E_CPU1_P0_TX_DP<9>")
	)
	(segment
		(start 58.331354 -369.03533)
		(end 58.601864 -369.30584)
		(width 0.12954)
		(layer "F.Cu")
		(net "P5E_CPU1_P0_TX_DP<9>")
	)
	(segment
		(start 105.181654 -285.082742)
		(end 105.249726 -285.122112)
		(width 0.1143)
		(layer "In6.Cu")
		(net "P5E_CPU1_P0_TX_DP<9>")
	)
	(segment
		(start 105.720642 -288.159952)
		(end 105.649014 -288.201608)
		(width 0.1143)
		(layer "In6.Cu")
		(net "P5E_CPU1_P0_TX_DP<9>")
	)
	(segment
		(start 105.71861 -289.78098)
		(end 105.649014 -289.82162)
		(width 0.1143)
		(layer "In6.Cu")
		(net "P5E_CPU1_P0_TX_DP<9>")
	)
	(segment
		(start 105.647744 -289.129724)
		(end 105.691178 -289.158426)
		(width 0.1143)
		(layer "In6.Cu")
		(net "P5E_CPU1_P0_TX_DP<9>")
	)
	(segment
		(start 105.207308 -285.75508)
		(end 105.197402 -285.760922)
		(width 0.1143)
		(layer "In6.Cu")
		(net "P5E_CPU1_P0_TX_DP<9>")
	)
	(segment
		(start 103.621078 -282.996386)
		(end 103.91902 -282.996386)
		(width 0.1143)
		(layer "In6.Cu")
		(net "P5E_CPU1_P0_TX_DP<9>")
	)
	(segment
		(start 105.20807 -285.754572)
		(end 105.207308 -285.75508)
		(width 0.1143)
		(layer "In6.Cu")
		(net "P5E_CPU1_P0_TX_DP<9>")
	)
	(segment
		(start 105.19664 -286.71139)
		(end 105.251504 -286.743394)
		(width 0.1143)
		(layer "In6.Cu")
		(net "P5E_CPU1_P0_TX_DP<9>")
	)
	(segment
		(start 65.252092 -364.87227)
		(end 59.527694 -367.243614)
		(width 0.14224)
		(layer "In6.Cu")
		(net "P5E_CPU1_P0_TX_DP<9>")
	)
	(segment
		(start 113.42878 -313.959494)
		(end 119.42826 -321.270122)
		(width 0.14224)
		(layer "In6.Cu")
		(net "P5E_CPU1_P0_TX_DP<9>")
	)
	(segment
		(start 105.651554 -287.512506)
		(end 105.71861 -287.551622)
		(width 0.1143)
		(layer "In6.Cu")
		(net "P5E_CPU1_P0_TX_DP<9>")
	)
	(segment
		(start 119.49811 -321.375532)
		(end 123.138184 -328.33818)
		(width 0.14224)
		(layer "In6.Cu")
		(net "P5E_CPU1_P0_TX_DP<9>")
	)
	(segment
		(start 103.91902 -282.996386)
		(end 104.001824 -283.07919)
		(width 0.1143)
		(layer "In6.Cu")
		(net "P5E_CPU1_P0_TX_DP<9>")
	)
	(segment
		(start 105.197402 -285.760922)
		(end 105.19664 -285.76143)
		(width 0.1143)
		(layer "In6.Cu")
		(net "P5E_CPU1_P0_TX_DP<9>")
	)
	(segment
		(start 101.88575 -365.501174)
		(end 72.335644 -365.501174)
		(width 0.14224)
		(layer "In6.Cu")
		(net "P5E_CPU1_P0_TX_DP<9>")
	)
	(segment
		(start 124.903484 -344.916252)
		(end 122.145298 -351.57537)
		(width 0.14224)
		(layer "In6.Cu")
		(net "P5E_CPU1_P0_TX_DP<9>")
	)
	(segment
		(start 59.331606 -367.374678)
		(end 58.751978 -367.954306)
		(width 0.14224)
		(layer "In6.Cu")
		(net "P5E_CPU1_P0_TX_DP<9>")
	)
	(segment
		(start 125.296676 -342.991948)
		(end 124.93371 -344.81643)
		(width 0.14224)
		(layer "In6.Cu")
		(net "P5E_CPU1_P0_TX_DP<9>")
	)
	(segment
		(start 123.39955 -329.289156)
		(end 125.425962 -340.571328)
		(width 0.14224)
		(layer "In6.Cu")
		(net "P5E_CPU1_P0_TX_DP<9>")
	)
	(segment
		(start 108.111544 -305.809142)
		(end 108.674154 -306.861972)
		(width 0.14224)
		(layer "In6.Cu")
		(net "P5E_CPU1_P0_TX_DP<9>")
	)
	(segment
		(start 58.622184 -368.267996)
		(end 58.622184 -368.7445)
		(width 0.14224)
		(layer "In6.Cu")
		(net "P5E_CPU1_P0_TX_DP<9>")
	)
	(segment
		(start 105.249726 -285.730696)
		(end 105.20807 -285.754572)
		(width 0.1143)
		(layer "In6.Cu")
		(net "P5E_CPU1_P0_TX_DP<9>")
	)
	(segment
		(start 105.003092 -298.304966)
		(end 108.111544 -305.809142)
		(width 0.14224)
		(layer "In6.Cu")
		(net "P5E_CPU1_P0_TX_DP<9>")
	)
	(segment
		(start 58.622184 -368.7445)
		(end 58.331354 -369.03533)
		(width 0.14224)
		(layer "In6.Cu")
		(net "P5E_CPU1_P0_TX_DP<9>")
	)
	(segment
		(start 105.01757 -296.21734)
		(end 104.97185 -296.26306)
		(width 0.1143)
		(layer "In6.Cu")
		(net "P5E_CPU1_P0_TX_DP<9>")
	)
	(segment
		(start 105.71861 -294.641016)
		(end 105.649014 -294.681656)
		(width 0.1143)
		(layer "In6.Cu")
		(net "P5E_CPU1_P0_TX_DP<9>")
	)
	(segment
		(start 72.046592 -365.44377)
		(end 70.456806 -364.785402)
		(width 0.14224)
		(layer "In6.Cu")
		(net "P5E_CPU1_P0_TX_DP<9>")
	)
	(segment
		(start 104.97185 -296.291508)
		(end 104.97185 -298.148248)
		(width 0.14224)
		(layer "In6.Cu")
		(net "P5E_CPU1_P0_TX_DP<9>")
	)
	(segment
		(start 105.64749 -289.129724)
		(end 105.647744 -289.129724)
		(width 0.1143)
		(layer "In6.Cu")
		(net "P5E_CPU1_P0_TX_DP<9>")
	)
	(segment
		(start 105.649014 -293.990776)
		(end 105.71861 -294.031416)
		(width 0.1143)
		(layer "In6.Cu")
		(net "P5E_CPU1_P0_TX_DP<9>")
	)
	(segment
		(start 105.01757 -296.082974)
		(end 105.01757 -296.21734)
		(width 0.1143)
		(layer "In6.Cu")
		(net "P5E_CPU1_P0_TX_DP<9>")
	)
	(segment
		(start 70.456806 -364.785402)
		(end 65.688972 -364.785402)
		(width 0.14224)
		(layer "In6.Cu")
		(net "P5E_CPU1_P0_TX_DP<9>")
	)
	(segment
		(start 105.649014 -290.750752)
		(end 105.71861 -290.791392)
		(width 0.1143)
		(layer "In6.Cu")
		(net "P5E_CPU1_P0_TX_DP<9>")
	)
	(segment
		(start 105.71861 -291.400992)
		(end 105.649014 -291.441632)
		(width 0.1143)
		(layer "In6.Cu")
		(net "P5E_CPU1_P0_TX_DP<9>")
	)
	(segment
		(start 104.97185 -296.26306)
		(end 104.97185 -296.291508)
		(width 0.1143)
		(layer "In6.Cu")
		(net "P5E_CPU1_P0_TX_DP<9>")
	)
	(segment
		(start 104.70896 -284.271212)
		(end 104.77119 -284.30728)
		(width 0.1143)
		(layer "In6.Cu")
		(net "P5E_CPU1_P0_TX_DP<9>")
	)
	(segment
		(start 121.054368 -352.913696)
		(end 102.549706 -365.299244)
		(width 0.14224)
		(layer "In6.Cu")
		(net "P5E_CPU1_P0_TX_DP<9>")
	)
	(segment
		(start 104.23906 -283.460952)
		(end 104.308656 -283.501592)
		(width 0.1143)
		(layer "In6.Cu")
		(net "P5E_CPU1_P0_TX_DP<9>")
	)
	(segment
		(start 105.71861 -293.021004)
		(end 105.649014 -293.061644)
		(width 0.1143)
		(layer "In6.Cu")
		(net "P5E_CPU1_P0_TX_DP<9>")
	)
	(segment
		(start 108.674154 -306.861972)
		(end 113.302542 -313.789314)
		(width 0.14224)
		(layer "In6.Cu")
		(net "P5E_CPU1_P0_TX_DP<9>")
	)
	(segment
		(start 105.649014 -292.370764)
		(end 105.71861 -292.411404)
		(width 0.1143)
		(layer "In6.Cu")
		(net "P5E_CPU1_P0_TX_DP<9>")
	)
	(arc
		(start 59.527694 -367.243614)
		(mid 59.423203 -367.299498)
		(end 59.331606 -367.374678)
		(width 0.14224)
		(layer "In6.Cu")
		(net "P5E_CPU1_P0_TX_DP<9>")
	)
	(arc
		(start 105.71861 -290.791392)
		(mid 105.875587 -291.096192)
		(end 105.71861 -291.400992)
		(width 0.1143)
		(layer "In6.Cu")
		(net "P5E_CPU1_P0_TX_DP<9>")
	)
	(arc
		(start 104.001824 -283.07919)
		(mid 104.003612 -283.090639)
		(end 104.005634 -283.10205)
		(width 0.1143)
		(layer "In6.Cu")
		(net "P5E_CPU1_P0_TX_DP<9>")
	)
	(arc
		(start 105.170986 -285.075376)
		(mid 105.1763 -285.079088)
		(end 105.181654 -285.082742)
		(width 0.1143)
		(layer "In6.Cu")
		(net "P5E_CPU1_P0_TX_DP<9>")
	)
	(arc
		(start 119.42826 -321.270122)
		(mid 119.465902 -321.321027)
		(end 119.49811 -321.375532)
		(width 0.14224)
		(layer "In6.Cu")
		(net "P5E_CPU1_P0_TX_DP<9>")
	)
	(arc
		(start 105.875582 -287.856422)
		(mid 105.834616 -288.026828)
		(end 105.720642 -288.159952)
		(width 0.1143)
		(layer "In6.Cu")
		(net "P5E_CPU1_P0_TX_DP<9>")
	)
	(arc
		(start 105.71861 -294.031416)
		(mid 105.875587 -294.336216)
		(end 105.71861 -294.641016)
		(width 0.1143)
		(layer "In6.Cu")
		(net "P5E_CPU1_P0_TX_DP<9>")
	)
	(arc
		(start 104.97185 -298.148248)
		(mid 104.979766 -298.228142)
		(end 105.003092 -298.304966)
		(width 0.14224)
		(layer "In6.Cu")
		(net "P5E_CPU1_P0_TX_DP<9>")
	)
	(arc
		(start 58.751978 -367.954306)
		(mid 58.655842 -368.098229)
		(end 58.622184 -368.267996)
		(width 0.14224)
		(layer "In6.Cu")
		(net "P5E_CPU1_P0_TX_DP<9>")
	)
	(arc
		(start 124.93371 -344.81643)
		(mid 124.921048 -344.867083)
		(end 124.903484 -344.916252)
		(width 0.14224)
		(layer "In6.Cu")
		(net "P5E_CPU1_P0_TX_DP<9>")
	)
	(arc
		(start 104.465882 -283.806392)
		(mid 104.53027 -284.068685)
		(end 104.70896 -284.271212)
		(width 0.1143)
		(layer "In6.Cu")
		(net "P5E_CPU1_P0_TX_DP<9>")
	)
	(arc
		(start 104.005634 -283.10205)
		(mid 104.087067 -283.304448)
		(end 104.23906 -283.460952)
		(width 0.1143)
		(layer "In6.Cu")
		(net "P5E_CPU1_P0_TX_DP<9>")
	)
	(arc
		(start 65.688972 -364.785402)
		(mid 65.466256 -364.80733)
		(end 65.252092 -364.87227)
		(width 0.14224)
		(layer "In6.Cu")
		(net "P5E_CPU1_P0_TX_DP<9>")
	)
	(arc
		(start 104.93375 -284.607254)
		(mid 104.935059 -284.619294)
		(end 104.935782 -284.631384)
		(width 0.1143)
		(layer "In6.Cu")
		(net "P5E_CPU1_P0_TX_DP<9>")
	)
	(arc
		(start 105.251504 -286.743394)
		(mid 105.364911 -286.876283)
		(end 105.405682 -287.046162)
		(width 0.1143)
		(layer "In6.Cu")
		(net "P5E_CPU1_P0_TX_DP<9>")
	)
	(arc
		(start 122.145298 -351.57537)
		(mid 121.697915 -352.32448)
		(end 121.054368 -352.913696)
		(width 0.14224)
		(layer "In6.Cu")
		(net "P5E_CPU1_P0_TX_DP<9>")
	)
	(arc
		(start 123.138184 -328.33818)
		(mid 123.164688 -328.395779)
		(end 123.185174 -328.455782)
		(width 0.14224)
		(layer "In6.Cu")
		(net "P5E_CPU1_P0_TX_DP<9>")
	)
	(arc
		(start 105.649014 -291.441632)
		(mid 105.405687 -291.906198)
		(end 105.649014 -292.370764)
		(width 0.1143)
		(layer "In6.Cu")
		(net "P5E_CPU1_P0_TX_DP<9>")
	)
	(arc
		(start 105.405682 -295.146222)
		(mid 105.359071 -295.380464)
		(end 105.226358 -295.579038)
		(width 0.1143)
		(layer "In6.Cu")
		(net "P5E_CPU1_P0_TX_DP<9>")
	)
	(arc
		(start 104.308656 -283.501592)
		(mid 104.424175 -283.634949)
		(end 104.465882 -283.806392)
		(width 0.1143)
		(layer "In6.Cu")
		(net "P5E_CPU1_P0_TX_DP<9>")
	)
	(arc
		(start 105.71861 -287.551622)
		(mid 105.834037 -287.684998)
		(end 105.875582 -287.856422)
		(width 0.1143)
		(layer "In6.Cu")
		(net "P5E_CPU1_P0_TX_DP<9>")
	)
	(arc
		(start 102.549706 -365.299244)
		(mid 102.232726 -365.449516)
		(end 101.88575 -365.501174)
		(width 0.14224)
		(layer "In6.Cu")
		(net "P5E_CPU1_P0_TX_DP<9>")
	)
	(arc
		(start 105.249726 -285.122112)
		(mid 105.405654 -285.426404)
		(end 105.249726 -285.730696)
		(width 0.1143)
		(layer "In6.Cu")
		(net "P5E_CPU1_P0_TX_DP<9>")
	)
	(arc
		(start 104.77119 -284.30728)
		(mid 104.87939 -284.442682)
		(end 104.93375 -284.607254)
		(width 0.1143)
		(layer "In6.Cu")
		(net "P5E_CPU1_P0_TX_DP<9>")
	)
	(arc
		(start 72.335644 -365.501174)
		(mid 72.188291 -365.486708)
		(end 72.046592 -365.44377)
		(width 0.14224)
		(layer "In6.Cu")
		(net "P5E_CPU1_P0_TX_DP<9>")
	)
	(arc
		(start 105.691178 -289.158426)
		(mid 105.873852 -289.462302)
		(end 105.71861 -289.78098)
		(width 0.1143)
		(layer "In6.Cu")
		(net "P5E_CPU1_P0_TX_DP<9>")
	)
	(arc
		(start 123.185174 -328.455782)
		(mid 123.297824 -328.871064)
		(end 123.39955 -329.289156)
		(width 0.14224)
		(layer "In6.Cu")
		(net "P5E_CPU1_P0_TX_DP<9>")
	)
	(arc
		(start 105.226358 -295.579038)
		(mid 105.071816 -295.810232)
		(end 105.01757 -296.082974)
		(width 0.1143)
		(layer "In6.Cu")
		(net "P5E_CPU1_P0_TX_DP<9>")
	)
	(arc
		(start 125.425962 -340.571328)
		(mid 125.435181 -340.63572)
		(end 125.439678 -340.700614)
		(width 0.14224)
		(layer "In6.Cu")
		(net "P5E_CPU1_P0_TX_DP<9>")
	)
	(arc
		(start 105.649014 -289.82162)
		(mid 105.405687 -290.286186)
		(end 105.649014 -290.750752)
		(width 0.1143)
		(layer "In6.Cu")
		(net "P5E_CPU1_P0_TX_DP<9>")
	)
	(arc
		(start 113.302542 -313.789314)
		(mid 113.363576 -313.87595)
		(end 113.42878 -313.959494)
		(width 0.14224)
		(layer "In6.Cu")
		(net "P5E_CPU1_P0_TX_DP<9>")
	)
	(arc
		(start 125.439678 -340.700614)
		(mid 125.421786 -341.849627)
		(end 125.296676 -342.991948)
		(width 0.14224)
		(layer "In6.Cu")
		(net "P5E_CPU1_P0_TX_DP<9>")
	)
	(arc
		(start 105.649014 -293.061644)
		(mid 105.405687 -293.52621)
		(end 105.649014 -293.990776)
		(width 0.1143)
		(layer "In6.Cu")
		(net "P5E_CPU1_P0_TX_DP<9>")
	)
	(arc
		(start 105.19664 -285.76143)
		(mid 104.923089 -286.23641)
		(end 105.19664 -286.71139)
		(width 0.1143)
		(layer "In6.Cu")
		(net "P5E_CPU1_P0_TX_DP<9>")
	)
	(arc
		(start 105.71861 -292.411404)
		(mid 105.875587 -292.716204)
		(end 105.71861 -293.021004)
		(width 0.1143)
		(layer "In6.Cu")
		(net "P5E_CPU1_P0_TX_DP<9>")
	)
	(arc
		(start 105.649014 -288.201608)
		(mid 105.405688 -288.665258)
		(end 105.64749 -289.129724)
		(width 0.1143)
		(layer "In6.Cu")
		(net "P5E_CPU1_P0_TX_DP<9>")
	)
	(arc
		(start 104.935782 -284.631384)
		(mid 105.001402 -284.880902)
		(end 105.170986 -285.075376)
		(width 0.1143)
		(layer "In6.Cu")
		(net "P5E_CPU1_P0_TX_DP<9>")
	)
	(arc
		(start 105.405682 -287.046162)
		(mid 105.470918 -287.309753)
		(end 105.651554 -287.512506)
		(width 0.1143)
		(layer "In6.Cu")
		(net "P5E_CPU1_P0_TX_DP<9>")
	)
	(arc
		(start 105.649014 -294.681656)
		(mid 105.470201 -294.884006)
		(end 105.405682 -295.146222)
		(width 0.1143)
		(layer "In6.Cu")
		(net "P5E_CPU1_P0_TX_DP<9>")
	)
	(segment
		(start 56.900064 -372.47322)
		(end 56.604154 -372.76913)
		(width 0.12954)
		(layer "F.Cu")
		(net "P5E_CPU1_P0_TX_DP<8>")
	)
	(segment
		(start 104.08793 -285.970472)
		(end 103.621078 -286.23641)
		(width 0.12954)
		(layer "F.Cu")
		(net "P5E_CPU1_P0_TX_DP<8>")
	)
	(segment
		(start 56.629554 -371.49913)
		(end 56.900064 -371.76964)
		(width 0.12954)
		(layer "F.Cu")
		(net "P5E_CPU1_P0_TX_DP<8>")
	)
	(segment
		(start 56.900064 -371.76964)
		(end 56.900064 -372.47322)
		(width 0.12954)
		(layer "F.Cu")
		(net "P5E_CPU1_P0_TX_DP<8>")
	)
	(segment
		(start 104.748838 -291.418264)
		(end 104.748076 -291.418772)
		(width 0.1143)
		(layer "In6.Cu")
		(net "P5E_CPU1_P0_TX_DP<8>")
	)
	(segment
		(start 120.059196 -352.435668)
		(end 120.05945 -352.435668)
		(width 0.14224)
		(layer "In6.Cu")
		(net "P5E_CPU1_P0_TX_DP<8>")
	)
	(segment
		(start 104.71658 -290.755324)
		(end 104.748076 -290.773612)
		(width 0.1143)
		(layer "In6.Cu")
		(net "P5E_CPU1_P0_TX_DP<8>")
	)
	(segment
		(start 104.748838 -290.77412)
		(end 104.779826 -290.7919)
		(width 0.1143)
		(layer "In6.Cu")
		(net "P5E_CPU1_P0_TX_DP<8>")
	)
	(segment
		(start 57.049416 -368.440462)
		(end 56.942736 -368.888772)
		(width 0.14224)
		(layer "In6.Cu")
		(net "P5E_CPU1_P0_TX_DP<8>")
	)
	(segment
		(start 104.7115 -287.512506)
		(end 104.715818 -287.515046)
		(width 0.1143)
		(layer "In6.Cu")
		(net "P5E_CPU1_P0_TX_DP<8>")
	)
	(segment
		(start 104.74706 -287.533334)
		(end 104.749854 -287.534858)
		(width 0.1143)
		(layer "In6.Cu")
		(net "P5E_CPU1_P0_TX_DP<8>")
	)
	(segment
		(start 72.063102 -364.438184)
		(end 70.645274 -363.85119)
		(width 0.14224)
		(layer "In6.Cu")
		(net "P5E_CPU1_P0_TX_DP<8>")
	)
	(segment
		(start 104.779826 -291.400484)
		(end 104.748838 -291.418264)
		(width 0.1143)
		(layer "In6.Cu")
		(net "P5E_CPU1_P0_TX_DP<8>")
	)
	(segment
		(start 104.780588 -294.032432)
		(end 104.780588 -294.032686)
		(width 0.1143)
		(layer "In6.Cu")
		(net "P5E_CPU1_P0_TX_DP<8>")
	)
	(segment
		(start 104.745536 -293.040308)
		(end 104.70896 -293.061644)
		(width 0.1143)
		(layer "In6.Cu")
		(net "P5E_CPU1_P0_TX_DP<8>")
	)
	(segment
		(start 104.748076 -290.773612)
		(end 104.748838 -290.77412)
		(width 0.1143)
		(layer "In6.Cu")
		(net "P5E_CPU1_P0_TX_DP<8>")
	)
	(segment
		(start 104.278176 -286.723836)
		(end 104.310688 -286.742632)
		(width 0.1143)
		(layer "In6.Cu")
		(net "P5E_CPU1_P0_TX_DP<8>")
	)
	(segment
		(start 107.443778 -306.693062)
		(end 107.443778 -306.693316)
		(width 0.14224)
		(layer "In6.Cu")
		(net "P5E_CPU1_P0_TX_DP<8>")
	)
	(segment
		(start 104.06634 -298.537376)
		(end 107.443778 -306.693062)
		(width 0.14224)
		(layer "In6.Cu")
		(net "P5E_CPU1_P0_TX_DP<8>")
	)
	(segment
		(start 56.920384 -371.2083)
		(end 56.629554 -371.49913)
		(width 0.14224)
		(layer "In6.Cu")
		(net "P5E_CPU1_P0_TX_DP<8>")
	)
	(segment
		(start 104.748076 -292.393624)
		(end 104.748838 -292.394132)
		(width 0.1143)
		(layer "In6.Cu")
		(net "P5E_CPU1_P0_TX_DP<8>")
	)
	(segment
		(start 104.71658 -287.515554)
		(end 104.74706 -287.533334)
		(width 0.1143)
		(layer "In6.Cu")
		(net "P5E_CPU1_P0_TX_DP<8>")
	)
	(segment
		(start 107.52963 -306.85359)
		(end 112.498886 -314.290964)
		(width 0.14224)
		(layer "In6.Cu")
		(net "P5E_CPU1_P0_TX_DP<8>")
	)
	(segment
		(start 104.74706 -293.039292)
		(end 104.745536 -293.040308)
		(width 0.1143)
		(layer "In6.Cu")
		(net "P5E_CPU1_P0_TX_DP<8>")
	)
	(segment
		(start 104.74706 -291.41928)
		(end 104.745536 -291.420296)
		(width 0.1143)
		(layer "In6.Cu")
		(net "P5E_CPU1_P0_TX_DP<8>")
	)
	(segment
		(start 103.91902 -286.23641)
		(end 104.001824 -286.319214)
		(width 0.1143)
		(layer "In6.Cu")
		(net "P5E_CPU1_P0_TX_DP<8>")
	)
	(segment
		(start 104.748838 -289.154108)
		(end 104.779826 -289.171888)
		(width 0.1143)
		(layer "In6.Cu")
		(net "P5E_CPU1_P0_TX_DP<8>")
	)
	(segment
		(start 104.715818 -289.134804)
		(end 104.71658 -289.135312)
		(width 0.1143)
		(layer "In6.Cu")
		(net "P5E_CPU1_P0_TX_DP<8>")
	)
	(segment
		(start 104.70896 -289.13074)
		(end 104.715818 -289.134804)
		(width 0.1143)
		(layer "In6.Cu")
		(net "P5E_CPU1_P0_TX_DP<8>")
	)
	(segment
		(start 118.76532 -321.998848)
		(end 122.266456 -328.694288)
		(width 0.14224)
		(layer "In6.Cu")
		(net "P5E_CPU1_P0_TX_DP<8>")
	)
	(segment
		(start 104.715818 -290.754816)
		(end 104.71658 -290.755324)
		(width 0.1143)
		(layer "In6.Cu")
		(net "P5E_CPU1_P0_TX_DP<8>")
	)
	(segment
		(start 104.23906 -286.700976)
		(end 104.278176 -286.723836)
		(width 0.1143)
		(layer "In6.Cu")
		(net "P5E_CPU1_P0_TX_DP<8>")
	)
	(segment
		(start 104.74706 -289.799268)
		(end 104.745536 -289.800284)
		(width 0.1143)
		(layer "In6.Cu")
		(net "P5E_CPU1_P0_TX_DP<8>")
	)
	(segment
		(start 104.715818 -287.515046)
		(end 104.71658 -287.515554)
		(width 0.1143)
		(layer "In6.Cu")
		(net "P5E_CPU1_P0_TX_DP<8>")
	)
	(segment
		(start 104.565196 -294.825674)
		(end 104.56545 -294.825928)
		(width 0.1143)
		(layer "In6.Cu")
		(net "P5E_CPU1_P0_TX_DP<8>")
	)
	(segment
		(start 104.779064 -294.031416)
		(end 104.780588 -294.032432)
		(width 0.1143)
		(layer "In6.Cu")
		(net "P5E_CPU1_P0_TX_DP<8>")
	)
	(segment
		(start 104.465882 -295.145968)
		(end 104.465882 -295.20134)
		(width 0.1143)
		(layer "In6.Cu")
		(net "P5E_CPU1_P0_TX_DP<8>")
	)
	(segment
		(start 104.779826 -293.020496)
		(end 104.748838 -293.038276)
		(width 0.1143)
		(layer "In6.Cu")
		(net "P5E_CPU1_P0_TX_DP<8>")
	)
	(segment
		(start 104.748838 -293.038276)
		(end 104.748076 -293.038784)
		(width 0.1143)
		(layer "In6.Cu")
		(net "P5E_CPU1_P0_TX_DP<8>")
	)
	(segment
		(start 120.05945 -352.435668)
		(end 102.249986 -364.356142)
		(width 0.14224)
		(layer "In6.Cu")
		(net "P5E_CPU1_P0_TX_DP<8>")
	)
	(segment
		(start 112.757458 -314.640214)
		(end 118.695724 -321.893438)
		(width 0.14224)
		(layer "In6.Cu")
		(net "P5E_CPU1_P0_TX_DP<8>")
	)
	(segment
		(start 103.621078 -286.23641)
		(end 103.91902 -286.23641)
		(width 0.1143)
		(layer "In6.Cu")
		(net "P5E_CPU1_P0_TX_DP<8>")
	)
	(segment
		(start 72.063356 -364.438184)
		(end 72.063102 -364.438184)
		(width 0.14224)
		(layer "In6.Cu")
		(net "P5E_CPU1_P0_TX_DP<8>")
	)
	(segment
		(start 104.324912 -295.540938)
		(end 104.215438 -295.650412)
		(width 0.1143)
		(layer "In6.Cu")
		(net "P5E_CPU1_P0_TX_DP<8>")
	)
	(segment
		(start 104.70896 -293.990776)
		(end 104.779064 -294.031416)
		(width 0.1143)
		(layer "In6.Cu")
		(net "P5E_CPU1_P0_TX_DP<8>")
	)
	(segment
		(start 104.780588 -294.64)
		(end 104.70896 -294.681656)
		(width 0.1143)
		(layer "In6.Cu")
		(net "P5E_CPU1_P0_TX_DP<8>")
	)
	(segment
		(start 104.035352 -296.232326)
		(end 104.035352 -298.380912)
		(width 0.14224)
		(layer "In6.Cu")
		(net "P5E_CPU1_P0_TX_DP<8>")
	)
	(segment
		(start 104.745536 -289.800284)
		(end 104.70896 -289.82162)
		(width 0.1143)
		(layer "In6.Cu")
		(net "P5E_CPU1_P0_TX_DP<8>")
	)
	(segment
		(start 104.71658 -292.375336)
		(end 104.748076 -292.393624)
		(width 0.1143)
		(layer "In6.Cu")
		(net "P5E_CPU1_P0_TX_DP<8>")
	)
	(segment
		(start 101.622098 -364.546896)
		(end 72.609202 -364.546896)
		(width 0.14224)
		(layer "In6.Cu")
		(net "P5E_CPU1_P0_TX_DP<8>")
	)
	(segment
		(start 104.715818 -292.374828)
		(end 104.71658 -292.375336)
		(width 0.1143)
		(layer "In6.Cu")
		(net "P5E_CPU1_P0_TX_DP<8>")
	)
	(segment
		(start 104.780588 -294.639746)
		(end 104.780588 -294.64)
		(width 0.1143)
		(layer "In6.Cu")
		(net "P5E_CPU1_P0_TX_DP<8>")
	)
	(segment
		(start 104.781604 -288.15919)
		(end 104.70896 -288.201608)
		(width 0.1143)
		(layer "In6.Cu")
		(net "P5E_CPU1_P0_TX_DP<8>")
	)
	(segment
		(start 104.748076 -289.1536)
		(end 104.748838 -289.154108)
		(width 0.1143)
		(layer "In6.Cu")
		(net "P5E_CPU1_P0_TX_DP<8>")
	)
	(segment
		(start 123.705366 -344.975434)
		(end 121.182384 -351.065592)
		(width 0.14224)
		(layer "In6.Cu")
		(net "P5E_CPU1_P0_TX_DP<8>")
	)
	(segment
		(start 104.70896 -290.750752)
		(end 104.715818 -290.754816)
		(width 0.1143)
		(layer "In6.Cu")
		(net "P5E_CPU1_P0_TX_DP<8>")
	)
	(segment
		(start 56.920384 -369.079272)
		(end 56.920384 -371.2083)
		(width 0.14224)
		(layer "In6.Cu")
		(net "P5E_CPU1_P0_TX_DP<8>")
	)
	(segment
		(start 122.495564 -329.621388)
		(end 124.436632 -340.422738)
		(width 0.14224)
		(layer "In6.Cu")
		(net "P5E_CPU1_P0_TX_DP<8>")
	)
	(segment
		(start 104.748838 -289.798252)
		(end 104.748076 -289.79876)
		(width 0.1143)
		(layer "In6.Cu")
		(net "P5E_CPU1_P0_TX_DP<8>")
	)
	(segment
		(start 104.748838 -292.394132)
		(end 104.779826 -292.411912)
		(width 0.1143)
		(layer "In6.Cu")
		(net "P5E_CPU1_P0_TX_DP<8>")
	)
	(segment
		(start 104.035352 -296.203878)
		(end 104.035352 -296.232326)
		(width 0.1143)
		(layer "In6.Cu")
		(net "P5E_CPU1_P0_TX_DP<8>")
	)
	(segment
		(start 104.748076 -289.79876)
		(end 104.74706 -289.799268)
		(width 0.1143)
		(layer "In6.Cu")
		(net "P5E_CPU1_P0_TX_DP<8>")
	)
	(segment
		(start 104.081072 -295.97477)
		(end 104.081072 -296.158158)
		(width 0.1143)
		(layer "In6.Cu")
		(net "P5E_CPU1_P0_TX_DP<8>")
	)
	(segment
		(start 104.779826 -289.780472)
		(end 104.748838 -289.798252)
		(width 0.1143)
		(layer "In6.Cu")
		(net "P5E_CPU1_P0_TX_DP<8>")
	)
	(segment
		(start 104.745536 -291.420296)
		(end 104.70896 -291.441632)
		(width 0.1143)
		(layer "In6.Cu")
		(net "P5E_CPU1_P0_TX_DP<8>")
	)
	(segment
		(start 104.081072 -296.158158)
		(end 104.035352 -296.203878)
		(width 0.1143)
		(layer "In6.Cu")
		(net "P5E_CPU1_P0_TX_DP<8>")
	)
	(segment
		(start 104.71658 -289.135312)
		(end 104.748076 -289.1536)
		(width 0.1143)
		(layer "In6.Cu")
		(net "P5E_CPU1_P0_TX_DP<8>")
	)
	(segment
		(start 65.087754 -363.92612)
		(end 58.997596 -366.449864)
		(width 0.14224)
		(layer "In6.Cu")
		(net "P5E_CPU1_P0_TX_DP<8>")
	)
	(segment
		(start 104.748076 -293.038784)
		(end 104.74706 -293.039292)
		(width 0.1143)
		(layer "In6.Cu")
		(net "P5E_CPU1_P0_TX_DP<8>")
	)
	(segment
		(start 58.801508 -366.580928)
		(end 57.185306 -368.19713)
		(width 0.14224)
		(layer "In6.Cu")
		(net "P5E_CPU1_P0_TX_DP<8>")
	)
	(segment
		(start 70.645274 -363.85119)
		(end 65.464436 -363.85119)
		(width 0.14224)
		(layer "In6.Cu")
		(net "P5E_CPU1_P0_TX_DP<8>")
	)
	(segment
		(start 104.748076 -291.418772)
		(end 104.74706 -291.41928)
		(width 0.1143)
		(layer "In6.Cu")
		(net "P5E_CPU1_P0_TX_DP<8>")
	)
	(segment
		(start 104.70896 -292.370764)
		(end 104.715818 -292.374828)
		(width 0.1143)
		(layer "In6.Cu")
		(net "P5E_CPU1_P0_TX_DP<8>")
	)
	(arc
		(start 120.156986 -352.356674)
		(mid 120.109864 -352.398366)
		(end 120.059196 -352.435668)
		(width 0.14224)
		(layer "In6.Cu")
		(net "P5E_CPU1_P0_TX_DP<8>")
	)
	(arc
		(start 104.310688 -286.742632)
		(mid 104.424617 -286.875779)
		(end 104.465628 -287.046162)
		(width 0.1143)
		(layer "In6.Cu")
		(net "P5E_CPU1_P0_TX_DP<8>")
	)
	(arc
		(start 104.780588 -294.032686)
		(mid 104.935477 -294.336216)
		(end 104.780588 -294.639746)
		(width 0.1143)
		(layer "In6.Cu")
		(net "P5E_CPU1_P0_TX_DP<8>")
	)
	(arc
		(start 122.312938 -328.812144)
		(mid 122.413208 -329.214745)
		(end 122.495564 -329.621388)
		(width 0.14224)
		(layer "In6.Cu")
		(net "P5E_CPU1_P0_TX_DP<8>")
	)
	(arc
		(start 65.464436 -363.85119)
		(mid 65.272407 -363.870109)
		(end 65.087754 -363.92612)
		(width 0.14224)
		(layer "In6.Cu")
		(net "P5E_CPU1_P0_TX_DP<8>")
	)
	(arc
		(start 104.70896 -291.441632)
		(mid 104.465633 -291.906198)
		(end 104.70896 -292.370764)
		(width 0.1143)
		(layer "In6.Cu")
		(net "P5E_CPU1_P0_TX_DP<8>")
	)
	(arc
		(start 124.436632 -340.422738)
		(mid 124.459496 -340.582528)
		(end 124.470922 -340.74354)
		(width 0.14224)
		(layer "In6.Cu")
		(net "P5E_CPU1_P0_TX_DP<8>")
	)
	(arc
		(start 104.935782 -287.856422)
		(mid 104.89502 -288.026306)
		(end 104.781604 -288.15919)
		(width 0.1143)
		(layer "In6.Cu")
		(net "P5E_CPU1_P0_TX_DP<8>")
	)
	(arc
		(start 104.465628 -287.046162)
		(mid 104.530864 -287.309753)
		(end 104.7115 -287.512506)
		(width 0.1143)
		(layer "In6.Cu")
		(net "P5E_CPU1_P0_TX_DP<8>")
	)
	(arc
		(start 104.001824 -286.319214)
		(mid 104.003612 -286.330663)
		(end 104.005634 -286.342074)
		(width 0.1143)
		(layer "In6.Cu")
		(net "P5E_CPU1_P0_TX_DP<8>")
	)
	(arc
		(start 112.498886 -314.290964)
		(mid 112.623935 -314.468726)
		(end 112.757458 -314.640214)
		(width 0.14224)
		(layer "In6.Cu")
		(net "P5E_CPU1_P0_TX_DP<8>")
	)
	(arc
		(start 102.249986 -364.356142)
		(mid 101.950194 -364.498095)
		(end 101.622098 -364.546896)
		(width 0.14224)
		(layer "In6.Cu")
		(net "P5E_CPU1_P0_TX_DP<8>")
	)
	(arc
		(start 104.70896 -289.82162)
		(mid 104.465633 -290.286186)
		(end 104.70896 -290.750752)
		(width 0.1143)
		(layer "In6.Cu")
		(net "P5E_CPU1_P0_TX_DP<8>")
	)
	(arc
		(start 124.470922 -340.74354)
		(mid 124.315258 -342.900575)
		(end 123.705366 -344.975434)
		(width 0.14224)
		(layer "In6.Cu")
		(net "P5E_CPU1_P0_TX_DP<8>")
	)
	(arc
		(start 104.70896 -294.681656)
		(mid 104.630537 -294.747137)
		(end 104.565196 -294.825674)
		(width 0.1143)
		(layer "In6.Cu")
		(net "P5E_CPU1_P0_TX_DP<8>")
	)
	(arc
		(start 104.749854 -287.534858)
		(mid 104.885935 -287.670706)
		(end 104.935782 -287.856422)
		(width 0.1143)
		(layer "In6.Cu")
		(net "P5E_CPU1_P0_TX_DP<8>")
	)
	(arc
		(start 122.266456 -328.694288)
		(mid 122.292876 -328.751962)
		(end 122.312938 -328.812144)
		(width 0.14224)
		(layer "In6.Cu")
		(net "P5E_CPU1_P0_TX_DP<8>")
	)
	(arc
		(start 121.12371 -351.177606)
		(mid 120.673764 -351.794539)
		(end 120.156986 -352.356674)
		(width 0.14224)
		(layer "In6.Cu")
		(net "P5E_CPU1_P0_TX_DP<8>")
	)
	(arc
		(start 104.56545 -294.825928)
		(mid 104.491444 -294.978406)
		(end 104.465882 -295.145968)
		(width 0.1143)
		(layer "In6.Cu")
		(net "P5E_CPU1_P0_TX_DP<8>")
	)
	(arc
		(start 107.443778 -306.693316)
		(mid 107.482771 -306.775559)
		(end 107.52963 -306.85359)
		(width 0.14224)
		(layer "In6.Cu")
		(net "P5E_CPU1_P0_TX_DP<8>")
	)
	(arc
		(start 104.779826 -290.7919)
		(mid 104.931415 -291.096192)
		(end 104.779826 -291.400484)
		(width 0.1143)
		(layer "In6.Cu")
		(net "P5E_CPU1_P0_TX_DP<8>")
	)
	(arc
		(start 104.70896 -293.061644)
		(mid 104.465633 -293.52621)
		(end 104.70896 -293.990776)
		(width 0.1143)
		(layer "In6.Cu")
		(net "P5E_CPU1_P0_TX_DP<8>")
	)
	(arc
		(start 104.779826 -292.411912)
		(mid 104.931415 -292.716204)
		(end 104.779826 -293.020496)
		(width 0.1143)
		(layer "In6.Cu")
		(net "P5E_CPU1_P0_TX_DP<8>")
	)
	(arc
		(start 121.182384 -351.065592)
		(mid 121.155584 -351.122928)
		(end 121.12371 -351.177606)
		(width 0.14224)
		(layer "In6.Cu")
		(net "P5E_CPU1_P0_TX_DP<8>")
	)
	(arc
		(start 72.609202 -364.546896)
		(mid 72.330922 -364.519433)
		(end 72.063356 -364.438184)
		(width 0.14224)
		(layer "In6.Cu")
		(net "P5E_CPU1_P0_TX_DP<8>")
	)
	(arc
		(start 118.695724 -321.893438)
		(mid 118.733211 -321.944367)
		(end 118.76532 -321.998848)
		(width 0.14224)
		(layer "In6.Cu")
		(net "P5E_CPU1_P0_TX_DP<8>")
	)
	(arc
		(start 56.942736 -368.888772)
		(mid 56.926006 -368.98337)
		(end 56.920384 -369.079272)
		(width 0.14224)
		(layer "In6.Cu")
		(net "P5E_CPU1_P0_TX_DP<8>")
	)
	(arc
		(start 58.997596 -366.449864)
		(mid 58.893105 -366.505748)
		(end 58.801508 -366.580928)
		(width 0.14224)
		(layer "In6.Cu")
		(net "P5E_CPU1_P0_TX_DP<8>")
	)
	(arc
		(start 104.70896 -288.201608)
		(mid 104.465633 -288.666174)
		(end 104.70896 -289.13074)
		(width 0.1143)
		(layer "In6.Cu")
		(net "P5E_CPU1_P0_TX_DP<8>")
	)
	(arc
		(start 104.779826 -289.171888)
		(mid 104.928923 -289.47618)
		(end 104.779826 -289.780472)
		(width 0.1143)
		(layer "In6.Cu")
		(net "P5E_CPU1_P0_TX_DP<8>")
	)
	(arc
		(start 104.215438 -295.650412)
		(mid 104.116002 -295.799229)
		(end 104.081072 -295.97477)
		(width 0.1143)
		(layer "In6.Cu")
		(net "P5E_CPU1_P0_TX_DP<8>")
	)
	(arc
		(start 104.465882 -295.20134)
		(mid 104.429203 -295.385177)
		(end 104.324912 -295.540938)
		(width 0.1143)
		(layer "In6.Cu")
		(net "P5E_CPU1_P0_TX_DP<8>")
	)
	(arc
		(start 104.035352 -298.380912)
		(mid 104.043159 -298.460664)
		(end 104.06634 -298.537376)
		(width 0.14224)
		(layer "In6.Cu")
		(net "P5E_CPU1_P0_TX_DP<8>")
	)
	(arc
		(start 104.005634 -286.342074)
		(mid 104.087067 -286.544472)
		(end 104.23906 -286.700976)
		(width 0.1143)
		(layer "In6.Cu")
		(net "P5E_CPU1_P0_TX_DP<8>")
	)
	(arc
		(start 57.185306 -368.19713)
		(mid 57.1005 -368.309374)
		(end 57.049416 -368.440462)
		(width 0.14224)
		(layer "In6.Cu")
		(net "P5E_CPU1_P0_TX_DP<8>")
	)
	(segment
		(start 55.198264 -374.93702)
		(end 54.902354 -375.23293)
		(width 0.12954)
		(layer "F.Cu")
		(net "P5E_CPU1_P0_TX_DP<7>")
	)
	(segment
		(start 55.198264 -374.23344)
		(end 55.198264 -374.93702)
		(width 0.12954)
		(layer "F.Cu")
		(net "P5E_CPU1_P0_TX_DP<7>")
	)
	(segment
		(start 104.08793 -284.35046)
		(end 103.621078 -284.616398)
		(width 0.12954)
		(layer "F.Cu")
		(net "P5E_CPU1_P0_TX_DP<7>")
	)
	(segment
		(start 54.927754 -373.96293)
		(end 55.198264 -374.23344)
		(width 0.12954)
		(layer "F.Cu")
		(net "P5E_CPU1_P0_TX_DP<7>")
	)
	(segment
		(start 103.065834 -295.92524)
		(end 103.065834 -296.20718)
		(width 0.1143)
		(layer "In6.Cu")
		(net "P5E_CPU1_P0_TX_DP<7>")
	)
	(segment
		(start 103.299006 -286.700976)
		(end 103.37165 -286.743394)
		(width 0.1143)
		(layer "In6.Cu")
		(net "P5E_CPU1_P0_TX_DP<7>")
	)
	(segment
		(start 72.16902 -363.45876)
		(end 70.938898 -362.948982)
		(width 0.14224)
		(layer "In6.Cu")
		(net "P5E_CPU1_P0_TX_DP<7>")
	)
	(segment
		(start 101.316028 -363.581696)
		(end 72.787256 -363.581696)
		(width 0.14224)
		(layer "In6.Cu")
		(net "P5E_CPU1_P0_TX_DP<7>")
	)
	(segment
		(start 103.338122 -285.748984)
		(end 103.337106 -285.749492)
		(width 0.1143)
		(layer "In6.Cu")
		(net "P5E_CPU1_P0_TX_DP<7>")
	)
	(segment
		(start 103.065834 -296.20718)
		(end 103.020114 -296.2529)
		(width 0.1143)
		(layer "In6.Cu")
		(net "P5E_CPU1_P0_TX_DP<7>")
	)
	(segment
		(start 118.882414 -352.076512)
		(end 101.954838 -363.387894)
		(width 0.14224)
		(layer "In6.Cu")
		(net "P5E_CPU1_P0_TX_DP<7>")
	)
	(segment
		(start 103.337106 -285.749492)
		(end 103.335582 -285.750508)
		(width 0.1143)
		(layer "In6.Cu")
		(net "P5E_CPU1_P0_TX_DP<7>")
	)
	(segment
		(start 103.7717 -293.992554)
		(end 103.808022 -294.013636)
		(width 0.1143)
		(layer "In6.Cu")
		(net "P5E_CPU1_P0_TX_DP<7>")
	)
	(segment
		(start 103.338884 -285.748476)
		(end 103.338122 -285.748984)
		(width 0.1143)
		(layer "In6.Cu")
		(net "P5E_CPU1_P0_TX_DP<7>")
	)
	(segment
		(start 55.17134 -373.719344)
		(end 54.927754 -373.96293)
		(width 0.14224)
		(layer "In6.Cu")
		(net "P5E_CPU1_P0_TX_DP<7>")
	)
	(segment
		(start 103.787448 -288.190686)
		(end 103.786686 -288.191194)
		(width 0.1143)
		(layer "In6.Cu")
		(net "P5E_CPU1_P0_TX_DP<7>")
	)
	(segment
		(start 58.38317 -365.679736)
		(end 57.624218 -366.438434)
		(width 0.14224)
		(layer "In6.Cu")
		(net "P5E_CPU1_P0_TX_DP<7>")
	)
	(segment
		(start 103.525828 -285.42742)
		(end 103.525574 -285.428944)
		(width 0.1143)
		(layer "In6.Cu")
		(net "P5E_CPU1_P0_TX_DP<7>")
	)
	(segment
		(start 70.781926 -362.917994)
		(end 65.401444 -362.917994)
		(width 0.14224)
		(layer "In6.Cu")
		(net "P5E_CPU1_P0_TX_DP<7>")
	)
	(segment
		(start 103.839772 -284.92069)
		(end 103.76789 -284.962092)
		(width 0.1143)
		(layer "In6.Cu")
		(net "P5E_CPU1_P0_TX_DP<7>")
	)
	(segment
		(start 103.76789 -284.962092)
		(end 103.75646 -284.970728)
		(width 0.1143)
		(layer "In6.Cu")
		(net "P5E_CPU1_P0_TX_DP<7>")
	)
	(segment
		(start 103.446834 -295.411906)
		(end 103.158544 -295.70045)
		(width 0.1143)
		(layer "In6.Cu")
		(net "P5E_CPU1_P0_TX_DP<7>")
	)
	(segment
		(start 103.020114 -296.281348)
		(end 103.020114 -298.366434)
		(width 0.14224)
		(layer "In6.Cu")
		(net "P5E_CPU1_P0_TX_DP<7>")
	)
	(segment
		(start 103.774494 -287.514284)
		(end 103.808022 -287.533842)
		(width 0.1143)
		(layer "In6.Cu")
		(net "P5E_CPU1_P0_TX_DP<7>")
	)
	(segment
		(start 55.218584 -369.847368)
		(end 55.218584 -373.605298)
		(width 0.14224)
		(layer "In6.Cu")
		(net "P5E_CPU1_P0_TX_DP<7>")
	)
	(segment
		(start 103.839772 -289.780472)
		(end 103.808022 -289.79876)
		(width 0.1143)
		(layer "In6.Cu")
		(net "P5E_CPU1_P0_TX_DP<7>")
	)
	(segment
		(start 112.156494 -315.482986)
		(end 118.029228 -322.639436)
		(width 0.14224)
		(layer "In6.Cu")
		(net "P5E_CPU1_P0_TX_DP<7>")
	)
	(segment
		(start 123.349512 -342.394032)
		(end 123.02871 -344.009218)
		(width 0.14224)
		(layer "In6.Cu")
		(net "P5E_CPU1_P0_TX_DP<7>")
	)
	(segment
		(start 122.99188 -344.130122)
		(end 120.533414 -350.064832)
		(width 0.14224)
		(layer "In6.Cu")
		(net "P5E_CPU1_P0_TX_DP<7>")
	)
	(segment
		(start 103.808022 -289.79876)
		(end 103.7717 -289.819842)
		(width 0.1143)
		(layer "In6.Cu")
		(net "P5E_CPU1_P0_TX_DP<7>")
	)
	(segment
		(start 103.839772 -294.640508)
		(end 103.76789 -294.68191)
		(width 0.1143)
		(layer "In6.Cu")
		(net "P5E_CPU1_P0_TX_DP<7>")
	)
	(segment
		(start 103.446834 -295.411652)
		(end 103.446834 -295.411906)
		(width 0.1143)
		(layer "In6.Cu")
		(net "P5E_CPU1_P0_TX_DP<7>")
	)
	(segment
		(start 103.335582 -285.750508)
		(end 103.299006 -285.771844)
		(width 0.1143)
		(layer "In6.Cu")
		(net "P5E_CPU1_P0_TX_DP<7>")
	)
	(segment
		(start 103.808022 -294.013636)
		(end 103.839772 -294.031924)
		(width 0.1143)
		(layer "In6.Cu")
		(net "P5E_CPU1_P0_TX_DP<7>")
	)
	(segment
		(start 64.725804 -363.052106)
		(end 58.38317 -365.679736)
		(width 0.14224)
		(layer "In6.Cu")
		(net "P5E_CPU1_P0_TX_DP<7>")
	)
	(segment
		(start 103.808022 -293.038784)
		(end 103.7717 -293.059866)
		(width 0.1143)
		(layer "In6.Cu")
		(net "P5E_CPU1_P0_TX_DP<7>")
	)
	(segment
		(start 118.099332 -322.744846)
		(end 121.35231 -328.969878)
		(width 0.14224)
		(layer "In6.Cu")
		(net "P5E_CPU1_P0_TX_DP<7>")
	)
	(segment
		(start 103.786686 -289.141154)
		(end 103.839772 -289.171888)
		(width 0.1143)
		(layer "In6.Cu")
		(net "P5E_CPU1_P0_TX_DP<7>")
	)
	(segment
		(start 103.839772 -293.020496)
		(end 103.808022 -293.038784)
		(width 0.1143)
		(layer "In6.Cu")
		(net "P5E_CPU1_P0_TX_DP<7>")
	)
	(segment
		(start 103.808022 -291.418772)
		(end 103.7717 -291.439854)
		(width 0.1143)
		(layer "In6.Cu")
		(net "P5E_CPU1_P0_TX_DP<7>")
	)
	(segment
		(start 103.808022 -292.393624)
		(end 103.839772 -292.411912)
		(width 0.1143)
		(layer "In6.Cu")
		(net "P5E_CPU1_P0_TX_DP<7>")
	)
	(segment
		(start 103.525828 -295.14419)
		(end 103.525828 -295.16578)
		(width 0.1143)
		(layer "In6.Cu")
		(net "P5E_CPU1_P0_TX_DP<7>")
	)
	(segment
		(start 103.369872 -285.730696)
		(end 103.338884 -285.748476)
		(width 0.1143)
		(layer "In6.Cu")
		(net "P5E_CPU1_P0_TX_DP<7>")
	)
	(segment
		(start 103.839772 -291.400484)
		(end 103.808022 -291.418772)
		(width 0.1143)
		(layer "In6.Cu")
		(net "P5E_CPU1_P0_TX_DP<7>")
	)
	(segment
		(start 106.67873 -307.285644)
		(end 112.156494 -315.482986)
		(width 0.14224)
		(layer "In6.Cu")
		(net "P5E_CPU1_P0_TX_DP<7>")
	)
	(segment
		(start 103.525828 -285.421832)
		(end 103.525828 -285.42742)
		(width 0.1143)
		(layer "In6.Cu")
		(net "P5E_CPU1_P0_TX_DP<7>")
	)
	(segment
		(start 103.621078 -284.616398)
		(end 103.91902 -284.616398)
		(width 0.1143)
		(layer "In6.Cu")
		(net "P5E_CPU1_P0_TX_DP<7>")
	)
	(segment
		(start 103.053134 -298.531788)
		(end 106.67873 -307.285644)
		(width 0.14224)
		(layer "In6.Cu")
		(net "P5E_CPU1_P0_TX_DP<7>")
	)
	(segment
		(start 103.020114 -296.2529)
		(end 103.020114 -296.281348)
		(width 0.1143)
		(layer "In6.Cu")
		(net "P5E_CPU1_P0_TX_DP<7>")
	)
	(segment
		(start 121.579386 -329.848464)
		(end 123.312936 -339.494876)
		(width 0.14224)
		(layer "In6.Cu")
		(net "P5E_CPU1_P0_TX_DP<7>")
	)
	(segment
		(start 120.533414 -350.064832)
		(end 120.533414 -350.065086)
		(width 0.14224)
		(layer "In6.Cu")
		(net "P5E_CPU1_P0_TX_DP<7>")
	)
	(segment
		(start 57.624218 -366.438434)
		(end 57.447688 -366.511586)
		(width 0.14224)
		(layer "In6.Cu")
		(net "P5E_CPU1_P0_TX_DP<7>")
	)
	(segment
		(start 103.7717 -292.372542)
		(end 103.808022 -292.393624)
		(width 0.1143)
		(layer "In6.Cu")
		(net "P5E_CPU1_P0_TX_DP<7>")
	)
	(segment
		(start 103.808022 -287.533842)
		(end 103.839772 -287.55213)
		(width 0.1143)
		(layer "In6.Cu")
		(net "P5E_CPU1_P0_TX_DP<7>")
	)
	(segment
		(start 103.84155 -288.15919)
		(end 103.787448 -288.190686)
		(width 0.1143)
		(layer "In6.Cu")
		(net "P5E_CPU1_P0_TX_DP<7>")
	)
	(segment
		(start 103.91902 -284.616398)
		(end 103.98887 -284.686248)
		(width 0.1143)
		(layer "In6.Cu")
		(net "P5E_CPU1_P0_TX_DP<7>")
	)
	(segment
		(start 103.808022 -290.773612)
		(end 103.839772 -290.7919)
		(width 0.1143)
		(layer "In6.Cu")
		(net "P5E_CPU1_P0_TX_DP<7>")
	)
	(segment
		(start 103.7717 -290.75253)
		(end 103.808022 -290.773612)
		(width 0.1143)
		(layer "In6.Cu")
		(net "P5E_CPU1_P0_TX_DP<7>")
	)
	(arc
		(start 103.759254 -289.828478)
		(mid 103.527786 -290.286186)
		(end 103.759254 -290.743894)
		(width 0.1143)
		(layer "In6.Cu")
		(net "P5E_CPU1_P0_TX_DP<7>")
	)
	(arc
		(start 101.954838 -363.387894)
		(mid 101.649802 -363.532167)
		(end 101.316028 -363.581696)
		(width 0.14224)
		(layer "In6.Cu")
		(net "P5E_CPU1_P0_TX_DP<7>")
	)
	(arc
		(start 103.76789 -294.68191)
		(mid 103.592273 -294.884462)
		(end 103.525828 -295.14419)
		(width 0.1143)
		(layer "In6.Cu")
		(net "P5E_CPU1_P0_TX_DP<7>")
	)
	(arc
		(start 103.525574 -285.428944)
		(mid 103.481035 -285.597002)
		(end 103.369872 -285.730696)
		(width 0.1143)
		(layer "In6.Cu")
		(net "P5E_CPU1_P0_TX_DP<7>")
	)
	(arc
		(start 103.98887 -284.686248)
		(mid 103.936821 -284.817767)
		(end 103.839772 -284.92069)
		(width 0.1143)
		(layer "In6.Cu")
		(net "P5E_CPU1_P0_TX_DP<7>")
	)
	(arc
		(start 103.7717 -291.439854)
		(mid 103.764551 -291.444754)
		(end 103.757476 -291.44976)
		(width 0.1143)
		(layer "In6.Cu")
		(net "P5E_CPU1_P0_TX_DP<7>")
	)
	(arc
		(start 103.525828 -295.16578)
		(mid 103.521691 -295.2341)
		(end 103.509318 -295.301416)
		(width 0.1143)
		(layer "In6.Cu")
		(net "P5E_CPU1_P0_TX_DP<7>")
	)
	(arc
		(start 103.525828 -287.05048)
		(mid 103.589805 -287.30311)
		(end 103.757476 -287.5026)
		(width 0.1143)
		(layer "In6.Cu")
		(net "P5E_CPU1_P0_TX_DP<7>")
	)
	(arc
		(start 103.7717 -289.819842)
		(mid 103.765448 -289.824119)
		(end 103.759254 -289.828478)
		(width 0.1143)
		(layer "In6.Cu")
		(net "P5E_CPU1_P0_TX_DP<7>")
	)
	(arc
		(start 123.02871 -344.009218)
		(mid 123.013273 -344.070577)
		(end 122.99188 -344.130122)
		(width 0.14224)
		(layer "In6.Cu")
		(net "P5E_CPU1_P0_TX_DP<7>")
	)
	(arc
		(start 103.509318 -295.301416)
		(mid 103.485606 -295.360803)
		(end 103.446834 -295.411652)
		(width 0.1143)
		(layer "In6.Cu")
		(net "P5E_CPU1_P0_TX_DP<7>")
	)
	(arc
		(start 103.839772 -292.411912)
		(mid 103.9957 -292.716204)
		(end 103.839772 -293.020496)
		(width 0.1143)
		(layer "In6.Cu")
		(net "P5E_CPU1_P0_TX_DP<7>")
	)
	(arc
		(start 118.029228 -322.639436)
		(mid 118.066992 -322.690337)
		(end 118.099332 -322.744846)
		(width 0.14224)
		(layer "In6.Cu")
		(net "P5E_CPU1_P0_TX_DP<7>")
	)
	(arc
		(start 103.525828 -287.046162)
		(mid 103.525823 -287.048321)
		(end 103.525828 -287.05048)
		(width 0.1143)
		(layer "In6.Cu")
		(net "P5E_CPU1_P0_TX_DP<7>")
	)
	(arc
		(start 103.75646 -293.070534)
		(mid 103.531289 -293.52621)
		(end 103.75646 -293.981886)
		(width 0.1143)
		(layer "In6.Cu")
		(net "P5E_CPU1_P0_TX_DP<7>")
	)
	(arc
		(start 103.757476 -287.5026)
		(mid 103.765933 -287.508518)
		(end 103.774494 -287.514284)
		(width 0.1143)
		(layer "In6.Cu")
		(net "P5E_CPU1_P0_TX_DP<7>")
	)
	(arc
		(start 70.938898 -362.948982)
		(mid 70.86194 -362.925755)
		(end 70.781926 -362.917994)
		(width 0.14224)
		(layer "In6.Cu")
		(net "P5E_CPU1_P0_TX_DP<7>")
	)
	(arc
		(start 103.995728 -287.856422)
		(mid 103.954966 -288.026306)
		(end 103.84155 -288.15919)
		(width 0.1143)
		(layer "In6.Cu")
		(net "P5E_CPU1_P0_TX_DP<7>")
	)
	(arc
		(start 103.020114 -298.366434)
		(mid 103.028503 -298.450732)
		(end 103.053134 -298.531788)
		(width 0.14224)
		(layer "In6.Cu")
		(net "P5E_CPU1_P0_TX_DP<7>")
	)
	(arc
		(start 103.839772 -290.7919)
		(mid 103.9957 -291.096192)
		(end 103.839772 -291.400484)
		(width 0.1143)
		(layer "In6.Cu")
		(net "P5E_CPU1_P0_TX_DP<7>")
	)
	(arc
		(start 123.312936 -339.494876)
		(mid 123.438468 -340.879979)
		(end 123.369832 -342.269064)
		(width 0.14224)
		(layer "In6.Cu")
		(net "P5E_CPU1_P0_TX_DP<7>")
	)
	(arc
		(start 72.787256 -363.581696)
		(mid 72.472088 -363.550659)
		(end 72.16902 -363.45876)
		(width 0.14224)
		(layer "In6.Cu")
		(net "P5E_CPU1_P0_TX_DP<7>")
	)
	(arc
		(start 121.399808 -329.08748)
		(mid 121.499844 -329.465554)
		(end 121.579386 -329.848464)
		(width 0.14224)
		(layer "In6.Cu")
		(net "P5E_CPU1_P0_TX_DP<7>")
	)
	(arc
		(start 103.75646 -284.970728)
		(mid 103.586838 -285.168514)
		(end 103.525828 -285.421832)
		(width 0.1143)
		(layer "In6.Cu")
		(net "P5E_CPU1_P0_TX_DP<7>")
	)
	(arc
		(start 121.35231 -328.969878)
		(mid 121.378938 -329.027515)
		(end 121.399808 -329.08748)
		(width 0.14224)
		(layer "In6.Cu")
		(net "P5E_CPU1_P0_TX_DP<7>")
	)
	(arc
		(start 103.37165 -286.743394)
		(mid 103.485057 -286.876283)
		(end 103.525828 -287.046162)
		(width 0.1143)
		(layer "In6.Cu")
		(net "P5E_CPU1_P0_TX_DP<7>")
	)
	(arc
		(start 120.533414 -350.065086)
		(mid 119.857081 -351.193239)
		(end 118.882414 -352.076512)
		(width 0.14224)
		(layer "In6.Cu")
		(net "P5E_CPU1_P0_TX_DP<7>")
	)
	(arc
		(start 103.757476 -292.362636)
		(mid 103.76455 -292.367643)
		(end 103.7717 -292.372542)
		(width 0.1143)
		(layer "In6.Cu")
		(net "P5E_CPU1_P0_TX_DP<7>")
	)
	(arc
		(start 103.158544 -295.70045)
		(mid 103.089851 -295.803629)
		(end 103.065834 -295.92524)
		(width 0.1143)
		(layer "In6.Cu")
		(net "P5E_CPU1_P0_TX_DP<7>")
	)
	(arc
		(start 103.75646 -293.981886)
		(mid 103.764036 -293.987282)
		(end 103.7717 -293.992554)
		(width 0.1143)
		(layer "In6.Cu")
		(net "P5E_CPU1_P0_TX_DP<7>")
	)
	(arc
		(start 103.757476 -291.44976)
		(mid 103.530093 -291.906198)
		(end 103.757476 -292.362636)
		(width 0.1143)
		(layer "In6.Cu")
		(net "P5E_CPU1_P0_TX_DP<7>")
	)
	(arc
		(start 103.839772 -287.55213)
		(mid 103.954448 -287.685464)
		(end 103.995728 -287.856422)
		(width 0.1143)
		(layer "In6.Cu")
		(net "P5E_CPU1_P0_TX_DP<7>")
	)
	(arc
		(start 123.369832 -342.269064)
		(mid 123.360866 -342.331742)
		(end 123.349512 -342.394032)
		(width 0.14224)
		(layer "In6.Cu")
		(net "P5E_CPU1_P0_TX_DP<7>")
	)
	(arc
		(start 103.839772 -294.031924)
		(mid 103.9957 -294.336216)
		(end 103.839772 -294.640508)
		(width 0.1143)
		(layer "In6.Cu")
		(net "P5E_CPU1_P0_TX_DP<7>")
	)
	(arc
		(start 57.447688 -366.511586)
		(mid 55.827196 -367.841375)
		(end 55.218584 -369.847368)
		(width 0.14224)
		(layer "In6.Cu")
		(net "P5E_CPU1_P0_TX_DP<7>")
	)
	(arc
		(start 103.786686 -288.191194)
		(mid 103.513135 -288.666174)
		(end 103.786686 -289.141154)
		(width 0.1143)
		(layer "In6.Cu")
		(net "P5E_CPU1_P0_TX_DP<7>")
	)
	(arc
		(start 103.839772 -289.171888)
		(mid 103.9957 -289.47618)
		(end 103.839772 -289.780472)
		(width 0.1143)
		(layer "In6.Cu")
		(net "P5E_CPU1_P0_TX_DP<7>")
	)
	(arc
		(start 103.759254 -290.743894)
		(mid 103.765448 -290.748254)
		(end 103.7717 -290.75253)
		(width 0.1143)
		(layer "In6.Cu")
		(net "P5E_CPU1_P0_TX_DP<7>")
	)
	(arc
		(start 103.299006 -285.771844)
		(mid 103.055679 -286.23641)
		(end 103.299006 -286.700976)
		(width 0.1143)
		(layer "In6.Cu")
		(net "P5E_CPU1_P0_TX_DP<7>")
	)
	(arc
		(start 103.7717 -293.059866)
		(mid 103.764036 -293.065137)
		(end 103.75646 -293.070534)
		(width 0.1143)
		(layer "In6.Cu")
		(net "P5E_CPU1_P0_TX_DP<7>")
	)
	(arc
		(start 55.218584 -373.605298)
		(mid 55.206307 -373.667021)
		(end 55.17134 -373.719344)
		(width 0.14224)
		(layer "In6.Cu")
		(net "P5E_CPU1_P0_TX_DP<7>")
	)
	(arc
		(start 65.401444 -362.917994)
		(mid 65.057017 -362.951769)
		(end 64.725804 -363.052106)
		(width 0.14224)
		(layer "In6.Cu")
		(net "P5E_CPU1_P0_TX_DP<7>")
	)
	(segment
		(start 101.268022 -281.110436)
		(end 100.80117 -281.376374)
		(width 0.12954)
		(layer "F.Cu")
		(net "P5E_CPU1_P0_TX_DP<6>")
	)
	(segment
		(start 51.794664 -369.30584)
		(end 51.794664 -370.00942)
		(width 0.12954)
		(layer "F.Cu")
		(net "P5E_CPU1_P0_TX_DP<6>")
	)
	(segment
		(start 51.794664 -370.00942)
		(end 51.498754 -370.30533)
		(width 0.12954)
		(layer "F.Cu")
		(net "P5E_CPU1_P0_TX_DP<6>")
	)
	(segment
		(start 51.524154 -369.03533)
		(end 51.794664 -369.30584)
		(width 0.12954)
		(layer "F.Cu")
		(net "P5E_CPU1_P0_TX_DP<6>")
	)
	(segment
		(start 102.585774 -295.146222)
		(end 102.585774 -295.34739)
		(width 0.1143)
		(layer "In6.Cu")
		(net "P5E_CPU1_P0_TX_DP<6>")
	)
	(segment
		(start 102.390448 -285.753302)
		(end 102.388416 -285.754572)
		(width 0.1143)
		(layer "In6.Cu")
		(net "P5E_CPU1_P0_TX_DP<6>")
	)
	(segment
		(start 57.884822 -364.85449)
		(end 57.10174 -365.637826)
		(width 0.14224)
		(layer "In6.Cu")
		(net "P5E_CPU1_P0_TX_DP<6>")
	)
	(segment
		(start 102.395528 -284.130496)
		(end 102.394512 -284.131004)
		(width 0.1143)
		(layer "In6.Cu")
		(net "P5E_CPU1_P0_TX_DP<6>")
	)
	(segment
		(start 64.68364 -362.044996)
		(end 57.884822 -364.85449)
		(width 0.14224)
		(layer "In6.Cu")
		(net "P5E_CPU1_P0_TX_DP<6>")
	)
	(segment
		(start 105.897426 -307.821076)
		(end 111.221266 -315.789056)
		(width 0.14224)
		(layer "In6.Cu")
		(net "P5E_CPU1_P0_TX_DP<6>")
	)
	(segment
		(start 102.075234 -296.549826)
		(end 102.075234 -298.49191)
		(width 0.14224)
		(layer "In6.Cu")
		(net "P5E_CPU1_P0_TX_DP<6>")
	)
	(segment
		(start 102.898702 -294.641016)
		(end 102.829106 -294.681656)
		(width 0.1143)
		(layer "In6.Cu")
		(net "P5E_CPU1_P0_TX_DP<6>")
	)
	(segment
		(start 102.898702 -291.400992)
		(end 102.829106 -291.441632)
		(width 0.1143)
		(layer "In6.Cu")
		(net "P5E_CPU1_P0_TX_DP<6>")
	)
	(segment
		(start 102.392226 -285.752286)
		(end 102.390448 -285.753302)
		(width 0.1143)
		(layer "In6.Cu")
		(net "P5E_CPU1_P0_TX_DP<6>")
	)
	(segment
		(start 102.405942 -283.488384)
		(end 102.408482 -283.489654)
		(width 0.1143)
		(layer "In6.Cu")
		(net "P5E_CPU1_P0_TX_DP<6>")
	)
	(segment
		(start 102.404672 -283.487622)
		(end 102.405942 -283.488384)
		(width 0.1143)
		(layer "In6.Cu")
		(net "P5E_CPU1_P0_TX_DP<6>")
	)
	(segment
		(start 102.075234 -296.521378)
		(end 102.075234 -296.549826)
		(width 0.1143)
		(layer "In6.Cu")
		(net "P5E_CPU1_P0_TX_DP<6>")
	)
	(segment
		(start 102.120954 -296.475658)
		(end 102.075234 -296.521378)
		(width 0.1143)
		(layer "In6.Cu")
		(net "P5E_CPU1_P0_TX_DP<6>")
	)
	(segment
		(start 102.366572 -283.465524)
		(end 102.398068 -283.483812)
		(width 0.1143)
		(layer "In6.Cu")
		(net "P5E_CPU1_P0_TX_DP<6>")
	)
	(segment
		(start 102.358952 -285.080964)
		(end 102.397052 -285.103316)
		(width 0.1143)
		(layer "In6.Cu")
		(net "P5E_CPU1_P0_TX_DP<6>")
	)
	(segment
		(start 101.099112 -281.376374)
		(end 101.181916 -281.459178)
		(width 0.1143)
		(layer "In6.Cu")
		(net "P5E_CPU1_P0_TX_DP<6>")
	)
	(segment
		(start 102.398068 -284.128972)
		(end 102.397052 -284.12948)
		(width 0.1143)
		(layer "In6.Cu")
		(net "P5E_CPU1_P0_TX_DP<6>")
	)
	(segment
		(start 102.395528 -285.750508)
		(end 102.394512 -285.751016)
		(width 0.1143)
		(layer "In6.Cu")
		(net "P5E_CPU1_P0_TX_DP<6>")
	)
	(segment
		(start 102.900734 -288.159952)
		(end 102.868222 -288.178748)
		(width 0.1143)
		(layer "In6.Cu")
		(net "P5E_CPU1_P0_TX_DP<6>")
	)
	(segment
		(start 101.890576 -282.651962)
		(end 101.957378 -282.691078)
		(width 0.1143)
		(layer "In6.Cu")
		(net "P5E_CPU1_P0_TX_DP<6>")
	)
	(segment
		(start 102.397052 -285.103316)
		(end 102.398068 -285.103824)
		(width 0.1143)
		(layer "In6.Cu")
		(net "P5E_CPU1_P0_TX_DP<6>")
	)
	(segment
		(start 102.868222 -288.178748)
		(end 102.829106 -288.201608)
		(width 0.1143)
		(layer "In6.Cu")
		(net "P5E_CPU1_P0_TX_DP<6>")
	)
	(segment
		(start 102.358952 -283.460952)
		(end 102.36581 -283.465016)
		(width 0.1143)
		(layer "In6.Cu")
		(net "P5E_CPU1_P0_TX_DP<6>")
	)
	(segment
		(start 102.548182 -295.43756)
		(end 102.267258 -295.718484)
		(width 0.1143)
		(layer "In6.Cu")
		(net "P5E_CPU1_P0_TX_DP<6>")
	)
	(segment
		(start 102.4001 -285.105094)
		(end 102.429818 -285.122112)
		(width 0.1143)
		(layer "In6.Cu")
		(net "P5E_CPU1_P0_TX_DP<6>")
	)
	(segment
		(start 72.439022 -362.557314)
		(end 71.202042 -362.044996)
		(width 0.14224)
		(layer "In6.Cu")
		(net "P5E_CPU1_P0_TX_DP<6>")
	)
	(segment
		(start 102.393242 -285.751778)
		(end 102.392226 -285.752286)
		(width 0.1143)
		(layer "In6.Cu")
		(net "P5E_CPU1_P0_TX_DP<6>")
	)
	(segment
		(start 102.4001 -285.747714)
		(end 102.39883 -285.748476)
		(width 0.1143)
		(layer "In6.Cu")
		(net "P5E_CPU1_P0_TX_DP<6>")
	)
	(segment
		(start 102.402386 -283.486352)
		(end 102.40391 -283.487114)
		(width 0.1143)
		(layer "In6.Cu")
		(net "P5E_CPU1_P0_TX_DP<6>")
	)
	(segment
		(start 102.4001 -284.127702)
		(end 102.39883 -284.128464)
		(width 0.1143)
		(layer "In6.Cu")
		(net "P5E_CPU1_P0_TX_DP<6>")
	)
	(segment
		(start 102.829106 -290.750752)
		(end 102.898702 -290.791392)
		(width 0.1143)
		(layer "In6.Cu")
		(net "P5E_CPU1_P0_TX_DP<6>")
	)
	(segment
		(start 70.851014 -361.975146)
		(end 65.034922 -361.975146)
		(width 0.14224)
		(layer "In6.Cu")
		(net "P5E_CPU1_P0_TX_DP<6>")
	)
	(segment
		(start 57.10174 -365.637826)
		(end 52.218082 -367.66119)
		(width 0.14224)
		(layer "In6.Cu")
		(net "P5E_CPU1_P0_TX_DP<6>")
	)
	(segment
		(start 102.36581 -283.465016)
		(end 102.366572 -283.465524)
		(width 0.1143)
		(layer "In6.Cu")
		(net "P5E_CPU1_P0_TX_DP<6>")
	)
	(segment
		(start 102.398068 -285.748984)
		(end 102.397052 -285.749492)
		(width 0.1143)
		(layer "In6.Cu")
		(net "P5E_CPU1_P0_TX_DP<6>")
	)
	(segment
		(start 102.898702 -289.78098)
		(end 102.829106 -289.82162)
		(width 0.1143)
		(layer "In6.Cu")
		(net "P5E_CPU1_P0_TX_DP<6>")
	)
	(segment
		(start 102.831646 -287.512506)
		(end 102.898702 -287.551622)
		(width 0.1143)
		(layer "In6.Cu")
		(net "P5E_CPU1_P0_TX_DP<6>")
	)
	(segment
		(start 102.40391 -283.487114)
		(end 102.404672 -283.487622)
		(width 0.1143)
		(layer "In6.Cu")
		(net "P5E_CPU1_P0_TX_DP<6>")
	)
	(segment
		(start 102.392226 -284.132274)
		(end 102.390448 -284.13329)
		(width 0.1143)
		(layer "In6.Cu")
		(net "P5E_CPU1_P0_TX_DP<6>")
	)
	(segment
		(start 102.388416 -285.754572)
		(end 102.38613 -285.755842)
		(width 0.1143)
		(layer "In6.Cu")
		(net "P5E_CPU1_P0_TX_DP<6>")
	)
	(segment
		(start 102.829106 -293.990776)
		(end 102.898702 -294.031416)
		(width 0.1143)
		(layer "In6.Cu")
		(net "P5E_CPU1_P0_TX_DP<6>")
	)
	(segment
		(start 102.38613 -285.755842)
		(end 102.358952 -285.771844)
		(width 0.1143)
		(layer "In6.Cu")
		(net "P5E_CPU1_P0_TX_DP<6>")
	)
	(segment
		(start 102.398068 -283.483812)
		(end 102.39883 -283.48432)
		(width 0.1143)
		(layer "In6.Cu")
		(net "P5E_CPU1_P0_TX_DP<6>")
	)
	(segment
		(start 102.121208 -298.72305)
		(end 105.85958 -307.750464)
		(width 0.14224)
		(layer "In6.Cu")
		(net "P5E_CPU1_P0_TX_DP<6>")
	)
	(segment
		(start 120.667272 -330.071984)
		(end 122.302778 -339.171534)
		(width 0.14224)
		(layer "In6.Cu")
		(net "P5E_CPU1_P0_TX_DP<6>")
	)
	(segment
		(start 102.39883 -284.128464)
		(end 102.398068 -284.128972)
		(width 0.1143)
		(layer "In6.Cu")
		(net "P5E_CPU1_P0_TX_DP<6>")
	)
	(segment
		(start 102.397052 -284.12948)
		(end 102.395528 -284.130496)
		(width 0.1143)
		(layer "In6.Cu")
		(net "P5E_CPU1_P0_TX_DP<6>")
	)
	(segment
		(start 52.218082 -367.66119)
		(end 52.02809 -367.851182)
		(width 0.14224)
		(layer "In6.Cu")
		(net "P5E_CPU1_P0_TX_DP<6>")
	)
	(segment
		(start 51.814984 -368.7445)
		(end 51.524154 -369.03533)
		(width 0.14224)
		(layer "In6.Cu")
		(net "P5E_CPU1_P0_TX_DP<6>")
	)
	(segment
		(start 102.429818 -284.110684)
		(end 102.4001 -284.127702)
		(width 0.1143)
		(layer "In6.Cu")
		(net "P5E_CPU1_P0_TX_DP<6>")
	)
	(segment
		(start 111.586772 -316.281562)
		(end 117.244114 -323.175376)
		(width 0.14224)
		(layer "In6.Cu")
		(net "P5E_CPU1_P0_TX_DP<6>")
	)
	(segment
		(start 101.181916 -281.47772)
		(end 101.18598 -281.481784)
		(width 0.1143)
		(layer "In6.Cu")
		(net "P5E_CPU1_P0_TX_DP<6>")
	)
	(segment
		(start 117.304312 -323.280278)
		(end 120.445276 -329.28941)
		(width 0.14224)
		(layer "In6.Cu")
		(net "P5E_CPU1_P0_TX_DP<6>")
	)
	(segment
		(start 100.80117 -281.376374)
		(end 101.099112 -281.376374)
		(width 0.1143)
		(layer "In6.Cu")
		(net "P5E_CPU1_P0_TX_DP<6>")
	)
	(segment
		(start 102.397052 -285.749492)
		(end 102.395528 -285.750508)
		(width 0.1143)
		(layer "In6.Cu")
		(net "P5E_CPU1_P0_TX_DP<6>")
	)
	(segment
		(start 102.898702 -293.021004)
		(end 102.829106 -293.061644)
		(width 0.1143)
		(layer "In6.Cu")
		(net "P5E_CPU1_P0_TX_DP<6>")
	)
	(segment
		(start 102.829106 -289.13074)
		(end 102.898702 -289.17138)
		(width 0.1143)
		(layer "In6.Cu")
		(net "P5E_CPU1_P0_TX_DP<6>")
	)
	(segment
		(start 102.390448 -284.13329)
		(end 102.388416 -284.13456)
		(width 0.1143)
		(layer "In6.Cu")
		(net "P5E_CPU1_P0_TX_DP<6>")
	)
	(segment
		(start 102.394512 -285.751016)
		(end 102.393242 -285.751778)
		(width 0.1143)
		(layer "In6.Cu")
		(net "P5E_CPU1_P0_TX_DP<6>")
	)
	(segment
		(start 102.829106 -292.370764)
		(end 102.898702 -292.411404)
		(width 0.1143)
		(layer "In6.Cu")
		(net "P5E_CPU1_P0_TX_DP<6>")
	)
	(segment
		(start 102.39883 -285.748476)
		(end 102.398068 -285.748984)
		(width 0.1143)
		(layer "In6.Cu")
		(net "P5E_CPU1_P0_TX_DP<6>")
	)
	(segment
		(start 121.710704 -344.660982)
		(end 119.660924 -349.609664)
		(width 0.14224)
		(layer "In6.Cu")
		(net "P5E_CPU1_P0_TX_DP<6>")
	)
	(segment
		(start 102.401624 -283.485844)
		(end 102.402386 -283.486352)
		(width 0.1143)
		(layer "In6.Cu")
		(net "P5E_CPU1_P0_TX_DP<6>")
	)
	(segment
		(start 102.358952 -286.700976)
		(end 102.431596 -286.743394)
		(width 0.1143)
		(layer "In6.Cu")
		(net "P5E_CPU1_P0_TX_DP<6>")
	)
	(segment
		(start 118.328694 -351.233994)
		(end 101.503226 -362.495846)
		(width 0.14224)
		(layer "In6.Cu")
		(net "P5E_CPU1_P0_TX_DP<6>")
	)
	(segment
		(start 102.38613 -284.13583)
		(end 102.358952 -284.151832)
		(width 0.1143)
		(layer "In6.Cu")
		(net "P5E_CPU1_P0_TX_DP<6>")
	)
	(segment
		(start 101.458014 -281.86507)
		(end 101.463348 -281.868372)
		(width 0.1143)
		(layer "In6.Cu")
		(net "P5E_CPU1_P0_TX_DP<6>")
	)
	(segment
		(start 102.408482 -283.489654)
		(end 102.429818 -283.5021)
		(width 0.1143)
		(layer "In6.Cu")
		(net "P5E_CPU1_P0_TX_DP<6>")
	)
	(segment
		(start 101.009704 -362.64596)
		(end 72.885554 -362.64596)
		(width 0.14224)
		(layer "In6.Cu")
		(net "P5E_CPU1_P0_TX_DP<6>")
	)
	(segment
		(start 102.429818 -285.730696)
		(end 102.4001 -285.747714)
		(width 0.1143)
		(layer "In6.Cu")
		(net "P5E_CPU1_P0_TX_DP<6>")
	)
	(segment
		(start 102.39883 -283.48432)
		(end 102.401624 -283.485844)
		(width 0.1143)
		(layer "In6.Cu")
		(net "P5E_CPU1_P0_TX_DP<6>")
	)
	(segment
		(start 102.393242 -284.131766)
		(end 102.392226 -284.132274)
		(width 0.1143)
		(layer "In6.Cu")
		(net "P5E_CPU1_P0_TX_DP<6>")
	)
	(segment
		(start 102.120954 -296.071544)
		(end 102.120954 -296.475658)
		(width 0.1143)
		(layer "In6.Cu")
		(net "P5E_CPU1_P0_TX_DP<6>")
	)
	(segment
		(start 102.394512 -284.131004)
		(end 102.393242 -284.131766)
		(width 0.1143)
		(layer "In6.Cu")
		(net "P5E_CPU1_P0_TX_DP<6>")
	)
	(segment
		(start 102.398068 -285.103824)
		(end 102.39883 -285.104332)
		(width 0.1143)
		(layer "In6.Cu")
		(net "P5E_CPU1_P0_TX_DP<6>")
	)
	(segment
		(start 51.814984 -368.365532)
		(end 51.814984 -368.7445)
		(width 0.14224)
		(layer "In6.Cu")
		(net "P5E_CPU1_P0_TX_DP<6>")
	)
	(segment
		(start 102.388416 -284.13456)
		(end 102.38613 -284.13583)
		(width 0.1143)
		(layer "In6.Cu")
		(net "P5E_CPU1_P0_TX_DP<6>")
	)
	(segment
		(start 101.957378 -282.691078)
		(end 101.958648 -282.691586)
		(width 0.1143)
		(layer "In6.Cu")
		(net "P5E_CPU1_P0_TX_DP<6>")
	)
	(segment
		(start 102.39883 -285.104332)
		(end 102.4001 -285.105094)
		(width 0.1143)
		(layer "In6.Cu")
		(net "P5E_CPU1_P0_TX_DP<6>")
	)
	(arc
		(start 120.557798 -329.578208)
		(mid 120.617535 -329.823987)
		(end 120.667272 -330.071984)
		(width 0.14224)
		(layer "In6.Cu")
		(net "P5E_CPU1_P0_TX_DP<6>")
	)
	(arc
		(start 102.898702 -292.411404)
		(mid 103.055679 -292.716204)
		(end 102.898702 -293.021004)
		(width 0.1143)
		(layer "In6.Cu")
		(net "P5E_CPU1_P0_TX_DP<6>")
	)
	(arc
		(start 120.445276 -329.28941)
		(mid 120.509511 -329.430703)
		(end 120.557798 -329.578208)
		(width 0.14224)
		(layer "In6.Cu")
		(net "P5E_CPU1_P0_TX_DP<6>")
	)
	(arc
		(start 102.585774 -287.046162)
		(mid 102.65101 -287.309753)
		(end 102.831646 -287.512506)
		(width 0.1143)
		(layer "In6.Cu")
		(net "P5E_CPU1_P0_TX_DP<6>")
	)
	(arc
		(start 102.429818 -283.5021)
		(mid 102.585746 -283.806392)
		(end 102.429818 -284.110684)
		(width 0.1143)
		(layer "In6.Cu")
		(net "P5E_CPU1_P0_TX_DP<6>")
	)
	(arc
		(start 102.267258 -295.718484)
		(mid 102.158969 -295.880455)
		(end 102.120954 -296.071544)
		(width 0.1143)
		(layer "In6.Cu")
		(net "P5E_CPU1_P0_TX_DP<6>")
	)
	(arc
		(start 102.429818 -285.122112)
		(mid 102.585746 -285.426404)
		(end 102.429818 -285.730696)
		(width 0.1143)
		(layer "In6.Cu")
		(net "P5E_CPU1_P0_TX_DP<6>")
	)
	(arc
		(start 102.829106 -289.82162)
		(mid 102.585779 -290.286186)
		(end 102.829106 -290.750752)
		(width 0.1143)
		(layer "In6.Cu")
		(net "P5E_CPU1_P0_TX_DP<6>")
	)
	(arc
		(start 102.898702 -287.551622)
		(mid 103.014129 -287.684998)
		(end 103.055674 -287.856422)
		(width 0.1143)
		(layer "In6.Cu")
		(net "P5E_CPU1_P0_TX_DP<6>")
	)
	(arc
		(start 65.034922 -361.975146)
		(mid 64.855844 -361.992783)
		(end 64.68364 -362.044996)
		(width 0.14224)
		(layer "In6.Cu")
		(net "P5E_CPU1_P0_TX_DP<6>")
	)
	(arc
		(start 102.075234 -298.49191)
		(mid 102.086835 -298.609746)
		(end 102.121208 -298.72305)
		(width 0.14224)
		(layer "In6.Cu")
		(net "P5E_CPU1_P0_TX_DP<6>")
	)
	(arc
		(start 101.463348 -281.868372)
		(mid 101.597031 -282.003035)
		(end 101.645974 -282.18638)
		(width 0.1143)
		(layer "In6.Cu")
		(net "P5E_CPU1_P0_TX_DP<6>")
	)
	(arc
		(start 101.181916 -281.459178)
		(mid 101.181837 -281.468449)
		(end 101.181916 -281.47772)
		(width 0.1143)
		(layer "In6.Cu")
		(net "P5E_CPU1_P0_TX_DP<6>")
	)
	(arc
		(start 102.358952 -284.151832)
		(mid 102.115625 -284.616398)
		(end 102.358952 -285.080964)
		(width 0.1143)
		(layer "In6.Cu")
		(net "P5E_CPU1_P0_TX_DP<6>")
	)
	(arc
		(start 101.958648 -282.691586)
		(mid 102.074075 -282.824962)
		(end 102.11562 -282.996386)
		(width 0.1143)
		(layer "In6.Cu")
		(net "P5E_CPU1_P0_TX_DP<6>")
	)
	(arc
		(start 111.221266 -315.789056)
		(mid 111.39792 -316.039835)
		(end 111.586772 -316.281562)
		(width 0.14224)
		(layer "In6.Cu")
		(net "P5E_CPU1_P0_TX_DP<6>")
	)
	(arc
		(start 72.885554 -362.64596)
		(mid 72.65792 -362.623637)
		(end 72.439022 -362.557314)
		(width 0.14224)
		(layer "In6.Cu")
		(net "P5E_CPU1_P0_TX_DP<6>")
	)
	(arc
		(start 119.660924 -349.609664)
		(mid 119.115113 -350.520497)
		(end 118.328694 -351.233994)
		(width 0.14224)
		(layer "In6.Cu")
		(net "P5E_CPU1_P0_TX_DP<6>")
	)
	(arc
		(start 103.055674 -287.856422)
		(mid 103.014708 -288.026828)
		(end 102.900734 -288.159952)
		(width 0.1143)
		(layer "In6.Cu")
		(net "P5E_CPU1_P0_TX_DP<6>")
	)
	(arc
		(start 101.18598 -281.481784)
		(mid 101.280085 -281.703189)
		(end 101.458014 -281.86507)
		(width 0.1143)
		(layer "In6.Cu")
		(net "P5E_CPU1_P0_TX_DP<6>")
	)
	(arc
		(start 101.645974 -282.18638)
		(mid 101.710792 -282.449369)
		(end 101.890576 -282.651962)
		(width 0.1143)
		(layer "In6.Cu")
		(net "P5E_CPU1_P0_TX_DP<6>")
	)
	(arc
		(start 102.585774 -295.34739)
		(mid 102.575935 -295.3962)
		(end 102.548182 -295.43756)
		(width 0.1143)
		(layer "In6.Cu")
		(net "P5E_CPU1_P0_TX_DP<6>")
	)
	(arc
		(start 102.829106 -293.061644)
		(mid 102.585779 -293.52621)
		(end 102.829106 -293.990776)
		(width 0.1143)
		(layer "In6.Cu")
		(net "P5E_CPU1_P0_TX_DP<6>")
	)
	(arc
		(start 122.302778 -339.171534)
		(mid 122.400919 -341.958776)
		(end 121.710704 -344.660982)
		(width 0.14224)
		(layer "In6.Cu")
		(net "P5E_CPU1_P0_TX_DP<6>")
	)
	(arc
		(start 102.898702 -289.17138)
		(mid 103.055679 -289.47618)
		(end 102.898702 -289.78098)
		(width 0.1143)
		(layer "In6.Cu")
		(net "P5E_CPU1_P0_TX_DP<6>")
	)
	(arc
		(start 102.358952 -285.771844)
		(mid 102.115625 -286.23641)
		(end 102.358952 -286.700976)
		(width 0.1143)
		(layer "In6.Cu")
		(net "P5E_CPU1_P0_TX_DP<6>")
	)
	(arc
		(start 71.202042 -362.044996)
		(mid 71.029969 -361.992777)
		(end 70.851014 -361.975146)
		(width 0.14224)
		(layer "In6.Cu")
		(net "P5E_CPU1_P0_TX_DP<6>")
	)
	(arc
		(start 105.85958 -307.750464)
		(mid 105.876768 -307.7867)
		(end 105.897426 -307.821076)
		(width 0.14224)
		(layer "In6.Cu")
		(net "P5E_CPU1_P0_TX_DP<6>")
	)
	(arc
		(start 101.503226 -362.495846)
		(mid 101.267609 -362.607526)
		(end 101.009704 -362.64596)
		(width 0.14224)
		(layer "In6.Cu")
		(net "P5E_CPU1_P0_TX_DP<6>")
	)
	(arc
		(start 52.02809 -367.851182)
		(mid 51.870356 -368.087154)
		(end 51.814984 -368.365532)
		(width 0.14224)
		(layer "In6.Cu")
		(net "P5E_CPU1_P0_TX_DP<6>")
	)
	(arc
		(start 117.244114 -323.175376)
		(mid 117.275224 -323.227247)
		(end 117.304312 -323.280278)
		(width 0.14224)
		(layer "In6.Cu")
		(net "P5E_CPU1_P0_TX_DP<6>")
	)
	(arc
		(start 102.11562 -282.996386)
		(mid 102.180135 -283.258605)
		(end 102.358952 -283.460952)
		(width 0.1143)
		(layer "In6.Cu")
		(net "P5E_CPU1_P0_TX_DP<6>")
	)
	(arc
		(start 102.898702 -294.031416)
		(mid 103.055679 -294.336216)
		(end 102.898702 -294.641016)
		(width 0.1143)
		(layer "In6.Cu")
		(net "P5E_CPU1_P0_TX_DP<6>")
	)
	(arc
		(start 102.431596 -286.743394)
		(mid 102.545003 -286.876283)
		(end 102.585774 -287.046162)
		(width 0.1143)
		(layer "In6.Cu")
		(net "P5E_CPU1_P0_TX_DP<6>")
	)
	(arc
		(start 102.829106 -288.201608)
		(mid 102.585779 -288.666174)
		(end 102.829106 -289.13074)
		(width 0.1143)
		(layer "In6.Cu")
		(net "P5E_CPU1_P0_TX_DP<6>")
	)
	(arc
		(start 102.898702 -290.791392)
		(mid 103.055679 -291.096192)
		(end 102.898702 -291.400992)
		(width 0.1143)
		(layer "In6.Cu")
		(net "P5E_CPU1_P0_TX_DP<6>")
	)
	(arc
		(start 102.829106 -291.441632)
		(mid 102.585779 -291.906198)
		(end 102.829106 -292.370764)
		(width 0.1143)
		(layer "In6.Cu")
		(net "P5E_CPU1_P0_TX_DP<6>")
	)
	(arc
		(start 102.829106 -294.681656)
		(mid 102.650293 -294.884006)
		(end 102.585774 -295.146222)
		(width 0.1143)
		(layer "In6.Cu")
		(net "P5E_CPU1_P0_TX_DP<6>")
	)
	(segment
		(start 50.092864 -371.76964)
		(end 50.092864 -372.47322)
		(width 0.12954)
		(layer "F.Cu")
		(net "P5E_CPU1_P0_TX_DP<5>")
	)
	(segment
		(start 50.092864 -372.47322)
		(end 49.796954 -372.76913)
		(width 0.12954)
		(layer "F.Cu")
		(net "P5E_CPU1_P0_TX_DP<5>")
	)
	(segment
		(start 101.268022 -285.970472)
		(end 100.80117 -286.23641)
		(width 0.12954)
		(layer "F.Cu")
		(net "P5E_CPU1_P0_TX_DP<5>")
	)
	(segment
		(start 49.822354 -371.49913)
		(end 50.092864 -371.76964)
		(width 0.12954)
		(layer "F.Cu")
		(net "P5E_CPU1_P0_TX_DP<5>")
	)
	(segment
		(start 119.73179 -330.209144)
		(end 121.384822 -339.405214)
		(width 0.14224)
		(layer "In6.Cu")
		(net "P5E_CPU1_P0_TX_DP<5>")
	)
	(segment
		(start 101.891592 -287.512506)
		(end 101.958648 -287.551622)
		(width 0.1143)
		(layer "In6.Cu")
		(net "P5E_CPU1_P0_TX_DP<5>")
	)
	(segment
		(start 101.431598 -295.483788)
		(end 101.314758 -295.600628)
		(width 0.1143)
		(layer "In6.Cu")
		(net "P5E_CPU1_P0_TX_DP<5>")
	)
	(segment
		(start 51.680618 -366.879378)
		(end 50.605182 -367.954814)
		(width 0.14224)
		(layer "In6.Cu")
		(net "P5E_CPU1_P0_TX_DP<5>")
	)
	(segment
		(start 101.130354 -296.435018)
		(end 101.130354 -296.463466)
		(width 0.1143)
		(layer "In6.Cu")
		(net "P5E_CPU1_P0_TX_DP<5>")
	)
	(segment
		(start 64.40043 -361.137708)
		(end 57.369964 -364.048548)
		(width 0.14224)
		(layer "In6.Cu")
		(net "P5E_CPU1_P0_TX_DP<5>")
	)
	(segment
		(start 101.958648 -294.641016)
		(end 101.889052 -294.681656)
		(width 0.1143)
		(layer "In6.Cu")
		(net "P5E_CPU1_P0_TX_DP<5>")
	)
	(segment
		(start 101.889052 -290.750752)
		(end 101.958648 -290.791392)
		(width 0.1143)
		(layer "In6.Cu")
		(net "P5E_CPU1_P0_TX_DP<5>")
	)
	(segment
		(start 101.461062 -295.46677)
		(end 101.431598 -295.483788)
		(width 0.1143)
		(layer "In6.Cu")
		(net "P5E_CPU1_P0_TX_DP<5>")
	)
	(segment
		(start 56.585612 -364.832646)
		(end 51.710082 -366.851946)
		(width 0.14224)
		(layer "In6.Cu")
		(net "P5E_CPU1_P0_TX_DP<5>")
	)
	(segment
		(start 57.369964 -364.048548)
		(end 56.585612 -364.832646)
		(width 0.14224)
		(layer "In6.Cu")
		(net "P5E_CPU1_P0_TX_DP<5>")
	)
	(segment
		(start 101.176074 -295.9354)
		(end 101.176074 -296.389298)
		(width 0.1143)
		(layer "In6.Cu")
		(net "P5E_CPU1_P0_TX_DP<5>")
	)
	(segment
		(start 120.86463 -344.228928)
		(end 118.822216 -349.160084)
		(width 0.14224)
		(layer "In6.Cu")
		(net "P5E_CPU1_P0_TX_DP<5>")
	)
	(segment
		(start 101.130354 -296.463466)
		(end 101.130354 -298.648882)
		(width 0.14224)
		(layer "In6.Cu")
		(net "P5E_CPU1_P0_TX_DP<5>")
	)
	(segment
		(start 50.113184 -369.142518)
		(end 50.113184 -371.2083)
		(width 0.14224)
		(layer "In6.Cu")
		(net "P5E_CPU1_P0_TX_DP<5>")
	)
	(segment
		(start 101.099112 -286.23641)
		(end 101.181916 -286.319214)
		(width 0.1143)
		(layer "In6.Cu")
		(net "P5E_CPU1_P0_TX_DP<5>")
	)
	(segment
		(start 101.958648 -293.021004)
		(end 101.889052 -293.061644)
		(width 0.1143)
		(layer "In6.Cu")
		(net "P5E_CPU1_P0_TX_DP<5>")
	)
	(segment
		(start 117.723666 -350.49968)
		(end 101.168962 -361.580176)
		(width 0.14224)
		(layer "In6.Cu")
		(net "P5E_CPU1_P0_TX_DP<5>")
	)
	(segment
		(start 101.183694 -298.917868)
		(end 105.005378 -308.14391)
		(width 0.14224)
		(layer "In6.Cu")
		(net "P5E_CPU1_P0_TX_DP<5>")
	)
	(segment
		(start 101.958648 -291.400992)
		(end 101.889052 -291.441632)
		(width 0.1143)
		(layer "In6.Cu")
		(net "P5E_CPU1_P0_TX_DP<5>")
	)
	(segment
		(start 101.458014 -286.723836)
		(end 101.491542 -286.743394)
		(width 0.1143)
		(layer "In6.Cu")
		(net "P5E_CPU1_P0_TX_DP<5>")
	)
	(segment
		(start 101.889052 -292.370764)
		(end 101.958648 -292.411404)
		(width 0.1143)
		(layer "In6.Cu")
		(net "P5E_CPU1_P0_TX_DP<5>")
	)
	(segment
		(start 101.176074 -296.389298)
		(end 101.130354 -296.435018)
		(width 0.1143)
		(layer "In6.Cu")
		(net "P5E_CPU1_P0_TX_DP<5>")
	)
	(segment
		(start 71.05269 -361.04068)
		(end 64.889126 -361.04068)
		(width 0.14224)
		(layer "In6.Cu")
		(net "P5E_CPU1_P0_TX_DP<5>")
	)
	(segment
		(start 101.889052 -289.13074)
		(end 101.958648 -289.17138)
		(width 0.1143)
		(layer "In6.Cu")
		(net "P5E_CPU1_P0_TX_DP<5>")
	)
	(segment
		(start 72.557894 -361.586018)
		(end 71.415148 -361.112816)
		(width 0.14224)
		(layer "In6.Cu")
		(net "P5E_CPU1_P0_TX_DP<5>")
	)
	(segment
		(start 101.889052 -293.990776)
		(end 101.958648 -294.031416)
		(width 0.1143)
		(layer "In6.Cu")
		(net "P5E_CPU1_P0_TX_DP<5>")
	)
	(segment
		(start 100.808282 -361.689904)
		(end 73.079864 -361.689904)
		(width 0.14224)
		(layer "In6.Cu")
		(net "P5E_CPU1_P0_TX_DP<5>")
	)
	(segment
		(start 101.96068 -288.159952)
		(end 101.928168 -288.178748)
		(width 0.1143)
		(layer "In6.Cu")
		(net "P5E_CPU1_P0_TX_DP<5>")
	)
	(segment
		(start 105.066846 -308.25948)
		(end 110.516416 -316.413896)
		(width 0.14224)
		(layer "In6.Cu")
		(net "P5E_CPU1_P0_TX_DP<5>")
	)
	(segment
		(start 50.113184 -371.2083)
		(end 49.822354 -371.49913)
		(width 0.14224)
		(layer "In6.Cu")
		(net "P5E_CPU1_P0_TX_DP<5>")
	)
	(segment
		(start 101.958648 -289.78098)
		(end 101.889052 -289.82162)
		(width 0.1143)
		(layer "In6.Cu")
		(net "P5E_CPU1_P0_TX_DP<5>")
	)
	(segment
		(start 100.80117 -286.23641)
		(end 101.099112 -286.23641)
		(width 0.1143)
		(layer "In6.Cu")
		(net "P5E_CPU1_P0_TX_DP<5>")
	)
	(segment
		(start 101.421692 -286.702754)
		(end 101.458014 -286.723836)
		(width 0.1143)
		(layer "In6.Cu")
		(net "P5E_CPU1_P0_TX_DP<5>")
	)
	(segment
		(start 101.928168 -288.178748)
		(end 101.889052 -288.201608)
		(width 0.1143)
		(layer "In6.Cu")
		(net "P5E_CPU1_P0_TX_DP<5>")
	)
	(segment
		(start 110.831884 -316.8396)
		(end 116.440712 -323.674232)
		(width 0.14224)
		(layer "In6.Cu")
		(net "P5E_CPU1_P0_TX_DP<5>")
	)
	(segment
		(start 116.510562 -323.779642)
		(end 119.5959 -329.68184)
		(width 0.14224)
		(layer "In6.Cu")
		(net "P5E_CPU1_P0_TX_DP<5>")
	)
	(arc
		(start 101.889052 -291.441632)
		(mid 101.645725 -291.906198)
		(end 101.889052 -292.370764)
		(width 0.1143)
		(layer "In6.Cu")
		(net "P5E_CPU1_P0_TX_DP<5>")
	)
	(arc
		(start 101.958648 -287.551622)
		(mid 102.074075 -287.684998)
		(end 102.11562 -287.856422)
		(width 0.1143)
		(layer "In6.Cu")
		(net "P5E_CPU1_P0_TX_DP<5>")
	)
	(arc
		(start 101.632766 -295.170606)
		(mid 101.586723 -295.341756)
		(end 101.461062 -295.46677)
		(width 0.1143)
		(layer "In6.Cu")
		(net "P5E_CPU1_P0_TX_DP<5>")
	)
	(arc
		(start 116.440712 -323.674232)
		(mid 116.478354 -323.725137)
		(end 116.510562 -323.779642)
		(width 0.14224)
		(layer "In6.Cu")
		(net "P5E_CPU1_P0_TX_DP<5>")
	)
	(arc
		(start 50.605182 -367.954814)
		(mid 50.241076 -368.499737)
		(end 50.113184 -369.142518)
		(width 0.14224)
		(layer "In6.Cu")
		(net "P5E_CPU1_P0_TX_DP<5>")
	)
	(arc
		(start 101.168962 -361.580176)
		(mid 100.996766 -361.6618)
		(end 100.808282 -361.689904)
		(width 0.14224)
		(layer "In6.Cu")
		(net "P5E_CPU1_P0_TX_DP<5>")
	)
	(arc
		(start 119.5959 -329.68184)
		(mid 119.622106 -329.7396)
		(end 119.64162 -329.79995)
		(width 0.14224)
		(layer "In6.Cu")
		(net "P5E_CPU1_P0_TX_DP<5>")
	)
	(arc
		(start 110.516416 -316.413896)
		(mid 110.668936 -316.630612)
		(end 110.831884 -316.8396)
		(width 0.14224)
		(layer "In6.Cu")
		(net "P5E_CPU1_P0_TX_DP<5>")
	)
	(arc
		(start 101.130354 -298.648882)
		(mid 101.143755 -298.786009)
		(end 101.183694 -298.917868)
		(width 0.14224)
		(layer "In6.Cu")
		(net "P5E_CPU1_P0_TX_DP<5>")
	)
	(arc
		(start 101.491542 -286.743394)
		(mid 101.604949 -286.876283)
		(end 101.64572 -287.046162)
		(width 0.1143)
		(layer "In6.Cu")
		(net "P5E_CPU1_P0_TX_DP<5>")
	)
	(arc
		(start 101.64572 -287.046162)
		(mid 101.710956 -287.309753)
		(end 101.891592 -287.512506)
		(width 0.1143)
		(layer "In6.Cu")
		(net "P5E_CPU1_P0_TX_DP<5>")
	)
	(arc
		(start 101.958648 -292.411404)
		(mid 102.115625 -292.716204)
		(end 101.958648 -293.021004)
		(width 0.1143)
		(layer "In6.Cu")
		(net "P5E_CPU1_P0_TX_DP<5>")
	)
	(arc
		(start 119.64162 -329.79995)
		(mid 119.690703 -330.003666)
		(end 119.73179 -330.209144)
		(width 0.14224)
		(layer "In6.Cu")
		(net "P5E_CPU1_P0_TX_DP<5>")
	)
	(arc
		(start 101.958648 -289.17138)
		(mid 102.115625 -289.47618)
		(end 101.958648 -289.78098)
		(width 0.1143)
		(layer "In6.Cu")
		(net "P5E_CPU1_P0_TX_DP<5>")
	)
	(arc
		(start 105.005378 -308.14391)
		(mid 105.033281 -308.203202)
		(end 105.066846 -308.25948)
		(width 0.14224)
		(layer "In6.Cu")
		(net "P5E_CPU1_P0_TX_DP<5>")
	)
	(arc
		(start 64.889126 -361.04068)
		(mid 64.639995 -361.065114)
		(end 64.40043 -361.137708)
		(width 0.14224)
		(layer "In6.Cu")
		(net "P5E_CPU1_P0_TX_DP<5>")
	)
	(arc
		(start 101.958648 -290.791392)
		(mid 102.115625 -291.096192)
		(end 101.958648 -291.400992)
		(width 0.1143)
		(layer "In6.Cu")
		(net "P5E_CPU1_P0_TX_DP<5>")
	)
	(arc
		(start 73.079864 -361.689904)
		(mid 72.813767 -361.66365)
		(end 72.557894 -361.586018)
		(width 0.14224)
		(layer "In6.Cu")
		(net "P5E_CPU1_P0_TX_DP<5>")
	)
	(arc
		(start 51.710082 -366.851946)
		(mid 51.6951 -366.865393)
		(end 51.680618 -366.879378)
		(width 0.14224)
		(layer "In6.Cu")
		(net "P5E_CPU1_P0_TX_DP<5>")
	)
	(arc
		(start 118.822216 -349.160084)
		(mid 118.372162 -349.911249)
		(end 117.723666 -350.49968)
		(width 0.14224)
		(layer "In6.Cu")
		(net "P5E_CPU1_P0_TX_DP<5>")
	)
	(arc
		(start 101.314758 -295.600628)
		(mid 101.212129 -295.754223)
		(end 101.176074 -295.9354)
		(width 0.1143)
		(layer "In6.Cu")
		(net "P5E_CPU1_P0_TX_DP<5>")
	)
	(arc
		(start 101.889052 -294.681656)
		(mid 101.7008 -294.89462)
		(end 101.632766 -295.170606)
		(width 0.1143)
		(layer "In6.Cu")
		(net "P5E_CPU1_P0_TX_DP<5>")
	)
	(arc
		(start 102.11562 -287.856422)
		(mid 102.074654 -288.026828)
		(end 101.96068 -288.159952)
		(width 0.1143)
		(layer "In6.Cu")
		(net "P5E_CPU1_P0_TX_DP<5>")
	)
	(arc
		(start 101.889052 -293.061644)
		(mid 101.645725 -293.52621)
		(end 101.889052 -293.990776)
		(width 0.1143)
		(layer "In6.Cu")
		(net "P5E_CPU1_P0_TX_DP<5>")
	)
	(arc
		(start 101.889052 -288.201608)
		(mid 101.645725 -288.666174)
		(end 101.889052 -289.13074)
		(width 0.1143)
		(layer "In6.Cu")
		(net "P5E_CPU1_P0_TX_DP<5>")
	)
	(arc
		(start 71.415148 -361.112816)
		(mid 71.237473 -361.058888)
		(end 71.05269 -361.04068)
		(width 0.14224)
		(layer "In6.Cu")
		(net "P5E_CPU1_P0_TX_DP<5>")
	)
	(arc
		(start 121.384822 -339.405214)
		(mid 121.471109 -341.854426)
		(end 120.86463 -344.228928)
		(width 0.14224)
		(layer "In6.Cu")
		(net "P5E_CPU1_P0_TX_DP<5>")
	)
	(arc
		(start 101.181916 -286.319214)
		(mid 101.261766 -286.536012)
		(end 101.421692 -286.702754)
		(width 0.1143)
		(layer "In6.Cu")
		(net "P5E_CPU1_P0_TX_DP<5>")
	)
	(arc
		(start 101.889052 -289.82162)
		(mid 101.645725 -290.286186)
		(end 101.889052 -290.750752)
		(width 0.1143)
		(layer "In6.Cu")
		(net "P5E_CPU1_P0_TX_DP<5>")
	)
	(arc
		(start 101.958648 -294.031416)
		(mid 102.115625 -294.336216)
		(end 101.958648 -294.641016)
		(width 0.1143)
		(layer "In6.Cu")
		(net "P5E_CPU1_P0_TX_DP<5>")
	)
	(segment
		(start 101.268022 -284.35046)
		(end 100.80117 -284.616398)
		(width 0.12954)
		(layer "F.Cu")
		(net "P5E_CPU1_P0_TX_DP<4>")
	)
	(segment
		(start 48.391064 -374.93702)
		(end 48.095154 -375.23293)
		(width 0.12954)
		(layer "F.Cu")
		(net "P5E_CPU1_P0_TX_DP<4>")
	)
	(segment
		(start 48.391064 -374.23344)
		(end 48.391064 -374.93702)
		(width 0.12954)
		(layer "F.Cu")
		(net "P5E_CPU1_P0_TX_DP<4>")
	)
	(segment
		(start 48.120554 -373.96293)
		(end 48.391064 -374.23344)
		(width 0.12954)
		(layer "F.Cu")
		(net "P5E_CPU1_P0_TX_DP<4>")
	)
	(segment
		(start 100.988876 -294.014144)
		(end 101.019864 -294.031924)
		(width 0.1143)
		(layer "In6.Cu")
		(net "P5E_CPU1_P0_TX_DP<4>")
	)
	(segment
		(start 100.955856 -287.515046)
		(end 100.956618 -287.515554)
		(width 0.1143)
		(layer "In6.Cu")
		(net "P5E_CPU1_P0_TX_DP<4>")
	)
	(segment
		(start 56.871616 -363.22762)
		(end 56.109108 -363.990128)
		(width 0.14224)
		(layer "In6.Cu")
		(net "P5E_CPU1_P0_TX_DP<4>")
	)
	(segment
		(start 101.00945 -292.40607)
		(end 101.019864 -292.411912)
		(width 0.1143)
		(layer "In6.Cu")
		(net "P5E_CPU1_P0_TX_DP<4>")
	)
	(segment
		(start 100.98151 -289.80257)
		(end 100.948998 -289.82162)
		(width 0.1143)
		(layer "In6.Cu")
		(net "P5E_CPU1_P0_TX_DP<4>")
	)
	(segment
		(start 100.98151 -291.422582)
		(end 100.948998 -291.441632)
		(width 0.1143)
		(layer "In6.Cu")
		(net "P5E_CPU1_P0_TX_DP<4>")
	)
	(segment
		(start 100.955856 -293.99484)
		(end 100.956618 -293.995348)
		(width 0.1143)
		(layer "In6.Cu")
		(net "P5E_CPU1_P0_TX_DP<4>")
	)
	(segment
		(start 100.991924 -290.775898)
		(end 100.994464 -290.777422)
		(width 0.1143)
		(layer "In6.Cu")
		(net "P5E_CPU1_P0_TX_DP<4>")
	)
	(segment
		(start 101.002084 -292.401752)
		(end 101.003608 -292.402514)
		(width 0.1143)
		(layer "In6.Cu")
		(net "P5E_CPU1_P0_TX_DP<4>")
	)
	(segment
		(start 72.8472 -360.689906)
		(end 71.617078 -360.180636)
		(width 0.14224)
		(layer "In6.Cu")
		(net "P5E_CPU1_P0_TX_DP<4>")
	)
	(segment
		(start 100.549964 -285.730188)
		(end 100.518976 -285.748476)
		(width 0.1143)
		(layer "In6.Cu")
		(net "P5E_CPU1_P0_TX_DP<4>")
	)
	(segment
		(start 100.99421 -289.157156)
		(end 101.019864 -289.171888)
		(width 0.1143)
		(layer "In6.Cu")
		(net "P5E_CPU1_P0_TX_DP<4>")
	)
	(segment
		(start 100.956618 -290.755324)
		(end 100.988114 -290.773612)
		(width 0.1143)
		(layer "In6.Cu")
		(net "P5E_CPU1_P0_TX_DP<4>")
	)
	(segment
		(start 100.985574 -289.800284)
		(end 100.98151 -289.80257)
		(width 0.1143)
		(layer "In6.Cu")
		(net "P5E_CPU1_P0_TX_DP<4>")
	)
	(segment
		(start 100.988876 -291.418264)
		(end 100.988114 -291.418772)
		(width 0.1143)
		(layer "In6.Cu")
		(net "P5E_CPU1_P0_TX_DP<4>")
	)
	(segment
		(start 100.518214 -285.748984)
		(end 100.479098 -285.771844)
		(width 0.1143)
		(layer "In6.Cu")
		(net "P5E_CPU1_P0_TX_DP<4>")
	)
	(segment
		(start 101.003608 -292.402514)
		(end 101.00437 -292.403022)
		(width 0.1143)
		(layer "In6.Cu")
		(net "P5E_CPU1_P0_TX_DP<4>")
	)
	(segment
		(start 101.02215 -294.638984)
		(end 101.010974 -294.645842)
		(width 0.1143)
		(layer "In6.Cu")
		(net "P5E_CPU1_P0_TX_DP<4>")
	)
	(segment
		(start 100.230178 -299.059854)
		(end 104.170226 -308.571138)
		(width 0.14224)
		(layer "In6.Cu")
		(net "P5E_CPU1_P0_TX_DP<4>")
	)
	(segment
		(start 100.994464 -290.777422)
		(end 100.995988 -290.778184)
		(width 0.1143)
		(layer "In6.Cu")
		(net "P5E_CPU1_P0_TX_DP<4>")
	)
	(segment
		(start 100.479098 -286.700976)
		(end 100.518214 -286.723836)
		(width 0.1143)
		(layer "In6.Cu")
		(net "P5E_CPU1_P0_TX_DP<4>")
	)
	(segment
		(start 100.955856 -290.754816)
		(end 100.956618 -290.755324)
		(width 0.1143)
		(layer "In6.Cu")
		(net "P5E_CPU1_P0_TX_DP<4>")
	)
	(segment
		(start 100.621084 -295.377616)
		(end 100.476812 -295.521888)
		(width 0.1143)
		(layer "In6.Cu")
		(net "P5E_CPU1_P0_TX_DP<4>")
	)
	(segment
		(start 100.988114 -291.418772)
		(end 100.987098 -291.41928)
		(width 0.1143)
		(layer "In6.Cu")
		(net "P5E_CPU1_P0_TX_DP<4>")
	)
	(segment
		(start 100.988114 -290.773612)
		(end 100.988876 -290.77412)
		(width 0.1143)
		(layer "In6.Cu")
		(net "P5E_CPU1_P0_TX_DP<4>")
	)
	(segment
		(start 64.057022 -360.251756)
		(end 60.4901 -361.72902)
		(width 0.14224)
		(layer "In6.Cu")
		(net "P5E_CPU1_P0_TX_DP<4>")
	)
	(segment
		(start 100.987098 -287.533334)
		(end 100.989892 -287.534858)
		(width 0.1143)
		(layer "In6.Cu")
		(net "P5E_CPU1_P0_TX_DP<4>")
	)
	(segment
		(start 100.948998 -293.990776)
		(end 100.955856 -293.99484)
		(width 0.1143)
		(layer "In6.Cu")
		(net "P5E_CPU1_P0_TX_DP<4>")
	)
	(segment
		(start 101.019864 -289.780472)
		(end 100.988876 -289.798252)
		(width 0.1143)
		(layer "In6.Cu")
		(net "P5E_CPU1_P0_TX_DP<4>")
	)
	(segment
		(start 100.80117 -284.616398)
		(end 101.099112 -284.616398)
		(width 0.1143)
		(layer "In6.Cu")
		(net "P5E_CPU1_P0_TX_DP<4>")
	)
	(segment
		(start 101.099112 -284.616398)
		(end 101.168962 -284.686248)
		(width 0.1143)
		(layer "In6.Cu")
		(net "P5E_CPU1_P0_TX_DP<4>")
	)
	(segment
		(start 100.988114 -292.393624)
		(end 100.988876 -292.394132)
		(width 0.1143)
		(layer "In6.Cu")
		(net "P5E_CPU1_P0_TX_DP<4>")
	)
	(segment
		(start 101.007164 -290.784534)
		(end 101.00945 -290.786058)
		(width 0.1143)
		(layer "In6.Cu")
		(net "P5E_CPU1_P0_TX_DP<4>")
	)
	(segment
		(start 100.578412 -360.750104)
		(end 73.149968 -360.750104)
		(width 0.14224)
		(layer "In6.Cu")
		(net "P5E_CPU1_P0_TX_DP<4>")
	)
	(segment
		(start 100.995988 -290.778184)
		(end 100.997766 -290.7792)
		(width 0.1143)
		(layer "In6.Cu")
		(net "P5E_CPU1_P0_TX_DP<4>")
	)
	(segment
		(start 100.23094 -296.358818)
		(end 100.18522 -296.404538)
		(width 0.1143)
		(layer "In6.Cu")
		(net "P5E_CPU1_P0_TX_DP<4>")
	)
	(segment
		(start 101.00564 -290.783772)
		(end 101.007164 -290.784534)
		(width 0.1143)
		(layer "In6.Cu")
		(net "P5E_CPU1_P0_TX_DP<4>")
	)
	(segment
		(start 101.019864 -293.020496)
		(end 100.988876 -293.038276)
		(width 0.1143)
		(layer "In6.Cu")
		(net "P5E_CPU1_P0_TX_DP<4>")
	)
	(segment
		(start 119.979694 -343.704164)
		(end 117.81028 -348.941136)
		(width 0.14224)
		(layer "In6.Cu")
		(net "P5E_CPU1_P0_TX_DP<4>")
	)
	(segment
		(start 101.00945 -290.786058)
		(end 101.019864 -290.7919)
		(width 0.1143)
		(layer "In6.Cu")
		(net "P5E_CPU1_P0_TX_DP<4>")
	)
	(segment
		(start 100.18522 -296.432986)
		(end 100.18522 -298.833032)
		(width 0.14224)
		(layer "In6.Cu")
		(net "P5E_CPU1_P0_TX_DP<4>")
	)
	(segment
		(start 117.132354 -349.767906)
		(end 100.844858 -360.669078)
		(width 0.14224)
		(layer "In6.Cu")
		(net "P5E_CPU1_P0_TX_DP<4>")
	)
	(segment
		(start 115.843558 -324.533006)
		(end 118.673372 -329.94854)
		(width 0.14224)
		(layer "In6.Cu")
		(net "P5E_CPU1_P0_TX_DP<4>")
	)
	(segment
		(start 100.955856 -292.374828)
		(end 100.956618 -292.375336)
		(width 0.1143)
		(layer "In6.Cu")
		(net "P5E_CPU1_P0_TX_DP<4>")
	)
	(segment
		(start 100.988114 -293.038784)
		(end 100.987098 -293.039292)
		(width 0.1143)
		(layer "In6.Cu")
		(net "P5E_CPU1_P0_TX_DP<4>")
	)
	(segment
		(start 100.997766 -292.399212)
		(end 100.998528 -292.39972)
		(width 0.1143)
		(layer "In6.Cu")
		(net "P5E_CPU1_P0_TX_DP<4>")
	)
	(segment
		(start 100.998528 -292.39972)
		(end 101.000052 -292.400482)
		(width 0.1143)
		(layer "In6.Cu")
		(net "P5E_CPU1_P0_TX_DP<4>")
	)
	(segment
		(start 100.985574 -291.420296)
		(end 100.98151 -291.422582)
		(width 0.1143)
		(layer "In6.Cu")
		(net "P5E_CPU1_P0_TX_DP<4>")
	)
	(segment
		(start 101.019864 -291.400484)
		(end 100.988876 -291.418264)
		(width 0.1143)
		(layer "In6.Cu")
		(net "P5E_CPU1_P0_TX_DP<4>")
	)
	(segment
		(start 101.00437 -292.403022)
		(end 101.00564 -292.403784)
		(width 0.1143)
		(layer "In6.Cu")
		(net "P5E_CPU1_P0_TX_DP<4>")
	)
	(segment
		(start 118.83771 -330.581)
		(end 120.436132 -339.471254)
		(width 0.14224)
		(layer "In6.Cu")
		(net "P5E_CPU1_P0_TX_DP<4>")
	)
	(segment
		(start 48.411384 -369.768882)
		(end 48.411384 -373.605298)
		(width 0.14224)
		(layer "In6.Cu")
		(net "P5E_CPU1_P0_TX_DP<4>")
	)
	(segment
		(start 101.000052 -290.78047)
		(end 101.000814 -290.780978)
		(width 0.1143)
		(layer "In6.Cu")
		(net "P5E_CPU1_P0_TX_DP<4>")
	)
	(segment
		(start 100.951538 -287.512506)
		(end 100.955856 -287.515046)
		(width 0.1143)
		(layer "In6.Cu")
		(net "P5E_CPU1_P0_TX_DP<4>")
	)
	(segment
		(start 100.985574 -293.040308)
		(end 100.98151 -293.042594)
		(width 0.1143)
		(layer "In6.Cu")
		(net "P5E_CPU1_P0_TX_DP<4>")
	)
	(segment
		(start 100.988876 -293.038276)
		(end 100.988114 -293.038784)
		(width 0.1143)
		(layer "In6.Cu")
		(net "P5E_CPU1_P0_TX_DP<4>")
	)
	(segment
		(start 56.109108 -363.990128)
		(end 50.804318 -366.187482)
		(width 0.14224)
		(layer "In6.Cu")
		(net "P5E_CPU1_P0_TX_DP<4>")
	)
	(segment
		(start 100.956618 -287.515554)
		(end 100.987098 -287.533334)
		(width 0.1143)
		(layer "In6.Cu")
		(net "P5E_CPU1_P0_TX_DP<4>")
	)
	(segment
		(start 100.987098 -293.039292)
		(end 100.985574 -293.040308)
		(width 0.1143)
		(layer "In6.Cu")
		(net "P5E_CPU1_P0_TX_DP<4>")
	)
	(segment
		(start 100.98151 -293.042594)
		(end 100.948998 -293.061644)
		(width 0.1143)
		(layer "In6.Cu")
		(net "P5E_CPU1_P0_TX_DP<4>")
	)
	(segment
		(start 100.997766 -290.7792)
		(end 100.998528 -290.779708)
		(width 0.1143)
		(layer "In6.Cu")
		(net "P5E_CPU1_P0_TX_DP<4>")
	)
	(segment
		(start 100.988114 -289.79876)
		(end 100.987098 -289.799268)
		(width 0.1143)
		(layer "In6.Cu")
		(net "P5E_CPU1_P0_TX_DP<4>")
	)
	(segment
		(start 100.518214 -286.723836)
		(end 100.550726 -286.742632)
		(width 0.1143)
		(layer "In6.Cu")
		(net "P5E_CPU1_P0_TX_DP<4>")
	)
	(segment
		(start 100.987098 -289.799268)
		(end 100.985574 -289.800284)
		(width 0.1143)
		(layer "In6.Cu")
		(net "P5E_CPU1_P0_TX_DP<4>")
	)
	(segment
		(start 100.991924 -292.39591)
		(end 100.994464 -292.397434)
		(width 0.1143)
		(layer "In6.Cu")
		(net "P5E_CPU1_P0_TX_DP<4>")
	)
	(segment
		(start 100.988114 -294.013636)
		(end 100.988876 -294.014144)
		(width 0.1143)
		(layer "In6.Cu")
		(net "P5E_CPU1_P0_TX_DP<4>")
	)
	(segment
		(start 100.956618 -292.375336)
		(end 100.988114 -292.393624)
		(width 0.1143)
		(layer "In6.Cu")
		(net "P5E_CPU1_P0_TX_DP<4>")
	)
	(segment
		(start 110.752636 -318.309752)
		(end 115.773708 -324.427596)
		(width 0.14224)
		(layer "In6.Cu")
		(net "P5E_CPU1_P0_TX_DP<4>")
	)
	(segment
		(start 100.988876 -290.77412)
		(end 100.990908 -290.77539)
		(width 0.1143)
		(layer "In6.Cu")
		(net "P5E_CPU1_P0_TX_DP<4>")
	)
	(segment
		(start 100.994464 -292.397434)
		(end 100.995988 -292.398196)
		(width 0.1143)
		(layer "In6.Cu")
		(net "P5E_CPU1_P0_TX_DP<4>")
	)
	(segment
		(start 100.998528 -290.779708)
		(end 101.000052 -290.78047)
		(width 0.1143)
		(layer "In6.Cu")
		(net "P5E_CPU1_P0_TX_DP<4>")
	)
	(segment
		(start 71.25462 -360.1085)
		(end 64.802512 -360.1085)
		(width 0.14224)
		(layer "In6.Cu")
		(net "P5E_CPU1_P0_TX_DP<4>")
	)
	(segment
		(start 101.002084 -290.78174)
		(end 101.003608 -290.782502)
		(width 0.1143)
		(layer "In6.Cu")
		(net "P5E_CPU1_P0_TX_DP<4>")
	)
	(segment
		(start 60.4901 -361.72902)
		(end 56.871616 -363.22762)
		(width 0.14224)
		(layer "In6.Cu")
		(net "P5E_CPU1_P0_TX_DP<4>")
	)
	(segment
		(start 101.000052 -292.400482)
		(end 101.000814 -292.40099)
		(width 0.1143)
		(layer "In6.Cu")
		(net "P5E_CPU1_P0_TX_DP<4>")
	)
	(segment
		(start 100.993194 -284.935676)
		(end 100.984558 -284.940248)
		(width 0.1143)
		(layer "In6.Cu")
		(net "P5E_CPU1_P0_TX_DP<4>")
	)
	(segment
		(start 101.00564 -292.403784)
		(end 101.007164 -292.404546)
		(width 0.1143)
		(layer "In6.Cu")
		(net "P5E_CPU1_P0_TX_DP<4>")
	)
	(segment
		(start 101.007164 -292.404546)
		(end 101.00945 -292.40607)
		(width 0.1143)
		(layer "In6.Cu")
		(net "P5E_CPU1_P0_TX_DP<4>")
	)
	(segment
		(start 100.948998 -289.13074)
		(end 100.993448 -289.156648)
		(width 0.1143)
		(layer "In6.Cu")
		(net "P5E_CPU1_P0_TX_DP<4>")
	)
	(segment
		(start 101.019864 -294.031924)
		(end 101.02215 -294.033448)
		(width 0.1143)
		(layer "In6.Cu")
		(net "P5E_CPU1_P0_TX_DP<4>")
	)
	(segment
		(start 100.948998 -290.750752)
		(end 100.955856 -290.754816)
		(width 0.1143)
		(layer "In6.Cu")
		(net "P5E_CPU1_P0_TX_DP<4>")
	)
	(segment
		(start 101.168962 -284.686248)
		(end 101.169216 -284.686248)
		(width 0.1143)
		(layer "In6.Cu")
		(net "P5E_CPU1_P0_TX_DP<4>")
	)
	(segment
		(start 101.000814 -292.40099)
		(end 101.002084 -292.401752)
		(width 0.1143)
		(layer "In6.Cu")
		(net "P5E_CPU1_P0_TX_DP<4>")
	)
	(segment
		(start 100.993448 -289.156648)
		(end 100.99421 -289.157156)
		(width 0.1143)
		(layer "In6.Cu")
		(net "P5E_CPU1_P0_TX_DP<4>")
	)
	(segment
		(start 101.000814 -290.780978)
		(end 101.002084 -290.78174)
		(width 0.1143)
		(layer "In6.Cu")
		(net "P5E_CPU1_P0_TX_DP<4>")
	)
	(segment
		(start 100.18522 -296.404538)
		(end 100.18522 -296.432986)
		(width 0.1143)
		(layer "In6.Cu")
		(net "P5E_CPU1_P0_TX_DP<4>")
	)
	(segment
		(start 101.021642 -288.15919)
		(end 100.948998 -288.201608)
		(width 0.1143)
		(layer "In6.Cu")
		(net "P5E_CPU1_P0_TX_DP<4>")
	)
	(segment
		(start 100.956618 -293.995348)
		(end 100.988114 -294.013636)
		(width 0.1143)
		(layer "In6.Cu")
		(net "P5E_CPU1_P0_TX_DP<4>")
	)
	(segment
		(start 100.988876 -289.798252)
		(end 100.988114 -289.79876)
		(width 0.1143)
		(layer "In6.Cu")
		(net "P5E_CPU1_P0_TX_DP<4>")
	)
	(segment
		(start 100.988876 -292.394132)
		(end 100.990908 -292.395402)
		(width 0.1143)
		(layer "In6.Cu")
		(net "P5E_CPU1_P0_TX_DP<4>")
	)
	(segment
		(start 100.23094 -296.115486)
		(end 100.23094 -296.358818)
		(width 0.1143)
		(layer "In6.Cu")
		(net "P5E_CPU1_P0_TX_DP<4>")
	)
	(segment
		(start 100.70592 -295.146222)
		(end 100.70592 -295.172892)
		(width 0.1143)
		(layer "In6.Cu")
		(net "P5E_CPU1_P0_TX_DP<4>")
	)
	(segment
		(start 100.990908 -292.395402)
		(end 100.991924 -292.39591)
		(width 0.1143)
		(layer "In6.Cu")
		(net "P5E_CPU1_P0_TX_DP<4>")
	)
	(segment
		(start 48.36414 -373.719344)
		(end 48.120554 -373.96293)
		(width 0.14224)
		(layer "In6.Cu")
		(net "P5E_CPU1_P0_TX_DP<4>")
	)
	(segment
		(start 100.987098 -291.41928)
		(end 100.985574 -291.420296)
		(width 0.1143)
		(layer "In6.Cu")
		(net "P5E_CPU1_P0_TX_DP<4>")
	)
	(segment
		(start 100.995988 -292.398196)
		(end 100.997766 -292.399212)
		(width 0.1143)
		(layer "In6.Cu")
		(net "P5E_CPU1_P0_TX_DP<4>")
	)
	(segment
		(start 101.003608 -290.782502)
		(end 101.00437 -290.78301)
		(width 0.1143)
		(layer "In6.Cu")
		(net "P5E_CPU1_P0_TX_DP<4>")
	)
	(segment
		(start 101.00437 -290.78301)
		(end 101.00564 -290.783772)
		(width 0.1143)
		(layer "In6.Cu")
		(net "P5E_CPU1_P0_TX_DP<4>")
	)
	(segment
		(start 101.010974 -294.645842)
		(end 100.94976 -294.681148)
		(width 0.1143)
		(layer "In6.Cu")
		(net "P5E_CPU1_P0_TX_DP<4>")
	)
	(segment
		(start 100.948998 -292.370764)
		(end 100.955856 -292.374828)
		(width 0.1143)
		(layer "In6.Cu")
		(net "P5E_CPU1_P0_TX_DP<4>")
	)
	(segment
		(start 104.27843 -308.77383)
		(end 109.710474 -316.903862)
		(width 0.14224)
		(layer "In6.Cu")
		(net "P5E_CPU1_P0_TX_DP<4>")
	)
	(segment
		(start 100.518976 -285.748476)
		(end 100.518214 -285.748984)
		(width 0.1143)
		(layer "In6.Cu")
		(net "P5E_CPU1_P0_TX_DP<4>")
	)
	(segment
		(start 100.990908 -290.77539)
		(end 100.991924 -290.775898)
		(width 0.1143)
		(layer "In6.Cu")
		(net "P5E_CPU1_P0_TX_DP<4>")
	)
	(arc
		(start 100.948998 -289.82162)
		(mid 100.705671 -290.286186)
		(end 100.948998 -290.750752)
		(width 0.1143)
		(layer "In6.Cu")
		(net "P5E_CPU1_P0_TX_DP<4>")
	)
	(arc
		(start 115.773708 -324.427596)
		(mid 115.81134 -324.478506)
		(end 115.843558 -324.533006)
		(width 0.14224)
		(layer "In6.Cu")
		(net "P5E_CPU1_P0_TX_DP<4>")
	)
	(arc
		(start 101.019864 -292.411912)
		(mid 101.171453 -292.716204)
		(end 101.019864 -293.020496)
		(width 0.1143)
		(layer "In6.Cu")
		(net "P5E_CPU1_P0_TX_DP<4>")
	)
	(arc
		(start 117.81028 -348.941136)
		(mid 117.532547 -349.404725)
		(end 117.132354 -349.767906)
		(width 0.14224)
		(layer "In6.Cu")
		(net "P5E_CPU1_P0_TX_DP<4>")
	)
	(arc
		(start 100.70592 -295.172892)
		(mid 100.683879 -295.283702)
		(end 100.621084 -295.377616)
		(width 0.1143)
		(layer "In6.Cu")
		(net "P5E_CPU1_P0_TX_DP<4>")
	)
	(arc
		(start 100.70592 -285.426404)
		(mid 100.664603 -285.59712)
		(end 100.549964 -285.730188)
		(width 0.1143)
		(layer "In6.Cu")
		(net "P5E_CPU1_P0_TX_DP<4>")
	)
	(arc
		(start 100.705666 -287.046162)
		(mid 100.770902 -287.309753)
		(end 100.951538 -287.512506)
		(width 0.1143)
		(layer "In6.Cu")
		(net "P5E_CPU1_P0_TX_DP<4>")
	)
	(arc
		(start 101.17582 -287.856422)
		(mid 101.135058 -288.026306)
		(end 101.021642 -288.15919)
		(width 0.1143)
		(layer "In6.Cu")
		(net "P5E_CPU1_P0_TX_DP<4>")
	)
	(arc
		(start 101.019864 -289.171888)
		(mid 101.168961 -289.47618)
		(end 101.019864 -289.780472)
		(width 0.1143)
		(layer "In6.Cu")
		(net "P5E_CPU1_P0_TX_DP<4>")
	)
	(arc
		(start 100.550726 -286.742632)
		(mid 100.664655 -286.875779)
		(end 100.705666 -287.046162)
		(width 0.1143)
		(layer "In6.Cu")
		(net "P5E_CPU1_P0_TX_DP<4>")
	)
	(arc
		(start 104.170226 -308.571138)
		(mid 104.219343 -308.675145)
		(end 104.27843 -308.77383)
		(width 0.14224)
		(layer "In6.Cu")
		(net "P5E_CPU1_P0_TX_DP<4>")
	)
	(arc
		(start 48.411384 -373.605298)
		(mid 48.399107 -373.667021)
		(end 48.36414 -373.719344)
		(width 0.14224)
		(layer "In6.Cu")
		(net "P5E_CPU1_P0_TX_DP<4>")
	)
	(arc
		(start 64.370966 -360.15422)
		(mid 64.211787 -360.195882)
		(end 64.057022 -360.251756)
		(width 0.14224)
		(layer "In6.Cu")
		(net "P5E_CPU1_P0_TX_DP<4>")
	)
	(arc
		(start 100.18522 -298.833032)
		(mid 100.196535 -298.948658)
		(end 100.230178 -299.059854)
		(width 0.14224)
		(layer "In6.Cu")
		(net "P5E_CPU1_P0_TX_DP<4>")
	)
	(arc
		(start 100.948998 -291.441632)
		(mid 100.705671 -291.906198)
		(end 100.948998 -292.370764)
		(width 0.1143)
		(layer "In6.Cu")
		(net "P5E_CPU1_P0_TX_DP<4>")
	)
	(arc
		(start 64.802512 -360.1085)
		(mid 64.585529 -360.119937)
		(end 64.370966 -360.15422)
		(width 0.14224)
		(layer "In6.Cu")
		(net "P5E_CPU1_P0_TX_DP<4>")
	)
	(arc
		(start 100.94976 -294.681148)
		(mid 100.770567 -294.883658)
		(end 100.70592 -295.146222)
		(width 0.1143)
		(layer "In6.Cu")
		(net "P5E_CPU1_P0_TX_DP<4>")
	)
	(arc
		(start 100.989892 -287.534858)
		(mid 101.125973 -287.670706)
		(end 101.17582 -287.856422)
		(width 0.1143)
		(layer "In6.Cu")
		(net "P5E_CPU1_P0_TX_DP<4>")
	)
	(arc
		(start 73.149968 -360.750104)
		(mid 72.995621 -360.734908)
		(end 72.8472 -360.689906)
		(width 0.14224)
		(layer "In6.Cu")
		(net "P5E_CPU1_P0_TX_DP<4>")
	)
	(arc
		(start 118.72849 -330.090018)
		(mid 118.788192 -330.334376)
		(end 118.83771 -330.581)
		(width 0.14224)
		(layer "In6.Cu")
		(net "P5E_CPU1_P0_TX_DP<4>")
	)
	(arc
		(start 100.844858 -360.669078)
		(mid 100.717651 -360.729381)
		(end 100.578412 -360.750104)
		(width 0.14224)
		(layer "In6.Cu")
		(net "P5E_CPU1_P0_TX_DP<4>")
	)
	(arc
		(start 109.710474 -316.903862)
		(mid 110.214294 -317.619603)
		(end 110.752636 -318.309752)
		(width 0.14224)
		(layer "In6.Cu")
		(net "P5E_CPU1_P0_TX_DP<4>")
	)
	(arc
		(start 100.948998 -288.201608)
		(mid 100.705671 -288.666174)
		(end 100.948998 -289.13074)
		(width 0.1143)
		(layer "In6.Cu")
		(net "P5E_CPU1_P0_TX_DP<4>")
	)
	(arc
		(start 100.476812 -295.521888)
		(mid 100.294837 -295.794233)
		(end 100.23094 -296.115486)
		(width 0.1143)
		(layer "In6.Cu")
		(net "P5E_CPU1_P0_TX_DP<4>")
	)
	(arc
		(start 71.617078 -360.180636)
		(mid 71.439402 -360.126722)
		(end 71.25462 -360.1085)
		(width 0.14224)
		(layer "In6.Cu")
		(net "P5E_CPU1_P0_TX_DP<4>")
	)
	(arc
		(start 101.019864 -290.7919)
		(mid 101.171453 -291.096192)
		(end 101.019864 -291.400484)
		(width 0.1143)
		(layer "In6.Cu")
		(net "P5E_CPU1_P0_TX_DP<4>")
	)
	(arc
		(start 101.169216 -284.686248)
		(mid 101.108265 -284.830061)
		(end 100.993194 -284.935676)
		(width 0.1143)
		(layer "In6.Cu")
		(net "P5E_CPU1_P0_TX_DP<4>")
	)
	(arc
		(start 120.436132 -339.471254)
		(mid 120.511877 -341.620487)
		(end 119.979694 -343.704164)
		(width 0.14224)
		(layer "In6.Cu")
		(net "P5E_CPU1_P0_TX_DP<4>")
	)
	(arc
		(start 118.673372 -329.94854)
		(mid 118.70484 -330.017757)
		(end 118.72849 -330.090018)
		(width 0.14224)
		(layer "In6.Cu")
		(net "P5E_CPU1_P0_TX_DP<4>")
	)
	(arc
		(start 100.948998 -293.061644)
		(mid 100.705671 -293.52621)
		(end 100.948998 -293.990776)
		(width 0.1143)
		(layer "In6.Cu")
		(net "P5E_CPU1_P0_TX_DP<4>")
	)
	(arc
		(start 50.804318 -366.187482)
		(mid 49.064671 -367.615251)
		(end 48.411384 -369.768882)
		(width 0.14224)
		(layer "In6.Cu")
		(net "P5E_CPU1_P0_TX_DP<4>")
	)
	(arc
		(start 100.984558 -284.940248)
		(mid 100.780416 -285.146182)
		(end 100.70592 -285.426404)
		(width 0.1143)
		(layer "In6.Cu")
		(net "P5E_CPU1_P0_TX_DP<4>")
	)
	(arc
		(start 101.02215 -294.033448)
		(mid 101.171723 -294.336216)
		(end 101.02215 -294.638984)
		(width 0.1143)
		(layer "In6.Cu")
		(net "P5E_CPU1_P0_TX_DP<4>")
	)
	(arc
		(start 100.479098 -285.771844)
		(mid 100.235771 -286.23641)
		(end 100.479098 -286.700976)
		(width 0.1143)
		(layer "In6.Cu")
		(net "P5E_CPU1_P0_TX_DP<4>")
	)
	(segment
		(start 101.268022 -282.730448)
		(end 100.80117 -282.996386)
		(width 0.12954)
		(layer "F.Cu")
		(net "P5E_CPU1_P0_TX_DP<3>")
	)
	(segment
		(start 44.716954 -369.03533)
		(end 44.987464 -369.30584)
		(width 0.12954)
		(layer "F.Cu")
		(net "P5E_CPU1_P0_TX_DP<3>")
	)
	(segment
		(start 44.987464 -370.00942)
		(end 44.691554 -370.30533)
		(width 0.12954)
		(layer "F.Cu")
		(net "P5E_CPU1_P0_TX_DP<3>")
	)
	(segment
		(start 44.987464 -369.30584)
		(end 44.987464 -370.00942)
		(width 0.12954)
		(layer "F.Cu")
		(net "P5E_CPU1_P0_TX_DP<3>")
	)
	(segment
		(start 55.526432 -363.219238)
		(end 45.662088 -367.308638)
		(width 0.14224)
		(layer "In6.Cu")
		(net "P5E_CPU1_P0_TX_DP<3>")
	)
	(segment
		(start 100.048822 -294.658288)
		(end 100.048568 -294.658542)
		(width 0.1143)
		(layer "In6.Cu")
		(net "P5E_CPU1_P0_TX_DP<3>")
	)
	(segment
		(start 100.009452 -287.511236)
		(end 100.078032 -287.551114)
		(width 0.1143)
		(layer "In6.Cu")
		(net "P5E_CPU1_P0_TX_DP<3>")
	)
	(segment
		(start 100.055172 -293.03472)
		(end 100.04806 -293.038276)
		(width 0.1143)
		(layer "In6.Cu")
		(net "P5E_CPU1_P0_TX_DP<3>")
	)
	(segment
		(start 72.991472 -359.736136)
		(end 71.813928 -359.248456)
		(width 0.14224)
		(layer "In6.Cu")
		(net "P5E_CPU1_P0_TX_DP<3>")
	)
	(segment
		(start 100.04806 -293.038276)
		(end 100.046536 -293.039292)
		(width 0.1143)
		(layer "In6.Cu")
		(net "P5E_CPU1_P0_TX_DP<3>")
	)
	(segment
		(start 100.048568 -294.658542)
		(end 100.048314 -294.658542)
		(width 0.1143)
		(layer "In6.Cu")
		(net "P5E_CPU1_P0_TX_DP<3>")
	)
	(segment
		(start 45.007784 -368.271298)
		(end 45.007784 -368.7445)
		(width 0.14224)
		(layer "In6.Cu")
		(net "P5E_CPU1_P0_TX_DP<3>")
	)
	(segment
		(start 100.00107 -293.985188)
		(end 100.00107 -293.986458)
		(width 0.1143)
		(layer "In6.Cu")
		(net "P5E_CPU1_P0_TX_DP<3>")
	)
	(segment
		(start 100.037138 -291.425376)
		(end 100.035868 -291.426138)
		(width 0.1143)
		(layer "In6.Cu")
		(net "P5E_CPU1_P0_TX_DP<3>")
	)
	(segment
		(start 100.009198 -289.131248)
		(end 100.080064 -289.172396)
		(width 0.1143)
		(layer "In6.Cu")
		(net "P5E_CPU1_P0_TX_DP<3>")
	)
	(segment
		(start 100.080318 -284.920182)
		(end 100.05568 -284.93466)
		(width 0.1143)
		(layer "In6.Cu")
		(net "P5E_CPU1_P0_TX_DP<3>")
	)
	(segment
		(start 116.60632 -348.973394)
		(end 100.45573 -359.783126)
		(width 0.14224)
		(layer "In6.Cu")
		(net "P5E_CPU1_P0_TX_DP<3>")
	)
	(segment
		(start 100.035868 -284.946344)
		(end 100.010468 -284.960568)
		(width 0.1143)
		(layer "In6.Cu")
		(net "P5E_CPU1_P0_TX_DP<3>")
	)
	(segment
		(start 63.872618 -359.31475)
		(end 56.465216 -362.38307)
		(width 0.14224)
		(layer "In6.Cu")
		(net "P5E_CPU1_P0_TX_DP<3>")
	)
	(segment
		(start 100.037138 -289.805364)
		(end 100.035868 -289.806126)
		(width 0.1143)
		(layer "In6.Cu")
		(net "P5E_CPU1_P0_TX_DP<3>")
	)
	(segment
		(start 99.29622 -296.082212)
		(end 99.29622 -296.288968)
		(width 0.1143)
		(layer "In6.Cu")
		(net "P5E_CPU1_P0_TX_DP<3>")
	)
	(segment
		(start 100.035868 -293.04615)
		(end 100.010468 -293.060374)
		(width 0.1143)
		(layer "In6.Cu")
		(net "P5E_CPU1_P0_TX_DP<3>")
	)
	(segment
		(start 71.392796 -359.164636)
		(end 64.782954 -359.164636)
		(width 0.14224)
		(layer "In6.Cu")
		(net "P5E_CPU1_P0_TX_DP<3>")
	)
	(segment
		(start 100.055172 -289.794696)
		(end 100.04806 -289.798252)
		(width 0.1143)
		(layer "In6.Cu")
		(net "P5E_CPU1_P0_TX_DP<3>")
	)
	(segment
		(start 100.00107 -292.365176)
		(end 100.00107 -292.366446)
		(width 0.1143)
		(layer "In6.Cu")
		(net "P5E_CPU1_P0_TX_DP<3>")
	)
	(segment
		(start 100.993194 -283.315664)
		(end 100.984558 -283.320236)
		(width 0.1143)
		(layer "In6.Cu")
		(net "P5E_CPU1_P0_TX_DP<3>")
	)
	(segment
		(start 100.07981 -289.780218)
		(end 100.055172 -289.794696)
		(width 0.1143)
		(layer "In6.Cu")
		(net "P5E_CPU1_P0_TX_DP<3>")
	)
	(segment
		(start 99.29622 -296.288968)
		(end 99.2505 -296.334688)
		(width 0.1143)
		(layer "In6.Cu")
		(net "P5E_CPU1_P0_TX_DP<3>")
	)
	(segment
		(start 100.035868 -291.426138)
		(end 100.010468 -291.440362)
		(width 0.1143)
		(layer "In6.Cu")
		(net "P5E_CPU1_P0_TX_DP<3>")
	)
	(segment
		(start 100.07981 -291.40023)
		(end 100.055172 -291.414708)
		(width 0.1143)
		(layer "In6.Cu")
		(net "P5E_CPU1_P0_TX_DP<3>")
	)
	(segment
		(start 100.044504 -289.800284)
		(end 100.037138 -289.805364)
		(width 0.1143)
		(layer "In6.Cu")
		(net "P5E_CPU1_P0_TX_DP<3>")
	)
	(segment
		(start 100.00107 -292.366446)
		(end 100.080064 -292.41242)
		(width 0.1143)
		(layer "In6.Cu")
		(net "P5E_CPU1_P0_TX_DP<3>")
	)
	(segment
		(start 100.037138 -284.945582)
		(end 100.035868 -284.946344)
		(width 0.1143)
		(layer "In6.Cu")
		(net "P5E_CPU1_P0_TX_DP<3>")
	)
	(segment
		(start 100.384864 -359.804716)
		(end 73.336404 -359.804716)
		(width 0.14224)
		(layer "In6.Cu")
		(net "P5E_CPU1_P0_TX_DP<3>")
	)
	(segment
		(start 101.168962 -283.066236)
		(end 101.169216 -283.066236)
		(width 0.1143)
		(layer "In6.Cu")
		(net "P5E_CPU1_P0_TX_DP<3>")
	)
	(segment
		(start 100.046536 -284.939486)
		(end 100.044504 -284.940502)
		(width 0.1143)
		(layer "In6.Cu")
		(net "P5E_CPU1_P0_TX_DP<3>")
	)
	(segment
		(start 100.07981 -293.020242)
		(end 100.055172 -293.03472)
		(width 0.1143)
		(layer "In6.Cu")
		(net "P5E_CPU1_P0_TX_DP<3>")
	)
	(segment
		(start 100.035868 -289.806126)
		(end 100.010468 -289.82035)
		(width 0.1143)
		(layer "In6.Cu")
		(net "P5E_CPU1_P0_TX_DP<3>")
	)
	(segment
		(start 100.080064 -288.16046)
		(end 100.006912 -288.203132)
		(width 0.1143)
		(layer "In6.Cu")
		(net "P5E_CPU1_P0_TX_DP<3>")
	)
	(segment
		(start 99.60991 -285.730442)
		(end 99.540568 -285.770828)
		(width 0.1143)
		(layer "In6.Cu")
		(net "P5E_CPU1_P0_TX_DP<3>")
	)
	(segment
		(start 99.765612 -295.115488)
		(end 99.765358 -295.145968)
		(width 0.1143)
		(layer "In6.Cu")
		(net "P5E_CPU1_P0_TX_DP<3>")
	)
	(segment
		(start 100.00107 -293.986458)
		(end 100.080064 -294.032432)
		(width 0.1143)
		(layer "In6.Cu")
		(net "P5E_CPU1_P0_TX_DP<3>")
	)
	(segment
		(start 100.016564 -294.677084)
		(end 100.009198 -294.681402)
		(width 0.1143)
		(layer "In6.Cu")
		(net "P5E_CPU1_P0_TX_DP<3>")
	)
	(segment
		(start 109.787944 -318.628776)
		(end 114.976656 -324.951598)
		(width 0.14224)
		(layer "In6.Cu")
		(net "P5E_CPU1_P0_TX_DP<3>")
	)
	(segment
		(start 100.04806 -284.93847)
		(end 100.046536 -284.939486)
		(width 0.1143)
		(layer "In6.Cu")
		(net "P5E_CPU1_P0_TX_DP<3>")
	)
	(segment
		(start 103.465884 -309.247286)
		(end 109.395006 -318.120014)
		(width 0.14224)
		(layer "In6.Cu")
		(net "P5E_CPU1_P0_TX_DP<3>")
	)
	(segment
		(start 100.80117 -282.996386)
		(end 101.099112 -282.996386)
		(width 0.1143)
		(layer "In6.Cu")
		(net "P5E_CPU1_P0_TX_DP<3>")
	)
	(segment
		(start 100.05568 -284.93466)
		(end 100.04806 -284.93847)
		(width 0.1143)
		(layer "In6.Cu")
		(net "P5E_CPU1_P0_TX_DP<3>")
	)
	(segment
		(start 56.254396 -362.524294)
		(end 55.626254 -363.15269)
		(width 0.14224)
		(layer "In6.Cu")
		(net "P5E_CPU1_P0_TX_DP<3>")
	)
	(segment
		(start 100.04806 -289.798252)
		(end 100.046536 -289.799268)
		(width 0.1143)
		(layer "In6.Cu")
		(net "P5E_CPU1_P0_TX_DP<3>")
	)
	(segment
		(start 100.046536 -289.799268)
		(end 100.044504 -289.800284)
		(width 0.1143)
		(layer "In6.Cu")
		(net "P5E_CPU1_P0_TX_DP<3>")
	)
	(segment
		(start 99.582732 -295.583102)
		(end 99.446334 -295.719246)
		(width 0.1143)
		(layer "In6.Cu")
		(net "P5E_CPU1_P0_TX_DP<3>")
	)
	(segment
		(start 100.046536 -293.039292)
		(end 100.044504 -293.040308)
		(width 0.1143)
		(layer "In6.Cu")
		(net "P5E_CPU1_P0_TX_DP<3>")
	)
	(segment
		(start 45.007784 -368.7445)
		(end 44.716954 -369.03533)
		(width 0.14224)
		(layer "In6.Cu")
		(net "P5E_CPU1_P0_TX_DP<3>")
	)
	(segment
		(start 99.766882 -295.112186)
		(end 99.765612 -295.115488)
		(width 0.1143)
		(layer "In6.Cu")
		(net "P5E_CPU1_P0_TX_DP<3>")
	)
	(segment
		(start 100.044504 -293.040308)
		(end 100.037138 -293.045388)
		(width 0.1143)
		(layer "In6.Cu")
		(net "P5E_CPU1_P0_TX_DP<3>")
	)
	(segment
		(start 99.538028 -286.700468)
		(end 99.60991 -286.742378)
		(width 0.1143)
		(layer "In6.Cu")
		(net "P5E_CPU1_P0_TX_DP<3>")
	)
	(segment
		(start 100.00107 -290.746434)
		(end 100.080064 -290.792408)
		(width 0.1143)
		(layer "In6.Cu")
		(net "P5E_CPU1_P0_TX_DP<3>")
	)
	(segment
		(start 100.048314 -294.658542)
		(end 100.016564 -294.677084)
		(width 0.1143)
		(layer "In6.Cu")
		(net "P5E_CPU1_P0_TX_DP<3>")
	)
	(segment
		(start 100.048822 -294.658034)
		(end 100.048822 -294.658288)
		(width 0.1143)
		(layer "In6.Cu")
		(net "P5E_CPU1_P0_TX_DP<3>")
	)
	(segment
		(start 100.009198 -294.681402)
		(end 100.009198 -294.681148)
		(width 0.1143)
		(layer "In6.Cu")
		(net "P5E_CPU1_P0_TX_DP<3>")
	)
	(segment
		(start 100.04806 -291.418264)
		(end 100.046536 -291.41928)
		(width 0.1143)
		(layer "In6.Cu")
		(net "P5E_CPU1_P0_TX_DP<3>")
	)
	(segment
		(start 100.044504 -291.420296)
		(end 100.037138 -291.425376)
		(width 0.1143)
		(layer "In6.Cu")
		(net "P5E_CPU1_P0_TX_DP<3>")
	)
	(segment
		(start 115.014248 -325.007986)
		(end 117.835426 -330.434442)
		(width 0.14224)
		(layer "In6.Cu")
		(net "P5E_CPU1_P0_TX_DP<3>")
	)
	(segment
		(start 100.037138 -293.045388)
		(end 100.035868 -293.04615)
		(width 0.1143)
		(layer "In6.Cu")
		(net "P5E_CPU1_P0_TX_DP<3>")
	)
	(segment
		(start 100.00107 -290.745164)
		(end 100.00107 -290.746434)
		(width 0.1143)
		(layer "In6.Cu")
		(net "P5E_CPU1_P0_TX_DP<3>")
	)
	(segment
		(start 117.920262 -330.759308)
		(end 119.491506 -339.500972)
		(width 0.14224)
		(layer "In6.Cu")
		(net "P5E_CPU1_P0_TX_DP<3>")
	)
	(segment
		(start 45.466508 -367.439702)
		(end 45.271436 -367.634774)
		(width 0.14224)
		(layer "In6.Cu")
		(net "P5E_CPU1_P0_TX_DP<3>")
	)
	(segment
		(start 99.2505 -296.363136)
		(end 99.2505 -299.051218)
		(width 0.14224)
		(layer "In6.Cu")
		(net "P5E_CPU1_P0_TX_DP<3>")
	)
	(segment
		(start 100.549964 -284.11043)
		(end 100.479098 -284.151832)
		(width 0.1143)
		(layer "In6.Cu")
		(net "P5E_CPU1_P0_TX_DP<3>")
	)
	(segment
		(start 99.281488 -299.207682)
		(end 103.347266 -309.025036)
		(width 0.14224)
		(layer "In6.Cu")
		(net "P5E_CPU1_P0_TX_DP<3>")
	)
	(segment
		(start 100.080064 -294.64)
		(end 100.055934 -294.654224)
		(width 0.1143)
		(layer "In6.Cu")
		(net "P5E_CPU1_P0_TX_DP<3>")
	)
	(segment
		(start 100.055172 -291.414708)
		(end 100.04806 -291.418264)
		(width 0.1143)
		(layer "In6.Cu")
		(net "P5E_CPU1_P0_TX_DP<3>")
	)
	(segment
		(start 100.046536 -291.41928)
		(end 100.044504 -291.420296)
		(width 0.1143)
		(layer "In6.Cu")
		(net "P5E_CPU1_P0_TX_DP<3>")
	)
	(segment
		(start 100.055934 -294.654224)
		(end 100.048822 -294.658034)
		(width 0.1143)
		(layer "In6.Cu")
		(net "P5E_CPU1_P0_TX_DP<3>")
	)
	(segment
		(start 99.2505 -296.334688)
		(end 99.2505 -296.363136)
		(width 0.1143)
		(layer "In6.Cu")
		(net "P5E_CPU1_P0_TX_DP<3>")
	)
	(segment
		(start 119.065802 -343.449148)
		(end 116.952268 -348.5515)
		(width 0.14224)
		(layer "In6.Cu")
		(net "P5E_CPU1_P0_TX_DP<3>")
	)
	(segment
		(start 101.099112 -282.996386)
		(end 101.168962 -283.066236)
		(width 0.1143)
		(layer "In6.Cu")
		(net "P5E_CPU1_P0_TX_DP<3>")
	)
	(segment
		(start 100.044504 -284.940502)
		(end 100.037138 -284.945582)
		(width 0.1143)
		(layer "In6.Cu")
		(net "P5E_CPU1_P0_TX_DP<3>")
	)
	(arc
		(start 99.765866 -287.046162)
		(mid 99.830384 -287.308704)
		(end 100.009452 -287.511236)
		(width 0.1143)
		(layer "In6.Cu")
		(net "P5E_CPU1_P0_TX_DP<3>")
	)
	(arc
		(start 64.205866 -359.219246)
		(mid 64.115255 -359.23872)
		(end 64.025526 -359.261918)
		(width 0.14224)
		(layer "In6.Cu")
		(net "P5E_CPU1_P0_TX_DP<3>")
	)
	(arc
		(start 64.782954 -359.164636)
		(mid 64.493118 -359.178287)
		(end 64.205866 -359.219246)
		(width 0.14224)
		(layer "In6.Cu")
		(net "P5E_CPU1_P0_TX_DP<3>")
	)
	(arc
		(start 100.009198 -294.681148)
		(mid 99.838376 -294.868761)
		(end 99.766882 -295.112186)
		(width 0.1143)
		(layer "In6.Cu")
		(net "P5E_CPU1_P0_TX_DP<3>")
	)
	(arc
		(start 103.347266 -309.025036)
		(mid 103.401112 -309.139076)
		(end 103.465884 -309.247286)
		(width 0.14224)
		(layer "In6.Cu")
		(net "P5E_CPU1_P0_TX_DP<3>")
	)
	(arc
		(start 73.336404 -359.804716)
		(mid 73.160562 -359.787404)
		(end 72.991472 -359.736136)
		(width 0.14224)
		(layer "In6.Cu")
		(net "P5E_CPU1_P0_TX_DP<3>")
	)
	(arc
		(start 100.006912 -288.203132)
		(mid 99.829716 -288.405144)
		(end 99.765866 -288.666174)
		(width 0.1143)
		(layer "In6.Cu")
		(net "P5E_CPU1_P0_TX_DP<3>")
	)
	(arc
		(start 100.010468 -293.060374)
		(mid 99.765578 -293.520393)
		(end 100.00107 -293.985188)
		(width 0.1143)
		(layer "In6.Cu")
		(net "P5E_CPU1_P0_TX_DP<3>")
	)
	(arc
		(start 99.765866 -285.426404)
		(mid 99.724607 -285.597261)
		(end 99.60991 -285.730442)
		(width 0.1143)
		(layer "In6.Cu")
		(net "P5E_CPU1_P0_TX_DP<3>")
	)
	(arc
		(start 45.271436 -367.634774)
		(mid 45.076301 -367.926814)
		(end 45.007784 -368.271298)
		(width 0.14224)
		(layer "In6.Cu")
		(net "P5E_CPU1_P0_TX_DP<3>")
	)
	(arc
		(start 99.765866 -288.666174)
		(mid 99.830336 -288.928624)
		(end 100.009198 -289.131248)
		(width 0.1143)
		(layer "In6.Cu")
		(net "P5E_CPU1_P0_TX_DP<3>")
	)
	(arc
		(start 109.395006 -318.120014)
		(mid 109.587728 -318.377289)
		(end 109.787944 -318.628776)
		(width 0.14224)
		(layer "In6.Cu")
		(net "P5E_CPU1_P0_TX_DP<3>")
	)
	(arc
		(start 100.010468 -284.960568)
		(mid 99.83068 -285.1633)
		(end 99.765866 -285.426404)
		(width 0.1143)
		(layer "In6.Cu")
		(net "P5E_CPU1_P0_TX_DP<3>")
	)
	(arc
		(start 100.984558 -283.320236)
		(mid 100.780416 -283.52617)
		(end 100.70592 -283.806392)
		(width 0.1143)
		(layer "In6.Cu")
		(net "P5E_CPU1_P0_TX_DP<3>")
	)
	(arc
		(start 99.60991 -286.742378)
		(mid 99.724529 -286.875456)
		(end 99.765866 -287.046162)
		(width 0.1143)
		(layer "In6.Cu")
		(net "P5E_CPU1_P0_TX_DP<3>")
	)
	(arc
		(start 99.446334 -295.719246)
		(mid 99.335145 -295.885791)
		(end 99.29622 -296.082212)
		(width 0.1143)
		(layer "In6.Cu")
		(net "P5E_CPU1_P0_TX_DP<3>")
	)
	(arc
		(start 100.080064 -294.032432)
		(mid 100.235685 -294.336216)
		(end 100.080064 -294.64)
		(width 0.1143)
		(layer "In6.Cu")
		(net "P5E_CPU1_P0_TX_DP<3>")
	)
	(arc
		(start 56.465216 -362.38307)
		(mid 56.352874 -362.443332)
		(end 56.254396 -362.524294)
		(width 0.14224)
		(layer "In6.Cu")
		(net "P5E_CPU1_P0_TX_DP<3>")
	)
	(arc
		(start 100.080064 -289.172396)
		(mid 100.23558 -289.476357)
		(end 100.07981 -289.780218)
		(width 0.1143)
		(layer "In6.Cu")
		(net "P5E_CPU1_P0_TX_DP<3>")
	)
	(arc
		(start 100.078032 -287.551114)
		(mid 100.235634 -287.855226)
		(end 100.080064 -288.16046)
		(width 0.1143)
		(layer "In6.Cu")
		(net "P5E_CPU1_P0_TX_DP<3>")
	)
	(arc
		(start 99.295966 -286.23641)
		(mid 99.36006 -286.498141)
		(end 99.538028 -286.700468)
		(width 0.1143)
		(layer "In6.Cu")
		(net "P5E_CPU1_P0_TX_DP<3>")
	)
	(arc
		(start 101.169216 -283.066236)
		(mid 101.108265 -283.210049)
		(end 100.993194 -283.315664)
		(width 0.1143)
		(layer "In6.Cu")
		(net "P5E_CPU1_P0_TX_DP<3>")
	)
	(arc
		(start 55.626254 -363.15269)
		(mid 55.579622 -363.190887)
		(end 55.526432 -363.219238)
		(width 0.14224)
		(layer "In6.Cu")
		(net "P5E_CPU1_P0_TX_DP<3>")
	)
	(arc
		(start 99.765358 -295.145968)
		(mid 99.717399 -295.382646)
		(end 99.582732 -295.583102)
		(width 0.1143)
		(layer "In6.Cu")
		(net "P5E_CPU1_P0_TX_DP<3>")
	)
	(arc
		(start 100.235766 -284.616398)
		(mid 100.194654 -284.78703)
		(end 100.080318 -284.920182)
		(width 0.1143)
		(layer "In6.Cu")
		(net "P5E_CPU1_P0_TX_DP<3>")
	)
	(arc
		(start 71.813928 -359.248456)
		(mid 71.607494 -359.185779)
		(end 71.392796 -359.164636)
		(width 0.14224)
		(layer "In6.Cu")
		(net "P5E_CPU1_P0_TX_DP<3>")
	)
	(arc
		(start 99.2505 -299.051218)
		(mid 99.258293 -299.130976)
		(end 99.281488 -299.207682)
		(width 0.14224)
		(layer "In6.Cu")
		(net "P5E_CPU1_P0_TX_DP<3>")
	)
	(arc
		(start 114.976656 -324.951598)
		(mid 114.996917 -324.978815)
		(end 115.014248 -325.007986)
		(width 0.14224)
		(layer "In6.Cu")
		(net "P5E_CPU1_P0_TX_DP<3>")
	)
	(arc
		(start 116.952268 -348.5515)
		(mid 116.810579 -348.78811)
		(end 116.60632 -348.973394)
		(width 0.14224)
		(layer "In6.Cu")
		(net "P5E_CPU1_P0_TX_DP<3>")
	)
	(arc
		(start 100.45573 -359.783126)
		(mid 100.421907 -359.799211)
		(end 100.384864 -359.804716)
		(width 0.14224)
		(layer "In6.Cu")
		(net "P5E_CPU1_P0_TX_DP<3>")
	)
	(arc
		(start 100.010468 -289.82035)
		(mid 99.765578 -290.280369)
		(end 100.00107 -290.745164)
		(width 0.1143)
		(layer "In6.Cu")
		(net "P5E_CPU1_P0_TX_DP<3>")
	)
	(arc
		(start 100.70592 -283.806392)
		(mid 100.664661 -283.977249)
		(end 100.549964 -284.11043)
		(width 0.1143)
		(layer "In6.Cu")
		(net "P5E_CPU1_P0_TX_DP<3>")
	)
	(arc
		(start 45.662088 -367.308638)
		(mid 45.557857 -367.364559)
		(end 45.466508 -367.439702)
		(width 0.14224)
		(layer "In6.Cu")
		(net "P5E_CPU1_P0_TX_DP<3>")
	)
	(arc
		(start 117.835426 -330.434442)
		(mid 117.861013 -330.492464)
		(end 117.87886 -330.553314)
		(width 0.14224)
		(layer "In6.Cu")
		(net "P5E_CPU1_P0_TX_DP<3>")
	)
	(arc
		(start 64.025526 -359.261918)
		(mid 63.948281 -359.286043)
		(end 63.872618 -359.31475)
		(width 0.14224)
		(layer "In6.Cu")
		(net "P5E_CPU1_P0_TX_DP<3>")
	)
	(arc
		(start 100.010468 -291.440362)
		(mid 99.765578 -291.900381)
		(end 100.00107 -292.365176)
		(width 0.1143)
		(layer "In6.Cu")
		(net "P5E_CPU1_P0_TX_DP<3>")
	)
	(arc
		(start 100.080064 -290.792408)
		(mid 100.23558 -291.096369)
		(end 100.07981 -291.40023)
		(width 0.1143)
		(layer "In6.Cu")
		(net "P5E_CPU1_P0_TX_DP<3>")
	)
	(arc
		(start 99.540568 -285.770828)
		(mid 99.360776 -285.973416)
		(end 99.295966 -286.23641)
		(width 0.1143)
		(layer "In6.Cu")
		(net "P5E_CPU1_P0_TX_DP<3>")
	)
	(arc
		(start 119.491506 -339.500972)
		(mid 119.562186 -341.505635)
		(end 119.065802 -343.449148)
		(width 0.14224)
		(layer "In6.Cu")
		(net "P5E_CPU1_P0_TX_DP<3>")
	)
	(arc
		(start 117.87886 -330.553314)
		(mid 117.900634 -330.656095)
		(end 117.920262 -330.759308)
		(width 0.14224)
		(layer "In6.Cu")
		(net "P5E_CPU1_P0_TX_DP<3>")
	)
	(arc
		(start 100.479098 -284.151832)
		(mid 100.300285 -284.354182)
		(end 100.235766 -284.616398)
		(width 0.1143)
		(layer "In6.Cu")
		(net "P5E_CPU1_P0_TX_DP<3>")
	)
	(arc
		(start 100.080064 -292.41242)
		(mid 100.23558 -292.716381)
		(end 100.07981 -293.020242)
		(width 0.1143)
		(layer "In6.Cu")
		(net "P5E_CPU1_P0_TX_DP<3>")
	)
	(segment
		(start 98.44786 -281.110436)
		(end 97.981008 -281.376374)
		(width 0.12954)
		(layer "F.Cu")
		(net "P5E_CPU1_P0_TX_DP<2>")
	)
	(segment
		(start 43.285664 -372.47322)
		(end 42.989754 -372.76913)
		(width 0.12954)
		(layer "F.Cu")
		(net "P5E_CPU1_P0_TX_DP<2>")
	)
	(segment
		(start 43.285664 -371.76964)
		(end 43.285664 -372.47322)
		(width 0.12954)
		(layer "F.Cu")
		(net "P5E_CPU1_P0_TX_DP<2>")
	)
	(segment
		(start 43.015154 -371.49913)
		(end 43.285664 -371.76964)
		(width 0.12954)
		(layer "F.Cu")
		(net "P5E_CPU1_P0_TX_DP<2>")
	)
	(segment
		(start 99.115118 -294.654732)
		(end 99.108006 -294.658288)
		(width 0.1143)
		(layer "In6.Cu")
		(net "P5E_CPU1_P0_TX_DP<2>")
	)
	(segment
		(start 98.638868 -281.864054)
		(end 98.6409 -281.86507)
		(width 0.1143)
		(layer "In6.Cu")
		(net "P5E_CPU1_P0_TX_DP<2>")
	)
	(segment
		(start 99.182174 -284.347666)
		(end 99.185222 -284.35046)
		(width 0.1143)
		(layer "In6.Cu")
		(net "P5E_CPU1_P0_TX_DP<2>")
	)
	(segment
		(start 98.310192 -296.281348)
		(end 98.310192 -299.123354)
		(width 0.14224)
		(layer "In6.Cu")
		(net "P5E_CPU1_P0_TX_DP<2>")
	)
	(segment
		(start 44.372276 -366.879378)
		(end 44.252134 -366.99952)
		(width 0.14224)
		(layer "In6.Cu")
		(net "P5E_CPU1_P0_TX_DP<2>")
	)
	(segment
		(start 98.606864 -285.767272)
		(end 98.599498 -285.771336)
		(width 0.1143)
		(layer "In6.Cu")
		(net "P5E_CPU1_P0_TX_DP<2>")
	)
	(segment
		(start 99.066858 -290.74999)
		(end 99.108514 -290.773612)
		(width 0.1143)
		(layer "In6.Cu")
		(net "P5E_CPU1_P0_TX_DP<2>")
	)
	(segment
		(start 99.069398 -288.201354)
		(end 99.058476 -288.209228)
		(width 0.1143)
		(layer "In6.Cu")
		(net "P5E_CPU1_P0_TX_DP<2>")
	)
	(segment
		(start 115.624102 -348.506034)
		(end 100.273104 -358.781604)
		(width 0.14224)
		(layer "In6.Cu")
		(net "P5E_CPU1_P0_TX_DP<2>")
	)
	(segment
		(start 99.116642 -283.314394)
		(end 99.067112 -283.342588)
		(width 0.1143)
		(layer "In6.Cu")
		(net "P5E_CPU1_P0_TX_DP<2>")
	)
	(segment
		(start 98.355912 -296.20718)
		(end 98.310192 -296.2529)
		(width 0.1143)
		(layer "In6.Cu")
		(net "P5E_CPU1_P0_TX_DP<2>")
	)
	(segment
		(start 98.721672 -295.402508)
		(end 98.561652 -295.562528)
		(width 0.1143)
		(layer "In6.Cu")
		(net "P5E_CPU1_P0_TX_DP<2>")
	)
	(segment
		(start 98.844862 -285.307786)
		(end 98.823018 -285.474918)
		(width 0.1143)
		(layer "In6.Cu")
		(net "P5E_CPU1_P0_TX_DP<2>")
	)
	(segment
		(start 43.305984 -371.2083)
		(end 43.015154 -371.49913)
		(width 0.14224)
		(layer "In6.Cu")
		(net "P5E_CPU1_P0_TX_DP<2>")
	)
	(segment
		(start 99.120452 -283.312108)
		(end 99.120706 -283.311854)
		(width 0.1143)
		(layer "In6.Cu")
		(net "P5E_CPU1_P0_TX_DP<2>")
	)
	(segment
		(start 117.01145 -331.03566)
		(end 118.535196 -339.514688)
		(width 0.14224)
		(layer "In6.Cu")
		(net "P5E_CPU1_P0_TX_DP<2>")
	)
	(segment
		(start 99.140264 -288.160206)
		(end 99.069398 -288.201354)
		(width 0.1143)
		(layer "In6.Cu")
		(net "P5E_CPU1_P0_TX_DP<2>")
	)
	(segment
		(start 98.825812 -287.046162)
		(end 98.825812 -287.053782)
		(width 0.1143)
		(layer "In6.Cu")
		(net "P5E_CPU1_P0_TX_DP<2>")
	)
	(segment
		(start 99.122738 -283.310584)
		(end 99.120452 -283.312108)
		(width 0.1143)
		(layer "In6.Cu")
		(net "P5E_CPU1_P0_TX_DP<2>")
	)
	(segment
		(start 98.380042 -299.475144)
		(end 102.587044 -309.632096)
		(width 0.14224)
		(layer "In6.Cu")
		(net "P5E_CPU1_P0_TX_DP<2>")
	)
	(segment
		(start 98.668332 -285.731458)
		(end 98.606864 -285.767272)
		(width 0.1143)
		(layer "In6.Cu")
		(net "P5E_CPU1_P0_TX_DP<2>")
	)
	(segment
		(start 54.856888 -362.487464)
		(end 44.568618 -366.748314)
		(width 0.14224)
		(layer "In6.Cu")
		(net "P5E_CPU1_P0_TX_DP<2>")
	)
	(segment
		(start 99.066858 -289.129978)
		(end 99.14001 -289.172142)
		(width 0.1143)
		(layer "In6.Cu")
		(net "P5E_CPU1_P0_TX_DP<2>")
	)
	(segment
		(start 71.600568 -358.226868)
		(end 64.46647 -358.226868)
		(width 0.14224)
		(layer "In6.Cu")
		(net "P5E_CPU1_P0_TX_DP<2>")
	)
	(segment
		(start 59.752738 -359.997502)
		(end 59.752738 -359.997756)
		(width 0.14224)
		(layer "In6.Cu")
		(net "P5E_CPU1_P0_TX_DP<2>")
	)
	(segment
		(start 98.599244 -286.700976)
		(end 98.61042 -286.707072)
		(width 0.1143)
		(layer "In6.Cu")
		(net "P5E_CPU1_P0_TX_DP<2>")
	)
	(segment
		(start 99.139756 -294.640254)
		(end 99.115118 -294.654732)
		(width 0.1143)
		(layer "In6.Cu")
		(net "P5E_CPU1_P0_TX_DP<2>")
	)
	(segment
		(start 102.656894 -309.76316)
		(end 108.484416 -318.48425)
		(width 0.14224)
		(layer "In6.Cu")
		(net "P5E_CPU1_P0_TX_DP<2>")
	)
	(segment
		(start 63.614554 -358.396286)
		(end 59.752738 -359.997502)
		(width 0.14224)
		(layer "In6.Cu")
		(net "P5E_CPU1_P0_TX_DP<2>")
	)
	(segment
		(start 114.208306 -325.531988)
		(end 116.93398 -330.744068)
		(width 0.14224)
		(layer "In6.Cu")
		(net "P5E_CPU1_P0_TX_DP<2>")
	)
	(segment
		(start 118.535196 -339.514688)
		(end 118.535196 -339.514434)
		(width 0.14224)
		(layer "In6.Cu")
		(net "P5E_CPU1_P0_TX_DP<2>")
	)
	(segment
		(start 73.112376 -358.75468)
		(end 72.057768 -358.3178)
		(width 0.14224)
		(layer "In6.Cu")
		(net "P5E_CPU1_P0_TX_DP<2>")
	)
	(segment
		(start 99.263708 -284.779212)
		(end 99.259136 -284.78861)
		(width 0.1143)
		(layer "In6.Cu")
		(net "P5E_CPU1_P0_TX_DP<2>")
	)
	(segment
		(start 98.355912 -286.23641)
		(end 98.355912 -286.246824)
		(width 0.1143)
		(layer "In6.Cu")
		(net "P5E_CPU1_P0_TX_DP<2>")
	)
	(segment
		(start 99.184206 -284.88132)
		(end 99.025456 -284.99943)
		(width 0.1143)
		(layer "In6.Cu")
		(net "P5E_CPU1_P0_TX_DP<2>")
	)
	(segment
		(start 99.179888 -284.34538)
		(end 99.182174 -284.347666)
		(width 0.1143)
		(layer "In6.Cu")
		(net "P5E_CPU1_P0_TX_DP<2>")
	)
	(segment
		(start 98.825812 -295.14292)
		(end 98.825812 -295.151048)
		(width 0.1143)
		(layer "In6.Cu")
		(net "P5E_CPU1_P0_TX_DP<2>")
	)
	(segment
		(start 99.066858 -284.270196)
		(end 99.13366 -284.30855)
		(width 0.1143)
		(layer "In6.Cu")
		(net "P5E_CPU1_P0_TX_DP<2>")
	)
	(segment
		(start 99.185222 -284.35046)
		(end 99.185984 -284.351476)
		(width 0.1143)
		(layer "In6.Cu")
		(net "P5E_CPU1_P0_TX_DP<2>")
	)
	(segment
		(start 99.108514 -292.393624)
		(end 99.139756 -292.412166)
		(width 0.1143)
		(layer "In6.Cu")
		(net "P5E_CPU1_P0_TX_DP<2>")
	)
	(segment
		(start 59.752738 -359.997756)
		(end 55.838598 -361.62107)
		(width 0.14224)
		(layer "In6.Cu")
		(net "P5E_CPU1_P0_TX_DP<2>")
	)
	(segment
		(start 98.59899 -281.84094)
		(end 98.638106 -281.8638)
		(width 0.1143)
		(layer "In6.Cu")
		(net "P5E_CPU1_P0_TX_DP<2>")
	)
	(segment
		(start 99.14001 -291.40023)
		(end 99.067874 -291.441886)
		(width 0.1143)
		(layer "In6.Cu")
		(net "P5E_CPU1_P0_TX_DP<2>")
	)
	(segment
		(start 99.14001 -289.780218)
		(end 99.066858 -289.822636)
		(width 0.1143)
		(layer "In6.Cu")
		(net "P5E_CPU1_P0_TX_DP<2>")
	)
	(segment
		(start 99.067874 -292.37051)
		(end 99.108514 -292.393624)
		(width 0.1143)
		(layer "In6.Cu")
		(net "P5E_CPU1_P0_TX_DP<2>")
	)
	(segment
		(start 98.581718 -286.68853)
		(end 98.599244 -286.700976)
		(width 0.1143)
		(layer "In6.Cu")
		(net "P5E_CPU1_P0_TX_DP<2>")
	)
	(segment
		(start 108.888022 -319.028826)
		(end 114.13871 -325.426578)
		(width 0.14224)
		(layer "In6.Cu")
		(net "P5E_CPU1_P0_TX_DP<2>")
	)
	(segment
		(start 99.120706 -283.311854)
		(end 99.116642 -283.314394)
		(width 0.1143)
		(layer "In6.Cu")
		(net "P5E_CPU1_P0_TX_DP<2>")
	)
	(segment
		(start 99.108006 -294.658288)
		(end 99.100894 -294.663114)
		(width 0.1143)
		(layer "In6.Cu")
		(net "P5E_CPU1_P0_TX_DP<2>")
	)
	(segment
		(start 98.82759 -282.189428)
		(end 98.82759 -282.199842)
		(width 0.1143)
		(layer "In6.Cu")
		(net "P5E_CPU1_P0_TX_DP<2>")
	)
	(segment
		(start 99.100894 -294.663114)
		(end 99.066858 -294.682418)
		(width 0.1143)
		(layer "In6.Cu")
		(net "P5E_CPU1_P0_TX_DP<2>")
	)
	(segment
		(start 99.14001 -293.020242)
		(end 99.066858 -293.06266)
		(width 0.1143)
		(layer "In6.Cu")
		(net "P5E_CPU1_P0_TX_DP<2>")
	)
	(segment
		(start 99.068382 -287.510728)
		(end 99.137978 -287.551114)
		(width 0.1143)
		(layer "In6.Cu")
		(net "P5E_CPU1_P0_TX_DP<2>")
	)
	(segment
		(start 98.825812 -295.151048)
		(end 98.825558 -295.150794)
		(width 0.1143)
		(layer "In6.Cu")
		(net "P5E_CPU1_P0_TX_DP<2>")
	)
	(segment
		(start 99.13366 -284.30855)
		(end 99.134168 -284.308804)
		(width 0.1143)
		(layer "In6.Cu")
		(net "P5E_CPU1_P0_TX_DP<2>")
	)
	(segment
		(start 99.108514 -294.013636)
		(end 99.139756 -294.032178)
		(width 0.1143)
		(layer "In6.Cu")
		(net "P5E_CPU1_P0_TX_DP<2>")
	)
	(segment
		(start 98.638106 -281.8638)
		(end 98.638868 -281.864308)
		(width 0.1143)
		(layer "In6.Cu")
		(net "P5E_CPU1_P0_TX_DP<2>")
	)
	(segment
		(start 98.6409 -281.86507)
		(end 98.641154 -281.86507)
		(width 0.1143)
		(layer "In6.Cu")
		(net "P5E_CPU1_P0_TX_DP<2>")
	)
	(segment
		(start 99.054666 -287.500568)
		(end 99.068382 -287.510728)
		(width 0.1143)
		(layer "In6.Cu")
		(net "P5E_CPU1_P0_TX_DP<2>")
	)
	(segment
		(start 98.355912 -296.058844)
		(end 98.355912 -296.20718)
		(width 0.1143)
		(layer "In6.Cu")
		(net "P5E_CPU1_P0_TX_DP<2>")
	)
	(segment
		(start 98.638868 -281.864308)
		(end 98.638868 -281.864054)
		(width 0.1143)
		(layer "In6.Cu")
		(net "P5E_CPU1_P0_TX_DP<2>")
	)
	(segment
		(start 97.981008 -281.376374)
		(end 98.27895 -281.376374)
		(width 0.1143)
		(layer "In6.Cu")
		(net "P5E_CPU1_P0_TX_DP<2>")
	)
	(segment
		(start 99.997768 -358.865424)
		(end 73.669398 -358.865424)
		(width 0.14224)
		(layer "In6.Cu")
		(net "P5E_CPU1_P0_TX_DP<2>")
	)
	(segment
		(start 98.61042 -286.707072)
		(end 98.667824 -286.7406)
		(width 0.1143)
		(layer "In6.Cu")
		(net "P5E_CPU1_P0_TX_DP<2>")
	)
	(segment
		(start 99.097592 -282.667964)
		(end 99.14255 -282.696158)
		(width 0.1143)
		(layer "In6.Cu")
		(net "P5E_CPU1_P0_TX_DP<2>")
	)
	(segment
		(start 98.580956 -286.688022)
		(end 98.581718 -286.68853)
		(width 0.1143)
		(layer "In6.Cu")
		(net "P5E_CPU1_P0_TX_DP<2>")
	)
	(segment
		(start 98.27895 -281.376374)
		(end 98.361754 -281.459178)
		(width 0.1143)
		(layer "In6.Cu")
		(net "P5E_CPU1_P0_TX_DP<2>")
	)
	(segment
		(start 99.139756 -283.300678)
		(end 99.122738 -283.310584)
		(width 0.1143)
		(layer "In6.Cu")
		(net "P5E_CPU1_P0_TX_DP<2>")
	)
	(segment
		(start 118.151148 -343.07653)
		(end 116.185696 -347.82125)
		(width 0.14224)
		(layer "In6.Cu")
		(net "P5E_CPU1_P0_TX_DP<2>")
	)
	(segment
		(start 98.310192 -296.2529)
		(end 98.310192 -296.281348)
		(width 0.1143)
		(layer "In6.Cu")
		(net "P5E_CPU1_P0_TX_DP<2>")
	)
	(segment
		(start 99.108514 -290.773612)
		(end 99.139756 -290.792154)
		(width 0.1143)
		(layer "In6.Cu")
		(net "P5E_CPU1_P0_TX_DP<2>")
	)
	(segment
		(start 55.838598 -361.62107)
		(end 55.204106 -362.255562)
		(width 0.14224)
		(layer "In6.Cu")
		(net "P5E_CPU1_P0_TX_DP<2>")
	)
	(segment
		(start 99.173538 -284.339284)
		(end 99.17811 -284.343856)
		(width 0.1143)
		(layer "In6.Cu")
		(net "P5E_CPU1_P0_TX_DP<2>")
	)
	(segment
		(start 99.066858 -293.990014)
		(end 99.108514 -294.013636)
		(width 0.1143)
		(layer "In6.Cu")
		(net "P5E_CPU1_P0_TX_DP<2>")
	)
	(segment
		(start 43.305984 -369.283996)
		(end 43.305984 -371.2083)
		(width 0.14224)
		(layer "In6.Cu")
		(net "P5E_CPU1_P0_TX_DP<2>")
	)
	(arc
		(start 98.825812 -287.053782)
		(mid 98.886345 -287.304787)
		(end 99.054666 -287.500568)
		(width 0.1143)
		(layer "In6.Cu")
		(net "P5E_CPU1_P0_TX_DP<2>")
	)
	(arc
		(start 99.058476 -288.209228)
		(mid 98.886311 -288.411318)
		(end 98.825558 -288.66973)
		(width 0.1143)
		(layer "In6.Cu")
		(net "P5E_CPU1_P0_TX_DP<2>")
	)
	(arc
		(start 98.823018 -285.474918)
		(mid 98.772457 -285.619348)
		(end 98.668332 -285.731458)
		(width 0.1143)
		(layer "In6.Cu")
		(net "P5E_CPU1_P0_TX_DP<2>")
	)
	(arc
		(start 99.137978 -287.551114)
		(mid 99.254025 -287.684585)
		(end 99.295966 -287.856422)
		(width 0.1143)
		(layer "In6.Cu")
		(net "P5E_CPU1_P0_TX_DP<2>")
	)
	(arc
		(start 55.204106 -362.255562)
		(mid 55.041919 -362.388615)
		(end 54.856888 -362.487464)
		(width 0.14224)
		(layer "In6.Cu")
		(net "P5E_CPU1_P0_TX_DP<2>")
	)
	(arc
		(start 98.825558 -288.66973)
		(mid 98.893175 -288.927664)
		(end 99.066858 -289.129978)
		(width 0.1143)
		(layer "In6.Cu")
		(net "P5E_CPU1_P0_TX_DP<2>")
	)
	(arc
		(start 100.273104 -358.781604)
		(mid 100.141658 -358.843963)
		(end 99.997768 -358.865424)
		(width 0.14224)
		(layer "In6.Cu")
		(net "P5E_CPU1_P0_TX_DP<2>")
	)
	(arc
		(start 99.066858 -293.06266)
		(mid 98.832238 -293.526389)
		(end 99.066858 -293.990014)
		(width 0.1143)
		(layer "In6.Cu")
		(net "P5E_CPU1_P0_TX_DP<2>")
	)
	(arc
		(start 99.066858 -294.682418)
		(mid 98.893242 -294.884881)
		(end 98.825812 -295.14292)
		(width 0.1143)
		(layer "In6.Cu")
		(net "P5E_CPU1_P0_TX_DP<2>")
	)
	(arc
		(start 98.310192 -299.123354)
		(mid 98.327809 -299.302684)
		(end 98.380042 -299.475144)
		(width 0.14224)
		(layer "In6.Cu")
		(net "P5E_CPU1_P0_TX_DP<2>")
	)
	(arc
		(start 99.275392 -282.87472)
		(mid 99.278013 -283.110129)
		(end 99.139756 -283.300678)
		(width 0.1143)
		(layer "In6.Cu")
		(net "P5E_CPU1_P0_TX_DP<2>")
	)
	(arc
		(start 99.066858 -289.822636)
		(mid 98.832238 -290.286365)
		(end 99.066858 -290.74999)
		(width 0.1143)
		(layer "In6.Cu")
		(net "P5E_CPU1_P0_TX_DP<2>")
	)
	(arc
		(start 99.14001 -289.172142)
		(mid 99.295837 -289.47618)
		(end 99.14001 -289.780218)
		(width 0.1143)
		(layer "In6.Cu")
		(net "P5E_CPU1_P0_TX_DP<2>")
	)
	(arc
		(start 99.139756 -294.032178)
		(mid 99.295689 -294.336216)
		(end 99.139756 -294.640254)
		(width 0.1143)
		(layer "In6.Cu")
		(net "P5E_CPU1_P0_TX_DP<2>")
	)
	(arc
		(start 98.825558 -295.150794)
		(mid 98.798656 -295.286984)
		(end 98.721672 -295.402508)
		(width 0.1143)
		(layer "In6.Cu")
		(net "P5E_CPU1_P0_TX_DP<2>")
	)
	(arc
		(start 44.252134 -366.99952)
		(mid 43.551852 -368.047661)
		(end 43.305984 -369.283996)
		(width 0.14224)
		(layer "In6.Cu")
		(net "P5E_CPU1_P0_TX_DP<2>")
	)
	(arc
		(start 108.484416 -318.48425)
		(mid 108.679559 -318.761474)
		(end 108.888022 -319.028826)
		(width 0.14224)
		(layer "In6.Cu")
		(net "P5E_CPU1_P0_TX_DP<2>")
	)
	(arc
		(start 116.97716 -330.863448)
		(mid 116.995086 -330.949398)
		(end 117.01145 -331.03566)
		(width 0.14224)
		(layer "In6.Cu")
		(net "P5E_CPU1_P0_TX_DP<2>")
	)
	(arc
		(start 116.93398 -330.744068)
		(mid 116.959598 -330.802302)
		(end 116.97716 -330.863448)
		(width 0.14224)
		(layer "In6.Cu")
		(net "P5E_CPU1_P0_TX_DP<2>")
	)
	(arc
		(start 99.17811 -284.343856)
		(mid 99.179 -284.344616)
		(end 99.179888 -284.34538)
		(width 0.1143)
		(layer "In6.Cu")
		(net "P5E_CPU1_P0_TX_DP<2>")
	)
	(arc
		(start 99.067874 -291.441886)
		(mid 98.829915 -291.906198)
		(end 99.067874 -292.37051)
		(width 0.1143)
		(layer "In6.Cu")
		(net "P5E_CPU1_P0_TX_DP<2>")
	)
	(arc
		(start 99.295966 -287.856422)
		(mid 99.254715 -288.02707)
		(end 99.140264 -288.160206)
		(width 0.1143)
		(layer "In6.Cu")
		(net "P5E_CPU1_P0_TX_DP<2>")
	)
	(arc
		(start 98.561652 -295.562528)
		(mid 98.409392 -295.790211)
		(end 98.355912 -296.058844)
		(width 0.1143)
		(layer "In6.Cu")
		(net "P5E_CPU1_P0_TX_DP<2>")
	)
	(arc
		(start 99.139756 -292.412166)
		(mid 99.295689 -292.716101)
		(end 99.14001 -293.020242)
		(width 0.1143)
		(layer "In6.Cu")
		(net "P5E_CPU1_P0_TX_DP<2>")
	)
	(arc
		(start 114.13871 -325.426578)
		(mid 114.176212 -325.477498)
		(end 114.208306 -325.531988)
		(width 0.14224)
		(layer "In6.Cu")
		(net "P5E_CPU1_P0_TX_DP<2>")
	)
	(arc
		(start 98.365564 -281.482038)
		(mid 98.446997 -281.684436)
		(end 98.59899 -281.84094)
		(width 0.1143)
		(layer "In6.Cu")
		(net "P5E_CPU1_P0_TX_DP<2>")
	)
	(arc
		(start 118.535196 -339.514434)
		(mid 118.598934 -341.323057)
		(end 118.151148 -343.07653)
		(width 0.14224)
		(layer "In6.Cu")
		(net "P5E_CPU1_P0_TX_DP<2>")
	)
	(arc
		(start 99.185984 -284.351476)
		(mid 99.295395 -284.552535)
		(end 99.263708 -284.779212)
		(width 0.1143)
		(layer "In6.Cu")
		(net "P5E_CPU1_P0_TX_DP<2>")
	)
	(arc
		(start 99.067112 -283.342588)
		(mid 98.832389 -283.80629)
		(end 99.066858 -284.270196)
		(width 0.1143)
		(layer "In6.Cu")
		(net "P5E_CPU1_P0_TX_DP<2>")
	)
	(arc
		(start 99.134168 -284.308804)
		(mid 99.154855 -284.322751)
		(end 99.173538 -284.339284)
		(width 0.1143)
		(layer "In6.Cu")
		(net "P5E_CPU1_P0_TX_DP<2>")
	)
	(arc
		(start 98.667824 -286.7406)
		(mid 98.784005 -286.874159)
		(end 98.825812 -287.046162)
		(width 0.1143)
		(layer "In6.Cu")
		(net "P5E_CPU1_P0_TX_DP<2>")
	)
	(arc
		(start 99.139756 -290.792154)
		(mid 99.295689 -291.096089)
		(end 99.14001 -291.40023)
		(width 0.1143)
		(layer "In6.Cu")
		(net "P5E_CPU1_P0_TX_DP<2>")
	)
	(arc
		(start 98.599498 -285.771336)
		(mid 98.420475 -285.973891)
		(end 98.355912 -286.23641)
		(width 0.1143)
		(layer "In6.Cu")
		(net "P5E_CPU1_P0_TX_DP<2>")
	)
	(arc
		(start 99.14255 -282.696158)
		(mid 99.222825 -282.77513)
		(end 99.275392 -282.87472)
		(width 0.1143)
		(layer "In6.Cu")
		(net "P5E_CPU1_P0_TX_DP<2>")
	)
	(arc
		(start 98.355912 -286.246824)
		(mid 98.415381 -286.494473)
		(end 98.580956 -286.688022)
		(width 0.1143)
		(layer "In6.Cu")
		(net "P5E_CPU1_P0_TX_DP<2>")
	)
	(arc
		(start 98.82759 -282.199842)
		(mid 98.899932 -282.47004)
		(end 99.097592 -282.667964)
		(width 0.1143)
		(layer "In6.Cu")
		(net "P5E_CPU1_P0_TX_DP<2>")
	)
	(arc
		(start 44.568618 -366.748314)
		(mid 44.463996 -366.804179)
		(end 44.372276 -366.879378)
		(width 0.14224)
		(layer "In6.Cu")
		(net "P5E_CPU1_P0_TX_DP<2>")
	)
	(arc
		(start 99.025456 -284.99943)
		(mid 98.903934 -285.135323)
		(end 98.844862 -285.307786)
		(width 0.1143)
		(layer "In6.Cu")
		(net "P5E_CPU1_P0_TX_DP<2>")
	)
	(arc
		(start 98.641154 -281.86507)
		(mid 98.777647 -282.002372)
		(end 98.82759 -282.189428)
		(width 0.1143)
		(layer "In6.Cu")
		(net "P5E_CPU1_P0_TX_DP<2>")
	)
	(arc
		(start 73.669398 -358.865424)
		(mid 73.38544 -358.83746)
		(end 73.112376 -358.75468)
		(width 0.14224)
		(layer "In6.Cu")
		(net "P5E_CPU1_P0_TX_DP<2>")
	)
	(arc
		(start 64.46647 -358.226868)
		(mid 64.032164 -358.269605)
		(end 63.614554 -358.396286)
		(width 0.14224)
		(layer "In6.Cu")
		(net "P5E_CPU1_P0_TX_DP<2>")
	)
	(arc
		(start 102.587044 -309.632096)
		(mid 102.61876 -309.699338)
		(end 102.656894 -309.76316)
		(width 0.14224)
		(layer "In6.Cu")
		(net "P5E_CPU1_P0_TX_DP<2>")
	)
	(arc
		(start 116.185696 -347.82125)
		(mid 115.955609 -348.205228)
		(end 115.624102 -348.506034)
		(width 0.14224)
		(layer "In6.Cu")
		(net "P5E_CPU1_P0_TX_DP<2>")
	)
	(arc
		(start 98.361754 -281.459178)
		(mid 98.363542 -281.470627)
		(end 98.365564 -281.482038)
		(width 0.1143)
		(layer "In6.Cu")
		(net "P5E_CPU1_P0_TX_DP<2>")
	)
	(arc
		(start 72.057768 -358.3178)
		(mid 71.833644 -358.249834)
		(end 71.600568 -358.226868)
		(width 0.14224)
		(layer "In6.Cu")
		(net "P5E_CPU1_P0_TX_DP<2>")
	)
	(arc
		(start 99.259136 -284.78861)
		(mid 99.226849 -284.839151)
		(end 99.184206 -284.88132)
		(width 0.1143)
		(layer "In6.Cu")
		(net "P5E_CPU1_P0_TX_DP<2>")
	)
	(segment
		(start 41.701212 -376.23877)
		(end 41.430702 -375.96826)
		(width 0.12954)
		(layer "F.Cu")
		(net "P5E_CPU1_P0_TX_DP<1>")
	)
	(segment
		(start 42.700702 -375.94286)
		(end 42.404792 -376.23877)
		(width 0.12954)
		(layer "F.Cu")
		(net "P5E_CPU1_P0_TX_DP<1>")
	)
	(segment
		(start 42.404792 -376.23877)
		(end 41.701212 -376.23877)
		(width 0.12954)
		(layer "F.Cu")
		(net "P5E_CPU1_P0_TX_DP<1>")
	)
	(segment
		(start 98.44786 -284.35046)
		(end 97.981008 -284.616398)
		(width 0.12954)
		(layer "F.Cu")
		(net "P5E_CPU1_P0_TX_DP<1>")
	)
	(segment
		(start 41.367964 -371.352318)
		(end 41.367964 -371.779038)
		(width 0.14224)
		(layer "In6.Cu")
		(net "P5E_CPU1_P0_TX_DP<1>")
	)
	(segment
		(start 42.569892 -375.41073)
		(end 42.569892 -376.028966)
		(width 0.14224)
		(layer "In6.Cu")
		(net "P5E_CPU1_P0_TX_DP<1>")
	)
	(segment
		(start 41.505124 -368.959638)
		(end 41.367964 -369.096798)
		(width 0.14224)
		(layer "In6.Cu")
		(net "P5E_CPU1_P0_TX_DP<1>")
	)
	(segment
		(start 44.018454 -365.979456)
		(end 43.867832 -366.069118)
		(width 0.14224)
		(layer "In6.Cu")
		(net "P5E_CPU1_P0_TX_DP<1>")
	)
	(segment
		(start 98.200972 -288.169096)
		(end 98.043238 -288.267902)
		(width 0.1143)
		(layer "In6.Cu")
		(net "P5E_CPU1_P0_TX_DP<1>")
	)
	(segment
		(start 114.581686 -348.07271)
		(end 99.99472 -357.835454)
		(width 0.14224)
		(layer "In6.Cu")
		(net "P5E_CPU1_P0_TX_DP<1>")
	)
	(segment
		(start 99.87788 -357.88219)
		(end 99.669854 -357.918258)
		(width 0.14224)
		(layer "In6.Cu")
		(net "P5E_CPU1_P0_TX_DP<1>")
	)
	(segment
		(start 41.505124 -371.916198)
		(end 41.505124 -372.012718)
		(width 0.14224)
		(layer "In6.Cu")
		(net "P5E_CPU1_P0_TX_DP<1>")
	)
	(segment
		(start 42.432732 -374.84685)
		(end 42.432732 -375.27357)
		(width 0.14224)
		(layer "In6.Cu")
		(net "P5E_CPU1_P0_TX_DP<1>")
	)
	(segment
		(start 42.34307 -376.255788)
		(end 41.71823 -376.255788)
		(width 0.14224)
		(layer "In6.Cu")
		(net "P5E_CPU1_P0_TX_DP<1>")
	)
	(segment
		(start 117.223032 -342.42502)
		(end 115.191794 -347.328744)
		(width 0.14224)
		(layer "In6.Cu")
		(net "P5E_CPU1_P0_TX_DP<1>")
	)
	(segment
		(start 97.650808 -285.777178)
		(end 97.651062 -285.777432)
		(width 0.1143)
		(layer "In6.Cu")
		(net "P5E_CPU1_P0_TX_DP<1>")
	)
	(segment
		(start 44.756578 -365.642398)
		(end 44.160948 -365.90605)
		(width 0.14224)
		(layer "In6.Cu")
		(net "P5E_CPU1_P0_TX_DP<1>")
	)
	(segment
		(start 41.505124 -369.660678)
		(end 41.505124 -370.087398)
		(width 0.14224)
		(layer "In6.Cu")
		(net "P5E_CPU1_P0_TX_DP<1>")
	)
	(segment
		(start 41.367964 -370.651278)
		(end 41.505124 -370.788438)
		(width 0.14224)
		(layer "In6.Cu")
		(net "P5E_CPU1_P0_TX_DP<1>")
	)
	(segment
		(start 98.130614 -293.991792)
		(end 98.199956 -294.032178)
		(width 0.1143)
		(layer "In6.Cu")
		(net "P5E_CPU1_P0_TX_DP<1>")
	)
	(segment
		(start 98.127566 -287.509458)
		(end 98.255582 -287.590484)
		(width 0.1143)
		(layer "In6.Cu")
		(net "P5E_CPU1_P0_TX_DP<1>")
	)
	(segment
		(start 41.367964 -370.224558)
		(end 41.367964 -370.651278)
		(width 0.14224)
		(layer "In6.Cu")
		(net "P5E_CPU1_P0_TX_DP<1>")
	)
	(segment
		(start 42.569892 -374.70969)
		(end 42.432732 -374.84685)
		(width 0.14224)
		(layer "In6.Cu")
		(net "P5E_CPU1_P0_TX_DP<1>")
	)
	(segment
		(start 97.886012 -288.659062)
		(end 97.886012 -288.666174)
		(width 0.1143)
		(layer "In6.Cu")
		(net "P5E_CPU1_P0_TX_DP<1>")
	)
	(segment
		(start 98.199956 -289.780218)
		(end 98.13036 -289.820604)
		(width 0.1143)
		(layer "In6.Cu")
		(net "P5E_CPU1_P0_TX_DP<1>")
	)
	(segment
		(start 42.532554 -376.118882)
		(end 42.432986 -376.21845)
		(width 0.14224)
		(layer "In6.Cu")
		(net "P5E_CPU1_P0_TX_DP<1>")
	)
	(segment
		(start 101.896164 -310.354726)
		(end 107.57662 -318.855852)
		(width 0.14224)
		(layer "In6.Cu")
		(net "P5E_CPU1_P0_TX_DP<1>")
	)
	(segment
		(start 42.26941 -373.856758)
		(end 42.532554 -374.119902)
		(width 0.14224)
		(layer "In6.Cu")
		(net "P5E_CPU1_P0_TX_DP<1>")
	)
	(segment
		(start 97.693988 -285.751524)
		(end 97.676208 -285.761938)
		(width 0.1143)
		(layer "In6.Cu")
		(net "P5E_CPU1_P0_TX_DP<1>")
	)
	(segment
		(start 97.797874 -295.445942)
		(end 97.518982 -295.725088)
		(width 0.1143)
		(layer "In6.Cu")
		(net "P5E_CPU1_P0_TX_DP<1>")
	)
	(segment
		(start 116.043456 -331.11948)
		(end 116.043456 -331.119734)
		(width 0.14224)
		(layer "In6.Cu")
		(net "P5E_CPU1_P0_TX_DP<1>")
	)
	(segment
		(start 98.199956 -291.40023)
		(end 98.13036 -291.440616)
		(width 0.1143)
		(layer "In6.Cu")
		(net "P5E_CPU1_P0_TX_DP<1>")
	)
	(segment
		(start 55.434992 -360.767122)
		(end 55.434738 -360.767376)
		(width 0.14224)
		(layer "In6.Cu")
		(net "P5E_CPU1_P0_TX_DP<1>")
	)
	(segment
		(start 41.367964 -371.779038)
		(end 41.505124 -371.916198)
		(width 0.14224)
		(layer "In6.Cu")
		(net "P5E_CPU1_P0_TX_DP<1>")
	)
	(segment
		(start 117.578378 -339.693758)
		(end 117.605048 -340.060534)
		(width 0.14224)
		(layer "In6.Cu")
		(net "P5E_CPU1_P0_TX_DP<1>")
	)
	(segment
		(start 97.719134 -285.735268)
		(end 97.700846 -285.747206)
		(width 0.1143)
		(layer "In6.Cu")
		(net "P5E_CPU1_P0_TX_DP<1>")
	)
	(segment
		(start 97.700846 -285.747206)
		(end 97.693988 -285.751524)
		(width 0.1143)
		(layer "In6.Cu")
		(net "P5E_CPU1_P0_TX_DP<1>")
	)
	(segment
		(start 98.130614 -289.131502)
		(end 98.199956 -289.172142)
		(width 0.1143)
		(layer "In6.Cu")
		(net "P5E_CPU1_P0_TX_DP<1>")
	)
	(segment
		(start 97.885758 -295.145714)
		(end 97.885758 -295.190164)
		(width 0.1143)
		(layer "In6.Cu")
		(net "P5E_CPU1_P0_TX_DP<1>")
	)
	(segment
		(start 41.367964 -369.523518)
		(end 41.505124 -369.660678)
		(width 0.14224)
		(layer "In6.Cu")
		(net "P5E_CPU1_P0_TX_DP<1>")
	)
	(segment
		(start 41.505124 -370.788438)
		(end 41.505124 -371.215158)
		(width 0.14224)
		(layer "In6.Cu")
		(net "P5E_CPU1_P0_TX_DP<1>")
	)
	(segment
		(start 98.199956 -293.020242)
		(end 98.13036 -293.060628)
		(width 0.1143)
		(layer "In6.Cu")
		(net "P5E_CPU1_P0_TX_DP<1>")
	)
	(segment
		(start 97.693988 -286.721042)
		(end 97.730056 -286.742124)
		(width 0.1143)
		(layer "In6.Cu")
		(net "P5E_CPU1_P0_TX_DP<1>")
	)
	(segment
		(start 97.676208 -285.761938)
		(end 97.662238 -285.769304)
		(width 0.1143)
		(layer "In6.Cu")
		(net "P5E_CPU1_P0_TX_DP<1>")
	)
	(segment
		(start 97.418398 -299.590714)
		(end 101.810312 -310.194198)
		(width 0.14224)
		(layer "In6.Cu")
		(net "P5E_CPU1_P0_TX_DP<1>")
	)
	(segment
		(start 97.888552 -285.4198)
		(end 97.888552 -285.442152)
		(width 0.1143)
		(layer "In6.Cu")
		(net "P5E_CPU1_P0_TX_DP<1>")
	)
	(segment
		(start 43.713146 -366.189514)
		(end 41.724326 -368.178334)
		(width 0.14224)
		(layer "In6.Cu")
		(net "P5E_CPU1_P0_TX_DP<1>")
	)
	(segment
		(start 97.415858 -295.973754)
		(end 97.415858 -296.22115)
		(width 0.1143)
		(layer "In6.Cu")
		(net "P5E_CPU1_P0_TX_DP<1>")
	)
	(segment
		(start 98.199956 -294.640254)
		(end 98.130868 -294.680386)
		(width 0.1143)
		(layer "In6.Cu")
		(net "P5E_CPU1_P0_TX_DP<1>")
	)
	(segment
		(start 98.199956 -284.920436)
		(end 98.16084 -284.943042)
		(width 0.1143)
		(layer "In6.Cu")
		(net "P5E_CPU1_P0_TX_DP<1>")
	)
	(segment
		(start 41.367964 -369.096798)
		(end 41.367964 -369.523518)
		(width 0.14224)
		(layer "In6.Cu")
		(net "P5E_CPU1_P0_TX_DP<1>")
	)
	(segment
		(start 116.043456 -331.119734)
		(end 117.561868 -339.564472)
		(width 0.14224)
		(layer "In6.Cu")
		(net "P5E_CPU1_P0_TX_DP<1>")
	)
	(segment
		(start 41.71823 -376.255788)
		(end 41.430702 -375.96826)
		(width 0.14224)
		(layer "In6.Cu")
		(net "P5E_CPU1_P0_TX_DP<1>")
	)
	(segment
		(start 117.561868 -339.564472)
		(end 117.561868 -339.564726)
		(width 0.14224)
		(layer "In6.Cu")
		(net "P5E_CPU1_P0_TX_DP<1>")
	)
	(segment
		(start 97.370138 -296.281348)
		(end 97.370138 -299.348144)
		(width 0.14224)
		(layer "In6.Cu")
		(net "P5E_CPU1_P0_TX_DP<1>")
	)
	(segment
		(start 98.355912 -287.783524)
		(end 98.355912 -287.888934)
		(width 0.1143)
		(layer "In6.Cu")
		(net "P5E_CPU1_P0_TX_DP<1>")
	)
	(segment
		(start 63.970154 -357.230934)
		(end 55.434992 -360.767376)
		(width 0.14224)
		(layer "In6.Cu")
		(net "P5E_CPU1_P0_TX_DP<1>")
	)
	(segment
		(start 42.432732 -375.27357)
		(end 42.569892 -375.41073)
		(width 0.14224)
		(layer "In6.Cu")
		(net "P5E_CPU1_P0_TX_DP<1>")
	)
	(segment
		(start 41.505124 -368.731292)
		(end 41.505124 -368.959638)
		(width 0.14224)
		(layer "In6.Cu")
		(net "P5E_CPU1_P0_TX_DP<1>")
	)
	(segment
		(start 97.981008 -284.616398)
		(end 98.194114 -284.616398)
		(width 0.1143)
		(layer "In6.Cu")
		(net "P5E_CPU1_P0_TX_DP<1>")
	)
	(segment
		(start 54.459632 -361.64266)
		(end 46.588426 -364.902496)
		(width 0.14224)
		(layer "In6.Cu")
		(net "P5E_CPU1_P0_TX_DP<1>")
	)
	(segment
		(start 73.021698 -357.70439)
		(end 72.032876 -357.294688)
		(width 0.14224)
		(layer "In6.Cu")
		(net "P5E_CPU1_P0_TX_DP<1>")
	)
	(segment
		(start 55.23865 -360.89844)
		(end 54.56428 -361.57281)
		(width 0.14224)
		(layer "In6.Cu")
		(net "P5E_CPU1_P0_TX_DP<1>")
	)
	(segment
		(start 55.434992 -360.767376)
		(end 55.434992 -360.767122)
		(width 0.14224)
		(layer "In6.Cu")
		(net "P5E_CPU1_P0_TX_DP<1>")
	)
	(segment
		(start 113.417096 -326.053958)
		(end 116.002816 -331.000608)
		(width 0.14224)
		(layer "In6.Cu")
		(net "P5E_CPU1_P0_TX_DP<1>")
	)
	(segment
		(start 42.569892 -374.209818)
		(end 42.569892 -374.70969)
		(width 0.14224)
		(layer "In6.Cu")
		(net "P5E_CPU1_P0_TX_DP<1>")
	)
	(segment
		(start 97.370138 -296.26687)
		(end 97.370138 -296.281348)
		(width 0.1143)
		(layer "In6.Cu")
		(net "P5E_CPU1_P0_TX_DP<1>")
	)
	(segment
		(start 97.415858 -296.22115)
		(end 97.370138 -296.26687)
		(width 0.1143)
		(layer "In6.Cu")
		(net "P5E_CPU1_P0_TX_DP<1>")
	)
	(segment
		(start 99.591876 -357.924862)
		(end 74.130408 -357.924862)
		(width 0.14224)
		(layer "In6.Cu")
		(net "P5E_CPU1_P0_TX_DP<1>")
	)
	(segment
		(start 98.130614 -292.37178)
		(end 98.199956 -292.412166)
		(width 0.1143)
		(layer "In6.Cu")
		(net "P5E_CPU1_P0_TX_DP<1>")
	)
	(segment
		(start 98.130614 -290.751768)
		(end 98.199956 -290.792154)
		(width 0.1143)
		(layer "In6.Cu")
		(net "P5E_CPU1_P0_TX_DP<1>")
	)
	(segment
		(start 41.505124 -370.087398)
		(end 41.367964 -370.224558)
		(width 0.14224)
		(layer "In6.Cu")
		(net "P5E_CPU1_P0_TX_DP<1>")
	)
	(segment
		(start 71.554848 -357.199692)
		(end 64.128142 -357.199692)
		(width 0.14224)
		(layer "In6.Cu")
		(net "P5E_CPU1_P0_TX_DP<1>")
	)
	(segment
		(start 108.041948 -319.48374)
		(end 113.348008 -325.949564)
		(width 0.14224)
		(layer "In6.Cu")
		(net "P5E_CPU1_P0_TX_DP<1>")
	)
	(segment
		(start 41.505124 -371.215158)
		(end 41.367964 -371.352318)
		(width 0.14224)
		(layer "In6.Cu")
		(net "P5E_CPU1_P0_TX_DP<1>")
	)
	(arc
		(start 98.13036 -289.820604)
		(mid 97.885539 -290.286291)
		(end 98.130614 -290.751768)
		(width 0.1143)
		(layer "In6.Cu")
		(net "P5E_CPU1_P0_TX_DP<1>")
	)
	(arc
		(start 99.669854 -357.918258)
		(mid 99.631005 -357.92321)
		(end 99.591876 -357.924862)
		(width 0.14224)
		(layer "In6.Cu")
		(net "P5E_CPU1_P0_TX_DP<1>")
	)
	(arc
		(start 97.415604 -286.23641)
		(mid 97.490149 -286.515865)
		(end 97.693988 -286.721042)
		(width 0.1143)
		(layer "In6.Cu")
		(net "P5E_CPU1_P0_TX_DP<1>")
	)
	(arc
		(start 97.863152 -295.33723)
		(mid 97.837208 -295.39561)
		(end 97.797874 -295.445942)
		(width 0.1143)
		(layer "In6.Cu")
		(net "P5E_CPU1_P0_TX_DP<1>")
	)
	(arc
		(start 41.60139 -368.344196)
		(mid 41.529457 -368.531828)
		(end 41.505124 -368.731292)
		(width 0.14224)
		(layer "In6.Cu")
		(net "P5E_CPU1_P0_TX_DP<1>")
	)
	(arc
		(start 72.032876 -357.294688)
		(mid 71.798545 -357.223615)
		(end 71.554848 -357.199692)
		(width 0.14224)
		(layer "In6.Cu")
		(net "P5E_CPU1_P0_TX_DP<1>")
	)
	(arc
		(start 98.199956 -290.792154)
		(mid 98.355783 -291.096192)
		(end 98.199956 -291.40023)
		(width 0.1143)
		(layer "In6.Cu")
		(net "P5E_CPU1_P0_TX_DP<1>")
	)
	(arc
		(start 98.194114 -284.616398)
		(mid 98.304557 -284.68051)
		(end 98.30308 -284.808168)
		(width 0.1143)
		(layer "In6.Cu")
		(net "P5E_CPU1_P0_TX_DP<1>")
	)
	(arc
		(start 42.532554 -374.119902)
		(mid 42.560173 -374.161142)
		(end 42.569892 -374.209818)
		(width 0.14224)
		(layer "In6.Cu")
		(net "P5E_CPU1_P0_TX_DP<1>")
	)
	(arc
		(start 97.518982 -295.725088)
		(mid 97.442721 -295.839176)
		(end 97.415858 -295.973754)
		(width 0.1143)
		(layer "In6.Cu")
		(net "P5E_CPU1_P0_TX_DP<1>")
	)
	(arc
		(start 117.561868 -339.564726)
		(mid 117.571819 -339.629025)
		(end 117.578378 -339.693758)
		(width 0.14224)
		(layer "In6.Cu")
		(net "P5E_CPU1_P0_TX_DP<1>")
	)
	(arc
		(start 99.99472 -357.835454)
		(mid 99.938759 -357.864972)
		(end 99.87788 -357.88219)
		(width 0.14224)
		(layer "In6.Cu")
		(net "P5E_CPU1_P0_TX_DP<1>")
	)
	(arc
		(start 46.588426 -364.902496)
		(mid 46.25866 -365.03601)
		(end 45.926756 -365.164116)
		(width 0.14224)
		(layer "In6.Cu")
		(net "P5E_CPU1_P0_TX_DP<1>")
	)
	(arc
		(start 113.348008 -325.949564)
		(mid 113.38521 -326.000002)
		(end 113.417096 -326.053958)
		(width 0.14224)
		(layer "In6.Cu")
		(net "P5E_CPU1_P0_TX_DP<1>")
	)
	(arc
		(start 98.30308 -284.808168)
		(mid 98.257268 -284.86958)
		(end 98.199956 -284.920436)
		(width 0.1143)
		(layer "In6.Cu")
		(net "P5E_CPU1_P0_TX_DP<1>")
	)
	(arc
		(start 44.160948 -365.90605)
		(mid 44.088607 -365.940629)
		(end 44.018454 -365.979456)
		(width 0.14224)
		(layer "In6.Cu")
		(net "P5E_CPU1_P0_TX_DP<1>")
	)
	(arc
		(start 43.867832 -366.069118)
		(mid 43.786744 -366.124504)
		(end 43.713146 -366.189514)
		(width 0.14224)
		(layer "In6.Cu")
		(net "P5E_CPU1_P0_TX_DP<1>")
	)
	(arc
		(start 115.191794 -347.328744)
		(mid 114.941821 -347.745893)
		(end 114.581686 -348.07271)
		(width 0.14224)
		(layer "In6.Cu")
		(net "P5E_CPU1_P0_TX_DP<1>")
	)
	(arc
		(start 97.370138 -299.348144)
		(mid 97.38233 -299.471802)
		(end 97.418398 -299.590714)
		(width 0.14224)
		(layer "In6.Cu")
		(net "P5E_CPU1_P0_TX_DP<1>")
	)
	(arc
		(start 98.043238 -288.267902)
		(mid 97.926832 -288.448285)
		(end 97.886012 -288.659062)
		(width 0.1143)
		(layer "In6.Cu")
		(net "P5E_CPU1_P0_TX_DP<1>")
	)
	(arc
		(start 98.024188 -285.055564)
		(mid 97.923449 -285.225415)
		(end 97.888552 -285.4198)
		(width 0.1143)
		(layer "In6.Cu")
		(net "P5E_CPU1_P0_TX_DP<1>")
	)
	(arc
		(start 117.605048 -340.060534)
		(mid 117.552109 -341.265081)
		(end 117.223032 -342.42502)
		(width 0.14224)
		(layer "In6.Cu")
		(net "P5E_CPU1_P0_TX_DP<1>")
	)
	(arc
		(start 55.434738 -360.767376)
		(mid 55.330247 -360.82326)
		(end 55.23865 -360.89844)
		(width 0.14224)
		(layer "In6.Cu")
		(net "P5E_CPU1_P0_TX_DP<1>")
	)
	(arc
		(start 97.662238 -285.769304)
		(mid 97.656498 -285.773205)
		(end 97.650808 -285.777178)
		(width 0.1143)
		(layer "In6.Cu")
		(net "P5E_CPU1_P0_TX_DP<1>")
	)
	(arc
		(start 101.810312 -310.194198)
		(mid 101.849301 -310.276567)
		(end 101.896164 -310.354726)
		(width 0.14224)
		(layer "In6.Cu")
		(net "P5E_CPU1_P0_TX_DP<1>")
	)
	(arc
		(start 98.355912 -287.888934)
		(mid 98.314539 -288.048977)
		(end 98.200972 -288.169096)
		(width 0.1143)
		(layer "In6.Cu")
		(net "P5E_CPU1_P0_TX_DP<1>")
	)
	(arc
		(start 98.199956 -294.032178)
		(mid 98.355783 -294.336216)
		(end 98.199956 -294.640254)
		(width 0.1143)
		(layer "In6.Cu")
		(net "P5E_CPU1_P0_TX_DP<1>")
	)
	(arc
		(start 45.926756 -365.164116)
		(mid 45.33828 -365.39497)
		(end 44.756578 -365.642398)
		(width 0.14224)
		(layer "In6.Cu")
		(net "P5E_CPU1_P0_TX_DP<1>")
	)
	(arc
		(start 41.505124 -372.012718)
		(mid 41.703799 -373.010785)
		(end 42.26941 -373.856758)
		(width 0.14224)
		(layer "In6.Cu")
		(net "P5E_CPU1_P0_TX_DP<1>")
	)
	(arc
		(start 97.886012 -287.046162)
		(mid 97.950021 -287.307413)
		(end 98.127566 -287.509458)
		(width 0.1143)
		(layer "In6.Cu")
		(net "P5E_CPU1_P0_TX_DP<1>")
	)
	(arc
		(start 98.16084 -284.943042)
		(mid 98.087878 -284.993671)
		(end 98.024188 -285.055564)
		(width 0.1143)
		(layer "In6.Cu")
		(net "P5E_CPU1_P0_TX_DP<1>")
	)
	(arc
		(start 116.002816 -331.000608)
		(mid 116.027648 -331.058502)
		(end 116.043456 -331.11948)
		(width 0.14224)
		(layer "In6.Cu")
		(net "P5E_CPU1_P0_TX_DP<1>")
	)
	(arc
		(start 98.255582 -287.590484)
		(mid 98.329304 -287.674755)
		(end 98.355912 -287.783524)
		(width 0.1143)
		(layer "In6.Cu")
		(net "P5E_CPU1_P0_TX_DP<1>")
	)
	(arc
		(start 98.130868 -294.680386)
		(mid 97.950872 -294.882797)
		(end 97.885758 -295.145714)
		(width 0.1143)
		(layer "In6.Cu")
		(net "P5E_CPU1_P0_TX_DP<1>")
	)
	(arc
		(start 98.13036 -291.440616)
		(mid 97.885539 -291.906303)
		(end 98.130614 -292.37178)
		(width 0.1143)
		(layer "In6.Cu")
		(net "P5E_CPU1_P0_TX_DP<1>")
	)
	(arc
		(start 97.886012 -288.666174)
		(mid 97.950889 -288.929022)
		(end 98.130614 -289.131502)
		(width 0.1143)
		(layer "In6.Cu")
		(net "P5E_CPU1_P0_TX_DP<1>")
	)
	(arc
		(start 74.130408 -357.924862)
		(mid 73.565191 -357.869242)
		(end 73.021698 -357.70439)
		(width 0.14224)
		(layer "In6.Cu")
		(net "P5E_CPU1_P0_TX_DP<1>")
	)
	(arc
		(start 97.651062 -285.777432)
		(mid 97.477984 -285.978522)
		(end 97.415604 -286.23641)
		(width 0.1143)
		(layer "In6.Cu")
		(net "P5E_CPU1_P0_TX_DP<1>")
	)
	(arc
		(start 42.432986 -376.21845)
		(mid 42.391746 -376.246069)
		(end 42.34307 -376.255788)
		(width 0.14224)
		(layer "In6.Cu")
		(net "P5E_CPU1_P0_TX_DP<1>")
	)
	(arc
		(start 98.199956 -292.412166)
		(mid 98.355783 -292.716204)
		(end 98.199956 -293.020242)
		(width 0.1143)
		(layer "In6.Cu")
		(net "P5E_CPU1_P0_TX_DP<1>")
	)
	(arc
		(start 107.57662 -318.855852)
		(mid 107.801582 -319.175504)
		(end 108.041948 -319.48374)
		(width 0.14224)
		(layer "In6.Cu")
		(net "P5E_CPU1_P0_TX_DP<1>")
	)
	(arc
		(start 97.730056 -286.742124)
		(mid 97.844732 -286.875315)
		(end 97.886012 -287.046162)
		(width 0.1143)
		(layer "In6.Cu")
		(net "P5E_CPU1_P0_TX_DP<1>")
	)
	(arc
		(start 54.56428 -361.57281)
		(mid 54.515396 -361.61289)
		(end 54.459632 -361.64266)
		(width 0.14224)
		(layer "In6.Cu")
		(net "P5E_CPU1_P0_TX_DP<1>")
	)
	(arc
		(start 97.888552 -285.442152)
		(mid 97.838906 -285.608973)
		(end 97.719134 -285.735268)
		(width 0.1143)
		(layer "In6.Cu")
		(net "P5E_CPU1_P0_TX_DP<1>")
	)
	(arc
		(start 41.724326 -368.178334)
		(mid 41.656717 -368.256713)
		(end 41.60139 -368.344196)
		(width 0.14224)
		(layer "In6.Cu")
		(net "P5E_CPU1_P0_TX_DP<1>")
	)
	(arc
		(start 64.128142 -357.199692)
		(mid 64.047602 -357.207499)
		(end 63.970154 -357.230934)
		(width 0.14224)
		(layer "In6.Cu")
		(net "P5E_CPU1_P0_TX_DP<1>")
	)
	(arc
		(start 98.13036 -293.060628)
		(mid 97.885539 -293.526315)
		(end 98.130614 -293.991792)
		(width 0.1143)
		(layer "In6.Cu")
		(net "P5E_CPU1_P0_TX_DP<1>")
	)
	(arc
		(start 42.569892 -376.028966)
		(mid 42.56019 -376.07765)
		(end 42.532554 -376.118882)
		(width 0.14224)
		(layer "In6.Cu")
		(net "P5E_CPU1_P0_TX_DP<1>")
	)
	(arc
		(start 98.199956 -289.172142)
		(mid 98.355783 -289.47618)
		(end 98.199956 -289.780218)
		(width 0.1143)
		(layer "In6.Cu")
		(net "P5E_CPU1_P0_TX_DP<1>")
	)
	(arc
		(start 97.885758 -295.190164)
		(mid 97.879807 -295.264521)
		(end 97.863152 -295.33723)
		(width 0.1143)
		(layer "In6.Cu")
		(net "P5E_CPU1_P0_TX_DP<1>")
	)
	(segment
		(start 71.007224 -379.767338)
		(end 70.303644 -379.767338)
		(width 0.12954)
		(layer "F.Cu")
		(net "P5E_CPU1_P0_TX_DP<15>")
	)
	(segment
		(start 109.257846 -281.920442)
		(end 108.790994 -282.18638)
		(width 0.12954)
		(layer "F.Cu")
		(net "P5E_CPU1_P0_TX_DP<15>")
	)
	(segment
		(start 70.303644 -379.767338)
		(end 70.007734 -379.471428)
		(width 0.12954)
		(layer "F.Cu")
		(net "P5E_CPU1_P0_TX_DP<15>")
	)
	(segment
		(start 71.277734 -379.496828)
		(end 71.007224 -379.767338)
		(width 0.12954)
		(layer "F.Cu")
		(net "P5E_CPU1_P0_TX_DP<15>")
	)
	(segment
		(start 127.471678 -354.471732)
		(end 131.308094 -345.210384)
		(width 0.14224)
		(layer "In6.Cu")
		(net "P5E_CPU1_P0_TX_DP<15>")
	)
	(segment
		(start 109.416596 -282.655518)
		(end 109.408976 -282.650946)
		(width 0.1143)
		(layer "In6.Cu")
		(net "P5E_CPU1_P0_TX_DP<15>")
	)
	(segment
		(start 111.246158 -298.209208)
		(end 111.214408 -297.888406)
		(width 0.14224)
		(layer "In6.Cu")
		(net "P5E_CPU1_P0_TX_DP<15>")
	)
	(segment
		(start 71.579994 -379.799088)
		(end 72.062848 -379.799088)
		(width 0.14224)
		(layer "In6.Cu")
		(net "P5E_CPU1_P0_TX_DP<15>")
	)
	(segment
		(start 108.333286 -371.059202)
		(end 108.509562 -370.977922)
		(width 0.14224)
		(layer "In6.Cu")
		(net "P5E_CPU1_P0_TX_DP<15>")
	)
	(segment
		(start 107.339638 -373.76354)
		(end 107.515914 -373.68226)
		(width 0.14224)
		(layer "In6.Cu")
		(net "P5E_CPU1_P0_TX_DP<15>")
	)
	(segment
		(start 75.390502 -379.145038)
		(end 75.56627 -379.484382)
		(width 0.14224)
		(layer "In6.Cu")
		(net "P5E_CPU1_P0_TX_DP<15>")
	)
	(segment
		(start 126.858776 -355.539802)
		(end 127.471678 -354.471732)
		(width 0.14224)
		(layer "In6.Cu")
		(net "P5E_CPU1_P0_TX_DP<15>")
	)
	(segment
		(start 101.946964 -379.871478)
		(end 102.614222 -380.538736)
		(width 0.14224)
		(layer "In6.Cu")
		(net "P5E_CPU1_P0_TX_DP<15>")
	)
	(segment
		(start 75.341988 -378.958348)
		(end 75.390502 -379.145038)
		(width 0.14224)
		(layer "In6.Cu")
		(net "P5E_CPU1_P0_TX_DP<15>")
	)
	(segment
		(start 106.2101 -377.237498)
		(end 107.302808 -374.261888)
		(width 0.14224)
		(layer "In6.Cu")
		(net "P5E_CPU1_P0_TX_DP<15>")
	)
	(segment
		(start 72.51954 -379.372114)
		(end 72.51954 -378.891546)
		(width 0.14224)
		(layer "In6.Cu")
		(net "P5E_CPU1_P0_TX_DP<15>")
	)
	(segment
		(start 109.479842 -282.692094)
		(end 109.448854 -282.674314)
		(width 0.1143)
		(layer "In6.Cu")
		(net "P5E_CPU1_P0_TX_DP<15>")
	)
	(segment
		(start 107.96524 -372.458996)
		(end 107.883706 -372.282974)
		(width 0.14224)
		(layer "In6.Cu")
		(net "P5E_CPU1_P0_TX_DP<15>")
	)
	(segment
		(start 76.207112 -379.810518)
		(end 76.722732 -379.810518)
		(width 0.14224)
		(layer "In6.Cu")
		(net "P5E_CPU1_P0_TX_DP<15>")
	)
	(segment
		(start 110.926372 -284.878526)
		(end 110.926372 -284.814518)
		(width 0.1143)
		(layer "In6.Cu")
		(net "P5E_CPU1_P0_TX_DP<15>")
	)
	(segment
		(start 101.491796 -379.640846)
		(end 101.744526 -379.739144)
		(width 0.14224)
		(layer "In6.Cu")
		(net "P5E_CPU1_P0_TX_DP<15>")
	)
	(segment
		(start 111.214408 -297.888406)
		(end 111.214408 -285.166562)
		(width 0.14224)
		(layer "In6.Cu")
		(net "P5E_CPU1_P0_TX_DP<15>")
	)
	(segment
		(start 110.926372 -284.814518)
		(end 110.4646 -284.352746)
		(width 0.1143)
		(layer "In6.Cu")
		(net "P5E_CPU1_P0_TX_DP<15>")
	)
	(segment
		(start 75.56627 -379.484382)
		(end 75.669394 -379.58776)
		(width 0.14224)
		(layer "In6.Cu")
		(net "P5E_CPU1_P0_TX_DP<15>")
	)
	(segment
		(start 73.385172 -377.975114)
		(end 74.280776 -377.975114)
		(width 0.14224)
		(layer "In6.Cu")
		(net "P5E_CPU1_P0_TX_DP<15>")
	)
	(segment
		(start 111.816388 -366.945672)
		(end 126.25832 -356.215442)
		(width 0.14224)
		(layer "In6.Cu")
		(net "P5E_CPU1_P0_TX_DP<15>")
	)
	(segment
		(start 131.431538 -341.549482)
		(end 128.736598 -326.549766)
		(width 0.14224)
		(layer "In6.Cu")
		(net "P5E_CPU1_P0_TX_DP<15>")
	)
	(segment
		(start 107.515914 -373.68226)
		(end 107.634024 -373.360442)
		(width 0.14224)
		(layer "In6.Cu")
		(net "P5E_CPU1_P0_TX_DP<15>")
	)
	(segment
		(start 107.883706 -372.282974)
		(end 108.00207 -371.960648)
		(width 0.14224)
		(layer "In6.Cu")
		(net "P5E_CPU1_P0_TX_DP<15>")
	)
	(segment
		(start 109.949742 -283.5021)
		(end 109.88167 -283.46273)
		(width 0.1143)
		(layer "In6.Cu")
		(net "P5E_CPU1_P0_TX_DP<15>")
	)
	(segment
		(start 111.214408 -285.166562)
		(end 110.946438 -284.898592)
		(width 0.14224)
		(layer "In6.Cu")
		(net "P5E_CPU1_P0_TX_DP<15>")
	)
	(segment
		(start 109.448854 -282.674314)
		(end 109.416596 -282.655518)
		(width 0.1143)
		(layer "In6.Cu")
		(net "P5E_CPU1_P0_TX_DP<15>")
	)
	(segment
		(start 107.221528 -374.085866)
		(end 107.339638 -373.76354)
		(width 0.14224)
		(layer "In6.Cu")
		(net "P5E_CPU1_P0_TX_DP<15>")
	)
	(segment
		(start 107.84713 -372.780814)
		(end 107.96524 -372.458996)
		(width 0.14224)
		(layer "In6.Cu")
		(net "P5E_CPU1_P0_TX_DP<15>")
	)
	(segment
		(start 109.17174 -282.269184)
		(end 109.088936 -282.18638)
		(width 0.1143)
		(layer "In6.Cu")
		(net "P5E_CPU1_P0_TX_DP<15>")
	)
	(segment
		(start 78.609698 -379.598682)
		(end 101.265736 -379.598682)
		(width 0.14224)
		(layer "In6.Cu")
		(net "P5E_CPU1_P0_TX_DP<15>")
	)
	(segment
		(start 108.627418 -370.656866)
		(end 108.627672 -370.656104)
		(width 0.14224)
		(layer "In6.Cu")
		(net "P5E_CPU1_P0_TX_DP<15>")
	)
	(segment
		(start 104.792272 -381.14605)
		(end 105.354882 -380.636018)
		(width 0.14224)
		(layer "In6.Cu")
		(net "P5E_CPU1_P0_TX_DP<15>")
	)
	(segment
		(start 109.40161 -369.112038)
		(end 109.669834 -368.843814)
		(width 0.14224)
		(layer "In6.Cu")
		(net "P5E_CPU1_P0_TX_DP<15>")
	)
	(segment
		(start 108.627672 -370.656104)
		(end 108.546138 -370.480082)
		(width 0.14224)
		(layer "In6.Cu")
		(net "P5E_CPU1_P0_TX_DP<15>")
	)
	(segment
		(start 72.79132 -378.235464)
		(end 72.815958 -378.210826)
		(width 0.14224)
		(layer "In6.Cu")
		(net "P5E_CPU1_P0_TX_DP<15>")
	)
	(segment
		(start 71.277734 -379.496828)
		(end 71.579994 -379.799088)
		(width 0.14224)
		(layer "In6.Cu")
		(net "P5E_CPU1_P0_TX_DP<15>")
	)
	(segment
		(start 105.567734 -380.20625)
		(end 106.2101 -377.237498)
		(width 0.14224)
		(layer "In6.Cu")
		(net "P5E_CPU1_P0_TX_DP<15>")
	)
	(segment
		(start 124.223018 -318.104774)
		(end 117.358414 -309.738522)
		(width 0.14224)
		(layer "In6.Cu")
		(net "P5E_CPU1_P0_TX_DP<15>")
	)
	(segment
		(start 108.00207 -371.960648)
		(end 108.178346 -371.879368)
		(width 0.14224)
		(layer "In6.Cu")
		(net "P5E_CPU1_P0_TX_DP<15>")
	)
	(segment
		(start 109.669834 -368.843814)
		(end 111.816388 -366.945672)
		(width 0.14224)
		(layer "In6.Cu")
		(net "P5E_CPU1_P0_TX_DP<15>")
	)
	(segment
		(start 110.388146 -284.293818)
		(end 110.34903 -284.270958)
		(width 0.1143)
		(layer "In6.Cu")
		(net "P5E_CPU1_P0_TX_DP<15>")
	)
	(segment
		(start 103.489506 -381.61214)
		(end 103.8733 -381.61214)
		(width 0.14224)
		(layer "In6.Cu")
		(net "P5E_CPU1_P0_TX_DP<15>")
	)
	(segment
		(start 108.178346 -371.879368)
		(end 108.296456 -371.55755)
		(width 0.14224)
		(layer "In6.Cu")
		(net "P5E_CPU1_P0_TX_DP<15>")
	)
	(segment
		(start 107.552744 -373.18442)
		(end 107.670854 -372.862094)
		(width 0.14224)
		(layer "In6.Cu")
		(net "P5E_CPU1_P0_TX_DP<15>")
	)
	(segment
		(start 109.088936 -282.18638)
		(end 108.790994 -282.18638)
		(width 0.1143)
		(layer "In6.Cu")
		(net "P5E_CPU1_P0_TX_DP<15>")
	)
	(segment
		(start 131.308094 -345.210384)
		(end 131.308094 -345.209876)
		(width 0.14224)
		(layer "In6.Cu")
		(net "P5E_CPU1_P0_TX_DP<15>")
	)
	(segment
		(start 107.302808 -374.261888)
		(end 107.221528 -374.085866)
		(width 0.14224)
		(layer "In6.Cu")
		(net "P5E_CPU1_P0_TX_DP<15>")
	)
	(segment
		(start 108.296456 -371.55755)
		(end 108.214922 -371.381528)
		(width 0.14224)
		(layer "In6.Cu")
		(net "P5E_CPU1_P0_TX_DP<15>")
	)
	(segment
		(start 117.358414 -309.738522)
		(end 113.504472 -303.97069)
		(width 0.14224)
		(layer "In6.Cu")
		(net "P5E_CPU1_P0_TX_DP<15>")
	)
	(segment
		(start 107.670854 -372.862094)
		(end 107.84713 -372.780814)
		(width 0.14224)
		(layer "In6.Cu")
		(net "P5E_CPU1_P0_TX_DP<15>")
	)
	(segment
		(start 107.634024 -373.360442)
		(end 107.552744 -373.18442)
		(width 0.14224)
		(layer "In6.Cu")
		(net "P5E_CPU1_P0_TX_DP<15>")
	)
	(segment
		(start 110.946438 -284.898592)
		(end 110.926372 -284.878526)
		(width 0.1143)
		(layer "In6.Cu")
		(net "P5E_CPU1_P0_TX_DP<15>")
	)
	(segment
		(start 74.594466 -378.104908)
		(end 75.199494 -378.709936)
		(width 0.14224)
		(layer "In6.Cu")
		(net "P5E_CPU1_P0_TX_DP<15>")
	)
	(segment
		(start 102.744016 -380.852426)
		(end 102.744016 -380.990856)
		(width 0.14224)
		(layer "In6.Cu")
		(net "P5E_CPU1_P0_TX_DP<15>")
	)
	(segment
		(start 108.546138 -370.480082)
		(end 108.664502 -370.157756)
		(width 0.14224)
		(layer "In6.Cu")
		(net "P5E_CPU1_P0_TX_DP<15>")
	)
	(segment
		(start 128.736598 -326.549766)
		(end 124.223018 -318.104774)
		(width 0.14224)
		(layer "In6.Cu")
		(net "P5E_CPU1_P0_TX_DP<15>")
	)
	(segment
		(start 104.624378 -381.278384)
		(end 104.694482 -381.226314)
		(width 0.14224)
		(layer "In6.Cu")
		(net "P5E_CPU1_P0_TX_DP<15>")
	)
	(segment
		(start 108.841286 -370.074952)
		(end 108.9152 -369.873022)
		(width 0.14224)
		(layer "In6.Cu")
		(net "P5E_CPU1_P0_TX_DP<15>")
	)
	(segment
		(start 113.504472 -303.97069)
		(end 111.441992 -298.991528)
		(width 0.14224)
		(layer "In6.Cu")
		(net "P5E_CPU1_P0_TX_DP<15>")
	)
	(segment
		(start 108.214922 -371.381528)
		(end 108.333286 -371.059202)
		(width 0.14224)
		(layer "In6.Cu")
		(net "P5E_CPU1_P0_TX_DP<15>")
	)
	(segment
		(start 102.896416 -381.358648)
		(end 102.909624 -381.371856)
		(width 0.14224)
		(layer "In6.Cu")
		(net "P5E_CPU1_P0_TX_DP<15>")
	)
	(segment
		(start 104.390952 -381.416306)
		(end 104.548178 -381.327914)
		(width 0.14224)
		(layer "In6.Cu")
		(net "P5E_CPU1_P0_TX_DP<15>")
	)
	(segment
		(start 131.477004 -344.343736)
		(end 131.477004 -342.05926)
		(width 0.14224)
		(layer "In6.Cu")
		(net "P5E_CPU1_P0_TX_DP<15>")
	)
	(segment
		(start 108.840778 -370.076476)
		(end 108.841286 -370.074952)
		(width 0.14224)
		(layer "In6.Cu")
		(net "P5E_CPU1_P0_TX_DP<15>")
	)
	(segment
		(start 103.99649 -381.587756)
		(end 104.27716 -381.471678)
		(width 0.14224)
		(layer "In6.Cu")
		(net "P5E_CPU1_P0_TX_DP<15>")
	)
	(segment
		(start 108.509562 -370.977922)
		(end 108.627418 -370.656866)
		(width 0.14224)
		(layer "In6.Cu")
		(net "P5E_CPU1_P0_TX_DP<15>")
	)
	(segment
		(start 108.664502 -370.157756)
		(end 108.840778 -370.076476)
		(width 0.14224)
		(layer "In6.Cu")
		(net "P5E_CPU1_P0_TX_DP<15>")
	)
	(arc
		(start 104.27716 -381.471678)
		(mid 104.334891 -381.445708)
		(end 104.390952 -381.416306)
		(width 0.14224)
		(layer "In6.Cu")
		(net "P5E_CPU1_P0_TX_DP<15>")
	)
	(arc
		(start 75.199494 -378.709936)
		(mid 75.287343 -378.824622)
		(end 75.341988 -378.958348)
		(width 0.14224)
		(layer "In6.Cu")
		(net "P5E_CPU1_P0_TX_DP<15>")
	)
	(arc
		(start 105.354882 -380.636018)
		(mid 105.398793 -380.59017)
		(end 105.435654 -380.538482)
		(width 0.14224)
		(layer "In6.Cu")
		(net "P5E_CPU1_P0_TX_DP<15>")
	)
	(arc
		(start 109.639862 -283.0322)
		(mid 109.637209 -283.006856)
		(end 109.636052 -282.9814)
		(width 0.1143)
		(layer "In6.Cu")
		(net "P5E_CPU1_P0_TX_DP<15>")
	)
	(arc
		(start 74.280776 -377.975114)
		(mid 74.450529 -378.008804)
		(end 74.594466 -378.104908)
		(width 0.14224)
		(layer "In6.Cu")
		(net "P5E_CPU1_P0_TX_DP<15>")
	)
	(arc
		(start 126.25832 -356.215442)
		(mid 126.593342 -355.908546)
		(end 126.858776 -355.539802)
		(width 0.14224)
		(layer "In6.Cu")
		(net "P5E_CPU1_P0_TX_DP<15>")
	)
	(arc
		(start 72.43191 -379.636528)
		(mid 72.469338 -379.568733)
		(end 72.498712 -379.497082)
		(width 0.14224)
		(layer "In6.Cu")
		(net "P5E_CPU1_P0_TX_DP<15>")
	)
	(arc
		(start 104.694482 -381.226314)
		(mid 104.744349 -381.187366)
		(end 104.792272 -381.14605)
		(width 0.14224)
		(layer "In6.Cu")
		(net "P5E_CPU1_P0_TX_DP<15>")
	)
	(arc
		(start 110.105698 -283.806392)
		(mid 110.064443 -283.635421)
		(end 109.949742 -283.5021)
		(width 0.1143)
		(layer "In6.Cu")
		(net "P5E_CPU1_P0_TX_DP<15>")
	)
	(arc
		(start 131.308094 -345.209876)
		(mid 131.317635 -345.186565)
		(end 131.32689 -345.16314)
		(width 0.14224)
		(layer "In6.Cu")
		(net "P5E_CPU1_P0_TX_DP<15>")
	)
	(arc
		(start 108.9152 -369.873022)
		(mid 109.117024 -369.466082)
		(end 109.40161 -369.112038)
		(width 0.14224)
		(layer "In6.Cu")
		(net "P5E_CPU1_P0_TX_DP<15>")
	)
	(arc
		(start 72.498712 -379.497082)
		(mid 72.514329 -379.435466)
		(end 72.51954 -379.372114)
		(width 0.14224)
		(layer "In6.Cu")
		(net "P5E_CPU1_P0_TX_DP<15>")
	)
	(arc
		(start 77.666342 -379.7046)
		(mid 78.135057 -379.625255)
		(end 78.609698 -379.598682)
		(width 0.14224)
		(layer "In6.Cu")
		(net "P5E_CPU1_P0_TX_DP<15>")
	)
	(arc
		(start 102.909624 -381.371856)
		(mid 103.175662 -381.54968)
		(end 103.489506 -381.61214)
		(width 0.14224)
		(layer "In6.Cu")
		(net "P5E_CPU1_P0_TX_DP<15>")
	)
	(arc
		(start 104.548178 -381.327914)
		(mid 104.58706 -381.304352)
		(end 104.624378 -381.278384)
		(width 0.14224)
		(layer "In6.Cu")
		(net "P5E_CPU1_P0_TX_DP<15>")
	)
	(arc
		(start 131.477004 -342.05926)
		(mid 131.465651 -341.803356)
		(end 131.431538 -341.549482)
		(width 0.14224)
		(layer "In6.Cu")
		(net "P5E_CPU1_P0_TX_DP<15>")
	)
	(arc
		(start 72.815958 -378.210826)
		(mid 73.07713 -378.03638)
		(end 73.385172 -377.975114)
		(width 0.14224)
		(layer "In6.Cu")
		(net "P5E_CPU1_P0_TX_DP<15>")
	)
	(arc
		(start 72.51954 -378.891546)
		(mid 72.590169 -378.536469)
		(end 72.79132 -378.235464)
		(width 0.14224)
		(layer "In6.Cu")
		(net "P5E_CPU1_P0_TX_DP<15>")
	)
	(arc
		(start 110.4646 -284.352746)
		(mid 110.428285 -284.320802)
		(end 110.388146 -284.293818)
		(width 0.1143)
		(layer "In6.Cu")
		(net "P5E_CPU1_P0_TX_DP<15>")
	)
	(arc
		(start 110.34903 -284.270958)
		(mid 110.170217 -284.068608)
		(end 110.105698 -283.806392)
		(width 0.1143)
		(layer "In6.Cu")
		(net "P5E_CPU1_P0_TX_DP<15>")
	)
	(arc
		(start 131.32689 -345.16314)
		(mid 131.345593 -345.112705)
		(end 131.362958 -345.061794)
		(width 0.14224)
		(layer "In6.Cu")
		(net "P5E_CPU1_P0_TX_DP<15>")
	)
	(arc
		(start 75.669394 -379.58776)
		(mid 75.916101 -379.752604)
		(end 76.207112 -379.810518)
		(width 0.14224)
		(layer "In6.Cu")
		(net "P5E_CPU1_P0_TX_DP<15>")
	)
	(arc
		(start 111.441992 -298.991528)
		(mid 111.315257 -298.607583)
		(end 111.246158 -298.209208)
		(width 0.14224)
		(layer "In6.Cu")
		(net "P5E_CPU1_P0_TX_DP<15>")
	)
	(arc
		(start 101.265736 -379.598682)
		(mid 101.38073 -379.609238)
		(end 101.491796 -379.640846)
		(width 0.14224)
		(layer "In6.Cu")
		(net "P5E_CPU1_P0_TX_DP<15>")
	)
	(arc
		(start 109.408976 -282.650946)
		(mid 109.256989 -282.494438)
		(end 109.17555 -282.292044)
		(width 0.1143)
		(layer "In6.Cu")
		(net "P5E_CPU1_P0_TX_DP<15>")
	)
	(arc
		(start 72.340724 -379.724412)
		(mid 72.391651 -379.686004)
		(end 72.43191 -379.636528)
		(width 0.14224)
		(layer "In6.Cu")
		(net "P5E_CPU1_P0_TX_DP<15>")
	)
	(arc
		(start 109.17555 -282.292044)
		(mid 109.173527 -282.280634)
		(end 109.17174 -282.269184)
		(width 0.1143)
		(layer "In6.Cu")
		(net "P5E_CPU1_P0_TX_DP<15>")
	)
	(arc
		(start 76.722732 -379.810518)
		(mid 77.197502 -379.783973)
		(end 77.666342 -379.7046)
		(width 0.14224)
		(layer "In6.Cu")
		(net "P5E_CPU1_P0_TX_DP<15>")
	)
	(arc
		(start 72.062848 -379.799088)
		(mid 72.206706 -379.78006)
		(end 72.340724 -379.724412)
		(width 0.14224)
		(layer "In6.Cu")
		(net "P5E_CPU1_P0_TX_DP<15>")
	)
	(arc
		(start 131.362958 -345.061794)
		(mid 131.448335 -344.707267)
		(end 131.477004 -344.343736)
		(width 0.14224)
		(layer "In6.Cu")
		(net "P5E_CPU1_P0_TX_DP<15>")
	)
	(arc
		(start 103.8733 -381.61214)
		(mid 103.936088 -381.60598)
		(end 103.99649 -381.587756)
		(width 0.14224)
		(layer "In6.Cu")
		(net "P5E_CPU1_P0_TX_DP<15>")
	)
	(arc
		(start 105.435654 -380.538482)
		(mid 105.515595 -380.377894)
		(end 105.567734 -380.20625)
		(width 0.14224)
		(layer "In6.Cu")
		(net "P5E_CPU1_P0_TX_DP<15>")
	)
	(arc
		(start 102.614222 -380.538736)
		(mid 102.710412 -380.682645)
		(end 102.744016 -380.852426)
		(width 0.14224)
		(layer "In6.Cu")
		(net "P5E_CPU1_P0_TX_DP<15>")
	)
	(arc
		(start 109.88167 -283.46273)
		(mid 109.720602 -283.270032)
		(end 109.639862 -283.0322)
		(width 0.1143)
		(layer "In6.Cu")
		(net "P5E_CPU1_P0_TX_DP<15>")
	)
	(arc
		(start 101.744526 -379.739144)
		(mid 101.852627 -379.794783)
		(end 101.946964 -379.871478)
		(width 0.14224)
		(layer "In6.Cu")
		(net "P5E_CPU1_P0_TX_DP<15>")
	)
	(arc
		(start 109.636052 -282.9814)
		(mid 109.591358 -282.818696)
		(end 109.479842 -282.692094)
		(width 0.1143)
		(layer "In6.Cu")
		(net "P5E_CPU1_P0_TX_DP<15>")
	)
	(arc
		(start 102.744016 -380.990856)
		(mid 102.783628 -381.189911)
		(end 102.896416 -381.358648)
		(width 0.14224)
		(layer "In6.Cu")
		(net "P5E_CPU1_P0_TX_DP<15>")
	)
	(segment
		(start 71.007224 -376.363738)
		(end 70.303644 -376.363738)
		(width 0.12954)
		(layer "F.Cu")
		(net "P5E_CPU1_P0_TX_DP<14>")
	)
	(segment
		(start 70.303644 -376.363738)
		(end 70.007734 -376.067828)
		(width 0.12954)
		(layer "F.Cu")
		(net "P5E_CPU1_P0_TX_DP<14>")
	)
	(segment
		(start 109.257846 -283.540454)
		(end 108.790994 -283.806392)
		(width 0.12954)
		(layer "F.Cu")
		(net "P5E_CPU1_P0_TX_DP<14>")
	)
	(segment
		(start 71.277734 -376.093228)
		(end 71.007224 -376.363738)
		(width 0.12954)
		(layer "F.Cu")
		(net "P5E_CPU1_P0_TX_DP<14>")
	)
	(segment
		(start 127.867664 -327.23328)
		(end 130.504692 -341.913972)
		(width 0.14224)
		(layer "In6.Cu")
		(net "P5E_CPU1_P0_TX_DP<14>")
	)
	(segment
		(start 72.323452 -376.384058)
		(end 71.568564 -376.384058)
		(width 0.14224)
		(layer "In6.Cu")
		(net "P5E_CPU1_P0_TX_DP<14>")
	)
	(segment
		(start 107.56265 -370.311934)
		(end 107.444794 -370.63299)
		(width 0.14224)
		(layer "In6.Cu")
		(net "P5E_CPU1_P0_TX_DP<14>")
	)
	(segment
		(start 106.900472 -372.114064)
		(end 106.782362 -372.435882)
		(width 0.14224)
		(layer "In6.Cu")
		(net "P5E_CPU1_P0_TX_DP<14>")
	)
	(segment
		(start 108.790994 -283.806392)
		(end 109.088936 -283.806392)
		(width 0.1143)
		(layer "In6.Cu")
		(net "P5E_CPU1_P0_TX_DP<14>")
	)
	(segment
		(start 110.418626 -289.78098)
		(end 110.34903 -289.82162)
		(width 0.1143)
		(layer "In6.Cu")
		(net "P5E_CPU1_P0_TX_DP<14>")
	)
	(segment
		(start 110.105698 -295.50741)
		(end 110.059978 -295.55313)
		(width 0.1143)
		(layer "In6.Cu")
		(net "P5E_CPU1_P0_TX_DP<14>")
	)
	(segment
		(start 107.48137 -370.13515)
		(end 107.562904 -370.311172)
		(width 0.14224)
		(layer "In6.Cu")
		(net "P5E_CPU1_P0_TX_DP<14>")
	)
	(segment
		(start 110.387892 -294.013636)
		(end 110.388146 -294.013636)
		(width 0.1143)
		(layer "In6.Cu")
		(net "P5E_CPU1_P0_TX_DP<14>")
	)
	(segment
		(start 123.264422 -318.425322)
		(end 127.867664 -327.23328)
		(width 0.14224)
		(layer "In6.Cu")
		(net "P5E_CPU1_P0_TX_DP<14>")
	)
	(segment
		(start 107.113578 -371.534436)
		(end 106.937302 -371.615716)
		(width 0.14224)
		(layer "In6.Cu")
		(net "P5E_CPU1_P0_TX_DP<14>")
	)
	(segment
		(start 112.345216 -303.797716)
		(end 112.657636 -304.38217)
		(width 0.14224)
		(layer "In6.Cu")
		(net "P5E_CPU1_P0_TX_DP<14>")
	)
	(segment
		(start 110.34903 -289.13074)
		(end 110.418626 -289.17138)
		(width 0.1143)
		(layer "In6.Cu")
		(net "P5E_CPU1_P0_TX_DP<14>")
	)
	(segment
		(start 110.418626 -291.400992)
		(end 110.34903 -291.441632)
		(width 0.1143)
		(layer "In6.Cu")
		(net "P5E_CPU1_P0_TX_DP<14>")
	)
	(segment
		(start 110.059978 -295.55313)
		(end 110.059978 -295.581578)
		(width 0.1143)
		(layer "In6.Cu")
		(net "P5E_CPU1_P0_TX_DP<14>")
	)
	(segment
		(start 106.937302 -371.615716)
		(end 106.819192 -371.938042)
		(width 0.14224)
		(layer "In6.Cu")
		(net "P5E_CPU1_P0_TX_DP<14>")
	)
	(segment
		(start 107.444794 -370.63299)
		(end 107.268518 -370.71427)
		(width 0.14224)
		(layer "In6.Cu")
		(net "P5E_CPU1_P0_TX_DP<14>")
	)
	(segment
		(start 130.504692 -341.913972)
		(end 130.504692 -344.424762)
		(width 0.14224)
		(layer "In6.Cu")
		(net "P5E_CPU1_P0_TX_DP<14>")
	)
	(segment
		(start 110.418626 -293.021004)
		(end 110.388146 -293.038784)
		(width 0.1143)
		(layer "In6.Cu")
		(net "P5E_CPU1_P0_TX_DP<14>")
	)
	(segment
		(start 110.420658 -288.159952)
		(end 110.34903 -288.201608)
		(width 0.1143)
		(layer "In6.Cu")
		(net "P5E_CPU1_P0_TX_DP<14>")
	)
	(segment
		(start 110.575598 -287.856422)
		(end 110.575598 -287.904174)
		(width 0.1143)
		(layer "In6.Cu")
		(net "P5E_CPU1_P0_TX_DP<14>")
	)
	(segment
		(start 71.568564 -376.384058)
		(end 71.277734 -376.093228)
		(width 0.14224)
		(layer "In6.Cu")
		(net "P5E_CPU1_P0_TX_DP<14>")
	)
	(segment
		(start 72.499728 -375.804684)
		(end 72.499728 -376.15622)
		(width 0.14224)
		(layer "In6.Cu")
		(net "P5E_CPU1_P0_TX_DP<14>")
	)
	(segment
		(start 110.35157 -287.512506)
		(end 110.418626 -287.551622)
		(width 0.1143)
		(layer "In6.Cu")
		(net "P5E_CPU1_P0_TX_DP<14>")
	)
	(segment
		(start 107.823508 -369.602004)
		(end 107.823254 -369.602766)
		(width 0.14224)
		(layer "In6.Cu")
		(net "P5E_CPU1_P0_TX_DP<14>")
	)
	(segment
		(start 107.150154 -371.036596)
		(end 107.231688 -371.212618)
		(width 0.14224)
		(layer "In6.Cu")
		(net "P5E_CPU1_P0_TX_DP<14>")
	)
	(segment
		(start 106.487976 -372.839488)
		(end 106.569256 -373.01551)
		(width 0.14224)
		(layer "In6.Cu")
		(net "P5E_CPU1_P0_TX_DP<14>")
	)
	(segment
		(start 106.819192 -371.938042)
		(end 106.900472 -372.114064)
		(width 0.14224)
		(layer "In6.Cu")
		(net "P5E_CPU1_P0_TX_DP<14>")
	)
	(segment
		(start 107.268518 -370.71427)
		(end 107.150154 -371.036596)
		(width 0.14224)
		(layer "In6.Cu")
		(net "P5E_CPU1_P0_TX_DP<14>")
	)
	(segment
		(start 125.655832 -355.499416)
		(end 111.149892 -366.27943)
		(width 0.14224)
		(layer "In6.Cu")
		(net "P5E_CPU1_P0_TX_DP<14>")
	)
	(segment
		(start 74.079862 -374.465342)
		(end 73.871074 -374.465342)
		(width 0.14224)
		(layer "In6.Cu")
		(net "P5E_CPU1_P0_TX_DP<14>")
	)
	(segment
		(start 110.059978 -295.581578)
		(end 110.059978 -298.130722)
		(width 0.14224)
		(layer "In6.Cu")
		(net "P5E_CPU1_P0_TX_DP<14>")
	)
	(segment
		(start 107.997498 -369.12804)
		(end 107.823508 -369.602004)
		(width 0.14224)
		(layer "In6.Cu")
		(net "P5E_CPU1_P0_TX_DP<14>")
	)
	(segment
		(start 109.917992 -285.103824)
		(end 109.949742 -285.122112)
		(width 0.1143)
		(layer "In6.Cu")
		(net "P5E_CPU1_P0_TX_DP<14>")
	)
	(segment
		(start 110.455964 -294.615362)
		(end 110.384844 -294.660828)
		(width 0.1143)
		(layer "In6.Cu")
		(net "P5E_CPU1_P0_TX_DP<14>")
	)
	(segment
		(start 107.562904 -370.311172)
		(end 107.56265 -370.311934)
		(width 0.14224)
		(layer "In6.Cu")
		(net "P5E_CPU1_P0_TX_DP<14>")
	)
	(segment
		(start 107.77601 -369.731544)
		(end 107.599734 -369.812824)
		(width 0.14224)
		(layer "In6.Cu")
		(net "P5E_CPU1_P0_TX_DP<14>")
	)
	(segment
		(start 75.903328 -375.543064)
		(end 75.35291 -374.992646)
		(width 0.14224)
		(layer "In6.Cu")
		(net "P5E_CPU1_P0_TX_DP<14>")
	)
	(segment
		(start 106.569256 -373.01551)
		(end 104.873552 -377.632722)
		(width 0.14224)
		(layer "In6.Cu")
		(net "P5E_CPU1_P0_TX_DP<14>")
	)
	(segment
		(start 130.409442 -344.903044)
		(end 126.864618 -353.460304)
		(width 0.14224)
		(layer "In6.Cu")
		(net "P5E_CPU1_P0_TX_DP<14>")
	)
	(segment
		(start 110.388146 -294.013636)
		(end 110.419896 -294.032178)
		(width 0.1143)
		(layer "In6.Cu")
		(net "P5E_CPU1_P0_TX_DP<14>")
	)
	(segment
		(start 110.41761 -286.541718)
		(end 110.355888 -286.577786)
		(width 0.1143)
		(layer "In6.Cu")
		(net "P5E_CPU1_P0_TX_DP<14>")
	)
	(segment
		(start 104.218994 -378.089668)
		(end 103.70312 -378.089668)
		(width 0.14224)
		(layer "In6.Cu")
		(net "P5E_CPU1_P0_TX_DP<14>")
	)
	(segment
		(start 109.408976 -284.270958)
		(end 109.456982 -284.298898)
		(width 0.1143)
		(layer "In6.Cu")
		(net "P5E_CPU1_P0_TX_DP<14>")
	)
	(segment
		(start 110.459266 -288.132012)
		(end 110.420658 -288.159952)
		(width 0.1143)
		(layer "In6.Cu")
		(net "P5E_CPU1_P0_TX_DP<14>")
	)
	(segment
		(start 110.34903 -290.750752)
		(end 110.418626 -290.791392)
		(width 0.1143)
		(layer "In6.Cu")
		(net "P5E_CPU1_P0_TX_DP<14>")
	)
	(segment
		(start 110.398814 -285.921704)
		(end 110.403132 -285.921704)
		(width 0.1143)
		(layer "In6.Cu")
		(net "P5E_CPU1_P0_TX_DP<14>")
	)
	(segment
		(start 107.599734 -369.812824)
		(end 107.48137 -370.13515)
		(width 0.14224)
		(layer "In6.Cu")
		(net "P5E_CPU1_P0_TX_DP<14>")
	)
	(segment
		(start 112.657636 -304.38217)
		(end 116.680996 -310.403494)
		(width 0.14224)
		(layer "In6.Cu")
		(net "P5E_CPU1_P0_TX_DP<14>")
	)
	(segment
		(start 110.105698 -295.146222)
		(end 110.105698 -295.50741)
		(width 0.1143)
		(layer "In6.Cu")
		(net "P5E_CPU1_P0_TX_DP<14>")
	)
	(segment
		(start 110.117128 -298.417996)
		(end 112.345216 -303.797716)
		(width 0.14224)
		(layer "In6.Cu")
		(net "P5E_CPU1_P0_TX_DP<14>")
	)
	(segment
		(start 72.426068 -376.33402)
		(end 72.413368 -376.34672)
		(width 0.14224)
		(layer "In6.Cu")
		(net "P5E_CPU1_P0_TX_DP<14>")
	)
	(segment
		(start 116.680996 -310.403494)
		(end 123.264422 -318.425322)
		(width 0.14224)
		(layer "In6.Cu")
		(net "P5E_CPU1_P0_TX_DP<14>")
	)
	(segment
		(start 106.606086 -372.517162)
		(end 106.487976 -372.839488)
		(width 0.14224)
		(layer "In6.Cu")
		(net "P5E_CPU1_P0_TX_DP<14>")
	)
	(segment
		(start 108.92536 -368.200178)
		(end 107.997498 -369.12804)
		(width 0.14224)
		(layer "In6.Cu")
		(net "P5E_CPU1_P0_TX_DP<14>")
	)
	(segment
		(start 110.34903 -292.370764)
		(end 110.418626 -292.411404)
		(width 0.1143)
		(layer "In6.Cu")
		(net "P5E_CPU1_P0_TX_DP<14>")
	)
	(segment
		(start 110.355888 -286.577786)
		(end 110.355888 -286.577532)
		(width 0.1143)
		(layer "In6.Cu")
		(net "P5E_CPU1_P0_TX_DP<14>")
	)
	(segment
		(start 72.499728 -376.15622)
		(end 72.426068 -376.33402)
		(width 0.14224)
		(layer "In6.Cu")
		(net "P5E_CPU1_P0_TX_DP<14>")
	)
	(segment
		(start 106.782362 -372.435882)
		(end 106.606086 -372.517162)
		(width 0.14224)
		(layer "In6.Cu")
		(net "P5E_CPU1_P0_TX_DP<14>")
	)
	(segment
		(start 107.231688 -371.212618)
		(end 107.113578 -371.534436)
		(width 0.14224)
		(layer "In6.Cu")
		(net "P5E_CPU1_P0_TX_DP<14>")
	)
	(segment
		(start 110.355888 -286.577532)
		(end 110.34903 -286.581596)
		(width 0.1143)
		(layer "In6.Cu")
		(net "P5E_CPU1_P0_TX_DP<14>")
	)
	(segment
		(start 110.388146 -293.038784)
		(end 110.387892 -293.039038)
		(width 0.1143)
		(layer "In6.Cu")
		(net "P5E_CPU1_P0_TX_DP<14>")
	)
	(segment
		(start 109.644688 -284.623764)
		(end 109.644688 -284.629098)
		(width 0.1143)
		(layer "In6.Cu")
		(net "P5E_CPU1_P0_TX_DP<14>")
	)
	(segment
		(start 97.988374 -376.286776)
		(end 77.698854 -376.286776)
		(width 0.14224)
		(layer "In6.Cu")
		(net "P5E_CPU1_P0_TX_DP<14>")
	)
	(segment
		(start 110.419896 -294.032178)
		(end 110.45317 -294.055292)
		(width 0.1143)
		(layer "In6.Cu")
		(net "P5E_CPU1_P0_TX_DP<14>")
	)
	(segment
		(start 109.088936 -283.806392)
		(end 109.17174 -283.889196)
		(width 0.1143)
		(layer "In6.Cu")
		(net "P5E_CPU1_P0_TX_DP<14>")
	)
	(segment
		(start 107.823254 -369.602766)
		(end 107.77601 -369.731544)
		(width 0.14224)
		(layer "In6.Cu")
		(net "P5E_CPU1_P0_TX_DP<14>")
	)
	(segment
		(start 110.384844 -294.660828)
		(end 110.350554 -294.680386)
		(width 0.1143)
		(layer "In6.Cu")
		(net "P5E_CPU1_P0_TX_DP<14>")
	)
	(segment
		(start 72.923654 -374.857772)
		(end 72.869552 -374.911874)
		(width 0.14224)
		(layer "In6.Cu")
		(net "P5E_CPU1_P0_TX_DP<14>")
	)
	(arc
		(start 110.418626 -289.17138)
		(mid 110.575603 -289.47618)
		(end 110.418626 -289.78098)
		(width 0.1143)
		(layer "In6.Cu")
		(net "P5E_CPU1_P0_TX_DP<14>")
	)
	(arc
		(start 110.34903 -286.581596)
		(mid 110.170217 -286.783946)
		(end 110.105698 -287.046162)
		(width 0.1143)
		(layer "In6.Cu")
		(net "P5E_CPU1_P0_TX_DP<14>")
	)
	(arc
		(start 110.403132 -285.921704)
		(mid 110.575115 -286.227892)
		(end 110.41761 -286.541718)
		(width 0.1143)
		(layer "In6.Cu")
		(net "P5E_CPU1_P0_TX_DP<14>")
	)
	(arc
		(start 110.059978 -298.130722)
		(mid 110.074405 -298.277174)
		(end 110.117128 -298.417996)
		(width 0.14224)
		(layer "In6.Cu")
		(net "P5E_CPU1_P0_TX_DP<14>")
	)
	(arc
		(start 110.45317 -294.055292)
		(mid 110.600323 -294.334562)
		(end 110.455964 -294.615362)
		(width 0.1143)
		(layer "In6.Cu")
		(net "P5E_CPU1_P0_TX_DP<14>")
	)
	(arc
		(start 77.698854 -376.286776)
		(mid 76.72713 -376.093488)
		(end 75.903328 -375.543064)
		(width 0.14224)
		(layer "In6.Cu")
		(net "P5E_CPU1_P0_TX_DP<14>")
	)
	(arc
		(start 109.644688 -284.629098)
		(mid 109.7179 -284.90298)
		(end 109.917992 -285.103824)
		(width 0.1143)
		(layer "In6.Cu")
		(net "P5E_CPU1_P0_TX_DP<14>")
	)
	(arc
		(start 110.105698 -287.046162)
		(mid 110.170934 -287.309753)
		(end 110.35157 -287.512506)
		(width 0.1143)
		(layer "In6.Cu")
		(net "P5E_CPU1_P0_TX_DP<14>")
	)
	(arc
		(start 111.149892 -366.27943)
		(mid 110.002493 -367.199114)
		(end 108.92536 -368.200178)
		(width 0.14224)
		(layer "In6.Cu")
		(net "P5E_CPU1_P0_TX_DP<14>")
	)
	(arc
		(start 103.70312 -378.089668)
		(mid 102.317349 -377.876251)
		(end 101.059996 -377.255786)
		(width 0.14224)
		(layer "In6.Cu")
		(net "P5E_CPU1_P0_TX_DP<14>")
	)
	(arc
		(start 110.387892 -293.039038)
		(mid 110.108128 -293.5264)
		(end 110.387892 -294.013636)
		(width 0.1143)
		(layer "In6.Cu")
		(net "P5E_CPU1_P0_TX_DP<14>")
	)
	(arc
		(start 110.350554 -294.680386)
		(mid 110.17061 -294.883067)
		(end 110.105698 -295.146222)
		(width 0.1143)
		(layer "In6.Cu")
		(net "P5E_CPU1_P0_TX_DP<14>")
	)
	(arc
		(start 109.456982 -284.298898)
		(mid 109.594414 -284.436157)
		(end 109.644688 -284.623764)
		(width 0.1143)
		(layer "In6.Cu")
		(net "P5E_CPU1_P0_TX_DP<14>")
	)
	(arc
		(start 72.869552 -374.911874)
		(mid 72.59585 -375.321499)
		(end 72.499728 -375.804684)
		(width 0.14224)
		(layer "In6.Cu")
		(net "P5E_CPU1_P0_TX_DP<14>")
	)
	(arc
		(start 110.34903 -289.82162)
		(mid 110.105703 -290.286186)
		(end 110.34903 -290.750752)
		(width 0.1143)
		(layer "In6.Cu")
		(net "P5E_CPU1_P0_TX_DP<14>")
	)
	(arc
		(start 110.342426 -285.886398)
		(mid 110.370098 -285.904885)
		(end 110.398814 -285.921704)
		(width 0.1143)
		(layer "In6.Cu")
		(net "P5E_CPU1_P0_TX_DP<14>")
	)
	(arc
		(start 101.059996 -377.255786)
		(mid 99.598807 -376.534741)
		(end 97.988374 -376.286776)
		(width 0.14224)
		(layer "In6.Cu")
		(net "P5E_CPU1_P0_TX_DP<14>")
	)
	(arc
		(start 110.34903 -291.441632)
		(mid 110.105703 -291.906198)
		(end 110.34903 -292.370764)
		(width 0.1143)
		(layer "In6.Cu")
		(net "P5E_CPU1_P0_TX_DP<14>")
	)
	(arc
		(start 109.949742 -285.122112)
		(mid 110.064418 -285.255446)
		(end 110.105698 -285.426404)
		(width 0.1143)
		(layer "In6.Cu")
		(net "P5E_CPU1_P0_TX_DP<14>")
	)
	(arc
		(start 110.418626 -290.791392)
		(mid 110.575603 -291.096192)
		(end 110.418626 -291.400992)
		(width 0.1143)
		(layer "In6.Cu")
		(net "P5E_CPU1_P0_TX_DP<14>")
	)
	(arc
		(start 110.34903 -288.201608)
		(mid 110.105703 -288.666174)
		(end 110.34903 -289.13074)
		(width 0.1143)
		(layer "In6.Cu")
		(net "P5E_CPU1_P0_TX_DP<14>")
	)
	(arc
		(start 130.504692 -344.424762)
		(mid 130.480614 -344.66859)
		(end 130.409442 -344.903044)
		(width 0.14224)
		(layer "In6.Cu")
		(net "P5E_CPU1_P0_TX_DP<14>")
	)
	(arc
		(start 125.745748 -355.410516)
		(mid 125.703935 -355.458147)
		(end 125.655832 -355.499416)
		(width 0.14224)
		(layer "In6.Cu")
		(net "P5E_CPU1_P0_TX_DP<14>")
	)
	(arc
		(start 109.17555 -283.912056)
		(mid 109.256983 -284.114454)
		(end 109.408976 -284.270958)
		(width 0.1143)
		(layer "In6.Cu")
		(net "P5E_CPU1_P0_TX_DP<14>")
	)
	(arc
		(start 75.35291 -374.992646)
		(mid 74.768831 -374.602377)
		(end 74.079862 -374.465342)
		(width 0.14224)
		(layer "In6.Cu")
		(net "P5E_CPU1_P0_TX_DP<14>")
	)
	(arc
		(start 110.575598 -287.904174)
		(mid 110.544825 -288.032074)
		(end 110.459266 -288.132012)
		(width 0.1143)
		(layer "In6.Cu")
		(net "P5E_CPU1_P0_TX_DP<14>")
	)
	(arc
		(start 126.864618 -353.460304)
		(mid 126.367789 -354.471329)
		(end 125.745748 -355.410516)
		(width 0.14224)
		(layer "In6.Cu")
		(net "P5E_CPU1_P0_TX_DP<14>")
	)
	(arc
		(start 73.871074 -374.465342)
		(mid 73.358336 -374.567332)
		(end 72.923654 -374.857772)
		(width 0.14224)
		(layer "In6.Cu")
		(net "P5E_CPU1_P0_TX_DP<14>")
	)
	(arc
		(start 72.413368 -376.34672)
		(mid 72.372128 -376.374339)
		(end 72.323452 -376.384058)
		(width 0.14224)
		(layer "In6.Cu")
		(net "P5E_CPU1_P0_TX_DP<14>")
	)
	(arc
		(start 110.418626 -287.551622)
		(mid 110.534053 -287.684998)
		(end 110.575598 -287.856422)
		(width 0.1143)
		(layer "In6.Cu")
		(net "P5E_CPU1_P0_TX_DP<14>")
	)
	(arc
		(start 110.105698 -285.426404)
		(mid 110.168343 -285.685083)
		(end 110.342426 -285.886398)
		(width 0.1143)
		(layer "In6.Cu")
		(net "P5E_CPU1_P0_TX_DP<14>")
	)
	(arc
		(start 109.17174 -283.889196)
		(mid 109.173528 -283.900645)
		(end 109.17555 -283.912056)
		(width 0.1143)
		(layer "In6.Cu")
		(net "P5E_CPU1_P0_TX_DP<14>")
	)
	(arc
		(start 104.873552 -377.632722)
		(mid 104.618143 -377.964157)
		(end 104.218994 -378.089668)
		(width 0.14224)
		(layer "In6.Cu")
		(net "P5E_CPU1_P0_TX_DP<14>")
	)
	(arc
		(start 110.418626 -292.411404)
		(mid 110.575603 -292.716204)
		(end 110.418626 -293.021004)
		(width 0.1143)
		(layer "In6.Cu")
		(net "P5E_CPU1_P0_TX_DP<14>")
	)
	(segment
		(start 69.135244 -369.30584)
		(end 69.135244 -370.00942)
		(width 0.12954)
		(layer "F.Cu")
		(net "P5E_CPU1_P0_TX_DP<13>")
	)
	(segment
		(start 69.405754 -369.03533)
		(end 69.135244 -369.30584)
		(width 0.12954)
		(layer "F.Cu")
		(net "P5E_CPU1_P0_TX_DP<13>")
	)
	(segment
		(start 69.135244 -370.00942)
		(end 69.431154 -370.30533)
		(width 0.12954)
		(layer "F.Cu")
		(net "P5E_CPU1_P0_TX_DP<13>")
	)
	(segment
		(start 109.257846 -285.160466)
		(end 108.790994 -285.426404)
		(width 0.12954)
		(layer "F.Cu")
		(net "P5E_CPU1_P0_TX_DP<13>")
	)
	(segment
		(start 70.759066 -369.97005)
		(end 70.75297 -369.969542)
		(width 0.14224)
		(layer "In6.Cu")
		(net "P5E_CPU1_P0_TX_DP<13>")
	)
	(segment
		(start 109.408976 -285.89097)
		(end 109.416596 -285.895542)
		(width 0.1143)
		(layer "In6.Cu")
		(net "P5E_CPU1_P0_TX_DP<13>")
	)
	(segment
		(start 109.119924 -295.519856)
		(end 109.119924 -295.548304)
		(width 0.1143)
		(layer "In6.Cu")
		(net "P5E_CPU1_P0_TX_DP<13>")
	)
	(segment
		(start 82.780632 -375.231914)
		(end 82.643472 -375.094754)
		(width 0.14224)
		(layer "In6.Cu")
		(net "P5E_CPU1_P0_TX_DP<13>")
	)
	(segment
		(start 109.553756 -366.168178)
		(end 105.664508 -370.057426)
		(width 0.14224)
		(layer "In6.Cu")
		(net "P5E_CPU1_P0_TX_DP<13>")
	)
	(segment
		(start 109.635798 -287.709356)
		(end 109.635798 -287.856422)
		(width 0.1143)
		(layer "In6.Cu")
		(net "P5E_CPU1_P0_TX_DP<13>")
	)
	(segment
		(start 79.66075 -375.094754)
		(end 79.52359 -375.231914)
		(width 0.14224)
		(layer "In6.Cu")
		(net "P5E_CPU1_P0_TX_DP<13>")
	)
	(segment
		(start 75.562968 -373.677688)
		(end 75.368912 -373.677688)
		(width 0.14224)
		(layer "In6.Cu")
		(net "P5E_CPU1_P0_TX_DP<13>")
	)
	(segment
		(start 109.406944 -286.58312)
		(end 109.40669 -286.58312)
		(width 0.1143)
		(layer "In6.Cu")
		(net "P5E_CPU1_P0_TX_DP<13>")
	)
	(segment
		(start 109.165644 -295.474136)
		(end 109.119924 -295.519856)
		(width 0.1143)
		(layer "In6.Cu")
		(net "P5E_CPU1_P0_TX_DP<13>")
	)
	(segment
		(start 109.416596 -289.135312)
		(end 109.444282 -289.151314)
		(width 0.1143)
		(layer "In6.Cu")
		(net "P5E_CPU1_P0_TX_DP<13>")
	)
	(segment
		(start 111.499396 -304.209958)
		(end 111.80318 -304.778156)
		(width 0.14224)
		(layer "In6.Cu")
		(net "P5E_CPU1_P0_TX_DP<13>")
	)
	(segment
		(start 109.088936 -285.426404)
		(end 109.17174 -285.509208)
		(width 0.1143)
		(layer "In6.Cu")
		(net "P5E_CPU1_P0_TX_DP<13>")
	)
	(segment
		(start 69.114924 -369.32616)
		(end 69.405754 -369.03533)
		(width 0.14224)
		(layer "In6.Cu")
		(net "P5E_CPU1_P0_TX_DP<13>")
	)
	(segment
		(start 109.469428 -285.926276)
		(end 109.469682 -285.926276)
		(width 0.1143)
		(layer "In6.Cu")
		(net "P5E_CPU1_P0_TX_DP<13>")
	)
	(segment
		(start 129.557272 -342.045798)
		(end 129.557272 -343.384378)
		(width 0.14224)
		(layer "In6.Cu")
		(net "P5E_CPU1_P0_TX_DP<13>")
	)
	(segment
		(start 109.499654 -293.006272)
		(end 109.479842 -293.020496)
		(width 0.1143)
		(layer "In6.Cu")
		(net "P5E_CPU1_P0_TX_DP<13>")
	)
	(segment
		(start 124.02312 -355.463348)
		(end 123.513596 -355.803962)
		(width 0.14224)
		(layer "In6.Cu")
		(net "P5E_CPU1_P0_TX_DP<13>")
	)
	(segment
		(start 74.765408 -372.880128)
		(end 74.571352 -372.880128)
		(width 0.14224)
		(layer "In6.Cu")
		(net "P5E_CPU1_P0_TX_DP<13>")
	)
	(segment
		(start 72.674734 -370.98351)
		(end 72.674734 -370.789454)
		(width 0.14224)
		(layer "In6.Cu")
		(net "P5E_CPU1_P0_TX_DP<13>")
	)
	(segment
		(start 109.151166 -298.539662)
		(end 111.499396 -304.209958)
		(width 0.14224)
		(layer "In6.Cu")
		(net "P5E_CPU1_P0_TX_DP<13>")
	)
	(segment
		(start 79.09687 -375.231914)
		(end 78.95971 -375.094754)
		(width 0.14224)
		(layer "In6.Cu")
		(net "P5E_CPU1_P0_TX_DP<13>")
	)
	(segment
		(start 109.408976 -292.370764)
		(end 109.448854 -292.394132)
		(width 0.1143)
		(layer "In6.Cu")
		(net "P5E_CPU1_P0_TX_DP<13>")
	)
	(segment
		(start 109.409992 -293.991538)
		(end 109.468666 -294.025574)
		(width 0.1143)
		(layer "In6.Cu")
		(net "P5E_CPU1_P0_TX_DP<13>")
	)
	(segment
		(start 109.119924 -295.548304)
		(end 109.119924 -298.382944)
		(width 0.14224)
		(layer "In6.Cu")
		(net "P5E_CPU1_P0_TX_DP<13>")
	)
	(segment
		(start 73.472294 -371.587014)
		(end 73.170288 -371.285008)
		(width 0.14224)
		(layer "In6.Cu")
		(net "P5E_CPU1_P0_TX_DP<13>")
	)
	(segment
		(start 73.773792 -372.082568)
		(end 73.472294 -371.78107)
		(width 0.14224)
		(layer "In6.Cu")
		(net "P5E_CPU1_P0_TX_DP<13>")
	)
	(segment
		(start 69.114924 -369.93449)
		(end 69.114924 -369.32616)
		(width 0.14224)
		(layer "In6.Cu")
		(net "P5E_CPU1_P0_TX_DP<13>")
	)
	(segment
		(start 109.445044 -289.151822)
		(end 109.479842 -289.171888)
		(width 0.1143)
		(layer "In6.Cu")
		(net "P5E_CPU1_P0_TX_DP<13>")
	)
	(segment
		(start 82.216752 -375.094754)
		(end 82.079592 -375.231914)
		(width 0.14224)
		(layer "In6.Cu")
		(net "P5E_CPU1_P0_TX_DP<13>")
	)
	(segment
		(start 80.08747 -375.094754)
		(end 79.66075 -375.094754)
		(width 0.14224)
		(layer "In6.Cu")
		(net "P5E_CPU1_P0_TX_DP<13>")
	)
	(segment
		(start 70.737476 -369.969288)
		(end 70.342252 -369.969288)
		(width 0.14224)
		(layer "In6.Cu")
		(net "P5E_CPU1_P0_TX_DP<13>")
	)
	(segment
		(start 70.75297 -369.969542)
		(end 70.751192 -369.97005)
		(width 0.14224)
		(layer "In6.Cu")
		(net "P5E_CPU1_P0_TX_DP<13>")
	)
	(segment
		(start 75.864974 -374.17375)
		(end 75.864974 -373.979694)
		(width 0.14224)
		(layer "In6.Cu")
		(net "P5E_CPU1_P0_TX_DP<13>")
	)
	(segment
		(start 109.448854 -290.77412)
		(end 109.479842 -290.7919)
		(width 0.1143)
		(layer "In6.Cu")
		(net "P5E_CPU1_P0_TX_DP<13>")
	)
	(segment
		(start 109.448092 -291.418772)
		(end 109.408976 -291.441632)
		(width 0.1143)
		(layer "In6.Cu")
		(net "P5E_CPU1_P0_TX_DP<13>")
	)
	(segment
		(start 108.790994 -285.426404)
		(end 109.088936 -285.426404)
		(width 0.1143)
		(layer "In6.Cu")
		(net "P5E_CPU1_P0_TX_DP<13>")
	)
	(segment
		(start 69.70268 -370.14785)
		(end 69.404738 -370.14785)
		(width 0.14224)
		(layer "In6.Cu")
		(net "P5E_CPU1_P0_TX_DP<13>")
	)
	(segment
		(start 109.468666 -294.025574)
		(end 109.469428 -294.026082)
		(width 0.1143)
		(layer "In6.Cu")
		(net "P5E_CPU1_P0_TX_DP<13>")
	)
	(segment
		(start 75.067414 -373.182134)
		(end 74.765408 -372.880128)
		(width 0.14224)
		(layer "In6.Cu")
		(net "P5E_CPU1_P0_TX_DP<13>")
	)
	(segment
		(start 79.52359 -375.231914)
		(end 79.09687 -375.231914)
		(width 0.14224)
		(layer "In6.Cu")
		(net "P5E_CPU1_P0_TX_DP<13>")
	)
	(segment
		(start 101.78288 -375.231914)
		(end 82.780632 -375.231914)
		(width 0.14224)
		(layer "In6.Cu")
		(net "P5E_CPU1_P0_TX_DP<13>")
	)
	(segment
		(start 109.479842 -289.171888)
		(end 109.499654 -289.186112)
		(width 0.1143)
		(layer "In6.Cu")
		(net "P5E_CPU1_P0_TX_DP<13>")
	)
	(segment
		(start 82.643472 -375.094754)
		(end 82.216752 -375.094754)
		(width 0.14224)
		(layer "In6.Cu")
		(net "P5E_CPU1_P0_TX_DP<13>")
	)
	(segment
		(start 73.472294 -371.78107)
		(end 73.472294 -371.587014)
		(width 0.14224)
		(layer "In6.Cu")
		(net "P5E_CPU1_P0_TX_DP<13>")
	)
	(segment
		(start 109.447076 -290.773104)
		(end 109.448854 -290.77412)
		(width 0.1143)
		(layer "In6.Cu")
		(net "P5E_CPU1_P0_TX_DP<13>")
	)
	(segment
		(start 80.22463 -375.231914)
		(end 80.08747 -375.094754)
		(width 0.14224)
		(layer "In6.Cu")
		(net "P5E_CPU1_P0_TX_DP<13>")
	)
	(segment
		(start 109.469428 -294.64635)
		(end 109.409738 -294.681148)
		(width 0.1143)
		(layer "In6.Cu")
		(net "P5E_CPU1_P0_TX_DP<13>")
	)
	(segment
		(start 109.479842 -293.020496)
		(end 109.448854 -293.038276)
		(width 0.1143)
		(layer "In6.Cu")
		(net "P5E_CPU1_P0_TX_DP<13>")
	)
	(segment
		(start 109.444282 -289.151314)
		(end 109.445044 -289.151822)
		(width 0.1143)
		(layer "In6.Cu")
		(net "P5E_CPU1_P0_TX_DP<13>")
	)
	(segment
		(start 109.48162 -288.15919)
		(end 109.408976 -288.201608)
		(width 0.1143)
		(layer "In6.Cu")
		(net "P5E_CPU1_P0_TX_DP<13>")
	)
	(segment
		(start 109.165898 -295.394634)
		(end 109.16539 -295.395142)
		(width 0.1143)
		(layer "In6.Cu")
		(net "P5E_CPU1_P0_TX_DP<13>")
	)
	(segment
		(start 82.079592 -375.231914)
		(end 80.22463 -375.231914)
		(width 0.14224)
		(layer "In6.Cu")
		(net "P5E_CPU1_P0_TX_DP<13>")
	)
	(segment
		(start 109.479842 -292.411912)
		(end 109.499654 -292.426136)
		(width 0.1143)
		(layer "In6.Cu")
		(net "P5E_CPU1_P0_TX_DP<13>")
	)
	(segment
		(start 78.39583 -375.231914)
		(end 77.460856 -375.231914)
		(width 0.14224)
		(layer "In6.Cu")
		(net "P5E_CPU1_P0_TX_DP<13>")
	)
	(segment
		(start 105.531412 -370.265452)
		(end 104.581452 -372.851426)
		(width 0.14224)
		(layer "In6.Cu")
		(net "P5E_CPU1_P0_TX_DP<13>")
	)
	(segment
		(start 109.445552 -289.800284)
		(end 109.408976 -289.82162)
		(width 0.1143)
		(layer "In6.Cu")
		(net "P5E_CPU1_P0_TX_DP<13>")
	)
	(segment
		(start 127.011176 -327.807574)
		(end 129.546096 -341.919814)
		(width 0.14224)
		(layer "In6.Cu")
		(net "P5E_CPU1_P0_TX_DP<13>")
	)
	(segment
		(start 73.170288 -371.285008)
		(end 72.976232 -371.285008)
		(width 0.14224)
		(layer "In6.Cu")
		(net "P5E_CPU1_P0_TX_DP<13>")
	)
	(segment
		(start 74.269854 -372.57863)
		(end 74.269854 -372.384574)
		(width 0.14224)
		(layer "In6.Cu")
		(net "P5E_CPU1_P0_TX_DP<13>")
	)
	(segment
		(start 72.372728 -370.487448)
		(end 72.178672 -370.487448)
		(width 0.14224)
		(layer "In6.Cu")
		(net "P5E_CPU1_P0_TX_DP<13>")
	)
	(segment
		(start 109.499654 -289.766248)
		(end 109.479842 -289.780472)
		(width 0.1143)
		(layer "In6.Cu")
		(net "P5E_CPU1_P0_TX_DP<13>")
	)
	(segment
		(start 109.469428 -294.026082)
		(end 109.469682 -294.026082)
		(width 0.1143)
		(layer "In6.Cu")
		(net "P5E_CPU1_P0_TX_DP<13>")
	)
	(segment
		(start 109.479842 -291.400484)
		(end 109.448854 -291.418264)
		(width 0.1143)
		(layer "In6.Cu")
		(net "P5E_CPU1_P0_TX_DP<13>")
	)
	(segment
		(start 109.448092 -293.038784)
		(end 109.432598 -293.04742)
		(width 0.1143)
		(layer "In6.Cu")
		(net "P5E_CPU1_P0_TX_DP<13>")
	)
	(segment
		(start 109.16539 -295.395142)
		(end 109.16539 -295.473882)
		(width 0.1143)
		(layer "In6.Cu")
		(net "P5E_CPU1_P0_TX_DP<13>")
	)
	(segment
		(start 109.469936 -294.64635)
		(end 109.469428 -294.64635)
		(width 0.1143)
		(layer "In6.Cu")
		(net "P5E_CPU1_P0_TX_DP<13>")
	)
	(segment
		(start 109.432598 -293.04742)
		(end 109.407706 -293.062406)
		(width 0.1143)
		(layer "In6.Cu")
		(net "P5E_CPU1_P0_TX_DP<13>")
	)
	(segment
		(start 112.107218 -364.25886)
		(end 109.681264 -366.058196)
		(width 0.14224)
		(layer "In6.Cu")
		(net "P5E_CPU1_P0_TX_DP<13>")
	)
	(segment
		(start 76.5429 -374.851676)
		(end 75.864974 -374.17375)
		(width 0.14224)
		(layer "In6.Cu")
		(net "P5E_CPU1_P0_TX_DP<13>")
	)
	(segment
		(start 78.53299 -375.094754)
		(end 78.39583 -375.231914)
		(width 0.14224)
		(layer "In6.Cu")
		(net "P5E_CPU1_P0_TX_DP<13>")
	)
	(segment
		(start 75.368912 -373.677688)
		(end 75.067414 -373.37619)
		(width 0.14224)
		(layer "In6.Cu")
		(net "P5E_CPU1_P0_TX_DP<13>")
	)
	(segment
		(start 109.16539 -295.473882)
		(end 109.165644 -295.474136)
		(width 0.1143)
		(layer "In6.Cu")
		(net "P5E_CPU1_P0_TX_DP<13>")
	)
	(segment
		(start 109.469428 -286.546544)
		(end 109.406944 -286.58312)
		(width 0.1143)
		(layer "In6.Cu")
		(net "P5E_CPU1_P0_TX_DP<13>")
	)
	(segment
		(start 109.450632 -285.9151)
		(end 109.451394 -285.915608)
		(width 0.1143)
		(layer "In6.Cu")
		(net "P5E_CPU1_P0_TX_DP<13>")
	)
	(segment
		(start 109.451394 -285.915608)
		(end 109.467904 -285.92526)
		(width 0.1143)
		(layer "In6.Cu")
		(net "P5E_CPU1_P0_TX_DP<13>")
	)
	(segment
		(start 75.067414 -373.37619)
		(end 75.067414 -373.182134)
		(width 0.14224)
		(layer "In6.Cu")
		(net "P5E_CPU1_P0_TX_DP<13>")
	)
	(segment
		(start 109.469936 -286.546544)
		(end 109.469428 -286.546544)
		(width 0.1143)
		(layer "In6.Cu")
		(net "P5E_CPU1_P0_TX_DP<13>")
	)
	(segment
		(start 129.153158 -345.415362)
		(end 125.978412 -353.08032)
		(width 0.14224)
		(layer "In6.Cu")
		(net "P5E_CPU1_P0_TX_DP<13>")
	)
	(segment
		(start 109.408976 -290.750752)
		(end 109.447076 -290.773104)
		(width 0.1143)
		(layer "In6.Cu")
		(net "P5E_CPU1_P0_TX_DP<13>")
	)
	(segment
		(start 115.950238 -310.985916)
		(end 122.423428 -318.873632)
		(width 0.14224)
		(layer "In6.Cu")
		(net "P5E_CPU1_P0_TX_DP<13>")
	)
	(segment
		(start 123.393962 -355.888036)
		(end 112.452404 -364.002828)
		(width 0.14224)
		(layer "In6.Cu")
		(net "P5E_CPU1_P0_TX_DP<13>")
	)
	(segment
		(start 72.178672 -370.487448)
		(end 71.877174 -370.18595)
		(width 0.14224)
		(layer "In6.Cu")
		(net "P5E_CPU1_P0_TX_DP<13>")
	)
	(segment
		(start 71.355966 -369.97005)
		(end 70.759066 -369.97005)
		(width 0.14224)
		(layer "In6.Cu")
		(net "P5E_CPU1_P0_TX_DP<13>")
	)
	(segment
		(start 109.479842 -287.55213)
		(end 109.599476 -287.638236)
		(width 0.1143)
		(layer "In6.Cu")
		(net "P5E_CPU1_P0_TX_DP<13>")
	)
	(segment
		(start 111.868204 -304.886614)
		(end 115.871498 -310.877966)
		(width 0.14224)
		(layer "In6.Cu")
		(net "P5E_CPU1_P0_TX_DP<13>")
	)
	(segment
		(start 75.864974 -373.979694)
		(end 75.562968 -373.677688)
		(width 0.14224)
		(layer "In6.Cu")
		(net "P5E_CPU1_P0_TX_DP<13>")
	)
	(segment
		(start 73.967848 -372.082568)
		(end 73.773792 -372.082568)
		(width 0.14224)
		(layer "In6.Cu")
		(net "P5E_CPU1_P0_TX_DP<13>")
	)
	(segment
		(start 109.479842 -289.780472)
		(end 109.445552 -289.800284)
		(width 0.1143)
		(layer "In6.Cu")
		(net "P5E_CPU1_P0_TX_DP<13>")
	)
	(segment
		(start 109.44606 -285.912814)
		(end 109.450632 -285.9151)
		(width 0.1143)
		(layer "In6.Cu")
		(net "P5E_CPU1_P0_TX_DP<13>")
	)
	(segment
		(start 109.448854 -291.418264)
		(end 109.448092 -291.418772)
		(width 0.1143)
		(layer "In6.Cu")
		(net "P5E_CPU1_P0_TX_DP<13>")
	)
	(segment
		(start 109.467904 -285.92526)
		(end 109.469428 -285.926276)
		(width 0.1143)
		(layer "In6.Cu")
		(net "P5E_CPU1_P0_TX_DP<13>")
	)
	(segment
		(start 112.452404 -364.002828)
		(end 112.107218 -364.25886)
		(width 0.14224)
		(layer "In6.Cu")
		(net "P5E_CPU1_P0_TX_DP<13>")
	)
	(segment
		(start 74.269854 -372.384574)
		(end 73.967848 -372.082568)
		(width 0.14224)
		(layer "In6.Cu")
		(net "P5E_CPU1_P0_TX_DP<13>")
	)
	(segment
		(start 122.493278 -318.979042)
		(end 126.89586 -327.40092)
		(width 0.14224)
		(layer "In6.Cu")
		(net "P5E_CPU1_P0_TX_DP<13>")
	)
	(segment
		(start 78.95971 -375.094754)
		(end 78.53299 -375.094754)
		(width 0.14224)
		(layer "In6.Cu")
		(net "P5E_CPU1_P0_TX_DP<13>")
	)
	(segment
		(start 126.941072 -327.518776)
		(end 126.98857 -327.704196)
		(width 0.14224)
		(layer "In6.Cu")
		(net "P5E_CPU1_P0_TX_DP<13>")
	)
	(segment
		(start 109.448854 -293.038276)
		(end 109.448092 -293.038784)
		(width 0.1143)
		(layer "In6.Cu")
		(net "P5E_CPU1_P0_TX_DP<13>")
	)
	(segment
		(start 109.411516 -287.512506)
		(end 109.479842 -287.55213)
		(width 0.1143)
		(layer "In6.Cu")
		(net "P5E_CPU1_P0_TX_DP<13>")
	)
	(segment
		(start 109.165898 -295.146222)
		(end 109.165898 -295.394634)
		(width 0.1143)
		(layer "In6.Cu")
		(net "P5E_CPU1_P0_TX_DP<13>")
	)
	(segment
		(start 109.416596 -285.895542)
		(end 109.44606 -285.912814)
		(width 0.1143)
		(layer "In6.Cu")
		(net "P5E_CPU1_P0_TX_DP<13>")
	)
	(segment
		(start 109.408976 -289.13074)
		(end 109.416596 -289.135312)
		(width 0.1143)
		(layer "In6.Cu")
		(net "P5E_CPU1_P0_TX_DP<13>")
	)
	(segment
		(start 74.571352 -372.880128)
		(end 74.269854 -372.57863)
		(width 0.14224)
		(layer "In6.Cu")
		(net "P5E_CPU1_P0_TX_DP<13>")
	)
	(segment
		(start 109.448854 -292.394132)
		(end 109.479842 -292.411912)
		(width 0.1143)
		(layer "In6.Cu")
		(net "P5E_CPU1_P0_TX_DP<13>")
	)
	(segment
		(start 72.976232 -371.285008)
		(end 72.674734 -370.98351)
		(width 0.14224)
		(layer "In6.Cu")
		(net "P5E_CPU1_P0_TX_DP<13>")
	)
	(segment
		(start 72.674734 -370.789454)
		(end 72.372728 -370.487448)
		(width 0.14224)
		(layer "In6.Cu")
		(net "P5E_CPU1_P0_TX_DP<13>")
	)
	(arc
		(start 71.877174 -370.18595)
		(mid 71.638042 -370.026167)
		(end 71.355966 -369.97005)
		(width 0.14224)
		(layer "In6.Cu")
		(net "P5E_CPU1_P0_TX_DP<13>")
	)
	(arc
		(start 109.17174 -285.509208)
		(mid 109.173528 -285.520657)
		(end 109.17555 -285.532068)
		(width 0.1143)
		(layer "In6.Cu")
		(net "P5E_CPU1_P0_TX_DP<13>")
	)
	(arc
		(start 122.423428 -318.873632)
		(mid 122.46107 -318.924537)
		(end 122.493278 -318.979042)
		(width 0.14224)
		(layer "In6.Cu")
		(net "P5E_CPU1_P0_TX_DP<13>")
	)
	(arc
		(start 126.89586 -327.40092)
		(mid 126.921869 -327.458543)
		(end 126.941072 -327.518776)
		(width 0.14224)
		(layer "In6.Cu")
		(net "P5E_CPU1_P0_TX_DP<13>")
	)
	(arc
		(start 109.599476 -287.638236)
		(mid 109.626164 -287.669436)
		(end 109.635798 -287.709356)
		(width 0.1143)
		(layer "In6.Cu")
		(net "P5E_CPU1_P0_TX_DP<13>")
	)
	(arc
		(start 109.469682 -294.026082)
		(mid 109.648224 -294.336106)
		(end 109.469936 -294.64635)
		(width 0.1143)
		(layer "In6.Cu")
		(net "P5E_CPU1_P0_TX_DP<13>")
	)
	(arc
		(start 126.98857 -327.704196)
		(mid 127.000812 -327.75568)
		(end 127.011176 -327.807574)
		(width 0.14224)
		(layer "In6.Cu")
		(net "P5E_CPU1_P0_TX_DP<13>")
	)
	(arc
		(start 109.408976 -291.441632)
		(mid 109.165649 -291.906198)
		(end 109.408976 -292.370764)
		(width 0.1143)
		(layer "In6.Cu")
		(net "P5E_CPU1_P0_TX_DP<13>")
	)
	(arc
		(start 69.404738 -370.14785)
		(mid 69.273185 -370.121758)
		(end 69.16166 -370.047266)
		(width 0.14224)
		(layer "In6.Cu")
		(net "P5E_CPU1_P0_TX_DP<13>")
	)
	(arc
		(start 104.581452 -372.851426)
		(mid 104.127196 -373.730002)
		(end 103.523034 -374.513094)
		(width 0.14224)
		(layer "In6.Cu")
		(net "P5E_CPU1_P0_TX_DP<13>")
	)
	(arc
		(start 115.871498 -310.877966)
		(mid 115.909721 -310.932778)
		(end 115.950238 -310.985916)
		(width 0.14224)
		(layer "In6.Cu")
		(net "P5E_CPU1_P0_TX_DP<13>")
	)
	(arc
		(start 111.80318 -304.778156)
		(mid 111.834366 -304.83318)
		(end 111.868204 -304.886614)
		(width 0.14224)
		(layer "In6.Cu")
		(net "P5E_CPU1_P0_TX_DP<13>")
	)
	(arc
		(start 129.557272 -343.384378)
		(mid 129.455245 -344.419775)
		(end 129.153158 -345.415362)
		(width 0.14224)
		(layer "In6.Cu")
		(net "P5E_CPU1_P0_TX_DP<13>")
	)
	(arc
		(start 70.751192 -369.97005)
		(mid 70.744345 -369.969477)
		(end 70.737476 -369.969288)
		(width 0.14224)
		(layer "In6.Cu")
		(net "P5E_CPU1_P0_TX_DP<13>")
	)
	(arc
		(start 109.469682 -285.926276)
		(mid 109.648224 -286.2363)
		(end 109.469936 -286.546544)
		(width 0.1143)
		(layer "In6.Cu")
		(net "P5E_CPU1_P0_TX_DP<13>")
	)
	(arc
		(start 109.407706 -293.062406)
		(mid 109.165661 -293.527584)
		(end 109.409992 -293.991538)
		(width 0.1143)
		(layer "In6.Cu")
		(net "P5E_CPU1_P0_TX_DP<13>")
	)
	(arc
		(start 109.408976 -289.82162)
		(mid 109.165649 -290.286186)
		(end 109.408976 -290.750752)
		(width 0.1143)
		(layer "In6.Cu")
		(net "P5E_CPU1_P0_TX_DP<13>")
	)
	(arc
		(start 77.460856 -375.231914)
		(mid 76.964059 -375.133095)
		(end 76.5429 -374.851676)
		(width 0.14224)
		(layer "In6.Cu")
		(net "P5E_CPU1_P0_TX_DP<13>")
	)
	(arc
		(start 69.860668 -370.103908)
		(mid 69.784689 -370.136713)
		(end 69.70268 -370.14785)
		(width 0.14224)
		(layer "In6.Cu")
		(net "P5E_CPU1_P0_TX_DP<13>")
	)
	(arc
		(start 109.681264 -366.058196)
		(mid 109.61548 -366.110834)
		(end 109.553756 -366.168178)
		(width 0.14224)
		(layer "In6.Cu")
		(net "P5E_CPU1_P0_TX_DP<13>")
	)
	(arc
		(start 109.635798 -287.856422)
		(mid 109.595036 -288.026306)
		(end 109.48162 -288.15919)
		(width 0.1143)
		(layer "In6.Cu")
		(net "P5E_CPU1_P0_TX_DP<13>")
	)
	(arc
		(start 125.978412 -353.08032)
		(mid 125.177451 -354.416801)
		(end 124.02312 -355.463348)
		(width 0.14224)
		(layer "In6.Cu")
		(net "P5E_CPU1_P0_TX_DP<13>")
	)
	(arc
		(start 109.408976 -288.201608)
		(mid 109.165649 -288.666174)
		(end 109.408976 -289.13074)
		(width 0.1143)
		(layer "In6.Cu")
		(net "P5E_CPU1_P0_TX_DP<13>")
	)
	(arc
		(start 109.479842 -290.7919)
		(mid 109.630227 -291.096192)
		(end 109.479842 -291.400484)
		(width 0.1143)
		(layer "In6.Cu")
		(net "P5E_CPU1_P0_TX_DP<13>")
	)
	(arc
		(start 109.499654 -289.186112)
		(mid 109.648368 -289.47618)
		(end 109.499654 -289.766248)
		(width 0.1143)
		(layer "In6.Cu")
		(net "P5E_CPU1_P0_TX_DP<13>")
	)
	(arc
		(start 123.513596 -355.803962)
		(mid 123.453263 -355.845265)
		(end 123.393962 -355.888036)
		(width 0.14224)
		(layer "In6.Cu")
		(net "P5E_CPU1_P0_TX_DP<13>")
	)
	(arc
		(start 109.119924 -298.382944)
		(mid 109.12784 -298.462838)
		(end 109.151166 -298.539662)
		(width 0.14224)
		(layer "In6.Cu")
		(net "P5E_CPU1_P0_TX_DP<13>")
	)
	(arc
		(start 109.17555 -285.532068)
		(mid 109.256983 -285.734466)
		(end 109.408976 -285.89097)
		(width 0.1143)
		(layer "In6.Cu")
		(net "P5E_CPU1_P0_TX_DP<13>")
	)
	(arc
		(start 103.523034 -374.513094)
		(mid 102.724248 -375.04509)
		(end 101.78288 -375.231914)
		(width 0.14224)
		(layer "In6.Cu")
		(net "P5E_CPU1_P0_TX_DP<13>")
	)
	(arc
		(start 69.16166 -370.047266)
		(mid 69.127087 -369.995524)
		(end 69.114924 -369.93449)
		(width 0.14224)
		(layer "In6.Cu")
		(net "P5E_CPU1_P0_TX_DP<13>")
	)
	(arc
		(start 109.409738 -294.681148)
		(mid 109.230545 -294.883658)
		(end 109.165898 -295.146222)
		(width 0.1143)
		(layer "In6.Cu")
		(net "P5E_CPU1_P0_TX_DP<13>")
	)
	(arc
		(start 129.546096 -341.919814)
		(mid 129.554491 -341.982557)
		(end 129.557272 -342.045798)
		(width 0.14224)
		(layer "In6.Cu")
		(net "P5E_CPU1_P0_TX_DP<13>")
	)
	(arc
		(start 70.342252 -369.969288)
		(mid 70.092243 -370.003617)
		(end 69.860668 -370.103908)
		(width 0.14224)
		(layer "In6.Cu")
		(net "P5E_CPU1_P0_TX_DP<13>")
	)
	(arc
		(start 105.664508 -370.057426)
		(mid 105.586666 -370.15421)
		(end 105.531412 -370.265452)
		(width 0.14224)
		(layer "In6.Cu")
		(net "P5E_CPU1_P0_TX_DP<13>")
	)
	(arc
		(start 109.40669 -286.58312)
		(mid 109.165601 -287.049086)
		(end 109.411516 -287.512506)
		(width 0.1143)
		(layer "In6.Cu")
		(net "P5E_CPU1_P0_TX_DP<13>")
	)
	(arc
		(start 109.499654 -292.426136)
		(mid 109.648368 -292.716204)
		(end 109.499654 -293.006272)
		(width 0.1143)
		(layer "In6.Cu")
		(net "P5E_CPU1_P0_TX_DP<13>")
	)
	(segment
		(start 65.409064 -369.30584)
		(end 65.138554 -369.03533)
		(width 0.12954)
		(layer "F.Cu")
		(net "P5E_CPU1_P0_TX_DP<12>")
	)
	(segment
		(start 106.907838 -282.730448)
		(end 106.440986 -282.996386)
		(width 0.12954)
		(layer "F.Cu")
		(net "P5E_CPU1_P0_TX_DP<12>")
	)
	(segment
		(start 65.113154 -370.30533)
		(end 65.409064 -370.00942)
		(width 0.12954)
		(layer "F.Cu")
		(net "P5E_CPU1_P0_TX_DP<12>")
	)
	(segment
		(start 65.409064 -370.00942)
		(end 65.409064 -369.30584)
		(width 0.12954)
		(layer "F.Cu")
		(net "P5E_CPU1_P0_TX_DP<12>")
	)
	(segment
		(start 83.48472 -370.069872)
		(end 82.056986 -370.069872)
		(width 0.14224)
		(layer "In6.Cu")
		(net "P5E_CPU1_P0_TX_DP<12>")
	)
	(segment
		(start 95.396812 -370.177822)
		(end 93.978222 -370.177822)
		(width 0.14224)
		(layer "In6.Cu")
		(net "P5E_CPU1_P0_TX_DP<12>")
	)
	(segment
		(start 76.657454 -370.069364)
		(end 75.75677 -370.069364)
		(width 0.14224)
		(layer "In6.Cu")
		(net "P5E_CPU1_P0_TX_DP<12>")
	)
	(segment
		(start 108.504482 -291.420804)
		(end 108.503212 -291.421566)
		(width 0.1143)
		(layer "In6.Cu")
		(net "P5E_CPU1_P0_TX_DP<12>")
	)
	(segment
		(start 65.429384 -368.247422)
		(end 65.429384 -368.7445)
		(width 0.14224)
		(layer "In6.Cu")
		(net "P5E_CPU1_P0_TX_DP<12>")
	)
	(segment
		(start 90.70594 -370.238782)
		(end 90.329258 -370.082826)
		(width 0.14224)
		(layer "In6.Cu")
		(net "P5E_CPU1_P0_TX_DP<12>")
	)
	(segment
		(start 108.47578 -292.374828)
		(end 108.476542 -292.375336)
		(width 0.1143)
		(layer "In6.Cu")
		(net "P5E_CPU1_P0_TX_DP<12>")
	)
	(segment
		(start 108.476542 -285.895542)
		(end 108.508038 -285.91383)
		(width 0.1143)
		(layer "In6.Cu")
		(net "P5E_CPU1_P0_TX_DP<12>")
	)
	(segment
		(start 108.5088 -285.914338)
		(end 108.511594 -285.915862)
		(width 0.1143)
		(layer "In6.Cu")
		(net "P5E_CPU1_P0_TX_DP<12>")
	)
	(segment
		(start 108.17987 -295.53662)
		(end 108.17987 -295.565068)
		(width 0.1143)
		(layer "In6.Cu")
		(net "P5E_CPU1_P0_TX_DP<12>")
	)
	(segment
		(start 108.51388 -289.156902)
		(end 108.514642 -289.15741)
		(width 0.1143)
		(layer "In6.Cu")
		(net "P5E_CPU1_P0_TX_DP<12>")
	)
	(segment
		(start 108.518452 -294.019478)
		(end 108.539788 -294.031924)
		(width 0.1143)
		(layer "In6.Cu")
		(net "P5E_CPU1_P0_TX_DP<12>")
	)
	(segment
		(start 108.505498 -291.420296)
		(end 108.504482 -291.420804)
		(width 0.1143)
		(layer "In6.Cu")
		(net "P5E_CPU1_P0_TX_DP<12>")
	)
	(segment
		(start 108.51388 -292.396926)
		(end 108.514642 -292.397434)
		(width 0.1143)
		(layer "In6.Cu")
		(net "P5E_CPU1_P0_TX_DP<12>")
	)
	(segment
		(start 102.296214 -370.140738)
		(end 102.230174 -370.16817)
		(width 0.14224)
		(layer "In6.Cu")
		(net "P5E_CPU1_P0_TX_DP<12>")
	)
	(segment
		(start 108.512356 -294.016176)
		(end 108.51388 -294.016938)
		(width 0.1143)
		(layer "In6.Cu")
		(net "P5E_CPU1_P0_TX_DP<12>")
	)
	(segment
		(start 108.514642 -294.017446)
		(end 108.515912 -294.018208)
		(width 0.1143)
		(layer "In6.Cu")
		(net "P5E_CPU1_P0_TX_DP<12>")
	)
	(segment
		(start 108.508038 -285.91383)
		(end 108.5088 -285.914338)
		(width 0.1143)
		(layer "In6.Cu")
		(net "P5E_CPU1_P0_TX_DP<12>")
	)
	(segment
		(start 108.468922 -285.89097)
		(end 108.47578 -285.895034)
		(width 0.1143)
		(layer "In6.Cu")
		(net "P5E_CPU1_P0_TX_DP<12>")
	)
	(segment
		(start 88.827102 -370.082826)
		(end 88.52154 -370.209318)
		(width 0.14224)
		(layer "In6.Cu")
		(net "P5E_CPU1_P0_TX_DP<12>")
	)
	(segment
		(start 108.508038 -290.773612)
		(end 108.5088 -290.77412)
		(width 0.1143)
		(layer "In6.Cu")
		(net "P5E_CPU1_P0_TX_DP<12>")
	)
	(segment
		(start 108.512356 -285.91637)
		(end 108.51388 -285.917132)
		(width 0.1143)
		(layer "In6.Cu")
		(net "P5E_CPU1_P0_TX_DP<12>")
	)
	(segment
		(start 108.515912 -290.778184)
		(end 108.518452 -290.779454)
		(width 0.1143)
		(layer "In6.Cu")
		(net "P5E_CPU1_P0_TX_DP<12>")
	)
	(segment
		(start 65.726564 -367.739168)
		(end 65.578482 -367.887504)
		(width 0.14224)
		(layer "In6.Cu")
		(net "P5E_CPU1_P0_TX_DP<12>")
	)
	(segment
		(start 107.058968 -283.461206)
		(end 107.121198 -283.497274)
		(width 0.1143)
		(layer "In6.Cu")
		(net "P5E_CPU1_P0_TX_DP<12>")
	)
	(segment
		(start 108.503212 -291.421566)
		(end 108.502196 -291.422074)
		(width 0.1143)
		(layer "In6.Cu")
		(net "P5E_CPU1_P0_TX_DP<12>")
	)
	(segment
		(start 108.503212 -293.041578)
		(end 108.502196 -293.042086)
		(width 0.1143)
		(layer "In6.Cu")
		(net "P5E_CPU1_P0_TX_DP<12>")
	)
	(segment
		(start 100.763324 -370.16817)
		(end 100.596192 -370.099082)
		(width 0.14224)
		(layer "In6.Cu")
		(net "P5E_CPU1_P0_TX_DP<12>")
	)
	(segment
		(start 88.52154 -370.209318)
		(end 87.230966 -370.209318)
		(width 0.14224)
		(layer "In6.Cu")
		(net "P5E_CPU1_P0_TX_DP<12>")
	)
	(segment
		(start 108.262166 -298.832778)
		(end 110.652814 -304.605436)
		(width 0.14224)
		(layer "In6.Cu")
		(net "P5E_CPU1_P0_TX_DP<12>")
	)
	(segment
		(start 108.511594 -290.775644)
		(end 108.512356 -290.776152)
		(width 0.1143)
		(layer "In6.Cu")
		(net "P5E_CPU1_P0_TX_DP<12>")
	)
	(segment
		(start 108.5088 -290.77412)
		(end 108.511594 -290.775644)
		(width 0.1143)
		(layer "In6.Cu")
		(net "P5E_CPU1_P0_TX_DP<12>")
	)
	(segment
		(start 108.5088 -289.798252)
		(end 108.508038 -289.79876)
		(width 0.1143)
		(layer "In6.Cu")
		(net "P5E_CPU1_P0_TX_DP<12>")
	)
	(segment
		(start 108.47578 -289.134804)
		(end 108.476542 -289.135312)
		(width 0.1143)
		(layer "In6.Cu")
		(net "P5E_CPU1_P0_TX_DP<12>")
	)
	(segment
		(start 108.515912 -294.018208)
		(end 108.518452 -294.019478)
		(width 0.1143)
		(layer "In6.Cu")
		(net "P5E_CPU1_P0_TX_DP<12>")
	)
	(segment
		(start 103.074724 -370.094764)
		(end 102.5271 -370.094764)
		(width 0.14224)
		(layer "In6.Cu")
		(net "P5E_CPU1_P0_TX_DP<12>")
	)
	(segment
		(start 108.507022 -293.039292)
		(end 108.505498 -293.040308)
		(width 0.1143)
		(layer "In6.Cu")
		(net "P5E_CPU1_P0_TX_DP<12>")
	)
	(segment
		(start 126.030482 -327.782682)
		(end 126.052834 -327.848214)
		(width 0.14224)
		(layer "In6.Cu")
		(net "P5E_CPU1_P0_TX_DP<12>")
	)
	(segment
		(start 102.230174 -370.16817)
		(end 100.763324 -370.16817)
		(width 0.14224)
		(layer "In6.Cu")
		(net "P5E_CPU1_P0_TX_DP<12>")
	)
	(segment
		(start 108.502196 -291.422074)
		(end 108.468922 -291.441632)
		(width 0.1143)
		(layer "In6.Cu")
		(net "P5E_CPU1_P0_TX_DP<12>")
	)
	(segment
		(start 80.127348 -370.07419)
		(end 78.689962 -370.07419)
		(width 0.14224)
		(layer "In6.Cu")
		(net "P5E_CPU1_P0_TX_DP<12>")
	)
	(segment
		(start 108.514642 -285.91764)
		(end 108.515912 -285.918402)
		(width 0.1143)
		(layer "In6.Cu")
		(net "P5E_CPU1_P0_TX_DP<12>")
	)
	(segment
		(start 108.5088 -293.038276)
		(end 108.508038 -293.038784)
		(width 0.1143)
		(layer "In6.Cu")
		(net "P5E_CPU1_P0_TX_DP<12>")
	)
	(segment
		(start 111.030766 -305.312318)
		(end 115.24615 -311.620408)
		(width 0.14224)
		(layer "In6.Cu")
		(net "P5E_CPU1_P0_TX_DP<12>")
	)
	(segment
		(start 121.719086 -319.522602)
		(end 126.005336 -327.724516)
		(width 0.14224)
		(layer "In6.Cu")
		(net "P5E_CPU1_P0_TX_DP<12>")
	)
	(segment
		(start 108.468922 -293.990776)
		(end 108.47578 -293.99484)
		(width 0.1143)
		(layer "In6.Cu")
		(net "P5E_CPU1_P0_TX_DP<12>")
	)
	(segment
		(start 108.468922 -289.13074)
		(end 108.47578 -289.134804)
		(width 0.1143)
		(layer "In6.Cu")
		(net "P5E_CPU1_P0_TX_DP<12>")
	)
	(segment
		(start 108.505498 -293.040308)
		(end 108.504482 -293.040816)
		(width 0.1143)
		(layer "In6.Cu")
		(net "P5E_CPU1_P0_TX_DP<12>")
	)
	(segment
		(start 108.50118 -294.66286)
		(end 108.469684 -294.681148)
		(width 0.1143)
		(layer "In6.Cu")
		(net "P5E_CPU1_P0_TX_DP<12>")
	)
	(segment
		(start 66.079116 -367.593626)
		(end 65.726564 -367.739168)
		(width 0.14224)
		(layer "In6.Cu")
		(net "P5E_CPU1_P0_TX_DP<12>")
	)
	(segment
		(start 108.51388 -290.776914)
		(end 108.514642 -290.777422)
		(width 0.1143)
		(layer "In6.Cu")
		(net "P5E_CPU1_P0_TX_DP<12>")
	)
	(segment
		(start 108.511594 -289.155632)
		(end 108.512356 -289.15614)
		(width 0.1143)
		(layer "In6.Cu")
		(net "P5E_CPU1_P0_TX_DP<12>")
	)
	(segment
		(start 108.47578 -290.754816)
		(end 108.476542 -290.755324)
		(width 0.1143)
		(layer "In6.Cu")
		(net "P5E_CPU1_P0_TX_DP<12>")
	)
	(segment
		(start 98.737674 -370.18976)
		(end 97.398586 -370.18976)
		(width 0.14224)
		(layer "In6.Cu")
		(net "P5E_CPU1_P0_TX_DP<12>")
	)
	(segment
		(start 107.567984 -284.293818)
		(end 107.599734 -284.312106)
		(width 0.1143)
		(layer "In6.Cu")
		(net "P5E_CPU1_P0_TX_DP<12>")
	)
	(segment
		(start 108.47578 -285.895034)
		(end 108.476542 -285.895542)
		(width 0.1143)
		(layer "In6.Cu")
		(net "P5E_CPU1_P0_TX_DP<12>")
	)
	(segment
		(start 65.429384 -368.7445)
		(end 65.138554 -369.03533)
		(width 0.14224)
		(layer "In6.Cu")
		(net "P5E_CPU1_P0_TX_DP<12>")
	)
	(segment
		(start 108.505498 -294.66032)
		(end 108.504482 -294.660828)
		(width 0.1143)
		(layer "In6.Cu")
		(net "P5E_CPU1_P0_TX_DP<12>")
	)
	(segment
		(start 108.22559 -295.4909)
		(end 108.17987 -295.53662)
		(width 0.1143)
		(layer "In6.Cu")
		(net "P5E_CPU1_P0_TX_DP<12>")
	)
	(segment
		(start 85.39861 -370.078508)
		(end 85.138514 -370.186204)
		(width 0.14224)
		(layer "In6.Cu")
		(net "P5E_CPU1_P0_TX_DP<12>")
	)
	(segment
		(start 78.305914 -370.233194)
		(end 77.053186 -370.233194)
		(width 0.14224)
		(layer "In6.Cu")
		(net "P5E_CPU1_P0_TX_DP<12>")
	)
	(segment
		(start 115.24615 -311.620408)
		(end 121.669048 -319.447164)
		(width 0.14224)
		(layer "In6.Cu")
		(net "P5E_CPU1_P0_TX_DP<12>")
	)
	(segment
		(start 108.51388 -294.016938)
		(end 108.514642 -294.017446)
		(width 0.1143)
		(layer "In6.Cu")
		(net "P5E_CPU1_P0_TX_DP<12>")
	)
	(segment
		(start 108.5088 -294.014144)
		(end 108.511594 -294.015668)
		(width 0.1143)
		(layer "In6.Cu")
		(net "P5E_CPU1_P0_TX_DP<12>")
	)
	(segment
		(start 108.511594 -285.915862)
		(end 108.512356 -285.91637)
		(width 0.1143)
		(layer "In6.Cu")
		(net "P5E_CPU1_P0_TX_DP<12>")
	)
	(segment
		(start 108.50372 -294.661336)
		(end 108.501942 -294.662352)
		(width 0.1143)
		(layer "In6.Cu")
		(net "P5E_CPU1_P0_TX_DP<12>")
	)
	(segment
		(start 108.511594 -292.395656)
		(end 108.512356 -292.396164)
		(width 0.1143)
		(layer "In6.Cu")
		(net "P5E_CPU1_P0_TX_DP<12>")
	)
	(segment
		(start 108.17987 -295.565068)
		(end 108.17987 -298.419012)
		(width 0.14224)
		(layer "In6.Cu")
		(net "P5E_CPU1_P0_TX_DP<12>")
	)
	(segment
		(start 78.689962 -370.07419)
		(end 78.305914 -370.233194)
		(width 0.14224)
		(layer "In6.Cu")
		(net "P5E_CPU1_P0_TX_DP<12>")
	)
	(segment
		(start 93.738446 -370.078508)
		(end 92.268294 -370.078508)
		(width 0.14224)
		(layer "In6.Cu")
		(net "P5E_CPU1_P0_TX_DP<12>")
	)
	(segment
		(start 108.539788 -293.020496)
		(end 108.5088 -293.038276)
		(width 0.1143)
		(layer "In6.Cu")
		(net "P5E_CPU1_P0_TX_DP<12>")
	)
	(segment
		(start 86.91499 -370.078508)
		(end 85.39861 -370.078508)
		(width 0.14224)
		(layer "In6.Cu")
		(net "P5E_CPU1_P0_TX_DP<12>")
	)
	(segment
		(start 108.515912 -292.398196)
		(end 108.518452 -292.399466)
		(width 0.1143)
		(layer "In6.Cu")
		(net "P5E_CPU1_P0_TX_DP<12>")
	)
	(segment
		(start 85.138514 -370.186204)
		(end 83.765644 -370.186204)
		(width 0.14224)
		(layer "In6.Cu")
		(net "P5E_CPU1_P0_TX_DP<12>")
	)
	(segment
		(start 98.956622 -370.099082)
		(end 98.737674 -370.18976)
		(width 0.14224)
		(layer "In6.Cu")
		(net "P5E_CPU1_P0_TX_DP<12>")
	)
	(segment
		(start 97.137728 -370.08181)
		(end 95.628714 -370.08181)
		(width 0.14224)
		(layer "In6.Cu")
		(net "P5E_CPU1_P0_TX_DP<12>")
	)
	(segment
		(start 90.329258 -370.082826)
		(end 88.827102 -370.082826)
		(width 0.14224)
		(layer "In6.Cu")
		(net "P5E_CPU1_P0_TX_DP<12>")
	)
	(segment
		(start 108.508038 -292.393624)
		(end 108.5088 -292.394132)
		(width 0.1143)
		(layer "In6.Cu")
		(net "P5E_CPU1_P0_TX_DP<12>")
	)
	(segment
		(start 108.539788 -291.400484)
		(end 108.5088 -291.418264)
		(width 0.1143)
		(layer "In6.Cu")
		(net "P5E_CPU1_P0_TX_DP<12>")
	)
	(segment
		(start 92.268294 -370.078508)
		(end 91.881198 -370.238782)
		(width 0.14224)
		(layer "In6.Cu")
		(net "P5E_CPU1_P0_TX_DP<12>")
	)
	(segment
		(start 106.440986 -282.996386)
		(end 106.738928 -282.996386)
		(width 0.1143)
		(layer "In6.Cu")
		(net "P5E_CPU1_P0_TX_DP<12>")
	)
	(segment
		(start 100.596192 -370.099082)
		(end 98.956622 -370.099082)
		(width 0.14224)
		(layer "In6.Cu")
		(net "P5E_CPU1_P0_TX_DP<12>")
	)
	(segment
		(start 108.508038 -291.418772)
		(end 108.507022 -291.41928)
		(width 0.1143)
		(layer "In6.Cu")
		(net "P5E_CPU1_P0_TX_DP<12>")
	)
	(segment
		(start 108.476542 -290.755324)
		(end 108.508038 -290.773612)
		(width 0.1143)
		(layer "In6.Cu")
		(net "P5E_CPU1_P0_TX_DP<12>")
	)
	(segment
		(start 108.507022 -289.799268)
		(end 108.505498 -289.800284)
		(width 0.1143)
		(layer "In6.Cu")
		(net "P5E_CPU1_P0_TX_DP<12>")
	)
	(segment
		(start 107.999022 -285.080964)
		(end 108.068618 -285.121604)
		(width 0.1143)
		(layer "In6.Cu")
		(net "P5E_CPU1_P0_TX_DP<12>")
	)
	(segment
		(start 106.738928 -282.996386)
		(end 106.821732 -283.07919)
		(width 0.1143)
		(layer "In6.Cu")
		(net "P5E_CPU1_P0_TX_DP<12>")
	)
	(segment
		(start 108.22559 -295.146984)
		(end 108.22559 -295.4909)
		(width 0.1143)
		(layer "In6.Cu")
		(net "P5E_CPU1_P0_TX_DP<12>")
	)
	(segment
		(start 108.504482 -293.040816)
		(end 108.503212 -293.041578)
		(width 0.1143)
		(layer "In6.Cu")
		(net "P5E_CPU1_P0_TX_DP<12>")
	)
	(segment
		(start 108.476542 -289.135312)
		(end 108.508038 -289.1536)
		(width 0.1143)
		(layer "In6.Cu")
		(net "P5E_CPU1_P0_TX_DP<12>")
	)
	(segment
		(start 83.765644 -370.186204)
		(end 83.48472 -370.069872)
		(width 0.14224)
		(layer "In6.Cu")
		(net "P5E_CPU1_P0_TX_DP<12>")
	)
	(segment
		(start 124.362464 -353.871784)
		(end 124.077984 -354.202238)
		(width 0.14224)
		(layer "In6.Cu")
		(net "P5E_CPU1_P0_TX_DP<12>")
	)
	(segment
		(start 108.502196 -293.042086)
		(end 108.468922 -293.061644)
		(width 0.1143)
		(layer "In6.Cu")
		(net "P5E_CPU1_P0_TX_DP<12>")
	)
	(segment
		(start 108.514642 -292.397434)
		(end 108.515912 -292.398196)
		(width 0.1143)
		(layer "In6.Cu")
		(net "P5E_CPU1_P0_TX_DP<12>")
	)
	(segment
		(start 108.507022 -291.41928)
		(end 108.505498 -291.420296)
		(width 0.1143)
		(layer "In6.Cu")
		(net "P5E_CPU1_P0_TX_DP<12>")
	)
	(segment
		(start 108.504482 -294.660828)
		(end 108.50372 -294.661336)
		(width 0.1143)
		(layer "In6.Cu")
		(net "P5E_CPU1_P0_TX_DP<12>")
	)
	(segment
		(start 82.056986 -370.069872)
		(end 81.764886 -370.190776)
		(width 0.14224)
		(layer "In6.Cu")
		(net "P5E_CPU1_P0_TX_DP<12>")
	)
	(segment
		(start 109.39653 -364.097062)
		(end 103.731568 -369.762024)
		(width 0.14224)
		(layer "In6.Cu")
		(net "P5E_CPU1_P0_TX_DP<12>")
	)
	(segment
		(start 108.468922 -292.370764)
		(end 108.47578 -292.374828)
		(width 0.1143)
		(layer "In6.Cu")
		(net "P5E_CPU1_P0_TX_DP<12>")
	)
	(segment
		(start 108.508038 -287.533842)
		(end 108.539788 -287.55213)
		(width 0.1143)
		(layer "In6.Cu")
		(net "P5E_CPU1_P0_TX_DP<12>")
	)
	(segment
		(start 108.518452 -290.779454)
		(end 108.539788 -290.7919)
		(width 0.1143)
		(layer "In6.Cu")
		(net "P5E_CPU1_P0_TX_DP<12>")
	)
	(segment
		(start 108.504482 -289.800792)
		(end 108.503212 -289.801554)
		(width 0.1143)
		(layer "In6.Cu")
		(net "P5E_CPU1_P0_TX_DP<12>")
	)
	(segment
		(start 108.512356 -289.15614)
		(end 108.51388 -289.156902)
		(width 0.1143)
		(layer "In6.Cu")
		(net "P5E_CPU1_P0_TX_DP<12>")
	)
	(segment
		(start 93.978222 -370.177822)
		(end 93.738446 -370.078508)
		(width 0.14224)
		(layer "In6.Cu")
		(net "P5E_CPU1_P0_TX_DP<12>")
	)
	(segment
		(start 97.398586 -370.18976)
		(end 97.137728 -370.08181)
		(width 0.14224)
		(layer "In6.Cu")
		(net "P5E_CPU1_P0_TX_DP<12>")
	)
	(segment
		(start 108.508038 -293.038784)
		(end 108.507022 -293.039292)
		(width 0.1143)
		(layer "In6.Cu")
		(net "P5E_CPU1_P0_TX_DP<12>")
	)
	(segment
		(start 108.505498 -289.800284)
		(end 108.504482 -289.800792)
		(width 0.1143)
		(layer "In6.Cu")
		(net "P5E_CPU1_P0_TX_DP<12>")
	)
	(segment
		(start 108.468922 -290.750752)
		(end 108.47578 -290.754816)
		(width 0.1143)
		(layer "In6.Cu")
		(net "P5E_CPU1_P0_TX_DP<12>")
	)
	(segment
		(start 108.508038 -289.1536)
		(end 108.5088 -289.154108)
		(width 0.1143)
		(layer "In6.Cu")
		(net "P5E_CPU1_P0_TX_DP<12>")
	)
	(segment
		(start 91.881198 -370.238782)
		(end 90.70594 -370.238782)
		(width 0.14224)
		(layer "In6.Cu")
		(net "P5E_CPU1_P0_TX_DP<12>")
	)
	(segment
		(start 123.688348 -354.54717)
		(end 109.39653 -364.097062)
		(width 0.14224)
		(layer "In6.Cu")
		(net "P5E_CPU1_P0_TX_DP<12>")
	)
	(segment
		(start 108.508038 -289.79876)
		(end 108.507022 -289.799268)
		(width 0.1143)
		(layer "In6.Cu")
		(net "P5E_CPU1_P0_TX_DP<12>")
	)
	(segment
		(start 128.519428 -341.630508)
		(end 128.519428 -341.630254)
		(width 0.14224)
		(layer "In6.Cu")
		(net "P5E_CPU1_P0_TX_DP<12>")
	)
	(segment
		(start 108.47578 -293.99484)
		(end 108.476542 -293.995348)
		(width 0.1143)
		(layer "In6.Cu")
		(net "P5E_CPU1_P0_TX_DP<12>")
	)
	(segment
		(start 108.514642 -290.777422)
		(end 108.515912 -290.778184)
		(width 0.1143)
		(layer "In6.Cu")
		(net "P5E_CPU1_P0_TX_DP<12>")
	)
	(segment
		(start 108.512356 -290.776152)
		(end 108.51388 -290.776914)
		(width 0.1143)
		(layer "In6.Cu")
		(net "P5E_CPU1_P0_TX_DP<12>")
	)
	(segment
		(start 108.471462 -287.512506)
		(end 108.508038 -287.533842)
		(width 0.1143)
		(layer "In6.Cu")
		(net "P5E_CPU1_P0_TX_DP<12>")
	)
	(segment
		(start 69.333872 -367.593626)
		(end 66.079116 -367.593626)
		(width 0.14224)
		(layer "In6.Cu")
		(net "P5E_CPU1_P0_TX_DP<12>")
	)
	(segment
		(start 81.764886 -370.190776)
		(end 80.409288 -370.190776)
		(width 0.14224)
		(layer "In6.Cu")
		(net "P5E_CPU1_P0_TX_DP<12>")
	)
	(segment
		(start 77.053186 -370.233194)
		(end 76.657454 -370.069364)
		(width 0.14224)
		(layer "In6.Cu")
		(net "P5E_CPU1_P0_TX_DP<12>")
	)
	(segment
		(start 87.230966 -370.209318)
		(end 86.91499 -370.078508)
		(width 0.14224)
		(layer "In6.Cu")
		(net "P5E_CPU1_P0_TX_DP<12>")
	)
	(segment
		(start 108.507022 -294.659304)
		(end 108.505498 -294.66032)
		(width 0.1143)
		(layer "In6.Cu")
		(net "P5E_CPU1_P0_TX_DP<12>")
	)
	(segment
		(start 108.5088 -291.418264)
		(end 108.508038 -291.418772)
		(width 0.1143)
		(layer "In6.Cu")
		(net "P5E_CPU1_P0_TX_DP<12>")
	)
	(segment
		(start 108.515912 -285.918402)
		(end 108.518452 -285.919672)
		(width 0.1143)
		(layer "In6.Cu")
		(net "P5E_CPU1_P0_TX_DP<12>")
	)
	(segment
		(start 108.518452 -289.159442)
		(end 108.539788 -289.171888)
		(width 0.1143)
		(layer "In6.Cu")
		(net "P5E_CPU1_P0_TX_DP<12>")
	)
	(segment
		(start 126.07925 -327.946766)
		(end 128.510538 -341.4776)
		(width 0.14224)
		(layer "In6.Cu")
		(net "P5E_CPU1_P0_TX_DP<12>")
	)
	(segment
		(start 107.531662 -284.272736)
		(end 107.567984 -284.293818)
		(width 0.1143)
		(layer "In6.Cu")
		(net "P5E_CPU1_P0_TX_DP<12>")
	)
	(segment
		(start 80.409288 -370.190776)
		(end 80.127348 -370.07419)
		(width 0.14224)
		(layer "In6.Cu")
		(net "P5E_CPU1_P0_TX_DP<12>")
	)
	(segment
		(start 108.541566 -288.15919)
		(end 108.468922 -288.201608)
		(width 0.1143)
		(layer "In6.Cu")
		(net "P5E_CPU1_P0_TX_DP<12>")
	)
	(segment
		(start 108.5088 -289.154108)
		(end 108.511594 -289.155632)
		(width 0.1143)
		(layer "In6.Cu")
		(net "P5E_CPU1_P0_TX_DP<12>")
	)
	(segment
		(start 108.503212 -289.801554)
		(end 108.502196 -289.802062)
		(width 0.1143)
		(layer "In6.Cu")
		(net "P5E_CPU1_P0_TX_DP<12>")
	)
	(segment
		(start 108.511594 -294.015668)
		(end 108.512356 -294.016176)
		(width 0.1143)
		(layer "In6.Cu")
		(net "P5E_CPU1_P0_TX_DP<12>")
	)
	(segment
		(start 108.5088 -292.394132)
		(end 108.511594 -292.395656)
		(width 0.1143)
		(layer "In6.Cu")
		(net "P5E_CPU1_P0_TX_DP<12>")
	)
	(segment
		(start 108.508038 -294.658796)
		(end 108.507022 -294.659304)
		(width 0.1143)
		(layer "In6.Cu")
		(net "P5E_CPU1_P0_TX_DP<12>")
	)
	(segment
		(start 75.75677 -370.069364)
		(end 70.191376 -367.76406)
		(width 0.14224)
		(layer "In6.Cu")
		(net "P5E_CPU1_P0_TX_DP<12>")
	)
	(segment
		(start 108.508038 -294.013636)
		(end 108.5088 -294.014144)
		(width 0.1143)
		(layer "In6.Cu")
		(net "P5E_CPU1_P0_TX_DP<12>")
	)
	(segment
		(start 108.518452 -292.399466)
		(end 108.539788 -292.411912)
		(width 0.1143)
		(layer "In6.Cu")
		(net "P5E_CPU1_P0_TX_DP<12>")
	)
	(segment
		(start 108.476542 -293.995348)
		(end 108.508038 -294.013636)
		(width 0.1143)
		(layer "In6.Cu")
		(net "P5E_CPU1_P0_TX_DP<12>")
	)
	(segment
		(start 95.628714 -370.08181)
		(end 95.396812 -370.177822)
		(width 0.14224)
		(layer "In6.Cu")
		(net "P5E_CPU1_P0_TX_DP<12>")
	)
	(segment
		(start 127.658876 -345.928188)
		(end 124.383546 -353.837494)
		(width 0.14224)
		(layer "In6.Cu")
		(net "P5E_CPU1_P0_TX_DP<12>")
	)
	(segment
		(start 108.501942 -294.662352)
		(end 108.50118 -294.66286)
		(width 0.1143)
		(layer "In6.Cu")
		(net "P5E_CPU1_P0_TX_DP<12>")
	)
	(segment
		(start 108.514642 -289.15741)
		(end 108.515912 -289.158172)
		(width 0.1143)
		(layer "In6.Cu")
		(net "P5E_CPU1_P0_TX_DP<12>")
	)
	(segment
		(start 108.476542 -292.375336)
		(end 108.508038 -292.393624)
		(width 0.1143)
		(layer "In6.Cu")
		(net "P5E_CPU1_P0_TX_DP<12>")
	)
	(segment
		(start 108.51388 -285.917132)
		(end 108.514642 -285.91764)
		(width 0.1143)
		(layer "In6.Cu")
		(net "P5E_CPU1_P0_TX_DP<12>")
	)
	(segment
		(start 108.539788 -289.780472)
		(end 108.5088 -289.798252)
		(width 0.1143)
		(layer "In6.Cu")
		(net "P5E_CPU1_P0_TX_DP<12>")
	)
	(segment
		(start 108.518452 -285.919672)
		(end 108.539788 -285.932118)
		(width 0.1143)
		(layer "In6.Cu")
		(net "P5E_CPU1_P0_TX_DP<12>")
	)
	(segment
		(start 108.512356 -292.396164)
		(end 108.51388 -292.396926)
		(width 0.1143)
		(layer "In6.Cu")
		(net "P5E_CPU1_P0_TX_DP<12>")
	)
	(segment
		(start 108.515912 -289.158172)
		(end 108.518452 -289.159442)
		(width 0.1143)
		(layer "In6.Cu")
		(net "P5E_CPU1_P0_TX_DP<12>")
	)
	(segment
		(start 108.502196 -289.802062)
		(end 108.468922 -289.82162)
		(width 0.1143)
		(layer "In6.Cu")
		(net "P5E_CPU1_P0_TX_DP<12>")
	)
	(segment
		(start 108.539788 -294.640508)
		(end 108.508038 -294.658796)
		(width 0.1143)
		(layer "In6.Cu")
		(net "P5E_CPU1_P0_TX_DP<12>")
	)
	(segment
		(start 110.652814 -304.605436)
		(end 111.030766 -305.312318)
		(width 0.14224)
		(layer "In6.Cu")
		(net "P5E_CPU1_P0_TX_DP<12>")
	)
	(segment
		(start 108.541566 -286.539178)
		(end 108.468922 -286.581596)
		(width 0.1143)
		(layer "In6.Cu")
		(net "P5E_CPU1_P0_TX_DP<12>")
	)
	(arc
		(start 102.5271 -370.094764)
		(mid 102.409394 -370.106389)
		(end 102.296214 -370.140738)
		(width 0.14224)
		(layer "In6.Cu")
		(net "P5E_CPU1_P0_TX_DP<12>")
	)
	(arc
		(start 108.22559 -285.426404)
		(mid 108.290105 -285.688623)
		(end 108.468922 -285.89097)
		(width 0.1143)
		(layer "In6.Cu")
		(net "P5E_CPU1_P0_TX_DP<12>")
	)
	(arc
		(start 65.578482 -367.887504)
		(mid 65.468144 -368.052636)
		(end 65.429384 -368.247422)
		(width 0.14224)
		(layer "In6.Cu")
		(net "P5E_CPU1_P0_TX_DP<12>")
	)
	(arc
		(start 124.383546 -353.837494)
		(mid 124.374388 -353.855491)
		(end 124.362464 -353.871784)
		(width 0.14224)
		(layer "In6.Cu")
		(net "P5E_CPU1_P0_TX_DP<12>")
	)
	(arc
		(start 108.468922 -286.581596)
		(mid 108.290109 -286.783946)
		(end 108.22559 -287.046162)
		(width 0.1143)
		(layer "In6.Cu")
		(net "P5E_CPU1_P0_TX_DP<12>")
	)
	(arc
		(start 108.468922 -293.061644)
		(mid 108.225595 -293.52621)
		(end 108.468922 -293.990776)
		(width 0.1143)
		(layer "In6.Cu")
		(net "P5E_CPU1_P0_TX_DP<12>")
	)
	(arc
		(start 108.539788 -287.55213)
		(mid 108.654464 -287.685464)
		(end 108.695744 -287.856422)
		(width 0.1143)
		(layer "In6.Cu")
		(net "P5E_CPU1_P0_TX_DP<12>")
	)
	(arc
		(start 108.468922 -288.201608)
		(mid 108.225595 -288.666174)
		(end 108.468922 -289.13074)
		(width 0.1143)
		(layer "In6.Cu")
		(net "P5E_CPU1_P0_TX_DP<12>")
	)
	(arc
		(start 106.82605 -283.101796)
		(mid 106.907177 -283.304392)
		(end 107.058968 -283.461206)
		(width 0.1143)
		(layer "In6.Cu")
		(net "P5E_CPU1_P0_TX_DP<12>")
	)
	(arc
		(start 107.121198 -283.497274)
		(mid 107.229398 -283.632676)
		(end 107.283758 -283.797248)
		(width 0.1143)
		(layer "In6.Cu")
		(net "P5E_CPU1_P0_TX_DP<12>")
	)
	(arc
		(start 126.052834 -327.848214)
		(mid 126.067726 -327.897039)
		(end 126.07925 -327.946766)
		(width 0.14224)
		(layer "In6.Cu")
		(net "P5E_CPU1_P0_TX_DP<12>")
	)
	(arc
		(start 70.191376 -367.76406)
		(mid 69.77102 -367.63659)
		(end 69.333872 -367.593626)
		(width 0.14224)
		(layer "In6.Cu")
		(net "P5E_CPU1_P0_TX_DP<12>")
	)
	(arc
		(start 108.539788 -289.171888)
		(mid 108.695716 -289.47618)
		(end 108.539788 -289.780472)
		(width 0.1143)
		(layer "In6.Cu")
		(net "P5E_CPU1_P0_TX_DP<12>")
	)
	(arc
		(start 107.520994 -284.26537)
		(mid 107.526308 -284.269082)
		(end 107.531662 -284.272736)
		(width 0.1143)
		(layer "In6.Cu")
		(net "P5E_CPU1_P0_TX_DP<12>")
	)
	(arc
		(start 106.821732 -283.07919)
		(mid 106.823777 -283.090515)
		(end 106.82605 -283.101796)
		(width 0.1143)
		(layer "In6.Cu")
		(net "P5E_CPU1_P0_TX_DP<12>")
	)
	(arc
		(start 108.695744 -286.23641)
		(mid 108.654982 -286.406294)
		(end 108.541566 -286.539178)
		(width 0.1143)
		(layer "In6.Cu")
		(net "P5E_CPU1_P0_TX_DP<12>")
	)
	(arc
		(start 126.005336 -327.724516)
		(mid 126.019001 -327.753126)
		(end 126.030482 -327.782682)
		(width 0.14224)
		(layer "In6.Cu")
		(net "P5E_CPU1_P0_TX_DP<12>")
	)
	(arc
		(start 107.75569 -284.616398)
		(mid 107.820205 -284.878617)
		(end 107.999022 -285.080964)
		(width 0.1143)
		(layer "In6.Cu")
		(net "P5E_CPU1_P0_TX_DP<12>")
	)
	(arc
		(start 107.28579 -283.821378)
		(mid 107.35141 -284.070896)
		(end 107.520994 -284.26537)
		(width 0.1143)
		(layer "In6.Cu")
		(net "P5E_CPU1_P0_TX_DP<12>")
	)
	(arc
		(start 108.695744 -287.856422)
		(mid 108.654982 -288.026306)
		(end 108.541566 -288.15919)
		(width 0.1143)
		(layer "In6.Cu")
		(net "P5E_CPU1_P0_TX_DP<12>")
	)
	(arc
		(start 103.731568 -369.762024)
		(mid 103.485756 -369.953027)
		(end 103.2002 -370.076984)
		(width 0.14224)
		(layer "In6.Cu")
		(net "P5E_CPU1_P0_TX_DP<12>")
	)
	(arc
		(start 128.519428 -341.630254)
		(mid 128.233541 -343.808132)
		(end 127.658876 -345.928188)
		(width 0.14224)
		(layer "In6.Cu")
		(net "P5E_CPU1_P0_TX_DP<12>")
	)
	(arc
		(start 121.669048 -319.447164)
		(mid 121.695994 -319.483604)
		(end 121.719086 -319.522602)
		(width 0.14224)
		(layer "In6.Cu")
		(net "P5E_CPU1_P0_TX_DP<12>")
	)
	(arc
		(start 103.2002 -370.076984)
		(mid 103.138096 -370.090355)
		(end 103.074724 -370.094764)
		(width 0.14224)
		(layer "In6.Cu")
		(net "P5E_CPU1_P0_TX_DP<12>")
	)
	(arc
		(start 107.283758 -283.797248)
		(mid 107.285067 -283.809288)
		(end 107.28579 -283.821378)
		(width 0.1143)
		(layer "In6.Cu")
		(net "P5E_CPU1_P0_TX_DP<12>")
	)
	(arc
		(start 108.539788 -290.7919)
		(mid 108.695716 -291.096192)
		(end 108.539788 -291.400484)
		(width 0.1143)
		(layer "In6.Cu")
		(net "P5E_CPU1_P0_TX_DP<12>")
	)
	(arc
		(start 108.468922 -291.441632)
		(mid 108.225595 -291.906198)
		(end 108.468922 -292.370764)
		(width 0.1143)
		(layer "In6.Cu")
		(net "P5E_CPU1_P0_TX_DP<12>")
	)
	(arc
		(start 108.469684 -294.681148)
		(mid 108.290207 -294.883982)
		(end 108.22559 -295.146984)
		(width 0.1143)
		(layer "In6.Cu")
		(net "P5E_CPU1_P0_TX_DP<12>")
	)
	(arc
		(start 107.599734 -284.312106)
		(mid 107.71441 -284.44544)
		(end 107.75569 -284.616398)
		(width 0.1143)
		(layer "In6.Cu")
		(net "P5E_CPU1_P0_TX_DP<12>")
	)
	(arc
		(start 108.468922 -289.82162)
		(mid 108.225595 -290.286186)
		(end 108.468922 -290.750752)
		(width 0.1143)
		(layer "In6.Cu")
		(net "P5E_CPU1_P0_TX_DP<12>")
	)
	(arc
		(start 108.539788 -294.031924)
		(mid 108.695716 -294.336216)
		(end 108.539788 -294.640508)
		(width 0.1143)
		(layer "In6.Cu")
		(net "P5E_CPU1_P0_TX_DP<12>")
	)
	(arc
		(start 108.539788 -292.411912)
		(mid 108.695716 -292.716204)
		(end 108.539788 -293.020496)
		(width 0.1143)
		(layer "In6.Cu")
		(net "P5E_CPU1_P0_TX_DP<12>")
	)
	(arc
		(start 108.22559 -287.046162)
		(mid 108.290826 -287.309753)
		(end 108.471462 -287.512506)
		(width 0.1143)
		(layer "In6.Cu")
		(net "P5E_CPU1_P0_TX_DP<12>")
	)
	(arc
		(start 108.17987 -298.419012)
		(mid 108.200644 -298.629947)
		(end 108.262166 -298.832778)
		(width 0.14224)
		(layer "In6.Cu")
		(net "P5E_CPU1_P0_TX_DP<12>")
	)
	(arc
		(start 128.510538 -341.4776)
		(mid 128.519587 -341.553786)
		(end 128.519428 -341.630508)
		(width 0.14224)
		(layer "In6.Cu")
		(net "P5E_CPU1_P0_TX_DP<12>")
	)
	(arc
		(start 124.077984 -354.202238)
		(mid 123.894875 -354.387932)
		(end 123.688348 -354.54717)
		(width 0.14224)
		(layer "In6.Cu")
		(net "P5E_CPU1_P0_TX_DP<12>")
	)
	(arc
		(start 108.539788 -285.932118)
		(mid 108.654464 -286.065452)
		(end 108.695744 -286.23641)
		(width 0.1143)
		(layer "In6.Cu")
		(net "P5E_CPU1_P0_TX_DP<12>")
	)
	(arc
		(start 108.068618 -285.121604)
		(mid 108.184045 -285.25498)
		(end 108.22559 -285.426404)
		(width 0.1143)
		(layer "In6.Cu")
		(net "P5E_CPU1_P0_TX_DP<12>")
	)
	(segment
		(start 106.907838 -285.970472)
		(end 106.440986 -286.23641)
		(width 0.12954)
		(layer "F.Cu")
		(net "P5E_CPU1_P0_TX_DP<11>")
	)
	(segment
		(start 63.707264 -371.76964)
		(end 63.707264 -372.47322)
		(width 0.12954)
		(layer "F.Cu")
		(net "P5E_CPU1_P0_TX_DP<11>")
	)
	(segment
		(start 63.436754 -371.49913)
		(end 63.707264 -371.76964)
		(width 0.12954)
		(layer "F.Cu")
		(net "P5E_CPU1_P0_TX_DP<11>")
	)
	(segment
		(start 63.707264 -372.47322)
		(end 63.411354 -372.76913)
		(width 0.12954)
		(layer "F.Cu")
		(net "P5E_CPU1_P0_TX_DP<11>")
	)
	(segment
		(start 107.57154 -290.775644)
		(end 107.572302 -290.776152)
		(width 0.1143)
		(layer "In6.Cu")
		(net "P5E_CPU1_P0_TX_DP<11>")
	)
	(segment
		(start 107.573318 -290.77666)
		(end 107.57408 -290.777168)
		(width 0.1143)
		(layer "In6.Cu")
		(net "P5E_CPU1_P0_TX_DP<11>")
	)
	(segment
		(start 107.059984 -296.538396)
		(end 107.014264 -296.584116)
		(width 0.1143)
		(layer "In6.Cu")
		(net "P5E_CPU1_P0_TX_DP<11>")
	)
	(segment
		(start 65.759076 -366.71504)
		(end 65.379092 -366.87252)
		(width 0.14224)
		(layer "In6.Cu")
		(net "P5E_CPU1_P0_TX_DP<11>")
	)
	(segment
		(start 125.070108 -328.004424)
		(end 125.243844 -328.762106)
		(width 0.14224)
		(layer "In6.Cu")
		(net "P5E_CPU1_P0_TX_DP<11>")
	)
	(segment
		(start 107.589828 -289.78606)
		(end 107.589066 -289.786568)
		(width 0.1143)
		(layer "In6.Cu")
		(net "P5E_CPU1_P0_TX_DP<11>")
	)
	(segment
		(start 107.567984 -289.79876)
		(end 107.56773 -289.799014)
		(width 0.1143)
		(layer "In6.Cu")
		(net "P5E_CPU1_P0_TX_DP<11>")
	)
	(segment
		(start 107.599734 -291.400484)
		(end 107.589828 -291.406072)
		(width 0.1143)
		(layer "In6.Cu")
		(net "P5E_CPU1_P0_TX_DP<11>")
	)
	(segment
		(start 107.074462 -298.427902)
		(end 109.75594 -304.90287)
		(width 0.14224)
		(layer "In6.Cu")
		(net "P5E_CPU1_P0_TX_DP<11>")
	)
	(segment
		(start 107.569762 -292.39464)
		(end 107.570524 -292.395148)
		(width 0.1143)
		(layer "In6.Cu")
		(net "P5E_CPU1_P0_TX_DP<11>")
	)
	(segment
		(start 107.56773 -290.773612)
		(end 107.567984 -290.773612)
		(width 0.1143)
		(layer "In6.Cu")
		(net "P5E_CPU1_P0_TX_DP<11>")
	)
	(segment
		(start 107.589066 -289.786568)
		(end 107.567984 -289.79876)
		(width 0.1143)
		(layer "In6.Cu")
		(net "P5E_CPU1_P0_TX_DP<11>")
	)
	(segment
		(start 106.738928 -286.23641)
		(end 106.763058 -286.26054)
		(width 0.1143)
		(layer "In6.Cu")
		(net "P5E_CPU1_P0_TX_DP<11>")
	)
	(segment
		(start 107.098084 -295.468802)
		(end 107.061762 -295.489884)
		(width 0.1143)
		(layer "In6.Cu")
		(net "P5E_CPU1_P0_TX_DP<11>")
	)
	(segment
		(start 107.064048 -286.703516)
		(end 107.130088 -286.742632)
		(width 0.1143)
		(layer "In6.Cu")
		(net "P5E_CPU1_P0_TX_DP<11>")
	)
	(segment
		(start 109.82198 -305.04257)
		(end 110.16361 -305.681634)
		(width 0.14224)
		(layer "In6.Cu")
		(net "P5E_CPU1_P0_TX_DP<11>")
	)
	(segment
		(start 107.567984 -293.038784)
		(end 107.531662 -293.059866)
		(width 0.1143)
		(layer "In6.Cu")
		(net "P5E_CPU1_P0_TX_DP<11>")
	)
	(segment
		(start 107.55503 -289.14598)
		(end 107.599734 -289.171888)
		(width 0.1143)
		(layer "In6.Cu")
		(net "P5E_CPU1_P0_TX_DP<11>")
	)
	(segment
		(start 107.589066 -291.40658)
		(end 107.567984 -291.418772)
		(width 0.1143)
		(layer "In6.Cu")
		(net "P5E_CPU1_P0_TX_DP<11>")
	)
	(segment
		(start 107.130088 -286.742632)
		(end 107.130596 -286.742886)
		(width 0.1143)
		(layer "In6.Cu")
		(net "P5E_CPU1_P0_TX_DP<11>")
	)
	(segment
		(start 107.57535 -290.77793)
		(end 107.599734 -290.7919)
		(width 0.1143)
		(layer "In6.Cu")
		(net "P5E_CPU1_P0_TX_DP<11>")
	)
	(segment
		(start 126.52883 -346.216478)
		(end 123.889008 -352.58883)
		(width 0.14224)
		(layer "In6.Cu")
		(net "P5E_CPU1_P0_TX_DP<11>")
	)
	(segment
		(start 102.11562 -367.498376)
		(end 72.275192 -367.498376)
		(width 0.14224)
		(layer "In6.Cu")
		(net "P5E_CPU1_P0_TX_DP<11>")
	)
	(segment
		(start 107.572302 -290.776152)
		(end 107.573318 -290.77666)
		(width 0.1143)
		(layer "In6.Cu")
		(net "P5E_CPU1_P0_TX_DP<11>")
	)
	(segment
		(start 107.014264 -296.612564)
		(end 107.014264 -298.125134)
		(width 0.14224)
		(layer "In6.Cu")
		(net "P5E_CPU1_P0_TX_DP<11>")
	)
	(segment
		(start 107.567984 -292.393624)
		(end 107.568746 -292.394132)
		(width 0.1143)
		(layer "In6.Cu")
		(net "P5E_CPU1_P0_TX_DP<11>")
	)
	(segment
		(start 122.611896 -354.145088)
		(end 103.053388 -367.213896)
		(width 0.14224)
		(layer "In6.Cu")
		(net "P5E_CPU1_P0_TX_DP<11>")
	)
	(segment
		(start 107.567984 -288.178748)
		(end 107.55503 -288.186368)
		(width 0.1143)
		(layer "In6.Cu")
		(net "P5E_CPU1_P0_TX_DP<11>")
	)
	(segment
		(start 107.570524 -292.395148)
		(end 107.57154 -292.395656)
		(width 0.1143)
		(layer "In6.Cu")
		(net "P5E_CPU1_P0_TX_DP<11>")
	)
	(segment
		(start 107.601512 -288.15919)
		(end 107.567984 -288.178748)
		(width 0.1143)
		(layer "In6.Cu")
		(net "P5E_CPU1_P0_TX_DP<11>")
	)
	(segment
		(start 114.550698 -312.244994)
		(end 120.79097 -319.850262)
		(width 0.14224)
		(layer "In6.Cu")
		(net "P5E_CPU1_P0_TX_DP<11>")
	)
	(segment
		(start 107.589828 -291.406072)
		(end 107.589066 -291.40658)
		(width 0.1143)
		(layer "In6.Cu")
		(net "P5E_CPU1_P0_TX_DP<11>")
	)
	(segment
		(start 71.792084 -367.40211)
		(end 70.60565 -366.910874)
		(width 0.14224)
		(layer "In6.Cu")
		(net "P5E_CPU1_P0_TX_DP<11>")
	)
	(segment
		(start 107.569762 -290.774628)
		(end 107.570524 -290.775136)
		(width 0.1143)
		(layer "In6.Cu")
		(net "P5E_CPU1_P0_TX_DP<11>")
	)
	(segment
		(start 107.014264 -296.584116)
		(end 107.014264 -296.612564)
		(width 0.1143)
		(layer "In6.Cu")
		(net "P5E_CPU1_P0_TX_DP<11>")
	)
	(segment
		(start 110.228634 -305.790092)
		(end 114.459004 -312.121042)
		(width 0.14224)
		(layer "In6.Cu")
		(net "P5E_CPU1_P0_TX_DP<11>")
	)
	(segment
		(start 107.533186 -287.510982)
		(end 107.567984 -287.533842)
		(width 0.1143)
		(layer "In6.Cu")
		(net "P5E_CPU1_P0_TX_DP<11>")
	)
	(segment
		(start 107.56773 -292.393624)
		(end 107.567984 -292.393624)
		(width 0.1143)
		(layer "In6.Cu")
		(net "P5E_CPU1_P0_TX_DP<11>")
	)
	(segment
		(start 107.568746 -292.394132)
		(end 107.569762 -292.39464)
		(width 0.1143)
		(layer "In6.Cu")
		(net "P5E_CPU1_P0_TX_DP<11>")
	)
	(segment
		(start 106.440986 -286.23641)
		(end 106.738928 -286.23641)
		(width 0.1143)
		(layer "In6.Cu")
		(net "P5E_CPU1_P0_TX_DP<11>")
	)
	(segment
		(start 120.955308 -320.098166)
		(end 125.02642 -327.885806)
		(width 0.14224)
		(layer "In6.Cu")
		(net "P5E_CPU1_P0_TX_DP<11>")
	)
	(segment
		(start 69.348604 -366.661192)
		(end 66.028824 -366.661192)
		(width 0.14224)
		(layer "In6.Cu")
		(net "P5E_CPU1_P0_TX_DP<11>")
	)
	(segment
		(start 120.955308 -320.097912)
		(end 120.955308 -320.098166)
		(width 0.14224)
		(layer "In6.Cu")
		(net "P5E_CPU1_P0_TX_DP<11>")
	)
	(segment
		(start 126.644654 -345.91244)
		(end 126.571756 -346.107512)
		(width 0.14224)
		(layer "In6.Cu")
		(net "P5E_CPU1_P0_TX_DP<11>")
	)
	(segment
		(start 107.57408 -290.777168)
		(end 107.57535 -290.77793)
		(width 0.1143)
		(layer "In6.Cu")
		(net "P5E_CPU1_P0_TX_DP<11>")
	)
	(segment
		(start 125.269244 -328.886058)
		(end 127.459994 -341.076534)
		(width 0.14224)
		(layer "In6.Cu")
		(net "P5E_CPU1_P0_TX_DP<11>")
	)
	(segment
		(start 107.567984 -294.013636)
		(end 107.599734 -294.031924)
		(width 0.1143)
		(layer "In6.Cu")
		(net "P5E_CPU1_P0_TX_DP<11>")
	)
	(segment
		(start 107.57408 -292.39718)
		(end 107.57662 -292.398704)
		(width 0.1143)
		(layer "In6.Cu")
		(net "P5E_CPU1_P0_TX_DP<11>")
	)
	(segment
		(start 106.81589 -295.956228)
		(end 106.81589 -296.008044)
		(width 0.1143)
		(layer "In6.Cu")
		(net "P5E_CPU1_P0_TX_DP<11>")
	)
	(segment
		(start 107.570524 -290.775136)
		(end 107.57154 -290.775644)
		(width 0.1143)
		(layer "In6.Cu")
		(net "P5E_CPU1_P0_TX_DP<11>")
	)
	(segment
		(start 107.572302 -292.396164)
		(end 107.573318 -292.396672)
		(width 0.1143)
		(layer "In6.Cu")
		(net "P5E_CPU1_P0_TX_DP<11>")
	)
	(segment
		(start 107.567984 -290.773612)
		(end 107.568746 -290.77412)
		(width 0.1143)
		(layer "In6.Cu")
		(net "P5E_CPU1_P0_TX_DP<11>")
	)
	(segment
		(start 63.727584 -371.2083)
		(end 63.436754 -371.49913)
		(width 0.14224)
		(layer "In6.Cu")
		(net "P5E_CPU1_P0_TX_DP<11>")
	)
	(segment
		(start 107.531662 -293.992554)
		(end 107.567984 -294.013636)
		(width 0.1143)
		(layer "In6.Cu")
		(net "P5E_CPU1_P0_TX_DP<11>")
	)
	(segment
		(start 106.938064 -296.302176)
		(end 107.022392 -296.386758)
		(width 0.1143)
		(layer "In6.Cu")
		(net "P5E_CPU1_P0_TX_DP<11>")
	)
	(segment
		(start 107.599734 -293.020496)
		(end 107.567984 -293.038784)
		(width 0.1143)
		(layer "In6.Cu")
		(net "P5E_CPU1_P0_TX_DP<11>")
	)
	(segment
		(start 107.059984 -296.476928)
		(end 107.059984 -296.538396)
		(width 0.1143)
		(layer "In6.Cu")
		(net "P5E_CPU1_P0_TX_DP<11>")
	)
	(segment
		(start 107.567984 -287.533842)
		(end 107.599734 -287.55213)
		(width 0.1143)
		(layer "In6.Cu")
		(net "P5E_CPU1_P0_TX_DP<11>")
	)
	(segment
		(start 107.573318 -292.396672)
		(end 107.57408 -292.39718)
		(width 0.1143)
		(layer "In6.Cu")
		(net "P5E_CPU1_P0_TX_DP<11>")
	)
	(segment
		(start 107.57662 -292.398704)
		(end 107.599734 -292.411912)
		(width 0.1143)
		(layer "In6.Cu")
		(net "P5E_CPU1_P0_TX_DP<11>")
	)
	(segment
		(start 63.727584 -368.581432)
		(end 63.727584 -371.2083)
		(width 0.14224)
		(layer "In6.Cu")
		(net "P5E_CPU1_P0_TX_DP<11>")
	)
	(segment
		(start 107.599734 -289.780472)
		(end 107.589828 -289.78606)
		(width 0.1143)
		(layer "In6.Cu")
		(net "P5E_CPU1_P0_TX_DP<11>")
	)
	(segment
		(start 107.27309 -295.15562)
		(end 107.27309 -295.166034)
		(width 0.1143)
		(layer "In6.Cu")
		(net "P5E_CPU1_P0_TX_DP<11>")
	)
	(segment
		(start 107.568746 -290.77412)
		(end 107.569762 -290.774628)
		(width 0.1143)
		(layer "In6.Cu")
		(net "P5E_CPU1_P0_TX_DP<11>")
	)
	(segment
		(start 107.57154 -292.395656)
		(end 107.572302 -292.396164)
		(width 0.1143)
		(layer "In6.Cu")
		(net "P5E_CPU1_P0_TX_DP<11>")
	)
	(segment
		(start 64.261746 -367.619788)
		(end 64.029844 -367.85169)
		(width 0.14224)
		(layer "In6.Cu")
		(net "P5E_CPU1_P0_TX_DP<11>")
	)
	(segment
		(start 107.599734 -294.640508)
		(end 107.554522 -294.66667)
		(width 0.1143)
		(layer "In6.Cu")
		(net "P5E_CPU1_P0_TX_DP<11>")
	)
	(segment
		(start 107.567984 -291.418772)
		(end 107.56773 -291.419026)
		(width 0.1143)
		(layer "In6.Cu")
		(net "P5E_CPU1_P0_TX_DP<11>")
	)
	(arc
		(start 103.053388 -367.213896)
		(mid 102.605603 -367.425702)
		(end 102.11562 -367.498376)
		(width 0.14224)
		(layer "In6.Cu")
		(net "P5E_CPU1_P0_TX_DP<11>")
	)
	(arc
		(start 106.763058 -286.26054)
		(mid 106.807511 -286.318297)
		(end 106.835702 -286.385508)
		(width 0.1143)
		(layer "In6.Cu")
		(net "P5E_CPU1_P0_TX_DP<11>")
	)
	(arc
		(start 72.275192 -367.498376)
		(mid 72.02889 -367.47406)
		(end 71.792084 -367.40211)
		(width 0.14224)
		(layer "In6.Cu")
		(net "P5E_CPU1_P0_TX_DP<11>")
	)
	(arc
		(start 107.014264 -298.125134)
		(mid 107.02946 -298.279481)
		(end 107.074462 -298.427902)
		(width 0.14224)
		(layer "In6.Cu")
		(net "P5E_CPU1_P0_TX_DP<11>")
	)
	(arc
		(start 120.79097 -319.850262)
		(mid 120.879497 -319.969868)
		(end 120.955308 -320.097912)
		(width 0.14224)
		(layer "In6.Cu")
		(net "P5E_CPU1_P0_TX_DP<11>")
	)
	(arc
		(start 107.599734 -292.411912)
		(mid 107.755662 -292.716204)
		(end 107.599734 -293.020496)
		(width 0.1143)
		(layer "In6.Cu")
		(net "P5E_CPU1_P0_TX_DP<11>")
	)
	(arc
		(start 107.28579 -287.033208)
		(mid 107.286832 -287.056112)
		(end 107.289092 -287.078928)
		(width 0.1143)
		(layer "In6.Cu")
		(net "P5E_CPU1_P0_TX_DP<11>")
	)
	(arc
		(start 114.459004 -312.121042)
		(mid 114.503333 -312.184141)
		(end 114.550698 -312.244994)
		(width 0.14224)
		(layer "In6.Cu")
		(net "P5E_CPU1_P0_TX_DP<11>")
	)
	(arc
		(start 107.599734 -290.7919)
		(mid 107.755662 -291.096192)
		(end 107.599734 -291.400484)
		(width 0.1143)
		(layer "In6.Cu")
		(net "P5E_CPU1_P0_TX_DP<11>")
	)
	(arc
		(start 123.889008 -352.58883)
		(mid 123.365878 -353.461682)
		(end 122.611896 -354.145088)
		(width 0.14224)
		(layer "In6.Cu")
		(net "P5E_CPU1_P0_TX_DP<11>")
	)
	(arc
		(start 125.02642 -327.885806)
		(mid 125.052082 -327.943709)
		(end 125.070108 -328.004424)
		(width 0.14224)
		(layer "In6.Cu")
		(net "P5E_CPU1_P0_TX_DP<11>")
	)
	(arc
		(start 107.061762 -295.489884)
		(mid 106.88111 -295.692629)
		(end 106.81589 -295.956228)
		(width 0.1143)
		(layer "In6.Cu")
		(net "P5E_CPU1_P0_TX_DP<11>")
	)
	(arc
		(start 127.459994 -341.076534)
		(mid 127.478609 -341.254562)
		(end 127.49403 -341.432896)
		(width 0.14224)
		(layer "In6.Cu")
		(net "P5E_CPU1_P0_TX_DP<11>")
	)
	(arc
		(start 107.75569 -287.856422)
		(mid 107.714928 -288.026306)
		(end 107.601512 -288.15919)
		(width 0.1143)
		(layer "In6.Cu")
		(net "P5E_CPU1_P0_TX_DP<11>")
	)
	(arc
		(start 64.029844 -367.85169)
		(mid 63.806132 -368.186498)
		(end 63.727584 -368.581432)
		(width 0.14224)
		(layer "In6.Cu")
		(net "P5E_CPU1_P0_TX_DP<11>")
	)
	(arc
		(start 106.81589 -296.008044)
		(mid 106.847745 -296.16725)
		(end 106.938064 -296.302176)
		(width 0.1143)
		(layer "In6.Cu")
		(net "P5E_CPU1_P0_TX_DP<11>")
	)
	(arc
		(start 70.60565 -366.910874)
		(mid 69.989424 -366.724126)
		(end 69.348604 -366.661192)
		(width 0.14224)
		(layer "In6.Cu")
		(net "P5E_CPU1_P0_TX_DP<11>")
	)
	(arc
		(start 127.502158 -342.373458)
		(mid 127.118856 -344.153962)
		(end 126.644654 -345.91244)
		(width 0.14224)
		(layer "In6.Cu")
		(net "P5E_CPU1_P0_TX_DP<11>")
	)
	(arc
		(start 126.571756 -346.107512)
		(mid 126.55076 -346.162179)
		(end 126.52883 -346.216478)
		(width 0.14224)
		(layer "In6.Cu")
		(net "P5E_CPU1_P0_TX_DP<11>")
	)
	(arc
		(start 109.75594 -304.90287)
		(mid 109.787238 -304.973534)
		(end 109.82198 -305.04257)
		(width 0.14224)
		(layer "In6.Cu")
		(net "P5E_CPU1_P0_TX_DP<11>")
	)
	(arc
		(start 65.379092 -366.87252)
		(mid 64.783645 -367.191172)
		(end 64.261746 -367.619788)
		(width 0.14224)
		(layer "In6.Cu")
		(net "P5E_CPU1_P0_TX_DP<11>")
	)
	(arc
		(start 107.531662 -293.059866)
		(mid 107.523998 -293.065137)
		(end 107.516422 -293.070534)
		(width 0.1143)
		(layer "In6.Cu")
		(net "P5E_CPU1_P0_TX_DP<11>")
	)
	(arc
		(start 107.55503 -288.186368)
		(mid 107.278697 -288.666174)
		(end 107.55503 -289.14598)
		(width 0.1143)
		(layer "In6.Cu")
		(net "P5E_CPU1_P0_TX_DP<11>")
	)
	(arc
		(start 66.028824 -366.661192)
		(mid 65.891292 -366.674806)
		(end 65.759076 -366.71504)
		(width 0.14224)
		(layer "In6.Cu")
		(net "P5E_CPU1_P0_TX_DP<11>")
	)
	(arc
		(start 107.554522 -294.66667)
		(mid 107.348454 -294.873533)
		(end 107.27309 -295.15562)
		(width 0.1143)
		(layer "In6.Cu")
		(net "P5E_CPU1_P0_TX_DP<11>")
	)
	(arc
		(start 107.56773 -289.799014)
		(mid 107.287083 -290.286376)
		(end 107.56773 -290.773612)
		(width 0.1143)
		(layer "In6.Cu")
		(net "P5E_CPU1_P0_TX_DP<11>")
	)
	(arc
		(start 107.56773 -291.419026)
		(mid 107.287083 -291.906388)
		(end 107.56773 -292.393624)
		(width 0.1143)
		(layer "In6.Cu")
		(net "P5E_CPU1_P0_TX_DP<11>")
	)
	(arc
		(start 107.599734 -289.171888)
		(mid 107.755662 -289.47618)
		(end 107.599734 -289.780472)
		(width 0.1143)
		(layer "In6.Cu")
		(net "P5E_CPU1_P0_TX_DP<11>")
	)
	(arc
		(start 127.49403 -341.432896)
		(mid 127.511635 -341.671987)
		(end 127.527812 -341.911178)
		(width 0.14224)
		(layer "In6.Cu")
		(net "P5E_CPU1_P0_TX_DP<11>")
	)
	(arc
		(start 110.16361 -305.681634)
		(mid 110.194789 -305.736662)
		(end 110.228634 -305.790092)
		(width 0.14224)
		(layer "In6.Cu")
		(net "P5E_CPU1_P0_TX_DP<11>")
	)
	(arc
		(start 107.516422 -293.070534)
		(mid 107.291251 -293.52621)
		(end 107.516422 -293.981886)
		(width 0.1143)
		(layer "In6.Cu")
		(net "P5E_CPU1_P0_TX_DP<11>")
	)
	(arc
		(start 107.599734 -294.031924)
		(mid 107.755662 -294.336216)
		(end 107.599734 -294.640508)
		(width 0.1143)
		(layer "In6.Cu")
		(net "P5E_CPU1_P0_TX_DP<11>")
	)
	(arc
		(start 107.022392 -296.386758)
		(mid 107.050226 -296.428085)
		(end 107.059984 -296.476928)
		(width 0.1143)
		(layer "In6.Cu")
		(net "P5E_CPU1_P0_TX_DP<11>")
	)
	(arc
		(start 107.289092 -287.078928)
		(mid 107.369781 -287.318315)
		(end 107.533186 -287.510982)
		(width 0.1143)
		(layer "In6.Cu")
		(net "P5E_CPU1_P0_TX_DP<11>")
	)
	(arc
		(start 107.130596 -286.742886)
		(mid 107.241851 -286.870065)
		(end 107.28579 -287.033208)
		(width 0.1143)
		(layer "In6.Cu")
		(net "P5E_CPU1_P0_TX_DP<11>")
	)
	(arc
		(start 106.835702 -286.385508)
		(mid 106.921433 -286.564942)
		(end 107.064048 -286.703516)
		(width 0.1143)
		(layer "In6.Cu")
		(net "P5E_CPU1_P0_TX_DP<11>")
	)
	(arc
		(start 107.599734 -287.55213)
		(mid 107.71441 -287.685464)
		(end 107.75569 -287.856422)
		(width 0.1143)
		(layer "In6.Cu")
		(net "P5E_CPU1_P0_TX_DP<11>")
	)
	(arc
		(start 107.516422 -293.981886)
		(mid 107.523998 -293.987282)
		(end 107.531662 -293.992554)
		(width 0.1143)
		(layer "In6.Cu")
		(net "P5E_CPU1_P0_TX_DP<11>")
	)
	(arc
		(start 127.527812 -341.911178)
		(mid 127.530077 -342.143156)
		(end 127.502158 -342.373458)
		(width 0.14224)
		(layer "In6.Cu")
		(net "P5E_CPU1_P0_TX_DP<11>")
	)
	(arc
		(start 107.27309 -295.166034)
		(mid 107.226199 -295.3409)
		(end 107.098084 -295.468802)
		(width 0.1143)
		(layer "In6.Cu")
		(net "P5E_CPU1_P0_TX_DP<11>")
	)
	(arc
		(start 125.243844 -328.762106)
		(mid 125.257279 -328.823931)
		(end 125.269244 -328.886058)
		(width 0.14224)
		(layer "In6.Cu")
		(net "P5E_CPU1_P0_TX_DP<11>")
	)
	(segment
		(start 106.907838 -284.35046)
		(end 106.440986 -284.616398)
		(width 0.12954)
		(layer "F.Cu")
		(net "P5E_CPU1_P0_TX_DP<10>")
	)
	(segment
		(start 62.005464 -374.23344)
		(end 62.005464 -374.93702)
		(width 0.12954)
		(layer "F.Cu")
		(net "P5E_CPU1_P0_TX_DP<10>")
	)
	(segment
		(start 61.734954 -373.96293)
		(end 62.005464 -374.23344)
		(width 0.12954)
		(layer "F.Cu")
		(net "P5E_CPU1_P0_TX_DP<10>")
	)
	(segment
		(start 62.005464 -374.93702)
		(end 61.709554 -375.23293)
		(width 0.12954)
		(layer "F.Cu")
		(net "P5E_CPU1_P0_TX_DP<10>")
	)
	(segment
		(start 105.962958 -298.181776)
		(end 108.945172 -305.382168)
		(width 0.14224)
		(layer "In6.Cu")
		(net "P5E_CPU1_P0_TX_DP<10>")
	)
	(segment
		(start 101.86797 -366.52581)
		(end 72.415908 -366.52581)
		(width 0.14224)
		(layer "In6.Cu")
		(net "P5E_CPU1_P0_TX_DP<10>")
	)
	(segment
		(start 106.589068 -290.750752)
		(end 106.658664 -290.791392)
		(width 0.1143)
		(layer "In6.Cu")
		(net "P5E_CPU1_P0_TX_DP<10>")
	)
	(segment
		(start 124.353066 -329.191366)
		(end 126.510288 -341.319104)
		(width 0.14224)
		(layer "In6.Cu")
		(net "P5E_CPU1_P0_TX_DP<10>")
	)
	(segment
		(start 69.750178 -365.725456)
		(end 65.850516 -365.725456)
		(width 0.14224)
		(layer "In6.Cu")
		(net "P5E_CPU1_P0_TX_DP<10>")
	)
	(segment
		(start 106.15803 -285.748984)
		(end 106.157014 -285.749492)
		(width 0.1143)
		(layer "In6.Cu")
		(net "P5E_CPU1_P0_TX_DP<10>")
	)
	(segment
		(start 106.157014 -285.749492)
		(end 106.15549 -285.750508)
		(width 0.1143)
		(layer "In6.Cu")
		(net "P5E_CPU1_P0_TX_DP<10>")
	)
	(segment
		(start 108.945172 -305.382168)
		(end 109.449616 -306.325524)
		(width 0.14224)
		(layer "In6.Cu")
		(net "P5E_CPU1_P0_TX_DP<10>")
	)
	(segment
		(start 121.918984 -353.483672)
		(end 102.844092 -366.229646)
		(width 0.14224)
		(layer "In6.Cu")
		(net "P5E_CPU1_P0_TX_DP<10>")
	)
	(segment
		(start 109.449616 -306.325524)
		(end 113.880646 -312.95721)
		(width 0.14224)
		(layer "In6.Cu")
		(net "P5E_CPU1_P0_TX_DP<10>")
	)
	(segment
		(start 106.18978 -285.730696)
		(end 106.160062 -285.747714)
		(width 0.1143)
		(layer "In6.Cu")
		(net "P5E_CPU1_P0_TX_DP<10>")
	)
	(segment
		(start 65.509648 -365.79302)
		(end 64.016382 -366.411764)
		(width 0.14224)
		(layer "In6.Cu")
		(net "P5E_CPU1_P0_TX_DP<10>")
	)
	(segment
		(start 71.881238 -366.419384)
		(end 70.627494 -365.899954)
		(width 0.14224)
		(layer "In6.Cu")
		(net "P5E_CPU1_P0_TX_DP<10>")
	)
	(segment
		(start 105.916984 -296.281348)
		(end 105.916984 -297.95089)
		(width 0.14224)
		(layer "In6.Cu")
		(net "P5E_CPU1_P0_TX_DP<10>")
	)
	(segment
		(start 125.886972 -344.99296)
		(end 122.79757 -352.453702)
		(width 0.14224)
		(layer "In6.Cu")
		(net "P5E_CPU1_P0_TX_DP<10>")
	)
	(segment
		(start 105.924858 -296.26052)
		(end 105.916984 -296.281348)
		(width 0.1143)
		(layer "In6.Cu")
		(net "P5E_CPU1_P0_TX_DP<10>")
	)
	(segment
		(start 106.118914 -286.700976)
		(end 106.191558 -286.743394)
		(width 0.1143)
		(layer "In6.Cu")
		(net "P5E_CPU1_P0_TX_DP<10>")
	)
	(segment
		(start 106.658664 -284.921198)
		(end 106.589068 -284.961838)
		(width 0.1143)
		(layer "In6.Cu")
		(net "P5E_CPU1_P0_TX_DP<10>")
	)
	(segment
		(start 106.589068 -293.990776)
		(end 106.658664 -294.031416)
		(width 0.1143)
		(layer "In6.Cu")
		(net "P5E_CPU1_P0_TX_DP<10>")
	)
	(segment
		(start 106.158792 -285.748476)
		(end 106.15803 -285.748984)
		(width 0.1143)
		(layer "In6.Cu")
		(net "P5E_CPU1_P0_TX_DP<10>")
	)
	(segment
		(start 106.160062 -285.747714)
		(end 106.158792 -285.748476)
		(width 0.1143)
		(layer "In6.Cu")
		(net "P5E_CPU1_P0_TX_DP<10>")
	)
	(segment
		(start 106.658664 -291.400992)
		(end 106.589068 -291.441632)
		(width 0.1143)
		(layer "In6.Cu")
		(net "P5E_CPU1_P0_TX_DP<10>")
	)
	(segment
		(start 106.345736 -295.146222)
		(end 106.345736 -295.18356)
		(width 0.1143)
		(layer "In6.Cu")
		(net "P5E_CPU1_P0_TX_DP<10>")
	)
	(segment
		(start 61.97854 -373.719344)
		(end 61.734954 -373.96293)
		(width 0.14224)
		(layer "In6.Cu")
		(net "P5E_CPU1_P0_TX_DP<10>")
	)
	(segment
		(start 106.738928 -284.616398)
		(end 106.808778 -284.686248)
		(width 0.1143)
		(layer "In6.Cu")
		(net "P5E_CPU1_P0_TX_DP<10>")
	)
	(segment
		(start 106.589068 -292.370764)
		(end 106.658664 -292.411404)
		(width 0.1143)
		(layer "In6.Cu")
		(net "P5E_CPU1_P0_TX_DP<10>")
	)
	(segment
		(start 106.658664 -293.021004)
		(end 106.589068 -293.061644)
		(width 0.1143)
		(layer "In6.Cu")
		(net "P5E_CPU1_P0_TX_DP<10>")
	)
	(segment
		(start 106.154474 -285.751016)
		(end 106.118914 -285.771844)
		(width 0.1143)
		(layer "In6.Cu")
		(net "P5E_CPU1_P0_TX_DP<10>")
	)
	(segment
		(start 106.192574 -295.553384)
		(end 106.125518 -295.62044)
		(width 0.1143)
		(layer "In6.Cu")
		(net "P5E_CPU1_P0_TX_DP<10>")
	)
	(segment
		(start 106.658664 -289.78098)
		(end 106.589068 -289.82162)
		(width 0.1143)
		(layer "In6.Cu")
		(net "P5E_CPU1_P0_TX_DP<10>")
	)
	(segment
		(start 105.962704 -296.013632)
		(end 105.962704 -296.15892)
		(width 0.1143)
		(layer "In6.Cu")
		(net "P5E_CPU1_P0_TX_DP<10>")
	)
	(segment
		(start 114.126264 -313.288934)
		(end 120.144794 -320.621914)
		(width 0.14224)
		(layer "In6.Cu")
		(net "P5E_CPU1_P0_TX_DP<10>")
	)
	(segment
		(start 106.591608 -287.512506)
		(end 106.658664 -287.551622)
		(width 0.1143)
		(layer "In6.Cu")
		(net "P5E_CPU1_P0_TX_DP<10>")
	)
	(segment
		(start 106.15549 -285.750508)
		(end 106.154474 -285.751016)
		(width 0.1143)
		(layer "In6.Cu")
		(net "P5E_CPU1_P0_TX_DP<10>")
	)
	(segment
		(start 106.660696 -288.159952)
		(end 106.628184 -288.178748)
		(width 0.1143)
		(layer "In6.Cu")
		(net "P5E_CPU1_P0_TX_DP<10>")
	)
	(segment
		(start 106.440986 -284.616398)
		(end 106.738928 -284.616398)
		(width 0.1143)
		(layer "In6.Cu")
		(net "P5E_CPU1_P0_TX_DP<10>")
	)
	(segment
		(start 120.214644 -320.727324)
		(end 124.111512 -328.180954)
		(width 0.14224)
		(layer "In6.Cu")
		(net "P5E_CPU1_P0_TX_DP<10>")
	)
	(segment
		(start 62.025784 -369.392708)
		(end 62.025784 -373.605298)
		(width 0.14224)
		(layer "In6.Cu")
		(net "P5E_CPU1_P0_TX_DP<10>")
	)
	(segment
		(start 126.51994 -341.445088)
		(end 126.51232 -341.79383)
		(width 0.14224)
		(layer "In6.Cu")
		(net "P5E_CPU1_P0_TX_DP<10>")
	)
	(segment
		(start 106.589068 -289.13074)
		(end 106.658664 -289.17138)
		(width 0.1143)
		(layer "In6.Cu")
		(net "P5E_CPU1_P0_TX_DP<10>")
	)
	(segment
		(start 106.658664 -294.641016)
		(end 106.589068 -294.681656)
		(width 0.1143)
		(layer "In6.Cu")
		(net "P5E_CPU1_P0_TX_DP<10>")
	)
	(segment
		(start 106.628184 -288.178748)
		(end 106.589068 -288.201608)
		(width 0.1143)
		(layer "In6.Cu")
		(net "P5E_CPU1_P0_TX_DP<10>")
	)
	(arc
		(start 106.658664 -294.031416)
		(mid 106.815641 -294.336216)
		(end 106.658664 -294.641016)
		(width 0.1143)
		(layer "In6.Cu")
		(net "P5E_CPU1_P0_TX_DP<10>")
	)
	(arc
		(start 122.741182 -352.56724)
		(mid 122.376203 -353.066838)
		(end 121.918984 -353.483672)
		(width 0.14224)
		(layer "In6.Cu")
		(net "P5E_CPU1_P0_TX_DP<10>")
	)
	(arc
		(start 106.589068 -291.441632)
		(mid 106.345741 -291.906198)
		(end 106.589068 -292.370764)
		(width 0.1143)
		(layer "In6.Cu")
		(net "P5E_CPU1_P0_TX_DP<10>")
	)
	(arc
		(start 106.191558 -286.743394)
		(mid 106.304965 -286.876283)
		(end 106.345736 -287.046162)
		(width 0.1143)
		(layer "In6.Cu")
		(net "P5E_CPU1_P0_TX_DP<10>")
	)
	(arc
		(start 102.844092 -366.229646)
		(mid 102.378001 -366.45014)
		(end 101.86797 -366.52581)
		(width 0.14224)
		(layer "In6.Cu")
		(net "P5E_CPU1_P0_TX_DP<10>")
	)
	(arc
		(start 105.962704 -296.15892)
		(mid 105.956681 -296.197786)
		(end 105.939336 -296.233088)
		(width 0.1143)
		(layer "In6.Cu")
		(net "P5E_CPU1_P0_TX_DP<10>")
	)
	(arc
		(start 62.025784 -373.605298)
		(mid 62.013507 -373.667021)
		(end 61.97854 -373.719344)
		(width 0.14224)
		(layer "In6.Cu")
		(net "P5E_CPU1_P0_TX_DP<10>")
	)
	(arc
		(start 106.589068 -284.961838)
		(mid 106.410255 -285.164188)
		(end 106.345736 -285.426404)
		(width 0.1143)
		(layer "In6.Cu")
		(net "P5E_CPU1_P0_TX_DP<10>")
	)
	(arc
		(start 106.808778 -284.686248)
		(mid 106.756361 -284.818179)
		(end 106.658664 -284.921198)
		(width 0.1143)
		(layer "In6.Cu")
		(net "P5E_CPU1_P0_TX_DP<10>")
	)
	(arc
		(start 106.815636 -287.856422)
		(mid 106.77467 -288.026828)
		(end 106.660696 -288.159952)
		(width 0.1143)
		(layer "In6.Cu")
		(net "P5E_CPU1_P0_TX_DP<10>")
	)
	(arc
		(start 70.627494 -365.899954)
		(mid 70.197429 -365.7695)
		(end 69.750178 -365.725456)
		(width 0.14224)
		(layer "In6.Cu")
		(net "P5E_CPU1_P0_TX_DP<10>")
	)
	(arc
		(start 122.79757 -352.453702)
		(mid 122.771338 -352.511446)
		(end 122.741182 -352.56724)
		(width 0.14224)
		(layer "In6.Cu")
		(net "P5E_CPU1_P0_TX_DP<10>")
	)
	(arc
		(start 126.510288 -341.319104)
		(mid 126.51823 -341.381857)
		(end 126.51994 -341.445088)
		(width 0.14224)
		(layer "In6.Cu")
		(net "P5E_CPU1_P0_TX_DP<10>")
	)
	(arc
		(start 106.589068 -288.201608)
		(mid 106.345741 -288.666174)
		(end 106.589068 -289.13074)
		(width 0.1143)
		(layer "In6.Cu")
		(net "P5E_CPU1_P0_TX_DP<10>")
	)
	(arc
		(start 106.658664 -289.17138)
		(mid 106.815641 -289.47618)
		(end 106.658664 -289.78098)
		(width 0.1143)
		(layer "In6.Cu")
		(net "P5E_CPU1_P0_TX_DP<10>")
	)
	(arc
		(start 65.850516 -365.725456)
		(mid 65.676748 -365.742428)
		(end 65.509648 -365.79302)
		(width 0.14224)
		(layer "In6.Cu")
		(net "P5E_CPU1_P0_TX_DP<10>")
	)
	(arc
		(start 106.658664 -292.411404)
		(mid 106.815641 -292.716204)
		(end 106.658664 -293.021004)
		(width 0.1143)
		(layer "In6.Cu")
		(net "P5E_CPU1_P0_TX_DP<10>")
	)
	(arc
		(start 105.939336 -296.233088)
		(mid 105.931251 -296.246358)
		(end 105.924858 -296.26052)
		(width 0.1143)
		(layer "In6.Cu")
		(net "P5E_CPU1_P0_TX_DP<10>")
	)
	(arc
		(start 106.125518 -295.62044)
		(mid 106.005034 -295.800852)
		(end 105.962704 -296.013632)
		(width 0.1143)
		(layer "In6.Cu")
		(net "P5E_CPU1_P0_TX_DP<10>")
	)
	(arc
		(start 72.415908 -366.52581)
		(mid 72.143337 -366.498911)
		(end 71.881238 -366.419384)
		(width 0.14224)
		(layer "In6.Cu")
		(net "P5E_CPU1_P0_TX_DP<10>")
	)
	(arc
		(start 106.589068 -293.061644)
		(mid 106.345741 -293.52621)
		(end 106.589068 -293.990776)
		(width 0.1143)
		(layer "In6.Cu")
		(net "P5E_CPU1_P0_TX_DP<10>")
	)
	(arc
		(start 113.880646 -312.95721)
		(mid 113.999432 -313.126051)
		(end 114.126264 -313.288934)
		(width 0.14224)
		(layer "In6.Cu")
		(net "P5E_CPU1_P0_TX_DP<10>")
	)
	(arc
		(start 106.118914 -285.771844)
		(mid 105.875587 -286.23641)
		(end 106.118914 -286.700976)
		(width 0.1143)
		(layer "In6.Cu")
		(net "P5E_CPU1_P0_TX_DP<10>")
	)
	(arc
		(start 106.658664 -290.791392)
		(mid 106.815641 -291.096192)
		(end 106.658664 -291.400992)
		(width 0.1143)
		(layer "In6.Cu")
		(net "P5E_CPU1_P0_TX_DP<10>")
	)
	(arc
		(start 106.345736 -295.18356)
		(mid 106.305926 -295.383698)
		(end 106.192574 -295.553384)
		(width 0.1143)
		(layer "In6.Cu")
		(net "P5E_CPU1_P0_TX_DP<10>")
	)
	(arc
		(start 64.016382 -366.411764)
		(mid 62.569053 -367.600365)
		(end 62.025784 -369.392708)
		(width 0.14224)
		(layer "In6.Cu")
		(net "P5E_CPU1_P0_TX_DP<10>")
	)
	(arc
		(start 126.51232 -341.79383)
		(mid 126.314794 -343.415903)
		(end 125.886972 -344.99296)
		(width 0.14224)
		(layer "In6.Cu")
		(net "P5E_CPU1_P0_TX_DP<10>")
	)
	(arc
		(start 105.916984 -297.95089)
		(mid 105.928609 -298.068596)
		(end 105.962958 -298.181776)
		(width 0.14224)
		(layer "In6.Cu")
		(net "P5E_CPU1_P0_TX_DP<10>")
	)
	(arc
		(start 106.658664 -287.551622)
		(mid 106.774091 -287.684998)
		(end 106.815636 -287.856422)
		(width 0.1143)
		(layer "In6.Cu")
		(net "P5E_CPU1_P0_TX_DP<10>")
	)
	(arc
		(start 124.111512 -328.180954)
		(mid 124.137575 -328.238727)
		(end 124.156978 -328.299064)
		(width 0.14224)
		(layer "In6.Cu")
		(net "P5E_CPU1_P0_TX_DP<10>")
	)
	(arc
		(start 106.345736 -287.046162)
		(mid 106.410972 -287.309753)
		(end 106.591608 -287.512506)
		(width 0.1143)
		(layer "In6.Cu")
		(net "P5E_CPU1_P0_TX_DP<10>")
	)
	(arc
		(start 124.156978 -328.299064)
		(mid 124.263965 -328.74325)
		(end 124.353066 -329.191366)
		(width 0.14224)
		(layer "In6.Cu")
		(net "P5E_CPU1_P0_TX_DP<10>")
	)
	(arc
		(start 106.589068 -289.82162)
		(mid 106.345741 -290.286186)
		(end 106.589068 -290.750752)
		(width 0.1143)
		(layer "In6.Cu")
		(net "P5E_CPU1_P0_TX_DP<10>")
	)
	(arc
		(start 120.144794 -320.621914)
		(mid 120.182436 -320.672819)
		(end 120.214644 -320.727324)
		(width 0.14224)
		(layer "In6.Cu")
		(net "P5E_CPU1_P0_TX_DP<10>")
	)
	(arc
		(start 106.345736 -285.426404)
		(mid 106.304481 -285.597375)
		(end 106.18978 -285.730696)
		(width 0.1143)
		(layer "In6.Cu")
		(net "P5E_CPU1_P0_TX_DP<10>")
	)
	(arc
		(start 106.589068 -294.681656)
		(mid 106.410255 -294.884006)
		(end 106.345736 -295.146222)
		(width 0.1143)
		(layer "In6.Cu")
		(net "P5E_CPU1_P0_TX_DP<10>")
	)
	(segment
		(start 42.404792 -382.09855)
		(end 42.700702 -382.39446)
		(width 0.12954)
		(layer "F.Cu")
		(net "P5E_CPU1_P0_TX_DP<0>")
	)
	(segment
		(start 41.701212 -382.09855)
		(end 42.404792 -382.09855)
		(width 0.12954)
		(layer "F.Cu")
		(net "P5E_CPU1_P0_TX_DP<0>")
	)
	(segment
		(start 41.430702 -382.36906)
		(end 41.701212 -382.09855)
		(width 0.12954)
		(layer "F.Cu")
		(net "P5E_CPU1_P0_TX_DP<0>")
	)
	(segment
		(start 98.44786 -282.730448)
		(end 97.981008 -282.996386)
		(width 0.12954)
		(layer "F.Cu")
		(net "P5E_CPU1_P0_TX_DP<0>")
	)
	(segment
		(start 116.550186 -339.32114)
		(end 116.55806 -339.437218)
		(width 0.14224)
		(layer "In6.Cu")
		(net "P5E_CPU1_P0_TX_DP<0>")
	)
	(segment
		(start 98.27895 -282.996386)
		(end 98.3488 -283.066236)
		(width 0.1143)
		(layer "In6.Cu")
		(net "P5E_CPU1_P0_TX_DP<0>")
	)
	(segment
		(start 113.732818 -347.499432)
		(end 100.09378 -356.629208)
		(width 0.14224)
		(layer "In6.Cu")
		(net "P5E_CPU1_P0_TX_DP<0>")
	)
	(segment
		(start 114.869976 -330.990194)
		(end 115.2398 -332.070456)
		(width 0.14224)
		(layer "In6.Cu")
		(net "P5E_CPU1_P0_TX_DP<0>")
	)
	(segment
		(start 97.19056 -293.991792)
		(end 97.259902 -294.032178)
		(width 0.1143)
		(layer "In6.Cu")
		(net "P5E_CPU1_P0_TX_DP<0>")
	)
	(segment
		(start 39.868602 -381.54356)
		(end 40.220646 -381.895604)
		(width 0.14224)
		(layer "In6.Cu")
		(net "P5E_CPU1_P0_TX_DP<0>")
	)
	(segment
		(start 96.475804 -295.94175)
		(end 96.475804 -296.294556)
		(width 0.1143)
		(layer "In6.Cu")
		(net "P5E_CPU1_P0_TX_DP<0>")
	)
	(segment
		(start 107.305348 -320.060066)
		(end 112.38865 -326.25538)
		(width 0.14224)
		(layer "In6.Cu")
		(net "P5E_CPU1_P0_TX_DP<0>")
	)
	(segment
		(start 97.19056 -290.751768)
		(end 97.259902 -290.792154)
		(width 0.1143)
		(layer "In6.Cu")
		(net "P5E_CPU1_P0_TX_DP<0>")
	)
	(segment
		(start 97.259902 -293.020242)
		(end 97.190306 -293.060628)
		(width 0.1143)
		(layer "In6.Cu")
		(net "P5E_CPU1_P0_TX_DP<0>")
	)
	(segment
		(start 97.258632 -284.921198)
		(end 97.189036 -284.961838)
		(width 0.1143)
		(layer "In6.Cu")
		(net "P5E_CPU1_P0_TX_DP<0>")
	)
	(segment
		(start 116.0526 -342.538304)
		(end 114.272314 -346.835984)
		(width 0.14224)
		(layer "In6.Cu")
		(net "P5E_CPU1_P0_TX_DP<0>")
	)
	(segment
		(start 97.259902 -289.780218)
		(end 97.190306 -289.820604)
		(width 0.1143)
		(layer "In6.Cu")
		(net "P5E_CPU1_P0_TX_DP<0>")
	)
	(segment
		(start 63.80861 -356.286308)
		(end 54.906672 -359.974134)
		(width 0.14224)
		(layer "In6.Cu")
		(net "P5E_CPU1_P0_TX_DP<0>")
	)
	(segment
		(start 53.92928 -360.85145)
		(end 47.246286 -363.619034)
		(width 0.14224)
		(layer "In6.Cu")
		(net "P5E_CPU1_P0_TX_DP<0>")
	)
	(segment
		(start 96.717104 -286.699452)
		(end 96.790002 -286.742124)
		(width 0.1143)
		(layer "In6.Cu")
		(net "P5E_CPU1_P0_TX_DP<0>")
	)
	(segment
		(start 97.981008 -282.996386)
		(end 98.27895 -282.996386)
		(width 0.1143)
		(layer "In6.Cu")
		(net "P5E_CPU1_P0_TX_DP<0>")
	)
	(segment
		(start 73.435718 -356.847648)
		(end 72.390508 -356.414578)
		(width 0.14224)
		(layer "In6.Cu")
		(net "P5E_CPU1_P0_TX_DP<0>")
	)
	(segment
		(start 97.68967 -284.133798)
		(end 97.688146 -284.134814)
		(width 0.1143)
		(layer "In6.Cu")
		(net "P5E_CPU1_P0_TX_DP<0>")
	)
	(segment
		(start 97.694496 -284.131004)
		(end 97.68967 -284.133798)
		(width 0.1143)
		(layer "In6.Cu")
		(net "P5E_CPU1_P0_TX_DP<0>")
	)
	(segment
		(start 43.21937 -365.377476)
		(end 42.942764 -365.582454)
		(width 0.14224)
		(layer "In6.Cu")
		(net "P5E_CPU1_P0_TX_DP<0>")
	)
	(segment
		(start 40.419782 -369.05057)
		(end 40.419782 -373.18061)
		(width 0.14224)
		(layer "In6.Cu")
		(net "P5E_CPU1_P0_TX_DP<0>")
	)
	(segment
		(start 112.4585 -326.360536)
		(end 114.819938 -330.874116)
		(width 0.14224)
		(layer "In6.Cu")
		(net "P5E_CPU1_P0_TX_DP<0>")
	)
	(segment
		(start 96.430084 -296.340276)
		(end 96.430084 -296.354754)
		(width 0.1143)
		(layer "In6.Cu")
		(net "P5E_CPU1_P0_TX_DP<0>")
	)
	(segment
		(start 41.139872 -382.07823)
		(end 41.430702 -382.36906)
		(width 0.14224)
		(layer "In6.Cu")
		(net "P5E_CPU1_P0_TX_DP<0>")
	)
	(segment
		(start 40.66159 -382.07823)
		(end 41.139872 -382.07823)
		(width 0.14224)
		(layer "In6.Cu")
		(net "P5E_CPU1_P0_TX_DP<0>")
	)
	(segment
		(start 39.736776 -375.847102)
		(end 39.736776 -381.225552)
		(width 0.14224)
		(layer "In6.Cu")
		(net "P5E_CPU1_P0_TX_DP<0>")
	)
	(segment
		(start 116.535454 -339.21192)
		(end 116.535454 -339.212174)
		(width 0.14224)
		(layer "In6.Cu")
		(net "P5E_CPU1_P0_TX_DP<0>")
	)
	(segment
		(start 101.077522 -310.815482)
		(end 106.788458 -319.36309)
		(width 0.14224)
		(layer "In6.Cu")
		(net "P5E_CPU1_P0_TX_DP<0>")
	)
	(segment
		(start 114.819938 -330.874116)
		(end 114.820192 -330.874116)
		(width 0.14224)
		(layer "In6.Cu")
		(net "P5E_CPU1_P0_TX_DP<0>")
	)
	(segment
		(start 97.70237 -284.126432)
		(end 97.701608 -284.12694)
		(width 0.1143)
		(layer "In6.Cu")
		(net "P5E_CPU1_P0_TX_DP<0>")
	)
	(segment
		(start 97.729802 -284.110684)
		(end 97.70237 -284.126432)
		(width 0.1143)
		(layer "In6.Cu")
		(net "P5E_CPU1_P0_TX_DP<0>")
	)
	(segment
		(start 97.68713 -284.135322)
		(end 97.658936 -284.151832)
		(width 0.1143)
		(layer "In6.Cu")
		(net "P5E_CPU1_P0_TX_DP<0>")
	)
	(segment
		(start 97.259902 -294.640254)
		(end 97.19056 -294.68064)
		(width 0.1143)
		(layer "In6.Cu")
		(net "P5E_CPU1_P0_TX_DP<0>")
	)
	(segment
		(start 96.781874 -295.489884)
		(end 96.578674 -295.693338)
		(width 0.1143)
		(layer "In6.Cu")
		(net "P5E_CPU1_P0_TX_DP<0>")
	)
	(segment
		(start 98.198686 -283.301186)
		(end 98.12909 -283.341826)
		(width 0.1143)
		(layer "In6.Cu")
		(net "P5E_CPU1_P0_TX_DP<0>")
	)
	(segment
		(start 96.475804 -296.294556)
		(end 96.430084 -296.340276)
		(width 0.1143)
		(layer "In6.Cu")
		(net "P5E_CPU1_P0_TX_DP<0>")
	)
	(segment
		(start 97.19056 -287.511744)
		(end 97.25787 -287.55086)
		(width 0.1143)
		(layer "In6.Cu")
		(net "P5E_CPU1_P0_TX_DP<0>")
	)
	(segment
		(start 71.5899 -356.25532)
		(end 63.965074 -356.25532)
		(width 0.14224)
		(layer "In6.Cu")
		(net "P5E_CPU1_P0_TX_DP<0>")
	)
	(segment
		(start 42.942764 -365.582454)
		(end 40.778176 -367.747042)
		(width 0.14224)
		(layer "In6.Cu")
		(net "P5E_CPU1_P0_TX_DP<0>")
	)
	(segment
		(start 96.430084 -296.354754)
		(end 96.430084 -299.52188)
		(width 0.14224)
		(layer "In6.Cu")
		(net "P5E_CPU1_P0_TX_DP<0>")
	)
	(segment
		(start 97.19056 -289.131756)
		(end 97.259902 -289.172142)
		(width 0.1143)
		(layer "In6.Cu")
		(net "P5E_CPU1_P0_TX_DP<0>")
	)
	(segment
		(start 97.688146 -284.134814)
		(end 97.68713 -284.135322)
		(width 0.1143)
		(layer "In6.Cu")
		(net "P5E_CPU1_P0_TX_DP<0>")
	)
	(segment
		(start 97.19056 -292.37178)
		(end 97.259902 -292.412166)
		(width 0.1143)
		(layer "In6.Cu")
		(net "P5E_CPU1_P0_TX_DP<0>")
	)
	(segment
		(start 97.259902 -291.40023)
		(end 97.190306 -291.440616)
		(width 0.1143)
		(layer "In6.Cu")
		(net "P5E_CPU1_P0_TX_DP<0>")
	)
	(segment
		(start 97.698052 -284.128972)
		(end 97.697036 -284.12948)
		(width 0.1143)
		(layer "In6.Cu")
		(net "P5E_CPU1_P0_TX_DP<0>")
	)
	(segment
		(start 97.701608 -284.12694)
		(end 97.698814 -284.128464)
		(width 0.1143)
		(layer "In6.Cu")
		(net "P5E_CPU1_P0_TX_DP<0>")
	)
	(segment
		(start 54.906672 -359.974134)
		(end 54.906418 -359.974134)
		(width 0.14224)
		(layer "In6.Cu")
		(net "P5E_CPU1_P0_TX_DP<0>")
	)
	(segment
		(start 97.695512 -284.130496)
		(end 97.694496 -284.131004)
		(width 0.1143)
		(layer "In6.Cu")
		(net "P5E_CPU1_P0_TX_DP<0>")
	)
	(segment
		(start 97.698814 -284.128464)
		(end 97.698052 -284.128972)
		(width 0.1143)
		(layer "In6.Cu")
		(net "P5E_CPU1_P0_TX_DP<0>")
	)
	(segment
		(start 97.259902 -288.160206)
		(end 97.18802 -288.202116)
		(width 0.1143)
		(layer "In6.Cu")
		(net "P5E_CPU1_P0_TX_DP<0>")
	)
	(segment
		(start 97.697036 -284.12948)
		(end 97.695512 -284.130496)
		(width 0.1143)
		(layer "In6.Cu")
		(net "P5E_CPU1_P0_TX_DP<0>")
	)
	(segment
		(start 47.246286 -363.619034)
		(end 44.841414 -364.503208)
		(width 0.14224)
		(layer "In6.Cu")
		(net "P5E_CPU1_P0_TX_DP<0>")
	)
	(segment
		(start 96.790002 -285.730442)
		(end 96.756982 -285.749746)
		(width 0.1143)
		(layer "In6.Cu")
		(net "P5E_CPU1_P0_TX_DP<0>")
	)
	(segment
		(start 98.961448 -356.973378)
		(end 74.068686 -356.973378)
		(width 0.14224)
		(layer "In6.Cu")
		(net "P5E_CPU1_P0_TX_DP<0>")
	)
	(segment
		(start 115.279678 -332.223872)
		(end 116.535454 -339.21192)
		(width 0.14224)
		(layer "In6.Cu")
		(net "P5E_CPU1_P0_TX_DP<0>")
	)
	(segment
		(start 96.476058 -299.753274)
		(end 100.99167 -310.655208)
		(width 0.14224)
		(layer "In6.Cu")
		(net "P5E_CPU1_P0_TX_DP<0>")
	)
	(segment
		(start 54.71033 -360.105198)
		(end 54.033928 -360.7816)
		(width 0.14224)
		(layer "In6.Cu")
		(net "P5E_CPU1_P0_TX_DP<0>")
	)
	(arc
		(start 96.475804 -286.23641)
		(mid 96.53975 -286.497479)
		(end 96.717104 -286.699452)
		(width 0.1143)
		(layer "In6.Cu")
		(net "P5E_CPU1_P0_TX_DP<0>")
	)
	(arc
		(start 106.788458 -319.36309)
		(mid 107.038403 -319.717881)
		(end 107.305348 -320.060066)
		(width 0.14224)
		(layer "In6.Cu")
		(net "P5E_CPU1_P0_TX_DP<0>")
	)
	(arc
		(start 97.259902 -289.172142)
		(mid 97.415729 -289.47618)
		(end 97.259902 -289.780218)
		(width 0.1143)
		(layer "In6.Cu")
		(net "P5E_CPU1_P0_TX_DP<0>")
	)
	(arc
		(start 44.841414 -364.503208)
		(mid 43.99923 -364.882529)
		(end 43.21937 -365.377476)
		(width 0.14224)
		(layer "In6.Cu")
		(net "P5E_CPU1_P0_TX_DP<0>")
	)
	(arc
		(start 98.3488 -283.066236)
		(mid 98.296383 -283.198167)
		(end 98.198686 -283.301186)
		(width 0.1143)
		(layer "In6.Cu")
		(net "P5E_CPU1_P0_TX_DP<0>")
	)
	(arc
		(start 96.790002 -286.742124)
		(mid 96.904678 -286.875315)
		(end 96.945958 -287.046162)
		(width 0.1143)
		(layer "In6.Cu")
		(net "P5E_CPU1_P0_TX_DP<0>")
	)
	(arc
		(start 40.419782 -373.18061)
		(mid 40.416795 -373.243903)
		(end 40.40759 -373.306594)
		(width 0.14224)
		(layer "In6.Cu")
		(net "P5E_CPU1_P0_TX_DP<0>")
	)
	(arc
		(start 96.756982 -285.749746)
		(mid 96.551186 -285.955396)
		(end 96.475804 -286.23641)
		(width 0.1143)
		(layer "In6.Cu")
		(net "P5E_CPU1_P0_TX_DP<0>")
	)
	(arc
		(start 96.945704 -285.426404)
		(mid 96.904511 -285.597193)
		(end 96.790002 -285.730442)
		(width 0.1143)
		(layer "In6.Cu")
		(net "P5E_CPU1_P0_TX_DP<0>")
	)
	(arc
		(start 97.18802 -288.202116)
		(mid 97.010066 -288.404451)
		(end 96.945958 -288.666174)
		(width 0.1143)
		(layer "In6.Cu")
		(net "P5E_CPU1_P0_TX_DP<0>")
	)
	(arc
		(start 115.2398 -332.070456)
		(mid 115.262647 -332.146408)
		(end 115.279678 -332.223872)
		(width 0.14224)
		(layer "In6.Cu")
		(net "P5E_CPU1_P0_TX_DP<0>")
	)
	(arc
		(start 116.55806 -339.437218)
		(mid 116.485385 -341.01711)
		(end 116.0526 -342.538304)
		(width 0.14224)
		(layer "In6.Cu")
		(net "P5E_CPU1_P0_TX_DP<0>")
	)
	(arc
		(start 40.647366 -367.940082)
		(mid 40.477198 -368.483775)
		(end 40.419782 -369.05057)
		(width 0.14224)
		(layer "In6.Cu")
		(net "P5E_CPU1_P0_TX_DP<0>")
	)
	(arc
		(start 96.578674 -295.693338)
		(mid 96.502598 -295.807338)
		(end 96.475804 -295.94175)
		(width 0.1143)
		(layer "In6.Cu")
		(net "P5E_CPU1_P0_TX_DP<0>")
	)
	(arc
		(start 54.033928 -360.7816)
		(mid 53.985044 -360.82168)
		(end 53.92928 -360.85145)
		(width 0.14224)
		(layer "In6.Cu")
		(net "P5E_CPU1_P0_TX_DP<0>")
	)
	(arc
		(start 97.190306 -289.820604)
		(mid 96.945485 -290.286291)
		(end 97.19056 -290.751768)
		(width 0.1143)
		(layer "In6.Cu")
		(net "P5E_CPU1_P0_TX_DP<0>")
	)
	(arc
		(start 97.415604 -284.616398)
		(mid 97.374055 -284.78782)
		(end 97.258632 -284.921198)
		(width 0.1143)
		(layer "In6.Cu")
		(net "P5E_CPU1_P0_TX_DP<0>")
	)
	(arc
		(start 54.906418 -359.974134)
		(mid 54.801927 -360.030018)
		(end 54.71033 -360.105198)
		(width 0.14224)
		(layer "In6.Cu")
		(net "P5E_CPU1_P0_TX_DP<0>")
	)
	(arc
		(start 96.945958 -287.046162)
		(mid 97.010776 -287.309151)
		(end 97.19056 -287.511744)
		(width 0.1143)
		(layer "In6.Cu")
		(net "P5E_CPU1_P0_TX_DP<0>")
	)
	(arc
		(start 97.658936 -284.151832)
		(mid 97.480123 -284.354182)
		(end 97.415604 -284.616398)
		(width 0.1143)
		(layer "In6.Cu")
		(net "P5E_CPU1_P0_TX_DP<0>")
	)
	(arc
		(start 63.965074 -356.25532)
		(mid 63.885316 -356.263113)
		(end 63.80861 -356.286308)
		(width 0.14224)
		(layer "In6.Cu")
		(net "P5E_CPU1_P0_TX_DP<0>")
	)
	(arc
		(start 96.430084 -299.52188)
		(mid 96.44166 -299.639845)
		(end 96.476058 -299.753274)
		(width 0.14224)
		(layer "In6.Cu")
		(net "P5E_CPU1_P0_TX_DP<0>")
	)
	(arc
		(start 96.946466 -295.118028)
		(mid 96.898772 -295.319266)
		(end 96.781874 -295.489884)
		(width 0.1143)
		(layer "In6.Cu")
		(net "P5E_CPU1_P0_TX_DP<0>")
	)
	(arc
		(start 97.190306 -293.060628)
		(mid 96.945485 -293.526315)
		(end 97.19056 -293.991792)
		(width 0.1143)
		(layer "In6.Cu")
		(net "P5E_CPU1_P0_TX_DP<0>")
	)
	(arc
		(start 74.068686 -356.973378)
		(mid 73.746006 -356.941699)
		(end 73.435718 -356.847648)
		(width 0.14224)
		(layer "In6.Cu")
		(net "P5E_CPU1_P0_TX_DP<0>")
	)
	(arc
		(start 96.945958 -288.666174)
		(mid 97.010776 -288.929163)
		(end 97.19056 -289.131756)
		(width 0.1143)
		(layer "In6.Cu")
		(net "P5E_CPU1_P0_TX_DP<0>")
	)
	(arc
		(start 97.25787 -287.55086)
		(mid 97.415472 -287.854972)
		(end 97.259902 -288.160206)
		(width 0.1143)
		(layer "In6.Cu")
		(net "P5E_CPU1_P0_TX_DP<0>")
	)
	(arc
		(start 39.736776 -381.225552)
		(mid 39.771033 -381.397682)
		(end 39.868602 -381.54356)
		(width 0.14224)
		(layer "In6.Cu")
		(net "P5E_CPU1_P0_TX_DP<0>")
	)
	(arc
		(start 40.220646 -381.895604)
		(mid 40.422953 -382.030781)
		(end 40.66159 -382.07823)
		(width 0.14224)
		(layer "In6.Cu")
		(net "P5E_CPU1_P0_TX_DP<0>")
	)
	(arc
		(start 72.390508 -356.414578)
		(mid 71.998048 -356.295517)
		(end 71.5899 -356.25532)
		(width 0.14224)
		(layer "In6.Cu")
		(net "P5E_CPU1_P0_TX_DP<0>")
	)
	(arc
		(start 114.272314 -346.835984)
		(mid 114.050992 -347.207088)
		(end 113.732818 -347.499432)
		(width 0.14224)
		(layer "In6.Cu")
		(net "P5E_CPU1_P0_TX_DP<0>")
	)
	(arc
		(start 97.259902 -290.792154)
		(mid 97.415729 -291.096192)
		(end 97.259902 -291.40023)
		(width 0.1143)
		(layer "In6.Cu")
		(net "P5E_CPU1_P0_TX_DP<0>")
	)
	(arc
		(start 112.38865 -326.25538)
		(mid 112.426275 -326.306165)
		(end 112.4585 -326.360536)
		(width 0.14224)
		(layer "In6.Cu")
		(net "P5E_CPU1_P0_TX_DP<0>")
	)
	(arc
		(start 97.885758 -283.806392)
		(mid 97.844503 -283.977363)
		(end 97.729802 -284.110684)
		(width 0.1143)
		(layer "In6.Cu")
		(net "P5E_CPU1_P0_TX_DP<0>")
	)
	(arc
		(start 100.09378 -356.629208)
		(mid 99.553173 -356.885376)
		(end 98.961448 -356.973378)
		(width 0.14224)
		(layer "In6.Cu")
		(net "P5E_CPU1_P0_TX_DP<0>")
	)
	(arc
		(start 40.40759 -373.306594)
		(mid 40.286245 -373.765105)
		(end 40.108886 -374.204992)
		(width 0.14224)
		(layer "In6.Cu")
		(net "P5E_CPU1_P0_TX_DP<0>")
	)
	(arc
		(start 97.259902 -292.412166)
		(mid 97.415729 -292.716204)
		(end 97.259902 -293.020242)
		(width 0.1143)
		(layer "In6.Cu")
		(net "P5E_CPU1_P0_TX_DP<0>")
	)
	(arc
		(start 40.778176 -367.747042)
		(mid 40.703552 -367.837315)
		(end 40.647366 -367.940082)
		(width 0.14224)
		(layer "In6.Cu")
		(net "P5E_CPU1_P0_TX_DP<0>")
	)
	(arc
		(start 114.820192 -330.874116)
		(mid 114.847289 -330.931209)
		(end 114.869976 -330.990194)
		(width 0.14224)
		(layer "In6.Cu")
		(net "P5E_CPU1_P0_TX_DP<0>")
	)
	(arc
		(start 97.259902 -294.032178)
		(mid 97.415729 -294.336216)
		(end 97.259902 -294.640254)
		(width 0.1143)
		(layer "In6.Cu")
		(net "P5E_CPU1_P0_TX_DP<0>")
	)
	(arc
		(start 97.190306 -291.440616)
		(mid 96.945485 -291.906303)
		(end 97.19056 -292.37178)
		(width 0.1143)
		(layer "In6.Cu")
		(net "P5E_CPU1_P0_TX_DP<0>")
	)
	(arc
		(start 116.535454 -339.212174)
		(mid 116.544126 -339.26648)
		(end 116.550186 -339.32114)
		(width 0.14224)
		(layer "In6.Cu")
		(net "P5E_CPU1_P0_TX_DP<0>")
	)
	(arc
		(start 100.99167 -310.655208)
		(mid 101.030654 -310.737457)
		(end 101.077522 -310.815482)
		(width 0.14224)
		(layer "In6.Cu")
		(net "P5E_CPU1_P0_TX_DP<0>")
	)
	(arc
		(start 97.189036 -284.961838)
		(mid 97.010223 -285.164188)
		(end 96.945704 -285.426404)
		(width 0.1143)
		(layer "In6.Cu")
		(net "P5E_CPU1_P0_TX_DP<0>")
	)
	(arc
		(start 98.12909 -283.341826)
		(mid 97.950277 -283.544176)
		(end 97.885758 -283.806392)
		(width 0.1143)
		(layer "In6.Cu")
		(net "P5E_CPU1_P0_TX_DP<0>")
	)
	(arc
		(start 40.108886 -374.204992)
		(mid 39.83098 -375.005234)
		(end 39.736776 -375.847102)
		(width 0.14224)
		(layer "In6.Cu")
		(net "P5E_CPU1_P0_TX_DP<0>")
	)
	(arc
		(start 97.19056 -294.68064)
		(mid 97.017394 -294.870809)
		(end 96.946466 -295.118028)
		(width 0.1143)
		(layer "In6.Cu")
		(net "P5E_CPU1_P0_TX_DP<0>")
	)
	(segment
		(start 59.194954 -369.03533)
		(end 58.924444 -369.30584)
		(width 0.12954)
		(layer "F.Cu")
		(net "P5E_CPU1_P0_TX_DN<9>")
	)
	(segment
		(start 58.924444 -370.00942)
		(end 59.220354 -370.30533)
		(width 0.12954)
		(layer "F.Cu")
		(net "P5E_CPU1_P0_TX_DN<9>")
	)
	(segment
		(start 58.924444 -369.30584)
		(end 58.924444 -370.00942)
		(width 0.12954)
		(layer "F.Cu")
		(net "P5E_CPU1_P0_TX_DN<9>")
	)
	(segment
		(start 105.027984 -282.730448)
		(end 104.561132 -282.996386)
		(width 0.12954)
		(layer "F.Cu")
		(net "P5E_CPU1_P0_TX_DN<9>")
	)
	(segment
		(start 105.352342 -285.891478)
		(end 105.304082 -285.919672)
		(width 0.1143)
		(layer "In6.Cu")
		(net "P5E_CPU1_P0_TX_DN<9>")
	)
	(segment
		(start 108.91647 -306.716684)
		(end 113.537238 -313.632596)
		(width 0.14224)
		(layer "In6.Cu")
		(net "P5E_CPU1_P0_TX_DN<9>")
	)
	(segment
		(start 105.75163 -288.969958)
		(end 105.7529 -288.97072)
		(width 0.1143)
		(layer "In6.Cu")
		(net "P5E_CPU1_P0_TX_DN<9>")
	)
	(segment
		(start 104.812084 -284.11043)
		(end 104.88168 -284.150816)
		(width 0.1143)
		(layer "In6.Cu")
		(net "P5E_CPU1_P0_TX_DN<9>")
	)
	(segment
		(start 121.1961 -353.158298)
		(end 102.706678 -365.533686)
		(width 0.14224)
		(layer "In6.Cu")
		(net "P5E_CPU1_P0_TX_DN<9>")
	)
	(segment
		(start 125.164088 -345.023948)
		(end 122.405902 -351.68332)
		(width 0.14224)
		(layer "In6.Cu")
		(net "P5E_CPU1_P0_TX_DN<9>")
	)
	(segment
		(start 65.360042 -365.132874)
		(end 59.635644 -367.504218)
		(width 0.14224)
		(layer "In6.Cu")
		(net "P5E_CPU1_P0_TX_DN<9>")
	)
	(segment
		(start 105.292144 -286.546544)
		(end 105.292652 -286.546544)
		(width 0.1143)
		(layer "In6.Cu")
		(net "P5E_CPU1_P0_TX_DN<9>")
	)
	(segment
		(start 108.366814 -305.688492)
		(end 108.91647 -306.716684)
		(width 0.14224)
		(layer "In6.Cu")
		(net "P5E_CPU1_P0_TX_DN<9>")
	)
	(segment
		(start 104.342184 -283.300424)
		(end 104.411526 -283.34081)
		(width 0.1143)
		(layer "In6.Cu")
		(net "P5E_CPU1_P0_TX_DN<9>")
	)
	(segment
		(start 105.82148 -291.561774)
		(end 105.752138 -291.60216)
		(width 0.1143)
		(layer "In6.Cu")
		(net "P5E_CPU1_P0_TX_DN<9>")
	)
	(segment
		(start 59.530996 -367.574068)
		(end 58.951368 -368.153696)
		(width 0.14224)
		(layer "In6.Cu")
		(net "P5E_CPU1_P0_TX_DN<9>")
	)
	(segment
		(start 105.82148 -289.941762)
		(end 105.752138 -289.982148)
		(width 0.1143)
		(layer "In6.Cu")
		(net "P5E_CPU1_P0_TX_DN<9>")
	)
	(segment
		(start 105.304082 -285.919672)
		(end 105.303066 -285.92018)
		(width 0.1143)
		(layer "In6.Cu")
		(net "P5E_CPU1_P0_TX_DN<9>")
	)
	(segment
		(start 125.574806 -343.040208)
		(end 125.210316 -344.871294)
		(width 0.14224)
		(layer "In6.Cu")
		(net "P5E_CPU1_P0_TX_DN<9>")
	)
	(segment
		(start 105.284016 -284.921706)
		(end 105.352342 -284.96133)
		(width 0.1143)
		(layer "In6.Cu")
		(net "P5E_CPU1_P0_TX_DN<9>")
	)
	(segment
		(start 71.938896 -365.704374)
		(end 70.400672 -365.067342)
		(width 0.14224)
		(layer "In6.Cu")
		(net "P5E_CPU1_P0_TX_DN<9>")
	)
	(segment
		(start 105.263696 -298.196508)
		(end 108.366814 -305.688492)
		(width 0.14224)
		(layer "In6.Cu")
		(net "P5E_CPU1_P0_TX_DN<9>")
	)
	(segment
		(start 105.25379 -296.26306)
		(end 105.25379 -296.291508)
		(width 0.1143)
		(layer "In6.Cu")
		(net "P5E_CPU1_P0_TX_DN<9>")
	)
	(segment
		(start 119.748046 -321.244722)
		(end 123.38812 -328.207624)
		(width 0.14224)
		(layer "In6.Cu")
		(net "P5E_CPU1_P0_TX_DN<9>")
	)
	(segment
		(start 105.82148 -293.181786)
		(end 105.752138 -293.222172)
		(width 0.1143)
		(layer "In6.Cu")
		(net "P5E_CPU1_P0_TX_DN<9>")
	)
	(segment
		(start 70.400672 -365.067342)
		(end 65.689226 -365.067342)
		(width 0.14224)
		(layer "In6.Cu")
		(net "P5E_CPU1_P0_TX_DN<9>")
	)
	(segment
		(start 105.82148 -294.801798)
		(end 105.752138 -294.842184)
		(width 0.1143)
		(layer "In6.Cu")
		(net "P5E_CPU1_P0_TX_DN<9>")
	)
	(segment
		(start 58.904124 -368.7445)
		(end 59.194954 -369.03533)
		(width 0.14224)
		(layer "In6.Cu")
		(net "P5E_CPU1_P0_TX_DN<9>")
	)
	(segment
		(start 104.26319 -282.996386)
		(end 104.193086 -283.06649)
		(width 0.1143)
		(layer "In6.Cu")
		(net "P5E_CPU1_P0_TX_DN<9>")
	)
	(segment
		(start 105.25379 -296.291508)
		(end 105.25379 -298.14774)
		(width 0.14224)
		(layer "In6.Cu")
		(net "P5E_CPU1_P0_TX_DN<9>")
	)
	(segment
		(start 105.302812 -285.92018)
		(end 105.296716 -285.926276)
		(width 0.1143)
		(layer "In6.Cu")
		(net "P5E_CPU1_P0_TX_DN<9>")
	)
	(segment
		(start 105.752138 -290.590224)
		(end 105.821734 -290.63061)
		(width 0.1143)
		(layer "In6.Cu")
		(net "P5E_CPU1_P0_TX_DN<9>")
	)
	(segment
		(start 104.561132 -282.996386)
		(end 104.26319 -282.996386)
		(width 0.1143)
		(layer "In6.Cu")
		(net "P5E_CPU1_P0_TX_DN<9>")
	)
	(segment
		(start 105.296716 -285.926276)
		(end 105.292144 -285.926276)
		(width 0.1143)
		(layer "In6.Cu")
		(net "P5E_CPU1_P0_TX_DN<9>")
	)
	(segment
		(start 105.752138 -292.210236)
		(end 105.821734 -292.250622)
		(width 0.1143)
		(layer "In6.Cu")
		(net "P5E_CPU1_P0_TX_DN<9>")
	)
	(segment
		(start 105.303066 -285.92018)
		(end 105.302812 -285.92018)
		(width 0.1143)
		(layer "In6.Cu")
		(net "P5E_CPU1_P0_TX_DN<9>")
	)
	(segment
		(start 105.208324 -296.082974)
		(end 105.20807 -296.21734)
		(width 0.1143)
		(layer "In6.Cu")
		(net "P5E_CPU1_P0_TX_DN<9>")
	)
	(segment
		(start 105.7529 -288.97072)
		(end 105.788206 -288.994088)
		(width 0.1143)
		(layer "In6.Cu")
		(net "P5E_CPU1_P0_TX_DN<9>")
	)
	(segment
		(start 105.752138 -293.830248)
		(end 105.821734 -293.870634)
		(width 0.1143)
		(layer "In6.Cu")
		(net "P5E_CPU1_P0_TX_DN<9>")
	)
	(segment
		(start 101.88575 -365.783114)
		(end 72.335644 -365.783114)
		(width 0.14224)
		(layer "In6.Cu")
		(net "P5E_CPU1_P0_TX_DN<9>")
	)
	(segment
		(start 105.292652 -286.546544)
		(end 105.355136 -286.58312)
		(width 0.1143)
		(layer "In6.Cu")
		(net "P5E_CPU1_P0_TX_DN<9>")
	)
	(segment
		(start 123.67641 -329.234546)
		(end 125.703584 -340.52129)
		(width 0.14224)
		(layer "In6.Cu")
		(net "P5E_CPU1_P0_TX_DN<9>")
	)
	(segment
		(start 121.196354 -353.158298)
		(end 121.1961 -353.158298)
		(width 0.14224)
		(layer "In6.Cu")
		(net "P5E_CPU1_P0_TX_DN<9>")
	)
	(segment
		(start 58.904124 -368.267742)
		(end 58.904124 -368.7445)
		(width 0.14224)
		(layer "In6.Cu")
		(net "P5E_CPU1_P0_TX_DN<9>")
	)
	(segment
		(start 105.75417 -287.351724)
		(end 105.82148 -287.39084)
		(width 0.1143)
		(layer "In6.Cu")
		(net "P5E_CPU1_P0_TX_DN<9>")
	)
	(segment
		(start 105.823766 -288.320734)
		(end 105.752392 -288.362136)
		(width 0.1143)
		(layer "In6.Cu")
		(net "P5E_CPU1_P0_TX_DN<9>")
	)
	(segment
		(start 113.646712 -313.780424)
		(end 119.646446 -321.091052)
		(width 0.14224)
		(layer "In6.Cu")
		(net "P5E_CPU1_P0_TX_DN<9>")
	)
	(segment
		(start 105.20807 -296.21734)
		(end 105.25379 -296.26306)
		(width 0.1143)
		(layer "In6.Cu")
		(net "P5E_CPU1_P0_TX_DN<9>")
	)
	(arc
		(start 123.38812 -328.207624)
		(mid 123.426632 -328.291227)
		(end 123.456446 -328.378312)
		(width 0.14224)
		(layer "In6.Cu")
		(net "P5E_CPU1_P0_TX_DN<9>")
	)
	(arc
		(start 105.352342 -284.96133)
		(mid 105.596196 -285.426404)
		(end 105.352342 -285.891478)
		(width 0.1143)
		(layer "In6.Cu")
		(net "P5E_CPU1_P0_TX_DN<9>")
	)
	(arc
		(start 105.821734 -292.250622)
		(mid 106.066555 -292.716309)
		(end 105.82148 -293.181786)
		(width 0.1143)
		(layer "In6.Cu")
		(net "P5E_CPU1_P0_TX_DN<9>")
	)
	(arc
		(start 105.122472 -284.581092)
		(mid 105.124959 -284.603395)
		(end 105.126282 -284.625796)
		(width 0.1143)
		(layer "In6.Cu")
		(net "P5E_CPU1_P0_TX_DN<9>")
	)
	(arc
		(start 123.674378 -329.226164)
		(mid 123.675395 -329.230355)
		(end 123.67641 -329.234546)
		(width 0.14224)
		(layer "In6.Cu")
		(net "P5E_CPU1_P0_TX_DN<9>")
	)
	(arc
		(start 105.821734 -290.63061)
		(mid 106.066555 -291.096297)
		(end 105.82148 -291.561774)
		(width 0.1143)
		(layer "In6.Cu")
		(net "P5E_CPU1_P0_TX_DN<9>")
	)
	(arc
		(start 105.355136 -286.58312)
		(mid 105.532332 -286.785132)
		(end 105.596182 -287.046162)
		(width 0.1143)
		(layer "In6.Cu")
		(net "P5E_CPU1_P0_TX_DN<9>")
	)
	(arc
		(start 119.646446 -321.091052)
		(mid 119.70119 -321.165279)
		(end 119.748046 -321.244722)
		(width 0.14224)
		(layer "In6.Cu")
		(net "P5E_CPU1_P0_TX_DN<9>")
	)
	(arc
		(start 105.752392 -288.362136)
		(mid 105.596253 -288.665896)
		(end 105.75163 -288.969958)
		(width 0.1143)
		(layer "In6.Cu")
		(net "P5E_CPU1_P0_TX_DN<9>")
	)
	(arc
		(start 72.335644 -365.783114)
		(mid 72.133386 -365.763301)
		(end 71.938896 -365.704374)
		(width 0.14224)
		(layer "In6.Cu")
		(net "P5E_CPU1_P0_TX_DN<9>")
	)
	(arc
		(start 105.752138 -291.60216)
		(mid 105.596311 -291.906198)
		(end 105.752138 -292.210236)
		(width 0.1143)
		(layer "In6.Cu")
		(net "P5E_CPU1_P0_TX_DN<9>")
	)
	(arc
		(start 104.88168 -284.150816)
		(mid 105.042374 -284.343408)
		(end 105.122472 -284.581092)
		(width 0.1143)
		(layer "In6.Cu")
		(net "P5E_CPU1_P0_TX_DN<9>")
	)
	(arc
		(start 106.066082 -287.856422)
		(mid 106.001906 -288.118309)
		(end 105.823766 -288.320734)
		(width 0.1143)
		(layer "In6.Cu")
		(net "P5E_CPU1_P0_TX_DN<9>")
	)
	(arc
		(start 105.596182 -295.146222)
		(mid 105.535168 -295.453433)
		(end 105.361232 -295.713912)
		(width 0.1143)
		(layer "In6.Cu")
		(net "P5E_CPU1_P0_TX_DN<9>")
	)
	(arc
		(start 102.706678 -365.533686)
		(mid 102.31474 -365.71937)
		(end 101.88575 -365.783114)
		(width 0.14224)
		(layer "In6.Cu")
		(net "P5E_CPU1_P0_TX_DN<9>")
	)
	(arc
		(start 105.752138 -293.222172)
		(mid 105.596311 -293.52621)
		(end 105.752138 -293.830248)
		(width 0.1143)
		(layer "In6.Cu")
		(net "P5E_CPU1_P0_TX_DN<9>")
	)
	(arc
		(start 105.82148 -287.39084)
		(mid 106.001272 -287.593428)
		(end 106.066082 -287.856422)
		(width 0.1143)
		(layer "In6.Cu")
		(net "P5E_CPU1_P0_TX_DN<9>")
	)
	(arc
		(start 105.596182 -287.046162)
		(mid 105.638022 -287.218148)
		(end 105.75417 -287.351724)
		(width 0.1143)
		(layer "In6.Cu")
		(net "P5E_CPU1_P0_TX_DN<9>")
	)
	(arc
		(start 123.456446 -328.378312)
		(mid 123.57097 -328.800809)
		(end 123.674378 -329.226164)
		(width 0.14224)
		(layer "In6.Cu")
		(net "P5E_CPU1_P0_TX_DN<9>")
	)
	(arc
		(start 105.281222 -284.919928)
		(mid 105.282617 -284.92082)
		(end 105.284016 -284.921706)
		(width 0.1143)
		(layer "In6.Cu")
		(net "P5E_CPU1_P0_TX_DN<9>")
	)
	(arc
		(start 125.210316 -344.871294)
		(mid 125.190956 -344.948758)
		(end 125.164088 -345.023948)
		(width 0.14224)
		(layer "In6.Cu")
		(net "P5E_CPU1_P0_TX_DN<9>")
	)
	(arc
		(start 59.635644 -367.504218)
		(mid 59.579875 -367.533983)
		(end 59.530996 -367.574068)
		(width 0.14224)
		(layer "In6.Cu")
		(net "P5E_CPU1_P0_TX_DN<9>")
	)
	(arc
		(start 122.405902 -351.68332)
		(mid 121.910361 -352.510381)
		(end 121.196354 -353.158298)
		(width 0.14224)
		(layer "In6.Cu")
		(net "P5E_CPU1_P0_TX_DN<9>")
	)
	(arc
		(start 125.703584 -340.52129)
		(mid 125.715231 -340.601121)
		(end 125.721364 -340.681564)
		(width 0.14224)
		(layer "In6.Cu")
		(net "P5E_CPU1_P0_TX_DN<9>")
	)
	(arc
		(start 65.689226 -365.067342)
		(mid 65.521401 -365.083875)
		(end 65.360042 -365.132874)
		(width 0.14224)
		(layer "In6.Cu")
		(net "P5E_CPU1_P0_TX_DN<9>")
	)
	(arc
		(start 104.656636 -283.806392)
		(mid 104.697671 -283.977189)
		(end 104.812084 -284.11043)
		(width 0.1143)
		(layer "In6.Cu")
		(net "P5E_CPU1_P0_TX_DN<9>")
	)
	(arc
		(start 125.721364 -340.681564)
		(mid 125.703612 -341.864337)
		(end 125.574806 -343.040208)
		(width 0.14224)
		(layer "In6.Cu")
		(net "P5E_CPU1_P0_TX_DN<9>")
	)
	(arc
		(start 105.752138 -289.982148)
		(mid 105.596311 -290.286186)
		(end 105.752138 -290.590224)
		(width 0.1143)
		(layer "In6.Cu")
		(net "P5E_CPU1_P0_TX_DN<9>")
	)
	(arc
		(start 105.788206 -288.994088)
		(mid 106.064619 -289.458773)
		(end 105.82148 -289.941762)
		(width 0.1143)
		(layer "In6.Cu")
		(net "P5E_CPU1_P0_TX_DN<9>")
	)
	(arc
		(start 105.25379 -298.14774)
		(mid 105.25634 -298.172612)
		(end 105.263696 -298.196508)
		(width 0.14224)
		(layer "In6.Cu")
		(net "P5E_CPU1_P0_TX_DN<9>")
	)
	(arc
		(start 105.292144 -285.926276)
		(mid 105.113602 -286.23641)
		(end 105.292144 -286.546544)
		(width 0.1143)
		(layer "In6.Cu")
		(net "P5E_CPU1_P0_TX_DN<9>")
	)
	(arc
		(start 104.411526 -283.34081)
		(mid 104.591581 -283.543334)
		(end 104.656636 -283.806392)
		(width 0.1143)
		(layer "In6.Cu")
		(net "P5E_CPU1_P0_TX_DN<9>")
	)
	(arc
		(start 105.126282 -284.625796)
		(mid 105.169413 -284.790933)
		(end 105.281222 -284.919928)
		(width 0.1143)
		(layer "In6.Cu")
		(net "P5E_CPU1_P0_TX_DN<9>")
	)
	(arc
		(start 105.752138 -294.842184)
		(mid 105.637462 -294.975375)
		(end 105.596182 -295.146222)
		(width 0.1143)
		(layer "In6.Cu")
		(net "P5E_CPU1_P0_TX_DN<9>")
	)
	(arc
		(start 105.821734 -293.870634)
		(mid 106.066555 -294.336321)
		(end 105.82148 -294.801798)
		(width 0.1143)
		(layer "In6.Cu")
		(net "P5E_CPU1_P0_TX_DN<9>")
	)
	(arc
		(start 105.361232 -295.713912)
		(mid 105.248091 -295.883239)
		(end 105.208324 -296.082974)
		(width 0.1143)
		(layer "In6.Cu")
		(net "P5E_CPU1_P0_TX_DN<9>")
	)
	(arc
		(start 113.537238 -313.632596)
		(mid 113.590162 -313.707853)
		(end 113.646712 -313.780424)
		(width 0.14224)
		(layer "In6.Cu")
		(net "P5E_CPU1_P0_TX_DN<9>")
	)
	(arc
		(start 104.193086 -283.06649)
		(mid 104.245189 -283.197762)
		(end 104.342184 -283.300424)
		(width 0.1143)
		(layer "In6.Cu")
		(net "P5E_CPU1_P0_TX_DN<9>")
	)
	(arc
		(start 58.951368 -368.153696)
		(mid 58.916406 -368.206021)
		(end 58.904124 -368.267742)
		(width 0.14224)
		(layer "In6.Cu")
		(net "P5E_CPU1_P0_TX_DN<9>")
	)
	(segment
		(start 57.222644 -371.76964)
		(end 57.222644 -372.47322)
		(width 0.12954)
		(layer "F.Cu")
		(net "P5E_CPU1_P0_TX_DN<8>")
	)
	(segment
		(start 105.027984 -285.970472)
		(end 104.561132 -286.23641)
		(width 0.12954)
		(layer "F.Cu")
		(net "P5E_CPU1_P0_TX_DN<8>")
	)
	(segment
		(start 57.222644 -372.47322)
		(end 57.518554 -372.76913)
		(width 0.12954)
		(layer "F.Cu")
		(net "P5E_CPU1_P0_TX_DN<8>")
	)
	(segment
		(start 57.493154 -371.49913)
		(end 57.222644 -371.76964)
		(width 0.12954)
		(layer "F.Cu")
		(net "P5E_CPU1_P0_TX_DN<8>")
	)
	(segment
		(start 71.955406 -364.698788)
		(end 70.58914 -364.13313)
		(width 0.14224)
		(layer "In6.Cu")
		(net "P5E_CPU1_P0_TX_DN<8>")
	)
	(segment
		(start 104.842056 -293.2049)
		(end 104.812338 -293.221918)
		(width 0.1143)
		(layer "In6.Cu")
		(net "P5E_CPU1_P0_TX_DN<8>")
	)
	(segment
		(start 104.88041 -288.322766)
		(end 104.844088 -288.343848)
		(width 0.1143)
		(layer "In6.Cu")
		(net "P5E_CPU1_P0_TX_DN<8>")
	)
	(segment
		(start 107.764072 -306.696872)
		(end 112.733328 -314.134246)
		(width 0.14224)
		(layer "In6.Cu")
		(net "P5E_CPU1_P0_TX_DN<8>")
	)
	(segment
		(start 104.842056 -291.584888)
		(end 104.812338 -291.601906)
		(width 0.1143)
		(layer "In6.Cu")
		(net "P5E_CPU1_P0_TX_DN<8>")
	)
	(segment
		(start 104.843326 -292.22827)
		(end 104.844088 -292.228778)
		(width 0.1143)
		(layer "In6.Cu")
		(net "P5E_CPU1_P0_TX_DN<8>")
	)
	(segment
		(start 104.892602 -294.794178)
		(end 104.883204 -294.801036)
		(width 0.1143)
		(layer "In6.Cu")
		(net "P5E_CPU1_P0_TX_DN<8>")
	)
	(segment
		(start 104.883204 -294.801036)
		(end 104.812338 -294.842184)
		(width 0.1143)
		(layer "In6.Cu")
		(net "P5E_CPU1_P0_TX_DN<8>")
	)
	(segment
		(start 122.773186 -329.57135)
		(end 124.714254 -340.3727)
		(width 0.14224)
		(layer "In6.Cu")
		(net "P5E_CPU1_P0_TX_DN<8>")
	)
	(segment
		(start 104.844088 -290.608766)
		(end 104.88041 -290.629848)
		(width 0.1143)
		(layer "In6.Cu")
		(net "P5E_CPU1_P0_TX_DN<8>")
	)
	(segment
		(start 104.842056 -287.367472)
		(end 104.843326 -287.368234)
		(width 0.1143)
		(layer "In6.Cu")
		(net "P5E_CPU1_P0_TX_DN<8>")
	)
	(segment
		(start 123.96597 -345.083384)
		(end 121.442988 -351.173288)
		(width 0.14224)
		(layer "In6.Cu")
		(net "P5E_CPU1_P0_TX_DN<8>")
	)
	(segment
		(start 104.812338 -288.970466)
		(end 104.843326 -288.988246)
		(width 0.1143)
		(layer "In6.Cu")
		(net "P5E_CPU1_P0_TX_DN<8>")
	)
	(segment
		(start 104.812338 -290.590478)
		(end 104.843326 -290.608258)
		(width 0.1143)
		(layer "In6.Cu")
		(net "P5E_CPU1_P0_TX_DN<8>")
	)
	(segment
		(start 104.88041 -289.942524)
		(end 104.844088 -289.963606)
		(width 0.1143)
		(layer "In6.Cu")
		(net "P5E_CPU1_P0_TX_DN<8>")
	)
	(segment
		(start 104.844088 -287.368742)
		(end 104.843834 -287.368996)
		(width 0.1143)
		(layer "In6.Cu")
		(net "P5E_CPU1_P0_TX_DN<8>")
	)
	(segment
		(start 104.26319 -286.23641)
		(end 104.19334 -286.30626)
		(width 0.1143)
		(layer "In6.Cu")
		(net "P5E_CPU1_P0_TX_DN<8>")
	)
	(segment
		(start 104.271572 -296.158158)
		(end 104.317292 -296.203878)
		(width 0.1143)
		(layer "In6.Cu")
		(net "P5E_CPU1_P0_TX_DN<8>")
	)
	(segment
		(start 104.843326 -291.584126)
		(end 104.842056 -291.584888)
		(width 0.1143)
		(layer "In6.Cu")
		(net "P5E_CPU1_P0_TX_DN<8>")
	)
	(segment
		(start 104.459532 -295.675812)
		(end 104.350312 -295.785286)
		(width 0.1143)
		(layer "In6.Cu")
		(net "P5E_CPU1_P0_TX_DN<8>")
	)
	(segment
		(start 70.58914 -364.13313)
		(end 65.46469 -364.13313)
		(width 0.14224)
		(layer "In6.Cu")
		(net "P5E_CPU1_P0_TX_DN<8>")
	)
	(segment
		(start 104.844088 -288.343848)
		(end 104.81056 -288.363406)
		(width 0.1143)
		(layer "In6.Cu")
		(net "P5E_CPU1_P0_TX_DN<8>")
	)
	(segment
		(start 104.317292 -296.232326)
		(end 104.317292 -298.380912)
		(width 0.14224)
		(layer "In6.Cu")
		(net "P5E_CPU1_P0_TX_DN<8>")
	)
	(segment
		(start 104.373934 -286.558736)
		(end 104.41305 -286.581596)
		(width 0.1143)
		(layer "In6.Cu")
		(net "P5E_CPU1_P0_TX_DN<8>")
	)
	(segment
		(start 104.844088 -291.583618)
		(end 104.843326 -291.584126)
		(width 0.1143)
		(layer "In6.Cu")
		(net "P5E_CPU1_P0_TX_DN<8>")
	)
	(segment
		(start 104.844088 -293.20363)
		(end 104.843326 -293.204138)
		(width 0.1143)
		(layer "In6.Cu")
		(net "P5E_CPU1_P0_TX_DN<8>")
	)
	(segment
		(start 112.975644 -314.461398)
		(end 118.914164 -321.714622)
		(width 0.14224)
		(layer "In6.Cu")
		(net "P5E_CPU1_P0_TX_DN<8>")
	)
	(segment
		(start 104.317292 -296.203878)
		(end 104.317292 -296.232326)
		(width 0.1143)
		(layer "In6.Cu")
		(net "P5E_CPU1_P0_TX_DN<8>")
	)
	(segment
		(start 104.271572 -295.975024)
		(end 104.271572 -296.158158)
		(width 0.1143)
		(layer "In6.Cu")
		(net "P5E_CPU1_P0_TX_DN<8>")
	)
	(segment
		(start 120.216168 -352.67011)
		(end 102.406704 -364.590584)
		(width 0.14224)
		(layer "In6.Cu")
		(net "P5E_CPU1_P0_TX_DN<8>")
	)
	(segment
		(start 104.656382 -295.146222)
		(end 104.656382 -295.201594)
		(width 0.1143)
		(layer "In6.Cu")
		(net "P5E_CPU1_P0_TX_DN<8>")
	)
	(segment
		(start 104.341422 -286.53994)
		(end 104.373934 -286.558736)
		(width 0.1143)
		(layer "In6.Cu")
		(net "P5E_CPU1_P0_TX_DN<8>")
	)
	(segment
		(start 104.844088 -289.963606)
		(end 104.843326 -289.964114)
		(width 0.1143)
		(layer "In6.Cu")
		(net "P5E_CPU1_P0_TX_DN<8>")
	)
	(segment
		(start 104.812338 -287.350454)
		(end 104.842056 -287.367472)
		(width 0.1143)
		(layer "In6.Cu")
		(net "P5E_CPU1_P0_TX_DN<8>")
	)
	(segment
		(start 57.202324 -369.079526)
		(end 57.202324 -371.2083)
		(width 0.14224)
		(layer "In6.Cu")
		(net "P5E_CPU1_P0_TX_DN<8>")
	)
	(segment
		(start 101.621844 -364.828836)
		(end 72.608948 -364.828836)
		(width 0.14224)
		(layer "In6.Cu")
		(net "P5E_CPU1_P0_TX_DN<8>")
	)
	(segment
		(start 104.843326 -293.204138)
		(end 104.842056 -293.2049)
		(width 0.1143)
		(layer "In6.Cu")
		(net "P5E_CPU1_P0_TX_DN<8>")
	)
	(segment
		(start 57.202324 -371.2083)
		(end 57.493154 -371.49913)
		(width 0.14224)
		(layer "In6.Cu")
		(net "P5E_CPU1_P0_TX_DN<8>")
	)
	(segment
		(start 104.812338 -293.830502)
		(end 104.883204 -293.871396)
		(width 0.1143)
		(layer "In6.Cu")
		(net "P5E_CPU1_P0_TX_DN<8>")
	)
	(segment
		(start 104.561132 -286.23641)
		(end 104.26319 -286.23641)
		(width 0.1143)
		(layer "In6.Cu")
		(net "P5E_CPU1_P0_TX_DN<8>")
	)
	(segment
		(start 119.015256 -321.868292)
		(end 122.516392 -328.563224)
		(width 0.14224)
		(layer "In6.Cu")
		(net "P5E_CPU1_P0_TX_DN<8>")
	)
	(segment
		(start 104.812338 -292.21049)
		(end 104.843326 -292.22827)
		(width 0.1143)
		(layer "In6.Cu")
		(net "P5E_CPU1_P0_TX_DN<8>")
	)
	(segment
		(start 104.842056 -289.964876)
		(end 104.812338 -289.981894)
		(width 0.1143)
		(layer "In6.Cu")
		(net "P5E_CPU1_P0_TX_DN<8>")
	)
	(segment
		(start 104.843326 -289.964114)
		(end 104.842056 -289.964876)
		(width 0.1143)
		(layer "In6.Cu")
		(net "P5E_CPU1_P0_TX_DN<8>")
	)
	(segment
		(start 104.843326 -290.608258)
		(end 104.844088 -290.608766)
		(width 0.1143)
		(layer "In6.Cu")
		(net "P5E_CPU1_P0_TX_DN<8>")
	)
	(segment
		(start 104.88041 -293.182548)
		(end 104.844088 -293.20363)
		(width 0.1143)
		(layer "In6.Cu")
		(net "P5E_CPU1_P0_TX_DN<8>")
	)
	(segment
		(start 104.844088 -288.988754)
		(end 104.88041 -289.009836)
		(width 0.1143)
		(layer "In6.Cu")
		(net "P5E_CPU1_P0_TX_DN<8>")
	)
	(segment
		(start 59.000898 -366.780318)
		(end 57.384696 -368.39652)
		(width 0.14224)
		(layer "In6.Cu")
		(net "P5E_CPU1_P0_TX_DN<8>")
	)
	(segment
		(start 104.843834 -287.368996)
		(end 104.844596 -287.369504)
		(width 0.1143)
		(layer "In6.Cu")
		(net "P5E_CPU1_P0_TX_DN<8>")
	)
	(segment
		(start 57.323736 -368.50574)
		(end 57.217056 -368.95405)
		(width 0.14224)
		(layer "In6.Cu")
		(net "P5E_CPU1_P0_TX_DN<8>")
	)
	(segment
		(start 65.195958 -364.186724)
		(end 59.105546 -366.710468)
		(width 0.14224)
		(layer "In6.Cu")
		(net "P5E_CPU1_P0_TX_DN<8>")
	)
	(segment
		(start 104.843326 -288.988246)
		(end 104.844088 -288.988754)
		(width 0.1143)
		(layer "In6.Cu")
		(net "P5E_CPU1_P0_TX_DN<8>")
	)
	(segment
		(start 104.843326 -287.368234)
		(end 104.844088 -287.368742)
		(width 0.1143)
		(layer "In6.Cu")
		(net "P5E_CPU1_P0_TX_DN<8>")
	)
	(segment
		(start 104.883204 -293.871396)
		(end 104.892602 -293.878254)
		(width 0.1143)
		(layer "In6.Cu")
		(net "P5E_CPU1_P0_TX_DN<8>")
	)
	(segment
		(start 104.88041 -291.562536)
		(end 104.844088 -291.583618)
		(width 0.1143)
		(layer "In6.Cu")
		(net "P5E_CPU1_P0_TX_DN<8>")
	)
	(segment
		(start 104.844088 -292.228778)
		(end 104.88041 -292.24986)
		(width 0.1143)
		(layer "In6.Cu")
		(net "P5E_CPU1_P0_TX_DN<8>")
	)
	(segment
		(start 104.326944 -298.429426)
		(end 107.704382 -306.585366)
		(width 0.14224)
		(layer "In6.Cu")
		(net "P5E_CPU1_P0_TX_DN<8>")
	)
	(arc
		(start 118.914164 -321.714622)
		(mid 118.968641 -321.788871)
		(end 119.015256 -321.868292)
		(width 0.14224)
		(layer "In6.Cu")
		(net "P5E_CPU1_P0_TX_DN<8>")
	)
	(arc
		(start 57.384696 -368.39652)
		(mid 57.346664 -368.446909)
		(end 57.323736 -368.50574)
		(width 0.14224)
		(layer "In6.Cu")
		(net "P5E_CPU1_P0_TX_DN<8>")
	)
	(arc
		(start 104.656382 -287.046162)
		(mid 104.697637 -287.217133)
		(end 104.812338 -287.350454)
		(width 0.1143)
		(layer "In6.Cu")
		(net "P5E_CPU1_P0_TX_DN<8>")
	)
	(arc
		(start 59.105546 -366.710468)
		(mid 59.049777 -366.740233)
		(end 59.000898 -366.780318)
		(width 0.14224)
		(layer "In6.Cu")
		(net "P5E_CPU1_P0_TX_DN<8>")
	)
	(arc
		(start 104.81056 -288.363406)
		(mid 104.697153 -288.496295)
		(end 104.656382 -288.666174)
		(width 0.1143)
		(layer "In6.Cu")
		(net "P5E_CPU1_P0_TX_DN<8>")
	)
	(arc
		(start 104.896666 -289.021266)
		(mid 105.11955 -289.47618)
		(end 104.896666 -289.931094)
		(width 0.1143)
		(layer "In6.Cu")
		(net "P5E_CPU1_P0_TX_DN<8>")
	)
	(arc
		(start 104.894634 -292.259766)
		(mid 105.122017 -292.716204)
		(end 104.894634 -293.172642)
		(width 0.1143)
		(layer "In6.Cu")
		(net "P5E_CPU1_P0_TX_DN<8>")
	)
	(arc
		(start 124.714254 -340.3727)
		(mid 124.740004 -340.552478)
		(end 124.752862 -340.733634)
		(width 0.14224)
		(layer "In6.Cu")
		(net "P5E_CPU1_P0_TX_DN<8>")
	)
	(arc
		(start 104.812338 -289.981894)
		(mid 104.65641 -290.286186)
		(end 104.812338 -290.590478)
		(width 0.1143)
		(layer "In6.Cu")
		(net "P5E_CPU1_P0_TX_DN<8>")
	)
	(arc
		(start 104.722422 -294.933878)
		(mid 104.673338 -295.035047)
		(end 104.656382 -295.146222)
		(width 0.1143)
		(layer "In6.Cu")
		(net "P5E_CPU1_P0_TX_DN<8>")
	)
	(arc
		(start 104.812338 -294.842184)
		(mid 104.763428 -294.884155)
		(end 104.722422 -294.933878)
		(width 0.1143)
		(layer "In6.Cu")
		(net "P5E_CPU1_P0_TX_DN<8>")
	)
	(arc
		(start 104.88041 -290.629848)
		(mid 104.887559 -290.634748)
		(end 104.894634 -290.639754)
		(width 0.1143)
		(layer "In6.Cu")
		(net "P5E_CPU1_P0_TX_DN<8>")
	)
	(arc
		(start 122.584972 -328.737722)
		(mid 122.688306 -329.152453)
		(end 122.773186 -329.57135)
		(width 0.14224)
		(layer "In6.Cu")
		(net "P5E_CPU1_P0_TX_DN<8>")
	)
	(arc
		(start 105.126282 -287.856422)
		(mid 105.061046 -288.120013)
		(end 104.88041 -288.322766)
		(width 0.1143)
		(layer "In6.Cu")
		(net "P5E_CPU1_P0_TX_DN<8>")
	)
	(arc
		(start 112.733328 -314.134246)
		(mid 112.850519 -314.30076)
		(end 112.975644 -314.461398)
		(width 0.14224)
		(layer "In6.Cu")
		(net "P5E_CPU1_P0_TX_DN<8>")
	)
	(arc
		(start 102.406704 -364.590584)
		(mid 102.03196 -364.76798)
		(end 101.621844 -364.828836)
		(width 0.14224)
		(layer "In6.Cu")
		(net "P5E_CPU1_P0_TX_DN<8>")
	)
	(arc
		(start 121.442988 -351.173288)
		(mid 121.405397 -351.253763)
		(end 121.360692 -351.330514)
		(width 0.14224)
		(layer "In6.Cu")
		(net "P5E_CPU1_P0_TX_DN<8>")
	)
	(arc
		(start 104.892602 -293.878254)
		(mid 105.126255 -294.336216)
		(end 104.892602 -294.794178)
		(width 0.1143)
		(layer "In6.Cu")
		(net "P5E_CPU1_P0_TX_DN<8>")
	)
	(arc
		(start 104.656382 -295.201594)
		(mid 104.605119 -295.458279)
		(end 104.459532 -295.675812)
		(width 0.1143)
		(layer "In6.Cu")
		(net "P5E_CPU1_P0_TX_DN<8>")
	)
	(arc
		(start 104.350312 -295.785286)
		(mid 104.292038 -295.87231)
		(end 104.271572 -295.975024)
		(width 0.1143)
		(layer "In6.Cu")
		(net "P5E_CPU1_P0_TX_DN<8>")
	)
	(arc
		(start 104.88041 -292.24986)
		(mid 104.887559 -292.25476)
		(end 104.894634 -292.259766)
		(width 0.1143)
		(layer "In6.Cu")
		(net "P5E_CPU1_P0_TX_DN<8>")
	)
	(arc
		(start 104.844596 -287.369504)
		(mid 105.050818 -287.575148)
		(end 105.126282 -287.856422)
		(width 0.1143)
		(layer "In6.Cu")
		(net "P5E_CPU1_P0_TX_DN<8>")
	)
	(arc
		(start 104.812338 -293.221918)
		(mid 104.65641 -293.52621)
		(end 104.812338 -293.830502)
		(width 0.1143)
		(layer "In6.Cu")
		(net "P5E_CPU1_P0_TX_DN<8>")
	)
	(arc
		(start 104.896666 -289.931094)
		(mid 104.888588 -289.93688)
		(end 104.88041 -289.942524)
		(width 0.1143)
		(layer "In6.Cu")
		(net "P5E_CPU1_P0_TX_DN<8>")
	)
	(arc
		(start 104.894634 -291.55263)
		(mid 104.88756 -291.557637)
		(end 104.88041 -291.562536)
		(width 0.1143)
		(layer "In6.Cu")
		(net "P5E_CPU1_P0_TX_DN<8>")
	)
	(arc
		(start 122.516392 -328.563224)
		(mid 122.555398 -328.64862)
		(end 122.584972 -328.737722)
		(width 0.14224)
		(layer "In6.Cu")
		(net "P5E_CPU1_P0_TX_DN<8>")
	)
	(arc
		(start 104.656382 -288.666174)
		(mid 104.697637 -288.837145)
		(end 104.812338 -288.970466)
		(width 0.1143)
		(layer "In6.Cu")
		(net "P5E_CPU1_P0_TX_DN<8>")
	)
	(arc
		(start 65.46469 -364.13313)
		(mid 65.327681 -364.146679)
		(end 65.195958 -364.186724)
		(width 0.14224)
		(layer "In6.Cu")
		(net "P5E_CPU1_P0_TX_DN<8>")
	)
	(arc
		(start 107.704382 -306.585366)
		(mid 107.731478 -306.642591)
		(end 107.764072 -306.696872)
		(width 0.14224)
		(layer "In6.Cu")
		(net "P5E_CPU1_P0_TX_DN<8>")
	)
	(arc
		(start 104.812338 -291.601906)
		(mid 104.65641 -291.906198)
		(end 104.812338 -292.21049)
		(width 0.1143)
		(layer "In6.Cu")
		(net "P5E_CPU1_P0_TX_DN<8>")
	)
	(arc
		(start 104.894634 -290.639754)
		(mid 105.122017 -291.096192)
		(end 104.894634 -291.55263)
		(width 0.1143)
		(layer "In6.Cu")
		(net "P5E_CPU1_P0_TX_DN<8>")
	)
	(arc
		(start 104.19334 -286.30626)
		(mid 104.245048 -286.437243)
		(end 104.341422 -286.53994)
		(width 0.1143)
		(layer "In6.Cu")
		(net "P5E_CPU1_P0_TX_DN<8>")
	)
	(arc
		(start 124.752862 -340.733634)
		(mid 124.592823 -342.950732)
		(end 123.96597 -345.083384)
		(width 0.14224)
		(layer "In6.Cu")
		(net "P5E_CPU1_P0_TX_DN<8>")
	)
	(arc
		(start 104.317292 -298.380912)
		(mid 104.319728 -298.405644)
		(end 104.326944 -298.429426)
		(width 0.14224)
		(layer "In6.Cu")
		(net "P5E_CPU1_P0_TX_DN<8>")
	)
	(arc
		(start 72.608948 -364.828836)
		(mid 72.275775 -364.795983)
		(end 71.955406 -364.698788)
		(width 0.14224)
		(layer "In6.Cu")
		(net "P5E_CPU1_P0_TX_DN<8>")
	)
	(arc
		(start 121.360692 -351.330514)
		(mid 120.891826 -351.97336)
		(end 120.353328 -352.559112)
		(width 0.14224)
		(layer "In6.Cu")
		(net "P5E_CPU1_P0_TX_DN<8>")
	)
	(arc
		(start 104.41305 -286.581596)
		(mid 104.591863 -286.783946)
		(end 104.656382 -287.046162)
		(width 0.1143)
		(layer "In6.Cu")
		(net "P5E_CPU1_P0_TX_DN<8>")
	)
	(arc
		(start 104.894634 -293.172642)
		(mid 104.88756 -293.177649)
		(end 104.88041 -293.182548)
		(width 0.1143)
		(layer "In6.Cu")
		(net "P5E_CPU1_P0_TX_DN<8>")
	)
	(arc
		(start 57.217056 -368.95405)
		(mid 57.206021 -369.016357)
		(end 57.202324 -369.079526)
		(width 0.14224)
		(layer "In6.Cu")
		(net "P5E_CPU1_P0_TX_DN<8>")
	)
	(arc
		(start 104.88041 -289.009836)
		(mid 104.888588 -289.015479)
		(end 104.896666 -289.021266)
		(width 0.1143)
		(layer "In6.Cu")
		(net "P5E_CPU1_P0_TX_DN<8>")
	)
	(arc
		(start 120.353328 -352.559112)
		(mid 120.287243 -352.617694)
		(end 120.216168 -352.67011)
		(width 0.14224)
		(layer "In6.Cu")
		(net "P5E_CPU1_P0_TX_DN<8>")
	)
	(segment
		(start 55.520844 -374.23344)
		(end 55.520844 -374.93702)
		(width 0.12954)
		(layer "F.Cu")
		(net "P5E_CPU1_P0_TX_DN<7>")
	)
	(segment
		(start 105.027984 -284.35046)
		(end 104.561132 -284.616398)
		(width 0.12954)
		(layer "F.Cu")
		(net "P5E_CPU1_P0_TX_DN<7>")
	)
	(segment
		(start 55.520844 -374.93702)
		(end 55.816754 -375.23293)
		(width 0.12954)
		(layer "F.Cu")
		(net "P5E_CPU1_P0_TX_DN<7>")
	)
	(segment
		(start 55.791354 -373.96293)
		(end 55.520844 -374.23344)
		(width 0.12954)
		(layer "F.Cu")
		(net "P5E_CPU1_P0_TX_DN<7>")
	)
	(segment
		(start 123.626118 -342.449404)
		(end 123.305316 -344.064336)
		(width 0.14224)
		(layer "In6.Cu")
		(net "P5E_CPU1_P0_TX_DN<7>")
	)
	(segment
		(start 72.06107 -363.719364)
		(end 70.830948 -363.209586)
		(width 0.14224)
		(layer "In6.Cu")
		(net "P5E_CPU1_P0_TX_DN<7>")
	)
	(segment
		(start 119.039132 -352.310954)
		(end 102.111556 -363.622336)
		(width 0.14224)
		(layer "In6.Cu")
		(net "P5E_CPU1_P0_TX_DN<7>")
	)
	(segment
		(start 64.833754 -363.31271)
		(end 58.542936 -365.91875)
		(width 0.14224)
		(layer "In6.Cu")
		(net "P5E_CPU1_P0_TX_DN<7>")
	)
	(segment
		(start 103.904034 -287.368742)
		(end 103.94061 -287.390078)
		(width 0.1143)
		(layer "In6.Cu")
		(net "P5E_CPU1_P0_TX_DN<7>")
	)
	(segment
		(start 57.783984 -366.677702)
		(end 57.555638 -366.77219)
		(width 0.14224)
		(layer "In6.Cu")
		(net "P5E_CPU1_P0_TX_DN<7>")
	)
	(segment
		(start 103.872284 -292.21049)
		(end 103.904034 -292.228778)
		(width 0.1143)
		(layer "In6.Cu")
		(net "P5E_CPU1_P0_TX_DN<7>")
	)
	(segment
		(start 103.90505 -294.823134)
		(end 103.904034 -294.823642)
		(width 0.1143)
		(layer "In6.Cu")
		(net "P5E_CPU1_P0_TX_DN<7>")
	)
	(segment
		(start 103.872284 -287.350454)
		(end 103.904034 -287.368742)
		(width 0.1143)
		(layer "In6.Cu")
		(net "P5E_CPU1_P0_TX_DN<7>")
	)
	(segment
		(start 103.256334 -295.924986)
		(end 103.256334 -296.20718)
		(width 0.1143)
		(layer "In6.Cu")
		(net "P5E_CPU1_P0_TX_DN<7>")
	)
	(segment
		(start 103.94315 -285.080964)
		(end 103.904034 -285.103824)
		(width 0.1143)
		(layer "In6.Cu")
		(net "P5E_CPU1_P0_TX_DN<7>")
	)
	(segment
		(start 103.88346 -288.355532)
		(end 103.882698 -288.35604)
		(width 0.1143)
		(layer "In6.Cu")
		(net "P5E_CPU1_P0_TX_DN<7>")
	)
	(segment
		(start 103.94315 -294.800782)
		(end 103.90505 -294.823134)
		(width 0.1143)
		(layer "In6.Cu")
		(net "P5E_CPU1_P0_TX_DN<7>")
	)
	(segment
		(start 103.872284 -285.122112)
		(end 103.868474 -285.124906)
		(width 0.1143)
		(layer "In6.Cu")
		(net "P5E_CPU1_P0_TX_DN<7>")
	)
	(segment
		(start 103.434134 -286.558736)
		(end 103.470456 -286.579818)
		(width 0.1143)
		(layer "In6.Cu")
		(net "P5E_CPU1_P0_TX_DN<7>")
	)
	(segment
		(start 103.716328 -295.146222)
		(end 103.716328 -295.166034)
		(width 0.1143)
		(layer "In6.Cu")
		(net "P5E_CPU1_P0_TX_DN<7>")
	)
	(segment
		(start 103.94315 -288.320988)
		(end 103.937562 -288.323782)
		(width 0.1143)
		(layer "In6.Cu")
		(net "P5E_CPU1_P0_TX_DN<7>")
	)
	(segment
		(start 103.470456 -285.892748)
		(end 103.434134 -285.91383)
		(width 0.1143)
		(layer "In6.Cu")
		(net "P5E_CPU1_P0_TX_DN<7>")
	)
	(segment
		(start 103.581454 -295.54678)
		(end 103.293418 -295.83507)
		(width 0.1143)
		(layer "In6.Cu")
		(net "P5E_CPU1_P0_TX_DN<7>")
	)
	(segment
		(start 103.434134 -285.91383)
		(end 103.433372 -285.914338)
		(width 0.1143)
		(layer "In6.Cu")
		(net "P5E_CPU1_P0_TX_DN<7>")
	)
	(segment
		(start 103.904034 -292.228778)
		(end 103.94315 -292.251638)
		(width 0.1143)
		(layer "In6.Cu")
		(net "P5E_CPU1_P0_TX_DN<7>")
	)
	(segment
		(start 103.882698 -288.976308)
		(end 103.942388 -289.011106)
		(width 0.1143)
		(layer "In6.Cu")
		(net "P5E_CPU1_P0_TX_DN<7>")
	)
	(segment
		(start 106.928666 -307.15204)
		(end 112.383316 -315.314838)
		(width 0.14224)
		(layer "In6.Cu")
		(net "P5E_CPU1_P0_TX_DN<7>")
	)
	(segment
		(start 103.904034 -293.20363)
		(end 103.872284 -293.221918)
		(width 0.1143)
		(layer "In6.Cu")
		(net "P5E_CPU1_P0_TX_DN<7>")
	)
	(segment
		(start 103.302054 -296.2529)
		(end 103.302054 -296.281348)
		(width 0.1143)
		(layer "In6.Cu")
		(net "P5E_CPU1_P0_TX_DN<7>")
	)
	(segment
		(start 104.561132 -284.616398)
		(end 104.26319 -284.616398)
		(width 0.1143)
		(layer "In6.Cu")
		(net "P5E_CPU1_P0_TX_DN<7>")
	)
	(segment
		(start 70.78218 -363.199934)
		(end 65.401444 -363.199934)
		(width 0.14224)
		(layer "In6.Cu")
		(net "P5E_CPU1_P0_TX_DN<7>")
	)
	(segment
		(start 103.903272 -294.82415)
		(end 103.872284 -294.84193)
		(width 0.1143)
		(layer "In6.Cu")
		(net "P5E_CPU1_P0_TX_DN<7>")
	)
	(segment
		(start 103.904034 -285.103824)
		(end 103.872284 -285.122112)
		(width 0.1143)
		(layer "In6.Cu")
		(net "P5E_CPU1_P0_TX_DN<7>")
	)
	(segment
		(start 112.383316 -315.314838)
		(end 118.247414 -322.460366)
		(width 0.14224)
		(layer "In6.Cu")
		(net "P5E_CPU1_P0_TX_DN<7>")
	)
	(segment
		(start 103.313738 -298.423584)
		(end 106.928666 -307.15204)
		(width 0.14224)
		(layer "In6.Cu")
		(net "P5E_CPU1_P0_TX_DN<7>")
	)
	(segment
		(start 55.547768 -373.719344)
		(end 55.791354 -373.96293)
		(width 0.14224)
		(layer "In6.Cu")
		(net "P5E_CPU1_P0_TX_DN<7>")
	)
	(segment
		(start 103.302054 -296.281348)
		(end 103.302054 -298.365926)
		(width 0.14224)
		(layer "In6.Cu")
		(net "P5E_CPU1_P0_TX_DN<7>")
	)
	(segment
		(start 120.794018 -350.172528)
		(end 120.794018 -350.172782)
		(width 0.14224)
		(layer "In6.Cu")
		(net "P5E_CPU1_P0_TX_DN<7>")
	)
	(segment
		(start 103.94315 -291.560758)
		(end 103.904034 -291.583618)
		(width 0.1143)
		(layer "In6.Cu")
		(net "P5E_CPU1_P0_TX_DN<7>")
	)
	(segment
		(start 103.904034 -290.608766)
		(end 103.94315 -290.631626)
		(width 0.1143)
		(layer "In6.Cu")
		(net "P5E_CPU1_P0_TX_DN<7>")
	)
	(segment
		(start 103.904034 -293.84879)
		(end 103.94315 -293.87165)
		(width 0.1143)
		(layer "In6.Cu")
		(net "P5E_CPU1_P0_TX_DN<7>")
	)
	(segment
		(start 103.904034 -291.583618)
		(end 103.872284 -291.601906)
		(width 0.1143)
		(layer "In6.Cu")
		(net "P5E_CPU1_P0_TX_DN<7>")
	)
	(segment
		(start 103.904034 -289.963606)
		(end 103.872284 -289.981894)
		(width 0.1143)
		(layer "In6.Cu")
		(net "P5E_CPU1_P0_TX_DN<7>")
	)
	(segment
		(start 58.542936 -365.91875)
		(end 57.783984 -366.677702)
		(width 0.14224)
		(layer "In6.Cu")
		(net "P5E_CPU1_P0_TX_DN<7>")
	)
	(segment
		(start 103.937562 -288.323782)
		(end 103.88346 -288.355532)
		(width 0.1143)
		(layer "In6.Cu")
		(net "P5E_CPU1_P0_TX_DN<7>")
	)
	(segment
		(start 103.716328 -285.421832)
		(end 103.716328 -285.426404)
		(width 0.1143)
		(layer "In6.Cu")
		(net "P5E_CPU1_P0_TX_DN<7>")
	)
	(segment
		(start 103.872284 -293.830502)
		(end 103.904034 -293.84879)
		(width 0.1143)
		(layer "In6.Cu")
		(net "P5E_CPU1_P0_TX_DN<7>")
	)
	(segment
		(start 103.94315 -293.18077)
		(end 103.904034 -293.20363)
		(width 0.1143)
		(layer "In6.Cu")
		(net "P5E_CPU1_P0_TX_DN<7>")
	)
	(segment
		(start 104.26319 -284.616398)
		(end 104.180386 -284.699202)
		(width 0.1143)
		(layer "In6.Cu")
		(net "P5E_CPU1_P0_TX_DN<7>")
	)
	(segment
		(start 103.882698 -288.35604)
		(end 103.882444 -288.35604)
		(width 0.1143)
		(layer "In6.Cu")
		(net "P5E_CPU1_P0_TX_DN<7>")
	)
	(segment
		(start 103.88219 -288.976308)
		(end 103.882698 -288.976308)
		(width 0.1143)
		(layer "In6.Cu")
		(net "P5E_CPU1_P0_TX_DN<7>")
	)
	(segment
		(start 101.315774 -363.863636)
		(end 72.787256 -363.863636)
		(width 0.14224)
		(layer "In6.Cu")
		(net "P5E_CPU1_P0_TX_DN<7>")
	)
	(segment
		(start 103.400606 -286.539178)
		(end 103.434134 -286.558736)
		(width 0.1143)
		(layer "In6.Cu")
		(net "P5E_CPU1_P0_TX_DN<7>")
	)
	(segment
		(start 103.94315 -289.940746)
		(end 103.904034 -289.963606)
		(width 0.1143)
		(layer "In6.Cu")
		(net "P5E_CPU1_P0_TX_DN<7>")
	)
	(segment
		(start 103.904034 -294.823642)
		(end 103.903272 -294.82415)
		(width 0.1143)
		(layer "In6.Cu")
		(net "P5E_CPU1_P0_TX_DN<7>")
	)
	(segment
		(start 121.857008 -329.79868)
		(end 123.591066 -339.447378)
		(width 0.14224)
		(layer "In6.Cu")
		(net "P5E_CPU1_P0_TX_DN<7>")
	)
	(segment
		(start 103.432102 -285.9151)
		(end 103.402384 -285.932118)
		(width 0.1143)
		(layer "In6.Cu")
		(net "P5E_CPU1_P0_TX_DN<7>")
	)
	(segment
		(start 123.252484 -344.238326)
		(end 120.794018 -350.172528)
		(width 0.14224)
		(layer "In6.Cu")
		(net "P5E_CPU1_P0_TX_DN<7>")
	)
	(segment
		(start 103.872284 -290.590478)
		(end 103.904034 -290.608766)
		(width 0.1143)
		(layer "In6.Cu")
		(net "P5E_CPU1_P0_TX_DN<7>")
	)
	(segment
		(start 103.433372 -285.914338)
		(end 103.432102 -285.9151)
		(width 0.1143)
		(layer "In6.Cu")
		(net "P5E_CPU1_P0_TX_DN<7>")
	)
	(segment
		(start 103.256334 -296.20718)
		(end 103.302054 -296.2529)
		(width 0.1143)
		(layer "In6.Cu")
		(net "P5E_CPU1_P0_TX_DN<7>")
	)
	(segment
		(start 118.349268 -322.61429)
		(end 121.602246 -328.839322)
		(width 0.14224)
		(layer "In6.Cu")
		(net "P5E_CPU1_P0_TX_DN<7>")
	)
	(segment
		(start 55.500524 -369.847368)
		(end 55.500524 -373.605298)
		(width 0.14224)
		(layer "In6.Cu")
		(net "P5E_CPU1_P0_TX_DN<7>")
	)
	(arc
		(start 104.186482 -287.856422)
		(mid 104.121967 -288.118641)
		(end 103.94315 -288.320988)
		(width 0.1143)
		(layer "In6.Cu")
		(net "P5E_CPU1_P0_TX_DN<7>")
	)
	(arc
		(start 103.716328 -285.426404)
		(mid 103.716338 -285.429706)
		(end 103.716328 -285.433008)
		(width 0.1143)
		(layer "In6.Cu")
		(net "P5E_CPU1_P0_TX_DN<7>")
	)
	(arc
		(start 121.670318 -329.007978)
		(mid 121.774319 -329.400813)
		(end 121.857008 -329.79868)
		(width 0.14224)
		(layer "In6.Cu")
		(net "P5E_CPU1_P0_TX_DN<7>")
	)
	(arc
		(start 123.305316 -344.064336)
		(mid 123.28317 -344.152627)
		(end 123.252484 -344.238326)
		(width 0.14224)
		(layer "In6.Cu")
		(net "P5E_CPU1_P0_TX_DN<7>")
	)
	(arc
		(start 123.591066 -339.447378)
		(mid 123.720463 -340.873184)
		(end 123.64974 -342.3031)
		(width 0.14224)
		(layer "In6.Cu")
		(net "P5E_CPU1_P0_TX_DN<7>")
	)
	(arc
		(start 103.872284 -294.84193)
		(mid 103.759476 -294.976212)
		(end 103.716328 -295.146222)
		(width 0.1143)
		(layer "In6.Cu")
		(net "P5E_CPU1_P0_TX_DN<7>")
	)
	(arc
		(start 103.872284 -289.981894)
		(mid 103.718343 -290.286186)
		(end 103.872284 -290.590478)
		(width 0.1143)
		(layer "In6.Cu")
		(net "P5E_CPU1_P0_TX_DN<7>")
	)
	(arc
		(start 103.94315 -289.011614)
		(mid 104.186477 -289.47618)
		(end 103.94315 -289.940746)
		(width 0.1143)
		(layer "In6.Cu")
		(net "P5E_CPU1_P0_TX_DN<7>")
	)
	(arc
		(start 103.942388 -289.011106)
		(mid 103.942769 -289.01136)
		(end 103.94315 -289.011614)
		(width 0.1143)
		(layer "In6.Cu")
		(net "P5E_CPU1_P0_TX_DN<7>")
	)
	(arc
		(start 103.882444 -288.35604)
		(mid 103.703902 -288.666064)
		(end 103.88219 -288.976308)
		(width 0.1143)
		(layer "In6.Cu")
		(net "P5E_CPU1_P0_TX_DN<7>")
	)
	(arc
		(start 103.716328 -285.433008)
		(mid 103.651456 -285.68275)
		(end 103.486712 -285.881318)
		(width 0.1143)
		(layer "In6.Cu")
		(net "P5E_CPU1_P0_TX_DN<7>")
	)
	(arc
		(start 103.94315 -292.251638)
		(mid 104.186477 -292.716204)
		(end 103.94315 -293.18077)
		(width 0.1143)
		(layer "In6.Cu")
		(net "P5E_CPU1_P0_TX_DN<7>")
	)
	(arc
		(start 70.830948 -363.209586)
		(mid 70.807038 -363.202374)
		(end 70.78218 -363.199934)
		(width 0.14224)
		(layer "In6.Cu")
		(net "P5E_CPU1_P0_TX_DN<7>")
	)
	(arc
		(start 55.500524 -373.605298)
		(mid 55.512801 -373.667021)
		(end 55.547768 -373.719344)
		(width 0.14224)
		(layer "In6.Cu")
		(net "P5E_CPU1_P0_TX_DN<7>")
	)
	(arc
		(start 103.716328 -295.166034)
		(mid 103.710872 -295.257244)
		(end 103.694484 -295.347136)
		(width 0.1143)
		(layer "In6.Cu")
		(net "P5E_CPU1_P0_TX_DN<7>")
	)
	(arc
		(start 118.247414 -322.460366)
		(mid 118.302306 -322.534704)
		(end 118.349268 -322.61429)
		(width 0.14224)
		(layer "In6.Cu")
		(net "P5E_CPU1_P0_TX_DN<7>")
	)
	(arc
		(start 123.64974 -342.3031)
		(mid 123.639334 -342.376479)
		(end 123.626118 -342.449404)
		(width 0.14224)
		(layer "In6.Cu")
		(net "P5E_CPU1_P0_TX_DN<7>")
	)
	(arc
		(start 121.602246 -328.839322)
		(mid 121.640424 -328.921978)
		(end 121.670318 -329.007978)
		(width 0.14224)
		(layer "In6.Cu")
		(net "P5E_CPU1_P0_TX_DN<7>")
	)
	(arc
		(start 103.694484 -295.347136)
		(mid 103.651625 -295.454689)
		(end 103.581454 -295.54678)
		(width 0.1143)
		(layer "In6.Cu")
		(net "P5E_CPU1_P0_TX_DN<7>")
	)
	(arc
		(start 103.293418 -295.83507)
		(mid 103.26599 -295.876353)
		(end 103.256334 -295.924986)
		(width 0.1143)
		(layer "In6.Cu")
		(net "P5E_CPU1_P0_TX_DN<7>")
	)
	(arc
		(start 103.716328 -287.046162)
		(mid 103.759388 -287.216217)
		(end 103.872284 -287.350454)
		(width 0.1143)
		(layer "In6.Cu")
		(net "P5E_CPU1_P0_TX_DN<7>")
	)
	(arc
		(start 120.794018 -350.172782)
		(mid 120.075146 -351.372014)
		(end 119.039132 -352.310954)
		(width 0.14224)
		(layer "In6.Cu")
		(net "P5E_CPU1_P0_TX_DN<7>")
	)
	(arc
		(start 103.486712 -285.881318)
		(mid 103.478634 -285.887104)
		(end 103.470456 -285.892748)
		(width 0.1143)
		(layer "In6.Cu")
		(net "P5E_CPU1_P0_TX_DN<7>")
	)
	(arc
		(start 102.111556 -363.622336)
		(mid 101.731559 -363.801985)
		(end 101.315774 -363.863636)
		(width 0.14224)
		(layer "In6.Cu")
		(net "P5E_CPU1_P0_TX_DN<7>")
	)
	(arc
		(start 104.176576 -284.722062)
		(mid 104.095143 -284.92446)
		(end 103.94315 -285.080964)
		(width 0.1143)
		(layer "In6.Cu")
		(net "P5E_CPU1_P0_TX_DN<7>")
	)
	(arc
		(start 103.246428 -286.23641)
		(mid 103.28719 -286.406294)
		(end 103.400606 -286.539178)
		(width 0.1143)
		(layer "In6.Cu")
		(net "P5E_CPU1_P0_TX_DN<7>")
	)
	(arc
		(start 103.94315 -293.87165)
		(mid 104.186477 -294.336216)
		(end 103.94315 -294.800782)
		(width 0.1143)
		(layer "In6.Cu")
		(net "P5E_CPU1_P0_TX_DN<7>")
	)
	(arc
		(start 65.401444 -363.199934)
		(mid 65.112037 -363.228339)
		(end 64.833754 -363.31271)
		(width 0.14224)
		(layer "In6.Cu")
		(net "P5E_CPU1_P0_TX_DN<7>")
	)
	(arc
		(start 104.180386 -284.699202)
		(mid 104.178598 -284.710651)
		(end 104.176576 -284.722062)
		(width 0.1143)
		(layer "In6.Cu")
		(net "P5E_CPU1_P0_TX_DN<7>")
	)
	(arc
		(start 103.94315 -290.631626)
		(mid 104.186477 -291.096192)
		(end 103.94315 -291.560758)
		(width 0.1143)
		(layer "In6.Cu")
		(net "P5E_CPU1_P0_TX_DN<7>")
	)
	(arc
		(start 103.470456 -286.579818)
		(mid 103.651108 -286.782563)
		(end 103.716328 -287.046162)
		(width 0.1143)
		(layer "In6.Cu")
		(net "P5E_CPU1_P0_TX_DN<7>")
	)
	(arc
		(start 57.555638 -366.77219)
		(mid 56.061628 -367.998043)
		(end 55.500524 -369.847368)
		(width 0.14224)
		(layer "In6.Cu")
		(net "P5E_CPU1_P0_TX_DN<7>")
	)
	(arc
		(start 103.872284 -293.221918)
		(mid 103.721899 -293.52621)
		(end 103.872284 -293.830502)
		(width 0.1143)
		(layer "In6.Cu")
		(net "P5E_CPU1_P0_TX_DN<7>")
	)
	(arc
		(start 103.402384 -285.932118)
		(mid 103.287708 -286.065452)
		(end 103.246428 -286.23641)
		(width 0.1143)
		(layer "In6.Cu")
		(net "P5E_CPU1_P0_TX_DN<7>")
	)
	(arc
		(start 103.868474 -285.124906)
		(mid 103.756564 -285.255009)
		(end 103.716328 -285.421832)
		(width 0.1143)
		(layer "In6.Cu")
		(net "P5E_CPU1_P0_TX_DN<7>")
	)
	(arc
		(start 103.872284 -291.601906)
		(mid 103.720695 -291.906198)
		(end 103.872284 -292.21049)
		(width 0.1143)
		(layer "In6.Cu")
		(net "P5E_CPU1_P0_TX_DN<7>")
	)
	(arc
		(start 72.787256 -363.863636)
		(mid 72.417054 -363.827276)
		(end 72.06107 -363.719364)
		(width 0.14224)
		(layer "In6.Cu")
		(net "P5E_CPU1_P0_TX_DN<7>")
	)
	(arc
		(start 103.94061 -287.390078)
		(mid 104.121262 -287.592823)
		(end 104.186482 -287.856422)
		(width 0.1143)
		(layer "In6.Cu")
		(net "P5E_CPU1_P0_TX_DN<7>")
	)
	(arc
		(start 103.302054 -298.365926)
		(mid 103.305049 -298.395333)
		(end 103.313738 -298.423584)
		(width 0.14224)
		(layer "In6.Cu")
		(net "P5E_CPU1_P0_TX_DN<7>")
	)
	(segment
		(start 52.117244 -369.30584)
		(end 52.117244 -370.00942)
		(width 0.12954)
		(layer "F.Cu")
		(net "P5E_CPU1_P0_TX_DN<6>")
	)
	(segment
		(start 52.387754 -369.03533)
		(end 52.117244 -369.30584)
		(width 0.12954)
		(layer "F.Cu")
		(net "P5E_CPU1_P0_TX_DN<6>")
	)
	(segment
		(start 102.207822 -281.110436)
		(end 101.74097 -281.376374)
		(width 0.12954)
		(layer "F.Cu")
		(net "P5E_CPU1_P0_TX_DN<6>")
	)
	(segment
		(start 52.117244 -370.00942)
		(end 52.413154 -370.30533)
		(width 0.12954)
		(layer "F.Cu")
		(net "P5E_CPU1_P0_TX_DN<6>")
	)
	(segment
		(start 102.934262 -287.351724)
		(end 103.001572 -287.39084)
		(width 0.1143)
		(layer "In6.Cu")
		(net "P5E_CPU1_P0_TX_DN<6>")
	)
	(segment
		(start 102.492048 -285.9151)
		(end 102.490524 -285.915862)
		(width 0.1143)
		(layer "In6.Cu")
		(net "P5E_CPU1_P0_TX_DN<6>")
	)
	(segment
		(start 101.74097 -281.376374)
		(end 101.443028 -281.376374)
		(width 0.1143)
		(layer "In6.Cu")
		(net "P5E_CPU1_P0_TX_DN<6>")
	)
	(segment
		(start 111.804704 -316.102492)
		(end 111.804958 -316.102492)
		(width 0.14224)
		(layer "In6.Cu")
		(net "P5E_CPU1_P0_TX_DN<6>")
	)
	(segment
		(start 102.490524 -285.915862)
		(end 102.489254 -285.916624)
		(width 0.1143)
		(layer "In6.Cu")
		(net "P5E_CPU1_P0_TX_DN<6>")
	)
	(segment
		(start 120.944894 -330.0222)
		(end 122.5804 -339.12175)
		(width 0.14224)
		(layer "In6.Cu")
		(net "P5E_CPU1_P0_TX_DN<6>")
	)
	(segment
		(start 102.48265 -285.920688)
		(end 102.46233 -285.932118)
		(width 0.1143)
		(layer "In6.Cu")
		(net "P5E_CPU1_P0_TX_DN<6>")
	)
	(segment
		(start 102.49662 -285.912306)
		(end 102.495096 -285.913322)
		(width 0.1143)
		(layer "In6.Cu")
		(net "P5E_CPU1_P0_TX_DN<6>")
	)
	(segment
		(start 102.357174 -296.535348)
		(end 102.357174 -296.549826)
		(width 0.1143)
		(layer "In6.Cu")
		(net "P5E_CPU1_P0_TX_DN<6>")
	)
	(segment
		(start 102.93223 -290.590224)
		(end 103.001826 -290.63061)
		(width 0.1143)
		(layer "In6.Cu")
		(net "P5E_CPU1_P0_TX_DN<6>")
	)
	(segment
		(start 102.46233 -283.300678)
		(end 102.493318 -283.318458)
		(width 0.1143)
		(layer "In6.Cu")
		(net "P5E_CPU1_P0_TX_DN<6>")
	)
	(segment
		(start 102.493318 -285.914338)
		(end 102.492048 -285.9151)
		(width 0.1143)
		(layer "In6.Cu")
		(net "P5E_CPU1_P0_TX_DN<6>")
	)
	(segment
		(start 106.131868 -307.664358)
		(end 111.455708 -315.632338)
		(width 0.14224)
		(layer "In6.Cu")
		(net "P5E_CPU1_P0_TX_DN<6>")
	)
	(segment
		(start 102.93223 -293.830248)
		(end 103.001826 -293.870634)
		(width 0.1143)
		(layer "In6.Cu")
		(net "P5E_CPU1_P0_TX_DN<6>")
	)
	(segment
		(start 101.009704 -362.9279)
		(end 72.885554 -362.9279)
		(width 0.14224)
		(layer "In6.Cu")
		(net "P5E_CPU1_P0_TX_DN<6>")
	)
	(segment
		(start 118.485666 -351.468436)
		(end 101.660198 -362.730288)
		(width 0.14224)
		(layer "In6.Cu")
		(net "P5E_CPU1_P0_TX_DN<6>")
	)
	(segment
		(start 101.443028 -281.376374)
		(end 101.373178 -281.446224)
		(width 0.1143)
		(layer "In6.Cu")
		(net "P5E_CPU1_P0_TX_DN<6>")
	)
	(segment
		(start 64.791336 -362.3056)
		(end 58.044588 -365.093758)
		(width 0.14224)
		(layer "In6.Cu")
		(net "P5E_CPU1_P0_TX_DN<6>")
	)
	(segment
		(start 102.495096 -284.939486)
		(end 102.49662 -284.940502)
		(width 0.1143)
		(layer "In6.Cu")
		(net "P5E_CPU1_P0_TX_DN<6>")
	)
	(segment
		(start 101.553518 -281.700224)
		(end 101.559614 -281.70378)
		(width 0.1143)
		(layer "In6.Cu")
		(net "P5E_CPU1_P0_TX_DN<6>")
	)
	(segment
		(start 102.490524 -284.29585)
		(end 102.489254 -284.296612)
		(width 0.1143)
		(layer "In6.Cu")
		(net "P5E_CPU1_P0_TX_DN<6>")
	)
	(segment
		(start 102.533196 -285.89097)
		(end 102.49662 -285.912306)
		(width 0.1143)
		(layer "In6.Cu")
		(net "P5E_CPU1_P0_TX_DN<6>")
	)
	(segment
		(start 102.776274 -295.146222)
		(end 102.776274 -295.347644)
		(width 0.1143)
		(layer "In6.Cu")
		(net "P5E_CPU1_P0_TX_DN<6>")
	)
	(segment
		(start 102.49408 -284.938978)
		(end 102.495096 -284.939486)
		(width 0.1143)
		(layer "In6.Cu")
		(net "P5E_CPU1_P0_TX_DN<6>")
	)
	(segment
		(start 102.49408 -283.318966)
		(end 102.495096 -283.319474)
		(width 0.1143)
		(layer "In6.Cu")
		(net "P5E_CPU1_P0_TX_DN<6>")
	)
	(segment
		(start 103.001572 -294.801798)
		(end 102.93223 -294.842184)
		(width 0.1143)
		(layer "In6.Cu")
		(net "P5E_CPU1_P0_TX_DN<6>")
	)
	(segment
		(start 102.48265 -284.300676)
		(end 102.46233 -284.312106)
		(width 0.1143)
		(layer "In6.Cu")
		(net "P5E_CPU1_P0_TX_DN<6>")
	)
	(segment
		(start 102.357174 -296.549826)
		(end 102.357174 -298.491656)
		(width 0.14224)
		(layer "In6.Cu")
		(net "P5E_CPU1_P0_TX_DN<6>")
	)
	(segment
		(start 102.93223 -288.970212)
		(end 103.001826 -289.010598)
		(width 0.1143)
		(layer "In6.Cu")
		(net "P5E_CPU1_P0_TX_DN<6>")
	)
	(segment
		(start 103.001572 -293.181786)
		(end 102.93223 -293.222172)
		(width 0.1143)
		(layer "In6.Cu")
		(net "P5E_CPU1_P0_TX_DN<6>")
	)
	(segment
		(start 102.488492 -285.917132)
		(end 102.487222 -285.917894)
		(width 0.1143)
		(layer "In6.Cu")
		(net "P5E_CPU1_P0_TX_DN<6>")
	)
	(segment
		(start 111.804958 -316.102492)
		(end 117.472968 -323.009768)
		(width 0.14224)
		(layer "In6.Cu")
		(net "P5E_CPU1_P0_TX_DN<6>")
	)
	(segment
		(start 102.381812 -298.6151)
		(end 106.120184 -307.64226)
		(width 0.14224)
		(layer "In6.Cu")
		(net "P5E_CPU1_P0_TX_DN<6>")
	)
	(segment
		(start 102.48519 -285.919164)
		(end 102.48265 -285.920688)
		(width 0.1143)
		(layer "In6.Cu")
		(net "P5E_CPU1_P0_TX_DN<6>")
	)
	(segment
		(start 102.495096 -284.29331)
		(end 102.49408 -284.293818)
		(width 0.1143)
		(layer "In6.Cu")
		(net "P5E_CPU1_P0_TX_DN<6>")
	)
	(segment
		(start 52.096924 -368.7445)
		(end 52.387754 -369.03533)
		(width 0.14224)
		(layer "In6.Cu")
		(net "P5E_CPU1_P0_TX_DN<6>")
	)
	(segment
		(start 102.311454 -296.071544)
		(end 102.311454 -296.489628)
		(width 0.1143)
		(layer "In6.Cu")
		(net "P5E_CPU1_P0_TX_DN<6>")
	)
	(segment
		(start 70.851268 -362.257086)
		(end 65.035176 -362.257086)
		(width 0.14224)
		(layer "In6.Cu")
		(net "P5E_CPU1_P0_TX_DN<6>")
	)
	(segment
		(start 102.49662 -284.940502)
		(end 102.533196 -284.961838)
		(width 0.1143)
		(layer "In6.Cu")
		(net "P5E_CPU1_P0_TX_DN<6>")
	)
	(segment
		(start 102.46233 -284.92069)
		(end 102.49408 -284.938978)
		(width 0.1143)
		(layer "In6.Cu")
		(net "P5E_CPU1_P0_TX_DN<6>")
	)
	(segment
		(start 102.49408 -285.91383)
		(end 102.493318 -285.914338)
		(width 0.1143)
		(layer "In6.Cu")
		(net "P5E_CPU1_P0_TX_DN<6>")
	)
	(segment
		(start 102.493318 -283.318458)
		(end 102.49408 -283.318966)
		(width 0.1143)
		(layer "In6.Cu")
		(net "P5E_CPU1_P0_TX_DN<6>")
	)
	(segment
		(start 102.533196 -284.270958)
		(end 102.49662 -284.292294)
		(width 0.1143)
		(layer "In6.Cu")
		(net "P5E_CPU1_P0_TX_DN<6>")
	)
	(segment
		(start 102.49662 -284.292294)
		(end 102.495096 -284.29331)
		(width 0.1143)
		(layer "In6.Cu")
		(net "P5E_CPU1_P0_TX_DN<6>")
	)
	(segment
		(start 102.495096 -283.319474)
		(end 102.49662 -283.32049)
		(width 0.1143)
		(layer "In6.Cu")
		(net "P5E_CPU1_P0_TX_DN<6>")
	)
	(segment
		(start 102.682802 -295.572434)
		(end 102.402132 -295.853358)
		(width 0.1143)
		(layer "In6.Cu")
		(net "P5E_CPU1_P0_TX_DN<6>")
	)
	(segment
		(start 102.492048 -284.295088)
		(end 102.490524 -284.29585)
		(width 0.1143)
		(layer "In6.Cu")
		(net "P5E_CPU1_P0_TX_DN<6>")
	)
	(segment
		(start 102.488492 -284.29712)
		(end 102.487222 -284.297882)
		(width 0.1143)
		(layer "In6.Cu")
		(net "P5E_CPU1_P0_TX_DN<6>")
	)
	(segment
		(start 102.93223 -292.210236)
		(end 103.001826 -292.250622)
		(width 0.1143)
		(layer "In6.Cu")
		(net "P5E_CPU1_P0_TX_DN<6>")
	)
	(segment
		(start 64.79159 -362.3056)
		(end 64.791336 -362.3056)
		(width 0.14224)
		(layer "In6.Cu")
		(net "P5E_CPU1_P0_TX_DN<6>")
	)
	(segment
		(start 57.261506 -365.87684)
		(end 52.377848 -367.900204)
		(width 0.14224)
		(layer "In6.Cu")
		(net "P5E_CPU1_P0_TX_DN<6>")
	)
	(segment
		(start 102.493318 -284.294326)
		(end 102.492048 -284.295088)
		(width 0.1143)
		(layer "In6.Cu")
		(net "P5E_CPU1_P0_TX_DN<6>")
	)
	(segment
		(start 103.001572 -291.561774)
		(end 102.93223 -291.60216)
		(width 0.1143)
		(layer "In6.Cu")
		(net "P5E_CPU1_P0_TX_DN<6>")
	)
	(segment
		(start 103.003858 -288.320734)
		(end 102.932484 -288.362136)
		(width 0.1143)
		(layer "In6.Cu")
		(net "P5E_CPU1_P0_TX_DN<6>")
	)
	(segment
		(start 103.001572 -289.941762)
		(end 102.93223 -289.982148)
		(width 0.1143)
		(layer "In6.Cu")
		(net "P5E_CPU1_P0_TX_DN<6>")
	)
	(segment
		(start 102.489254 -284.296612)
		(end 102.488492 -284.29712)
		(width 0.1143)
		(layer "In6.Cu")
		(net "P5E_CPU1_P0_TX_DN<6>")
	)
	(segment
		(start 117.554248 -323.149722)
		(end 120.695212 -329.158854)
		(width 0.14224)
		(layer "In6.Cu")
		(net "P5E_CPU1_P0_TX_DN<6>")
	)
	(segment
		(start 102.489254 -285.916624)
		(end 102.488492 -285.917132)
		(width 0.1143)
		(layer "In6.Cu")
		(net "P5E_CPU1_P0_TX_DN<6>")
	)
	(segment
		(start 102.495096 -285.913322)
		(end 102.49408 -285.91383)
		(width 0.1143)
		(layer "In6.Cu")
		(net "P5E_CPU1_P0_TX_DN<6>")
	)
	(segment
		(start 121.971308 -344.768932)
		(end 119.921528 -349.717614)
		(width 0.14224)
		(layer "In6.Cu")
		(net "P5E_CPU1_P0_TX_DN<6>")
	)
	(segment
		(start 102.49408 -284.293818)
		(end 102.493318 -284.294326)
		(width 0.1143)
		(layer "In6.Cu")
		(net "P5E_CPU1_P0_TX_DN<6>")
	)
	(segment
		(start 102.311454 -296.489628)
		(end 102.357174 -296.535348)
		(width 0.1143)
		(layer "In6.Cu")
		(net "P5E_CPU1_P0_TX_DN<6>")
	)
	(segment
		(start 58.044588 -365.093758)
		(end 57.261506 -365.87684)
		(width 0.14224)
		(layer "In6.Cu")
		(net "P5E_CPU1_P0_TX_DN<6>")
	)
	(segment
		(start 102.49662 -283.32049)
		(end 102.497636 -283.320998)
		(width 0.1143)
		(layer "In6.Cu")
		(net "P5E_CPU1_P0_TX_DN<6>")
	)
	(segment
		(start 102.462076 -286.540448)
		(end 102.535228 -286.58312)
		(width 0.1143)
		(layer "In6.Cu")
		(net "P5E_CPU1_P0_TX_DN<6>")
	)
	(segment
		(start 106.131868 -307.664104)
		(end 106.131868 -307.664358)
		(width 0.14224)
		(layer "In6.Cu")
		(net "P5E_CPU1_P0_TX_DN<6>")
	)
	(segment
		(start 102.487222 -284.297882)
		(end 102.48519 -284.299152)
		(width 0.1143)
		(layer "In6.Cu")
		(net "P5E_CPU1_P0_TX_DN<6>")
	)
	(segment
		(start 52.096924 -368.365532)
		(end 52.096924 -368.7445)
		(width 0.14224)
		(layer "In6.Cu")
		(net "P5E_CPU1_P0_TX_DN<6>")
	)
	(segment
		(start 102.487222 -285.917894)
		(end 102.48519 -285.919164)
		(width 0.1143)
		(layer "In6.Cu")
		(net "P5E_CPU1_P0_TX_DN<6>")
	)
	(segment
		(start 72.331326 -362.817918)
		(end 71.094092 -362.3056)
		(width 0.14224)
		(layer "In6.Cu")
		(net "P5E_CPU1_P0_TX_DN<6>")
	)
	(segment
		(start 102.48519 -284.299152)
		(end 102.48265 -284.300676)
		(width 0.1143)
		(layer "In6.Cu")
		(net "P5E_CPU1_P0_TX_DN<6>")
	)
	(segment
		(start 101.993446 -282.49118)
		(end 102.063042 -282.53182)
		(width 0.1143)
		(layer "In6.Cu")
		(net "P5E_CPU1_P0_TX_DN<6>")
	)
	(segment
		(start 52.377848 -367.900204)
		(end 52.22748 -368.050572)
		(width 0.14224)
		(layer "In6.Cu")
		(net "P5E_CPU1_P0_TX_DN<6>")
	)
	(segment
		(start 102.497636 -283.320998)
		(end 102.533196 -283.341826)
		(width 0.1143)
		(layer "In6.Cu")
		(net "P5E_CPU1_P0_TX_DN<6>")
	)
	(arc
		(start 103.001826 -289.010598)
		(mid 103.246647 -289.476285)
		(end 103.001572 -289.941762)
		(width 0.1143)
		(layer "In6.Cu")
		(net "P5E_CPU1_P0_TX_DN<6>")
	)
	(arc
		(start 120.83034 -329.505818)
		(mid 120.892852 -329.762848)
		(end 120.944894 -330.0222)
		(width 0.14224)
		(layer "In6.Cu")
		(net "P5E_CPU1_P0_TX_DN<6>")
	)
	(arc
		(start 103.246174 -287.856422)
		(mid 103.181998 -288.118309)
		(end 103.003858 -288.320734)
		(width 0.1143)
		(layer "In6.Cu")
		(net "P5E_CPU1_P0_TX_DN<6>")
	)
	(arc
		(start 102.93223 -294.842184)
		(mid 102.817554 -294.975375)
		(end 102.776274 -295.146222)
		(width 0.1143)
		(layer "In6.Cu")
		(net "P5E_CPU1_P0_TX_DN<6>")
	)
	(arc
		(start 52.22748 -368.050572)
		(mid 52.130871 -368.195063)
		(end 52.096924 -368.365532)
		(width 0.14224)
		(layer "In6.Cu")
		(net "P5E_CPU1_P0_TX_DN<6>")
	)
	(arc
		(start 120.695212 -329.158854)
		(mid 120.772358 -329.328604)
		(end 120.83034 -329.505818)
		(width 0.14224)
		(layer "In6.Cu")
		(net "P5E_CPU1_P0_TX_DN<6>")
	)
	(arc
		(start 72.885554 -362.9279)
		(mid 72.603029 -362.900182)
		(end 72.331326 -362.817918)
		(width 0.14224)
		(layer "In6.Cu")
		(net "P5E_CPU1_P0_TX_DN<6>")
	)
	(arc
		(start 102.776274 -287.046162)
		(mid 102.818114 -287.218148)
		(end 102.934262 -287.351724)
		(width 0.1143)
		(layer "In6.Cu")
		(net "P5E_CPU1_P0_TX_DN<6>")
	)
	(arc
		(start 102.357174 -298.491656)
		(mid 102.363428 -298.554587)
		(end 102.381812 -298.6151)
		(width 0.14224)
		(layer "In6.Cu")
		(net "P5E_CPU1_P0_TX_DN<6>")
	)
	(arc
		(start 103.001826 -290.63061)
		(mid 103.246647 -291.096297)
		(end 103.001572 -291.561774)
		(width 0.1143)
		(layer "In6.Cu")
		(net "P5E_CPU1_P0_TX_DN<6>")
	)
	(arc
		(start 106.120184 -307.64226)
		(mid 106.125485 -307.653472)
		(end 106.131868 -307.664104)
		(width 0.14224)
		(layer "In6.Cu")
		(net "P5E_CPU1_P0_TX_DN<6>")
	)
	(arc
		(start 102.776274 -295.347644)
		(mid 102.75195 -295.46937)
		(end 102.682802 -295.572434)
		(width 0.1143)
		(layer "In6.Cu")
		(net "P5E_CPU1_P0_TX_DN<6>")
	)
	(arc
		(start 102.46233 -285.932118)
		(mid 102.306191 -286.236233)
		(end 102.462076 -286.540448)
		(width 0.1143)
		(layer "In6.Cu")
		(net "P5E_CPU1_P0_TX_DN<6>")
	)
	(arc
		(start 102.063042 -282.53182)
		(mid 102.241855 -282.73417)
		(end 102.306374 -282.996386)
		(width 0.1143)
		(layer "In6.Cu")
		(net "P5E_CPU1_P0_TX_DN<6>")
	)
	(arc
		(start 102.46233 -284.312106)
		(mid 102.306402 -284.616398)
		(end 102.46233 -284.92069)
		(width 0.1143)
		(layer "In6.Cu")
		(net "P5E_CPU1_P0_TX_DN<6>")
	)
	(arc
		(start 101.559614 -281.70378)
		(mid 101.762341 -281.908193)
		(end 101.836474 -282.18638)
		(width 0.1143)
		(layer "In6.Cu")
		(net "P5E_CPU1_P0_TX_DN<6>")
	)
	(arc
		(start 102.533196 -284.961838)
		(mid 102.776523 -285.426404)
		(end 102.533196 -285.89097)
		(width 0.1143)
		(layer "In6.Cu")
		(net "P5E_CPU1_P0_TX_DN<6>")
	)
	(arc
		(start 117.472968 -323.009768)
		(mid 117.515142 -323.078854)
		(end 117.554248 -323.149722)
		(width 0.14224)
		(layer "In6.Cu")
		(net "P5E_CPU1_P0_TX_DN<6>")
	)
	(arc
		(start 119.921528 -349.717614)
		(mid 119.333246 -350.699343)
		(end 118.485666 -351.468436)
		(width 0.14224)
		(layer "In6.Cu")
		(net "P5E_CPU1_P0_TX_DN<6>")
	)
	(arc
		(start 102.306374 -282.996386)
		(mid 102.347629 -283.167357)
		(end 102.46233 -283.300678)
		(width 0.1143)
		(layer "In6.Cu")
		(net "P5E_CPU1_P0_TX_DN<6>")
	)
	(arc
		(start 65.035176 -362.257086)
		(mid 64.910989 -362.269328)
		(end 64.79159 -362.3056)
		(width 0.14224)
		(layer "In6.Cu")
		(net "P5E_CPU1_P0_TX_DN<6>")
	)
	(arc
		(start 103.001826 -293.870634)
		(mid 103.246647 -294.336321)
		(end 103.001572 -294.801798)
		(width 0.1143)
		(layer "In6.Cu")
		(net "P5E_CPU1_P0_TX_DN<6>")
	)
	(arc
		(start 101.660198 -362.730288)
		(mid 101.349629 -362.877411)
		(end 101.009704 -362.9279)
		(width 0.14224)
		(layer "In6.Cu")
		(net "P5E_CPU1_P0_TX_DN<6>")
	)
	(arc
		(start 101.836474 -282.18638)
		(mid 101.878023 -282.357802)
		(end 101.993446 -282.49118)
		(width 0.1143)
		(layer "In6.Cu")
		(net "P5E_CPU1_P0_TX_DN<6>")
	)
	(arc
		(start 103.001826 -292.250622)
		(mid 103.246647 -292.716309)
		(end 103.001572 -293.181786)
		(width 0.1143)
		(layer "In6.Cu")
		(net "P5E_CPU1_P0_TX_DN<6>")
	)
	(arc
		(start 102.93223 -293.222172)
		(mid 102.776403 -293.52621)
		(end 102.93223 -293.830248)
		(width 0.1143)
		(layer "In6.Cu")
		(net "P5E_CPU1_P0_TX_DN<6>")
	)
	(arc
		(start 102.932484 -288.362136)
		(mid 102.776551 -288.666071)
		(end 102.93223 -288.970212)
		(width 0.1143)
		(layer "In6.Cu")
		(net "P5E_CPU1_P0_TX_DN<6>")
	)
	(arc
		(start 102.533196 -283.341826)
		(mid 102.776523 -283.806392)
		(end 102.533196 -284.270958)
		(width 0.1143)
		(layer "In6.Cu")
		(net "P5E_CPU1_P0_TX_DN<6>")
	)
	(arc
		(start 71.094092 -362.3056)
		(mid 70.975068 -362.269396)
		(end 70.851268 -362.257086)
		(width 0.14224)
		(layer "In6.Cu")
		(net "P5E_CPU1_P0_TX_DN<6>")
	)
	(arc
		(start 102.535228 -286.58312)
		(mid 102.712424 -286.785132)
		(end 102.776274 -287.046162)
		(width 0.1143)
		(layer "In6.Cu")
		(net "P5E_CPU1_P0_TX_DN<6>")
	)
	(arc
		(start 122.5804 -339.12175)
		(mid 122.681337 -341.989077)
		(end 121.971308 -344.768932)
		(width 0.14224)
		(layer "In6.Cu")
		(net "P5E_CPU1_P0_TX_DN<6>")
	)
	(arc
		(start 103.001572 -287.39084)
		(mid 103.181364 -287.593428)
		(end 103.246174 -287.856422)
		(width 0.1143)
		(layer "In6.Cu")
		(net "P5E_CPU1_P0_TX_DN<6>")
	)
	(arc
		(start 102.93223 -291.60216)
		(mid 102.776403 -291.906198)
		(end 102.93223 -292.210236)
		(width 0.1143)
		(layer "In6.Cu")
		(net "P5E_CPU1_P0_TX_DN<6>")
	)
	(arc
		(start 101.373178 -281.446224)
		(mid 101.435529 -281.592987)
		(end 101.553518 -281.700224)
		(width 0.1143)
		(layer "In6.Cu")
		(net "P5E_CPU1_P0_TX_DN<6>")
	)
	(arc
		(start 102.402132 -295.853358)
		(mid 102.335108 -295.953433)
		(end 102.311454 -296.071544)
		(width 0.1143)
		(layer "In6.Cu")
		(net "P5E_CPU1_P0_TX_DN<6>")
	)
	(arc
		(start 111.455708 -315.632338)
		(mid 111.624385 -315.871736)
		(end 111.804704 -316.102492)
		(width 0.14224)
		(layer "In6.Cu")
		(net "P5E_CPU1_P0_TX_DN<6>")
	)
	(arc
		(start 102.93223 -289.982148)
		(mid 102.776403 -290.286186)
		(end 102.93223 -290.590224)
		(width 0.1143)
		(layer "In6.Cu")
		(net "P5E_CPU1_P0_TX_DN<6>")
	)
	(segment
		(start 50.415444 -371.76964)
		(end 50.415444 -372.47322)
		(width 0.12954)
		(layer "F.Cu")
		(net "P5E_CPU1_P0_TX_DN<5>")
	)
	(segment
		(start 50.415444 -372.47322)
		(end 50.711354 -372.76913)
		(width 0.12954)
		(layer "F.Cu")
		(net "P5E_CPU1_P0_TX_DN<5>")
	)
	(segment
		(start 50.685954 -371.49913)
		(end 50.415444 -371.76964)
		(width 0.12954)
		(layer "F.Cu")
		(net "P5E_CPU1_P0_TX_DN<5>")
	)
	(segment
		(start 102.207822 -285.970472)
		(end 101.74097 -286.23641)
		(width 0.12954)
		(layer "F.Cu")
		(net "P5E_CPU1_P0_TX_DN<5>")
	)
	(segment
		(start 57.52973 -364.287562)
		(end 56.745378 -365.07166)
		(width 0.14224)
		(layer "In6.Cu")
		(net "P5E_CPU1_P0_TX_DN<5>")
	)
	(segment
		(start 101.366574 -295.9354)
		(end 101.366574 -296.389298)
		(width 0.1143)
		(layer "In6.Cu")
		(net "P5E_CPU1_P0_TX_DN<5>")
	)
	(segment
		(start 101.444298 -298.809918)
		(end 105.265982 -308.036214)
		(width 0.14224)
		(layer "In6.Cu")
		(net "P5E_CPU1_P0_TX_DN<5>")
	)
	(segment
		(start 101.993446 -292.210998)
		(end 102.063042 -292.251638)
		(width 0.1143)
		(layer "In6.Cu")
		(net "P5E_CPU1_P0_TX_DN<5>")
	)
	(segment
		(start 102.063042 -291.560758)
		(end 101.993446 -291.601398)
		(width 0.1143)
		(layer "In6.Cu")
		(net "P5E_CPU1_P0_TX_DN<5>")
	)
	(segment
		(start 116.760498 -323.648832)
		(end 119.845836 -329.551284)
		(width 0.14224)
		(layer "In6.Cu")
		(net "P5E_CPU1_P0_TX_DN<5>")
	)
	(segment
		(start 101.993446 -290.590986)
		(end 102.063042 -290.631626)
		(width 0.1143)
		(layer "In6.Cu")
		(net "P5E_CPU1_P0_TX_DN<5>")
	)
	(segment
		(start 101.443028 -286.23641)
		(end 101.373178 -286.30626)
		(width 0.1143)
		(layer "In6.Cu")
		(net "P5E_CPU1_P0_TX_DN<5>")
	)
	(segment
		(start 101.412294 -296.463466)
		(end 101.412294 -298.648882)
		(width 0.14224)
		(layer "In6.Cu")
		(net "P5E_CPU1_P0_TX_DN<5>")
	)
	(segment
		(start 101.548692 -295.636188)
		(end 101.449632 -295.735502)
		(width 0.1143)
		(layer "In6.Cu")
		(net "P5E_CPU1_P0_TX_DN<5>")
	)
	(segment
		(start 101.993446 -288.970974)
		(end 102.063042 -289.011614)
		(width 0.1143)
		(layer "In6.Cu")
		(net "P5E_CPU1_P0_TX_DN<5>")
	)
	(segment
		(start 101.993446 -287.350962)
		(end 102.060502 -287.390078)
		(width 0.1143)
		(layer "In6.Cu")
		(net "P5E_CPU1_P0_TX_DN<5>")
	)
	(segment
		(start 117.880638 -350.734122)
		(end 101.325934 -361.814618)
		(width 0.14224)
		(layer "In6.Cu")
		(net "P5E_CPU1_P0_TX_DN<5>")
	)
	(segment
		(start 72.449944 -361.846622)
		(end 71.307198 -361.37342)
		(width 0.14224)
		(layer "In6.Cu")
		(net "P5E_CPU1_P0_TX_DN<5>")
	)
	(segment
		(start 102.063042 -289.940746)
		(end 101.993446 -289.981386)
		(width 0.1143)
		(layer "In6.Cu")
		(net "P5E_CPU1_P0_TX_DN<5>")
	)
	(segment
		(start 64.508126 -361.398312)
		(end 57.52973 -364.287562)
		(width 0.14224)
		(layer "In6.Cu")
		(net "P5E_CPU1_P0_TX_DN<5>")
	)
	(segment
		(start 101.412294 -296.435018)
		(end 101.412294 -296.463466)
		(width 0.1143)
		(layer "In6.Cu")
		(net "P5E_CPU1_P0_TX_DN<5>")
	)
	(segment
		(start 101.366574 -296.389298)
		(end 101.412294 -296.435018)
		(width 0.1143)
		(layer "In6.Cu")
		(net "P5E_CPU1_P0_TX_DN<5>")
	)
	(segment
		(start 101.556058 -295.632124)
		(end 101.548692 -295.636188)
		(width 0.1143)
		(layer "In6.Cu")
		(net "P5E_CPU1_P0_TX_DN<5>")
	)
	(segment
		(start 102.023926 -288.343848)
		(end 101.991414 -288.362644)
		(width 0.1143)
		(layer "In6.Cu")
		(net "P5E_CPU1_P0_TX_DN<5>")
	)
	(segment
		(start 64.50838 -361.398312)
		(end 64.508126 -361.398312)
		(width 0.14224)
		(layer "In6.Cu")
		(net "P5E_CPU1_P0_TX_DN<5>")
	)
	(segment
		(start 100.808282 -361.971844)
		(end 73.07961 -361.971844)
		(width 0.14224)
		(layer "In6.Cu")
		(net "P5E_CPU1_P0_TX_DN<5>")
	)
	(segment
		(start 121.125234 -344.336878)
		(end 119.08282 -349.268034)
		(width 0.14224)
		(layer "In6.Cu")
		(net "P5E_CPU1_P0_TX_DN<5>")
	)
	(segment
		(start 101.74097 -286.23641)
		(end 101.443028 -286.23641)
		(width 0.1143)
		(layer "In6.Cu")
		(net "P5E_CPU1_P0_TX_DN<5>")
	)
	(segment
		(start 102.063042 -293.18077)
		(end 101.993446 -293.22141)
		(width 0.1143)
		(layer "In6.Cu")
		(net "P5E_CPU1_P0_TX_DN<5>")
	)
	(segment
		(start 120.009412 -330.15936)
		(end 121.662444 -339.35543)
		(width 0.14224)
		(layer "In6.Cu")
		(net "P5E_CPU1_P0_TX_DN<5>")
	)
	(segment
		(start 101.993446 -293.83101)
		(end 102.063042 -293.87165)
		(width 0.1143)
		(layer "In6.Cu")
		(net "P5E_CPU1_P0_TX_DN<5>")
	)
	(segment
		(start 50.395124 -369.142518)
		(end 50.395124 -371.2083)
		(width 0.14224)
		(layer "In6.Cu")
		(net "P5E_CPU1_P0_TX_DN<5>")
	)
	(segment
		(start 71.052944 -361.32262)
		(end 64.889126 -361.32262)
		(width 0.14224)
		(layer "In6.Cu")
		(net "P5E_CPU1_P0_TX_DN<5>")
	)
	(segment
		(start 105.301542 -308.103016)
		(end 110.750858 -316.257178)
		(width 0.14224)
		(layer "In6.Cu")
		(net "P5E_CPU1_P0_TX_DN<5>")
	)
	(segment
		(start 101.520498 -286.539178)
		(end 101.593142 -286.581596)
		(width 0.1143)
		(layer "In6.Cu")
		(net "P5E_CPU1_P0_TX_DN<5>")
	)
	(segment
		(start 102.063042 -288.320988)
		(end 102.023926 -288.343848)
		(width 0.1143)
		(layer "In6.Cu")
		(net "P5E_CPU1_P0_TX_DN<5>")
	)
	(segment
		(start 50.395124 -371.2083)
		(end 50.685954 -371.49913)
		(width 0.14224)
		(layer "In6.Cu")
		(net "P5E_CPU1_P0_TX_DN<5>")
	)
	(segment
		(start 102.063042 -294.800782)
		(end 101.993446 -294.841422)
		(width 0.1143)
		(layer "In6.Cu")
		(net "P5E_CPU1_P0_TX_DN<5>")
	)
	(segment
		(start 111.05007 -316.66053)
		(end 116.658898 -323.495162)
		(width 0.14224)
		(layer "In6.Cu")
		(net "P5E_CPU1_P0_TX_DN<5>")
	)
	(segment
		(start 51.866292 -367.092484)
		(end 50.804572 -368.154204)
		(width 0.14224)
		(layer "In6.Cu")
		(net "P5E_CPU1_P0_TX_DN<5>")
	)
	(segment
		(start 56.745378 -365.07166)
		(end 51.866292 -367.092484)
		(width 0.14224)
		(layer "In6.Cu")
		(net "P5E_CPU1_P0_TX_DN<5>")
	)
	(arc
		(start 119.914416 -329.728576)
		(mid 119.966119 -329.943041)
		(end 120.009412 -330.15936)
		(width 0.14224)
		(layer "In6.Cu")
		(net "P5E_CPU1_P0_TX_DN<5>")
	)
	(arc
		(start 110.750858 -316.257178)
		(mid 110.895519 -316.462523)
		(end 111.05007 -316.66053)
		(width 0.14224)
		(layer "In6.Cu")
		(net "P5E_CPU1_P0_TX_DN<5>")
	)
	(arc
		(start 73.07961 -361.971844)
		(mid 72.758608 -361.940243)
		(end 72.449944 -361.846622)
		(width 0.14224)
		(layer "In6.Cu")
		(net "P5E_CPU1_P0_TX_DN<5>")
	)
	(arc
		(start 105.265982 -308.036214)
		(mid 105.282137 -308.07048)
		(end 105.301542 -308.103016)
		(width 0.14224)
		(layer "In6.Cu")
		(net "P5E_CPU1_P0_TX_DN<5>")
	)
	(arc
		(start 119.08282 -349.268034)
		(mid 118.590294 -350.090095)
		(end 117.880638 -350.734122)
		(width 0.14224)
		(layer "In6.Cu")
		(net "P5E_CPU1_P0_TX_DN<5>")
	)
	(arc
		(start 121.662444 -339.35543)
		(mid 121.751527 -341.884726)
		(end 121.125234 -344.336878)
		(width 0.14224)
		(layer "In6.Cu")
		(net "P5E_CPU1_P0_TX_DN<5>")
	)
	(arc
		(start 64.889126 -361.32262)
		(mid 64.69503 -361.341732)
		(end 64.50838 -361.398312)
		(width 0.14224)
		(layer "In6.Cu")
		(net "P5E_CPU1_P0_TX_DN<5>")
	)
	(arc
		(start 101.993446 -291.601398)
		(mid 101.836469 -291.906198)
		(end 101.993446 -292.210998)
		(width 0.1143)
		(layer "In6.Cu")
		(net "P5E_CPU1_P0_TX_DN<5>")
	)
	(arc
		(start 50.804572 -368.154204)
		(mid 50.501538 -368.607632)
		(end 50.395124 -369.142518)
		(width 0.14224)
		(layer "In6.Cu")
		(net "P5E_CPU1_P0_TX_DN<5>")
	)
	(arc
		(start 119.845836 -329.551284)
		(mid 119.885142 -329.63799)
		(end 119.914416 -329.728576)
		(width 0.14224)
		(layer "In6.Cu")
		(net "P5E_CPU1_P0_TX_DN<5>")
	)
	(arc
		(start 101.836474 -288.666174)
		(mid 101.878023 -288.837596)
		(end 101.993446 -288.970974)
		(width 0.1143)
		(layer "In6.Cu")
		(net "P5E_CPU1_P0_TX_DN<5>")
	)
	(arc
		(start 101.993446 -289.981386)
		(mid 101.836469 -290.286186)
		(end 101.993446 -290.590986)
		(width 0.1143)
		(layer "In6.Cu")
		(net "P5E_CPU1_P0_TX_DN<5>")
	)
	(arc
		(start 101.593142 -286.581596)
		(mid 101.771955 -286.783946)
		(end 101.836474 -287.046162)
		(width 0.1143)
		(layer "In6.Cu")
		(net "P5E_CPU1_P0_TX_DN<5>")
	)
	(arc
		(start 101.993446 -293.22141)
		(mid 101.836469 -293.52621)
		(end 101.993446 -293.83101)
		(width 0.1143)
		(layer "In6.Cu")
		(net "P5E_CPU1_P0_TX_DN<5>")
	)
	(arc
		(start 101.325934 -361.814618)
		(mid 101.078786 -361.931685)
		(end 100.808282 -361.971844)
		(width 0.14224)
		(layer "In6.Cu")
		(net "P5E_CPU1_P0_TX_DN<5>")
	)
	(arc
		(start 101.993446 -294.841422)
		(mid 101.868564 -294.985418)
		(end 101.82352 -295.170606)
		(width 0.1143)
		(layer "In6.Cu")
		(net "P5E_CPU1_P0_TX_DN<5>")
	)
	(arc
		(start 102.306374 -287.856422)
		(mid 102.241859 -288.118641)
		(end 102.063042 -288.320988)
		(width 0.1143)
		(layer "In6.Cu")
		(net "P5E_CPU1_P0_TX_DN<5>")
	)
	(arc
		(start 101.449632 -295.735502)
		(mid 101.388214 -295.827187)
		(end 101.366574 -295.9354)
		(width 0.1143)
		(layer "In6.Cu")
		(net "P5E_CPU1_P0_TX_DN<5>")
	)
	(arc
		(start 102.063042 -290.631626)
		(mid 102.306369 -291.096192)
		(end 102.063042 -291.560758)
		(width 0.1143)
		(layer "In6.Cu")
		(net "P5E_CPU1_P0_TX_DN<5>")
	)
	(arc
		(start 102.063042 -292.251638)
		(mid 102.306369 -292.716204)
		(end 102.063042 -293.18077)
		(width 0.1143)
		(layer "In6.Cu")
		(net "P5E_CPU1_P0_TX_DN<5>")
	)
	(arc
		(start 101.373178 -286.30626)
		(mid 101.424668 -286.436733)
		(end 101.520498 -286.539178)
		(width 0.1143)
		(layer "In6.Cu")
		(net "P5E_CPU1_P0_TX_DN<5>")
	)
	(arc
		(start 102.063042 -293.87165)
		(mid 102.306369 -294.336216)
		(end 102.063042 -294.800782)
		(width 0.1143)
		(layer "In6.Cu")
		(net "P5E_CPU1_P0_TX_DN<5>")
	)
	(arc
		(start 101.991414 -288.362644)
		(mid 101.877485 -288.495791)
		(end 101.836474 -288.666174)
		(width 0.1143)
		(layer "In6.Cu")
		(net "P5E_CPU1_P0_TX_DN<5>")
	)
	(arc
		(start 102.063042 -289.011614)
		(mid 102.306369 -289.47618)
		(end 102.063042 -289.940746)
		(width 0.1143)
		(layer "In6.Cu")
		(net "P5E_CPU1_P0_TX_DN<5>")
	)
	(arc
		(start 71.307198 -361.37342)
		(mid 71.18257 -361.335522)
		(end 71.052944 -361.32262)
		(width 0.14224)
		(layer "In6.Cu")
		(net "P5E_CPU1_P0_TX_DN<5>")
	)
	(arc
		(start 101.82352 -295.170606)
		(mid 101.751819 -295.43731)
		(end 101.556058 -295.632124)
		(width 0.1143)
		(layer "In6.Cu")
		(net "P5E_CPU1_P0_TX_DN<5>")
	)
	(arc
		(start 101.412294 -298.648882)
		(mid 101.420377 -298.730973)
		(end 101.444298 -298.809918)
		(width 0.14224)
		(layer "In6.Cu")
		(net "P5E_CPU1_P0_TX_DN<5>")
	)
	(arc
		(start 116.658898 -323.495162)
		(mid 116.713656 -323.569381)
		(end 116.760498 -323.648832)
		(width 0.14224)
		(layer "In6.Cu")
		(net "P5E_CPU1_P0_TX_DN<5>")
	)
	(arc
		(start 101.836474 -287.046162)
		(mid 101.878023 -287.217584)
		(end 101.993446 -287.350962)
		(width 0.1143)
		(layer "In6.Cu")
		(net "P5E_CPU1_P0_TX_DN<5>")
	)
	(arc
		(start 102.060502 -287.390078)
		(mid 102.241154 -287.592823)
		(end 102.306374 -287.856422)
		(width 0.1143)
		(layer "In6.Cu")
		(net "P5E_CPU1_P0_TX_DN<5>")
	)
	(segment
		(start 48.984154 -373.96293)
		(end 48.713644 -374.23344)
		(width 0.12954)
		(layer "F.Cu")
		(net "P5E_CPU1_P0_TX_DN<4>")
	)
	(segment
		(start 48.713644 -374.23344)
		(end 48.713644 -374.93702)
		(width 0.12954)
		(layer "F.Cu")
		(net "P5E_CPU1_P0_TX_DN<4>")
	)
	(segment
		(start 102.207822 -284.35046)
		(end 101.74097 -284.616398)
		(width 0.12954)
		(layer "F.Cu")
		(net "P5E_CPU1_P0_TX_DN<4>")
	)
	(segment
		(start 48.713644 -374.93702)
		(end 49.009554 -375.23293)
		(width 0.12954)
		(layer "F.Cu")
		(net "P5E_CPU1_P0_TX_DN<4>")
	)
	(segment
		(start 101.057456 -293.83355)
		(end 101.120448 -293.869618)
		(width 0.1143)
		(layer "In6.Cu")
		(net "P5E_CPU1_P0_TX_DN<4>")
	)
	(segment
		(start 101.124004 -293.180516)
		(end 101.091238 -293.199312)
		(width 0.1143)
		(layer "In6.Cu")
		(net "P5E_CPU1_P0_TX_DN<4>")
	)
	(segment
		(start 101.089206 -288.991548)
		(end 101.088952 -288.991802)
		(width 0.1143)
		(layer "In6.Cu")
		(net "P5E_CPU1_P0_TX_DN<4>")
	)
	(segment
		(start 119.115332 -330.531216)
		(end 120.713754 -339.42147)
		(width 0.14224)
		(layer "In6.Cu")
		(net "P5E_CPU1_P0_TX_DN<4>")
	)
	(segment
		(start 101.084126 -293.204138)
		(end 101.077522 -293.20744)
		(width 0.1143)
		(layer "In6.Cu")
		(net "P5E_CPU1_P0_TX_DN<4>")
	)
	(segment
		(start 101.083872 -285.103316)
		(end 101.082856 -285.103824)
		(width 0.1143)
		(layer "In6.Cu")
		(net "P5E_CPU1_P0_TX_DN<4>")
	)
	(segment
		(start 101.054662 -293.831772)
		(end 101.057456 -293.833296)
		(width 0.1143)
		(layer "In6.Cu")
		(net "P5E_CPU1_P0_TX_DN<4>")
	)
	(segment
		(start 101.057456 -292.213284)
		(end 101.057456 -292.213538)
		(width 0.1143)
		(layer "In6.Cu")
		(net "P5E_CPU1_P0_TX_DN<4>")
	)
	(segment
		(start 71.254366 -360.39044)
		(end 64.802766 -360.39044)
		(width 0.14224)
		(layer "In6.Cu")
		(net "P5E_CPU1_P0_TX_DN<4>")
	)
	(segment
		(start 100.46716 -296.404538)
		(end 100.46716 -296.432986)
		(width 0.1143)
		(layer "In6.Cu")
		(net "P5E_CPU1_P0_TX_DN<4>")
	)
	(segment
		(start 101.091238 -292.232842)
		(end 101.092508 -292.23335)
		(width 0.1143)
		(layer "In6.Cu")
		(net "P5E_CPU1_P0_TX_DN<4>")
	)
	(segment
		(start 101.087936 -285.10103)
		(end 101.083872 -285.103316)
		(width 0.1143)
		(layer "In6.Cu")
		(net "P5E_CPU1_P0_TX_DN<4>")
	)
	(segment
		(start 101.102668 -292.239446)
		(end 101.103684 -292.239954)
		(width 0.1143)
		(layer "In6.Cu")
		(net "P5E_CPU1_P0_TX_DN<4>")
	)
	(segment
		(start 101.077522 -293.20744)
		(end 101.052122 -293.222172)
		(width 0.1143)
		(layer "In6.Cu")
		(net "P5E_CPU1_P0_TX_DN<4>")
	)
	(segment
		(start 100.42144 -296.115486)
		(end 100.42144 -296.358818)
		(width 0.1143)
		(layer "In6.Cu")
		(net "P5E_CPU1_P0_TX_DN<4>")
	)
	(segment
		(start 116.090192 -324.3961)
		(end 118.923308 -329.817984)
		(width 0.14224)
		(layer "In6.Cu")
		(net "P5E_CPU1_P0_TX_DN<4>")
	)
	(segment
		(start 101.091238 -290.61283)
		(end 101.092508 -290.613338)
		(width 0.1143)
		(layer "In6.Cu")
		(net "P5E_CPU1_P0_TX_DN<4>")
	)
	(segment
		(start 101.05263 -293.830502)
		(end 101.054662 -293.831772)
		(width 0.1143)
		(layer "In6.Cu")
		(net "P5E_CPU1_P0_TX_DN<4>")
	)
	(segment
		(start 101.106224 -294.810942)
		(end 101.052376 -294.84193)
		(width 0.1143)
		(layer "In6.Cu")
		(net "P5E_CPU1_P0_TX_DN<4>")
	)
	(segment
		(start 101.137974 -294.790368)
		(end 101.137974 -294.791384)
		(width 0.1143)
		(layer "In6.Cu")
		(net "P5E_CPU1_P0_TX_DN<4>")
	)
	(segment
		(start 48.693324 -369.768882)
		(end 48.693324 -373.605298)
		(width 0.14224)
		(layer "In6.Cu")
		(net "P5E_CPU1_P0_TX_DN<4>")
	)
	(segment
		(start 101.077522 -289.967416)
		(end 101.052122 -289.982148)
		(width 0.1143)
		(layer "In6.Cu")
		(net "P5E_CPU1_P0_TX_DN<4>")
	)
	(segment
		(start 101.052884 -287.350708)
		(end 101.057202 -287.353248)
		(width 0.1143)
		(layer "In6.Cu")
		(net "P5E_CPU1_P0_TX_DN<4>")
	)
	(segment
		(start 101.08946 -288.991802)
		(end 101.125274 -289.012376)
		(width 0.1143)
		(layer "In6.Cu")
		(net "P5E_CPU1_P0_TX_DN<4>")
	)
	(segment
		(start 100.490782 -298.952158)
		(end 104.43083 -308.463442)
		(width 0.14224)
		(layer "In6.Cu")
		(net "P5E_CPU1_P0_TX_DN<4>")
	)
	(segment
		(start 101.057456 -292.213538)
		(end 101.088952 -292.231826)
		(width 0.1143)
		(layer "In6.Cu")
		(net "P5E_CPU1_P0_TX_DN<4>")
	)
	(segment
		(start 101.12502 -288.319464)
		(end 101.052122 -288.362136)
		(width 0.1143)
		(layer "In6.Cu")
		(net "P5E_CPU1_P0_TX_DN<4>")
	)
	(segment
		(start 101.05263 -290.590478)
		(end 101.054662 -290.591748)
		(width 0.1143)
		(layer "In6.Cu")
		(net "P5E_CPU1_P0_TX_DN<4>")
	)
	(segment
		(start 101.052122 -288.969958)
		(end 101.089206 -288.991548)
		(width 0.1143)
		(layer "In6.Cu")
		(net "P5E_CPU1_P0_TX_DN<4>")
	)
	(segment
		(start 101.077522 -291.587428)
		(end 101.052122 -291.60216)
		(width 0.1143)
		(layer "In6.Cu")
		(net "P5E_CPU1_P0_TX_DN<4>")
	)
	(segment
		(start 101.101906 -292.238938)
		(end 101.102668 -292.239446)
		(width 0.1143)
		(layer "In6.Cu")
		(net "P5E_CPU1_P0_TX_DN<4>")
	)
	(segment
		(start 48.740568 -373.719344)
		(end 48.984154 -373.96293)
		(width 0.14224)
		(layer "In6.Cu")
		(net "P5E_CPU1_P0_TX_DN<4>")
	)
	(segment
		(start 101.088952 -288.991802)
		(end 101.08946 -288.991802)
		(width 0.1143)
		(layer "In6.Cu")
		(net "P5E_CPU1_P0_TX_DN<4>")
	)
	(segment
		(start 101.088952 -290.611814)
		(end 101.08946 -290.611814)
		(width 0.1143)
		(layer "In6.Cu")
		(net "P5E_CPU1_P0_TX_DN<4>")
	)
	(segment
		(start 101.124004 -291.560504)
		(end 101.091238 -291.5793)
		(width 0.1143)
		(layer "In6.Cu")
		(net "P5E_CPU1_P0_TX_DN<4>")
	)
	(segment
		(start 101.137974 -294.791384)
		(end 101.106732 -294.810688)
		(width 0.1143)
		(layer "In6.Cu")
		(net "P5E_CPU1_P0_TX_DN<4>")
	)
	(segment
		(start 100.582222 -286.540448)
		(end 100.65385 -286.58185)
		(width 0.1143)
		(layer "In6.Cu")
		(net "P5E_CPU1_P0_TX_DN<4>")
	)
	(segment
		(start 101.08946 -290.611814)
		(end 101.091238 -290.61283)
		(width 0.1143)
		(layer "In6.Cu")
		(net "P5E_CPU1_P0_TX_DN<4>")
	)
	(segment
		(start 101.090984 -289.959542)
		(end 101.084126 -289.964114)
		(width 0.1143)
		(layer "In6.Cu")
		(net "P5E_CPU1_P0_TX_DN<4>")
	)
	(segment
		(start 101.091238 -293.199312)
		(end 101.084126 -293.204138)
		(width 0.1143)
		(layer "In6.Cu")
		(net "P5E_CPU1_P0_TX_DN<4>")
	)
	(segment
		(start 101.084126 -291.584126)
		(end 101.077522 -291.587428)
		(width 0.1143)
		(layer "In6.Cu")
		(net "P5E_CPU1_P0_TX_DN<4>")
	)
	(segment
		(start 100.615242 -285.913068)
		(end 100.61448 -285.913576)
		(width 0.1143)
		(layer "In6.Cu")
		(net "P5E_CPU1_P0_TX_DN<4>")
	)
	(segment
		(start 117.289072 -350.002348)
		(end 101.00183 -360.90352)
		(width 0.14224)
		(layer "In6.Cu")
		(net "P5E_CPU1_P0_TX_DN<4>")
	)
	(segment
		(start 64.164718 -360.51236)
		(end 57.031382 -363.466634)
		(width 0.14224)
		(layer "In6.Cu")
		(net "P5E_CPU1_P0_TX_DN<4>")
	)
	(segment
		(start 100.755958 -295.51249)
		(end 100.611686 -295.656762)
		(width 0.1143)
		(layer "In6.Cu")
		(net "P5E_CPU1_P0_TX_DN<4>")
	)
	(segment
		(start 104.512872 -308.617112)
		(end 109.944916 -316.747144)
		(width 0.14224)
		(layer "In6.Cu")
		(net "P5E_CPU1_P0_TX_DN<4>")
	)
	(segment
		(start 101.057202 -287.353248)
		(end 101.057456 -287.353756)
		(width 0.1143)
		(layer "In6.Cu")
		(net "P5E_CPU1_P0_TX_DN<4>")
	)
	(segment
		(start 101.08946 -292.231826)
		(end 101.091238 -292.232842)
		(width 0.1143)
		(layer "In6.Cu")
		(net "P5E_CPU1_P0_TX_DN<4>")
	)
	(segment
		(start 101.088952 -292.231826)
		(end 101.08946 -292.231826)
		(width 0.1143)
		(layer "In6.Cu")
		(net "P5E_CPU1_P0_TX_DN<4>")
	)
	(segment
		(start 120.240298 -343.81186)
		(end 118.070884 -349.049086)
		(width 0.14224)
		(layer "In6.Cu")
		(net "P5E_CPU1_P0_TX_DN<4>")
	)
	(segment
		(start 101.091238 -291.5793)
		(end 101.084126 -291.584126)
		(width 0.1143)
		(layer "In6.Cu")
		(net "P5E_CPU1_P0_TX_DN<4>")
	)
	(segment
		(start 100.42144 -296.358818)
		(end 100.46716 -296.404538)
		(width 0.1143)
		(layer "In6.Cu")
		(net "P5E_CPU1_P0_TX_DN<4>")
	)
	(segment
		(start 100.89642 -295.146222)
		(end 100.89642 -295.172892)
		(width 0.1143)
		(layer "In6.Cu")
		(net "P5E_CPU1_P0_TX_DN<4>")
	)
	(segment
		(start 101.054662 -290.591748)
		(end 101.057456 -290.593272)
		(width 0.1143)
		(layer "In6.Cu")
		(net "P5E_CPU1_P0_TX_DN<4>")
	)
	(segment
		(start 101.082602 -287.368234)
		(end 101.085142 -287.369758)
		(width 0.1143)
		(layer "In6.Cu")
		(net "P5E_CPU1_P0_TX_DN<4>")
	)
	(segment
		(start 101.102668 -290.619434)
		(end 101.103684 -290.619942)
		(width 0.1143)
		(layer "In6.Cu")
		(net "P5E_CPU1_P0_TX_DN<4>")
	)
	(segment
		(start 101.74097 -284.616398)
		(end 101.443028 -284.616398)
		(width 0.1143)
		(layer "In6.Cu")
		(net "P5E_CPU1_P0_TX_DN<4>")
	)
	(segment
		(start 101.057456 -287.353756)
		(end 101.082602 -287.368234)
		(width 0.1143)
		(layer "In6.Cu")
		(net "P5E_CPU1_P0_TX_DN<4>")
	)
	(segment
		(start 101.101906 -290.618926)
		(end 101.102668 -290.619434)
		(width 0.1143)
		(layer "In6.Cu")
		(net "P5E_CPU1_P0_TX_DN<4>")
	)
	(segment
		(start 101.057456 -293.833296)
		(end 101.057456 -293.83355)
		(width 0.1143)
		(layer "In6.Cu")
		(net "P5E_CPU1_P0_TX_DN<4>")
	)
	(segment
		(start 101.443028 -284.616398)
		(end 101.360224 -284.699202)
		(width 0.1143)
		(layer "In6.Cu")
		(net "P5E_CPU1_P0_TX_DN<4>")
	)
	(segment
		(start 72.73925 -360.95051)
		(end 71.509128 -360.44124)
		(width 0.14224)
		(layer "In6.Cu")
		(net "P5E_CPU1_P0_TX_DN<4>")
	)
	(segment
		(start 101.103684 -292.239954)
		(end 101.124004 -292.251892)
		(width 0.1143)
		(layer "In6.Cu")
		(net "P5E_CPU1_P0_TX_DN<4>")
	)
	(segment
		(start 101.106732 -294.810688)
		(end 101.106224 -294.810942)
		(width 0.1143)
		(layer "In6.Cu")
		(net "P5E_CPU1_P0_TX_DN<4>")
	)
	(segment
		(start 100.46716 -296.432986)
		(end 100.46716 -298.833032)
		(width 0.14224)
		(layer "In6.Cu")
		(net "P5E_CPU1_P0_TX_DN<4>")
	)
	(segment
		(start 100.61448 -285.913576)
		(end 100.582222 -285.932372)
		(width 0.1143)
		(layer "In6.Cu")
		(net "P5E_CPU1_P0_TX_DN<4>")
	)
	(segment
		(start 101.12502 -289.939984)
		(end 101.090984 -289.959542)
		(width 0.1143)
		(layer "In6.Cu")
		(net "P5E_CPU1_P0_TX_DN<4>")
	)
	(segment
		(start 110.970822 -318.130682)
		(end 115.99164 -324.248526)
		(width 0.14224)
		(layer "In6.Cu")
		(net "P5E_CPU1_P0_TX_DN<4>")
	)
	(segment
		(start 101.05263 -292.21049)
		(end 101.054662 -292.21176)
		(width 0.1143)
		(layer "In6.Cu")
		(net "P5E_CPU1_P0_TX_DN<4>")
	)
	(segment
		(start 101.103684 -290.619942)
		(end 101.124004 -290.63188)
		(width 0.1143)
		(layer "In6.Cu")
		(net "P5E_CPU1_P0_TX_DN<4>")
	)
	(segment
		(start 101.054662 -292.21176)
		(end 101.057456 -292.213284)
		(width 0.1143)
		(layer "In6.Cu")
		(net "P5E_CPU1_P0_TX_DN<4>")
	)
	(segment
		(start 101.084126 -289.964114)
		(end 101.077522 -289.967416)
		(width 0.1143)
		(layer "In6.Cu")
		(net "P5E_CPU1_P0_TX_DN<4>")
	)
	(segment
		(start 101.057456 -290.593272)
		(end 101.057456 -290.593526)
		(width 0.1143)
		(layer "In6.Cu")
		(net "P5E_CPU1_P0_TX_DN<4>")
	)
	(segment
		(start 57.031382 -363.466634)
		(end 56.268874 -364.229142)
		(width 0.14224)
		(layer "In6.Cu")
		(net "P5E_CPU1_P0_TX_DN<4>")
	)
	(segment
		(start 100.653088 -285.89097)
		(end 100.615242 -285.913068)
		(width 0.1143)
		(layer "In6.Cu")
		(net "P5E_CPU1_P0_TX_DN<4>")
	)
	(segment
		(start 101.120448 -293.869618)
		(end 101.13264 -293.878)
		(width 0.1143)
		(layer "In6.Cu")
		(net "P5E_CPU1_P0_TX_DN<4>")
	)
	(segment
		(start 101.057456 -290.593526)
		(end 101.088952 -290.611814)
		(width 0.1143)
		(layer "In6.Cu")
		(net "P5E_CPU1_P0_TX_DN<4>")
	)
	(segment
		(start 101.092508 -292.23335)
		(end 101.101906 -292.238938)
		(width 0.1143)
		(layer "In6.Cu")
		(net "P5E_CPU1_P0_TX_DN<4>")
	)
	(segment
		(start 101.092508 -290.613338)
		(end 101.101906 -290.618926)
		(width 0.1143)
		(layer "In6.Cu")
		(net "P5E_CPU1_P0_TX_DN<4>")
	)
	(segment
		(start 100.578666 -361.032044)
		(end 73.149968 -361.032044)
		(width 0.14224)
		(layer "In6.Cu")
		(net "P5E_CPU1_P0_TX_DN<4>")
	)
	(segment
		(start 56.268874 -364.229142)
		(end 50.912268 -366.448086)
		(width 0.14224)
		(layer "In6.Cu")
		(net "P5E_CPU1_P0_TX_DN<4>")
	)
	(arc
		(start 71.509128 -360.44124)
		(mid 71.384251 -360.403292)
		(end 71.254366 -360.39044)
		(width 0.14224)
		(layer "In6.Cu")
		(net "P5E_CPU1_P0_TX_DN<4>")
	)
	(arc
		(start 101.052122 -293.222172)
		(mid 100.896295 -293.52649)
		(end 101.05263 -293.830502)
		(width 0.1143)
		(layer "In6.Cu")
		(net "P5E_CPU1_P0_TX_DN<4>")
	)
	(arc
		(start 119.001032 -330.01712)
		(mid 119.063522 -330.272981)
		(end 119.115332 -330.531216)
		(width 0.14224)
		(layer "In6.Cu")
		(net "P5E_CPU1_P0_TX_DN<4>")
	)
	(arc
		(start 101.124004 -292.251892)
		(mid 101.362069 -292.716204)
		(end 101.124004 -293.180516)
		(width 0.1143)
		(layer "In6.Cu")
		(net "P5E_CPU1_P0_TX_DN<4>")
	)
	(arc
		(start 100.611686 -295.656762)
		(mid 100.470975 -295.867211)
		(end 100.42144 -296.115486)
		(width 0.1143)
		(layer "In6.Cu")
		(net "P5E_CPU1_P0_TX_DN<4>")
	)
	(arc
		(start 100.46716 -298.833032)
		(mid 100.473127 -298.893753)
		(end 100.490782 -298.952158)
		(width 0.14224)
		(layer "In6.Cu")
		(net "P5E_CPU1_P0_TX_DN<4>")
	)
	(arc
		(start 101.052122 -291.60216)
		(mid 100.896295 -291.906478)
		(end 101.05263 -292.21049)
		(width 0.1143)
		(layer "In6.Cu")
		(net "P5E_CPU1_P0_TX_DN<4>")
	)
	(arc
		(start 48.693324 -373.605298)
		(mid 48.705601 -373.667021)
		(end 48.740568 -373.719344)
		(width 0.14224)
		(layer "In6.Cu")
		(net "P5E_CPU1_P0_TX_DN<4>")
	)
	(arc
		(start 120.713754 -339.42147)
		(mid 120.792237 -341.650653)
		(end 120.240298 -343.81186)
		(width 0.14224)
		(layer "In6.Cu")
		(net "P5E_CPU1_P0_TX_DN<4>")
	)
	(arc
		(start 101.052122 -289.982148)
		(mid 100.896295 -290.286466)
		(end 101.05263 -290.590478)
		(width 0.1143)
		(layer "In6.Cu")
		(net "P5E_CPU1_P0_TX_DN<4>")
	)
	(arc
		(start 101.085142 -287.369758)
		(mid 101.290938 -287.575408)
		(end 101.36632 -287.856422)
		(width 0.1143)
		(layer "In6.Cu")
		(net "P5E_CPU1_P0_TX_DN<4>")
	)
	(arc
		(start 115.99164 -324.248526)
		(mid 116.044582 -324.319865)
		(end 116.090192 -324.3961)
		(width 0.14224)
		(layer "In6.Cu")
		(net "P5E_CPU1_P0_TX_DN<4>")
	)
	(arc
		(start 101.052122 -288.362136)
		(mid 100.896295 -288.6661)
		(end 101.052122 -288.969958)
		(width 0.1143)
		(layer "In6.Cu")
		(net "P5E_CPU1_P0_TX_DN<4>")
	)
	(arc
		(start 64.802766 -360.39044)
		(mid 64.615406 -360.400371)
		(end 64.430148 -360.430064)
		(width 0.14224)
		(layer "In6.Cu")
		(net "P5E_CPU1_P0_TX_DN<4>")
	)
	(arc
		(start 101.360224 -284.699202)
		(mid 101.358435 -284.710524)
		(end 101.356414 -284.721808)
		(width 0.1143)
		(layer "In6.Cu")
		(net "P5E_CPU1_P0_TX_DN<4>")
	)
	(arc
		(start 64.430148 -360.430064)
		(mid 64.295569 -360.4652)
		(end 64.164718 -360.51236)
		(width 0.14224)
		(layer "In6.Cu")
		(net "P5E_CPU1_P0_TX_DN<4>")
	)
	(arc
		(start 101.00183 -360.90352)
		(mid 100.799787 -360.999198)
		(end 100.578666 -361.032044)
		(width 0.14224)
		(layer "In6.Cu")
		(net "P5E_CPU1_P0_TX_DN<4>")
	)
	(arc
		(start 109.944916 -316.747144)
		(mid 110.440885 -317.451507)
		(end 110.970822 -318.130682)
		(width 0.14224)
		(layer "In6.Cu")
		(net "P5E_CPU1_P0_TX_DN<4>")
	)
	(arc
		(start 104.43083 -308.463442)
		(mid 104.468068 -308.542297)
		(end 104.512872 -308.617112)
		(width 0.14224)
		(layer "In6.Cu")
		(net "P5E_CPU1_P0_TX_DN<4>")
	)
	(arc
		(start 100.89642 -285.426404)
		(mid 100.831905 -285.688623)
		(end 100.653088 -285.89097)
		(width 0.1143)
		(layer "In6.Cu")
		(net "P5E_CPU1_P0_TX_DN<4>")
	)
	(arc
		(start 100.65385 -286.58185)
		(mid 100.832032 -286.784253)
		(end 100.896166 -287.046162)
		(width 0.1143)
		(layer "In6.Cu")
		(net "P5E_CPU1_P0_TX_DN<4>")
	)
	(arc
		(start 101.124004 -290.63188)
		(mid 101.362069 -291.096192)
		(end 101.124004 -291.560504)
		(width 0.1143)
		(layer "In6.Cu")
		(net "P5E_CPU1_P0_TX_DN<4>")
	)
	(arc
		(start 101.052376 -294.84193)
		(mid 100.9377 -294.975264)
		(end 100.89642 -295.146222)
		(width 0.1143)
		(layer "In6.Cu")
		(net "P5E_CPU1_P0_TX_DN<4>")
	)
	(arc
		(start 100.896166 -287.046162)
		(mid 100.937653 -287.217402)
		(end 101.052884 -287.350708)
		(width 0.1143)
		(layer "In6.Cu")
		(net "P5E_CPU1_P0_TX_DN<4>")
	)
	(arc
		(start 101.13264 -293.878)
		(mid 101.362451 -294.332863)
		(end 101.137974 -294.790368)
		(width 0.1143)
		(layer "In6.Cu")
		(net "P5E_CPU1_P0_TX_DN<4>")
	)
	(arc
		(start 101.125274 -289.012376)
		(mid 101.359894 -289.476282)
		(end 101.12502 -289.939984)
		(width 0.1143)
		(layer "In6.Cu")
		(net "P5E_CPU1_P0_TX_DN<4>")
	)
	(arc
		(start 118.070884 -349.049086)
		(mid 117.750538 -349.583583)
		(end 117.289072 -350.002348)
		(width 0.14224)
		(layer "In6.Cu")
		(net "P5E_CPU1_P0_TX_DN<4>")
	)
	(arc
		(start 118.923308 -329.817984)
		(mid 118.967658 -329.91541)
		(end 119.001032 -330.01712)
		(width 0.14224)
		(layer "In6.Cu")
		(net "P5E_CPU1_P0_TX_DN<4>")
	)
	(arc
		(start 100.89642 -295.172892)
		(mid 100.859961 -295.356657)
		(end 100.755958 -295.51249)
		(width 0.1143)
		(layer "In6.Cu")
		(net "P5E_CPU1_P0_TX_DN<4>")
	)
	(arc
		(start 101.356414 -284.721808)
		(mid 101.263446 -284.940637)
		(end 101.087936 -285.10103)
		(width 0.1143)
		(layer "In6.Cu")
		(net "P5E_CPU1_P0_TX_DN<4>")
	)
	(arc
		(start 50.912268 -366.448086)
		(mid 49.299103 -367.77192)
		(end 48.693324 -369.768882)
		(width 0.14224)
		(layer "In6.Cu")
		(net "P5E_CPU1_P0_TX_DN<4>")
	)
	(arc
		(start 73.149968 -361.032044)
		(mid 72.940601 -361.011478)
		(end 72.73925 -360.95051)
		(width 0.14224)
		(layer "In6.Cu")
		(net "P5E_CPU1_P0_TX_DN<4>")
	)
	(arc
		(start 101.082856 -285.103824)
		(mid 100.946408 -285.240123)
		(end 100.89642 -285.426404)
		(width 0.1143)
		(layer "In6.Cu")
		(net "P5E_CPU1_P0_TX_DN<4>")
	)
	(arc
		(start 101.36632 -287.856422)
		(mid 101.302374 -288.117491)
		(end 101.12502 -288.319464)
		(width 0.1143)
		(layer "In6.Cu")
		(net "P5E_CPU1_P0_TX_DN<4>")
	)
	(arc
		(start 100.582222 -285.932372)
		(mid 100.426395 -286.23641)
		(end 100.582222 -286.540448)
		(width 0.1143)
		(layer "In6.Cu")
		(net "P5E_CPU1_P0_TX_DN<4>")
	)
	(segment
		(start 45.310044 -370.00942)
		(end 45.605954 -370.30533)
		(width 0.12954)
		(layer "F.Cu")
		(net "P5E_CPU1_P0_TX_DN<3>")
	)
	(segment
		(start 45.580554 -369.03533)
		(end 45.310044 -369.30584)
		(width 0.12954)
		(layer "F.Cu")
		(net "P5E_CPU1_P0_TX_DN<3>")
	)
	(segment
		(start 45.310044 -369.30584)
		(end 45.310044 -370.00942)
		(width 0.12954)
		(layer "F.Cu")
		(net "P5E_CPU1_P0_TX_DN<3>")
	)
	(segment
		(start 102.207822 -282.730448)
		(end 101.74097 -282.996386)
		(width 0.12954)
		(layer "F.Cu")
		(net "P5E_CPU1_P0_TX_DN<3>")
	)
	(segment
		(start 100.132642 -293.210488)
		(end 100.112322 -293.221918)
		(width 0.1143)
		(layer "In6.Cu")
		(net "P5E_CPU1_P0_TX_DN<3>")
	)
	(segment
		(start 100.151692 -292.23335)
		(end 100.183188 -292.251638)
		(width 0.1143)
		(layer "In6.Cu")
		(net "P5E_CPU1_P0_TX_DN<3>")
	)
	(segment
		(start 99.48672 -296.082212)
		(end 99.48672 -296.288968)
		(width 0.1143)
		(layer "In6.Cu")
		(net "P5E_CPU1_P0_TX_DN<3>")
	)
	(segment
		(start 100.135182 -291.588952)
		(end 100.132642 -291.590476)
		(width 0.1143)
		(layer "In6.Cu")
		(net "P5E_CPU1_P0_TX_DN<3>")
	)
	(segment
		(start 100.140516 -289.965638)
		(end 100.139754 -289.966146)
		(width 0.1143)
		(layer "In6.Cu")
		(net "P5E_CPU1_P0_TX_DN<3>")
	)
	(segment
		(start 100.653088 -284.270958)
		(end 100.583492 -284.311598)
		(width 0.1143)
		(layer "In6.Cu")
		(net "P5E_CPU1_P0_TX_DN<3>")
	)
	(segment
		(start 101.083872 -283.483304)
		(end 101.082856 -283.483812)
		(width 0.1143)
		(layer "In6.Cu")
		(net "P5E_CPU1_P0_TX_DN<3>")
	)
	(segment
		(start 115.194588 -324.772528)
		(end 115.194842 -324.772528)
		(width 0.14224)
		(layer "In6.Cu")
		(net "P5E_CPU1_P0_TX_DN<3>")
	)
	(segment
		(start 99.956366 -295.146222)
		(end 99.956112 -295.146984)
		(width 0.1143)
		(layer "In6.Cu")
		(net "P5E_CPU1_P0_TX_DN<3>")
	)
	(segment
		(start 71.39305 -359.446576)
		(end 64.783208 -359.446576)
		(width 0.14224)
		(layer "In6.Cu")
		(net "P5E_CPU1_P0_TX_DN<3>")
	)
	(segment
		(start 100.132642 -285.110682)
		(end 100.112322 -285.122112)
		(width 0.1143)
		(layer "In6.Cu")
		(net "P5E_CPU1_P0_TX_DN<3>")
	)
	(segment
		(start 100.140516 -293.205662)
		(end 100.139754 -293.20617)
		(width 0.1143)
		(layer "In6.Cu")
		(net "P5E_CPU1_P0_TX_DN<3>")
	)
	(segment
		(start 45.289724 -368.271298)
		(end 45.289724 -368.7445)
		(width 0.14224)
		(layer "In6.Cu")
		(net "P5E_CPU1_P0_TX_DN<3>")
	)
	(segment
		(start 63.980314 -359.575354)
		(end 56.57342 -362.643674)
		(width 0.14224)
		(layer "In6.Cu")
		(net "P5E_CPU1_P0_TX_DN<3>")
	)
	(segment
		(start 100.145088 -291.58311)
		(end 100.144072 -291.583618)
		(width 0.1143)
		(layer "In6.Cu")
		(net "P5E_CPU1_P0_TX_DN<3>")
	)
	(segment
		(start 116.763292 -349.207836)
		(end 100.612702 -360.017568)
		(width 0.14224)
		(layer "In6.Cu")
		(net "P5E_CPU1_P0_TX_DN<3>")
	)
	(segment
		(start 100.148898 -292.231572)
		(end 100.150168 -292.232334)
		(width 0.1143)
		(layer "In6.Cu")
		(net "P5E_CPU1_P0_TX_DN<3>")
	)
	(segment
		(start 100.145088 -289.963098)
		(end 100.144072 -289.963606)
		(width 0.1143)
		(layer "In6.Cu")
		(net "P5E_CPU1_P0_TX_DN<3>")
	)
	(segment
		(start 100.183188 -294.800782)
		(end 100.112322 -294.84193)
		(width 0.1143)
		(layer "In6.Cu")
		(net "P5E_CPU1_P0_TX_DN<3>")
	)
	(segment
		(start 99.717352 -295.717976)
		(end 99.581208 -295.85412)
		(width 0.1143)
		(layer "In6.Cu")
		(net "P5E_CPU1_P0_TX_DN<3>")
	)
	(segment
		(start 100.148898 -293.851584)
		(end 100.150168 -293.852346)
		(width 0.1143)
		(layer "In6.Cu")
		(net "P5E_CPU1_P0_TX_DN<3>")
	)
	(segment
		(start 99.53244 -296.334688)
		(end 99.53244 -296.363136)
		(width 0.1143)
		(layer "In6.Cu")
		(net "P5E_CPU1_P0_TX_DN<3>")
	)
	(segment
		(start 100.183188 -289.940746)
		(end 100.145088 -289.963098)
		(width 0.1143)
		(layer "In6.Cu")
		(net "P5E_CPU1_P0_TX_DN<3>")
	)
	(segment
		(start 100.183188 -288.320988)
		(end 100.110544 -288.363406)
		(width 0.1143)
		(layer "In6.Cu")
		(net "P5E_CPU1_P0_TX_DN<3>")
	)
	(segment
		(start 100.151692 -290.613338)
		(end 100.183188 -290.631626)
		(width 0.1143)
		(layer "In6.Cu")
		(net "P5E_CPU1_P0_TX_DN<3>")
	)
	(segment
		(start 100.148898 -290.61156)
		(end 100.150168 -290.612322)
		(width 0.1143)
		(layer "In6.Cu")
		(net "P5E_CPU1_P0_TX_DN<3>")
	)
	(segment
		(start 100.135182 -293.208964)
		(end 100.132642 -293.210488)
		(width 0.1143)
		(layer "In6.Cu")
		(net "P5E_CPU1_P0_TX_DN<3>")
	)
	(segment
		(start 99.53244 -296.363136)
		(end 99.53244 -299.051218)
		(width 0.14224)
		(layer "In6.Cu")
		(net "P5E_CPU1_P0_TX_DN<3>")
	)
	(segment
		(start 72.883522 -359.99674)
		(end 71.705978 -359.50906)
		(width 0.14224)
		(layer "In6.Cu")
		(net "P5E_CPU1_P0_TX_DN<3>")
	)
	(segment
		(start 99.48672 -296.288968)
		(end 99.53244 -296.334688)
		(width 0.1143)
		(layer "In6.Cu")
		(net "P5E_CPU1_P0_TX_DN<3>")
	)
	(segment
		(start 100.145088 -293.203122)
		(end 100.144072 -293.20363)
		(width 0.1143)
		(layer "In6.Cu")
		(net "P5E_CPU1_P0_TX_DN<3>")
	)
	(segment
		(start 100.14331 -291.584126)
		(end 100.14204 -291.584888)
		(width 0.1143)
		(layer "In6.Cu")
		(net "P5E_CPU1_P0_TX_DN<3>")
	)
	(segment
		(start 100.14331 -293.204138)
		(end 100.14204 -293.2049)
		(width 0.1143)
		(layer "In6.Cu")
		(net "P5E_CPU1_P0_TX_DN<3>")
	)
	(segment
		(start 100.14204 -289.964876)
		(end 100.140516 -289.965638)
		(width 0.1143)
		(layer "In6.Cu")
		(net "P5E_CPU1_P0_TX_DN<3>")
	)
	(segment
		(start 100.140516 -285.105856)
		(end 100.139754 -285.106364)
		(width 0.1143)
		(layer "In6.Cu")
		(net "P5E_CPU1_P0_TX_DN<3>")
	)
	(segment
		(start 103.700326 -309.090568)
		(end 109.6264 -317.958724)
		(width 0.14224)
		(layer "In6.Cu")
		(net "P5E_CPU1_P0_TX_DN<3>")
	)
	(segment
		(start 100.139754 -289.966146)
		(end 100.135182 -289.96894)
		(width 0.1143)
		(layer "In6.Cu")
		(net "P5E_CPU1_P0_TX_DN<3>")
	)
	(segment
		(start 100.151692 -293.853362)
		(end 100.183188 -293.87165)
		(width 0.1143)
		(layer "In6.Cu")
		(net "P5E_CPU1_P0_TX_DN<3>")
	)
	(segment
		(start 100.14331 -289.964114)
		(end 100.14204 -289.964876)
		(width 0.1143)
		(layer "In6.Cu")
		(net "P5E_CPU1_P0_TX_DN<3>")
	)
	(segment
		(start 100.183188 -293.18077)
		(end 100.145088 -293.203122)
		(width 0.1143)
		(layer "In6.Cu")
		(net "P5E_CPU1_P0_TX_DN<3>")
	)
	(segment
		(start 100.150168 -293.852346)
		(end 100.151692 -293.853362)
		(width 0.1143)
		(layer "In6.Cu")
		(net "P5E_CPU1_P0_TX_DN<3>")
	)
	(segment
		(start 100.139754 -285.106364)
		(end 100.135182 -285.109158)
		(width 0.1143)
		(layer "In6.Cu")
		(net "P5E_CPU1_P0_TX_DN<3>")
	)
	(segment
		(start 100.145088 -285.103316)
		(end 100.144072 -285.103824)
		(width 0.1143)
		(layer "In6.Cu")
		(net "P5E_CPU1_P0_TX_DN<3>")
	)
	(segment
		(start 45.665898 -367.639092)
		(end 45.470826 -367.834164)
		(width 0.14224)
		(layer "In6.Cu")
		(net "P5E_CPU1_P0_TX_DN<3>")
	)
	(segment
		(start 101.087936 -283.481018)
		(end 101.083872 -283.483304)
		(width 0.1143)
		(layer "In6.Cu")
		(net "P5E_CPU1_P0_TX_DN<3>")
	)
	(segment
		(start 101.74097 -282.996386)
		(end 101.443028 -282.996386)
		(width 0.1143)
		(layer "In6.Cu")
		(net "P5E_CPU1_P0_TX_DN<3>")
	)
	(segment
		(start 100.132642 -289.970464)
		(end 100.112322 -289.981894)
		(width 0.1143)
		(layer "In6.Cu")
		(net "P5E_CPU1_P0_TX_DN<3>")
	)
	(segment
		(start 45.289724 -368.7445)
		(end 45.580554 -369.03533)
		(width 0.14224)
		(layer "In6.Cu")
		(net "P5E_CPU1_P0_TX_DN<3>")
	)
	(segment
		(start 100.144072 -291.583618)
		(end 100.14331 -291.584126)
		(width 0.1143)
		(layer "In6.Cu")
		(net "P5E_CPU1_P0_TX_DN<3>")
	)
	(segment
		(start 100.112322 -292.21049)
		(end 100.148898 -292.231572)
		(width 0.1143)
		(layer "In6.Cu")
		(net "P5E_CPU1_P0_TX_DN<3>")
	)
	(segment
		(start 99.713034 -285.89097)
		(end 99.643438 -285.93161)
		(width 0.1143)
		(layer "In6.Cu")
		(net "P5E_CPU1_P0_TX_DN<3>")
	)
	(segment
		(start 100.112322 -288.970466)
		(end 100.183188 -289.011614)
		(width 0.1143)
		(layer "In6.Cu")
		(net "P5E_CPU1_P0_TX_DN<3>")
	)
	(segment
		(start 100.112322 -287.350454)
		(end 100.180648 -287.390078)
		(width 0.1143)
		(layer "In6.Cu")
		(net "P5E_CPU1_P0_TX_DN<3>")
	)
	(segment
		(start 100.14331 -285.104332)
		(end 100.14204 -285.105094)
		(width 0.1143)
		(layer "In6.Cu")
		(net "P5E_CPU1_P0_TX_DN<3>")
	)
	(segment
		(start 100.139754 -291.586158)
		(end 100.135182 -291.588952)
		(width 0.1143)
		(layer "In6.Cu")
		(net "P5E_CPU1_P0_TX_DN<3>")
	)
	(segment
		(start 100.150168 -292.232334)
		(end 100.151692 -292.23335)
		(width 0.1143)
		(layer "In6.Cu")
		(net "P5E_CPU1_P0_TX_DN<3>")
	)
	(segment
		(start 55.634636 -363.479842)
		(end 45.770292 -367.569242)
		(width 0.14224)
		(layer "In6.Cu")
		(net "P5E_CPU1_P0_TX_DN<3>")
	)
	(segment
		(start 115.264438 -324.877938)
		(end 118.085616 -330.304394)
		(width 0.14224)
		(layer "In6.Cu")
		(net "P5E_CPU1_P0_TX_DN<3>")
	)
	(segment
		(start 99.641406 -286.53994)
		(end 99.713034 -286.581596)
		(width 0.1143)
		(layer "In6.Cu")
		(net "P5E_CPU1_P0_TX_DN<3>")
	)
	(segment
		(start 100.144072 -285.103824)
		(end 100.14331 -285.104332)
		(width 0.1143)
		(layer "In6.Cu")
		(net "P5E_CPU1_P0_TX_DN<3>")
	)
	(segment
		(start 56.453786 -362.723684)
		(end 55.825644 -363.35208)
		(width 0.14224)
		(layer "In6.Cu")
		(net "P5E_CPU1_P0_TX_DN<3>")
	)
	(segment
		(start 100.183188 -291.560758)
		(end 100.145088 -291.58311)
		(width 0.1143)
		(layer "In6.Cu")
		(net "P5E_CPU1_P0_TX_DN<3>")
	)
	(segment
		(start 100.144072 -289.963606)
		(end 100.14331 -289.964114)
		(width 0.1143)
		(layer "In6.Cu")
		(net "P5E_CPU1_P0_TX_DN<3>")
	)
	(segment
		(start 100.135182 -289.96894)
		(end 100.132642 -289.970464)
		(width 0.1143)
		(layer "In6.Cu")
		(net "P5E_CPU1_P0_TX_DN<3>")
	)
	(segment
		(start 100.135182 -285.109158)
		(end 100.132642 -285.110682)
		(width 0.1143)
		(layer "In6.Cu")
		(net "P5E_CPU1_P0_TX_DN<3>")
	)
	(segment
		(start 100.139754 -293.20617)
		(end 100.135182 -293.208964)
		(width 0.1143)
		(layer "In6.Cu")
		(net "P5E_CPU1_P0_TX_DN<3>")
	)
	(segment
		(start 101.443028 -282.996386)
		(end 101.360224 -283.07919)
		(width 0.1143)
		(layer "In6.Cu")
		(net "P5E_CPU1_P0_TX_DN<3>")
	)
	(segment
		(start 100.140516 -291.58565)
		(end 100.139754 -291.586158)
		(width 0.1143)
		(layer "In6.Cu")
		(net "P5E_CPU1_P0_TX_DN<3>")
	)
	(segment
		(start 100.112322 -290.590478)
		(end 100.148898 -290.61156)
		(width 0.1143)
		(layer "In6.Cu")
		(net "P5E_CPU1_P0_TX_DN<3>")
	)
	(segment
		(start 100.14204 -285.105094)
		(end 100.140516 -285.105856)
		(width 0.1143)
		(layer "In6.Cu")
		(net "P5E_CPU1_P0_TX_DN<3>")
	)
	(segment
		(start 110.00613 -318.449706)
		(end 115.194588 -324.772528)
		(width 0.14224)
		(layer "In6.Cu")
		(net "P5E_CPU1_P0_TX_DN<3>")
	)
	(segment
		(start 100.183188 -285.080964)
		(end 100.145088 -285.103316)
		(width 0.1143)
		(layer "In6.Cu")
		(net "P5E_CPU1_P0_TX_DN<3>")
	)
	(segment
		(start 100.132642 -291.590476)
		(end 100.112322 -291.601906)
		(width 0.1143)
		(layer "In6.Cu")
		(net "P5E_CPU1_P0_TX_DN<3>")
	)
	(segment
		(start 100.144072 -293.20363)
		(end 100.14331 -293.204138)
		(width 0.1143)
		(layer "In6.Cu")
		(net "P5E_CPU1_P0_TX_DN<3>")
	)
	(segment
		(start 118.197884 -330.70927)
		(end 119.769128 -339.451188)
		(width 0.14224)
		(layer "In6.Cu")
		(net "P5E_CPU1_P0_TX_DN<3>")
	)
	(segment
		(start 100.112322 -293.830502)
		(end 100.148898 -293.851584)
		(width 0.1143)
		(layer "In6.Cu")
		(net "P5E_CPU1_P0_TX_DN<3>")
	)
	(segment
		(start 100.150168 -290.612322)
		(end 100.151692 -290.613338)
		(width 0.1143)
		(layer "In6.Cu")
		(net "P5E_CPU1_P0_TX_DN<3>")
	)
	(segment
		(start 99.542092 -299.099986)
		(end 103.60787 -308.91734)
		(width 0.14224)
		(layer "In6.Cu")
		(net "P5E_CPU1_P0_TX_DN<3>")
	)
	(segment
		(start 100.384864 -360.086656)
		(end 73.336404 -360.086656)
		(width 0.14224)
		(layer "In6.Cu")
		(net "P5E_CPU1_P0_TX_DN<3>")
	)
	(segment
		(start 100.14204 -291.584888)
		(end 100.140516 -291.58565)
		(width 0.1143)
		(layer "In6.Cu")
		(net "P5E_CPU1_P0_TX_DN<3>")
	)
	(segment
		(start 119.326406 -343.557098)
		(end 117.212872 -348.65945)
		(width 0.14224)
		(layer "In6.Cu")
		(net "P5E_CPU1_P0_TX_DN<3>")
	)
	(segment
		(start 100.14204 -293.2049)
		(end 100.140516 -293.205662)
		(width 0.1143)
		(layer "In6.Cu")
		(net "P5E_CPU1_P0_TX_DN<3>")
	)
	(arc
		(start 101.082856 -283.483812)
		(mid 100.946408 -283.620111)
		(end 100.89642 -283.806392)
		(width 0.1143)
		(layer "In6.Cu")
		(net "P5E_CPU1_P0_TX_DN<3>")
	)
	(arc
		(start 99.956366 -287.046162)
		(mid 99.997621 -287.217133)
		(end 100.112322 -287.350454)
		(width 0.1143)
		(layer "In6.Cu")
		(net "P5E_CPU1_P0_TX_DN<3>")
	)
	(arc
		(start 64.258952 -359.49636)
		(mid 64.179829 -359.513274)
		(end 64.101472 -359.533444)
		(width 0.14224)
		(layer "In6.Cu")
		(net "P5E_CPU1_P0_TX_DN<3>")
	)
	(arc
		(start 100.110544 -288.363406)
		(mid 99.997137 -288.496295)
		(end 99.956366 -288.666174)
		(width 0.1143)
		(layer "In6.Cu")
		(net "P5E_CPU1_P0_TX_DN<3>")
	)
	(arc
		(start 100.112322 -293.221918)
		(mid 99.956394 -293.52621)
		(end 100.112322 -293.830502)
		(width 0.1143)
		(layer "In6.Cu")
		(net "P5E_CPU1_P0_TX_DN<3>")
	)
	(arc
		(start 100.183188 -292.251638)
		(mid 100.426515 -292.716204)
		(end 100.183188 -293.18077)
		(width 0.1143)
		(layer "In6.Cu")
		(net "P5E_CPU1_P0_TX_DN<3>")
	)
	(arc
		(start 99.486466 -286.23641)
		(mid 99.527432 -286.406816)
		(end 99.641406 -286.53994)
		(width 0.1143)
		(layer "In6.Cu")
		(net "P5E_CPU1_P0_TX_DN<3>")
	)
	(arc
		(start 100.42652 -284.616398)
		(mid 100.362005 -284.878617)
		(end 100.183188 -285.080964)
		(width 0.1143)
		(layer "In6.Cu")
		(net "P5E_CPU1_P0_TX_DN<3>")
	)
	(arc
		(start 103.60787 -308.91734)
		(mid 103.649837 -309.006228)
		(end 103.700326 -309.090568)
		(width 0.14224)
		(layer "In6.Cu")
		(net "P5E_CPU1_P0_TX_DN<3>")
	)
	(arc
		(start 100.183188 -289.011614)
		(mid 100.426515 -289.47618)
		(end 100.183188 -289.940746)
		(width 0.1143)
		(layer "In6.Cu")
		(net "P5E_CPU1_P0_TX_DN<3>")
	)
	(arc
		(start 55.825644 -363.35208)
		(mid 55.736414 -363.42534)
		(end 55.634636 -363.479842)
		(width 0.14224)
		(layer "In6.Cu")
		(net "P5E_CPU1_P0_TX_DN<3>")
	)
	(arc
		(start 119.769128 -339.451188)
		(mid 119.842604 -341.535936)
		(end 119.326406 -343.557098)
		(width 0.14224)
		(layer "In6.Cu")
		(net "P5E_CPU1_P0_TX_DN<3>")
	)
	(arc
		(start 100.180648 -287.390078)
		(mid 100.426536 -287.854872)
		(end 100.183188 -288.320988)
		(width 0.1143)
		(layer "In6.Cu")
		(net "P5E_CPU1_P0_TX_DN<3>")
	)
	(arc
		(start 100.112322 -291.601906)
		(mid 99.956394 -291.906198)
		(end 100.112322 -292.21049)
		(width 0.1143)
		(layer "In6.Cu")
		(net "P5E_CPU1_P0_TX_DN<3>")
	)
	(arc
		(start 45.470826 -367.834164)
		(mid 45.336817 -368.034723)
		(end 45.289724 -368.271298)
		(width 0.14224)
		(layer "In6.Cu")
		(net "P5E_CPU1_P0_TX_DN<3>")
	)
	(arc
		(start 99.581208 -295.85412)
		(mid 99.511283 -295.958769)
		(end 99.48672 -296.082212)
		(width 0.1143)
		(layer "In6.Cu")
		(net "P5E_CPU1_P0_TX_DN<3>")
	)
	(arc
		(start 73.336404 -360.086656)
		(mid 73.105542 -360.063974)
		(end 72.883522 -359.99674)
		(width 0.14224)
		(layer "In6.Cu")
		(net "P5E_CPU1_P0_TX_DN<3>")
	)
	(arc
		(start 101.360224 -283.07919)
		(mid 101.358435 -283.090512)
		(end 101.356414 -283.101796)
		(width 0.1143)
		(layer "In6.Cu")
		(net "P5E_CPU1_P0_TX_DN<3>")
	)
	(arc
		(start 99.956112 -295.146984)
		(mid 99.893323 -295.456144)
		(end 99.717352 -295.717976)
		(width 0.1143)
		(layer "In6.Cu")
		(net "P5E_CPU1_P0_TX_DN<3>")
	)
	(arc
		(start 115.194842 -324.772528)
		(mid 115.232392 -324.823417)
		(end 115.264438 -324.877938)
		(width 0.14224)
		(layer "In6.Cu")
		(net "P5E_CPU1_P0_TX_DN<3>")
	)
	(arc
		(start 99.643438 -285.93161)
		(mid 99.528011 -286.064986)
		(end 99.486466 -286.23641)
		(width 0.1143)
		(layer "In6.Cu")
		(net "P5E_CPU1_P0_TX_DN<3>")
	)
	(arc
		(start 100.612702 -360.017568)
		(mid 100.503921 -360.069064)
		(end 100.384864 -360.086656)
		(width 0.14224)
		(layer "In6.Cu")
		(net "P5E_CPU1_P0_TX_DN<3>")
	)
	(arc
		(start 56.57342 -362.643674)
		(mid 56.509671 -362.677799)
		(end 56.453786 -362.723684)
		(width 0.14224)
		(layer "In6.Cu")
		(net "P5E_CPU1_P0_TX_DN<3>")
	)
	(arc
		(start 64.101472 -359.533444)
		(mid 64.040264 -359.552579)
		(end 63.980314 -359.575354)
		(width 0.14224)
		(layer "In6.Cu")
		(net "P5E_CPU1_P0_TX_DN<3>")
	)
	(arc
		(start 71.705978 -359.50906)
		(mid 71.552593 -359.462398)
		(end 71.39305 -359.446576)
		(width 0.14224)
		(layer "In6.Cu")
		(net "P5E_CPU1_P0_TX_DN<3>")
	)
	(arc
		(start 100.583492 -284.311598)
		(mid 100.468065 -284.444974)
		(end 100.42652 -284.616398)
		(width 0.1143)
		(layer "In6.Cu")
		(net "P5E_CPU1_P0_TX_DN<3>")
	)
	(arc
		(start 117.212872 -348.65945)
		(mid 117.028712 -348.966956)
		(end 116.763292 -349.207836)
		(width 0.14224)
		(layer "In6.Cu")
		(net "P5E_CPU1_P0_TX_DN<3>")
	)
	(arc
		(start 99.956366 -288.666174)
		(mid 99.997621 -288.837145)
		(end 100.112322 -288.970466)
		(width 0.1143)
		(layer "In6.Cu")
		(net "P5E_CPU1_P0_TX_DN<3>")
	)
	(arc
		(start 99.956366 -285.426404)
		(mid 99.891851 -285.688623)
		(end 99.713034 -285.89097)
		(width 0.1143)
		(layer "In6.Cu")
		(net "P5E_CPU1_P0_TX_DN<3>")
	)
	(arc
		(start 100.183188 -290.631626)
		(mid 100.426515 -291.096192)
		(end 100.183188 -291.560758)
		(width 0.1143)
		(layer "In6.Cu")
		(net "P5E_CPU1_P0_TX_DN<3>")
	)
	(arc
		(start 99.53244 -299.051218)
		(mid 99.534886 -299.076071)
		(end 99.542092 -299.099986)
		(width 0.14224)
		(layer "In6.Cu")
		(net "P5E_CPU1_P0_TX_DN<3>")
	)
	(arc
		(start 100.112322 -289.981894)
		(mid 99.956394 -290.286186)
		(end 100.112322 -290.590478)
		(width 0.1143)
		(layer "In6.Cu")
		(net "P5E_CPU1_P0_TX_DN<3>")
	)
	(arc
		(start 100.112322 -285.122112)
		(mid 99.997646 -285.255446)
		(end 99.956366 -285.426404)
		(width 0.1143)
		(layer "In6.Cu")
		(net "P5E_CPU1_P0_TX_DN<3>")
	)
	(arc
		(start 100.112322 -294.84193)
		(mid 100.002955 -294.965276)
		(end 99.957128 -295.123616)
		(width 0.1143)
		(layer "In6.Cu")
		(net "P5E_CPU1_P0_TX_DN<3>")
	)
	(arc
		(start 109.6264 -317.958724)
		(mid 109.812681 -318.206987)
		(end 110.00613 -318.449706)
		(width 0.14224)
		(layer "In6.Cu")
		(net "P5E_CPU1_P0_TX_DN<3>")
	)
	(arc
		(start 64.783208 -359.446576)
		(mid 64.519901 -359.459049)
		(end 64.258952 -359.49636)
		(width 0.14224)
		(layer "In6.Cu")
		(net "P5E_CPU1_P0_TX_DN<3>")
	)
	(arc
		(start 100.183188 -293.87165)
		(mid 100.426515 -294.336216)
		(end 100.183188 -294.800782)
		(width 0.1143)
		(layer "In6.Cu")
		(net "P5E_CPU1_P0_TX_DN<3>")
	)
	(arc
		(start 99.713034 -286.581596)
		(mid 99.891847 -286.783946)
		(end 99.956366 -287.046162)
		(width 0.1143)
		(layer "In6.Cu")
		(net "P5E_CPU1_P0_TX_DN<3>")
	)
	(arc
		(start 101.356414 -283.101796)
		(mid 101.263446 -283.320625)
		(end 101.087936 -283.481018)
		(width 0.1143)
		(layer "In6.Cu")
		(net "P5E_CPU1_P0_TX_DN<3>")
	)
	(arc
		(start 118.154196 -330.491846)
		(mid 118.177171 -330.600331)
		(end 118.197884 -330.70927)
		(width 0.14224)
		(layer "In6.Cu")
		(net "P5E_CPU1_P0_TX_DN<3>")
	)
	(arc
		(start 99.957128 -295.123616)
		(mid 99.956578 -295.134913)
		(end 99.956366 -295.146222)
		(width 0.1143)
		(layer "In6.Cu")
		(net "P5E_CPU1_P0_TX_DN<3>")
	)
	(arc
		(start 45.770292 -367.569242)
		(mid 45.714653 -367.599026)
		(end 45.665898 -367.639092)
		(width 0.14224)
		(layer "In6.Cu")
		(net "P5E_CPU1_P0_TX_DN<3>")
	)
	(arc
		(start 100.89642 -283.806392)
		(mid 100.831905 -284.068611)
		(end 100.653088 -284.270958)
		(width 0.1143)
		(layer "In6.Cu")
		(net "P5E_CPU1_P0_TX_DN<3>")
	)
	(arc
		(start 118.085616 -330.304394)
		(mid 118.125995 -330.395891)
		(end 118.154196 -330.491846)
		(width 0.14224)
		(layer "In6.Cu")
		(net "P5E_CPU1_P0_TX_DN<3>")
	)
	(segment
		(start 43.608244 -372.47322)
		(end 43.904154 -372.76913)
		(width 0.12954)
		(layer "F.Cu")
		(net "P5E_CPU1_P0_TX_DN<2>")
	)
	(segment
		(start 43.608244 -371.76964)
		(end 43.608244 -372.47322)
		(width 0.12954)
		(layer "F.Cu")
		(net "P5E_CPU1_P0_TX_DN<2>")
	)
	(segment
		(start 99.387914 -281.110436)
		(end 98.921062 -281.376374)
		(width 0.12954)
		(layer "F.Cu")
		(net "P5E_CPU1_P0_TX_DN<2>")
	)
	(segment
		(start 43.878754 -371.49913)
		(end 43.608244 -371.76964)
		(width 0.12954)
		(layer "F.Cu")
		(net "P5E_CPU1_P0_TX_DN<2>")
	)
	(segment
		(start 73.004426 -359.015284)
		(end 71.949818 -358.578404)
		(width 0.14224)
		(layer "In6.Cu")
		(net "P5E_CPU1_P0_TX_DN<2>")
	)
	(segment
		(start 63.722758 -358.65689)
		(end 55.998364 -361.860084)
		(width 0.14224)
		(layer "In6.Cu")
		(net "P5E_CPU1_P0_TX_DN<2>")
	)
	(segment
		(start 99.243134 -291.560758)
		(end 99.204018 -291.583618)
		(width 0.1143)
		(layer "In6.Cu")
		(net "P5E_CPU1_P0_TX_DN<2>")
	)
	(segment
		(start 115.781074 -348.740476)
		(end 100.430076 -359.016046)
		(width 0.14224)
		(layer "In6.Cu")
		(net "P5E_CPU1_P0_TX_DN<2>")
	)
	(segment
		(start 99.172268 -287.350454)
		(end 99.240594 -287.390078)
		(width 0.1143)
		(layer "In6.Cu")
		(net "P5E_CPU1_P0_TX_DN<2>")
	)
	(segment
		(start 99.21367 -283.478478)
		(end 99.21113 -283.480002)
		(width 0.1143)
		(layer "In6.Cu")
		(net "P5E_CPU1_P0_TX_DN<2>")
	)
	(segment
		(start 99.204018 -290.608766)
		(end 99.243134 -290.631626)
		(width 0.1143)
		(layer "In6.Cu")
		(net "P5E_CPU1_P0_TX_DN<2>")
	)
	(segment
		(start 99.21621 -283.476954)
		(end 99.214686 -283.47797)
		(width 0.1143)
		(layer "In6.Cu")
		(net "P5E_CPU1_P0_TX_DN<2>")
	)
	(segment
		(start 44.571666 -367.078768)
		(end 44.451524 -367.19891)
		(width 0.14224)
		(layer "In6.Cu")
		(net "P5E_CPU1_P0_TX_DN<2>")
	)
	(segment
		(start 99.242118 -283.461714)
		(end 99.219004 -283.475176)
		(width 0.1143)
		(layer "In6.Cu")
		(net "P5E_CPU1_P0_TX_DN<2>")
	)
	(segment
		(start 98.62312 -281.376374)
		(end 98.55327 -281.446224)
		(width 0.1143)
		(layer "In6.Cu")
		(net "P5E_CPU1_P0_TX_DN<2>")
	)
	(segment
		(start 43.587924 -369.283996)
		(end 43.587924 -371.2083)
		(width 0.14224)
		(layer "In6.Cu")
		(net "P5E_CPU1_P0_TX_DN<2>")
	)
	(segment
		(start 98.546412 -296.058844)
		(end 98.546412 -296.20718)
		(width 0.1143)
		(layer "In6.Cu")
		(net "P5E_CPU1_P0_TX_DN<2>")
	)
	(segment
		(start 55.998364 -361.860084)
		(end 55.403496 -362.454952)
		(width 0.14224)
		(layer "In6.Cu")
		(net "P5E_CPU1_P0_TX_DN<2>")
	)
	(segment
		(start 99.204018 -291.583618)
		(end 99.172268 -291.601906)
		(width 0.1143)
		(layer "In6.Cu")
		(net "P5E_CPU1_P0_TX_DN<2>")
	)
	(segment
		(start 71.600314 -358.508808)
		(end 64.466724 -358.508808)
		(width 0.14224)
		(layer "In6.Cu")
		(net "P5E_CPU1_P0_TX_DN<2>")
	)
	(segment
		(start 98.703892 -286.540956)
		(end 98.77044 -286.579818)
		(width 0.1143)
		(layer "In6.Cu")
		(net "P5E_CPU1_P0_TX_DN<2>")
	)
	(segment
		(start 99.033838 -285.332678)
		(end 99.011994 -285.499556)
		(width 0.1143)
		(layer "In6.Cu")
		(net "P5E_CPU1_P0_TX_DN<2>")
	)
	(segment
		(start 109.106208 -318.849756)
		(end 114.356896 -325.247762)
		(width 0.14224)
		(layer "In6.Cu")
		(net "P5E_CPU1_P0_TX_DN<2>")
	)
	(segment
		(start 99.172268 -293.830502)
		(end 99.204018 -293.84879)
		(width 0.1143)
		(layer "In6.Cu")
		(net "P5E_CPU1_P0_TX_DN<2>")
	)
	(segment
		(start 98.921062 -281.376374)
		(end 98.62312 -281.376374)
		(width 0.1143)
		(layer "In6.Cu")
		(net "P5E_CPU1_P0_TX_DN<2>")
	)
	(segment
		(start 99.173284 -288.361374)
		(end 99.17049 -288.363406)
		(width 0.1143)
		(layer "In6.Cu")
		(net "P5E_CPU1_P0_TX_DN<2>")
	)
	(segment
		(start 98.546412 -286.23641)
		(end 98.546412 -286.246824)
		(width 0.1143)
		(layer "In6.Cu")
		(net "P5E_CPU1_P0_TX_DN<2>")
	)
	(segment
		(start 98.592132 -296.281348)
		(end 98.592132 -299.123354)
		(width 0.14224)
		(layer "In6.Cu")
		(net "P5E_CPU1_P0_TX_DN<2>")
	)
	(segment
		(start 99.165918 -287.345882)
		(end 99.172268 -287.350454)
		(width 0.1143)
		(layer "In6.Cu")
		(net "P5E_CPU1_P0_TX_DN<2>")
	)
	(segment
		(start 99.204018 -293.84879)
		(end 99.243134 -293.87165)
		(width 0.1143)
		(layer "In6.Cu")
		(net "P5E_CPU1_P0_TX_DN<2>")
	)
	(segment
		(start 98.77044 -285.892748)
		(end 98.702368 -285.932118)
		(width 0.1143)
		(layer "In6.Cu")
		(net "P5E_CPU1_P0_TX_DN<2>")
	)
	(segment
		(start 117.289072 -330.985622)
		(end 118.812818 -339.46465)
		(width 0.14224)
		(layer "In6.Cu")
		(net "P5E_CPU1_P0_TX_DN<2>")
	)
	(segment
		(start 99.172268 -292.21049)
		(end 99.204018 -292.228778)
		(width 0.1143)
		(layer "In6.Cu")
		(net "P5E_CPU1_P0_TX_DN<2>")
	)
	(segment
		(start 114.457734 -325.400416)
		(end 117.183916 -330.613512)
		(width 0.14224)
		(layer "In6.Cu")
		(net "P5E_CPU1_P0_TX_DN<2>")
	)
	(segment
		(start 118.411752 -343.18448)
		(end 116.4463 -347.9292)
		(width 0.14224)
		(layer "In6.Cu")
		(net "P5E_CPU1_P0_TX_DN<2>")
	)
	(segment
		(start 99.243134 -293.18077)
		(end 99.204018 -293.20363)
		(width 0.1143)
		(layer "In6.Cu")
		(net "P5E_CPU1_P0_TX_DN<2>")
	)
	(segment
		(start 99.243134 -288.320988)
		(end 99.173284 -288.361374)
		(width 0.1143)
		(layer "In6.Cu")
		(net "P5E_CPU1_P0_TX_DN<2>")
	)
	(segment
		(start 99.205034 -294.823134)
		(end 99.204018 -294.823642)
		(width 0.1143)
		(layer "In6.Cu")
		(net "P5E_CPU1_P0_TX_DN<2>")
	)
	(segment
		(start 99.204018 -288.988754)
		(end 99.243134 -289.011614)
		(width 0.1143)
		(layer "In6.Cu")
		(net "P5E_CPU1_P0_TX_DN<2>")
	)
	(segment
		(start 99.204018 -289.963606)
		(end 99.172268 -289.981894)
		(width 0.1143)
		(layer "In6.Cu")
		(net "P5E_CPU1_P0_TX_DN<2>")
	)
	(segment
		(start 99.172268 -290.590478)
		(end 99.204018 -290.608766)
		(width 0.1143)
		(layer "In6.Cu")
		(net "P5E_CPU1_P0_TX_DN<2>")
	)
	(segment
		(start 99.308412 -284.20441)
		(end 99.312476 -284.208474)
		(width 0.1143)
		(layer "In6.Cu")
		(net "P5E_CPU1_P0_TX_DN<2>")
	)
	(segment
		(start 98.691954 -286.533082)
		(end 98.70059 -286.539178)
		(width 0.1143)
		(layer "In6.Cu")
		(net "P5E_CPU1_P0_TX_DN<2>")
	)
	(segment
		(start 98.640646 -299.367194)
		(end 102.847648 -309.524146)
		(width 0.14224)
		(layer "In6.Cu")
		(net "P5E_CPU1_P0_TX_DN<2>")
	)
	(segment
		(start 54.964838 -362.748068)
		(end 44.676314 -367.008918)
		(width 0.14224)
		(layer "In6.Cu")
		(net "P5E_CPU1_P0_TX_DN<2>")
	)
	(segment
		(start 99.203256 -294.82415)
		(end 99.172268 -294.84193)
		(width 0.1143)
		(layer "In6.Cu")
		(net "P5E_CPU1_P0_TX_DN<2>")
	)
	(segment
		(start 99.214686 -283.47797)
		(end 99.21367 -283.478478)
		(width 0.1143)
		(layer "In6.Cu")
		(net "P5E_CPU1_P0_TX_DN<2>")
	)
	(segment
		(start 99.172268 -284.110684)
		(end 99.229672 -284.143958)
		(width 0.1143)
		(layer "In6.Cu")
		(net "P5E_CPU1_P0_TX_DN<2>")
	)
	(segment
		(start 99.016312 -295.146222)
		(end 99.016312 -295.150794)
		(width 0.1143)
		(layer "In6.Cu")
		(net "P5E_CPU1_P0_TX_DN<2>")
	)
	(segment
		(start 99.204018 -293.20363)
		(end 99.172268 -293.221918)
		(width 0.1143)
		(layer "In6.Cu")
		(net "P5E_CPU1_P0_TX_DN<2>")
	)
	(segment
		(start 98.70059 -286.539178)
		(end 98.703892 -286.540956)
		(width 0.1143)
		(layer "In6.Cu")
		(net "P5E_CPU1_P0_TX_DN<2>")
	)
	(segment
		(start 99.204018 -294.823642)
		(end 99.203256 -294.82415)
		(width 0.1143)
		(layer "In6.Cu")
		(net "P5E_CPU1_P0_TX_DN<2>")
	)
	(segment
		(start 98.592132 -296.2529)
		(end 98.592132 -296.281348)
		(width 0.1143)
		(layer "In6.Cu")
		(net "P5E_CPU1_P0_TX_DN<2>")
	)
	(segment
		(start 99.21113 -283.480002)
		(end 99.172268 -283.5021)
		(width 0.1143)
		(layer "In6.Cu")
		(net "P5E_CPU1_P0_TX_DN<2>")
	)
	(segment
		(start 98.856546 -295.537128)
		(end 98.696526 -295.697402)
		(width 0.1143)
		(layer "In6.Cu")
		(net "P5E_CPU1_P0_TX_DN<2>")
	)
	(segment
		(start 99.312476 -284.208474)
		(end 99.314508 -284.210252)
		(width 0.1143)
		(layer "In6.Cu")
		(net "P5E_CPU1_P0_TX_DN<2>")
	)
	(segment
		(start 98.702368 -281.680666)
		(end 98.726498 -281.694128)
		(width 0.1143)
		(layer "In6.Cu")
		(net "P5E_CPU1_P0_TX_DN<2>")
	)
	(segment
		(start 99.196144 -282.504642)
		(end 99.248468 -282.537408)
		(width 0.1143)
		(layer "In6.Cu")
		(net "P5E_CPU1_P0_TX_DN<2>")
	)
	(segment
		(start 99.01809 -282.189428)
		(end 99.01809 -282.199842)
		(width 0.1143)
		(layer "In6.Cu")
		(net "P5E_CPU1_P0_TX_DN<2>")
	)
	(segment
		(start 99.30003 -285.032704)
		(end 99.139502 -285.152338)
		(width 0.1143)
		(layer "In6.Cu")
		(net "P5E_CPU1_P0_TX_DN<2>")
	)
	(segment
		(start 99.243134 -289.940746)
		(end 99.204018 -289.963606)
		(width 0.1143)
		(layer "In6.Cu")
		(net "P5E_CPU1_P0_TX_DN<2>")
	)
	(segment
		(start 99.172268 -288.970466)
		(end 99.204018 -288.988754)
		(width 0.1143)
		(layer "In6.Cu")
		(net "P5E_CPU1_P0_TX_DN<2>")
	)
	(segment
		(start 43.587924 -371.2083)
		(end 43.878754 -371.49913)
		(width 0.14224)
		(layer "In6.Cu")
		(net "P5E_CPU1_P0_TX_DN<2>")
	)
	(segment
		(start 99.193096 -282.503118)
		(end 99.196144 -282.504642)
		(width 0.1143)
		(layer "In6.Cu")
		(net "P5E_CPU1_P0_TX_DN<2>")
	)
	(segment
		(start 102.89159 -309.606442)
		(end 108.718858 -318.327532)
		(width 0.14224)
		(layer "In6.Cu")
		(net "P5E_CPU1_P0_TX_DN<2>")
	)
	(segment
		(start 99.016312 -287.046162)
		(end 99.016312 -287.053782)
		(width 0.1143)
		(layer "In6.Cu")
		(net "P5E_CPU1_P0_TX_DN<2>")
	)
	(segment
		(start 99.204018 -292.228778)
		(end 99.243134 -292.251638)
		(width 0.1143)
		(layer "In6.Cu")
		(net "P5E_CPU1_P0_TX_DN<2>")
	)
	(segment
		(start 99.997514 -359.147364)
		(end 73.669398 -359.147364)
		(width 0.14224)
		(layer "In6.Cu")
		(net "P5E_CPU1_P0_TX_DN<2>")
	)
	(segment
		(start 99.219004 -283.475176)
		(end 99.21621 -283.476954)
		(width 0.1143)
		(layer "In6.Cu")
		(net "P5E_CPU1_P0_TX_DN<2>")
	)
	(segment
		(start 98.546412 -296.20718)
		(end 98.592132 -296.2529)
		(width 0.1143)
		(layer "In6.Cu")
		(net "P5E_CPU1_P0_TX_DN<2>")
	)
	(segment
		(start 99.43465 -284.86354)
		(end 99.430078 -284.872938)
		(width 0.1143)
		(layer "In6.Cu")
		(net "P5E_CPU1_P0_TX_DN<2>")
	)
	(segment
		(start 99.314508 -284.210252)
		(end 99.316794 -284.212538)
		(width 0.1143)
		(layer "In6.Cu")
		(net "P5E_CPU1_P0_TX_DN<2>")
	)
	(segment
		(start 99.243134 -294.800782)
		(end 99.205034 -294.823134)
		(width 0.1143)
		(layer "In6.Cu")
		(net "P5E_CPU1_P0_TX_DN<2>")
	)
	(arc
		(start 99.172268 -291.601906)
		(mid 99.020679 -291.906198)
		(end 99.172268 -292.21049)
		(width 0.1143)
		(layer "In6.Cu")
		(net "P5E_CPU1_P0_TX_DN<2>")
	)
	(arc
		(start 99.011994 -285.499556)
		(mid 98.933137 -285.721899)
		(end 98.77044 -285.892748)
		(width 0.1143)
		(layer "In6.Cu")
		(net "P5E_CPU1_P0_TX_DN<2>")
	)
	(arc
		(start 108.718858 -318.327532)
		(mid 108.906149 -318.593379)
		(end 109.106208 -318.849756)
		(width 0.14224)
		(layer "In6.Cu")
		(net "P5E_CPU1_P0_TX_DN<2>")
	)
	(arc
		(start 99.172268 -283.5021)
		(mid 99.023171 -283.806392)
		(end 99.172268 -284.110684)
		(width 0.1143)
		(layer "In6.Cu")
		(net "P5E_CPU1_P0_TX_DN<2>")
	)
	(arc
		(start 99.316794 -284.212538)
		(mid 99.48304 -284.518607)
		(end 99.43465 -284.86354)
		(width 0.1143)
		(layer "In6.Cu")
		(net "P5E_CPU1_P0_TX_DN<2>")
	)
	(arc
		(start 99.455732 -282.812744)
		(mid 99.458047 -283.173146)
		(end 99.242118 -283.461714)
		(width 0.1143)
		(layer "In6.Cu")
		(net "P5E_CPU1_P0_TX_DN<2>")
	)
	(arc
		(start 98.696526 -295.697402)
		(mid 98.585477 -295.863175)
		(end 98.546412 -296.058844)
		(width 0.1143)
		(layer "In6.Cu")
		(net "P5E_CPU1_P0_TX_DN<2>")
	)
	(arc
		(start 99.172268 -293.221918)
		(mid 99.023171 -293.52621)
		(end 99.172268 -293.830502)
		(width 0.1143)
		(layer "In6.Cu")
		(net "P5E_CPU1_P0_TX_DN<2>")
	)
	(arc
		(start 98.702368 -285.932118)
		(mid 98.587692 -286.065452)
		(end 98.546412 -286.23641)
		(width 0.1143)
		(layer "In6.Cu")
		(net "P5E_CPU1_P0_TX_DN<2>")
	)
	(arc
		(start 117.183916 -330.613512)
		(mid 117.224739 -330.706318)
		(end 117.25275 -330.803758)
		(width 0.14224)
		(layer "In6.Cu")
		(net "P5E_CPU1_P0_TX_DN<2>")
	)
	(arc
		(start 99.17049 -288.363406)
		(mid 99.057083 -288.496295)
		(end 99.016312 -288.666174)
		(width 0.1143)
		(layer "In6.Cu")
		(net "P5E_CPU1_P0_TX_DN<2>")
	)
	(arc
		(start 99.240594 -287.390078)
		(mid 99.421246 -287.592823)
		(end 99.486466 -287.856422)
		(width 0.1143)
		(layer "In6.Cu")
		(net "P5E_CPU1_P0_TX_DN<2>")
	)
	(arc
		(start 64.466724 -358.508808)
		(mid 64.08744 -358.54618)
		(end 63.722758 -358.65689)
		(width 0.14224)
		(layer "In6.Cu")
		(net "P5E_CPU1_P0_TX_DN<2>")
	)
	(arc
		(start 118.812818 -339.46465)
		(mid 118.879352 -341.353357)
		(end 118.411752 -343.18448)
		(width 0.14224)
		(layer "In6.Cu")
		(net "P5E_CPU1_P0_TX_DN<2>")
	)
	(arc
		(start 99.139502 -285.152338)
		(mid 99.068411 -285.231806)
		(end 99.033838 -285.332678)
		(width 0.1143)
		(layer "In6.Cu")
		(net "P5E_CPU1_P0_TX_DN<2>")
	)
	(arc
		(start 99.172268 -289.981894)
		(mid 99.023171 -290.286186)
		(end 99.172268 -290.590478)
		(width 0.1143)
		(layer "In6.Cu")
		(net "P5E_CPU1_P0_TX_DN<2>")
	)
	(arc
		(start 99.243134 -289.011614)
		(mid 99.486461 -289.47618)
		(end 99.243134 -289.940746)
		(width 0.1143)
		(layer "In6.Cu")
		(net "P5E_CPU1_P0_TX_DN<2>")
	)
	(arc
		(start 99.248468 -282.537408)
		(mid 99.373875 -282.658677)
		(end 99.455732 -282.812744)
		(width 0.1143)
		(layer "In6.Cu")
		(net "P5E_CPU1_P0_TX_DN<2>")
	)
	(arc
		(start 99.016312 -287.053782)
		(mid 99.055892 -287.21787)
		(end 99.165918 -287.345882)
		(width 0.1143)
		(layer "In6.Cu")
		(net "P5E_CPU1_P0_TX_DN<2>")
	)
	(arc
		(start 100.430076 -359.016046)
		(mid 100.223547 -359.113817)
		(end 99.997514 -359.147364)
		(width 0.14224)
		(layer "In6.Cu")
		(net "P5E_CPU1_P0_TX_DN<2>")
	)
	(arc
		(start 73.669398 -359.147364)
		(mid 73.330406 -359.114077)
		(end 73.004426 -359.015284)
		(width 0.14224)
		(layer "In6.Cu")
		(net "P5E_CPU1_P0_TX_DN<2>")
	)
	(arc
		(start 116.4463 -347.9292)
		(mid 116.173785 -348.384121)
		(end 115.781074 -348.740476)
		(width 0.14224)
		(layer "In6.Cu")
		(net "P5E_CPU1_P0_TX_DN<2>")
	)
	(arc
		(start 99.486466 -287.856422)
		(mid 99.421951 -288.118641)
		(end 99.243134 -288.320988)
		(width 0.1143)
		(layer "In6.Cu")
		(net "P5E_CPU1_P0_TX_DN<2>")
	)
	(arc
		(start 99.01809 -282.199842)
		(mid 99.064981 -282.374914)
		(end 99.193096 -282.503118)
		(width 0.1143)
		(layer "In6.Cu")
		(net "P5E_CPU1_P0_TX_DN<2>")
	)
	(arc
		(start 98.77044 -286.579818)
		(mid 98.951092 -286.782563)
		(end 99.016312 -287.046162)
		(width 0.1143)
		(layer "In6.Cu")
		(net "P5E_CPU1_P0_TX_DN<2>")
	)
	(arc
		(start 99.243134 -292.251638)
		(mid 99.486461 -292.716204)
		(end 99.243134 -293.18077)
		(width 0.1143)
		(layer "In6.Cu")
		(net "P5E_CPU1_P0_TX_DN<2>")
	)
	(arc
		(start 98.726498 -281.694128)
		(mid 98.939792 -281.902044)
		(end 99.01809 -282.189428)
		(width 0.1143)
		(layer "In6.Cu")
		(net "P5E_CPU1_P0_TX_DN<2>")
	)
	(arc
		(start 99.243134 -290.631626)
		(mid 99.486461 -291.096192)
		(end 99.243134 -291.560758)
		(width 0.1143)
		(layer "In6.Cu")
		(net "P5E_CPU1_P0_TX_DN<2>")
	)
	(arc
		(start 99.229672 -284.143958)
		(mid 99.271024 -284.171604)
		(end 99.308412 -284.20441)
		(width 0.1143)
		(layer "In6.Cu")
		(net "P5E_CPU1_P0_TX_DN<2>")
	)
	(arc
		(start 99.172268 -294.84193)
		(mid 99.060471 -294.976731)
		(end 99.016312 -295.146222)
		(width 0.1143)
		(layer "In6.Cu")
		(net "P5E_CPU1_P0_TX_DN<2>")
	)
	(arc
		(start 44.451524 -367.19891)
		(mid 43.812368 -368.15557)
		(end 43.587924 -369.283996)
		(width 0.14224)
		(layer "In6.Cu")
		(net "P5E_CPU1_P0_TX_DN<2>")
	)
	(arc
		(start 102.847648 -309.524146)
		(mid 102.867597 -309.566374)
		(end 102.89159 -309.606442)
		(width 0.14224)
		(layer "In6.Cu")
		(net "P5E_CPU1_P0_TX_DN<2>")
	)
	(arc
		(start 99.016312 -295.150794)
		(mid 98.974841 -295.359845)
		(end 98.856546 -295.537128)
		(width 0.1143)
		(layer "In6.Cu")
		(net "P5E_CPU1_P0_TX_DN<2>")
	)
	(arc
		(start 117.25275 -330.803758)
		(mid 117.271733 -330.894526)
		(end 117.289072 -330.985622)
		(width 0.14224)
		(layer "In6.Cu")
		(net "P5E_CPU1_P0_TX_DN<2>")
	)
	(arc
		(start 98.546412 -286.246824)
		(mid 98.584829 -286.407421)
		(end 98.691954 -286.533082)
		(width 0.1143)
		(layer "In6.Cu")
		(net "P5E_CPU1_P0_TX_DN<2>")
	)
	(arc
		(start 98.592132 -299.123354)
		(mid 98.604379 -299.247664)
		(end 98.640646 -299.367194)
		(width 0.14224)
		(layer "In6.Cu")
		(net "P5E_CPU1_P0_TX_DN<2>")
	)
	(arc
		(start 99.016312 -288.666174)
		(mid 99.060383 -288.83571)
		(end 99.172268 -288.970466)
		(width 0.1143)
		(layer "In6.Cu")
		(net "P5E_CPU1_P0_TX_DN<2>")
	)
	(arc
		(start 71.949818 -358.578404)
		(mid 71.778496 -358.526371)
		(end 71.600314 -358.508808)
		(width 0.14224)
		(layer "In6.Cu")
		(net "P5E_CPU1_P0_TX_DN<2>")
	)
	(arc
		(start 114.356896 -325.247762)
		(mid 114.411219 -325.321511)
		(end 114.457734 -325.400416)
		(width 0.14224)
		(layer "In6.Cu")
		(net "P5E_CPU1_P0_TX_DN<2>")
	)
	(arc
		(start 98.55327 -281.446224)
		(mid 98.605319 -281.577743)
		(end 98.702368 -281.680666)
		(width 0.1143)
		(layer "In6.Cu")
		(net "P5E_CPU1_P0_TX_DN<2>")
	)
	(arc
		(start 99.430078 -284.872938)
		(mid 99.374103 -284.960188)
		(end 99.30003 -285.032704)
		(width 0.1143)
		(layer "In6.Cu")
		(net "P5E_CPU1_P0_TX_DN<2>")
	)
	(arc
		(start 55.403496 -362.454952)
		(mid 55.198614 -362.623133)
		(end 54.964838 -362.748068)
		(width 0.14224)
		(layer "In6.Cu")
		(net "P5E_CPU1_P0_TX_DN<2>")
	)
	(arc
		(start 99.243134 -293.87165)
		(mid 99.486461 -294.336216)
		(end 99.243134 -294.800782)
		(width 0.1143)
		(layer "In6.Cu")
		(net "P5E_CPU1_P0_TX_DN<2>")
	)
	(arc
		(start 44.676314 -367.008918)
		(mid 44.620545 -367.038683)
		(end 44.571666 -367.078768)
		(width 0.14224)
		(layer "In6.Cu")
		(net "P5E_CPU1_P0_TX_DN<2>")
	)
	(segment
		(start 42.404792 -376.56135)
		(end 41.701212 -376.56135)
		(width 0.12954)
		(layer "F.Cu")
		(net "P5E_CPU1_P0_TX_DN<1>")
	)
	(segment
		(start 99.387914 -284.35046)
		(end 98.921062 -284.616398)
		(width 0.12954)
		(layer "F.Cu")
		(net "P5E_CPU1_P0_TX_DN<1>")
	)
	(segment
		(start 42.700702 -376.85726)
		(end 42.404792 -376.56135)
		(width 0.12954)
		(layer "F.Cu")
		(net "P5E_CPU1_P0_TX_DN<1>")
	)
	(segment
		(start 41.701212 -376.56135)
		(end 41.430702 -376.83186)
		(width 0.12954)
		(layer "F.Cu")
		(net "P5E_CPU1_P0_TX_DN<1>")
	)
	(segment
		(start 98.30308 -293.18077)
		(end 98.233484 -293.22141)
		(width 0.1143)
		(layer "In6.Cu")
		(net "P5E_CPU1_P0_TX_DN<1>")
	)
	(segment
		(start 97.652078 -296.2529)
		(end 97.652078 -296.281348)
		(width 0.1143)
		(layer "In6.Cu")
		(net "P5E_CPU1_P0_TX_DN<1>")
	)
	(segment
		(start 97.822766 -285.895288)
		(end 97.804224 -285.907226)
		(width 0.1143)
		(layer "In6.Cu")
		(net "P5E_CPU1_P0_TX_DN<1>")
	)
	(segment
		(start 42.34307 -376.537728)
		(end 41.724834 -376.537728)
		(width 0.14224)
		(layer "In6.Cu")
		(net "P5E_CPU1_P0_TX_DN<1>")
	)
	(segment
		(start 98.546412 -287.783524)
		(end 98.546412 -287.888934)
		(width 0.1143)
		(layer "In6.Cu")
		(net "P5E_CPU1_P0_TX_DN<1>")
	)
	(segment
		(start 98.302318 -288.33064)
		(end 98.166682 -288.41573)
		(width 0.1143)
		(layer "In6.Cu")
		(net "P5E_CPU1_P0_TX_DN<1>")
	)
	(segment
		(start 42.851832 -374.210072)
		(end 42.851832 -376.028966)
		(width 0.14224)
		(layer "In6.Cu")
		(net "P5E_CPU1_P0_TX_DN<1>")
	)
	(segment
		(start 42.731944 -376.318272)
		(end 42.632376 -376.41784)
		(width 0.14224)
		(layer "In6.Cu")
		(net "P5E_CPU1_P0_TX_DN<1>")
	)
	(segment
		(start 64.078358 -357.491538)
		(end 55.542688 -361.02798)
		(width 0.14224)
		(layer "In6.Cu")
		(net "P5E_CPU1_P0_TX_DN<1>")
	)
	(segment
		(start 98.62312 -284.616398)
		(end 98.540316 -284.699202)
		(width 0.1143)
		(layer "In6.Cu")
		(net "P5E_CPU1_P0_TX_DN<1>")
	)
	(segment
		(start 97.804224 -285.907226)
		(end 97.80397 -285.90875)
		(width 0.1143)
		(layer "In6.Cu")
		(net "P5E_CPU1_P0_TX_DN<1>")
	)
	(segment
		(start 117.483636 -342.532716)
		(end 115.452398 -347.436694)
		(width 0.14224)
		(layer "In6.Cu")
		(net "P5E_CPU1_P0_TX_DN<1>")
	)
	(segment
		(start 117.85981 -339.673184)
		(end 117.88648 -340.04123)
		(width 0.14224)
		(layer "In6.Cu")
		(net "P5E_CPU1_P0_TX_DN<1>")
	)
	(segment
		(start 44.870878 -365.900462)
		(end 44.274994 -366.164114)
		(width 0.14224)
		(layer "In6.Cu")
		(net "P5E_CPU1_P0_TX_DN<1>")
	)
	(segment
		(start 99.591622 -358.206802)
		(end 74.130408 -358.206802)
		(width 0.14224)
		(layer "In6.Cu")
		(net "P5E_CPU1_P0_TX_DN<1>")
	)
	(segment
		(start 72.913748 -357.964994)
		(end 71.924926 -357.555292)
		(width 0.14224)
		(layer "In6.Cu")
		(net "P5E_CPU1_P0_TX_DN<1>")
	)
	(segment
		(start 102.130606 -310.198008)
		(end 107.811062 -318.699134)
		(width 0.14224)
		(layer "In6.Cu")
		(net "P5E_CPU1_P0_TX_DN<1>")
	)
	(segment
		(start 97.932748 -295.580816)
		(end 97.653602 -295.859962)
		(width 0.1143)
		(layer "In6.Cu")
		(net "P5E_CPU1_P0_TX_DN<1>")
	)
	(segment
		(start 98.233484 -293.83101)
		(end 98.30308 -293.87165)
		(width 0.1143)
		(layer "In6.Cu")
		(net "P5E_CPU1_P0_TX_DN<1>")
	)
	(segment
		(start 41.787064 -368.731038)
		(end 41.787064 -372.012464)
		(width 0.14224)
		(layer "In6.Cu")
		(net "P5E_CPU1_P0_TX_DN<1>")
	)
	(segment
		(start 54.567582 -361.903264)
		(end 46.696122 -365.1631)
		(width 0.14224)
		(layer "In6.Cu")
		(net "P5E_CPU1_P0_TX_DN<1>")
	)
	(segment
		(start 97.606358 -295.974008)
		(end 97.606358 -296.20718)
		(width 0.1143)
		(layer "In6.Cu")
		(net "P5E_CPU1_P0_TX_DN<1>")
	)
	(segment
		(start 71.554848 -357.481632)
		(end 64.128142 -357.481632)
		(width 0.14224)
		(layer "In6.Cu")
		(net "P5E_CPU1_P0_TX_DN<1>")
	)
	(segment
		(start 97.606358 -296.20718)
		(end 97.652078 -296.2529)
		(width 0.1143)
		(layer "In6.Cu")
		(net "P5E_CPU1_P0_TX_DN<1>")
	)
	(segment
		(start 99.925886 -358.160066)
		(end 99.717606 -358.196134)
		(width 0.14224)
		(layer "In6.Cu")
		(net "P5E_CPU1_P0_TX_DN<1>")
	)
	(segment
		(start 98.30308 -291.560758)
		(end 98.233484 -291.601398)
		(width 0.1143)
		(layer "In6.Cu")
		(net "P5E_CPU1_P0_TX_DN<1>")
	)
	(segment
		(start 98.233484 -287.350962)
		(end 98.360738 -287.43148)
		(width 0.1143)
		(layer "In6.Cu")
		(net "P5E_CPU1_P0_TX_DN<1>")
	)
	(segment
		(start 44.162472 -366.222026)
		(end 44.012104 -366.311434)
		(width 0.14224)
		(layer "In6.Cu")
		(net "P5E_CPU1_P0_TX_DN<1>")
	)
	(segment
		(start 98.30308 -285.080964)
		(end 98.256344 -285.108142)
		(width 0.1143)
		(layer "In6.Cu")
		(net "P5E_CPU1_P0_TX_DN<1>")
	)
	(segment
		(start 116.321078 -331.070204)
		(end 117.83949 -339.51418)
		(width 0.14224)
		(layer "In6.Cu")
		(net "P5E_CPU1_P0_TX_DN<1>")
	)
	(segment
		(start 98.921062 -284.616398)
		(end 98.62312 -284.616398)
		(width 0.1143)
		(layer "In6.Cu")
		(net "P5E_CPU1_P0_TX_DN<1>")
	)
	(segment
		(start 97.80397 -285.90875)
		(end 97.762314 -285.932118)
		(width 0.1143)
		(layer "In6.Cu")
		(net "P5E_CPU1_P0_TX_DN<1>")
	)
	(segment
		(start 97.679002 -299.48251)
		(end 102.070916 -310.086248)
		(width 0.14224)
		(layer "In6.Cu")
		(net "P5E_CPU1_P0_TX_DN<1>")
	)
	(segment
		(start 98.233484 -292.210998)
		(end 98.30308 -292.251638)
		(width 0.1143)
		(layer "In6.Cu")
		(net "P5E_CPU1_P0_TX_DN<1>")
	)
	(segment
		(start 97.79 -286.55645)
		(end 97.83318 -286.581596)
		(width 0.1143)
		(layer "In6.Cu")
		(net "P5E_CPU1_P0_TX_DN<1>")
	)
	(segment
		(start 55.43804 -361.09783)
		(end 54.76367 -361.7722)
		(width 0.14224)
		(layer "In6.Cu")
		(net "P5E_CPU1_P0_TX_DN<1>")
	)
	(segment
		(start 98.076512 -295.146222)
		(end 98.076258 -295.191434)
		(width 0.1143)
		(layer "In6.Cu")
		(net "P5E_CPU1_P0_TX_DN<1>")
	)
	(segment
		(start 98.076512 -288.659316)
		(end 98.076512 -288.666174)
		(width 0.1143)
		(layer "In6.Cu")
		(net "P5E_CPU1_P0_TX_DN<1>")
	)
	(segment
		(start 98.233484 -288.970974)
		(end 98.30308 -289.011614)
		(width 0.1143)
		(layer "In6.Cu")
		(net "P5E_CPU1_P0_TX_DN<1>")
	)
	(segment
		(start 98.233484 -290.590986)
		(end 98.30308 -290.631626)
		(width 0.1143)
		(layer "In6.Cu")
		(net "P5E_CPU1_P0_TX_DN<1>")
	)
	(segment
		(start 98.30308 -294.800782)
		(end 98.233484 -294.841422)
		(width 0.1143)
		(layer "In6.Cu")
		(net "P5E_CPU1_P0_TX_DN<1>")
	)
	(segment
		(start 97.652078 -296.281348)
		(end 97.652078 -299.34789)
		(width 0.14224)
		(layer "In6.Cu")
		(net "P5E_CPU1_P0_TX_DN<1>")
	)
	(segment
		(start 41.724834 -376.537728)
		(end 41.430702 -376.83186)
		(width 0.14224)
		(layer "In6.Cu")
		(net "P5E_CPU1_P0_TX_DN<1>")
	)
	(segment
		(start 43.912536 -366.388904)
		(end 41.923716 -368.377724)
		(width 0.14224)
		(layer "In6.Cu")
		(net "P5E_CPU1_P0_TX_DN<1>")
	)
	(segment
		(start 114.738658 -348.307152)
		(end 100.151438 -358.069896)
		(width 0.14224)
		(layer "In6.Cu")
		(net "P5E_CPU1_P0_TX_DN<1>")
	)
	(segment
		(start 113.667032 -325.923402)
		(end 116.253006 -330.870052)
		(width 0.14224)
		(layer "In6.Cu")
		(net "P5E_CPU1_P0_TX_DN<1>")
	)
	(segment
		(start 98.30308 -289.940746)
		(end 98.233484 -289.981386)
		(width 0.1143)
		(layer "In6.Cu")
		(net "P5E_CPU1_P0_TX_DN<1>")
	)
	(segment
		(start 108.260134 -319.30467)
		(end 113.566194 -325.770748)
		(width 0.14224)
		(layer "In6.Cu")
		(net "P5E_CPU1_P0_TX_DN<1>")
	)
	(segment
		(start 42.4688 -373.657368)
		(end 42.731944 -373.920512)
		(width 0.14224)
		(layer "In6.Cu")
		(net "P5E_CPU1_P0_TX_DN<1>")
	)
	(segment
		(start 98.079052 -285.419546)
		(end 98.079052 -285.446978)
		(width 0.1143)
		(layer "In6.Cu")
		(net "P5E_CPU1_P0_TX_DN<1>")
	)
	(arc
		(start 117.88648 -340.04123)
		(mid 117.830554 -341.310497)
		(end 117.483636 -342.532716)
		(width 0.14224)
		(layer "In6.Cu")
		(net "P5E_CPU1_P0_TX_DN<1>")
	)
	(arc
		(start 42.731944 -373.920512)
		(mid 42.820737 -374.05335)
		(end 42.851832 -374.210072)
		(width 0.14224)
		(layer "In6.Cu")
		(net "P5E_CPU1_P0_TX_DN<1>")
	)
	(arc
		(start 115.452398 -347.436694)
		(mid 115.160016 -347.924803)
		(end 114.738658 -348.307152)
		(width 0.14224)
		(layer "In6.Cu")
		(net "P5E_CPU1_P0_TX_DN<1>")
	)
	(arc
		(start 98.233484 -289.981386)
		(mid 98.076507 -290.286186)
		(end 98.233484 -290.590986)
		(width 0.1143)
		(layer "In6.Cu")
		(net "P5E_CPU1_P0_TX_DN<1>")
	)
	(arc
		(start 54.76367 -361.7722)
		(mid 54.672073 -361.847374)
		(end 54.567582 -361.903264)
		(width 0.14224)
		(layer "In6.Cu")
		(net "P5E_CPU1_P0_TX_DN<1>")
	)
	(arc
		(start 99.717606 -358.196134)
		(mid 99.654841 -358.204149)
		(end 99.591622 -358.206802)
		(width 0.14224)
		(layer "In6.Cu")
		(net "P5E_CPU1_P0_TX_DN<1>")
	)
	(arc
		(start 98.46691 -284.905704)
		(mid 98.394406 -285.002131)
		(end 98.30308 -285.080964)
		(width 0.1143)
		(layer "In6.Cu")
		(net "P5E_CPU1_P0_TX_DN<1>")
	)
	(arc
		(start 107.811062 -318.699134)
		(mid 108.028165 -319.007415)
		(end 108.260134 -319.30467)
		(width 0.14224)
		(layer "In6.Cu")
		(net "P5E_CPU1_P0_TX_DN<1>")
	)
	(arc
		(start 98.30308 -289.011614)
		(mid 98.546407 -289.47618)
		(end 98.30308 -289.940746)
		(width 0.1143)
		(layer "In6.Cu")
		(net "P5E_CPU1_P0_TX_DN<1>")
	)
	(arc
		(start 98.166682 -288.41573)
		(mid 98.099797 -288.529456)
		(end 98.076512 -288.659316)
		(width 0.1143)
		(layer "In6.Cu")
		(net "P5E_CPU1_P0_TX_DN<1>")
	)
	(arc
		(start 74.130408 -358.206802)
		(mid 73.510169 -358.145816)
		(end 72.913748 -357.964994)
		(width 0.14224)
		(layer "In6.Cu")
		(net "P5E_CPU1_P0_TX_DN<1>")
	)
	(arc
		(start 97.606358 -286.23641)
		(mid 97.655464 -286.420946)
		(end 97.79 -286.55645)
		(width 0.1143)
		(layer "In6.Cu")
		(net "P5E_CPU1_P0_TX_DN<1>")
	)
	(arc
		(start 46.696122 -365.1631)
		(mid 46.362178 -365.298298)
		(end 46.02607 -365.428022)
		(width 0.14224)
		(layer "In6.Cu")
		(net "P5E_CPU1_P0_TX_DN<1>")
	)
	(arc
		(start 46.02607 -365.428022)
		(mid 45.44513 -365.656066)
		(end 44.870878 -365.900462)
		(width 0.14224)
		(layer "In6.Cu")
		(net "P5E_CPU1_P0_TX_DN<1>")
	)
	(arc
		(start 117.83949 -339.51418)
		(mid 117.851749 -339.593414)
		(end 117.85981 -339.673184)
		(width 0.14224)
		(layer "In6.Cu")
		(net "P5E_CPU1_P0_TX_DN<1>")
	)
	(arc
		(start 98.546412 -287.888934)
		(mid 98.48133 -288.141268)
		(end 98.302318 -288.33064)
		(width 0.1143)
		(layer "In6.Cu")
		(net "P5E_CPU1_P0_TX_DN<1>")
	)
	(arc
		(start 41.85031 -368.476784)
		(mid 41.803115 -368.600035)
		(end 41.787064 -368.731038)
		(width 0.14224)
		(layer "In6.Cu")
		(net "P5E_CPU1_P0_TX_DN<1>")
	)
	(arc
		(start 98.30308 -293.87165)
		(mid 98.546407 -294.336216)
		(end 98.30308 -294.800782)
		(width 0.1143)
		(layer "In6.Cu")
		(net "P5E_CPU1_P0_TX_DN<1>")
	)
	(arc
		(start 98.30308 -290.631626)
		(mid 98.546407 -291.096192)
		(end 98.30308 -291.560758)
		(width 0.1143)
		(layer "In6.Cu")
		(net "P5E_CPU1_P0_TX_DN<1>")
	)
	(arc
		(start 97.652078 -299.34789)
		(mid 97.6589 -299.416528)
		(end 97.679002 -299.48251)
		(width 0.14224)
		(layer "In6.Cu")
		(net "P5E_CPU1_P0_TX_DN<1>")
	)
	(arc
		(start 44.274994 -366.164114)
		(mid 44.217874 -366.1914)
		(end 44.162472 -366.222026)
		(width 0.14224)
		(layer "In6.Cu")
		(net "P5E_CPU1_P0_TX_DN<1>")
	)
	(arc
		(start 97.653602 -295.859962)
		(mid 97.618693 -295.912301)
		(end 97.606358 -295.974008)
		(width 0.1143)
		(layer "In6.Cu")
		(net "P5E_CPU1_P0_TX_DN<1>")
	)
	(arc
		(start 98.360738 -287.43148)
		(mid 98.497184 -287.584509)
		(end 98.546412 -287.783524)
		(width 0.1143)
		(layer "In6.Cu")
		(net "P5E_CPU1_P0_TX_DN<1>")
	)
	(arc
		(start 44.012104 -366.311434)
		(mid 43.959892 -366.34705)
		(end 43.912536 -366.388904)
		(width 0.14224)
		(layer "In6.Cu")
		(net "P5E_CPU1_P0_TX_DN<1>")
	)
	(arc
		(start 98.079052 -285.446978)
		(mid 98.005202 -285.702177)
		(end 97.822766 -285.895288)
		(width 0.1143)
		(layer "In6.Cu")
		(net "P5E_CPU1_P0_TX_DN<1>")
	)
	(arc
		(start 98.045524 -295.39311)
		(mid 98.000655 -295.493883)
		(end 97.932748 -295.580816)
		(width 0.1143)
		(layer "In6.Cu")
		(net "P5E_CPU1_P0_TX_DN<1>")
	)
	(arc
		(start 98.076512 -288.666174)
		(mid 98.118061 -288.837596)
		(end 98.233484 -288.970974)
		(width 0.1143)
		(layer "In6.Cu")
		(net "P5E_CPU1_P0_TX_DN<1>")
	)
	(arc
		(start 64.128142 -357.481632)
		(mid 64.102766 -357.484142)
		(end 64.078358 -357.491538)
		(width 0.14224)
		(layer "In6.Cu")
		(net "P5E_CPU1_P0_TX_DN<1>")
	)
	(arc
		(start 113.566194 -325.770748)
		(mid 113.620512 -325.844499)
		(end 113.667032 -325.923402)
		(width 0.14224)
		(layer "In6.Cu")
		(net "P5E_CPU1_P0_TX_DN<1>")
	)
	(arc
		(start 55.542688 -361.02798)
		(mid 55.486919 -361.057745)
		(end 55.43804 -361.09783)
		(width 0.14224)
		(layer "In6.Cu")
		(net "P5E_CPU1_P0_TX_DN<1>")
	)
	(arc
		(start 97.83318 -286.581596)
		(mid 98.011993 -286.783946)
		(end 98.076512 -287.046162)
		(width 0.1143)
		(layer "In6.Cu")
		(net "P5E_CPU1_P0_TX_DN<1>")
	)
	(arc
		(start 98.30308 -292.251638)
		(mid 98.546407 -292.716204)
		(end 98.30308 -293.18077)
		(width 0.1143)
		(layer "In6.Cu")
		(net "P5E_CPU1_P0_TX_DN<1>")
	)
	(arc
		(start 71.924926 -357.555292)
		(mid 71.743517 -357.500225)
		(end 71.554848 -357.481632)
		(width 0.14224)
		(layer "In6.Cu")
		(net "P5E_CPU1_P0_TX_DN<1>")
	)
	(arc
		(start 102.070916 -310.086248)
		(mid 102.098009 -310.143599)
		(end 102.130606 -310.198008)
		(width 0.14224)
		(layer "In6.Cu")
		(net "P5E_CPU1_P0_TX_DN<1>")
	)
	(arc
		(start 41.923716 -368.377724)
		(mid 41.883347 -368.424538)
		(end 41.85031 -368.476784)
		(width 0.14224)
		(layer "In6.Cu")
		(net "P5E_CPU1_P0_TX_DN<1>")
	)
	(arc
		(start 42.851832 -376.028966)
		(mid 42.820669 -376.185544)
		(end 42.731944 -376.318272)
		(width 0.14224)
		(layer "In6.Cu")
		(net "P5E_CPU1_P0_TX_DN<1>")
	)
	(arc
		(start 98.233484 -291.601398)
		(mid 98.076507 -291.906198)
		(end 98.233484 -292.210998)
		(width 0.1143)
		(layer "In6.Cu")
		(net "P5E_CPU1_P0_TX_DN<1>")
	)
	(arc
		(start 98.076258 -295.191434)
		(mid 98.068222 -295.29339)
		(end 98.045524 -295.39311)
		(width 0.1143)
		(layer "In6.Cu")
		(net "P5E_CPU1_P0_TX_DN<1>")
	)
	(arc
		(start 98.076512 -287.046162)
		(mid 98.118061 -287.217584)
		(end 98.233484 -287.350962)
		(width 0.1143)
		(layer "In6.Cu")
		(net "P5E_CPU1_P0_TX_DN<1>")
	)
	(arc
		(start 42.632376 -376.41784)
		(mid 42.499656 -376.506584)
		(end 42.34307 -376.537728)
		(width 0.14224)
		(layer "In6.Cu")
		(net "P5E_CPU1_P0_TX_DN<1>")
	)
	(arc
		(start 116.253006 -330.870052)
		(mid 116.294662 -330.967537)
		(end 116.321078 -331.070204)
		(width 0.14224)
		(layer "In6.Cu")
		(net "P5E_CPU1_P0_TX_DN<1>")
	)
	(arc
		(start 98.256344 -285.108142)
		(mid 98.209275 -285.140826)
		(end 98.168206 -285.180786)
		(width 0.1143)
		(layer "In6.Cu")
		(net "P5E_CPU1_P0_TX_DN<1>")
	)
	(arc
		(start 41.787064 -372.012464)
		(mid 41.964312 -372.90272)
		(end 42.4688 -373.657368)
		(width 0.14224)
		(layer "In6.Cu")
		(net "P5E_CPU1_P0_TX_DN<1>")
	)
	(arc
		(start 98.540316 -284.699202)
		(mid 98.513722 -284.806045)
		(end 98.46691 -284.905704)
		(width 0.1143)
		(layer "In6.Cu")
		(net "P5E_CPU1_P0_TX_DN<1>")
	)
	(arc
		(start 98.233484 -294.841422)
		(mid 98.118057 -294.974798)
		(end 98.076512 -295.146222)
		(width 0.1143)
		(layer "In6.Cu")
		(net "P5E_CPU1_P0_TX_DN<1>")
	)
	(arc
		(start 98.233484 -293.22141)
		(mid 98.076507 -293.52621)
		(end 98.233484 -293.83101)
		(width 0.1143)
		(layer "In6.Cu")
		(net "P5E_CPU1_P0_TX_DN<1>")
	)
	(arc
		(start 98.168206 -285.180786)
		(mid 98.102047 -285.292104)
		(end 98.079052 -285.419546)
		(width 0.1143)
		(layer "In6.Cu")
		(net "P5E_CPU1_P0_TX_DN<1>")
	)
	(arc
		(start 97.762314 -285.932118)
		(mid 97.647638 -286.065452)
		(end 97.606358 -286.23641)
		(width 0.1143)
		(layer "In6.Cu")
		(net "P5E_CPU1_P0_TX_DN<1>")
	)
	(arc
		(start 100.151438 -358.069896)
		(mid 100.0434 -358.126837)
		(end 99.925886 -358.160066)
		(width 0.14224)
		(layer "In6.Cu")
		(net "P5E_CPU1_P0_TX_DN<1>")
	)
	(segment
		(start 71.277734 -380.360428)
		(end 71.007224 -380.089918)
		(width 0.12954)
		(layer "F.Cu")
		(net "P5E_CPU1_P0_TX_DN<15>")
	)
	(segment
		(start 70.303644 -380.089918)
		(end 70.007734 -380.385828)
		(width 0.12954)
		(layer "F.Cu")
		(net "P5E_CPU1_P0_TX_DN<15>")
	)
	(segment
		(start 71.007224 -380.089918)
		(end 70.303644 -380.089918)
		(width 0.12954)
		(layer "F.Cu")
		(net "P5E_CPU1_P0_TX_DN<15>")
	)
	(segment
		(start 110.1979 -281.920442)
		(end 109.731048 -282.18638)
		(width 0.12954)
		(layer "F.Cu")
		(net "P5E_CPU1_P0_TX_DN<15>")
	)
	(segment
		(start 111.496348 -285.049722)
		(end 111.145828 -284.699202)
		(width 0.14224)
		(layer "In6.Cu")
		(net "P5E_CPU1_P0_TX_DN<15>")
	)
	(segment
		(start 129.006346 -326.45604)
		(end 124.458984 -317.947802)
		(width 0.14224)
		(layer "In6.Cu")
		(net "P5E_CPU1_P0_TX_DN<15>")
	)
	(segment
		(start 78.609698 -379.880622)
		(end 101.26599 -379.880622)
		(width 0.14224)
		(layer "In6.Cu")
		(net "P5E_CPU1_P0_TX_DN<15>")
	)
	(segment
		(start 76.207112 -380.092458)
		(end 76.722478 -380.092458)
		(width 0.14224)
		(layer "In6.Cu")
		(net "P5E_CPU1_P0_TX_DN<15>")
	)
	(segment
		(start 104.104186 -381.84836)
		(end 104.399588 -381.726186)
		(width 0.14224)
		(layer "In6.Cu")
		(net "P5E_CPU1_P0_TX_DN<15>")
	)
	(segment
		(start 109.105446 -370.173504)
		(end 109.1057 -370.17325)
		(width 0.14224)
		(layer "In6.Cu")
		(net "P5E_CPU1_P0_TX_DN<15>")
	)
	(segment
		(start 109.433106 -282.18638)
		(end 109.731048 -282.18638)
		(width 0.1143)
		(layer "In6.Cu")
		(net "P5E_CPU1_P0_TX_DN<15>")
	)
	(segment
		(start 109.544104 -282.50896)
		(end 109.543342 -282.508452)
		(width 0.1143)
		(layer "In6.Cu")
		(net "P5E_CPU1_P0_TX_DN<15>")
	)
	(segment
		(start 109.542072 -282.50769)
		(end 109.540548 -282.506928)
		(width 0.1143)
		(layer "In6.Cu")
		(net "P5E_CPU1_P0_TX_DN<15>")
	)
	(segment
		(start 71.557134 -380.081028)
		(end 72.062594 -380.081028)
		(width 0.14224)
		(layer "In6.Cu")
		(net "P5E_CPU1_P0_TX_DN<15>")
	)
	(segment
		(start 109.363256 -282.25623)
		(end 109.433106 -282.18638)
		(width 0.1143)
		(layer "In6.Cu")
		(net "P5E_CPU1_P0_TX_DN<15>")
	)
	(segment
		(start 131.758944 -344.343736)
		(end 131.758944 -342.059514)
		(width 0.14224)
		(layer "In6.Cu")
		(net "P5E_CPU1_P0_TX_DN<15>")
	)
	(segment
		(start 72.80148 -379.37186)
		(end 72.80148 -378.891546)
		(width 0.14224)
		(layer "In6.Cu")
		(net "P5E_CPU1_P0_TX_DN<15>")
	)
	(segment
		(start 71.277734 -380.360428)
		(end 71.557134 -380.081028)
		(width 0.14224)
		(layer "In6.Cu")
		(net "P5E_CPU1_P0_TX_DN<15>")
	)
	(segment
		(start 109.540548 -282.506928)
		(end 109.539786 -282.50642)
		(width 0.1143)
		(layer "In6.Cu")
		(net "P5E_CPU1_P0_TX_DN<15>")
	)
	(segment
		(start 111.496348 -297.874436)
		(end 111.496348 -285.049722)
		(width 0.14224)
		(layer "In6.Cu")
		(net "P5E_CPU1_P0_TX_DN<15>")
	)
	(segment
		(start 75.335892 -379.652784)
		(end 75.470004 -379.78715)
		(width 0.14224)
		(layer "In6.Cu")
		(net "P5E_CPU1_P0_TX_DN<15>")
	)
	(segment
		(start 127.725424 -354.596446)
		(end 131.590034 -345.266518)
		(width 0.14224)
		(layer "In6.Cu")
		(net "P5E_CPU1_P0_TX_DN<15>")
	)
	(segment
		(start 127.103378 -355.680264)
		(end 127.725424 -354.596446)
		(width 0.14224)
		(layer "In6.Cu")
		(net "P5E_CPU1_P0_TX_DN<15>")
	)
	(segment
		(start 110.483904 -284.128972)
		(end 110.453424 -284.111192)
		(width 0.1143)
		(layer "In6.Cu")
		(net "P5E_CPU1_P0_TX_DN<15>")
	)
	(segment
		(start 104.981502 -381.355092)
		(end 105.544112 -380.84506)
		(width 0.14224)
		(layer "In6.Cu")
		(net "P5E_CPU1_P0_TX_DN<15>")
	)
	(segment
		(start 131.70916 -341.499444)
		(end 129.006346 -326.45604)
		(width 0.14224)
		(layer "In6.Cu")
		(net "P5E_CPU1_P0_TX_DN<15>")
	)
	(segment
		(start 104.792526 -381.504698)
		(end 104.86263 -381.452628)
		(width 0.14224)
		(layer "In6.Cu")
		(net "P5E_CPU1_P0_TX_DN<15>")
	)
	(segment
		(start 102.462076 -380.852172)
		(end 102.462076 -380.990856)
		(width 0.14224)
		(layer "In6.Cu")
		(net "P5E_CPU1_P0_TX_DN<15>")
	)
	(segment
		(start 109.539786 -282.50642)
		(end 109.512354 -282.490672)
		(width 0.1143)
		(layer "In6.Cu")
		(net "P5E_CPU1_P0_TX_DN<15>")
	)
	(segment
		(start 124.458984 -317.947802)
		(end 117.585236 -309.570374)
		(width 0.14224)
		(layer "In6.Cu")
		(net "P5E_CPU1_P0_TX_DN<15>")
	)
	(segment
		(start 109.046264 -370.33454)
		(end 109.105446 -370.173504)
		(width 0.14224)
		(layer "In6.Cu")
		(net "P5E_CPU1_P0_TX_DN<15>")
	)
	(segment
		(start 111.526828 -298.181522)
		(end 111.496348 -297.874436)
		(width 0.14224)
		(layer "In6.Cu")
		(net "P5E_CPU1_P0_TX_DN<15>")
	)
	(segment
		(start 74.395076 -378.304298)
		(end 75.000104 -378.909326)
		(width 0.14224)
		(layer "In6.Cu")
		(net "P5E_CPU1_P0_TX_DN<15>")
	)
	(segment
		(start 103.489506 -381.89408)
		(end 103.873046 -381.89408)
		(width 0.14224)
		(layer "In6.Cu")
		(net "P5E_CPU1_P0_TX_DN<15>")
	)
	(segment
		(start 117.585236 -309.570374)
		(end 113.754408 -303.837086)
		(width 0.14224)
		(layer "In6.Cu")
		(net "P5E_CPU1_P0_TX_DN<15>")
	)
	(segment
		(start 109.106208 -370.171726)
		(end 109.180122 -369.970304)
		(width 0.14224)
		(layer "In6.Cu")
		(net "P5E_CPU1_P0_TX_DN<15>")
	)
	(segment
		(start 73.385172 -378.257054)
		(end 74.28103 -378.257054)
		(width 0.14224)
		(layer "In6.Cu")
		(net "P5E_CPU1_P0_TX_DN<15>")
	)
	(segment
		(start 108.892086 -370.754402)
		(end 108.89234 -370.75364)
		(width 0.14224)
		(layer "In6.Cu")
		(net "P5E_CPU1_P0_TX_DN<15>")
	)
	(segment
		(start 109.601 -369.311428)
		(end 109.863128 -369.0493)
		(width 0.14224)
		(layer "In6.Cu")
		(net "P5E_CPU1_P0_TX_DN<15>")
	)
	(segment
		(start 101.747574 -380.070868)
		(end 102.414832 -380.738126)
		(width 0.14224)
		(layer "In6.Cu")
		(net "P5E_CPU1_P0_TX_DN<15>")
	)
	(segment
		(start 101.389688 -379.903736)
		(end 101.642164 -380.002034)
		(width 0.14224)
		(layer "In6.Cu")
		(net "P5E_CPU1_P0_TX_DN<15>")
	)
	(segment
		(start 104.529382 -381.662178)
		(end 104.686608 -381.573532)
		(width 0.14224)
		(layer "In6.Cu")
		(net "P5E_CPU1_P0_TX_DN<15>")
	)
	(segment
		(start 108.89234 -370.75364)
		(end 109.046264 -370.33454)
		(width 0.14224)
		(layer "In6.Cu")
		(net "P5E_CPU1_P0_TX_DN<15>")
	)
	(segment
		(start 110.05312 -283.341826)
		(end 109.991398 -283.305758)
		(width 0.1143)
		(layer "In6.Cu")
		(net "P5E_CPU1_P0_TX_DN<15>")
	)
	(segment
		(start 109.582204 -282.531058)
		(end 109.544104 -282.50896)
		(width 0.1143)
		(layer "In6.Cu")
		(net "P5E_CPU1_P0_TX_DN<15>")
	)
	(segment
		(start 102.697026 -381.558038)
		(end 102.710234 -381.571246)
		(width 0.14224)
		(layer "In6.Cu")
		(net "P5E_CPU1_P0_TX_DN<15>")
	)
	(segment
		(start 109.543342 -282.508452)
		(end 109.542072 -282.50769)
		(width 0.1143)
		(layer "In6.Cu")
		(net "P5E_CPU1_P0_TX_DN<15>")
	)
	(segment
		(start 75.125326 -379.246638)
		(end 75.335892 -379.652784)
		(width 0.14224)
		(layer "In6.Cu")
		(net "P5E_CPU1_P0_TX_DN<15>")
	)
	(segment
		(start 109.1057 -370.17325)
		(end 109.106208 -370.171726)
		(width 0.14224)
		(layer "In6.Cu")
		(net "P5E_CPU1_P0_TX_DN<15>")
	)
	(segment
		(start 111.994188 -367.164874)
		(end 126.426468 -356.441756)
		(width 0.14224)
		(layer "In6.Cu")
		(net "P5E_CPU1_P0_TX_DN<15>")
	)
	(segment
		(start 105.843578 -380.265686)
		(end 106.481626 -377.316238)
		(width 0.14224)
		(layer "In6.Cu")
		(net "P5E_CPU1_P0_TX_DN<15>")
	)
	(segment
		(start 113.754408 -303.837086)
		(end 111.702596 -298.883578)
		(width 0.14224)
		(layer "In6.Cu")
		(net "P5E_CPU1_P0_TX_DN<15>")
	)
	(segment
		(start 109.863128 -369.0493)
		(end 111.994188 -367.164874)
		(width 0.14224)
		(layer "In6.Cu")
		(net "P5E_CPU1_P0_TX_DN<15>")
	)
	(segment
		(start 72.99071 -378.434854)
		(end 73.015348 -378.410216)
		(width 0.14224)
		(layer "In6.Cu")
		(net "P5E_CPU1_P0_TX_DN<15>")
	)
	(segment
		(start 131.590034 -345.266518)
		(end 131.590034 -345.26474)
		(width 0.14224)
		(layer "In6.Cu")
		(net "P5E_CPU1_P0_TX_DN<15>")
	)
	(segment
		(start 111.060738 -284.679136)
		(end 110.599474 -284.217872)
		(width 0.1143)
		(layer "In6.Cu")
		(net "P5E_CPU1_P0_TX_DN<15>")
	)
	(segment
		(start 75.068938 -379.029468)
		(end 75.125326 -379.246638)
		(width 0.14224)
		(layer "In6.Cu")
		(net "P5E_CPU1_P0_TX_DN<15>")
	)
	(segment
		(start 111.125762 -284.679136)
		(end 111.060738 -284.679136)
		(width 0.1143)
		(layer "In6.Cu")
		(net "P5E_CPU1_P0_TX_DN<15>")
	)
	(segment
		(start 111.145828 -284.699202)
		(end 111.125762 -284.679136)
		(width 0.1143)
		(layer "In6.Cu")
		(net "P5E_CPU1_P0_TX_DN<15>")
	)
	(segment
		(start 106.481626 -377.316238)
		(end 108.892086 -370.754402)
		(width 0.14224)
		(layer "In6.Cu")
		(net "P5E_CPU1_P0_TX_DN<15>")
	)
	(arc
		(start 111.702596 -298.883578)
		(mid 111.58884 -298.539027)
		(end 111.526828 -298.181522)
		(width 0.14224)
		(layer "In6.Cu")
		(net "P5E_CPU1_P0_TX_DN<15>")
	)
	(arc
		(start 105.544112 -380.84506)
		(mid 105.616179 -380.769835)
		(end 105.6767 -380.68504)
		(width 0.14224)
		(layer "In6.Cu")
		(net "P5E_CPU1_P0_TX_DN<15>")
	)
	(arc
		(start 72.80148 -378.891546)
		(mid 72.850663 -378.644377)
		(end 72.99071 -378.434854)
		(width 0.14224)
		(layer "In6.Cu")
		(net "P5E_CPU1_P0_TX_DN<15>")
	)
	(arc
		(start 126.426468 -356.441756)
		(mid 126.804149 -356.095879)
		(end 127.103378 -355.680264)
		(width 0.14224)
		(layer "In6.Cu")
		(net "P5E_CPU1_P0_TX_DN<15>")
	)
	(arc
		(start 101.642164 -380.002034)
		(mid 101.698454 -380.030961)
		(end 101.747574 -380.070868)
		(width 0.14224)
		(layer "In6.Cu")
		(net "P5E_CPU1_P0_TX_DN<15>")
	)
	(arc
		(start 102.462076 -380.990856)
		(mid 102.523135 -381.297819)
		(end 102.697026 -381.558038)
		(width 0.14224)
		(layer "In6.Cu")
		(net "P5E_CPU1_P0_TX_DN<15>")
	)
	(arc
		(start 109.991398 -283.305758)
		(mid 109.883262 -283.170417)
		(end 109.828584 -283.006038)
		(width 0.1143)
		(layer "In6.Cu")
		(net "P5E_CPU1_P0_TX_DN<15>")
	)
	(arc
		(start 104.86263 -381.452628)
		(mid 104.923243 -381.405295)
		(end 104.981502 -381.355092)
		(width 0.14224)
		(layer "In6.Cu")
		(net "P5E_CPU1_P0_TX_DN<15>")
	)
	(arc
		(start 109.512354 -282.490672)
		(mid 109.415219 -282.387803)
		(end 109.363256 -282.25623)
		(width 0.1143)
		(layer "In6.Cu")
		(net "P5E_CPU1_P0_TX_DN<15>")
	)
	(arc
		(start 77.728826 -379.979682)
		(mid 78.16649 -379.905498)
		(end 78.609698 -379.880622)
		(width 0.14224)
		(layer "In6.Cu")
		(net "P5E_CPU1_P0_TX_DN<15>")
	)
	(arc
		(start 103.873046 -381.89408)
		(mid 103.990868 -381.882598)
		(end 104.104186 -381.84836)
		(width 0.14224)
		(layer "In6.Cu")
		(net "P5E_CPU1_P0_TX_DN<15>")
	)
	(arc
		(start 76.722478 -380.092458)
		(mid 77.228807 -380.064227)
		(end 77.728826 -379.979682)
		(width 0.14224)
		(layer "In6.Cu")
		(net "P5E_CPU1_P0_TX_DN<15>")
	)
	(arc
		(start 109.826552 -282.97632)
		(mid 109.757159 -282.724721)
		(end 109.582204 -282.531058)
		(width 0.1143)
		(layer "In6.Cu")
		(net "P5E_CPU1_P0_TX_DN<15>")
	)
	(arc
		(start 131.631182 -345.149424)
		(mid 131.726885 -344.751625)
		(end 131.758944 -344.343736)
		(width 0.14224)
		(layer "In6.Cu")
		(net "P5E_CPU1_P0_TX_DN<15>")
	)
	(arc
		(start 102.414832 -380.738126)
		(mid 102.449848 -380.790436)
		(end 102.462076 -380.852172)
		(width 0.14224)
		(layer "In6.Cu")
		(net "P5E_CPU1_P0_TX_DN<15>")
	)
	(arc
		(start 102.710234 -381.571246)
		(mid 103.067753 -381.810196)
		(end 103.489506 -381.89408)
		(width 0.14224)
		(layer "In6.Cu")
		(net "P5E_CPU1_P0_TX_DN<15>")
	)
	(arc
		(start 110.296452 -283.806392)
		(mid 110.231937 -283.544173)
		(end 110.05312 -283.341826)
		(width 0.1143)
		(layer "In6.Cu")
		(net "P5E_CPU1_P0_TX_DN<15>")
	)
	(arc
		(start 101.26599 -379.880622)
		(mid 101.328915 -379.886424)
		(end 101.389688 -379.903736)
		(width 0.14224)
		(layer "In6.Cu")
		(net "P5E_CPU1_P0_TX_DN<15>")
	)
	(arc
		(start 105.6767 -380.68504)
		(mid 105.777707 -380.482353)
		(end 105.843578 -380.265686)
		(width 0.14224)
		(layer "In6.Cu")
		(net "P5E_CPU1_P0_TX_DN<15>")
	)
	(arc
		(start 73.015348 -378.410216)
		(mid 73.185025 -378.296842)
		(end 73.385172 -378.257054)
		(width 0.14224)
		(layer "In6.Cu")
		(net "P5E_CPU1_P0_TX_DN<15>")
	)
	(arc
		(start 104.399588 -381.726186)
		(mid 104.465352 -381.695941)
		(end 104.529382 -381.662178)
		(width 0.14224)
		(layer "In6.Cu")
		(net "P5E_CPU1_P0_TX_DN<15>")
	)
	(arc
		(start 72.765412 -379.588776)
		(mid 72.792464 -379.481819)
		(end 72.80148 -379.37186)
		(width 0.14224)
		(layer "In6.Cu")
		(net "P5E_CPU1_P0_TX_DN<15>")
	)
	(arc
		(start 110.453424 -284.111192)
		(mid 110.337997 -283.977816)
		(end 110.296452 -283.806392)
		(width 0.1143)
		(layer "In6.Cu")
		(net "P5E_CPU1_P0_TX_DN<15>")
	)
	(arc
		(start 72.670416 -379.786896)
		(mid 72.723643 -379.690582)
		(end 72.765412 -379.588776)
		(width 0.14224)
		(layer "In6.Cu")
		(net "P5E_CPU1_P0_TX_DN<15>")
	)
	(arc
		(start 75.000104 -378.909326)
		(mid 75.042561 -378.964793)
		(end 75.068938 -379.029468)
		(width 0.14224)
		(layer "In6.Cu")
		(net "P5E_CPU1_P0_TX_DN<15>")
	)
	(arc
		(start 109.828584 -283.006038)
		(mid 109.827113 -282.99121)
		(end 109.826552 -282.97632)
		(width 0.1143)
		(layer "In6.Cu")
		(net "P5E_CPU1_P0_TX_DN<15>")
	)
	(arc
		(start 72.48525 -379.966728)
		(mid 72.588604 -379.8879)
		(end 72.670416 -379.786896)
		(width 0.14224)
		(layer "In6.Cu")
		(net "P5E_CPU1_P0_TX_DN<15>")
	)
	(arc
		(start 72.062594 -380.081028)
		(mid 72.281518 -380.051975)
		(end 72.48525 -379.966728)
		(width 0.14224)
		(layer "In6.Cu")
		(net "P5E_CPU1_P0_TX_DN<15>")
	)
	(arc
		(start 74.28103 -378.257054)
		(mid 74.342753 -378.269331)
		(end 74.395076 -378.304298)
		(width 0.14224)
		(layer "In6.Cu")
		(net "P5E_CPU1_P0_TX_DN<15>")
	)
	(arc
		(start 131.590034 -345.26474)
		(mid 131.61137 -345.207354)
		(end 131.631182 -345.149424)
		(width 0.14224)
		(layer "In6.Cu")
		(net "P5E_CPU1_P0_TX_DN<15>")
	)
	(arc
		(start 104.686608 -381.573532)
		(mid 104.740652 -381.540785)
		(end 104.792526 -381.504698)
		(width 0.14224)
		(layer "In6.Cu")
		(net "P5E_CPU1_P0_TX_DN<15>")
	)
	(arc
		(start 75.470004 -379.78715)
		(mid 75.808192 -380.01312)
		(end 76.207112 -380.092458)
		(width 0.14224)
		(layer "In6.Cu")
		(net "P5E_CPU1_P0_TX_DN<15>")
	)
	(arc
		(start 110.599474 -284.217872)
		(mid 110.544575 -284.16967)
		(end 110.483904 -284.128972)
		(width 0.1143)
		(layer "In6.Cu")
		(net "P5E_CPU1_P0_TX_DN<15>")
	)
	(arc
		(start 109.180122 -369.970304)
		(mid 109.354713 -369.617964)
		(end 109.601 -369.311428)
		(width 0.14224)
		(layer "In6.Cu")
		(net "P5E_CPU1_P0_TX_DN<15>")
	)
	(arc
		(start 131.758944 -342.059514)
		(mid 131.74655 -341.778368)
		(end 131.70916 -341.499444)
		(width 0.14224)
		(layer "In6.Cu")
		(net "P5E_CPU1_P0_TX_DN<15>")
	)
	(segment
		(start 110.1979 -283.540454)
		(end 109.731048 -283.806392)
		(width 0.12954)
		(layer "F.Cu")
		(net "P5E_CPU1_P0_TX_DN<14>")
	)
	(segment
		(start 71.007224 -376.686318)
		(end 70.303644 -376.686318)
		(width 0.12954)
		(layer "F.Cu")
		(net "P5E_CPU1_P0_TX_DN<14>")
	)
	(segment
		(start 71.277734 -376.956828)
		(end 71.007224 -376.686318)
		(width 0.12954)
		(layer "F.Cu")
		(net "P5E_CPU1_P0_TX_DN<14>")
	)
	(segment
		(start 70.303644 -376.686318)
		(end 70.007734 -376.982228)
		(width 0.12954)
		(layer "F.Cu")
		(net "P5E_CPU1_P0_TX_DN<14>")
	)
	(segment
		(start 110.377732 -298.310046)
		(end 112.600486 -303.677066)
		(width 0.14224)
		(layer "In6.Cu")
		(net "P5E_CPU1_P0_TX_DN<14>")
	)
	(segment
		(start 109.731048 -283.806392)
		(end 109.433106 -283.806392)
		(width 0.1143)
		(layer "In6.Cu")
		(net "P5E_CPU1_P0_TX_DN<14>")
	)
	(segment
		(start 110.455456 -287.352232)
		(end 110.521496 -287.39084)
		(width 0.1143)
		(layer "In6.Cu")
		(net "P5E_CPU1_P0_TX_DN<14>")
	)
	(segment
		(start 108.087414 -369.701826)
		(end 105.13822 -377.730004)
		(width 0.14224)
		(layer "In6.Cu")
		(net "P5E_CPU1_P0_TX_DN<14>")
	)
	(segment
		(start 109.5121 -284.11043)
		(end 109.551724 -284.133544)
		(width 0.1143)
		(layer "In6.Cu")
		(net "P5E_CPU1_P0_TX_DN<14>")
	)
	(segment
		(start 110.453424 -292.210998)
		(end 110.483904 -292.228778)
		(width 0.1143)
		(layer "In6.Cu")
		(net "P5E_CPU1_P0_TX_DN<14>")
	)
	(segment
		(start 123.500896 -318.268858)
		(end 128.137666 -327.140824)
		(width 0.14224)
		(layer "In6.Cu")
		(net "P5E_CPU1_P0_TX_DN<14>")
	)
	(segment
		(start 108.088176 -369.69954)
		(end 108.087414 -369.701826)
		(width 0.14224)
		(layer "In6.Cu")
		(net "P5E_CPU1_P0_TX_DN<14>")
	)
	(segment
		(start 104.218994 -378.371608)
		(end 103.702866 -378.371608)
		(width 0.14224)
		(layer "In6.Cu")
		(net "P5E_CPU1_P0_TX_DN<14>")
	)
	(segment
		(start 73.123044 -375.057162)
		(end 73.068942 -375.111264)
		(width 0.14224)
		(layer "In6.Cu")
		(net "P5E_CPU1_P0_TX_DN<14>")
	)
	(segment
		(start 108.24083 -369.283488)
		(end 108.088176 -369.69954)
		(width 0.14224)
		(layer "In6.Cu")
		(net "P5E_CPU1_P0_TX_DN<14>")
	)
	(segment
		(start 110.341918 -295.581578)
		(end 110.341918 -298.130722)
		(width 0.14224)
		(layer "In6.Cu")
		(net "P5E_CPU1_P0_TX_DN<14>")
	)
	(segment
		(start 110.524544 -288.319972)
		(end 110.451392 -288.362644)
		(width 0.1143)
		(layer "In6.Cu")
		(net "P5E_CPU1_P0_TX_DN<14>")
	)
	(segment
		(start 110.52302 -293.87165)
		(end 110.561882 -293.898574)
		(width 0.1143)
		(layer "In6.Cu")
		(net "P5E_CPU1_P0_TX_DN<14>")
	)
	(segment
		(start 110.520226 -293.182548)
		(end 110.483904 -293.20363)
		(width 0.1143)
		(layer "In6.Cu")
		(net "P5E_CPU1_P0_TX_DN<14>")
	)
	(segment
		(start 72.781668 -375.804684)
		(end 72.781668 -376.212354)
		(width 0.14224)
		(layer "In6.Cu")
		(net "P5E_CPU1_P0_TX_DN<14>")
	)
	(segment
		(start 110.454186 -290.591494)
		(end 110.520226 -290.629848)
		(width 0.1143)
		(layer "In6.Cu")
		(net "P5E_CPU1_P0_TX_DN<14>")
	)
	(segment
		(start 72.665082 -376.493786)
		(end 72.612758 -376.54611)
		(width 0.14224)
		(layer "In6.Cu")
		(net "P5E_CPU1_P0_TX_DN<14>")
	)
	(segment
		(start 116.907818 -310.235346)
		(end 123.500896 -318.268858)
		(width 0.14224)
		(layer "In6.Cu")
		(net "P5E_CPU1_P0_TX_DN<14>")
	)
	(segment
		(start 110.45571 -285.731204)
		(end 110.484412 -285.747968)
		(width 0.1143)
		(layer "In6.Cu")
		(net "P5E_CPU1_P0_TX_DN<14>")
	)
	(segment
		(start 72.781668 -376.212354)
		(end 72.665082 -376.493786)
		(width 0.14224)
		(layer "In6.Cu")
		(net "P5E_CPU1_P0_TX_DN<14>")
	)
	(segment
		(start 112.826038 -304.098198)
		(end 112.900714 -304.238152)
		(width 0.14224)
		(layer "In6.Cu")
		(net "P5E_CPU1_P0_TX_DN<14>")
	)
	(segment
		(start 112.600486 -303.677066)
		(end 112.825784 -304.098198)
		(width 0.14224)
		(layer "In6.Cu")
		(net "P5E_CPU1_P0_TX_DN<14>")
	)
	(segment
		(start 109.12475 -368.399568)
		(end 108.24083 -369.283488)
		(width 0.14224)
		(layer "In6.Cu")
		(net "P5E_CPU1_P0_TX_DN<14>")
	)
	(segment
		(start 110.483904 -289.963606)
		(end 110.453424 -289.981386)
		(width 0.1143)
		(layer "In6.Cu")
		(net "P5E_CPU1_P0_TX_DN<14>")
	)
	(segment
		(start 110.483904 -294.823642)
		(end 110.45317 -294.841422)
		(width 0.1143)
		(layer "In6.Cu")
		(net "P5E_CPU1_P0_TX_DN<14>")
	)
	(segment
		(start 110.484412 -285.747968)
		(end 110.484666 -285.748222)
		(width 0.1143)
		(layer "In6.Cu")
		(net "P5E_CPU1_P0_TX_DN<14>")
	)
	(segment
		(start 110.47603 -293.843964)
		(end 110.521496 -293.870634)
		(width 0.1143)
		(layer "In6.Cu")
		(net "P5E_CPU1_P0_TX_DN<14>")
	)
	(segment
		(start 109.835188 -284.623764)
		(end 109.835188 -284.629098)
		(width 0.1143)
		(layer "In6.Cu")
		(net "P5E_CPU1_P0_TX_DN<14>")
	)
	(segment
		(start 110.453424 -288.970974)
		(end 110.483904 -288.988754)
		(width 0.1143)
		(layer "In6.Cu")
		(net "P5E_CPU1_P0_TX_DN<14>")
	)
	(segment
		(start 128.137666 -327.140824)
		(end 130.786632 -341.888826)
		(width 0.14224)
		(layer "In6.Cu")
		(net "P5E_CPU1_P0_TX_DN<14>")
	)
	(segment
		(start 110.766098 -287.856422)
		(end 110.766098 -287.904174)
		(width 0.1143)
		(layer "In6.Cu")
		(net "P5E_CPU1_P0_TX_DN<14>")
	)
	(segment
		(start 110.483904 -292.228778)
		(end 110.520226 -292.24986)
		(width 0.1143)
		(layer "In6.Cu")
		(net "P5E_CPU1_P0_TX_DN<14>")
	)
	(segment
		(start 72.323452 -376.665998)
		(end 71.568564 -376.665998)
		(width 0.14224)
		(layer "In6.Cu")
		(net "P5E_CPU1_P0_TX_DN<14>")
	)
	(segment
		(start 109.433106 -283.806392)
		(end 109.363256 -283.876242)
		(width 0.1143)
		(layer "In6.Cu")
		(net "P5E_CPU1_P0_TX_DN<14>")
	)
	(segment
		(start 110.453424 -287.350962)
		(end 110.455456 -287.352232)
		(width 0.1143)
		(layer "In6.Cu")
		(net "P5E_CPU1_P0_TX_DN<14>")
	)
	(segment
		(start 110.571026 -288.286444)
		(end 110.524544 -288.319972)
		(width 0.1143)
		(layer "In6.Cu")
		(net "P5E_CPU1_P0_TX_DN<14>")
	)
	(segment
		(start 97.988628 -376.568716)
		(end 77.698854 -376.568716)
		(width 0.14224)
		(layer "In6.Cu")
		(net "P5E_CPU1_P0_TX_DN<14>")
	)
	(segment
		(start 110.013496 -284.938978)
		(end 110.052358 -284.96133)
		(width 0.1143)
		(layer "In6.Cu")
		(net "P5E_CPU1_P0_TX_DN<14>")
	)
	(segment
		(start 110.483904 -288.988754)
		(end 110.520226 -289.009836)
		(width 0.1143)
		(layer "In6.Cu")
		(net "P5E_CPU1_P0_TX_DN<14>")
	)
	(segment
		(start 130.786632 -341.888826)
		(end 130.786632 -344.425016)
		(width 0.14224)
		(layer "In6.Cu")
		(net "P5E_CPU1_P0_TX_DN<14>")
	)
	(segment
		(start 110.341918 -295.55313)
		(end 110.341918 -295.581578)
		(width 0.1143)
		(layer "In6.Cu")
		(net "P5E_CPU1_P0_TX_DN<14>")
	)
	(segment
		(start 112.900714 -304.238152)
		(end 116.907818 -310.235346)
		(width 0.14224)
		(layer "In6.Cu")
		(net "P5E_CPU1_P0_TX_DN<14>")
	)
	(segment
		(start 110.561882 -294.773858)
		(end 110.483904 -294.823642)
		(width 0.1143)
		(layer "In6.Cu")
		(net "P5E_CPU1_P0_TX_DN<14>")
	)
	(segment
		(start 110.296198 -295.146222)
		(end 110.296198 -295.50741)
		(width 0.1143)
		(layer "In6.Cu")
		(net "P5E_CPU1_P0_TX_DN<14>")
	)
	(segment
		(start 110.453424 -290.590986)
		(end 110.454186 -290.591494)
		(width 0.1143)
		(layer "In6.Cu")
		(net "P5E_CPU1_P0_TX_DN<14>")
	)
	(segment
		(start 125.82398 -355.72573)
		(end 111.31804 -366.505744)
		(width 0.14224)
		(layer "In6.Cu")
		(net "P5E_CPU1_P0_TX_DN<14>")
	)
	(segment
		(start 71.568564 -376.665998)
		(end 71.277734 -376.956828)
		(width 0.14224)
		(layer "In6.Cu")
		(net "P5E_CPU1_P0_TX_DN<14>")
	)
	(segment
		(start 130.670046 -345.010994)
		(end 127.125222 -353.568254)
		(width 0.14224)
		(layer "In6.Cu")
		(net "P5E_CPU1_P0_TX_DN<14>")
	)
	(segment
		(start 75.703938 -375.742454)
		(end 75.15352 -375.192036)
		(width 0.14224)
		(layer "In6.Cu")
		(net "P5E_CPU1_P0_TX_DN<14>")
	)
	(segment
		(start 74.079862 -374.747282)
		(end 73.871074 -374.747282)
		(width 0.14224)
		(layer "In6.Cu")
		(net "P5E_CPU1_P0_TX_DN<14>")
	)
	(segment
		(start 110.483904 -291.583618)
		(end 110.453424 -291.601398)
		(width 0.1143)
		(layer "In6.Cu")
		(net "P5E_CPU1_P0_TX_DN<14>")
	)
	(segment
		(start 110.520226 -291.562536)
		(end 110.483904 -291.583618)
		(width 0.1143)
		(layer "In6.Cu")
		(net "P5E_CPU1_P0_TX_DN<14>")
	)
	(segment
		(start 112.825784 -304.098198)
		(end 112.826038 -304.098198)
		(width 0.14224)
		(layer "In6.Cu")
		(net "P5E_CPU1_P0_TX_DN<14>")
	)
	(segment
		(start 110.45317 -285.731204)
		(end 110.45571 -285.731204)
		(width 0.1143)
		(layer "In6.Cu")
		(net "P5E_CPU1_P0_TX_DN<14>")
	)
	(segment
		(start 110.483904 -293.20363)
		(end 110.484158 -293.20363)
		(width 0.1143)
		(layer "In6.Cu")
		(net "P5E_CPU1_P0_TX_DN<14>")
	)
	(segment
		(start 110.520226 -286.702754)
		(end 110.451392 -286.742632)
		(width 0.1143)
		(layer "In6.Cu")
		(net "P5E_CPU1_P0_TX_DN<14>")
	)
	(segment
		(start 110.296198 -295.50741)
		(end 110.341918 -295.55313)
		(width 0.1143)
		(layer "In6.Cu")
		(net "P5E_CPU1_P0_TX_DN<14>")
	)
	(segment
		(start 110.520226 -289.942524)
		(end 110.483904 -289.963606)
		(width 0.1143)
		(layer "In6.Cu")
		(net "P5E_CPU1_P0_TX_DN<14>")
	)
	(arc
		(start 110.506002 -285.761176)
		(mid 110.765814 -286.22814)
		(end 110.520226 -286.702754)
		(width 0.1143)
		(layer "In6.Cu")
		(net "P5E_CPU1_P0_TX_DN<14>")
	)
	(arc
		(start 109.363256 -283.876242)
		(mid 109.41521 -284.007611)
		(end 109.5121 -284.11043)
		(width 0.1143)
		(layer "In6.Cu")
		(net "P5E_CPU1_P0_TX_DN<14>")
	)
	(arc
		(start 110.453424 -289.981386)
		(mid 110.296447 -290.286186)
		(end 110.453424 -290.590986)
		(width 0.1143)
		(layer "In6.Cu")
		(net "P5E_CPU1_P0_TX_DN<14>")
	)
	(arc
		(start 110.453424 -291.601398)
		(mid 110.296447 -291.906198)
		(end 110.453424 -292.210998)
		(width 0.1143)
		(layer "In6.Cu")
		(net "P5E_CPU1_P0_TX_DN<14>")
	)
	(arc
		(start 75.15352 -375.192036)
		(mid 74.660922 -374.862892)
		(end 74.079862 -374.747282)
		(width 0.14224)
		(layer "In6.Cu")
		(net "P5E_CPU1_P0_TX_DN<14>")
	)
	(arc
		(start 127.125222 -353.568254)
		(mid 126.612491 -354.611792)
		(end 125.970538 -355.581204)
		(width 0.14224)
		(layer "In6.Cu")
		(net "P5E_CPU1_P0_TX_DN<14>")
	)
	(arc
		(start 110.296198 -285.426404)
		(mid 110.337747 -285.597826)
		(end 110.45317 -285.731204)
		(width 0.1143)
		(layer "In6.Cu")
		(net "P5E_CPU1_P0_TX_DN<14>")
	)
	(arc
		(start 110.052358 -284.96133)
		(mid 110.231551 -285.16384)
		(end 110.296198 -285.426404)
		(width 0.1143)
		(layer "In6.Cu")
		(net "P5E_CPU1_P0_TX_DN<14>")
	)
	(arc
		(start 100.898452 -377.486926)
		(mid 99.514248 -376.803761)
		(end 97.988628 -376.568716)
		(width 0.14224)
		(layer "In6.Cu")
		(net "P5E_CPU1_P0_TX_DN<14>")
	)
	(arc
		(start 110.451392 -286.742632)
		(mid 110.337463 -286.875779)
		(end 110.296452 -287.046162)
		(width 0.1143)
		(layer "In6.Cu")
		(net "P5E_CPU1_P0_TX_DN<14>")
	)
	(arc
		(start 109.835188 -284.629098)
		(mid 109.882949 -284.807854)
		(end 110.013496 -284.938978)
		(width 0.1143)
		(layer "In6.Cu")
		(net "P5E_CPU1_P0_TX_DN<14>")
	)
	(arc
		(start 125.970538 -355.581204)
		(mid 125.902372 -355.658652)
		(end 125.82398 -355.72573)
		(width 0.14224)
		(layer "In6.Cu")
		(net "P5E_CPU1_P0_TX_DN<14>")
	)
	(arc
		(start 110.520226 -289.009836)
		(mid 110.766116 -289.47618)
		(end 110.520226 -289.942524)
		(width 0.1143)
		(layer "In6.Cu")
		(net "P5E_CPU1_P0_TX_DN<14>")
	)
	(arc
		(start 103.702866 -378.371608)
		(mid 102.232565 -378.145141)
		(end 100.898452 -377.486926)
		(width 0.14224)
		(layer "In6.Cu")
		(net "P5E_CPU1_P0_TX_DN<14>")
	)
	(arc
		(start 105.13822 -377.730004)
		(mid 104.779514 -378.195398)
		(end 104.218994 -378.371608)
		(width 0.14224)
		(layer "In6.Cu")
		(net "P5E_CPU1_P0_TX_DN<14>")
	)
	(arc
		(start 73.871074 -374.747282)
		(mid 73.466229 -374.827811)
		(end 73.123044 -375.057162)
		(width 0.14224)
		(layer "In6.Cu")
		(net "P5E_CPU1_P0_TX_DN<14>")
	)
	(arc
		(start 110.520226 -290.629848)
		(mid 110.766116 -291.096192)
		(end 110.520226 -291.562536)
		(width 0.1143)
		(layer "In6.Cu")
		(net "P5E_CPU1_P0_TX_DN<14>")
	)
	(arc
		(start 110.296452 -287.046162)
		(mid 110.338001 -287.217584)
		(end 110.453424 -287.350962)
		(width 0.1143)
		(layer "In6.Cu")
		(net "P5E_CPU1_P0_TX_DN<14>")
	)
	(arc
		(start 110.561882 -293.898574)
		(mid 110.79106 -294.336216)
		(end 110.561882 -294.773858)
		(width 0.1143)
		(layer "In6.Cu")
		(net "P5E_CPU1_P0_TX_DN<14>")
	)
	(arc
		(start 110.341918 -298.130722)
		(mid 110.350974 -298.222154)
		(end 110.377732 -298.310046)
		(width 0.14224)
		(layer "In6.Cu")
		(net "P5E_CPU1_P0_TX_DN<14>")
	)
	(arc
		(start 72.612758 -376.54611)
		(mid 72.480038 -376.634854)
		(end 72.323452 -376.665998)
		(width 0.14224)
		(layer "In6.Cu")
		(net "P5E_CPU1_P0_TX_DN<14>")
	)
	(arc
		(start 110.484666 -285.748222)
		(mid 110.495405 -285.754582)
		(end 110.506002 -285.761176)
		(width 0.1143)
		(layer "In6.Cu")
		(net "P5E_CPU1_P0_TX_DN<14>")
	)
	(arc
		(start 110.766098 -287.904174)
		(mid 110.714519 -288.118766)
		(end 110.571026 -288.286444)
		(width 0.1143)
		(layer "In6.Cu")
		(net "P5E_CPU1_P0_TX_DN<14>")
	)
	(arc
		(start 130.786632 -344.425016)
		(mid 130.757211 -344.723751)
		(end 130.670046 -345.010994)
		(width 0.14224)
		(layer "In6.Cu")
		(net "P5E_CPU1_P0_TX_DN<14>")
	)
	(arc
		(start 73.068942 -375.111264)
		(mid 72.856311 -375.429394)
		(end 72.781668 -375.804684)
		(width 0.14224)
		(layer "In6.Cu")
		(net "P5E_CPU1_P0_TX_DN<14>")
	)
	(arc
		(start 110.521496 -287.39084)
		(mid 110.701288 -287.593428)
		(end 110.766098 -287.856422)
		(width 0.1143)
		(layer "In6.Cu")
		(net "P5E_CPU1_P0_TX_DN<14>")
	)
	(arc
		(start 110.296452 -288.666174)
		(mid 110.338001 -288.837596)
		(end 110.453424 -288.970974)
		(width 0.1143)
		(layer "In6.Cu")
		(net "P5E_CPU1_P0_TX_DN<14>")
	)
	(arc
		(start 110.520226 -292.24986)
		(mid 110.766116 -292.716204)
		(end 110.520226 -293.182548)
		(width 0.1143)
		(layer "In6.Cu")
		(net "P5E_CPU1_P0_TX_DN<14>")
	)
	(arc
		(start 110.451392 -288.362644)
		(mid 110.337463 -288.495791)
		(end 110.296452 -288.666174)
		(width 0.1143)
		(layer "In6.Cu")
		(net "P5E_CPU1_P0_TX_DN<14>")
	)
	(arc
		(start 110.484158 -293.20363)
		(mid 110.29918 -293.521484)
		(end 110.47603 -293.843964)
		(width 0.1143)
		(layer "In6.Cu")
		(net "P5E_CPU1_P0_TX_DN<14>")
	)
	(arc
		(start 109.551724 -284.133544)
		(mid 109.759208 -284.340631)
		(end 109.835188 -284.623764)
		(width 0.1143)
		(layer "In6.Cu")
		(net "P5E_CPU1_P0_TX_DN<14>")
	)
	(arc
		(start 77.698854 -376.568716)
		(mid 76.619222 -376.353982)
		(end 75.703938 -375.742454)
		(width 0.14224)
		(layer "In6.Cu")
		(net "P5E_CPU1_P0_TX_DN<14>")
	)
	(arc
		(start 110.521496 -293.870634)
		(mid 110.522258 -293.871141)
		(end 110.52302 -293.87165)
		(width 0.1143)
		(layer "In6.Cu")
		(net "P5E_CPU1_P0_TX_DN<14>")
	)
	(arc
		(start 110.45317 -294.841422)
		(mid 110.337743 -294.974798)
		(end 110.296198 -295.146222)
		(width 0.1143)
		(layer "In6.Cu")
		(net "P5E_CPU1_P0_TX_DN<14>")
	)
	(arc
		(start 111.31804 -366.505744)
		(mid 110.18675 -367.412533)
		(end 109.12475 -368.399568)
		(width 0.14224)
		(layer "In6.Cu")
		(net "P5E_CPU1_P0_TX_DN<14>")
	)
	(segment
		(start 68.812664 -370.00942)
		(end 68.516754 -370.30533)
		(width 0.12954)
		(layer "F.Cu")
		(net "P5E_CPU1_P0_TX_DN<13>")
	)
	(segment
		(start 68.542154 -369.03533)
		(end 68.812664 -369.30584)
		(width 0.12954)
		(layer "F.Cu")
		(net "P5E_CPU1_P0_TX_DN<13>")
	)
	(segment
		(start 110.1979 -285.160466)
		(end 109.731048 -285.426404)
		(width 0.12954)
		(layer "F.Cu")
		(net "P5E_CPU1_P0_TX_DN<13>")
	)
	(segment
		(start 68.812664 -369.30584)
		(end 68.812664 -370.00942)
		(width 0.12954)
		(layer "F.Cu")
		(net "P5E_CPU1_P0_TX_DN<13>")
	)
	(segment
		(start 109.512354 -290.590478)
		(end 109.544104 -290.608766)
		(width 0.1143)
		(layer "In6.Cu")
		(net "P5E_CPU1_P0_TX_DN<13>")
	)
	(segment
		(start 124.179838 -355.69779)
		(end 123.67006 -356.038658)
		(width 0.14224)
		(layer "In6.Cu")
		(net "P5E_CPU1_P0_TX_DN<13>")
	)
	(segment
		(start 109.582966 -289.01136)
		(end 109.610906 -289.031426)
		(width 0.1143)
		(layer "In6.Cu")
		(net "P5E_CPU1_P0_TX_DN<13>")
	)
	(segment
		(start 112.107218 -364.610142)
		(end 109.849158 -366.284764)
		(width 0.14224)
		(layer "In6.Cu")
		(net "P5E_CPU1_P0_TX_DN<13>")
	)
	(segment
		(start 109.433106 -285.426404)
		(end 109.363256 -285.496254)
		(width 0.1143)
		(layer "In6.Cu")
		(net "P5E_CPU1_P0_TX_DN<13>")
	)
	(segment
		(start 109.582966 -293.181024)
		(end 109.549438 -293.200582)
		(width 0.1143)
		(layer "In6.Cu")
		(net "P5E_CPU1_P0_TX_DN<13>")
	)
	(segment
		(start 109.513624 -287.351216)
		(end 109.583474 -287.391602)
		(width 0.1143)
		(layer "In6.Cu")
		(net "P5E_CPU1_P0_TX_DN<13>")
	)
	(segment
		(start 109.546644 -285.750508)
		(end 109.562138 -285.759398)
		(width 0.1143)
		(layer "In6.Cu")
		(net "P5E_CPU1_P0_TX_DN<13>")
	)
	(segment
		(start 109.543088 -285.748476)
		(end 109.545882 -285.75)
		(width 0.1143)
		(layer "In6.Cu")
		(net "P5E_CPU1_P0_TX_DN<13>")
	)
	(segment
		(start 109.753146 -366.367568)
		(end 105.863898 -370.256816)
		(width 0.14224)
		(layer "In6.Cu")
		(net "P5E_CPU1_P0_TX_DN<13>")
	)
	(segment
		(start 109.532928 -292.222174)
		(end 109.582966 -292.251384)
		(width 0.1143)
		(layer "In6.Cu")
		(net "P5E_CPU1_P0_TX_DN<13>")
	)
	(segment
		(start 109.545882 -285.75)
		(end 109.546644 -285.750508)
		(width 0.1143)
		(layer "In6.Cu")
		(net "P5E_CPU1_P0_TX_DN<13>")
	)
	(segment
		(start 109.512354 -285.730696)
		(end 109.539786 -285.746444)
		(width 0.1143)
		(layer "In6.Cu")
		(net "P5E_CPU1_P0_TX_DN<13>")
	)
	(segment
		(start 76.34351 -375.051066)
		(end 71.677784 -370.38534)
		(width 0.14224)
		(layer "In6.Cu")
		(net "P5E_CPU1_P0_TX_DN<13>")
	)
	(segment
		(start 69.702426 -370.42979)
		(end 69.404738 -370.42979)
		(width 0.14224)
		(layer "In6.Cu")
		(net "P5E_CPU1_P0_TX_DN<13>")
	)
	(segment
		(start 109.512354 -288.970466)
		(end 109.539786 -288.986214)
		(width 0.1143)
		(layer "In6.Cu")
		(net "P5E_CPU1_P0_TX_DN<13>")
	)
	(segment
		(start 109.540548 -288.986722)
		(end 109.546898 -288.990532)
		(width 0.1143)
		(layer "In6.Cu")
		(net "P5E_CPU1_P0_TX_DN<13>")
	)
	(segment
		(start 109.356144 -295.474136)
		(end 109.401864 -295.519856)
		(width 0.1143)
		(layer "In6.Cu")
		(net "P5E_CPU1_P0_TX_DN<13>")
	)
	(segment
		(start 109.545628 -289.96259)
		(end 109.543342 -289.964114)
		(width 0.1143)
		(layer "In6.Cu")
		(net "P5E_CPU1_P0_TX_DN<13>")
	)
	(segment
		(start 127.288798 -327.757536)
		(end 127.288798 -327.75779)
		(width 0.14224)
		(layer "In6.Cu")
		(net "P5E_CPU1_P0_TX_DN<13>")
	)
	(segment
		(start 123.561856 -356.114604)
		(end 112.107218 -364.610142)
		(width 0.14224)
		(layer "In6.Cu")
		(net "P5E_CPU1_P0_TX_DN<13>")
	)
	(segment
		(start 109.543342 -289.964114)
		(end 109.540548 -289.965638)
		(width 0.1143)
		(layer "In6.Cu")
		(net "P5E_CPU1_P0_TX_DN<13>")
	)
	(segment
		(start 109.537754 -289.967162)
		(end 109.512354 -289.981894)
		(width 0.1143)
		(layer "In6.Cu")
		(net "P5E_CPU1_P0_TX_DN<13>")
	)
	(segment
		(start 111.754666 -304.089308)
		(end 112.075468 -304.688748)
		(width 0.14224)
		(layer "In6.Cu")
		(net "P5E_CPU1_P0_TX_DN<13>")
	)
	(segment
		(start 129.839212 -342.046052)
		(end 129.839212 -343.384378)
		(width 0.14224)
		(layer "In6.Cu")
		(net "P5E_CPU1_P0_TX_DN<13>")
	)
	(segment
		(start 109.41177 -298.431712)
		(end 111.754666 -304.089308)
		(width 0.14224)
		(layer "In6.Cu")
		(net "P5E_CPU1_P0_TX_DN<13>")
	)
	(segment
		(start 129.413762 -345.523312)
		(end 126.239016 -353.18827)
		(width 0.14224)
		(layer "In6.Cu")
		(net "P5E_CPU1_P0_TX_DN<13>")
	)
	(segment
		(start 68.832984 -369.93449)
		(end 68.832984 -369.32616)
		(width 0.14224)
		(layer "In6.Cu")
		(net "P5E_CPU1_P0_TX_DN<13>")
	)
	(segment
		(start 70.751192 -370.25199)
		(end 70.737476 -370.251228)
		(width 0.14224)
		(layer "In6.Cu")
		(net "P5E_CPU1_P0_TX_DN<13>")
	)
	(segment
		(start 109.539786 -289.966146)
		(end 109.537754 -289.967162)
		(width 0.1143)
		(layer "In6.Cu")
		(net "P5E_CPU1_P0_TX_DN<13>")
	)
	(segment
		(start 109.512354 -292.21049)
		(end 109.532928 -292.222174)
		(width 0.1143)
		(layer "In6.Cu")
		(net "P5E_CPU1_P0_TX_DN<13>")
	)
	(segment
		(start 109.610906 -289.920934)
		(end 109.582966 -289.941)
		(width 0.1143)
		(layer "In6.Cu")
		(net "P5E_CPU1_P0_TX_DN<13>")
	)
	(segment
		(start 70.737476 -370.251228)
		(end 70.342506 -370.251228)
		(width 0.14224)
		(layer "In6.Cu")
		(net "P5E_CPU1_P0_TX_DN<13>")
	)
	(segment
		(start 109.546898 -288.990532)
		(end 109.582966 -289.01136)
		(width 0.1143)
		(layer "In6.Cu")
		(net "P5E_CPU1_P0_TX_DN<13>")
	)
	(segment
		(start 105.796334 -370.362734)
		(end 104.844596 -372.95328)
		(width 0.14224)
		(layer "In6.Cu")
		(net "P5E_CPU1_P0_TX_DN<13>")
	)
	(segment
		(start 109.527848 -293.21252)
		(end 109.512354 -293.221918)
		(width 0.1143)
		(layer "In6.Cu")
		(net "P5E_CPU1_P0_TX_DN<13>")
	)
	(segment
		(start 109.401864 -295.519856)
		(end 109.401864 -295.548304)
		(width 0.1143)
		(layer "In6.Cu")
		(net "P5E_CPU1_P0_TX_DN<13>")
	)
	(segment
		(start 122.743214 -318.848232)
		(end 127.145796 -327.270364)
		(width 0.14224)
		(layer "In6.Cu")
		(net "P5E_CPU1_P0_TX_DN<13>")
	)
	(segment
		(start 127.214376 -327.448672)
		(end 127.261874 -327.634092)
		(width 0.14224)
		(layer "In6.Cu")
		(net "P5E_CPU1_P0_TX_DN<13>")
	)
	(segment
		(start 109.539786 -285.746444)
		(end 109.540548 -285.746952)
		(width 0.1143)
		(layer "In6.Cu")
		(net "P5E_CPU1_P0_TX_DN<13>")
	)
	(segment
		(start 109.540548 -291.58565)
		(end 109.539786 -291.586158)
		(width 0.1143)
		(layer "In6.Cu")
		(net "P5E_CPU1_P0_TX_DN<13>")
	)
	(segment
		(start 71.355966 -370.25199)
		(end 70.751192 -370.25199)
		(width 0.14224)
		(layer "In6.Cu")
		(net "P5E_CPU1_P0_TX_DN<13>")
	)
	(segment
		(start 109.731048 -285.426404)
		(end 109.433106 -285.426404)
		(width 0.1143)
		(layer "In6.Cu")
		(net "P5E_CPU1_P0_TX_DN<13>")
	)
	(segment
		(start 109.56544 -286.71139)
		(end 109.510576 -286.743394)
		(width 0.1143)
		(layer "In6.Cu")
		(net "P5E_CPU1_P0_TX_DN<13>")
	)
	(segment
		(start 109.540548 -289.965638)
		(end 109.539786 -289.966146)
		(width 0.1143)
		(layer "In6.Cu")
		(net "P5E_CPU1_P0_TX_DN<13>")
	)
	(segment
		(start 109.537754 -291.587174)
		(end 109.512354 -291.601906)
		(width 0.1143)
		(layer "In6.Cu")
		(net "P5E_CPU1_P0_TX_DN<13>")
	)
	(segment
		(start 109.539786 -291.586158)
		(end 109.537754 -291.587174)
		(width 0.1143)
		(layer "In6.Cu")
		(net "P5E_CPU1_P0_TX_DN<13>")
	)
	(segment
		(start 116.180362 -310.821578)
		(end 122.64136 -318.694562)
		(width 0.14224)
		(layer "In6.Cu")
		(net "P5E_CPU1_P0_TX_DN<13>")
	)
	(segment
		(start 109.564678 -293.860728)
		(end 109.56544 -293.861236)
		(width 0.1143)
		(layer "In6.Cu")
		(net "P5E_CPU1_P0_TX_DN<13>")
	)
	(segment
		(start 109.356398 -295.146222)
		(end 109.356398 -295.473882)
		(width 0.1143)
		(layer "In6.Cu")
		(net "P5E_CPU1_P0_TX_DN<13>")
	)
	(segment
		(start 109.549438 -293.200582)
		(end 109.527848 -293.21252)
		(width 0.1143)
		(layer "In6.Cu")
		(net "P5E_CPU1_P0_TX_DN<13>")
	)
	(segment
		(start 109.582966 -292.251384)
		(end 109.610906 -292.27145)
		(width 0.1143)
		(layer "In6.Cu")
		(net "P5E_CPU1_P0_TX_DN<13>")
	)
	(segment
		(start 109.539786 -288.986214)
		(end 109.540548 -288.986722)
		(width 0.1143)
		(layer "In6.Cu")
		(net "P5E_CPU1_P0_TX_DN<13>")
	)
	(segment
		(start 109.58576 -288.31921)
		(end 109.510576 -288.363406)
		(width 0.1143)
		(layer "In6.Cu")
		(net "P5E_CPU1_P0_TX_DN<13>")
	)
	(segment
		(start 109.583474 -287.391602)
		(end 109.710982 -287.48355)
		(width 0.1143)
		(layer "In6.Cu")
		(net "P5E_CPU1_P0_TX_DN<13>")
	)
	(segment
		(start 109.544104 -290.608766)
		(end 109.580426 -290.629848)
		(width 0.1143)
		(layer "In6.Cu")
		(net "P5E_CPU1_P0_TX_DN<13>")
	)
	(segment
		(start 68.832984 -369.32616)
		(end 68.542154 -369.03533)
		(width 0.14224)
		(layer "In6.Cu")
		(net "P5E_CPU1_P0_TX_DN<13>")
	)
	(segment
		(start 109.580426 -291.562536)
		(end 109.544104 -291.583618)
		(width 0.1143)
		(layer "In6.Cu")
		(net "P5E_CPU1_P0_TX_DN<13>")
	)
	(segment
		(start 101.783134 -375.513854)
		(end 77.460856 -375.513854)
		(width 0.14224)
		(layer "In6.Cu")
		(net "P5E_CPU1_P0_TX_DN<13>")
	)
	(segment
		(start 112.075468 -304.688748)
		(end 116.10594 -310.721248)
		(width 0.14224)
		(layer "In6.Cu")
		(net "P5E_CPU1_P0_TX_DN<13>")
	)
	(segment
		(start 109.56544 -294.811196)
		(end 109.512354 -294.84193)
		(width 0.1143)
		(layer "In6.Cu")
		(net "P5E_CPU1_P0_TX_DN<13>")
	)
	(segment
		(start 109.544104 -291.583618)
		(end 109.543342 -291.584126)
		(width 0.1143)
		(layer "In6.Cu")
		(net "P5E_CPU1_P0_TX_DN<13>")
	)
	(segment
		(start 109.401864 -295.548304)
		(end 109.401864 -298.38269)
		(width 0.14224)
		(layer "In6.Cu")
		(net "P5E_CPU1_P0_TX_DN<13>")
	)
	(segment
		(start 109.356398 -295.473882)
		(end 109.356144 -295.474136)
		(width 0.1143)
		(layer "In6.Cu")
		(net "P5E_CPU1_P0_TX_DN<13>")
	)
	(segment
		(start 109.540548 -285.746952)
		(end 109.542326 -285.747968)
		(width 0.1143)
		(layer "In6.Cu")
		(net "P5E_CPU1_P0_TX_DN<13>")
	)
	(segment
		(start 109.41177 -298.431458)
		(end 109.41177 -298.431712)
		(width 0.14224)
		(layer "In6.Cu")
		(net "P5E_CPU1_P0_TX_DN<13>")
	)
	(segment
		(start 127.288798 -327.75779)
		(end 129.823718 -341.87003)
		(width 0.14224)
		(layer "In6.Cu")
		(net "P5E_CPU1_P0_TX_DN<13>")
	)
	(segment
		(start 109.543342 -291.584126)
		(end 109.540548 -291.58565)
		(width 0.1143)
		(layer "In6.Cu")
		(net "P5E_CPU1_P0_TX_DN<13>")
	)
	(segment
		(start 109.512354 -293.830502)
		(end 109.564678 -293.860728)
		(width 0.1143)
		(layer "In6.Cu")
		(net "P5E_CPU1_P0_TX_DN<13>")
	)
	(segment
		(start 109.826298 -287.709356)
		(end 109.826298 -287.856422)
		(width 0.1143)
		(layer "In6.Cu")
		(net "P5E_CPU1_P0_TX_DN<13>")
	)
	(segment
		(start 109.512354 -287.350454)
		(end 109.513624 -287.351216)
		(width 0.1143)
		(layer "In6.Cu")
		(net "P5E_CPU1_P0_TX_DN<13>")
	)
	(segment
		(start 109.610906 -293.160958)
		(end 109.582966 -293.181024)
		(width 0.1143)
		(layer "In6.Cu")
		(net "P5E_CPU1_P0_TX_DN<13>")
	)
	(segment
		(start 109.562138 -285.759398)
		(end 109.563662 -285.760414)
		(width 0.1143)
		(layer "In6.Cu")
		(net "P5E_CPU1_P0_TX_DN<13>")
	)
	(segment
		(start 109.563662 -285.760414)
		(end 109.56544 -285.76143)
		(width 0.1143)
		(layer "In6.Cu")
		(net "P5E_CPU1_P0_TX_DN<13>")
	)
	(segment
		(start 109.582966 -289.941)
		(end 109.545628 -289.96259)
		(width 0.1143)
		(layer "In6.Cu")
		(net "P5E_CPU1_P0_TX_DN<13>")
	)
	(segment
		(start 109.542326 -285.747968)
		(end 109.543088 -285.748476)
		(width 0.1143)
		(layer "In6.Cu")
		(net "P5E_CPU1_P0_TX_DN<13>")
	)
	(arc
		(start 69.404738 -370.42979)
		(mid 69.165291 -370.382237)
		(end 68.96227 -370.246656)
		(width 0.14224)
		(layer "In6.Cu")
		(net "P5E_CPU1_P0_TX_DN<13>")
	)
	(arc
		(start 71.677784 -370.38534)
		(mid 71.530147 -370.286629)
		(end 71.355966 -370.25199)
		(width 0.14224)
		(layer "In6.Cu")
		(net "P5E_CPU1_P0_TX_DN<13>")
	)
	(arc
		(start 109.401864 -298.38269)
		(mid 109.404414 -298.407562)
		(end 109.41177 -298.431458)
		(width 0.14224)
		(layer "In6.Cu")
		(net "P5E_CPU1_P0_TX_DN<13>")
	)
	(arc
		(start 109.56544 -285.76143)
		(mid 109.838991 -286.23641)
		(end 109.56544 -286.71139)
		(width 0.1143)
		(layer "In6.Cu")
		(net "P5E_CPU1_P0_TX_DN<13>")
	)
	(arc
		(start 127.145796 -327.270364)
		(mid 127.185237 -327.357537)
		(end 127.214376 -327.448672)
		(width 0.14224)
		(layer "In6.Cu")
		(net "P5E_CPU1_P0_TX_DN<13>")
	)
	(arc
		(start 109.610906 -289.031426)
		(mid 109.838906 -289.47618)
		(end 109.610906 -289.920934)
		(width 0.1143)
		(layer "In6.Cu")
		(net "P5E_CPU1_P0_TX_DN<13>")
	)
	(arc
		(start 109.580426 -290.629848)
		(mid 109.58809 -290.635119)
		(end 109.595666 -290.640516)
		(width 0.1143)
		(layer "In6.Cu")
		(net "P5E_CPU1_P0_TX_DN<13>")
	)
	(arc
		(start 109.510576 -288.363406)
		(mid 109.397169 -288.496295)
		(end 109.356398 -288.666174)
		(width 0.1143)
		(layer "In6.Cu")
		(net "P5E_CPU1_P0_TX_DN<13>")
	)
	(arc
		(start 70.006718 -370.345208)
		(mid 69.860373 -370.40836)
		(end 69.702426 -370.42979)
		(width 0.14224)
		(layer "In6.Cu")
		(net "P5E_CPU1_P0_TX_DN<13>")
	)
	(arc
		(start 109.512354 -293.221918)
		(mid 109.356426 -293.52621)
		(end 109.512354 -293.830502)
		(width 0.1143)
		(layer "In6.Cu")
		(net "P5E_CPU1_P0_TX_DN<13>")
	)
	(arc
		(start 116.10594 -310.721248)
		(mid 116.14194 -310.772311)
		(end 116.180362 -310.821578)
		(width 0.14224)
		(layer "In6.Cu")
		(net "P5E_CPU1_P0_TX_DN<13>")
	)
	(arc
		(start 105.863898 -370.256816)
		(mid 105.824378 -370.306111)
		(end 105.796334 -370.362734)
		(width 0.14224)
		(layer "In6.Cu")
		(net "P5E_CPU1_P0_TX_DN<13>")
	)
	(arc
		(start 109.512354 -294.84193)
		(mid 109.397678 -294.975264)
		(end 109.356398 -295.146222)
		(width 0.1143)
		(layer "In6.Cu")
		(net "P5E_CPU1_P0_TX_DN<13>")
	)
	(arc
		(start 103.72217 -374.712738)
		(mid 102.832109 -375.305626)
		(end 101.783134 -375.513854)
		(width 0.14224)
		(layer "In6.Cu")
		(net "P5E_CPU1_P0_TX_DN<13>")
	)
	(arc
		(start 126.239016 -353.18827)
		(mid 125.395517 -354.595729)
		(end 124.179838 -355.69779)
		(width 0.14224)
		(layer "In6.Cu")
		(net "P5E_CPU1_P0_TX_DN<13>")
	)
	(arc
		(start 109.356398 -287.046162)
		(mid 109.397653 -287.217133)
		(end 109.512354 -287.350454)
		(width 0.1143)
		(layer "In6.Cu")
		(net "P5E_CPU1_P0_TX_DN<13>")
	)
	(arc
		(start 109.610906 -292.27145)
		(mid 109.838906 -292.716204)
		(end 109.610906 -293.160958)
		(width 0.1143)
		(layer "In6.Cu")
		(net "P5E_CPU1_P0_TX_DN<13>")
	)
	(arc
		(start 77.460856 -375.513854)
		(mid 76.856165 -375.393573)
		(end 76.34351 -375.051066)
		(width 0.14224)
		(layer "In6.Cu")
		(net "P5E_CPU1_P0_TX_DN<13>")
	)
	(arc
		(start 109.56544 -293.861236)
		(mid 109.838991 -294.336216)
		(end 109.56544 -294.811196)
		(width 0.1143)
		(layer "In6.Cu")
		(net "P5E_CPU1_P0_TX_DN<13>")
	)
	(arc
		(start 70.342506 -370.251228)
		(mid 70.168154 -370.275155)
		(end 70.006718 -370.345208)
		(width 0.14224)
		(layer "In6.Cu")
		(net "P5E_CPU1_P0_TX_DN<13>")
	)
	(arc
		(start 109.710982 -287.48355)
		(mid 109.795813 -287.582568)
		(end 109.826298 -287.709356)
		(width 0.1143)
		(layer "In6.Cu")
		(net "P5E_CPU1_P0_TX_DN<13>")
	)
	(arc
		(start 109.849158 -366.284764)
		(mid 109.79962 -366.324389)
		(end 109.753146 -366.367568)
		(width 0.14224)
		(layer "In6.Cu")
		(net "P5E_CPU1_P0_TX_DN<13>")
	)
	(arc
		(start 109.512354 -291.601906)
		(mid 109.356426 -291.906198)
		(end 109.512354 -292.21049)
		(width 0.1143)
		(layer "In6.Cu")
		(net "P5E_CPU1_P0_TX_DN<13>")
	)
	(arc
		(start 103.726234 -374.708928)
		(mid 103.724203 -374.710834)
		(end 103.72217 -374.712738)
		(width 0.14224)
		(layer "In6.Cu")
		(net "P5E_CPU1_P0_TX_DN<13>")
	)
	(arc
		(start 123.67006 -356.038658)
		(mid 123.615491 -356.075966)
		(end 123.561856 -356.114604)
		(width 0.14224)
		(layer "In6.Cu")
		(net "P5E_CPU1_P0_TX_DN<13>")
	)
	(arc
		(start 68.96227 -370.246656)
		(mid 68.866571 -370.103433)
		(end 68.832984 -369.93449)
		(width 0.14224)
		(layer "In6.Cu")
		(net "P5E_CPU1_P0_TX_DN<13>")
	)
	(arc
		(start 109.356398 -288.666174)
		(mid 109.397653 -288.837145)
		(end 109.512354 -288.970466)
		(width 0.1143)
		(layer "In6.Cu")
		(net "P5E_CPU1_P0_TX_DN<13>")
	)
	(arc
		(start 129.823718 -341.87003)
		(mid 129.835373 -341.957697)
		(end 129.839212 -342.046052)
		(width 0.14224)
		(layer "In6.Cu")
		(net "P5E_CPU1_P0_TX_DN<13>")
	)
	(arc
		(start 109.595666 -290.640516)
		(mid 109.820837 -291.096192)
		(end 109.595666 -291.551868)
		(width 0.1143)
		(layer "In6.Cu")
		(net "P5E_CPU1_P0_TX_DN<13>")
	)
	(arc
		(start 109.512354 -289.981894)
		(mid 109.356426 -290.286186)
		(end 109.512354 -290.590478)
		(width 0.1143)
		(layer "In6.Cu")
		(net "P5E_CPU1_P0_TX_DN<13>")
	)
	(arc
		(start 122.64136 -318.694562)
		(mid 122.696245 -318.768774)
		(end 122.743214 -318.848232)
		(width 0.14224)
		(layer "In6.Cu")
		(net "P5E_CPU1_P0_TX_DN<13>")
	)
	(arc
		(start 109.363256 -285.496254)
		(mid 109.415305 -285.627773)
		(end 109.512354 -285.730696)
		(width 0.1143)
		(layer "In6.Cu")
		(net "P5E_CPU1_P0_TX_DN<13>")
	)
	(arc
		(start 109.826298 -287.856422)
		(mid 109.762622 -288.117226)
		(end 109.58576 -288.31921)
		(width 0.1143)
		(layer "In6.Cu")
		(net "P5E_CPU1_P0_TX_DN<13>")
	)
	(arc
		(start 109.510576 -286.743394)
		(mid 109.397169 -286.876283)
		(end 109.356398 -287.046162)
		(width 0.1143)
		(layer "In6.Cu")
		(net "P5E_CPU1_P0_TX_DN<13>")
	)
	(arc
		(start 127.261874 -327.634092)
		(mid 127.276458 -327.695569)
		(end 127.288798 -327.757536)
		(width 0.14224)
		(layer "In6.Cu")
		(net "P5E_CPU1_P0_TX_DN<13>")
	)
	(arc
		(start 104.844596 -372.95328)
		(mid 104.365003 -373.8818)
		(end 103.726234 -374.708928)
		(width 0.14224)
		(layer "In6.Cu")
		(net "P5E_CPU1_P0_TX_DN<13>")
	)
	(arc
		(start 129.839212 -343.384378)
		(mid 129.731819 -344.474797)
		(end 129.413762 -345.523312)
		(width 0.14224)
		(layer "In6.Cu")
		(net "P5E_CPU1_P0_TX_DN<13>")
	)
	(arc
		(start 109.595666 -291.551868)
		(mid 109.58809 -291.557264)
		(end 109.580426 -291.562536)
		(width 0.1143)
		(layer "In6.Cu")
		(net "P5E_CPU1_P0_TX_DN<13>")
	)
	(segment
		(start 65.731644 -370.00942)
		(end 65.731644 -369.30584)
		(width 0.12954)
		(layer "F.Cu")
		(net "P5E_CPU1_P0_TX_DN<12>")
	)
	(segment
		(start 107.847892 -282.730448)
		(end 107.38104 -282.996386)
		(width 0.12954)
		(layer "F.Cu")
		(net "P5E_CPU1_P0_TX_DN<12>")
	)
	(segment
		(start 66.027554 -370.30533)
		(end 65.731644 -370.00942)
		(width 0.12954)
		(layer "F.Cu")
		(net "P5E_CPU1_P0_TX_DN<12>")
	)
	(segment
		(start 65.731644 -369.30584)
		(end 66.002154 -369.03533)
		(width 0.12954)
		(layer "F.Cu")
		(net "P5E_CPU1_P0_TX_DN<12>")
	)
	(segment
		(start 87.174832 -370.491258)
		(end 86.858856 -370.360448)
		(width 0.14224)
		(layer "In6.Cu")
		(net "P5E_CPU1_P0_TX_DN<12>")
	)
	(segment
		(start 93.922088 -370.459762)
		(end 93.682312 -370.360448)
		(width 0.14224)
		(layer "In6.Cu")
		(net "P5E_CPU1_P0_TX_DN<12>")
	)
	(segment
		(start 107.162346 -283.300678)
		(end 107.23118 -283.340556)
		(width 0.1143)
		(layer "In6.Cu")
		(net "P5E_CPU1_P0_TX_DN<12>")
	)
	(segment
		(start 76.60132 -370.351304)
		(end 75.700636 -370.351304)
		(width 0.14224)
		(layer "In6.Cu")
		(net "P5E_CPU1_P0_TX_DN<12>")
	)
	(segment
		(start 108.587286 -293.213536)
		(end 108.5723 -293.221918)
		(width 0.1143)
		(layer "In6.Cu")
		(net "P5E_CPU1_P0_TX_DN<12>")
	)
	(segment
		(start 93.682312 -370.360448)
		(end 92.324428 -370.360448)
		(width 0.14224)
		(layer "In6.Cu")
		(net "P5E_CPU1_P0_TX_DN<12>")
	)
	(segment
		(start 108.597954 -294.827198)
		(end 108.596938 -294.827706)
		(width 0.1143)
		(layer "In6.Cu")
		(net "P5E_CPU1_P0_TX_DN<12>")
	)
	(segment
		(start 108.5723 -292.21049)
		(end 108.603288 -292.22827)
		(width 0.1143)
		(layer "In6.Cu")
		(net "P5E_CPU1_P0_TX_DN<12>")
	)
	(segment
		(start 75.700636 -370.351304)
		(end 70.083426 -368.024664)
		(width 0.14224)
		(layer "In6.Cu")
		(net "P5E_CPU1_P0_TX_DN<12>")
	)
	(segment
		(start 97.081594 -370.36375)
		(end 95.684848 -370.36375)
		(width 0.14224)
		(layer "In6.Cu")
		(net "P5E_CPU1_P0_TX_DN<12>")
	)
	(segment
		(start 108.603288 -291.584126)
		(end 108.602018 -291.584888)
		(width 0.1143)
		(layer "In6.Cu")
		(net "P5E_CPU1_P0_TX_DN<12>")
	)
	(segment
		(start 81.82102 -370.472716)
		(end 80.353154 -370.472716)
		(width 0.14224)
		(layer "In6.Cu")
		(net "P5E_CPU1_P0_TX_DN<12>")
	)
	(segment
		(start 113.373154 -308.309772)
		(end 115.472972 -311.45226)
		(width 0.14224)
		(layer "In6.Cu")
		(net "P5E_CPU1_P0_TX_DN<12>")
	)
	(segment
		(start 103.07447 -370.376704)
		(end 102.527354 -370.376704)
		(width 0.14224)
		(layer "In6.Cu")
		(net "P5E_CPU1_P0_TX_DN<12>")
	)
	(segment
		(start 108.60659 -292.230302)
		(end 108.607606 -292.23081)
		(width 0.1143)
		(layer "In6.Cu")
		(net "P5E_CPU1_P0_TX_DN<12>")
	)
	(segment
		(start 108.603288 -285.748476)
		(end 108.60405 -285.748984)
		(width 0.1143)
		(layer "In6.Cu")
		(net "P5E_CPU1_P0_TX_DN<12>")
	)
	(segment
		(start 80.353154 -370.472716)
		(end 80.071214 -370.35613)
		(width 0.14224)
		(layer "In6.Cu")
		(net "P5E_CPU1_P0_TX_DN<12>")
	)
	(segment
		(start 108.59516 -293.208964)
		(end 108.59262 -293.210488)
		(width 0.1143)
		(layer "In6.Cu")
		(net "P5E_CPU1_P0_TX_DN<12>")
	)
	(segment
		(start 108.605066 -292.229286)
		(end 108.60659 -292.230302)
		(width 0.1143)
		(layer "In6.Cu")
		(net "P5E_CPU1_P0_TX_DN<12>")
	)
	(segment
		(start 108.60405 -293.20363)
		(end 108.603288 -293.204138)
		(width 0.1143)
		(layer "In6.Cu")
		(net "P5E_CPU1_P0_TX_DN<12>")
	)
	(segment
		(start 108.598462 -291.58692)
		(end 108.59516 -291.588952)
		(width 0.1143)
		(layer "In6.Cu")
		(net "P5E_CPU1_P0_TX_DN<12>")
	)
	(segment
		(start 78.746096 -370.35613)
		(end 78.362048 -370.515134)
		(width 0.14224)
		(layer "In6.Cu")
		(net "P5E_CPU1_P0_TX_DN<12>")
	)
	(segment
		(start 108.5723 -285.730696)
		(end 108.603288 -285.748476)
		(width 0.1143)
		(layer "In6.Cu")
		(net "P5E_CPU1_P0_TX_DN<12>")
	)
	(segment
		(start 108.5723 -287.350454)
		(end 108.60405 -287.368742)
		(width 0.1143)
		(layer "In6.Cu")
		(net "P5E_CPU1_P0_TX_DN<12>")
	)
	(segment
		(start 88.577674 -370.491258)
		(end 87.174832 -370.491258)
		(width 0.14224)
		(layer "In6.Cu")
		(net "P5E_CPU1_P0_TX_DN<12>")
	)
	(segment
		(start 108.603288 -288.988246)
		(end 108.60405 -288.988754)
		(width 0.1143)
		(layer "In6.Cu")
		(net "P5E_CPU1_P0_TX_DN<12>")
	)
	(segment
		(start 108.603288 -293.204138)
		(end 108.602018 -293.2049)
		(width 0.1143)
		(layer "In6.Cu")
		(net "P5E_CPU1_P0_TX_DN<12>")
	)
	(segment
		(start 108.60659 -288.990278)
		(end 108.607606 -288.990786)
		(width 0.1143)
		(layer "In6.Cu")
		(net "P5E_CPU1_P0_TX_DN<12>")
	)
	(segment
		(start 108.5723 -290.590478)
		(end 108.603288 -290.608258)
		(width 0.1143)
		(layer "In6.Cu")
		(net "P5E_CPU1_P0_TX_DN<12>")
	)
	(segment
		(start 108.589318 -291.592254)
		(end 108.587286 -291.593524)
		(width 0.1143)
		(layer "In6.Cu")
		(net "P5E_CPU1_P0_TX_DN<12>")
	)
	(segment
		(start 95.452946 -370.459762)
		(end 93.922088 -370.459762)
		(width 0.14224)
		(layer "In6.Cu")
		(net "P5E_CPU1_P0_TX_DN<12>")
	)
	(segment
		(start 98.793808 -370.4717)
		(end 97.342452 -370.4717)
		(width 0.14224)
		(layer "In6.Cu")
		(net "P5E_CPU1_P0_TX_DN<12>")
	)
	(segment
		(start 66.13525 -367.875566)
		(end 65.88633 -367.978436)
		(width 0.14224)
		(layer "In6.Cu")
		(net "P5E_CPU1_P0_TX_DN<12>")
	)
	(segment
		(start 65.711324 -368.7445)
		(end 66.002154 -369.03533)
		(width 0.14224)
		(layer "In6.Cu")
		(net "P5E_CPU1_P0_TX_DN<12>")
	)
	(segment
		(start 86.858856 -370.360448)
		(end 85.454744 -370.360448)
		(width 0.14224)
		(layer "In6.Cu")
		(net "P5E_CPU1_P0_TX_DN<12>")
	)
	(segment
		(start 108.603288 -293.848282)
		(end 108.60405 -293.84879)
		(width 0.1143)
		(layer "In6.Cu")
		(net "P5E_CPU1_P0_TX_DN<12>")
	)
	(segment
		(start 108.60405 -293.84879)
		(end 108.605066 -293.849298)
		(width 0.1143)
		(layer "In6.Cu")
		(net "P5E_CPU1_P0_TX_DN<12>")
	)
	(segment
		(start 108.602018 -291.584888)
		(end 108.600494 -291.58565)
		(width 0.1143)
		(layer "In6.Cu")
		(net "P5E_CPU1_P0_TX_DN<12>")
	)
	(segment
		(start 108.60405 -288.988754)
		(end 108.605066 -288.989262)
		(width 0.1143)
		(layer "In6.Cu")
		(net "P5E_CPU1_P0_TX_DN<12>")
	)
	(segment
		(start 108.607606 -288.990786)
		(end 108.643166 -289.011614)
		(width 0.1143)
		(layer "In6.Cu")
		(net "P5E_CPU1_P0_TX_DN<12>")
	)
	(segment
		(start 108.607606 -290.610798)
		(end 108.643166 -290.631626)
		(width 0.1143)
		(layer "In6.Cu")
		(net "P5E_CPU1_P0_TX_DN<12>")
	)
	(segment
		(start 107.083098 -282.996386)
		(end 107.013248 -283.066236)
		(width 0.1143)
		(layer "In6.Cu")
		(net "P5E_CPU1_P0_TX_DN<12>")
	)
	(segment
		(start 108.103416 -284.921198)
		(end 108.173012 -284.961838)
		(width 0.1143)
		(layer "In6.Cu")
		(net "P5E_CPU1_P0_TX_DN<12>")
	)
	(segment
		(start 108.603288 -292.22827)
		(end 108.60405 -292.228778)
		(width 0.1143)
		(layer "In6.Cu")
		(net "P5E_CPU1_P0_TX_DN<12>")
	)
	(segment
		(start 108.605066 -293.849298)
		(end 108.60659 -293.850314)
		(width 0.1143)
		(layer "In6.Cu")
		(net "P5E_CPU1_P0_TX_DN<12>")
	)
	(segment
		(start 100.540058 -370.381022)
		(end 99.012756 -370.381022)
		(width 0.14224)
		(layer "In6.Cu")
		(net "P5E_CPU1_P0_TX_DN<12>")
	)
	(segment
		(start 107.38104 -282.996386)
		(end 107.083098 -282.996386)
		(width 0.1143)
		(layer "In6.Cu")
		(net "P5E_CPU1_P0_TX_DN<12>")
	)
	(segment
		(start 108.60405 -287.368742)
		(end 108.640626 -287.390078)
		(width 0.1143)
		(layer "In6.Cu")
		(net "P5E_CPU1_P0_TX_DN<12>")
	)
	(segment
		(start 108.607606 -292.23081)
		(end 108.643166 -292.251638)
		(width 0.1143)
		(layer "In6.Cu")
		(net "P5E_CPU1_P0_TX_DN<12>")
	)
	(segment
		(start 108.41609 -295.4909)
		(end 108.46181 -295.53662)
		(width 0.1143)
		(layer "In6.Cu")
		(net "P5E_CPU1_P0_TX_DN<12>")
	)
	(segment
		(start 108.600494 -294.825674)
		(end 108.597954 -294.827198)
		(width 0.1143)
		(layer "In6.Cu")
		(net "P5E_CPU1_P0_TX_DN<12>")
	)
	(segment
		(start 108.599224 -289.9664)
		(end 108.598462 -289.966908)
		(width 0.1143)
		(layer "In6.Cu")
		(net "P5E_CPU1_P0_TX_DN<12>")
	)
	(segment
		(start 108.600494 -291.58565)
		(end 108.599224 -291.586412)
		(width 0.1143)
		(layer "In6.Cu")
		(net "P5E_CPU1_P0_TX_DN<12>")
	)
	(segment
		(start 108.643166 -293.18077)
		(end 108.605066 -293.203122)
		(width 0.1143)
		(layer "In6.Cu")
		(net "P5E_CPU1_P0_TX_DN<12>")
	)
	(segment
		(start 108.60405 -290.608766)
		(end 108.605066 -290.609274)
		(width 0.1143)
		(layer "In6.Cu")
		(net "P5E_CPU1_P0_TX_DN<12>")
	)
	(segment
		(start 108.643166 -288.320988)
		(end 108.570522 -288.363406)
		(width 0.1143)
		(layer "In6.Cu")
		(net "P5E_CPU1_P0_TX_DN<12>")
	)
	(segment
		(start 108.600494 -293.205662)
		(end 108.599224 -293.206424)
		(width 0.1143)
		(layer "In6.Cu")
		(net "P5E_CPU1_P0_TX_DN<12>")
	)
	(segment
		(start 108.599224 -293.206424)
		(end 108.598462 -293.206932)
		(width 0.1143)
		(layer "In6.Cu")
		(net "P5E_CPU1_P0_TX_DN<12>")
	)
	(segment
		(start 78.362048 -370.515134)
		(end 76.997052 -370.515134)
		(width 0.14224)
		(layer "In6.Cu")
		(net "P5E_CPU1_P0_TX_DN<12>")
	)
	(segment
		(start 108.60405 -291.583618)
		(end 108.603288 -291.584126)
		(width 0.1143)
		(layer "In6.Cu")
		(net "P5E_CPU1_P0_TX_DN<12>")
	)
	(segment
		(start 108.603288 -290.608258)
		(end 108.60405 -290.608766)
		(width 0.1143)
		(layer "In6.Cu")
		(net "P5E_CPU1_P0_TX_DN<12>")
	)
	(segment
		(start 85.454744 -370.360448)
		(end 85.194648 -370.468144)
		(width 0.14224)
		(layer "In6.Cu")
		(net "P5E_CPU1_P0_TX_DN<12>")
	)
	(segment
		(start 108.46181 -295.53662)
		(end 108.46181 -295.565068)
		(width 0.1143)
		(layer "In6.Cu")
		(net "P5E_CPU1_P0_TX_DN<12>")
	)
	(segment
		(start 124.576332 -354.05568)
		(end 124.291852 -354.386388)
		(width 0.14224)
		(layer "In6.Cu")
		(net "P5E_CPU1_P0_TX_DN<12>")
	)
	(segment
		(start 108.603288 -289.964114)
		(end 108.602018 -289.964876)
		(width 0.1143)
		(layer "In6.Cu")
		(net "P5E_CPU1_P0_TX_DN<12>")
	)
	(segment
		(start 108.5723 -288.970466)
		(end 108.603288 -288.988246)
		(width 0.1143)
		(layer "In6.Cu")
		(net "P5E_CPU1_P0_TX_DN<12>")
	)
	(segment
		(start 108.59262 -293.210488)
		(end 108.589318 -293.212266)
		(width 0.1143)
		(layer "In6.Cu")
		(net "P5E_CPU1_P0_TX_DN<12>")
	)
	(segment
		(start 88.883236 -370.364766)
		(end 88.577674 -370.491258)
		(width 0.14224)
		(layer "In6.Cu")
		(net "P5E_CPU1_P0_TX_DN<12>")
	)
	(segment
		(start 90.649806 -370.520722)
		(end 90.273124 -370.364766)
		(width 0.14224)
		(layer "In6.Cu")
		(net "P5E_CPU1_P0_TX_DN<12>")
	)
	(segment
		(start 108.605066 -285.749492)
		(end 108.60659 -285.750508)
		(width 0.1143)
		(layer "In6.Cu")
		(net "P5E_CPU1_P0_TX_DN<12>")
	)
	(segment
		(start 108.602018 -289.964876)
		(end 108.600494 -289.965638)
		(width 0.1143)
		(layer "In6.Cu")
		(net "P5E_CPU1_P0_TX_DN<12>")
	)
	(segment
		(start 111.273082 -305.16703)
		(end 113.373154 -308.309772)
		(width 0.14224)
		(layer "In6.Cu")
		(net "P5E_CPU1_P0_TX_DN<12>")
	)
	(segment
		(start 109.576362 -364.31601)
		(end 103.930958 -369.961414)
		(width 0.14224)
		(layer "In6.Cu")
		(net "P5E_CPU1_P0_TX_DN<12>")
	)
	(segment
		(start 108.643166 -289.940746)
		(end 108.605066 -289.963098)
		(width 0.1143)
		(layer "In6.Cu")
		(net "P5E_CPU1_P0_TX_DN<12>")
	)
	(segment
		(start 108.605066 -294.823134)
		(end 108.60405 -294.823642)
		(width 0.1143)
		(layer "In6.Cu")
		(net "P5E_CPU1_P0_TX_DN<12>")
	)
	(segment
		(start 108.587286 -289.973512)
		(end 108.5723 -289.981894)
		(width 0.1143)
		(layer "In6.Cu")
		(net "P5E_CPU1_P0_TX_DN<12>")
	)
	(segment
		(start 127.922782 -346.028264)
		(end 124.64415 -353.945444)
		(width 0.14224)
		(layer "In6.Cu")
		(net "P5E_CPU1_P0_TX_DN<12>")
	)
	(segment
		(start 108.59262 -289.970464)
		(end 108.589318 -289.972242)
		(width 0.1143)
		(layer "In6.Cu")
		(net "P5E_CPU1_P0_TX_DN<12>")
	)
	(segment
		(start 108.59516 -289.96894)
		(end 108.59262 -289.970464)
		(width 0.1143)
		(layer "In6.Cu")
		(net "P5E_CPU1_P0_TX_DN<12>")
	)
	(segment
		(start 108.643166 -294.800782)
		(end 108.605066 -294.823134)
		(width 0.1143)
		(layer "In6.Cu")
		(net "P5E_CPU1_P0_TX_DN<12>")
	)
	(segment
		(start 65.711324 -368.247422)
		(end 65.711324 -368.7445)
		(width 0.14224)
		(layer "In6.Cu")
		(net "P5E_CPU1_P0_TX_DN<12>")
	)
	(segment
		(start 108.598462 -293.206932)
		(end 108.59516 -293.208964)
		(width 0.1143)
		(layer "In6.Cu")
		(net "P5E_CPU1_P0_TX_DN<12>")
	)
	(segment
		(start 90.273124 -370.364766)
		(end 88.883236 -370.364766)
		(width 0.14224)
		(layer "In6.Cu")
		(net "P5E_CPU1_P0_TX_DN<12>")
	)
	(segment
		(start 108.60659 -293.850314)
		(end 108.607606 -293.850822)
		(width 0.1143)
		(layer "In6.Cu")
		(net "P5E_CPU1_P0_TX_DN<12>")
	)
	(segment
		(start 97.342452 -370.4717)
		(end 97.081594 -370.36375)
		(width 0.14224)
		(layer "In6.Cu")
		(net "P5E_CPU1_P0_TX_DN<12>")
	)
	(segment
		(start 126.297436 -327.691242)
		(end 126.319788 -327.757028)
		(width 0.14224)
		(layer "In6.Cu")
		(net "P5E_CPU1_P0_TX_DN<12>")
	)
	(segment
		(start 108.5723 -293.830502)
		(end 108.603288 -293.848282)
		(width 0.1143)
		(layer "In6.Cu")
		(net "P5E_CPU1_P0_TX_DN<12>")
	)
	(segment
		(start 83.70951 -370.468144)
		(end 83.428586 -370.351812)
		(width 0.14224)
		(layer "In6.Cu")
		(net "P5E_CPU1_P0_TX_DN<12>")
	)
	(segment
		(start 65.88633 -367.978436)
		(end 65.777872 -368.086894)
		(width 0.14224)
		(layer "In6.Cu")
		(net "P5E_CPU1_P0_TX_DN<12>")
	)
	(segment
		(start 85.194648 -370.468144)
		(end 83.70951 -370.468144)
		(width 0.14224)
		(layer "In6.Cu")
		(net "P5E_CPU1_P0_TX_DN<12>")
	)
	(segment
		(start 108.598462 -289.966908)
		(end 108.59516 -289.96894)
		(width 0.1143)
		(layer "In6.Cu")
		(net "P5E_CPU1_P0_TX_DN<12>")
	)
	(segment
		(start 108.59262 -291.590476)
		(end 108.589318 -291.592254)
		(width 0.1143)
		(layer "In6.Cu")
		(net "P5E_CPU1_P0_TX_DN<12>")
	)
	(segment
		(start 102.286308 -370.45011)
		(end 100.70719 -370.45011)
		(width 0.14224)
		(layer "In6.Cu")
		(net "P5E_CPU1_P0_TX_DN<12>")
	)
	(segment
		(start 115.472972 -311.45226)
		(end 121.887234 -319.268094)
		(width 0.14224)
		(layer "In6.Cu")
		(net "P5E_CPU1_P0_TX_DN<12>")
	)
	(segment
		(start 108.587286 -291.593524)
		(end 108.5723 -291.601906)
		(width 0.1143)
		(layer "In6.Cu")
		(net "P5E_CPU1_P0_TX_DN<12>")
	)
	(segment
		(start 108.59516 -291.588952)
		(end 108.59262 -291.590476)
		(width 0.1143)
		(layer "In6.Cu")
		(net "P5E_CPU1_P0_TX_DN<12>")
	)
	(segment
		(start 108.46181 -295.565068)
		(end 108.46181 -298.419012)
		(width 0.14224)
		(layer "In6.Cu")
		(net "P5E_CPU1_P0_TX_DN<12>")
	)
	(segment
		(start 108.605066 -288.989262)
		(end 108.60659 -288.990278)
		(width 0.1143)
		(layer "In6.Cu")
		(net "P5E_CPU1_P0_TX_DN<12>")
	)
	(segment
		(start 108.607606 -285.751016)
		(end 108.643166 -285.771844)
		(width 0.1143)
		(layer "In6.Cu")
		(net "P5E_CPU1_P0_TX_DN<12>")
	)
	(segment
		(start 108.602018 -293.2049)
		(end 108.600494 -293.205662)
		(width 0.1143)
		(layer "In6.Cu")
		(net "P5E_CPU1_P0_TX_DN<12>")
	)
	(segment
		(start 108.643166 -286.700976)
		(end 108.570522 -286.743394)
		(width 0.1143)
		(layer "In6.Cu")
		(net "P5E_CPU1_P0_TX_DN<12>")
	)
	(segment
		(start 108.60405 -294.823642)
		(end 108.603288 -294.82415)
		(width 0.1143)
		(layer "In6.Cu")
		(net "P5E_CPU1_P0_TX_DN<12>")
	)
	(segment
		(start 108.607606 -293.850822)
		(end 108.643166 -293.87165)
		(width 0.1143)
		(layer "In6.Cu")
		(net "P5E_CPU1_P0_TX_DN<12>")
	)
	(segment
		(start 110.908084 -304.484786)
		(end 111.273082 -305.16703)
		(width 0.14224)
		(layer "In6.Cu")
		(net "P5E_CPU1_P0_TX_DN<12>")
	)
	(segment
		(start 108.600494 -289.965638)
		(end 108.599224 -289.9664)
		(width 0.1143)
		(layer "In6.Cu")
		(net "P5E_CPU1_P0_TX_DN<12>")
	)
	(segment
		(start 108.605066 -291.58311)
		(end 108.60405 -291.583618)
		(width 0.1143)
		(layer "In6.Cu")
		(net "P5E_CPU1_P0_TX_DN<12>")
	)
	(segment
		(start 108.589318 -289.972242)
		(end 108.587286 -289.973512)
		(width 0.1143)
		(layer "In6.Cu")
		(net "P5E_CPU1_P0_TX_DN<12>")
	)
	(segment
		(start 69.333872 -367.875566)
		(end 66.13525 -367.875566)
		(width 0.14224)
		(layer "In6.Cu")
		(net "P5E_CPU1_P0_TX_DN<12>")
	)
	(segment
		(start 108.60659 -290.61029)
		(end 108.607606 -290.610798)
		(width 0.1143)
		(layer "In6.Cu")
		(net "P5E_CPU1_P0_TX_DN<12>")
	)
	(segment
		(start 108.605066 -289.963098)
		(end 108.60405 -289.963606)
		(width 0.1143)
		(layer "In6.Cu")
		(net "P5E_CPU1_P0_TX_DN<12>")
	)
	(segment
		(start 107.632246 -284.110684)
		(end 107.703112 -284.151832)
		(width 0.1143)
		(layer "In6.Cu")
		(net "P5E_CPU1_P0_TX_DN<12>")
	)
	(segment
		(start 123.845066 -354.781612)
		(end 109.576362 -364.31601)
		(width 0.14224)
		(layer "In6.Cu")
		(net "P5E_CPU1_P0_TX_DN<12>")
	)
	(segment
		(start 108.52277 -298.724828)
		(end 110.908084 -304.484786)
		(width 0.14224)
		(layer "In6.Cu")
		(net "P5E_CPU1_P0_TX_DN<12>")
	)
	(segment
		(start 95.684848 -370.36375)
		(end 95.452946 -370.459762)
		(width 0.14224)
		(layer "In6.Cu")
		(net "P5E_CPU1_P0_TX_DN<12>")
	)
	(segment
		(start 100.70719 -370.45011)
		(end 100.540058 -370.381022)
		(width 0.14224)
		(layer "In6.Cu")
		(net "P5E_CPU1_P0_TX_DN<12>")
	)
	(segment
		(start 126.356618 -327.89495)
		(end 128.78816 -341.427562)
		(width 0.14224)
		(layer "In6.Cu")
		(net "P5E_CPU1_P0_TX_DN<12>")
	)
	(segment
		(start 108.599224 -291.586412)
		(end 108.598462 -291.58692)
		(width 0.1143)
		(layer "In6.Cu")
		(net "P5E_CPU1_P0_TX_DN<12>")
	)
	(segment
		(start 108.589318 -293.212266)
		(end 108.587286 -293.213536)
		(width 0.1143)
		(layer "In6.Cu")
		(net "P5E_CPU1_P0_TX_DN<12>")
	)
	(segment
		(start 91.937332 -370.520722)
		(end 90.649806 -370.520722)
		(width 0.14224)
		(layer "In6.Cu")
		(net "P5E_CPU1_P0_TX_DN<12>")
	)
	(segment
		(start 108.596938 -294.827706)
		(end 108.5723 -294.84193)
		(width 0.1143)
		(layer "In6.Cu")
		(net "P5E_CPU1_P0_TX_DN<12>")
	)
	(segment
		(start 108.605066 -290.609274)
		(end 108.60659 -290.61029)
		(width 0.1143)
		(layer "In6.Cu")
		(net "P5E_CPU1_P0_TX_DN<12>")
	)
	(segment
		(start 108.643166 -291.560758)
		(end 108.605066 -291.58311)
		(width 0.1143)
		(layer "In6.Cu")
		(net "P5E_CPU1_P0_TX_DN<12>")
	)
	(segment
		(start 108.602018 -294.824912)
		(end 108.600494 -294.825674)
		(width 0.1143)
		(layer "In6.Cu")
		(net "P5E_CPU1_P0_TX_DN<12>")
	)
	(segment
		(start 80.071214 -370.35613)
		(end 78.746096 -370.35613)
		(width 0.14224)
		(layer "In6.Cu")
		(net "P5E_CPU1_P0_TX_DN<12>")
	)
	(segment
		(start 108.60405 -285.748984)
		(end 108.605066 -285.749492)
		(width 0.1143)
		(layer "In6.Cu")
		(net "P5E_CPU1_P0_TX_DN<12>")
	)
	(segment
		(start 108.41609 -295.14673)
		(end 108.41609 -295.4909)
		(width 0.1143)
		(layer "In6.Cu")
		(net "P5E_CPU1_P0_TX_DN<12>")
	)
	(segment
		(start 102.404164 -370.401342)
		(end 102.286308 -370.45011)
		(width 0.14224)
		(layer "In6.Cu")
		(net "P5E_CPU1_P0_TX_DN<12>")
	)
	(segment
		(start 92.324428 -370.360448)
		(end 91.937332 -370.520722)
		(width 0.14224)
		(layer "In6.Cu")
		(net "P5E_CPU1_P0_TX_DN<12>")
	)
	(segment
		(start 121.969022 -319.391792)
		(end 126.255272 -327.593706)
		(width 0.14224)
		(layer "In6.Cu")
		(net "P5E_CPU1_P0_TX_DN<12>")
	)
	(segment
		(start 108.60405 -289.963606)
		(end 108.603288 -289.964114)
		(width 0.1143)
		(layer "In6.Cu")
		(net "P5E_CPU1_P0_TX_DN<12>")
	)
	(segment
		(start 99.012756 -370.381022)
		(end 98.793808 -370.4717)
		(width 0.14224)
		(layer "In6.Cu")
		(net "P5E_CPU1_P0_TX_DN<12>")
	)
	(segment
		(start 108.603288 -294.82415)
		(end 108.602018 -294.824912)
		(width 0.1143)
		(layer "In6.Cu")
		(net "P5E_CPU1_P0_TX_DN<12>")
	)
	(segment
		(start 82.11312 -370.351812)
		(end 81.82102 -370.472716)
		(width 0.14224)
		(layer "In6.Cu")
		(net "P5E_CPU1_P0_TX_DN<12>")
	)
	(segment
		(start 108.605066 -293.203122)
		(end 108.60405 -293.20363)
		(width 0.1143)
		(layer "In6.Cu")
		(net "P5E_CPU1_P0_TX_DN<12>")
	)
	(segment
		(start 76.997052 -370.515134)
		(end 76.60132 -370.351304)
		(width 0.14224)
		(layer "In6.Cu")
		(net "P5E_CPU1_P0_TX_DN<12>")
	)
	(segment
		(start 83.428586 -370.351812)
		(end 82.11312 -370.351812)
		(width 0.14224)
		(layer "In6.Cu")
		(net "P5E_CPU1_P0_TX_DN<12>")
	)
	(segment
		(start 108.60659 -285.750508)
		(end 108.607606 -285.751016)
		(width 0.1143)
		(layer "In6.Cu")
		(net "P5E_CPU1_P0_TX_DN<12>")
	)
	(segment
		(start 108.60405 -292.228778)
		(end 108.605066 -292.229286)
		(width 0.1143)
		(layer "In6.Cu")
		(net "P5E_CPU1_P0_TX_DN<12>")
	)
	(arc
		(start 108.5723 -291.601906)
		(mid 108.416372 -291.906198)
		(end 108.5723 -292.21049)
		(width 0.1143)
		(layer "In6.Cu")
		(net "P5E_CPU1_P0_TX_DN<12>")
	)
	(arc
		(start 108.643166 -285.771844)
		(mid 108.886493 -286.23641)
		(end 108.643166 -286.700976)
		(width 0.1143)
		(layer "In6.Cu")
		(net "P5E_CPU1_P0_TX_DN<12>")
	)
	(arc
		(start 108.570522 -288.363406)
		(mid 108.457115 -288.496295)
		(end 108.416344 -288.666174)
		(width 0.1143)
		(layer "In6.Cu")
		(net "P5E_CPU1_P0_TX_DN<12>")
	)
	(arc
		(start 103.27894 -370.347748)
		(mid 103.177735 -370.3695)
		(end 103.07447 -370.376704)
		(width 0.14224)
		(layer "In6.Cu")
		(net "P5E_CPU1_P0_TX_DN<12>")
	)
	(arc
		(start 108.416344 -287.046162)
		(mid 108.457599 -287.217133)
		(end 108.5723 -287.350454)
		(width 0.1143)
		(layer "In6.Cu")
		(net "P5E_CPU1_P0_TX_DN<12>")
	)
	(arc
		(start 108.640626 -287.390078)
		(mid 108.821278 -287.592823)
		(end 108.886498 -287.856422)
		(width 0.1143)
		(layer "In6.Cu")
		(net "P5E_CPU1_P0_TX_DN<12>")
	)
	(arc
		(start 108.643166 -293.87165)
		(mid 108.886493 -294.336216)
		(end 108.643166 -294.800782)
		(width 0.1143)
		(layer "In6.Cu")
		(net "P5E_CPU1_P0_TX_DN<12>")
	)
	(arc
		(start 108.5723 -293.221918)
		(mid 108.416372 -293.52621)
		(end 108.5723 -293.830502)
		(width 0.1143)
		(layer "In6.Cu")
		(net "P5E_CPU1_P0_TX_DN<12>")
	)
	(arc
		(start 126.319788 -327.757028)
		(mid 126.340583 -327.825353)
		(end 126.356618 -327.89495)
		(width 0.14224)
		(layer "In6.Cu")
		(net "P5E_CPU1_P0_TX_DN<12>")
	)
	(arc
		(start 108.5723 -294.84193)
		(mid 108.457399 -294.975476)
		(end 108.41609 -295.14673)
		(width 0.1143)
		(layer "In6.Cu")
		(net "P5E_CPU1_P0_TX_DN<12>")
	)
	(arc
		(start 108.643166 -292.251638)
		(mid 108.886493 -292.716204)
		(end 108.643166 -293.18077)
		(width 0.1143)
		(layer "In6.Cu")
		(net "P5E_CPU1_P0_TX_DN<12>")
	)
	(arc
		(start 65.777872 -368.086894)
		(mid 65.728606 -368.160531)
		(end 65.711324 -368.247422)
		(width 0.14224)
		(layer "In6.Cu")
		(net "P5E_CPU1_P0_TX_DN<12>")
	)
	(arc
		(start 108.643166 -289.011614)
		(mid 108.886493 -289.47618)
		(end 108.643166 -289.940746)
		(width 0.1143)
		(layer "In6.Cu")
		(net "P5E_CPU1_P0_TX_DN<12>")
	)
	(arc
		(start 124.291852 -354.386388)
		(mid 124.081867 -354.599158)
		(end 123.845066 -354.781612)
		(width 0.14224)
		(layer "In6.Cu")
		(net "P5E_CPU1_P0_TX_DN<12>")
	)
	(arc
		(start 108.416344 -285.426404)
		(mid 108.457599 -285.597375)
		(end 108.5723 -285.730696)
		(width 0.1143)
		(layer "In6.Cu")
		(net "P5E_CPU1_P0_TX_DN<12>")
	)
	(arc
		(start 121.887234 -319.268094)
		(mid 121.931301 -319.327845)
		(end 121.969022 -319.391792)
		(width 0.14224)
		(layer "In6.Cu")
		(net "P5E_CPU1_P0_TX_DN<12>")
	)
	(arc
		(start 108.46181 -298.419012)
		(mid 108.477214 -298.574927)
		(end 108.52277 -298.724828)
		(width 0.14224)
		(layer "In6.Cu")
		(net "P5E_CPU1_P0_TX_DN<12>")
	)
	(arc
		(start 107.703112 -284.151832)
		(mid 107.881925 -284.354182)
		(end 107.946444 -284.616398)
		(width 0.1143)
		(layer "In6.Cu")
		(net "P5E_CPU1_P0_TX_DN<12>")
	)
	(arc
		(start 107.23118 -283.340556)
		(mid 107.392394 -283.533414)
		(end 107.472734 -283.771594)
		(width 0.1143)
		(layer "In6.Cu")
		(net "P5E_CPU1_P0_TX_DN<12>")
	)
	(arc
		(start 108.643166 -290.631626)
		(mid 108.886493 -291.096192)
		(end 108.643166 -291.560758)
		(width 0.1143)
		(layer "In6.Cu")
		(net "P5E_CPU1_P0_TX_DN<12>")
	)
	(arc
		(start 108.416344 -288.666174)
		(mid 108.457599 -288.837145)
		(end 108.5723 -288.970466)
		(width 0.1143)
		(layer "In6.Cu")
		(net "P5E_CPU1_P0_TX_DN<12>")
	)
	(arc
		(start 102.527354 -370.376704)
		(mid 102.464553 -370.382982)
		(end 102.404164 -370.401342)
		(width 0.14224)
		(layer "In6.Cu")
		(net "P5E_CPU1_P0_TX_DN<12>")
	)
	(arc
		(start 124.64415 -353.945444)
		(mid 124.614637 -354.003267)
		(end 124.576332 -354.05568)
		(width 0.14224)
		(layer "In6.Cu")
		(net "P5E_CPU1_P0_TX_DN<12>")
	)
	(arc
		(start 108.173012 -284.961838)
		(mid 108.351825 -285.164188)
		(end 108.416344 -285.426404)
		(width 0.1143)
		(layer "In6.Cu")
		(net "P5E_CPU1_P0_TX_DN<12>")
	)
	(arc
		(start 108.886498 -287.856422)
		(mid 108.821983 -288.118641)
		(end 108.643166 -288.320988)
		(width 0.1143)
		(layer "In6.Cu")
		(net "P5E_CPU1_P0_TX_DN<12>")
	)
	(arc
		(start 128.80086 -341.648034)
		(mid 128.50927 -343.867708)
		(end 127.922782 -346.028264)
		(width 0.14224)
		(layer "In6.Cu")
		(net "P5E_CPU1_P0_TX_DN<12>")
	)
	(arc
		(start 128.78816 -341.427562)
		(mid 128.801146 -341.537415)
		(end 128.80086 -341.648034)
		(width 0.14224)
		(layer "In6.Cu")
		(net "P5E_CPU1_P0_TX_DN<12>")
	)
	(arc
		(start 108.5723 -289.981894)
		(mid 108.416372 -290.286186)
		(end 108.5723 -290.590478)
		(width 0.1143)
		(layer "In6.Cu")
		(net "P5E_CPU1_P0_TX_DN<12>")
	)
	(arc
		(start 107.472734 -283.771594)
		(mid 107.475078 -283.793774)
		(end 107.47629 -283.816044)
		(width 0.1143)
		(layer "In6.Cu")
		(net "P5E_CPU1_P0_TX_DN<12>")
	)
	(arc
		(start 107.47629 -283.816044)
		(mid 107.519683 -283.981676)
		(end 107.632246 -284.110684)
		(width 0.1143)
		(layer "In6.Cu")
		(net "P5E_CPU1_P0_TX_DN<12>")
	)
	(arc
		(start 107.013248 -283.066236)
		(mid 107.065297 -283.197755)
		(end 107.162346 -283.300678)
		(width 0.1143)
		(layer "In6.Cu")
		(net "P5E_CPU1_P0_TX_DN<12>")
	)
	(arc
		(start 108.570522 -286.743394)
		(mid 108.457115 -286.876283)
		(end 108.416344 -287.046162)
		(width 0.1143)
		(layer "In6.Cu")
		(net "P5E_CPU1_P0_TX_DN<12>")
	)
	(arc
		(start 126.255272 -327.593706)
		(mid 126.278198 -327.641677)
		(end 126.297436 -327.691242)
		(width 0.14224)
		(layer "In6.Cu")
		(net "P5E_CPU1_P0_TX_DN<12>")
	)
	(arc
		(start 70.083426 -368.024664)
		(mid 69.715992 -367.913199)
		(end 69.333872 -367.875566)
		(width 0.14224)
		(layer "In6.Cu")
		(net "P5E_CPU1_P0_TX_DN<12>")
	)
	(arc
		(start 107.946444 -284.616398)
		(mid 107.987993 -284.78782)
		(end 108.103416 -284.921198)
		(width 0.1143)
		(layer "In6.Cu")
		(net "P5E_CPU1_P0_TX_DN<12>")
	)
	(arc
		(start 103.930958 -369.961414)
		(mid 103.629326 -370.195721)
		(end 103.27894 -370.347748)
		(width 0.14224)
		(layer "In6.Cu")
		(net "P5E_CPU1_P0_TX_DN<12>")
	)
	(segment
		(start 64.300354 -371.49913)
		(end 64.029844 -371.76964)
		(width 0.12954)
		(layer "F.Cu")
		(net "P5E_CPU1_P0_TX_DN<11>")
	)
	(segment
		(start 64.029844 -371.76964)
		(end 64.029844 -372.47322)
		(width 0.12954)
		(layer "F.Cu")
		(net "P5E_CPU1_P0_TX_DN<11>")
	)
	(segment
		(start 107.847892 -285.970472)
		(end 107.38104 -286.23641)
		(width 0.12954)
		(layer "F.Cu")
		(net "P5E_CPU1_P0_TX_DN<11>")
	)
	(segment
		(start 64.029844 -372.47322)
		(end 64.325754 -372.76913)
		(width 0.12954)
		(layer "F.Cu")
		(net "P5E_CPU1_P0_TX_DN<11>")
	)
	(segment
		(start 65.86728 -366.97539)
		(end 65.487296 -367.133124)
		(width 0.14224)
		(layer "In6.Cu")
		(net "P5E_CPU1_P0_TX_DN<11>")
	)
	(segment
		(start 125.54585 -328.831194)
		(end 127.73914 -341.03564)
		(width 0.14224)
		(layer "In6.Cu")
		(net "P5E_CPU1_P0_TX_DN<11>")
	)
	(segment
		(start 107.167172 -295.649396)
		(end 107.16387 -295.651174)
		(width 0.1143)
		(layer "In6.Cu")
		(net "P5E_CPU1_P0_TX_DN<11>")
	)
	(segment
		(start 107.335066 -298.319952)
		(end 110.016544 -304.795174)
		(width 0.14224)
		(layer "In6.Cu")
		(net "P5E_CPU1_P0_TX_DN<11>")
	)
	(segment
		(start 110.463076 -305.633374)
		(end 114.693446 -311.964324)
		(width 0.14224)
		(layer "In6.Cu")
		(net "P5E_CPU1_P0_TX_DN<11>")
	)
	(segment
		(start 126.91237 -346.002356)
		(end 126.835916 -346.206572)
		(width 0.14224)
		(layer "In6.Cu")
		(net "P5E_CPU1_P0_TX_DN<11>")
	)
	(segment
		(start 107.651042 -288.35096)
		(end 107.650788 -288.351214)
		(width 0.1143)
		(layer "In6.Cu")
		(net "P5E_CPU1_P0_TX_DN<11>")
	)
	(segment
		(start 107.700318 -293.182802)
		(end 107.663996 -293.20363)
		(width 0.1143)
		(layer "In6.Cu")
		(net "P5E_CPU1_P0_TX_DN<11>")
	)
	(segment
		(start 107.697524 -288.323782)
		(end 107.664504 -288.34334)
		(width 0.1143)
		(layer "In6.Cu")
		(net "P5E_CPU1_P0_TX_DN<11>")
	)
	(segment
		(start 107.00639 -295.956228)
		(end 107.00639 -296.00779)
		(width 0.1143)
		(layer "In6.Cu")
		(net "P5E_CPU1_P0_TX_DN<11>")
	)
	(segment
		(start 107.296204 -296.584116)
		(end 107.296204 -296.612564)
		(width 0.1143)
		(layer "In6.Cu")
		(net "P5E_CPU1_P0_TX_DN<11>")
	)
	(segment
		(start 107.38104 -286.23641)
		(end 107.083098 -286.23641)
		(width 0.1143)
		(layer "In6.Cu")
		(net "P5E_CPU1_P0_TX_DN<11>")
	)
	(segment
		(start 107.646216 -287.357058)
		(end 107.668314 -287.371536)
		(width 0.1143)
		(layer "In6.Cu")
		(net "P5E_CPU1_P0_TX_DN<11>")
	)
	(segment
		(start 107.296204 -296.612564)
		(end 107.296204 -298.125134)
		(width 0.14224)
		(layer "In6.Cu")
		(net "P5E_CPU1_P0_TX_DN<11>")
	)
	(segment
		(start 107.179618 -295.641776)
		(end 107.178856 -295.642284)
		(width 0.1143)
		(layer "In6.Cu")
		(net "P5E_CPU1_P0_TX_DN<11>")
	)
	(segment
		(start 102.115366 -367.780316)
		(end 72.274938 -367.780316)
		(width 0.14224)
		(layer "In6.Cu")
		(net "P5E_CPU1_P0_TX_DN<11>")
	)
	(segment
		(start 107.221528 -286.574992)
		(end 107.228132 -286.578548)
		(width 0.1143)
		(layer "In6.Cu")
		(net "P5E_CPU1_P0_TX_DN<11>")
	)
	(segment
		(start 107.250484 -296.476674)
		(end 107.250484 -296.538396)
		(width 0.1143)
		(layer "In6.Cu")
		(net "P5E_CPU1_P0_TX_DN<11>")
	)
	(segment
		(start 69.348858 -366.943132)
		(end 66.029078 -366.943132)
		(width 0.14224)
		(layer "In6.Cu")
		(net "P5E_CPU1_P0_TX_DN<11>")
	)
	(segment
		(start 107.650534 -294.831262)
		(end 107.65028 -294.831516)
		(width 0.1143)
		(layer "In6.Cu")
		(net "P5E_CPU1_P0_TX_DN<11>")
	)
	(segment
		(start 107.178856 -295.642284)
		(end 107.167172 -295.649396)
		(width 0.1143)
		(layer "In6.Cu")
		(net "P5E_CPU1_P0_TX_DN<11>")
	)
	(segment
		(start 107.46359 -295.15562)
		(end 107.46359 -295.166034)
		(width 0.1143)
		(layer "In6.Cu")
		(net "P5E_CPU1_P0_TX_DN<11>")
	)
	(segment
		(start 107.663996 -293.20363)
		(end 107.632246 -293.221918)
		(width 0.1143)
		(layer "In6.Cu")
		(net "P5E_CPU1_P0_TX_DN<11>")
	)
	(segment
		(start 107.651042 -288.981388)
		(end 107.70235 -289.011106)
		(width 0.1143)
		(layer "In6.Cu")
		(net "P5E_CPU1_P0_TX_DN<11>")
	)
	(segment
		(start 107.670346 -292.232334)
		(end 107.70235 -292.25113)
		(width 0.1143)
		(layer "In6.Cu")
		(net "P5E_CPU1_P0_TX_DN<11>")
	)
	(segment
		(start 107.684824 -291.571426)
		(end 107.663488 -291.583872)
		(width 0.1143)
		(layer "In6.Cu")
		(net "P5E_CPU1_P0_TX_DN<11>")
	)
	(segment
		(start 71.684134 -367.662714)
		(end 70.4977 -367.171478)
		(width 0.14224)
		(layer "In6.Cu")
		(net "P5E_CPU1_P0_TX_DN<11>")
	)
	(segment
		(start 107.66933 -292.231826)
		(end 107.670346 -292.232334)
		(width 0.1143)
		(layer "In6.Cu")
		(net "P5E_CPU1_P0_TX_DN<11>")
	)
	(segment
		(start 107.166664 -286.54248)
		(end 107.221528 -286.574992)
		(width 0.1143)
		(layer "In6.Cu")
		(net "P5E_CPU1_P0_TX_DN<11>")
	)
	(segment
		(start 107.668568 -292.231318)
		(end 107.66933 -292.231826)
		(width 0.1143)
		(layer "In6.Cu")
		(net "P5E_CPU1_P0_TX_DN<11>")
	)
	(segment
		(start 107.083098 -286.23641)
		(end 107.013248 -286.30626)
		(width 0.1143)
		(layer "In6.Cu")
		(net "P5E_CPU1_P0_TX_DN<11>")
	)
	(segment
		(start 107.685078 -291.571426)
		(end 107.684824 -291.571426)
		(width 0.1143)
		(layer "In6.Cu")
		(net "P5E_CPU1_P0_TX_DN<11>")
	)
	(segment
		(start 107.70235 -287.391348)
		(end 107.70235 -287.391094)
		(width 0.1143)
		(layer "In6.Cu")
		(net "P5E_CPU1_P0_TX_DN<11>")
	)
	(segment
		(start 107.703112 -288.320988)
		(end 107.697524 -288.323782)
		(width 0.1143)
		(layer "In6.Cu")
		(net "P5E_CPU1_P0_TX_DN<11>")
	)
	(segment
		(start 64.461136 -367.819178)
		(end 64.229234 -368.05108)
		(width 0.14224)
		(layer "In6.Cu")
		(net "P5E_CPU1_P0_TX_DN<11>")
	)
	(segment
		(start 121.205244 -319.967356)
		(end 125.276356 -327.75525)
		(width 0.14224)
		(layer "In6.Cu")
		(net "P5E_CPU1_P0_TX_DN<11>")
	)
	(segment
		(start 107.632246 -293.830502)
		(end 107.663996 -293.84879)
		(width 0.1143)
		(layer "In6.Cu")
		(net "P5E_CPU1_P0_TX_DN<11>")
	)
	(segment
		(start 107.664504 -288.34334)
		(end 107.651042 -288.35096)
		(width 0.1143)
		(layer "In6.Cu")
		(net "P5E_CPU1_P0_TX_DN<11>")
	)
	(segment
		(start 110.070646 -304.909474)
		(end 110.412276 -305.548538)
		(width 0.14224)
		(layer "In6.Cu")
		(net "P5E_CPU1_P0_TX_DN<11>")
	)
	(segment
		(start 107.656122 -292.224206)
		(end 107.668568 -292.231318)
		(width 0.1143)
		(layer "In6.Cu")
		(net "P5E_CPU1_P0_TX_DN<11>")
	)
	(segment
		(start 107.650534 -288.981134)
		(end 107.651042 -288.981388)
		(width 0.1143)
		(layer "In6.Cu")
		(net "P5E_CPU1_P0_TX_DN<11>")
	)
	(segment
		(start 125.344936 -327.941432)
		(end 125.518672 -328.699114)
		(width 0.14224)
		(layer "In6.Cu")
		(net "P5E_CPU1_P0_TX_DN<11>")
	)
	(segment
		(start 64.009524 -368.581432)
		(end 64.009524 -371.2083)
		(width 0.14224)
		(layer "In6.Cu")
		(net "P5E_CPU1_P0_TX_DN<11>")
	)
	(segment
		(start 107.668314 -287.371536)
		(end 107.70235 -287.391348)
		(width 0.1143)
		(layer "In6.Cu")
		(net "P5E_CPU1_P0_TX_DN<11>")
	)
	(segment
		(start 107.66933 -290.611814)
		(end 107.670346 -290.612322)
		(width 0.1143)
		(layer "In6.Cu")
		(net "P5E_CPU1_P0_TX_DN<11>")
	)
	(segment
		(start 107.685078 -289.951414)
		(end 107.684824 -289.951414)
		(width 0.1143)
		(layer "In6.Cu")
		(net "P5E_CPU1_P0_TX_DN<11>")
	)
	(segment
		(start 107.656122 -290.604194)
		(end 107.668568 -290.611306)
		(width 0.1143)
		(layer "In6.Cu")
		(net "P5E_CPU1_P0_TX_DN<11>")
	)
	(segment
		(start 107.684824 -289.951414)
		(end 107.663488 -289.96386)
		(width 0.1143)
		(layer "In6.Cu")
		(net "P5E_CPU1_P0_TX_DN<11>")
	)
	(segment
		(start 107.072684 -296.167302)
		(end 107.157266 -296.251884)
		(width 0.1143)
		(layer "In6.Cu")
		(net "P5E_CPU1_P0_TX_DN<11>")
	)
	(segment
		(start 107.663996 -293.84879)
		(end 107.703112 -293.87165)
		(width 0.1143)
		(layer "In6.Cu")
		(net "P5E_CPU1_P0_TX_DN<11>")
	)
	(segment
		(start 107.670346 -290.612322)
		(end 107.70235 -290.631118)
		(width 0.1143)
		(layer "In6.Cu")
		(net "P5E_CPU1_P0_TX_DN<11>")
	)
	(segment
		(start 107.193588 -295.633648)
		(end 107.179618 -295.641776)
		(width 0.1143)
		(layer "In6.Cu")
		(net "P5E_CPU1_P0_TX_DN<11>")
	)
	(segment
		(start 107.703112 -291.560758)
		(end 107.685078 -291.571426)
		(width 0.1143)
		(layer "In6.Cu")
		(net "P5E_CPU1_P0_TX_DN<11>")
	)
	(segment
		(start 126.789434 -346.324428)
		(end 124.149612 -352.69678)
		(width 0.14224)
		(layer "In6.Cu")
		(net "P5E_CPU1_P0_TX_DN<11>")
	)
	(segment
		(start 107.250484 -296.538396)
		(end 107.296204 -296.584116)
		(width 0.1143)
		(layer "In6.Cu")
		(net "P5E_CPU1_P0_TX_DN<11>")
	)
	(segment
		(start 122.768614 -354.37953)
		(end 103.210106 -367.448338)
		(width 0.14224)
		(layer "In6.Cu")
		(net "P5E_CPU1_P0_TX_DN<11>")
	)
	(segment
		(start 114.768884 -312.065924)
		(end 121.009156 -319.671192)
		(width 0.14224)
		(layer "In6.Cu")
		(net "P5E_CPU1_P0_TX_DN<11>")
	)
	(segment
		(start 64.009524 -371.2083)
		(end 64.300354 -371.49913)
		(width 0.14224)
		(layer "In6.Cu")
		(net "P5E_CPU1_P0_TX_DN<11>")
	)
	(segment
		(start 107.703112 -289.940746)
		(end 107.685078 -289.951414)
		(width 0.1143)
		(layer "In6.Cu")
		(net "P5E_CPU1_P0_TX_DN<11>")
	)
	(segment
		(start 107.703112 -293.18077)
		(end 107.700318 -293.182802)
		(width 0.1143)
		(layer "In6.Cu")
		(net "P5E_CPU1_P0_TX_DN<11>")
	)
	(segment
		(start 107.668568 -290.611306)
		(end 107.66933 -290.611814)
		(width 0.1143)
		(layer "In6.Cu")
		(net "P5E_CPU1_P0_TX_DN<11>")
	)
	(segment
		(start 107.703112 -294.800782)
		(end 107.650534 -294.831262)
		(width 0.1143)
		(layer "In6.Cu")
		(net "P5E_CPU1_P0_TX_DN<11>")
	)
	(arc
		(start 107.650788 -288.351214)
		(mid 107.469464 -288.666064)
		(end 107.650534 -288.981134)
		(width 0.1143)
		(layer "In6.Cu")
		(net "P5E_CPU1_P0_TX_DN<11>")
	)
	(arc
		(start 114.693446 -311.964324)
		(mid 114.729924 -312.016046)
		(end 114.768884 -312.065924)
		(width 0.14224)
		(layer "In6.Cu")
		(net "P5E_CPU1_P0_TX_DN<11>")
	)
	(arc
		(start 107.70235 -290.631118)
		(mid 107.702731 -290.631372)
		(end 107.703112 -290.631626)
		(width 0.1143)
		(layer "In6.Cu")
		(net "P5E_CPU1_P0_TX_DN<11>")
	)
	(arc
		(start 127.779272 -342.425528)
		(mid 127.391889 -344.225108)
		(end 126.91237 -346.002356)
		(width 0.14224)
		(layer "In6.Cu")
		(net "P5E_CPU1_P0_TX_DN<11>")
	)
	(arc
		(start 107.663488 -289.96386)
		(mid 107.477968 -290.281917)
		(end 107.656122 -290.604194)
		(width 0.1143)
		(layer "In6.Cu")
		(net "P5E_CPU1_P0_TX_DN<11>")
	)
	(arc
		(start 107.011216 -286.307022)
		(mid 107.015622 -286.320927)
		(end 107.019598 -286.334962)
		(width 0.1143)
		(layer "In6.Cu")
		(net "P5E_CPU1_P0_TX_DN<11>")
	)
	(arc
		(start 72.274938 -367.780316)
		(mid 71.973746 -367.750605)
		(end 71.684134 -367.662714)
		(width 0.14224)
		(layer "In6.Cu")
		(net "P5E_CPU1_P0_TX_DN<11>")
	)
	(arc
		(start 107.703112 -292.251638)
		(mid 107.946439 -292.716204)
		(end 107.703112 -293.18077)
		(width 0.1143)
		(layer "In6.Cu")
		(net "P5E_CPU1_P0_TX_DN<11>")
	)
	(arc
		(start 107.228132 -286.578548)
		(mid 107.406271 -286.773632)
		(end 107.47629 -287.028382)
		(width 0.1143)
		(layer "In6.Cu")
		(net "P5E_CPU1_P0_TX_DN<11>")
	)
	(arc
		(start 65.487296 -367.133124)
		(mid 64.940469 -367.425673)
		(end 64.461136 -367.819178)
		(width 0.14224)
		(layer "In6.Cu")
		(net "P5E_CPU1_P0_TX_DN<11>")
	)
	(arc
		(start 127.775208 -341.411306)
		(mid 127.79294 -341.651412)
		(end 127.809244 -341.89162)
		(width 0.14224)
		(layer "In6.Cu")
		(net "P5E_CPU1_P0_TX_DN<11>")
	)
	(arc
		(start 107.703112 -289.011614)
		(mid 107.946439 -289.47618)
		(end 107.703112 -289.940746)
		(width 0.1143)
		(layer "In6.Cu")
		(net "P5E_CPU1_P0_TX_DN<11>")
	)
	(arc
		(start 107.663488 -291.583872)
		(mid 107.477968 -291.901929)
		(end 107.656122 -292.224206)
		(width 0.1143)
		(layer "In6.Cu")
		(net "P5E_CPU1_P0_TX_DN<11>")
	)
	(arc
		(start 107.70235 -292.25113)
		(mid 107.702731 -292.251384)
		(end 107.703112 -292.251638)
		(width 0.1143)
		(layer "In6.Cu")
		(net "P5E_CPU1_P0_TX_DN<11>")
	)
	(arc
		(start 107.632246 -293.221918)
		(mid 107.481861 -293.52621)
		(end 107.632246 -293.830502)
		(width 0.1143)
		(layer "In6.Cu")
		(net "P5E_CPU1_P0_TX_DN<11>")
	)
	(arc
		(start 107.019598 -286.334962)
		(mid 107.074978 -286.451581)
		(end 107.166664 -286.54248)
		(width 0.1143)
		(layer "In6.Cu")
		(net "P5E_CPU1_P0_TX_DN<11>")
	)
	(arc
		(start 107.46359 -295.166034)
		(mid 107.391249 -295.436027)
		(end 107.193588 -295.633648)
		(width 0.1143)
		(layer "In6.Cu")
		(net "P5E_CPU1_P0_TX_DN<11>")
	)
	(arc
		(start 125.518672 -328.699114)
		(mid 125.533015 -328.764999)
		(end 125.54585 -328.831194)
		(width 0.14224)
		(layer "In6.Cu")
		(net "P5E_CPU1_P0_TX_DN<11>")
	)
	(arc
		(start 107.296204 -298.125134)
		(mid 107.30603 -298.224461)
		(end 107.335066 -298.319952)
		(width 0.14224)
		(layer "In6.Cu")
		(net "P5E_CPU1_P0_TX_DN<11>")
	)
	(arc
		(start 107.703112 -290.631626)
		(mid 107.946439 -291.096192)
		(end 107.703112 -291.560758)
		(width 0.1143)
		(layer "In6.Cu")
		(net "P5E_CPU1_P0_TX_DN<11>")
	)
	(arc
		(start 107.70235 -289.011106)
		(mid 107.702731 -289.01136)
		(end 107.703112 -289.011614)
		(width 0.1143)
		(layer "In6.Cu")
		(net "P5E_CPU1_P0_TX_DN<11>")
	)
	(arc
		(start 107.65028 -294.831516)
		(mid 107.513591 -294.968603)
		(end 107.46359 -295.15562)
		(width 0.1143)
		(layer "In6.Cu")
		(net "P5E_CPU1_P0_TX_DN<11>")
	)
	(arc
		(start 107.00639 -296.00779)
		(mid 107.023661 -296.094149)
		(end 107.072684 -296.167302)
		(width 0.1143)
		(layer "In6.Cu")
		(net "P5E_CPU1_P0_TX_DN<11>")
	)
	(arc
		(start 127.809244 -341.89162)
		(mid 127.811609 -342.159547)
		(end 127.779272 -342.425528)
		(width 0.14224)
		(layer "In6.Cu")
		(net "P5E_CPU1_P0_TX_DN<11>")
	)
	(arc
		(start 110.016544 -304.795174)
		(mid 110.042196 -304.852986)
		(end 110.070646 -304.909474)
		(width 0.14224)
		(layer "In6.Cu")
		(net "P5E_CPU1_P0_TX_DN<11>")
	)
	(arc
		(start 103.210106 -367.448338)
		(mid 102.687353 -367.695488)
		(end 102.115366 -367.780316)
		(width 0.14224)
		(layer "In6.Cu")
		(net "P5E_CPU1_P0_TX_DN<11>")
	)
	(arc
		(start 107.703112 -293.87165)
		(mid 107.946439 -294.336216)
		(end 107.703112 -294.800782)
		(width 0.1143)
		(layer "In6.Cu")
		(net "P5E_CPU1_P0_TX_DN<11>")
	)
	(arc
		(start 126.835916 -346.206572)
		(mid 126.813182 -346.2657)
		(end 126.789434 -346.324428)
		(width 0.14224)
		(layer "In6.Cu")
		(net "P5E_CPU1_P0_TX_DN<11>")
	)
	(arc
		(start 121.009156 -319.671192)
		(mid 121.114798 -319.814243)
		(end 121.205244 -319.967356)
		(width 0.14224)
		(layer "In6.Cu")
		(net "P5E_CPU1_P0_TX_DN<11>")
	)
	(arc
		(start 107.70235 -287.391094)
		(mid 107.946522 -287.855892)
		(end 107.703112 -288.320988)
		(width 0.1143)
		(layer "In6.Cu")
		(net "P5E_CPU1_P0_TX_DN<11>")
	)
	(arc
		(start 107.16387 -295.651174)
		(mid 107.048125 -295.7846)
		(end 107.00639 -295.956228)
		(width 0.1143)
		(layer "In6.Cu")
		(net "P5E_CPU1_P0_TX_DN<11>")
	)
	(arc
		(start 107.478068 -287.05429)
		(mid 107.513206 -287.179549)
		(end 107.580684 -287.290764)
		(width 0.1143)
		(layer "In6.Cu")
		(net "P5E_CPU1_P0_TX_DN<11>")
	)
	(arc
		(start 70.4977 -367.171478)
		(mid 69.934522 -367.000746)
		(end 69.348858 -366.943132)
		(width 0.14224)
		(layer "In6.Cu")
		(net "P5E_CPU1_P0_TX_DN<11>")
	)
	(arc
		(start 125.276356 -327.75525)
		(mid 125.31663 -327.846137)
		(end 125.344936 -327.941432)
		(width 0.14224)
		(layer "In6.Cu")
		(net "P5E_CPU1_P0_TX_DN<11>")
	)
	(arc
		(start 107.580684 -287.290764)
		(mid 107.611839 -287.325504)
		(end 107.646216 -287.357058)
		(width 0.1143)
		(layer "In6.Cu")
		(net "P5E_CPU1_P0_TX_DN<11>")
	)
	(arc
		(start 124.149612 -352.69678)
		(mid 123.583919 -353.64058)
		(end 122.768614 -354.37953)
		(width 0.14224)
		(layer "In6.Cu")
		(net "P5E_CPU1_P0_TX_DN<11>")
	)
	(arc
		(start 107.013248 -286.30626)
		(mid 107.012228 -286.306631)
		(end 107.011216 -286.307022)
		(width 0.1143)
		(layer "In6.Cu")
		(net "P5E_CPU1_P0_TX_DN<11>")
	)
	(arc
		(start 66.029078 -366.943132)
		(mid 65.946585 -366.951271)
		(end 65.86728 -366.97539)
		(width 0.14224)
		(layer "In6.Cu")
		(net "P5E_CPU1_P0_TX_DN<11>")
	)
	(arc
		(start 110.412276 -305.548538)
		(mid 110.436637 -305.591578)
		(end 110.463076 -305.633374)
		(width 0.14224)
		(layer "In6.Cu")
		(net "P5E_CPU1_P0_TX_DN<11>")
	)
	(arc
		(start 64.229234 -368.05108)
		(mid 64.066648 -368.294408)
		(end 64.009524 -368.581432)
		(width 0.14224)
		(layer "In6.Cu")
		(net "P5E_CPU1_P0_TX_DN<11>")
	)
	(arc
		(start 127.73914 -341.03564)
		(mid 127.758898 -341.223307)
		(end 127.775208 -341.411306)
		(width 0.14224)
		(layer "In6.Cu")
		(net "P5E_CPU1_P0_TX_DN<11>")
	)
	(arc
		(start 107.47629 -287.028382)
		(mid 107.476833 -287.04136)
		(end 107.478068 -287.05429)
		(width 0.1143)
		(layer "In6.Cu")
		(net "P5E_CPU1_P0_TX_DN<11>")
	)
	(arc
		(start 107.157266 -296.251884)
		(mid 107.226261 -296.355003)
		(end 107.250484 -296.476674)
		(width 0.1143)
		(layer "In6.Cu")
		(net "P5E_CPU1_P0_TX_DN<11>")
	)
	(segment
		(start 62.328044 -374.93702)
		(end 62.623954 -375.23293)
		(width 0.12954)
		(layer "F.Cu")
		(net "P5E_CPU1_P0_TX_DN<10>")
	)
	(segment
		(start 62.598554 -373.96293)
		(end 62.328044 -374.23344)
		(width 0.12954)
		(layer "F.Cu")
		(net "P5E_CPU1_P0_TX_DN<10>")
	)
	(segment
		(start 62.328044 -374.23344)
		(end 62.328044 -374.93702)
		(width 0.12954)
		(layer "F.Cu")
		(net "P5E_CPU1_P0_TX_DN<10>")
	)
	(segment
		(start 107.847892 -284.35046)
		(end 107.38104 -284.616398)
		(width 0.12954)
		(layer "F.Cu")
		(net "P5E_CPU1_P0_TX_DN<10>")
	)
	(segment
		(start 106.198924 -296.26687)
		(end 106.198924 -296.281348)
		(width 0.1143)
		(layer "In6.Cu")
		(net "P5E_CPU1_P0_TX_DN<10>")
	)
	(segment
		(start 69.749924 -366.007396)
		(end 65.850516 -366.007396)
		(width 0.14224)
		(layer "In6.Cu")
		(net "P5E_CPU1_P0_TX_DN<10>")
	)
	(segment
		(start 106.24947 -285.91637)
		(end 106.247946 -285.917386)
		(width 0.1143)
		(layer "In6.Cu")
		(net "P5E_CPU1_P0_TX_DN<10>")
	)
	(segment
		(start 107.38104 -284.616398)
		(end 107.083098 -284.616398)
		(width 0.1143)
		(layer "In6.Cu")
		(net "P5E_CPU1_P0_TX_DN<10>")
	)
	(segment
		(start 122.081544 -353.714558)
		(end 103.00081 -366.464088)
		(width 0.14224)
		(layer "In6.Cu")
		(net "P5E_CPU1_P0_TX_DN<10>")
	)
	(segment
		(start 101.86797 -366.80775)
		(end 72.415654 -366.80775)
		(width 0.14224)
		(layer "In6.Cu")
		(net "P5E_CPU1_P0_TX_DN<10>")
	)
	(segment
		(start 106.763058 -285.080964)
		(end 106.693462 -285.121604)
		(width 0.1143)
		(layer "In6.Cu")
		(net "P5E_CPU1_P0_TX_DN<10>")
	)
	(segment
		(start 106.692192 -292.210236)
		(end 106.761788 -292.250622)
		(width 0.1143)
		(layer "In6.Cu")
		(net "P5E_CPU1_P0_TX_DN<10>")
	)
	(segment
		(start 106.327448 -295.688258)
		(end 106.260392 -295.755314)
		(width 0.1143)
		(layer "In6.Cu")
		(net "P5E_CPU1_P0_TX_DN<10>")
	)
	(segment
		(start 120.46458 -320.596514)
		(end 124.361448 -328.050398)
		(width 0.14224)
		(layer "In6.Cu")
		(net "P5E_CPU1_P0_TX_DN<10>")
	)
	(segment
		(start 106.293158 -285.89097)
		(end 106.256582 -285.912306)
		(width 0.1143)
		(layer "In6.Cu")
		(net "P5E_CPU1_P0_TX_DN<10>")
	)
	(segment
		(start 106.246422 -285.918148)
		(end 106.24566 -285.918656)
		(width 0.1143)
		(layer "In6.Cu")
		(net "P5E_CPU1_P0_TX_DN<10>")
	)
	(segment
		(start 106.222038 -286.540448)
		(end 106.29519 -286.58312)
		(width 0.1143)
		(layer "In6.Cu")
		(net "P5E_CPU1_P0_TX_DN<10>")
	)
	(segment
		(start 114.34445 -313.110118)
		(end 120.362726 -320.442844)
		(width 0.14224)
		(layer "In6.Cu")
		(net "P5E_CPU1_P0_TX_DN<10>")
	)
	(segment
		(start 106.24439 -285.919418)
		(end 106.242866 -285.92018)
		(width 0.1143)
		(layer "In6.Cu")
		(net "P5E_CPU1_P0_TX_DN<10>")
	)
	(segment
		(start 106.25328 -285.914338)
		(end 106.25201 -285.9151)
		(width 0.1143)
		(layer "In6.Cu")
		(net "P5E_CPU1_P0_TX_DN<10>")
	)
	(segment
		(start 106.761534 -294.801798)
		(end 106.692192 -294.842184)
		(width 0.1143)
		(layer "In6.Cu")
		(net "P5E_CPU1_P0_TX_DN<10>")
	)
	(segment
		(start 106.761534 -291.561774)
		(end 106.692192 -291.60216)
		(width 0.1143)
		(layer "In6.Cu")
		(net "P5E_CPU1_P0_TX_DN<10>")
	)
	(segment
		(start 107.083098 -284.616398)
		(end 107.000294 -284.699202)
		(width 0.1143)
		(layer "In6.Cu")
		(net "P5E_CPU1_P0_TX_DN<10>")
	)
	(segment
		(start 106.24566 -285.918656)
		(end 106.24439 -285.919418)
		(width 0.1143)
		(layer "In6.Cu")
		(net "P5E_CPU1_P0_TX_DN<10>")
	)
	(segment
		(start 109.200442 -305.261518)
		(end 109.691932 -306.180236)
		(width 0.14224)
		(layer "In6.Cu")
		(net "P5E_CPU1_P0_TX_DN<10>")
	)
	(segment
		(start 106.76382 -288.320734)
		(end 106.692446 -288.362136)
		(width 0.1143)
		(layer "In6.Cu")
		(net "P5E_CPU1_P0_TX_DN<10>")
	)
	(segment
		(start 106.692192 -293.830248)
		(end 106.761788 -293.870634)
		(width 0.1143)
		(layer "In6.Cu")
		(net "P5E_CPU1_P0_TX_DN<10>")
	)
	(segment
		(start 106.692192 -290.590224)
		(end 106.761788 -290.63061)
		(width 0.1143)
		(layer "In6.Cu")
		(net "P5E_CPU1_P0_TX_DN<10>")
	)
	(segment
		(start 126.802134 -341.45093)
		(end 126.79426 -341.803736)
		(width 0.14224)
		(layer "In6.Cu")
		(net "P5E_CPU1_P0_TX_DN<10>")
	)
	(segment
		(start 106.761534 -293.181786)
		(end 106.692192 -293.222172)
		(width 0.1143)
		(layer "In6.Cu")
		(net "P5E_CPU1_P0_TX_DN<10>")
	)
	(segment
		(start 106.153204 -296.22115)
		(end 106.198924 -296.26687)
		(width 0.1143)
		(layer "In6.Cu")
		(net "P5E_CPU1_P0_TX_DN<10>")
	)
	(segment
		(start 71.773288 -366.679988)
		(end 70.519544 -366.160558)
		(width 0.14224)
		(layer "In6.Cu")
		(net "P5E_CPU1_P0_TX_DN<10>")
	)
	(segment
		(start 106.247946 -285.917386)
		(end 106.246422 -285.918148)
		(width 0.1143)
		(layer "In6.Cu")
		(net "P5E_CPU1_P0_TX_DN<10>")
	)
	(segment
		(start 106.198924 -296.281348)
		(end 106.198924 -297.950636)
		(width 0.14224)
		(layer "In6.Cu")
		(net "P5E_CPU1_P0_TX_DN<10>")
	)
	(segment
		(start 109.691932 -306.180236)
		(end 114.115088 -312.800492)
		(width 0.14224)
		(layer "In6.Cu")
		(net "P5E_CPU1_P0_TX_DN<10>")
	)
	(segment
		(start 124.630688 -329.14209)
		(end 126.78791 -341.269828)
		(width 0.14224)
		(layer "In6.Cu")
		(net "P5E_CPU1_P0_TX_DN<10>")
	)
	(segment
		(start 106.761534 -289.941762)
		(end 106.692192 -289.982148)
		(width 0.1143)
		(layer "In6.Cu")
		(net "P5E_CPU1_P0_TX_DN<10>")
	)
	(segment
		(start 106.153204 -296.013632)
		(end 106.153204 -296.22115)
		(width 0.1143)
		(layer "In6.Cu")
		(net "P5E_CPU1_P0_TX_DN<10>")
	)
	(segment
		(start 106.223562 -298.073826)
		(end 109.200442 -305.261518)
		(width 0.14224)
		(layer "In6.Cu")
		(net "P5E_CPU1_P0_TX_DN<10>")
	)
	(segment
		(start 106.254042 -285.91383)
		(end 106.25328 -285.914338)
		(width 0.1143)
		(layer "In6.Cu")
		(net "P5E_CPU1_P0_TX_DN<10>")
	)
	(segment
		(start 106.692192 -288.970212)
		(end 106.761788 -289.010598)
		(width 0.1143)
		(layer "In6.Cu")
		(net "P5E_CPU1_P0_TX_DN<10>")
	)
	(segment
		(start 62.307724 -369.392454)
		(end 62.307724 -373.605298)
		(width 0.14224)
		(layer "In6.Cu")
		(net "P5E_CPU1_P0_TX_DN<10>")
	)
	(segment
		(start 106.694224 -287.351724)
		(end 106.761534 -287.39084)
		(width 0.1143)
		(layer "In6.Cu")
		(net "P5E_CPU1_P0_TX_DN<10>")
	)
	(segment
		(start 65.617598 -366.053624)
		(end 64.124586 -366.672368)
		(width 0.14224)
		(layer "In6.Cu")
		(net "P5E_CPU1_P0_TX_DN<10>")
	)
	(segment
		(start 106.255058 -285.913322)
		(end 106.254042 -285.91383)
		(width 0.1143)
		(layer "In6.Cu")
		(net "P5E_CPU1_P0_TX_DN<10>")
	)
	(segment
		(start 106.242104 -285.920688)
		(end 106.222292 -285.932372)
		(width 0.1143)
		(layer "In6.Cu")
		(net "P5E_CPU1_P0_TX_DN<10>")
	)
	(segment
		(start 62.354968 -373.719344)
		(end 62.598554 -373.96293)
		(width 0.14224)
		(layer "In6.Cu")
		(net "P5E_CPU1_P0_TX_DN<10>")
	)
	(segment
		(start 106.242866 -285.92018)
		(end 106.242104 -285.920688)
		(width 0.1143)
		(layer "In6.Cu")
		(net "P5E_CPU1_P0_TX_DN<10>")
	)
	(segment
		(start 106.536236 -295.146222)
		(end 106.536236 -295.18356)
		(width 0.1143)
		(layer "In6.Cu")
		(net "P5E_CPU1_P0_TX_DN<10>")
	)
	(segment
		(start 126.150878 -345.093036)
		(end 123.058174 -352.561398)
		(width 0.14224)
		(layer "In6.Cu")
		(net "P5E_CPU1_P0_TX_DN<10>")
	)
	(segment
		(start 106.25201 -285.9151)
		(end 106.24947 -285.91637)
		(width 0.1143)
		(layer "In6.Cu")
		(net "P5E_CPU1_P0_TX_DN<10>")
	)
	(segment
		(start 106.256582 -285.912306)
		(end 106.255058 -285.913322)
		(width 0.1143)
		(layer "In6.Cu")
		(net "P5E_CPU1_P0_TX_DN<10>")
	)
	(arc
		(start 123.058174 -352.561398)
		(mid 123.023904 -352.636837)
		(end 122.984514 -352.709734)
		(width 0.14224)
		(layer "In6.Cu")
		(net "P5E_CPU1_P0_TX_DN<10>")
	)
	(arc
		(start 106.692192 -291.60216)
		(mid 106.536365 -291.906198)
		(end 106.692192 -292.210236)
		(width 0.1143)
		(layer "In6.Cu")
		(net "P5E_CPU1_P0_TX_DN<10>")
	)
	(arc
		(start 120.362726 -320.442844)
		(mid 120.417611 -320.517056)
		(end 120.46458 -320.596514)
		(width 0.14224)
		(layer "In6.Cu")
		(net "P5E_CPU1_P0_TX_DN<10>")
	)
	(arc
		(start 64.124586 -366.672368)
		(mid 62.803711 -367.756905)
		(end 62.307724 -369.392454)
		(width 0.14224)
		(layer "In6.Cu")
		(net "P5E_CPU1_P0_TX_DN<10>")
	)
	(arc
		(start 106.996484 -284.722062)
		(mid 106.915051 -284.92446)
		(end 106.763058 -285.080964)
		(width 0.1143)
		(layer "In6.Cu")
		(net "P5E_CPU1_P0_TX_DN<10>")
	)
	(arc
		(start 106.692192 -293.222172)
		(mid 106.536365 -293.52621)
		(end 106.692192 -293.830248)
		(width 0.1143)
		(layer "In6.Cu")
		(net "P5E_CPU1_P0_TX_DN<10>")
	)
	(arc
		(start 62.307724 -373.605298)
		(mid 62.320001 -373.667021)
		(end 62.354968 -373.719344)
		(width 0.14224)
		(layer "In6.Cu")
		(net "P5E_CPU1_P0_TX_DN<10>")
	)
	(arc
		(start 106.260392 -295.755314)
		(mid 106.181118 -295.873816)
		(end 106.153204 -296.013632)
		(width 0.1143)
		(layer "In6.Cu")
		(net "P5E_CPU1_P0_TX_DN<10>")
	)
	(arc
		(start 106.761788 -292.250622)
		(mid 107.006609 -292.716309)
		(end 106.761534 -293.181786)
		(width 0.1143)
		(layer "In6.Cu")
		(net "P5E_CPU1_P0_TX_DN<10>")
	)
	(arc
		(start 122.984514 -352.709734)
		(mid 122.583871 -353.257838)
		(end 122.081544 -353.714558)
		(width 0.14224)
		(layer "In6.Cu")
		(net "P5E_CPU1_P0_TX_DN<10>")
	)
	(arc
		(start 106.536236 -295.18356)
		(mid 106.482023 -295.456667)
		(end 106.327448 -295.688258)
		(width 0.1143)
		(layer "In6.Cu")
		(net "P5E_CPU1_P0_TX_DN<10>")
	)
	(arc
		(start 107.000294 -284.699202)
		(mid 106.998506 -284.710651)
		(end 106.996484 -284.722062)
		(width 0.1143)
		(layer "In6.Cu")
		(net "P5E_CPU1_P0_TX_DN<10>")
	)
	(arc
		(start 106.761788 -290.63061)
		(mid 107.006609 -291.096297)
		(end 106.761534 -291.561774)
		(width 0.1143)
		(layer "In6.Cu")
		(net "P5E_CPU1_P0_TX_DN<10>")
	)
	(arc
		(start 103.00081 -366.464088)
		(mid 102.459883 -366.719957)
		(end 101.86797 -366.80775)
		(width 0.14224)
		(layer "In6.Cu")
		(net "P5E_CPU1_P0_TX_DN<10>")
	)
	(arc
		(start 106.761788 -289.010598)
		(mid 107.006609 -289.476285)
		(end 106.761534 -289.941762)
		(width 0.1143)
		(layer "In6.Cu")
		(net "P5E_CPU1_P0_TX_DN<10>")
	)
	(arc
		(start 106.761788 -293.870634)
		(mid 107.006609 -294.336321)
		(end 106.761534 -294.801798)
		(width 0.1143)
		(layer "In6.Cu")
		(net "P5E_CPU1_P0_TX_DN<10>")
	)
	(arc
		(start 126.78791 -341.269828)
		(mid 126.799498 -341.360027)
		(end 126.802134 -341.45093)
		(width 0.14224)
		(layer "In6.Cu")
		(net "P5E_CPU1_P0_TX_DN<10>")
	)
	(arc
		(start 72.415654 -366.80775)
		(mid 72.088176 -366.775508)
		(end 71.773288 -366.679988)
		(width 0.14224)
		(layer "In6.Cu")
		(net "P5E_CPU1_P0_TX_DN<10>")
	)
	(arc
		(start 106.536236 -287.046162)
		(mid 106.578076 -287.218148)
		(end 106.694224 -287.351724)
		(width 0.1143)
		(layer "In6.Cu")
		(net "P5E_CPU1_P0_TX_DN<10>")
	)
	(arc
		(start 106.761534 -287.39084)
		(mid 106.941326 -287.593428)
		(end 107.006136 -287.856422)
		(width 0.1143)
		(layer "In6.Cu")
		(net "P5E_CPU1_P0_TX_DN<10>")
	)
	(arc
		(start 124.361448 -328.050398)
		(mid 124.400612 -328.137116)
		(end 124.429774 -328.22769)
		(width 0.14224)
		(layer "In6.Cu")
		(net "P5E_CPU1_P0_TX_DN<10>")
	)
	(arc
		(start 70.519544 -366.160558)
		(mid 70.142277 -366.046084)
		(end 69.749924 -366.007396)
		(width 0.14224)
		(layer "In6.Cu")
		(net "P5E_CPU1_P0_TX_DN<10>")
	)
	(arc
		(start 124.429774 -328.22769)
		(mid 124.539394 -328.682877)
		(end 124.630688 -329.14209)
		(width 0.14224)
		(layer "In6.Cu")
		(net "P5E_CPU1_P0_TX_DN<10>")
	)
	(arc
		(start 65.850516 -366.007396)
		(mid 65.731783 -366.019045)
		(end 65.617598 -366.053624)
		(width 0.14224)
		(layer "In6.Cu")
		(net "P5E_CPU1_P0_TX_DN<10>")
	)
	(arc
		(start 106.198924 -297.950636)
		(mid 106.205202 -298.013437)
		(end 106.223562 -298.073826)
		(width 0.14224)
		(layer "In6.Cu")
		(net "P5E_CPU1_P0_TX_DN<10>")
	)
	(arc
		(start 106.692446 -288.362136)
		(mid 106.536513 -288.666071)
		(end 106.692192 -288.970212)
		(width 0.1143)
		(layer "In6.Cu")
		(net "P5E_CPU1_P0_TX_DN<10>")
	)
	(arc
		(start 106.692192 -294.842184)
		(mid 106.577516 -294.975375)
		(end 106.536236 -295.146222)
		(width 0.1143)
		(layer "In6.Cu")
		(net "P5E_CPU1_P0_TX_DN<10>")
	)
	(arc
		(start 107.006136 -287.856422)
		(mid 106.94196 -288.118309)
		(end 106.76382 -288.320734)
		(width 0.1143)
		(layer "In6.Cu")
		(net "P5E_CPU1_P0_TX_DN<10>")
	)
	(arc
		(start 106.29519 -286.58312)
		(mid 106.472386 -286.785132)
		(end 106.536236 -287.046162)
		(width 0.1143)
		(layer "In6.Cu")
		(net "P5E_CPU1_P0_TX_DN<10>")
	)
	(arc
		(start 106.53649 -285.426404)
		(mid 106.471975 -285.688623)
		(end 106.293158 -285.89097)
		(width 0.1143)
		(layer "In6.Cu")
		(net "P5E_CPU1_P0_TX_DN<10>")
	)
	(arc
		(start 106.222292 -285.932372)
		(mid 106.066359 -286.236307)
		(end 106.222038 -286.540448)
		(width 0.1143)
		(layer "In6.Cu")
		(net "P5E_CPU1_P0_TX_DN<10>")
	)
	(arc
		(start 114.115088 -312.800492)
		(mid 114.226018 -312.958084)
		(end 114.34445 -313.110118)
		(width 0.14224)
		(layer "In6.Cu")
		(net "P5E_CPU1_P0_TX_DN<10>")
	)
	(arc
		(start 106.693462 -285.121604)
		(mid 106.578035 -285.25498)
		(end 106.53649 -285.426404)
		(width 0.1143)
		(layer "In6.Cu")
		(net "P5E_CPU1_P0_TX_DN<10>")
	)
	(arc
		(start 126.79426 -341.803736)
		(mid 126.591364 -343.471622)
		(end 126.150878 -345.093036)
		(width 0.14224)
		(layer "In6.Cu")
		(net "P5E_CPU1_P0_TX_DN<10>")
	)
	(arc
		(start 106.692192 -289.982148)
		(mid 106.536365 -290.286186)
		(end 106.692192 -290.590224)
		(width 0.1143)
		(layer "In6.Cu")
		(net "P5E_CPU1_P0_TX_DN<10>")
	)
	(segment
		(start 42.404792 -381.77597)
		(end 42.700702 -381.48006)
		(width 0.12954)
		(layer "F.Cu")
		(net "P5E_CPU1_P0_TX_DN<0>")
	)
	(segment
		(start 41.430702 -381.50546)
		(end 41.701212 -381.77597)
		(width 0.12954)
		(layer "F.Cu")
		(net "P5E_CPU1_P0_TX_DN<0>")
	)
	(segment
		(start 99.387914 -282.730448)
		(end 98.921062 -282.996386)
		(width 0.12954)
		(layer "F.Cu")
		(net "P5E_CPU1_P0_TX_DN<0>")
	)
	(segment
		(start 41.701212 -381.77597)
		(end 42.404792 -381.77597)
		(width 0.12954)
		(layer "F.Cu")
		(net "P5E_CPU1_P0_TX_DN<0>")
	)
	(segment
		(start 40.018716 -378.349002)
		(end 40.018716 -378.855732)
		(width 0.14224)
		(layer "In6.Cu")
		(net "P5E_CPU1_P0_TX_DN<0>")
	)
	(segment
		(start 54.03723 -361.112054)
		(end 47.35449 -363.879638)
		(width 0.14224)
		(layer "In6.Cu")
		(net "P5E_CPU1_P0_TX_DN<0>")
	)
	(segment
		(start 40.018716 -380.141734)
		(end 40.155876 -380.278894)
		(width 0.14224)
		(layer "In6.Cu")
		(net "P5E_CPU1_P0_TX_DN<0>")
	)
	(segment
		(start 54.90972 -360.304588)
		(end 54.233318 -360.98099)
		(width 0.14224)
		(layer "In6.Cu")
		(net "P5E_CPU1_P0_TX_DN<0>")
	)
	(segment
		(start 96.916748 -295.624504)
		(end 96.713548 -295.827958)
		(width 0.1143)
		(layer "In6.Cu")
		(net "P5E_CPU1_P0_TX_DN<0>")
	)
	(segment
		(start 97.78365 -284.29966)
		(end 97.762314 -284.312106)
		(width 0.1143)
		(layer "In6.Cu")
		(net "P5E_CPU1_P0_TX_DN<0>")
	)
	(segment
		(start 97.796604 -284.292294)
		(end 97.79508 -284.29331)
		(width 0.1143)
		(layer "In6.Cu")
		(net "P5E_CPU1_P0_TX_DN<0>")
	)
	(segment
		(start 97.363026 -291.560758)
		(end 97.29343 -291.601398)
		(width 0.1143)
		(layer "In6.Cu")
		(net "P5E_CPU1_P0_TX_DN<0>")
	)
	(segment
		(start 96.893126 -285.89097)
		(end 96.855026 -285.913322)
		(width 0.1143)
		(layer "In6.Cu")
		(net "P5E_CPU1_P0_TX_DN<0>")
	)
	(segment
		(start 97.29343 -290.590986)
		(end 97.363026 -290.631626)
		(width 0.1143)
		(layer "In6.Cu")
		(net "P5E_CPU1_P0_TX_DN<0>")
	)
	(segment
		(start 96.736662 -299.64507)
		(end 101.252274 -310.547258)
		(width 0.14224)
		(layer "In6.Cu")
		(net "P5E_CPU1_P0_TX_DN<0>")
	)
	(segment
		(start 97.29343 -292.210998)
		(end 97.363026 -292.251638)
		(width 0.1143)
		(layer "In6.Cu")
		(net "P5E_CPU1_P0_TX_DN<0>")
	)
	(segment
		(start 98.921062 -282.996386)
		(end 98.62312 -282.996386)
		(width 0.1143)
		(layer "In6.Cu")
		(net "P5E_CPU1_P0_TX_DN<0>")
	)
	(segment
		(start 96.820482 -286.539178)
		(end 96.893126 -286.581596)
		(width 0.1143)
		(layer "In6.Cu")
		(net "P5E_CPU1_P0_TX_DN<0>")
	)
	(segment
		(start 97.363026 -293.18077)
		(end 97.29343 -293.22141)
		(width 0.1143)
		(layer "In6.Cu")
		(net "P5E_CPU1_P0_TX_DN<0>")
	)
	(segment
		(start 97.790508 -284.29585)
		(end 97.789746 -284.296358)
		(width 0.1143)
		(layer "In6.Cu")
		(net "P5E_CPU1_P0_TX_DN<0>")
	)
	(segment
		(start 97.788222 -284.29712)
		(end 97.78746 -284.297628)
		(width 0.1143)
		(layer "In6.Cu")
		(net "P5E_CPU1_P0_TX_DN<0>")
	)
	(segment
		(start 40.155876 -376.426222)
		(end 40.155876 -376.852942)
		(width 0.14224)
		(layer "In6.Cu")
		(net "P5E_CPU1_P0_TX_DN<0>")
	)
	(segment
		(start 113.879376 -347.740986)
		(end 113.879122 -347.740986)
		(width 0.14224)
		(layer "In6.Cu")
		(net "P5E_CPU1_P0_TX_DN<0>")
	)
	(segment
		(start 40.018716 -378.855732)
		(end 40.155876 -378.992892)
		(width 0.14224)
		(layer "In6.Cu")
		(net "P5E_CPU1_P0_TX_DN<0>")
	)
	(segment
		(start 47.35449 -363.879892)
		(end 44.938696 -364.767876)
		(width 0.14224)
		(layer "In6.Cu")
		(net "P5E_CPU1_P0_TX_DN<0>")
	)
	(segment
		(start 40.155876 -380.278894)
		(end 40.155876 -380.705614)
		(width 0.14224)
		(layer "In6.Cu")
		(net "P5E_CPU1_P0_TX_DN<0>")
	)
	(segment
		(start 40.018716 -375.847356)
		(end 40.018716 -376.289062)
		(width 0.14224)
		(layer "In6.Cu")
		(net "P5E_CPU1_P0_TX_DN<0>")
	)
	(segment
		(start 63.916306 -356.546912)
		(end 55.014368 -360.234738)
		(width 0.14224)
		(layer "In6.Cu")
		(net "P5E_CPU1_P0_TX_DN<0>")
	)
	(segment
		(start 97.794064 -284.293818)
		(end 97.793302 -284.294326)
		(width 0.1143)
		(layer "In6.Cu")
		(net "P5E_CPU1_P0_TX_DN<0>")
	)
	(segment
		(start 97.29343 -293.83101)
		(end 97.363026 -293.87165)
		(width 0.1143)
		(layer "In6.Cu")
		(net "P5E_CPU1_P0_TX_DN<0>")
	)
	(segment
		(start 47.35449 -363.879638)
		(end 47.35449 -363.879892)
		(width 0.14224)
		(layer "In6.Cu")
		(net "P5E_CPU1_P0_TX_DN<0>")
	)
	(segment
		(start 43.127422 -365.796576)
		(end 40.977566 -367.946432)
		(width 0.14224)
		(layer "In6.Cu")
		(net "P5E_CPU1_P0_TX_DN<0>")
	)
	(segment
		(start 96.712024 -296.354754)
		(end 96.712024 -299.521626)
		(width 0.14224)
		(layer "In6.Cu")
		(net "P5E_CPU1_P0_TX_DN<0>")
	)
	(segment
		(start 115.5573 -332.173834)
		(end 116.813076 -339.161628)
		(width 0.14224)
		(layer "In6.Cu")
		(net "P5E_CPU1_P0_TX_DN<0>")
	)
	(segment
		(start 96.855026 -285.913322)
		(end 96.852232 -285.914846)
		(width 0.1143)
		(layer "In6.Cu")
		(net "P5E_CPU1_P0_TX_DN<0>")
	)
	(segment
		(start 116.831364 -339.299804)
		(end 116.839492 -339.41766)
		(width 0.14224)
		(layer "In6.Cu")
		(net "P5E_CPU1_P0_TX_DN<0>")
	)
	(segment
		(start 98.30308 -283.460952)
		(end 98.233484 -283.501592)
		(width 0.1143)
		(layer "In6.Cu")
		(net "P5E_CPU1_P0_TX_DN<0>")
	)
	(segment
		(start 71.589646 -356.53726)
		(end 63.965074 -356.53726)
		(width 0.14224)
		(layer "In6.Cu")
		(net "P5E_CPU1_P0_TX_DN<0>")
	)
	(segment
		(start 115.13693 -330.8985)
		(end 115.506754 -331.979016)
		(width 0.14224)
		(layer "In6.Cu")
		(net "P5E_CPU1_P0_TX_DN<0>")
	)
	(segment
		(start 96.712024 -296.326306)
		(end 96.712024 -296.354754)
		(width 0.1143)
		(layer "In6.Cu")
		(net "P5E_CPU1_P0_TX_DN<0>")
	)
	(segment
		(start 97.363026 -294.800782)
		(end 97.29343 -294.841422)
		(width 0.1143)
		(layer "In6.Cu")
		(net "P5E_CPU1_P0_TX_DN<0>")
	)
	(segment
		(start 96.666304 -296.280586)
		(end 96.712024 -296.326306)
		(width 0.1143)
		(layer "In6.Cu")
		(net "P5E_CPU1_P0_TX_DN<0>")
	)
	(segment
		(start 40.018716 -380.842774)
		(end 40.018716 -381.225552)
		(width 0.14224)
		(layer "In6.Cu")
		(net "P5E_CPU1_P0_TX_DN<0>")
	)
	(segment
		(start 40.018716 -376.990102)
		(end 40.018716 -377.647962)
		(width 0.14224)
		(layer "In6.Cu")
		(net "P5E_CPU1_P0_TX_DN<0>")
	)
	(segment
		(start 98.62312 -282.996386)
		(end 98.540316 -283.07919)
		(width 0.1143)
		(layer "In6.Cu")
		(net "P5E_CPU1_P0_TX_DN<0>")
	)
	(segment
		(start 73.327768 -357.108252)
		(end 72.282558 -356.675182)
		(width 0.14224)
		(layer "In6.Cu")
		(net "P5E_CPU1_P0_TX_DN<0>")
	)
	(segment
		(start 40.018716 -376.289062)
		(end 40.155876 -376.426222)
		(width 0.14224)
		(layer "In6.Cu")
		(net "P5E_CPU1_P0_TX_DN<0>")
	)
	(segment
		(start 43.387264 -365.604298)
		(end 43.127422 -365.796576)
		(width 0.14224)
		(layer "In6.Cu")
		(net "P5E_CPU1_P0_TX_DN<0>")
	)
	(segment
		(start 113.879122 -347.740986)
		(end 100.250752 -356.86365)
		(width 0.14224)
		(layer "In6.Cu")
		(net "P5E_CPU1_P0_TX_DN<0>")
	)
	(segment
		(start 40.155876 -377.785122)
		(end 40.155876 -378.211842)
		(width 0.14224)
		(layer "In6.Cu")
		(net "P5E_CPU1_P0_TX_DN<0>")
	)
	(segment
		(start 40.155876 -378.992892)
		(end 40.155876 -379.419612)
		(width 0.14224)
		(layer "In6.Cu")
		(net "P5E_CPU1_P0_TX_DN<0>")
	)
	(segment
		(start 97.78746 -284.297628)
		(end 97.78619 -284.29839)
		(width 0.1143)
		(layer "In6.Cu")
		(net "P5E_CPU1_P0_TX_DN<0>")
	)
	(segment
		(start 107.523534 -319.880996)
		(end 112.606836 -326.07631)
		(width 0.14224)
		(layer "In6.Cu")
		(net "P5E_CPU1_P0_TX_DN<0>")
	)
	(segment
		(start 40.66159 -381.79629)
		(end 41.139872 -381.79629)
		(width 0.14224)
		(layer "In6.Cu")
		(net "P5E_CPU1_P0_TX_DN<0>")
	)
	(segment
		(start 101.311964 -310.658764)
		(end 107.0229 -319.206372)
		(width 0.14224)
		(layer "In6.Cu")
		(net "P5E_CPU1_P0_TX_DN<0>")
	)
	(segment
		(start 96.666304 -295.942004)
		(end 96.666304 -296.280586)
		(width 0.1143)
		(layer "In6.Cu")
		(net "P5E_CPU1_P0_TX_DN<0>")
	)
	(segment
		(start 97.79508 -284.29331)
		(end 97.794064 -284.293818)
		(width 0.1143)
		(layer "In6.Cu")
		(net "P5E_CPU1_P0_TX_DN<0>")
	)
	(segment
		(start 97.83318 -284.270958)
		(end 97.796604 -284.292294)
		(width 0.1143)
		(layer "In6.Cu")
		(net "P5E_CPU1_P0_TX_DN<0>")
	)
	(segment
		(start 97.29343 -287.350962)
		(end 97.360486 -287.390078)
		(width 0.1143)
		(layer "In6.Cu")
		(net "P5E_CPU1_P0_TX_DN<0>")
	)
	(segment
		(start 40.155876 -378.211842)
		(end 40.018716 -378.349002)
		(width 0.14224)
		(layer "In6.Cu")
		(net "P5E_CPU1_P0_TX_DN<0>")
	)
	(segment
		(start 41.139872 -381.79629)
		(end 41.430702 -381.50546)
		(width 0.14224)
		(layer "In6.Cu")
		(net "P5E_CPU1_P0_TX_DN<0>")
	)
	(segment
		(start 97.789746 -284.296358)
		(end 97.788222 -284.29712)
		(width 0.1143)
		(layer "In6.Cu")
		(net "P5E_CPU1_P0_TX_DN<0>")
	)
	(segment
		(start 40.067992 -381.34417)
		(end 40.420036 -381.696214)
		(width 0.14224)
		(layer "In6.Cu")
		(net "P5E_CPU1_P0_TX_DN<0>")
	)
	(segment
		(start 97.363026 -285.080964)
		(end 97.29343 -285.121604)
		(width 0.1143)
		(layer "In6.Cu")
		(net "P5E_CPU1_P0_TX_DN<0>")
	)
	(segment
		(start 112.708436 -326.229726)
		(end 115.069874 -330.743052)
		(width 0.14224)
		(layer "In6.Cu")
		(net "P5E_CPU1_P0_TX_DN<0>")
	)
	(segment
		(start 40.701722 -369.05057)
		(end 40.701722 -373.180356)
		(width 0.14224)
		(layer "In6.Cu")
		(net "P5E_CPU1_P0_TX_DN<0>")
	)
	(segment
		(start 97.363026 -288.320988)
		(end 97.291398 -288.362644)
		(width 0.1143)
		(layer "In6.Cu")
		(net "P5E_CPU1_P0_TX_DN<0>")
	)
	(segment
		(start 40.155876 -379.419612)
		(end 40.018716 -379.556772)
		(width 0.14224)
		(layer "In6.Cu")
		(net "P5E_CPU1_P0_TX_DN<0>")
	)
	(segment
		(start 40.155876 -380.705614)
		(end 40.018716 -380.842774)
		(width 0.14224)
		(layer "In6.Cu")
		(net "P5E_CPU1_P0_TX_DN<0>")
	)
	(segment
		(start 40.018716 -379.556772)
		(end 40.018716 -380.141734)
		(width 0.14224)
		(layer "In6.Cu")
		(net "P5E_CPU1_P0_TX_DN<0>")
	)
	(segment
		(start 97.29343 -288.970974)
		(end 97.363026 -289.011614)
		(width 0.1143)
		(layer "In6.Cu")
		(net "P5E_CPU1_P0_TX_DN<0>")
	)
	(segment
		(start 97.792032 -284.295088)
		(end 97.790508 -284.29585)
		(width 0.1143)
		(layer "In6.Cu")
		(net "P5E_CPU1_P0_TX_DN<0>")
	)
	(segment
		(start 40.067992 -381.343916)
		(end 40.067992 -381.34417)
		(width 0.14224)
		(layer "In6.Cu")
		(net "P5E_CPU1_P0_TX_DN<0>")
	)
	(segment
		(start 116.313204 -342.646254)
		(end 114.532918 -346.943934)
		(width 0.14224)
		(layer "In6.Cu")
		(net "P5E_CPU1_P0_TX_DN<0>")
	)
	(segment
		(start 40.018716 -377.647962)
		(end 40.155876 -377.785122)
		(width 0.14224)
		(layer "In6.Cu")
		(net "P5E_CPU1_P0_TX_DN<0>")
	)
	(segment
		(start 98.961448 -357.255318)
		(end 74.068686 -357.255318)
		(width 0.14224)
		(layer "In6.Cu")
		(net "P5E_CPU1_P0_TX_DN<0>")
	)
	(segment
		(start 97.363026 -289.940746)
		(end 97.29343 -289.981386)
		(width 0.1143)
		(layer "In6.Cu")
		(net "P5E_CPU1_P0_TX_DN<0>")
	)
	(segment
		(start 97.78619 -284.29839)
		(end 97.78365 -284.29966)
		(width 0.1143)
		(layer "In6.Cu")
		(net "P5E_CPU1_P0_TX_DN<0>")
	)
	(segment
		(start 40.155876 -376.852942)
		(end 40.018716 -376.990102)
		(width 0.14224)
		(layer "In6.Cu")
		(net "P5E_CPU1_P0_TX_DN<0>")
	)
	(segment
		(start 97.793302 -284.294326)
		(end 97.792032 -284.295088)
		(width 0.1143)
		(layer "In6.Cu")
		(net "P5E_CPU1_P0_TX_DN<0>")
	)
	(arc
		(start 97.29343 -285.121604)
		(mid 97.178003 -285.25498)
		(end 97.136458 -285.426404)
		(width 0.1143)
		(layer "In6.Cu")
		(net "P5E_CPU1_P0_TX_DN<0>")
	)
	(arc
		(start 98.536506 -283.10205)
		(mid 98.455073 -283.304448)
		(end 98.30308 -283.460952)
		(width 0.1143)
		(layer "In6.Cu")
		(net "P5E_CPU1_P0_TX_DN<0>")
	)
	(arc
		(start 98.076512 -283.806392)
		(mid 98.011997 -284.068611)
		(end 97.83318 -284.270958)
		(width 0.1143)
		(layer "In6.Cu")
		(net "P5E_CPU1_P0_TX_DN<0>")
	)
	(arc
		(start 74.068686 -357.255318)
		(mid 73.690986 -357.218269)
		(end 73.327768 -357.108252)
		(width 0.14224)
		(layer "In6.Cu")
		(net "P5E_CPU1_P0_TX_DN<0>")
	)
	(arc
		(start 97.136966 -295.127426)
		(mid 97.073092 -295.396443)
		(end 96.916748 -295.624504)
		(width 0.1143)
		(layer "In6.Cu")
		(net "P5E_CPU1_P0_TX_DN<0>")
	)
	(arc
		(start 115.506754 -331.979016)
		(mid 115.535726 -332.075465)
		(end 115.5573 -332.173834)
		(width 0.14224)
		(layer "In6.Cu")
		(net "P5E_CPU1_P0_TX_DN<0>")
	)
	(arc
		(start 97.136458 -287.046162)
		(mid 97.178007 -287.217584)
		(end 97.29343 -287.350962)
		(width 0.1143)
		(layer "In6.Cu")
		(net "P5E_CPU1_P0_TX_DN<0>")
	)
	(arc
		(start 97.29343 -291.601398)
		(mid 97.136453 -291.906198)
		(end 97.29343 -292.210998)
		(width 0.1143)
		(layer "In6.Cu")
		(net "P5E_CPU1_P0_TX_DN<0>")
	)
	(arc
		(start 40.018716 -381.225552)
		(mid 40.031575 -381.289637)
		(end 40.067992 -381.343916)
		(width 0.14224)
		(layer "In6.Cu")
		(net "P5E_CPU1_P0_TX_DN<0>")
	)
	(arc
		(start 40.420036 -381.696214)
		(mid 40.530862 -381.770266)
		(end 40.66159 -381.79629)
		(width 0.14224)
		(layer "In6.Cu")
		(net "P5E_CPU1_P0_TX_DN<0>")
	)
	(arc
		(start 40.701722 -373.180356)
		(mid 40.697422 -373.271339)
		(end 40.684196 -373.361458)
		(width 0.14224)
		(layer "In6.Cu")
		(net "P5E_CPU1_P0_TX_DN<0>")
	)
	(arc
		(start 97.363026 -293.87165)
		(mid 97.606353 -294.336216)
		(end 97.363026 -294.800782)
		(width 0.1143)
		(layer "In6.Cu")
		(net "P5E_CPU1_P0_TX_DN<0>")
	)
	(arc
		(start 112.606836 -326.07631)
		(mid 112.661564 -326.150416)
		(end 112.708436 -326.229726)
		(width 0.14224)
		(layer "In6.Cu")
		(net "P5E_CPU1_P0_TX_DN<0>")
	)
	(arc
		(start 63.965074 -356.53726)
		(mid 63.940221 -356.539706)
		(end 63.916306 -356.546912)
		(width 0.14224)
		(layer "In6.Cu")
		(net "P5E_CPU1_P0_TX_DN<0>")
	)
	(arc
		(start 40.977566 -367.946432)
		(mid 40.937148 -367.995379)
		(end 40.9067 -368.05108)
		(width 0.14224)
		(layer "In6.Cu")
		(net "P5E_CPU1_P0_TX_DN<0>")
	)
	(arc
		(start 115.069874 -330.743052)
		(mid 115.106352 -330.819503)
		(end 115.13693 -330.8985)
		(width 0.14224)
		(layer "In6.Cu")
		(net "P5E_CPU1_P0_TX_DN<0>")
	)
	(arc
		(start 40.363394 -374.326404)
		(mid 40.105982 -375.067599)
		(end 40.018716 -375.847356)
		(width 0.14224)
		(layer "In6.Cu")
		(net "P5E_CPU1_P0_TX_DN<0>")
	)
	(arc
		(start 97.29343 -294.841422)
		(mid 97.182412 -294.966493)
		(end 97.136966 -295.127426)
		(width 0.1143)
		(layer "In6.Cu")
		(net "P5E_CPU1_P0_TX_DN<0>")
	)
	(arc
		(start 116.813076 -339.161628)
		(mid 116.82391 -339.230492)
		(end 116.831364 -339.299804)
		(width 0.14224)
		(layer "In6.Cu")
		(net "P5E_CPU1_P0_TX_DN<0>")
	)
	(arc
		(start 97.29343 -289.981386)
		(mid 97.136453 -290.286186)
		(end 97.29343 -290.590986)
		(width 0.1143)
		(layer "In6.Cu")
		(net "P5E_CPU1_P0_TX_DN<0>")
	)
	(arc
		(start 96.852232 -285.914846)
		(mid 96.716151 -286.050694)
		(end 96.666304 -286.23641)
		(width 0.1143)
		(layer "In6.Cu")
		(net "P5E_CPU1_P0_TX_DN<0>")
	)
	(arc
		(start 98.233484 -283.501592)
		(mid 98.118057 -283.634968)
		(end 98.076512 -283.806392)
		(width 0.1143)
		(layer "In6.Cu")
		(net "P5E_CPU1_P0_TX_DN<0>")
	)
	(arc
		(start 40.9067 -368.05108)
		(mid 40.753491 -368.540423)
		(end 40.701722 -369.05057)
		(width 0.14224)
		(layer "In6.Cu")
		(net "P5E_CPU1_P0_TX_DN<0>")
	)
	(arc
		(start 97.136458 -285.426404)
		(mid 97.071943 -285.688623)
		(end 96.893126 -285.89097)
		(width 0.1143)
		(layer "In6.Cu")
		(net "P5E_CPU1_P0_TX_DN<0>")
	)
	(arc
		(start 97.363026 -292.251638)
		(mid 97.606353 -292.716204)
		(end 97.363026 -293.18077)
		(width 0.1143)
		(layer "In6.Cu")
		(net "P5E_CPU1_P0_TX_DN<0>")
	)
	(arc
		(start 107.0229 -319.206372)
		(mid 107.264994 -319.549786)
		(end 107.523534 -319.880996)
		(width 0.14224)
		(layer "In6.Cu")
		(net "P5E_CPU1_P0_TX_DN<0>")
	)
	(arc
		(start 44.938696 -364.767876)
		(mid 44.133179 -365.13081)
		(end 43.387264 -365.604298)
		(width 0.14224)
		(layer "In6.Cu")
		(net "P5E_CPU1_P0_TX_DN<0>")
	)
	(arc
		(start 114.532918 -346.943934)
		(mid 114.265162 -347.390847)
		(end 113.879376 -347.740986)
		(width 0.14224)
		(layer "In6.Cu")
		(net "P5E_CPU1_P0_TX_DN<0>")
	)
	(arc
		(start 97.363026 -290.631626)
		(mid 97.606353 -291.096192)
		(end 97.363026 -291.560758)
		(width 0.1143)
		(layer "In6.Cu")
		(net "P5E_CPU1_P0_TX_DN<0>")
	)
	(arc
		(start 97.363026 -289.011614)
		(mid 97.606353 -289.47618)
		(end 97.363026 -289.940746)
		(width 0.1143)
		(layer "In6.Cu")
		(net "P5E_CPU1_P0_TX_DN<0>")
	)
	(arc
		(start 96.666304 -286.23641)
		(mid 96.707066 -286.406294)
		(end 96.820482 -286.539178)
		(width 0.1143)
		(layer "In6.Cu")
		(net "P5E_CPU1_P0_TX_DN<0>")
	)
	(arc
		(start 97.360486 -287.390078)
		(mid 97.606374 -287.854872)
		(end 97.363026 -288.320988)
		(width 0.1143)
		(layer "In6.Cu")
		(net "P5E_CPU1_P0_TX_DN<0>")
	)
	(arc
		(start 96.713548 -295.827958)
		(mid 96.678557 -295.880282)
		(end 96.666304 -295.942004)
		(width 0.1143)
		(layer "In6.Cu")
		(net "P5E_CPU1_P0_TX_DN<0>")
	)
	(arc
		(start 97.136458 -288.666174)
		(mid 97.178007 -288.837596)
		(end 97.29343 -288.970974)
		(width 0.1143)
		(layer "In6.Cu")
		(net "P5E_CPU1_P0_TX_DN<0>")
	)
	(arc
		(start 54.233318 -360.98099)
		(mid 54.141721 -361.056164)
		(end 54.03723 -361.112054)
		(width 0.14224)
		(layer "In6.Cu")
		(net "P5E_CPU1_P0_TX_DN<0>")
	)
	(arc
		(start 97.762314 -284.312106)
		(mid 97.647638 -284.44544)
		(end 97.606358 -284.616398)
		(width 0.1143)
		(layer "In6.Cu")
		(net "P5E_CPU1_P0_TX_DN<0>")
	)
	(arc
		(start 40.684196 -373.361458)
		(mid 40.553883 -373.853934)
		(end 40.363394 -374.326404)
		(width 0.14224)
		(layer "In6.Cu")
		(net "P5E_CPU1_P0_TX_DN<0>")
	)
	(arc
		(start 98.540316 -283.07919)
		(mid 98.538528 -283.090639)
		(end 98.536506 -283.10205)
		(width 0.1143)
		(layer "In6.Cu")
		(net "P5E_CPU1_P0_TX_DN<0>")
	)
	(arc
		(start 97.606358 -284.616398)
		(mid 97.541843 -284.878617)
		(end 97.363026 -285.080964)
		(width 0.1143)
		(layer "In6.Cu")
		(net "P5E_CPU1_P0_TX_DN<0>")
	)
	(arc
		(start 72.282558 -356.675182)
		(mid 71.942895 -356.572102)
		(end 71.589646 -356.53726)
		(width 0.14224)
		(layer "In6.Cu")
		(net "P5E_CPU1_P0_TX_DN<0>")
	)
	(arc
		(start 116.839492 -339.41766)
		(mid 116.763817 -341.062519)
		(end 116.313204 -342.646254)
		(width 0.14224)
		(layer "In6.Cu")
		(net "P5E_CPU1_P0_TX_DN<0>")
	)
	(arc
		(start 101.252274 -310.547258)
		(mid 101.279381 -310.604477)
		(end 101.311964 -310.658764)
		(width 0.14224)
		(layer "In6.Cu")
		(net "P5E_CPU1_P0_TX_DN<0>")
	)
	(arc
		(start 97.29343 -293.22141)
		(mid 97.136453 -293.52621)
		(end 97.29343 -293.83101)
		(width 0.1143)
		(layer "In6.Cu")
		(net "P5E_CPU1_P0_TX_DN<0>")
	)
	(arc
		(start 97.291398 -288.362644)
		(mid 97.177469 -288.495791)
		(end 97.136458 -288.666174)
		(width 0.1143)
		(layer "In6.Cu")
		(net "P5E_CPU1_P0_TX_DN<0>")
	)
	(arc
		(start 96.893126 -286.581596)
		(mid 97.071939 -286.783946)
		(end 97.136458 -287.046162)
		(width 0.1143)
		(layer "In6.Cu")
		(net "P5E_CPU1_P0_TX_DN<0>")
	)
	(arc
		(start 96.712024 -299.521626)
		(mid 96.718278 -299.584557)
		(end 96.736662 -299.64507)
		(width 0.14224)
		(layer "In6.Cu")
		(net "P5E_CPU1_P0_TX_DN<0>")
	)
	(arc
		(start 100.250752 -356.86365)
		(mid 99.635187 -357.15523)
		(end 98.961448 -357.255318)
		(width 0.14224)
		(layer "In6.Cu")
		(net "P5E_CPU1_P0_TX_DN<0>")
	)
	(arc
		(start 55.014368 -360.234738)
		(mid 54.958599 -360.264503)
		(end 54.90972 -360.304588)
		(width 0.14224)
		(layer "In6.Cu")
		(net "P5E_CPU1_P0_TX_DN<0>")
	)
	(segment
		(start 107.847892 -271.390364)
		(end 107.38104 -271.656302)
		(width 0.12954)
		(layer "F.Cu")
		(net "P5E_CPU1_P0_RX_DP<9>")
	)
	(segment
		(start 58.470546 -386.003292)
		(end 58.991246 -386.003292)
		(width 0.127)
		(layer "F.Cu")
		(net "P5E_CPU1_P0_RX_DP<9>")
	)
	(segment
		(start 59.815222 -372.645686)
		(end 64.050672 -367.076736)
		(width 0.14224)
		(layer "In15.Cu")
		(net "P5E_CPU1_P0_RX_DP<9>")
	)
	(segment
		(start 105.596182 -295.239948)
		(end 105.596436 -295.239694)
		(width 0.1143)
		(layer "In15.Cu")
		(net "P5E_CPU1_P0_RX_DP<9>")
	)
	(segment
		(start 106.26598 -272.94713)
		(end 106.293158 -272.930874)
		(width 0.1143)
		(layer "In15.Cu")
		(net "P5E_CPU1_P0_RX_DP<9>")
	)
	(segment
		(start 148.97227 -359.214166)
		(end 148.97227 -357.84536)
		(width 0.14224)
		(layer "In15.Cu")
		(net "P5E_CPU1_P0_RX_DP<9>")
	)
	(segment
		(start 130.28168 -361.113578)
		(end 129.97434 -360.806238)
		(width 0.14224)
		(layer "In15.Cu")
		(net "P5E_CPU1_P0_RX_DP<9>")
	)
	(segment
		(start 105.823004 -274.43176)
		(end 105.783888 -274.4089)
		(width 0.1143)
		(layer "In15.Cu")
		(net "P5E_CPU1_P0_RX_DP<9>")
	)
	(segment
		(start 105.783888 -276.028912)
		(end 105.753408 -276.011132)
		(width 0.1143)
		(layer "In15.Cu")
		(net "P5E_CPU1_P0_RX_DP<9>")
	)
	(segment
		(start 105.783888 -293.84879)
		(end 105.753408 -293.83101)
		(width 0.1143)
		(layer "In15.Cu")
		(net "P5E_CPU1_P0_RX_DP<9>")
	)
	(segment
		(start 107.000294 -271.739106)
		(end 107.083098 -271.656302)
		(width 0.1143)
		(layer "In15.Cu")
		(net "P5E_CPU1_P0_RX_DP<9>")
	)
	(segment
		(start 105.823004 -293.87165)
		(end 105.783888 -293.84879)
		(width 0.1143)
		(layer "In15.Cu")
		(net "P5E_CPU1_P0_RX_DP<9>")
	)
	(segment
		(start 105.783888 -274.4089)
		(end 105.753408 -274.39112)
		(width 0.1143)
		(layer "In15.Cu")
		(net "P5E_CPU1_P0_RX_DP<9>")
	)
	(segment
		(start 105.823004 -292.251638)
		(end 105.783888 -292.228778)
		(width 0.1143)
		(layer "In15.Cu")
		(net "P5E_CPU1_P0_RX_DP<9>")
	)
	(segment
		(start 105.823004 -279.291796)
		(end 105.783888 -279.268936)
		(width 0.1143)
		(layer "In15.Cu")
		(net "P5E_CPU1_P0_RX_DP<9>")
	)
	(segment
		(start 58.991246 -386.003292)
		(end 59.086242 -385.649216)
		(width 0.14224)
		(layer "In15.Cu")
		(net "P5E_CPU1_P0_RX_DP<9>")
	)
	(segment
		(start 105.753408 -273.78152)
		(end 105.783888 -273.76374)
		(width 0.1143)
		(layer "In15.Cu")
		(net "P5E_CPU1_P0_RX_DP<9>")
	)
	(segment
		(start 105.596436 -295.239694)
		(end 105.596436 -295.146222)
		(width 0.1143)
		(layer "In15.Cu")
		(net "P5E_CPU1_P0_RX_DP<9>")
	)
	(segment
		(start 106.693462 -272.161508)
		(end 106.723942 -272.143728)
		(width 0.1143)
		(layer "In15.Cu")
		(net "P5E_CPU1_P0_RX_DP<9>")
	)
	(segment
		(start 105.753408 -278.641556)
		(end 105.783888 -278.623776)
		(width 0.1143)
		(layer "In15.Cu")
		(net "P5E_CPU1_P0_RX_DP<9>")
	)
	(segment
		(start 130.28168 -361.918758)
		(end 130.28168 -361.113578)
		(width 0.14224)
		(layer "In15.Cu")
		(net "P5E_CPU1_P0_RX_DP<9>")
	)
	(segment
		(start 148.941282 -357.688896)
		(end 148.749512 -357.2256)
		(width 0.14224)
		(layer "In15.Cu")
		(net "P5E_CPU1_P0_RX_DP<9>")
	)
	(segment
		(start 117.702076 -331.584554)
		(end 105.295446 -301.63135)
		(width 0.14224)
		(layer "In15.Cu")
		(net "P5E_CPU1_P0_RX_DP<9>")
	)
	(segment
		(start 118.295166 -360.806238)
		(end 118.152926 -360.663998)
		(width 0.14224)
		(layer "In15.Cu")
		(net "P5E_CPU1_P0_RX_DP<9>")
	)
	(segment
		(start 105.783888 -280.888948)
		(end 105.753408 -280.871168)
		(width 0.1143)
		(layer "In15.Cu")
		(net "P5E_CPU1_P0_RX_DP<9>")
	)
	(segment
		(start 59.260486 -385.548632)
		(end 59.348624 -385.460494)
		(width 0.14224)
		(layer "In15.Cu")
		(net "P5E_CPU1_P0_RX_DP<9>")
	)
	(segment
		(start 105.753408 -280.261568)
		(end 105.783888 -280.243788)
		(width 0.1143)
		(layer "In15.Cu")
		(net "P5E_CPU1_P0_RX_DP<9>")
	)
	(segment
		(start 105.783888 -277.003764)
		(end 105.823004 -276.980904)
		(width 0.1143)
		(layer "In15.Cu")
		(net "P5E_CPU1_P0_RX_DP<9>")
	)
	(segment
		(start 105.823004 -280.911808)
		(end 105.783888 -280.888948)
		(width 0.1143)
		(layer "In15.Cu")
		(net "P5E_CPU1_P0_RX_DP<9>")
	)
	(segment
		(start 105.245662 -295.829736)
		(end 105.47985 -295.595294)
		(width 0.1143)
		(layer "In15.Cu")
		(net "P5E_CPU1_P0_RX_DP<9>")
	)
	(segment
		(start 105.783888 -288.343848)
		(end 105.823004 -288.320988)
		(width 0.1143)
		(layer "In15.Cu")
		(net "P5E_CPU1_P0_RX_DP<9>")
	)
	(segment
		(start 105.823004 -290.631626)
		(end 105.783888 -290.608766)
		(width 0.1143)
		(layer "In15.Cu")
		(net "P5E_CPU1_P0_RX_DP<9>")
	)
	(segment
		(start 105.823004 -285.771844)
		(end 105.783888 -285.748984)
		(width 0.1143)
		(layer "In15.Cu")
		(net "P5E_CPU1_P0_RX_DP<9>")
	)
	(segment
		(start 105.783888 -285.748984)
		(end 105.753408 -285.731204)
		(width 0.1143)
		(layer "In15.Cu")
		(net "P5E_CPU1_P0_RX_DP<9>")
	)
	(segment
		(start 105.596182 -295.315386)
		(end 105.596182 -295.239948)
		(width 0.1143)
		(layer "In15.Cu")
		(net "P5E_CPU1_P0_RX_DP<9>")
	)
	(segment
		(start 148.537168 -356.967028)
		(end 131.839208 -345.810332)
		(width 0.14224)
		(layer "In15.Cu")
		(net "P5E_CPU1_P0_RX_DP<9>")
	)
	(segment
		(start 105.823004 -277.671784)
		(end 105.783888 -277.648924)
		(width 0.1143)
		(layer "In15.Cu")
		(net "P5E_CPU1_P0_RX_DP<9>")
	)
	(segment
		(start 59.00039 -374.974612)
		(end 59.590686 -373.081042)
		(width 0.14224)
		(layer "In15.Cu")
		(net "P5E_CPU1_P0_RX_DP<9>")
	)
	(segment
		(start 75.366372 -362.749084)
		(end 105.625138 -362.749084)
		(width 0.14224)
		(layer "In15.Cu")
		(net "P5E_CPU1_P0_RX_DP<9>")
	)
	(segment
		(start 59.086242 -385.649216)
		(end 59.260486 -385.548632)
		(width 0.14224)
		(layer "In15.Cu")
		(net "P5E_CPU1_P0_RX_DP<9>")
	)
	(segment
		(start 105.823004 -282.53182)
		(end 105.783888 -282.50896)
		(width 0.1143)
		(layer "In15.Cu")
		(net "P5E_CPU1_P0_RX_DP<9>")
	)
	(segment
		(start 105.753408 -285.121604)
		(end 105.783888 -285.103824)
		(width 0.1143)
		(layer "In15.Cu")
		(net "P5E_CPU1_P0_RX_DP<9>")
	)
	(segment
		(start 105.823004 -276.051772)
		(end 105.783888 -276.028912)
		(width 0.1143)
		(layer "In15.Cu")
		(net "P5E_CPU1_P0_RX_DP<9>")
	)
	(segment
		(start 105.820464 -287.390078)
		(end 105.753408 -287.350962)
		(width 0.1143)
		(layer "In15.Cu")
		(net "P5E_CPU1_P0_RX_DP<9>")
	)
	(segment
		(start 105.753408 -293.22141)
		(end 105.783888 -293.20363)
		(width 0.1143)
		(layer "In15.Cu")
		(net "P5E_CPU1_P0_RX_DP<9>")
	)
	(segment
		(start 106.723942 -272.143728)
		(end 106.763058 -272.120868)
		(width 0.1143)
		(layer "In15.Cu")
		(net "P5E_CPU1_P0_RX_DP<9>")
	)
	(segment
		(start 105.783888 -292.228778)
		(end 105.753408 -292.210998)
		(width 0.1143)
		(layer "In15.Cu")
		(net "P5E_CPU1_P0_RX_DP<9>")
	)
	(segment
		(start 105.783888 -283.483812)
		(end 105.823004 -283.460952)
		(width 0.1143)
		(layer "In15.Cu")
		(net "P5E_CPU1_P0_RX_DP<9>")
	)
	(segment
		(start 105.783888 -273.76374)
		(end 105.823004 -273.74088)
		(width 0.1143)
		(layer "In15.Cu")
		(net "P5E_CPU1_P0_RX_DP<9>")
	)
	(segment
		(start 105.783888 -281.8638)
		(end 105.823004 -281.84094)
		(width 0.1143)
		(layer "In15.Cu")
		(net "P5E_CPU1_P0_RX_DP<9>")
	)
	(segment
		(start 105.783888 -275.383752)
		(end 105.823004 -275.360892)
		(width 0.1143)
		(layer "In15.Cu")
		(net "P5E_CPU1_P0_RX_DP<9>")
	)
	(segment
		(start 105.783888 -289.963606)
		(end 105.823004 -289.940746)
		(width 0.1143)
		(layer "In15.Cu")
		(net "P5E_CPU1_P0_RX_DP<9>")
	)
	(segment
		(start 106.222292 -272.972022)
		(end 106.222546 -272.972276)
		(width 0.1143)
		(layer "In15.Cu")
		(net "P5E_CPU1_P0_RX_DP<9>")
	)
	(segment
		(start 59.032648 -384.731006)
		(end 59.035696 -384.3528)
		(width 0.14224)
		(layer "In15.Cu")
		(net "P5E_CPU1_P0_RX_DP<9>")
	)
	(segment
		(start 105.783888 -278.623776)
		(end 105.823004 -278.600916)
		(width 0.1143)
		(layer "In15.Cu")
		(net "P5E_CPU1_P0_RX_DP<9>")
	)
	(segment
		(start 105.783888 -284.128972)
		(end 105.753408 -284.111192)
		(width 0.1143)
		(layer "In15.Cu")
		(net "P5E_CPU1_P0_RX_DP<9>")
	)
	(segment
		(start 105.751376 -286.742632)
		(end 105.783888 -286.723836)
		(width 0.1143)
		(layer "In15.Cu")
		(net "P5E_CPU1_P0_RX_DP<9>")
	)
	(segment
		(start 105.783888 -288.988754)
		(end 105.753408 -288.970974)
		(width 0.1143)
		(layer "In15.Cu")
		(net "P5E_CPU1_P0_RX_DP<9>")
	)
	(segment
		(start 105.783888 -285.103824)
		(end 105.823004 -285.080964)
		(width 0.1143)
		(layer "In15.Cu")
		(net "P5E_CPU1_P0_RX_DP<9>")
	)
	(segment
		(start 105.783888 -279.268936)
		(end 105.753408 -279.251156)
		(width 0.1143)
		(layer "In15.Cu")
		(net "P5E_CPU1_P0_RX_DP<9>")
	)
	(segment
		(start 64.86398 -366.481868)
		(end 75.3237 -362.75645)
		(width 0.14224)
		(layer "In15.Cu")
		(net "P5E_CPU1_P0_RX_DP<9>")
	)
	(segment
		(start 59.035696 -384.3528)
		(end 59.340496 -384.048)
		(width 0.14224)
		(layer "In15.Cu")
		(net "P5E_CPU1_P0_RX_DP<9>")
	)
	(segment
		(start 148.608796 -359.83037)
		(end 148.793454 -359.645712)
		(width 0.14224)
		(layer "In15.Cu")
		(net "P5E_CPU1_P0_RX_DP<9>")
	)
	(segment
		(start 105.783888 -280.243788)
		(end 105.823004 -280.220928)
		(width 0.1143)
		(layer "In15.Cu")
		(net "P5E_CPU1_P0_RX_DP<9>")
	)
	(segment
		(start 106.222546 -272.972276)
		(end 106.26598 -272.94713)
		(width 0.1143)
		(layer "In15.Cu")
		(net "P5E_CPU1_P0_RX_DP<9>")
	)
	(segment
		(start 105.753408 -294.841422)
		(end 105.823004 -294.800782)
		(width 0.1143)
		(layer "In15.Cu")
		(net "P5E_CPU1_P0_RX_DP<9>")
	)
	(segment
		(start 129.97434 -360.806238)
		(end 118.295166 -360.806238)
		(width 0.14224)
		(layer "In15.Cu")
		(net "P5E_CPU1_P0_RX_DP<9>")
	)
	(segment
		(start 59.348624 -385.046982)
		(end 59.032648 -384.731006)
		(width 0.14224)
		(layer "In15.Cu")
		(net "P5E_CPU1_P0_RX_DP<9>")
	)
	(segment
		(start 105.753408 -289.981386)
		(end 105.783888 -289.963606)
		(width 0.1143)
		(layer "In15.Cu")
		(net "P5E_CPU1_P0_RX_DP<9>")
	)
	(segment
		(start 59.348624 -385.460494)
		(end 59.348624 -385.046982)
		(width 0.14224)
		(layer "In15.Cu")
		(net "P5E_CPU1_P0_RX_DP<9>")
	)
	(segment
		(start 59.340496 -384.048)
		(end 59.340496 -382.36906)
		(width 0.14224)
		(layer "In15.Cu")
		(net "P5E_CPU1_P0_RX_DP<9>")
	)
	(segment
		(start 118.152926 -360.663998)
		(end 118.152926 -360.092498)
		(width 0.14224)
		(layer "In15.Cu")
		(net "P5E_CPU1_P0_RX_DP<9>")
	)
	(segment
		(start 105.753408 -281.88158)
		(end 105.783888 -281.8638)
		(width 0.1143)
		(layer "In15.Cu")
		(net "P5E_CPU1_P0_RX_DP<9>")
	)
	(segment
		(start 105.20807 -296.300652)
		(end 105.20807 -295.919906)
		(width 0.1143)
		(layer "In15.Cu")
		(net "P5E_CPU1_P0_RX_DP<9>")
	)
	(segment
		(start 105.25379 -296.346372)
		(end 105.20807 -296.300652)
		(width 0.1143)
		(layer "In15.Cu")
		(net "P5E_CPU1_P0_RX_DP<9>")
	)
	(segment
		(start 105.25379 -296.37482)
		(end 105.25379 -296.346372)
		(width 0.1143)
		(layer "In15.Cu")
		(net "P5E_CPU1_P0_RX_DP<9>")
	)
	(segment
		(start 118.152926 -360.092498)
		(end 118.295166 -359.950258)
		(width 0.14224)
		(layer "In15.Cu")
		(net "P5E_CPU1_P0_RX_DP<9>")
	)
	(segment
		(start 131.55676 -345.57843)
		(end 117.981984 -332.003654)
		(width 0.14224)
		(layer "In15.Cu")
		(net "P5E_CPU1_P0_RX_DP<9>")
	)
	(segment
		(start 129.97434 -362.226098)
		(end 130.28168 -361.918758)
		(width 0.14224)
		(layer "In15.Cu")
		(net "P5E_CPU1_P0_RX_DP<9>")
	)
	(segment
		(start 107.276138 -362.226098)
		(end 129.97434 -362.226098)
		(width 0.14224)
		(layer "In15.Cu")
		(net "P5E_CPU1_P0_RX_DP<9>")
	)
	(segment
		(start 105.753408 -277.021544)
		(end 105.783888 -277.003764)
		(width 0.1143)
		(layer "In15.Cu")
		(net "P5E_CPU1_P0_RX_DP<9>")
	)
	(segment
		(start 105.823004 -284.151832)
		(end 105.783888 -284.128972)
		(width 0.1143)
		(layer "In15.Cu")
		(net "P5E_CPU1_P0_RX_DP<9>")
	)
	(segment
		(start 105.25379 -301.421546)
		(end 105.25379 -296.37482)
		(width 0.14224)
		(layer "In15.Cu")
		(net "P5E_CPU1_P0_RX_DP<9>")
	)
	(segment
		(start 105.783888 -282.50896)
		(end 105.753408 -282.49118)
		(width 0.1143)
		(layer "In15.Cu")
		(net "P5E_CPU1_P0_RX_DP<9>")
	)
	(segment
		(start 105.783888 -277.648924)
		(end 105.753408 -277.631144)
		(width 0.1143)
		(layer "In15.Cu")
		(net "P5E_CPU1_P0_RX_DP<9>")
	)
	(segment
		(start 105.783888 -291.583618)
		(end 105.823004 -291.560758)
		(width 0.1143)
		(layer "In15.Cu")
		(net "P5E_CPU1_P0_RX_DP<9>")
	)
	(segment
		(start 118.295166 -359.950258)
		(end 148.31949 -359.950258)
		(width 0.14224)
		(layer "In15.Cu")
		(net "P5E_CPU1_P0_RX_DP<9>")
	)
	(segment
		(start 105.753408 -291.601398)
		(end 105.783888 -291.583618)
		(width 0.1143)
		(layer "In15.Cu")
		(net "P5E_CPU1_P0_RX_DP<9>")
	)
	(segment
		(start 105.783888 -286.723836)
		(end 105.823004 -286.700976)
		(width 0.1143)
		(layer "In15.Cu")
		(net "P5E_CPU1_P0_RX_DP<9>")
	)
	(segment
		(start 59.340496 -382.36906)
		(end 59.00039 -374.974612)
		(width 0.14224)
		(layer "In15.Cu")
		(net "P5E_CPU1_P0_RX_DP<9>")
	)
	(segment
		(start 105.753408 -283.501592)
		(end 105.783888 -283.483812)
		(width 0.1143)
		(layer "In15.Cu")
		(net "P5E_CPU1_P0_RX_DP<9>")
	)
	(segment
		(start 105.751376 -288.362644)
		(end 105.783888 -288.343848)
		(width 0.1143)
		(layer "In15.Cu")
		(net "P5E_CPU1_P0_RX_DP<9>")
	)
	(segment
		(start 106.705908 -362.44657)
		(end 106.89209 -362.33354)
		(width 0.14224)
		(layer "In15.Cu")
		(net "P5E_CPU1_P0_RX_DP<9>")
	)
	(segment
		(start 105.783888 -293.20363)
		(end 105.823004 -293.18077)
		(width 0.1143)
		(layer "In15.Cu")
		(net "P5E_CPU1_P0_RX_DP<9>")
	)
	(segment
		(start 107.083098 -271.656302)
		(end 107.38104 -271.656302)
		(width 0.1143)
		(layer "In15.Cu")
		(net "P5E_CPU1_P0_RX_DP<9>")
	)
	(segment
		(start 105.823004 -289.011614)
		(end 105.783888 -288.988754)
		(width 0.1143)
		(layer "In15.Cu")
		(net "P5E_CPU1_P0_RX_DP<9>")
	)
	(segment
		(start 105.753408 -275.401532)
		(end 105.783888 -275.383752)
		(width 0.1143)
		(layer "In15.Cu")
		(net "P5E_CPU1_P0_RX_DP<9>")
	)
	(segment
		(start 105.783888 -290.608766)
		(end 105.753408 -290.590986)
		(width 0.1143)
		(layer "In15.Cu")
		(net "P5E_CPU1_P0_RX_DP<9>")
	)
	(arc
		(start 105.823004 -280.220928)
		(mid 106.066331 -279.756362)
		(end 105.823004 -279.291796)
		(width 0.1143)
		(layer "In15.Cu")
		(net "P5E_CPU1_P0_RX_DP<9>")
	)
	(arc
		(start 105.823004 -283.460952)
		(mid 106.066331 -282.996386)
		(end 105.823004 -282.53182)
		(width 0.1143)
		(layer "In15.Cu")
		(net "P5E_CPU1_P0_RX_DP<9>")
	)
	(arc
		(start 105.753408 -277.631144)
		(mid 105.596431 -277.326344)
		(end 105.753408 -277.021544)
		(width 0.1143)
		(layer "In15.Cu")
		(net "P5E_CPU1_P0_RX_DP<9>")
	)
	(arc
		(start 148.749512 -357.2256)
		(mid 148.662543 -357.080535)
		(end 148.537168 -356.967028)
		(width 0.14224)
		(layer "In15.Cu")
		(net "P5E_CPU1_P0_RX_DP<9>")
	)
	(arc
		(start 105.753408 -276.011132)
		(mid 105.596431 -275.706332)
		(end 105.753408 -275.401532)
		(width 0.1143)
		(layer "In15.Cu")
		(net "P5E_CPU1_P0_RX_DP<9>")
	)
	(arc
		(start 106.53649 -272.466308)
		(mid 106.578039 -272.294886)
		(end 106.693462 -272.161508)
		(width 0.1143)
		(layer "In15.Cu")
		(net "P5E_CPU1_P0_RX_DP<9>")
	)
	(arc
		(start 75.3237 -362.75645)
		(mid 75.34472 -362.750938)
		(end 75.366372 -362.749084)
		(width 0.14224)
		(layer "In15.Cu")
		(net "P5E_CPU1_P0_RX_DP<9>")
	)
	(arc
		(start 105.823004 -293.18077)
		(mid 106.066331 -292.716204)
		(end 105.823004 -292.251638)
		(width 0.1143)
		(layer "In15.Cu")
		(net "P5E_CPU1_P0_RX_DP<9>")
	)
	(arc
		(start 106.066336 -287.856422)
		(mid 106.0011 -287.592831)
		(end 105.820464 -287.390078)
		(width 0.1143)
		(layer "In15.Cu")
		(net "P5E_CPU1_P0_RX_DP<9>")
	)
	(arc
		(start 105.753408 -280.871168)
		(mid 105.596431 -280.566368)
		(end 105.753408 -280.261568)
		(width 0.1143)
		(layer "In15.Cu")
		(net "P5E_CPU1_P0_RX_DP<9>")
	)
	(arc
		(start 105.823004 -294.800782)
		(mid 106.066331 -294.336216)
		(end 105.823004 -293.87165)
		(width 0.1143)
		(layer "In15.Cu")
		(net "P5E_CPU1_P0_RX_DP<9>")
	)
	(arc
		(start 105.753408 -287.350962)
		(mid 105.637981 -287.217586)
		(end 105.596436 -287.046162)
		(width 0.1143)
		(layer "In15.Cu")
		(net "P5E_CPU1_P0_RX_DP<9>")
	)
	(arc
		(start 106.763058 -272.120868)
		(mid 106.915045 -271.96436)
		(end 106.996484 -271.761966)
		(width 0.1143)
		(layer "In15.Cu")
		(net "P5E_CPU1_P0_RX_DP<9>")
	)
	(arc
		(start 105.20807 -295.919906)
		(mid 105.217909 -295.871096)
		(end 105.245662 -295.829736)
		(width 0.1143)
		(layer "In15.Cu")
		(net "P5E_CPU1_P0_RX_DP<9>")
	)
	(arc
		(start 105.753408 -284.111192)
		(mid 105.596431 -283.806392)
		(end 105.753408 -283.501592)
		(width 0.1143)
		(layer "In15.Cu")
		(net "P5E_CPU1_P0_RX_DP<9>")
	)
	(arc
		(start 105.753408 -285.731204)
		(mid 105.596431 -285.426404)
		(end 105.753408 -285.121604)
		(width 0.1143)
		(layer "In15.Cu")
		(net "P5E_CPU1_P0_RX_DP<9>")
	)
	(arc
		(start 105.753408 -293.83101)
		(mid 105.596431 -293.52621)
		(end 105.753408 -293.22141)
		(width 0.1143)
		(layer "In15.Cu")
		(net "P5E_CPU1_P0_RX_DP<9>")
	)
	(arc
		(start 131.839208 -345.810332)
		(mid 131.692286 -345.701321)
		(end 131.55676 -345.57843)
		(width 0.14224)
		(layer "In15.Cu")
		(net "P5E_CPU1_P0_RX_DP<9>")
	)
	(arc
		(start 105.753408 -279.251156)
		(mid 105.596431 -278.946356)
		(end 105.753408 -278.641556)
		(width 0.1143)
		(layer "In15.Cu")
		(net "P5E_CPU1_P0_RX_DP<9>")
	)
	(arc
		(start 64.050672 -367.076736)
		(mid 64.414036 -366.720123)
		(end 64.86398 -366.481868)
		(width 0.14224)
		(layer "In15.Cu")
		(net "P5E_CPU1_P0_RX_DP<9>")
	)
	(arc
		(start 105.596436 -295.146222)
		(mid 105.637985 -294.9748)
		(end 105.753408 -294.841422)
		(width 0.1143)
		(layer "In15.Cu")
		(net "P5E_CPU1_P0_RX_DP<9>")
	)
	(arc
		(start 105.47985 -295.595294)
		(mid 105.565879 -295.466915)
		(end 105.596182 -295.315386)
		(width 0.1143)
		(layer "In15.Cu")
		(net "P5E_CPU1_P0_RX_DP<9>")
	)
	(arc
		(start 106.996484 -271.761966)
		(mid 106.998507 -271.750556)
		(end 107.000294 -271.739106)
		(width 0.1143)
		(layer "In15.Cu")
		(net "P5E_CPU1_P0_RX_DP<9>")
	)
	(arc
		(start 105.625138 -362.749084)
		(mid 106.186284 -362.671997)
		(end 106.705908 -362.44657)
		(width 0.14224)
		(layer "In15.Cu")
		(net "P5E_CPU1_P0_RX_DP<9>")
	)
	(arc
		(start 105.823004 -278.600916)
		(mid 106.066331 -278.13635)
		(end 105.823004 -277.671784)
		(width 0.1143)
		(layer "In15.Cu")
		(net "P5E_CPU1_P0_RX_DP<9>")
	)
	(arc
		(start 117.981984 -332.003654)
		(mid 117.821378 -331.807896)
		(end 117.702076 -331.584554)
		(width 0.14224)
		(layer "In15.Cu")
		(net "P5E_CPU1_P0_RX_DP<9>")
	)
	(arc
		(start 105.753408 -292.210998)
		(mid 105.596431 -291.906198)
		(end 105.753408 -291.601398)
		(width 0.1143)
		(layer "In15.Cu")
		(net "P5E_CPU1_P0_RX_DP<9>")
	)
	(arc
		(start 105.823004 -291.560758)
		(mid 106.066331 -291.096192)
		(end 105.823004 -290.631626)
		(width 0.1143)
		(layer "In15.Cu")
		(net "P5E_CPU1_P0_RX_DP<9>")
	)
	(arc
		(start 105.753408 -274.39112)
		(mid 105.596431 -274.08632)
		(end 105.753408 -273.78152)
		(width 0.1143)
		(layer "In15.Cu")
		(net "P5E_CPU1_P0_RX_DP<9>")
	)
	(arc
		(start 105.596436 -288.666174)
		(mid 105.637402 -288.495768)
		(end 105.751376 -288.362644)
		(width 0.1143)
		(layer "In15.Cu")
		(net "P5E_CPU1_P0_RX_DP<9>")
	)
	(arc
		(start 105.823004 -288.320988)
		(mid 106.001817 -288.118638)
		(end 106.066336 -287.856422)
		(width 0.1143)
		(layer "In15.Cu")
		(net "P5E_CPU1_P0_RX_DP<9>")
	)
	(arc
		(start 148.793454 -359.645712)
		(mid 148.925804 -359.447731)
		(end 148.97227 -359.214166)
		(width 0.14224)
		(layer "In15.Cu")
		(net "P5E_CPU1_P0_RX_DP<9>")
	)
	(arc
		(start 106.89209 -362.33354)
		(mid 107.076752 -362.253524)
		(end 107.276138 -362.226098)
		(width 0.14224)
		(layer "In15.Cu")
		(net "P5E_CPU1_P0_RX_DP<9>")
	)
	(arc
		(start 106.066336 -273.276314)
		(mid 106.107591 -273.105343)
		(end 106.222292 -272.972022)
		(width 0.1143)
		(layer "In15.Cu")
		(net "P5E_CPU1_P0_RX_DP<9>")
	)
	(arc
		(start 59.590686 -373.081042)
		(mid 59.683956 -372.853565)
		(end 59.815222 -372.645686)
		(width 0.14224)
		(layer "In15.Cu")
		(net "P5E_CPU1_P0_RX_DP<9>")
	)
	(arc
		(start 105.295446 -301.63135)
		(mid 105.264265 -301.528503)
		(end 105.25379 -301.421546)
		(width 0.14224)
		(layer "In15.Cu")
		(net "P5E_CPU1_P0_RX_DP<9>")
	)
	(arc
		(start 105.753408 -290.590986)
		(mid 105.596431 -290.286186)
		(end 105.753408 -289.981386)
		(width 0.1143)
		(layer "In15.Cu")
		(net "P5E_CPU1_P0_RX_DP<9>")
	)
	(arc
		(start 105.823004 -276.980904)
		(mid 106.066331 -276.516338)
		(end 105.823004 -276.051772)
		(width 0.1143)
		(layer "In15.Cu")
		(net "P5E_CPU1_P0_RX_DP<9>")
	)
	(arc
		(start 105.823004 -281.84094)
		(mid 106.066331 -281.376374)
		(end 105.823004 -280.911808)
		(width 0.1143)
		(layer "In15.Cu")
		(net "P5E_CPU1_P0_RX_DP<9>")
	)
	(arc
		(start 105.753408 -282.49118)
		(mid 105.596431 -282.18638)
		(end 105.753408 -281.88158)
		(width 0.1143)
		(layer "In15.Cu")
		(net "P5E_CPU1_P0_RX_DP<9>")
	)
	(arc
		(start 105.823004 -289.940746)
		(mid 106.066331 -289.47618)
		(end 105.823004 -289.011614)
		(width 0.1143)
		(layer "In15.Cu")
		(net "P5E_CPU1_P0_RX_DP<9>")
	)
	(arc
		(start 105.823004 -273.74088)
		(mid 106.001817 -273.53853)
		(end 106.066336 -273.276314)
		(width 0.1143)
		(layer "In15.Cu")
		(net "P5E_CPU1_P0_RX_DP<9>")
	)
	(arc
		(start 148.31949 -359.950258)
		(mid 148.476068 -359.919095)
		(end 148.608796 -359.83037)
		(width 0.14224)
		(layer "In15.Cu")
		(net "P5E_CPU1_P0_RX_DP<9>")
	)
	(arc
		(start 105.823004 -285.080964)
		(mid 106.066331 -284.616398)
		(end 105.823004 -284.151832)
		(width 0.1143)
		(layer "In15.Cu")
		(net "P5E_CPU1_P0_RX_DP<9>")
	)
	(arc
		(start 106.293158 -272.930874)
		(mid 106.471971 -272.728524)
		(end 106.53649 -272.466308)
		(width 0.1143)
		(layer "In15.Cu")
		(net "P5E_CPU1_P0_RX_DP<9>")
	)
	(arc
		(start 105.596436 -287.046162)
		(mid 105.637402 -286.875756)
		(end 105.751376 -286.742632)
		(width 0.1143)
		(layer "In15.Cu")
		(net "P5E_CPU1_P0_RX_DP<9>")
	)
	(arc
		(start 105.823004 -275.360892)
		(mid 106.066331 -274.896326)
		(end 105.823004 -274.43176)
		(width 0.1143)
		(layer "In15.Cu")
		(net "P5E_CPU1_P0_RX_DP<9>")
	)
	(arc
		(start 105.753408 -288.970974)
		(mid 105.637981 -288.837598)
		(end 105.596436 -288.666174)
		(width 0.1143)
		(layer "In15.Cu")
		(net "P5E_CPU1_P0_RX_DP<9>")
	)
	(arc
		(start 148.97227 -357.84536)
		(mid 148.964477 -357.765602)
		(end 148.941282 -357.688896)
		(width 0.14224)
		(layer "In15.Cu")
		(net "P5E_CPU1_P0_RX_DP<9>")
	)
	(arc
		(start 105.823004 -286.700976)
		(mid 106.066331 -286.23641)
		(end 105.823004 -285.771844)
		(width 0.1143)
		(layer "In15.Cu")
		(net "P5E_CPU1_P0_RX_DP<9>")
	)
	(segment
		(start 57.27065 -386.003292)
		(end 57.79135 -386.003292)
		(width 0.127)
		(layer "F.Cu")
		(net "P5E_CPU1_P0_RX_DP<8>")
	)
	(segment
		(start 105.027984 -269.770352)
		(end 104.561132 -270.03629)
		(width 0.12954)
		(layer "F.Cu")
		(net "P5E_CPU1_P0_RX_DP<8>")
	)
	(segment
		(start 104.847898 -275.38172)
		(end 104.850692 -275.380196)
		(width 0.1143)
		(layer "In15.Cu")
		(net "P5E_CPU1_P0_RX_DP<8>")
	)
	(segment
		(start 104.876346 -285.76778)
		(end 104.875584 -285.767272)
		(width 0.1143)
		(layer "In15.Cu")
		(net "P5E_CPU1_P0_RX_DP<8>")
	)
	(segment
		(start 104.852724 -293.85387)
		(end 104.850438 -293.852346)
		(width 0.1143)
		(layer "In15.Cu")
		(net "P5E_CPU1_P0_RX_DP<8>")
	)
	(segment
		(start 104.651048 -295.33215)
		(end 104.651048 -295.15181)
		(width 0.1143)
		(layer "In15.Cu")
		(net "P5E_CPU1_P0_RX_DP<8>")
	)
	(segment
		(start 116.75491 -359.833672)
		(end 107.248452 -359.833672)
		(width 0.14224)
		(layer "In15.Cu")
		(net "P5E_CPU1_P0_RX_DP<8>")
	)
	(segment
		(start 104.843326 -285.104332)
		(end 104.844088 -285.103824)
		(width 0.1143)
		(layer "In15.Cu")
		(net "P5E_CPU1_P0_RX_DP<8>")
	)
	(segment
		(start 104.864916 -291.571426)
		(end 104.86517 -291.571426)
		(width 0.1143)
		(layer "In15.Cu")
		(net "P5E_CPU1_P0_RX_DP<8>")
	)
	(segment
		(start 104.845104 -280.889456)
		(end 104.844088 -280.888948)
		(width 0.1143)
		(layer "In15.Cu")
		(net "P5E_CPU1_P0_RX_DP<8>")
	)
	(segment
		(start 104.843326 -280.88844)
		(end 104.812338 -280.87066)
		(width 0.1143)
		(layer "In15.Cu")
		(net "P5E_CPU1_P0_RX_DP<8>")
	)
	(segment
		(start 104.792526 -277.036276)
		(end 104.812338 -277.022052)
		(width 0.1143)
		(layer "In15.Cu")
		(net "P5E_CPU1_P0_RX_DP<8>")
	)
	(segment
		(start 104.850438 -292.232334)
		(end 104.849422 -292.231826)
		(width 0.1143)
		(layer "In15.Cu")
		(net "P5E_CPU1_P0_RX_DP<8>")
	)
	(segment
		(start 104.41305 -270.38173)
		(end 104.373934 -270.35887)
		(width 0.1143)
		(layer "In15.Cu")
		(net "P5E_CPU1_P0_RX_DP<8>")
	)
	(segment
		(start 104.844088 -294.823642)
		(end 104.845104 -294.823134)
		(width 0.1143)
		(layer "In15.Cu")
		(net "P5E_CPU1_P0_RX_DP<8>")
	)
	(segment
		(start 104.84358 -286.723582)
		(end 104.844088 -286.723836)
		(width 0.1143)
		(layer "In15.Cu")
		(net "P5E_CPU1_P0_RX_DP<8>")
	)
	(segment
		(start 57.79135 -386.003292)
		(end 57.886346 -385.649216)
		(width 0.14224)
		(layer "In15.Cu")
		(net "P5E_CPU1_P0_RX_DP<8>")
	)
	(segment
		(start 104.84358 -293.203884)
		(end 104.864916 -293.191438)
		(width 0.1143)
		(layer "In15.Cu")
		(net "P5E_CPU1_P0_RX_DP<8>")
	)
	(segment
		(start 58.1406 -383.7813)
		(end 58.1406 -381.465074)
		(width 0.14224)
		(layer "In15.Cu")
		(net "P5E_CPU1_P0_RX_DP<8>")
	)
	(segment
		(start 58.977022 -372.145814)
		(end 63.606426 -366.061498)
		(width 0.14224)
		(layer "In15.Cu")
		(net "P5E_CPU1_P0_RX_DP<8>")
	)
	(segment
		(start 104.845104 -276.02942)
		(end 104.844088 -276.028912)
		(width 0.1143)
		(layer "In15.Cu")
		(net "P5E_CPU1_P0_RX_DP<8>")
	)
	(segment
		(start 104.843326 -276.028404)
		(end 104.812338 -276.010624)
		(width 0.1143)
		(layer "In15.Cu")
		(net "P5E_CPU1_P0_RX_DP<8>")
	)
	(segment
		(start 104.831134 -288.35096)
		(end 104.844596 -288.34334)
		(width 0.1143)
		(layer "In15.Cu")
		(net "P5E_CPU1_P0_RX_DP<8>")
	)
	(segment
		(start 104.883204 -284.151832)
		(end 104.876346 -284.147768)
		(width 0.1143)
		(layer "In15.Cu")
		(net "P5E_CPU1_P0_RX_DP<8>")
	)
	(segment
		(start 107.315254 -358.977692)
		(end 142.043658 -358.977692)
		(width 0.14224)
		(layer "In15.Cu")
		(net "P5E_CPU1_P0_RX_DP<8>")
	)
	(segment
		(start 104.843326 -282.508452)
		(end 104.812338 -282.490672)
		(width 0.1143)
		(layer "In15.Cu")
		(net "P5E_CPU1_P0_RX_DP<8>")
	)
	(segment
		(start 57.838086 -384.083814)
		(end 58.1406 -383.7813)
		(width 0.14224)
		(layer "In15.Cu")
		(net "P5E_CPU1_P0_RX_DP<8>")
	)
	(segment
		(start 104.878886 -287.389316)
		(end 104.837484 -287.364424)
		(width 0.1143)
		(layer "In15.Cu")
		(net "P5E_CPU1_P0_RX_DP<8>")
	)
	(segment
		(start 104.855772 -275.377148)
		(end 104.883204 -275.360892)
		(width 0.1143)
		(layer "In15.Cu")
		(net "P5E_CPU1_P0_RX_DP<8>")
	)
	(segment
		(start 104.812338 -281.882088)
		(end 104.843326 -281.864308)
		(width 0.1143)
		(layer "In15.Cu")
		(net "P5E_CPU1_P0_RX_DP<8>")
	)
	(segment
		(start 104.844088 -279.268936)
		(end 104.843326 -279.268428)
		(width 0.1143)
		(layer "In15.Cu")
		(net "P5E_CPU1_P0_RX_DP<8>")
	)
	(segment
		(start 104.883204 -285.771844)
		(end 104.876346 -285.76778)
		(width 0.1143)
		(layer "In15.Cu")
		(net "P5E_CPU1_P0_RX_DP<8>")
	)
	(segment
		(start 104.308656 -296.346372)
		(end 104.262936 -296.300652)
		(width 0.1143)
		(layer "In15.Cu")
		(net "P5E_CPU1_P0_RX_DP<8>")
	)
	(segment
		(start 104.845104 -285.749492)
		(end 104.844088 -285.748984)
		(width 0.1143)
		(layer "In15.Cu")
		(net "P5E_CPU1_P0_RX_DP<8>")
	)
	(segment
		(start 104.844088 -278.623776)
		(end 104.845104 -278.623268)
		(width 0.1143)
		(layer "In15.Cu")
		(net "P5E_CPU1_P0_RX_DP<8>")
	)
	(segment
		(start 104.845104 -274.409408)
		(end 104.844088 -274.4089)
		(width 0.1143)
		(layer "In15.Cu")
		(net "P5E_CPU1_P0_RX_DP<8>")
	)
	(segment
		(start 104.875584 -274.427188)
		(end 104.845104 -274.409408)
		(width 0.1143)
		(layer "In15.Cu")
		(net "P5E_CPU1_P0_RX_DP<8>")
	)
	(segment
		(start 142.748 -358.27335)
		(end 142.748 -354.713032)
		(width 0.14224)
		(layer "In15.Cu")
		(net "P5E_CPU1_P0_RX_DP<8>")
	)
	(segment
		(start 104.812338 -278.642064)
		(end 104.843326 -278.624284)
		(width 0.1143)
		(layer "In15.Cu")
		(net "P5E_CPU1_P0_RX_DP<8>")
	)
	(segment
		(start 104.83088 -288.351214)
		(end 104.831134 -288.35096)
		(width 0.1143)
		(layer "In15.Cu")
		(net "P5E_CPU1_P0_RX_DP<8>")
	)
	(segment
		(start 104.812338 -280.87066)
		(end 104.793542 -280.856944)
		(width 0.1143)
		(layer "In15.Cu")
		(net "P5E_CPU1_P0_RX_DP<8>")
	)
	(segment
		(start 104.849676 -277.000462)
		(end 104.883204 -276.980904)
		(width 0.1143)
		(layer "In15.Cu")
		(net "P5E_CPU1_P0_RX_DP<8>")
	)
	(segment
		(start 104.849422 -292.231826)
		(end 104.84866 -292.231318)
		(width 0.1143)
		(layer "In15.Cu")
		(net "P5E_CPU1_P0_RX_DP<8>")
	)
	(segment
		(start 104.844088 -283.483812)
		(end 104.845104 -283.483304)
		(width 0.1143)
		(layer "In15.Cu")
		(net "P5E_CPU1_P0_RX_DP<8>")
	)
	(segment
		(start 104.845104 -279.269444)
		(end 104.844088 -279.268936)
		(width 0.1143)
		(layer "In15.Cu")
		(net "P5E_CPU1_P0_RX_DP<8>")
	)
	(segment
		(start 104.843326 -283.48432)
		(end 104.844088 -283.483812)
		(width 0.1143)
		(layer "In15.Cu")
		(net "P5E_CPU1_P0_RX_DP<8>")
	)
	(segment
		(start 104.807766 -272.164556)
		(end 104.874568 -272.126202)
		(width 0.1143)
		(layer "In15.Cu")
		(net "P5E_CPU1_P0_RX_DP<8>")
	)
	(segment
		(start 104.876346 -279.287732)
		(end 104.875584 -279.287224)
		(width 0.1143)
		(layer "In15.Cu")
		(net "P5E_CPU1_P0_RX_DP<8>")
	)
	(segment
		(start 104.844596 -288.34334)
		(end 104.877616 -288.323782)
		(width 0.1143)
		(layer "In15.Cu")
		(net "P5E_CPU1_P0_RX_DP<8>")
	)
	(segment
		(start 104.852978 -294.818816)
		(end 104.854502 -294.8178)
		(width 0.1143)
		(layer "In15.Cu")
		(net "P5E_CPU1_P0_RX_DP<8>")
	)
	(segment
		(start 104.262936 -296.300652)
		(end 104.262936 -295.92524)
		(width 0.1143)
		(layer "In15.Cu")
		(net "P5E_CPU1_P0_RX_DP<8>")
	)
	(segment
		(start 104.864916 -289.951414)
		(end 104.86517 -289.951414)
		(width 0.1143)
		(layer "In15.Cu")
		(net "P5E_CPU1_P0_RX_DP<8>")
	)
	(segment
		(start 104.88041 -271.189958)
		(end 104.844088 -271.168876)
		(width 0.1143)
		(layer "In15.Cu")
		(net "P5E_CPU1_P0_RX_DP<8>")
	)
	(segment
		(start 104.308656 -301.565818)
		(end 104.308656 -296.37482)
		(width 0.14224)
		(layer "In15.Cu")
		(net "P5E_CPU1_P0_RX_DP<8>")
	)
	(segment
		(start 104.843326 -285.748476)
		(end 104.812338 -285.730696)
		(width 0.1143)
		(layer "In15.Cu")
		(net "P5E_CPU1_P0_RX_DP<8>")
	)
	(segment
		(start 104.843326 -284.128464)
		(end 104.812338 -284.110684)
		(width 0.1143)
		(layer "In15.Cu")
		(net "P5E_CPU1_P0_RX_DP<8>")
	)
	(segment
		(start 104.792526 -275.416264)
		(end 104.812338 -275.40204)
		(width 0.1143)
		(layer "In15.Cu")
		(net "P5E_CPU1_P0_RX_DP<8>")
	)
	(segment
		(start 64.031622 -365.750348)
		(end 74.840338 -361.901232)
		(width 0.14224)
		(layer "In15.Cu")
		(net "P5E_CPU1_P0_RX_DP<8>")
	)
	(segment
		(start 104.882442 -290.631118)
		(end 104.836214 -290.604194)
		(width 0.1143)
		(layer "In15.Cu")
		(net "P5E_CPU1_P0_RX_DP<8>")
	)
	(segment
		(start 104.850692 -294.820086)
		(end 104.852978 -294.818816)
		(width 0.1143)
		(layer "In15.Cu")
		(net "P5E_CPU1_P0_RX_DP<8>")
	)
	(segment
		(start 104.882442 -292.25113)
		(end 104.850438 -292.232334)
		(width 0.1143)
		(layer "In15.Cu")
		(net "P5E_CPU1_P0_RX_DP<8>")
	)
	(segment
		(start 104.812338 -277.630636)
		(end 104.792526 -277.616412)
		(width 0.1143)
		(layer "In15.Cu")
		(net "P5E_CPU1_P0_RX_DP<8>")
	)
	(segment
		(start 104.26319 -270.03629)
		(end 104.561132 -270.03629)
		(width 0.1143)
		(layer "In15.Cu")
		(net "P5E_CPU1_P0_RX_DP<8>")
	)
	(segment
		(start 104.843326 -277.648416)
		(end 104.812338 -277.630636)
		(width 0.1143)
		(layer "In15.Cu")
		(net "P5E_CPU1_P0_RX_DP<8>")
	)
	(segment
		(start 104.845104 -278.623268)
		(end 104.883204 -278.600916)
		(width 0.1143)
		(layer "In15.Cu")
		(net "P5E_CPU1_P0_RX_DP<8>")
	)
	(segment
		(start 130.718306 -346.119196)
		(end 117.301772 -332.702662)
		(width 0.14224)
		(layer "In15.Cu")
		(net "P5E_CPU1_P0_RX_DP<8>")
	)
	(segment
		(start 104.883204 -272.811748)
		(end 104.876346 -272.807684)
		(width 0.1143)
		(layer "In15.Cu")
		(net "P5E_CPU1_P0_RX_DP<8>")
	)
	(segment
		(start 104.19334 -270.10614)
		(end 104.26319 -270.03629)
		(width 0.1143)
		(layer "In15.Cu")
		(net "P5E_CPU1_P0_RX_DP<8>")
	)
	(segment
		(start 104.882442 -287.391348)
		(end 104.878886 -287.389316)
		(width 0.1143)
		(layer "In15.Cu")
		(net "P5E_CPU1_P0_RX_DP<8>")
	)
	(segment
		(start 104.308656 -296.37482)
		(end 104.308656 -296.346372)
		(width 0.1143)
		(layer "In15.Cu")
		(net "P5E_CPU1_P0_RX_DP<8>")
	)
	(segment
		(start 58.148728 -385.460494)
		(end 58.148728 -385.046982)
		(width 0.14224)
		(layer "In15.Cu")
		(net "P5E_CPU1_P0_RX_DP<8>")
	)
	(segment
		(start 116.75491 -361.253532)
		(end 117.06225 -360.946192)
		(width 0.14224)
		(layer "In15.Cu")
		(net "P5E_CPU1_P0_RX_DP<8>")
	)
	(segment
		(start 57.886346 -385.649216)
		(end 58.06059 -385.548632)
		(width 0.14224)
		(layer "In15.Cu")
		(net "P5E_CPU1_P0_RX_DP<8>")
	)
	(segment
		(start 104.850692 -275.380196)
		(end 104.852978 -275.378926)
		(width 0.1143)
		(layer "In15.Cu")
		(net "P5E_CPU1_P0_RX_DP<8>")
	)
	(segment
		(start 104.844088 -277.648924)
		(end 104.843326 -277.648416)
		(width 0.1143)
		(layer "In15.Cu")
		(net "P5E_CPU1_P0_RX_DP<8>")
	)
	(segment
		(start 57.832752 -384.731006)
		(end 57.838086 -384.083814)
		(width 0.14224)
		(layer "In15.Cu")
		(net "P5E_CPU1_P0_RX_DP<8>")
	)
	(segment
		(start 104.834436 -287.362392)
		(end 104.727502 -287.255458)
		(width 0.1143)
		(layer "In15.Cu")
		(net "P5E_CPU1_P0_RX_DP<8>")
	)
	(segment
		(start 142.347696 -353.963732)
		(end 131.173728 -346.49283)
		(width 0.14224)
		(layer "In15.Cu")
		(net "P5E_CPU1_P0_RX_DP<8>")
	)
	(segment
		(start 104.86517 -293.191438)
		(end 104.883204 -293.18077)
		(width 0.1143)
		(layer "In15.Cu")
		(net "P5E_CPU1_P0_RX_DP<8>")
	)
	(segment
		(start 104.84358 -291.583872)
		(end 104.864916 -291.571426)
		(width 0.1143)
		(layer "In15.Cu")
		(net "P5E_CPU1_P0_RX_DP<8>")
	)
	(segment
		(start 104.844088 -285.748984)
		(end 104.843326 -285.748476)
		(width 0.1143)
		(layer "In15.Cu")
		(net "P5E_CPU1_P0_RX_DP<8>")
	)
	(segment
		(start 104.844088 -280.888948)
		(end 104.843326 -280.88844)
		(width 0.1143)
		(layer "In15.Cu")
		(net "P5E_CPU1_P0_RX_DP<8>")
	)
	(segment
		(start 104.812338 -275.40204)
		(end 104.843326 -275.38426)
		(width 0.1143)
		(layer "In15.Cu")
		(net "P5E_CPU1_P0_RX_DP<8>")
	)
	(segment
		(start 104.843326 -278.624284)
		(end 104.844088 -278.623776)
		(width 0.1143)
		(layer "In15.Cu")
		(net "P5E_CPU1_P0_RX_DP<8>")
	)
	(segment
		(start 104.845104 -281.863292)
		(end 104.883204 -281.84094)
		(width 0.1143)
		(layer "In15.Cu")
		(net "P5E_CPU1_P0_RX_DP<8>")
	)
	(segment
		(start 58.1406 -381.465074)
		(end 57.865518 -375.443242)
		(width 0.14224)
		(layer "In15.Cu")
		(net "P5E_CPU1_P0_RX_DP<8>")
	)
	(segment
		(start 104.812338 -273.782028)
		(end 104.843326 -273.764248)
		(width 0.1143)
		(layer "In15.Cu")
		(net "P5E_CPU1_P0_RX_DP<8>")
	)
	(segment
		(start 104.876346 -274.427696)
		(end 104.875584 -274.427188)
		(width 0.1143)
		(layer "In15.Cu")
		(net "P5E_CPU1_P0_RX_DP<8>")
	)
	(segment
		(start 104.845104 -272.789396)
		(end 104.844088 -272.788888)
		(width 0.1143)
		(layer "In15.Cu")
		(net "P5E_CPU1_P0_RX_DP<8>")
	)
	(segment
		(start 104.883204 -280.911808)
		(end 104.845104 -280.889456)
		(width 0.1143)
		(layer "In15.Cu")
		(net "P5E_CPU1_P0_RX_DP<8>")
	)
	(segment
		(start 104.792526 -278.656288)
		(end 104.812338 -278.642064)
		(width 0.1143)
		(layer "In15.Cu")
		(net "P5E_CPU1_P0_RX_DP<8>")
	)
	(segment
		(start 104.845104 -284.12948)
		(end 104.844088 -284.128972)
		(width 0.1143)
		(layer "In15.Cu")
		(net "P5E_CPU1_P0_RX_DP<8>")
	)
	(segment
		(start 104.843326 -275.38426)
		(end 104.844088 -275.383752)
		(width 0.1143)
		(layer "In15.Cu")
		(net "P5E_CPU1_P0_RX_DP<8>")
	)
	(segment
		(start 104.877616 -288.323782)
		(end 104.883204 -288.320988)
		(width 0.1143)
		(layer "In15.Cu")
		(net "P5E_CPU1_P0_RX_DP<8>")
	)
	(segment
		(start 104.845104 -285.103316)
		(end 104.883204 -285.080964)
		(width 0.1143)
		(layer "In15.Cu")
		(net "P5E_CPU1_P0_RX_DP<8>")
	)
	(segment
		(start 104.845104 -273.763232)
		(end 104.883204 -273.74088)
		(width 0.1143)
		(layer "In15.Cu")
		(net "P5E_CPU1_P0_RX_DP<8>")
	)
	(segment
		(start 104.843326 -294.82415)
		(end 104.844088 -294.823642)
		(width 0.1143)
		(layer "In15.Cu")
		(net "P5E_CPU1_P0_RX_DP<8>")
	)
	(segment
		(start 104.876346 -284.147768)
		(end 104.875584 -284.14726)
		(width 0.1143)
		(layer "In15.Cu")
		(net "P5E_CPU1_P0_RX_DP<8>")
	)
	(segment
		(start 104.844088 -274.4089)
		(end 104.843326 -274.408392)
		(width 0.1143)
		(layer "In15.Cu")
		(net "P5E_CPU1_P0_RX_DP<8>")
	)
	(segment
		(start 104.883204 -279.291796)
		(end 104.876346 -279.287732)
		(width 0.1143)
		(layer "In15.Cu")
		(net "P5E_CPU1_P0_RX_DP<8>")
	)
	(segment
		(start 106.681778 -361.253532)
		(end 116.75491 -361.253532)
		(width 0.14224)
		(layer "In15.Cu")
		(net "P5E_CPU1_P0_RX_DP<8>")
	)
	(segment
		(start 104.883204 -276.051772)
		(end 104.876346 -276.047708)
		(width 0.1143)
		(layer "In15.Cu")
		(net "P5E_CPU1_P0_RX_DP<8>")
	)
	(segment
		(start 104.843326 -273.764248)
		(end 104.844088 -273.76374)
		(width 0.1143)
		(layer "In15.Cu")
		(net "P5E_CPU1_P0_RX_DP<8>")
	)
	(segment
		(start 104.844088 -275.383752)
		(end 104.845104 -275.383244)
		(width 0.1143)
		(layer "In15.Cu")
		(net "P5E_CPU1_P0_RX_DP<8>")
	)
	(segment
		(start 104.793542 -280.275792)
		(end 104.812338 -280.262076)
		(width 0.1143)
		(layer "In15.Cu")
		(net "P5E_CPU1_P0_RX_DP<8>")
	)
	(segment
		(start 104.300528 -295.83507)
		(end 104.542844 -295.5925)
		(width 0.1143)
		(layer "In15.Cu")
		(net "P5E_CPU1_P0_RX_DP<8>")
	)
	(segment
		(start 75.534266 -361.781344)
		(end 105.3465 -361.781344)
		(width 0.14224)
		(layer "In15.Cu")
		(net "P5E_CPU1_P0_RX_DP<8>")
	)
	(segment
		(start 58.06059 -385.548632)
		(end 58.148728 -385.460494)
		(width 0.14224)
		(layer "In15.Cu")
		(net "P5E_CPU1_P0_RX_DP<8>")
	)
	(segment
		(start 104.883204 -277.671784)
		(end 104.876346 -277.66772)
		(width 0.1143)
		(layer "In15.Cu")
		(net "P5E_CPU1_P0_RX_DP<8>")
	)
	(segment
		(start 104.373934 -270.35887)
		(end 104.343454 -270.34109)
		(width 0.1143)
		(layer "In15.Cu")
		(net "P5E_CPU1_P0_RX_DP<8>")
	)
	(segment
		(start 104.837484 -287.364424)
		(end 104.834436 -287.362392)
		(width 0.1143)
		(layer "In15.Cu")
		(net "P5E_CPU1_P0_RX_DP<8>")
	)
	(segment
		(start 107.106212 -359.691432)
		(end 107.106212 -359.186734)
		(width 0.14224)
		(layer "In15.Cu")
		(net "P5E_CPU1_P0_RX_DP<8>")
	)
	(segment
		(start 104.845104 -282.509468)
		(end 104.844088 -282.50896)
		(width 0.1143)
		(layer "In15.Cu")
		(net "P5E_CPU1_P0_RX_DP<8>")
	)
	(segment
		(start 104.855772 -294.817038)
		(end 104.883204 -294.800782)
		(width 0.1143)
		(layer "In15.Cu")
		(net "P5E_CPU1_P0_RX_DP<8>")
	)
	(segment
		(start 104.812338 -277.022052)
		(end 104.843326 -277.004272)
		(width 0.1143)
		(layer "In15.Cu")
		(net "P5E_CPU1_P0_RX_DP<8>")
	)
	(segment
		(start 117.06225 -360.141012)
		(end 116.75491 -359.833672)
		(width 0.14224)
		(layer "In15.Cu")
		(net "P5E_CPU1_P0_RX_DP<8>")
	)
	(segment
		(start 104.845104 -277.649432)
		(end 104.844088 -277.648924)
		(width 0.1143)
		(layer "In15.Cu")
		(net "P5E_CPU1_P0_RX_DP<8>")
	)
	(segment
		(start 104.81564 -272.772378)
		(end 104.812846 -272.7706)
		(width 0.1143)
		(layer "In15.Cu")
		(net "P5E_CPU1_P0_RX_DP<8>")
	)
	(segment
		(start 104.812338 -282.490672)
		(end 104.792526 -282.476448)
		(width 0.1143)
		(layer "In15.Cu")
		(net "P5E_CPU1_P0_RX_DP<8>")
	)
	(segment
		(start 104.843326 -281.864308)
		(end 104.844088 -281.8638)
		(width 0.1143)
		(layer "In15.Cu")
		(net "P5E_CPU1_P0_RX_DP<8>")
	)
	(segment
		(start 104.844088 -271.168876)
		(end 104.812338 -271.150588)
		(width 0.1143)
		(layer "In15.Cu")
		(net "P5E_CPU1_P0_RX_DP<8>")
	)
	(segment
		(start 104.875584 -277.667212)
		(end 104.845104 -277.649432)
		(width 0.1143)
		(layer "In15.Cu")
		(net "P5E_CPU1_P0_RX_DP<8>")
	)
	(segment
		(start 104.864916 -293.191438)
		(end 104.86517 -293.191438)
		(width 0.1143)
		(layer "In15.Cu")
		(net "P5E_CPU1_P0_RX_DP<8>")
	)
	(segment
		(start 104.875584 -276.0472)
		(end 104.845104 -276.02942)
		(width 0.1143)
		(layer "In15.Cu")
		(net "P5E_CPU1_P0_RX_DP<8>")
	)
	(segment
		(start 104.876346 -276.047708)
		(end 104.875584 -276.0472)
		(width 0.1143)
		(layer "In15.Cu")
		(net "P5E_CPU1_P0_RX_DP<8>")
	)
	(segment
		(start 104.844088 -281.8638)
		(end 104.845104 -281.863292)
		(width 0.1143)
		(layer "In15.Cu")
		(net "P5E_CPU1_P0_RX_DP<8>")
	)
	(segment
		(start 104.845104 -275.383244)
		(end 104.846882 -275.382228)
		(width 0.1143)
		(layer "In15.Cu")
		(net "P5E_CPU1_P0_RX_DP<8>")
	)
	(segment
		(start 104.874568 -272.126202)
		(end 104.87533 -272.125694)
		(width 0.1143)
		(layer "In15.Cu")
		(net "P5E_CPU1_P0_RX_DP<8>")
	)
	(segment
		(start 104.850438 -293.852346)
		(end 104.836214 -293.844218)
		(width 0.1143)
		(layer "In15.Cu")
		(net "P5E_CPU1_P0_RX_DP<8>")
	)
	(segment
		(start 104.812338 -285.122112)
		(end 104.843326 -285.104332)
		(width 0.1143)
		(layer "In15.Cu")
		(net "P5E_CPU1_P0_RX_DP<8>")
	)
	(segment
		(start 104.86517 -289.951414)
		(end 104.883204 -289.940746)
		(width 0.1143)
		(layer "In15.Cu")
		(net "P5E_CPU1_P0_RX_DP<8>")
	)
	(segment
		(start 104.854502 -275.37791)
		(end 104.855772 -275.377148)
		(width 0.1143)
		(layer "In15.Cu")
		(net "P5E_CPU1_P0_RX_DP<8>")
	)
	(segment
		(start 107.106212 -359.186734)
		(end 107.315254 -358.977692)
		(width 0.14224)
		(layer "In15.Cu")
		(net "P5E_CPU1_P0_RX_DP<8>")
	)
	(segment
		(start 104.844088 -284.128972)
		(end 104.843326 -284.128464)
		(width 0.1143)
		(layer "In15.Cu")
		(net "P5E_CPU1_P0_RX_DP<8>")
	)
	(segment
		(start 104.81437 -286.7406)
		(end 104.84358 -286.723582)
		(width 0.1143)
		(layer "In15.Cu")
		(net "P5E_CPU1_P0_RX_DP<8>")
	)
	(segment
		(start 104.876346 -277.66772)
		(end 104.875584 -277.667212)
		(width 0.1143)
		(layer "In15.Cu")
		(net "P5E_CPU1_P0_RX_DP<8>")
	)
	(segment
		(start 104.84358 -289.96386)
		(end 104.864916 -289.951414)
		(width 0.1143)
		(layer "In15.Cu")
		(net "P5E_CPU1_P0_RX_DP<8>")
	)
	(segment
		(start 104.844088 -285.103824)
		(end 104.845104 -285.103316)
		(width 0.1143)
		(layer "In15.Cu")
		(net "P5E_CPU1_P0_RX_DP<8>")
	)
	(segment
		(start 104.883204 -274.43176)
		(end 104.876346 -274.427696)
		(width 0.1143)
		(layer "In15.Cu")
		(net "P5E_CPU1_P0_RX_DP<8>")
	)
	(segment
		(start 104.844088 -280.243788)
		(end 104.845104 -280.24328)
		(width 0.1143)
		(layer "In15.Cu")
		(net "P5E_CPU1_P0_RX_DP<8>")
	)
	(segment
		(start 104.812846 -272.7706)
		(end 104.807766 -272.767044)
		(width 0.1143)
		(layer "In15.Cu")
		(net "P5E_CPU1_P0_RX_DP<8>")
	)
	(segment
		(start 104.844088 -276.028912)
		(end 104.843326 -276.028404)
		(width 0.1143)
		(layer "In15.Cu")
		(net "P5E_CPU1_P0_RX_DP<8>")
	)
	(segment
		(start 104.843326 -272.78838)
		(end 104.81564 -272.772378)
		(width 0.1143)
		(layer "In15.Cu")
		(net "P5E_CPU1_P0_RX_DP<8>")
	)
	(segment
		(start 116.835428 -332.00467)
		(end 104.382824 -301.937928)
		(width 0.14224)
		(layer "In15.Cu")
		(net "P5E_CPU1_P0_RX_DP<8>")
	)
	(segment
		(start 104.876346 -282.527756)
		(end 104.875584 -282.527248)
		(width 0.1143)
		(layer "In15.Cu")
		(net "P5E_CPU1_P0_RX_DP<8>")
	)
	(segment
		(start 104.84866 -292.231318)
		(end 104.836214 -292.224206)
		(width 0.1143)
		(layer "In15.Cu")
		(net "P5E_CPU1_P0_RX_DP<8>")
	)
	(segment
		(start 104.854502 -294.8178)
		(end 104.855772 -294.817038)
		(width 0.1143)
		(layer "In15.Cu")
		(net "P5E_CPU1_P0_RX_DP<8>")
	)
	(segment
		(start 104.843326 -279.268428)
		(end 104.812338 -279.250648)
		(width 0.1143)
		(layer "In15.Cu")
		(net "P5E_CPU1_P0_RX_DP<8>")
	)
	(segment
		(start 104.845104 -294.823134)
		(end 104.850692 -294.820086)
		(width 0.1143)
		(layer "In15.Cu")
		(net "P5E_CPU1_P0_RX_DP<8>")
	)
	(segment
		(start 57.91962 -375.024142)
		(end 58.574432 -372.925594)
		(width 0.14224)
		(layer "In15.Cu")
		(net "P5E_CPU1_P0_RX_DP<8>")
	)
	(segment
		(start 104.659176 -287.090612)
		(end 104.659176 -287.000696)
		(width 0.1143)
		(layer "In15.Cu")
		(net "P5E_CPU1_P0_RX_DP<8>")
	)
	(segment
		(start 104.792526 -283.516324)
		(end 104.812338 -283.5021)
		(width 0.1143)
		(layer "In15.Cu")
		(net "P5E_CPU1_P0_RX_DP<8>")
	)
	(segment
		(start 104.843326 -280.244296)
		(end 104.844088 -280.243788)
		(width 0.1143)
		(layer "In15.Cu")
		(net "P5E_CPU1_P0_RX_DP<8>")
	)
	(segment
		(start 104.843326 -274.408392)
		(end 104.812338 -274.390612)
		(width 0.1143)
		(layer "In15.Cu")
		(net "P5E_CPU1_P0_RX_DP<8>")
	)
	(segment
		(start 104.86517 -291.571426)
		(end 104.883204 -291.560758)
		(width 0.1143)
		(layer "In15.Cu")
		(net "P5E_CPU1_P0_RX_DP<8>")
	)
	(segment
		(start 104.812338 -284.110684)
		(end 104.792526 -284.09646)
		(width 0.1143)
		(layer "In15.Cu")
		(net "P5E_CPU1_P0_RX_DP<8>")
	)
	(segment
		(start 104.882442 -287.391094)
		(end 104.882442 -287.391348)
		(width 0.1143)
		(layer "In15.Cu")
		(net "P5E_CPU1_P0_RX_DP<8>")
	)
	(segment
		(start 104.845104 -280.24328)
		(end 104.883204 -280.220928)
		(width 0.1143)
		(layer "In15.Cu")
		(net "P5E_CPU1_P0_RX_DP<8>")
	)
	(segment
		(start 104.812338 -279.250648)
		(end 104.792526 -279.236424)
		(width 0.1143)
		(layer "In15.Cu")
		(net "P5E_CPU1_P0_RX_DP<8>")
	)
	(segment
		(start 104.844088 -272.788888)
		(end 104.843326 -272.78838)
		(width 0.1143)
		(layer "In15.Cu")
		(net "P5E_CPU1_P0_RX_DP<8>")
	)
	(segment
		(start 104.844088 -277.003764)
		(end 104.845104 -277.003256)
		(width 0.1143)
		(layer "In15.Cu")
		(net "P5E_CPU1_P0_RX_DP<8>")
	)
	(segment
		(start 104.875584 -284.14726)
		(end 104.845104 -284.12948)
		(width 0.1143)
		(layer "In15.Cu")
		(net "P5E_CPU1_P0_RX_DP<8>")
	)
	(segment
		(start 104.862376 -286.713168)
		(end 104.883204 -286.700976)
		(width 0.1143)
		(layer "In15.Cu")
		(net "P5E_CPU1_P0_RX_DP<8>")
	)
	(segment
		(start 104.845104 -283.483304)
		(end 104.883204 -283.460952)
		(width 0.1143)
		(layer "In15.Cu")
		(net "P5E_CPU1_P0_RX_DP<8>")
	)
	(segment
		(start 104.844088 -282.50896)
		(end 104.843326 -282.508452)
		(width 0.1143)
		(layer "In15.Cu")
		(net "P5E_CPU1_P0_RX_DP<8>")
	)
	(segment
		(start 104.844088 -273.76374)
		(end 104.845104 -273.763232)
		(width 0.1143)
		(layer "In15.Cu")
		(net "P5E_CPU1_P0_RX_DP<8>")
	)
	(segment
		(start 104.852978 -275.378926)
		(end 104.854502 -275.37791)
		(width 0.1143)
		(layer "In15.Cu")
		(net "P5E_CPU1_P0_RX_DP<8>")
	)
	(segment
		(start 104.846882 -275.382228)
		(end 104.847898 -275.38172)
		(width 0.1143)
		(layer "In15.Cu")
		(net "P5E_CPU1_P0_RX_DP<8>")
	)
	(segment
		(start 104.845104 -277.003256)
		(end 104.849676 -277.000462)
		(width 0.1143)
		(layer "In15.Cu")
		(net "P5E_CPU1_P0_RX_DP<8>")
	)
	(segment
		(start 104.843326 -277.004272)
		(end 104.844088 -277.003764)
		(width 0.1143)
		(layer "In15.Cu")
		(net "P5E_CPU1_P0_RX_DP<8>")
	)
	(segment
		(start 107.248452 -359.833672)
		(end 107.106212 -359.691432)
		(width 0.14224)
		(layer "In15.Cu")
		(net "P5E_CPU1_P0_RX_DP<8>")
	)
	(segment
		(start 104.839262 -294.826436)
		(end 104.843326 -294.82415)
		(width 0.1143)
		(layer "In15.Cu")
		(net "P5E_CPU1_P0_RX_DP<8>")
	)
	(segment
		(start 106.290872 -361.395264)
		(end 106.596688 -361.270296)
		(width 0.14224)
		(layer "In15.Cu")
		(net "P5E_CPU1_P0_RX_DP<8>")
	)
	(segment
		(start 104.812338 -276.010624)
		(end 104.792526 -275.9964)
		(width 0.1143)
		(layer "In15.Cu")
		(net "P5E_CPU1_P0_RX_DP<8>")
	)
	(segment
		(start 117.06225 -360.946192)
		(end 117.06225 -360.141012)
		(width 0.14224)
		(layer "In15.Cu")
		(net "P5E_CPU1_P0_RX_DP<8>")
	)
	(segment
		(start 104.791256 -272.176494)
		(end 104.807766 -272.164556)
		(width 0.1143)
		(layer "In15.Cu")
		(net "P5E_CPU1_P0_RX_DP<8>")
	)
	(segment
		(start 104.831134 -288.981388)
		(end 104.830626 -288.981134)
		(width 0.1143)
		(layer "In15.Cu")
		(net "P5E_CPU1_P0_RX_DP<8>")
	)
	(segment
		(start 104.812338 -283.5021)
		(end 104.843326 -283.48432)
		(width 0.1143)
		(layer "In15.Cu")
		(net "P5E_CPU1_P0_RX_DP<8>")
	)
	(segment
		(start 104.875584 -285.767272)
		(end 104.845104 -285.749492)
		(width 0.1143)
		(layer "In15.Cu")
		(net "P5E_CPU1_P0_RX_DP<8>")
	)
	(segment
		(start 104.844088 -286.723836)
		(end 104.862376 -286.713168)
		(width 0.1143)
		(layer "In15.Cu")
		(net "P5E_CPU1_P0_RX_DP<8>")
	)
	(segment
		(start 104.812338 -280.262076)
		(end 104.843326 -280.244296)
		(width 0.1143)
		(layer "In15.Cu")
		(net "P5E_CPU1_P0_RX_DP<8>")
	)
	(segment
		(start 104.876346 -272.807684)
		(end 104.875584 -272.807176)
		(width 0.1143)
		(layer "In15.Cu")
		(net "P5E_CPU1_P0_RX_DP<8>")
	)
	(segment
		(start 104.882442 -293.871142)
		(end 104.852724 -293.85387)
		(width 0.1143)
		(layer "In15.Cu")
		(net "P5E_CPU1_P0_RX_DP<8>")
	)
	(segment
		(start 104.882442 -289.011106)
		(end 104.831134 -288.981388)
		(width 0.1143)
		(layer "In15.Cu")
		(net "P5E_CPU1_P0_RX_DP<8>")
	)
	(segment
		(start 104.792526 -281.896312)
		(end 104.812338 -281.882088)
		(width 0.1143)
		(layer "In15.Cu")
		(net "P5E_CPU1_P0_RX_DP<8>")
	)
	(segment
		(start 104.87533 -272.125694)
		(end 104.88041 -272.122646)
		(width 0.1143)
		(layer "In15.Cu")
		(net "P5E_CPU1_P0_RX_DP<8>")
	)
	(segment
		(start 104.875584 -272.807176)
		(end 104.845104 -272.789396)
		(width 0.1143)
		(layer "In15.Cu")
		(net "P5E_CPU1_P0_RX_DP<8>")
	)
	(segment
		(start 104.875584 -282.527248)
		(end 104.845104 -282.509468)
		(width 0.1143)
		(layer "In15.Cu")
		(net "P5E_CPU1_P0_RX_DP<8>")
	)
	(segment
		(start 58.148728 -385.046982)
		(end 57.832752 -384.731006)
		(width 0.14224)
		(layer "In15.Cu")
		(net "P5E_CPU1_P0_RX_DP<8>")
	)
	(segment
		(start 104.875584 -279.287224)
		(end 104.845104 -279.269444)
		(width 0.1143)
		(layer "In15.Cu")
		(net "P5E_CPU1_P0_RX_DP<8>")
	)
	(segment
		(start 104.807004 -272.766536)
		(end 104.792526 -272.756376)
		(width 0.1143)
		(layer "In15.Cu")
		(net "P5E_CPU1_P0_RX_DP<8>")
	)
	(segment
		(start 104.807766 -272.767044)
		(end 104.807004 -272.766536)
		(width 0.1143)
		(layer "In15.Cu")
		(net "P5E_CPU1_P0_RX_DP<8>")
	)
	(segment
		(start 104.883204 -282.53182)
		(end 104.876346 -282.527756)
		(width 0.1143)
		(layer "In15.Cu")
		(net "P5E_CPU1_P0_RX_DP<8>")
	)
	(arc
		(start 104.88041 -272.122646)
		(mid 104.887559 -272.117746)
		(end 104.894634 -272.11274)
		(width 0.1143)
		(layer "In15.Cu")
		(net "P5E_CPU1_P0_RX_DP<8>")
	)
	(arc
		(start 104.883204 -289.940746)
		(mid 105.126531 -289.47618)
		(end 104.883204 -289.011614)
		(width 0.1143)
		(layer "In15.Cu")
		(net "P5E_CPU1_P0_RX_DP<8>")
	)
	(arc
		(start 104.894634 -272.11274)
		(mid 105.122017 -271.656302)
		(end 104.894634 -271.199864)
		(width 0.1143)
		(layer "In15.Cu")
		(net "P5E_CPU1_P0_RX_DP<8>")
	)
	(arc
		(start 104.792526 -284.09646)
		(mid 104.643812 -283.806392)
		(end 104.792526 -283.516324)
		(width 0.1143)
		(layer "In15.Cu")
		(net "P5E_CPU1_P0_RX_DP<8>")
	)
	(arc
		(start 104.883204 -281.84094)
		(mid 105.126531 -281.376374)
		(end 104.883204 -280.911808)
		(width 0.1143)
		(layer "In15.Cu")
		(net "P5E_CPU1_P0_RX_DP<8>")
	)
	(arc
		(start 104.883204 -291.560758)
		(mid 105.126531 -291.096192)
		(end 104.883204 -290.631626)
		(width 0.1143)
		(layer "In15.Cu")
		(net "P5E_CPU1_P0_RX_DP<8>")
	)
	(arc
		(start 104.651048 -295.15181)
		(mid 104.701433 -294.963832)
		(end 104.839262 -294.826436)
		(width 0.1143)
		(layer "In15.Cu")
		(net "P5E_CPU1_P0_RX_DP<8>")
	)
	(arc
		(start 104.883204 -273.74088)
		(mid 105.126531 -273.276314)
		(end 104.883204 -272.811748)
		(width 0.1143)
		(layer "In15.Cu")
		(net "P5E_CPU1_P0_RX_DP<8>")
	)
	(arc
		(start 104.830626 -288.981134)
		(mid 104.649428 -288.666064)
		(end 104.83088 -288.351214)
		(width 0.1143)
		(layer "In15.Cu")
		(net "P5E_CPU1_P0_RX_DP<8>")
	)
	(arc
		(start 104.836214 -293.844218)
		(mid 104.657997 -293.521941)
		(end 104.84358 -293.203884)
		(width 0.1143)
		(layer "In15.Cu")
		(net "P5E_CPU1_P0_RX_DP<8>")
	)
	(arc
		(start 104.792526 -279.236424)
		(mid 104.643812 -278.946356)
		(end 104.792526 -278.656288)
		(width 0.1143)
		(layer "In15.Cu")
		(net "P5E_CPU1_P0_RX_DP<8>")
	)
	(arc
		(start 104.883204 -280.220928)
		(mid 105.126531 -279.756362)
		(end 104.883204 -279.291796)
		(width 0.1143)
		(layer "In15.Cu")
		(net "P5E_CPU1_P0_RX_DP<8>")
	)
	(arc
		(start 104.883204 -288.320988)
		(mid 105.126421 -287.855892)
		(end 104.882442 -287.391094)
		(width 0.1143)
		(layer "In15.Cu")
		(net "P5E_CPU1_P0_RX_DP<8>")
	)
	(arc
		(start 104.883204 -289.011614)
		(mid 104.882823 -289.01136)
		(end 104.882442 -289.011106)
		(width 0.1143)
		(layer "In15.Cu")
		(net "P5E_CPU1_P0_RX_DP<8>")
	)
	(arc
		(start 57.865518 -375.443242)
		(mid 57.874299 -375.231334)
		(end 57.91962 -375.024142)
		(width 0.14224)
		(layer "In15.Cu")
		(net "P5E_CPU1_P0_RX_DP<8>")
	)
	(arc
		(start 104.343454 -270.34109)
		(mid 104.245689 -270.238114)
		(end 104.19334 -270.10614)
		(width 0.1143)
		(layer "In15.Cu")
		(net "P5E_CPU1_P0_RX_DP<8>")
	)
	(arc
		(start 131.173728 -346.49283)
		(mid 130.936853 -346.317183)
		(end 130.718306 -346.119196)
		(width 0.14224)
		(layer "In15.Cu")
		(net "P5E_CPU1_P0_RX_DP<8>")
	)
	(arc
		(start 104.883204 -283.460952)
		(mid 105.126531 -282.996386)
		(end 104.883204 -282.53182)
		(width 0.1143)
		(layer "In15.Cu")
		(net "P5E_CPU1_P0_RX_DP<8>")
	)
	(arc
		(start 104.883204 -293.87165)
		(mid 104.882823 -293.871396)
		(end 104.882442 -293.871142)
		(width 0.1143)
		(layer "In15.Cu")
		(net "P5E_CPU1_P0_RX_DP<8>")
	)
	(arc
		(start 117.301772 -332.702662)
		(mid 117.034215 -332.376638)
		(end 116.835428 -332.00467)
		(width 0.14224)
		(layer "In15.Cu")
		(net "P5E_CPU1_P0_RX_DP<8>")
	)
	(arc
		(start 104.883204 -275.360892)
		(mid 105.126531 -274.896326)
		(end 104.883204 -274.43176)
		(width 0.1143)
		(layer "In15.Cu")
		(net "P5E_CPU1_P0_RX_DP<8>")
	)
	(arc
		(start 104.883204 -286.700976)
		(mid 105.126531 -286.23641)
		(end 104.883204 -285.771844)
		(width 0.1143)
		(layer "In15.Cu")
		(net "P5E_CPU1_P0_RX_DP<8>")
	)
	(arc
		(start 58.574432 -372.925594)
		(mid 58.741724 -372.518149)
		(end 58.977022 -372.145814)
		(width 0.14224)
		(layer "In15.Cu")
		(net "P5E_CPU1_P0_RX_DP<8>")
	)
	(arc
		(start 142.748 -354.713032)
		(mid 142.641652 -354.288268)
		(end 142.347696 -353.963732)
		(width 0.14224)
		(layer "In15.Cu")
		(net "P5E_CPU1_P0_RX_DP<8>")
	)
	(arc
		(start 74.840338 -361.901232)
		(mid 75.182162 -361.811541)
		(end 75.534266 -361.781344)
		(width 0.14224)
		(layer "In15.Cu")
		(net "P5E_CPU1_P0_RX_DP<8>")
	)
	(arc
		(start 104.894634 -271.199864)
		(mid 104.88756 -271.194857)
		(end 104.88041 -271.189958)
		(width 0.1143)
		(layer "In15.Cu")
		(net "P5E_CPU1_P0_RX_DP<8>")
	)
	(arc
		(start 104.883204 -294.800782)
		(mid 105.126531 -294.336216)
		(end 104.883204 -293.87165)
		(width 0.1143)
		(layer "In15.Cu")
		(net "P5E_CPU1_P0_RX_DP<8>")
	)
	(arc
		(start 105.3465 -361.781344)
		(mid 105.785155 -361.701472)
		(end 106.167428 -361.471972)
		(width 0.14224)
		(layer "In15.Cu")
		(net "P5E_CPU1_P0_RX_DP<8>")
	)
	(arc
		(start 104.792526 -272.756376)
		(mid 104.643818 -272.466792)
		(end 104.791256 -272.176494)
		(width 0.1143)
		(layer "In15.Cu")
		(net "P5E_CPU1_P0_RX_DP<8>")
	)
	(arc
		(start 104.793542 -280.856944)
		(mid 104.644627 -280.566368)
		(end 104.793542 -280.275792)
		(width 0.1143)
		(layer "In15.Cu")
		(net "P5E_CPU1_P0_RX_DP<8>")
	)
	(arc
		(start 104.836214 -290.604194)
		(mid 104.657997 -290.281917)
		(end 104.84358 -289.96386)
		(width 0.1143)
		(layer "In15.Cu")
		(net "P5E_CPU1_P0_RX_DP<8>")
	)
	(arc
		(start 104.883204 -290.631626)
		(mid 104.882823 -290.631372)
		(end 104.882442 -290.631118)
		(width 0.1143)
		(layer "In15.Cu")
		(net "P5E_CPU1_P0_RX_DP<8>")
	)
	(arc
		(start 104.659176 -287.000696)
		(mid 104.709297 -286.854248)
		(end 104.81437 -286.7406)
		(width 0.1143)
		(layer "In15.Cu")
		(net "P5E_CPU1_P0_RX_DP<8>")
	)
	(arc
		(start 104.382824 -301.937928)
		(mid 104.327417 -301.755526)
		(end 104.308656 -301.565818)
		(width 0.14224)
		(layer "In15.Cu")
		(net "P5E_CPU1_P0_RX_DP<8>")
	)
	(arc
		(start 104.792526 -275.9964)
		(mid 104.643812 -275.706332)
		(end 104.792526 -275.416264)
		(width 0.1143)
		(layer "In15.Cu")
		(net "P5E_CPU1_P0_RX_DP<8>")
	)
	(arc
		(start 104.812338 -274.390612)
		(mid 104.661953 -274.08632)
		(end 104.812338 -273.782028)
		(width 0.1143)
		(layer "In15.Cu")
		(net "P5E_CPU1_P0_RX_DP<8>")
	)
	(arc
		(start 63.606426 -366.061498)
		(mid 63.79637 -365.874964)
		(end 64.031622 -365.750348)
		(width 0.14224)
		(layer "In15.Cu")
		(net "P5E_CPU1_P0_RX_DP<8>")
	)
	(arc
		(start 104.812338 -271.150588)
		(mid 104.697662 -271.017254)
		(end 104.656382 -270.846296)
		(width 0.1143)
		(layer "In15.Cu")
		(net "P5E_CPU1_P0_RX_DP<8>")
	)
	(arc
		(start 104.792526 -277.616412)
		(mid 104.643812 -277.326344)
		(end 104.792526 -277.036276)
		(width 0.1143)
		(layer "In15.Cu")
		(net "P5E_CPU1_P0_RX_DP<8>")
	)
	(arc
		(start 142.043658 -358.977692)
		(mid 142.541703 -358.771395)
		(end 142.748 -358.27335)
		(width 0.14224)
		(layer "In15.Cu")
		(net "P5E_CPU1_P0_RX_DP<8>")
	)
	(arc
		(start 104.883204 -285.080964)
		(mid 105.126531 -284.616398)
		(end 104.883204 -284.151832)
		(width 0.1143)
		(layer "In15.Cu")
		(net "P5E_CPU1_P0_RX_DP<8>")
	)
	(arc
		(start 106.167428 -361.471972)
		(mid 106.225958 -361.428484)
		(end 106.290872 -361.395264)
		(width 0.14224)
		(layer "In15.Cu")
		(net "P5E_CPU1_P0_RX_DP<8>")
	)
	(arc
		(start 104.542844 -295.5925)
		(mid 104.622824 -295.47308)
		(end 104.651048 -295.33215)
		(width 0.1143)
		(layer "In15.Cu")
		(net "P5E_CPU1_P0_RX_DP<8>")
	)
	(arc
		(start 104.883204 -292.251638)
		(mid 104.882823 -292.251384)
		(end 104.882442 -292.25113)
		(width 0.1143)
		(layer "In15.Cu")
		(net "P5E_CPU1_P0_RX_DP<8>")
	)
	(arc
		(start 104.883204 -278.600916)
		(mid 105.126531 -278.13635)
		(end 104.883204 -277.671784)
		(width 0.1143)
		(layer "In15.Cu")
		(net "P5E_CPU1_P0_RX_DP<8>")
	)
	(arc
		(start 104.727502 -287.255458)
		(mid 104.676913 -287.17984)
		(end 104.659176 -287.090612)
		(width 0.1143)
		(layer "In15.Cu")
		(net "P5E_CPU1_P0_RX_DP<8>")
	)
	(arc
		(start 104.883204 -293.18077)
		(mid 105.126531 -292.716204)
		(end 104.883204 -292.251638)
		(width 0.1143)
		(layer "In15.Cu")
		(net "P5E_CPU1_P0_RX_DP<8>")
	)
	(arc
		(start 104.262936 -295.92524)
		(mid 104.272775 -295.87643)
		(end 104.300528 -295.83507)
		(width 0.1143)
		(layer "In15.Cu")
		(net "P5E_CPU1_P0_RX_DP<8>")
	)
	(arc
		(start 104.812338 -285.730696)
		(mid 104.661953 -285.426404)
		(end 104.812338 -285.122112)
		(width 0.1143)
		(layer "In15.Cu")
		(net "P5E_CPU1_P0_RX_DP<8>")
	)
	(arc
		(start 104.656382 -270.846296)
		(mid 104.591867 -270.584077)
		(end 104.41305 -270.38173)
		(width 0.1143)
		(layer "In15.Cu")
		(net "P5E_CPU1_P0_RX_DP<8>")
	)
	(arc
		(start 106.596688 -361.270296)
		(mid 106.638418 -361.257769)
		(end 106.681778 -361.253532)
		(width 0.14224)
		(layer "In15.Cu")
		(net "P5E_CPU1_P0_RX_DP<8>")
	)
	(arc
		(start 104.836214 -292.224206)
		(mid 104.657997 -291.901929)
		(end 104.84358 -291.583872)
		(width 0.1143)
		(layer "In15.Cu")
		(net "P5E_CPU1_P0_RX_DP<8>")
	)
	(arc
		(start 104.792526 -282.476448)
		(mid 104.643812 -282.18638)
		(end 104.792526 -281.896312)
		(width 0.1143)
		(layer "In15.Cu")
		(net "P5E_CPU1_P0_RX_DP<8>")
	)
	(arc
		(start 104.883204 -276.980904)
		(mid 105.126531 -276.516338)
		(end 104.883204 -276.051772)
		(width 0.1143)
		(layer "In15.Cu")
		(net "P5E_CPU1_P0_RX_DP<8>")
	)
	(segment
		(start 105.027984 -273.010376)
		(end 104.561132 -273.276314)
		(width 0.12954)
		(layer "F.Cu")
		(net "P5E_CPU1_P0_RX_DP<7>")
	)
	(segment
		(start 56.0705 -386.003292)
		(end 56.5912 -386.003292)
		(width 0.127)
		(layer "F.Cu")
		(net "P5E_CPU1_P0_RX_DP<7>")
	)
	(segment
		(start 135.615172 -370.539518)
		(end 136.598914 -370.539518)
		(width 0.14224)
		(layer "In13.Cu")
		(net "P5E_CPU1_P0_RX_DP<7>")
	)
	(segment
		(start 103.72725 -374.71604)
		(end 108.680758 -374.71604)
		(width 0.14224)
		(layer "In13.Cu")
		(net "P5E_CPU1_P0_RX_DP<7>")
	)
	(segment
		(start 132.55371 -372.59133)
		(end 132.684266 -372.460774)
		(width 0.14224)
		(layer "In13.Cu")
		(net "P5E_CPU1_P0_RX_DP<7>")
	)
	(segment
		(start 103.904034 -277.648924)
		(end 103.873554 -277.631144)
		(width 0.1143)
		(layer "In13.Cu")
		(net "P5E_CPU1_P0_RX_DP<7>")
	)
	(segment
		(start 103.94315 -274.43176)
		(end 103.904034 -274.4089)
		(width 0.1143)
		(layer "In13.Cu")
		(net "P5E_CPU1_P0_RX_DP<7>")
	)
	(segment
		(start 103.904034 -275.383752)
		(end 103.94315 -275.360892)
		(width 0.1143)
		(layer "In13.Cu")
		(net "P5E_CPU1_P0_RX_DP<7>")
	)
	(segment
		(start 57.203086 -381.847344)
		(end 70.735952 -374.627648)
		(width 0.14224)
		(layer "In13.Cu")
		(net "P5E_CPU1_P0_RX_DP<7>")
	)
	(segment
		(start 111.562642 -376.468132)
		(end 112.912906 -377.026932)
		(width 0.14224)
		(layer "In13.Cu")
		(net "P5E_CPU1_P0_RX_DP<7>")
	)
	(segment
		(start 104.26319 -273.276314)
		(end 104.561132 -273.276314)
		(width 0.1143)
		(layer "In13.Cu")
		(net "P5E_CPU1_P0_RX_DP<7>")
	)
	(segment
		(start 115.179856 -305.594258)
		(end 114.323876 -304.083466)
		(width 0.14224)
		(layer "In13.Cu")
		(net "P5E_CPU1_P0_RX_DP<7>")
	)
	(segment
		(start 102.705154 -375.326402)
		(end 103.024178 -375.007378)
		(width 0.14224)
		(layer "In13.Cu")
		(net "P5E_CPU1_P0_RX_DP<7>")
	)
	(segment
		(start 103.94315 -280.911808)
		(end 103.904034 -280.888948)
		(width 0.1143)
		(layer "In13.Cu")
		(net "P5E_CPU1_P0_RX_DP<7>")
	)
	(segment
		(start 104.447848 -297.032426)
		(end 104.447848 -296.502582)
		(width 0.14224)
		(layer "In13.Cu")
		(net "P5E_CPU1_P0_RX_DP<7>")
	)
	(segment
		(start 103.904034 -292.228778)
		(end 103.873554 -292.210998)
		(width 0.1143)
		(layer "In13.Cu")
		(net "P5E_CPU1_P0_RX_DP<7>")
	)
	(segment
		(start 137.094214 -370.334286)
		(end 137.675366 -369.753134)
		(width 0.14224)
		(layer "In13.Cu")
		(net "P5E_CPU1_P0_RX_DP<7>")
	)
	(segment
		(start 103.904034 -281.8638)
		(end 103.94315 -281.84094)
		(width 0.1143)
		(layer "In13.Cu")
		(net "P5E_CPU1_P0_RX_DP<7>")
	)
	(segment
		(start 131.105402 -376.123708)
		(end 131.105402 -373.84609)
		(width 0.14224)
		(layer "In13.Cu")
		(net "P5E_CPU1_P0_RX_DP<7>")
	)
	(segment
		(start 103.873554 -285.121604)
		(end 103.904034 -285.103824)
		(width 0.1143)
		(layer "In13.Cu")
		(net "P5E_CPU1_P0_RX_DP<7>")
	)
	(segment
		(start 56.999632 -382.292098)
		(end 57.144412 -381.914146)
		(width 0.14224)
		(layer "In13.Cu")
		(net "P5E_CPU1_P0_RX_DP<7>")
	)
	(segment
		(start 137.885932 -369.244626)
		(end 137.940034 -368.9731)
		(width 0.14224)
		(layer "In13.Cu")
		(net "P5E_CPU1_P0_RX_DP<7>")
	)
	(segment
		(start 103.904034 -273.76374)
		(end 103.94315 -273.74088)
		(width 0.1143)
		(layer "In13.Cu")
		(net "P5E_CPU1_P0_RX_DP<7>")
	)
	(segment
		(start 115.78971 -377.079764)
		(end 130.188462 -377.079764)
		(width 0.14224)
		(layer "In13.Cu")
		(net "P5E_CPU1_P0_RX_DP<7>")
	)
	(segment
		(start 103.871522 -286.742632)
		(end 103.904034 -286.723836)
		(width 0.1143)
		(layer "In13.Cu")
		(net "P5E_CPU1_P0_RX_DP<7>")
	)
	(segment
		(start 132.81406 -372.147084)
		(end 132.81406 -371.257576)
		(width 0.14224)
		(layer "In13.Cu")
		(net "P5E_CPU1_P0_RX_DP<7>")
	)
	(segment
		(start 103.904034 -288.343848)
		(end 103.94315 -288.320988)
		(width 0.1143)
		(layer "In13.Cu")
		(net "P5E_CPU1_P0_RX_DP<7>")
	)
	(segment
		(start 111.876332 -302.372268)
		(end 107.475782 -300.01972)
		(width 0.14224)
		(layer "In13.Cu")
		(net "P5E_CPU1_P0_RX_DP<7>")
	)
	(segment
		(start 132.90931 -371.027452)
		(end 133.479794 -370.456968)
		(width 0.14224)
		(layer "In13.Cu")
		(net "P5E_CPU1_P0_RX_DP<7>")
	)
	(segment
		(start 103.904034 -280.888948)
		(end 103.873554 -280.871168)
		(width 0.1143)
		(layer "In13.Cu")
		(net "P5E_CPU1_P0_RX_DP<7>")
	)
	(segment
		(start 103.904034 -280.243788)
		(end 103.94315 -280.220928)
		(width 0.1143)
		(layer "In13.Cu")
		(net "P5E_CPU1_P0_RX_DP<7>")
	)
	(segment
		(start 126.628144 -321.762628)
		(end 124.327412 -317.924434)
		(width 0.14224)
		(layer "In13.Cu")
		(net "P5E_CPU1_P0_RX_DP<7>")
	)
	(segment
		(start 103.904034 -293.84879)
		(end 103.873554 -293.83101)
		(width 0.1143)
		(layer "In13.Cu")
		(net "P5E_CPU1_P0_RX_DP<7>")
	)
	(segment
		(start 136.598914 -370.539518)
		(end 137.094214 -370.334286)
		(width 0.14224)
		(layer "In13.Cu")
		(net "P5E_CPU1_P0_RX_DP<7>")
	)
	(segment
		(start 104.447848 -296.474134)
		(end 104.402128 -296.428414)
		(width 0.1143)
		(layer "In13.Cu")
		(net "P5E_CPU1_P0_RX_DP<7>")
	)
	(segment
		(start 130.804666 -337.31581)
		(end 130.08483 -332.451964)
		(width 0.14224)
		(layer "In13.Cu")
		(net "P5E_CPU1_P0_RX_DP<7>")
	)
	(segment
		(start 133.808724 -370.320824)
		(end 134.627112 -370.320824)
		(width 0.14224)
		(layer "In13.Cu")
		(net "P5E_CPU1_P0_RX_DP<7>")
	)
	(segment
		(start 103.873554 -278.641556)
		(end 103.904034 -278.623776)
		(width 0.1143)
		(layer "In13.Cu")
		(net "P5E_CPU1_P0_RX_DP<7>")
	)
	(segment
		(start 103.873554 -293.22141)
		(end 103.904034 -293.20363)
		(width 0.1143)
		(layer "In13.Cu")
		(net "P5E_CPU1_P0_RX_DP<7>")
	)
	(segment
		(start 78.337918 -377.171966)
		(end 101.048566 -377.171966)
		(width 0.14224)
		(layer "In13.Cu")
		(net "P5E_CPU1_P0_RX_DP<7>")
	)
	(segment
		(start 103.873554 -275.401532)
		(end 103.904034 -275.383752)
		(width 0.1143)
		(layer "In13.Cu")
		(net "P5E_CPU1_P0_RX_DP<7>")
	)
	(segment
		(start 137.675366 -369.753134)
		(end 137.885932 -369.244626)
		(width 0.14224)
		(layer "In13.Cu")
		(net "P5E_CPU1_P0_RX_DP<7>")
	)
	(segment
		(start 115.64747 -377.222004)
		(end 115.78971 -377.079764)
		(width 0.14224)
		(layer "In13.Cu")
		(net "P5E_CPU1_P0_RX_DP<7>")
	)
	(segment
		(start 103.94315 -279.291796)
		(end 103.904034 -279.268936)
		(width 0.1143)
		(layer "In13.Cu")
		(net "P5E_CPU1_P0_RX_DP<7>")
	)
	(segment
		(start 125.201426 -379.048264)
		(end 125.201426 -378.243084)
		(width 0.14224)
		(layer "In13.Cu")
		(net "P5E_CPU1_P0_RX_DP<7>")
	)
	(segment
		(start 128.499616 -326.516238)
		(end 126.628144 -321.762628)
		(width 0.14224)
		(layer "In13.Cu")
		(net "P5E_CPU1_P0_RX_DP<7>")
	)
	(segment
		(start 103.904034 -283.483812)
		(end 103.94315 -283.460952)
		(width 0.1143)
		(layer "In13.Cu")
		(net "P5E_CPU1_P0_RX_DP<7>")
	)
	(segment
		(start 137.940034 -364.897162)
		(end 134.264908 -352.747834)
		(width 0.14224)
		(layer "In13.Cu")
		(net "P5E_CPU1_P0_RX_DP<7>")
	)
	(segment
		(start 103.873554 -281.88158)
		(end 103.904034 -281.8638)
		(width 0.1143)
		(layer "In13.Cu")
		(net "P5E_CPU1_P0_RX_DP<7>")
	)
	(segment
		(start 114.22761 -379.048264)
		(end 114.53495 -379.355604)
		(width 0.14224)
		(layer "In13.Cu")
		(net "P5E_CPU1_P0_RX_DP<7>")
	)
	(segment
		(start 71.635112 -374.402604)
		(end 74.857356 -374.402604)
		(width 0.14224)
		(layer "In13.Cu")
		(net "P5E_CPU1_P0_RX_DP<7>")
	)
	(segment
		(start 103.873554 -273.78152)
		(end 103.904034 -273.76374)
		(width 0.1143)
		(layer "In13.Cu")
		(net "P5E_CPU1_P0_RX_DP<7>")
	)
	(segment
		(start 103.94315 -284.151832)
		(end 103.904034 -284.128972)
		(width 0.1143)
		(layer "In13.Cu")
		(net "P5E_CPU1_P0_RX_DP<7>")
	)
	(segment
		(start 124.894086 -379.355604)
		(end 125.201426 -379.048264)
		(width 0.14224)
		(layer "In13.Cu")
		(net "P5E_CPU1_P0_RX_DP<7>")
	)
	(segment
		(start 103.94315 -277.671784)
		(end 103.904034 -277.648924)
		(width 0.1143)
		(layer "In13.Cu")
		(net "P5E_CPU1_P0_RX_DP<7>")
	)
	(segment
		(start 115.78971 -377.935744)
		(end 115.64747 -377.793504)
		(width 0.14224)
		(layer "In13.Cu")
		(net "P5E_CPU1_P0_RX_DP<7>")
	)
	(segment
		(start 56.686196 -385.649216)
		(end 56.86044 -385.548632)
		(width 0.14224)
		(layer "In13.Cu")
		(net "P5E_CPU1_P0_RX_DP<7>")
	)
	(segment
		(start 103.904034 -282.50896)
		(end 103.873554 -282.49118)
		(width 0.1143)
		(layer "In13.Cu")
		(net "P5E_CPU1_P0_RX_DP<7>")
	)
	(segment
		(start 110.235238 -375.35993)
		(end 110.901988 -376.02668)
		(width 0.14224)
		(layer "In13.Cu")
		(net "P5E_CPU1_P0_RX_DP<7>")
	)
	(segment
		(start 102.667816 -375.854468)
		(end 102.667816 -375.416572)
		(width 0.14224)
		(layer "In13.Cu")
		(net "P5E_CPU1_P0_RX_DP<7>")
	)
	(segment
		(start 134.232904 -352.625406)
		(end 130.804666 -337.31581)
		(width 0.14224)
		(layer "In13.Cu")
		(net "P5E_CPU1_P0_RX_DP<7>")
	)
	(segment
		(start 103.904034 -284.128972)
		(end 103.873554 -284.111192)
		(width 0.1143)
		(layer "In13.Cu")
		(net "P5E_CPU1_P0_RX_DP<7>")
	)
	(segment
		(start 56.63565 -384.3528)
		(end 56.94045 -384.048)
		(width 0.14224)
		(layer "In13.Cu")
		(net "P5E_CPU1_P0_RX_DP<7>")
	)
	(segment
		(start 102.11816 -376.72899)
		(end 102.4382 -376.40895)
		(width 0.14224)
		(layer "In13.Cu")
		(net "P5E_CPU1_P0_RX_DP<7>")
	)
	(segment
		(start 103.873554 -280.261568)
		(end 103.904034 -280.243788)
		(width 0.1143)
		(layer "In13.Cu")
		(net "P5E_CPU1_P0_RX_DP<7>")
	)
	(segment
		(start 103.871522 -288.362644)
		(end 103.904034 -288.343848)
		(width 0.1143)
		(layer "In13.Cu")
		(net "P5E_CPU1_P0_RX_DP<7>")
	)
	(segment
		(start 103.904034 -274.4089)
		(end 103.873554 -274.39112)
		(width 0.1143)
		(layer "In13.Cu")
		(net "P5E_CPU1_P0_RX_DP<7>")
	)
	(segment
		(start 113.593626 -377.079764)
		(end 114.08537 -377.079764)
		(width 0.14224)
		(layer "In13.Cu")
		(net "P5E_CPU1_P0_RX_DP<7>")
	)
	(segment
		(start 103.904034 -288.988754)
		(end 103.873554 -288.970974)
		(width 0.1143)
		(layer "In13.Cu")
		(net "P5E_CPU1_P0_RX_DP<7>")
	)
	(segment
		(start 103.904034 -285.748984)
		(end 103.873554 -285.731204)
		(width 0.1143)
		(layer "In13.Cu")
		(net "P5E_CPU1_P0_RX_DP<7>")
	)
	(segment
		(start 104.299258 -295.985438)
		(end 103.9241 -295.610534)
		(width 0.1143)
		(layer "In13.Cu")
		(net "P5E_CPU1_P0_RX_DP<7>")
	)
	(segment
		(start 103.873554 -283.501592)
		(end 103.904034 -283.483812)
		(width 0.1143)
		(layer "In13.Cu")
		(net "P5E_CPU1_P0_RX_DP<7>")
	)
	(segment
		(start 56.632602 -384.731006)
		(end 56.63565 -384.3528)
		(width 0.14224)
		(layer "In13.Cu")
		(net "P5E_CPU1_P0_RX_DP<7>")
	)
	(segment
		(start 56.948578 -385.046982)
		(end 56.632602 -384.731006)
		(width 0.14224)
		(layer "In13.Cu")
		(net "P5E_CPU1_P0_RX_DP<7>")
	)
	(segment
		(start 130.419602 -377.03379)
		(end 130.705098 -376.91568)
		(width 0.14224)
		(layer "In13.Cu")
		(net "P5E_CPU1_P0_RX_DP<7>")
	)
	(segment
		(start 114.22761 -377.222004)
		(end 114.22761 -379.048264)
		(width 0.14224)
		(layer "In13.Cu")
		(net "P5E_CPU1_P0_RX_DP<7>")
	)
	(segment
		(start 103.873554 -277.021544)
		(end 103.904034 -277.003764)
		(width 0.1143)
		(layer "In13.Cu")
		(net "P5E_CPU1_P0_RX_DP<7>")
	)
	(segment
		(start 103.904034 -286.723836)
		(end 103.94315 -286.700976)
		(width 0.1143)
		(layer "In13.Cu")
		(net "P5E_CPU1_P0_RX_DP<7>")
	)
	(segment
		(start 103.904034 -277.003764)
		(end 103.94315 -276.980904)
		(width 0.1143)
		(layer "In13.Cu")
		(net "P5E_CPU1_P0_RX_DP<7>")
	)
	(segment
		(start 103.904034 -289.963606)
		(end 103.94315 -289.940746)
		(width 0.1143)
		(layer "In13.Cu")
		(net "P5E_CPU1_P0_RX_DP<7>")
	)
	(segment
		(start 104.447848 -296.502582)
		(end 104.447848 -296.474134)
		(width 0.1143)
		(layer "In13.Cu")
		(net "P5E_CPU1_P0_RX_DP<7>")
	)
	(segment
		(start 56.948578 -385.460494)
		(end 56.948578 -385.046982)
		(width 0.14224)
		(layer "In13.Cu")
		(net "P5E_CPU1_P0_RX_DP<7>")
	)
	(segment
		(start 103.904034 -290.608766)
		(end 103.873554 -290.590986)
		(width 0.1143)
		(layer "In13.Cu")
		(net "P5E_CPU1_P0_RX_DP<7>")
	)
	(segment
		(start 74.947272 -374.439942)
		(end 77.213714 -376.706384)
		(width 0.14224)
		(layer "In13.Cu")
		(net "P5E_CPU1_P0_RX_DP<7>")
	)
	(segment
		(start 137.940034 -368.9731)
		(end 137.940034 -364.897162)
		(width 0.14224)
		(layer "In13.Cu")
		(net "P5E_CPU1_P0_RX_DP<7>")
	)
	(segment
		(start 103.94315 -285.771844)
		(end 103.904034 -285.748984)
		(width 0.1143)
		(layer "In13.Cu")
		(net "P5E_CPU1_P0_RX_DP<7>")
	)
	(segment
		(start 103.94061 -287.390078)
		(end 103.873554 -287.350962)
		(width 0.1143)
		(layer "In13.Cu")
		(net "P5E_CPU1_P0_RX_DP<7>")
	)
	(segment
		(start 114.08537 -377.079764)
		(end 114.22761 -377.222004)
		(width 0.14224)
		(layer "In13.Cu")
		(net "P5E_CPU1_P0_RX_DP<7>")
	)
	(segment
		(start 107.115864 -299.75302)
		(end 104.485186 -297.122342)
		(width 0.14224)
		(layer "In13.Cu")
		(net "P5E_CPU1_P0_RX_DP<7>")
	)
	(segment
		(start 130.08483 -332.451964)
		(end 128.499616 -326.516238)
		(width 0.14224)
		(layer "In13.Cu")
		(net "P5E_CPU1_P0_RX_DP<7>")
	)
	(segment
		(start 103.904034 -293.20363)
		(end 103.94315 -293.18077)
		(width 0.1143)
		(layer "In13.Cu")
		(net "P5E_CPU1_P0_RX_DP<7>")
	)
	(segment
		(start 103.904034 -279.268936)
		(end 103.873554 -279.251156)
		(width 0.1143)
		(layer "In13.Cu")
		(net "P5E_CPU1_P0_RX_DP<7>")
	)
	(segment
		(start 103.94315 -282.53182)
		(end 103.904034 -282.50896)
		(width 0.1143)
		(layer "In13.Cu")
		(net "P5E_CPU1_P0_RX_DP<7>")
	)
	(segment
		(start 56.86044 -385.548632)
		(end 56.948578 -385.460494)
		(width 0.14224)
		(layer "In13.Cu")
		(net "P5E_CPU1_P0_RX_DP<7>")
	)
	(segment
		(start 103.826564 -294.894)
		(end 103.886508 -294.833802)
		(width 0.1143)
		(layer "In13.Cu")
		(net "P5E_CPU1_P0_RX_DP<7>")
	)
	(segment
		(start 124.894086 -377.935744)
		(end 115.78971 -377.935744)
		(width 0.14224)
		(layer "In13.Cu")
		(net "P5E_CPU1_P0_RX_DP<7>")
	)
	(segment
		(start 103.94315 -276.051772)
		(end 103.904034 -276.028912)
		(width 0.1143)
		(layer "In13.Cu")
		(net "P5E_CPU1_P0_RX_DP<7>")
	)
	(segment
		(start 103.904034 -278.623776)
		(end 103.94315 -278.600916)
		(width 0.1143)
		(layer "In13.Cu")
		(net "P5E_CPU1_P0_RX_DP<7>")
	)
	(segment
		(start 131.326382 -373.312436)
		(end 131.634738 -373.00408)
		(width 0.14224)
		(layer "In13.Cu")
		(net "P5E_CPU1_P0_RX_DP<7>")
	)
	(segment
		(start 103.904034 -276.028912)
		(end 103.873554 -276.011132)
		(width 0.1143)
		(layer "In13.Cu")
		(net "P5E_CPU1_P0_RX_DP<7>")
	)
	(segment
		(start 103.886508 -294.833802)
		(end 103.94315 -294.800782)
		(width 0.1143)
		(layer "In13.Cu")
		(net "P5E_CPU1_P0_RX_DP<7>")
	)
	(segment
		(start 104.180386 -273.359118)
		(end 104.26319 -273.276314)
		(width 0.1143)
		(layer "In13.Cu")
		(net "P5E_CPU1_P0_RX_DP<7>")
	)
	(segment
		(start 103.94315 -289.011614)
		(end 103.904034 -288.988754)
		(width 0.1143)
		(layer "In13.Cu")
		(net "P5E_CPU1_P0_RX_DP<7>")
	)
	(segment
		(start 125.201426 -378.243084)
		(end 124.894086 -377.935744)
		(width 0.14224)
		(layer "In13.Cu")
		(net "P5E_CPU1_P0_RX_DP<7>")
	)
	(segment
		(start 103.94315 -292.251638)
		(end 103.904034 -292.228778)
		(width 0.1143)
		(layer "In13.Cu")
		(net "P5E_CPU1_P0_RX_DP<7>")
	)
	(segment
		(start 103.94315 -293.87165)
		(end 103.904034 -293.84879)
		(width 0.1143)
		(layer "In13.Cu")
		(net "P5E_CPU1_P0_RX_DP<7>")
	)
	(segment
		(start 103.904034 -291.583618)
		(end 103.94315 -291.560758)
		(width 0.1143)
		(layer "In13.Cu")
		(net "P5E_CPU1_P0_RX_DP<7>")
	)
	(segment
		(start 103.873554 -291.601398)
		(end 103.904034 -291.583618)
		(width 0.1143)
		(layer "In13.Cu")
		(net "P5E_CPU1_P0_RX_DP<7>")
	)
	(segment
		(start 115.64747 -377.793504)
		(end 115.64747 -377.222004)
		(width 0.14224)
		(layer "In13.Cu")
		(net "P5E_CPU1_P0_RX_DP<7>")
	)
	(segment
		(start 103.904034 -285.103824)
		(end 103.94315 -285.080964)
		(width 0.1143)
		(layer "In13.Cu")
		(net "P5E_CPU1_P0_RX_DP<7>")
	)
	(segment
		(start 56.5912 -386.003292)
		(end 56.686196 -385.649216)
		(width 0.14224)
		(layer "In13.Cu")
		(net "P5E_CPU1_P0_RX_DP<7>")
	)
	(segment
		(start 114.53495 -379.355604)
		(end 124.894086 -379.355604)
		(width 0.14224)
		(layer "In13.Cu")
		(net "P5E_CPU1_P0_RX_DP<7>")
	)
	(segment
		(start 103.94315 -290.631626)
		(end 103.904034 -290.608766)
		(width 0.1143)
		(layer "In13.Cu")
		(net "P5E_CPU1_P0_RX_DP<7>")
	)
	(segment
		(start 103.873554 -289.981386)
		(end 103.904034 -289.963606)
		(width 0.1143)
		(layer "In13.Cu")
		(net "P5E_CPU1_P0_RX_DP<7>")
	)
	(segment
		(start 104.402128 -296.428414)
		(end 104.402128 -296.234104)
		(width 0.1143)
		(layer "In13.Cu")
		(net "P5E_CPU1_P0_RX_DP<7>")
	)
	(segment
		(start 124.327412 -317.924434)
		(end 115.179856 -305.594258)
		(width 0.14224)
		(layer "In13.Cu")
		(net "P5E_CPU1_P0_RX_DP<7>")
	)
	(segment
		(start 114.138456 -303.883822)
		(end 111.876332 -302.372268)
		(width 0.14224)
		(layer "In13.Cu")
		(net "P5E_CPU1_P0_RX_DP<7>")
	)
	(segment
		(start 56.94045 -384.048)
		(end 56.94045 -382.612138)
		(width 0.14224)
		(layer "In13.Cu")
		(net "P5E_CPU1_P0_RX_DP<7>")
	)
	(arc
		(start 103.873554 -290.590986)
		(mid 103.716577 -290.286186)
		(end 103.873554 -289.981386)
		(width 0.1143)
		(layer "In13.Cu")
		(net "P5E_CPU1_P0_RX_DP<7>")
	)
	(arc
		(start 103.873554 -277.631144)
		(mid 103.716577 -277.326344)
		(end 103.873554 -277.021544)
		(width 0.1143)
		(layer "In13.Cu")
		(net "P5E_CPU1_P0_RX_DP<7>")
	)
	(arc
		(start 77.213714 -376.706384)
		(mid 77.729517 -377.05097)
		(end 78.337918 -377.171966)
		(width 0.14224)
		(layer "In13.Cu")
		(net "P5E_CPU1_P0_RX_DP<7>")
	)
	(arc
		(start 74.857356 -374.402604)
		(mid 74.90604 -374.412306)
		(end 74.947272 -374.439942)
		(width 0.14224)
		(layer "In13.Cu")
		(net "P5E_CPU1_P0_RX_DP<7>")
	)
	(arc
		(start 103.873554 -282.49118)
		(mid 103.716577 -282.18638)
		(end 103.873554 -281.88158)
		(width 0.1143)
		(layer "In13.Cu")
		(net "P5E_CPU1_P0_RX_DP<7>")
	)
	(arc
		(start 103.873554 -287.350962)
		(mid 103.758127 -287.217586)
		(end 103.716582 -287.046162)
		(width 0.1143)
		(layer "In13.Cu")
		(net "P5E_CPU1_P0_RX_DP<7>")
	)
	(arc
		(start 103.873554 -288.970974)
		(mid 103.758127 -288.837598)
		(end 103.716582 -288.666174)
		(width 0.1143)
		(layer "In13.Cu")
		(net "P5E_CPU1_P0_RX_DP<7>")
	)
	(arc
		(start 70.735952 -374.627648)
		(mid 71.171676 -374.459758)
		(end 71.635112 -374.402604)
		(width 0.14224)
		(layer "In13.Cu")
		(net "P5E_CPU1_P0_RX_DP<7>")
	)
	(arc
		(start 103.94315 -273.74088)
		(mid 104.095137 -273.584372)
		(end 104.176576 -273.381978)
		(width 0.1143)
		(layer "In13.Cu")
		(net "P5E_CPU1_P0_RX_DP<7>")
	)
	(arc
		(start 102.4382 -376.40895)
		(mid 102.60813 -376.154537)
		(end 102.667816 -375.854468)
		(width 0.14224)
		(layer "In13.Cu")
		(net "P5E_CPU1_P0_RX_DP<7>")
	)
	(arc
		(start 132.81406 -371.257576)
		(mid 132.838828 -371.133061)
		(end 132.90931 -371.027452)
		(width 0.14224)
		(layer "In13.Cu")
		(net "P5E_CPU1_P0_RX_DP<7>")
	)
	(arc
		(start 107.475782 -300.01972)
		(mid 107.285975 -299.899658)
		(end 107.115864 -299.75302)
		(width 0.14224)
		(layer "In13.Cu")
		(net "P5E_CPU1_P0_RX_DP<7>")
	)
	(arc
		(start 103.94315 -283.460952)
		(mid 104.186477 -282.996386)
		(end 103.94315 -282.53182)
		(width 0.1143)
		(layer "In13.Cu")
		(net "P5E_CPU1_P0_RX_DP<7>")
	)
	(arc
		(start 103.94315 -276.980904)
		(mid 104.186477 -276.516338)
		(end 103.94315 -276.051772)
		(width 0.1143)
		(layer "In13.Cu")
		(net "P5E_CPU1_P0_RX_DP<7>")
	)
	(arc
		(start 103.94315 -293.18077)
		(mid 104.186477 -292.716204)
		(end 103.94315 -292.251638)
		(width 0.1143)
		(layer "In13.Cu")
		(net "P5E_CPU1_P0_RX_DP<7>")
	)
	(arc
		(start 103.716582 -288.666174)
		(mid 103.757548 -288.495768)
		(end 103.871522 -288.362644)
		(width 0.1143)
		(layer "In13.Cu")
		(net "P5E_CPU1_P0_RX_DP<7>")
	)
	(arc
		(start 131.634738 -373.00408)
		(mid 131.79113 -372.894937)
		(end 131.975606 -372.8466)
		(width 0.14224)
		(layer "In13.Cu")
		(net "P5E_CPU1_P0_RX_DP<7>")
	)
	(arc
		(start 103.873554 -284.111192)
		(mid 103.716577 -283.806392)
		(end 103.873554 -283.501592)
		(width 0.1143)
		(layer "In13.Cu")
		(net "P5E_CPU1_P0_RX_DP<7>")
	)
	(arc
		(start 103.94315 -278.600916)
		(mid 104.186477 -278.13635)
		(end 103.94315 -277.671784)
		(width 0.1143)
		(layer "In13.Cu")
		(net "P5E_CPU1_P0_RX_DP<7>")
	)
	(arc
		(start 103.024178 -375.007378)
		(mid 103.346735 -374.791759)
		(end 103.72725 -374.71604)
		(width 0.14224)
		(layer "In13.Cu")
		(net "P5E_CPU1_P0_RX_DP<7>")
	)
	(arc
		(start 134.264908 -352.747834)
		(mid 134.247781 -352.686914)
		(end 134.232904 -352.625406)
		(width 0.14224)
		(layer "In13.Cu")
		(net "P5E_CPU1_P0_RX_DP<7>")
	)
	(arc
		(start 132.399532 -372.710964)
		(mid 132.480384 -372.655997)
		(end 132.55371 -372.59133)
		(width 0.14224)
		(layer "In13.Cu")
		(net "P5E_CPU1_P0_RX_DP<7>")
	)
	(arc
		(start 103.94315 -285.080964)
		(mid 104.186477 -284.616398)
		(end 103.94315 -284.151832)
		(width 0.1143)
		(layer "In13.Cu")
		(net "P5E_CPU1_P0_RX_DP<7>")
	)
	(arc
		(start 103.873554 -292.210998)
		(mid 103.716577 -291.906198)
		(end 103.873554 -291.601398)
		(width 0.1143)
		(layer "In13.Cu")
		(net "P5E_CPU1_P0_RX_DP<7>")
	)
	(arc
		(start 103.94315 -286.700976)
		(mid 104.186477 -286.23641)
		(end 103.94315 -285.771844)
		(width 0.1143)
		(layer "In13.Cu")
		(net "P5E_CPU1_P0_RX_DP<7>")
	)
	(arc
		(start 130.188462 -377.079764)
		(mid 130.306298 -377.068163)
		(end 130.419602 -377.03379)
		(width 0.14224)
		(layer "In13.Cu")
		(net "P5E_CPU1_P0_RX_DP<7>")
	)
	(arc
		(start 133.479794 -370.456968)
		(mid 133.630708 -370.35613)
		(end 133.808724 -370.320824)
		(width 0.14224)
		(layer "In13.Cu")
		(net "P5E_CPU1_P0_RX_DP<7>")
	)
	(arc
		(start 103.94315 -275.360892)
		(mid 104.186477 -274.896326)
		(end 103.94315 -274.43176)
		(width 0.1143)
		(layer "In13.Cu")
		(net "P5E_CPU1_P0_RX_DP<7>")
	)
	(arc
		(start 104.402128 -296.234104)
		(mid 104.375399 -296.099549)
		(end 104.299258 -295.985438)
		(width 0.1143)
		(layer "In13.Cu")
		(net "P5E_CPU1_P0_RX_DP<7>")
	)
	(arc
		(start 108.680758 -374.71604)
		(mid 109.522038 -374.883381)
		(end 110.235238 -375.35993)
		(width 0.14224)
		(layer "In13.Cu")
		(net "P5E_CPU1_P0_RX_DP<7>")
	)
	(arc
		(start 135.395462 -370.501672)
		(mid 135.503692 -370.530027)
		(end 135.615172 -370.539518)
		(width 0.14224)
		(layer "In13.Cu")
		(net "P5E_CPU1_P0_RX_DP<7>")
	)
	(arc
		(start 101.048566 -377.171966)
		(mid 101.627416 -377.056843)
		(end 102.11816 -376.72899)
		(width 0.14224)
		(layer "In13.Cu")
		(net "P5E_CPU1_P0_RX_DP<7>")
	)
	(arc
		(start 103.94315 -288.320988)
		(mid 104.121963 -288.118638)
		(end 104.186482 -287.856422)
		(width 0.1143)
		(layer "In13.Cu")
		(net "P5E_CPU1_P0_RX_DP<7>")
	)
	(arc
		(start 132.684266 -372.460774)
		(mid 132.780402 -372.316851)
		(end 132.81406 -372.147084)
		(width 0.14224)
		(layer "In13.Cu")
		(net "P5E_CPU1_P0_RX_DP<7>")
	)
	(arc
		(start 104.176576 -273.381978)
		(mid 104.178599 -273.370568)
		(end 104.180386 -273.359118)
		(width 0.1143)
		(layer "In13.Cu")
		(net "P5E_CPU1_P0_RX_DP<7>")
	)
	(arc
		(start 57.144412 -381.914146)
		(mid 57.167716 -381.875444)
		(end 57.203086 -381.847344)
		(width 0.14224)
		(layer "In13.Cu")
		(net "P5E_CPU1_P0_RX_DP<7>")
	)
	(arc
		(start 110.901988 -376.02668)
		(mid 111.210569 -376.279948)
		(end 111.562642 -376.468132)
		(width 0.14224)
		(layer "In13.Cu")
		(net "P5E_CPU1_P0_RX_DP<7>")
	)
	(arc
		(start 134.627112 -370.320824)
		(mid 134.943106 -370.352046)
		(end 135.246872 -370.444522)
		(width 0.14224)
		(layer "In13.Cu")
		(net "P5E_CPU1_P0_RX_DP<7>")
	)
	(arc
		(start 104.186482 -287.856422)
		(mid 104.121246 -287.592831)
		(end 103.94061 -287.390078)
		(width 0.1143)
		(layer "In13.Cu")
		(net "P5E_CPU1_P0_RX_DP<7>")
	)
	(arc
		(start 103.843836 -295.51249)
		(mid 103.769758 -295.371286)
		(end 103.725472 -295.218104)
		(width 0.1143)
		(layer "In13.Cu")
		(net "P5E_CPU1_P0_RX_DP<7>")
	)
	(arc
		(start 113.432082 -377.091448)
		(mid 113.512644 -377.082703)
		(end 113.593626 -377.079764)
		(width 0.14224)
		(layer "In13.Cu")
		(net "P5E_CPU1_P0_RX_DP<7>")
	)
	(arc
		(start 132.155692 -372.815104)
		(mid 132.281014 -372.770998)
		(end 132.399532 -372.710964)
		(width 0.14224)
		(layer "In13.Cu")
		(net "P5E_CPU1_P0_RX_DP<7>")
	)
	(arc
		(start 103.873554 -280.871168)
		(mid 103.716577 -280.566368)
		(end 103.873554 -280.261568)
		(width 0.1143)
		(layer "In13.Cu")
		(net "P5E_CPU1_P0_RX_DP<7>")
	)
	(arc
		(start 102.667816 -375.416572)
		(mid 102.677522 -375.367777)
		(end 102.705154 -375.326402)
		(width 0.14224)
		(layer "In13.Cu")
		(net "P5E_CPU1_P0_RX_DP<7>")
	)
	(arc
		(start 131.105402 -373.84609)
		(mid 131.16283 -373.55729)
		(end 131.326382 -373.312436)
		(width 0.14224)
		(layer "In13.Cu")
		(net "P5E_CPU1_P0_RX_DP<7>")
	)
	(arc
		(start 103.94315 -289.940746)
		(mid 104.186477 -289.47618)
		(end 103.94315 -289.011614)
		(width 0.1143)
		(layer "In13.Cu")
		(net "P5E_CPU1_P0_RX_DP<7>")
	)
	(arc
		(start 103.716582 -287.046162)
		(mid 103.757548 -286.875756)
		(end 103.871522 -286.742632)
		(width 0.1143)
		(layer "In13.Cu")
		(net "P5E_CPU1_P0_RX_DP<7>")
	)
	(arc
		(start 103.9241 -295.610534)
		(mid 103.881476 -295.563551)
		(end 103.843836 -295.51249)
		(width 0.1143)
		(layer "In13.Cu")
		(net "P5E_CPU1_P0_RX_DP<7>")
	)
	(arc
		(start 103.873554 -276.011132)
		(mid 103.716577 -275.706332)
		(end 103.873554 -275.401532)
		(width 0.1143)
		(layer "In13.Cu")
		(net "P5E_CPU1_P0_RX_DP<7>")
	)
	(arc
		(start 103.725472 -295.218104)
		(mid 103.736249 -295.043652)
		(end 103.826564 -294.894)
		(width 0.1143)
		(layer "In13.Cu")
		(net "P5E_CPU1_P0_RX_DP<7>")
	)
	(arc
		(start 103.873554 -274.39112)
		(mid 103.716577 -274.08632)
		(end 103.873554 -273.78152)
		(width 0.1143)
		(layer "In13.Cu")
		(net "P5E_CPU1_P0_RX_DP<7>")
	)
	(arc
		(start 114.323876 -304.083466)
		(mid 114.242858 -303.972784)
		(end 114.138456 -303.883822)
		(width 0.14224)
		(layer "In13.Cu")
		(net "P5E_CPU1_P0_RX_DP<7>")
	)
	(arc
		(start 103.94315 -280.220928)
		(mid 104.186477 -279.756362)
		(end 103.94315 -279.291796)
		(width 0.1143)
		(layer "In13.Cu")
		(net "P5E_CPU1_P0_RX_DP<7>")
	)
	(arc
		(start 56.94045 -382.612138)
		(mid 56.955347 -382.449401)
		(end 56.999632 -382.292098)
		(width 0.14224)
		(layer "In13.Cu")
		(net "P5E_CPU1_P0_RX_DP<7>")
	)
	(arc
		(start 112.912906 -377.026932)
		(mid 113.168138 -377.094269)
		(end 113.432082 -377.091448)
		(width 0.14224)
		(layer "In13.Cu")
		(net "P5E_CPU1_P0_RX_DP<7>")
	)
	(arc
		(start 135.246872 -370.444522)
		(mid 135.32079 -370.474078)
		(end 135.395462 -370.501672)
		(width 0.14224)
		(layer "In13.Cu")
		(net "P5E_CPU1_P0_RX_DP<7>")
	)
	(arc
		(start 130.932936 -376.723402)
		(mid 131.061508 -376.43573)
		(end 131.105402 -376.123708)
		(width 0.14224)
		(layer "In13.Cu")
		(net "P5E_CPU1_P0_RX_DP<7>")
	)
	(arc
		(start 130.705098 -376.91568)
		(mid 130.834016 -376.837305)
		(end 130.932936 -376.723402)
		(width 0.14224)
		(layer "In13.Cu")
		(net "P5E_CPU1_P0_RX_DP<7>")
	)
	(arc
		(start 103.94315 -291.560758)
		(mid 104.186477 -291.096192)
		(end 103.94315 -290.631626)
		(width 0.1143)
		(layer "In13.Cu")
		(net "P5E_CPU1_P0_RX_DP<7>")
	)
	(arc
		(start 103.873554 -293.83101)
		(mid 103.716577 -293.52621)
		(end 103.873554 -293.22141)
		(width 0.1143)
		(layer "In13.Cu")
		(net "P5E_CPU1_P0_RX_DP<7>")
	)
	(arc
		(start 104.485186 -297.122342)
		(mid 104.457567 -297.081102)
		(end 104.447848 -297.032426)
		(width 0.14224)
		(layer "In13.Cu")
		(net "P5E_CPU1_P0_RX_DP<7>")
	)
	(arc
		(start 103.94315 -294.800782)
		(mid 104.186477 -294.336216)
		(end 103.94315 -293.87165)
		(width 0.1143)
		(layer "In13.Cu")
		(net "P5E_CPU1_P0_RX_DP<7>")
	)
	(arc
		(start 103.873554 -279.251156)
		(mid 103.716577 -278.946356)
		(end 103.873554 -278.641556)
		(width 0.1143)
		(layer "In13.Cu")
		(net "P5E_CPU1_P0_RX_DP<7>")
	)
	(arc
		(start 103.873554 -285.731204)
		(mid 103.716577 -285.426404)
		(end 103.873554 -285.121604)
		(width 0.1143)
		(layer "In13.Cu")
		(net "P5E_CPU1_P0_RX_DP<7>")
	)
	(arc
		(start 131.975606 -372.8466)
		(mid 132.066428 -372.835309)
		(end 132.155692 -372.815104)
		(width 0.14224)
		(layer "In13.Cu")
		(net "P5E_CPU1_P0_RX_DP<7>")
	)
	(arc
		(start 103.94315 -281.84094)
		(mid 104.186477 -281.376374)
		(end 103.94315 -280.911808)
		(width 0.1143)
		(layer "In13.Cu")
		(net "P5E_CPU1_P0_RX_DP<7>")
	)
	(segment
		(start 54.870604 -386.003292)
		(end 55.391304 -386.003292)
		(width 0.127)
		(layer "F.Cu")
		(net "P5E_CPU1_P0_RX_DP<6>")
	)
	(segment
		(start 105.027984 -271.390364)
		(end 104.561132 -271.656302)
		(width 0.12954)
		(layer "F.Cu")
		(net "P5E_CPU1_P0_RX_DP<6>")
	)
	(segment
		(start 102.9335 -275.401532)
		(end 103.003096 -275.360892)
		(width 0.1143)
		(layer "In13.Cu")
		(net "P5E_CPU1_P0_RX_DP<6>")
	)
	(segment
		(start 55.391304 -386.003292)
		(end 55.4863 -385.649216)
		(width 0.14224)
		(layer "In13.Cu")
		(net "P5E_CPU1_P0_RX_DP<6>")
	)
	(segment
		(start 103.420164 -272.961608)
		(end 103.420926 -272.961354)
		(width 0.1143)
		(layer "In13.Cu")
		(net "P5E_CPU1_P0_RX_DP<6>")
	)
	(segment
		(start 104.180386 -271.739106)
		(end 104.26319 -271.656302)
		(width 0.1143)
		(layer "In13.Cu")
		(net "P5E_CPU1_P0_RX_DP<6>")
	)
	(segment
		(start 132.295392 -365.667544)
		(end 132.437632 -365.525304)
		(width 0.14224)
		(layer "In13.Cu")
		(net "P5E_CPU1_P0_RX_DP<6>")
	)
	(segment
		(start 136.999218 -366.602518)
		(end 136.999218 -365.341154)
		(width 0.14224)
		(layer "In13.Cu")
		(net "P5E_CPU1_P0_RX_DP<6>")
	)
	(segment
		(start 55.4863 -385.649216)
		(end 55.660544 -385.548632)
		(width 0.14224)
		(layer "In13.Cu")
		(net "P5E_CPU1_P0_RX_DP<6>")
	)
	(segment
		(start 103.428292 -368.072162)
		(end 103.120952 -368.379502)
		(width 0.14224)
		(layer "In13.Cu")
		(net "P5E_CPU1_P0_RX_DP<6>")
	)
	(segment
		(start 102.9335 -289.981132)
		(end 103.003096 -289.940746)
		(width 0.1143)
		(layer "In13.Cu")
		(net "P5E_CPU1_P0_RX_DP<6>")
	)
	(segment
		(start 103.428292 -272.958306)
		(end 103.429054 -272.957798)
		(width 0.1143)
		(layer "In13.Cu")
		(net "P5E_CPU1_P0_RX_DP<6>")
	)
	(segment
		(start 56.186832 -380.862332)
		(end 63.582296 -368.781584)
		(width 0.14224)
		(layer "In13.Cu")
		(net "P5E_CPU1_P0_RX_DP<6>")
	)
	(segment
		(start 75.688698 -367.767362)
		(end 74.317352 -367.767362)
		(width 0.14224)
		(layer "In13.Cu")
		(net "P5E_CPU1_P0_RX_DP<6>")
	)
	(segment
		(start 103.434642 -272.954242)
		(end 103.43769 -272.951956)
		(width 0.1143)
		(layer "In13.Cu")
		(net "P5E_CPU1_P0_RX_DP<6>")
	)
	(segment
		(start 103.000556 -287.389824)
		(end 102.933246 -287.350962)
		(width 0.1143)
		(layer "In13.Cu")
		(net "P5E_CPU1_P0_RX_DP<6>")
	)
	(segment
		(start 75.688698 -369.187222)
		(end 75.996038 -368.879882)
		(width 0.14224)
		(layer "In13.Cu")
		(net "P5E_CPU1_P0_RX_DP<6>")
	)
	(segment
		(start 115.906042 -308.481984)
		(end 114.441224 -306.290218)
		(width 0.14224)
		(layer "In13.Cu")
		(net "P5E_CPU1_P0_RX_DP<6>")
	)
	(segment
		(start 132.003292 -367.801144)
		(end 132.295392 -367.509044)
		(width 0.14224)
		(layer "In13.Cu")
		(net "P5E_CPU1_P0_RX_DP<6>")
	)
	(segment
		(start 103.001572 -284.150816)
		(end 102.932484 -284.11043)
		(width 0.1143)
		(layer "In13.Cu")
		(net "P5E_CPU1_P0_RX_DP<6>")
	)
	(segment
		(start 106.379772 -300.47184)
		(end 103.396542 -297.488356)
		(width 0.14224)
		(layer "In13.Cu")
		(net "P5E_CPU1_P0_RX_DP<6>")
	)
	(segment
		(start 102.9335 -293.22141)
		(end 102.934262 -293.220902)
		(width 0.1143)
		(layer "In13.Cu")
		(net "P5E_CPU1_P0_RX_DP<6>")
	)
	(segment
		(start 55.435754 -384.3528)
		(end 55.740554 -384.048)
		(width 0.14224)
		(layer "In13.Cu")
		(net "P5E_CPU1_P0_RX_DP<6>")
	)
	(segment
		(start 133.151372 -367.509044)
		(end 133.443472 -367.801144)
		(width 0.14224)
		(layer "In13.Cu")
		(net "P5E_CPU1_P0_RX_DP<6>")
	)
	(segment
		(start 133.151372 -366.688624)
		(end 133.151372 -367.509044)
		(width 0.14224)
		(layer "In13.Cu")
		(net "P5E_CPU1_P0_RX_DP<6>")
	)
	(segment
		(start 103.431594 -272.956274)
		(end 103.433372 -272.955004)
		(width 0.1143)
		(layer "In13.Cu")
		(net "P5E_CPU1_P0_RX_DP<6>")
	)
	(segment
		(start 74.317352 -367.767362)
		(end 74.175112 -367.625122)
		(width 0.14224)
		(layer "In13.Cu")
		(net "P5E_CPU1_P0_RX_DP<6>")
	)
	(segment
		(start 135.20801 -366.381284)
		(end 133.458712 -366.381284)
		(width 0.14224)
		(layer "In13.Cu")
		(net "P5E_CPU1_P0_RX_DP<6>")
	)
	(segment
		(start 103.43769 -272.951956)
		(end 103.442262 -272.948908)
		(width 0.1143)
		(layer "In13.Cu")
		(net "P5E_CPU1_P0_RX_DP<6>")
	)
	(segment
		(start 133.458712 -366.381284)
		(end 133.151372 -366.688624)
		(width 0.14224)
		(layer "In13.Cu")
		(net "P5E_CPU1_P0_RX_DP<6>")
	)
	(segment
		(start 133.443472 -367.801144)
		(end 135.800592 -367.801144)
		(width 0.14224)
		(layer "In13.Cu")
		(net "P5E_CPU1_P0_RX_DP<6>")
	)
	(segment
		(start 102.776274 -295.13276)
		(end 102.776528 -295.133014)
		(width 0.1143)
		(layer "In13.Cu")
		(net "P5E_CPU1_P0_RX_DP<6>")
	)
	(segment
		(start 74.317352 -366.911382)
		(end 108.425488 -366.911382)
		(width 0.14224)
		(layer "In13.Cu")
		(net "P5E_CPU1_P0_RX_DP<6>")
	)
	(segment
		(start 135.20801 -365.525304)
		(end 135.35025 -365.667544)
		(width 0.14224)
		(layer "In13.Cu")
		(net "P5E_CPU1_P0_RX_DP<6>")
	)
	(segment
		(start 121.23547 -315.486796)
		(end 115.906042 -308.481984)
		(width 0.14224)
		(layer "In13.Cu")
		(net "P5E_CPU1_P0_RX_DP<6>")
	)
	(segment
		(start 108.567728 -367.053622)
		(end 108.567728 -367.929922)
		(width 0.14224)
		(layer "In13.Cu")
		(net "P5E_CPU1_P0_RX_DP<6>")
	)
	(segment
		(start 55.748682 -385.046982)
		(end 55.432706 -384.731006)
		(width 0.14224)
		(layer "In13.Cu")
		(net "P5E_CPU1_P0_RX_DP<6>")
	)
	(segment
		(start 110.292388 -367.928144)
		(end 110.419388 -367.801144)
		(width 0.14224)
		(layer "In13.Cu")
		(net "P5E_CPU1_P0_RX_DP<6>")
	)
	(segment
		(start 72.613012 -366.911382)
		(end 72.755252 -367.053622)
		(width 0.14224)
		(layer "In13.Cu")
		(net "P5E_CPU1_P0_RX_DP<6>")
	)
	(segment
		(start 103.433372 -272.955004)
		(end 103.434642 -272.954242)
		(width 0.1143)
		(layer "In13.Cu")
		(net "P5E_CPU1_P0_RX_DP<6>")
	)
	(segment
		(start 103.42753 -272.957544)
		(end 103.427784 -272.957544)
		(width 0.1143)
		(layer "In13.Cu")
		(net "P5E_CPU1_P0_RX_DP<6>")
	)
	(segment
		(start 102.931468 -288.36239)
		(end 103.002842 -288.321242)
		(width 0.1143)
		(layer "In13.Cu")
		(net "P5E_CPU1_P0_RX_DP<6>")
	)
	(segment
		(start 104.26319 -271.656302)
		(end 104.561132 -271.656302)
		(width 0.1143)
		(layer "In13.Cu")
		(net "P5E_CPU1_P0_RX_DP<6>")
	)
	(segment
		(start 132.295392 -367.509044)
		(end 132.295392 -365.667544)
		(width 0.14224)
		(layer "In13.Cu")
		(net "P5E_CPU1_P0_RX_DP<6>")
	)
	(segment
		(start 103.402384 -272.972022)
		(end 103.419402 -272.962116)
		(width 0.1143)
		(layer "In13.Cu")
		(net "P5E_CPU1_P0_RX_DP<6>")
	)
	(segment
		(start 73.062592 -369.187222)
		(end 75.688698 -369.187222)
		(width 0.14224)
		(layer "In13.Cu")
		(net "P5E_CPU1_P0_RX_DP<6>")
	)
	(segment
		(start 103.427784 -272.957544)
		(end 103.428292 -272.958306)
		(width 0.1143)
		(layer "In13.Cu")
		(net "P5E_CPU1_P0_RX_DP<6>")
	)
	(segment
		(start 102.934262 -293.220902)
		(end 103.002842 -293.181024)
		(width 0.1143)
		(layer "In13.Cu")
		(net "P5E_CPU1_P0_RX_DP<6>")
	)
	(segment
		(start 103.003096 -290.631626)
		(end 102.9335 -290.590986)
		(width 0.1143)
		(layer "In13.Cu")
		(net "P5E_CPU1_P0_RX_DP<6>")
	)
	(segment
		(start 102.776274 -295.370504)
		(end 102.776274 -295.13276)
		(width 0.1143)
		(layer "In13.Cu")
		(net "P5E_CPU1_P0_RX_DP<6>")
	)
	(segment
		(start 108.567728 -367.929922)
		(end 108.425488 -368.072162)
		(width 0.14224)
		(layer "In13.Cu")
		(net "P5E_CPU1_P0_RX_DP<6>")
	)
	(segment
		(start 63.853314 -368.474498)
		(end 65.555368 -367.112804)
		(width 0.14224)
		(layer "In13.Cu")
		(net "P5E_CPU1_P0_RX_DP<6>")
	)
	(segment
		(start 135.35025 -366.239044)
		(end 135.20801 -366.381284)
		(width 0.14224)
		(layer "In13.Cu")
		(net "P5E_CPU1_P0_RX_DP<6>")
	)
	(segment
		(start 103.001572 -282.530804)
		(end 102.932484 -282.490418)
		(width 0.1143)
		(layer "In13.Cu")
		(net "P5E_CPU1_P0_RX_DP<6>")
	)
	(segment
		(start 133.397498 -353.469448)
		(end 131.108196 -344.329258)
		(width 0.14224)
		(layer "In13.Cu")
		(net "P5E_CPU1_P0_RX_DP<6>")
	)
	(segment
		(start 75.996038 -368.879882)
		(end 75.996038 -368.074702)
		(width 0.14224)
		(layer "In13.Cu")
		(net "P5E_CPU1_P0_RX_DP<6>")
	)
	(segment
		(start 103.430832 -272.956782)
		(end 103.431594 -272.956274)
		(width 0.1143)
		(layer "In13.Cu")
		(net "P5E_CPU1_P0_RX_DP<6>")
	)
	(segment
		(start 103.003096 -277.671784)
		(end 102.9335 -277.631144)
		(width 0.1143)
		(layer "In13.Cu")
		(net "P5E_CPU1_P0_RX_DP<6>")
	)
	(segment
		(start 55.743348 -382.89611)
		(end 56.147462 -380.961138)
		(width 0.14224)
		(layer "In13.Cu")
		(net "P5E_CPU1_P0_RX_DP<6>")
	)
	(segment
		(start 109.985048 -369.796822)
		(end 110.292388 -369.489482)
		(width 0.14224)
		(layer "In13.Cu")
		(net "P5E_CPU1_P0_RX_DP<6>")
	)
	(segment
		(start 102.931468 -286.742378)
		(end 103.002842 -286.70123)
		(width 0.1143)
		(layer "In13.Cu")
		(net "P5E_CPU1_P0_RX_DP<6>")
	)
	(segment
		(start 103.176832 -295.97731)
		(end 102.922832 -295.72331)
		(width 0.1143)
		(layer "In13.Cu")
		(net "P5E_CPU1_P0_RX_DP<6>")
	)
	(segment
		(start 102.93223 -285.122366)
		(end 103.001572 -285.08198)
		(width 0.1143)
		(layer "In13.Cu")
		(net "P5E_CPU1_P0_RX_DP<6>")
	)
	(segment
		(start 110.292388 -369.489482)
		(end 110.292388 -367.928144)
		(width 0.14224)
		(layer "In13.Cu")
		(net "P5E_CPU1_P0_RX_DP<6>")
	)
	(segment
		(start 103.244904 -294.419528)
		(end 103.244904 -294.291766)
		(width 0.1143)
		(layer "In13.Cu")
		(net "P5E_CPU1_P0_RX_DP<6>")
	)
	(segment
		(start 114.441224 -306.290218)
		(end 113.74501 -304.98796)
		(width 0.14224)
		(layer "In13.Cu")
		(net "P5E_CPU1_P0_RX_DP<6>")
	)
	(segment
		(start 103.424736 -272.959068)
		(end 103.42626 -272.958306)
		(width 0.1143)
		(layer "In13.Cu")
		(net "P5E_CPU1_P0_RX_DP<6>")
	)
	(segment
		(start 103.428292 -369.796822)
		(end 109.985048 -369.796822)
		(width 0.14224)
		(layer "In13.Cu")
		(net "P5E_CPU1_P0_RX_DP<6>")
	)
	(segment
		(start 103.359204 -296.598086)
		(end 103.313484 -296.552366)
		(width 0.1143)
		(layer "In13.Cu")
		(net "P5E_CPU1_P0_RX_DP<6>")
	)
	(segment
		(start 103.423974 -272.959576)
		(end 103.424736 -272.959068)
		(width 0.1143)
		(layer "In13.Cu")
		(net "P5E_CPU1_P0_RX_DP<6>")
	)
	(segment
		(start 103.359204 -297.398186)
		(end 103.359204 -296.612564)
		(width 0.14224)
		(layer "In13.Cu")
		(net "P5E_CPU1_P0_RX_DP<6>")
	)
	(segment
		(start 103.429054 -272.957798)
		(end 103.430832 -272.956782)
		(width 0.1143)
		(layer "In13.Cu")
		(net "P5E_CPU1_P0_RX_DP<6>")
	)
	(segment
		(start 102.9335 -278.641556)
		(end 103.003096 -278.600916)
		(width 0.1143)
		(layer "In13.Cu")
		(net "P5E_CPU1_P0_RX_DP<6>")
	)
	(segment
		(start 103.359204 -296.612564)
		(end 103.359204 -296.598086)
		(width 0.1143)
		(layer "In13.Cu")
		(net "P5E_CPU1_P0_RX_DP<6>")
	)
	(segment
		(start 103.442262 -272.948908)
		(end 103.47325 -272.930874)
		(width 0.1143)
		(layer "In13.Cu")
		(net "P5E_CPU1_P0_RX_DP<6>")
	)
	(segment
		(start 55.432706 -384.731006)
		(end 55.435754 -384.3528)
		(width 0.14224)
		(layer "In13.Cu")
		(net "P5E_CPU1_P0_RX_DP<6>")
	)
	(segment
		(start 136.999218 -365.341154)
		(end 133.397498 -353.469448)
		(width 0.14224)
		(layer "In13.Cu")
		(net "P5E_CPU1_P0_RX_DP<6>")
	)
	(segment
		(start 55.660544 -385.548632)
		(end 55.748682 -385.460494)
		(width 0.14224)
		(layer "In13.Cu")
		(net "P5E_CPU1_P0_RX_DP<6>")
	)
	(segment
		(start 131.108196 -344.329258)
		(end 128.641348 -331.082904)
		(width 0.14224)
		(layer "In13.Cu")
		(net "P5E_CPU1_P0_RX_DP<6>")
	)
	(segment
		(start 75.996038 -368.074702)
		(end 75.688698 -367.767362)
		(width 0.14224)
		(layer "In13.Cu")
		(net "P5E_CPU1_P0_RX_DP<6>")
	)
	(segment
		(start 102.9335 -280.870914)
		(end 102.9335 -280.871168)
		(width 0.1143)
		(layer "In13.Cu")
		(net "P5E_CPU1_P0_RX_DP<6>")
	)
	(segment
		(start 103.001572 -280.910792)
		(end 102.9335 -280.870914)
		(width 0.1143)
		(layer "In13.Cu")
		(net "P5E_CPU1_P0_RX_DP<6>")
	)
	(segment
		(start 135.35025 -365.667544)
		(end 135.35025 -366.239044)
		(width 0.14224)
		(layer "In13.Cu")
		(net "P5E_CPU1_P0_RX_DP<6>")
	)
	(segment
		(start 103.00335 -285.771844)
		(end 102.932484 -285.730442)
		(width 0.1143)
		(layer "In13.Cu")
		(net "P5E_CPU1_P0_RX_DP<6>")
	)
	(segment
		(start 108.425488 -366.911382)
		(end 108.567728 -367.053622)
		(width 0.14224)
		(layer "In13.Cu")
		(net "P5E_CPU1_P0_RX_DP<6>")
	)
	(segment
		(start 103.003096 -292.251638)
		(end 102.9335 -292.210998)
		(width 0.1143)
		(layer "In13.Cu")
		(net "P5E_CPU1_P0_RX_DP<6>")
	)
	(segment
		(start 102.9335 -273.78152)
		(end 103.003096 -273.74088)
		(width 0.1143)
		(layer "In13.Cu")
		(net "P5E_CPU1_P0_RX_DP<6>")
	)
	(segment
		(start 72.755252 -367.053622)
		(end 72.755252 -368.879882)
		(width 0.14224)
		(layer "In13.Cu")
		(net "P5E_CPU1_P0_RX_DP<6>")
	)
	(segment
		(start 113.514886 -304.732944)
		(end 110.885478 -302.975772)
		(width 0.14224)
		(layer "In13.Cu")
		(net "P5E_CPU1_P0_RX_DP<6>")
	)
	(segment
		(start 102.93223 -281.882342)
		(end 103.001572 -281.841956)
		(width 0.1143)
		(layer "In13.Cu")
		(net "P5E_CPU1_P0_RX_DP<6>")
	)
	(segment
		(start 102.9335 -291.601144)
		(end 103.003096 -291.560758)
		(width 0.1143)
		(layer "In13.Cu")
		(net "P5E_CPU1_P0_RX_DP<6>")
	)
	(segment
		(start 103.873554 -272.161508)
		(end 103.94315 -272.120868)
		(width 0.1143)
		(layer "In13.Cu")
		(net "P5E_CPU1_P0_RX_DP<6>")
	)
	(segment
		(start 103.120952 -368.379502)
		(end 103.120952 -369.489482)
		(width 0.14224)
		(layer "In13.Cu")
		(net "P5E_CPU1_P0_RX_DP<6>")
	)
	(segment
		(start 102.93223 -283.502354)
		(end 103.001572 -283.461968)
		(width 0.1143)
		(layer "In13.Cu")
		(net "P5E_CPU1_P0_RX_DP<6>")
	)
	(segment
		(start 103.419402 -272.962116)
		(end 103.420164 -272.961608)
		(width 0.1143)
		(layer "In13.Cu")
		(net "P5E_CPU1_P0_RX_DP<6>")
	)
	(segment
		(start 103.003096 -289.011614)
		(end 102.9335 -288.970974)
		(width 0.1143)
		(layer "In13.Cu")
		(net "P5E_CPU1_P0_RX_DP<6>")
	)
	(segment
		(start 128.116584 -329.01509)
		(end 126.763018 -324.832472)
		(width 0.14224)
		(layer "In13.Cu")
		(net "P5E_CPU1_P0_RX_DP<6>")
	)
	(segment
		(start 55.748682 -385.460494)
		(end 55.748682 -385.046982)
		(width 0.14224)
		(layer "In13.Cu")
		(net "P5E_CPU1_P0_RX_DP<6>")
	)
	(segment
		(start 113.673382 -304.89144)
		(end 113.514886 -304.732944)
		(width 0.14224)
		(layer "In13.Cu")
		(net "P5E_CPU1_P0_RX_DP<6>")
	)
	(segment
		(start 66.129662 -366.911382)
		(end 72.613012 -366.911382)
		(width 0.14224)
		(layer "In13.Cu")
		(net "P5E_CPU1_P0_RX_DP<6>")
	)
	(segment
		(start 132.437632 -365.525304)
		(end 135.20801 -365.525304)
		(width 0.14224)
		(layer "In13.Cu")
		(net "P5E_CPU1_P0_RX_DP<6>")
	)
	(segment
		(start 103.120952 -369.489482)
		(end 103.428292 -369.796822)
		(width 0.14224)
		(layer "In13.Cu")
		(net "P5E_CPU1_P0_RX_DP<6>")
	)
	(segment
		(start 55.740554 -384.048)
		(end 55.740554 -382.922272)
		(width 0.14224)
		(layer "In13.Cu")
		(net "P5E_CPU1_P0_RX_DP<6>")
	)
	(segment
		(start 103.422704 -272.960338)
		(end 103.423974 -272.959576)
		(width 0.1143)
		(layer "In13.Cu")
		(net "P5E_CPU1_P0_RX_DP<6>")
	)
	(segment
		(start 125.024642 -321.157854)
		(end 121.23547 -315.486796)
		(width 0.14224)
		(layer "In13.Cu")
		(net "P5E_CPU1_P0_RX_DP<6>")
	)
	(segment
		(start 103.003096 -279.291796)
		(end 102.9335 -279.251156)
		(width 0.1143)
		(layer "In13.Cu")
		(net "P5E_CPU1_P0_RX_DP<6>")
	)
	(segment
		(start 103.313484 -296.552366)
		(end 103.313484 -296.307764)
		(width 0.1143)
		(layer "In13.Cu")
		(net "P5E_CPU1_P0_RX_DP<6>")
	)
	(segment
		(start 108.425488 -368.072162)
		(end 103.428292 -368.072162)
		(width 0.14224)
		(layer "In13.Cu")
		(net "P5E_CPU1_P0_RX_DP<6>")
	)
	(segment
		(start 72.755252 -368.879882)
		(end 73.062592 -369.187222)
		(width 0.14224)
		(layer "In13.Cu")
		(net "P5E_CPU1_P0_RX_DP<6>")
	)
	(segment
		(start 102.9335 -277.021544)
		(end 103.003096 -276.980904)
		(width 0.1143)
		(layer "In13.Cu")
		(net "P5E_CPU1_P0_RX_DP<6>")
	)
	(segment
		(start 74.175112 -367.625122)
		(end 74.175112 -367.053622)
		(width 0.14224)
		(layer "In13.Cu")
		(net "P5E_CPU1_P0_RX_DP<6>")
	)
	(segment
		(start 110.885478 -302.975772)
		(end 106.841544 -300.813978)
		(width 0.14224)
		(layer "In13.Cu")
		(net "P5E_CPU1_P0_RX_DP<6>")
	)
	(segment
		(start 126.763018 -324.832472)
		(end 125.024642 -321.157854)
		(width 0.14224)
		(layer "In13.Cu")
		(net "P5E_CPU1_P0_RX_DP<6>")
	)
	(segment
		(start 103.420926 -272.961354)
		(end 103.422704 -272.960338)
		(width 0.1143)
		(layer "In13.Cu")
		(net "P5E_CPU1_P0_RX_DP<6>")
	)
	(segment
		(start 74.175112 -367.053622)
		(end 74.317352 -366.911382)
		(width 0.14224)
		(layer "In13.Cu")
		(net "P5E_CPU1_P0_RX_DP<6>")
	)
	(segment
		(start 103.003096 -276.051772)
		(end 102.9335 -276.011132)
		(width 0.1143)
		(layer "In13.Cu")
		(net "P5E_CPU1_P0_RX_DP<6>")
	)
	(segment
		(start 102.9335 -280.261568)
		(end 103.003096 -280.220928)
		(width 0.1143)
		(layer "In13.Cu")
		(net "P5E_CPU1_P0_RX_DP<6>")
	)
	(segment
		(start 103.003096 -274.43176)
		(end 102.9335 -274.39112)
		(width 0.1143)
		(layer "In13.Cu")
		(net "P5E_CPU1_P0_RX_DP<6>")
	)
	(segment
		(start 128.641348 -331.082904)
		(end 128.116584 -329.01509)
		(width 0.14224)
		(layer "In13.Cu")
		(net "P5E_CPU1_P0_RX_DP<6>")
	)
	(segment
		(start 103.42626 -272.958306)
		(end 103.42753 -272.957544)
		(width 0.1143)
		(layer "In13.Cu")
		(net "P5E_CPU1_P0_RX_DP<6>")
	)
	(segment
		(start 110.419388 -367.801144)
		(end 132.003292 -367.801144)
		(width 0.14224)
		(layer "In13.Cu")
		(net "P5E_CPU1_P0_RX_DP<6>")
	)
	(arc
		(start 102.932484 -284.11043)
		(mid 102.776551 -283.806495)
		(end 102.93223 -283.502354)
		(width 0.1143)
		(layer "In13.Cu")
		(net "P5E_CPU1_P0_RX_DP<6>")
	)
	(arc
		(start 102.9335 -280.871168)
		(mid 102.776523 -280.566368)
		(end 102.9335 -280.261568)
		(width 0.1143)
		(layer "In13.Cu")
		(net "P5E_CPU1_P0_RX_DP<6>")
	)
	(arc
		(start 102.932484 -285.730442)
		(mid 102.776551 -285.426507)
		(end 102.93223 -285.122366)
		(width 0.1143)
		(layer "In13.Cu")
		(net "P5E_CPU1_P0_RX_DP<6>")
	)
	(arc
		(start 103.003096 -273.74088)
		(mid 103.181909 -273.53853)
		(end 103.246428 -273.276314)
		(width 0.1143)
		(layer "In13.Cu")
		(net "P5E_CPU1_P0_RX_DP<6>")
	)
	(arc
		(start 136.647936 -367.449862)
		(mid 136.907866 -367.061127)
		(end 136.999218 -366.602518)
		(width 0.14224)
		(layer "In13.Cu")
		(net "P5E_CPU1_P0_RX_DP<6>")
	)
	(arc
		(start 104.176576 -271.761966)
		(mid 104.178599 -271.750556)
		(end 104.180386 -271.739106)
		(width 0.1143)
		(layer "In13.Cu")
		(net "P5E_CPU1_P0_RX_DP<6>")
	)
	(arc
		(start 56.147462 -380.961138)
		(mid 56.162918 -380.910052)
		(end 56.186832 -380.862332)
		(width 0.14224)
		(layer "In13.Cu")
		(net "P5E_CPU1_P0_RX_DP<6>")
	)
	(arc
		(start 102.9335 -276.011132)
		(mid 102.776523 -275.706332)
		(end 102.9335 -275.401532)
		(width 0.1143)
		(layer "In13.Cu")
		(net "P5E_CPU1_P0_RX_DP<6>")
	)
	(arc
		(start 113.74501 -304.98796)
		(mid 113.712747 -304.937066)
		(end 113.673382 -304.89144)
		(width 0.14224)
		(layer "In13.Cu")
		(net "P5E_CPU1_P0_RX_DP<6>")
	)
	(arc
		(start 102.922832 -295.72331)
		(mid 102.829252 -295.593805)
		(end 102.781354 -295.44137)
		(width 0.1143)
		(layer "In13.Cu")
		(net "P5E_CPU1_P0_RX_DP<6>")
	)
	(arc
		(start 63.582296 -368.781584)
		(mid 63.70447 -368.616274)
		(end 63.853314 -368.474498)
		(width 0.14224)
		(layer "In13.Cu")
		(net "P5E_CPU1_P0_RX_DP<6>")
	)
	(arc
		(start 103.003096 -291.560758)
		(mid 103.246423 -291.096192)
		(end 103.003096 -290.631626)
		(width 0.1143)
		(layer "In13.Cu")
		(net "P5E_CPU1_P0_RX_DP<6>")
	)
	(arc
		(start 103.688642 -272.607024)
		(mid 103.707727 -272.528406)
		(end 103.716836 -272.44802)
		(width 0.1143)
		(layer "In13.Cu")
		(net "P5E_CPU1_P0_RX_DP<6>")
	)
	(arc
		(start 102.9335 -288.970974)
		(mid 102.81824 -288.837555)
		(end 102.776782 -288.666174)
		(width 0.1143)
		(layer "In13.Cu")
		(net "P5E_CPU1_P0_RX_DP<6>")
	)
	(arc
		(start 103.003096 -278.600916)
		(mid 103.246423 -278.13635)
		(end 103.003096 -277.671784)
		(width 0.1143)
		(layer "In13.Cu")
		(net "P5E_CPU1_P0_RX_DP<6>")
	)
	(arc
		(start 103.002842 -293.181024)
		(mid 103.246487 -292.716381)
		(end 103.003096 -292.251638)
		(width 0.1143)
		(layer "In13.Cu")
		(net "P5E_CPU1_P0_RX_DP<6>")
	)
	(arc
		(start 65.555368 -367.112804)
		(mid 65.825368 -366.963207)
		(end 66.129662 -366.911382)
		(width 0.14224)
		(layer "In13.Cu")
		(net "P5E_CPU1_P0_RX_DP<6>")
	)
	(arc
		(start 103.003096 -280.220928)
		(mid 103.246423 -279.756362)
		(end 103.003096 -279.291796)
		(width 0.1143)
		(layer "In13.Cu")
		(net "P5E_CPU1_P0_RX_DP<6>")
	)
	(arc
		(start 102.776528 -295.133014)
		(mid 102.798406 -295.011846)
		(end 102.861618 -294.906192)
		(width 0.1143)
		(layer "In13.Cu")
		(net "P5E_CPU1_P0_RX_DP<6>")
	)
	(arc
		(start 55.740554 -382.922272)
		(mid 55.741284 -382.90912)
		(end 55.743348 -382.89611)
		(width 0.14224)
		(layer "In13.Cu")
		(net "P5E_CPU1_P0_RX_DP<6>")
	)
	(arc
		(start 103.20274 -294.090344)
		(mid 103.098066 -293.936353)
		(end 102.945946 -293.828978)
		(width 0.1143)
		(layer "In13.Cu")
		(net "P5E_CPU1_P0_RX_DP<6>")
	)
	(arc
		(start 102.861618 -294.906192)
		(mid 102.907978 -294.862817)
		(end 102.961694 -294.828976)
		(width 0.1143)
		(layer "In13.Cu")
		(net "P5E_CPU1_P0_RX_DP<6>")
	)
	(arc
		(start 103.396542 -297.488356)
		(mid 103.368899 -297.446986)
		(end 103.359204 -297.398186)
		(width 0.14224)
		(layer "In13.Cu")
		(net "P5E_CPU1_P0_RX_DP<6>")
	)
	(arc
		(start 103.313484 -296.307764)
		(mid 103.278011 -296.128957)
		(end 103.176832 -295.97731)
		(width 0.1143)
		(layer "In13.Cu")
		(net "P5E_CPU1_P0_RX_DP<6>")
	)
	(arc
		(start 103.246428 -273.276314)
		(mid 103.287683 -273.105343)
		(end 103.402384 -272.972022)
		(width 0.1143)
		(layer "In13.Cu")
		(net "P5E_CPU1_P0_RX_DP<6>")
	)
	(arc
		(start 103.002842 -286.70123)
		(mid 103.246487 -286.236691)
		(end 103.00335 -285.771844)
		(width 0.1143)
		(layer "In13.Cu")
		(net "P5E_CPU1_P0_RX_DP<6>")
	)
	(arc
		(start 103.001572 -285.08198)
		(mid 103.246393 -284.616398)
		(end 103.001572 -284.150816)
		(width 0.1143)
		(layer "In13.Cu")
		(net "P5E_CPU1_P0_RX_DP<6>")
	)
	(arc
		(start 103.003096 -275.360892)
		(mid 103.246423 -274.896326)
		(end 103.003096 -274.43176)
		(width 0.1143)
		(layer "In13.Cu")
		(net "P5E_CPU1_P0_RX_DP<6>")
	)
	(arc
		(start 102.776782 -288.666174)
		(mid 102.817551 -288.495644)
		(end 102.931468 -288.36239)
		(width 0.1143)
		(layer "In13.Cu")
		(net "P5E_CPU1_P0_RX_DP<6>")
	)
	(arc
		(start 102.9335 -277.631144)
		(mid 102.776523 -277.326344)
		(end 102.9335 -277.021544)
		(width 0.1143)
		(layer "In13.Cu")
		(net "P5E_CPU1_P0_RX_DP<6>")
	)
	(arc
		(start 103.002842 -288.321242)
		(mid 103.246485 -287.854977)
		(end 103.000556 -287.389824)
		(width 0.1143)
		(layer "In13.Cu")
		(net "P5E_CPU1_P0_RX_DP<6>")
	)
	(arc
		(start 103.716836 -272.44802)
		(mid 103.762332 -272.28679)
		(end 103.873554 -272.161508)
		(width 0.1143)
		(layer "In13.Cu")
		(net "P5E_CPU1_P0_RX_DP<6>")
	)
	(arc
		(start 102.776782 -287.046162)
		(mid 102.817551 -286.875632)
		(end 102.931468 -286.742378)
		(width 0.1143)
		(layer "In13.Cu")
		(net "P5E_CPU1_P0_RX_DP<6>")
	)
	(arc
		(start 103.001572 -283.461968)
		(mid 103.246393 -282.996386)
		(end 103.001572 -282.530804)
		(width 0.1143)
		(layer "In13.Cu")
		(net "P5E_CPU1_P0_RX_DP<6>")
	)
	(arc
		(start 102.9335 -292.210998)
		(mid 102.776523 -291.906124)
		(end 102.9335 -291.601144)
		(width 0.1143)
		(layer "In13.Cu")
		(net "P5E_CPU1_P0_RX_DP<6>")
	)
	(arc
		(start 103.003096 -276.980904)
		(mid 103.246423 -276.516338)
		(end 103.003096 -276.051772)
		(width 0.1143)
		(layer "In13.Cu")
		(net "P5E_CPU1_P0_RX_DP<6>")
	)
	(arc
		(start 103.168196 -294.653716)
		(mid 103.225364 -294.542779)
		(end 103.244904 -294.419528)
		(width 0.1143)
		(layer "In13.Cu")
		(net "P5E_CPU1_P0_RX_DP<6>")
	)
	(arc
		(start 103.001572 -281.841956)
		(mid 103.246393 -281.376374)
		(end 103.001572 -280.910792)
		(width 0.1143)
		(layer "In13.Cu")
		(net "P5E_CPU1_P0_RX_DP<6>")
	)
	(arc
		(start 103.244904 -294.291766)
		(mid 103.234354 -294.18885)
		(end 103.20274 -294.090344)
		(width 0.1143)
		(layer "In13.Cu")
		(net "P5E_CPU1_P0_RX_DP<6>")
	)
	(arc
		(start 102.933246 -287.350962)
		(mid 102.818061 -287.217518)
		(end 102.776782 -287.046162)
		(width 0.1143)
		(layer "In13.Cu")
		(net "P5E_CPU1_P0_RX_DP<6>")
	)
	(arc
		(start 102.961694 -294.828976)
		(mid 103.075221 -294.753455)
		(end 103.168196 -294.653716)
		(width 0.1143)
		(layer "In13.Cu")
		(net "P5E_CPU1_P0_RX_DP<6>")
	)
	(arc
		(start 102.9335 -274.39112)
		(mid 102.776523 -274.08632)
		(end 102.9335 -273.78152)
		(width 0.1143)
		(layer "In13.Cu")
		(net "P5E_CPU1_P0_RX_DP<6>")
	)
	(arc
		(start 135.800592 -367.801144)
		(mid 136.259179 -367.709738)
		(end 136.647936 -367.449862)
		(width 0.14224)
		(layer "In13.Cu")
		(net "P5E_CPU1_P0_RX_DP<6>")
	)
	(arc
		(start 103.003096 -289.940746)
		(mid 103.246423 -289.47618)
		(end 103.003096 -289.011614)
		(width 0.1143)
		(layer "In13.Cu")
		(net "P5E_CPU1_P0_RX_DP<6>")
	)
	(arc
		(start 102.781354 -295.44137)
		(mid 102.777547 -295.406028)
		(end 102.776274 -295.370504)
		(width 0.1143)
		(layer "In13.Cu")
		(net "P5E_CPU1_P0_RX_DP<6>")
	)
	(arc
		(start 103.94315 -272.120868)
		(mid 104.095137 -271.96436)
		(end 104.176576 -271.761966)
		(width 0.1143)
		(layer "In13.Cu")
		(net "P5E_CPU1_P0_RX_DP<6>")
	)
	(arc
		(start 102.945946 -293.828978)
		(mid 102.891952 -293.795054)
		(end 102.848156 -293.748714)
		(width 0.1143)
		(layer "In13.Cu")
		(net "P5E_CPU1_P0_RX_DP<6>")
	)
	(arc
		(start 102.848156 -293.748714)
		(mid 102.780758 -293.467231)
		(end 102.9335 -293.22141)
		(width 0.1143)
		(layer "In13.Cu")
		(net "P5E_CPU1_P0_RX_DP<6>")
	)
	(arc
		(start 103.47325 -272.930874)
		(mid 103.604275 -272.784466)
		(end 103.688642 -272.607024)
		(width 0.1143)
		(layer "In13.Cu")
		(net "P5E_CPU1_P0_RX_DP<6>")
	)
	(arc
		(start 102.932484 -282.490418)
		(mid 102.776551 -282.186483)
		(end 102.93223 -281.882342)
		(width 0.1143)
		(layer "In13.Cu")
		(net "P5E_CPU1_P0_RX_DP<6>")
	)
	(arc
		(start 106.841544 -300.813978)
		(mid 106.598038 -300.659942)
		(end 106.379772 -300.47184)
		(width 0.14224)
		(layer "In13.Cu")
		(net "P5E_CPU1_P0_RX_DP<6>")
	)
	(arc
		(start 102.9335 -290.590986)
		(mid 102.776523 -290.286112)
		(end 102.9335 -289.981132)
		(width 0.1143)
		(layer "In13.Cu")
		(net "P5E_CPU1_P0_RX_DP<6>")
	)
	(arc
		(start 102.9335 -279.251156)
		(mid 102.776523 -278.946356)
		(end 102.9335 -278.641556)
		(width 0.1143)
		(layer "In13.Cu")
		(net "P5E_CPU1_P0_RX_DP<6>")
	)
	(segment
		(start 102.207822 -269.770352)
		(end 101.74097 -270.03629)
		(width 0.12954)
		(layer "F.Cu")
		(net "P5E_CPU1_P0_RX_DP<5>")
	)
	(segment
		(start 53.670708 -386.003292)
		(end 54.191408 -386.003292)
		(width 0.127)
		(layer "F.Cu")
		(net "P5E_CPU1_P0_RX_DP<5>")
	)
	(segment
		(start 101.993446 -281.88158)
		(end 102.023926 -281.8638)
		(width 0.1143)
		(layer "In13.Cu")
		(net "P5E_CPU1_P0_RX_DP<5>")
	)
	(segment
		(start 134.545832 -360.520488)
		(end 133.97611 -359.950766)
		(width 0.14224)
		(layer "In13.Cu")
		(net "P5E_CPU1_P0_RX_DP<5>")
	)
	(segment
		(start 102.023926 -277.003764)
		(end 102.063042 -276.980904)
		(width 0.1143)
		(layer "In13.Cu")
		(net "P5E_CPU1_P0_RX_DP<5>")
	)
	(segment
		(start 102.063042 -289.011614)
		(end 102.023926 -288.988754)
		(width 0.1143)
		(layer "In13.Cu")
		(net "P5E_CPU1_P0_RX_DP<5>")
	)
	(segment
		(start 128.787398 -366.71377)
		(end 134.545832 -360.955336)
		(width 0.14224)
		(layer "In13.Cu")
		(net "P5E_CPU1_P0_RX_DP<5>")
	)
	(segment
		(start 102.023926 -277.648924)
		(end 101.993446 -277.631144)
		(width 0.1143)
		(layer "In13.Cu")
		(net "P5E_CPU1_P0_RX_DP<5>")
	)
	(segment
		(start 102.023926 -288.343848)
		(end 102.063042 -288.320988)
		(width 0.1143)
		(layer "In13.Cu")
		(net "P5E_CPU1_P0_RX_DP<5>")
	)
	(segment
		(start 119.464836 -366.833658)
		(end 119.772176 -366.526318)
		(width 0.14224)
		(layer "In13.Cu")
		(net "P5E_CPU1_P0_RX_DP<5>")
	)
	(segment
		(start 102.023926 -291.583618)
		(end 102.063042 -291.560758)
		(width 0.1143)
		(layer "In13.Cu")
		(net "P5E_CPU1_P0_RX_DP<5>")
	)
	(segment
		(start 102.023926 -282.50896)
		(end 101.993446 -282.49118)
		(width 0.1143)
		(layer "In13.Cu")
		(net "P5E_CPU1_P0_RX_DP<5>")
	)
	(segment
		(start 127.512572 -364.768892)
		(end 133.529578 -358.751886)
		(width 0.14224)
		(layer "In13.Cu")
		(net "P5E_CPU1_P0_RX_DP<5>")
	)
	(segment
		(start 128.117854 -365.374174)
		(end 127.916686 -365.374174)
		(width 0.14224)
		(layer "In13.Cu")
		(net "P5E_CPU1_P0_RX_DP<5>")
	)
	(segment
		(start 102.023926 -290.608766)
		(end 101.993446 -290.590986)
		(width 0.1143)
		(layer "In13.Cu")
		(net "P5E_CPU1_P0_RX_DP<5>")
	)
	(segment
		(start 102.063042 -272.811748)
		(end 102.023926 -272.788888)
		(width 0.1143)
		(layer "In13.Cu")
		(net "P5E_CPU1_P0_RX_DP<5>")
	)
	(segment
		(start 101.991414 -288.362644)
		(end 102.023926 -288.343848)
		(width 0.1143)
		(layer "In13.Cu")
		(net "P5E_CPU1_P0_RX_DP<5>")
	)
	(segment
		(start 102.030276 -294.819832)
		(end 102.051866 -294.807386)
		(width 0.1143)
		(layer "In13.Cu")
		(net "P5E_CPU1_P0_RX_DP<5>")
	)
	(segment
		(start 101.993446 -289.981386)
		(end 102.023926 -289.963606)
		(width 0.1143)
		(layer "In13.Cu")
		(net "P5E_CPU1_P0_RX_DP<5>")
	)
	(segment
		(start 102.063042 -285.771844)
		(end 101.993446 -285.731204)
		(width 0.1143)
		(layer "In13.Cu")
		(net "P5E_CPU1_P0_RX_DP<5>")
	)
	(segment
		(start 102.352094 -296.436288)
		(end 102.352094 -296.40784)
		(width 0.1143)
		(layer "In13.Cu")
		(net "P5E_CPU1_P0_RX_DP<5>")
	)
	(segment
		(start 62.996572 -367.962688)
		(end 65.174368 -366.22101)
		(width 0.14224)
		(layer "In13.Cu")
		(net "P5E_CPU1_P0_RX_DP<5>")
	)
	(segment
		(start 102.023926 -273.76374)
		(end 102.063042 -273.74088)
		(width 0.1143)
		(layer "In13.Cu")
		(net "P5E_CPU1_P0_RX_DP<5>")
	)
	(segment
		(start 101.993446 -272.161508)
		(end 102.023926 -272.143728)
		(width 0.1143)
		(layer "In13.Cu")
		(net "P5E_CPU1_P0_RX_DP<5>")
	)
	(segment
		(start 54.540658 -384.048)
		(end 54.540658 -382.620266)
		(width 0.14224)
		(layer "In13.Cu")
		(net "P5E_CPU1_P0_RX_DP<5>")
	)
	(segment
		(start 101.991414 -286.742632)
		(end 102.023926 -286.723836)
		(width 0.1143)
		(layer "In13.Cu")
		(net "P5E_CPU1_P0_RX_DP<5>")
	)
	(segment
		(start 101.993446 -275.401532)
		(end 102.023926 -275.383752)
		(width 0.1143)
		(layer "In13.Cu")
		(net "P5E_CPU1_P0_RX_DP<5>")
	)
	(segment
		(start 101.8286 -295.22801)
		(end 101.8286 -295.122092)
		(width 0.1143)
		(layer "In13.Cu")
		(net "P5E_CPU1_P0_RX_DP<5>")
	)
	(segment
		(start 55.348124 -380.44247)
		(end 62.967616 -367.995708)
		(width 0.14224)
		(layer "In13.Cu")
		(net "P5E_CPU1_P0_RX_DP<5>")
	)
	(segment
		(start 124.426726 -364.557818)
		(end 124.568966 -364.700058)
		(width 0.14224)
		(layer "In13.Cu")
		(net "P5E_CPU1_P0_RX_DP<5>")
	)
	(segment
		(start 120.935496 -365.413798)
		(end 120.628156 -365.721138)
		(width 0.14224)
		(layer "In13.Cu")
		(net "P5E_CPU1_P0_RX_DP<5>")
	)
	(segment
		(start 102.063042 -277.671784)
		(end 102.023926 -277.648924)
		(width 0.1143)
		(layer "In13.Cu")
		(net "P5E_CPU1_P0_RX_DP<5>")
	)
	(segment
		(start 102.023926 -280.888948)
		(end 101.993446 -280.871168)
		(width 0.1143)
		(layer "In13.Cu")
		(net "P5E_CPU1_P0_RX_DP<5>")
	)
	(segment
		(start 102.352094 -296.40784)
		(end 102.306374 -296.36212)
		(width 0.1143)
		(layer "In13.Cu")
		(net "P5E_CPU1_P0_RX_DP<5>")
	)
	(segment
		(start 108.908342 -366.014508)
		(end 109.60735 -366.71377)
		(width 0.14224)
		(layer "In13.Cu")
		(net "P5E_CPU1_P0_RX_DP<5>")
	)
	(segment
		(start 101.993446 -273.78152)
		(end 102.023926 -273.76374)
		(width 0.1143)
		(layer "In13.Cu")
		(net "P5E_CPU1_P0_RX_DP<5>")
	)
	(segment
		(start 102.063042 -292.251638)
		(end 102.023926 -292.228778)
		(width 0.1143)
		(layer "In13.Cu")
		(net "P5E_CPU1_P0_RX_DP<5>")
	)
	(segment
		(start 102.063042 -284.151832)
		(end 102.023926 -284.128972)
		(width 0.1143)
		(layer "In13.Cu")
		(net "P5E_CPU1_P0_RX_DP<5>")
	)
	(segment
		(start 124.568966 -364.700058)
		(end 124.568966 -365.271558)
		(width 0.14224)
		(layer "In13.Cu")
		(net "P5E_CPU1_P0_RX_DP<5>")
	)
	(segment
		(start 134.545832 -360.955336)
		(end 134.545832 -360.520488)
		(width 0.14224)
		(layer "In13.Cu")
		(net "P5E_CPU1_P0_RX_DP<5>")
	)
	(segment
		(start 125.401832 -324.236334)
		(end 122.554746 -319.210436)
		(width 0.14224)
		(layer "In13.Cu")
		(net "P5E_CPU1_P0_RX_DP<5>")
	)
	(segment
		(start 54.286404 -385.649216)
		(end 54.460648 -385.548632)
		(width 0.14224)
		(layer "In13.Cu")
		(net "P5E_CPU1_P0_RX_DP<5>")
	)
	(segment
		(start 133.97611 -359.950766)
		(end 133.541262 -359.950766)
		(width 0.14224)
		(layer "In13.Cu")
		(net "P5E_CPU1_P0_RX_DP<5>")
	)
	(segment
		(start 54.191408 -386.003292)
		(end 54.286404 -385.649216)
		(width 0.14224)
		(layer "In13.Cu")
		(net "P5E_CPU1_P0_RX_DP<5>")
	)
	(segment
		(start 105.99547 -301.47895)
		(end 102.475792 -297.959272)
		(width 0.14224)
		(layer "In13.Cu")
		(net "P5E_CPU1_P0_RX_DP<5>")
	)
	(segment
		(start 111.055404 -304.284888)
		(end 106.621326 -301.940722)
		(width 0.14224)
		(layer "In13.Cu")
		(net "P5E_CPU1_P0_RX_DP<5>")
	)
	(segment
		(start 102.063042 -276.051772)
		(end 102.023926 -276.028912)
		(width 0.1143)
		(layer "In13.Cu")
		(net "P5E_CPU1_P0_RX_DP<5>")
	)
	(segment
		(start 102.023926 -272.788888)
		(end 101.993446 -272.771108)
		(width 0.1143)
		(layer "In13.Cu")
		(net "P5E_CPU1_P0_RX_DP<5>")
	)
	(segment
		(start 124.426726 -365.413798)
		(end 120.935496 -365.413798)
		(width 0.14224)
		(layer "In13.Cu")
		(net "P5E_CPU1_P0_RX_DP<5>")
	)
	(segment
		(start 128.420622 -335.644998)
		(end 127.676148 -331.354176)
		(width 0.14224)
		(layer "In13.Cu")
		(net "P5E_CPU1_P0_RX_DP<5>")
	)
	(segment
		(start 102.023926 -272.143728)
		(end 102.063042 -272.120868)
		(width 0.1143)
		(layer "In13.Cu")
		(net "P5E_CPU1_P0_RX_DP<5>")
	)
	(segment
		(start 65.86982 -365.97717)
		(end 108.818426 -365.97717)
		(width 0.14224)
		(layer "In13.Cu")
		(net "P5E_CPU1_P0_RX_DP<5>")
	)
	(segment
		(start 127.512572 -364.97006)
		(end 127.512572 -364.768892)
		(width 0.14224)
		(layer "In13.Cu")
		(net "P5E_CPU1_P0_RX_DP<5>")
	)
	(segment
		(start 112.496854 -305.228752)
		(end 111.055404 -304.284888)
		(width 0.14224)
		(layer "In13.Cu")
		(net "P5E_CPU1_P0_RX_DP<5>")
	)
	(segment
		(start 102.023926 -283.483812)
		(end 102.063042 -283.460952)
		(width 0.1143)
		(layer "In13.Cu")
		(net "P5E_CPU1_P0_RX_DP<5>")
	)
	(segment
		(start 102.023926 -276.028912)
		(end 101.993446 -276.011132)
		(width 0.1143)
		(layer "In13.Cu")
		(net "P5E_CPU1_P0_RX_DP<5>")
	)
	(segment
		(start 54.548024 -382.577086)
		(end 55.218584 -380.712726)
		(width 0.14224)
		(layer "In13.Cu")
		(net "P5E_CPU1_P0_RX_DP<5>")
	)
	(segment
		(start 102.056692 -294.804592)
		(end 102.063042 -294.800782)
		(width 0.1143)
		(layer "In13.Cu")
		(net "P5E_CPU1_P0_RX_DP<5>")
	)
	(segment
		(start 102.051866 -294.807386)
		(end 102.052882 -294.806878)
		(width 0.1143)
		(layer "In13.Cu")
		(net "P5E_CPU1_P0_RX_DP<5>")
	)
	(segment
		(start 115.301522 -309.429912)
		(end 113.04778 -306.056538)
		(width 0.14224)
		(layer "In13.Cu")
		(net "P5E_CPU1_P0_RX_DP<5>")
	)
	(segment
		(start 101.553518 -270.359886)
		(end 101.553264 -270.359632)
		(width 0.1143)
		(layer "In13.Cu")
		(net "P5E_CPU1_P0_RX_DP<5>")
	)
	(segment
		(start 101.993446 -285.121604)
		(end 102.023926 -285.103824)
		(width 0.1143)
		(layer "In13.Cu")
		(net "P5E_CPU1_P0_RX_DP<5>")
	)
	(segment
		(start 102.023926 -285.103824)
		(end 102.063042 -285.080964)
		(width 0.1143)
		(layer "In13.Cu")
		(net "P5E_CPU1_P0_RX_DP<5>")
	)
	(segment
		(start 119.772176 -366.526318)
		(end 119.772176 -364.700058)
		(width 0.14224)
		(layer "In13.Cu")
		(net "P5E_CPU1_P0_RX_DP<5>")
	)
	(segment
		(start 102.023926 -288.988754)
		(end 101.993446 -288.970974)
		(width 0.1143)
		(layer "In13.Cu")
		(net "P5E_CPU1_P0_RX_DP<5>")
	)
	(segment
		(start 101.443028 -270.03629)
		(end 101.74097 -270.03629)
		(width 0.1143)
		(layer "In13.Cu")
		(net "P5E_CPU1_P0_RX_DP<5>")
	)
	(segment
		(start 54.23281 -384.731006)
		(end 54.235858 -384.3528)
		(width 0.14224)
		(layer "In13.Cu")
		(net "P5E_CPU1_P0_RX_DP<5>")
	)
	(segment
		(start 133.637274 -358.363012)
		(end 130.24612 -344.829384)
		(width 0.14224)
		(layer "In13.Cu")
		(net "P5E_CPU1_P0_RX_DP<5>")
	)
	(segment
		(start 119.772176 -364.700058)
		(end 119.914416 -364.557818)
		(width 0.14224)
		(layer "In13.Cu")
		(net "P5E_CPU1_P0_RX_DP<5>")
	)
	(segment
		(start 102.306374 -296.36212)
		(end 102.306374 -295.956228)
		(width 0.1143)
		(layer "In13.Cu")
		(net "P5E_CPU1_P0_RX_DP<5>")
	)
	(segment
		(start 102.053644 -294.80637)
		(end 102.05593 -294.8051)
		(width 0.1143)
		(layer "In13.Cu")
		(net "P5E_CPU1_P0_RX_DP<5>")
	)
	(segment
		(start 54.548786 -385.460494)
		(end 54.548786 -385.046982)
		(width 0.14224)
		(layer "In13.Cu")
		(net "P5E_CPU1_P0_RX_DP<5>")
	)
	(segment
		(start 102.008432 -294.832532)
		(end 102.030276 -294.819832)
		(width 0.1143)
		(layer "In13.Cu")
		(net "P5E_CPU1_P0_RX_DP<5>")
	)
	(segment
		(start 102.063042 -293.87165)
		(end 102.023926 -293.84879)
		(width 0.1143)
		(layer "In13.Cu")
		(net "P5E_CPU1_P0_RX_DP<5>")
	)
	(segment
		(start 102.023926 -275.383752)
		(end 102.063042 -275.360892)
		(width 0.1143)
		(layer "In13.Cu")
		(net "P5E_CPU1_P0_RX_DP<5>")
	)
	(segment
		(start 102.023926 -274.4089)
		(end 101.993446 -274.39112)
		(width 0.1143)
		(layer "In13.Cu")
		(net "P5E_CPU1_P0_RX_DP<5>")
	)
	(segment
		(start 54.548786 -385.046982)
		(end 54.23281 -384.731006)
		(width 0.14224)
		(layer "In13.Cu")
		(net "P5E_CPU1_P0_RX_DP<5>")
	)
	(segment
		(start 102.063042 -271.191736)
		(end 101.993446 -271.151096)
		(width 0.1143)
		(layer "In13.Cu")
		(net "P5E_CPU1_P0_RX_DP<5>")
	)
	(segment
		(start 102.05593 -294.8051)
		(end 102.056692 -294.804592)
		(width 0.1143)
		(layer "In13.Cu")
		(net "P5E_CPU1_P0_RX_DP<5>")
	)
	(segment
		(start 101.906324 -294.934894)
		(end 102.008432 -294.832532)
		(width 0.1143)
		(layer "In13.Cu")
		(net "P5E_CPU1_P0_RX_DP<5>")
	)
	(segment
		(start 101.993446 -278.641556)
		(end 102.023926 -278.623776)
		(width 0.1143)
		(layer "In13.Cu")
		(net "P5E_CPU1_P0_RX_DP<5>")
	)
	(segment
		(start 120.628156 -365.721138)
		(end 120.628156 -366.526318)
		(width 0.14224)
		(layer "In13.Cu")
		(net "P5E_CPU1_P0_RX_DP<5>")
	)
	(segment
		(start 119.914416 -364.557818)
		(end 124.426726 -364.557818)
		(width 0.14224)
		(layer "In13.Cu")
		(net "P5E_CPU1_P0_RX_DP<5>")
	)
	(segment
		(start 102.023926 -278.623776)
		(end 102.063042 -278.600916)
		(width 0.1143)
		(layer "In13.Cu")
		(net "P5E_CPU1_P0_RX_DP<5>")
	)
	(segment
		(start 101.55936 -270.363188)
		(end 101.553518 -270.359886)
		(width 0.1143)
		(layer "In13.Cu")
		(net "P5E_CPU1_P0_RX_DP<5>")
	)
	(segment
		(start 120.628156 -366.526318)
		(end 120.935496 -366.833658)
		(width 0.14224)
		(layer "In13.Cu")
		(net "P5E_CPU1_P0_RX_DP<5>")
	)
	(segment
		(start 101.93655 -295.412922)
		(end 101.88321 -295.359582)
		(width 0.1143)
		(layer "In13.Cu")
		(net "P5E_CPU1_P0_RX_DP<5>")
	)
	(segment
		(start 102.063042 -279.291796)
		(end 102.023926 -279.268936)
		(width 0.1143)
		(layer "In13.Cu")
		(net "P5E_CPU1_P0_RX_DP<5>")
	)
	(segment
		(start 120.935496 -366.833658)
		(end 128.498092 -366.833658)
		(width 0.14224)
		(layer "In13.Cu")
		(net "P5E_CPU1_P0_RX_DP<5>")
	)
	(segment
		(start 101.993446 -280.261568)
		(end 102.023926 -280.243788)
		(width 0.1143)
		(layer "In13.Cu")
		(net "P5E_CPU1_P0_RX_DP<5>")
	)
	(segment
		(start 102.060502 -287.390078)
		(end 101.993446 -287.350962)
		(width 0.1143)
		(layer "In13.Cu")
		(net "P5E_CPU1_P0_RX_DP<5>")
	)
	(segment
		(start 122.554746 -319.210436)
		(end 115.301522 -309.429912)
		(width 0.14224)
		(layer "In13.Cu")
		(net "P5E_CPU1_P0_RX_DP<5>")
	)
	(segment
		(start 102.063042 -290.631626)
		(end 102.023926 -290.608766)
		(width 0.1143)
		(layer "In13.Cu")
		(net "P5E_CPU1_P0_RX_DP<5>")
	)
	(segment
		(start 101.993446 -283.501592)
		(end 102.023926 -283.483812)
		(width 0.1143)
		(layer "In13.Cu")
		(net "P5E_CPU1_P0_RX_DP<5>")
	)
	(segment
		(start 130.24612 -344.829384)
		(end 128.420622 -335.644998)
		(width 0.14224)
		(layer "In13.Cu")
		(net "P5E_CPU1_P0_RX_DP<5>")
	)
	(segment
		(start 127.676148 -331.354176)
		(end 126.102872 -325.927974)
		(width 0.14224)
		(layer "In13.Cu")
		(net "P5E_CPU1_P0_RX_DP<5>")
	)
	(segment
		(start 126.102872 -325.927974)
		(end 125.401832 -324.236334)
		(width 0.14224)
		(layer "In13.Cu")
		(net "P5E_CPU1_P0_RX_DP<5>")
	)
	(segment
		(start 54.235858 -384.3528)
		(end 54.540658 -384.048)
		(width 0.14224)
		(layer "In13.Cu")
		(net "P5E_CPU1_P0_RX_DP<5>")
	)
	(segment
		(start 102.023926 -286.723836)
		(end 102.063042 -286.700976)
		(width 0.1143)
		(layer "In13.Cu")
		(net "P5E_CPU1_P0_RX_DP<5>")
	)
	(segment
		(start 102.352094 -297.660822)
		(end 102.352094 -296.436288)
		(width 0.14224)
		(layer "In13.Cu")
		(net "P5E_CPU1_P0_RX_DP<5>")
	)
	(segment
		(start 102.023926 -293.84879)
		(end 101.993446 -293.83101)
		(width 0.1143)
		(layer "In13.Cu")
		(net "P5E_CPU1_P0_RX_DP<5>")
	)
	(segment
		(start 102.023926 -289.963606)
		(end 102.063042 -289.940746)
		(width 0.1143)
		(layer "In13.Cu")
		(net "P5E_CPU1_P0_RX_DP<5>")
	)
	(segment
		(start 102.023926 -279.268936)
		(end 101.993446 -279.251156)
		(width 0.1143)
		(layer "In13.Cu")
		(net "P5E_CPU1_P0_RX_DP<5>")
	)
	(segment
		(start 102.063042 -282.53182)
		(end 102.023926 -282.50896)
		(width 0.1143)
		(layer "In13.Cu")
		(net "P5E_CPU1_P0_RX_DP<5>")
	)
	(segment
		(start 109.89691 -366.833658)
		(end 119.464836 -366.833658)
		(width 0.14224)
		(layer "In13.Cu")
		(net "P5E_CPU1_P0_RX_DP<5>")
	)
	(segment
		(start 102.052882 -294.806878)
		(end 102.053644 -294.80637)
		(width 0.1143)
		(layer "In13.Cu")
		(net "P5E_CPU1_P0_RX_DP<5>")
	)
	(segment
		(start 133.541262 -359.950766)
		(end 128.117854 -365.374174)
		(width 0.14224)
		(layer "In13.Cu")
		(net "P5E_CPU1_P0_RX_DP<5>")
	)
	(segment
		(start 124.568966 -365.271558)
		(end 124.426726 -365.413798)
		(width 0.14224)
		(layer "In13.Cu")
		(net "P5E_CPU1_P0_RX_DP<5>")
	)
	(segment
		(start 102.023926 -293.20363)
		(end 102.063042 -293.18077)
		(width 0.1143)
		(layer "In13.Cu")
		(net "P5E_CPU1_P0_RX_DP<5>")
	)
	(segment
		(start 102.023926 -284.128972)
		(end 101.993446 -284.111192)
		(width 0.1143)
		(layer "In13.Cu")
		(net "P5E_CPU1_P0_RX_DP<5>")
	)
	(segment
		(start 102.063042 -274.43176)
		(end 102.023926 -274.4089)
		(width 0.1143)
		(layer "In13.Cu")
		(net "P5E_CPU1_P0_RX_DP<5>")
	)
	(segment
		(start 101.993446 -291.601398)
		(end 102.023926 -291.583618)
		(width 0.1143)
		(layer "In13.Cu")
		(net "P5E_CPU1_P0_RX_DP<5>")
	)
	(segment
		(start 54.460648 -385.548632)
		(end 54.548786 -385.460494)
		(width 0.14224)
		(layer "In13.Cu")
		(net "P5E_CPU1_P0_RX_DP<5>")
	)
	(segment
		(start 102.023926 -281.8638)
		(end 102.063042 -281.84094)
		(width 0.1143)
		(layer "In13.Cu")
		(net "P5E_CPU1_P0_RX_DP<5>")
	)
	(segment
		(start 127.916686 -365.374174)
		(end 127.512572 -364.97006)
		(width 0.14224)
		(layer "In13.Cu")
		(net "P5E_CPU1_P0_RX_DP<5>")
	)
	(segment
		(start 102.023926 -292.228778)
		(end 101.993446 -292.210998)
		(width 0.1143)
		(layer "In13.Cu")
		(net "P5E_CPU1_P0_RX_DP<5>")
	)
	(segment
		(start 102.023926 -280.243788)
		(end 102.063042 -280.220928)
		(width 0.1143)
		(layer "In13.Cu")
		(net "P5E_CPU1_P0_RX_DP<5>")
	)
	(segment
		(start 113.04778 -306.056538)
		(end 112.717834 -305.465734)
		(width 0.14224)
		(layer "In13.Cu")
		(net "P5E_CPU1_P0_RX_DP<5>")
	)
	(segment
		(start 102.078028 -295.503854)
		(end 101.981762 -295.44772)
		(width 0.1143)
		(layer "In13.Cu")
		(net "P5E_CPU1_P0_RX_DP<5>")
	)
	(segment
		(start 101.373178 -270.10614)
		(end 101.443028 -270.03629)
		(width 0.1143)
		(layer "In13.Cu")
		(net "P5E_CPU1_P0_RX_DP<5>")
	)
	(segment
		(start 101.993446 -277.021544)
		(end 102.023926 -277.003764)
		(width 0.1143)
		(layer "In13.Cu")
		(net "P5E_CPU1_P0_RX_DP<5>")
	)
	(segment
		(start 101.993446 -293.22141)
		(end 102.023926 -293.20363)
		(width 0.1143)
		(layer "In13.Cu")
		(net "P5E_CPU1_P0_RX_DP<5>")
	)
	(segment
		(start 102.063042 -280.911808)
		(end 102.023926 -280.888948)
		(width 0.1143)
		(layer "In13.Cu")
		(net "P5E_CPU1_P0_RX_DP<5>")
	)
	(arc
		(start 101.993446 -279.251156)
		(mid 101.836469 -278.946356)
		(end 101.993446 -278.641556)
		(width 0.1143)
		(layer "In13.Cu")
		(net "P5E_CPU1_P0_RX_DP<5>")
	)
	(arc
		(start 101.993446 -292.210998)
		(mid 101.836469 -291.906198)
		(end 101.993446 -291.601398)
		(width 0.1143)
		(layer "In13.Cu")
		(net "P5E_CPU1_P0_RX_DP<5>")
	)
	(arc
		(start 108.818426 -365.97717)
		(mid 108.86711 -365.986872)
		(end 108.908342 -366.014508)
		(width 0.14224)
		(layer "In13.Cu")
		(net "P5E_CPU1_P0_RX_DP<5>")
	)
	(arc
		(start 65.174368 -366.22101)
		(mid 65.501344 -366.039917)
		(end 65.86982 -365.97717)
		(width 0.14224)
		(layer "In13.Cu")
		(net "P5E_CPU1_P0_RX_DP<5>")
	)
	(arc
		(start 102.306374 -287.856422)
		(mid 102.241138 -287.592831)
		(end 102.060502 -287.390078)
		(width 0.1143)
		(layer "In13.Cu")
		(net "P5E_CPU1_P0_RX_DP<5>")
	)
	(arc
		(start 54.540658 -382.620266)
		(mid 54.542466 -382.598356)
		(end 54.548024 -382.577086)
		(width 0.14224)
		(layer "In13.Cu")
		(net "P5E_CPU1_P0_RX_DP<5>")
	)
	(arc
		(start 109.60735 -366.71377)
		(mid 109.740188 -366.802563)
		(end 109.89691 -366.833658)
		(width 0.14224)
		(layer "In13.Cu")
		(net "P5E_CPU1_P0_RX_DP<5>")
	)
	(arc
		(start 101.836474 -288.666174)
		(mid 101.87744 -288.495768)
		(end 101.991414 -288.362644)
		(width 0.1143)
		(layer "In13.Cu")
		(net "P5E_CPU1_P0_RX_DP<5>")
	)
	(arc
		(start 101.993446 -284.111192)
		(mid 101.836469 -283.806392)
		(end 101.993446 -283.501592)
		(width 0.1143)
		(layer "In13.Cu")
		(net "P5E_CPU1_P0_RX_DP<5>")
	)
	(arc
		(start 102.063042 -278.600916)
		(mid 102.306369 -278.13635)
		(end 102.063042 -277.671784)
		(width 0.1143)
		(layer "In13.Cu")
		(net "P5E_CPU1_P0_RX_DP<5>")
	)
	(arc
		(start 101.993446 -285.731204)
		(mid 101.836469 -285.426404)
		(end 101.993446 -285.121604)
		(width 0.1143)
		(layer "In13.Cu")
		(net "P5E_CPU1_P0_RX_DP<5>")
	)
	(arc
		(start 133.529578 -358.751886)
		(mid 133.634724 -358.571644)
		(end 133.637274 -358.363012)
		(width 0.14224)
		(layer "In13.Cu")
		(net "P5E_CPU1_P0_RX_DP<5>")
	)
	(arc
		(start 101.993446 -276.011132)
		(mid 101.836469 -275.706332)
		(end 101.993446 -275.401532)
		(width 0.1143)
		(layer "In13.Cu")
		(net "P5E_CPU1_P0_RX_DP<5>")
	)
	(arc
		(start 102.063042 -273.74088)
		(mid 102.306369 -273.276314)
		(end 102.063042 -272.811748)
		(width 0.1143)
		(layer "In13.Cu")
		(net "P5E_CPU1_P0_RX_DP<5>")
	)
	(arc
		(start 102.063042 -294.800782)
		(mid 102.306369 -294.336216)
		(end 102.063042 -293.87165)
		(width 0.1143)
		(layer "In13.Cu")
		(net "P5E_CPU1_P0_RX_DP<5>")
	)
	(arc
		(start 102.063042 -280.220928)
		(mid 102.306369 -279.756362)
		(end 102.063042 -279.291796)
		(width 0.1143)
		(layer "In13.Cu")
		(net "P5E_CPU1_P0_RX_DP<5>")
	)
	(arc
		(start 101.553264 -270.359632)
		(mid 101.545332 -270.354901)
		(end 101.537516 -270.34998)
		(width 0.1143)
		(layer "In13.Cu")
		(net "P5E_CPU1_P0_RX_DP<5>")
	)
	(arc
		(start 55.218584 -380.712726)
		(mid 55.276443 -380.574284)
		(end 55.348124 -380.44247)
		(width 0.14224)
		(layer "In13.Cu")
		(net "P5E_CPU1_P0_RX_DP<5>")
	)
	(arc
		(start 101.993446 -277.631144)
		(mid 101.836469 -277.326344)
		(end 101.993446 -277.021544)
		(width 0.1143)
		(layer "In13.Cu")
		(net "P5E_CPU1_P0_RX_DP<5>")
	)
	(arc
		(start 102.063042 -276.980904)
		(mid 102.306369 -276.516338)
		(end 102.063042 -276.051772)
		(width 0.1143)
		(layer "In13.Cu")
		(net "P5E_CPU1_P0_RX_DP<5>")
	)
	(arc
		(start 106.621326 -301.940722)
		(mid 106.291112 -301.733267)
		(end 105.99547 -301.47895)
		(width 0.14224)
		(layer "In13.Cu")
		(net "P5E_CPU1_P0_RX_DP<5>")
	)
	(arc
		(start 101.993446 -287.350962)
		(mid 101.878019 -287.217586)
		(end 101.836474 -287.046162)
		(width 0.1143)
		(layer "In13.Cu")
		(net "P5E_CPU1_P0_RX_DP<5>")
	)
	(arc
		(start 101.993446 -293.83101)
		(mid 101.836469 -293.52621)
		(end 101.993446 -293.22141)
		(width 0.1143)
		(layer "In13.Cu")
		(net "P5E_CPU1_P0_RX_DP<5>")
	)
	(arc
		(start 102.063042 -289.940746)
		(mid 102.306369 -289.47618)
		(end 102.063042 -289.011614)
		(width 0.1143)
		(layer "In13.Cu")
		(net "P5E_CPU1_P0_RX_DP<5>")
	)
	(arc
		(start 101.993446 -271.151096)
		(mid 101.878019 -271.01772)
		(end 101.836474 -270.846296)
		(width 0.1143)
		(layer "In13.Cu")
		(net "P5E_CPU1_P0_RX_DP<5>")
	)
	(arc
		(start 128.498092 -366.833658)
		(mid 128.65467 -366.802495)
		(end 128.787398 -366.71377)
		(width 0.14224)
		(layer "In13.Cu")
		(net "P5E_CPU1_P0_RX_DP<5>")
	)
	(arc
		(start 101.993446 -272.771108)
		(mid 101.836469 -272.466308)
		(end 101.993446 -272.161508)
		(width 0.1143)
		(layer "In13.Cu")
		(net "P5E_CPU1_P0_RX_DP<5>")
	)
	(arc
		(start 101.836474 -287.046162)
		(mid 101.87744 -286.875756)
		(end 101.991414 -286.742632)
		(width 0.1143)
		(layer "In13.Cu")
		(net "P5E_CPU1_P0_RX_DP<5>")
	)
	(arc
		(start 101.8286 -295.122092)
		(mid 101.848849 -295.020764)
		(end 101.906324 -294.934894)
		(width 0.1143)
		(layer "In13.Cu")
		(net "P5E_CPU1_P0_RX_DP<5>")
	)
	(arc
		(start 102.233476 -295.666414)
		(mid 102.166681 -295.574684)
		(end 102.078028 -295.503854)
		(width 0.1143)
		(layer "In13.Cu")
		(net "P5E_CPU1_P0_RX_DP<5>")
	)
	(arc
		(start 102.475792 -297.959272)
		(mid 102.384245 -297.822356)
		(end 102.352094 -297.660822)
		(width 0.14224)
		(layer "In13.Cu")
		(net "P5E_CPU1_P0_RX_DP<5>")
	)
	(arc
		(start 102.063042 -281.84094)
		(mid 102.306369 -281.376374)
		(end 102.063042 -280.911808)
		(width 0.1143)
		(layer "In13.Cu")
		(net "P5E_CPU1_P0_RX_DP<5>")
	)
	(arc
		(start 102.063042 -288.320988)
		(mid 102.241855 -288.118638)
		(end 102.306374 -287.856422)
		(width 0.1143)
		(layer "In13.Cu")
		(net "P5E_CPU1_P0_RX_DP<5>")
	)
	(arc
		(start 102.063042 -275.360892)
		(mid 102.306369 -274.896326)
		(end 102.063042 -274.43176)
		(width 0.1143)
		(layer "In13.Cu")
		(net "P5E_CPU1_P0_RX_DP<5>")
	)
	(arc
		(start 101.993446 -274.39112)
		(mid 101.836469 -274.08632)
		(end 101.993446 -273.78152)
		(width 0.1143)
		(layer "In13.Cu")
		(net "P5E_CPU1_P0_RX_DP<5>")
	)
	(arc
		(start 101.981762 -295.44772)
		(mid 101.958038 -295.431774)
		(end 101.93655 -295.412922)
		(width 0.1143)
		(layer "In13.Cu")
		(net "P5E_CPU1_P0_RX_DP<5>")
	)
	(arc
		(start 112.717834 -305.465734)
		(mid 112.621684 -305.33387)
		(end 112.496854 -305.228752)
		(width 0.14224)
		(layer "In13.Cu")
		(net "P5E_CPU1_P0_RX_DP<5>")
	)
	(arc
		(start 101.993446 -288.970974)
		(mid 101.878019 -288.837598)
		(end 101.836474 -288.666174)
		(width 0.1143)
		(layer "In13.Cu")
		(net "P5E_CPU1_P0_RX_DP<5>")
	)
	(arc
		(start 101.993446 -280.871168)
		(mid 101.836469 -280.566368)
		(end 101.993446 -280.261568)
		(width 0.1143)
		(layer "In13.Cu")
		(net "P5E_CPU1_P0_RX_DP<5>")
	)
	(arc
		(start 101.836474 -270.846296)
		(mid 101.762268 -270.567838)
		(end 101.55936 -270.363188)
		(width 0.1143)
		(layer "In13.Cu")
		(net "P5E_CPU1_P0_RX_DP<5>")
	)
	(arc
		(start 102.063042 -283.460952)
		(mid 102.306369 -282.996386)
		(end 102.063042 -282.53182)
		(width 0.1143)
		(layer "In13.Cu")
		(net "P5E_CPU1_P0_RX_DP<5>")
	)
	(arc
		(start 62.967616 -367.995708)
		(mid 62.98065 -367.977931)
		(end 62.996572 -367.962688)
		(width 0.14224)
		(layer "In13.Cu")
		(net "P5E_CPU1_P0_RX_DP<5>")
	)
	(arc
		(start 102.063042 -286.700976)
		(mid 102.306369 -286.23641)
		(end 102.063042 -285.771844)
		(width 0.1143)
		(layer "In13.Cu")
		(net "P5E_CPU1_P0_RX_DP<5>")
	)
	(arc
		(start 102.063042 -272.120868)
		(mid 102.306369 -271.656302)
		(end 102.063042 -271.191736)
		(width 0.1143)
		(layer "In13.Cu")
		(net "P5E_CPU1_P0_RX_DP<5>")
	)
	(arc
		(start 101.993446 -290.590986)
		(mid 101.836469 -290.286186)
		(end 101.993446 -289.981386)
		(width 0.1143)
		(layer "In13.Cu")
		(net "P5E_CPU1_P0_RX_DP<5>")
	)
	(arc
		(start 101.993446 -282.49118)
		(mid 101.836469 -282.18638)
		(end 101.993446 -281.88158)
		(width 0.1143)
		(layer "In13.Cu")
		(net "P5E_CPU1_P0_RX_DP<5>")
	)
	(arc
		(start 101.88321 -295.359582)
		(mid 101.842846 -295.299217)
		(end 101.8286 -295.22801)
		(width 0.1143)
		(layer "In13.Cu")
		(net "P5E_CPU1_P0_RX_DP<5>")
	)
	(arc
		(start 102.063042 -285.080964)
		(mid 102.306369 -284.616398)
		(end 102.063042 -284.151832)
		(width 0.1143)
		(layer "In13.Cu")
		(net "P5E_CPU1_P0_RX_DP<5>")
	)
	(arc
		(start 101.537516 -270.34998)
		(mid 101.430214 -270.244988)
		(end 101.373178 -270.10614)
		(width 0.1143)
		(layer "In13.Cu")
		(net "P5E_CPU1_P0_RX_DP<5>")
	)
	(arc
		(start 102.063042 -291.560758)
		(mid 102.306369 -291.096192)
		(end 102.063042 -290.631626)
		(width 0.1143)
		(layer "In13.Cu")
		(net "P5E_CPU1_P0_RX_DP<5>")
	)
	(arc
		(start 102.306374 -295.956228)
		(mid 102.28804 -295.80676)
		(end 102.233476 -295.666414)
		(width 0.1143)
		(layer "In13.Cu")
		(net "P5E_CPU1_P0_RX_DP<5>")
	)
	(arc
		(start 102.063042 -293.18077)
		(mid 102.306369 -292.716204)
		(end 102.063042 -292.251638)
		(width 0.1143)
		(layer "In13.Cu")
		(net "P5E_CPU1_P0_RX_DP<5>")
	)
	(segment
		(start 52.470558 -386.003292)
		(end 52.991258 -386.003292)
		(width 0.127)
		(layer "F.Cu")
		(net "P5E_CPU1_P0_RX_DP<4>")
	)
	(segment
		(start 102.207822 -273.010376)
		(end 101.74097 -273.276314)
		(width 0.12954)
		(layer "F.Cu")
		(net "P5E_CPU1_P0_RX_DP<4>")
	)
	(segment
		(start 121.858278 -319.941448)
		(end 111.40948 -305.853592)
		(width 0.14224)
		(layer "In13.Cu")
		(net "P5E_CPU1_P0_RX_DP<4>")
	)
	(segment
		(start 130.297174 -357.6447)
		(end 130.701796 -358.049322)
		(width 0.14224)
		(layer "In13.Cu")
		(net "P5E_CPU1_P0_RX_DP<4>")
	)
	(segment
		(start 101.123242 -279.291796)
		(end 101.053646 -279.251156)
		(width 0.1143)
		(layer "In13.Cu")
		(net "P5E_CPU1_P0_RX_DP<4>")
	)
	(segment
		(start 111.170466 -305.647598)
		(end 105.757726 -302.755046)
		(width 0.14224)
		(layer "In13.Cu")
		(net "P5E_CPU1_P0_RX_DP<4>")
	)
	(segment
		(start 101.05136 -288.362644)
		(end 101.123242 -288.321242)
		(width 0.1143)
		(layer "In13.Cu")
		(net "P5E_CPU1_P0_RX_DP<4>")
	)
	(segment
		(start 101.053392 -293.22141)
		(end 101.123242 -293.18077)
		(width 0.1143)
		(layer "In13.Cu")
		(net "P5E_CPU1_P0_RX_DP<4>")
	)
	(segment
		(start 101.055424 -286.7406)
		(end 101.056694 -286.739838)
		(width 0.1143)
		(layer "In13.Cu")
		(net "P5E_CPU1_P0_RX_DP<4>")
	)
	(segment
		(start 112.008158 -364.272068)
		(end 112.008158 -363.700568)
		(width 0.14224)
		(layer "In13.Cu")
		(net "P5E_CPU1_P0_RX_DP<4>")
	)
	(segment
		(start 101.058472 -286.738568)
		(end 101.059742 -286.737806)
		(width 0.1143)
		(layer "In13.Cu")
		(net "P5E_CPU1_P0_RX_DP<4>")
	)
	(segment
		(start 101.053646 -285.121604)
		(end 101.123242 -285.080964)
		(width 0.1143)
		(layer "In13.Cu")
		(net "P5E_CPU1_P0_RX_DP<4>")
	)
	(segment
		(start 101.122988 -290.631372)
		(end 101.053138 -290.590986)
		(width 0.1143)
		(layer "In13.Cu")
		(net "P5E_CPU1_P0_RX_DP<4>")
	)
	(segment
		(start 101.060758 -286.737044)
		(end 101.06406 -286.735012)
		(width 0.1143)
		(layer "In13.Cu")
		(net "P5E_CPU1_P0_RX_DP<4>")
	)
	(segment
		(start 118.762018 -364.721648)
		(end 118.454678 -364.414308)
		(width 0.14224)
		(layer "In13.Cu")
		(net "P5E_CPU1_P0_RX_DP<4>")
	)
	(segment
		(start 101.084126 -286.723074)
		(end 101.084888 -286.722566)
		(width 0.1143)
		(layer "In13.Cu")
		(net "P5E_CPU1_P0_RX_DP<4>")
	)
	(segment
		(start 101.051106 -286.74314)
		(end 101.052376 -286.742378)
		(width 0.1143)
		(layer "In13.Cu")
		(net "P5E_CPU1_P0_RX_DP<4>")
	)
	(segment
		(start 100.94214 -297.905424)
		(end 100.94214 -296.422318)
		(width 0.14224)
		(layer "In13.Cu")
		(net "P5E_CPU1_P0_RX_DP<4>")
	)
	(segment
		(start 101.06406 -286.735012)
		(end 101.067362 -286.732726)
		(width 0.1143)
		(layer "In13.Cu")
		(net "P5E_CPU1_P0_RX_DP<4>")
	)
	(segment
		(start 101.053646 -273.78152)
		(end 101.123242 -273.74088)
		(width 0.1143)
		(layer "In13.Cu")
		(net "P5E_CPU1_P0_RX_DP<4>")
	)
	(segment
		(start 112.150398 -363.558328)
		(end 124.013976 -363.558328)
		(width 0.14224)
		(layer "In13.Cu")
		(net "P5E_CPU1_P0_RX_DP<4>")
	)
	(segment
		(start 65.676018 -365.04245)
		(end 109.252004 -365.04245)
		(width 0.14224)
		(layer "In13.Cu")
		(net "P5E_CPU1_P0_RX_DP<4>")
	)
	(segment
		(start 123.048776 -361.473242)
		(end 125.502924 -359.01884)
		(width 0.14224)
		(layer "In13.Cu")
		(net "P5E_CPU1_P0_RX_DP<4>")
	)
	(segment
		(start 101.122988 -292.251384)
		(end 101.053138 -292.210998)
		(width 0.1143)
		(layer "In13.Cu")
		(net "P5E_CPU1_P0_RX_DP<4>")
	)
	(segment
		(start 118.762018 -365.526828)
		(end 118.762018 -364.721648)
		(width 0.14224)
		(layer "In13.Cu")
		(net "P5E_CPU1_P0_RX_DP<4>")
	)
	(segment
		(start 53.348636 -385.046982)
		(end 53.03266 -384.731006)
		(width 0.14224)
		(layer "In13.Cu")
		(net "P5E_CPU1_P0_RX_DP<4>")
	)
	(segment
		(start 101.360478 -273.359118)
		(end 101.443282 -273.276314)
		(width 0.1143)
		(layer "In13.Cu")
		(net "P5E_CPU1_P0_RX_DP<4>")
	)
	(segment
		(start 101.053392 -289.981386)
		(end 101.123242 -289.940746)
		(width 0.1143)
		(layer "In13.Cu")
		(net "P5E_CPU1_P0_RX_DP<4>")
	)
	(segment
		(start 101.053646 -281.88158)
		(end 101.123242 -281.84094)
		(width 0.1143)
		(layer "In13.Cu")
		(net "P5E_CPU1_P0_RX_DP<4>")
	)
	(segment
		(start 101.059742 -286.737806)
		(end 101.060758 -286.737044)
		(width 0.1143)
		(layer "In13.Cu")
		(net "P5E_CPU1_P0_RX_DP<4>")
	)
	(segment
		(start 110.265718 -365.834168)
		(end 118.454678 -365.834168)
		(width 0.14224)
		(layer "In13.Cu")
		(net "P5E_CPU1_P0_RX_DP<4>")
	)
	(segment
		(start 101.123242 -289.01136)
		(end 101.053646 -288.970974)
		(width 0.1143)
		(layer "In13.Cu")
		(net "P5E_CPU1_P0_RX_DP<4>")
	)
	(segment
		(start 126.995682 -360.310938)
		(end 127.43053 -360.310938)
		(width 0.14224)
		(layer "In13.Cu")
		(net "P5E_CPU1_P0_RX_DP<4>")
	)
	(segment
		(start 127.43053 -360.310938)
		(end 130.096768 -357.6447)
		(width 0.14224)
		(layer "In13.Cu")
		(net "P5E_CPU1_P0_RX_DP<4>")
	)
	(segment
		(start 125.820678 -360.347768)
		(end 125.38583 -360.347768)
		(width 0.14224)
		(layer "In13.Cu")
		(net "P5E_CPU1_P0_RX_DP<4>")
	)
	(segment
		(start 101.053646 -277.021544)
		(end 101.123242 -276.980904)
		(width 0.1143)
		(layer "In13.Cu")
		(net "P5E_CPU1_P0_RX_DP<4>")
	)
	(segment
		(start 101.069902 -286.731202)
		(end 101.084126 -286.723074)
		(width 0.1143)
		(layer "In13.Cu")
		(net "P5E_CPU1_P0_RX_DP<4>")
	)
	(segment
		(start 126.389892 -361.35183)
		(end 126.389892 -360.916982)
		(width 0.14224)
		(layer "In13.Cu")
		(net "P5E_CPU1_P0_RX_DP<4>")
	)
	(segment
		(start 53.340508 -384.048)
		(end 53.340508 -382.633982)
		(width 0.14224)
		(layer "In13.Cu")
		(net "P5E_CPU1_P0_RX_DP<4>")
	)
	(segment
		(start 132.371846 -358.318054)
		(end 128.335532 -340.84641)
		(width 0.14224)
		(layer "In13.Cu")
		(net "P5E_CPU1_P0_RX_DP<4>")
	)
	(segment
		(start 126.31039 -364.651544)
		(end 132.262372 -358.699562)
		(width 0.14224)
		(layer "In13.Cu")
		(net "P5E_CPU1_P0_RX_DP<4>")
	)
	(segment
		(start 100.94214 -296.39387)
		(end 100.89642 -296.34815)
		(width 0.1143)
		(layer "In13.Cu")
		(net "P5E_CPU1_P0_RX_DP<4>")
	)
	(segment
		(start 101.053646 -280.261568)
		(end 101.123242 -280.220928)
		(width 0.1143)
		(layer "In13.Cu")
		(net "P5E_CPU1_P0_RX_DP<4>")
	)
	(segment
		(start 101.068378 -286.732218)
		(end 101.069902 -286.731202)
		(width 0.1143)
		(layer "In13.Cu")
		(net "P5E_CPU1_P0_RX_DP<4>")
	)
	(segment
		(start 101.123242 -276.051772)
		(end 101.053646 -276.011132)
		(width 0.1143)
		(layer "In13.Cu")
		(net "P5E_CPU1_P0_RX_DP<4>")
	)
	(segment
		(start 101.120702 -287.389824)
		(end 101.053392 -287.350962)
		(width 0.1143)
		(layer "In13.Cu")
		(net "P5E_CPU1_P0_RX_DP<4>")
	)
	(segment
		(start 127.243078 -334.55102)
		(end 126.366778 -330.758292)
		(width 0.14224)
		(layer "In13.Cu")
		(net "P5E_CPU1_P0_RX_DP<4>")
	)
	(segment
		(start 125.703584 -359.01884)
		(end 126.995682 -360.310938)
		(width 0.14224)
		(layer "In13.Cu")
		(net "P5E_CPU1_P0_RX_DP<4>")
	)
	(segment
		(start 101.123242 -274.43176)
		(end 101.053646 -274.39112)
		(width 0.1143)
		(layer "In13.Cu")
		(net "P5E_CPU1_P0_RX_DP<4>")
	)
	(segment
		(start 53.348636 -385.460494)
		(end 53.348636 -385.046982)
		(width 0.14224)
		(layer "In13.Cu")
		(net "P5E_CPU1_P0_RX_DP<4>")
	)
	(segment
		(start 128.335532 -340.84641)
		(end 127.243078 -334.55102)
		(width 0.14224)
		(layer "In13.Cu")
		(net "P5E_CPU1_P0_RX_DP<4>")
	)
	(segment
		(start 130.701542 -358.250744)
		(end 125.305566 -363.64672)
		(width 0.14224)
		(layer "In13.Cu")
		(net "P5E_CPU1_P0_RX_DP<4>")
	)
	(segment
		(start 125.305566 -363.64672)
		(end 125.305566 -364.08106)
		(width 0.14224)
		(layer "In13.Cu")
		(net "P5E_CPU1_P0_RX_DP<4>")
	)
	(segment
		(start 124.667264 -324.899274)
		(end 121.858278 -319.941448)
		(width 0.14224)
		(layer "In13.Cu")
		(net "P5E_CPU1_P0_RX_DP<4>")
	)
	(segment
		(start 101.067362 -286.732726)
		(end 101.068378 -286.732218)
		(width 0.1143)
		(layer "In13.Cu")
		(net "P5E_CPU1_P0_RX_DP<4>")
	)
	(segment
		(start 123.048776 -361.673902)
		(end 123.048776 -361.473242)
		(width 0.14224)
		(layer "In13.Cu")
		(net "P5E_CPU1_P0_RX_DP<4>")
	)
	(segment
		(start 118.454678 -365.834168)
		(end 118.762018 -365.526828)
		(width 0.14224)
		(layer "In13.Cu")
		(net "P5E_CPU1_P0_RX_DP<4>")
	)
	(segment
		(start 53.035708 -384.3528)
		(end 53.340508 -384.048)
		(width 0.14224)
		(layer "In13.Cu")
		(net "P5E_CPU1_P0_RX_DP<4>")
	)
	(segment
		(start 130.096768 -357.6447)
		(end 130.297174 -357.6447)
		(width 0.14224)
		(layer "In13.Cu")
		(net "P5E_CPU1_P0_RX_DP<4>")
	)
	(segment
		(start 101.056694 -286.739838)
		(end 101.058472 -286.738568)
		(width 0.1143)
		(layer "In13.Cu")
		(net "P5E_CPU1_P0_RX_DP<4>")
	)
	(segment
		(start 101.122988 -293.871396)
		(end 101.053138 -293.83101)
		(width 0.1143)
		(layer "In13.Cu")
		(net "P5E_CPU1_P0_RX_DP<4>")
	)
	(segment
		(start 54.226968 -380.483364)
		(end 62.177168 -367.495836)
		(width 0.14224)
		(layer "In13.Cu")
		(net "P5E_CPU1_P0_RX_DP<4>")
	)
	(segment
		(start 53.350414 -382.58496)
		(end 54.226968 -380.483364)
		(width 0.14224)
		(layer "In13.Cu")
		(net "P5E_CPU1_P0_RX_DP<4>")
	)
	(segment
		(start 112.150398 -364.414308)
		(end 112.008158 -364.272068)
		(width 0.14224)
		(layer "In13.Cu")
		(net "P5E_CPU1_P0_RX_DP<4>")
	)
	(segment
		(start 123.65482 -362.078778)
		(end 123.453652 -362.078778)
		(width 0.14224)
		(layer "In13.Cu")
		(net "P5E_CPU1_P0_RX_DP<4>")
	)
	(segment
		(start 126.366778 -330.758292)
		(end 124.667264 -324.899274)
		(width 0.14224)
		(layer "In13.Cu")
		(net "P5E_CPU1_P0_RX_DP<4>")
	)
	(segment
		(start 101.123242 -277.671784)
		(end 101.053646 -277.631144)
		(width 0.1143)
		(layer "In13.Cu")
		(net "P5E_CPU1_P0_RX_DP<4>")
	)
	(segment
		(start 53.260498 -385.548632)
		(end 53.348636 -385.460494)
		(width 0.14224)
		(layer "In13.Cu")
		(net "P5E_CPU1_P0_RX_DP<4>")
	)
	(segment
		(start 100.89642 -296.34815)
		(end 100.89642 -295.145714)
		(width 0.1143)
		(layer "In13.Cu")
		(net "P5E_CPU1_P0_RX_DP<4>")
	)
	(segment
		(start 112.008158 -363.700568)
		(end 112.150398 -363.558328)
		(width 0.14224)
		(layer "In13.Cu")
		(net "P5E_CPU1_P0_RX_DP<4>")
	)
	(segment
		(start 101.058218 -285.733998)
		(end 101.053138 -285.731204)
		(width 0.1143)
		(layer "In13.Cu")
		(net "P5E_CPU1_P0_RX_DP<4>")
	)
	(segment
		(start 101.04882 -286.744664)
		(end 101.05009 -286.743648)
		(width 0.1143)
		(layer "In13.Cu")
		(net "P5E_CPU1_P0_RX_DP<4>")
	)
	(segment
		(start 101.053646 -275.401532)
		(end 101.123242 -275.360892)
		(width 0.1143)
		(layer "In13.Cu")
		(net "P5E_CPU1_P0_RX_DP<4>")
	)
	(segment
		(start 123.453652 -362.078778)
		(end 123.048776 -361.673902)
		(width 0.14224)
		(layer "In13.Cu")
		(net "P5E_CPU1_P0_RX_DP<4>")
	)
	(segment
		(start 105.589324 -302.630586)
		(end 100.997258 -298.03852)
		(width 0.14224)
		(layer "In13.Cu")
		(net "P5E_CPU1_P0_RX_DP<4>")
	)
	(segment
		(start 53.086254 -385.649216)
		(end 53.260498 -385.548632)
		(width 0.14224)
		(layer "In13.Cu")
		(net "P5E_CPU1_P0_RX_DP<4>")
	)
	(segment
		(start 109.34192 -365.079788)
		(end 109.976412 -365.71428)
		(width 0.14224)
		(layer "In13.Cu")
		(net "P5E_CPU1_P0_RX_DP<4>")
	)
	(segment
		(start 125.38583 -360.347768)
		(end 123.65482 -362.078778)
		(width 0.14224)
		(layer "In13.Cu")
		(net "P5E_CPU1_P0_RX_DP<4>")
	)
	(segment
		(start 101.123242 -280.911808)
		(end 101.053646 -280.871168)
		(width 0.1143)
		(layer "In13.Cu")
		(net "P5E_CPU1_P0_RX_DP<4>")
	)
	(segment
		(start 53.03266 -384.731006)
		(end 53.035708 -384.3528)
		(width 0.14224)
		(layer "In13.Cu")
		(net "P5E_CPU1_P0_RX_DP<4>")
	)
	(segment
		(start 101.053392 -291.601398)
		(end 101.123242 -291.560758)
		(width 0.1143)
		(layer "In13.Cu")
		(net "P5E_CPU1_P0_RX_DP<4>")
	)
	(segment
		(start 125.875796 -364.651544)
		(end 126.31039 -364.651544)
		(width 0.14224)
		(layer "In13.Cu")
		(net "P5E_CPU1_P0_RX_DP<4>")
	)
	(segment
		(start 101.052376 -286.742378)
		(end 101.054408 -286.741108)
		(width 0.1143)
		(layer "In13.Cu")
		(net "P5E_CPU1_P0_RX_DP<4>")
	)
	(segment
		(start 101.123242 -284.151832)
		(end 101.053646 -284.111192)
		(width 0.1143)
		(layer "In13.Cu")
		(net "P5E_CPU1_P0_RX_DP<4>")
	)
	(segment
		(start 125.502924 -359.01884)
		(end 125.703584 -359.01884)
		(width 0.14224)
		(layer "In13.Cu")
		(net "P5E_CPU1_P0_RX_DP<4>")
	)
	(segment
		(start 101.123242 -285.771844)
		(end 101.058218 -285.733998)
		(width 0.1143)
		(layer "In13.Cu")
		(net "P5E_CPU1_P0_RX_DP<4>")
	)
	(segment
		(start 130.701796 -358.049322)
		(end 130.701542 -358.250744)
		(width 0.14224)
		(layer "In13.Cu")
		(net "P5E_CPU1_P0_RX_DP<4>")
	)
	(segment
		(start 101.053646 -283.501592)
		(end 101.123242 -283.460952)
		(width 0.1143)
		(layer "In13.Cu")
		(net "P5E_CPU1_P0_RX_DP<4>")
	)
	(segment
		(start 101.443282 -273.276314)
		(end 101.74097 -273.276314)
		(width 0.1143)
		(layer "In13.Cu")
		(net "P5E_CPU1_P0_RX_DP<4>")
	)
	(segment
		(start 101.123242 -282.53182)
		(end 101.053646 -282.49118)
		(width 0.1143)
		(layer "In13.Cu")
		(net "P5E_CPU1_P0_RX_DP<4>")
	)
	(segment
		(start 52.991258 -386.003292)
		(end 53.086254 -385.649216)
		(width 0.14224)
		(layer "In13.Cu")
		(net "P5E_CPU1_P0_RX_DP<4>")
	)
	(segment
		(start 126.389892 -360.916982)
		(end 125.820678 -360.347768)
		(width 0.14224)
		(layer "In13.Cu")
		(net "P5E_CPU1_P0_RX_DP<4>")
	)
	(segment
		(start 101.053646 -278.641556)
		(end 101.123242 -278.600916)
		(width 0.1143)
		(layer "In13.Cu")
		(net "P5E_CPU1_P0_RX_DP<4>")
	)
	(segment
		(start 125.305566 -364.08106)
		(end 125.875796 -364.651544)
		(width 0.14224)
		(layer "In13.Cu")
		(net "P5E_CPU1_P0_RX_DP<4>")
	)
	(segment
		(start 62.401958 -367.241074)
		(end 64.741298 -365.370364)
		(width 0.14224)
		(layer "In13.Cu")
		(net "P5E_CPU1_P0_RX_DP<4>")
	)
	(segment
		(start 101.054408 -286.741108)
		(end 101.055424 -286.7406)
		(width 0.1143)
		(layer "In13.Cu")
		(net "P5E_CPU1_P0_RX_DP<4>")
	)
	(segment
		(start 124.303282 -363.43844)
		(end 126.389892 -361.35183)
		(width 0.14224)
		(layer "In13.Cu")
		(net "P5E_CPU1_P0_RX_DP<4>")
	)
	(segment
		(start 101.05009 -286.743648)
		(end 101.051106 -286.74314)
		(width 0.1143)
		(layer "In13.Cu")
		(net "P5E_CPU1_P0_RX_DP<4>")
	)
	(segment
		(start 118.454678 -364.414308)
		(end 112.150398 -364.414308)
		(width 0.14224)
		(layer "In13.Cu")
		(net "P5E_CPU1_P0_RX_DP<4>")
	)
	(segment
		(start 101.053646 -294.841422)
		(end 101.123242 -294.800782)
		(width 0.1143)
		(layer "In13.Cu")
		(net "P5E_CPU1_P0_RX_DP<4>")
	)
	(segment
		(start 100.94214 -296.422318)
		(end 100.94214 -296.39387)
		(width 0.1143)
		(layer "In13.Cu")
		(net "P5E_CPU1_P0_RX_DP<4>")
	)
	(arc
		(start 101.123242 -275.360892)
		(mid 101.366569 -274.896326)
		(end 101.123242 -274.43176)
		(width 0.1143)
		(layer "In13.Cu")
		(net "P5E_CPU1_P0_RX_DP<4>")
	)
	(arc
		(start 101.123242 -293.18077)
		(mid 101.366569 -292.716027)
		(end 101.122988 -292.251384)
		(width 0.1143)
		(layer "In13.Cu")
		(net "P5E_CPU1_P0_RX_DP<4>")
	)
	(arc
		(start 62.177168 -367.495836)
		(mid 62.278501 -367.358697)
		(end 62.401958 -367.241074)
		(width 0.14224)
		(layer "In13.Cu")
		(net "P5E_CPU1_P0_RX_DP<4>")
	)
	(arc
		(start 101.053646 -277.631144)
		(mid 100.896669 -277.326344)
		(end 101.053646 -277.021544)
		(width 0.1143)
		(layer "In13.Cu")
		(net "P5E_CPU1_P0_RX_DP<4>")
	)
	(arc
		(start 101.123242 -289.940746)
		(mid 101.366678 -289.476108)
		(end 101.123242 -289.01136)
		(width 0.1143)
		(layer "In13.Cu")
		(net "P5E_CPU1_P0_RX_DP<4>")
	)
	(arc
		(start 101.053138 -290.590986)
		(mid 100.896374 -290.286083)
		(end 101.053392 -289.981386)
		(width 0.1143)
		(layer "In13.Cu")
		(net "P5E_CPU1_P0_RX_DP<4>")
	)
	(arc
		(start 111.40948 -305.853592)
		(mid 111.301404 -305.737328)
		(end 111.170466 -305.647598)
		(width 0.14224)
		(layer "In13.Cu")
		(net "P5E_CPU1_P0_RX_DP<4>")
	)
	(arc
		(start 101.053646 -279.251156)
		(mid 100.896669 -278.946356)
		(end 101.053646 -278.641556)
		(width 0.1143)
		(layer "In13.Cu")
		(net "P5E_CPU1_P0_RX_DP<4>")
	)
	(arc
		(start 101.053646 -274.39112)
		(mid 100.896669 -274.08632)
		(end 101.053646 -273.78152)
		(width 0.1143)
		(layer "In13.Cu")
		(net "P5E_CPU1_P0_RX_DP<4>")
	)
	(arc
		(start 101.123242 -280.220928)
		(mid 101.366569 -279.756362)
		(end 101.123242 -279.291796)
		(width 0.1143)
		(layer "In13.Cu")
		(net "P5E_CPU1_P0_RX_DP<4>")
	)
	(arc
		(start 101.053646 -276.011132)
		(mid 100.896669 -275.706332)
		(end 101.053646 -275.401532)
		(width 0.1143)
		(layer "In13.Cu")
		(net "P5E_CPU1_P0_RX_DP<4>")
	)
	(arc
		(start 101.053646 -284.111192)
		(mid 100.896669 -283.806392)
		(end 101.053646 -283.501592)
		(width 0.1143)
		(layer "In13.Cu")
		(net "P5E_CPU1_P0_RX_DP<4>")
	)
	(arc
		(start 101.123242 -281.84094)
		(mid 101.366569 -281.376374)
		(end 101.123242 -280.911808)
		(width 0.1143)
		(layer "In13.Cu")
		(net "P5E_CPU1_P0_RX_DP<4>")
	)
	(arc
		(start 101.123242 -278.600916)
		(mid 101.366569 -278.13635)
		(end 101.123242 -277.671784)
		(width 0.1143)
		(layer "In13.Cu")
		(net "P5E_CPU1_P0_RX_DP<4>")
	)
	(arc
		(start 101.053646 -280.871168)
		(mid 100.896669 -280.566368)
		(end 101.053646 -280.261568)
		(width 0.1143)
		(layer "In13.Cu")
		(net "P5E_CPU1_P0_RX_DP<4>")
	)
	(arc
		(start 101.123242 -288.321242)
		(mid 101.366775 -287.854872)
		(end 101.120702 -287.389824)
		(width 0.1143)
		(layer "In13.Cu")
		(net "P5E_CPU1_P0_RX_DP<4>")
	)
	(arc
		(start 100.896928 -288.666174)
		(mid 100.937709 -288.495877)
		(end 101.05136 -288.362644)
		(width 0.1143)
		(layer "In13.Cu")
		(net "P5E_CPU1_P0_RX_DP<4>")
	)
	(arc
		(start 100.997258 -298.03852)
		(mid 100.956456 -297.977455)
		(end 100.94214 -297.905424)
		(width 0.14224)
		(layer "In13.Cu")
		(net "P5E_CPU1_P0_RX_DP<4>")
	)
	(arc
		(start 109.252004 -365.04245)
		(mid 109.300688 -365.052152)
		(end 109.34192 -365.079788)
		(width 0.14224)
		(layer "In13.Cu")
		(net "P5E_CPU1_P0_RX_DP<4>")
	)
	(arc
		(start 64.741298 -365.370364)
		(mid 65.180736 -365.126796)
		(end 65.676018 -365.04245)
		(width 0.14224)
		(layer "In13.Cu")
		(net "P5E_CPU1_P0_RX_DP<4>")
	)
	(arc
		(start 101.053138 -293.83101)
		(mid 100.896374 -293.526107)
		(end 101.053392 -293.22141)
		(width 0.1143)
		(layer "In13.Cu")
		(net "P5E_CPU1_P0_RX_DP<4>")
	)
	(arc
		(start 101.053138 -292.210998)
		(mid 100.896374 -291.906095)
		(end 101.053392 -291.601398)
		(width 0.1143)
		(layer "In13.Cu")
		(net "P5E_CPU1_P0_RX_DP<4>")
	)
	(arc
		(start 101.123242 -294.800782)
		(mid 101.366569 -294.336039)
		(end 101.122988 -293.871396)
		(width 0.1143)
		(layer "In13.Cu")
		(net "P5E_CPU1_P0_RX_DP<4>")
	)
	(arc
		(start 100.89642 -295.145714)
		(mid 100.938224 -294.974558)
		(end 101.053646 -294.841422)
		(width 0.1143)
		(layer "In13.Cu")
		(net "P5E_CPU1_P0_RX_DP<4>")
	)
	(arc
		(start 53.340508 -382.633982)
		(mid 53.343039 -382.608983)
		(end 53.350414 -382.58496)
		(width 0.14224)
		(layer "In13.Cu")
		(net "P5E_CPU1_P0_RX_DP<4>")
	)
	(arc
		(start 100.896928 -287.046162)
		(mid 100.936975 -286.877315)
		(end 101.04882 -286.744664)
		(width 0.1143)
		(layer "In13.Cu")
		(net "P5E_CPU1_P0_RX_DP<4>")
	)
	(arc
		(start 101.053646 -282.49118)
		(mid 100.896669 -282.18638)
		(end 101.053646 -281.88158)
		(width 0.1143)
		(layer "In13.Cu")
		(net "P5E_CPU1_P0_RX_DP<4>")
	)
	(arc
		(start 124.013976 -363.558328)
		(mid 124.170554 -363.527165)
		(end 124.303282 -363.43844)
		(width 0.14224)
		(layer "In13.Cu")
		(net "P5E_CPU1_P0_RX_DP<4>")
	)
	(arc
		(start 101.123242 -283.460952)
		(mid 101.366569 -282.996386)
		(end 101.123242 -282.53182)
		(width 0.1143)
		(layer "In13.Cu")
		(net "P5E_CPU1_P0_RX_DP<4>")
	)
	(arc
		(start 101.123242 -273.74088)
		(mid 101.275229 -273.584372)
		(end 101.356668 -273.381978)
		(width 0.1143)
		(layer "In13.Cu")
		(net "P5E_CPU1_P0_RX_DP<4>")
	)
	(arc
		(start 101.053138 -285.731204)
		(mid 100.896474 -285.426304)
		(end 101.053646 -285.121604)
		(width 0.1143)
		(layer "In13.Cu")
		(net "P5E_CPU1_P0_RX_DP<4>")
	)
	(arc
		(start 101.053646 -288.970974)
		(mid 100.938386 -288.837555)
		(end 100.896928 -288.666174)
		(width 0.1143)
		(layer "In13.Cu")
		(net "P5E_CPU1_P0_RX_DP<4>")
	)
	(arc
		(start 132.262372 -358.699562)
		(mid 132.366489 -358.522967)
		(end 132.371846 -358.318054)
		(width 0.14224)
		(layer "In13.Cu")
		(net "P5E_CPU1_P0_RX_DP<4>")
	)
	(arc
		(start 101.123242 -276.980904)
		(mid 101.366569 -276.516338)
		(end 101.123242 -276.051772)
		(width 0.1143)
		(layer "In13.Cu")
		(net "P5E_CPU1_P0_RX_DP<4>")
	)
	(arc
		(start 101.053392 -287.350962)
		(mid 100.938207 -287.217518)
		(end 100.896928 -287.046162)
		(width 0.1143)
		(layer "In13.Cu")
		(net "P5E_CPU1_P0_RX_DP<4>")
	)
	(arc
		(start 101.123242 -285.080964)
		(mid 101.366569 -284.616398)
		(end 101.123242 -284.151832)
		(width 0.1143)
		(layer "In13.Cu")
		(net "P5E_CPU1_P0_RX_DP<4>")
	)
	(arc
		(start 101.123242 -291.560758)
		(mid 101.366569 -291.096015)
		(end 101.122988 -290.631372)
		(width 0.1143)
		(layer "In13.Cu")
		(net "P5E_CPU1_P0_RX_DP<4>")
	)
	(arc
		(start 109.976412 -365.71428)
		(mid 110.109132 -365.803024)
		(end 110.265718 -365.834168)
		(width 0.14224)
		(layer "In13.Cu")
		(net "P5E_CPU1_P0_RX_DP<4>")
	)
	(arc
		(start 105.757726 -302.755046)
		(mid 105.668934 -302.699028)
		(end 105.589324 -302.630586)
		(width 0.14224)
		(layer "In13.Cu")
		(net "P5E_CPU1_P0_RX_DP<4>")
	)
	(arc
		(start 101.356668 -273.381978)
		(mid 101.358691 -273.370568)
		(end 101.360478 -273.359118)
		(width 0.1143)
		(layer "In13.Cu")
		(net "P5E_CPU1_P0_RX_DP<4>")
	)
	(arc
		(start 101.084888 -286.722566)
		(mid 101.365332 -286.257793)
		(end 101.123242 -285.771844)
		(width 0.1143)
		(layer "In13.Cu")
		(net "P5E_CPU1_P0_RX_DP<4>")
	)
	(segment
		(start 51.270662 -386.003292)
		(end 51.791362 -386.003292)
		(width 0.127)
		(layer "F.Cu")
		(net "P5E_CPU1_P0_RX_DP<3>")
	)
	(segment
		(start 102.207822 -271.390364)
		(end 101.74097 -271.656302)
		(width 0.12954)
		(layer "F.Cu")
		(net "P5E_CPU1_P0_RX_DP<3>")
	)
	(segment
		(start 100.113592 -275.401532)
		(end 100.144072 -275.383752)
		(width 0.1143)
		(layer "In13.Cu")
		(net "P5E_CPU1_P0_RX_DP<3>")
	)
	(segment
		(start 129.016506 -349.141288)
		(end 125.751336 -332.908148)
		(width 0.14224)
		(layer "In13.Cu")
		(net "P5E_CPU1_P0_RX_DP<3>")
	)
	(segment
		(start 99.943412 -295.269412)
		(end 99.943412 -295.125902)
		(width 0.1143)
		(layer "In13.Cu")
		(net "P5E_CPU1_P0_RX_DP<3>")
	)
	(segment
		(start 100.183188 -276.051772)
		(end 100.144072 -276.028912)
		(width 0.1143)
		(layer "In13.Cu")
		(net "P5E_CPU1_P0_RX_DP<3>")
	)
	(segment
		(start 121.656856 -362.510324)
		(end 121.964196 -362.202984)
		(width 0.14224)
		(layer "In13.Cu")
		(net "P5E_CPU1_P0_RX_DP<3>")
	)
	(segment
		(start 100.144072 -281.8638)
		(end 100.183188 -281.84094)
		(width 0.1143)
		(layer "In13.Cu")
		(net "P5E_CPU1_P0_RX_DP<3>")
	)
	(segment
		(start 100.11156 -288.362644)
		(end 100.144072 -288.343848)
		(width 0.1143)
		(layer "In13.Cu")
		(net "P5E_CPU1_P0_RX_DP<3>")
	)
	(segment
		(start 100.183188 -280.911808)
		(end 100.144072 -280.888948)
		(width 0.1143)
		(layer "In13.Cu")
		(net "P5E_CPU1_P0_RX_DP<3>")
	)
	(segment
		(start 100.144072 -292.228778)
		(end 100.113592 -292.210998)
		(width 0.1143)
		(layer "In13.Cu")
		(net "P5E_CPU1_P0_RX_DP<3>")
	)
	(segment
		(start 100.183188 -292.251638)
		(end 100.144072 -292.228778)
		(width 0.1143)
		(layer "In13.Cu")
		(net "P5E_CPU1_P0_RX_DP<3>")
	)
	(segment
		(start 100.020374 -294.940482)
		(end 100.12807 -294.832786)
		(width 0.1143)
		(layer "In13.Cu")
		(net "P5E_CPU1_P0_RX_DP<3>")
	)
	(segment
		(start 100.609908 -272.956274)
		(end 100.61067 -272.955766)
		(width 0.1143)
		(layer "In13.Cu")
		(net "P5E_CPU1_P0_RX_DP<3>")
	)
	(segment
		(start 122.83694 -360.07929)
		(end 128.471422 -354.444808)
		(width 0.14224)
		(layer "In13.Cu")
		(net "P5E_CPU1_P0_RX_DP<3>")
	)
	(segment
		(start 101.084126 -272.143728)
		(end 101.123242 -272.120868)
		(width 0.1143)
		(layer "In13.Cu")
		(net "P5E_CPU1_P0_RX_DP<3>")
	)
	(segment
		(start 111.05134 -360.234484)
		(end 122.46229 -360.234484)
		(width 0.14224)
		(layer "In13.Cu")
		(net "P5E_CPU1_P0_RX_DP<3>")
	)
	(segment
		(start 57.152286 -367.975388)
		(end 57.919112 -367.208562)
		(width 0.14224)
		(layer "In13.Cu")
		(net "P5E_CPU1_P0_RX_DP<3>")
	)
	(segment
		(start 51.791362 -386.003292)
		(end 51.886358 -385.649216)
		(width 0.14224)
		(layer "In13.Cu")
		(net "P5E_CPU1_P0_RX_DP<3>")
	)
	(segment
		(start 100.144072 -285.103824)
		(end 100.183188 -285.080964)
		(width 0.1143)
		(layer "In13.Cu")
		(net "P5E_CPU1_P0_RX_DP<3>")
	)
	(segment
		(start 100.604066 -272.959576)
		(end 100.604828 -272.959068)
		(width 0.1143)
		(layer "In13.Cu")
		(net "P5E_CPU1_P0_RX_DP<3>")
	)
	(segment
		(start 129.077212 -354.84943)
		(end 129.077212 -355.050598)
		(width 0.14224)
		(layer "In13.Cu")
		(net "P5E_CPU1_P0_RX_DP<3>")
	)
	(segment
		(start 52.140612 -384.048254)
		(end 52.140612 -382.800352)
		(width 0.14224)
		(layer "In13.Cu")
		(net "P5E_CPU1_P0_RX_DP<3>")
	)
	(segment
		(start 127.348234 -358.7877)
		(end 130.514344 -355.62159)
		(width 0.14224)
		(layer "In13.Cu")
		(net "P5E_CPU1_P0_RX_DP<3>")
	)
	(segment
		(start 128.471422 -354.444808)
		(end 128.67259 -354.444808)
		(width 0.14224)
		(layer "In13.Cu")
		(net "P5E_CPU1_P0_RX_DP<3>")
	)
	(segment
		(start 100.113592 -293.22141)
		(end 100.144072 -293.20363)
		(width 0.1143)
		(layer "In13.Cu")
		(net "P5E_CPU1_P0_RX_DP<3>")
	)
	(segment
		(start 100.113592 -289.981386)
		(end 100.144072 -289.963606)
		(width 0.1143)
		(layer "In13.Cu")
		(net "P5E_CPU1_P0_RX_DP<3>")
	)
	(segment
		(start 105.34396 -363.951266)
		(end 106.747564 -362.547662)
		(width 0.14224)
		(layer "In13.Cu")
		(net "P5E_CPU1_P0_RX_DP<3>")
	)
	(segment
		(start 100.144072 -282.50896)
		(end 100.113592 -282.49118)
		(width 0.1143)
		(layer "In13.Cu")
		(net "P5E_CPU1_P0_RX_DP<3>")
	)
	(segment
		(start 100.606352 -272.958306)
		(end 100.607622 -272.957544)
		(width 0.1143)
		(layer "In13.Cu")
		(net "P5E_CPU1_P0_RX_DP<3>")
	)
	(segment
		(start 100.144072 -293.84879)
		(end 100.113592 -293.83101)
		(width 0.1143)
		(layer "In13.Cu")
		(net "P5E_CPU1_P0_RX_DP<3>")
	)
	(segment
		(start 100.613464 -272.954242)
		(end 100.614226 -272.953734)
		(width 0.1143)
		(layer "In13.Cu")
		(net "P5E_CPU1_P0_RX_DP<3>")
	)
	(segment
		(start 100.113592 -278.641556)
		(end 100.144072 -278.623776)
		(width 0.1143)
		(layer "In13.Cu")
		(net "P5E_CPU1_P0_RX_DP<3>")
	)
	(segment
		(start 100.144072 -284.128972)
		(end 100.113592 -284.111192)
		(width 0.1143)
		(layer "In13.Cu")
		(net "P5E_CPU1_P0_RX_DP<3>")
	)
	(segment
		(start 130.634232 -354.983034)
		(end 129.016506 -349.141288)
		(width 0.14224)
		(layer "In13.Cu")
		(net "P5E_CPU1_P0_RX_DP<3>")
	)
	(segment
		(start 100.144072 -288.343848)
		(end 100.183188 -288.320988)
		(width 0.1143)
		(layer "In13.Cu")
		(net "P5E_CPU1_P0_RX_DP<3>")
	)
	(segment
		(start 130.634232 -355.332284)
		(end 130.634232 -354.983034)
		(width 0.14224)
		(layer "In13.Cu")
		(net "P5E_CPU1_P0_RX_DP<3>")
	)
	(segment
		(start 125.751336 -332.908148)
		(end 124.05741 -326.14616)
		(width 0.14224)
		(layer "In13.Cu")
		(net "P5E_CPU1_P0_RX_DP<3>")
	)
	(segment
		(start 51.886358 -385.649216)
		(end 52.060602 -385.548632)
		(width 0.14224)
		(layer "In13.Cu")
		(net "P5E_CPU1_P0_RX_DP<3>")
	)
	(segment
		(start 100.113592 -283.501592)
		(end 100.144072 -283.483812)
		(width 0.1143)
		(layer "In13.Cu")
		(net "P5E_CPU1_P0_RX_DP<3>")
	)
	(segment
		(start 99.835462 -296.538396)
		(end 99.835462 -295.663112)
		(width 0.1143)
		(layer "In13.Cu")
		(net "P5E_CPU1_P0_RX_DP<3>")
	)
	(segment
		(start 100.616766 -272.95221)
		(end 100.617782 -272.951702)
		(width 0.1143)
		(layer "In13.Cu")
		(net "P5E_CPU1_P0_RX_DP<3>")
	)
	(segment
		(start 99.881182 -296.584116)
		(end 99.835462 -296.538396)
		(width 0.1143)
		(layer "In13.Cu")
		(net "P5E_CPU1_P0_RX_DP<3>")
	)
	(segment
		(start 100.144072 -277.648924)
		(end 100.113592 -277.631144)
		(width 0.1143)
		(layer "In13.Cu")
		(net "P5E_CPU1_P0_RX_DP<3>")
	)
	(segment
		(start 100.61067 -272.955766)
		(end 100.613464 -272.954242)
		(width 0.1143)
		(layer "In13.Cu")
		(net "P5E_CPU1_P0_RX_DP<3>")
	)
	(segment
		(start 52.141882 -382.78181)
		(end 53.446172 -373.828564)
		(width 0.14224)
		(layer "In13.Cu")
		(net "P5E_CPU1_P0_RX_DP<3>")
	)
	(segment
		(start 101.053646 -272.161508)
		(end 101.084126 -272.143728)
		(width 0.1143)
		(layer "In13.Cu")
		(net "P5E_CPU1_P0_RX_DP<3>")
	)
	(segment
		(start 100.144072 -276.028912)
		(end 100.113592 -276.011132)
		(width 0.1143)
		(layer "In13.Cu")
		(net "P5E_CPU1_P0_RX_DP<3>")
	)
	(segment
		(start 100.113592 -291.601398)
		(end 100.144072 -291.583618)
		(width 0.1143)
		(layer "In13.Cu")
		(net "P5E_CPU1_P0_RX_DP<3>")
	)
	(segment
		(start 106.837734 -362.510324)
		(end 121.656856 -362.510324)
		(width 0.14224)
		(layer "In13.Cu")
		(net "P5E_CPU1_P0_RX_DP<3>")
	)
	(segment
		(start 100.12807 -294.832786)
		(end 100.183188 -294.800782)
		(width 0.1143)
		(layer "In13.Cu")
		(net "P5E_CPU1_P0_RX_DP<3>")
	)
	(segment
		(start 100.144072 -283.483812)
		(end 100.183188 -283.460952)
		(width 0.1143)
		(layer "In13.Cu")
		(net "P5E_CPU1_P0_RX_DP<3>")
	)
	(segment
		(start 58.404252 -366.859058)
		(end 63.886588 -364.121446)
		(width 0.14224)
		(layer "In13.Cu")
		(net "P5E_CPU1_P0_RX_DP<3>")
	)
	(segment
		(start 100.183188 -279.291796)
		(end 100.144072 -279.268936)
		(width 0.1143)
		(layer "In13.Cu")
		(net "P5E_CPU1_P0_RX_DP<3>")
	)
	(segment
		(start 110.9091 -360.376724)
		(end 111.05134 -360.234484)
		(width 0.14224)
		(layer "In13.Cu")
		(net "P5E_CPU1_P0_RX_DP<3>")
	)
	(segment
		(start 100.623624 -272.948146)
		(end 100.653342 -272.930874)
		(width 0.1143)
		(layer "In13.Cu")
		(net "P5E_CPU1_P0_RX_DP<3>")
	)
	(segment
		(start 100.11156 -286.742632)
		(end 100.144072 -286.723836)
		(width 0.1143)
		(layer "In13.Cu")
		(net "P5E_CPU1_P0_RX_DP<3>")
	)
	(segment
		(start 121.056146 -320.47815)
		(end 111.417862 -307.482748)
		(width 0.14224)
		(layer "In13.Cu")
		(net "P5E_CPU1_P0_RX_DP<3>")
	)
	(segment
		(start 51.832764 -384.731006)
		(end 51.835812 -384.3528)
		(width 0.14224)
		(layer "In13.Cu")
		(net "P5E_CPU1_P0_RX_DP<3>")
	)
	(segment
		(start 100.144072 -273.76374)
		(end 100.183188 -273.74088)
		(width 0.1143)
		(layer "In13.Cu")
		(net "P5E_CPU1_P0_RX_DP<3>")
	)
	(segment
		(start 111.05134 -361.090464)
		(end 110.9091 -360.948224)
		(width 0.14224)
		(layer "In13.Cu")
		(net "P5E_CPU1_P0_RX_DP<3>")
	)
	(segment
		(start 101.443282 -271.656302)
		(end 101.74097 -271.656302)
		(width 0.1143)
		(layer "In13.Cu")
		(net "P5E_CPU1_P0_RX_DP<3>")
	)
	(segment
		(start 100.144072 -277.003764)
		(end 100.183188 -276.980904)
		(width 0.1143)
		(layer "In13.Cu")
		(net "P5E_CPU1_P0_RX_DP<3>")
	)
	(segment
		(start 100.144072 -288.988754)
		(end 100.113592 -288.970974)
		(width 0.1143)
		(layer "In13.Cu")
		(net "P5E_CPU1_P0_RX_DP<3>")
	)
	(segment
		(start 52.060602 -385.548632)
		(end 52.14874 -385.460494)
		(width 0.14224)
		(layer "In13.Cu")
		(net "P5E_CPU1_P0_RX_DP<3>")
	)
	(segment
		(start 100.144072 -289.963606)
		(end 100.183188 -289.940746)
		(width 0.1143)
		(layer "In13.Cu")
		(net "P5E_CPU1_P0_RX_DP<3>")
	)
	(segment
		(start 100.183188 -277.671784)
		(end 100.144072 -277.648924)
		(width 0.1143)
		(layer "In13.Cu")
		(net "P5E_CPU1_P0_RX_DP<3>")
	)
	(segment
		(start 100.144072 -290.608766)
		(end 100.113592 -290.590986)
		(width 0.1143)
		(layer "In13.Cu")
		(net "P5E_CPU1_P0_RX_DP<3>")
	)
	(segment
		(start 126.913386 -358.7877)
		(end 127.348234 -358.7877)
		(width 0.14224)
		(layer "In13.Cu")
		(net "P5E_CPU1_P0_RX_DP<3>")
	)
	(segment
		(start 100.614226 -272.953734)
		(end 100.615242 -272.953226)
		(width 0.1143)
		(layer "In13.Cu")
		(net "P5E_CPU1_P0_RX_DP<3>")
	)
	(segment
		(start 124.05741 -326.14616)
		(end 123.486672 -324.767956)
		(width 0.14224)
		(layer "In13.Cu")
		(net "P5E_CPU1_P0_RX_DP<3>")
	)
	(segment
		(start 100.183188 -274.43176)
		(end 100.144072 -274.4089)
		(width 0.1143)
		(layer "In13.Cu")
		(net "P5E_CPU1_P0_RX_DP<3>")
	)
	(segment
		(start 100.113592 -280.261568)
		(end 100.144072 -280.243788)
		(width 0.1143)
		(layer "In13.Cu")
		(net "P5E_CPU1_P0_RX_DP<3>")
	)
	(segment
		(start 99.845114 -295.614344)
		(end 99.902264 -295.476422)
		(width 0.1143)
		(layer "In13.Cu")
		(net "P5E_CPU1_P0_RX_DP<3>")
	)
	(segment
		(start 123.486672 -324.767956)
		(end 121.056146 -320.47815)
		(width 0.14224)
		(layer "In13.Cu")
		(net "P5E_CPU1_P0_RX_DP<3>")
	)
	(segment
		(start 129.077212 -355.050598)
		(end 126.344172 -357.783638)
		(width 0.14224)
		(layer "In13.Cu")
		(net "P5E_CPU1_P0_RX_DP<3>")
	)
	(segment
		(start 110.481872 -306.60721)
		(end 105.59923 -303.997614)
		(width 0.14224)
		(layer "In13.Cu")
		(net "P5E_CPU1_P0_RX_DP<3>")
	)
	(segment
		(start 52.14874 -385.046982)
		(end 51.832764 -384.731006)
		(width 0.14224)
		(layer "In13.Cu")
		(net "P5E_CPU1_P0_RX_DP<3>")
	)
	(segment
		(start 100.183188 -289.011614)
		(end 100.144072 -288.988754)
		(width 0.1143)
		(layer "In13.Cu")
		(net "P5E_CPU1_P0_RX_DP<3>")
	)
	(segment
		(start 105.24617 -303.735994)
		(end 100.028248 -298.518072)
		(width 0.14224)
		(layer "In13.Cu")
		(net "P5E_CPU1_P0_RX_DP<3>")
	)
	(segment
		(start 100.144072 -278.623776)
		(end 100.183188 -278.600916)
		(width 0.1143)
		(layer "In13.Cu")
		(net "P5E_CPU1_P0_RX_DP<3>")
	)
	(segment
		(start 100.615242 -272.953226)
		(end 100.616766 -272.95221)
		(width 0.1143)
		(layer "In13.Cu")
		(net "P5E_CPU1_P0_RX_DP<3>")
	)
	(segment
		(start 100.582476 -272.972022)
		(end 100.604066 -272.959576)
		(width 0.1143)
		(layer "In13.Cu")
		(net "P5E_CPU1_P0_RX_DP<3>")
	)
	(segment
		(start 100.617782 -272.951702)
		(end 100.6221 -272.949162)
		(width 0.1143)
		(layer "In13.Cu")
		(net "P5E_CPU1_P0_RX_DP<3>")
	)
	(segment
		(start 51.835812 -384.3528)
		(end 52.140612 -384.048254)
		(width 0.14224)
		(layer "In13.Cu")
		(net "P5E_CPU1_P0_RX_DP<3>")
	)
	(segment
		(start 126.344172 -357.783638)
		(end 126.344172 -358.218486)
		(width 0.14224)
		(layer "In13.Cu")
		(net "P5E_CPU1_P0_RX_DP<3>")
	)
	(segment
		(start 101.360478 -271.739106)
		(end 101.443282 -271.656302)
		(width 0.1143)
		(layer "In13.Cu")
		(net "P5E_CPU1_P0_RX_DP<3>")
	)
	(segment
		(start 100.607622 -272.957544)
		(end 100.608384 -272.957036)
		(width 0.1143)
		(layer "In13.Cu")
		(net "P5E_CPU1_P0_RX_DP<3>")
	)
	(segment
		(start 100.113592 -273.78152)
		(end 100.144072 -273.76374)
		(width 0.1143)
		(layer "In13.Cu")
		(net "P5E_CPU1_P0_RX_DP<3>")
	)
	(segment
		(start 100.183188 -290.631626)
		(end 100.144072 -290.608766)
		(width 0.1143)
		(layer "In13.Cu")
		(net "P5E_CPU1_P0_RX_DP<3>")
	)
	(segment
		(start 100.183188 -282.53182)
		(end 100.144072 -282.50896)
		(width 0.1143)
		(layer "In13.Cu")
		(net "P5E_CPU1_P0_RX_DP<3>")
	)
	(segment
		(start 121.656856 -361.090464)
		(end 111.05134 -361.090464)
		(width 0.14224)
		(layer "In13.Cu")
		(net "P5E_CPU1_P0_RX_DP<3>")
	)
	(segment
		(start 100.113592 -281.88158)
		(end 100.144072 -281.8638)
		(width 0.1143)
		(layer "In13.Cu")
		(net "P5E_CPU1_P0_RX_DP<3>")
	)
	(segment
		(start 100.6221 -272.949162)
		(end 100.623624 -272.948146)
		(width 0.1143)
		(layer "In13.Cu")
		(net "P5E_CPU1_P0_RX_DP<3>")
	)
	(segment
		(start 52.14874 -385.460494)
		(end 52.14874 -385.046982)
		(width 0.14224)
		(layer "In13.Cu")
		(net "P5E_CPU1_P0_RX_DP<3>")
	)
	(segment
		(start 128.67259 -354.444808)
		(end 129.077212 -354.84943)
		(width 0.14224)
		(layer "In13.Cu")
		(net "P5E_CPU1_P0_RX_DP<3>")
	)
	(segment
		(start 100.144072 -274.4089)
		(end 100.113592 -274.39112)
		(width 0.1143)
		(layer "In13.Cu")
		(net "P5E_CPU1_P0_RX_DP<3>")
	)
	(segment
		(start 99.881182 -298.16298)
		(end 99.881182 -296.612564)
		(width 0.14224)
		(layer "In13.Cu")
		(net "P5E_CPU1_P0_RX_DP<3>")
	)
	(segment
		(start 100.144072 -279.268936)
		(end 100.113592 -279.251156)
		(width 0.1143)
		(layer "In13.Cu")
		(net "P5E_CPU1_P0_RX_DP<3>")
	)
	(segment
		(start 100.183188 -285.771844)
		(end 100.113592 -285.731204)
		(width 0.1143)
		(layer "In13.Cu")
		(net "P5E_CPU1_P0_RX_DP<3>")
	)
	(segment
		(start 100.144072 -280.243788)
		(end 100.183188 -280.220928)
		(width 0.1143)
		(layer "In13.Cu")
		(net "P5E_CPU1_P0_RX_DP<3>")
	)
	(segment
		(start 100.183188 -293.87165)
		(end 100.144072 -293.84879)
		(width 0.1143)
		(layer "In13.Cu")
		(net "P5E_CPU1_P0_RX_DP<3>")
	)
	(segment
		(start 100.144072 -275.383752)
		(end 100.183188 -275.360892)
		(width 0.1143)
		(layer "In13.Cu")
		(net "P5E_CPU1_P0_RX_DP<3>")
	)
	(segment
		(start 111.417862 -307.482748)
		(end 111.370618 -307.412136)
		(width 0.14224)
		(layer "In13.Cu")
		(net "P5E_CPU1_P0_RX_DP<3>")
	)
	(segment
		(start 110.9091 -360.948224)
		(end 110.9091 -360.376724)
		(width 0.14224)
		(layer "In13.Cu")
		(net "P5E_CPU1_P0_RX_DP<3>")
	)
	(segment
		(start 100.144072 -280.888948)
		(end 100.113592 -280.871168)
		(width 0.1143)
		(layer "In13.Cu")
		(net "P5E_CPU1_P0_RX_DP<3>")
	)
	(segment
		(start 100.113592 -277.021544)
		(end 100.144072 -277.003764)
		(width 0.1143)
		(layer "In13.Cu")
		(net "P5E_CPU1_P0_RX_DP<3>")
	)
	(segment
		(start 99.881182 -296.612564)
		(end 99.881182 -296.584116)
		(width 0.1143)
		(layer "In13.Cu")
		(net "P5E_CPU1_P0_RX_DP<3>")
	)
	(segment
		(start 121.964196 -361.397804)
		(end 121.656856 -361.090464)
		(width 0.14224)
		(layer "In13.Cu")
		(net "P5E_CPU1_P0_RX_DP<3>")
	)
	(segment
		(start 100.180648 -287.390078)
		(end 100.113592 -287.350962)
		(width 0.1143)
		(layer "In13.Cu")
		(net "P5E_CPU1_P0_RX_DP<3>")
	)
	(segment
		(start 100.144072 -293.20363)
		(end 100.183188 -293.18077)
		(width 0.1143)
		(layer "In13.Cu")
		(net "P5E_CPU1_P0_RX_DP<3>")
	)
	(segment
		(start 100.144072 -286.723836)
		(end 100.183188 -286.700976)
		(width 0.1143)
		(layer "In13.Cu")
		(net "P5E_CPU1_P0_RX_DP<3>")
	)
	(segment
		(start 53.469032 -373.765064)
		(end 56.564784 -368.720116)
		(width 0.14224)
		(layer "In13.Cu")
		(net "P5E_CPU1_P0_RX_DP<3>")
	)
	(segment
		(start 63.94323 -364.10773)
		(end 104.966262 -364.10773)
		(width 0.14224)
		(layer "In13.Cu")
		(net "P5E_CPU1_P0_RX_DP<3>")
	)
	(segment
		(start 100.608384 -272.957036)
		(end 100.609908 -272.956274)
		(width 0.1143)
		(layer "In13.Cu")
		(net "P5E_CPU1_P0_RX_DP<3>")
	)
	(segment
		(start 100.144072 -291.583618)
		(end 100.183188 -291.560758)
		(width 0.1143)
		(layer "In13.Cu")
		(net "P5E_CPU1_P0_RX_DP<3>")
	)
	(segment
		(start 121.964196 -362.202984)
		(end 121.964196 -361.397804)
		(width 0.14224)
		(layer "In13.Cu")
		(net "P5E_CPU1_P0_RX_DP<3>")
	)
	(segment
		(start 126.344172 -358.218486)
		(end 126.913386 -358.7877)
		(width 0.14224)
		(layer "In13.Cu")
		(net "P5E_CPU1_P0_RX_DP<3>")
	)
	(segment
		(start 100.183188 -284.151832)
		(end 100.144072 -284.128972)
		(width 0.1143)
		(layer "In13.Cu")
		(net "P5E_CPU1_P0_RX_DP<3>")
	)
	(segment
		(start 100.113592 -285.121604)
		(end 100.144072 -285.103824)
		(width 0.1143)
		(layer "In13.Cu")
		(net "P5E_CPU1_P0_RX_DP<3>")
	)
	(segment
		(start 100.604828 -272.959068)
		(end 100.606352 -272.958306)
		(width 0.1143)
		(layer "In13.Cu")
		(net "P5E_CPU1_P0_RX_DP<3>")
	)
	(arc
		(start 105.59923 -303.997614)
		(mid 105.413038 -303.879841)
		(end 105.24617 -303.735994)
		(width 0.14224)
		(layer "In13.Cu")
		(net "P5E_CPU1_P0_RX_DP<3>")
	)
	(arc
		(start 99.835462 -295.663112)
		(mid 99.837864 -295.638246)
		(end 99.845114 -295.614344)
		(width 0.1143)
		(layer "In13.Cu")
		(net "P5E_CPU1_P0_RX_DP<3>")
	)
	(arc
		(start 100.183188 -276.980904)
		(mid 100.426515 -276.516338)
		(end 100.183188 -276.051772)
		(width 0.1143)
		(layer "In13.Cu")
		(net "P5E_CPU1_P0_RX_DP<3>")
	)
	(arc
		(start 130.514344 -355.62159)
		(mid 130.603088 -355.48887)
		(end 130.634232 -355.332284)
		(width 0.14224)
		(layer "In13.Cu")
		(net "P5E_CPU1_P0_RX_DP<3>")
	)
	(arc
		(start 100.113592 -292.210998)
		(mid 99.956615 -291.906198)
		(end 100.113592 -291.601398)
		(width 0.1143)
		(layer "In13.Cu")
		(net "P5E_CPU1_P0_RX_DP<3>")
	)
	(arc
		(start 100.113592 -290.590986)
		(mid 99.956615 -290.286186)
		(end 100.113592 -289.981386)
		(width 0.1143)
		(layer "In13.Cu")
		(net "P5E_CPU1_P0_RX_DP<3>")
	)
	(arc
		(start 63.886588 -364.121446)
		(mid 63.914109 -364.111277)
		(end 63.94323 -364.10773)
		(width 0.14224)
		(layer "In13.Cu")
		(net "P5E_CPU1_P0_RX_DP<3>")
	)
	(arc
		(start 100.42652 -281.376374)
		(mid 100.362005 -281.114155)
		(end 100.183188 -280.911808)
		(width 0.1143)
		(layer "In13.Cu")
		(net "P5E_CPU1_P0_RX_DP<3>")
	)
	(arc
		(start 99.95662 -288.666174)
		(mid 99.997586 -288.495768)
		(end 100.11156 -288.362644)
		(width 0.1143)
		(layer "In13.Cu")
		(net "P5E_CPU1_P0_RX_DP<3>")
	)
	(arc
		(start 101.123242 -272.120868)
		(mid 101.275229 -271.96436)
		(end 101.356668 -271.761966)
		(width 0.1143)
		(layer "In13.Cu")
		(net "P5E_CPU1_P0_RX_DP<3>")
	)
	(arc
		(start 100.113592 -287.350962)
		(mid 99.998165 -287.217586)
		(end 99.95662 -287.046162)
		(width 0.1143)
		(layer "In13.Cu")
		(net "P5E_CPU1_P0_RX_DP<3>")
	)
	(arc
		(start 56.564784 -368.720116)
		(mid 56.836632 -368.330473)
		(end 57.152286 -367.975388)
		(width 0.14224)
		(layer "In13.Cu")
		(net "P5E_CPU1_P0_RX_DP<3>")
	)
	(arc
		(start 100.183188 -291.560758)
		(mid 100.426515 -291.096192)
		(end 100.183188 -290.631626)
		(width 0.1143)
		(layer "In13.Cu")
		(net "P5E_CPU1_P0_RX_DP<3>")
	)
	(arc
		(start 100.113592 -277.631144)
		(mid 99.956615 -277.326344)
		(end 100.113592 -277.021544)
		(width 0.1143)
		(layer "In13.Cu")
		(net "P5E_CPU1_P0_RX_DP<3>")
	)
	(arc
		(start 100.113592 -280.871168)
		(mid 99.956615 -280.566368)
		(end 100.113592 -280.261568)
		(width 0.1143)
		(layer "In13.Cu")
		(net "P5E_CPU1_P0_RX_DP<3>")
	)
	(arc
		(start 100.183188 -280.220928)
		(mid 100.426515 -279.756362)
		(end 100.183188 -279.291796)
		(width 0.1143)
		(layer "In13.Cu")
		(net "P5E_CPU1_P0_RX_DP<3>")
	)
	(arc
		(start 104.966262 -364.10773)
		(mid 105.170677 -364.067069)
		(end 105.34396 -363.951266)
		(width 0.14224)
		(layer "In13.Cu")
		(net "P5E_CPU1_P0_RX_DP<3>")
	)
	(arc
		(start 100.183188 -285.080964)
		(mid 100.426515 -284.616398)
		(end 100.183188 -284.151832)
		(width 0.1143)
		(layer "In13.Cu")
		(net "P5E_CPU1_P0_RX_DP<3>")
	)
	(arc
		(start 100.183188 -294.800782)
		(mid 100.426515 -294.336216)
		(end 100.183188 -293.87165)
		(width 0.1143)
		(layer "In13.Cu")
		(net "P5E_CPU1_P0_RX_DP<3>")
	)
	(arc
		(start 100.42652 -273.276314)
		(mid 100.467775 -273.105343)
		(end 100.582476 -272.972022)
		(width 0.1143)
		(layer "In13.Cu")
		(net "P5E_CPU1_P0_RX_DP<3>")
	)
	(arc
		(start 122.46229 -360.234484)
		(mid 122.665053 -360.194152)
		(end 122.83694 -360.07929)
		(width 0.14224)
		(layer "In13.Cu")
		(net "P5E_CPU1_P0_RX_DP<3>")
	)
	(arc
		(start 99.95662 -287.046162)
		(mid 99.997586 -286.875756)
		(end 100.11156 -286.742632)
		(width 0.1143)
		(layer "In13.Cu")
		(net "P5E_CPU1_P0_RX_DP<3>")
	)
	(arc
		(start 100.113592 -276.011132)
		(mid 99.956615 -275.706332)
		(end 100.113592 -275.401532)
		(width 0.1143)
		(layer "In13.Cu")
		(net "P5E_CPU1_P0_RX_DP<3>")
	)
	(arc
		(start 101.356668 -271.761966)
		(mid 101.358691 -271.750556)
		(end 101.360478 -271.739106)
		(width 0.1143)
		(layer "In13.Cu")
		(net "P5E_CPU1_P0_RX_DP<3>")
	)
	(arc
		(start 100.183188 -286.700976)
		(mid 100.426515 -286.23641)
		(end 100.183188 -285.771844)
		(width 0.1143)
		(layer "In13.Cu")
		(net "P5E_CPU1_P0_RX_DP<3>")
	)
	(arc
		(start 100.113592 -284.111192)
		(mid 99.956615 -283.806392)
		(end 100.113592 -283.501592)
		(width 0.1143)
		(layer "In13.Cu")
		(net "P5E_CPU1_P0_RX_DP<3>")
	)
	(arc
		(start 100.183188 -293.18077)
		(mid 100.426515 -292.716204)
		(end 100.183188 -292.251638)
		(width 0.1143)
		(layer "In13.Cu")
		(net "P5E_CPU1_P0_RX_DP<3>")
	)
	(arc
		(start 100.113592 -282.49118)
		(mid 99.956615 -282.18638)
		(end 100.113592 -281.88158)
		(width 0.1143)
		(layer "In13.Cu")
		(net "P5E_CPU1_P0_RX_DP<3>")
	)
	(arc
		(start 100.113592 -274.39112)
		(mid 99.956615 -274.08632)
		(end 100.113592 -273.78152)
		(width 0.1143)
		(layer "In13.Cu")
		(net "P5E_CPU1_P0_RX_DP<3>")
	)
	(arc
		(start 99.902264 -295.476422)
		(mid 99.933026 -295.374942)
		(end 99.943412 -295.269412)
		(width 0.1143)
		(layer "In13.Cu")
		(net "P5E_CPU1_P0_RX_DP<3>")
	)
	(arc
		(start 100.113592 -285.731204)
		(mid 99.956615 -285.426404)
		(end 100.113592 -285.121604)
		(width 0.1143)
		(layer "In13.Cu")
		(net "P5E_CPU1_P0_RX_DP<3>")
	)
	(arc
		(start 100.183188 -281.84094)
		(mid 100.362001 -281.63859)
		(end 100.42652 -281.376374)
		(width 0.1143)
		(layer "In13.Cu")
		(net "P5E_CPU1_P0_RX_DP<3>")
	)
	(arc
		(start 100.183188 -273.74088)
		(mid 100.362001 -273.53853)
		(end 100.42652 -273.276314)
		(width 0.1143)
		(layer "In13.Cu")
		(net "P5E_CPU1_P0_RX_DP<3>")
	)
	(arc
		(start 106.747564 -362.547662)
		(mid 106.788934 -362.520019)
		(end 106.837734 -362.510324)
		(width 0.14224)
		(layer "In13.Cu")
		(net "P5E_CPU1_P0_RX_DP<3>")
	)
	(arc
		(start 100.183188 -275.360892)
		(mid 100.426515 -274.896326)
		(end 100.183188 -274.43176)
		(width 0.1143)
		(layer "In13.Cu")
		(net "P5E_CPU1_P0_RX_DP<3>")
	)
	(arc
		(start 100.028248 -298.518072)
		(mid 99.91939 -298.355154)
		(end 99.881182 -298.16298)
		(width 0.14224)
		(layer "In13.Cu")
		(net "P5E_CPU1_P0_RX_DP<3>")
	)
	(arc
		(start 100.653342 -272.930874)
		(mid 100.832155 -272.728524)
		(end 100.896674 -272.466308)
		(width 0.1143)
		(layer "In13.Cu")
		(net "P5E_CPU1_P0_RX_DP<3>")
	)
	(arc
		(start 100.113592 -279.251156)
		(mid 99.956615 -278.946356)
		(end 100.113592 -278.641556)
		(width 0.1143)
		(layer "In13.Cu")
		(net "P5E_CPU1_P0_RX_DP<3>")
	)
	(arc
		(start 100.183188 -283.460952)
		(mid 100.426515 -282.996386)
		(end 100.183188 -282.53182)
		(width 0.1143)
		(layer "In13.Cu")
		(net "P5E_CPU1_P0_RX_DP<3>")
	)
	(arc
		(start 53.446172 -373.828564)
		(mid 53.454366 -373.795648)
		(end 53.469032 -373.765064)
		(width 0.14224)
		(layer "In13.Cu")
		(net "P5E_CPU1_P0_RX_DP<3>")
	)
	(arc
		(start 100.113592 -293.83101)
		(mid 99.956615 -293.52621)
		(end 100.113592 -293.22141)
		(width 0.1143)
		(layer "In13.Cu")
		(net "P5E_CPU1_P0_RX_DP<3>")
	)
	(arc
		(start 100.42652 -287.856422)
		(mid 100.361284 -287.592831)
		(end 100.180648 -287.390078)
		(width 0.1143)
		(layer "In13.Cu")
		(net "P5E_CPU1_P0_RX_DP<3>")
	)
	(arc
		(start 100.896674 -272.466308)
		(mid 100.938223 -272.294886)
		(end 101.053646 -272.161508)
		(width 0.1143)
		(layer "In13.Cu")
		(net "P5E_CPU1_P0_RX_DP<3>")
	)
	(arc
		(start 100.183188 -278.600916)
		(mid 100.426515 -278.13635)
		(end 100.183188 -277.671784)
		(width 0.1143)
		(layer "In13.Cu")
		(net "P5E_CPU1_P0_RX_DP<3>")
	)
	(arc
		(start 100.113592 -288.970974)
		(mid 99.998165 -288.837598)
		(end 99.95662 -288.666174)
		(width 0.1143)
		(layer "In13.Cu")
		(net "P5E_CPU1_P0_RX_DP<3>")
	)
	(arc
		(start 100.183188 -288.320988)
		(mid 100.362001 -288.118638)
		(end 100.42652 -287.856422)
		(width 0.1143)
		(layer "In13.Cu")
		(net "P5E_CPU1_P0_RX_DP<3>")
	)
	(arc
		(start 99.943412 -295.125902)
		(mid 99.9634 -295.025507)
		(end 100.020374 -294.940482)
		(width 0.1143)
		(layer "In13.Cu")
		(net "P5E_CPU1_P0_RX_DP<3>")
	)
	(arc
		(start 57.919112 -367.208562)
		(mid 58.147553 -367.014195)
		(end 58.404252 -366.859058)
		(width 0.14224)
		(layer "In13.Cu")
		(net "P5E_CPU1_P0_RX_DP<3>")
	)
	(arc
		(start 111.370618 -307.412136)
		(mid 110.975732 -306.955035)
		(end 110.481872 -306.60721)
		(width 0.14224)
		(layer "In13.Cu")
		(net "P5E_CPU1_P0_RX_DP<3>")
	)
	(arc
		(start 52.140612 -382.800352)
		(mid 52.140912 -382.791058)
		(end 52.141882 -382.78181)
		(width 0.14224)
		(layer "In13.Cu")
		(net "P5E_CPU1_P0_RX_DP<3>")
	)
	(arc
		(start 100.183188 -289.940746)
		(mid 100.426515 -289.47618)
		(end 100.183188 -289.011614)
		(width 0.1143)
		(layer "In13.Cu")
		(net "P5E_CPU1_P0_RX_DP<3>")
	)
	(segment
		(start 50.070512 -386.003292)
		(end 50.591212 -386.003292)
		(width 0.127)
		(layer "F.Cu")
		(net "P5E_CPU1_P0_RX_DP<2>")
	)
	(segment
		(start 99.387914 -269.770352)
		(end 98.921062 -270.03629)
		(width 0.12954)
		(layer "F.Cu")
		(net "P5E_CPU1_P0_RX_DP<2>")
	)
	(segment
		(start 99.172268 -273.782028)
		(end 99.203256 -273.764248)
		(width 0.1143)
		(layer "In13.Cu")
		(net "P5E_CPU1_P0_RX_DP<2>")
	)
	(segment
		(start 127.61595 -351.436178)
		(end 123.936506 -355.115622)
		(width 0.14224)
		(layer "In13.Cu")
		(net "P5E_CPU1_P0_RX_DP<2>")
	)
	(segment
		(start 99.243134 -282.53182)
		(end 99.236276 -282.527756)
		(width 0.1143)
		(layer "In13.Cu")
		(net "P5E_CPU1_P0_RX_DP<2>")
	)
	(segment
		(start 99.214432 -294.8178)
		(end 99.215702 -294.817038)
		(width 0.1143)
		(layer "In13.Cu")
		(net "P5E_CPU1_P0_RX_DP<2>")
	)
	(segment
		(start 99.206812 -275.382228)
		(end 99.207828 -275.38172)
		(width 0.1143)
		(layer "In13.Cu")
		(net "P5E_CPU1_P0_RX_DP<2>")
	)
	(segment
		(start 99.2251 -291.571426)
		(end 99.243134 -291.560758)
		(width 0.1143)
		(layer "In13.Cu")
		(net "P5E_CPU1_P0_RX_DP<2>")
	)
	(segment
		(start 124.421646 -331.718666)
		(end 123.167902 -326.5805)
		(width 0.14224)
		(layer "In13.Cu")
		(net "P5E_CPU1_P0_RX_DP<2>")
	)
	(segment
		(start 99.152456 -275.416264)
		(end 99.172268 -275.40204)
		(width 0.1143)
		(layer "In13.Cu")
		(net "P5E_CPU1_P0_RX_DP<2>")
	)
	(segment
		(start 98.542348 -296.324782)
		(end 98.542348 -296.072814)
		(width 0.1143)
		(layer "In13.Cu")
		(net "P5E_CPU1_P0_RX_DP<2>")
	)
	(segment
		(start 99.215702 -294.817038)
		(end 99.243134 -294.800782)
		(width 0.1143)
		(layer "In13.Cu")
		(net "P5E_CPU1_P0_RX_DP<2>")
	)
	(segment
		(start 99.208336 -279.271476)
		(end 99.206812 -279.27046)
		(width 0.1143)
		(layer "In13.Cu")
		(net "P5E_CPU1_P0_RX_DP<2>")
	)
	(segment
		(start 123.331224 -354.711508)
		(end 123.331224 -354.51034)
		(width 0.14224)
		(layer "In13.Cu")
		(net "P5E_CPU1_P0_RX_DP<2>")
	)
	(segment
		(start 104.746044 -304.914808)
		(end 98.88093 -299.049694)
		(width 0.14224)
		(layer "In13.Cu")
		(net "P5E_CPU1_P0_RX_DP<2>")
	)
	(segment
		(start 99.203764 -288.988754)
		(end 99.198176 -288.985706)
		(width 0.1143)
		(layer "In13.Cu")
		(net "P5E_CPU1_P0_RX_DP<2>")
	)
	(segment
		(start 99.191064 -288.35096)
		(end 99.204526 -288.34334)
		(width 0.1143)
		(layer "In13.Cu")
		(net "P5E_CPU1_P0_RX_DP<2>")
	)
	(segment
		(start 99.204018 -277.003764)
		(end 99.205034 -277.003256)
		(width 0.1143)
		(layer "In13.Cu")
		(net "P5E_CPU1_P0_RX_DP<2>")
	)
	(segment
		(start 99.212654 -293.85387)
		(end 99.210368 -293.852346)
		(width 0.1143)
		(layer "In13.Cu")
		(net "P5E_CPU1_P0_RX_DP<2>")
	)
	(segment
		(start 99.210876 -284.133036)
		(end 99.209352 -284.13202)
		(width 0.1143)
		(layer "In13.Cu")
		(net "P5E_CPU1_P0_RX_DP<2>")
	)
	(segment
		(start 99.243134 -277.671784)
		(end 99.236276 -277.66772)
		(width 0.1143)
		(layer "In13.Cu")
		(net "P5E_CPU1_P0_RX_DP<2>")
	)
	(segment
		(start 123.735338 -355.115622)
		(end 123.331224 -354.711508)
		(width 0.14224)
		(layer "In13.Cu")
		(net "P5E_CPU1_P0_RX_DP<2>")
	)
	(segment
		(start 123.167902 -326.5805)
		(end 121.332498 -322.989702)
		(width 0.14224)
		(layer "In13.Cu")
		(net "P5E_CPU1_P0_RX_DP<2>")
	)
	(segment
		(start 99.205034 -283.483304)
		(end 99.243134 -283.460952)
		(width 0.1143)
		(layer "In13.Cu")
		(net "P5E_CPU1_P0_RX_DP<2>")
	)
	(segment
		(start 99.204018 -279.268936)
		(end 99.203256 -279.268428)
		(width 0.1143)
		(layer "In13.Cu")
		(net "P5E_CPU1_P0_RX_DP<2>")
	)
	(segment
		(start 98.592132 -296.422318)
		(end 98.592132 -296.365422)
		(width 0.1143)
		(layer "In13.Cu")
		(net "P5E_CPU1_P0_RX_DP<2>")
	)
	(segment
		(start 99.243134 -274.43176)
		(end 99.236276 -274.427696)
		(width 0.1143)
		(layer "In13.Cu")
		(net "P5E_CPU1_P0_RX_DP<2>")
	)
	(segment
		(start 110.831122 -357.000048)
		(end 123.891802 -357.000048)
		(width 0.14224)
		(layer "In13.Cu")
		(net "P5E_CPU1_P0_RX_DP<2>")
	)
	(segment
		(start 99.203256 -272.144236)
		(end 99.204018 -272.143728)
		(width 0.1143)
		(layer "In13.Cu")
		(net "P5E_CPU1_P0_RX_DP<2>")
	)
	(segment
		(start 99.172268 -282.490672)
		(end 99.152456 -282.476448)
		(width 0.1143)
		(layer "In13.Cu")
		(net "P5E_CPU1_P0_RX_DP<2>")
	)
	(segment
		(start 99.205034 -280.889456)
		(end 99.204018 -280.888948)
		(width 0.1143)
		(layer "In13.Cu")
		(net "P5E_CPU1_P0_RX_DP<2>")
	)
	(segment
		(start 99.205034 -277.003256)
		(end 99.209606 -277.000462)
		(width 0.1143)
		(layer "In13.Cu")
		(net "P5E_CPU1_P0_RX_DP<2>")
	)
	(segment
		(start 99.235514 -282.527248)
		(end 99.210876 -282.513024)
		(width 0.1143)
		(layer "In13.Cu")
		(net "P5E_CPU1_P0_RX_DP<2>")
	)
	(segment
		(start 121.253504 -358.968548)
		(end 121.253504 -358.163368)
		(width 0.14224)
		(layer "In13.Cu")
		(net "P5E_CPU1_P0_RX_DP<2>")
	)
	(segment
		(start 99.205034 -278.623268)
		(end 99.243134 -278.600916)
		(width 0.1143)
		(layer "In13.Cu")
		(net "P5E_CPU1_P0_RX_DP<2>")
	)
	(segment
		(start 99.194366 -287.362392)
		(end 99.131374 -287.2994)
		(width 0.1143)
		(layer "In13.Cu")
		(net "P5E_CPU1_P0_RX_DP<2>")
	)
	(segment
		(start 99.20732 -293.850568)
		(end 99.205288 -293.849298)
		(width 0.1143)
		(layer "In13.Cu")
		(net "P5E_CPU1_P0_RX_DP<2>")
	)
	(segment
		(start 99.195636 -287.363154)
		(end 99.194366 -287.362392)
		(width 0.1143)
		(layer "In13.Cu")
		(net "P5E_CPU1_P0_RX_DP<2>")
	)
	(segment
		(start 99.194874 -292.22065)
		(end 99.190556 -292.22065)
		(width 0.1143)
		(layer "In13.Cu")
		(net "P5E_CPU1_P0_RX_DP<2>")
	)
	(segment
		(start 99.236276 -282.527756)
		(end 99.235514 -282.527248)
		(width 0.1143)
		(layer "In13.Cu")
		(net "P5E_CPU1_P0_RX_DP<2>")
	)
	(segment
		(start 99.236276 -276.047708)
		(end 99.235514 -276.0472)
		(width 0.1143)
		(layer "In13.Cu")
		(net "P5E_CPU1_P0_RX_DP<2>")
	)
	(segment
		(start 50.635662 -384.3528)
		(end 50.940462 -384.048254)
		(width 0.14224)
		(layer "In13.Cu")
		(net "P5E_CPU1_P0_RX_DP<2>")
	)
	(segment
		(start 99.215702 -275.377148)
		(end 99.243134 -275.360892)
		(width 0.1143)
		(layer "In13.Cu")
		(net "P5E_CPU1_P0_RX_DP<2>")
	)
	(segment
		(start 110.688882 -357.142288)
		(end 110.831122 -357.000048)
		(width 0.14224)
		(layer "In13.Cu")
		(net "P5E_CPU1_P0_RX_DP<2>")
	)
	(segment
		(start 99.205034 -277.649432)
		(end 99.204018 -277.648924)
		(width 0.1143)
		(layer "In13.Cu")
		(net "P5E_CPU1_P0_RX_DP<2>")
	)
	(segment
		(start 99.235514 -279.287224)
		(end 99.210876 -279.273)
		(width 0.1143)
		(layer "In13.Cu")
		(net "P5E_CPU1_P0_RX_DP<2>")
	)
	(segment
		(start 99.152456 -283.516324)
		(end 99.172268 -283.5021)
		(width 0.1143)
		(layer "In13.Cu")
		(net "P5E_CPU1_P0_RX_DP<2>")
	)
	(segment
		(start 99.205034 -284.12948)
		(end 99.204018 -284.128972)
		(width 0.1143)
		(layer "In13.Cu")
		(net "P5E_CPU1_P0_RX_DP<2>")
	)
	(segment
		(start 121.253504 -358.163368)
		(end 120.946164 -357.856028)
		(width 0.14224)
		(layer "In13.Cu")
		(net "P5E_CPU1_P0_RX_DP<2>")
	)
	(segment
		(start 99.210876 -285.753048)
		(end 99.209352 -285.752032)
		(width 0.1143)
		(layer "In13.Cu")
		(net "P5E_CPU1_P0_RX_DP<2>")
	)
	(segment
		(start 50.591212 -386.003292)
		(end 50.686208 -385.649216)
		(width 0.14224)
		(layer "In13.Cu")
		(net "P5E_CPU1_P0_RX_DP<2>")
	)
	(segment
		(start 99.172268 -278.642064)
		(end 99.203256 -278.624284)
		(width 0.1143)
		(layer "In13.Cu")
		(net "P5E_CPU1_P0_RX_DP<2>")
	)
	(segment
		(start 99.224084 -291.571934)
		(end 99.2251 -291.571426)
		(width 0.1143)
		(layer "In13.Cu")
		(net "P5E_CPU1_P0_RX_DP<2>")
	)
	(segment
		(start 50.94859 -385.046982)
		(end 50.632614 -384.731006)
		(width 0.14224)
		(layer "In13.Cu")
		(net "P5E_CPU1_P0_RX_DP<2>")
	)
	(segment
		(start 99.204018 -275.383752)
		(end 99.205034 -275.383244)
		(width 0.1143)
		(layer "In13.Cu")
		(net "P5E_CPU1_P0_RX_DP<2>")
	)
	(segment
		(start 125.171454 -334.791304)
		(end 124.421646 -331.71892)
		(width 0.14224)
		(layer "In13.Cu")
		(net "P5E_CPU1_P0_RX_DP<2>")
	)
	(segment
		(start 99.205034 -281.863292)
		(end 99.243134 -281.84094)
		(width 0.1143)
		(layer "In13.Cu")
		(net "P5E_CPU1_P0_RX_DP<2>")
	)
	(segment
		(start 99.238816 -287.389316)
		(end 99.197414 -287.364424)
		(width 0.1143)
		(layer "In13.Cu")
		(net "P5E_CPU1_P0_RX_DP<2>")
	)
	(segment
		(start 117.835172 -317.755778)
		(end 112.230662 -310.197246)
		(width 0.14224)
		(layer "In13.Cu")
		(net "P5E_CPU1_P0_RX_DP<2>")
	)
	(segment
		(start 99.205034 -272.789396)
		(end 99.204018 -272.788888)
		(width 0.1143)
		(layer "In13.Cu")
		(net "P5E_CPU1_P0_RX_DP<2>")
	)
	(segment
		(start 99.210876 -279.273)
		(end 99.209352 -279.271984)
		(width 0.1143)
		(layer "In13.Cu")
		(net "P5E_CPU1_P0_RX_DP<2>")
	)
	(segment
		(start 98.592132 -296.365422)
		(end 98.542348 -296.324782)
		(width 0.1143)
		(layer "In13.Cu")
		(net "P5E_CPU1_P0_RX_DP<2>")
	)
	(segment
		(start 99.212908 -275.378926)
		(end 99.214432 -275.37791)
		(width 0.1143)
		(layer "In13.Cu")
		(net "P5E_CPU1_P0_RX_DP<2>")
	)
	(segment
		(start 99.205034 -285.103316)
		(end 99.243134 -285.080964)
		(width 0.1143)
		(layer "In13.Cu")
		(net "P5E_CPU1_P0_RX_DP<2>")
	)
	(segment
		(start 99.205288 -288.98977)
		(end 99.203764 -288.988754)
		(width 0.1143)
		(layer "In13.Cu")
		(net "P5E_CPU1_P0_RX_DP<2>")
	)
	(segment
		(start 98.55327 -270.10614)
		(end 98.62312 -270.03629)
		(width 0.1143)
		(layer "In13.Cu")
		(net "P5E_CPU1_P0_RX_DP<2>")
	)
	(segment
		(start 99.203256 -278.624284)
		(end 99.204018 -278.623776)
		(width 0.1143)
		(layer "In13.Cu")
		(net "P5E_CPU1_P0_RX_DP<2>")
	)
	(segment
		(start 99.208336 -276.031452)
		(end 99.206812 -276.030436)
		(width 0.1143)
		(layer "In13.Cu")
		(net "P5E_CPU1_P0_RX_DP<2>")
	)
	(segment
		(start 57.927748 -366.051846)
		(end 63.598806 -363.219746)
		(width 0.14224)
		(layer "In13.Cu")
		(net "P5E_CPU1_P0_RX_DP<2>")
	)
	(segment
		(start 99.243134 -280.911808)
		(end 99.205034 -280.889456)
		(width 0.1143)
		(layer "In13.Cu")
		(net "P5E_CPU1_P0_RX_DP<2>")
	)
	(segment
		(start 50.940462 -384.048254)
		(end 50.940462 -382.474978)
		(width 0.14224)
		(layer "In13.Cu")
		(net "P5E_CPU1_P0_RX_DP<2>")
	)
	(segment
		(start 99.203256 -273.764248)
		(end 99.204018 -273.76374)
		(width 0.1143)
		(layer "In13.Cu")
		(net "P5E_CPU1_P0_RX_DP<2>")
	)
	(segment
		(start 99.203256 -285.104332)
		(end 99.204018 -285.103824)
		(width 0.1143)
		(layer "In13.Cu")
		(net "P5E_CPU1_P0_RX_DP<2>")
	)
	(segment
		(start 128.62052 -352.440748)
		(end 128.62052 -352.0059)
		(width 0.14224)
		(layer "In13.Cu")
		(net "P5E_CPU1_P0_RX_DP<2>")
	)
	(segment
		(start 99.196144 -288.984436)
		(end 99.191064 -288.981388)
		(width 0.1143)
		(layer "In13.Cu")
		(net "P5E_CPU1_P0_RX_DP<2>")
	)
	(segment
		(start 50.942494 -382.452626)
		(end 52.501546 -373.594122)
		(width 0.14224)
		(layer "In13.Cu")
		(net "P5E_CPU1_P0_RX_DP<2>")
	)
	(segment
		(start 99.209352 -274.411948)
		(end 99.208336 -274.41144)
		(width 0.1143)
		(layer "In13.Cu")
		(net "P5E_CPU1_P0_RX_DP<2>")
	)
	(segment
		(start 99.206812 -282.510484)
		(end 99.205034 -282.509468)
		(width 0.1143)
		(layer "In13.Cu")
		(net "P5E_CPU1_P0_RX_DP<2>")
	)
	(segment
		(start 50.94859 -385.460494)
		(end 50.94859 -385.046982)
		(width 0.14224)
		(layer "In13.Cu")
		(net "P5E_CPU1_P0_RX_DP<2>")
	)
	(segment
		(start 99.191064 -288.981388)
		(end 99.190556 -288.981134)
		(width 0.1143)
		(layer "In13.Cu")
		(net "P5E_CPU1_P0_RX_DP<2>")
	)
	(segment
		(start 99.172268 -281.882088)
		(end 99.203256 -281.864308)
		(width 0.1143)
		(layer "In13.Cu")
		(net "P5E_CPU1_P0_RX_DP<2>")
	)
	(segment
		(start 50.860452 -385.548632)
		(end 50.94859 -385.460494)
		(width 0.14224)
		(layer "In13.Cu")
		(net "P5E_CPU1_P0_RX_DP<2>")
	)
	(segment
		(start 99.242372 -285.771844)
		(end 99.235514 -285.767272)
		(width 0.1143)
		(layer "In13.Cu")
		(net "P5E_CPU1_P0_RX_DP<2>")
	)
	(segment
		(start 99.210622 -294.820086)
		(end 99.212908 -294.818816)
		(width 0.1143)
		(layer "In13.Cu")
		(net "P5E_CPU1_P0_RX_DP<2>")
	)
	(segment
		(start 124.421646 -331.71892)
		(end 124.421646 -331.718666)
		(width 0.14224)
		(layer "In13.Cu")
		(net "P5E_CPU1_P0_RX_DP<2>")
	)
	(segment
		(start 110.043976 -307.826156)
		(end 105.130092 -305.199288)
		(width 0.14224)
		(layer "In13.Cu")
		(net "P5E_CPU1_P0_RX_DP<2>")
	)
	(segment
		(start 99.203256 -283.48432)
		(end 99.204018 -283.483812)
		(width 0.1143)
		(layer "In13.Cu")
		(net "P5E_CPU1_P0_RX_DP<2>")
	)
	(segment
		(start 99.206812 -284.130496)
		(end 99.205034 -284.12948)
		(width 0.1143)
		(layer "In13.Cu")
		(net "P5E_CPU1_P0_RX_DP<2>")
	)
	(segment
		(start 99.235514 -285.767272)
		(end 99.210876 -285.753048)
		(width 0.1143)
		(layer "In13.Cu")
		(net "P5E_CPU1_P0_RX_DP<2>")
	)
	(segment
		(start 99.24161 -290.63061)
		(end 99.196144 -290.604194)
		(width 0.1143)
		(layer "In13.Cu")
		(net "P5E_CPU1_P0_RX_DP<2>")
	)
	(segment
		(start 99.203256 -285.748476)
		(end 99.172268 -285.730696)
		(width 0.1143)
		(layer "In13.Cu")
		(net "P5E_CPU1_P0_RX_DP<2>")
	)
	(segment
		(start 110.831122 -357.856028)
		(end 110.688882 -357.713788)
		(width 0.14224)
		(layer "In13.Cu")
		(net "P5E_CPU1_P0_RX_DP<2>")
	)
	(segment
		(start 123.331224 -354.51034)
		(end 127.76581 -350.075754)
		(width 0.14224)
		(layer "In13.Cu")
		(net "P5E_CPU1_P0_RX_DP<2>")
	)
	(segment
		(start 99.204018 -284.128972)
		(end 99.203256 -284.128464)
		(width 0.1143)
		(layer "In13.Cu")
		(net "P5E_CPU1_P0_RX_DP<2>")
	)
	(segment
		(start 99.242372 -287.391348)
		(end 99.238816 -287.389316)
		(width 0.1143)
		(layer "In13.Cu")
		(net "P5E_CPU1_P0_RX_DP<2>")
	)
	(segment
		(start 99.214432 -275.37791)
		(end 99.215702 -275.377148)
		(width 0.1143)
		(layer "In13.Cu")
		(net "P5E_CPU1_P0_RX_DP<2>")
	)
	(segment
		(start 104.282748 -363.082586)
		(end 109.567218 -359.313988)
		(width 0.14224)
		(layer "In13.Cu")
		(net "P5E_CPU1_P0_RX_DP<2>")
	)
	(segment
		(start 99.172268 -275.40204)
		(end 99.203256 -275.38426)
		(width 0.1143)
		(layer "In13.Cu")
		(net "P5E_CPU1_P0_RX_DP<2>")
	)
	(segment
		(start 99.235514 -276.0472)
		(end 99.210876 -276.032976)
		(width 0.1143)
		(layer "In13.Cu")
		(net "P5E_CPU1_P0_RX_DP<2>")
	)
	(segment
		(start 99.205034 -294.823134)
		(end 99.210622 -294.820086)
		(width 0.1143)
		(layer "In13.Cu")
		(net "P5E_CPU1_P0_RX_DP<2>")
	)
	(segment
		(start 99.210876 -274.412964)
		(end 99.209352 -274.411948)
		(width 0.1143)
		(layer "In13.Cu")
		(net "P5E_CPU1_P0_RX_DP<2>")
	)
	(segment
		(start 99.172268 -283.5021)
		(end 99.203256 -283.48432)
		(width 0.1143)
		(layer "In13.Cu")
		(net "P5E_CPU1_P0_RX_DP<2>")
	)
	(segment
		(start 99.203256 -271.168368)
		(end 99.172268 -271.150588)
		(width 0.1143)
		(layer "In13.Cu")
		(net "P5E_CPU1_P0_RX_DP<2>")
	)
	(segment
		(start 99.203256 -280.244296)
		(end 99.204018 -280.243788)
		(width 0.1143)
		(layer "In13.Cu")
		(net "P5E_CPU1_P0_RX_DP<2>")
	)
	(segment
		(start 99.236784 -288.32429)
		(end 99.237546 -288.323782)
		(width 0.1143)
		(layer "In13.Cu")
		(net "P5E_CPU1_P0_RX_DP<2>")
	)
	(segment
		(start 99.203256 -282.508452)
		(end 99.172268 -282.490672)
		(width 0.1143)
		(layer "In13.Cu")
		(net "P5E_CPU1_P0_RX_DP<2>")
	)
	(segment
		(start 99.205034 -279.269444)
		(end 99.204018 -279.268936)
		(width 0.1143)
		(layer "In13.Cu")
		(net "P5E_CPU1_P0_RX_DP<2>")
	)
	(segment
		(start 99.209352 -276.03196)
		(end 99.208336 -276.031452)
		(width 0.1143)
		(layer "In13.Cu")
		(net "P5E_CPU1_P0_RX_DP<2>")
	)
	(segment
		(start 99.197414 -287.364424)
		(end 99.196398 -287.363662)
		(width 0.1143)
		(layer "In13.Cu")
		(net "P5E_CPU1_P0_RX_DP<2>")
	)
	(segment
		(start 99.212654 -289.95878)
		(end 99.243642 -289.940238)
		(width 0.1143)
		(layer "In13.Cu")
		(net "P5E_CPU1_P0_RX_DP<2>")
	)
	(segment
		(start 98.62312 -270.03629)
		(end 98.921062 -270.03629)
		(width 0.1143)
		(layer "In13.Cu")
		(net "P5E_CPU1_P0_RX_DP<2>")
	)
	(segment
		(start 99.198176 -288.985706)
		(end 99.196906 -288.984944)
		(width 0.1143)
		(layer "In13.Cu")
		(net "P5E_CPU1_P0_RX_DP<2>")
	)
	(segment
		(start 99.206812 -277.650448)
		(end 99.205034 -277.649432)
		(width 0.1143)
		(layer "In13.Cu")
		(net "P5E_CPU1_P0_RX_DP<2>")
	)
	(segment
		(start 120.946164 -357.856028)
		(end 110.831122 -357.856028)
		(width 0.14224)
		(layer "In13.Cu")
		(net "P5E_CPU1_P0_RX_DP<2>")
	)
	(segment
		(start 99.010978 -295.151556)
		(end 99.011232 -295.15181)
		(width 0.1143)
		(layer "In13.Cu")
		(net "P5E_CPU1_P0_RX_DP<2>")
	)
	(segment
		(start 99.205034 -282.509468)
		(end 99.204018 -282.50896)
		(width 0.1143)
		(layer "In13.Cu")
		(net "P5E_CPU1_P0_RX_DP<2>")
	)
	(segment
		(start 99.205034 -280.24328)
		(end 99.243134 -280.220928)
		(width 0.1143)
		(layer "In13.Cu")
		(net "P5E_CPU1_P0_RX_DP<2>")
	)
	(segment
		(start 99.204018 -273.76374)
		(end 99.205034 -273.763232)
		(width 0.1143)
		(layer "In13.Cu")
		(net "P5E_CPU1_P0_RX_DP<2>")
	)
	(segment
		(start 99.204018 -283.483812)
		(end 99.205034 -283.483304)
		(width 0.1143)
		(layer "In13.Cu")
		(net "P5E_CPU1_P0_RX_DP<2>")
	)
	(segment
		(start 99.237546 -288.323782)
		(end 99.243134 -288.320988)
		(width 0.1143)
		(layer "In13.Cu")
		(net "P5E_CPU1_P0_RX_DP<2>")
	)
	(segment
		(start 99.207828 -275.38172)
		(end 99.210622 -275.380196)
		(width 0.1143)
		(layer "In13.Cu")
		(net "P5E_CPU1_P0_RX_DP<2>")
	)
	(segment
		(start 99.19081 -288.351214)
		(end 99.191064 -288.35096)
		(width 0.1143)
		(layer "In13.Cu")
		(net "P5E_CPU1_P0_RX_DP<2>")
	)
	(segment
		(start 99.204018 -281.8638)
		(end 99.205034 -281.863292)
		(width 0.1143)
		(layer "In13.Cu")
		(net "P5E_CPU1_P0_RX_DP<2>")
	)
	(segment
		(start 99.209352 -285.752032)
		(end 99.208336 -285.751524)
		(width 0.1143)
		(layer "In13.Cu")
		(net "P5E_CPU1_P0_RX_DP<2>")
	)
	(segment
		(start 99.208336 -285.751524)
		(end 99.206812 -285.750508)
		(width 0.1143)
		(layer "In13.Cu")
		(net "P5E_CPU1_P0_RX_DP<2>")
	)
	(segment
		(start 99.204018 -278.623776)
		(end 99.205034 -278.623268)
		(width 0.1143)
		(layer "In13.Cu")
		(net "P5E_CPU1_P0_RX_DP<2>")
	)
	(segment
		(start 99.20351 -291.583872)
		(end 99.224084 -291.571934)
		(width 0.1143)
		(layer "In13.Cu")
		(net "P5E_CPU1_P0_RX_DP<2>")
	)
	(segment
		(start 99.236276 -271.187672)
		(end 99.235514 -271.187164)
		(width 0.1143)
		(layer "In13.Cu")
		(net "P5E_CPU1_P0_RX_DP<2>")
	)
	(segment
		(start 99.243134 -271.191736)
		(end 99.236276 -271.187672)
		(width 0.1143)
		(layer "In13.Cu")
		(net "P5E_CPU1_P0_RX_DP<2>")
	)
	(segment
		(start 99.172268 -285.122112)
		(end 99.203256 -285.104332)
		(width 0.1143)
		(layer "In13.Cu")
		(net "P5E_CPU1_P0_RX_DP<2>")
	)
	(segment
		(start 99.203256 -276.028404)
		(end 99.172268 -276.010624)
		(width 0.1143)
		(layer "In13.Cu")
		(net "P5E_CPU1_P0_RX_DP<2>")
	)
	(segment
		(start 99.242372 -287.391094)
		(end 99.242372 -287.391348)
		(width 0.1143)
		(layer "In13.Cu")
		(net "P5E_CPU1_P0_RX_DP<2>")
	)
	(segment
		(start 99.172268 -276.010624)
		(end 99.152456 -275.9964)
		(width 0.1143)
		(layer "In13.Cu")
		(net "P5E_CPU1_P0_RX_DP<2>")
	)
	(segment
		(start 99.203256 -275.38426)
		(end 99.204018 -275.383752)
		(width 0.1143)
		(layer "In13.Cu")
		(net "P5E_CPU1_P0_RX_DP<2>")
	)
	(segment
		(start 99.205034 -285.749492)
		(end 99.204018 -285.748984)
		(width 0.1143)
		(layer "In13.Cu")
		(net "P5E_CPU1_P0_RX_DP<2>")
	)
	(segment
		(start 99.235514 -271.187164)
		(end 99.205034 -271.169384)
		(width 0.1143)
		(layer "In13.Cu")
		(net "P5E_CPU1_P0_RX_DP<2>")
	)
	(segment
		(start 99.205034 -276.02942)
		(end 99.204018 -276.028912)
		(width 0.1143)
		(layer "In13.Cu")
		(net "P5E_CPU1_P0_RX_DP<2>")
	)
	(segment
		(start 99.209606 -277.000462)
		(end 99.243134 -276.980904)
		(width 0.1143)
		(layer "In13.Cu")
		(net "P5E_CPU1_P0_RX_DP<2>")
	)
	(segment
		(start 99.209098 -293.851584)
		(end 99.20732 -293.850568)
		(width 0.1143)
		(layer "In13.Cu")
		(net "P5E_CPU1_P0_RX_DP<2>")
	)
	(segment
		(start 99.204018 -276.028912)
		(end 99.203256 -276.028404)
		(width 0.1143)
		(layer "In13.Cu")
		(net "P5E_CPU1_P0_RX_DP<2>")
	)
	(segment
		(start 99.172268 -277.630636)
		(end 99.152456 -277.616412)
		(width 0.1143)
		(layer "In13.Cu")
		(net "P5E_CPU1_P0_RX_DP<2>")
	)
	(segment
		(start 112.230662 -310.197246)
		(end 110.78083 -308.43093)
		(width 0.14224)
		(layer "In13.Cu")
		(net "P5E_CPU1_P0_RX_DP<2>")
	)
	(segment
		(start 98.592132 -298.352464)
		(end 98.592132 -296.422318)
		(width 0.14224)
		(layer "In13.Cu")
		(net "P5E_CPU1_P0_RX_DP<2>")
	)
	(segment
		(start 99.152456 -277.036276)
		(end 99.172268 -277.022052)
		(width 0.1143)
		(layer "In13.Cu")
		(net "P5E_CPU1_P0_RX_DP<2>")
	)
	(segment
		(start 99.210876 -277.652988)
		(end 99.209352 -277.651972)
		(width 0.1143)
		(layer "In13.Cu")
		(net "P5E_CPU1_P0_RX_DP<2>")
	)
	(segment
		(start 99.204018 -272.788888)
		(end 99.203256 -272.78838)
		(width 0.1143)
		(layer "In13.Cu")
		(net "P5E_CPU1_P0_RX_DP<2>")
	)
	(segment
		(start 99.208336 -284.131512)
		(end 99.206812 -284.130496)
		(width 0.1143)
		(layer "In13.Cu")
		(net "P5E_CPU1_P0_RX_DP<2>")
	)
	(segment
		(start 99.236276 -284.147768)
		(end 99.235514 -284.14726)
		(width 0.1143)
		(layer "In13.Cu")
		(net "P5E_CPU1_P0_RX_DP<2>")
	)
	(segment
		(start 99.204018 -277.648924)
		(end 99.203256 -277.648416)
		(width 0.1143)
		(layer "In13.Cu")
		(net "P5E_CPU1_P0_RX_DP<2>")
	)
	(segment
		(start 50.632614 -384.731006)
		(end 50.635662 -384.3528)
		(width 0.14224)
		(layer "In13.Cu")
		(net "P5E_CPU1_P0_RX_DP<2>")
	)
	(segment
		(start 124.181108 -356.88016)
		(end 128.62052 -352.440748)
		(width 0.14224)
		(layer "In13.Cu")
		(net "P5E_CPU1_P0_RX_DP<2>")
	)
	(segment
		(start 99.235514 -284.14726)
		(end 99.210876 -284.133036)
		(width 0.1143)
		(layer "In13.Cu")
		(net "P5E_CPU1_P0_RX_DP<2>")
	)
	(segment
		(start 99.204018 -294.823642)
		(end 99.205034 -294.823134)
		(width 0.1143)
		(layer "In13.Cu")
		(net "P5E_CPU1_P0_RX_DP<2>")
	)
	(segment
		(start 56.206136 -367.52403)
		(end 56.206136 -367.523776)
		(width 0.14224)
		(layer "In13.Cu")
		(net "P5E_CPU1_P0_RX_DP<2>")
	)
	(segment
		(start 99.204018 -285.103824)
		(end 99.205034 -285.103316)
		(width 0.1143)
		(layer "In13.Cu")
		(net "P5E_CPU1_P0_RX_DP<2>")
	)
	(segment
		(start 128.62052 -352.0059)
		(end 128.050798 -351.436178)
		(width 0.14224)
		(layer "In13.Cu")
		(net "P5E_CPU1_P0_RX_DP<2>")
	)
	(segment
		(start 98.645726 -295.823132)
		(end 98.918014 -295.550844)
		(width 0.1143)
		(layer "In13.Cu")
		(net "P5E_CPU1_P0_RX_DP<2>")
	)
	(segment
		(start 99.204018 -285.748984)
		(end 99.203256 -285.748476)
		(width 0.1143)
		(layer "In13.Cu")
		(net "P5E_CPU1_P0_RX_DP<2>")
	)
	(segment
		(start 99.203256 -277.004272)
		(end 99.204018 -277.003764)
		(width 0.1143)
		(layer "In13.Cu")
		(net "P5E_CPU1_P0_RX_DP<2>")
	)
	(segment
		(start 99.016312 -270.847312)
		(end 99.016312 -270.835628)
		(width 0.1143)
		(layer "In13.Cu")
		(net "P5E_CPU1_P0_RX_DP<2>")
	)
	(segment
		(start 99.209352 -279.271984)
		(end 99.208336 -279.271476)
		(width 0.1143)
		(layer "In13.Cu")
		(net "P5E_CPU1_P0_RX_DP<2>")
	)
	(segment
		(start 99.203256 -280.88844)
		(end 99.172268 -280.87066)
		(width 0.1143)
		(layer "In13.Cu")
		(net "P5E_CPU1_P0_RX_DP<2>")
	)
	(segment
		(start 99.235514 -277.667212)
		(end 99.210876 -277.652988)
		(width 0.1143)
		(layer "In13.Cu")
		(net "P5E_CPU1_P0_RX_DP<2>")
	)
	(segment
		(start 109.68609 -359.275888)
		(end 120.946164 -359.275888)
		(width 0.14224)
		(layer "In13.Cu")
		(net "P5E_CPU1_P0_RX_DP<2>")
	)
	(segment
		(start 99.203256 -294.82415)
		(end 99.204018 -294.823642)
		(width 0.1143)
		(layer "In13.Cu")
		(net "P5E_CPU1_P0_RX_DP<2>")
	)
	(segment
		(start 110.688882 -357.713788)
		(end 110.688882 -357.142288)
		(width 0.14224)
		(layer "In13.Cu")
		(net "P5E_CPU1_P0_RX_DP<2>")
	)
	(segment
		(start 121.332498 -322.989702)
		(end 117.835172 -317.755778)
		(width 0.14224)
		(layer "In13.Cu")
		(net "P5E_CPU1_P0_RX_DP<2>")
	)
	(segment
		(start 99.152456 -281.896312)
		(end 99.172268 -281.882088)
		(width 0.1143)
		(layer "In13.Cu")
		(net "P5E_CPU1_P0_RX_DP<2>")
	)
	(segment
		(start 99.209352 -284.13202)
		(end 99.208336 -284.131512)
		(width 0.1143)
		(layer "In13.Cu")
		(net "P5E_CPU1_P0_RX_DP<2>")
	)
	(segment
		(start 99.212908 -294.818816)
		(end 99.214432 -294.8178)
		(width 0.1143)
		(layer "In13.Cu")
		(net "P5E_CPU1_P0_RX_DP<2>")
	)
	(segment
		(start 99.205288 -293.849298)
		(end 99.196144 -293.844218)
		(width 0.1143)
		(layer "In13.Cu")
		(net "P5E_CPU1_P0_RX_DP<2>")
	)
	(segment
		(start 99.203256 -284.128464)
		(end 99.172268 -284.110684)
		(width 0.1143)
		(layer "In13.Cu")
		(net "P5E_CPU1_P0_RX_DP<2>")
	)
	(segment
		(start 99.203256 -272.78838)
		(end 99.172268 -272.7706)
		(width 0.1143)
		(layer "In13.Cu")
		(net "P5E_CPU1_P0_RX_DP<2>")
	)
	(segment
		(start 99.210368 -293.852346)
		(end 99.209098 -293.851584)
		(width 0.1143)
		(layer "In13.Cu")
		(net "P5E_CPU1_P0_RX_DP<2>")
	)
	(segment
		(start 99.206812 -274.410424)
		(end 99.205034 -274.409408)
		(width 0.1143)
		(layer "In13.Cu")
		(net "P5E_CPU1_P0_RX_DP<2>")
	)
	(segment
		(start 99.236276 -279.287732)
		(end 99.235514 -279.287224)
		(width 0.1143)
		(layer "In13.Cu")
		(net "P5E_CPU1_P0_RX_DP<2>")
	)
	(segment
		(start 99.205034 -273.763232)
		(end 99.243134 -273.74088)
		(width 0.1143)
		(layer "In13.Cu")
		(net "P5E_CPU1_P0_RX_DP<2>")
	)
	(segment
		(start 128.050798 -351.436178)
		(end 127.61595 -351.436178)
		(width 0.14224)
		(layer "In13.Cu")
		(net "P5E_CPU1_P0_RX_DP<2>")
	)
	(segment
		(start 99.209352 -282.512008)
		(end 99.208336 -282.5115)
		(width 0.1143)
		(layer "In13.Cu")
		(net "P5E_CPU1_P0_RX_DP<2>")
	)
	(segment
		(start 99.172268 -280.262076)
		(end 99.203256 -280.244296)
		(width 0.1143)
		(layer "In13.Cu")
		(net "P5E_CPU1_P0_RX_DP<2>")
	)
	(segment
		(start 99.236276 -274.427696)
		(end 99.235514 -274.427188)
		(width 0.1143)
		(layer "In13.Cu")
		(net "P5E_CPU1_P0_RX_DP<2>")
	)
	(segment
		(start 99.210876 -282.513024)
		(end 99.209352 -282.512008)
		(width 0.1143)
		(layer "In13.Cu")
		(net "P5E_CPU1_P0_RX_DP<2>")
	)
	(segment
		(start 99.204018 -272.143728)
		(end 99.205034 -272.14322)
		(width 0.1143)
		(layer "In13.Cu")
		(net "P5E_CPU1_P0_RX_DP<2>")
	)
	(segment
		(start 63.797434 -363.17301)
		(end 104.0003 -363.17301)
		(width 0.14224)
		(layer "In13.Cu")
		(net "P5E_CPU1_P0_RX_DP<2>")
	)
	(segment
		(start 99.208336 -277.651464)
		(end 99.206812 -277.650448)
		(width 0.1143)
		(layer "In13.Cu")
		(net "P5E_CPU1_P0_RX_DP<2>")
	)
	(segment
		(start 99.243134 -276.051772)
		(end 99.236276 -276.047708)
		(width 0.1143)
		(layer "In13.Cu")
		(net "P5E_CPU1_P0_RX_DP<2>")
	)
	(segment
		(start 99.172268 -277.022052)
		(end 99.203256 -277.004272)
		(width 0.1143)
		(layer "In13.Cu")
		(net "P5E_CPU1_P0_RX_DP<2>")
	)
	(segment
		(start 123.936506 -355.115622)
		(end 123.735338 -355.115622)
		(width 0.14224)
		(layer "In13.Cu")
		(net "P5E_CPU1_P0_RX_DP<2>")
	)
	(segment
		(start 99.205034 -271.169384)
		(end 99.204018 -271.168876)
		(width 0.1143)
		(layer "In13.Cu")
		(net "P5E_CPU1_P0_RX_DP<2>")
	)
	(segment
		(start 99.208336 -274.41144)
		(end 99.206812 -274.410424)
		(width 0.1143)
		(layer "In13.Cu")
		(net "P5E_CPU1_P0_RX_DP<2>")
	)
	(segment
		(start 99.172268 -272.162016)
		(end 99.203256 -272.144236)
		(width 0.1143)
		(layer "In13.Cu")
		(net "P5E_CPU1_P0_RX_DP<2>")
	)
	(segment
		(start 99.205034 -272.14322)
		(end 99.243134 -272.120868)
		(width 0.1143)
		(layer "In13.Cu")
		(net "P5E_CPU1_P0_RX_DP<2>")
	)
	(segment
		(start 98.789744 -270.393414)
		(end 98.77298 -270.381476)
		(width 0.1143)
		(layer "In13.Cu")
		(net "P5E_CPU1_P0_RX_DP<2>")
	)
	(segment
		(start 99.204018 -280.888948)
		(end 99.203256 -280.88844)
		(width 0.1143)
		(layer "In13.Cu")
		(net "P5E_CPU1_P0_RX_DP<2>")
	)
	(segment
		(start 56.206136 -367.523776)
		(end 57.034684 -366.695228)
		(width 0.14224)
		(layer "In13.Cu")
		(net "P5E_CPU1_P0_RX_DP<2>")
	)
	(segment
		(start 120.946164 -359.275888)
		(end 121.253504 -358.968548)
		(width 0.14224)
		(layer "In13.Cu")
		(net "P5E_CPU1_P0_RX_DP<2>")
	)
	(segment
		(start 99.208336 -282.5115)
		(end 99.206812 -282.510484)
		(width 0.1143)
		(layer "In13.Cu")
		(net "P5E_CPU1_P0_RX_DP<2>")
	)
	(segment
		(start 99.204018 -274.4089)
		(end 99.203256 -274.408392)
		(width 0.1143)
		(layer "In13.Cu")
		(net "P5E_CPU1_P0_RX_DP<2>")
	)
	(segment
		(start 99.210622 -275.380196)
		(end 99.212908 -275.378926)
		(width 0.1143)
		(layer "In13.Cu")
		(net "P5E_CPU1_P0_RX_DP<2>")
	)
	(segment
		(start 99.204018 -271.168876)
		(end 99.203256 -271.168368)
		(width 0.1143)
		(layer "In13.Cu")
		(net "P5E_CPU1_P0_RX_DP<2>")
	)
	(segment
		(start 50.686208 -385.649216)
		(end 50.860452 -385.548632)
		(width 0.14224)
		(layer "In13.Cu")
		(net "P5E_CPU1_P0_RX_DP<2>")
	)
	(segment
		(start 99.196906 -288.984944)
		(end 99.196144 -288.984436)
		(width 0.1143)
		(layer "In13.Cu")
		(net "P5E_CPU1_P0_RX_DP<2>")
	)
	(segment
		(start 99.204018 -282.50896)
		(end 99.203256 -282.508452)
		(width 0.1143)
		(layer "In13.Cu")
		(net "P5E_CPU1_P0_RX_DP<2>")
	)
	(segment
		(start 127.879094 -349.71355)
		(end 125.171454 -334.791304)
		(width 0.14224)
		(layer "In13.Cu")
		(net "P5E_CPU1_P0_RX_DP<2>")
	)
	(segment
		(start 99.206812 -279.27046)
		(end 99.205034 -279.269444)
		(width 0.1143)
		(layer "In13.Cu")
		(net "P5E_CPU1_P0_RX_DP<2>")
	)
	(segment
		(start 99.243134 -272.811748)
		(end 99.205034 -272.789396)
		(width 0.1143)
		(layer "In13.Cu")
		(net "P5E_CPU1_P0_RX_DP<2>")
	)
	(segment
		(start 99.203256 -277.648416)
		(end 99.172268 -277.630636)
		(width 0.1143)
		(layer "In13.Cu")
		(net "P5E_CPU1_P0_RX_DP<2>")
	)
	(segment
		(start 99.209352 -277.651972)
		(end 99.208336 -277.651464)
		(width 0.1143)
		(layer "In13.Cu")
		(net "P5E_CPU1_P0_RX_DP<2>")
	)
	(segment
		(start 99.243134 -279.291796)
		(end 99.236276 -279.287732)
		(width 0.1143)
		(layer "In13.Cu")
		(net "P5E_CPU1_P0_RX_DP<2>")
	)
	(segment
		(start 99.243134 -284.151832)
		(end 99.236276 -284.147768)
		(width 0.1143)
		(layer "In13.Cu")
		(net "P5E_CPU1_P0_RX_DP<2>")
	)
	(segment
		(start 99.203256 -279.268428)
		(end 99.172268 -279.250648)
		(width 0.1143)
		(layer "In13.Cu")
		(net "P5E_CPU1_P0_RX_DP<2>")
	)
	(segment
		(start 99.205034 -275.383244)
		(end 99.206812 -275.382228)
		(width 0.1143)
		(layer "In13.Cu")
		(net "P5E_CPU1_P0_RX_DP<2>")
	)
	(segment
		(start 52.540154 -373.492268)
		(end 56.187594 -367.547144)
		(width 0.14224)
		(layer "In13.Cu")
		(net "P5E_CPU1_P0_RX_DP<2>")
	)
	(segment
		(start 99.196398 -287.363662)
		(end 99.195636 -287.363154)
		(width 0.1143)
		(layer "In13.Cu")
		(net "P5E_CPU1_P0_RX_DP<2>")
	)
	(segment
		(start 99.172268 -284.110684)
		(end 99.152456 -284.09646)
		(width 0.1143)
		(layer "In13.Cu")
		(net "P5E_CPU1_P0_RX_DP<2>")
	)
	(segment
		(start 99.206812 -276.030436)
		(end 99.205034 -276.02942)
		(width 0.1143)
		(layer "In13.Cu")
		(net "P5E_CPU1_P0_RX_DP<2>")
	)
	(segment
		(start 99.172268 -280.87066)
		(end 99.153472 -280.856944)
		(width 0.1143)
		(layer "In13.Cu")
		(net "P5E_CPU1_P0_RX_DP<2>")
	)
	(segment
		(start 98.717608 -270.349472)
		(end 98.702368 -270.340582)
		(width 0.1143)
		(layer "In13.Cu")
		(net "P5E_CPU1_P0_RX_DP<2>")
	)
	(segment
		(start 99.187 -293.214044)
		(end 99.188524 -293.214044)
		(width 0.1143)
		(layer "In13.Cu")
		(net "P5E_CPU1_P0_RX_DP<2>")
	)
	(segment
		(start 99.152456 -278.656288)
		(end 99.172268 -278.642064)
		(width 0.1143)
		(layer "In13.Cu")
		(net "P5E_CPU1_P0_RX_DP<2>")
	)
	(segment
		(start 99.236276 -277.66772)
		(end 99.235514 -277.667212)
		(width 0.1143)
		(layer "In13.Cu")
		(net "P5E_CPU1_P0_RX_DP<2>")
	)
	(segment
		(start 99.204018 -280.243788)
		(end 99.205034 -280.24328)
		(width 0.1143)
		(layer "In13.Cu")
		(net "P5E_CPU1_P0_RX_DP<2>")
	)
	(segment
		(start 98.77298 -270.381476)
		(end 98.717608 -270.349472)
		(width 0.1143)
		(layer "In13.Cu")
		(net "P5E_CPU1_P0_RX_DP<2>")
	)
	(segment
		(start 99.172268 -279.250648)
		(end 99.152456 -279.236424)
		(width 0.1143)
		(layer "In13.Cu")
		(net "P5E_CPU1_P0_RX_DP<2>")
	)
	(segment
		(start 99.242372 -293.871142)
		(end 99.212654 -293.85387)
		(width 0.1143)
		(layer "In13.Cu")
		(net "P5E_CPU1_P0_RX_DP<2>")
	)
	(segment
		(start 99.203256 -281.864308)
		(end 99.204018 -281.8638)
		(width 0.1143)
		(layer "In13.Cu")
		(net "P5E_CPU1_P0_RX_DP<2>")
	)
	(segment
		(start 99.204526 -288.34334)
		(end 99.236784 -288.32429)
		(width 0.1143)
		(layer "In13.Cu")
		(net "P5E_CPU1_P0_RX_DP<2>")
	)
	(segment
		(start 99.203256 -274.408392)
		(end 99.172268 -274.390612)
		(width 0.1143)
		(layer "In13.Cu")
		(net "P5E_CPU1_P0_RX_DP<2>")
	)
	(segment
		(start 110.78083 -308.43093)
		(end 110.043976 -307.826156)
		(width 0.14224)
		(layer "In13.Cu")
		(net "P5E_CPU1_P0_RX_DP<2>")
	)
	(segment
		(start 99.199192 -294.826436)
		(end 99.203256 -294.82415)
		(width 0.1143)
		(layer "In13.Cu")
		(net "P5E_CPU1_P0_RX_DP<2>")
	)
	(segment
		(start 99.210876 -276.032976)
		(end 99.209352 -276.03196)
		(width 0.1143)
		(layer "In13.Cu")
		(net "P5E_CPU1_P0_RX_DP<2>")
	)
	(segment
		(start 99.235514 -274.427188)
		(end 99.210876 -274.412964)
		(width 0.1143)
		(layer "In13.Cu")
		(net "P5E_CPU1_P0_RX_DP<2>")
	)
	(segment
		(start 99.010978 -295.3258)
		(end 99.010978 -295.151556)
		(width 0.1143)
		(layer "In13.Cu")
		(net "P5E_CPU1_P0_RX_DP<2>")
	)
	(segment
		(start 99.20351 -289.96386)
		(end 99.212654 -289.95878)
		(width 0.1143)
		(layer "In13.Cu")
		(net "P5E_CPU1_P0_RX_DP<2>")
	)
	(segment
		(start 99.206812 -285.750508)
		(end 99.205034 -285.749492)
		(width 0.1143)
		(layer "In13.Cu")
		(net "P5E_CPU1_P0_RX_DP<2>")
	)
	(segment
		(start 99.205034 -274.409408)
		(end 99.204018 -274.4089)
		(width 0.1143)
		(layer "In13.Cu")
		(net "P5E_CPU1_P0_RX_DP<2>")
	)
	(segment
		(start 99.153472 -280.275792)
		(end 99.172268 -280.262076)
		(width 0.1143)
		(layer "In13.Cu")
		(net "P5E_CPU1_P0_RX_DP<2>")
	)
	(arc
		(start 99.152456 -279.236424)
		(mid 99.003742 -278.946356)
		(end 99.152456 -278.656288)
		(width 0.1143)
		(layer "In13.Cu")
		(net "P5E_CPU1_P0_RX_DP<2>")
	)
	(arc
		(start 99.131374 -287.2994)
		(mid 99.027253 -286.994701)
		(end 99.205288 -286.726376)
		(width 0.1143)
		(layer "In13.Cu")
		(net "P5E_CPU1_P0_RX_DP<2>")
	)
	(arc
		(start 99.016312 -270.835628)
		(mid 98.956426 -270.587164)
		(end 98.789744 -270.393414)
		(width 0.1143)
		(layer "In13.Cu")
		(net "P5E_CPU1_P0_RX_DP<2>")
	)
	(arc
		(start 99.196144 -293.844218)
		(mid 99.01782 -293.531636)
		(end 99.187 -293.214044)
		(width 0.1143)
		(layer "In13.Cu")
		(net "P5E_CPU1_P0_RX_DP<2>")
	)
	(arc
		(start 99.011232 -295.15181)
		(mid 99.061561 -294.963928)
		(end 99.199192 -294.826436)
		(width 0.1143)
		(layer "In13.Cu")
		(net "P5E_CPU1_P0_RX_DP<2>")
	)
	(arc
		(start 99.243134 -285.080964)
		(mid 99.486461 -284.616398)
		(end 99.243134 -284.151832)
		(width 0.1143)
		(layer "In13.Cu")
		(net "P5E_CPU1_P0_RX_DP<2>")
	)
	(arc
		(start 99.152456 -284.09646)
		(mid 99.003742 -283.806392)
		(end 99.152456 -283.516324)
		(width 0.1143)
		(layer "In13.Cu")
		(net "P5E_CPU1_P0_RX_DP<2>")
	)
	(arc
		(start 63.598806 -363.219746)
		(mid 63.695403 -363.184833)
		(end 63.797434 -363.17301)
		(width 0.14224)
		(layer "In13.Cu")
		(net "P5E_CPU1_P0_RX_DP<2>")
	)
	(arc
		(start 104.0003 -363.17301)
		(mid 104.148587 -363.149856)
		(end 104.282748 -363.082586)
		(width 0.14224)
		(layer "In13.Cu")
		(net "P5E_CPU1_P0_RX_DP<2>")
	)
	(arc
		(start 99.152456 -275.9964)
		(mid 99.003742 -275.706332)
		(end 99.152456 -275.416264)
		(width 0.1143)
		(layer "In13.Cu")
		(net "P5E_CPU1_P0_RX_DP<2>")
	)
	(arc
		(start 99.243134 -278.600916)
		(mid 99.486461 -278.13635)
		(end 99.243134 -277.671784)
		(width 0.1143)
		(layer "In13.Cu")
		(net "P5E_CPU1_P0_RX_DP<2>")
	)
	(arc
		(start 109.567218 -359.313988)
		(mid 109.623675 -359.285643)
		(end 109.68609 -359.275888)
		(width 0.14224)
		(layer "In13.Cu")
		(net "P5E_CPU1_P0_RX_DP<2>")
	)
	(arc
		(start 99.243642 -289.940238)
		(mid 99.485476 -289.454472)
		(end 99.205288 -288.98977)
		(width 0.1143)
		(layer "In13.Cu")
		(net "P5E_CPU1_P0_RX_DP<2>")
	)
	(arc
		(start 99.243134 -280.220928)
		(mid 99.486461 -279.756362)
		(end 99.243134 -279.291796)
		(width 0.1143)
		(layer "In13.Cu")
		(net "P5E_CPU1_P0_RX_DP<2>")
	)
	(arc
		(start 99.243134 -272.120868)
		(mid 99.486461 -271.656302)
		(end 99.243134 -271.191736)
		(width 0.1143)
		(layer "In13.Cu")
		(net "P5E_CPU1_P0_RX_DP<2>")
	)
	(arc
		(start 99.172268 -285.730696)
		(mid 99.021883 -285.426404)
		(end 99.172268 -285.122112)
		(width 0.1143)
		(layer "In13.Cu")
		(net "P5E_CPU1_P0_RX_DP<2>")
	)
	(arc
		(start 99.152456 -277.616412)
		(mid 99.003742 -277.326344)
		(end 99.152456 -277.036276)
		(width 0.1143)
		(layer "In13.Cu")
		(net "P5E_CPU1_P0_RX_DP<2>")
	)
	(arc
		(start 98.88093 -299.049694)
		(mid 98.667185 -298.729802)
		(end 98.592132 -298.352464)
		(width 0.14224)
		(layer "In13.Cu")
		(net "P5E_CPU1_P0_RX_DP<2>")
	)
	(arc
		(start 99.152456 -282.476448)
		(mid 99.003742 -282.18638)
		(end 99.152456 -281.896312)
		(width 0.1143)
		(layer "In13.Cu")
		(net "P5E_CPU1_P0_RX_DP<2>")
	)
	(arc
		(start 98.542348 -296.072814)
		(mid 98.569208 -295.93769)
		(end 98.645726 -295.823132)
		(width 0.1143)
		(layer "In13.Cu")
		(net "P5E_CPU1_P0_RX_DP<2>")
	)
	(arc
		(start 99.243134 -288.320988)
		(mid 99.486351 -287.855892)
		(end 99.242372 -287.391094)
		(width 0.1143)
		(layer "In13.Cu")
		(net "P5E_CPU1_P0_RX_DP<2>")
	)
	(arc
		(start 99.205288 -286.726376)
		(mid 99.485818 -286.259339)
		(end 99.242372 -285.771844)
		(width 0.1143)
		(layer "In13.Cu")
		(net "P5E_CPU1_P0_RX_DP<2>")
	)
	(arc
		(start 99.172268 -271.150588)
		(mid 99.060958 -271.017071)
		(end 99.016312 -270.84909)
		(width 0.1143)
		(layer "In13.Cu")
		(net "P5E_CPU1_P0_RX_DP<2>")
	)
	(arc
		(start 99.188524 -293.214044)
		(mid 99.487306 -292.719274)
		(end 99.194874 -292.22065)
		(width 0.1143)
		(layer "In13.Cu")
		(net "P5E_CPU1_P0_RX_DP<2>")
	)
	(arc
		(start 99.243134 -290.631626)
		(mid 99.242372 -290.631118)
		(end 99.24161 -290.63061)
		(width 0.1143)
		(layer "In13.Cu")
		(net "P5E_CPU1_P0_RX_DP<2>")
	)
	(arc
		(start 56.187594 -367.547144)
		(mid 56.196182 -367.535039)
		(end 56.206136 -367.52403)
		(width 0.14224)
		(layer "In13.Cu")
		(net "P5E_CPU1_P0_RX_DP<2>")
	)
	(arc
		(start 99.196144 -290.604194)
		(mid 99.017927 -290.281917)
		(end 99.20351 -289.96386)
		(width 0.1143)
		(layer "In13.Cu")
		(net "P5E_CPU1_P0_RX_DP<2>")
	)
	(arc
		(start 99.243134 -276.980904)
		(mid 99.486461 -276.516338)
		(end 99.243134 -276.051772)
		(width 0.1143)
		(layer "In13.Cu")
		(net "P5E_CPU1_P0_RX_DP<2>")
	)
	(arc
		(start 127.76581 -350.075754)
		(mid 127.867053 -349.908592)
		(end 127.879094 -349.71355)
		(width 0.14224)
		(layer "In13.Cu")
		(net "P5E_CPU1_P0_RX_DP<2>")
	)
	(arc
		(start 99.243134 -273.74088)
		(mid 99.486461 -273.276314)
		(end 99.243134 -272.811748)
		(width 0.1143)
		(layer "In13.Cu")
		(net "P5E_CPU1_P0_RX_DP<2>")
	)
	(arc
		(start 99.190556 -288.981134)
		(mid 99.009465 -288.67502)
		(end 99.17557 -288.360612)
		(width 0.1143)
		(layer "In13.Cu")
		(net "P5E_CPU1_P0_RX_DP<2>")
	)
	(arc
		(start 99.172268 -274.390612)
		(mid 99.021883 -274.08632)
		(end 99.172268 -273.782028)
		(width 0.1143)
		(layer "In13.Cu")
		(net "P5E_CPU1_P0_RX_DP<2>")
	)
	(arc
		(start 99.243134 -283.460952)
		(mid 99.486461 -282.996386)
		(end 99.243134 -282.53182)
		(width 0.1143)
		(layer "In13.Cu")
		(net "P5E_CPU1_P0_RX_DP<2>")
	)
	(arc
		(start 99.016312 -270.84909)
		(mid 99.016311 -270.848201)
		(end 99.016312 -270.847312)
		(width 0.1143)
		(layer "In13.Cu")
		(net "P5E_CPU1_P0_RX_DP<2>")
	)
	(arc
		(start 99.243134 -275.360892)
		(mid 99.486461 -274.896326)
		(end 99.243134 -274.43176)
		(width 0.1143)
		(layer "In13.Cu")
		(net "P5E_CPU1_P0_RX_DP<2>")
	)
	(arc
		(start 99.243134 -291.560758)
		(mid 99.486461 -291.096192)
		(end 99.243134 -290.631626)
		(width 0.1143)
		(layer "In13.Cu")
		(net "P5E_CPU1_P0_RX_DP<2>")
	)
	(arc
		(start 99.17557 -288.360612)
		(mid 99.183134 -288.355822)
		(end 99.19081 -288.351214)
		(width 0.1143)
		(layer "In13.Cu")
		(net "P5E_CPU1_P0_RX_DP<2>")
	)
	(arc
		(start 99.153472 -280.856944)
		(mid 99.004557 -280.566368)
		(end 99.153472 -280.275792)
		(width 0.1143)
		(layer "In13.Cu")
		(net "P5E_CPU1_P0_RX_DP<2>")
	)
	(arc
		(start 99.243134 -281.84094)
		(mid 99.486461 -281.376374)
		(end 99.243134 -280.911808)
		(width 0.1143)
		(layer "In13.Cu")
		(net "P5E_CPU1_P0_RX_DP<2>")
	)
	(arc
		(start 99.190556 -292.22065)
		(mid 99.018037 -291.898618)
		(end 99.20351 -291.583872)
		(width 0.1143)
		(layer "In13.Cu")
		(net "P5E_CPU1_P0_RX_DP<2>")
	)
	(arc
		(start 123.891802 -357.000048)
		(mid 124.04838 -356.968885)
		(end 124.181108 -356.88016)
		(width 0.14224)
		(layer "In13.Cu")
		(net "P5E_CPU1_P0_RX_DP<2>")
	)
	(arc
		(start 99.243134 -293.87165)
		(mid 99.242753 -293.871396)
		(end 99.242372 -293.871142)
		(width 0.1143)
		(layer "In13.Cu")
		(net "P5E_CPU1_P0_RX_DP<2>")
	)
	(arc
		(start 98.702368 -270.340582)
		(mid 98.605233 -270.237713)
		(end 98.55327 -270.10614)
		(width 0.1143)
		(layer "In13.Cu")
		(net "P5E_CPU1_P0_RX_DP<2>")
	)
	(arc
		(start 52.501546 -373.594122)
		(mid 52.516018 -373.541361)
		(end 52.540154 -373.492268)
		(width 0.14224)
		(layer "In13.Cu")
		(net "P5E_CPU1_P0_RX_DP<2>")
	)
	(arc
		(start 99.243134 -294.800782)
		(mid 99.486461 -294.336216)
		(end 99.243134 -293.87165)
		(width 0.1143)
		(layer "In13.Cu")
		(net "P5E_CPU1_P0_RX_DP<2>")
	)
	(arc
		(start 57.034684 -366.695228)
		(mid 57.455235 -366.337471)
		(end 57.927748 -366.051846)
		(width 0.14224)
		(layer "In13.Cu")
		(net "P5E_CPU1_P0_RX_DP<2>")
	)
	(arc
		(start 98.918014 -295.550844)
		(mid 98.986868 -295.447564)
		(end 99.010978 -295.3258)
		(width 0.1143)
		(layer "In13.Cu")
		(net "P5E_CPU1_P0_RX_DP<2>")
	)
	(arc
		(start 50.940462 -382.474978)
		(mid 50.940995 -382.463758)
		(end 50.942494 -382.452626)
		(width 0.14224)
		(layer "In13.Cu")
		(net "P5E_CPU1_P0_RX_DP<2>")
	)
	(arc
		(start 105.130092 -305.199288)
		(mid 104.927578 -305.07121)
		(end 104.746044 -304.914808)
		(width 0.14224)
		(layer "In13.Cu")
		(net "P5E_CPU1_P0_RX_DP<2>")
	)
	(arc
		(start 99.172268 -272.7706)
		(mid 99.020679 -272.466308)
		(end 99.172268 -272.162016)
		(width 0.1143)
		(layer "In13.Cu")
		(net "P5E_CPU1_P0_RX_DP<2>")
	)
	(segment
		(start 48.870616 -386.003292)
		(end 49.391316 -386.003292)
		(width 0.127)
		(layer "F.Cu")
		(net "P5E_CPU1_P0_RX_DP<1>")
	)
	(segment
		(start 99.387914 -273.010376)
		(end 98.921062 -273.276314)
		(width 0.12954)
		(layer "F.Cu")
		(net "P5E_CPU1_P0_RX_DP<1>")
	)
	(segment
		(start 110.371636 -354.038662)
		(end 110.351824 -354.238306)
		(width 0.14224)
		(layer "In13.Cu")
		(net "P5E_CPU1_P0_RX_DP<1>")
	)
	(segment
		(start 98.085148 -295.279572)
		(end 98.085148 -295.128696)
		(width 0.1143)
		(layer "In13.Cu")
		(net "P5E_CPU1_P0_RX_DP<1>")
	)
	(segment
		(start 63.502286 -362.240068)
		(end 99.10699 -362.240068)
		(width 0.14224)
		(layer "In13.Cu")
		(net "P5E_CPU1_P0_RX_DP<1>")
	)
	(segment
		(start 98.301556 -292.250622)
		(end 98.232468 -292.210236)
		(width 0.1143)
		(layer "In13.Cu")
		(net "P5E_CPU1_P0_RX_DP<1>")
	)
	(segment
		(start 104.3051 -306.050188)
		(end 97.926398 -299.671486)
		(width 0.14224)
		(layer "In13.Cu")
		(net "P5E_CPU1_P0_RX_DP<1>")
	)
	(segment
		(start 110.402116 -356.035102)
		(end 111.889794 -356.035102)
		(width 0.14224)
		(layer "In13.Cu")
		(net "P5E_CPU1_P0_RX_DP<1>")
	)
	(segment
		(start 49.748694 -385.046982)
		(end 49.432718 -384.731006)
		(width 0.14224)
		(layer "In13.Cu")
		(net "P5E_CPU1_P0_RX_DP<1>")
	)
	(segment
		(start 98.30308 -284.151832)
		(end 98.233484 -284.111192)
		(width 0.1143)
		(layer "In13.Cu")
		(net "P5E_CPU1_P0_RX_DP<1>")
	)
	(segment
		(start 98.30308 -279.291796)
		(end 98.233484 -279.251156)
		(width 0.1143)
		(layer "In13.Cu")
		(net "P5E_CPU1_P0_RX_DP<1>")
	)
	(segment
		(start 49.391316 -386.003292)
		(end 49.486312 -385.649216)
		(width 0.14224)
		(layer "In13.Cu")
		(net "P5E_CPU1_P0_RX_DP<1>")
	)
	(segment
		(start 98.233484 -275.401532)
		(end 98.30308 -275.360892)
		(width 0.1143)
		(layer "In13.Cu")
		(net "P5E_CPU1_P0_RX_DP<1>")
	)
	(segment
		(start 102.08006 -361.425236)
		(end 102.591108 -362.048298)
		(width 0.14224)
		(layer "In13.Cu")
		(net "P5E_CPU1_P0_RX_DP<1>")
	)
	(segment
		(start 98.30308 -276.051772)
		(end 98.233484 -276.011132)
		(width 0.1143)
		(layer "In13.Cu")
		(net "P5E_CPU1_P0_RX_DP<1>")
	)
	(segment
		(start 110.360714 -309.524146)
		(end 109.706664 -308.869334)
		(width 0.14224)
		(layer "In13.Cu")
		(net "P5E_CPU1_P0_RX_DP<1>")
	)
	(segment
		(start 98.233484 -283.501592)
		(end 98.30308 -283.460952)
		(width 0.1143)
		(layer "In13.Cu")
		(net "P5E_CPU1_P0_RX_DP<1>")
	)
	(segment
		(start 49.660556 -385.548632)
		(end 49.748694 -385.460494)
		(width 0.14224)
		(layer "In13.Cu")
		(net "P5E_CPU1_P0_RX_DP<1>")
	)
	(segment
		(start 98.233484 -278.641556)
		(end 98.30308 -278.600916)
		(width 0.1143)
		(layer "In13.Cu")
		(net "P5E_CPU1_P0_RX_DP<1>")
	)
	(segment
		(start 98.232214 -288.362136)
		(end 98.30308 -288.320988)
		(width 0.1143)
		(layer "In13.Cu")
		(net "P5E_CPU1_P0_RX_DP<1>")
	)
	(segment
		(start 98.233484 -281.88158)
		(end 98.30308 -281.84094)
		(width 0.1143)
		(layer "In13.Cu")
		(net "P5E_CPU1_P0_RX_DP<1>")
	)
	(segment
		(start 98.62312 -273.276314)
		(end 98.921062 -273.276314)
		(width 0.1143)
		(layer "In13.Cu")
		(net "P5E_CPU1_P0_RX_DP<1>")
	)
	(segment
		(start 119.91594 -354.473002)
		(end 119.7737 -354.615242)
		(width 0.14224)
		(layer "In13.Cu")
		(net "P5E_CPU1_P0_RX_DP<1>")
	)
	(segment
		(start 110.351824 -354.238306)
		(end 102.122478 -360.992674)
		(width 0.14224)
		(layer "In13.Cu")
		(net "P5E_CPU1_P0_RX_DP<1>")
	)
	(segment
		(start 98.233484 -280.261568)
		(end 98.30308 -280.220928)
		(width 0.1143)
		(layer "In13.Cu")
		(net "P5E_CPU1_P0_RX_DP<1>")
	)
	(segment
		(start 99.366578 -362.147104)
		(end 109.80801 -353.576128)
		(width 0.14224)
		(layer "In13.Cu")
		(net "P5E_CPU1_P0_RX_DP<1>")
	)
	(segment
		(start 98.30308 -282.53182)
		(end 98.233484 -282.49118)
		(width 0.1143)
		(layer "In13.Cu")
		(net "P5E_CPU1_P0_RX_DP<1>")
	)
	(segment
		(start 49.742852 -382.26111)
		(end 51.392074 -373.598186)
		(width 0.14224)
		(layer "In13.Cu")
		(net "P5E_CPU1_P0_RX_DP<1>")
	)
	(segment
		(start 98.30308 -285.771844)
		(end 98.233484 -285.731204)
		(width 0.1143)
		(layer "In13.Cu")
		(net "P5E_CPU1_P0_RX_DP<1>")
	)
	(segment
		(start 112.339374 -353.759262)
		(end 119.7737 -353.759262)
		(width 0.14224)
		(layer "In13.Cu")
		(net "P5E_CPU1_P0_RX_DP<1>")
	)
	(segment
		(start 49.748694 -385.460494)
		(end 49.748694 -385.046982)
		(width 0.14224)
		(layer "In13.Cu")
		(net "P5E_CPU1_P0_RX_DP<1>")
	)
	(segment
		(start 98.233484 -273.78152)
		(end 98.30308 -273.74088)
		(width 0.1143)
		(layer "In13.Cu")
		(net "P5E_CPU1_P0_RX_DP<1>")
	)
	(segment
		(start 98.30308 -277.671784)
		(end 98.233484 -277.631144)
		(width 0.1143)
		(layer "In13.Cu")
		(net "P5E_CPU1_P0_RX_DP<1>")
	)
	(segment
		(start 49.740566 -384.048254)
		(end 49.740566 -382.284986)
		(width 0.14224)
		(layer "In13.Cu")
		(net "P5E_CPU1_P0_RX_DP<1>")
	)
	(segment
		(start 112.197134 -355.727762)
		(end 112.197134 -353.901502)
		(width 0.14224)
		(layer "In13.Cu")
		(net "P5E_CPU1_P0_RX_DP<1>")
	)
	(segment
		(start 113.360454 -354.615242)
		(end 113.053114 -354.922582)
		(width 0.14224)
		(layer "In13.Cu")
		(net "P5E_CPU1_P0_RX_DP<1>")
	)
	(segment
		(start 126.639828 -349.777812)
		(end 126.639828 -348.616524)
		(width 0.14224)
		(layer "In13.Cu")
		(net "P5E_CPU1_P0_RX_DP<1>")
	)
	(segment
		(start 55.374794 -367.03635)
		(end 56.861964 -365.54918)
		(width 0.14224)
		(layer "In13.Cu")
		(net "P5E_CPU1_P0_RX_DP<1>")
	)
	(segment
		(start 111.889794 -356.035102)
		(end 112.197134 -355.727762)
		(width 0.14224)
		(layer "In13.Cu")
		(net "P5E_CPU1_P0_RX_DP<1>")
	)
	(segment
		(start 120.39092 -356.033832)
		(end 126.639828 -349.777812)
		(width 0.14224)
		(layer "In13.Cu")
		(net "P5E_CPU1_P0_RX_DP<1>")
	)
	(segment
		(start 97.788984 -295.756838)
		(end 97.957386 -295.588436)
		(width 0.1143)
		(layer "In13.Cu")
		(net "P5E_CPU1_P0_RX_DP<1>")
	)
	(segment
		(start 98.301556 -289.010598)
		(end 98.232468 -288.970212)
		(width 0.1143)
		(layer "In13.Cu")
		(net "P5E_CPU1_P0_RX_DP<1>")
	)
	(segment
		(start 49.432718 -384.731006)
		(end 49.435766 -384.3528)
		(width 0.14224)
		(layer "In13.Cu")
		(net "P5E_CPU1_P0_RX_DP<1>")
	)
	(segment
		(start 124.29617 -335.19237)
		(end 122.2375 -327.002394)
		(width 0.14224)
		(layer "In13.Cu")
		(net "P5E_CPU1_P0_RX_DP<1>")
	)
	(segment
		(start 102.591108 -362.048298)
		(end 103.023416 -362.090462)
		(width 0.14224)
		(layer "In13.Cu")
		(net "P5E_CPU1_P0_RX_DP<1>")
	)
	(segment
		(start 98.232214 -291.60216)
		(end 98.301556 -291.561774)
		(width 0.1143)
		(layer "In13.Cu")
		(net "P5E_CPU1_P0_RX_DP<1>")
	)
	(segment
		(start 126.639828 -348.616524)
		(end 124.29617 -335.19237)
		(width 0.14224)
		(layer "In13.Cu")
		(net "P5E_CPU1_P0_RX_DP<1>")
	)
	(segment
		(start 113.053114 -354.922582)
		(end 113.053114 -355.727762)
		(width 0.14224)
		(layer "In13.Cu")
		(net "P5E_CPU1_P0_RX_DP<1>")
	)
	(segment
		(start 97.652078 -299.009562)
		(end 97.652078 -296.422318)
		(width 0.14224)
		(layer "In13.Cu")
		(net "P5E_CPU1_P0_RX_DP<1>")
	)
	(segment
		(start 119.7737 -353.759262)
		(end 119.91594 -353.901502)
		(width 0.14224)
		(layer "In13.Cu")
		(net "P5E_CPU1_P0_RX_DP<1>")
	)
	(segment
		(start 98.232214 -289.982148)
		(end 98.301556 -289.941762)
		(width 0.1143)
		(layer "In13.Cu")
		(net "P5E_CPU1_P0_RX_DP<1>")
	)
	(segment
		(start 109.80801 -353.576128)
		(end 110.007908 -353.59594)
		(width 0.14224)
		(layer "In13.Cu")
		(net "P5E_CPU1_P0_RX_DP<1>")
	)
	(segment
		(start 97.606358 -296.36212)
		(end 97.606358 -296.197782)
		(width 0.1143)
		(layer "In13.Cu")
		(net "P5E_CPU1_P0_RX_DP<1>")
	)
	(segment
		(start 109.5756 -308.774592)
		(end 104.635046 -306.28844)
		(width 0.14224)
		(layer "In13.Cu")
		(net "P5E_CPU1_P0_RX_DP<1>")
	)
	(segment
		(start 122.2375 -327.002394)
		(end 118.671594 -320.7131)
		(width 0.14224)
		(layer "In13.Cu")
		(net "P5E_CPU1_P0_RX_DP<1>")
	)
	(segment
		(start 112.197134 -353.901502)
		(end 112.339374 -353.759262)
		(width 0.14224)
		(layer "In13.Cu")
		(net "P5E_CPU1_P0_RX_DP<1>")
	)
	(segment
		(start 103.023416 -362.090462)
		(end 110.402116 -356.035102)
		(width 0.14224)
		(layer "In13.Cu")
		(net "P5E_CPU1_P0_RX_DP<1>")
	)
	(segment
		(start 98.301556 -293.870634)
		(end 98.232468 -293.830248)
		(width 0.1143)
		(layer "In13.Cu")
		(net "P5E_CPU1_P0_RX_DP<1>")
	)
	(segment
		(start 98.301556 -290.63061)
		(end 98.232468 -290.590224)
		(width 0.1143)
		(layer "In13.Cu")
		(net "P5E_CPU1_P0_RX_DP<1>")
	)
	(segment
		(start 97.652078 -296.40784)
		(end 97.606358 -296.36212)
		(width 0.1143)
		(layer "In13.Cu")
		(net "P5E_CPU1_P0_RX_DP<1>")
	)
	(segment
		(start 98.540316 -273.359118)
		(end 98.62312 -273.276314)
		(width 0.1143)
		(layer "In13.Cu")
		(net "P5E_CPU1_P0_RX_DP<1>")
	)
	(segment
		(start 98.30308 -274.43176)
		(end 98.233484 -274.39112)
		(width 0.1143)
		(layer "In13.Cu")
		(net "P5E_CPU1_P0_RX_DP<1>")
	)
	(segment
		(start 56.895238 -365.525304)
		(end 63.445644 -362.25353)
		(width 0.14224)
		(layer "In13.Cu")
		(net "P5E_CPU1_P0_RX_DP<1>")
	)
	(segment
		(start 55.374794 -367.036604)
		(end 55.374794 -367.03635)
		(width 0.14224)
		(layer "In13.Cu")
		(net "P5E_CPU1_P0_RX_DP<1>")
	)
	(segment
		(start 51.472846 -373.389398)
		(end 55.356252 -367.059718)
		(width 0.14224)
		(layer "In13.Cu")
		(net "P5E_CPU1_P0_RX_DP<1>")
	)
	(segment
		(start 110.007908 -353.59594)
		(end 110.371636 -354.038662)
		(width 0.14224)
		(layer "In13.Cu")
		(net "P5E_CPU1_P0_RX_DP<1>")
	)
	(segment
		(start 113.053114 -355.727762)
		(end 113.359184 -356.033832)
		(width 0.14224)
		(layer "In13.Cu")
		(net "P5E_CPU1_P0_RX_DP<1>")
	)
	(segment
		(start 113.359184 -356.033832)
		(end 120.39092 -356.033832)
		(width 0.14224)
		(layer "In13.Cu")
		(net "P5E_CPU1_P0_RX_DP<1>")
	)
	(segment
		(start 98.233484 -285.121604)
		(end 98.30308 -285.080964)
		(width 0.1143)
		(layer "In13.Cu")
		(net "P5E_CPU1_P0_RX_DP<1>")
	)
	(segment
		(start 102.122478 -360.992674)
		(end 102.08006 -361.425236)
		(width 0.14224)
		(layer "In13.Cu")
		(net "P5E_CPU1_P0_RX_DP<1>")
	)
	(segment
		(start 98.30054 -287.390078)
		(end 98.233484 -287.350962)
		(width 0.1143)
		(layer "In13.Cu")
		(net "P5E_CPU1_P0_RX_DP<1>")
	)
	(segment
		(start 118.671594 -320.7131)
		(end 110.360714 -309.524146)
		(width 0.14224)
		(layer "In13.Cu")
		(net "P5E_CPU1_P0_RX_DP<1>")
	)
	(segment
		(start 119.7737 -354.615242)
		(end 113.360454 -354.615242)
		(width 0.14224)
		(layer "In13.Cu")
		(net "P5E_CPU1_P0_RX_DP<1>")
	)
	(segment
		(start 98.233484 -277.021544)
		(end 98.30308 -276.980904)
		(width 0.1143)
		(layer "In13.Cu")
		(net "P5E_CPU1_P0_RX_DP<1>")
	)
	(segment
		(start 98.30308 -280.911808)
		(end 98.233484 -280.871168)
		(width 0.1143)
		(layer "In13.Cu")
		(net "P5E_CPU1_P0_RX_DP<1>")
	)
	(segment
		(start 49.486312 -385.649216)
		(end 49.660556 -385.548632)
		(width 0.14224)
		(layer "In13.Cu")
		(net "P5E_CPU1_P0_RX_DP<1>")
	)
	(segment
		(start 97.652078 -296.422318)
		(end 97.652078 -296.40784)
		(width 0.1143)
		(layer "In13.Cu")
		(net "P5E_CPU1_P0_RX_DP<1>")
	)
	(segment
		(start 49.435766 -384.3528)
		(end 49.740566 -384.048254)
		(width 0.14224)
		(layer "In13.Cu")
		(net "P5E_CPU1_P0_RX_DP<1>")
	)
	(segment
		(start 119.91594 -353.901502)
		(end 119.91594 -354.473002)
		(width 0.14224)
		(layer "In13.Cu")
		(net "P5E_CPU1_P0_RX_DP<1>")
	)
	(segment
		(start 98.232214 -293.222172)
		(end 98.301556 -293.181786)
		(width 0.1143)
		(layer "In13.Cu")
		(net "P5E_CPU1_P0_RX_DP<1>")
	)
	(segment
		(start 98.231452 -286.742632)
		(end 98.30308 -286.700976)
		(width 0.1143)
		(layer "In13.Cu")
		(net "P5E_CPU1_P0_RX_DP<1>")
	)
	(segment
		(start 98.232468 -294.84193)
		(end 98.301556 -294.801798)
		(width 0.1143)
		(layer "In13.Cu")
		(net "P5E_CPU1_P0_RX_DP<1>")
	)
	(arc
		(start 55.356252 -367.059718)
		(mid 55.36484 -367.047613)
		(end 55.374794 -367.036604)
		(width 0.14224)
		(layer "In13.Cu")
		(net "P5E_CPU1_P0_RX_DP<1>")
	)
	(arc
		(start 98.233484 -276.011132)
		(mid 98.076507 -275.706332)
		(end 98.233484 -275.401532)
		(width 0.1143)
		(layer "In13.Cu")
		(net "P5E_CPU1_P0_RX_DP<1>")
	)
	(arc
		(start 98.233484 -277.631144)
		(mid 98.076507 -277.326344)
		(end 98.233484 -277.021544)
		(width 0.1143)
		(layer "In13.Cu")
		(net "P5E_CPU1_P0_RX_DP<1>")
	)
	(arc
		(start 98.232468 -293.830248)
		(mid 98.076535 -293.526313)
		(end 98.232214 -293.222172)
		(width 0.1143)
		(layer "In13.Cu")
		(net "P5E_CPU1_P0_RX_DP<1>")
	)
	(arc
		(start 98.30308 -273.74088)
		(mid 98.455067 -273.584372)
		(end 98.536506 -273.381978)
		(width 0.1143)
		(layer "In13.Cu")
		(net "P5E_CPU1_P0_RX_DP<1>")
	)
	(arc
		(start 98.233484 -274.39112)
		(mid 98.076507 -274.08632)
		(end 98.233484 -273.78152)
		(width 0.1143)
		(layer "In13.Cu")
		(net "P5E_CPU1_P0_RX_DP<1>")
	)
	(arc
		(start 98.232468 -292.210236)
		(mid 98.076535 -291.906301)
		(end 98.232214 -291.60216)
		(width 0.1143)
		(layer "In13.Cu")
		(net "P5E_CPU1_P0_RX_DP<1>")
	)
	(arc
		(start 104.635046 -306.28844)
		(mid 104.460543 -306.182511)
		(end 104.3051 -306.050188)
		(width 0.14224)
		(layer "In13.Cu")
		(net "P5E_CPU1_P0_RX_DP<1>")
	)
	(arc
		(start 98.233484 -284.111192)
		(mid 98.076507 -283.806392)
		(end 98.233484 -283.501592)
		(width 0.1143)
		(layer "In13.Cu")
		(net "P5E_CPU1_P0_RX_DP<1>")
	)
	(arc
		(start 98.233484 -285.731204)
		(mid 98.076507 -285.426404)
		(end 98.233484 -285.121604)
		(width 0.1143)
		(layer "In13.Cu")
		(net "P5E_CPU1_P0_RX_DP<1>")
	)
	(arc
		(start 98.232468 -288.970212)
		(mid 98.076535 -288.666277)
		(end 98.232214 -288.362136)
		(width 0.1143)
		(layer "In13.Cu")
		(net "P5E_CPU1_P0_RX_DP<1>")
	)
	(arc
		(start 98.233484 -280.871168)
		(mid 98.076507 -280.566368)
		(end 98.233484 -280.261568)
		(width 0.1143)
		(layer "In13.Cu")
		(net "P5E_CPU1_P0_RX_DP<1>")
	)
	(arc
		(start 98.30308 -286.700976)
		(mid 98.546407 -286.23641)
		(end 98.30308 -285.771844)
		(width 0.1143)
		(layer "In13.Cu")
		(net "P5E_CPU1_P0_RX_DP<1>")
	)
	(arc
		(start 98.076512 -287.046162)
		(mid 98.117478 -286.875756)
		(end 98.231452 -286.742632)
		(width 0.1143)
		(layer "In13.Cu")
		(net "P5E_CPU1_P0_RX_DP<1>")
	)
	(arc
		(start 98.301556 -294.801798)
		(mid 98.546377 -294.336216)
		(end 98.301556 -293.870634)
		(width 0.1143)
		(layer "In13.Cu")
		(net "P5E_CPU1_P0_RX_DP<1>")
	)
	(arc
		(start 98.30308 -281.84094)
		(mid 98.546407 -281.376374)
		(end 98.30308 -280.911808)
		(width 0.1143)
		(layer "In13.Cu")
		(net "P5E_CPU1_P0_RX_DP<1>")
	)
	(arc
		(start 97.926398 -299.671486)
		(mid 97.723369 -299.367821)
		(end 97.652078 -299.009562)
		(width 0.14224)
		(layer "In13.Cu")
		(net "P5E_CPU1_P0_RX_DP<1>")
	)
	(arc
		(start 51.392074 -373.598186)
		(mid 51.422974 -373.490122)
		(end 51.472846 -373.389398)
		(width 0.14224)
		(layer "In13.Cu")
		(net "P5E_CPU1_P0_RX_DP<1>")
	)
	(arc
		(start 98.30308 -283.460952)
		(mid 98.546407 -282.996386)
		(end 98.30308 -282.53182)
		(width 0.1143)
		(layer "In13.Cu")
		(net "P5E_CPU1_P0_RX_DP<1>")
	)
	(arc
		(start 63.445644 -362.25353)
		(mid 63.47318 -362.243492)
		(end 63.502286 -362.240068)
		(width 0.14224)
		(layer "In13.Cu")
		(net "P5E_CPU1_P0_RX_DP<1>")
	)
	(arc
		(start 98.546412 -287.856422)
		(mid 98.481176 -287.592831)
		(end 98.30054 -287.390078)
		(width 0.1143)
		(layer "In13.Cu")
		(net "P5E_CPU1_P0_RX_DP<1>")
	)
	(arc
		(start 98.301556 -293.181786)
		(mid 98.546377 -292.716204)
		(end 98.301556 -292.250622)
		(width 0.1143)
		(layer "In13.Cu")
		(net "P5E_CPU1_P0_RX_DP<1>")
	)
	(arc
		(start 98.30308 -285.080964)
		(mid 98.546407 -284.616398)
		(end 98.30308 -284.151832)
		(width 0.1143)
		(layer "In13.Cu")
		(net "P5E_CPU1_P0_RX_DP<1>")
	)
	(arc
		(start 98.232468 -290.590224)
		(mid 98.076535 -290.286289)
		(end 98.232214 -289.982148)
		(width 0.1143)
		(layer "In13.Cu")
		(net "P5E_CPU1_P0_RX_DP<1>")
	)
	(arc
		(start 98.30308 -275.360892)
		(mid 98.546407 -274.896326)
		(end 98.30308 -274.43176)
		(width 0.1143)
		(layer "In13.Cu")
		(net "P5E_CPU1_P0_RX_DP<1>")
	)
	(arc
		(start 98.536506 -273.381978)
		(mid 98.538529 -273.370568)
		(end 98.540316 -273.359118)
		(width 0.1143)
		(layer "In13.Cu")
		(net "P5E_CPU1_P0_RX_DP<1>")
	)
	(arc
		(start 98.30308 -278.600916)
		(mid 98.546407 -278.13635)
		(end 98.30308 -277.671784)
		(width 0.1143)
		(layer "In13.Cu")
		(net "P5E_CPU1_P0_RX_DP<1>")
	)
	(arc
		(start 98.233484 -287.350962)
		(mid 98.118057 -287.217586)
		(end 98.076512 -287.046162)
		(width 0.1143)
		(layer "In13.Cu")
		(net "P5E_CPU1_P0_RX_DP<1>")
	)
	(arc
		(start 49.740566 -382.284986)
		(mid 49.741154 -382.272995)
		(end 49.742852 -382.26111)
		(width 0.14224)
		(layer "In13.Cu")
		(net "P5E_CPU1_P0_RX_DP<1>")
	)
	(arc
		(start 98.30308 -288.320988)
		(mid 98.481893 -288.118638)
		(end 98.546412 -287.856422)
		(width 0.1143)
		(layer "In13.Cu")
		(net "P5E_CPU1_P0_RX_DP<1>")
	)
	(arc
		(start 98.301556 -289.941762)
		(mid 98.546377 -289.47618)
		(end 98.301556 -289.010598)
		(width 0.1143)
		(layer "In13.Cu")
		(net "P5E_CPU1_P0_RX_DP<1>")
	)
	(arc
		(start 98.30308 -276.980904)
		(mid 98.546407 -276.516338)
		(end 98.30308 -276.051772)
		(width 0.1143)
		(layer "In13.Cu")
		(net "P5E_CPU1_P0_RX_DP<1>")
	)
	(arc
		(start 97.606358 -296.197782)
		(mid 97.653824 -295.959152)
		(end 97.788984 -295.756838)
		(width 0.1143)
		(layer "In13.Cu")
		(net "P5E_CPU1_P0_RX_DP<1>")
	)
	(arc
		(start 99.10699 -362.240068)
		(mid 99.244857 -362.216127)
		(end 99.366578 -362.147104)
		(width 0.14224)
		(layer "In13.Cu")
		(net "P5E_CPU1_P0_RX_DP<1>")
	)
	(arc
		(start 98.233484 -282.49118)
		(mid 98.076507 -282.18638)
		(end 98.233484 -281.88158)
		(width 0.1143)
		(layer "In13.Cu")
		(net "P5E_CPU1_P0_RX_DP<1>")
	)
	(arc
		(start 98.085148 -295.128696)
		(mid 98.12411 -294.967471)
		(end 98.232468 -294.84193)
		(width 0.1143)
		(layer "In13.Cu")
		(net "P5E_CPU1_P0_RX_DP<1>")
	)
	(arc
		(start 109.706664 -308.869334)
		(mid 109.644926 -308.816714)
		(end 109.5756 -308.774592)
		(width 0.14224)
		(layer "In13.Cu")
		(net "P5E_CPU1_P0_RX_DP<1>")
	)
	(arc
		(start 98.301556 -291.561774)
		(mid 98.546377 -291.096192)
		(end 98.301556 -290.63061)
		(width 0.1143)
		(layer "In13.Cu")
		(net "P5E_CPU1_P0_RX_DP<1>")
	)
	(arc
		(start 97.957386 -295.588436)
		(mid 98.051989 -295.446713)
		(end 98.085148 -295.279572)
		(width 0.1143)
		(layer "In13.Cu")
		(net "P5E_CPU1_P0_RX_DP<1>")
	)
	(arc
		(start 56.861964 -365.54918)
		(mid 56.877632 -365.53589)
		(end 56.895238 -365.525304)
		(width 0.14224)
		(layer "In13.Cu")
		(net "P5E_CPU1_P0_RX_DP<1>")
	)
	(arc
		(start 98.30308 -280.220928)
		(mid 98.546407 -279.756362)
		(end 98.30308 -279.291796)
		(width 0.1143)
		(layer "In13.Cu")
		(net "P5E_CPU1_P0_RX_DP<1>")
	)
	(arc
		(start 98.233484 -279.251156)
		(mid 98.076507 -278.946356)
		(end 98.233484 -278.641556)
		(width 0.1143)
		(layer "In13.Cu")
		(net "P5E_CPU1_P0_RX_DP<1>")
	)
	(segment
		(start 110.1979 -268.960346)
		(end 109.731048 -269.226284)
		(width 0.12954)
		(layer "F.Cu")
		(net "P5E_CPU1_P0_RX_DP<15>")
	)
	(segment
		(start 65.670684 -386.003292)
		(end 66.191384 -386.003292)
		(width 0.127)
		(layer "F.Cu")
		(net "P5E_CPU1_P0_RX_DP<15>")
	)
	(segment
		(start 112.134142 -376.53468)
		(end 131.632198 -376.53468)
		(width 0.14224)
		(layer "In15.Cu")
		(net "P5E_CPU1_P0_RX_DP<15>")
	)
	(segment
		(start 107.035854 -374.48236)
		(end 109.23778 -374.48236)
		(width 0.14224)
		(layer "In15.Cu")
		(net "P5E_CPU1_P0_RX_DP<15>")
	)
	(segment
		(start 109.537754 -269.5448)
		(end 109.534706 -269.543276)
		(width 0.1143)
		(layer "In15.Cu")
		(net "P5E_CPU1_P0_RX_DP<15>")
	)
	(segment
		(start 109.433106 -269.226284)
		(end 109.731048 -269.226284)
		(width 0.1143)
		(layer "In15.Cu")
		(net "P5E_CPU1_P0_RX_DP<15>")
	)
	(segment
		(start 141.96568 -374.563132)
		(end 143.535654 -376.133106)
		(width 0.14224)
		(layer "In15.Cu")
		(net "P5E_CPU1_P0_RX_DP<15>")
	)
	(segment
		(start 66.548762 -385.460494)
		(end 66.548762 -384.852418)
		(width 0.14224)
		(layer "In15.Cu")
		(net "P5E_CPU1_P0_RX_DP<15>")
	)
	(segment
		(start 136.587992 -374.515888)
		(end 141.851634 -374.515888)
		(width 0.14224)
		(layer "In15.Cu")
		(net "P5E_CPU1_P0_RX_DP<15>")
	)
	(segment
		(start 165.553644 -354.564188)
		(end 156.248354 -354.564188)
		(width 0.14224)
		(layer "In15.Cu")
		(net "P5E_CPU1_P0_RX_DP<15>")
	)
	(segment
		(start 112.05972 -301.357538)
		(end 112.05972 -295.345612)
		(width 0.14224)
		(layer "In15.Cu")
		(net "P5E_CPU1_P0_RX_DP<15>")
	)
	(segment
		(start 110.05312 -270.38173)
		(end 110.046262 -270.377666)
		(width 0.1143)
		(layer "In15.Cu")
		(net "P5E_CPU1_P0_RX_DP<15>")
	)
	(segment
		(start 153.44775 -352.587052)
		(end 135.020812 -340.274402)
		(width 0.14224)
		(layer "In15.Cu")
		(net "P5E_CPU1_P0_RX_DP<15>")
	)
	(segment
		(start 110.014004 -270.35887)
		(end 110.013242 -270.358362)
		(width 0.1143)
		(layer "In15.Cu")
		(net "P5E_CPU1_P0_RX_DP<15>")
	)
	(segment
		(start 131.788916 -376.503438)
		(end 136.587992 -374.515888)
		(width 0.14224)
		(layer "In15.Cu")
		(net "P5E_CPU1_P0_RX_DP<15>")
	)
	(segment
		(start 109.534706 -269.543276)
		(end 109.533944 -269.542768)
		(width 0.1143)
		(layer "In15.Cu")
		(net "P5E_CPU1_P0_RX_DP<15>")
	)
	(segment
		(start 66.460624 -385.548632)
		(end 66.548762 -385.460494)
		(width 0.14224)
		(layer "In15.Cu")
		(net "P5E_CPU1_P0_RX_DP<15>")
	)
	(segment
		(start 134.554722 -339.891878)
		(end 123.305824 -328.64298)
		(width 0.14224)
		(layer "In15.Cu")
		(net "P5E_CPU1_P0_RX_DP<15>")
	)
	(segment
		(start 66.28638 -385.649216)
		(end 66.460624 -385.548632)
		(width 0.14224)
		(layer "In15.Cu")
		(net "P5E_CPU1_P0_RX_DP<15>")
	)
	(segment
		(start 123.086114 -328.31405)
		(end 112.19053 -302.013874)
		(width 0.14224)
		(layer "In15.Cu")
		(net "P5E_CPU1_P0_RX_DP<15>")
	)
	(segment
		(start 170.940984 -358.704896)
		(end 167.681656 -355.445568)
		(width 0.14224)
		(layer "In15.Cu")
		(net "P5E_CPU1_P0_RX_DP<15>")
	)
	(segment
		(start 111.727234 -274.806918)
		(end 111.727234 -272.326354)
		(width 0.14224)
		(layer "In15.Cu")
		(net "P5E_CPU1_P0_RX_DP<15>")
	)
	(segment
		(start 112.05972 -295.345612)
		(end 111.727234 -274.806918)
		(width 0.14224)
		(layer "In15.Cu")
		(net "P5E_CPU1_P0_RX_DP<15>")
	)
	(segment
		(start 109.551216 -269.552674)
		(end 109.54766 -269.550642)
		(width 0.1143)
		(layer "In15.Cu")
		(net "P5E_CPU1_P0_RX_DP<15>")
	)
	(segment
		(start 66.191384 -386.003292)
		(end 66.28638 -385.649216)
		(width 0.14224)
		(layer "In15.Cu")
		(net "P5E_CPU1_P0_RX_DP<15>")
	)
	(segment
		(start 110.01502 -270.359378)
		(end 110.014004 -270.35887)
		(width 0.1143)
		(layer "In15.Cu")
		(net "P5E_CPU1_P0_RX_DP<15>")
	)
	(segment
		(start 105.160826 -378.122688)
		(end 106.512106 -374.859804)
		(width 0.14224)
		(layer "In15.Cu")
		(net "P5E_CPU1_P0_RX_DP<15>")
	)
	(segment
		(start 75.657202 -378.375418)
		(end 104.782874 -378.375418)
		(width 0.14224)
		(layer "In15.Cu")
		(net "P5E_CPU1_P0_RX_DP<15>")
	)
	(segment
		(start 109.531404 -269.541498)
		(end 109.512354 -269.530576)
		(width 0.1143)
		(layer "In15.Cu")
		(net "P5E_CPU1_P0_RX_DP<15>")
	)
	(segment
		(start 109.836712 -270.053562)
		(end 109.836712 -270.044164)
		(width 0.1143)
		(layer "In15.Cu")
		(net "P5E_CPU1_P0_RX_DP<15>")
	)
	(segment
		(start 69.16166 -382.52146)
		(end 70.596506 -382.52146)
		(width 0.14224)
		(layer "In15.Cu")
		(net "P5E_CPU1_P0_RX_DP<15>")
	)
	(segment
		(start 110.046262 -270.377666)
		(end 110.0455 -270.377158)
		(width 0.1143)
		(layer "In15.Cu")
		(net "P5E_CPU1_P0_RX_DP<15>")
	)
	(segment
		(start 110.0455 -270.377158)
		(end 110.01502 -270.359378)
		(width 0.1143)
		(layer "In15.Cu")
		(net "P5E_CPU1_P0_RX_DP<15>")
	)
	(segment
		(start 66.548762 -384.852418)
		(end 68.68033 -382.72085)
		(width 0.14224)
		(layer "In15.Cu")
		(net "P5E_CPU1_P0_RX_DP<15>")
	)
	(segment
		(start 111.14024 -271.73936)
		(end 111.075978 -271.73936)
		(width 0.1143)
		(layer "In15.Cu")
		(net "P5E_CPU1_P0_RX_DP<15>")
	)
	(segment
		(start 168.890188 -375.589546)
		(end 172.465492 -366.957864)
		(width 0.14224)
		(layer "In15.Cu")
		(net "P5E_CPU1_P0_RX_DP<15>")
	)
	(segment
		(start 109.55528 -269.555214)
		(end 109.551216 -269.552674)
		(width 0.1143)
		(layer "In15.Cu")
		(net "P5E_CPU1_P0_RX_DP<15>")
	)
	(segment
		(start 71.646288 -382.086612)
		(end 75.145646 -378.587254)
		(width 0.14224)
		(layer "In15.Cu")
		(net "P5E_CPU1_P0_RX_DP<15>")
	)
	(segment
		(start 172.51172 -366.72647)
		(end 172.51172 -361.66044)
		(width 0.14224)
		(layer "In15.Cu")
		(net "P5E_CPU1_P0_RX_DP<15>")
	)
	(segment
		(start 109.54766 -269.550642)
		(end 109.537754 -269.5448)
		(width 0.1143)
		(layer "In15.Cu")
		(net "P5E_CPU1_P0_RX_DP<15>")
	)
	(segment
		(start 109.533944 -269.542768)
		(end 109.531404 -269.541498)
		(width 0.1143)
		(layer "In15.Cu")
		(net "P5E_CPU1_P0_RX_DP<15>")
	)
	(segment
		(start 144.545812 -376.551698)
		(end 167.449754 -376.551698)
		(width 0.14224)
		(layer "In15.Cu")
		(net "P5E_CPU1_P0_RX_DP<15>")
	)
	(segment
		(start 110.535974 -271.199356)
		(end 110.453424 -271.151096)
		(width 0.1143)
		(layer "In15.Cu")
		(net "P5E_CPU1_P0_RX_DP<15>")
	)
	(segment
		(start 111.075978 -271.73936)
		(end 110.535974 -271.199356)
		(width 0.1143)
		(layer "In15.Cu")
		(net "P5E_CPU1_P0_RX_DP<15>")
	)
	(segment
		(start 106.512106 -374.859804)
		(end 106.512106 -374.860058)
		(width 0.14224)
		(layer "In15.Cu")
		(net "P5E_CPU1_P0_RX_DP<15>")
	)
	(segment
		(start 154.842464 -353.981766)
		(end 153.44775 -352.587052)
		(width 0.14224)
		(layer "In15.Cu")
		(net "P5E_CPU1_P0_RX_DP<15>")
	)
	(segment
		(start 111.160306 -271.759426)
		(end 111.14024 -271.73936)
		(width 0.1143)
		(layer "In15.Cu")
		(net "P5E_CPU1_P0_RX_DP<15>")
	)
	(segment
		(start 109.363256 -269.296134)
		(end 109.433106 -269.226284)
		(width 0.1143)
		(layer "In15.Cu")
		(net "P5E_CPU1_P0_RX_DP<15>")
	)
	(segment
		(start 109.327696 -374.519698)
		(end 110.78337 -375.975372)
		(width 0.14224)
		(layer "In15.Cu")
		(net "P5E_CPU1_P0_RX_DP<15>")
	)
	(segment
		(start 111.727234 -272.326354)
		(end 111.160306 -271.759426)
		(width 0.14224)
		(layer "In15.Cu")
		(net "P5E_CPU1_P0_RX_DP<15>")
	)
	(arc
		(start 106.512106 -374.860058)
		(mid 106.670815 -374.635105)
		(end 106.910886 -374.500394)
		(width 0.14224)
		(layer "In15.Cu")
		(net "P5E_CPU1_P0_RX_DP<15>")
	)
	(arc
		(start 143.535654 -376.133106)
		(mid 143.999103 -376.442895)
		(end 144.545812 -376.551698)
		(width 0.14224)
		(layer "In15.Cu")
		(net "P5E_CPU1_P0_RX_DP<15>")
	)
	(arc
		(start 110.296452 -270.846296)
		(mid 110.231937 -270.584077)
		(end 110.05312 -270.38173)
		(width 0.1143)
		(layer "In15.Cu")
		(net "P5E_CPU1_P0_RX_DP<15>")
	)
	(arc
		(start 75.145646 -378.587254)
		(mid 75.380364 -378.430484)
		(end 75.657202 -378.375418)
		(width 0.14224)
		(layer "In15.Cu")
		(net "P5E_CPU1_P0_RX_DP<15>")
	)
	(arc
		(start 172.49267 -361.483148)
		(mid 171.909848 -359.986217)
		(end 170.940984 -358.704896)
		(width 0.14224)
		(layer "In15.Cu")
		(net "P5E_CPU1_P0_RX_DP<15>")
	)
	(arc
		(start 109.512354 -269.530576)
		(mid 109.415219 -269.427707)
		(end 109.363256 -269.296134)
		(width 0.1143)
		(layer "In15.Cu")
		(net "P5E_CPU1_P0_RX_DP<15>")
	)
	(arc
		(start 106.910886 -374.500394)
		(mid 106.972719 -374.486864)
		(end 107.035854 -374.48236)
		(width 0.14224)
		(layer "In15.Cu")
		(net "P5E_CPU1_P0_RX_DP<15>")
	)
	(arc
		(start 141.851634 -374.515888)
		(mid 141.913357 -374.528165)
		(end 141.96568 -374.563132)
		(width 0.14224)
		(layer "In15.Cu")
		(net "P5E_CPU1_P0_RX_DP<15>")
	)
	(arc
		(start 104.782874 -378.375418)
		(mid 105.010201 -378.306411)
		(end 105.160826 -378.122688)
		(width 0.14224)
		(layer "In15.Cu")
		(net "P5E_CPU1_P0_RX_DP<15>")
	)
	(arc
		(start 68.68033 -382.72085)
		(mid 68.901166 -382.573292)
		(end 69.16166 -382.52146)
		(width 0.14224)
		(layer "In15.Cu")
		(net "P5E_CPU1_P0_RX_DP<15>")
	)
	(arc
		(start 110.013242 -270.358362)
		(mid 109.883988 -270.229692)
		(end 109.836712 -270.053562)
		(width 0.1143)
		(layer "In15.Cu")
		(net "P5E_CPU1_P0_RX_DP<15>")
	)
	(arc
		(start 135.020812 -340.274402)
		(mid 134.778365 -340.094595)
		(end 134.554722 -339.891878)
		(width 0.14224)
		(layer "In15.Cu")
		(net "P5E_CPU1_P0_RX_DP<15>")
	)
	(arc
		(start 109.836712 -270.044164)
		(mid 109.761325 -269.762091)
		(end 109.55528 -269.555214)
		(width 0.1143)
		(layer "In15.Cu")
		(net "P5E_CPU1_P0_RX_DP<15>")
	)
	(arc
		(start 110.78337 -375.975372)
		(mid 111.403124 -376.389386)
		(end 112.134142 -376.53468)
		(width 0.14224)
		(layer "In15.Cu")
		(net "P5E_CPU1_P0_RX_DP<15>")
	)
	(arc
		(start 70.596506 -382.52146)
		(mid 71.164649 -382.408449)
		(end 71.646288 -382.086612)
		(width 0.14224)
		(layer "In15.Cu")
		(net "P5E_CPU1_P0_RX_DP<15>")
	)
	(arc
		(start 131.632198 -376.53468)
		(mid 131.712092 -376.526764)
		(end 131.788916 -376.503438)
		(width 0.14224)
		(layer "In15.Cu")
		(net "P5E_CPU1_P0_RX_DP<15>")
	)
	(arc
		(start 123.305824 -328.64298)
		(mid 123.179745 -328.489349)
		(end 123.086114 -328.31405)
		(width 0.14224)
		(layer "In15.Cu")
		(net "P5E_CPU1_P0_RX_DP<15>")
	)
	(arc
		(start 167.681656 -355.445568)
		(mid 166.705302 -354.793252)
		(end 165.553644 -354.564188)
		(width 0.14224)
		(layer "In15.Cu")
		(net "P5E_CPU1_P0_RX_DP<15>")
	)
	(arc
		(start 172.51172 -361.66044)
		(mid 172.507024 -361.571275)
		(end 172.49267 -361.483148)
		(width 0.14224)
		(layer "In15.Cu")
		(net "P5E_CPU1_P0_RX_DP<15>")
	)
	(arc
		(start 172.465492 -366.957864)
		(mid 172.50003 -366.844447)
		(end 172.51172 -366.72647)
		(width 0.14224)
		(layer "In15.Cu")
		(net "P5E_CPU1_P0_RX_DP<15>")
	)
	(arc
		(start 110.453424 -271.151096)
		(mid 110.337997 -271.01772)
		(end 110.296452 -270.846296)
		(width 0.1143)
		(layer "In15.Cu")
		(net "P5E_CPU1_P0_RX_DP<15>")
	)
	(arc
		(start 112.19053 -302.013874)
		(mid 112.092803 -301.692149)
		(end 112.05972 -301.357538)
		(width 0.14224)
		(layer "In15.Cu")
		(net "P5E_CPU1_P0_RX_DP<15>")
	)
	(arc
		(start 109.23778 -374.48236)
		(mid 109.286464 -374.492062)
		(end 109.327696 -374.519698)
		(width 0.14224)
		(layer "In15.Cu")
		(net "P5E_CPU1_P0_RX_DP<15>")
	)
	(arc
		(start 156.248354 -354.564188)
		(mid 155.487474 -354.412822)
		(end 154.842464 -353.981766)
		(width 0.14224)
		(layer "In15.Cu")
		(net "P5E_CPU1_P0_RX_DP<15>")
	)
	(arc
		(start 167.449754 -376.551698)
		(mid 168.315928 -376.289113)
		(end 168.890188 -375.589546)
		(width 0.14224)
		(layer "In15.Cu")
		(net "P5E_CPU1_P0_RX_DP<15>")
	)
	(segment
		(start 110.1979 -270.580358)
		(end 109.731048 -270.846296)
		(width 0.12954)
		(layer "F.Cu")
		(net "P5E_CPU1_P0_RX_DP<14>")
	)
	(segment
		(start 64.470534 -386.003292)
		(end 64.991234 -386.003292)
		(width 0.127)
		(layer "F.Cu")
		(net "P5E_CPU1_P0_RX_DP<14>")
	)
	(segment
		(start 65.340484 -384.048254)
		(end 65.340484 -382.084326)
		(width 0.14224)
		(layer "In15.Cu")
		(net "P5E_CPU1_P0_RX_DP<14>")
	)
	(segment
		(start 110.451392 -286.742632)
		(end 110.537752 -286.69234)
		(width 0.1143)
		(layer "In15.Cu")
		(net "P5E_CPU1_P0_RX_DP<14>")
	)
	(segment
		(start 110.483904 -280.243788)
		(end 110.484412 -280.24328)
		(width 0.1143)
		(layer "In15.Cu")
		(net "P5E_CPU1_P0_RX_DP<14>")
	)
	(segment
		(start 110.484158 -288.34334)
		(end 110.523782 -288.320226)
		(width 0.1143)
		(layer "In15.Cu")
		(net "P5E_CPU1_P0_RX_DP<14>")
	)
	(segment
		(start 110.453424 -283.501592)
		(end 110.454186 -283.501084)
		(width 0.1143)
		(layer "In15.Cu")
		(net "P5E_CPU1_P0_RX_DP<14>")
	)
	(segment
		(start 110.453424 -294.841422)
		(end 110.483904 -294.823642)
		(width 0.1143)
		(layer "In15.Cu")
		(net "P5E_CPU1_P0_RX_DP<14>")
	)
	(segment
		(start 110.485174 -293.203122)
		(end 110.50524 -293.191184)
		(width 0.1143)
		(layer "In15.Cu")
		(net "P5E_CPU1_P0_RX_DP<14>")
	)
	(segment
		(start 77.08011 -367.66119)
		(end 108.820966 -367.66119)
		(width 0.14224)
		(layer "In15.Cu")
		(net "P5E_CPU1_P0_RX_DP<14>")
	)
	(segment
		(start 109.433106 -270.846296)
		(end 109.731048 -270.846296)
		(width 0.1143)
		(layer "In15.Cu")
		(net "P5E_CPU1_P0_RX_DP<14>")
	)
	(segment
		(start 110.766352 -292.716204)
		(end 110.766098 -292.716204)
		(width 0.1143)
		(layer "In15.Cu")
		(net "P5E_CPU1_P0_RX_DP<14>")
	)
	(segment
		(start 110.766098 -274.896326)
		(end 110.766098 -274.891754)
		(width 0.1143)
		(layer "In15.Cu")
		(net "P5E_CPU1_P0_RX_DP<14>")
	)
	(segment
		(start 110.453424 -273.78152)
		(end 110.524036 -273.740626)
		(width 0.1143)
		(layer "In15.Cu")
		(net "P5E_CPU1_P0_RX_DP<14>")
	)
	(segment
		(start 110.52048 -287.390078)
		(end 110.453424 -287.350962)
		(width 0.1143)
		(layer "In15.Cu")
		(net "P5E_CPU1_P0_RX_DP<14>")
	)
	(segment
		(start 110.483904 -279.268936)
		(end 110.453424 -279.251156)
		(width 0.1143)
		(layer "In15.Cu")
		(net "P5E_CPU1_P0_RX_DP<14>")
	)
	(segment
		(start 109.580426 -271.189958)
		(end 109.544104 -271.168876)
		(width 0.1143)
		(layer "In15.Cu")
		(net "P5E_CPU1_P0_RX_DP<14>")
	)
	(segment
		(start 110.520226 -289.009836)
		(end 110.483904 -288.988754)
		(width 0.1143)
		(layer "In15.Cu")
		(net "P5E_CPU1_P0_RX_DP<14>")
	)
	(segment
		(start 110.477808 -277.00732)
		(end 110.48238 -277.00478)
		(width 0.1143)
		(layer "In15.Cu")
		(net "P5E_CPU1_P0_RX_DP<14>")
	)
	(segment
		(start 110.516416 -293.18458)
		(end 110.52302 -293.18077)
		(width 0.1143)
		(layer "In15.Cu")
		(net "P5E_CPU1_P0_RX_DP<14>")
	)
	(segment
		(start 110.481872 -278.630888)
		(end 110.48619 -278.628348)
		(width 0.1143)
		(layer "In15.Cu")
		(net "P5E_CPU1_P0_RX_DP<14>")
	)
	(segment
		(start 110.451392 -288.362644)
		(end 110.483904 -288.343848)
		(width 0.1143)
		(layer "In15.Cu")
		(net "P5E_CPU1_P0_RX_DP<14>")
	)
	(segment
		(start 110.52302 -277.671784)
		(end 110.453424 -277.631144)
		(width 0.1143)
		(layer "In15.Cu")
		(net "P5E_CPU1_P0_RX_DP<14>")
	)
	(segment
		(start 110.453424 -275.401532)
		(end 110.52302 -275.360892)
		(width 0.1143)
		(layer "In15.Cu")
		(net "P5E_CPU1_P0_RX_DP<14>")
	)
	(segment
		(start 110.483904 -285.748984)
		(end 110.453424 -285.731204)
		(width 0.1143)
		(layer "In15.Cu")
		(net "P5E_CPU1_P0_RX_DP<14>")
	)
	(segment
		(start 110.561882 -293.898574)
		(end 110.52302 -293.87165)
		(width 0.1143)
		(layer "In15.Cu")
		(net "P5E_CPU1_P0_RX_DP<14>")
	)
	(segment
		(start 110.483904 -292.228778)
		(end 110.453424 -292.210998)
		(width 0.1143)
		(layer "In15.Cu")
		(net "P5E_CPU1_P0_RX_DP<14>")
	)
	(segment
		(start 168.816274 -366.97539)
		(end 169.35577 -366.435894)
		(width 0.14224)
		(layer "In15.Cu")
		(net "P5E_CPU1_P0_RX_DP<14>")
	)
	(segment
		(start 69.835268 -375.82729)
		(end 75.039728 -369.3922)
		(width 0.14224)
		(layer "In15.Cu")
		(net "P5E_CPU1_P0_RX_DP<14>")
	)
	(segment
		(start 65.260474 -385.548632)
		(end 65.348612 -385.460494)
		(width 0.14224)
		(layer "In15.Cu")
		(net "P5E_CPU1_P0_RX_DP<14>")
	)
	(segment
		(start 110.484158 -285.749238)
		(end 110.484158 -285.748984)
		(width 0.1143)
		(layer "In15.Cu")
		(net "P5E_CPU1_P0_RX_DP<14>")
	)
	(segment
		(start 110.520226 -284.150054)
		(end 110.453424 -284.111192)
		(width 0.1143)
		(layer "In15.Cu")
		(net "P5E_CPU1_P0_RX_DP<14>")
	)
	(segment
		(start 110.48238 -280.244804)
		(end 110.483904 -280.243788)
		(width 0.1143)
		(layer "In15.Cu")
		(net "P5E_CPU1_P0_RX_DP<14>")
	)
	(segment
		(start 166.13251 -355.595682)
		(end 155.034488 -355.595682)
		(width 0.14224)
		(layer "In15.Cu")
		(net "P5E_CPU1_P0_RX_DP<14>")
	)
	(segment
		(start 151.394668 -352.473006)
		(end 135.226044 -341.66937)
		(width 0.14224)
		(layer "In15.Cu")
		(net "P5E_CPU1_P0_RX_DP<14>")
	)
	(segment
		(start 110.766098 -286.236918)
		(end 110.766098 -286.23641)
		(width 0.1143)
		(layer "In15.Cu")
		(net "P5E_CPU1_P0_RX_DP<14>")
	)
	(segment
		(start 110.453424 -289.981386)
		(end 110.483904 -289.963606)
		(width 0.1143)
		(layer "In15.Cu")
		(net "P5E_CPU1_P0_RX_DP<14>")
	)
	(segment
		(start 154.19451 -355.247702)
		(end 151.53513 -352.588322)
		(width 0.14224)
		(layer "In15.Cu")
		(net "P5E_CPU1_P0_RX_DP<14>")
	)
	(segment
		(start 65.08623 -385.649216)
		(end 65.260474 -385.548632)
		(width 0.14224)
		(layer "In15.Cu")
		(net "P5E_CPU1_P0_RX_DP<14>")
	)
	(segment
		(start 110.483904 -288.988754)
		(end 110.453424 -288.970974)
		(width 0.1143)
		(layer "In15.Cu")
		(net "P5E_CPU1_P0_RX_DP<14>")
	)
	(segment
		(start 110.483904 -290.608766)
		(end 110.454186 -290.591494)
		(width 0.1143)
		(layer "In15.Cu")
		(net "P5E_CPU1_P0_RX_DP<14>")
	)
	(segment
		(start 133.946138 -340.618826)
		(end 122.253756 -328.926444)
		(width 0.14224)
		(layer "In15.Cu")
		(net "P5E_CPU1_P0_RX_DP<14>")
	)
	(segment
		(start 110.341918 -300.17466)
		(end 110.341918 -295.842182)
		(width 0.14224)
		(layer "In15.Cu")
		(net "P5E_CPU1_P0_RX_DP<14>")
	)
	(segment
		(start 75.039728 -369.3922)
		(end 76.632816 -367.799112)
		(width 0.14224)
		(layer "In15.Cu")
		(net "P5E_CPU1_P0_RX_DP<14>")
	)
	(segment
		(start 110.452154 -281.882596)
		(end 110.52302 -281.84094)
		(width 0.1143)
		(layer "In15.Cu")
		(net "P5E_CPU1_P0_RX_DP<14>")
	)
	(segment
		(start 110.45571 -276.012402)
		(end 110.453424 -276.011132)
		(width 0.1143)
		(layer "In15.Cu")
		(net "P5E_CPU1_P0_RX_DP<14>")
	)
	(segment
		(start 109.363256 -270.916146)
		(end 109.433106 -270.846296)
		(width 0.1143)
		(layer "In15.Cu")
		(net "P5E_CPU1_P0_RX_DP<14>")
	)
	(segment
		(start 110.452154 -285.12262)
		(end 110.52429 -285.080202)
		(width 0.1143)
		(layer "In15.Cu")
		(net "P5E_CPU1_P0_RX_DP<14>")
	)
	(segment
		(start 109.544104 -271.168876)
		(end 109.512354 -271.150588)
		(width 0.1143)
		(layer "In15.Cu")
		(net "P5E_CPU1_P0_RX_DP<14>")
	)
	(segment
		(start 110.50524 -293.191184)
		(end 110.505494 -293.191184)
		(width 0.1143)
		(layer "In15.Cu")
		(net "P5E_CPU1_P0_RX_DP<14>")
	)
	(segment
		(start 65.348612 -385.460494)
		(end 65.348612 -385.046982)
		(width 0.14224)
		(layer "In15.Cu")
		(net "P5E_CPU1_P0_RX_DP<14>")
	)
	(segment
		(start 110.454186 -283.501084)
		(end 110.483904 -283.483812)
		(width 0.1143)
		(layer "In15.Cu")
		(net "P5E_CPU1_P0_RX_DP<14>")
	)
	(segment
		(start 110.531402 -292.25748)
		(end 110.483904 -292.228778)
		(width 0.1143)
		(layer "In15.Cu")
		(net "P5E_CPU1_P0_RX_DP<14>")
	)
	(segment
		(start 110.483904 -289.963606)
		(end 110.520226 -289.942524)
		(width 0.1143)
		(layer "In15.Cu")
		(net "P5E_CPU1_P0_RX_DP<14>")
	)
	(segment
		(start 110.505494 -293.191184)
		(end 110.516416 -293.18458)
		(width 0.1143)
		(layer "In15.Cu")
		(net "P5E_CPU1_P0_RX_DP<14>")
	)
	(segment
		(start 110.537752 -286.69234)
		(end 110.546388 -286.683704)
		(width 0.1143)
		(layer "In15.Cu")
		(net "P5E_CPU1_P0_RX_DP<14>")
	)
	(segment
		(start 110.296198 -295.768014)
		(end 110.296198 -295.146222)
		(width 0.1143)
		(layer "In15.Cu")
		(net "P5E_CPU1_P0_RX_DP<14>")
	)
	(segment
		(start 110.453424 -280.261568)
		(end 110.477808 -280.247344)
		(width 0.1143)
		(layer "In15.Cu")
		(net "P5E_CPU1_P0_RX_DP<14>")
	)
	(segment
		(start 110.484412 -276.02942)
		(end 110.483904 -276.028912)
		(width 0.1143)
		(layer "In15.Cu")
		(net "P5E_CPU1_P0_RX_DP<14>")
	)
	(segment
		(start 110.45317 -294.841422)
		(end 110.453424 -294.841422)
		(width 0.1143)
		(layer "In15.Cu")
		(net "P5E_CPU1_P0_RX_DP<14>")
	)
	(segment
		(start 110.766098 -284.628844)
		(end 110.766098 -284.616398)
		(width 0.1143)
		(layer "In15.Cu")
		(net "P5E_CPU1_P0_RX_DP<14>")
	)
	(segment
		(start 110.453424 -291.601398)
		(end 110.483904 -291.583618)
		(width 0.1143)
		(layer "In15.Cu")
		(net "P5E_CPU1_P0_RX_DP<14>")
	)
	(segment
		(start 169.265854 -358.729026)
		(end 166.13251 -355.595682)
		(width 0.14224)
		(layer "In15.Cu")
		(net "P5E_CPU1_P0_RX_DP<14>")
	)
	(segment
		(start 110.453424 -272.770854)
		(end 110.453424 -272.771108)
		(width 0.1143)
		(layer "In15.Cu")
		(net "P5E_CPU1_P0_RX_DP<14>")
	)
	(segment
		(start 122.062748 -328.640694)
		(end 110.408466 -300.508924)
		(width 0.14224)
		(layer "In15.Cu")
		(net "P5E_CPU1_P0_RX_DP<14>")
	)
	(segment
		(start 110.483904 -288.343848)
		(end 110.484158 -288.34334)
		(width 0.1143)
		(layer "In15.Cu")
		(net "P5E_CPU1_P0_RX_DP<14>")
	)
	(segment
		(start 110.52429 -274.432776)
		(end 110.453424 -274.39112)
		(width 0.1143)
		(layer "In15.Cu")
		(net "P5E_CPU1_P0_RX_DP<14>")
	)
	(segment
		(start 110.341918 -295.813734)
		(end 110.296198 -295.768014)
		(width 0.1143)
		(layer "In15.Cu")
		(net "P5E_CPU1_P0_RX_DP<14>")
	)
	(segment
		(start 110.766352 -274.896326)
		(end 110.766098 -274.896326)
		(width 0.1143)
		(layer "In15.Cu")
		(net "P5E_CPU1_P0_RX_DP<14>")
	)
	(segment
		(start 110.483904 -276.028912)
		(end 110.45571 -276.012402)
		(width 0.1143)
		(layer "In15.Cu")
		(net "P5E_CPU1_P0_RX_DP<14>")
	)
	(segment
		(start 65.035684 -384.3528)
		(end 65.340484 -384.048254)
		(width 0.14224)
		(layer "In15.Cu")
		(net "P5E_CPU1_P0_RX_DP<14>")
	)
	(segment
		(start 110.483904 -277.003764)
		(end 110.484412 -277.003256)
		(width 0.1143)
		(layer "In15.Cu")
		(net "P5E_CPU1_P0_RX_DP<14>")
	)
	(segment
		(start 110.477808 -280.247344)
		(end 110.48238 -280.244804)
		(width 0.1143)
		(layer "In15.Cu")
		(net "P5E_CPU1_P0_RX_DP<14>")
	)
	(segment
		(start 65.348612 -385.046982)
		(end 65.032636 -384.731006)
		(width 0.14224)
		(layer "In15.Cu")
		(net "P5E_CPU1_P0_RX_DP<14>")
	)
	(segment
		(start 110.766098 -292.716204)
		(end 110.766098 -292.702996)
		(width 0.1143)
		(layer "In15.Cu")
		(net "P5E_CPU1_P0_RX_DP<14>")
	)
	(segment
		(start 110.05312 -272.001488)
		(end 109.99089 -271.96542)
		(width 0.1143)
		(layer "In15.Cu")
		(net "P5E_CPU1_P0_RX_DP<14>")
	)
	(segment
		(start 110.484158 -293.20363)
		(end 110.485174 -293.203122)
		(width 0.1143)
		(layer "In15.Cu")
		(net "P5E_CPU1_P0_RX_DP<14>")
	)
	(segment
		(start 110.52429 -272.812256)
		(end 110.453424 -272.770854)
		(width 0.1143)
		(layer "In15.Cu")
		(net "P5E_CPU1_P0_RX_DP<14>")
	)
	(segment
		(start 169.555414 -365.953802)
		(end 169.555414 -359.428288)
		(width 0.14224)
		(layer "In15.Cu")
		(net "P5E_CPU1_P0_RX_DP<14>")
	)
	(segment
		(start 110.520226 -282.530042)
		(end 110.453424 -282.49118)
		(width 0.1143)
		(layer "In15.Cu")
		(net "P5E_CPU1_P0_RX_DP<14>")
	)
	(segment
		(start 110.484412 -279.269444)
		(end 110.483904 -279.268936)
		(width 0.1143)
		(layer "In15.Cu")
		(net "P5E_CPU1_P0_RX_DP<14>")
	)
	(segment
		(start 110.483904 -283.483812)
		(end 110.520226 -283.46273)
		(width 0.1143)
		(layer "In15.Cu")
		(net "P5E_CPU1_P0_RX_DP<14>")
	)
	(segment
		(start 110.483904 -291.583618)
		(end 110.520226 -291.562536)
		(width 0.1143)
		(layer "In15.Cu")
		(net "P5E_CPU1_P0_RX_DP<14>")
	)
	(segment
		(start 110.533434 -272.819114)
		(end 110.52429 -272.812256)
		(width 0.1143)
		(layer "In15.Cu")
		(net "P5E_CPU1_P0_RX_DP<14>")
	)
	(segment
		(start 110.48238 -277.00478)
		(end 110.483904 -277.003764)
		(width 0.1143)
		(layer "In15.Cu")
		(net "P5E_CPU1_P0_RX_DP<14>")
	)
	(segment
		(start 110.454186 -290.591494)
		(end 110.453424 -290.590986)
		(width 0.1143)
		(layer "In15.Cu")
		(net "P5E_CPU1_P0_RX_DP<14>")
	)
	(segment
		(start 110.484158 -285.748984)
		(end 110.483904 -285.748984)
		(width 0.1143)
		(layer "In15.Cu")
		(net "P5E_CPU1_P0_RX_DP<14>")
	)
	(segment
		(start 110.453424 -277.021544)
		(end 110.477808 -277.00732)
		(width 0.1143)
		(layer "In15.Cu")
		(net "P5E_CPU1_P0_RX_DP<14>")
	)
	(segment
		(start 110.520226 -290.629848)
		(end 110.483904 -290.608766)
		(width 0.1143)
		(layer "In15.Cu")
		(net "P5E_CPU1_P0_RX_DP<14>")
	)
	(segment
		(start 110.521496 -293.870634)
		(end 110.47603 -293.843964)
		(width 0.1143)
		(layer "In15.Cu")
		(net "P5E_CPU1_P0_RX_DP<14>")
	)
	(segment
		(start 110.483904 -294.823642)
		(end 110.561882 -294.773858)
		(width 0.1143)
		(layer "In15.Cu")
		(net "P5E_CPU1_P0_RX_DP<14>")
	)
	(segment
		(start 110.341918 -295.842182)
		(end 110.341918 -295.813734)
		(width 0.1143)
		(layer "In15.Cu")
		(net "P5E_CPU1_P0_RX_DP<14>")
	)
	(segment
		(start 110.640622 -367.149634)
		(end 168.39565 -367.149634)
		(width 0.14224)
		(layer "In15.Cu")
		(net "P5E_CPU1_P0_RX_DP<14>")
	)
	(segment
		(start 65.032636 -384.731006)
		(end 65.035684 -384.3528)
		(width 0.14224)
		(layer "In15.Cu")
		(net "P5E_CPU1_P0_RX_DP<14>")
	)
	(segment
		(start 110.521496 -285.770828)
		(end 110.484158 -285.749238)
		(width 0.1143)
		(layer "In15.Cu")
		(net "P5E_CPU1_P0_RX_DP<14>")
	)
	(segment
		(start 110.52302 -280.911808)
		(end 110.453424 -280.871168)
		(width 0.1143)
		(layer "In15.Cu")
		(net "P5E_CPU1_P0_RX_DP<14>")
	)
	(segment
		(start 65.364614 -382.00965)
		(end 69.835268 -375.82729)
		(width 0.14224)
		(layer "In15.Cu")
		(net "P5E_CPU1_P0_RX_DP<14>")
	)
	(segment
		(start 64.991234 -386.003292)
		(end 65.08623 -385.649216)
		(width 0.14224)
		(layer "In15.Cu")
		(net "P5E_CPU1_P0_RX_DP<14>")
	)
	(arc
		(start 110.52302 -281.84094)
		(mid 110.529016 -281.836787)
		(end 110.534958 -281.832558)
		(width 0.1143)
		(layer "In15.Cu")
		(net "P5E_CPU1_P0_RX_DP<14>")
	)
	(arc
		(start 110.296198 -295.146222)
		(mid 110.337747 -294.9748)
		(end 110.45317 -294.841422)
		(width 0.1143)
		(layer "In15.Cu")
		(net "P5E_CPU1_P0_RX_DP<14>")
	)
	(arc
		(start 110.765844 -292.737286)
		(mid 110.766196 -292.726747)
		(end 110.766352 -292.716204)
		(width 0.1143)
		(layer "In15.Cu")
		(net "P5E_CPU1_P0_RX_DP<14>")
	)
	(arc
		(start 110.453424 -274.39112)
		(mid 110.296447 -274.08632)
		(end 110.453424 -273.78152)
		(width 0.1143)
		(layer "In15.Cu")
		(net "P5E_CPU1_P0_RX_DP<14>")
	)
	(arc
		(start 110.453424 -279.251156)
		(mid 110.298764 -278.933255)
		(end 110.481872 -278.630888)
		(width 0.1143)
		(layer "In15.Cu")
		(net "P5E_CPU1_P0_RX_DP<14>")
	)
	(arc
		(start 110.453424 -280.871168)
		(mid 110.296447 -280.566368)
		(end 110.453424 -280.261568)
		(width 0.1143)
		(layer "In15.Cu")
		(net "P5E_CPU1_P0_RX_DP<14>")
	)
	(arc
		(start 110.762796 -273.21129)
		(mid 110.689699 -272.990875)
		(end 110.533434 -272.819114)
		(width 0.1143)
		(layer "In15.Cu")
		(net "P5E_CPU1_P0_RX_DP<14>")
	)
	(arc
		(start 109.826298 -271.641316)
		(mid 109.760678 -271.391798)
		(end 109.591094 -271.197324)
		(width 0.1143)
		(layer "In15.Cu")
		(net "P5E_CPU1_P0_RX_DP<14>")
	)
	(arc
		(start 109.99089 -271.96542)
		(mid 109.88269 -271.830018)
		(end 109.82833 -271.665446)
		(width 0.1143)
		(layer "In15.Cu")
		(net "P5E_CPU1_P0_RX_DP<14>")
	)
	(arc
		(start 76.632816 -367.799112)
		(mid 76.749697 -367.715339)
		(end 76.887324 -367.673636)
		(width 0.14224)
		(layer "In15.Cu")
		(net "P5E_CPU1_P0_RX_DP<14>")
	)
	(arc
		(start 110.766098 -274.891754)
		(mid 110.702023 -274.63231)
		(end 110.52429 -274.432776)
		(width 0.1143)
		(layer "In15.Cu")
		(net "P5E_CPU1_P0_RX_DP<14>")
	)
	(arc
		(start 65.340484 -382.084326)
		(mid 65.346671 -382.04509)
		(end 65.364614 -382.00965)
		(width 0.14224)
		(layer "In15.Cu")
		(net "P5E_CPU1_P0_RX_DP<14>")
	)
	(arc
		(start 76.887324 -367.673636)
		(mid 76.983516 -367.664308)
		(end 77.08011 -367.66119)
		(width 0.14224)
		(layer "In15.Cu")
		(net "P5E_CPU1_P0_RX_DP<14>")
	)
	(arc
		(start 110.520226 -289.942524)
		(mid 110.766116 -289.47618)
		(end 110.520226 -289.009836)
		(width 0.1143)
		(layer "In15.Cu")
		(net "P5E_CPU1_P0_RX_DP<14>")
	)
	(arc
		(start 122.253756 -328.926444)
		(mid 122.144176 -328.792977)
		(end 122.062748 -328.640694)
		(width 0.14224)
		(layer "In15.Cu")
		(net "P5E_CPU1_P0_RX_DP<14>")
	)
	(arc
		(start 110.453424 -288.970974)
		(mid 110.337997 -288.837598)
		(end 110.296452 -288.666174)
		(width 0.1143)
		(layer "In15.Cu")
		(net "P5E_CPU1_P0_RX_DP<14>")
	)
	(arc
		(start 110.453424 -272.771108)
		(mid 110.337905 -272.637751)
		(end 110.296198 -272.466308)
		(width 0.1143)
		(layer "In15.Cu")
		(net "P5E_CPU1_P0_RX_DP<14>")
	)
	(arc
		(start 135.226044 -341.66937)
		(mid 134.560288 -341.175535)
		(end 133.946138 -340.618826)
		(width 0.14224)
		(layer "In15.Cu")
		(net "P5E_CPU1_P0_RX_DP<14>")
	)
	(arc
		(start 169.35577 -366.435894)
		(mid 169.503508 -366.214694)
		(end 169.555414 -365.953802)
		(width 0.14224)
		(layer "In15.Cu")
		(net "P5E_CPU1_P0_RX_DP<14>")
	)
	(arc
		(start 109.730794 -367.405412)
		(mid 110.168067 -367.21476)
		(end 110.640622 -367.149634)
		(width 0.14224)
		(layer "In15.Cu")
		(net "P5E_CPU1_P0_RX_DP<14>")
	)
	(arc
		(start 110.520226 -291.562536)
		(mid 110.766116 -291.096192)
		(end 110.520226 -290.629848)
		(width 0.1143)
		(layer "In15.Cu")
		(net "P5E_CPU1_P0_RX_DP<14>")
	)
	(arc
		(start 110.453424 -290.590986)
		(mid 110.296447 -290.286186)
		(end 110.453424 -289.981386)
		(width 0.1143)
		(layer "In15.Cu")
		(net "P5E_CPU1_P0_RX_DP<14>")
	)
	(arc
		(start 109.591094 -271.197324)
		(mid 109.58578 -271.193612)
		(end 109.580426 -271.189958)
		(width 0.1143)
		(layer "In15.Cu")
		(net "P5E_CPU1_P0_RX_DP<14>")
	)
	(arc
		(start 110.766606 -273.276314)
		(mid 110.765638 -273.243747)
		(end 110.762796 -273.21129)
		(width 0.1143)
		(layer "In15.Cu")
		(net "P5E_CPU1_P0_RX_DP<14>")
	)
	(arc
		(start 110.484412 -280.24328)
		(mid 110.763863 -279.756362)
		(end 110.484412 -279.269444)
		(width 0.1143)
		(layer "In15.Cu")
		(net "P5E_CPU1_P0_RX_DP<14>")
	)
	(arc
		(start 110.48619 -278.628348)
		(mid 110.766972 -278.160189)
		(end 110.52302 -277.671784)
		(width 0.1143)
		(layer "In15.Cu")
		(net "P5E_CPU1_P0_RX_DP<14>")
	)
	(arc
		(start 155.034488 -355.595682)
		(mid 154.57989 -355.505239)
		(end 154.19451 -355.247702)
		(width 0.14224)
		(layer "In15.Cu")
		(net "P5E_CPU1_P0_RX_DP<14>")
	)
	(arc
		(start 110.453424 -287.350962)
		(mid 110.337997 -287.217586)
		(end 110.296452 -287.046162)
		(width 0.1143)
		(layer "In15.Cu")
		(net "P5E_CPU1_P0_RX_DP<14>")
	)
	(arc
		(start 110.453424 -277.631144)
		(mid 110.296447 -277.326344)
		(end 110.453424 -277.021544)
		(width 0.1143)
		(layer "In15.Cu")
		(net "P5E_CPU1_P0_RX_DP<14>")
	)
	(arc
		(start 110.520226 -283.46273)
		(mid 110.766116 -282.996386)
		(end 110.520226 -282.530042)
		(width 0.1143)
		(layer "In15.Cu")
		(net "P5E_CPU1_P0_RX_DP<14>")
	)
	(arc
		(start 110.296452 -288.666174)
		(mid 110.337418 -288.495768)
		(end 110.451392 -288.362644)
		(width 0.1143)
		(layer "In15.Cu")
		(net "P5E_CPU1_P0_RX_DP<14>")
	)
	(arc
		(start 110.523782 -288.320226)
		(mid 110.690348 -288.113318)
		(end 110.766098 -287.858708)
		(width 0.1143)
		(layer "In15.Cu")
		(net "P5E_CPU1_P0_RX_DP<14>")
	)
	(arc
		(start 151.53513 -352.588322)
		(mid 151.467731 -352.527214)
		(end 151.394668 -352.473006)
		(width 0.14224)
		(layer "In15.Cu")
		(net "P5E_CPU1_P0_RX_DP<14>")
	)
	(arc
		(start 110.76559 -284.63367)
		(mid 110.765849 -284.631258)
		(end 110.766098 -284.628844)
		(width 0.1143)
		(layer "In15.Cu")
		(net "P5E_CPU1_P0_RX_DP<14>")
	)
	(arc
		(start 110.47603 -293.843964)
		(mid 110.299122 -293.521483)
		(end 110.484158 -293.20363)
		(width 0.1143)
		(layer "In15.Cu")
		(net "P5E_CPU1_P0_RX_DP<14>")
	)
	(arc
		(start 110.524036 -273.740626)
		(mid 110.702388 -273.538268)
		(end 110.766606 -273.276314)
		(width 0.1143)
		(layer "In15.Cu")
		(net "P5E_CPU1_P0_RX_DP<14>")
	)
	(arc
		(start 110.762288 -287.790128)
		(mid 110.684724 -287.563893)
		(end 110.52048 -287.390078)
		(width 0.1143)
		(layer "In15.Cu")
		(net "P5E_CPU1_P0_RX_DP<14>")
	)
	(arc
		(start 110.296452 -287.046162)
		(mid 110.337418 -286.875756)
		(end 110.451392 -286.742632)
		(width 0.1143)
		(layer "In15.Cu")
		(net "P5E_CPU1_P0_RX_DP<14>")
	)
	(arc
		(start 109.512354 -271.150588)
		(mid 109.415219 -271.047719)
		(end 109.363256 -270.916146)
		(width 0.1143)
		(layer "In15.Cu")
		(net "P5E_CPU1_P0_RX_DP<14>")
	)
	(arc
		(start 110.453424 -284.111192)
		(mid 110.296447 -283.806392)
		(end 110.453424 -283.501592)
		(width 0.1143)
		(layer "In15.Cu")
		(net "P5E_CPU1_P0_RX_DP<14>")
	)
	(arc
		(start 110.534958 -281.832558)
		(mid 110.763355 -281.376374)
		(end 110.534958 -280.92019)
		(width 0.1143)
		(layer "In15.Cu")
		(net "P5E_CPU1_P0_RX_DP<14>")
	)
	(arc
		(start 110.52302 -293.18077)
		(mid 110.696853 -292.987716)
		(end 110.765844 -292.737286)
		(width 0.1143)
		(layer "In15.Cu")
		(net "P5E_CPU1_P0_RX_DP<14>")
	)
	(arc
		(start 110.561882 -294.773858)
		(mid 110.79106 -294.336216)
		(end 110.561882 -293.898574)
		(width 0.1143)
		(layer "In15.Cu")
		(net "P5E_CPU1_P0_RX_DP<14>")
	)
	(arc
		(start 110.766098 -287.858708)
		(mid 110.765238 -287.82436)
		(end 110.762288 -287.790128)
		(width 0.1143)
		(layer "In15.Cu")
		(net "P5E_CPU1_P0_RX_DP<14>")
	)
	(arc
		(start 110.546388 -286.683704)
		(mid 110.708198 -286.485861)
		(end 110.766098 -286.236918)
		(width 0.1143)
		(layer "In15.Cu")
		(net "P5E_CPU1_P0_RX_DP<14>")
	)
	(arc
		(start 110.52302 -293.87165)
		(mid 110.522258 -293.871141)
		(end 110.521496 -293.870634)
		(width 0.1143)
		(layer "In15.Cu")
		(net "P5E_CPU1_P0_RX_DP<14>")
	)
	(arc
		(start 110.766098 -292.702996)
		(mid 110.703894 -292.451187)
		(end 110.531402 -292.25748)
		(width 0.1143)
		(layer "In15.Cu")
		(net "P5E_CPU1_P0_RX_DP<14>")
	)
	(arc
		(start 169.555414 -359.428288)
		(mid 169.480159 -359.049868)
		(end 169.265854 -358.729026)
		(width 0.14224)
		(layer "In15.Cu")
		(net "P5E_CPU1_P0_RX_DP<14>")
	)
	(arc
		(start 109.82833 -271.665446)
		(mid 109.827021 -271.653406)
		(end 109.826298 -271.641316)
		(width 0.1143)
		(layer "In15.Cu")
		(net "P5E_CPU1_P0_RX_DP<14>")
	)
	(arc
		(start 168.39565 -367.149634)
		(mid 168.623296 -367.104352)
		(end 168.816274 -366.97539)
		(width 0.14224)
		(layer "In15.Cu")
		(net "P5E_CPU1_P0_RX_DP<14>")
	)
	(arc
		(start 110.765844 -274.917408)
		(mid 110.766196 -274.906869)
		(end 110.766352 -274.896326)
		(width 0.1143)
		(layer "In15.Cu")
		(net "P5E_CPU1_P0_RX_DP<14>")
	)
	(arc
		(start 110.52429 -285.080202)
		(mid 110.534277 -285.072945)
		(end 110.544102 -285.06547)
		(width 0.1143)
		(layer "In15.Cu")
		(net "P5E_CPU1_P0_RX_DP<14>")
	)
	(arc
		(start 110.453424 -276.011132)
		(mid 110.296447 -275.706332)
		(end 110.453424 -275.401532)
		(width 0.1143)
		(layer "In15.Cu")
		(net "P5E_CPU1_P0_RX_DP<14>")
	)
	(arc
		(start 110.534958 -280.92019)
		(mid 110.529016 -280.91596)
		(end 110.52302 -280.911808)
		(width 0.1143)
		(layer "In15.Cu")
		(net "P5E_CPU1_P0_RX_DP<14>")
	)
	(arc
		(start 110.766098 -284.616398)
		(mid 110.700862 -284.352807)
		(end 110.520226 -284.150054)
		(width 0.1143)
		(layer "In15.Cu")
		(net "P5E_CPU1_P0_RX_DP<14>")
	)
	(arc
		(start 110.52302 -275.360892)
		(mid 110.696853 -275.167838)
		(end 110.765844 -274.917408)
		(width 0.1143)
		(layer "In15.Cu")
		(net "P5E_CPU1_P0_RX_DP<14>")
	)
	(arc
		(start 110.453424 -282.49118)
		(mid 110.296554 -282.187192)
		(end 110.452154 -281.882596)
		(width 0.1143)
		(layer "In15.Cu")
		(net "P5E_CPU1_P0_RX_DP<14>")
	)
	(arc
		(start 108.820966 -367.66119)
		(mid 109.293513 -367.596027)
		(end 109.730794 -367.405412)
		(width 0.14224)
		(layer "In15.Cu")
		(net "P5E_CPU1_P0_RX_DP<14>")
	)
	(arc
		(start 110.453424 -292.210998)
		(mid 110.296447 -291.906198)
		(end 110.453424 -291.601398)
		(width 0.1143)
		(layer "In15.Cu")
		(net "P5E_CPU1_P0_RX_DP<14>")
	)
	(arc
		(start 110.453424 -285.731204)
		(mid 110.296554 -285.427216)
		(end 110.452154 -285.12262)
		(width 0.1143)
		(layer "In15.Cu")
		(net "P5E_CPU1_P0_RX_DP<14>")
	)
	(arc
		(start 110.766098 -286.23641)
		(mid 110.70128 -285.973421)
		(end 110.521496 -285.770828)
		(width 0.1143)
		(layer "In15.Cu")
		(net "P5E_CPU1_P0_RX_DP<14>")
	)
	(arc
		(start 110.484412 -277.003256)
		(mid 110.763863 -276.516338)
		(end 110.484412 -276.02942)
		(width 0.1143)
		(layer "In15.Cu")
		(net "P5E_CPU1_P0_RX_DP<14>")
	)
	(arc
		(start 110.296198 -272.466308)
		(mid 110.23181 -272.204015)
		(end 110.05312 -272.001488)
		(width 0.1143)
		(layer "In15.Cu")
		(net "P5E_CPU1_P0_RX_DP<14>")
	)
	(arc
		(start 110.408466 -300.508924)
		(mid 110.358759 -300.345067)
		(end 110.341918 -300.17466)
		(width 0.14224)
		(layer "In15.Cu")
		(net "P5E_CPU1_P0_RX_DP<14>")
	)
	(arc
		(start 110.544102 -285.06547)
		(mid 110.698661 -284.872044)
		(end 110.76559 -284.63367)
		(width 0.1143)
		(layer "In15.Cu")
		(net "P5E_CPU1_P0_RX_DP<14>")
	)
	(segment
		(start 110.1979 -273.820382)
		(end 109.731048 -274.08632)
		(width 0.12954)
		(layer "F.Cu")
		(net "P5E_CPU1_P0_RX_DP<13>")
	)
	(segment
		(start 63.270638 -386.003292)
		(end 63.791338 -386.003292)
		(width 0.127)
		(layer "F.Cu")
		(net "P5E_CPU1_P0_RX_DP<13>")
	)
	(segment
		(start 165.763702 -356.803706)
		(end 155.078176 -356.803706)
		(width 0.14224)
		(layer "In15.Cu")
		(net "P5E_CPU1_P0_RX_DP<13>")
	)
	(segment
		(start 109.540802 -292.227)
		(end 109.54004 -292.226492)
		(width 0.1143)
		(layer "In15.Cu")
		(net "P5E_CPU1_P0_RX_DP<13>")
	)
	(segment
		(start 132.88645 -341.005668)
		(end 121.627138 -329.746356)
		(width 0.14224)
		(layer "In15.Cu")
		(net "P5E_CPU1_P0_RX_DP<13>")
	)
	(segment
		(start 109.65688 -287.459928)
		(end 109.518958 -287.36163)
		(width 0.1143)
		(layer "In15.Cu")
		(net "P5E_CPU1_P0_RX_DP<13>")
	)
	(segment
		(start 109.512354 -285.122112)
		(end 109.544104 -285.103824)
		(width 0.1143)
		(layer "In15.Cu")
		(net "P5E_CPU1_P0_RX_DP<13>")
	)
	(segment
		(start 168.361868 -359.181654)
		(end 166.139622 -356.959408)
		(width 0.14224)
		(layer "In15.Cu")
		(net "P5E_CPU1_P0_RX_DP<13>")
	)
	(segment
		(start 64.060578 -385.548632)
		(end 64.148716 -385.460494)
		(width 0.14224)
		(layer "In15.Cu")
		(net "P5E_CPU1_P0_RX_DP<13>")
	)
	(segment
		(start 109.582966 -293.181024)
		(end 109.610906 -293.160958)
		(width 0.1143)
		(layer "In15.Cu")
		(net "P5E_CPU1_P0_RX_DP<13>")
	)
	(segment
		(start 109.580426 -282.530042)
		(end 109.578902 -282.529026)
		(width 0.1143)
		(layer "In15.Cu")
		(net "P5E_CPU1_P0_RX_DP<13>")
	)
	(segment
		(start 109.56544 -274.421346)
		(end 109.512354 -274.390612)
		(width 0.1143)
		(layer "In15.Cu")
		(net "P5E_CPU1_P0_RX_DP<13>")
	)
	(segment
		(start 109.551724 -293.199312)
		(end 109.553248 -293.198296)
		(width 0.1143)
		(layer "In15.Cu")
		(net "P5E_CPU1_P0_RX_DP<13>")
	)
	(segment
		(start 109.564678 -293.860728)
		(end 109.512354 -293.830502)
		(width 0.1143)
		(layer "In15.Cu")
		(net "P5E_CPU1_P0_RX_DP<13>")
	)
	(segment
		(start 64.140588 -384.048)
		(end 64.140588 -382.197864)
		(width 0.14224)
		(layer "In15.Cu")
		(net "P5E_CPU1_P0_RX_DP<13>")
	)
	(segment
		(start 109.578902 -282.529026)
		(end 109.544104 -282.50896)
		(width 0.1143)
		(layer "In15.Cu")
		(net "P5E_CPU1_P0_RX_DP<13>")
	)
	(segment
		(start 63.83274 -384.731006)
		(end 63.835788 -384.3528)
		(width 0.14224)
		(layer "In15.Cu")
		(net "P5E_CPU1_P0_RX_DP<13>")
	)
	(segment
		(start 64.148716 -385.046982)
		(end 63.83274 -384.731006)
		(width 0.14224)
		(layer "In15.Cu")
		(net "P5E_CPU1_P0_RX_DP<13>")
	)
	(segment
		(start 109.534198 -280.883106)
		(end 109.532928 -280.882344)
		(width 0.1143)
		(layer "In15.Cu")
		(net "P5E_CPU1_P0_RX_DP<13>")
	)
	(segment
		(start 109.401864 -295.882822)
		(end 109.356144 -295.837102)
		(width 0.1143)
		(layer "In15.Cu")
		(net "P5E_CPU1_P0_RX_DP<13>")
	)
	(segment
		(start 69.115178 -375.12117)
		(end 74.289412 -368.693954)
		(width 0.14224)
		(layer "In15.Cu")
		(net "P5E_CPU1_P0_RX_DP<13>")
	)
	(segment
		(start 142.711932 -347.819218)
		(end 142.711932 -347.819472)
		(width 0.14224)
		(layer "In15.Cu")
		(net "P5E_CPU1_P0_RX_DP<13>")
	)
	(segment
		(start 109.527848 -293.21252)
		(end 109.54512 -293.202868)
		(width 0.1143)
		(layer "In15.Cu")
		(net "P5E_CPU1_P0_RX_DP<13>")
	)
	(segment
		(start 109.580426 -284.150054)
		(end 109.544104 -284.128972)
		(width 0.1143)
		(layer "In15.Cu")
		(net "P5E_CPU1_P0_RX_DP<13>")
	)
	(segment
		(start 109.544104 -291.583618)
		(end 109.580426 -291.562536)
		(width 0.1143)
		(layer "In15.Cu")
		(net "P5E_CPU1_P0_RX_DP<13>")
	)
	(segment
		(start 109.508798 -286.74441)
		(end 109.511338 -286.742886)
		(width 0.1143)
		(layer "In15.Cu")
		(net "P5E_CPU1_P0_RX_DP<13>")
	)
	(segment
		(start 109.512354 -277.022052)
		(end 109.544104 -277.003764)
		(width 0.1143)
		(layer "In15.Cu")
		(net "P5E_CPU1_P0_RX_DP<13>")
	)
	(segment
		(start 109.564678 -280.23185)
		(end 109.56544 -280.231342)
		(width 0.1143)
		(layer "In15.Cu")
		(net "P5E_CPU1_P0_RX_DP<13>")
	)
	(segment
		(start 109.5375 -292.225222)
		(end 109.536738 -292.224714)
		(width 0.1143)
		(layer "In15.Cu")
		(net "P5E_CPU1_P0_RX_DP<13>")
	)
	(segment
		(start 109.544104 -277.648924)
		(end 109.512354 -277.630636)
		(width 0.1143)
		(layer "In15.Cu")
		(net "P5E_CPU1_P0_RX_DP<13>")
	)
	(segment
		(start 109.54385 -288.343594)
		(end 109.58576 -288.31921)
		(width 0.1143)
		(layer "In15.Cu")
		(net "P5E_CPU1_P0_RX_DP<13>")
	)
	(segment
		(start 109.512354 -291.601906)
		(end 109.542072 -291.584888)
		(width 0.1143)
		(layer "In15.Cu")
		(net "P5E_CPU1_P0_RX_DP<13>")
	)
	(segment
		(start 63.835788 -384.3528)
		(end 64.140588 -384.048)
		(width 0.14224)
		(layer "In15.Cu")
		(net "P5E_CPU1_P0_RX_DP<13>")
	)
	(segment
		(start 109.532928 -280.882344)
		(end 109.531404 -280.881582)
		(width 0.1143)
		(layer "In15.Cu")
		(net "P5E_CPU1_P0_RX_DP<13>")
	)
	(segment
		(start 109.542072 -291.584888)
		(end 109.543342 -291.584126)
		(width 0.1143)
		(layer "In15.Cu")
		(net "P5E_CPU1_P0_RX_DP<13>")
	)
	(segment
		(start 109.543342 -291.584126)
		(end 109.544104 -291.583618)
		(width 0.1143)
		(layer "In15.Cu")
		(net "P5E_CPU1_P0_RX_DP<13>")
	)
	(segment
		(start 109.54004 -292.226492)
		(end 109.5375 -292.225222)
		(width 0.1143)
		(layer "In15.Cu")
		(net "P5E_CPU1_P0_RX_DP<13>")
	)
	(segment
		(start 109.539786 -288.986214)
		(end 109.53877 -288.985706)
		(width 0.1143)
		(layer "In15.Cu")
		(net "P5E_CPU1_P0_RX_DP<13>")
	)
	(segment
		(start 109.544104 -285.103824)
		(end 109.580426 -285.082742)
		(width 0.1143)
		(layer "In15.Cu")
		(net "P5E_CPU1_P0_RX_DP<13>")
	)
	(segment
		(start 109.543342 -289.964114)
		(end 109.545628 -289.96259)
		(width 0.1143)
		(layer "In15.Cu")
		(net "P5E_CPU1_P0_RX_DP<13>")
	)
	(segment
		(start 109.545628 -289.96259)
		(end 109.582966 -289.941)
		(width 0.1143)
		(layer "In15.Cu")
		(net "P5E_CPU1_P0_RX_DP<13>")
	)
	(segment
		(start 109.363256 -274.15617)
		(end 109.433106 -274.08632)
		(width 0.1143)
		(layer "In15.Cu")
		(net "P5E_CPU1_P0_RX_DP<13>")
	)
	(segment
		(start 109.544104 -277.003764)
		(end 109.580426 -276.982682)
		(width 0.1143)
		(layer "In15.Cu")
		(net "P5E_CPU1_P0_RX_DP<13>")
	)
	(segment
		(start 109.356144 -295.292272)
		(end 109.356398 -295.292018)
		(width 0.1143)
		(layer "In15.Cu")
		(net "P5E_CPU1_P0_RX_DP<13>")
	)
	(segment
		(start 109.610906 -292.27145)
		(end 109.582966 -292.251384)
		(width 0.1143)
		(layer "In15.Cu")
		(net "P5E_CPU1_P0_RX_DP<13>")
	)
	(segment
		(start 109.56544 -293.861236)
		(end 109.564678 -293.860728)
		(width 0.1143)
		(layer "In15.Cu")
		(net "P5E_CPU1_P0_RX_DP<13>")
	)
	(segment
		(start 109.554264 -293.197788)
		(end 109.555788 -293.196772)
		(width 0.1143)
		(layer "In15.Cu")
		(net "P5E_CPU1_P0_RX_DP<13>")
	)
	(segment
		(start 109.826298 -287.856422)
		(end 109.826298 -287.85439)
		(width 0.1143)
		(layer "In15.Cu")
		(net "P5E_CPU1_P0_RX_DP<13>")
	)
	(segment
		(start 109.549438 -293.200582)
		(end 109.551724 -293.199312)
		(width 0.1143)
		(layer "In15.Cu")
		(net "P5E_CPU1_P0_RX_DP<13>")
	)
	(segment
		(start 109.531404 -280.881582)
		(end 109.529626 -280.880566)
		(width 0.1143)
		(layer "In15.Cu")
		(net "P5E_CPU1_P0_RX_DP<13>")
	)
	(segment
		(start 109.544104 -288.988754)
		(end 109.543342 -288.988246)
		(width 0.1143)
		(layer "In15.Cu")
		(net "P5E_CPU1_P0_RX_DP<13>")
	)
	(segment
		(start 63.886334 -385.649216)
		(end 64.060578 -385.548632)
		(width 0.14224)
		(layer "In15.Cu")
		(net "P5E_CPU1_P0_RX_DP<13>")
	)
	(segment
		(start 109.54512 -293.202868)
		(end 109.549438 -293.200582)
		(width 0.1143)
		(layer "In15.Cu")
		(net "P5E_CPU1_P0_RX_DP<13>")
	)
	(segment
		(start 109.564678 -275.371814)
		(end 109.56544 -275.371306)
		(width 0.1143)
		(layer "In15.Cu")
		(net "P5E_CPU1_P0_RX_DP<13>")
	)
	(segment
		(start 109.535468 -292.223952)
		(end 109.533436 -292.222936)
		(width 0.1143)
		(layer "In15.Cu")
		(net "P5E_CPU1_P0_RX_DP<13>")
	)
	(segment
		(start 109.356144 -295.837102)
		(end 109.356144 -295.292272)
		(width 0.1143)
		(layer "In15.Cu")
		(net "P5E_CPU1_P0_RX_DP<13>")
	)
	(segment
		(start 109.544104 -284.128972)
		(end 109.512354 -284.110684)
		(width 0.1143)
		(layer "In15.Cu")
		(net "P5E_CPU1_P0_RX_DP<13>")
	)
	(segment
		(start 109.512354 -283.5021)
		(end 109.544104 -283.483812)
		(width 0.1143)
		(layer "In15.Cu")
		(net "P5E_CPU1_P0_RX_DP<13>")
	)
	(segment
		(start 109.555788 -293.196772)
		(end 109.582966 -293.181024)
		(width 0.1143)
		(layer "In15.Cu")
		(net "P5E_CPU1_P0_RX_DP<13>")
	)
	(segment
		(start 109.544104 -282.50896)
		(end 109.512354 -282.490672)
		(width 0.1143)
		(layer "In15.Cu")
		(net "P5E_CPU1_P0_RX_DP<13>")
	)
	(segment
		(start 109.542072 -289.964876)
		(end 109.543342 -289.964114)
		(width 0.1143)
		(layer "In15.Cu")
		(net "P5E_CPU1_P0_RX_DP<13>")
	)
	(segment
		(start 109.610906 -289.031426)
		(end 109.582966 -289.01136)
		(width 0.1143)
		(layer "In15.Cu")
		(net "P5E_CPU1_P0_RX_DP<13>")
	)
	(segment
		(start 109.553248 -293.198296)
		(end 109.554264 -293.197788)
		(width 0.1143)
		(layer "In15.Cu")
		(net "P5E_CPU1_P0_RX_DP<13>")
	)
	(segment
		(start 109.544104 -290.608766)
		(end 109.512354 -290.590478)
		(width 0.1143)
		(layer "In15.Cu")
		(net "P5E_CPU1_P0_RX_DP<13>")
	)
	(segment
		(start 109.401864 -300.320202)
		(end 109.401864 -295.91127)
		(width 0.14224)
		(layer "In15.Cu")
		(net "P5E_CPU1_P0_RX_DP<13>")
	)
	(segment
		(start 110.845854 -366.027716)
		(end 168.071292 -366.027716)
		(width 0.14224)
		(layer "In15.Cu")
		(net "P5E_CPU1_P0_RX_DP<13>")
	)
	(segment
		(start 109.536738 -292.224714)
		(end 109.535468 -292.223952)
		(width 0.1143)
		(layer "In15.Cu")
		(net "P5E_CPU1_P0_RX_DP<13>")
	)
	(segment
		(start 109.533436 -292.222936)
		(end 109.512354 -292.21049)
		(width 0.1143)
		(layer "In15.Cu")
		(net "P5E_CPU1_P0_RX_DP<13>")
	)
	(segment
		(start 109.512354 -289.981894)
		(end 109.542072 -289.964876)
		(width 0.1143)
		(layer "In15.Cu")
		(net "P5E_CPU1_P0_RX_DP<13>")
	)
	(segment
		(start 109.541818 -292.227508)
		(end 109.540802 -292.227)
		(width 0.1143)
		(layer "In15.Cu")
		(net "P5E_CPU1_P0_RX_DP<13>")
	)
	(segment
		(start 109.580426 -277.670006)
		(end 109.544104 -277.648924)
		(width 0.1143)
		(layer "In15.Cu")
		(net "P5E_CPU1_P0_RX_DP<13>")
	)
	(segment
		(start 74.289412 -368.693954)
		(end 76.17968 -366.803686)
		(width 0.14224)
		(layer "In15.Cu")
		(net "P5E_CPU1_P0_RX_DP<13>")
	)
	(segment
		(start 109.401864 -295.91127)
		(end 109.401864 -295.882822)
		(width 0.1143)
		(layer "In15.Cu")
		(net "P5E_CPU1_P0_RX_DP<13>")
	)
	(segment
		(start 109.543342 -288.988246)
		(end 109.542072 -288.987484)
		(width 0.1143)
		(layer "In15.Cu")
		(net "P5E_CPU1_P0_RX_DP<13>")
	)
	(segment
		(start 109.544104 -285.748984)
		(end 109.512354 -285.730696)
		(width 0.1143)
		(layer "In15.Cu")
		(net "P5E_CPU1_P0_RX_DP<13>")
	)
	(segment
		(start 109.510576 -288.363406)
		(end 109.544104 -288.343848)
		(width 0.1143)
		(layer "In15.Cu")
		(net "P5E_CPU1_P0_RX_DP<13>")
	)
	(segment
		(start 109.512354 -294.84193)
		(end 109.56544 -294.811196)
		(width 0.1143)
		(layer "In15.Cu")
		(net "P5E_CPU1_P0_RX_DP<13>")
	)
	(segment
		(start 142.711932 -347.819472)
		(end 134.516876 -342.34374)
		(width 0.14224)
		(layer "In15.Cu")
		(net "P5E_CPU1_P0_RX_DP<13>")
	)
	(segment
		(start 109.56544 -279.281382)
		(end 109.512354 -279.250648)
		(width 0.1143)
		(layer "In15.Cu")
		(net "P5E_CPU1_P0_RX_DP<13>")
	)
	(segment
		(start 109.544104 -288.343848)
		(end 109.54385 -288.343594)
		(width 0.1143)
		(layer "In15.Cu")
		(net "P5E_CPU1_P0_RX_DP<13>")
	)
	(segment
		(start 63.791338 -386.003292)
		(end 63.886334 -385.649216)
		(width 0.14224)
		(layer "In15.Cu")
		(net "P5E_CPU1_P0_RX_DP<13>")
	)
	(segment
		(start 153.959814 -356.34041)
		(end 150.930102 -353.310698)
		(width 0.14224)
		(layer "In15.Cu")
		(net "P5E_CPU1_P0_RX_DP<13>")
	)
	(segment
		(start 109.544104 -280.888948)
		(end 109.534198 -280.883106)
		(width 0.1143)
		(layer "In15.Cu")
		(net "P5E_CPU1_P0_RX_DP<13>")
	)
	(segment
		(start 121.26214 -329.200002)
		(end 109.496098 -300.79315)
		(width 0.14224)
		(layer "In15.Cu")
		(net "P5E_CPU1_P0_RX_DP<13>")
	)
	(segment
		(start 64.18707 -382.052576)
		(end 69.115178 -375.12117)
		(width 0.14224)
		(layer "In15.Cu")
		(net "P5E_CPU1_P0_RX_DP<13>")
	)
	(segment
		(start 109.512354 -293.221918)
		(end 109.527848 -293.21252)
		(width 0.1143)
		(layer "In15.Cu")
		(net "P5E_CPU1_P0_RX_DP<13>")
	)
	(segment
		(start 168.538906 -365.560102)
		(end 168.538906 -359.609136)
		(width 0.14224)
		(layer "In15.Cu")
		(net "P5E_CPU1_P0_RX_DP<13>")
	)
	(segment
		(start 109.512354 -275.40204)
		(end 109.544104 -275.383752)
		(width 0.1143)
		(layer "In15.Cu")
		(net "P5E_CPU1_P0_RX_DP<13>")
	)
	(segment
		(start 109.356398 -287.046416)
		(end 109.356144 -287.046162)
		(width 0.1143)
		(layer "In15.Cu")
		(net "P5E_CPU1_P0_RX_DP<13>")
	)
	(segment
		(start 109.580426 -290.629848)
		(end 109.544104 -290.608766)
		(width 0.1143)
		(layer "In15.Cu")
		(net "P5E_CPU1_P0_RX_DP<13>")
	)
	(segment
		(start 109.511338 -286.742886)
		(end 109.580426 -286.702754)
		(width 0.1143)
		(layer "In15.Cu")
		(net "P5E_CPU1_P0_RX_DP<13>")
	)
	(segment
		(start 109.512354 -281.882088)
		(end 109.544104 -281.8638)
		(width 0.1143)
		(layer "In15.Cu")
		(net "P5E_CPU1_P0_RX_DP<13>")
	)
	(segment
		(start 109.530134 -280.251916)
		(end 109.564678 -280.23185)
		(width 0.1143)
		(layer "In15.Cu")
		(net "P5E_CPU1_P0_RX_DP<13>")
	)
	(segment
		(start 109.54258 -292.228016)
		(end 109.541818 -292.227508)
		(width 0.1143)
		(layer "In15.Cu")
		(net "P5E_CPU1_P0_RX_DP<13>")
	)
	(segment
		(start 109.580426 -285.770066)
		(end 109.544104 -285.748984)
		(width 0.1143)
		(layer "In15.Cu")
		(net "P5E_CPU1_P0_RX_DP<13>")
	)
	(segment
		(start 109.544104 -276.028912)
		(end 109.512354 -276.010624)
		(width 0.1143)
		(layer "In15.Cu")
		(net "P5E_CPU1_P0_RX_DP<13>")
	)
	(segment
		(start 109.582966 -292.251384)
		(end 109.54258 -292.228016)
		(width 0.1143)
		(layer "In15.Cu")
		(net "P5E_CPU1_P0_RX_DP<13>")
	)
	(segment
		(start 109.542072 -288.987484)
		(end 109.540548 -288.986722)
		(width 0.1143)
		(layer "In15.Cu")
		(net "P5E_CPU1_P0_RX_DP<13>")
	)
	(segment
		(start 109.544104 -278.623776)
		(end 109.580426 -278.602694)
		(width 0.1143)
		(layer "In15.Cu")
		(net "P5E_CPU1_P0_RX_DP<13>")
	)
	(segment
		(start 109.356398 -295.292018)
		(end 109.356398 -295.146222)
		(width 0.1143)
		(layer "In15.Cu")
		(net "P5E_CPU1_P0_RX_DP<13>")
	)
	(segment
		(start 109.580426 -276.049994)
		(end 109.544104 -276.028912)
		(width 0.1143)
		(layer "In15.Cu")
		(net "P5E_CPU1_P0_RX_DP<13>")
	)
	(segment
		(start 109.512354 -278.642064)
		(end 109.544104 -278.623776)
		(width 0.1143)
		(layer "In15.Cu")
		(net "P5E_CPU1_P0_RX_DP<13>")
	)
	(segment
		(start 109.544104 -283.483812)
		(end 109.580426 -283.46273)
		(width 0.1143)
		(layer "In15.Cu")
		(net "P5E_CPU1_P0_RX_DP<13>")
	)
	(segment
		(start 64.148716 -385.460494)
		(end 64.148716 -385.046982)
		(width 0.14224)
		(layer "In15.Cu")
		(net "P5E_CPU1_P0_RX_DP<13>")
	)
	(segment
		(start 109.433106 -274.08632)
		(end 109.731048 -274.08632)
		(width 0.1143)
		(layer "In15.Cu")
		(net "P5E_CPU1_P0_RX_DP<13>")
	)
	(segment
		(start 109.544104 -275.383752)
		(end 109.564678 -275.371814)
		(width 0.1143)
		(layer "In15.Cu")
		(net "P5E_CPU1_P0_RX_DP<13>")
	)
	(segment
		(start 76.602336 -366.699038)
		(end 108.160058 -366.699038)
		(width 0.14224)
		(layer "In15.Cu")
		(net "P5E_CPU1_P0_RX_DP<13>")
	)
	(segment
		(start 150.930102 -353.310698)
		(end 142.711932 -347.819218)
		(width 0.14224)
		(layer "In15.Cu")
		(net "P5E_CPU1_P0_RX_DP<13>")
	)
	(segment
		(start 109.546898 -288.990532)
		(end 109.544104 -288.988754)
		(width 0.1143)
		(layer "In15.Cu")
		(net "P5E_CPU1_P0_RX_DP<13>")
	)
	(segment
		(start 109.540548 -288.986722)
		(end 109.539786 -288.986214)
		(width 0.1143)
		(layer "In15.Cu")
		(net "P5E_CPU1_P0_RX_DP<13>")
	)
	(segment
		(start 109.582966 -289.941)
		(end 109.610906 -289.920934)
		(width 0.1143)
		(layer "In15.Cu")
		(net "P5E_CPU1_P0_RX_DP<13>")
	)
	(segment
		(start 109.582966 -289.01136)
		(end 109.546898 -288.990532)
		(width 0.1143)
		(layer "In15.Cu")
		(net "P5E_CPU1_P0_RX_DP<13>")
	)
	(segment
		(start 109.53877 -288.985706)
		(end 109.512354 -288.970466)
		(width 0.1143)
		(layer "In15.Cu")
		(net "P5E_CPU1_P0_RX_DP<13>")
	)
	(arc
		(start 109.595666 -277.680674)
		(mid 109.58809 -277.675278)
		(end 109.580426 -277.670006)
		(width 0.1143)
		(layer "In15.Cu")
		(net "P5E_CPU1_P0_RX_DP<13>")
	)
	(arc
		(start 109.496098 -300.79315)
		(mid 109.425704 -300.561316)
		(end 109.401864 -300.320202)
		(width 0.14224)
		(layer "In15.Cu")
		(net "P5E_CPU1_P0_RX_DP<13>")
	)
	(arc
		(start 109.595666 -278.592026)
		(mid 109.820837 -278.13635)
		(end 109.595666 -277.680674)
		(width 0.1143)
		(layer "In15.Cu")
		(net "P5E_CPU1_P0_RX_DP<13>")
	)
	(arc
		(start 109.610906 -293.160958)
		(mid 109.838906 -292.716204)
		(end 109.610906 -292.27145)
		(width 0.1143)
		(layer "In15.Cu")
		(net "P5E_CPU1_P0_RX_DP<13>")
	)
	(arc
		(start 109.580426 -291.562536)
		(mid 109.58809 -291.557265)
		(end 109.595666 -291.551868)
		(width 0.1143)
		(layer "In15.Cu")
		(net "P5E_CPU1_P0_RX_DP<13>")
	)
	(arc
		(start 109.356398 -295.146222)
		(mid 109.397653 -294.975251)
		(end 109.512354 -294.84193)
		(width 0.1143)
		(layer "In15.Cu")
		(net "P5E_CPU1_P0_RX_DP<13>")
	)
	(arc
		(start 109.58576 -288.31921)
		(mid 109.762652 -288.117242)
		(end 109.826298 -287.856422)
		(width 0.1143)
		(layer "In15.Cu")
		(net "P5E_CPU1_P0_RX_DP<13>")
	)
	(arc
		(start 109.56544 -280.231342)
		(mid 109.838991 -279.756362)
		(end 109.56544 -279.281382)
		(width 0.1143)
		(layer "In15.Cu")
		(net "P5E_CPU1_P0_RX_DP<13>")
	)
	(arc
		(start 109.544104 -281.8638)
		(mid 109.824751 -281.376374)
		(end 109.544104 -280.888948)
		(width 0.1143)
		(layer "In15.Cu")
		(net "P5E_CPU1_P0_RX_DP<13>")
	)
	(arc
		(start 109.356144 -287.046162)
		(mid 109.396473 -286.87707)
		(end 109.508798 -286.74441)
		(width 0.1143)
		(layer "In15.Cu")
		(net "P5E_CPU1_P0_RX_DP<13>")
	)
	(arc
		(start 109.595666 -285.072074)
		(mid 109.820837 -284.616398)
		(end 109.595666 -284.160722)
		(width 0.1143)
		(layer "In15.Cu")
		(net "P5E_CPU1_P0_RX_DP<13>")
	)
	(arc
		(start 109.580426 -285.082742)
		(mid 109.58809 -285.077471)
		(end 109.595666 -285.072074)
		(width 0.1143)
		(layer "In15.Cu")
		(net "P5E_CPU1_P0_RX_DP<13>")
	)
	(arc
		(start 109.56544 -294.811196)
		(mid 109.838991 -294.336216)
		(end 109.56544 -293.861236)
		(width 0.1143)
		(layer "In15.Cu")
		(net "P5E_CPU1_P0_RX_DP<13>")
	)
	(arc
		(start 76.289154 -366.74044)
		(mid 76.444384 -366.70944)
		(end 76.602336 -366.699038)
		(width 0.14224)
		(layer "In15.Cu")
		(net "P5E_CPU1_P0_RX_DP<13>")
	)
	(arc
		(start 168.071292 -366.027716)
		(mid 168.401945 -365.890755)
		(end 168.538906 -365.560102)
		(width 0.14224)
		(layer "In15.Cu")
		(net "P5E_CPU1_P0_RX_DP<13>")
	)
	(arc
		(start 109.512354 -276.010624)
		(mid 109.356426 -275.706332)
		(end 109.512354 -275.40204)
		(width 0.1143)
		(layer "In15.Cu")
		(net "P5E_CPU1_P0_RX_DP<13>")
	)
	(arc
		(start 109.610906 -289.920934)
		(mid 109.838906 -289.47618)
		(end 109.610906 -289.031426)
		(width 0.1143)
		(layer "In15.Cu")
		(net "P5E_CPU1_P0_RX_DP<13>")
	)
	(arc
		(start 109.502956 -366.363504)
		(mid 110.153748 -366.112996)
		(end 110.845854 -366.027716)
		(width 0.14224)
		(layer "In15.Cu")
		(net "P5E_CPU1_P0_RX_DP<13>")
	)
	(arc
		(start 109.580426 -283.46273)
		(mid 109.587575 -283.45783)
		(end 109.59465 -283.452824)
		(width 0.1143)
		(layer "In15.Cu")
		(net "P5E_CPU1_P0_RX_DP<13>")
	)
	(arc
		(start 109.512354 -285.730696)
		(mid 109.356426 -285.426404)
		(end 109.512354 -285.122112)
		(width 0.1143)
		(layer "In15.Cu")
		(net "P5E_CPU1_P0_RX_DP<13>")
	)
	(arc
		(start 109.512354 -277.630636)
		(mid 109.356426 -277.326344)
		(end 109.512354 -277.022052)
		(width 0.1143)
		(layer "In15.Cu")
		(net "P5E_CPU1_P0_RX_DP<13>")
	)
	(arc
		(start 109.512354 -279.250648)
		(mid 109.356426 -278.946356)
		(end 109.512354 -278.642064)
		(width 0.1143)
		(layer "In15.Cu")
		(net "P5E_CPU1_P0_RX_DP<13>")
	)
	(arc
		(start 109.59465 -283.452824)
		(mid 109.822033 -282.996386)
		(end 109.59465 -282.539948)
		(width 0.1143)
		(layer "In15.Cu")
		(net "P5E_CPU1_P0_RX_DP<13>")
	)
	(arc
		(start 166.139622 -356.959408)
		(mid 165.967148 -356.844165)
		(end 165.763702 -356.803706)
		(width 0.14224)
		(layer "In15.Cu")
		(net "P5E_CPU1_P0_RX_DP<13>")
	)
	(arc
		(start 76.17968 -366.803686)
		(mid 76.230257 -366.764861)
		(end 76.289154 -366.74044)
		(width 0.14224)
		(layer "In15.Cu")
		(net "P5E_CPU1_P0_RX_DP<13>")
	)
	(arc
		(start 109.59465 -282.539948)
		(mid 109.587576 -282.534941)
		(end 109.580426 -282.530042)
		(width 0.1143)
		(layer "In15.Cu")
		(net "P5E_CPU1_P0_RX_DP<13>")
	)
	(arc
		(start 109.580426 -276.982682)
		(mid 109.58809 -276.977411)
		(end 109.595666 -276.972014)
		(width 0.1143)
		(layer "In15.Cu")
		(net "P5E_CPU1_P0_RX_DP<13>")
	)
	(arc
		(start 134.516876 -342.34374)
		(mid 133.668789 -341.71476)
		(end 132.88645 -341.005668)
		(width 0.14224)
		(layer "In15.Cu")
		(net "P5E_CPU1_P0_RX_DP<13>")
	)
	(arc
		(start 109.580426 -286.702754)
		(mid 109.76261 -286.497084)
		(end 109.826298 -286.229806)
		(width 0.1143)
		(layer "In15.Cu")
		(net "P5E_CPU1_P0_RX_DP<13>")
	)
	(arc
		(start 155.078176 -356.803706)
		(mid 154.472916 -356.683294)
		(end 153.959814 -356.34041)
		(width 0.14224)
		(layer "In15.Cu")
		(net "P5E_CPU1_P0_RX_DP<13>")
	)
	(arc
		(start 108.160058 -366.699038)
		(mid 108.852154 -366.613895)
		(end 109.502956 -366.363504)
		(width 0.14224)
		(layer "In15.Cu")
		(net "P5E_CPU1_P0_RX_DP<13>")
	)
	(arc
		(start 109.580426 -278.602694)
		(mid 109.58809 -278.597423)
		(end 109.595666 -278.592026)
		(width 0.1143)
		(layer "In15.Cu")
		(net "P5E_CPU1_P0_RX_DP<13>")
	)
	(arc
		(start 109.518958 -287.36163)
		(mid 109.399476 -287.223722)
		(end 109.356398 -287.046416)
		(width 0.1143)
		(layer "In15.Cu")
		(net "P5E_CPU1_P0_RX_DP<13>")
	)
	(arc
		(start 109.529626 -280.880566)
		(mid 109.34959 -280.566085)
		(end 109.530134 -280.251916)
		(width 0.1143)
		(layer "In15.Cu")
		(net "P5E_CPU1_P0_RX_DP<13>")
	)
	(arc
		(start 109.512354 -284.110684)
		(mid 109.356426 -283.806392)
		(end 109.512354 -283.5021)
		(width 0.1143)
		(layer "In15.Cu")
		(net "P5E_CPU1_P0_RX_DP<13>")
	)
	(arc
		(start 109.596682 -285.781496)
		(mid 109.588604 -285.77571)
		(end 109.580426 -285.770066)
		(width 0.1143)
		(layer "In15.Cu")
		(net "P5E_CPU1_P0_RX_DP<13>")
	)
	(arc
		(start 109.595666 -276.972014)
		(mid 109.820837 -276.516338)
		(end 109.595666 -276.060662)
		(width 0.1143)
		(layer "In15.Cu")
		(net "P5E_CPU1_P0_RX_DP<13>")
	)
	(arc
		(start 109.512354 -293.830502)
		(mid 109.356426 -293.52621)
		(end 109.512354 -293.221918)
		(width 0.1143)
		(layer "In15.Cu")
		(net "P5E_CPU1_P0_RX_DP<13>")
	)
	(arc
		(start 109.595666 -276.060662)
		(mid 109.58809 -276.055266)
		(end 109.580426 -276.049994)
		(width 0.1143)
		(layer "In15.Cu")
		(net "P5E_CPU1_P0_RX_DP<13>")
	)
	(arc
		(start 109.356398 -288.666174)
		(mid 109.39716 -288.49629)
		(end 109.510576 -288.363406)
		(width 0.1143)
		(layer "In15.Cu")
		(net "P5E_CPU1_P0_RX_DP<13>")
	)
	(arc
		(start 121.627138 -329.746356)
		(mid 121.41771 -329.491166)
		(end 121.26214 -329.200002)
		(width 0.14224)
		(layer "In15.Cu")
		(net "P5E_CPU1_P0_RX_DP<13>")
	)
	(arc
		(start 109.595666 -290.640516)
		(mid 109.58809 -290.63512)
		(end 109.580426 -290.629848)
		(width 0.1143)
		(layer "In15.Cu")
		(net "P5E_CPU1_P0_RX_DP<13>")
	)
	(arc
		(start 109.512354 -288.970466)
		(mid 109.397678 -288.837132)
		(end 109.356398 -288.666174)
		(width 0.1143)
		(layer "In15.Cu")
		(net "P5E_CPU1_P0_RX_DP<13>")
	)
	(arc
		(start 64.140588 -382.197864)
		(mid 64.152546 -382.121616)
		(end 64.18707 -382.052576)
		(width 0.14224)
		(layer "In15.Cu")
		(net "P5E_CPU1_P0_RX_DP<13>")
	)
	(arc
		(start 109.512354 -290.590478)
		(mid 109.356426 -290.286186)
		(end 109.512354 -289.981894)
		(width 0.1143)
		(layer "In15.Cu")
		(net "P5E_CPU1_P0_RX_DP<13>")
	)
	(arc
		(start 109.595666 -284.160722)
		(mid 109.58809 -284.155326)
		(end 109.580426 -284.150054)
		(width 0.1143)
		(layer "In15.Cu")
		(net "P5E_CPU1_P0_RX_DP<13>")
	)
	(arc
		(start 109.826298 -286.229806)
		(mid 109.761426 -285.980064)
		(end 109.596682 -285.781496)
		(width 0.1143)
		(layer "In15.Cu")
		(net "P5E_CPU1_P0_RX_DP<13>")
	)
	(arc
		(start 168.538906 -359.609136)
		(mid 168.49289 -359.377796)
		(end 168.361868 -359.181654)
		(width 0.14224)
		(layer "In15.Cu")
		(net "P5E_CPU1_P0_RX_DP<13>")
	)
	(arc
		(start 109.826298 -287.85439)
		(mid 109.782145 -287.639745)
		(end 109.65688 -287.459928)
		(width 0.1143)
		(layer "In15.Cu")
		(net "P5E_CPU1_P0_RX_DP<13>")
	)
	(arc
		(start 109.56544 -275.371306)
		(mid 109.838991 -274.896326)
		(end 109.56544 -274.421346)
		(width 0.1143)
		(layer "In15.Cu")
		(net "P5E_CPU1_P0_RX_DP<13>")
	)
	(arc
		(start 109.512354 -292.21049)
		(mid 109.356426 -291.906198)
		(end 109.512354 -291.601906)
		(width 0.1143)
		(layer "In15.Cu")
		(net "P5E_CPU1_P0_RX_DP<13>")
	)
	(arc
		(start 109.595666 -291.551868)
		(mid 109.820837 -291.096192)
		(end 109.595666 -290.640516)
		(width 0.1143)
		(layer "In15.Cu")
		(net "P5E_CPU1_P0_RX_DP<13>")
	)
	(arc
		(start 109.512354 -282.490672)
		(mid 109.356426 -282.18638)
		(end 109.512354 -281.882088)
		(width 0.1143)
		(layer "In15.Cu")
		(net "P5E_CPU1_P0_RX_DP<13>")
	)
	(arc
		(start 109.512354 -274.390612)
		(mid 109.415219 -274.287743)
		(end 109.363256 -274.15617)
		(width 0.1143)
		(layer "In15.Cu")
		(net "P5E_CPU1_P0_RX_DP<13>")
	)
	(segment
		(start 110.1979 -272.20037)
		(end 109.731048 -272.466308)
		(width 0.12954)
		(layer "F.Cu")
		(net "P5E_CPU1_P0_RX_DP<12>")
	)
	(segment
		(start 62.070488 -386.003292)
		(end 62.591188 -386.003292)
		(width 0.127)
		(layer "F.Cu")
		(net "P5E_CPU1_P0_RX_DP<12>")
	)
	(segment
		(start 108.600494 -273.765772)
		(end 108.603288 -273.764248)
		(width 0.1143)
		(layer "In15.Cu")
		(net "P5E_CPU1_P0_RX_DP<12>")
	)
	(segment
		(start 108.603288 -293.848282)
		(end 108.602018 -293.84752)
		(width 0.1143)
		(layer "In15.Cu")
		(net "P5E_CPU1_P0_RX_DP<12>")
	)
	(segment
		(start 151.537924 -355.269292)
		(end 133.923786 -343.498932)
		(width 0.14224)
		(layer "In15.Cu")
		(net "P5E_CPU1_P0_RX_DP<12>")
	)
	(segment
		(start 62.635638 -384.3528)
		(end 62.940438 -384.048)
		(width 0.14224)
		(layer "In15.Cu")
		(net "P5E_CPU1_P0_RX_DP<12>")
	)
	(segment
		(start 108.635546 -292.247066)
		(end 108.60405 -292.228778)
		(width 0.1143)
		(layer "In15.Cu")
		(net "P5E_CPU1_P0_RX_DP<12>")
	)
	(segment
		(start 108.635546 -289.007042)
		(end 108.60405 -288.988754)
		(width 0.1143)
		(layer "In15.Cu")
		(net "P5E_CPU1_P0_RX_DP<12>")
	)
	(segment
		(start 108.60405 -285.103824)
		(end 108.640372 -285.082996)
		(width 0.1143)
		(layer "In15.Cu")
		(net "P5E_CPU1_P0_RX_DP<12>")
	)
	(segment
		(start 108.5723 -273.782028)
		(end 108.596176 -273.768312)
		(width 0.1143)
		(layer "In15.Cu")
		(net "P5E_CPU1_P0_RX_DP<12>")
	)
	(segment
		(start 108.603288 -277.004272)
		(end 108.60405 -277.003764)
		(width 0.1143)
		(layer "In15.Cu")
		(net "P5E_CPU1_P0_RX_DP<12>")
	)
	(segment
		(start 108.6231 -274.419314)
		(end 108.622338 -274.418806)
		(width 0.1143)
		(layer "In15.Cu")
		(net "P5E_CPU1_P0_RX_DP<12>")
	)
	(segment
		(start 108.613194 -280.894282)
		(end 108.612178 -280.89352)
		(width 0.1143)
		(layer "In15.Cu")
		(net "P5E_CPU1_P0_RX_DP<12>")
	)
	(segment
		(start 108.41609 -295.996614)
		(end 108.41609 -295.42359)
		(width 0.1143)
		(layer "In15.Cu")
		(net "P5E_CPU1_P0_RX_DP<12>")
	)
	(segment
		(start 108.596176 -280.24836)
		(end 108.597446 -280.247598)
		(width 0.1143)
		(layer "In15.Cu")
		(net "P5E_CPU1_P0_RX_DP<12>")
	)
	(segment
		(start 108.603288 -275.38426)
		(end 108.60405 -275.383752)
		(width 0.1143)
		(layer "In15.Cu")
		(net "P5E_CPU1_P0_RX_DP<12>")
	)
	(segment
		(start 108.596938 -294.827706)
		(end 108.597954 -294.827198)
		(width 0.1143)
		(layer "In15.Cu")
		(net "P5E_CPU1_P0_RX_DP<12>")
	)
	(segment
		(start 108.60659 -284.130496)
		(end 108.605066 -284.12948)
		(width 0.1143)
		(layer "In15.Cu")
		(net "P5E_CPU1_P0_RX_DP<12>")
	)
	(segment
		(start 108.636308 -292.247574)
		(end 108.635546 -292.247066)
		(width 0.1143)
		(layer "In15.Cu")
		(net "P5E_CPU1_P0_RX_DP<12>")
	)
	(segment
		(start 108.605066 -284.12948)
		(end 108.60405 -284.128972)
		(width 0.1143)
		(layer "In15.Cu")
		(net "P5E_CPU1_P0_RX_DP<12>")
	)
	(segment
		(start 108.60659 -278.622252)
		(end 108.643166 -278.600916)
		(width 0.1143)
		(layer "In15.Cu")
		(net "P5E_CPU1_P0_RX_DP<12>")
	)
	(segment
		(start 108.60405 -294.823642)
		(end 108.605066 -294.823134)
		(width 0.1143)
		(layer "In15.Cu")
		(net "P5E_CPU1_P0_RX_DP<12>")
	)
	(segment
		(start 108.60405 -275.383752)
		(end 108.605066 -275.383244)
		(width 0.1143)
		(layer "In15.Cu")
		(net "P5E_CPU1_P0_RX_DP<12>")
	)
	(segment
		(start 108.64342 -289.941)
		(end 108.643166 -289.940746)
		(width 0.1143)
		(layer "In15.Cu")
		(net "P5E_CPU1_P0_RX_DP<12>")
	)
	(segment
		(start 108.603288 -283.48432)
		(end 108.60405 -283.483812)
		(width 0.1143)
		(layer "In15.Cu")
		(net "P5E_CPU1_P0_RX_DP<12>")
	)
	(segment
		(start 108.605066 -282.509468)
		(end 108.60405 -282.50896)
		(width 0.1143)
		(layer "In15.Cu")
		(net "P5E_CPU1_P0_RX_DP<12>")
	)
	(segment
		(start 108.594652 -276.023578)
		(end 108.5723 -276.010624)
		(width 0.1143)
		(layer "In15.Cu")
		(net "P5E_CPU1_P0_RX_DP<12>")
	)
	(segment
		(start 108.46181 -300.656752)
		(end 108.46181 -296.070782)
		(width 0.14224)
		(layer "In15.Cu")
		(net "P5E_CPU1_P0_RX_DP<12>")
	)
	(segment
		(start 108.602018 -293.84752)
		(end 108.5723 -293.830502)
		(width 0.1143)
		(layer "In15.Cu")
		(net "P5E_CPU1_P0_RX_DP<12>")
	)
	(segment
		(start 108.605066 -278.623268)
		(end 108.60659 -278.622252)
		(width 0.1143)
		(layer "In15.Cu")
		(net "P5E_CPU1_P0_RX_DP<12>")
	)
	(segment
		(start 62.98311 -382.02743)
		(end 68.210684 -374.493028)
		(width 0.14224)
		(layer "In15.Cu")
		(net "P5E_CPU1_P0_RX_DP<12>")
	)
	(segment
		(start 108.5723 -280.262076)
		(end 108.596176 -280.24836)
		(width 0.1143)
		(layer "In15.Cu")
		(net "P5E_CPU1_P0_RX_DP<12>")
	)
	(segment
		(start 120.400318 -329.721718)
		(end 108.577888 -301.178214)
		(width 0.14224)
		(layer "In15.Cu")
		(net "P5E_CPU1_P0_RX_DP<12>")
	)
	(segment
		(start 108.643166 -293.87165)
		(end 108.636308 -293.867586)
		(width 0.1143)
		(layer "In15.Cu")
		(net "P5E_CPU1_P0_RX_DP<12>")
	)
	(segment
		(start 108.605066 -283.483304)
		(end 108.643166 -283.460952)
		(width 0.1143)
		(layer "In15.Cu")
		(net "P5E_CPU1_P0_RX_DP<12>")
	)
	(segment
		(start 108.599732 -275.386292)
		(end 108.600494 -275.385784)
		(width 0.1143)
		(layer "In15.Cu")
		(net "P5E_CPU1_P0_RX_DP<12>")
	)
	(segment
		(start 108.5723 -293.221918)
		(end 108.583222 -293.221918)
		(width 0.1143)
		(layer "In15.Cu")
		(net "P5E_CPU1_P0_RX_DP<12>")
	)
	(segment
		(start 108.640372 -285.082996)
		(end 108.643166 -285.080964)
		(width 0.1143)
		(layer "In15.Cu")
		(net "P5E_CPU1_P0_RX_DP<12>")
	)
	(segment
		(start 108.6231 -276.039326)
		(end 108.622338 -276.038818)
		(width 0.1143)
		(layer "In15.Cu")
		(net "P5E_CPU1_P0_RX_DP<12>")
	)
	(segment
		(start 108.612178 -280.89352)
		(end 108.605828 -280.889964)
		(width 0.1143)
		(layer "In15.Cu")
		(net "P5E_CPU1_P0_RX_DP<12>")
	)
	(segment
		(start 108.5723 -291.60216)
		(end 108.574078 -291.60089)
		(width 0.1143)
		(layer "In15.Cu")
		(net "P5E_CPU1_P0_RX_DP<12>")
	)
	(segment
		(start 108.5723 -281.882088)
		(end 108.60405 -281.8638)
		(width 0.1143)
		(layer "In15.Cu")
		(net "P5E_CPU1_P0_RX_DP<12>")
	)
	(segment
		(start 108.60405 -280.888948)
		(end 108.603288 -280.88844)
		(width 0.1143)
		(layer "In15.Cu")
		(net "P5E_CPU1_P0_RX_DP<12>")
	)
	(segment
		(start 108.60405 -277.003764)
		(end 108.605066 -277.003256)
		(width 0.1143)
		(layer "In15.Cu")
		(net "P5E_CPU1_P0_RX_DP<12>")
	)
	(segment
		(start 108.597446 -275.387562)
		(end 108.598208 -275.387054)
		(width 0.1143)
		(layer "In15.Cu")
		(net "P5E_CPU1_P0_RX_DP<12>")
	)
	(segment
		(start 108.5723 -291.601906)
		(end 108.5723 -291.60216)
		(width 0.1143)
		(layer "In15.Cu")
		(net "P5E_CPU1_P0_RX_DP<12>")
	)
	(segment
		(start 76.22667 -365.681514)
		(end 107.966764 -365.681514)
		(width 0.14224)
		(layer "In15.Cu")
		(net "P5E_CPU1_P0_RX_DP<12>")
	)
	(segment
		(start 108.596176 -277.008336)
		(end 108.597446 -277.007574)
		(width 0.1143)
		(layer "In15.Cu")
		(net "P5E_CPU1_P0_RX_DP<12>")
	)
	(segment
		(start 62.63259 -384.731006)
		(end 62.635638 -384.3528)
		(width 0.14224)
		(layer "In15.Cu")
		(net "P5E_CPU1_P0_RX_DP<12>")
	)
	(segment
		(start 108.46181 -296.070782)
		(end 108.46181 -296.042334)
		(width 0.1143)
		(layer "In15.Cu")
		(net "P5E_CPU1_P0_RX_DP<12>")
	)
	(segment
		(start 108.60405 -288.343848)
		(end 108.643166 -288.320988)
		(width 0.1143)
		(layer "In15.Cu")
		(net "P5E_CPU1_P0_RX_DP<12>")
	)
	(segment
		(start 108.603288 -280.88844)
		(end 108.602018 -280.887678)
		(width 0.1143)
		(layer "In15.Cu")
		(net "P5E_CPU1_P0_RX_DP<12>")
	)
	(segment
		(start 108.416344 -295.423336)
		(end 108.416344 -295.146222)
		(width 0.1143)
		(layer "In15.Cu")
		(net "P5E_CPU1_P0_RX_DP<12>")
	)
	(segment
		(start 108.605066 -277.649432)
		(end 108.60405 -277.648924)
		(width 0.1143)
		(layer "In15.Cu")
		(net "P5E_CPU1_P0_RX_DP<12>")
	)
	(segment
		(start 108.596176 -275.388324)
		(end 108.597446 -275.387562)
		(width 0.1143)
		(layer "In15.Cu")
		(net "P5E_CPU1_P0_RX_DP<12>")
	)
	(segment
		(start 108.598208 -280.24709)
		(end 108.599732 -280.246328)
		(width 0.1143)
		(layer "In15.Cu")
		(net "P5E_CPU1_P0_RX_DP<12>")
	)
	(segment
		(start 68.210684 -374.493028)
		(end 73.428098 -368.176302)
		(width 0.14224)
		(layer "In15.Cu")
		(net "P5E_CPU1_P0_RX_DP<12>")
	)
	(segment
		(start 108.5723 -285.122112)
		(end 108.60405 -285.103824)
		(width 0.1143)
		(layer "In15.Cu")
		(net "P5E_CPU1_P0_RX_DP<12>")
	)
	(segment
		(start 108.60405 -283.483812)
		(end 108.605066 -283.483304)
		(width 0.1143)
		(layer "In15.Cu")
		(net "P5E_CPU1_P0_RX_DP<12>")
	)
	(segment
		(start 108.605828 -280.889964)
		(end 108.605066 -280.889456)
		(width 0.1143)
		(layer "In15.Cu")
		(net "P5E_CPU1_P0_RX_DP<12>")
	)
	(segment
		(start 109.350302 -272.549112)
		(end 109.433106 -272.466308)
		(width 0.1143)
		(layer "In15.Cu")
		(net "P5E_CPU1_P0_RX_DP<12>")
	)
	(segment
		(start 108.599732 -277.006304)
		(end 108.600494 -277.005796)
		(width 0.1143)
		(layer "In15.Cu")
		(net "P5E_CPU1_P0_RX_DP<12>")
	)
	(segment
		(start 108.600494 -280.24582)
		(end 108.603288 -280.244296)
		(width 0.1143)
		(layer "In15.Cu")
		(net "P5E_CPU1_P0_RX_DP<12>")
	)
	(segment
		(start 108.643166 -293.181024)
		(end 108.643166 -293.18077)
		(width 0.1143)
		(layer "In15.Cu")
		(net "P5E_CPU1_P0_RX_DP<12>")
	)
	(segment
		(start 108.583222 -293.215568)
		(end 108.642658 -293.181278)
		(width 0.1143)
		(layer "In15.Cu")
		(net "P5E_CPU1_P0_RX_DP<12>")
	)
	(segment
		(start 62.948566 -385.046982)
		(end 62.63259 -384.731006)
		(width 0.14224)
		(layer "In15.Cu")
		(net "P5E_CPU1_P0_RX_DP<12>")
	)
	(segment
		(start 108.643166 -292.251638)
		(end 108.636308 -292.247574)
		(width 0.1143)
		(layer "In15.Cu")
		(net "P5E_CPU1_P0_RX_DP<12>")
	)
	(segment
		(start 108.600494 -278.625808)
		(end 108.603288 -278.624284)
		(width 0.1143)
		(layer "In15.Cu")
		(net "P5E_CPU1_P0_RX_DP<12>")
	)
	(segment
		(start 108.60405 -285.748984)
		(end 108.5723 -285.730696)
		(width 0.1143)
		(layer "In15.Cu")
		(net "P5E_CPU1_P0_RX_DP<12>")
	)
	(segment
		(start 108.643166 -274.43176)
		(end 108.643166 -274.43049)
		(width 0.1143)
		(layer "In15.Cu")
		(net "P5E_CPU1_P0_RX_DP<12>")
	)
	(segment
		(start 108.60405 -288.988754)
		(end 108.603288 -288.988246)
		(width 0.1143)
		(layer "In15.Cu")
		(net "P5E_CPU1_P0_RX_DP<12>")
	)
	(segment
		(start 108.60405 -273.76374)
		(end 108.605066 -273.763232)
		(width 0.1143)
		(layer "In15.Cu")
		(net "P5E_CPU1_P0_RX_DP<12>")
	)
	(segment
		(start 62.591188 -386.003292)
		(end 62.686184 -385.649216)
		(width 0.14224)
		(layer "In15.Cu")
		(net "P5E_CPU1_P0_RX_DP<12>")
	)
	(segment
		(start 108.60405 -277.648924)
		(end 108.5723 -277.630636)
		(width 0.1143)
		(layer "In15.Cu")
		(net "P5E_CPU1_P0_RX_DP<12>")
	)
	(segment
		(start 108.603288 -290.608258)
		(end 108.602018 -290.607496)
		(width 0.1143)
		(layer "In15.Cu")
		(net "P5E_CPU1_P0_RX_DP<12>")
	)
	(segment
		(start 108.643166 -285.771844)
		(end 108.636308 -285.76778)
		(width 0.1143)
		(layer "In15.Cu")
		(net "P5E_CPU1_P0_RX_DP<12>")
	)
	(segment
		(start 109.07395 -272.953734)
		(end 109.113066 -272.930874)
		(width 0.1143)
		(layer "In15.Cu")
		(net "P5E_CPU1_P0_RX_DP<12>")
	)
	(segment
		(start 108.594652 -274.403566)
		(end 108.5723 -274.390612)
		(width 0.1143)
		(layer "In15.Cu")
		(net "P5E_CPU1_P0_RX_DP<12>")
	)
	(segment
		(start 108.642658 -293.181278)
		(end 108.643166 -293.181024)
		(width 0.1143)
		(layer "In15.Cu")
		(net "P5E_CPU1_P0_RX_DP<12>")
	)
	(segment
		(start 108.603288 -292.22827)
		(end 108.602018 -292.227508)
		(width 0.1143)
		(layer "In15.Cu")
		(net "P5E_CPU1_P0_RX_DP<12>")
	)
	(segment
		(start 108.60405 -279.268936)
		(end 108.5723 -279.250648)
		(width 0.1143)
		(layer "In15.Cu")
		(net "P5E_CPU1_P0_RX_DP<12>")
	)
	(segment
		(start 108.600494 -277.005796)
		(end 108.603288 -277.004272)
		(width 0.1143)
		(layer "In15.Cu")
		(net "P5E_CPU1_P0_RX_DP<12>")
	)
	(segment
		(start 108.643166 -274.43049)
		(end 108.6231 -274.419314)
		(width 0.1143)
		(layer "In15.Cu")
		(net "P5E_CPU1_P0_RX_DP<12>")
	)
	(segment
		(start 108.598208 -273.767042)
		(end 108.599732 -273.76628)
		(width 0.1143)
		(layer "In15.Cu")
		(net "P5E_CPU1_P0_RX_DP<12>")
	)
	(segment
		(start 108.603288 -273.764248)
		(end 108.60405 -273.76374)
		(width 0.1143)
		(layer "In15.Cu")
		(net "P5E_CPU1_P0_RX_DP<12>")
	)
	(segment
		(start 108.5723 -278.642064)
		(end 108.596176 -278.628348)
		(width 0.1143)
		(layer "In15.Cu")
		(net "P5E_CPU1_P0_RX_DP<12>")
	)
	(segment
		(start 108.60659 -282.510484)
		(end 108.605066 -282.509468)
		(width 0.1143)
		(layer "In15.Cu")
		(net "P5E_CPU1_P0_RX_DP<12>")
	)
	(segment
		(start 108.643166 -277.671784)
		(end 108.60659 -277.650448)
		(width 0.1143)
		(layer "In15.Cu")
		(net "P5E_CPU1_P0_RX_DP<12>")
	)
	(segment
		(start 108.605066 -294.823134)
		(end 108.643166 -294.800782)
		(width 0.1143)
		(layer "In15.Cu")
		(net "P5E_CPU1_P0_RX_DP<12>")
	)
	(segment
		(start 108.60405 -290.608766)
		(end 108.603288 -290.608258)
		(width 0.1143)
		(layer "In15.Cu")
		(net "P5E_CPU1_P0_RX_DP<12>")
	)
	(segment
		(start 62.948566 -385.460494)
		(end 62.948566 -385.046982)
		(width 0.14224)
		(layer "In15.Cu")
		(net "P5E_CPU1_P0_RX_DP<12>")
	)
	(segment
		(start 108.598208 -277.007066)
		(end 108.599732 -277.006304)
		(width 0.1143)
		(layer "In15.Cu")
		(net "P5E_CPU1_P0_RX_DP<12>")
	)
	(segment
		(start 108.622338 -274.418806)
		(end 108.594652 -274.403566)
		(width 0.1143)
		(layer "In15.Cu")
		(net "P5E_CPU1_P0_RX_DP<12>")
	)
	(segment
		(start 108.605066 -273.763232)
		(end 108.60659 -273.762216)
		(width 0.1143)
		(layer "In15.Cu")
		(net "P5E_CPU1_P0_RX_DP<12>")
	)
	(segment
		(start 108.599732 -273.76628)
		(end 108.600494 -273.765772)
		(width 0.1143)
		(layer "In15.Cu")
		(net "P5E_CPU1_P0_RX_DP<12>")
	)
	(segment
		(start 108.643166 -280.911808)
		(end 108.614464 -280.895044)
		(width 0.1143)
		(layer "In15.Cu")
		(net "P5E_CPU1_P0_RX_DP<12>")
	)
	(segment
		(start 108.60405 -280.243788)
		(end 108.605066 -280.24328)
		(width 0.1143)
		(layer "In15.Cu")
		(net "P5E_CPU1_P0_RX_DP<12>")
	)
	(segment
		(start 108.636308 -285.76778)
		(end 108.635546 -285.767272)
		(width 0.1143)
		(layer "In15.Cu")
		(net "P5E_CPU1_P0_RX_DP<12>")
	)
	(segment
		(start 108.643166 -279.291796)
		(end 108.60659 -279.27046)
		(width 0.1143)
		(layer "In15.Cu")
		(net "P5E_CPU1_P0_RX_DP<12>")
	)
	(segment
		(start 108.60405 -292.228778)
		(end 108.603288 -292.22827)
		(width 0.1143)
		(layer "In15.Cu")
		(net "P5E_CPU1_P0_RX_DP<12>")
	)
	(segment
		(start 109.04347 -272.971514)
		(end 109.07395 -272.953734)
		(width 0.1143)
		(layer "In15.Cu")
		(net "P5E_CPU1_P0_RX_DP<12>")
	)
	(segment
		(start 163.00704 -364.43666)
		(end 163.00704 -358.43464)
		(width 0.14224)
		(layer "In15.Cu")
		(net "P5E_CPU1_P0_RX_DP<12>")
	)
	(segment
		(start 108.572554 -289.982148)
		(end 108.642912 -289.941254)
		(width 0.1143)
		(layer "In15.Cu")
		(net "P5E_CPU1_P0_RX_DP<12>")
	)
	(segment
		(start 133.923786 -343.498932)
		(end 120.84558 -330.420726)
		(width 0.14224)
		(layer "In15.Cu")
		(net "P5E_CPU1_P0_RX_DP<12>")
	)
	(segment
		(start 108.5723 -294.84193)
		(end 108.596938 -294.827706)
		(width 0.1143)
		(layer "In15.Cu")
		(net "P5E_CPU1_P0_RX_DP<12>")
	)
	(segment
		(start 108.597446 -273.76755)
		(end 108.598208 -273.767042)
		(width 0.1143)
		(layer "In15.Cu")
		(net "P5E_CPU1_P0_RX_DP<12>")
	)
	(segment
		(start 108.596176 -278.628348)
		(end 108.597446 -278.627586)
		(width 0.1143)
		(layer "In15.Cu")
		(net "P5E_CPU1_P0_RX_DP<12>")
	)
	(segment
		(start 108.5723 -275.40204)
		(end 108.596176 -275.388324)
		(width 0.1143)
		(layer "In15.Cu")
		(net "P5E_CPU1_P0_RX_DP<12>")
	)
	(segment
		(start 108.635546 -290.627054)
		(end 108.60405 -290.608766)
		(width 0.1143)
		(layer "In15.Cu")
		(net "P5E_CPU1_P0_RX_DP<12>")
	)
	(segment
		(start 108.603288 -278.624284)
		(end 108.60405 -278.623776)
		(width 0.1143)
		(layer "In15.Cu")
		(net "P5E_CPU1_P0_RX_DP<12>")
	)
	(segment
		(start 108.597446 -280.247598)
		(end 108.598208 -280.24709)
		(width 0.1143)
		(layer "In15.Cu")
		(net "P5E_CPU1_P0_RX_DP<12>")
	)
	(segment
		(start 108.605066 -279.269444)
		(end 108.60405 -279.268936)
		(width 0.1143)
		(layer "In15.Cu")
		(net "P5E_CPU1_P0_RX_DP<12>")
	)
	(segment
		(start 108.600494 -294.825674)
		(end 108.602018 -294.824912)
		(width 0.1143)
		(layer "In15.Cu")
		(net "P5E_CPU1_P0_RX_DP<12>")
	)
	(segment
		(start 108.600494 -275.385784)
		(end 108.603288 -275.38426)
		(width 0.1143)
		(layer "In15.Cu")
		(net "P5E_CPU1_P0_RX_DP<12>")
	)
	(segment
		(start 108.46181 -296.042334)
		(end 108.41609 -295.996614)
		(width 0.1143)
		(layer "In15.Cu")
		(net "P5E_CPU1_P0_RX_DP<12>")
	)
	(segment
		(start 108.603288 -280.244296)
		(end 108.60405 -280.243788)
		(width 0.1143)
		(layer "In15.Cu")
		(net "P5E_CPU1_P0_RX_DP<12>")
	)
	(segment
		(start 108.636308 -293.867586)
		(end 108.635546 -293.867078)
		(width 0.1143)
		(layer "In15.Cu")
		(net "P5E_CPU1_P0_RX_DP<12>")
	)
	(segment
		(start 108.635546 -285.767272)
		(end 108.60405 -285.748984)
		(width 0.1143)
		(layer "In15.Cu")
		(net "P5E_CPU1_P0_RX_DP<12>")
	)
	(segment
		(start 108.605066 -280.889456)
		(end 108.60405 -280.888948)
		(width 0.1143)
		(layer "In15.Cu")
		(net "P5E_CPU1_P0_RX_DP<12>")
	)
	(segment
		(start 108.574078 -291.60089)
		(end 108.642658 -291.561266)
		(width 0.1143)
		(layer "In15.Cu")
		(net "P5E_CPU1_P0_RX_DP<12>")
	)
	(segment
		(start 153.5684 -357.274622)
		(end 151.678386 -355.384608)
		(width 0.14224)
		(layer "In15.Cu")
		(net "P5E_CPU1_P0_RX_DP<12>")
	)
	(segment
		(start 108.642912 -289.941254)
		(end 108.64342 -289.941)
		(width 0.1143)
		(layer "In15.Cu")
		(net "P5E_CPU1_P0_RX_DP<12>")
	)
	(segment
		(start 108.60659 -277.650448)
		(end 108.605066 -277.649432)
		(width 0.1143)
		(layer "In15.Cu")
		(net "P5E_CPU1_P0_RX_DP<12>")
	)
	(segment
		(start 108.635546 -293.867078)
		(end 108.60405 -293.84879)
		(width 0.1143)
		(layer "In15.Cu")
		(net "P5E_CPU1_P0_RX_DP<12>")
	)
	(segment
		(start 108.643166 -276.050502)
		(end 108.6231 -276.039326)
		(width 0.1143)
		(layer "In15.Cu")
		(net "P5E_CPU1_P0_RX_DP<12>")
	)
	(segment
		(start 108.60405 -278.623776)
		(end 108.605066 -278.623268)
		(width 0.1143)
		(layer "In15.Cu")
		(net "P5E_CPU1_P0_RX_DP<12>")
	)
	(segment
		(start 108.642658 -291.561266)
		(end 108.643166 -291.561012)
		(width 0.1143)
		(layer "In15.Cu")
		(net "P5E_CPU1_P0_RX_DP<12>")
	)
	(segment
		(start 108.636308 -289.00755)
		(end 108.635546 -289.007042)
		(width 0.1143)
		(layer "In15.Cu")
		(net "P5E_CPU1_P0_RX_DP<12>")
	)
	(segment
		(start 108.614464 -280.895044)
		(end 108.613194 -280.894282)
		(width 0.1143)
		(layer "In15.Cu")
		(net "P5E_CPU1_P0_RX_DP<12>")
	)
	(segment
		(start 108.643166 -276.051772)
		(end 108.643166 -276.050502)
		(width 0.1143)
		(layer "In15.Cu")
		(net "P5E_CPU1_P0_RX_DP<12>")
	)
	(segment
		(start 108.60405 -286.723836)
		(end 108.643166 -286.700976)
		(width 0.1143)
		(layer "In15.Cu")
		(net "P5E_CPU1_P0_RX_DP<12>")
	)
	(segment
		(start 108.5723 -277.022052)
		(end 108.596176 -277.008336)
		(width 0.1143)
		(layer "In15.Cu")
		(net "P5E_CPU1_P0_RX_DP<12>")
	)
	(segment
		(start 108.583222 -293.221918)
		(end 108.583222 -293.215568)
		(width 0.1143)
		(layer "In15.Cu")
		(net "P5E_CPU1_P0_RX_DP<12>")
	)
	(segment
		(start 108.640372 -281.842972)
		(end 108.643166 -281.84094)
		(width 0.1143)
		(layer "In15.Cu")
		(net "P5E_CPU1_P0_RX_DP<12>")
	)
	(segment
		(start 108.60405 -287.368742)
		(end 108.5723 -287.350454)
		(width 0.1143)
		(layer "In15.Cu")
		(net "P5E_CPU1_P0_RX_DP<12>")
	)
	(segment
		(start 108.60659 -273.762216)
		(end 108.643166 -273.74088)
		(width 0.1143)
		(layer "In15.Cu")
		(net "P5E_CPU1_P0_RX_DP<12>")
	)
	(segment
		(start 109.433106 -272.466308)
		(end 109.731048 -272.466308)
		(width 0.1143)
		(layer "In15.Cu")
		(net "P5E_CPU1_P0_RX_DP<12>")
	)
	(segment
		(start 108.598208 -275.387054)
		(end 108.599732 -275.386292)
		(width 0.1143)
		(layer "In15.Cu")
		(net "P5E_CPU1_P0_RX_DP<12>")
	)
	(segment
		(start 108.599732 -278.626316)
		(end 108.600494 -278.625808)
		(width 0.1143)
		(layer "In15.Cu")
		(net "P5E_CPU1_P0_RX_DP<12>")
	)
	(segment
		(start 108.603288 -294.82415)
		(end 108.60405 -294.823642)
		(width 0.1143)
		(layer "In15.Cu")
		(net "P5E_CPU1_P0_RX_DP<12>")
	)
	(segment
		(start 108.41609 -295.42359)
		(end 108.416344 -295.423336)
		(width 0.1143)
		(layer "In15.Cu")
		(net "P5E_CPU1_P0_RX_DP<12>")
	)
	(segment
		(start 62.940438 -384.048)
		(end 62.940438 -382.164082)
		(width 0.14224)
		(layer "In15.Cu")
		(net "P5E_CPU1_P0_RX_DP<12>")
	)
	(segment
		(start 108.602018 -290.607496)
		(end 108.5723 -290.590478)
		(width 0.1143)
		(layer "In15.Cu")
		(net "P5E_CPU1_P0_RX_DP<12>")
	)
	(segment
		(start 108.605066 -277.003256)
		(end 108.60659 -277.00224)
		(width 0.1143)
		(layer "In15.Cu")
		(net "P5E_CPU1_P0_RX_DP<12>")
	)
	(segment
		(start 108.622338 -276.038818)
		(end 108.594652 -276.023578)
		(width 0.1143)
		(layer "In15.Cu")
		(net "P5E_CPU1_P0_RX_DP<12>")
	)
	(segment
		(start 108.643166 -291.561012)
		(end 108.643166 -291.560758)
		(width 0.1143)
		(layer "In15.Cu")
		(net "P5E_CPU1_P0_RX_DP<12>")
	)
	(segment
		(start 108.596176 -273.768312)
		(end 108.597446 -273.76755)
		(width 0.1143)
		(layer "In15.Cu")
		(net "P5E_CPU1_P0_RX_DP<12>")
	)
	(segment
		(start 108.5723 -289.981894)
		(end 108.572554 -289.982148)
		(width 0.1143)
		(layer "In15.Cu")
		(net "P5E_CPU1_P0_RX_DP<12>")
	)
	(segment
		(start 108.636308 -290.627562)
		(end 108.635546 -290.627054)
		(width 0.1143)
		(layer "In15.Cu")
		(net "P5E_CPU1_P0_RX_DP<12>")
	)
	(segment
		(start 108.598208 -278.627078)
		(end 108.599732 -278.626316)
		(width 0.1143)
		(layer "In15.Cu")
		(net "P5E_CPU1_P0_RX_DP<12>")
	)
	(segment
		(start 108.60659 -280.242264)
		(end 108.643166 -280.220928)
		(width 0.1143)
		(layer "In15.Cu")
		(net "P5E_CPU1_P0_RX_DP<12>")
	)
	(segment
		(start 62.686184 -385.649216)
		(end 62.860428 -385.548632)
		(width 0.14224)
		(layer "In15.Cu")
		(net "P5E_CPU1_P0_RX_DP<12>")
	)
	(segment
		(start 108.599732 -280.246328)
		(end 108.600494 -280.24582)
		(width 0.1143)
		(layer "In15.Cu")
		(net "P5E_CPU1_P0_RX_DP<12>")
	)
	(segment
		(start 108.60659 -279.27046)
		(end 108.605066 -279.269444)
		(width 0.1143)
		(layer "In15.Cu")
		(net "P5E_CPU1_P0_RX_DP<12>")
	)
	(segment
		(start 109.97819 -365.069882)
		(end 162.373818 -365.069882)
		(width 0.14224)
		(layer "In15.Cu")
		(net "P5E_CPU1_P0_RX_DP<12>")
	)
	(segment
		(start 108.602018 -294.824912)
		(end 108.603288 -294.82415)
		(width 0.1143)
		(layer "In15.Cu")
		(net "P5E_CPU1_P0_RX_DP<12>")
	)
	(segment
		(start 108.597446 -277.007574)
		(end 108.598208 -277.007066)
		(width 0.1143)
		(layer "In15.Cu")
		(net "P5E_CPU1_P0_RX_DP<12>")
	)
	(segment
		(start 108.605066 -275.383244)
		(end 108.60659 -275.382228)
		(width 0.1143)
		(layer "In15.Cu")
		(net "P5E_CPU1_P0_RX_DP<12>")
	)
	(segment
		(start 108.597954 -294.827198)
		(end 108.600494 -294.825674)
		(width 0.1143)
		(layer "In15.Cu")
		(net "P5E_CPU1_P0_RX_DP<12>")
	)
	(segment
		(start 108.570522 -286.743394)
		(end 108.60405 -286.723836)
		(width 0.1143)
		(layer "In15.Cu")
		(net "P5E_CPU1_P0_RX_DP<12>")
	)
	(segment
		(start 108.60405 -282.50896)
		(end 108.5723 -282.490672)
		(width 0.1143)
		(layer "In15.Cu")
		(net "P5E_CPU1_P0_RX_DP<12>")
	)
	(segment
		(start 108.60659 -275.382228)
		(end 108.643166 -275.360892)
		(width 0.1143)
		(layer "In15.Cu")
		(net "P5E_CPU1_P0_RX_DP<12>")
	)
	(segment
		(start 108.643166 -284.151832)
		(end 108.60659 -284.130496)
		(width 0.1143)
		(layer "In15.Cu")
		(net "P5E_CPU1_P0_RX_DP<12>")
	)
	(segment
		(start 108.602018 -280.887678)
		(end 108.5723 -280.87066)
		(width 0.1143)
		(layer "In15.Cu")
		(net "P5E_CPU1_P0_RX_DP<12>")
	)
	(segment
		(start 108.570522 -288.363406)
		(end 108.60405 -288.343848)
		(width 0.1143)
		(layer "In15.Cu")
		(net "P5E_CPU1_P0_RX_DP<12>")
	)
	(segment
		(start 108.602018 -288.987484)
		(end 108.5723 -288.970466)
		(width 0.1143)
		(layer "In15.Cu")
		(net "P5E_CPU1_P0_RX_DP<12>")
	)
	(segment
		(start 162.466528 -357.894128)
		(end 155.063952 -357.894128)
		(width 0.14224)
		(layer "In15.Cu")
		(net "P5E_CPU1_P0_RX_DP<12>")
	)
	(segment
		(start 108.602018 -283.485082)
		(end 108.603288 -283.48432)
		(width 0.1143)
		(layer "In15.Cu")
		(net "P5E_CPU1_P0_RX_DP<12>")
	)
	(segment
		(start 108.5723 -283.5021)
		(end 108.602018 -283.485082)
		(width 0.1143)
		(layer "In15.Cu")
		(net "P5E_CPU1_P0_RX_DP<12>")
	)
	(segment
		(start 108.643166 -290.631626)
		(end 108.636308 -290.627562)
		(width 0.1143)
		(layer "In15.Cu")
		(net "P5E_CPU1_P0_RX_DP<12>")
	)
	(segment
		(start 108.602018 -292.227508)
		(end 108.5723 -292.21049)
		(width 0.1143)
		(layer "In15.Cu")
		(net "P5E_CPU1_P0_RX_DP<12>")
	)
	(segment
		(start 108.60405 -281.8638)
		(end 108.640372 -281.842972)
		(width 0.1143)
		(layer "In15.Cu")
		(net "P5E_CPU1_P0_RX_DP<12>")
	)
	(segment
		(start 108.60659 -277.00224)
		(end 108.643166 -276.980904)
		(width 0.1143)
		(layer "In15.Cu")
		(net "P5E_CPU1_P0_RX_DP<12>")
	)
	(segment
		(start 108.60405 -284.128972)
		(end 108.5723 -284.110684)
		(width 0.1143)
		(layer "In15.Cu")
		(net "P5E_CPU1_P0_RX_DP<12>")
	)
	(segment
		(start 62.860428 -385.548632)
		(end 62.948566 -385.460494)
		(width 0.14224)
		(layer "In15.Cu")
		(net "P5E_CPU1_P0_RX_DP<12>")
	)
	(segment
		(start 108.605066 -280.24328)
		(end 108.60659 -280.242264)
		(width 0.1143)
		(layer "In15.Cu")
		(net "P5E_CPU1_P0_RX_DP<12>")
	)
	(segment
		(start 108.597446 -278.627586)
		(end 108.598208 -278.627078)
		(width 0.1143)
		(layer "In15.Cu")
		(net "P5E_CPU1_P0_RX_DP<12>")
	)
	(segment
		(start 108.643166 -282.53182)
		(end 108.60659 -282.510484)
		(width 0.1143)
		(layer "In15.Cu")
		(net "P5E_CPU1_P0_RX_DP<12>")
	)
	(segment
		(start 108.640626 -287.390078)
		(end 108.60405 -287.368742)
		(width 0.1143)
		(layer "In15.Cu")
		(net "P5E_CPU1_P0_RX_DP<12>")
	)
	(segment
		(start 73.428098 -368.176302)
		(end 75.809602 -365.794798)
		(width 0.14224)
		(layer "In15.Cu")
		(net "P5E_CPU1_P0_RX_DP<12>")
	)
	(segment
		(start 108.60405 -293.84879)
		(end 108.603288 -293.848282)
		(width 0.1143)
		(layer "In15.Cu")
		(net "P5E_CPU1_P0_RX_DP<12>")
	)
	(segment
		(start 108.643166 -289.011614)
		(end 108.636308 -289.00755)
		(width 0.1143)
		(layer "In15.Cu")
		(net "P5E_CPU1_P0_RX_DP<12>")
	)
	(segment
		(start 108.603288 -288.988246)
		(end 108.602018 -288.987484)
		(width 0.1143)
		(layer "In15.Cu")
		(net "P5E_CPU1_P0_RX_DP<12>")
	)
	(arc
		(start 109.129322 -365.3282)
		(mid 109.534538 -365.135867)
		(end 109.97819 -365.069882)
		(width 0.14224)
		(layer "In15.Cu")
		(net "P5E_CPU1_P0_RX_DP<12>")
	)
	(arc
		(start 107.966764 -365.681514)
		(mid 108.574309 -365.591277)
		(end 109.129322 -365.3282)
		(width 0.14224)
		(layer "In15.Cu")
		(net "P5E_CPU1_P0_RX_DP<12>")
	)
	(arc
		(start 108.643166 -293.18077)
		(mid 108.886493 -292.716204)
		(end 108.643166 -292.251638)
		(width 0.1143)
		(layer "In15.Cu")
		(net "P5E_CPU1_P0_RX_DP<12>")
	)
	(arc
		(start 108.886498 -287.856422)
		(mid 108.821262 -287.592831)
		(end 108.640626 -287.390078)
		(width 0.1143)
		(layer "In15.Cu")
		(net "P5E_CPU1_P0_RX_DP<12>")
	)
	(arc
		(start 108.416344 -287.046162)
		(mid 108.457106 -286.876278)
		(end 108.570522 -286.743394)
		(width 0.1143)
		(layer "In15.Cu")
		(net "P5E_CPU1_P0_RX_DP<12>")
	)
	(arc
		(start 108.643166 -289.940746)
		(mid 108.886493 -289.47618)
		(end 108.643166 -289.011614)
		(width 0.1143)
		(layer "In15.Cu")
		(net "P5E_CPU1_P0_RX_DP<12>")
	)
	(arc
		(start 108.643166 -273.74088)
		(mid 108.821979 -273.53853)
		(end 108.886498 -273.276314)
		(width 0.1143)
		(layer "In15.Cu")
		(net "P5E_CPU1_P0_RX_DP<12>")
	)
	(arc
		(start 108.643166 -285.080964)
		(mid 108.886493 -284.616398)
		(end 108.643166 -284.151832)
		(width 0.1143)
		(layer "In15.Cu")
		(net "P5E_CPU1_P0_RX_DP<12>")
	)
	(arc
		(start 108.886498 -273.276314)
		(mid 108.928047 -273.104892)
		(end 109.04347 -272.971514)
		(width 0.1143)
		(layer "In15.Cu")
		(net "P5E_CPU1_P0_RX_DP<12>")
	)
	(arc
		(start 108.5723 -282.490672)
		(mid 108.416372 -282.18638)
		(end 108.5723 -281.882088)
		(width 0.1143)
		(layer "In15.Cu")
		(net "P5E_CPU1_P0_RX_DP<12>")
	)
	(arc
		(start 120.666764 -330.207366)
		(mid 120.520291 -329.971811)
		(end 120.400318 -329.721718)
		(width 0.14224)
		(layer "In15.Cu")
		(net "P5E_CPU1_P0_RX_DP<12>")
	)
	(arc
		(start 108.643166 -286.700976)
		(mid 108.886493 -286.23641)
		(end 108.643166 -285.771844)
		(width 0.1143)
		(layer "In15.Cu")
		(net "P5E_CPU1_P0_RX_DP<12>")
	)
	(arc
		(start 108.643166 -275.360892)
		(mid 108.886493 -274.896326)
		(end 108.643166 -274.43176)
		(width 0.1143)
		(layer "In15.Cu")
		(net "P5E_CPU1_P0_RX_DP<12>")
	)
	(arc
		(start 108.416344 -295.146222)
		(mid 108.457599 -294.975251)
		(end 108.5723 -294.84193)
		(width 0.1143)
		(layer "In15.Cu")
		(net "P5E_CPU1_P0_RX_DP<12>")
	)
	(arc
		(start 108.643166 -276.980904)
		(mid 108.886493 -276.516338)
		(end 108.643166 -276.051772)
		(width 0.1143)
		(layer "In15.Cu")
		(net "P5E_CPU1_P0_RX_DP<12>")
	)
	(arc
		(start 108.5723 -293.830502)
		(mid 108.416372 -293.52621)
		(end 108.5723 -293.221918)
		(width 0.1143)
		(layer "In15.Cu")
		(net "P5E_CPU1_P0_RX_DP<12>")
	)
	(arc
		(start 108.5723 -274.390612)
		(mid 108.416372 -274.08632)
		(end 108.5723 -273.782028)
		(width 0.1143)
		(layer "In15.Cu")
		(net "P5E_CPU1_P0_RX_DP<12>")
	)
	(arc
		(start 108.643166 -283.460952)
		(mid 108.886493 -282.996386)
		(end 108.643166 -282.53182)
		(width 0.1143)
		(layer "In15.Cu")
		(net "P5E_CPU1_P0_RX_DP<12>")
	)
	(arc
		(start 108.577888 -301.178214)
		(mid 108.506408 -300.963399)
		(end 108.466382 -300.740572)
		(width 0.14224)
		(layer "In15.Cu")
		(net "P5E_CPU1_P0_RX_DP<12>")
	)
	(arc
		(start 151.678386 -355.384608)
		(mid 151.610988 -355.323499)
		(end 151.537924 -355.269292)
		(width 0.14224)
		(layer "In15.Cu")
		(net "P5E_CPU1_P0_RX_DP<12>")
	)
	(arc
		(start 108.5723 -277.630636)
		(mid 108.416372 -277.326344)
		(end 108.5723 -277.022052)
		(width 0.1143)
		(layer "In15.Cu")
		(net "P5E_CPU1_P0_RX_DP<12>")
	)
	(arc
		(start 108.5723 -292.21049)
		(mid 108.416372 -291.906198)
		(end 108.5723 -291.601906)
		(width 0.1143)
		(layer "In15.Cu")
		(net "P5E_CPU1_P0_RX_DP<12>")
	)
	(arc
		(start 108.5723 -276.010624)
		(mid 108.416372 -275.706332)
		(end 108.5723 -275.40204)
		(width 0.1143)
		(layer "In15.Cu")
		(net "P5E_CPU1_P0_RX_DP<12>")
	)
	(arc
		(start 163.00704 -358.43464)
		(mid 162.848728 -358.05244)
		(end 162.466528 -357.894128)
		(width 0.14224)
		(layer "In15.Cu")
		(net "P5E_CPU1_P0_RX_DP<12>")
	)
	(arc
		(start 109.346492 -272.571972)
		(mid 109.348515 -272.560562)
		(end 109.350302 -272.549112)
		(width 0.1143)
		(layer "In15.Cu")
		(net "P5E_CPU1_P0_RX_DP<12>")
	)
	(arc
		(start 108.643166 -294.800782)
		(mid 108.886493 -294.336216)
		(end 108.643166 -293.87165)
		(width 0.1143)
		(layer "In15.Cu")
		(net "P5E_CPU1_P0_RX_DP<12>")
	)
	(arc
		(start 155.063952 -357.894128)
		(mid 154.254554 -357.733129)
		(end 153.5684 -357.274622)
		(width 0.14224)
		(layer "In15.Cu")
		(net "P5E_CPU1_P0_RX_DP<12>")
	)
	(arc
		(start 108.5723 -280.87066)
		(mid 108.416372 -280.566368)
		(end 108.5723 -280.262076)
		(width 0.1143)
		(layer "In15.Cu")
		(net "P5E_CPU1_P0_RX_DP<12>")
	)
	(arc
		(start 108.643166 -288.320988)
		(mid 108.821979 -288.118638)
		(end 108.886498 -287.856422)
		(width 0.1143)
		(layer "In15.Cu")
		(net "P5E_CPU1_P0_RX_DP<12>")
	)
	(arc
		(start 108.416344 -288.666174)
		(mid 108.457106 -288.49629)
		(end 108.570522 -288.363406)
		(width 0.1143)
		(layer "In15.Cu")
		(net "P5E_CPU1_P0_RX_DP<12>")
	)
	(arc
		(start 108.643166 -280.220928)
		(mid 108.886493 -279.756362)
		(end 108.643166 -279.291796)
		(width 0.1143)
		(layer "In15.Cu")
		(net "P5E_CPU1_P0_RX_DP<12>")
	)
	(arc
		(start 162.373818 -365.069882)
		(mid 162.821574 -364.884416)
		(end 163.00704 -364.43666)
		(width 0.14224)
		(layer "In15.Cu")
		(net "P5E_CPU1_P0_RX_DP<12>")
	)
	(arc
		(start 108.466382 -300.740572)
		(mid 108.463011 -300.698721)
		(end 108.46181 -300.656752)
		(width 0.14224)
		(layer "In15.Cu")
		(net "P5E_CPU1_P0_RX_DP<12>")
	)
	(arc
		(start 109.113066 -272.930874)
		(mid 109.265053 -272.774366)
		(end 109.346492 -272.571972)
		(width 0.1143)
		(layer "In15.Cu")
		(net "P5E_CPU1_P0_RX_DP<12>")
	)
	(arc
		(start 108.5723 -287.350454)
		(mid 108.457624 -287.21712)
		(end 108.416344 -287.046162)
		(width 0.1143)
		(layer "In15.Cu")
		(net "P5E_CPU1_P0_RX_DP<12>")
	)
	(arc
		(start 108.643166 -281.84094)
		(mid 108.886493 -281.376374)
		(end 108.643166 -280.911808)
		(width 0.1143)
		(layer "In15.Cu")
		(net "P5E_CPU1_P0_RX_DP<12>")
	)
	(arc
		(start 108.5723 -279.250648)
		(mid 108.416372 -278.946356)
		(end 108.5723 -278.642064)
		(width 0.1143)
		(layer "In15.Cu")
		(net "P5E_CPU1_P0_RX_DP<12>")
	)
	(arc
		(start 108.5723 -288.970466)
		(mid 108.457624 -288.837132)
		(end 108.416344 -288.666174)
		(width 0.1143)
		(layer "In15.Cu")
		(net "P5E_CPU1_P0_RX_DP<12>")
	)
	(arc
		(start 108.5723 -285.730696)
		(mid 108.416372 -285.426404)
		(end 108.5723 -285.122112)
		(width 0.1143)
		(layer "In15.Cu")
		(net "P5E_CPU1_P0_RX_DP<12>")
	)
	(arc
		(start 62.940438 -382.164082)
		(mid 62.951299 -382.092479)
		(end 62.98311 -382.02743)
		(width 0.14224)
		(layer "In15.Cu")
		(net "P5E_CPU1_P0_RX_DP<12>")
	)
	(arc
		(start 108.643166 -291.560758)
		(mid 108.886493 -291.096192)
		(end 108.643166 -290.631626)
		(width 0.1143)
		(layer "In15.Cu")
		(net "P5E_CPU1_P0_RX_DP<12>")
	)
	(arc
		(start 120.84558 -330.420726)
		(mid 120.751492 -330.317968)
		(end 120.666764 -330.207366)
		(width 0.14224)
		(layer "In15.Cu")
		(net "P5E_CPU1_P0_RX_DP<12>")
	)
	(arc
		(start 75.809602 -365.794798)
		(mid 75.859749 -365.755501)
		(end 75.917806 -365.729266)
		(width 0.14224)
		(layer "In15.Cu")
		(net "P5E_CPU1_P0_RX_DP<12>")
	)
	(arc
		(start 108.643166 -278.600916)
		(mid 108.886493 -278.13635)
		(end 108.643166 -277.671784)
		(width 0.1143)
		(layer "In15.Cu")
		(net "P5E_CPU1_P0_RX_DP<12>")
	)
	(arc
		(start 75.917806 -365.729266)
		(mid 76.07041 -365.693574)
		(end 76.22667 -365.681514)
		(width 0.14224)
		(layer "In15.Cu")
		(net "P5E_CPU1_P0_RX_DP<12>")
	)
	(arc
		(start 108.5723 -290.590478)
		(mid 108.416372 -290.286186)
		(end 108.5723 -289.981894)
		(width 0.1143)
		(layer "In15.Cu")
		(net "P5E_CPU1_P0_RX_DP<12>")
	)
	(arc
		(start 108.5723 -284.110684)
		(mid 108.416372 -283.806392)
		(end 108.5723 -283.5021)
		(width 0.1143)
		(layer "In15.Cu")
		(net "P5E_CPU1_P0_RX_DP<12>")
	)
	(segment
		(start 107.847892 -269.770352)
		(end 107.38104 -270.03629)
		(width 0.12954)
		(layer "F.Cu")
		(net "P5E_CPU1_P0_RX_DP<11>")
	)
	(segment
		(start 60.870592 -386.003292)
		(end 61.391292 -386.003292)
		(width 0.127)
		(layer "F.Cu")
		(net "P5E_CPU1_P0_RX_DP<11>")
	)
	(segment
		(start 107.70235 -292.25113)
		(end 107.696 -292.24732)
		(width 0.1143)
		(layer "In15.Cu")
		(net "P5E_CPU1_P0_RX_DP<11>")
	)
	(segment
		(start 107.665012 -272.14322)
		(end 107.666536 -272.142204)
		(width 0.1143)
		(layer "In15.Cu")
		(net "P5E_CPU1_P0_RX_DP<11>")
	)
	(segment
		(start 107.296204 -296.584116)
		(end 107.250484 -296.538396)
		(width 0.1143)
		(layer "In15.Cu")
		(net "P5E_CPU1_P0_RX_DP<11>")
	)
	(segment
		(start 107.666536 -279.27046)
		(end 107.665012 -279.269444)
		(width 0.1143)
		(layer "In15.Cu")
		(net "P5E_CPU1_P0_RX_DP<11>")
	)
	(segment
		(start 107.666536 -274.410424)
		(end 107.665012 -274.409408)
		(width 0.1143)
		(layer "In15.Cu")
		(net "P5E_CPU1_P0_RX_DP<11>")
	)
	(segment
		(start 107.632246 -293.221918)
		(end 107.663996 -293.20363)
		(width 0.1143)
		(layer "In15.Cu")
		(net "P5E_CPU1_P0_RX_DP<11>")
	)
	(segment
		(start 107.632246 -273.782028)
		(end 107.663234 -273.764248)
		(width 0.1143)
		(layer "In15.Cu")
		(net "P5E_CPU1_P0_RX_DP<11>")
	)
	(segment
		(start 107.663234 -271.168368)
		(end 107.632246 -271.150588)
		(width 0.1143)
		(layer "In15.Cu")
		(net "P5E_CPU1_P0_RX_DP<11>")
	)
	(segment
		(start 107.663996 -282.50896)
		(end 107.663234 -282.508452)
		(width 0.1143)
		(layer "In15.Cu")
		(net "P5E_CPU1_P0_RX_DP<11>")
	)
	(segment
		(start 107.663996 -285.103824)
		(end 107.665012 -285.103316)
		(width 0.1143)
		(layer "In15.Cu")
		(net "P5E_CPU1_P0_RX_DP<11>")
	)
	(segment
		(start 72.588628 -367.6523)
		(end 75.445874 -364.7948)
		(width 0.14224)
		(layer "In15.Cu")
		(net "P5E_CPU1_P0_RX_DP<11>")
	)
	(segment
		(start 107.632246 -277.630636)
		(end 107.612434 -277.616412)
		(width 0.1143)
		(layer "In15.Cu")
		(net "P5E_CPU1_P0_RX_DP<11>")
	)
	(segment
		(start 107.666536 -273.762216)
		(end 107.703112 -273.74088)
		(width 0.1143)
		(layer "In15.Cu")
		(net "P5E_CPU1_P0_RX_DP<11>")
	)
	(segment
		(start 107.666536 -272.142204)
		(end 107.703112 -272.120868)
		(width 0.1143)
		(layer "In15.Cu")
		(net "P5E_CPU1_P0_RX_DP<11>")
	)
	(segment
		(start 107.663996 -276.028912)
		(end 107.663234 -276.028404)
		(width 0.1143)
		(layer "In15.Cu")
		(net "P5E_CPU1_P0_RX_DP<11>")
	)
	(segment
		(start 107.663234 -285.748476)
		(end 107.632246 -285.730696)
		(width 0.1143)
		(layer "In15.Cu")
		(net "P5E_CPU1_P0_RX_DP<11>")
	)
	(segment
		(start 107.663488 -289.96386)
		(end 107.684824 -289.951414)
		(width 0.1143)
		(layer "In15.Cu")
		(net "P5E_CPU1_P0_RX_DP<11>")
	)
	(segment
		(start 107.697524 -288.323782)
		(end 107.703112 -288.320988)
		(width 0.1143)
		(layer "In15.Cu")
		(net "P5E_CPU1_P0_RX_DP<11>")
	)
	(segment
		(start 107.703112 -274.43176)
		(end 107.666536 -274.410424)
		(width 0.1143)
		(layer "In15.Cu")
		(net "P5E_CPU1_P0_RX_DP<11>")
	)
	(segment
		(start 107.696 -292.24732)
		(end 107.672124 -292.233604)
		(width 0.1143)
		(layer "In15.Cu")
		(net "P5E_CPU1_P0_RX_DP<11>")
	)
	(segment
		(start 107.654344 -287.362392)
		(end 107.54741 -287.255458)
		(width 0.1143)
		(layer "In15.Cu")
		(net "P5E_CPU1_P0_RX_DP<11>")
	)
	(segment
		(start 61.660532 -385.548632)
		(end 61.74867 -385.460494)
		(width 0.14224)
		(layer "In15.Cu")
		(net "P5E_CPU1_P0_RX_DP<11>")
	)
	(segment
		(start 107.669584 -277.000462)
		(end 107.703112 -276.980904)
		(width 0.1143)
		(layer "In15.Cu")
		(net "P5E_CPU1_P0_RX_DP<11>")
	)
	(segment
		(start 107.663996 -271.168876)
		(end 107.663234 -271.168368)
		(width 0.1143)
		(layer "In15.Cu")
		(net "P5E_CPU1_P0_RX_DP<11>")
	)
	(segment
		(start 107.666536 -282.510484)
		(end 107.665012 -282.509468)
		(width 0.1143)
		(layer "In15.Cu")
		(net "P5E_CPU1_P0_RX_DP<11>")
	)
	(segment
		(start 107.663234 -293.848282)
		(end 107.632246 -293.830502)
		(width 0.1143)
		(layer "In15.Cu")
		(net "P5E_CPU1_P0_RX_DP<11>")
	)
	(segment
		(start 107.250484 -296.538396)
		(end 107.250484 -296.34053)
		(width 0.1143)
		(layer "In15.Cu")
		(net "P5E_CPU1_P0_RX_DP<11>")
	)
	(segment
		(start 107.663996 -281.8638)
		(end 107.665012 -281.863292)
		(width 0.1143)
		(layer "In15.Cu")
		(net "P5E_CPU1_P0_RX_DP<11>")
	)
	(segment
		(start 107.663996 -283.483812)
		(end 107.665012 -283.483304)
		(width 0.1143)
		(layer "In15.Cu")
		(net "P5E_CPU1_P0_RX_DP<11>")
	)
	(segment
		(start 107.703112 -284.151832)
		(end 107.666536 -284.130496)
		(width 0.1143)
		(layer "In15.Cu")
		(net "P5E_CPU1_P0_RX_DP<11>")
	)
	(segment
		(start 61.435742 -384.3528)
		(end 61.740542 -384.048)
		(width 0.14224)
		(layer "In15.Cu")
		(net "P5E_CPU1_P0_RX_DP<11>")
	)
	(segment
		(start 61.740542 -384.048)
		(end 61.740542 -382.128522)
		(width 0.14224)
		(layer "In15.Cu")
		(net "P5E_CPU1_P0_RX_DP<11>")
	)
	(segment
		(start 107.663996 -280.888948)
		(end 107.663234 -280.88844)
		(width 0.1143)
		(layer "In15.Cu")
		(net "P5E_CPU1_P0_RX_DP<11>")
	)
	(segment
		(start 107.665012 -294.823134)
		(end 107.703112 -294.800782)
		(width 0.1143)
		(layer "In15.Cu")
		(net "P5E_CPU1_P0_RX_DP<11>")
	)
	(segment
		(start 107.695492 -293.867078)
		(end 107.665012 -293.849298)
		(width 0.1143)
		(layer "In15.Cu")
		(net "P5E_CPU1_P0_RX_DP<11>")
	)
	(segment
		(start 107.663234 -284.128464)
		(end 107.632246 -284.110684)
		(width 0.1143)
		(layer "In15.Cu")
		(net "P5E_CPU1_P0_RX_DP<11>")
	)
	(segment
		(start 107.665012 -275.383244)
		(end 107.66679 -275.382228)
		(width 0.1143)
		(layer "In15.Cu")
		(net "P5E_CPU1_P0_RX_DP<11>")
	)
	(segment
		(start 67.329304 -373.992394)
		(end 72.588628 -367.6523)
		(width 0.14224)
		(layer "In15.Cu")
		(net "P5E_CPU1_P0_RX_DP<11>")
	)
	(segment
		(start 107.703112 -276.051772)
		(end 107.666536 -276.030436)
		(width 0.1143)
		(layer "In15.Cu")
		(net "P5E_CPU1_P0_RX_DP<11>")
	)
	(segment
		(start 107.663234 -282.508452)
		(end 107.632246 -282.490672)
		(width 0.1143)
		(layer "In15.Cu")
		(net "P5E_CPU1_P0_RX_DP<11>")
	)
	(segment
		(start 107.650788 -288.351214)
		(end 107.651042 -288.35096)
		(width 0.1143)
		(layer "In15.Cu")
		(net "P5E_CPU1_P0_RX_DP<11>")
	)
	(segment
		(start 107.612434 -283.516324)
		(end 107.632246 -283.5021)
		(width 0.1143)
		(layer "In15.Cu")
		(net "P5E_CPU1_P0_RX_DP<11>")
	)
	(segment
		(start 107.632246 -279.250648)
		(end 107.612434 -279.236424)
		(width 0.1143)
		(layer "In15.Cu")
		(net "P5E_CPU1_P0_RX_DP<11>")
	)
	(segment
		(start 107.666536 -276.030436)
		(end 107.665012 -276.02942)
		(width 0.1143)
		(layer "In15.Cu")
		(net "P5E_CPU1_P0_RX_DP<11>")
	)
	(segment
		(start 107.663996 -279.268936)
		(end 107.663234 -279.268428)
		(width 0.1143)
		(layer "In15.Cu")
		(net "P5E_CPU1_P0_RX_DP<11>")
	)
	(segment
		(start 107.632246 -280.262076)
		(end 107.663234 -280.244296)
		(width 0.1143)
		(layer "In15.Cu")
		(net "P5E_CPU1_P0_RX_DP<11>")
	)
	(segment
		(start 107.663234 -281.864308)
		(end 107.663996 -281.8638)
		(width 0.1143)
		(layer "In15.Cu")
		(net "P5E_CPU1_P0_RX_DP<11>")
	)
	(segment
		(start 107.296204 -300.735492)
		(end 107.296204 -296.612564)
		(width 0.14224)
		(layer "In15.Cu")
		(net "P5E_CPU1_P0_RX_DP<11>")
	)
	(segment
		(start 107.70235 -287.391094)
		(end 107.70235 -287.391348)
		(width 0.1143)
		(layer "In15.Cu")
		(net "P5E_CPU1_P0_RX_DP<11>")
	)
	(segment
		(start 107.663234 -276.028404)
		(end 107.632246 -276.010624)
		(width 0.1143)
		(layer "In15.Cu")
		(net "P5E_CPU1_P0_RX_DP<11>")
	)
	(segment
		(start 107.665012 -281.863292)
		(end 107.703112 -281.84094)
		(width 0.1143)
		(layer "In15.Cu")
		(net "P5E_CPU1_P0_RX_DP<11>")
	)
	(segment
		(start 107.665012 -276.02942)
		(end 107.663996 -276.028912)
		(width 0.1143)
		(layer "In15.Cu")
		(net "P5E_CPU1_P0_RX_DP<11>")
	)
	(segment
		(start 107.666536 -284.130496)
		(end 107.665012 -284.12948)
		(width 0.1143)
		(layer "In15.Cu")
		(net "P5E_CPU1_P0_RX_DP<11>")
	)
	(segment
		(start 107.700318 -293.182802)
		(end 107.703112 -293.18077)
		(width 0.1143)
		(layer "In15.Cu")
		(net "P5E_CPU1_P0_RX_DP<11>")
	)
	(segment
		(start 107.648502 -294.832278)
		(end 107.663234 -294.82415)
		(width 0.1143)
		(layer "In15.Cu")
		(net "P5E_CPU1_P0_RX_DP<11>")
	)
	(segment
		(start 107.663996 -272.788888)
		(end 107.663234 -272.78838)
		(width 0.1143)
		(layer "In15.Cu")
		(net "P5E_CPU1_P0_RX_DP<11>")
	)
	(segment
		(start 107.657392 -287.364424)
		(end 107.654344 -287.362392)
		(width 0.1143)
		(layer "In15.Cu")
		(net "P5E_CPU1_P0_RX_DP<11>")
	)
	(segment
		(start 75.884278 -364.664244)
		(end 106.810302 -364.664244)
		(width 0.14224)
		(layer "In15.Cu")
		(net "P5E_CPU1_P0_RX_DP<11>")
	)
	(segment
		(start 107.663234 -272.144236)
		(end 107.663996 -272.143728)
		(width 0.1143)
		(layer "In15.Cu")
		(net "P5E_CPU1_P0_RX_DP<11>")
	)
	(segment
		(start 107.665012 -280.24328)
		(end 107.703112 -280.220928)
		(width 0.1143)
		(layer "In15.Cu")
		(net "P5E_CPU1_P0_RX_DP<11>")
	)
	(segment
		(start 107.67568 -275.377148)
		(end 107.703112 -275.360892)
		(width 0.1143)
		(layer "In15.Cu")
		(net "P5E_CPU1_P0_RX_DP<11>")
	)
	(segment
		(start 107.632246 -281.882088)
		(end 107.663234 -281.864308)
		(width 0.1143)
		(layer "In15.Cu")
		(net "P5E_CPU1_P0_RX_DP<11>")
	)
	(segment
		(start 107.632246 -285.122112)
		(end 107.663234 -285.104332)
		(width 0.1143)
		(layer "In15.Cu")
		(net "P5E_CPU1_P0_RX_DP<11>")
	)
	(segment
		(start 107.663996 -280.243788)
		(end 107.665012 -280.24328)
		(width 0.1143)
		(layer "In15.Cu")
		(net "P5E_CPU1_P0_RX_DP<11>")
	)
	(segment
		(start 107.66933 -292.231826)
		(end 107.668568 -292.231318)
		(width 0.1143)
		(layer "In15.Cu")
		(net "P5E_CPU1_P0_RX_DP<11>")
	)
	(segment
		(start 107.695492 -272.807176)
		(end 107.663996 -272.788888)
		(width 0.1143)
		(layer "In15.Cu")
		(net "P5E_CPU1_P0_RX_DP<11>")
	)
	(segment
		(start 107.612434 -275.416264)
		(end 107.632246 -275.40204)
		(width 0.1143)
		(layer "In15.Cu")
		(net "P5E_CPU1_P0_RX_DP<11>")
	)
	(segment
		(start 107.665012 -280.889456)
		(end 107.663996 -280.888948)
		(width 0.1143)
		(layer "In15.Cu")
		(net "P5E_CPU1_P0_RX_DP<11>")
	)
	(segment
		(start 107.632246 -280.87066)
		(end 107.61345 -280.856944)
		(width 0.1143)
		(layer "In15.Cu")
		(net "P5E_CPU1_P0_RX_DP<11>")
	)
	(segment
		(start 108.976922 -364.114334)
		(end 160.993074 -364.114334)
		(width 0.14224)
		(layer "In15.Cu")
		(net "P5E_CPU1_P0_RX_DP<11>")
	)
	(segment
		(start 107.00639 -296.048684)
		(end 107.00639 -295.939464)
		(width 0.1143)
		(layer "In15.Cu")
		(net "P5E_CPU1_P0_RX_DP<11>")
	)
	(segment
		(start 107.632246 -283.5021)
		(end 107.663234 -283.48432)
		(width 0.1143)
		(layer "In15.Cu")
		(net "P5E_CPU1_P0_RX_DP<11>")
	)
	(segment
		(start 107.194096 -270.35887)
		(end 107.162346 -270.340582)
		(width 0.1143)
		(layer "In15.Cu")
		(net "P5E_CPU1_P0_RX_DP<11>")
	)
	(segment
		(start 107.665012 -277.003256)
		(end 107.669584 -277.000462)
		(width 0.1143)
		(layer "In15.Cu")
		(net "P5E_CPU1_P0_RX_DP<11>")
	)
	(segment
		(start 107.663234 -275.38426)
		(end 107.663996 -275.383752)
		(width 0.1143)
		(layer "In15.Cu")
		(net "P5E_CPU1_P0_RX_DP<11>")
	)
	(segment
		(start 61.74867 -385.046982)
		(end 61.432694 -384.731006)
		(width 0.14224)
		(layer "In15.Cu")
		(net "P5E_CPU1_P0_RX_DP<11>")
	)
	(segment
		(start 107.685078 -291.571426)
		(end 107.703112 -291.560758)
		(width 0.1143)
		(layer "In15.Cu")
		(net "P5E_CPU1_P0_RX_DP<11>")
	)
	(segment
		(start 107.663234 -277.648416)
		(end 107.632246 -277.630636)
		(width 0.1143)
		(layer "In15.Cu")
		(net "P5E_CPU1_P0_RX_DP<11>")
	)
	(segment
		(start 107.67441 -275.37791)
		(end 107.67568 -275.377148)
		(width 0.1143)
		(layer "In15.Cu")
		(net "P5E_CPU1_P0_RX_DP<11>")
	)
	(segment
		(start 107.663996 -286.723836)
		(end 107.682284 -286.713168)
		(width 0.1143)
		(layer "In15.Cu")
		(net "P5E_CPU1_P0_RX_DP<11>")
	)
	(segment
		(start 107.250484 -296.34053)
		(end 107.188762 -296.283888)
		(width 0.1143)
		(layer "In15.Cu")
		(net "P5E_CPU1_P0_RX_DP<11>")
	)
	(segment
		(start 107.632246 -272.162016)
		(end 107.663234 -272.144236)
		(width 0.1143)
		(layer "In15.Cu")
		(net "P5E_CPU1_P0_RX_DP<11>")
	)
	(segment
		(start 107.665012 -274.409408)
		(end 107.663996 -274.4089)
		(width 0.1143)
		(layer "In15.Cu")
		(net "P5E_CPU1_P0_RX_DP<11>")
	)
	(segment
		(start 61.391292 -386.003292)
		(end 61.486288 -385.649216)
		(width 0.14224)
		(layer "In15.Cu")
		(net "P5E_CPU1_P0_RX_DP<11>")
	)
	(segment
		(start 107.216194 -270.37157)
		(end 107.215432 -270.371062)
		(width 0.1143)
		(layer "In15.Cu")
		(net "P5E_CPU1_P0_RX_DP<11>")
	)
	(segment
		(start 107.663996 -284.128972)
		(end 107.663234 -284.128464)
		(width 0.1143)
		(layer "In15.Cu")
		(net "P5E_CPU1_P0_RX_DP<11>")
	)
	(segment
		(start 107.663996 -278.623776)
		(end 107.665012 -278.623268)
		(width 0.1143)
		(layer "In15.Cu")
		(net "P5E_CPU1_P0_RX_DP<11>")
	)
	(segment
		(start 61.763148 -382.056386)
		(end 67.329304 -373.992394)
		(width 0.14224)
		(layer "In15.Cu")
		(net "P5E_CPU1_P0_RX_DP<11>")
	)
	(segment
		(start 107.665012 -285.749492)
		(end 107.663996 -285.748984)
		(width 0.1143)
		(layer "In15.Cu")
		(net "P5E_CPU1_P0_RX_DP<11>")
	)
	(segment
		(start 107.696254 -271.187672)
		(end 107.695492 -271.187164)
		(width 0.1143)
		(layer "In15.Cu")
		(net "P5E_CPU1_P0_RX_DP<11>")
	)
	(segment
		(start 107.632246 -275.40204)
		(end 107.663234 -275.38426)
		(width 0.1143)
		(layer "In15.Cu")
		(net "P5E_CPU1_P0_RX_DP<11>")
	)
	(segment
		(start 107.612434 -278.656288)
		(end 107.632246 -278.642064)
		(width 0.1143)
		(layer "In15.Cu")
		(net "P5E_CPU1_P0_RX_DP<11>")
	)
	(segment
		(start 107.665012 -293.849298)
		(end 107.663996 -293.84879)
		(width 0.1143)
		(layer "In15.Cu")
		(net "P5E_CPU1_P0_RX_DP<11>")
	)
	(segment
		(start 107.663234 -283.48432)
		(end 107.663996 -283.483812)
		(width 0.1143)
		(layer "In15.Cu")
		(net "P5E_CPU1_P0_RX_DP<11>")
	)
	(segment
		(start 107.670346 -290.612322)
		(end 107.656122 -290.604194)
		(width 0.1143)
		(layer "In15.Cu")
		(net "P5E_CPU1_P0_RX_DP<11>")
	)
	(segment
		(start 107.663996 -277.648924)
		(end 107.663234 -277.648416)
		(width 0.1143)
		(layer "In15.Cu")
		(net "P5E_CPU1_P0_RX_DP<11>")
	)
	(segment
		(start 107.663234 -279.268428)
		(end 107.632246 -279.250648)
		(width 0.1143)
		(layer "In15.Cu")
		(net "P5E_CPU1_P0_RX_DP<11>")
	)
	(segment
		(start 107.696254 -293.867586)
		(end 107.695492 -293.867078)
		(width 0.1143)
		(layer "In15.Cu")
		(net "P5E_CPU1_P0_RX_DP<11>")
	)
	(segment
		(start 107.663234 -273.764248)
		(end 107.663996 -273.76374)
		(width 0.1143)
		(layer "In15.Cu")
		(net "P5E_CPU1_P0_RX_DP<11>")
	)
	(segment
		(start 107.695492 -271.187164)
		(end 107.663996 -271.168876)
		(width 0.1143)
		(layer "In15.Cu")
		(net "P5E_CPU1_P0_RX_DP<11>")
	)
	(segment
		(start 107.666536 -277.650448)
		(end 107.665012 -277.649432)
		(width 0.1143)
		(layer "In15.Cu")
		(net "P5E_CPU1_P0_RX_DP<11>")
	)
	(segment
		(start 107.188762 -296.283888)
		(end 107.043982 -296.138854)
		(width 0.1143)
		(layer "In15.Cu")
		(net "P5E_CPU1_P0_RX_DP<11>")
	)
	(segment
		(start 107.612434 -281.896312)
		(end 107.632246 -281.882088)
		(width 0.1143)
		(layer "In15.Cu")
		(net "P5E_CPU1_P0_RX_DP<11>")
	)
	(segment
		(start 107.698794 -287.389316)
		(end 107.657392 -287.364424)
		(width 0.1143)
		(layer "In15.Cu")
		(net "P5E_CPU1_P0_RX_DP<11>")
	)
	(segment
		(start 107.634278 -286.7406)
		(end 107.663488 -286.723582)
		(width 0.1143)
		(layer "In15.Cu")
		(net "P5E_CPU1_P0_RX_DP<11>")
	)
	(segment
		(start 107.663996 -293.84879)
		(end 107.663234 -293.848282)
		(width 0.1143)
		(layer "In15.Cu")
		(net "P5E_CPU1_P0_RX_DP<11>")
	)
	(segment
		(start 107.083098 -270.03629)
		(end 107.38104 -270.03629)
		(width 0.1143)
		(layer "In15.Cu")
		(net "P5E_CPU1_P0_RX_DP<11>")
	)
	(segment
		(start 107.70235 -287.391348)
		(end 107.698794 -287.389316)
		(width 0.1143)
		(layer "In15.Cu")
		(net "P5E_CPU1_P0_RX_DP<11>")
	)
	(segment
		(start 107.703112 -280.911808)
		(end 107.665012 -280.889456)
		(width 0.1143)
		(layer "In15.Cu")
		(net "P5E_CPU1_P0_RX_DP<11>")
	)
	(segment
		(start 107.663996 -294.823642)
		(end 107.665012 -294.823134)
		(width 0.1143)
		(layer "In15.Cu")
		(net "P5E_CPU1_P0_RX_DP<11>")
	)
	(segment
		(start 160.86582 -358.896158)
		(end 154.656282 -358.896158)
		(width 0.14224)
		(layer "In15.Cu")
		(net "P5E_CPU1_P0_RX_DP<11>")
	)
	(segment
		(start 107.663234 -272.78838)
		(end 107.632246 -272.7706)
		(width 0.1143)
		(layer "In15.Cu")
		(net "P5E_CPU1_P0_RX_DP<11>")
	)
	(segment
		(start 107.632246 -282.490672)
		(end 107.612434 -282.476448)
		(width 0.1143)
		(layer "In15.Cu")
		(net "P5E_CPU1_P0_RX_DP<11>")
	)
	(segment
		(start 107.672124 -292.233604)
		(end 107.66933 -292.231826)
		(width 0.1143)
		(layer "In15.Cu")
		(net "P5E_CPU1_P0_RX_DP<11>")
	)
	(segment
		(start 107.664504 -288.34334)
		(end 107.697524 -288.323782)
		(width 0.1143)
		(layer "In15.Cu")
		(net "P5E_CPU1_P0_RX_DP<11>")
	)
	(segment
		(start 107.703112 -279.291796)
		(end 107.666536 -279.27046)
		(width 0.1143)
		(layer "In15.Cu")
		(net "P5E_CPU1_P0_RX_DP<11>")
	)
	(segment
		(start 107.632246 -276.010624)
		(end 107.612434 -275.9964)
		(width 0.1143)
		(layer "In15.Cu")
		(net "P5E_CPU1_P0_RX_DP<11>")
	)
	(segment
		(start 107.663996 -275.383752)
		(end 107.665012 -275.383244)
		(width 0.1143)
		(layer "In15.Cu")
		(net "P5E_CPU1_P0_RX_DP<11>")
	)
	(segment
		(start 107.703112 -282.53182)
		(end 107.666536 -282.510484)
		(width 0.1143)
		(layer "In15.Cu")
		(net "P5E_CPU1_P0_RX_DP<11>")
	)
	(segment
		(start 107.663996 -277.003764)
		(end 107.665012 -277.003256)
		(width 0.1143)
		(layer "In15.Cu")
		(net "P5E_CPU1_P0_RX_DP<11>")
	)
	(segment
		(start 150.40102 -355.689408)
		(end 133.292596 -344.257884)
		(width 0.14224)
		(layer "In15.Cu")
		(net "P5E_CPU1_P0_RX_DP<11>")
	)
	(segment
		(start 107.672632 -290.613846)
		(end 107.670346 -290.612322)
		(width 0.1143)
		(layer "In15.Cu")
		(net "P5E_CPU1_P0_RX_DP<11>")
	)
	(segment
		(start 107.703112 -272.811748)
		(end 107.696254 -272.807684)
		(width 0.1143)
		(layer "In15.Cu")
		(net "P5E_CPU1_P0_RX_DP<11>")
	)
	(segment
		(start 107.663996 -274.4089)
		(end 107.663234 -274.408392)
		(width 0.1143)
		(layer "In15.Cu")
		(net "P5E_CPU1_P0_RX_DP<11>")
	)
	(segment
		(start 107.6706 -275.380196)
		(end 107.672886 -275.378926)
		(width 0.1143)
		(layer "In15.Cu")
		(net "P5E_CPU1_P0_RX_DP<11>")
	)
	(segment
		(start 107.61345 -280.275792)
		(end 107.632246 -280.262076)
		(width 0.1143)
		(layer "In15.Cu")
		(net "P5E_CPU1_P0_RX_DP<11>")
	)
	(segment
		(start 107.1499 -295.659302)
		(end 107.220004 -295.618662)
		(width 0.1143)
		(layer "In15.Cu")
		(net "P5E_CPU1_P0_RX_DP<11>")
	)
	(segment
		(start 61.486288 -385.649216)
		(end 61.660532 -385.548632)
		(width 0.14224)
		(layer "In15.Cu")
		(net "P5E_CPU1_P0_RX_DP<11>")
	)
	(segment
		(start 107.663234 -278.624284)
		(end 107.663996 -278.623776)
		(width 0.1143)
		(layer "In15.Cu")
		(net "P5E_CPU1_P0_RX_DP<11>")
	)
	(segment
		(start 107.666536 -285.750508)
		(end 107.665012 -285.749492)
		(width 0.1143)
		(layer "In15.Cu")
		(net "P5E_CPU1_P0_RX_DP<11>")
	)
	(segment
		(start 107.013248 -270.10614)
		(end 107.083098 -270.03629)
		(width 0.1143)
		(layer "In15.Cu")
		(net "P5E_CPU1_P0_RX_DP<11>")
	)
	(segment
		(start 107.665012 -283.483304)
		(end 107.703112 -283.460952)
		(width 0.1143)
		(layer "In15.Cu")
		(net "P5E_CPU1_P0_RX_DP<11>")
	)
	(segment
		(start 107.665012 -285.103316)
		(end 107.703112 -285.080964)
		(width 0.1143)
		(layer "In15.Cu")
		(net "P5E_CPU1_P0_RX_DP<11>")
	)
	(segment
		(start 107.663234 -280.244296)
		(end 107.663996 -280.243788)
		(width 0.1143)
		(layer "In15.Cu")
		(net "P5E_CPU1_P0_RX_DP<11>")
	)
	(segment
		(start 107.70235 -289.011106)
		(end 107.651042 -288.981388)
		(width 0.1143)
		(layer "In15.Cu")
		(net "P5E_CPU1_P0_RX_DP<11>")
	)
	(segment
		(start 107.703112 -277.671784)
		(end 107.666536 -277.650448)
		(width 0.1143)
		(layer "In15.Cu")
		(net "P5E_CPU1_P0_RX_DP<11>")
	)
	(segment
		(start 107.663996 -273.76374)
		(end 107.665012 -273.763232)
		(width 0.1143)
		(layer "In15.Cu")
		(net "P5E_CPU1_P0_RX_DP<11>")
	)
	(segment
		(start 107.632246 -284.110684)
		(end 107.612434 -284.09646)
		(width 0.1143)
		(layer "In15.Cu")
		(net "P5E_CPU1_P0_RX_DP<11>")
	)
	(segment
		(start 107.663996 -272.143728)
		(end 107.665012 -272.14322)
		(width 0.1143)
		(layer "In15.Cu")
		(net "P5E_CPU1_P0_RX_DP<11>")
	)
	(segment
		(start 107.665012 -279.269444)
		(end 107.663996 -279.268936)
		(width 0.1143)
		(layer "In15.Cu")
		(net "P5E_CPU1_P0_RX_DP<11>")
	)
	(segment
		(start 61.74867 -385.460494)
		(end 61.74867 -385.046982)
		(width 0.14224)
		(layer "In15.Cu")
		(net "P5E_CPU1_P0_RX_DP<11>")
	)
	(segment
		(start 107.667806 -275.38172)
		(end 107.6706 -275.380196)
		(width 0.1143)
		(layer "In15.Cu")
		(net "P5E_CPU1_P0_RX_DP<11>")
	)
	(segment
		(start 107.296204 -296.612564)
		(end 107.296204 -296.584116)
		(width 0.1143)
		(layer "In15.Cu")
		(net "P5E_CPU1_P0_RX_DP<11>")
	)
	(segment
		(start 107.651042 -288.35096)
		(end 107.664504 -288.34334)
		(width 0.1143)
		(layer "In15.Cu")
		(net "P5E_CPU1_P0_RX_DP<11>")
	)
	(segment
		(start 107.684824 -291.571426)
		(end 107.685078 -291.571426)
		(width 0.1143)
		(layer "In15.Cu")
		(net "P5E_CPU1_P0_RX_DP<11>")
	)
	(segment
		(start 107.632246 -278.642064)
		(end 107.663234 -278.624284)
		(width 0.1143)
		(layer "In15.Cu")
		(net "P5E_CPU1_P0_RX_DP<11>")
	)
	(segment
		(start 119.467376 -330.432664)
		(end 107.35945 -301.201328)
		(width 0.14224)
		(layer "In15.Cu")
		(net "P5E_CPU1_P0_RX_DP<11>")
	)
	(segment
		(start 107.479084 -287.090612)
		(end 107.479084 -287.000696)
		(width 0.1143)
		(layer "In15.Cu")
		(net "P5E_CPU1_P0_RX_DP<11>")
	)
	(segment
		(start 107.651042 -288.981388)
		(end 107.650534 -288.981134)
		(width 0.1143)
		(layer "In15.Cu")
		(net "P5E_CPU1_P0_RX_DP<11>")
	)
	(segment
		(start 107.663234 -280.88844)
		(end 107.632246 -280.87066)
		(width 0.1143)
		(layer "In15.Cu")
		(net "P5E_CPU1_P0_RX_DP<11>")
	)
	(segment
		(start 107.703112 -285.771844)
		(end 107.666536 -285.750508)
		(width 0.1143)
		(layer "In15.Cu")
		(net "P5E_CPU1_P0_RX_DP<11>")
	)
	(segment
		(start 107.663234 -294.82415)
		(end 107.663996 -294.823642)
		(width 0.1143)
		(layer "In15.Cu")
		(net "P5E_CPU1_P0_RX_DP<11>")
	)
	(segment
		(start 107.665012 -284.12948)
		(end 107.663996 -284.128972)
		(width 0.1143)
		(layer "In15.Cu")
		(net "P5E_CPU1_P0_RX_DP<11>")
	)
	(segment
		(start 107.663234 -274.408392)
		(end 107.632246 -274.390612)
		(width 0.1143)
		(layer "In15.Cu")
		(net "P5E_CPU1_P0_RX_DP<11>")
	)
	(segment
		(start 107.703112 -271.191736)
		(end 107.696254 -271.187672)
		(width 0.1143)
		(layer "In15.Cu")
		(net "P5E_CPU1_P0_RX_DP<11>")
	)
	(segment
		(start 107.665012 -278.623268)
		(end 107.703112 -278.600916)
		(width 0.1143)
		(layer "In15.Cu")
		(net "P5E_CPU1_P0_RX_DP<11>")
	)
	(segment
		(start 161.516568 -363.59084)
		(end 161.516568 -359.546906)
		(width 0.14224)
		(layer "In15.Cu")
		(net "P5E_CPU1_P0_RX_DP<11>")
	)
	(segment
		(start 107.682284 -286.713168)
		(end 107.703112 -286.700976)
		(width 0.1143)
		(layer "In15.Cu")
		(net "P5E_CPU1_P0_RX_DP<11>")
	)
	(segment
		(start 107.663488 -291.583872)
		(end 107.684824 -291.571426)
		(width 0.1143)
		(layer "In15.Cu")
		(net "P5E_CPU1_P0_RX_DP<11>")
	)
	(segment
		(start 107.612434 -277.036276)
		(end 107.632246 -277.022052)
		(width 0.1143)
		(layer "In15.Cu")
		(net "P5E_CPU1_P0_RX_DP<11>")
	)
	(segment
		(start 107.66679 -275.382228)
		(end 107.667806 -275.38172)
		(width 0.1143)
		(layer "In15.Cu")
		(net "P5E_CPU1_P0_RX_DP<11>")
	)
	(segment
		(start 107.215432 -270.371062)
		(end 107.194096 -270.35887)
		(width 0.1143)
		(layer "In15.Cu")
		(net "P5E_CPU1_P0_RX_DP<11>")
	)
	(segment
		(start 107.696254 -272.807684)
		(end 107.695492 -272.807176)
		(width 0.1143)
		(layer "In15.Cu")
		(net "P5E_CPU1_P0_RX_DP<11>")
	)
	(segment
		(start 107.665012 -273.763232)
		(end 107.666536 -273.762216)
		(width 0.1143)
		(layer "In15.Cu")
		(net "P5E_CPU1_P0_RX_DP<11>")
	)
	(segment
		(start 133.292596 -344.257884)
		(end 119.467376 -330.432664)
		(width 0.14224)
		(layer "In15.Cu")
		(net "P5E_CPU1_P0_RX_DP<11>")
	)
	(segment
		(start 107.703112 -293.87165)
		(end 107.696254 -293.867586)
		(width 0.1143)
		(layer "In15.Cu")
		(net "P5E_CPU1_P0_RX_DP<11>")
	)
	(segment
		(start 107.70235 -290.631118)
		(end 107.672632 -290.613846)
		(width 0.1143)
		(layer "In15.Cu")
		(net "P5E_CPU1_P0_RX_DP<11>")
	)
	(segment
		(start 107.663488 -286.723582)
		(end 107.663996 -286.723836)
		(width 0.1143)
		(layer "In15.Cu")
		(net "P5E_CPU1_P0_RX_DP<11>")
	)
	(segment
		(start 107.684824 -289.951414)
		(end 107.685078 -289.951414)
		(width 0.1143)
		(layer "In15.Cu")
		(net "P5E_CPU1_P0_RX_DP<11>")
	)
	(segment
		(start 107.665012 -282.509468)
		(end 107.663996 -282.50896)
		(width 0.1143)
		(layer "In15.Cu")
		(net "P5E_CPU1_P0_RX_DP<11>")
	)
	(segment
		(start 107.665012 -277.649432)
		(end 107.663996 -277.648924)
		(width 0.1143)
		(layer "In15.Cu")
		(net "P5E_CPU1_P0_RX_DP<11>")
	)
	(segment
		(start 107.230418 -270.379952)
		(end 107.216194 -270.37157)
		(width 0.1143)
		(layer "In15.Cu")
		(net "P5E_CPU1_P0_RX_DP<11>")
	)
	(segment
		(start 107.668568 -292.231318)
		(end 107.656122 -292.224206)
		(width 0.1143)
		(layer "In15.Cu")
		(net "P5E_CPU1_P0_RX_DP<11>")
	)
	(segment
		(start 107.672886 -275.378926)
		(end 107.67441 -275.37791)
		(width 0.1143)
		(layer "In15.Cu")
		(net "P5E_CPU1_P0_RX_DP<11>")
	)
	(segment
		(start 107.663234 -277.004272)
		(end 107.663996 -277.003764)
		(width 0.1143)
		(layer "In15.Cu")
		(net "P5E_CPU1_P0_RX_DP<11>")
	)
	(segment
		(start 107.632246 -277.022052)
		(end 107.663234 -277.004272)
		(width 0.1143)
		(layer "In15.Cu")
		(net "P5E_CPU1_P0_RX_DP<11>")
	)
	(segment
		(start 61.432694 -384.731006)
		(end 61.435742 -384.3528)
		(width 0.14224)
		(layer "In15.Cu")
		(net "P5E_CPU1_P0_RX_DP<11>")
	)
	(segment
		(start 107.685078 -289.951414)
		(end 107.703112 -289.940746)
		(width 0.1143)
		(layer "In15.Cu")
		(net "P5E_CPU1_P0_RX_DP<11>")
	)
	(segment
		(start 107.663234 -285.104332)
		(end 107.663996 -285.103824)
		(width 0.1143)
		(layer "In15.Cu")
		(net "P5E_CPU1_P0_RX_DP<11>")
	)
	(segment
		(start 153.000202 -358.210104)
		(end 150.84044 -356.050342)
		(width 0.14224)
		(layer "In15.Cu")
		(net "P5E_CPU1_P0_RX_DP<11>")
	)
	(segment
		(start 107.663996 -285.748984)
		(end 107.663234 -285.748476)
		(width 0.1143)
		(layer "In15.Cu")
		(net "P5E_CPU1_P0_RX_DP<11>")
	)
	(segment
		(start 107.663996 -293.20363)
		(end 107.700318 -293.182802)
		(width 0.1143)
		(layer "In15.Cu")
		(net "P5E_CPU1_P0_RX_DP<11>")
	)
	(arc
		(start 107.656122 -292.224206)
		(mid 107.477905 -291.901929)
		(end 107.663488 -291.583872)
		(width 0.1143)
		(layer "In15.Cu")
		(net "P5E_CPU1_P0_RX_DP<11>")
	)
	(arc
		(start 107.656122 -290.604194)
		(mid 107.477905 -290.281917)
		(end 107.663488 -289.96386)
		(width 0.1143)
		(layer "In15.Cu")
		(net "P5E_CPU1_P0_RX_DP<11>")
	)
	(arc
		(start 107.703112 -289.011614)
		(mid 107.702731 -289.01136)
		(end 107.70235 -289.011106)
		(width 0.1143)
		(layer "In15.Cu")
		(net "P5E_CPU1_P0_RX_DP<11>")
	)
	(arc
		(start 150.84044 -356.050342)
		(mid 150.629617 -355.859054)
		(end 150.40102 -355.689408)
		(width 0.14224)
		(layer "In15.Cu")
		(net "P5E_CPU1_P0_RX_DP<11>")
	)
	(arc
		(start 107.703112 -290.631626)
		(mid 107.702731 -290.631372)
		(end 107.70235 -290.631118)
		(width 0.1143)
		(layer "In15.Cu")
		(net "P5E_CPU1_P0_RX_DP<11>")
	)
	(arc
		(start 107.612434 -275.9964)
		(mid 107.46372 -275.706332)
		(end 107.612434 -275.416264)
		(width 0.1143)
		(layer "In15.Cu")
		(net "P5E_CPU1_P0_RX_DP<11>")
	)
	(arc
		(start 108.064554 -364.375192)
		(mid 108.448437 -364.22156)
		(end 108.85043 -364.124748)
		(width 0.14224)
		(layer "In15.Cu")
		(net "P5E_CPU1_P0_RX_DP<11>")
	)
	(arc
		(start 107.35945 -301.201328)
		(mid 107.312105 -300.970545)
		(end 107.296204 -300.735492)
		(width 0.14224)
		(layer "In15.Cu")
		(net "P5E_CPU1_P0_RX_DP<11>")
	)
	(arc
		(start 107.703112 -281.84094)
		(mid 107.946439 -281.376374)
		(end 107.703112 -280.911808)
		(width 0.1143)
		(layer "In15.Cu")
		(net "P5E_CPU1_P0_RX_DP<11>")
	)
	(arc
		(start 106.810302 -364.664244)
		(mid 107.453878 -364.591086)
		(end 108.064554 -364.375192)
		(width 0.14224)
		(layer "In15.Cu")
		(net "P5E_CPU1_P0_RX_DP<11>")
	)
	(arc
		(start 107.61345 -280.856944)
		(mid 107.464535 -280.566368)
		(end 107.61345 -280.275792)
		(width 0.1143)
		(layer "In15.Cu")
		(net "P5E_CPU1_P0_RX_DP<11>")
	)
	(arc
		(start 108.85043 -364.124748)
		(mid 108.913461 -364.116929)
		(end 108.976922 -364.114334)
		(width 0.14224)
		(layer "In15.Cu")
		(net "P5E_CPU1_P0_RX_DP<11>")
	)
	(arc
		(start 107.703112 -280.220928)
		(mid 107.946439 -279.756362)
		(end 107.703112 -279.291796)
		(width 0.1143)
		(layer "In15.Cu")
		(net "P5E_CPU1_P0_RX_DP<11>")
	)
	(arc
		(start 107.632246 -274.390612)
		(mid 107.481861 -274.08632)
		(end 107.632246 -273.782028)
		(width 0.1143)
		(layer "In15.Cu")
		(net "P5E_CPU1_P0_RX_DP<11>")
	)
	(arc
		(start 107.612434 -277.616412)
		(mid 107.46372 -277.326344)
		(end 107.612434 -277.036276)
		(width 0.1143)
		(layer "In15.Cu")
		(net "P5E_CPU1_P0_RX_DP<11>")
	)
	(arc
		(start 107.479084 -287.000696)
		(mid 107.529205 -286.854248)
		(end 107.634278 -286.7406)
		(width 0.1143)
		(layer "In15.Cu")
		(net "P5E_CPU1_P0_RX_DP<11>")
	)
	(arc
		(start 107.162346 -270.340582)
		(mid 107.065211 -270.237713)
		(end 107.013248 -270.10614)
		(width 0.1143)
		(layer "In15.Cu")
		(net "P5E_CPU1_P0_RX_DP<11>")
	)
	(arc
		(start 107.471972 -270.808958)
		(mid 107.396055 -270.581291)
		(end 107.24642 -270.393668)
		(width 0.1143)
		(layer "In15.Cu")
		(net "P5E_CPU1_P0_RX_DP<11>")
	)
	(arc
		(start 107.612434 -282.476448)
		(mid 107.46372 -282.18638)
		(end 107.612434 -281.896312)
		(width 0.1143)
		(layer "In15.Cu")
		(net "P5E_CPU1_P0_RX_DP<11>")
	)
	(arc
		(start 161.516568 -359.546906)
		(mid 161.325968 -359.086758)
		(end 160.86582 -358.896158)
		(width 0.14224)
		(layer "In15.Cu")
		(net "P5E_CPU1_P0_RX_DP<11>")
	)
	(arc
		(start 107.703112 -285.080964)
		(mid 107.946439 -284.616398)
		(end 107.703112 -284.151832)
		(width 0.1143)
		(layer "In15.Cu")
		(net "P5E_CPU1_P0_RX_DP<11>")
	)
	(arc
		(start 107.00639 -295.939464)
		(mid 107.044411 -295.782105)
		(end 107.1499 -295.659302)
		(width 0.1143)
		(layer "In15.Cu")
		(net "P5E_CPU1_P0_RX_DP<11>")
	)
	(arc
		(start 107.703112 -291.560758)
		(mid 107.946439 -291.096192)
		(end 107.703112 -290.631626)
		(width 0.1143)
		(layer "In15.Cu")
		(net "P5E_CPU1_P0_RX_DP<11>")
	)
	(arc
		(start 107.632246 -293.830502)
		(mid 107.481861 -293.52621)
		(end 107.632246 -293.221918)
		(width 0.1143)
		(layer "In15.Cu")
		(net "P5E_CPU1_P0_RX_DP<11>")
	)
	(arc
		(start 107.703112 -286.700976)
		(mid 107.946439 -286.23641)
		(end 107.703112 -285.771844)
		(width 0.1143)
		(layer "In15.Cu")
		(net "P5E_CPU1_P0_RX_DP<11>")
	)
	(arc
		(start 107.703112 -273.74088)
		(mid 107.946439 -273.276314)
		(end 107.703112 -272.811748)
		(width 0.1143)
		(layer "In15.Cu")
		(net "P5E_CPU1_P0_RX_DP<11>")
	)
	(arc
		(start 75.552046 -364.725966)
		(mid 75.715324 -364.679819)
		(end 75.884278 -364.664244)
		(width 0.14224)
		(layer "In15.Cu")
		(net "P5E_CPU1_P0_RX_DP<11>")
	)
	(arc
		(start 107.476036 -270.86052)
		(mid 107.474764 -270.834679)
		(end 107.471972 -270.808958)
		(width 0.1143)
		(layer "In15.Cu")
		(net "P5E_CPU1_P0_RX_DP<11>")
	)
	(arc
		(start 107.703112 -293.18077)
		(mid 107.946439 -292.716204)
		(end 107.703112 -292.251638)
		(width 0.1143)
		(layer "In15.Cu")
		(net "P5E_CPU1_P0_RX_DP<11>")
	)
	(arc
		(start 107.703112 -278.600916)
		(mid 107.946439 -278.13635)
		(end 107.703112 -277.671784)
		(width 0.1143)
		(layer "In15.Cu")
		(net "P5E_CPU1_P0_RX_DP<11>")
	)
	(arc
		(start 107.46359 -295.153588)
		(mid 107.51312 -294.96823)
		(end 107.648502 -294.832278)
		(width 0.1143)
		(layer "In15.Cu")
		(net "P5E_CPU1_P0_RX_DP<11>")
	)
	(arc
		(start 107.703112 -289.940746)
		(mid 107.946439 -289.47618)
		(end 107.703112 -289.011614)
		(width 0.1143)
		(layer "In15.Cu")
		(net "P5E_CPU1_P0_RX_DP<11>")
	)
	(arc
		(start 107.612434 -284.09646)
		(mid 107.46372 -283.806392)
		(end 107.612434 -283.516324)
		(width 0.1143)
		(layer "In15.Cu")
		(net "P5E_CPU1_P0_RX_DP<11>")
	)
	(arc
		(start 107.703112 -276.980904)
		(mid 107.946439 -276.516338)
		(end 107.703112 -276.051772)
		(width 0.1143)
		(layer "In15.Cu")
		(net "P5E_CPU1_P0_RX_DP<11>")
	)
	(arc
		(start 107.043982 -296.138854)
		(mid 107.016148 -296.097527)
		(end 107.00639 -296.048684)
		(width 0.1143)
		(layer "In15.Cu")
		(net "P5E_CPU1_P0_RX_DP<11>")
	)
	(arc
		(start 107.632246 -272.7706)
		(mid 107.481861 -272.466308)
		(end 107.632246 -272.162016)
		(width 0.1143)
		(layer "In15.Cu")
		(net "P5E_CPU1_P0_RX_DP<11>")
	)
	(arc
		(start 107.703112 -272.120868)
		(mid 107.946439 -271.656302)
		(end 107.703112 -271.191736)
		(width 0.1143)
		(layer "In15.Cu")
		(net "P5E_CPU1_P0_RX_DP<11>")
	)
	(arc
		(start 107.703112 -275.360892)
		(mid 107.946439 -274.896326)
		(end 107.703112 -274.43176)
		(width 0.1143)
		(layer "In15.Cu")
		(net "P5E_CPU1_P0_RX_DP<11>")
	)
	(arc
		(start 107.703112 -288.320988)
		(mid 107.946329 -287.855892)
		(end 107.70235 -287.391094)
		(width 0.1143)
		(layer "In15.Cu")
		(net "P5E_CPU1_P0_RX_DP<11>")
	)
	(arc
		(start 61.740542 -382.128522)
		(mid 61.746371 -382.090741)
		(end 61.763148 -382.056386)
		(width 0.14224)
		(layer "In15.Cu")
		(net "P5E_CPU1_P0_RX_DP<11>")
	)
	(arc
		(start 107.612434 -279.236424)
		(mid 107.46372 -278.946356)
		(end 107.612434 -278.656288)
		(width 0.1143)
		(layer "In15.Cu")
		(net "P5E_CPU1_P0_RX_DP<11>")
	)
	(arc
		(start 107.632246 -271.150588)
		(mid 107.520623 -271.023611)
		(end 107.476036 -270.86052)
		(width 0.1143)
		(layer "In15.Cu")
		(net "P5E_CPU1_P0_RX_DP<11>")
	)
	(arc
		(start 107.54741 -287.255458)
		(mid 107.496821 -287.17984)
		(end 107.479084 -287.090612)
		(width 0.1143)
		(layer "In15.Cu")
		(net "P5E_CPU1_P0_RX_DP<11>")
	)
	(arc
		(start 107.220004 -295.618662)
		(mid 107.399027 -295.416107)
		(end 107.46359 -295.153588)
		(width 0.1143)
		(layer "In15.Cu")
		(net "P5E_CPU1_P0_RX_DP<11>")
	)
	(arc
		(start 107.703112 -283.460952)
		(mid 107.946439 -282.996386)
		(end 107.703112 -282.53182)
		(width 0.1143)
		(layer "In15.Cu")
		(net "P5E_CPU1_P0_RX_DP<11>")
	)
	(arc
		(start 107.632246 -285.730696)
		(mid 107.481861 -285.426404)
		(end 107.632246 -285.122112)
		(width 0.1143)
		(layer "In15.Cu")
		(net "P5E_CPU1_P0_RX_DP<11>")
	)
	(arc
		(start 107.703112 -292.251638)
		(mid 107.702731 -292.251384)
		(end 107.70235 -292.25113)
		(width 0.1143)
		(layer "In15.Cu")
		(net "P5E_CPU1_P0_RX_DP<11>")
	)
	(arc
		(start 75.445874 -364.7948)
		(mid 75.495339 -364.754798)
		(end 75.552046 -364.725966)
		(width 0.14224)
		(layer "In15.Cu")
		(net "P5E_CPU1_P0_RX_DP<11>")
	)
	(arc
		(start 154.656282 -358.896158)
		(mid 153.76 -358.717859)
		(end 153.000202 -358.210104)
		(width 0.14224)
		(layer "In15.Cu")
		(net "P5E_CPU1_P0_RX_DP<11>")
	)
	(arc
		(start 107.24642 -270.393668)
		(mid 107.238471 -270.386749)
		(end 107.230418 -270.379952)
		(width 0.1143)
		(layer "In15.Cu")
		(net "P5E_CPU1_P0_RX_DP<11>")
	)
	(arc
		(start 107.703112 -294.800782)
		(mid 107.946439 -294.336216)
		(end 107.703112 -293.87165)
		(width 0.1143)
		(layer "In15.Cu")
		(net "P5E_CPU1_P0_RX_DP<11>")
	)
	(arc
		(start 107.650534 -288.981134)
		(mid 107.469336 -288.666064)
		(end 107.650788 -288.351214)
		(width 0.1143)
		(layer "In15.Cu")
		(net "P5E_CPU1_P0_RX_DP<11>")
	)
	(arc
		(start 160.993074 -364.114334)
		(mid 161.36324 -363.961006)
		(end 161.516568 -363.59084)
		(width 0.14224)
		(layer "In15.Cu")
		(net "P5E_CPU1_P0_RX_DP<11>")
	)
	(segment
		(start 107.847892 -273.010376)
		(end 107.38104 -273.276314)
		(width 0.12954)
		(layer "F.Cu")
		(net "P5E_CPU1_P0_RX_DP<10>")
	)
	(segment
		(start 59.670696 -386.003292)
		(end 60.191396 -386.003292)
		(width 0.127)
		(layer "F.Cu")
		(net "P5E_CPU1_P0_RX_DP<10>")
	)
	(segment
		(start 135.048244 -360.89336)
		(end 138.772392 -360.89336)
		(width 0.14224)
		(layer "In15.Cu")
		(net "P5E_CPU1_P0_RX_DP<10>")
	)
	(segment
		(start 158.60395 -359.898442)
		(end 153.76906 -359.898442)
		(width 0.14224)
		(layer "In15.Cu")
		(net "P5E_CPU1_P0_RX_DP<10>")
	)
	(segment
		(start 106.723942 -294.823642)
		(end 106.763058 -294.800782)
		(width 0.1143)
		(layer "In15.Cu")
		(net "P5E_CPU1_P0_RX_DP<10>")
	)
	(segment
		(start 106.723942 -293.84879)
		(end 106.693462 -293.83101)
		(width 0.1143)
		(layer "In15.Cu")
		(net "P5E_CPU1_P0_RX_DP<10>")
	)
	(segment
		(start 106.763058 -279.291796)
		(end 106.723942 -279.268936)
		(width 0.1143)
		(layer "In15.Cu")
		(net "P5E_CPU1_P0_RX_DP<10>")
	)
	(segment
		(start 106.723942 -288.988754)
		(end 106.693462 -288.970974)
		(width 0.1143)
		(layer "In15.Cu")
		(net "P5E_CPU1_P0_RX_DP<10>")
	)
	(segment
		(start 106.723942 -279.268936)
		(end 106.693462 -279.251156)
		(width 0.1143)
		(layer "In15.Cu")
		(net "P5E_CPU1_P0_RX_DP<10>")
	)
	(segment
		(start 106.723942 -283.483812)
		(end 106.763058 -283.460952)
		(width 0.1143)
		(layer "In15.Cu")
		(net "P5E_CPU1_P0_RX_DP<10>")
	)
	(segment
		(start 106.723942 -280.243788)
		(end 106.763058 -280.220928)
		(width 0.1143)
		(layer "In15.Cu")
		(net "P5E_CPU1_P0_RX_DP<10>")
	)
	(segment
		(start 106.190796 -295.824656)
		(end 106.392472 -295.622726)
		(width 0.1143)
		(layer "In15.Cu")
		(net "P5E_CPU1_P0_RX_DP<10>")
	)
	(segment
		(start 106.693462 -293.22141)
		(end 106.723942 -293.20363)
		(width 0.1143)
		(layer "In15.Cu")
		(net "P5E_CPU1_P0_RX_DP<10>")
	)
	(segment
		(start 134.906004 -361.0356)
		(end 135.048244 -360.89336)
		(width 0.14224)
		(layer "In15.Cu")
		(net "P5E_CPU1_P0_RX_DP<10>")
	)
	(segment
		(start 106.763058 -284.151832)
		(end 106.723942 -284.128972)
		(width 0.1143)
		(layer "In15.Cu")
		(net "P5E_CPU1_P0_RX_DP<10>")
	)
	(segment
		(start 60.197492 -374.990614)
		(end 60.527184 -373.930164)
		(width 0.14224)
		(layer "In15.Cu")
		(net "P5E_CPU1_P0_RX_DP<10>")
	)
	(segment
		(start 106.693462 -281.88158)
		(end 106.723942 -281.8638)
		(width 0.1143)
		(layer "In15.Cu")
		(net "P5E_CPU1_P0_RX_DP<10>")
	)
	(segment
		(start 106.763058 -274.43176)
		(end 106.723942 -274.4089)
		(width 0.1143)
		(layer "In15.Cu")
		(net "P5E_CPU1_P0_RX_DP<10>")
	)
	(segment
		(start 106.723942 -278.623776)
		(end 106.763058 -278.600916)
		(width 0.1143)
		(layer "In15.Cu")
		(net "P5E_CPU1_P0_RX_DP<10>")
	)
	(segment
		(start 60.527692 -373.92864)
		(end 60.527438 -373.92864)
		(width 0.14224)
		(layer "In15.Cu")
		(net "P5E_CPU1_P0_RX_DP<10>")
	)
	(segment
		(start 106.723942 -281.8638)
		(end 106.763058 -281.84094)
		(width 0.1143)
		(layer "In15.Cu")
		(net "P5E_CPU1_P0_RX_DP<10>")
	)
	(segment
		(start 106.536236 -295.193212)
		(end 106.53649 -295.146222)
		(width 0.1143)
		(layer "In15.Cu")
		(net "P5E_CPU1_P0_RX_DP<10>")
	)
	(segment
		(start 106.723942 -280.888948)
		(end 106.693462 -280.871168)
		(width 0.1143)
		(layer "In15.Cu")
		(net "P5E_CPU1_P0_RX_DP<10>")
	)
	(segment
		(start 138.914632 -361.0356)
		(end 138.914632 -362.579158)
		(width 0.14224)
		(layer "In15.Cu")
		(net "P5E_CPU1_P0_RX_DP<10>")
	)
	(segment
		(start 106.693462 -280.261568)
		(end 106.723942 -280.243788)
		(width 0.1143)
		(layer "In15.Cu")
		(net "P5E_CPU1_P0_RX_DP<10>")
	)
	(segment
		(start 60.527438 -373.92864)
		(end 60.85713 -372.867174)
		(width 0.14224)
		(layer "In15.Cu")
		(net "P5E_CPU1_P0_RX_DP<10>")
	)
	(segment
		(start 106.763058 -277.671784)
		(end 106.723942 -277.648924)
		(width 0.1143)
		(layer "In15.Cu")
		(net "P5E_CPU1_P0_RX_DP<10>")
	)
	(segment
		(start 138.058652 -362.05668)
		(end 137.751312 -361.74934)
		(width 0.14224)
		(layer "In15.Cu")
		(net "P5E_CPU1_P0_RX_DP<10>")
	)
	(segment
		(start 107.000294 -273.359118)
		(end 107.083098 -273.276314)
		(width 0.1143)
		(layer "In15.Cu")
		(net "P5E_CPU1_P0_RX_DP<10>")
	)
	(segment
		(start 60.286392 -385.649216)
		(end 60.460636 -385.548632)
		(width 0.14224)
		(layer "In15.Cu")
		(net "P5E_CPU1_P0_RX_DP<10>")
	)
	(segment
		(start 138.772392 -360.89336)
		(end 138.914632 -361.0356)
		(width 0.14224)
		(layer "In15.Cu")
		(net "P5E_CPU1_P0_RX_DP<10>")
	)
	(segment
		(start 106.723942 -292.228778)
		(end 106.693462 -292.210998)
		(width 0.1143)
		(layer "In15.Cu")
		(net "P5E_CPU1_P0_RX_DP<10>")
	)
	(segment
		(start 106.69143 -286.742632)
		(end 106.723942 -286.723836)
		(width 0.1143)
		(layer "In15.Cu")
		(net "P5E_CPU1_P0_RX_DP<10>")
	)
	(segment
		(start 106.693462 -291.601398)
		(end 106.723942 -291.583618)
		(width 0.1143)
		(layer "In15.Cu")
		(net "P5E_CPU1_P0_RX_DP<10>")
	)
	(segment
		(start 106.723942 -277.648924)
		(end 106.693462 -277.631144)
		(width 0.1143)
		(layer "In15.Cu")
		(net "P5E_CPU1_P0_RX_DP<10>")
	)
	(segment
		(start 106.693462 -278.641556)
		(end 106.723942 -278.623776)
		(width 0.1143)
		(layer "In15.Cu")
		(net "P5E_CPU1_P0_RX_DP<10>")
	)
	(segment
		(start 159.19196 -362.570522)
		(end 159.19196 -360.486452)
		(width 0.14224)
		(layer "In15.Cu")
		(net "P5E_CPU1_P0_RX_DP<10>")
	)
	(segment
		(start 106.693462 -285.121604)
		(end 106.723942 -285.103824)
		(width 0.1143)
		(layer "In15.Cu")
		(net "P5E_CPU1_P0_RX_DP<10>")
	)
	(segment
		(start 60.191396 -386.003292)
		(end 60.286392 -385.649216)
		(width 0.14224)
		(layer "In15.Cu")
		(net "P5E_CPU1_P0_RX_DP<10>")
	)
	(segment
		(start 60.87745 -372.828058)
		(end 64.662558 -367.854484)
		(width 0.14224)
		(layer "In15.Cu")
		(net "P5E_CPU1_P0_RX_DP<10>")
	)
	(segment
		(start 106.723942 -291.583618)
		(end 106.763058 -291.560758)
		(width 0.1143)
		(layer "In15.Cu")
		(net "P5E_CPU1_P0_RX_DP<10>")
	)
	(segment
		(start 106.198924 -300.922436)
		(end 106.198924 -296.37482)
		(width 0.14224)
		(layer "In15.Cu")
		(net "P5E_CPU1_P0_RX_DP<10>")
	)
	(segment
		(start 135.048244 -361.74934)
		(end 134.906004 -361.6071)
		(width 0.14224)
		(layer "In15.Cu")
		(net "P5E_CPU1_P0_RX_DP<10>")
	)
	(segment
		(start 106.198924 -296.37482)
		(end 106.198924 -296.346372)
		(width 0.1143)
		(layer "In15.Cu")
		(net "P5E_CPU1_P0_RX_DP<10>")
	)
	(segment
		(start 106.763058 -285.771844)
		(end 106.723942 -285.748984)
		(width 0.1143)
		(layer "In15.Cu")
		(net "P5E_CPU1_P0_RX_DP<10>")
	)
	(segment
		(start 106.723942 -286.723836)
		(end 106.763058 -286.700976)
		(width 0.1143)
		(layer "In15.Cu")
		(net "P5E_CPU1_P0_RX_DP<10>")
	)
	(segment
		(start 106.693462 -273.78152)
		(end 106.723942 -273.76374)
		(width 0.1143)
		(layer "In15.Cu")
		(net "P5E_CPU1_P0_RX_DP<10>")
	)
	(segment
		(start 132.297424 -344.767154)
		(end 118.846854 -331.316584)
		(width 0.14224)
		(layer "In15.Cu")
		(net "P5E_CPU1_P0_RX_DP<10>")
	)
	(segment
		(start 60.877196 -372.828312)
		(end 60.87745 -372.828058)
		(width 0.14224)
		(layer "In15.Cu")
		(net "P5E_CPU1_P0_RX_DP<10>")
	)
	(segment
		(start 106.763058 -282.53182)
		(end 106.723942 -282.50896)
		(width 0.1143)
		(layer "In15.Cu")
		(net "P5E_CPU1_P0_RX_DP<10>")
	)
	(segment
		(start 106.536236 -295.276524)
		(end 106.536236 -295.193212)
		(width 0.1143)
		(layer "In15.Cu")
		(net "P5E_CPU1_P0_RX_DP<10>")
	)
	(segment
		(start 106.763058 -289.011614)
		(end 106.723942 -288.988754)
		(width 0.1143)
		(layer "In15.Cu")
		(net "P5E_CPU1_P0_RX_DP<10>")
	)
	(segment
		(start 106.763058 -293.87165)
		(end 106.723942 -293.84879)
		(width 0.1143)
		(layer "In15.Cu")
		(net "P5E_CPU1_P0_RX_DP<10>")
	)
	(segment
		(start 106.723942 -277.003764)
		(end 106.763058 -276.980904)
		(width 0.1143)
		(layer "In15.Cu")
		(net "P5E_CPU1_P0_RX_DP<10>")
	)
	(segment
		(start 106.693462 -294.841422)
		(end 106.723942 -294.823642)
		(width 0.1143)
		(layer "In15.Cu")
		(net "P5E_CPU1_P0_RX_DP<10>")
	)
	(segment
		(start 118.437406 -330.703682)
		(end 106.289094 -301.375064)
		(width 0.14224)
		(layer "In15.Cu")
		(net "P5E_CPU1_P0_RX_DP<10>")
	)
	(segment
		(start 106.723942 -276.028912)
		(end 106.693462 -276.011132)
		(width 0.1143)
		(layer "In15.Cu")
		(net "P5E_CPU1_P0_RX_DP<10>")
	)
	(segment
		(start 106.693462 -289.981386)
		(end 106.723942 -289.963606)
		(width 0.1143)
		(layer "In15.Cu")
		(net "P5E_CPU1_P0_RX_DP<10>")
	)
	(segment
		(start 106.763058 -280.911808)
		(end 106.723942 -280.888948)
		(width 0.1143)
		(layer "In15.Cu")
		(net "P5E_CPU1_P0_RX_DP<10>")
	)
	(segment
		(start 139.439396 -363.103922)
		(end 158.65856 -363.103922)
		(width 0.14224)
		(layer "In15.Cu")
		(net "P5E_CPU1_P0_RX_DP<10>")
	)
	(segment
		(start 106.760518 -287.390078)
		(end 106.693462 -287.350962)
		(width 0.1143)
		(layer "In15.Cu")
		(net "P5E_CPU1_P0_RX_DP<10>")
	)
	(segment
		(start 60.548774 -385.460494)
		(end 60.548774 -385.046982)
		(width 0.14224)
		(layer "In15.Cu")
		(net "P5E_CPU1_P0_RX_DP<10>")
	)
	(segment
		(start 106.723942 -282.50896)
		(end 106.693462 -282.49118)
		(width 0.1143)
		(layer "In15.Cu")
		(net "P5E_CPU1_P0_RX_DP<10>")
	)
	(segment
		(start 60.540646 -382.3081)
		(end 60.191396 -375.037096)
		(width 0.14224)
		(layer "In15.Cu")
		(net "P5E_CPU1_P0_RX_DP<10>")
	)
	(segment
		(start 75.529186 -363.69117)
		(end 106.05897 -363.69117)
		(width 0.14224)
		(layer "In15.Cu")
		(net "P5E_CPU1_P0_RX_DP<10>")
	)
	(segment
		(start 106.198924 -296.346372)
		(end 106.153204 -296.300652)
		(width 0.1143)
		(layer "In15.Cu")
		(net "P5E_CPU1_P0_RX_DP<10>")
	)
	(segment
		(start 152.687528 -359.450386)
		(end 149.818344 -356.581202)
		(width 0.14224)
		(layer "In15.Cu")
		(net "P5E_CPU1_P0_RX_DP<10>")
	)
	(segment
		(start 106.723942 -293.20363)
		(end 106.763058 -293.18077)
		(width 0.1143)
		(layer "In15.Cu")
		(net "P5E_CPU1_P0_RX_DP<10>")
	)
	(segment
		(start 134.906004 -361.6071)
		(end 134.906004 -361.0356)
		(width 0.14224)
		(layer "In15.Cu")
		(net "P5E_CPU1_P0_RX_DP<10>")
	)
	(segment
		(start 106.723942 -273.76374)
		(end 106.763058 -273.74088)
		(width 0.1143)
		(layer "In15.Cu")
		(net "P5E_CPU1_P0_RX_DP<10>")
	)
	(segment
		(start 60.460636 -385.548632)
		(end 60.548774 -385.460494)
		(width 0.14224)
		(layer "In15.Cu")
		(net "P5E_CPU1_P0_RX_DP<10>")
	)
	(segment
		(start 106.723942 -285.103824)
		(end 106.763058 -285.080964)
		(width 0.1143)
		(layer "In15.Cu")
		(net "P5E_CPU1_P0_RX_DP<10>")
	)
	(segment
		(start 107.083098 -273.276314)
		(end 107.38104 -273.276314)
		(width 0.1143)
		(layer "In15.Cu")
		(net "P5E_CPU1_P0_RX_DP<10>")
	)
	(segment
		(start 106.693462 -275.401532)
		(end 106.723942 -275.383752)
		(width 0.1143)
		(layer "In15.Cu")
		(net "P5E_CPU1_P0_RX_DP<10>")
	)
	(segment
		(start 138.058652 -362.86186)
		(end 138.058652 -362.05668)
		(width 0.14224)
		(layer "In15.Cu")
		(net "P5E_CPU1_P0_RX_DP<10>")
	)
	(segment
		(start 106.763058 -276.051772)
		(end 106.723942 -276.028912)
		(width 0.1143)
		(layer "In15.Cu")
		(net "P5E_CPU1_P0_RX_DP<10>")
	)
	(segment
		(start 137.751312 -361.74934)
		(end 135.048244 -361.74934)
		(width 0.14224)
		(layer "In15.Cu")
		(net "P5E_CPU1_P0_RX_DP<10>")
	)
	(segment
		(start 106.723942 -290.608766)
		(end 106.693462 -290.590986)
		(width 0.1143)
		(layer "In15.Cu")
		(net "P5E_CPU1_P0_RX_DP<10>")
	)
	(segment
		(start 106.69143 -288.362644)
		(end 106.723942 -288.343848)
		(width 0.1143)
		(layer "In15.Cu")
		(net "P5E_CPU1_P0_RX_DP<10>")
	)
	(segment
		(start 106.693462 -283.501592)
		(end 106.723942 -283.483812)
		(width 0.1143)
		(layer "In15.Cu")
		(net "P5E_CPU1_P0_RX_DP<10>")
	)
	(segment
		(start 106.763058 -292.251638)
		(end 106.723942 -292.228778)
		(width 0.1143)
		(layer "In15.Cu")
		(net "P5E_CPU1_P0_RX_DP<10>")
	)
	(segment
		(start 106.763058 -290.631626)
		(end 106.723942 -290.608766)
		(width 0.1143)
		(layer "In15.Cu")
		(net "P5E_CPU1_P0_RX_DP<10>")
	)
	(segment
		(start 107.947206 -363.1692)
		(end 137.751312 -363.1692)
		(width 0.14224)
		(layer "In15.Cu")
		(net "P5E_CPU1_P0_RX_DP<10>")
	)
	(segment
		(start 106.723942 -275.383752)
		(end 106.763058 -275.360892)
		(width 0.1143)
		(layer "In15.Cu")
		(net "P5E_CPU1_P0_RX_DP<10>")
	)
	(segment
		(start 60.235846 -384.3528)
		(end 60.540646 -384.048254)
		(width 0.14224)
		(layer "In15.Cu")
		(net "P5E_CPU1_P0_RX_DP<10>")
	)
	(segment
		(start 60.548774 -385.046982)
		(end 60.232798 -384.731006)
		(width 0.14224)
		(layer "In15.Cu")
		(net "P5E_CPU1_P0_RX_DP<10>")
	)
	(segment
		(start 137.751312 -363.1692)
		(end 138.058652 -362.86186)
		(width 0.14224)
		(layer "In15.Cu")
		(net "P5E_CPU1_P0_RX_DP<10>")
	)
	(segment
		(start 60.232798 -384.731006)
		(end 60.235846 -384.3528)
		(width 0.14224)
		(layer "In15.Cu")
		(net "P5E_CPU1_P0_RX_DP<10>")
	)
	(segment
		(start 60.527184 -373.930164)
		(end 60.527692 -373.92864)
		(width 0.14224)
		(layer "In15.Cu")
		(net "P5E_CPU1_P0_RX_DP<10>")
	)
	(segment
		(start 106.723942 -285.748984)
		(end 106.693462 -285.731204)
		(width 0.1143)
		(layer "In15.Cu")
		(net "P5E_CPU1_P0_RX_DP<10>")
	)
	(segment
		(start 106.723942 -284.128972)
		(end 106.693462 -284.111192)
		(width 0.1143)
		(layer "In15.Cu")
		(net "P5E_CPU1_P0_RX_DP<10>")
	)
	(segment
		(start 106.723942 -289.963606)
		(end 106.763058 -289.940746)
		(width 0.1143)
		(layer "In15.Cu")
		(net "P5E_CPU1_P0_RX_DP<10>")
	)
	(segment
		(start 65.462912 -367.269014)
		(end 75.486514 -363.698536)
		(width 0.14224)
		(layer "In15.Cu")
		(net "P5E_CPU1_P0_RX_DP<10>")
	)
	(segment
		(start 60.540646 -384.048254)
		(end 60.540646 -382.3081)
		(width 0.14224)
		(layer "In15.Cu")
		(net "P5E_CPU1_P0_RX_DP<10>")
	)
	(segment
		(start 106.723942 -274.4089)
		(end 106.693462 -274.39112)
		(width 0.1143)
		(layer "In15.Cu")
		(net "P5E_CPU1_P0_RX_DP<10>")
	)
	(segment
		(start 149.720554 -356.500684)
		(end 132.905246 -345.26601)
		(width 0.14224)
		(layer "In15.Cu")
		(net "P5E_CPU1_P0_RX_DP<10>")
	)
	(segment
		(start 106.723942 -288.343848)
		(end 106.763058 -288.320988)
		(width 0.1143)
		(layer "In15.Cu")
		(net "P5E_CPU1_P0_RX_DP<10>")
	)
	(segment
		(start 106.693462 -277.021544)
		(end 106.723942 -277.003764)
		(width 0.1143)
		(layer "In15.Cu")
		(net "P5E_CPU1_P0_RX_DP<10>")
	)
	(segment
		(start 106.153204 -296.300652)
		(end 106.153204 -295.914826)
		(width 0.1143)
		(layer "In15.Cu")
		(net "P5E_CPU1_P0_RX_DP<10>")
	)
	(arc
		(start 75.486514 -363.698536)
		(mid 75.507534 -363.693024)
		(end 75.529186 -363.69117)
		(width 0.14224)
		(layer "In15.Cu")
		(net "P5E_CPU1_P0_RX_DP<10>")
	)
	(arc
		(start 106.693462 -284.111192)
		(mid 106.536485 -283.806392)
		(end 106.693462 -283.501592)
		(width 0.1143)
		(layer "In15.Cu")
		(net "P5E_CPU1_P0_RX_DP<10>")
	)
	(arc
		(start 106.763058 -291.560758)
		(mid 107.006385 -291.096192)
		(end 106.763058 -290.631626)
		(width 0.1143)
		(layer "In15.Cu")
		(net "P5E_CPU1_P0_RX_DP<10>")
	)
	(arc
		(start 106.996484 -273.381978)
		(mid 106.998507 -273.370568)
		(end 107.000294 -273.359118)
		(width 0.1143)
		(layer "In15.Cu")
		(net "P5E_CPU1_P0_RX_DP<10>")
	)
	(arc
		(start 106.763058 -275.360892)
		(mid 107.006385 -274.896326)
		(end 106.763058 -274.43176)
		(width 0.1143)
		(layer "In15.Cu")
		(net "P5E_CPU1_P0_RX_DP<10>")
	)
	(arc
		(start 106.763058 -281.84094)
		(mid 107.006385 -281.376374)
		(end 106.763058 -280.911808)
		(width 0.1143)
		(layer "In15.Cu")
		(net "P5E_CPU1_P0_RX_DP<10>")
	)
	(arc
		(start 138.914632 -362.579158)
		(mid 139.068332 -362.950222)
		(end 139.439396 -363.103922)
		(width 0.14224)
		(layer "In15.Cu")
		(net "P5E_CPU1_P0_RX_DP<10>")
	)
	(arc
		(start 106.693462 -285.731204)
		(mid 106.536485 -285.426404)
		(end 106.693462 -285.121604)
		(width 0.1143)
		(layer "In15.Cu")
		(net "P5E_CPU1_P0_RX_DP<10>")
	)
	(arc
		(start 153.76906 -359.898442)
		(mid 153.183726 -359.781994)
		(end 152.687528 -359.450386)
		(width 0.14224)
		(layer "In15.Cu")
		(net "P5E_CPU1_P0_RX_DP<10>")
	)
	(arc
		(start 106.693462 -282.49118)
		(mid 106.536485 -282.18638)
		(end 106.693462 -281.88158)
		(width 0.1143)
		(layer "In15.Cu")
		(net "P5E_CPU1_P0_RX_DP<10>")
	)
	(arc
		(start 106.763058 -285.080964)
		(mid 107.006385 -284.616398)
		(end 106.763058 -284.151832)
		(width 0.1143)
		(layer "In15.Cu")
		(net "P5E_CPU1_P0_RX_DP<10>")
	)
	(arc
		(start 132.905246 -345.26601)
		(mid 132.589078 -345.031516)
		(end 132.297424 -344.767154)
		(width 0.14224)
		(layer "In15.Cu")
		(net "P5E_CPU1_P0_RX_DP<10>")
	)
	(arc
		(start 118.846854 -331.316584)
		(mid 118.611946 -331.030297)
		(end 118.437406 -330.703682)
		(width 0.14224)
		(layer "In15.Cu")
		(net "P5E_CPU1_P0_RX_DP<10>")
	)
	(arc
		(start 106.763058 -273.74088)
		(mid 106.915045 -273.584372)
		(end 106.996484 -273.381978)
		(width 0.1143)
		(layer "In15.Cu")
		(net "P5E_CPU1_P0_RX_DP<10>")
	)
	(arc
		(start 106.289094 -301.375064)
		(mid 106.221738 -301.153189)
		(end 106.198924 -300.922436)
		(width 0.14224)
		(layer "In15.Cu")
		(net "P5E_CPU1_P0_RX_DP<10>")
	)
	(arc
		(start 106.693462 -293.83101)
		(mid 106.536485 -293.52621)
		(end 106.693462 -293.22141)
		(width 0.1143)
		(layer "In15.Cu")
		(net "P5E_CPU1_P0_RX_DP<10>")
	)
	(arc
		(start 106.763058 -283.460952)
		(mid 107.006385 -282.996386)
		(end 106.763058 -282.53182)
		(width 0.1143)
		(layer "In15.Cu")
		(net "P5E_CPU1_P0_RX_DP<10>")
	)
	(arc
		(start 106.693462 -292.210998)
		(mid 106.536485 -291.906198)
		(end 106.693462 -291.601398)
		(width 0.1143)
		(layer "In15.Cu")
		(net "P5E_CPU1_P0_RX_DP<10>")
	)
	(arc
		(start 106.763058 -278.600916)
		(mid 107.006385 -278.13635)
		(end 106.763058 -277.671784)
		(width 0.1143)
		(layer "In15.Cu")
		(net "P5E_CPU1_P0_RX_DP<10>")
	)
	(arc
		(start 106.693462 -274.39112)
		(mid 106.536485 -274.08632)
		(end 106.693462 -273.78152)
		(width 0.1143)
		(layer "In15.Cu")
		(net "P5E_CPU1_P0_RX_DP<10>")
	)
	(arc
		(start 106.763058 -293.18077)
		(mid 107.006385 -292.716204)
		(end 106.763058 -292.251638)
		(width 0.1143)
		(layer "In15.Cu")
		(net "P5E_CPU1_P0_RX_DP<10>")
	)
	(arc
		(start 106.763058 -276.980904)
		(mid 107.006385 -276.516338)
		(end 106.763058 -276.051772)
		(width 0.1143)
		(layer "In15.Cu")
		(net "P5E_CPU1_P0_RX_DP<10>")
	)
	(arc
		(start 106.693462 -288.970974)
		(mid 106.578035 -288.837598)
		(end 106.53649 -288.666174)
		(width 0.1143)
		(layer "In15.Cu")
		(net "P5E_CPU1_P0_RX_DP<10>")
	)
	(arc
		(start 106.693462 -287.350962)
		(mid 106.578035 -287.217586)
		(end 106.53649 -287.046162)
		(width 0.1143)
		(layer "In15.Cu")
		(net "P5E_CPU1_P0_RX_DP<10>")
	)
	(arc
		(start 106.693462 -279.251156)
		(mid 106.536485 -278.946356)
		(end 106.693462 -278.641556)
		(width 0.1143)
		(layer "In15.Cu")
		(net "P5E_CPU1_P0_RX_DP<10>")
	)
	(arc
		(start 60.191396 -375.037096)
		(mid 60.19243 -375.013593)
		(end 60.197492 -374.990614)
		(width 0.14224)
		(layer "In15.Cu")
		(net "P5E_CPU1_P0_RX_DP<10>")
	)
	(arc
		(start 159.19196 -360.486452)
		(mid 159.019736 -360.070666)
		(end 158.60395 -359.898442)
		(width 0.14224)
		(layer "In15.Cu")
		(net "P5E_CPU1_P0_RX_DP<10>")
	)
	(arc
		(start 158.65856 -363.103922)
		(mid 159.035731 -362.947693)
		(end 159.19196 -362.570522)
		(width 0.14224)
		(layer "In15.Cu")
		(net "P5E_CPU1_P0_RX_DP<10>")
	)
	(arc
		(start 106.153204 -295.914826)
		(mid 106.163012 -295.865987)
		(end 106.190796 -295.824656)
		(width 0.1143)
		(layer "In15.Cu")
		(net "P5E_CPU1_P0_RX_DP<10>")
	)
	(arc
		(start 106.763058 -294.800782)
		(mid 107.006385 -294.336216)
		(end 106.763058 -293.87165)
		(width 0.1143)
		(layer "In15.Cu")
		(net "P5E_CPU1_P0_RX_DP<10>")
	)
	(arc
		(start 106.693462 -290.590986)
		(mid 106.536485 -290.286186)
		(end 106.693462 -289.981386)
		(width 0.1143)
		(layer "In15.Cu")
		(net "P5E_CPU1_P0_RX_DP<10>")
	)
	(arc
		(start 107.00639 -287.856422)
		(mid 106.941154 -287.592831)
		(end 106.760518 -287.390078)
		(width 0.1143)
		(layer "In15.Cu")
		(net "P5E_CPU1_P0_RX_DP<10>")
	)
	(arc
		(start 106.53649 -287.046162)
		(mid 106.577456 -286.875756)
		(end 106.69143 -286.742632)
		(width 0.1143)
		(layer "In15.Cu")
		(net "P5E_CPU1_P0_RX_DP<10>")
	)
	(arc
		(start 107.003342 -363.430058)
		(mid 107.457585 -363.235633)
		(end 107.947206 -363.1692)
		(width 0.14224)
		(layer "In15.Cu")
		(net "P5E_CPU1_P0_RX_DP<10>")
	)
	(arc
		(start 106.693462 -276.011132)
		(mid 106.536485 -275.706332)
		(end 106.693462 -275.401532)
		(width 0.1143)
		(layer "In15.Cu")
		(net "P5E_CPU1_P0_RX_DP<10>")
	)
	(arc
		(start 106.53649 -295.146222)
		(mid 106.578039 -294.9748)
		(end 106.693462 -294.841422)
		(width 0.1143)
		(layer "In15.Cu")
		(net "P5E_CPU1_P0_RX_DP<10>")
	)
	(arc
		(start 106.693462 -280.871168)
		(mid 106.536485 -280.566368)
		(end 106.693462 -280.261568)
		(width 0.1143)
		(layer "In15.Cu")
		(net "P5E_CPU1_P0_RX_DP<10>")
	)
	(arc
		(start 106.763058 -289.940746)
		(mid 107.006385 -289.47618)
		(end 106.763058 -289.011614)
		(width 0.1143)
		(layer "In15.Cu")
		(net "P5E_CPU1_P0_RX_DP<10>")
	)
	(arc
		(start 106.392472 -295.622726)
		(mid 106.498771 -295.463917)
		(end 106.536236 -295.276524)
		(width 0.1143)
		(layer "In15.Cu")
		(net "P5E_CPU1_P0_RX_DP<10>")
	)
	(arc
		(start 149.818344 -356.581202)
		(mid 149.771436 -356.538529)
		(end 149.720554 -356.500684)
		(width 0.14224)
		(layer "In15.Cu")
		(net "P5E_CPU1_P0_RX_DP<10>")
	)
	(arc
		(start 106.763058 -288.320988)
		(mid 106.941871 -288.118638)
		(end 107.00639 -287.856422)
		(width 0.1143)
		(layer "In15.Cu")
		(net "P5E_CPU1_P0_RX_DP<10>")
	)
	(arc
		(start 106.693462 -277.631144)
		(mid 106.536485 -277.326344)
		(end 106.693462 -277.021544)
		(width 0.1143)
		(layer "In15.Cu")
		(net "P5E_CPU1_P0_RX_DP<10>")
	)
	(arc
		(start 106.05897 -363.69117)
		(mid 106.548853 -363.624639)
		(end 107.003342 -363.430058)
		(width 0.14224)
		(layer "In15.Cu")
		(net "P5E_CPU1_P0_RX_DP<10>")
	)
	(arc
		(start 106.763058 -286.700976)
		(mid 107.006385 -286.23641)
		(end 106.763058 -285.771844)
		(width 0.1143)
		(layer "In15.Cu")
		(net "P5E_CPU1_P0_RX_DP<10>")
	)
	(arc
		(start 60.85713 -372.867174)
		(mid 60.865463 -372.846864)
		(end 60.877196 -372.828312)
		(width 0.14224)
		(layer "In15.Cu")
		(net "P5E_CPU1_P0_RX_DP<10>")
	)
	(arc
		(start 106.53649 -288.666174)
		(mid 106.577456 -288.495768)
		(end 106.69143 -288.362644)
		(width 0.1143)
		(layer "In15.Cu")
		(net "P5E_CPU1_P0_RX_DP<10>")
	)
	(arc
		(start 64.662558 -367.854484)
		(mid 65.020145 -367.503533)
		(end 65.462912 -367.269014)
		(width 0.14224)
		(layer "In15.Cu")
		(net "P5E_CPU1_P0_RX_DP<10>")
	)
	(arc
		(start 106.763058 -280.220928)
		(mid 107.006385 -279.756362)
		(end 106.763058 -279.291796)
		(width 0.1143)
		(layer "In15.Cu")
		(net "P5E_CPU1_P0_RX_DP<10>")
	)
	(segment
		(start 47.67072 -386.003292)
		(end 48.19142 -386.003292)
		(width 0.127)
		(layer "F.Cu")
		(net "P5E_CPU1_P0_RX_DP<0>")
	)
	(segment
		(start 99.387914 -271.390364)
		(end 98.921062 -271.656302)
		(width 0.12954)
		(layer "F.Cu")
		(net "P5E_CPU1_P0_RX_DP<0>")
	)
	(segment
		(start 110.86592 -352.26244)
		(end 111.17326 -352.56978)
		(width 0.14224)
		(layer "In13.Cu")
		(net "P5E_CPU1_P0_RX_DP<0>")
	)
	(segment
		(start 119.88546 -351.14992)
		(end 111.17326 -351.14992)
		(width 0.14224)
		(layer "In13.Cu")
		(net "P5E_CPU1_P0_RX_DP<0>")
	)
	(segment
		(start 102.761542 -356.592632)
		(end 103.27259 -357.215694)
		(width 0.14224)
		(layer "In13.Cu")
		(net "P5E_CPU1_P0_RX_DP<0>")
	)
	(segment
		(start 97.29343 -281.88158)
		(end 97.363026 -281.84094)
		(width 0.1143)
		(layer "In13.Cu")
		(net "P5E_CPU1_P0_RX_DP<0>")
	)
	(segment
		(start 97.29343 -277.631144)
		(end 97.29089 -277.629366)
		(width 0.1143)
		(layer "In13.Cu")
		(net "P5E_CPU1_P0_RX_DP<0>")
	)
	(segment
		(start 97.291398 -286.742632)
		(end 97.29216 -286.742124)
		(width 0.1143)
		(layer "In13.Cu")
		(net "P5E_CPU1_P0_RX_DP<0>")
	)
	(segment
		(start 97.363026 -280.911808)
		(end 97.29343 -280.871168)
		(width 0.1143)
		(layer "In13.Cu")
		(net "P5E_CPU1_P0_RX_DP<0>")
	)
	(segment
		(start 108.99775 -309.874412)
		(end 104.493568 -307.46573)
		(width 0.14224)
		(layer "In13.Cu")
		(net "P5E_CPU1_P0_RX_DP<0>")
	)
	(segment
		(start 120.0277 -350.43618)
		(end 120.0277 -351.00768)
		(width 0.14224)
		(layer "In13.Cu")
		(net "P5E_CPU1_P0_RX_DP<0>")
	)
	(segment
		(start 97.363026 -282.53182)
		(end 97.29343 -282.49118)
		(width 0.1143)
		(layer "In13.Cu")
		(net "P5E_CPU1_P0_RX_DP<0>")
	)
	(segment
		(start 120.0277 -351.00768)
		(end 119.88546 -351.14992)
		(width 0.14224)
		(layer "In13.Cu")
		(net "P5E_CPU1_P0_RX_DP<0>")
	)
	(segment
		(start 48.46066 -385.548632)
		(end 48.548798 -385.460494)
		(width 0.14224)
		(layer "In13.Cu")
		(net "P5E_CPU1_P0_RX_DP<0>")
	)
	(segment
		(start 48.548798 -385.046982)
		(end 48.232822 -384.731006)
		(width 0.14224)
		(layer "In13.Cu")
		(net "P5E_CPU1_P0_RX_DP<0>")
	)
	(segment
		(start 48.286416 -385.649216)
		(end 48.46066 -385.548632)
		(width 0.14224)
		(layer "In13.Cu")
		(net "P5E_CPU1_P0_RX_DP<0>")
	)
	(segment
		(start 98.62312 -271.656302)
		(end 98.921062 -271.656302)
		(width 0.1143)
		(layer "In13.Cu")
		(net "P5E_CPU1_P0_RX_DP<0>")
	)
	(segment
		(start 48.526446 -382.459484)
		(end 46.778672 -374.836182)
		(width 0.14224)
		(layer "In13.Cu")
		(net "P5E_CPU1_P0_RX_DP<0>")
	)
	(segment
		(start 98.233484 -272.161508)
		(end 98.30308 -272.120868)
		(width 0.1143)
		(layer "In13.Cu")
		(net "P5E_CPU1_P0_RX_DP<0>")
	)
	(segment
		(start 48.54067 -384.048254)
		(end 48.54067 -382.58496)
		(width 0.14224)
		(layer "In13.Cu")
		(net "P5E_CPU1_P0_RX_DP<0>")
	)
	(segment
		(start 111.17326 -352.56978)
		(end 121.363232 -352.56978)
		(width 0.14224)
		(layer "In13.Cu")
		(net "P5E_CPU1_P0_RX_DP<0>")
	)
	(segment
		(start 106.04754 -352.572574)
		(end 106.411522 -353.015296)
		(width 0.14224)
		(layer "In13.Cu")
		(net "P5E_CPU1_P0_RX_DP<0>")
	)
	(segment
		(start 48.232822 -384.731006)
		(end 48.23587 -384.3528)
		(width 0.14224)
		(layer "In13.Cu")
		(net "P5E_CPU1_P0_RX_DP<0>")
	)
	(segment
		(start 109.504734 -352.497136)
		(end 109.737398 -352.264218)
		(width 0.14224)
		(layer "In13.Cu")
		(net "P5E_CPU1_P0_RX_DP<0>")
	)
	(segment
		(start 97.363026 -292.251638)
		(end 97.29343 -292.210998)
		(width 0.1143)
		(layer "In13.Cu")
		(net "P5E_CPU1_P0_RX_DP<0>")
	)
	(segment
		(start 97.363026 -293.87165)
		(end 97.29343 -293.83101)
		(width 0.1143)
		(layer "In13.Cu")
		(net "P5E_CPU1_P0_RX_DP<0>")
	)
	(segment
		(start 101.450902 -356.346506)
		(end 101.470714 -356.146862)
		(width 0.14224)
		(layer "In13.Cu")
		(net "P5E_CPU1_P0_RX_DP<0>")
	)
	(segment
		(start 97.79508 -272.953226)
		(end 97.796604 -272.95221)
		(width 0.1143)
		(layer "In13.Cu")
		(net "P5E_CPU1_P0_RX_DP<0>")
	)
	(segment
		(start 97.29343 -280.261568)
		(end 97.363026 -280.220928)
		(width 0.1143)
		(layer "In13.Cu")
		(net "P5E_CPU1_P0_RX_DP<0>")
	)
	(segment
		(start 97.363026 -289.011614)
		(end 97.29343 -288.970974)
		(width 0.1143)
		(layer "In13.Cu")
		(net "P5E_CPU1_P0_RX_DP<0>")
	)
	(segment
		(start 48.548798 -385.460494)
		(end 48.548798 -385.046982)
		(width 0.14224)
		(layer "In13.Cu")
		(net "P5E_CPU1_P0_RX_DP<0>")
	)
	(segment
		(start 97.796604 -272.95221)
		(end 97.83318 -272.930874)
		(width 0.1143)
		(layer "In13.Cu")
		(net "P5E_CPU1_P0_RX_DP<0>")
	)
	(segment
		(start 102.80396 -356.16007)
		(end 102.761542 -356.592632)
		(width 0.14224)
		(layer "In13.Cu")
		(net "P5E_CPU1_P0_RX_DP<0>")
	)
	(segment
		(start 48.19142 -386.003292)
		(end 48.286416 -385.649216)
		(width 0.14224)
		(layer "In13.Cu")
		(net "P5E_CPU1_P0_RX_DP<0>")
	)
	(segment
		(start 97.291398 -288.362644)
		(end 97.363026 -288.320988)
		(width 0.1143)
		(layer "In13.Cu")
		(net "P5E_CPU1_P0_RX_DP<0>")
	)
	(segment
		(start 97.29343 -285.121604)
		(end 97.363026 -285.080964)
		(width 0.1143)
		(layer "In13.Cu")
		(net "P5E_CPU1_P0_RX_DP<0>")
	)
	(segment
		(start 97.762314 -272.972022)
		(end 97.787714 -272.95729)
		(width 0.1143)
		(layer "In13.Cu")
		(net "P5E_CPU1_P0_RX_DP<0>")
	)
	(segment
		(start 97.29343 -273.78152)
		(end 97.363026 -273.74088)
		(width 0.1143)
		(layer "In13.Cu")
		(net "P5E_CPU1_P0_RX_DP<0>")
	)
	(segment
		(start 96.712024 -296.39387)
		(end 96.666304 -296.34815)
		(width 0.1143)
		(layer "In13.Cu")
		(net "P5E_CPU1_P0_RX_DP<0>")
	)
	(segment
		(start 101.470714 -356.146862)
		(end 105.84815 -352.552762)
		(width 0.14224)
		(layer "In13.Cu")
		(net "P5E_CPU1_P0_RX_DP<0>")
	)
	(segment
		(start 97.363026 -276.051772)
		(end 97.29343 -276.011132)
		(width 0.1143)
		(layer "In13.Cu")
		(net "P5E_CPU1_P0_RX_DP<0>")
	)
	(segment
		(start 122.200162 -331.508862)
		(end 120.767856 -326.454008)
		(width 0.14224)
		(layer "In13.Cu")
		(net "P5E_CPU1_P0_RX_DP<0>")
	)
	(segment
		(start 97.29343 -293.22141)
		(end 97.363026 -293.18077)
		(width 0.1143)
		(layer "In13.Cu")
		(net "P5E_CPU1_P0_RX_DP<0>")
	)
	(segment
		(start 109.881416 -350.29394)
		(end 119.88546 -350.29394)
		(width 0.14224)
		(layer "In13.Cu")
		(net "P5E_CPU1_P0_RX_DP<0>")
	)
	(segment
		(start 109.737398 -350.437958)
		(end 109.881416 -350.29394)
		(width 0.14224)
		(layer "In13.Cu")
		(net "P5E_CPU1_P0_RX_DP<0>")
	)
	(segment
		(start 97.360486 -287.390078)
		(end 97.29343 -287.350962)
		(width 0.1143)
		(layer "In13.Cu")
		(net "P5E_CPU1_P0_RX_DP<0>")
	)
	(segment
		(start 97.29343 -277.021544)
		(end 97.363026 -276.980904)
		(width 0.1143)
		(layer "In13.Cu")
		(net "P5E_CPU1_P0_RX_DP<0>")
	)
	(segment
		(start 117.634004 -320.923158)
		(end 112.225328 -313.630056)
		(width 0.14224)
		(layer "In13.Cu")
		(net "P5E_CPU1_P0_RX_DP<0>")
	)
	(segment
		(start 97.29343 -275.401532)
		(end 97.363026 -275.360892)
		(width 0.1143)
		(layer "In13.Cu")
		(net "P5E_CPU1_P0_RX_DP<0>")
	)
	(segment
		(start 110.86592 -351.45726)
		(end 110.86592 -352.26244)
		(width 0.14224)
		(layer "In13.Cu")
		(net "P5E_CPU1_P0_RX_DP<0>")
	)
	(segment
		(start 97.794064 -272.953734)
		(end 97.79508 -272.953226)
		(width 0.1143)
		(layer "In13.Cu")
		(net "P5E_CPU1_P0_RX_DP<0>")
	)
	(segment
		(start 97.363026 -279.291796)
		(end 97.29343 -279.251156)
		(width 0.1143)
		(layer "In13.Cu")
		(net "P5E_CPU1_P0_RX_DP<0>")
	)
	(segment
		(start 103.705152 -357.257858)
		(end 109.504734 -352.497136)
		(width 0.14224)
		(layer "In13.Cu")
		(net "P5E_CPU1_P0_RX_DP<0>")
	)
	(segment
		(start 99.100386 -361.038648)
		(end 102.568502 -358.191308)
		(width 0.14224)
		(layer "In13.Cu")
		(net "P5E_CPU1_P0_RX_DP<0>")
	)
	(segment
		(start 46.77156 -374.773444)
		(end 46.77156 -373.718836)
		(width 0.14224)
		(layer "In13.Cu")
		(net "P5E_CPU1_P0_RX_DP<0>")
	)
	(segment
		(start 50.969672 -367.596166)
		(end 62.785244 -361.28071)
		(width 0.14224)
		(layer "In13.Cu")
		(net "P5E_CPU1_P0_RX_DP<0>")
	)
	(segment
		(start 97.29343 -283.501592)
		(end 97.363026 -283.460952)
		(width 0.1143)
		(layer "In13.Cu")
		(net "P5E_CPU1_P0_RX_DP<0>")
	)
	(segment
		(start 125.611128 -348.667324)
		(end 122.200162 -331.508862)
		(width 0.14224)
		(layer "In13.Cu")
		(net "P5E_CPU1_P0_RX_DP<0>")
	)
	(segment
		(start 97.292414 -294.842184)
		(end 97.363026 -294.800782)
		(width 0.1143)
		(layer "In13.Cu")
		(net "P5E_CPU1_P0_RX_DP<0>")
	)
	(segment
		(start 105.84815 -352.552762)
		(end 106.04754 -352.572574)
		(width 0.14224)
		(layer "In13.Cu")
		(net "P5E_CPU1_P0_RX_DP<0>")
	)
	(segment
		(start 109.445552 -310.242966)
		(end 108.99775 -309.874412)
		(width 0.14224)
		(layer "In13.Cu")
		(net "P5E_CPU1_P0_RX_DP<0>")
	)
	(segment
		(start 97.363026 -277.671784)
		(end 97.29343 -277.631144)
		(width 0.1143)
		(layer "In13.Cu")
		(net "P5E_CPU1_P0_RX_DP<0>")
	)
	(segment
		(start 109.737398 -352.264218)
		(end 109.737398 -350.437958)
		(width 0.14224)
		(layer "In13.Cu")
		(net "P5E_CPU1_P0_RX_DP<0>")
	)
	(segment
		(start 122.106182 -352.304096)
		(end 125.223778 -349.748602)
		(width 0.14224)
		(layer "In13.Cu")
		(net "P5E_CPU1_P0_RX_DP<0>")
	)
	(segment
		(start 97.29089 -277.023322)
		(end 97.29343 -277.021544)
		(width 0.1143)
		(layer "In13.Cu")
		(net "P5E_CPU1_P0_RX_DP<0>")
	)
	(segment
		(start 50.559462 -367.996978)
		(end 50.934874 -367.621566)
		(width 0.14224)
		(layer "In13.Cu")
		(net "P5E_CPU1_P0_RX_DP<0>")
	)
	(segment
		(start 111.17326 -351.14992)
		(end 110.86592 -351.45726)
		(width 0.14224)
		(layer "In13.Cu")
		(net "P5E_CPU1_P0_RX_DP<0>")
	)
	(segment
		(start 96.712024 -299.4279)
		(end 96.712024 -296.422318)
		(width 0.14224)
		(layer "In13.Cu")
		(net "P5E_CPU1_P0_RX_DP<0>")
	)
	(segment
		(start 97.363026 -285.771844)
		(end 97.29343 -285.731204)
		(width 0.1143)
		(layer "In13.Cu")
		(net "P5E_CPU1_P0_RX_DP<0>")
	)
	(segment
		(start 98.540316 -271.739106)
		(end 98.62312 -271.656302)
		(width 0.1143)
		(layer "In13.Cu")
		(net "P5E_CPU1_P0_RX_DP<0>")
	)
	(segment
		(start 106.39171 -353.214686)
		(end 102.80396 -356.16007)
		(width 0.14224)
		(layer "In13.Cu")
		(net "P5E_CPU1_P0_RX_DP<0>")
	)
	(segment
		(start 96.862392 -295.753282)
		(end 97.043494 -295.57218)
		(width 0.1143)
		(layer "In13.Cu")
		(net "P5E_CPU1_P0_RX_DP<0>")
	)
	(segment
		(start 97.793302 -272.954242)
		(end 97.794064 -272.953734)
		(width 0.1143)
		(layer "In13.Cu")
		(net "P5E_CPU1_P0_RX_DP<0>")
	)
	(segment
		(start 97.789746 -272.956274)
		(end 97.790508 -272.955766)
		(width 0.1143)
		(layer "In13.Cu")
		(net "P5E_CPU1_P0_RX_DP<0>")
	)
	(segment
		(start 103.27259 -357.215694)
		(end 103.705152 -357.257858)
		(width 0.14224)
		(layer "In13.Cu")
		(net "P5E_CPU1_P0_RX_DP<0>")
	)
	(segment
		(start 119.88546 -350.29394)
		(end 120.0277 -350.43618)
		(width 0.14224)
		(layer "In13.Cu")
		(net "P5E_CPU1_P0_RX_DP<0>")
	)
	(segment
		(start 97.29343 -291.601398)
		(end 97.363026 -291.560758)
		(width 0.1143)
		(layer "In13.Cu")
		(net "P5E_CPU1_P0_RX_DP<0>")
	)
	(segment
		(start 106.411522 -353.015296)
		(end 106.39171 -353.214686)
		(width 0.14224)
		(layer "In13.Cu")
		(net "P5E_CPU1_P0_RX_DP<0>")
	)
	(segment
		(start 97.787714 -272.95729)
		(end 97.789746 -272.956274)
		(width 0.1143)
		(layer "In13.Cu")
		(net "P5E_CPU1_P0_RX_DP<0>")
	)
	(segment
		(start 97.363026 -274.43176)
		(end 97.29343 -274.39112)
		(width 0.1143)
		(layer "In13.Cu")
		(net "P5E_CPU1_P0_RX_DP<0>")
	)
	(segment
		(start 48.23587 -384.3528)
		(end 48.54067 -384.048254)
		(width 0.14224)
		(layer "In13.Cu")
		(net "P5E_CPU1_P0_RX_DP<0>")
	)
	(segment
		(start 97.790508 -272.955766)
		(end 97.793302 -272.954242)
		(width 0.1143)
		(layer "In13.Cu")
		(net "P5E_CPU1_P0_RX_DP<0>")
	)
	(segment
		(start 120.767856 -326.454008)
		(end 117.634004 -320.923158)
		(width 0.14224)
		(layer "In13.Cu")
		(net "P5E_CPU1_P0_RX_DP<0>")
	)
	(segment
		(start 97.363026 -290.631626)
		(end 97.29343 -290.590986)
		(width 0.1143)
		(layer "In13.Cu")
		(net "P5E_CPU1_P0_RX_DP<0>")
	)
	(segment
		(start 96.712024 -296.422318)
		(end 96.712024 -296.39387)
		(width 0.1143)
		(layer "In13.Cu")
		(net "P5E_CPU1_P0_RX_DP<0>")
	)
	(segment
		(start 102.61092 -357.758746)
		(end 101.450902 -356.346506)
		(width 0.14224)
		(layer "In13.Cu")
		(net "P5E_CPU1_P0_RX_DP<0>")
	)
	(segment
		(start 96.666304 -296.34815)
		(end 96.666304 -296.226738)
		(width 0.1143)
		(layer "In13.Cu")
		(net "P5E_CPU1_P0_RX_DP<0>")
	)
	(segment
		(start 97.136458 -295.347136)
		(end 97.136458 -295.145968)
		(width 0.1143)
		(layer "In13.Cu")
		(net "P5E_CPU1_P0_RX_DP<0>")
	)
	(segment
		(start 97.136458 -295.145968)
		(end 97.136712 -295.146222)
		(width 0.1143)
		(layer "In13.Cu")
		(net "P5E_CPU1_P0_RX_DP<0>")
	)
	(segment
		(start 97.29343 -278.641556)
		(end 97.363026 -278.600916)
		(width 0.1143)
		(layer "In13.Cu")
		(net "P5E_CPU1_P0_RX_DP<0>")
	)
	(segment
		(start 112.225328 -313.630056)
		(end 109.445552 -310.242966)
		(width 0.14224)
		(layer "In13.Cu")
		(net "P5E_CPU1_P0_RX_DP<0>")
	)
	(segment
		(start 97.363026 -284.151832)
		(end 97.29343 -284.111192)
		(width 0.1143)
		(layer "In13.Cu")
		(net "P5E_CPU1_P0_RX_DP<0>")
	)
	(segment
		(start 103.933244 -307.05044)
		(end 96.995996 -300.113192)
		(width 0.14224)
		(layer "In13.Cu")
		(net "P5E_CPU1_P0_RX_DP<0>")
	)
	(segment
		(start 46.807882 -373.599456)
		(end 50.51425 -368.052096)
		(width 0.14224)
		(layer "In13.Cu")
		(net "P5E_CPU1_P0_RX_DP<0>")
	)
	(segment
		(start 102.568502 -358.191308)
		(end 102.61092 -357.758746)
		(width 0.14224)
		(layer "In13.Cu")
		(net "P5E_CPU1_P0_RX_DP<0>")
	)
	(segment
		(start 63.380874 -361.131612)
		(end 98.840544 -361.131612)
		(width 0.14224)
		(layer "In13.Cu")
		(net "P5E_CPU1_P0_RX_DP<0>")
	)
	(segment
		(start 97.29216 -286.742124)
		(end 97.294192 -286.740854)
		(width 0.1143)
		(layer "In13.Cu")
		(net "P5E_CPU1_P0_RX_DP<0>")
	)
	(segment
		(start 97.294192 -286.740854)
		(end 97.363026 -286.700976)
		(width 0.1143)
		(layer "In13.Cu")
		(net "P5E_CPU1_P0_RX_DP<0>")
	)
	(segment
		(start 97.29343 -289.981386)
		(end 97.363026 -289.940746)
		(width 0.1143)
		(layer "In13.Cu")
		(net "P5E_CPU1_P0_RX_DP<0>")
	)
	(arc
		(start 104.493568 -307.46573)
		(mid 104.198092 -307.278747)
		(end 103.933244 -307.05044)
		(width 0.14224)
		(layer "In13.Cu")
		(net "P5E_CPU1_P0_RX_DP<0>")
	)
	(arc
		(start 97.136712 -295.146222)
		(mid 97.177832 -294.975382)
		(end 97.292414 -294.842184)
		(width 0.1143)
		(layer "In13.Cu")
		(net "P5E_CPU1_P0_RX_DP<0>")
	)
	(arc
		(start 97.29343 -290.590986)
		(mid 97.136453 -290.286186)
		(end 97.29343 -289.981386)
		(width 0.1143)
		(layer "In13.Cu")
		(net "P5E_CPU1_P0_RX_DP<0>")
	)
	(arc
		(start 97.363026 -289.940746)
		(mid 97.606353 -289.47618)
		(end 97.363026 -289.011614)
		(width 0.1143)
		(layer "In13.Cu")
		(net "P5E_CPU1_P0_RX_DP<0>")
	)
	(arc
		(start 97.29343 -284.111192)
		(mid 97.136453 -283.806392)
		(end 97.29343 -283.501592)
		(width 0.1143)
		(layer "In13.Cu")
		(net "P5E_CPU1_P0_RX_DP<0>")
	)
	(arc
		(start 97.136458 -288.666174)
		(mid 97.177424 -288.495768)
		(end 97.291398 -288.362644)
		(width 0.1143)
		(layer "In13.Cu")
		(net "P5E_CPU1_P0_RX_DP<0>")
	)
	(arc
		(start 97.606358 -273.276314)
		(mid 97.647613 -273.105343)
		(end 97.762314 -272.972022)
		(width 0.1143)
		(layer "In13.Cu")
		(net "P5E_CPU1_P0_RX_DP<0>")
	)
	(arc
		(start 50.934874 -367.621566)
		(mid 50.951341 -367.607589)
		(end 50.969672 -367.596166)
		(width 0.14224)
		(layer "In13.Cu")
		(net "P5E_CPU1_P0_RX_DP<0>")
	)
	(arc
		(start 121.363232 -352.56978)
		(mid 121.757748 -352.501365)
		(end 122.106182 -352.304096)
		(width 0.14224)
		(layer "In13.Cu")
		(net "P5E_CPU1_P0_RX_DP<0>")
	)
	(arc
		(start 97.29343 -288.970974)
		(mid 97.178003 -288.837598)
		(end 97.136458 -288.666174)
		(width 0.1143)
		(layer "In13.Cu")
		(net "P5E_CPU1_P0_RX_DP<0>")
	)
	(arc
		(start 97.29343 -287.350962)
		(mid 97.178003 -287.217586)
		(end 97.136458 -287.046162)
		(width 0.1143)
		(layer "In13.Cu")
		(net "P5E_CPU1_P0_RX_DP<0>")
	)
	(arc
		(start 97.363026 -294.800782)
		(mid 97.606353 -294.336216)
		(end 97.363026 -293.87165)
		(width 0.1143)
		(layer "In13.Cu")
		(net "P5E_CPU1_P0_RX_DP<0>")
	)
	(arc
		(start 97.363026 -280.220928)
		(mid 97.606353 -279.756362)
		(end 97.363026 -279.291796)
		(width 0.1143)
		(layer "In13.Cu")
		(net "P5E_CPU1_P0_RX_DP<0>")
	)
	(arc
		(start 97.29343 -282.49118)
		(mid 97.136453 -282.18638)
		(end 97.29343 -281.88158)
		(width 0.1143)
		(layer "In13.Cu")
		(net "P5E_CPU1_P0_RX_DP<0>")
	)
	(arc
		(start 97.363026 -276.980904)
		(mid 97.606353 -276.516338)
		(end 97.363026 -276.051772)
		(width 0.1143)
		(layer "In13.Cu")
		(net "P5E_CPU1_P0_RX_DP<0>")
	)
	(arc
		(start 98.840544 -361.131612)
		(mid 98.978533 -361.107675)
		(end 99.100386 -361.038648)
		(width 0.14224)
		(layer "In13.Cu")
		(net "P5E_CPU1_P0_RX_DP<0>")
	)
	(arc
		(start 97.29343 -279.251156)
		(mid 97.136453 -278.946356)
		(end 97.29343 -278.641556)
		(width 0.1143)
		(layer "In13.Cu")
		(net "P5E_CPU1_P0_RX_DP<0>")
	)
	(arc
		(start 97.363026 -273.74088)
		(mid 97.541839 -273.53853)
		(end 97.606358 -273.276314)
		(width 0.1143)
		(layer "In13.Cu")
		(net "P5E_CPU1_P0_RX_DP<0>")
	)
	(arc
		(start 97.363026 -285.080964)
		(mid 97.606353 -284.616398)
		(end 97.363026 -284.151832)
		(width 0.1143)
		(layer "In13.Cu")
		(net "P5E_CPU1_P0_RX_DP<0>")
	)
	(arc
		(start 97.363026 -286.700976)
		(mid 97.606353 -286.23641)
		(end 97.363026 -285.771844)
		(width 0.1143)
		(layer "In13.Cu")
		(net "P5E_CPU1_P0_RX_DP<0>")
	)
	(arc
		(start 98.30308 -272.120868)
		(mid 98.455067 -271.96436)
		(end 98.536506 -271.761966)
		(width 0.1143)
		(layer "In13.Cu")
		(net "P5E_CPU1_P0_RX_DP<0>")
	)
	(arc
		(start 97.363026 -283.460952)
		(mid 97.606353 -282.996386)
		(end 97.363026 -282.53182)
		(width 0.1143)
		(layer "In13.Cu")
		(net "P5E_CPU1_P0_RX_DP<0>")
	)
	(arc
		(start 96.666304 -296.226738)
		(mid 96.71727 -295.970515)
		(end 96.862392 -295.753282)
		(width 0.1143)
		(layer "In13.Cu")
		(net "P5E_CPU1_P0_RX_DP<0>")
	)
	(arc
		(start 97.29343 -292.210998)
		(mid 97.136453 -291.906198)
		(end 97.29343 -291.601398)
		(width 0.1143)
		(layer "In13.Cu")
		(net "P5E_CPU1_P0_RX_DP<0>")
	)
	(arc
		(start 97.363026 -281.84094)
		(mid 97.606353 -281.376374)
		(end 97.363026 -280.911808)
		(width 0.1143)
		(layer "In13.Cu")
		(net "P5E_CPU1_P0_RX_DP<0>")
	)
	(arc
		(start 97.363026 -293.18077)
		(mid 97.606353 -292.716204)
		(end 97.363026 -292.251638)
		(width 0.1143)
		(layer "In13.Cu")
		(net "P5E_CPU1_P0_RX_DP<0>")
	)
	(arc
		(start 97.363026 -278.600916)
		(mid 97.606353 -278.13635)
		(end 97.363026 -277.671784)
		(width 0.1143)
		(layer "In13.Cu")
		(net "P5E_CPU1_P0_RX_DP<0>")
	)
	(arc
		(start 97.29343 -274.39112)
		(mid 97.136453 -274.08632)
		(end 97.29343 -273.78152)
		(width 0.1143)
		(layer "In13.Cu")
		(net "P5E_CPU1_P0_RX_DP<0>")
	)
	(arc
		(start 50.51425 -368.052096)
		(mid 50.535499 -368.023424)
		(end 50.559462 -367.996978)
		(width 0.14224)
		(layer "In13.Cu")
		(net "P5E_CPU1_P0_RX_DP<0>")
	)
	(arc
		(start 62.785244 -361.28071)
		(mid 63.073868 -361.169455)
		(end 63.380874 -361.131612)
		(width 0.14224)
		(layer "In13.Cu")
		(net "P5E_CPU1_P0_RX_DP<0>")
	)
	(arc
		(start 97.363026 -291.560758)
		(mid 97.606353 -291.096192)
		(end 97.363026 -290.631626)
		(width 0.1143)
		(layer "In13.Cu")
		(net "P5E_CPU1_P0_RX_DP<0>")
	)
	(arc
		(start 97.363026 -288.320988)
		(mid 97.60635 -287.854872)
		(end 97.360486 -287.390078)
		(width 0.1143)
		(layer "In13.Cu")
		(net "P5E_CPU1_P0_RX_DP<0>")
	)
	(arc
		(start 97.29089 -277.629366)
		(mid 97.134828 -277.326344)
		(end 97.29089 -277.023322)
		(width 0.1143)
		(layer "In13.Cu")
		(net "P5E_CPU1_P0_RX_DP<0>")
	)
	(arc
		(start 48.54067 -382.58496)
		(mid 48.537081 -382.521824)
		(end 48.526446 -382.459484)
		(width 0.14224)
		(layer "In13.Cu")
		(net "P5E_CPU1_P0_RX_DP<0>")
	)
	(arc
		(start 125.223778 -349.748602)
		(mid 125.567123 -349.261582)
		(end 125.611128 -348.667324)
		(width 0.14224)
		(layer "In13.Cu")
		(net "P5E_CPU1_P0_RX_DP<0>")
	)
	(arc
		(start 98.076512 -272.466308)
		(mid 98.118061 -272.294886)
		(end 98.233484 -272.161508)
		(width 0.1143)
		(layer "In13.Cu")
		(net "P5E_CPU1_P0_RX_DP<0>")
	)
	(arc
		(start 98.536506 -271.761966)
		(mid 98.538529 -271.750556)
		(end 98.540316 -271.739106)
		(width 0.1143)
		(layer "In13.Cu")
		(net "P5E_CPU1_P0_RX_DP<0>")
	)
	(arc
		(start 46.778672 -374.836182)
		(mid 46.773332 -374.805015)
		(end 46.77156 -374.773444)
		(width 0.14224)
		(layer "In13.Cu")
		(net "P5E_CPU1_P0_RX_DP<0>")
	)
	(arc
		(start 96.995996 -300.113192)
		(mid 96.785803 -299.798806)
		(end 96.712024 -299.4279)
		(width 0.14224)
		(layer "In13.Cu")
		(net "P5E_CPU1_P0_RX_DP<0>")
	)
	(arc
		(start 97.363026 -275.360892)
		(mid 97.606353 -274.896326)
		(end 97.363026 -274.43176)
		(width 0.1143)
		(layer "In13.Cu")
		(net "P5E_CPU1_P0_RX_DP<0>")
	)
	(arc
		(start 97.136458 -287.046162)
		(mid 97.177424 -286.875756)
		(end 97.291398 -286.742632)
		(width 0.1143)
		(layer "In13.Cu")
		(net "P5E_CPU1_P0_RX_DP<0>")
	)
	(arc
		(start 97.29343 -276.011132)
		(mid 97.136453 -275.706332)
		(end 97.29343 -275.401532)
		(width 0.1143)
		(layer "In13.Cu")
		(net "P5E_CPU1_P0_RX_DP<0>")
	)
	(arc
		(start 46.77156 -373.718836)
		(mid 46.780889 -373.656463)
		(end 46.807882 -373.599456)
		(width 0.14224)
		(layer "In13.Cu")
		(net "P5E_CPU1_P0_RX_DP<0>")
	)
	(arc
		(start 97.83318 -272.930874)
		(mid 98.011993 -272.728524)
		(end 98.076512 -272.466308)
		(width 0.1143)
		(layer "In13.Cu")
		(net "P5E_CPU1_P0_RX_DP<0>")
	)
	(arc
		(start 97.29343 -280.871168)
		(mid 97.136453 -280.566368)
		(end 97.29343 -280.261568)
		(width 0.1143)
		(layer "In13.Cu")
		(net "P5E_CPU1_P0_RX_DP<0>")
	)
	(arc
		(start 97.29343 -293.83101)
		(mid 97.136453 -293.52621)
		(end 97.29343 -293.22141)
		(width 0.1143)
		(layer "In13.Cu")
		(net "P5E_CPU1_P0_RX_DP<0>")
	)
	(arc
		(start 97.29343 -285.731204)
		(mid 97.136453 -285.426404)
		(end 97.29343 -285.121604)
		(width 0.1143)
		(layer "In13.Cu")
		(net "P5E_CPU1_P0_RX_DP<0>")
	)
	(arc
		(start 97.043494 -295.57218)
		(mid 97.112348 -295.4689)
		(end 97.136458 -295.347136)
		(width 0.1143)
		(layer "In13.Cu")
		(net "P5E_CPU1_P0_RX_DP<0>")
	)
	(segment
		(start 58.070496 -385.31038)
		(end 58.591196 -385.31038)
		(width 0.127)
		(layer "F.Cu")
		(net "P5E_CPU1_P0_RX_DN<9>")
	)
	(segment
		(start 106.907838 -271.390364)
		(end 106.440986 -271.656302)
		(width 0.12954)
		(layer "F.Cu")
		(net "P5E_CPU1_P0_RX_DN<9>")
	)
	(segment
		(start 58.591196 -385.31038)
		(end 58.94451 -385.405376)
		(width 0.14224)
		(layer "In15.Cu")
		(net "P5E_CPU1_P0_RX_DN<9>")
	)
	(segment
		(start 105.68813 -276.193758)
		(end 105.649014 -276.170898)
		(width 0.1143)
		(layer "In15.Cu")
		(net "P5E_CPU1_P0_RX_DN<9>")
	)
	(segment
		(start 105.68813 -292.393624)
		(end 105.649014 -292.370764)
		(width 0.1143)
		(layer "In15.Cu")
		(net "P5E_CPU1_P0_RX_DN<9>")
	)
	(segment
		(start 129.99974 -361.230418)
		(end 129.8575 -361.088178)
		(width 0.14224)
		(layer "In15.Cu")
		(net "P5E_CPU1_P0_RX_DN<9>")
	)
	(segment
		(start 106.738928 -271.656302)
		(end 106.440986 -271.656302)
		(width 0.1143)
		(layer "In15.Cu")
		(net "P5E_CPU1_P0_RX_DN<9>")
	)
	(segment
		(start 117.441472 -331.692504)
		(end 105.034842 -301.739046)
		(width 0.14224)
		(layer "In15.Cu")
		(net "P5E_CPU1_P0_RX_DN<9>")
	)
	(segment
		(start 105.68813 -291.418772)
		(end 105.71861 -291.400992)
		(width 0.1143)
		(layer "In15.Cu")
		(net "P5E_CPU1_P0_RX_DN<9>")
	)
	(segment
		(start 105.68813 -293.038784)
		(end 105.71861 -293.021004)
		(width 0.1143)
		(layer "In15.Cu")
		(net "P5E_CPU1_P0_RX_DN<9>")
	)
	(segment
		(start 143.84782 -359.531158)
		(end 144.27454 -359.531158)
		(width 0.14224)
		(layer "In15.Cu")
		(net "P5E_CPU1_P0_RX_DN<9>")
	)
	(segment
		(start 105.71861 -279.451562)
		(end 105.68813 -279.433782)
		(width 0.1143)
		(layer "In15.Cu")
		(net "P5E_CPU1_P0_RX_DN<9>")
	)
	(segment
		(start 105.68813 -279.433782)
		(end 105.649014 -279.410922)
		(width 0.1143)
		(layer "In15.Cu")
		(net "P5E_CPU1_P0_RX_DN<9>")
	)
	(segment
		(start 105.68813 -273.598894)
		(end 105.71861 -273.581114)
		(width 0.1143)
		(layer "In15.Cu")
		(net "P5E_CPU1_P0_RX_DN<9>")
	)
	(segment
		(start 105.405682 -295.315132)
		(end 105.405682 -295.146222)
		(width 0.1143)
		(layer "In15.Cu")
		(net "P5E_CPU1_P0_RX_DN<9>")
	)
	(segment
		(start 106.589068 -272.001742)
		(end 106.628184 -271.978882)
		(width 0.1143)
		(layer "In15.Cu")
		(net "P5E_CPU1_P0_RX_DN<9>")
	)
	(segment
		(start 105.68813 -276.838918)
		(end 105.71861 -276.821138)
		(width 0.1143)
		(layer "In15.Cu")
		(net "P5E_CPU1_P0_RX_DN<9>")
	)
	(segment
		(start 105.649014 -280.101802)
		(end 105.68813 -280.078942)
		(width 0.1143)
		(layer "In15.Cu")
		(net "P5E_CPU1_P0_RX_DN<9>")
	)
	(segment
		(start 58.94451 -385.405376)
		(end 58.945018 -385.404868)
		(width 0.14224)
		(layer "In15.Cu")
		(net "P5E_CPU1_P0_RX_DN<9>")
	)
	(segment
		(start 105.649014 -288.201608)
		(end 105.68813 -288.178748)
		(width 0.1143)
		(layer "In15.Cu")
		(net "P5E_CPU1_P0_RX_DN<9>")
	)
	(segment
		(start 145.53946 -359.668318)
		(end 146.17954 -359.668318)
		(width 0.14224)
		(layer "In15.Cu")
		(net "P5E_CPU1_P0_RX_DN<9>")
	)
	(segment
		(start 144.97558 -359.531158)
		(end 145.4023 -359.531158)
		(width 0.14224)
		(layer "In15.Cu")
		(net "P5E_CPU1_P0_RX_DN<9>")
	)
	(segment
		(start 118.178326 -359.668318)
		(end 143.71066 -359.668318)
		(width 0.14224)
		(layer "In15.Cu")
		(net "P5E_CPU1_P0_RX_DN<9>")
	)
	(segment
		(start 105.71861 -290.791392)
		(end 105.68813 -290.773612)
		(width 0.1143)
		(layer "In15.Cu")
		(net "P5E_CPU1_P0_RX_DN<9>")
	)
	(segment
		(start 146.3167 -359.531158)
		(end 146.74342 -359.531158)
		(width 0.14224)
		(layer "In15.Cu")
		(net "P5E_CPU1_P0_RX_DN<9>")
	)
	(segment
		(start 148.69033 -359.214166)
		(end 148.69033 -357.84536)
		(width 0.14224)
		(layer "In15.Cu")
		(net "P5E_CPU1_P0_RX_DN<9>")
	)
	(segment
		(start 106.118914 -272.811748)
		(end 106.18978 -272.7706)
		(width 0.1143)
		(layer "In15.Cu")
		(net "P5E_CPU1_P0_RX_DN<9>")
	)
	(segment
		(start 105.71861 -282.691586)
		(end 105.68813 -282.673806)
		(width 0.1143)
		(layer "In15.Cu")
		(net "P5E_CPU1_P0_RX_DN<9>")
	)
	(segment
		(start 104.97185 -296.37482)
		(end 104.97185 -296.346372)
		(width 0.1143)
		(layer "In15.Cu")
		(net "P5E_CPU1_P0_RX_DN<9>")
	)
	(segment
		(start 105.649014 -281.721814)
		(end 105.68813 -281.698954)
		(width 0.1143)
		(layer "In15.Cu")
		(net "P5E_CPU1_P0_RX_DN<9>")
	)
	(segment
		(start 64.769238 -366.216184)
		(end 75.229212 -362.490766)
		(width 0.14224)
		(layer "In15.Cu")
		(net "P5E_CPU1_P0_RX_DN<9>")
	)
	(segment
		(start 105.649014 -275.241766)
		(end 105.68813 -275.218906)
		(width 0.1143)
		(layer "In15.Cu")
		(net "P5E_CPU1_P0_RX_DN<9>")
	)
	(segment
		(start 58.716418 -374.938036)
		(end 59.321446 -372.997222)
		(width 0.14224)
		(layer "In15.Cu")
		(net "P5E_CPU1_P0_RX_DN<9>")
	)
	(segment
		(start 105.71861 -292.411404)
		(end 105.68813 -292.393624)
		(width 0.1143)
		(layer "In15.Cu")
		(net "P5E_CPU1_P0_RX_DN<9>")
	)
	(segment
		(start 105.71861 -274.591526)
		(end 105.68813 -274.573746)
		(width 0.1143)
		(layer "In15.Cu")
		(net "P5E_CPU1_P0_RX_DN<9>")
	)
	(segment
		(start 148.38045 -357.20147)
		(end 131.68249 -346.044774)
		(width 0.14224)
		(layer "In15.Cu")
		(net "P5E_CPU1_P0_RX_DN<9>")
	)
	(segment
		(start 58.749692 -384.84683)
		(end 58.754518 -384.234944)
		(width 0.14224)
		(layer "In15.Cu")
		(net "P5E_CPU1_P0_RX_DN<9>")
	)
	(segment
		(start 144.27454 -359.531158)
		(end 144.4117 -359.668318)
		(width 0.14224)
		(layer "In15.Cu")
		(net "P5E_CPU1_P0_RX_DN<9>")
	)
	(segment
		(start 105.71861 -281.071574)
		(end 105.68813 -281.053794)
		(width 0.1143)
		(layer "In15.Cu")
		(net "P5E_CPU1_P0_RX_DN<9>")
	)
	(segment
		(start 105.110788 -295.694862)
		(end 105.34523 -295.46042)
		(width 0.1143)
		(layer "In15.Cu")
		(net "P5E_CPU1_P0_RX_DN<9>")
	)
	(segment
		(start 105.68813 -282.673806)
		(end 105.649014 -282.650946)
		(width 0.1143)
		(layer "In15.Cu")
		(net "P5E_CPU1_P0_RX_DN<9>")
	)
	(segment
		(start 105.71861 -276.211538)
		(end 105.68813 -276.193758)
		(width 0.1143)
		(layer "In15.Cu")
		(net "P5E_CPU1_P0_RX_DN<9>")
	)
	(segment
		(start 105.71861 -285.93161)
		(end 105.68813 -285.91383)
		(width 0.1143)
		(layer "In15.Cu")
		(net "P5E_CPU1_P0_RX_DN<9>")
	)
	(segment
		(start 146.88058 -359.668318)
		(end 148.31949 -359.668318)
		(width 0.14224)
		(layer "In15.Cu")
		(net "P5E_CPU1_P0_RX_DN<9>")
	)
	(segment
		(start 105.649014 -291.441632)
		(end 105.68813 -291.418772)
		(width 0.1143)
		(layer "In15.Cu")
		(net "P5E_CPU1_P0_RX_DN<9>")
	)
	(segment
		(start 105.71861 -277.83155)
		(end 105.68813 -277.81377)
		(width 0.1143)
		(layer "In15.Cu")
		(net "P5E_CPU1_P0_RX_DN<9>")
	)
	(segment
		(start 105.649014 -289.82162)
		(end 105.68813 -289.79876)
		(width 0.1143)
		(layer "In15.Cu")
		(net "P5E_CPU1_P0_RX_DN<9>")
	)
	(segment
		(start 105.68813 -284.938978)
		(end 105.71861 -284.921198)
		(width 0.1143)
		(layer "In15.Cu")
		(net "P5E_CPU1_P0_RX_DN<9>")
	)
	(segment
		(start 105.68813 -277.81377)
		(end 105.649014 -277.79091)
		(width 0.1143)
		(layer "In15.Cu")
		(net "P5E_CPU1_P0_RX_DN<9>")
	)
	(segment
		(start 117.870986 -360.780838)
		(end 117.870986 -359.975658)
		(width 0.14224)
		(layer "In15.Cu")
		(net "P5E_CPU1_P0_RX_DN<9>")
	)
	(segment
		(start 105.649014 -283.341826)
		(end 105.68813 -283.318966)
		(width 0.1143)
		(layer "In15.Cu")
		(net "P5E_CPU1_P0_RX_DN<9>")
	)
	(segment
		(start 105.68813 -290.773612)
		(end 105.649014 -290.750752)
		(width 0.1143)
		(layer "In15.Cu")
		(net "P5E_CPU1_P0_RX_DN<9>")
	)
	(segment
		(start 105.651046 -286.580072)
		(end 105.68813 -286.558736)
		(width 0.1143)
		(layer "In15.Cu")
		(net "P5E_CPU1_P0_RX_DN<9>")
	)
	(segment
		(start 118.178326 -361.088178)
		(end 117.870986 -360.780838)
		(width 0.14224)
		(layer "In15.Cu")
		(net "P5E_CPU1_P0_RX_DN<9>")
	)
	(segment
		(start 105.649014 -273.621754)
		(end 105.68813 -273.598894)
		(width 0.1143)
		(layer "In15.Cu")
		(net "P5E_CPU1_P0_RX_DN<9>")
	)
	(segment
		(start 105.68813 -289.79876)
		(end 105.71861 -289.78098)
		(width 0.1143)
		(layer "In15.Cu")
		(net "P5E_CPU1_P0_RX_DN<9>")
	)
	(segment
		(start 105.68813 -288.178748)
		(end 105.720642 -288.159952)
		(width 0.1143)
		(layer "In15.Cu")
		(net "P5E_CPU1_P0_RX_DN<9>")
	)
	(segment
		(start 59.058556 -382.375664)
		(end 58.716418 -374.938036)
		(width 0.14224)
		(layer "In15.Cu")
		(net "P5E_CPU1_P0_RX_DN<9>")
	)
	(segment
		(start 146.74342 -359.531158)
		(end 146.88058 -359.668318)
		(width 0.14224)
		(layer "In15.Cu")
		(net "P5E_CPU1_P0_RX_DN<9>")
	)
	(segment
		(start 105.68813 -289.1536)
		(end 105.649014 -289.13074)
		(width 0.1143)
		(layer "In15.Cu")
		(net "P5E_CPU1_P0_RX_DN<9>")
	)
	(segment
		(start 105.68813 -281.698954)
		(end 105.71861 -281.681174)
		(width 0.1143)
		(layer "In15.Cu")
		(net "P5E_CPU1_P0_RX_DN<9>")
	)
	(segment
		(start 105.68813 -274.573746)
		(end 105.649014 -274.550886)
		(width 0.1143)
		(layer "In15.Cu")
		(net "P5E_CPU1_P0_RX_DN<9>")
	)
	(segment
		(start 146.17954 -359.668318)
		(end 146.3167 -359.531158)
		(width 0.14224)
		(layer "In15.Cu")
		(net "P5E_CPU1_P0_RX_DN<9>")
	)
	(segment
		(start 105.68813 -281.053794)
		(end 105.649014 -281.030934)
		(width 0.1143)
		(layer "In15.Cu")
		(net "P5E_CPU1_P0_RX_DN<9>")
	)
	(segment
		(start 105.649014 -276.861778)
		(end 105.68813 -276.838918)
		(width 0.1143)
		(layer "In15.Cu")
		(net "P5E_CPU1_P0_RX_DN<9>")
	)
	(segment
		(start 59.590686 -372.474998)
		(end 63.826136 -366.906048)
		(width 0.14224)
		(layer "In15.Cu")
		(net "P5E_CPU1_P0_RX_DN<9>")
	)
	(segment
		(start 129.8575 -361.088178)
		(end 118.178326 -361.088178)
		(width 0.14224)
		(layer "In15.Cu")
		(net "P5E_CPU1_P0_RX_DN<9>")
	)
	(segment
		(start 143.71066 -359.668318)
		(end 143.84782 -359.531158)
		(width 0.14224)
		(layer "In15.Cu")
		(net "P5E_CPU1_P0_RX_DN<9>")
	)
	(segment
		(start 105.71861 -289.17138)
		(end 105.68813 -289.1536)
		(width 0.1143)
		(layer "In15.Cu")
		(net "P5E_CPU1_P0_RX_DN<9>")
	)
	(segment
		(start 107.275884 -361.944158)
		(end 129.8575 -361.944158)
		(width 0.14224)
		(layer "In15.Cu")
		(net "P5E_CPU1_P0_RX_DN<9>")
	)
	(segment
		(start 105.68813 -280.078942)
		(end 105.71861 -280.061162)
		(width 0.1143)
		(layer "In15.Cu")
		(net "P5E_CPU1_P0_RX_DN<9>")
	)
	(segment
		(start 105.68813 -278.45893)
		(end 105.71861 -278.44115)
		(width 0.1143)
		(layer "In15.Cu")
		(net "P5E_CPU1_P0_RX_DN<9>")
	)
	(segment
		(start 148.409406 -359.63098)
		(end 148.594064 -359.446322)
		(width 0.14224)
		(layer "In15.Cu")
		(net "P5E_CPU1_P0_RX_DN<9>")
	)
	(segment
		(start 59.058556 -383.930906)
		(end 59.058556 -382.375664)
		(width 0.14224)
		(layer "In15.Cu")
		(net "P5E_CPU1_P0_RX_DN<9>")
	)
	(segment
		(start 59.066684 -385.334764)
		(end 59.066684 -385.163822)
		(width 0.14224)
		(layer "In15.Cu")
		(net "P5E_CPU1_P0_RX_DN<9>")
	)
	(segment
		(start 105.649014 -284.961838)
		(end 105.68813 -284.938978)
		(width 0.1143)
		(layer "In15.Cu")
		(net "P5E_CPU1_P0_RX_DN<9>")
	)
	(segment
		(start 105.68813 -285.91383)
		(end 105.649014 -285.89097)
		(width 0.1143)
		(layer "In15.Cu")
		(net "P5E_CPU1_P0_RX_DN<9>")
	)
	(segment
		(start 144.4117 -359.668318)
		(end 144.83842 -359.668318)
		(width 0.14224)
		(layer "In15.Cu")
		(net "P5E_CPU1_P0_RX_DN<9>")
	)
	(segment
		(start 144.83842 -359.668318)
		(end 144.97558 -359.531158)
		(width 0.14224)
		(layer "In15.Cu")
		(net "P5E_CPU1_P0_RX_DN<9>")
	)
	(segment
		(start 105.71861 -284.311598)
		(end 105.68813 -284.293818)
		(width 0.1143)
		(layer "In15.Cu")
		(net "P5E_CPU1_P0_RX_DN<9>")
	)
	(segment
		(start 105.649014 -286.581596)
		(end 105.651046 -286.580072)
		(width 0.1143)
		(layer "In15.Cu")
		(net "P5E_CPU1_P0_RX_DN<9>")
	)
	(segment
		(start 58.754518 -384.234944)
		(end 59.058556 -383.930906)
		(width 0.14224)
		(layer "In15.Cu")
		(net "P5E_CPU1_P0_RX_DN<9>")
	)
	(segment
		(start 105.649014 -278.48179)
		(end 105.68813 -278.45893)
		(width 0.1143)
		(layer "In15.Cu")
		(net "P5E_CPU1_P0_RX_DN<9>")
	)
	(segment
		(start 106.559604 -362.205524)
		(end 106.745786 -362.092494)
		(width 0.14224)
		(layer "In15.Cu")
		(net "P5E_CPU1_P0_RX_DN<9>")
	)
	(segment
		(start 105.68813 -275.218906)
		(end 105.71861 -275.201126)
		(width 0.1143)
		(layer "In15.Cu")
		(net "P5E_CPU1_P0_RX_DN<9>")
	)
	(segment
		(start 58.945018 -385.404868)
		(end 59.066684 -385.334764)
		(width 0.14224)
		(layer "In15.Cu")
		(net "P5E_CPU1_P0_RX_DN<9>")
	)
	(segment
		(start 129.8575 -361.944158)
		(end 129.99974 -361.801918)
		(width 0.14224)
		(layer "In15.Cu")
		(net "P5E_CPU1_P0_RX_DN<9>")
	)
	(segment
		(start 106.808778 -271.726152)
		(end 106.738928 -271.656302)
		(width 0.1143)
		(layer "In15.Cu")
		(net "P5E_CPU1_P0_RX_DN<9>")
	)
	(segment
		(start 104.97185 -301.421292)
		(end 104.97185 -296.37482)
		(width 0.14224)
		(layer "In15.Cu")
		(net "P5E_CPU1_P0_RX_DN<9>")
	)
	(segment
		(start 105.68813 -294.013636)
		(end 105.649014 -293.990776)
		(width 0.1143)
		(layer "In15.Cu")
		(net "P5E_CPU1_P0_RX_DN<9>")
	)
	(segment
		(start 131.35737 -345.77782)
		(end 117.782594 -332.203044)
		(width 0.14224)
		(layer "In15.Cu")
		(net "P5E_CPU1_P0_RX_DN<9>")
	)
	(segment
		(start 145.4023 -359.531158)
		(end 145.53946 -359.668318)
		(width 0.14224)
		(layer "In15.Cu")
		(net "P5E_CPU1_P0_RX_DN<9>")
	)
	(segment
		(start 75.366372 -362.467144)
		(end 105.624884 -362.467144)
		(width 0.14224)
		(layer "In15.Cu")
		(net "P5E_CPU1_P0_RX_DN<9>")
	)
	(segment
		(start 106.628184 -271.978882)
		(end 106.658664 -271.961102)
		(width 0.1143)
		(layer "In15.Cu")
		(net "P5E_CPU1_P0_RX_DN<9>")
	)
	(segment
		(start 129.99974 -361.801918)
		(end 129.99974 -361.230418)
		(width 0.14224)
		(layer "In15.Cu")
		(net "P5E_CPU1_P0_RX_DN<9>")
	)
	(segment
		(start 105.68813 -286.558736)
		(end 105.720642 -286.53994)
		(width 0.1143)
		(layer "In15.Cu")
		(net "P5E_CPU1_P0_RX_DN<9>")
	)
	(segment
		(start 104.97185 -296.346372)
		(end 105.01757 -296.300652)
		(width 0.1143)
		(layer "In15.Cu")
		(net "P5E_CPU1_P0_RX_DN<9>")
	)
	(segment
		(start 117.870986 -359.975658)
		(end 118.178326 -359.668318)
		(width 0.14224)
		(layer "In15.Cu")
		(net "P5E_CPU1_P0_RX_DN<9>")
	)
	(segment
		(start 105.649014 -293.061644)
		(end 105.68813 -293.038784)
		(width 0.1143)
		(layer "In15.Cu")
		(net "P5E_CPU1_P0_RX_DN<9>")
	)
	(segment
		(start 148.680678 -357.796592)
		(end 148.488908 -357.33355)
		(width 0.14224)
		(layer "In15.Cu")
		(net "P5E_CPU1_P0_RX_DN<9>")
	)
	(segment
		(start 105.68813 -283.318966)
		(end 105.71861 -283.301186)
		(width 0.1143)
		(layer "In15.Cu")
		(net "P5E_CPU1_P0_RX_DN<9>")
	)
	(segment
		(start 59.066684 -385.163822)
		(end 58.749692 -384.84683)
		(width 0.14224)
		(layer "In15.Cu")
		(net "P5E_CPU1_P0_RX_DN<9>")
	)
	(segment
		(start 105.01757 -296.300652)
		(end 105.01757 -295.919652)
		(width 0.1143)
		(layer "In15.Cu")
		(net "P5E_CPU1_P0_RX_DN<9>")
	)
	(segment
		(start 105.68813 -284.293818)
		(end 105.649014 -284.270958)
		(width 0.1143)
		(layer "In15.Cu")
		(net "P5E_CPU1_P0_RX_DN<9>")
	)
	(segment
		(start 105.649014 -294.681656)
		(end 105.71861 -294.641016)
		(width 0.1143)
		(layer "In15.Cu")
		(net "P5E_CPU1_P0_RX_DN<9>")
	)
	(segment
		(start 105.71861 -287.551622)
		(end 105.651554 -287.512506)
		(width 0.1143)
		(layer "In15.Cu")
		(net "P5E_CPU1_P0_RX_DN<9>")
	)
	(segment
		(start 105.71861 -294.031416)
		(end 105.68813 -294.013636)
		(width 0.1143)
		(layer "In15.Cu")
		(net "P5E_CPU1_P0_RX_DN<9>")
	)
	(arc
		(start 105.649014 -293.990776)
		(mid 105.405687 -293.52621)
		(end 105.649014 -293.061644)
		(width 0.1143)
		(layer "In15.Cu")
		(net "P5E_CPU1_P0_RX_DN<9>")
	)
	(arc
		(start 105.34523 -295.46042)
		(mid 105.389907 -295.393791)
		(end 105.405682 -295.315132)
		(width 0.1143)
		(layer "In15.Cu")
		(net "P5E_CPU1_P0_RX_DN<9>")
	)
	(arc
		(start 106.745786 -362.092494)
		(mid 107.000669 -361.982011)
		(end 107.275884 -361.944158)
		(width 0.14224)
		(layer "In15.Cu")
		(net "P5E_CPU1_P0_RX_DN<9>")
	)
	(arc
		(start 105.649014 -274.550886)
		(mid 105.405687 -274.08632)
		(end 105.649014 -273.621754)
		(width 0.1143)
		(layer "In15.Cu")
		(net "P5E_CPU1_P0_RX_DN<9>")
	)
	(arc
		(start 105.71861 -278.44115)
		(mid 105.875587 -278.13635)
		(end 105.71861 -277.83155)
		(width 0.1143)
		(layer "In15.Cu")
		(net "P5E_CPU1_P0_RX_DN<9>")
	)
	(arc
		(start 75.229212 -362.490766)
		(mid 75.296782 -362.473099)
		(end 75.366372 -362.467144)
		(width 0.14224)
		(layer "In15.Cu")
		(net "P5E_CPU1_P0_RX_DN<9>")
	)
	(arc
		(start 148.31949 -359.668318)
		(mid 148.368174 -359.658616)
		(end 148.409406 -359.63098)
		(width 0.14224)
		(layer "In15.Cu")
		(net "P5E_CPU1_P0_RX_DN<9>")
	)
	(arc
		(start 105.405682 -287.046162)
		(mid 105.470197 -286.783943)
		(end 105.649014 -286.581596)
		(width 0.1143)
		(layer "In15.Cu")
		(net "P5E_CPU1_P0_RX_DN<9>")
	)
	(arc
		(start 105.649014 -282.650946)
		(mid 105.405687 -282.18638)
		(end 105.649014 -281.721814)
		(width 0.1143)
		(layer "In15.Cu")
		(net "P5E_CPU1_P0_RX_DN<9>")
	)
	(arc
		(start 148.488908 -357.33355)
		(mid 148.444477 -357.259463)
		(end 148.38045 -357.20147)
		(width 0.14224)
		(layer "In15.Cu")
		(net "P5E_CPU1_P0_RX_DN<9>")
	)
	(arc
		(start 105.649014 -281.030934)
		(mid 105.405687 -280.566368)
		(end 105.649014 -280.101802)
		(width 0.1143)
		(layer "In15.Cu")
		(net "P5E_CPU1_P0_RX_DN<9>")
	)
	(arc
		(start 105.649014 -279.410922)
		(mid 105.405687 -278.946356)
		(end 105.649014 -278.48179)
		(width 0.1143)
		(layer "In15.Cu")
		(net "P5E_CPU1_P0_RX_DN<9>")
	)
	(arc
		(start 105.71861 -284.921198)
		(mid 105.875587 -284.616398)
		(end 105.71861 -284.311598)
		(width 0.1143)
		(layer "In15.Cu")
		(net "P5E_CPU1_P0_RX_DN<9>")
	)
	(arc
		(start 105.71861 -289.78098)
		(mid 105.875587 -289.47618)
		(end 105.71861 -289.17138)
		(width 0.1143)
		(layer "In15.Cu")
		(net "P5E_CPU1_P0_RX_DN<9>")
	)
	(arc
		(start 105.875582 -273.276314)
		(mid 105.940097 -273.014095)
		(end 106.118914 -272.811748)
		(width 0.1143)
		(layer "In15.Cu")
		(net "P5E_CPU1_P0_RX_DN<9>")
	)
	(arc
		(start 105.71861 -281.681174)
		(mid 105.875587 -281.376374)
		(end 105.71861 -281.071574)
		(width 0.1143)
		(layer "In15.Cu")
		(net "P5E_CPU1_P0_RX_DN<9>")
	)
	(arc
		(start 106.18978 -272.7706)
		(mid 106.304456 -272.637266)
		(end 106.345736 -272.466308)
		(width 0.1143)
		(layer "In15.Cu")
		(net "P5E_CPU1_P0_RX_DN<9>")
	)
	(arc
		(start 106.658664 -271.961102)
		(mid 106.756429 -271.858126)
		(end 106.808778 -271.726152)
		(width 0.1143)
		(layer "In15.Cu")
		(net "P5E_CPU1_P0_RX_DN<9>")
	)
	(arc
		(start 105.71861 -293.021004)
		(mid 105.875587 -292.716204)
		(end 105.71861 -292.411404)
		(width 0.1143)
		(layer "In15.Cu")
		(net "P5E_CPU1_P0_RX_DN<9>")
	)
	(arc
		(start 105.649014 -290.750752)
		(mid 105.405687 -290.286186)
		(end 105.649014 -289.82162)
		(width 0.1143)
		(layer "In15.Cu")
		(net "P5E_CPU1_P0_RX_DN<9>")
	)
	(arc
		(start 105.624884 -362.467144)
		(mid 106.11021 -362.400514)
		(end 106.559604 -362.205524)
		(width 0.14224)
		(layer "In15.Cu")
		(net "P5E_CPU1_P0_RX_DN<9>")
	)
	(arc
		(start 105.405682 -295.146222)
		(mid 105.470197 -294.884003)
		(end 105.649014 -294.681656)
		(width 0.1143)
		(layer "In15.Cu")
		(net "P5E_CPU1_P0_RX_DN<9>")
	)
	(arc
		(start 105.875582 -286.23641)
		(mid 105.834033 -286.064988)
		(end 105.71861 -285.93161)
		(width 0.1143)
		(layer "In15.Cu")
		(net "P5E_CPU1_P0_RX_DN<9>")
	)
	(arc
		(start 106.345736 -272.466308)
		(mid 106.410251 -272.204089)
		(end 106.589068 -272.001742)
		(width 0.1143)
		(layer "In15.Cu")
		(net "P5E_CPU1_P0_RX_DN<9>")
	)
	(arc
		(start 131.68249 -346.044774)
		(mid 131.513388 -345.919265)
		(end 131.35737 -345.77782)
		(width 0.14224)
		(layer "In15.Cu")
		(net "P5E_CPU1_P0_RX_DN<9>")
	)
	(arc
		(start 105.649014 -292.370764)
		(mid 105.405687 -291.906198)
		(end 105.649014 -291.441632)
		(width 0.1143)
		(layer "In15.Cu")
		(net "P5E_CPU1_P0_RX_DN<9>")
	)
	(arc
		(start 105.649014 -289.13074)
		(mid 105.405687 -288.666174)
		(end 105.649014 -288.201608)
		(width 0.1143)
		(layer "In15.Cu")
		(net "P5E_CPU1_P0_RX_DN<9>")
	)
	(arc
		(start 105.71861 -294.641016)
		(mid 105.875587 -294.336216)
		(end 105.71861 -294.031416)
		(width 0.1143)
		(layer "In15.Cu")
		(net "P5E_CPU1_P0_RX_DN<9>")
	)
	(arc
		(start 105.649014 -277.79091)
		(mid 105.405687 -277.326344)
		(end 105.649014 -276.861778)
		(width 0.1143)
		(layer "In15.Cu")
		(net "P5E_CPU1_P0_RX_DN<9>")
	)
	(arc
		(start 105.71861 -280.061162)
		(mid 105.875587 -279.756362)
		(end 105.71861 -279.451562)
		(width 0.1143)
		(layer "In15.Cu")
		(net "P5E_CPU1_P0_RX_DN<9>")
	)
	(arc
		(start 63.826136 -366.906048)
		(mid 64.247488 -366.492499)
		(end 64.769238 -366.216184)
		(width 0.14224)
		(layer "In15.Cu")
		(net "P5E_CPU1_P0_RX_DN<9>")
	)
	(arc
		(start 117.782594 -332.203044)
		(mid 117.586887 -331.964575)
		(end 117.441472 -331.692504)
		(width 0.14224)
		(layer "In15.Cu")
		(net "P5E_CPU1_P0_RX_DN<9>")
	)
	(arc
		(start 105.651554 -287.512506)
		(mid 105.470902 -287.309761)
		(end 105.405682 -287.046162)
		(width 0.1143)
		(layer "In15.Cu")
		(net "P5E_CPU1_P0_RX_DN<9>")
	)
	(arc
		(start 105.71861 -283.301186)
		(mid 105.875587 -282.996386)
		(end 105.71861 -282.691586)
		(width 0.1143)
		(layer "In15.Cu")
		(net "P5E_CPU1_P0_RX_DN<9>")
	)
	(arc
		(start 105.720642 -286.53994)
		(mid 105.834571 -286.406793)
		(end 105.875582 -286.23641)
		(width 0.1143)
		(layer "In15.Cu")
		(net "P5E_CPU1_P0_RX_DN<9>")
	)
	(arc
		(start 105.649014 -284.270958)
		(mid 105.405687 -283.806392)
		(end 105.649014 -283.341826)
		(width 0.1143)
		(layer "In15.Cu")
		(net "P5E_CPU1_P0_RX_DN<9>")
	)
	(arc
		(start 105.720642 -288.159952)
		(mid 105.834571 -288.026805)
		(end 105.875582 -287.856422)
		(width 0.1143)
		(layer "In15.Cu")
		(net "P5E_CPU1_P0_RX_DN<9>")
	)
	(arc
		(start 105.71861 -276.821138)
		(mid 105.875587 -276.516338)
		(end 105.71861 -276.211538)
		(width 0.1143)
		(layer "In15.Cu")
		(net "P5E_CPU1_P0_RX_DN<9>")
	)
	(arc
		(start 59.321446 -372.997222)
		(mid 59.433304 -372.724377)
		(end 59.590686 -372.474998)
		(width 0.14224)
		(layer "In15.Cu")
		(net "P5E_CPU1_P0_RX_DN<9>")
	)
	(arc
		(start 105.01757 -295.919652)
		(mid 105.04186 -295.798009)
		(end 105.110788 -295.694862)
		(width 0.1143)
		(layer "In15.Cu")
		(net "P5E_CPU1_P0_RX_DN<9>")
	)
	(arc
		(start 105.034842 -301.739046)
		(mid 104.987703 -301.583272)
		(end 104.97185 -301.421292)
		(width 0.14224)
		(layer "In15.Cu")
		(net "P5E_CPU1_P0_RX_DN<9>")
	)
	(arc
		(start 105.71861 -275.201126)
		(mid 105.875587 -274.896326)
		(end 105.71861 -274.591526)
		(width 0.1143)
		(layer "In15.Cu")
		(net "P5E_CPU1_P0_RX_DN<9>")
	)
	(arc
		(start 148.594064 -359.446322)
		(mid 148.665288 -359.339822)
		(end 148.69033 -359.214166)
		(width 0.14224)
		(layer "In15.Cu")
		(net "P5E_CPU1_P0_RX_DN<9>")
	)
	(arc
		(start 105.649014 -285.89097)
		(mid 105.405687 -285.426404)
		(end 105.649014 -284.961838)
		(width 0.1143)
		(layer "In15.Cu")
		(net "P5E_CPU1_P0_RX_DN<9>")
	)
	(arc
		(start 105.875582 -287.856422)
		(mid 105.834033 -287.685)
		(end 105.71861 -287.551622)
		(width 0.1143)
		(layer "In15.Cu")
		(net "P5E_CPU1_P0_RX_DN<9>")
	)
	(arc
		(start 105.71861 -273.581114)
		(mid 105.834037 -273.447738)
		(end 105.875582 -273.276314)
		(width 0.1143)
		(layer "In15.Cu")
		(net "P5E_CPU1_P0_RX_DN<9>")
	)
	(arc
		(start 148.69033 -357.84536)
		(mid 148.687884 -357.820507)
		(end 148.680678 -357.796592)
		(width 0.14224)
		(layer "In15.Cu")
		(net "P5E_CPU1_P0_RX_DN<9>")
	)
	(arc
		(start 105.649014 -276.170898)
		(mid 105.405687 -275.706332)
		(end 105.649014 -275.241766)
		(width 0.1143)
		(layer "In15.Cu")
		(net "P5E_CPU1_P0_RX_DN<9>")
	)
	(arc
		(start 105.71861 -291.400992)
		(mid 105.875587 -291.096192)
		(end 105.71861 -290.791392)
		(width 0.1143)
		(layer "In15.Cu")
		(net "P5E_CPU1_P0_RX_DN<9>")
	)
	(segment
		(start 104.08793 -269.770352)
		(end 103.621078 -270.03629)
		(width 0.12954)
		(layer "F.Cu")
		(net "P5E_CPU1_P0_RX_DN<8>")
	)
	(segment
		(start 56.8706 -385.31038)
		(end 57.3913 -385.31038)
		(width 0.127)
		(layer "F.Cu")
		(net "P5E_CPU1_P0_RX_DN<8>")
	)
	(segment
		(start 104.745282 -282.672028)
		(end 104.709214 -282.6512)
		(width 0.1143)
		(layer "In15.Cu")
		(net "P5E_CPU1_P0_RX_DN<8>")
	)
	(segment
		(start 104.75214 -294.65651)
		(end 104.75468 -294.65524)
		(width 0.1143)
		(layer "In15.Cu")
		(net "P5E_CPU1_P0_RX_DN<8>")
	)
	(segment
		(start 104.754172 -282.677362)
		(end 104.752648 -282.676346)
		(width 0.1143)
		(layer "In15.Cu")
		(net "P5E_CPU1_P0_RX_DN<8>")
	)
	(segment
		(start 104.769158 -293.026592)
		(end 104.76992 -293.026084)
		(width 0.1143)
		(layer "In15.Cu")
		(net "P5E_CPU1_P0_RX_DN<8>")
	)
	(segment
		(start 104.699562 -272.924016)
		(end 104.698546 -272.923254)
		(width 0.1143)
		(layer "In15.Cu")
		(net "P5E_CPU1_P0_RX_DN<8>")
	)
	(segment
		(start 104.750108 -274.575016)
		(end 104.748838 -274.574254)
		(width 0.1143)
		(layer "In15.Cu")
		(net "P5E_CPU1_P0_RX_DN<8>")
	)
	(segment
		(start 104.747822 -294.65905)
		(end 104.748584 -294.658542)
		(width 0.1143)
		(layer "In15.Cu")
		(net "P5E_CPU1_P0_RX_DN<8>")
	)
	(segment
		(start 57.744614 -385.405376)
		(end 57.745122 -385.404868)
		(width 0.14224)
		(layer "In15.Cu")
		(net "P5E_CPU1_P0_RX_DN<8>")
	)
	(segment
		(start 104.752394 -290.776152)
		(end 104.751632 -290.775644)
		(width 0.1143)
		(layer "In15.Cu")
		(net "P5E_CPU1_P0_RX_DN<8>")
	)
	(segment
		(start 106.184192 -361.134152)
		(end 106.490008 -361.009184)
		(width 0.14224)
		(layer "In15.Cu")
		(net "P5E_CPU1_P0_RX_DN<8>")
	)
	(segment
		(start 58.752486 -371.974872)
		(end 63.38189 -365.89081)
		(width 0.14224)
		(layer "In15.Cu")
		(net "P5E_CPU1_P0_RX_DN<8>")
	)
	(segment
		(start 104.779826 -289.171888)
		(end 104.735122 -289.14598)
		(width 0.1143)
		(layer "In15.Cu")
		(net "P5E_CPU1_P0_RX_DN<8>")
	)
	(segment
		(start 104.748076 -294.013636)
		(end 104.747822 -294.013636)
		(width 0.1143)
		(layer "In15.Cu")
		(net "P5E_CPU1_P0_RX_DN<8>")
	)
	(segment
		(start 104.750362 -275.217636)
		(end 104.751378 -275.217128)
		(width 0.1143)
		(layer "In15.Cu")
		(net "P5E_CPU1_P0_RX_DN<8>")
	)
	(segment
		(start 104.756712 -271.974056)
		(end 104.779826 -271.960594)
		(width 0.1143)
		(layer "In15.Cu")
		(net "P5E_CPU1_P0_RX_DN<8>")
	)
	(segment
		(start 104.750108 -282.675076)
		(end 104.748838 -282.674314)
		(width 0.1143)
		(layer "In15.Cu")
		(net "P5E_CPU1_P0_RX_DN<8>")
	)
	(segment
		(start 104.698546 -272.923254)
		(end 104.697022 -272.922238)
		(width 0.1143)
		(layer "In15.Cu")
		(net "P5E_CPU1_P0_RX_DN<8>")
	)
	(segment
		(start 104.748076 -284.938978)
		(end 104.779826 -284.92069)
		(width 0.1143)
		(layer "In15.Cu")
		(net "P5E_CPU1_P0_RX_DN<8>")
	)
	(segment
		(start 104.779826 -290.7919)
		(end 104.756204 -290.778184)
		(width 0.1143)
		(layer "In15.Cu")
		(net "P5E_CPU1_P0_RX_DN<8>")
	)
	(segment
		(start 104.755696 -281.694636)
		(end 104.756712 -281.694128)
		(width 0.1143)
		(layer "In15.Cu")
		(net "P5E_CPU1_P0_RX_DN<8>")
	)
	(segment
		(start 104.75214 -271.976596)
		(end 104.753156 -271.976088)
		(width 0.1143)
		(layer "In15.Cu")
		(net "P5E_CPU1_P0_RX_DN<8>")
	)
	(segment
		(start 138.11504 -358.558592)
		(end 138.2522 -358.695752)
		(width 0.14224)
		(layer "In15.Cu")
		(net "P5E_CPU1_P0_RX_DN<8>")
	)
	(segment
		(start 104.468676 -287.090612)
		(end 104.468676 -286.990028)
		(width 0.1143)
		(layer "In15.Cu")
		(net "P5E_CPU1_P0_RX_DN<8>")
	)
	(segment
		(start 104.749854 -292.39464)
		(end 104.748838 -292.394132)
		(width 0.1143)
		(layer "In15.Cu")
		(net "P5E_CPU1_P0_RX_DN<8>")
	)
	(segment
		(start 104.745282 -279.432004)
		(end 104.709214 -279.411176)
		(width 0.1143)
		(layer "In15.Cu")
		(net "P5E_CPU1_P0_RX_DN<8>")
	)
	(segment
		(start 137.55116 -358.695752)
		(end 137.68832 -358.558592)
		(width 0.14224)
		(layer "In15.Cu")
		(net "P5E_CPU1_P0_RX_DN<8>")
	)
	(segment
		(start 104.709214 -279.411176)
		(end 104.681274 -279.39111)
		(width 0.1143)
		(layer "In15.Cu")
		(net "P5E_CPU1_P0_RX_DN<8>")
	)
	(segment
		(start 104.681274 -275.261578)
		(end 104.709214 -275.241512)
		(width 0.1143)
		(layer "In15.Cu")
		(net "P5E_CPU1_P0_RX_DN<8>")
	)
	(segment
		(start 104.679496 -272.022062)
		(end 104.704134 -272.004282)
		(width 0.1143)
		(layer "In15.Cu")
		(net "P5E_CPU1_P0_RX_DN<8>")
	)
	(segment
		(start 104.748076 -277.81377)
		(end 104.745282 -277.811992)
		(width 0.1143)
		(layer "In15.Cu")
		(net "P5E_CPU1_P0_RX_DN<8>")
	)
	(segment
		(start 104.751378 -278.457152)
		(end 104.75214 -278.456644)
		(width 0.1143)
		(layer "In15.Cu")
		(net "P5E_CPU1_P0_RX_DN<8>")
	)
	(segment
		(start 135.84428 -358.558592)
		(end 136.271 -358.558592)
		(width 0.14224)
		(layer "In15.Cu")
		(net "P5E_CPU1_P0_RX_DN<8>")
	)
	(segment
		(start 104.748076 -274.573746)
		(end 104.711754 -274.552664)
		(width 0.1143)
		(layer "In15.Cu")
		(net "P5E_CPU1_P0_RX_DN<8>")
	)
	(segment
		(start 104.745282 -284.29204)
		(end 104.709214 -284.271212)
		(width 0.1143)
		(layer "In15.Cu")
		(net "P5E_CPU1_P0_RX_DN<8>")
	)
	(segment
		(start 104.748838 -284.294326)
		(end 104.748076 -284.293818)
		(width 0.1143)
		(layer "In15.Cu")
		(net "P5E_CPU1_P0_RX_DN<8>")
	)
	(segment
		(start 104.7496 -281.698192)
		(end 104.750362 -281.697684)
		(width 0.1143)
		(layer "In15.Cu")
		(net "P5E_CPU1_P0_RX_DN<8>")
	)
	(segment
		(start 116.78031 -360.829352)
		(end 116.78031 -360.257852)
		(width 0.14224)
		(layer "In15.Cu")
		(net "P5E_CPU1_P0_RX_DN<8>")
	)
	(segment
		(start 104.750108 -277.81504)
		(end 104.748838 -277.814278)
		(width 0.1143)
		(layer "In15.Cu")
		(net "P5E_CPU1_P0_RX_DN<8>")
	)
	(segment
		(start 104.711754 -286.579818)
		(end 104.781604 -286.539178)
		(width 0.1143)
		(layer "In15.Cu")
		(net "P5E_CPU1_P0_RX_DN<8>")
	)
	(segment
		(start 104.756204 -290.778184)
		(end 104.754172 -290.777168)
		(width 0.1143)
		(layer "In15.Cu")
		(net "P5E_CPU1_P0_RX_DN<8>")
	)
	(segment
		(start 104.753156 -276.836124)
		(end 104.753918 -276.835616)
		(width 0.1143)
		(layer "In15.Cu")
		(net "P5E_CPU1_P0_RX_DN<8>")
	)
	(segment
		(start 104.709214 -278.481536)
		(end 104.7496 -278.458168)
		(width 0.1143)
		(layer "In15.Cu")
		(net "P5E_CPU1_P0_RX_DN<8>")
	)
	(segment
		(start 104.709214 -282.6512)
		(end 104.681274 -282.631134)
		(width 0.1143)
		(layer "In15.Cu")
		(net "P5E_CPU1_P0_RX_DN<8>")
	)
	(segment
		(start 136.40816 -358.695752)
		(end 137.55116 -358.695752)
		(width 0.14224)
		(layer "In15.Cu")
		(net "P5E_CPU1_P0_RX_DN<8>")
	)
	(segment
		(start 104.754172 -272.95729)
		(end 104.752648 -272.956274)
		(width 0.1143)
		(layer "In15.Cu")
		(net "P5E_CPU1_P0_RX_DN<8>")
	)
	(segment
		(start 104.750362 -283.317696)
		(end 104.751378 -283.317188)
		(width 0.1143)
		(layer "In15.Cu")
		(net "P5E_CPU1_P0_RX_DN<8>")
	)
	(segment
		(start 135.70712 -358.695752)
		(end 135.84428 -358.558592)
		(width 0.14224)
		(layer "In15.Cu")
		(net "P5E_CPU1_P0_RX_DN<8>")
	)
	(segment
		(start 104.748076 -281.05354)
		(end 104.708452 -281.030934)
		(width 0.1143)
		(layer "In15.Cu")
		(net "P5E_CPU1_P0_RX_DN<8>")
	)
	(segment
		(start 104.779826 -276.212046)
		(end 104.754172 -276.197314)
		(width 0.1143)
		(layer "In15.Cu")
		(net "P5E_CPU1_P0_RX_DN<8>")
	)
	(segment
		(start 137.68832 -358.558592)
		(end 138.11504 -358.558592)
		(width 0.14224)
		(layer "In15.Cu")
		(net "P5E_CPU1_P0_RX_DN<8>")
	)
	(segment
		(start 103.91902 -270.03629)
		(end 103.621078 -270.03629)
		(width 0.1143)
		(layer "In15.Cu")
		(net "P5E_CPU1_P0_RX_DN<8>")
	)
	(segment
		(start 104.748838 -274.574254)
		(end 104.748076 -274.573746)
		(width 0.1143)
		(layer "In15.Cu")
		(net "P5E_CPU1_P0_RX_DN<8>")
	)
	(segment
		(start 104.751378 -294.657018)
		(end 104.75214 -294.65651)
		(width 0.1143)
		(layer "In15.Cu")
		(net "P5E_CPU1_P0_RX_DN<8>")
	)
	(segment
		(start 104.756712 -281.694128)
		(end 104.779826 -281.680666)
		(width 0.1143)
		(layer "In15.Cu")
		(net "P5E_CPU1_P0_RX_DN<8>")
	)
	(segment
		(start 104.750616 -290.775136)
		(end 104.749854 -290.774628)
		(width 0.1143)
		(layer "In15.Cu")
		(net "P5E_CPU1_P0_RX_DN<8>")
	)
	(segment
		(start 104.748076 -271.333722)
		(end 104.74706 -271.333214)
		(width 0.1143)
		(layer "In15.Cu")
		(net "P5E_CPU1_P0_RX_DN<8>")
	)
	(segment
		(start 104.681528 -280.12136)
		(end 104.708452 -280.101802)
		(width 0.1143)
		(layer "In15.Cu")
		(net "P5E_CPU1_P0_RX_DN<8>")
	)
	(segment
		(start 57.65038 -374.940068)
		(end 58.305192 -372.84152)
		(width 0.14224)
		(layer "In15.Cu")
		(net "P5E_CPU1_P0_RX_DN<8>")
	)
	(segment
		(start 104.709214 -275.241512)
		(end 104.7496 -275.218144)
		(width 0.1143)
		(layer "In15.Cu")
		(net "P5E_CPU1_P0_RX_DN<8>")
	)
	(segment
		(start 104.001824 -270.119094)
		(end 103.91902 -270.03629)
		(width 0.1143)
		(layer "In15.Cu")
		(net "P5E_CPU1_P0_RX_DN<8>")
	)
	(segment
		(start 104.748838 -277.814278)
		(end 104.748076 -277.81377)
		(width 0.1143)
		(layer "In15.Cu")
		(net "P5E_CPU1_P0_RX_DN<8>")
	)
	(segment
		(start 104.779826 -281.072082)
		(end 104.748076 -281.053794)
		(width 0.1143)
		(layer "In15.Cu")
		(net "P5E_CPU1_P0_RX_DN<8>")
	)
	(segment
		(start 104.75341 -290.77666)
		(end 104.752394 -290.776152)
		(width 0.1143)
		(layer "In15.Cu")
		(net "P5E_CPU1_P0_RX_DN<8>")
	)
	(segment
		(start 104.75341 -292.396672)
		(end 104.752394 -292.396164)
		(width 0.1143)
		(layer "In15.Cu")
		(net "P5E_CPU1_P0_RX_DN<8>")
	)
	(segment
		(start 104.700324 -272.924524)
		(end 104.699562 -272.924016)
		(width 0.1143)
		(layer "In15.Cu")
		(net "P5E_CPU1_P0_RX_DN<8>")
	)
	(segment
		(start 104.76992 -291.406072)
		(end 104.779826 -291.400484)
		(width 0.1143)
		(layer "In15.Cu")
		(net "P5E_CPU1_P0_RX_DN<8>")
	)
	(segment
		(start 142.46606 -358.27335)
		(end 142.46606 -354.713032)
		(width 0.14224)
		(layer "In15.Cu")
		(net "P5E_CPU1_P0_RX_DN<8>")
	)
	(segment
		(start 104.754934 -278.45512)
		(end 104.755696 -278.454612)
		(width 0.1143)
		(layer "In15.Cu")
		(net "P5E_CPU1_P0_RX_DN<8>")
	)
	(segment
		(start 104.779826 -282.692094)
		(end 104.754172 -282.677362)
		(width 0.1143)
		(layer "In15.Cu")
		(net "P5E_CPU1_P0_RX_DN<8>")
	)
	(segment
		(start 104.7496 -294.658034)
		(end 104.750362 -294.657526)
		(width 0.1143)
		(layer "In15.Cu")
		(net "P5E_CPU1_P0_RX_DN<8>")
	)
	(segment
		(start 104.752648 -282.676346)
		(end 104.750108 -282.675076)
		(width 0.1143)
		(layer "In15.Cu")
		(net "P5E_CPU1_P0_RX_DN<8>")
	)
	(segment
		(start 104.748076 -293.038784)
		(end 104.769158 -293.026592)
		(width 0.1143)
		(layer "In15.Cu")
		(net "P5E_CPU1_P0_RX_DN<8>")
	)
	(segment
		(start 104.756712 -283.31414)
		(end 104.779826 -283.300678)
		(width 0.1143)
		(layer "In15.Cu")
		(net "P5E_CPU1_P0_RX_DN<8>")
	)
	(segment
		(start 104.748838 -294.014144)
		(end 104.748076 -294.013636)
		(width 0.1143)
		(layer "In15.Cu")
		(net "P5E_CPU1_P0_RX_DN<8>")
	)
	(segment
		(start 116.63807 -360.971592)
		(end 116.78031 -360.829352)
		(width 0.14224)
		(layer "In15.Cu")
		(net "P5E_CPU1_P0_RX_DN<8>")
	)
	(segment
		(start 104.748838 -271.33423)
		(end 104.748076 -271.333722)
		(width 0.1143)
		(layer "In15.Cu")
		(net "P5E_CPU1_P0_RX_DN<8>")
	)
	(segment
		(start 104.750108 -284.295088)
		(end 104.748838 -284.294326)
		(width 0.1143)
		(layer "In15.Cu")
		(net "P5E_CPU1_P0_RX_DN<8>")
	)
	(segment
		(start 104.753156 -281.69616)
		(end 104.753918 -281.695652)
		(width 0.1143)
		(layer "In15.Cu")
		(net "P5E_CPU1_P0_RX_DN<8>")
	)
	(segment
		(start 104.748838 -276.194266)
		(end 104.748076 -276.193758)
		(width 0.1143)
		(layer "In15.Cu")
		(net "P5E_CPU1_P0_RX_DN<8>")
	)
	(segment
		(start 104.748838 -282.674314)
		(end 104.748076 -282.673806)
		(width 0.1143)
		(layer "In15.Cu")
		(net "P5E_CPU1_P0_RX_DN<8>")
	)
	(segment
		(start 104.74706 -271.333214)
		(end 104.70896 -271.310862)
		(width 0.1143)
		(layer "In15.Cu")
		(net "P5E_CPU1_P0_RX_DN<8>")
	)
	(segment
		(start 104.753918 -276.835616)
		(end 104.779826 -276.82063)
		(width 0.1143)
		(layer "In15.Cu")
		(net "P5E_CPU1_P0_RX_DN<8>")
	)
	(segment
		(start 104.752648 -284.296358)
		(end 104.750108 -284.295088)
		(width 0.1143)
		(layer "In15.Cu")
		(net "P5E_CPU1_P0_RX_DN<8>")
	)
	(segment
		(start 104.75214 -278.456644)
		(end 104.753156 -278.456136)
		(width 0.1143)
		(layer "In15.Cu")
		(net "P5E_CPU1_P0_RX_DN<8>")
	)
	(segment
		(start 107.131612 -360.115612)
		(end 106.824272 -359.808272)
		(width 0.14224)
		(layer "In15.Cu")
		(net "P5E_CPU1_P0_RX_DN<8>")
	)
	(segment
		(start 104.708452 -281.030934)
		(end 104.681528 -281.011376)
		(width 0.1143)
		(layer "In15.Cu")
		(net "P5E_CPU1_P0_RX_DN<8>")
	)
	(segment
		(start 130.518916 -346.318586)
		(end 117.102382 -332.902052)
		(width 0.14224)
		(layer "In15.Cu")
		(net "P5E_CPU1_P0_RX_DN<8>")
	)
	(segment
		(start 104.779826 -272.972022)
		(end 104.754172 -272.95729)
		(width 0.1143)
		(layer "In15.Cu")
		(net "P5E_CPU1_P0_RX_DN<8>")
	)
	(segment
		(start 104.748838 -272.954242)
		(end 104.748076 -272.953734)
		(width 0.1143)
		(layer "In15.Cu")
		(net "P5E_CPU1_P0_RX_DN<8>")
	)
	(segment
		(start 104.750362 -276.837648)
		(end 104.751378 -276.83714)
		(width 0.1143)
		(layer "In15.Cu")
		(net "P5E_CPU1_P0_RX_DN<8>")
	)
	(segment
		(start 104.755696 -278.454612)
		(end 104.756712 -278.454104)
		(width 0.1143)
		(layer "In15.Cu")
		(net "P5E_CPU1_P0_RX_DN<8>")
	)
	(segment
		(start 104.7496 -275.218144)
		(end 104.750362 -275.217636)
		(width 0.1143)
		(layer "In15.Cu")
		(net "P5E_CPU1_P0_RX_DN<8>")
	)
	(segment
		(start 104.751632 -294.015668)
		(end 104.750616 -294.01516)
		(width 0.1143)
		(layer "In15.Cu")
		(net "P5E_CPU1_P0_RX_DN<8>")
	)
	(segment
		(start 104.681274 -276.88159)
		(end 104.709214 -276.861524)
		(width 0.1143)
		(layer "In15.Cu")
		(net "P5E_CPU1_P0_RX_DN<8>")
	)
	(segment
		(start 104.754172 -290.777168)
		(end 104.75341 -290.77666)
		(width 0.1143)
		(layer "In15.Cu")
		(net "P5E_CPU1_P0_RX_DN<8>")
	)
	(segment
		(start 104.754934 -271.975072)
		(end 104.755696 -271.974564)
		(width 0.1143)
		(layer "In15.Cu")
		(net "P5E_CPU1_P0_RX_DN<8>")
	)
	(segment
		(start 104.752648 -285.91637)
		(end 104.750108 -285.9151)
		(width 0.1143)
		(layer "In15.Cu")
		(net "P5E_CPU1_P0_RX_DN<8>")
	)
	(segment
		(start 104.751378 -276.83714)
		(end 104.75214 -276.836632)
		(width 0.1143)
		(layer "In15.Cu")
		(net "P5E_CPU1_P0_RX_DN<8>")
	)
	(segment
		(start 104.779826 -292.411912)
		(end 104.756712 -292.398704)
		(width 0.1143)
		(layer "In15.Cu")
		(net "P5E_CPU1_P0_RX_DN<8>")
	)
	(segment
		(start 104.751378 -271.977104)
		(end 104.75214 -271.976596)
		(width 0.1143)
		(layer "In15.Cu")
		(net "P5E_CPU1_P0_RX_DN<8>")
	)
	(segment
		(start 104.752394 -292.396164)
		(end 104.751632 -292.395656)
		(width 0.1143)
		(layer "In15.Cu")
		(net "P5E_CPU1_P0_RX_DN<8>")
	)
	(segment
		(start 104.748076 -288.178748)
		(end 104.781604 -288.15919)
		(width 0.1143)
		(layer "In15.Cu")
		(net "P5E_CPU1_P0_RX_DN<8>")
	)
	(segment
		(start 104.75214 -281.696668)
		(end 104.753156 -281.69616)
		(width 0.1143)
		(layer "In15.Cu")
		(net "P5E_CPU1_P0_RX_DN<8>")
	)
	(segment
		(start 104.750616 -294.01516)
		(end 104.749854 -294.014652)
		(width 0.1143)
		(layer "In15.Cu")
		(net "P5E_CPU1_P0_RX_DN<8>")
	)
	(segment
		(start 104.709214 -276.171152)
		(end 104.681274 -276.151086)
		(width 0.1143)
		(layer "In15.Cu")
		(net "P5E_CPU1_P0_RX_DN<8>")
	)
	(segment
		(start 104.779826 -294.031924)
		(end 104.757474 -294.01897)
		(width 0.1143)
		(layer "In15.Cu")
		(net "P5E_CPU1_P0_RX_DN<8>")
	)
	(segment
		(start 104.754172 -284.297374)
		(end 104.752648 -284.296358)
		(width 0.1143)
		(layer "In15.Cu")
		(net "P5E_CPU1_P0_RX_DN<8>")
	)
	(segment
		(start 104.75214 -276.836632)
		(end 104.753156 -276.836124)
		(width 0.1143)
		(layer "In15.Cu")
		(net "P5E_CPU1_P0_RX_DN<8>")
	)
	(segment
		(start 104.779826 -277.832058)
		(end 104.754172 -277.817326)
		(width 0.1143)
		(layer "In15.Cu")
		(net "P5E_CPU1_P0_RX_DN<8>")
	)
	(segment
		(start 104.755442 -275.214842)
		(end 104.779826 -275.200618)
		(width 0.1143)
		(layer "In15.Cu")
		(net "P5E_CPU1_P0_RX_DN<8>")
	)
	(segment
		(start 104.75341 -294.016684)
		(end 104.752394 -294.016176)
		(width 0.1143)
		(layer "In15.Cu")
		(net "P5E_CPU1_P0_RX_DN<8>")
	)
	(segment
		(start 104.754172 -292.39718)
		(end 104.75341 -292.396672)
		(width 0.1143)
		(layer "In15.Cu")
		(net "P5E_CPU1_P0_RX_DN<8>")
	)
	(segment
		(start 104.709214 -276.861524)
		(end 104.7496 -276.838156)
		(width 0.1143)
		(layer "In15.Cu")
		(net "P5E_CPU1_P0_RX_DN<8>")
	)
	(segment
		(start 104.75468 -275.21535)
		(end 104.755442 -275.214842)
		(width 0.1143)
		(layer "In15.Cu")
		(net "P5E_CPU1_P0_RX_DN<8>")
	)
	(segment
		(start 142.190978 -354.198174)
		(end 131.01701 -346.727272)
		(width 0.14224)
		(layer "In15.Cu")
		(net "P5E_CPU1_P0_RX_DN<8>")
	)
	(segment
		(start 104.026716 -296.37482)
		(end 104.026716 -296.346372)
		(width 0.1143)
		(layer "In15.Cu")
		(net "P5E_CPU1_P0_RX_DN<8>")
	)
	(segment
		(start 104.754172 -276.197314)
		(end 104.752648 -276.196298)
		(width 0.1143)
		(layer "In15.Cu")
		(net "P5E_CPU1_P0_RX_DN<8>")
	)
	(segment
		(start 104.747822 -293.039038)
		(end 104.748076 -293.038784)
		(width 0.1143)
		(layer "In15.Cu")
		(net "P5E_CPU1_P0_RX_DN<8>")
	)
	(segment
		(start 104.779826 -279.45207)
		(end 104.754172 -279.437338)
		(width 0.1143)
		(layer "In15.Cu")
		(net "P5E_CPU1_P0_RX_DN<8>")
	)
	(segment
		(start 104.745282 -272.951956)
		(end 104.709214 -272.931128)
		(width 0.1143)
		(layer "In15.Cu")
		(net "P5E_CPU1_P0_RX_DN<8>")
	)
	(segment
		(start 140.02766 -358.695752)
		(end 142.043658 -358.695752)
		(width 0.14224)
		(layer "In15.Cu")
		(net "P5E_CPU1_P0_RX_DN<8>")
	)
	(segment
		(start 104.75214 -283.31668)
		(end 104.753156 -283.316172)
		(width 0.1143)
		(layer "In15.Cu")
		(net "P5E_CPU1_P0_RX_DN<8>")
	)
	(segment
		(start 104.709214 -284.271212)
		(end 104.681274 -284.251146)
		(width 0.1143)
		(layer "In15.Cu")
		(net "P5E_CPU1_P0_RX_DN<8>")
	)
	(segment
		(start 104.75468 -294.65524)
		(end 104.755442 -294.654732)
		(width 0.1143)
		(layer "In15.Cu")
		(net "P5E_CPU1_P0_RX_DN<8>")
	)
	(segment
		(start 104.697022 -272.922238)
		(end 104.681274 -272.911062)
		(width 0.1143)
		(layer "In15.Cu")
		(net "P5E_CPU1_P0_RX_DN<8>")
	)
	(segment
		(start 104.709214 -277.791164)
		(end 104.681274 -277.771098)
		(width 0.1143)
		(layer "In15.Cu")
		(net "P5E_CPU1_P0_RX_DN<8>")
	)
	(segment
		(start 104.752648 -272.956274)
		(end 104.750108 -272.955004)
		(width 0.1143)
		(layer "In15.Cu")
		(net "P5E_CPU1_P0_RX_DN<8>")
	)
	(segment
		(start 104.748076 -289.79876)
		(end 104.769158 -289.786568)
		(width 0.1143)
		(layer "In15.Cu")
		(net "P5E_CPU1_P0_RX_DN<8>")
	)
	(segment
		(start 106.824272 -359.069894)
		(end 107.198414 -358.695752)
		(width 0.14224)
		(layer "In15.Cu")
		(net "P5E_CPU1_P0_RX_DN<8>")
	)
	(segment
		(start 104.713278 -287.510982)
		(end 104.592628 -287.390078)
		(width 0.1143)
		(layer "In15.Cu")
		(net "P5E_CPU1_P0_RX_DN<8>")
	)
	(segment
		(start 104.748076 -284.293818)
		(end 104.745282 -284.29204)
		(width 0.1143)
		(layer "In15.Cu")
		(net "P5E_CPU1_P0_RX_DN<8>")
	)
	(segment
		(start 104.752648 -279.436322)
		(end 104.750108 -279.435052)
		(width 0.1143)
		(layer "In15.Cu")
		(net "P5E_CPU1_P0_RX_DN<8>")
	)
	(segment
		(start 104.748076 -272.953734)
		(end 104.745282 -272.951956)
		(width 0.1143)
		(layer "In15.Cu")
		(net "P5E_CPU1_P0_RX_DN<8>")
	)
	(segment
		(start 104.750362 -271.977612)
		(end 104.751378 -271.977104)
		(width 0.1143)
		(layer "In15.Cu")
		(net "P5E_CPU1_P0_RX_DN<8>")
	)
	(segment
		(start 104.745282 -277.811992)
		(end 104.709214 -277.791164)
		(width 0.1143)
		(layer "In15.Cu")
		(net "P5E_CPU1_P0_RX_DN<8>")
	)
	(segment
		(start 57.549796 -384.84683)
		(end 57.556908 -383.965958)
		(width 0.14224)
		(layer "In15.Cu")
		(net "P5E_CPU1_P0_RX_DN<8>")
	)
	(segment
		(start 104.754172 -294.017192)
		(end 104.75341 -294.016684)
		(width 0.1143)
		(layer "In15.Cu")
		(net "P5E_CPU1_P0_RX_DN<8>")
	)
	(segment
		(start 104.165654 -295.700196)
		(end 104.408224 -295.457626)
		(width 0.1143)
		(layer "In15.Cu")
		(net "P5E_CPU1_P0_RX_DN<8>")
	)
	(segment
		(start 104.749854 -294.014652)
		(end 104.748838 -294.014144)
		(width 0.1143)
		(layer "In15.Cu")
		(net "P5E_CPU1_P0_RX_DN<8>")
	)
	(segment
		(start 104.755442 -294.654732)
		(end 104.779826 -294.640508)
		(width 0.1143)
		(layer "In15.Cu")
		(net "P5E_CPU1_P0_RX_DN<8>")
	)
	(segment
		(start 116.78031 -360.257852)
		(end 116.63807 -360.115612)
		(width 0.14224)
		(layer "In15.Cu")
		(net "P5E_CPU1_P0_RX_DN<8>")
	)
	(segment
		(start 104.749854 -290.774628)
		(end 104.748838 -290.77412)
		(width 0.1143)
		(layer "In15.Cu")
		(net "P5E_CPU1_P0_RX_DN<8>")
	)
	(segment
		(start 104.779826 -274.592034)
		(end 104.754172 -274.577302)
		(width 0.1143)
		(layer "In15.Cu")
		(net "P5E_CPU1_P0_RX_DN<8>")
	)
	(segment
		(start 57.556908 -383.965958)
		(end 57.85866 -383.664206)
		(width 0.14224)
		(layer "In15.Cu")
		(net "P5E_CPU1_P0_RX_DN<8>")
	)
	(segment
		(start 104.745028 -294.660574)
		(end 104.747822 -294.65905)
		(width 0.1143)
		(layer "In15.Cu")
		(net "P5E_CPU1_P0_RX_DN<8>")
	)
	(segment
		(start 104.779826 -284.312106)
		(end 104.754172 -284.297374)
		(width 0.1143)
		(layer "In15.Cu")
		(net "P5E_CPU1_P0_RX_DN<8>")
	)
	(segment
		(start 104.751378 -275.217128)
		(end 104.75214 -275.21662)
		(width 0.1143)
		(layer "In15.Cu")
		(net "P5E_CPU1_P0_RX_DN<8>")
	)
	(segment
		(start 104.750108 -272.955004)
		(end 104.748838 -272.954242)
		(width 0.1143)
		(layer "In15.Cu")
		(net "P5E_CPU1_P0_RX_DN<8>")
	)
	(segment
		(start 104.748838 -279.43429)
		(end 104.748076 -279.433782)
		(width 0.1143)
		(layer "In15.Cu")
		(net "P5E_CPU1_P0_RX_DN<8>")
	)
	(segment
		(start 104.748584 -294.658542)
		(end 104.7496 -294.658034)
		(width 0.1143)
		(layer "In15.Cu")
		(net "P5E_CPU1_P0_RX_DN<8>")
	)
	(segment
		(start 104.748076 -276.193758)
		(end 104.745282 -276.19198)
		(width 0.1143)
		(layer "In15.Cu")
		(net "P5E_CPU1_P0_RX_DN<8>")
	)
	(segment
		(start 104.701594 -272.92554)
		(end 104.700324 -272.924524)
		(width 0.1143)
		(layer "In15.Cu")
		(net "P5E_CPU1_P0_RX_DN<8>")
	)
	(segment
		(start 139.8905 -358.558592)
		(end 140.02766 -358.695752)
		(width 0.14224)
		(layer "In15.Cu")
		(net "P5E_CPU1_P0_RX_DN<8>")
	)
	(segment
		(start 104.7496 -278.458168)
		(end 104.750362 -278.45766)
		(width 0.1143)
		(layer "In15.Cu")
		(net "P5E_CPU1_P0_RX_DN<8>")
	)
	(segment
		(start 104.026716 -296.346372)
		(end 104.072436 -296.300652)
		(width 0.1143)
		(layer "In15.Cu")
		(net "P5E_CPU1_P0_RX_DN<8>")
	)
	(segment
		(start 104.755188 -294.0177)
		(end 104.754172 -294.017192)
		(width 0.1143)
		(layer "In15.Cu")
		(net "P5E_CPU1_P0_RX_DN<8>")
	)
	(segment
		(start 104.752394 -294.016176)
		(end 104.751632 -294.015668)
		(width 0.1143)
		(layer "In15.Cu")
		(net "P5E_CPU1_P0_RX_DN<8>")
	)
	(segment
		(start 104.76992 -293.026084)
		(end 104.779826 -293.020496)
		(width 0.1143)
		(layer "In15.Cu")
		(net "P5E_CPU1_P0_RX_DN<8>")
	)
	(segment
		(start 104.754172 -277.817326)
		(end 104.752648 -277.81631)
		(width 0.1143)
		(layer "In15.Cu")
		(net "P5E_CPU1_P0_RX_DN<8>")
	)
	(segment
		(start 104.750108 -285.9151)
		(end 104.748838 -285.914338)
		(width 0.1143)
		(layer "In15.Cu")
		(net "P5E_CPU1_P0_RX_DN<8>")
	)
	(segment
		(start 104.756712 -278.454104)
		(end 104.779826 -278.440642)
		(width 0.1143)
		(layer "In15.Cu")
		(net "P5E_CPU1_P0_RX_DN<8>")
	)
	(segment
		(start 104.750362 -294.657526)
		(end 104.751378 -294.657018)
		(width 0.1143)
		(layer "In15.Cu")
		(net "P5E_CPU1_P0_RX_DN<8>")
	)
	(segment
		(start 104.753918 -281.695652)
		(end 104.754934 -281.695144)
		(width 0.1143)
		(layer "In15.Cu")
		(net "P5E_CPU1_P0_RX_DN<8>")
	)
	(segment
		(start 104.748076 -292.393624)
		(end 104.747822 -292.393624)
		(width 0.1143)
		(layer "In15.Cu")
		(net "P5E_CPU1_P0_RX_DN<8>")
	)
	(segment
		(start 104.751632 -292.395656)
		(end 104.750616 -292.395148)
		(width 0.1143)
		(layer "In15.Cu")
		(net "P5E_CPU1_P0_RX_DN<8>")
	)
	(segment
		(start 104.711754 -284.96006)
		(end 104.748076 -284.938978)
		(width 0.1143)
		(layer "In15.Cu")
		(net "P5E_CPU1_P0_RX_DN<8>")
	)
	(segment
		(start 104.748076 -282.673806)
		(end 104.745282 -282.672028)
		(width 0.1143)
		(layer "In15.Cu")
		(net "P5E_CPU1_P0_RX_DN<8>")
	)
	(segment
		(start 104.753156 -271.976088)
		(end 104.753918 -271.97558)
		(width 0.1143)
		(layer "In15.Cu")
		(net "P5E_CPU1_P0_RX_DN<8>")
	)
	(segment
		(start 104.755696 -283.314648)
		(end 104.756712 -283.31414)
		(width 0.1143)
		(layer "In15.Cu")
		(net "P5E_CPU1_P0_RX_DN<8>")
	)
	(segment
		(start 104.752648 -274.576286)
		(end 104.750108 -274.575016)
		(width 0.1143)
		(layer "In15.Cu")
		(net "P5E_CPU1_P0_RX_DN<8>")
	)
	(segment
		(start 104.681274 -281.741626)
		(end 104.709214 -281.72156)
		(width 0.1143)
		(layer "In15.Cu")
		(net "P5E_CPU1_P0_RX_DN<8>")
	)
	(segment
		(start 104.704134 -272.004282)
		(end 104.7496 -271.97812)
		(width 0.1143)
		(layer "In15.Cu")
		(net "P5E_CPU1_P0_RX_DN<8>")
	)
	(segment
		(start 116.574824 -332.11262)
		(end 104.12222 -302.045878)
		(width 0.14224)
		(layer "In15.Cu")
		(net "P5E_CPU1_P0_RX_DN<8>")
	)
	(segment
		(start 104.748076 -287.533842)
		(end 104.713278 -287.510982)
		(width 0.1143)
		(layer "In15.Cu")
		(net "P5E_CPU1_P0_RX_DN<8>")
	)
	(segment
		(start 57.866788 -385.334764)
		(end 57.866788 -385.163822)
		(width 0.14224)
		(layer "In15.Cu")
		(net "P5E_CPU1_P0_RX_DN<8>")
	)
	(segment
		(start 57.85866 -381.471678)
		(end 57.583832 -375.456196)
		(width 0.14224)
		(layer "In15.Cu")
		(net "P5E_CPU1_P0_RX_DN<8>")
	)
	(segment
		(start 104.709214 -283.341572)
		(end 104.7496 -283.318204)
		(width 0.1143)
		(layer "In15.Cu")
		(net "P5E_CPU1_P0_RX_DN<8>")
	)
	(segment
		(start 104.754172 -274.577302)
		(end 104.752648 -274.576286)
		(width 0.1143)
		(layer "In15.Cu")
		(net "P5E_CPU1_P0_RX_DN<8>")
	)
	(segment
		(start 104.754934 -281.695144)
		(end 104.755696 -281.694636)
		(width 0.1143)
		(layer "In15.Cu")
		(net "P5E_CPU1_P0_RX_DN<8>")
	)
	(segment
		(start 104.748076 -285.91383)
		(end 104.711754 -285.892748)
		(width 0.1143)
		(layer "In15.Cu")
		(net "P5E_CPU1_P0_RX_DN<8>")
	)
	(segment
		(start 104.752648 -276.196298)
		(end 104.750108 -276.195028)
		(width 0.1143)
		(layer "In15.Cu")
		(net "P5E_CPU1_P0_RX_DN<8>")
	)
	(segment
		(start 138.2522 -358.695752)
		(end 139.32662 -358.695752)
		(width 0.14224)
		(layer "In15.Cu")
		(net "P5E_CPU1_P0_RX_DN<8>")
	)
	(segment
		(start 104.747822 -289.799014)
		(end 104.748076 -289.79876)
		(width 0.1143)
		(layer "In15.Cu")
		(net "P5E_CPU1_P0_RX_DN<8>")
	)
	(segment
		(start 106.824272 -359.808272)
		(end 106.824272 -359.069894)
		(width 0.14224)
		(layer "In15.Cu")
		(net "P5E_CPU1_P0_RX_DN<8>")
	)
	(segment
		(start 104.75214 -275.21662)
		(end 104.75468 -275.21535)
		(width 0.1143)
		(layer "In15.Cu")
		(net "P5E_CPU1_P0_RX_DN<8>")
	)
	(segment
		(start 104.278176 -270.523716)
		(end 104.23906 -270.500856)
		(width 0.1143)
		(layer "In15.Cu")
		(net "P5E_CPU1_P0_RX_DN<8>")
	)
	(segment
		(start 104.681274 -278.501602)
		(end 104.709214 -278.481536)
		(width 0.1143)
		(layer "In15.Cu")
		(net "P5E_CPU1_P0_RX_DN<8>")
	)
	(segment
		(start 104.754172 -279.437338)
		(end 104.752648 -279.436322)
		(width 0.1143)
		(layer "In15.Cu")
		(net "P5E_CPU1_P0_RX_DN<8>")
	)
	(segment
		(start 63.93688 -365.484664)
		(end 74.74585 -361.635548)
		(width 0.14224)
		(layer "In15.Cu")
		(net "P5E_CPU1_P0_RX_DN<8>")
	)
	(segment
		(start 104.709214 -281.72156)
		(end 104.7496 -281.698192)
		(width 0.1143)
		(layer "In15.Cu")
		(net "P5E_CPU1_P0_RX_DN<8>")
	)
	(segment
		(start 104.072436 -296.300652)
		(end 104.072436 -295.924986)
		(width 0.1143)
		(layer "In15.Cu")
		(net "P5E_CPU1_P0_RX_DN<8>")
	)
	(segment
		(start 104.779826 -271.35201)
		(end 104.748838 -271.33423)
		(width 0.1143)
		(layer "In15.Cu")
		(net "P5E_CPU1_P0_RX_DN<8>")
	)
	(segment
		(start 104.681274 -283.361638)
		(end 104.709214 -283.341572)
		(width 0.1143)
		(layer "In15.Cu")
		(net "P5E_CPU1_P0_RX_DN<8>")
	)
	(segment
		(start 104.747822 -291.419026)
		(end 104.748076 -291.418772)
		(width 0.1143)
		(layer "In15.Cu")
		(net "P5E_CPU1_P0_RX_DN<8>")
	)
	(segment
		(start 104.769158 -289.786568)
		(end 104.76992 -289.78606)
		(width 0.1143)
		(layer "In15.Cu")
		(net "P5E_CPU1_P0_RX_DN<8>")
	)
	(segment
		(start 104.748076 -279.433782)
		(end 104.745282 -279.432004)
		(width 0.1143)
		(layer "In15.Cu")
		(net "P5E_CPU1_P0_RX_DN<8>")
	)
	(segment
		(start 104.755696 -271.974564)
		(end 104.756712 -271.974056)
		(width 0.1143)
		(layer "In15.Cu")
		(net "P5E_CPU1_P0_RX_DN<8>")
	)
	(segment
		(start 104.7496 -283.318204)
		(end 104.750362 -283.317696)
		(width 0.1143)
		(layer "In15.Cu")
		(net "P5E_CPU1_P0_RX_DN<8>")
	)
	(segment
		(start 104.753918 -278.455628)
		(end 104.754934 -278.45512)
		(width 0.1143)
		(layer "In15.Cu")
		(net "P5E_CPU1_P0_RX_DN<8>")
	)
	(segment
		(start 104.748076 -291.418772)
		(end 104.769158 -291.40658)
		(width 0.1143)
		(layer "In15.Cu")
		(net "P5E_CPU1_P0_RX_DN<8>")
	)
	(segment
		(start 104.708452 -280.101802)
		(end 104.779826 -280.060654)
		(width 0.1143)
		(layer "In15.Cu")
		(net "P5E_CPU1_P0_RX_DN<8>")
	)
	(segment
		(start 104.748076 -290.773612)
		(end 104.747822 -290.773612)
		(width 0.1143)
		(layer "In15.Cu")
		(net "P5E_CPU1_P0_RX_DN<8>")
	)
	(segment
		(start 104.7496 -271.97812)
		(end 104.750362 -271.977612)
		(width 0.1143)
		(layer "In15.Cu")
		(net "P5E_CPU1_P0_RX_DN<8>")
	)
	(segment
		(start 57.745122 -385.404868)
		(end 57.866788 -385.334764)
		(width 0.14224)
		(layer "In15.Cu")
		(net "P5E_CPU1_P0_RX_DN<8>")
	)
	(segment
		(start 104.751378 -283.317188)
		(end 104.75214 -283.31668)
		(width 0.1143)
		(layer "In15.Cu")
		(net "P5E_CPU1_P0_RX_DN<8>")
	)
	(segment
		(start 104.769158 -291.40658)
		(end 104.76992 -291.406072)
		(width 0.1143)
		(layer "In15.Cu")
		(net "P5E_CPU1_P0_RX_DN<8>")
	)
	(segment
		(start 104.750108 -279.435052)
		(end 104.748838 -279.43429)
		(width 0.1143)
		(layer "In15.Cu")
		(net "P5E_CPU1_P0_RX_DN<8>")
	)
	(segment
		(start 104.753156 -278.456136)
		(end 104.753918 -278.455628)
		(width 0.1143)
		(layer "In15.Cu")
		(net "P5E_CPU1_P0_RX_DN<8>")
	)
	(segment
		(start 104.748838 -290.77412)
		(end 104.748076 -290.773612)
		(width 0.1143)
		(layer "In15.Cu")
		(net "P5E_CPU1_P0_RX_DN<8>")
	)
	(segment
		(start 104.026716 -301.566072)
		(end 104.026716 -296.37482)
		(width 0.14224)
		(layer "In15.Cu")
		(net "P5E_CPU1_P0_RX_DN<8>")
	)
	(segment
		(start 106.681524 -360.971592)
		(end 116.63807 -360.971592)
		(width 0.14224)
		(layer "In15.Cu")
		(net "P5E_CPU1_P0_RX_DN<8>")
	)
	(segment
		(start 104.779826 -285.932118)
		(end 104.754172 -285.917386)
		(width 0.1143)
		(layer "In15.Cu")
		(net "P5E_CPU1_P0_RX_DN<8>")
	)
	(segment
		(start 104.748076 -281.053794)
		(end 104.748076 -281.05354)
		(width 0.1143)
		(layer "In15.Cu")
		(net "P5E_CPU1_P0_RX_DN<8>")
	)
	(segment
		(start 104.779826 -287.55213)
		(end 104.748076 -287.533842)
		(width 0.1143)
		(layer "In15.Cu")
		(net "P5E_CPU1_P0_RX_DN<8>")
	)
	(segment
		(start 57.3913 -385.31038)
		(end 57.744614 -385.405376)
		(width 0.14224)
		(layer "In15.Cu")
		(net "P5E_CPU1_P0_RX_DN<8>")
	)
	(segment
		(start 104.308656 -270.541496)
		(end 104.278176 -270.523716)
		(width 0.1143)
		(layer "In15.Cu")
		(net "P5E_CPU1_P0_RX_DN<8>")
	)
	(segment
		(start 107.198414 -358.695752)
		(end 135.70712 -358.695752)
		(width 0.14224)
		(layer "In15.Cu")
		(net "P5E_CPU1_P0_RX_DN<8>")
	)
	(segment
		(start 104.748838 -292.394132)
		(end 104.748076 -292.393624)
		(width 0.1143)
		(layer "In15.Cu")
		(net "P5E_CPU1_P0_RX_DN<8>")
	)
	(segment
		(start 104.754934 -283.315156)
		(end 104.755696 -283.314648)
		(width 0.1143)
		(layer "In15.Cu")
		(net "P5E_CPU1_P0_RX_DN<8>")
	)
	(segment
		(start 104.709214 -272.931128)
		(end 104.701594 -272.92554)
		(width 0.1143)
		(layer "In15.Cu")
		(net "P5E_CPU1_P0_RX_DN<8>")
	)
	(segment
		(start 104.711754 -273.619976)
		(end 104.748076 -273.598894)
		(width 0.1143)
		(layer "In15.Cu")
		(net "P5E_CPU1_P0_RX_DN<8>")
	)
	(segment
		(start 139.46378 -358.558592)
		(end 139.8905 -358.558592)
		(width 0.14224)
		(layer "In15.Cu")
		(net "P5E_CPU1_P0_RX_DN<8>")
	)
	(segment
		(start 104.750362 -278.45766)
		(end 104.751378 -278.457152)
		(width 0.1143)
		(layer "In15.Cu")
		(net "P5E_CPU1_P0_RX_DN<8>")
	)
	(segment
		(start 104.753918 -271.97558)
		(end 104.754934 -271.975072)
		(width 0.1143)
		(layer "In15.Cu")
		(net "P5E_CPU1_P0_RX_DN<8>")
	)
	(segment
		(start 104.752648 -277.81631)
		(end 104.750108 -277.81504)
		(width 0.1143)
		(layer "In15.Cu")
		(net "P5E_CPU1_P0_RX_DN<8>")
	)
	(segment
		(start 104.750362 -281.697684)
		(end 104.751378 -281.697176)
		(width 0.1143)
		(layer "In15.Cu")
		(net "P5E_CPU1_P0_RX_DN<8>")
	)
	(segment
		(start 139.32662 -358.695752)
		(end 139.46378 -358.558592)
		(width 0.14224)
		(layer "In15.Cu")
		(net "P5E_CPU1_P0_RX_DN<8>")
	)
	(segment
		(start 104.750616 -292.395148)
		(end 104.749854 -292.39464)
		(width 0.1143)
		(layer "In15.Cu")
		(net "P5E_CPU1_P0_RX_DN<8>")
	)
	(segment
		(start 104.756712 -292.398704)
		(end 104.754172 -292.39718)
		(width 0.1143)
		(layer "In15.Cu")
		(net "P5E_CPU1_P0_RX_DN<8>")
	)
	(segment
		(start 104.745282 -276.19198)
		(end 104.709214 -276.171152)
		(width 0.1143)
		(layer "In15.Cu")
		(net "P5E_CPU1_P0_RX_DN<8>")
	)
	(segment
		(start 104.748076 -273.598894)
		(end 104.779826 -273.580606)
		(width 0.1143)
		(layer "In15.Cu")
		(net "P5E_CPU1_P0_RX_DN<8>")
	)
	(segment
		(start 104.751378 -281.697176)
		(end 104.75214 -281.696668)
		(width 0.1143)
		(layer "In15.Cu")
		(net "P5E_CPU1_P0_RX_DN<8>")
	)
	(segment
		(start 104.754172 -285.917386)
		(end 104.752648 -285.91637)
		(width 0.1143)
		(layer "In15.Cu")
		(net "P5E_CPU1_P0_RX_DN<8>")
	)
	(segment
		(start 136.271 -358.558592)
		(end 136.40816 -358.695752)
		(width 0.14224)
		(layer "In15.Cu")
		(net "P5E_CPU1_P0_RX_DN<8>")
	)
	(segment
		(start 57.85866 -383.664206)
		(end 57.85866 -381.471678)
		(width 0.14224)
		(layer "In15.Cu")
		(net "P5E_CPU1_P0_RX_DN<8>")
	)
	(segment
		(start 104.76992 -289.78606)
		(end 104.779826 -289.780472)
		(width 0.1143)
		(layer "In15.Cu")
		(net "P5E_CPU1_P0_RX_DN<8>")
	)
	(segment
		(start 104.753156 -283.316172)
		(end 104.753918 -283.315664)
		(width 0.1143)
		(layer "In15.Cu")
		(net "P5E_CPU1_P0_RX_DN<8>")
	)
	(segment
		(start 104.757474 -294.01897)
		(end 104.755188 -294.0177)
		(width 0.1143)
		(layer "In15.Cu")
		(net "P5E_CPU1_P0_RX_DN<8>")
	)
	(segment
		(start 104.753918 -283.315664)
		(end 104.754934 -283.315156)
		(width 0.1143)
		(layer "In15.Cu")
		(net "P5E_CPU1_P0_RX_DN<8>")
	)
	(segment
		(start 104.735122 -288.186368)
		(end 104.748076 -288.178748)
		(width 0.1143)
		(layer "In15.Cu")
		(net "P5E_CPU1_P0_RX_DN<8>")
	)
	(segment
		(start 104.750108 -276.195028)
		(end 104.748838 -276.194266)
		(width 0.1143)
		(layer "In15.Cu")
		(net "P5E_CPU1_P0_RX_DN<8>")
	)
	(segment
		(start 75.534266 -361.499404)
		(end 105.3465 -361.499404)
		(width 0.14224)
		(layer "In15.Cu")
		(net "P5E_CPU1_P0_RX_DN<8>")
	)
	(segment
		(start 104.7496 -276.838156)
		(end 104.750362 -276.837648)
		(width 0.1143)
		(layer "In15.Cu")
		(net "P5E_CPU1_P0_RX_DN<8>")
	)
	(segment
		(start 104.748838 -285.914338)
		(end 104.748076 -285.91383)
		(width 0.1143)
		(layer "In15.Cu")
		(net "P5E_CPU1_P0_RX_DN<8>")
	)
	(segment
		(start 116.63807 -360.115612)
		(end 107.131612 -360.115612)
		(width 0.14224)
		(layer "In15.Cu")
		(net "P5E_CPU1_P0_RX_DN<8>")
	)
	(segment
		(start 104.460548 -295.331896)
		(end 104.460548 -295.15181)
		(width 0.1143)
		(layer "In15.Cu")
		(net "P5E_CPU1_P0_RX_DN<8>")
	)
	(segment
		(start 57.866788 -385.163822)
		(end 57.549796 -384.84683)
		(width 0.14224)
		(layer "In15.Cu")
		(net "P5E_CPU1_P0_RX_DN<8>")
	)
	(segment
		(start 104.751632 -290.775644)
		(end 104.750616 -290.775136)
		(width 0.1143)
		(layer "In15.Cu")
		(net "P5E_CPU1_P0_RX_DN<8>")
	)
	(arc
		(start 104.592628 -287.390078)
		(mid 104.500876 -287.252668)
		(end 104.468676 -287.090612)
		(width 0.1143)
		(layer "In15.Cu")
		(net "P5E_CPU1_P0_RX_DN<8>")
	)
	(arc
		(start 104.779826 -278.440642)
		(mid 104.935754 -278.13635)
		(end 104.779826 -277.832058)
		(width 0.1143)
		(layer "In15.Cu")
		(net "P5E_CPU1_P0_RX_DN<8>")
	)
	(arc
		(start 104.681274 -284.251146)
		(mid 104.453274 -283.806392)
		(end 104.681274 -283.361638)
		(width 0.1143)
		(layer "In15.Cu")
		(net "P5E_CPU1_P0_RX_DN<8>")
	)
	(arc
		(start 104.681274 -277.771098)
		(mid 104.453274 -277.326344)
		(end 104.681274 -276.88159)
		(width 0.1143)
		(layer "In15.Cu")
		(net "P5E_CPU1_P0_RX_DN<8>")
	)
	(arc
		(start 104.681274 -276.151086)
		(mid 104.453274 -275.706332)
		(end 104.681274 -275.261578)
		(width 0.1143)
		(layer "In15.Cu")
		(net "P5E_CPU1_P0_RX_DN<8>")
	)
	(arc
		(start 104.681528 -281.011376)
		(mid 104.45385 -280.566368)
		(end 104.681528 -280.12136)
		(width 0.1143)
		(layer "In15.Cu")
		(net "P5E_CPU1_P0_RX_DN<8>")
	)
	(arc
		(start 142.043658 -358.695752)
		(mid 142.342341 -358.572033)
		(end 142.46606 -358.27335)
		(width 0.14224)
		(layer "In15.Cu")
		(net "P5E_CPU1_P0_RX_DN<8>")
	)
	(arc
		(start 104.747822 -294.013636)
		(mid 104.467395 -293.5264)
		(end 104.747822 -293.039038)
		(width 0.1143)
		(layer "In15.Cu")
		(net "P5E_CPU1_P0_RX_DN<8>")
	)
	(arc
		(start 104.408224 -295.457626)
		(mid 104.446905 -295.39997)
		(end 104.460548 -295.331896)
		(width 0.1143)
		(layer "In15.Cu")
		(net "P5E_CPU1_P0_RX_DN<8>")
	)
	(arc
		(start 104.711754 -274.552664)
		(mid 104.70409 -274.547393)
		(end 104.696514 -274.541996)
		(width 0.1143)
		(layer "In15.Cu")
		(net "P5E_CPU1_P0_RX_DN<8>")
	)
	(arc
		(start 104.779826 -289.780472)
		(mid 104.935754 -289.47618)
		(end 104.779826 -289.171888)
		(width 0.1143)
		(layer "In15.Cu")
		(net "P5E_CPU1_P0_RX_DN<8>")
	)
	(arc
		(start 104.747822 -292.393624)
		(mid 104.467395 -291.906388)
		(end 104.747822 -291.419026)
		(width 0.1143)
		(layer "In15.Cu")
		(net "P5E_CPU1_P0_RX_DN<8>")
	)
	(arc
		(start 58.305192 -372.84152)
		(mid 58.491058 -372.388698)
		(end 58.752486 -371.974872)
		(width 0.14224)
		(layer "In15.Cu")
		(net "P5E_CPU1_P0_RX_DN<8>")
	)
	(arc
		(start 104.468676 -286.990028)
		(mid 104.544842 -286.758039)
		(end 104.711754 -286.579818)
		(width 0.1143)
		(layer "In15.Cu")
		(net "P5E_CPU1_P0_RX_DN<8>")
	)
	(arc
		(start 104.935782 -287.856422)
		(mid 104.894527 -287.685451)
		(end 104.779826 -287.55213)
		(width 0.1143)
		(layer "In15.Cu")
		(net "P5E_CPU1_P0_RX_DN<8>")
	)
	(arc
		(start 117.102382 -332.902052)
		(mid 116.79973 -332.533315)
		(end 116.574824 -332.11262)
		(width 0.14224)
		(layer "In15.Cu")
		(net "P5E_CPU1_P0_RX_DN<8>")
	)
	(arc
		(start 104.779826 -280.060654)
		(mid 104.935754 -279.756362)
		(end 104.779826 -279.45207)
		(width 0.1143)
		(layer "In15.Cu")
		(net "P5E_CPU1_P0_RX_DN<8>")
	)
	(arc
		(start 104.779826 -281.680666)
		(mid 104.935754 -281.376374)
		(end 104.779826 -281.072082)
		(width 0.1143)
		(layer "In15.Cu")
		(net "P5E_CPU1_P0_RX_DN<8>")
	)
	(arc
		(start 104.696514 -274.541996)
		(mid 104.471343 -274.08632)
		(end 104.696514 -273.630644)
		(width 0.1143)
		(layer "In15.Cu")
		(net "P5E_CPU1_P0_RX_DN<8>")
	)
	(arc
		(start 104.696514 -284.970728)
		(mid 104.70409 -284.965332)
		(end 104.711754 -284.96006)
		(width 0.1143)
		(layer "In15.Cu")
		(net "P5E_CPU1_P0_RX_DN<8>")
	)
	(arc
		(start 104.779826 -276.82063)
		(mid 104.935754 -276.516338)
		(end 104.779826 -276.212046)
		(width 0.1143)
		(layer "In15.Cu")
		(net "P5E_CPU1_P0_RX_DN<8>")
	)
	(arc
		(start 105.3465 -361.499404)
		(mid 105.685552 -361.437598)
		(end 105.980992 -361.260136)
		(width 0.14224)
		(layer "In15.Cu")
		(net "P5E_CPU1_P0_RX_DN<8>")
	)
	(arc
		(start 104.735122 -289.14598)
		(mid 104.458789 -288.666174)
		(end 104.735122 -288.186368)
		(width 0.1143)
		(layer "In15.Cu")
		(net "P5E_CPU1_P0_RX_DN<8>")
	)
	(arc
		(start 104.779826 -293.020496)
		(mid 104.935754 -292.716204)
		(end 104.779826 -292.411912)
		(width 0.1143)
		(layer "In15.Cu")
		(net "P5E_CPU1_P0_RX_DN<8>")
	)
	(arc
		(start 104.460548 -295.15181)
		(mid 104.536669 -294.867889)
		(end 104.745028 -294.660574)
		(width 0.1143)
		(layer "In15.Cu")
		(net "P5E_CPU1_P0_RX_DN<8>")
	)
	(arc
		(start 104.23906 -270.500856)
		(mid 104.087073 -270.344348)
		(end 104.005634 -270.141954)
		(width 0.1143)
		(layer "In15.Cu")
		(net "P5E_CPU1_P0_RX_DN<8>")
	)
	(arc
		(start 104.681274 -272.911062)
		(mid 104.452969 -272.466967)
		(end 104.679496 -272.022062)
		(width 0.1143)
		(layer "In15.Cu")
		(net "P5E_CPU1_P0_RX_DN<8>")
	)
	(arc
		(start 74.74585 -361.635548)
		(mid 75.134224 -361.533702)
		(end 75.534266 -361.499404)
		(width 0.14224)
		(layer "In15.Cu")
		(net "P5E_CPU1_P0_RX_DN<8>")
	)
	(arc
		(start 104.681274 -282.631134)
		(mid 104.453274 -282.18638)
		(end 104.681274 -281.741626)
		(width 0.1143)
		(layer "In15.Cu")
		(net "P5E_CPU1_P0_RX_DN<8>")
	)
	(arc
		(start 104.681274 -279.39111)
		(mid 104.453274 -278.946356)
		(end 104.681274 -278.501602)
		(width 0.1143)
		(layer "In15.Cu")
		(net "P5E_CPU1_P0_RX_DN<8>")
	)
	(arc
		(start 104.935782 -286.23641)
		(mid 104.894527 -286.065439)
		(end 104.779826 -285.932118)
		(width 0.1143)
		(layer "In15.Cu")
		(net "P5E_CPU1_P0_RX_DN<8>")
	)
	(arc
		(start 104.005634 -270.141954)
		(mid 104.003611 -270.130544)
		(end 104.001824 -270.119094)
		(width 0.1143)
		(layer "In15.Cu")
		(net "P5E_CPU1_P0_RX_DN<8>")
	)
	(arc
		(start 131.01701 -346.727272)
		(mid 130.757932 -346.535153)
		(end 130.518916 -346.318586)
		(width 0.14224)
		(layer "In15.Cu")
		(net "P5E_CPU1_P0_RX_DN<8>")
	)
	(arc
		(start 104.12222 -302.045878)
		(mid 104.050832 -301.810679)
		(end 104.026716 -301.566072)
		(width 0.14224)
		(layer "In15.Cu")
		(net "P5E_CPU1_P0_RX_DN<8>")
	)
	(arc
		(start 104.072436 -295.924986)
		(mid 104.096726 -295.803343)
		(end 104.165654 -295.700196)
		(width 0.1143)
		(layer "In15.Cu")
		(net "P5E_CPU1_P0_RX_DN<8>")
	)
	(arc
		(start 104.779826 -271.960594)
		(mid 104.931415 -271.656302)
		(end 104.779826 -271.35201)
		(width 0.1143)
		(layer "In15.Cu")
		(net "P5E_CPU1_P0_RX_DN<8>")
	)
	(arc
		(start 104.779826 -284.92069)
		(mid 104.935754 -284.616398)
		(end 104.779826 -284.312106)
		(width 0.1143)
		(layer "In15.Cu")
		(net "P5E_CPU1_P0_RX_DN<8>")
	)
	(arc
		(start 57.583832 -375.456196)
		(mid 57.594592 -375.19523)
		(end 57.65038 -374.940068)
		(width 0.14224)
		(layer "In15.Cu")
		(net "P5E_CPU1_P0_RX_DN<8>")
	)
	(arc
		(start 104.781604 -286.539178)
		(mid 104.895011 -286.406289)
		(end 104.935782 -286.23641)
		(width 0.1143)
		(layer "In15.Cu")
		(net "P5E_CPU1_P0_RX_DN<8>")
	)
	(arc
		(start 106.490008 -361.009184)
		(mid 106.583938 -360.981064)
		(end 106.681524 -360.971592)
		(width 0.14224)
		(layer "In15.Cu")
		(net "P5E_CPU1_P0_RX_DN<8>")
	)
	(arc
		(start 104.779826 -283.300678)
		(mid 104.935754 -282.996386)
		(end 104.779826 -282.692094)
		(width 0.1143)
		(layer "In15.Cu")
		(net "P5E_CPU1_P0_RX_DN<8>")
	)
	(arc
		(start 104.779826 -294.640508)
		(mid 104.935754 -294.336216)
		(end 104.779826 -294.031924)
		(width 0.1143)
		(layer "In15.Cu")
		(net "P5E_CPU1_P0_RX_DN<8>")
	)
	(arc
		(start 104.747822 -290.773612)
		(mid 104.467395 -290.286376)
		(end 104.747822 -289.799014)
		(width 0.1143)
		(layer "In15.Cu")
		(net "P5E_CPU1_P0_RX_DN<8>")
	)
	(arc
		(start 105.980992 -361.260136)
		(mid 106.077337 -361.18867)
		(end 106.184192 -361.134152)
		(width 0.14224)
		(layer "In15.Cu")
		(net "P5E_CPU1_P0_RX_DN<8>")
	)
	(arc
		(start 104.711754 -285.892748)
		(mid 104.70409 -285.887477)
		(end 104.696514 -285.88208)
		(width 0.1143)
		(layer "In15.Cu")
		(net "P5E_CPU1_P0_RX_DN<8>")
	)
	(arc
		(start 104.779826 -291.400484)
		(mid 104.935754 -291.096192)
		(end 104.779826 -290.7919)
		(width 0.1143)
		(layer "In15.Cu")
		(net "P5E_CPU1_P0_RX_DN<8>")
	)
	(arc
		(start 104.696514 -285.88208)
		(mid 104.471343 -285.426404)
		(end 104.696514 -284.970728)
		(width 0.1143)
		(layer "In15.Cu")
		(net "P5E_CPU1_P0_RX_DN<8>")
	)
	(arc
		(start 104.781604 -288.15919)
		(mid 104.895011 -288.026301)
		(end 104.935782 -287.856422)
		(width 0.1143)
		(layer "In15.Cu")
		(net "P5E_CPU1_P0_RX_DN<8>")
	)
	(arc
		(start 63.38189 -365.89081)
		(mid 63.629822 -365.64734)
		(end 63.93688 -365.484664)
		(width 0.14224)
		(layer "In15.Cu")
		(net "P5E_CPU1_P0_RX_DN<8>")
	)
	(arc
		(start 142.46606 -354.713032)
		(mid 142.392969 -354.421175)
		(end 142.190978 -354.198174)
		(width 0.14224)
		(layer "In15.Cu")
		(net "P5E_CPU1_P0_RX_DN<8>")
	)
	(arc
		(start 104.465628 -270.846296)
		(mid 104.424079 -270.674874)
		(end 104.308656 -270.541496)
		(width 0.1143)
		(layer "In15.Cu")
		(net "P5E_CPU1_P0_RX_DN<8>")
	)
	(arc
		(start 104.779826 -273.580606)
		(mid 104.935754 -273.276314)
		(end 104.779826 -272.972022)
		(width 0.1143)
		(layer "In15.Cu")
		(net "P5E_CPU1_P0_RX_DN<8>")
	)
	(arc
		(start 104.696514 -273.630644)
		(mid 104.70409 -273.625248)
		(end 104.711754 -273.619976)
		(width 0.1143)
		(layer "In15.Cu")
		(net "P5E_CPU1_P0_RX_DN<8>")
	)
	(arc
		(start 104.70896 -271.310862)
		(mid 104.530147 -271.108512)
		(end 104.465628 -270.846296)
		(width 0.1143)
		(layer "In15.Cu")
		(net "P5E_CPU1_P0_RX_DN<8>")
	)
	(arc
		(start 104.779826 -275.200618)
		(mid 104.935754 -274.896326)
		(end 104.779826 -274.592034)
		(width 0.1143)
		(layer "In15.Cu")
		(net "P5E_CPU1_P0_RX_DN<8>")
	)
	(segment
		(start 104.08793 -273.010376)
		(end 103.621078 -273.276314)
		(width 0.12954)
		(layer "F.Cu")
		(net "P5E_CPU1_P0_RX_DN<7>")
	)
	(segment
		(start 55.670704 -385.31038)
		(end 56.191404 -385.31038)
		(width 0.127)
		(layer "F.Cu")
		(net "P5E_CPU1_P0_RX_DN<7>")
	)
	(segment
		(start 103.808276 -291.418772)
		(end 103.838756 -291.400992)
		(width 0.1143)
		(layer "In13.Cu")
		(net "P5E_CPU1_P0_RX_DN<7>")
	)
	(segment
		(start 103.838756 -290.791392)
		(end 103.808276 -290.773612)
		(width 0.1143)
		(layer "In13.Cu")
		(net "P5E_CPU1_P0_RX_DN<7>")
	)
	(segment
		(start 106.916474 -299.95241)
		(end 104.285796 -297.321732)
		(width 0.14224)
		(layer "In13.Cu")
		(net "P5E_CPU1_P0_RX_DN<7>")
	)
	(segment
		(start 56.354472 -384.234944)
		(end 56.65851 -383.93116)
		(width 0.14224)
		(layer "In13.Cu")
		(net "P5E_CPU1_P0_RX_DN<7>")
	)
	(segment
		(start 103.91902 -273.276314)
		(end 103.621078 -273.276314)
		(width 0.1143)
		(layer "In13.Cu")
		(net "P5E_CPU1_P0_RX_DN<7>")
	)
	(segment
		(start 104.164384 -296.120312)
		(end 103.78948 -295.745408)
		(width 0.1143)
		(layer "In13.Cu")
		(net "P5E_CPU1_P0_RX_DN<7>")
	)
	(segment
		(start 129.808224 -332.509114)
		(end 128.231392 -326.60463)
		(width 0.14224)
		(layer "In13.Cu")
		(net "P5E_CPU1_P0_RX_DN<7>")
	)
	(segment
		(start 61.083952 -379.457204)
		(end 70.60311 -374.378728)
		(width 0.14224)
		(layer "In13.Cu")
		(net "P5E_CPU1_P0_RX_DN<7>")
	)
	(segment
		(start 136.934448 -370.095018)
		(end 137.436352 -369.593368)
		(width 0.14224)
		(layer "In13.Cu")
		(net "P5E_CPU1_P0_RX_DN<7>")
	)
	(segment
		(start 103.76916 -275.241766)
		(end 103.808276 -275.218906)
		(width 0.1143)
		(layer "In13.Cu")
		(net "P5E_CPU1_P0_RX_DN<7>")
	)
	(segment
		(start 132.35432 -372.391686)
		(end 132.484876 -372.261384)
		(width 0.14224)
		(layer "In13.Cu")
		(net "P5E_CPU1_P0_RX_DN<7>")
	)
	(segment
		(start 103.98887 -273.346164)
		(end 103.91902 -273.276314)
		(width 0.1143)
		(layer "In13.Cu")
		(net "P5E_CPU1_P0_RX_DN<7>")
	)
	(segment
		(start 103.808276 -274.573746)
		(end 103.76916 -274.550886)
		(width 0.1143)
		(layer "In13.Cu")
		(net "P5E_CPU1_P0_RX_DN<7>")
	)
	(segment
		(start 103.808276 -275.218906)
		(end 103.838756 -275.201126)
		(width 0.1143)
		(layer "In13.Cu")
		(net "P5E_CPU1_P0_RX_DN<7>")
	)
	(segment
		(start 103.838756 -289.17138)
		(end 103.808276 -289.1536)
		(width 0.1143)
		(layer "In13.Cu")
		(net "P5E_CPU1_P0_RX_DN<7>")
	)
	(segment
		(start 103.76916 -286.581596)
		(end 103.771192 -286.580072)
		(width 0.1143)
		(layer "In13.Cu")
		(net "P5E_CPU1_P0_RX_DN<7>")
	)
	(segment
		(start 114.50955 -377.105164)
		(end 114.50955 -378.931424)
		(width 0.14224)
		(layer "In13.Cu")
		(net "P5E_CPU1_P0_RX_DN<7>")
	)
	(segment
		(start 56.666638 -385.163822)
		(end 56.349646 -384.84683)
		(width 0.14224)
		(layer "In13.Cu")
		(net "P5E_CPU1_P0_RX_DN<7>")
	)
	(segment
		(start 56.544972 -385.404868)
		(end 56.666638 -385.334764)
		(width 0.14224)
		(layer "In13.Cu")
		(net "P5E_CPU1_P0_RX_DN<7>")
	)
	(segment
		(start 60.08878 -379.988064)
		(end 60.465208 -379.787404)
		(width 0.14224)
		(layer "In13.Cu")
		(net "P5E_CPU1_P0_RX_DN<7>")
	)
	(segment
		(start 59.526424 -380.132336)
		(end 59.903106 -379.931422)
		(width 0.14224)
		(layer "In13.Cu")
		(net "P5E_CPU1_P0_RX_DN<7>")
	)
	(segment
		(start 60.465208 -379.787404)
		(end 60.521596 -379.601476)
		(width 0.14224)
		(layer "In13.Cu")
		(net "P5E_CPU1_P0_RX_DN<7>")
	)
	(segment
		(start 103.808276 -284.938978)
		(end 103.838756 -284.921198)
		(width 0.1143)
		(layer "In13.Cu")
		(net "P5E_CPU1_P0_RX_DN<7>")
	)
	(segment
		(start 56.349646 -384.84683)
		(end 56.354472 -384.234944)
		(width 0.14224)
		(layer "In13.Cu")
		(net "P5E_CPU1_P0_RX_DN<7>")
	)
	(segment
		(start 103.838756 -294.031416)
		(end 103.808276 -294.013636)
		(width 0.1143)
		(layer "In13.Cu")
		(net "P5E_CPU1_P0_RX_DN<7>")
	)
	(segment
		(start 115.67287 -378.217684)
		(end 115.36553 -377.910344)
		(width 0.14224)
		(layer "In13.Cu")
		(net "P5E_CPU1_P0_RX_DN<7>")
	)
	(segment
		(start 130.823462 -376.123708)
		(end 130.823462 -373.84609)
		(width 0.14224)
		(layer "In13.Cu")
		(net "P5E_CPU1_P0_RX_DN<7>")
	)
	(segment
		(start 103.838756 -282.691586)
		(end 103.808276 -282.673806)
		(width 0.1143)
		(layer "In13.Cu")
		(net "P5E_CPU1_P0_RX_DN<7>")
	)
	(segment
		(start 124.777246 -379.073664)
		(end 124.919486 -378.931424)
		(width 0.14224)
		(layer "In13.Cu")
		(net "P5E_CPU1_P0_RX_DN<7>")
	)
	(segment
		(start 56.736234 -382.19126)
		(end 56.88076 -381.813308)
		(width 0.14224)
		(layer "In13.Cu")
		(net "P5E_CPU1_P0_RX_DN<7>")
	)
	(segment
		(start 124.919486 -378.359924)
		(end 124.777246 -378.217684)
		(width 0.14224)
		(layer "In13.Cu")
		(net "P5E_CPU1_P0_RX_DN<7>")
	)
	(segment
		(start 137.658094 -368.94516)
		(end 137.658094 -364.939072)
		(width 0.14224)
		(layer "In13.Cu")
		(net "P5E_CPU1_P0_RX_DN<7>")
	)
	(segment
		(start 114.943128 -305.748436)
		(end 114.078512 -304.222404)
		(width 0.14224)
		(layer "In13.Cu")
		(net "P5E_CPU1_P0_RX_DN<7>")
	)
	(segment
		(start 103.808276 -293.038784)
		(end 103.838756 -293.021004)
		(width 0.1143)
		(layer "In13.Cu")
		(net "P5E_CPU1_P0_RX_DN<7>")
	)
	(segment
		(start 103.69169 -294.75938)
		(end 103.69169 -294.759126)
		(width 0.1143)
		(layer "In13.Cu")
		(net "P5E_CPU1_P0_RX_DN<7>")
	)
	(segment
		(start 103.808276 -285.91383)
		(end 103.76916 -285.89097)
		(width 0.1143)
		(layer "In13.Cu")
		(net "P5E_CPU1_P0_RX_DN<7>")
	)
	(segment
		(start 103.838756 -276.211538)
		(end 103.808276 -276.193758)
		(width 0.1143)
		(layer "In13.Cu")
		(net "P5E_CPU1_P0_RX_DN<7>")
	)
	(segment
		(start 59.093608 -380.518924)
		(end 59.470036 -380.318264)
		(width 0.14224)
		(layer "In13.Cu")
		(net "P5E_CPU1_P0_RX_DN<7>")
	)
	(segment
		(start 132.53212 -372.147338)
		(end 132.53212 -371.257576)
		(width 0.14224)
		(layer "In13.Cu")
		(net "P5E_CPU1_P0_RX_DN<7>")
	)
	(segment
		(start 103.76916 -280.101802)
		(end 103.808276 -280.078942)
		(width 0.1143)
		(layer "In13.Cu")
		(net "P5E_CPU1_P0_RX_DN<7>")
	)
	(segment
		(start 104.211628 -296.428414)
		(end 104.211628 -296.234358)
		(width 0.1143)
		(layer "In13.Cu")
		(net "P5E_CPU1_P0_RX_DN<7>")
	)
	(segment
		(start 103.838756 -281.071574)
		(end 103.808276 -281.053794)
		(width 0.1143)
		(layer "In13.Cu")
		(net "P5E_CPU1_P0_RX_DN<7>")
	)
	(segment
		(start 126.374144 -321.887596)
		(end 124.092716 -318.081406)
		(width 0.14224)
		(layer "In13.Cu")
		(net "P5E_CPU1_P0_RX_DN<7>")
	)
	(segment
		(start 103.808276 -273.598894)
		(end 103.838756 -273.581114)
		(width 0.1143)
		(layer "In13.Cu")
		(net "P5E_CPU1_P0_RX_DN<7>")
	)
	(segment
		(start 133.808978 -370.038884)
		(end 134.627366 -370.038884)
		(width 0.14224)
		(layer "In13.Cu")
		(net "P5E_CPU1_P0_RX_DN<7>")
	)
	(segment
		(start 56.666638 -385.334764)
		(end 56.666638 -385.163822)
		(width 0.14224)
		(layer "In13.Cu")
		(net "P5E_CPU1_P0_RX_DN<7>")
	)
	(segment
		(start 115.67287 -376.797824)
		(end 130.188208 -376.797824)
		(width 0.14224)
		(layer "In13.Cu")
		(net "P5E_CPU1_P0_RX_DN<7>")
	)
	(segment
		(start 56.544464 -385.405376)
		(end 56.544972 -385.404868)
		(width 0.14224)
		(layer "In13.Cu")
		(net "P5E_CPU1_P0_RX_DN<7>")
	)
	(segment
		(start 114.20221 -376.797824)
		(end 114.50955 -377.105164)
		(width 0.14224)
		(layer "In13.Cu")
		(net "P5E_CPU1_P0_RX_DN<7>")
	)
	(segment
		(start 57.06999 -381.598424)
		(end 58.474864 -380.849124)
		(width 0.14224)
		(layer "In13.Cu")
		(net "P5E_CPU1_P0_RX_DN<7>")
	)
	(segment
		(start 103.76916 -278.48179)
		(end 103.808276 -278.45893)
		(width 0.1143)
		(layer "In13.Cu")
		(net "P5E_CPU1_P0_RX_DN<7>")
	)
	(segment
		(start 60.898278 -379.400562)
		(end 61.083952 -379.457204)
		(width 0.14224)
		(layer "In13.Cu")
		(net "P5E_CPU1_P0_RX_DN<7>")
	)
	(segment
		(start 102.505764 -375.127012)
		(end 102.824788 -374.807988)
		(width 0.14224)
		(layer "In13.Cu")
		(net "P5E_CPU1_P0_RX_DN<7>")
	)
	(segment
		(start 103.69169 -294.759126)
		(end 103.76916 -294.681656)
		(width 0.1143)
		(layer "In13.Cu")
		(net "P5E_CPU1_P0_RX_DN<7>")
	)
	(segment
		(start 103.726996 -374.4341)
		(end 108.680758 -374.4341)
		(width 0.14224)
		(layer "In13.Cu")
		(net "P5E_CPU1_P0_RX_DN<7>")
	)
	(segment
		(start 103.808276 -283.318966)
		(end 103.838756 -283.301186)
		(width 0.1143)
		(layer "In13.Cu")
		(net "P5E_CPU1_P0_RX_DN<7>")
	)
	(segment
		(start 135.614918 -370.257578)
		(end 136.54278 -370.257578)
		(width 0.14224)
		(layer "In13.Cu")
		(net "P5E_CPU1_P0_RX_DN<7>")
	)
	(segment
		(start 103.76916 -273.621754)
		(end 103.808276 -273.598894)
		(width 0.1143)
		(layer "In13.Cu")
		(net "P5E_CPU1_P0_RX_DN<7>")
	)
	(segment
		(start 60.521596 -379.601476)
		(end 60.898278 -379.400562)
		(width 0.14224)
		(layer "In13.Cu")
		(net "P5E_CPU1_P0_RX_DN<7>")
	)
	(segment
		(start 111.670592 -376.207528)
		(end 113.020602 -376.766328)
		(width 0.14224)
		(layer "In13.Cu")
		(net "P5E_CPU1_P0_RX_DN<7>")
	)
	(segment
		(start 137.658094 -364.939072)
		(end 133.994906 -352.829368)
		(width 0.14224)
		(layer "In13.Cu")
		(net "P5E_CPU1_P0_RX_DN<7>")
	)
	(segment
		(start 103.76916 -284.961838)
		(end 103.808276 -284.938978)
		(width 0.1143)
		(layer "In13.Cu")
		(net "P5E_CPU1_P0_RX_DN<7>")
	)
	(segment
		(start 103.808276 -276.193758)
		(end 103.76916 -276.170898)
		(width 0.1143)
		(layer "In13.Cu")
		(net "P5E_CPU1_P0_RX_DN<7>")
	)
	(segment
		(start 114.50955 -378.931424)
		(end 114.65179 -379.073664)
		(width 0.14224)
		(layer "In13.Cu")
		(net "P5E_CPU1_P0_RX_DN<7>")
	)
	(segment
		(start 103.808276 -278.45893)
		(end 103.838756 -278.44115)
		(width 0.1143)
		(layer "In13.Cu")
		(net "P5E_CPU1_P0_RX_DN<7>")
	)
	(segment
		(start 103.76916 -294.681656)
		(end 103.838756 -294.641016)
		(width 0.1143)
		(layer "In13.Cu")
		(net "P5E_CPU1_P0_RX_DN<7>")
	)
	(segment
		(start 137.61466 -369.16233)
		(end 137.658094 -368.94516)
		(width 0.14224)
		(layer "In13.Cu")
		(net "P5E_CPU1_P0_RX_DN<7>")
	)
	(segment
		(start 130.527044 -337.367372)
		(end 129.808224 -332.509114)
		(width 0.14224)
		(layer "In13.Cu")
		(net "P5E_CPU1_P0_RX_DN<7>")
	)
	(segment
		(start 124.919486 -378.931424)
		(end 124.919486 -378.359924)
		(width 0.14224)
		(layer "In13.Cu")
		(net "P5E_CPU1_P0_RX_DN<7>")
	)
	(segment
		(start 103.808276 -276.838918)
		(end 103.838756 -276.821138)
		(width 0.1143)
		(layer "In13.Cu")
		(net "P5E_CPU1_P0_RX_DN<7>")
	)
	(segment
		(start 75.146662 -374.240552)
		(end 77.413104 -376.506994)
		(width 0.14224)
		(layer "In13.Cu")
		(net "P5E_CPU1_P0_RX_DN<7>")
	)
	(segment
		(start 124.092716 -318.081406)
		(end 114.943128 -305.748436)
		(width 0.14224)
		(layer "In13.Cu")
		(net "P5E_CPU1_P0_RX_DN<7>")
	)
	(segment
		(start 56.191404 -385.31038)
		(end 56.544464 -385.405376)
		(width 0.14224)
		(layer "In13.Cu")
		(net "P5E_CPU1_P0_RX_DN<7>")
	)
	(segment
		(start 103.76916 -289.82162)
		(end 103.808276 -289.79876)
		(width 0.1143)
		(layer "In13.Cu")
		(net "P5E_CPU1_P0_RX_DN<7>")
	)
	(segment
		(start 103.76916 -291.441632)
		(end 103.808276 -291.418772)
		(width 0.1143)
		(layer "In13.Cu")
		(net "P5E_CPU1_P0_RX_DN<7>")
	)
	(segment
		(start 103.808276 -282.673806)
		(end 103.76916 -282.650946)
		(width 0.1143)
		(layer "In13.Cu")
		(net "P5E_CPU1_P0_RX_DN<7>")
	)
	(segment
		(start 101.91877 -376.5296)
		(end 102.23881 -376.20956)
		(width 0.14224)
		(layer "In13.Cu")
		(net "P5E_CPU1_P0_RX_DN<7>")
	)
	(segment
		(start 56.65851 -383.93116)
		(end 56.65851 -382.612138)
		(width 0.14224)
		(layer "In13.Cu")
		(net "P5E_CPU1_P0_RX_DN<7>")
	)
	(segment
		(start 103.808276 -289.1536)
		(end 103.76916 -289.13074)
		(width 0.1143)
		(layer "In13.Cu")
		(net "P5E_CPU1_P0_RX_DN<7>")
	)
	(segment
		(start 128.231392 -326.60463)
		(end 126.374144 -321.887596)
		(width 0.14224)
		(layer "In13.Cu")
		(net "P5E_CPU1_P0_RX_DN<7>")
	)
	(segment
		(start 103.76916 -283.341826)
		(end 103.808276 -283.318966)
		(width 0.1143)
		(layer "In13.Cu")
		(net "P5E_CPU1_P0_RX_DN<7>")
	)
	(segment
		(start 103.771192 -286.580072)
		(end 103.808276 -286.558736)
		(width 0.1143)
		(layer "In13.Cu")
		(net "P5E_CPU1_P0_RX_DN<7>")
	)
	(segment
		(start 130.311652 -376.773186)
		(end 130.597402 -376.655076)
		(width 0.14224)
		(layer "In13.Cu")
		(net "P5E_CPU1_P0_RX_DN<7>")
	)
	(segment
		(start 114.65179 -379.073664)
		(end 124.777246 -379.073664)
		(width 0.14224)
		(layer "In13.Cu")
		(net "P5E_CPU1_P0_RX_DN<7>")
	)
	(segment
		(start 115.36553 -377.910344)
		(end 115.36553 -377.105164)
		(width 0.14224)
		(layer "In13.Cu")
		(net "P5E_CPU1_P0_RX_DN<7>")
	)
	(segment
		(start 104.165908 -296.502582)
		(end 104.165908 -296.474134)
		(width 0.1143)
		(layer "In13.Cu")
		(net "P5E_CPU1_P0_RX_DN<7>")
	)
	(segment
		(start 59.903106 -379.931422)
		(end 60.08878 -379.988064)
		(width 0.14224)
		(layer "In13.Cu")
		(net "P5E_CPU1_P0_RX_DN<7>")
	)
	(segment
		(start 71.635112 -374.120664)
		(end 74.857356 -374.120664)
		(width 0.14224)
		(layer "In13.Cu")
		(net "P5E_CPU1_P0_RX_DN<7>")
	)
	(segment
		(start 103.808276 -286.558736)
		(end 103.840788 -286.53994)
		(width 0.1143)
		(layer "In13.Cu")
		(net "P5E_CPU1_P0_RX_DN<7>")
	)
	(segment
		(start 131.126992 -373.113046)
		(end 131.435348 -372.80469)
		(width 0.14224)
		(layer "In13.Cu")
		(net "P5E_CPU1_P0_RX_DN<7>")
	)
	(segment
		(start 103.838756 -287.551622)
		(end 103.7717 -287.512506)
		(width 0.1143)
		(layer "In13.Cu")
		(net "P5E_CPU1_P0_RX_DN<7>")
	)
	(segment
		(start 103.808276 -281.698954)
		(end 103.838756 -281.681174)
		(width 0.1143)
		(layer "In13.Cu")
		(net "P5E_CPU1_P0_RX_DN<7>")
	)
	(segment
		(start 113.593626 -376.797824)
		(end 114.20221 -376.797824)
		(width 0.14224)
		(layer "In13.Cu")
		(net "P5E_CPU1_P0_RX_DN<7>")
	)
	(segment
		(start 78.337918 -376.890026)
		(end 101.048566 -376.890026)
		(width 0.14224)
		(layer "In13.Cu")
		(net "P5E_CPU1_P0_RX_DN<7>")
	)
	(segment
		(start 104.165908 -297.032426)
		(end 104.165908 -296.502582)
		(width 0.14224)
		(layer "In13.Cu")
		(net "P5E_CPU1_P0_RX_DN<7>")
	)
	(segment
		(start 110.434628 -375.16054)
		(end 111.101378 -375.82729)
		(width 0.14224)
		(layer "In13.Cu")
		(net "P5E_CPU1_P0_RX_DN<7>")
	)
	(segment
		(start 103.808276 -277.81377)
		(end 103.76916 -277.79091)
		(width 0.1143)
		(layer "In13.Cu")
		(net "P5E_CPU1_P0_RX_DN<7>")
	)
	(segment
		(start 58.531252 -380.663196)
		(end 58.907934 -380.462282)
		(width 0.14224)
		(layer "In13.Cu")
		(net "P5E_CPU1_P0_RX_DN<7>")
	)
	(segment
		(start 136.54278 -370.257578)
		(end 136.934448 -370.095018)
		(width 0.14224)
		(layer "In13.Cu")
		(net "P5E_CPU1_P0_RX_DN<7>")
	)
	(segment
		(start 113.981738 -304.118264)
		(end 111.731044 -302.614584)
		(width 0.14224)
		(layer "In13.Cu")
		(net "P5E_CPU1_P0_RX_DN<7>")
	)
	(segment
		(start 111.731044 -302.614584)
		(end 107.342686 -300.26864)
		(width 0.14224)
		(layer "In13.Cu")
		(net "P5E_CPU1_P0_RX_DN<7>")
	)
	(segment
		(start 103.838756 -279.451562)
		(end 103.808276 -279.433782)
		(width 0.1143)
		(layer "In13.Cu")
		(net "P5E_CPU1_P0_RX_DN<7>")
	)
	(segment
		(start 133.957568 -352.686874)
		(end 130.527044 -337.367372)
		(width 0.14224)
		(layer "In13.Cu")
		(net "P5E_CPU1_P0_RX_DN<7>")
	)
	(segment
		(start 103.76916 -288.201608)
		(end 103.808276 -288.178748)
		(width 0.1143)
		(layer "In13.Cu")
		(net "P5E_CPU1_P0_RX_DN<7>")
	)
	(segment
		(start 103.808276 -284.293818)
		(end 103.76916 -284.270958)
		(width 0.1143)
		(layer "In13.Cu")
		(net "P5E_CPU1_P0_RX_DN<7>")
	)
	(segment
		(start 59.470036 -380.318264)
		(end 59.526424 -380.132336)
		(width 0.14224)
		(layer "In13.Cu")
		(net "P5E_CPU1_P0_RX_DN<7>")
	)
	(segment
		(start 103.808276 -294.013636)
		(end 103.76916 -293.990776)
		(width 0.1143)
		(layer "In13.Cu")
		(net "P5E_CPU1_P0_RX_DN<7>")
	)
	(segment
		(start 103.838756 -274.591526)
		(end 103.808276 -274.573746)
		(width 0.1143)
		(layer "In13.Cu")
		(net "P5E_CPU1_P0_RX_DN<7>")
	)
	(segment
		(start 58.474864 -380.849124)
		(end 58.531252 -380.663196)
		(width 0.14224)
		(layer "In13.Cu")
		(net "P5E_CPU1_P0_RX_DN<7>")
	)
	(segment
		(start 115.36553 -377.105164)
		(end 115.67287 -376.797824)
		(width 0.14224)
		(layer "In13.Cu")
		(net "P5E_CPU1_P0_RX_DN<7>")
	)
	(segment
		(start 103.838756 -292.411404)
		(end 103.808276 -292.393624)
		(width 0.1143)
		(layer "In13.Cu")
		(net "P5E_CPU1_P0_RX_DN<7>")
	)
	(segment
		(start 103.838756 -285.93161)
		(end 103.808276 -285.91383)
		(width 0.1143)
		(layer "In13.Cu")
		(net "P5E_CPU1_P0_RX_DN<7>")
	)
	(segment
		(start 103.808276 -279.433782)
		(end 103.76916 -279.410922)
		(width 0.1143)
		(layer "In13.Cu")
		(net "P5E_CPU1_P0_RX_DN<7>")
	)
	(segment
		(start 104.165908 -296.474134)
		(end 104.211628 -296.428414)
		(width 0.1143)
		(layer "In13.Cu")
		(net "P5E_CPU1_P0_RX_DN<7>")
	)
	(segment
		(start 103.838756 -277.83155)
		(end 103.808276 -277.81377)
		(width 0.1143)
		(layer "In13.Cu")
		(net "P5E_CPU1_P0_RX_DN<7>")
	)
	(segment
		(start 132.70992 -370.828062)
		(end 133.280404 -370.257578)
		(width 0.14224)
		(layer "In13.Cu")
		(net "P5E_CPU1_P0_RX_DN<7>")
	)
	(segment
		(start 103.808276 -280.078942)
		(end 103.838756 -280.061162)
		(width 0.1143)
		(layer "In13.Cu")
		(net "P5E_CPU1_P0_RX_DN<7>")
	)
	(segment
		(start 102.385876 -375.854468)
		(end 102.385876 -375.416572)
		(width 0.14224)
		(layer "In13.Cu")
		(net "P5E_CPU1_P0_RX_DN<7>")
	)
	(segment
		(start 103.808276 -290.773612)
		(end 103.76916 -290.750752)
		(width 0.1143)
		(layer "In13.Cu")
		(net "P5E_CPU1_P0_RX_DN<7>")
	)
	(segment
		(start 124.777246 -378.217684)
		(end 115.67287 -378.217684)
		(width 0.14224)
		(layer "In13.Cu")
		(net "P5E_CPU1_P0_RX_DN<7>")
	)
	(segment
		(start 103.808276 -289.79876)
		(end 103.838756 -289.78098)
		(width 0.1143)
		(layer "In13.Cu")
		(net "P5E_CPU1_P0_RX_DN<7>")
	)
	(segment
		(start 103.808276 -281.053794)
		(end 103.76916 -281.030934)
		(width 0.1143)
		(layer "In13.Cu")
		(net "P5E_CPU1_P0_RX_DN<7>")
	)
	(segment
		(start 103.76916 -293.061644)
		(end 103.808276 -293.038784)
		(width 0.1143)
		(layer "In13.Cu")
		(net "P5E_CPU1_P0_RX_DN<7>")
	)
	(segment
		(start 103.76916 -276.861778)
		(end 103.808276 -276.838918)
		(width 0.1143)
		(layer "In13.Cu")
		(net "P5E_CPU1_P0_RX_DN<7>")
	)
	(segment
		(start 58.907934 -380.462282)
		(end 59.093608 -380.518924)
		(width 0.14224)
		(layer "In13.Cu")
		(net "P5E_CPU1_P0_RX_DN<7>")
	)
	(segment
		(start 137.436352 -369.593368)
		(end 137.61466 -369.16233)
		(width 0.14224)
		(layer "In13.Cu")
		(net "P5E_CPU1_P0_RX_DN<7>")
	)
	(segment
		(start 103.76916 -281.721814)
		(end 103.808276 -281.698954)
		(width 0.1143)
		(layer "In13.Cu")
		(net "P5E_CPU1_P0_RX_DN<7>")
	)
	(segment
		(start 103.808276 -292.393624)
		(end 103.76916 -292.370764)
		(width 0.1143)
		(layer "In13.Cu")
		(net "P5E_CPU1_P0_RX_DN<7>")
	)
	(segment
		(start 103.838756 -284.311598)
		(end 103.808276 -284.293818)
		(width 0.1143)
		(layer "In13.Cu")
		(net "P5E_CPU1_P0_RX_DN<7>")
	)
	(segment
		(start 103.808276 -288.178748)
		(end 103.840788 -288.159952)
		(width 0.1143)
		(layer "In13.Cu")
		(net "P5E_CPU1_P0_RX_DN<7>")
	)
	(arc
		(start 103.838756 -284.921198)
		(mid 103.995733 -284.616398)
		(end 103.838756 -284.311598)
		(width 0.1143)
		(layer "In13.Cu")
		(net "P5E_CPU1_P0_RX_DN<7>")
	)
	(arc
		(start 103.76916 -281.030934)
		(mid 103.525833 -280.566368)
		(end 103.76916 -280.101802)
		(width 0.1143)
		(layer "In13.Cu")
		(net "P5E_CPU1_P0_RX_DN<7>")
	)
	(arc
		(start 103.78948 -295.745408)
		(mid 103.733912 -295.684184)
		(end 103.684832 -295.617646)
		(width 0.1143)
		(layer "In13.Cu")
		(net "P5E_CPU1_P0_RX_DN<7>")
	)
	(arc
		(start 103.76916 -285.89097)
		(mid 103.525833 -285.426404)
		(end 103.76916 -284.961838)
		(width 0.1143)
		(layer "In13.Cu")
		(net "P5E_CPU1_P0_RX_DN<7>")
	)
	(arc
		(start 103.838756 -278.44115)
		(mid 103.995733 -278.13635)
		(end 103.838756 -277.83155)
		(width 0.1143)
		(layer "In13.Cu")
		(net "P5E_CPU1_P0_RX_DN<7>")
	)
	(arc
		(start 103.525828 -287.046162)
		(mid 103.590343 -286.783943)
		(end 103.76916 -286.581596)
		(width 0.1143)
		(layer "In13.Cu")
		(net "P5E_CPU1_P0_RX_DN<7>")
	)
	(arc
		(start 135.48995 -370.235988)
		(mid 135.551508 -370.252136)
		(end 135.614918 -370.257578)
		(width 0.14224)
		(layer "In13.Cu")
		(net "P5E_CPU1_P0_RX_DN<7>")
	)
	(arc
		(start 103.838756 -276.821138)
		(mid 103.995733 -276.516338)
		(end 103.838756 -276.211538)
		(width 0.1143)
		(layer "In13.Cu")
		(net "P5E_CPU1_P0_RX_DN<7>")
	)
	(arc
		(start 102.385876 -375.416572)
		(mid 102.417028 -375.259869)
		(end 102.505764 -375.127012)
		(width 0.14224)
		(layer "In13.Cu")
		(net "P5E_CPU1_P0_RX_DN<7>")
	)
	(arc
		(start 130.188208 -376.797824)
		(mid 130.251139 -376.79157)
		(end 130.311652 -376.773186)
		(width 0.14224)
		(layer "In13.Cu")
		(net "P5E_CPU1_P0_RX_DN<7>")
	)
	(arc
		(start 131.954016 -372.565422)
		(mid 132.017423 -372.55762)
		(end 132.079746 -372.543578)
		(width 0.14224)
		(layer "In13.Cu")
		(net "P5E_CPU1_P0_RX_DN<7>")
	)
	(arc
		(start 103.995728 -287.856422)
		(mid 103.954179 -287.685)
		(end 103.838756 -287.551622)
		(width 0.1143)
		(layer "In13.Cu")
		(net "P5E_CPU1_P0_RX_DN<7>")
	)
	(arc
		(start 101.048566 -376.890026)
		(mid 101.519508 -376.79635)
		(end 101.91877 -376.5296)
		(width 0.14224)
		(layer "In13.Cu")
		(net "P5E_CPU1_P0_RX_DN<7>")
	)
	(arc
		(start 113.020602 -376.766328)
		(mid 113.202917 -376.814375)
		(end 113.391442 -376.812302)
		(width 0.14224)
		(layer "In13.Cu")
		(net "P5E_CPU1_P0_RX_DN<7>")
	)
	(arc
		(start 132.254498 -372.469156)
		(mid 132.306859 -372.433579)
		(end 132.35432 -372.391686)
		(width 0.14224)
		(layer "In13.Cu")
		(net "P5E_CPU1_P0_RX_DN<7>")
	)
	(arc
		(start 113.391442 -376.812302)
		(mid 113.492273 -376.801423)
		(end 113.593626 -376.797824)
		(width 0.14224)
		(layer "In13.Cu")
		(net "P5E_CPU1_P0_RX_DN<7>")
	)
	(arc
		(start 134.627366 -370.038884)
		(mid 134.998382 -370.075471)
		(end 135.355076 -370.183918)
		(width 0.14224)
		(layer "In13.Cu")
		(net "P5E_CPU1_P0_RX_DN<7>")
	)
	(arc
		(start 130.823462 -373.84609)
		(mid 130.902351 -373.449396)
		(end 131.126992 -373.113046)
		(width 0.14224)
		(layer "In13.Cu")
		(net "P5E_CPU1_P0_RX_DN<7>")
	)
	(arc
		(start 111.101378 -375.82729)
		(mid 111.367246 -376.045463)
		(end 111.670592 -376.207528)
		(width 0.14224)
		(layer "In13.Cu")
		(net "P5E_CPU1_P0_RX_DN<7>")
	)
	(arc
		(start 104.211628 -296.234358)
		(mid 104.199366 -296.172621)
		(end 104.164384 -296.120312)
		(width 0.1143)
		(layer "In13.Cu")
		(net "P5E_CPU1_P0_RX_DN<7>")
	)
	(arc
		(start 130.694176 -376.573288)
		(mid 130.790577 -376.357626)
		(end 130.823462 -376.123708)
		(width 0.14224)
		(layer "In13.Cu")
		(net "P5E_CPU1_P0_RX_DN<7>")
	)
	(arc
		(start 132.484876 -372.261384)
		(mid 132.519838 -372.209059)
		(end 132.53212 -372.147338)
		(width 0.14224)
		(layer "In13.Cu")
		(net "P5E_CPU1_P0_RX_DN<7>")
	)
	(arc
		(start 103.76916 -274.550886)
		(mid 103.525833 -274.08632)
		(end 103.76916 -273.621754)
		(width 0.1143)
		(layer "In13.Cu")
		(net "P5E_CPU1_P0_RX_DN<7>")
	)
	(arc
		(start 103.76916 -284.270958)
		(mid 103.525833 -283.806392)
		(end 103.76916 -283.341826)
		(width 0.1143)
		(layer "In13.Cu")
		(net "P5E_CPU1_P0_RX_DN<7>")
	)
	(arc
		(start 102.824788 -374.807988)
		(mid 103.238724 -374.531375)
		(end 103.726996 -374.4341)
		(width 0.14224)
		(layer "In13.Cu")
		(net "P5E_CPU1_P0_RX_DN<7>")
	)
	(arc
		(start 103.838756 -280.061162)
		(mid 103.995733 -279.756362)
		(end 103.838756 -279.451562)
		(width 0.1143)
		(layer "In13.Cu")
		(net "P5E_CPU1_P0_RX_DN<7>")
	)
	(arc
		(start 132.079746 -372.543578)
		(mid 132.169532 -372.512025)
		(end 132.254498 -372.469156)
		(width 0.14224)
		(layer "In13.Cu")
		(net "P5E_CPU1_P0_RX_DN<7>")
	)
	(arc
		(start 103.838756 -283.301186)
		(mid 103.995733 -282.996386)
		(end 103.838756 -282.691586)
		(width 0.1143)
		(layer "In13.Cu")
		(net "P5E_CPU1_P0_RX_DN<7>")
	)
	(arc
		(start 103.838756 -273.581114)
		(mid 103.936521 -273.478138)
		(end 103.98887 -273.346164)
		(width 0.1143)
		(layer "In13.Cu")
		(net "P5E_CPU1_P0_RX_DN<7>")
	)
	(arc
		(start 103.76916 -279.410922)
		(mid 103.525833 -278.946356)
		(end 103.76916 -278.48179)
		(width 0.1143)
		(layer "In13.Cu")
		(net "P5E_CPU1_P0_RX_DN<7>")
	)
	(arc
		(start 103.840788 -288.159952)
		(mid 103.954717 -288.026805)
		(end 103.995728 -287.856422)
		(width 0.1143)
		(layer "In13.Cu")
		(net "P5E_CPU1_P0_RX_DN<7>")
	)
	(arc
		(start 102.23881 -376.20956)
		(mid 102.347668 -376.046642)
		(end 102.385876 -375.854468)
		(width 0.14224)
		(layer "In13.Cu")
		(net "P5E_CPU1_P0_RX_DN<7>")
	)
	(arc
		(start 103.76916 -277.79091)
		(mid 103.525833 -277.326344)
		(end 103.76916 -276.861778)
		(width 0.1143)
		(layer "In13.Cu")
		(net "P5E_CPU1_P0_RX_DN<7>")
	)
	(arc
		(start 56.65851 -382.612138)
		(mid 56.67806 -382.398133)
		(end 56.736234 -382.19126)
		(width 0.14224)
		(layer "In13.Cu")
		(net "P5E_CPU1_P0_RX_DN<7>")
	)
	(arc
		(start 104.285796 -297.321732)
		(mid 104.197052 -297.189012)
		(end 104.165908 -297.032426)
		(width 0.14224)
		(layer "In13.Cu")
		(net "P5E_CPU1_P0_RX_DN<7>")
	)
	(arc
		(start 135.355076 -370.183918)
		(mid 135.422169 -370.210845)
		(end 135.48995 -370.235988)
		(width 0.14224)
		(layer "In13.Cu")
		(net "P5E_CPU1_P0_RX_DN<7>")
	)
	(arc
		(start 56.88076 -381.813308)
		(mid 56.95595 -381.688755)
		(end 57.06999 -381.598424)
		(width 0.14224)
		(layer "In13.Cu")
		(net "P5E_CPU1_P0_RX_DN<7>")
	)
	(arc
		(start 132.53212 -371.257576)
		(mid 132.578349 -371.025167)
		(end 132.70992 -370.828062)
		(width 0.14224)
		(layer "In13.Cu")
		(net "P5E_CPU1_P0_RX_DN<7>")
	)
	(arc
		(start 103.838756 -275.201126)
		(mid 103.995733 -274.896326)
		(end 103.838756 -274.591526)
		(width 0.1143)
		(layer "In13.Cu")
		(net "P5E_CPU1_P0_RX_DN<7>")
	)
	(arc
		(start 103.76916 -289.13074)
		(mid 103.525833 -288.666174)
		(end 103.76916 -288.201608)
		(width 0.1143)
		(layer "In13.Cu")
		(net "P5E_CPU1_P0_RX_DN<7>")
	)
	(arc
		(start 103.838756 -293.021004)
		(mid 103.995733 -292.716204)
		(end 103.838756 -292.411404)
		(width 0.1143)
		(layer "In13.Cu")
		(net "P5E_CPU1_P0_RX_DN<7>")
	)
	(arc
		(start 103.76916 -282.650946)
		(mid 103.525833 -282.18638)
		(end 103.76916 -281.721814)
		(width 0.1143)
		(layer "In13.Cu")
		(net "P5E_CPU1_P0_RX_DN<7>")
	)
	(arc
		(start 103.838756 -291.400992)
		(mid 103.995733 -291.096192)
		(end 103.838756 -290.791392)
		(width 0.1143)
		(layer "In13.Cu")
		(net "P5E_CPU1_P0_RX_DN<7>")
	)
	(arc
		(start 103.684832 -295.617646)
		(mid 103.592931 -295.442323)
		(end 103.53802 -295.25214)
		(width 0.1143)
		(layer "In13.Cu")
		(net "P5E_CPU1_P0_RX_DN<7>")
	)
	(arc
		(start 131.435348 -372.80469)
		(mid 131.67332 -372.638746)
		(end 131.954016 -372.565422)
		(width 0.14224)
		(layer "In13.Cu")
		(net "P5E_CPU1_P0_RX_DN<7>")
	)
	(arc
		(start 103.838756 -281.681174)
		(mid 103.995733 -281.376374)
		(end 103.838756 -281.071574)
		(width 0.1143)
		(layer "In13.Cu")
		(net "P5E_CPU1_P0_RX_DN<7>")
	)
	(arc
		(start 103.838756 -294.641016)
		(mid 103.995733 -294.336216)
		(end 103.838756 -294.031416)
		(width 0.1143)
		(layer "In13.Cu")
		(net "P5E_CPU1_P0_RX_DN<7>")
	)
	(arc
		(start 103.76916 -293.990776)
		(mid 103.525833 -293.52621)
		(end 103.76916 -293.061644)
		(width 0.1143)
		(layer "In13.Cu")
		(net "P5E_CPU1_P0_RX_DN<7>")
	)
	(arc
		(start 103.7717 -287.512506)
		(mid 103.591048 -287.309761)
		(end 103.525828 -287.046162)
		(width 0.1143)
		(layer "In13.Cu")
		(net "P5E_CPU1_P0_RX_DN<7>")
	)
	(arc
		(start 103.53802 -295.25214)
		(mid 103.554378 -294.98691)
		(end 103.69169 -294.75938)
		(width 0.1143)
		(layer "In13.Cu")
		(net "P5E_CPU1_P0_RX_DN<7>")
	)
	(arc
		(start 103.838756 -289.78098)
		(mid 103.995733 -289.47618)
		(end 103.838756 -289.17138)
		(width 0.1143)
		(layer "In13.Cu")
		(net "P5E_CPU1_P0_RX_DN<7>")
	)
	(arc
		(start 103.995728 -286.23641)
		(mid 103.954179 -286.064988)
		(end 103.838756 -285.93161)
		(width 0.1143)
		(layer "In13.Cu")
		(net "P5E_CPU1_P0_RX_DN<7>")
	)
	(arc
		(start 103.76916 -276.170898)
		(mid 103.525833 -275.706332)
		(end 103.76916 -275.241766)
		(width 0.1143)
		(layer "In13.Cu")
		(net "P5E_CPU1_P0_RX_DN<7>")
	)
	(arc
		(start 103.76916 -292.370764)
		(mid 103.525833 -291.906198)
		(end 103.76916 -291.441632)
		(width 0.1143)
		(layer "In13.Cu")
		(net "P5E_CPU1_P0_RX_DN<7>")
	)
	(arc
		(start 133.994906 -352.829368)
		(mid 133.974924 -352.758465)
		(end 133.957568 -352.686874)
		(width 0.14224)
		(layer "In13.Cu")
		(net "P5E_CPU1_P0_RX_DN<7>")
	)
	(arc
		(start 114.078512 -304.222404)
		(mid 114.036234 -304.164654)
		(end 113.981738 -304.118264)
		(width 0.14224)
		(layer "In13.Cu")
		(net "P5E_CPU1_P0_RX_DN<7>")
	)
	(arc
		(start 103.76916 -290.750752)
		(mid 103.525833 -290.286186)
		(end 103.76916 -289.82162)
		(width 0.1143)
		(layer "In13.Cu")
		(net "P5E_CPU1_P0_RX_DN<7>")
	)
	(arc
		(start 70.60311 -374.378728)
		(mid 71.103223 -374.186158)
		(end 71.635112 -374.120664)
		(width 0.14224)
		(layer "In13.Cu")
		(net "P5E_CPU1_P0_RX_DN<7>")
	)
	(arc
		(start 74.857356 -374.120664)
		(mid 75.013934 -374.151827)
		(end 75.146662 -374.240552)
		(width 0.14224)
		(layer "In13.Cu")
		(net "P5E_CPU1_P0_RX_DN<7>")
	)
	(arc
		(start 133.280404 -370.257578)
		(mid 133.522932 -370.095649)
		(end 133.808978 -370.038884)
		(width 0.14224)
		(layer "In13.Cu")
		(net "P5E_CPU1_P0_RX_DN<7>")
	)
	(arc
		(start 108.680758 -374.4341)
		(mid 109.629932 -374.622902)
		(end 110.434628 -375.16054)
		(width 0.14224)
		(layer "In13.Cu")
		(net "P5E_CPU1_P0_RX_DN<7>")
	)
	(arc
		(start 103.840788 -286.53994)
		(mid 103.954717 -286.406793)
		(end 103.995728 -286.23641)
		(width 0.1143)
		(layer "In13.Cu")
		(net "P5E_CPU1_P0_RX_DN<7>")
	)
	(arc
		(start 107.342686 -300.26864)
		(mid 107.117913 -300.126249)
		(end 106.916474 -299.95241)
		(width 0.14224)
		(layer "In13.Cu")
		(net "P5E_CPU1_P0_RX_DN<7>")
	)
	(arc
		(start 77.413104 -376.506994)
		(mid 77.837427 -376.790454)
		(end 78.337918 -376.890026)
		(width 0.14224)
		(layer "In13.Cu")
		(net "P5E_CPU1_P0_RX_DN<7>")
	)
	(arc
		(start 130.597402 -376.655076)
		(mid 130.652158 -376.621717)
		(end 130.694176 -376.573288)
		(width 0.14224)
		(layer "In13.Cu")
		(net "P5E_CPU1_P0_RX_DN<7>")
	)
	(segment
		(start 54.470554 -385.31038)
		(end 54.991254 -385.31038)
		(width 0.127)
		(layer "F.Cu")
		(net "P5E_CPU1_P0_RX_DN<6>")
	)
	(segment
		(start 104.08793 -271.390364)
		(end 103.621078 -271.656302)
		(width 0.12954)
		(layer "F.Cu")
		(net "P5E_CPU1_P0_RX_DN<6>")
	)
	(segment
		(start 132.013452 -366.13338)
		(end 132.013452 -365.550704)
		(width 0.14224)
		(layer "In13.Cu")
		(net "P5E_CPU1_P0_RX_DN<6>")
	)
	(segment
		(start 113.473992 -305.09083)
		(end 113.335054 -304.951892)
		(width 0.14224)
		(layer "In13.Cu")
		(net "P5E_CPU1_P0_RX_DN<6>")
	)
	(segment
		(start 102.898702 -276.211538)
		(end 102.829106 -276.170898)
		(width 0.1143)
		(layer "In13.Cu")
		(net "P5E_CPU1_P0_RX_DN<6>")
	)
	(segment
		(start 128.365758 -331.143356)
		(end 128.105408 -330.117958)
		(width 0.14224)
		(layer "In13.Cu")
		(net "P5E_CPU1_P0_RX_DN<6>")
	)
	(segment
		(start 129.376932 -367.519204)
		(end 129.514092 -367.382044)
		(width 0.14224)
		(layer "In13.Cu")
		(net "P5E_CPU1_P0_RX_DN<6>")
	)
	(segment
		(start 129.514092 -367.382044)
		(end 129.940812 -367.382044)
		(width 0.14224)
		(layer "In13.Cu")
		(net "P5E_CPU1_P0_RX_DN<6>")
	)
	(segment
		(start 113.335054 -304.951892)
		(end 110.74019 -303.218088)
		(width 0.14224)
		(layer "In13.Cu")
		(net "P5E_CPU1_P0_RX_DN<6>")
	)
	(segment
		(start 103.077264 -297.398186)
		(end 103.077264 -296.612564)
		(width 0.14224)
		(layer "In13.Cu")
		(net "P5E_CPU1_P0_RX_DN<6>")
	)
	(segment
		(start 135.32485 -366.663224)
		(end 133.575552 -366.663224)
		(width 0.14224)
		(layer "In13.Cu")
		(net "P5E_CPU1_P0_RX_DN<6>")
	)
	(segment
		(start 115.676172 -308.646068)
		(end 114.198908 -306.435506)
		(width 0.14224)
		(layer "In13.Cu")
		(net "P5E_CPU1_P0_RX_DN<6>")
	)
	(segment
		(start 131.876292 -366.69726)
		(end 131.876292 -366.27054)
		(width 0.14224)
		(layer "In13.Cu")
		(net "P5E_CPU1_P0_RX_DN<6>")
	)
	(segment
		(start 103.077264 -296.612564)
		(end 103.077264 -296.584116)
		(width 0.1143)
		(layer "In13.Cu")
		(net "P5E_CPU1_P0_RX_DN<6>")
	)
	(segment
		(start 63.677038 -368.254026)
		(end 65.379092 -366.892332)
		(width 0.14224)
		(layer "In13.Cu")
		(net "P5E_CPU1_P0_RX_DN<6>")
	)
	(segment
		(start 75.571858 -368.905282)
		(end 75.714098 -368.763042)
		(width 0.14224)
		(layer "In13.Cu")
		(net "P5E_CPU1_P0_RX_DN<6>")
	)
	(segment
		(start 103.077264 -296.584116)
		(end 103.122984 -296.538396)
		(width 0.1143)
		(layer "In13.Cu")
		(net "P5E_CPU1_P0_RX_DN<6>")
	)
	(segment
		(start 135.32485 -365.243364)
		(end 135.63219 -365.550704)
		(width 0.14224)
		(layer "In13.Cu")
		(net "P5E_CPU1_P0_RX_DN<6>")
	)
	(segment
		(start 128.105154 -330.117958)
		(end 127.845312 -329.093322)
		(width 0.14224)
		(layer "In13.Cu")
		(net "P5E_CPU1_P0_RX_DN<6>")
	)
	(segment
		(start 74.200512 -368.049302)
		(end 73.893172 -367.741962)
		(width 0.14224)
		(layer "In13.Cu")
		(net "P5E_CPU1_P0_RX_DN<6>")
	)
	(segment
		(start 121.0056 -315.65088)
		(end 115.676172 -308.646068)
		(width 0.14224)
		(layer "In13.Cu")
		(net "P5E_CPU1_P0_RX_DN<6>")
	)
	(segment
		(start 102.83063 -289.820604)
		(end 102.899718 -289.780218)
		(width 0.1143)
		(layer "In13.Cu")
		(net "P5E_CPU1_P0_RX_DN<6>")
	)
	(segment
		(start 102.829106 -283.341826)
		(end 102.898702 -283.301186)
		(width 0.1143)
		(layer "In13.Cu")
		(net "P5E_CPU1_P0_RX_DN<6>")
	)
	(segment
		(start 75.714098 -368.763042)
		(end 75.714098 -368.191542)
		(width 0.14224)
		(layer "In13.Cu")
		(net "P5E_CPU1_P0_RX_DN<6>")
	)
	(segment
		(start 108.542328 -366.629442)
		(end 108.849668 -366.936782)
		(width 0.14224)
		(layer "In13.Cu")
		(net "P5E_CPU1_P0_RX_DN<6>")
	)
	(segment
		(start 103.326184 -272.795746)
		(end 103.329232 -272.793714)
		(width 0.1143)
		(layer "In13.Cu")
		(net "P5E_CPU1_P0_RX_DN<6>")
	)
	(segment
		(start 103.545132 -369.514882)
		(end 109.868208 -369.514882)
		(width 0.14224)
		(layer "In13.Cu")
		(net "P5E_CPU1_P0_RX_DN<6>")
	)
	(segment
		(start 130.832606 -344.389456)
		(end 128.365758 -331.143356)
		(width 0.14224)
		(layer "In13.Cu")
		(net "P5E_CPU1_P0_RX_DN<6>")
	)
	(segment
		(start 103.299006 -272.811748)
		(end 103.32212 -272.798032)
		(width 0.1143)
		(layer "In13.Cu")
		(net "P5E_CPU1_P0_RX_DN<6>")
	)
	(segment
		(start 135.63219 -365.550704)
		(end 135.63219 -366.355884)
		(width 0.14224)
		(layer "In13.Cu")
		(net "P5E_CPU1_P0_RX_DN<6>")
	)
	(segment
		(start 103.330248 -272.793206)
		(end 103.343964 -272.785332)
		(width 0.1143)
		(layer "In13.Cu")
		(net "P5E_CPU1_P0_RX_DN<6>")
	)
	(segment
		(start 73.037192 -368.763042)
		(end 73.179432 -368.905282)
		(width 0.14224)
		(layer "In13.Cu")
		(net "P5E_CPU1_P0_RX_DN<6>")
	)
	(segment
		(start 133.433312 -366.805464)
		(end 133.433312 -367.392204)
		(width 0.14224)
		(layer "In13.Cu")
		(net "P5E_CPU1_P0_RX_DN<6>")
	)
	(segment
		(start 55.344568 -385.405376)
		(end 55.345076 -385.404868)
		(width 0.14224)
		(layer "In13.Cu")
		(net "P5E_CPU1_P0_RX_DN<6>")
	)
	(segment
		(start 72.729852 -366.629442)
		(end 73.037192 -366.936782)
		(width 0.14224)
		(layer "In13.Cu")
		(net "P5E_CPU1_P0_RX_DN<6>")
	)
	(segment
		(start 55.946294 -380.714758)
		(end 63.341758 -368.634264)
		(width 0.14224)
		(layer "In13.Cu")
		(net "P5E_CPU1_P0_RX_DN<6>")
	)
	(segment
		(start 102.829106 -278.48179)
		(end 102.898702 -278.44115)
		(width 0.1143)
		(layer "In13.Cu")
		(net "P5E_CPU1_P0_RX_DN<6>")
	)
	(segment
		(start 102.829106 -276.861778)
		(end 102.898702 -276.821138)
		(width 0.1143)
		(layer "In13.Cu")
		(net "P5E_CPU1_P0_RX_DN<6>")
	)
	(segment
		(start 131.876292 -366.27054)
		(end 132.013452 -366.13338)
		(width 0.14224)
		(layer "In13.Cu")
		(net "P5E_CPU1_P0_RX_DN<6>")
	)
	(segment
		(start 55.14975 -384.84683)
		(end 55.154576 -384.234944)
		(width 0.14224)
		(layer "In13.Cu")
		(net "P5E_CPU1_P0_RX_DN<6>")
	)
	(segment
		(start 102.585774 -295.37025)
		(end 102.585774 -295.133014)
		(width 0.1143)
		(layer "In13.Cu")
		(net "P5E_CPU1_P0_RX_DN<6>")
	)
	(segment
		(start 103.329232 -272.793714)
		(end 103.330248 -272.793206)
		(width 0.1143)
		(layer "In13.Cu")
		(net "P5E_CPU1_P0_RX_DN<6>")
	)
	(segment
		(start 103.041958 -296.112184)
		(end 102.787958 -295.858184)
		(width 0.1143)
		(layer "In13.Cu")
		(net "P5E_CPU1_P0_RX_DN<6>")
	)
	(segment
		(start 135.63219 -366.355884)
		(end 135.32485 -366.663224)
		(width 0.14224)
		(layer "In13.Cu")
		(net "P5E_CPU1_P0_RX_DN<6>")
	)
	(segment
		(start 108.542328 -368.354102)
		(end 103.545132 -368.354102)
		(width 0.14224)
		(layer "In13.Cu")
		(net "P5E_CPU1_P0_RX_DN<6>")
	)
	(segment
		(start 102.830122 -293.061136)
		(end 102.83698 -293.057072)
		(width 0.1143)
		(layer "In13.Cu")
		(net "P5E_CPU1_P0_RX_DN<6>")
	)
	(segment
		(start 55.466742 -385.163822)
		(end 55.14975 -384.84683)
		(width 0.14224)
		(layer "In13.Cu")
		(net "P5E_CPU1_P0_RX_DN<6>")
	)
	(segment
		(start 106.180382 -300.67123)
		(end 103.197152 -297.687746)
		(width 0.14224)
		(layer "In13.Cu")
		(net "P5E_CPU1_P0_RX_DN<6>")
	)
	(segment
		(start 130.077972 -367.519204)
		(end 130.504692 -367.519204)
		(width 0.14224)
		(layer "In13.Cu")
		(net "P5E_CPU1_P0_RX_DN<6>")
	)
	(segment
		(start 108.849668 -366.936782)
		(end 108.849668 -368.046762)
		(width 0.14224)
		(layer "In13.Cu")
		(net "P5E_CPU1_P0_RX_DN<6>")
	)
	(segment
		(start 74.200512 -366.629442)
		(end 108.542328 -366.629442)
		(width 0.14224)
		(layer "In13.Cu")
		(net "P5E_CPU1_P0_RX_DN<6>")
	)
	(segment
		(start 55.458614 -383.93116)
		(end 55.458614 -382.921764)
		(width 0.14224)
		(layer "In13.Cu")
		(net "P5E_CPU1_P0_RX_DN<6>")
	)
	(segment
		(start 108.849668 -368.046762)
		(end 108.542328 -368.354102)
		(width 0.14224)
		(layer "In13.Cu")
		(net "P5E_CPU1_P0_RX_DN<6>")
	)
	(segment
		(start 73.037192 -366.936782)
		(end 73.037192 -368.763042)
		(width 0.14224)
		(layer "In13.Cu")
		(net "P5E_CPU1_P0_RX_DN<6>")
	)
	(segment
		(start 110.74019 -303.218088)
		(end 106.708448 -301.062898)
		(width 0.14224)
		(layer "In13.Cu")
		(net "P5E_CPU1_P0_RX_DN<6>")
	)
	(segment
		(start 103.122984 -296.538396)
		(end 103.122984 -296.307764)
		(width 0.1143)
		(layer "In13.Cu")
		(net "P5E_CPU1_P0_RX_DN<6>")
	)
	(segment
		(start 103.98887 -271.726152)
		(end 103.91902 -271.656302)
		(width 0.1143)
		(layer "In13.Cu")
		(net "P5E_CPU1_P0_RX_DN<6>")
	)
	(segment
		(start 102.899972 -285.932372)
		(end 102.829106 -285.89097)
		(width 0.1143)
		(layer "In13.Cu")
		(net "P5E_CPU1_P0_RX_DN<6>")
	)
	(segment
		(start 130.504692 -367.519204)
		(end 130.641852 -367.382044)
		(width 0.14224)
		(layer "In13.Cu")
		(net "P5E_CPU1_P0_RX_DN<6>")
	)
	(segment
		(start 55.466742 -385.334764)
		(end 55.466742 -385.163822)
		(width 0.14224)
		(layer "In13.Cu")
		(net "P5E_CPU1_P0_RX_DN<6>")
	)
	(segment
		(start 131.205732 -367.519204)
		(end 131.886452 -367.519204)
		(width 0.14224)
		(layer "In13.Cu")
		(net "P5E_CPU1_P0_RX_DN<6>")
	)
	(segment
		(start 102.899972 -290.792154)
		(end 102.83063 -290.751768)
		(width 0.1143)
		(layer "In13.Cu")
		(net "P5E_CPU1_P0_RX_DN<6>")
	)
	(segment
		(start 102.898702 -277.83155)
		(end 102.829106 -277.79091)
		(width 0.1143)
		(layer "In13.Cu")
		(net "P5E_CPU1_P0_RX_DN<6>")
	)
	(segment
		(start 133.433312 -367.392204)
		(end 133.560312 -367.519204)
		(width 0.14224)
		(layer "In13.Cu")
		(net "P5E_CPU1_P0_RX_DN<6>")
	)
	(segment
		(start 55.345076 -385.404868)
		(end 55.466742 -385.334764)
		(width 0.14224)
		(layer "In13.Cu")
		(net "P5E_CPU1_P0_RX_DN<6>")
	)
	(segment
		(start 132.013452 -367.392204)
		(end 132.013452 -366.83442)
		(width 0.14224)
		(layer "In13.Cu")
		(net "P5E_CPU1_P0_RX_DN<6>")
	)
	(segment
		(start 102.837742 -293.056564)
		(end 102.899718 -293.020242)
		(width 0.1143)
		(layer "In13.Cu")
		(net "P5E_CPU1_P0_RX_DN<6>")
	)
	(segment
		(start 133.125464 -353.544632)
		(end 130.832606 -344.389456)
		(width 0.14224)
		(layer "In13.Cu")
		(net "P5E_CPU1_P0_RX_DN<6>")
	)
	(segment
		(start 126.500382 -324.936612)
		(end 124.778516 -321.2973)
		(width 0.14224)
		(layer "In13.Cu")
		(net "P5E_CPU1_P0_RX_DN<6>")
	)
	(segment
		(start 66.129662 -366.629442)
		(end 72.729852 -366.629442)
		(width 0.14224)
		(layer "In13.Cu")
		(net "P5E_CPU1_P0_RX_DN<6>")
	)
	(segment
		(start 131.068572 -367.382044)
		(end 131.205732 -367.519204)
		(width 0.14224)
		(layer "In13.Cu")
		(net "P5E_CPU1_P0_RX_DN<6>")
	)
	(segment
		(start 133.560312 -367.519204)
		(end 135.800338 -367.519204)
		(width 0.14224)
		(layer "In13.Cu")
		(net "P5E_CPU1_P0_RX_DN<6>")
	)
	(segment
		(start 103.402892 -368.496342)
		(end 103.402892 -369.372642)
		(width 0.14224)
		(layer "In13.Cu")
		(net "P5E_CPU1_P0_RX_DN<6>")
	)
	(segment
		(start 102.828344 -286.58185)
		(end 102.899718 -286.540448)
		(width 0.1143)
		(layer "In13.Cu")
		(net "P5E_CPU1_P0_RX_DN<6>")
	)
	(segment
		(start 102.829106 -275.241766)
		(end 102.898702 -275.201126)
		(width 0.1143)
		(layer "In13.Cu")
		(net "P5E_CPU1_P0_RX_DN<6>")
	)
	(segment
		(start 132.013452 -365.550704)
		(end 132.320792 -365.243364)
		(width 0.14224)
		(layer "In13.Cu")
		(net "P5E_CPU1_P0_RX_DN<6>")
	)
	(segment
		(start 136.717278 -366.602264)
		(end 136.717278 -365.383064)
		(width 0.14224)
		(layer "In13.Cu")
		(net "P5E_CPU1_P0_RX_DN<6>")
	)
	(segment
		(start 73.179432 -368.905282)
		(end 75.571858 -368.905282)
		(width 0.14224)
		(layer "In13.Cu")
		(net "P5E_CPU1_P0_RX_DN<6>")
	)
	(segment
		(start 54.991254 -385.31038)
		(end 55.344568 -385.405376)
		(width 0.14224)
		(layer "In13.Cu")
		(net "P5E_CPU1_P0_RX_DN<6>")
	)
	(segment
		(start 110.010448 -369.372642)
		(end 110.010448 -367.811304)
		(width 0.14224)
		(layer "In13.Cu")
		(net "P5E_CPU1_P0_RX_DN<6>")
	)
	(segment
		(start 114.198908 -306.435506)
		(end 113.49609 -305.121056)
		(width 0.14224)
		(layer "In13.Cu")
		(net "P5E_CPU1_P0_RX_DN<6>")
	)
	(segment
		(start 75.571858 -368.049302)
		(end 74.200512 -368.049302)
		(width 0.14224)
		(layer "In13.Cu")
		(net "P5E_CPU1_P0_RX_DN<6>")
	)
	(segment
		(start 109.868208 -369.514882)
		(end 110.010448 -369.372642)
		(width 0.14224)
		(layer "In13.Cu")
		(net "P5E_CPU1_P0_RX_DN<6>")
	)
	(segment
		(start 110.010448 -367.811304)
		(end 110.302548 -367.519204)
		(width 0.14224)
		(layer "In13.Cu")
		(net "P5E_CPU1_P0_RX_DN<6>")
	)
	(segment
		(start 103.76916 -272.001742)
		(end 103.838756 -271.961102)
		(width 0.1143)
		(layer "In13.Cu")
		(net "P5E_CPU1_P0_RX_DN<6>")
	)
	(segment
		(start 73.893172 -366.936782)
		(end 74.200512 -366.629442)
		(width 0.14224)
		(layer "In13.Cu")
		(net "P5E_CPU1_P0_RX_DN<6>")
	)
	(segment
		(start 103.402892 -369.372642)
		(end 103.545132 -369.514882)
		(width 0.14224)
		(layer "In13.Cu")
		(net "P5E_CPU1_P0_RX_DN<6>")
	)
	(segment
		(start 102.898702 -284.311598)
		(end 102.829106 -284.270958)
		(width 0.1143)
		(layer "In13.Cu")
		(net "P5E_CPU1_P0_RX_DN<6>")
	)
	(segment
		(start 133.575552 -366.663224)
		(end 133.433312 -366.805464)
		(width 0.14224)
		(layer "In13.Cu")
		(net "P5E_CPU1_P0_RX_DN<6>")
	)
	(segment
		(start 102.899972 -292.412166)
		(end 102.83063 -292.37178)
		(width 0.1143)
		(layer "In13.Cu")
		(net "P5E_CPU1_P0_RX_DN<6>")
	)
	(segment
		(start 75.714098 -368.191542)
		(end 75.571858 -368.049302)
		(width 0.14224)
		(layer "In13.Cu")
		(net "P5E_CPU1_P0_RX_DN<6>")
	)
	(segment
		(start 102.898702 -282.691586)
		(end 102.829106 -282.650946)
		(width 0.1143)
		(layer "In13.Cu")
		(net "P5E_CPU1_P0_RX_DN<6>")
	)
	(segment
		(start 132.320792 -365.243364)
		(end 135.32485 -365.243364)
		(width 0.14224)
		(layer "In13.Cu")
		(net "P5E_CPU1_P0_RX_DN<6>")
	)
	(segment
		(start 102.898702 -281.071574)
		(end 102.829106 -281.030934)
		(width 0.1143)
		(layer "In13.Cu")
		(net "P5E_CPU1_P0_RX_DN<6>")
	)
	(segment
		(start 102.898702 -274.591526)
		(end 102.829106 -274.550886)
		(width 0.1143)
		(layer "In13.Cu")
		(net "P5E_CPU1_P0_RX_DN<6>")
	)
	(segment
		(start 102.829106 -281.721814)
		(end 102.898702 -281.681174)
		(width 0.1143)
		(layer "In13.Cu")
		(net "P5E_CPU1_P0_RX_DN<6>")
	)
	(segment
		(start 110.302548 -367.519204)
		(end 129.376932 -367.519204)
		(width 0.14224)
		(layer "In13.Cu")
		(net "P5E_CPU1_P0_RX_DN<6>")
	)
	(segment
		(start 102.829106 -273.621754)
		(end 102.898702 -273.581114)
		(width 0.1143)
		(layer "In13.Cu")
		(net "P5E_CPU1_P0_RX_DN<6>")
	)
	(segment
		(start 132.013452 -366.83442)
		(end 131.876292 -366.69726)
		(width 0.14224)
		(layer "In13.Cu")
		(net "P5E_CPU1_P0_RX_DN<6>")
	)
	(segment
		(start 102.829106 -280.101802)
		(end 102.898702 -280.061162)
		(width 0.1143)
		(layer "In13.Cu")
		(net "P5E_CPU1_P0_RX_DN<6>")
	)
	(segment
		(start 103.91902 -271.656302)
		(end 103.621078 -271.656302)
		(width 0.1143)
		(layer "In13.Cu")
		(net "P5E_CPU1_P0_RX_DN<6>")
	)
	(segment
		(start 130.641852 -367.382044)
		(end 131.068572 -367.382044)
		(width 0.14224)
		(layer "In13.Cu")
		(net "P5E_CPU1_P0_RX_DN<6>")
	)
	(segment
		(start 103.343964 -272.785332)
		(end 103.344218 -272.785332)
		(width 0.1143)
		(layer "In13.Cu")
		(net "P5E_CPU1_P0_RX_DN<6>")
	)
	(segment
		(start 102.83063 -291.440616)
		(end 102.899718 -291.40023)
		(width 0.1143)
		(layer "In13.Cu")
		(net "P5E_CPU1_P0_RX_DN<6>")
	)
	(segment
		(start 136.717278 -365.383064)
		(end 133.125464 -353.544632)
		(width 0.14224)
		(layer "In13.Cu")
		(net "P5E_CPU1_P0_RX_DN<6>")
	)
	(segment
		(start 55.46725 -382.838198)
		(end 55.871364 -380.903226)
		(width 0.14224)
		(layer "In13.Cu")
		(net "P5E_CPU1_P0_RX_DN<6>")
	)
	(segment
		(start 103.346758 -272.784062)
		(end 103.361998 -272.775172)
		(width 0.1143)
		(layer "In13.Cu")
		(net "P5E_CPU1_P0_RX_DN<6>")
	)
	(segment
		(start 103.545132 -368.354102)
		(end 103.402892 -368.496342)
		(width 0.14224)
		(layer "In13.Cu")
		(net "P5E_CPU1_P0_RX_DN<6>")
	)
	(segment
		(start 129.940812 -367.382044)
		(end 130.077972 -367.519204)
		(width 0.14224)
		(layer "In13.Cu")
		(net "P5E_CPU1_P0_RX_DN<6>")
	)
	(segment
		(start 103.32212 -272.798032)
		(end 103.326184 -272.795746)
		(width 0.1143)
		(layer "In13.Cu")
		(net "P5E_CPU1_P0_RX_DN<6>")
	)
	(segment
		(start 102.898702 -279.451562)
		(end 102.829106 -279.410922)
		(width 0.1143)
		(layer "In13.Cu")
		(net "P5E_CPU1_P0_RX_DN<6>")
	)
	(segment
		(start 103.054404 -294.419782)
		(end 103.054404 -294.291766)
		(width 0.1143)
		(layer "In13.Cu")
		(net "P5E_CPU1_P0_RX_DN<6>")
	)
	(segment
		(start 103.344218 -272.785332)
		(end 103.346758 -272.784062)
		(width 0.1143)
		(layer "In13.Cu")
		(net "P5E_CPU1_P0_RX_DN<6>")
	)
	(segment
		(start 102.899972 -289.172142)
		(end 102.83063 -289.131756)
		(width 0.1143)
		(layer "In13.Cu")
		(net "P5E_CPU1_P0_RX_DN<6>")
	)
	(segment
		(start 128.105408 -330.117958)
		(end 128.105154 -330.117958)
		(width 0.14224)
		(layer "In13.Cu")
		(net "P5E_CPU1_P0_RX_DN<6>")
	)
	(segment
		(start 102.829106 -284.961838)
		(end 102.898702 -284.921198)
		(width 0.1143)
		(layer "In13.Cu")
		(net "P5E_CPU1_P0_RX_DN<6>")
	)
	(segment
		(start 55.154576 -384.234944)
		(end 55.458614 -383.93116)
		(width 0.14224)
		(layer "In13.Cu")
		(net "P5E_CPU1_P0_RX_DN<6>")
	)
	(segment
		(start 102.828344 -288.201862)
		(end 102.899718 -288.16046)
		(width 0.1143)
		(layer "In13.Cu")
		(net "P5E_CPU1_P0_RX_DN<6>")
	)
	(segment
		(start 73.893172 -367.741962)
		(end 73.893172 -366.936782)
		(width 0.14224)
		(layer "In13.Cu")
		(net "P5E_CPU1_P0_RX_DN<6>")
	)
	(segment
		(start 102.83698 -293.057072)
		(end 102.837742 -293.056564)
		(width 0.1143)
		(layer "In13.Cu")
		(net "P5E_CPU1_P0_RX_DN<6>")
	)
	(segment
		(start 124.778516 -321.2973)
		(end 121.0056 -315.65088)
		(width 0.14224)
		(layer "In13.Cu")
		(net "P5E_CPU1_P0_RX_DN<6>")
	)
	(segment
		(start 131.886452 -367.519204)
		(end 132.013452 -367.392204)
		(width 0.14224)
		(layer "In13.Cu")
		(net "P5E_CPU1_P0_RX_DN<6>")
	)
	(segment
		(start 127.845312 -329.093322)
		(end 126.500382 -324.936612)
		(width 0.14224)
		(layer "In13.Cu")
		(net "P5E_CPU1_P0_RX_DN<6>")
	)
	(segment
		(start 102.89794 -287.55086)
		(end 102.83063 -287.511744)
		(width 0.1143)
		(layer "In13.Cu")
		(net "P5E_CPU1_P0_RX_DN<6>")
	)
	(arc
		(start 102.83063 -289.131756)
		(mid 102.650838 -288.929168)
		(end 102.586028 -288.666174)
		(width 0.1143)
		(layer "In13.Cu")
		(net "P5E_CPU1_P0_RX_DN<6>")
	)
	(arc
		(start 102.829106 -279.410922)
		(mid 102.585779 -278.946356)
		(end 102.829106 -278.48179)
		(width 0.1143)
		(layer "In13.Cu")
		(net "P5E_CPU1_P0_RX_DN<6>")
	)
	(arc
		(start 102.586028 -288.666174)
		(mid 102.650204 -288.404287)
		(end 102.828344 -288.201862)
		(width 0.1143)
		(layer "In13.Cu")
		(net "P5E_CPU1_P0_RX_DN<6>")
	)
	(arc
		(start 63.341758 -368.634264)
		(mid 63.492872 -368.429573)
		(end 63.677038 -368.254026)
		(width 0.14224)
		(layer "In13.Cu")
		(net "P5E_CPU1_P0_RX_DN<6>")
	)
	(arc
		(start 102.865428 -294.001698)
		(mid 102.770946 -293.942157)
		(end 102.694232 -293.860982)
		(width 0.1143)
		(layer "In13.Cu")
		(net "P5E_CPU1_P0_RX_DN<6>")
	)
	(arc
		(start 103.506524 -272.55089)
		(mid 103.519989 -272.495127)
		(end 103.526336 -272.438114)
		(width 0.1143)
		(layer "In13.Cu")
		(net "P5E_CPU1_P0_RX_DN<6>")
	)
	(arc
		(start 103.028242 -294.16756)
		(mid 102.961893 -294.069847)
		(end 102.865428 -294.001698)
		(width 0.1143)
		(layer "In13.Cu")
		(net "P5E_CPU1_P0_RX_DN<6>")
	)
	(arc
		(start 102.83063 -287.511744)
		(mid 102.650838 -287.309156)
		(end 102.586028 -287.046162)
		(width 0.1143)
		(layer "In13.Cu")
		(net "P5E_CPU1_P0_RX_DN<6>")
	)
	(arc
		(start 102.898702 -283.301186)
		(mid 103.055679 -282.996386)
		(end 102.898702 -282.691586)
		(width 0.1143)
		(layer "In13.Cu")
		(net "P5E_CPU1_P0_RX_DN<6>")
	)
	(arc
		(start 102.592632 -295.468294)
		(mid 102.587455 -295.419394)
		(end 102.585774 -295.37025)
		(width 0.1143)
		(layer "In13.Cu")
		(net "P5E_CPU1_P0_RX_DN<6>")
	)
	(arc
		(start 113.49609 -305.121056)
		(mid 113.486156 -305.105128)
		(end 113.473992 -305.09083)
		(width 0.14224)
		(layer "In13.Cu")
		(net "P5E_CPU1_P0_RX_DN<6>")
	)
	(arc
		(start 102.694232 -293.860982)
		(mid 102.592703 -293.436696)
		(end 102.82301 -293.066216)
		(width 0.1143)
		(layer "In13.Cu")
		(net "P5E_CPU1_P0_RX_DN<6>")
	)
	(arc
		(start 103.01478 -294.540686)
		(mid 103.04429 -294.483412)
		(end 103.054404 -294.419782)
		(width 0.1143)
		(layer "In13.Cu")
		(net "P5E_CPU1_P0_RX_DN<6>")
	)
	(arc
		(start 102.718362 -294.780462)
		(mid 102.791054 -294.712157)
		(end 102.875334 -294.658796)
		(width 0.1143)
		(layer "In13.Cu")
		(net "P5E_CPU1_P0_RX_DN<6>")
	)
	(arc
		(start 102.829106 -282.650946)
		(mid 102.585779 -282.18638)
		(end 102.829106 -281.721814)
		(width 0.1143)
		(layer "In13.Cu")
		(net "P5E_CPU1_P0_RX_DN<6>")
	)
	(arc
		(start 102.829106 -274.550886)
		(mid 102.585779 -274.08632)
		(end 102.829106 -273.621754)
		(width 0.1143)
		(layer "In13.Cu")
		(net "P5E_CPU1_P0_RX_DN<6>")
	)
	(arc
		(start 102.585774 -295.133014)
		(mid 102.619983 -294.944676)
		(end 102.718362 -294.780462)
		(width 0.1143)
		(layer "In13.Cu")
		(net "P5E_CPU1_P0_RX_DN<6>")
	)
	(arc
		(start 102.829106 -281.030934)
		(mid 102.585779 -280.566368)
		(end 102.829106 -280.101802)
		(width 0.1143)
		(layer "In13.Cu")
		(net "P5E_CPU1_P0_RX_DN<6>")
	)
	(arc
		(start 102.875334 -294.658796)
		(mid 102.951969 -294.607906)
		(end 103.01478 -294.540686)
		(width 0.1143)
		(layer "In13.Cu")
		(net "P5E_CPU1_P0_RX_DN<6>")
	)
	(arc
		(start 55.458614 -382.921764)
		(mid 55.460798 -382.879761)
		(end 55.46725 -382.838198)
		(width 0.14224)
		(layer "In13.Cu")
		(net "P5E_CPU1_P0_RX_DN<6>")
	)
	(arc
		(start 102.899718 -288.16046)
		(mid 103.055543 -287.855256)
		(end 102.89794 -287.55086)
		(width 0.1143)
		(layer "In13.Cu")
		(net "P5E_CPU1_P0_RX_DN<6>")
	)
	(arc
		(start 102.82301 -293.066216)
		(mid 102.826557 -293.063663)
		(end 102.830122 -293.061136)
		(width 0.1143)
		(layer "In13.Cu")
		(net "P5E_CPU1_P0_RX_DN<6>")
	)
	(arc
		(start 102.829106 -285.89097)
		(mid 102.585779 -285.426404)
		(end 102.829106 -284.961838)
		(width 0.1143)
		(layer "In13.Cu")
		(net "P5E_CPU1_P0_RX_DN<6>")
	)
	(arc
		(start 102.829106 -276.170898)
		(mid 102.585779 -275.706332)
		(end 102.829106 -275.241766)
		(width 0.1143)
		(layer "In13.Cu")
		(net "P5E_CPU1_P0_RX_DN<6>")
	)
	(arc
		(start 102.898702 -280.061162)
		(mid 103.055679 -279.756362)
		(end 102.898702 -279.451562)
		(width 0.1143)
		(layer "In13.Cu")
		(net "P5E_CPU1_P0_RX_DN<6>")
	)
	(arc
		(start 102.83063 -290.751768)
		(mid 102.585809 -290.286186)
		(end 102.83063 -289.820604)
		(width 0.1143)
		(layer "In13.Cu")
		(net "P5E_CPU1_P0_RX_DN<6>")
	)
	(arc
		(start 102.898702 -275.201126)
		(mid 103.055679 -274.896326)
		(end 102.898702 -274.591526)
		(width 0.1143)
		(layer "In13.Cu")
		(net "P5E_CPU1_P0_RX_DN<6>")
	)
	(arc
		(start 136.448546 -367.250472)
		(mid 136.647399 -366.953101)
		(end 136.717278 -366.602264)
		(width 0.14224)
		(layer "In13.Cu")
		(net "P5E_CPU1_P0_RX_DN<6>")
	)
	(arc
		(start 135.800338 -367.519204)
		(mid 136.151168 -367.449308)
		(end 136.448546 -367.250472)
		(width 0.14224)
		(layer "In13.Cu")
		(net "P5E_CPU1_P0_RX_DN<6>")
	)
	(arc
		(start 103.526336 -272.438114)
		(mid 103.595219 -272.195094)
		(end 103.763064 -272.006314)
		(width 0.1143)
		(layer "In13.Cu")
		(net "P5E_CPU1_P0_RX_DN<6>")
	)
	(arc
		(start 103.763064 -272.006314)
		(mid 103.766104 -272.004018)
		(end 103.76916 -272.001742)
		(width 0.1143)
		(layer "In13.Cu")
		(net "P5E_CPU1_P0_RX_DN<6>")
	)
	(arc
		(start 102.899718 -289.780218)
		(mid 103.055651 -289.476283)
		(end 102.899972 -289.172142)
		(width 0.1143)
		(layer "In13.Cu")
		(net "P5E_CPU1_P0_RX_DN<6>")
	)
	(arc
		(start 106.708448 -301.062898)
		(mid 106.429963 -300.886548)
		(end 106.180382 -300.67123)
		(width 0.14224)
		(layer "In13.Cu")
		(net "P5E_CPU1_P0_RX_DN<6>")
	)
	(arc
		(start 102.83063 -292.37178)
		(mid 102.585809 -291.906198)
		(end 102.83063 -291.440616)
		(width 0.1143)
		(layer "In13.Cu")
		(net "P5E_CPU1_P0_RX_DN<6>")
	)
	(arc
		(start 102.898702 -278.44115)
		(mid 103.055679 -278.13635)
		(end 102.898702 -277.83155)
		(width 0.1143)
		(layer "In13.Cu")
		(net "P5E_CPU1_P0_RX_DN<6>")
	)
	(arc
		(start 103.197152 -297.687746)
		(mid 103.108437 -297.554881)
		(end 103.077264 -297.398186)
		(width 0.14224)
		(layer "In13.Cu")
		(net "P5E_CPU1_P0_RX_DN<6>")
	)
	(arc
		(start 103.361998 -272.775172)
		(mid 103.449549 -272.672884)
		(end 103.506524 -272.55089)
		(width 0.1143)
		(layer "In13.Cu")
		(net "P5E_CPU1_P0_RX_DN<6>")
	)
	(arc
		(start 102.898702 -284.921198)
		(mid 103.055679 -284.616398)
		(end 102.898702 -284.311598)
		(width 0.1143)
		(layer "In13.Cu")
		(net "P5E_CPU1_P0_RX_DN<6>")
	)
	(arc
		(start 55.871364 -380.903226)
		(mid 55.900696 -380.805756)
		(end 55.946294 -380.714758)
		(width 0.14224)
		(layer "In13.Cu")
		(net "P5E_CPU1_P0_RX_DN<6>")
	)
	(arc
		(start 102.586028 -287.046162)
		(mid 102.650204 -286.784275)
		(end 102.828344 -286.58185)
		(width 0.1143)
		(layer "In13.Cu")
		(net "P5E_CPU1_P0_RX_DN<6>")
	)
	(arc
		(start 102.898702 -273.581114)
		(mid 103.014129 -273.447738)
		(end 103.055674 -273.276314)
		(width 0.1143)
		(layer "In13.Cu")
		(net "P5E_CPU1_P0_RX_DN<6>")
	)
	(arc
		(start 103.054404 -294.291766)
		(mid 103.047821 -294.228294)
		(end 103.028242 -294.16756)
		(width 0.1143)
		(layer "In13.Cu")
		(net "P5E_CPU1_P0_RX_DN<6>")
	)
	(arc
		(start 102.787958 -295.858184)
		(mid 102.658686 -295.679074)
		(end 102.592632 -295.468294)
		(width 0.1143)
		(layer "In13.Cu")
		(net "P5E_CPU1_P0_RX_DN<6>")
	)
	(arc
		(start 102.829106 -284.270958)
		(mid 102.585779 -283.806392)
		(end 102.829106 -283.341826)
		(width 0.1143)
		(layer "In13.Cu")
		(net "P5E_CPU1_P0_RX_DN<6>")
	)
	(arc
		(start 102.898702 -281.681174)
		(mid 103.055679 -281.376374)
		(end 102.898702 -281.071574)
		(width 0.1143)
		(layer "In13.Cu")
		(net "P5E_CPU1_P0_RX_DN<6>")
	)
	(arc
		(start 102.899718 -286.540448)
		(mid 103.055651 -286.236513)
		(end 102.899972 -285.932372)
		(width 0.1143)
		(layer "In13.Cu")
		(net "P5E_CPU1_P0_RX_DN<6>")
	)
	(arc
		(start 102.899718 -293.020242)
		(mid 103.055651 -292.716307)
		(end 102.899972 -292.412166)
		(width 0.1143)
		(layer "In13.Cu")
		(net "P5E_CPU1_P0_RX_DN<6>")
	)
	(arc
		(start 103.838756 -271.961102)
		(mid 103.936521 -271.858126)
		(end 103.98887 -271.726152)
		(width 0.1143)
		(layer "In13.Cu")
		(net "P5E_CPU1_P0_RX_DN<6>")
	)
	(arc
		(start 102.899718 -291.40023)
		(mid 103.055651 -291.096295)
		(end 102.899972 -290.792154)
		(width 0.1143)
		(layer "In13.Cu")
		(net "P5E_CPU1_P0_RX_DN<6>")
	)
	(arc
		(start 102.829106 -277.79091)
		(mid 102.585779 -277.326344)
		(end 102.829106 -276.861778)
		(width 0.1143)
		(layer "In13.Cu")
		(net "P5E_CPU1_P0_RX_DN<6>")
	)
	(arc
		(start 103.055674 -273.276314)
		(mid 103.120189 -273.014095)
		(end 103.299006 -272.811748)
		(width 0.1143)
		(layer "In13.Cu")
		(net "P5E_CPU1_P0_RX_DN<6>")
	)
	(arc
		(start 65.379092 -366.892332)
		(mid 65.731993 -366.696977)
		(end 66.129662 -366.629442)
		(width 0.14224)
		(layer "In13.Cu")
		(net "P5E_CPU1_P0_RX_DN<6>")
	)
	(arc
		(start 102.898702 -276.821138)
		(mid 103.055679 -276.516338)
		(end 102.898702 -276.211538)
		(width 0.1143)
		(layer "In13.Cu")
		(net "P5E_CPU1_P0_RX_DN<6>")
	)
	(arc
		(start 103.122984 -296.307764)
		(mid 103.101929 -296.201911)
		(end 103.041958 -296.112184)
		(width 0.1143)
		(layer "In13.Cu")
		(net "P5E_CPU1_P0_RX_DN<6>")
	)
	(segment
		(start 101.268022 -269.770352)
		(end 100.80117 -270.03629)
		(width 0.12954)
		(layer "F.Cu")
		(net "P5E_CPU1_P0_RX_DN<5>")
	)
	(segment
		(start 53.270658 -385.31038)
		(end 53.791358 -385.31038)
		(width 0.127)
		(layer "F.Cu")
		(net "P5E_CPU1_P0_RX_DN<5>")
	)
	(segment
		(start 53.95468 -384.234944)
		(end 54.258718 -383.93116)
		(width 0.14224)
		(layer "In13.Cu")
		(net "P5E_CPU1_P0_RX_DN<5>")
	)
	(segment
		(start 101.889052 -273.621754)
		(end 101.928168 -273.598894)
		(width 0.1143)
		(layer "In13.Cu")
		(net "P5E_CPU1_P0_RX_DN<5>")
	)
	(segment
		(start 54.266846 -385.334764)
		(end 54.266846 -385.163822)
		(width 0.14224)
		(layer "In13.Cu")
		(net "P5E_CPU1_P0_RX_DN<5>")
	)
	(segment
		(start 101.46411 -270.528542)
		(end 101.460808 -270.526764)
		(width 0.1143)
		(layer "In13.Cu")
		(net "P5E_CPU1_P0_RX_DN<5>")
	)
	(segment
		(start 101.959918 -285.932372)
		(end 101.889052 -285.89097)
		(width 0.1143)
		(layer "In13.Cu")
		(net "P5E_CPU1_P0_RX_DN<5>")
	)
	(segment
		(start 101.928168 -273.598894)
		(end 101.958648 -273.581114)
		(width 0.1143)
		(layer "In13.Cu")
		(net "P5E_CPU1_P0_RX_DN<5>")
	)
	(segment
		(start 101.928168 -281.698954)
		(end 101.958648 -281.681174)
		(width 0.1143)
		(layer "In13.Cu")
		(net "P5E_CPU1_P0_RX_DN<5>")
	)
	(segment
		(start 101.889052 -284.961838)
		(end 101.928168 -284.938978)
		(width 0.1143)
		(layer "In13.Cu")
		(net "P5E_CPU1_P0_RX_DN<5>")
	)
	(segment
		(start 101.099112 -270.03629)
		(end 100.80117 -270.03629)
		(width 0.1143)
		(layer "In13.Cu")
		(net "P5E_CPU1_P0_RX_DN<5>")
	)
	(segment
		(start 102.070154 -296.436288)
		(end 102.070154 -296.40784)
		(width 0.1143)
		(layer "In13.Cu")
		(net "P5E_CPU1_P0_RX_DN<5>")
	)
	(segment
		(start 101.958648 -284.311598)
		(end 101.928168 -284.293818)
		(width 0.1143)
		(layer "In13.Cu")
		(net "P5E_CPU1_P0_RX_DN<5>")
	)
	(segment
		(start 101.890576 -291.440616)
		(end 101.959664 -291.40023)
		(width 0.1143)
		(layer "In13.Cu")
		(net "P5E_CPU1_P0_RX_DN<5>")
	)
	(segment
		(start 101.958648 -274.591526)
		(end 101.928168 -274.573746)
		(width 0.1143)
		(layer "In13.Cu")
		(net "P5E_CPU1_P0_RX_DN<5>")
	)
	(segment
		(start 119.797576 -364.275878)
		(end 124.543566 -364.275878)
		(width 0.14224)
		(layer "In13.Cu")
		(net "P5E_CPU1_P0_RX_DN<5>")
	)
	(segment
		(start 101.959918 -290.792154)
		(end 101.890576 -290.751768)
		(width 0.1143)
		(layer "In13.Cu")
		(net "P5E_CPU1_P0_RX_DN<5>")
	)
	(segment
		(start 127.799846 -365.656114)
		(end 127.230632 -365.0869)
		(width 0.14224)
		(layer "In13.Cu")
		(net "P5E_CPU1_P0_RX_DN<5>")
	)
	(segment
		(start 129.970784 -344.891106)
		(end 128.143254 -335.69656)
		(width 0.14224)
		(layer "In13.Cu")
		(net "P5E_CPU1_P0_RX_DN<5>")
	)
	(segment
		(start 54.266846 -385.163822)
		(end 53.949854 -384.84683)
		(width 0.14224)
		(layer "In13.Cu")
		(net "P5E_CPU1_P0_RX_DN<5>")
	)
	(segment
		(start 133.007354 -357.009446)
		(end 129.970784 -344.891106)
		(width 0.14224)
		(layer "In13.Cu")
		(net "P5E_CPU1_P0_RX_DN<5>")
	)
	(segment
		(start 101.88829 -286.58185)
		(end 101.959664 -286.540448)
		(width 0.1143)
		(layer "In13.Cu")
		(net "P5E_CPU1_P0_RX_DN<5>")
	)
	(segment
		(start 126.2253 -366.414558)
		(end 126.65202 -366.414558)
		(width 0.14224)
		(layer "In13.Cu")
		(net "P5E_CPU1_P0_RX_DN<5>")
	)
	(segment
		(start 101.959918 -294.032178)
		(end 101.890576 -293.991792)
		(width 0.1143)
		(layer "In13.Cu")
		(net "P5E_CPU1_P0_RX_DN<5>")
	)
	(segment
		(start 101.958648 -277.83155)
		(end 101.928168 -277.81377)
		(width 0.1143)
		(layer "In13.Cu")
		(net "P5E_CPU1_P0_RX_DN<5>")
	)
	(segment
		(start 101.958648 -279.451562)
		(end 101.928168 -279.433782)
		(width 0.1143)
		(layer "In13.Cu")
		(net "P5E_CPU1_P0_RX_DN<5>")
	)
	(segment
		(start 120.910096 -365.837978)
		(end 120.910096 -366.409478)
		(width 0.14224)
		(layer "In13.Cu")
		(net "P5E_CPU1_P0_RX_DN<5>")
	)
	(segment
		(start 101.928168 -284.293818)
		(end 101.889052 -284.270958)
		(width 0.1143)
		(layer "In13.Cu")
		(net "P5E_CPU1_P0_RX_DN<5>")
	)
	(segment
		(start 101.958648 -271.351502)
		(end 101.890576 -271.311878)
		(width 0.1143)
		(layer "In13.Cu")
		(net "P5E_CPU1_P0_RX_DN<5>")
	)
	(segment
		(start 125.147832 -324.360286)
		(end 122.317764 -319.364614)
		(width 0.14224)
		(layer "In13.Cu")
		(net "P5E_CPU1_P0_RX_DN<5>")
	)
	(segment
		(start 120.910096 -366.409478)
		(end 121.052336 -366.551718)
		(width 0.14224)
		(layer "In13.Cu")
		(net "P5E_CPU1_P0_RX_DN<5>")
	)
	(segment
		(start 101.958648 -281.071574)
		(end 101.928168 -281.053794)
		(width 0.1143)
		(layer "In13.Cu")
		(net "P5E_CPU1_P0_RX_DN<5>")
	)
	(segment
		(start 109.89691 -366.551718)
		(end 119.347996 -366.551718)
		(width 0.14224)
		(layer "In13.Cu")
		(net "P5E_CPU1_P0_RX_DN<5>")
	)
	(segment
		(start 127.230632 -365.0869)
		(end 127.230632 -364.652052)
		(width 0.14224)
		(layer "In13.Cu")
		(net "P5E_CPU1_P0_RX_DN<5>")
	)
	(segment
		(start 101.959918 -294.640254)
		(end 101.96068 -294.639746)
		(width 0.1143)
		(layer "In13.Cu")
		(net "P5E_CPU1_P0_RX_DN<5>")
	)
	(segment
		(start 101.928168 -279.433782)
		(end 101.889052 -279.410922)
		(width 0.1143)
		(layer "In13.Cu")
		(net "P5E_CPU1_P0_RX_DN<5>")
	)
	(segment
		(start 124.96038 -366.551718)
		(end 125.09754 -366.414558)
		(width 0.14224)
		(layer "In13.Cu")
		(net "P5E_CPU1_P0_RX_DN<5>")
	)
	(segment
		(start 133.85927 -360.232706)
		(end 133.658102 -360.232706)
		(width 0.14224)
		(layer "In13.Cu")
		(net "P5E_CPU1_P0_RX_DN<5>")
	)
	(segment
		(start 119.490236 -366.409478)
		(end 119.490236 -364.583218)
		(width 0.14224)
		(layer "In13.Cu")
		(net "P5E_CPU1_P0_RX_DN<5>")
	)
	(segment
		(start 119.490236 -364.583218)
		(end 119.797576 -364.275878)
		(width 0.14224)
		(layer "In13.Cu")
		(net "P5E_CPU1_P0_RX_DN<5>")
	)
	(segment
		(start 101.460808 -270.526764)
		(end 101.459538 -270.526002)
		(width 0.1143)
		(layer "In13.Cu")
		(net "P5E_CPU1_P0_RX_DN<5>")
	)
	(segment
		(start 101.6381 -295.228264)
		(end 101.6381 -295.121584)
		(width 0.1143)
		(layer "In13.Cu")
		(net "P5E_CPU1_P0_RX_DN<5>")
	)
	(segment
		(start 53.949854 -384.84683)
		(end 53.95468 -384.234944)
		(width 0.14224)
		(layer "In13.Cu")
		(net "P5E_CPU1_P0_RX_DN<5>")
	)
	(segment
		(start 101.957632 -294.641524)
		(end 101.959918 -294.640254)
		(width 0.1143)
		(layer "In13.Cu")
		(net "P5E_CPU1_P0_RX_DN<5>")
	)
	(segment
		(start 101.889052 -276.861778)
		(end 101.928168 -276.838918)
		(width 0.1143)
		(layer "In13.Cu")
		(net "P5E_CPU1_P0_RX_DN<5>")
	)
	(segment
		(start 101.74859 -295.49471)
		(end 101.748336 -295.494456)
		(width 0.1143)
		(layer "In13.Cu")
		(net "P5E_CPU1_P0_RX_DN<5>")
	)
	(segment
		(start 125.09754 -366.414558)
		(end 125.52426 -366.414558)
		(width 0.14224)
		(layer "In13.Cu")
		(net "P5E_CPU1_P0_RX_DN<5>")
	)
	(segment
		(start 125.836172 -326.0217)
		(end 125.147832 -324.360286)
		(width 0.14224)
		(layer "In13.Cu")
		(net "P5E_CPU1_P0_RX_DN<5>")
	)
	(segment
		(start 101.437186 -270.513048)
		(end 101.434392 -270.510508)
		(width 0.1143)
		(layer "In13.Cu")
		(net "P5E_CPU1_P0_RX_DN<5>")
	)
	(segment
		(start 128.234694 -365.656114)
		(end 127.799846 -365.656114)
		(width 0.14224)
		(layer "In13.Cu")
		(net "P5E_CPU1_P0_RX_DN<5>")
	)
	(segment
		(start 101.748336 -295.494456)
		(end 101.748336 -295.494202)
		(width 0.1143)
		(layer "In13.Cu")
		(net "P5E_CPU1_P0_RX_DN<5>")
	)
	(segment
		(start 133.178042 -357.689912)
		(end 133.011418 -357.59009)
		(width 0.14224)
		(layer "In13.Cu")
		(net "P5E_CPU1_P0_RX_DN<5>")
	)
	(segment
		(start 125.52426 -366.414558)
		(end 125.66142 -366.551718)
		(width 0.14224)
		(layer "In13.Cu")
		(net "P5E_CPU1_P0_RX_DN<5>")
	)
	(segment
		(start 55.107332 -380.29515)
		(end 62.726824 -367.848642)
		(width 0.14224)
		(layer "In13.Cu")
		(net "P5E_CPU1_P0_RX_DN<5>")
	)
	(segment
		(start 101.889052 -278.48179)
		(end 101.928168 -278.45893)
		(width 0.1143)
		(layer "In13.Cu")
		(net "P5E_CPU1_P0_RX_DN<5>")
	)
	(segment
		(start 128.143254 -335.69656)
		(end 127.400812 -331.417676)
		(width 0.14224)
		(layer "In13.Cu")
		(net "P5E_CPU1_P0_RX_DN<5>")
	)
	(segment
		(start 65.86982 -365.69523)
		(end 108.818426 -365.69523)
		(width 0.14224)
		(layer "In13.Cu")
		(net "P5E_CPU1_P0_RX_DN<5>")
	)
	(segment
		(start 101.959918 -289.172142)
		(end 101.890576 -289.131756)
		(width 0.1143)
		(layer "In13.Cu")
		(net "P5E_CPU1_P0_RX_DN<5>")
	)
	(segment
		(start 101.928168 -281.053794)
		(end 101.889052 -281.030934)
		(width 0.1143)
		(layer "In13.Cu")
		(net "P5E_CPU1_P0_RX_DN<5>")
	)
	(segment
		(start 101.9556 -294.642794)
		(end 101.95687 -294.642032)
		(width 0.1143)
		(layer "In13.Cu")
		(net "P5E_CPU1_P0_RX_DN<5>")
	)
	(segment
		(start 62.820042 -367.74247)
		(end 64.998092 -366.000538)
		(width 0.14224)
		(layer "In13.Cu")
		(net "P5E_CPU1_P0_RX_DN<5>")
	)
	(segment
		(start 101.928168 -272.953734)
		(end 101.889052 -272.930874)
		(width 0.1143)
		(layer "In13.Cu")
		(net "P5E_CPU1_P0_RX_DN<5>")
	)
	(segment
		(start 115.070636 -309.592472)
		(end 112.806988 -306.203858)
		(width 0.14224)
		(layer "In13.Cu")
		(net "P5E_CPU1_P0_RX_DN<5>")
	)
	(segment
		(start 132.907532 -357.17607)
		(end 133.007354 -357.009446)
		(width 0.14224)
		(layer "In13.Cu")
		(net "P5E_CPU1_P0_RX_DN<5>")
	)
	(segment
		(start 101.88829 -288.201862)
		(end 101.959664 -288.16046)
		(width 0.1143)
		(layer "In13.Cu")
		(net "P5E_CPU1_P0_RX_DN<5>")
	)
	(segment
		(start 109.107986 -365.815118)
		(end 109.806994 -366.51438)
		(width 0.14224)
		(layer "In13.Cu")
		(net "P5E_CPU1_P0_RX_DN<5>")
	)
	(segment
		(start 101.957886 -287.55086)
		(end 101.890576 -287.511744)
		(width 0.1143)
		(layer "In13.Cu")
		(net "P5E_CPU1_P0_RX_DN<5>")
	)
	(segment
		(start 134.263892 -360.838496)
		(end 134.263892 -360.637328)
		(width 0.14224)
		(layer "In13.Cu")
		(net "P5E_CPU1_P0_RX_DN<5>")
	)
	(segment
		(start 110.911894 -304.527966)
		(end 106.4895 -302.19015)
		(width 0.14224)
		(layer "In13.Cu")
		(net "P5E_CPU1_P0_RX_DN<5>")
	)
	(segment
		(start 133.011418 -357.59009)
		(end 132.907532 -357.17607)
		(width 0.14224)
		(layer "In13.Cu")
		(net "P5E_CPU1_P0_RX_DN<5>")
	)
	(segment
		(start 105.79608 -301.67834)
		(end 102.276402 -298.158662)
		(width 0.14224)
		(layer "In13.Cu")
		(net "P5E_CPU1_P0_RX_DN<5>")
	)
	(segment
		(start 127.400812 -331.417676)
		(end 125.836172 -326.0217)
		(width 0.14224)
		(layer "In13.Cu")
		(net "P5E_CPU1_P0_RX_DN<5>")
	)
	(segment
		(start 101.928168 -283.318966)
		(end 101.958648 -283.301186)
		(width 0.1143)
		(layer "In13.Cu")
		(net "P5E_CPU1_P0_RX_DN<5>")
	)
	(segment
		(start 101.928168 -274.573746)
		(end 101.889052 -274.550886)
		(width 0.1143)
		(layer "In13.Cu")
		(net "P5E_CPU1_P0_RX_DN<5>")
	)
	(segment
		(start 101.889052 -281.721814)
		(end 101.928168 -281.698954)
		(width 0.1143)
		(layer "In13.Cu")
		(net "P5E_CPU1_P0_RX_DN<5>")
	)
	(segment
		(start 124.850906 -364.583218)
		(end 124.850906 -365.388398)
		(width 0.14224)
		(layer "In13.Cu")
		(net "P5E_CPU1_P0_RX_DN<5>")
	)
	(segment
		(start 126.65202 -366.414558)
		(end 126.78918 -366.551718)
		(width 0.14224)
		(layer "In13.Cu")
		(net "P5E_CPU1_P0_RX_DN<5>")
	)
	(segment
		(start 124.543566 -364.275878)
		(end 124.850906 -364.583218)
		(width 0.14224)
		(layer "In13.Cu")
		(net "P5E_CPU1_P0_RX_DN<5>")
	)
	(segment
		(start 134.263892 -360.637328)
		(end 133.85927 -360.232706)
		(width 0.14224)
		(layer "In13.Cu")
		(net "P5E_CPU1_P0_RX_DN<5>")
	)
	(segment
		(start 101.77145 -294.80002)
		(end 101.891084 -294.680386)
		(width 0.1143)
		(layer "In13.Cu")
		(net "P5E_CPU1_P0_RX_DN<5>")
	)
	(segment
		(start 126.08814 -366.551718)
		(end 126.2253 -366.414558)
		(width 0.14224)
		(layer "In13.Cu")
		(net "P5E_CPU1_P0_RX_DN<5>")
	)
	(segment
		(start 101.958648 -272.971514)
		(end 101.928168 -272.953734)
		(width 0.1143)
		(layer "In13.Cu")
		(net "P5E_CPU1_P0_RX_DN<5>")
	)
	(segment
		(start 101.959918 -292.412166)
		(end 101.890576 -292.37178)
		(width 0.1143)
		(layer "In13.Cu")
		(net "P5E_CPU1_P0_RX_DN<5>")
	)
	(segment
		(start 101.889052 -283.341826)
		(end 101.928168 -283.318966)
		(width 0.1143)
		(layer "In13.Cu")
		(net "P5E_CPU1_P0_RX_DN<5>")
	)
	(segment
		(start 101.928168 -284.938978)
		(end 101.958648 -284.921198)
		(width 0.1143)
		(layer "In13.Cu")
		(net "P5E_CPU1_P0_RX_DN<5>")
	)
	(segment
		(start 54.258718 -383.93116)
		(end 54.258718 -382.62052)
		(width 0.14224)
		(layer "In13.Cu")
		(net "P5E_CPU1_P0_RX_DN<5>")
	)
	(segment
		(start 101.80193 -295.547796)
		(end 101.74859 -295.49471)
		(width 0.1143)
		(layer "In13.Cu")
		(net "P5E_CPU1_P0_RX_DN<5>")
	)
	(segment
		(start 119.347996 -366.551718)
		(end 119.490236 -366.409478)
		(width 0.14224)
		(layer "In13.Cu")
		(net "P5E_CPU1_P0_RX_DN<5>")
	)
	(segment
		(start 101.977444 -295.665906)
		(end 101.88575 -295.612312)
		(width 0.1143)
		(layer "In13.Cu")
		(net "P5E_CPU1_P0_RX_DN<5>")
	)
	(segment
		(start 122.317764 -319.364614)
		(end 115.070636 -309.592472)
		(width 0.14224)
		(layer "In13.Cu")
		(net "P5E_CPU1_P0_RX_DN<5>")
	)
	(segment
		(start 101.890576 -293.060628)
		(end 101.959664 -293.020242)
		(width 0.1143)
		(layer "In13.Cu")
		(net "P5E_CPU1_P0_RX_DN<5>")
	)
	(segment
		(start 133.658102 -360.232706)
		(end 128.234694 -365.656114)
		(width 0.14224)
		(layer "In13.Cu")
		(net "P5E_CPU1_P0_RX_DN<5>")
	)
	(segment
		(start 101.928168 -276.193758)
		(end 101.889052 -276.170898)
		(width 0.1143)
		(layer "In13.Cu")
		(net "P5E_CPU1_P0_RX_DN<5>")
	)
	(segment
		(start 101.181916 -270.119094)
		(end 101.099112 -270.03629)
		(width 0.1143)
		(layer "In13.Cu")
		(net "P5E_CPU1_P0_RX_DN<5>")
	)
	(segment
		(start 102.115874 -296.36212)
		(end 102.115874 -295.955974)
		(width 0.1143)
		(layer "In13.Cu")
		(net "P5E_CPU1_P0_RX_DN<5>")
	)
	(segment
		(start 133.363716 -358.431592)
		(end 133.178042 -357.689912)
		(width 0.14224)
		(layer "In13.Cu")
		(net "P5E_CPU1_P0_RX_DN<5>")
	)
	(segment
		(start 124.850906 -365.388398)
		(end 124.543566 -365.695738)
		(width 0.14224)
		(layer "In13.Cu")
		(net "P5E_CPU1_P0_RX_DN<5>")
	)
	(segment
		(start 101.459538 -270.526002)
		(end 101.437186 -270.513048)
		(width 0.1143)
		(layer "In13.Cu")
		(net "P5E_CPU1_P0_RX_DN<5>")
	)
	(segment
		(start 54.14518 -385.404868)
		(end 54.266846 -385.334764)
		(width 0.14224)
		(layer "In13.Cu")
		(net "P5E_CPU1_P0_RX_DN<5>")
	)
	(segment
		(start 101.928168 -271.978882)
		(end 101.958648 -271.961102)
		(width 0.1143)
		(layer "In13.Cu")
		(net "P5E_CPU1_P0_RX_DN<5>")
	)
	(segment
		(start 101.928168 -280.078942)
		(end 101.958648 -280.061162)
		(width 0.1143)
		(layer "In13.Cu")
		(net "P5E_CPU1_P0_RX_DN<5>")
	)
	(segment
		(start 101.928168 -278.45893)
		(end 101.958648 -278.44115)
		(width 0.1143)
		(layer "In13.Cu")
		(net "P5E_CPU1_P0_RX_DN<5>")
	)
	(segment
		(start 101.958648 -276.211538)
		(end 101.928168 -276.193758)
		(width 0.1143)
		(layer "In13.Cu")
		(net "P5E_CPU1_P0_RX_DN<5>")
	)
	(segment
		(start 121.052336 -365.695738)
		(end 120.910096 -365.837978)
		(width 0.14224)
		(layer "In13.Cu")
		(net "P5E_CPU1_P0_RX_DN<5>")
	)
	(segment
		(start 101.889052 -272.001742)
		(end 101.928168 -271.978882)
		(width 0.1143)
		(layer "In13.Cu")
		(net "P5E_CPU1_P0_RX_DN<5>")
	)
	(segment
		(start 121.052336 -366.551718)
		(end 124.96038 -366.551718)
		(width 0.14224)
		(layer "In13.Cu")
		(net "P5E_CPU1_P0_RX_DN<5>")
	)
	(segment
		(start 101.928168 -275.218906)
		(end 101.958648 -275.201126)
		(width 0.1143)
		(layer "In13.Cu")
		(net "P5E_CPU1_P0_RX_DN<5>")
	)
	(segment
		(start 127.230632 -364.652052)
		(end 133.330188 -358.552496)
		(width 0.14224)
		(layer "In13.Cu")
		(net "P5E_CPU1_P0_RX_DN<5>")
	)
	(segment
		(start 112.342422 -305.464718)
		(end 110.911894 -304.527966)
		(width 0.14224)
		(layer "In13.Cu")
		(net "P5E_CPU1_P0_RX_DN<5>")
	)
	(segment
		(start 53.791358 -385.31038)
		(end 54.144672 -385.405376)
		(width 0.14224)
		(layer "In13.Cu")
		(net "P5E_CPU1_P0_RX_DN<5>")
	)
	(segment
		(start 54.144672 -385.405376)
		(end 54.14518 -385.404868)
		(width 0.14224)
		(layer "In13.Cu")
		(net "P5E_CPU1_P0_RX_DN<5>")
	)
	(segment
		(start 101.928168 -277.81377)
		(end 101.889052 -277.79091)
		(width 0.1143)
		(layer "In13.Cu")
		(net "P5E_CPU1_P0_RX_DN<5>")
	)
	(segment
		(start 128.588008 -366.51438)
		(end 134.263892 -360.838496)
		(width 0.14224)
		(layer "In13.Cu")
		(net "P5E_CPU1_P0_RX_DN<5>")
	)
	(segment
		(start 112.806988 -306.203858)
		(end 112.471454 -305.603402)
		(width 0.14224)
		(layer "In13.Cu")
		(net "P5E_CPU1_P0_RX_DN<5>")
	)
	(segment
		(start 101.958648 -282.691586)
		(end 101.928168 -282.673806)
		(width 0.1143)
		(layer "In13.Cu")
		(net "P5E_CPU1_P0_RX_DN<5>")
	)
	(segment
		(start 124.543566 -365.695738)
		(end 121.052336 -365.695738)
		(width 0.14224)
		(layer "In13.Cu")
		(net "P5E_CPU1_P0_RX_DN<5>")
	)
	(segment
		(start 101.95687 -294.642032)
		(end 101.957632 -294.641524)
		(width 0.1143)
		(layer "In13.Cu")
		(net "P5E_CPU1_P0_RX_DN<5>")
	)
	(segment
		(start 101.928168 -282.673806)
		(end 101.889052 -282.650946)
		(width 0.1143)
		(layer "In13.Cu")
		(net "P5E_CPU1_P0_RX_DN<5>")
	)
	(segment
		(start 102.070154 -296.40784)
		(end 102.115874 -296.36212)
		(width 0.1143)
		(layer "In13.Cu")
		(net "P5E_CPU1_P0_RX_DN<5>")
	)
	(segment
		(start 101.889052 -280.101802)
		(end 101.928168 -280.078942)
		(width 0.1143)
		(layer "In13.Cu")
		(net "P5E_CPU1_P0_RX_DN<5>")
	)
	(segment
		(start 101.891084 -294.680386)
		(end 101.954838 -294.643302)
		(width 0.1143)
		(layer "In13.Cu")
		(net "P5E_CPU1_P0_RX_DN<5>")
	)
	(segment
		(start 101.954838 -294.643302)
		(end 101.9556 -294.642794)
		(width 0.1143)
		(layer "In13.Cu")
		(net "P5E_CPU1_P0_RX_DN<5>")
	)
	(segment
		(start 126.78918 -366.551718)
		(end 128.498092 -366.551718)
		(width 0.14224)
		(layer "In13.Cu")
		(net "P5E_CPU1_P0_RX_DN<5>")
	)
	(segment
		(start 102.070154 -297.660822)
		(end 102.070154 -296.436288)
		(width 0.14224)
		(layer "In13.Cu")
		(net "P5E_CPU1_P0_RX_DN<5>")
	)
	(segment
		(start 54.28234 -382.481836)
		(end 54.953154 -380.617222)
		(width 0.14224)
		(layer "In13.Cu")
		(net "P5E_CPU1_P0_RX_DN<5>")
	)
	(segment
		(start 101.889052 -275.241766)
		(end 101.928168 -275.218906)
		(width 0.1143)
		(layer "In13.Cu")
		(net "P5E_CPU1_P0_RX_DN<5>")
	)
	(segment
		(start 101.928168 -276.838918)
		(end 101.958648 -276.821138)
		(width 0.1143)
		(layer "In13.Cu")
		(net "P5E_CPU1_P0_RX_DN<5>")
	)
	(segment
		(start 101.890576 -289.820604)
		(end 101.959664 -289.780218)
		(width 0.1143)
		(layer "In13.Cu")
		(net "P5E_CPU1_P0_RX_DN<5>")
	)
	(segment
		(start 125.66142 -366.551718)
		(end 126.08814 -366.551718)
		(width 0.14224)
		(layer "In13.Cu")
		(net "P5E_CPU1_P0_RX_DN<5>")
	)
	(arc
		(start 101.889052 -282.650946)
		(mid 101.645725 -282.18638)
		(end 101.889052 -281.721814)
		(width 0.1143)
		(layer "In13.Cu")
		(net "P5E_CPU1_P0_RX_DN<5>")
	)
	(arc
		(start 133.330188 -358.552496)
		(mid 133.362951 -358.496463)
		(end 133.363716 -358.431592)
		(width 0.14224)
		(layer "In13.Cu")
		(net "P5E_CPU1_P0_RX_DN<5>")
	)
	(arc
		(start 101.890576 -287.511744)
		(mid 101.710784 -287.309156)
		(end 101.645974 -287.046162)
		(width 0.1143)
		(layer "In13.Cu")
		(net "P5E_CPU1_P0_RX_DN<5>")
	)
	(arc
		(start 128.498092 -366.551718)
		(mid 128.546776 -366.542016)
		(end 128.588008 -366.51438)
		(width 0.14224)
		(layer "In13.Cu")
		(net "P5E_CPU1_P0_RX_DN<5>")
	)
	(arc
		(start 101.434392 -270.510508)
		(mid 101.265815 -270.342114)
		(end 101.181916 -270.119094)
		(width 0.1143)
		(layer "In13.Cu")
		(net "P5E_CPU1_P0_RX_DN<5>")
	)
	(arc
		(start 101.958648 -280.061162)
		(mid 102.115625 -279.756362)
		(end 101.958648 -279.451562)
		(width 0.1143)
		(layer "In13.Cu")
		(net "P5E_CPU1_P0_RX_DN<5>")
	)
	(arc
		(start 101.889052 -276.170898)
		(mid 101.645725 -275.706332)
		(end 101.889052 -275.241766)
		(width 0.1143)
		(layer "In13.Cu")
		(net "P5E_CPU1_P0_RX_DN<5>")
	)
	(arc
		(start 112.471454 -305.603402)
		(mid 112.415335 -305.526243)
		(end 112.342422 -305.464718)
		(width 0.14224)
		(layer "In13.Cu")
		(net "P5E_CPU1_P0_RX_DN<5>")
	)
	(arc
		(start 101.958648 -273.581114)
		(mid 102.115625 -273.276314)
		(end 101.958648 -272.971514)
		(width 0.1143)
		(layer "In13.Cu")
		(net "P5E_CPU1_P0_RX_DN<5>")
	)
	(arc
		(start 108.818426 -365.69523)
		(mid 108.97514 -365.726344)
		(end 109.107986 -365.815118)
		(width 0.14224)
		(layer "In13.Cu")
		(net "P5E_CPU1_P0_RX_DN<5>")
	)
	(arc
		(start 101.96068 -294.639746)
		(mid 102.115779 -294.335758)
		(end 101.959918 -294.032178)
		(width 0.1143)
		(layer "In13.Cu")
		(net "P5E_CPU1_P0_RX_DN<5>")
	)
	(arc
		(start 101.958648 -284.921198)
		(mid 102.115625 -284.616398)
		(end 101.958648 -284.311598)
		(width 0.1143)
		(layer "In13.Cu")
		(net "P5E_CPU1_P0_RX_DN<5>")
	)
	(arc
		(start 106.4895 -302.19015)
		(mid 106.123617 -301.960222)
		(end 105.79608 -301.67834)
		(width 0.14224)
		(layer "In13.Cu")
		(net "P5E_CPU1_P0_RX_DN<5>")
	)
	(arc
		(start 101.889052 -277.79091)
		(mid 101.645725 -277.326344)
		(end 101.889052 -276.861778)
		(width 0.1143)
		(layer "In13.Cu")
		(net "P5E_CPU1_P0_RX_DN<5>")
	)
	(arc
		(start 102.115874 -295.955974)
		(mid 102.103267 -295.853409)
		(end 102.065836 -295.757092)
		(width 0.1143)
		(layer "In13.Cu")
		(net "P5E_CPU1_P0_RX_DN<5>")
	)
	(arc
		(start 101.889052 -281.030934)
		(mid 101.645725 -280.566368)
		(end 101.889052 -280.101802)
		(width 0.1143)
		(layer "In13.Cu")
		(net "P5E_CPU1_P0_RX_DN<5>")
	)
	(arc
		(start 101.959664 -293.020242)
		(mid 102.115597 -292.716307)
		(end 101.959918 -292.412166)
		(width 0.1143)
		(layer "In13.Cu")
		(net "P5E_CPU1_P0_RX_DN<5>")
	)
	(arc
		(start 101.6381 -295.121584)
		(mid 101.672849 -294.947561)
		(end 101.77145 -294.80002)
		(width 0.1143)
		(layer "In13.Cu")
		(net "P5E_CPU1_P0_RX_DN<5>")
	)
	(arc
		(start 101.890576 -271.311878)
		(mid 101.710784 -271.10929)
		(end 101.645974 -270.846296)
		(width 0.1143)
		(layer "In13.Cu")
		(net "P5E_CPU1_P0_RX_DN<5>")
	)
	(arc
		(start 101.959664 -286.540448)
		(mid 102.115597 -286.236513)
		(end 101.959918 -285.932372)
		(width 0.1143)
		(layer "In13.Cu")
		(net "P5E_CPU1_P0_RX_DN<5>")
	)
	(arc
		(start 101.88575 -295.612312)
		(mid 101.841772 -295.582742)
		(end 101.80193 -295.547796)
		(width 0.1143)
		(layer "In13.Cu")
		(net "P5E_CPU1_P0_RX_DN<5>")
	)
	(arc
		(start 102.276402 -298.158662)
		(mid 102.123783 -297.930251)
		(end 102.070154 -297.660822)
		(width 0.14224)
		(layer "In13.Cu")
		(net "P5E_CPU1_P0_RX_DN<5>")
	)
	(arc
		(start 109.806994 -366.51438)
		(mid 109.848234 -366.541999)
		(end 109.89691 -366.551718)
		(width 0.14224)
		(layer "In13.Cu")
		(net "P5E_CPU1_P0_RX_DN<5>")
	)
	(arc
		(start 101.959664 -288.16046)
		(mid 102.115489 -287.855256)
		(end 101.957886 -287.55086)
		(width 0.1143)
		(layer "In13.Cu")
		(net "P5E_CPU1_P0_RX_DN<5>")
	)
	(arc
		(start 101.889052 -272.930874)
		(mid 101.645725 -272.466308)
		(end 101.889052 -272.001742)
		(width 0.1143)
		(layer "In13.Cu")
		(net "P5E_CPU1_P0_RX_DN<5>")
	)
	(arc
		(start 101.890576 -290.751768)
		(mid 101.645755 -290.286186)
		(end 101.890576 -289.820604)
		(width 0.1143)
		(layer "In13.Cu")
		(net "P5E_CPU1_P0_RX_DN<5>")
	)
	(arc
		(start 101.889052 -284.270958)
		(mid 101.645725 -283.806392)
		(end 101.889052 -283.341826)
		(width 0.1143)
		(layer "In13.Cu")
		(net "P5E_CPU1_P0_RX_DN<5>")
	)
	(arc
		(start 54.953154 -380.617222)
		(mid 55.022025 -380.452252)
		(end 55.107332 -380.29515)
		(width 0.14224)
		(layer "In13.Cu")
		(net "P5E_CPU1_P0_RX_DN<5>")
	)
	(arc
		(start 102.065836 -295.757092)
		(mid 102.027909 -295.705423)
		(end 101.977444 -295.665906)
		(width 0.1143)
		(layer "In13.Cu")
		(net "P5E_CPU1_P0_RX_DN<5>")
	)
	(arc
		(start 101.889052 -274.550886)
		(mid 101.645725 -274.08632)
		(end 101.889052 -273.621754)
		(width 0.1143)
		(layer "In13.Cu")
		(net "P5E_CPU1_P0_RX_DN<5>")
	)
	(arc
		(start 101.645974 -288.666174)
		(mid 101.71015 -288.404287)
		(end 101.88829 -288.201862)
		(width 0.1143)
		(layer "In13.Cu")
		(net "P5E_CPU1_P0_RX_DN<5>")
	)
	(arc
		(start 54.258718 -382.62052)
		(mid 54.264543 -382.55016)
		(end 54.28234 -382.481836)
		(width 0.14224)
		(layer "In13.Cu")
		(net "P5E_CPU1_P0_RX_DN<5>")
	)
	(arc
		(start 101.958648 -276.821138)
		(mid 102.115625 -276.516338)
		(end 101.958648 -276.211538)
		(width 0.1143)
		(layer "In13.Cu")
		(net "P5E_CPU1_P0_RX_DN<5>")
	)
	(arc
		(start 101.890576 -289.131756)
		(mid 101.710784 -288.929168)
		(end 101.645974 -288.666174)
		(width 0.1143)
		(layer "In13.Cu")
		(net "P5E_CPU1_P0_RX_DN<5>")
	)
	(arc
		(start 101.958648 -275.201126)
		(mid 102.115625 -274.896326)
		(end 101.958648 -274.591526)
		(width 0.1143)
		(layer "In13.Cu")
		(net "P5E_CPU1_P0_RX_DN<5>")
	)
	(arc
		(start 101.645974 -270.846296)
		(mid 101.597242 -270.663259)
		(end 101.46411 -270.528542)
		(width 0.1143)
		(layer "In13.Cu")
		(net "P5E_CPU1_P0_RX_DN<5>")
	)
	(arc
		(start 101.959664 -291.40023)
		(mid 102.115597 -291.096295)
		(end 101.959918 -290.792154)
		(width 0.1143)
		(layer "In13.Cu")
		(net "P5E_CPU1_P0_RX_DN<5>")
	)
	(arc
		(start 101.890576 -292.37178)
		(mid 101.645755 -291.906198)
		(end 101.890576 -291.440616)
		(width 0.1143)
		(layer "In13.Cu")
		(net "P5E_CPU1_P0_RX_DN<5>")
	)
	(arc
		(start 101.959664 -289.780218)
		(mid 102.115597 -289.476283)
		(end 101.959918 -289.172142)
		(width 0.1143)
		(layer "In13.Cu")
		(net "P5E_CPU1_P0_RX_DN<5>")
	)
	(arc
		(start 101.748336 -295.494202)
		(mid 101.666804 -295.372176)
		(end 101.6381 -295.228264)
		(width 0.1143)
		(layer "In13.Cu")
		(net "P5E_CPU1_P0_RX_DN<5>")
	)
	(arc
		(start 101.958648 -278.44115)
		(mid 102.115625 -278.13635)
		(end 101.958648 -277.83155)
		(width 0.1143)
		(layer "In13.Cu")
		(net "P5E_CPU1_P0_RX_DN<5>")
	)
	(arc
		(start 101.890576 -293.991792)
		(mid 101.645755 -293.52621)
		(end 101.890576 -293.060628)
		(width 0.1143)
		(layer "In13.Cu")
		(net "P5E_CPU1_P0_RX_DN<5>")
	)
	(arc
		(start 101.958648 -271.961102)
		(mid 102.115625 -271.656302)
		(end 101.958648 -271.351502)
		(width 0.1143)
		(layer "In13.Cu")
		(net "P5E_CPU1_P0_RX_DN<5>")
	)
	(arc
		(start 101.958648 -281.681174)
		(mid 102.115625 -281.376374)
		(end 101.958648 -281.071574)
		(width 0.1143)
		(layer "In13.Cu")
		(net "P5E_CPU1_P0_RX_DN<5>")
	)
	(arc
		(start 101.958648 -283.301186)
		(mid 102.115625 -282.996386)
		(end 101.958648 -282.691586)
		(width 0.1143)
		(layer "In13.Cu")
		(net "P5E_CPU1_P0_RX_DN<5>")
	)
	(arc
		(start 64.998092 -366.000538)
		(mid 65.407969 -365.773687)
		(end 65.86982 -365.69523)
		(width 0.14224)
		(layer "In13.Cu")
		(net "P5E_CPU1_P0_RX_DN<5>")
	)
	(arc
		(start 101.645974 -287.046162)
		(mid 101.71015 -286.784275)
		(end 101.88829 -286.58185)
		(width 0.1143)
		(layer "In13.Cu")
		(net "P5E_CPU1_P0_RX_DN<5>")
	)
	(arc
		(start 62.726824 -367.848642)
		(mid 62.768816 -367.791502)
		(end 62.820042 -367.74247)
		(width 0.14224)
		(layer "In13.Cu")
		(net "P5E_CPU1_P0_RX_DN<5>")
	)
	(arc
		(start 101.889052 -279.410922)
		(mid 101.645725 -278.946356)
		(end 101.889052 -278.48179)
		(width 0.1143)
		(layer "In13.Cu")
		(net "P5E_CPU1_P0_RX_DN<5>")
	)
	(arc
		(start 101.889052 -285.89097)
		(mid 101.645725 -285.426404)
		(end 101.889052 -284.961838)
		(width 0.1143)
		(layer "In13.Cu")
		(net "P5E_CPU1_P0_RX_DN<5>")
	)
	(segment
		(start 52.070508 -385.31038)
		(end 52.591208 -385.31038)
		(width 0.127)
		(layer "F.Cu")
		(net "P5E_CPU1_P0_RX_DN<4>")
	)
	(segment
		(start 101.268022 -273.010376)
		(end 100.80117 -273.276314)
		(width 0.12954)
		(layer "F.Cu")
		(net "P5E_CPU1_P0_RX_DN<4>")
	)
	(segment
		(start 110.265718 -365.552228)
		(end 118.337838 -365.552228)
		(width 0.14224)
		(layer "In13.Cu")
		(net "P5E_CPU1_P0_RX_DN<4>")
	)
	(segment
		(start 100.956618 -286.577278)
		(end 100.958396 -286.576262)
		(width 0.1143)
		(layer "In13.Cu")
		(net "P5E_CPU1_P0_RX_DN<4>")
	)
	(segment
		(start 107.27182 -364.62335)
		(end 107.40898 -364.76051)
		(width 0.14224)
		(layer "In13.Cu")
		(net "P5E_CPU1_P0_RX_DN<4>")
	)
	(segment
		(start 101.018848 -279.451562)
		(end 100.949252 -279.410922)
		(width 0.1143)
		(layer "In13.Cu")
		(net "P5E_CPU1_P0_RX_DN<4>")
	)
	(segment
		(start 130.983482 -358.367838)
		(end 125.587506 -363.76356)
		(width 0.14224)
		(layer "In13.Cu")
		(net "P5E_CPU1_P0_RX_DN<4>")
	)
	(segment
		(start 111.037624 -305.896518)
		(end 105.62463 -303.003966)
		(width 0.14224)
		(layer "In13.Cu")
		(net "P5E_CPU1_P0_RX_DN<4>")
	)
	(segment
		(start 100.947982 -286.582612)
		(end 100.950522 -286.580834)
		(width 0.1143)
		(layer "In13.Cu")
		(net "P5E_CPU1_P0_RX_DN<4>")
	)
	(segment
		(start 124.103892 -363.23905)
		(end 126.107952 -361.23499)
		(width 0.14224)
		(layer "In13.Cu")
		(net "P5E_CPU1_P0_RX_DN<4>")
	)
	(segment
		(start 100.948236 -288.202116)
		(end 101.020118 -288.16046)
		(width 0.1143)
		(layer "In13.Cu")
		(net "P5E_CPU1_P0_RX_DN<4>")
	)
	(segment
		(start 101.168962 -273.346164)
		(end 101.099112 -273.276314)
		(width 0.1143)
		(layer "In13.Cu")
		(net "P5E_CPU1_P0_RX_DN<4>")
	)
	(segment
		(start 123.77166 -362.360718)
		(end 123.336812 -362.360718)
		(width 0.14224)
		(layer "In13.Cu")
		(net "P5E_CPU1_P0_RX_DN<4>")
	)
	(segment
		(start 100.972366 -286.567372)
		(end 100.973382 -286.566864)
		(width 0.1143)
		(layer "In13.Cu")
		(net "P5E_CPU1_P0_RX_DN<4>")
	)
	(segment
		(start 52.75453 -384.234944)
		(end 53.058568 -383.93116)
		(width 0.14224)
		(layer "In13.Cu")
		(net "P5E_CPU1_P0_RX_DN<4>")
	)
	(segment
		(start 101.020118 -285.932372)
		(end 100.950522 -285.891986)
		(width 0.1143)
		(layer "In13.Cu")
		(net "P5E_CPU1_P0_RX_DN<4>")
	)
	(segment
		(start 52.94503 -385.404868)
		(end 53.066696 -385.334764)
		(width 0.14224)
		(layer "In13.Cu")
		(net "P5E_CPU1_P0_RX_DN<4>")
	)
	(segment
		(start 100.6602 -297.905424)
		(end 100.6602 -296.422318)
		(width 0.14224)
		(layer "In13.Cu")
		(net "P5E_CPU1_P0_RX_DN<4>")
	)
	(segment
		(start 101.099112 -273.276314)
		(end 100.80117 -273.276314)
		(width 0.1143)
		(layer "In13.Cu")
		(net "P5E_CPU1_P0_RX_DN<4>")
	)
	(segment
		(start 100.950776 -293.060628)
		(end 101.020118 -293.020242)
		(width 0.1143)
		(layer "In13.Cu")
		(net "P5E_CPU1_P0_RX_DN<4>")
	)
	(segment
		(start 100.962714 -286.573214)
		(end 100.965508 -286.571436)
		(width 0.1143)
		(layer "In13.Cu")
		(net "P5E_CPU1_P0_RX_DN<4>")
	)
	(segment
		(start 112.033558 -364.696248)
		(end 111.726218 -364.388908)
		(width 0.14224)
		(layer "In13.Cu")
		(net "P5E_CPU1_P0_RX_DN<4>")
	)
	(segment
		(start 101.018848 -274.591526)
		(end 100.949252 -274.550886)
		(width 0.1143)
		(layer "In13.Cu")
		(net "P5E_CPU1_P0_RX_DN<4>")
	)
	(segment
		(start 107.87634 -364.76051)
		(end 108.0135 -364.62335)
		(width 0.14224)
		(layer "In13.Cu")
		(net "P5E_CPU1_P0_RX_DN<4>")
	)
	(segment
		(start 101.020118 -292.412166)
		(end 100.950522 -292.37178)
		(width 0.1143)
		(layer "In13.Cu")
		(net "P5E_CPU1_P0_RX_DN<4>")
	)
	(segment
		(start 118.480078 -365.409988)
		(end 118.480078 -364.838488)
		(width 0.14224)
		(layer "In13.Cu")
		(net "P5E_CPU1_P0_RX_DN<4>")
	)
	(segment
		(start 125.820424 -358.7369)
		(end 127.112522 -360.028998)
		(width 0.14224)
		(layer "In13.Cu")
		(net "P5E_CPU1_P0_RX_DN<4>")
	)
	(segment
		(start 106.8451 -364.62335)
		(end 107.27182 -364.62335)
		(width 0.14224)
		(layer "In13.Cu")
		(net "P5E_CPU1_P0_RX_DN<4>")
	)
	(segment
		(start 100.974652 -286.566102)
		(end 100.975668 -286.565594)
		(width 0.1143)
		(layer "In13.Cu")
		(net "P5E_CPU1_P0_RX_DN<4>")
	)
	(segment
		(start 130.414014 -357.36276)
		(end 130.98399 -357.932736)
		(width 0.14224)
		(layer "In13.Cu")
		(net "P5E_CPU1_P0_RX_DN<4>")
	)
	(segment
		(start 108.44022 -364.62335)
		(end 108.57738 -364.76051)
		(width 0.14224)
		(layer "In13.Cu")
		(net "P5E_CPU1_P0_RX_DN<4>")
	)
	(segment
		(start 111.726218 -364.388908)
		(end 111.726218 -363.583728)
		(width 0.14224)
		(layer "In13.Cu")
		(net "P5E_CPU1_P0_RX_DN<4>")
	)
	(segment
		(start 101.020118 -289.172142)
		(end 100.950776 -289.131756)
		(width 0.1143)
		(layer "In13.Cu")
		(net "P5E_CPU1_P0_RX_DN<4>")
	)
	(segment
		(start 100.958396 -286.576262)
		(end 100.96119 -286.574484)
		(width 0.1143)
		(layer "In13.Cu")
		(net "P5E_CPU1_P0_RX_DN<4>")
	)
	(segment
		(start 100.939854 -286.5882)
		(end 100.940108 -286.587946)
		(width 0.1143)
		(layer "In13.Cu")
		(net "P5E_CPU1_P0_RX_DN<4>")
	)
	(segment
		(start 53.066696 -385.334764)
		(end 53.066696 -385.163822)
		(width 0.14224)
		(layer "In13.Cu")
		(net "P5E_CPU1_P0_RX_DN<4>")
	)
	(segment
		(start 127.31369 -360.028998)
		(end 129.979928 -357.36276)
		(width 0.14224)
		(layer "In13.Cu")
		(net "P5E_CPU1_P0_RX_DN<4>")
	)
	(segment
		(start 100.953824 -286.578802)
		(end 100.956618 -286.577278)
		(width 0.1143)
		(layer "In13.Cu")
		(net "P5E_CPU1_P0_RX_DN<4>")
	)
	(segment
		(start 65.675764 -364.76051)
		(end 105.58018 -364.76051)
		(width 0.14224)
		(layer "In13.Cu")
		(net "P5E_CPU1_P0_RX_DN<4>")
	)
	(segment
		(start 100.940108 -286.587946)
		(end 100.946966 -286.583374)
		(width 0.1143)
		(layer "In13.Cu")
		(net "P5E_CPU1_P0_RX_DN<4>")
	)
	(segment
		(start 111.726218 -363.583728)
		(end 112.033558 -363.276388)
		(width 0.14224)
		(layer "In13.Cu")
		(net "P5E_CPU1_P0_RX_DN<4>")
	)
	(segment
		(start 129.979928 -357.36276)
		(end 130.414014 -357.36276)
		(width 0.14224)
		(layer "In13.Cu")
		(net "P5E_CPU1_P0_RX_DN<4>")
	)
	(segment
		(start 53.066696 -385.163822)
		(end 52.749704 -384.84683)
		(width 0.14224)
		(layer "In13.Cu")
		(net "P5E_CPU1_P0_RX_DN<4>")
	)
	(segment
		(start 132.097018 -358.381554)
		(end 128.058926 -340.90229)
		(width 0.14224)
		(layer "In13.Cu")
		(net "P5E_CPU1_P0_RX_DN<4>")
	)
	(segment
		(start 108.0135 -364.62335)
		(end 108.44022 -364.62335)
		(width 0.14224)
		(layer "In13.Cu")
		(net "P5E_CPU1_P0_RX_DN<4>")
	)
	(segment
		(start 126.966472 -334.6069)
		(end 126.093728 -330.829412)
		(width 0.14224)
		(layer "In13.Cu")
		(net "P5E_CPU1_P0_RX_DN<4>")
	)
	(segment
		(start 109.541564 -364.880398)
		(end 110.175802 -365.51489)
		(width 0.14224)
		(layer "In13.Cu")
		(net "P5E_CPU1_P0_RX_DN<4>")
	)
	(segment
		(start 125.386084 -358.7369)
		(end 125.820424 -358.7369)
		(width 0.14224)
		(layer "In13.Cu")
		(net "P5E_CPU1_P0_RX_DN<4>")
	)
	(segment
		(start 100.949252 -283.341826)
		(end 101.018848 -283.301186)
		(width 0.1143)
		(layer "In13.Cu")
		(net "P5E_CPU1_P0_RX_DN<4>")
	)
	(segment
		(start 53.090064 -382.476248)
		(end 53.975 -380.354586)
		(width 0.14224)
		(layer "In13.Cu")
		(net "P5E_CPU1_P0_RX_DN<4>")
	)
	(segment
		(start 105.71734 -364.62335)
		(end 106.14406 -364.62335)
		(width 0.14224)
		(layer "In13.Cu")
		(net "P5E_CPU1_P0_RX_DN<4>")
	)
	(segment
		(start 125.703838 -360.629708)
		(end 125.50267 -360.629708)
		(width 0.14224)
		(layer "In13.Cu")
		(net "P5E_CPU1_P0_RX_DN<4>")
	)
	(segment
		(start 52.591208 -385.31038)
		(end 52.944522 -385.405376)
		(width 0.14224)
		(layer "In13.Cu")
		(net "P5E_CPU1_P0_RX_DN<4>")
	)
	(segment
		(start 105.58018 -364.76051)
		(end 105.71734 -364.62335)
		(width 0.14224)
		(layer "In13.Cu")
		(net "P5E_CPU1_P0_RX_DN<4>")
	)
	(segment
		(start 100.96119 -286.574484)
		(end 100.962714 -286.573214)
		(width 0.1143)
		(layer "In13.Cu")
		(net "P5E_CPU1_P0_RX_DN<4>")
	)
	(segment
		(start 105.389934 -302.829976)
		(end 100.797868 -298.23791)
		(width 0.14224)
		(layer "In13.Cu")
		(net "P5E_CPU1_P0_RX_DN<4>")
	)
	(segment
		(start 100.949252 -273.621754)
		(end 101.018848 -273.581114)
		(width 0.1143)
		(layer "In13.Cu")
		(net "P5E_CPU1_P0_RX_DN<4>")
	)
	(segment
		(start 126.19355 -364.369604)
		(end 132.062982 -358.500172)
		(width 0.14224)
		(layer "In13.Cu")
		(net "P5E_CPU1_P0_RX_DN<4>")
	)
	(segment
		(start 100.973382 -286.566864)
		(end 100.974652 -286.566102)
		(width 0.1143)
		(layer "In13.Cu")
		(net "P5E_CPU1_P0_RX_DN<4>")
	)
	(segment
		(start 101.018848 -276.211538)
		(end 100.949252 -276.170898)
		(width 0.1143)
		(layer "In13.Cu")
		(net "P5E_CPU1_P0_RX_DN<4>")
	)
	(segment
		(start 100.950522 -286.580834)
		(end 100.9523 -286.579818)
		(width 0.1143)
		(layer "In13.Cu")
		(net "P5E_CPU1_P0_RX_DN<4>")
	)
	(segment
		(start 107.40898 -364.76051)
		(end 107.87634 -364.76051)
		(width 0.14224)
		(layer "In13.Cu")
		(net "P5E_CPU1_P0_RX_DN<4>")
	)
	(segment
		(start 100.949252 -278.48179)
		(end 101.018848 -278.44115)
		(width 0.1143)
		(layer "In13.Cu")
		(net "P5E_CPU1_P0_RX_DN<4>")
	)
	(segment
		(start 53.975 -380.354586)
		(end 61.93663 -367.348516)
		(width 0.14224)
		(layer "In13.Cu")
		(net "P5E_CPU1_P0_RX_DN<4>")
	)
	(segment
		(start 118.480078 -364.838488)
		(end 118.337838 -364.696248)
		(width 0.14224)
		(layer "In13.Cu")
		(net "P5E_CPU1_P0_RX_DN<4>")
	)
	(segment
		(start 100.9523 -286.579818)
		(end 100.953824 -286.578802)
		(width 0.1143)
		(layer "In13.Cu")
		(net "P5E_CPU1_P0_RX_DN<4>")
	)
	(segment
		(start 100.950776 -291.440616)
		(end 101.020118 -291.40023)
		(width 0.1143)
		(layer "In13.Cu")
		(net "P5E_CPU1_P0_RX_DN<4>")
	)
	(segment
		(start 125.587506 -363.76356)
		(end 125.587506 -363.96422)
		(width 0.14224)
		(layer "In13.Cu")
		(net "P5E_CPU1_P0_RX_DN<4>")
	)
	(segment
		(start 124.405644 -325.00951)
		(end 121.621296 -320.095626)
		(width 0.14224)
		(layer "In13.Cu")
		(net "P5E_CPU1_P0_RX_DN<4>")
	)
	(segment
		(start 100.6602 -296.39387)
		(end 100.70592 -296.34815)
		(width 0.1143)
		(layer "In13.Cu")
		(net "P5E_CPU1_P0_RX_DN<4>")
	)
	(segment
		(start 125.587506 -363.96422)
		(end 125.99289 -364.369604)
		(width 0.14224)
		(layer "In13.Cu")
		(net "P5E_CPU1_P0_RX_DN<4>")
	)
	(segment
		(start 52.749704 -384.84683)
		(end 52.75453 -384.234944)
		(width 0.14224)
		(layer "In13.Cu")
		(net "P5E_CPU1_P0_RX_DN<4>")
	)
	(segment
		(start 116.40185 -313.058556)
		(end 116.402104 -313.058556)
		(width 0.14224)
		(layer "In13.Cu")
		(net "P5E_CPU1_P0_RX_DN<4>")
	)
	(segment
		(start 108.57738 -364.76051)
		(end 109.252004 -364.76051)
		(width 0.14224)
		(layer "In13.Cu")
		(net "P5E_CPU1_P0_RX_DN<4>")
	)
	(segment
		(start 124.40539 -325.00951)
		(end 124.405644 -325.00951)
		(width 0.14224)
		(layer "In13.Cu")
		(net "P5E_CPU1_P0_RX_DN<4>")
	)
	(segment
		(start 100.6602 -296.422318)
		(end 100.6602 -296.39387)
		(width 0.1143)
		(layer "In13.Cu")
		(net "P5E_CPU1_P0_RX_DN<4>")
	)
	(segment
		(start 126.107952 -361.033822)
		(end 125.703838 -360.629708)
		(width 0.14224)
		(layer "In13.Cu")
		(net "P5E_CPU1_P0_RX_DN<4>")
	)
	(segment
		(start 100.965508 -286.571436)
		(end 100.972366 -286.567372)
		(width 0.1143)
		(layer "In13.Cu")
		(net "P5E_CPU1_P0_RX_DN<4>")
	)
	(segment
		(start 128.058926 -340.90229)
		(end 126.966472 -334.6069)
		(width 0.14224)
		(layer "In13.Cu")
		(net "P5E_CPU1_P0_RX_DN<4>")
	)
	(segment
		(start 101.020118 -294.032178)
		(end 100.950522 -293.991792)
		(width 0.1143)
		(layer "In13.Cu")
		(net "P5E_CPU1_P0_RX_DN<4>")
	)
	(segment
		(start 100.949252 -284.961838)
		(end 101.018848 -284.921198)
		(width 0.1143)
		(layer "In13.Cu")
		(net "P5E_CPU1_P0_RX_DN<4>")
	)
	(segment
		(start 101.020118 -290.792154)
		(end 100.950522 -290.751768)
		(width 0.1143)
		(layer "In13.Cu")
		(net "P5E_CPU1_P0_RX_DN<4>")
	)
	(segment
		(start 52.944522 -385.405376)
		(end 52.94503 -385.404868)
		(width 0.14224)
		(layer "In13.Cu")
		(net "P5E_CPU1_P0_RX_DN<4>")
	)
	(segment
		(start 53.058568 -383.93116)
		(end 53.058568 -382.633728)
		(width 0.14224)
		(layer "In13.Cu")
		(net "P5E_CPU1_P0_RX_DN<4>")
	)
	(segment
		(start 125.99289 -364.369604)
		(end 126.19355 -364.369604)
		(width 0.14224)
		(layer "In13.Cu")
		(net "P5E_CPU1_P0_RX_DN<4>")
	)
	(segment
		(start 122.766836 -361.790742)
		(end 122.766836 -361.356402)
		(width 0.14224)
		(layer "In13.Cu")
		(net "P5E_CPU1_P0_RX_DN<4>")
	)
	(segment
		(start 122.766836 -361.356402)
		(end 125.386084 -358.7369)
		(width 0.14224)
		(layer "In13.Cu")
		(net "P5E_CPU1_P0_RX_DN<4>")
	)
	(segment
		(start 100.946966 -286.583374)
		(end 100.947982 -286.582612)
		(width 0.1143)
		(layer "In13.Cu")
		(net "P5E_CPU1_P0_RX_DN<4>")
	)
	(segment
		(start 100.949252 -276.861778)
		(end 101.018848 -276.821138)
		(width 0.1143)
		(layer "In13.Cu")
		(net "P5E_CPU1_P0_RX_DN<4>")
	)
	(segment
		(start 125.50267 -360.629708)
		(end 123.77166 -362.360718)
		(width 0.14224)
		(layer "In13.Cu")
		(net "P5E_CPU1_P0_RX_DN<4>")
	)
	(segment
		(start 100.949252 -280.101802)
		(end 101.018848 -280.061162)
		(width 0.1143)
		(layer "In13.Cu")
		(net "P5E_CPU1_P0_RX_DN<4>")
	)
	(segment
		(start 106.70794 -364.76051)
		(end 106.8451 -364.62335)
		(width 0.14224)
		(layer "In13.Cu")
		(net "P5E_CPU1_P0_RX_DN<4>")
	)
	(segment
		(start 100.949252 -275.241766)
		(end 101.018848 -275.201126)
		(width 0.1143)
		(layer "In13.Cu")
		(net "P5E_CPU1_P0_RX_DN<4>")
	)
	(segment
		(start 101.018848 -277.83155)
		(end 100.949252 -277.79091)
		(width 0.1143)
		(layer "In13.Cu")
		(net "P5E_CPU1_P0_RX_DN<4>")
	)
	(segment
		(start 100.70592 -296.34815)
		(end 100.70592 -295.145714)
		(width 0.1143)
		(layer "In13.Cu")
		(net "P5E_CPU1_P0_RX_DN<4>")
	)
	(segment
		(start 101.018848 -281.071574)
		(end 100.949252 -281.030934)
		(width 0.1143)
		(layer "In13.Cu")
		(net "P5E_CPU1_P0_RX_DN<4>")
	)
	(segment
		(start 101.018086 -287.55086)
		(end 100.950776 -287.511744)
		(width 0.1143)
		(layer "In13.Cu")
		(net "P5E_CPU1_P0_RX_DN<4>")
	)
	(segment
		(start 100.950776 -294.68064)
		(end 101.020118 -294.640254)
		(width 0.1143)
		(layer "In13.Cu")
		(net "P5E_CPU1_P0_RX_DN<4>")
	)
	(segment
		(start 100.949252 -281.721814)
		(end 101.018848 -281.681174)
		(width 0.1143)
		(layer "In13.Cu")
		(net "P5E_CPU1_P0_RX_DN<4>")
	)
	(segment
		(start 118.337838 -364.696248)
		(end 112.033558 -364.696248)
		(width 0.14224)
		(layer "In13.Cu")
		(net "P5E_CPU1_P0_RX_DN<4>")
	)
	(segment
		(start 106.28122 -364.76051)
		(end 106.70794 -364.76051)
		(width 0.14224)
		(layer "In13.Cu")
		(net "P5E_CPU1_P0_RX_DN<4>")
	)
	(segment
		(start 116.402104 -313.058556)
		(end 111.182912 -306.02174)
		(width 0.14224)
		(layer "In13.Cu")
		(net "P5E_CPU1_P0_RX_DN<4>")
	)
	(segment
		(start 126.093728 -330.829412)
		(end 124.40539 -325.00951)
		(width 0.14224)
		(layer "In13.Cu")
		(net "P5E_CPU1_P0_RX_DN<4>")
	)
	(segment
		(start 112.033558 -363.276388)
		(end 124.013976 -363.276388)
		(width 0.14224)
		(layer "In13.Cu")
		(net "P5E_CPU1_P0_RX_DN<4>")
	)
	(segment
		(start 130.98399 -357.932736)
		(end 130.983482 -358.367838)
		(width 0.14224)
		(layer "In13.Cu")
		(net "P5E_CPU1_P0_RX_DN<4>")
	)
	(segment
		(start 121.621296 -320.095626)
		(end 116.40185 -313.058556)
		(width 0.14224)
		(layer "In13.Cu")
		(net "P5E_CPU1_P0_RX_DN<4>")
	)
	(segment
		(start 101.018848 -282.691586)
		(end 100.949252 -282.650946)
		(width 0.1143)
		(layer "In13.Cu")
		(net "P5E_CPU1_P0_RX_DN<4>")
	)
	(segment
		(start 123.336812 -362.360718)
		(end 122.766836 -361.790742)
		(width 0.14224)
		(layer "In13.Cu")
		(net "P5E_CPU1_P0_RX_DN<4>")
	)
	(segment
		(start 118.337838 -365.552228)
		(end 118.480078 -365.409988)
		(width 0.14224)
		(layer "In13.Cu")
		(net "P5E_CPU1_P0_RX_DN<4>")
	)
	(segment
		(start 126.107952 -361.23499)
		(end 126.107952 -361.033822)
		(width 0.14224)
		(layer "In13.Cu")
		(net "P5E_CPU1_P0_RX_DN<4>")
	)
	(segment
		(start 62.225682 -367.020602)
		(end 64.565022 -365.149892)
		(width 0.14224)
		(layer "In13.Cu")
		(net "P5E_CPU1_P0_RX_DN<4>")
	)
	(segment
		(start 106.14406 -364.62335)
		(end 106.28122 -364.76051)
		(width 0.14224)
		(layer "In13.Cu")
		(net "P5E_CPU1_P0_RX_DN<4>")
	)
	(segment
		(start 100.975668 -286.565594)
		(end 100.989384 -286.55772)
		(width 0.1143)
		(layer "In13.Cu")
		(net "P5E_CPU1_P0_RX_DN<4>")
	)
	(segment
		(start 100.950776 -289.820604)
		(end 101.020118 -289.780218)
		(width 0.1143)
		(layer "In13.Cu")
		(net "P5E_CPU1_P0_RX_DN<4>")
	)
	(segment
		(start 127.112522 -360.028998)
		(end 127.31369 -360.028998)
		(width 0.14224)
		(layer "In13.Cu")
		(net "P5E_CPU1_P0_RX_DN<4>")
	)
	(segment
		(start 101.018848 -284.311598)
		(end 100.949252 -284.270958)
		(width 0.1143)
		(layer "In13.Cu")
		(net "P5E_CPU1_P0_RX_DN<4>")
	)
	(arc
		(start 101.018848 -280.061162)
		(mid 101.175825 -279.756362)
		(end 101.018848 -279.451562)
		(width 0.1143)
		(layer "In13.Cu")
		(net "P5E_CPU1_P0_RX_DN<4>")
	)
	(arc
		(start 101.020118 -293.020242)
		(mid 101.175945 -292.716204)
		(end 101.020118 -292.412166)
		(width 0.1143)
		(layer "In13.Cu")
		(net "P5E_CPU1_P0_RX_DN<4>")
	)
	(arc
		(start 109.252004 -364.76051)
		(mid 109.408718 -364.791624)
		(end 109.541564 -364.880398)
		(width 0.14224)
		(layer "In13.Cu")
		(net "P5E_CPU1_P0_RX_DN<4>")
	)
	(arc
		(start 111.182912 -306.02174)
		(mid 111.117218 -305.951062)
		(end 111.037624 -305.896518)
		(width 0.14224)
		(layer "In13.Cu")
		(net "P5E_CPU1_P0_RX_DN<4>")
	)
	(arc
		(start 101.018848 -273.581114)
		(mid 101.116613 -273.478138)
		(end 101.168962 -273.346164)
		(width 0.1143)
		(layer "In13.Cu")
		(net "P5E_CPU1_P0_RX_DN<4>")
	)
	(arc
		(start 101.018848 -284.921198)
		(mid 101.175825 -284.616398)
		(end 101.018848 -284.311598)
		(width 0.1143)
		(layer "In13.Cu")
		(net "P5E_CPU1_P0_RX_DN<4>")
	)
	(arc
		(start 124.013976 -363.276388)
		(mid 124.06266 -363.266686)
		(end 124.103892 -363.23905)
		(width 0.14224)
		(layer "In13.Cu")
		(net "P5E_CPU1_P0_RX_DN<4>")
	)
	(arc
		(start 100.706174 -287.046162)
		(mid 100.767965 -286.789088)
		(end 100.939854 -286.5882)
		(width 0.1143)
		(layer "In13.Cu")
		(net "P5E_CPU1_P0_RX_DN<4>")
	)
	(arc
		(start 101.018848 -283.301186)
		(mid 101.175825 -282.996386)
		(end 101.018848 -282.691586)
		(width 0.1143)
		(layer "In13.Cu")
		(net "P5E_CPU1_P0_RX_DN<4>")
	)
	(arc
		(start 100.949252 -281.030934)
		(mid 100.705925 -280.566368)
		(end 100.949252 -280.101802)
		(width 0.1143)
		(layer "In13.Cu")
		(net "P5E_CPU1_P0_RX_DN<4>")
	)
	(arc
		(start 100.949252 -284.270958)
		(mid 100.705925 -283.806392)
		(end 100.949252 -283.341826)
		(width 0.1143)
		(layer "In13.Cu")
		(net "P5E_CPU1_P0_RX_DN<4>")
	)
	(arc
		(start 110.175802 -365.51489)
		(mid 110.217042 -365.542509)
		(end 110.265718 -365.552228)
		(width 0.14224)
		(layer "In13.Cu")
		(net "P5E_CPU1_P0_RX_DN<4>")
	)
	(arc
		(start 132.062982 -358.500172)
		(mid 132.095312 -358.445266)
		(end 132.097018 -358.381554)
		(width 0.14224)
		(layer "In13.Cu")
		(net "P5E_CPU1_P0_RX_DN<4>")
	)
	(arc
		(start 100.950522 -292.37178)
		(mid 100.705701 -291.906093)
		(end 100.950776 -291.440616)
		(width 0.1143)
		(layer "In13.Cu")
		(net "P5E_CPU1_P0_RX_DN<4>")
	)
	(arc
		(start 105.62463 -303.003966)
		(mid 105.500859 -302.925634)
		(end 105.389934 -302.829976)
		(width 0.14224)
		(layer "In13.Cu")
		(net "P5E_CPU1_P0_RX_DN<4>")
	)
	(arc
		(start 100.706174 -288.666174)
		(mid 100.770268 -288.404443)
		(end 100.948236 -288.202116)
		(width 0.1143)
		(layer "In13.Cu")
		(net "P5E_CPU1_P0_RX_DN<4>")
	)
	(arc
		(start 100.989384 -286.55772)
		(mid 101.1747 -286.253421)
		(end 101.020118 -285.932372)
		(width 0.1143)
		(layer "In13.Cu")
		(net "P5E_CPU1_P0_RX_DN<4>")
	)
	(arc
		(start 64.565022 -365.149892)
		(mid 65.08725 -364.860649)
		(end 65.675764 -364.76051)
		(width 0.14224)
		(layer "In13.Cu")
		(net "P5E_CPU1_P0_RX_DN<4>")
	)
	(arc
		(start 100.949252 -282.650946)
		(mid 100.705925 -282.18638)
		(end 100.949252 -281.721814)
		(width 0.1143)
		(layer "In13.Cu")
		(net "P5E_CPU1_P0_RX_DN<4>")
	)
	(arc
		(start 101.018848 -276.821138)
		(mid 101.175825 -276.516338)
		(end 101.018848 -276.211538)
		(width 0.1143)
		(layer "In13.Cu")
		(net "P5E_CPU1_P0_RX_DN<4>")
	)
	(arc
		(start 100.950776 -289.131756)
		(mid 100.770984 -288.929168)
		(end 100.706174 -288.666174)
		(width 0.1143)
		(layer "In13.Cu")
		(net "P5E_CPU1_P0_RX_DN<4>")
	)
	(arc
		(start 101.018848 -281.681174)
		(mid 101.175825 -281.376374)
		(end 101.018848 -281.071574)
		(width 0.1143)
		(layer "In13.Cu")
		(net "P5E_CPU1_P0_RX_DN<4>")
	)
	(arc
		(start 53.058568 -382.633728)
		(mid 53.066519 -382.553429)
		(end 53.090064 -382.476248)
		(width 0.14224)
		(layer "In13.Cu")
		(net "P5E_CPU1_P0_RX_DN<4>")
	)
	(arc
		(start 61.93663 -367.348516)
		(mid 62.066903 -367.171996)
		(end 62.225682 -367.020602)
		(width 0.14224)
		(layer "In13.Cu")
		(net "P5E_CPU1_P0_RX_DN<4>")
	)
	(arc
		(start 100.949252 -279.410922)
		(mid 100.705925 -278.946356)
		(end 100.949252 -278.48179)
		(width 0.1143)
		(layer "In13.Cu")
		(net "P5E_CPU1_P0_RX_DN<4>")
	)
	(arc
		(start 101.018848 -278.44115)
		(mid 101.175825 -278.13635)
		(end 101.018848 -277.83155)
		(width 0.1143)
		(layer "In13.Cu")
		(net "P5E_CPU1_P0_RX_DN<4>")
	)
	(arc
		(start 101.020118 -291.40023)
		(mid 101.175945 -291.096192)
		(end 101.020118 -290.792154)
		(width 0.1143)
		(layer "In13.Cu")
		(net "P5E_CPU1_P0_RX_DN<4>")
	)
	(arc
		(start 100.950522 -293.991792)
		(mid 100.705701 -293.526105)
		(end 100.950776 -293.060628)
		(width 0.1143)
		(layer "In13.Cu")
		(net "P5E_CPU1_P0_RX_DN<4>")
	)
	(arc
		(start 100.70592 -295.145714)
		(mid 100.770978 -294.882968)
		(end 100.950776 -294.68064)
		(width 0.1143)
		(layer "In13.Cu")
		(net "P5E_CPU1_P0_RX_DN<4>")
	)
	(arc
		(start 100.797868 -298.23791)
		(mid 100.695994 -298.08535)
		(end 100.6602 -297.905424)
		(width 0.14224)
		(layer "In13.Cu")
		(net "P5E_CPU1_P0_RX_DN<4>")
	)
	(arc
		(start 100.950522 -290.751768)
		(mid 100.705701 -290.286081)
		(end 100.950776 -289.820604)
		(width 0.1143)
		(layer "In13.Cu")
		(net "P5E_CPU1_P0_RX_DN<4>")
	)
	(arc
		(start 100.950522 -285.891986)
		(mid 100.705702 -285.427215)
		(end 100.949252 -284.961838)
		(width 0.1143)
		(layer "In13.Cu")
		(net "P5E_CPU1_P0_RX_DN<4>")
	)
	(arc
		(start 100.949252 -276.170898)
		(mid 100.705925 -275.706332)
		(end 100.949252 -275.241766)
		(width 0.1143)
		(layer "In13.Cu")
		(net "P5E_CPU1_P0_RX_DN<4>")
	)
	(arc
		(start 101.020118 -288.16046)
		(mid 101.175943 -287.855152)
		(end 101.018086 -287.55086)
		(width 0.1143)
		(layer "In13.Cu")
		(net "P5E_CPU1_P0_RX_DN<4>")
	)
	(arc
		(start 100.949252 -274.550886)
		(mid 100.705925 -274.08632)
		(end 100.949252 -273.621754)
		(width 0.1143)
		(layer "In13.Cu")
		(net "P5E_CPU1_P0_RX_DN<4>")
	)
	(arc
		(start 101.020118 -289.780218)
		(mid 101.175945 -289.47618)
		(end 101.020118 -289.172142)
		(width 0.1143)
		(layer "In13.Cu")
		(net "P5E_CPU1_P0_RX_DN<4>")
	)
	(arc
		(start 100.949252 -277.79091)
		(mid 100.705925 -277.326344)
		(end 100.949252 -276.861778)
		(width 0.1143)
		(layer "In13.Cu")
		(net "P5E_CPU1_P0_RX_DN<4>")
	)
	(arc
		(start 101.018848 -275.201126)
		(mid 101.175825 -274.896326)
		(end 101.018848 -274.591526)
		(width 0.1143)
		(layer "In13.Cu")
		(net "P5E_CPU1_P0_RX_DN<4>")
	)
	(arc
		(start 100.950776 -287.511744)
		(mid 100.770984 -287.309156)
		(end 100.706174 -287.046162)
		(width 0.1143)
		(layer "In13.Cu")
		(net "P5E_CPU1_P0_RX_DN<4>")
	)
	(arc
		(start 101.020118 -294.640254)
		(mid 101.175945 -294.336216)
		(end 101.020118 -294.032178)
		(width 0.1143)
		(layer "In13.Cu")
		(net "P5E_CPU1_P0_RX_DN<4>")
	)
	(segment
		(start 50.870612 -385.31038)
		(end 51.391312 -385.31038)
		(width 0.127)
		(layer "F.Cu")
		(net "P5E_CPU1_P0_RX_DN<3>")
	)
	(segment
		(start 101.268022 -271.390364)
		(end 100.80117 -271.656302)
		(width 0.12954)
		(layer "F.Cu")
		(net "P5E_CPU1_P0_RX_DN<3>")
	)
	(segment
		(start 107.89412 -362.091224)
		(end 108.32084 -362.091224)
		(width 0.14224)
		(layer "In13.Cu")
		(net "P5E_CPU1_P0_RX_DN<3>")
	)
	(segment
		(start 126.626112 -357.900478)
		(end 126.626112 -358.101646)
		(width 0.14224)
		(layer "In13.Cu")
		(net "P5E_CPU1_P0_RX_DN<3>")
	)
	(segment
		(start 105.14457 -363.751876)
		(end 105.495852 -363.400594)
		(width 0.14224)
		(layer "In13.Cu")
		(net "P5E_CPU1_P0_RX_DN<3>")
	)
	(segment
		(start 106.837734 -362.228384)
		(end 107.75696 -362.228384)
		(width 0.14224)
		(layer "In13.Cu")
		(net "P5E_CPU1_P0_RX_DN<3>")
	)
	(segment
		(start 105.495852 -363.206538)
		(end 105.797858 -362.904532)
		(width 0.14224)
		(layer "In13.Cu")
		(net "P5E_CPU1_P0_RX_DN<3>")
	)
	(segment
		(start 110.9345 -359.952544)
		(end 122.46229 -359.952544)
		(width 0.14224)
		(layer "In13.Cu")
		(net "P5E_CPU1_P0_RX_DN<3>")
	)
	(segment
		(start 125.476 -332.970378)
		(end 123.788932 -326.234806)
		(width 0.14224)
		(layer "In13.Cu")
		(net "P5E_CPU1_P0_RX_DN<3>")
	)
	(segment
		(start 100.078794 -277.83155)
		(end 100.048314 -277.81377)
		(width 0.1143)
		(layer "In13.Cu")
		(net "P5E_CPU1_P0_RX_DN<3>")
	)
	(segment
		(start 100.010976 -294.680386)
		(end 100.080064 -294.640254)
		(width 0.1143)
		(layer "In13.Cu")
		(net "P5E_CPU1_P0_RX_DN<3>")
	)
	(segment
		(start 101.168962 -271.726152)
		(end 101.099112 -271.656302)
		(width 0.1143)
		(layer "In13.Cu")
		(net "P5E_CPU1_P0_RX_DN<3>")
	)
	(segment
		(start 100.048314 -276.838918)
		(end 100.078794 -276.821138)
		(width 0.1143)
		(layer "In13.Cu")
		(net "P5E_CPU1_P0_RX_DN<3>")
	)
	(segment
		(start 100.048314 -274.573746)
		(end 100.009198 -274.550886)
		(width 0.1143)
		(layer "In13.Cu")
		(net "P5E_CPU1_P0_RX_DN<3>")
	)
	(segment
		(start 100.009198 -281.721814)
		(end 100.048314 -281.698954)
		(width 0.1143)
		(layer "In13.Cu")
		(net "P5E_CPU1_P0_RX_DN<3>")
	)
	(segment
		(start 109.27334 -362.228384)
		(end 109.4105 -362.091224)
		(width 0.14224)
		(layer "In13.Cu")
		(net "P5E_CPU1_P0_RX_DN<3>")
	)
	(segment
		(start 100.078794 -276.211538)
		(end 100.048314 -276.193758)
		(width 0.1143)
		(layer "In13.Cu")
		(net "P5E_CPU1_P0_RX_DN<3>")
	)
	(segment
		(start 51.8668 -385.334764)
		(end 51.8668 -385.163822)
		(width 0.14224)
		(layer "In13.Cu")
		(net "P5E_CPU1_P0_RX_DN<3>")
	)
	(segment
		(start 99.885754 -294.805608)
		(end 100.010976 -294.680386)
		(width 0.1143)
		(layer "In13.Cu")
		(net "P5E_CPU1_P0_RX_DN<3>")
	)
	(segment
		(start 51.391312 -385.31038)
		(end 51.744626 -385.405376)
		(width 0.14224)
		(layer "In13.Cu")
		(net "P5E_CPU1_P0_RX_DN<3>")
	)
	(segment
		(start 100.048314 -281.053794)
		(end 100.009198 -281.030934)
		(width 0.1143)
		(layer "In13.Cu")
		(net "P5E_CPU1_P0_RX_DN<3>")
	)
	(segment
		(start 109.83722 -362.091224)
		(end 109.97438 -362.228384)
		(width 0.14224)
		(layer "In13.Cu")
		(net "P5E_CPU1_P0_RX_DN<3>")
	)
	(segment
		(start 130.352292 -355.021388)
		(end 128.741932 -349.20682)
		(width 0.14224)
		(layer "In13.Cu")
		(net "P5E_CPU1_P0_RX_DN<3>")
	)
	(segment
		(start 100.479098 -272.811748)
		(end 100.507038 -272.795492)
		(width 0.1143)
		(layer "In13.Cu")
		(net "P5E_CPU1_P0_RX_DN<3>")
	)
	(segment
		(start 126.626112 -358.101646)
		(end 127.030226 -358.50576)
		(width 0.14224)
		(layer "In13.Cu")
		(net "P5E_CPU1_P0_RX_DN<3>")
	)
	(segment
		(start 99.599242 -298.16298)
		(end 99.599242 -296.612564)
		(width 0.14224)
		(layer "In13.Cu")
		(net "P5E_CPU1_P0_RX_DN<3>")
	)
	(segment
		(start 110.348776 -306.85613)
		(end 105.466134 -304.246534)
		(width 0.14224)
		(layer "In13.Cu")
		(net "P5E_CPU1_P0_RX_DN<3>")
	)
	(segment
		(start 100.078794 -279.451562)
		(end 100.048314 -279.433782)
		(width 0.1143)
		(layer "In13.Cu")
		(net "P5E_CPU1_P0_RX_DN<3>")
	)
	(segment
		(start 111.18723 -307.645308)
		(end 111.136176 -307.569108)
		(width 0.14224)
		(layer "In13.Cu")
		(net "P5E_CPU1_P0_RX_DN<3>")
	)
	(segment
		(start 51.554634 -384.234944)
		(end 51.858672 -383.93116)
		(width 0.14224)
		(layer "In13.Cu")
		(net "P5E_CPU1_P0_RX_DN<3>")
	)
	(segment
		(start 100.078794 -282.691586)
		(end 100.048314 -282.673806)
		(width 0.1143)
		(layer "In13.Cu")
		(net "P5E_CPU1_P0_RX_DN<3>")
	)
	(segment
		(start 53.228494 -373.617744)
		(end 56.3245 -368.572542)
		(width 0.14224)
		(layer "In13.Cu")
		(net "P5E_CPU1_P0_RX_DN<3>")
	)
	(segment
		(start 120.819164 -320.632328)
		(end 111.18723 -307.645308)
		(width 0.14224)
		(layer "In13.Cu")
		(net "P5E_CPU1_P0_RX_DN<3>")
	)
	(segment
		(start 99.644962 -296.538396)
		(end 99.644962 -295.663112)
		(width 0.1143)
		(layer "In13.Cu")
		(net "P5E_CPU1_P0_RX_DN<3>")
	)
	(segment
		(start 107.75696 -362.228384)
		(end 107.89412 -362.091224)
		(width 0.14224)
		(layer "In13.Cu")
		(net "P5E_CPU1_P0_RX_DN<3>")
	)
	(segment
		(start 100.009198 -284.961838)
		(end 100.048314 -284.938978)
		(width 0.1143)
		(layer "In13.Cu")
		(net "P5E_CPU1_P0_RX_DN<3>")
	)
	(segment
		(start 110.62716 -360.259884)
		(end 110.9345 -359.952544)
		(width 0.14224)
		(layer "In13.Cu")
		(net "P5E_CPU1_P0_RX_DN<3>")
	)
	(segment
		(start 99.599242 -296.612564)
		(end 99.599242 -296.584116)
		(width 0.1143)
		(layer "In13.Cu")
		(net "P5E_CPU1_P0_RX_DN<3>")
	)
	(segment
		(start 99.752912 -295.269412)
		(end 99.752912 -295.125648)
		(width 0.1143)
		(layer "In13.Cu")
		(net "P5E_CPU1_P0_RX_DN<3>")
	)
	(segment
		(start 129.359152 -355.167438)
		(end 126.626112 -357.900478)
		(width 0.14224)
		(layer "In13.Cu")
		(net "P5E_CPU1_P0_RX_DN<3>")
	)
	(segment
		(start 105.04678 -303.935384)
		(end 99.828858 -298.717462)
		(width 0.14224)
		(layer "In13.Cu")
		(net "P5E_CPU1_P0_RX_DN<3>")
	)
	(segment
		(start 100.010722 -289.820604)
		(end 100.07981 -289.780218)
		(width 0.1143)
		(layer "In13.Cu")
		(net "P5E_CPU1_P0_RX_DN<3>")
	)
	(segment
		(start 100.518214 -272.788888)
		(end 100.518976 -272.78838)
		(width 0.1143)
		(layer "In13.Cu")
		(net "P5E_CPU1_P0_RX_DN<3>")
	)
	(segment
		(start 100.009198 -278.48179)
		(end 100.048314 -278.45893)
		(width 0.1143)
		(layer "In13.Cu")
		(net "P5E_CPU1_P0_RX_DN<3>")
	)
	(segment
		(start 100.518976 -272.78838)
		(end 100.520246 -272.787618)
		(width 0.1143)
		(layer "In13.Cu")
		(net "P5E_CPU1_P0_RX_DN<3>")
	)
	(segment
		(start 110.9345 -361.372404)
		(end 110.62716 -361.065064)
		(width 0.14224)
		(layer "In13.Cu")
		(net "P5E_CPU1_P0_RX_DN<3>")
	)
	(segment
		(start 100.525834 -272.78457)
		(end 100.526596 -272.784062)
		(width 0.1143)
		(layer "In13.Cu")
		(net "P5E_CPU1_P0_RX_DN<3>")
	)
	(segment
		(start 100.009198 -273.621754)
		(end 100.048314 -273.598894)
		(width 0.1143)
		(layer "In13.Cu")
		(net "P5E_CPU1_P0_RX_DN<3>")
	)
	(segment
		(start 100.078794 -284.311598)
		(end 100.048314 -284.293818)
		(width 0.1143)
		(layer "In13.Cu")
		(net "P5E_CPU1_P0_RX_DN<3>")
	)
	(segment
		(start 128.78943 -354.162868)
		(end 129.359152 -354.73259)
		(width 0.14224)
		(layer "In13.Cu")
		(net "P5E_CPU1_P0_RX_DN<3>")
	)
	(segment
		(start 100.008436 -286.58185)
		(end 100.07981 -286.540448)
		(width 0.1143)
		(layer "In13.Cu")
		(net "P5E_CPU1_P0_RX_DN<3>")
	)
	(segment
		(start 108.458 -362.228384)
		(end 109.27334 -362.228384)
		(width 0.14224)
		(layer "In13.Cu")
		(net "P5E_CPU1_P0_RX_DN<3>")
	)
	(segment
		(start 100.080064 -285.932372)
		(end 100.009198 -285.89097)
		(width 0.1143)
		(layer "In13.Cu")
		(net "P5E_CPU1_P0_RX_DN<3>")
	)
	(segment
		(start 100.048314 -273.598894)
		(end 100.078794 -273.581114)
		(width 0.1143)
		(layer "In13.Cu")
		(net "P5E_CPU1_P0_RX_DN<3>")
	)
	(segment
		(start 100.048314 -276.193758)
		(end 100.009198 -276.170898)
		(width 0.1143)
		(layer "In13.Cu")
		(net "P5E_CPU1_P0_RX_DN<3>")
	)
	(segment
		(start 100.520246 -272.787618)
		(end 100.522786 -272.786348)
		(width 0.1143)
		(layer "In13.Cu")
		(net "P5E_CPU1_P0_RX_DN<3>")
	)
	(segment
		(start 56.952896 -367.775998)
		(end 57.719722 -367.009172)
		(width 0.14224)
		(layer "In13.Cu")
		(net "P5E_CPU1_P0_RX_DN<3>")
	)
	(segment
		(start 100.048314 -283.318966)
		(end 100.078794 -283.301186)
		(width 0.1143)
		(layer "In13.Cu")
		(net "P5E_CPU1_P0_RX_DN<3>")
	)
	(segment
		(start 100.009198 -275.241766)
		(end 100.048314 -275.218906)
		(width 0.1143)
		(layer "In13.Cu")
		(net "P5E_CPU1_P0_RX_DN<3>")
	)
	(segment
		(start 129.359152 -354.73259)
		(end 129.359152 -355.167438)
		(width 0.14224)
		(layer "In13.Cu")
		(net "P5E_CPU1_P0_RX_DN<3>")
	)
	(segment
		(start 100.048314 -280.078942)
		(end 100.078794 -280.061162)
		(width 0.1143)
		(layer "In13.Cu")
		(net "P5E_CPU1_P0_RX_DN<3>")
	)
	(segment
		(start 51.8668 -385.163822)
		(end 51.549808 -384.84683)
		(width 0.14224)
		(layer "In13.Cu")
		(net "P5E_CPU1_P0_RX_DN<3>")
	)
	(segment
		(start 121.682256 -361.514644)
		(end 121.540016 -361.372404)
		(width 0.14224)
		(layer "In13.Cu")
		(net "P5E_CPU1_P0_RX_DN<3>")
	)
	(segment
		(start 123.232672 -324.891908)
		(end 120.819164 -320.632328)
		(width 0.14224)
		(layer "In13.Cu")
		(net "P5E_CPU1_P0_RX_DN<3>")
	)
	(segment
		(start 105.797858 -362.904532)
		(end 105.991914 -362.904532)
		(width 0.14224)
		(layer "In13.Cu")
		(net "P5E_CPU1_P0_RX_DN<3>")
	)
	(segment
		(start 100.078032 -287.55086)
		(end 100.010722 -287.511744)
		(width 0.1143)
		(layer "In13.Cu")
		(net "P5E_CPU1_P0_RX_DN<3>")
	)
	(segment
		(start 100.514658 -272.79092)
		(end 100.515674 -272.790412)
		(width 0.1143)
		(layer "In13.Cu")
		(net "P5E_CPU1_P0_RX_DN<3>")
	)
	(segment
		(start 63.942976 -363.82579)
		(end 104.966262 -363.82579)
		(width 0.14224)
		(layer "In13.Cu")
		(net "P5E_CPU1_P0_RX_DN<3>")
	)
	(segment
		(start 100.048314 -284.293818)
		(end 100.009198 -284.270958)
		(width 0.1143)
		(layer "In13.Cu")
		(net "P5E_CPU1_P0_RX_DN<3>")
	)
	(segment
		(start 128.741932 -349.20682)
		(end 125.476 -332.970378)
		(width 0.14224)
		(layer "In13.Cu")
		(net "P5E_CPU1_P0_RX_DN<3>")
	)
	(segment
		(start 127.231394 -358.50576)
		(end 130.314954 -355.4222)
		(width 0.14224)
		(layer "In13.Cu")
		(net "P5E_CPU1_P0_RX_DN<3>")
	)
	(segment
		(start 122.63755 -359.8799)
		(end 128.354582 -354.162868)
		(width 0.14224)
		(layer "In13.Cu")
		(net "P5E_CPU1_P0_RX_DN<3>")
	)
	(segment
		(start 100.080064 -289.172142)
		(end 100.010722 -289.131756)
		(width 0.1143)
		(layer "In13.Cu")
		(net "P5E_CPU1_P0_RX_DN<3>")
	)
	(segment
		(start 100.080064 -294.032178)
		(end 100.010722 -293.991792)
		(width 0.1143)
		(layer "In13.Cu")
		(net "P5E_CPU1_P0_RX_DN<3>")
	)
	(segment
		(start 100.078794 -274.591526)
		(end 100.048314 -274.573746)
		(width 0.1143)
		(layer "In13.Cu")
		(net "P5E_CPU1_P0_RX_DN<3>")
	)
	(segment
		(start 100.515674 -272.790412)
		(end 100.517198 -272.789396)
		(width 0.1143)
		(layer "In13.Cu")
		(net "P5E_CPU1_P0_RX_DN<3>")
	)
	(segment
		(start 130.352292 -355.332284)
		(end 130.352292 -355.021388)
		(width 0.14224)
		(layer "In13.Cu")
		(net "P5E_CPU1_P0_RX_DN<3>")
	)
	(segment
		(start 100.048314 -279.433782)
		(end 100.009198 -279.410922)
		(width 0.1143)
		(layer "In13.Cu")
		(net "P5E_CPU1_P0_RX_DN<3>")
	)
	(segment
		(start 100.048314 -278.45893)
		(end 100.078794 -278.44115)
		(width 0.1143)
		(layer "In13.Cu")
		(net "P5E_CPU1_P0_RX_DN<3>")
	)
	(segment
		(start 99.669092 -295.541446)
		(end 99.726242 -295.403524)
		(width 0.1143)
		(layer "In13.Cu")
		(net "P5E_CPU1_P0_RX_DN<3>")
	)
	(segment
		(start 100.507038 -272.795492)
		(end 100.5078 -272.794984)
		(width 0.1143)
		(layer "In13.Cu")
		(net "P5E_CPU1_P0_RX_DN<3>")
	)
	(segment
		(start 100.048314 -282.673806)
		(end 100.009198 -282.650946)
		(width 0.1143)
		(layer "In13.Cu")
		(net "P5E_CPU1_P0_RX_DN<3>")
	)
	(segment
		(start 121.540016 -362.228384)
		(end 121.682256 -362.086144)
		(width 0.14224)
		(layer "In13.Cu")
		(net "P5E_CPU1_P0_RX_DN<3>")
	)
	(segment
		(start 100.526596 -272.784062)
		(end 100.549964 -272.7706)
		(width 0.1143)
		(layer "In13.Cu")
		(net "P5E_CPU1_P0_RX_DN<3>")
	)
	(segment
		(start 58.278268 -366.606582)
		(end 63.76035 -363.86897)
		(width 0.14224)
		(layer "In13.Cu")
		(net "P5E_CPU1_P0_RX_DN<3>")
	)
	(segment
		(start 99.599242 -296.584116)
		(end 99.644962 -296.538396)
		(width 0.1143)
		(layer "In13.Cu")
		(net "P5E_CPU1_P0_RX_DN<3>")
	)
	(segment
		(start 100.080064 -292.412166)
		(end 100.010722 -292.37178)
		(width 0.1143)
		(layer "In13.Cu")
		(net "P5E_CPU1_P0_RX_DN<3>")
	)
	(segment
		(start 100.048314 -284.938978)
		(end 100.078794 -284.921198)
		(width 0.1143)
		(layer "In13.Cu")
		(net "P5E_CPU1_P0_RX_DN<3>")
	)
	(segment
		(start 100.078794 -281.071574)
		(end 100.048314 -281.053794)
		(width 0.1143)
		(layer "In13.Cu")
		(net "P5E_CPU1_P0_RX_DN<3>")
	)
	(segment
		(start 100.009198 -276.861778)
		(end 100.048314 -276.838918)
		(width 0.1143)
		(layer "In13.Cu")
		(net "P5E_CPU1_P0_RX_DN<3>")
	)
	(segment
		(start 123.788932 -326.234806)
		(end 123.232672 -324.891908)
		(width 0.14224)
		(layer "In13.Cu")
		(net "P5E_CPU1_P0_RX_DN<3>")
	)
	(segment
		(start 100.517198 -272.789396)
		(end 100.518214 -272.788888)
		(width 0.1143)
		(layer "In13.Cu")
		(net "P5E_CPU1_P0_RX_DN<3>")
	)
	(segment
		(start 100.949252 -272.001742)
		(end 100.988368 -271.978882)
		(width 0.1143)
		(layer "In13.Cu")
		(net "P5E_CPU1_P0_RX_DN<3>")
	)
	(segment
		(start 109.97438 -362.228384)
		(end 121.540016 -362.228384)
		(width 0.14224)
		(layer "In13.Cu")
		(net "P5E_CPU1_P0_RX_DN<3>")
	)
	(segment
		(start 100.5078 -272.794984)
		(end 100.514658 -272.79092)
		(width 0.1143)
		(layer "In13.Cu")
		(net "P5E_CPU1_P0_RX_DN<3>")
	)
	(segment
		(start 100.522786 -272.786348)
		(end 100.52431 -272.785332)
		(width 0.1143)
		(layer "In13.Cu")
		(net "P5E_CPU1_P0_RX_DN<3>")
	)
	(segment
		(start 121.540016 -361.372404)
		(end 110.9345 -361.372404)
		(width 0.14224)
		(layer "In13.Cu")
		(net "P5E_CPU1_P0_RX_DN<3>")
	)
	(segment
		(start 100.009198 -280.101802)
		(end 100.048314 -280.078942)
		(width 0.1143)
		(layer "In13.Cu")
		(net "P5E_CPU1_P0_RX_DN<3>")
	)
	(segment
		(start 100.010722 -291.440616)
		(end 100.07981 -291.40023)
		(width 0.1143)
		(layer "In13.Cu")
		(net "P5E_CPU1_P0_RX_DN<3>")
	)
	(segment
		(start 51.745134 -385.404868)
		(end 51.8668 -385.334764)
		(width 0.14224)
		(layer "In13.Cu")
		(net "P5E_CPU1_P0_RX_DN<3>")
	)
	(segment
		(start 100.080064 -290.792154)
		(end 100.010722 -290.751768)
		(width 0.1143)
		(layer "In13.Cu")
		(net "P5E_CPU1_P0_RX_DN<3>")
	)
	(segment
		(start 121.682256 -362.086144)
		(end 121.682256 -361.514644)
		(width 0.14224)
		(layer "In13.Cu")
		(net "P5E_CPU1_P0_RX_DN<3>")
	)
	(segment
		(start 105.495852 -363.400594)
		(end 105.495852 -363.206538)
		(width 0.14224)
		(layer "In13.Cu")
		(net "P5E_CPU1_P0_RX_DN<3>")
	)
	(segment
		(start 109.4105 -362.091224)
		(end 109.83722 -362.091224)
		(width 0.14224)
		(layer "In13.Cu")
		(net "P5E_CPU1_P0_RX_DN<3>")
	)
	(segment
		(start 51.744626 -385.405376)
		(end 51.745134 -385.404868)
		(width 0.14224)
		(layer "In13.Cu")
		(net "P5E_CPU1_P0_RX_DN<3>")
	)
	(segment
		(start 101.099112 -271.656302)
		(end 100.80117 -271.656302)
		(width 0.1143)
		(layer "In13.Cu")
		(net "P5E_CPU1_P0_RX_DN<3>")
	)
	(segment
		(start 105.991914 -362.904532)
		(end 106.548174 -362.348272)
		(width 0.14224)
		(layer "In13.Cu")
		(net "P5E_CPU1_P0_RX_DN<3>")
	)
	(segment
		(start 128.354582 -354.162868)
		(end 128.78943 -354.162868)
		(width 0.14224)
		(layer "In13.Cu")
		(net "P5E_CPU1_P0_RX_DN<3>")
	)
	(segment
		(start 51.862736 -382.741678)
		(end 53.167026 -373.788178)
		(width 0.14224)
		(layer "In13.Cu")
		(net "P5E_CPU1_P0_RX_DN<3>")
	)
	(segment
		(start 100.988368 -271.978882)
		(end 101.018848 -271.961102)
		(width 0.1143)
		(layer "In13.Cu")
		(net "P5E_CPU1_P0_RX_DN<3>")
	)
	(segment
		(start 100.048314 -275.218906)
		(end 100.078794 -275.201126)
		(width 0.1143)
		(layer "In13.Cu")
		(net "P5E_CPU1_P0_RX_DN<3>")
	)
	(segment
		(start 127.030226 -358.50576)
		(end 127.231394 -358.50576)
		(width 0.14224)
		(layer "In13.Cu")
		(net "P5E_CPU1_P0_RX_DN<3>")
	)
	(segment
		(start 100.52431 -272.785332)
		(end 100.525834 -272.78457)
		(width 0.1143)
		(layer "In13.Cu")
		(net "P5E_CPU1_P0_RX_DN<3>")
	)
	(segment
		(start 51.858672 -383.93116)
		(end 51.858672 -382.800606)
		(width 0.14224)
		(layer "In13.Cu")
		(net "P5E_CPU1_P0_RX_DN<3>")
	)
	(segment
		(start 110.62716 -361.065064)
		(end 110.62716 -360.259884)
		(width 0.14224)
		(layer "In13.Cu")
		(net "P5E_CPU1_P0_RX_DN<3>")
	)
	(segment
		(start 100.008436 -288.201862)
		(end 100.07981 -288.16046)
		(width 0.1143)
		(layer "In13.Cu")
		(net "P5E_CPU1_P0_RX_DN<3>")
	)
	(segment
		(start 108.32084 -362.091224)
		(end 108.458 -362.228384)
		(width 0.14224)
		(layer "In13.Cu")
		(net "P5E_CPU1_P0_RX_DN<3>")
	)
	(segment
		(start 100.009198 -283.341826)
		(end 100.048314 -283.318966)
		(width 0.1143)
		(layer "In13.Cu")
		(net "P5E_CPU1_P0_RX_DN<3>")
	)
	(segment
		(start 100.048314 -277.81377)
		(end 100.009198 -277.79091)
		(width 0.1143)
		(layer "In13.Cu")
		(net "P5E_CPU1_P0_RX_DN<3>")
	)
	(segment
		(start 51.549808 -384.84683)
		(end 51.554634 -384.234944)
		(width 0.14224)
		(layer "In13.Cu")
		(net "P5E_CPU1_P0_RX_DN<3>")
	)
	(segment
		(start 100.048314 -281.698954)
		(end 100.078794 -281.681174)
		(width 0.1143)
		(layer "In13.Cu")
		(net "P5E_CPU1_P0_RX_DN<3>")
	)
	(segment
		(start 100.010722 -293.060628)
		(end 100.07981 -293.020242)
		(width 0.1143)
		(layer "In13.Cu")
		(net "P5E_CPU1_P0_RX_DN<3>")
	)
	(arc
		(start 100.078794 -275.201126)
		(mid 100.235771 -274.896326)
		(end 100.078794 -274.591526)
		(width 0.1143)
		(layer "In13.Cu")
		(net "P5E_CPU1_P0_RX_DN<3>")
	)
	(arc
		(start 99.828858 -298.717462)
		(mid 99.658928 -298.463049)
		(end 99.599242 -298.16298)
		(width 0.14224)
		(layer "In13.Cu")
		(net "P5E_CPU1_P0_RX_DN<3>")
	)
	(arc
		(start 100.009198 -284.270958)
		(mid 99.765871 -283.806392)
		(end 100.009198 -283.341826)
		(width 0.1143)
		(layer "In13.Cu")
		(net "P5E_CPU1_P0_RX_DN<3>")
	)
	(arc
		(start 100.078794 -284.921198)
		(mid 100.235771 -284.616398)
		(end 100.078794 -284.311598)
		(width 0.1143)
		(layer "In13.Cu")
		(net "P5E_CPU1_P0_RX_DN<3>")
	)
	(arc
		(start 111.136176 -307.569108)
		(mid 110.786315 -307.164202)
		(end 110.348776 -306.85613)
		(width 0.14224)
		(layer "In13.Cu")
		(net "P5E_CPU1_P0_RX_DN<3>")
	)
	(arc
		(start 100.010722 -287.511744)
		(mid 99.83093 -287.309156)
		(end 99.76612 -287.046162)
		(width 0.1143)
		(layer "In13.Cu")
		(net "P5E_CPU1_P0_RX_DN<3>")
	)
	(arc
		(start 100.010722 -293.991792)
		(mid 99.765901 -293.52621)
		(end 100.010722 -293.060628)
		(width 0.1143)
		(layer "In13.Cu")
		(net "P5E_CPU1_P0_RX_DN<3>")
	)
	(arc
		(start 100.009198 -277.79091)
		(mid 99.765871 -277.326344)
		(end 100.009198 -276.861778)
		(width 0.1143)
		(layer "In13.Cu")
		(net "P5E_CPU1_P0_RX_DN<3>")
	)
	(arc
		(start 100.078794 -281.681174)
		(mid 100.235771 -281.376374)
		(end 100.078794 -281.071574)
		(width 0.1143)
		(layer "In13.Cu")
		(net "P5E_CPU1_P0_RX_DN<3>")
	)
	(arc
		(start 56.3245 -368.572542)
		(mid 56.615272 -368.155789)
		(end 56.952896 -367.775998)
		(width 0.14224)
		(layer "In13.Cu")
		(net "P5E_CPU1_P0_RX_DN<3>")
	)
	(arc
		(start 100.07981 -291.40023)
		(mid 100.235743 -291.096295)
		(end 100.080064 -290.792154)
		(width 0.1143)
		(layer "In13.Cu")
		(net "P5E_CPU1_P0_RX_DN<3>")
	)
	(arc
		(start 100.009198 -281.030934)
		(mid 99.765871 -280.566368)
		(end 100.009198 -280.101802)
		(width 0.1143)
		(layer "In13.Cu")
		(net "P5E_CPU1_P0_RX_DN<3>")
	)
	(arc
		(start 100.010722 -289.131756)
		(mid 99.83093 -288.929168)
		(end 99.76612 -288.666174)
		(width 0.1143)
		(layer "In13.Cu")
		(net "P5E_CPU1_P0_RX_DN<3>")
	)
	(arc
		(start 99.752912 -295.125648)
		(mid 99.787484 -294.952406)
		(end 99.885754 -294.805608)
		(width 0.1143)
		(layer "In13.Cu")
		(net "P5E_CPU1_P0_RX_DN<3>")
	)
	(arc
		(start 100.07981 -288.16046)
		(mid 100.235635 -287.855256)
		(end 100.078032 -287.55086)
		(width 0.1143)
		(layer "In13.Cu")
		(net "P5E_CPU1_P0_RX_DN<3>")
	)
	(arc
		(start 104.966262 -363.82579)
		(mid 105.062769 -363.806576)
		(end 105.14457 -363.751876)
		(width 0.14224)
		(layer "In13.Cu")
		(net "P5E_CPU1_P0_RX_DN<3>")
	)
	(arc
		(start 53.167026 -373.788178)
		(mid 53.189087 -373.699833)
		(end 53.228494 -373.617744)
		(width 0.14224)
		(layer "In13.Cu")
		(net "P5E_CPU1_P0_RX_DN<3>")
	)
	(arc
		(start 101.018848 -271.961102)
		(mid 101.116613 -271.858126)
		(end 101.168962 -271.726152)
		(width 0.1143)
		(layer "In13.Cu")
		(net "P5E_CPU1_P0_RX_DN<3>")
	)
	(arc
		(start 100.009198 -279.410922)
		(mid 99.765871 -278.946356)
		(end 100.009198 -278.48179)
		(width 0.1143)
		(layer "In13.Cu")
		(net "P5E_CPU1_P0_RX_DN<3>")
	)
	(arc
		(start 100.009198 -276.170898)
		(mid 99.765871 -275.706332)
		(end 100.009198 -275.241766)
		(width 0.1143)
		(layer "In13.Cu")
		(net "P5E_CPU1_P0_RX_DN<3>")
	)
	(arc
		(start 100.078794 -278.44115)
		(mid 100.235771 -278.13635)
		(end 100.078794 -277.83155)
		(width 0.1143)
		(layer "In13.Cu")
		(net "P5E_CPU1_P0_RX_DN<3>")
	)
	(arc
		(start 100.080064 -294.640254)
		(mid 100.235891 -294.336216)
		(end 100.080064 -294.032178)
		(width 0.1143)
		(layer "In13.Cu")
		(net "P5E_CPU1_P0_RX_DN<3>")
	)
	(arc
		(start 100.010722 -290.751768)
		(mid 99.765901 -290.286186)
		(end 100.010722 -289.820604)
		(width 0.1143)
		(layer "In13.Cu")
		(net "P5E_CPU1_P0_RX_DN<3>")
	)
	(arc
		(start 106.548174 -362.348272)
		(mid 106.681039 -362.259557)
		(end 106.837734 -362.228384)
		(width 0.14224)
		(layer "In13.Cu")
		(net "P5E_CPU1_P0_RX_DN<3>")
	)
	(arc
		(start 100.078794 -273.581114)
		(mid 100.194221 -273.447738)
		(end 100.235766 -273.276314)
		(width 0.1143)
		(layer "In13.Cu")
		(net "P5E_CPU1_P0_RX_DN<3>")
	)
	(arc
		(start 100.009198 -274.550886)
		(mid 99.765871 -274.08632)
		(end 100.009198 -273.621754)
		(width 0.1143)
		(layer "In13.Cu")
		(net "P5E_CPU1_P0_RX_DN<3>")
	)
	(arc
		(start 100.70592 -272.466308)
		(mid 100.770435 -272.204089)
		(end 100.949252 -272.001742)
		(width 0.1143)
		(layer "In13.Cu")
		(net "P5E_CPU1_P0_RX_DN<3>")
	)
	(arc
		(start 99.726242 -295.403524)
		(mid 99.74618 -295.337781)
		(end 99.752912 -295.269412)
		(width 0.1143)
		(layer "In13.Cu")
		(net "P5E_CPU1_P0_RX_DN<3>")
	)
	(arc
		(start 99.76612 -288.666174)
		(mid 99.830296 -288.404287)
		(end 100.008436 -288.201862)
		(width 0.1143)
		(layer "In13.Cu")
		(net "P5E_CPU1_P0_RX_DN<3>")
	)
	(arc
		(start 100.549964 -272.7706)
		(mid 100.66464 -272.637266)
		(end 100.70592 -272.466308)
		(width 0.1143)
		(layer "In13.Cu")
		(net "P5E_CPU1_P0_RX_DN<3>")
	)
	(arc
		(start 100.235766 -273.276314)
		(mid 100.300281 -273.014095)
		(end 100.479098 -272.811748)
		(width 0.1143)
		(layer "In13.Cu")
		(net "P5E_CPU1_P0_RX_DN<3>")
	)
	(arc
		(start 63.76035 -363.86897)
		(mid 63.84915 -363.836747)
		(end 63.942976 -363.82579)
		(width 0.14224)
		(layer "In13.Cu")
		(net "P5E_CPU1_P0_RX_DN<3>")
	)
	(arc
		(start 100.078794 -276.821138)
		(mid 100.235771 -276.516338)
		(end 100.078794 -276.211538)
		(width 0.1143)
		(layer "In13.Cu")
		(net "P5E_CPU1_P0_RX_DN<3>")
	)
	(arc
		(start 100.078794 -283.301186)
		(mid 100.235771 -282.996386)
		(end 100.078794 -282.691586)
		(width 0.1143)
		(layer "In13.Cu")
		(net "P5E_CPU1_P0_RX_DN<3>")
	)
	(arc
		(start 51.858672 -382.800606)
		(mid 51.859645 -382.771069)
		(end 51.862736 -382.741678)
		(width 0.14224)
		(layer "In13.Cu")
		(net "P5E_CPU1_P0_RX_DN<3>")
	)
	(arc
		(start 100.07981 -293.020242)
		(mid 100.235743 -292.716307)
		(end 100.080064 -292.412166)
		(width 0.1143)
		(layer "In13.Cu")
		(net "P5E_CPU1_P0_RX_DN<3>")
	)
	(arc
		(start 105.466134 -304.246534)
		(mid 105.244975 -304.106432)
		(end 105.04678 -303.935384)
		(width 0.14224)
		(layer "In13.Cu")
		(net "P5E_CPU1_P0_RX_DN<3>")
	)
	(arc
		(start 100.07981 -286.540448)
		(mid 100.235743 -286.236513)
		(end 100.080064 -285.932372)
		(width 0.1143)
		(layer "In13.Cu")
		(net "P5E_CPU1_P0_RX_DN<3>")
	)
	(arc
		(start 100.009198 -285.89097)
		(mid 99.765871 -285.426404)
		(end 100.009198 -284.961838)
		(width 0.1143)
		(layer "In13.Cu")
		(net "P5E_CPU1_P0_RX_DN<3>")
	)
	(arc
		(start 100.010722 -292.37178)
		(mid 99.765901 -291.906198)
		(end 100.010722 -291.440616)
		(width 0.1143)
		(layer "In13.Cu")
		(net "P5E_CPU1_P0_RX_DN<3>")
	)
	(arc
		(start 100.009198 -282.650946)
		(mid 99.765871 -282.18638)
		(end 100.009198 -281.721814)
		(width 0.1143)
		(layer "In13.Cu")
		(net "P5E_CPU1_P0_RX_DN<3>")
	)
	(arc
		(start 130.314954 -355.4222)
		(mid 130.342573 -355.38096)
		(end 130.352292 -355.332284)
		(width 0.14224)
		(layer "In13.Cu")
		(net "P5E_CPU1_P0_RX_DN<3>")
	)
	(arc
		(start 100.07981 -289.780218)
		(mid 100.235743 -289.476283)
		(end 100.080064 -289.172142)
		(width 0.1143)
		(layer "In13.Cu")
		(net "P5E_CPU1_P0_RX_DN<3>")
	)
	(arc
		(start 57.719722 -367.009172)
		(mid 57.982739 -366.785325)
		(end 58.278268 -366.606582)
		(width 0.14224)
		(layer "In13.Cu")
		(net "P5E_CPU1_P0_RX_DN<3>")
	)
	(arc
		(start 122.46229 -359.952544)
		(mid 122.557145 -359.933658)
		(end 122.63755 -359.8799)
		(width 0.14224)
		(layer "In13.Cu")
		(net "P5E_CPU1_P0_RX_DN<3>")
	)
	(arc
		(start 99.644962 -295.663112)
		(mid 99.651024 -295.601087)
		(end 99.669092 -295.541446)
		(width 0.1143)
		(layer "In13.Cu")
		(net "P5E_CPU1_P0_RX_DN<3>")
	)
	(arc
		(start 99.76612 -287.046162)
		(mid 99.830296 -286.784275)
		(end 100.008436 -286.58185)
		(width 0.1143)
		(layer "In13.Cu")
		(net "P5E_CPU1_P0_RX_DN<3>")
	)
	(arc
		(start 100.078794 -280.061162)
		(mid 100.235771 -279.756362)
		(end 100.078794 -279.451562)
		(width 0.1143)
		(layer "In13.Cu")
		(net "P5E_CPU1_P0_RX_DN<3>")
	)
	(segment
		(start 49.670716 -385.31038)
		(end 50.191416 -385.31038)
		(width 0.127)
		(layer "F.Cu")
		(net "P5E_CPU1_P0_RX_DN<2>")
	)
	(segment
		(start 98.44786 -269.770352)
		(end 97.981008 -270.03629)
		(width 0.12954)
		(layer "F.Cu")
		(net "P5E_CPU1_P0_RX_DN<2>")
	)
	(segment
		(start 99.108006 -279.433782)
		(end 99.105212 -279.432004)
		(width 0.1143)
		(layer "In13.Cu")
		(net "P5E_CPU1_P0_RX_DN<2>")
	)
	(segment
		(start 99.068382 -280.101802)
		(end 99.139756 -280.060654)
		(width 0.1143)
		(layer "In13.Cu")
		(net "P5E_CPU1_P0_RX_DN<2>")
	)
	(segment
		(start 123.049284 -354.3935)
		(end 127.56642 -349.876364)
		(width 0.14224)
		(layer "In13.Cu")
		(net "P5E_CPU1_P0_RX_DN<2>")
	)
	(segment
		(start 99.10953 -283.318204)
		(end 99.110292 -283.317696)
		(width 0.1143)
		(layer "In13.Cu")
		(net "P5E_CPU1_P0_RX_DN<2>")
	)
	(segment
		(start 99.113086 -278.456136)
		(end 99.113848 -278.455628)
		(width 0.1143)
		(layer "In13.Cu")
		(net "P5E_CPU1_P0_RX_DN<2>")
	)
	(segment
		(start 99.111308 -281.697176)
		(end 99.11207 -281.696668)
		(width 0.1143)
		(layer "In13.Cu")
		(net "P5E_CPU1_P0_RX_DN<2>")
	)
	(segment
		(start 110.406942 -357.025448)
		(end 110.714282 -356.718108)
		(width 0.14224)
		(layer "In13.Cu")
		(net "P5E_CPU1_P0_RX_DN<2>")
	)
	(segment
		(start 99.139756 -279.45207)
		(end 99.115118 -279.437846)
		(width 0.1143)
		(layer "In13.Cu")
		(net "P5E_CPU1_P0_RX_DN<2>")
	)
	(segment
		(start 99.134168 -293.023544)
		(end 99.135438 -293.023544)
		(width 0.1143)
		(layer "In13.Cu")
		(net "P5E_CPU1_P0_RX_DN<2>")
	)
	(segment
		(start 121.76506 -356.580948)
		(end 122.19178 -356.580948)
		(width 0.14224)
		(layer "In13.Cu")
		(net "P5E_CPU1_P0_RX_DN<2>")
	)
	(segment
		(start 110.580424 -308.631336)
		(end 109.886496 -308.061868)
		(width 0.14224)
		(layer "In13.Cu")
		(net "P5E_CPU1_P0_RX_DN<2>")
	)
	(segment
		(start 99.107752 -289.799014)
		(end 99.128072 -289.78733)
		(width 0.1143)
		(layer "In13.Cu")
		(net "P5E_CPU1_P0_RX_DN<2>")
	)
	(segment
		(start 98.310192 -298.352464)
		(end 98.310192 -296.422318)
		(width 0.14224)
		(layer "In13.Cu")
		(net "P5E_CPU1_P0_RX_DN<2>")
	)
	(segment
		(start 99.094544 -287.524952)
		(end 99.094798 -287.525206)
		(width 0.1143)
		(layer "In13.Cu")
		(net "P5E_CPU1_P0_RX_DN<2>")
	)
	(segment
		(start 123.618498 -355.397562)
		(end 123.049284 -354.828348)
		(width 0.14224)
		(layer "In13.Cu")
		(net "P5E_CPU1_P0_RX_DN<2>")
	)
	(segment
		(start 127.601472 -349.763842)
		(end 124.895356 -334.849978)
		(width 0.14224)
		(layer "In13.Cu")
		(net "P5E_CPU1_P0_RX_DN<2>")
	)
	(segment
		(start 99.105212 -279.432004)
		(end 99.069144 -279.411176)
		(width 0.1143)
		(layer "In13.Cu")
		(net "P5E_CPU1_P0_RX_DN<2>")
	)
	(segment
		(start 123.4567 -356.718108)
		(end 123.891802 -356.718108)
		(width 0.14224)
		(layer "In13.Cu")
		(net "P5E_CPU1_P0_RX_DN<2>")
	)
	(segment
		(start 98.820478 -295.326054)
		(end 98.820478 -295.15181)
		(width 0.1143)
		(layer "In13.Cu")
		(net "P5E_CPU1_P0_RX_DN<2>")
	)
	(segment
		(start 99.108006 -272.953734)
		(end 99.071684 -272.932652)
		(width 0.1143)
		(layer "In13.Cu")
		(net "P5E_CPU1_P0_RX_DN<2>")
	)
	(segment
		(start 99.114102 -279.437338)
		(end 99.112578 -279.436322)
		(width 0.1143)
		(layer "In13.Cu")
		(net "P5E_CPU1_P0_RX_DN<2>")
	)
	(segment
		(start 99.108006 -284.938978)
		(end 99.139756 -284.92069)
		(width 0.1143)
		(layer "In13.Cu")
		(net "P5E_CPU1_P0_RX_DN<2>")
	)
	(segment
		(start 106.546142 -360.953558)
		(end 106.737404 -360.985562)
		(width 0.14224)
		(layer "In13.Cu")
		(net "P5E_CPU1_P0_RX_DN<2>")
	)
	(segment
		(start 99.113086 -283.316172)
		(end 99.113848 -283.315664)
		(width 0.1143)
		(layer "In13.Cu")
		(net "P5E_CPU1_P0_RX_DN<2>")
	)
	(segment
		(start 99.069144 -284.271212)
		(end 99.041204 -284.251146)
		(width 0.1143)
		(layer "In13.Cu")
		(net "P5E_CPU1_P0_RX_DN<2>")
	)
	(segment
		(start 99.068382 -281.030934)
		(end 99.041458 -281.011376)
		(width 0.1143)
		(layer "In13.Cu")
		(net "P5E_CPU1_P0_RX_DN<2>")
	)
	(segment
		(start 99.041204 -278.501602)
		(end 99.069144 -278.481536)
		(width 0.1143)
		(layer "In13.Cu")
		(net "P5E_CPU1_P0_RX_DN<2>")
	)
	(segment
		(start 99.114102 -277.817326)
		(end 99.112578 -277.81631)
		(width 0.1143)
		(layer "In13.Cu")
		(net "P5E_CPU1_P0_RX_DN<2>")
	)
	(segment
		(start 99.108006 -285.91383)
		(end 99.071684 -285.892748)
		(width 0.1143)
		(layer "In13.Cu")
		(net "P5E_CPU1_P0_RX_DN<2>")
	)
	(segment
		(start 99.139756 -271.35201)
		(end 99.114864 -271.337786)
		(width 0.1143)
		(layer "In13.Cu")
		(net "P5E_CPU1_P0_RX_DN<2>")
	)
	(segment
		(start 99.114102 -274.577302)
		(end 99.112578 -274.576286)
		(width 0.1143)
		(layer "In13.Cu")
		(net "P5E_CPU1_P0_RX_DN<2>")
	)
	(segment
		(start 99.110292 -278.45766)
		(end 99.111308 -278.457152)
		(width 0.1143)
		(layer "In13.Cu")
		(net "P5E_CPU1_P0_RX_DN<2>")
	)
	(segment
		(start 123.399804 -328.721466)
		(end 123.39955 -328.721466)
		(width 0.14224)
		(layer "In13.Cu")
		(net "P5E_CPU1_P0_RX_DN<2>")
	)
	(segment
		(start 99.115118 -279.437846)
		(end 99.114102 -279.437338)
		(width 0.1143)
		(layer "In13.Cu")
		(net "P5E_CPU1_P0_RX_DN<2>")
	)
	(segment
		(start 99.109022 -288.178494)
		(end 99.137978 -288.161222)
		(width 0.1143)
		(layer "In13.Cu")
		(net "P5E_CPU1_P0_RX_DN<2>")
	)
	(segment
		(start 99.110292 -276.837648)
		(end 99.111308 -276.83714)
		(width 0.1143)
		(layer "In13.Cu")
		(net "P5E_CPU1_P0_RX_DN<2>")
	)
	(segment
		(start 123.39955 -328.721466)
		(end 122.90171 -326.679306)
		(width 0.14224)
		(layer "In13.Cu")
		(net "P5E_CPU1_P0_RX_DN<2>")
	)
	(segment
		(start 99.117404 -294.653462)
		(end 99.118928 -294.6527)
		(width 0.1143)
		(layer "In13.Cu")
		(net "P5E_CPU1_P0_RX_DN<2>")
	)
	(segment
		(start 99.113848 -278.455628)
		(end 99.114864 -278.45512)
		(width 0.1143)
		(layer "In13.Cu")
		(net "P5E_CPU1_P0_RX_DN<2>")
	)
	(segment
		(start 99.107498 -293.039038)
		(end 99.133152 -293.024052)
		(width 0.1143)
		(layer "In13.Cu")
		(net "P5E_CPU1_P0_RX_DN<2>")
	)
	(segment
		(start 99.101656 -289.150044)
		(end 99.100386 -289.149282)
		(width 0.1143)
		(layer "In13.Cu")
		(net "P5E_CPU1_P0_RX_DN<2>")
	)
	(segment
		(start 99.095306 -287.52546)
		(end 99.094544 -287.524952)
		(width 0.1143)
		(layer "In13.Cu")
		(net "P5E_CPU1_P0_RX_DN<2>")
	)
	(segment
		(start 99.113086 -281.69616)
		(end 99.113848 -281.695652)
		(width 0.1143)
		(layer "In13.Cu")
		(net "P5E_CPU1_P0_RX_DN<2>")
	)
	(segment
		(start 99.115118 -282.67787)
		(end 99.114102 -282.677362)
		(width 0.1143)
		(layer "In13.Cu")
		(net "P5E_CPU1_P0_RX_DN<2>")
	)
	(segment
		(start 99.089718 -287.521904)
		(end 99.088956 -287.521142)
		(width 0.1143)
		(layer "In13.Cu")
		(net "P5E_CPU1_P0_RX_DN<2>")
	)
	(segment
		(start 99.139756 -272.972022)
		(end 99.108006 -272.953734)
		(width 0.1143)
		(layer "In13.Cu")
		(net "P5E_CPU1_P0_RX_DN<2>")
	)
	(segment
		(start 99.115626 -281.694636)
		(end 99.116642 -281.694128)
		(width 0.1143)
		(layer "In13.Cu")
		(net "P5E_CPU1_P0_RX_DN<2>")
	)
	(segment
		(start 99.115118 -274.57781)
		(end 99.114102 -274.577302)
		(width 0.1143)
		(layer "In13.Cu")
		(net "P5E_CPU1_P0_RX_DN<2>")
	)
	(segment
		(start 98.310192 -296.39387)
		(end 98.351848 -296.343324)
		(width 0.1143)
		(layer "In13.Cu")
		(net "P5E_CPU1_P0_RX_DN<2>")
	)
	(segment
		(start 99.110038 -284.295088)
		(end 99.108768 -284.294326)
		(width 0.1143)
		(layer "In13.Cu")
		(net "P5E_CPU1_P0_RX_DN<2>")
	)
	(segment
		(start 122.75566 -356.718108)
		(end 122.89282 -356.580948)
		(width 0.14224)
		(layer "In13.Cu")
		(net "P5E_CPU1_P0_RX_DN<2>")
	)
	(segment
		(start 99.113848 -281.695652)
		(end 99.114864 -281.695144)
		(width 0.1143)
		(layer "In13.Cu")
		(net "P5E_CPU1_P0_RX_DN<2>")
	)
	(segment
		(start 99.116642 -294.65397)
		(end 99.117404 -294.653462)
		(width 0.1143)
		(layer "In13.Cu")
		(net "P5E_CPU1_P0_RX_DN<2>")
	)
	(segment
		(start 99.115118 -285.917894)
		(end 99.114102 -285.917386)
		(width 0.1143)
		(layer "In13.Cu")
		(net "P5E_CPU1_P0_RX_DN<2>")
	)
	(segment
		(start 99.108768 -284.294326)
		(end 99.108006 -284.293818)
		(width 0.1143)
		(layer "In13.Cu")
		(net "P5E_CPU1_P0_RX_DN<2>")
	)
	(segment
		(start 99.139756 -294.031924)
		(end 99.096576 -294.006778)
		(width 0.1143)
		(layer "In13.Cu")
		(net "P5E_CPU1_P0_RX_DN<2>")
	)
	(segment
		(start 99.108768 -279.43429)
		(end 99.108006 -279.433782)
		(width 0.1143)
		(layer "In13.Cu")
		(net "P5E_CPU1_P0_RX_DN<2>")
	)
	(segment
		(start 99.069144 -278.481536)
		(end 99.10953 -278.458168)
		(width 0.1143)
		(layer "In13.Cu")
		(net "P5E_CPU1_P0_RX_DN<2>")
	)
	(segment
		(start 122.19178 -356.580948)
		(end 122.32894 -356.718108)
		(width 0.14224)
		(layer "In13.Cu")
		(net "P5E_CPU1_P0_RX_DN<2>")
	)
	(segment
		(start 123.31954 -356.580948)
		(end 123.4567 -356.718108)
		(width 0.14224)
		(layer "In13.Cu")
		(net "P5E_CPU1_P0_RX_DN<2>")
	)
	(segment
		(start 99.071684 -271.999964)
		(end 99.073208 -271.998948)
		(width 0.1143)
		(layer "In13.Cu")
		(net "P5E_CPU1_P0_RX_DN<2>")
	)
	(segment
		(start 98.27895 -270.03629)
		(end 97.981008 -270.03629)
		(width 0.1143)
		(layer "In13.Cu")
		(net "P5E_CPU1_P0_RX_DN<2>")
	)
	(segment
		(start 99.088956 -287.521142)
		(end 99.072954 -287.510474)
		(width 0.1143)
		(layer "In13.Cu")
		(net "P5E_CPU1_P0_RX_DN<2>")
	)
	(segment
		(start 99.10953 -276.838156)
		(end 99.110292 -276.837648)
		(width 0.1143)
		(layer "In13.Cu")
		(net "P5E_CPU1_P0_RX_DN<2>")
	)
	(segment
		(start 99.115626 -283.314648)
		(end 99.116642 -283.31414)
		(width 0.1143)
		(layer "In13.Cu")
		(net "P5E_CPU1_P0_RX_DN<2>")
	)
	(segment
		(start 50.66665 -385.334764)
		(end 50.66665 -385.163822)
		(width 0.14224)
		(layer "In13.Cu")
		(net "P5E_CPU1_P0_RX_DN<2>")
	)
	(segment
		(start 122.89282 -356.580948)
		(end 123.31954 -356.580948)
		(width 0.14224)
		(layer "In13.Cu")
		(net "P5E_CPU1_P0_RX_DN<2>")
	)
	(segment
		(start 123.049284 -354.828348)
		(end 123.049284 -354.3935)
		(width 0.14224)
		(layer "In13.Cu")
		(net "P5E_CPU1_P0_RX_DN<2>")
	)
	(segment
		(start 121.088912 -323.132704)
		(end 117.604286 -317.918338)
		(width 0.14224)
		(layer "In13.Cu")
		(net "P5E_CPU1_P0_RX_DN<2>")
	)
	(segment
		(start 99.110038 -279.435052)
		(end 99.108768 -279.43429)
		(width 0.1143)
		(layer "In13.Cu")
		(net "P5E_CPU1_P0_RX_DN<2>")
	)
	(segment
		(start 99.111308 -278.457152)
		(end 99.11207 -278.456644)
		(width 0.1143)
		(layer "In13.Cu")
		(net "P5E_CPU1_P0_RX_DN<2>")
	)
	(segment
		(start 117.604286 -317.918338)
		(end 112.008158 -310.370982)
		(width 0.14224)
		(layer "In13.Cu")
		(net "P5E_CPU1_P0_RX_DN<2>")
	)
	(segment
		(start 128.33858 -352.12274)
		(end 127.933958 -351.718118)
		(width 0.14224)
		(layer "In13.Cu")
		(net "P5E_CPU1_P0_RX_DN<2>")
	)
	(segment
		(start 99.112578 -285.91637)
		(end 99.110038 -285.9151)
		(width 0.1143)
		(layer "In13.Cu")
		(net "P5E_CPU1_P0_RX_DN<2>")
	)
	(segment
		(start 127.73279 -351.718118)
		(end 124.053346 -355.397562)
		(width 0.14224)
		(layer "In13.Cu")
		(net "P5E_CPU1_P0_RX_DN<2>")
	)
	(segment
		(start 99.142296 -287.553908)
		(end 99.095306 -287.52546)
		(width 0.1143)
		(layer "In13.Cu")
		(net "P5E_CPU1_P0_RX_DN<2>")
	)
	(segment
		(start 50.66665 -385.163822)
		(end 50.349658 -384.84683)
		(width 0.14224)
		(layer "In13.Cu")
		(net "P5E_CPU1_P0_RX_DN<2>")
	)
	(segment
		(start 99.139756 -276.212046)
		(end 99.115118 -276.197822)
		(width 0.1143)
		(layer "In13.Cu")
		(net "P5E_CPU1_P0_RX_DN<2>")
	)
	(segment
		(start 99.128072 -289.78733)
		(end 99.139502 -289.780472)
		(width 0.1143)
		(layer "In13.Cu")
		(net "P5E_CPU1_P0_RX_DN<2>")
	)
	(segment
		(start 50.354484 -384.234944)
		(end 50.658522 -383.93116)
		(width 0.14224)
		(layer "In13.Cu")
		(net "P5E_CPU1_P0_RX_DN<2>")
	)
	(segment
		(start 99.112578 -279.436322)
		(end 99.110038 -279.435052)
		(width 0.1143)
		(layer "In13.Cu")
		(net "P5E_CPU1_P0_RX_DN<2>")
	)
	(segment
		(start 99.072954 -287.510474)
		(end 98.996754 -287.434274)
		(width 0.1143)
		(layer "In13.Cu")
		(net "P5E_CPU1_P0_RX_DN<2>")
	)
	(segment
		(start 99.139502 -288.160206)
		(end 99.143312 -288.15792)
		(width 0.1143)
		(layer "In13.Cu")
		(net "P5E_CPU1_P0_RX_DN<2>")
	)
	(segment
		(start 127.933958 -351.718118)
		(end 127.73279 -351.718118)
		(width 0.14224)
		(layer "In13.Cu")
		(net "P5E_CPU1_P0_RX_DN<2>")
	)
	(segment
		(start 99.112578 -284.296358)
		(end 99.110038 -284.295088)
		(width 0.1143)
		(layer "In13.Cu")
		(net "P5E_CPU1_P0_RX_DN<2>")
	)
	(segment
		(start 99.108006 -271.978882)
		(end 99.139756 -271.960594)
		(width 0.1143)
		(layer "In13.Cu")
		(net "P5E_CPU1_P0_RX_DN<2>")
	)
	(segment
		(start 99.073208 -273.61896)
		(end 99.108006 -273.598894)
		(width 0.1143)
		(layer "In13.Cu")
		(net "P5E_CPU1_P0_RX_DN<2>")
	)
	(segment
		(start 98.510852 -295.688258)
		(end 98.78314 -295.416224)
		(width 0.1143)
		(layer "In13.Cu")
		(net "P5E_CPU1_P0_RX_DN<2>")
	)
	(segment
		(start 99.108006 -284.293818)
		(end 99.105212 -284.29204)
		(width 0.1143)
		(layer "In13.Cu")
		(net "P5E_CPU1_P0_RX_DN<2>")
	)
	(segment
		(start 99.069144 -282.6512)
		(end 99.041204 -282.631134)
		(width 0.1143)
		(layer "In13.Cu")
		(net "P5E_CPU1_P0_RX_DN<2>")
	)
	(segment
		(start 50.544984 -385.404868)
		(end 50.66665 -385.334764)
		(width 0.14224)
		(layer "In13.Cu")
		(net "P5E_CPU1_P0_RX_DN<2>")
	)
	(segment
		(start 63.797688 -362.89107)
		(end 104.0003 -362.89107)
		(width 0.14224)
		(layer "In13.Cu")
		(net "P5E_CPU1_P0_RX_DN<2>")
	)
	(segment
		(start 99.09175 -287.523174)
		(end 99.089718 -287.521904)
		(width 0.1143)
		(layer "In13.Cu")
		(net "P5E_CPU1_P0_RX_DN<2>")
	)
	(segment
		(start 120.829324 -358.137968)
		(end 110.714282 -358.137968)
		(width 0.14224)
		(layer "In13.Cu")
		(net "P5E_CPU1_P0_RX_DN<2>")
	)
	(segment
		(start 99.112578 -282.676346)
		(end 99.110038 -282.675076)
		(width 0.1143)
		(layer "In13.Cu")
		(net "P5E_CPU1_P0_RX_DN<2>")
	)
	(segment
		(start 99.069144 -275.241512)
		(end 99.10953 -275.218144)
		(width 0.1143)
		(layer "In13.Cu")
		(net "P5E_CPU1_P0_RX_DN<2>")
	)
	(segment
		(start 99.110292 -283.317696)
		(end 99.111308 -283.317188)
		(width 0.1143)
		(layer "In13.Cu")
		(net "P5E_CPU1_P0_RX_DN<2>")
	)
	(segment
		(start 99.041204 -275.261578)
		(end 99.069144 -275.241512)
		(width 0.1143)
		(layer "In13.Cu")
		(net "P5E_CPU1_P0_RX_DN<2>")
	)
	(segment
		(start 99.110038 -276.195028)
		(end 99.108768 -276.194266)
		(width 0.1143)
		(layer "In13.Cu")
		(net "P5E_CPU1_P0_RX_DN<2>")
	)
	(segment
		(start 99.108768 -276.194266)
		(end 99.108006 -276.193758)
		(width 0.1143)
		(layer "In13.Cu")
		(net "P5E_CPU1_P0_RX_DN<2>")
	)
	(segment
		(start 99.108768 -271.33423)
		(end 99.108006 -271.333722)
		(width 0.1143)
		(layer "In13.Cu")
		(net "P5E_CPU1_P0_RX_DN<2>")
	)
	(segment
		(start 99.106482 -289.153092)
		(end 99.103942 -289.151568)
		(width 0.1143)
		(layer "In13.Cu")
		(net "P5E_CPU1_P0_RX_DN<2>")
	)
	(segment
		(start 99.138994 -290.791646)
		(end 99.10064 -290.76904)
		(width 0.1143)
		(layer "In13.Cu")
		(net "P5E_CPU1_P0_RX_DN<2>")
	)
	(segment
		(start 99.069144 -281.72156)
		(end 99.10953 -281.698192)
		(width 0.1143)
		(layer "In13.Cu")
		(net "P5E_CPU1_P0_RX_DN<2>")
	)
	(segment
		(start 98.678746 -270.548354)
		(end 98.669856 -270.542004)
		(width 0.1143)
		(layer "In13.Cu")
		(net "P5E_CPU1_P0_RX_DN<2>")
	)
	(segment
		(start 99.105212 -277.811992)
		(end 99.069144 -277.791164)
		(width 0.1143)
		(layer "In13.Cu")
		(net "P5E_CPU1_P0_RX_DN<2>")
	)
	(segment
		(start 99.110292 -275.217636)
		(end 99.111308 -275.217128)
		(width 0.1143)
		(layer "In13.Cu")
		(net "P5E_CPU1_P0_RX_DN<2>")
	)
	(segment
		(start 99.108006 -277.81377)
		(end 99.105212 -277.811992)
		(width 0.1143)
		(layer "In13.Cu")
		(net "P5E_CPU1_P0_RX_DN<2>")
	)
	(segment
		(start 99.11207 -278.456644)
		(end 99.113086 -278.456136)
		(width 0.1143)
		(layer "In13.Cu")
		(net "P5E_CPU1_P0_RX_DN<2>")
	)
	(segment
		(start 98.351848 -296.343324)
		(end 98.351848 -296.072814)
		(width 0.1143)
		(layer "In13.Cu")
		(net "P5E_CPU1_P0_RX_DN<2>")
	)
	(segment
		(start 99.13493 -285.929324)
		(end 99.115118 -285.917894)
		(width 0.1143)
		(layer "In13.Cu")
		(net "P5E_CPU1_P0_RX_DN<2>")
	)
	(segment
		(start 124.053346 -355.397562)
		(end 123.618498 -355.397562)
		(width 0.14224)
		(layer "In13.Cu")
		(net "P5E_CPU1_P0_RX_DN<2>")
	)
	(segment
		(start 98.310192 -296.422318)
		(end 98.310192 -296.39387)
		(width 0.1143)
		(layer "In13.Cu")
		(net "P5E_CPU1_P0_RX_DN<2>")
	)
	(segment
		(start 106.737404 -360.985562)
		(end 109.403388 -359.084372)
		(width 0.14224)
		(layer "In13.Cu")
		(net "P5E_CPU1_P0_RX_DN<2>")
	)
	(segment
		(start 99.11207 -283.31668)
		(end 99.113086 -283.316172)
		(width 0.1143)
		(layer "In13.Cu")
		(net "P5E_CPU1_P0_RX_DN<2>")
	)
	(segment
		(start 99.110292 -281.697684)
		(end 99.111308 -281.697176)
		(width 0.1143)
		(layer "In13.Cu")
		(net "P5E_CPU1_P0_RX_DN<2>")
	)
	(segment
		(start 110.714282 -356.718108)
		(end 121.6279 -356.718108)
		(width 0.14224)
		(layer "In13.Cu")
		(net "P5E_CPU1_P0_RX_DN<2>")
	)
	(segment
		(start 99.108006 -273.598894)
		(end 99.139756 -273.580606)
		(width 0.1143)
		(layer "In13.Cu")
		(net "P5E_CPU1_P0_RX_DN<2>")
	)
	(segment
		(start 99.116642 -278.454104)
		(end 99.139756 -278.440642)
		(width 0.1143)
		(layer "In13.Cu")
		(net "P5E_CPU1_P0_RX_DN<2>")
	)
	(segment
		(start 123.981718 -356.68077)
		(end 128.33858 -352.323908)
		(width 0.14224)
		(layer "In13.Cu")
		(net "P5E_CPU1_P0_RX_DN<2>")
	)
	(segment
		(start 99.074478 -288.197798)
		(end 99.109022 -288.178494)
		(width 0.1143)
		(layer "In13.Cu")
		(net "P5E_CPU1_P0_RX_DN<2>")
	)
	(segment
		(start 98.825812 -270.846296)
		(end 98.825812 -270.835628)
		(width 0.1143)
		(layer "In13.Cu")
		(net "P5E_CPU1_P0_RX_DN<2>")
	)
	(segment
		(start 99.073208 -271.998948)
		(end 99.108006 -271.978882)
		(width 0.1143)
		(layer "In13.Cu")
		(net "P5E_CPU1_P0_RX_DN<2>")
	)
	(segment
		(start 99.104704 -294.660574)
		(end 99.108006 -294.658288)
		(width 0.1143)
		(layer "In13.Cu")
		(net "P5E_CPU1_P0_RX_DN<2>")
	)
	(segment
		(start 99.108768 -277.814278)
		(end 99.108006 -277.81377)
		(width 0.1143)
		(layer "In13.Cu")
		(net "P5E_CPU1_P0_RX_DN<2>")
	)
	(segment
		(start 99.112324 -271.336262)
		(end 99.111562 -271.335754)
		(width 0.1143)
		(layer "In13.Cu")
		(net "P5E_CPU1_P0_RX_DN<2>")
	)
	(segment
		(start 99.108006 -294.658288)
		(end 99.116642 -294.65397)
		(width 0.1143)
		(layer "In13.Cu")
		(net "P5E_CPU1_P0_RX_DN<2>")
	)
	(segment
		(start 99.11207 -276.836632)
		(end 99.113086 -276.836124)
		(width 0.1143)
		(layer "In13.Cu")
		(net "P5E_CPU1_P0_RX_DN<2>")
	)
	(segment
		(start 99.111308 -276.83714)
		(end 99.11207 -276.836632)
		(width 0.1143)
		(layer "In13.Cu")
		(net "P5E_CPU1_P0_RX_DN<2>")
	)
	(segment
		(start 99.112578 -274.576286)
		(end 99.110038 -274.575016)
		(width 0.1143)
		(layer "In13.Cu")
		(net "P5E_CPU1_P0_RX_DN<2>")
	)
	(segment
		(start 99.069144 -279.411176)
		(end 99.041204 -279.39111)
		(width 0.1143)
		(layer "In13.Cu")
		(net "P5E_CPU1_P0_RX_DN<2>")
	)
	(segment
		(start 98.601784 -270.502888)
		(end 98.59899 -270.500856)
		(width 0.1143)
		(layer "In13.Cu")
		(net "P5E_CPU1_P0_RX_DN<2>")
	)
	(segment
		(start 99.108006 -282.673806)
		(end 99.105212 -282.672028)
		(width 0.1143)
		(layer "In13.Cu")
		(net "P5E_CPU1_P0_RX_DN<2>")
	)
	(segment
		(start 99.041204 -281.741626)
		(end 99.069144 -281.72156)
		(width 0.1143)
		(layer "In13.Cu")
		(net "P5E_CPU1_P0_RX_DN<2>")
	)
	(segment
		(start 99.069144 -276.171152)
		(end 99.041204 -276.151086)
		(width 0.1143)
		(layer "In13.Cu")
		(net "P5E_CPU1_P0_RX_DN<2>")
	)
	(segment
		(start 99.139756 -274.592034)
		(end 99.115118 -274.57781)
		(width 0.1143)
		(layer "In13.Cu")
		(net "P5E_CPU1_P0_RX_DN<2>")
	)
	(segment
		(start 99.108006 -274.573746)
		(end 99.071684 -274.552664)
		(width 0.1143)
		(layer "In13.Cu")
		(net "P5E_CPU1_P0_RX_DN<2>")
	)
	(segment
		(start 99.133152 -293.024052)
		(end 99.134168 -293.023544)
		(width 0.1143)
		(layer "In13.Cu")
		(net "P5E_CPU1_P0_RX_DN<2>")
	)
	(segment
		(start 99.109276 -286.561784)
		(end 99.109022 -286.56153)
		(width 0.1143)
		(layer "In13.Cu")
		(net "P5E_CPU1_P0_RX_DN<2>")
	)
	(segment
		(start 99.113848 -276.835616)
		(end 99.139756 -276.82063)
		(width 0.1143)
		(layer "In13.Cu")
		(net "P5E_CPU1_P0_RX_DN<2>")
	)
	(segment
		(start 99.071684 -284.96006)
		(end 99.108006 -284.938978)
		(width 0.1143)
		(layer "In13.Cu")
		(net "P5E_CPU1_P0_RX_DN<2>")
	)
	(segment
		(start 99.114864 -271.337786)
		(end 99.112324 -271.336262)
		(width 0.1143)
		(layer "In13.Cu")
		(net "P5E_CPU1_P0_RX_DN<2>")
	)
	(segment
		(start 99.11207 -275.21662)
		(end 99.11461 -275.21535)
		(width 0.1143)
		(layer "In13.Cu")
		(net "P5E_CPU1_P0_RX_DN<2>")
	)
	(segment
		(start 99.111562 -271.335754)
		(end 99.110038 -271.334992)
		(width 0.1143)
		(layer "In13.Cu")
		(net "P5E_CPU1_P0_RX_DN<2>")
	)
	(segment
		(start 99.115118 -284.297882)
		(end 99.114102 -284.297374)
		(width 0.1143)
		(layer "In13.Cu")
		(net "P5E_CPU1_P0_RX_DN<2>")
	)
	(segment
		(start 99.108768 -282.674314)
		(end 99.108006 -282.673806)
		(width 0.1143)
		(layer "In13.Cu")
		(net "P5E_CPU1_P0_RX_DN<2>")
	)
	(segment
		(start 128.33858 -352.323908)
		(end 128.33858 -352.12274)
		(width 0.14224)
		(layer "In13.Cu")
		(net "P5E_CPU1_P0_RX_DN<2>")
	)
	(segment
		(start 99.108006 -281.05354)
		(end 99.068382 -281.030934)
		(width 0.1143)
		(layer "In13.Cu")
		(net "P5E_CPU1_P0_RX_DN<2>")
	)
	(segment
		(start 99.116642 -283.31414)
		(end 99.139756 -283.300678)
		(width 0.1143)
		(layer "In13.Cu")
		(net "P5E_CPU1_P0_RX_DN<2>")
	)
	(segment
		(start 110.406942 -357.830628)
		(end 110.406942 -357.025448)
		(width 0.14224)
		(layer "In13.Cu")
		(net "P5E_CPU1_P0_RX_DN<2>")
	)
	(segment
		(start 99.123246 -292.402006)
		(end 99.11334 -292.39718)
		(width 0.1143)
		(layer "In13.Cu")
		(net "P5E_CPU1_P0_RX_DN<2>")
	)
	(segment
		(start 99.069144 -277.791164)
		(end 99.041204 -277.771098)
		(width 0.1143)
		(layer "In13.Cu")
		(net "P5E_CPU1_P0_RX_DN<2>")
	)
	(segment
		(start 99.10953 -281.698192)
		(end 99.110292 -281.697684)
		(width 0.1143)
		(layer "In13.Cu")
		(net "P5E_CPU1_P0_RX_DN<2>")
	)
	(segment
		(start 99.069144 -283.341572)
		(end 99.10953 -283.318204)
		(width 0.1143)
		(layer "In13.Cu")
		(net "P5E_CPU1_P0_RX_DN<2>")
	)
	(segment
		(start 99.112578 -276.196298)
		(end 99.110038 -276.195028)
		(width 0.1143)
		(layer "In13.Cu")
		(net "P5E_CPU1_P0_RX_DN<2>")
	)
	(segment
		(start 99.139756 -277.832058)
		(end 99.115118 -277.817834)
		(width 0.1143)
		(layer "In13.Cu")
		(net "P5E_CPU1_P0_RX_DN<2>")
	)
	(segment
		(start 99.108768 -274.574254)
		(end 99.108006 -274.573746)
		(width 0.1143)
		(layer "In13.Cu")
		(net "P5E_CPU1_P0_RX_DN<2>")
	)
	(segment
		(start 120.971564 -358.280208)
		(end 120.829324 -358.137968)
		(width 0.14224)
		(layer "In13.Cu")
		(net "P5E_CPU1_P0_RX_DN<2>")
	)
	(segment
		(start 122.90171 -326.679306)
		(end 121.088912 -323.132704)
		(width 0.14224)
		(layer "In13.Cu")
		(net "P5E_CPU1_P0_RX_DN<2>")
	)
	(segment
		(start 99.114102 -276.197314)
		(end 99.112578 -276.196298)
		(width 0.1143)
		(layer "In13.Cu")
		(net "P5E_CPU1_P0_RX_DN<2>")
	)
	(segment
		(start 99.115372 -275.214842)
		(end 99.139756 -275.200618)
		(width 0.1143)
		(layer "In13.Cu")
		(net "P5E_CPU1_P0_RX_DN<2>")
	)
	(segment
		(start 109.886496 -308.061868)
		(end 104.996996 -305.448208)
		(width 0.14224)
		(layer "In13.Cu")
		(net "P5E_CPU1_P0_RX_DN<2>")
	)
	(segment
		(start 99.128072 -291.407342)
		(end 99.139502 -291.400484)
		(width 0.1143)
		(layer "In13.Cu")
		(net "P5E_CPU1_P0_RX_DN<2>")
	)
	(segment
		(start 99.103942 -289.151568)
		(end 99.101656 -289.150044)
		(width 0.1143)
		(layer "In13.Cu")
		(net "P5E_CPU1_P0_RX_DN<2>")
	)
	(segment
		(start 99.138994 -292.41115)
		(end 99.123246 -292.402006)
		(width 0.1143)
		(layer "In13.Cu")
		(net "P5E_CPU1_P0_RX_DN<2>")
	)
	(segment
		(start 110.714282 -358.137968)
		(end 110.406942 -357.830628)
		(width 0.14224)
		(layer "In13.Cu")
		(net "P5E_CPU1_P0_RX_DN<2>")
	)
	(segment
		(start 99.071684 -288.200592)
		(end 99.074478 -288.197798)
		(width 0.1143)
		(layer "In13.Cu")
		(net "P5E_CPU1_P0_RX_DN<2>")
	)
	(segment
		(start 99.110038 -274.575016)
		(end 99.108768 -274.574254)
		(width 0.1143)
		(layer "In13.Cu")
		(net "P5E_CPU1_P0_RX_DN<2>")
	)
	(segment
		(start 104.546654 -305.114198)
		(end 98.68154 -299.249084)
		(width 0.14224)
		(layer "In13.Cu")
		(net "P5E_CPU1_P0_RX_DN<2>")
	)
	(segment
		(start 50.191416 -385.31038)
		(end 50.544476 -385.405376)
		(width 0.14224)
		(layer "In13.Cu")
		(net "P5E_CPU1_P0_RX_DN<2>")
	)
	(segment
		(start 50.544476 -385.405376)
		(end 50.544984 -385.404868)
		(width 0.14224)
		(layer "In13.Cu")
		(net "P5E_CPU1_P0_RX_DN<2>")
	)
	(segment
		(start 104.118918 -362.85297)
		(end 106.166412 -361.392724)
		(width 0.14224)
		(layer "In13.Cu")
		(net "P5E_CPU1_P0_RX_DN<2>")
	)
	(segment
		(start 99.118928 -294.6527)
		(end 99.139502 -294.640508)
		(width 0.1143)
		(layer "In13.Cu")
		(net "P5E_CPU1_P0_RX_DN<2>")
	)
	(segment
		(start 50.664872 -382.40335)
		(end 52.22367 -373.5451)
		(width 0.14224)
		(layer "In13.Cu")
		(net "P5E_CPU1_P0_RX_DN<2>")
	)
	(segment
		(start 99.10953 -275.218144)
		(end 99.110292 -275.217636)
		(width 0.1143)
		(layer "In13.Cu")
		(net "P5E_CPU1_P0_RX_DN<2>")
	)
	(segment
		(start 99.115118 -277.817834)
		(end 99.114102 -277.817326)
		(width 0.1143)
		(layer "In13.Cu")
		(net "P5E_CPU1_P0_RX_DN<2>")
	)
	(segment
		(start 99.10064 -290.76904)
		(end 99.096576 -290.766754)
		(width 0.1143)
		(layer "In13.Cu")
		(net "P5E_CPU1_P0_RX_DN<2>")
	)
	(segment
		(start 99.041458 -280.12136)
		(end 99.068382 -280.101802)
		(width 0.1143)
		(layer "In13.Cu")
		(net "P5E_CPU1_P0_RX_DN<2>")
	)
	(segment
		(start 99.107752 -291.419026)
		(end 99.128072 -291.407342)
		(width 0.1143)
		(layer "In13.Cu")
		(net "P5E_CPU1_P0_RX_DN<2>")
	)
	(segment
		(start 99.110038 -271.334992)
		(end 99.108768 -271.33423)
		(width 0.1143)
		(layer "In13.Cu")
		(net "P5E_CPU1_P0_RX_DN<2>")
	)
	(segment
		(start 99.111308 -283.317188)
		(end 99.11207 -283.31668)
		(width 0.1143)
		(layer "In13.Cu")
		(net "P5E_CPU1_P0_RX_DN<2>")
	)
	(segment
		(start 99.143058 -287.554416)
		(end 99.142296 -287.553908)
		(width 0.1143)
		(layer "In13.Cu")
		(net "P5E_CPU1_P0_RX_DN<2>")
	)
	(segment
		(start 57.801764 -365.79937)
		(end 63.472822 -362.96727)
		(width 0.14224)
		(layer "In13.Cu")
		(net "P5E_CPU1_P0_RX_DN<2>")
	)
	(segment
		(start 99.114102 -285.917386)
		(end 99.112578 -285.91637)
		(width 0.1143)
		(layer "In13.Cu")
		(net "P5E_CPU1_P0_RX_DN<2>")
	)
	(segment
		(start 99.069144 -276.861524)
		(end 99.10953 -276.838156)
		(width 0.1143)
		(layer "In13.Cu")
		(net "P5E_CPU1_P0_RX_DN<2>")
	)
	(segment
		(start 99.114102 -282.677362)
		(end 99.112578 -282.676346)
		(width 0.1143)
		(layer "In13.Cu")
		(net "P5E_CPU1_P0_RX_DN<2>")
	)
	(segment
		(start 98.361754 -270.119094)
		(end 98.27895 -270.03629)
		(width 0.1143)
		(layer "In13.Cu")
		(net "P5E_CPU1_P0_RX_DN<2>")
	)
	(segment
		(start 99.113086 -276.836124)
		(end 99.113848 -276.835616)
		(width 0.1143)
		(layer "In13.Cu")
		(net "P5E_CPU1_P0_RX_DN<2>")
	)
	(segment
		(start 99.105212 -282.672028)
		(end 99.069144 -282.6512)
		(width 0.1143)
		(layer "In13.Cu")
		(net "P5E_CPU1_P0_RX_DN<2>")
	)
	(segment
		(start 122.32894 -356.718108)
		(end 122.75566 -356.718108)
		(width 0.14224)
		(layer "In13.Cu")
		(net "P5E_CPU1_P0_RX_DN<2>")
	)
	(segment
		(start 52.29987 -373.344694)
		(end 55.94731 -367.39957)
		(width 0.14224)
		(layer "In13.Cu")
		(net "P5E_CPU1_P0_RX_DN<2>")
	)
	(segment
		(start 99.137978 -288.161222)
		(end 99.139502 -288.160206)
		(width 0.1143)
		(layer "In13.Cu")
		(net "P5E_CPU1_P0_RX_DN<2>")
	)
	(segment
		(start 121.6279 -356.718108)
		(end 121.76506 -356.580948)
		(width 0.14224)
		(layer "In13.Cu")
		(net "P5E_CPU1_P0_RX_DN<2>")
	)
	(segment
		(start 99.110038 -285.9151)
		(end 99.108768 -285.914338)
		(width 0.1143)
		(layer "In13.Cu")
		(net "P5E_CPU1_P0_RX_DN<2>")
	)
	(segment
		(start 99.111562 -292.39591)
		(end 99.096576 -292.386766)
		(width 0.1143)
		(layer "In13.Cu")
		(net "P5E_CPU1_P0_RX_DN<2>")
	)
	(segment
		(start 124.895356 -334.849978)
		(end 123.399804 -328.721466)
		(width 0.14224)
		(layer "In13.Cu")
		(net "P5E_CPU1_P0_RX_DN<2>")
	)
	(segment
		(start 99.10953 -278.458168)
		(end 99.110292 -278.45766)
		(width 0.1143)
		(layer "In13.Cu")
		(net "P5E_CPU1_P0_RX_DN<2>")
	)
	(segment
		(start 99.114102 -284.297374)
		(end 99.112578 -284.296358)
		(width 0.1143)
		(layer "In13.Cu")
		(net "P5E_CPU1_P0_RX_DN<2>")
	)
	(segment
		(start 56.007 -367.324132)
		(end 56.835294 -366.495838)
		(width 0.14224)
		(layer "In13.Cu")
		(net "P5E_CPU1_P0_RX_DN<2>")
	)
	(segment
		(start 99.105212 -276.19198)
		(end 99.069144 -276.171152)
		(width 0.1143)
		(layer "In13.Cu")
		(net "P5E_CPU1_P0_RX_DN<2>")
	)
	(segment
		(start 99.115626 -278.454612)
		(end 99.116642 -278.454104)
		(width 0.1143)
		(layer "In13.Cu")
		(net "P5E_CPU1_P0_RX_DN<2>")
	)
	(segment
		(start 112.008158 -310.370982)
		(end 110.580424 -308.631336)
		(width 0.14224)
		(layer "In13.Cu")
		(net "P5E_CPU1_P0_RX_DN<2>")
	)
	(segment
		(start 99.105212 -284.29204)
		(end 99.069144 -284.271212)
		(width 0.1143)
		(layer "In13.Cu")
		(net "P5E_CPU1_P0_RX_DN<2>")
	)
	(segment
		(start 99.116642 -281.694128)
		(end 99.139756 -281.680666)
		(width 0.1143)
		(layer "In13.Cu")
		(net "P5E_CPU1_P0_RX_DN<2>")
	)
	(segment
		(start 99.139756 -281.072082)
		(end 99.108006 -281.053794)
		(width 0.1143)
		(layer "In13.Cu")
		(net "P5E_CPU1_P0_RX_DN<2>")
	)
	(segment
		(start 106.198416 -361.201462)
		(end 106.546142 -360.953558)
		(width 0.14224)
		(layer "In13.Cu")
		(net "P5E_CPU1_P0_RX_DN<2>")
	)
	(segment
		(start 106.166412 -361.392724)
		(end 106.198416 -361.201462)
		(width 0.14224)
		(layer "In13.Cu")
		(net "P5E_CPU1_P0_RX_DN<2>")
	)
	(segment
		(start 120.829324 -358.993948)
		(end 120.971564 -358.851708)
		(width 0.14224)
		(layer "In13.Cu")
		(net "P5E_CPU1_P0_RX_DN<2>")
	)
	(segment
		(start 99.041204 -283.361638)
		(end 99.069144 -283.341572)
		(width 0.1143)
		(layer "In13.Cu")
		(net "P5E_CPU1_P0_RX_DN<2>")
	)
	(segment
		(start 99.140264 -292.41115)
		(end 99.138994 -292.41115)
		(width 0.1143)
		(layer "In13.Cu")
		(net "P5E_CPU1_P0_RX_DN<2>")
	)
	(segment
		(start 99.108006 -281.053794)
		(end 99.108006 -281.05354)
		(width 0.1143)
		(layer "In13.Cu")
		(net "P5E_CPU1_P0_RX_DN<2>")
	)
	(segment
		(start 99.108006 -271.333722)
		(end 99.071684 -271.31264)
		(width 0.1143)
		(layer "In13.Cu")
		(net "P5E_CPU1_P0_RX_DN<2>")
	)
	(segment
		(start 99.139756 -284.312106)
		(end 99.115118 -284.297882)
		(width 0.1143)
		(layer "In13.Cu")
		(net "P5E_CPU1_P0_RX_DN<2>")
	)
	(segment
		(start 99.114864 -281.695144)
		(end 99.115626 -281.694636)
		(width 0.1143)
		(layer "In13.Cu")
		(net "P5E_CPU1_P0_RX_DN<2>")
	)
	(segment
		(start 99.11207 -281.696668)
		(end 99.113086 -281.69616)
		(width 0.1143)
		(layer "In13.Cu")
		(net "P5E_CPU1_P0_RX_DN<2>")
	)
	(segment
		(start 99.11461 -275.21535)
		(end 99.115372 -275.214842)
		(width 0.1143)
		(layer "In13.Cu")
		(net "P5E_CPU1_P0_RX_DN<2>")
	)
	(segment
		(start 99.114864 -278.45512)
		(end 99.115626 -278.454612)
		(width 0.1143)
		(layer "In13.Cu")
		(net "P5E_CPU1_P0_RX_DN<2>")
	)
	(segment
		(start 99.139756 -282.692094)
		(end 99.115118 -282.67787)
		(width 0.1143)
		(layer "In13.Cu")
		(net "P5E_CPU1_P0_RX_DN<2>")
	)
	(segment
		(start 120.971564 -358.851708)
		(end 120.971564 -358.280208)
		(width 0.14224)
		(layer "In13.Cu")
		(net "P5E_CPU1_P0_RX_DN<2>")
	)
	(segment
		(start 50.658522 -383.93116)
		(end 50.658522 -382.47447)
		(width 0.14224)
		(layer "In13.Cu")
		(net "P5E_CPU1_P0_RX_DN<2>")
	)
	(segment
		(start 99.115118 -276.197822)
		(end 99.114102 -276.197314)
		(width 0.1143)
		(layer "In13.Cu")
		(net "P5E_CPU1_P0_RX_DN<2>")
	)
	(segment
		(start 99.094798 -287.525206)
		(end 99.09175 -287.523174)
		(width 0.1143)
		(layer "In13.Cu")
		(net "P5E_CPU1_P0_RX_DN<2>")
	)
	(segment
		(start 109.68609 -358.993948)
		(end 120.829324 -358.993948)
		(width 0.14224)
		(layer "In13.Cu")
		(net "P5E_CPU1_P0_RX_DN<2>")
	)
	(segment
		(start 99.041204 -276.88159)
		(end 99.069144 -276.861524)
		(width 0.1143)
		(layer "In13.Cu")
		(net "P5E_CPU1_P0_RX_DN<2>")
	)
	(segment
		(start 99.110038 -277.81504)
		(end 99.108768 -277.814278)
		(width 0.1143)
		(layer "In13.Cu")
		(net "P5E_CPU1_P0_RX_DN<2>")
	)
	(segment
		(start 99.108006 -276.193758)
		(end 99.105212 -276.19198)
		(width 0.1143)
		(layer "In13.Cu")
		(net "P5E_CPU1_P0_RX_DN<2>")
	)
	(segment
		(start 99.114864 -283.315156)
		(end 99.115626 -283.314648)
		(width 0.1143)
		(layer "In13.Cu")
		(net "P5E_CPU1_P0_RX_DN<2>")
	)
	(segment
		(start 99.071684 -273.619976)
		(end 99.073208 -273.61896)
		(width 0.1143)
		(layer "In13.Cu")
		(net "P5E_CPU1_P0_RX_DN<2>")
	)
	(segment
		(start 50.349658 -384.84683)
		(end 50.354484 -384.234944)
		(width 0.14224)
		(layer "In13.Cu")
		(net "P5E_CPU1_P0_RX_DN<2>")
	)
	(segment
		(start 99.111308 -275.217128)
		(end 99.11207 -275.21662)
		(width 0.1143)
		(layer "In13.Cu")
		(net "P5E_CPU1_P0_RX_DN<2>")
	)
	(segment
		(start 99.113848 -283.315664)
		(end 99.114864 -283.315156)
		(width 0.1143)
		(layer "In13.Cu")
		(net "P5E_CPU1_P0_RX_DN<2>")
	)
	(segment
		(start 99.112578 -277.81631)
		(end 99.110038 -277.81504)
		(width 0.1143)
		(layer "In13.Cu")
		(net "P5E_CPU1_P0_RX_DN<2>")
	)
	(segment
		(start 99.108768 -285.914338)
		(end 99.108006 -285.91383)
		(width 0.1143)
		(layer "In13.Cu")
		(net "P5E_CPU1_P0_RX_DN<2>")
	)
	(segment
		(start 99.10318 -294.66159)
		(end 99.104704 -294.660574)
		(width 0.1143)
		(layer "In13.Cu")
		(net "P5E_CPU1_P0_RX_DN<2>")
	)
	(segment
		(start 99.11334 -292.39718)
		(end 99.111562 -292.39591)
		(width 0.1143)
		(layer "In13.Cu")
		(net "P5E_CPU1_P0_RX_DN<2>")
	)
	(segment
		(start 99.110038 -282.675076)
		(end 99.108768 -282.674314)
		(width 0.1143)
		(layer "In13.Cu")
		(net "P5E_CPU1_P0_RX_DN<2>")
	)
	(segment
		(start 98.669856 -270.542004)
		(end 98.601784 -270.502888)
		(width 0.1143)
		(layer "In13.Cu")
		(net "P5E_CPU1_P0_RX_DN<2>")
	)
	(arc
		(start 50.658522 -382.47447)
		(mid 50.660142 -382.438771)
		(end 50.664872 -382.40335)
		(width 0.14224)
		(layer "In13.Cu")
		(net "P5E_CPU1_P0_RX_DN<2>")
	)
	(arc
		(start 99.041458 -281.011376)
		(mid 98.81378 -280.566368)
		(end 99.041458 -280.12136)
		(width 0.1143)
		(layer "In13.Cu")
		(net "P5E_CPU1_P0_RX_DN<2>")
	)
	(arc
		(start 99.139756 -284.92069)
		(mid 99.295684 -284.616398)
		(end 99.139756 -284.312106)
		(width 0.1143)
		(layer "In13.Cu")
		(net "P5E_CPU1_P0_RX_DN<2>")
	)
	(arc
		(start 98.365564 -270.141954)
		(mid 98.363541 -270.130544)
		(end 98.361754 -270.119094)
		(width 0.1143)
		(layer "In13.Cu")
		(net "P5E_CPU1_P0_RX_DN<2>")
	)
	(arc
		(start 99.139502 -291.400484)
		(mid 99.295641 -291.095912)
		(end 99.138994 -290.791646)
		(width 0.1143)
		(layer "In13.Cu")
		(net "P5E_CPU1_P0_RX_DN<2>")
	)
	(arc
		(start 99.056444 -284.970728)
		(mid 99.06402 -284.965332)
		(end 99.071684 -284.96006)
		(width 0.1143)
		(layer "In13.Cu")
		(net "P5E_CPU1_P0_RX_DN<2>")
	)
	(arc
		(start 99.041204 -276.151086)
		(mid 98.813204 -275.706332)
		(end 99.041204 -275.261578)
		(width 0.1143)
		(layer "In13.Cu")
		(net "P5E_CPU1_P0_RX_DN<2>")
	)
	(arc
		(start 98.78314 -295.416224)
		(mid 98.810729 -295.374839)
		(end 98.820478 -295.326054)
		(width 0.1143)
		(layer "In13.Cu")
		(net "P5E_CPU1_P0_RX_DN<2>")
	)
	(arc
		(start 99.139502 -294.640508)
		(mid 99.295747 -294.336319)
		(end 99.139756 -294.031924)
		(width 0.1143)
		(layer "In13.Cu")
		(net "P5E_CPU1_P0_RX_DN<2>")
	)
	(arc
		(start 99.071684 -285.892748)
		(mid 99.06402 -285.887477)
		(end 99.056444 -285.88208)
		(width 0.1143)
		(layer "In13.Cu")
		(net "P5E_CPU1_P0_RX_DN<2>")
	)
	(arc
		(start 99.139756 -278.440642)
		(mid 99.295684 -278.13635)
		(end 99.139756 -277.832058)
		(width 0.1143)
		(layer "In13.Cu")
		(net "P5E_CPU1_P0_RX_DN<2>")
	)
	(arc
		(start 63.472822 -362.96727)
		(mid 63.630821 -362.910273)
		(end 63.797688 -362.89107)
		(width 0.14224)
		(layer "In13.Cu")
		(net "P5E_CPU1_P0_RX_DN<2>")
	)
	(arc
		(start 99.05746 -272.922746)
		(mid 98.830077 -272.466308)
		(end 99.05746 -272.00987)
		(width 0.1143)
		(layer "In13.Cu")
		(net "P5E_CPU1_P0_RX_DN<2>")
	)
	(arc
		(start 99.071684 -274.552664)
		(mid 99.06402 -274.547393)
		(end 99.056444 -274.541996)
		(width 0.1143)
		(layer "In13.Cu")
		(net "P5E_CPU1_P0_RX_DN<2>")
	)
	(arc
		(start 99.041204 -282.631134)
		(mid 98.813204 -282.18638)
		(end 99.041204 -281.741626)
		(width 0.1143)
		(layer "In13.Cu")
		(net "P5E_CPU1_P0_RX_DN<2>")
	)
	(arc
		(start 99.135438 -293.023544)
		(mid 99.296624 -292.718619)
		(end 99.140264 -292.41115)
		(width 0.1143)
		(layer "In13.Cu")
		(net "P5E_CPU1_P0_RX_DN<2>")
	)
	(arc
		(start 99.056444 -273.630644)
		(mid 99.06402 -273.625248)
		(end 99.071684 -273.619976)
		(width 0.1143)
		(layer "In13.Cu")
		(net "P5E_CPU1_P0_RX_DN<2>")
	)
	(arc
		(start 99.041204 -277.771098)
		(mid 98.813204 -277.326344)
		(end 99.041204 -276.88159)
		(width 0.1143)
		(layer "In13.Cu")
		(net "P5E_CPU1_P0_RX_DN<2>")
	)
	(arc
		(start 52.22367 -373.5451)
		(mid 52.252302 -373.441296)
		(end 52.29987 -373.344694)
		(width 0.14224)
		(layer "In13.Cu")
		(net "P5E_CPU1_P0_RX_DN<2>")
	)
	(arc
		(start 98.825812 -270.8529)
		(mid 98.825802 -270.849598)
		(end 98.825812 -270.846296)
		(width 0.1143)
		(layer "In13.Cu")
		(net "P5E_CPU1_P0_RX_DN<2>")
	)
	(arc
		(start 99.100386 -289.149282)
		(mid 98.818759 -288.682991)
		(end 99.071684 -288.200592)
		(width 0.1143)
		(layer "In13.Cu")
		(net "P5E_CPU1_P0_RX_DN<2>")
	)
	(arc
		(start 123.891802 -356.718108)
		(mid 123.940486 -356.708406)
		(end 123.981718 -356.68077)
		(width 0.14224)
		(layer "In13.Cu")
		(net "P5E_CPU1_P0_RX_DN<2>")
	)
	(arc
		(start 99.096576 -294.006778)
		(mid 98.827088 -293.534314)
		(end 99.08286 -293.054278)
		(width 0.1143)
		(layer "In13.Cu")
		(net "P5E_CPU1_P0_RX_DN<2>")
	)
	(arc
		(start 99.139756 -280.060654)
		(mid 99.295684 -279.756362)
		(end 99.139756 -279.45207)
		(width 0.1143)
		(layer "In13.Cu")
		(net "P5E_CPU1_P0_RX_DN<2>")
	)
	(arc
		(start 99.071684 -271.31264)
		(mid 99.063506 -271.306997)
		(end 99.055428 -271.30121)
		(width 0.1143)
		(layer "In13.Cu")
		(net "P5E_CPU1_P0_RX_DN<2>")
	)
	(arc
		(start 99.071684 -272.932652)
		(mid 99.064535 -272.927752)
		(end 99.05746 -272.922746)
		(width 0.1143)
		(layer "In13.Cu")
		(net "P5E_CPU1_P0_RX_DN<2>")
	)
	(arc
		(start 99.139756 -276.82063)
		(mid 99.295684 -276.516338)
		(end 99.139756 -276.212046)
		(width 0.1143)
		(layer "In13.Cu")
		(net "P5E_CPU1_P0_RX_DN<2>")
	)
	(arc
		(start 55.94731 -367.39957)
		(mid 55.974928 -367.360089)
		(end 56.007 -367.324132)
		(width 0.14224)
		(layer "In13.Cu")
		(net "P5E_CPU1_P0_RX_DN<2>")
	)
	(arc
		(start 99.041204 -284.251146)
		(mid 98.813204 -283.806392)
		(end 99.041204 -283.361638)
		(width 0.1143)
		(layer "In13.Cu")
		(net "P5E_CPU1_P0_RX_DN<2>")
	)
	(arc
		(start 104.996996 -305.448208)
		(mid 104.759503 -305.297816)
		(end 104.546654 -305.114198)
		(width 0.14224)
		(layer "In13.Cu")
		(net "P5E_CPU1_P0_RX_DN<2>")
	)
	(arc
		(start 99.139756 -271.960594)
		(mid 99.295684 -271.656302)
		(end 99.139756 -271.35201)
		(width 0.1143)
		(layer "In13.Cu")
		(net "P5E_CPU1_P0_RX_DN<2>")
	)
	(arc
		(start 99.08286 -293.054278)
		(mid 99.095081 -293.0465)
		(end 99.107498 -293.039038)
		(width 0.1143)
		(layer "In13.Cu")
		(net "P5E_CPU1_P0_RX_DN<2>")
	)
	(arc
		(start 99.139756 -281.680666)
		(mid 99.295684 -281.376374)
		(end 99.139756 -281.072082)
		(width 0.1143)
		(layer "In13.Cu")
		(net "P5E_CPU1_P0_RX_DN<2>")
	)
	(arc
		(start 98.59899 -270.500856)
		(mid 98.447003 -270.344348)
		(end 98.365564 -270.141954)
		(width 0.1143)
		(layer "In13.Cu")
		(net "P5E_CPU1_P0_RX_DN<2>")
	)
	(arc
		(start 99.139756 -283.300678)
		(mid 99.295684 -282.996386)
		(end 99.139756 -282.692094)
		(width 0.1143)
		(layer "In13.Cu")
		(net "P5E_CPU1_P0_RX_DN<2>")
	)
	(arc
		(start 98.996754 -287.434274)
		(mid 98.838256 -286.970339)
		(end 99.109276 -286.561784)
		(width 0.1143)
		(layer "In13.Cu")
		(net "P5E_CPU1_P0_RX_DN<2>")
	)
	(arc
		(start 127.56642 -349.876364)
		(mid 127.597756 -349.824413)
		(end 127.601472 -349.763842)
		(width 0.14224)
		(layer "In13.Cu")
		(net "P5E_CPU1_P0_RX_DN<2>")
	)
	(arc
		(start 99.143312 -288.15792)
		(mid 99.295828 -287.856066)
		(end 99.143058 -287.554416)
		(width 0.1143)
		(layer "In13.Cu")
		(net "P5E_CPU1_P0_RX_DN<2>")
	)
	(arc
		(start 99.05746 -272.00987)
		(mid 99.064534 -272.004863)
		(end 99.071684 -271.999964)
		(width 0.1143)
		(layer "In13.Cu")
		(net "P5E_CPU1_P0_RX_DN<2>")
	)
	(arc
		(start 99.109022 -286.56153)
		(mid 99.295125 -286.252532)
		(end 99.13493 -285.929324)
		(width 0.1143)
		(layer "In13.Cu")
		(net "P5E_CPU1_P0_RX_DN<2>")
	)
	(arc
		(start 99.096576 -292.386766)
		(mid 98.82731 -291.899707)
		(end 99.107752 -291.419026)
		(width 0.1143)
		(layer "In13.Cu")
		(net "P5E_CPU1_P0_RX_DN<2>")
	)
	(arc
		(start 99.056444 -285.88208)
		(mid 98.831273 -285.426404)
		(end 99.056444 -284.970728)
		(width 0.1143)
		(layer "In13.Cu")
		(net "P5E_CPU1_P0_RX_DN<2>")
	)
	(arc
		(start 98.820478 -295.15181)
		(mid 98.896087 -294.868776)
		(end 99.10318 -294.66159)
		(width 0.1143)
		(layer "In13.Cu")
		(net "P5E_CPU1_P0_RX_DN<2>")
	)
	(arc
		(start 99.139502 -289.780472)
		(mid 99.294515 -289.457798)
		(end 99.106482 -289.153092)
		(width 0.1143)
		(layer "In13.Cu")
		(net "P5E_CPU1_P0_RX_DN<2>")
	)
	(arc
		(start 99.041204 -279.39111)
		(mid 98.813204 -278.946356)
		(end 99.041204 -278.501602)
		(width 0.1143)
		(layer "In13.Cu")
		(net "P5E_CPU1_P0_RX_DN<2>")
	)
	(arc
		(start 99.139756 -275.200618)
		(mid 99.295684 -274.896326)
		(end 99.139756 -274.592034)
		(width 0.1143)
		(layer "In13.Cu")
		(net "P5E_CPU1_P0_RX_DN<2>")
	)
	(arc
		(start 56.835294 -366.495838)
		(mid 57.290405 -366.108574)
		(end 57.801764 -365.79937)
		(width 0.14224)
		(layer "In13.Cu")
		(net "P5E_CPU1_P0_RX_DN<2>")
	)
	(arc
		(start 98.825812 -270.835628)
		(mid 98.786979 -270.674215)
		(end 98.678746 -270.548354)
		(width 0.1143)
		(layer "In13.Cu")
		(net "P5E_CPU1_P0_RX_DN<2>")
	)
	(arc
		(start 98.68154 -299.249084)
		(mid 98.406723 -298.837697)
		(end 98.310192 -298.352464)
		(width 0.14224)
		(layer "In13.Cu")
		(net "P5E_CPU1_P0_RX_DN<2>")
	)
	(arc
		(start 99.096576 -290.766754)
		(mid 98.82731 -290.279695)
		(end 99.107752 -289.799014)
		(width 0.1143)
		(layer "In13.Cu")
		(net "P5E_CPU1_P0_RX_DN<2>")
	)
	(arc
		(start 109.403388 -359.084372)
		(mid 109.537674 -359.017076)
		(end 109.68609 -358.993948)
		(width 0.14224)
		(layer "In13.Cu")
		(net "P5E_CPU1_P0_RX_DN<2>")
	)
	(arc
		(start 99.056444 -274.541996)
		(mid 98.831273 -274.08632)
		(end 99.056444 -273.630644)
		(width 0.1143)
		(layer "In13.Cu")
		(net "P5E_CPU1_P0_RX_DN<2>")
	)
	(arc
		(start 98.351848 -296.072814)
		(mid 98.393126 -295.864735)
		(end 98.510852 -295.688258)
		(width 0.1143)
		(layer "In13.Cu")
		(net "P5E_CPU1_P0_RX_DN<2>")
	)
	(arc
		(start 99.139756 -273.580606)
		(mid 99.295684 -273.276314)
		(end 99.139756 -272.972022)
		(width 0.1143)
		(layer "In13.Cu")
		(net "P5E_CPU1_P0_RX_DN<2>")
	)
	(arc
		(start 99.055428 -271.30121)
		(mid 98.890761 -271.102603)
		(end 98.825812 -270.8529)
		(width 0.1143)
		(layer "In13.Cu")
		(net "P5E_CPU1_P0_RX_DN<2>")
	)
	(arc
		(start 104.0003 -362.89107)
		(mid 104.062573 -362.881262)
		(end 104.118918 -362.85297)
		(width 0.14224)
		(layer "In13.Cu")
		(net "P5E_CPU1_P0_RX_DN<2>")
	)
	(segment
		(start 98.44786 -273.010376)
		(end 97.981008 -273.276314)
		(width 0.12954)
		(layer "F.Cu")
		(net "P5E_CPU1_P0_RX_DN<1>")
	)
	(segment
		(start 48.470566 -385.31038)
		(end 48.991266 -385.31038)
		(width 0.127)
		(layer "F.Cu")
		(net "P5E_CPU1_P0_RX_DN<1>")
	)
	(segment
		(start 98.168206 -280.078942)
		(end 98.198686 -280.061162)
		(width 0.1143)
		(layer "In13.Cu")
		(net "P5E_CPU1_P0_RX_DN<1>")
	)
	(segment
		(start 98.198686 -290.791138)
		(end 98.12909 -290.750752)
		(width 0.1143)
		(layer "In13.Cu")
		(net "P5E_CPU1_P0_RX_DN<1>")
	)
	(segment
		(start 120.19788 -354.589842)
		(end 119.89054 -354.897182)
		(width 0.14224)
		(layer "In13.Cu")
		(net "P5E_CPU1_P0_RX_DN<1>")
	)
	(segment
		(start 111.915194 -355.610922)
		(end 111.915194 -353.784662)
		(width 0.14224)
		(layer "In13.Cu")
		(net "P5E_CPU1_P0_RX_DN<1>")
	)
	(segment
		(start 99.187508 -361.929172)
		(end 109.719364 -353.283774)
		(width 0.14224)
		(layer "In13.Cu")
		(net "P5E_CPU1_P0_RX_DN<1>")
	)
	(segment
		(start 122.117358 -353.712018)
		(end 122.419364 -353.410012)
		(width 0.14224)
		(layer "In13.Cu")
		(net "P5E_CPU1_P0_RX_DN<1>")
	)
	(segment
		(start 48.991266 -385.31038)
		(end 49.34458 -385.405376)
		(width 0.14224)
		(layer "In13.Cu")
		(net "P5E_CPU1_P0_RX_DN<1>")
	)
	(segment
		(start 49.458626 -383.93116)
		(end 49.458626 -382.284732)
		(width 0.14224)
		(layer "In13.Cu")
		(net "P5E_CPU1_P0_RX_DN<1>")
	)
	(segment
		(start 98.198686 -294.031162)
		(end 98.12909 -293.990776)
		(width 0.1143)
		(layer "In13.Cu")
		(net "P5E_CPU1_P0_RX_DN<1>")
	)
	(segment
		(start 97.370138 -299.009562)
		(end 97.370138 -296.422318)
		(width 0.14224)
		(layer "In13.Cu")
		(net "P5E_CPU1_P0_RX_DN<1>")
	)
	(segment
		(start 98.12909 -275.241766)
		(end 98.168206 -275.218906)
		(width 0.1143)
		(layer "In13.Cu")
		(net "P5E_CPU1_P0_RX_DN<1>")
	)
	(segment
		(start 98.12909 -288.201354)
		(end 98.199956 -288.160206)
		(width 0.1143)
		(layer "In13.Cu")
		(net "P5E_CPU1_P0_RX_DN<1>")
	)
	(segment
		(start 55.175658 -366.836706)
		(end 56.662574 -365.349536)
		(width 0.14224)
		(layer "In13.Cu")
		(net "P5E_CPU1_P0_RX_DN<1>")
	)
	(segment
		(start 121.32056 -354.704142)
		(end 121.320306 -354.510086)
		(width 0.14224)
		(layer "In13.Cu")
		(net "P5E_CPU1_P0_RX_DN<1>")
	)
	(segment
		(start 98.168206 -281.053794)
		(end 98.12909 -281.030934)
		(width 0.1143)
		(layer "In13.Cu")
		(net "P5E_CPU1_P0_RX_DN<1>")
	)
	(segment
		(start 98.168206 -276.193758)
		(end 98.12909 -276.170898)
		(width 0.1143)
		(layer "In13.Cu")
		(net "P5E_CPU1_P0_RX_DN<1>")
	)
	(segment
		(start 56.769254 -365.272828)
		(end 63.319406 -362.001308)
		(width 0.14224)
		(layer "In13.Cu")
		(net "P5E_CPU1_P0_RX_DN<1>")
	)
	(segment
		(start 123.410218 -352.61169)
		(end 126.357888 -349.660972)
		(width 0.14224)
		(layer "In13.Cu")
		(net "P5E_CPU1_P0_RX_DN<1>")
	)
	(segment
		(start 110.589568 -353.859592)
		(end 110.589568 -353.859338)
		(width 0.14224)
		(layer "In13.Cu")
		(net "P5E_CPU1_P0_RX_DN<1>")
	)
	(segment
		(start 98.199956 -285.932372)
		(end 98.12909 -285.89097)
		(width 0.1143)
		(layer "In13.Cu")
		(net "P5E_CPU1_P0_RX_DN<1>")
	)
	(segment
		(start 98.27895 -273.276314)
		(end 97.981008 -273.276314)
		(width 0.1143)
		(layer "In13.Cu")
		(net "P5E_CPU1_P0_RX_DN<1>")
	)
	(segment
		(start 98.12909 -289.82162)
		(end 98.198686 -289.78098)
		(width 0.1143)
		(layer "In13.Cu")
		(net "P5E_CPU1_P0_RX_DN<1>")
	)
	(segment
		(start 98.128328 -286.58185)
		(end 98.199702 -286.540448)
		(width 0.1143)
		(layer "In13.Cu")
		(net "P5E_CPU1_P0_RX_DN<1>")
	)
	(segment
		(start 98.198686 -276.211538)
		(end 98.168206 -276.193758)
		(width 0.1143)
		(layer "In13.Cu")
		(net "P5E_CPU1_P0_RX_DN<1>")
	)
	(segment
		(start 98.198686 -274.591526)
		(end 98.168206 -274.573746)
		(width 0.1143)
		(layer "In13.Cu")
		(net "P5E_CPU1_P0_RX_DN<1>")
	)
	(segment
		(start 122.419364 -353.410012)
		(end 122.613166 -353.409758)
		(width 0.14224)
		(layer "In13.Cu")
		(net "P5E_CPU1_P0_RX_DN<1>")
	)
	(segment
		(start 119.89054 -354.897182)
		(end 113.477294 -354.897182)
		(width 0.14224)
		(layer "In13.Cu")
		(net "P5E_CPU1_P0_RX_DN<1>")
	)
	(segment
		(start 98.168206 -274.573746)
		(end 98.12909 -274.550886)
		(width 0.1143)
		(layer "In13.Cu")
		(net "P5E_CPU1_P0_RX_DN<1>")
	)
	(segment
		(start 110.589568 -353.859338)
		(end 110.66399 -353.950016)
		(width 0.14224)
		(layer "In13.Cu")
		(net "P5E_CPU1_P0_RX_DN<1>")
	)
	(segment
		(start 98.12909 -284.961838)
		(end 98.168206 -284.938978)
		(width 0.1143)
		(layer "In13.Cu")
		(net "P5E_CPU1_P0_RX_DN<1>")
	)
	(segment
		(start 97.894394 -295.279572)
		(end 97.894648 -295.279826)
		(width 0.1143)
		(layer "In13.Cu")
		(net "P5E_CPU1_P0_RX_DN<1>")
	)
	(segment
		(start 49.345088 -385.404868)
		(end 49.466754 -385.334764)
		(width 0.14224)
		(layer "In13.Cu")
		(net "P5E_CPU1_P0_RX_DN<1>")
	)
	(segment
		(start 98.12909 -283.341826)
		(end 98.168206 -283.318966)
		(width 0.1143)
		(layer "In13.Cu")
		(net "P5E_CPU1_P0_RX_DN<1>")
	)
	(segment
		(start 49.154588 -384.234944)
		(end 49.458626 -383.93116)
		(width 0.14224)
		(layer "In13.Cu")
		(net "P5E_CPU1_P0_RX_DN<1>")
	)
	(segment
		(start 97.65411 -295.621964)
		(end 97.822512 -295.453562)
		(width 0.1143)
		(layer "In13.Cu")
		(net "P5E_CPU1_P0_RX_DN<1>")
	)
	(segment
		(start 98.197924 -287.55086)
		(end 98.130614 -287.511744)
		(width 0.1143)
		(layer "In13.Cu")
		(net "P5E_CPU1_P0_RX_DN<1>")
	)
	(segment
		(start 126.357888 -349.660972)
		(end 126.357888 -348.641162)
		(width 0.14224)
		(layer "In13.Cu")
		(net "P5E_CPU1_P0_RX_DN<1>")
	)
	(segment
		(start 98.168206 -278.45893)
		(end 98.198686 -278.44115)
		(width 0.1143)
		(layer "In13.Cu")
		(net "P5E_CPU1_P0_RX_DN<1>")
	)
	(segment
		(start 109.448854 -309.02656)
		(end 104.5083 -306.540408)
		(width 0.14224)
		(layer "In13.Cu")
		(net "P5E_CPU1_P0_RX_DN<1>")
	)
	(segment
		(start 102.391718 -361.136438)
		(end 102.37216 -361.33659)
		(width 0.14224)
		(layer "In13.Cu")
		(net "P5E_CPU1_P0_RX_DN<1>")
	)
	(segment
		(start 110.621064 -354.382324)
		(end 102.391718 -361.136438)
		(width 0.14224)
		(layer "In13.Cu")
		(net "P5E_CPU1_P0_RX_DN<1>")
	)
	(segment
		(start 110.301024 -355.753162)
		(end 111.772954 -355.753162)
		(width 0.14224)
		(layer "In13.Cu")
		(net "P5E_CPU1_P0_RX_DN<1>")
	)
	(segment
		(start 51.232308 -373.241824)
		(end 55.115968 -366.912144)
		(width 0.14224)
		(layer "In13.Cu")
		(net "P5E_CPU1_P0_RX_DN<1>")
	)
	(segment
		(start 98.168206 -273.598894)
		(end 98.198686 -273.581114)
		(width 0.1143)
		(layer "In13.Cu")
		(net "P5E_CPU1_P0_RX_DN<1>")
	)
	(segment
		(start 111.772954 -355.753162)
		(end 111.915194 -355.610922)
		(width 0.14224)
		(layer "In13.Cu")
		(net "P5E_CPU1_P0_RX_DN<1>")
	)
	(segment
		(start 121.320306 -354.510086)
		(end 121.622312 -354.207826)
		(width 0.14224)
		(layer "In13.Cu")
		(net "P5E_CPU1_P0_RX_DN<1>")
	)
	(segment
		(start 109.813852 -309.37581)
		(end 109.507274 -309.068724)
		(width 0.14224)
		(layer "In13.Cu")
		(net "P5E_CPU1_P0_RX_DN<1>")
	)
	(segment
		(start 98.168206 -279.433782)
		(end 98.12909 -279.410922)
		(width 0.1143)
		(layer "In13.Cu")
		(net "P5E_CPU1_P0_RX_DN<1>")
	)
	(segment
		(start 98.168206 -283.318966)
		(end 98.198686 -283.301186)
		(width 0.1143)
		(layer "In13.Cu")
		(net "P5E_CPU1_P0_RX_DN<1>")
	)
	(segment
		(start 98.12909 -278.48179)
		(end 98.168206 -278.45893)
		(width 0.1143)
		(layer "In13.Cu")
		(net "P5E_CPU1_P0_RX_DN<1>")
	)
	(segment
		(start 122.117612 -353.906074)
		(end 122.117358 -353.712018)
		(width 0.14224)
		(layer "In13.Cu")
		(net "P5E_CPU1_P0_RX_DN<1>")
	)
	(segment
		(start 98.12909 -280.101802)
		(end 98.168206 -280.078942)
		(width 0.1143)
		(layer "In13.Cu")
		(net "P5E_CPU1_P0_RX_DN<1>")
	)
	(segment
		(start 49.466754 -385.334764)
		(end 49.466754 -385.163822)
		(width 0.14224)
		(layer "In13.Cu")
		(net "P5E_CPU1_P0_RX_DN<1>")
	)
	(segment
		(start 122.613166 -353.409758)
		(end 122.914664 -353.108006)
		(width 0.14224)
		(layer "In13.Cu")
		(net "P5E_CPU1_P0_RX_DN<1>")
	)
	(segment
		(start 98.12909 -294.681402)
		(end 98.198686 -294.641016)
		(width 0.1143)
		(layer "In13.Cu")
		(net "P5E_CPU1_P0_RX_DN<1>")
	)
	(segment
		(start 102.37216 -361.33659)
		(end 102.735126 -361.778804)
		(width 0.14224)
		(layer "In13.Cu")
		(net "P5E_CPU1_P0_RX_DN<1>")
	)
	(segment
		(start 122.91441 -352.91395)
		(end 123.216416 -352.611944)
		(width 0.14224)
		(layer "In13.Cu")
		(net "P5E_CPU1_P0_RX_DN<1>")
	)
	(segment
		(start 110.66399 -353.950016)
		(end 110.621064 -354.382324)
		(width 0.14224)
		(layer "In13.Cu")
		(net "P5E_CPU1_P0_RX_DN<1>")
	)
	(segment
		(start 126.357888 -348.641162)
		(end 124.020072 -335.251044)
		(width 0.14224)
		(layer "In13.Cu")
		(net "P5E_CPU1_P0_RX_DN<1>")
	)
	(segment
		(start 110.151926 -353.3267)
		(end 110.589568 -353.859592)
		(width 0.14224)
		(layer "In13.Cu")
		(net "P5E_CPU1_P0_RX_DN<1>")
	)
	(segment
		(start 109.719364 -353.283774)
		(end 110.151926 -353.3267)
		(width 0.14224)
		(layer "In13.Cu")
		(net "P5E_CPU1_P0_RX_DN<1>")
	)
	(segment
		(start 98.198686 -277.83155)
		(end 98.168206 -277.81377)
		(width 0.1143)
		(layer "In13.Cu")
		(net "P5E_CPU1_P0_RX_DN<1>")
	)
	(segment
		(start 98.168206 -276.838918)
		(end 98.198686 -276.821138)
		(width 0.1143)
		(layer "In13.Cu")
		(net "P5E_CPU1_P0_RX_DN<1>")
	)
	(segment
		(start 123.216416 -352.611944)
		(end 123.410218 -352.61169)
		(width 0.14224)
		(layer "In13.Cu")
		(net "P5E_CPU1_P0_RX_DN<1>")
	)
	(segment
		(start 98.198686 -281.071574)
		(end 98.168206 -281.053794)
		(width 0.1143)
		(layer "In13.Cu")
		(net "P5E_CPU1_P0_RX_DN<1>")
	)
	(segment
		(start 49.465738 -382.208278)
		(end 51.11496 -373.545354)
		(width 0.14224)
		(layer "In13.Cu")
		(net "P5E_CPU1_P0_RX_DN<1>")
	)
	(segment
		(start 98.168206 -277.81377)
		(end 98.12909 -277.79091)
		(width 0.1143)
		(layer "In13.Cu")
		(net "P5E_CPU1_P0_RX_DN<1>")
	)
	(segment
		(start 124.020072 -335.251044)
		(end 121.97334 -327.108312)
		(width 0.14224)
		(layer "In13.Cu")
		(net "P5E_CPU1_P0_RX_DN<1>")
	)
	(segment
		(start 98.198686 -292.41115)
		(end 98.12909 -292.370764)
		(width 0.1143)
		(layer "In13.Cu")
		(net "P5E_CPU1_P0_RX_DN<1>")
	)
	(segment
		(start 98.198686 -289.171126)
		(end 98.12909 -289.13074)
		(width 0.1143)
		(layer "In13.Cu")
		(net "P5E_CPU1_P0_RX_DN<1>")
	)
	(segment
		(start 97.894648 -295.279826)
		(end 97.894648 -295.128442)
		(width 0.1143)
		(layer "In13.Cu")
		(net "P5E_CPU1_P0_RX_DN<1>")
	)
	(segment
		(start 98.12909 -291.441632)
		(end 98.198686 -291.400992)
		(width 0.1143)
		(layer "In13.Cu")
		(net "P5E_CPU1_P0_RX_DN<1>")
	)
	(segment
		(start 97.415858 -296.36212)
		(end 97.415858 -296.197782)
		(width 0.1143)
		(layer "In13.Cu")
		(net "P5E_CPU1_P0_RX_DN<1>")
	)
	(segment
		(start 102.735126 -361.778804)
		(end 102.934516 -361.798362)
		(width 0.14224)
		(layer "In13.Cu")
		(net "P5E_CPU1_P0_RX_DN<1>")
	)
	(segment
		(start 120.19788 -353.784662)
		(end 120.19788 -354.589842)
		(width 0.14224)
		(layer "In13.Cu")
		(net "P5E_CPU1_P0_RX_DN<1>")
	)
	(segment
		(start 118.434866 -320.867278)
		(end 110.146592 -309.708804)
		(width 0.14224)
		(layer "In13.Cu")
		(net "P5E_CPU1_P0_RX_DN<1>")
	)
	(segment
		(start 113.477294 -354.897182)
		(end 113.335054 -355.039422)
		(width 0.14224)
		(layer "In13.Cu")
		(net "P5E_CPU1_P0_RX_DN<1>")
	)
	(segment
		(start 97.370138 -296.40784)
		(end 97.415858 -296.36212)
		(width 0.1143)
		(layer "In13.Cu")
		(net "P5E_CPU1_P0_RX_DN<1>")
	)
	(segment
		(start 119.319294 -322.427092)
		(end 119.31904 -322.427092)
		(width 0.14224)
		(layer "In13.Cu")
		(net "P5E_CPU1_P0_RX_DN<1>")
	)
	(segment
		(start 119.31904 -322.427092)
		(end 118.434866 -320.867278)
		(width 0.14224)
		(layer "In13.Cu")
		(net "P5E_CPU1_P0_RX_DN<1>")
	)
	(segment
		(start 98.12909 -273.621754)
		(end 98.168206 -273.598894)
		(width 0.1143)
		(layer "In13.Cu")
		(net "P5E_CPU1_P0_RX_DN<1>")
	)
	(segment
		(start 49.34458 -385.405376)
		(end 49.345088 -385.404868)
		(width 0.14224)
		(layer "In13.Cu")
		(net "P5E_CPU1_P0_RX_DN<1>")
	)
	(segment
		(start 121.622312 -354.207826)
		(end 121.816114 -354.207826)
		(width 0.14224)
		(layer "In13.Cu")
		(net "P5E_CPU1_P0_RX_DN<1>")
	)
	(segment
		(start 112.222534 -353.477322)
		(end 119.89054 -353.477322)
		(width 0.14224)
		(layer "In13.Cu")
		(net "P5E_CPU1_P0_RX_DN<1>")
	)
	(segment
		(start 113.476024 -355.751892)
		(end 120.273826 -355.751892)
		(width 0.14224)
		(layer "In13.Cu")
		(net "P5E_CPU1_P0_RX_DN<1>")
	)
	(segment
		(start 98.168206 -281.698954)
		(end 98.198686 -281.681174)
		(width 0.1143)
		(layer "In13.Cu")
		(net "P5E_CPU1_P0_RX_DN<1>")
	)
	(segment
		(start 49.466754 -385.163822)
		(end 49.149762 -384.84683)
		(width 0.14224)
		(layer "In13.Cu")
		(net "P5E_CPU1_P0_RX_DN<1>")
	)
	(segment
		(start 119.89054 -353.477322)
		(end 120.19788 -353.784662)
		(width 0.14224)
		(layer "In13.Cu")
		(net "P5E_CPU1_P0_RX_DN<1>")
	)
	(segment
		(start 98.12909 -293.061644)
		(end 98.198686 -293.021004)
		(width 0.1143)
		(layer "In13.Cu")
		(net "P5E_CPU1_P0_RX_DN<1>")
	)
	(segment
		(start 97.370138 -296.422318)
		(end 97.370138 -296.40784)
		(width 0.1143)
		(layer "In13.Cu")
		(net "P5E_CPU1_P0_RX_DN<1>")
	)
	(segment
		(start 98.168206 -275.218906)
		(end 98.198686 -275.201126)
		(width 0.1143)
		(layer "In13.Cu")
		(net "P5E_CPU1_P0_RX_DN<1>")
	)
	(segment
		(start 113.335054 -355.039422)
		(end 113.335054 -355.610922)
		(width 0.14224)
		(layer "In13.Cu")
		(net "P5E_CPU1_P0_RX_DN<1>")
	)
	(segment
		(start 110.146592 -309.708804)
		(end 109.813852 -309.37581)
		(width 0.14224)
		(layer "In13.Cu")
		(net "P5E_CPU1_P0_RX_DN<1>")
	)
	(segment
		(start 102.934516 -361.798362)
		(end 110.301024 -355.753162)
		(width 0.14224)
		(layer "In13.Cu")
		(net "P5E_CPU1_P0_RX_DN<1>")
	)
	(segment
		(start 49.149762 -384.84683)
		(end 49.154588 -384.234944)
		(width 0.14224)
		(layer "In13.Cu")
		(net "P5E_CPU1_P0_RX_DN<1>")
	)
	(segment
		(start 63.502032 -361.958128)
		(end 99.10699 -361.958128)
		(width 0.14224)
		(layer "In13.Cu")
		(net "P5E_CPU1_P0_RX_DN<1>")
	)
	(segment
		(start 98.3488 -273.346164)
		(end 98.27895 -273.276314)
		(width 0.1143)
		(layer "In13.Cu")
		(net "P5E_CPU1_P0_RX_DN<1>")
	)
	(segment
		(start 98.198686 -279.451562)
		(end 98.168206 -279.433782)
		(width 0.1143)
		(layer "In13.Cu")
		(net "P5E_CPU1_P0_RX_DN<1>")
	)
	(segment
		(start 121.97334 -327.108312)
		(end 119.319294 -322.427092)
		(width 0.14224)
		(layer "In13.Cu")
		(net "P5E_CPU1_P0_RX_DN<1>")
	)
	(segment
		(start 98.168206 -282.673806)
		(end 98.12909 -282.650946)
		(width 0.1143)
		(layer "In13.Cu")
		(net "P5E_CPU1_P0_RX_DN<1>")
	)
	(segment
		(start 113.335054 -355.610922)
		(end 113.476024 -355.751892)
		(width 0.14224)
		(layer "In13.Cu")
		(net "P5E_CPU1_P0_RX_DN<1>")
	)
	(segment
		(start 98.198686 -282.691586)
		(end 98.168206 -282.673806)
		(width 0.1143)
		(layer "In13.Cu")
		(net "P5E_CPU1_P0_RX_DN<1>")
	)
	(segment
		(start 98.168206 -284.293818)
		(end 98.12909 -284.270958)
		(width 0.1143)
		(layer "In13.Cu")
		(net "P5E_CPU1_P0_RX_DN<1>")
	)
	(segment
		(start 98.168206 -284.938978)
		(end 98.198686 -284.921198)
		(width 0.1143)
		(layer "In13.Cu")
		(net "P5E_CPU1_P0_RX_DN<1>")
	)
	(segment
		(start 98.12909 -281.721814)
		(end 98.168206 -281.698954)
		(width 0.1143)
		(layer "In13.Cu")
		(net "P5E_CPU1_P0_RX_DN<1>")
	)
	(segment
		(start 98.12909 -276.861778)
		(end 98.168206 -276.838918)
		(width 0.1143)
		(layer "In13.Cu")
		(net "P5E_CPU1_P0_RX_DN<1>")
	)
	(segment
		(start 121.816114 -354.207826)
		(end 122.117612 -353.906074)
		(width 0.14224)
		(layer "In13.Cu")
		(net "P5E_CPU1_P0_RX_DN<1>")
	)
	(segment
		(start 98.198686 -284.311598)
		(end 98.168206 -284.293818)
		(width 0.1143)
		(layer "In13.Cu")
		(net "P5E_CPU1_P0_RX_DN<1>")
	)
	(segment
		(start 122.914664 -353.108006)
		(end 122.91441 -352.91395)
		(width 0.14224)
		(layer "In13.Cu")
		(net "P5E_CPU1_P0_RX_DN<1>")
	)
	(segment
		(start 120.273826 -355.751892)
		(end 121.32056 -354.704142)
		(width 0.14224)
		(layer "In13.Cu")
		(net "P5E_CPU1_P0_RX_DN<1>")
	)
	(segment
		(start 104.10571 -306.249578)
		(end 97.727008 -299.870876)
		(width 0.14224)
		(layer "In13.Cu")
		(net "P5E_CPU1_P0_RX_DN<1>")
	)
	(segment
		(start 111.915194 -353.784662)
		(end 112.222534 -353.477322)
		(width 0.14224)
		(layer "In13.Cu")
		(net "P5E_CPU1_P0_RX_DN<1>")
	)
	(arc
		(start 98.12909 -293.990776)
		(mid 97.885763 -293.52621)
		(end 98.12909 -293.061644)
		(width 0.1143)
		(layer "In13.Cu")
		(net "P5E_CPU1_P0_RX_DN<1>")
	)
	(arc
		(start 98.12909 -285.89097)
		(mid 97.885763 -285.426404)
		(end 98.12909 -284.961838)
		(width 0.1143)
		(layer "In13.Cu")
		(net "P5E_CPU1_P0_RX_DN<1>")
	)
	(arc
		(start 97.727008 -299.870876)
		(mid 97.462907 -299.475716)
		(end 97.370138 -299.009562)
		(width 0.14224)
		(layer "In13.Cu")
		(net "P5E_CPU1_P0_RX_DN<1>")
	)
	(arc
		(start 97.886012 -287.046162)
		(mid 97.950188 -286.784275)
		(end 98.128328 -286.58185)
		(width 0.1143)
		(layer "In13.Cu")
		(net "P5E_CPU1_P0_RX_DN<1>")
	)
	(arc
		(start 98.12909 -282.650946)
		(mid 97.885763 -282.18638)
		(end 98.12909 -281.721814)
		(width 0.1143)
		(layer "In13.Cu")
		(net "P5E_CPU1_P0_RX_DN<1>")
	)
	(arc
		(start 98.12909 -284.270958)
		(mid 97.885763 -283.806392)
		(end 98.12909 -283.341826)
		(width 0.1143)
		(layer "In13.Cu")
		(net "P5E_CPU1_P0_RX_DN<1>")
	)
	(arc
		(start 98.198686 -280.061162)
		(mid 98.355663 -279.756362)
		(end 98.198686 -279.451562)
		(width 0.1143)
		(layer "In13.Cu")
		(net "P5E_CPU1_P0_RX_DN<1>")
	)
	(arc
		(start 98.12909 -274.550886)
		(mid 97.885763 -274.08632)
		(end 98.12909 -273.621754)
		(width 0.1143)
		(layer "In13.Cu")
		(net "P5E_CPU1_P0_RX_DN<1>")
	)
	(arc
		(start 98.198686 -278.44115)
		(mid 98.355663 -278.13635)
		(end 98.198686 -277.83155)
		(width 0.1143)
		(layer "In13.Cu")
		(net "P5E_CPU1_P0_RX_DN<1>")
	)
	(arc
		(start 98.130614 -287.511744)
		(mid 97.950822 -287.309156)
		(end 97.886012 -287.046162)
		(width 0.1143)
		(layer "In13.Cu")
		(net "P5E_CPU1_P0_RX_DN<1>")
	)
	(arc
		(start 99.10699 -361.958128)
		(mid 99.149753 -361.950621)
		(end 99.187508 -361.929172)
		(width 0.14224)
		(layer "In13.Cu")
		(net "P5E_CPU1_P0_RX_DN<1>")
	)
	(arc
		(start 109.507274 -309.068724)
		(mid 109.479744 -309.045317)
		(end 109.448854 -309.02656)
		(width 0.14224)
		(layer "In13.Cu")
		(net "P5E_CPU1_P0_RX_DN<1>")
	)
	(arc
		(start 97.894648 -295.128442)
		(mid 97.954721 -294.880306)
		(end 98.12147 -294.68699)
		(width 0.1143)
		(layer "In13.Cu")
		(net "P5E_CPU1_P0_RX_DN<1>")
	)
	(arc
		(start 98.12909 -277.79091)
		(mid 97.885763 -277.326344)
		(end 98.12909 -276.861778)
		(width 0.1143)
		(layer "In13.Cu")
		(net "P5E_CPU1_P0_RX_DN<1>")
	)
	(arc
		(start 97.822512 -295.453562)
		(mid 97.875768 -295.37372)
		(end 97.894394 -295.279572)
		(width 0.1143)
		(layer "In13.Cu")
		(net "P5E_CPU1_P0_RX_DN<1>")
	)
	(arc
		(start 98.198686 -273.581114)
		(mid 98.296451 -273.478138)
		(end 98.3488 -273.346164)
		(width 0.1143)
		(layer "In13.Cu")
		(net "P5E_CPU1_P0_RX_DN<1>")
	)
	(arc
		(start 98.199702 -286.540448)
		(mid 98.355635 -286.236513)
		(end 98.199956 -285.932372)
		(width 0.1143)
		(layer "In13.Cu")
		(net "P5E_CPU1_P0_RX_DN<1>")
	)
	(arc
		(start 98.12909 -289.13074)
		(mid 97.885763 -288.666102)
		(end 98.12909 -288.201354)
		(width 0.1143)
		(layer "In13.Cu")
		(net "P5E_CPU1_P0_RX_DN<1>")
	)
	(arc
		(start 98.12909 -279.410922)
		(mid 97.885763 -278.946356)
		(end 98.12909 -278.48179)
		(width 0.1143)
		(layer "In13.Cu")
		(net "P5E_CPU1_P0_RX_DN<1>")
	)
	(arc
		(start 98.198686 -276.821138)
		(mid 98.355663 -276.516338)
		(end 98.198686 -276.211538)
		(width 0.1143)
		(layer "In13.Cu")
		(net "P5E_CPU1_P0_RX_DN<1>")
	)
	(arc
		(start 98.198686 -281.681174)
		(mid 98.355663 -281.376374)
		(end 98.198686 -281.071574)
		(width 0.1143)
		(layer "In13.Cu")
		(net "P5E_CPU1_P0_RX_DN<1>")
	)
	(arc
		(start 49.458626 -382.284732)
		(mid 49.460381 -382.246337)
		(end 49.465738 -382.208278)
		(width 0.14224)
		(layer "In13.Cu")
		(net "P5E_CPU1_P0_RX_DN<1>")
	)
	(arc
		(start 98.198686 -294.641016)
		(mid 98.355663 -294.336142)
		(end 98.198686 -294.031162)
		(width 0.1143)
		(layer "In13.Cu")
		(net "P5E_CPU1_P0_RX_DN<1>")
	)
	(arc
		(start 98.12909 -290.750752)
		(mid 97.885763 -290.286186)
		(end 98.12909 -289.82162)
		(width 0.1143)
		(layer "In13.Cu")
		(net "P5E_CPU1_P0_RX_DN<1>")
	)
	(arc
		(start 98.12147 -294.68699)
		(mid 98.125268 -294.68418)
		(end 98.12909 -294.681402)
		(width 0.1143)
		(layer "In13.Cu")
		(net "P5E_CPU1_P0_RX_DN<1>")
	)
	(arc
		(start 98.12909 -292.370764)
		(mid 97.885763 -291.906198)
		(end 98.12909 -291.441632)
		(width 0.1143)
		(layer "In13.Cu")
		(net "P5E_CPU1_P0_RX_DN<1>")
	)
	(arc
		(start 63.319406 -362.001308)
		(mid 63.408206 -361.969085)
		(end 63.502032 -361.958128)
		(width 0.14224)
		(layer "In13.Cu")
		(net "P5E_CPU1_P0_RX_DN<1>")
	)
	(arc
		(start 55.115968 -366.912144)
		(mid 55.143586 -366.872663)
		(end 55.175658 -366.836706)
		(width 0.14224)
		(layer "In13.Cu")
		(net "P5E_CPU1_P0_RX_DN<1>")
	)
	(arc
		(start 98.12909 -281.030934)
		(mid 97.885763 -280.566368)
		(end 98.12909 -280.101802)
		(width 0.1143)
		(layer "In13.Cu")
		(net "P5E_CPU1_P0_RX_DN<1>")
	)
	(arc
		(start 98.198686 -293.021004)
		(mid 98.355663 -292.71613)
		(end 98.198686 -292.41115)
		(width 0.1143)
		(layer "In13.Cu")
		(net "P5E_CPU1_P0_RX_DN<1>")
	)
	(arc
		(start 98.199956 -288.160206)
		(mid 98.355781 -287.854972)
		(end 98.197924 -287.55086)
		(width 0.1143)
		(layer "In13.Cu")
		(net "P5E_CPU1_P0_RX_DN<1>")
	)
	(arc
		(start 98.198686 -291.400992)
		(mid 98.355663 -291.096118)
		(end 98.198686 -290.791138)
		(width 0.1143)
		(layer "In13.Cu")
		(net "P5E_CPU1_P0_RX_DN<1>")
	)
	(arc
		(start 98.198686 -289.78098)
		(mid 98.355663 -289.476106)
		(end 98.198686 -289.171126)
		(width 0.1143)
		(layer "In13.Cu")
		(net "P5E_CPU1_P0_RX_DN<1>")
	)
	(arc
		(start 104.5083 -306.540408)
		(mid 104.295385 -306.41108)
		(end 104.10571 -306.249578)
		(width 0.14224)
		(layer "In13.Cu")
		(net "P5E_CPU1_P0_RX_DN<1>")
	)
	(arc
		(start 98.198686 -284.921198)
		(mid 98.355663 -284.616398)
		(end 98.198686 -284.311598)
		(width 0.1143)
		(layer "In13.Cu")
		(net "P5E_CPU1_P0_RX_DN<1>")
	)
	(arc
		(start 98.12909 -276.170898)
		(mid 97.885763 -275.706332)
		(end 98.12909 -275.241766)
		(width 0.1143)
		(layer "In13.Cu")
		(net "P5E_CPU1_P0_RX_DN<1>")
	)
	(arc
		(start 98.198686 -275.201126)
		(mid 98.355663 -274.896326)
		(end 98.198686 -274.591526)
		(width 0.1143)
		(layer "In13.Cu")
		(net "P5E_CPU1_P0_RX_DN<1>")
	)
	(arc
		(start 56.662574 -365.349536)
		(mid 56.712815 -365.306871)
		(end 56.769254 -365.272828)
		(width 0.14224)
		(layer "In13.Cu")
		(net "P5E_CPU1_P0_RX_DN<1>")
	)
	(arc
		(start 97.415858 -296.197782)
		(mid 97.477727 -295.886183)
		(end 97.65411 -295.621964)
		(width 0.1143)
		(layer "In13.Cu")
		(net "P5E_CPU1_P0_RX_DN<1>")
	)
	(arc
		(start 98.198686 -283.301186)
		(mid 98.355663 -282.996386)
		(end 98.198686 -282.691586)
		(width 0.1143)
		(layer "In13.Cu")
		(net "P5E_CPU1_P0_RX_DN<1>")
	)
	(arc
		(start 51.11496 -373.545354)
		(mid 51.159853 -373.388261)
		(end 51.232308 -373.241824)
		(width 0.14224)
		(layer "In13.Cu")
		(net "P5E_CPU1_P0_RX_DN<1>")
	)
	(segment
		(start 109.257846 -268.960346)
		(end 108.790994 -269.226284)
		(width 0.12954)
		(layer "F.Cu")
		(net "P5E_CPU1_P0_RX_DN<15>")
	)
	(segment
		(start 65.270634 -385.31038)
		(end 65.791334 -385.31038)
		(width 0.127)
		(layer "F.Cu")
		(net "P5E_CPU1_P0_RX_DN<15>")
	)
	(segment
		(start 109.448092 -269.71371)
		(end 109.445806 -269.712186)
		(width 0.1143)
		(layer "In15.Cu")
		(net "P5E_CPU1_P0_RX_DN<15>")
	)
	(segment
		(start 83.263486 -378.093478)
		(end 104.782874 -378.093478)
		(width 0.14224)
		(layer "In15.Cu")
		(net "P5E_CPU1_P0_RX_DN<15>")
	)
	(segment
		(start 80.444086 -377.956318)
		(end 80.870806 -377.956318)
		(width 0.14224)
		(layer "In15.Cu")
		(net "P5E_CPU1_P0_RX_DN<15>")
	)
	(segment
		(start 82.135726 -378.093478)
		(end 82.562446 -378.093478)
		(width 0.14224)
		(layer "In15.Cu")
		(net "P5E_CPU1_P0_RX_DN<15>")
	)
	(segment
		(start 109.924088 -270.527272)
		(end 109.922564 -270.526256)
		(width 0.1143)
		(layer "In15.Cu")
		(net "P5E_CPU1_P0_RX_DN<15>")
	)
	(segment
		(start 71.446898 -381.887222)
		(end 74.946256 -378.387864)
		(width 0.14224)
		(layer "In15.Cu")
		(net "P5E_CPU1_P0_RX_DN<15>")
	)
	(segment
		(start 80.306926 -378.093478)
		(end 80.444086 -377.956318)
		(width 0.14224)
		(layer "In15.Cu")
		(net "P5E_CPU1_P0_RX_DN<15>")
	)
	(segment
		(start 110.388146 -271.333722)
		(end 110.34903 -271.310862)
		(width 0.1143)
		(layer "In15.Cu")
		(net "P5E_CPU1_P0_RX_DN<15>")
	)
	(segment
		(start 109.416342 -269.695168)
		(end 109.409738 -269.691358)
		(width 0.1143)
		(layer "In15.Cu")
		(net "P5E_CPU1_P0_RX_DN<15>")
	)
	(segment
		(start 111.77778 -301.357284)
		(end 111.77778 -295.347898)
		(width 0.14224)
		(layer "In15.Cu")
		(net "P5E_CPU1_P0_RX_DN<15>")
	)
	(segment
		(start 82.562446 -378.093478)
		(end 82.699606 -377.956318)
		(width 0.14224)
		(layer "In15.Cu")
		(net "P5E_CPU1_P0_RX_DN<15>")
	)
	(segment
		(start 109.436154 -269.706598)
		(end 109.417104 -269.695676)
		(width 0.1143)
		(layer "In15.Cu")
		(net "P5E_CPU1_P0_RX_DN<15>")
	)
	(segment
		(start 81.571846 -377.956318)
		(end 81.998566 -377.956318)
		(width 0.14224)
		(layer "In15.Cu")
		(net "P5E_CPU1_P0_RX_DN<15>")
	)
	(segment
		(start 110.94085 -271.93875)
		(end 110.94085 -271.873726)
		(width 0.1143)
		(layer "In15.Cu")
		(net "P5E_CPU1_P0_RX_DN<15>")
	)
	(segment
		(start 109.918754 -270.524224)
		(end 109.917992 -270.523716)
		(width 0.1143)
		(layer "In15.Cu")
		(net "P5E_CPU1_P0_RX_DN<15>")
	)
	(segment
		(start 104.900222 -378.014992)
		(end 106.251502 -374.752108)
		(width 0.14224)
		(layer "In15.Cu")
		(net "P5E_CPU1_P0_RX_DN<15>")
	)
	(segment
		(start 109.442504 -269.710408)
		(end 109.440726 -269.709392)
		(width 0.1143)
		(layer "In15.Cu")
		(net "P5E_CPU1_P0_RX_DN<15>")
	)
	(segment
		(start 109.440726 -269.709392)
		(end 109.439964 -269.708884)
		(width 0.1143)
		(layer "In15.Cu")
		(net "P5E_CPU1_P0_RX_DN<15>")
	)
	(segment
		(start 66.145156 -385.404868)
		(end 66.266822 -385.334764)
		(width 0.14224)
		(layer "In15.Cu")
		(net "P5E_CPU1_P0_RX_DN<15>")
	)
	(segment
		(start 134.355332 -340.091268)
		(end 123.106434 -328.84237)
		(width 0.14224)
		(layer "In15.Cu")
		(net "P5E_CPU1_P0_RX_DN<15>")
	)
	(segment
		(start 66.144648 -385.405376)
		(end 66.145156 -385.404868)
		(width 0.14224)
		(layer "In15.Cu")
		(net "P5E_CPU1_P0_RX_DN<15>")
	)
	(segment
		(start 109.436916 -269.707106)
		(end 109.436154 -269.706598)
		(width 0.1143)
		(layer "In15.Cu")
		(net "P5E_CPU1_P0_RX_DN<15>")
	)
	(segment
		(start 110.418626 -271.351502)
		(end 110.388146 -271.333722)
		(width 0.1143)
		(layer "In15.Cu")
		(net "P5E_CPU1_P0_RX_DN<15>")
	)
	(segment
		(start 109.460284 -269.720568)
		(end 109.458506 -269.719552)
		(width 0.1143)
		(layer "In15.Cu")
		(net "P5E_CPU1_P0_RX_DN<15>")
	)
	(segment
		(start 111.445294 -274.809204)
		(end 111.445294 -272.443194)
		(width 0.14224)
		(layer "In15.Cu")
		(net "P5E_CPU1_P0_RX_DN<15>")
	)
	(segment
		(start 111.445294 -272.443194)
		(end 110.960916 -271.958816)
		(width 0.14224)
		(layer "In15.Cu")
		(net "P5E_CPU1_P0_RX_DN<15>")
	)
	(segment
		(start 109.527086 -374.320308)
		(end 110.98276 -375.775982)
		(width 0.14224)
		(layer "In15.Cu")
		(net "P5E_CPU1_P0_RX_DN<15>")
	)
	(segment
		(start 109.922564 -270.526256)
		(end 109.920024 -270.524986)
		(width 0.1143)
		(layer "In15.Cu")
		(net "P5E_CPU1_P0_RX_DN<15>")
	)
	(segment
		(start 170.741594 -358.904286)
		(end 167.482266 -355.644958)
		(width 0.14224)
		(layer "In15.Cu")
		(net "P5E_CPU1_P0_RX_DN<15>")
	)
	(segment
		(start 136.531858 -374.233948)
		(end 141.851634 -374.233948)
		(width 0.14224)
		(layer "In15.Cu")
		(net "P5E_CPU1_P0_RX_DN<15>")
	)
	(segment
		(start 144.546066 -376.269758)
		(end 167.449754 -376.269758)
		(width 0.14224)
		(layer "In15.Cu")
		(net "P5E_CPU1_P0_RX_DN<15>")
	)
	(segment
		(start 109.646212 -270.053562)
		(end 109.646212 -270.044164)
		(width 0.1143)
		(layer "In15.Cu")
		(net "P5E_CPU1_P0_RX_DN<15>")
	)
	(segment
		(start 168.629584 -375.481596)
		(end 172.205142 -366.84966)
		(width 0.14224)
		(layer "In15.Cu")
		(net "P5E_CPU1_P0_RX_DN<15>")
	)
	(segment
		(start 122.82551 -328.422)
		(end 111.929926 -302.121824)
		(width 0.14224)
		(layer "In15.Cu")
		(net "P5E_CPU1_P0_RX_DN<15>")
	)
	(segment
		(start 109.439964 -269.708884)
		(end 109.436916 -269.707106)
		(width 0.1143)
		(layer "In15.Cu")
		(net "P5E_CPU1_P0_RX_DN<15>")
	)
	(segment
		(start 109.458506 -269.719552)
		(end 109.454696 -269.71752)
		(width 0.1143)
		(layer "In15.Cu")
		(net "P5E_CPU1_P0_RX_DN<15>")
	)
	(segment
		(start 131.680966 -376.242834)
		(end 136.531858 -374.233948)
		(width 0.14224)
		(layer "In15.Cu")
		(net "P5E_CPU1_P0_RX_DN<15>")
	)
	(segment
		(start 109.949742 -270.542004)
		(end 109.924088 -270.527272)
		(width 0.1143)
		(layer "In15.Cu")
		(net "P5E_CPU1_P0_RX_DN<15>")
	)
	(segment
		(start 65.791334 -385.31038)
		(end 66.144648 -385.405376)
		(width 0.14224)
		(layer "In15.Cu")
		(net "P5E_CPU1_P0_RX_DN<15>")
	)
	(segment
		(start 81.998566 -377.956318)
		(end 82.135726 -378.093478)
		(width 0.14224)
		(layer "In15.Cu")
		(net "P5E_CPU1_P0_RX_DN<15>")
	)
	(segment
		(start 81.434686 -378.093478)
		(end 81.571846 -377.956318)
		(width 0.14224)
		(layer "In15.Cu")
		(net "P5E_CPU1_P0_RX_DN<15>")
	)
	(segment
		(start 81.007966 -378.093478)
		(end 81.434686 -378.093478)
		(width 0.14224)
		(layer "In15.Cu")
		(net "P5E_CPU1_P0_RX_DN<15>")
	)
	(segment
		(start 110.94085 -271.873726)
		(end 110.418626 -271.351502)
		(width 0.1143)
		(layer "In15.Cu")
		(net "P5E_CPU1_P0_RX_DN<15>")
	)
	(segment
		(start 83.126326 -377.956318)
		(end 83.263486 -378.093478)
		(width 0.14224)
		(layer "In15.Cu")
		(net "P5E_CPU1_P0_RX_DN<15>")
	)
	(segment
		(start 109.17174 -269.309088)
		(end 109.088936 -269.226284)
		(width 0.1143)
		(layer "In15.Cu")
		(net "P5E_CPU1_P0_RX_DN<15>")
	)
	(segment
		(start 75.657202 -378.093478)
		(end 80.306926 -378.093478)
		(width 0.14224)
		(layer "In15.Cu")
		(net "P5E_CPU1_P0_RX_DN<15>")
	)
	(segment
		(start 109.445806 -269.712186)
		(end 109.442504 -269.710408)
		(width 0.1143)
		(layer "In15.Cu")
		(net "P5E_CPU1_P0_RX_DN<15>")
	)
	(segment
		(start 109.454696 -269.71752)
		(end 109.449362 -269.714472)
		(width 0.1143)
		(layer "In15.Cu")
		(net "P5E_CPU1_P0_RX_DN<15>")
	)
	(segment
		(start 153.267918 -352.806)
		(end 134.864094 -340.508844)
		(width 0.14224)
		(layer "In15.Cu")
		(net "P5E_CPU1_P0_RX_DN<15>")
	)
	(segment
		(start 111.77778 -295.347898)
		(end 111.445294 -274.809204)
		(width 0.14224)
		(layer "In15.Cu")
		(net "P5E_CPU1_P0_RX_DN<15>")
	)
	(segment
		(start 109.417104 -269.695676)
		(end 109.416342 -269.695168)
		(width 0.1143)
		(layer "In15.Cu")
		(net "P5E_CPU1_P0_RX_DN<15>")
	)
	(segment
		(start 82.699606 -377.956318)
		(end 83.126326 -377.956318)
		(width 0.14224)
		(layer "In15.Cu")
		(net "P5E_CPU1_P0_RX_DN<15>")
	)
	(segment
		(start 80.870806 -377.956318)
		(end 81.007966 -378.093478)
		(width 0.14224)
		(layer "In15.Cu")
		(net "P5E_CPU1_P0_RX_DN<15>")
	)
	(segment
		(start 112.133888 -376.25274)
		(end 131.631944 -376.25274)
		(width 0.14224)
		(layer "In15.Cu")
		(net "P5E_CPU1_P0_RX_DN<15>")
	)
	(segment
		(start 165.553644 -354.846128)
		(end 156.248354 -354.846128)
		(width 0.14224)
		(layer "In15.Cu")
		(net "P5E_CPU1_P0_RX_DN<15>")
	)
	(segment
		(start 69.16166 -382.23952)
		(end 70.596506 -382.23952)
		(width 0.14224)
		(layer "In15.Cu")
		(net "P5E_CPU1_P0_RX_DN<15>")
	)
	(segment
		(start 154.643074 -354.181156)
		(end 153.267918 -352.806)
		(width 0.14224)
		(layer "In15.Cu")
		(net "P5E_CPU1_P0_RX_DN<15>")
	)
	(segment
		(start 66.266822 -384.735578)
		(end 68.48094 -382.52146)
		(width 0.14224)
		(layer "In15.Cu")
		(net "P5E_CPU1_P0_RX_DN<15>")
	)
	(segment
		(start 142.16507 -374.363742)
		(end 143.735044 -375.933716)
		(width 0.14224)
		(layer "In15.Cu")
		(net "P5E_CPU1_P0_RX_DN<15>")
	)
	(segment
		(start 109.449362 -269.714472)
		(end 109.448092 -269.71371)
		(width 0.1143)
		(layer "In15.Cu")
		(net "P5E_CPU1_P0_RX_DN<15>")
	)
	(segment
		(start 66.266822 -385.334764)
		(end 66.266822 -384.735578)
		(width 0.14224)
		(layer "In15.Cu")
		(net "P5E_CPU1_P0_RX_DN<15>")
	)
	(segment
		(start 109.088936 -269.226284)
		(end 108.790994 -269.226284)
		(width 0.1143)
		(layer "In15.Cu")
		(net "P5E_CPU1_P0_RX_DN<15>")
	)
	(segment
		(start 172.22978 -366.726216)
		(end 172.22978 -361.66044)
		(width 0.14224)
		(layer "In15.Cu")
		(net "P5E_CPU1_P0_RX_DN<15>")
	)
	(segment
		(start 109.917992 -270.523716)
		(end 109.917992 -270.523462)
		(width 0.1143)
		(layer "In15.Cu")
		(net "P5E_CPU1_P0_RX_DN<15>")
	)
	(segment
		(start 109.920024 -270.524986)
		(end 109.918754 -270.524224)
		(width 0.1143)
		(layer "In15.Cu")
		(net "P5E_CPU1_P0_RX_DN<15>")
	)
	(segment
		(start 110.960916 -271.958816)
		(end 110.94085 -271.93875)
		(width 0.1143)
		(layer "In15.Cu")
		(net "P5E_CPU1_P0_RX_DN<15>")
	)
	(segment
		(start 107.036616 -374.20042)
		(end 109.23778 -374.20042)
		(width 0.14224)
		(layer "In15.Cu")
		(net "P5E_CPU1_P0_RX_DN<15>")
	)
	(arc
		(start 74.946256 -378.387864)
		(mid 75.272455 -378.169968)
		(end 75.657202 -378.093478)
		(width 0.14224)
		(layer "In15.Cu")
		(net "P5E_CPU1_P0_RX_DN<15>")
	)
	(arc
		(start 156.248354 -354.846128)
		(mid 155.37958 -354.6733)
		(end 154.643074 -354.181156)
		(width 0.14224)
		(layer "In15.Cu")
		(net "P5E_CPU1_P0_RX_DN<15>")
	)
	(arc
		(start 68.48094 -382.52146)
		(mid 68.793257 -382.312776)
		(end 69.16166 -382.23952)
		(width 0.14224)
		(layer "In15.Cu")
		(net "P5E_CPU1_P0_RX_DN<15>")
	)
	(arc
		(start 167.482266 -355.644958)
		(mid 166.597407 -355.053714)
		(end 165.553644 -354.846128)
		(width 0.14224)
		(layer "In15.Cu")
		(net "P5E_CPU1_P0_RX_DN<15>")
	)
	(arc
		(start 172.215048 -361.53471)
		(mid 171.660219 -360.117608)
		(end 170.741594 -358.904286)
		(width 0.14224)
		(layer "In15.Cu")
		(net "P5E_CPU1_P0_RX_DN<15>")
	)
	(arc
		(start 109.646212 -270.044164)
		(mid 109.596428 -269.85755)
		(end 109.460284 -269.720568)
		(width 0.1143)
		(layer "In15.Cu")
		(net "P5E_CPU1_P0_RX_DN<15>")
	)
	(arc
		(start 109.408976 -269.69085)
		(mid 109.256989 -269.534342)
		(end 109.17555 -269.331948)
		(width 0.1143)
		(layer "In15.Cu")
		(net "P5E_CPU1_P0_RX_DN<15>")
	)
	(arc
		(start 70.596506 -382.23952)
		(mid 71.056741 -382.147956)
		(end 71.446898 -381.887222)
		(width 0.14224)
		(layer "In15.Cu")
		(net "P5E_CPU1_P0_RX_DN<15>")
	)
	(arc
		(start 110.98276 -375.775982)
		(mid 111.510916 -376.128822)
		(end 112.133888 -376.25274)
		(width 0.14224)
		(layer "In15.Cu")
		(net "P5E_CPU1_P0_RX_DN<15>")
	)
	(arc
		(start 167.449754 -376.269758)
		(mid 168.159184 -376.05459)
		(end 168.629584 -375.481596)
		(width 0.14224)
		(layer "In15.Cu")
		(net "P5E_CPU1_P0_RX_DN<15>")
	)
	(arc
		(start 106.830622 -374.229884)
		(mid 106.932551 -374.20768)
		(end 107.036616 -374.20042)
		(width 0.14224)
		(layer "In15.Cu")
		(net "P5E_CPU1_P0_RX_DN<15>")
	)
	(arc
		(start 134.864094 -340.508844)
		(mid 134.599458 -340.312551)
		(end 134.355332 -340.091268)
		(width 0.14224)
		(layer "In15.Cu")
		(net "P5E_CPU1_P0_RX_DN<15>")
	)
	(arc
		(start 109.17555 -269.331948)
		(mid 109.173527 -269.320538)
		(end 109.17174 -269.309088)
		(width 0.1143)
		(layer "In15.Cu")
		(net "P5E_CPU1_P0_RX_DN<15>")
	)
	(arc
		(start 172.205142 -366.84966)
		(mid 172.223565 -366.789154)
		(end 172.22978 -366.726216)
		(width 0.14224)
		(layer "In15.Cu")
		(net "P5E_CPU1_P0_RX_DN<15>")
	)
	(arc
		(start 109.409738 -269.691358)
		(mid 109.409357 -269.691104)
		(end 109.408976 -269.69085)
		(width 0.1143)
		(layer "In15.Cu")
		(net "P5E_CPU1_P0_RX_DN<15>")
	)
	(arc
		(start 143.735044 -375.933716)
		(mid 144.107129 -376.182428)
		(end 144.546066 -376.269758)
		(width 0.14224)
		(layer "In15.Cu")
		(net "P5E_CPU1_P0_RX_DN<15>")
	)
	(arc
		(start 131.631944 -376.25274)
		(mid 131.656945 -376.250214)
		(end 131.680966 -376.242834)
		(width 0.14224)
		(layer "In15.Cu")
		(net "P5E_CPU1_P0_RX_DN<15>")
	)
	(arc
		(start 106.251502 -374.752108)
		(mid 106.482022 -374.425523)
		(end 106.830622 -374.229884)
		(width 0.14224)
		(layer "In15.Cu")
		(net "P5E_CPU1_P0_RX_DN<15>")
	)
	(arc
		(start 123.106434 -328.84237)
		(mid 122.945288 -328.64601)
		(end 122.82551 -328.422)
		(width 0.14224)
		(layer "In15.Cu")
		(net "P5E_CPU1_P0_RX_DN<15>")
	)
	(arc
		(start 110.105698 -270.846296)
		(mid 110.064443 -270.675325)
		(end 109.949742 -270.542004)
		(width 0.1143)
		(layer "In15.Cu")
		(net "P5E_CPU1_P0_RX_DN<15>")
	)
	(arc
		(start 109.23778 -374.20042)
		(mid 109.394358 -374.231583)
		(end 109.527086 -374.320308)
		(width 0.14224)
		(layer "In15.Cu")
		(net "P5E_CPU1_P0_RX_DN<15>")
	)
	(arc
		(start 111.929926 -302.121824)
		(mid 111.816169 -301.747052)
		(end 111.77778 -301.357284)
		(width 0.14224)
		(layer "In15.Cu")
		(net "P5E_CPU1_P0_RX_DN<15>")
	)
	(arc
		(start 141.851634 -374.233948)
		(mid 142.021251 -374.267687)
		(end 142.16507 -374.363742)
		(width 0.14224)
		(layer "In15.Cu")
		(net "P5E_CPU1_P0_RX_DN<15>")
	)
	(arc
		(start 104.782874 -378.093478)
		(mid 104.853467 -378.072051)
		(end 104.900222 -378.014992)
		(width 0.14224)
		(layer "In15.Cu")
		(net "P5E_CPU1_P0_RX_DN<15>")
	)
	(arc
		(start 172.22978 -361.66044)
		(mid 172.226133 -361.597139)
		(end 172.215048 -361.53471)
		(width 0.14224)
		(layer "In15.Cu")
		(net "P5E_CPU1_P0_RX_DN<15>")
	)
	(arc
		(start 110.34903 -271.310862)
		(mid 110.170217 -271.108512)
		(end 110.105698 -270.846296)
		(width 0.1143)
		(layer "In15.Cu")
		(net "P5E_CPU1_P0_RX_DN<15>")
	)
	(arc
		(start 109.917992 -270.523462)
		(mid 109.719024 -270.324989)
		(end 109.646212 -270.053562)
		(width 0.1143)
		(layer "In15.Cu")
		(net "P5E_CPU1_P0_RX_DN<15>")
	)
	(segment
		(start 64.070738 -385.31038)
		(end 64.591438 -385.31038)
		(width 0.127)
		(layer "F.Cu")
		(net "P5E_CPU1_P0_RX_DN<14>")
	)
	(segment
		(start 109.257846 -270.580358)
		(end 108.790994 -270.846296)
		(width 0.12954)
		(layer "F.Cu")
		(net "P5E_CPU1_P0_RX_DN<14>")
	)
	(segment
		(start 110.388146 -281.053794)
		(end 110.34903 -281.030934)
		(width 0.1143)
		(layer "In15.Cu")
		(net "P5E_CPU1_P0_RX_DN<14>")
	)
	(segment
		(start 118.031006 -366.730534)
		(end 118.168166 -366.867694)
		(width 0.14224)
		(layer "In15.Cu")
		(net "P5E_CPU1_P0_RX_DN<14>")
	)
	(segment
		(start 65.058544 -383.93116)
		(end 65.058544 -382.084326)
		(width 0.14224)
		(layer "In15.Cu")
		(net "P5E_CPU1_P0_RX_DN<14>")
	)
	(segment
		(start 116.193062 -366.867694)
		(end 117.467126 -366.867694)
		(width 0.14224)
		(layer "In15.Cu")
		(net "P5E_CPU1_P0_RX_DN<14>")
	)
	(segment
		(start 110.388146 -294.013636)
		(end 110.387892 -294.013636)
		(width 0.1143)
		(layer "In15.Cu")
		(net "P5E_CPU1_P0_RX_DN<14>")
	)
	(segment
		(start 115.065302 -366.867694)
		(end 115.492022 -366.867694)
		(width 0.14224)
		(layer "In15.Cu")
		(net "P5E_CPU1_P0_RX_DN<14>")
	)
	(segment
		(start 110.418626 -285.93161)
		(end 110.34903 -285.89097)
		(width 0.1143)
		(layer "In15.Cu")
		(net "P5E_CPU1_P0_RX_DN<14>")
	)
	(segment
		(start 110.388146 -282.673806)
		(end 110.34903 -282.650946)
		(width 0.1143)
		(layer "In15.Cu")
		(net "P5E_CPU1_P0_RX_DN<14>")
	)
	(segment
		(start 110.34903 -275.241766)
		(end 110.419642 -275.200364)
		(width 0.1143)
		(layer "In15.Cu")
		(net "P5E_CPU1_P0_RX_DN<14>")
	)
	(segment
		(start 115.629182 -366.730534)
		(end 116.055902 -366.730534)
		(width 0.14224)
		(layer "In15.Cu")
		(net "P5E_CPU1_P0_RX_DN<14>")
	)
	(segment
		(start 110.34903 -288.201608)
		(end 110.388146 -288.178748)
		(width 0.1143)
		(layer "In15.Cu")
		(net "P5E_CPU1_P0_RX_DN<14>")
	)
	(segment
		(start 110.420912 -281.072844)
		(end 110.388146 -281.053794)
		(width 0.1143)
		(layer "In15.Cu")
		(net "P5E_CPU1_P0_RX_DN<14>")
	)
	(segment
		(start 110.34903 -280.101802)
		(end 110.366556 -280.091642)
		(width 0.1143)
		(layer "In15.Cu")
		(net "P5E_CPU1_P0_RX_DN<14>")
	)
	(segment
		(start 117.467126 -366.867694)
		(end 117.604286 -366.730534)
		(width 0.14224)
		(layer "In15.Cu")
		(net "P5E_CPU1_P0_RX_DN<14>")
	)
	(segment
		(start 133.746748 -340.818216)
		(end 122.054366 -329.125834)
		(width 0.14224)
		(layer "In15.Cu")
		(net "P5E_CPU1_P0_RX_DN<14>")
	)
	(segment
		(start 116.055902 -366.730534)
		(end 116.193062 -366.867694)
		(width 0.14224)
		(layer "In15.Cu")
		(net "P5E_CPU1_P0_RX_DN<14>")
	)
	(segment
		(start 110.367064 -279.42159)
		(end 110.366556 -279.421082)
		(width 0.1143)
		(layer "In15.Cu")
		(net "P5E_CPU1_P0_RX_DN<14>")
	)
	(segment
		(start 114.501422 -366.730534)
		(end 114.928142 -366.730534)
		(width 0.14224)
		(layer "In15.Cu")
		(net "P5E_CPU1_P0_RX_DN<14>")
	)
	(segment
		(start 110.366556 -276.851618)
		(end 110.367064 -276.85111)
		(width 0.1143)
		(layer "In15.Cu")
		(net "P5E_CPU1_P0_RX_DN<14>")
	)
	(segment
		(start 110.367064 -280.091134)
		(end 110.38205 -280.082498)
		(width 0.1143)
		(layer "In15.Cu")
		(net "P5E_CPU1_P0_RX_DN<14>")
	)
	(segment
		(start 114.364262 -366.867694)
		(end 114.501422 -366.730534)
		(width 0.14224)
		(layer "In15.Cu")
		(net "P5E_CPU1_P0_RX_DN<14>")
	)
	(segment
		(start 166.01567 -355.877622)
		(end 155.034488 -355.877622)
		(width 0.14224)
		(layer "In15.Cu")
		(net "P5E_CPU1_P0_RX_DN<14>")
	)
	(segment
		(start 110.388146 -291.418772)
		(end 110.418626 -291.400992)
		(width 0.1143)
		(layer "In15.Cu")
		(net "P5E_CPU1_P0_RX_DN<14>")
	)
	(segment
		(start 110.640876 -366.867694)
		(end 114.364262 -366.867694)
		(width 0.14224)
		(layer "In15.Cu")
		(net "P5E_CPU1_P0_RX_DN<14>")
	)
	(segment
		(start 110.366556 -276.181058)
		(end 110.350554 -276.171914)
		(width 0.1143)
		(layer "In15.Cu")
		(net "P5E_CPU1_P0_RX_DN<14>")
	)
	(segment
		(start 74.829924 -369.203224)
		(end 76.433426 -367.599722)
		(width 0.14224)
		(layer "In15.Cu")
		(net "P5E_CPU1_P0_RX_DN<14>")
	)
	(segment
		(start 110.388146 -286.558736)
		(end 110.420658 -286.53994)
		(width 0.1143)
		(layer "In15.Cu")
		(net "P5E_CPU1_P0_RX_DN<14>")
	)
	(segment
		(start 115.492022 -366.867694)
		(end 115.629182 -366.730534)
		(width 0.14224)
		(layer "In15.Cu")
		(net "P5E_CPU1_P0_RX_DN<14>")
	)
	(segment
		(start 110.575852 -273.276314)
		(end 110.575598 -273.276314)
		(width 0.1143)
		(layer "In15.Cu")
		(net "P5E_CPU1_P0_RX_DN<14>")
	)
	(segment
		(start 110.38967 -278.463756)
		(end 110.389924 -278.463756)
		(width 0.1143)
		(layer "In15.Cu")
		(net "P5E_CPU1_P0_RX_DN<14>")
	)
	(segment
		(start 109.088936 -270.846296)
		(end 108.790994 -270.846296)
		(width 0.1143)
		(layer "In15.Cu")
		(net "P5E_CPU1_P0_RX_DN<14>")
	)
	(segment
		(start 110.386876 -276.839426)
		(end 110.388146 -276.838664)
		(width 0.1143)
		(layer "In15.Cu")
		(net "P5E_CPU1_P0_RX_DN<14>")
	)
	(segment
		(start 110.420658 -286.53994)
		(end 110.421166 -286.539432)
		(width 0.1143)
		(layer "In15.Cu")
		(net "P5E_CPU1_P0_RX_DN<14>")
	)
	(segment
		(start 118.168166 -366.867694)
		(end 168.39565 -366.867694)
		(width 0.14224)
		(layer "In15.Cu")
		(net "P5E_CPU1_P0_RX_DN<14>")
	)
	(segment
		(start 169.066464 -358.928416)
		(end 166.01567 -355.877622)
		(width 0.14224)
		(layer "In15.Cu")
		(net "P5E_CPU1_P0_RX_DN<14>")
	)
	(segment
		(start 110.418626 -287.551622)
		(end 110.35157 -287.512506)
		(width 0.1143)
		(layer "In15.Cu")
		(net "P5E_CPU1_P0_RX_DN<14>")
	)
	(segment
		(start 110.059978 -295.813734)
		(end 110.105698 -295.768014)
		(width 0.1143)
		(layer "In15.Cu")
		(net "P5E_CPU1_P0_RX_DN<14>")
	)
	(segment
		(start 110.387892 -293.039038)
		(end 110.388146 -293.038784)
		(width 0.1143)
		(layer "In15.Cu")
		(net "P5E_CPU1_P0_RX_DN<14>")
	)
	(segment
		(start 110.34903 -284.961838)
		(end 110.419642 -284.92069)
		(width 0.1143)
		(layer "In15.Cu")
		(net "P5E_CPU1_P0_RX_DN<14>")
	)
	(segment
		(start 110.38205 -276.842474)
		(end 110.383574 -276.841458)
		(width 0.1143)
		(layer "In15.Cu")
		(net "P5E_CPU1_P0_RX_DN<14>")
	)
	(segment
		(start 110.388146 -284.293818)
		(end 110.34903 -284.270958)
		(width 0.1143)
		(layer "In15.Cu")
		(net "P5E_CPU1_P0_RX_DN<14>")
	)
	(segment
		(start 110.105698 -295.768014)
		(end 110.105698 -295.146222)
		(width 0.1143)
		(layer "In15.Cu")
		(net "P5E_CPU1_P0_RX_DN<14>")
	)
	(segment
		(start 110.34903 -276.861778)
		(end 110.366556 -276.851618)
		(width 0.1143)
		(layer "In15.Cu")
		(net "P5E_CPU1_P0_RX_DN<14>")
	)
	(segment
		(start 65.136014 -381.84455)
		(end 69.61124 -375.65584)
		(width 0.14224)
		(layer "In15.Cu")
		(net "P5E_CPU1_P0_RX_DN<14>")
	)
	(segment
		(start 110.3884 -276.194012)
		(end 110.367064 -276.181566)
		(width 0.1143)
		(layer "In15.Cu")
		(net "P5E_CPU1_P0_RX_DN<14>")
	)
	(segment
		(start 110.34903 -273.621754)
		(end 110.420912 -273.579844)
		(width 0.1143)
		(layer "In15.Cu")
		(net "P5E_CPU1_P0_RX_DN<14>")
	)
	(segment
		(start 110.388146 -283.318966)
		(end 110.418626 -283.301186)
		(width 0.1143)
		(layer "In15.Cu")
		(net "P5E_CPU1_P0_RX_DN<14>")
	)
	(segment
		(start 110.418626 -284.311598)
		(end 110.388146 -284.293818)
		(width 0.1143)
		(layer "In15.Cu")
		(net "P5E_CPU1_P0_RX_DN<14>")
	)
	(segment
		(start 64.591438 -385.31038)
		(end 64.944498 -385.405376)
		(width 0.14224)
		(layer "In15.Cu")
		(net "P5E_CPU1_P0_RX_DN<14>")
	)
	(segment
		(start 110.575598 -286.236918)
		(end 110.575598 -286.23641)
		(width 0.1143)
		(layer "In15.Cu")
		(net "P5E_CPU1_P0_RX_DN<14>")
	)
	(segment
		(start 110.366556 -280.091642)
		(end 110.367064 -280.091134)
		(width 0.1143)
		(layer "In15.Cu")
		(net "P5E_CPU1_P0_RX_DN<14>")
	)
	(segment
		(start 110.575344 -274.910296)
		(end 110.575344 -274.891754)
		(width 0.1143)
		(layer "In15.Cu")
		(net "P5E_CPU1_P0_RX_DN<14>")
	)
	(segment
		(start 110.419896 -277.832312)
		(end 110.34903 -277.79091)
		(width 0.1143)
		(layer "In15.Cu")
		(net "P5E_CPU1_P0_RX_DN<14>")
	)
	(segment
		(start 110.34903 -283.341826)
		(end 110.349538 -283.341572)
		(width 0.1143)
		(layer "In15.Cu")
		(net "P5E_CPU1_P0_RX_DN<14>")
	)
	(segment
		(start 110.38459 -294.660828)
		(end 110.455964 -294.615362)
		(width 0.1143)
		(layer "In15.Cu")
		(net "P5E_CPU1_P0_RX_DN<14>")
	)
	(segment
		(start 110.418626 -289.17138)
		(end 110.388146 -289.1536)
		(width 0.1143)
		(layer "In15.Cu")
		(net "P5E_CPU1_P0_RX_DN<14>")
	)
	(segment
		(start 110.383574 -280.081482)
		(end 110.386114 -280.079958)
		(width 0.1143)
		(layer "In15.Cu")
		(net "P5E_CPU1_P0_RX_DN<14>")
	)
	(segment
		(start 77.080364 -367.37925)
		(end 108.820966 -367.37925)
		(width 0.14224)
		(layer "In15.Cu")
		(net "P5E_CPU1_P0_RX_DN<14>")
	)
	(segment
		(start 110.418626 -272.971514)
		(end 110.34903 -272.930874)
		(width 0.1143)
		(layer "In15.Cu")
		(net "P5E_CPU1_P0_RX_DN<14>")
	)
	(segment
		(start 110.367064 -276.181566)
		(end 110.366556 -276.181058)
		(width 0.1143)
		(layer "In15.Cu")
		(net "P5E_CPU1_P0_RX_DN<14>")
	)
	(segment
		(start 110.386876 -280.07945)
		(end 110.388146 -280.078688)
		(width 0.1143)
		(layer "In15.Cu")
		(net "P5E_CPU1_P0_RX_DN<14>")
	)
	(segment
		(start 110.349538 -283.341572)
		(end 110.388146 -283.318966)
		(width 0.1143)
		(layer "In15.Cu")
		(net "P5E_CPU1_P0_RX_DN<14>")
	)
	(segment
		(start 109.949742 -272.162016)
		(end 109.880908 -272.122138)
		(width 0.1143)
		(layer "In15.Cu")
		(net "P5E_CPU1_P0_RX_DN<14>")
	)
	(segment
		(start 109.17174 -270.9291)
		(end 109.088936 -270.846296)
		(width 0.1143)
		(layer "In15.Cu")
		(net "P5E_CPU1_P0_RX_DN<14>")
	)
	(segment
		(start 110.418626 -282.691586)
		(end 110.388146 -282.673806)
		(width 0.1143)
		(layer "In15.Cu")
		(net "P5E_CPU1_P0_RX_DN<14>")
	)
	(segment
		(start 168.616884 -366.776)
		(end 169.15638 -366.236504)
		(width 0.14224)
		(layer "In15.Cu")
		(net "P5E_CPU1_P0_RX_DN<14>")
	)
	(segment
		(start 110.388146 -290.773612)
		(end 110.34903 -290.750752)
		(width 0.1143)
		(layer "In15.Cu")
		(net "P5E_CPU1_P0_RX_DN<14>")
	)
	(segment
		(start 110.419896 -294.032178)
		(end 110.388146 -294.013636)
		(width 0.1143)
		(layer "In15.Cu")
		(net "P5E_CPU1_P0_RX_DN<14>")
	)
	(segment
		(start 151.23795 -352.707448)
		(end 135.069326 -341.903812)
		(width 0.14224)
		(layer "In15.Cu")
		(net "P5E_CPU1_P0_RX_DN<14>")
	)
	(segment
		(start 110.059978 -300.174914)
		(end 110.059978 -295.842182)
		(width 0.14224)
		(layer "In15.Cu")
		(net "P5E_CPU1_P0_RX_DN<14>")
	)
	(segment
		(start 110.385352 -278.466296)
		(end 110.38967 -278.463756)
		(width 0.1143)
		(layer "In15.Cu")
		(net "P5E_CPU1_P0_RX_DN<14>")
	)
	(segment
		(start 117.604286 -366.730534)
		(end 118.031006 -366.730534)
		(width 0.14224)
		(layer "In15.Cu")
		(net "P5E_CPU1_P0_RX_DN<14>")
	)
	(segment
		(start 64.74968 -384.84683)
		(end 64.754506 -384.234944)
		(width 0.14224)
		(layer "In15.Cu")
		(net "P5E_CPU1_P0_RX_DN<14>")
	)
	(segment
		(start 110.45317 -294.055292)
		(end 110.419896 -294.032178)
		(width 0.1143)
		(layer "In15.Cu")
		(net "P5E_CPU1_P0_RX_DN<14>")
	)
	(segment
		(start 110.575598 -273.276314)
		(end 110.575598 -273.273774)
		(width 0.1143)
		(layer "In15.Cu")
		(net "P5E_CPU1_P0_RX_DN<14>")
	)
	(segment
		(start 110.34903 -289.82162)
		(end 110.388146 -289.79876)
		(width 0.1143)
		(layer "In15.Cu")
		(net "P5E_CPU1_P0_RX_DN<14>")
	)
	(segment
		(start 110.420658 -272.973038)
		(end 110.418626 -272.971514)
		(width 0.1143)
		(layer "In15.Cu")
		(net "P5E_CPU1_P0_RX_DN<14>")
	)
	(segment
		(start 65.066672 -385.163822)
		(end 64.74968 -384.84683)
		(width 0.14224)
		(layer "In15.Cu")
		(net "P5E_CPU1_P0_RX_DN<14>")
	)
	(segment
		(start 121.802144 -328.748644)
		(end 110.147862 -300.616874)
		(width 0.14224)
		(layer "In15.Cu")
		(net "P5E_CPU1_P0_RX_DN<14>")
	)
	(segment
		(start 110.38205 -280.082498)
		(end 110.383574 -280.081482)
		(width 0.1143)
		(layer "In15.Cu")
		(net "P5E_CPU1_P0_RX_DN<14>")
	)
	(segment
		(start 110.367064 -276.85111)
		(end 110.38205 -276.842474)
		(width 0.1143)
		(layer "In15.Cu")
		(net "P5E_CPU1_P0_RX_DN<14>")
	)
	(segment
		(start 110.3884 -279.434036)
		(end 110.367064 -279.42159)
		(width 0.1143)
		(layer "In15.Cu")
		(net "P5E_CPU1_P0_RX_DN<14>")
	)
	(segment
		(start 110.34903 -281.721814)
		(end 110.420912 -281.679904)
		(width 0.1143)
		(layer "In15.Cu")
		(net "P5E_CPU1_P0_RX_DN<14>")
	)
	(segment
		(start 153.99512 -355.447092)
		(end 151.33574 -352.787712)
		(width 0.14224)
		(layer "In15.Cu")
		(net "P5E_CPU1_P0_RX_DN<14>")
	)
	(segment
		(start 110.386114 -280.079958)
		(end 110.386876 -280.07945)
		(width 0.1143)
		(layer "In15.Cu")
		(net "P5E_CPU1_P0_RX_DN<14>")
	)
	(segment
		(start 110.059978 -295.842182)
		(end 110.059978 -295.813734)
		(width 0.1143)
		(layer "In15.Cu")
		(net "P5E_CPU1_P0_RX_DN<14>")
	)
	(segment
		(start 110.34903 -286.581596)
		(end 110.388146 -286.558736)
		(width 0.1143)
		(layer "In15.Cu")
		(net "P5E_CPU1_P0_RX_DN<14>")
	)
	(segment
		(start 110.419388 -293.020496)
		(end 110.42015 -293.019988)
		(width 0.1143)
		(layer "In15.Cu")
		(net "P5E_CPU1_P0_RX_DN<14>")
	)
	(segment
		(start 110.350554 -294.68064)
		(end 110.38459 -294.660828)
		(width 0.1143)
		(layer "In15.Cu")
		(net "P5E_CPU1_P0_RX_DN<14>")
	)
	(segment
		(start 110.575598 -284.6197)
		(end 110.575598 -284.616398)
		(width 0.1143)
		(layer "In15.Cu")
		(net "P5E_CPU1_P0_RX_DN<14>")
	)
	(segment
		(start 69.61124 -375.65584)
		(end 74.829924 -369.203224)
		(width 0.14224)
		(layer "In15.Cu")
		(net "P5E_CPU1_P0_RX_DN<14>")
	)
	(segment
		(start 64.945006 -385.404868)
		(end 65.066672 -385.334764)
		(width 0.14224)
		(layer "In15.Cu")
		(net "P5E_CPU1_P0_RX_DN<14>")
	)
	(segment
		(start 110.388146 -293.038784)
		(end 110.419388 -293.020496)
		(width 0.1143)
		(layer "In15.Cu")
		(net "P5E_CPU1_P0_RX_DN<14>")
	)
	(segment
		(start 110.388146 -288.178748)
		(end 110.41253 -288.164524)
		(width 0.1143)
		(layer "In15.Cu")
		(net "P5E_CPU1_P0_RX_DN<14>")
	)
	(segment
		(start 110.383574 -276.841458)
		(end 110.386114 -276.839934)
		(width 0.1143)
		(layer "In15.Cu")
		(net "P5E_CPU1_P0_RX_DN<14>")
	)
	(segment
		(start 65.066672 -385.334764)
		(end 65.066672 -385.163822)
		(width 0.14224)
		(layer "In15.Cu")
		(net "P5E_CPU1_P0_RX_DN<14>")
	)
	(segment
		(start 110.366556 -279.421082)
		(end 110.350554 -279.411938)
		(width 0.1143)
		(layer "In15.Cu")
		(net "P5E_CPU1_P0_RX_DN<14>")
	)
	(segment
		(start 110.386114 -276.839934)
		(end 110.386876 -276.839426)
		(width 0.1143)
		(layer "In15.Cu")
		(net "P5E_CPU1_P0_RX_DN<14>")
	)
	(segment
		(start 114.928142 -366.730534)
		(end 115.065302 -366.867694)
		(width 0.14224)
		(layer "In15.Cu")
		(net "P5E_CPU1_P0_RX_DN<14>")
	)
	(segment
		(start 110.418626 -290.791392)
		(end 110.388146 -290.773612)
		(width 0.1143)
		(layer "In15.Cu")
		(net "P5E_CPU1_P0_RX_DN<14>")
	)
	(segment
		(start 110.388146 -289.79876)
		(end 110.418626 -289.78098)
		(width 0.1143)
		(layer "In15.Cu")
		(net "P5E_CPU1_P0_RX_DN<14>")
	)
	(segment
		(start 64.944498 -385.405376)
		(end 64.945006 -385.404868)
		(width 0.14224)
		(layer "In15.Cu")
		(net "P5E_CPU1_P0_RX_DN<14>")
	)
	(segment
		(start 110.386622 -292.392608)
		(end 110.34903 -292.370764)
		(width 0.1143)
		(layer "In15.Cu")
		(net "P5E_CPU1_P0_RX_DN<14>")
	)
	(segment
		(start 110.388146 -289.1536)
		(end 110.34903 -289.13074)
		(width 0.1143)
		(layer "In15.Cu")
		(net "P5E_CPU1_P0_RX_DN<14>")
	)
	(segment
		(start 110.575344 -292.730174)
		(end 110.575344 -292.702996)
		(width 0.1143)
		(layer "In15.Cu")
		(net "P5E_CPU1_P0_RX_DN<14>")
	)
	(segment
		(start 169.273474 -365.953802)
		(end 169.273474 -359.428288)
		(width 0.14224)
		(layer "In15.Cu")
		(net "P5E_CPU1_P0_RX_DN<14>")
	)
	(segment
		(start 109.479842 -271.35201)
		(end 109.408976 -271.310862)
		(width 0.1143)
		(layer "In15.Cu")
		(net "P5E_CPU1_P0_RX_DN<14>")
	)
	(segment
		(start 110.427516 -292.4175)
		(end 110.386622 -292.392608)
		(width 0.1143)
		(layer "In15.Cu")
		(net "P5E_CPU1_P0_RX_DN<14>")
	)
	(segment
		(start 110.421166 -274.593304)
		(end 110.350554 -274.551902)
		(width 0.1143)
		(layer "In15.Cu")
		(net "P5E_CPU1_P0_RX_DN<14>")
	)
	(segment
		(start 64.754506 -384.234944)
		(end 65.058544 -383.93116)
		(width 0.14224)
		(layer "In15.Cu")
		(net "P5E_CPU1_P0_RX_DN<14>")
	)
	(segment
		(start 110.34903 -291.441632)
		(end 110.388146 -291.418772)
		(width 0.1143)
		(layer "In15.Cu")
		(net "P5E_CPU1_P0_RX_DN<14>")
	)
	(arc
		(start 110.388146 -276.838664)
		(mid 110.57306 -276.516448)
		(end 110.3884 -276.194012)
		(width 0.1143)
		(layer "In15.Cu")
		(net "P5E_CPU1_P0_RX_DN<14>")
	)
	(arc
		(start 110.34903 -292.370764)
		(mid 110.105703 -291.906198)
		(end 110.34903 -291.441632)
		(width 0.1143)
		(layer "In15.Cu")
		(net "P5E_CPU1_P0_RX_DN<14>")
	)
	(arc
		(start 169.273474 -359.428288)
		(mid 169.219681 -359.157762)
		(end 169.066464 -358.928416)
		(width 0.14224)
		(layer "In15.Cu")
		(net "P5E_CPU1_P0_RX_DN<14>")
	)
	(arc
		(start 110.34903 -276.170898)
		(mid 110.105703 -275.706332)
		(end 110.34903 -275.241766)
		(width 0.1143)
		(layer "In15.Cu")
		(net "P5E_CPU1_P0_RX_DN<14>")
	)
	(arc
		(start 110.575344 -292.702996)
		(mid 110.536261 -292.542205)
		(end 110.427516 -292.4175)
		(width 0.1143)
		(layer "In15.Cu")
		(net "P5E_CPU1_P0_RX_DN<14>")
	)
	(arc
		(start 110.420912 -273.579844)
		(mid 110.534841 -273.446697)
		(end 110.575852 -273.276314)
		(width 0.1143)
		(layer "In15.Cu")
		(net "P5E_CPU1_P0_RX_DN<14>")
	)
	(arc
		(start 109.880908 -272.122138)
		(mid 109.719694 -271.92928)
		(end 109.639354 -271.6911)
		(width 0.1143)
		(layer "In15.Cu")
		(net "P5E_CPU1_P0_RX_DN<14>")
	)
	(arc
		(start 109.17555 -270.95196)
		(mid 109.173527 -270.94055)
		(end 109.17174 -270.9291)
		(width 0.1143)
		(layer "In15.Cu")
		(net "P5E_CPU1_P0_RX_DN<14>")
	)
	(arc
		(start 110.34903 -285.89097)
		(mid 110.105703 -285.426404)
		(end 110.34903 -284.961838)
		(width 0.1143)
		(layer "In15.Cu")
		(net "P5E_CPU1_P0_RX_DN<14>")
	)
	(arc
		(start 110.575598 -286.23641)
		(mid 110.534049 -286.064988)
		(end 110.418626 -285.93161)
		(width 0.1143)
		(layer "In15.Cu")
		(net "P5E_CPU1_P0_RX_DN<14>")
	)
	(arc
		(start 110.34903 -274.550886)
		(mid 110.105703 -274.08632)
		(end 110.34903 -273.621754)
		(width 0.1143)
		(layer "In15.Cu")
		(net "P5E_CPU1_P0_RX_DN<14>")
	)
	(arc
		(start 110.350554 -279.411938)
		(mid 110.108041 -278.929555)
		(end 110.385352 -278.466296)
		(width 0.1143)
		(layer "In15.Cu")
		(net "P5E_CPU1_P0_RX_DN<14>")
	)
	(arc
		(start 110.389924 -278.463756)
		(mid 110.576167 -278.156204)
		(end 110.419896 -277.832312)
		(width 0.1143)
		(layer "In15.Cu")
		(net "P5E_CPU1_P0_RX_DN<14>")
	)
	(arc
		(start 110.418626 -289.78098)
		(mid 110.575603 -289.47618)
		(end 110.418626 -289.17138)
		(width 0.1143)
		(layer "In15.Cu")
		(net "P5E_CPU1_P0_RX_DN<14>")
	)
	(arc
		(start 169.15638 -366.236504)
		(mid 169.243046 -366.106799)
		(end 169.273474 -365.953802)
		(width 0.14224)
		(layer "In15.Cu")
		(net "P5E_CPU1_P0_RX_DN<14>")
	)
	(arc
		(start 110.350554 -276.171914)
		(mid 110.349792 -276.171407)
		(end 110.34903 -276.170898)
		(width 0.1143)
		(layer "In15.Cu")
		(net "P5E_CPU1_P0_RX_DN<14>")
	)
	(arc
		(start 110.419642 -284.92069)
		(mid 110.421807 -284.919047)
		(end 110.42396 -284.917388)
		(width 0.1143)
		(layer "In15.Cu")
		(net "P5E_CPU1_P0_RX_DN<14>")
	)
	(arc
		(start 110.34903 -289.13074)
		(mid 110.105703 -288.666174)
		(end 110.34903 -288.201608)
		(width 0.1143)
		(layer "In15.Cu")
		(net "P5E_CPU1_P0_RX_DN<14>")
	)
	(arc
		(start 151.33574 -352.787712)
		(mid 151.288813 -352.745183)
		(end 151.23795 -352.707448)
		(width 0.14224)
		(layer "In15.Cu")
		(net "P5E_CPU1_P0_RX_DN<14>")
	)
	(arc
		(start 110.42015 -293.019988)
		(mid 110.531285 -292.893032)
		(end 110.575344 -292.730174)
		(width 0.1143)
		(layer "In15.Cu")
		(net "P5E_CPU1_P0_RX_DN<14>")
	)
	(arc
		(start 110.34903 -272.930874)
		(mid 110.170217 -272.728524)
		(end 110.105698 -272.466308)
		(width 0.1143)
		(layer "In15.Cu")
		(net "P5E_CPU1_P0_RX_DN<14>")
	)
	(arc
		(start 110.41253 -288.164524)
		(mid 110.523078 -288.021961)
		(end 110.575344 -287.84931)
		(width 0.1143)
		(layer "In15.Cu")
		(net "P5E_CPU1_P0_RX_DN<14>")
	)
	(arc
		(start 110.35157 -287.512506)
		(mid 110.170918 -287.309761)
		(end 110.105698 -287.046162)
		(width 0.1143)
		(layer "In15.Cu")
		(net "P5E_CPU1_P0_RX_DN<14>")
	)
	(arc
		(start 110.105698 -295.146222)
		(mid 110.170213 -294.884003)
		(end 110.34903 -294.681656)
		(width 0.1143)
		(layer "In15.Cu")
		(net "P5E_CPU1_P0_RX_DN<14>")
	)
	(arc
		(start 110.147862 -300.616874)
		(mid 110.082174 -300.400219)
		(end 110.059978 -300.174914)
		(width 0.14224)
		(layer "In15.Cu")
		(net "P5E_CPU1_P0_RX_DN<14>")
	)
	(arc
		(start 110.34903 -282.650946)
		(mid 110.105703 -282.18638)
		(end 110.34903 -281.721814)
		(width 0.1143)
		(layer "In15.Cu")
		(net "P5E_CPU1_P0_RX_DN<14>")
	)
	(arc
		(start 110.105698 -287.046162)
		(mid 110.170213 -286.783943)
		(end 110.34903 -286.581596)
		(width 0.1143)
		(layer "In15.Cu")
		(net "P5E_CPU1_P0_RX_DN<14>")
	)
	(arc
		(start 76.433426 -367.599722)
		(mid 76.625068 -367.46232)
		(end 76.850748 -367.393982)
		(width 0.14224)
		(layer "In15.Cu")
		(net "P5E_CPU1_P0_RX_DN<14>")
	)
	(arc
		(start 122.054366 -329.125834)
		(mid 121.909685 -328.949657)
		(end 121.802144 -328.748644)
		(width 0.14224)
		(layer "In15.Cu")
		(net "P5E_CPU1_P0_RX_DN<14>")
	)
	(arc
		(start 110.34903 -277.79091)
		(mid 110.105703 -277.326344)
		(end 110.34903 -276.861778)
		(width 0.1143)
		(layer "In15.Cu")
		(net "P5E_CPU1_P0_RX_DN<14>")
	)
	(arc
		(start 110.575344 -287.84931)
		(mid 110.574525 -287.830864)
		(end 110.572804 -287.81248)
		(width 0.1143)
		(layer "In15.Cu")
		(net "P5E_CPU1_P0_RX_DN<14>")
	)
	(arc
		(start 110.575598 -284.616398)
		(mid 110.534049 -284.444976)
		(end 110.418626 -284.311598)
		(width 0.1143)
		(layer "In15.Cu")
		(net "P5E_CPU1_P0_RX_DN<14>")
	)
	(arc
		(start 110.420912 -281.679904)
		(mid 110.572804 -281.376374)
		(end 110.420912 -281.072844)
		(width 0.1143)
		(layer "In15.Cu")
		(net "P5E_CPU1_P0_RX_DN<14>")
	)
	(arc
		(start 109.408976 -271.310862)
		(mid 109.256989 -271.154354)
		(end 109.17555 -270.95196)
		(width 0.1143)
		(layer "In15.Cu")
		(net "P5E_CPU1_P0_RX_DN<14>")
	)
	(arc
		(start 110.388146 -280.078688)
		(mid 110.57306 -279.756472)
		(end 110.3884 -279.434036)
		(width 0.1143)
		(layer "In15.Cu")
		(net "P5E_CPU1_P0_RX_DN<14>")
	)
	(arc
		(start 110.42396 -284.917388)
		(mid 110.529715 -284.7838)
		(end 110.575598 -284.6197)
		(width 0.1143)
		(layer "In15.Cu")
		(net "P5E_CPU1_P0_RX_DN<14>")
	)
	(arc
		(start 110.34903 -281.030934)
		(mid 110.105703 -280.566368)
		(end 110.34903 -280.101802)
		(width 0.1143)
		(layer "In15.Cu")
		(net "P5E_CPU1_P0_RX_DN<14>")
	)
	(arc
		(start 110.575344 -274.891754)
		(mid 110.534581 -274.72376)
		(end 110.421166 -274.593304)
		(width 0.1143)
		(layer "In15.Cu")
		(net "P5E_CPU1_P0_RX_DN<14>")
	)
	(arc
		(start 168.39565 -366.867694)
		(mid 168.515388 -366.843859)
		(end 168.616884 -366.776)
		(width 0.14224)
		(layer "In15.Cu")
		(net "P5E_CPU1_P0_RX_DN<14>")
	)
	(arc
		(start 109.635798 -271.64665)
		(mid 109.592405 -271.481018)
		(end 109.479842 -271.35201)
		(width 0.1143)
		(layer "In15.Cu")
		(net "P5E_CPU1_P0_RX_DN<14>")
	)
	(arc
		(start 110.34903 -294.681656)
		(mid 110.349792 -294.681147)
		(end 110.350554 -294.68064)
		(width 0.1143)
		(layer "In15.Cu")
		(net "P5E_CPU1_P0_RX_DN<14>")
	)
	(arc
		(start 110.105698 -272.466308)
		(mid 110.064443 -272.295337)
		(end 109.949742 -272.162016)
		(width 0.1143)
		(layer "In15.Cu")
		(net "P5E_CPU1_P0_RX_DN<14>")
	)
	(arc
		(start 110.421166 -286.539432)
		(mid 110.534721 -286.406733)
		(end 110.575598 -286.236918)
		(width 0.1143)
		(layer "In15.Cu")
		(net "P5E_CPU1_P0_RX_DN<14>")
	)
	(arc
		(start 109.639354 -271.6911)
		(mid 109.63701 -271.66892)
		(end 109.635798 -271.64665)
		(width 0.1143)
		(layer "In15.Cu")
		(net "P5E_CPU1_P0_RX_DN<14>")
	)
	(arc
		(start 110.572804 -287.81248)
		(mid 110.523313 -287.665731)
		(end 110.418626 -287.551622)
		(width 0.1143)
		(layer "In15.Cu")
		(net "P5E_CPU1_P0_RX_DN<14>")
	)
	(arc
		(start 110.419642 -275.200364)
		(mid 110.531073 -275.073359)
		(end 110.575344 -274.910296)
		(width 0.1143)
		(layer "In15.Cu")
		(net "P5E_CPU1_P0_RX_DN<14>")
	)
	(arc
		(start 110.387892 -294.013636)
		(mid 110.108348 -293.5264)
		(end 110.387892 -293.039038)
		(width 0.1143)
		(layer "In15.Cu")
		(net "P5E_CPU1_P0_RX_DN<14>")
	)
	(arc
		(start 108.820966 -367.37925)
		(mid 109.217158 -367.324552)
		(end 109.583728 -367.16462)
		(width 0.14224)
		(layer "In15.Cu")
		(net "P5E_CPU1_P0_RX_DN<14>")
	)
	(arc
		(start 65.058544 -382.084326)
		(mid 65.078396 -381.958339)
		(end 65.136014 -381.84455)
		(width 0.14224)
		(layer "In15.Cu")
		(net "P5E_CPU1_P0_RX_DN<14>")
	)
	(arc
		(start 109.583728 -367.16462)
		(mid 110.091826 -366.943266)
		(end 110.640876 -366.867694)
		(width 0.14224)
		(layer "In15.Cu")
		(net "P5E_CPU1_P0_RX_DN<14>")
	)
	(arc
		(start 110.418626 -283.301186)
		(mid 110.575603 -282.996386)
		(end 110.418626 -282.691586)
		(width 0.1143)
		(layer "In15.Cu")
		(net "P5E_CPU1_P0_RX_DN<14>")
	)
	(arc
		(start 110.455964 -294.615362)
		(mid 110.600468 -294.334561)
		(end 110.45317 -294.055292)
		(width 0.1143)
		(layer "In15.Cu")
		(net "P5E_CPU1_P0_RX_DN<14>")
	)
	(arc
		(start 110.34903 -290.750752)
		(mid 110.105703 -290.286186)
		(end 110.34903 -289.82162)
		(width 0.1143)
		(layer "In15.Cu")
		(net "P5E_CPU1_P0_RX_DN<14>")
	)
	(arc
		(start 110.575598 -273.273774)
		(mid 110.534566 -273.104649)
		(end 110.420658 -272.973038)
		(width 0.1143)
		(layer "In15.Cu")
		(net "P5E_CPU1_P0_RX_DN<14>")
	)
	(arc
		(start 110.34903 -284.270958)
		(mid 110.105703 -283.806392)
		(end 110.34903 -283.341826)
		(width 0.1143)
		(layer "In15.Cu")
		(net "P5E_CPU1_P0_RX_DN<14>")
	)
	(arc
		(start 155.034488 -355.877622)
		(mid 154.471982 -355.765733)
		(end 153.99512 -355.447092)
		(width 0.14224)
		(layer "In15.Cu")
		(net "P5E_CPU1_P0_RX_DN<14>")
	)
	(arc
		(start 110.350554 -274.551902)
		(mid 110.349792 -274.551395)
		(end 110.34903 -274.550886)
		(width 0.1143)
		(layer "In15.Cu")
		(net "P5E_CPU1_P0_RX_DN<14>")
	)
	(arc
		(start 110.418626 -291.400992)
		(mid 110.575603 -291.096192)
		(end 110.418626 -290.791392)
		(width 0.1143)
		(layer "In15.Cu")
		(net "P5E_CPU1_P0_RX_DN<14>")
	)
	(arc
		(start 135.069326 -341.903812)
		(mid 134.381368 -341.393505)
		(end 133.746748 -340.818216)
		(width 0.14224)
		(layer "In15.Cu")
		(net "P5E_CPU1_P0_RX_DN<14>")
	)
	(arc
		(start 76.850748 -367.393982)
		(mid 76.965318 -367.382909)
		(end 77.080364 -367.37925)
		(width 0.14224)
		(layer "In15.Cu")
		(net "P5E_CPU1_P0_RX_DN<14>")
	)
	(segment
		(start 62.870588 -385.31038)
		(end 63.391288 -385.31038)
		(width 0.127)
		(layer "F.Cu")
		(net "P5E_CPU1_P0_RX_DN<13>")
	)
	(segment
		(start 109.257846 -273.820382)
		(end 108.790994 -274.08632)
		(width 0.12954)
		(layer "F.Cu")
		(net "P5E_CPU1_P0_RX_DN<13>")
	)
	(segment
		(start 109.448092 -283.318966)
		(end 109.479842 -283.300678)
		(width 0.1143)
		(layer "In15.Cu")
		(net "P5E_CPU1_P0_RX_DN<13>")
	)
	(segment
		(start 109.440218 -292.389306)
		(end 109.439456 -292.388798)
		(width 0.1143)
		(layer "In15.Cu")
		(net "P5E_CPU1_P0_RX_DN<13>")
	)
	(segment
		(start 165.50386 -365.745776)
		(end 165.93058 -365.745776)
		(width 0.14224)
		(layer "In15.Cu")
		(net "P5E_CPU1_P0_RX_DN<13>")
	)
	(segment
		(start 121.001536 -329.307952)
		(end 109.235494 -300.9011)
		(width 0.14224)
		(layer "In15.Cu")
		(net "P5E_CPU1_P0_RX_DN<13>")
	)
	(segment
		(start 109.455458 -293.034466)
		(end 109.457998 -293.032942)
		(width 0.1143)
		(layer "In15.Cu")
		(net "P5E_CPU1_P0_RX_DN<13>")
	)
	(segment
		(start 109.4359 -294.006778)
		(end 109.433106 -294.005)
		(width 0.1143)
		(layer "In15.Cu")
		(net "P5E_CPU1_P0_RX_DN<13>")
	)
	(segment
		(start 109.459522 -293.03218)
		(end 109.479842 -293.020496)
		(width 0.1143)
		(layer "In15.Cu")
		(net "P5E_CPU1_P0_RX_DN<13>")
	)
	(segment
		(start 109.416596 -289.135312)
		(end 109.415834 -289.134804)
		(width 0.1143)
		(layer "In15.Cu")
		(net "P5E_CPU1_P0_RX_DN<13>")
	)
	(segment
		(start 63.866776 -385.163822)
		(end 63.549784 -384.84683)
		(width 0.14224)
		(layer "In15.Cu")
		(net "P5E_CPU1_P0_RX_DN<13>")
	)
	(segment
		(start 109.408976 -275.241766)
		(end 109.468666 -275.206968)
		(width 0.1143)
		(layer "In15.Cu")
		(net "P5E_CPU1_P0_RX_DN<13>")
	)
	(segment
		(start 109.468666 -275.206968)
		(end 109.469428 -275.20646)
		(width 0.1143)
		(layer "In15.Cu")
		(net "P5E_CPU1_P0_RX_DN<13>")
	)
	(segment
		(start 109.447838 -281.05354)
		(end 109.438694 -281.04846)
		(width 0.1143)
		(layer "In15.Cu")
		(net "P5E_CPU1_P0_RX_DN<13>")
	)
	(segment
		(start 165.93058 -365.745776)
		(end 166.06774 -365.608616)
		(width 0.14224)
		(layer "In15.Cu")
		(net "P5E_CPU1_P0_RX_DN<13>")
	)
	(segment
		(start 109.415834 -289.134804)
		(end 109.408976 -289.13074)
		(width 0.1143)
		(layer "In15.Cu")
		(net "P5E_CPU1_P0_RX_DN<13>")
	)
	(segment
		(start 74.079354 -368.505232)
		(end 75.98029 -366.604296)
		(width 0.14224)
		(layer "In15.Cu")
		(net "P5E_CPU1_P0_RX_DN<13>")
	)
	(segment
		(start 63.74511 -385.404868)
		(end 63.866776 -385.334764)
		(width 0.14224)
		(layer "In15.Cu")
		(net "P5E_CPU1_P0_RX_DN<13>")
	)
	(segment
		(start 109.448092 -290.773612)
		(end 109.447076 -290.773104)
		(width 0.1143)
		(layer "In15.Cu")
		(net "P5E_CPU1_P0_RX_DN<13>")
	)
	(segment
		(start 109.479842 -277.832058)
		(end 109.448092 -277.81377)
		(width 0.1143)
		(layer "In15.Cu")
		(net "P5E_CPU1_P0_RX_DN<13>")
	)
	(segment
		(start 109.479842 -289.780472)
		(end 109.499654 -289.766248)
		(width 0.1143)
		(layer "In15.Cu")
		(net "P5E_CPU1_P0_RX_DN<13>")
	)
	(segment
		(start 109.445552 -291.420296)
		(end 109.447076 -291.41928)
		(width 0.1143)
		(layer "In15.Cu")
		(net "P5E_CPU1_P0_RX_DN<13>")
	)
	(segment
		(start 109.408976 -278.48179)
		(end 109.448092 -278.45893)
		(width 0.1143)
		(layer "In15.Cu")
		(net "P5E_CPU1_P0_RX_DN<13>")
	)
	(segment
		(start 166.49446 -365.608616)
		(end 166.63162 -365.745776)
		(width 0.14224)
		(layer "In15.Cu")
		(net "P5E_CPU1_P0_RX_DN<13>")
	)
	(segment
		(start 109.448092 -276.193758)
		(end 109.408976 -276.170898)
		(width 0.1143)
		(layer "In15.Cu")
		(net "P5E_CPU1_P0_RX_DN<13>")
	)
	(segment
		(start 109.635798 -287.856676)
		(end 109.635798 -287.85439)
		(width 0.1143)
		(layer "In15.Cu")
		(net "P5E_CPU1_P0_RX_DN<13>")
	)
	(segment
		(start 164.80282 -365.745776)
		(end 164.93998 -365.608616)
		(width 0.14224)
		(layer "In15.Cu")
		(net "P5E_CPU1_P0_RX_DN<13>")
	)
	(segment
		(start 109.534198 -287.606486)
		(end 109.408214 -287.516824)
		(width 0.1143)
		(layer "In15.Cu")
		(net "P5E_CPU1_P0_RX_DN<13>")
	)
	(segment
		(start 109.119924 -300.320202)
		(end 109.119924 -295.91127)
		(width 0.14224)
		(layer "In15.Cu")
		(net "P5E_CPU1_P0_RX_DN<13>")
	)
	(segment
		(start 63.549784 -384.84683)
		(end 63.55461 -384.234944)
		(width 0.14224)
		(layer "In15.Cu")
		(net "P5E_CPU1_P0_RX_DN<13>")
	)
	(segment
		(start 109.635544 -287.856422)
		(end 109.635798 -287.856676)
		(width 0.1143)
		(layer "In15.Cu")
		(net "P5E_CPU1_P0_RX_DN<13>")
	)
	(segment
		(start 109.448092 -284.293818)
		(end 109.408976 -284.270958)
		(width 0.1143)
		(layer "In15.Cu")
		(net "P5E_CPU1_P0_RX_DN<13>")
	)
	(segment
		(start 109.451394 -293.036752)
		(end 109.454696 -293.034974)
		(width 0.1143)
		(layer "In15.Cu")
		(net "P5E_CPU1_P0_RX_DN<13>")
	)
	(segment
		(start 109.441488 -292.390068)
		(end 109.440218 -292.389306)
		(width 0.1143)
		(layer "In15.Cu")
		(net "P5E_CPU1_P0_RX_DN<13>")
	)
	(segment
		(start 166.63162 -365.745776)
		(end 168.071292 -365.745776)
		(width 0.14224)
		(layer "In15.Cu")
		(net "P5E_CPU1_P0_RX_DN<13>")
	)
	(segment
		(start 109.478826 -286.54121)
		(end 109.48162 -286.539178)
		(width 0.1143)
		(layer "In15.Cu")
		(net "P5E_CPU1_P0_RX_DN<13>")
	)
	(segment
		(start 109.447076 -290.773104)
		(end 109.408976 -290.750752)
		(width 0.1143)
		(layer "In15.Cu")
		(net "P5E_CPU1_P0_RX_DN<13>")
	)
	(segment
		(start 109.469428 -294.64635)
		(end 109.469936 -294.64635)
		(width 0.1143)
		(layer "In15.Cu")
		(net "P5E_CPU1_P0_RX_DN<13>")
	)
	(segment
		(start 109.469428 -294.026082)
		(end 109.468666 -294.025574)
		(width 0.1143)
		(layer "In15.Cu")
		(net "P5E_CPU1_P0_RX_DN<13>")
	)
	(segment
		(start 166.06774 -365.608616)
		(end 166.49446 -365.608616)
		(width 0.14224)
		(layer "In15.Cu")
		(net "P5E_CPU1_P0_RX_DN<13>")
	)
	(segment
		(start 109.407706 -293.062406)
		(end 109.432598 -293.04742)
		(width 0.1143)
		(layer "In15.Cu")
		(net "P5E_CPU1_P0_RX_DN<13>")
	)
	(segment
		(start 164.93998 -365.608616)
		(end 165.3667 -365.608616)
		(width 0.14224)
		(layer "In15.Cu")
		(net "P5E_CPU1_P0_RX_DN<13>")
	)
	(segment
		(start 109.408976 -276.861778)
		(end 109.448092 -276.838918)
		(width 0.1143)
		(layer "In15.Cu")
		(net "P5E_CPU1_P0_RX_DN<13>")
	)
	(segment
		(start 150.75027 -353.529646)
		(end 134.360158 -342.578182)
		(width 0.14224)
		(layer "In15.Cu")
		(net "P5E_CPU1_P0_RX_DN<13>")
	)
	(segment
		(start 109.119924 -295.91127)
		(end 109.119924 -295.882822)
		(width 0.1143)
		(layer "In15.Cu")
		(net "P5E_CPU1_P0_RX_DN<13>")
	)
	(segment
		(start 63.744602 -385.405376)
		(end 63.74511 -385.404868)
		(width 0.14224)
		(layer "In15.Cu")
		(net "P5E_CPU1_P0_RX_DN<13>")
	)
	(segment
		(start 109.429804 -294.002968)
		(end 109.409992 -293.991538)
		(width 0.1143)
		(layer "In15.Cu")
		(net "P5E_CPU1_P0_RX_DN<13>")
	)
	(segment
		(start 63.55461 -384.234944)
		(end 63.858648 -383.93116)
		(width 0.14224)
		(layer "In15.Cu")
		(net "P5E_CPU1_P0_RX_DN<13>")
	)
	(segment
		(start 109.447076 -292.393116)
		(end 109.441488 -292.390068)
		(width 0.1143)
		(layer "In15.Cu")
		(net "P5E_CPU1_P0_RX_DN<13>")
	)
	(segment
		(start 109.43209 -294.004492)
		(end 109.429804 -294.002968)
		(width 0.1143)
		(layer "In15.Cu")
		(net "P5E_CPU1_P0_RX_DN<13>")
	)
	(segment
		(start 109.479842 -284.312106)
		(end 109.448092 -284.293818)
		(width 0.1143)
		(layer "In15.Cu")
		(net "P5E_CPU1_P0_RX_DN<13>")
	)
	(segment
		(start 165.3667 -365.608616)
		(end 165.50386 -365.745776)
		(width 0.14224)
		(layer "In15.Cu")
		(net "P5E_CPU1_P0_RX_DN<13>")
	)
	(segment
		(start 109.499654 -292.426136)
		(end 109.479842 -292.411912)
		(width 0.1143)
		(layer "In15.Cu")
		(net "P5E_CPU1_P0_RX_DN<13>")
	)
	(segment
		(start 109.4359 -281.046682)
		(end 109.433614 -281.045412)
		(width 0.1143)
		(layer "In15.Cu")
		(net "P5E_CPU1_P0_RX_DN<13>")
	)
	(segment
		(start 109.448092 -291.418772)
		(end 109.448854 -291.418264)
		(width 0.1143)
		(layer "In15.Cu")
		(net "P5E_CPU1_P0_RX_DN<13>")
	)
	(segment
		(start 109.499654 -289.186112)
		(end 109.479842 -289.171888)
		(width 0.1143)
		(layer "In15.Cu")
		(net "P5E_CPU1_P0_RX_DN<13>")
	)
	(segment
		(start 109.408976 -283.341826)
		(end 109.448092 -283.318966)
		(width 0.1143)
		(layer "In15.Cu")
		(net "P5E_CPU1_P0_RX_DN<13>")
	)
	(segment
		(start 109.088936 -274.08632)
		(end 108.790994 -274.08632)
		(width 0.1143)
		(layer "In15.Cu")
		(net "P5E_CPU1_P0_RX_DN<13>")
	)
	(segment
		(start 110.8456 -365.745776)
		(end 164.80282 -365.745776)
		(width 0.14224)
		(layer "In15.Cu")
		(net "P5E_CPU1_P0_RX_DN<13>")
	)
	(segment
		(start 109.469936 -274.586192)
		(end 109.469428 -274.586192)
		(width 0.1143)
		(layer "In15.Cu")
		(net "P5E_CPU1_P0_RX_DN<13>")
	)
	(segment
		(start 109.445552 -289.800284)
		(end 109.447076 -289.799268)
		(width 0.1143)
		(layer "In15.Cu")
		(net "P5E_CPU1_P0_RX_DN<13>")
	)
	(segment
		(start 109.438694 -281.04846)
		(end 109.4359 -281.046682)
		(width 0.1143)
		(layer "In15.Cu")
		(net "P5E_CPU1_P0_RX_DN<13>")
	)
	(segment
		(start 109.119924 -295.882822)
		(end 109.165644 -295.837102)
		(width 0.1143)
		(layer "In15.Cu")
		(net "P5E_CPU1_P0_RX_DN<13>")
	)
	(segment
		(start 109.408976 -281.721814)
		(end 109.4486 -281.6987)
		(width 0.1143)
		(layer "In15.Cu")
		(net "P5E_CPU1_P0_RX_DN<13>")
	)
	(segment
		(start 109.165644 -295.837102)
		(end 109.165644 -295.146222)
		(width 0.1143)
		(layer "In15.Cu")
		(net "P5E_CPU1_P0_RX_DN<13>")
	)
	(segment
		(start 109.439456 -292.388798)
		(end 109.43844 -292.38829)
		(width 0.1143)
		(layer "In15.Cu")
		(net "P5E_CPU1_P0_RX_DN<13>")
	)
	(segment
		(start 109.408976 -286.581596)
		(end 109.478826 -286.54121)
		(width 0.1143)
		(layer "In15.Cu")
		(net "P5E_CPU1_P0_RX_DN<13>")
	)
	(segment
		(start 68.890134 -374.950736)
		(end 74.079354 -368.505232)
		(width 0.14224)
		(layer "In15.Cu")
		(net "P5E_CPU1_P0_RX_DN<13>")
	)
	(segment
		(start 153.760424 -356.5398)
		(end 150.75027 -353.529646)
		(width 0.14224)
		(layer "In15.Cu")
		(net "P5E_CPU1_P0_RX_DN<13>")
	)
	(segment
		(start 109.447076 -291.41928)
		(end 109.448092 -291.418772)
		(width 0.1143)
		(layer "In15.Cu")
		(net "P5E_CPU1_P0_RX_DN<13>")
	)
	(segment
		(start 132.68706 -341.205058)
		(end 121.427748 -329.945746)
		(width 0.14224)
		(layer "In15.Cu")
		(net "P5E_CPU1_P0_RX_DN<13>")
	)
	(segment
		(start 109.469428 -280.066496)
		(end 109.469682 -280.066496)
		(width 0.1143)
		(layer "In15.Cu")
		(net "P5E_CPU1_P0_RX_DN<13>")
	)
	(segment
		(start 168.256966 -365.560102)
		(end 168.256966 -359.609136)
		(width 0.14224)
		(layer "In15.Cu")
		(net "P5E_CPU1_P0_RX_DN<13>")
	)
	(segment
		(start 109.448092 -282.673806)
		(end 109.408976 -282.650946)
		(width 0.1143)
		(layer "In15.Cu")
		(net "P5E_CPU1_P0_RX_DN<13>")
	)
	(segment
		(start 109.4486 -281.053794)
		(end 109.447838 -281.05354)
		(width 0.1143)
		(layer "In15.Cu")
		(net "P5E_CPU1_P0_RX_DN<13>")
	)
	(segment
		(start 109.408976 -284.961838)
		(end 109.448092 -284.938978)
		(width 0.1143)
		(layer "In15.Cu")
		(net "P5E_CPU1_P0_RX_DN<13>")
	)
	(segment
		(start 109.448092 -289.1536)
		(end 109.447076 -289.153092)
		(width 0.1143)
		(layer "In15.Cu")
		(net "P5E_CPU1_P0_RX_DN<13>")
	)
	(segment
		(start 109.448092 -289.79876)
		(end 109.448854 -289.798252)
		(width 0.1143)
		(layer "In15.Cu")
		(net "P5E_CPU1_P0_RX_DN<13>")
	)
	(segment
		(start 109.448854 -289.154108)
		(end 109.448092 -289.1536)
		(width 0.1143)
		(layer "In15.Cu")
		(net "P5E_CPU1_P0_RX_DN<13>")
	)
	(segment
		(start 109.469428 -279.446228)
		(end 109.409738 -279.41143)
		(width 0.1143)
		(layer "In15.Cu")
		(net "P5E_CPU1_P0_RX_DN<13>")
	)
	(segment
		(start 109.467904 -288.167318)
		(end 109.482128 -288.158682)
		(width 0.1143)
		(layer "In15.Cu")
		(net "P5E_CPU1_P0_RX_DN<13>")
	)
	(segment
		(start 109.408976 -291.441632)
		(end 109.445552 -291.420296)
		(width 0.1143)
		(layer "In15.Cu")
		(net "P5E_CPU1_P0_RX_DN<13>")
	)
	(segment
		(start 109.447076 -289.799268)
		(end 109.448092 -289.79876)
		(width 0.1143)
		(layer "In15.Cu")
		(net "P5E_CPU1_P0_RX_DN<13>")
	)
	(segment
		(start 109.443774 -289.15106)
		(end 109.416596 -289.135312)
		(width 0.1143)
		(layer "In15.Cu")
		(net "P5E_CPU1_P0_RX_DN<13>")
	)
	(segment
		(start 109.448092 -284.938978)
		(end 109.479842 -284.92069)
		(width 0.1143)
		(layer "In15.Cu")
		(net "P5E_CPU1_P0_RX_DN<13>")
	)
	(segment
		(start 63.858648 -383.93116)
		(end 63.858648 -382.19761)
		(width 0.14224)
		(layer "In15.Cu")
		(net "P5E_CPU1_P0_RX_DN<13>")
	)
	(segment
		(start 109.469936 -279.446228)
		(end 109.469428 -279.446228)
		(width 0.1143)
		(layer "In15.Cu")
		(net "P5E_CPU1_P0_RX_DN<13>")
	)
	(segment
		(start 109.479842 -290.7919)
		(end 109.448854 -290.77412)
		(width 0.1143)
		(layer "In15.Cu")
		(net "P5E_CPU1_P0_RX_DN<13>")
	)
	(segment
		(start 109.408976 -289.82162)
		(end 109.445552 -289.800284)
		(width 0.1143)
		(layer "In15.Cu")
		(net "P5E_CPU1_P0_RX_DN<13>")
	)
	(segment
		(start 109.479842 -285.932118)
		(end 109.448092 -285.91383)
		(width 0.1143)
		(layer "In15.Cu")
		(net "P5E_CPU1_P0_RX_DN<13>")
	)
	(segment
		(start 109.448092 -292.393624)
		(end 109.447076 -292.393116)
		(width 0.1143)
		(layer "In15.Cu")
		(net "P5E_CPU1_P0_RX_DN<13>")
	)
	(segment
		(start 109.447076 -289.153092)
		(end 109.444536 -289.151568)
		(width 0.1143)
		(layer "In15.Cu")
		(net "P5E_CPU1_P0_RX_DN<13>")
	)
	(segment
		(start 109.479842 -276.212046)
		(end 109.448092 -276.193758)
		(width 0.1143)
		(layer "In15.Cu")
		(net "P5E_CPU1_P0_RX_DN<13>")
	)
	(segment
		(start 109.479842 -293.020496)
		(end 109.499654 -293.006272)
		(width 0.1143)
		(layer "In15.Cu")
		(net "P5E_CPU1_P0_RX_DN<13>")
	)
	(segment
		(start 109.448854 -292.394132)
		(end 109.448092 -292.393624)
		(width 0.1143)
		(layer "In15.Cu")
		(net "P5E_CPU1_P0_RX_DN<13>")
	)
	(segment
		(start 63.391288 -385.31038)
		(end 63.744602 -385.405376)
		(width 0.14224)
		(layer "In15.Cu")
		(net "P5E_CPU1_P0_RX_DN<13>")
	)
	(segment
		(start 109.479842 -289.171888)
		(end 109.448854 -289.154108)
		(width 0.1143)
		(layer "In15.Cu")
		(net "P5E_CPU1_P0_RX_DN<13>")
	)
	(segment
		(start 109.409738 -294.681148)
		(end 109.469428 -294.64635)
		(width 0.1143)
		(layer "In15.Cu")
		(net "P5E_CPU1_P0_RX_DN<13>")
	)
	(segment
		(start 63.9572 -381.889)
		(end 68.890134 -374.950736)
		(width 0.14224)
		(layer "In15.Cu")
		(net "P5E_CPU1_P0_RX_DN<13>")
	)
	(segment
		(start 109.434122 -280.08707)
		(end 109.468666 -280.067004)
		(width 0.1143)
		(layer "In15.Cu")
		(net "P5E_CPU1_P0_RX_DN<13>")
	)
	(segment
		(start 109.469428 -274.586192)
		(end 109.409738 -274.551394)
		(width 0.1143)
		(layer "In15.Cu")
		(net "P5E_CPU1_P0_RX_DN<13>")
	)
	(segment
		(start 109.433106 -294.005)
		(end 109.43209 -294.004492)
		(width 0.1143)
		(layer "In15.Cu")
		(net "P5E_CPU1_P0_RX_DN<13>")
	)
	(segment
		(start 109.448854 -293.038276)
		(end 109.451394 -293.036752)
		(width 0.1143)
		(layer "In15.Cu")
		(net "P5E_CPU1_P0_RX_DN<13>")
	)
	(segment
		(start 109.448092 -277.81377)
		(end 109.408976 -277.79091)
		(width 0.1143)
		(layer "In15.Cu")
		(net "P5E_CPU1_P0_RX_DN<13>")
	)
	(segment
		(start 109.448854 -290.77412)
		(end 109.448092 -290.773612)
		(width 0.1143)
		(layer "In15.Cu")
		(net "P5E_CPU1_P0_RX_DN<13>")
	)
	(segment
		(start 109.17174 -274.169124)
		(end 109.088936 -274.08632)
		(width 0.1143)
		(layer "In15.Cu")
		(net "P5E_CPU1_P0_RX_DN<13>")
	)
	(segment
		(start 109.454696 -293.034974)
		(end 109.455458 -293.034466)
		(width 0.1143)
		(layer "In15.Cu")
		(net "P5E_CPU1_P0_RX_DN<13>")
	)
	(segment
		(start 109.468666 -280.067004)
		(end 109.469428 -280.066496)
		(width 0.1143)
		(layer "In15.Cu")
		(net "P5E_CPU1_P0_RX_DN<13>")
	)
	(segment
		(start 109.469428 -275.20646)
		(end 109.469682 -275.20646)
		(width 0.1143)
		(layer "In15.Cu")
		(net "P5E_CPU1_P0_RX_DN<13>")
	)
	(segment
		(start 109.468666 -294.025574)
		(end 109.4359 -294.006778)
		(width 0.1143)
		(layer "In15.Cu")
		(net "P5E_CPU1_P0_RX_DN<13>")
	)
	(segment
		(start 109.448092 -293.038784)
		(end 109.448854 -293.038276)
		(width 0.1143)
		(layer "In15.Cu")
		(net "P5E_CPU1_P0_RX_DN<13>")
	)
	(segment
		(start 109.457998 -293.032942)
		(end 109.459522 -293.03218)
		(width 0.1143)
		(layer "In15.Cu")
		(net "P5E_CPU1_P0_RX_DN<13>")
	)
	(segment
		(start 109.444536 -289.151568)
		(end 109.443774 -289.15106)
		(width 0.1143)
		(layer "In15.Cu")
		(net "P5E_CPU1_P0_RX_DN<13>")
	)
	(segment
		(start 109.448854 -289.798252)
		(end 109.479842 -289.780472)
		(width 0.1143)
		(layer "In15.Cu")
		(net "P5E_CPU1_P0_RX_DN<13>")
	)
	(segment
		(start 109.479842 -282.692094)
		(end 109.448092 -282.673806)
		(width 0.1143)
		(layer "In15.Cu")
		(net "P5E_CPU1_P0_RX_DN<13>")
	)
	(segment
		(start 76.602336 -366.417098)
		(end 108.159804 -366.417098)
		(width 0.14224)
		(layer "In15.Cu")
		(net "P5E_CPU1_P0_RX_DN<13>")
	)
	(segment
		(start 168.162478 -359.381044)
		(end 165.940232 -357.158798)
		(width 0.14224)
		(layer "In15.Cu")
		(net "P5E_CPU1_P0_RX_DN<13>")
	)
	(segment
		(start 63.866776 -385.334764)
		(end 63.866776 -385.163822)
		(width 0.14224)
		(layer "In15.Cu")
		(net "P5E_CPU1_P0_RX_DN<13>")
	)
	(segment
		(start 109.436916 -292.387274)
		(end 109.408976 -292.370764)
		(width 0.1143)
		(layer "In15.Cu")
		(net "P5E_CPU1_P0_RX_DN<13>")
	)
	(segment
		(start 109.469682 -294.026082)
		(end 109.469428 -294.026082)
		(width 0.1143)
		(layer "In15.Cu")
		(net "P5E_CPU1_P0_RX_DN<13>")
	)
	(segment
		(start 109.479842 -292.411912)
		(end 109.448854 -292.394132)
		(width 0.1143)
		(layer "In15.Cu")
		(net "P5E_CPU1_P0_RX_DN<13>")
	)
	(segment
		(start 109.448854 -291.418264)
		(end 109.479842 -291.400484)
		(width 0.1143)
		(layer "In15.Cu")
		(net "P5E_CPU1_P0_RX_DN<13>")
	)
	(segment
		(start 109.408976 -288.201608)
		(end 109.428534 -288.190178)
		(width 0.1143)
		(layer "In15.Cu")
		(net "P5E_CPU1_P0_RX_DN<13>")
	)
	(segment
		(start 109.43844 -292.38829)
		(end 109.436916 -292.387274)
		(width 0.1143)
		(layer "In15.Cu")
		(net "P5E_CPU1_P0_RX_DN<13>")
	)
	(segment
		(start 109.448092 -278.45893)
		(end 109.479842 -278.440642)
		(width 0.1143)
		(layer "In15.Cu")
		(net "P5E_CPU1_P0_RX_DN<13>")
	)
	(segment
		(start 109.448092 -276.838918)
		(end 109.479842 -276.82063)
		(width 0.1143)
		(layer "In15.Cu")
		(net "P5E_CPU1_P0_RX_DN<13>")
	)
	(segment
		(start 109.432598 -293.04742)
		(end 109.448092 -293.038784)
		(width 0.1143)
		(layer "In15.Cu")
		(net "P5E_CPU1_P0_RX_DN<13>")
	)
	(segment
		(start 109.448092 -285.91383)
		(end 109.408976 -285.89097)
		(width 0.1143)
		(layer "In15.Cu")
		(net "P5E_CPU1_P0_RX_DN<13>")
	)
	(segment
		(start 165.763702 -357.085646)
		(end 155.078176 -357.085646)
		(width 0.14224)
		(layer "In15.Cu")
		(net "P5E_CPU1_P0_RX_DN<13>")
	)
	(segment
		(start 109.428534 -288.190178)
		(end 109.467904 -288.167318)
		(width 0.1143)
		(layer "In15.Cu")
		(net "P5E_CPU1_P0_RX_DN<13>")
	)
	(arc
		(start 109.479842 -284.92069)
		(mid 109.630227 -284.616398)
		(end 109.479842 -284.312106)
		(width 0.1143)
		(layer "In15.Cu")
		(net "P5E_CPU1_P0_RX_DN<13>")
	)
	(arc
		(start 109.48162 -286.539178)
		(mid 109.595027 -286.406289)
		(end 109.635798 -286.23641)
		(width 0.1143)
		(layer "In15.Cu")
		(net "P5E_CPU1_P0_RX_DN<13>")
	)
	(arc
		(start 109.408976 -285.89097)
		(mid 109.165649 -285.426404)
		(end 109.408976 -284.961838)
		(width 0.1143)
		(layer "In15.Cu")
		(net "P5E_CPU1_P0_RX_DN<13>")
	)
	(arc
		(start 121.427748 -329.945746)
		(mid 121.183253 -329.647828)
		(end 121.001536 -329.307952)
		(width 0.14224)
		(layer "In15.Cu")
		(net "P5E_CPU1_P0_RX_DN<13>")
	)
	(arc
		(start 109.4486 -281.6987)
		(mid 109.634018 -281.37631)
		(end 109.4486 -281.053794)
		(width 0.1143)
		(layer "In15.Cu")
		(net "P5E_CPU1_P0_RX_DN<13>")
	)
	(arc
		(start 109.408976 -294.681656)
		(mid 109.409357 -294.681402)
		(end 109.409738 -294.681148)
		(width 0.1143)
		(layer "In15.Cu")
		(net "P5E_CPU1_P0_RX_DN<13>")
	)
	(arc
		(start 109.409738 -279.41143)
		(mid 109.409357 -279.411176)
		(end 109.408976 -279.410922)
		(width 0.1143)
		(layer "In15.Cu")
		(net "P5E_CPU1_P0_RX_DN<13>")
	)
	(arc
		(start 63.858648 -382.19761)
		(mid 63.883867 -382.035616)
		(end 63.9572 -381.889)
		(width 0.14224)
		(layer "In15.Cu")
		(net "P5E_CPU1_P0_RX_DN<13>")
	)
	(arc
		(start 109.235494 -300.9011)
		(mid 109.149095 -300.616344)
		(end 109.119924 -300.320202)
		(width 0.14224)
		(layer "In15.Cu")
		(net "P5E_CPU1_P0_RX_DN<13>")
	)
	(arc
		(start 109.165644 -295.146222)
		(mid 109.230159 -294.884003)
		(end 109.408976 -294.681656)
		(width 0.1143)
		(layer "In15.Cu")
		(net "P5E_CPU1_P0_RX_DN<13>")
	)
	(arc
		(start 75.98029 -366.604296)
		(mid 76.089187 -366.520705)
		(end 76.216002 -366.468152)
		(width 0.14224)
		(layer "In15.Cu")
		(net "P5E_CPU1_P0_RX_DN<13>")
	)
	(arc
		(start 109.479842 -276.82063)
		(mid 109.630227 -276.516338)
		(end 109.479842 -276.212046)
		(width 0.1143)
		(layer "In15.Cu")
		(net "P5E_CPU1_P0_RX_DN<13>")
	)
	(arc
		(start 76.216002 -366.468152)
		(mid 76.407491 -366.429921)
		(end 76.602336 -366.417098)
		(width 0.14224)
		(layer "In15.Cu")
		(net "P5E_CPU1_P0_RX_DN<13>")
	)
	(arc
		(start 109.408976 -284.270958)
		(mid 109.165649 -283.806392)
		(end 109.408976 -283.341826)
		(width 0.1143)
		(layer "In15.Cu")
		(net "P5E_CPU1_P0_RX_DN<13>")
	)
	(arc
		(start 109.469682 -280.066496)
		(mid 109.648224 -279.756472)
		(end 109.469936 -279.446228)
		(width 0.1143)
		(layer "In15.Cu")
		(net "P5E_CPU1_P0_RX_DN<13>")
	)
	(arc
		(start 109.408976 -292.370764)
		(mid 109.165649 -291.906198)
		(end 109.408976 -291.441632)
		(width 0.1143)
		(layer "In15.Cu")
		(net "P5E_CPU1_P0_RX_DN<13>")
	)
	(arc
		(start 109.408976 -276.170898)
		(mid 109.165649 -275.706332)
		(end 109.408976 -275.241766)
		(width 0.1143)
		(layer "In15.Cu")
		(net "P5E_CPU1_P0_RX_DN<13>")
	)
	(arc
		(start 109.635798 -286.23641)
		(mid 109.591727 -286.066874)
		(end 109.479842 -285.932118)
		(width 0.1143)
		(layer "In15.Cu")
		(net "P5E_CPU1_P0_RX_DN<13>")
	)
	(arc
		(start 109.408976 -290.750752)
		(mid 109.165649 -290.286186)
		(end 109.408976 -289.82162)
		(width 0.1143)
		(layer "In15.Cu")
		(net "P5E_CPU1_P0_RX_DN<13>")
	)
	(arc
		(start 109.479842 -291.400484)
		(mid 109.630227 -291.096192)
		(end 109.479842 -290.7919)
		(width 0.1143)
		(layer "In15.Cu")
		(net "P5E_CPU1_P0_RX_DN<13>")
	)
	(arc
		(start 109.469936 -294.64635)
		(mid 109.648352 -294.336106)
		(end 109.469682 -294.026082)
		(width 0.1143)
		(layer "In15.Cu")
		(net "P5E_CPU1_P0_RX_DN<13>")
	)
	(arc
		(start 109.499654 -293.006272)
		(mid 109.648368 -292.716204)
		(end 109.499654 -292.426136)
		(width 0.1143)
		(layer "In15.Cu")
		(net "P5E_CPU1_P0_RX_DN<13>")
	)
	(arc
		(start 109.635798 -287.85439)
		(mid 109.609417 -287.720428)
		(end 109.534198 -287.606486)
		(width 0.1143)
		(layer "In15.Cu")
		(net "P5E_CPU1_P0_RX_DN<13>")
	)
	(arc
		(start 109.408976 -289.13074)
		(mid 109.165649 -288.666174)
		(end 109.408976 -288.201608)
		(width 0.1143)
		(layer "In15.Cu")
		(net "P5E_CPU1_P0_RX_DN<13>")
	)
	(arc
		(start 155.078176 -357.085646)
		(mid 154.365008 -356.943788)
		(end 153.760424 -356.5398)
		(width 0.14224)
		(layer "In15.Cu")
		(net "P5E_CPU1_P0_RX_DN<13>")
	)
	(arc
		(start 109.408214 -287.516824)
		(mid 109.229914 -287.310889)
		(end 109.165644 -287.046162)
		(width 0.1143)
		(layer "In15.Cu")
		(net "P5E_CPU1_P0_RX_DN<13>")
	)
	(arc
		(start 109.165644 -287.046162)
		(mid 109.230159 -286.783943)
		(end 109.408976 -286.581596)
		(width 0.1143)
		(layer "In15.Cu")
		(net "P5E_CPU1_P0_RX_DN<13>")
	)
	(arc
		(start 168.071292 -365.745776)
		(mid 168.202583 -365.691393)
		(end 168.256966 -365.560102)
		(width 0.14224)
		(layer "In15.Cu")
		(net "P5E_CPU1_P0_RX_DN<13>")
	)
	(arc
		(start 165.940232 -357.158798)
		(mid 165.859239 -357.10468)
		(end 165.763702 -357.085646)
		(width 0.14224)
		(layer "In15.Cu")
		(net "P5E_CPU1_P0_RX_DN<13>")
	)
	(arc
		(start 109.409738 -274.551394)
		(mid 109.409357 -274.55114)
		(end 109.408976 -274.550886)
		(width 0.1143)
		(layer "In15.Cu")
		(net "P5E_CPU1_P0_RX_DN<13>")
	)
	(arc
		(start 109.408976 -279.410922)
		(mid 109.165649 -278.946356)
		(end 109.408976 -278.48179)
		(width 0.1143)
		(layer "In15.Cu")
		(net "P5E_CPU1_P0_RX_DN<13>")
	)
	(arc
		(start 109.479842 -283.300678)
		(mid 109.631431 -282.996386)
		(end 109.479842 -282.692094)
		(width 0.1143)
		(layer "In15.Cu")
		(net "P5E_CPU1_P0_RX_DN<13>")
	)
	(arc
		(start 134.360158 -342.578182)
		(mid 133.489878 -341.93272)
		(end 132.68706 -341.205058)
		(width 0.14224)
		(layer "In15.Cu")
		(net "P5E_CPU1_P0_RX_DN<13>")
	)
	(arc
		(start 109.408976 -282.650946)
		(mid 109.165649 -282.18638)
		(end 109.408976 -281.721814)
		(width 0.1143)
		(layer "In15.Cu")
		(net "P5E_CPU1_P0_RX_DN<13>")
	)
	(arc
		(start 109.482128 -288.158682)
		(mid 109.595014 -288.025911)
		(end 109.635544 -287.856422)
		(width 0.1143)
		(layer "In15.Cu")
		(net "P5E_CPU1_P0_RX_DN<13>")
	)
	(arc
		(start 109.408976 -274.550886)
		(mid 109.256989 -274.394378)
		(end 109.17555 -274.191984)
		(width 0.1143)
		(layer "In15.Cu")
		(net "P5E_CPU1_P0_RX_DN<13>")
	)
	(arc
		(start 109.469682 -275.20646)
		(mid 109.648224 -274.896436)
		(end 109.469936 -274.586192)
		(width 0.1143)
		(layer "In15.Cu")
		(net "P5E_CPU1_P0_RX_DN<13>")
	)
	(arc
		(start 168.256966 -359.609136)
		(mid 168.232411 -359.48569)
		(end 168.162478 -359.381044)
		(width 0.14224)
		(layer "In15.Cu")
		(net "P5E_CPU1_P0_RX_DN<13>")
	)
	(arc
		(start 109.499654 -289.766248)
		(mid 109.648368 -289.47618)
		(end 109.499654 -289.186112)
		(width 0.1143)
		(layer "In15.Cu")
		(net "P5E_CPU1_P0_RX_DN<13>")
	)
	(arc
		(start 109.409992 -293.991538)
		(mid 109.165712 -293.527583)
		(end 109.407706 -293.062406)
		(width 0.1143)
		(layer "In15.Cu")
		(net "P5E_CPU1_P0_RX_DN<13>")
	)
	(arc
		(start 109.17555 -274.191984)
		(mid 109.173527 -274.180574)
		(end 109.17174 -274.169124)
		(width 0.1143)
		(layer "In15.Cu")
		(net "P5E_CPU1_P0_RX_DN<13>")
	)
	(arc
		(start 109.433614 -281.045412)
		(mid 109.158696 -280.566085)
		(end 109.434122 -280.08707)
		(width 0.1143)
		(layer "In15.Cu")
		(net "P5E_CPU1_P0_RX_DN<13>")
	)
	(arc
		(start 109.479842 -278.440642)
		(mid 109.630227 -278.13635)
		(end 109.479842 -277.832058)
		(width 0.1143)
		(layer "In15.Cu")
		(net "P5E_CPU1_P0_RX_DN<13>")
	)
	(arc
		(start 108.159804 -366.417098)
		(mid 108.783701 -366.340328)
		(end 109.370368 -366.114584)
		(width 0.14224)
		(layer "In15.Cu")
		(net "P5E_CPU1_P0_RX_DN<13>")
	)
	(arc
		(start 109.408976 -277.79091)
		(mid 109.165649 -277.326344)
		(end 109.408976 -276.861778)
		(width 0.1143)
		(layer "In15.Cu")
		(net "P5E_CPU1_P0_RX_DN<13>")
	)
	(arc
		(start 109.370368 -366.114584)
		(mid 110.085305 -365.83948)
		(end 110.8456 -365.745776)
		(width 0.14224)
		(layer "In15.Cu")
		(net "P5E_CPU1_P0_RX_DN<13>")
	)
	(segment
		(start 109.257846 -272.20037)
		(end 108.790994 -272.466308)
		(width 0.12954)
		(layer "F.Cu")
		(net "P5E_CPU1_P0_RX_DN<12>")
	)
	(segment
		(start 61.670692 -385.31038)
		(end 62.191392 -385.31038)
		(width 0.127)
		(layer "F.Cu")
		(net "P5E_CPU1_P0_RX_DN<12>")
	)
	(segment
		(start 108.539788 -289.171888)
		(end 108.5088 -289.154108)
		(width 0.1143)
		(layer "In15.Cu")
		(net "P5E_CPU1_P0_RX_DN<12>")
	)
	(segment
		(start 108.22559 -295.996614)
		(end 108.22559 -295.146222)
		(width 0.1143)
		(layer "In15.Cu")
		(net "P5E_CPU1_P0_RX_DN<12>")
	)
	(segment
		(start 108.5088 -282.674314)
		(end 108.508038 -282.673806)
		(width 0.1143)
		(layer "In15.Cu")
		(net "P5E_CPU1_P0_RX_DN<12>")
	)
	(segment
		(start 108.507022 -281.053286)
		(end 108.505498 -281.05227)
		(width 0.1143)
		(layer "In15.Cu")
		(net "P5E_CPU1_P0_RX_DN<12>")
	)
	(segment
		(start 108.508038 -281.698954)
		(end 108.539788 -281.680666)
		(width 0.1143)
		(layer "In15.Cu")
		(net "P5E_CPU1_P0_RX_DN<12>")
	)
	(segment
		(start 108.51007 -284.295088)
		(end 108.5088 -284.294326)
		(width 0.1143)
		(layer "In15.Cu")
		(net "P5E_CPU1_P0_RX_DN<12>")
	)
	(segment
		(start 108.504482 -278.460962)
		(end 108.505498 -278.460454)
		(width 0.1143)
		(layer "In15.Cu")
		(net "P5E_CPU1_P0_RX_DN<12>")
	)
	(segment
		(start 133.743954 -343.71788)
		(end 120.64619 -330.620116)
		(width 0.14224)
		(layer "In15.Cu")
		(net "P5E_CPU1_P0_RX_DN<12>")
	)
	(segment
		(start 108.468922 -294.681656)
		(end 108.50118 -294.66286)
		(width 0.1143)
		(layer "In15.Cu")
		(net "P5E_CPU1_P0_RX_DN<12>")
	)
	(segment
		(start 108.539788 -285.932118)
		(end 108.5088 -285.914338)
		(width 0.1143)
		(layer "In15.Cu")
		(net "P5E_CPU1_P0_RX_DN<12>")
	)
	(segment
		(start 108.508038 -288.178748)
		(end 108.541566 -288.15919)
		(width 0.1143)
		(layer "In15.Cu")
		(net "P5E_CPU1_P0_RX_DN<12>")
	)
	(segment
		(start 108.505498 -289.152076)
		(end 108.468922 -289.13074)
		(width 0.1143)
		(layer "In15.Cu")
		(net "P5E_CPU1_P0_RX_DN<12>")
	)
	(segment
		(start 108.539788 -290.7919)
		(end 108.5088 -290.77412)
		(width 0.1143)
		(layer "In15.Cu")
		(net "P5E_CPU1_P0_RX_DN<12>")
	)
	(segment
		(start 108.508038 -277.81377)
		(end 108.507022 -277.813262)
		(width 0.1143)
		(layer "In15.Cu")
		(net "P5E_CPU1_P0_RX_DN<12>")
	)
	(segment
		(start 162.58794 -361.85602)
		(end 162.7251 -361.71886)
		(width 0.14224)
		(layer "In15.Cu")
		(net "P5E_CPU1_P0_RX_DN<12>")
	)
	(segment
		(start 108.51007 -279.435052)
		(end 108.5088 -279.43429)
		(width 0.1143)
		(layer "In15.Cu")
		(net "P5E_CPU1_P0_RX_DN<12>")
	)
	(segment
		(start 108.505498 -278.460454)
		(end 108.507022 -278.459438)
		(width 0.1143)
		(layer "In15.Cu")
		(net "P5E_CPU1_P0_RX_DN<12>")
	)
	(segment
		(start 108.507022 -294.659304)
		(end 108.508038 -294.658796)
		(width 0.1143)
		(layer "In15.Cu")
		(net "P5E_CPU1_P0_RX_DN<12>")
	)
	(segment
		(start 109.158786 -272.536158)
		(end 109.088936 -272.466308)
		(width 0.1143)
		(layer "In15.Cu")
		(net "P5E_CPU1_P0_RX_DN<12>")
	)
	(segment
		(start 108.517436 -281.059636)
		(end 108.514896 -281.058112)
		(width 0.1143)
		(layer "In15.Cu")
		(net "P5E_CPU1_P0_RX_DN<12>")
	)
	(segment
		(start 108.505498 -273.600418)
		(end 108.507022 -273.599402)
		(width 0.1143)
		(layer "In15.Cu")
		(net "P5E_CPU1_P0_RX_DN<12>")
	)
	(segment
		(start 162.7251 -364.43666)
		(end 162.7251 -363.54766)
		(width 0.14224)
		(layer "In15.Cu")
		(net "P5E_CPU1_P0_RX_DN<12>")
	)
	(segment
		(start 108.507022 -284.29331)
		(end 108.468922 -284.270958)
		(width 0.1143)
		(layer "In15.Cu")
		(net "P5E_CPU1_P0_RX_DN<12>")
	)
	(segment
		(start 108.507022 -282.673298)
		(end 108.468922 -282.650946)
		(width 0.1143)
		(layer "In15.Cu")
		(net "P5E_CPU1_P0_RX_DN<12>")
	)
	(segment
		(start 108.51007 -276.837648)
		(end 108.539788 -276.82063)
		(width 0.1143)
		(layer "In15.Cu")
		(net "P5E_CPU1_P0_RX_DN<12>")
	)
	(segment
		(start 108.532676 -274.587208)
		(end 108.53166 -274.5867)
		(width 0.1143)
		(layer "In15.Cu")
		(net "P5E_CPU1_P0_RX_DN<12>")
	)
	(segment
		(start 108.468922 -275.241766)
		(end 108.504482 -275.220938)
		(width 0.1143)
		(layer "In15.Cu")
		(net "P5E_CPU1_P0_RX_DN<12>")
	)
	(segment
		(start 108.508038 -279.433782)
		(end 108.507022 -279.433274)
		(width 0.1143)
		(layer "In15.Cu")
		(net "P5E_CPU1_P0_RX_DN<12>")
	)
	(segment
		(start 108.5088 -292.394132)
		(end 108.508038 -292.393624)
		(width 0.1143)
		(layer "In15.Cu")
		(net "P5E_CPU1_P0_RX_DN<12>")
	)
	(segment
		(start 108.539534 -276.82063)
		(end 108.540042 -276.820376)
		(width 0.1143)
		(layer "In15.Cu")
		(net "P5E_CPU1_P0_RX_DN<12>")
	)
	(segment
		(start 108.476796 -276.17547)
		(end 108.468922 -276.170898)
		(width 0.1143)
		(layer "In15.Cu")
		(net "P5E_CPU1_P0_RX_DN<12>")
	)
	(segment
		(start 108.539788 -287.55213)
		(end 108.508038 -287.533842)
		(width 0.1143)
		(layer "In15.Cu")
		(net "P5E_CPU1_P0_RX_DN<12>")
	)
	(segment
		(start 108.505498 -294.66032)
		(end 108.507022 -294.659304)
		(width 0.1143)
		(layer "In15.Cu")
		(net "P5E_CPU1_P0_RX_DN<12>")
	)
	(segment
		(start 62.349634 -384.84683)
		(end 62.35446 -384.234944)
		(width 0.14224)
		(layer "In15.Cu")
		(net "P5E_CPU1_P0_RX_DN<12>")
	)
	(segment
		(start 162.7251 -361.71886)
		(end 162.7251 -361.29214)
		(width 0.14224)
		(layer "In15.Cu")
		(net "P5E_CPU1_P0_RX_DN<12>")
	)
	(segment
		(start 108.505498 -294.012112)
		(end 108.468922 -293.990776)
		(width 0.1143)
		(layer "In15.Cu")
		(net "P5E_CPU1_P0_RX_DN<12>")
	)
	(segment
		(start 108.468922 -291.441632)
		(end 108.477558 -291.436552)
		(width 0.1143)
		(layer "In15.Cu")
		(net "P5E_CPU1_P0_RX_DN<12>")
	)
	(segment
		(start 108.539788 -294.031924)
		(end 108.5088 -294.014144)
		(width 0.1143)
		(layer "In15.Cu")
		(net "P5E_CPU1_P0_RX_DN<12>")
	)
	(segment
		(start 108.507022 -279.433274)
		(end 108.468922 -279.410922)
		(width 0.1143)
		(layer "In15.Cu")
		(net "P5E_CPU1_P0_RX_DN<12>")
	)
	(segment
		(start 108.539788 -275.200618)
		(end 108.539534 -275.200618)
		(width 0.1143)
		(layer "In15.Cu")
		(net "P5E_CPU1_P0_RX_DN<12>")
	)
	(segment
		(start 162.7251 -362.4199)
		(end 162.58794 -362.28274)
		(width 0.14224)
		(layer "In15.Cu")
		(net "P5E_CPU1_P0_RX_DN<12>")
	)
	(segment
		(start 62.544452 -385.405376)
		(end 62.54496 -385.404868)
		(width 0.14224)
		(layer "In15.Cu")
		(net "P5E_CPU1_P0_RX_DN<12>")
	)
	(segment
		(start 108.505498 -276.840442)
		(end 108.507022 -276.839426)
		(width 0.1143)
		(layer "In15.Cu")
		(net "P5E_CPU1_P0_RX_DN<12>")
	)
	(segment
		(start 108.5088 -275.218398)
		(end 108.51007 -275.217636)
		(width 0.1143)
		(layer "In15.Cu")
		(net "P5E_CPU1_P0_RX_DN<12>")
	)
	(segment
		(start 108.507022 -276.839426)
		(end 108.508038 -276.838918)
		(width 0.1143)
		(layer "In15.Cu")
		(net "P5E_CPU1_P0_RX_DN<12>")
	)
	(segment
		(start 108.539788 -281.072082)
		(end 108.518452 -281.060144)
		(width 0.1143)
		(layer "In15.Cu")
		(net "P5E_CPU1_P0_RX_DN<12>")
	)
	(segment
		(start 108.5088 -273.598386)
		(end 108.51007 -273.597624)
		(width 0.1143)
		(layer "In15.Cu")
		(net "P5E_CPU1_P0_RX_DN<12>")
	)
	(segment
		(start 108.468922 -293.061644)
		(end 108.486702 -293.05123)
		(width 0.1143)
		(layer "In15.Cu")
		(net "P5E_CPU1_P0_RX_DN<12>")
	)
	(segment
		(start 108.505498 -290.772088)
		(end 108.468922 -290.750752)
		(width 0.1143)
		(layer "In15.Cu")
		(net "P5E_CPU1_P0_RX_DN<12>")
	)
	(segment
		(start 108.17987 -300.657006)
		(end 108.17987 -296.070782)
		(width 0.14224)
		(layer "In15.Cu")
		(net "P5E_CPU1_P0_RX_DN<12>")
	)
	(segment
		(start 108.5088 -281.054302)
		(end 108.508038 -281.053794)
		(width 0.1143)
		(layer "In15.Cu")
		(net "P5E_CPU1_P0_RX_DN<12>")
	)
	(segment
		(start 108.508038 -284.938978)
		(end 108.539788 -284.92069)
		(width 0.1143)
		(layer "In15.Cu")
		(net "P5E_CPU1_P0_RX_DN<12>")
	)
	(segment
		(start 108.507022 -277.813262)
		(end 108.468922 -277.79091)
		(width 0.1143)
		(layer "In15.Cu")
		(net "P5E_CPU1_P0_RX_DN<12>")
	)
	(segment
		(start 108.508038 -281.053794)
		(end 108.507022 -281.053286)
		(width 0.1143)
		(layer "In15.Cu")
		(net "P5E_CPU1_P0_RX_DN<12>")
	)
	(segment
		(start 109.088936 -272.466308)
		(end 108.790994 -272.466308)
		(width 0.1143)
		(layer "In15.Cu")
		(net "P5E_CPU1_P0_RX_DN<12>")
	)
	(segment
		(start 108.539788 -284.312106)
		(end 108.51007 -284.295088)
		(width 0.1143)
		(layer "In15.Cu")
		(net "P5E_CPU1_P0_RX_DN<12>")
	)
	(segment
		(start 108.51007 -273.597624)
		(end 108.539788 -273.580606)
		(width 0.1143)
		(layer "In15.Cu")
		(net "P5E_CPU1_P0_RX_DN<12>")
	)
	(segment
		(start 108.539788 -282.692094)
		(end 108.51007 -282.675076)
		(width 0.1143)
		(layer "In15.Cu")
		(net "P5E_CPU1_P0_RX_DN<12>")
	)
	(segment
		(start 108.50118 -294.66286)
		(end 108.501942 -294.662352)
		(width 0.1143)
		(layer "In15.Cu")
		(net "P5E_CPU1_P0_RX_DN<12>")
	)
	(segment
		(start 108.468922 -281.721814)
		(end 108.508038 -281.698954)
		(width 0.1143)
		(layer "In15.Cu")
		(net "P5E_CPU1_P0_RX_DN<12>")
	)
	(segment
		(start 62.658498 -383.93116)
		(end 62.658498 -382.164082)
		(width 0.14224)
		(layer "In15.Cu")
		(net "P5E_CPU1_P0_RX_DN<12>")
	)
	(segment
		(start 162.58794 -360.72826)
		(end 162.7251 -360.5911)
		(width 0.14224)
		(layer "In15.Cu")
		(net "P5E_CPU1_P0_RX_DN<12>")
	)
	(segment
		(start 62.751462 -381.866648)
		(end 67.98564 -374.32234)
		(width 0.14224)
		(layer "In15.Cu")
		(net "P5E_CPU1_P0_RX_DN<12>")
	)
	(segment
		(start 108.539788 -292.411912)
		(end 108.5088 -292.394132)
		(width 0.1143)
		(layer "In15.Cu")
		(net "P5E_CPU1_P0_RX_DN<12>")
	)
	(segment
		(start 108.17987 -296.070782)
		(end 108.17987 -296.042334)
		(width 0.1143)
		(layer "In15.Cu")
		(net "P5E_CPU1_P0_RX_DN<12>")
	)
	(segment
		(start 108.504482 -294.660828)
		(end 108.505498 -294.66032)
		(width 0.1143)
		(layer "In15.Cu")
		(net "P5E_CPU1_P0_RX_DN<12>")
	)
	(segment
		(start 108.512864 -281.056842)
		(end 108.5088 -281.054302)
		(width 0.1143)
		(layer "In15.Cu")
		(net "P5E_CPU1_P0_RX_DN<12>")
	)
	(segment
		(start 108.508038 -286.558736)
		(end 108.541566 -286.539178)
		(width 0.1143)
		(layer "In15.Cu")
		(net "P5E_CPU1_P0_RX_DN<12>")
	)
	(segment
		(start 108.514134 -281.057604)
		(end 108.512864 -281.056842)
		(width 0.1143)
		(layer "In15.Cu")
		(net "P5E_CPU1_P0_RX_DN<12>")
	)
	(segment
		(start 108.507022 -292.393116)
		(end 108.505498 -292.3921)
		(width 0.1143)
		(layer "In15.Cu")
		(net "P5E_CPU1_P0_RX_DN<12>")
	)
	(segment
		(start 162.58794 -361.15498)
		(end 162.58794 -360.72826)
		(width 0.14224)
		(layer "In15.Cu")
		(net "P5E_CPU1_P0_RX_DN<12>")
	)
	(segment
		(start 108.508038 -289.1536)
		(end 108.507022 -289.153092)
		(width 0.1143)
		(layer "In15.Cu")
		(net "P5E_CPU1_P0_RX_DN<12>")
	)
	(segment
		(start 108.505498 -281.05227)
		(end 108.468922 -281.030934)
		(width 0.1143)
		(layer "In15.Cu")
		(net "P5E_CPU1_P0_RX_DN<12>")
	)
	(segment
		(start 151.381206 -355.503734)
		(end 133.743954 -343.71788)
		(width 0.14224)
		(layer "In15.Cu")
		(net "P5E_CPU1_P0_RX_DN<12>")
	)
	(segment
		(start 162.7251 -361.29214)
		(end 162.58794 -361.15498)
		(width 0.14224)
		(layer "In15.Cu")
		(net "P5E_CPU1_P0_RX_DN<12>")
	)
	(segment
		(start 108.46943 -286.581342)
		(end 108.508038 -286.558736)
		(width 0.1143)
		(layer "In15.Cu")
		(net "P5E_CPU1_P0_RX_DN<12>")
	)
	(segment
		(start 108.51007 -282.675076)
		(end 108.5088 -282.674314)
		(width 0.1143)
		(layer "In15.Cu")
		(net "P5E_CPU1_P0_RX_DN<12>")
	)
	(segment
		(start 108.539788 -276.82063)
		(end 108.539534 -276.82063)
		(width 0.1143)
		(layer "In15.Cu")
		(net "P5E_CPU1_P0_RX_DN<12>")
	)
	(segment
		(start 108.5088 -285.914338)
		(end 108.508038 -285.91383)
		(width 0.1143)
		(layer "In15.Cu")
		(net "P5E_CPU1_P0_RX_DN<12>")
	)
	(segment
		(start 108.468922 -280.101802)
		(end 108.504482 -280.080974)
		(width 0.1143)
		(layer "In15.Cu")
		(net "P5E_CPU1_P0_RX_DN<12>")
	)
	(segment
		(start 108.507022 -285.913322)
		(end 108.468922 -285.89097)
		(width 0.1143)
		(layer "In15.Cu")
		(net "P5E_CPU1_P0_RX_DN<12>")
	)
	(segment
		(start 108.508038 -280.078942)
		(end 108.5088 -280.078434)
		(width 0.1143)
		(layer "In15.Cu")
		(net "P5E_CPU1_P0_RX_DN<12>")
	)
	(segment
		(start 108.501942 -294.662352)
		(end 108.50372 -294.661336)
		(width 0.1143)
		(layer "In15.Cu")
		(net "P5E_CPU1_P0_RX_DN<12>")
	)
	(segment
		(start 108.502196 -274.57019)
		(end 108.476796 -274.555458)
		(width 0.1143)
		(layer "In15.Cu")
		(net "P5E_CPU1_P0_RX_DN<12>")
	)
	(segment
		(start 108.507022 -278.459438)
		(end 108.508038 -278.45893)
		(width 0.1143)
		(layer "In15.Cu")
		(net "P5E_CPU1_P0_RX_DN<12>")
	)
	(segment
		(start 162.58794 -363.4105)
		(end 162.58794 -362.98378)
		(width 0.14224)
		(layer "In15.Cu")
		(net "P5E_CPU1_P0_RX_DN<12>")
	)
	(segment
		(start 108.51007 -275.217636)
		(end 108.539788 -275.200618)
		(width 0.1143)
		(layer "In15.Cu")
		(net "P5E_CPU1_P0_RX_DN<12>")
	)
	(segment
		(start 108.518452 -281.060144)
		(end 108.517436 -281.059636)
		(width 0.1143)
		(layer "In15.Cu")
		(net "P5E_CPU1_P0_RX_DN<12>")
	)
	(segment
		(start 73.21931 -367.98631)
		(end 75.610212 -365.595408)
		(width 0.14224)
		(layer "In15.Cu")
		(net "P5E_CPU1_P0_RX_DN<12>")
	)
	(segment
		(start 108.508038 -282.673806)
		(end 108.507022 -282.673298)
		(width 0.1143)
		(layer "In15.Cu")
		(net "P5E_CPU1_P0_RX_DN<12>")
	)
	(segment
		(start 108.53166 -276.206712)
		(end 108.530136 -276.205696)
		(width 0.1143)
		(layer "In15.Cu")
		(net "P5E_CPU1_P0_RX_DN<12>")
	)
	(segment
		(start 108.532676 -276.20722)
		(end 108.53166 -276.206712)
		(width 0.1143)
		(layer "In15.Cu")
		(net "P5E_CPU1_P0_RX_DN<12>")
	)
	(segment
		(start 108.5088 -277.814278)
		(end 108.508038 -277.81377)
		(width 0.1143)
		(layer "In15.Cu")
		(net "P5E_CPU1_P0_RX_DN<12>")
	)
	(segment
		(start 108.5088 -276.83841)
		(end 108.51007 -276.837648)
		(width 0.1143)
		(layer "In15.Cu")
		(net "P5E_CPU1_P0_RX_DN<12>")
	)
	(segment
		(start 108.53166 -274.5867)
		(end 108.530136 -274.585684)
		(width 0.1143)
		(layer "In15.Cu")
		(net "P5E_CPU1_P0_RX_DN<12>")
	)
	(segment
		(start 108.534454 -276.208236)
		(end 108.532676 -276.20722)
		(width 0.1143)
		(layer "In15.Cu")
		(net "P5E_CPU1_P0_RX_DN<12>")
	)
	(segment
		(start 108.478574 -291.436044)
		(end 108.539788 -291.400484)
		(width 0.1143)
		(layer "In15.Cu")
		(net "P5E_CPU1_P0_RX_DN<12>")
	)
	(segment
		(start 62.54496 -385.404868)
		(end 62.666626 -385.334764)
		(width 0.14224)
		(layer "In15.Cu")
		(net "P5E_CPU1_P0_RX_DN<12>")
	)
	(segment
		(start 108.508038 -294.658796)
		(end 108.539788 -294.640508)
		(width 0.1143)
		(layer "In15.Cu")
		(net "P5E_CPU1_P0_RX_DN<12>")
	)
	(segment
		(start 108.508038 -285.91383)
		(end 108.507022 -285.913322)
		(width 0.1143)
		(layer "In15.Cu")
		(net "P5E_CPU1_P0_RX_DN<12>")
	)
	(segment
		(start 108.50372 -294.661336)
		(end 108.504482 -294.660828)
		(width 0.1143)
		(layer "In15.Cu")
		(net "P5E_CPU1_P0_RX_DN<12>")
	)
	(segment
		(start 108.508038 -292.393624)
		(end 108.507022 -292.393116)
		(width 0.1143)
		(layer "In15.Cu")
		(net "P5E_CPU1_P0_RX_DN<12>")
	)
	(segment
		(start 162.58794 -362.98378)
		(end 162.7251 -362.84662)
		(width 0.14224)
		(layer "In15.Cu")
		(net "P5E_CPU1_P0_RX_DN<12>")
	)
	(segment
		(start 108.476796 -274.555458)
		(end 108.468922 -274.550886)
		(width 0.1143)
		(layer "In15.Cu")
		(net "P5E_CPU1_P0_RX_DN<12>")
	)
	(segment
		(start 108.5088 -289.154108)
		(end 108.508038 -289.1536)
		(width 0.1143)
		(layer "In15.Cu")
		(net "P5E_CPU1_P0_RX_DN<12>")
	)
	(segment
		(start 108.487718 -293.050722)
		(end 108.539788 -293.020496)
		(width 0.1143)
		(layer "In15.Cu")
		(net "P5E_CPU1_P0_RX_DN<12>")
	)
	(segment
		(start 108.514896 -281.058112)
		(end 108.514134 -281.057604)
		(width 0.1143)
		(layer "In15.Cu")
		(net "P5E_CPU1_P0_RX_DN<12>")
	)
	(segment
		(start 108.508038 -283.318966)
		(end 108.539788 -283.300678)
		(width 0.1143)
		(layer "In15.Cu")
		(net "P5E_CPU1_P0_RX_DN<12>")
	)
	(segment
		(start 109.977936 -364.787942)
		(end 162.373818 -364.787942)
		(width 0.14224)
		(layer "In15.Cu")
		(net "P5E_CPU1_P0_RX_DN<12>")
	)
	(segment
		(start 153.36901 -357.474012)
		(end 151.478996 -355.583998)
		(width 0.14224)
		(layer "In15.Cu")
		(net "P5E_CPU1_P0_RX_DN<12>")
	)
	(segment
		(start 108.486702 -293.05123)
		(end 108.487718 -293.050722)
		(width 0.1143)
		(layer "In15.Cu")
		(net "P5E_CPU1_P0_RX_DN<12>")
	)
	(segment
		(start 108.539534 -275.200618)
		(end 108.540042 -275.200364)
		(width 0.1143)
		(layer "In15.Cu")
		(net "P5E_CPU1_P0_RX_DN<12>")
	)
	(segment
		(start 108.17987 -296.042334)
		(end 108.22559 -295.996614)
		(width 0.1143)
		(layer "In15.Cu")
		(net "P5E_CPU1_P0_RX_DN<12>")
	)
	(segment
		(start 108.978192 -272.788888)
		(end 109.008672 -272.771108)
		(width 0.1143)
		(layer "In15.Cu")
		(net "P5E_CPU1_P0_RX_DN<12>")
	)
	(segment
		(start 108.508038 -290.773612)
		(end 108.507022 -290.773104)
		(width 0.1143)
		(layer "In15.Cu")
		(net "P5E_CPU1_P0_RX_DN<12>")
	)
	(segment
		(start 108.468922 -286.581596)
		(end 108.46943 -286.581342)
		(width 0.1143)
		(layer "In15.Cu")
		(net "P5E_CPU1_P0_RX_DN<12>")
	)
	(segment
		(start 108.508038 -284.293818)
		(end 108.507022 -284.29331)
		(width 0.1143)
		(layer "In15.Cu")
		(net "P5E_CPU1_P0_RX_DN<12>")
	)
	(segment
		(start 67.98564 -374.32234)
		(end 73.21931 -367.98631)
		(width 0.14224)
		(layer "In15.Cu")
		(net "P5E_CPU1_P0_RX_DN<12>")
	)
	(segment
		(start 108.507022 -280.07945)
		(end 108.508038 -280.078942)
		(width 0.1143)
		(layer "In15.Cu")
		(net "P5E_CPU1_P0_RX_DN<12>")
	)
	(segment
		(start 162.7251 -363.54766)
		(end 162.58794 -363.4105)
		(width 0.14224)
		(layer "In15.Cu")
		(net "P5E_CPU1_P0_RX_DN<12>")
	)
	(segment
		(start 108.508038 -275.218906)
		(end 108.5088 -275.218398)
		(width 0.1143)
		(layer "In15.Cu")
		(net "P5E_CPU1_P0_RX_DN<12>")
	)
	(segment
		(start 108.468922 -283.341826)
		(end 108.505498 -283.32049)
		(width 0.1143)
		(layer "In15.Cu")
		(net "P5E_CPU1_P0_RX_DN<12>")
	)
	(segment
		(start 108.534454 -274.588224)
		(end 108.532676 -274.587208)
		(width 0.1143)
		(layer "In15.Cu")
		(net "P5E_CPU1_P0_RX_DN<12>")
	)
	(segment
		(start 108.530136 -274.585684)
		(end 108.502196 -274.57019)
		(width 0.1143)
		(layer "In15.Cu")
		(net "P5E_CPU1_P0_RX_DN<12>")
	)
	(segment
		(start 162.7251 -362.84662)
		(end 162.7251 -362.4199)
		(width 0.14224)
		(layer "In15.Cu")
		(net "P5E_CPU1_P0_RX_DN<12>")
	)
	(segment
		(start 162.466528 -358.176068)
		(end 155.063952 -358.176068)
		(width 0.14224)
		(layer "In15.Cu")
		(net "P5E_CPU1_P0_RX_DN<12>")
	)
	(segment
		(start 108.468922 -278.48179)
		(end 108.504482 -278.460962)
		(width 0.1143)
		(layer "In15.Cu")
		(net "P5E_CPU1_P0_RX_DN<12>")
	)
	(segment
		(start 108.468922 -273.621754)
		(end 108.504482 -273.600926)
		(width 0.1143)
		(layer "In15.Cu")
		(net "P5E_CPU1_P0_RX_DN<12>")
	)
	(segment
		(start 108.507022 -294.013128)
		(end 108.505498 -294.012112)
		(width 0.1143)
		(layer "In15.Cu")
		(net "P5E_CPU1_P0_RX_DN<12>")
	)
	(segment
		(start 108.507022 -273.599402)
		(end 108.508038 -273.598894)
		(width 0.1143)
		(layer "In15.Cu")
		(net "P5E_CPU1_P0_RX_DN<12>")
	)
	(segment
		(start 108.468922 -284.961838)
		(end 108.508038 -284.938978)
		(width 0.1143)
		(layer "In15.Cu")
		(net "P5E_CPU1_P0_RX_DN<12>")
	)
	(segment
		(start 108.507022 -290.773104)
		(end 108.505498 -290.772088)
		(width 0.1143)
		(layer "In15.Cu")
		(net "P5E_CPU1_P0_RX_DN<12>")
	)
	(segment
		(start 108.530136 -276.205696)
		(end 108.502196 -276.190202)
		(width 0.1143)
		(layer "In15.Cu")
		(net "P5E_CPU1_P0_RX_DN<12>")
	)
	(segment
		(start 108.5088 -280.078434)
		(end 108.51007 -280.077672)
		(width 0.1143)
		(layer "In15.Cu")
		(net "P5E_CPU1_P0_RX_DN<12>")
	)
	(segment
		(start 108.539788 -277.832058)
		(end 108.51007 -277.81504)
		(width 0.1143)
		(layer "In15.Cu")
		(net "P5E_CPU1_P0_RX_DN<12>")
	)
	(segment
		(start 62.666626 -385.334764)
		(end 62.666626 -385.163822)
		(width 0.14224)
		(layer "In15.Cu")
		(net "P5E_CPU1_P0_RX_DN<12>")
	)
	(segment
		(start 162.7251 -360.5911)
		(end 162.7251 -358.43464)
		(width 0.14224)
		(layer "In15.Cu")
		(net "P5E_CPU1_P0_RX_DN<12>")
	)
	(segment
		(start 108.505498 -292.3921)
		(end 108.468922 -292.370764)
		(width 0.1143)
		(layer "In15.Cu")
		(net "P5E_CPU1_P0_RX_DN<12>")
	)
	(segment
		(start 108.507022 -275.219414)
		(end 108.508038 -275.218906)
		(width 0.1143)
		(layer "In15.Cu")
		(net "P5E_CPU1_P0_RX_DN<12>")
	)
	(segment
		(start 108.477558 -291.436552)
		(end 108.478574 -291.436044)
		(width 0.1143)
		(layer "In15.Cu")
		(net "P5E_CPU1_P0_RX_DN<12>")
	)
	(segment
		(start 62.35446 -384.234944)
		(end 62.658498 -383.93116)
		(width 0.14224)
		(layer "In15.Cu")
		(net "P5E_CPU1_P0_RX_DN<12>")
	)
	(segment
		(start 108.539788 -279.45207)
		(end 108.51007 -279.435052)
		(width 0.1143)
		(layer "In15.Cu")
		(net "P5E_CPU1_P0_RX_DN<12>")
	)
	(segment
		(start 108.5088 -284.294326)
		(end 108.508038 -284.293818)
		(width 0.1143)
		(layer "In15.Cu")
		(net "P5E_CPU1_P0_RX_DN<12>")
	)
	(segment
		(start 108.508038 -276.838918)
		(end 108.5088 -276.83841)
		(width 0.1143)
		(layer "In15.Cu")
		(net "P5E_CPU1_P0_RX_DN<12>")
	)
	(segment
		(start 108.51007 -277.81504)
		(end 108.5088 -277.814278)
		(width 0.1143)
		(layer "In15.Cu")
		(net "P5E_CPU1_P0_RX_DN<12>")
	)
	(segment
		(start 108.468922 -288.201608)
		(end 108.508038 -288.178748)
		(width 0.1143)
		(layer "In15.Cu")
		(net "P5E_CPU1_P0_RX_DN<12>")
	)
	(segment
		(start 108.504482 -273.600926)
		(end 108.505498 -273.600418)
		(width 0.1143)
		(layer "In15.Cu")
		(net "P5E_CPU1_P0_RX_DN<12>")
	)
	(segment
		(start 120.139714 -329.829668)
		(end 108.317284 -301.286164)
		(width 0.14224)
		(layer "In15.Cu")
		(net "P5E_CPU1_P0_RX_DN<12>")
	)
	(segment
		(start 108.505498 -275.22043)
		(end 108.507022 -275.219414)
		(width 0.1143)
		(layer "In15.Cu")
		(net "P5E_CPU1_P0_RX_DN<12>")
	)
	(segment
		(start 108.51007 -278.45766)
		(end 108.539788 -278.440642)
		(width 0.1143)
		(layer "In15.Cu")
		(net "P5E_CPU1_P0_RX_DN<12>")
	)
	(segment
		(start 108.508038 -287.533842)
		(end 108.471462 -287.512506)
		(width 0.1143)
		(layer "In15.Cu")
		(net "P5E_CPU1_P0_RX_DN<12>")
	)
	(segment
		(start 108.5088 -294.014144)
		(end 108.508038 -294.013636)
		(width 0.1143)
		(layer "In15.Cu")
		(net "P5E_CPU1_P0_RX_DN<12>")
	)
	(segment
		(start 108.468922 -289.82162)
		(end 108.539788 -289.780472)
		(width 0.1143)
		(layer "In15.Cu")
		(net "P5E_CPU1_P0_RX_DN<12>")
	)
	(segment
		(start 108.5088 -279.43429)
		(end 108.508038 -279.433782)
		(width 0.1143)
		(layer "In15.Cu")
		(net "P5E_CPU1_P0_RX_DN<12>")
	)
	(segment
		(start 108.504482 -276.84095)
		(end 108.505498 -276.840442)
		(width 0.1143)
		(layer "In15.Cu")
		(net "P5E_CPU1_P0_RX_DN<12>")
	)
	(segment
		(start 108.51007 -280.077672)
		(end 108.539788 -280.060654)
		(width 0.1143)
		(layer "In15.Cu")
		(net "P5E_CPU1_P0_RX_DN<12>")
	)
	(segment
		(start 108.504482 -280.080974)
		(end 108.505498 -280.080466)
		(width 0.1143)
		(layer "In15.Cu")
		(net "P5E_CPU1_P0_RX_DN<12>")
	)
	(segment
		(start 62.666626 -385.163822)
		(end 62.349634 -384.84683)
		(width 0.14224)
		(layer "In15.Cu")
		(net "P5E_CPU1_P0_RX_DN<12>")
	)
	(segment
		(start 108.5088 -290.77412)
		(end 108.508038 -290.773612)
		(width 0.1143)
		(layer "In15.Cu")
		(net "P5E_CPU1_P0_RX_DN<12>")
	)
	(segment
		(start 162.58794 -362.28274)
		(end 162.58794 -361.85602)
		(width 0.14224)
		(layer "In15.Cu")
		(net "P5E_CPU1_P0_RX_DN<12>")
	)
	(segment
		(start 108.508038 -294.013636)
		(end 108.507022 -294.013128)
		(width 0.1143)
		(layer "In15.Cu")
		(net "P5E_CPU1_P0_RX_DN<12>")
	)
	(segment
		(start 108.505498 -283.32049)
		(end 108.507022 -283.319474)
		(width 0.1143)
		(layer "In15.Cu")
		(net "P5E_CPU1_P0_RX_DN<12>")
	)
	(segment
		(start 108.939076 -272.811748)
		(end 108.978192 -272.788888)
		(width 0.1143)
		(layer "In15.Cu")
		(net "P5E_CPU1_P0_RX_DN<12>")
	)
	(segment
		(start 108.507022 -283.319474)
		(end 108.508038 -283.318966)
		(width 0.1143)
		(layer "In15.Cu")
		(net "P5E_CPU1_P0_RX_DN<12>")
	)
	(segment
		(start 108.505498 -280.080466)
		(end 108.507022 -280.07945)
		(width 0.1143)
		(layer "In15.Cu")
		(net "P5E_CPU1_P0_RX_DN<12>")
	)
	(segment
		(start 108.468922 -276.861778)
		(end 108.504482 -276.84095)
		(width 0.1143)
		(layer "In15.Cu")
		(net "P5E_CPU1_P0_RX_DN<12>")
	)
	(segment
		(start 108.508038 -278.45893)
		(end 108.5088 -278.458422)
		(width 0.1143)
		(layer "In15.Cu")
		(net "P5E_CPU1_P0_RX_DN<12>")
	)
	(segment
		(start 108.508038 -273.598894)
		(end 108.5088 -273.598386)
		(width 0.1143)
		(layer "In15.Cu")
		(net "P5E_CPU1_P0_RX_DN<12>")
	)
	(segment
		(start 62.191392 -385.31038)
		(end 62.544452 -385.405376)
		(width 0.14224)
		(layer "In15.Cu")
		(net "P5E_CPU1_P0_RX_DN<12>")
	)
	(segment
		(start 108.502196 -276.190202)
		(end 108.476796 -276.17547)
		(width 0.1143)
		(layer "In15.Cu")
		(net "P5E_CPU1_P0_RX_DN<12>")
	)
	(segment
		(start 108.5088 -278.458422)
		(end 108.51007 -278.45766)
		(width 0.1143)
		(layer "In15.Cu")
		(net "P5E_CPU1_P0_RX_DN<12>")
	)
	(segment
		(start 108.507022 -289.153092)
		(end 108.505498 -289.152076)
		(width 0.1143)
		(layer "In15.Cu")
		(net "P5E_CPU1_P0_RX_DN<12>")
	)
	(segment
		(start 76.226416 -365.399574)
		(end 107.966764 -365.399574)
		(width 0.14224)
		(layer "In15.Cu")
		(net "P5E_CPU1_P0_RX_DN<12>")
	)
	(segment
		(start 108.504482 -275.220938)
		(end 108.505498 -275.22043)
		(width 0.1143)
		(layer "In15.Cu")
		(net "P5E_CPU1_P0_RX_DN<12>")
	)
	(arc
		(start 162.373818 -364.787942)
		(mid 162.622212 -364.685054)
		(end 162.7251 -364.43666)
		(width 0.14224)
		(layer "In15.Cu")
		(net "P5E_CPU1_P0_RX_DN<12>")
	)
	(arc
		(start 108.468922 -293.990776)
		(mid 108.225595 -293.52621)
		(end 108.468922 -293.061644)
		(width 0.1143)
		(layer "In15.Cu")
		(net "P5E_CPU1_P0_RX_DN<12>")
	)
	(arc
		(start 108.539788 -278.440642)
		(mid 108.695716 -278.13635)
		(end 108.539788 -277.832058)
		(width 0.1143)
		(layer "In15.Cu")
		(net "P5E_CPU1_P0_RX_DN<12>")
	)
	(arc
		(start 75.610212 -365.595408)
		(mid 75.713436 -365.514395)
		(end 75.83297 -365.46028)
		(width 0.14224)
		(layer "In15.Cu")
		(net "P5E_CPU1_P0_RX_DN<12>")
	)
	(arc
		(start 108.539788 -289.780472)
		(mid 108.695716 -289.47618)
		(end 108.539788 -289.171888)
		(width 0.1143)
		(layer "In15.Cu")
		(net "P5E_CPU1_P0_RX_DN<12>")
	)
	(arc
		(start 108.540042 -276.820376)
		(mid 108.695853 -276.512884)
		(end 108.534454 -276.208236)
		(width 0.1143)
		(layer "In15.Cu")
		(net "P5E_CPU1_P0_RX_DN<12>")
	)
	(arc
		(start 75.83297 -365.46028)
		(mid 76.027371 -365.414877)
		(end 76.226416 -365.399574)
		(width 0.14224)
		(layer "In15.Cu")
		(net "P5E_CPU1_P0_RX_DN<12>")
	)
	(arc
		(start 108.468922 -281.030934)
		(mid 108.225595 -280.566368)
		(end 108.468922 -280.101802)
		(width 0.1143)
		(layer "In15.Cu")
		(net "P5E_CPU1_P0_RX_DN<12>")
	)
	(arc
		(start 108.539788 -283.300678)
		(mid 108.695716 -282.996386)
		(end 108.539788 -282.692094)
		(width 0.1143)
		(layer "In15.Cu")
		(net "P5E_CPU1_P0_RX_DN<12>")
	)
	(arc
		(start 108.695744 -287.856422)
		(mid 108.654489 -287.685451)
		(end 108.539788 -287.55213)
		(width 0.1143)
		(layer "In15.Cu")
		(net "P5E_CPU1_P0_RX_DN<12>")
	)
	(arc
		(start 151.478996 -355.583998)
		(mid 151.432069 -355.541469)
		(end 151.381206 -355.503734)
		(width 0.14224)
		(layer "In15.Cu")
		(net "P5E_CPU1_P0_RX_DN<12>")
	)
	(arc
		(start 108.468922 -282.650946)
		(mid 108.225595 -282.18638)
		(end 108.468922 -281.721814)
		(width 0.1143)
		(layer "In15.Cu")
		(net "P5E_CPU1_P0_RX_DN<12>")
	)
	(arc
		(start 108.540042 -275.200364)
		(mid 108.695853 -274.892872)
		(end 108.534454 -274.588224)
		(width 0.1143)
		(layer "In15.Cu")
		(net "P5E_CPU1_P0_RX_DN<12>")
	)
	(arc
		(start 108.541566 -286.539178)
		(mid 108.654973 -286.406289)
		(end 108.695744 -286.23641)
		(width 0.1143)
		(layer "In15.Cu")
		(net "P5E_CPU1_P0_RX_DN<12>")
	)
	(arc
		(start 108.468922 -285.89097)
		(mid 108.225595 -285.426404)
		(end 108.468922 -284.961838)
		(width 0.1143)
		(layer "In15.Cu")
		(net "P5E_CPU1_P0_RX_DN<12>")
	)
	(arc
		(start 108.539788 -293.020496)
		(mid 108.695716 -292.716204)
		(end 108.539788 -292.411912)
		(width 0.1143)
		(layer "In15.Cu")
		(net "P5E_CPU1_P0_RX_DN<12>")
	)
	(arc
		(start 108.539788 -280.060654)
		(mid 108.695716 -279.756362)
		(end 108.539788 -279.45207)
		(width 0.1143)
		(layer "In15.Cu")
		(net "P5E_CPU1_P0_RX_DN<12>")
	)
	(arc
		(start 108.468922 -274.550886)
		(mid 108.225595 -274.08632)
		(end 108.468922 -273.621754)
		(width 0.1143)
		(layer "In15.Cu")
		(net "P5E_CPU1_P0_RX_DN<12>")
	)
	(arc
		(start 108.695744 -273.276314)
		(mid 108.760259 -273.014095)
		(end 108.939076 -272.811748)
		(width 0.1143)
		(layer "In15.Cu")
		(net "P5E_CPU1_P0_RX_DN<12>")
	)
	(arc
		(start 108.539788 -273.580606)
		(mid 108.654464 -273.447272)
		(end 108.695744 -273.276314)
		(width 0.1143)
		(layer "In15.Cu")
		(net "P5E_CPU1_P0_RX_DN<12>")
	)
	(arc
		(start 109.008672 -272.771108)
		(mid 109.106437 -272.668132)
		(end 109.158786 -272.536158)
		(width 0.1143)
		(layer "In15.Cu")
		(net "P5E_CPU1_P0_RX_DN<12>")
	)
	(arc
		(start 108.468922 -290.750752)
		(mid 108.225595 -290.286186)
		(end 108.468922 -289.82162)
		(width 0.1143)
		(layer "In15.Cu")
		(net "P5E_CPU1_P0_RX_DN<12>")
	)
	(arc
		(start 108.22559 -295.146222)
		(mid 108.290105 -294.884003)
		(end 108.468922 -294.681656)
		(width 0.1143)
		(layer "In15.Cu")
		(net "P5E_CPU1_P0_RX_DN<12>")
	)
	(arc
		(start 108.468922 -277.79091)
		(mid 108.225595 -277.326344)
		(end 108.468922 -276.861778)
		(width 0.1143)
		(layer "In15.Cu")
		(net "P5E_CPU1_P0_RX_DN<12>")
	)
	(arc
		(start 108.468922 -279.410922)
		(mid 108.225595 -278.946356)
		(end 108.468922 -278.48179)
		(width 0.1143)
		(layer "In15.Cu")
		(net "P5E_CPU1_P0_RX_DN<12>")
	)
	(arc
		(start 108.539788 -281.680666)
		(mid 108.695716 -281.376374)
		(end 108.539788 -281.072082)
		(width 0.1143)
		(layer "In15.Cu")
		(net "P5E_CPU1_P0_RX_DN<12>")
	)
	(arc
		(start 108.539788 -284.92069)
		(mid 108.695716 -284.616398)
		(end 108.539788 -284.312106)
		(width 0.1143)
		(layer "In15.Cu")
		(net "P5E_CPU1_P0_RX_DN<12>")
	)
	(arc
		(start 108.539788 -294.640508)
		(mid 108.695716 -294.336216)
		(end 108.539788 -294.031924)
		(width 0.1143)
		(layer "In15.Cu")
		(net "P5E_CPU1_P0_RX_DN<12>")
	)
	(arc
		(start 155.063952 -358.176068)
		(mid 154.146661 -357.993607)
		(end 153.36901 -357.474012)
		(width 0.14224)
		(layer "In15.Cu")
		(net "P5E_CPU1_P0_RX_DN<12>")
	)
	(arc
		(start 108.539788 -291.400484)
		(mid 108.695716 -291.096192)
		(end 108.539788 -290.7919)
		(width 0.1143)
		(layer "In15.Cu")
		(net "P5E_CPU1_P0_RX_DN<12>")
	)
	(arc
		(start 108.468922 -276.170898)
		(mid 108.225595 -275.706332)
		(end 108.468922 -275.241766)
		(width 0.1143)
		(layer "In15.Cu")
		(net "P5E_CPU1_P0_RX_DN<12>")
	)
	(arc
		(start 120.64619 -330.620116)
		(mid 120.535407 -330.499254)
		(end 120.435624 -330.369164)
		(width 0.14224)
		(layer "In15.Cu")
		(net "P5E_CPU1_P0_RX_DN<12>")
	)
	(arc
		(start 162.7251 -358.43464)
		(mid 162.649366 -358.251802)
		(end 162.466528 -358.176068)
		(width 0.14224)
		(layer "In15.Cu")
		(net "P5E_CPU1_P0_RX_DN<12>")
	)
	(arc
		(start 108.695744 -286.23641)
		(mid 108.654489 -286.065439)
		(end 108.539788 -285.932118)
		(width 0.1143)
		(layer "In15.Cu")
		(net "P5E_CPU1_P0_RX_DN<12>")
	)
	(arc
		(start 107.966764 -365.399574)
		(mid 108.492132 -365.32149)
		(end 108.972096 -365.094012)
		(width 0.14224)
		(layer "In15.Cu")
		(net "P5E_CPU1_P0_RX_DN<12>")
	)
	(arc
		(start 108.185966 -300.77029)
		(mid 108.181451 -300.713727)
		(end 108.17987 -300.657006)
		(width 0.14224)
		(layer "In15.Cu")
		(net "P5E_CPU1_P0_RX_DN<12>")
	)
	(arc
		(start 108.468922 -284.270958)
		(mid 108.225595 -283.806392)
		(end 108.468922 -283.341826)
		(width 0.1143)
		(layer "In15.Cu")
		(net "P5E_CPU1_P0_RX_DN<12>")
	)
	(arc
		(start 120.435624 -330.369164)
		(mid 120.272942 -330.107493)
		(end 120.139714 -329.829668)
		(width 0.14224)
		(layer "In15.Cu")
		(net "P5E_CPU1_P0_RX_DN<12>")
	)
	(arc
		(start 62.658498 -382.164082)
		(mid 62.682234 -382.008252)
		(end 62.751462 -381.866648)
		(width 0.14224)
		(layer "In15.Cu")
		(net "P5E_CPU1_P0_RX_DN<12>")
	)
	(arc
		(start 108.468922 -289.13074)
		(mid 108.225595 -288.666174)
		(end 108.468922 -288.201608)
		(width 0.1143)
		(layer "In15.Cu")
		(net "P5E_CPU1_P0_RX_DN<12>")
	)
	(arc
		(start 108.22559 -287.046162)
		(mid 108.290105 -286.783943)
		(end 108.468922 -286.581596)
		(width 0.1143)
		(layer "In15.Cu")
		(net "P5E_CPU1_P0_RX_DN<12>")
	)
	(arc
		(start 108.468922 -292.370764)
		(mid 108.225595 -291.906198)
		(end 108.468922 -291.441632)
		(width 0.1143)
		(layer "In15.Cu")
		(net "P5E_CPU1_P0_RX_DN<12>")
	)
	(arc
		(start 108.541566 -288.15919)
		(mid 108.654973 -288.026301)
		(end 108.695744 -287.856422)
		(width 0.1143)
		(layer "In15.Cu")
		(net "P5E_CPU1_P0_RX_DN<12>")
	)
	(arc
		(start 108.972096 -365.094012)
		(mid 109.452254 -364.866168)
		(end 109.977936 -364.787942)
		(width 0.14224)
		(layer "In15.Cu")
		(net "P5E_CPU1_P0_RX_DN<12>")
	)
	(arc
		(start 108.317284 -301.286164)
		(mid 108.233109 -301.032941)
		(end 108.185966 -300.77029)
		(width 0.14224)
		(layer "In15.Cu")
		(net "P5E_CPU1_P0_RX_DN<12>")
	)
	(arc
		(start 108.471462 -287.512506)
		(mid 108.29081 -287.309761)
		(end 108.22559 -287.046162)
		(width 0.1143)
		(layer "In15.Cu")
		(net "P5E_CPU1_P0_RX_DN<12>")
	)
	(segment
		(start 60.470542 -385.31038)
		(end 60.991242 -385.31038)
		(width 0.127)
		(layer "F.Cu")
		(net "P5E_CPU1_P0_RX_DN<11>")
	)
	(segment
		(start 106.907838 -269.770352)
		(end 106.440986 -270.03629)
		(width 0.12954)
		(layer "F.Cu")
		(net "P5E_CPU1_P0_RX_DN<11>")
	)
	(segment
		(start 107.575604 -283.314648)
		(end 107.57662 -283.31414)
		(width 0.1143)
		(layer "In15.Cu")
		(net "P5E_CPU1_P0_RX_DN<11>")
	)
	(segment
		(start 107.57916 -292.399974)
		(end 107.57662 -292.398704)
		(width 0.1143)
		(layer "In15.Cu")
		(net "P5E_CPU1_P0_RX_DN<11>")
	)
	(segment
		(start 107.56519 -284.29204)
		(end 107.529122 -284.271212)
		(width 0.1143)
		(layer "In15.Cu")
		(net "P5E_CPU1_P0_RX_DN<11>")
	)
	(segment
		(start 107.599734 -276.212046)
		(end 107.570016 -276.195028)
		(width 0.1143)
		(layer "In15.Cu")
		(net "P5E_CPU1_P0_RX_DN<11>")
	)
	(segment
		(start 107.568746 -282.674314)
		(end 107.567984 -282.673806)
		(width 0.1143)
		(layer "In15.Cu")
		(net "P5E_CPU1_P0_RX_DN<11>")
	)
	(segment
		(start 161.234628 -360.32948)
		(end 161.234628 -359.546906)
		(width 0.14224)
		(layer "In15.Cu")
		(net "P5E_CPU1_P0_RX_DN<11>")
	)
	(segment
		(start 107.056936 -296.421556)
		(end 106.909108 -296.273728)
		(width 0.1143)
		(layer "In15.Cu")
		(net "P5E_CPU1_P0_RX_DN<11>")
	)
	(segment
		(start 107.567984 -285.91383)
		(end 107.531662 -285.892748)
		(width 0.1143)
		(layer "In15.Cu")
		(net "P5E_CPU1_P0_RX_DN<11>")
	)
	(segment
		(start 107.57154 -292.395656)
		(end 107.570524 -292.395148)
		(width 0.1143)
		(layer "In15.Cu")
		(net "P5E_CPU1_P0_RX_DN<11>")
	)
	(segment
		(start 107.56773 -291.419026)
		(end 107.567984 -291.418772)
		(width 0.1143)
		(layer "In15.Cu")
		(net "P5E_CPU1_P0_RX_DN<11>")
	)
	(segment
		(start 61.154564 -384.234944)
		(end 61.458602 -383.93116)
		(width 0.14224)
		(layer "In15.Cu")
		(net "P5E_CPU1_P0_RX_DN<11>")
	)
	(segment
		(start 161.097468 -361.62742)
		(end 161.234628 -361.49026)
		(width 0.14224)
		(layer "In15.Cu")
		(net "P5E_CPU1_P0_RX_DN<11>")
	)
	(segment
		(start 107.533186 -287.510982)
		(end 107.412536 -287.390078)
		(width 0.1143)
		(layer "In15.Cu")
		(net "P5E_CPU1_P0_RX_DN<11>")
	)
	(segment
		(start 107.572048 -278.456644)
		(end 107.573064 -278.456136)
		(width 0.1143)
		(layer "In15.Cu")
		(net "P5E_CPU1_P0_RX_DN<11>")
	)
	(segment
		(start 107.570016 -276.195028)
		(end 107.568746 -276.194266)
		(width 0.1143)
		(layer "In15.Cu")
		(net "P5E_CPU1_P0_RX_DN<11>")
	)
	(segment
		(start 75.884278 -364.382304)
		(end 106.810302 -364.382304)
		(width 0.14224)
		(layer "In15.Cu")
		(net "P5E_CPU1_P0_RX_DN<11>")
	)
	(segment
		(start 107.599734 -290.7919)
		(end 107.577382 -290.778946)
		(width 0.1143)
		(layer "In15.Cu")
		(net "P5E_CPU1_P0_RX_DN<11>")
	)
	(segment
		(start 107.577382 -290.778946)
		(end 107.575096 -290.777676)
		(width 0.1143)
		(layer "In15.Cu")
		(net "P5E_CPU1_P0_RX_DN<11>")
	)
	(segment
		(start 107.56519 -282.672028)
		(end 107.529122 -282.6512)
		(width 0.1143)
		(layer "In15.Cu")
		(net "P5E_CPU1_P0_RX_DN<11>")
	)
	(segment
		(start 107.529122 -283.341572)
		(end 107.569508 -283.318204)
		(width 0.1143)
		(layer "In15.Cu")
		(net "P5E_CPU1_P0_RX_DN<11>")
	)
	(segment
		(start 107.573826 -276.835616)
		(end 107.599734 -276.82063)
		(width 0.1143)
		(layer "In15.Cu")
		(net "P5E_CPU1_P0_RX_DN<11>")
	)
	(segment
		(start 159.84728 -363.832394)
		(end 159.98444 -363.695234)
		(width 0.14224)
		(layer "In15.Cu")
		(net "P5E_CPU1_P0_RX_DN<11>")
	)
	(segment
		(start 107.568746 -285.914338)
		(end 107.567984 -285.91383)
		(width 0.1143)
		(layer "In15.Cu")
		(net "P5E_CPU1_P0_RX_DN<11>")
	)
	(segment
		(start 107.533186 -273.61896)
		(end 107.567984 -273.598894)
		(width 0.1143)
		(layer "In15.Cu")
		(net "P5E_CPU1_P0_RX_DN<11>")
	)
	(segment
		(start 107.567984 -277.81377)
		(end 107.56519 -277.811992)
		(width 0.1143)
		(layer "In15.Cu")
		(net "P5E_CPU1_P0_RX_DN<11>")
	)
	(segment
		(start 61.46673 -385.334764)
		(end 61.46673 -385.163822)
		(width 0.14224)
		(layer "In15.Cu")
		(net "P5E_CPU1_P0_RX_DN<11>")
	)
	(segment
		(start 107.568746 -274.574254)
		(end 107.567984 -274.573746)
		(width 0.1143)
		(layer "In15.Cu")
		(net "P5E_CPU1_P0_RX_DN<11>")
	)
	(segment
		(start 107.589828 -289.78606)
		(end 107.599734 -289.780472)
		(width 0.1143)
		(layer "In15.Cu")
		(net "P5E_CPU1_P0_RX_DN<11>")
	)
	(segment
		(start 107.568746 -271.978374)
		(end 107.570016 -271.977612)
		(width 0.1143)
		(layer "In15.Cu")
		(net "P5E_CPU1_P0_RX_DN<11>")
	)
	(segment
		(start 72.37984 -367.462054)
		(end 75.246484 -364.59541)
		(width 0.14224)
		(layer "In15.Cu")
		(net "P5E_CPU1_P0_RX_DN<11>")
	)
	(segment
		(start 107.531662 -293.059866)
		(end 107.567984 -293.038784)
		(width 0.1143)
		(layer "In15.Cu")
		(net "P5E_CPU1_P0_RX_DN<11>")
	)
	(segment
		(start 107.568746 -273.598386)
		(end 107.570016 -273.597624)
		(width 0.1143)
		(layer "In15.Cu")
		(net "P5E_CPU1_P0_RX_DN<11>")
	)
	(segment
		(start 107.599734 -271.35201)
		(end 107.568746 -271.33423)
		(width 0.1143)
		(layer "In15.Cu")
		(net "P5E_CPU1_P0_RX_DN<11>")
	)
	(segment
		(start 107.599734 -294.031924)
		(end 107.574842 -294.0177)
		(width 0.1143)
		(layer "In15.Cu")
		(net "P5E_CPU1_P0_RX_DN<11>")
	)
	(segment
		(start 107.589828 -291.406072)
		(end 107.599734 -291.400484)
		(width 0.1143)
		(layer "In15.Cu")
		(net "P5E_CPU1_P0_RX_DN<11>")
	)
	(segment
		(start 107.57535 -275.214842)
		(end 107.599734 -275.200618)
		(width 0.1143)
		(layer "In15.Cu")
		(net "P5E_CPU1_P0_RX_DN<11>")
	)
	(segment
		(start 108.977176 -363.832394)
		(end 159.84728 -363.832394)
		(width 0.14224)
		(layer "In15.Cu")
		(net "P5E_CPU1_P0_RX_DN<11>")
	)
	(segment
		(start 107.573318 -290.77666)
		(end 107.572302 -290.776152)
		(width 0.1143)
		(layer "In15.Cu")
		(net "P5E_CPU1_P0_RX_DN<11>")
	)
	(segment
		(start 161.234628 -361.03052)
		(end 161.097468 -360.89336)
		(width 0.14224)
		(layer "In15.Cu")
		(net "P5E_CPU1_P0_RX_DN<11>")
	)
	(segment
		(start 107.567984 -273.598894)
		(end 107.568746 -273.598386)
		(width 0.1143)
		(layer "In15.Cu")
		(net "P5E_CPU1_P0_RX_DN<11>")
	)
	(segment
		(start 61.345064 -385.404868)
		(end 61.46673 -385.334764)
		(width 0.14224)
		(layer "In15.Cu")
		(net "P5E_CPU1_P0_RX_DN<11>")
	)
	(segment
		(start 107.57662 -281.694128)
		(end 107.599734 -281.680666)
		(width 0.1143)
		(layer "In15.Cu")
		(net "P5E_CPU1_P0_RX_DN<11>")
	)
	(segment
		(start 67.10426 -373.82196)
		(end 72.37984 -367.462054)
		(width 0.14224)
		(layer "In15.Cu")
		(net "P5E_CPU1_P0_RX_DN<11>")
	)
	(segment
		(start 107.567984 -271.978882)
		(end 107.568746 -271.978374)
		(width 0.1143)
		(layer "In15.Cu")
		(net "P5E_CPU1_P0_RX_DN<11>")
	)
	(segment
		(start 107.574842 -281.695144)
		(end 107.575604 -281.694636)
		(width 0.1143)
		(layer "In15.Cu")
		(net "P5E_CPU1_P0_RX_DN<11>")
	)
	(segment
		(start 107.568746 -271.33423)
		(end 107.567984 -271.333722)
		(width 0.1143)
		(layer "In15.Cu")
		(net "P5E_CPU1_P0_RX_DN<11>")
	)
	(segment
		(start 107.529122 -282.6512)
		(end 107.501182 -282.631134)
		(width 0.1143)
		(layer "In15.Cu")
		(net "P5E_CPU1_P0_RX_DN<11>")
	)
	(segment
		(start 160.41116 -363.695234)
		(end 160.54832 -363.832394)
		(width 0.14224)
		(layer "In15.Cu")
		(net "P5E_CPU1_P0_RX_DN<11>")
	)
	(segment
		(start 107.573826 -278.455628)
		(end 107.574842 -278.45512)
		(width 0.1143)
		(layer "In15.Cu")
		(net "P5E_CPU1_P0_RX_DN<11>")
	)
	(segment
		(start 107.589066 -291.40658)
		(end 107.589828 -291.406072)
		(width 0.1143)
		(layer "In15.Cu")
		(net "P5E_CPU1_P0_RX_DN<11>")
	)
	(segment
		(start 107.014264 -296.612564)
		(end 107.014264 -296.584116)
		(width 0.1143)
		(layer "In15.Cu")
		(net "P5E_CPU1_P0_RX_DN<11>")
	)
	(segment
		(start 107.57408 -290.777168)
		(end 107.573318 -290.77666)
		(width 0.1143)
		(layer "In15.Cu")
		(net "P5E_CPU1_P0_RX_DN<11>")
	)
	(segment
		(start 159.98444 -363.695234)
		(end 160.41116 -363.695234)
		(width 0.14224)
		(layer "In15.Cu")
		(net "P5E_CPU1_P0_RX_DN<11>")
	)
	(segment
		(start 107.567984 -282.673806)
		(end 107.56519 -282.672028)
		(width 0.1143)
		(layer "In15.Cu")
		(net "P5E_CPU1_P0_RX_DN<11>")
	)
	(segment
		(start 107.120436 -270.53667)
		(end 107.061762 -270.502888)
		(width 0.1143)
		(layer "In15.Cu")
		(net "P5E_CPU1_P0_RX_DN<11>")
	)
	(segment
		(start 107.57027 -283.317696)
		(end 107.571286 -283.317188)
		(width 0.1143)
		(layer "In15.Cu")
		(net "P5E_CPU1_P0_RX_DN<11>")
	)
	(segment
		(start 106.821732 -270.119094)
		(end 106.738928 -270.03629)
		(width 0.1143)
		(layer "In15.Cu")
		(net "P5E_CPU1_P0_RX_DN<11>")
	)
	(segment
		(start 61.46673 -385.163822)
		(end 61.149738 -384.84683)
		(width 0.14224)
		(layer "In15.Cu")
		(net "P5E_CPU1_P0_RX_DN<11>")
	)
	(segment
		(start 107.574588 -275.21535)
		(end 107.57535 -275.214842)
		(width 0.1143)
		(layer "In15.Cu")
		(net "P5E_CPU1_P0_RX_DN<11>")
	)
	(segment
		(start 161.234628 -362.1913)
		(end 161.097468 -362.05414)
		(width 0.14224)
		(layer "In15.Cu")
		(net "P5E_CPU1_P0_RX_DN<11>")
	)
	(segment
		(start 161.097468 -360.89336)
		(end 161.097468 -360.46664)
		(width 0.14224)
		(layer "In15.Cu")
		(net "P5E_CPU1_P0_RX_DN<11>")
	)
	(segment
		(start 107.57027 -281.697684)
		(end 107.571286 -281.697176)
		(width 0.1143)
		(layer "In15.Cu")
		(net "P5E_CPU1_P0_RX_DN<11>")
	)
	(segment
		(start 107.567984 -291.418772)
		(end 107.589066 -291.40658)
		(width 0.1143)
		(layer "In15.Cu")
		(net "P5E_CPU1_P0_RX_DN<11>")
	)
	(segment
		(start 107.573064 -278.456136)
		(end 107.573826 -278.455628)
		(width 0.1143)
		(layer "In15.Cu")
		(net "P5E_CPU1_P0_RX_DN<11>")
	)
	(segment
		(start 107.570016 -294.014906)
		(end 107.568746 -294.014144)
		(width 0.1143)
		(layer "In15.Cu")
		(net "P5E_CPU1_P0_RX_DN<11>")
	)
	(segment
		(start 107.567984 -294.013636)
		(end 107.533186 -293.99357)
		(width 0.1143)
		(layer "In15.Cu")
		(net "P5E_CPU1_P0_RX_DN<11>")
	)
	(segment
		(start 107.599734 -281.072082)
		(end 107.567984 -281.053794)
		(width 0.1143)
		(layer "In15.Cu")
		(net "P5E_CPU1_P0_RX_DN<11>")
	)
	(segment
		(start 107.52836 -280.101802)
		(end 107.599734 -280.060654)
		(width 0.1143)
		(layer "In15.Cu")
		(net "P5E_CPU1_P0_RX_DN<11>")
	)
	(segment
		(start 107.570016 -274.575016)
		(end 107.568746 -274.574254)
		(width 0.1143)
		(layer "In15.Cu")
		(net "P5E_CPU1_P0_RX_DN<11>")
	)
	(segment
		(start 107.570016 -282.675076)
		(end 107.568746 -282.674314)
		(width 0.1143)
		(layer "In15.Cu")
		(net "P5E_CPU1_P0_RX_DN<11>")
	)
	(segment
		(start 107.573064 -281.69616)
		(end 107.573826 -281.695652)
		(width 0.1143)
		(layer "In15.Cu")
		(net "P5E_CPU1_P0_RX_DN<11>")
	)
	(segment
		(start 107.56519 -276.19198)
		(end 107.529122 -276.171152)
		(width 0.1143)
		(layer "In15.Cu")
		(net "P5E_CPU1_P0_RX_DN<11>")
	)
	(segment
		(start 161.234628 -363.59084)
		(end 161.234628 -362.1913)
		(width 0.14224)
		(layer "In15.Cu")
		(net "P5E_CPU1_P0_RX_DN<11>")
	)
	(segment
		(start 107.599734 -287.55213)
		(end 107.567984 -287.533842)
		(width 0.1143)
		(layer "In15.Cu")
		(net "P5E_CPU1_P0_RX_DN<11>")
	)
	(segment
		(start 107.059984 -296.538396)
		(end 107.059984 -296.42435)
		(width 0.1143)
		(layer "In15.Cu")
		(net "P5E_CPU1_P0_RX_DN<11>")
	)
	(segment
		(start 107.55503 -288.186368)
		(end 107.567984 -288.178748)
		(width 0.1143)
		(layer "In15.Cu")
		(net "P5E_CPU1_P0_RX_DN<11>")
	)
	(segment
		(start 107.567984 -284.293818)
		(end 107.56519 -284.29204)
		(width 0.1143)
		(layer "In15.Cu")
		(net "P5E_CPU1_P0_RX_DN<11>")
	)
	(segment
		(start 107.572302 -294.016176)
		(end 107.57154 -294.015668)
		(width 0.1143)
		(layer "In15.Cu")
		(net "P5E_CPU1_P0_RX_DN<11>")
	)
	(segment
		(start 107.531662 -271.999964)
		(end 107.567984 -271.978882)
		(width 0.1143)
		(layer "In15.Cu")
		(net "P5E_CPU1_P0_RX_DN<11>")
	)
	(segment
		(start 161.234628 -361.49026)
		(end 161.234628 -361.03052)
		(width 0.14224)
		(layer "In15.Cu")
		(net "P5E_CPU1_P0_RX_DN<11>")
	)
	(segment
		(start 107.574842 -294.0177)
		(end 107.572302 -294.016176)
		(width 0.1143)
		(layer "In15.Cu")
		(net "P5E_CPU1_P0_RX_DN<11>")
	)
	(segment
		(start 107.569508 -281.698192)
		(end 107.57027 -281.697684)
		(width 0.1143)
		(layer "In15.Cu")
		(net "P5E_CPU1_P0_RX_DN<11>")
	)
	(segment
		(start 107.572302 -292.396164)
		(end 107.57154 -292.395656)
		(width 0.1143)
		(layer "In15.Cu")
		(net "P5E_CPU1_P0_RX_DN<11>")
	)
	(segment
		(start 107.529122 -277.791164)
		(end 107.501182 -277.771098)
		(width 0.1143)
		(layer "In15.Cu")
		(net "P5E_CPU1_P0_RX_DN<11>")
	)
	(segment
		(start 107.572048 -275.21662)
		(end 107.574588 -275.21535)
		(width 0.1143)
		(layer "In15.Cu")
		(net "P5E_CPU1_P0_RX_DN<11>")
	)
	(segment
		(start 107.57154 -290.775644)
		(end 107.570524 -290.775136)
		(width 0.1143)
		(layer "In15.Cu")
		(net "P5E_CPU1_P0_RX_DN<11>")
	)
	(segment
		(start 107.52836 -281.030934)
		(end 107.501436 -281.011376)
		(width 0.1143)
		(layer "In15.Cu")
		(net "P5E_CPU1_P0_RX_DN<11>")
	)
	(segment
		(start 107.568746 -277.814278)
		(end 107.567984 -277.81377)
		(width 0.1143)
		(layer "In15.Cu")
		(net "P5E_CPU1_P0_RX_DN<11>")
	)
	(segment
		(start 107.567984 -292.393624)
		(end 107.56773 -292.393624)
		(width 0.1143)
		(layer "In15.Cu")
		(net "P5E_CPU1_P0_RX_DN<11>")
	)
	(segment
		(start 107.575096 -290.777676)
		(end 107.57408 -290.777168)
		(width 0.1143)
		(layer "In15.Cu")
		(net "P5E_CPU1_P0_RX_DN<11>")
	)
	(segment
		(start 107.288584 -287.090612)
		(end 107.288584 -286.990028)
		(width 0.1143)
		(layer "In15.Cu")
		(net "P5E_CPU1_P0_RX_DN<11>")
	)
	(segment
		(start 107.57662 -292.398704)
		(end 107.57408 -292.39718)
		(width 0.1143)
		(layer "In15.Cu")
		(net "P5E_CPU1_P0_RX_DN<11>")
	)
	(segment
		(start 107.501182 -276.88159)
		(end 107.529122 -276.861524)
		(width 0.1143)
		(layer "In15.Cu")
		(net "P5E_CPU1_P0_RX_DN<11>")
	)
	(segment
		(start 107.568746 -294.014144)
		(end 107.567984 -294.013636)
		(width 0.1143)
		(layer "In15.Cu")
		(net "P5E_CPU1_P0_RX_DN<11>")
	)
	(segment
		(start 107.57027 -276.837648)
		(end 107.571286 -276.83714)
		(width 0.1143)
		(layer "In15.Cu")
		(net "P5E_CPU1_P0_RX_DN<11>")
	)
	(segment
		(start 61.530992 -381.895858)
		(end 67.10426 -373.82196)
		(width 0.14224)
		(layer "In15.Cu")
		(net "P5E_CPU1_P0_RX_DN<11>")
	)
	(segment
		(start 107.529122 -276.861524)
		(end 107.569508 -276.838156)
		(width 0.1143)
		(layer "In15.Cu")
		(net "P5E_CPU1_P0_RX_DN<11>")
	)
	(segment
		(start 107.570524 -290.775136)
		(end 107.569762 -290.774628)
		(width 0.1143)
		(layer "In15.Cu")
		(net "P5E_CPU1_P0_RX_DN<11>")
	)
	(segment
		(start 107.567984 -289.79876)
		(end 107.589066 -289.786568)
		(width 0.1143)
		(layer "In15.Cu")
		(net "P5E_CPU1_P0_RX_DN<11>")
	)
	(segment
		(start 107.589066 -289.786568)
		(end 107.589828 -289.78606)
		(width 0.1143)
		(layer "In15.Cu")
		(net "P5E_CPU1_P0_RX_DN<11>")
	)
	(segment
		(start 61.344556 -385.405376)
		(end 61.345064 -385.404868)
		(width 0.14224)
		(layer "In15.Cu")
		(net "P5E_CPU1_P0_RX_DN<11>")
	)
	(segment
		(start 107.572302 -290.776152)
		(end 107.57154 -290.775644)
		(width 0.1143)
		(layer "In15.Cu")
		(net "P5E_CPU1_P0_RX_DN<11>")
	)
	(segment
		(start 107.599734 -274.592034)
		(end 107.570016 -274.575016)
		(width 0.1143)
		(layer "In15.Cu")
		(net "P5E_CPU1_P0_RX_DN<11>")
	)
	(segment
		(start 107.567984 -274.573746)
		(end 107.531662 -274.552664)
		(width 0.1143)
		(layer "In15.Cu")
		(net "P5E_CPU1_P0_RX_DN<11>")
	)
	(segment
		(start 106.81589 -296.048938)
		(end 106.81589 -295.939464)
		(width 0.1143)
		(layer "In15.Cu")
		(net "P5E_CPU1_P0_RX_DN<11>")
	)
	(segment
		(start 107.567984 -271.333722)
		(end 107.531662 -271.31264)
		(width 0.1143)
		(layer "In15.Cu")
		(net "P5E_CPU1_P0_RX_DN<11>")
	)
	(segment
		(start 107.529122 -281.72156)
		(end 107.569508 -281.698192)
		(width 0.1143)
		(layer "In15.Cu")
		(net "P5E_CPU1_P0_RX_DN<11>")
	)
	(segment
		(start 107.567984 -272.953734)
		(end 107.531662 -272.932652)
		(width 0.1143)
		(layer "In15.Cu")
		(net "P5E_CPU1_P0_RX_DN<11>")
	)
	(segment
		(start 107.501182 -281.741626)
		(end 107.529122 -281.72156)
		(width 0.1143)
		(layer "In15.Cu")
		(net "P5E_CPU1_P0_RX_DN<11>")
	)
	(segment
		(start 107.571286 -283.317188)
		(end 107.572048 -283.31668)
		(width 0.1143)
		(layer "In15.Cu")
		(net "P5E_CPU1_P0_RX_DN<11>")
	)
	(segment
		(start 107.56519 -277.811992)
		(end 107.529122 -277.791164)
		(width 0.1143)
		(layer "In15.Cu")
		(net "P5E_CPU1_P0_RX_DN<11>")
	)
	(segment
		(start 107.575604 -278.454612)
		(end 107.57662 -278.454104)
		(width 0.1143)
		(layer "In15.Cu")
		(net "P5E_CPU1_P0_RX_DN<11>")
	)
	(segment
		(start 107.575604 -281.694636)
		(end 107.57662 -281.694128)
		(width 0.1143)
		(layer "In15.Cu")
		(net "P5E_CPU1_P0_RX_DN<11>")
	)
	(segment
		(start 107.568746 -284.294326)
		(end 107.567984 -284.293818)
		(width 0.1143)
		(layer "In15.Cu")
		(net "P5E_CPU1_P0_RX_DN<11>")
	)
	(segment
		(start 107.570016 -271.977612)
		(end 107.599734 -271.960594)
		(width 0.1143)
		(layer "In15.Cu")
		(net "P5E_CPU1_P0_RX_DN<11>")
	)
	(segment
		(start 61.149738 -384.84683)
		(end 61.154564 -384.234944)
		(width 0.14224)
		(layer "In15.Cu")
		(net "P5E_CPU1_P0_RX_DN<11>")
	)
	(segment
		(start 107.56773 -289.799014)
		(end 107.567984 -289.79876)
		(width 0.1143)
		(layer "In15.Cu")
		(net "P5E_CPU1_P0_RX_DN<11>")
	)
	(segment
		(start 107.570016 -277.81504)
		(end 107.568746 -277.814278)
		(width 0.1143)
		(layer "In15.Cu")
		(net "P5E_CPU1_P0_RX_DN<11>")
	)
	(segment
		(start 107.599734 -279.45207)
		(end 107.570016 -279.435052)
		(width 0.1143)
		(layer "In15.Cu")
		(net "P5E_CPU1_P0_RX_DN<11>")
	)
	(segment
		(start 119.228362 -330.59243)
		(end 107.092496 -301.293784)
		(width 0.14224)
		(layer "In15.Cu")
		(net "P5E_CPU1_P0_RX_DN<11>")
	)
	(segment
		(start 107.567984 -281.053794)
		(end 107.567984 -281.05354)
		(width 0.1143)
		(layer "In15.Cu")
		(net "P5E_CPU1_P0_RX_DN<11>")
	)
	(segment
		(start 107.568746 -292.394132)
		(end 107.567984 -292.393624)
		(width 0.1143)
		(layer "In15.Cu")
		(net "P5E_CPU1_P0_RX_DN<11>")
	)
	(segment
		(start 161.097468 -362.05414)
		(end 161.097468 -361.62742)
		(width 0.14224)
		(layer "In15.Cu")
		(net "P5E_CPU1_P0_RX_DN<11>")
	)
	(segment
		(start 107.04703 -295.49852)
		(end 107.117134 -295.45788)
		(width 0.1143)
		(layer "In15.Cu")
		(net "P5E_CPU1_P0_RX_DN<11>")
	)
	(segment
		(start 107.571286 -276.83714)
		(end 107.572048 -276.836632)
		(width 0.1143)
		(layer "In15.Cu")
		(net "P5E_CPU1_P0_RX_DN<11>")
	)
	(segment
		(start 107.570016 -285.9151)
		(end 107.568746 -285.914338)
		(width 0.1143)
		(layer "In15.Cu")
		(net "P5E_CPU1_P0_RX_DN<11>")
	)
	(segment
		(start 133.112764 -344.476832)
		(end 119.228362 -330.59243)
		(width 0.14224)
		(layer "In15.Cu")
		(net "P5E_CPU1_P0_RX_DN<11>")
	)
	(segment
		(start 107.568746 -279.43429)
		(end 107.567984 -279.433782)
		(width 0.1143)
		(layer "In15.Cu")
		(net "P5E_CPU1_P0_RX_DN<11>")
	)
	(segment
		(start 107.599734 -284.312106)
		(end 107.570016 -284.295088)
		(width 0.1143)
		(layer "In15.Cu")
		(net "P5E_CPU1_P0_RX_DN<11>")
	)
	(segment
		(start 152.800812 -358.409494)
		(end 150.64105 -356.249732)
		(width 0.14224)
		(layer "In15.Cu")
		(net "P5E_CPU1_P0_RX_DN<11>")
	)
	(segment
		(start 106.738928 -270.03629)
		(end 106.440986 -270.03629)
		(width 0.1143)
		(layer "In15.Cu")
		(net "P5E_CPU1_P0_RX_DN<11>")
	)
	(segment
		(start 107.568746 -272.954242)
		(end 107.567984 -272.953734)
		(width 0.1143)
		(layer "In15.Cu")
		(net "P5E_CPU1_P0_RX_DN<11>")
	)
	(segment
		(start 160.54832 -363.832394)
		(end 160.993074 -363.832394)
		(width 0.14224)
		(layer "In15.Cu")
		(net "P5E_CPU1_P0_RX_DN<11>")
	)
	(segment
		(start 107.567984 -293.038784)
		(end 107.599734 -293.020496)
		(width 0.1143)
		(layer "In15.Cu")
		(net "P5E_CPU1_P0_RX_DN<11>")
	)
	(segment
		(start 107.599734 -292.411912)
		(end 107.598972 -292.411404)
		(width 0.1143)
		(layer "In15.Cu")
		(net "P5E_CPU1_P0_RX_DN<11>")
	)
	(segment
		(start 61.458602 -383.93116)
		(end 61.458602 -382.128268)
		(width 0.14224)
		(layer "In15.Cu")
		(net "P5E_CPU1_P0_RX_DN<11>")
	)
	(segment
		(start 107.531662 -273.619976)
		(end 107.533186 -273.61896)
		(width 0.1143)
		(layer "In15.Cu")
		(net "P5E_CPU1_P0_RX_DN<11>")
	)
	(segment
		(start 107.570016 -273.597624)
		(end 107.599734 -273.580606)
		(width 0.1143)
		(layer "In15.Cu")
		(net "P5E_CPU1_P0_RX_DN<11>")
	)
	(segment
		(start 107.599734 -282.692094)
		(end 107.570016 -282.675076)
		(width 0.1143)
		(layer "In15.Cu")
		(net "P5E_CPU1_P0_RX_DN<11>")
	)
	(segment
		(start 107.567984 -279.433782)
		(end 107.56519 -279.432004)
		(width 0.1143)
		(layer "In15.Cu")
		(net "P5E_CPU1_P0_RX_DN<11>")
	)
	(segment
		(start 60.991242 -385.31038)
		(end 61.344556 -385.405376)
		(width 0.14224)
		(layer "In15.Cu")
		(net "P5E_CPU1_P0_RX_DN<11>")
	)
	(segment
		(start 107.573318 -292.396672)
		(end 107.572302 -292.396164)
		(width 0.1143)
		(layer "In15.Cu")
		(net "P5E_CPU1_P0_RX_DN<11>")
	)
	(segment
		(start 107.57027 -275.217636)
		(end 107.571286 -275.217128)
		(width 0.1143)
		(layer "In15.Cu")
		(net "P5E_CPU1_P0_RX_DN<11>")
	)
	(segment
		(start 107.572048 -276.836632)
		(end 107.573064 -276.836124)
		(width 0.1143)
		(layer "In15.Cu")
		(net "P5E_CPU1_P0_RX_DN<11>")
	)
	(segment
		(start 107.571286 -278.457152)
		(end 107.572048 -278.456644)
		(width 0.1143)
		(layer "In15.Cu")
		(net "P5E_CPU1_P0_RX_DN<11>")
	)
	(segment
		(start 107.061762 -270.502888)
		(end 107.058968 -270.500856)
		(width 0.1143)
		(layer "In15.Cu")
		(net "P5E_CPU1_P0_RX_DN<11>")
	)
	(segment
		(start 107.573064 -276.836124)
		(end 107.573826 -276.835616)
		(width 0.1143)
		(layer "In15.Cu")
		(net "P5E_CPU1_P0_RX_DN<11>")
	)
	(segment
		(start 107.574842 -278.45512)
		(end 107.575604 -278.454612)
		(width 0.1143)
		(layer "In15.Cu")
		(net "P5E_CPU1_P0_RX_DN<11>")
	)
	(segment
		(start 107.569762 -292.39464)
		(end 107.568746 -292.394132)
		(width 0.1143)
		(layer "In15.Cu")
		(net "P5E_CPU1_P0_RX_DN<11>")
	)
	(segment
		(start 107.569762 -290.774628)
		(end 107.568746 -290.77412)
		(width 0.1143)
		(layer "In15.Cu")
		(net "P5E_CPU1_P0_RX_DN<11>")
	)
	(segment
		(start 107.569508 -278.458168)
		(end 107.57027 -278.45766)
		(width 0.1143)
		(layer "In15.Cu")
		(net "P5E_CPU1_P0_RX_DN<11>")
	)
	(segment
		(start 107.57662 -283.31414)
		(end 107.599734 -283.300678)
		(width 0.1143)
		(layer "In15.Cu")
		(net "P5E_CPU1_P0_RX_DN<11>")
	)
	(segment
		(start 107.599734 -277.832058)
		(end 107.570016 -277.81504)
		(width 0.1143)
		(layer "In15.Cu")
		(net "P5E_CPU1_P0_RX_DN<11>")
	)
	(segment
		(start 107.501182 -275.261578)
		(end 107.529122 -275.241512)
		(width 0.1143)
		(layer "In15.Cu")
		(net "P5E_CPU1_P0_RX_DN<11>")
	)
	(segment
		(start 160.86582 -359.178098)
		(end 154.656282 -359.178098)
		(width 0.14224)
		(layer "In15.Cu")
		(net "P5E_CPU1_P0_RX_DN<11>")
	)
	(segment
		(start 107.598972 -292.411404)
		(end 107.57916 -292.399974)
		(width 0.1143)
		(layer "In15.Cu")
		(net "P5E_CPU1_P0_RX_DN<11>")
	)
	(segment
		(start 107.567984 -290.773612)
		(end 107.56773 -290.773612)
		(width 0.1143)
		(layer "In15.Cu")
		(net "P5E_CPU1_P0_RX_DN<11>")
	)
	(segment
		(start 107.531662 -286.579818)
		(end 107.601512 -286.539178)
		(width 0.1143)
		(layer "In15.Cu")
		(net "P5E_CPU1_P0_RX_DN<11>")
	)
	(segment
		(start 107.574842 -283.315156)
		(end 107.575604 -283.314648)
		(width 0.1143)
		(layer "In15.Cu")
		(net "P5E_CPU1_P0_RX_DN<11>")
	)
	(segment
		(start 107.573826 -283.315664)
		(end 107.574842 -283.315156)
		(width 0.1143)
		(layer "In15.Cu")
		(net "P5E_CPU1_P0_RX_DN<11>")
	)
	(segment
		(start 107.599734 -289.171888)
		(end 107.55503 -289.14598)
		(width 0.1143)
		(layer "In15.Cu")
		(net "P5E_CPU1_P0_RX_DN<11>")
	)
	(segment
		(start 107.567984 -287.533842)
		(end 107.533186 -287.510982)
		(width 0.1143)
		(layer "In15.Cu")
		(net "P5E_CPU1_P0_RX_DN<11>")
	)
	(segment
		(start 107.572048 -283.31668)
		(end 107.573064 -283.316172)
		(width 0.1143)
		(layer "In15.Cu")
		(net "P5E_CPU1_P0_RX_DN<11>")
	)
	(segment
		(start 107.568746 -290.77412)
		(end 107.567984 -290.773612)
		(width 0.1143)
		(layer "In15.Cu")
		(net "P5E_CPU1_P0_RX_DN<11>")
	)
	(segment
		(start 107.501182 -283.361638)
		(end 107.529122 -283.341572)
		(width 0.1143)
		(layer "In15.Cu")
		(net "P5E_CPU1_P0_RX_DN<11>")
	)
	(segment
		(start 107.57408 -292.39718)
		(end 107.573318 -292.396672)
		(width 0.1143)
		(layer "In15.Cu")
		(net "P5E_CPU1_P0_RX_DN<11>")
	)
	(segment
		(start 107.059984 -296.42435)
		(end 107.056936 -296.421556)
		(width 0.1143)
		(layer "In15.Cu")
		(net "P5E_CPU1_P0_RX_DN<11>")
	)
	(segment
		(start 107.599734 -285.932118)
		(end 107.570016 -285.9151)
		(width 0.1143)
		(layer "In15.Cu")
		(net "P5E_CPU1_P0_RX_DN<11>")
	)
	(segment
		(start 107.568746 -276.194266)
		(end 107.567984 -276.193758)
		(width 0.1143)
		(layer "In15.Cu")
		(net "P5E_CPU1_P0_RX_DN<11>")
	)
	(segment
		(start 107.567984 -281.05354)
		(end 107.52836 -281.030934)
		(width 0.1143)
		(layer "In15.Cu")
		(net "P5E_CPU1_P0_RX_DN<11>")
	)
	(segment
		(start 107.57027 -278.45766)
		(end 107.571286 -278.457152)
		(width 0.1143)
		(layer "In15.Cu")
		(net "P5E_CPU1_P0_RX_DN<11>")
	)
	(segment
		(start 107.56519 -279.432004)
		(end 107.529122 -279.411176)
		(width 0.1143)
		(layer "In15.Cu")
		(net "P5E_CPU1_P0_RX_DN<11>")
	)
	(segment
		(start 107.501182 -278.501602)
		(end 107.529122 -278.481536)
		(width 0.1143)
		(layer "In15.Cu")
		(net "P5E_CPU1_P0_RX_DN<11>")
	)
	(segment
		(start 107.529122 -275.241512)
		(end 107.569508 -275.218144)
		(width 0.1143)
		(layer "In15.Cu")
		(net "P5E_CPU1_P0_RX_DN<11>")
	)
	(segment
		(start 107.573064 -283.316172)
		(end 107.573826 -283.315664)
		(width 0.1143)
		(layer "In15.Cu")
		(net "P5E_CPU1_P0_RX_DN<11>")
	)
	(segment
		(start 107.570016 -279.435052)
		(end 107.568746 -279.43429)
		(width 0.1143)
		(layer "In15.Cu")
		(net "P5E_CPU1_P0_RX_DN<11>")
	)
	(segment
		(start 107.570524 -292.395148)
		(end 107.569762 -292.39464)
		(width 0.1143)
		(layer "In15.Cu")
		(net "P5E_CPU1_P0_RX_DN<11>")
	)
	(segment
		(start 107.501436 -280.12136)
		(end 107.52836 -280.101802)
		(width 0.1143)
		(layer "In15.Cu")
		(net "P5E_CPU1_P0_RX_DN<11>")
	)
	(segment
		(start 107.531662 -284.96006)
		(end 107.567984 -284.938978)
		(width 0.1143)
		(layer "In15.Cu")
		(net "P5E_CPU1_P0_RX_DN<11>")
	)
	(segment
		(start 107.529122 -284.271212)
		(end 107.501182 -284.251146)
		(width 0.1143)
		(layer "In15.Cu")
		(net "P5E_CPU1_P0_RX_DN<11>")
	)
	(segment
		(start 107.552998 -294.667432)
		(end 107.599734 -294.640508)
		(width 0.1143)
		(layer "In15.Cu")
		(net "P5E_CPU1_P0_RX_DN<11>")
	)
	(segment
		(start 107.57662 -278.454104)
		(end 107.599734 -278.440642)
		(width 0.1143)
		(layer "In15.Cu")
		(net "P5E_CPU1_P0_RX_DN<11>")
	)
	(segment
		(start 107.599734 -272.972022)
		(end 107.568746 -272.954242)
		(width 0.1143)
		(layer "In15.Cu")
		(net "P5E_CPU1_P0_RX_DN<11>")
	)
	(segment
		(start 107.570016 -284.295088)
		(end 107.568746 -284.294326)
		(width 0.1143)
		(layer "In15.Cu")
		(net "P5E_CPU1_P0_RX_DN<11>")
	)
	(segment
		(start 107.569508 -283.318204)
		(end 107.57027 -283.317696)
		(width 0.1143)
		(layer "In15.Cu")
		(net "P5E_CPU1_P0_RX_DN<11>")
	)
	(segment
		(start 107.567984 -284.938978)
		(end 107.599734 -284.92069)
		(width 0.1143)
		(layer "In15.Cu")
		(net "P5E_CPU1_P0_RX_DN<11>")
	)
	(segment
		(start 107.529122 -278.481536)
		(end 107.569508 -278.458168)
		(width 0.1143)
		(layer "In15.Cu")
		(net "P5E_CPU1_P0_RX_DN<11>")
	)
	(segment
		(start 107.567984 -276.193758)
		(end 107.56519 -276.19198)
		(width 0.1143)
		(layer "In15.Cu")
		(net "P5E_CPU1_P0_RX_DN<11>")
	)
	(segment
		(start 107.572048 -281.696668)
		(end 107.573064 -281.69616)
		(width 0.1143)
		(layer "In15.Cu")
		(net "P5E_CPU1_P0_RX_DN<11>")
	)
	(segment
		(start 107.571286 -281.697176)
		(end 107.572048 -281.696668)
		(width 0.1143)
		(layer "In15.Cu")
		(net "P5E_CPU1_P0_RX_DN<11>")
	)
	(segment
		(start 107.571286 -275.217128)
		(end 107.572048 -275.21662)
		(width 0.1143)
		(layer "In15.Cu")
		(net "P5E_CPU1_P0_RX_DN<11>")
	)
	(segment
		(start 107.567984 -288.178748)
		(end 107.601512 -288.15919)
		(width 0.1143)
		(layer "In15.Cu")
		(net "P5E_CPU1_P0_RX_DN<11>")
	)
	(segment
		(start 150.244302 -355.92385)
		(end 133.112764 -344.476832)
		(width 0.14224)
		(layer "In15.Cu")
		(net "P5E_CPU1_P0_RX_DN<11>")
	)
	(segment
		(start 161.097468 -360.46664)
		(end 161.234628 -360.32948)
		(width 0.14224)
		(layer "In15.Cu")
		(net "P5E_CPU1_P0_RX_DN<11>")
	)
	(segment
		(start 107.529122 -276.171152)
		(end 107.501182 -276.151086)
		(width 0.1143)
		(layer "In15.Cu")
		(net "P5E_CPU1_P0_RX_DN<11>")
	)
	(segment
		(start 107.014264 -296.584116)
		(end 107.059984 -296.538396)
		(width 0.1143)
		(layer "In15.Cu")
		(net "P5E_CPU1_P0_RX_DN<11>")
	)
	(segment
		(start 107.573826 -281.695652)
		(end 107.574842 -281.695144)
		(width 0.1143)
		(layer "In15.Cu")
		(net "P5E_CPU1_P0_RX_DN<11>")
	)
	(segment
		(start 107.014264 -300.735238)
		(end 107.014264 -296.612564)
		(width 0.14224)
		(layer "In15.Cu")
		(net "P5E_CPU1_P0_RX_DN<11>")
	)
	(segment
		(start 107.57154 -294.015668)
		(end 107.570016 -294.014906)
		(width 0.1143)
		(layer "In15.Cu")
		(net "P5E_CPU1_P0_RX_DN<11>")
	)
	(segment
		(start 107.569508 -276.838156)
		(end 107.57027 -276.837648)
		(width 0.1143)
		(layer "In15.Cu")
		(net "P5E_CPU1_P0_RX_DN<11>")
	)
	(segment
		(start 107.569508 -275.218144)
		(end 107.57027 -275.217636)
		(width 0.1143)
		(layer "In15.Cu")
		(net "P5E_CPU1_P0_RX_DN<11>")
	)
	(segment
		(start 107.529122 -279.411176)
		(end 107.501182 -279.39111)
		(width 0.1143)
		(layer "In15.Cu")
		(net "P5E_CPU1_P0_RX_DN<11>")
	)
	(segment
		(start 107.533186 -293.99357)
		(end 107.531662 -293.992554)
		(width 0.1143)
		(layer "In15.Cu")
		(net "P5E_CPU1_P0_RX_DN<11>")
	)
	(arc
		(start 107.599734 -284.92069)
		(mid 107.755662 -284.616398)
		(end 107.599734 -284.312106)
		(width 0.1143)
		(layer "In15.Cu")
		(net "P5E_CPU1_P0_RX_DN<11>")
	)
	(arc
		(start 107.599734 -280.060654)
		(mid 107.755662 -279.756362)
		(end 107.599734 -279.45207)
		(width 0.1143)
		(layer "In15.Cu")
		(net "P5E_CPU1_P0_RX_DN<11>")
	)
	(arc
		(start 107.531662 -274.552664)
		(mid 107.523998 -274.547393)
		(end 107.516422 -274.541996)
		(width 0.1143)
		(layer "In15.Cu")
		(net "P5E_CPU1_P0_RX_DN<11>")
	)
	(arc
		(start 107.601512 -288.15919)
		(mid 107.714919 -288.026301)
		(end 107.75569 -287.856422)
		(width 0.1143)
		(layer "In15.Cu")
		(net "P5E_CPU1_P0_RX_DN<11>")
	)
	(arc
		(start 106.825542 -270.141954)
		(mid 106.823519 -270.130544)
		(end 106.821732 -270.119094)
		(width 0.1143)
		(layer "In15.Cu")
		(net "P5E_CPU1_P0_RX_DN<11>")
	)
	(arc
		(start 107.599734 -278.440642)
		(mid 107.755662 -278.13635)
		(end 107.599734 -277.832058)
		(width 0.1143)
		(layer "In15.Cu")
		(net "P5E_CPU1_P0_RX_DN<11>")
	)
	(arc
		(start 107.058968 -270.500856)
		(mid 106.906981 -270.344348)
		(end 106.825542 -270.141954)
		(width 0.1143)
		(layer "In15.Cu")
		(net "P5E_CPU1_P0_RX_DN<11>")
	)
	(arc
		(start 107.75569 -286.23641)
		(mid 107.714435 -286.065439)
		(end 107.599734 -285.932118)
		(width 0.1143)
		(layer "In15.Cu")
		(net "P5E_CPU1_P0_RX_DN<11>")
	)
	(arc
		(start 75.246484 -364.59541)
		(mid 75.341735 -364.518239)
		(end 75.450954 -364.462568)
		(width 0.14224)
		(layer "In15.Cu")
		(net "P5E_CPU1_P0_RX_DN<11>")
	)
	(arc
		(start 107.599734 -276.82063)
		(mid 107.755662 -276.516338)
		(end 107.599734 -276.212046)
		(width 0.1143)
		(layer "In15.Cu")
		(net "P5E_CPU1_P0_RX_DN<11>")
	)
	(arc
		(start 107.412536 -287.390078)
		(mid 107.320784 -287.252668)
		(end 107.288584 -287.090612)
		(width 0.1143)
		(layer "In15.Cu")
		(net "P5E_CPU1_P0_RX_DN<11>")
	)
	(arc
		(start 107.501182 -277.771098)
		(mid 107.273182 -277.326344)
		(end 107.501182 -276.88159)
		(width 0.1143)
		(layer "In15.Cu")
		(net "P5E_CPU1_P0_RX_DN<11>")
	)
	(arc
		(start 107.599734 -291.400484)
		(mid 107.755662 -291.096192)
		(end 107.599734 -290.7919)
		(width 0.1143)
		(layer "In15.Cu")
		(net "P5E_CPU1_P0_RX_DN<11>")
	)
	(arc
		(start 107.599734 -271.960594)
		(mid 107.755662 -271.656302)
		(end 107.599734 -271.35201)
		(width 0.1143)
		(layer "In15.Cu")
		(net "P5E_CPU1_P0_RX_DN<11>")
	)
	(arc
		(start 107.56773 -290.773612)
		(mid 107.287303 -290.286376)
		(end 107.56773 -289.799014)
		(width 0.1143)
		(layer "In15.Cu")
		(net "P5E_CPU1_P0_RX_DN<11>")
	)
	(arc
		(start 107.092496 -301.293784)
		(mid 107.033893 -301.01724)
		(end 107.014264 -300.735238)
		(width 0.14224)
		(layer "In15.Cu")
		(net "P5E_CPU1_P0_RX_DN<11>")
	)
	(arc
		(start 107.599734 -283.300678)
		(mid 107.755662 -282.996386)
		(end 107.599734 -282.692094)
		(width 0.1143)
		(layer "In15.Cu")
		(net "P5E_CPU1_P0_RX_DN<11>")
	)
	(arc
		(start 107.516422 -293.981886)
		(mid 107.291251 -293.52621)
		(end 107.516422 -293.070534)
		(width 0.1143)
		(layer "In15.Cu")
		(net "P5E_CPU1_P0_RX_DN<11>")
	)
	(arc
		(start 107.28325 -270.836136)
		(mid 107.228346 -270.671999)
		(end 107.120436 -270.53667)
		(width 0.1143)
		(layer "In15.Cu")
		(net "P5E_CPU1_P0_RX_DN<11>")
	)
	(arc
		(start 107.285536 -270.864584)
		(mid 107.284804 -270.850327)
		(end 107.28325 -270.836136)
		(width 0.1143)
		(layer "In15.Cu")
		(net "P5E_CPU1_P0_RX_DN<11>")
	)
	(arc
		(start 107.516422 -274.541996)
		(mid 107.291251 -274.08632)
		(end 107.516422 -273.630644)
		(width 0.1143)
		(layer "In15.Cu")
		(net "P5E_CPU1_P0_RX_DN<11>")
	)
	(arc
		(start 107.516422 -272.921984)
		(mid 107.291251 -272.466308)
		(end 107.516422 -272.010632)
		(width 0.1143)
		(layer "In15.Cu")
		(net "P5E_CPU1_P0_RX_DN<11>")
	)
	(arc
		(start 107.599734 -281.680666)
		(mid 107.755662 -281.376374)
		(end 107.599734 -281.072082)
		(width 0.1143)
		(layer "In15.Cu")
		(net "P5E_CPU1_P0_RX_DN<11>")
	)
	(arc
		(start 107.288584 -286.990028)
		(mid 107.36475 -286.758039)
		(end 107.531662 -286.579818)
		(width 0.1143)
		(layer "In15.Cu")
		(net "P5E_CPU1_P0_RX_DN<11>")
	)
	(arc
		(start 107.531662 -293.992554)
		(mid 107.523998 -293.987283)
		(end 107.516422 -293.981886)
		(width 0.1143)
		(layer "In15.Cu")
		(net "P5E_CPU1_P0_RX_DN<11>")
	)
	(arc
		(start 150.64105 -356.249732)
		(mid 150.450688 -356.077038)
		(end 150.244302 -355.92385)
		(width 0.14224)
		(layer "In15.Cu")
		(net "P5E_CPU1_P0_RX_DN<11>")
	)
	(arc
		(start 161.234628 -359.546906)
		(mid 161.126607 -359.286119)
		(end 160.86582 -359.178098)
		(width 0.14224)
		(layer "In15.Cu")
		(net "P5E_CPU1_P0_RX_DN<11>")
	)
	(arc
		(start 107.501182 -276.151086)
		(mid 107.273182 -275.706332)
		(end 107.501182 -275.261578)
		(width 0.1143)
		(layer "In15.Cu")
		(net "P5E_CPU1_P0_RX_DN<11>")
	)
	(arc
		(start 107.56773 -292.393624)
		(mid 107.287303 -291.906388)
		(end 107.56773 -291.419026)
		(width 0.1143)
		(layer "In15.Cu")
		(net "P5E_CPU1_P0_RX_DN<11>")
	)
	(arc
		(start 107.501182 -282.631134)
		(mid 107.273182 -282.18638)
		(end 107.501182 -281.741626)
		(width 0.1143)
		(layer "In15.Cu")
		(net "P5E_CPU1_P0_RX_DN<11>")
	)
	(arc
		(start 107.516422 -284.970728)
		(mid 107.523998 -284.965332)
		(end 107.531662 -284.96006)
		(width 0.1143)
		(layer "In15.Cu")
		(net "P5E_CPU1_P0_RX_DN<11>")
	)
	(arc
		(start 107.599734 -289.780472)
		(mid 107.755662 -289.47618)
		(end 107.599734 -289.171888)
		(width 0.1143)
		(layer "In15.Cu")
		(net "P5E_CPU1_P0_RX_DN<11>")
	)
	(arc
		(start 108.804202 -363.846364)
		(mid 108.890401 -363.835823)
		(end 108.977176 -363.832394)
		(width 0.14224)
		(layer "In15.Cu")
		(net "P5E_CPU1_P0_RX_DN<11>")
	)
	(arc
		(start 107.601512 -286.539178)
		(mid 107.714919 -286.406289)
		(end 107.75569 -286.23641)
		(width 0.1143)
		(layer "In15.Cu")
		(net "P5E_CPU1_P0_RX_DN<11>")
	)
	(arc
		(start 107.531662 -272.932652)
		(mid 107.523998 -272.927381)
		(end 107.516422 -272.921984)
		(width 0.1143)
		(layer "In15.Cu")
		(net "P5E_CPU1_P0_RX_DN<11>")
	)
	(arc
		(start 107.117134 -295.45788)
		(mid 107.23181 -295.324546)
		(end 107.27309 -295.153588)
		(width 0.1143)
		(layer "In15.Cu")
		(net "P5E_CPU1_P0_RX_DN<11>")
	)
	(arc
		(start 107.94111 -364.1217)
		(mid 108.362695 -363.952804)
		(end 108.804202 -363.846364)
		(width 0.14224)
		(layer "In15.Cu")
		(net "P5E_CPU1_P0_RX_DN<11>")
	)
	(arc
		(start 154.656282 -359.178098)
		(mid 153.652107 -358.978337)
		(end 152.800812 -358.409494)
		(width 0.14224)
		(layer "In15.Cu")
		(net "P5E_CPU1_P0_RX_DN<11>")
	)
	(arc
		(start 107.516422 -273.630644)
		(mid 107.523998 -273.625248)
		(end 107.531662 -273.619976)
		(width 0.1143)
		(layer "In15.Cu")
		(net "P5E_CPU1_P0_RX_DN<11>")
	)
	(arc
		(start 61.458602 -382.128268)
		(mid 61.477122 -382.006559)
		(end 61.530992 -381.895858)
		(width 0.14224)
		(layer "In15.Cu")
		(net "P5E_CPU1_P0_RX_DN<11>")
	)
	(arc
		(start 107.516422 -272.010632)
		(mid 107.523998 -272.005236)
		(end 107.531662 -271.999964)
		(width 0.1143)
		(layer "In15.Cu")
		(net "P5E_CPU1_P0_RX_DN<11>")
	)
	(arc
		(start 107.75569 -287.856422)
		(mid 107.714435 -287.685451)
		(end 107.599734 -287.55213)
		(width 0.1143)
		(layer "In15.Cu")
		(net "P5E_CPU1_P0_RX_DN<11>")
	)
	(arc
		(start 107.599734 -293.020496)
		(mid 107.755662 -292.716204)
		(end 107.599734 -292.411912)
		(width 0.1143)
		(layer "In15.Cu")
		(net "P5E_CPU1_P0_RX_DN<11>")
	)
	(arc
		(start 106.810302 -364.382304)
		(mid 107.390521 -364.316298)
		(end 107.94111 -364.1217)
		(width 0.14224)
		(layer "In15.Cu")
		(net "P5E_CPU1_P0_RX_DN<11>")
	)
	(arc
		(start 107.516422 -293.070534)
		(mid 107.523998 -293.065138)
		(end 107.531662 -293.059866)
		(width 0.1143)
		(layer "In15.Cu")
		(net "P5E_CPU1_P0_RX_DN<11>")
	)
	(arc
		(start 160.993074 -363.832394)
		(mid 161.163878 -363.761644)
		(end 161.234628 -363.59084)
		(width 0.14224)
		(layer "In15.Cu")
		(net "P5E_CPU1_P0_RX_DN<11>")
	)
	(arc
		(start 107.55503 -289.14598)
		(mid 107.278697 -288.666174)
		(end 107.55503 -288.186368)
		(width 0.1143)
		(layer "In15.Cu")
		(net "P5E_CPU1_P0_RX_DN<11>")
	)
	(arc
		(start 106.81589 -295.939464)
		(mid 106.877175 -295.690535)
		(end 107.04703 -295.49852)
		(width 0.1143)
		(layer "In15.Cu")
		(net "P5E_CPU1_P0_RX_DN<11>")
	)
	(arc
		(start 107.501436 -281.011376)
		(mid 107.273758 -280.566368)
		(end 107.501436 -280.12136)
		(width 0.1143)
		(layer "In15.Cu")
		(net "P5E_CPU1_P0_RX_DN<11>")
	)
	(arc
		(start 107.599734 -273.580606)
		(mid 107.755662 -273.276314)
		(end 107.599734 -272.972022)
		(width 0.1143)
		(layer "In15.Cu")
		(net "P5E_CPU1_P0_RX_DN<11>")
	)
	(arc
		(start 107.599734 -294.640508)
		(mid 107.755662 -294.336216)
		(end 107.599734 -294.031924)
		(width 0.1143)
		(layer "In15.Cu")
		(net "P5E_CPU1_P0_RX_DN<11>")
	)
	(arc
		(start 107.531662 -285.892748)
		(mid 107.523998 -285.887477)
		(end 107.516422 -285.88208)
		(width 0.1143)
		(layer "In15.Cu")
		(net "P5E_CPU1_P0_RX_DN<11>")
	)
	(arc
		(start 107.599734 -275.200618)
		(mid 107.755662 -274.896326)
		(end 107.599734 -274.592034)
		(width 0.1143)
		(layer "In15.Cu")
		(net "P5E_CPU1_P0_RX_DN<11>")
	)
	(arc
		(start 107.501182 -279.39111)
		(mid 107.273182 -278.946356)
		(end 107.501182 -278.501602)
		(width 0.1143)
		(layer "In15.Cu")
		(net "P5E_CPU1_P0_RX_DN<11>")
	)
	(arc
		(start 107.520994 -271.305274)
		(mid 107.35192 -271.112353)
		(end 107.285536 -270.864584)
		(width 0.1143)
		(layer "In15.Cu")
		(net "P5E_CPU1_P0_RX_DN<11>")
	)
	(arc
		(start 75.450954 -364.462568)
		(mid 75.663927 -364.402513)
		(end 75.884278 -364.382304)
		(width 0.14224)
		(layer "In15.Cu")
		(net "P5E_CPU1_P0_RX_DN<11>")
	)
	(arc
		(start 107.27309 -295.153588)
		(mid 107.34807 -294.873104)
		(end 107.552998 -294.667432)
		(width 0.1143)
		(layer "In15.Cu")
		(net "P5E_CPU1_P0_RX_DN<11>")
	)
	(arc
		(start 107.501182 -284.251146)
		(mid 107.273182 -283.806392)
		(end 107.501182 -283.361638)
		(width 0.1143)
		(layer "In15.Cu")
		(net "P5E_CPU1_P0_RX_DN<11>")
	)
	(arc
		(start 107.531662 -271.31264)
		(mid 107.526306 -271.308989)
		(end 107.520994 -271.305274)
		(width 0.1143)
		(layer "In15.Cu")
		(net "P5E_CPU1_P0_RX_DN<11>")
	)
	(arc
		(start 107.516422 -285.88208)
		(mid 107.291251 -285.426404)
		(end 107.516422 -284.970728)
		(width 0.1143)
		(layer "In15.Cu")
		(net "P5E_CPU1_P0_RX_DN<11>")
	)
	(arc
		(start 106.909108 -296.273728)
		(mid 106.840113 -296.170609)
		(end 106.81589 -296.048938)
		(width 0.1143)
		(layer "In15.Cu")
		(net "P5E_CPU1_P0_RX_DN<11>")
	)
	(segment
		(start 59.270646 -385.31038)
		(end 59.791346 -385.31038)
		(width 0.127)
		(layer "F.Cu")
		(net "P5E_CPU1_P0_RX_DN<10>")
	)
	(segment
		(start 106.907838 -273.010376)
		(end 106.440986 -273.276314)
		(width 0.12954)
		(layer "F.Cu")
		(net "P5E_CPU1_P0_RX_DN<10>")
	)
	(segment
		(start 60.266834 -385.163822)
		(end 59.949842 -384.84683)
		(width 0.14224)
		(layer "In15.Cu")
		(net "P5E_CPU1_P0_RX_DN<10>")
	)
	(segment
		(start 106.589068 -280.101802)
		(end 106.628184 -280.078942)
		(width 0.1143)
		(layer "In15.Cu")
		(net "P5E_CPU1_P0_RX_DN<10>")
	)
	(segment
		(start 60.145168 -385.404868)
		(end 60.266834 -385.334764)
		(width 0.14224)
		(layer "In15.Cu")
		(net "P5E_CPU1_P0_RX_DN<10>")
	)
	(segment
		(start 157.04312 -362.821982)
		(end 158.65856 -362.821982)
		(width 0.14224)
		(layer "In15.Cu")
		(net "P5E_CPU1_P0_RX_DN<10>")
	)
	(segment
		(start 106.589068 -273.621754)
		(end 106.628184 -273.598894)
		(width 0.1143)
		(layer "In15.Cu")
		(net "P5E_CPU1_P0_RX_DN<10>")
	)
	(segment
		(start 106.589068 -283.341826)
		(end 106.628184 -283.318966)
		(width 0.1143)
		(layer "In15.Cu")
		(net "P5E_CPU1_P0_RX_DN<10>")
	)
	(segment
		(start 106.589068 -281.721814)
		(end 106.628184 -281.698954)
		(width 0.1143)
		(layer "In15.Cu")
		(net "P5E_CPU1_P0_RX_DN<10>")
	)
	(segment
		(start 65.36817 -367.00333)
		(end 75.392026 -363.432852)
		(width 0.14224)
		(layer "In15.Cu")
		(net "P5E_CPU1_P0_RX_DN<10>")
	)
	(segment
		(start 106.658664 -289.17138)
		(end 106.628184 -289.1536)
		(width 0.1143)
		(layer "In15.Cu")
		(net "P5E_CPU1_P0_RX_DN<10>")
	)
	(segment
		(start 106.589068 -276.861778)
		(end 106.628184 -276.838918)
		(width 0.1143)
		(layer "In15.Cu")
		(net "P5E_CPU1_P0_RX_DN<10>")
	)
	(segment
		(start 106.628184 -284.293818)
		(end 106.589068 -284.270958)
		(width 0.1143)
		(layer "In15.Cu")
		(net "P5E_CPU1_P0_RX_DN<10>")
	)
	(segment
		(start 106.589068 -294.681656)
		(end 106.628184 -294.658796)
		(width 0.1143)
		(layer "In15.Cu")
		(net "P5E_CPU1_P0_RX_DN<10>")
	)
	(segment
		(start 106.628184 -278.45893)
		(end 106.658664 -278.44115)
		(width 0.1143)
		(layer "In15.Cu")
		(net "P5E_CPU1_P0_RX_DN<10>")
	)
	(segment
		(start 106.628184 -274.573746)
		(end 106.589068 -274.550886)
		(width 0.1143)
		(layer "In15.Cu")
		(net "P5E_CPU1_P0_RX_DN<10>")
	)
	(segment
		(start 158.91002 -362.570522)
		(end 158.91002 -360.486452)
		(width 0.14224)
		(layer "In15.Cu")
		(net "P5E_CPU1_P0_RX_DN<10>")
	)
	(segment
		(start 60.14466 -385.405376)
		(end 60.145168 -385.404868)
		(width 0.14224)
		(layer "In15.Cu")
		(net "P5E_CPU1_P0_RX_DN<10>")
	)
	(segment
		(start 155.62326 -362.684822)
		(end 155.76042 -362.821982)
		(width 0.14224)
		(layer "In15.Cu")
		(net "P5E_CPU1_P0_RX_DN<10>")
	)
	(segment
		(start 105.916984 -296.37482)
		(end 105.916984 -296.346372)
		(width 0.1143)
		(layer "In15.Cu")
		(net "P5E_CPU1_P0_RX_DN<10>")
	)
	(segment
		(start 106.658664 -290.791392)
		(end 106.628184 -290.773612)
		(width 0.1143)
		(layer "In15.Cu")
		(net "P5E_CPU1_P0_RX_DN<10>")
	)
	(segment
		(start 106.589068 -291.441632)
		(end 106.628184 -291.418772)
		(width 0.1143)
		(layer "In15.Cu")
		(net "P5E_CPU1_P0_RX_DN<10>")
	)
	(segment
		(start 158.60395 -360.180382)
		(end 153.76906 -360.180382)
		(width 0.14224)
		(layer "In15.Cu")
		(net "P5E_CPU1_P0_RX_DN<10>")
	)
	(segment
		(start 106.628184 -285.91383)
		(end 106.589068 -285.89097)
		(width 0.1143)
		(layer "In15.Cu")
		(net "P5E_CPU1_P0_RX_DN<10>")
	)
	(segment
		(start 106.589068 -289.82162)
		(end 106.628184 -289.79876)
		(width 0.1143)
		(layer "In15.Cu")
		(net "P5E_CPU1_P0_RX_DN<10>")
	)
	(segment
		(start 106.5911 -286.580072)
		(end 106.628184 -286.558736)
		(width 0.1143)
		(layer "In15.Cu")
		(net "P5E_CPU1_P0_RX_DN<10>")
	)
	(segment
		(start 132.098034 -344.966544)
		(end 118.647464 -331.515974)
		(width 0.14224)
		(layer "In15.Cu")
		(net "P5E_CPU1_P0_RX_DN<10>")
	)
	(segment
		(start 75.529186 -363.40923)
		(end 106.058716 -363.40923)
		(width 0.14224)
		(layer "In15.Cu")
		(net "P5E_CPU1_P0_RX_DN<10>")
	)
	(segment
		(start 59.791346 -385.31038)
		(end 60.14466 -385.405376)
		(width 0.14224)
		(layer "In15.Cu")
		(net "P5E_CPU1_P0_RX_DN<10>")
	)
	(segment
		(start 106.628184 -283.318966)
		(end 106.658664 -283.301186)
		(width 0.1143)
		(layer "In15.Cu")
		(net "P5E_CPU1_P0_RX_DN<10>")
	)
	(segment
		(start 105.916984 -300.922436)
		(end 105.916984 -296.37482)
		(width 0.14224)
		(layer "In15.Cu")
		(net "P5E_CPU1_P0_RX_DN<10>")
	)
	(segment
		(start 106.589068 -286.581596)
		(end 106.5911 -286.580072)
		(width 0.1143)
		(layer "In15.Cu")
		(net "P5E_CPU1_P0_RX_DN<10>")
	)
	(segment
		(start 106.658664 -279.451562)
		(end 106.628184 -279.433782)
		(width 0.1143)
		(layer "In15.Cu")
		(net "P5E_CPU1_P0_RX_DN<10>")
	)
	(segment
		(start 106.628184 -276.193758)
		(end 106.589068 -276.170898)
		(width 0.1143)
		(layer "In15.Cu")
		(net "P5E_CPU1_P0_RX_DN<10>")
	)
	(segment
		(start 106.628184 -282.673806)
		(end 106.589068 -282.650946)
		(width 0.1143)
		(layer "In15.Cu")
		(net "P5E_CPU1_P0_RX_DN<10>")
	)
	(segment
		(start 60.266834 -385.334764)
		(end 60.266834 -385.163822)
		(width 0.14224)
		(layer "In15.Cu")
		(net "P5E_CPU1_P0_RX_DN<10>")
	)
	(segment
		(start 106.658664 -282.691586)
		(end 106.628184 -282.673806)
		(width 0.1143)
		(layer "In15.Cu")
		(net "P5E_CPU1_P0_RX_DN<10>")
	)
	(segment
		(start 106.589068 -293.061644)
		(end 106.628184 -293.038784)
		(width 0.1143)
		(layer "In15.Cu")
		(net "P5E_CPU1_P0_RX_DN<10>")
	)
	(segment
		(start 155.05938 -362.821982)
		(end 155.19654 -362.684822)
		(width 0.14224)
		(layer "In15.Cu")
		(net "P5E_CPU1_P0_RX_DN<10>")
	)
	(segment
		(start 106.589068 -288.201608)
		(end 106.628184 -288.178748)
		(width 0.1143)
		(layer "In15.Cu")
		(net "P5E_CPU1_P0_RX_DN<10>")
	)
	(segment
		(start 106.628184 -280.078942)
		(end 106.658664 -280.061162)
		(width 0.1143)
		(layer "In15.Cu")
		(net "P5E_CPU1_P0_RX_DN<10>")
	)
	(segment
		(start 106.628184 -291.418772)
		(end 106.658664 -291.400992)
		(width 0.1143)
		(layer "In15.Cu")
		(net "P5E_CPU1_P0_RX_DN<10>")
	)
	(segment
		(start 106.658664 -287.551622)
		(end 106.591608 -287.512506)
		(width 0.1143)
		(layer "In15.Cu")
		(net "P5E_CPU1_P0_RX_DN<10>")
	)
	(segment
		(start 60.653168 -372.657116)
		(end 64.438022 -367.683542)
		(width 0.14224)
		(layer "In15.Cu")
		(net "P5E_CPU1_P0_RX_DN<10>")
	)
	(segment
		(start 106.658664 -284.311598)
		(end 106.628184 -284.293818)
		(width 0.1143)
		(layer "In15.Cu")
		(net "P5E_CPU1_P0_RX_DN<10>")
	)
	(segment
		(start 138.889232 -360.61142)
		(end 139.196572 -360.91876)
		(width 0.14224)
		(layer "In15.Cu")
		(net "P5E_CPU1_P0_RX_DN<10>")
	)
	(segment
		(start 106.628184 -292.393624)
		(end 106.589068 -292.370764)
		(width 0.1143)
		(layer "In15.Cu")
		(net "P5E_CPU1_P0_RX_DN<10>")
	)
	(segment
		(start 105.916984 -296.346372)
		(end 105.962704 -296.300652)
		(width 0.1143)
		(layer "In15.Cu")
		(net "P5E_CPU1_P0_RX_DN<10>")
	)
	(segment
		(start 106.628184 -288.178748)
		(end 106.660696 -288.159952)
		(width 0.1143)
		(layer "In15.Cu")
		(net "P5E_CPU1_P0_RX_DN<10>")
	)
	(segment
		(start 106.628184 -275.218906)
		(end 106.658664 -275.201126)
		(width 0.1143)
		(layer "In15.Cu")
		(net "P5E_CPU1_P0_RX_DN<10>")
	)
	(segment
		(start 105.962704 -296.300652)
		(end 105.962704 -295.914826)
		(width 0.1143)
		(layer "In15.Cu")
		(net "P5E_CPU1_P0_RX_DN<10>")
	)
	(segment
		(start 106.628184 -284.938978)
		(end 106.658664 -284.921198)
		(width 0.1143)
		(layer "In15.Cu")
		(net "P5E_CPU1_P0_RX_DN<10>")
	)
	(segment
		(start 106.628184 -286.558736)
		(end 106.660696 -286.53994)
		(width 0.1143)
		(layer "In15.Cu")
		(net "P5E_CPU1_P0_RX_DN<10>")
	)
	(segment
		(start 106.628184 -276.838918)
		(end 106.658664 -276.821138)
		(width 0.1143)
		(layer "In15.Cu")
		(net "P5E_CPU1_P0_RX_DN<10>")
	)
	(segment
		(start 118.176802 -330.811632)
		(end 106.02849 -301.483014)
		(width 0.14224)
		(layer "In15.Cu")
		(net "P5E_CPU1_P0_RX_DN<10>")
	)
	(segment
		(start 60.25769 -373.84609)
		(end 60.257944 -373.845328)
		(width 0.14224)
		(layer "In15.Cu")
		(net "P5E_CPU1_P0_RX_DN<10>")
	)
	(segment
		(start 134.931404 -360.61142)
		(end 138.889232 -360.61142)
		(width 0.14224)
		(layer "In15.Cu")
		(net "P5E_CPU1_P0_RX_DN<10>")
	)
	(segment
		(start 134.931404 -362.03128)
		(end 134.624064 -361.72394)
		(width 0.14224)
		(layer "In15.Cu")
		(net "P5E_CPU1_P0_RX_DN<10>")
	)
	(segment
		(start 106.628184 -289.79876)
		(end 106.658664 -289.78098)
		(width 0.1143)
		(layer "In15.Cu")
		(net "P5E_CPU1_P0_RX_DN<10>")
	)
	(segment
		(start 106.808778 -273.346164)
		(end 106.738928 -273.276314)
		(width 0.1143)
		(layer "In15.Cu")
		(net "P5E_CPU1_P0_RX_DN<10>")
	)
	(segment
		(start 137.634472 -362.88726)
		(end 137.776712 -362.74502)
		(width 0.14224)
		(layer "In15.Cu")
		(net "P5E_CPU1_P0_RX_DN<10>")
	)
	(segment
		(start 106.658664 -294.031416)
		(end 106.628184 -294.013636)
		(width 0.1143)
		(layer "In15.Cu")
		(net "P5E_CPU1_P0_RX_DN<10>")
	)
	(segment
		(start 154.46502 -362.821982)
		(end 155.05938 -362.821982)
		(width 0.14224)
		(layer "In15.Cu")
		(net "P5E_CPU1_P0_RX_DN<10>")
	)
	(segment
		(start 59.954668 -384.234944)
		(end 60.258706 -383.930906)
		(width 0.14224)
		(layer "In15.Cu")
		(net "P5E_CPU1_P0_RX_DN<10>")
	)
	(segment
		(start 106.589068 -275.241766)
		(end 106.628184 -275.218906)
		(width 0.1143)
		(layer "In15.Cu")
		(net "P5E_CPU1_P0_RX_DN<10>")
	)
	(segment
		(start 106.628184 -293.038784)
		(end 106.658664 -293.021004)
		(width 0.1143)
		(layer "In15.Cu")
		(net "P5E_CPU1_P0_RX_DN<10>")
	)
	(segment
		(start 106.628184 -289.1536)
		(end 106.589068 -289.13074)
		(width 0.1143)
		(layer "In15.Cu")
		(net "P5E_CPU1_P0_RX_DN<10>")
	)
	(segment
		(start 139.439396 -362.821982)
		(end 153.76398 -362.821982)
		(width 0.14224)
		(layer "In15.Cu")
		(net "P5E_CPU1_P0_RX_DN<10>")
	)
	(segment
		(start 60.258706 -382.314958)
		(end 59.90971 -375.050304)
		(width 0.14224)
		(layer "In15.Cu")
		(net "P5E_CPU1_P0_RX_DN<10>")
	)
	(segment
		(start 149.563836 -356.73538)
		(end 132.748528 -345.500452)
		(width 0.14224)
		(layer "In15.Cu")
		(net "P5E_CPU1_P0_RX_DN<10>")
	)
	(segment
		(start 139.196572 -360.91876)
		(end 139.196572 -362.579158)
		(width 0.14224)
		(layer "In15.Cu")
		(net "P5E_CPU1_P0_RX_DN<10>")
	)
	(segment
		(start 106.628184 -279.433782)
		(end 106.589068 -279.410922)
		(width 0.1143)
		(layer "In15.Cu")
		(net "P5E_CPU1_P0_RX_DN<10>")
	)
	(segment
		(start 137.634472 -362.03128)
		(end 134.931404 -362.03128)
		(width 0.14224)
		(layer "In15.Cu")
		(net "P5E_CPU1_P0_RX_DN<10>")
	)
	(segment
		(start 106.345736 -295.27627)
		(end 106.345736 -295.145714)
		(width 0.1143)
		(layer "In15.Cu")
		(net "P5E_CPU1_P0_RX_DN<10>")
	)
	(segment
		(start 106.589068 -278.48179)
		(end 106.628184 -278.45893)
		(width 0.1143)
		(layer "In15.Cu")
		(net "P5E_CPU1_P0_RX_DN<10>")
	)
	(segment
		(start 106.055922 -295.689782)
		(end 106.257852 -295.487852)
		(width 0.1143)
		(layer "In15.Cu")
		(net "P5E_CPU1_P0_RX_DN<10>")
	)
	(segment
		(start 106.658664 -281.071574)
		(end 106.628184 -281.053794)
		(width 0.1143)
		(layer "In15.Cu")
		(net "P5E_CPU1_P0_RX_DN<10>")
	)
	(segment
		(start 106.589068 -284.961838)
		(end 106.628184 -284.938978)
		(width 0.1143)
		(layer "In15.Cu")
		(net "P5E_CPU1_P0_RX_DN<10>")
	)
	(segment
		(start 153.76398 -362.821982)
		(end 153.90114 -362.684822)
		(width 0.14224)
		(layer "In15.Cu")
		(net "P5E_CPU1_P0_RX_DN<10>")
	)
	(segment
		(start 106.628184 -290.773612)
		(end 106.589068 -290.750752)
		(width 0.1143)
		(layer "In15.Cu")
		(net "P5E_CPU1_P0_RX_DN<10>")
	)
	(segment
		(start 156.34208 -362.821982)
		(end 156.47924 -362.684822)
		(width 0.14224)
		(layer "In15.Cu")
		(net "P5E_CPU1_P0_RX_DN<10>")
	)
	(segment
		(start 59.928252 -374.90654)
		(end 60.25769 -373.84609)
		(width 0.14224)
		(layer "In15.Cu")
		(net "P5E_CPU1_P0_RX_DN<10>")
	)
	(segment
		(start 106.738928 -273.276314)
		(end 106.440986 -273.276314)
		(width 0.1143)
		(layer "In15.Cu")
		(net "P5E_CPU1_P0_RX_DN<10>")
	)
	(segment
		(start 107.946952 -362.88726)
		(end 137.634472 -362.88726)
		(width 0.14224)
		(layer "In15.Cu")
		(net "P5E_CPU1_P0_RX_DN<10>")
	)
	(segment
		(start 137.776712 -362.17352)
		(end 137.634472 -362.03128)
		(width 0.14224)
		(layer "In15.Cu")
		(net "P5E_CPU1_P0_RX_DN<10>")
	)
	(segment
		(start 137.776712 -362.74502)
		(end 137.776712 -362.17352)
		(width 0.14224)
		(layer "In15.Cu")
		(net "P5E_CPU1_P0_RX_DN<10>")
	)
	(segment
		(start 106.658664 -292.411404)
		(end 106.628184 -292.393624)
		(width 0.1143)
		(layer "In15.Cu")
		(net "P5E_CPU1_P0_RX_DN<10>")
	)
	(segment
		(start 60.257944 -373.845328)
		(end 60.58789 -372.7831)
		(width 0.14224)
		(layer "In15.Cu")
		(net "P5E_CPU1_P0_RX_DN<10>")
	)
	(segment
		(start 155.76042 -362.821982)
		(end 156.34208 -362.821982)
		(width 0.14224)
		(layer "In15.Cu")
		(net "P5E_CPU1_P0_RX_DN<10>")
	)
	(segment
		(start 106.628184 -281.698954)
		(end 106.658664 -281.681174)
		(width 0.1143)
		(layer "In15.Cu")
		(net "P5E_CPU1_P0_RX_DN<10>")
	)
	(segment
		(start 106.658664 -277.83155)
		(end 106.628184 -277.81377)
		(width 0.1143)
		(layer "In15.Cu")
		(net "P5E_CPU1_P0_RX_DN<10>")
	)
	(segment
		(start 154.32786 -362.684822)
		(end 154.46502 -362.821982)
		(width 0.14224)
		(layer "In15.Cu")
		(net "P5E_CPU1_P0_RX_DN<10>")
	)
	(segment
		(start 156.90596 -362.684822)
		(end 157.04312 -362.821982)
		(width 0.14224)
		(layer "In15.Cu")
		(net "P5E_CPU1_P0_RX_DN<10>")
	)
	(segment
		(start 134.624064 -361.72394)
		(end 134.624064 -360.91876)
		(width 0.14224)
		(layer "In15.Cu")
		(net "P5E_CPU1_P0_RX_DN<10>")
	)
	(segment
		(start 153.90114 -362.684822)
		(end 154.32786 -362.684822)
		(width 0.14224)
		(layer "In15.Cu")
		(net "P5E_CPU1_P0_RX_DN<10>")
	)
	(segment
		(start 106.628184 -273.598894)
		(end 106.658664 -273.581114)
		(width 0.1143)
		(layer "In15.Cu")
		(net "P5E_CPU1_P0_RX_DN<10>")
	)
	(segment
		(start 155.19654 -362.684822)
		(end 155.62326 -362.684822)
		(width 0.14224)
		(layer "In15.Cu")
		(net "P5E_CPU1_P0_RX_DN<10>")
	)
	(segment
		(start 156.47924 -362.684822)
		(end 156.90596 -362.684822)
		(width 0.14224)
		(layer "In15.Cu")
		(net "P5E_CPU1_P0_RX_DN<10>")
	)
	(segment
		(start 59.949842 -384.84683)
		(end 59.954668 -384.234944)
		(width 0.14224)
		(layer "In15.Cu")
		(net "P5E_CPU1_P0_RX_DN<10>")
	)
	(segment
		(start 134.624064 -360.91876)
		(end 134.931404 -360.61142)
		(width 0.14224)
		(layer "In15.Cu")
		(net "P5E_CPU1_P0_RX_DN<10>")
	)
	(segment
		(start 106.658664 -276.211538)
		(end 106.628184 -276.193758)
		(width 0.1143)
		(layer "In15.Cu")
		(net "P5E_CPU1_P0_RX_DN<10>")
	)
	(segment
		(start 106.628184 -294.013636)
		(end 106.589068 -293.990776)
		(width 0.1143)
		(layer "In15.Cu")
		(net "P5E_CPU1_P0_RX_DN<10>")
	)
	(segment
		(start 106.658664 -274.591526)
		(end 106.628184 -274.573746)
		(width 0.1143)
		(layer "In15.Cu")
		(net "P5E_CPU1_P0_RX_DN<10>")
	)
	(segment
		(start 106.628184 -294.658796)
		(end 106.658664 -294.641016)
		(width 0.1143)
		(layer "In15.Cu")
		(net "P5E_CPU1_P0_RX_DN<10>")
	)
	(segment
		(start 106.628184 -277.81377)
		(end 106.589068 -277.79091)
		(width 0.1143)
		(layer "In15.Cu")
		(net "P5E_CPU1_P0_RX_DN<10>")
	)
	(segment
		(start 106.658664 -285.93161)
		(end 106.628184 -285.91383)
		(width 0.1143)
		(layer "In15.Cu")
		(net "P5E_CPU1_P0_RX_DN<10>")
	)
	(segment
		(start 106.628184 -281.053794)
		(end 106.589068 -281.030934)
		(width 0.1143)
		(layer "In15.Cu")
		(net "P5E_CPU1_P0_RX_DN<10>")
	)
	(segment
		(start 60.258706 -383.930906)
		(end 60.258706 -382.314958)
		(width 0.14224)
		(layer "In15.Cu")
		(net "P5E_CPU1_P0_RX_DN<10>")
	)
	(segment
		(start 152.488138 -359.649776)
		(end 149.618954 -356.780592)
		(width 0.14224)
		(layer "In15.Cu")
		(net "P5E_CPU1_P0_RX_DN<10>")
	)
	(arc
		(start 106.589068 -274.550886)
		(mid 106.345741 -274.08632)
		(end 106.589068 -273.621754)
		(width 0.1143)
		(layer "In15.Cu")
		(net "P5E_CPU1_P0_RX_DN<10>")
	)
	(arc
		(start 106.589068 -289.13074)
		(mid 106.345741 -288.666174)
		(end 106.589068 -288.201608)
		(width 0.1143)
		(layer "In15.Cu")
		(net "P5E_CPU1_P0_RX_DN<10>")
	)
	(arc
		(start 106.345736 -295.145206)
		(mid 106.410486 -294.883553)
		(end 106.589068 -294.681656)
		(width 0.1143)
		(layer "In15.Cu")
		(net "P5E_CPU1_P0_RX_DN<10>")
	)
	(arc
		(start 139.196572 -362.579158)
		(mid 139.267694 -362.75086)
		(end 139.439396 -362.821982)
		(width 0.14224)
		(layer "In15.Cu")
		(net "P5E_CPU1_P0_RX_DN<10>")
	)
	(arc
		(start 106.589068 -292.370764)
		(mid 106.345741 -291.906198)
		(end 106.589068 -291.441632)
		(width 0.1143)
		(layer "In15.Cu")
		(net "P5E_CPU1_P0_RX_DN<10>")
	)
	(arc
		(start 106.589068 -290.750752)
		(mid 106.345741 -290.286186)
		(end 106.589068 -289.82162)
		(width 0.1143)
		(layer "In15.Cu")
		(net "P5E_CPU1_P0_RX_DN<10>")
	)
	(arc
		(start 106.589068 -277.79091)
		(mid 106.345741 -277.326344)
		(end 106.589068 -276.861778)
		(width 0.1143)
		(layer "In15.Cu")
		(net "P5E_CPU1_P0_RX_DN<10>")
	)
	(arc
		(start 106.658664 -284.921198)
		(mid 106.815641 -284.616398)
		(end 106.658664 -284.311598)
		(width 0.1143)
		(layer "In15.Cu")
		(net "P5E_CPU1_P0_RX_DN<10>")
	)
	(arc
		(start 106.658664 -294.641016)
		(mid 106.815641 -294.336216)
		(end 106.658664 -294.031416)
		(width 0.1143)
		(layer "In15.Cu")
		(net "P5E_CPU1_P0_RX_DN<10>")
	)
	(arc
		(start 106.815636 -286.23641)
		(mid 106.774087 -286.064988)
		(end 106.658664 -285.93161)
		(width 0.1143)
		(layer "In15.Cu")
		(net "P5E_CPU1_P0_RX_DN<10>")
	)
	(arc
		(start 106.815636 -287.856422)
		(mid 106.774087 -287.685)
		(end 106.658664 -287.551622)
		(width 0.1143)
		(layer "In15.Cu")
		(net "P5E_CPU1_P0_RX_DN<10>")
	)
	(arc
		(start 106.658664 -293.021004)
		(mid 106.815641 -292.716204)
		(end 106.658664 -292.411404)
		(width 0.1143)
		(layer "In15.Cu")
		(net "P5E_CPU1_P0_RX_DN<10>")
	)
	(arc
		(start 106.589068 -276.170898)
		(mid 106.345741 -275.706332)
		(end 106.589068 -275.241766)
		(width 0.1143)
		(layer "In15.Cu")
		(net "P5E_CPU1_P0_RX_DN<10>")
	)
	(arc
		(start 106.345736 -295.145714)
		(mid 106.345736 -295.14546)
		(end 106.345736 -295.145206)
		(width 0.1143)
		(layer "In15.Cu")
		(net "P5E_CPU1_P0_RX_DN<10>")
	)
	(arc
		(start 106.589068 -279.410922)
		(mid 106.345741 -278.946356)
		(end 106.589068 -278.48179)
		(width 0.1143)
		(layer "In15.Cu")
		(net "P5E_CPU1_P0_RX_DN<10>")
	)
	(arc
		(start 106.658664 -289.78098)
		(mid 106.815641 -289.47618)
		(end 106.658664 -289.17138)
		(width 0.1143)
		(layer "In15.Cu")
		(net "P5E_CPU1_P0_RX_DN<10>")
	)
	(arc
		(start 106.589068 -281.030934)
		(mid 106.345741 -280.566368)
		(end 106.589068 -280.101802)
		(width 0.1143)
		(layer "In15.Cu")
		(net "P5E_CPU1_P0_RX_DN<10>")
	)
	(arc
		(start 60.58789 -372.7831)
		(mid 60.615012 -372.717248)
		(end 60.653168 -372.657116)
		(width 0.14224)
		(layer "In15.Cu")
		(net "P5E_CPU1_P0_RX_DN<10>")
	)
	(arc
		(start 149.618954 -356.780592)
		(mid 149.592508 -356.756629)
		(end 149.563836 -356.73538)
		(width 0.14224)
		(layer "In15.Cu")
		(net "P5E_CPU1_P0_RX_DN<10>")
	)
	(arc
		(start 106.02849 -301.483014)
		(mid 105.945129 -301.208217)
		(end 105.916984 -300.922436)
		(width 0.14224)
		(layer "In15.Cu")
		(net "P5E_CPU1_P0_RX_DN<10>")
	)
	(arc
		(start 106.589068 -282.650946)
		(mid 106.345741 -282.18638)
		(end 106.589068 -281.721814)
		(width 0.1143)
		(layer "In15.Cu")
		(net "P5E_CPU1_P0_RX_DN<10>")
	)
	(arc
		(start 106.660696 -286.53994)
		(mid 106.774625 -286.406793)
		(end 106.815636 -286.23641)
		(width 0.1143)
		(layer "In15.Cu")
		(net "P5E_CPU1_P0_RX_DN<10>")
	)
	(arc
		(start 64.438022 -367.683542)
		(mid 64.853587 -367.275726)
		(end 65.36817 -367.00333)
		(width 0.14224)
		(layer "In15.Cu")
		(net "P5E_CPU1_P0_RX_DN<10>")
	)
	(arc
		(start 106.858562 -363.187996)
		(mid 107.38237 -362.963856)
		(end 107.946952 -362.88726)
		(width 0.14224)
		(layer "In15.Cu")
		(net "P5E_CPU1_P0_RX_DN<10>")
	)
	(arc
		(start 106.658664 -276.821138)
		(mid 106.815641 -276.516338)
		(end 106.658664 -276.211538)
		(width 0.1143)
		(layer "In15.Cu")
		(net "P5E_CPU1_P0_RX_DN<10>")
	)
	(arc
		(start 106.658664 -291.400992)
		(mid 106.815641 -291.096192)
		(end 106.658664 -290.791392)
		(width 0.1143)
		(layer "In15.Cu")
		(net "P5E_CPU1_P0_RX_DN<10>")
	)
	(arc
		(start 105.962704 -295.914826)
		(mid 105.98693 -295.793032)
		(end 106.055922 -295.689782)
		(width 0.1143)
		(layer "In15.Cu")
		(net "P5E_CPU1_P0_RX_DN<10>")
	)
	(arc
		(start 106.658664 -281.681174)
		(mid 106.815641 -281.376374)
		(end 106.658664 -281.071574)
		(width 0.1143)
		(layer "In15.Cu")
		(net "P5E_CPU1_P0_RX_DN<10>")
	)
	(arc
		(start 106.658664 -275.201126)
		(mid 106.815641 -274.896326)
		(end 106.658664 -274.591526)
		(width 0.1143)
		(layer "In15.Cu")
		(net "P5E_CPU1_P0_RX_DN<10>")
	)
	(arc
		(start 106.658664 -280.061162)
		(mid 106.815641 -279.756362)
		(end 106.658664 -279.451562)
		(width 0.1143)
		(layer "In15.Cu")
		(net "P5E_CPU1_P0_RX_DN<10>")
	)
	(arc
		(start 106.058716 -363.40923)
		(mid 106.47366 -363.352911)
		(end 106.858562 -363.187996)
		(width 0.14224)
		(layer "In15.Cu")
		(net "P5E_CPU1_P0_RX_DN<10>")
	)
	(arc
		(start 106.589068 -284.270958)
		(mid 106.345741 -283.806392)
		(end 106.589068 -283.341826)
		(width 0.1143)
		(layer "In15.Cu")
		(net "P5E_CPU1_P0_RX_DN<10>")
	)
	(arc
		(start 106.658664 -273.581114)
		(mid 106.756429 -273.478138)
		(end 106.808778 -273.346164)
		(width 0.1143)
		(layer "In15.Cu")
		(net "P5E_CPU1_P0_RX_DN<10>")
	)
	(arc
		(start 106.589068 -293.990776)
		(mid 106.345741 -293.52621)
		(end 106.589068 -293.061644)
		(width 0.1143)
		(layer "In15.Cu")
		(net "P5E_CPU1_P0_RX_DN<10>")
	)
	(arc
		(start 132.748528 -345.500452)
		(mid 132.410168 -345.249475)
		(end 132.098034 -344.966544)
		(width 0.14224)
		(layer "In15.Cu")
		(net "P5E_CPU1_P0_RX_DN<10>")
	)
	(arc
		(start 158.91002 -360.486452)
		(mid 158.820374 -360.270028)
		(end 158.60395 -360.180382)
		(width 0.14224)
		(layer "In15.Cu")
		(net "P5E_CPU1_P0_RX_DN<10>")
	)
	(arc
		(start 106.591608 -287.512506)
		(mid 106.410956 -287.309761)
		(end 106.345736 -287.046162)
		(width 0.1143)
		(layer "In15.Cu")
		(net "P5E_CPU1_P0_RX_DN<10>")
	)
	(arc
		(start 158.65856 -362.821982)
		(mid 158.836369 -362.748331)
		(end 158.91002 -362.570522)
		(width 0.14224)
		(layer "In15.Cu")
		(net "P5E_CPU1_P0_RX_DN<10>")
	)
	(arc
		(start 59.90971 -375.050304)
		(mid 59.912695 -374.977612)
		(end 59.928252 -374.90654)
		(width 0.14224)
		(layer "In15.Cu")
		(net "P5E_CPU1_P0_RX_DN<10>")
	)
	(arc
		(start 106.257852 -295.487852)
		(mid 106.322852 -295.390807)
		(end 106.345736 -295.27627)
		(width 0.1143)
		(layer "In15.Cu")
		(net "P5E_CPU1_P0_RX_DN<10>")
	)
	(arc
		(start 106.660696 -288.159952)
		(mid 106.774625 -288.026805)
		(end 106.815636 -287.856422)
		(width 0.1143)
		(layer "In15.Cu")
		(net "P5E_CPU1_P0_RX_DN<10>")
	)
	(arc
		(start 75.392026 -363.432852)
		(mid 75.459596 -363.415185)
		(end 75.529186 -363.40923)
		(width 0.14224)
		(layer "In15.Cu")
		(net "P5E_CPU1_P0_RX_DN<10>")
	)
	(arc
		(start 106.658664 -278.44115)
		(mid 106.815641 -278.13635)
		(end 106.658664 -277.83155)
		(width 0.1143)
		(layer "In15.Cu")
		(net "P5E_CPU1_P0_RX_DN<10>")
	)
	(arc
		(start 106.589068 -285.89097)
		(mid 106.345741 -285.426404)
		(end 106.589068 -284.961838)
		(width 0.1143)
		(layer "In15.Cu")
		(net "P5E_CPU1_P0_RX_DN<10>")
	)
	(arc
		(start 106.345736 -287.046162)
		(mid 106.410251 -286.783943)
		(end 106.589068 -286.581596)
		(width 0.1143)
		(layer "In15.Cu")
		(net "P5E_CPU1_P0_RX_DN<10>")
	)
	(arc
		(start 118.647464 -331.515974)
		(mid 118.377461 -331.186974)
		(end 118.176802 -330.811632)
		(width 0.14224)
		(layer "In15.Cu")
		(net "P5E_CPU1_P0_RX_DN<10>")
	)
	(arc
		(start 106.658664 -283.301186)
		(mid 106.815641 -282.996386)
		(end 106.658664 -282.691586)
		(width 0.1143)
		(layer "In15.Cu")
		(net "P5E_CPU1_P0_RX_DN<10>")
	)
	(arc
		(start 153.76906 -360.180382)
		(mid 153.075818 -360.042488)
		(end 152.488138 -359.649776)
		(width 0.14224)
		(layer "In15.Cu")
		(net "P5E_CPU1_P0_RX_DN<10>")
	)
	(segment
		(start 98.44786 -271.390364)
		(end 97.981008 -271.656302)
		(width 0.12954)
		(layer "F.Cu")
		(net "P5E_CPU1_P0_RX_DN<0>")
	)
	(segment
		(start 47.27067 -385.31038)
		(end 47.79137 -385.31038)
		(width 0.127)
		(layer "F.Cu")
		(net "P5E_CPU1_P0_RX_DN<0>")
	)
	(segment
		(start 108.792264 -352.539554)
		(end 108.985304 -352.55835)
		(width 0.14224)
		(layer "In13.Cu")
		(net "P5E_CPU1_P0_RX_DN<0>")
	)
	(segment
		(start 97.189036 -293.061644)
		(end 97.258632 -293.021004)
		(width 0.1143)
		(layer "In13.Cu")
		(net "P5E_CPU1_P0_RX_DN<0>")
	)
	(segment
		(start 97.189036 -289.82162)
		(end 97.258632 -289.78098)
		(width 0.1143)
		(layer "In13.Cu")
		(net "P5E_CPU1_P0_RX_DN<0>")
	)
	(segment
		(start 109.244892 -310.443372)
		(end 108.840016 -310.110124)
		(width 0.14224)
		(layer "In13.Cu")
		(net "P5E_CPU1_P0_RX_DN<0>")
	)
	(segment
		(start 48.145192 -385.404868)
		(end 48.266858 -385.334764)
		(width 0.14224)
		(layer "In13.Cu")
		(net "P5E_CPU1_P0_RX_DN<0>")
	)
	(segment
		(start 96.430084 -299.4279)
		(end 96.430084 -296.422318)
		(width 0.14224)
		(layer "In13.Cu")
		(net "P5E_CPU1_P0_RX_DN<0>")
	)
	(segment
		(start 97.258632 -290.791392)
		(end 97.189036 -290.750752)
		(width 0.1143)
		(layer "In13.Cu")
		(net "P5E_CPU1_P0_RX_DN<0>")
	)
	(segment
		(start 48.144684 -385.405376)
		(end 48.145192 -385.404868)
		(width 0.14224)
		(layer "In13.Cu")
		(net "P5E_CPU1_P0_RX_DN<0>")
	)
	(segment
		(start 121.925588 -331.574902)
		(end 120.505728 -326.563482)
		(width 0.14224)
		(layer "In13.Cu")
		(net "P5E_CPU1_P0_RX_DN<0>")
	)
	(segment
		(start 96.727518 -295.618408)
		(end 96.90862 -295.43756)
		(width 0.1143)
		(layer "In13.Cu")
		(net "P5E_CPU1_P0_RX_DN<0>")
	)
	(segment
		(start 98.27895 -271.656302)
		(end 97.981008 -271.656302)
		(width 0.1143)
		(layer "In13.Cu")
		(net "P5E_CPU1_P0_RX_DN<0>")
	)
	(segment
		(start 102.31882 -357.847646)
		(end 101.158802 -356.435152)
		(width 0.14224)
		(layer "In13.Cu")
		(net "P5E_CPU1_P0_RX_DN<0>")
	)
	(segment
		(start 97.258632 -285.93161)
		(end 97.189036 -285.89097)
		(width 0.1143)
		(layer "In13.Cu")
		(net "P5E_CPU1_P0_RX_DN<0>")
	)
	(segment
		(start 122.909838 -351.280476)
		(end 123.3551 -350.915478)
		(width 0.14224)
		(layer "In13.Cu")
		(net "P5E_CPU1_P0_RX_DN<0>")
	)
	(segment
		(start 63.381128 -360.849672)
		(end 98.840544 -360.849672)
		(width 0.14224)
		(layer "In13.Cu")
		(net "P5E_CPU1_P0_RX_DN<0>")
	)
	(segment
		(start 97.258632 -282.691586)
		(end 97.189036 -282.650946)
		(width 0.1143)
		(layer "In13.Cu")
		(net "P5E_CPU1_P0_RX_DN<0>")
	)
	(segment
		(start 102.299262 -358.047544)
		(end 102.31882 -357.847646)
		(width 0.14224)
		(layer "In13.Cu")
		(net "P5E_CPU1_P0_RX_DN<0>")
	)
	(segment
		(start 97.198434 -286.575754)
		(end 97.260664 -286.53994)
		(width 0.1143)
		(layer "In13.Cu")
		(net "P5E_CPU1_P0_RX_DN<0>")
	)
	(segment
		(start 121.927366 -352.08591)
		(end 122.367294 -351.72523)
		(width 0.14224)
		(layer "In13.Cu")
		(net "P5E_CPU1_P0_RX_DN<0>")
	)
	(segment
		(start 106.191558 -352.303334)
		(end 106.703622 -352.92665)
		(width 0.14224)
		(layer "In13.Cu")
		(net "P5E_CPU1_P0_RX_DN<0>")
	)
	(segment
		(start 48.25873 -382.553464)
		(end 46.503844 -374.899174)
		(width 0.14224)
		(layer "In13.Cu")
		(net "P5E_CPU1_P0_RX_DN<0>")
	)
	(segment
		(start 111.14786 -352.1456)
		(end 111.2901 -352.28784)
		(width 0.14224)
		(layer "In13.Cu")
		(net "P5E_CPU1_P0_RX_DN<0>")
	)
	(segment
		(start 97.258632 -274.591526)
		(end 97.189036 -274.550886)
		(width 0.1143)
		(layer "In13.Cu")
		(net "P5E_CPU1_P0_RX_DN<0>")
	)
	(segment
		(start 123.37415 -350.722438)
		(end 123.70435 -350.451674)
		(width 0.14224)
		(layer "In13.Cu")
		(net "P5E_CPU1_P0_RX_DN<0>")
	)
	(segment
		(start 112.002824 -313.803792)
		(end 109.244892 -310.443372)
		(width 0.14224)
		(layer "In13.Cu")
		(net "P5E_CPU1_P0_RX_DN<0>")
	)
	(segment
		(start 97.189036 -283.341826)
		(end 97.258632 -283.301186)
		(width 0.1143)
		(layer "In13.Cu")
		(net "P5E_CPU1_P0_RX_DN<0>")
	)
	(segment
		(start 97.258632 -284.311598)
		(end 97.189036 -284.270958)
		(width 0.1143)
		(layer "In13.Cu")
		(net "P5E_CPU1_P0_RX_DN<0>")
	)
	(segment
		(start 98.3488 -271.726152)
		(end 98.27895 -271.656302)
		(width 0.1143)
		(layer "In13.Cu")
		(net "P5E_CPU1_P0_RX_DN<0>")
	)
	(segment
		(start 50.836576 -367.347246)
		(end 62.652148 -361.03179)
		(width 0.14224)
		(layer "In13.Cu")
		(net "P5E_CPU1_P0_RX_DN<0>")
	)
	(segment
		(start 97.19691 -286.57677)
		(end 97.198434 -286.575754)
		(width 0.1143)
		(layer "In13.Cu")
		(net "P5E_CPU1_P0_RX_DN<0>")
	)
	(segment
		(start 97.698814 -272.78838)
		(end 97.700084 -272.787618)
		(width 0.1143)
		(layer "In13.Cu")
		(net "P5E_CPU1_P0_RX_DN<0>")
	)
	(segment
		(start 48.25873 -383.93116)
		(end 48.25873 -382.553464)
		(width 0.14224)
		(layer "In13.Cu")
		(net "P5E_CPU1_P0_RX_DN<0>")
	)
	(segment
		(start 46.573186 -373.442992)
		(end 50.279808 -367.895378)
		(width 0.14224)
		(layer "In13.Cu")
		(net "P5E_CPU1_P0_RX_DN<0>")
	)
	(segment
		(start 109.764576 -350.012)
		(end 120.0023 -350.012)
		(width 0.14224)
		(layer "In13.Cu")
		(net "P5E_CPU1_P0_RX_DN<0>")
	)
	(segment
		(start 103.616506 -356.965758)
		(end 108.443268 -353.003612)
		(width 0.14224)
		(layer "In13.Cu")
		(net "P5E_CPU1_P0_RX_DN<0>")
	)
	(segment
		(start 122.386598 -351.53219)
		(end 122.716798 -351.261426)
		(width 0.14224)
		(layer "In13.Cu")
		(net "P5E_CPU1_P0_RX_DN<0>")
	)
	(segment
		(start 103.733854 -307.24983)
		(end 96.796606 -300.312582)
		(width 0.14224)
		(layer "In13.Cu")
		(net "P5E_CPU1_P0_RX_DN<0>")
	)
	(segment
		(start 97.189036 -288.201608)
		(end 97.260664 -288.159952)
		(width 0.1143)
		(layer "In13.Cu")
		(net "P5E_CPU1_P0_RX_DN<0>")
	)
	(segment
		(start 103.416608 -356.9462)
		(end 103.616506 -356.965758)
		(width 0.14224)
		(layer "In13.Cu")
		(net "P5E_CPU1_P0_RX_DN<0>")
	)
	(segment
		(start 96.430084 -296.39387)
		(end 96.475804 -296.34815)
		(width 0.1143)
		(layer "In13.Cu")
		(net "P5E_CPU1_P0_RX_DN<0>")
	)
	(segment
		(start 101.158802 -356.435152)
		(end 101.201474 -356.002844)
		(width 0.14224)
		(layer "In13.Cu")
		(net "P5E_CPU1_P0_RX_DN<0>")
	)
	(segment
		(start 97.191068 -286.580072)
		(end 97.19691 -286.57677)
		(width 0.1143)
		(layer "In13.Cu")
		(net "P5E_CPU1_P0_RX_DN<0>")
	)
	(segment
		(start 122.716798 -351.261426)
		(end 122.909838 -351.280476)
		(width 0.14224)
		(layer "In13.Cu")
		(net "P5E_CPU1_P0_RX_DN<0>")
	)
	(segment
		(start 120.505728 -326.563482)
		(end 117.397022 -321.077336)
		(width 0.14224)
		(layer "In13.Cu")
		(net "P5E_CPU1_P0_RX_DN<0>")
	)
	(segment
		(start 117.397022 -321.077336)
		(end 112.002824 -313.803792)
		(width 0.14224)
		(layer "In13.Cu")
		(net "P5E_CPU1_P0_RX_DN<0>")
	)
	(segment
		(start 97.189036 -286.581596)
		(end 97.191068 -286.580072)
		(width 0.1143)
		(layer "In13.Cu")
		(net "P5E_CPU1_P0_RX_DN<0>")
	)
	(segment
		(start 105.759504 -352.260662)
		(end 106.191558 -352.303334)
		(width 0.14224)
		(layer "In13.Cu")
		(net "P5E_CPU1_P0_RX_DN<0>")
	)
	(segment
		(start 97.658936 -272.811748)
		(end 97.698052 -272.788888)
		(width 0.1143)
		(layer "In13.Cu")
		(net "P5E_CPU1_P0_RX_DN<0>")
	)
	(segment
		(start 97.258632 -276.211538)
		(end 97.189036 -276.170898)
		(width 0.1143)
		(layer "In13.Cu")
		(net "P5E_CPU1_P0_RX_DN<0>")
	)
	(segment
		(start 97.189036 -291.441632)
		(end 97.258632 -291.400992)
		(width 0.1143)
		(layer "In13.Cu")
		(net "P5E_CPU1_P0_RX_DN<0>")
	)
	(segment
		(start 97.189036 -273.621754)
		(end 97.258632 -273.581114)
		(width 0.1143)
		(layer "In13.Cu")
		(net "P5E_CPU1_P0_RX_DN<0>")
	)
	(segment
		(start 97.189036 -278.48179)
		(end 97.258632 -278.44115)
		(width 0.1143)
		(layer "In13.Cu")
		(net "P5E_CPU1_P0_RX_DN<0>")
	)
	(segment
		(start 120.0023 -351.43186)
		(end 111.2901 -351.43186)
		(width 0.14224)
		(layer "In13.Cu")
		(net "P5E_CPU1_P0_RX_DN<0>")
	)
	(segment
		(start 102.299008 -358.047544)
		(end 102.299262 -358.047544)
		(width 0.14224)
		(layer "In13.Cu")
		(net "P5E_CPU1_P0_RX_DN<0>")
	)
	(segment
		(start 97.189036 -294.681656)
		(end 97.258632 -294.641016)
		(width 0.1143)
		(layer "In13.Cu")
		(net "P5E_CPU1_P0_RX_DN<0>")
	)
	(segment
		(start 96.430084 -296.422318)
		(end 96.430084 -296.39387)
		(width 0.1143)
		(layer "In13.Cu")
		(net "P5E_CPU1_P0_RX_DN<0>")
	)
	(segment
		(start 97.258632 -294.031416)
		(end 97.189036 -293.990776)
		(width 0.1143)
		(layer "In13.Cu")
		(net "P5E_CPU1_P0_RX_DN<0>")
	)
	(segment
		(start 111.2901 -351.43186)
		(end 111.14786 -351.5741)
		(width 0.14224)
		(layer "In13.Cu")
		(net "P5E_CPU1_P0_RX_DN<0>")
	)
	(segment
		(start 47.949866 -384.84683)
		(end 47.954692 -384.234944)
		(width 0.14224)
		(layer "In13.Cu")
		(net "P5E_CPU1_P0_RX_DN<0>")
	)
	(segment
		(start 48.266858 -385.334764)
		(end 48.266858 -385.163822)
		(width 0.14224)
		(layer "In13.Cu")
		(net "P5E_CPU1_P0_RX_DN<0>")
	)
	(segment
		(start 97.189036 -275.241766)
		(end 97.258632 -275.201126)
		(width 0.1143)
		(layer "In13.Cu")
		(net "P5E_CPU1_P0_RX_DN<0>")
	)
	(segment
		(start 108.985304 -352.55835)
		(end 109.314996 -352.28784)
		(width 0.14224)
		(layer "In13.Cu")
		(net "P5E_CPU1_P0_RX_DN<0>")
	)
	(segment
		(start 109.455458 -352.147378)
		(end 109.455458 -350.321118)
		(width 0.14224)
		(layer "In13.Cu")
		(net "P5E_CPU1_P0_RX_DN<0>")
	)
	(segment
		(start 50.360072 -367.797588)
		(end 50.735484 -367.422176)
		(width 0.14224)
		(layer "In13.Cu")
		(net "P5E_CPU1_P0_RX_DN<0>")
	)
	(segment
		(start 111.2901 -352.28784)
		(end 121.363232 -352.28784)
		(width 0.14224)
		(layer "In13.Cu")
		(net "P5E_CPU1_P0_RX_DN<0>")
	)
	(segment
		(start 97.258632 -292.411404)
		(end 97.189036 -292.370764)
		(width 0.1143)
		(layer "In13.Cu")
		(net "P5E_CPU1_P0_RX_DN<0>")
	)
	(segment
		(start 97.258632 -289.17138)
		(end 97.189036 -289.13074)
		(width 0.1143)
		(layer "In13.Cu")
		(net "P5E_CPU1_P0_RX_DN<0>")
	)
	(segment
		(start 123.3551 -350.915478)
		(end 123.37415 -350.722438)
		(width 0.14224)
		(layer "In13.Cu")
		(net "P5E_CPU1_P0_RX_DN<0>")
	)
	(segment
		(start 46.48962 -374.773698)
		(end 46.48962 -373.718582)
		(width 0.14224)
		(layer "In13.Cu")
		(net "P5E_CPU1_P0_RX_DN<0>")
	)
	(segment
		(start 97.19056 -276.860762)
		(end 97.259648 -276.820376)
		(width 0.1143)
		(layer "In13.Cu")
		(net "P5E_CPU1_P0_RX_DN<0>")
	)
	(segment
		(start 120.30964 -350.31934)
		(end 120.30964 -351.12452)
		(width 0.14224)
		(layer "In13.Cu")
		(net "P5E_CPU1_P0_RX_DN<0>")
	)
	(segment
		(start 47.79137 -385.31038)
		(end 48.144684 -385.405376)
		(width 0.14224)
		(layer "In13.Cu")
		(net "P5E_CPU1_P0_RX_DN<0>")
	)
	(segment
		(start 108.443268 -353.003612)
		(end 108.462064 -352.810572)
		(width 0.14224)
		(layer "In13.Cu")
		(net "P5E_CPU1_P0_RX_DN<0>")
	)
	(segment
		(start 97.698052 -272.788888)
		(end 97.698814 -272.78838)
		(width 0.1143)
		(layer "In13.Cu")
		(net "P5E_CPU1_P0_RX_DN<0>")
	)
	(segment
		(start 111.14786 -351.5741)
		(end 111.14786 -352.1456)
		(width 0.14224)
		(layer "In13.Cu")
		(net "P5E_CPU1_P0_RX_DN<0>")
	)
	(segment
		(start 120.30964 -351.12452)
		(end 120.0023 -351.43186)
		(width 0.14224)
		(layer "In13.Cu")
		(net "P5E_CPU1_P0_RX_DN<0>")
	)
	(segment
		(start 47.954692 -384.234944)
		(end 48.25873 -383.93116)
		(width 0.14224)
		(layer "In13.Cu")
		(net "P5E_CPU1_P0_RX_DN<0>")
	)
	(segment
		(start 103.0732 -356.304088)
		(end 103.053642 -356.503986)
		(width 0.14224)
		(layer "In13.Cu")
		(net "P5E_CPU1_P0_RX_DN<0>")
	)
	(segment
		(start 109.455458 -350.321118)
		(end 109.764576 -350.012)
		(width 0.14224)
		(layer "In13.Cu")
		(net "P5E_CPU1_P0_RX_DN<0>")
	)
	(segment
		(start 97.189036 -280.101802)
		(end 97.258632 -280.061162)
		(width 0.1143)
		(layer "In13.Cu")
		(net "P5E_CPU1_P0_RX_DN<0>")
	)
	(segment
		(start 98.12909 -272.001742)
		(end 98.198686 -271.961102)
		(width 0.1143)
		(layer "In13.Cu")
		(net "P5E_CPU1_P0_RX_DN<0>")
	)
	(segment
		(start 97.189036 -281.721814)
		(end 97.258632 -281.681174)
		(width 0.1143)
		(layer "In13.Cu")
		(net "P5E_CPU1_P0_RX_DN<0>")
	)
	(segment
		(start 97.258632 -281.071574)
		(end 97.189036 -281.030934)
		(width 0.1143)
		(layer "In13.Cu")
		(net "P5E_CPU1_P0_RX_DN<0>")
	)
	(segment
		(start 123.70435 -350.451674)
		(end 123.89739 -350.470978)
		(width 0.14224)
		(layer "In13.Cu")
		(net "P5E_CPU1_P0_RX_DN<0>")
	)
	(segment
		(start 97.19056 -277.791926)
		(end 97.180908 -277.785068)
		(width 0.1143)
		(layer "In13.Cu")
		(net "P5E_CPU1_P0_RX_DN<0>")
	)
	(segment
		(start 122.367294 -351.72523)
		(end 122.386598 -351.53219)
		(width 0.14224)
		(layer "In13.Cu")
		(net "P5E_CPU1_P0_RX_DN<0>")
	)
	(segment
		(start 108.840016 -310.110124)
		(end 104.360472 -307.71465)
		(width 0.14224)
		(layer "In13.Cu")
		(net "P5E_CPU1_P0_RX_DN<0>")
	)
	(segment
		(start 97.258632 -287.551622)
		(end 97.191576 -287.512506)
		(width 0.1143)
		(layer "In13.Cu")
		(net "P5E_CPU1_P0_RX_DN<0>")
	)
	(segment
		(start 48.266858 -385.163822)
		(end 47.949866 -384.84683)
		(width 0.14224)
		(layer "In13.Cu")
		(net "P5E_CPU1_P0_RX_DN<0>")
	)
	(segment
		(start 123.89739 -350.470978)
		(end 125.044708 -349.530416)
		(width 0.14224)
		(layer "In13.Cu")
		(net "P5E_CPU1_P0_RX_DN<0>")
	)
	(segment
		(start 106.703622 -352.92665)
		(end 106.66095 -353.358704)
		(width 0.14224)
		(layer "In13.Cu")
		(net "P5E_CPU1_P0_RX_DN<0>")
	)
	(segment
		(start 103.053642 -356.503986)
		(end 103.416608 -356.9462)
		(width 0.14224)
		(layer "In13.Cu")
		(net "P5E_CPU1_P0_RX_DN<0>")
	)
	(segment
		(start 109.314996 -352.28784)
		(end 109.455458 -352.147378)
		(width 0.14224)
		(layer "In13.Cu")
		(net "P5E_CPU1_P0_RX_DN<0>")
	)
	(segment
		(start 97.258632 -277.83155)
		(end 97.19056 -277.791926)
		(width 0.1143)
		(layer "In13.Cu")
		(net "P5E_CPU1_P0_RX_DN<0>")
	)
	(segment
		(start 96.475804 -296.34815)
		(end 96.475804 -296.226738)
		(width 0.1143)
		(layer "In13.Cu")
		(net "P5E_CPU1_P0_RX_DN<0>")
	)
	(segment
		(start 96.945958 -295.34739)
		(end 96.945958 -295.146222)
		(width 0.1143)
		(layer "In13.Cu")
		(net "P5E_CPU1_P0_RX_DN<0>")
	)
	(segment
		(start 108.462064 -352.810572)
		(end 108.792264 -352.539554)
		(width 0.14224)
		(layer "In13.Cu")
		(net "P5E_CPU1_P0_RX_DN<0>")
	)
	(segment
		(start 97.700084 -272.787618)
		(end 97.729802 -272.7706)
		(width 0.1143)
		(layer "In13.Cu")
		(net "P5E_CPU1_P0_RX_DN<0>")
	)
	(segment
		(start 101.201474 -356.002844)
		(end 105.759504 -352.260662)
		(width 0.14224)
		(layer "In13.Cu")
		(net "P5E_CPU1_P0_RX_DN<0>")
	)
	(segment
		(start 97.258632 -279.451562)
		(end 97.189036 -279.410922)
		(width 0.1143)
		(layer "In13.Cu")
		(net "P5E_CPU1_P0_RX_DN<0>")
	)
	(segment
		(start 98.921316 -360.820462)
		(end 102.299008 -358.047544)
		(width 0.14224)
		(layer "In13.Cu")
		(net "P5E_CPU1_P0_RX_DN<0>")
	)
	(segment
		(start 120.0023 -350.012)
		(end 120.30964 -350.31934)
		(width 0.14224)
		(layer "In13.Cu")
		(net "P5E_CPU1_P0_RX_DN<0>")
	)
	(segment
		(start 125.334522 -348.722188)
		(end 121.925588 -331.574902)
		(width 0.14224)
		(layer "In13.Cu")
		(net "P5E_CPU1_P0_RX_DN<0>")
	)
	(segment
		(start 106.66095 -353.358704)
		(end 103.0732 -356.304088)
		(width 0.14224)
		(layer "In13.Cu")
		(net "P5E_CPU1_P0_RX_DN<0>")
	)
	(segment
		(start 97.180908 -276.86762)
		(end 97.19056 -276.860762)
		(width 0.1143)
		(layer "In13.Cu")
		(net "P5E_CPU1_P0_RX_DN<0>")
	)
	(segment
		(start 97.189036 -284.961838)
		(end 97.258632 -284.921198)
		(width 0.1143)
		(layer "In13.Cu")
		(net "P5E_CPU1_P0_RX_DN<0>")
	)
	(arc
		(start 97.415604 -287.856422)
		(mid 97.374055 -287.685)
		(end 97.258632 -287.551622)
		(width 0.1143)
		(layer "In13.Cu")
		(net "P5E_CPU1_P0_RX_DN<0>")
	)
	(arc
		(start 97.189036 -290.750752)
		(mid 96.945709 -290.286186)
		(end 97.189036 -289.82162)
		(width 0.1143)
		(layer "In13.Cu")
		(net "P5E_CPU1_P0_RX_DN<0>")
	)
	(arc
		(start 97.415604 -273.276314)
		(mid 97.480119 -273.014095)
		(end 97.658936 -272.811748)
		(width 0.1143)
		(layer "In13.Cu")
		(net "P5E_CPU1_P0_RX_DN<0>")
	)
	(arc
		(start 121.363232 -352.28784)
		(mid 121.662803 -352.235786)
		(end 121.927366 -352.08591)
		(width 0.14224)
		(layer "In13.Cu")
		(net "P5E_CPU1_P0_RX_DN<0>")
	)
	(arc
		(start 97.189036 -293.990776)
		(mid 96.945709 -293.52621)
		(end 97.189036 -293.061644)
		(width 0.1143)
		(layer "In13.Cu")
		(net "P5E_CPU1_P0_RX_DN<0>")
	)
	(arc
		(start 98.840544 -360.849672)
		(mid 98.883453 -360.842054)
		(end 98.921316 -360.820462)
		(width 0.14224)
		(layer "In13.Cu")
		(net "P5E_CPU1_P0_RX_DN<0>")
	)
	(arc
		(start 97.258632 -273.581114)
		(mid 97.374059 -273.447738)
		(end 97.415604 -273.276314)
		(width 0.1143)
		(layer "In13.Cu")
		(net "P5E_CPU1_P0_RX_DN<0>")
	)
	(arc
		(start 97.258632 -294.641016)
		(mid 97.415609 -294.336216)
		(end 97.258632 -294.031416)
		(width 0.1143)
		(layer "In13.Cu")
		(net "P5E_CPU1_P0_RX_DN<0>")
	)
	(arc
		(start 46.48962 -373.718582)
		(mid 46.511015 -373.574608)
		(end 46.573186 -373.442992)
		(width 0.14224)
		(layer "In13.Cu")
		(net "P5E_CPU1_P0_RX_DN<0>")
	)
	(arc
		(start 98.198686 -271.961102)
		(mid 98.296451 -271.858126)
		(end 98.3488 -271.726152)
		(width 0.1143)
		(layer "In13.Cu")
		(net "P5E_CPU1_P0_RX_DN<0>")
	)
	(arc
		(start 97.258632 -278.44115)
		(mid 97.415609 -278.13635)
		(end 97.258632 -277.83155)
		(width 0.1143)
		(layer "In13.Cu")
		(net "P5E_CPU1_P0_RX_DN<0>")
	)
	(arc
		(start 97.258632 -281.681174)
		(mid 97.415609 -281.376374)
		(end 97.258632 -281.071574)
		(width 0.1143)
		(layer "In13.Cu")
		(net "P5E_CPU1_P0_RX_DN<0>")
	)
	(arc
		(start 97.189036 -292.370764)
		(mid 96.945709 -291.906198)
		(end 97.189036 -291.441632)
		(width 0.1143)
		(layer "In13.Cu")
		(net "P5E_CPU1_P0_RX_DN<0>")
	)
	(arc
		(start 97.189036 -284.270958)
		(mid 96.945709 -283.806392)
		(end 97.189036 -283.341826)
		(width 0.1143)
		(layer "In13.Cu")
		(net "P5E_CPU1_P0_RX_DN<0>")
	)
	(arc
		(start 97.258632 -283.301186)
		(mid 97.415609 -282.996386)
		(end 97.258632 -282.691586)
		(width 0.1143)
		(layer "In13.Cu")
		(net "P5E_CPU1_P0_RX_DN<0>")
	)
	(arc
		(start 97.258632 -291.400992)
		(mid 97.415609 -291.096192)
		(end 97.258632 -290.791392)
		(width 0.1143)
		(layer "In13.Cu")
		(net "P5E_CPU1_P0_RX_DN<0>")
	)
	(arc
		(start 97.258632 -284.921198)
		(mid 97.415609 -284.616398)
		(end 97.258632 -284.311598)
		(width 0.1143)
		(layer "In13.Cu")
		(net "P5E_CPU1_P0_RX_DN<0>")
	)
	(arc
		(start 97.189036 -282.650946)
		(mid 96.945709 -282.18638)
		(end 97.189036 -281.721814)
		(width 0.1143)
		(layer "In13.Cu")
		(net "P5E_CPU1_P0_RX_DN<0>")
	)
	(arc
		(start 96.90862 -295.43756)
		(mid 96.936209 -295.396175)
		(end 96.945958 -295.34739)
		(width 0.1143)
		(layer "In13.Cu")
		(net "P5E_CPU1_P0_RX_DN<0>")
	)
	(arc
		(start 97.258632 -280.061162)
		(mid 97.415609 -279.756362)
		(end 97.258632 -279.451562)
		(width 0.1143)
		(layer "In13.Cu")
		(net "P5E_CPU1_P0_RX_DN<0>")
	)
	(arc
		(start 62.652148 -361.03179)
		(mid 63.0054 -360.895736)
		(end 63.381128 -360.849672)
		(width 0.14224)
		(layer "In13.Cu")
		(net "P5E_CPU1_P0_RX_DN<0>")
	)
	(arc
		(start 125.044708 -349.530416)
		(mid 125.301503 -349.166427)
		(end 125.334522 -348.722188)
		(width 0.14224)
		(layer "In13.Cu")
		(net "P5E_CPU1_P0_RX_DN<0>")
	)
	(arc
		(start 97.260664 -286.53994)
		(mid 97.374593 -286.406793)
		(end 97.415604 -286.23641)
		(width 0.1143)
		(layer "In13.Cu")
		(net "P5E_CPU1_P0_RX_DN<0>")
	)
	(arc
		(start 97.189036 -289.13074)
		(mid 96.945709 -288.666174)
		(end 97.189036 -288.201608)
		(width 0.1143)
		(layer "In13.Cu")
		(net "P5E_CPU1_P0_RX_DN<0>")
	)
	(arc
		(start 97.258632 -293.021004)
		(mid 97.415609 -292.716204)
		(end 97.258632 -292.411404)
		(width 0.1143)
		(layer "In13.Cu")
		(net "P5E_CPU1_P0_RX_DN<0>")
	)
	(arc
		(start 50.279808 -367.895378)
		(mid 50.317529 -367.844503)
		(end 50.360072 -367.797588)
		(width 0.14224)
		(layer "In13.Cu")
		(net "P5E_CPU1_P0_RX_DN<0>")
	)
	(arc
		(start 97.189036 -279.410922)
		(mid 96.945709 -278.946356)
		(end 97.189036 -278.48179)
		(width 0.1143)
		(layer "In13.Cu")
		(net "P5E_CPU1_P0_RX_DN<0>")
	)
	(arc
		(start 104.360472 -307.71465)
		(mid 104.030017 -307.505353)
		(end 103.733854 -307.24983)
		(width 0.14224)
		(layer "In13.Cu")
		(net "P5E_CPU1_P0_RX_DN<0>")
	)
	(arc
		(start 97.189036 -281.030934)
		(mid 96.945709 -280.566368)
		(end 97.189036 -280.101802)
		(width 0.1143)
		(layer "In13.Cu")
		(net "P5E_CPU1_P0_RX_DN<0>")
	)
	(arc
		(start 97.885758 -272.466308)
		(mid 97.950273 -272.204089)
		(end 98.12909 -272.001742)
		(width 0.1143)
		(layer "In13.Cu")
		(net "P5E_CPU1_P0_RX_DN<0>")
	)
	(arc
		(start 97.191576 -287.512506)
		(mid 96.945688 -287.047712)
		(end 97.189036 -286.581596)
		(width 0.1143)
		(layer "In13.Cu")
		(net "P5E_CPU1_P0_RX_DN<0>")
	)
	(arc
		(start 97.189036 -276.170898)
		(mid 96.945709 -275.706332)
		(end 97.189036 -275.241766)
		(width 0.1143)
		(layer "In13.Cu")
		(net "P5E_CPU1_P0_RX_DN<0>")
	)
	(arc
		(start 96.796606 -300.312582)
		(mid 96.525342 -299.906701)
		(end 96.430084 -299.4279)
		(width 0.14224)
		(layer "In13.Cu")
		(net "P5E_CPU1_P0_RX_DN<0>")
	)
	(arc
		(start 96.475804 -296.226738)
		(mid 96.541173 -295.897545)
		(end 96.727518 -295.618408)
		(width 0.1143)
		(layer "In13.Cu")
		(net "P5E_CPU1_P0_RX_DN<0>")
	)
	(arc
		(start 50.735484 -367.422176)
		(mid 50.783266 -367.38098)
		(end 50.836576 -367.347246)
		(width 0.14224)
		(layer "In13.Cu")
		(net "P5E_CPU1_P0_RX_DN<0>")
	)
	(arc
		(start 46.503844 -374.899174)
		(mid 46.493179 -374.836838)
		(end 46.48962 -374.773698)
		(width 0.14224)
		(layer "In13.Cu")
		(net "P5E_CPU1_P0_RX_DN<0>")
	)
	(arc
		(start 97.258632 -275.201126)
		(mid 97.415609 -274.896326)
		(end 97.258632 -274.591526)
		(width 0.1143)
		(layer "In13.Cu")
		(net "P5E_CPU1_P0_RX_DN<0>")
	)
	(arc
		(start 97.258632 -289.78098)
		(mid 97.415609 -289.47618)
		(end 97.258632 -289.17138)
		(width 0.1143)
		(layer "In13.Cu")
		(net "P5E_CPU1_P0_RX_DN<0>")
	)
	(arc
		(start 97.189036 -274.550886)
		(mid 96.945709 -274.08632)
		(end 97.189036 -273.621754)
		(width 0.1143)
		(layer "In13.Cu")
		(net "P5E_CPU1_P0_RX_DN<0>")
	)
	(arc
		(start 97.362264 -276.708616)
		(mid 97.407542 -276.439869)
		(end 97.258632 -276.211538)
		(width 0.1143)
		(layer "In13.Cu")
		(net "P5E_CPU1_P0_RX_DN<0>")
	)
	(arc
		(start 97.260664 -288.159952)
		(mid 97.374593 -288.026805)
		(end 97.415604 -287.856422)
		(width 0.1143)
		(layer "In13.Cu")
		(net "P5E_CPU1_P0_RX_DN<0>")
	)
	(arc
		(start 97.415604 -286.23641)
		(mid 97.374055 -286.064988)
		(end 97.258632 -285.93161)
		(width 0.1143)
		(layer "In13.Cu")
		(net "P5E_CPU1_P0_RX_DN<0>")
	)
	(arc
		(start 97.180908 -277.785068)
		(mid 96.944201 -277.326344)
		(end 97.180908 -276.86762)
		(width 0.1143)
		(layer "In13.Cu")
		(net "P5E_CPU1_P0_RX_DN<0>")
	)
	(arc
		(start 97.189036 -285.89097)
		(mid 96.945709 -285.426404)
		(end 97.189036 -284.961838)
		(width 0.1143)
		(layer "In13.Cu")
		(net "P5E_CPU1_P0_RX_DN<0>")
	)
	(arc
		(start 97.259648 -276.820376)
		(mid 97.316677 -276.769749)
		(end 97.362264 -276.708616)
		(width 0.1143)
		(layer "In13.Cu")
		(net "P5E_CPU1_P0_RX_DN<0>")
	)
	(arc
		(start 96.945958 -295.146222)
		(mid 97.010332 -294.884018)
		(end 97.189036 -294.681656)
		(width 0.1143)
		(layer "In13.Cu")
		(net "P5E_CPU1_P0_RX_DN<0>")
	)
	(arc
		(start 97.729802 -272.7706)
		(mid 97.844478 -272.637266)
		(end 97.885758 -272.466308)
		(width 0.1143)
		(layer "In13.Cu")
		(net "P5E_CPU1_P0_RX_DN<0>")
	)
	(segment
		(start 378.027692 -382.34493)
		(end 378.298202 -382.61544)
		(width 0.12954)
		(layer "F.Cu")
		(net "P5E_CPU0_P3_TX_DP<7>")
	)
	(segment
		(start 378.298202 -382.61544)
		(end 378.298202 -383.31902)
		(width 0.12954)
		(layer "F.Cu")
		(net "P5E_CPU0_P3_TX_DP<7>")
	)
	(segment
		(start 378.298202 -383.31902)
		(end 378.002292 -383.61493)
		(width 0.12954)
		(layer "F.Cu")
		(net "P5E_CPU0_P3_TX_DP<7>")
	)
	(segment
		(start 367.067846 -274.630134)
		(end 367.534698 -274.896072)
		(width 0.12954)
		(layer "F.Cu")
		(net "P5E_CPU0_P3_TX_DP<7>")
	)
	(segment
		(start 367.25352 -293.204392)
		(end 367.254282 -293.2049)
		(width 0.1143)
		(layer "In11.Cu")
		(net "P5E_CPU0_P3_TX_DP<7>")
	)
	(segment
		(start 367.534698 -274.896072)
		(end 367.83264 -274.896072)
		(width 0.1143)
		(layer "In11.Cu")
		(net "P5E_CPU0_P3_TX_DP<7>")
	)
	(segment
		(start 367.252504 -276.02942)
		(end 367.25225 -276.029674)
		(width 0.1143)
		(layer "In11.Cu")
		(net "P5E_CPU0_P3_TX_DP<7>")
	)
	(segment
		(start 367.252504 -291.583872)
		(end 367.253774 -291.584634)
		(width 0.1143)
		(layer "In11.Cu")
		(net "P5E_CPU0_P3_TX_DP<7>")
	)
	(segment
		(start 367.682018 -295.610026)
		(end 367.692178 -295.616122)
		(width 0.1143)
		(layer "In11.Cu")
		(net "P5E_CPU0_P3_TX_DP<7>")
	)
	(segment
		(start 367.238788 -278.616156)
		(end 367.23955 -278.616664)
		(width 0.1143)
		(layer "In11.Cu")
		(net "P5E_CPU0_P3_TX_DP<7>")
	)
	(segment
		(start 366.742726 -277.790656)
		(end 366.749584 -277.79472)
		(width 0.1143)
		(layer "In11.Cu")
		(net "P5E_CPU0_P3_TX_DP<7>")
	)
	(segment
		(start 384.926332 -361.65917)
		(end 384.640582 -362.528358)
		(width 0.14224)
		(layer "In11.Cu")
		(net "P5E_CPU0_P3_TX_DP<7>")
	)
	(segment
		(start 378.318522 -375.92762)
		(end 378.318522 -382.0541)
		(width 0.14224)
		(layer "In11.Cu")
		(net "P5E_CPU0_P3_TX_DP<7>")
	)
	(segment
		(start 366.785398 -277.815294)
		(end 366.785906 -277.815548)
		(width 0.1143)
		(layer "In11.Cu")
		(net "P5E_CPU0_P3_TX_DP<7>")
	)
	(segment
		(start 367.251742 -292.228524)
		(end 367.251488 -292.228778)
		(width 0.1143)
		(layer "In11.Cu")
		(net "P5E_CPU0_P3_TX_DP<7>")
	)
	(segment
		(start 367.253774 -291.584634)
		(end 367.283492 -291.601652)
		(width 0.1143)
		(layer "In11.Cu")
		(net "P5E_CPU0_P3_TX_DP<7>")
	)
	(segment
		(start 366.781842 -277.813516)
		(end 366.782604 -277.814024)
		(width 0.1143)
		(layer "In11.Cu")
		(net "P5E_CPU0_P3_TX_DP<7>")
	)
	(segment
		(start 366.782604 -277.814024)
		(end 366.785398 -277.815294)
		(width 0.1143)
		(layer "In11.Cu")
		(net "P5E_CPU0_P3_TX_DP<7>")
	)
	(segment
		(start 367.25352 -288.987484)
		(end 367.252504 -288.987992)
		(width 0.1143)
		(layer "In11.Cu")
		(net "P5E_CPU0_P3_TX_DP<7>")
	)
	(segment
		(start 367.273332 -285.73603)
		(end 367.249964 -285.749492)
		(width 0.1143)
		(layer "In11.Cu")
		(net "P5E_CPU0_P3_TX_DP<7>")
	)
	(segment
		(start 367.752376 -280.060908)
		(end 367.68278 -280.101548)
		(width 0.1143)
		(layer "In11.Cu")
		(net "P5E_CPU0_P3_TX_DP<7>")
	)
	(segment
		(start 367.213642 -278.601424)
		(end 367.236756 -278.614886)
		(width 0.1143)
		(layer "In11.Cu")
		(net "P5E_CPU0_P3_TX_DP<7>")
	)
	(segment
		(start 367.863882 -297.151298)
		(end 368.886232 -300.522386)
		(width 0.14224)
		(layer "In11.Cu")
		(net "P5E_CPU0_P3_TX_DP<7>")
	)
	(segment
		(start 384.594862 -362.646214)
		(end 382.278636 -367.791492)
		(width 0.14224)
		(layer "In11.Cu")
		(net "P5E_CPU0_P3_TX_DP<7>")
	)
	(segment
		(start 367.249964 -285.749492)
		(end 367.249202 -285.75)
		(width 0.1143)
		(layer "In11.Cu")
		(net "P5E_CPU0_P3_TX_DP<7>")
	)
	(segment
		(start 367.23955 -278.616664)
		(end 367.240566 -278.617172)
		(width 0.1143)
		(layer "In11.Cu")
		(net "P5E_CPU0_P3_TX_DP<7>")
	)
	(segment
		(start 367.251488 -293.203376)
		(end 367.251742 -293.203376)
		(width 0.1143)
		(layer "In11.Cu")
		(net "P5E_CPU0_P3_TX_DP<7>")
	)
	(segment
		(start 367.246662 -278.620474)
		(end 367.247424 -278.620982)
		(width 0.1143)
		(layer "In11.Cu")
		(net "P5E_CPU0_P3_TX_DP<7>")
	)
	(segment
		(start 367.251996 -278.623522)
		(end 367.25352 -278.624538)
		(width 0.1143)
		(layer "In11.Cu")
		(net "P5E_CPU0_P3_TX_DP<7>")
	)
	(segment
		(start 371.1956 -303.978564)
		(end 377.988576 -312.255662)
		(width 0.14224)
		(layer "In11.Cu")
		(net "P5E_CPU0_P3_TX_DP<7>")
	)
	(segment
		(start 367.283492 -290.590224)
		(end 367.251742 -290.608512)
		(width 0.1143)
		(layer "In11.Cu")
		(net "P5E_CPU0_P3_TX_DP<7>")
	)
	(segment
		(start 367.215166 -285.082234)
		(end 367.274094 -285.116524)
		(width 0.1143)
		(layer "In11.Cu")
		(net "P5E_CPU0_P3_TX_DP<7>")
	)
	(segment
		(start 367.25606 -288.98596)
		(end 367.255298 -288.986468)
		(width 0.1143)
		(layer "In11.Cu")
		(net "P5E_CPU0_P3_TX_DP<7>")
	)
	(segment
		(start 387.326632 -353.51466)
		(end 385.611878 -359.428796)
		(width 0.14224)
		(layer "In11.Cu")
		(net "P5E_CPU0_P3_TX_DP<7>")
	)
	(segment
		(start 366.749584 -277.79472)
		(end 366.750346 -277.795228)
		(width 0.1143)
		(layer "In11.Cu")
		(net "P5E_CPU0_P3_TX_DP<7>")
	)
	(segment
		(start 378.800868 -374.644666)
		(end 378.364496 -375.69648)
		(width 0.14224)
		(layer "In11.Cu")
		(net "P5E_CPU0_P3_TX_DP<7>")
	)
	(segment
		(start 367.257838 -293.206932)
		(end 367.260378 -293.208202)
		(width 0.1143)
		(layer "In11.Cu")
		(net "P5E_CPU0_P3_TX_DP<7>")
	)
	(segment
		(start 367.68278 -279.410668)
		(end 367.721896 -279.433528)
		(width 0.1143)
		(layer "In11.Cu")
		(net "P5E_CPU0_P3_TX_DP<7>")
	)
	(segment
		(start 367.254282 -293.2049)
		(end 367.255298 -293.205408)
		(width 0.1143)
		(layer "In11.Cu")
		(net "P5E_CPU0_P3_TX_DP<7>")
	)
	(segment
		(start 367.237772 -278.615648)
		(end 367.238788 -278.616156)
		(width 0.1143)
		(layer "In11.Cu")
		(net "P5E_CPU0_P3_TX_DP<7>")
	)
	(segment
		(start 367.252504 -289.96386)
		(end 367.253774 -289.964622)
		(width 0.1143)
		(layer "In11.Cu")
		(net "P5E_CPU0_P3_TX_DP<7>")
	)
	(segment
		(start 367.25352 -278.624538)
		(end 367.254282 -278.624792)
		(width 0.1143)
		(layer "In11.Cu")
		(net "P5E_CPU0_P3_TX_DP<7>")
	)
	(segment
		(start 377.988576 -312.255662)
		(end 382.95326 -319.686178)
		(width 0.14224)
		(layer "In11.Cu")
		(net "P5E_CPU0_P3_TX_DP<7>")
	)
	(segment
		(start 382.95326 -319.686178)
		(end 384.684016 -323.862954)
		(width 0.14224)
		(layer "In11.Cu")
		(net "P5E_CPU0_P3_TX_DP<7>")
	)
	(segment
		(start 367.236756 -278.614886)
		(end 367.236502 -278.614886)
		(width 0.1143)
		(layer "In11.Cu")
		(net "P5E_CPU0_P3_TX_DP<7>")
	)
	(segment
		(start 367.260378 -293.208202)
		(end 367.283492 -293.221664)
		(width 0.1143)
		(layer "In11.Cu")
		(net "P5E_CPU0_P3_TX_DP<7>")
	)
	(segment
		(start 367.251742 -288.9885)
		(end 367.248948 -288.990024)
		(width 0.1143)
		(layer "In11.Cu")
		(net "P5E_CPU0_P3_TX_DP<7>")
	)
	(segment
		(start 367.249202 -278.621998)
		(end 367.251996 -278.623522)
		(width 0.1143)
		(layer "In11.Cu")
		(net "P5E_CPU0_P3_TX_DP<7>")
	)
	(segment
		(start 367.909602 -295.99255)
		(end 367.909602 -296.538142)
		(width 0.1143)
		(layer "In11.Cu")
		(net "P5E_CPU0_P3_TX_DP<7>")
	)
	(segment
		(start 367.21542 -283.462476)
		(end 367.283492 -283.501846)
		(width 0.1143)
		(layer "In11.Cu")
		(net "P5E_CPU0_P3_TX_DP<7>")
	)
	(segment
		(start 367.439448 -295.145968)
		(end 367.439702 -295.145968)
		(width 0.1143)
		(layer "In11.Cu")
		(net "P5E_CPU0_P3_TX_DP<7>")
	)
	(segment
		(start 367.236502 -278.614886)
		(end 367.237772 -278.615648)
		(width 0.1143)
		(layer "In11.Cu")
		(net "P5E_CPU0_P3_TX_DP<7>")
	)
	(segment
		(start 367.283492 -293.830248)
		(end 367.251742 -293.848536)
		(width 0.1143)
		(layer "In11.Cu")
		(net "P5E_CPU0_P3_TX_DP<7>")
	)
	(segment
		(start 367.21542 -281.842464)
		(end 367.283492 -281.881834)
		(width 0.1143)
		(layer "In11.Cu")
		(net "P5E_CPU0_P3_TX_DP<7>")
	)
	(segment
		(start 367.251996 -282.50642)
		(end 367.25098 -282.506928)
		(width 0.1143)
		(layer "In11.Cu")
		(net "P5E_CPU0_P3_TX_DP<7>")
	)
	(segment
		(start 367.25606 -293.205916)
		(end 367.257076 -293.206424)
		(width 0.1143)
		(layer "In11.Cu")
		(net "P5E_CPU0_P3_TX_DP<7>")
	)
	(segment
		(start 367.254282 -288.986976)
		(end 367.25352 -288.987484)
		(width 0.1143)
		(layer "In11.Cu")
		(net "P5E_CPU0_P3_TX_DP<7>")
	)
	(segment
		(start 367.255552 -287.363916)
		(end 367.250726 -287.36671)
		(width 0.1143)
		(layer "In11.Cu")
		(net "P5E_CPU0_P3_TX_DP<7>")
	)
	(segment
		(start 367.25352 -280.887678)
		(end 367.251742 -280.888694)
		(width 0.1143)
		(layer "In11.Cu")
		(net "P5E_CPU0_P3_TX_DP<7>")
	)
	(segment
		(start 367.24844 -278.62149)
		(end 367.249202 -278.621998)
		(width 0.1143)
		(layer "In11.Cu")
		(net "P5E_CPU0_P3_TX_DP<7>")
	)
	(segment
		(start 367.24463 -278.619458)
		(end 367.246662 -278.620474)
		(width 0.1143)
		(layer "In11.Cu")
		(net "P5E_CPU0_P3_TX_DP<7>")
	)
	(segment
		(start 367.251742 -280.888694)
		(end 367.25098 -280.889202)
		(width 0.1143)
		(layer "In11.Cu")
		(net "P5E_CPU0_P3_TX_DP<7>")
	)
	(segment
		(start 367.863882 -296.583862)
		(end 367.863882 -296.61231)
		(width 0.1143)
		(layer "In11.Cu")
		(net "P5E_CPU0_P3_TX_DP<7>")
	)
	(segment
		(start 367.252504 -293.203884)
		(end 367.25352 -293.204392)
		(width 0.1143)
		(layer "In11.Cu")
		(net "P5E_CPU0_P3_TX_DP<7>")
	)
	(segment
		(start 388.054596 -340.809326)
		(end 388.054596 -348.390972)
		(width 0.14224)
		(layer "In11.Cu")
		(net "P5E_CPU0_P3_TX_DP<7>")
	)
	(segment
		(start 367.255044 -278.6253)
		(end 367.25606 -278.625808)
		(width 0.1143)
		(layer "In11.Cu")
		(net "P5E_CPU0_P3_TX_DP<7>")
	)
	(segment
		(start 367.25606 -278.625808)
		(end 367.283492 -278.64181)
		(width 0.1143)
		(layer "In11.Cu")
		(net "P5E_CPU0_P3_TX_DP<7>")
	)
	(segment
		(start 367.251742 -293.848536)
		(end 367.234216 -293.858696)
		(width 0.1143)
		(layer "In11.Cu")
		(net "P5E_CPU0_P3_TX_DP<7>")
	)
	(segment
		(start 367.240566 -278.617172)
		(end 367.241328 -278.61768)
		(width 0.1143)
		(layer "In11.Cu")
		(net "P5E_CPU0_P3_TX_DP<7>")
	)
	(segment
		(start 367.863882 -296.61231)
		(end 367.863882 -297.151298)
		(width 0.14224)
		(layer "In11.Cu")
		(net "P5E_CPU0_P3_TX_DP<7>")
	)
	(segment
		(start 367.243868 -278.61895)
		(end 367.24463 -278.619458)
		(width 0.1143)
		(layer "In11.Cu")
		(net "P5E_CPU0_P3_TX_DP<7>")
	)
	(segment
		(start 367.253774 -289.964622)
		(end 367.283492 -289.98164)
		(width 0.1143)
		(layer "In11.Cu")
		(net "P5E_CPU0_P3_TX_DP<7>")
	)
	(segment
		(start 367.255298 -288.986468)
		(end 367.254282 -288.986976)
		(width 0.1143)
		(layer "In11.Cu")
		(net "P5E_CPU0_P3_TX_DP<7>")
	)
	(segment
		(start 367.241328 -278.61768)
		(end 367.243868 -278.61895)
		(width 0.1143)
		(layer "In11.Cu")
		(net "P5E_CPU0_P3_TX_DP<7>")
	)
	(segment
		(start 367.721896 -279.433528)
		(end 367.752376 -279.451308)
		(width 0.1143)
		(layer "In11.Cu")
		(net "P5E_CPU0_P3_TX_DP<7>")
	)
	(segment
		(start 367.234216 -294.813228)
		(end 367.283492 -294.841676)
		(width 0.1143)
		(layer "In11.Cu")
		(net "P5E_CPU0_P3_TX_DP<7>")
	)
	(segment
		(start 367.249202 -285.75)
		(end 367.249456 -285.75)
		(width 0.1143)
		(layer "In11.Cu")
		(net "P5E_CPU0_P3_TX_DP<7>")
	)
	(segment
		(start 367.255298 -293.205408)
		(end 367.25606 -293.205916)
		(width 0.1143)
		(layer "In11.Cu")
		(net "P5E_CPU0_P3_TX_DP<7>")
	)
	(segment
		(start 367.25225 -276.029674)
		(end 367.24844 -276.03196)
		(width 0.1143)
		(layer "In11.Cu")
		(net "P5E_CPU0_P3_TX_DP<7>")
	)
	(segment
		(start 366.813592 -276.820376)
		(end 366.742726 -276.861524)
		(width 0.1143)
		(layer "In11.Cu")
		(net "P5E_CPU0_P3_TX_DP<7>")
	)
	(segment
		(start 367.249456 -286.722312)
		(end 367.251742 -286.723582)
		(width 0.1143)
		(layer "In11.Cu")
		(net "P5E_CPU0_P3_TX_DP<7>")
	)
	(segment
		(start 367.251742 -289.963352)
		(end 367.252504 -289.96386)
		(width 0.1143)
		(layer "In11.Cu")
		(net "P5E_CPU0_P3_TX_DP<7>")
	)
	(segment
		(start 367.283492 -292.210236)
		(end 367.251742 -292.228524)
		(width 0.1143)
		(layer "In11.Cu")
		(net "P5E_CPU0_P3_TX_DP<7>")
	)
	(segment
		(start 367.752376 -275.200872)
		(end 367.68278 -275.241512)
		(width 0.1143)
		(layer "In11.Cu")
		(net "P5E_CPU0_P3_TX_DP<7>")
	)
	(segment
		(start 384.684016 -323.862954)
		(end 388.054596 -340.809326)
		(width 0.14224)
		(layer "In11.Cu")
		(net "P5E_CPU0_P3_TX_DP<7>")
	)
	(segment
		(start 367.21542 -288.322512)
		(end 367.28527 -288.363152)
		(width 0.1143)
		(layer "In11.Cu")
		(net "P5E_CPU0_P3_TX_DP<7>")
	)
	(segment
		(start 368.886232 -300.522386)
		(end 371.1956 -303.978564)
		(width 0.14224)
		(layer "In11.Cu")
		(net "P5E_CPU0_P3_TX_DP<7>")
	)
	(segment
		(start 367.251742 -286.723582)
		(end 367.28527 -286.74314)
		(width 0.1143)
		(layer "In11.Cu")
		(net "P5E_CPU0_P3_TX_DP<7>")
	)
	(segment
		(start 367.909602 -296.538142)
		(end 367.863882 -296.583862)
		(width 0.1143)
		(layer "In11.Cu")
		(net "P5E_CPU0_P3_TX_DP<7>")
	)
	(segment
		(start 367.251996 -284.126432)
		(end 367.25098 -284.12694)
		(width 0.1143)
		(layer "In11.Cu")
		(net "P5E_CPU0_P3_TX_DP<7>")
	)
	(segment
		(start 378.318522 -382.0541)
		(end 378.027692 -382.34493)
		(width 0.14224)
		(layer "In11.Cu")
		(net "P5E_CPU0_P3_TX_DP<7>")
	)
	(segment
		(start 367.248948 -289.961828)
		(end 367.251742 -289.963352)
		(width 0.1143)
		(layer "In11.Cu")
		(net "P5E_CPU0_P3_TX_DP<7>")
	)
	(segment
		(start 367.257076 -293.206424)
		(end 367.257838 -293.206932)
		(width 0.1143)
		(layer "In11.Cu")
		(net "P5E_CPU0_P3_TX_DP<7>")
	)
	(segment
		(start 366.750346 -277.795228)
		(end 366.781842 -277.813516)
		(width 0.1143)
		(layer "In11.Cu")
		(net "P5E_CPU0_P3_TX_DP<7>")
	)
	(segment
		(start 367.252504 -288.987992)
		(end 367.251742 -288.9885)
		(width 0.1143)
		(layer "In11.Cu")
		(net "P5E_CPU0_P3_TX_DP<7>")
	)
	(segment
		(start 367.251742 -291.583364)
		(end 367.252504 -291.583872)
		(width 0.1143)
		(layer "In11.Cu")
		(net "P5E_CPU0_P3_TX_DP<7>")
	)
	(segment
		(start 367.254282 -278.624792)
		(end 367.255044 -278.6253)
		(width 0.1143)
		(layer "In11.Cu")
		(net "P5E_CPU0_P3_TX_DP<7>")
	)
	(segment
		(start 367.83264 -274.896072)
		(end 367.90249 -274.965922)
		(width 0.1143)
		(layer "In11.Cu")
		(net "P5E_CPU0_P3_TX_DP<7>")
	)
	(segment
		(start 367.283492 -288.970212)
		(end 367.25606 -288.98596)
		(width 0.1143)
		(layer "In11.Cu")
		(net "P5E_CPU0_P3_TX_DP<7>")
	)
	(segment
		(start 367.247424 -278.620982)
		(end 367.24844 -278.62149)
		(width 0.1143)
		(layer "In11.Cu")
		(net "P5E_CPU0_P3_TX_DP<7>")
	)
	(segment
		(start 367.251742 -293.203376)
		(end 367.252504 -293.203884)
		(width 0.1143)
		(layer "In11.Cu")
		(net "P5E_CPU0_P3_TX_DP<7>")
	)
	(arc
		(start 367.752376 -279.451308)
		(mid 367.909353 -279.756108)
		(end 367.752376 -280.060908)
		(width 0.1143)
		(layer "In11.Cu")
		(net "P5E_CPU0_P3_TX_DP<7>")
	)
	(arc
		(start 367.283492 -283.501846)
		(mid 367.437828 -283.822656)
		(end 367.251996 -284.126432)
		(width 0.1143)
		(layer "In11.Cu")
		(net "P5E_CPU0_P3_TX_DP<7>")
	)
	(arc
		(start 384.640582 -362.528358)
		(mid 384.619277 -362.587889)
		(end 384.594862 -362.646214)
		(width 0.14224)
		(layer "In11.Cu")
		(net "P5E_CPU0_P3_TX_DP<7>")
	)
	(arc
		(start 367.439702 -295.145968)
		(mid 367.503937 -295.407714)
		(end 367.682018 -295.610026)
		(width 0.1143)
		(layer "In11.Cu")
		(net "P5E_CPU0_P3_TX_DP<7>")
	)
	(arc
		(start 367.28527 -286.74314)
		(mid 367.398677 -286.876029)
		(end 367.439448 -287.045908)
		(width 0.1143)
		(layer "In11.Cu")
		(net "P5E_CPU0_P3_TX_DP<7>")
	)
	(arc
		(start 366.742726 -276.861524)
		(mid 366.499399 -277.32609)
		(end 366.742726 -277.790656)
		(width 0.1143)
		(layer "In11.Cu")
		(net "P5E_CPU0_P3_TX_DP<7>")
	)
	(arc
		(start 366.969548 -278.136096)
		(mid 367.03427 -278.398835)
		(end 367.213642 -278.601424)
		(width 0.1143)
		(layer "In11.Cu")
		(net "P5E_CPU0_P3_TX_DP<7>")
	)
	(arc
		(start 367.68278 -280.101548)
		(mid 367.503967 -280.303898)
		(end 367.439448 -280.566114)
		(width 0.1143)
		(layer "In11.Cu")
		(net "P5E_CPU0_P3_TX_DP<7>")
	)
	(arc
		(start 366.969548 -276.516084)
		(mid 366.928293 -276.687055)
		(end 366.813592 -276.820376)
		(width 0.1143)
		(layer "In11.Cu")
		(net "P5E_CPU0_P3_TX_DP<7>")
	)
	(arc
		(start 367.68278 -275.241512)
		(mid 367.503967 -275.443862)
		(end 367.439448 -275.706078)
		(width 0.1143)
		(layer "In11.Cu")
		(net "P5E_CPU0_P3_TX_DP<7>")
	)
	(arc
		(start 367.251742 -290.608512)
		(mid 366.971095 -291.095938)
		(end 367.251742 -291.583364)
		(width 0.1143)
		(layer "In11.Cu")
		(net "P5E_CPU0_P3_TX_DP<7>")
	)
	(arc
		(start 367.250726 -287.36671)
		(mid 367.044872 -287.573941)
		(end 366.969548 -287.856168)
		(width 0.1143)
		(layer "In11.Cu")
		(net "P5E_CPU0_P3_TX_DP<7>")
	)
	(arc
		(start 367.274094 -285.116524)
		(mid 367.451944 -285.426543)
		(end 367.273332 -285.73603)
		(width 0.1143)
		(layer "In11.Cu")
		(net "P5E_CPU0_P3_TX_DP<7>")
	)
	(arc
		(start 367.439448 -275.706078)
		(mid 367.393854 -275.884747)
		(end 367.268252 -276.019768)
		(width 0.1143)
		(layer "In11.Cu")
		(net "P5E_CPU0_P3_TX_DP<7>")
	)
	(arc
		(start 367.439448 -287.045908)
		(mid 367.390174 -287.229599)
		(end 367.255552 -287.363916)
		(width 0.1143)
		(layer "In11.Cu")
		(net "P5E_CPU0_P3_TX_DP<7>")
	)
	(arc
		(start 367.249456 -285.75)
		(mid 366.969528 -286.236156)
		(end 367.249456 -286.722312)
		(width 0.1143)
		(layer "In11.Cu")
		(net "P5E_CPU0_P3_TX_DP<7>")
	)
	(arc
		(start 367.283492 -291.601652)
		(mid 367.43942 -291.905944)
		(end 367.283492 -292.210236)
		(width 0.1143)
		(layer "In11.Cu")
		(net "P5E_CPU0_P3_TX_DP<7>")
	)
	(arc
		(start 367.251488 -292.228778)
		(mid 366.970841 -292.71614)
		(end 367.251488 -293.203376)
		(width 0.1143)
		(layer "In11.Cu")
		(net "P5E_CPU0_P3_TX_DP<7>")
	)
	(arc
		(start 367.25098 -280.889202)
		(mid 366.970414 -281.356065)
		(end 367.21542 -281.842464)
		(width 0.1143)
		(layer "In11.Cu")
		(net "P5E_CPU0_P3_TX_DP<7>")
	)
	(arc
		(start 366.785906 -277.815548)
		(mid 366.920378 -277.951386)
		(end 366.969548 -278.136096)
		(width 0.1143)
		(layer "In11.Cu")
		(net "P5E_CPU0_P3_TX_DP<7>")
	)
	(arc
		(start 367.692178 -295.616122)
		(mid 367.851332 -295.775199)
		(end 367.909602 -295.99255)
		(width 0.1143)
		(layer "In11.Cu")
		(net "P5E_CPU0_P3_TX_DP<7>")
	)
	(arc
		(start 380.73711 -370.76634)
		(mid 379.701263 -372.671691)
		(end 378.800868 -374.644666)
		(width 0.14224)
		(layer "In11.Cu")
		(net "P5E_CPU0_P3_TX_DP<7>")
	)
	(arc
		(start 366.969548 -287.856168)
		(mid 367.034784 -288.119759)
		(end 367.21542 -288.322512)
		(width 0.1143)
		(layer "In11.Cu")
		(net "P5E_CPU0_P3_TX_DP<7>")
	)
	(arc
		(start 367.283492 -293.221664)
		(mid 367.43942 -293.525956)
		(end 367.283492 -293.830248)
		(width 0.1143)
		(layer "In11.Cu")
		(net "P5E_CPU0_P3_TX_DP<7>")
	)
	(arc
		(start 367.24844 -276.03196)
		(mid 367.044231 -276.23672)
		(end 366.969548 -276.516084)
		(width 0.1143)
		(layer "In11.Cu")
		(net "P5E_CPU0_P3_TX_DP<7>")
	)
	(arc
		(start 367.283492 -289.98164)
		(mid 367.43942 -290.285932)
		(end 367.283492 -290.590224)
		(width 0.1143)
		(layer "In11.Cu")
		(net "P5E_CPU0_P3_TX_DP<7>")
	)
	(arc
		(start 367.25098 -282.506928)
		(mid 366.969911 -282.974879)
		(end 367.21542 -283.462476)
		(width 0.1143)
		(layer "In11.Cu")
		(net "P5E_CPU0_P3_TX_DP<7>")
	)
	(arc
		(start 378.364496 -375.69648)
		(mid 378.330112 -375.809784)
		(end 378.318522 -375.92762)
		(width 0.14224)
		(layer "In11.Cu")
		(net "P5E_CPU0_P3_TX_DP<7>")
	)
	(arc
		(start 367.28527 -288.363152)
		(mid 367.398677 -288.496041)
		(end 367.439448 -288.66592)
		(width 0.1143)
		(layer "In11.Cu")
		(net "P5E_CPU0_P3_TX_DP<7>")
	)
	(arc
		(start 367.234216 -293.858696)
		(mid 366.959447 -294.335962)
		(end 367.234216 -294.813228)
		(width 0.1143)
		(layer "In11.Cu")
		(net "P5E_CPU0_P3_TX_DP<7>")
	)
	(arc
		(start 385.611878 -359.428796)
		(mid 385.278003 -360.546718)
		(end 384.926332 -361.65917)
		(width 0.14224)
		(layer "In11.Cu")
		(net "P5E_CPU0_P3_TX_DP<7>")
	)
	(arc
		(start 367.283492 -281.881834)
		(mid 367.437828 -282.202644)
		(end 367.251996 -282.50642)
		(width 0.1143)
		(layer "In11.Cu")
		(net "P5E_CPU0_P3_TX_DP<7>")
	)
	(arc
		(start 382.278636 -367.791492)
		(mid 381.548742 -369.300093)
		(end 380.73711 -370.76634)
		(width 0.14224)
		(layer "In11.Cu")
		(net "P5E_CPU0_P3_TX_DP<7>")
	)
	(arc
		(start 367.283492 -278.64181)
		(mid 367.398168 -278.775144)
		(end 367.439448 -278.946102)
		(width 0.1143)
		(layer "In11.Cu")
		(net "P5E_CPU0_P3_TX_DP<7>")
	)
	(arc
		(start 367.90249 -274.965922)
		(mid 367.850073 -275.097853)
		(end 367.752376 -275.200872)
		(width 0.1143)
		(layer "In11.Cu")
		(net "P5E_CPU0_P3_TX_DP<7>")
	)
	(arc
		(start 367.439448 -288.66592)
		(mid 367.398193 -288.836891)
		(end 367.283492 -288.970212)
		(width 0.1143)
		(layer "In11.Cu")
		(net "P5E_CPU0_P3_TX_DP<7>")
	)
	(arc
		(start 367.248948 -288.990024)
		(mid 366.969113 -289.475926)
		(end 367.248948 -289.961828)
		(width 0.1143)
		(layer "In11.Cu")
		(net "P5E_CPU0_P3_TX_DP<7>")
	)
	(arc
		(start 388.054596 -348.390972)
		(mid 387.871667 -350.978541)
		(end 387.326632 -353.51466)
		(width 0.14224)
		(layer "In11.Cu")
		(net "P5E_CPU0_P3_TX_DP<7>")
	)
	(arc
		(start 367.439448 -278.946102)
		(mid 367.503963 -279.208321)
		(end 367.68278 -279.410668)
		(width 0.1143)
		(layer "In11.Cu")
		(net "P5E_CPU0_P3_TX_DP<7>")
	)
	(arc
		(start 367.244884 -284.130496)
		(mid 366.969766 -284.59824)
		(end 367.215166 -285.082234)
		(width 0.1143)
		(layer "In11.Cu")
		(net "P5E_CPU0_P3_TX_DP<7>")
	)
	(arc
		(start 367.25098 -284.12694)
		(mid 367.247927 -284.128709)
		(end 367.244884 -284.130496)
		(width 0.1143)
		(layer "In11.Cu")
		(net "P5E_CPU0_P3_TX_DP<7>")
	)
	(arc
		(start 367.283492 -294.841676)
		(mid 367.398168 -294.97501)
		(end 367.439448 -295.145968)
		(width 0.1143)
		(layer "In11.Cu")
		(net "P5E_CPU0_P3_TX_DP<7>")
	)
	(arc
		(start 367.439448 -280.566114)
		(mid 367.389625 -280.751844)
		(end 367.25352 -280.887678)
		(width 0.1143)
		(layer "In11.Cu")
		(net "P5E_CPU0_P3_TX_DP<7>")
	)
	(arc
		(start 367.268252 -276.019768)
		(mid 367.260437 -276.02469)
		(end 367.252504 -276.02942)
		(width 0.1143)
		(layer "In11.Cu")
		(net "P5E_CPU0_P3_TX_DP<7>")
	)
	(segment
		(start 374.894602 -378.39142)
		(end 374.598692 -378.68733)
		(width 0.12954)
		(layer "F.Cu")
		(net "P5E_CPU0_P3_TX_DP<6>")
	)
	(segment
		(start 374.894602 -377.68784)
		(end 374.894602 -378.39142)
		(width 0.12954)
		(layer "F.Cu")
		(net "P5E_CPU0_P3_TX_DP<6>")
	)
	(segment
		(start 374.624092 -377.41733)
		(end 374.894602 -377.68784)
		(width 0.12954)
		(layer "F.Cu")
		(net "P5E_CPU0_P3_TX_DP<6>")
	)
	(segment
		(start 364.247938 -276.250146)
		(end 364.71479 -276.516084)
		(width 0.12954)
		(layer "F.Cu")
		(net "P5E_CPU0_P3_TX_DP<6>")
	)
	(segment
		(start 366.776762 -280.081482)
		(end 366.771936 -280.08453)
		(width 0.1143)
		(layer "In11.Cu")
		(net "P5E_CPU0_P3_TX_DP<6>")
	)
	(segment
		(start 365.791496 -277.782782)
		(end 365.80191 -277.790402)
		(width 0.1143)
		(layer "In11.Cu")
		(net "P5E_CPU0_P3_TX_DP<6>")
	)
	(segment
		(start 366.311688 -292.228778)
		(end 366.27435 -292.250368)
		(width 0.1143)
		(layer "In11.Cu")
		(net "P5E_CPU0_P3_TX_DP<6>")
	)
	(segment
		(start 366.311688 -282.50896)
		(end 366.27435 -282.53055)
		(width 0.1143)
		(layer "In11.Cu")
		(net "P5E_CPU0_P3_TX_DP<6>")
	)
	(segment
		(start 366.27435 -294.801544)
		(end 366.311688 -294.823134)
		(width 0.1143)
		(layer "In11.Cu")
		(net "P5E_CPU0_P3_TX_DP<6>")
	)
	(segment
		(start 366.311688 -288.988754)
		(end 366.27435 -289.010344)
		(width 0.1143)
		(layer "In11.Cu")
		(net "P5E_CPU0_P3_TX_DP<6>")
	)
	(segment
		(start 366.311688 -293.203122)
		(end 366.343438 -293.221918)
		(width 0.1143)
		(layer "In11.Cu")
		(net "P5E_CPU0_P3_TX_DP<6>")
	)
	(segment
		(start 366.813592 -280.060146)
		(end 366.788954 -280.074624)
		(width 0.1143)
		(layer "In11.Cu")
		(net "P5E_CPU0_P3_TX_DP<6>")
	)
	(segment
		(start 366.311688 -280.888948)
		(end 366.27435 -280.910538)
		(width 0.1143)
		(layer "In11.Cu")
		(net "P5E_CPU0_P3_TX_DP<6>")
	)
	(segment
		(start 366.27435 -285.081726)
		(end 366.311688 -285.103316)
		(width 0.1143)
		(layer "In11.Cu")
		(net "P5E_CPU0_P3_TX_DP<6>")
	)
	(segment
		(start 377.956318 -313.88812)
		(end 382.055878 -320.022728)
		(width 0.14224)
		(layer "In11.Cu")
		(net "P5E_CPU0_P3_TX_DP<6>")
	)
	(segment
		(start 368.016028 -300.902624)
		(end 371.155468 -305.601116)
		(width 0.14224)
		(layer "In11.Cu")
		(net "P5E_CPU0_P3_TX_DP<6>")
	)
	(segment
		(start 366.27435 -293.181532)
		(end 366.311688 -293.203122)
		(width 0.1143)
		(layer "In11.Cu")
		(net "P5E_CPU0_P3_TX_DP<6>")
	)
	(segment
		(start 366.781842 -295.633394)
		(end 366.813592 -295.651682)
		(width 0.1143)
		(layer "In11.Cu")
		(net "P5E_CPU0_P3_TX_DP<6>")
	)
	(segment
		(start 371.155468 -305.601116)
		(end 377.956318 -313.88812)
		(width 0.14224)
		(layer "In11.Cu")
		(net "P5E_CPU0_P3_TX_DP<6>")
	)
	(segment
		(start 366.311688 -285.748984)
		(end 366.27435 -285.770574)
		(width 0.1143)
		(layer "In11.Cu")
		(net "P5E_CPU0_P3_TX_DP<6>")
	)
	(segment
		(start 365.346996 -276.989032)
		(end 365.40186 -277.020782)
		(width 0.1143)
		(layer "In11.Cu")
		(net "P5E_CPU0_P3_TX_DP<6>")
	)
	(segment
		(start 366.343692 -284.110176)
		(end 366.311688 -284.128972)
		(width 0.1143)
		(layer "In11.Cu")
		(net "P5E_CPU0_P3_TX_DP<6>")
	)
	(segment
		(start 366.311688 -281.863292)
		(end 366.343438 -281.882088)
		(width 0.1143)
		(layer "In11.Cu")
		(net "P5E_CPU0_P3_TX_DP<6>")
	)
	(segment
		(start 366.969548 -296.372788)
		(end 366.923828 -296.418508)
		(width 0.1143)
		(layer "In11.Cu")
		(net "P5E_CPU0_P3_TX_DP<6>")
	)
	(segment
		(start 387.119114 -340.952582)
		(end 387.119114 -347.962474)
		(width 0.14224)
		(layer "In11.Cu")
		(net "P5E_CPU0_P3_TX_DP<6>")
	)
	(segment
		(start 366.781842 -280.07818)
		(end 366.776762 -280.081482)
		(width 0.1143)
		(layer "In11.Cu")
		(net "P5E_CPU0_P3_TX_DP<6>")
	)
	(segment
		(start 366.272064 -288.32048)
		(end 366.311942 -288.34334)
		(width 0.1143)
		(layer "In11.Cu")
		(net "P5E_CPU0_P3_TX_DP<6>")
	)
	(segment
		(start 366.775238 -279.429718)
		(end 366.781842 -279.434036)
		(width 0.1143)
		(layer "In11.Cu")
		(net "P5E_CPU0_P3_TX_DP<6>")
	)
	(segment
		(start 366.311688 -283.483304)
		(end 366.343438 -283.5021)
		(width 0.1143)
		(layer "In11.Cu")
		(net "P5E_CPU0_P3_TX_DP<6>")
	)
	(segment
		(start 366.311688 -289.963098)
		(end 366.343438 -289.981894)
		(width 0.1143)
		(layer "In11.Cu")
		(net "P5E_CPU0_P3_TX_DP<6>")
	)
	(segment
		(start 366.311942 -288.34334)
		(end 366.343438 -288.361882)
		(width 0.1143)
		(layer "In11.Cu")
		(net "P5E_CPU0_P3_TX_DP<6>")
	)
	(segment
		(start 366.343692 -292.209982)
		(end 366.311688 -292.228778)
		(width 0.1143)
		(layer "In11.Cu")
		(net "P5E_CPU0_P3_TX_DP<6>")
	)
	(segment
		(start 365.333534 -276.981158)
		(end 365.346996 -276.989032)
		(width 0.1143)
		(layer "In11.Cu")
		(net "P5E_CPU0_P3_TX_DP<6>")
	)
	(segment
		(start 366.343692 -288.969958)
		(end 366.311688 -288.988754)
		(width 0.1143)
		(layer "In11.Cu")
		(net "P5E_CPU0_P3_TX_DP<6>")
	)
	(segment
		(start 377.324874 -372.790974)
		(end 375.859294 -374.256554)
		(width 0.14224)
		(layer "In11.Cu")
		(net "P5E_CPU0_P3_TX_DP<6>")
	)
	(segment
		(start 366.311688 -291.58311)
		(end 366.343438 -291.601906)
		(width 0.1143)
		(layer "In11.Cu")
		(net "P5E_CPU0_P3_TX_DP<6>")
	)
	(segment
		(start 380.336552 -368.971576)
		(end 377.386342 -372.721378)
		(width 0.14224)
		(layer "In11.Cu")
		(net "P5E_CPU0_P3_TX_DP<6>")
	)
	(segment
		(start 366.923828 -296.446956)
		(end 366.923828 -297.301666)
		(width 0.14224)
		(layer "In11.Cu")
		(net "P5E_CPU0_P3_TX_DP<6>")
	)
	(segment
		(start 366.311688 -285.103316)
		(end 366.343438 -285.122112)
		(width 0.1143)
		(layer "In11.Cu")
		(net "P5E_CPU0_P3_TX_DP<6>")
	)
	(segment
		(start 366.343692 -285.730188)
		(end 366.311688 -285.748984)
		(width 0.1143)
		(layer "In11.Cu")
		(net "P5E_CPU0_P3_TX_DP<6>")
	)
	(segment
		(start 366.27435 -281.841702)
		(end 366.311688 -281.863292)
		(width 0.1143)
		(layer "In11.Cu")
		(net "P5E_CPU0_P3_TX_DP<6>")
	)
	(segment
		(start 366.743488 -279.41143)
		(end 366.775238 -279.429718)
		(width 0.1143)
		(layer "In11.Cu")
		(net "P5E_CPU0_P3_TX_DP<6>")
	)
	(segment
		(start 387.11886 -340.952836)
		(end 387.119114 -340.952582)
		(width 0.14224)
		(layer "In11.Cu")
		(net "P5E_CPU0_P3_TX_DP<6>")
	)
	(segment
		(start 374.914922 -376.536712)
		(end 374.914922 -377.1265)
		(width 0.14224)
		(layer "In11.Cu")
		(net "P5E_CPU0_P3_TX_DP<6>")
	)
	(segment
		(start 365.80191 -277.790402)
		(end 365.87303 -277.831804)
		(width 0.1143)
		(layer "In11.Cu")
		(net "P5E_CPU0_P3_TX_DP<6>")
	)
	(segment
		(start 366.923828 -297.301666)
		(end 368.016028 -300.902624)
		(width 0.14224)
		(layer "In11.Cu")
		(net "P5E_CPU0_P3_TX_DP<6>")
	)
	(segment
		(start 366.272064 -286.700468)
		(end 366.311942 -286.723328)
		(width 0.1143)
		(layer "In11.Cu")
		(net "P5E_CPU0_P3_TX_DP<6>")
	)
	(segment
		(start 366.311942 -286.723328)
		(end 366.343438 -286.74187)
		(width 0.1143)
		(layer "In11.Cu")
		(net "P5E_CPU0_P3_TX_DP<6>")
	)
	(segment
		(start 366.343692 -282.490164)
		(end 366.311688 -282.50896)
		(width 0.1143)
		(layer "In11.Cu")
		(net "P5E_CPU0_P3_TX_DP<6>")
	)
	(segment
		(start 366.311688 -290.608766)
		(end 366.27435 -290.630356)
		(width 0.1143)
		(layer "In11.Cu")
		(net "P5E_CPU0_P3_TX_DP<6>")
	)
	(segment
		(start 366.788954 -280.074624)
		(end 366.781842 -280.07818)
		(width 0.1143)
		(layer "In11.Cu")
		(net "P5E_CPU0_P3_TX_DP<6>")
	)
	(segment
		(start 380.406148 -368.866166)
		(end 380.406402 -368.866166)
		(width 0.14224)
		(layer "In11.Cu")
		(net "P5E_CPU0_P3_TX_DP<6>")
	)
	(segment
		(start 366.784382 -279.43556)
		(end 366.791494 -279.439116)
		(width 0.1143)
		(layer "In11.Cu")
		(net "P5E_CPU0_P3_TX_DP<6>")
	)
	(segment
		(start 366.34166 -287.35147)
		(end 366.27435 -287.390586)
		(width 0.1143)
		(layer "In11.Cu")
		(net "P5E_CPU0_P3_TX_DP<6>")
	)
	(segment
		(start 366.77219 -280.084276)
		(end 366.771174 -280.085038)
		(width 0.1143)
		(layer "In11.Cu")
		(net "P5E_CPU0_P3_TX_DP<6>")
	)
	(segment
		(start 366.27435 -283.461714)
		(end 366.311688 -283.483304)
		(width 0.1143)
		(layer "In11.Cu")
		(net "P5E_CPU0_P3_TX_DP<6>")
	)
	(segment
		(start 366.745774 -295.612566)
		(end 366.781842 -295.633394)
		(width 0.1143)
		(layer "In11.Cu")
		(net "P5E_CPU0_P3_TX_DP<6>")
	)
	(segment
		(start 366.311688 -294.823134)
		(end 366.343438 -294.84193)
		(width 0.1143)
		(layer "In11.Cu")
		(net "P5E_CPU0_P3_TX_DP<6>")
	)
	(segment
		(start 374.914922 -377.1265)
		(end 374.624092 -377.41733)
		(width 0.14224)
		(layer "In11.Cu")
		(net "P5E_CPU0_P3_TX_DP<6>")
	)
	(segment
		(start 386.387086 -352.89617)
		(end 384.490722 -359.147618)
		(width 0.14224)
		(layer "In11.Cu")
		(net "P5E_CPU0_P3_TX_DP<6>")
	)
	(segment
		(start 365.87303 -277.831804)
		(end 365.873792 -277.832312)
		(width 0.1143)
		(layer "In11.Cu")
		(net "P5E_CPU0_P3_TX_DP<6>")
	)
	(segment
		(start 366.311688 -278.623268)
		(end 366.343438 -278.642064)
		(width 0.1143)
		(layer "In11.Cu")
		(net "P5E_CPU0_P3_TX_DP<6>")
	)
	(segment
		(start 366.781842 -279.434036)
		(end 366.782858 -279.434544)
		(width 0.1143)
		(layer "In11.Cu")
		(net "P5E_CPU0_P3_TX_DP<6>")
	)
	(segment
		(start 366.743488 -295.611042)
		(end 366.745774 -295.612566)
		(width 0.1143)
		(layer "In11.Cu")
		(net "P5E_CPU0_P3_TX_DP<6>")
	)
	(segment
		(start 366.311688 -293.84879)
		(end 366.27435 -293.87038)
		(width 0.1143)
		(layer "In11.Cu")
		(net "P5E_CPU0_P3_TX_DP<6>")
	)
	(segment
		(start 366.923828 -296.418508)
		(end 366.923828 -296.446956)
		(width 0.1143)
		(layer "In11.Cu")
		(net "P5E_CPU0_P3_TX_DP<6>")
	)
	(segment
		(start 365.559594 -277.32609)
		(end 365.559594 -277.329138)
		(width 0.1143)
		(layer "In11.Cu")
		(net "P5E_CPU0_P3_TX_DP<6>")
	)
	(segment
		(start 366.311688 -284.128972)
		(end 366.27435 -284.150562)
		(width 0.1143)
		(layer "In11.Cu")
		(net "P5E_CPU0_P3_TX_DP<6>")
	)
	(segment
		(start 366.969548 -295.955974)
		(end 366.969548 -296.372788)
		(width 0.1143)
		(layer "In11.Cu")
		(net "P5E_CPU0_P3_TX_DP<6>")
	)
	(segment
		(start 366.791494 -279.439116)
		(end 366.792256 -279.439624)
		(width 0.1143)
		(layer "In11.Cu")
		(net "P5E_CPU0_P3_TX_DP<6>")
	)
	(segment
		(start 366.782858 -279.434544)
		(end 366.784382 -279.43556)
		(width 0.1143)
		(layer "In11.Cu")
		(net "P5E_CPU0_P3_TX_DP<6>")
	)
	(segment
		(start 364.71479 -276.516084)
		(end 365.012732 -276.516084)
		(width 0.1143)
		(layer "In11.Cu")
		(net "P5E_CPU0_P3_TX_DP<6>")
	)
	(segment
		(start 366.27435 -289.941508)
		(end 366.311688 -289.963098)
		(width 0.1143)
		(layer "In11.Cu")
		(net "P5E_CPU0_P3_TX_DP<6>")
	)
	(segment
		(start 383.807208 -324.251066)
		(end 387.112002 -340.881716)
		(width 0.14224)
		(layer "In11.Cu")
		(net "P5E_CPU0_P3_TX_DP<6>")
	)
	(segment
		(start 366.792256 -279.439624)
		(end 366.813592 -279.45207)
		(width 0.1143)
		(layer "In11.Cu")
		(net "P5E_CPU0_P3_TX_DP<6>")
	)
	(segment
		(start 366.343692 -293.829994)
		(end 366.311688 -293.84879)
		(width 0.1143)
		(layer "In11.Cu")
		(net "P5E_CPU0_P3_TX_DP<6>")
	)
	(segment
		(start 365.095536 -276.598888)
		(end 365.09579 -276.598888)
		(width 0.1143)
		(layer "In11.Cu")
		(net "P5E_CPU0_P3_TX_DP<6>")
	)
	(segment
		(start 365.012732 -276.516084)
		(end 365.095536 -276.598888)
		(width 0.1143)
		(layer "In11.Cu")
		(net "P5E_CPU0_P3_TX_DP<6>")
	)
	(segment
		(start 366.343692 -290.58997)
		(end 366.311688 -290.608766)
		(width 0.1143)
		(layer "In11.Cu")
		(net "P5E_CPU0_P3_TX_DP<6>")
	)
	(segment
		(start 382.055878 -320.022728)
		(end 383.807208 -324.251066)
		(width 0.14224)
		(layer "In11.Cu")
		(net "P5E_CPU0_P3_TX_DP<6>")
	)
	(segment
		(start 366.771936 -280.08453)
		(end 366.77219 -280.084276)
		(width 0.1143)
		(layer "In11.Cu")
		(net "P5E_CPU0_P3_TX_DP<6>")
	)
	(segment
		(start 366.27435 -291.56152)
		(end 366.311688 -291.58311)
		(width 0.1143)
		(layer "In11.Cu")
		(net "P5E_CPU0_P3_TX_DP<6>")
	)
	(segment
		(start 366.343692 -280.870152)
		(end 366.311688 -280.888948)
		(width 0.1143)
		(layer "In11.Cu")
		(net "P5E_CPU0_P3_TX_DP<6>")
	)
	(segment
		(start 366.27435 -278.601678)
		(end 366.311688 -278.623268)
		(width 0.1143)
		(layer "In11.Cu")
		(net "P5E_CPU0_P3_TX_DP<6>")
	)
	(segment
		(start 366.771174 -280.085038)
		(end 366.743742 -280.100786)
		(width 0.1143)
		(layer "In11.Cu")
		(net "P5E_CPU0_P3_TX_DP<6>")
	)
	(arc
		(start 366.27435 -290.630356)
		(mid 366.029529 -291.095938)
		(end 366.27435 -291.56152)
		(width 0.1143)
		(layer "In11.Cu")
		(net "P5E_CPU0_P3_TX_DP<6>")
	)
	(arc
		(start 387.119114 -347.962474)
		(mid 386.935079 -350.456324)
		(end 386.387086 -352.89617)
		(width 0.14224)
		(layer "In11.Cu")
		(net "P5E_CPU0_P3_TX_DP<6>")
	)
	(arc
		(start 365.873792 -277.832312)
		(mid 365.988411 -277.96539)
		(end 366.029748 -278.136096)
		(width 0.1143)
		(layer "In11.Cu")
		(net "P5E_CPU0_P3_TX_DP<6>")
	)
	(arc
		(start 384.490722 -359.147618)
		(mid 382.699731 -364.112508)
		(end 380.406148 -368.866166)
		(width 0.14224)
		(layer "In11.Cu")
		(net "P5E_CPU0_P3_TX_DP<6>")
	)
	(arc
		(start 366.499648 -280.566114)
		(mid 366.458389 -280.736971)
		(end 366.343692 -280.870152)
		(width 0.1143)
		(layer "In11.Cu")
		(net "P5E_CPU0_P3_TX_DP<6>")
	)
	(arc
		(start 366.343438 -286.74187)
		(mid 366.458281 -286.875018)
		(end 366.499648 -287.045908)
		(width 0.1143)
		(layer "In11.Cu")
		(net "P5E_CPU0_P3_TX_DP<6>")
	)
	(arc
		(start 366.27435 -293.87038)
		(mid 366.029529 -294.335962)
		(end 366.27435 -294.801544)
		(width 0.1143)
		(layer "In11.Cu")
		(net "P5E_CPU0_P3_TX_DP<6>")
	)
	(arc
		(start 366.499648 -287.045908)
		(mid 366.457808 -287.217894)
		(end 366.34166 -287.35147)
		(width 0.1143)
		(layer "In11.Cu")
		(net "P5E_CPU0_P3_TX_DP<6>")
	)
	(arc
		(start 366.813592 -295.651682)
		(mid 366.928268 -295.785016)
		(end 366.969548 -295.955974)
		(width 0.1143)
		(layer "In11.Cu")
		(net "P5E_CPU0_P3_TX_DP<6>")
	)
	(arc
		(start 366.499648 -288.66592)
		(mid 366.458389 -288.836777)
		(end 366.343692 -288.969958)
		(width 0.1143)
		(layer "In11.Cu")
		(net "P5E_CPU0_P3_TX_DP<6>")
	)
	(arc
		(start 366.743742 -280.100786)
		(mid 366.564397 -280.303389)
		(end 366.499648 -280.566114)
		(width 0.1143)
		(layer "In11.Cu")
		(net "P5E_CPU0_P3_TX_DP<6>")
	)
	(arc
		(start 366.343438 -294.84193)
		(mid 366.458281 -294.975078)
		(end 366.499648 -295.145968)
		(width 0.1143)
		(layer "In11.Cu")
		(net "P5E_CPU0_P3_TX_DP<6>")
	)
	(arc
		(start 380.406402 -368.866166)
		(mid 380.373649 -368.92031)
		(end 380.336552 -368.971576)
		(width 0.14224)
		(layer "In11.Cu")
		(net "P5E_CPU0_P3_TX_DP<6>")
	)
	(arc
		(start 366.343438 -291.601906)
		(mid 366.499371 -291.905841)
		(end 366.343692 -292.209982)
		(width 0.1143)
		(layer "In11.Cu")
		(net "P5E_CPU0_P3_TX_DP<6>")
	)
	(arc
		(start 366.813592 -279.45207)
		(mid 366.969525 -279.756108)
		(end 366.813592 -280.060146)
		(width 0.1143)
		(layer "In11.Cu")
		(net "P5E_CPU0_P3_TX_DP<6>")
	)
	(arc
		(start 366.27435 -284.150562)
		(mid 366.029529 -284.616144)
		(end 366.27435 -285.081726)
		(width 0.1143)
		(layer "In11.Cu")
		(net "P5E_CPU0_P3_TX_DP<6>")
	)
	(arc
		(start 366.499648 -278.946102)
		(mid 366.564248 -279.208801)
		(end 366.743488 -279.41143)
		(width 0.1143)
		(layer "In11.Cu")
		(net "P5E_CPU0_P3_TX_DP<6>")
	)
	(arc
		(start 365.09579 -276.598888)
		(mid 365.175007 -276.814671)
		(end 365.333534 -276.981158)
		(width 0.1143)
		(layer "In11.Cu")
		(net "P5E_CPU0_P3_TX_DP<6>")
	)
	(arc
		(start 366.343438 -285.122112)
		(mid 366.499371 -285.426047)
		(end 366.343692 -285.730188)
		(width 0.1143)
		(layer "In11.Cu")
		(net "P5E_CPU0_P3_TX_DP<6>")
	)
	(arc
		(start 366.27435 -285.770574)
		(mid 366.094558 -285.973162)
		(end 366.029748 -286.236156)
		(width 0.1143)
		(layer "In11.Cu")
		(net "P5E_CPU0_P3_TX_DP<6>")
	)
	(arc
		(start 366.27435 -280.910538)
		(mid 366.029529 -281.37612)
		(end 366.27435 -281.841702)
		(width 0.1143)
		(layer "In11.Cu")
		(net "P5E_CPU0_P3_TX_DP<6>")
	)
	(arc
		(start 366.27435 -292.250368)
		(mid 366.029529 -292.71595)
		(end 366.27435 -293.181532)
		(width 0.1143)
		(layer "In11.Cu")
		(net "P5E_CPU0_P3_TX_DP<6>")
	)
	(arc
		(start 365.40186 -277.020782)
		(mid 365.517815 -277.154272)
		(end 365.559594 -277.32609)
		(width 0.1143)
		(layer "In11.Cu")
		(net "P5E_CPU0_P3_TX_DP<6>")
	)
	(arc
		(start 366.343438 -278.642064)
		(mid 366.458281 -278.775212)
		(end 366.499648 -278.946102)
		(width 0.1143)
		(layer "In11.Cu")
		(net "P5E_CPU0_P3_TX_DP<6>")
	)
	(arc
		(start 366.343438 -293.221918)
		(mid 366.499371 -293.525853)
		(end 366.343692 -293.829994)
		(width 0.1143)
		(layer "In11.Cu")
		(net "P5E_CPU0_P3_TX_DP<6>")
	)
	(arc
		(start 366.343438 -288.361882)
		(mid 366.458281 -288.49503)
		(end 366.499648 -288.66592)
		(width 0.1143)
		(layer "In11.Cu")
		(net "P5E_CPU0_P3_TX_DP<6>")
	)
	(arc
		(start 377.386342 -372.721378)
		(mid 377.356635 -372.757083)
		(end 377.324874 -372.790974)
		(width 0.14224)
		(layer "In11.Cu")
		(net "P5E_CPU0_P3_TX_DP<6>")
	)
	(arc
		(start 365.559594 -277.329138)
		(mid 365.620884 -277.583897)
		(end 365.791496 -277.782782)
		(width 0.1143)
		(layer "In11.Cu")
		(net "P5E_CPU0_P3_TX_DP<6>")
	)
	(arc
		(start 366.343438 -281.882088)
		(mid 366.499371 -282.186023)
		(end 366.343692 -282.490164)
		(width 0.1143)
		(layer "In11.Cu")
		(net "P5E_CPU0_P3_TX_DP<6>")
	)
	(arc
		(start 366.029748 -287.856168)
		(mid 366.093924 -288.118055)
		(end 366.272064 -288.32048)
		(width 0.1143)
		(layer "In11.Cu")
		(net "P5E_CPU0_P3_TX_DP<6>")
	)
	(arc
		(start 366.343438 -289.981894)
		(mid 366.499371 -290.285829)
		(end 366.343692 -290.58997)
		(width 0.1143)
		(layer "In11.Cu")
		(net "P5E_CPU0_P3_TX_DP<6>")
	)
	(arc
		(start 375.859294 -374.256554)
		(mid 375.160336 -375.302714)
		(end 374.914922 -376.536712)
		(width 0.14224)
		(layer "In11.Cu")
		(net "P5E_CPU0_P3_TX_DP<6>")
	)
	(arc
		(start 366.27435 -289.010344)
		(mid 366.029529 -289.475926)
		(end 366.27435 -289.941508)
		(width 0.1143)
		(layer "In11.Cu")
		(net "P5E_CPU0_P3_TX_DP<6>")
	)
	(arc
		(start 366.27435 -287.390586)
		(mid 366.094558 -287.593174)
		(end 366.029748 -287.856168)
		(width 0.1143)
		(layer "In11.Cu")
		(net "P5E_CPU0_P3_TX_DP<6>")
	)
	(arc
		(start 366.343438 -283.5021)
		(mid 366.499371 -283.806035)
		(end 366.343692 -284.110176)
		(width 0.1143)
		(layer "In11.Cu")
		(net "P5E_CPU0_P3_TX_DP<6>")
	)
	(arc
		(start 366.029748 -278.136096)
		(mid 366.094566 -278.399085)
		(end 366.27435 -278.601678)
		(width 0.1143)
		(layer "In11.Cu")
		(net "P5E_CPU0_P3_TX_DP<6>")
	)
	(arc
		(start 366.27435 -282.53055)
		(mid 366.029529 -282.996132)
		(end 366.27435 -283.461714)
		(width 0.1143)
		(layer "In11.Cu")
		(net "P5E_CPU0_P3_TX_DP<6>")
	)
	(arc
		(start 366.499648 -295.145968)
		(mid 366.564307 -295.408525)
		(end 366.743488 -295.611042)
		(width 0.1143)
		(layer "In11.Cu")
		(net "P5E_CPU0_P3_TX_DP<6>")
	)
	(arc
		(start 387.112002 -340.881716)
		(mid 387.117194 -340.917106)
		(end 387.11886 -340.952836)
		(width 0.14224)
		(layer "In11.Cu")
		(net "P5E_CPU0_P3_TX_DP<6>")
	)
	(arc
		(start 366.029748 -286.236156)
		(mid 366.093924 -286.498043)
		(end 366.272064 -286.700468)
		(width 0.1143)
		(layer "In11.Cu")
		(net "P5E_CPU0_P3_TX_DP<6>")
	)
	(segment
		(start 373.192802 -380.15164)
		(end 373.192802 -380.85522)
		(width 0.12954)
		(layer "F.Cu")
		(net "P5E_CPU0_P3_TX_DP<5>")
	)
	(segment
		(start 373.192802 -380.85522)
		(end 372.896892 -381.15113)
		(width 0.12954)
		(layer "F.Cu")
		(net "P5E_CPU0_P3_TX_DP<5>")
	)
	(segment
		(start 364.247938 -277.870158)
		(end 364.71479 -278.136096)
		(width 0.12954)
		(layer "F.Cu")
		(net "P5E_CPU0_P3_TX_DP<5>")
	)
	(segment
		(start 372.922292 -379.88113)
		(end 373.192802 -380.15164)
		(width 0.12954)
		(layer "F.Cu")
		(net "P5E_CPU0_P3_TX_DP<5>")
	)
	(segment
		(start 365.371888 -288.9885)
		(end 365.370872 -288.989008)
		(width 0.1143)
		(layer "In11.Cu")
		(net "P5E_CPU0_P3_TX_DP<5>")
	)
	(segment
		(start 365.371888 -290.608512)
		(end 365.370872 -290.60902)
		(width 0.1143)
		(layer "In11.Cu")
		(net "P5E_CPU0_P3_TX_DP<5>")
	)
	(segment
		(start 365.375444 -282.506928)
		(end 365.374936 -282.506928)
		(width 0.1143)
		(layer "In11.Cu")
		(net "P5E_CPU0_P3_TX_DP<5>")
	)
	(segment
		(start 365.848392 -295.637204)
		(end 365.849662 -295.637966)
		(width 0.1143)
		(layer "In11.Cu")
		(net "P5E_CPU0_P3_TX_DP<5>")
	)
	(segment
		(start 365.370872 -282.509214)
		(end 365.332772 -282.531566)
		(width 0.1143)
		(layer "In11.Cu")
		(net "P5E_CPU0_P3_TX_DP<5>")
	)
	(segment
		(start 365.842042 -279.433528)
		(end 365.873538 -279.45207)
		(width 0.1143)
		(layer "In11.Cu")
		(net "P5E_CPU0_P3_TX_DP<5>")
	)
	(segment
		(start 365.367316 -292.231318)
		(end 365.3663 -292.231826)
		(width 0.1143)
		(layer "In11.Cu")
		(net "P5E_CPU0_P3_TX_DP<5>")
	)
	(segment
		(start 365.332772 -288.320734)
		(end 365.338868 -288.32429)
		(width 0.1143)
		(layer "In11.Cu")
		(net "P5E_CPU0_P3_TX_DP<5>")
	)
	(segment
		(start 365.371888 -283.483558)
		(end 365.37265 -283.484066)
		(width 0.1143)
		(layer "In11.Cu")
		(net "P5E_CPU0_P3_TX_DP<5>")
	)
	(segment
		(start 365.332772 -281.840686)
		(end 365.370872 -281.863038)
		(width 0.1143)
		(layer "In11.Cu")
		(net "P5E_CPU0_P3_TX_DP<5>")
	)
	(segment
		(start 365.370872 -285.749238)
		(end 365.332772 -285.77159)
		(width 0.1143)
		(layer "In11.Cu")
		(net "P5E_CPU0_P3_TX_DP<5>")
	)
	(segment
		(start 365.984028 -297.421554)
		(end 367.166652 -301.320454)
		(width 0.14224)
		(layer "In11.Cu")
		(net "P5E_CPU0_P3_TX_DP<5>")
	)
	(segment
		(start 365.375444 -284.12694)
		(end 365.374936 -284.12694)
		(width 0.1143)
		(layer "In11.Cu")
		(net "P5E_CPU0_P3_TX_DP<5>")
	)
	(segment
		(start 365.371888 -292.228524)
		(end 365.370872 -292.229032)
		(width 0.1143)
		(layer "In11.Cu")
		(net "P5E_CPU0_P3_TX_DP<5>")
	)
	(segment
		(start 365.012732 -278.136096)
		(end 365.095536 -278.2189)
		(width 0.1143)
		(layer "In11.Cu")
		(net "P5E_CPU0_P3_TX_DP<5>")
	)
	(segment
		(start 365.370872 -292.229032)
		(end 365.36884 -292.230302)
		(width 0.1143)
		(layer "In11.Cu")
		(net "P5E_CPU0_P3_TX_DP<5>")
	)
	(segment
		(start 365.37265 -289.96386)
		(end 365.374682 -289.96513)
		(width 0.1143)
		(layer "In11.Cu")
		(net "P5E_CPU0_P3_TX_DP<5>")
	)
	(segment
		(start 386.081524 -340.685628)
		(end 386.081524 -348.605856)
		(width 0.14224)
		(layer "In11.Cu")
		(net "P5E_CPU0_P3_TX_DP<5>")
	)
	(segment
		(start 373.213122 -377.154694)
		(end 373.213122 -379.5903)
		(width 0.14224)
		(layer "In11.Cu")
		(net "P5E_CPU0_P3_TX_DP<5>")
	)
	(segment
		(start 365.37265 -293.203884)
		(end 365.374682 -293.205154)
		(width 0.1143)
		(layer "In11.Cu")
		(net "P5E_CPU0_P3_TX_DP<5>")
	)
	(segment
		(start 365.36884 -292.230302)
		(end 365.367316 -292.231318)
		(width 0.1143)
		(layer "In11.Cu")
		(net "P5E_CPU0_P3_TX_DP<5>")
	)
	(segment
		(start 365.407448 -287.347406)
		(end 365.403638 -287.3502)
		(width 0.1143)
		(layer "In11.Cu")
		(net "P5E_CPU0_P3_TX_DP<5>")
	)
	(segment
		(start 365.332772 -289.940492)
		(end 365.370872 -289.962844)
		(width 0.1143)
		(layer "In11.Cu")
		(net "P5E_CPU0_P3_TX_DP<5>")
	)
	(segment
		(start 365.403638 -287.3502)
		(end 365.335312 -287.389824)
		(width 0.1143)
		(layer "In11.Cu")
		(net "P5E_CPU0_P3_TX_DP<5>")
	)
	(segment
		(start 365.371888 -285.10357)
		(end 365.37265 -285.104078)
		(width 0.1143)
		(layer "In11.Cu")
		(net "P5E_CPU0_P3_TX_DP<5>")
	)
	(segment
		(start 379.344428 -367.826798)
		(end 379.00864 -368.359436)
		(width 0.14224)
		(layer "In11.Cu")
		(net "P5E_CPU0_P3_TX_DP<5>")
	)
	(segment
		(start 366.029748 -295.955974)
		(end 366.029748 -296.372788)
		(width 0.1143)
		(layer "In11.Cu")
		(net "P5E_CPU0_P3_TX_DP<5>")
	)
	(segment
		(start 365.371888 -289.963352)
		(end 365.37265 -289.96386)
		(width 0.1143)
		(layer "In11.Cu")
		(net "P5E_CPU0_P3_TX_DP<5>")
	)
	(segment
		(start 365.370872 -288.989008)
		(end 365.332772 -289.01136)
		(width 0.1143)
		(layer "In11.Cu")
		(net "P5E_CPU0_P3_TX_DP<5>")
	)
	(segment
		(start 365.33963 -278.604726)
		(end 365.340392 -278.605234)
		(width 0.1143)
		(layer "In11.Cu")
		(net "P5E_CPU0_P3_TX_DP<5>")
	)
	(segment
		(start 365.374682 -283.485336)
		(end 365.37519 -283.485336)
		(width 0.1143)
		(layer "In11.Cu")
		(net "P5E_CPU0_P3_TX_DP<5>")
	)
	(segment
		(start 365.370872 -285.103062)
		(end 365.371888 -285.10357)
		(width 0.1143)
		(layer "In11.Cu")
		(net "P5E_CPU0_P3_TX_DP<5>")
	)
	(segment
		(start 365.371888 -291.583364)
		(end 365.37265 -291.583872)
		(width 0.1143)
		(layer "In11.Cu")
		(net "P5E_CPU0_P3_TX_DP<5>")
	)
	(segment
		(start 365.37265 -292.228016)
		(end 365.371888 -292.228524)
		(width 0.1143)
		(layer "In11.Cu")
		(net "P5E_CPU0_P3_TX_DP<5>")
	)
	(segment
		(start 365.37265 -293.848282)
		(end 365.371888 -293.848536)
		(width 0.1143)
		(layer "In11.Cu")
		(net "P5E_CPU0_P3_TX_DP<5>")
	)
	(segment
		(start 365.370872 -284.129226)
		(end 365.332772 -284.151578)
		(width 0.1143)
		(layer "In11.Cu")
		(net "P5E_CPU0_P3_TX_DP<5>")
	)
	(segment
		(start 382.86817 -324.49516)
		(end 386.074412 -340.614508)
		(width 0.14224)
		(layer "In11.Cu")
		(net "P5E_CPU0_P3_TX_DP<5>")
	)
	(segment
		(start 365.373666 -278.624284)
		(end 365.387382 -278.632158)
		(width 0.1143)
		(layer "In11.Cu")
		(net "P5E_CPU0_P3_TX_DP<5>")
	)
	(segment
		(start 377.239276 -314.497212)
		(end 381.154178 -320.356484)
		(width 0.14224)
		(layer "In11.Cu")
		(net "P5E_CPU0_P3_TX_DP<5>")
	)
	(segment
		(start 365.332772 -286.700722)
		(end 365.405416 -286.74314)
		(width 0.1143)
		(layer "In11.Cu")
		(net "P5E_CPU0_P3_TX_DP<5>")
	)
	(segment
		(start 365.3663 -292.231826)
		(end 365.332772 -292.251384)
		(width 0.1143)
		(layer "In11.Cu")
		(net "P5E_CPU0_P3_TX_DP<5>")
	)
	(segment
		(start 365.370872 -281.863038)
		(end 365.371888 -281.863546)
		(width 0.1143)
		(layer "In11.Cu")
		(net "P5E_CPU0_P3_TX_DP<5>")
	)
	(segment
		(start 365.37265 -283.484066)
		(end 365.374682 -283.485336)
		(width 0.1143)
		(layer "In11.Cu")
		(net "P5E_CPU0_P3_TX_DP<5>")
	)
	(segment
		(start 365.37265 -290.608258)
		(end 365.371888 -290.608512)
		(width 0.1143)
		(layer "In11.Cu")
		(net "P5E_CPU0_P3_TX_DP<5>")
	)
	(segment
		(start 365.371888 -285.74873)
		(end 365.370872 -285.749238)
		(width 0.1143)
		(layer "In11.Cu")
		(net "P5E_CPU0_P3_TX_DP<5>")
	)
	(segment
		(start 365.403638 -292.210236)
		(end 365.37265 -292.228016)
		(width 0.1143)
		(layer "In11.Cu")
		(net "P5E_CPU0_P3_TX_DP<5>")
	)
	(segment
		(start 365.802672 -295.610534)
		(end 365.840772 -295.632886)
		(width 0.1143)
		(layer "In11.Cu")
		(net "P5E_CPU0_P3_TX_DP<5>")
	)
	(segment
		(start 365.374936 -290.606734)
		(end 365.37265 -290.608258)
		(width 0.1143)
		(layer "In11.Cu")
		(net "P5E_CPU0_P3_TX_DP<5>")
	)
	(segment
		(start 365.370872 -294.82288)
		(end 365.374428 -294.824658)
		(width 0.1143)
		(layer "In11.Cu")
		(net "P5E_CPU0_P3_TX_DP<5>")
	)
	(segment
		(start 365.371888 -278.623522)
		(end 365.37265 -278.62403)
		(width 0.1143)
		(layer "In11.Cu")
		(net "P5E_CPU0_P3_TX_DP<5>")
	)
	(segment
		(start 378.937012 -368.46383)
		(end 377.993656 -369.725194)
		(width 0.14224)
		(layer "In11.Cu")
		(net "P5E_CPU0_P3_TX_DP<5>")
	)
	(segment
		(start 365.371888 -280.888694)
		(end 365.370872 -280.889202)
		(width 0.1143)
		(layer "In11.Cu")
		(net "P5E_CPU0_P3_TX_DP<5>")
	)
	(segment
		(start 365.984028 -296.446956)
		(end 365.984028 -297.421554)
		(width 0.14224)
		(layer "In11.Cu")
		(net "P5E_CPU0_P3_TX_DP<5>")
	)
	(segment
		(start 365.371888 -284.128718)
		(end 365.370872 -284.129226)
		(width 0.1143)
		(layer "In11.Cu")
		(net "P5E_CPU0_P3_TX_DP<5>")
	)
	(segment
		(start 365.340392 -278.605234)
		(end 365.371888 -278.623522)
		(width 0.1143)
		(layer "In11.Cu")
		(net "P5E_CPU0_P3_TX_DP<5>")
	)
	(segment
		(start 365.873538 -280.0604)
		(end 365.828834 -280.086308)
		(width 0.1143)
		(layer "In11.Cu")
		(net "P5E_CPU0_P3_TX_DP<5>")
	)
	(segment
		(start 365.374682 -281.865324)
		(end 365.37519 -281.865324)
		(width 0.1143)
		(layer "In11.Cu")
		(net "P5E_CPU0_P3_TX_DP<5>")
	)
	(segment
		(start 365.559594 -287.045908)
		(end 365.559594 -287.05048)
		(width 0.1143)
		(layer "In11.Cu")
		(net "P5E_CPU0_P3_TX_DP<5>")
	)
	(segment
		(start 376.464576 -371.491002)
		(end 375.645426 -372.310152)
		(width 0.14224)
		(layer "In11.Cu")
		(net "P5E_CPU0_P3_TX_DP<5>")
	)
	(segment
		(start 365.37265 -278.62403)
		(end 365.37265 -278.623776)
		(width 0.1143)
		(layer "In11.Cu")
		(net "P5E_CPU0_P3_TX_DP<5>")
	)
	(segment
		(start 365.33963 -283.464762)
		(end 365.340392 -283.46527)
		(width 0.1143)
		(layer "In11.Cu")
		(net "P5E_CPU0_P3_TX_DP<5>")
	)
	(segment
		(start 384.07594 -356.940612)
		(end 383.136902 -359.445052)
		(width 0.14224)
		(layer "In11.Cu")
		(net "P5E_CPU0_P3_TX_DP<5>")
	)
	(segment
		(start 365.37265 -284.128464)
		(end 365.371888 -284.128718)
		(width 0.1143)
		(layer "In11.Cu")
		(net "P5E_CPU0_P3_TX_DP<5>")
	)
	(segment
		(start 365.370872 -280.889202)
		(end 365.332772 -280.911554)
		(width 0.1143)
		(layer "In11.Cu")
		(net "P5E_CPU0_P3_TX_DP<5>")
	)
	(segment
		(start 383.136902 -359.445052)
		(end 383.137156 -359.445052)
		(width 0.14224)
		(layer "In11.Cu")
		(net "P5E_CPU0_P3_TX_DP<5>")
	)
	(segment
		(start 365.408718 -292.20668)
		(end 365.403638 -292.210236)
		(width 0.1143)
		(layer "In11.Cu")
		(net "P5E_CPU0_P3_TX_DP<5>")
	)
	(segment
		(start 365.37265 -278.623776)
		(end 365.373666 -278.624284)
		(width 0.1143)
		(layer "In11.Cu")
		(net "P5E_CPU0_P3_TX_DP<5>")
	)
	(segment
		(start 365.84255 -295.633902)
		(end 365.845344 -295.635426)
		(width 0.1143)
		(layer "In11.Cu")
		(net "P5E_CPU0_P3_TX_DP<5>")
	)
	(segment
		(start 365.841788 -295.633394)
		(end 365.84255 -295.633902)
		(width 0.1143)
		(layer "In11.Cu")
		(net "P5E_CPU0_P3_TX_DP<5>")
	)
	(segment
		(start 365.559594 -295.145968)
		(end 365.55934 -295.145968)
		(width 0.1143)
		(layer "In11.Cu")
		(net "P5E_CPU0_P3_TX_DP<5>")
	)
	(segment
		(start 365.572294 -278.953468)
		(end 365.572294 -278.965914)
		(width 0.1143)
		(layer "In11.Cu")
		(net "P5E_CPU0_P3_TX_DP<5>")
	)
	(segment
		(start 365.374682 -285.105348)
		(end 365.37519 -285.105348)
		(width 0.1143)
		(layer "In11.Cu")
		(net "P5E_CPU0_P3_TX_DP<5>")
	)
	(segment
		(start 365.371888 -281.863546)
		(end 365.37265 -281.864054)
		(width 0.1143)
		(layer "In11.Cu")
		(net "P5E_CPU0_P3_TX_DP<5>")
	)
	(segment
		(start 374.39473 -374.181878)
		(end 373.259096 -376.923808)
		(width 0.14224)
		(layer "In11.Cu")
		(net "P5E_CPU0_P3_TX_DP<5>")
	)
	(segment
		(start 373.213122 -379.5903)
		(end 372.922292 -379.88113)
		(width 0.14224)
		(layer "In11.Cu")
		(net "P5E_CPU0_P3_TX_DP<5>")
	)
	(segment
		(start 385.557776 -352.102928)
		(end 384.07594 -356.940612)
		(width 0.14224)
		(layer "In11.Cu")
		(net "P5E_CPU0_P3_TX_DP<5>")
	)
	(segment
		(start 365.37265 -285.104078)
		(end 365.374682 -285.105348)
		(width 0.1143)
		(layer "In11.Cu")
		(net "P5E_CPU0_P3_TX_DP<5>")
	)
	(segment
		(start 365.984028 -296.418508)
		(end 365.984028 -296.446956)
		(width 0.1143)
		(layer "In11.Cu")
		(net "P5E_CPU0_P3_TX_DP<5>")
	)
	(segment
		(start 365.547656 -280.574496)
		(end 365.547656 -280.585926)
		(width 0.1143)
		(layer "In11.Cu")
		(net "P5E_CPU0_P3_TX_DP<5>")
	)
	(segment
		(start 365.845344 -295.635426)
		(end 365.846106 -295.635934)
		(width 0.1143)
		(layer "In11.Cu")
		(net "P5E_CPU0_P3_TX_DP<5>")
	)
	(segment
		(start 365.375444 -285.746952)
		(end 365.374936 -285.746952)
		(width 0.1143)
		(layer "In11.Cu")
		(net "P5E_CPU0_P3_TX_DP<5>")
	)
	(segment
		(start 365.403638 -291.601652)
		(end 365.408718 -291.605208)
		(width 0.1143)
		(layer "In11.Cu")
		(net "P5E_CPU0_P3_TX_DP<5>")
	)
	(segment
		(start 365.84763 -295.636696)
		(end 365.848392 -295.637204)
		(width 0.1143)
		(layer "In11.Cu")
		(net "P5E_CPU0_P3_TX_DP<5>")
	)
	(segment
		(start 365.332772 -285.08071)
		(end 365.370872 -285.103062)
		(width 0.1143)
		(layer "In11.Cu")
		(net "P5E_CPU0_P3_TX_DP<5>")
	)
	(segment
		(start 365.332772 -293.180516)
		(end 365.370872 -293.202868)
		(width 0.1143)
		(layer "In11.Cu")
		(net "P5E_CPU0_P3_TX_DP<5>")
	)
	(segment
		(start 365.370872 -293.202868)
		(end 365.371888 -293.203376)
		(width 0.1143)
		(layer "In11.Cu")
		(net "P5E_CPU0_P3_TX_DP<5>")
	)
	(segment
		(start 370.414042 -306.180744)
		(end 377.239276 -314.497212)
		(width 0.14224)
		(layer "In11.Cu")
		(net "P5E_CPU0_P3_TX_DP<5>")
	)
	(segment
		(start 365.375444 -293.846758)
		(end 365.374936 -293.846758)
		(width 0.1143)
		(layer "In11.Cu")
		(net "P5E_CPU0_P3_TX_DP<5>")
	)
	(segment
		(start 365.37265 -282.508452)
		(end 365.371888 -282.508706)
		(width 0.1143)
		(layer "In11.Cu")
		(net "P5E_CPU0_P3_TX_DP<5>")
	)
	(segment
		(start 365.338868 -288.32429)
		(end 365.339122 -288.32429)
		(width 0.1143)
		(layer "In11.Cu")
		(net "P5E_CPU0_P3_TX_DP<5>")
	)
	(segment
		(start 367.166652 -301.320454)
		(end 370.414042 -306.180744)
		(width 0.14224)
		(layer "In11.Cu")
		(net "P5E_CPU0_P3_TX_DP<5>")
	)
	(segment
		(start 365.332772 -278.600662)
		(end 365.33963 -278.604726)
		(width 0.1143)
		(layer "In11.Cu")
		(net "P5E_CPU0_P3_TX_DP<5>")
	)
	(segment
		(start 365.370872 -291.582856)
		(end 365.371888 -291.583364)
		(width 0.1143)
		(layer "In11.Cu")
		(net "P5E_CPU0_P3_TX_DP<5>")
	)
	(segment
		(start 365.374682 -289.96513)
		(end 365.37519 -289.96513)
		(width 0.1143)
		(layer "In11.Cu")
		(net "P5E_CPU0_P3_TX_DP<5>")
	)
	(segment
		(start 365.339122 -288.32429)
		(end 365.374936 -288.345118)
		(width 0.1143)
		(layer "In11.Cu")
		(net "P5E_CPU0_P3_TX_DP<5>")
	)
	(segment
		(start 365.374936 -293.846758)
		(end 365.37265 -293.848282)
		(width 0.1143)
		(layer "In11.Cu")
		(net "P5E_CPU0_P3_TX_DP<5>")
	)
	(segment
		(start 365.375444 -290.606734)
		(end 365.374936 -290.606734)
		(width 0.1143)
		(layer "In11.Cu")
		(net "P5E_CPU0_P3_TX_DP<5>")
	)
	(segment
		(start 365.370872 -293.849044)
		(end 365.332772 -293.871396)
		(width 0.1143)
		(layer "In11.Cu")
		(net "P5E_CPU0_P3_TX_DP<5>")
	)
	(segment
		(start 365.374428 -294.824658)
		(end 365.404654 -294.842692)
		(width 0.1143)
		(layer "In11.Cu")
		(net "P5E_CPU0_P3_TX_DP<5>")
	)
	(segment
		(start 365.332772 -283.460698)
		(end 365.33963 -283.464762)
		(width 0.1143)
		(layer "In11.Cu")
		(net "P5E_CPU0_P3_TX_DP<5>")
	)
	(segment
		(start 365.37265 -288.988246)
		(end 365.371888 -288.9885)
		(width 0.1143)
		(layer "In11.Cu")
		(net "P5E_CPU0_P3_TX_DP<5>")
	)
	(segment
		(start 365.37265 -281.864054)
		(end 365.374682 -281.865324)
		(width 0.1143)
		(layer "In11.Cu")
		(net "P5E_CPU0_P3_TX_DP<5>")
	)
	(segment
		(start 365.332772 -294.800528)
		(end 365.370872 -294.82288)
		(width 0.1143)
		(layer "In11.Cu")
		(net "P5E_CPU0_P3_TX_DP<5>")
	)
	(segment
		(start 365.37265 -285.748476)
		(end 365.371888 -285.74873)
		(width 0.1143)
		(layer "In11.Cu")
		(net "P5E_CPU0_P3_TX_DP<5>")
	)
	(segment
		(start 365.374936 -288.986722)
		(end 365.37265 -288.988246)
		(width 0.1143)
		(layer "In11.Cu")
		(net "P5E_CPU0_P3_TX_DP<5>")
	)
	(segment
		(start 365.374936 -285.746952)
		(end 365.37265 -285.748476)
		(width 0.1143)
		(layer "In11.Cu")
		(net "P5E_CPU0_P3_TX_DP<5>")
	)
	(segment
		(start 365.840772 -295.632886)
		(end 365.841788 -295.633394)
		(width 0.1143)
		(layer "In11.Cu")
		(net "P5E_CPU0_P3_TX_DP<5>")
	)
	(segment
		(start 365.374682 -293.205154)
		(end 365.37519 -293.205154)
		(width 0.1143)
		(layer "In11.Cu")
		(net "P5E_CPU0_P3_TX_DP<5>")
	)
	(segment
		(start 365.340392 -283.46527)
		(end 365.371888 -283.483558)
		(width 0.1143)
		(layer "In11.Cu")
		(net "P5E_CPU0_P3_TX_DP<5>")
	)
	(segment
		(start 365.846106 -295.635934)
		(end 365.84763 -295.636696)
		(width 0.1143)
		(layer "In11.Cu")
		(net "P5E_CPU0_P3_TX_DP<5>")
	)
	(segment
		(start 365.332772 -291.560504)
		(end 365.370872 -291.582856)
		(width 0.1143)
		(layer "In11.Cu")
		(net "P5E_CPU0_P3_TX_DP<5>")
	)
	(segment
		(start 365.371888 -282.508706)
		(end 365.370872 -282.509214)
		(width 0.1143)
		(layer "In11.Cu")
		(net "P5E_CPU0_P3_TX_DP<5>")
	)
	(segment
		(start 365.852202 -295.639236)
		(end 365.873538 -295.651682)
		(width 0.1143)
		(layer "In11.Cu")
		(net "P5E_CPU0_P3_TX_DP<5>")
	)
	(segment
		(start 365.374936 -288.345118)
		(end 365.37519 -288.345118)
		(width 0.1143)
		(layer "In11.Cu")
		(net "P5E_CPU0_P3_TX_DP<5>")
	)
	(segment
		(start 365.371888 -293.203376)
		(end 365.37265 -293.203884)
		(width 0.1143)
		(layer "In11.Cu")
		(net "P5E_CPU0_P3_TX_DP<5>")
	)
	(segment
		(start 364.71479 -278.136096)
		(end 365.012732 -278.136096)
		(width 0.1143)
		(layer "In11.Cu")
		(net "P5E_CPU0_P3_TX_DP<5>")
	)
	(segment
		(start 365.37265 -291.583872)
		(end 365.403638 -291.601652)
		(width 0.1143)
		(layer "In11.Cu")
		(net "P5E_CPU0_P3_TX_DP<5>")
	)
	(segment
		(start 381.154178 -320.356484)
		(end 382.86817 -324.49516)
		(width 0.14224)
		(layer "In11.Cu")
		(net "P5E_CPU0_P3_TX_DP<5>")
	)
	(segment
		(start 365.559594 -295.14165)
		(end 365.559594 -295.145968)
		(width 0.1143)
		(layer "In11.Cu")
		(net "P5E_CPU0_P3_TX_DP<5>")
	)
	(segment
		(start 365.370872 -289.962844)
		(end 365.371888 -289.963352)
		(width 0.1143)
		(layer "In11.Cu")
		(net "P5E_CPU0_P3_TX_DP<5>")
	)
	(segment
		(start 365.849662 -295.637966)
		(end 365.852202 -295.639236)
		(width 0.1143)
		(layer "In11.Cu")
		(net "P5E_CPU0_P3_TX_DP<5>")
	)
	(segment
		(start 365.37265 -280.888186)
		(end 365.371888 -280.888694)
		(width 0.1143)
		(layer "In11.Cu")
		(net "P5E_CPU0_P3_TX_DP<5>")
	)
	(segment
		(start 365.374936 -282.506928)
		(end 365.37265 -282.508452)
		(width 0.1143)
		(layer "In11.Cu")
		(net "P5E_CPU0_P3_TX_DP<5>")
	)
	(segment
		(start 366.029748 -296.372788)
		(end 365.984028 -296.418508)
		(width 0.1143)
		(layer "In11.Cu")
		(net "P5E_CPU0_P3_TX_DP<5>")
	)
	(segment
		(start 365.370872 -290.60902)
		(end 365.332772 -290.631372)
		(width 0.1143)
		(layer "In11.Cu")
		(net "P5E_CPU0_P3_TX_DP<5>")
	)
	(segment
		(start 365.375444 -288.986722)
		(end 365.374936 -288.986722)
		(width 0.1143)
		(layer "In11.Cu")
		(net "P5E_CPU0_P3_TX_DP<5>")
	)
	(segment
		(start 365.371888 -293.848536)
		(end 365.370872 -293.849044)
		(width 0.1143)
		(layer "In11.Cu")
		(net "P5E_CPU0_P3_TX_DP<5>")
	)
	(segment
		(start 365.374936 -284.12694)
		(end 365.37265 -284.128464)
		(width 0.1143)
		(layer "In11.Cu")
		(net "P5E_CPU0_P3_TX_DP<5>")
	)
	(arc
		(start 365.332772 -292.251384)
		(mid 365.089445 -292.71595)
		(end 365.332772 -293.180516)
		(width 0.1143)
		(layer "In11.Cu")
		(net "P5E_CPU0_P3_TX_DP<5>")
	)
	(arc
		(start 382.69164 -360.561128)
		(mid 381.130195 -364.170434)
		(end 379.412246 -367.707926)
		(width 0.14224)
		(layer "In11.Cu")
		(net "P5E_CPU0_P3_TX_DP<5>")
	)
	(arc
		(start 365.095536 -278.2189)
		(mid 365.097324 -278.230349)
		(end 365.099346 -278.24176)
		(width 0.1143)
		(layer "In11.Cu")
		(net "P5E_CPU0_P3_TX_DP<5>")
	)
	(arc
		(start 386.074412 -340.614508)
		(mid 386.079714 -340.649893)
		(end 386.081524 -340.685628)
		(width 0.14224)
		(layer "In11.Cu")
		(net "P5E_CPU0_P3_TX_DP<5>")
	)
	(arc
		(start 365.099346 -278.24176)
		(mid 365.180779 -278.444158)
		(end 365.332772 -278.600662)
		(width 0.1143)
		(layer "In11.Cu")
		(net "P5E_CPU0_P3_TX_DP<5>")
	)
	(arc
		(start 365.405416 -286.74314)
		(mid 365.518823 -286.876029)
		(end 365.559594 -287.045908)
		(width 0.1143)
		(layer "In11.Cu")
		(net "P5E_CPU0_P3_TX_DP<5>")
	)
	(arc
		(start 366.009174 -279.634442)
		(mid 366.011795 -279.869851)
		(end 365.873538 -280.0604)
		(width 0.1143)
		(layer "In11.Cu")
		(net "P5E_CPU0_P3_TX_DP<5>")
	)
	(arc
		(start 365.873538 -295.651682)
		(mid 365.92247 -295.69377)
		(end 365.963454 -295.74363)
		(width 0.1143)
		(layer "In11.Cu")
		(net "P5E_CPU0_P3_TX_DP<5>")
	)
	(arc
		(start 365.572294 -278.965914)
		(mid 365.644559 -279.235843)
		(end 365.842042 -279.433528)
		(width 0.1143)
		(layer "In11.Cu")
		(net "P5E_CPU0_P3_TX_DP<5>")
	)
	(arc
		(start 365.332772 -282.531566)
		(mid 365.089445 -282.996132)
		(end 365.332772 -283.460698)
		(width 0.1143)
		(layer "In11.Cu")
		(net "P5E_CPU0_P3_TX_DP<5>")
	)
	(arc
		(start 365.37519 -281.865324)
		(mid 365.559923 -282.186016)
		(end 365.375444 -282.506928)
		(width 0.1143)
		(layer "In11.Cu")
		(net "P5E_CPU0_P3_TX_DP<5>")
	)
	(arc
		(start 365.408718 -291.605208)
		(mid 365.562816 -291.905944)
		(end 365.408718 -292.20668)
		(width 0.1143)
		(layer "In11.Cu")
		(net "P5E_CPU0_P3_TX_DP<5>")
	)
	(arc
		(start 365.37519 -288.345118)
		(mid 365.559923 -288.66581)
		(end 365.375444 -288.986722)
		(width 0.1143)
		(layer "In11.Cu")
		(net "P5E_CPU0_P3_TX_DP<5>")
	)
	(arc
		(start 365.547656 -280.585926)
		(mid 365.500745 -280.760555)
		(end 365.37265 -280.888186)
		(width 0.1143)
		(layer "In11.Cu")
		(net "P5E_CPU0_P3_TX_DP<5>")
	)
	(arc
		(start 365.332772 -290.631372)
		(mid 365.089445 -291.095938)
		(end 365.332772 -291.560504)
		(width 0.1143)
		(layer "In11.Cu")
		(net "P5E_CPU0_P3_TX_DP<5>")
	)
	(arc
		(start 375.645426 -372.310152)
		(mid 374.927904 -373.184422)
		(end 374.39473 -374.181878)
		(width 0.14224)
		(layer "In11.Cu")
		(net "P5E_CPU0_P3_TX_DP<5>")
	)
	(arc
		(start 365.404654 -294.842692)
		(mid 365.518537 -294.973306)
		(end 365.559594 -295.14165)
		(width 0.1143)
		(layer "In11.Cu")
		(net "P5E_CPU0_P3_TX_DP<5>")
	)
	(arc
		(start 365.37519 -289.96513)
		(mid 365.559923 -290.285822)
		(end 365.375444 -290.606734)
		(width 0.1143)
		(layer "In11.Cu")
		(net "P5E_CPU0_P3_TX_DP<5>")
	)
	(arc
		(start 365.828834 -280.086308)
		(mid 365.622975 -280.292809)
		(end 365.547656 -280.574496)
		(width 0.1143)
		(layer "In11.Cu")
		(net "P5E_CPU0_P3_TX_DP<5>")
	)
	(arc
		(start 365.332772 -285.77159)
		(mid 365.089445 -286.236156)
		(end 365.332772 -286.700722)
		(width 0.1143)
		(layer "In11.Cu")
		(net "P5E_CPU0_P3_TX_DP<5>")
	)
	(arc
		(start 365.387382 -278.632158)
		(mid 365.52277 -278.768107)
		(end 365.572294 -278.953468)
		(width 0.1143)
		(layer "In11.Cu")
		(net "P5E_CPU0_P3_TX_DP<5>")
	)
	(arc
		(start 379.00864 -368.359436)
		(mid 378.973867 -368.412347)
		(end 378.937012 -368.46383)
		(width 0.14224)
		(layer "In11.Cu")
		(net "P5E_CPU0_P3_TX_DP<5>")
	)
	(arc
		(start 365.332772 -284.151578)
		(mid 365.089445 -284.616144)
		(end 365.332772 -285.08071)
		(width 0.1143)
		(layer "In11.Cu")
		(net "P5E_CPU0_P3_TX_DP<5>")
	)
	(arc
		(start 386.081524 -348.605856)
		(mid 385.949824 -350.373888)
		(end 385.557776 -352.102928)
		(width 0.14224)
		(layer "In11.Cu")
		(net "P5E_CPU0_P3_TX_DP<5>")
	)
	(arc
		(start 365.37519 -283.485336)
		(mid 365.559923 -283.806028)
		(end 365.375444 -284.12694)
		(width 0.1143)
		(layer "In11.Cu")
		(net "P5E_CPU0_P3_TX_DP<5>")
	)
	(arc
		(start 365.559594 -287.05048)
		(mid 365.519339 -287.217293)
		(end 365.407448 -287.347406)
		(width 0.1143)
		(layer "In11.Cu")
		(net "P5E_CPU0_P3_TX_DP<5>")
	)
	(arc
		(start 383.137156 -359.445052)
		(mid 382.916266 -360.003835)
		(end 382.69164 -360.561128)
		(width 0.14224)
		(layer "In11.Cu")
		(net "P5E_CPU0_P3_TX_DP<5>")
	)
	(arc
		(start 365.963454 -295.74363)
		(mid 366.012774 -295.844759)
		(end 366.029748 -295.955974)
		(width 0.1143)
		(layer "In11.Cu")
		(net "P5E_CPU0_P3_TX_DP<5>")
	)
	(arc
		(start 365.08944 -287.856168)
		(mid 365.153955 -288.118387)
		(end 365.332772 -288.320734)
		(width 0.1143)
		(layer "In11.Cu")
		(net "P5E_CPU0_P3_TX_DP<5>")
	)
	(arc
		(start 379.412246 -367.707926)
		(mid 379.379654 -367.768114)
		(end 379.344428 -367.826798)
		(width 0.14224)
		(layer "In11.Cu")
		(net "P5E_CPU0_P3_TX_DP<5>")
	)
	(arc
		(start 377.993656 -369.725194)
		(mid 377.260782 -370.635519)
		(end 376.464576 -371.491002)
		(width 0.14224)
		(layer "In11.Cu")
		(net "P5E_CPU0_P3_TX_DP<5>")
	)
	(arc
		(start 365.37519 -285.105348)
		(mid 365.559923 -285.42604)
		(end 365.375444 -285.746952)
		(width 0.1143)
		(layer "In11.Cu")
		(net "P5E_CPU0_P3_TX_DP<5>")
	)
	(arc
		(start 365.332772 -280.911554)
		(mid 365.089445 -281.37612)
		(end 365.332772 -281.840686)
		(width 0.1143)
		(layer "In11.Cu")
		(net "P5E_CPU0_P3_TX_DP<5>")
	)
	(arc
		(start 365.335312 -287.389824)
		(mid 365.15466 -287.592569)
		(end 365.08944 -287.856168)
		(width 0.1143)
		(layer "In11.Cu")
		(net "P5E_CPU0_P3_TX_DP<5>")
	)
	(arc
		(start 365.332772 -289.01136)
		(mid 365.089445 -289.475926)
		(end 365.332772 -289.940492)
		(width 0.1143)
		(layer "In11.Cu")
		(net "P5E_CPU0_P3_TX_DP<5>")
	)
	(arc
		(start 365.332772 -293.871396)
		(mid 365.089445 -294.335962)
		(end 365.332772 -294.800528)
		(width 0.1143)
		(layer "In11.Cu")
		(net "P5E_CPU0_P3_TX_DP<5>")
	)
	(arc
		(start 365.37519 -293.205154)
		(mid 365.559923 -293.525846)
		(end 365.375444 -293.846758)
		(width 0.1143)
		(layer "In11.Cu")
		(net "P5E_CPU0_P3_TX_DP<5>")
	)
	(arc
		(start 365.873538 -279.45207)
		(mid 365.955519 -279.53272)
		(end 366.009174 -279.634442)
		(width 0.1143)
		(layer "In11.Cu")
		(net "P5E_CPU0_P3_TX_DP<5>")
	)
	(arc
		(start 373.259096 -376.923808)
		(mid 373.224765 -377.036991)
		(end 373.213122 -377.154694)
		(width 0.14224)
		(layer "In11.Cu")
		(net "P5E_CPU0_P3_TX_DP<5>")
	)
	(arc
		(start 365.55934 -295.145968)
		(mid 365.623855 -295.408187)
		(end 365.802672 -295.610534)
		(width 0.1143)
		(layer "In11.Cu")
		(net "P5E_CPU0_P3_TX_DP<5>")
	)
	(segment
		(start 371.220492 -382.34493)
		(end 371.491002 -382.61544)
		(width 0.12954)
		(layer "F.Cu")
		(net "P5E_CPU0_P3_TX_DP<4>")
	)
	(segment
		(start 364.247938 -279.49017)
		(end 364.71479 -279.756108)
		(width 0.12954)
		(layer "F.Cu")
		(net "P5E_CPU0_P3_TX_DP<4>")
	)
	(segment
		(start 371.491002 -382.61544)
		(end 371.491002 -383.31902)
		(width 0.12954)
		(layer "F.Cu")
		(net "P5E_CPU0_P3_TX_DP<4>")
	)
	(segment
		(start 371.491002 -383.31902)
		(end 371.195092 -383.61493)
		(width 0.12954)
		(layer "F.Cu")
		(net "P5E_CPU0_P3_TX_DP<4>")
	)
	(segment
		(start 364.43539 -282.506928)
		(end 364.434882 -282.506928)
		(width 0.1143)
		(layer "In11.Cu")
		(net "P5E_CPU0_P3_TX_DP<4>")
	)
	(segment
		(start 364.432342 -290.608512)
		(end 364.431834 -290.608766)
		(width 0.1143)
		(layer "In11.Cu")
		(net "P5E_CPU0_P3_TX_DP<4>")
	)
	(segment
		(start 364.430818 -285.103062)
		(end 364.431834 -285.10357)
		(width 0.1143)
		(layer "In11.Cu")
		(net "P5E_CPU0_P3_TX_DP<4>")
	)
	(segment
		(start 365.089694 -296.372788)
		(end 365.043974 -296.418508)
		(width 0.1143)
		(layer "In11.Cu")
		(net "P5E_CPU0_P3_TX_DP<4>")
	)
	(segment
		(start 364.429802 -283.482288)
		(end 364.430564 -283.482796)
		(width 0.1143)
		(layer "In11.Cu")
		(net "P5E_CPU0_P3_TX_DP<4>")
	)
	(segment
		(start 364.555278 -287.24098)
		(end 364.488476 -287.32353)
		(width 0.1143)
		(layer "In11.Cu")
		(net "P5E_CPU0_P3_TX_DP<4>")
	)
	(segment
		(start 364.433104 -288.987992)
		(end 364.431834 -288.9885)
		(width 0.1143)
		(layer "In11.Cu")
		(net "P5E_CPU0_P3_TX_DP<4>")
	)
	(segment
		(start 364.430564 -283.482796)
		(end 364.432342 -283.483812)
		(width 0.1143)
		(layer "In11.Cu")
		(net "P5E_CPU0_P3_TX_DP<4>")
	)
	(segment
		(start 364.427262 -285.10103)
		(end 364.428278 -285.101538)
		(width 0.1143)
		(layer "In11.Cu")
		(net "P5E_CPU0_P3_TX_DP<4>")
	)
	(segment
		(start 364.431834 -293.203122)
		(end 364.432342 -293.203376)
		(width 0.1143)
		(layer "In11.Cu")
		(net "P5E_CPU0_P3_TX_DP<4>")
	)
	(segment
		(start 364.431834 -291.58311)
		(end 364.432342 -291.583364)
		(width 0.1143)
		(layer "In11.Cu")
		(net "P5E_CPU0_P3_TX_DP<4>")
	)
	(segment
		(start 364.433104 -283.48432)
		(end 364.448598 -283.49321)
		(width 0.1143)
		(layer "In11.Cu")
		(net "P5E_CPU0_P3_TX_DP<4>")
	)
	(segment
		(start 364.428786 -283.48178)
		(end 364.429802 -283.482288)
		(width 0.1143)
		(layer "In11.Cu")
		(net "P5E_CPU0_P3_TX_DP<4>")
	)
	(segment
		(start 364.400338 -293.185088)
		(end 364.431834 -293.203376)
		(width 0.1143)
		(layer "In11.Cu")
		(net "P5E_CPU0_P3_TX_DP<4>")
	)
	(segment
		(start 364.392718 -281.840686)
		(end 364.399576 -281.84475)
		(width 0.1143)
		(layer "In11.Cu")
		(net "P5E_CPU0_P3_TX_DP<4>")
	)
	(segment
		(start 364.431834 -288.9885)
		(end 364.430818 -288.989008)
		(width 0.1143)
		(layer "In11.Cu")
		(net "P5E_CPU0_P3_TX_DP<4>")
	)
	(segment
		(start 364.432342 -292.228524)
		(end 364.431834 -292.228778)
		(width 0.1143)
		(layer "In11.Cu")
		(net "P5E_CPU0_P3_TX_DP<4>")
	)
	(segment
		(start 364.432342 -293.848536)
		(end 364.431834 -293.84879)
		(width 0.1143)
		(layer "In11.Cu")
		(net "P5E_CPU0_P3_TX_DP<4>")
	)
	(segment
		(start 364.432342 -283.483812)
		(end 364.433104 -283.48432)
		(width 0.1143)
		(layer "In11.Cu")
		(net "P5E_CPU0_P3_TX_DP<4>")
	)
	(segment
		(start 364.434628 -281.865324)
		(end 364.435136 -281.865324)
		(width 0.1143)
		(layer "In11.Cu")
		(net "P5E_CPU0_P3_TX_DP<4>")
	)
	(segment
		(start 364.450122 -283.494226)
		(end 364.450376 -283.494226)
		(width 0.1143)
		(layer "In11.Cu")
		(net "P5E_CPU0_P3_TX_DP<4>")
	)
	(segment
		(start 364.442248 -294.836342)
		(end 364.4519 -294.836342)
		(width 0.1143)
		(layer "In11.Cu")
		(net "P5E_CPU0_P3_TX_DP<4>")
	)
	(segment
		(start 365.039402 -297.5483)
		(end 366.3442 -301.849536)
		(width 0.14224)
		(layer "In11.Cu")
		(net "P5E_CPU0_P3_TX_DP<4>")
	)
	(segment
		(start 364.399576 -281.84475)
		(end 364.400338 -281.845258)
		(width 0.1143)
		(layer "In11.Cu")
		(net "P5E_CPU0_P3_TX_DP<4>")
	)
	(segment
		(start 364.430818 -293.849044)
		(end 364.429294 -293.85006)
		(width 0.1143)
		(layer "In11.Cu")
		(net "P5E_CPU0_P3_TX_DP<4>")
	)
	(segment
		(start 365.043974 -296.446956)
		(end 365.043974 -296.774108)
		(width 0.14224)
		(layer "In11.Cu")
		(net "P5E_CPU0_P3_TX_DP<4>")
	)
	(segment
		(start 364.61954 -280.56332)
		(end 364.61954 -280.566114)
		(width 0.1143)
		(layer "In11.Cu")
		(net "P5E_CPU0_P3_TX_DP<4>")
	)
	(segment
		(start 364.430818 -285.749238)
		(end 364.429294 -285.750254)
		(width 0.1143)
		(layer "In11.Cu")
		(net "P5E_CPU0_P3_TX_DP<4>")
	)
	(segment
		(start 364.431834 -292.228778)
		(end 364.431834 -292.228524)
		(width 0.1143)
		(layer "In11.Cu")
		(net "P5E_CPU0_P3_TX_DP<4>")
	)
	(segment
		(start 364.432596 -285.748222)
		(end 364.431834 -285.74873)
		(width 0.1143)
		(layer "In11.Cu")
		(net "P5E_CPU0_P3_TX_DP<4>")
	)
	(segment
		(start 364.555278 -287.240726)
		(end 364.555278 -287.24098)
		(width 0.1143)
		(layer "In11.Cu")
		(net "P5E_CPU0_P3_TX_DP<4>")
	)
	(segment
		(start 364.431834 -293.203376)
		(end 364.431834 -293.203122)
		(width 0.1143)
		(layer "In11.Cu")
		(net "P5E_CPU0_P3_TX_DP<4>")
	)
	(segment
		(start 371.511322 -377.5075)
		(end 371.511322 -381.987298)
		(width 0.14224)
		(layer "In11.Cu")
		(net "P5E_CPU0_P3_TX_DP<4>")
	)
	(segment
		(start 364.431834 -293.84879)
		(end 364.431834 -293.848536)
		(width 0.1143)
		(layer "In11.Cu")
		(net "P5E_CPU0_P3_TX_DP<4>")
	)
	(segment
		(start 365.039402 -296.77868)
		(end 365.039402 -297.5483)
		(width 0.14224)
		(layer "In11.Cu")
		(net "P5E_CPU0_P3_TX_DP<4>")
	)
	(segment
		(start 364.432596 -281.864054)
		(end 364.434628 -281.865324)
		(width 0.1143)
		(layer "In11.Cu")
		(net "P5E_CPU0_P3_TX_DP<4>")
	)
	(segment
		(start 364.446058 -284.12059)
		(end 364.445296 -284.121098)
		(width 0.1143)
		(layer "In11.Cu")
		(net "P5E_CPU0_P3_TX_DP<4>")
	)
	(segment
		(start 364.61573 -287.049718)
		(end 364.591854 -287.163764)
		(width 0.1143)
		(layer "In11.Cu")
		(net "P5E_CPU0_P3_TX_DP<4>")
	)
	(segment
		(start 364.933484 -280.0604)
		(end 364.901734 -280.078688)
		(width 0.1143)
		(layer "In11.Cu")
		(net "P5E_CPU0_P3_TX_DP<4>")
	)
	(segment
		(start 364.431834 -290.608512)
		(end 364.430818 -290.60902)
		(width 0.1143)
		(layer "In11.Cu")
		(net "P5E_CPU0_P3_TX_DP<4>")
	)
	(segment
		(start 364.429294 -292.230048)
		(end 364.392718 -292.251384)
		(width 0.1143)
		(layer "In11.Cu")
		(net "P5E_CPU0_P3_TX_DP<4>")
	)
	(segment
		(start 364.430056 -285.102554)
		(end 364.430818 -285.103062)
		(width 0.1143)
		(layer "In11.Cu")
		(net "P5E_CPU0_P3_TX_DP<4>")
	)
	(segment
		(start 364.886748 -295.624758)
		(end 364.89132 -295.627552)
		(width 0.1143)
		(layer "In11.Cu")
		(net "P5E_CPU0_P3_TX_DP<4>")
	)
	(segment
		(start 364.432596 -282.508452)
		(end 364.432596 -282.508198)
		(width 0.1143)
		(layer "In11.Cu")
		(net "P5E_CPU0_P3_TX_DP<4>")
	)
	(segment
		(start 364.448598 -283.49321)
		(end 364.450122 -283.494226)
		(width 0.1143)
		(layer "In11.Cu")
		(net "P5E_CPU0_P3_TX_DP<4>")
	)
	(segment
		(start 364.863634 -295.611296)
		(end 364.886748 -295.624758)
		(width 0.1143)
		(layer "In11.Cu")
		(net "P5E_CPU0_P3_TX_DP<4>")
	)
	(segment
		(start 364.430818 -292.229032)
		(end 364.429294 -292.230048)
		(width 0.1143)
		(layer "In11.Cu")
		(net "P5E_CPU0_P3_TX_DP<4>")
	)
	(segment
		(start 364.463584 -285.730442)
		(end 364.432596 -285.748222)
		(width 0.1143)
		(layer "In11.Cu")
		(net "P5E_CPU0_P3_TX_DP<4>")
	)
	(segment
		(start 364.429294 -288.990024)
		(end 364.392718 -289.01136)
		(width 0.1143)
		(layer "In11.Cu")
		(net "P5E_CPU0_P3_TX_DP<4>")
	)
	(segment
		(start 366.3442 -301.849536)
		(end 370.037868 -307.377592)
		(width 0.14224)
		(layer "In11.Cu")
		(net "P5E_CPU0_P3_TX_DP<4>")
	)
	(segment
		(start 364.45063 -284.11805)
		(end 364.450122 -284.11805)
		(width 0.1143)
		(layer "In11.Cu")
		(net "P5E_CPU0_P3_TX_DP<4>")
	)
	(segment
		(start 364.427262 -282.511246)
		(end 364.425738 -282.512262)
		(width 0.1143)
		(layer "In11.Cu")
		(net "P5E_CPU0_P3_TX_DP<4>")
	)
	(segment
		(start 364.392718 -288.320734)
		(end 364.398306 -288.323528)
		(width 0.1143)
		(layer "In11.Cu")
		(net "P5E_CPU0_P3_TX_DP<4>")
	)
	(segment
		(start 371.464078 -382.101344)
		(end 371.220492 -382.34493)
		(width 0.14224)
		(layer "In11.Cu")
		(net "P5E_CPU0_P3_TX_DP<4>")
	)
	(segment
		(start 380.280164 -320.730372)
		(end 381.921004 -324.97014)
		(width 0.14224)
		(layer "In11.Cu")
		(net "P5E_CPU0_P3_TX_DP<4>")
	)
	(segment
		(start 364.464854 -286.742886)
		(end 364.465362 -286.74314)
		(width 0.1143)
		(layer "In11.Cu")
		(net "P5E_CPU0_P3_TX_DP<4>")
	)
	(segment
		(start 385.131564 -341.11184)
		(end 385.131564 -348.284546)
		(width 0.14224)
		(layer "In11.Cu")
		(net "P5E_CPU0_P3_TX_DP<4>")
	)
	(segment
		(start 364.392718 -291.560504)
		(end 364.399576 -291.564568)
		(width 0.1143)
		(layer "In11.Cu")
		(net "P5E_CPU0_P3_TX_DP<4>")
	)
	(segment
		(start 364.431834 -285.10357)
		(end 364.432596 -285.104078)
		(width 0.1143)
		(layer "In11.Cu")
		(net "P5E_CPU0_P3_TX_DP<4>")
	)
	(segment
		(start 364.463584 -280.870406)
		(end 364.392718 -280.911554)
		(width 0.1143)
		(layer "In11.Cu")
		(net "P5E_CPU0_P3_TX_DP<4>")
	)
	(segment
		(start 364.61573 -287.049464)
		(end 364.61573 -287.049718)
		(width 0.1143)
		(layer "In11.Cu")
		(net "P5E_CPU0_P3_TX_DP<4>")
	)
	(segment
		(start 364.450122 -284.11805)
		(end 364.44936 -284.118558)
		(width 0.1143)
		(layer "In11.Cu")
		(net "P5E_CPU0_P3_TX_DP<4>")
	)
	(segment
		(start 364.392718 -286.700722)
		(end 364.432342 -286.723328)
		(width 0.1143)
		(layer "In11.Cu")
		(net "P5E_CPU0_P3_TX_DP<4>")
	)
	(segment
		(start 364.429294 -285.750254)
		(end 364.392718 -285.77159)
		(width 0.1143)
		(layer "In11.Cu")
		(net "P5E_CPU0_P3_TX_DP<4>")
	)
	(segment
		(start 364.892336 -295.62806)
		(end 364.933484 -295.651682)
		(width 0.1143)
		(layer "In11.Cu")
		(net "P5E_CPU0_P3_TX_DP<4>")
	)
	(segment
		(start 364.431834 -291.583364)
		(end 364.431834 -291.58311)
		(width 0.1143)
		(layer "In11.Cu")
		(net "P5E_CPU0_P3_TX_DP<4>")
	)
	(segment
		(start 364.410752 -283.471366)
		(end 364.428786 -283.48178)
		(width 0.1143)
		(layer "In11.Cu")
		(net "P5E_CPU0_P3_TX_DP<4>")
	)
	(segment
		(start 364.392718 -289.940492)
		(end 364.399576 -289.944556)
		(width 0.1143)
		(layer "In11.Cu")
		(net "P5E_CPU0_P3_TX_DP<4>")
	)
	(segment
		(start 364.400338 -289.945064)
		(end 364.431834 -289.963352)
		(width 0.1143)
		(layer "In11.Cu")
		(net "P5E_CPU0_P3_TX_DP<4>")
	)
	(segment
		(start 364.400338 -281.845258)
		(end 364.431834 -281.863546)
		(width 0.1143)
		(layer "In11.Cu")
		(net "P5E_CPU0_P3_TX_DP<4>")
	)
	(segment
		(start 377.142756 -316.035182)
		(end 380.280164 -320.730372)
		(width 0.14224)
		(layer "In11.Cu")
		(net "P5E_CPU0_P3_TX_DP<4>")
	)
	(segment
		(start 364.425738 -282.512262)
		(end 364.411768 -282.52039)
		(width 0.1143)
		(layer "In11.Cu")
		(net "P5E_CPU0_P3_TX_DP<4>")
	)
	(segment
		(start 381.921004 -324.97014)
		(end 385.131564 -341.11184)
		(width 0.14224)
		(layer "In11.Cu")
		(net "P5E_CPU0_P3_TX_DP<4>")
	)
	(segment
		(start 364.400338 -291.565076)
		(end 364.431834 -291.583364)
		(width 0.1143)
		(layer "In11.Cu")
		(net "P5E_CPU0_P3_TX_DP<4>")
	)
	(segment
		(start 365.043974 -296.774108)
		(end 365.039402 -296.77868)
		(width 0.14224)
		(layer "In11.Cu")
		(net "P5E_CPU0_P3_TX_DP<4>")
	)
	(segment
		(start 364.431834 -282.508706)
		(end 364.427262 -282.511246)
		(width 0.1143)
		(layer "In11.Cu")
		(net "P5E_CPU0_P3_TX_DP<4>")
	)
	(segment
		(start 364.445296 -284.121098)
		(end 364.434374 -284.127448)
		(width 0.1143)
		(layer "In11.Cu")
		(net "P5E_CPU0_P3_TX_DP<4>")
	)
	(segment
		(start 364.398306 -288.323528)
		(end 364.427008 -288.340292)
		(width 0.1143)
		(layer "In11.Cu")
		(net "P5E_CPU0_P3_TX_DP<4>")
	)
	(segment
		(start 364.429294 -290.610036)
		(end 364.392718 -290.631372)
		(width 0.1143)
		(layer "In11.Cu")
		(net "P5E_CPU0_P3_TX_DP<4>")
	)
	(segment
		(start 377.193302 -367.564416)
		(end 373.700802 -371.6147)
		(width 0.14224)
		(layer "In11.Cu")
		(net "P5E_CPU0_P3_TX_DP<4>")
	)
	(segment
		(start 364.418626 -287.377378)
		(end 364.403386 -287.384998)
		(width 0.1143)
		(layer "In11.Cu")
		(net "P5E_CPU0_P3_TX_DP<4>")
	)
	(segment
		(start 385.131564 -348.284546)
		(end 385.13131 -348.284292)
		(width 0.14224)
		(layer "In11.Cu")
		(net "P5E_CPU0_P3_TX_DP<4>")
	)
	(segment
		(start 364.431834 -292.228524)
		(end 364.430818 -292.229032)
		(width 0.1143)
		(layer "In11.Cu")
		(net "P5E_CPU0_P3_TX_DP<4>")
	)
	(segment
		(start 364.42777 -288.3408)
		(end 364.431834 -288.34334)
		(width 0.1143)
		(layer "In11.Cu")
		(net "P5E_CPU0_P3_TX_DP<4>")
	)
	(segment
		(start 364.434882 -282.506928)
		(end 364.432596 -282.508452)
		(width 0.1143)
		(layer "In11.Cu")
		(net "P5E_CPU0_P3_TX_DP<4>")
	)
	(segment
		(start 364.431834 -293.848536)
		(end 364.430818 -293.849044)
		(width 0.1143)
		(layer "In11.Cu")
		(net "P5E_CPU0_P3_TX_DP<4>")
	)
	(segment
		(start 364.431834 -290.608766)
		(end 364.431834 -290.608512)
		(width 0.1143)
		(layer "In11.Cu")
		(net "P5E_CPU0_P3_TX_DP<4>")
	)
	(segment
		(start 364.431834 -285.74873)
		(end 364.430818 -285.749238)
		(width 0.1143)
		(layer "In11.Cu")
		(net "P5E_CPU0_P3_TX_DP<4>")
	)
	(segment
		(start 364.431834 -289.963098)
		(end 364.432342 -289.963352)
		(width 0.1143)
		(layer "In11.Cu")
		(net "P5E_CPU0_P3_TX_DP<4>")
	)
	(segment
		(start 365.012732 -279.756108)
		(end 365.082582 -279.825958)
		(width 0.1143)
		(layer "In11.Cu")
		(net "P5E_CPU0_P3_TX_DP<4>")
	)
	(segment
		(start 364.399576 -289.944556)
		(end 364.400338 -289.945064)
		(width 0.1143)
		(layer "In11.Cu")
		(net "P5E_CPU0_P3_TX_DP<4>")
	)
	(segment
		(start 364.434374 -284.127448)
		(end 364.430818 -284.129226)
		(width 0.1143)
		(layer "In11.Cu")
		(net "P5E_CPU0_P3_TX_DP<4>")
	)
	(segment
		(start 364.89132 -295.627552)
		(end 364.892336 -295.62806)
		(width 0.1143)
		(layer "In11.Cu")
		(net "P5E_CPU0_P3_TX_DP<4>")
	)
	(segment
		(start 364.428278 -285.101538)
		(end 364.430056 -285.102554)
		(width 0.1143)
		(layer "In11.Cu")
		(net "P5E_CPU0_P3_TX_DP<4>")
	)
	(segment
		(start 364.71479 -279.756108)
		(end 365.012732 -279.756108)
		(width 0.1143)
		(layer "In11.Cu")
		(net "P5E_CPU0_P3_TX_DP<4>")
	)
	(segment
		(start 364.429294 -293.85006)
		(end 364.428024 -293.850822)
		(width 0.1143)
		(layer "In11.Cu")
		(net "P5E_CPU0_P3_TX_DP<4>")
	)
	(segment
		(start 364.432596 -282.508198)
		(end 364.431834 -282.508706)
		(width 0.1143)
		(layer "In11.Cu")
		(net "P5E_CPU0_P3_TX_DP<4>")
	)
	(segment
		(start 364.432596 -285.104078)
		(end 364.463584 -285.121858)
		(width 0.1143)
		(layer "In11.Cu")
		(net "P5E_CPU0_P3_TX_DP<4>")
	)
	(segment
		(start 364.430818 -290.60902)
		(end 364.429294 -290.610036)
		(width 0.1143)
		(layer "In11.Cu")
		(net "P5E_CPU0_P3_TX_DP<4>")
	)
	(segment
		(start 364.425484 -287.374076)
		(end 364.418626 -287.377378)
		(width 0.1143)
		(layer "In11.Cu")
		(net "P5E_CPU0_P3_TX_DP<4>")
	)
	(segment
		(start 364.430818 -284.129226)
		(end 364.428532 -284.13075)
		(width 0.1143)
		(layer "In11.Cu")
		(net "P5E_CPU0_P3_TX_DP<4>")
	)
	(segment
		(start 364.430818 -288.989008)
		(end 364.429294 -288.990024)
		(width 0.1143)
		(layer "In11.Cu")
		(net "P5E_CPU0_P3_TX_DP<4>")
	)
	(segment
		(start 364.44936 -284.118558)
		(end 364.446058 -284.12059)
		(width 0.1143)
		(layer "In11.Cu")
		(net "P5E_CPU0_P3_TX_DP<4>")
	)
	(segment
		(start 364.425738 -294.819832)
		(end 364.442248 -294.836342)
		(width 0.1143)
		(layer "In11.Cu")
		(net "P5E_CPU0_P3_TX_DP<4>")
	)
	(segment
		(start 364.431834 -281.863546)
		(end 364.432596 -281.864054)
		(width 0.1143)
		(layer "In11.Cu")
		(net "P5E_CPU0_P3_TX_DP<4>")
	)
	(segment
		(start 364.399576 -291.564568)
		(end 364.400338 -291.565076)
		(width 0.1143)
		(layer "In11.Cu")
		(net "P5E_CPU0_P3_TX_DP<4>")
	)
	(segment
		(start 370.037868 -307.377592)
		(end 377.142756 -316.035182)
		(width 0.14224)
		(layer "In11.Cu")
		(net "P5E_CPU0_P3_TX_DP<4>")
	)
	(segment
		(start 365.089694 -295.955974)
		(end 365.089694 -296.372788)
		(width 0.1143)
		(layer "In11.Cu")
		(net "P5E_CPU0_P3_TX_DP<4>")
	)
	(segment
		(start 365.043974 -296.418508)
		(end 365.043974 -296.446956)
		(width 0.1143)
		(layer "In11.Cu")
		(net "P5E_CPU0_P3_TX_DP<4>")
	)
	(segment
		(start 364.403386 -287.384998)
		(end 364.395258 -287.389824)
		(width 0.1143)
		(layer "In11.Cu")
		(net "P5E_CPU0_P3_TX_DP<4>")
	)
	(segment
		(start 364.427008 -288.340292)
		(end 364.42777 -288.3408)
		(width 0.1143)
		(layer "In11.Cu")
		(net "P5E_CPU0_P3_TX_DP<4>")
	)
	(segment
		(start 364.399576 -293.18458)
		(end 364.400338 -293.185088)
		(width 0.1143)
		(layer "In11.Cu")
		(net "P5E_CPU0_P3_TX_DP<4>")
	)
	(segment
		(start 364.901734 -280.078688)
		(end 364.863126 -280.101294)
		(width 0.1143)
		(layer "In11.Cu")
		(net "P5E_CPU0_P3_TX_DP<4>")
	)
	(segment
		(start 364.431834 -288.34334)
		(end 364.43285 -288.343848)
		(width 0.1143)
		(layer "In11.Cu")
		(net "P5E_CPU0_P3_TX_DP<4>")
	)
	(segment
		(start 364.432342 -286.723328)
		(end 364.461044 -286.740092)
		(width 0.1143)
		(layer "In11.Cu")
		(net "P5E_CPU0_P3_TX_DP<4>")
	)
	(segment
		(start 364.392718 -293.180516)
		(end 364.399576 -293.18458)
		(width 0.1143)
		(layer "In11.Cu")
		(net "P5E_CPU0_P3_TX_DP<4>")
	)
	(segment
		(start 384.497326 -351.938844)
		(end 381.631952 -359.946702)
		(width 0.14224)
		(layer "In11.Cu")
		(net "P5E_CPU0_P3_TX_DP<4>")
	)
	(segment
		(start 364.431834 -289.963352)
		(end 364.431834 -289.963098)
		(width 0.1143)
		(layer "In11.Cu")
		(net "P5E_CPU0_P3_TX_DP<4>")
	)
	(segment
		(start 364.591854 -287.163764)
		(end 364.591854 -287.164272)
		(width 0.1143)
		(layer "In11.Cu")
		(net "P5E_CPU0_P3_TX_DP<4>")
	)
	(arc
		(start 364.43285 -288.343848)
		(mid 364.618302 -288.66581)
		(end 364.433104 -288.987992)
		(width 0.1143)
		(layer "In11.Cu")
		(net "P5E_CPU0_P3_TX_DP<4>")
	)
	(arc
		(start 371.511322 -381.987298)
		(mid 371.499045 -382.049021)
		(end 371.464078 -382.101344)
		(width 0.14224)
		(layer "In11.Cu")
		(net "P5E_CPU0_P3_TX_DP<4>")
	)
	(arc
		(start 364.863126 -280.101294)
		(mid 364.684196 -280.302178)
		(end 364.61954 -280.56332)
		(width 0.1143)
		(layer "In11.Cu")
		(net "P5E_CPU0_P3_TX_DP<4>")
	)
	(arc
		(start 364.461044 -286.740092)
		(mid 364.462953 -286.741483)
		(end 364.464854 -286.742886)
		(width 0.1143)
		(layer "In11.Cu")
		(net "P5E_CPU0_P3_TX_DP<4>")
	)
	(arc
		(start 364.4519 -294.836342)
		(mid 364.574918 -294.969928)
		(end 364.61954 -295.145968)
		(width 0.1143)
		(layer "In11.Cu")
		(net "P5E_CPU0_P3_TX_DP<4>")
	)
	(arc
		(start 364.61954 -295.145968)
		(mid 364.684262 -295.408707)
		(end 364.863634 -295.611296)
		(width 0.1143)
		(layer "In11.Cu")
		(net "P5E_CPU0_P3_TX_DP<4>")
	)
	(arc
		(start 364.392718 -292.251384)
		(mid 364.149391 -292.71595)
		(end 364.392718 -293.180516)
		(width 0.1143)
		(layer "In11.Cu")
		(net "P5E_CPU0_P3_TX_DP<4>")
	)
	(arc
		(start 364.392718 -285.77159)
		(mid 364.149391 -286.236156)
		(end 364.392718 -286.700722)
		(width 0.1143)
		(layer "In11.Cu")
		(net "P5E_CPU0_P3_TX_DP<4>")
	)
	(arc
		(start 373.700802 -371.6147)
		(mid 372.076295 -374.364264)
		(end 371.511322 -377.5075)
		(width 0.14224)
		(layer "In11.Cu")
		(net "P5E_CPU0_P3_TX_DP<4>")
	)
	(arc
		(start 364.618016 -287.01238)
		(mid 364.618253 -287.031008)
		(end 364.61573 -287.049464)
		(width 0.1143)
		(layer "In11.Cu")
		(net "P5E_CPU0_P3_TX_DP<4>")
	)
	(arc
		(start 364.411768 -282.52039)
		(mid 364.138695 -282.995565)
		(end 364.410752 -283.471366)
		(width 0.1143)
		(layer "In11.Cu")
		(net "P5E_CPU0_P3_TX_DP<4>")
	)
	(arc
		(start 364.463584 -285.121858)
		(mid 364.613969 -285.42615)
		(end 364.463584 -285.730442)
		(width 0.1143)
		(layer "In11.Cu")
		(net "P5E_CPU0_P3_TX_DP<4>")
	)
	(arc
		(start 365.082582 -279.825958)
		(mid 365.030533 -279.957477)
		(end 364.933484 -280.0604)
		(width 0.1143)
		(layer "In11.Cu")
		(net "P5E_CPU0_P3_TX_DP<4>")
	)
	(arc
		(start 381.631952 -359.946702)
		(mid 379.764038 -363.96032)
		(end 377.193302 -367.564416)
		(width 0.14224)
		(layer "In11.Cu")
		(net "P5E_CPU0_P3_TX_DP<4>")
	)
	(arc
		(start 364.933484 -295.651682)
		(mid 364.982416 -295.69377)
		(end 365.0234 -295.74363)
		(width 0.1143)
		(layer "In11.Cu")
		(net "P5E_CPU0_P3_TX_DP<4>")
	)
	(arc
		(start 364.61954 -280.566114)
		(mid 364.578285 -280.737085)
		(end 364.463584 -280.870406)
		(width 0.1143)
		(layer "In11.Cu")
		(net "P5E_CPU0_P3_TX_DP<4>")
	)
	(arc
		(start 364.432342 -293.203376)
		(mid 364.61798 -293.525956)
		(end 364.432342 -293.848536)
		(width 0.1143)
		(layer "In11.Cu")
		(net "P5E_CPU0_P3_TX_DP<4>")
	)
	(arc
		(start 364.591854 -287.164272)
		(mid 364.578162 -287.204695)
		(end 364.555278 -287.240726)
		(width 0.1143)
		(layer "In11.Cu")
		(net "P5E_CPU0_P3_TX_DP<4>")
	)
	(arc
		(start 364.465362 -286.74314)
		(mid 364.570819 -286.861245)
		(end 364.618016 -287.01238)
		(width 0.1143)
		(layer "In11.Cu")
		(net "P5E_CPU0_P3_TX_DP<4>")
	)
	(arc
		(start 364.392718 -289.01136)
		(mid 364.149391 -289.475926)
		(end 364.392718 -289.940492)
		(width 0.1143)
		(layer "In11.Cu")
		(net "P5E_CPU0_P3_TX_DP<4>")
	)
	(arc
		(start 364.395258 -287.389824)
		(mid 364.14937 -287.854618)
		(end 364.392718 -288.320734)
		(width 0.1143)
		(layer "In11.Cu")
		(net "P5E_CPU0_P3_TX_DP<4>")
	)
	(arc
		(start 385.13131 -348.284292)
		(mid 384.97169 -350.13887)
		(end 384.497326 -351.938844)
		(width 0.14224)
		(layer "In11.Cu")
		(net "P5E_CPU0_P3_TX_DP<4>")
	)
	(arc
		(start 364.428532 -284.13075)
		(mid 364.149768 -284.615468)
		(end 364.427262 -285.10103)
		(width 0.1143)
		(layer "In11.Cu")
		(net "P5E_CPU0_P3_TX_DP<4>")
	)
	(arc
		(start 364.428024 -293.850822)
		(mid 364.14948 -294.334655)
		(end 364.425738 -294.819832)
		(width 0.1143)
		(layer "In11.Cu")
		(net "P5E_CPU0_P3_TX_DP<4>")
	)
	(arc
		(start 364.488476 -287.32353)
		(mid 364.459654 -287.352135)
		(end 364.425484 -287.374076)
		(width 0.1143)
		(layer "In11.Cu")
		(net "P5E_CPU0_P3_TX_DP<4>")
	)
	(arc
		(start 364.392718 -280.911554)
		(mid 364.149391 -281.37612)
		(end 364.392718 -281.840686)
		(width 0.1143)
		(layer "In11.Cu")
		(net "P5E_CPU0_P3_TX_DP<4>")
	)
	(arc
		(start 364.432342 -291.583364)
		(mid 364.61798 -291.905944)
		(end 364.432342 -292.228524)
		(width 0.1143)
		(layer "In11.Cu")
		(net "P5E_CPU0_P3_TX_DP<4>")
	)
	(arc
		(start 364.450376 -283.494226)
		(mid 364.62995 -283.806028)
		(end 364.45063 -284.11805)
		(width 0.1143)
		(layer "In11.Cu")
		(net "P5E_CPU0_P3_TX_DP<4>")
	)
	(arc
		(start 364.432342 -289.963352)
		(mid 364.61798 -290.285932)
		(end 364.432342 -290.608512)
		(width 0.1143)
		(layer "In11.Cu")
		(net "P5E_CPU0_P3_TX_DP<4>")
	)
	(arc
		(start 365.0234 -295.74363)
		(mid 365.07272 -295.844759)
		(end 365.089694 -295.955974)
		(width 0.1143)
		(layer "In11.Cu")
		(net "P5E_CPU0_P3_TX_DP<4>")
	)
	(arc
		(start 364.392718 -290.631372)
		(mid 364.149391 -291.095938)
		(end 364.392718 -291.560504)
		(width 0.1143)
		(layer "In11.Cu")
		(net "P5E_CPU0_P3_TX_DP<4>")
	)
	(arc
		(start 364.435136 -281.865324)
		(mid 364.619869 -282.186016)
		(end 364.43539 -282.506928)
		(width 0.1143)
		(layer "In11.Cu")
		(net "P5E_CPU0_P3_TX_DP<4>")
	)
	(segment
		(start 378.891292 -382.34493)
		(end 378.620782 -382.61544)
		(width 0.12954)
		(layer "F.Cu")
		(net "P5E_CPU0_P3_TX_DN<7>")
	)
	(segment
		(start 378.620782 -383.31902)
		(end 378.916692 -383.61493)
		(width 0.12954)
		(layer "F.Cu")
		(net "P5E_CPU0_P3_TX_DN<7>")
	)
	(segment
		(start 378.620782 -382.61544)
		(end 378.620782 -383.31902)
		(width 0.12954)
		(layer "F.Cu")
		(net "P5E_CPU0_P3_TX_DN<7>")
	)
	(segment
		(start 368.0079 -274.630134)
		(end 368.474752 -274.896072)
		(width 0.12954)
		(layer "F.Cu")
		(net "P5E_CPU0_P3_TX_DN<7>")
	)
	(segment
		(start 367.354866 -293.042594)
		(end 367.35639 -293.04361)
		(width 0.1143)
		(layer "In11.Cu")
		(net "P5E_CPU0_P3_TX_DN<7>")
	)
	(segment
		(start 367.347246 -286.558736)
		(end 367.347754 -286.55899)
		(width 0.1143)
		(layer "In11.Cu")
		(net "P5E_CPU0_P3_TX_DN<7>")
	)
	(segment
		(start 366.88776 -276.998176)
		(end 366.846104 -277.021798)
		(width 0.1143)
		(layer "In11.Cu")
		(net "P5E_CPU0_P3_TX_DN<7>")
	)
	(segment
		(start 367.341912 -278.45512)
		(end 367.343182 -278.455882)
		(width 0.1143)
		(layer "In11.Cu")
		(net "P5E_CPU0_P3_TX_DN<7>")
	)
	(segment
		(start 367.34496 -289.15487)
		(end 367.342928 -289.15614)
		(width 0.1143)
		(layer "In11.Cu")
		(net "P5E_CPU0_P3_TX_DN<7>")
	)
	(segment
		(start 367.318036 -288.16173)
		(end 367.347246 -288.178748)
		(width 0.1143)
		(layer "In11.Cu")
		(net "P5E_CPU0_P3_TX_DN<7>")
	)
	(segment
		(start 366.915954 -276.981412)
		(end 366.89284 -276.994874)
		(width 0.1143)
		(layer "In11.Cu")
		(net "P5E_CPU0_P3_TX_DN<7>")
	)
	(segment
		(start 367.336324 -278.452072)
		(end 367.338864 -278.453596)
		(width 0.1143)
		(layer "In11.Cu")
		(net "P5E_CPU0_P3_TX_DN<7>")
	)
	(segment
		(start 368.100102 -296.538142)
		(end 368.145822 -296.583862)
		(width 0.1143)
		(layer "In11.Cu")
		(net "P5E_CPU0_P3_TX_DN<7>")
	)
	(segment
		(start 367.34877 -289.799014)
		(end 367.350294 -289.80003)
		(width 0.1143)
		(layer "In11.Cu")
		(net "P5E_CPU0_P3_TX_DN<7>")
	)
	(segment
		(start 378.215398 -312.087514)
		(end 383.203196 -319.552574)
		(width 0.14224)
		(layer "In11.Cu")
		(net "P5E_CPU0_P3_TX_DN<7>")
	)
	(segment
		(start 367.347754 -286.55899)
		(end 367.388902 -286.582866)
		(width 0.1143)
		(layer "In11.Cu")
		(net "P5E_CPU0_P3_TX_DN<7>")
	)
	(segment
		(start 367.85677 -275.360638)
		(end 367.786158 -275.40204)
		(width 0.1143)
		(layer "In11.Cu")
		(net "P5E_CPU0_P3_TX_DN<7>")
	)
	(segment
		(start 366.877854 -277.64867)
		(end 366.88014 -277.64994)
		(width 0.1143)
		(layer "In11.Cu")
		(net "P5E_CPU0_P3_TX_DN<7>")
	)
	(segment
		(start 378.600462 -382.0541)
		(end 378.891292 -382.34493)
		(width 0.14224)
		(layer "In11.Cu")
		(net "P5E_CPU0_P3_TX_DN<7>")
	)
	(segment
		(start 388.336536 -340.781386)
		(end 388.336536 -348.390972)
		(width 0.14224)
		(layer "In11.Cu")
		(net "P5E_CPU0_P3_TX_DN<7>")
	)
	(segment
		(start 368.474752 -274.896072)
		(end 368.17681 -274.896072)
		(width 0.1143)
		(layer "In11.Cu")
		(net "P5E_CPU0_P3_TX_DN<7>")
	)
	(segment
		(start 367.366042 -288.189162)
		(end 367.38687 -288.201354)
		(width 0.1143)
		(layer "In11.Cu")
		(net "P5E_CPU0_P3_TX_DN<7>")
	)
	(segment
		(start 366.877092 -277.648162)
		(end 366.877854 -277.64867)
		(width 0.1143)
		(layer "In11.Cu")
		(net "P5E_CPU0_P3_TX_DN<7>")
	)
	(segment
		(start 384.955288 -323.780658)
		(end 388.336536 -340.781386)
		(width 0.14224)
		(layer "In11.Cu")
		(net "P5E_CPU0_P3_TX_DN<7>")
	)
	(segment
		(start 367.348516 -278.45893)
		(end 367.351056 -278.460454)
		(width 0.1143)
		(layer "In11.Cu")
		(net "P5E_CPU0_P3_TX_DN<7>")
	)
	(segment
		(start 367.345468 -285.914592)
		(end 367.343944 -285.915608)
		(width 0.1143)
		(layer "In11.Cu")
		(net "P5E_CPU0_P3_TX_DN<7>")
	)
	(segment
		(start 367.786158 -295.45026)
		(end 367.787428 -295.451022)
		(width 0.1143)
		(layer "In11.Cu")
		(net "P5E_CPU0_P3_TX_DN<7>")
	)
	(segment
		(start 367.347246 -291.418518)
		(end 367.347754 -291.418518)
		(width 0.1143)
		(layer "In11.Cu")
		(net "P5E_CPU0_P3_TX_DN<7>")
	)
	(segment
		(start 366.89284 -276.995128)
		(end 366.88776 -276.998176)
		(width 0.1143)
		(layer "In11.Cu")
		(net "P5E_CPU0_P3_TX_DN<7>")
	)
	(segment
		(start 367.318036 -284.921452)
		(end 367.370106 -284.951932)
		(width 0.1143)
		(layer "In11.Cu")
		(net "P5E_CPU0_P3_TX_DN<7>")
	)
	(segment
		(start 367.316004 -278.440388)
		(end 367.33353 -278.450548)
		(width 0.1143)
		(layer "In11.Cu")
		(net "P5E_CPU0_P3_TX_DN<7>")
	)
	(segment
		(start 387.59765 -353.593146)
		(end 385.882896 -359.507282)
		(width 0.14224)
		(layer "In11.Cu")
		(net "P5E_CPU0_P3_TX_DN<7>")
	)
	(segment
		(start 367.342674 -289.795712)
		(end 367.347754 -289.798506)
		(width 0.1143)
		(layer "In11.Cu")
		(net "P5E_CPU0_P3_TX_DN<7>")
	)
	(segment
		(start 367.38687 -293.990522)
		(end 367.329974 -294.023542)
		(width 0.1143)
		(layer "In11.Cu")
		(net "P5E_CPU0_P3_TX_DN<7>")
	)
	(segment
		(start 367.33988 -293.033958)
		(end 367.354866 -293.042594)
		(width 0.1143)
		(layer "In11.Cu")
		(net "P5E_CPU0_P3_TX_DN<7>")
	)
	(segment
		(start 384.852164 -362.761784)
		(end 382.535938 -367.907062)
		(width 0.14224)
		(layer "In11.Cu")
		(net "P5E_CPU0_P3_TX_DN<7>")
	)
	(segment
		(start 367.351056 -278.460454)
		(end 367.35258 -278.46147)
		(width 0.1143)
		(layer "In11.Cu")
		(net "P5E_CPU0_P3_TX_DN<7>")
	)
	(segment
		(start 367.338864 -278.453596)
		(end 367.339626 -278.454104)
		(width 0.1143)
		(layer "In11.Cu")
		(net "P5E_CPU0_P3_TX_DN<7>")
	)
	(segment
		(start 367.38687 -289.130486)
		(end 367.34496 -289.15487)
		(width 0.1143)
		(layer "In11.Cu")
		(net "P5E_CPU0_P3_TX_DN<7>")
	)
	(segment
		(start 367.347754 -289.798506)
		(end 367.34877 -289.799014)
		(width 0.1143)
		(layer "In11.Cu")
		(net "P5E_CPU0_P3_TX_DN<7>")
	)
	(segment
		(start 367.334292 -278.451056)
		(end 367.336324 -278.452072)
		(width 0.1143)
		(layer "In11.Cu")
		(net "P5E_CPU0_P3_TX_DN<7>")
	)
	(segment
		(start 367.347754 -288.178494)
		(end 367.366042 -288.189162)
		(width 0.1143)
		(layer "In11.Cu")
		(net "P5E_CPU0_P3_TX_DN<7>")
	)
	(segment
		(start 367.343182 -278.455882)
		(end 367.343944 -278.45639)
		(width 0.1143)
		(layer "In11.Cu")
		(net "P5E_CPU0_P3_TX_DN<7>")
	)
	(segment
		(start 367.34877 -291.419026)
		(end 367.350294 -291.420042)
		(width 0.1143)
		(layer "In11.Cu")
		(net "P5E_CPU0_P3_TX_DN<7>")
	)
	(segment
		(start 366.89284 -276.994874)
		(end 366.89284 -276.995128)
		(width 0.1143)
		(layer "In11.Cu")
		(net "P5E_CPU0_P3_TX_DN<7>")
	)
	(segment
		(start 367.85677 -280.220674)
		(end 367.786158 -280.262076)
		(width 0.1143)
		(layer "In11.Cu")
		(net "P5E_CPU0_P3_TX_DN<7>")
	)
	(segment
		(start 367.33353 -278.450548)
		(end 367.334292 -278.451056)
		(width 0.1143)
		(layer "In11.Cu")
		(net "P5E_CPU0_P3_TX_DN<7>")
	)
	(segment
		(start 367.347754 -291.418518)
		(end 367.34877 -291.419026)
		(width 0.1143)
		(layer "In11.Cu")
		(net "P5E_CPU0_P3_TX_DN<7>")
	)
	(segment
		(start 371.422422 -303.810416)
		(end 378.215398 -312.087514)
		(width 0.14224)
		(layer "In11.Cu")
		(net "P5E_CPU0_P3_TX_DN<7>")
	)
	(segment
		(start 368.145822 -297.109388)
		(end 369.144042 -300.400466)
		(width 0.14224)
		(layer "In11.Cu")
		(net "P5E_CPU0_P3_TX_DN<7>")
	)
	(segment
		(start 368.145822 -296.583862)
		(end 368.145822 -296.61231)
		(width 0.1143)
		(layer "In11.Cu")
		(net "P5E_CPU0_P3_TX_DN<7>")
	)
	(segment
		(start 367.38687 -290.750498)
		(end 367.347246 -290.773612)
		(width 0.1143)
		(layer "In11.Cu")
		(net "P5E_CPU0_P3_TX_DN<7>")
	)
	(segment
		(start 367.817654 -279.268682)
		(end 367.85677 -279.291542)
		(width 0.1143)
		(layer "In11.Cu")
		(net "P5E_CPU0_P3_TX_DN<7>")
	)
	(segment
		(start 367.343944 -278.45639)
		(end 367.345976 -278.457406)
		(width 0.1143)
		(layer "In11.Cu")
		(net "P5E_CPU0_P3_TX_DN<7>")
	)
	(segment
		(start 367.371376 -276.180296)
		(end 367.37036 -276.181058)
		(width 0.1143)
		(layer "In11.Cu")
		(net "P5E_CPU0_P3_TX_DN<7>")
	)
	(segment
		(start 367.347246 -288.178748)
		(end 367.347754 -288.178494)
		(width 0.1143)
		(layer "In11.Cu")
		(net "P5E_CPU0_P3_TX_DN<7>")
	)
	(segment
		(start 368.145822 -296.61231)
		(end 368.145822 -297.109388)
		(width 0.14224)
		(layer "In11.Cu")
		(net "P5E_CPU0_P3_TX_DN<7>")
	)
	(segment
		(start 367.350548 -281.051762)
		(end 367.346738 -281.054048)
		(width 0.1143)
		(layer "In11.Cu")
		(net "P5E_CPU0_P3_TX_DN<7>")
	)
	(segment
		(start 368.17681 -274.896072)
		(end 368.094006 -274.978876)
		(width 0.1143)
		(layer "In11.Cu")
		(net "P5E_CPU0_P3_TX_DN<7>")
	)
	(segment
		(start 369.144042 -300.400466)
		(end 371.422422 -303.810416)
		(width 0.14224)
		(layer "In11.Cu")
		(net "P5E_CPU0_P3_TX_DN<7>")
	)
	(segment
		(start 367.346738 -281.054048)
		(end 367.346484 -281.054048)
		(width 0.1143)
		(layer "In11.Cu")
		(net "P5E_CPU0_P3_TX_DN<7>")
	)
	(segment
		(start 379.061472 -374.75287)
		(end 378.6251 -375.804684)
		(width 0.14224)
		(layer "In11.Cu")
		(net "P5E_CPU0_P3_TX_DN<7>")
	)
	(segment
		(start 367.37036 -276.181058)
		(end 367.344198 -276.19706)
		(width 0.1143)
		(layer "In11.Cu")
		(net "P5E_CPU0_P3_TX_DN<7>")
	)
	(segment
		(start 367.35258 -278.46147)
		(end 367.38687 -278.481536)
		(width 0.1143)
		(layer "In11.Cu")
		(net "P5E_CPU0_P3_TX_DN<7>")
	)
	(segment
		(start 367.339626 -278.454104)
		(end 367.341912 -278.45512)
		(width 0.1143)
		(layer "In11.Cu")
		(net "P5E_CPU0_P3_TX_DN<7>")
	)
	(segment
		(start 367.35639 -293.04361)
		(end 367.386108 -293.060882)
		(width 0.1143)
		(layer "In11.Cu")
		(net "P5E_CPU0_P3_TX_DN<7>")
	)
	(segment
		(start 367.32972 -294.648382)
		(end 367.386108 -294.680894)
		(width 0.1143)
		(layer "In11.Cu")
		(net "P5E_CPU0_P3_TX_DN<7>")
	)
	(segment
		(start 366.846104 -277.630382)
		(end 366.877092 -277.648162)
		(width 0.1143)
		(layer "In11.Cu")
		(net "P5E_CPU0_P3_TX_DN<7>")
	)
	(segment
		(start 367.345976 -278.457406)
		(end 367.3475 -278.458422)
		(width 0.1143)
		(layer "In11.Cu")
		(net "P5E_CPU0_P3_TX_DN<7>")
	)
	(segment
		(start 367.317782 -281.681428)
		(end 367.386362 -281.721052)
		(width 0.1143)
		(layer "In11.Cu")
		(net "P5E_CPU0_P3_TX_DN<7>")
	)
	(segment
		(start 367.368836 -285.90113)
		(end 367.345468 -285.914592)
		(width 0.1143)
		(layer "In11.Cu")
		(net "P5E_CPU0_P3_TX_DN<7>")
	)
	(segment
		(start 368.100102 -295.99255)
		(end 368.100102 -296.538142)
		(width 0.1143)
		(layer "In11.Cu")
		(net "P5E_CPU0_P3_TX_DN<7>")
	)
	(segment
		(start 367.38687 -292.37051)
		(end 367.34877 -292.392862)
		(width 0.1143)
		(layer "In11.Cu")
		(net "P5E_CPU0_P3_TX_DN<7>")
	)
	(segment
		(start 367.34369 -286.556704)
		(end 367.345976 -286.557974)
		(width 0.1143)
		(layer "In11.Cu")
		(net "P5E_CPU0_P3_TX_DN<7>")
	)
	(segment
		(start 367.350294 -291.420042)
		(end 367.38687 -291.441378)
		(width 0.1143)
		(layer "In11.Cu")
		(net "P5E_CPU0_P3_TX_DN<7>")
	)
	(segment
		(start 367.317782 -283.30144)
		(end 367.386362 -283.341064)
		(width 0.1143)
		(layer "In11.Cu")
		(net "P5E_CPU0_P3_TX_DN<7>")
	)
	(segment
		(start 367.34877 -292.392862)
		(end 367.347246 -292.393624)
		(width 0.1143)
		(layer "In11.Cu")
		(net "P5E_CPU0_P3_TX_DN<7>")
	)
	(segment
		(start 383.203196 -319.552574)
		(end 384.955288 -323.780658)
		(width 0.14224)
		(layer "In11.Cu")
		(net "P5E_CPU0_P3_TX_DN<7>")
	)
	(segment
		(start 367.350802 -287.529016)
		(end 367.346738 -287.531556)
		(width 0.1143)
		(layer "In11.Cu")
		(net "P5E_CPU0_P3_TX_DN<7>")
	)
	(segment
		(start 385.194556 -361.7468)
		(end 384.908552 -362.616242)
		(width 0.14224)
		(layer "In11.Cu")
		(net "P5E_CPU0_P3_TX_DN<7>")
	)
	(segment
		(start 378.600462 -375.927874)
		(end 378.600462 -382.0541)
		(width 0.14224)
		(layer "In11.Cu")
		(net "P5E_CPU0_P3_TX_DN<7>")
	)
	(segment
		(start 367.350294 -289.80003)
		(end 367.38687 -289.821366)
		(width 0.1143)
		(layer "In11.Cu")
		(net "P5E_CPU0_P3_TX_DN<7>")
	)
	(segment
		(start 367.345976 -286.557974)
		(end 367.347246 -286.558736)
		(width 0.1143)
		(layer "In11.Cu")
		(net "P5E_CPU0_P3_TX_DN<7>")
	)
	(segment
		(start 367.3475 -278.458422)
		(end 367.348516 -278.45893)
		(width 0.1143)
		(layer "In11.Cu")
		(net "P5E_CPU0_P3_TX_DN<7>")
	)
	(segment
		(start 367.787174 -279.250902)
		(end 367.817654 -279.268682)
		(width 0.1143)
		(layer "In11.Cu")
		(net "P5E_CPU0_P3_TX_DN<7>")
	)
	(arc
		(start 367.386362 -281.721052)
		(mid 367.628401 -282.209631)
		(end 367.342674 -282.67406)
		(width 0.1143)
		(layer "In11.Cu")
		(net "P5E_CPU0_P3_TX_DN<7>")
	)
	(arc
		(start 367.85677 -279.291542)
		(mid 368.100097 -279.756108)
		(end 367.85677 -280.220674)
		(width 0.1143)
		(layer "In11.Cu")
		(net "P5E_CPU0_P3_TX_DN<7>")
	)
	(arc
		(start 367.346738 -287.531556)
		(mid 367.21008 -287.668958)
		(end 367.160048 -287.856168)
		(width 0.1143)
		(layer "In11.Cu")
		(net "P5E_CPU0_P3_TX_DN<7>")
	)
	(arc
		(start 367.343944 -285.915608)
		(mid 367.160187 -286.236046)
		(end 367.34369 -286.556704)
		(width 0.1143)
		(layer "In11.Cu")
		(net "P5E_CPU0_P3_TX_DN<7>")
	)
	(arc
		(start 367.347246 -292.393624)
		(mid 367.161726 -292.711681)
		(end 367.33988 -293.033958)
		(width 0.1143)
		(layer "In11.Cu")
		(net "P5E_CPU0_P3_TX_DN<7>")
	)
	(arc
		(start 367.342928 -289.15614)
		(mid 367.160079 -289.475817)
		(end 367.342674 -289.795712)
		(width 0.1143)
		(layer "In11.Cu")
		(net "P5E_CPU0_P3_TX_DN<7>")
	)
	(arc
		(start 368.090196 -275.001736)
		(mid 368.008763 -275.204134)
		(end 367.85677 -275.360638)
		(width 0.1143)
		(layer "In11.Cu")
		(net "P5E_CPU0_P3_TX_DN<7>")
	)
	(arc
		(start 367.38687 -293.06139)
		(mid 367.630197 -293.525956)
		(end 367.38687 -293.990522)
		(width 0.1143)
		(layer "In11.Cu")
		(net "P5E_CPU0_P3_TX_DN<7>")
	)
	(arc
		(start 367.329974 -294.023542)
		(mid 367.150087 -294.335852)
		(end 367.32972 -294.648382)
		(width 0.1143)
		(layer "In11.Cu")
		(net "P5E_CPU0_P3_TX_DN<7>")
	)
	(arc
		(start 367.160048 -278.136096)
		(mid 367.201303 -278.307067)
		(end 367.316004 -278.440388)
		(width 0.1143)
		(layer "In11.Cu")
		(net "P5E_CPU0_P3_TX_DN<7>")
	)
	(arc
		(start 385.882896 -359.507282)
		(mid 385.547665 -360.629788)
		(end 385.194556 -361.7468)
		(width 0.14224)
		(layer "In11.Cu")
		(net "P5E_CPU0_P3_TX_DN<7>")
	)
	(arc
		(start 367.38687 -288.201354)
		(mid 367.630197 -288.66592)
		(end 367.38687 -289.130486)
		(width 0.1143)
		(layer "In11.Cu")
		(net "P5E_CPU0_P3_TX_DN<7>")
	)
	(arc
		(start 367.38687 -278.481536)
		(mid 367.565683 -278.683886)
		(end 367.630202 -278.946102)
		(width 0.1143)
		(layer "In11.Cu")
		(net "P5E_CPU0_P3_TX_DN<7>")
	)
	(arc
		(start 388.336536 -348.390972)
		(mid 388.150916 -351.018169)
		(end 387.59765 -353.593146)
		(width 0.14224)
		(layer "In11.Cu")
		(net "P5E_CPU0_P3_TX_DN<7>")
	)
	(arc
		(start 367.38687 -289.821366)
		(mid 367.630197 -290.285932)
		(end 367.38687 -290.750498)
		(width 0.1143)
		(layer "In11.Cu")
		(net "P5E_CPU0_P3_TX_DN<7>")
	)
	(arc
		(start 367.38687 -291.441378)
		(mid 367.630197 -291.905944)
		(end 367.38687 -292.37051)
		(width 0.1143)
		(layer "In11.Cu")
		(net "P5E_CPU0_P3_TX_DN<7>")
	)
	(arc
		(start 367.386362 -283.341064)
		(mid 367.628401 -283.829643)
		(end 367.342674 -284.294072)
		(width 0.1143)
		(layer "In11.Cu")
		(net "P5E_CPU0_P3_TX_DN<7>")
	)
	(arc
		(start 367.346484 -281.054048)
		(mid 367.161141 -281.359869)
		(end 367.317782 -281.681428)
		(width 0.1143)
		(layer "In11.Cu")
		(net "P5E_CPU0_P3_TX_DN<7>")
	)
	(arc
		(start 384.908552 -362.616242)
		(mid 384.882276 -362.689756)
		(end 384.852164 -362.761784)
		(width 0.14224)
		(layer "In11.Cu")
		(net "P5E_CPU0_P3_TX_DN<7>")
	)
	(arc
		(start 367.786158 -275.40204)
		(mid 367.671315 -275.535188)
		(end 367.629948 -275.706078)
		(width 0.1143)
		(layer "In11.Cu")
		(net "P5E_CPU0_P3_TX_DN<7>")
	)
	(arc
		(start 367.344198 -276.19706)
		(mid 367.209521 -276.331965)
		(end 367.160048 -276.516084)
		(width 0.1143)
		(layer "In11.Cu")
		(net "P5E_CPU0_P3_TX_DN<7>")
	)
	(arc
		(start 378.6251 -375.804684)
		(mid 378.606721 -375.865066)
		(end 378.600462 -375.927874)
		(width 0.14224)
		(layer "In11.Cu")
		(net "P5E_CPU0_P3_TX_DN<7>")
	)
	(arc
		(start 367.388902 -286.582866)
		(mid 367.566098 -286.784878)
		(end 367.629948 -287.045908)
		(width 0.1143)
		(layer "In11.Cu")
		(net "P5E_CPU0_P3_TX_DN<7>")
	)
	(arc
		(start 367.629948 -287.045908)
		(mid 367.555137 -287.324875)
		(end 367.350802 -287.529016)
		(width 0.1143)
		(layer "In11.Cu")
		(net "P5E_CPU0_P3_TX_DN<7>")
	)
	(arc
		(start 367.342674 -284.294072)
		(mid 367.160359 -284.601128)
		(end 367.318036 -284.921452)
		(width 0.1143)
		(layer "In11.Cu")
		(net "P5E_CPU0_P3_TX_DN<7>")
	)
	(arc
		(start 367.370106 -284.951932)
		(mid 367.642493 -285.42689)
		(end 367.368836 -285.90113)
		(width 0.1143)
		(layer "In11.Cu")
		(net "P5E_CPU0_P3_TX_DN<7>")
	)
	(arc
		(start 367.629948 -275.706078)
		(mid 367.561157 -275.976169)
		(end 367.371376 -276.180296)
		(width 0.1143)
		(layer "In11.Cu")
		(net "P5E_CPU0_P3_TX_DN<7>")
	)
	(arc
		(start 380.980188 -370.909596)
		(mid 379.953724 -372.797731)
		(end 379.061472 -374.75287)
		(width 0.14224)
		(layer "In11.Cu")
		(net "P5E_CPU0_P3_TX_DN<7>")
	)
	(arc
		(start 367.160048 -287.856168)
		(mid 367.201888 -288.028154)
		(end 367.318036 -288.16173)
		(width 0.1143)
		(layer "In11.Cu")
		(net "P5E_CPU0_P3_TX_DN<7>")
	)
	(arc
		(start 367.786158 -280.262076)
		(mid 367.671315 -280.395224)
		(end 367.629948 -280.566114)
		(width 0.1143)
		(layer "In11.Cu")
		(net "P5E_CPU0_P3_TX_DN<7>")
	)
	(arc
		(start 368.094006 -274.978876)
		(mid 368.092218 -274.990325)
		(end 368.090196 -275.001736)
		(width 0.1143)
		(layer "In11.Cu")
		(net "P5E_CPU0_P3_TX_DN<7>")
	)
	(arc
		(start 367.386108 -293.060882)
		(mid 367.386489 -293.061136)
		(end 367.38687 -293.06139)
		(width 0.1143)
		(layer "In11.Cu")
		(net "P5E_CPU0_P3_TX_DN<7>")
	)
	(arc
		(start 367.787428 -295.451022)
		(mid 368.016297 -295.679901)
		(end 368.100102 -295.99255)
		(width 0.1143)
		(layer "In11.Cu")
		(net "P5E_CPU0_P3_TX_DN<7>")
	)
	(arc
		(start 367.629948 -280.566114)
		(mid 367.55512 -280.846265)
		(end 367.350548 -281.051762)
		(width 0.1143)
		(layer "In11.Cu")
		(net "P5E_CPU0_P3_TX_DN<7>")
	)
	(arc
		(start 367.342674 -282.67406)
		(mid 367.160363 -282.981013)
		(end 367.317782 -283.30144)
		(width 0.1143)
		(layer "In11.Cu")
		(net "P5E_CPU0_P3_TX_DN<7>")
	)
	(arc
		(start 367.160048 -276.516084)
		(mid 367.095326 -276.778823)
		(end 366.915954 -276.981412)
		(width 0.1143)
		(layer "In11.Cu")
		(net "P5E_CPU0_P3_TX_DN<7>")
	)
	(arc
		(start 382.535938 -367.907062)
		(mid 381.799314 -369.429703)
		(end 380.980188 -370.909596)
		(width 0.14224)
		(layer "In11.Cu")
		(net "P5E_CPU0_P3_TX_DN<7>")
	)
	(arc
		(start 367.630202 -295.145968)
		(mid 367.671457 -295.316939)
		(end 367.786158 -295.45026)
		(width 0.1143)
		(layer "In11.Cu")
		(net "P5E_CPU0_P3_TX_DN<7>")
	)
	(arc
		(start 366.846104 -277.021798)
		(mid 366.690176 -277.32609)
		(end 366.846104 -277.630382)
		(width 0.1143)
		(layer "In11.Cu")
		(net "P5E_CPU0_P3_TX_DN<7>")
	)
	(arc
		(start 367.347246 -290.773612)
		(mid 367.161608 -291.096128)
		(end 367.347246 -291.418518)
		(width 0.1143)
		(layer "In11.Cu")
		(net "P5E_CPU0_P3_TX_DN<7>")
	)
	(arc
		(start 367.630202 -278.946102)
		(mid 367.671751 -279.117524)
		(end 367.787174 -279.250902)
		(width 0.1143)
		(layer "In11.Cu")
		(net "P5E_CPU0_P3_TX_DN<7>")
	)
	(arc
		(start 366.88014 -277.64994)
		(mid 367.085085 -277.855602)
		(end 367.160048 -278.136096)
		(width 0.1143)
		(layer "In11.Cu")
		(net "P5E_CPU0_P3_TX_DN<7>")
	)
	(arc
		(start 367.38687 -294.681402)
		(mid 367.565683 -294.883752)
		(end 367.630202 -295.145968)
		(width 0.1143)
		(layer "In11.Cu")
		(net "P5E_CPU0_P3_TX_DN<7>")
	)
	(arc
		(start 367.386108 -294.680894)
		(mid 367.386489 -294.681148)
		(end 367.38687 -294.681402)
		(width 0.1143)
		(layer "In11.Cu")
		(net "P5E_CPU0_P3_TX_DN<7>")
	)
	(segment
		(start 375.217182 -377.68784)
		(end 375.217182 -378.39142)
		(width 0.12954)
		(layer "F.Cu")
		(net "P5E_CPU0_P3_TX_DN<6>")
	)
	(segment
		(start 375.487692 -377.41733)
		(end 375.217182 -377.68784)
		(width 0.12954)
		(layer "F.Cu")
		(net "P5E_CPU0_P3_TX_DN<6>")
	)
	(segment
		(start 365.187992 -276.250146)
		(end 365.654844 -276.516084)
		(width 0.12954)
		(layer "F.Cu")
		(net "P5E_CPU0_P3_TX_DN<6>")
	)
	(segment
		(start 375.217182 -378.39142)
		(end 375.513092 -378.68733)
		(width 0.12954)
		(layer "F.Cu")
		(net "P5E_CPU0_P3_TX_DN<6>")
	)
	(segment
		(start 366.4077 -290.773358)
		(end 366.37722 -290.791138)
		(width 0.1143)
		(layer "In11.Cu")
		(net "P5E_CPU0_P3_TX_DN<6>")
	)
	(segment
		(start 366.446816 -281.03068)
		(end 366.4077 -281.05354)
		(width 0.1143)
		(layer "In11.Cu")
		(net "P5E_CPU0_P3_TX_DN<6>")
	)
	(segment
		(start 366.4077 -294.658542)
		(end 366.446816 -294.681402)
		(width 0.1143)
		(layer "In11.Cu")
		(net "P5E_CPU0_P3_TX_DN<6>")
	)
	(segment
		(start 366.37722 -283.300932)
		(end 366.4077 -283.318712)
		(width 0.1143)
		(layer "In11.Cu")
		(net "P5E_CPU0_P3_TX_DN<6>")
	)
	(segment
		(start 366.870234 -279.264364)
		(end 366.877092 -279.268174)
		(width 0.1143)
		(layer "In11.Cu")
		(net "P5E_CPU0_P3_TX_DN<6>")
	)
	(segment
		(start 366.877854 -280.243534)
		(end 366.877092 -280.244042)
		(width 0.1143)
		(layer "In11.Cu")
		(net "P5E_CPU0_P3_TX_DN<6>")
	)
	(segment
		(start 367.160048 -295.955974)
		(end 367.160048 -296.372788)
		(width 0.1143)
		(layer "In11.Cu")
		(net "P5E_CPU0_P3_TX_DN<6>")
	)
	(segment
		(start 365.903256 -277.62835)
		(end 365.90605 -277.630382)
		(width 0.1143)
		(layer "In11.Cu")
		(net "P5E_CPU0_P3_TX_DN<6>")
	)
	(segment
		(start 366.4077 -291.418518)
		(end 366.446816 -291.441378)
		(width 0.1143)
		(layer "In11.Cu")
		(net "P5E_CPU0_P3_TX_DN<6>")
	)
	(segment
		(start 367.160048 -296.372788)
		(end 367.205768 -296.418508)
		(width 0.1143)
		(layer "In11.Cu")
		(net "P5E_CPU0_P3_TX_DN<6>")
	)
	(segment
		(start 366.4077 -281.05354)
		(end 366.37722 -281.07132)
		(width 0.1143)
		(layer "In11.Cu")
		(net "P5E_CPU0_P3_TX_DN<6>")
	)
	(segment
		(start 365.356902 -276.516084)
		(end 365.287052 -276.585934)
		(width 0.1143)
		(layer "In11.Cu")
		(net "P5E_CPU0_P3_TX_DN<6>")
	)
	(segment
		(start 366.4077 -294.013382)
		(end 366.37722 -294.031162)
		(width 0.1143)
		(layer "In11.Cu")
		(net "P5E_CPU0_P3_TX_DN<6>")
	)
	(segment
		(start 382.305814 -319.889124)
		(end 384.07848 -324.16877)
		(width 0.14224)
		(layer "In11.Cu")
		(net "P5E_CPU0_P3_TX_DN<6>")
	)
	(segment
		(start 366.37722 -284.920944)
		(end 366.4077 -284.938724)
		(width 0.1143)
		(layer "In11.Cu")
		(net "P5E_CPU0_P3_TX_DN<6>")
	)
	(segment
		(start 366.877854 -279.268682)
		(end 366.87887 -279.26919)
		(width 0.1143)
		(layer "In11.Cu")
		(net "P5E_CPU0_P3_TX_DN<6>")
	)
	(segment
		(start 366.37722 -293.02075)
		(end 366.4077 -293.03853)
		(width 0.1143)
		(layer "In11.Cu")
		(net "P5E_CPU0_P3_TX_DN<6>")
	)
	(segment
		(start 366.88141 -279.270714)
		(end 366.91697 -279.291542)
		(width 0.1143)
		(layer "In11.Cu")
		(net "P5E_CPU0_P3_TX_DN<6>")
	)
	(segment
		(start 365.90605 -277.630382)
		(end 365.976916 -277.67153)
		(width 0.1143)
		(layer "In11.Cu")
		(net "P5E_CPU0_P3_TX_DN<6>")
	)
	(segment
		(start 366.4077 -284.293564)
		(end 366.37722 -284.311344)
		(width 0.1143)
		(layer "In11.Cu")
		(net "P5E_CPU0_P3_TX_DN<6>")
	)
	(segment
		(start 368.273838 -300.780704)
		(end 371.38229 -305.432968)
		(width 0.14224)
		(layer "In11.Cu")
		(net "P5E_CPU0_P3_TX_DN<6>")
	)
	(segment
		(start 366.4077 -281.6987)
		(end 366.446816 -281.72156)
		(width 0.1143)
		(layer "In11.Cu")
		(net "P5E_CPU0_P3_TX_DN<6>")
	)
	(segment
		(start 366.875822 -280.244804)
		(end 366.846104 -280.261822)
		(width 0.1143)
		(layer "In11.Cu")
		(net "P5E_CPU0_P3_TX_DN<6>")
	)
	(segment
		(start 380.559056 -369.144804)
		(end 377.608084 -372.895876)
		(width 0.14224)
		(layer "In11.Cu")
		(net "P5E_CPU0_P3_TX_DN<6>")
	)
	(segment
		(start 366.37722 -289.780726)
		(end 366.4077 -289.798506)
		(width 0.1143)
		(layer "In11.Cu")
		(net "P5E_CPU0_P3_TX_DN<6>")
	)
	(segment
		(start 366.4077 -289.153346)
		(end 366.37722 -289.171126)
		(width 0.1143)
		(layer "In11.Cu")
		(net "P5E_CPU0_P3_TX_DN<6>")
	)
	(segment
		(start 366.446816 -284.270704)
		(end 366.4077 -284.293564)
		(width 0.1143)
		(layer "In11.Cu")
		(net "P5E_CPU0_P3_TX_DN<6>")
	)
	(segment
		(start 371.38229 -305.432968)
		(end 378.18314 -313.719972)
		(width 0.14224)
		(layer "In11.Cu")
		(net "P5E_CPU0_P3_TX_DN<6>")
	)
	(segment
		(start 366.91697 -280.220674)
		(end 366.877854 -280.243534)
		(width 0.1143)
		(layer "In11.Cu")
		(net "P5E_CPU0_P3_TX_DN<6>")
	)
	(segment
		(start 366.4077 -286.558482)
		(end 366.446816 -286.581342)
		(width 0.1143)
		(layer "In11.Cu")
		(net "P5E_CPU0_P3_TX_DN<6>")
	)
	(segment
		(start 366.846104 -279.250394)
		(end 366.870234 -279.264364)
		(width 0.1143)
		(layer "In11.Cu")
		(net "P5E_CPU0_P3_TX_DN<6>")
	)
	(segment
		(start 365.43615 -276.820376)
		(end 365.504222 -276.859746)
		(width 0.1143)
		(layer "In11.Cu")
		(net "P5E_CPU0_P3_TX_DN<6>")
	)
	(segment
		(start 366.4077 -285.913576)
		(end 366.37722 -285.931356)
		(width 0.1143)
		(layer "In11.Cu")
		(net "P5E_CPU0_P3_TX_DN<6>")
	)
	(segment
		(start 365.750094 -277.32609)
		(end 365.750094 -277.329138)
		(width 0.1143)
		(layer "In11.Cu")
		(net "P5E_CPU0_P3_TX_DN<6>")
	)
	(segment
		(start 366.846104 -295.45026)
		(end 366.91697 -295.491408)
		(width 0.1143)
		(layer "In11.Cu")
		(net "P5E_CPU0_P3_TX_DN<6>")
	)
	(segment
		(start 366.4077 -292.39337)
		(end 366.37722 -292.41115)
		(width 0.1143)
		(layer "In11.Cu")
		(net "P5E_CPU0_P3_TX_DN<6>")
	)
	(segment
		(start 366.877092 -280.244042)
		(end 366.875822 -280.244804)
		(width 0.1143)
		(layer "In11.Cu")
		(net "P5E_CPU0_P3_TX_DN<6>")
	)
	(segment
		(start 366.37722 -294.640762)
		(end 366.4077 -294.658542)
		(width 0.1143)
		(layer "In11.Cu")
		(net "P5E_CPU0_P3_TX_DN<6>")
	)
	(segment
		(start 366.87887 -279.26919)
		(end 366.880394 -279.270206)
		(width 0.1143)
		(layer "In11.Cu")
		(net "P5E_CPU0_P3_TX_DN<6>")
	)
	(segment
		(start 375.196862 -376.536712)
		(end 375.196862 -377.1265)
		(width 0.14224)
		(layer "In11.Cu")
		(net "P5E_CPU0_P3_TX_DN<6>")
	)
	(segment
		(start 366.877092 -279.268174)
		(end 366.877854 -279.268682)
		(width 0.1143)
		(layer "In11.Cu")
		(net "P5E_CPU0_P3_TX_DN<6>")
	)
	(segment
		(start 366.446816 -293.990522)
		(end 366.4077 -294.013382)
		(width 0.1143)
		(layer "In11.Cu")
		(net "P5E_CPU0_P3_TX_DN<6>")
	)
	(segment
		(start 366.4077 -288.178494)
		(end 366.446816 -288.201354)
		(width 0.1143)
		(layer "In11.Cu")
		(net "P5E_CPU0_P3_TX_DN<6>")
	)
	(segment
		(start 366.446816 -282.650692)
		(end 366.4077 -282.673552)
		(width 0.1143)
		(layer "In11.Cu")
		(net "P5E_CPU0_P3_TX_DN<6>")
	)
	(segment
		(start 367.205768 -296.418508)
		(end 367.205768 -296.446956)
		(width 0.1143)
		(layer "In11.Cu")
		(net "P5E_CPU0_P3_TX_DN<6>")
	)
	(segment
		(start 367.205768 -297.259756)
		(end 368.273838 -300.780704)
		(width 0.14224)
		(layer "In11.Cu")
		(net "P5E_CPU0_P3_TX_DN<6>")
	)
	(segment
		(start 366.446816 -292.37051)
		(end 366.4077 -292.39337)
		(width 0.1143)
		(layer "In11.Cu")
		(net "P5E_CPU0_P3_TX_DN<6>")
	)
	(segment
		(start 378.18314 -313.719972)
		(end 382.305814 -319.889124)
		(width 0.14224)
		(layer "In11.Cu")
		(net "P5E_CPU0_P3_TX_DN<6>")
	)
	(segment
		(start 366.4077 -282.673552)
		(end 366.37722 -282.691332)
		(width 0.1143)
		(layer "In11.Cu")
		(net "P5E_CPU0_P3_TX_DN<6>")
	)
	(segment
		(start 384.07848 -324.16877)
		(end 387.388608 -340.826598)
		(width 0.14224)
		(layer "In11.Cu")
		(net "P5E_CPU0_P3_TX_DN<6>")
	)
	(segment
		(start 366.37722 -281.68092)
		(end 366.4077 -281.6987)
		(width 0.1143)
		(layer "In11.Cu")
		(net "P5E_CPU0_P3_TX_DN<6>")
	)
	(segment
		(start 366.4077 -278.458676)
		(end 366.446816 -278.481536)
		(width 0.1143)
		(layer "In11.Cu")
		(net "P5E_CPU0_P3_TX_DN<6>")
	)
	(segment
		(start 366.4077 -289.798506)
		(end 366.446816 -289.821366)
		(width 0.1143)
		(layer "In11.Cu")
		(net "P5E_CPU0_P3_TX_DN<6>")
	)
	(segment
		(start 366.375188 -288.159698)
		(end 366.4077 -288.178494)
		(width 0.1143)
		(layer "In11.Cu")
		(net "P5E_CPU0_P3_TX_DN<6>")
	)
	(segment
		(start 377.524264 -372.990364)
		(end 376.058684 -374.455944)
		(width 0.14224)
		(layer "In11.Cu")
		(net "P5E_CPU0_P3_TX_DN<6>")
	)
	(segment
		(start 366.37722 -291.400738)
		(end 366.4077 -291.418518)
		(width 0.1143)
		(layer "In11.Cu")
		(net "P5E_CPU0_P3_TX_DN<6>")
	)
	(segment
		(start 366.4077 -293.03853)
		(end 366.446816 -293.06139)
		(width 0.1143)
		(layer "In11.Cu")
		(net "P5E_CPU0_P3_TX_DN<6>")
	)
	(segment
		(start 366.375188 -286.539686)
		(end 366.4077 -286.558482)
		(width 0.1143)
		(layer "In11.Cu")
		(net "P5E_CPU0_P3_TX_DN<6>")
	)
	(segment
		(start 366.4077 -283.318712)
		(end 366.446816 -283.341572)
		(width 0.1143)
		(layer "In11.Cu")
		(net "P5E_CPU0_P3_TX_DN<6>")
	)
	(segment
		(start 375.196862 -377.1265)
		(end 375.487692 -377.41733)
		(width 0.14224)
		(layer "In11.Cu")
		(net "P5E_CPU0_P3_TX_DN<6>")
	)
	(segment
		(start 386.657088 -352.977958)
		(end 384.760724 -359.22966)
		(width 0.14224)
		(layer "In11.Cu")
		(net "P5E_CPU0_P3_TX_DN<6>")
	)
	(segment
		(start 367.205768 -296.446956)
		(end 367.205768 -297.259756)
		(width 0.14224)
		(layer "In11.Cu")
		(net "P5E_CPU0_P3_TX_DN<6>")
	)
	(segment
		(start 366.37722 -278.440896)
		(end 366.4077 -278.458676)
		(width 0.1143)
		(layer "In11.Cu")
		(net "P5E_CPU0_P3_TX_DN<6>")
	)
	(segment
		(start 366.880394 -279.270206)
		(end 366.88141 -279.270714)
		(width 0.1143)
		(layer "In11.Cu")
		(net "P5E_CPU0_P3_TX_DN<6>")
	)
	(segment
		(start 366.4077 -284.938724)
		(end 366.446816 -284.961584)
		(width 0.1143)
		(layer "In11.Cu")
		(net "P5E_CPU0_P3_TX_DN<6>")
	)
	(segment
		(start 366.446816 -285.890716)
		(end 366.4077 -285.913576)
		(width 0.1143)
		(layer "In11.Cu")
		(net "P5E_CPU0_P3_TX_DN<6>")
	)
	(segment
		(start 365.654844 -276.516084)
		(end 365.356902 -276.516084)
		(width 0.1143)
		(layer "In11.Cu")
		(net "P5E_CPU0_P3_TX_DN<6>")
	)
	(segment
		(start 366.446816 -290.750498)
		(end 366.4077 -290.773358)
		(width 0.1143)
		(layer "In11.Cu")
		(net "P5E_CPU0_P3_TX_DN<6>")
	)
	(segment
		(start 366.444276 -287.512252)
		(end 366.37722 -287.551368)
		(width 0.1143)
		(layer "In11.Cu")
		(net "P5E_CPU0_P3_TX_DN<6>")
	)
	(segment
		(start 366.446816 -289.130486)
		(end 366.4077 -289.153346)
		(width 0.1143)
		(layer "In11.Cu")
		(net "P5E_CPU0_P3_TX_DN<6>")
	)
	(segment
		(start 387.401054 -340.952836)
		(end 387.401054 -347.962474)
		(width 0.14224)
		(layer "In11.Cu")
		(net "P5E_CPU0_P3_TX_DN<6>")
	)
	(arc
		(start 366.446816 -283.341572)
		(mid 366.690143 -283.806138)
		(end 366.446816 -284.270704)
		(width 0.1143)
		(layer "In11.Cu")
		(net "P5E_CPU0_P3_TX_DN<6>")
	)
	(arc
		(start 366.37722 -281.07132)
		(mid 366.220243 -281.37612)
		(end 366.37722 -281.68092)
		(width 0.1143)
		(layer "In11.Cu")
		(net "P5E_CPU0_P3_TX_DN<6>")
	)
	(arc
		(start 366.220248 -287.856168)
		(mid 366.261214 -288.026574)
		(end 366.375188 -288.159698)
		(width 0.1143)
		(layer "In11.Cu")
		(net "P5E_CPU0_P3_TX_DN<6>")
	)
	(arc
		(start 366.690148 -278.946102)
		(mid 366.731403 -279.117073)
		(end 366.846104 -279.250394)
		(width 0.1143)
		(layer "In11.Cu")
		(net "P5E_CPU0_P3_TX_DN<6>")
	)
	(arc
		(start 365.504222 -276.859746)
		(mid 365.684874 -277.062491)
		(end 365.750094 -277.32609)
		(width 0.1143)
		(layer "In11.Cu")
		(net "P5E_CPU0_P3_TX_DN<6>")
	)
	(arc
		(start 366.446816 -284.961584)
		(mid 366.690143 -285.42615)
		(end 366.446816 -285.890716)
		(width 0.1143)
		(layer "In11.Cu")
		(net "P5E_CPU0_P3_TX_DN<6>")
	)
	(arc
		(start 366.37722 -287.551368)
		(mid 366.261793 -287.684744)
		(end 366.220248 -287.856168)
		(width 0.1143)
		(layer "In11.Cu")
		(net "P5E_CPU0_P3_TX_DN<6>")
	)
	(arc
		(start 366.690148 -287.045908)
		(mid 366.624912 -287.309499)
		(end 366.444276 -287.512252)
		(width 0.1143)
		(layer "In11.Cu")
		(net "P5E_CPU0_P3_TX_DN<6>")
	)
	(arc
		(start 365.976916 -277.67153)
		(mid 366.155729 -277.87388)
		(end 366.220248 -278.136096)
		(width 0.1143)
		(layer "In11.Cu")
		(net "P5E_CPU0_P3_TX_DN<6>")
	)
	(arc
		(start 387.388608 -340.826598)
		(mid 387.39795 -340.88941)
		(end 387.401054 -340.952836)
		(width 0.14224)
		(layer "In11.Cu")
		(net "P5E_CPU0_P3_TX_DN<6>")
	)
	(arc
		(start 376.058684 -374.455944)
		(mid 375.420851 -375.410623)
		(end 375.196862 -376.536712)
		(width 0.14224)
		(layer "In11.Cu")
		(net "P5E_CPU0_P3_TX_DN<6>")
	)
	(arc
		(start 366.690148 -280.566114)
		(mid 366.625633 -280.828333)
		(end 366.446816 -281.03068)
		(width 0.1143)
		(layer "In11.Cu")
		(net "P5E_CPU0_P3_TX_DN<6>")
	)
	(arc
		(start 366.91697 -279.291542)
		(mid 367.160297 -279.756108)
		(end 366.91697 -280.220674)
		(width 0.1143)
		(layer "In11.Cu")
		(net "P5E_CPU0_P3_TX_DN<6>")
	)
	(arc
		(start 366.37722 -294.031162)
		(mid 366.220243 -294.335962)
		(end 366.37722 -294.640762)
		(width 0.1143)
		(layer "In11.Cu")
		(net "P5E_CPU0_P3_TX_DN<6>")
	)
	(arc
		(start 366.37722 -292.41115)
		(mid 366.220243 -292.71595)
		(end 366.37722 -293.02075)
		(width 0.1143)
		(layer "In11.Cu")
		(net "P5E_CPU0_P3_TX_DN<6>")
	)
	(arc
		(start 366.690148 -295.145968)
		(mid 366.731403 -295.316939)
		(end 366.846104 -295.45026)
		(width 0.1143)
		(layer "In11.Cu")
		(net "P5E_CPU0_P3_TX_DN<6>")
	)
	(arc
		(start 365.750094 -277.329138)
		(mid 365.79054 -277.497253)
		(end 365.903256 -277.62835)
		(width 0.1143)
		(layer "In11.Cu")
		(net "P5E_CPU0_P3_TX_DN<6>")
	)
	(arc
		(start 366.37722 -285.931356)
		(mid 366.261793 -286.064732)
		(end 366.220248 -286.236156)
		(width 0.1143)
		(layer "In11.Cu")
		(net "P5E_CPU0_P3_TX_DN<6>")
	)
	(arc
		(start 366.220248 -278.136096)
		(mid 366.261797 -278.307518)
		(end 366.37722 -278.440896)
		(width 0.1143)
		(layer "In11.Cu")
		(net "P5E_CPU0_P3_TX_DN<6>")
	)
	(arc
		(start 366.37722 -282.691332)
		(mid 366.220243 -282.996132)
		(end 366.37722 -283.300932)
		(width 0.1143)
		(layer "In11.Cu")
		(net "P5E_CPU0_P3_TX_DN<6>")
	)
	(arc
		(start 365.287052 -276.585934)
		(mid 365.339101 -276.717453)
		(end 365.43615 -276.820376)
		(width 0.1143)
		(layer "In11.Cu")
		(net "P5E_CPU0_P3_TX_DN<6>")
	)
	(arc
		(start 387.401054 -347.962474)
		(mid 387.214051 -350.497655)
		(end 386.657088 -352.977958)
		(width 0.14224)
		(layer "In11.Cu")
		(net "P5E_CPU0_P3_TX_DN<6>")
	)
	(arc
		(start 366.446816 -289.821366)
		(mid 366.690143 -290.285932)
		(end 366.446816 -290.750498)
		(width 0.1143)
		(layer "In11.Cu")
		(net "P5E_CPU0_P3_TX_DN<6>")
	)
	(arc
		(start 366.446816 -291.441378)
		(mid 366.690143 -291.905944)
		(end 366.446816 -292.37051)
		(width 0.1143)
		(layer "In11.Cu")
		(net "P5E_CPU0_P3_TX_DN<6>")
	)
	(arc
		(start 366.220248 -286.236156)
		(mid 366.261214 -286.406562)
		(end 366.375188 -286.539686)
		(width 0.1143)
		(layer "In11.Cu")
		(net "P5E_CPU0_P3_TX_DN<6>")
	)
	(arc
		(start 366.91697 -295.491408)
		(mid 367.095628 -295.693808)
		(end 367.160048 -295.955974)
		(width 0.1143)
		(layer "In11.Cu")
		(net "P5E_CPU0_P3_TX_DN<6>")
	)
	(arc
		(start 366.446816 -294.681402)
		(mid 366.625629 -294.883752)
		(end 366.690148 -295.145968)
		(width 0.1143)
		(layer "In11.Cu")
		(net "P5E_CPU0_P3_TX_DN<6>")
	)
	(arc
		(start 366.446816 -293.06139)
		(mid 366.690143 -293.525956)
		(end 366.446816 -293.990522)
		(width 0.1143)
		(layer "In11.Cu")
		(net "P5E_CPU0_P3_TX_DN<6>")
	)
	(arc
		(start 366.37722 -284.311344)
		(mid 366.220243 -284.616144)
		(end 366.37722 -284.920944)
		(width 0.1143)
		(layer "In11.Cu")
		(net "P5E_CPU0_P3_TX_DN<6>")
	)
	(arc
		(start 366.446816 -278.481536)
		(mid 366.625629 -278.683886)
		(end 366.690148 -278.946102)
		(width 0.1143)
		(layer "In11.Cu")
		(net "P5E_CPU0_P3_TX_DN<6>")
	)
	(arc
		(start 366.446816 -286.581342)
		(mid 366.625629 -286.783692)
		(end 366.690148 -287.045908)
		(width 0.1143)
		(layer "In11.Cu")
		(net "P5E_CPU0_P3_TX_DN<6>")
	)
	(arc
		(start 366.846104 -280.261822)
		(mid 366.731428 -280.395156)
		(end 366.690148 -280.566114)
		(width 0.1143)
		(layer "In11.Cu")
		(net "P5E_CPU0_P3_TX_DN<6>")
	)
	(arc
		(start 377.608084 -372.895876)
		(mid 377.567577 -372.944365)
		(end 377.524264 -372.990364)
		(width 0.14224)
		(layer "In11.Cu")
		(net "P5E_CPU0_P3_TX_DN<6>")
	)
	(arc
		(start 366.446816 -288.201354)
		(mid 366.690143 -288.66592)
		(end 366.446816 -289.130486)
		(width 0.1143)
		(layer "In11.Cu")
		(net "P5E_CPU0_P3_TX_DN<6>")
	)
	(arc
		(start 366.37722 -290.791138)
		(mid 366.220243 -291.095938)
		(end 366.37722 -291.400738)
		(width 0.1143)
		(layer "In11.Cu")
		(net "P5E_CPU0_P3_TX_DN<6>")
	)
	(arc
		(start 384.760724 -359.22966)
		(mid 382.959817 -364.222056)
		(end 380.653544 -369.002056)
		(width 0.14224)
		(layer "In11.Cu")
		(net "P5E_CPU0_P3_TX_DN<6>")
	)
	(arc
		(start 366.37722 -289.171126)
		(mid 366.220243 -289.475926)
		(end 366.37722 -289.780726)
		(width 0.1143)
		(layer "In11.Cu")
		(net "P5E_CPU0_P3_TX_DN<6>")
	)
	(arc
		(start 366.446816 -281.72156)
		(mid 366.690143 -282.186126)
		(end 366.446816 -282.650692)
		(width 0.1143)
		(layer "In11.Cu")
		(net "P5E_CPU0_P3_TX_DN<6>")
	)
	(arc
		(start 380.653544 -369.002056)
		(mid 380.609221 -369.075364)
		(end 380.559056 -369.144804)
		(width 0.14224)
		(layer "In11.Cu")
		(net "P5E_CPU0_P3_TX_DN<6>")
	)
	(segment
		(start 373.515382 -380.15164)
		(end 373.515382 -380.85522)
		(width 0.12954)
		(layer "F.Cu")
		(net "P5E_CPU0_P3_TX_DN<5>")
	)
	(segment
		(start 373.515382 -380.85522)
		(end 373.811292 -381.15113)
		(width 0.12954)
		(layer "F.Cu")
		(net "P5E_CPU0_P3_TX_DN<5>")
	)
	(segment
		(start 373.785892 -379.88113)
		(end 373.515382 -380.15164)
		(width 0.12954)
		(layer "F.Cu")
		(net "P5E_CPU0_P3_TX_DN<5>")
	)
	(segment
		(start 365.187992 -277.870158)
		(end 365.654844 -278.136096)
		(width 0.12954)
		(layer "F.Cu")
		(net "P5E_CPU0_P3_TX_DN<5>")
	)
	(segment
		(start 365.435134 -288.159444)
		(end 365.4679 -288.178494)
		(width 0.1143)
		(layer "In11.Cu")
		(net "P5E_CPU0_P3_TX_DN<5>")
	)
	(segment
		(start 365.43615 -283.300424)
		(end 365.467138 -283.318204)
		(width 0.1143)
		(layer "In11.Cu")
		(net "P5E_CPU0_P3_TX_DN<5>")
	)
	(segment
		(start 381.404114 -320.22288)
		(end 383.139442 -324.412864)
		(width 0.14224)
		(layer "In11.Cu")
		(net "P5E_CPU0_P3_TX_DN<5>")
	)
	(segment
		(start 365.4679 -283.318712)
		(end 365.470948 -283.32049)
		(width 0.1143)
		(layer "In11.Cu")
		(net "P5E_CPU0_P3_TX_DN<5>")
	)
	(segment
		(start 365.434372 -286.538924)
		(end 365.509048 -286.582866)
		(width 0.1143)
		(layer "In11.Cu")
		(net "P5E_CPU0_P3_TX_DN<5>")
	)
	(segment
		(start 365.4679 -284.938724)
		(end 365.470948 -284.940502)
		(width 0.1143)
		(layer "In11.Cu")
		(net "P5E_CPU0_P3_TX_DN<5>")
	)
	(segment
		(start 366.265968 -296.446956)
		(end 366.265968 -297.379644)
		(width 0.14224)
		(layer "In11.Cu")
		(net "P5E_CPU0_P3_TX_DN<5>")
	)
	(segment
		(start 365.467138 -278.458168)
		(end 365.4679 -278.458676)
		(width 0.1143)
		(layer "In11.Cu")
		(net "P5E_CPU0_P3_TX_DN<5>")
	)
	(segment
		(start 365.4679 -281.6987)
		(end 365.470948 -281.700478)
		(width 0.1143)
		(layer "In11.Cu")
		(net "P5E_CPU0_P3_TX_DN<5>")
	)
	(segment
		(start 365.43615 -289.780218)
		(end 365.4679 -289.798506)
		(width 0.1143)
		(layer "In11.Cu")
		(net "P5E_CPU0_P3_TX_DN<5>")
	)
	(segment
		(start 365.4679 -281.05354)
		(end 365.43615 -281.071828)
		(width 0.1143)
		(layer "In11.Cu")
		(net "P5E_CPU0_P3_TX_DN<5>")
	)
	(segment
		(start 365.976916 -280.220674)
		(end 365.924846 -280.2509)
		(width 0.1143)
		(layer "In11.Cu")
		(net "P5E_CPU0_P3_TX_DN<5>")
	)
	(segment
		(start 373.495062 -377.154948)
		(end 373.495062 -379.5903)
		(width 0.14224)
		(layer "In11.Cu")
		(net "P5E_CPU0_P3_TX_DN<5>")
	)
	(segment
		(start 367.424462 -301.198534)
		(end 370.640864 -306.012596)
		(width 0.14224)
		(layer "In11.Cu")
		(net "P5E_CPU0_P3_TX_DN<5>")
	)
	(segment
		(start 365.434372 -288.158936)
		(end 365.435134 -288.159444)
		(width 0.1143)
		(layer "In11.Cu")
		(net "P5E_CPU0_P3_TX_DN<5>")
	)
	(segment
		(start 384.343148 -357.031544)
		(end 383.400554 -359.54589)
		(width 0.14224)
		(layer "In11.Cu")
		(net "P5E_CPU0_P3_TX_DN<5>")
	)
	(segment
		(start 377.466098 -314.329064)
		(end 381.404114 -320.22288)
		(width 0.14224)
		(layer "In11.Cu")
		(net "P5E_CPU0_P3_TX_DN<5>")
	)
	(segment
		(start 374.655334 -374.289828)
		(end 373.5197 -377.031758)
		(width 0.14224)
		(layer "In11.Cu")
		(net "P5E_CPU0_P3_TX_DN<5>")
	)
	(segment
		(start 366.220248 -295.955974)
		(end 366.220248 -296.372788)
		(width 0.1143)
		(layer "In11.Cu")
		(net "P5E_CPU0_P3_TX_DN<5>")
	)
	(segment
		(start 365.9378 -279.268682)
		(end 365.976916 -279.291542)
		(width 0.1143)
		(layer "In11.Cu")
		(net "P5E_CPU0_P3_TX_DN<5>")
	)
	(segment
		(start 365.470948 -289.151568)
		(end 365.43615 -289.171634)
		(width 0.1143)
		(layer "In11.Cu")
		(net "P5E_CPU0_P3_TX_DN<5>")
	)
	(segment
		(start 365.43615 -291.40023)
		(end 365.4679 -291.418518)
		(width 0.1143)
		(layer "In11.Cu")
		(net "P5E_CPU0_P3_TX_DN<5>")
	)
	(segment
		(start 365.750094 -295.14165)
		(end 365.750094 -295.145968)
		(width 0.1143)
		(layer "In11.Cu")
		(net "P5E_CPU0_P3_TX_DN<5>")
	)
	(segment
		(start 365.470948 -290.77158)
		(end 365.43615 -290.791646)
		(width 0.1143)
		(layer "In11.Cu")
		(net "P5E_CPU0_P3_TX_DN<5>")
	)
	(segment
		(start 376.663966 -371.690392)
		(end 375.844816 -372.509542)
		(width 0.14224)
		(layer "In11.Cu")
		(net "P5E_CPU0_P3_TX_DN<5>")
	)
	(segment
		(start 365.508032 -287.51022)
		(end 365.43615 -287.551876)
		(width 0.1143)
		(layer "In11.Cu")
		(net "P5E_CPU0_P3_TX_DN<5>")
	)
	(segment
		(start 366.265968 -296.418508)
		(end 366.265968 -296.446956)
		(width 0.1143)
		(layer "In11.Cu")
		(net "P5E_CPU0_P3_TX_DN<5>")
	)
	(segment
		(start 365.738156 -280.574496)
		(end 365.738156 -280.585926)
		(width 0.1143)
		(layer "In11.Cu")
		(net "P5E_CPU0_P3_TX_DN<5>")
	)
	(segment
		(start 365.468916 -278.459184)
		(end 365.482886 -278.467312)
		(width 0.1143)
		(layer "In11.Cu")
		(net "P5E_CPU0_P3_TX_DN<5>")
	)
	(segment
		(start 365.4679 -291.418518)
		(end 365.4679 -291.418772)
		(width 0.1143)
		(layer "In11.Cu")
		(net "P5E_CPU0_P3_TX_DN<5>")
	)
	(segment
		(start 365.924846 -280.2509)
		(end 365.924592 -280.251154)
		(width 0.1143)
		(layer "In11.Cu")
		(net "P5E_CPU0_P3_TX_DN<5>")
	)
	(segment
		(start 365.750094 -287.045908)
		(end 365.750094 -287.05048)
		(width 0.1143)
		(layer "In11.Cu")
		(net "P5E_CPU0_P3_TX_DN<5>")
	)
	(segment
		(start 365.477806 -281.047444)
		(end 365.4679 -281.05354)
		(width 0.1143)
		(layer "In11.Cu")
		(net "P5E_CPU0_P3_TX_DN<5>")
	)
	(segment
		(start 365.356902 -278.136096)
		(end 365.287052 -278.205946)
		(width 0.1143)
		(layer "In11.Cu")
		(net "P5E_CPU0_P3_TX_DN<5>")
	)
	(segment
		(start 379.163072 -368.632486)
		(end 378.219462 -369.894104)
		(width 0.14224)
		(layer "In11.Cu")
		(net "P5E_CPU0_P3_TX_DN<5>")
	)
	(segment
		(start 365.470948 -285.911798)
		(end 365.43615 -285.931864)
		(width 0.1143)
		(layer "In11.Cu")
		(net "P5E_CPU0_P3_TX_DN<5>")
	)
	(segment
		(start 365.467138 -283.318204)
		(end 365.4679 -283.318712)
		(width 0.1143)
		(layer "In11.Cu")
		(net "P5E_CPU0_P3_TX_DN<5>")
	)
	(segment
		(start 365.762794 -278.953468)
		(end 365.762794 -278.965914)
		(width 0.1143)
		(layer "In11.Cu")
		(net "P5E_CPU0_P3_TX_DN<5>")
	)
	(segment
		(start 365.4679 -293.03853)
		(end 365.470948 -293.040308)
		(width 0.1143)
		(layer "In11.Cu")
		(net "P5E_CPU0_P3_TX_DN<5>")
	)
	(segment
		(start 365.4679 -288.178494)
		(end 365.470948 -288.180272)
		(width 0.1143)
		(layer "In11.Cu")
		(net "P5E_CPU0_P3_TX_DN<5>")
	)
	(segment
		(start 365.43615 -284.920436)
		(end 365.4679 -284.938724)
		(width 0.1143)
		(layer "In11.Cu")
		(net "P5E_CPU0_P3_TX_DN<5>")
	)
	(segment
		(start 365.519462 -287.501584)
		(end 365.508032 -287.51022)
		(width 0.1143)
		(layer "In11.Cu")
		(net "P5E_CPU0_P3_TX_DN<5>")
	)
	(segment
		(start 379.583188 -367.976912)
		(end 379.247146 -368.509804)
		(width 0.14224)
		(layer "In11.Cu")
		(net "P5E_CPU0_P3_TX_DN<5>")
	)
	(segment
		(start 365.43615 -278.440388)
		(end 365.467138 -278.458168)
		(width 0.1143)
		(layer "In11.Cu")
		(net "P5E_CPU0_P3_TX_DN<5>")
	)
	(segment
		(start 366.220248 -296.372788)
		(end 366.265968 -296.418508)
		(width 0.1143)
		(layer "In11.Cu")
		(net "P5E_CPU0_P3_TX_DN<5>")
	)
	(segment
		(start 386.363464 -340.685374)
		(end 386.363464 -348.605856)
		(width 0.14224)
		(layer "In11.Cu")
		(net "P5E_CPU0_P3_TX_DN<5>")
	)
	(segment
		(start 365.4679 -289.798506)
		(end 365.470948 -289.800284)
		(width 0.1143)
		(layer "In11.Cu")
		(net "P5E_CPU0_P3_TX_DN<5>")
	)
	(segment
		(start 365.43615 -293.020242)
		(end 365.4679 -293.03853)
		(width 0.1143)
		(layer "In11.Cu")
		(net "P5E_CPU0_P3_TX_DN<5>")
	)
	(segment
		(start 365.4679 -294.658542)
		(end 365.507778 -294.682164)
		(width 0.1143)
		(layer "In11.Cu")
		(net "P5E_CPU0_P3_TX_DN<5>")
	)
	(segment
		(start 365.506 -291.440362)
		(end 365.518954 -291.44976)
		(width 0.1143)
		(layer "In11.Cu")
		(net "P5E_CPU0_P3_TX_DN<5>")
	)
	(segment
		(start 365.654844 -278.136096)
		(end 365.356902 -278.136096)
		(width 0.1143)
		(layer "In11.Cu")
		(net "P5E_CPU0_P3_TX_DN<5>")
	)
	(segment
		(start 365.941356 -295.47058)
		(end 365.976916 -295.491408)
		(width 0.1143)
		(layer "In11.Cu")
		(net "P5E_CPU0_P3_TX_DN<5>")
	)
	(segment
		(start 365.470948 -294.011604)
		(end 365.43615 -294.03167)
		(width 0.1143)
		(layer "In11.Cu")
		(net "P5E_CPU0_P3_TX_DN<5>")
	)
	(segment
		(start 370.640864 -306.012596)
		(end 377.466098 -314.329064)
		(width 0.14224)
		(layer "In11.Cu")
		(net "P5E_CPU0_P3_TX_DN<5>")
	)
	(segment
		(start 365.9378 -295.468548)
		(end 365.938816 -295.469056)
		(width 0.1143)
		(layer "In11.Cu")
		(net "P5E_CPU0_P3_TX_DN<5>")
	)
	(segment
		(start 365.4679 -278.458676)
		(end 365.468916 -278.459184)
		(width 0.1143)
		(layer "In11.Cu")
		(net "P5E_CPU0_P3_TX_DN<5>")
	)
	(segment
		(start 365.43615 -294.640254)
		(end 365.4679 -294.658542)
		(width 0.1143)
		(layer "In11.Cu")
		(net "P5E_CPU0_P3_TX_DN<5>")
	)
	(segment
		(start 365.506 -292.371526)
		(end 365.43615 -292.411658)
		(width 0.1143)
		(layer "In11.Cu")
		(net "P5E_CPU0_P3_TX_DN<5>")
	)
	(segment
		(start 365.470948 -284.291786)
		(end 365.43615 -284.311852)
		(width 0.1143)
		(layer "In11.Cu")
		(net "P5E_CPU0_P3_TX_DN<5>")
	)
	(segment
		(start 385.827524 -352.185478)
		(end 384.343148 -357.031544)
		(width 0.14224)
		(layer "In11.Cu")
		(net "P5E_CPU0_P3_TX_DN<5>")
	)
	(segment
		(start 365.4679 -291.418772)
		(end 365.506 -291.440362)
		(width 0.1143)
		(layer "In11.Cu")
		(net "P5E_CPU0_P3_TX_DN<5>")
	)
	(segment
		(start 365.470948 -282.671774)
		(end 365.43615 -282.69184)
		(width 0.1143)
		(layer "In11.Cu")
		(net "P5E_CPU0_P3_TX_DN<5>")
	)
	(segment
		(start 365.938816 -295.469056)
		(end 365.94034 -295.470072)
		(width 0.1143)
		(layer "In11.Cu")
		(net "P5E_CPU0_P3_TX_DN<5>")
	)
	(segment
		(start 365.43615 -281.680412)
		(end 365.4679 -281.6987)
		(width 0.1143)
		(layer "In11.Cu")
		(net "P5E_CPU0_P3_TX_DN<5>")
	)
	(segment
		(start 383.139442 -324.412864)
		(end 386.351018 -340.55939)
		(width 0.14224)
		(layer "In11.Cu")
		(net "P5E_CPU0_P3_TX_DN<5>")
	)
	(segment
		(start 365.94034 -295.470072)
		(end 365.941356 -295.47058)
		(width 0.1143)
		(layer "In11.Cu")
		(net "P5E_CPU0_P3_TX_DN<5>")
	)
	(segment
		(start 373.495062 -379.5903)
		(end 373.785892 -379.88113)
		(width 0.14224)
		(layer "In11.Cu")
		(net "P5E_CPU0_P3_TX_DN<5>")
	)
	(segment
		(start 366.265968 -297.379644)
		(end 367.424462 -301.198534)
		(width 0.14224)
		(layer "In11.Cu")
		(net "P5E_CPU0_P3_TX_DN<5>")
	)
	(segment
		(start 365.518954 -292.362128)
		(end 365.506 -292.371526)
		(width 0.1143)
		(layer "In11.Cu")
		(net "P5E_CPU0_P3_TX_DN<5>")
	)
	(segment
		(start 365.90605 -295.45026)
		(end 365.9378 -295.468548)
		(width 0.1143)
		(layer "In11.Cu")
		(net "P5E_CPU0_P3_TX_DN<5>")
	)
	(arc
		(start 378.219462 -369.894104)
		(mid 377.473921 -370.820137)
		(end 376.663966 -371.690392)
		(width 0.14224)
		(layer "In11.Cu")
		(net "P5E_CPU0_P3_TX_DN<5>")
	)
	(arc
		(start 365.470948 -283.32049)
		(mid 365.750563 -283.806138)
		(end 365.470948 -284.291786)
		(width 0.1143)
		(layer "In11.Cu")
		(net "P5E_CPU0_P3_TX_DN<5>")
	)
	(arc
		(start 365.738156 -280.585926)
		(mid 365.66858 -280.85087)
		(end 365.477806 -281.047444)
		(width 0.1143)
		(layer "In11.Cu")
		(net "P5E_CPU0_P3_TX_DN<5>")
	)
	(arc
		(start 365.507778 -294.682164)
		(mid 365.685814 -294.881914)
		(end 365.750094 -295.14165)
		(width 0.1143)
		(layer "In11.Cu")
		(net "P5E_CPU0_P3_TX_DN<5>")
	)
	(arc
		(start 365.924592 -280.251154)
		(mid 365.788112 -280.387879)
		(end 365.738156 -280.574496)
		(width 0.1143)
		(layer "In11.Cu")
		(net "P5E_CPU0_P3_TX_DN<5>")
	)
	(arc
		(start 365.470948 -288.180272)
		(mid 365.750563 -288.66592)
		(end 365.470948 -289.151568)
		(width 0.1143)
		(layer "In11.Cu")
		(net "P5E_CPU0_P3_TX_DN<5>")
	)
	(arc
		(start 365.470948 -281.700478)
		(mid 365.750563 -282.186126)
		(end 365.470948 -282.671774)
		(width 0.1143)
		(layer "In11.Cu")
		(net "P5E_CPU0_P3_TX_DN<5>")
	)
	(arc
		(start 365.43615 -282.69184)
		(mid 365.280222 -282.996132)
		(end 365.43615 -283.300424)
		(width 0.1143)
		(layer "In11.Cu")
		(net "P5E_CPU0_P3_TX_DN<5>")
	)
	(arc
		(start 365.43615 -289.171634)
		(mid 365.280222 -289.475926)
		(end 365.43615 -289.780218)
		(width 0.1143)
		(layer "In11.Cu")
		(net "P5E_CPU0_P3_TX_DN<5>")
	)
	(arc
		(start 365.470948 -293.040308)
		(mid 365.750563 -293.525956)
		(end 365.470948 -294.011604)
		(width 0.1143)
		(layer "In11.Cu")
		(net "P5E_CPU0_P3_TX_DN<5>")
	)
	(arc
		(start 365.43615 -290.791646)
		(mid 365.280222 -291.095938)
		(end 365.43615 -291.40023)
		(width 0.1143)
		(layer "In11.Cu")
		(net "P5E_CPU0_P3_TX_DN<5>")
	)
	(arc
		(start 365.43615 -292.411658)
		(mid 365.280222 -292.71595)
		(end 365.43615 -293.020242)
		(width 0.1143)
		(layer "In11.Cu")
		(net "P5E_CPU0_P3_TX_DN<5>")
	)
	(arc
		(start 365.43615 -281.071828)
		(mid 365.280222 -281.37612)
		(end 365.43615 -281.680412)
		(width 0.1143)
		(layer "In11.Cu")
		(net "P5E_CPU0_P3_TX_DN<5>")
	)
	(arc
		(start 365.470948 -289.800284)
		(mid 365.750563 -290.285932)
		(end 365.470948 -290.77158)
		(width 0.1143)
		(layer "In11.Cu")
		(net "P5E_CPU0_P3_TX_DN<5>")
	)
	(arc
		(start 365.762794 -278.965914)
		(mid 365.809685 -279.14078)
		(end 365.9378 -279.268682)
		(width 0.1143)
		(layer "In11.Cu")
		(net "P5E_CPU0_P3_TX_DN<5>")
	)
	(arc
		(start 365.976916 -279.291542)
		(mid 366.220133 -279.756108)
		(end 365.976916 -280.220674)
		(width 0.1143)
		(layer "In11.Cu")
		(net "P5E_CPU0_P3_TX_DN<5>")
	)
	(arc
		(start 365.43615 -287.551876)
		(mid 365.321474 -287.68521)
		(end 365.280194 -287.856168)
		(width 0.1143)
		(layer "In11.Cu")
		(net "P5E_CPU0_P3_TX_DN<5>")
	)
	(arc
		(start 365.43615 -285.931864)
		(mid 365.321474 -286.065198)
		(end 365.280194 -286.236156)
		(width 0.1143)
		(layer "In11.Cu")
		(net "P5E_CPU0_P3_TX_DN<5>")
	)
	(arc
		(start 365.518954 -291.44976)
		(mid 365.753381 -291.905944)
		(end 365.518954 -292.362128)
		(width 0.1143)
		(layer "In11.Cu")
		(net "P5E_CPU0_P3_TX_DN<5>")
	)
	(arc
		(start 365.482886 -278.467312)
		(mid 365.687831 -278.672974)
		(end 365.762794 -278.953468)
		(width 0.1143)
		(layer "In11.Cu")
		(net "P5E_CPU0_P3_TX_DN<5>")
	)
	(arc
		(start 375.844816 -372.509542)
		(mid 375.162395 -373.341101)
		(end 374.655334 -374.289828)
		(width 0.14224)
		(layer "In11.Cu")
		(net "P5E_CPU0_P3_TX_DN<5>")
	)
	(arc
		(start 365.470948 -284.940502)
		(mid 365.750563 -285.42615)
		(end 365.470948 -285.911798)
		(width 0.1143)
		(layer "In11.Cu")
		(net "P5E_CPU0_P3_TX_DN<5>")
	)
	(arc
		(start 382.953006 -360.667554)
		(mid 381.386596 -364.288023)
		(end 379.663198 -367.83645)
		(width 0.14224)
		(layer "In11.Cu")
		(net "P5E_CPU0_P3_TX_DN<5>")
	)
	(arc
		(start 365.509048 -286.582866)
		(mid 365.686244 -286.784878)
		(end 365.750094 -287.045908)
		(width 0.1143)
		(layer "In11.Cu")
		(net "P5E_CPU0_P3_TX_DN<5>")
	)
	(arc
		(start 365.976916 -295.491408)
		(mid 366.055339 -295.556889)
		(end 366.12068 -295.635426)
		(width 0.1143)
		(layer "In11.Cu")
		(net "P5E_CPU0_P3_TX_DN<5>")
	)
	(arc
		(start 365.43615 -294.03167)
		(mid 365.280222 -294.335962)
		(end 365.43615 -294.640254)
		(width 0.1143)
		(layer "In11.Cu")
		(net "P5E_CPU0_P3_TX_DN<5>")
	)
	(arc
		(start 379.247146 -368.509804)
		(mid 379.206328 -368.57198)
		(end 379.163072 -368.632486)
		(width 0.14224)
		(layer "In11.Cu")
		(net "P5E_CPU0_P3_TX_DN<5>")
	)
	(arc
		(start 386.363464 -348.605856)
		(mid 386.228738 -350.415616)
		(end 385.827524 -352.185478)
		(width 0.14224)
		(layer "In11.Cu")
		(net "P5E_CPU0_P3_TX_DN<5>")
	)
	(arc
		(start 365.750094 -295.145968)
		(mid 365.791349 -295.316939)
		(end 365.90605 -295.45026)
		(width 0.1143)
		(layer "In11.Cu")
		(net "P5E_CPU0_P3_TX_DN<5>")
	)
	(arc
		(start 365.287052 -278.205946)
		(mid 365.339101 -278.337465)
		(end 365.43615 -278.440388)
		(width 0.1143)
		(layer "In11.Cu")
		(net "P5E_CPU0_P3_TX_DN<5>")
	)
	(arc
		(start 386.351018 -340.55939)
		(mid 386.36033 -340.622076)
		(end 386.363464 -340.685374)
		(width 0.14224)
		(layer "In11.Cu")
		(net "P5E_CPU0_P3_TX_DN<5>")
	)
	(arc
		(start 366.12068 -295.635426)
		(mid 366.194794 -295.78814)
		(end 366.220248 -295.955974)
		(width 0.1143)
		(layer "In11.Cu")
		(net "P5E_CPU0_P3_TX_DN<5>")
	)
	(arc
		(start 383.400554 -359.54589)
		(mid 383.178659 -360.107472)
		(end 382.953006 -360.667554)
		(width 0.14224)
		(layer "In11.Cu")
		(net "P5E_CPU0_P3_TX_DN<5>")
	)
	(arc
		(start 379.663198 -367.83645)
		(mid 379.624748 -367.907567)
		(end 379.583188 -367.976912)
		(width 0.14224)
		(layer "In11.Cu")
		(net "P5E_CPU0_P3_TX_DN<5>")
	)
	(arc
		(start 365.280194 -286.236156)
		(mid 365.320956 -286.40604)
		(end 365.434372 -286.538924)
		(width 0.1143)
		(layer "In11.Cu")
		(net "P5E_CPU0_P3_TX_DN<5>")
	)
	(arc
		(start 373.5197 -377.031758)
		(mid 373.501302 -377.092139)
		(end 373.495062 -377.154948)
		(width 0.14224)
		(layer "In11.Cu")
		(net "P5E_CPU0_P3_TX_DN<5>")
	)
	(arc
		(start 365.750094 -287.05048)
		(mid 365.689095 -287.303804)
		(end 365.519462 -287.501584)
		(width 0.1143)
		(layer "In11.Cu")
		(net "P5E_CPU0_P3_TX_DN<5>")
	)
	(arc
		(start 365.43615 -284.311852)
		(mid 365.280222 -284.616144)
		(end 365.43615 -284.920436)
		(width 0.1143)
		(layer "In11.Cu")
		(net "P5E_CPU0_P3_TX_DN<5>")
	)
	(arc
		(start 365.280194 -287.856168)
		(mid 365.320956 -288.026052)
		(end 365.434372 -288.158936)
		(width 0.1143)
		(layer "In11.Cu")
		(net "P5E_CPU0_P3_TX_DN<5>")
	)
	(segment
		(start 371.813582 -382.61544)
		(end 371.813582 -383.31902)
		(width 0.12954)
		(layer "F.Cu")
		(net "P5E_CPU0_P3_TX_DN<4>")
	)
	(segment
		(start 365.187992 -279.49017)
		(end 365.654844 -279.756108)
		(width 0.12954)
		(layer "F.Cu")
		(net "P5E_CPU0_P3_TX_DN<4>")
	)
	(segment
		(start 371.813582 -383.31902)
		(end 372.109492 -383.61493)
		(width 0.12954)
		(layer "F.Cu")
		(net "P5E_CPU0_P3_TX_DN<4>")
	)
	(segment
		(start 372.084092 -382.34493)
		(end 371.813582 -382.61544)
		(width 0.12954)
		(layer "F.Cu")
		(net "P5E_CPU0_P3_TX_DN<4>")
	)
	(segment
		(start 364.496096 -291.40023)
		(end 364.527084 -291.41801)
		(width 0.1143)
		(layer "In11.Cu")
		(net "P5E_CPU0_P3_TX_DN<4>")
	)
	(segment
		(start 364.52429 -283.31668)
		(end 364.526322 -283.31795)
		(width 0.1143)
		(layer "In11.Cu")
		(net "P5E_CPU0_P3_TX_DN<4>")
	)
	(segment
		(start 364.527846 -285.913576)
		(end 364.527084 -285.914084)
		(width 0.1143)
		(layer "In11.Cu")
		(net "P5E_CPU0_P3_TX_DN<4>")
	)
	(segment
		(start 364.540038 -284.286706)
		(end 364.53699 -284.288484)
		(width 0.1143)
		(layer "In11.Cu")
		(net "P5E_CPU0_P3_TX_DN<4>")
	)
	(segment
		(start 364.525814 -289.154616)
		(end 364.496096 -289.171634)
		(width 0.1143)
		(layer "In11.Cu")
		(net "P5E_CPU0_P3_TX_DN<4>")
	)
	(segment
		(start 365.280194 -295.955974)
		(end 365.280194 -296.372788)
		(width 0.1143)
		(layer "In11.Cu")
		(net "P5E_CPU0_P3_TX_DN<4>")
	)
	(segment
		(start 364.527084 -285.914084)
		(end 364.525814 -285.914846)
		(width 0.1143)
		(layer "In11.Cu")
		(net "P5E_CPU0_P3_TX_DN<4>")
	)
	(segment
		(start 364.530894 -282.671774)
		(end 364.527846 -282.673552)
		(width 0.1143)
		(layer "In11.Cu")
		(net "P5E_CPU0_P3_TX_DN<4>")
	)
	(segment
		(start 364.527084 -290.773866)
		(end 364.525814 -290.774628)
		(width 0.1143)
		(layer "In11.Cu")
		(net "P5E_CPU0_P3_TX_DN<4>")
	)
	(segment
		(start 364.53699 -284.288484)
		(end 364.536228 -284.288992)
		(width 0.1143)
		(layer "In11.Cu")
		(net "P5E_CPU0_P3_TX_DN<4>")
	)
	(segment
		(start 364.527846 -281.6987)
		(end 364.530894 -281.700478)
		(width 0.1143)
		(layer "In11.Cu")
		(net "P5E_CPU0_P3_TX_DN<4>")
	)
	(segment
		(start 364.527846 -288.178494)
		(end 364.528608 -288.179002)
		(width 0.1143)
		(layer "In11.Cu")
		(net "P5E_CPU0_P3_TX_DN<4>")
	)
	(segment
		(start 364.527084 -292.393878)
		(end 364.525814 -292.39464)
		(width 0.1143)
		(layer "In11.Cu")
		(net "P5E_CPU0_P3_TX_DN<4>")
	)
	(segment
		(start 365.325914 -296.784776)
		(end 365.321342 -296.789348)
		(width 0.14224)
		(layer "In11.Cu")
		(net "P5E_CPU0_P3_TX_DN<4>")
	)
	(segment
		(start 365.036862 -280.220674)
		(end 364.965996 -280.262076)
		(width 0.1143)
		(layer "In11.Cu")
		(net "P5E_CPU0_P3_TX_DN<4>")
	)
	(segment
		(start 385.413504 -341.0839)
		(end 385.413504 -348.284292)
		(width 0.14224)
		(layer "In11.Cu")
		(net "P5E_CPU0_P3_TX_DN<4>")
	)
	(segment
		(start 364.522004 -283.31541)
		(end 364.523528 -283.316172)
		(width 0.1143)
		(layer "In11.Cu")
		(net "P5E_CPU0_P3_TX_DN<4>")
	)
	(segment
		(start 364.565946 -281.031442)
		(end 364.542832 -281.044904)
		(width 0.1143)
		(layer "In11.Cu")
		(net "P5E_CPU0_P3_TX_DN<4>")
	)
	(segment
		(start 364.526322 -283.31795)
		(end 364.527084 -283.318458)
		(width 0.1143)
		(layer "In11.Cu")
		(net "P5E_CPU0_P3_TX_DN<4>")
	)
	(segment
		(start 364.496096 -281.680412)
		(end 364.527084 -281.698192)
		(width 0.1143)
		(layer "In11.Cu")
		(net "P5E_CPU0_P3_TX_DN<4>")
	)
	(segment
		(start 364.527084 -289.153854)
		(end 364.525814 -289.154616)
		(width 0.1143)
		(layer "In11.Cu")
		(net "P5E_CPU0_P3_TX_DN<4>")
	)
	(segment
		(start 365.280194 -296.372788)
		(end 365.325914 -296.418508)
		(width 0.1143)
		(layer "In11.Cu")
		(net "P5E_CPU0_P3_TX_DN<4>")
	)
	(segment
		(start 371.793262 -377.507246)
		(end 371.793262 -381.987298)
		(width 0.14224)
		(layer "In11.Cu")
		(net "P5E_CPU0_P3_TX_DN<4>")
	)
	(segment
		(start 364.496096 -293.020242)
		(end 364.527084 -293.038022)
		(width 0.1143)
		(layer "In11.Cu")
		(net "P5E_CPU0_P3_TX_DN<4>")
	)
	(segment
		(start 365.321342 -296.789348)
		(end 365.321342 -297.50639)
		(width 0.14224)
		(layer "In11.Cu")
		(net "P5E_CPU0_P3_TX_DN<4>")
	)
	(segment
		(start 364.525814 -290.774628)
		(end 364.496096 -290.791646)
		(width 0.1143)
		(layer "In11.Cu")
		(net "P5E_CPU0_P3_TX_DN<4>")
	)
	(segment
		(start 364.525814 -285.914846)
		(end 364.496096 -285.931864)
		(width 0.1143)
		(layer "In11.Cu")
		(net "P5E_CPU0_P3_TX_DN<4>")
	)
	(segment
		(start 364.527084 -291.41801)
		(end 364.527846 -291.418518)
		(width 0.1143)
		(layer "In11.Cu")
		(net "P5E_CPU0_P3_TX_DN<4>")
	)
	(segment
		(start 370.26469 -307.209444)
		(end 377.369578 -315.867034)
		(width 0.14224)
		(layer "In11.Cu")
		(net "P5E_CPU0_P3_TX_DN<4>")
	)
	(segment
		(start 364.527846 -292.39337)
		(end 364.527084 -292.393878)
		(width 0.1143)
		(layer "In11.Cu")
		(net "P5E_CPU0_P3_TX_DN<4>")
	)
	(segment
		(start 364.545372 -283.328872)
		(end 364.546134 -283.32938)
		(width 0.1143)
		(layer "In11.Cu")
		(net "P5E_CPU0_P3_TX_DN<4>")
	)
	(segment
		(start 364.541562 -284.28569)
		(end 364.540038 -284.286706)
		(width 0.1143)
		(layer "In11.Cu")
		(net "P5E_CPU0_P3_TX_DN<4>")
	)
	(segment
		(start 365.321342 -297.50639)
		(end 366.60201 -301.727616)
		(width 0.14224)
		(layer "In11.Cu")
		(net "P5E_CPU0_P3_TX_DN<4>")
	)
	(segment
		(start 365.654844 -279.756108)
		(end 365.356902 -279.756108)
		(width 0.1143)
		(layer "In11.Cu")
		(net "P5E_CPU0_P3_TX_DN<4>")
	)
	(segment
		(start 377.406916 -367.748566)
		(end 373.914416 -371.79885)
		(width 0.14224)
		(layer "In11.Cu")
		(net "P5E_CPU0_P3_TX_DN<4>")
	)
	(segment
		(start 364.536228 -284.288992)
		(end 364.527846 -284.293564)
		(width 0.1143)
		(layer "In11.Cu")
		(net "P5E_CPU0_P3_TX_DN<4>")
	)
	(segment
		(start 364.527084 -289.797998)
		(end 364.527846 -289.798506)
		(width 0.1143)
		(layer "In11.Cu")
		(net "P5E_CPU0_P3_TX_DN<4>")
	)
	(segment
		(start 364.517432 -284.932882)
		(end 364.52048 -284.93466)
		(width 0.1143)
		(layer "In11.Cu")
		(net "P5E_CPU0_P3_TX_DN<4>")
	)
	(segment
		(start 364.81004 -280.56332)
		(end 364.81004 -280.566114)
		(width 0.1143)
		(layer "In11.Cu")
		(net "P5E_CPU0_P3_TX_DN<4>")
	)
	(segment
		(start 364.527084 -283.318204)
		(end 364.528608 -283.31922)
		(width 0.1143)
		(layer "In11.Cu")
		(net "P5E_CPU0_P3_TX_DN<4>")
	)
	(segment
		(start 364.527846 -286.558482)
		(end 364.564168 -286.579564)
		(width 0.1143)
		(layer "In11.Cu")
		(net "P5E_CPU0_P3_TX_DN<4>")
	)
	(segment
		(start 364.527846 -284.293564)
		(end 364.524544 -284.295342)
		(width 0.1143)
		(layer "In11.Cu")
		(net "P5E_CPU0_P3_TX_DN<4>")
	)
	(segment
		(start 364.524798 -284.936946)
		(end 364.527846 -284.938724)
		(width 0.1143)
		(layer "In11.Cu")
		(net "P5E_CPU0_P3_TX_DN<4>")
	)
	(segment
		(start 364.80242 -287.088834)
		(end 364.778544 -287.202626)
		(width 0.1143)
		(layer "In11.Cu")
		(net "P5E_CPU0_P3_TX_DN<4>")
	)
	(segment
		(start 364.496096 -289.780218)
		(end 364.527084 -289.797998)
		(width 0.1143)
		(layer "In11.Cu")
		(net "P5E_CPU0_P3_TX_DN<4>")
	)
	(segment
		(start 364.527084 -283.318458)
		(end 364.527084 -283.318204)
		(width 0.1143)
		(layer "In11.Cu")
		(net "P5E_CPU0_P3_TX_DN<4>")
	)
	(segment
		(start 364.494318 -286.538924)
		(end 364.527846 -286.558482)
		(width 0.1143)
		(layer "In11.Cu")
		(net "P5E_CPU0_P3_TX_DN<4>")
	)
	(segment
		(start 364.511082 -287.54451)
		(end 364.496858 -287.551622)
		(width 0.1143)
		(layer "In11.Cu")
		(net "P5E_CPU0_P3_TX_DN<4>")
	)
	(segment
		(start 364.527084 -294.658034)
		(end 364.527846 -294.658542)
		(width 0.1143)
		(layer "In11.Cu")
		(net "P5E_CPU0_P3_TX_DN<4>")
	)
	(segment
		(start 364.527846 -290.773358)
		(end 364.527084 -290.773866)
		(width 0.1143)
		(layer "In11.Cu")
		(net "P5E_CPU0_P3_TX_DN<4>")
	)
	(segment
		(start 364.544102 -284.284166)
		(end 364.54334 -284.284674)
		(width 0.1143)
		(layer "In11.Cu")
		(net "P5E_CPU0_P3_TX_DN<4>")
	)
	(segment
		(start 364.52302 -294.656002)
		(end 364.52556 -294.657526)
		(width 0.1143)
		(layer "In11.Cu")
		(net "P5E_CPU0_P3_TX_DN<4>")
	)
	(segment
		(start 364.528608 -289.152838)
		(end 364.527084 -289.153854)
		(width 0.1143)
		(layer "In11.Cu")
		(net "P5E_CPU0_P3_TX_DN<4>")
	)
	(segment
		(start 364.965996 -295.45026)
		(end 365.036862 -295.491408)
		(width 0.1143)
		(layer "In11.Cu")
		(net "P5E_CPU0_P3_TX_DN<4>")
	)
	(segment
		(start 365.356902 -279.756108)
		(end 365.274098 -279.838912)
		(width 0.1143)
		(layer "In11.Cu")
		(net "P5E_CPU0_P3_TX_DN<4>")
	)
	(segment
		(start 364.542832 -281.044904)
		(end 364.542832 -281.045158)
		(width 0.1143)
		(layer "In11.Cu")
		(net "P5E_CPU0_P3_TX_DN<4>")
	)
	(segment
		(start 364.496858 -287.551622)
		(end 364.496096 -287.551876)
		(width 0.1143)
		(layer "In11.Cu")
		(net "P5E_CPU0_P3_TX_DN<4>")
	)
	(segment
		(start 364.523528 -283.316172)
		(end 364.52429 -283.31668)
		(width 0.1143)
		(layer "In11.Cu")
		(net "P5E_CPU0_P3_TX_DN<4>")
	)
	(segment
		(start 364.524036 -282.675584)
		(end 364.50778 -282.684982)
		(width 0.1143)
		(layer "In11.Cu")
		(net "P5E_CPU0_P3_TX_DN<4>")
	)
	(segment
		(start 364.527846 -284.938724)
		(end 364.564168 -284.959806)
		(width 0.1143)
		(layer "In11.Cu")
		(net "P5E_CPU0_P3_TX_DN<4>")
	)
	(segment
		(start 371.840506 -382.101344)
		(end 372.084092 -382.34493)
		(width 0.14224)
		(layer "In11.Cu")
		(net "P5E_CPU0_P3_TX_DN<4>")
	)
	(segment
		(start 364.564168 -285.892494)
		(end 364.527846 -285.913576)
		(width 0.1143)
		(layer "In11.Cu")
		(net "P5E_CPU0_P3_TX_DN<4>")
	)
	(segment
		(start 364.527592 -282.673806)
		(end 364.524036 -282.675584)
		(width 0.1143)
		(layer "In11.Cu")
		(net "P5E_CPU0_P3_TX_DN<4>")
	)
	(segment
		(start 364.54334 -284.284674)
		(end 364.541562 -284.28569)
		(width 0.1143)
		(layer "In11.Cu")
		(net "P5E_CPU0_P3_TX_DN<4>")
	)
	(segment
		(start 365.325914 -296.446956)
		(end 365.325914 -296.784776)
		(width 0.14224)
		(layer "In11.Cu")
		(net "P5E_CPU0_P3_TX_DN<4>")
	)
	(segment
		(start 364.525814 -294.657272)
		(end 364.527084 -294.658034)
		(width 0.1143)
		(layer "In11.Cu")
		(net "P5E_CPU0_P3_TX_DN<4>")
	)
	(segment
		(start 364.522258 -284.935422)
		(end 364.524798 -284.936946)
		(width 0.1143)
		(layer "In11.Cu")
		(net "P5E_CPU0_P3_TX_DN<4>")
	)
	(segment
		(start 364.52048 -284.93466)
		(end 364.522258 -284.935422)
		(width 0.1143)
		(layer "In11.Cu")
		(net "P5E_CPU0_P3_TX_DN<4>")
	)
	(segment
		(start 364.70336 -287.361122)
		(end 364.636558 -287.443672)
		(width 0.1143)
		(layer "In11.Cu")
		(net "P5E_CPU0_P3_TX_DN<4>")
	)
	(segment
		(start 364.527084 -281.698192)
		(end 364.527846 -281.6987)
		(width 0.1143)
		(layer "In11.Cu")
		(net "P5E_CPU0_P3_TX_DN<4>")
	)
	(segment
		(start 365.325914 -296.418508)
		(end 365.325914 -296.446956)
		(width 0.1143)
		(layer "In11.Cu")
		(net "P5E_CPU0_P3_TX_DN<4>")
	)
	(segment
		(start 380.531878 -320.599562)
		(end 382.192784 -324.891146)
		(width 0.14224)
		(layer "In11.Cu")
		(net "P5E_CPU0_P3_TX_DN<4>")
	)
	(segment
		(start 364.528608 -283.31922)
		(end 364.545372 -283.328872)
		(width 0.1143)
		(layer "In11.Cu")
		(net "P5E_CPU0_P3_TX_DN<4>")
	)
	(segment
		(start 364.542832 -281.045158)
		(end 364.537752 -281.048206)
		(width 0.1143)
		(layer "In11.Cu")
		(net "P5E_CPU0_P3_TX_DN<4>")
	)
	(segment
		(start 364.527846 -294.013382)
		(end 364.527084 -294.01389)
		(width 0.1143)
		(layer "In11.Cu")
		(net "P5E_CPU0_P3_TX_DN<4>")
	)
	(segment
		(start 366.60201 -301.727616)
		(end 370.26469 -307.209444)
		(width 0.14224)
		(layer "In11.Cu")
		(net "P5E_CPU0_P3_TX_DN<4>")
	)
	(segment
		(start 364.527846 -294.658542)
		(end 364.555786 -294.676576)
		(width 0.1143)
		(layer "In11.Cu")
		(net "P5E_CPU0_P3_TX_DN<4>")
	)
	(segment
		(start 364.494318 -288.158936)
		(end 364.527846 -288.178494)
		(width 0.1143)
		(layer "In11.Cu")
		(net "P5E_CPU0_P3_TX_DN<4>")
	)
	(segment
		(start 382.192784 -324.891146)
		(end 385.413504 -341.0839)
		(width 0.14224)
		(layer "In11.Cu")
		(net "P5E_CPU0_P3_TX_DN<4>")
	)
	(segment
		(start 364.525814 -292.39464)
		(end 364.496096 -292.411658)
		(width 0.1143)
		(layer "In11.Cu")
		(net "P5E_CPU0_P3_TX_DN<4>")
	)
	(segment
		(start 364.52556 -294.657526)
		(end 364.525814 -294.657272)
		(width 0.1143)
		(layer "In11.Cu")
		(net "P5E_CPU0_P3_TX_DN<4>")
	)
	(segment
		(start 377.369578 -315.867034)
		(end 380.531878 -320.599562)
		(width 0.14224)
		(layer "In11.Cu")
		(net "P5E_CPU0_P3_TX_DN<4>")
	)
	(segment
		(start 384.76301 -352.03384)
		(end 381.897636 -360.041698)
		(width 0.14224)
		(layer "In11.Cu")
		(net "P5E_CPU0_P3_TX_DN<4>")
	)
	(segment
		(start 364.546134 -284.282896)
		(end 364.544102 -284.284166)
		(width 0.1143)
		(layer "In11.Cu")
		(net "P5E_CPU0_P3_TX_DN<4>")
	)
	(segment
		(start 364.527084 -293.038022)
		(end 364.527846 -293.03853)
		(width 0.1143)
		(layer "In11.Cu")
		(net "P5E_CPU0_P3_TX_DN<4>")
	)
	(segment
		(start 364.527846 -282.673552)
		(end 364.527592 -282.673806)
		(width 0.1143)
		(layer "In11.Cu")
		(net "P5E_CPU0_P3_TX_DN<4>")
	)
	(segment
		(start 364.537752 -281.048206)
		(end 364.496096 -281.071828)
		(width 0.1143)
		(layer "In11.Cu")
		(net "P5E_CPU0_P3_TX_DN<4>")
	)
	(segment
		(start 364.506764 -283.306774)
		(end 364.522004 -283.31541)
		(width 0.1143)
		(layer "In11.Cu")
		(net "P5E_CPU0_P3_TX_DN<4>")
	)
	(segment
		(start 364.527084 -294.01389)
		(end 364.52429 -294.015414)
		(width 0.1143)
		(layer "In11.Cu")
		(net "P5E_CPU0_P3_TX_DN<4>")
	)
	(arc
		(start 364.496096 -281.071828)
		(mid 364.340168 -281.37612)
		(end 364.496096 -281.680412)
		(width 0.1143)
		(layer "In11.Cu")
		(net "P5E_CPU0_P3_TX_DN<4>")
	)
	(arc
		(start 365.270288 -279.861772)
		(mid 365.188855 -280.06417)
		(end 365.036862 -280.220674)
		(width 0.1143)
		(layer "In11.Cu")
		(net "P5E_CPU0_P3_TX_DN<4>")
	)
	(arc
		(start 364.808008 -286.995616)
		(mid 364.80864 -287.042429)
		(end 364.80242 -287.088834)
		(width 0.1143)
		(layer "In11.Cu")
		(net "P5E_CPU0_P3_TX_DN<4>")
	)
	(arc
		(start 364.778544 -287.202626)
		(mid 364.750498 -287.286401)
		(end 364.70336 -287.361122)
		(width 0.1143)
		(layer "In11.Cu")
		(net "P5E_CPU0_P3_TX_DN<4>")
	)
	(arc
		(start 364.527846 -289.798506)
		(mid 364.808493 -290.285932)
		(end 364.527846 -290.773358)
		(width 0.1143)
		(layer "In11.Cu")
		(net "P5E_CPU0_P3_TX_DN<4>")
	)
	(arc
		(start 381.897636 -360.041698)
		(mid 380.007765 -364.102271)
		(end 377.406916 -367.748566)
		(width 0.14224)
		(layer "In11.Cu")
		(net "P5E_CPU0_P3_TX_DN<4>")
	)
	(arc
		(start 365.180626 -295.635426)
		(mid 365.25474 -295.78814)
		(end 365.280194 -295.955974)
		(width 0.1143)
		(layer "In11.Cu")
		(net "P5E_CPU0_P3_TX_DN<4>")
	)
	(arc
		(start 364.496096 -292.411658)
		(mid 364.340168 -292.71595)
		(end 364.496096 -293.020242)
		(width 0.1143)
		(layer "In11.Cu")
		(net "P5E_CPU0_P3_TX_DN<4>")
	)
	(arc
		(start 365.274098 -279.838912)
		(mid 365.27231 -279.850361)
		(end 365.270288 -279.861772)
		(width 0.1143)
		(layer "In11.Cu")
		(net "P5E_CPU0_P3_TX_DN<4>")
	)
	(arc
		(start 364.81004 -280.566114)
		(mid 364.745318 -280.828853)
		(end 364.565946 -281.031442)
		(width 0.1143)
		(layer "In11.Cu")
		(net "P5E_CPU0_P3_TX_DN<4>")
	)
	(arc
		(start 364.52429 -294.015414)
		(mid 364.340156 -294.335286)
		(end 364.52302 -294.656002)
		(width 0.1143)
		(layer "In11.Cu")
		(net "P5E_CPU0_P3_TX_DN<4>")
	)
	(arc
		(start 364.579408 -284.970474)
		(mid 364.804579 -285.42615)
		(end 364.579408 -285.881826)
		(width 0.1143)
		(layer "In11.Cu")
		(net "P5E_CPU0_P3_TX_DN<4>")
	)
	(arc
		(start 364.528608 -288.179002)
		(mid 364.808942 -288.66592)
		(end 364.528608 -289.152838)
		(width 0.1143)
		(layer "In11.Cu")
		(net "P5E_CPU0_P3_TX_DN<4>")
	)
	(arc
		(start 364.564168 -284.959806)
		(mid 364.571832 -284.965077)
		(end 364.579408 -284.970474)
		(width 0.1143)
		(layer "In11.Cu")
		(net "P5E_CPU0_P3_TX_DN<4>")
	)
	(arc
		(start 364.50778 -282.684982)
		(mid 364.329244 -282.995565)
		(end 364.506764 -283.306774)
		(width 0.1143)
		(layer "In11.Cu")
		(net "P5E_CPU0_P3_TX_DN<4>")
	)
	(arc
		(start 364.34014 -287.856168)
		(mid 364.380902 -288.026052)
		(end 364.494318 -288.158936)
		(width 0.1143)
		(layer "In11.Cu")
		(net "P5E_CPU0_P3_TX_DN<4>")
	)
	(arc
		(start 364.496096 -285.931864)
		(mid 364.38142 -286.065198)
		(end 364.34014 -286.236156)
		(width 0.1143)
		(layer "In11.Cu")
		(net "P5E_CPU0_P3_TX_DN<4>")
	)
	(arc
		(start 364.57763 -286.589216)
		(mid 364.736836 -286.767474)
		(end 364.808008 -286.995616)
		(width 0.1143)
		(layer "In11.Cu")
		(net "P5E_CPU0_P3_TX_DN<4>")
	)
	(arc
		(start 364.564168 -286.579564)
		(mid 364.570934 -286.584341)
		(end 364.57763 -286.589216)
		(width 0.1143)
		(layer "In11.Cu")
		(net "P5E_CPU0_P3_TX_DN<4>")
	)
	(arc
		(start 364.579408 -285.881826)
		(mid 364.571832 -285.887222)
		(end 364.564168 -285.892494)
		(width 0.1143)
		(layer "In11.Cu")
		(net "P5E_CPU0_P3_TX_DN<4>")
	)
	(arc
		(start 364.527846 -293.03853)
		(mid 364.808493 -293.525956)
		(end 364.527846 -294.013382)
		(width 0.1143)
		(layer "In11.Cu")
		(net "P5E_CPU0_P3_TX_DN<4>")
	)
	(arc
		(start 373.914416 -371.79885)
		(mid 372.340636 -374.462357)
		(end 371.793262 -377.507246)
		(width 0.14224)
		(layer "In11.Cu")
		(net "P5E_CPU0_P3_TX_DN<4>")
	)
	(arc
		(start 364.555786 -294.676576)
		(mid 364.742422 -294.879044)
		(end 364.81004 -295.145968)
		(width 0.1143)
		(layer "In11.Cu")
		(net "P5E_CPU0_P3_TX_DN<4>")
	)
	(arc
		(start 385.413504 -348.284292)
		(mid 385.249689 -350.187071)
		(end 384.76301 -352.03384)
		(width 0.14224)
		(layer "In11.Cu")
		(net "P5E_CPU0_P3_TX_DN<4>")
	)
	(arc
		(start 364.496096 -290.791646)
		(mid 364.340168 -291.095938)
		(end 364.496096 -291.40023)
		(width 0.1143)
		(layer "In11.Cu")
		(net "P5E_CPU0_P3_TX_DN<4>")
	)
	(arc
		(start 364.524544 -284.295342)
		(mid 364.340339 -284.61205)
		(end 364.517432 -284.932882)
		(width 0.1143)
		(layer "In11.Cu")
		(net "P5E_CPU0_P3_TX_DN<4>")
	)
	(arc
		(start 364.636558 -287.443672)
		(mid 364.579159 -287.500731)
		(end 364.511082 -287.54451)
		(width 0.1143)
		(layer "In11.Cu")
		(net "P5E_CPU0_P3_TX_DN<4>")
	)
	(arc
		(start 364.34014 -286.236156)
		(mid 364.380902 -286.40604)
		(end 364.494318 -286.538924)
		(width 0.1143)
		(layer "In11.Cu")
		(net "P5E_CPU0_P3_TX_DN<4>")
	)
	(arc
		(start 364.530894 -281.700478)
		(mid 364.810509 -282.186126)
		(end 364.530894 -282.671774)
		(width 0.1143)
		(layer "In11.Cu")
		(net "P5E_CPU0_P3_TX_DN<4>")
	)
	(arc
		(start 364.496096 -287.551876)
		(mid 364.38142 -287.68521)
		(end 364.34014 -287.856168)
		(width 0.1143)
		(layer "In11.Cu")
		(net "P5E_CPU0_P3_TX_DN<4>")
	)
	(arc
		(start 364.546134 -283.32938)
		(mid 364.820717 -283.806138)
		(end 364.546134 -284.282896)
		(width 0.1143)
		(layer "In11.Cu")
		(net "P5E_CPU0_P3_TX_DN<4>")
	)
	(arc
		(start 364.496096 -289.171634)
		(mid 364.340168 -289.475926)
		(end 364.496096 -289.780218)
		(width 0.1143)
		(layer "In11.Cu")
		(net "P5E_CPU0_P3_TX_DN<4>")
	)
	(arc
		(start 365.036862 -295.491408)
		(mid 365.115285 -295.556889)
		(end 365.180626 -295.635426)
		(width 0.1143)
		(layer "In11.Cu")
		(net "P5E_CPU0_P3_TX_DN<4>")
	)
	(arc
		(start 371.793262 -381.987298)
		(mid 371.805539 -382.049021)
		(end 371.840506 -382.101344)
		(width 0.14224)
		(layer "In11.Cu")
		(net "P5E_CPU0_P3_TX_DN<4>")
	)
	(arc
		(start 364.527846 -291.418518)
		(mid 364.808493 -291.905944)
		(end 364.527846 -292.39337)
		(width 0.1143)
		(layer "In11.Cu")
		(net "P5E_CPU0_P3_TX_DN<4>")
	)
	(arc
		(start 364.965996 -280.262076)
		(mid 364.851368 -280.393729)
		(end 364.81004 -280.56332)
		(width 0.1143)
		(layer "In11.Cu")
		(net "P5E_CPU0_P3_TX_DN<4>")
	)
	(arc
		(start 364.81004 -295.145968)
		(mid 364.851295 -295.316939)
		(end 364.965996 -295.45026)
		(width 0.1143)
		(layer "In11.Cu")
		(net "P5E_CPU0_P3_TX_DN<4>")
	)
	(segment
		(start 379.170438 -394.385292)
		(end 379.691138 -394.385292)
		(width 0.127)
		(layer "F.Cu")
		(net "P5E_CPU0_P3_RX_DP<7>")
	)
	(segment
		(start 368.0079 -290.83)
		(end 368.474752 -291.095938)
		(width 0.12954)
		(layer "F.Cu")
		(net "P5E_CPU0_P3_RX_DP<7>")
	)
	(segment
		(start 368.287808 -294.658542)
		(end 368.256058 -294.640254)
		(width 0.1143)
		(layer "In4.Cu")
		(net "P5E_CPU0_P3_RX_DP<7>")
	)
	(segment
		(start 386.92328 -352.528632)
		(end 386.92328 -337.090766)
		(width 0.14224)
		(layer "In4.Cu")
		(net "P5E_CPU0_P3_RX_DP<7>")
	)
	(segment
		(start 381.22479 -317.048896)
		(end 378.962412 -312.815986)
		(width 0.14224)
		(layer "In4.Cu")
		(net "P5E_CPU0_P3_RX_DP<7>")
	)
	(segment
		(start 379.236986 -380.881382)
		(end 378.67209 -380.316486)
		(width 0.14224)
		(layer "In4.Cu")
		(net "P5E_CPU0_P3_RX_DP<7>")
	)
	(segment
		(start 380.302262 -385.309618)
		(end 380.302262 -381.983234)
		(width 0.14224)
		(layer "In4.Cu")
		(net "P5E_CPU0_P3_RX_DP<7>")
	)
	(segment
		(start 368.285268 -294.014906)
		(end 368.28603 -294.014398)
		(width 0.1143)
		(layer "In4.Cu")
		(net "P5E_CPU0_P3_RX_DP<7>")
	)
	(segment
		(start 368.284252 -294.015414)
		(end 368.285268 -294.014906)
		(width 0.1143)
		(layer "In4.Cu")
		(net "P5E_CPU0_P3_RX_DP<7>")
	)
	(segment
		(start 379.960378 -393.930632)
		(end 380.048516 -393.842494)
		(width 0.14224)
		(layer "In4.Cu")
		(net "P5E_CPU0_P3_RX_DP<7>")
	)
	(segment
		(start 368.288316 -293.03853)
		(end 368.287808 -293.03853)
		(width 0.1143)
		(layer "In4.Cu")
		(net "P5E_CPU0_P3_RX_DP<7>")
	)
	(segment
		(start 369.2271 -300.670468)
		(end 368.18316 -298.148756)
		(width 0.14224)
		(layer "In4.Cu")
		(net "P5E_CPU0_P3_RX_DP<7>")
	)
	(segment
		(start 378.626624 -375.623836)
		(end 386.52704 -356.550468)
		(width 0.14224)
		(layer "In4.Cu")
		(net "P5E_CPU0_P3_RX_DP<7>")
	)
	(segment
		(start 368.256058 -294.03167)
		(end 368.281458 -294.016938)
		(width 0.1143)
		(layer "In4.Cu")
		(net "P5E_CPU0_P3_RX_DP<7>")
	)
	(segment
		(start 368.287808 -295.633394)
		(end 368.288316 -295.633394)
		(width 0.1143)
		(layer "In4.Cu")
		(net "P5E_CPU0_P3_RX_DP<7>")
	)
	(segment
		(start 368.287808 -294.013382)
		(end 368.288316 -294.013382)
		(width 0.1143)
		(layer "In4.Cu")
		(net "P5E_CPU0_P3_RX_DP<7>")
	)
	(segment
		(start 378.54128 -380.00051)
		(end 378.54128 -376.05335)
		(width 0.14224)
		(layer "In4.Cu")
		(net "P5E_CPU0_P3_RX_DP<7>")
	)
	(segment
		(start 383.37744 -323.246242)
		(end 381.22479 -317.048896)
		(width 0.14224)
		(layer "In4.Cu")
		(net "P5E_CPU0_P3_RX_DP<7>")
	)
	(segment
		(start 370.305584 -302.267366)
		(end 369.2271 -300.670468)
		(width 0.14224)
		(layer "In4.Cu")
		(net "P5E_CPU0_P3_RX_DP<7>")
	)
	(segment
		(start 386.52704 -356.550468)
		(end 386.92328 -352.528632)
		(width 0.14224)
		(layer "In4.Cu")
		(net "P5E_CPU0_P3_RX_DP<7>")
	)
	(segment
		(start 378.54128 -376.05335)
		(end 378.541534 -376.053604)
		(width 0.14224)
		(layer "In4.Cu")
		(net "P5E_CPU0_P3_RX_DP<7>")
	)
	(segment
		(start 368.100102 -296.388282)
		(end 368.100102 -295.869614)
		(width 0.1143)
		(layer "In4.Cu")
		(net "P5E_CPU0_P3_RX_DP<7>")
	)
	(segment
		(start 385.526534 -329.433428)
		(end 383.37744 -323.246242)
		(width 0.14224)
		(layer "In4.Cu")
		(net "P5E_CPU0_P3_RX_DP<7>")
	)
	(segment
		(start 368.256058 -292.411658)
		(end 368.287808 -292.39337)
		(width 0.1143)
		(layer "In4.Cu")
		(net "P5E_CPU0_P3_RX_DP<7>")
	)
	(segment
		(start 368.256058 -295.651682)
		(end 368.287046 -295.633902)
		(width 0.1143)
		(layer "In4.Cu")
		(net "P5E_CPU0_P3_RX_DP<7>")
	)
	(segment
		(start 368.288316 -294.658542)
		(end 368.287808 -294.658542)
		(width 0.1143)
		(layer "In4.Cu")
		(net "P5E_CPU0_P3_RX_DP<7>")
	)
	(segment
		(start 368.28603 -294.014398)
		(end 368.287046 -294.01389)
		(width 0.1143)
		(layer "In4.Cu")
		(net "P5E_CPU0_P3_RX_DP<7>")
	)
	(segment
		(start 379.953266 -381.326898)
		(end 379.734826 -381.179832)
		(width 0.14224)
		(layer "In4.Cu")
		(net "P5E_CPU0_P3_RX_DP<7>")
	)
	(segment
		(start 368.28349 -294.015922)
		(end 368.284252 -294.015414)
		(width 0.1143)
		(layer "In4.Cu")
		(net "P5E_CPU0_P3_RX_DP<7>")
	)
	(segment
		(start 380.040388 -390.64438)
		(end 380.302262 -385.309618)
		(width 0.14224)
		(layer "In4.Cu")
		(net "P5E_CPU0_P3_RX_DP<7>")
	)
	(segment
		(start 368.17681 -291.095938)
		(end 368.474752 -291.095938)
		(width 0.1143)
		(layer "In4.Cu")
		(net "P5E_CPU0_P3_RX_DP<7>")
	)
	(segment
		(start 368.145822 -296.434002)
		(end 368.100102 -296.388282)
		(width 0.1143)
		(layer "In4.Cu")
		(net "P5E_CPU0_P3_RX_DP<7>")
	)
	(segment
		(start 386.92328 -337.090766)
		(end 385.59359 -329.689714)
		(width 0.14224)
		(layer "In4.Cu")
		(net "P5E_CPU0_P3_RX_DP<7>")
	)
	(segment
		(start 368.145822 -297.960542)
		(end 368.145822 -296.46245)
		(width 0.14224)
		(layer "In4.Cu")
		(net "P5E_CPU0_P3_RX_DP<7>")
	)
	(segment
		(start 368.287046 -295.633902)
		(end 368.287808 -295.633394)
		(width 0.1143)
		(layer "In4.Cu")
		(net "P5E_CPU0_P3_RX_DP<7>")
	)
	(segment
		(start 379.73254 -393.113006)
		(end 379.735588 -392.7348)
		(width 0.14224)
		(layer "In4.Cu")
		(net "P5E_CPU0_P3_RX_DP<7>")
	)
	(segment
		(start 368.10696 -291.165788)
		(end 368.17681 -291.095938)
		(width 0.1143)
		(layer "In4.Cu")
		(net "P5E_CPU0_P3_RX_DP<7>")
	)
	(segment
		(start 368.287808 -293.03853)
		(end 368.256058 -293.020242)
		(width 0.1143)
		(layer "In4.Cu")
		(net "P5E_CPU0_P3_RX_DP<7>")
	)
	(segment
		(start 379.691138 -394.385292)
		(end 379.786134 -394.031216)
		(width 0.14224)
		(layer "In4.Cu")
		(net "P5E_CPU0_P3_RX_DP<7>")
	)
	(segment
		(start 368.287046 -294.01389)
		(end 368.287808 -294.013382)
		(width 0.1143)
		(layer "In4.Cu")
		(net "P5E_CPU0_P3_RX_DP<7>")
	)
	(segment
		(start 379.735588 -392.7348)
		(end 380.040388 -392.430254)
		(width 0.14224)
		(layer "In4.Cu")
		(net "P5E_CPU0_P3_RX_DP<7>")
	)
	(segment
		(start 380.040388 -392.430254)
		(end 380.040388 -390.64438)
		(width 0.14224)
		(layer "In4.Cu")
		(net "P5E_CPU0_P3_RX_DP<7>")
	)
	(segment
		(start 368.287808 -291.418518)
		(end 368.256058 -291.40023)
		(width 0.1143)
		(layer "In4.Cu")
		(net "P5E_CPU0_P3_RX_DP<7>")
	)
	(segment
		(start 380.048516 -393.428982)
		(end 379.73254 -393.113006)
		(width 0.14224)
		(layer "In4.Cu")
		(net "P5E_CPU0_P3_RX_DP<7>")
	)
	(segment
		(start 385.59359 -329.689714)
		(end 385.526534 -329.433428)
		(width 0.14224)
		(layer "In4.Cu")
		(net "P5E_CPU0_P3_RX_DP<7>")
	)
	(segment
		(start 379.786134 -394.031216)
		(end 379.960378 -393.930632)
		(width 0.14224)
		(layer "In4.Cu")
		(net "P5E_CPU0_P3_RX_DP<7>")
	)
	(segment
		(start 368.145822 -296.46245)
		(end 368.145822 -296.434002)
		(width 0.1143)
		(layer "In4.Cu")
		(net "P5E_CPU0_P3_RX_DP<7>")
	)
	(segment
		(start 380.048516 -393.842494)
		(end 380.048516 -393.428982)
		(width 0.14224)
		(layer "In4.Cu")
		(net "P5E_CPU0_P3_RX_DP<7>")
	)
	(segment
		(start 368.281458 -294.016938)
		(end 368.28349 -294.015922)
		(width 0.1143)
		(layer "In4.Cu")
		(net "P5E_CPU0_P3_RX_DP<7>")
	)
	(segment
		(start 378.962412 -312.815986)
		(end 370.305584 -302.267366)
		(width 0.14224)
		(layer "In4.Cu")
		(net "P5E_CPU0_P3_RX_DP<7>")
	)
	(arc
		(start 368.307874 -294.67048)
		(mid 368.298155 -294.664413)
		(end 368.288316 -294.658542)
		(width 0.1143)
		(layer "In4.Cu")
		(net "P5E_CPU0_P3_RX_DP<7>")
	)
	(arc
		(start 368.256058 -291.40023)
		(mid 368.158923 -291.297361)
		(end 368.10696 -291.165788)
		(width 0.1143)
		(layer "In4.Cu")
		(net "P5E_CPU0_P3_RX_DP<7>")
	)
	(arc
		(start 368.100102 -295.869614)
		(mid 368.158227 -295.746447)
		(end 368.256058 -295.651682)
		(width 0.1143)
		(layer "In4.Cu")
		(net "P5E_CPU0_P3_RX_DP<7>")
	)
	(arc
		(start 368.288316 -294.013382)
		(mid 368.56872 -293.537413)
		(end 368.307874 -293.050468)
		(width 0.1143)
		(layer "In4.Cu")
		(net "P5E_CPU0_P3_RX_DP<7>")
	)
	(arc
		(start 378.67209 -380.316486)
		(mid 378.575277 -380.171501)
		(end 378.54128 -380.00051)
		(width 0.14224)
		(layer "In4.Cu")
		(net "P5E_CPU0_P3_RX_DP<7>")
	)
	(arc
		(start 379.734826 -381.179832)
		(mid 379.616523 -381.108746)
		(end 379.491494 -381.050292)
		(width 0.14224)
		(layer "In4.Cu")
		(net "P5E_CPU0_P3_RX_DP<7>")
	)
	(arc
		(start 368.287808 -292.39337)
		(mid 368.568455 -291.905944)
		(end 368.287808 -291.418518)
		(width 0.1143)
		(layer "In4.Cu")
		(net "P5E_CPU0_P3_RX_DP<7>")
	)
	(arc
		(start 368.307874 -293.050468)
		(mid 368.298155 -293.044401)
		(end 368.288316 -293.03853)
		(width 0.1143)
		(layer "In4.Cu")
		(net "P5E_CPU0_P3_RX_DP<7>")
	)
	(arc
		(start 368.256058 -293.020242)
		(mid 368.10013 -292.71595)
		(end 368.256058 -292.411658)
		(width 0.1143)
		(layer "In4.Cu")
		(net "P5E_CPU0_P3_RX_DP<7>")
	)
	(arc
		(start 368.18316 -298.148756)
		(mid 368.155235 -298.056486)
		(end 368.145822 -297.960542)
		(width 0.14224)
		(layer "In4.Cu")
		(net "P5E_CPU0_P3_RX_DP<7>")
	)
	(arc
		(start 368.256058 -294.640254)
		(mid 368.10013 -294.335962)
		(end 368.256058 -294.03167)
		(width 0.1143)
		(layer "In4.Cu")
		(net "P5E_CPU0_P3_RX_DP<7>")
	)
	(arc
		(start 379.491494 -381.050292)
		(mid 379.355764 -380.978612)
		(end 379.236986 -380.881382)
		(width 0.14224)
		(layer "In4.Cu")
		(net "P5E_CPU0_P3_RX_DP<7>")
	)
	(arc
		(start 378.541534 -376.053604)
		(mid 378.562968 -375.834542)
		(end 378.626624 -375.623836)
		(width 0.14224)
		(layer "In4.Cu")
		(net "P5E_CPU0_P3_RX_DP<7>")
	)
	(arc
		(start 368.288316 -295.633394)
		(mid 368.56872 -295.157425)
		(end 368.307874 -294.67048)
		(width 0.1143)
		(layer "In4.Cu")
		(net "P5E_CPU0_P3_RX_DP<7>")
	)
	(arc
		(start 380.302262 -381.983234)
		(mid 380.209613 -381.611525)
		(end 379.953266 -381.326898)
		(width 0.14224)
		(layer "In4.Cu")
		(net "P5E_CPU0_P3_RX_DP<7>")
	)
	(segment
		(start 368.0079 -287.59023)
		(end 368.474752 -287.856168)
		(width 0.12954)
		(layer "F.Cu")
		(net "P5E_CPU0_P3_RX_DP<6>")
	)
	(segment
		(start 377.970542 -394.385292)
		(end 378.491242 -394.385292)
		(width 0.127)
		(layer "F.Cu")
		(net "P5E_CPU0_P3_RX_DP<6>")
	)
	(segment
		(start 367.350548 -291.420042)
		(end 367.34877 -291.419026)
		(width 0.1143)
		(layer "In4.Cu")
		(net "P5E_CPU0_P3_RX_DP<6>")
	)
	(segment
		(start 368.17681 -287.856168)
		(end 368.474752 -287.856168)
		(width 0.1143)
		(layer "In4.Cu")
		(net "P5E_CPU0_P3_RX_DP<6>")
	)
	(segment
		(start 367.341912 -291.415216)
		(end 367.34115 -291.414708)
		(width 0.1143)
		(layer "In4.Cu")
		(net "P5E_CPU0_P3_RX_DP<6>")
	)
	(segment
		(start 376.89282 -382.337564)
		(end 376.89282 -375.712482)
		(width 0.14224)
		(layer "In4.Cu")
		(net "P5E_CPU0_P3_RX_DP<6>")
	)
	(segment
		(start 367.33988 -289.157918)
		(end 367.34115 -289.157156)
		(width 0.1143)
		(layer "In4.Cu")
		(net "P5E_CPU0_P3_RX_DP<6>")
	)
	(segment
		(start 367.316004 -294.03167)
		(end 367.337594 -294.019224)
		(width 0.1143)
		(layer "In4.Cu")
		(net "P5E_CPU0_P3_RX_DP<6>")
	)
	(segment
		(start 367.316004 -289.171634)
		(end 367.337594 -289.159188)
		(width 0.1143)
		(layer "In4.Cu")
		(net "P5E_CPU0_P3_RX_DP<6>")
	)
	(segment
		(start 378.491242 -394.385292)
		(end 378.586238 -394.031216)
		(width 0.14224)
		(layer "In4.Cu")
		(net "P5E_CPU0_P3_RX_DP<6>")
	)
	(segment
		(start 367.785142 -288.36239)
		(end 367.817654 -288.343594)
		(width 0.1143)
		(layer "In4.Cu")
		(net "P5E_CPU0_P3_RX_DP<6>")
	)
	(segment
		(start 367.34115 -292.39718)
		(end 367.341912 -292.396672)
		(width 0.1143)
		(layer "In4.Cu")
		(net "P5E_CPU0_P3_RX_DP<6>")
	)
	(segment
		(start 367.37925 -291.436806)
		(end 367.354612 -291.422582)
		(width 0.1143)
		(layer "In4.Cu")
		(net "P5E_CPU0_P3_RX_DP<6>")
	)
	(segment
		(start 367.341912 -294.016684)
		(end 367.343436 -294.015922)
		(width 0.1143)
		(layer "In4.Cu")
		(net "P5E_CPU0_P3_RX_DP<6>")
	)
	(segment
		(start 367.341912 -289.156648)
		(end 367.343436 -289.155886)
		(width 0.1143)
		(layer "In4.Cu")
		(net "P5E_CPU0_P3_RX_DP<6>")
	)
	(segment
		(start 378.212858 -313.394344)
		(end 378.199904 -313.370214)
		(width 0.14224)
		(layer "In4.Cu")
		(net "P5E_CPU0_P3_RX_DP<6>")
	)
	(segment
		(start 378.212858 -313.394598)
		(end 378.212858 -313.394344)
		(width 0.14224)
		(layer "In4.Cu")
		(net "P5E_CPU0_P3_RX_DP<6>")
	)
	(segment
		(start 378.836428 -392.381994)
		(end 378.822712 -390.70788)
		(width 0.14224)
		(layer "In4.Cu")
		(net "P5E_CPU0_P3_RX_DP<6>")
	)
	(segment
		(start 366.84712 -289.981132)
		(end 366.8776 -289.963352)
		(width 0.1143)
		(layer "In4.Cu")
		(net "P5E_CPU0_P3_RX_DP<6>")
	)
	(segment
		(start 384.685794 -329.909932)
		(end 380.313946 -317.32474)
		(width 0.14224)
		(layer "In4.Cu")
		(net "P5E_CPU0_P3_RX_DP<6>")
	)
	(segment
		(start 367.34877 -294.012874)
		(end 367.350294 -294.011858)
		(width 0.1143)
		(layer "In4.Cu")
		(net "P5E_CPU0_P3_RX_DP<6>")
	)
	(segment
		(start 378.822712 -390.70788)
		(end 377.55703 -384.342132)
		(width 0.14224)
		(layer "In4.Cu")
		(net "P5E_CPU0_P3_RX_DP<6>")
	)
	(segment
		(start 367.341912 -292.396672)
		(end 367.343436 -292.39591)
		(width 0.1143)
		(layer "In4.Cu")
		(net "P5E_CPU0_P3_RX_DP<6>")
	)
	(segment
		(start 367.353088 -291.421566)
		(end 367.352072 -291.421058)
		(width 0.1143)
		(layer "In4.Cu")
		(net "P5E_CPU0_P3_RX_DP<6>")
	)
	(segment
		(start 367.34877 -289.152838)
		(end 367.350294 -289.151822)
		(width 0.1143)
		(layer "In4.Cu")
		(net "P5E_CPU0_P3_RX_DP<6>")
	)
	(segment
		(start 367.344198 -291.416486)
		(end 367.343436 -291.415978)
		(width 0.1143)
		(layer "In4.Cu")
		(net "P5E_CPU0_P3_RX_DP<6>")
	)
	(segment
		(start 367.316004 -292.411658)
		(end 367.337594 -292.399212)
		(width 0.1143)
		(layer "In4.Cu")
		(net "P5E_CPU0_P3_RX_DP<6>")
	)
	(segment
		(start 367.34115 -289.157156)
		(end 367.341912 -289.156648)
		(width 0.1143)
		(layer "In4.Cu")
		(net "P5E_CPU0_P3_RX_DP<6>")
	)
	(segment
		(start 367.354866 -289.149282)
		(end 367.38687 -289.130486)
		(width 0.1143)
		(layer "In4.Cu")
		(net "P5E_CPU0_P3_RX_DP<6>")
	)
	(segment
		(start 367.338864 -291.413438)
		(end 367.306352 -291.394388)
		(width 0.1143)
		(layer "In4.Cu")
		(net "P5E_CPU0_P3_RX_DP<6>")
	)
	(segment
		(start 367.34115 -291.414708)
		(end 367.338864 -291.413438)
		(width 0.1143)
		(layer "In4.Cu")
		(net "P5E_CPU0_P3_RX_DP<6>")
	)
	(segment
		(start 367.380012 -291.437314)
		(end 367.37925 -291.436806)
		(width 0.1143)
		(layer "In4.Cu")
		(net "P5E_CPU0_P3_RX_DP<6>")
	)
	(segment
		(start 367.350294 -294.011858)
		(end 367.354866 -294.009318)
		(width 0.1143)
		(layer "In4.Cu")
		(net "P5E_CPU0_P3_RX_DP<6>")
	)
	(segment
		(start 385.9911 -337.177126)
		(end 384.685794 -329.909932)
		(width 0.14224)
		(layer "In4.Cu")
		(net "P5E_CPU0_P3_RX_DP<6>")
	)
	(segment
		(start 367.172748 -291.163248)
		(end 367.172748 -291.105336)
		(width 0.1143)
		(layer "In4.Cu")
		(net "P5E_CPU0_P3_RX_DP<6>")
	)
	(segment
		(start 367.337594 -289.159188)
		(end 367.338356 -289.15868)
		(width 0.1143)
		(layer "In4.Cu")
		(net "P5E_CPU0_P3_RX_DP<6>")
	)
	(segment
		(start 367.354612 -291.422582)
		(end 367.353088 -291.421566)
		(width 0.1143)
		(layer "In4.Cu")
		(net "P5E_CPU0_P3_RX_DP<6>")
	)
	(segment
		(start 367.205514 -296.456862)
		(end 367.205514 -296.428414)
		(width 0.1143)
		(layer "In4.Cu")
		(net "P5E_CPU0_P3_RX_DP<6>")
	)
	(segment
		(start 367.347754 -289.153346)
		(end 367.34877 -289.152838)
		(width 0.1143)
		(layer "In4.Cu")
		(net "P5E_CPU0_P3_RX_DP<6>")
	)
	(segment
		(start 385.9911 -352.44913)
		(end 385.9911 -337.177126)
		(width 0.14224)
		(layer "In4.Cu")
		(net "P5E_CPU0_P3_RX_DP<6>")
	)
	(segment
		(start 367.347754 -294.658542)
		(end 367.316004 -294.640254)
		(width 0.1143)
		(layer "In4.Cu")
		(net "P5E_CPU0_P3_RX_DP<6>")
	)
	(segment
		(start 367.346992 -291.41801)
		(end 367.344198 -291.416486)
		(width 0.1143)
		(layer "In4.Cu")
		(net "P5E_CPU0_P3_RX_DP<6>")
	)
	(segment
		(start 367.354866 -294.009318)
		(end 367.38687 -293.990522)
		(width 0.1143)
		(layer "In4.Cu")
		(net "P5E_CPU0_P3_RX_DP<6>")
	)
	(segment
		(start 366.89284 -290.617402)
		(end 366.846104 -290.58997)
		(width 0.1143)
		(layer "In4.Cu")
		(net "P5E_CPU0_P3_RX_DP<6>")
	)
	(segment
		(start 367.337594 -292.399212)
		(end 367.338356 -292.398704)
		(width 0.1143)
		(layer "In4.Cu")
		(net "P5E_CPU0_P3_RX_DP<6>")
	)
	(segment
		(start 368.094006 -287.938972)
		(end 368.17681 -287.856168)
		(width 0.1143)
		(layer "In4.Cu")
		(net "P5E_CPU0_P3_RX_DP<6>")
	)
	(segment
		(start 367.33988 -294.017954)
		(end 367.34115 -294.017192)
		(width 0.1143)
		(layer "In4.Cu")
		(net "P5E_CPU0_P3_RX_DP<6>")
	)
	(segment
		(start 367.38687 -291.441378)
		(end 367.380012 -291.437314)
		(width 0.1143)
		(layer "In4.Cu")
		(net "P5E_CPU0_P3_RX_DP<6>")
	)
	(segment
		(start 367.338356 -292.398704)
		(end 367.33988 -292.397942)
		(width 0.1143)
		(layer "In4.Cu")
		(net "P5E_CPU0_P3_RX_DP<6>")
	)
	(segment
		(start 377.100592 -374.686576)
		(end 385.564634 -356.209854)
		(width 0.14224)
		(layer "In4.Cu")
		(net "P5E_CPU0_P3_RX_DP<6>")
	)
	(segment
		(start 367.34877 -294.65905)
		(end 367.347754 -294.658542)
		(width 0.1143)
		(layer "In4.Cu")
		(net "P5E_CPU0_P3_RX_DP<6>")
	)
	(segment
		(start 367.31575 -295.651682)
		(end 367.38814 -295.609518)
		(width 0.1143)
		(layer "In4.Cu")
		(net "P5E_CPU0_P3_RX_DP<6>")
	)
	(segment
		(start 367.817654 -288.343594)
		(end 367.85677 -288.320734)
		(width 0.1143)
		(layer "In4.Cu")
		(net "P5E_CPU0_P3_RX_DP<6>")
	)
	(segment
		(start 378.532644 -393.113006)
		(end 378.535946 -392.682476)
		(width 0.14224)
		(layer "In4.Cu")
		(net "P5E_CPU0_P3_RX_DP<6>")
	)
	(segment
		(start 368.383058 -301.09033)
		(end 367.215166 -298.253912)
		(width 0.14224)
		(layer "In4.Cu")
		(net "P5E_CPU0_P3_RX_DP<6>")
	)
	(segment
		(start 367.344198 -292.395402)
		(end 367.346992 -292.393878)
		(width 0.1143)
		(layer "In4.Cu")
		(net "P5E_CPU0_P3_RX_DP<6>")
	)
	(segment
		(start 367.350294 -294.660066)
		(end 367.34877 -294.65905)
		(width 0.1143)
		(layer "In4.Cu")
		(net "P5E_CPU0_P3_RX_DP<6>")
	)
	(segment
		(start 380.313946 -317.32474)
		(end 378.212858 -313.394598)
		(width 0.14224)
		(layer "In4.Cu")
		(net "P5E_CPU0_P3_RX_DP<6>")
	)
	(segment
		(start 367.347754 -294.013382)
		(end 367.34877 -294.012874)
		(width 0.1143)
		(layer "In4.Cu")
		(net "P5E_CPU0_P3_RX_DP<6>")
	)
	(segment
		(start 367.347754 -292.39337)
		(end 367.34877 -292.392862)
		(width 0.1143)
		(layer "In4.Cu")
		(net "P5E_CPU0_P3_RX_DP<6>")
	)
	(segment
		(start 367.343436 -289.155886)
		(end 367.344198 -289.155378)
		(width 0.1143)
		(layer "In4.Cu")
		(net "P5E_CPU0_P3_RX_DP<6>")
	)
	(segment
		(start 377.269756 -383.446274)
		(end 377.005342 -382.860042)
		(width 0.14224)
		(layer "In4.Cu")
		(net "P5E_CPU0_P3_RX_DP<6>")
	)
	(segment
		(start 367.352072 -291.421058)
		(end 367.350548 -291.420042)
		(width 0.1143)
		(layer "In4.Cu")
		(net "P5E_CPU0_P3_RX_DP<6>")
	)
	(segment
		(start 378.760482 -393.930632)
		(end 378.84862 -393.842494)
		(width 0.14224)
		(layer "In4.Cu")
		(net "P5E_CPU0_P3_RX_DP<6>")
	)
	(segment
		(start 367.159794 -296.382694)
		(end 367.159794 -295.954704)
		(width 0.1143)
		(layer "In4.Cu")
		(net "P5E_CPU0_P3_RX_DP<6>")
	)
	(segment
		(start 367.344198 -289.155378)
		(end 367.346992 -289.153854)
		(width 0.1143)
		(layer "In4.Cu")
		(net "P5E_CPU0_P3_RX_DP<6>")
	)
	(segment
		(start 367.34877 -291.419026)
		(end 367.347754 -291.418518)
		(width 0.1143)
		(layer "In4.Cu")
		(net "P5E_CPU0_P3_RX_DP<6>")
	)
	(segment
		(start 367.338356 -294.018716)
		(end 367.33988 -294.017954)
		(width 0.1143)
		(layer "In4.Cu")
		(net "P5E_CPU0_P3_RX_DP<6>")
	)
	(segment
		(start 367.338356 -289.15868)
		(end 367.33988 -289.157918)
		(width 0.1143)
		(layer "In4.Cu")
		(net "P5E_CPU0_P3_RX_DP<6>")
	)
	(segment
		(start 367.33988 -292.397942)
		(end 367.34115 -292.39718)
		(width 0.1143)
		(layer "In4.Cu")
		(net "P5E_CPU0_P3_RX_DP<6>")
	)
	(segment
		(start 369.47856 -302.732948)
		(end 368.383058 -301.09033)
		(width 0.14224)
		(layer "In4.Cu")
		(net "P5E_CPU0_P3_RX_DP<6>")
	)
	(segment
		(start 367.350294 -293.040054)
		(end 367.34877 -293.039038)
		(width 0.1143)
		(layer "In4.Cu")
		(net "P5E_CPU0_P3_RX_DP<6>")
	)
	(segment
		(start 367.354866 -292.389306)
		(end 367.38687 -292.37051)
		(width 0.1143)
		(layer "In4.Cu")
		(net "P5E_CPU0_P3_RX_DP<6>")
	)
	(segment
		(start 367.38687 -294.681402)
		(end 367.350294 -294.660066)
		(width 0.1143)
		(layer "In4.Cu")
		(net "P5E_CPU0_P3_RX_DP<6>")
	)
	(segment
		(start 367.350294 -292.391846)
		(end 367.354866 -292.389306)
		(width 0.1143)
		(layer "In4.Cu")
		(net "P5E_CPU0_P3_RX_DP<6>")
	)
	(segment
		(start 367.347754 -293.03853)
		(end 367.316004 -293.020242)
		(width 0.1143)
		(layer "In4.Cu")
		(net "P5E_CPU0_P3_RX_DP<6>")
	)
	(segment
		(start 367.337594 -294.019224)
		(end 367.338356 -294.018716)
		(width 0.1143)
		(layer "In4.Cu")
		(net "P5E_CPU0_P3_RX_DP<6>")
	)
	(segment
		(start 378.84862 -393.428982)
		(end 378.532644 -393.113006)
		(width 0.14224)
		(layer "In4.Cu")
		(net "P5E_CPU0_P3_RX_DP<6>")
	)
	(segment
		(start 367.34115 -294.017192)
		(end 367.341912 -294.016684)
		(width 0.1143)
		(layer "In4.Cu")
		(net "P5E_CPU0_P3_RX_DP<6>")
	)
	(segment
		(start 378.586238 -394.031216)
		(end 378.760482 -393.930632)
		(width 0.14224)
		(layer "In4.Cu")
		(net "P5E_CPU0_P3_RX_DP<6>")
	)
	(segment
		(start 367.343436 -292.39591)
		(end 367.344198 -292.395402)
		(width 0.1143)
		(layer "In4.Cu")
		(net "P5E_CPU0_P3_RX_DP<6>")
	)
	(segment
		(start 367.343436 -291.415978)
		(end 367.341912 -291.415216)
		(width 0.1143)
		(layer "In4.Cu")
		(net "P5E_CPU0_P3_RX_DP<6>")
	)
	(segment
		(start 366.8776 -289.963352)
		(end 366.916716 -289.940492)
		(width 0.1143)
		(layer "In4.Cu")
		(net "P5E_CPU0_P3_RX_DP<6>")
	)
	(segment
		(start 367.630202 -295.146476)
		(end 367.630202 -295.145968)
		(width 0.1143)
		(layer "In4.Cu")
		(net "P5E_CPU0_P3_RX_DP<6>")
	)
	(segment
		(start 367.205514 -296.428414)
		(end 367.159794 -296.382694)
		(width 0.1143)
		(layer "In4.Cu")
		(net "P5E_CPU0_P3_RX_DP<6>")
	)
	(segment
		(start 367.34877 -293.039038)
		(end 367.347754 -293.03853)
		(width 0.1143)
		(layer "In4.Cu")
		(net "P5E_CPU0_P3_RX_DP<6>")
	)
	(segment
		(start 367.347754 -291.418518)
		(end 367.346992 -291.41801)
		(width 0.1143)
		(layer "In4.Cu")
		(net "P5E_CPU0_P3_RX_DP<6>")
	)
	(segment
		(start 367.346992 -292.393878)
		(end 367.347754 -292.39337)
		(width 0.1143)
		(layer "In4.Cu")
		(net "P5E_CPU0_P3_RX_DP<6>")
	)
	(segment
		(start 367.38687 -293.06139)
		(end 367.350294 -293.040054)
		(width 0.1143)
		(layer "In4.Cu")
		(net "P5E_CPU0_P3_RX_DP<6>")
	)
	(segment
		(start 367.34877 -292.392862)
		(end 367.350294 -292.391846)
		(width 0.1143)
		(layer "In4.Cu")
		(net "P5E_CPU0_P3_RX_DP<6>")
	)
	(segment
		(start 367.344198 -294.015414)
		(end 367.346992 -294.01389)
		(width 0.1143)
		(layer "In4.Cu")
		(net "P5E_CPU0_P3_RX_DP<6>")
	)
	(segment
		(start 385.599432 -356.083362)
		(end 385.9911 -352.44913)
		(width 0.14224)
		(layer "In4.Cu")
		(net "P5E_CPU0_P3_RX_DP<6>")
	)
	(segment
		(start 367.343436 -294.015922)
		(end 367.344198 -294.015414)
		(width 0.1143)
		(layer "In4.Cu")
		(net "P5E_CPU0_P3_RX_DP<6>")
	)
	(segment
		(start 378.535946 -392.682476)
		(end 378.836428 -392.381994)
		(width 0.14224)
		(layer "In4.Cu")
		(net "P5E_CPU0_P3_RX_DP<6>")
	)
	(segment
		(start 378.84862 -393.842494)
		(end 378.84862 -393.428982)
		(width 0.14224)
		(layer "In4.Cu")
		(net "P5E_CPU0_P3_RX_DP<6>")
	)
	(segment
		(start 378.199904 -313.370214)
		(end 369.47856 -302.732948)
		(width 0.14224)
		(layer "In4.Cu")
		(net "P5E_CPU0_P3_RX_DP<6>")
	)
	(segment
		(start 367.205514 -298.205398)
		(end 367.205514 -296.456862)
		(width 0.14224)
		(layer "In4.Cu")
		(net "P5E_CPU0_P3_RX_DP<6>")
	)
	(segment
		(start 367.346992 -294.01389)
		(end 367.347754 -294.013382)
		(width 0.1143)
		(layer "In4.Cu")
		(net "P5E_CPU0_P3_RX_DP<6>")
	)
	(segment
		(start 367.346992 -289.153854)
		(end 367.347754 -289.153346)
		(width 0.1143)
		(layer "In4.Cu")
		(net "P5E_CPU0_P3_RX_DP<6>")
	)
	(segment
		(start 367.350294 -289.151822)
		(end 367.354866 -289.149282)
		(width 0.1143)
		(layer "In4.Cu")
		(net "P5E_CPU0_P3_RX_DP<6>")
	)
	(arc
		(start 367.215166 -298.253912)
		(mid 367.207946 -298.230129)
		(end 367.205514 -298.205398)
		(width 0.14224)
		(layer "In4.Cu")
		(net "P5E_CPU0_P3_RX_DP<6>")
	)
	(arc
		(start 367.38687 -289.130486)
		(mid 367.565683 -288.928136)
		(end 367.630202 -288.66592)
		(width 0.1143)
		(layer "In4.Cu")
		(net "P5E_CPU0_P3_RX_DP<6>")
	)
	(arc
		(start 367.630202 -288.66592)
		(mid 367.671168 -288.495514)
		(end 367.785142 -288.36239)
		(width 0.1143)
		(layer "In4.Cu")
		(net "P5E_CPU0_P3_RX_DP<6>")
	)
	(arc
		(start 367.306352 -291.394388)
		(mid 367.20862 -291.296698)
		(end 367.172748 -291.163248)
		(width 0.1143)
		(layer "In4.Cu")
		(net "P5E_CPU0_P3_RX_DP<6>")
	)
	(arc
		(start 376.963432 -375.079514)
		(mid 377.022802 -374.87983)
		(end 377.100592 -374.686576)
		(width 0.14224)
		(layer "In4.Cu")
		(net "P5E_CPU0_P3_RX_DP<6>")
	)
	(arc
		(start 367.160048 -289.475926)
		(mid 367.201303 -289.304955)
		(end 367.316004 -289.171634)
		(width 0.1143)
		(layer "In4.Cu")
		(net "P5E_CPU0_P3_RX_DP<6>")
	)
	(arc
		(start 367.316004 -294.640254)
		(mid 367.160076 -294.335962)
		(end 367.316004 -294.03167)
		(width 0.1143)
		(layer "In4.Cu")
		(net "P5E_CPU0_P3_RX_DP<6>")
	)
	(arc
		(start 367.38814 -295.609518)
		(mid 367.565983 -295.407696)
		(end 367.630202 -295.146476)
		(width 0.1143)
		(layer "In4.Cu")
		(net "P5E_CPU0_P3_RX_DP<6>")
	)
	(arc
		(start 367.159794 -295.954704)
		(mid 367.159793 -295.953688)
		(end 367.159794 -295.952672)
		(width 0.1143)
		(layer "In4.Cu")
		(net "P5E_CPU0_P3_RX_DP<6>")
	)
	(arc
		(start 385.564634 -356.209854)
		(mid 385.587153 -356.148015)
		(end 385.599432 -356.083362)
		(width 0.14224)
		(layer "In4.Cu")
		(net "P5E_CPU0_P3_RX_DP<6>")
	)
	(arc
		(start 376.89282 -375.712482)
		(mid 376.910554 -375.394038)
		(end 376.963432 -375.079514)
		(width 0.14224)
		(layer "In4.Cu")
		(net "P5E_CPU0_P3_RX_DP<6>")
	)
	(arc
		(start 367.630202 -295.145968)
		(mid 367.565687 -294.883749)
		(end 367.38687 -294.681402)
		(width 0.1143)
		(layer "In4.Cu")
		(net "P5E_CPU0_P3_RX_DP<6>")
	)
	(arc
		(start 366.846104 -290.58997)
		(mid 366.789075 -290.539343)
		(end 366.743488 -290.47821)
		(width 0.1143)
		(layer "In4.Cu")
		(net "P5E_CPU0_P3_RX_DP<6>")
	)
	(arc
		(start 377.005342 -382.860042)
		(mid 376.9213 -382.604788)
		(end 376.89282 -382.337564)
		(width 0.14224)
		(layer "In4.Cu")
		(net "P5E_CPU0_P3_RX_DP<6>")
	)
	(arc
		(start 366.916716 -289.940492)
		(mid 367.095529 -289.738142)
		(end 367.160048 -289.475926)
		(width 0.1143)
		(layer "In4.Cu")
		(net "P5E_CPU0_P3_RX_DP<6>")
	)
	(arc
		(start 367.38687 -293.990522)
		(mid 367.630197 -293.525956)
		(end 367.38687 -293.06139)
		(width 0.1143)
		(layer "In4.Cu")
		(net "P5E_CPU0_P3_RX_DP<6>")
	)
	(arc
		(start 367.85677 -288.320734)
		(mid 368.008757 -288.164226)
		(end 368.090196 -287.961832)
		(width 0.1143)
		(layer "In4.Cu")
		(net "P5E_CPU0_P3_RX_DP<6>")
	)
	(arc
		(start 366.743488 -290.47821)
		(mid 366.69821 -290.209463)
		(end 366.84712 -289.981132)
		(width 0.1143)
		(layer "In4.Cu")
		(net "P5E_CPU0_P3_RX_DP<6>")
	)
	(arc
		(start 367.159794 -295.952672)
		(mid 367.205086 -295.785239)
		(end 367.31575 -295.651682)
		(width 0.1143)
		(layer "In4.Cu")
		(net "P5E_CPU0_P3_RX_DP<6>")
	)
	(arc
		(start 367.316004 -293.020242)
		(mid 367.160076 -292.71595)
		(end 367.316004 -292.411658)
		(width 0.1143)
		(layer "In4.Cu")
		(net "P5E_CPU0_P3_RX_DP<6>")
	)
	(arc
		(start 367.38687 -292.37051)
		(mid 367.630197 -291.905944)
		(end 367.38687 -291.441378)
		(width 0.1143)
		(layer "In4.Cu")
		(net "P5E_CPU0_P3_RX_DP<6>")
	)
	(arc
		(start 367.172748 -291.105336)
		(mid 367.097795 -290.824087)
		(end 366.89284 -290.617402)
		(width 0.1143)
		(layer "In4.Cu")
		(net "P5E_CPU0_P3_RX_DP<6>")
	)
	(arc
		(start 377.55703 -384.342132)
		(mid 377.438872 -383.886034)
		(end 377.269756 -383.446274)
		(width 0.14224)
		(layer "In4.Cu")
		(net "P5E_CPU0_P3_RX_DP<6>")
	)
	(arc
		(start 368.090196 -287.961832)
		(mid 368.092219 -287.950422)
		(end 368.094006 -287.938972)
		(width 0.1143)
		(layer "In4.Cu")
		(net "P5E_CPU0_P3_RX_DP<6>")
	)
	(segment
		(start 376.770646 -394.385292)
		(end 377.291346 -394.385292)
		(width 0.127)
		(layer "F.Cu")
		(net "P5E_CPU0_P3_RX_DP<5>")
	)
	(segment
		(start 365.187992 -289.209988)
		(end 365.654844 -289.475926)
		(width 0.12954)
		(layer "F.Cu")
		(net "P5E_CPU0_P3_RX_DP<5>")
	)
	(segment
		(start 366.4077 -294.658542)
		(end 366.37722 -294.640762)
		(width 0.1143)
		(layer "In4.Cu")
		(net "P5E_CPU0_P3_RX_DP<5>")
	)
	(segment
		(start 365.970058 -290.627308)
		(end 365.969296 -290.6268)
		(width 0.1143)
		(layer "In4.Cu")
		(net "P5E_CPU0_P3_RX_DP<5>")
	)
	(segment
		(start 366.220248 -296.284142)
		(end 366.220248 -295.955974)
		(width 0.1143)
		(layer "In4.Cu")
		(net "P5E_CPU0_P3_RX_DP<5>")
	)
	(segment
		(start 365.944658 -290.612576)
		(end 365.943134 -290.61156)
		(width 0.1143)
		(layer "In4.Cu")
		(net "P5E_CPU0_P3_RX_DP<5>")
	)
	(segment
		(start 385.05892 -337.263232)
		(end 383.7813 -330.150724)
		(width 0.14224)
		(layer "In4.Cu")
		(net "P5E_CPU0_P3_RX_DP<5>")
	)
	(segment
		(start 366.265968 -296.35831)
		(end 366.265968 -296.329862)
		(width 0.1143)
		(layer "In4.Cu")
		(net "P5E_CPU0_P3_RX_DP<5>")
	)
	(segment
		(start 365.940594 -290.610036)
		(end 365.938816 -290.60902)
		(width 0.1143)
		(layer "In4.Cu")
		(net "P5E_CPU0_P3_RX_DP<5>")
	)
	(segment
		(start 384.458464 -356.018084)
		(end 385.05892 -351.149158)
		(width 0.14224)
		(layer "In4.Cu")
		(net "P5E_CPU0_P3_RX_DP<5>")
	)
	(segment
		(start 365.470694 -289.800284)
		(end 365.4679 -289.798506)
		(width 0.1143)
		(layer "In4.Cu")
		(net "P5E_CPU0_P3_RX_DP<5>")
	)
	(segment
		(start 373.55907 -376.467116)
		(end 384.413252 -356.160832)
		(width 0.14224)
		(layer "In4.Cu")
		(net "P5E_CPU0_P3_RX_DP<5>")
	)
	(segment
		(start 376.90679 -387.058662)
		(end 376.37466 -384.383788)
		(width 0.14224)
		(layer "In4.Cu")
		(net "P5E_CPU0_P3_RX_DP<5>")
	)
	(segment
		(start 366.4077 -292.39337)
		(end 366.446816 -292.37051)
		(width 0.1143)
		(layer "In4.Cu")
		(net "P5E_CPU0_P3_RX_DP<5>")
	)
	(segment
		(start 377.386342 -394.031216)
		(end 377.560586 -393.930632)
		(width 0.14224)
		(layer "In4.Cu")
		(net "P5E_CPU0_P3_RX_DP<5>")
	)
	(segment
		(start 368.754406 -303.333404)
		(end 367.564162 -301.550324)
		(width 0.14224)
		(layer "In4.Cu")
		(net "P5E_CPU0_P3_RX_DP<5>")
	)
	(segment
		(start 365.4679 -289.798506)
		(end 365.466884 -289.797998)
		(width 0.1143)
		(layer "In4.Cu")
		(net "P5E_CPU0_P3_RX_DP<5>")
	)
	(segment
		(start 366.265968 -298.224194)
		(end 366.265968 -296.35831)
		(width 0.14224)
		(layer "In4.Cu")
		(net "P5E_CPU0_P3_RX_DP<5>")
	)
	(segment
		(start 374.131586 -378.417582)
		(end 373.562626 -377.848622)
		(width 0.14224)
		(layer "In4.Cu")
		(net "P5E_CPU0_P3_RX_DP<5>")
	)
	(segment
		(start 365.976916 -290.631372)
		(end 365.970058 -290.627308)
		(width 0.1143)
		(layer "In4.Cu")
		(net "P5E_CPU0_P3_RX_DP<5>")
	)
	(segment
		(start 373.489982 -377.673362)
		(end 373.489982 -376.743214)
		(width 0.14224)
		(layer "In4.Cu")
		(net "P5E_CPU0_P3_RX_DP<5>")
	)
	(segment
		(start 366.37722 -294.031162)
		(end 366.4077 -294.013382)
		(width 0.1143)
		(layer "In4.Cu")
		(net "P5E_CPU0_P3_RX_DP<5>")
	)
	(segment
		(start 365.943134 -290.61156)
		(end 365.942118 -290.611052)
		(width 0.1143)
		(layer "In4.Cu")
		(net "P5E_CPU0_P3_RX_DP<5>")
	)
	(segment
		(start 377.648724 -393.842494)
		(end 377.648724 -393.428982)
		(width 0.14224)
		(layer "In4.Cu")
		(net "P5E_CPU0_P3_RX_DP<5>")
	)
	(segment
		(start 366.446816 -294.681402)
		(end 366.4077 -294.658542)
		(width 0.1143)
		(layer "In4.Cu")
		(net "P5E_CPU0_P3_RX_DP<5>")
	)
	(segment
		(start 377.426728 -313.901582)
		(end 368.754406 -303.333404)
		(width 0.14224)
		(layer "In4.Cu")
		(net "P5E_CPU0_P3_RX_DP<5>")
	)
	(segment
		(start 385.05892 -351.149158)
		(end 385.05892 -337.263232)
		(width 0.14224)
		(layer "In4.Cu")
		(net "P5E_CPU0_P3_RX_DP<5>")
	)
	(segment
		(start 366.4077 -294.013382)
		(end 366.446816 -293.990522)
		(width 0.1143)
		(layer "In4.Cu")
		(net "P5E_CPU0_P3_RX_DP<5>")
	)
	(segment
		(start 366.446816 -291.441378)
		(end 366.4077 -291.418518)
		(width 0.1143)
		(layer "In4.Cu")
		(net "P5E_CPU0_P3_RX_DP<5>")
	)
	(segment
		(start 379.457966 -317.702184)
		(end 377.426728 -313.901582)
		(width 0.14224)
		(layer "In4.Cu")
		(net "P5E_CPU0_P3_RX_DP<5>")
	)
	(segment
		(start 366.37722 -295.651174)
		(end 366.4077 -295.633394)
		(width 0.1143)
		(layer "In4.Cu")
		(net "P5E_CPU0_P3_RX_DP<5>")
	)
	(segment
		(start 377.560586 -393.930632)
		(end 377.648724 -393.842494)
		(width 0.14224)
		(layer "In4.Cu")
		(net "P5E_CPU0_P3_RX_DP<5>")
	)
	(segment
		(start 366.37722 -292.41115)
		(end 366.4077 -292.39337)
		(width 0.1143)
		(layer "In4.Cu")
		(net "P5E_CPU0_P3_RX_DP<5>")
	)
	(segment
		(start 366.4077 -291.418518)
		(end 366.37722 -291.400738)
		(width 0.1143)
		(layer "In4.Cu")
		(net "P5E_CPU0_P3_RX_DP<5>")
	)
	(segment
		(start 365.942118 -290.611052)
		(end 365.940594 -290.610036)
		(width 0.1143)
		(layer "In4.Cu")
		(net "P5E_CPU0_P3_RX_DP<5>")
	)
	(segment
		(start 365.938816 -290.60902)
		(end 365.9378 -290.608512)
		(width 0.1143)
		(layer "In4.Cu")
		(net "P5E_CPU0_P3_RX_DP<5>")
	)
	(segment
		(start 374.847612 -378.863098)
		(end 374.629426 -378.716032)
		(width 0.14224)
		(layer "In4.Cu")
		(net "P5E_CPU0_P3_RX_DP<5>")
	)
	(segment
		(start 383.7813 -330.150724)
		(end 379.457966 -317.702184)
		(width 0.14224)
		(layer "In4.Cu")
		(net "P5E_CPU0_P3_RX_DP<5>")
	)
	(segment
		(start 365.287052 -289.545776)
		(end 365.356902 -289.475926)
		(width 0.1143)
		(layer "In4.Cu")
		(net "P5E_CPU0_P3_RX_DP<5>")
	)
	(segment
		(start 365.969296 -290.6268)
		(end 365.944658 -290.612576)
		(width 0.1143)
		(layer "In4.Cu")
		(net "P5E_CPU0_P3_RX_DP<5>")
	)
	(segment
		(start 365.356902 -289.475926)
		(end 365.654844 -289.475926)
		(width 0.1143)
		(layer "In4.Cu")
		(net "P5E_CPU0_P3_RX_DP<5>")
	)
	(segment
		(start 367.564162 -301.550324)
		(end 366.339628 -298.594272)
		(width 0.14224)
		(layer "In4.Cu")
		(net "P5E_CPU0_P3_RX_DP<5>")
	)
	(segment
		(start 366.446816 -293.06139)
		(end 366.4077 -293.03853)
		(width 0.1143)
		(layer "In4.Cu")
		(net "P5E_CPU0_P3_RX_DP<5>")
	)
	(segment
		(start 365.466884 -289.797998)
		(end 365.43615 -289.780218)
		(width 0.1143)
		(layer "In4.Cu")
		(net "P5E_CPU0_P3_RX_DP<5>")
	)
	(segment
		(start 377.291346 -394.385292)
		(end 377.386342 -394.031216)
		(width 0.14224)
		(layer "In4.Cu")
		(net "P5E_CPU0_P3_RX_DP<5>")
	)
	(segment
		(start 377.648724 -393.428982)
		(end 377.332748 -393.113006)
		(width 0.14224)
		(layer "In4.Cu")
		(net "P5E_CPU0_P3_RX_DP<5>")
	)
	(segment
		(start 377.337828 -392.557762)
		(end 377.640596 -392.254994)
		(width 0.14224)
		(layer "In4.Cu")
		(net "P5E_CPU0_P3_RX_DP<5>")
	)
	(segment
		(start 366.265968 -296.329862)
		(end 366.220248 -296.284142)
		(width 0.1143)
		(layer "In4.Cu")
		(net "P5E_CPU0_P3_RX_DP<5>")
	)
	(segment
		(start 377.332748 -393.113006)
		(end 377.337828 -392.557762)
		(width 0.14224)
		(layer "In4.Cu")
		(net "P5E_CPU0_P3_RX_DP<5>")
	)
	(segment
		(start 365.9378 -290.608512)
		(end 365.937038 -290.608004)
		(width 0.1143)
		(layer "In4.Cu")
		(net "P5E_CPU0_P3_RX_DP<5>")
	)
	(segment
		(start 377.640596 -392.254994)
		(end 377.640596 -390.83869)
		(width 0.14224)
		(layer "In4.Cu")
		(net "P5E_CPU0_P3_RX_DP<5>")
	)
	(segment
		(start 375.196862 -380.862078)
		(end 375.196862 -379.519688)
		(width 0.14224)
		(layer "In4.Cu")
		(net "P5E_CPU0_P3_RX_DP<5>")
	)
	(segment
		(start 366.4077 -293.03853)
		(end 366.37722 -293.02075)
		(width 0.1143)
		(layer "In4.Cu")
		(net "P5E_CPU0_P3_RX_DP<5>")
	)
	(segment
		(start 377.622816 -390.658096)
		(end 376.90679 -387.058662)
		(width 0.14224)
		(layer "In4.Cu")
		(net "P5E_CPU0_P3_RX_DP<5>")
	)
	(segment
		(start 366.4077 -295.633394)
		(end 366.446816 -295.610534)
		(width 0.1143)
		(layer "In4.Cu")
		(net "P5E_CPU0_P3_RX_DP<5>")
	)
	(arc
		(start 375.83999 -383.096516)
		(mid 375.360926 -382.024634)
		(end 375.196862 -380.862078)
		(width 0.14224)
		(layer "In4.Cu")
		(net "P5E_CPU0_P3_RX_DP<5>")
	)
	(arc
		(start 366.220248 -295.955974)
		(mid 366.261797 -295.784552)
		(end 366.37722 -295.651174)
		(width 0.1143)
		(layer "In4.Cu")
		(net "P5E_CPU0_P3_RX_DP<5>")
	)
	(arc
		(start 374.629426 -378.716032)
		(mid 374.511123 -378.644946)
		(end 374.386094 -378.586492)
		(width 0.14224)
		(layer "In4.Cu")
		(net "P5E_CPU0_P3_RX_DP<5>")
	)
	(arc
		(start 384.413252 -356.160832)
		(mid 384.442449 -356.091545)
		(end 384.458464 -356.018084)
		(width 0.14224)
		(layer "In4.Cu")
		(net "P5E_CPU0_P3_RX_DP<5>")
	)
	(arc
		(start 366.37722 -293.02075)
		(mid 366.220243 -292.71595)
		(end 366.37722 -292.41115)
		(width 0.1143)
		(layer "In4.Cu")
		(net "P5E_CPU0_P3_RX_DP<5>")
	)
	(arc
		(start 366.446816 -295.610534)
		(mid 366.690143 -295.145968)
		(end 366.446816 -294.681402)
		(width 0.1143)
		(layer "In4.Cu")
		(net "P5E_CPU0_P3_RX_DP<5>")
	)
	(arc
		(start 366.37722 -291.400738)
		(mid 366.261793 -291.267362)
		(end 366.220248 -291.095938)
		(width 0.1143)
		(layer "In4.Cu")
		(net "P5E_CPU0_P3_RX_DP<5>")
	)
	(arc
		(start 377.640596 -390.83869)
		(mid 377.636143 -390.747956)
		(end 377.622816 -390.658096)
		(width 0.14224)
		(layer "In4.Cu")
		(net "P5E_CPU0_P3_RX_DP<5>")
	)
	(arc
		(start 365.937038 -290.608004)
		(mid 365.799636 -290.471171)
		(end 365.749332 -290.2839)
		(width 0.1143)
		(layer "In4.Cu")
		(net "P5E_CPU0_P3_RX_DP<5>")
	)
	(arc
		(start 366.37722 -294.640762)
		(mid 366.220243 -294.335962)
		(end 366.37722 -294.031162)
		(width 0.1143)
		(layer "In4.Cu")
		(net "P5E_CPU0_P3_RX_DP<5>")
	)
	(arc
		(start 365.43615 -289.780218)
		(mid 365.339015 -289.677349)
		(end 365.287052 -289.545776)
		(width 0.1143)
		(layer "In4.Cu")
		(net "P5E_CPU0_P3_RX_DP<5>")
	)
	(arc
		(start 373.489982 -376.743214)
		(mid 373.507472 -376.600894)
		(end 373.55907 -376.467116)
		(width 0.14224)
		(layer "In4.Cu")
		(net "P5E_CPU0_P3_RX_DP<5>")
	)
	(arc
		(start 366.446816 -292.37051)
		(mid 366.690143 -291.905944)
		(end 366.446816 -291.441378)
		(width 0.1143)
		(layer "In4.Cu")
		(net "P5E_CPU0_P3_RX_DP<5>")
	)
	(arc
		(start 366.446816 -293.990522)
		(mid 366.690143 -293.525956)
		(end 366.446816 -293.06139)
		(width 0.1143)
		(layer "In4.Cu")
		(net "P5E_CPU0_P3_RX_DP<5>")
	)
	(arc
		(start 375.196862 -379.519688)
		(mid 375.10411 -379.14785)
		(end 374.847612 -378.863098)
		(width 0.14224)
		(layer "In4.Cu")
		(net "P5E_CPU0_P3_RX_DP<5>")
	)
	(arc
		(start 366.220248 -291.095938)
		(mid 366.155733 -290.833719)
		(end 365.976916 -290.631372)
		(width 0.1143)
		(layer "In4.Cu")
		(net "P5E_CPU0_P3_RX_DP<5>")
	)
	(arc
		(start 366.339628 -298.594272)
		(mid 366.284589 -298.412859)
		(end 366.265968 -298.224194)
		(width 0.14224)
		(layer "In4.Cu")
		(net "P5E_CPU0_P3_RX_DP<5>")
	)
	(arc
		(start 365.749332 -290.2839)
		(mid 365.674693 -290.004823)
		(end 365.470694 -289.800284)
		(width 0.1143)
		(layer "In4.Cu")
		(net "P5E_CPU0_P3_RX_DP<5>")
	)
	(arc
		(start 373.562626 -377.848622)
		(mid 373.508844 -377.768226)
		(end 373.489982 -377.673362)
		(width 0.14224)
		(layer "In4.Cu")
		(net "P5E_CPU0_P3_RX_DP<5>")
	)
	(arc
		(start 376.37466 -384.383788)
		(mid 376.161028 -383.717848)
		(end 375.83999 -383.096516)
		(width 0.14224)
		(layer "In4.Cu")
		(net "P5E_CPU0_P3_RX_DP<5>")
	)
	(arc
		(start 374.386094 -378.586492)
		(mid 374.250364 -378.514812)
		(end 374.131586 -378.417582)
		(width 0.14224)
		(layer "In4.Cu")
		(net "P5E_CPU0_P3_RX_DP<5>")
	)
	(segment
		(start 365.187992 -290.83)
		(end 365.654844 -291.095938)
		(width 0.12954)
		(layer "F.Cu")
		(net "P5E_CPU0_P3_RX_DP<4>")
	)
	(segment
		(start 375.570496 -394.385292)
		(end 376.091196 -394.385292)
		(width 0.127)
		(layer "F.Cu")
		(net "P5E_CPU0_P3_RX_DP<4>")
	)
	(segment
		(start 365.464344 -294.015414)
		(end 365.46536 -294.014906)
		(width 0.1143)
		(layer "In4.Cu")
		(net "P5E_CPU0_P3_RX_DP<4>")
	)
	(segment
		(start 371.68328 -376.760994)
		(end 371.683534 -376.761248)
		(width 0.14224)
		(layer "In4.Cu")
		(net "P5E_CPU0_P3_RX_DP<4>")
	)
	(segment
		(start 365.46536 -294.014906)
		(end 365.466122 -294.014398)
		(width 0.1143)
		(layer "In4.Cu")
		(net "P5E_CPU0_P3_RX_DP<4>")
	)
	(segment
		(start 374.511824 -383.448306)
		(end 373.0498 -381.259588)
		(width 0.14224)
		(layer "In4.Cu")
		(net "P5E_CPU0_P3_RX_DP<4>")
	)
	(segment
		(start 365.287052 -291.165788)
		(end 365.356902 -291.095938)
		(width 0.1143)
		(layer "In4.Cu")
		(net "P5E_CPU0_P3_RX_DP<4>")
	)
	(segment
		(start 365.288068 -295.885108)
		(end 365.287052 -295.883838)
		(width 0.1143)
		(layer "In4.Cu")
		(net "P5E_CPU0_P3_RX_DP<4>")
	)
	(segment
		(start 378.600208 -318.077342)
		(end 376.644154 -314.418218)
		(width 0.14224)
		(layer "In4.Cu")
		(net "P5E_CPU0_P3_RX_DP<4>")
	)
	(segment
		(start 384.12674 -337.351624)
		(end 382.875282 -330.384404)
		(width 0.14224)
		(layer "In4.Cu")
		(net "P5E_CPU0_P3_RX_DP<4>")
	)
	(segment
		(start 365.356902 -291.095938)
		(end 365.654844 -291.095938)
		(width 0.1143)
		(layer "In4.Cu")
		(net "P5E_CPU0_P3_RX_DP<4>")
	)
	(segment
		(start 376.34926 -390.306814)
		(end 375.673366 -386.907024)
		(width 0.14224)
		(layer "In4.Cu")
		(net "P5E_CPU0_P3_RX_DP<4>")
	)
	(segment
		(start 365.4679 -294.013382)
		(end 365.468408 -294.013382)
		(width 0.1143)
		(layer "In4.Cu")
		(net "P5E_CPU0_P3_RX_DP<4>")
	)
	(segment
		(start 383.394204 -355.836728)
		(end 384.12674 -350.4438)
		(width 0.14224)
		(layer "In4.Cu")
		(net "P5E_CPU0_P3_RX_DP<4>")
	)
	(segment
		(start 365.333788 -296.362628)
		(end 365.333788 -296.33418)
		(width 0.1143)
		(layer "In4.Cu")
		(net "P5E_CPU0_P3_RX_DP<4>")
	)
	(segment
		(start 365.467138 -294.01389)
		(end 365.4679 -294.013382)
		(width 0.1143)
		(layer "In4.Cu")
		(net "P5E_CPU0_P3_RX_DP<4>")
	)
	(segment
		(start 376.132598 -393.113006)
		(end 376.137678 -392.497818)
		(width 0.14224)
		(layer "In4.Cu")
		(net "P5E_CPU0_P3_RX_DP<4>")
	)
	(segment
		(start 365.288068 -296.28846)
		(end 365.288068 -295.885108)
		(width 0.1143)
		(layer "In4.Cu")
		(net "P5E_CPU0_P3_RX_DP<4>")
	)
	(segment
		(start 371.913404 -375.842276)
		(end 375.79681 -368.576352)
		(width 0.14224)
		(layer "In4.Cu")
		(net "P5E_CPU0_P3_RX_DP<4>")
	)
	(segment
		(start 375.79681 -368.576352)
		(end 383.339594 -355.991922)
		(width 0.14224)
		(layer "In4.Cu")
		(net "P5E_CPU0_P3_RX_DP<4>")
	)
	(segment
		(start 372.40591 -380.8603)
		(end 372.405656 -380.8603)
		(width 0.14224)
		(layer "In4.Cu")
		(net "P5E_CPU0_P3_RX_DP<4>")
	)
	(segment
		(start 365.461042 -294.017192)
		(end 365.463582 -294.015922)
		(width 0.1143)
		(layer "In4.Cu")
		(net "P5E_CPU0_P3_RX_DP<4>")
	)
	(segment
		(start 376.137678 -392.497818)
		(end 376.440446 -392.19505)
		(width 0.14224)
		(layer "In4.Cu")
		(net "P5E_CPU0_P3_RX_DP<4>")
	)
	(segment
		(start 365.333788 -298.595288)
		(end 365.333788 -296.362628)
		(width 0.14224)
		(layer "In4.Cu")
		(net "P5E_CPU0_P3_RX_DP<4>")
	)
	(segment
		(start 365.436404 -294.640254)
		(end 365.432086 -294.637206)
		(width 0.1143)
		(layer "In4.Cu")
		(net "P5E_CPU0_P3_RX_DP<4>")
	)
	(segment
		(start 376.440446 -392.19505)
		(end 376.440446 -391.232898)
		(width 0.14224)
		(layer "In4.Cu")
		(net "P5E_CPU0_P3_RX_DP<4>")
	)
	(segment
		(start 365.468408 -293.03853)
		(end 365.4679 -293.03853)
		(width 0.1143)
		(layer "In4.Cu")
		(net "P5E_CPU0_P3_RX_DP<4>")
	)
	(segment
		(start 376.644154 -314.418218)
		(end 367.9825 -303.863248)
		(width 0.14224)
		(layer "In4.Cu")
		(net "P5E_CPU0_P3_RX_DP<4>")
	)
	(segment
		(start 365.4679 -291.418518)
		(end 365.43615 -291.40023)
		(width 0.1143)
		(layer "In4.Cu")
		(net "P5E_CPU0_P3_RX_DP<4>")
	)
	(segment
		(start 372.405656 -380.8603)
		(end 372.173246 -380.62789)
		(width 0.14224)
		(layer "In4.Cu")
		(net "P5E_CPU0_P3_RX_DP<4>")
	)
	(segment
		(start 376.448574 -393.428982)
		(end 376.132598 -393.113006)
		(width 0.14224)
		(layer "In4.Cu")
		(net "P5E_CPU0_P3_RX_DP<4>")
	)
	(segment
		(start 365.436658 -292.411912)
		(end 365.466376 -292.394894)
		(width 0.1143)
		(layer "In4.Cu")
		(net "P5E_CPU0_P3_RX_DP<4>")
	)
	(segment
		(start 376.091196 -394.385292)
		(end 376.186192 -394.031216)
		(width 0.14224)
		(layer "In4.Cu")
		(net "P5E_CPU0_P3_RX_DP<4>")
	)
	(segment
		(start 365.333788 -296.33418)
		(end 365.288068 -296.28846)
		(width 0.1143)
		(layer "In4.Cu")
		(net "P5E_CPU0_P3_RX_DP<4>")
	)
	(segment
		(start 367.9825 -303.863248)
		(end 366.726216 -301.98187)
		(width 0.14224)
		(layer "In4.Cu")
		(net "P5E_CPU0_P3_RX_DP<4>")
	)
	(segment
		(start 384.12674 -350.4438)
		(end 384.12674 -337.351624)
		(width 0.14224)
		(layer "In4.Cu")
		(net "P5E_CPU0_P3_RX_DP<4>")
	)
	(segment
		(start 365.506762 -294.681402)
		(end 365.437166 -294.640762)
		(width 0.1143)
		(layer "In4.Cu")
		(net "P5E_CPU0_P3_RX_DP<4>")
	)
	(segment
		(start 371.68328 -379.445266)
		(end 371.68328 -376.760994)
		(width 0.14224)
		(layer "In4.Cu")
		(net "P5E_CPU0_P3_RX_DP<4>")
	)
	(segment
		(start 375.673366 -386.907024)
		(end 375.586498 -386.470144)
		(width 0.14224)
		(layer "In4.Cu")
		(net "P5E_CPU0_P3_RX_DP<4>")
	)
	(segment
		(start 376.360436 -393.930632)
		(end 376.448574 -393.842494)
		(width 0.14224)
		(layer "In4.Cu")
		(net "P5E_CPU0_P3_RX_DP<4>")
	)
	(segment
		(start 365.437166 -294.640762)
		(end 365.436404 -294.640254)
		(width 0.1143)
		(layer "In4.Cu")
		(net "P5E_CPU0_P3_RX_DP<4>")
	)
	(segment
		(start 366.726216 -301.98187)
		(end 365.34344 -298.644056)
		(width 0.14224)
		(layer "In4.Cu")
		(net "P5E_CPU0_P3_RX_DP<4>")
	)
	(segment
		(start 365.437166 -295.651174)
		(end 365.506762 -295.610534)
		(width 0.1143)
		(layer "In4.Cu")
		(net "P5E_CPU0_P3_RX_DP<4>")
	)
	(segment
		(start 376.448574 -393.842494)
		(end 376.448574 -393.428982)
		(width 0.14224)
		(layer "In4.Cu")
		(net "P5E_CPU0_P3_RX_DP<4>")
	)
	(segment
		(start 372.827042 -381.076708)
		(end 372.570248 -380.970282)
		(width 0.14224)
		(layer "In4.Cu")
		(net "P5E_CPU0_P3_RX_DP<4>")
	)
	(segment
		(start 365.463582 -294.015922)
		(end 365.464344 -294.015414)
		(width 0.1143)
		(layer "In4.Cu")
		(net "P5E_CPU0_P3_RX_DP<4>")
	)
	(segment
		(start 382.875282 -330.384404)
		(end 378.600208 -318.077342)
		(width 0.14224)
		(layer "In4.Cu")
		(net "P5E_CPU0_P3_RX_DP<4>")
	)
	(segment
		(start 376.186192 -394.031216)
		(end 376.360436 -393.930632)
		(width 0.14224)
		(layer "In4.Cu")
		(net "P5E_CPU0_P3_RX_DP<4>")
	)
	(segment
		(start 365.466122 -294.014398)
		(end 365.467138 -294.01389)
		(width 0.1143)
		(layer "In4.Cu")
		(net "P5E_CPU0_P3_RX_DP<4>")
	)
	(segment
		(start 365.467138 -293.038022)
		(end 365.436658 -293.020496)
		(width 0.1143)
		(layer "In4.Cu")
		(net "P5E_CPU0_P3_RX_DP<4>")
	)
	(segment
		(start 365.4679 -293.03853)
		(end 365.467138 -293.038022)
		(width 0.1143)
		(layer "In4.Cu")
		(net "P5E_CPU0_P3_RX_DP<4>")
	)
	(arc
		(start 383.339594 -355.991922)
		(mid 383.374767 -355.917095)
		(end 383.394204 -355.836728)
		(width 0.14224)
		(layer "In4.Cu")
		(net "P5E_CPU0_P3_RX_DP<4>")
	)
	(arc
		(start 365.506762 -295.610534)
		(mid 365.750089 -295.145968)
		(end 365.506762 -294.681402)
		(width 0.1143)
		(layer "In4.Cu")
		(net "P5E_CPU0_P3_RX_DP<4>")
	)
	(arc
		(start 372.570248 -380.970282)
		(mid 372.482647 -380.923402)
		(end 372.40591 -380.8603)
		(width 0.14224)
		(layer "In4.Cu")
		(net "P5E_CPU0_P3_RX_DP<4>")
	)
	(arc
		(start 372.173246 -380.62789)
		(mid 371.810644 -380.085312)
		(end 371.68328 -379.445266)
		(width 0.14224)
		(layer "In4.Cu")
		(net "P5E_CPU0_P3_RX_DP<4>")
	)
	(arc
		(start 365.287052 -295.883838)
		(mid 365.327237 -295.774116)
		(end 365.39932 -295.682162)
		(width 0.1143)
		(layer "In4.Cu")
		(net "P5E_CPU0_P3_RX_DP<4>")
	)
	(arc
		(start 375.586498 -386.470144)
		(mid 375.187627 -384.994808)
		(end 374.59285 -383.58699)
		(width 0.14224)
		(layer "In4.Cu")
		(net "P5E_CPU0_P3_RX_DP<4>")
	)
	(arc
		(start 376.440446 -391.232898)
		(mid 376.417598 -390.767616)
		(end 376.34926 -390.306814)
		(width 0.14224)
		(layer "In4.Cu")
		(net "P5E_CPU0_P3_RX_DP<4>")
	)
	(arc
		(start 365.34344 -298.644056)
		(mid 365.336195 -298.620149)
		(end 365.333788 -298.595288)
		(width 0.14224)
		(layer "In4.Cu")
		(net "P5E_CPU0_P3_RX_DP<4>")
	)
	(arc
		(start 371.683534 -376.761248)
		(mid 371.741863 -376.2876)
		(end 371.913404 -375.842276)
		(width 0.14224)
		(layer "In4.Cu")
		(net "P5E_CPU0_P3_RX_DP<4>")
	)
	(arc
		(start 365.436658 -293.020496)
		(mid 365.28073 -292.716204)
		(end 365.436658 -292.411912)
		(width 0.1143)
		(layer "In4.Cu")
		(net "P5E_CPU0_P3_RX_DP<4>")
	)
	(arc
		(start 365.43615 -291.40023)
		(mid 365.339015 -291.297361)
		(end 365.287052 -291.165788)
		(width 0.1143)
		(layer "In4.Cu")
		(net "P5E_CPU0_P3_RX_DP<4>")
	)
	(arc
		(start 365.466376 -292.394894)
		(mid 365.748883 -291.907112)
		(end 365.4679 -291.418518)
		(width 0.1143)
		(layer "In4.Cu")
		(net "P5E_CPU0_P3_RX_DP<4>")
	)
	(arc
		(start 365.39932 -295.682162)
		(mid 365.417739 -295.666052)
		(end 365.437166 -295.651174)
		(width 0.1143)
		(layer "In4.Cu")
		(net "P5E_CPU0_P3_RX_DP<4>")
	)
	(arc
		(start 365.432086 -294.637206)
		(mid 365.277859 -294.319274)
		(end 365.461042 -294.017192)
		(width 0.1143)
		(layer "In4.Cu")
		(net "P5E_CPU0_P3_RX_DP<4>")
	)
	(arc
		(start 374.59285 -383.58699)
		(mid 374.554436 -383.516422)
		(end 374.511824 -383.448306)
		(width 0.14224)
		(layer "In4.Cu")
		(net "P5E_CPU0_P3_RX_DP<4>")
	)
	(arc
		(start 373.0498 -381.259588)
		(mid 372.951985 -381.151619)
		(end 372.827042 -381.076708)
		(width 0.14224)
		(layer "In4.Cu")
		(net "P5E_CPU0_P3_RX_DP<4>")
	)
	(arc
		(start 365.468408 -294.013382)
		(mid 365.749055 -293.525956)
		(end 365.468408 -293.03853)
		(width 0.1143)
		(layer "In4.Cu")
		(net "P5E_CPU0_P3_RX_DP<4>")
	)
	(segment
		(start 378.770642 -393.69238)
		(end 379.291342 -393.69238)
		(width 0.127)
		(layer "F.Cu")
		(net "P5E_CPU0_P3_RX_DN<7>")
	)
	(segment
		(start 367.067846 -290.83)
		(end 367.534698 -291.095938)
		(width 0.12954)
		(layer "F.Cu")
		(net "P5E_CPU0_P3_RX_DN<7>")
	)
	(segment
		(start 379.758448 -390.637268)
		(end 380.020322 -385.302506)
		(width 0.14224)
		(layer "In4.Cu")
		(net "P5E_CPU0_P3_RX_DN<7>")
	)
	(segment
		(start 368.18824 -293.85006)
		(end 368.189256 -293.849552)
		(width 0.1143)
		(layer "In4.Cu")
		(net "P5E_CPU0_P3_RX_DN<7>")
	)
	(segment
		(start 386.250434 -356.481126)
		(end 386.64134 -352.514662)
		(width 0.14224)
		(layer "In4.Cu")
		(net "P5E_CPU0_P3_RX_DN<7>")
	)
	(segment
		(start 368.191542 -293.203122)
		(end 368.188748 -293.201344)
		(width 0.1143)
		(layer "In4.Cu")
		(net "P5E_CPU0_P3_RX_DN<7>")
	)
	(segment
		(start 368.189256 -293.849552)
		(end 368.190018 -293.849044)
		(width 0.1143)
		(layer "In4.Cu")
		(net "P5E_CPU0_P3_RX_DN<7>")
	)
	(segment
		(start 367.863882 -297.960288)
		(end 367.863882 -296.46245)
		(width 0.14224)
		(layer "In4.Cu")
		(net "P5E_CPU0_P3_RX_DN<7>")
	)
	(segment
		(start 379.45441 -392.616944)
		(end 379.758448 -392.31316)
		(width 0.14224)
		(layer "In4.Cu")
		(net "P5E_CPU0_P3_RX_DN<7>")
	)
	(segment
		(start 386.64134 -352.514662)
		(end 386.64134 -337.115912)
		(width 0.14224)
		(layer "In4.Cu")
		(net "P5E_CPU0_P3_RX_DN<7>")
	)
	(segment
		(start 379.385322 -381.311658)
		(end 379.385576 -381.311658)
		(width 0.14224)
		(layer "In4.Cu")
		(net "P5E_CPU0_P3_RX_DN<7>")
	)
	(segment
		(start 368.152934 -293.870888)
		(end 368.181128 -293.854886)
		(width 0.1143)
		(layer "In4.Cu")
		(net "P5E_CPU0_P3_RX_DN<7>")
	)
	(segment
		(start 368.977418 -300.80458)
		(end 367.922556 -298.256452)
		(width 0.14224)
		(layer "In4.Cu")
		(net "P5E_CPU0_P3_RX_DN<7>")
	)
	(segment
		(start 368.188748 -294.821356)
		(end 368.184684 -294.81907)
		(width 0.1143)
		(layer "In4.Cu")
		(net "P5E_CPU0_P3_RX_DN<7>")
	)
	(segment
		(start 368.184176 -293.852854)
		(end 368.18824 -293.85006)
		(width 0.1143)
		(layer "In4.Cu")
		(net "P5E_CPU0_P3_RX_DN<7>")
	)
	(segment
		(start 380.020322 -384.78206)
		(end 379.883162 -384.6449)
		(width 0.14224)
		(layer "In4.Cu")
		(net "P5E_CPU0_P3_RX_DN<7>")
	)
	(segment
		(start 378.25934 -379.52934)
		(end 378.12218 -379.39218)
		(width 0.14224)
		(layer "In4.Cu")
		(net "P5E_CPU0_P3_RX_DN<7>")
	)
	(segment
		(start 370.079016 -302.436276)
		(end 368.977418 -300.80458)
		(width 0.14224)
		(layer "In4.Cu")
		(net "P5E_CPU0_P3_RX_DN<7>")
	)
	(segment
		(start 367.863882 -296.46245)
		(end 367.863882 -296.434002)
		(width 0.1143)
		(layer "In4.Cu")
		(net "P5E_CPU0_P3_RX_DN<7>")
	)
	(segment
		(start 378.7267 -312.973466)
		(end 370.079016 -302.436276)
		(width 0.14224)
		(layer "In4.Cu")
		(net "P5E_CPU0_P3_RX_DN<7>")
	)
	(segment
		(start 368.191034 -293.848536)
		(end 368.229896 -293.822882)
		(width 0.1143)
		(layer "In4.Cu")
		(net "P5E_CPU0_P3_RX_DN<7>")
	)
	(segment
		(start 380.020322 -383.6543)
		(end 379.883162 -383.51714)
		(width 0.14224)
		(layer "In4.Cu")
		(net "P5E_CPU0_P3_RX_DN<7>")
	)
	(segment
		(start 368.190018 -293.849044)
		(end 368.191034 -293.848536)
		(width 0.1143)
		(layer "In4.Cu")
		(net "P5E_CPU0_P3_RX_DN<7>")
	)
	(segment
		(start 367.909602 -296.388282)
		(end 367.909602 -295.847008)
		(width 0.1143)
		(layer "In4.Cu")
		(net "P5E_CPU0_P3_RX_DN<7>")
	)
	(segment
		(start 368.205512 -293.21125)
		(end 368.191542 -293.203122)
		(width 0.1143)
		(layer "In4.Cu")
		(net "P5E_CPU0_P3_RX_DN<7>")
	)
	(segment
		(start 368.229896 -295.442894)
		(end 368.230912 -295.442894)
		(width 0.1143)
		(layer "In4.Cu")
		(net "P5E_CPU0_P3_RX_DN<7>")
	)
	(segment
		(start 368.155982 -295.489122)
		(end 368.184684 -295.472866)
		(width 0.1143)
		(layer "In4.Cu")
		(net "P5E_CPU0_P3_RX_DN<7>")
	)
	(segment
		(start 386.64134 -337.115912)
		(end 385.318 -329.75042)
		(width 0.14224)
		(layer "In4.Cu")
		(net "P5E_CPU0_P3_RX_DN<7>")
	)
	(segment
		(start 379.037596 -381.080772)
		(end 378.4727 -380.515876)
		(width 0.14224)
		(layer "In4.Cu")
		(net "P5E_CPU0_P3_RX_DN<7>")
	)
	(segment
		(start 378.25934 -380.00051)
		(end 378.25934 -379.52934)
		(width 0.14224)
		(layer "In4.Cu")
		(net "P5E_CPU0_P3_RX_DN<7>")
	)
	(segment
		(start 379.883162 -384.6449)
		(end 379.883162 -384.21818)
		(width 0.14224)
		(layer "In4.Cu")
		(net "P5E_CPU0_P3_RX_DN<7>")
	)
	(segment
		(start 368.184684 -295.472866)
		(end 368.186208 -295.47185)
		(width 0.1143)
		(layer "In4.Cu")
		(net "P5E_CPU0_P3_RX_DN<7>")
	)
	(segment
		(start 379.883162 -384.21818)
		(end 380.020322 -384.08102)
		(width 0.14224)
		(layer "In4.Cu")
		(net "P5E_CPU0_P3_RX_DN<7>")
	)
	(segment
		(start 378.12218 -379.39218)
		(end 378.12218 -378.96546)
		(width 0.14224)
		(layer "In4.Cu")
		(net "P5E_CPU0_P3_RX_DN<7>")
	)
	(segment
		(start 379.291342 -393.69238)
		(end 379.644402 -393.787376)
		(width 0.14224)
		(layer "In4.Cu")
		(net "P5E_CPU0_P3_RX_DN<7>")
	)
	(segment
		(start 385.318 -329.75042)
		(end 385.256532 -329.51547)
		(width 0.14224)
		(layer "In4.Cu")
		(net "P5E_CPU0_P3_RX_DN<7>")
	)
	(segment
		(start 380.020322 -385.302506)
		(end 380.020322 -384.78206)
		(width 0.14224)
		(layer "In4.Cu")
		(net "P5E_CPU0_P3_RX_DN<7>")
	)
	(segment
		(start 367.863882 -296.434002)
		(end 367.909602 -296.388282)
		(width 0.1143)
		(layer "In4.Cu")
		(net "P5E_CPU0_P3_RX_DN<7>")
	)
	(segment
		(start 378.36602 -375.51614)
		(end 386.250434 -356.481126)
		(width 0.14224)
		(layer "In4.Cu")
		(net "P5E_CPU0_P3_RX_DN<7>")
	)
	(segment
		(start 367.83264 -291.095938)
		(end 367.534698 -291.095938)
		(width 0.1143)
		(layer "In4.Cu")
		(net "P5E_CPU0_P3_RX_DN<7>")
	)
	(segment
		(start 368.184684 -294.81907)
		(end 368.153442 -294.801036)
		(width 0.1143)
		(layer "In4.Cu")
		(net "P5E_CPU0_P3_RX_DN<7>")
	)
	(segment
		(start 367.915444 -291.178742)
		(end 367.83264 -291.095938)
		(width 0.1143)
		(layer "In4.Cu")
		(net "P5E_CPU0_P3_RX_DN<7>")
	)
	(segment
		(start 379.64491 -393.786868)
		(end 379.766576 -393.716764)
		(width 0.14224)
		(layer "In4.Cu")
		(net "P5E_CPU0_P3_RX_DN<7>")
	)
	(segment
		(start 368.184684 -293.199058)
		(end 368.153442 -293.181024)
		(width 0.1143)
		(layer "In4.Cu")
		(net "P5E_CPU0_P3_RX_DN<7>")
	)
	(segment
		(start 379.449584 -393.22883)
		(end 379.45441 -392.616944)
		(width 0.14224)
		(layer "In4.Cu")
		(net "P5E_CPU0_P3_RX_DN<7>")
	)
	(segment
		(start 368.229896 -293.822882)
		(end 368.230912 -293.822882)
		(width 0.1143)
		(layer "In4.Cu")
		(net "P5E_CPU0_P3_RX_DN<7>")
	)
	(segment
		(start 379.766576 -393.545822)
		(end 379.449584 -393.22883)
		(width 0.14224)
		(layer "In4.Cu")
		(net "P5E_CPU0_P3_RX_DN<7>")
	)
	(segment
		(start 368.192304 -291.583364)
		(end 368.153442 -291.561012)
		(width 0.1143)
		(layer "In4.Cu")
		(net "P5E_CPU0_P3_RX_DN<7>")
	)
	(segment
		(start 368.153442 -292.250876)
		(end 368.192304 -292.228524)
		(width 0.1143)
		(layer "In4.Cu")
		(net "P5E_CPU0_P3_RX_DN<7>")
	)
	(segment
		(start 378.12218 -378.96546)
		(end 378.25934 -378.8283)
		(width 0.14224)
		(layer "In4.Cu")
		(net "P5E_CPU0_P3_RX_DN<7>")
	)
	(segment
		(start 368.186208 -295.47185)
		(end 368.229896 -295.442894)
		(width 0.1143)
		(layer "In4.Cu")
		(net "P5E_CPU0_P3_RX_DN<7>")
	)
	(segment
		(start 368.188748 -293.201344)
		(end 368.184684 -293.199058)
		(width 0.1143)
		(layer "In4.Cu")
		(net "P5E_CPU0_P3_RX_DN<7>")
	)
	(segment
		(start 385.256532 -329.51547)
		(end 380.965456 -317.162434)
		(width 0.14224)
		(layer "In4.Cu")
		(net "P5E_CPU0_P3_RX_DN<7>")
	)
	(segment
		(start 380.020322 -382.95326)
		(end 380.020322 -381.983488)
		(width 0.14224)
		(layer "In4.Cu")
		(net "P5E_CPU0_P3_RX_DN<7>")
	)
	(segment
		(start 367.915698 -291.178742)
		(end 367.915444 -291.178742)
		(width 0.1143)
		(layer "In4.Cu")
		(net "P5E_CPU0_P3_RX_DN<7>")
	)
	(segment
		(start 379.883162 -383.09042)
		(end 380.020322 -382.95326)
		(width 0.14224)
		(layer "In4.Cu")
		(net "P5E_CPU0_P3_RX_DN<7>")
	)
	(segment
		(start 368.181128 -293.854886)
		(end 368.184176 -293.852854)
		(width 0.1143)
		(layer "In4.Cu")
		(net "P5E_CPU0_P3_RX_DN<7>")
	)
	(segment
		(start 379.795278 -381.560832)
		(end 379.577346 -381.413766)
		(width 0.14224)
		(layer "In4.Cu")
		(net "P5E_CPU0_P3_RX_DN<7>")
	)
	(segment
		(start 368.205512 -294.831262)
		(end 368.191542 -294.823134)
		(width 0.1143)
		(layer "In4.Cu")
		(net "P5E_CPU0_P3_RX_DN<7>")
	)
	(segment
		(start 379.883162 -383.51714)
		(end 379.883162 -383.09042)
		(width 0.14224)
		(layer "In4.Cu")
		(net "P5E_CPU0_P3_RX_DN<7>")
	)
	(segment
		(start 378.25934 -378.8283)
		(end 378.25934 -376.053604)
		(width 0.14224)
		(layer "In4.Cu")
		(net "P5E_CPU0_P3_RX_DN<7>")
	)
	(segment
		(start 379.644402 -393.787376)
		(end 379.64491 -393.786868)
		(width 0.14224)
		(layer "In4.Cu")
		(net "P5E_CPU0_P3_RX_DN<7>")
	)
	(segment
		(start 379.766576 -393.716764)
		(end 379.766576 -393.545822)
		(width 0.14224)
		(layer "In4.Cu")
		(net "P5E_CPU0_P3_RX_DN<7>")
	)
	(segment
		(start 380.020322 -384.08102)
		(end 380.020322 -383.6543)
		(width 0.14224)
		(layer "In4.Cu")
		(net "P5E_CPU0_P3_RX_DN<7>")
	)
	(segment
		(start 379.758448 -392.31316)
		(end 379.758448 -390.637268)
		(width 0.14224)
		(layer "In4.Cu")
		(net "P5E_CPU0_P3_RX_DN<7>")
	)
	(segment
		(start 380.965456 -317.162434)
		(end 378.7267 -312.973466)
		(width 0.14224)
		(layer "In4.Cu")
		(net "P5E_CPU0_P3_RX_DN<7>")
	)
	(segment
		(start 368.191542 -294.823134)
		(end 368.188748 -294.821356)
		(width 0.1143)
		(layer "In4.Cu")
		(net "P5E_CPU0_P3_RX_DN<7>")
	)
	(arc
		(start 368.153442 -294.801036)
		(mid 367.90927 -294.336061)
		(end 368.152934 -293.870888)
		(width 0.1143)
		(layer "In4.Cu")
		(net "P5E_CPU0_P3_RX_DN<7>")
	)
	(arc
		(start 368.153442 -293.181024)
		(mid 367.909588 -292.71595)
		(end 368.153442 -292.250876)
		(width 0.1143)
		(layer "In4.Cu")
		(net "P5E_CPU0_P3_RX_DN<7>")
	)
	(arc
		(start 378.4727 -380.515876)
		(mid 378.314815 -380.279396)
		(end 378.25934 -380.00051)
		(width 0.14224)
		(layer "In4.Cu")
		(net "P5E_CPU0_P3_RX_DN<7>")
	)
	(arc
		(start 368.192304 -292.228524)
		(mid 368.377942 -291.905944)
		(end 368.192304 -291.583364)
		(width 0.1143)
		(layer "In4.Cu")
		(net "P5E_CPU0_P3_RX_DN<7>")
	)
	(arc
		(start 379.385576 -381.311658)
		(mid 379.199987 -381.213696)
		(end 379.037596 -381.080772)
		(width 0.14224)
		(layer "In4.Cu")
		(net "P5E_CPU0_P3_RX_DN<7>")
	)
	(arc
		(start 378.25934 -376.053604)
		(mid 378.286274 -375.779632)
		(end 378.36602 -375.51614)
		(width 0.14224)
		(layer "In4.Cu")
		(net "P5E_CPU0_P3_RX_DN<7>")
	)
	(arc
		(start 367.909602 -295.847008)
		(mid 367.997354 -295.643668)
		(end 368.155982 -295.489122)
		(width 0.1143)
		(layer "In4.Cu")
		(net "P5E_CPU0_P3_RX_DN<7>")
	)
	(arc
		(start 367.919508 -291.201348)
		(mid 367.917489 -291.190064)
		(end 367.915698 -291.178742)
		(width 0.1143)
		(layer "In4.Cu")
		(net "P5E_CPU0_P3_RX_DN<7>")
	)
	(arc
		(start 368.153442 -291.561012)
		(mid 368.000968 -291.404261)
		(end 367.919508 -291.201348)
		(width 0.1143)
		(layer "In4.Cu")
		(net "P5E_CPU0_P3_RX_DN<7>")
	)
	(arc
		(start 379.577346 -381.413766)
		(mid 379.483985 -381.357727)
		(end 379.385322 -381.311658)
		(width 0.14224)
		(layer "In4.Cu")
		(net "P5E_CPU0_P3_RX_DN<7>")
	)
	(arc
		(start 368.230912 -293.822882)
		(mid 368.377917 -293.510455)
		(end 368.205512 -293.21125)
		(width 0.1143)
		(layer "In4.Cu")
		(net "P5E_CPU0_P3_RX_DN<7>")
	)
	(arc
		(start 368.230912 -295.442894)
		(mid 368.377917 -295.130467)
		(end 368.205512 -294.831262)
		(width 0.1143)
		(layer "In4.Cu")
		(net "P5E_CPU0_P3_RX_DN<7>")
	)
	(arc
		(start 367.922556 -298.256452)
		(mid 367.878626 -298.11126)
		(end 367.863882 -297.960288)
		(width 0.14224)
		(layer "In4.Cu")
		(net "P5E_CPU0_P3_RX_DN<7>")
	)
	(arc
		(start 380.020322 -381.983488)
		(mid 379.96049 -381.744112)
		(end 379.795278 -381.560832)
		(width 0.14224)
		(layer "In4.Cu")
		(net "P5E_CPU0_P3_RX_DN<7>")
	)
	(segment
		(start 367.067846 -287.59023)
		(end 367.534698 -287.856168)
		(width 0.12954)
		(layer "F.Cu")
		(net "P5E_CPU0_P3_RX_DN<6>")
	)
	(segment
		(start 377.570492 -393.69238)
		(end 378.091192 -393.69238)
		(width 0.127)
		(layer "F.Cu")
		(net "P5E_CPU0_P3_RX_DN<6>")
	)
	(segment
		(start 378.076206 -389.104378)
		(end 377.992894 -388.685786)
		(width 0.14224)
		(layer "In4.Cu")
		(net "P5E_CPU0_P3_RX_DN<6>")
	)
	(segment
		(start 377.964192 -313.527694)
		(end 369.251484 -302.901096)
		(width 0.14224)
		(layer "In4.Cu")
		(net "P5E_CPU0_P3_RX_DN<6>")
	)
	(segment
		(start 367.250726 -293.202868)
		(end 367.212626 -293.180516)
		(width 0.1143)
		(layer "In4.Cu")
		(net "P5E_CPU0_P3_RX_DN<6>")
	)
	(segment
		(start 367.439702 -295.146222)
		(end 367.439702 -295.145968)
		(width 0.1143)
		(layer "In4.Cu")
		(net "P5E_CPU0_P3_RX_DN<6>")
	)
	(segment
		(start 367.250726 -294.82288)
		(end 367.212626 -294.800528)
		(width 0.1143)
		(layer "In4.Cu")
		(net "P5E_CPU0_P3_RX_DN<6>")
	)
	(segment
		(start 367.250726 -292.229032)
		(end 367.251742 -292.228524)
		(width 0.1143)
		(layer "In4.Cu")
		(net "P5E_CPU0_P3_RX_DN<6>")
	)
	(segment
		(start 378.100844 -388.524496)
		(end 378.017786 -388.106158)
		(width 0.14224)
		(layer "In4.Cu")
		(net "P5E_CPU0_P3_RX_DN<6>")
	)
	(segment
		(start 367.251742 -288.9885)
		(end 367.252504 -288.987992)
		(width 0.1143)
		(layer "In4.Cu")
		(net "P5E_CPU0_P3_RX_DN<6>")
	)
	(segment
		(start 385.060444 -333.591916)
		(end 384.411982 -329.98156)
		(width 0.14224)
		(layer "In4.Cu")
		(net "P5E_CPU0_P3_RX_DN<6>")
	)
	(segment
		(start 367.248186 -293.850568)
		(end 367.249202 -293.85006)
		(width 0.1143)
		(layer "In4.Cu")
		(net "P5E_CPU0_P3_RX_DN<6>")
	)
	(segment
		(start 367.253774 -294.824658)
		(end 367.252504 -294.823896)
		(width 0.1143)
		(layer "In4.Cu")
		(net "P5E_CPU0_P3_RX_DN<6>")
	)
	(segment
		(start 367.253774 -288.98723)
		(end 367.255298 -288.986468)
		(width 0.1143)
		(layer "In4.Cu")
		(net "P5E_CPU0_P3_RX_DN<6>")
	)
	(segment
		(start 377.77293 -387.579616)
		(end 377.88088 -387.418326)
		(width 0.14224)
		(layer "In4.Cu")
		(net "P5E_CPU0_P3_RX_DN<6>")
	)
	(segment
		(start 367.240566 -293.85514)
		(end 367.241328 -293.854632)
		(width 0.1143)
		(layer "In4.Cu")
		(net "P5E_CPU0_P3_RX_DN<6>")
	)
	(segment
		(start 367.255298 -288.986468)
		(end 367.25606 -288.98596)
		(width 0.1143)
		(layer "In4.Cu")
		(net "P5E_CPU0_P3_RX_DN<6>")
	)
	(segment
		(start 367.252504 -294.823896)
		(end 367.251742 -294.823388)
		(width 0.1143)
		(layer "In4.Cu")
		(net "P5E_CPU0_P3_RX_DN<6>")
	)
	(segment
		(start 378.457714 -390.318498)
		(end 378.29617 -390.210548)
		(width 0.14224)
		(layer "In4.Cu")
		(net "P5E_CPU0_P3_RX_DN<6>")
	)
	(segment
		(start 367.249202 -291.58184)
		(end 367.248186 -291.581332)
		(width 0.1143)
		(layer "In4.Cu")
		(net "P5E_CPU0_P3_RX_DN<6>")
	)
	(segment
		(start 378.56668 -393.716764)
		(end 378.56668 -393.545822)
		(width 0.14224)
		(layer "In4.Cu")
		(net "P5E_CPU0_P3_RX_DN<6>")
	)
	(segment
		(start 367.721896 -288.178494)
		(end 367.754408 -288.159698)
		(width 0.1143)
		(layer "In4.Cu")
		(net "P5E_CPU0_P3_RX_DN<6>")
	)
	(segment
		(start 367.253774 -291.584634)
		(end 367.252504 -291.583872)
		(width 0.1143)
		(layer "In4.Cu")
		(net "P5E_CPU0_P3_RX_DN<6>")
	)
	(segment
		(start 366.923574 -296.428414)
		(end 366.969294 -296.382694)
		(width 0.1143)
		(layer "In4.Cu")
		(net "P5E_CPU0_P3_RX_DN<6>")
	)
	(segment
		(start 376.844052 -374.568974)
		(end 385.308094 -356.092252)
		(width 0.14224)
		(layer "In4.Cu")
		(net "P5E_CPU0_P3_RX_DN<6>")
	)
	(segment
		(start 367.251742 -293.848536)
		(end 367.252504 -293.848028)
		(width 0.1143)
		(layer "In4.Cu")
		(net "P5E_CPU0_P3_RX_DN<6>")
	)
	(segment
		(start 367.252504 -291.583872)
		(end 367.251742 -291.583364)
		(width 0.1143)
		(layer "In4.Cu")
		(net "P5E_CPU0_P3_RX_DN<6>")
	)
	(segment
		(start 366.742726 -289.821366)
		(end 366.781842 -289.798506)
		(width 0.1143)
		(layer "In4.Cu")
		(net "P5E_CPU0_P3_RX_DN<6>")
	)
	(segment
		(start 369.251484 -302.901096)
		(end 368.132868 -301.223426)
		(width 0.14224)
		(layer "In4.Cu")
		(net "P5E_CPU0_P3_RX_DN<6>")
	)
	(segment
		(start 378.445014 -393.786868)
		(end 378.56668 -393.716764)
		(width 0.14224)
		(layer "In4.Cu")
		(net "P5E_CPU0_P3_RX_DN<6>")
	)
	(segment
		(start 367.257076 -293.845488)
		(end 367.257838 -293.84498)
		(width 0.1143)
		(layer "In4.Cu")
		(net "P5E_CPU0_P3_RX_DN<6>")
	)
	(segment
		(start 366.969294 -296.382694)
		(end 366.969294 -295.955974)
		(width 0.1143)
		(layer "In4.Cu")
		(net "P5E_CPU0_P3_RX_DN<6>")
	)
	(segment
		(start 377.992894 -388.685786)
		(end 378.100844 -388.524496)
		(width 0.14224)
		(layer "In4.Cu")
		(net "P5E_CPU0_P3_RX_DN<6>")
	)
	(segment
		(start 378.23775 -389.212328)
		(end 378.076206 -389.104378)
		(width 0.14224)
		(layer "In4.Cu")
		(net "P5E_CPU0_P3_RX_DN<6>")
	)
	(segment
		(start 367.252504 -292.228016)
		(end 367.253774 -292.227254)
		(width 0.1143)
		(layer "In4.Cu")
		(net "P5E_CPU0_P3_RX_DN<6>")
	)
	(segment
		(start 382.233424 -323.709792)
		(end 380.054866 -317.438278)
		(width 0.14224)
		(layer "In4.Cu")
		(net "P5E_CPU0_P3_RX_DN<6>")
	)
	(segment
		(start 367.249202 -293.85006)
		(end 367.250726 -293.849044)
		(width 0.1143)
		(layer "In4.Cu")
		(net "P5E_CPU0_P3_RX_DN<6>")
	)
	(segment
		(start 367.249202 -292.230048)
		(end 367.250726 -292.229032)
		(width 0.1143)
		(layer "In4.Cu")
		(net "P5E_CPU0_P3_RX_DN<6>")
	)
	(segment
		(start 366.781842 -289.798506)
		(end 366.812322 -289.780726)
		(width 0.1143)
		(layer "In4.Cu")
		(net "P5E_CPU0_P3_RX_DN<6>")
	)
	(segment
		(start 382.23317 -323.709792)
		(end 382.233424 -323.709792)
		(width 0.14224)
		(layer "In4.Cu")
		(net "P5E_CPU0_P3_RX_DN<6>")
	)
	(segment
		(start 367.24463 -291.579046)
		(end 367.210848 -291.559488)
		(width 0.1143)
		(layer "In4.Cu")
		(net "P5E_CPU0_P3_RX_DN<6>")
	)
	(segment
		(start 367.68278 -288.201354)
		(end 367.721896 -288.178494)
		(width 0.1143)
		(layer "In4.Cu")
		(net "P5E_CPU0_P3_RX_DN<6>")
	)
	(segment
		(start 367.248186 -288.990532)
		(end 367.249202 -288.990024)
		(width 0.1143)
		(layer "In4.Cu")
		(net "P5E_CPU0_P3_RX_DN<6>")
	)
	(segment
		(start 367.251742 -291.583364)
		(end 367.250726 -291.582856)
		(width 0.1143)
		(layer "In4.Cu")
		(net "P5E_CPU0_P3_RX_DN<6>")
	)
	(segment
		(start 366.982248 -291.163248)
		(end 366.982248 -291.105336)
		(width 0.1143)
		(layer "In4.Cu")
		(net "P5E_CPU0_P3_RX_DN<6>")
	)
	(segment
		(start 367.248186 -291.581332)
		(end 367.245646 -291.579808)
		(width 0.1143)
		(layer "In4.Cu")
		(net "P5E_CPU0_P3_RX_DN<6>")
	)
	(segment
		(start 367.257076 -288.985452)
		(end 367.257838 -288.984944)
		(width 0.1143)
		(layer "In4.Cu")
		(net "P5E_CPU0_P3_RX_DN<6>")
	)
	(segment
		(start 378.444506 -393.787376)
		(end 378.445014 -393.786868)
		(width 0.14224)
		(layer "In4.Cu")
		(net "P5E_CPU0_P3_RX_DN<6>")
	)
	(segment
		(start 366.923574 -296.456862)
		(end 366.923574 -296.428414)
		(width 0.1143)
		(layer "In4.Cu")
		(net "P5E_CPU0_P3_RX_DN<6>")
	)
	(segment
		(start 378.553472 -392.265916)
		(end 378.540772 -390.736836)
		(width 0.14224)
		(layer "In4.Cu")
		(net "P5E_CPU0_P3_RX_DN<6>")
	)
	(segment
		(start 377.88088 -387.418326)
		(end 377.280424 -384.39725)
		(width 0.14224)
		(layer "In4.Cu")
		(net "P5E_CPU0_P3_RX_DN<6>")
	)
	(segment
		(start 367.245646 -291.579808)
		(end 367.24463 -291.579046)
		(width 0.1143)
		(layer "In4.Cu")
		(net "P5E_CPU0_P3_RX_DN<6>")
	)
	(segment
		(start 367.253774 -293.204646)
		(end 367.252504 -293.203884)
		(width 0.1143)
		(layer "In4.Cu")
		(net "P5E_CPU0_P3_RX_DN<6>")
	)
	(segment
		(start 367.257838 -292.224968)
		(end 367.258854 -292.22446)
		(width 0.1143)
		(layer "In4.Cu")
		(net "P5E_CPU0_P3_RX_DN<6>")
	)
	(segment
		(start 378.29617 -390.210548)
		(end 378.212858 -389.791956)
		(width 0.14224)
		(layer "In4.Cu")
		(net "P5E_CPU0_P3_RX_DN<6>")
	)
	(segment
		(start 376.61088 -382.337818)
		(end 376.61088 -375.712228)
		(width 0.14224)
		(layer "In4.Cu")
		(net "P5E_CPU0_P3_RX_DN<6>")
	)
	(segment
		(start 377.856242 -387.998208)
		(end 377.77293 -387.579616)
		(width 0.14224)
		(layer "In4.Cu")
		(net "P5E_CPU0_P3_RX_DN<6>")
	)
	(segment
		(start 367.251742 -293.203376)
		(end 367.250726 -293.202868)
		(width 0.1143)
		(layer "In4.Cu")
		(net "P5E_CPU0_P3_RX_DN<6>")
	)
	(segment
		(start 367.241328 -292.23462)
		(end 367.248186 -292.230556)
		(width 0.1143)
		(layer "In4.Cu")
		(net "P5E_CPU0_P3_RX_DN<6>")
	)
	(segment
		(start 378.56668 -393.545822)
		(end 378.249688 -393.22883)
		(width 0.14224)
		(layer "In4.Cu")
		(net "P5E_CPU0_P3_RX_DN<6>")
	)
	(segment
		(start 367.257838 -293.84498)
		(end 367.258854 -293.844472)
		(width 0.1143)
		(layer "In4.Cu")
		(net "P5E_CPU0_P3_RX_DN<6>")
	)
	(segment
		(start 385.384802 -335.397348)
		(end 385.384802 -335.397602)
		(width 0.14224)
		(layer "In4.Cu")
		(net "P5E_CPU0_P3_RX_DN<6>")
	)
	(segment
		(start 367.257076 -292.225476)
		(end 367.257838 -292.224968)
		(width 0.1143)
		(layer "In4.Cu")
		(net "P5E_CPU0_P3_RX_DN<6>")
	)
	(segment
		(start 366.796574 -290.781994)
		(end 366.742726 -290.750498)
		(width 0.1143)
		(layer "In4.Cu")
		(net "P5E_CPU0_P3_RX_DN<6>")
	)
	(segment
		(start 378.540772 -390.736836)
		(end 378.457714 -390.318498)
		(width 0.14224)
		(layer "In4.Cu")
		(net "P5E_CPU0_P3_RX_DN<6>")
	)
	(segment
		(start 367.257838 -288.984944)
		(end 367.258854 -288.984436)
		(width 0.1143)
		(layer "In4.Cu")
		(net "P5E_CPU0_P3_RX_DN<6>")
	)
	(segment
		(start 380.054866 -317.438278)
		(end 377.964192 -313.527694)
		(width 0.14224)
		(layer "In4.Cu")
		(net "P5E_CPU0_P3_RX_DN<6>")
	)
	(segment
		(start 368.132868 -301.223426)
		(end 366.954308 -298.361354)
		(width 0.14224)
		(layer "In4.Cu")
		(net "P5E_CPU0_P3_RX_DN<6>")
	)
	(segment
		(start 367.251742 -294.823388)
		(end 367.250726 -294.82288)
		(width 0.1143)
		(layer "In4.Cu")
		(net "P5E_CPU0_P3_RX_DN<6>")
	)
	(segment
		(start 378.249688 -393.22883)
		(end 378.254768 -392.56462)
		(width 0.14224)
		(layer "In4.Cu")
		(net "P5E_CPU0_P3_RX_DN<6>")
	)
	(segment
		(start 385.319016 -356.053136)
		(end 385.70916 -352.43389)
		(width 0.14224)
		(layer "In4.Cu")
		(net "P5E_CPU0_P3_RX_DN<6>")
	)
	(segment
		(start 385.70916 -337.202272)
		(end 385.384802 -335.397348)
		(width 0.14224)
		(layer "In4.Cu")
		(net "P5E_CPU0_P3_RX_DN<6>")
	)
	(segment
		(start 378.254768 -392.56462)
		(end 378.553472 -392.265916)
		(width 0.14224)
		(layer "In4.Cu")
		(net "P5E_CPU0_P3_RX_DN<6>")
	)
	(segment
		(start 367.212626 -292.251384)
		(end 367.240566 -292.235128)
		(width 0.1143)
		(layer "In4.Cu")
		(net "P5E_CPU0_P3_RX_DN<6>")
	)
	(segment
		(start 367.258854 -292.22446)
		(end 367.283492 -292.210236)
		(width 0.1143)
		(layer "In4.Cu")
		(net "P5E_CPU0_P3_RX_DN<6>")
	)
	(segment
		(start 367.252504 -293.203884)
		(end 367.251742 -293.203376)
		(width 0.1143)
		(layer "In4.Cu")
		(net "P5E_CPU0_P3_RX_DN<6>")
	)
	(segment
		(start 367.212626 -289.01136)
		(end 367.240566 -288.995104)
		(width 0.1143)
		(layer "In4.Cu")
		(net "P5E_CPU0_P3_RX_DN<6>")
	)
	(segment
		(start 367.241328 -293.854632)
		(end 367.248186 -293.850568)
		(width 0.1143)
		(layer "In4.Cu")
		(net "P5E_CPU0_P3_RX_DN<6>")
	)
	(segment
		(start 367.283492 -293.221664)
		(end 367.253774 -293.204646)
		(width 0.1143)
		(layer "In4.Cu")
		(net "P5E_CPU0_P3_RX_DN<6>")
	)
	(segment
		(start 367.25606 -293.845996)
		(end 367.257076 -293.845488)
		(width 0.1143)
		(layer "In4.Cu")
		(net "P5E_CPU0_P3_RX_DN<6>")
	)
	(segment
		(start 367.258854 -293.844472)
		(end 367.283492 -293.830248)
		(width 0.1143)
		(layer "In4.Cu")
		(net "P5E_CPU0_P3_RX_DN<6>")
	)
	(segment
		(start 367.283492 -291.601652)
		(end 367.258854 -291.587428)
		(width 0.1143)
		(layer "In4.Cu")
		(net "P5E_CPU0_P3_RX_DN<6>")
	)
	(segment
		(start 378.320808 -389.630666)
		(end 378.23775 -389.212328)
		(width 0.14224)
		(layer "In4.Cu")
		(net "P5E_CPU0_P3_RX_DN<6>")
	)
	(segment
		(start 367.241328 -288.994596)
		(end 367.248186 -288.990532)
		(width 0.1143)
		(layer "In4.Cu")
		(net "P5E_CPU0_P3_RX_DN<6>")
	)
	(segment
		(start 367.25606 -288.98596)
		(end 367.257076 -288.985452)
		(width 0.1143)
		(layer "In4.Cu")
		(net "P5E_CPU0_P3_RX_DN<6>")
	)
	(segment
		(start 367.252504 -288.987992)
		(end 367.253774 -288.98723)
		(width 0.1143)
		(layer "In4.Cu")
		(net "P5E_CPU0_P3_RX_DN<6>")
	)
	(segment
		(start 367.258854 -288.984436)
		(end 367.283492 -288.970212)
		(width 0.1143)
		(layer "In4.Cu")
		(net "P5E_CPU0_P3_RX_DN<6>")
	)
	(segment
		(start 367.25606 -292.225984)
		(end 367.257076 -292.225476)
		(width 0.1143)
		(layer "In4.Cu")
		(net "P5E_CPU0_P3_RX_DN<6>")
	)
	(segment
		(start 366.923574 -298.205652)
		(end 366.923574 -296.456862)
		(width 0.14224)
		(layer "In4.Cu")
		(net "P5E_CPU0_P3_RX_DN<6>")
	)
	(segment
		(start 367.248186 -292.230556)
		(end 367.249202 -292.230048)
		(width 0.1143)
		(layer "In4.Cu")
		(net "P5E_CPU0_P3_RX_DN<6>")
	)
	(segment
		(start 367.250726 -291.582856)
		(end 367.249202 -291.58184)
		(width 0.1143)
		(layer "In4.Cu")
		(net "P5E_CPU0_P3_RX_DN<6>")
	)
	(segment
		(start 367.253774 -292.227254)
		(end 367.255298 -292.226492)
		(width 0.1143)
		(layer "In4.Cu")
		(net "P5E_CPU0_P3_RX_DN<6>")
	)
	(segment
		(start 367.249202 -288.990024)
		(end 367.250726 -288.989008)
		(width 0.1143)
		(layer "In4.Cu")
		(net "P5E_CPU0_P3_RX_DN<6>")
	)
	(segment
		(start 367.253774 -293.847266)
		(end 367.255298 -293.846504)
		(width 0.1143)
		(layer "In4.Cu")
		(net "P5E_CPU0_P3_RX_DN<6>")
	)
	(segment
		(start 367.258854 -291.587428)
		(end 367.257838 -291.58692)
		(width 0.1143)
		(layer "In4.Cu")
		(net "P5E_CPU0_P3_RX_DN<6>")
	)
	(segment
		(start 384.411982 -329.98156)
		(end 382.23317 -323.709792)
		(width 0.14224)
		(layer "In4.Cu")
		(net "P5E_CPU0_P3_RX_DN<6>")
	)
	(segment
		(start 367.90249 -287.926018)
		(end 367.83264 -287.856168)
		(width 0.1143)
		(layer "In4.Cu")
		(net "P5E_CPU0_P3_RX_DN<6>")
	)
	(segment
		(start 367.83264 -287.856168)
		(end 367.534698 -287.856168)
		(width 0.1143)
		(layer "In4.Cu")
		(net "P5E_CPU0_P3_RX_DN<6>")
	)
	(segment
		(start 367.213896 -295.490392)
		(end 367.284508 -295.449244)
		(width 0.1143)
		(layer "In4.Cu")
		(net "P5E_CPU0_P3_RX_DN<6>")
	)
	(segment
		(start 385.70916 -352.43389)
		(end 385.70916 -337.202272)
		(width 0.14224)
		(layer "In4.Cu")
		(net "P5E_CPU0_P3_RX_DN<6>")
	)
	(segment
		(start 378.212858 -389.791956)
		(end 378.320808 -389.630666)
		(width 0.14224)
		(layer "In4.Cu")
		(net "P5E_CPU0_P3_RX_DN<6>")
	)
	(segment
		(start 377.012708 -383.562352)
		(end 376.748294 -382.97612)
		(width 0.14224)
		(layer "In4.Cu")
		(net "P5E_CPU0_P3_RX_DN<6>")
	)
	(segment
		(start 367.212626 -293.871396)
		(end 367.240566 -293.85514)
		(width 0.1143)
		(layer "In4.Cu")
		(net "P5E_CPU0_P3_RX_DN<6>")
	)
	(segment
		(start 367.255298 -292.226492)
		(end 367.25606 -292.225984)
		(width 0.1143)
		(layer "In4.Cu")
		(net "P5E_CPU0_P3_RX_DN<6>")
	)
	(segment
		(start 367.257838 -291.58692)
		(end 367.256314 -291.585904)
		(width 0.1143)
		(layer "In4.Cu")
		(net "P5E_CPU0_P3_RX_DN<6>")
	)
	(segment
		(start 367.255298 -293.846504)
		(end 367.25606 -293.845996)
		(width 0.1143)
		(layer "In4.Cu")
		(net "P5E_CPU0_P3_RX_DN<6>")
	)
	(segment
		(start 367.240566 -288.995104)
		(end 367.241328 -288.994596)
		(width 0.1143)
		(layer "In4.Cu")
		(net "P5E_CPU0_P3_RX_DN<6>")
	)
	(segment
		(start 385.384802 -335.397602)
		(end 385.060444 -333.593186)
		(width 0.14224)
		(layer "In4.Cu")
		(net "P5E_CPU0_P3_RX_DN<6>")
	)
	(segment
		(start 367.251742 -292.228524)
		(end 367.252504 -292.228016)
		(width 0.1143)
		(layer "In4.Cu")
		(net "P5E_CPU0_P3_RX_DN<6>")
	)
	(segment
		(start 367.240566 -292.235128)
		(end 367.241328 -292.23462)
		(width 0.1143)
		(layer "In4.Cu")
		(net "P5E_CPU0_P3_RX_DN<6>")
	)
	(segment
		(start 367.256314 -291.585904)
		(end 367.253774 -291.584634)
		(width 0.1143)
		(layer "In4.Cu")
		(net "P5E_CPU0_P3_RX_DN<6>")
	)
	(segment
		(start 367.250726 -293.849044)
		(end 367.251742 -293.848536)
		(width 0.1143)
		(layer "In4.Cu")
		(net "P5E_CPU0_P3_RX_DN<6>")
	)
	(segment
		(start 367.252504 -293.848028)
		(end 367.253774 -293.847266)
		(width 0.1143)
		(layer "In4.Cu")
		(net "P5E_CPU0_P3_RX_DN<6>")
	)
	(segment
		(start 367.283492 -294.841676)
		(end 367.253774 -294.824658)
		(width 0.1143)
		(layer "In4.Cu")
		(net "P5E_CPU0_P3_RX_DN<6>")
	)
	(segment
		(start 378.091192 -393.69238)
		(end 378.444506 -393.787376)
		(width 0.14224)
		(layer "In4.Cu")
		(net "P5E_CPU0_P3_RX_DN<6>")
	)
	(segment
		(start 378.017786 -388.106158)
		(end 377.856242 -387.998208)
		(width 0.14224)
		(layer "In4.Cu")
		(net "P5E_CPU0_P3_RX_DN<6>")
	)
	(segment
		(start 367.250726 -288.989008)
		(end 367.251742 -288.9885)
		(width 0.1143)
		(layer "In4.Cu")
		(net "P5E_CPU0_P3_RX_DN<6>")
	)
	(segment
		(start 385.060444 -333.593186)
		(end 385.060444 -333.591916)
		(width 0.14224)
		(layer "In4.Cu")
		(net "P5E_CPU0_P3_RX_DN<6>")
	)
	(arc
		(start 376.68962 -375.01195)
		(mid 376.756446 -374.786839)
		(end 376.844052 -374.568974)
		(width 0.14224)
		(layer "In4.Cu")
		(net "P5E_CPU0_P3_RX_DN<6>")
	)
	(arc
		(start 376.748294 -382.97612)
		(mid 376.645655 -382.664276)
		(end 376.61088 -382.337818)
		(width 0.14224)
		(layer "In4.Cu")
		(net "P5E_CPU0_P3_RX_DN<6>")
	)
	(arc
		(start 367.284508 -295.449244)
		(mid 367.398603 -295.316423)
		(end 367.439702 -295.146222)
		(width 0.1143)
		(layer "In4.Cu")
		(net "P5E_CPU0_P3_RX_DN<6>")
	)
	(arc
		(start 376.688858 -375.01449)
		(mid 376.689239 -375.01322)
		(end 376.68962 -375.01195)
		(width 0.14224)
		(layer "In4.Cu")
		(net "P5E_CPU0_P3_RX_DN<6>")
	)
	(arc
		(start 367.210848 -291.559488)
		(mid 367.043496 -291.391975)
		(end 366.982248 -291.163248)
		(width 0.1143)
		(layer "In4.Cu")
		(net "P5E_CPU0_P3_RX_DN<6>")
	)
	(arc
		(start 366.969294 -295.955974)
		(mid 366.969281 -295.952037)
		(end 366.969294 -295.9481)
		(width 0.1143)
		(layer "In4.Cu")
		(net "P5E_CPU0_P3_RX_DN<6>")
	)
	(arc
		(start 366.969294 -295.9481)
		(mid 367.03464 -295.699877)
		(end 367.197894 -295.501822)
		(width 0.1143)
		(layer "In4.Cu")
		(net "P5E_CPU0_P3_RX_DN<6>")
	)
	(arc
		(start 367.213134 -295.4909)
		(mid 367.213515 -295.490646)
		(end 367.213896 -295.490392)
		(width 0.1143)
		(layer "In4.Cu")
		(net "P5E_CPU0_P3_RX_DN<6>")
	)
	(arc
		(start 367.283492 -288.970212)
		(mid 367.398168 -288.836878)
		(end 367.439448 -288.66592)
		(width 0.1143)
		(layer "In4.Cu")
		(net "P5E_CPU0_P3_RX_DN<6>")
	)
	(arc
		(start 367.439448 -288.66592)
		(mid 367.503963 -288.403701)
		(end 367.68278 -288.201354)
		(width 0.1143)
		(layer "In4.Cu")
		(net "P5E_CPU0_P3_RX_DN<6>")
	)
	(arc
		(start 377.280424 -384.39725)
		(mid 377.231878 -384.185022)
		(end 377.171458 -383.975864)
		(width 0.14224)
		(layer "In4.Cu")
		(net "P5E_CPU0_P3_RX_DN<6>")
	)
	(arc
		(start 366.812322 -289.780726)
		(mid 366.927749 -289.64735)
		(end 366.969294 -289.475926)
		(width 0.1143)
		(layer "In4.Cu")
		(net "P5E_CPU0_P3_RX_DN<6>")
	)
	(arc
		(start 367.754408 -288.159698)
		(mid 367.850848 -288.057043)
		(end 367.90249 -287.926018)
		(width 0.1143)
		(layer "In4.Cu")
		(net "P5E_CPU0_P3_RX_DN<6>")
	)
	(arc
		(start 367.212626 -293.180516)
		(mid 366.969299 -292.71595)
		(end 367.212626 -292.251384)
		(width 0.1143)
		(layer "In4.Cu")
		(net "P5E_CPU0_P3_RX_DN<6>")
	)
	(arc
		(start 367.212626 -294.800528)
		(mid 366.969299 -294.335962)
		(end 367.212626 -293.871396)
		(width 0.1143)
		(layer "In4.Cu")
		(net "P5E_CPU0_P3_RX_DN<6>")
	)
	(arc
		(start 377.171458 -383.975864)
		(mid 377.098016 -383.76683)
		(end 377.012708 -383.562352)
		(width 0.14224)
		(layer "In4.Cu")
		(net "P5E_CPU0_P3_RX_DN<6>")
	)
	(arc
		(start 376.61088 -375.712228)
		(mid 376.630417 -375.361185)
		(end 376.688858 -375.01449)
		(width 0.14224)
		(layer "In4.Cu")
		(net "P5E_CPU0_P3_RX_DN<6>")
	)
	(arc
		(start 366.969294 -289.475926)
		(mid 367.033809 -289.213707)
		(end 367.212626 -289.01136)
		(width 0.1143)
		(layer "In4.Cu")
		(net "P5E_CPU0_P3_RX_DN<6>")
	)
	(arc
		(start 367.197894 -295.501822)
		(mid 367.205468 -295.496297)
		(end 367.213134 -295.4909)
		(width 0.1143)
		(layer "In4.Cu")
		(net "P5E_CPU0_P3_RX_DN<6>")
	)
	(arc
		(start 367.283492 -292.210236)
		(mid 367.43942 -291.905944)
		(end 367.283492 -291.601652)
		(width 0.1143)
		(layer "In4.Cu")
		(net "P5E_CPU0_P3_RX_DN<6>")
	)
	(arc
		(start 366.982248 -291.105336)
		(mid 366.932529 -290.918904)
		(end 366.796574 -290.781994)
		(width 0.1143)
		(layer "In4.Cu")
		(net "P5E_CPU0_P3_RX_DN<6>")
	)
	(arc
		(start 367.283492 -293.830248)
		(mid 367.43942 -293.525956)
		(end 367.283492 -293.221664)
		(width 0.1143)
		(layer "In4.Cu")
		(net "P5E_CPU0_P3_RX_DN<6>")
	)
	(arc
		(start 385.308094 -356.092252)
		(mid 385.315151 -356.073138)
		(end 385.319016 -356.053136)
		(width 0.14224)
		(layer "In4.Cu")
		(net "P5E_CPU0_P3_RX_DN<6>")
	)
	(arc
		(start 366.954308 -298.361354)
		(mid 366.931313 -298.285007)
		(end 366.923574 -298.205652)
		(width 0.14224)
		(layer "In4.Cu")
		(net "P5E_CPU0_P3_RX_DN<6>")
	)
	(arc
		(start 366.742726 -290.750498)
		(mid 366.499399 -290.285932)
		(end 366.742726 -289.821366)
		(width 0.1143)
		(layer "In4.Cu")
		(net "P5E_CPU0_P3_RX_DN<6>")
	)
	(arc
		(start 367.439702 -295.145968)
		(mid 367.398362 -294.974953)
		(end 367.283492 -294.841676)
		(width 0.1143)
		(layer "In4.Cu")
		(net "P5E_CPU0_P3_RX_DN<6>")
	)
	(segment
		(start 364.247938 -289.209988)
		(end 364.71479 -289.475926)
		(width 0.12954)
		(layer "F.Cu")
		(net "P5E_CPU0_P3_RX_DN<5>")
	)
	(segment
		(start 376.370596 -393.69238)
		(end 376.891296 -393.69238)
		(width 0.127)
		(layer "F.Cu")
		(net "P5E_CPU0_P3_RX_DN<5>")
	)
	(segment
		(start 366.311942 -293.203376)
		(end 366.272826 -293.180516)
		(width 0.1143)
		(layer "In4.Cu")
		(net "P5E_CPU0_P3_RX_DN<5>")
	)
	(segment
		(start 365.984028 -298.224448)
		(end 365.984028 -296.35831)
		(width 0.14224)
		(layer "In4.Cu")
		(net "P5E_CPU0_P3_RX_DN<5>")
	)
	(segment
		(start 377.34621 -390.713214)
		(end 377.207272 -390.014206)
		(width 0.14224)
		(layer "In4.Cu")
		(net "P5E_CPU0_P3_RX_DN<5>")
	)
	(segment
		(start 366.311942 -291.583364)
		(end 366.272826 -291.560504)
		(width 0.1143)
		(layer "In4.Cu")
		(net "P5E_CPU0_P3_RX_DN<5>")
	)
	(segment
		(start 376.62993 -387.114034)
		(end 376.098816 -384.443224)
		(width 0.14224)
		(layer "In4.Cu")
		(net "P5E_CPU0_P3_RX_DN<5>")
	)
	(segment
		(start 377.366784 -393.716764)
		(end 377.366784 -393.545822)
		(width 0.14224)
		(layer "In4.Cu")
		(net "P5E_CPU0_P3_RX_DN<5>")
	)
	(segment
		(start 376.987054 -388.908036)
		(end 376.82551 -388.80034)
		(width 0.14224)
		(layer "In4.Cu")
		(net "P5E_CPU0_P3_RX_DN<5>")
	)
	(segment
		(start 377.056904 -392.439906)
		(end 377.358656 -392.138154)
		(width 0.14224)
		(layer "In4.Cu")
		(net "P5E_CPU0_P3_RX_DN<5>")
	)
	(segment
		(start 384.77698 -337.288378)
		(end 383.507488 -330.222352)
		(width 0.14224)
		(layer "In4.Cu")
		(net "P5E_CPU0_P3_RX_DN<5>")
	)
	(segment
		(start 374.690132 -379.097032)
		(end 374.471946 -378.949966)
		(width 0.14224)
		(layer "In4.Cu")
		(net "P5E_CPU0_P3_RX_DN<5>")
	)
	(segment
		(start 377.045728 -389.90651)
		(end 376.962416 -389.487664)
		(width 0.14224)
		(layer "In4.Cu")
		(net "P5E_CPU0_P3_RX_DN<5>")
	)
	(segment
		(start 366.272826 -292.251384)
		(end 366.311942 -292.228524)
		(width 0.1143)
		(layer "In4.Cu")
		(net "P5E_CPU0_P3_RX_DN<5>")
	)
	(segment
		(start 383.507488 -330.222352)
		(end 379.198632 -317.815722)
		(width 0.14224)
		(layer "In4.Cu")
		(net "P5E_CPU0_P3_RX_DN<5>")
	)
	(segment
		(start 376.742198 -388.381494)
		(end 376.849894 -388.220204)
		(width 0.14224)
		(layer "In4.Cu")
		(net "P5E_CPU0_P3_RX_DN<5>")
	)
	(segment
		(start 366.029748 -296.284142)
		(end 366.029748 -295.955974)
		(width 0.1143)
		(layer "In4.Cu")
		(net "P5E_CPU0_P3_RX_DN<5>")
	)
	(segment
		(start 376.82551 -388.80034)
		(end 376.742198 -388.381494)
		(width 0.14224)
		(layer "In4.Cu")
		(net "P5E_CPU0_P3_RX_DN<5>")
	)
	(segment
		(start 377.366784 -393.545822)
		(end 377.049538 -393.22883)
		(width 0.14224)
		(layer "In4.Cu")
		(net "P5E_CPU0_P3_RX_DN<5>")
	)
	(segment
		(start 384.178556 -355.98354)
		(end 384.77698 -351.131632)
		(width 0.14224)
		(layer "In4.Cu")
		(net "P5E_CPU0_P3_RX_DN<5>")
	)
	(segment
		(start 366.311942 -294.823388)
		(end 366.272826 -294.800528)
		(width 0.1143)
		(layer "In4.Cu")
		(net "P5E_CPU0_P3_RX_DN<5>")
	)
	(segment
		(start 377.24461 -393.787376)
		(end 377.245118 -393.786868)
		(width 0.14224)
		(layer "In4.Cu")
		(net "P5E_CPU0_P3_RX_DN<5>")
	)
	(segment
		(start 376.605292 -387.693916)
		(end 376.52198 -387.275324)
		(width 0.14224)
		(layer "In4.Cu")
		(net "P5E_CPU0_P3_RX_DN<5>")
	)
	(segment
		(start 365.873538 -290.791646)
		(end 365.8489 -290.777422)
		(width 0.1143)
		(layer "In4.Cu")
		(net "P5E_CPU0_P3_RX_DN<5>")
	)
	(segment
		(start 365.84382 -290.774628)
		(end 365.84255 -290.773866)
		(width 0.1143)
		(layer "In4.Cu")
		(net "P5E_CPU0_P3_RX_DN<5>")
	)
	(segment
		(start 366.311942 -293.848536)
		(end 366.342422 -293.830756)
		(width 0.1143)
		(layer "In4.Cu")
		(net "P5E_CPU0_P3_RX_DN<5>")
	)
	(segment
		(start 373.932196 -378.616972)
		(end 373.363236 -378.048012)
		(width 0.14224)
		(layer "In4.Cu")
		(net "P5E_CPU0_P3_RX_DN<5>")
	)
	(segment
		(start 377.049538 -393.22883)
		(end 377.056904 -392.439906)
		(width 0.14224)
		(layer "In4.Cu")
		(net "P5E_CPU0_P3_RX_DN<5>")
	)
	(segment
		(start 366.272826 -295.491408)
		(end 366.342422 -295.450768)
		(width 0.1143)
		(layer "In4.Cu")
		(net "P5E_CPU0_P3_RX_DN<5>")
	)
	(segment
		(start 376.849894 -388.220204)
		(end 376.766836 -387.801866)
		(width 0.14224)
		(layer "In4.Cu")
		(net "P5E_CPU0_P3_RX_DN<5>")
	)
	(segment
		(start 366.272826 -293.871396)
		(end 366.311942 -293.848536)
		(width 0.1143)
		(layer "In4.Cu")
		(net "P5E_CPU0_P3_RX_DN<5>")
	)
	(segment
		(start 373.208042 -377.673362)
		(end 373.208042 -376.743214)
		(width 0.14224)
		(layer "In4.Cu")
		(net "P5E_CPU0_P3_RX_DN<5>")
	)
	(segment
		(start 365.984028 -296.35831)
		(end 365.984028 -296.329862)
		(width 0.1143)
		(layer "In4.Cu")
		(net "P5E_CPU0_P3_RX_DN<5>")
	)
	(segment
		(start 365.37519 -289.96513)
		(end 365.372396 -289.963606)
		(width 0.1143)
		(layer "In4.Cu")
		(net "P5E_CPU0_P3_RX_DN<5>")
	)
	(segment
		(start 365.012732 -289.475926)
		(end 364.71479 -289.475926)
		(width 0.1143)
		(layer "In4.Cu")
		(net "P5E_CPU0_P3_RX_DN<5>")
	)
	(segment
		(start 365.095536 -289.55873)
		(end 365.012732 -289.475926)
		(width 0.1143)
		(layer "In4.Cu")
		(net "P5E_CPU0_P3_RX_DN<5>")
	)
	(segment
		(start 367.314226 -301.683928)
		(end 366.079024 -298.702222)
		(width 0.14224)
		(layer "In4.Cu")
		(net "P5E_CPU0_P3_RX_DN<5>")
	)
	(segment
		(start 377.191016 -314.059062)
		(end 368.527584 -303.501552)
		(width 0.14224)
		(layer "In4.Cu")
		(net "P5E_CPU0_P3_RX_DN<5>")
	)
	(segment
		(start 365.84255 -290.773866)
		(end 365.841788 -290.773358)
		(width 0.1143)
		(layer "In4.Cu")
		(net "P5E_CPU0_P3_RX_DN<5>")
	)
	(segment
		(start 373.31015 -376.33402)
		(end 384.164332 -356.027736)
		(width 0.14224)
		(layer "In4.Cu")
		(net "P5E_CPU0_P3_RX_DN<5>")
	)
	(segment
		(start 377.358656 -392.138154)
		(end 377.358656 -390.838944)
		(width 0.14224)
		(layer "In4.Cu")
		(net "P5E_CPU0_P3_RX_DN<5>")
	)
	(segment
		(start 377.207272 -390.014206)
		(end 377.045728 -389.90651)
		(width 0.14224)
		(layer "In4.Cu")
		(net "P5E_CPU0_P3_RX_DN<5>")
	)
	(segment
		(start 365.371634 -289.963098)
		(end 365.333534 -289.941)
		(width 0.1143)
		(layer "In4.Cu")
		(net "P5E_CPU0_P3_RX_DN<5>")
	)
	(segment
		(start 377.070112 -389.326374)
		(end 376.987054 -388.908036)
		(width 0.14224)
		(layer "In4.Cu")
		(net "P5E_CPU0_P3_RX_DN<5>")
	)
	(segment
		(start 368.527584 -303.501552)
		(end 367.314226 -301.683928)
		(width 0.14224)
		(layer "In4.Cu")
		(net "P5E_CPU0_P3_RX_DN<5>")
	)
	(segment
		(start 384.77698 -351.131632)
		(end 384.77698 -337.288378)
		(width 0.14224)
		(layer "In4.Cu")
		(net "P5E_CPU0_P3_RX_DN<5>")
	)
	(segment
		(start 365.8489 -290.777422)
		(end 365.847884 -290.776914)
		(width 0.1143)
		(layer "In4.Cu")
		(net "P5E_CPU0_P3_RX_DN<5>")
	)
	(segment
		(start 376.766836 -387.801866)
		(end 376.605292 -387.693916)
		(width 0.14224)
		(layer "In4.Cu")
		(net "P5E_CPU0_P3_RX_DN<5>")
	)
	(segment
		(start 374.914922 -380.862332)
		(end 374.914922 -379.519688)
		(width 0.14224)
		(layer "In4.Cu")
		(net "P5E_CPU0_P3_RX_DN<5>")
	)
	(segment
		(start 366.342422 -293.221156)
		(end 366.311942 -293.203376)
		(width 0.1143)
		(layer "In4.Cu")
		(net "P5E_CPU0_P3_RX_DN<5>")
	)
	(segment
		(start 366.311942 -292.228524)
		(end 366.342422 -292.210744)
		(width 0.1143)
		(layer "In4.Cu")
		(net "P5E_CPU0_P3_RX_DN<5>")
	)
	(segment
		(start 366.342422 -294.841168)
		(end 366.311942 -294.823388)
		(width 0.1143)
		(layer "In4.Cu")
		(net "P5E_CPU0_P3_RX_DN<5>")
	)
	(segment
		(start 379.198632 -317.815722)
		(end 377.191016 -314.059062)
		(width 0.14224)
		(layer "In4.Cu")
		(net "P5E_CPU0_P3_RX_DN<5>")
	)
	(segment
		(start 366.342422 -291.601144)
		(end 366.311942 -291.583364)
		(width 0.1143)
		(layer "In4.Cu")
		(net "P5E_CPU0_P3_RX_DN<5>")
	)
	(segment
		(start 365.841788 -290.773358)
		(end 365.831882 -290.767262)
		(width 0.1143)
		(layer "In4.Cu")
		(net "P5E_CPU0_P3_RX_DN<5>")
	)
	(segment
		(start 365.984028 -296.329862)
		(end 366.029748 -296.284142)
		(width 0.1143)
		(layer "In4.Cu")
		(net "P5E_CPU0_P3_RX_DN<5>")
	)
	(segment
		(start 365.372396 -289.963606)
		(end 365.371634 -289.963098)
		(width 0.1143)
		(layer "In4.Cu")
		(net "P5E_CPU0_P3_RX_DN<5>")
	)
	(segment
		(start 374.279922 -378.847858)
		(end 374.280176 -378.847858)
		(width 0.14224)
		(layer "In4.Cu")
		(net "P5E_CPU0_P3_RX_DN<5>")
	)
	(segment
		(start 365.84636 -290.775898)
		(end 365.84382 -290.774628)
		(width 0.1143)
		(layer "In4.Cu")
		(net "P5E_CPU0_P3_RX_DN<5>")
	)
	(segment
		(start 376.52198 -387.275324)
		(end 376.62993 -387.114034)
		(width 0.14224)
		(layer "In4.Cu")
		(net "P5E_CPU0_P3_RX_DN<5>")
	)
	(segment
		(start 376.891296 -393.69238)
		(end 377.24461 -393.787376)
		(width 0.14224)
		(layer "In4.Cu")
		(net "P5E_CPU0_P3_RX_DN<5>")
	)
	(segment
		(start 377.245118 -393.786868)
		(end 377.366784 -393.716764)
		(width 0.14224)
		(layer "In4.Cu")
		(net "P5E_CPU0_P3_RX_DN<5>")
	)
	(segment
		(start 376.962416 -389.487664)
		(end 377.070112 -389.326374)
		(width 0.14224)
		(layer "In4.Cu")
		(net "P5E_CPU0_P3_RX_DN<5>")
	)
	(segment
		(start 365.847884 -290.776914)
		(end 365.84636 -290.775898)
		(width 0.1143)
		(layer "In4.Cu")
		(net "P5E_CPU0_P3_RX_DN<5>")
	)
	(arc
		(start 366.029494 -291.095938)
		(mid 365.988239 -290.924967)
		(end 365.873538 -290.791646)
		(width 0.1143)
		(layer "In4.Cu")
		(net "P5E_CPU0_P3_RX_DN<5>")
	)
	(arc
		(start 366.029748 -295.955974)
		(mid 366.094122 -295.69377)
		(end 366.272826 -295.491408)
		(width 0.1143)
		(layer "In4.Cu")
		(net "P5E_CPU0_P3_RX_DN<5>")
	)
	(arc
		(start 365.332772 -289.940492)
		(mid 365.180785 -289.783984)
		(end 365.099346 -289.58159)
		(width 0.1143)
		(layer "In4.Cu")
		(net "P5E_CPU0_P3_RX_DN<5>")
	)
	(arc
		(start 384.164332 -356.027736)
		(mid 384.173472 -356.006292)
		(end 384.178556 -355.98354)
		(width 0.14224)
		(layer "In4.Cu")
		(net "P5E_CPU0_P3_RX_DN<5>")
	)
	(arc
		(start 374.914922 -379.519688)
		(mid 374.855232 -379.280326)
		(end 374.690132 -379.097032)
		(width 0.14224)
		(layer "In4.Cu")
		(net "P5E_CPU0_P3_RX_DN<5>")
	)
	(arc
		(start 365.333534 -289.941)
		(mid 365.333153 -289.940746)
		(end 365.332772 -289.940492)
		(width 0.1143)
		(layer "In4.Cu")
		(net "P5E_CPU0_P3_RX_DN<5>")
	)
	(arc
		(start 374.280176 -378.847858)
		(mid 374.094587 -378.749896)
		(end 373.932196 -378.616972)
		(width 0.14224)
		(layer "In4.Cu")
		(net "P5E_CPU0_P3_RX_DN<5>")
	)
	(arc
		(start 375.600976 -383.246376)
		(mid 375.089904 -382.102714)
		(end 374.914922 -380.862332)
		(width 0.14224)
		(layer "In4.Cu")
		(net "P5E_CPU0_P3_RX_DN<5>")
	)
	(arc
		(start 373.363236 -378.048012)
		(mid 373.248382 -377.876121)
		(end 373.208042 -377.673362)
		(width 0.14224)
		(layer "In4.Cu")
		(net "P5E_CPU0_P3_RX_DN<5>")
	)
	(arc
		(start 366.342422 -292.210744)
		(mid 366.499399 -291.905944)
		(end 366.342422 -291.601144)
		(width 0.1143)
		(layer "In4.Cu")
		(net "P5E_CPU0_P3_RX_DN<5>")
	)
	(arc
		(start 366.342422 -293.830756)
		(mid 366.499399 -293.525956)
		(end 366.342422 -293.221156)
		(width 0.1143)
		(layer "In4.Cu")
		(net "P5E_CPU0_P3_RX_DN<5>")
	)
	(arc
		(start 376.098816 -384.443224)
		(mid 375.899664 -383.8241)
		(end 375.600976 -383.246376)
		(width 0.14224)
		(layer "In4.Cu")
		(net "P5E_CPU0_P3_RX_DN<5>")
	)
	(arc
		(start 365.831882 -290.767262)
		(mid 365.631824 -290.561473)
		(end 365.558832 -290.2839)
		(width 0.1143)
		(layer "In4.Cu")
		(net "P5E_CPU0_P3_RX_DN<5>")
	)
	(arc
		(start 365.558832 -290.2839)
		(mid 365.509643 -290.099949)
		(end 365.37519 -289.96513)
		(width 0.1143)
		(layer "In4.Cu")
		(net "P5E_CPU0_P3_RX_DN<5>")
	)
	(arc
		(start 374.471946 -378.949966)
		(mid 374.378585 -378.893927)
		(end 374.279922 -378.847858)
		(width 0.14224)
		(layer "In4.Cu")
		(net "P5E_CPU0_P3_RX_DN<5>")
	)
	(arc
		(start 366.079024 -298.702222)
		(mid 366.008005 -298.468012)
		(end 365.984028 -298.224448)
		(width 0.14224)
		(layer "In4.Cu")
		(net "P5E_CPU0_P3_RX_DN<5>")
	)
	(arc
		(start 377.358656 -390.838944)
		(mid 377.355528 -390.775772)
		(end 377.34621 -390.713214)
		(width 0.14224)
		(layer "In4.Cu")
		(net "P5E_CPU0_P3_RX_DN<5>")
	)
	(arc
		(start 366.272826 -291.560504)
		(mid 366.094013 -291.358154)
		(end 366.029494 -291.095938)
		(width 0.1143)
		(layer "In4.Cu")
		(net "P5E_CPU0_P3_RX_DN<5>")
	)
	(arc
		(start 365.099346 -289.58159)
		(mid 365.097323 -289.57018)
		(end 365.095536 -289.55873)
		(width 0.1143)
		(layer "In4.Cu")
		(net "P5E_CPU0_P3_RX_DN<5>")
	)
	(arc
		(start 366.272826 -293.180516)
		(mid 366.029499 -292.71595)
		(end 366.272826 -292.251384)
		(width 0.1143)
		(layer "In4.Cu")
		(net "P5E_CPU0_P3_RX_DN<5>")
	)
	(arc
		(start 366.342422 -295.450768)
		(mid 366.499399 -295.145968)
		(end 366.342422 -294.841168)
		(width 0.1143)
		(layer "In4.Cu")
		(net "P5E_CPU0_P3_RX_DN<5>")
	)
	(arc
		(start 373.208042 -376.743214)
		(mid 373.23387 -376.532324)
		(end 373.31015 -376.33402)
		(width 0.14224)
		(layer "In4.Cu")
		(net "P5E_CPU0_P3_RX_DN<5>")
	)
	(arc
		(start 366.272826 -294.800528)
		(mid 366.029499 -294.335962)
		(end 366.272826 -293.871396)
		(width 0.1143)
		(layer "In4.Cu")
		(net "P5E_CPU0_P3_RX_DN<5>")
	)
	(segment
		(start 375.170446 -393.69238)
		(end 375.691146 -393.69238)
		(width 0.127)
		(layer "F.Cu")
		(net "P5E_CPU0_P3_RX_DN<4>")
	)
	(segment
		(start 364.247938 -290.83)
		(end 364.71479 -291.095938)
		(width 0.12954)
		(layer "F.Cu")
		(net "P5E_CPU0_P3_RX_DN<4>")
	)
	(segment
		(start 366.47628 -302.115474)
		(end 365.082836 -298.751752)
		(width 0.14224)
		(layer "In4.Cu")
		(net "P5E_CPU0_P3_RX_DN<4>")
	)
	(segment
		(start 365.09579 -291.178742)
		(end 365.095536 -291.178742)
		(width 0.1143)
		(layer "In4.Cu")
		(net "P5E_CPU0_P3_RX_DN<4>")
	)
	(segment
		(start 365.051848 -296.33418)
		(end 365.097568 -296.28846)
		(width 0.1143)
		(layer "In4.Cu")
		(net "P5E_CPU0_P3_RX_DN<4>")
	)
	(segment
		(start 382.60147 -330.456032)
		(end 378.340874 -318.19088)
		(width 0.14224)
		(layer "In4.Cu")
		(net "P5E_CPU0_P3_RX_DN<4>")
	)
	(segment
		(start 383.8448 -337.37677)
		(end 383.223008 -333.91602)
		(width 0.14224)
		(layer "In4.Cu")
		(net "P5E_CPU0_P3_RX_DN<4>")
	)
	(segment
		(start 375.753376 -388.756144)
		(end 375.591832 -388.648194)
		(width 0.14224)
		(layer "In4.Cu")
		(net "P5E_CPU0_P3_RX_DN<4>")
	)
	(segment
		(start 378.340874 -318.19088)
		(end 376.408442 -314.575698)
		(width 0.14224)
		(layer "In4.Cu")
		(net "P5E_CPU0_P3_RX_DN<4>")
	)
	(segment
		(start 383.223008 -333.916274)
		(end 382.60147 -330.456032)
		(width 0.14224)
		(layer "In4.Cu")
		(net "P5E_CPU0_P3_RX_DN<4>")
	)
	(segment
		(start 375.396506 -386.962142)
		(end 375.309892 -386.525008)
		(width 0.14224)
		(layer "In4.Cu")
		(net "P5E_CPU0_P3_RX_DN<4>")
	)
	(segment
		(start 383.8448 -350.424496)
		(end 383.8448 -337.37677)
		(width 0.14224)
		(layer "In4.Cu")
		(net "P5E_CPU0_P3_RX_DN<4>")
	)
	(segment
		(start 375.551192 -368.43716)
		(end 383.097786 -355.846888)
		(width 0.14224)
		(layer "In4.Cu")
		(net "P5E_CPU0_P3_RX_DN<4>")
	)
	(segment
		(start 365.051848 -296.362628)
		(end 365.051848 -296.33418)
		(width 0.1143)
		(layer "In4.Cu")
		(net "P5E_CPU0_P3_RX_DN<4>")
	)
	(segment
		(start 374.277382 -383.605278)
		(end 372.815358 -381.416306)
		(width 0.14224)
		(layer "In4.Cu")
		(net "P5E_CPU0_P3_RX_DN<4>")
	)
	(segment
		(start 375.836434 -389.174482)
		(end 375.753376 -388.756144)
		(width 0.14224)
		(layer "In4.Cu")
		(net "P5E_CPU0_P3_RX_DN<4>")
	)
	(segment
		(start 365.371888 -293.203376)
		(end 365.370872 -293.202868)
		(width 0.1143)
		(layer "In4.Cu")
		(net "P5E_CPU0_P3_RX_DN<4>")
	)
	(segment
		(start 365.334296 -294.801544)
		(end 365.3282 -294.797226)
		(width 0.1143)
		(layer "In4.Cu")
		(net "P5E_CPU0_P3_RX_DN<4>")
	)
	(segment
		(start 375.728738 -389.335772)
		(end 375.836434 -389.174482)
		(width 0.14224)
		(layer "In4.Cu")
		(net "P5E_CPU0_P3_RX_DN<4>")
	)
	(segment
		(start 365.012732 -291.095938)
		(end 364.71479 -291.095938)
		(width 0.1143)
		(layer "In4.Cu")
		(net "P5E_CPU0_P3_RX_DN<4>")
	)
	(segment
		(start 375.849642 -393.22883)
		(end 375.8565 -392.379962)
		(width 0.14224)
		(layer "In4.Cu")
		(net "P5E_CPU0_P3_RX_DN<4>")
	)
	(segment
		(start 375.533412 -387.649974)
		(end 375.371868 -387.542024)
		(width 0.14224)
		(layer "In4.Cu")
		(net "P5E_CPU0_P3_RX_DN<4>")
	)
	(segment
		(start 375.591832 -388.648194)
		(end 375.508774 -388.229602)
		(width 0.14224)
		(layer "In4.Cu")
		(net "P5E_CPU0_P3_RX_DN<4>")
	)
	(segment
		(start 365.097568 -295.964102)
		(end 365.08944 -295.955974)
		(width 0.1143)
		(layer "In4.Cu")
		(net "P5E_CPU0_P3_RX_DN<4>")
	)
	(segment
		(start 365.372396 -291.583618)
		(end 365.333534 -291.561012)
		(width 0.1143)
		(layer "In4.Cu")
		(net "P5E_CPU0_P3_RX_DN<4>")
	)
	(segment
		(start 375.61647 -388.068312)
		(end 375.533412 -387.649974)
		(width 0.14224)
		(layer "In4.Cu")
		(net "P5E_CPU0_P3_RX_DN<4>")
	)
	(segment
		(start 376.044968 -393.786868)
		(end 376.166634 -393.716764)
		(width 0.14224)
		(layer "In4.Cu")
		(net "P5E_CPU0_P3_RX_DN<4>")
	)
	(segment
		(start 365.36503 -293.199312)
		(end 365.363506 -293.198296)
		(width 0.1143)
		(layer "In4.Cu")
		(net "P5E_CPU0_P3_RX_DN<4>")
	)
	(segment
		(start 375.81205 -389.754364)
		(end 375.728738 -389.335772)
		(width 0.14224)
		(layer "In4.Cu")
		(net "P5E_CPU0_P3_RX_DN<4>")
	)
	(segment
		(start 376.158506 -392.07821)
		(end 376.158506 -391.233152)
		(width 0.14224)
		(layer "In4.Cu")
		(net "P5E_CPU0_P3_RX_DN<4>")
	)
	(segment
		(start 376.166634 -393.716764)
		(end 376.166634 -393.545822)
		(width 0.14224)
		(layer "In4.Cu")
		(net "P5E_CPU0_P3_RX_DN<4>")
	)
	(segment
		(start 365.402368 -294.841168)
		(end 365.334296 -294.801544)
		(width 0.1143)
		(layer "In4.Cu")
		(net "P5E_CPU0_P3_RX_DN<4>")
	)
	(segment
		(start 365.095536 -291.178742)
		(end 365.012732 -291.095938)
		(width 0.1143)
		(layer "In4.Cu")
		(net "P5E_CPU0_P3_RX_DN<4>")
	)
	(segment
		(start 371.664484 -375.70918)
		(end 371.664738 -375.70918)
		(width 0.14224)
		(layer "In4.Cu")
		(net "P5E_CPU0_P3_RX_DN<4>")
	)
	(segment
		(start 365.332772 -295.491408)
		(end 365.402368 -295.450768)
		(width 0.1143)
		(layer "In4.Cu")
		(net "P5E_CPU0_P3_RX_DN<4>")
	)
	(segment
		(start 375.8565 -392.379962)
		(end 376.158506 -392.07821)
		(width 0.14224)
		(layer "In4.Cu")
		(net "P5E_CPU0_P3_RX_DN<4>")
	)
	(segment
		(start 365.363506 -293.198296)
		(end 365.334042 -293.181532)
		(width 0.1143)
		(layer "In4.Cu")
		(net "P5E_CPU0_P3_RX_DN<4>")
	)
	(segment
		(start 375.371868 -387.542024)
		(end 375.28881 -387.123178)
		(width 0.14224)
		(layer "In4.Cu")
		(net "P5E_CPU0_P3_RX_DN<4>")
	)
	(segment
		(start 365.38408 -293.210234)
		(end 365.37265 -293.20363)
		(width 0.1143)
		(layer "In4.Cu")
		(net "P5E_CPU0_P3_RX_DN<4>")
	)
	(segment
		(start 365.097568 -296.28846)
		(end 365.097568 -295.964102)
		(width 0.1143)
		(layer "In4.Cu")
		(net "P5E_CPU0_P3_RX_DN<4>")
	)
	(segment
		(start 365.365538 -293.852346)
		(end 365.383318 -293.841932)
		(width 0.1143)
		(layer "In4.Cu")
		(net "P5E_CPU0_P3_RX_DN<4>")
	)
	(segment
		(start 365.37265 -293.20363)
		(end 365.371888 -293.203376)
		(width 0.1143)
		(layer "In4.Cu")
		(net "P5E_CPU0_P3_RX_DN<4>")
	)
	(segment
		(start 372.206266 -381.05969)
		(end 371.973856 -380.82728)
		(width 0.14224)
		(layer "In4.Cu")
		(net "P5E_CPU0_P3_RX_DN<4>")
	)
	(segment
		(start 372.718838 -381.337312)
		(end 372.462044 -381.230886)
		(width 0.14224)
		(layer "In4.Cu")
		(net "P5E_CPU0_P3_RX_DN<4>")
	)
	(segment
		(start 365.051848 -298.595034)
		(end 365.051848 -296.362628)
		(width 0.14224)
		(layer "In4.Cu")
		(net "P5E_CPU0_P3_RX_DN<4>")
	)
	(segment
		(start 376.408442 -314.575698)
		(end 367.755678 -304.031396)
		(width 0.14224)
		(layer "In4.Cu")
		(net "P5E_CPU0_P3_RX_DN<4>")
	)
	(segment
		(start 365.37011 -293.20236)
		(end 365.36503 -293.199312)
		(width 0.1143)
		(layer "In4.Cu")
		(net "P5E_CPU0_P3_RX_DN<4>")
	)
	(segment
		(start 383.223008 -333.91602)
		(end 383.223008 -333.916274)
		(width 0.14224)
		(layer "In4.Cu")
		(net "P5E_CPU0_P3_RX_DN<4>")
	)
	(segment
		(start 383.114804 -355.798628)
		(end 383.8448 -350.424496)
		(width 0.14224)
		(layer "In4.Cu")
		(net "P5E_CPU0_P3_RX_DN<4>")
	)
	(segment
		(start 375.508774 -388.229602)
		(end 375.61647 -388.068312)
		(width 0.14224)
		(layer "In4.Cu")
		(net "P5E_CPU0_P3_RX_DN<4>")
	)
	(segment
		(start 376.04446 -393.787376)
		(end 376.044968 -393.786868)
		(width 0.14224)
		(layer "In4.Cu")
		(net "P5E_CPU0_P3_RX_DN<4>")
	)
	(segment
		(start 375.691146 -393.69238)
		(end 376.04446 -393.787376)
		(width 0.14224)
		(layer "In4.Cu")
		(net "P5E_CPU0_P3_RX_DN<4>")
	)
	(segment
		(start 376.166634 -393.545822)
		(end 375.849642 -393.22883)
		(width 0.14224)
		(layer "In4.Cu")
		(net "P5E_CPU0_P3_RX_DN<4>")
	)
	(segment
		(start 375.28881 -387.123178)
		(end 375.396506 -386.962142)
		(width 0.14224)
		(layer "In4.Cu")
		(net "P5E_CPU0_P3_RX_DN<4>")
	)
	(segment
		(start 365.334296 -292.250876)
		(end 365.371126 -292.22954)
		(width 0.1143)
		(layer "In4.Cu")
		(net "P5E_CPU0_P3_RX_DN<4>")
	)
	(segment
		(start 375.97334 -389.862314)
		(end 375.81205 -389.754364)
		(width 0.14224)
		(layer "In4.Cu")
		(net "P5E_CPU0_P3_RX_DN<4>")
	)
	(segment
		(start 376.072654 -390.361678)
		(end 375.97334 -389.862314)
		(width 0.14224)
		(layer "In4.Cu")
		(net "P5E_CPU0_P3_RX_DN<4>")
	)
	(segment
		(start 371.664738 -375.70918)
		(end 375.551192 -368.43716)
		(width 0.14224)
		(layer "In4.Cu")
		(net "P5E_CPU0_P3_RX_DN<4>")
	)
	(segment
		(start 371.40134 -379.445266)
		(end 371.40134 -376.761248)
		(width 0.14224)
		(layer "In4.Cu")
		(net "P5E_CPU0_P3_RX_DN<4>")
	)
	(segment
		(start 367.755678 -304.031396)
		(end 366.47628 -302.115474)
		(width 0.14224)
		(layer "In4.Cu")
		(net "P5E_CPU0_P3_RX_DN<4>")
	)
	(segment
		(start 365.370872 -293.202868)
		(end 365.37011 -293.20236)
		(width 0.1143)
		(layer "In4.Cu")
		(net "P5E_CPU0_P3_RX_DN<4>")
	)
	(arc
		(start 365.371126 -292.22954)
		(mid 365.55793 -291.906938)
		(end 365.372396 -291.583618)
		(width 0.1143)
		(layer "In4.Cu")
		(net "P5E_CPU0_P3_RX_DN<4>")
	)
	(arc
		(start 365.402368 -295.450768)
		(mid 365.559345 -295.145968)
		(end 365.402368 -294.841168)
		(width 0.1143)
		(layer "In4.Cu")
		(net "P5E_CPU0_P3_RX_DN<4>")
	)
	(arc
		(start 365.334042 -293.181532)
		(mid 365.08987 -292.716099)
		(end 365.334296 -292.250876)
		(width 0.1143)
		(layer "In4.Cu")
		(net "P5E_CPU0_P3_RX_DN<4>")
	)
	(arc
		(start 376.158506 -391.233152)
		(mid 376.136996 -390.795305)
		(end 376.072654 -390.361678)
		(width 0.14224)
		(layer "In4.Cu")
		(net "P5E_CPU0_P3_RX_DN<4>")
	)
	(arc
		(start 383.097786 -355.846888)
		(mid 383.108743 -355.823622)
		(end 383.114804 -355.798628)
		(width 0.14224)
		(layer "In4.Cu")
		(net "P5E_CPU0_P3_RX_DN<4>")
	)
	(arc
		(start 365.333534 -291.561012)
		(mid 365.174978 -291.394564)
		(end 365.09579 -291.178742)
		(width 0.1143)
		(layer "In4.Cu")
		(net "P5E_CPU0_P3_RX_DN<4>")
	)
	(arc
		(start 371.40134 -376.761248)
		(mid 371.468131 -376.219013)
		(end 371.664484 -375.70918)
		(width 0.14224)
		(layer "In4.Cu")
		(net "P5E_CPU0_P3_RX_DN<4>")
	)
	(arc
		(start 374.34139 -383.714498)
		(mid 374.311049 -383.658913)
		(end 374.277382 -383.605278)
		(width 0.14224)
		(layer "In4.Cu")
		(net "P5E_CPU0_P3_RX_DN<4>")
	)
	(arc
		(start 375.309892 -386.525008)
		(mid 374.921112 -385.086853)
		(end 374.34139 -383.714498)
		(width 0.14224)
		(layer "In4.Cu")
		(net "P5E_CPU0_P3_RX_DN<4>")
	)
	(arc
		(start 365.3282 -294.797226)
		(mid 365.08745 -294.314567)
		(end 365.365538 -293.852346)
		(width 0.1143)
		(layer "In4.Cu")
		(net "P5E_CPU0_P3_RX_DN<4>")
	)
	(arc
		(start 365.383318 -293.841932)
		(mid 365.558268 -293.526346)
		(end 365.38408 -293.210234)
		(width 0.1143)
		(layer "In4.Cu")
		(net "P5E_CPU0_P3_RX_DN<4>")
	)
	(arc
		(start 365.269272 -295.542716)
		(mid 365.300091 -295.515909)
		(end 365.332772 -295.491408)
		(width 0.1143)
		(layer "In4.Cu")
		(net "P5E_CPU0_P3_RX_DN<4>")
	)
	(arc
		(start 371.973856 -380.82728)
		(mid 371.550128 -380.193221)
		(end 371.40134 -379.445266)
		(width 0.14224)
		(layer "In4.Cu")
		(net "P5E_CPU0_P3_RX_DN<4>")
	)
	(arc
		(start 365.082836 -298.751752)
		(mid 365.059633 -298.674918)
		(end 365.051848 -298.595034)
		(width 0.14224)
		(layer "In4.Cu")
		(net "P5E_CPU0_P3_RX_DN<4>")
	)
	(arc
		(start 372.815358 -381.416306)
		(mid 372.772962 -381.369641)
		(end 372.718838 -381.337312)
		(width 0.14224)
		(layer "In4.Cu")
		(net "P5E_CPU0_P3_RX_DN<4>")
	)
	(arc
		(start 372.462044 -381.230886)
		(mid 372.325721 -381.157887)
		(end 372.206266 -381.05969)
		(width 0.14224)
		(layer "In4.Cu")
		(net "P5E_CPU0_P3_RX_DN<4>")
	)
	(arc
		(start 365.08944 -295.955974)
		(mid 365.136374 -295.73063)
		(end 365.269272 -295.542716)
		(width 0.1143)
		(layer "In4.Cu")
		(net "P5E_CPU0_P3_RX_DN<4>")
	)
	(segment
		(start 413.95904 -377.41733)
		(end 414.22955 -377.68784)
		(width 0.12954)
		(layer "F.Cu")
		(net "P5E_CPU0_P2_TX_DP<9>")
	)
	(segment
		(start 414.22955 -377.68784)
		(end 414.22955 -378.39142)
		(width 0.12954)
		(layer "F.Cu")
		(net "P5E_CPU0_P2_TX_DP<9>")
	)
	(segment
		(start 367.067846 -271.39011)
		(end 367.534698 -271.656048)
		(width 0.12954)
		(layer "F.Cu")
		(net "P5E_CPU0_P2_TX_DP<9>")
	)
	(segment
		(start 414.22955 -378.39142)
		(end 413.93364 -378.68733)
		(width 0.12954)
		(layer "F.Cu")
		(net "P5E_CPU0_P2_TX_DP<9>")
	)
	(segment
		(start 369.100354 -276.985222)
		(end 369.13185 -277.00351)
		(width 0.1143)
		(layer "In13.Cu")
		(net "P5E_CPU0_P2_TX_DP<9>")
	)
	(segment
		(start 369.13185 -277.00351)
		(end 369.132612 -277.004018)
		(width 0.1143)
		(layer "In13.Cu")
		(net "P5E_CPU0_P2_TX_DP<9>")
	)
	(segment
		(start 414.24987 -376.47753)
		(end 414.24987 -377.1265)
		(width 0.14224)
		(layer "In13.Cu")
		(net "P5E_CPU0_P2_TX_DP<9>")
	)
	(segment
		(start 369.13185 -293.848536)
		(end 369.092734 -293.871396)
		(width 0.1143)
		(layer "In13.Cu")
		(net "P5E_CPU0_P2_TX_DP<9>")
	)
	(segment
		(start 369.132612 -274.408138)
		(end 369.13185 -274.408646)
		(width 0.1143)
		(layer "In13.Cu")
		(net "P5E_CPU0_P2_TX_DP<9>")
	)
	(segment
		(start 369.13185 -285.74873)
		(end 369.092734 -285.77159)
		(width 0.1143)
		(layer "In13.Cu")
		(net "P5E_CPU0_P2_TX_DP<9>")
	)
	(segment
		(start 369.13185 -284.128718)
		(end 369.092734 -284.151578)
		(width 0.1143)
		(layer "In13.Cu")
		(net "P5E_CPU0_P2_TX_DP<9>")
	)
	(segment
		(start 369.130834 -279.26919)
		(end 369.12931 -279.270206)
		(width 0.1143)
		(layer "In13.Cu")
		(net "P5E_CPU0_P2_TX_DP<9>")
	)
	(segment
		(start 369.74399 -296.463974)
		(end 369.74399 -296.492422)
		(width 0.1143)
		(layer "In13.Cu")
		(net "P5E_CPU0_P2_TX_DP<9>")
	)
	(segment
		(start 369.183412 -279.23617)
		(end 369.1636 -279.250394)
		(width 0.1143)
		(layer "In13.Cu")
		(net "P5E_CPU0_P2_TX_DP<9>")
	)
	(segment
		(start 369.13185 -293.203376)
		(end 369.16233 -293.221156)
		(width 0.1143)
		(layer "In13.Cu")
		(net "P5E_CPU0_P2_TX_DP<9>")
	)
	(segment
		(start 368.159538 -272.124678)
		(end 368.1603 -272.125186)
		(width 0.1143)
		(layer "In13.Cu")
		(net "P5E_CPU0_P2_TX_DP<9>")
	)
	(segment
		(start 369.13185 -286.723582)
		(end 369.164362 -286.742378)
		(width 0.1143)
		(layer "In13.Cu")
		(net "P5E_CPU0_P2_TX_DP<9>")
	)
	(segment
		(start 369.099592 -275.364702)
		(end 369.100354 -275.36521)
		(width 0.1143)
		(layer "In13.Cu")
		(net "P5E_CPU0_P2_TX_DP<9>")
	)
	(segment
		(start 369.132612 -280.244042)
		(end 369.1636 -280.261822)
		(width 0.1143)
		(layer "In13.Cu")
		(net "P5E_CPU0_P2_TX_DP<9>")
	)
	(segment
		(start 369.099592 -280.224738)
		(end 369.100354 -280.225246)
		(width 0.1143)
		(layer "In13.Cu")
		(net "P5E_CPU0_P2_TX_DP<9>")
	)
	(segment
		(start 369.092734 -280.220674)
		(end 369.099592 -280.224738)
		(width 0.1143)
		(layer "In13.Cu")
		(net "P5E_CPU0_P2_TX_DP<9>")
	)
	(segment
		(start 369.132612 -275.384006)
		(end 369.1636 -275.401786)
		(width 0.1143)
		(layer "In13.Cu")
		(net "P5E_CPU0_P2_TX_DP<9>")
	)
	(segment
		(start 369.130834 -274.409154)
		(end 369.12931 -274.41017)
		(width 0.1143)
		(layer "In13.Cu")
		(net "P5E_CPU0_P2_TX_DP<9>")
	)
	(segment
		(start 369.13185 -292.228524)
		(end 369.092734 -292.251384)
		(width 0.1143)
		(layer "In13.Cu")
		(net "P5E_CPU0_P2_TX_DP<9>")
	)
	(segment
		(start 369.092734 -273.740626)
		(end 369.099592 -273.74469)
		(width 0.1143)
		(layer "In13.Cu")
		(net "P5E_CPU0_P2_TX_DP<9>")
	)
	(segment
		(start 369.092734 -293.180516)
		(end 369.13185 -293.203376)
		(width 0.1143)
		(layer "In13.Cu")
		(net "P5E_CPU0_P2_TX_DP<9>")
	)
	(segment
		(start 369.1636 -276.01037)
		(end 369.132612 -276.02815)
		(width 0.1143)
		(layer "In13.Cu")
		(net "P5E_CPU0_P2_TX_DP<9>")
	)
	(segment
		(start 369.092734 -278.600662)
		(end 369.099592 -278.604726)
		(width 0.1143)
		(layer "In13.Cu")
		(net "P5E_CPU0_P2_TX_DP<9>")
	)
	(segment
		(start 369.099592 -276.984714)
		(end 369.100354 -276.985222)
		(width 0.1143)
		(layer "In13.Cu")
		(net "P5E_CPU0_P2_TX_DP<9>")
	)
	(segment
		(start 369.13185 -282.508706)
		(end 369.092734 -282.531566)
		(width 0.1143)
		(layer "In13.Cu")
		(net "P5E_CPU0_P2_TX_DP<9>")
	)
	(segment
		(start 369.13185 -279.268682)
		(end 369.130834 -279.26919)
		(width 0.1143)
		(layer "In13.Cu")
		(net "P5E_CPU0_P2_TX_DP<9>")
	)
	(segment
		(start 369.13185 -285.10357)
		(end 369.16233 -285.12135)
		(width 0.1143)
		(layer "In13.Cu")
		(net "P5E_CPU0_P2_TX_DP<9>")
	)
	(segment
		(start 404.418546 -371.955314)
		(end 413.798258 -375.840498)
		(width 0.14224)
		(layer "In13.Cu")
		(net "P5E_CPU0_P2_TX_DP<9>")
	)
	(segment
		(start 369.1636 -280.870406)
		(end 369.095528 -280.909522)
		(width 0.1143)
		(layer "In13.Cu")
		(net "P5E_CPU0_P2_TX_DP<9>")
	)
	(segment
		(start 369.130834 -276.029166)
		(end 369.12931 -276.030182)
		(width 0.1143)
		(layer "In13.Cu")
		(net "P5E_CPU0_P2_TX_DP<9>")
	)
	(segment
		(start 369.099592 -278.604726)
		(end 369.100354 -278.605234)
		(width 0.1143)
		(layer "In13.Cu")
		(net "P5E_CPU0_P2_TX_DP<9>")
	)
	(segment
		(start 369.13185 -289.963352)
		(end 369.16233 -289.981132)
		(width 0.1143)
		(layer "In13.Cu")
		(net "P5E_CPU0_P2_TX_DP<9>")
	)
	(segment
		(start 369.319302 -295.145968)
		(end 369.319556 -295.145968)
		(width 0.1143)
		(layer "In13.Cu")
		(net "P5E_CPU0_P2_TX_DP<9>")
	)
	(segment
		(start 369.16233 -287.350708)
		(end 369.095274 -287.389824)
		(width 0.1143)
		(layer "In13.Cu")
		(net "P5E_CPU0_P2_TX_DP<9>")
	)
	(segment
		(start 367.534698 -271.656048)
		(end 367.83264 -271.656048)
		(width 0.1143)
		(layer "In13.Cu")
		(net "P5E_CPU0_P2_TX_DP<9>")
	)
	(segment
		(start 369.16233 -292.210744)
		(end 369.13185 -292.228524)
		(width 0.1143)
		(layer "In13.Cu")
		(net "P5E_CPU0_P2_TX_DP<9>")
	)
	(segment
		(start 369.183412 -280.856182)
		(end 369.1636 -280.870406)
		(width 0.1143)
		(layer "In13.Cu")
		(net "P5E_CPU0_P2_TX_DP<9>")
	)
	(segment
		(start 369.13185 -274.408646)
		(end 369.130834 -274.409154)
		(width 0.1143)
		(layer "In13.Cu")
		(net "P5E_CPU0_P2_TX_DP<9>")
	)
	(segment
		(start 368.1984 -272.147284)
		(end 368.199416 -272.147792)
		(width 0.1143)
		(layer "In13.Cu")
		(net "P5E_CPU0_P2_TX_DP<9>")
	)
	(segment
		(start 368.15268 -272.120614)
		(end 368.159538 -272.124678)
		(width 0.1143)
		(layer "In13.Cu")
		(net "P5E_CPU0_P2_TX_DP<9>")
	)
	(segment
		(start 369.16233 -293.830756)
		(end 369.13185 -293.848536)
		(width 0.1143)
		(layer "In13.Cu")
		(net "P5E_CPU0_P2_TX_DP<9>")
	)
	(segment
		(start 369.095528 -280.909522)
		(end 369.092734 -280.911554)
		(width 0.1143)
		(layer "In13.Cu")
		(net "P5E_CPU0_P2_TX_DP<9>")
	)
	(segment
		(start 369.099592 -273.74469)
		(end 369.100354 -273.745198)
		(width 0.1143)
		(layer "In13.Cu")
		(net "P5E_CPU0_P2_TX_DP<9>")
	)
	(segment
		(start 369.16233 -285.73095)
		(end 369.13185 -285.74873)
		(width 0.1143)
		(layer "In13.Cu")
		(net "P5E_CPU0_P2_TX_DP<9>")
	)
	(segment
		(start 369.12931 -277.650194)
		(end 369.092734 -277.67153)
		(width 0.1143)
		(layer "In13.Cu")
		(net "P5E_CPU0_P2_TX_DP<9>")
	)
	(segment
		(start 369.092734 -283.460698)
		(end 369.13185 -283.483558)
		(width 0.1143)
		(layer "In13.Cu")
		(net "P5E_CPU0_P2_TX_DP<9>")
	)
	(segment
		(start 367.83264 -271.656048)
		(end 367.915444 -271.738852)
		(width 0.1143)
		(layer "In13.Cu")
		(net "P5E_CPU0_P2_TX_DP<9>")
	)
	(segment
		(start 369.092734 -288.320734)
		(end 369.13185 -288.343594)
		(width 0.1143)
		(layer "In13.Cu")
		(net "P5E_CPU0_P2_TX_DP<9>")
	)
	(segment
		(start 369.16233 -284.110938)
		(end 369.13185 -284.128718)
		(width 0.1143)
		(layer "In13.Cu")
		(net "P5E_CPU0_P2_TX_DP<9>")
	)
	(segment
		(start 369.74399 -296.492422)
		(end 369.74399 -298.285408)
		(width 0.14224)
		(layer "In13.Cu")
		(net "P5E_CPU0_P2_TX_DP<9>")
	)
	(segment
		(start 396.423388 -362.740702)
		(end 401.005802 -369.598702)
		(width 0.14224)
		(layer "In13.Cu")
		(net "P5E_CPU0_P2_TX_DP<9>")
	)
	(segment
		(start 369.132612 -277.004018)
		(end 369.1636 -277.021798)
		(width 0.1143)
		(layer "In13.Cu")
		(net "P5E_CPU0_P2_TX_DP<9>")
	)
	(segment
		(start 369.100354 -275.36521)
		(end 369.13185 -275.383498)
		(width 0.1143)
		(layer "In13.Cu")
		(net "P5E_CPU0_P2_TX_DP<9>")
	)
	(segment
		(start 369.13185 -283.483558)
		(end 369.16233 -283.501338)
		(width 0.1143)
		(layer "In13.Cu")
		(net "P5E_CPU0_P2_TX_DP<9>")
	)
	(segment
		(start 368.199416 -272.147792)
		(end 368.223546 -272.161762)
		(width 0.1143)
		(layer "In13.Cu")
		(net "P5E_CPU0_P2_TX_DP<9>")
	)
	(segment
		(start 369.13185 -277.64867)
		(end 369.130834 -277.649178)
		(width 0.1143)
		(layer "In13.Cu")
		(net "P5E_CPU0_P2_TX_DP<9>")
	)
	(segment
		(start 369.1636 -274.390358)
		(end 369.132612 -274.408138)
		(width 0.1143)
		(layer "In13.Cu")
		(net "P5E_CPU0_P2_TX_DP<9>")
	)
	(segment
		(start 369.100354 -280.225246)
		(end 369.13185 -280.243534)
		(width 0.1143)
		(layer "In13.Cu")
		(net "P5E_CPU0_P2_TX_DP<9>")
	)
	(segment
		(start 401.233894 -369.826794)
		(end 404.418546 -371.955314)
		(width 0.14224)
		(layer "In13.Cu")
		(net "P5E_CPU0_P2_TX_DP<9>")
	)
	(segment
		(start 368.196114 -272.146014)
		(end 368.197638 -272.146776)
		(width 0.1143)
		(layer "In13.Cu")
		(net "P5E_CPU0_P2_TX_DP<9>")
	)
	(segment
		(start 369.092734 -285.08071)
		(end 369.13185 -285.10357)
		(width 0.1143)
		(layer "In13.Cu")
		(net "P5E_CPU0_P2_TX_DP<9>")
	)
	(segment
		(start 368.622834 -272.93062)
		(end 368.66195 -272.95348)
		(width 0.1143)
		(layer "In13.Cu")
		(net "P5E_CPU0_P2_TX_DP<9>")
	)
	(segment
		(start 413.855408 -375.887234)
		(end 414.24987 -376.47753)
		(width 0.14224)
		(layer "In13.Cu")
		(net "P5E_CPU0_P2_TX_DP<9>")
	)
	(segment
		(start 369.13185 -288.9885)
		(end 369.092734 -289.01136)
		(width 0.1143)
		(layer "In13.Cu")
		(net "P5E_CPU0_P2_TX_DP<9>")
	)
	(segment
		(start 369.789964 -298.516548)
		(end 396.337536 -362.580682)
		(width 0.14224)
		(layer "In13.Cu")
		(net "P5E_CPU0_P2_TX_DP<9>")
	)
	(segment
		(start 369.16233 -288.97072)
		(end 369.13185 -288.9885)
		(width 0.1143)
		(layer "In13.Cu")
		(net "P5E_CPU0_P2_TX_DP<9>")
	)
	(segment
		(start 369.092734 -291.560504)
		(end 369.13185 -291.583364)
		(width 0.1143)
		(layer "In13.Cu")
		(net "P5E_CPU0_P2_TX_DP<9>")
	)
	(segment
		(start 369.12931 -274.41017)
		(end 369.092734 -274.431506)
		(width 0.1143)
		(layer "In13.Cu")
		(net "P5E_CPU0_P2_TX_DP<9>")
	)
	(segment
		(start 368.195352 -272.145506)
		(end 368.196114 -272.146014)
		(width 0.1143)
		(layer "In13.Cu")
		(net "P5E_CPU0_P2_TX_DP<9>")
	)
	(segment
		(start 369.1636 -280.261822)
		(end 369.183412 -280.276046)
		(width 0.1143)
		(layer "In13.Cu")
		(net "P5E_CPU0_P2_TX_DP<9>")
	)
	(segment
		(start 369.092734 -294.800528)
		(end 369.13185 -294.823388)
		(width 0.1143)
		(layer "In13.Cu")
		(net "P5E_CPU0_P2_TX_DP<9>")
	)
	(segment
		(start 369.12931 -279.270206)
		(end 369.092734 -279.291542)
		(width 0.1143)
		(layer "In13.Cu")
		(net "P5E_CPU0_P2_TX_DP<9>")
	)
	(segment
		(start 369.092734 -276.98065)
		(end 369.099592 -276.984714)
		(width 0.1143)
		(layer "In13.Cu")
		(net "P5E_CPU0_P2_TX_DP<9>")
	)
	(segment
		(start 369.092734 -289.940492)
		(end 369.13185 -289.963352)
		(width 0.1143)
		(layer "In13.Cu")
		(net "P5E_CPU0_P2_TX_DP<9>")
	)
	(segment
		(start 369.13185 -276.028658)
		(end 369.130834 -276.029166)
		(width 0.1143)
		(layer "In13.Cu")
		(net "P5E_CPU0_P2_TX_DP<9>")
	)
	(segment
		(start 369.132612 -278.62403)
		(end 369.1636 -278.64181)
		(width 0.1143)
		(layer "In13.Cu")
		(net "P5E_CPU0_P2_TX_DP<9>")
	)
	(segment
		(start 369.13185 -291.583364)
		(end 369.16233 -291.601144)
		(width 0.1143)
		(layer "In13.Cu")
		(net "P5E_CPU0_P2_TX_DP<9>")
	)
	(segment
		(start 368.1603 -272.125186)
		(end 368.191796 -272.143474)
		(width 0.1143)
		(layer "In13.Cu")
		(net "P5E_CPU0_P2_TX_DP<9>")
	)
	(segment
		(start 369.16233 -290.590732)
		(end 369.13185 -290.608512)
		(width 0.1143)
		(layer "In13.Cu")
		(net "P5E_CPU0_P2_TX_DP<9>")
	)
	(segment
		(start 369.13185 -275.383498)
		(end 369.132612 -275.384006)
		(width 0.1143)
		(layer "In13.Cu")
		(net "P5E_CPU0_P2_TX_DP<9>")
	)
	(segment
		(start 368.191796 -272.143474)
		(end 368.192558 -272.143982)
		(width 0.1143)
		(layer "In13.Cu")
		(net "P5E_CPU0_P2_TX_DP<9>")
	)
	(segment
		(start 369.100354 -278.605234)
		(end 369.13185 -278.623522)
		(width 0.1143)
		(layer "In13.Cu")
		(net "P5E_CPU0_P2_TX_DP<9>")
	)
	(segment
		(start 369.13185 -294.823388)
		(end 369.16233 -294.841168)
		(width 0.1143)
		(layer "In13.Cu")
		(net "P5E_CPU0_P2_TX_DP<9>")
	)
	(segment
		(start 369.13185 -278.623522)
		(end 369.132612 -278.62403)
		(width 0.1143)
		(layer "In13.Cu")
		(net "P5E_CPU0_P2_TX_DP<9>")
	)
	(segment
		(start 369.092734 -275.360638)
		(end 369.099592 -275.364702)
		(width 0.1143)
		(layer "In13.Cu")
		(net "P5E_CPU0_P2_TX_DP<9>")
	)
	(segment
		(start 414.24987 -377.1265)
		(end 413.95904 -377.41733)
		(width 0.14224)
		(layer "In13.Cu")
		(net "P5E_CPU0_P2_TX_DP<9>")
	)
	(segment
		(start 368.192558 -272.143982)
		(end 368.195352 -272.145506)
		(width 0.1143)
		(layer "In13.Cu")
		(net "P5E_CPU0_P2_TX_DP<9>")
	)
	(segment
		(start 369.16233 -282.490926)
		(end 369.13185 -282.508706)
		(width 0.1143)
		(layer "In13.Cu")
		(net "P5E_CPU0_P2_TX_DP<9>")
	)
	(segment
		(start 369.78971 -295.955974)
		(end 369.78971 -296.418254)
		(width 0.1143)
		(layer "In13.Cu")
		(net "P5E_CPU0_P2_TX_DP<9>")
	)
	(segment
		(start 369.092734 -286.700722)
		(end 369.13185 -286.723582)
		(width 0.1143)
		(layer "In13.Cu")
		(net "P5E_CPU0_P2_TX_DP<9>")
	)
	(segment
		(start 369.565428 -295.612312)
		(end 369.6335 -295.651682)
		(width 0.1143)
		(layer "In13.Cu")
		(net "P5E_CPU0_P2_TX_DP<9>")
	)
	(segment
		(start 369.132612 -273.763994)
		(end 369.1636 -273.781774)
		(width 0.1143)
		(layer "In13.Cu")
		(net "P5E_CPU0_P2_TX_DP<9>")
	)
	(segment
		(start 369.13185 -288.343594)
		(end 369.164362 -288.36239)
		(width 0.1143)
		(layer "In13.Cu")
		(net "P5E_CPU0_P2_TX_DP<9>")
	)
	(segment
		(start 369.130834 -277.649178)
		(end 369.12931 -277.650194)
		(width 0.1143)
		(layer "In13.Cu")
		(net "P5E_CPU0_P2_TX_DP<9>")
	)
	(segment
		(start 369.1636 -279.250394)
		(end 369.132612 -279.268174)
		(width 0.1143)
		(layer "In13.Cu")
		(net "P5E_CPU0_P2_TX_DP<9>")
	)
	(segment
		(start 369.100354 -273.745198)
		(end 369.13185 -273.763486)
		(width 0.1143)
		(layer "In13.Cu")
		(net "P5E_CPU0_P2_TX_DP<9>")
	)
	(segment
		(start 369.132612 -279.268174)
		(end 369.13185 -279.268682)
		(width 0.1143)
		(layer "In13.Cu")
		(net "P5E_CPU0_P2_TX_DP<9>")
	)
	(segment
		(start 369.132612 -277.648162)
		(end 369.13185 -277.64867)
		(width 0.1143)
		(layer "In13.Cu")
		(net "P5E_CPU0_P2_TX_DP<9>")
	)
	(segment
		(start 369.132612 -276.02815)
		(end 369.13185 -276.028658)
		(width 0.1143)
		(layer "In13.Cu")
		(net "P5E_CPU0_P2_TX_DP<9>")
	)
	(segment
		(start 369.13185 -290.608512)
		(end 369.092734 -290.631372)
		(width 0.1143)
		(layer "In13.Cu")
		(net "P5E_CPU0_P2_TX_DP<9>")
	)
	(segment
		(start 369.78971 -296.418254)
		(end 369.74399 -296.463974)
		(width 0.1143)
		(layer "In13.Cu")
		(net "P5E_CPU0_P2_TX_DP<9>")
	)
	(segment
		(start 369.1636 -277.630382)
		(end 369.132612 -277.648162)
		(width 0.1143)
		(layer "In13.Cu")
		(net "P5E_CPU0_P2_TX_DP<9>")
	)
	(segment
		(start 369.13185 -273.763486)
		(end 369.132612 -273.763994)
		(width 0.1143)
		(layer "In13.Cu")
		(net "P5E_CPU0_P2_TX_DP<9>")
	)
	(segment
		(start 369.1636 -278.64181)
		(end 369.183412 -278.656034)
		(width 0.1143)
		(layer "In13.Cu")
		(net "P5E_CPU0_P2_TX_DP<9>")
	)
	(segment
		(start 368.66195 -272.95348)
		(end 368.69243 -272.97126)
		(width 0.1143)
		(layer "In13.Cu")
		(net "P5E_CPU0_P2_TX_DP<9>")
	)
	(segment
		(start 369.13185 -280.243534)
		(end 369.132612 -280.244042)
		(width 0.1143)
		(layer "In13.Cu")
		(net "P5E_CPU0_P2_TX_DP<9>")
	)
	(segment
		(start 368.197638 -272.146776)
		(end 368.1984 -272.147284)
		(width 0.1143)
		(layer "In13.Cu")
		(net "P5E_CPU0_P2_TX_DP<9>")
	)
	(segment
		(start 369.092734 -281.840686)
		(end 369.13185 -281.863546)
		(width 0.1143)
		(layer "In13.Cu")
		(net "P5E_CPU0_P2_TX_DP<9>")
	)
	(segment
		(start 369.13185 -281.863546)
		(end 369.16233 -281.881326)
		(width 0.1143)
		(layer "In13.Cu")
		(net "P5E_CPU0_P2_TX_DP<9>")
	)
	(segment
		(start 369.12931 -276.030182)
		(end 369.092734 -276.051518)
		(width 0.1143)
		(layer "In13.Cu")
		(net "P5E_CPU0_P2_TX_DP<9>")
	)
	(arc
		(start 369.6335 -295.651682)
		(mid 369.669363 -295.681074)
		(end 369.701318 -295.714674)
		(width 0.1143)
		(layer "In13.Cu")
		(net "P5E_CPU0_P2_TX_DP<9>")
	)
	(arc
		(start 369.1636 -275.401786)
		(mid 369.313985 -275.706078)
		(end 369.1636 -276.01037)
		(width 0.1143)
		(layer "In13.Cu")
		(net "P5E_CPU0_P2_TX_DP<9>")
	)
	(arc
		(start 368.849402 -273.27606)
		(mid 368.913917 -273.538279)
		(end 369.092734 -273.740626)
		(width 0.1143)
		(layer "In13.Cu")
		(net "P5E_CPU0_P2_TX_DP<9>")
	)
	(arc
		(start 369.16233 -291.601144)
		(mid 369.319307 -291.905944)
		(end 369.16233 -292.210744)
		(width 0.1143)
		(layer "In13.Cu")
		(net "P5E_CPU0_P2_TX_DP<9>")
	)
	(arc
		(start 369.16233 -285.12135)
		(mid 369.319307 -285.42615)
		(end 369.16233 -285.73095)
		(width 0.1143)
		(layer "In13.Cu")
		(net "P5E_CPU0_P2_TX_DP<9>")
	)
	(arc
		(start 368.849402 -287.856168)
		(mid 368.913917 -288.118387)
		(end 369.092734 -288.320734)
		(width 0.1143)
		(layer "In13.Cu")
		(net "P5E_CPU0_P2_TX_DP<9>")
	)
	(arc
		(start 369.701318 -295.714674)
		(mid 369.764299 -295.828442)
		(end 369.78971 -295.955974)
		(width 0.1143)
		(layer "In13.Cu")
		(net "P5E_CPU0_P2_TX_DP<9>")
	)
	(arc
		(start 369.092734 -282.531566)
		(mid 368.849407 -282.996132)
		(end 369.092734 -283.460698)
		(width 0.1143)
		(layer "In13.Cu")
		(net "P5E_CPU0_P2_TX_DP<9>")
	)
	(arc
		(start 401.005802 -369.598702)
		(mid 401.108624 -369.723972)
		(end 401.233894 -369.826794)
		(width 0.14224)
		(layer "In13.Cu")
		(net "P5E_CPU0_P2_TX_DP<9>")
	)
	(arc
		(start 396.337536 -362.580682)
		(mid 396.376538 -362.662797)
		(end 396.423388 -362.740702)
		(width 0.14224)
		(layer "In13.Cu")
		(net "P5E_CPU0_P2_TX_DP<9>")
	)
	(arc
		(start 369.74399 -298.285408)
		(mid 369.755591 -298.403244)
		(end 369.789964 -298.516548)
		(width 0.14224)
		(layer "In13.Cu")
		(net "P5E_CPU0_P2_TX_DP<9>")
	)
	(arc
		(start 369.092734 -289.01136)
		(mid 368.849407 -289.475926)
		(end 369.092734 -289.940492)
		(width 0.1143)
		(layer "In13.Cu")
		(net "P5E_CPU0_P2_TX_DP<9>")
	)
	(arc
		(start 369.092734 -290.631372)
		(mid 368.849407 -291.095938)
		(end 369.092734 -291.560504)
		(width 0.1143)
		(layer "In13.Cu")
		(net "P5E_CPU0_P2_TX_DP<9>")
	)
	(arc
		(start 369.16233 -294.841168)
		(mid 369.277757 -294.974544)
		(end 369.319302 -295.145968)
		(width 0.1143)
		(layer "In13.Cu")
		(net "P5E_CPU0_P2_TX_DP<9>")
	)
	(arc
		(start 368.69243 -272.97126)
		(mid 368.807857 -273.104636)
		(end 368.849402 -273.27606)
		(width 0.1143)
		(layer "In13.Cu")
		(net "P5E_CPU0_P2_TX_DP<9>")
	)
	(arc
		(start 369.319302 -288.66592)
		(mid 369.277753 -288.837342)
		(end 369.16233 -288.97072)
		(width 0.1143)
		(layer "In13.Cu")
		(net "P5E_CPU0_P2_TX_DP<9>")
	)
	(arc
		(start 369.092734 -274.431506)
		(mid 368.849407 -274.896072)
		(end 369.092734 -275.360638)
		(width 0.1143)
		(layer "In13.Cu")
		(net "P5E_CPU0_P2_TX_DP<9>")
	)
	(arc
		(start 369.1636 -277.021798)
		(mid 369.315189 -277.32609)
		(end 369.1636 -277.630382)
		(width 0.1143)
		(layer "In13.Cu")
		(net "P5E_CPU0_P2_TX_DP<9>")
	)
	(arc
		(start 369.183412 -280.276046)
		(mid 369.332126 -280.566114)
		(end 369.183412 -280.856182)
		(width 0.1143)
		(layer "In13.Cu")
		(net "P5E_CPU0_P2_TX_DP<9>")
	)
	(arc
		(start 369.092734 -285.77159)
		(mid 368.849407 -286.236156)
		(end 369.092734 -286.700722)
		(width 0.1143)
		(layer "In13.Cu")
		(net "P5E_CPU0_P2_TX_DP<9>")
	)
	(arc
		(start 369.092734 -292.251384)
		(mid 368.849407 -292.71595)
		(end 369.092734 -293.180516)
		(width 0.1143)
		(layer "In13.Cu")
		(net "P5E_CPU0_P2_TX_DP<9>")
	)
	(arc
		(start 369.164362 -286.742378)
		(mid 369.278291 -286.875525)
		(end 369.319302 -287.045908)
		(width 0.1143)
		(layer "In13.Cu")
		(net "P5E_CPU0_P2_TX_DP<9>")
	)
	(arc
		(start 367.919254 -271.761712)
		(mid 368.000687 -271.96411)
		(end 368.15268 -272.120614)
		(width 0.1143)
		(layer "In13.Cu")
		(net "P5E_CPU0_P2_TX_DP<9>")
	)
	(arc
		(start 369.1636 -273.781774)
		(mid 369.315189 -274.086066)
		(end 369.1636 -274.390358)
		(width 0.1143)
		(layer "In13.Cu")
		(net "P5E_CPU0_P2_TX_DP<9>")
	)
	(arc
		(start 369.092734 -280.911554)
		(mid 368.849407 -281.37612)
		(end 369.092734 -281.840686)
		(width 0.1143)
		(layer "In13.Cu")
		(net "P5E_CPU0_P2_TX_DP<9>")
	)
	(arc
		(start 369.16233 -289.981132)
		(mid 369.319307 -290.285932)
		(end 369.16233 -290.590732)
		(width 0.1143)
		(layer "In13.Cu")
		(net "P5E_CPU0_P2_TX_DP<9>")
	)
	(arc
		(start 369.092734 -276.051518)
		(mid 368.849407 -276.516084)
		(end 369.092734 -276.98065)
		(width 0.1143)
		(layer "In13.Cu")
		(net "P5E_CPU0_P2_TX_DP<9>")
	)
	(arc
		(start 367.915444 -271.738852)
		(mid 367.917232 -271.750301)
		(end 367.919254 -271.761712)
		(width 0.1143)
		(layer "In13.Cu")
		(net "P5E_CPU0_P2_TX_DP<9>")
	)
	(arc
		(start 369.319556 -295.145968)
		(mid 369.384792 -295.409559)
		(end 369.565428 -295.612312)
		(width 0.1143)
		(layer "In13.Cu")
		(net "P5E_CPU0_P2_TX_DP<9>")
	)
	(arc
		(start 369.16233 -283.501338)
		(mid 369.319307 -283.806138)
		(end 369.16233 -284.110938)
		(width 0.1143)
		(layer "In13.Cu")
		(net "P5E_CPU0_P2_TX_DP<9>")
	)
	(arc
		(start 369.183412 -278.656034)
		(mid 369.332126 -278.946102)
		(end 369.183412 -279.23617)
		(width 0.1143)
		(layer "In13.Cu")
		(net "P5E_CPU0_P2_TX_DP<9>")
	)
	(arc
		(start 368.223546 -272.161762)
		(mid 368.338222 -272.295096)
		(end 368.379502 -272.466054)
		(width 0.1143)
		(layer "In13.Cu")
		(net "P5E_CPU0_P2_TX_DP<9>")
	)
	(arc
		(start 369.16233 -281.881326)
		(mid 369.319307 -282.186126)
		(end 369.16233 -282.490926)
		(width 0.1143)
		(layer "In13.Cu")
		(net "P5E_CPU0_P2_TX_DP<9>")
	)
	(arc
		(start 369.092734 -284.151578)
		(mid 368.849407 -284.616144)
		(end 369.092734 -285.08071)
		(width 0.1143)
		(layer "In13.Cu")
		(net "P5E_CPU0_P2_TX_DP<9>")
	)
	(arc
		(start 368.379502 -272.466054)
		(mid 368.444017 -272.728273)
		(end 368.622834 -272.93062)
		(width 0.1143)
		(layer "In13.Cu")
		(net "P5E_CPU0_P2_TX_DP<9>")
	)
	(arc
		(start 369.16233 -293.221156)
		(mid 369.319307 -293.525956)
		(end 369.16233 -293.830756)
		(width 0.1143)
		(layer "In13.Cu")
		(net "P5E_CPU0_P2_TX_DP<9>")
	)
	(arc
		(start 413.798258 -375.840498)
		(mid 413.830311 -375.859614)
		(end 413.855408 -375.887234)
		(width 0.14224)
		(layer "In13.Cu")
		(net "P5E_CPU0_P2_TX_DP<9>")
	)
	(arc
		(start 369.092734 -293.871396)
		(mid 368.849407 -294.335962)
		(end 369.092734 -294.800528)
		(width 0.1143)
		(layer "In13.Cu")
		(net "P5E_CPU0_P2_TX_DP<9>")
	)
	(arc
		(start 369.319302 -287.045908)
		(mid 369.277753 -287.21733)
		(end 369.16233 -287.350708)
		(width 0.1143)
		(layer "In13.Cu")
		(net "P5E_CPU0_P2_TX_DP<9>")
	)
	(arc
		(start 369.092734 -279.291542)
		(mid 368.849407 -279.756108)
		(end 369.092734 -280.220674)
		(width 0.1143)
		(layer "In13.Cu")
		(net "P5E_CPU0_P2_TX_DP<9>")
	)
	(arc
		(start 369.095274 -287.389824)
		(mid 368.914622 -287.592569)
		(end 368.849402 -287.856168)
		(width 0.1143)
		(layer "In13.Cu")
		(net "P5E_CPU0_P2_TX_DP<9>")
	)
	(arc
		(start 369.092734 -277.67153)
		(mid 368.849407 -278.136096)
		(end 369.092734 -278.600662)
		(width 0.1143)
		(layer "In13.Cu")
		(net "P5E_CPU0_P2_TX_DP<9>")
	)
	(arc
		(start 369.164362 -288.36239)
		(mid 369.278291 -288.495537)
		(end 369.319302 -288.66592)
		(width 0.1143)
		(layer "In13.Cu")
		(net "P5E_CPU0_P2_TX_DP<9>")
	)
	(segment
		(start 412.25724 -379.88113)
		(end 412.52775 -380.15164)
		(width 0.12954)
		(layer "F.Cu")
		(net "P5E_CPU0_P2_TX_DP<8>")
	)
	(segment
		(start 412.52775 -380.15164)
		(end 412.52775 -380.85522)
		(width 0.12954)
		(layer "F.Cu")
		(net "P5E_CPU0_P2_TX_DP<8>")
	)
	(segment
		(start 412.52775 -380.85522)
		(end 412.23184 -381.15113)
		(width 0.12954)
		(layer "F.Cu")
		(net "P5E_CPU0_P2_TX_DP<8>")
	)
	(segment
		(start 367.067846 -273.010122)
		(end 367.534698 -273.27606)
		(width 0.12954)
		(layer "F.Cu")
		(net "P5E_CPU0_P2_TX_DP<8>")
	)
	(segment
		(start 368.159538 -283.464762)
		(end 368.1603 -283.46527)
		(width 0.1143)
		(layer "In13.Cu")
		(net "P5E_CPU0_P2_TX_DP<8>")
	)
	(segment
		(start 368.223546 -277.630382)
		(end 368.192558 -277.648162)
		(width 0.1143)
		(layer "In13.Cu")
		(net "P5E_CPU0_P2_TX_DP<8>")
	)
	(segment
		(start 368.18824 -279.270714)
		(end 368.18697 -279.271476)
		(width 0.1143)
		(layer "In13.Cu")
		(net "P5E_CPU0_P2_TX_DP<8>")
	)
	(segment
		(start 368.15268 -275.360638)
		(end 368.159538 -275.364702)
		(width 0.1143)
		(layer "In13.Cu")
		(net "P5E_CPU0_P2_TX_DP<8>")
	)
	(segment
		(start 368.192558 -292.228016)
		(end 368.191796 -292.228524)
		(width 0.1143)
		(layer "In13.Cu")
		(net "P5E_CPU0_P2_TX_DP<8>")
	)
	(segment
		(start 368.192558 -278.62403)
		(end 368.193828 -278.624792)
		(width 0.1143)
		(layer "In13.Cu")
		(net "P5E_CPU0_P2_TX_DP<8>")
	)
	(segment
		(start 368.191796 -288.9885)
		(end 368.19078 -288.989008)
		(width 0.1143)
		(layer "In13.Cu")
		(net "P5E_CPU0_P2_TX_DP<8>")
	)
	(segment
		(start 368.19459 -289.96513)
		(end 368.195098 -289.96513)
		(width 0.1143)
		(layer "In13.Cu")
		(net "P5E_CPU0_P2_TX_DP<8>")
	)
	(segment
		(start 368.19967 -273.768058)
		(end 368.20221 -273.769328)
		(width 0.1143)
		(layer "In13.Cu")
		(net "P5E_CPU0_P2_TX_DP<8>")
	)
	(segment
		(start 368.19459 -283.485336)
		(end 368.195098 -283.485336)
		(width 0.1143)
		(layer "In13.Cu")
		(net "P5E_CPU0_P2_TX_DP<8>")
	)
	(segment
		(start 368.18824 -277.650702)
		(end 368.18697 -277.651464)
		(width 0.1143)
		(layer "In13.Cu")
		(net "P5E_CPU0_P2_TX_DP<8>")
	)
	(segment
		(start 368.194844 -293.846758)
		(end 368.192558 -293.848282)
		(width 0.1143)
		(layer "In13.Cu")
		(net "P5E_CPU0_P2_TX_DP<8>")
	)
	(segment
		(start 368.192558 -288.988246)
		(end 368.191796 -288.9885)
		(width 0.1143)
		(layer "In13.Cu")
		(net "P5E_CPU0_P2_TX_DP<8>")
	)
	(segment
		(start 368.191796 -277.64867)
		(end 368.19078 -277.649178)
		(width 0.1143)
		(layer "In13.Cu")
		(net "P5E_CPU0_P2_TX_DP<8>")
	)
	(segment
		(start 368.18824 -276.03069)
		(end 368.18697 -276.031452)
		(width 0.1143)
		(layer "In13.Cu")
		(net "P5E_CPU0_P2_TX_DP<8>")
	)
	(segment
		(start 368.15268 -276.98065)
		(end 368.159538 -276.984714)
		(width 0.1143)
		(layer "In13.Cu")
		(net "P5E_CPU0_P2_TX_DP<8>")
	)
	(segment
		(start 368.191796 -293.848536)
		(end 368.19078 -293.849044)
		(width 0.1143)
		(layer "In13.Cu")
		(net "P5E_CPU0_P2_TX_DP<8>")
	)
	(segment
		(start 368.19967 -277.008082)
		(end 368.20221 -277.009352)
		(width 0.1143)
		(layer "In13.Cu")
		(net "P5E_CPU0_P2_TX_DP<8>")
	)
	(segment
		(start 368.852704 -295.961054)
		(end 368.852704 -296.36339)
		(width 0.1143)
		(layer "In13.Cu")
		(net "P5E_CPU0_P2_TX_DP<8>")
	)
	(segment
		(start 368.19078 -293.202868)
		(end 368.191796 -293.203376)
		(width 0.1143)
		(layer "In13.Cu")
		(net "P5E_CPU0_P2_TX_DP<8>")
	)
	(segment
		(start 368.806984 -296.437558)
		(end 368.806984 -298.633642)
		(width 0.14224)
		(layer "In13.Cu")
		(net "P5E_CPU0_P2_TX_DP<8>")
	)
	(segment
		(start 368.182652 -274.41398)
		(end 368.181636 -274.414488)
		(width 0.1143)
		(layer "In13.Cu")
		(net "P5E_CPU0_P2_TX_DP<8>")
	)
	(segment
		(start 368.192558 -274.408138)
		(end 368.191796 -274.408646)
		(width 0.1143)
		(layer "In13.Cu")
		(net "P5E_CPU0_P2_TX_DP<8>")
	)
	(segment
		(start 368.181636 -276.0345)
		(end 368.15268 -276.051518)
		(width 0.1143)
		(layer "In13.Cu")
		(net "P5E_CPU0_P2_TX_DP<8>")
	)
	(segment
		(start 368.192558 -275.384006)
		(end 368.195352 -275.38553)
		(width 0.1143)
		(layer "In13.Cu")
		(net "P5E_CPU0_P2_TX_DP<8>")
	)
	(segment
		(start 368.159538 -275.364702)
		(end 368.1603 -275.36521)
		(width 0.1143)
		(layer "In13.Cu")
		(net "P5E_CPU0_P2_TX_DP<8>")
	)
	(segment
		(start 368.15268 -293.180516)
		(end 368.19078 -293.202868)
		(width 0.1143)
		(layer "In13.Cu")
		(net "P5E_CPU0_P2_TX_DP<8>")
	)
	(segment
		(start 368.191796 -273.763486)
		(end 368.192558 -273.763994)
		(width 0.1143)
		(layer "In13.Cu")
		(net "P5E_CPU0_P2_TX_DP<8>")
	)
	(segment
		(start 368.20221 -275.38934)
		(end 368.223546 -275.401786)
		(width 0.1143)
		(layer "In13.Cu")
		(net "P5E_CPU0_P2_TX_DP<8>")
	)
	(segment
		(start 368.192558 -282.508452)
		(end 368.191796 -282.508706)
		(width 0.1143)
		(layer "In13.Cu")
		(net "P5E_CPU0_P2_TX_DP<8>")
	)
	(segment
		(start 368.19078 -276.029166)
		(end 368.189256 -276.030182)
		(width 0.1143)
		(layer "In13.Cu")
		(net "P5E_CPU0_P2_TX_DP<8>")
	)
	(segment
		(start 368.15268 -280.220674)
		(end 368.190018 -280.242518)
		(width 0.1143)
		(layer "In13.Cu")
		(net "P5E_CPU0_P2_TX_DP<8>")
	)
	(segment
		(start 368.19078 -278.623014)
		(end 368.191796 -278.623522)
		(width 0.1143)
		(layer "In13.Cu")
		(net "P5E_CPU0_P2_TX_DP<8>")
	)
	(segment
		(start 368.185954 -279.271984)
		(end 368.184176 -279.273)
		(width 0.1143)
		(layer "In13.Cu")
		(net "P5E_CPU0_P2_TX_DP<8>")
	)
	(segment
		(start 368.192558 -289.96386)
		(end 368.19459 -289.96513)
		(width 0.1143)
		(layer "In13.Cu")
		(net "P5E_CPU0_P2_TX_DP<8>")
	)
	(segment
		(start 368.191796 -280.243534)
		(end 368.223546 -280.261822)
		(width 0.1143)
		(layer "In13.Cu")
		(net "P5E_CPU0_P2_TX_DP<8>")
	)
	(segment
		(start 368.192558 -277.004018)
		(end 368.195352 -277.005542)
		(width 0.1143)
		(layer "In13.Cu")
		(net "P5E_CPU0_P2_TX_DP<8>")
	)
	(segment
		(start 368.193828 -278.624792)
		(end 368.223546 -278.64181)
		(width 0.1143)
		(layer "In13.Cu")
		(net "P5E_CPU0_P2_TX_DP<8>")
	)
	(segment
		(start 368.158776 -288.32429)
		(end 368.15903 -288.32429)
		(width 0.1143)
		(layer "In13.Cu")
		(net "P5E_CPU0_P2_TX_DP<8>")
	)
	(segment
		(start 368.852704 -296.36339)
		(end 368.806984 -296.40911)
		(width 0.1143)
		(layer "In13.Cu")
		(net "P5E_CPU0_P2_TX_DP<8>")
	)
	(segment
		(start 368.191796 -285.10357)
		(end 368.192558 -285.104078)
		(width 0.1143)
		(layer "In13.Cu")
		(net "P5E_CPU0_P2_TX_DP<8>")
	)
	(segment
		(start 368.1603 -275.36521)
		(end 368.191796 -275.383498)
		(width 0.1143)
		(layer "In13.Cu")
		(net "P5E_CPU0_P2_TX_DP<8>")
	)
	(segment
		(start 368.1603 -273.745198)
		(end 368.191796 -273.763486)
		(width 0.1143)
		(layer "In13.Cu")
		(net "P5E_CPU0_P2_TX_DP<8>")
	)
	(segment
		(start 368.19078 -284.129226)
		(end 368.15268 -284.151578)
		(width 0.1143)
		(layer "In13.Cu")
		(net "P5E_CPU0_P2_TX_DP<8>")
	)
	(segment
		(start 368.192558 -290.608258)
		(end 368.191796 -290.608512)
		(width 0.1143)
		(layer "In13.Cu")
		(net "P5E_CPU0_P2_TX_DP<8>")
	)
	(segment
		(start 368.19078 -285.749238)
		(end 368.15268 -285.77159)
		(width 0.1143)
		(layer "In13.Cu")
		(net "P5E_CPU0_P2_TX_DP<8>")
	)
	(segment
		(start 368.15268 -294.800528)
		(end 368.19078 -294.82288)
		(width 0.1143)
		(layer "In13.Cu")
		(net "P5E_CPU0_P2_TX_DP<8>")
	)
	(segment
		(start 368.196114 -273.766026)
		(end 368.197638 -273.766788)
		(width 0.1143)
		(layer "In13.Cu")
		(net "P5E_CPU0_P2_TX_DP<8>")
	)
	(segment
		(start 368.196114 -277.00605)
		(end 368.197638 -277.006812)
		(width 0.1143)
		(layer "In13.Cu")
		(net "P5E_CPU0_P2_TX_DP<8>")
	)
	(segment
		(start 368.194844 -284.12694)
		(end 368.192558 -284.128464)
		(width 0.1143)
		(layer "In13.Cu")
		(net "P5E_CPU0_P2_TX_DP<8>")
	)
	(segment
		(start 368.194844 -288.986722)
		(end 368.192558 -288.988246)
		(width 0.1143)
		(layer "In13.Cu")
		(net "P5E_CPU0_P2_TX_DP<8>")
	)
	(segment
		(start 368.19078 -282.509214)
		(end 368.15268 -282.531566)
		(width 0.1143)
		(layer "In13.Cu")
		(net "P5E_CPU0_P2_TX_DP<8>")
	)
	(segment
		(start 368.638836 -295.619932)
		(end 368.671348 -295.638982)
		(width 0.1143)
		(layer "In13.Cu")
		(net "P5E_CPU0_P2_TX_DP<8>")
	)
	(segment
		(start 368.190018 -280.242518)
		(end 368.19078 -280.243026)
		(width 0.1143)
		(layer "In13.Cu")
		(net "P5E_CPU0_P2_TX_DP<8>")
	)
	(segment
		(start 368.197638 -273.766788)
		(end 368.1984 -273.767296)
		(width 0.1143)
		(layer "In13.Cu")
		(net "P5E_CPU0_P2_TX_DP<8>")
	)
	(segment
		(start 368.184176 -274.412964)
		(end 368.182652 -274.41398)
		(width 0.1143)
		(layer "In13.Cu")
		(net "P5E_CPU0_P2_TX_DP<8>")
	)
	(segment
		(start 368.191796 -289.963352)
		(end 368.192558 -289.96386)
		(width 0.1143)
		(layer "In13.Cu")
		(net "P5E_CPU0_P2_TX_DP<8>")
	)
	(segment
		(start 368.18824 -274.410678)
		(end 368.18697 -274.41144)
		(width 0.1143)
		(layer "In13.Cu")
		(net "P5E_CPU0_P2_TX_DP<8>")
	)
	(segment
		(start 368.638328 -295.619678)
		(end 368.638836 -295.619932)
		(width 0.1143)
		(layer "In13.Cu")
		(net "P5E_CPU0_P2_TX_DP<8>")
	)
	(segment
		(start 368.191796 -275.383498)
		(end 368.192558 -275.384006)
		(width 0.1143)
		(layer "In13.Cu")
		(net "P5E_CPU0_P2_TX_DP<8>")
	)
	(segment
		(start 368.191796 -293.203376)
		(end 368.192558 -293.203884)
		(width 0.1143)
		(layer "In13.Cu")
		(net "P5E_CPU0_P2_TX_DP<8>")
	)
	(segment
		(start 368.189256 -277.650194)
		(end 368.18824 -277.650702)
		(width 0.1143)
		(layer "In13.Cu")
		(net "P5E_CPU0_P2_TX_DP<8>")
	)
	(segment
		(start 368.223546 -280.870406)
		(end 368.191796 -280.888694)
		(width 0.1143)
		(layer "In13.Cu")
		(net "P5E_CPU0_P2_TX_DP<8>")
	)
	(segment
		(start 368.191796 -280.888694)
		(end 368.155474 -280.909522)
		(width 0.1143)
		(layer "In13.Cu")
		(net "P5E_CPU0_P2_TX_DP<8>")
	)
	(segment
		(start 368.15268 -281.840686)
		(end 368.19078 -281.863038)
		(width 0.1143)
		(layer "In13.Cu")
		(net "P5E_CPU0_P2_TX_DP<8>")
	)
	(segment
		(start 368.189256 -279.270206)
		(end 368.18824 -279.270714)
		(width 0.1143)
		(layer "In13.Cu")
		(net "P5E_CPU0_P2_TX_DP<8>")
	)
	(segment
		(start 368.191796 -279.268682)
		(end 368.19078 -279.26919)
		(width 0.1143)
		(layer "In13.Cu")
		(net "P5E_CPU0_P2_TX_DP<8>")
	)
	(segment
		(start 368.19078 -290.60902)
		(end 368.15268 -290.631372)
		(width 0.1143)
		(layer "In13.Cu")
		(net "P5E_CPU0_P2_TX_DP<8>")
	)
	(segment
		(start 395.58341 -363.332268)
		(end 400.097244 -370.087906)
		(width 0.14224)
		(layer "In13.Cu")
		(net "P5E_CPU0_P2_TX_DP<8>")
	)
	(segment
		(start 368.192558 -276.02815)
		(end 368.191796 -276.028658)
		(width 0.1143)
		(layer "In13.Cu")
		(net "P5E_CPU0_P2_TX_DP<8>")
	)
	(segment
		(start 368.19459 -285.105348)
		(end 368.195098 -285.105348)
		(width 0.1143)
		(layer "In13.Cu")
		(net "P5E_CPU0_P2_TX_DP<8>")
	)
	(segment
		(start 368.15268 -285.08071)
		(end 368.19078 -285.103062)
		(width 0.1143)
		(layer "In13.Cu")
		(net "P5E_CPU0_P2_TX_DP<8>")
	)
	(segment
		(start 368.195352 -288.986722)
		(end 368.194844 -288.986722)
		(width 0.1143)
		(layer "In13.Cu")
		(net "P5E_CPU0_P2_TX_DP<8>")
	)
	(segment
		(start 368.181636 -277.654512)
		(end 368.15268 -277.67153)
		(width 0.1143)
		(layer "In13.Cu")
		(net "P5E_CPU0_P2_TX_DP<8>")
	)
	(segment
		(start 368.184176 -276.032976)
		(end 368.182652 -276.033992)
		(width 0.1143)
		(layer "In13.Cu")
		(net "P5E_CPU0_P2_TX_DP<8>")
	)
	(segment
		(start 368.20221 -273.769328)
		(end 368.223546 -273.781774)
		(width 0.1143)
		(layer "In13.Cu")
		(net "P5E_CPU0_P2_TX_DP<8>")
	)
	(segment
		(start 368.192558 -293.203884)
		(end 368.19459 -293.205154)
		(width 0.1143)
		(layer "In13.Cu")
		(net "P5E_CPU0_P2_TX_DP<8>")
	)
	(segment
		(start 368.19967 -275.38807)
		(end 368.20221 -275.38934)
		(width 0.1143)
		(layer "In13.Cu")
		(net "P5E_CPU0_P2_TX_DP<8>")
	)
	(segment
		(start 368.195352 -273.765518)
		(end 368.196114 -273.766026)
		(width 0.1143)
		(layer "In13.Cu")
		(net "P5E_CPU0_P2_TX_DP<8>")
	)
	(segment
		(start 368.186208 -292.231826)
		(end 368.15268 -292.251384)
		(width 0.1143)
		(layer "In13.Cu")
		(net "P5E_CPU0_P2_TX_DP<8>")
	)
	(segment
		(start 368.223546 -274.390358)
		(end 368.192558 -274.408138)
		(width 0.1143)
		(layer "In13.Cu")
		(net "P5E_CPU0_P2_TX_DP<8>")
	)
	(segment
		(start 368.19078 -288.989008)
		(end 368.15268 -289.01136)
		(width 0.1143)
		(layer "In13.Cu")
		(net "P5E_CPU0_P2_TX_DP<8>")
	)
	(segment
		(start 368.188748 -292.230302)
		(end 368.187224 -292.231318)
		(width 0.1143)
		(layer "In13.Cu")
		(net "P5E_CPU0_P2_TX_DP<8>")
	)
	(segment
		(start 368.19459 -281.865324)
		(end 368.195098 -281.865324)
		(width 0.1143)
		(layer "In13.Cu")
		(net "P5E_CPU0_P2_TX_DP<8>")
	)
	(segment
		(start 368.19078 -281.863038)
		(end 368.191796 -281.863546)
		(width 0.1143)
		(layer "In13.Cu")
		(net "P5E_CPU0_P2_TX_DP<8>")
	)
	(segment
		(start 368.223546 -291.601652)
		(end 368.228626 -291.605208)
		(width 0.1143)
		(layer "In13.Cu")
		(net "P5E_CPU0_P2_TX_DP<8>")
	)
	(segment
		(start 368.19078 -285.103062)
		(end 368.191796 -285.10357)
		(width 0.1143)
		(layer "In13.Cu")
		(net "P5E_CPU0_P2_TX_DP<8>")
	)
	(segment
		(start 368.195352 -285.746952)
		(end 368.194844 -285.746952)
		(width 0.1143)
		(layer "In13.Cu")
		(net "P5E_CPU0_P2_TX_DP<8>")
	)
	(segment
		(start 368.195352 -290.606734)
		(end 368.194844 -290.606734)
		(width 0.1143)
		(layer "In13.Cu")
		(net "P5E_CPU0_P2_TX_DP<8>")
	)
	(segment
		(start 367.83264 -273.27606)
		(end 367.915444 -273.358864)
		(width 0.1143)
		(layer "In13.Cu")
		(net "P5E_CPU0_P2_TX_DP<8>")
	)
	(segment
		(start 368.192558 -291.583872)
		(end 368.223546 -291.601652)
		(width 0.1143)
		(layer "In13.Cu")
		(net "P5E_CPU0_P2_TX_DP<8>")
	)
	(segment
		(start 368.192558 -285.104078)
		(end 368.19459 -285.105348)
		(width 0.1143)
		(layer "In13.Cu")
		(net "P5E_CPU0_P2_TX_DP<8>")
	)
	(segment
		(start 368.192558 -273.763994)
		(end 368.195352 -273.765518)
		(width 0.1143)
		(layer "In13.Cu")
		(net "P5E_CPU0_P2_TX_DP<8>")
	)
	(segment
		(start 368.15268 -278.600662)
		(end 368.19078 -278.623014)
		(width 0.1143)
		(layer "In13.Cu")
		(net "P5E_CPU0_P2_TX_DP<8>")
	)
	(segment
		(start 368.223546 -279.250394)
		(end 368.192558 -279.268174)
		(width 0.1143)
		(layer "In13.Cu")
		(net "P5E_CPU0_P2_TX_DP<8>")
	)
	(segment
		(start 368.189256 -276.030182)
		(end 368.18824 -276.03069)
		(width 0.1143)
		(layer "In13.Cu")
		(net "P5E_CPU0_P2_TX_DP<8>")
	)
	(segment
		(start 368.159538 -273.74469)
		(end 368.1603 -273.745198)
		(width 0.1143)
		(layer "In13.Cu")
		(net "P5E_CPU0_P2_TX_DP<8>")
	)
	(segment
		(start 368.182652 -277.654004)
		(end 368.181636 -277.654512)
		(width 0.1143)
		(layer "In13.Cu")
		(net "P5E_CPU0_P2_TX_DP<8>")
	)
	(segment
		(start 367.534698 -273.27606)
		(end 367.83264 -273.27606)
		(width 0.1143)
		(layer "In13.Cu")
		(net "P5E_CPU0_P2_TX_DP<8>")
	)
	(segment
		(start 412.06801 -376.343164)
		(end 412.526734 -377.029472)
		(width 0.14224)
		(layer "In13.Cu")
		(net "P5E_CPU0_P2_TX_DP<8>")
	)
	(segment
		(start 368.191796 -291.583364)
		(end 368.192558 -291.583872)
		(width 0.1143)
		(layer "In13.Cu")
		(net "P5E_CPU0_P2_TX_DP<8>")
	)
	(segment
		(start 368.181636 -279.274524)
		(end 368.15268 -279.291542)
		(width 0.1143)
		(layer "In13.Cu")
		(net "P5E_CPU0_P2_TX_DP<8>")
	)
	(segment
		(start 368.379502 -287.045908)
		(end 368.379502 -287.05048)
		(width 0.1143)
		(layer "In13.Cu")
		(net "P5E_CPU0_P2_TX_DP<8>")
	)
	(segment
		(start 368.19078 -294.82288)
		(end 368.194336 -294.824658)
		(width 0.1143)
		(layer "In13.Cu")
		(net "P5E_CPU0_P2_TX_DP<8>")
	)
	(segment
		(start 368.191796 -283.483558)
		(end 368.192558 -283.484066)
		(width 0.1143)
		(layer "In13.Cu")
		(net "P5E_CPU0_P2_TX_DP<8>")
	)
	(segment
		(start 368.192558 -281.864054)
		(end 368.19459 -281.865324)
		(width 0.1143)
		(layer "In13.Cu")
		(net "P5E_CPU0_P2_TX_DP<8>")
	)
	(segment
		(start 412.54807 -377.100084)
		(end 412.54807 -379.5903)
		(width 0.14224)
		(layer "In13.Cu")
		(net "P5E_CPU0_P2_TX_DP<8>")
	)
	(segment
		(start 368.19078 -291.582856)
		(end 368.191796 -291.583364)
		(width 0.1143)
		(layer "In13.Cu")
		(net "P5E_CPU0_P2_TX_DP<8>")
	)
	(segment
		(start 368.191796 -276.028658)
		(end 368.19078 -276.029166)
		(width 0.1143)
		(layer "In13.Cu")
		(net "P5E_CPU0_P2_TX_DP<8>")
	)
	(segment
		(start 368.19078 -274.409154)
		(end 368.189256 -274.41017)
		(width 0.1143)
		(layer "In13.Cu")
		(net "P5E_CPU0_P2_TX_DP<8>")
	)
	(segment
		(start 368.191796 -278.623522)
		(end 368.192558 -278.62403)
		(width 0.1143)
		(layer "In13.Cu")
		(net "P5E_CPU0_P2_TX_DP<8>")
	)
	(segment
		(start 368.194844 -288.345118)
		(end 368.195098 -288.345118)
		(width 0.1143)
		(layer "In13.Cu")
		(net "P5E_CPU0_P2_TX_DP<8>")
	)
	(segment
		(start 412.54807 -379.5903)
		(end 412.25724 -379.88113)
		(width 0.14224)
		(layer "In13.Cu")
		(net "P5E_CPU0_P2_TX_DP<8>")
	)
	(segment
		(start 368.15268 -283.460698)
		(end 368.159538 -283.464762)
		(width 0.1143)
		(layer "In13.Cu")
		(net "P5E_CPU0_P2_TX_DP<8>")
	)
	(segment
		(start 368.223546 -292.210236)
		(end 368.192558 -292.228016)
		(width 0.1143)
		(layer "In13.Cu")
		(net "P5E_CPU0_P2_TX_DP<8>")
	)
	(segment
		(start 368.195352 -275.38553)
		(end 368.196114 -275.386038)
		(width 0.1143)
		(layer "In13.Cu")
		(net "P5E_CPU0_P2_TX_DP<8>")
	)
	(segment
		(start 368.19459 -293.205154)
		(end 368.195098 -293.205154)
		(width 0.1143)
		(layer "In13.Cu")
		(net "P5E_CPU0_P2_TX_DP<8>")
	)
	(segment
		(start 368.195352 -277.005542)
		(end 368.196114 -277.00605)
		(width 0.1143)
		(layer "In13.Cu")
		(net "P5E_CPU0_P2_TX_DP<8>")
	)
	(segment
		(start 368.19078 -277.649178)
		(end 368.189256 -277.650194)
		(width 0.1143)
		(layer "In13.Cu")
		(net "P5E_CPU0_P2_TX_DP<8>")
	)
	(segment
		(start 368.671348 -295.638982)
		(end 368.67211 -295.63949)
		(width 0.1143)
		(layer "In13.Cu")
		(net "P5E_CPU0_P2_TX_DP<8>")
	)
	(segment
		(start 368.194844 -282.506928)
		(end 368.192558 -282.508452)
		(width 0.1143)
		(layer "In13.Cu")
		(net "P5E_CPU0_P2_TX_DP<8>")
	)
	(segment
		(start 368.15268 -291.560504)
		(end 368.19078 -291.582856)
		(width 0.1143)
		(layer "In13.Cu")
		(net "P5E_CPU0_P2_TX_DP<8>")
	)
	(segment
		(start 368.622834 -295.610534)
		(end 368.637566 -295.61917)
		(width 0.1143)
		(layer "In13.Cu")
		(net "P5E_CPU0_P2_TX_DP<8>")
	)
	(segment
		(start 368.194844 -285.746952)
		(end 368.192558 -285.748476)
		(width 0.1143)
		(layer "In13.Cu")
		(net "P5E_CPU0_P2_TX_DP<8>")
	)
	(segment
		(start 368.15268 -289.940492)
		(end 368.19078 -289.962844)
		(width 0.1143)
		(layer "In13.Cu")
		(net "P5E_CPU0_P2_TX_DP<8>")
	)
	(segment
		(start 368.192558 -284.128464)
		(end 368.191796 -284.128718)
		(width 0.1143)
		(layer "In13.Cu")
		(net "P5E_CPU0_P2_TX_DP<8>")
	)
	(segment
		(start 368.184176 -279.273)
		(end 368.182652 -279.274016)
		(width 0.1143)
		(layer "In13.Cu")
		(net "P5E_CPU0_P2_TX_DP<8>")
	)
	(segment
		(start 368.185954 -276.03196)
		(end 368.184176 -276.032976)
		(width 0.1143)
		(layer "In13.Cu")
		(net "P5E_CPU0_P2_TX_DP<8>")
	)
	(segment
		(start 368.191796 -290.608512)
		(end 368.19078 -290.60902)
		(width 0.1143)
		(layer "In13.Cu")
		(net "P5E_CPU0_P2_TX_DP<8>")
	)
	(segment
		(start 368.223546 -287.3502)
		(end 368.15522 -287.389824)
		(width 0.1143)
		(layer "In13.Cu")
		(net "P5E_CPU0_P2_TX_DP<8>")
	)
	(segment
		(start 368.19078 -289.962844)
		(end 368.191796 -289.963352)
		(width 0.1143)
		(layer "In13.Cu")
		(net "P5E_CPU0_P2_TX_DP<8>")
	)
	(segment
		(start 368.191796 -274.408646)
		(end 368.19078 -274.409154)
		(width 0.1143)
		(layer "In13.Cu")
		(net "P5E_CPU0_P2_TX_DP<8>")
	)
	(segment
		(start 368.189256 -274.41017)
		(end 368.18824 -274.410678)
		(width 0.1143)
		(layer "In13.Cu")
		(net "P5E_CPU0_P2_TX_DP<8>")
	)
	(segment
		(start 368.1984 -273.767296)
		(end 368.19967 -273.768058)
		(width 0.1143)
		(layer "In13.Cu")
		(net "P5E_CPU0_P2_TX_DP<8>")
	)
	(segment
		(start 368.18697 -274.41144)
		(end 368.185954 -274.411948)
		(width 0.1143)
		(layer "In13.Cu")
		(net "P5E_CPU0_P2_TX_DP<8>")
	)
	(segment
		(start 368.191796 -285.74873)
		(end 368.19078 -285.749238)
		(width 0.1143)
		(layer "In13.Cu")
		(net "P5E_CPU0_P2_TX_DP<8>")
	)
	(segment
		(start 368.18697 -277.651464)
		(end 368.185954 -277.651972)
		(width 0.1143)
		(layer "In13.Cu")
		(net "P5E_CPU0_P2_TX_DP<8>")
	)
	(segment
		(start 368.837972 -298.79036)
		(end 395.58341 -363.332268)
		(width 0.14224)
		(layer "In13.Cu")
		(net "P5E_CPU0_P2_TX_DP<8>")
	)
	(segment
		(start 368.191796 -284.128718)
		(end 368.19078 -284.129226)
		(width 0.1143)
		(layer "In13.Cu")
		(net "P5E_CPU0_P2_TX_DP<8>")
	)
	(segment
		(start 368.15268 -286.700722)
		(end 368.225324 -286.74314)
		(width 0.1143)
		(layer "In13.Cu")
		(net "P5E_CPU0_P2_TX_DP<8>")
	)
	(segment
		(start 368.195352 -293.846758)
		(end 368.194844 -293.846758)
		(width 0.1143)
		(layer "In13.Cu")
		(net "P5E_CPU0_P2_TX_DP<8>")
	)
	(segment
		(start 368.192558 -285.748476)
		(end 368.191796 -285.74873)
		(width 0.1143)
		(layer "In13.Cu")
		(net "P5E_CPU0_P2_TX_DP<8>")
	)
	(segment
		(start 368.18697 -279.271476)
		(end 368.185954 -279.271984)
		(width 0.1143)
		(layer "In13.Cu")
		(net "P5E_CPU0_P2_TX_DP<8>")
	)
	(segment
		(start 368.15268 -288.320734)
		(end 368.158776 -288.32429)
		(width 0.1143)
		(layer "In13.Cu")
		(net "P5E_CPU0_P2_TX_DP<8>")
	)
	(segment
		(start 368.19078 -279.26919)
		(end 368.189256 -279.270206)
		(width 0.1143)
		(layer "In13.Cu")
		(net "P5E_CPU0_P2_TX_DP<8>")
	)
	(segment
		(start 368.227356 -287.347406)
		(end 368.223546 -287.3502)
		(width 0.1143)
		(layer "In13.Cu")
		(net "P5E_CPU0_P2_TX_DP<8>")
	)
	(segment
		(start 368.1984 -277.00732)
		(end 368.19967 -277.008082)
		(width 0.1143)
		(layer "In13.Cu")
		(net "P5E_CPU0_P2_TX_DP<8>")
	)
	(segment
		(start 368.191796 -281.863546)
		(end 368.192558 -281.864054)
		(width 0.1143)
		(layer "In13.Cu")
		(net "P5E_CPU0_P2_TX_DP<8>")
	)
	(segment
		(start 368.1603 -283.46527)
		(end 368.191796 -283.483558)
		(width 0.1143)
		(layer "In13.Cu")
		(net "P5E_CPU0_P2_TX_DP<8>")
	)
	(segment
		(start 368.187224 -292.231318)
		(end 368.186208 -292.231826)
		(width 0.1143)
		(layer "In13.Cu")
		(net "P5E_CPU0_P2_TX_DP<8>")
	)
	(segment
		(start 368.191796 -277.00351)
		(end 368.192558 -277.004018)
		(width 0.1143)
		(layer "In13.Cu")
		(net "P5E_CPU0_P2_TX_DP<8>")
	)
	(segment
		(start 368.195352 -284.12694)
		(end 368.194844 -284.12694)
		(width 0.1143)
		(layer "In13.Cu")
		(net "P5E_CPU0_P2_TX_DP<8>")
	)
	(segment
		(start 368.1603 -276.985222)
		(end 368.191796 -277.00351)
		(width 0.1143)
		(layer "In13.Cu")
		(net "P5E_CPU0_P2_TX_DP<8>")
	)
	(segment
		(start 368.192558 -293.848282)
		(end 368.191796 -293.848536)
		(width 0.1143)
		(layer "In13.Cu")
		(net "P5E_CPU0_P2_TX_DP<8>")
	)
	(segment
		(start 368.806984 -296.40911)
		(end 368.806984 -296.437558)
		(width 0.1143)
		(layer "In13.Cu")
		(net "P5E_CPU0_P2_TX_DP<8>")
	)
	(segment
		(start 368.197638 -275.3868)
		(end 368.1984 -275.387308)
		(width 0.1143)
		(layer "In13.Cu")
		(net "P5E_CPU0_P2_TX_DP<8>")
	)
	(segment
		(start 368.228626 -292.20668)
		(end 368.223546 -292.210236)
		(width 0.1143)
		(layer "In13.Cu")
		(net "P5E_CPU0_P2_TX_DP<8>")
	)
	(segment
		(start 368.181636 -274.414488)
		(end 368.15268 -274.431506)
		(width 0.1143)
		(layer "In13.Cu")
		(net "P5E_CPU0_P2_TX_DP<8>")
	)
	(segment
		(start 368.194844 -290.606734)
		(end 368.192558 -290.608258)
		(width 0.1143)
		(layer "In13.Cu")
		(net "P5E_CPU0_P2_TX_DP<8>")
	)
	(segment
		(start 368.185954 -277.651972)
		(end 368.184176 -277.652988)
		(width 0.1143)
		(layer "In13.Cu")
		(net "P5E_CPU0_P2_TX_DP<8>")
	)
	(segment
		(start 368.19078 -293.849044)
		(end 368.15268 -293.871396)
		(width 0.1143)
		(layer "In13.Cu")
		(net "P5E_CPU0_P2_TX_DP<8>")
	)
	(segment
		(start 368.19078 -292.229032)
		(end 368.188748 -292.230302)
		(width 0.1143)
		(layer "In13.Cu")
		(net "P5E_CPU0_P2_TX_DP<8>")
	)
	(segment
		(start 368.18697 -276.031452)
		(end 368.185954 -276.03196)
		(width 0.1143)
		(layer "In13.Cu")
		(net "P5E_CPU0_P2_TX_DP<8>")
	)
	(segment
		(start 368.185954 -274.411948)
		(end 368.184176 -274.412964)
		(width 0.1143)
		(layer "In13.Cu")
		(net "P5E_CPU0_P2_TX_DP<8>")
	)
	(segment
		(start 368.192558 -277.648162)
		(end 368.191796 -277.64867)
		(width 0.1143)
		(layer "In13.Cu")
		(net "P5E_CPU0_P2_TX_DP<8>")
	)
	(segment
		(start 368.194336 -294.824658)
		(end 368.224562 -294.842692)
		(width 0.1143)
		(layer "In13.Cu")
		(net "P5E_CPU0_P2_TX_DP<8>")
	)
	(segment
		(start 368.15903 -288.32429)
		(end 368.194844 -288.345118)
		(width 0.1143)
		(layer "In13.Cu")
		(net "P5E_CPU0_P2_TX_DP<8>")
	)
	(segment
		(start 400.462242 -370.452904)
		(end 404.044912 -372.8466)
		(width 0.14224)
		(layer "In13.Cu")
		(net "P5E_CPU0_P2_TX_DP<8>")
	)
	(segment
		(start 368.1984 -275.387308)
		(end 368.19967 -275.38807)
		(width 0.1143)
		(layer "In13.Cu")
		(net "P5E_CPU0_P2_TX_DP<8>")
	)
	(segment
		(start 368.15268 -273.740626)
		(end 368.159538 -273.74469)
		(width 0.1143)
		(layer "In13.Cu")
		(net "P5E_CPU0_P2_TX_DP<8>")
	)
	(segment
		(start 368.182652 -276.033992)
		(end 368.181636 -276.0345)
		(width 0.1143)
		(layer "In13.Cu")
		(net "P5E_CPU0_P2_TX_DP<8>")
	)
	(segment
		(start 368.192558 -279.268174)
		(end 368.191796 -279.268682)
		(width 0.1143)
		(layer "In13.Cu")
		(net "P5E_CPU0_P2_TX_DP<8>")
	)
	(segment
		(start 368.223546 -276.01037)
		(end 368.192558 -276.02815)
		(width 0.1143)
		(layer "In13.Cu")
		(net "P5E_CPU0_P2_TX_DP<8>")
	)
	(segment
		(start 368.192558 -283.484066)
		(end 368.19459 -283.485336)
		(width 0.1143)
		(layer "In13.Cu")
		(net "P5E_CPU0_P2_TX_DP<8>")
	)
	(segment
		(start 368.637566 -295.61917)
		(end 368.638328 -295.619678)
		(width 0.1143)
		(layer "In13.Cu")
		(net "P5E_CPU0_P2_TX_DP<8>")
	)
	(segment
		(start 368.155474 -280.909522)
		(end 368.15268 -280.911554)
		(width 0.1143)
		(layer "In13.Cu")
		(net "P5E_CPU0_P2_TX_DP<8>")
	)
	(segment
		(start 368.196114 -275.386038)
		(end 368.197638 -275.3868)
		(width 0.1143)
		(layer "In13.Cu")
		(net "P5E_CPU0_P2_TX_DP<8>")
	)
	(segment
		(start 368.159538 -276.984714)
		(end 368.1603 -276.985222)
		(width 0.1143)
		(layer "In13.Cu")
		(net "P5E_CPU0_P2_TX_DP<8>")
	)
	(segment
		(start 368.191796 -282.508706)
		(end 368.19078 -282.509214)
		(width 0.1143)
		(layer "In13.Cu")
		(net "P5E_CPU0_P2_TX_DP<8>")
	)
	(segment
		(start 368.195352 -282.506928)
		(end 368.194844 -282.506928)
		(width 0.1143)
		(layer "In13.Cu")
		(net "P5E_CPU0_P2_TX_DP<8>")
	)
	(segment
		(start 368.184176 -277.652988)
		(end 368.182652 -277.654004)
		(width 0.1143)
		(layer "In13.Cu")
		(net "P5E_CPU0_P2_TX_DP<8>")
	)
	(segment
		(start 368.197638 -277.006812)
		(end 368.1984 -277.00732)
		(width 0.1143)
		(layer "In13.Cu")
		(net "P5E_CPU0_P2_TX_DP<8>")
	)
	(segment
		(start 368.379502 -295.14165)
		(end 368.379502 -295.145968)
		(width 0.1143)
		(layer "In13.Cu")
		(net "P5E_CPU0_P2_TX_DP<8>")
	)
	(segment
		(start 368.191796 -292.228524)
		(end 368.19078 -292.229032)
		(width 0.1143)
		(layer "In13.Cu")
		(net "P5E_CPU0_P2_TX_DP<8>")
	)
	(segment
		(start 368.182652 -279.274016)
		(end 368.181636 -279.274524)
		(width 0.1143)
		(layer "In13.Cu")
		(net "P5E_CPU0_P2_TX_DP<8>")
	)
	(segment
		(start 368.20221 -277.009352)
		(end 368.223546 -277.021798)
		(width 0.1143)
		(layer "In13.Cu")
		(net "P5E_CPU0_P2_TX_DP<8>")
	)
	(segment
		(start 404.044912 -372.8466)
		(end 411.641544 -375.993406)
		(width 0.14224)
		(layer "In13.Cu")
		(net "P5E_CPU0_P2_TX_DP<8>")
	)
	(segment
		(start 368.19078 -280.243026)
		(end 368.191796 -280.243534)
		(width 0.1143)
		(layer "In13.Cu")
		(net "P5E_CPU0_P2_TX_DP<8>")
	)
	(arc
		(start 368.223546 -273.781774)
		(mid 368.379474 -274.086066)
		(end 368.223546 -274.390358)
		(width 0.1143)
		(layer "In13.Cu")
		(net "P5E_CPU0_P2_TX_DP<8>")
	)
	(arc
		(start 368.223546 -277.021798)
		(mid 368.379474 -277.32609)
		(end 368.223546 -277.630382)
		(width 0.1143)
		(layer "In13.Cu")
		(net "P5E_CPU0_P2_TX_DP<8>")
	)
	(arc
		(start 400.097244 -370.087906)
		(mid 400.26177 -370.288378)
		(end 400.462242 -370.452904)
		(width 0.14224)
		(layer "In13.Cu")
		(net "P5E_CPU0_P2_TX_DP<8>")
	)
	(arc
		(start 368.806984 -298.633642)
		(mid 368.814752 -298.71353)
		(end 368.837972 -298.79036)
		(width 0.14224)
		(layer "In13.Cu")
		(net "P5E_CPU0_P2_TX_DP<8>")
	)
	(arc
		(start 368.379502 -287.05048)
		(mid 368.339247 -287.217293)
		(end 368.227356 -287.347406)
		(width 0.1143)
		(layer "In13.Cu")
		(net "P5E_CPU0_P2_TX_DP<8>")
	)
	(arc
		(start 368.15268 -280.911554)
		(mid 367.909353 -281.37612)
		(end 368.15268 -281.840686)
		(width 0.1143)
		(layer "In13.Cu")
		(net "P5E_CPU0_P2_TX_DP<8>")
	)
	(arc
		(start 368.15268 -292.251384)
		(mid 367.909353 -292.71595)
		(end 368.15268 -293.180516)
		(width 0.1143)
		(layer "In13.Cu")
		(net "P5E_CPU0_P2_TX_DP<8>")
	)
	(arc
		(start 368.15268 -274.431506)
		(mid 367.909353 -274.896072)
		(end 368.15268 -275.360638)
		(width 0.1143)
		(layer "In13.Cu")
		(net "P5E_CPU0_P2_TX_DP<8>")
	)
	(arc
		(start 368.195098 -293.205154)
		(mid 368.379831 -293.525846)
		(end 368.195352 -293.846758)
		(width 0.1143)
		(layer "In13.Cu")
		(net "P5E_CPU0_P2_TX_DP<8>")
	)
	(arc
		(start 411.641544 -375.993406)
		(mid 411.88071 -376.136665)
		(end 412.06801 -376.343164)
		(width 0.14224)
		(layer "In13.Cu")
		(net "P5E_CPU0_P2_TX_DP<8>")
	)
	(arc
		(start 368.195098 -289.96513)
		(mid 368.379831 -290.285822)
		(end 368.195352 -290.606734)
		(width 0.1143)
		(layer "In13.Cu")
		(net "P5E_CPU0_P2_TX_DP<8>")
	)
	(arc
		(start 368.15268 -282.531566)
		(mid 367.909353 -282.996132)
		(end 368.15268 -283.460698)
		(width 0.1143)
		(layer "In13.Cu")
		(net "P5E_CPU0_P2_TX_DP<8>")
	)
	(arc
		(start 368.15268 -285.77159)
		(mid 367.909353 -286.236156)
		(end 368.15268 -286.700722)
		(width 0.1143)
		(layer "In13.Cu")
		(net "P5E_CPU0_P2_TX_DP<8>")
	)
	(arc
		(start 368.195098 -281.865324)
		(mid 368.379831 -282.186016)
		(end 368.195352 -282.506928)
		(width 0.1143)
		(layer "In13.Cu")
		(net "P5E_CPU0_P2_TX_DP<8>")
	)
	(arc
		(start 368.15268 -279.291542)
		(mid 367.909353 -279.756108)
		(end 368.15268 -280.220674)
		(width 0.1143)
		(layer "In13.Cu")
		(net "P5E_CPU0_P2_TX_DP<8>")
	)
	(arc
		(start 368.379502 -295.145968)
		(mid 368.444017 -295.408187)
		(end 368.622834 -295.610534)
		(width 0.1143)
		(layer "In13.Cu")
		(net "P5E_CPU0_P2_TX_DP<8>")
	)
	(arc
		(start 368.760248 -295.712642)
		(mid 368.828777 -295.828545)
		(end 368.852704 -295.961054)
		(width 0.1143)
		(layer "In13.Cu")
		(net "P5E_CPU0_P2_TX_DP<8>")
	)
	(arc
		(start 368.195098 -283.485336)
		(mid 368.379831 -283.806028)
		(end 368.195352 -284.12694)
		(width 0.1143)
		(layer "In13.Cu")
		(net "P5E_CPU0_P2_TX_DP<8>")
	)
	(arc
		(start 368.223546 -278.64181)
		(mid 368.379474 -278.946102)
		(end 368.223546 -279.250394)
		(width 0.1143)
		(layer "In13.Cu")
		(net "P5E_CPU0_P2_TX_DP<8>")
	)
	(arc
		(start 367.909348 -287.856168)
		(mid 367.973863 -288.118387)
		(end 368.15268 -288.320734)
		(width 0.1143)
		(layer "In13.Cu")
		(net "P5E_CPU0_P2_TX_DP<8>")
	)
	(arc
		(start 368.15268 -276.051518)
		(mid 367.909353 -276.516084)
		(end 368.15268 -276.98065)
		(width 0.1143)
		(layer "In13.Cu")
		(net "P5E_CPU0_P2_TX_DP<8>")
	)
	(arc
		(start 368.224562 -294.842692)
		(mid 368.338445 -294.973306)
		(end 368.379502 -295.14165)
		(width 0.1143)
		(layer "In13.Cu")
		(net "P5E_CPU0_P2_TX_DP<8>")
	)
	(arc
		(start 368.223546 -280.261822)
		(mid 368.379474 -280.566114)
		(end 368.223546 -280.870406)
		(width 0.1143)
		(layer "In13.Cu")
		(net "P5E_CPU0_P2_TX_DP<8>")
	)
	(arc
		(start 367.915444 -273.358864)
		(mid 367.917232 -273.370313)
		(end 367.919254 -273.381724)
		(width 0.1143)
		(layer "In13.Cu")
		(net "P5E_CPU0_P2_TX_DP<8>")
	)
	(arc
		(start 368.15268 -277.67153)
		(mid 367.909353 -278.136096)
		(end 368.15268 -278.600662)
		(width 0.1143)
		(layer "In13.Cu")
		(net "P5E_CPU0_P2_TX_DP<8>")
	)
	(arc
		(start 368.228626 -291.605208)
		(mid 368.382724 -291.905944)
		(end 368.228626 -292.20668)
		(width 0.1143)
		(layer "In13.Cu")
		(net "P5E_CPU0_P2_TX_DP<8>")
	)
	(arc
		(start 368.15268 -293.871396)
		(mid 367.909353 -294.335962)
		(end 368.15268 -294.800528)
		(width 0.1143)
		(layer "In13.Cu")
		(net "P5E_CPU0_P2_TX_DP<8>")
	)
	(arc
		(start 368.15268 -289.01136)
		(mid 367.909353 -289.475926)
		(end 368.15268 -289.940492)
		(width 0.1143)
		(layer "In13.Cu")
		(net "P5E_CPU0_P2_TX_DP<8>")
	)
	(arc
		(start 368.15268 -284.151578)
		(mid 367.909353 -284.616144)
		(end 368.15268 -285.08071)
		(width 0.1143)
		(layer "In13.Cu")
		(net "P5E_CPU0_P2_TX_DP<8>")
	)
	(arc
		(start 368.195098 -288.345118)
		(mid 368.379831 -288.66581)
		(end 368.195352 -288.986722)
		(width 0.1143)
		(layer "In13.Cu")
		(net "P5E_CPU0_P2_TX_DP<8>")
	)
	(arc
		(start 368.15522 -287.389824)
		(mid 367.974568 -287.592569)
		(end 367.909348 -287.856168)
		(width 0.1143)
		(layer "In13.Cu")
		(net "P5E_CPU0_P2_TX_DP<8>")
	)
	(arc
		(start 368.15268 -290.631372)
		(mid 367.909353 -291.095938)
		(end 368.15268 -291.560504)
		(width 0.1143)
		(layer "In13.Cu")
		(net "P5E_CPU0_P2_TX_DP<8>")
	)
	(arc
		(start 368.67211 -295.63949)
		(mid 368.719173 -295.672458)
		(end 368.760248 -295.712642)
		(width 0.1143)
		(layer "In13.Cu")
		(net "P5E_CPU0_P2_TX_DP<8>")
	)
	(arc
		(start 367.919254 -273.381724)
		(mid 368.000687 -273.584122)
		(end 368.15268 -273.740626)
		(width 0.1143)
		(layer "In13.Cu")
		(net "P5E_CPU0_P2_TX_DP<8>")
	)
	(arc
		(start 368.195098 -285.105348)
		(mid 368.379831 -285.42604)
		(end 368.195352 -285.746952)
		(width 0.1143)
		(layer "In13.Cu")
		(net "P5E_CPU0_P2_TX_DP<8>")
	)
	(arc
		(start 368.223546 -275.401786)
		(mid 368.379474 -275.706078)
		(end 368.223546 -276.01037)
		(width 0.1143)
		(layer "In13.Cu")
		(net "P5E_CPU0_P2_TX_DP<8>")
	)
	(arc
		(start 368.225324 -286.74314)
		(mid 368.338731 -286.876029)
		(end 368.379502 -287.045908)
		(width 0.1143)
		(layer "In13.Cu")
		(net "P5E_CPU0_P2_TX_DP<8>")
	)
	(arc
		(start 412.526734 -377.029472)
		(mid 412.542615 -377.063198)
		(end 412.54807 -377.100084)
		(width 0.14224)
		(layer "In13.Cu")
		(net "P5E_CPU0_P2_TX_DP<8>")
	)
	(segment
		(start 410.82595 -383.31902)
		(end 410.53004 -383.61493)
		(width 0.12954)
		(layer "F.Cu")
		(net "P5E_CPU0_P2_TX_DP<7>")
	)
	(segment
		(start 410.55544 -382.34493)
		(end 410.82595 -382.61544)
		(width 0.12954)
		(layer "F.Cu")
		(net "P5E_CPU0_P2_TX_DP<7>")
	)
	(segment
		(start 410.82595 -382.61544)
		(end 410.82595 -383.31902)
		(width 0.12954)
		(layer "F.Cu")
		(net "P5E_CPU0_P2_TX_DP<7>")
	)
	(segment
		(start 367.067846 -269.770098)
		(end 367.534698 -270.036036)
		(width 0.12954)
		(layer "F.Cu")
		(net "P5E_CPU0_P2_TX_DP<7>")
	)
	(segment
		(start 367.283492 -280.870406)
		(end 367.253774 -280.887424)
		(width 0.1143)
		(layer "In13.Cu")
		(net "P5E_CPU0_P2_TX_DP<7>")
	)
	(segment
		(start 367.251742 -272.143474)
		(end 367.283492 -272.161762)
		(width 0.1143)
		(layer "In13.Cu")
		(net "P5E_CPU0_P2_TX_DP<7>")
	)
	(segment
		(start 367.251742 -292.228524)
		(end 367.251488 -292.228778)
		(width 0.1143)
		(layer "In13.Cu")
		(net "P5E_CPU0_P2_TX_DP<7>")
	)
	(segment
		(start 367.253774 -289.964622)
		(end 367.283492 -289.98164)
		(width 0.1143)
		(layer "In13.Cu")
		(net "P5E_CPU0_P2_TX_DP<7>")
	)
	(segment
		(start 367.251742 -286.723582)
		(end 367.28527 -286.74314)
		(width 0.1143)
		(layer "In13.Cu")
		(net "P5E_CPU0_P2_TX_DP<7>")
	)
	(segment
		(start 367.439448 -295.145968)
		(end 367.439702 -295.145968)
		(width 0.1143)
		(layer "In13.Cu")
		(net "P5E_CPU0_P2_TX_DP<7>")
	)
	(segment
		(start 367.251742 -275.383498)
		(end 367.283492 -275.401786)
		(width 0.1143)
		(layer "In13.Cu")
		(net "P5E_CPU0_P2_TX_DP<7>")
	)
	(segment
		(start 367.251742 -293.203376)
		(end 367.252504 -293.203884)
		(width 0.1143)
		(layer "In13.Cu")
		(net "P5E_CPU0_P2_TX_DP<7>")
	)
	(segment
		(start 367.249964 -285.749492)
		(end 367.249202 -285.75)
		(width 0.1143)
		(layer "In13.Cu")
		(net "P5E_CPU0_P2_TX_DP<7>")
	)
	(segment
		(start 367.252504 -291.583872)
		(end 367.253774 -291.584634)
		(width 0.1143)
		(layer "In13.Cu")
		(net "P5E_CPU0_P2_TX_DP<7>")
	)
	(segment
		(start 367.21542 -275.362416)
		(end 367.251742 -275.383498)
		(width 0.1143)
		(layer "In13.Cu")
		(net "P5E_CPU0_P2_TX_DP<7>")
	)
	(segment
		(start 367.251742 -278.623522)
		(end 367.283492 -278.64181)
		(width 0.1143)
		(layer "In13.Cu")
		(net "P5E_CPU0_P2_TX_DP<7>")
	)
	(segment
		(start 367.215166 -285.082234)
		(end 367.274094 -285.116524)
		(width 0.1143)
		(layer "In13.Cu")
		(net "P5E_CPU0_P2_TX_DP<7>")
	)
	(segment
		(start 367.255298 -293.205408)
		(end 367.25606 -293.205916)
		(width 0.1143)
		(layer "In13.Cu")
		(net "P5E_CPU0_P2_TX_DP<7>")
	)
	(segment
		(start 367.252504 -280.888186)
		(end 367.25098 -280.889202)
		(width 0.1143)
		(layer "In13.Cu")
		(net "P5E_CPU0_P2_TX_DP<7>")
	)
	(segment
		(start 367.66119 -295.594786)
		(end 367.88217 -295.815766)
		(width 0.1143)
		(layer "In13.Cu")
		(net "P5E_CPU0_P2_TX_DP<7>")
	)
	(segment
		(start 367.919508 -296.290746)
		(end 367.873788 -296.336466)
		(width 0.1143)
		(layer "In13.Cu")
		(net "P5E_CPU0_P2_TX_DP<7>")
	)
	(segment
		(start 367.283492 -271.150334)
		(end 367.251742 -271.168622)
		(width 0.1143)
		(layer "In13.Cu")
		(net "P5E_CPU0_P2_TX_DP<7>")
	)
	(segment
		(start 367.253774 -291.584634)
		(end 367.283492 -291.601652)
		(width 0.1143)
		(layer "In13.Cu")
		(net "P5E_CPU0_P2_TX_DP<7>")
	)
	(segment
		(start 367.83264 -270.036036)
		(end 367.90249 -270.105886)
		(width 0.1143)
		(layer "In13.Cu")
		(net "P5E_CPU0_P2_TX_DP<7>")
	)
	(segment
		(start 367.257838 -293.206932)
		(end 367.260378 -293.208202)
		(width 0.1143)
		(layer "In13.Cu")
		(net "P5E_CPU0_P2_TX_DP<7>")
	)
	(segment
		(start 367.251742 -288.9885)
		(end 367.248948 -288.990024)
		(width 0.1143)
		(layer "In13.Cu")
		(net "P5E_CPU0_P2_TX_DP<7>")
	)
	(segment
		(start 367.273332 -285.73603)
		(end 367.249964 -285.749492)
		(width 0.1143)
		(layer "In13.Cu")
		(net "P5E_CPU0_P2_TX_DP<7>")
	)
	(segment
		(start 399.543778 -370.970048)
		(end 403.60981 -373.687594)
		(width 0.14224)
		(layer "In13.Cu")
		(net "P5E_CPU0_P2_TX_DP<7>")
	)
	(segment
		(start 367.251742 -272.788634)
		(end 367.21542 -272.809716)
		(width 0.1143)
		(layer "In13.Cu")
		(net "P5E_CPU0_P2_TX_DP<7>")
	)
	(segment
		(start 367.251742 -293.848536)
		(end 367.234216 -293.858696)
		(width 0.1143)
		(layer "In13.Cu")
		(net "P5E_CPU0_P2_TX_DP<7>")
	)
	(segment
		(start 367.253774 -280.887424)
		(end 367.252504 -280.888186)
		(width 0.1143)
		(layer "In13.Cu")
		(net "P5E_CPU0_P2_TX_DP<7>")
	)
	(segment
		(start 367.873788 -296.364914)
		(end 367.873788 -298.795948)
		(width 0.14224)
		(layer "In13.Cu")
		(net "P5E_CPU0_P2_TX_DP<7>")
	)
	(segment
		(start 367.283492 -293.830248)
		(end 367.251742 -293.848536)
		(width 0.1143)
		(layer "In13.Cu")
		(net "P5E_CPU0_P2_TX_DP<7>")
	)
	(segment
		(start 407.730198 -375.444004)
		(end 409.067762 -376.781568)
		(width 0.14224)
		(layer "In13.Cu")
		(net "P5E_CPU0_P2_TX_DP<7>")
	)
	(segment
		(start 394.880338 -364.135162)
		(end 399.254726 -370.680996)
		(width 0.14224)
		(layer "In13.Cu")
		(net "P5E_CPU0_P2_TX_DP<7>")
	)
	(segment
		(start 367.25352 -288.987484)
		(end 367.252504 -288.987992)
		(width 0.1143)
		(layer "In13.Cu")
		(net "P5E_CPU0_P2_TX_DP<7>")
	)
	(segment
		(start 367.283492 -274.390358)
		(end 367.251742 -274.408646)
		(width 0.1143)
		(layer "In13.Cu")
		(net "P5E_CPU0_P2_TX_DP<7>")
	)
	(segment
		(start 410.84627 -379.460506)
		(end 410.84627 -382.0541)
		(width 0.14224)
		(layer "In13.Cu")
		(net "P5E_CPU0_P2_TX_DP<7>")
	)
	(segment
		(start 367.940336 -299.131736)
		(end 394.880338 -364.135162)
		(width 0.14224)
		(layer "In13.Cu")
		(net "P5E_CPU0_P2_TX_DP<7>")
	)
	(segment
		(start 367.251742 -276.028658)
		(end 367.21542 -276.04974)
		(width 0.1143)
		(layer "In13.Cu")
		(net "P5E_CPU0_P2_TX_DP<7>")
	)
	(segment
		(start 367.283492 -279.250394)
		(end 367.251742 -279.268682)
		(width 0.1143)
		(layer "In13.Cu")
		(net "P5E_CPU0_P2_TX_DP<7>")
	)
	(segment
		(start 367.283492 -292.210236)
		(end 367.251742 -292.228524)
		(width 0.1143)
		(layer "In13.Cu")
		(net "P5E_CPU0_P2_TX_DP<7>")
	)
	(segment
		(start 409.1432 -376.963432)
		(end 409.1432 -378.010166)
		(width 0.14224)
		(layer "In13.Cu")
		(net "P5E_CPU0_P2_TX_DP<7>")
	)
	(segment
		(start 367.283492 -290.590224)
		(end 367.251742 -290.608512)
		(width 0.1143)
		(layer "In13.Cu")
		(net "P5E_CPU0_P2_TX_DP<7>")
	)
	(segment
		(start 367.254282 -293.2049)
		(end 367.255298 -293.205408)
		(width 0.1143)
		(layer "In13.Cu")
		(net "P5E_CPU0_P2_TX_DP<7>")
	)
	(segment
		(start 367.251742 -277.00351)
		(end 367.283492 -277.021798)
		(width 0.1143)
		(layer "In13.Cu")
		(net "P5E_CPU0_P2_TX_DP<7>")
	)
	(segment
		(start 367.283492 -272.770346)
		(end 367.251742 -272.788634)
		(width 0.1143)
		(layer "In13.Cu")
		(net "P5E_CPU0_P2_TX_DP<7>")
	)
	(segment
		(start 367.254282 -288.986976)
		(end 367.25352 -288.987484)
		(width 0.1143)
		(layer "In13.Cu")
		(net "P5E_CPU0_P2_TX_DP<7>")
	)
	(segment
		(start 367.21542 -280.222452)
		(end 367.251742 -280.243534)
		(width 0.1143)
		(layer "In13.Cu")
		(net "P5E_CPU0_P2_TX_DP<7>")
	)
	(segment
		(start 367.21542 -283.462476)
		(end 367.283492 -283.501846)
		(width 0.1143)
		(layer "In13.Cu")
		(net "P5E_CPU0_P2_TX_DP<7>")
	)
	(segment
		(start 367.283492 -276.01037)
		(end 367.251742 -276.028658)
		(width 0.1143)
		(layer "In13.Cu")
		(net "P5E_CPU0_P2_TX_DP<7>")
	)
	(segment
		(start 410.84627 -382.0541)
		(end 410.55544 -382.34493)
		(width 0.14224)
		(layer "In13.Cu")
		(net "P5E_CPU0_P2_TX_DP<7>")
	)
	(segment
		(start 367.251742 -277.64867)
		(end 367.21542 -277.669752)
		(width 0.1143)
		(layer "In13.Cu")
		(net "P5E_CPU0_P2_TX_DP<7>")
	)
	(segment
		(start 367.251742 -273.763486)
		(end 367.283492 -273.781774)
		(width 0.1143)
		(layer "In13.Cu")
		(net "P5E_CPU0_P2_TX_DP<7>")
	)
	(segment
		(start 367.248948 -289.961828)
		(end 367.251742 -289.963352)
		(width 0.1143)
		(layer "In13.Cu")
		(net "P5E_CPU0_P2_TX_DP<7>")
	)
	(segment
		(start 367.752376 -270.340836)
		(end 367.721896 -270.358616)
		(width 0.1143)
		(layer "In13.Cu")
		(net "P5E_CPU0_P2_TX_DP<7>")
	)
	(segment
		(start 367.234216 -294.813228)
		(end 367.283492 -294.841676)
		(width 0.1143)
		(layer "In13.Cu")
		(net "P5E_CPU0_P2_TX_DP<7>")
	)
	(segment
		(start 367.251742 -280.243534)
		(end 367.283492 -280.261822)
		(width 0.1143)
		(layer "In13.Cu")
		(net "P5E_CPU0_P2_TX_DP<7>")
	)
	(segment
		(start 367.251742 -291.583364)
		(end 367.252504 -291.583872)
		(width 0.1143)
		(layer "In13.Cu")
		(net "P5E_CPU0_P2_TX_DP<7>")
	)
	(segment
		(start 367.257076 -293.206424)
		(end 367.257838 -293.206932)
		(width 0.1143)
		(layer "In13.Cu")
		(net "P5E_CPU0_P2_TX_DP<7>")
	)
	(segment
		(start 367.251742 -289.963352)
		(end 367.252504 -289.96386)
		(width 0.1143)
		(layer "In13.Cu")
		(net "P5E_CPU0_P2_TX_DP<7>")
	)
	(segment
		(start 367.21542 -272.122392)
		(end 367.251742 -272.143474)
		(width 0.1143)
		(layer "In13.Cu")
		(net "P5E_CPU0_P2_TX_DP<7>")
	)
	(segment
		(start 367.251488 -293.203376)
		(end 367.251742 -293.203376)
		(width 0.1143)
		(layer "In13.Cu")
		(net "P5E_CPU0_P2_TX_DP<7>")
	)
	(segment
		(start 367.251742 -274.408646)
		(end 367.21542 -274.429728)
		(width 0.1143)
		(layer "In13.Cu")
		(net "P5E_CPU0_P2_TX_DP<7>")
	)
	(segment
		(start 367.251996 -284.126432)
		(end 367.25098 -284.12694)
		(width 0.1143)
		(layer "In13.Cu")
		(net "P5E_CPU0_P2_TX_DP<7>")
	)
	(segment
		(start 367.252504 -293.203884)
		(end 367.25352 -293.204392)
		(width 0.1143)
		(layer "In13.Cu")
		(net "P5E_CPU0_P2_TX_DP<7>")
	)
	(segment
		(start 367.249456 -286.722312)
		(end 367.251742 -286.723582)
		(width 0.1143)
		(layer "In13.Cu")
		(net "P5E_CPU0_P2_TX_DP<7>")
	)
	(segment
		(start 367.283492 -288.970212)
		(end 367.255298 -288.986468)
		(width 0.1143)
		(layer "In13.Cu")
		(net "P5E_CPU0_P2_TX_DP<7>")
	)
	(segment
		(start 367.283492 -277.630382)
		(end 367.251742 -277.64867)
		(width 0.1143)
		(layer "In13.Cu")
		(net "P5E_CPU0_P2_TX_DP<7>")
	)
	(segment
		(start 367.873788 -296.336466)
		(end 367.873788 -296.364914)
		(width 0.1143)
		(layer "In13.Cu")
		(net "P5E_CPU0_P2_TX_DP<7>")
	)
	(segment
		(start 367.21542 -281.842464)
		(end 367.283492 -281.881834)
		(width 0.1143)
		(layer "In13.Cu")
		(net "P5E_CPU0_P2_TX_DP<7>")
	)
	(segment
		(start 367.21542 -273.742404)
		(end 367.251742 -273.763486)
		(width 0.1143)
		(layer "In13.Cu")
		(net "P5E_CPU0_P2_TX_DP<7>")
	)
	(segment
		(start 367.21542 -278.60244)
		(end 367.251742 -278.623522)
		(width 0.1143)
		(layer "In13.Cu")
		(net "P5E_CPU0_P2_TX_DP<7>")
	)
	(segment
		(start 367.249202 -285.75)
		(end 367.249456 -285.75)
		(width 0.1143)
		(layer "In13.Cu")
		(net "P5E_CPU0_P2_TX_DP<7>")
	)
	(segment
		(start 367.25606 -293.205916)
		(end 367.257076 -293.206424)
		(width 0.1143)
		(layer "In13.Cu")
		(net "P5E_CPU0_P2_TX_DP<7>")
	)
	(segment
		(start 367.252504 -288.987992)
		(end 367.251742 -288.9885)
		(width 0.1143)
		(layer "In13.Cu")
		(net "P5E_CPU0_P2_TX_DP<7>")
	)
	(segment
		(start 367.255298 -288.986468)
		(end 367.254282 -288.986976)
		(width 0.1143)
		(layer "In13.Cu")
		(net "P5E_CPU0_P2_TX_DP<7>")
	)
	(segment
		(start 367.251996 -282.50642)
		(end 367.25098 -282.506928)
		(width 0.1143)
		(layer "In13.Cu")
		(net "P5E_CPU0_P2_TX_DP<7>")
	)
	(segment
		(start 410.27477 -378.836174)
		(end 410.808932 -379.370336)
		(width 0.14224)
		(layer "In13.Cu")
		(net "P5E_CPU0_P2_TX_DP<7>")
	)
	(segment
		(start 367.919508 -295.905936)
		(end 367.919508 -296.290746)
		(width 0.1143)
		(layer "In13.Cu")
		(net "P5E_CPU0_P2_TX_DP<7>")
	)
	(segment
		(start 367.534698 -270.036036)
		(end 367.83264 -270.036036)
		(width 0.1143)
		(layer "In13.Cu")
		(net "P5E_CPU0_P2_TX_DP<7>")
	)
	(segment
		(start 367.252504 -289.96386)
		(end 367.253774 -289.964622)
		(width 0.1143)
		(layer "In13.Cu")
		(net "P5E_CPU0_P2_TX_DP<7>")
	)
	(segment
		(start 367.260378 -293.208202)
		(end 367.283492 -293.221664)
		(width 0.1143)
		(layer "In13.Cu")
		(net "P5E_CPU0_P2_TX_DP<7>")
	)
	(segment
		(start 367.721896 -270.358616)
		(end 367.68278 -270.381476)
		(width 0.1143)
		(layer "In13.Cu")
		(net "P5E_CPU0_P2_TX_DP<7>")
	)
	(segment
		(start 367.255552 -287.363916)
		(end 367.250726 -287.36671)
		(width 0.1143)
		(layer "In13.Cu")
		(net "P5E_CPU0_P2_TX_DP<7>")
	)
	(segment
		(start 367.21542 -276.982428)
		(end 367.251742 -277.00351)
		(width 0.1143)
		(layer "In13.Cu")
		(net "P5E_CPU0_P2_TX_DP<7>")
	)
	(segment
		(start 367.251742 -279.268682)
		(end 367.21542 -279.289764)
		(width 0.1143)
		(layer "In13.Cu")
		(net "P5E_CPU0_P2_TX_DP<7>")
	)
	(segment
		(start 367.251742 -271.168622)
		(end 367.21542 -271.189704)
		(width 0.1143)
		(layer "In13.Cu")
		(net "P5E_CPU0_P2_TX_DP<7>")
	)
	(segment
		(start 367.25352 -293.204392)
		(end 367.254282 -293.2049)
		(width 0.1143)
		(layer "In13.Cu")
		(net "P5E_CPU0_P2_TX_DP<7>")
	)
	(segment
		(start 367.21542 -288.322512)
		(end 367.28527 -288.363152)
		(width 0.1143)
		(layer "In13.Cu")
		(net "P5E_CPU0_P2_TX_DP<7>")
	)
	(segment
		(start 403.75205 -373.763286)
		(end 407.601674 -375.358152)
		(width 0.14224)
		(layer "In13.Cu")
		(net "P5E_CPU0_P2_TX_DP<7>")
	)
	(arc
		(start 399.254726 -370.680996)
		(mid 399.385024 -370.83975)
		(end 399.543778 -370.970048)
		(width 0.14224)
		(layer "In13.Cu")
		(net "P5E_CPU0_P2_TX_DP<7>")
	)
	(arc
		(start 367.25098 -280.889202)
		(mid 366.970414 -281.356065)
		(end 367.21542 -281.842464)
		(width 0.1143)
		(layer "In13.Cu")
		(net "P5E_CPU0_P2_TX_DP<7>")
	)
	(arc
		(start 367.439448 -270.846042)
		(mid 367.398193 -271.017013)
		(end 367.283492 -271.150334)
		(width 0.1143)
		(layer "In13.Cu")
		(net "P5E_CPU0_P2_TX_DP<7>")
	)
	(arc
		(start 366.969548 -287.856168)
		(mid 367.034784 -288.119759)
		(end 367.21542 -288.322512)
		(width 0.1143)
		(layer "In13.Cu")
		(net "P5E_CPU0_P2_TX_DP<7>")
	)
	(arc
		(start 367.21542 -274.429728)
		(mid 367.208271 -274.434628)
		(end 367.201196 -274.439634)
		(width 0.1143)
		(layer "In13.Cu")
		(net "P5E_CPU0_P2_TX_DP<7>")
	)
	(arc
		(start 367.201196 -272.112486)
		(mid 367.20827 -272.117493)
		(end 367.21542 -272.122392)
		(width 0.1143)
		(layer "In13.Cu")
		(net "P5E_CPU0_P2_TX_DP<7>")
	)
	(arc
		(start 367.249456 -285.75)
		(mid 366.969528 -286.236156)
		(end 367.249456 -286.722312)
		(width 0.1143)
		(layer "In13.Cu")
		(net "P5E_CPU0_P2_TX_DP<7>")
	)
	(arc
		(start 367.234216 -293.858696)
		(mid 366.959447 -294.335962)
		(end 367.234216 -294.813228)
		(width 0.1143)
		(layer "In13.Cu")
		(net "P5E_CPU0_P2_TX_DP<7>")
	)
	(arc
		(start 367.25098 -284.12694)
		(mid 367.247927 -284.128709)
		(end 367.244884 -284.130496)
		(width 0.1143)
		(layer "In13.Cu")
		(net "P5E_CPU0_P2_TX_DP<7>")
	)
	(arc
		(start 367.283492 -277.021798)
		(mid 367.43942 -277.32609)
		(end 367.283492 -277.630382)
		(width 0.1143)
		(layer "In13.Cu")
		(net "P5E_CPU0_P2_TX_DP<7>")
	)
	(arc
		(start 367.88217 -295.815766)
		(mid 367.909813 -295.857136)
		(end 367.919508 -295.905936)
		(width 0.1143)
		(layer "In13.Cu")
		(net "P5E_CPU0_P2_TX_DP<7>")
	)
	(arc
		(start 367.201196 -274.439634)
		(mid 366.973813 -274.896072)
		(end 367.201196 -275.35251)
		(width 0.1143)
		(layer "In13.Cu")
		(net "P5E_CPU0_P2_TX_DP<7>")
	)
	(arc
		(start 367.201196 -279.29967)
		(mid 366.973813 -279.756108)
		(end 367.201196 -280.212546)
		(width 0.1143)
		(layer "In13.Cu")
		(net "P5E_CPU0_P2_TX_DP<7>")
	)
	(arc
		(start 367.21542 -271.189704)
		(mid 367.208271 -271.194604)
		(end 367.201196 -271.19961)
		(width 0.1143)
		(layer "In13.Cu")
		(net "P5E_CPU0_P2_TX_DP<7>")
	)
	(arc
		(start 367.201196 -276.972522)
		(mid 367.20827 -276.977529)
		(end 367.21542 -276.982428)
		(width 0.1143)
		(layer "In13.Cu")
		(net "P5E_CPU0_P2_TX_DP<7>")
	)
	(arc
		(start 367.244884 -284.130496)
		(mid 366.969766 -284.59824)
		(end 367.215166 -285.082234)
		(width 0.1143)
		(layer "In13.Cu")
		(net "P5E_CPU0_P2_TX_DP<7>")
	)
	(arc
		(start 367.283492 -273.781774)
		(mid 367.43942 -274.086066)
		(end 367.283492 -274.390358)
		(width 0.1143)
		(layer "In13.Cu")
		(net "P5E_CPU0_P2_TX_DP<7>")
	)
	(arc
		(start 367.21542 -276.04974)
		(mid 367.208271 -276.05464)
		(end 367.201196 -276.059646)
		(width 0.1143)
		(layer "In13.Cu")
		(net "P5E_CPU0_P2_TX_DP<7>")
	)
	(arc
		(start 367.68278 -270.381476)
		(mid 367.503967 -270.583826)
		(end 367.439448 -270.846042)
		(width 0.1143)
		(layer "In13.Cu")
		(net "P5E_CPU0_P2_TX_DP<7>")
	)
	(arc
		(start 409.1432 -378.010166)
		(mid 409.196105 -378.253296)
		(end 409.345384 -378.45238)
		(width 0.14224)
		(layer "In13.Cu")
		(net "P5E_CPU0_P2_TX_DP<7>")
	)
	(arc
		(start 367.251488 -292.228778)
		(mid 366.970841 -292.71614)
		(end 367.251488 -293.203376)
		(width 0.1143)
		(layer "In13.Cu")
		(net "P5E_CPU0_P2_TX_DP<7>")
	)
	(arc
		(start 367.90249 -270.105886)
		(mid 367.850073 -270.237817)
		(end 367.752376 -270.340836)
		(width 0.1143)
		(layer "In13.Cu")
		(net "P5E_CPU0_P2_TX_DP<7>")
	)
	(arc
		(start 367.283492 -275.401786)
		(mid 367.43942 -275.706078)
		(end 367.283492 -276.01037)
		(width 0.1143)
		(layer "In13.Cu")
		(net "P5E_CPU0_P2_TX_DP<7>")
	)
	(arc
		(start 367.283492 -281.881834)
		(mid 367.437828 -282.202644)
		(end 367.251996 -282.50642)
		(width 0.1143)
		(layer "In13.Cu")
		(net "P5E_CPU0_P2_TX_DP<7>")
	)
	(arc
		(start 367.201196 -275.35251)
		(mid 367.20827 -275.357517)
		(end 367.21542 -275.362416)
		(width 0.1143)
		(layer "In13.Cu")
		(net "P5E_CPU0_P2_TX_DP<7>")
	)
	(arc
		(start 367.201196 -278.592534)
		(mid 367.20827 -278.597541)
		(end 367.21542 -278.60244)
		(width 0.1143)
		(layer "In13.Cu")
		(net "P5E_CPU0_P2_TX_DP<7>")
	)
	(arc
		(start 367.28527 -288.363152)
		(mid 367.398677 -288.496041)
		(end 367.439448 -288.66592)
		(width 0.1143)
		(layer "In13.Cu")
		(net "P5E_CPU0_P2_TX_DP<7>")
	)
	(arc
		(start 367.28527 -286.74314)
		(mid 367.398677 -286.876029)
		(end 367.439448 -287.045908)
		(width 0.1143)
		(layer "In13.Cu")
		(net "P5E_CPU0_P2_TX_DP<7>")
	)
	(arc
		(start 367.21542 -277.669752)
		(mid 367.208271 -277.674652)
		(end 367.201196 -277.679658)
		(width 0.1143)
		(layer "In13.Cu")
		(net "P5E_CPU0_P2_TX_DP<7>")
	)
	(arc
		(start 409.067762 -376.781568)
		(mid 409.123569 -376.864994)
		(end 409.1432 -376.963432)
		(width 0.14224)
		(layer "In13.Cu")
		(net "P5E_CPU0_P2_TX_DP<7>")
	)
	(arc
		(start 367.283492 -289.98164)
		(mid 367.43942 -290.285932)
		(end 367.283492 -290.590224)
		(width 0.1143)
		(layer "In13.Cu")
		(net "P5E_CPU0_P2_TX_DP<7>")
	)
	(arc
		(start 367.283492 -280.261822)
		(mid 367.43942 -280.566114)
		(end 367.283492 -280.870406)
		(width 0.1143)
		(layer "In13.Cu")
		(net "P5E_CPU0_P2_TX_DP<7>")
	)
	(arc
		(start 367.283492 -293.221664)
		(mid 367.43942 -293.525956)
		(end 367.283492 -293.830248)
		(width 0.1143)
		(layer "In13.Cu")
		(net "P5E_CPU0_P2_TX_DP<7>")
	)
	(arc
		(start 367.201196 -272.819622)
		(mid 366.973813 -273.27606)
		(end 367.201196 -273.732498)
		(width 0.1143)
		(layer "In13.Cu")
		(net "P5E_CPU0_P2_TX_DP<7>")
	)
	(arc
		(start 367.283492 -294.841676)
		(mid 367.398168 -294.97501)
		(end 367.439448 -295.145968)
		(width 0.1143)
		(layer "In13.Cu")
		(net "P5E_CPU0_P2_TX_DP<7>")
	)
	(arc
		(start 409.345384 -378.45238)
		(mid 409.736964 -378.693493)
		(end 410.1846 -378.798836)
		(width 0.14224)
		(layer "In13.Cu")
		(net "P5E_CPU0_P2_TX_DP<7>")
	)
	(arc
		(start 403.60981 -373.687594)
		(mid 403.6791 -373.728879)
		(end 403.75205 -373.763286)
		(width 0.14224)
		(layer "In13.Cu")
		(net "P5E_CPU0_P2_TX_DP<7>")
	)
	(arc
		(start 410.808932 -379.370336)
		(mid 410.836575 -379.411706)
		(end 410.84627 -379.460506)
		(width 0.14224)
		(layer "In13.Cu")
		(net "P5E_CPU0_P2_TX_DP<7>")
	)
	(arc
		(start 367.873788 -298.795948)
		(mid 367.890483 -298.967129)
		(end 367.940336 -299.131736)
		(width 0.14224)
		(layer "In13.Cu")
		(net "P5E_CPU0_P2_TX_DP<7>")
	)
	(arc
		(start 367.250726 -287.36671)
		(mid 367.044872 -287.573941)
		(end 366.969548 -287.856168)
		(width 0.1143)
		(layer "In13.Cu")
		(net "P5E_CPU0_P2_TX_DP<7>")
	)
	(arc
		(start 367.201196 -276.059646)
		(mid 366.973813 -276.516084)
		(end 367.201196 -276.972522)
		(width 0.1143)
		(layer "In13.Cu")
		(net "P5E_CPU0_P2_TX_DP<7>")
	)
	(arc
		(start 367.283492 -283.501846)
		(mid 367.437828 -283.822656)
		(end 367.251996 -284.126432)
		(width 0.1143)
		(layer "In13.Cu")
		(net "P5E_CPU0_P2_TX_DP<7>")
	)
	(arc
		(start 367.201196 -271.19961)
		(mid 366.973813 -271.656048)
		(end 367.201196 -272.112486)
		(width 0.1143)
		(layer "In13.Cu")
		(net "P5E_CPU0_P2_TX_DP<7>")
	)
	(arc
		(start 367.283492 -272.161762)
		(mid 367.43942 -272.466054)
		(end 367.283492 -272.770346)
		(width 0.1143)
		(layer "In13.Cu")
		(net "P5E_CPU0_P2_TX_DP<7>")
	)
	(arc
		(start 367.251742 -290.608512)
		(mid 366.971095 -291.095938)
		(end 367.251742 -291.583364)
		(width 0.1143)
		(layer "In13.Cu")
		(net "P5E_CPU0_P2_TX_DP<7>")
	)
	(arc
		(start 367.201196 -277.679658)
		(mid 366.973813 -278.136096)
		(end 367.201196 -278.592534)
		(width 0.1143)
		(layer "In13.Cu")
		(net "P5E_CPU0_P2_TX_DP<7>")
	)
	(arc
		(start 367.439448 -288.66592)
		(mid 367.398193 -288.836891)
		(end 367.283492 -288.970212)
		(width 0.1143)
		(layer "In13.Cu")
		(net "P5E_CPU0_P2_TX_DP<7>")
	)
	(arc
		(start 367.274094 -285.116524)
		(mid 367.451944 -285.426543)
		(end 367.273332 -285.73603)
		(width 0.1143)
		(layer "In13.Cu")
		(net "P5E_CPU0_P2_TX_DP<7>")
	)
	(arc
		(start 367.248948 -288.990024)
		(mid 366.969113 -289.475926)
		(end 367.248948 -289.961828)
		(width 0.1143)
		(layer "In13.Cu")
		(net "P5E_CPU0_P2_TX_DP<7>")
	)
	(arc
		(start 367.21542 -272.809716)
		(mid 367.208271 -272.814616)
		(end 367.201196 -272.819622)
		(width 0.1143)
		(layer "In13.Cu")
		(net "P5E_CPU0_P2_TX_DP<7>")
	)
	(arc
		(start 410.1846 -378.798836)
		(mid 410.233395 -378.808542)
		(end 410.27477 -378.836174)
		(width 0.14224)
		(layer "In13.Cu")
		(net "P5E_CPU0_P2_TX_DP<7>")
	)
	(arc
		(start 407.601674 -375.358152)
		(mid 407.670116 -375.394818)
		(end 407.730198 -375.444004)
		(width 0.14224)
		(layer "In13.Cu")
		(net "P5E_CPU0_P2_TX_DP<7>")
	)
	(arc
		(start 367.21542 -279.289764)
		(mid 367.208271 -279.294664)
		(end 367.201196 -279.29967)
		(width 0.1143)
		(layer "In13.Cu")
		(net "P5E_CPU0_P2_TX_DP<7>")
	)
	(arc
		(start 367.283492 -291.601652)
		(mid 367.43942 -291.905944)
		(end 367.283492 -292.210236)
		(width 0.1143)
		(layer "In13.Cu")
		(net "P5E_CPU0_P2_TX_DP<7>")
	)
	(arc
		(start 367.25098 -282.506928)
		(mid 366.969911 -282.974879)
		(end 367.21542 -283.462476)
		(width 0.1143)
		(layer "In13.Cu")
		(net "P5E_CPU0_P2_TX_DP<7>")
	)
	(arc
		(start 367.439448 -287.045908)
		(mid 367.390174 -287.229599)
		(end 367.255552 -287.363916)
		(width 0.1143)
		(layer "In13.Cu")
		(net "P5E_CPU0_P2_TX_DP<7>")
	)
	(arc
		(start 367.201196 -280.212546)
		(mid 367.20827 -280.217553)
		(end 367.21542 -280.222452)
		(width 0.1143)
		(layer "In13.Cu")
		(net "P5E_CPU0_P2_TX_DP<7>")
	)
	(arc
		(start 367.283492 -278.64181)
		(mid 367.43942 -278.946102)
		(end 367.283492 -279.250394)
		(width 0.1143)
		(layer "In13.Cu")
		(net "P5E_CPU0_P2_TX_DP<7>")
	)
	(arc
		(start 367.201196 -273.732498)
		(mid 367.20827 -273.737505)
		(end 367.21542 -273.742404)
		(width 0.1143)
		(layer "In13.Cu")
		(net "P5E_CPU0_P2_TX_DP<7>")
	)
	(arc
		(start 367.439702 -295.145968)
		(mid 367.498094 -295.396208)
		(end 367.66119 -295.594786)
		(width 0.1143)
		(layer "In13.Cu")
		(net "P5E_CPU0_P2_TX_DP<7>")
	)
	(segment
		(start 407.15184 -377.41733)
		(end 407.42235 -377.68784)
		(width 0.12954)
		(layer "F.Cu")
		(net "P5E_CPU0_P2_TX_DP<6>")
	)
	(segment
		(start 407.42235 -377.68784)
		(end 407.42235 -378.39142)
		(width 0.12954)
		(layer "F.Cu")
		(net "P5E_CPU0_P2_TX_DP<6>")
	)
	(segment
		(start 364.247938 -271.39011)
		(end 364.71479 -271.656048)
		(width 0.12954)
		(layer "F.Cu")
		(net "P5E_CPU0_P2_TX_DP<6>")
	)
	(segment
		(start 407.42235 -378.39142)
		(end 407.12644 -378.68733)
		(width 0.12954)
		(layer "F.Cu")
		(net "P5E_CPU0_P2_TX_DP<6>")
	)
	(segment
		(start 366.311942 -286.723582)
		(end 366.344454 -286.742378)
		(width 0.1143)
		(layer "In13.Cu")
		(net "P5E_CPU0_P2_TX_DP<6>")
	)
	(segment
		(start 366.311942 -283.483558)
		(end 366.342422 -283.501338)
		(width 0.1143)
		(layer "In13.Cu")
		(net "P5E_CPU0_P2_TX_DP<6>")
	)
	(segment
		(start 366.311942 -288.9885)
		(end 366.272826 -289.01136)
		(width 0.1143)
		(layer "In13.Cu")
		(net "P5E_CPU0_P2_TX_DP<6>")
	)
	(segment
		(start 366.311942 -290.608512)
		(end 366.272826 -290.631372)
		(width 0.1143)
		(layer "In13.Cu")
		(net "P5E_CPU0_P2_TX_DP<6>")
	)
	(segment
		(start 407.44267 -377.1265)
		(end 407.15184 -377.41733)
		(width 0.14224)
		(layer "In13.Cu")
		(net "P5E_CPU0_P2_TX_DP<6>")
	)
	(segment
		(start 366.342422 -276.010878)
		(end 366.311942 -276.028658)
		(width 0.1143)
		(layer "In13.Cu")
		(net "P5E_CPU0_P2_TX_DP<6>")
	)
	(segment
		(start 366.311942 -291.583364)
		(end 366.342422 -291.601144)
		(width 0.1143)
		(layer "In13.Cu")
		(net "P5E_CPU0_P2_TX_DP<6>")
	)
	(segment
		(start 366.311942 -294.823388)
		(end 366.342422 -294.841168)
		(width 0.1143)
		(layer "In13.Cu")
		(net "P5E_CPU0_P2_TX_DP<6>")
	)
	(segment
		(start 366.969548 -296.268394)
		(end 366.923828 -296.314114)
		(width 0.1143)
		(layer "In13.Cu")
		(net "P5E_CPU0_P2_TX_DP<6>")
	)
	(segment
		(start 366.272826 -293.180516)
		(end 366.311942 -293.203376)
		(width 0.1143)
		(layer "In13.Cu")
		(net "P5E_CPU0_P2_TX_DP<6>")
	)
	(segment
		(start 365.371888 -272.143474)
		(end 365.402368 -272.161254)
		(width 0.1143)
		(layer "In13.Cu")
		(net "P5E_CPU0_P2_TX_DP<6>")
	)
	(segment
		(start 366.342422 -290.590732)
		(end 366.311942 -290.608512)
		(width 0.1143)
		(layer "In13.Cu")
		(net "P5E_CPU0_P2_TX_DP<6>")
	)
	(segment
		(start 366.311942 -281.863546)
		(end 366.342422 -281.881326)
		(width 0.1143)
		(layer "In13.Cu")
		(net "P5E_CPU0_P2_TX_DP<6>")
	)
	(segment
		(start 366.342422 -277.63089)
		(end 366.311942 -277.64867)
		(width 0.1143)
		(layer "In13.Cu")
		(net "P5E_CPU0_P2_TX_DP<6>")
	)
	(segment
		(start 366.311942 -276.028658)
		(end 366.272826 -276.051518)
		(width 0.1143)
		(layer "In13.Cu")
		(net "P5E_CPU0_P2_TX_DP<6>")
	)
	(segment
		(start 407.061924 -376.146568)
		(end 407.44267 -376.527314)
		(width 0.14224)
		(layer "In13.Cu")
		(net "P5E_CPU0_P2_TX_DP<6>")
	)
	(segment
		(start 366.311942 -292.228524)
		(end 366.272826 -292.251384)
		(width 0.1143)
		(layer "In13.Cu")
		(net "P5E_CPU0_P2_TX_DP<6>")
	)
	(segment
		(start 366.272826 -283.460698)
		(end 366.311942 -283.483558)
		(width 0.1143)
		(layer "In13.Cu")
		(net "P5E_CPU0_P2_TX_DP<6>")
	)
	(segment
		(start 366.781842 -295.633394)
		(end 366.782604 -295.633902)
		(width 0.1143)
		(layer "In13.Cu")
		(net "P5E_CPU0_P2_TX_DP<6>")
	)
	(segment
		(start 366.272826 -291.560504)
		(end 366.311942 -291.583364)
		(width 0.1143)
		(layer "In13.Cu")
		(net "P5E_CPU0_P2_TX_DP<6>")
	)
	(segment
		(start 366.342422 -287.350708)
		(end 366.275366 -287.389824)
		(width 0.1143)
		(layer "In13.Cu")
		(net "P5E_CPU0_P2_TX_DP<6>")
	)
	(segment
		(start 366.311942 -289.963352)
		(end 366.342422 -289.981132)
		(width 0.1143)
		(layer "In13.Cu")
		(net "P5E_CPU0_P2_TX_DP<6>")
	)
	(segment
		(start 403.209506 -374.55094)
		(end 407.061924 -376.146568)
		(width 0.14224)
		(layer "In13.Cu")
		(net "P5E_CPU0_P2_TX_DP<6>")
	)
	(segment
		(start 366.311942 -273.763486)
		(end 366.342422 -273.781266)
		(width 0.1143)
		(layer "In13.Cu")
		(net "P5E_CPU0_P2_TX_DP<6>")
	)
	(segment
		(start 365.84255 -272.953988)
		(end 365.873538 -272.971768)
		(width 0.1143)
		(layer "In13.Cu")
		(net "P5E_CPU0_P2_TX_DP<6>")
	)
	(segment
		(start 366.272826 -286.700722)
		(end 366.311942 -286.723582)
		(width 0.1143)
		(layer "In13.Cu")
		(net "P5E_CPU0_P2_TX_DP<6>")
	)
	(segment
		(start 366.342422 -292.210744)
		(end 366.311942 -292.228524)
		(width 0.1143)
		(layer "In13.Cu")
		(net "P5E_CPU0_P2_TX_DP<6>")
	)
	(segment
		(start 365.802672 -272.93062)
		(end 365.841788 -272.95348)
		(width 0.1143)
		(layer "In13.Cu")
		(net "P5E_CPU0_P2_TX_DP<6>")
	)
	(segment
		(start 366.311942 -277.64867)
		(end 366.272826 -277.67153)
		(width 0.1143)
		(layer "In13.Cu")
		(net "P5E_CPU0_P2_TX_DP<6>")
	)
	(segment
		(start 365.332772 -272.120614)
		(end 365.371888 -272.143474)
		(width 0.1143)
		(layer "In13.Cu")
		(net "P5E_CPU0_P2_TX_DP<6>")
	)
	(segment
		(start 366.272826 -273.740626)
		(end 366.311942 -273.763486)
		(width 0.1143)
		(layer "In13.Cu")
		(net "P5E_CPU0_P2_TX_DP<6>")
	)
	(segment
		(start 366.311942 -282.508706)
		(end 366.272826 -282.531566)
		(width 0.1143)
		(layer "In13.Cu")
		(net "P5E_CPU0_P2_TX_DP<6>")
	)
	(segment
		(start 366.311942 -285.74873)
		(end 366.272826 -285.77159)
		(width 0.1143)
		(layer "In13.Cu")
		(net "P5E_CPU0_P2_TX_DP<6>")
	)
	(segment
		(start 366.311942 -277.00351)
		(end 366.342422 -277.02129)
		(width 0.1143)
		(layer "In13.Cu")
		(net "P5E_CPU0_P2_TX_DP<6>")
	)
	(segment
		(start 366.342422 -274.390866)
		(end 366.311942 -274.408646)
		(width 0.1143)
		(layer "In13.Cu")
		(net "P5E_CPU0_P2_TX_DP<6>")
	)
	(segment
		(start 366.311942 -285.10357)
		(end 366.342422 -285.12135)
		(width 0.1143)
		(layer "In13.Cu")
		(net "P5E_CPU0_P2_TX_DP<6>")
	)
	(segment
		(start 366.923828 -296.342562)
		(end 366.923828 -299.050202)
		(width 0.14224)
		(layer "In13.Cu")
		(net "P5E_CPU0_P2_TX_DP<6>")
	)
	(segment
		(start 366.272826 -294.800528)
		(end 366.311942 -294.823388)
		(width 0.1143)
		(layer "In13.Cu")
		(net "P5E_CPU0_P2_TX_DP<6>")
	)
	(segment
		(start 366.311942 -293.203376)
		(end 366.342422 -293.221156)
		(width 0.1143)
		(layer "In13.Cu")
		(net "P5E_CPU0_P2_TX_DP<6>")
	)
	(segment
		(start 366.782604 -295.633902)
		(end 366.813592 -295.651682)
		(width 0.1143)
		(layer "In13.Cu")
		(net "P5E_CPU0_P2_TX_DP<6>")
	)
	(segment
		(start 366.272826 -276.98065)
		(end 366.311942 -277.00351)
		(width 0.1143)
		(layer "In13.Cu")
		(net "P5E_CPU0_P2_TX_DP<6>")
	)
	(segment
		(start 366.342422 -282.490926)
		(end 366.311942 -282.508706)
		(width 0.1143)
		(layer "In13.Cu")
		(net "P5E_CPU0_P2_TX_DP<6>")
	)
	(segment
		(start 366.311942 -288.343594)
		(end 366.344454 -288.36239)
		(width 0.1143)
		(layer "In13.Cu")
		(net "P5E_CPU0_P2_TX_DP<6>")
	)
	(segment
		(start 366.742726 -295.610534)
		(end 366.781842 -295.633394)
		(width 0.1143)
		(layer "In13.Cu")
		(net "P5E_CPU0_P2_TX_DP<6>")
	)
	(segment
		(start 364.71479 -271.656048)
		(end 365.012732 -271.656048)
		(width 0.1143)
		(layer "In13.Cu")
		(net "P5E_CPU0_P2_TX_DP<6>")
	)
	(segment
		(start 366.272826 -280.220674)
		(end 366.311942 -280.243534)
		(width 0.1143)
		(layer "In13.Cu")
		(net "P5E_CPU0_P2_TX_DP<6>")
	)
	(segment
		(start 366.342422 -280.870914)
		(end 366.311942 -280.888694)
		(width 0.1143)
		(layer "In13.Cu")
		(net "P5E_CPU0_P2_TX_DP<6>")
	)
	(segment
		(start 407.44267 -376.527314)
		(end 407.44267 -377.1265)
		(width 0.14224)
		(layer "In13.Cu")
		(net "P5E_CPU0_P2_TX_DP<6>")
	)
	(segment
		(start 366.311942 -284.128718)
		(end 366.272826 -284.151578)
		(width 0.1143)
		(layer "In13.Cu")
		(net "P5E_CPU0_P2_TX_DP<6>")
	)
	(segment
		(start 366.272826 -288.320734)
		(end 366.311942 -288.343594)
		(width 0.1143)
		(layer "In13.Cu")
		(net "P5E_CPU0_P2_TX_DP<6>")
	)
	(segment
		(start 366.342422 -284.110938)
		(end 366.311942 -284.128718)
		(width 0.1143)
		(layer "In13.Cu")
		(net "P5E_CPU0_P2_TX_DP<6>")
	)
	(segment
		(start 366.272826 -281.840686)
		(end 366.311942 -281.863546)
		(width 0.1143)
		(layer "In13.Cu")
		(net "P5E_CPU0_P2_TX_DP<6>")
	)
	(segment
		(start 366.954816 -299.20692)
		(end 394.124434 -364.77194)
		(width 0.14224)
		(layer "In13.Cu")
		(net "P5E_CPU0_P2_TX_DP<6>")
	)
	(segment
		(start 366.342422 -285.73095)
		(end 366.311942 -285.74873)
		(width 0.1143)
		(layer "In13.Cu")
		(net "P5E_CPU0_P2_TX_DP<6>")
	)
	(segment
		(start 366.342422 -293.830756)
		(end 366.311942 -293.848536)
		(width 0.1143)
		(layer "In13.Cu")
		(net "P5E_CPU0_P2_TX_DP<6>")
	)
	(segment
		(start 365.841788 -272.95348)
		(end 365.84255 -272.953988)
		(width 0.1143)
		(layer "In13.Cu")
		(net "P5E_CPU0_P2_TX_DP<6>")
	)
	(segment
		(start 366.311942 -280.243534)
		(end 366.342422 -280.261314)
		(width 0.1143)
		(layer "In13.Cu")
		(net "P5E_CPU0_P2_TX_DP<6>")
	)
	(segment
		(start 366.311942 -275.383498)
		(end 366.342422 -275.401278)
		(width 0.1143)
		(layer "In13.Cu")
		(net "P5E_CPU0_P2_TX_DP<6>")
	)
	(segment
		(start 366.272826 -278.600662)
		(end 366.311942 -278.623522)
		(width 0.1143)
		(layer "In13.Cu")
		(net "P5E_CPU0_P2_TX_DP<6>")
	)
	(segment
		(start 366.342422 -288.97072)
		(end 366.311942 -288.9885)
		(width 0.1143)
		(layer "In13.Cu")
		(net "P5E_CPU0_P2_TX_DP<6>")
	)
	(segment
		(start 366.272826 -289.940492)
		(end 366.311942 -289.963352)
		(width 0.1143)
		(layer "In13.Cu")
		(net "P5E_CPU0_P2_TX_DP<6>")
	)
	(segment
		(start 366.311942 -280.888694)
		(end 366.272826 -280.911554)
		(width 0.1143)
		(layer "In13.Cu")
		(net "P5E_CPU0_P2_TX_DP<6>")
	)
	(segment
		(start 365.012732 -271.656048)
		(end 365.095536 -271.738852)
		(width 0.1143)
		(layer "In13.Cu")
		(net "P5E_CPU0_P2_TX_DP<6>")
	)
	(segment
		(start 366.923828 -296.314114)
		(end 366.923828 -296.342562)
		(width 0.1143)
		(layer "In13.Cu")
		(net "P5E_CPU0_P2_TX_DP<6>")
	)
	(segment
		(start 366.969548 -295.955974)
		(end 366.969548 -296.268394)
		(width 0.1143)
		(layer "In13.Cu")
		(net "P5E_CPU0_P2_TX_DP<6>")
	)
	(segment
		(start 366.311942 -278.623522)
		(end 366.342422 -278.641302)
		(width 0.1143)
		(layer "In13.Cu")
		(net "P5E_CPU0_P2_TX_DP<6>")
	)
	(segment
		(start 366.311942 -279.268682)
		(end 366.272826 -279.291542)
		(width 0.1143)
		(layer "In13.Cu")
		(net "P5E_CPU0_P2_TX_DP<6>")
	)
	(segment
		(start 394.124434 -364.77194)
		(end 398.466056 -371.270022)
		(width 0.14224)
		(layer "In13.Cu")
		(net "P5E_CPU0_P2_TX_DP<6>")
	)
	(segment
		(start 366.311942 -274.408646)
		(end 366.272826 -274.431506)
		(width 0.1143)
		(layer "In13.Cu")
		(net "P5E_CPU0_P2_TX_DP<6>")
	)
	(segment
		(start 366.272826 -275.360638)
		(end 366.311942 -275.383498)
		(width 0.1143)
		(layer "In13.Cu")
		(net "P5E_CPU0_P2_TX_DP<6>")
	)
	(segment
		(start 398.803368 -371.607334)
		(end 403.209506 -374.55094)
		(width 0.14224)
		(layer "In13.Cu")
		(net "P5E_CPU0_P2_TX_DP<6>")
	)
	(segment
		(start 366.272826 -285.08071)
		(end 366.311942 -285.10357)
		(width 0.1143)
		(layer "In13.Cu")
		(net "P5E_CPU0_P2_TX_DP<6>")
	)
	(segment
		(start 366.311942 -293.848536)
		(end 366.272826 -293.871396)
		(width 0.1143)
		(layer "In13.Cu")
		(net "P5E_CPU0_P2_TX_DP<6>")
	)
	(segment
		(start 366.342422 -279.250902)
		(end 366.311942 -279.268682)
		(width 0.1143)
		(layer "In13.Cu")
		(net "P5E_CPU0_P2_TX_DP<6>")
	)
	(arc
		(start 366.272826 -293.871396)
		(mid 366.029499 -294.335962)
		(end 366.272826 -294.800528)
		(width 0.1143)
		(layer "In13.Cu")
		(net "P5E_CPU0_P2_TX_DP<6>")
	)
	(arc
		(start 366.272826 -290.631372)
		(mid 366.029499 -291.095938)
		(end 366.272826 -291.560504)
		(width 0.1143)
		(layer "In13.Cu")
		(net "P5E_CPU0_P2_TX_DP<6>")
	)
	(arc
		(start 366.342422 -283.501338)
		(mid 366.499399 -283.806138)
		(end 366.342422 -284.110938)
		(width 0.1143)
		(layer "In13.Cu")
		(net "P5E_CPU0_P2_TX_DP<6>")
	)
	(arc
		(start 365.402368 -272.161254)
		(mid 365.517795 -272.29463)
		(end 365.55934 -272.466054)
		(width 0.1143)
		(layer "In13.Cu")
		(net "P5E_CPU0_P2_TX_DP<6>")
	)
	(arc
		(start 366.272826 -274.431506)
		(mid 366.029499 -274.896072)
		(end 366.272826 -275.360638)
		(width 0.1143)
		(layer "In13.Cu")
		(net "P5E_CPU0_P2_TX_DP<6>")
	)
	(arc
		(start 366.272826 -285.77159)
		(mid 366.029499 -286.236156)
		(end 366.272826 -286.700722)
		(width 0.1143)
		(layer "In13.Cu")
		(net "P5E_CPU0_P2_TX_DP<6>")
	)
	(arc
		(start 366.342422 -280.261314)
		(mid 366.499399 -280.566114)
		(end 366.342422 -280.870914)
		(width 0.1143)
		(layer "In13.Cu")
		(net "P5E_CPU0_P2_TX_DP<6>")
	)
	(arc
		(start 366.272826 -276.051518)
		(mid 366.029499 -276.516084)
		(end 366.272826 -276.98065)
		(width 0.1143)
		(layer "In13.Cu")
		(net "P5E_CPU0_P2_TX_DP<6>")
	)
	(arc
		(start 366.272826 -277.67153)
		(mid 366.029499 -278.136096)
		(end 366.272826 -278.600662)
		(width 0.1143)
		(layer "In13.Cu")
		(net "P5E_CPU0_P2_TX_DP<6>")
	)
	(arc
		(start 366.344454 -288.36239)
		(mid 366.458383 -288.495537)
		(end 366.499394 -288.66592)
		(width 0.1143)
		(layer "In13.Cu")
		(net "P5E_CPU0_P2_TX_DP<6>")
	)
	(arc
		(start 398.466056 -371.270022)
		(mid 398.618095 -371.455295)
		(end 398.803368 -371.607334)
		(width 0.14224)
		(layer "In13.Cu")
		(net "P5E_CPU0_P2_TX_DP<6>")
	)
	(arc
		(start 366.342422 -285.12135)
		(mid 366.499399 -285.42615)
		(end 366.342422 -285.73095)
		(width 0.1143)
		(layer "In13.Cu")
		(net "P5E_CPU0_P2_TX_DP<6>")
	)
	(arc
		(start 366.499394 -287.045908)
		(mid 366.457845 -287.21733)
		(end 366.342422 -287.350708)
		(width 0.1143)
		(layer "In13.Cu")
		(net "P5E_CPU0_P2_TX_DP<6>")
	)
	(arc
		(start 366.029494 -287.856168)
		(mid 366.094009 -288.118387)
		(end 366.272826 -288.320734)
		(width 0.1143)
		(layer "In13.Cu")
		(net "P5E_CPU0_P2_TX_DP<6>")
	)
	(arc
		(start 366.342422 -289.981132)
		(mid 366.499399 -290.285932)
		(end 366.342422 -290.590732)
		(width 0.1143)
		(layer "In13.Cu")
		(net "P5E_CPU0_P2_TX_DP<6>")
	)
	(arc
		(start 366.272826 -279.291542)
		(mid 366.029499 -279.756108)
		(end 366.272826 -280.220674)
		(width 0.1143)
		(layer "In13.Cu")
		(net "P5E_CPU0_P2_TX_DP<6>")
	)
	(arc
		(start 366.342422 -273.781266)
		(mid 366.499399 -274.086066)
		(end 366.342422 -274.390866)
		(width 0.1143)
		(layer "In13.Cu")
		(net "P5E_CPU0_P2_TX_DP<6>")
	)
	(arc
		(start 366.342422 -277.02129)
		(mid 366.499399 -277.32609)
		(end 366.342422 -277.63089)
		(width 0.1143)
		(layer "In13.Cu")
		(net "P5E_CPU0_P2_TX_DP<6>")
	)
	(arc
		(start 366.029494 -273.27606)
		(mid 366.094009 -273.538279)
		(end 366.272826 -273.740626)
		(width 0.1143)
		(layer "In13.Cu")
		(net "P5E_CPU0_P2_TX_DP<6>")
	)
	(arc
		(start 366.272826 -282.531566)
		(mid 366.029499 -282.996132)
		(end 366.272826 -283.460698)
		(width 0.1143)
		(layer "In13.Cu")
		(net "P5E_CPU0_P2_TX_DP<6>")
	)
	(arc
		(start 366.342422 -291.601144)
		(mid 366.499399 -291.905944)
		(end 366.342422 -292.210744)
		(width 0.1143)
		(layer "In13.Cu")
		(net "P5E_CPU0_P2_TX_DP<6>")
	)
	(arc
		(start 366.344454 -286.742378)
		(mid 366.458383 -286.875525)
		(end 366.499394 -287.045908)
		(width 0.1143)
		(layer "In13.Cu")
		(net "P5E_CPU0_P2_TX_DP<6>")
	)
	(arc
		(start 366.342422 -281.881326)
		(mid 366.499399 -282.186126)
		(end 366.342422 -282.490926)
		(width 0.1143)
		(layer "In13.Cu")
		(net "P5E_CPU0_P2_TX_DP<6>")
	)
	(arc
		(start 366.342422 -278.641302)
		(mid 366.499399 -278.946102)
		(end 366.342422 -279.250902)
		(width 0.1143)
		(layer "In13.Cu")
		(net "P5E_CPU0_P2_TX_DP<6>")
	)
	(arc
		(start 366.272826 -284.151578)
		(mid 366.029499 -284.616144)
		(end 366.272826 -285.08071)
		(width 0.1143)
		(layer "In13.Cu")
		(net "P5E_CPU0_P2_TX_DP<6>")
	)
	(arc
		(start 366.499394 -295.145968)
		(mid 366.563909 -295.408187)
		(end 366.742726 -295.610534)
		(width 0.1143)
		(layer "In13.Cu")
		(net "P5E_CPU0_P2_TX_DP<6>")
	)
	(arc
		(start 366.499394 -288.66592)
		(mid 366.457845 -288.837342)
		(end 366.342422 -288.97072)
		(width 0.1143)
		(layer "In13.Cu")
		(net "P5E_CPU0_P2_TX_DP<6>")
	)
	(arc
		(start 366.813592 -295.651682)
		(mid 366.928268 -295.785016)
		(end 366.969548 -295.955974)
		(width 0.1143)
		(layer "In13.Cu")
		(net "P5E_CPU0_P2_TX_DP<6>")
	)
	(arc
		(start 366.272826 -292.251384)
		(mid 366.029499 -292.71595)
		(end 366.272826 -293.180516)
		(width 0.1143)
		(layer "In13.Cu")
		(net "P5E_CPU0_P2_TX_DP<6>")
	)
	(arc
		(start 366.342422 -293.221156)
		(mid 366.499399 -293.525956)
		(end 366.342422 -293.830756)
		(width 0.1143)
		(layer "In13.Cu")
		(net "P5E_CPU0_P2_TX_DP<6>")
	)
	(arc
		(start 366.342422 -275.401278)
		(mid 366.499399 -275.706078)
		(end 366.342422 -276.010878)
		(width 0.1143)
		(layer "In13.Cu")
		(net "P5E_CPU0_P2_TX_DP<6>")
	)
	(arc
		(start 365.55934 -272.466054)
		(mid 365.623855 -272.728273)
		(end 365.802672 -272.93062)
		(width 0.1143)
		(layer "In13.Cu")
		(net "P5E_CPU0_P2_TX_DP<6>")
	)
	(arc
		(start 366.272826 -289.01136)
		(mid 366.029499 -289.475926)
		(end 366.272826 -289.940492)
		(width 0.1143)
		(layer "In13.Cu")
		(net "P5E_CPU0_P2_TX_DP<6>")
	)
	(arc
		(start 366.923828 -299.050202)
		(mid 366.931596 -299.13009)
		(end 366.954816 -299.20692)
		(width 0.14224)
		(layer "In13.Cu")
		(net "P5E_CPU0_P2_TX_DP<6>")
	)
	(arc
		(start 366.275366 -287.389824)
		(mid 366.094714 -287.592569)
		(end 366.029494 -287.856168)
		(width 0.1143)
		(layer "In13.Cu")
		(net "P5E_CPU0_P2_TX_DP<6>")
	)
	(arc
		(start 366.272826 -280.911554)
		(mid 366.029499 -281.37612)
		(end 366.272826 -281.840686)
		(width 0.1143)
		(layer "In13.Cu")
		(net "P5E_CPU0_P2_TX_DP<6>")
	)
	(arc
		(start 366.342422 -294.841168)
		(mid 366.457849 -294.974544)
		(end 366.499394 -295.145968)
		(width 0.1143)
		(layer "In13.Cu")
		(net "P5E_CPU0_P2_TX_DP<6>")
	)
	(arc
		(start 365.095536 -271.738852)
		(mid 365.174615 -271.954297)
		(end 365.332772 -272.120614)
		(width 0.1143)
		(layer "In13.Cu")
		(net "P5E_CPU0_P2_TX_DP<6>")
	)
	(arc
		(start 365.873538 -272.971768)
		(mid 365.988214 -273.105102)
		(end 366.029494 -273.27606)
		(width 0.1143)
		(layer "In13.Cu")
		(net "P5E_CPU0_P2_TX_DP<6>")
	)
	(segment
		(start 405.72055 -380.15164)
		(end 405.72055 -380.85522)
		(width 0.12954)
		(layer "F.Cu")
		(net "P5E_CPU0_P2_TX_DP<5>")
	)
	(segment
		(start 405.45004 -379.88113)
		(end 405.72055 -380.15164)
		(width 0.12954)
		(layer "F.Cu")
		(net "P5E_CPU0_P2_TX_DP<5>")
	)
	(segment
		(start 364.247938 -273.010122)
		(end 364.71479 -273.27606)
		(width 0.12954)
		(layer "F.Cu")
		(net "P5E_CPU0_P2_TX_DP<5>")
	)
	(segment
		(start 405.72055 -380.85522)
		(end 405.42464 -381.15113)
		(width 0.12954)
		(layer "F.Cu")
		(net "P5E_CPU0_P2_TX_DP<5>")
	)
	(segment
		(start 365.971582 -296.458894)
		(end 365.971582 -296.487342)
		(width 0.1143)
		(layer "In13.Cu")
		(net "P5E_CPU0_P2_TX_DP<5>")
	)
	(segment
		(start 365.559594 -287.045908)
		(end 365.559594 -287.05048)
		(width 0.1143)
		(layer "In13.Cu")
		(net "P5E_CPU0_P2_TX_DP<5>")
	)
	(segment
		(start 365.371888 -280.243534)
		(end 365.402368 -280.261314)
		(width 0.1143)
		(layer "In13.Cu")
		(net "P5E_CPU0_P2_TX_DP<5>")
	)
	(segment
		(start 364.71479 -273.27606)
		(end 365.012732 -273.27606)
		(width 0.1143)
		(layer "In13.Cu")
		(net "P5E_CPU0_P2_TX_DP<5>")
	)
	(segment
		(start 365.374682 -289.96513)
		(end 365.37519 -289.96513)
		(width 0.1143)
		(layer "In13.Cu")
		(net "P5E_CPU0_P2_TX_DP<5>")
	)
	(segment
		(start 365.371888 -277.64867)
		(end 365.332772 -277.67153)
		(width 0.1143)
		(layer "In13.Cu")
		(net "P5E_CPU0_P2_TX_DP<5>")
	)
	(segment
		(start 365.374682 -283.485336)
		(end 365.37519 -283.485336)
		(width 0.1143)
		(layer "In13.Cu")
		(net "P5E_CPU0_P2_TX_DP<5>")
	)
	(segment
		(start 365.371888 -285.74873)
		(end 365.370872 -285.749238)
		(width 0.1143)
		(layer "In13.Cu")
		(net "P5E_CPU0_P2_TX_DP<5>")
	)
	(segment
		(start 365.408718 -292.20668)
		(end 365.403638 -292.210236)
		(width 0.1143)
		(layer "In13.Cu")
		(net "P5E_CPU0_P2_TX_DP<5>")
	)
	(segment
		(start 365.371888 -288.9885)
		(end 365.370872 -288.989008)
		(width 0.1143)
		(layer "In13.Cu")
		(net "P5E_CPU0_P2_TX_DP<5>")
	)
	(segment
		(start 365.332772 -281.840686)
		(end 365.370872 -281.863038)
		(width 0.1143)
		(layer "In13.Cu")
		(net "P5E_CPU0_P2_TX_DP<5>")
	)
	(segment
		(start 365.371888 -273.763486)
		(end 365.402368 -273.781266)
		(width 0.1143)
		(layer "In13.Cu")
		(net "P5E_CPU0_P2_TX_DP<5>")
	)
	(segment
		(start 365.012732 -273.27606)
		(end 365.095536 -273.358864)
		(width 0.1143)
		(layer "In13.Cu")
		(net "P5E_CPU0_P2_TX_DP<5>")
	)
	(segment
		(start 365.370872 -284.129226)
		(end 365.332772 -284.151578)
		(width 0.1143)
		(layer "In13.Cu")
		(net "P5E_CPU0_P2_TX_DP<5>")
	)
	(segment
		(start 365.407448 -287.347406)
		(end 365.403638 -287.3502)
		(width 0.1143)
		(layer "In13.Cu")
		(net "P5E_CPU0_P2_TX_DP<5>")
	)
	(segment
		(start 365.37265 -283.484066)
		(end 365.374682 -283.485336)
		(width 0.1143)
		(layer "In13.Cu")
		(net "P5E_CPU0_P2_TX_DP<5>")
	)
	(segment
		(start 393.559284 -365.891064)
		(end 397.449294 -371.71249)
		(width 0.14224)
		(layer "In13.Cu")
		(net "P5E_CPU0_P2_TX_DP<5>")
	)
	(segment
		(start 366.023144 -299.44187)
		(end 393.559284 -365.891064)
		(width 0.14224)
		(layer "In13.Cu")
		(net "P5E_CPU0_P2_TX_DP<5>")
	)
	(segment
		(start 365.371888 -280.888694)
		(end 365.33328 -280.9113)
		(width 0.1143)
		(layer "In13.Cu")
		(net "P5E_CPU0_P2_TX_DP<5>")
	)
	(segment
		(start 405.74087 -377.064778)
		(end 405.74087 -379.5903)
		(width 0.14224)
		(layer "In13.Cu")
		(net "P5E_CPU0_P2_TX_DP<5>")
	)
	(segment
		(start 365.37265 -281.864054)
		(end 365.374682 -281.865324)
		(width 0.1143)
		(layer "In13.Cu")
		(net "P5E_CPU0_P2_TX_DP<5>")
	)
	(segment
		(start 365.332772 -276.98065)
		(end 365.371888 -277.00351)
		(width 0.1143)
		(layer "In13.Cu")
		(net "P5E_CPU0_P2_TX_DP<5>")
	)
	(segment
		(start 365.37265 -293.203884)
		(end 365.374682 -293.205154)
		(width 0.1143)
		(layer "In13.Cu")
		(net "P5E_CPU0_P2_TX_DP<5>")
	)
	(segment
		(start 365.371888 -292.228524)
		(end 365.370872 -292.229032)
		(width 0.1143)
		(layer "In13.Cu")
		(net "P5E_CPU0_P2_TX_DP<5>")
	)
	(segment
		(start 365.33328 -280.9113)
		(end 365.332772 -280.911554)
		(width 0.1143)
		(layer "In13.Cu")
		(net "P5E_CPU0_P2_TX_DP<5>")
	)
	(segment
		(start 365.37265 -285.104078)
		(end 365.374682 -285.105348)
		(width 0.1143)
		(layer "In13.Cu")
		(net "P5E_CPU0_P2_TX_DP<5>")
	)
	(segment
		(start 365.37265 -284.128464)
		(end 365.371888 -284.128718)
		(width 0.1143)
		(layer "In13.Cu")
		(net "P5E_CPU0_P2_TX_DP<5>")
	)
	(segment
		(start 405.74087 -379.5903)
		(end 405.45004 -379.88113)
		(width 0.14224)
		(layer "In13.Cu")
		(net "P5E_CPU0_P2_TX_DP<5>")
	)
	(segment
		(start 365.371888 -275.383498)
		(end 365.402368 -275.401278)
		(width 0.1143)
		(layer "In13.Cu")
		(net "P5E_CPU0_P2_TX_DP<5>")
	)
	(segment
		(start 365.370872 -288.989008)
		(end 365.332772 -289.01136)
		(width 0.1143)
		(layer "In13.Cu")
		(net "P5E_CPU0_P2_TX_DP<5>")
	)
	(segment
		(start 365.339122 -288.32429)
		(end 365.374936 -288.345118)
		(width 0.1143)
		(layer "In13.Cu")
		(net "P5E_CPU0_P2_TX_DP<5>")
	)
	(segment
		(start 365.370872 -285.749238)
		(end 365.332772 -285.77159)
		(width 0.1143)
		(layer "In13.Cu")
		(net "P5E_CPU0_P2_TX_DP<5>")
	)
	(segment
		(start 365.375444 -284.12694)
		(end 365.374936 -284.12694)
		(width 0.1143)
		(layer "In13.Cu")
		(net "P5E_CPU0_P2_TX_DP<5>")
	)
	(segment
		(start 365.374936 -285.746952)
		(end 365.37265 -285.748476)
		(width 0.1143)
		(layer "In13.Cu")
		(net "P5E_CPU0_P2_TX_DP<5>")
	)
	(segment
		(start 365.374936 -288.986722)
		(end 365.37265 -288.988246)
		(width 0.1143)
		(layer "In13.Cu")
		(net "P5E_CPU0_P2_TX_DP<5>")
	)
	(segment
		(start 365.371888 -274.408646)
		(end 365.332772 -274.431506)
		(width 0.1143)
		(layer "In13.Cu")
		(net "P5E_CPU0_P2_TX_DP<5>")
	)
	(segment
		(start 365.371888 -285.10357)
		(end 365.37265 -285.104078)
		(width 0.1143)
		(layer "In13.Cu")
		(net "P5E_CPU0_P2_TX_DP<5>")
	)
	(segment
		(start 365.374682 -281.865324)
		(end 365.37519 -281.865324)
		(width 0.1143)
		(layer "In13.Cu")
		(net "P5E_CPU0_P2_TX_DP<5>")
	)
	(segment
		(start 365.37265 -291.583872)
		(end 365.403638 -291.601652)
		(width 0.1143)
		(layer "In13.Cu")
		(net "P5E_CPU0_P2_TX_DP<5>")
	)
	(segment
		(start 365.402368 -276.010878)
		(end 365.371888 -276.028658)
		(width 0.1143)
		(layer "In13.Cu")
		(net "P5E_CPU0_P2_TX_DP<5>")
	)
	(segment
		(start 365.332772 -273.740626)
		(end 365.371888 -273.763486)
		(width 0.1143)
		(layer "In13.Cu")
		(net "P5E_CPU0_P2_TX_DP<5>")
	)
	(segment
		(start 405.013922 -376.320558)
		(end 405.120856 -376.391932)
		(width 0.14224)
		(layer "In13.Cu")
		(net "P5E_CPU0_P2_TX_DP<5>")
	)
	(segment
		(start 365.36884 -292.230302)
		(end 365.367316 -292.231318)
		(width 0.1143)
		(layer "In13.Cu")
		(net "P5E_CPU0_P2_TX_DP<5>")
	)
	(segment
		(start 398.191228 -372.454424)
		(end 402.282152 -375.188226)
		(width 0.14224)
		(layer "In13.Cu")
		(net "P5E_CPU0_P2_TX_DP<5>")
	)
	(segment
		(start 365.332772 -291.560504)
		(end 365.370872 -291.582856)
		(width 0.1143)
		(layer "In13.Cu")
		(net "P5E_CPU0_P2_TX_DP<5>")
	)
	(segment
		(start 365.332772 -275.360638)
		(end 365.371888 -275.383498)
		(width 0.1143)
		(layer "In13.Cu")
		(net "P5E_CPU0_P2_TX_DP<5>")
	)
	(segment
		(start 365.37265 -285.748476)
		(end 365.371888 -285.74873)
		(width 0.1143)
		(layer "In13.Cu")
		(net "P5E_CPU0_P2_TX_DP<5>")
	)
	(segment
		(start 365.332772 -283.460698)
		(end 365.33963 -283.464762)
		(width 0.1143)
		(layer "In13.Cu")
		(net "P5E_CPU0_P2_TX_DP<5>")
	)
	(segment
		(start 405.120856 -376.391932)
		(end 405.703532 -376.974608)
		(width 0.14224)
		(layer "In13.Cu")
		(net "P5E_CPU0_P2_TX_DP<5>")
	)
	(segment
		(start 365.641128 -295.449498)
		(end 365.979964 -295.78808)
		(width 0.1143)
		(layer "In13.Cu")
		(net "P5E_CPU0_P2_TX_DP<5>")
	)
	(segment
		(start 365.374936 -290.606734)
		(end 365.37265 -290.608258)
		(width 0.1143)
		(layer "In13.Cu")
		(net "P5E_CPU0_P2_TX_DP<5>")
	)
	(segment
		(start 365.371888 -279.268682)
		(end 365.332772 -279.291542)
		(width 0.1143)
		(layer "In13.Cu")
		(net "P5E_CPU0_P2_TX_DP<5>")
	)
	(segment
		(start 365.971582 -296.487342)
		(end 365.971582 -299.183044)
		(width 0.14224)
		(layer "In13.Cu")
		(net "P5E_CPU0_P2_TX_DP<5>")
	)
	(segment
		(start 365.370872 -292.229032)
		(end 365.36884 -292.230302)
		(width 0.1143)
		(layer "In13.Cu")
		(net "P5E_CPU0_P2_TX_DP<5>")
	)
	(segment
		(start 365.370872 -293.202868)
		(end 365.371888 -293.203376)
		(width 0.1143)
		(layer "In13.Cu")
		(net "P5E_CPU0_P2_TX_DP<5>")
	)
	(segment
		(start 365.37265 -290.608258)
		(end 365.371888 -290.608512)
		(width 0.1143)
		(layer "In13.Cu")
		(net "P5E_CPU0_P2_TX_DP<5>")
	)
	(segment
		(start 366.017302 -295.878504)
		(end 366.017302 -296.413174)
		(width 0.1143)
		(layer "In13.Cu")
		(net "P5E_CPU0_P2_TX_DP<5>")
	)
	(segment
		(start 365.374682 -285.105348)
		(end 365.37519 -285.105348)
		(width 0.1143)
		(layer "In13.Cu")
		(net "P5E_CPU0_P2_TX_DP<5>")
	)
	(segment
		(start 365.332772 -289.940492)
		(end 365.370872 -289.962844)
		(width 0.1143)
		(layer "In13.Cu")
		(net "P5E_CPU0_P2_TX_DP<5>")
	)
	(segment
		(start 365.371888 -284.128718)
		(end 365.370872 -284.129226)
		(width 0.1143)
		(layer "In13.Cu")
		(net "P5E_CPU0_P2_TX_DP<5>")
	)
	(segment
		(start 365.374936 -288.345118)
		(end 365.37519 -288.345118)
		(width 0.1143)
		(layer "In13.Cu")
		(net "P5E_CPU0_P2_TX_DP<5>")
	)
	(segment
		(start 365.338868 -288.32429)
		(end 365.339122 -288.32429)
		(width 0.1143)
		(layer "In13.Cu")
		(net "P5E_CPU0_P2_TX_DP<5>")
	)
	(segment
		(start 365.321088 -294.78859)
		(end 365.393478 -294.830754)
		(width 0.1143)
		(layer "In13.Cu")
		(net "P5E_CPU0_P2_TX_DP<5>")
	)
	(segment
		(start 365.371888 -290.608512)
		(end 365.370872 -290.60902)
		(width 0.1143)
		(layer "In13.Cu")
		(net "P5E_CPU0_P2_TX_DP<5>")
	)
	(segment
		(start 365.370872 -281.863038)
		(end 365.371888 -281.863546)
		(width 0.1143)
		(layer "In13.Cu")
		(net "P5E_CPU0_P2_TX_DP<5>")
	)
	(segment
		(start 365.370872 -291.582856)
		(end 365.371888 -291.583364)
		(width 0.1143)
		(layer "In13.Cu")
		(net "P5E_CPU0_P2_TX_DP<5>")
	)
	(segment
		(start 365.370872 -289.962844)
		(end 365.371888 -289.963352)
		(width 0.1143)
		(layer "In13.Cu")
		(net "P5E_CPU0_P2_TX_DP<5>")
	)
	(segment
		(start 365.332772 -285.08071)
		(end 365.370872 -285.103062)
		(width 0.1143)
		(layer "In13.Cu")
		(net "P5E_CPU0_P2_TX_DP<5>")
	)
	(segment
		(start 365.402368 -274.390866)
		(end 365.371888 -274.408646)
		(width 0.1143)
		(layer "In13.Cu")
		(net "P5E_CPU0_P2_TX_DP<5>")
	)
	(segment
		(start 365.375444 -290.606734)
		(end 365.374936 -290.606734)
		(width 0.1143)
		(layer "In13.Cu")
		(net "P5E_CPU0_P2_TX_DP<5>")
	)
	(segment
		(start 365.371888 -283.483558)
		(end 365.37265 -283.484066)
		(width 0.1143)
		(layer "In13.Cu")
		(net "P5E_CPU0_P2_TX_DP<5>")
	)
	(segment
		(start 365.332772 -280.220674)
		(end 365.371888 -280.243534)
		(width 0.1143)
		(layer "In13.Cu")
		(net "P5E_CPU0_P2_TX_DP<5>")
	)
	(segment
		(start 365.375444 -285.746952)
		(end 365.374936 -285.746952)
		(width 0.1143)
		(layer "In13.Cu")
		(net "P5E_CPU0_P2_TX_DP<5>")
	)
	(segment
		(start 365.332772 -288.320734)
		(end 365.338868 -288.32429)
		(width 0.1143)
		(layer "In13.Cu")
		(net "P5E_CPU0_P2_TX_DP<5>")
	)
	(segment
		(start 365.402368 -279.250902)
		(end 365.371888 -279.268682)
		(width 0.1143)
		(layer "In13.Cu")
		(net "P5E_CPU0_P2_TX_DP<5>")
	)
	(segment
		(start 365.375444 -288.986722)
		(end 365.374936 -288.986722)
		(width 0.1143)
		(layer "In13.Cu")
		(net "P5E_CPU0_P2_TX_DP<5>")
	)
	(segment
		(start 365.332772 -293.180516)
		(end 365.33963 -293.18458)
		(width 0.1143)
		(layer "In13.Cu")
		(net "P5E_CPU0_P2_TX_DP<5>")
	)
	(segment
		(start 365.403638 -291.601652)
		(end 365.408718 -291.605208)
		(width 0.1143)
		(layer "In13.Cu")
		(net "P5E_CPU0_P2_TX_DP<5>")
	)
	(segment
		(start 365.54791 -295.129458)
		(end 365.54791 -295.224708)
		(width 0.1143)
		(layer "In13.Cu")
		(net "P5E_CPU0_P2_TX_DP<5>")
	)
	(segment
		(start 365.371888 -282.508706)
		(end 365.370872 -282.509214)
		(width 0.1143)
		(layer "In13.Cu")
		(net "P5E_CPU0_P2_TX_DP<5>")
	)
	(segment
		(start 365.332772 -286.700722)
		(end 365.405416 -286.74314)
		(width 0.1143)
		(layer "In13.Cu")
		(net "P5E_CPU0_P2_TX_DP<5>")
	)
	(segment
		(start 365.371888 -278.623522)
		(end 365.402368 -278.641302)
		(width 0.1143)
		(layer "In13.Cu")
		(net "P5E_CPU0_P2_TX_DP<5>")
	)
	(segment
		(start 365.37265 -289.96386)
		(end 365.374682 -289.96513)
		(width 0.1143)
		(layer "In13.Cu")
		(net "P5E_CPU0_P2_TX_DP<5>")
	)
	(segment
		(start 365.340392 -283.46527)
		(end 365.371888 -283.483558)
		(width 0.1143)
		(layer "In13.Cu")
		(net "P5E_CPU0_P2_TX_DP<5>")
	)
	(segment
		(start 365.402368 -280.870914)
		(end 365.371888 -280.888694)
		(width 0.1143)
		(layer "In13.Cu")
		(net "P5E_CPU0_P2_TX_DP<5>")
	)
	(segment
		(start 365.3663 -292.231826)
		(end 365.332772 -292.251384)
		(width 0.1143)
		(layer "In13.Cu")
		(net "P5E_CPU0_P2_TX_DP<5>")
	)
	(segment
		(start 365.374936 -284.12694)
		(end 365.37265 -284.128464)
		(width 0.1143)
		(layer "In13.Cu")
		(net "P5E_CPU0_P2_TX_DP<5>")
	)
	(segment
		(start 365.403638 -287.3502)
		(end 365.335312 -287.389824)
		(width 0.1143)
		(layer "In13.Cu")
		(net "P5E_CPU0_P2_TX_DP<5>")
	)
	(segment
		(start 365.33963 -283.464762)
		(end 365.340392 -283.46527)
		(width 0.1143)
		(layer "In13.Cu")
		(net "P5E_CPU0_P2_TX_DP<5>")
	)
	(segment
		(start 365.371888 -293.203376)
		(end 365.37265 -293.203884)
		(width 0.1143)
		(layer "In13.Cu")
		(net "P5E_CPU0_P2_TX_DP<5>")
	)
	(segment
		(start 365.370618 -293.847266)
		(end 365.369348 -293.848028)
		(width 0.1143)
		(layer "In13.Cu")
		(net "P5E_CPU0_P2_TX_DP<5>")
	)
	(segment
		(start 365.340392 -293.185088)
		(end 365.370872 -293.202868)
		(width 0.1143)
		(layer "In13.Cu")
		(net "P5E_CPU0_P2_TX_DP<5>")
	)
	(segment
		(start 365.371888 -289.963352)
		(end 365.37265 -289.96386)
		(width 0.1143)
		(layer "In13.Cu")
		(net "P5E_CPU0_P2_TX_DP<5>")
	)
	(segment
		(start 365.332772 -278.600662)
		(end 365.371888 -278.623522)
		(width 0.1143)
		(layer "In13.Cu")
		(net "P5E_CPU0_P2_TX_DP<5>")
	)
	(segment
		(start 365.374936 -282.506928)
		(end 365.37265 -282.508452)
		(width 0.1143)
		(layer "In13.Cu")
		(net "P5E_CPU0_P2_TX_DP<5>")
	)
	(segment
		(start 365.369348 -293.848028)
		(end 365.35995 -293.853362)
		(width 0.1143)
		(layer "In13.Cu")
		(net "P5E_CPU0_P2_TX_DP<5>")
	)
	(segment
		(start 365.37265 -292.228016)
		(end 365.371888 -292.228524)
		(width 0.1143)
		(layer "In13.Cu")
		(net "P5E_CPU0_P2_TX_DP<5>")
	)
	(segment
		(start 365.403638 -292.210236)
		(end 365.37265 -292.228016)
		(width 0.1143)
		(layer "In13.Cu")
		(net "P5E_CPU0_P2_TX_DP<5>")
	)
	(segment
		(start 365.37265 -288.988246)
		(end 365.371888 -288.9885)
		(width 0.1143)
		(layer "In13.Cu")
		(net "P5E_CPU0_P2_TX_DP<5>")
	)
	(segment
		(start 365.367316 -292.231318)
		(end 365.3663 -292.231826)
		(width 0.1143)
		(layer "In13.Cu")
		(net "P5E_CPU0_P2_TX_DP<5>")
	)
	(segment
		(start 365.371888 -277.00351)
		(end 365.402368 -277.02129)
		(width 0.1143)
		(layer "In13.Cu")
		(net "P5E_CPU0_P2_TX_DP<5>")
	)
	(segment
		(start 365.371888 -291.583364)
		(end 365.37265 -291.583872)
		(width 0.1143)
		(layer "In13.Cu")
		(net "P5E_CPU0_P2_TX_DP<5>")
	)
	(segment
		(start 365.37265 -282.508452)
		(end 365.371888 -282.508706)
		(width 0.1143)
		(layer "In13.Cu")
		(net "P5E_CPU0_P2_TX_DP<5>")
	)
	(segment
		(start 366.017302 -296.413174)
		(end 365.971582 -296.458894)
		(width 0.1143)
		(layer "In13.Cu")
		(net "P5E_CPU0_P2_TX_DP<5>")
	)
	(segment
		(start 365.370872 -290.60902)
		(end 365.332772 -290.631372)
		(width 0.1143)
		(layer "In13.Cu")
		(net "P5E_CPU0_P2_TX_DP<5>")
	)
	(segment
		(start 402.282152 -375.188226)
		(end 405.013922 -376.320558)
		(width 0.14224)
		(layer "In13.Cu")
		(net "P5E_CPU0_P2_TX_DP<5>")
	)
	(segment
		(start 365.374682 -293.205154)
		(end 365.37519 -293.205154)
		(width 0.1143)
		(layer "In13.Cu")
		(net "P5E_CPU0_P2_TX_DP<5>")
	)
	(segment
		(start 365.402368 -277.63089)
		(end 365.371888 -277.64867)
		(width 0.1143)
		(layer "In13.Cu")
		(net "P5E_CPU0_P2_TX_DP<5>")
	)
	(segment
		(start 365.370872 -282.509214)
		(end 365.332772 -282.531566)
		(width 0.1143)
		(layer "In13.Cu")
		(net "P5E_CPU0_P2_TX_DP<5>")
	)
	(segment
		(start 365.33963 -293.18458)
		(end 365.340392 -293.185088)
		(width 0.1143)
		(layer "In13.Cu")
		(net "P5E_CPU0_P2_TX_DP<5>")
	)
	(segment
		(start 365.375444 -282.506928)
		(end 365.374936 -282.506928)
		(width 0.1143)
		(layer "In13.Cu")
		(net "P5E_CPU0_P2_TX_DP<5>")
	)
	(segment
		(start 365.371888 -281.863546)
		(end 365.37265 -281.864054)
		(width 0.1143)
		(layer "In13.Cu")
		(net "P5E_CPU0_P2_TX_DP<5>")
	)
	(segment
		(start 365.371888 -276.028658)
		(end 365.332772 -276.051518)
		(width 0.1143)
		(layer "In13.Cu")
		(net "P5E_CPU0_P2_TX_DP<5>")
	)
	(segment
		(start 365.370872 -285.103062)
		(end 365.371888 -285.10357)
		(width 0.1143)
		(layer "In13.Cu")
		(net "P5E_CPU0_P2_TX_DP<5>")
	)
	(arc
		(start 365.402368 -280.261314)
		(mid 365.559345 -280.566114)
		(end 365.402368 -280.870914)
		(width 0.1143)
		(layer "In13.Cu")
		(net "P5E_CPU0_P2_TX_DP<5>")
	)
	(arc
		(start 365.332772 -279.291542)
		(mid 365.089445 -279.756108)
		(end 365.332772 -280.220674)
		(width 0.1143)
		(layer "In13.Cu")
		(net "P5E_CPU0_P2_TX_DP<5>")
	)
	(arc
		(start 365.332772 -274.431506)
		(mid 365.089445 -274.896072)
		(end 365.332772 -275.360638)
		(width 0.1143)
		(layer "In13.Cu")
		(net "P5E_CPU0_P2_TX_DP<5>")
	)
	(arc
		(start 365.37519 -283.485336)
		(mid 365.559923 -283.806028)
		(end 365.375444 -284.12694)
		(width 0.1143)
		(layer "In13.Cu")
		(net "P5E_CPU0_P2_TX_DP<5>")
	)
	(arc
		(start 365.971582 -299.183044)
		(mid 365.984632 -299.314991)
		(end 366.023144 -299.44187)
		(width 0.14224)
		(layer "In13.Cu")
		(net "P5E_CPU0_P2_TX_DP<5>")
	)
	(arc
		(start 365.405416 -286.74314)
		(mid 365.518823 -286.876029)
		(end 365.559594 -287.045908)
		(width 0.1143)
		(layer "In13.Cu")
		(net "P5E_CPU0_P2_TX_DP<5>")
	)
	(arc
		(start 365.37519 -289.96513)
		(mid 365.559923 -290.285822)
		(end 365.375444 -290.606734)
		(width 0.1143)
		(layer "In13.Cu")
		(net "P5E_CPU0_P2_TX_DP<5>")
	)
	(arc
		(start 365.402368 -273.781266)
		(mid 365.559345 -274.086066)
		(end 365.402368 -274.390866)
		(width 0.1143)
		(layer "In13.Cu")
		(net "P5E_CPU0_P2_TX_DP<5>")
	)
	(arc
		(start 365.332772 -276.051518)
		(mid 365.089445 -276.516084)
		(end 365.332772 -276.98065)
		(width 0.1143)
		(layer "In13.Cu")
		(net "P5E_CPU0_P2_TX_DP<5>")
	)
	(arc
		(start 365.095536 -273.358864)
		(mid 365.097324 -273.370313)
		(end 365.099346 -273.381724)
		(width 0.1143)
		(layer "In13.Cu")
		(net "P5E_CPU0_P2_TX_DP<5>")
	)
	(arc
		(start 365.332772 -290.631372)
		(mid 365.089445 -291.095938)
		(end 365.332772 -291.560504)
		(width 0.1143)
		(layer "In13.Cu")
		(net "P5E_CPU0_P2_TX_DP<5>")
	)
	(arc
		(start 365.402368 -275.401278)
		(mid 365.559345 -275.706078)
		(end 365.402368 -276.010878)
		(width 0.1143)
		(layer "In13.Cu")
		(net "P5E_CPU0_P2_TX_DP<5>")
	)
	(arc
		(start 365.332772 -277.67153)
		(mid 365.089445 -278.136096)
		(end 365.332772 -278.600662)
		(width 0.1143)
		(layer "In13.Cu")
		(net "P5E_CPU0_P2_TX_DP<5>")
	)
	(arc
		(start 365.332772 -284.151578)
		(mid 365.089445 -284.616144)
		(end 365.332772 -285.08071)
		(width 0.1143)
		(layer "In13.Cu")
		(net "P5E_CPU0_P2_TX_DP<5>")
	)
	(arc
		(start 365.37519 -293.205154)
		(mid 365.558155 -293.527555)
		(end 365.370618 -293.847266)
		(width 0.1143)
		(layer "In13.Cu")
		(net "P5E_CPU0_P2_TX_DP<5>")
	)
	(arc
		(start 365.332772 -285.77159)
		(mid 365.089445 -286.236156)
		(end 365.332772 -286.700722)
		(width 0.1143)
		(layer "In13.Cu")
		(net "P5E_CPU0_P2_TX_DP<5>")
	)
	(arc
		(start 365.408718 -291.605208)
		(mid 365.562816 -291.905944)
		(end 365.408718 -292.20668)
		(width 0.1143)
		(layer "In13.Cu")
		(net "P5E_CPU0_P2_TX_DP<5>")
	)
	(arc
		(start 365.332772 -280.911554)
		(mid 365.089445 -281.37612)
		(end 365.332772 -281.840686)
		(width 0.1143)
		(layer "In13.Cu")
		(net "P5E_CPU0_P2_TX_DP<5>")
	)
	(arc
		(start 365.37519 -281.865324)
		(mid 365.559923 -282.186016)
		(end 365.375444 -282.506928)
		(width 0.1143)
		(layer "In13.Cu")
		(net "P5E_CPU0_P2_TX_DP<5>")
	)
	(arc
		(start 365.402368 -277.02129)
		(mid 365.559345 -277.32609)
		(end 365.402368 -277.63089)
		(width 0.1143)
		(layer "In13.Cu")
		(net "P5E_CPU0_P2_TX_DP<5>")
	)
	(arc
		(start 365.559594 -287.05048)
		(mid 365.519339 -287.217293)
		(end 365.407448 -287.347406)
		(width 0.1143)
		(layer "In13.Cu")
		(net "P5E_CPU0_P2_TX_DP<5>")
	)
	(arc
		(start 365.332772 -292.251384)
		(mid 365.089445 -292.71595)
		(end 365.332772 -293.180516)
		(width 0.1143)
		(layer "In13.Cu")
		(net "P5E_CPU0_P2_TX_DP<5>")
	)
	(arc
		(start 365.35995 -293.853362)
		(mid 365.083204 -294.310233)
		(end 365.321088 -294.78859)
		(width 0.1143)
		(layer "In13.Cu")
		(net "P5E_CPU0_P2_TX_DP<5>")
	)
	(arc
		(start 365.37519 -285.105348)
		(mid 365.559923 -285.42604)
		(end 365.375444 -285.746952)
		(width 0.1143)
		(layer "In13.Cu")
		(net "P5E_CPU0_P2_TX_DP<5>")
	)
	(arc
		(start 365.099346 -273.381724)
		(mid 365.180779 -273.584122)
		(end 365.332772 -273.740626)
		(width 0.1143)
		(layer "In13.Cu")
		(net "P5E_CPU0_P2_TX_DP<5>")
	)
	(arc
		(start 365.402368 -278.641302)
		(mid 365.559345 -278.946102)
		(end 365.402368 -279.250902)
		(width 0.1143)
		(layer "In13.Cu")
		(net "P5E_CPU0_P2_TX_DP<5>")
	)
	(arc
		(start 365.37519 -288.345118)
		(mid 365.559923 -288.66581)
		(end 365.375444 -288.986722)
		(width 0.1143)
		(layer "In13.Cu")
		(net "P5E_CPU0_P2_TX_DP<5>")
	)
	(arc
		(start 365.335312 -287.389824)
		(mid 365.15466 -287.592569)
		(end 365.08944 -287.856168)
		(width 0.1143)
		(layer "In13.Cu")
		(net "P5E_CPU0_P2_TX_DP<5>")
	)
	(arc
		(start 365.393478 -294.830754)
		(mid 365.506966 -294.961343)
		(end 365.54791 -295.129458)
		(width 0.1143)
		(layer "In13.Cu")
		(net "P5E_CPU0_P2_TX_DP<5>")
	)
	(arc
		(start 405.703532 -376.974608)
		(mid 405.731175 -377.015978)
		(end 405.74087 -377.064778)
		(width 0.14224)
		(layer "In13.Cu")
		(net "P5E_CPU0_P2_TX_DP<5>")
	)
	(arc
		(start 365.979964 -295.78808)
		(mid 366.007602 -295.829582)
		(end 366.017302 -295.878504)
		(width 0.1143)
		(layer "In13.Cu")
		(net "P5E_CPU0_P2_TX_DP<5>")
	)
	(arc
		(start 365.332772 -282.531566)
		(mid 365.089445 -282.996132)
		(end 365.332772 -283.460698)
		(width 0.1143)
		(layer "In13.Cu")
		(net "P5E_CPU0_P2_TX_DP<5>")
	)
	(arc
		(start 365.08944 -287.856168)
		(mid 365.153955 -288.118387)
		(end 365.332772 -288.320734)
		(width 0.1143)
		(layer "In13.Cu")
		(net "P5E_CPU0_P2_TX_DP<5>")
	)
	(arc
		(start 365.54791 -295.224708)
		(mid 365.572132 -295.34639)
		(end 365.641128 -295.449498)
		(width 0.1143)
		(layer "In13.Cu")
		(net "P5E_CPU0_P2_TX_DP<5>")
	)
	(arc
		(start 365.332772 -289.01136)
		(mid 365.089445 -289.475926)
		(end 365.332772 -289.940492)
		(width 0.1143)
		(layer "In13.Cu")
		(net "P5E_CPU0_P2_TX_DP<5>")
	)
	(arc
		(start 397.449294 -371.71249)
		(mid 397.783729 -372.119989)
		(end 398.191228 -372.454424)
		(width 0.14224)
		(layer "In13.Cu")
		(net "P5E_CPU0_P2_TX_DP<5>")
	)
	(segment
		(start 403.74824 -382.34493)
		(end 404.01875 -382.61544)
		(width 0.12954)
		(layer "F.Cu")
		(net "P5E_CPU0_P2_TX_DP<4>")
	)
	(segment
		(start 364.247938 -269.770098)
		(end 364.71479 -270.036036)
		(width 0.12954)
		(layer "F.Cu")
		(net "P5E_CPU0_P2_TX_DP<4>")
	)
	(segment
		(start 404.01875 -383.31902)
		(end 403.72284 -383.61493)
		(width 0.12954)
		(layer "F.Cu")
		(net "P5E_CPU0_P2_TX_DP<4>")
	)
	(segment
		(start 404.01875 -382.61544)
		(end 404.01875 -383.31902)
		(width 0.12954)
		(layer "F.Cu")
		(net "P5E_CPU0_P2_TX_DP<4>")
	)
	(segment
		(start 364.431834 -276.028658)
		(end 364.429294 -276.030182)
		(width 0.1143)
		(layer "In13.Cu")
		(net "P5E_CPU0_P2_TX_DP<4>")
	)
	(segment
		(start 364.463584 -280.870406)
		(end 364.395512 -280.909522)
		(width 0.1143)
		(layer "In13.Cu")
		(net "P5E_CPU0_P2_TX_DP<4>")
	)
	(segment
		(start 364.432596 -279.268174)
		(end 364.431834 -279.268682)
		(width 0.1143)
		(layer "In13.Cu")
		(net "P5E_CPU0_P2_TX_DP<4>")
	)
	(segment
		(start 364.400338 -291.565076)
		(end 364.431834 -291.583364)
		(width 0.1143)
		(layer "In13.Cu")
		(net "P5E_CPU0_P2_TX_DP<4>")
	)
	(segment
		(start 364.432342 -290.608512)
		(end 364.431834 -290.608766)
		(width 0.1143)
		(layer "In13.Cu")
		(net "P5E_CPU0_P2_TX_DP<4>")
	)
	(segment
		(start 364.429294 -277.650194)
		(end 364.392718 -277.67153)
		(width 0.1143)
		(layer "In13.Cu")
		(net "P5E_CPU0_P2_TX_DP<4>")
	)
	(segment
		(start 396.837916 -372.495572)
		(end 398.883632 -374.541288)
		(width 0.14224)
		(layer "In13.Cu")
		(net "P5E_CPU0_P2_TX_DP<4>")
	)
	(segment
		(start 364.431834 -290.608766)
		(end 364.431834 -290.608512)
		(width 0.1143)
		(layer "In13.Cu")
		(net "P5E_CPU0_P2_TX_DP<4>")
	)
	(segment
		(start 364.431834 -277.00351)
		(end 364.432596 -277.004018)
		(width 0.1143)
		(layer "In13.Cu")
		(net "P5E_CPU0_P2_TX_DP<4>")
	)
	(segment
		(start 364.431834 -279.268682)
		(end 364.429294 -279.270206)
		(width 0.1143)
		(layer "In13.Cu")
		(net "P5E_CPU0_P2_TX_DP<4>")
	)
	(segment
		(start 364.428278 -285.101538)
		(end 364.430056 -285.102554)
		(width 0.1143)
		(layer "In13.Cu")
		(net "P5E_CPU0_P2_TX_DP<4>")
	)
	(segment
		(start 365.080042 -296.434256)
		(end 365.034322 -296.479976)
		(width 0.1143)
		(layer "In13.Cu")
		(net "P5E_CPU0_P2_TX_DP<4>")
	)
	(segment
		(start 364.432596 -278.62403)
		(end 364.463584 -278.64181)
		(width 0.1143)
		(layer "In13.Cu")
		(net "P5E_CPU0_P2_TX_DP<4>")
	)
	(segment
		(start 364.431834 -288.9885)
		(end 364.429294 -288.990024)
		(width 0.1143)
		(layer "In13.Cu")
		(net "P5E_CPU0_P2_TX_DP<4>")
	)
	(segment
		(start 364.429294 -279.270206)
		(end 364.392718 -279.291542)
		(width 0.1143)
		(layer "In13.Cu")
		(net "P5E_CPU0_P2_TX_DP<4>")
	)
	(segment
		(start 364.450122 -283.494226)
		(end 364.450376 -283.494226)
		(width 0.1143)
		(layer "In13.Cu")
		(net "P5E_CPU0_P2_TX_DP<4>")
	)
	(segment
		(start 364.399576 -291.564568)
		(end 364.400338 -291.565076)
		(width 0.1143)
		(layer "In13.Cu")
		(net "P5E_CPU0_P2_TX_DP<4>")
	)
	(segment
		(start 364.410752 -283.471366)
		(end 364.426754 -283.48051)
		(width 0.1143)
		(layer "In13.Cu")
		(net "P5E_CPU0_P2_TX_DP<4>")
	)
	(segment
		(start 364.446058 -284.12059)
		(end 364.445296 -284.121098)
		(width 0.1143)
		(layer "In13.Cu")
		(net "P5E_CPU0_P2_TX_DP<4>")
	)
	(segment
		(start 364.433104 -283.48432)
		(end 364.448598 -283.49321)
		(width 0.1143)
		(layer "In13.Cu")
		(net "P5E_CPU0_P2_TX_DP<4>")
	)
	(segment
		(start 364.463584 -280.261822)
		(end 364.483396 -280.276046)
		(width 0.1143)
		(layer "In13.Cu")
		(net "P5E_CPU0_P2_TX_DP<4>")
	)
	(segment
		(start 364.399576 -276.984714)
		(end 364.400338 -276.985222)
		(width 0.1143)
		(layer "In13.Cu")
		(net "P5E_CPU0_P2_TX_DP<4>")
	)
	(segment
		(start 364.391194 -288.319464)
		(end 364.427008 -288.340292)
		(width 0.1143)
		(layer "In13.Cu")
		(net "P5E_CPU0_P2_TX_DP<4>")
	)
	(segment
		(start 364.431834 -293.203376)
		(end 364.431834 -293.203122)
		(width 0.1143)
		(layer "In13.Cu")
		(net "P5E_CPU0_P2_TX_DP<4>")
	)
	(segment
		(start 364.432596 -271.168114)
		(end 364.431834 -271.168622)
		(width 0.1143)
		(layer "In13.Cu")
		(net "P5E_CPU0_P2_TX_DP<4>")
	)
	(segment
		(start 364.430818 -285.103062)
		(end 364.432596 -285.104078)
		(width 0.1143)
		(layer "In13.Cu")
		(net "P5E_CPU0_P2_TX_DP<4>")
	)
	(segment
		(start 364.463584 -285.730442)
		(end 364.432596 -285.748222)
		(width 0.1143)
		(layer "In13.Cu")
		(net "P5E_CPU0_P2_TX_DP<4>")
	)
	(segment
		(start 364.434374 -284.127448)
		(end 364.430818 -284.129226)
		(width 0.1143)
		(layer "In13.Cu")
		(net "P5E_CPU0_P2_TX_DP<4>")
	)
	(segment
		(start 364.432596 -282.508198)
		(end 364.425738 -282.512262)
		(width 0.1143)
		(layer "In13.Cu")
		(net "P5E_CPU0_P2_TX_DP<4>")
	)
	(segment
		(start 364.429294 -272.790158)
		(end 364.392718 -272.811494)
		(width 0.1143)
		(layer "In13.Cu")
		(net "P5E_CPU0_P2_TX_DP<4>")
	)
	(segment
		(start 364.392718 -278.600662)
		(end 364.430818 -278.623014)
		(width 0.1143)
		(layer "In13.Cu")
		(net "P5E_CPU0_P2_TX_DP<4>")
	)
	(segment
		(start 364.429294 -285.750254)
		(end 364.392718 -285.77159)
		(width 0.1143)
		(layer "In13.Cu")
		(net "P5E_CPU0_P2_TX_DP<4>")
	)
	(segment
		(start 364.392718 -281.840686)
		(end 364.399576 -281.84475)
		(width 0.1143)
		(layer "In13.Cu")
		(net "P5E_CPU0_P2_TX_DP<4>")
	)
	(segment
		(start 364.463584 -276.01037)
		(end 364.432596 -276.02815)
		(width 0.1143)
		(layer "In13.Cu")
		(net "P5E_CPU0_P2_TX_DP<4>")
	)
	(segment
		(start 400.940524 -375.524522)
		(end 401.09394 -375.627138)
		(width 0.14224)
		(layer "In13.Cu")
		(net "P5E_CPU0_P2_TX_DP<4>")
	)
	(segment
		(start 364.924848 -295.6433)
		(end 365.042704 -295.761156)
		(width 0.1143)
		(layer "In13.Cu")
		(net "P5E_CPU0_P2_TX_DP<4>")
	)
	(segment
		(start 364.432596 -282.508452)
		(end 364.432596 -282.508198)
		(width 0.1143)
		(layer "In13.Cu")
		(net "P5E_CPU0_P2_TX_DP<4>")
	)
	(segment
		(start 364.431834 -271.168622)
		(end 364.392718 -271.191482)
		(width 0.1143)
		(layer "In13.Cu")
		(net "P5E_CPU0_P2_TX_DP<4>")
	)
	(segment
		(start 364.430818 -278.623014)
		(end 364.432596 -278.62403)
		(width 0.1143)
		(layer "In13.Cu")
		(net "P5E_CPU0_P2_TX_DP<4>")
	)
	(segment
		(start 364.431834 -272.788634)
		(end 364.429294 -272.790158)
		(width 0.1143)
		(layer "In13.Cu")
		(net "P5E_CPU0_P2_TX_DP<4>")
	)
	(segment
		(start 364.430056 -285.102554)
		(end 364.430818 -285.103062)
		(width 0.1143)
		(layer "In13.Cu")
		(net "P5E_CPU0_P2_TX_DP<4>")
	)
	(segment
		(start 364.448598 -283.49321)
		(end 364.450122 -283.494226)
		(width 0.1143)
		(layer "In13.Cu")
		(net "P5E_CPU0_P2_TX_DP<4>")
	)
	(segment
		(start 364.44936 -284.118558)
		(end 364.446058 -284.12059)
		(width 0.1143)
		(layer "In13.Cu")
		(net "P5E_CPU0_P2_TX_DP<4>")
	)
	(segment
		(start 364.619286 -287.038288)
		(end 364.617254 -287.059878)
		(width 0.1143)
		(layer "In13.Cu")
		(net "P5E_CPU0_P2_TX_DP<4>")
	)
	(segment
		(start 364.429294 -288.990024)
		(end 364.392718 -289.01136)
		(width 0.1143)
		(layer "In13.Cu")
		(net "P5E_CPU0_P2_TX_DP<4>")
	)
	(segment
		(start 364.429294 -292.230048)
		(end 364.392718 -292.251384)
		(width 0.1143)
		(layer "In13.Cu")
		(net "P5E_CPU0_P2_TX_DP<4>")
	)
	(segment
		(start 364.429294 -276.030182)
		(end 364.392718 -276.051518)
		(width 0.1143)
		(layer "In13.Cu")
		(net "P5E_CPU0_P2_TX_DP<4>")
	)
	(segment
		(start 364.463584 -277.630382)
		(end 364.429294 -277.650194)
		(width 0.1143)
		(layer "In13.Cu")
		(net "P5E_CPU0_P2_TX_DP<4>")
	)
	(segment
		(start 364.392718 -280.220674)
		(end 364.399576 -280.224738)
		(width 0.1143)
		(layer "In13.Cu")
		(net "P5E_CPU0_P2_TX_DP<4>")
	)
	(segment
		(start 365.068866 -299.714412)
		(end 392.724894 -366.45469)
		(width 0.14224)
		(layer "In13.Cu")
		(net "P5E_CPU0_P2_TX_DP<4>")
	)
	(segment
		(start 364.432596 -280.244042)
		(end 364.463584 -280.261822)
		(width 0.1143)
		(layer "In13.Cu")
		(net "P5E_CPU0_P2_TX_DP<4>")
	)
	(segment
		(start 364.483396 -280.856182)
		(end 364.463584 -280.870406)
		(width 0.1143)
		(layer "In13.Cu")
		(net "P5E_CPU0_P2_TX_DP<4>")
	)
	(segment
		(start 364.429294 -290.610036)
		(end 364.392718 -290.631372)
		(width 0.1143)
		(layer "In13.Cu")
		(net "P5E_CPU0_P2_TX_DP<4>")
	)
	(segment
		(start 364.399576 -293.18458)
		(end 364.400338 -293.185088)
		(width 0.1143)
		(layer "In13.Cu")
		(net "P5E_CPU0_P2_TX_DP<4>")
	)
	(segment
		(start 402.450808 -378.134118)
		(end 402.835618 -378.518674)
		(width 0.14224)
		(layer "In13.Cu")
		(net "P5E_CPU0_P2_TX_DP<4>")
	)
	(segment
		(start 364.71479 -270.036036)
		(end 365.012732 -270.036036)
		(width 0.1143)
		(layer "In13.Cu")
		(net "P5E_CPU0_P2_TX_DP<4>")
	)
	(segment
		(start 364.432342 -293.848536)
		(end 364.431834 -293.84879)
		(width 0.1143)
		(layer "In13.Cu")
		(net "P5E_CPU0_P2_TX_DP<4>")
	)
	(segment
		(start 364.463584 -272.770346)
		(end 364.432596 -272.788126)
		(width 0.1143)
		(layer "In13.Cu")
		(net "P5E_CPU0_P2_TX_DP<4>")
	)
	(segment
		(start 364.431834 -288.34334)
		(end 364.43285 -288.343848)
		(width 0.1143)
		(layer "In13.Cu")
		(net "P5E_CPU0_P2_TX_DP<4>")
	)
	(segment
		(start 364.431834 -291.58311)
		(end 364.432342 -291.583364)
		(width 0.1143)
		(layer "In13.Cu")
		(net "P5E_CPU0_P2_TX_DP<4>")
	)
	(segment
		(start 403.424644 -378.832364)
		(end 403.684486 -378.955808)
		(width 0.14224)
		(layer "In13.Cu")
		(net "P5E_CPU0_P2_TX_DP<4>")
	)
	(segment
		(start 364.432596 -281.864054)
		(end 364.434628 -281.865324)
		(width 0.1143)
		(layer "In13.Cu")
		(net "P5E_CPU0_P2_TX_DP<4>")
	)
	(segment
		(start 364.431834 -289.963352)
		(end 364.431834 -289.963098)
		(width 0.1143)
		(layer "In13.Cu")
		(net "P5E_CPU0_P2_TX_DP<4>")
	)
	(segment
		(start 364.392718 -272.120614)
		(end 364.463584 -272.161762)
		(width 0.1143)
		(layer "In13.Cu")
		(net "P5E_CPU0_P2_TX_DP<4>")
	)
	(segment
		(start 364.434628 -281.865324)
		(end 364.435136 -281.865324)
		(width 0.1143)
		(layer "In13.Cu")
		(net "P5E_CPU0_P2_TX_DP<4>")
	)
	(segment
		(start 396.426436 -371.994176)
		(end 396.837916 -372.495572)
		(width 0.14224)
		(layer "In13.Cu")
		(net "P5E_CPU0_P2_TX_DP<4>")
	)
	(segment
		(start 364.431834 -292.228778)
		(end 364.431834 -292.228524)
		(width 0.1143)
		(layer "In13.Cu")
		(net "P5E_CPU0_P2_TX_DP<4>")
	)
	(segment
		(start 364.483396 -277.616158)
		(end 364.463584 -277.630382)
		(width 0.1143)
		(layer "In13.Cu")
		(net "P5E_CPU0_P2_TX_DP<4>")
	)
	(segment
		(start 365.034322 -296.479976)
		(end 365.034322 -296.508424)
		(width 0.1143)
		(layer "In13.Cu")
		(net "P5E_CPU0_P2_TX_DP<4>")
	)
	(segment
		(start 364.432596 -285.104078)
		(end 364.463584 -285.121858)
		(width 0.1143)
		(layer "In13.Cu")
		(net "P5E_CPU0_P2_TX_DP<4>")
	)
	(segment
		(start 364.431834 -290.608512)
		(end 364.429294 -290.610036)
		(width 0.1143)
		(layer "In13.Cu")
		(net "P5E_CPU0_P2_TX_DP<4>")
	)
	(segment
		(start 403.787356 -379.028452)
		(end 403.900386 -379.141482)
		(width 0.14224)
		(layer "In13.Cu")
		(net "P5E_CPU0_P2_TX_DP<4>")
	)
	(segment
		(start 364.392718 -291.560504)
		(end 364.399576 -291.564568)
		(width 0.1143)
		(layer "In13.Cu")
		(net "P5E_CPU0_P2_TX_DP<4>")
	)
	(segment
		(start 364.400338 -281.845258)
		(end 364.431834 -281.863546)
		(width 0.1143)
		(layer "In13.Cu")
		(net "P5E_CPU0_P2_TX_DP<4>")
	)
	(segment
		(start 364.392718 -286.700722)
		(end 364.461044 -286.740092)
		(width 0.1143)
		(layer "In13.Cu")
		(net "P5E_CPU0_P2_TX_DP<4>")
	)
	(segment
		(start 364.45063 -284.11805)
		(end 364.450122 -284.11805)
		(width 0.1143)
		(layer "In13.Cu")
		(net "P5E_CPU0_P2_TX_DP<4>")
	)
	(segment
		(start 364.463584 -277.021798)
		(end 364.483396 -277.036022)
		(width 0.1143)
		(layer "In13.Cu")
		(net "P5E_CPU0_P2_TX_DP<4>")
	)
	(segment
		(start 364.432596 -285.748222)
		(end 364.431834 -285.74873)
		(width 0.1143)
		(layer "In13.Cu")
		(net "P5E_CPU0_P2_TX_DP<4>")
	)
	(segment
		(start 364.431834 -289.963098)
		(end 364.432342 -289.963352)
		(width 0.1143)
		(layer "In13.Cu")
		(net "P5E_CPU0_P2_TX_DP<4>")
	)
	(segment
		(start 364.432596 -276.02815)
		(end 364.431834 -276.028658)
		(width 0.1143)
		(layer "In13.Cu")
		(net "P5E_CPU0_P2_TX_DP<4>")
	)
	(segment
		(start 364.425738 -294.819832)
		(end 364.442248 -294.836342)
		(width 0.1143)
		(layer "In13.Cu")
		(net "P5E_CPU0_P2_TX_DP<4>")
	)
	(segment
		(start 364.42777 -288.3408)
		(end 364.431834 -288.34334)
		(width 0.1143)
		(layer "In13.Cu")
		(net "P5E_CPU0_P2_TX_DP<4>")
	)
	(segment
		(start 401.09394 -375.627138)
		(end 402.286216 -376.819414)
		(width 0.14224)
		(layer "In13.Cu")
		(net "P5E_CPU0_P2_TX_DP<4>")
	)
	(segment
		(start 364.431834 -292.228524)
		(end 364.429294 -292.230048)
		(width 0.1143)
		(layer "In13.Cu")
		(net "P5E_CPU0_P2_TX_DP<4>")
	)
	(segment
		(start 392.724894 -366.45469)
		(end 396.426436 -371.994176)
		(width 0.14224)
		(layer "In13.Cu")
		(net "P5E_CPU0_P2_TX_DP<4>")
	)
	(segment
		(start 404.03907 -379.476254)
		(end 404.03907 -382.0541)
		(width 0.14224)
		(layer "In13.Cu")
		(net "P5E_CPU0_P2_TX_DP<4>")
	)
	(segment
		(start 364.431834 -285.74873)
		(end 364.429294 -285.750254)
		(width 0.1143)
		(layer "In13.Cu")
		(net "P5E_CPU0_P2_TX_DP<4>")
	)
	(segment
		(start 364.463584 -274.390358)
		(end 364.432596 -274.408138)
		(width 0.1143)
		(layer "In13.Cu")
		(net "P5E_CPU0_P2_TX_DP<4>")
	)
	(segment
		(start 364.426754 -283.48051)
		(end 364.428786 -283.48178)
		(width 0.1143)
		(layer "In13.Cu")
		(net "P5E_CPU0_P2_TX_DP<4>")
	)
	(segment
		(start 364.433104 -288.987992)
		(end 364.431834 -288.9885)
		(width 0.1143)
		(layer "In13.Cu")
		(net "P5E_CPU0_P2_TX_DP<4>")
	)
	(segment
		(start 364.432596 -277.004018)
		(end 364.463584 -277.021798)
		(width 0.1143)
		(layer "In13.Cu")
		(net "P5E_CPU0_P2_TX_DP<4>")
	)
	(segment
		(start 364.399576 -280.224738)
		(end 364.400338 -280.225246)
		(width 0.1143)
		(layer "In13.Cu")
		(net "P5E_CPU0_P2_TX_DP<4>")
	)
	(segment
		(start 399.399506 -374.88622)
		(end 400.940524 -375.524522)
		(width 0.14224)
		(layer "In13.Cu")
		(net "P5E_CPU0_P2_TX_DP<4>")
	)
	(segment
		(start 364.470696 -287.34512)
		(end 364.38967 -287.394904)
		(width 0.1143)
		(layer "In13.Cu")
		(net "P5E_CPU0_P2_TX_DP<4>")
	)
	(segment
		(start 364.400338 -276.985222)
		(end 364.431834 -277.00351)
		(width 0.1143)
		(layer "In13.Cu")
		(net "P5E_CPU0_P2_TX_DP<4>")
	)
	(segment
		(start 364.43539 -282.506928)
		(end 364.434882 -282.506928)
		(width 0.1143)
		(layer "In13.Cu")
		(net "P5E_CPU0_P2_TX_DP<4>")
	)
	(segment
		(start 364.392718 -289.940492)
		(end 364.399576 -289.944556)
		(width 0.1143)
		(layer "In13.Cu")
		(net "P5E_CPU0_P2_TX_DP<4>")
	)
	(segment
		(start 364.399576 -289.944556)
		(end 364.400338 -289.945064)
		(width 0.1143)
		(layer "In13.Cu")
		(net "P5E_CPU0_P2_TX_DP<4>")
	)
	(segment
		(start 364.431834 -293.203122)
		(end 364.432342 -293.203376)
		(width 0.1143)
		(layer "In13.Cu")
		(net "P5E_CPU0_P2_TX_DP<4>")
	)
	(segment
		(start 364.8964 -295.62679)
		(end 364.924848 -295.6433)
		(width 0.1143)
		(layer "In13.Cu")
		(net "P5E_CPU0_P2_TX_DP<4>")
	)
	(segment
		(start 364.450122 -284.11805)
		(end 364.44936 -284.118558)
		(width 0.1143)
		(layer "In13.Cu")
		(net "P5E_CPU0_P2_TX_DP<4>")
	)
	(segment
		(start 364.395512 -280.909522)
		(end 364.392718 -280.911554)
		(width 0.1143)
		(layer "In13.Cu")
		(net "P5E_CPU0_P2_TX_DP<4>")
	)
	(segment
		(start 364.431834 -274.408646)
		(end 364.429294 -274.41017)
		(width 0.1143)
		(layer "In13.Cu")
		(net "P5E_CPU0_P2_TX_DP<4>")
	)
	(segment
		(start 402.33092 -376.927364)
		(end 402.33092 -377.844558)
		(width 0.14224)
		(layer "In13.Cu")
		(net "P5E_CPU0_P2_TX_DP<4>")
	)
	(segment
		(start 364.400338 -289.945064)
		(end 364.431834 -289.963352)
		(width 0.1143)
		(layer "In13.Cu")
		(net "P5E_CPU0_P2_TX_DP<4>")
	)
	(segment
		(start 364.431834 -291.583364)
		(end 364.431834 -291.58311)
		(width 0.1143)
		(layer "In13.Cu")
		(net "P5E_CPU0_P2_TX_DP<4>")
	)
	(segment
		(start 364.429294 -274.41017)
		(end 364.392718 -274.431506)
		(width 0.1143)
		(layer "In13.Cu")
		(net "P5E_CPU0_P2_TX_DP<4>")
	)
	(segment
		(start 364.399576 -281.84475)
		(end 364.400338 -281.845258)
		(width 0.1143)
		(layer "In13.Cu")
		(net "P5E_CPU0_P2_TX_DP<4>")
	)
	(segment
		(start 365.080042 -295.851072)
		(end 365.080042 -296.434256)
		(width 0.1143)
		(layer "In13.Cu")
		(net "P5E_CPU0_P2_TX_DP<4>")
	)
	(segment
		(start 364.432342 -292.228524)
		(end 364.431834 -292.228778)
		(width 0.1143)
		(layer "In13.Cu")
		(net "P5E_CPU0_P2_TX_DP<4>")
	)
	(segment
		(start 364.933484 -270.340328)
		(end 364.89132 -270.364712)
		(width 0.1143)
		(layer "In13.Cu")
		(net "P5E_CPU0_P2_TX_DP<4>")
	)
	(segment
		(start 364.431834 -293.848536)
		(end 364.428024 -293.850822)
		(width 0.1143)
		(layer "In13.Cu")
		(net "P5E_CPU0_P2_TX_DP<4>")
	)
	(segment
		(start 364.431834 -281.863546)
		(end 364.432596 -281.864054)
		(width 0.1143)
		(layer "In13.Cu")
		(net "P5E_CPU0_P2_TX_DP<4>")
	)
	(segment
		(start 364.434882 -282.506928)
		(end 364.432596 -282.508452)
		(width 0.1143)
		(layer "In13.Cu")
		(net "P5E_CPU0_P2_TX_DP<4>")
	)
	(segment
		(start 364.400338 -280.225246)
		(end 364.431834 -280.243534)
		(width 0.1143)
		(layer "In13.Cu")
		(net "P5E_CPU0_P2_TX_DP<4>")
	)
	(segment
		(start 364.392718 -273.740626)
		(end 364.463584 -273.781774)
		(width 0.1143)
		(layer "In13.Cu")
		(net "P5E_CPU0_P2_TX_DP<4>")
	)
	(segment
		(start 364.609888 -270.853662)
		(end 364.609888 -270.862044)
		(width 0.1143)
		(layer "In13.Cu")
		(net "P5E_CPU0_P2_TX_DP<4>")
	)
	(segment
		(start 364.463584 -279.250394)
		(end 364.432596 -279.268174)
		(width 0.1143)
		(layer "In13.Cu")
		(net "P5E_CPU0_P2_TX_DP<4>")
	)
	(segment
		(start 364.400338 -293.185088)
		(end 364.431834 -293.203376)
		(width 0.1143)
		(layer "In13.Cu")
		(net "P5E_CPU0_P2_TX_DP<4>")
	)
	(segment
		(start 364.442248 -294.836342)
		(end 364.4519 -294.836342)
		(width 0.1143)
		(layer "In13.Cu")
		(net "P5E_CPU0_P2_TX_DP<4>")
	)
	(segment
		(start 364.445296 -284.121098)
		(end 364.434374 -284.127448)
		(width 0.1143)
		(layer "In13.Cu")
		(net "P5E_CPU0_P2_TX_DP<4>")
	)
	(segment
		(start 364.431834 -280.243534)
		(end 364.432596 -280.244042)
		(width 0.1143)
		(layer "In13.Cu")
		(net "P5E_CPU0_P2_TX_DP<4>")
	)
	(segment
		(start 364.427262 -285.10103)
		(end 364.428278 -285.101538)
		(width 0.1143)
		(layer "In13.Cu")
		(net "P5E_CPU0_P2_TX_DP<4>")
	)
	(segment
		(start 365.034322 -296.508424)
		(end 365.034322 -299.539914)
		(width 0.14224)
		(layer "In13.Cu")
		(net "P5E_CPU0_P2_TX_DP<4>")
	)
	(segment
		(start 364.431834 -293.84879)
		(end 364.431834 -293.848536)
		(width 0.1143)
		(layer "In13.Cu")
		(net "P5E_CPU0_P2_TX_DP<4>")
	)
	(segment
		(start 364.392718 -293.180516)
		(end 364.399576 -293.18458)
		(width 0.1143)
		(layer "In13.Cu")
		(net "P5E_CPU0_P2_TX_DP<4>")
	)
	(segment
		(start 364.432596 -274.408138)
		(end 364.431834 -274.408646)
		(width 0.1143)
		(layer "In13.Cu")
		(net "P5E_CPU0_P2_TX_DP<4>")
	)
	(segment
		(start 404.03907 -382.0541)
		(end 403.74824 -382.34493)
		(width 0.14224)
		(layer "In13.Cu")
		(net "P5E_CPU0_P2_TX_DP<4>")
	)
	(segment
		(start 364.392718 -275.360638)
		(end 364.463584 -275.401786)
		(width 0.1143)
		(layer "In13.Cu")
		(net "P5E_CPU0_P2_TX_DP<4>")
	)
	(segment
		(start 364.430818 -284.129226)
		(end 364.428532 -284.13075)
		(width 0.1143)
		(layer "In13.Cu")
		(net "P5E_CPU0_P2_TX_DP<4>")
	)
	(segment
		(start 364.432596 -272.788126)
		(end 364.431834 -272.788634)
		(width 0.1143)
		(layer "In13.Cu")
		(net "P5E_CPU0_P2_TX_DP<4>")
	)
	(segment
		(start 364.427008 -288.340292)
		(end 364.42777 -288.3408)
		(width 0.1143)
		(layer "In13.Cu")
		(net "P5E_CPU0_P2_TX_DP<4>")
	)
	(segment
		(start 364.428786 -283.48178)
		(end 364.433104 -283.48432)
		(width 0.1143)
		(layer "In13.Cu")
		(net "P5E_CPU0_P2_TX_DP<4>")
	)
	(segment
		(start 364.392718 -276.98065)
		(end 364.399576 -276.984714)
		(width 0.1143)
		(layer "In13.Cu")
		(net "P5E_CPU0_P2_TX_DP<4>")
	)
	(segment
		(start 364.425738 -282.512262)
		(end 364.411768 -282.52039)
		(width 0.1143)
		(layer "In13.Cu")
		(net "P5E_CPU0_P2_TX_DP<4>")
	)
	(segment
		(start 365.012732 -270.036036)
		(end 365.082582 -270.105886)
		(width 0.1143)
		(layer "In13.Cu")
		(net "P5E_CPU0_P2_TX_DP<4>")
	)
	(arc
		(start 364.432342 -289.963352)
		(mid 364.61798 -290.285932)
		(end 364.432342 -290.608512)
		(width 0.1143)
		(layer "In13.Cu")
		(net "P5E_CPU0_P2_TX_DP<4>")
	)
	(arc
		(start 364.463584 -273.781774)
		(mid 364.615173 -274.086066)
		(end 364.463584 -274.390358)
		(width 0.1143)
		(layer "In13.Cu")
		(net "P5E_CPU0_P2_TX_DP<4>")
	)
	(arc
		(start 364.14964 -287.856168)
		(mid 364.213649 -288.117419)
		(end 364.391194 -288.319464)
		(width 0.1143)
		(layer "In13.Cu")
		(net "P5E_CPU0_P2_TX_DP<4>")
	)
	(arc
		(start 364.392718 -285.77159)
		(mid 364.149391 -286.236156)
		(end 364.392718 -286.700722)
		(width 0.1143)
		(layer "In13.Cu")
		(net "P5E_CPU0_P2_TX_DP<4>")
	)
	(arc
		(start 365.042704 -295.761156)
		(mid 365.070323 -295.802396)
		(end 365.080042 -295.851072)
		(width 0.1143)
		(layer "In13.Cu")
		(net "P5E_CPU0_P2_TX_DP<4>")
	)
	(arc
		(start 364.435136 -281.865324)
		(mid 364.619869 -282.186016)
		(end 364.43539 -282.506928)
		(width 0.1143)
		(layer "In13.Cu")
		(net "P5E_CPU0_P2_TX_DP<4>")
	)
	(arc
		(start 402.33092 -377.844558)
		(mid 402.362072 -378.001261)
		(end 402.450808 -378.134118)
		(width 0.14224)
		(layer "In13.Cu")
		(net "P5E_CPU0_P2_TX_DP<4>")
	)
	(arc
		(start 364.392718 -290.631372)
		(mid 364.149391 -291.095938)
		(end 364.392718 -291.560504)
		(width 0.1143)
		(layer "In13.Cu")
		(net "P5E_CPU0_P2_TX_DP<4>")
	)
	(arc
		(start 364.463584 -278.64181)
		(mid 364.613969 -278.946102)
		(end 364.463584 -279.250394)
		(width 0.1143)
		(layer "In13.Cu")
		(net "P5E_CPU0_P2_TX_DP<4>")
	)
	(arc
		(start 364.392718 -276.051518)
		(mid 364.149391 -276.516084)
		(end 364.392718 -276.98065)
		(width 0.1143)
		(layer "In13.Cu")
		(net "P5E_CPU0_P2_TX_DP<4>")
	)
	(arc
		(start 364.411768 -282.52039)
		(mid 364.138695 -282.995565)
		(end 364.410752 -283.471366)
		(width 0.1143)
		(layer "In13.Cu")
		(net "P5E_CPU0_P2_TX_DP<4>")
	)
	(arc
		(start 364.392718 -274.431506)
		(mid 364.149391 -274.896072)
		(end 364.392718 -275.360638)
		(width 0.1143)
		(layer "In13.Cu")
		(net "P5E_CPU0_P2_TX_DP<4>")
	)
	(arc
		(start 364.43285 -288.343848)
		(mid 364.618302 -288.66581)
		(end 364.433104 -288.987992)
		(width 0.1143)
		(layer "In13.Cu")
		(net "P5E_CPU0_P2_TX_DP<4>")
	)
	(arc
		(start 364.461044 -286.740092)
		(mid 364.462953 -286.741483)
		(end 364.464854 -286.742886)
		(width 0.1143)
		(layer "In13.Cu")
		(net "P5E_CPU0_P2_TX_DP<4>")
	)
	(arc
		(start 364.483396 -280.276046)
		(mid 364.63211 -280.566114)
		(end 364.483396 -280.856182)
		(width 0.1143)
		(layer "In13.Cu")
		(net "P5E_CPU0_P2_TX_DP<4>")
	)
	(arc
		(start 365.034322 -299.539914)
		(mid 365.042983 -299.628869)
		(end 365.068866 -299.714412)
		(width 0.14224)
		(layer "In13.Cu")
		(net "P5E_CPU0_P2_TX_DP<4>")
	)
	(arc
		(start 364.450376 -283.494226)
		(mid 364.62995 -283.806028)
		(end 364.45063 -284.11805)
		(width 0.1143)
		(layer "In13.Cu")
		(net "P5E_CPU0_P2_TX_DP<4>")
	)
	(arc
		(start 364.89132 -270.364712)
		(mid 364.685252 -270.571575)
		(end 364.609888 -270.853662)
		(width 0.1143)
		(layer "In13.Cu")
		(net "P5E_CPU0_P2_TX_DP<4>")
	)
	(arc
		(start 364.392718 -292.251384)
		(mid 364.149391 -292.71595)
		(end 364.392718 -293.180516)
		(width 0.1143)
		(layer "In13.Cu")
		(net "P5E_CPU0_P2_TX_DP<4>")
	)
	(arc
		(start 364.38967 -287.394904)
		(mid 364.213223 -287.596163)
		(end 364.14964 -287.856168)
		(width 0.1143)
		(layer "In13.Cu")
		(net "P5E_CPU0_P2_TX_DP<4>")
	)
	(arc
		(start 402.835618 -378.518674)
		(mid 403.03601 -378.673827)
		(end 403.268942 -378.77369)
		(width 0.14224)
		(layer "In13.Cu")
		(net "P5E_CPU0_P2_TX_DP<4>")
	)
	(arc
		(start 364.392718 -272.811494)
		(mid 364.149391 -273.27606)
		(end 364.392718 -273.740626)
		(width 0.1143)
		(layer "In13.Cu")
		(net "P5E_CPU0_P2_TX_DP<4>")
	)
	(arc
		(start 364.4519 -294.836342)
		(mid 364.574918 -294.969928)
		(end 364.61954 -295.145968)
		(width 0.1143)
		(layer "In13.Cu")
		(net "P5E_CPU0_P2_TX_DP<4>")
	)
	(arc
		(start 364.61954 -295.145968)
		(mid 364.693697 -295.423392)
		(end 364.8964 -295.62679)
		(width 0.1143)
		(layer "In13.Cu")
		(net "P5E_CPU0_P2_TX_DP<4>")
	)
	(arc
		(start 364.428532 -284.13075)
		(mid 364.149768 -284.615468)
		(end 364.427262 -285.10103)
		(width 0.1143)
		(layer "In13.Cu")
		(net "P5E_CPU0_P2_TX_DP<4>")
	)
	(arc
		(start 403.268942 -378.77369)
		(mid 403.348016 -378.799782)
		(end 403.424644 -378.832364)
		(width 0.14224)
		(layer "In13.Cu")
		(net "P5E_CPU0_P2_TX_DP<4>")
	)
	(arc
		(start 403.684486 -378.955808)
		(mid 403.739044 -378.987711)
		(end 403.787356 -379.028452)
		(width 0.14224)
		(layer "In13.Cu")
		(net "P5E_CPU0_P2_TX_DP<4>")
	)
	(arc
		(start 364.392718 -277.67153)
		(mid 364.149391 -278.136096)
		(end 364.392718 -278.600662)
		(width 0.1143)
		(layer "In13.Cu")
		(net "P5E_CPU0_P2_TX_DP<4>")
	)
	(arc
		(start 364.609888 -270.862044)
		(mid 364.562362 -271.038895)
		(end 364.432596 -271.168114)
		(width 0.1143)
		(layer "In13.Cu")
		(net "P5E_CPU0_P2_TX_DP<4>")
	)
	(arc
		(start 398.883632 -374.541288)
		(mid 399.124595 -374.739136)
		(end 399.399506 -374.88622)
		(width 0.14224)
		(layer "In13.Cu")
		(net "P5E_CPU0_P2_TX_DP<4>")
	)
	(arc
		(start 364.392718 -280.911554)
		(mid 364.149391 -281.37612)
		(end 364.392718 -281.840686)
		(width 0.1143)
		(layer "In13.Cu")
		(net "P5E_CPU0_P2_TX_DP<4>")
	)
	(arc
		(start 403.900386 -379.141482)
		(mid 404.003015 -379.295077)
		(end 404.03907 -379.476254)
		(width 0.14224)
		(layer "In13.Cu")
		(net "P5E_CPU0_P2_TX_DP<4>")
	)
	(arc
		(start 402.286216 -376.819414)
		(mid 402.319309 -376.868942)
		(end 402.33092 -376.927364)
		(width 0.14224)
		(layer "In13.Cu")
		(net "P5E_CPU0_P2_TX_DP<4>")
	)
	(arc
		(start 364.392718 -279.291542)
		(mid 364.149391 -279.756108)
		(end 364.392718 -280.220674)
		(width 0.1143)
		(layer "In13.Cu")
		(net "P5E_CPU0_P2_TX_DP<4>")
	)
	(arc
		(start 364.464854 -286.742886)
		(mid 364.57681 -286.872435)
		(end 364.619286 -287.038288)
		(width 0.1143)
		(layer "In13.Cu")
		(net "P5E_CPU0_P2_TX_DP<4>")
	)
	(arc
		(start 364.428024 -293.850822)
		(mid 364.14948 -294.334655)
		(end 364.425738 -294.819832)
		(width 0.1143)
		(layer "In13.Cu")
		(net "P5E_CPU0_P2_TX_DP<4>")
	)
	(arc
		(start 364.392718 -289.01136)
		(mid 364.149391 -289.475926)
		(end 364.392718 -289.940492)
		(width 0.1143)
		(layer "In13.Cu")
		(net "P5E_CPU0_P2_TX_DP<4>")
	)
	(arc
		(start 364.392718 -271.191482)
		(mid 364.149391 -271.656048)
		(end 364.392718 -272.120614)
		(width 0.1143)
		(layer "In13.Cu")
		(net "P5E_CPU0_P2_TX_DP<4>")
	)
	(arc
		(start 364.483396 -277.036022)
		(mid 364.63211 -277.32609)
		(end 364.483396 -277.616158)
		(width 0.1143)
		(layer "In13.Cu")
		(net "P5E_CPU0_P2_TX_DP<4>")
	)
	(arc
		(start 364.463584 -285.121858)
		(mid 364.613969 -285.42615)
		(end 364.463584 -285.730442)
		(width 0.1143)
		(layer "In13.Cu")
		(net "P5E_CPU0_P2_TX_DP<4>")
	)
	(arc
		(start 364.617254 -287.059878)
		(mid 364.571855 -287.21682)
		(end 364.470696 -287.34512)
		(width 0.1143)
		(layer "In13.Cu")
		(net "P5E_CPU0_P2_TX_DP<4>")
	)
	(arc
		(start 364.463584 -275.401786)
		(mid 364.615173 -275.706078)
		(end 364.463584 -276.01037)
		(width 0.1143)
		(layer "In13.Cu")
		(net "P5E_CPU0_P2_TX_DP<4>")
	)
	(arc
		(start 364.432342 -291.583364)
		(mid 364.61798 -291.905944)
		(end 364.432342 -292.228524)
		(width 0.1143)
		(layer "In13.Cu")
		(net "P5E_CPU0_P2_TX_DP<4>")
	)
	(arc
		(start 364.432342 -293.203376)
		(mid 364.61798 -293.525956)
		(end 364.432342 -293.848536)
		(width 0.1143)
		(layer "In13.Cu")
		(net "P5E_CPU0_P2_TX_DP<4>")
	)
	(arc
		(start 364.463584 -272.161762)
		(mid 364.615173 -272.466054)
		(end 364.463584 -272.770346)
		(width 0.1143)
		(layer "In13.Cu")
		(net "P5E_CPU0_P2_TX_DP<4>")
	)
	(arc
		(start 365.082582 -270.105886)
		(mid 365.030533 -270.237405)
		(end 364.933484 -270.340328)
		(width 0.1143)
		(layer "In13.Cu")
		(net "P5E_CPU0_P2_TX_DP<4>")
	)
	(segment
		(start 361.89793 -272.200116)
		(end 362.364782 -272.466054)
		(width 0.12954)
		(layer "F.Cu")
		(net "P5E_CPU0_P2_TX_DP<3>")
	)
	(segment
		(start 400.61515 -377.68784)
		(end 400.61515 -378.39142)
		(width 0.12954)
		(layer "F.Cu")
		(net "P5E_CPU0_P2_TX_DP<3>")
	)
	(segment
		(start 400.34464 -377.41733)
		(end 400.61515 -377.68784)
		(width 0.12954)
		(layer "F.Cu")
		(net "P5E_CPU0_P2_TX_DP<3>")
	)
	(segment
		(start 400.61515 -378.39142)
		(end 400.31924 -378.68733)
		(width 0.12954)
		(layer "F.Cu")
		(net "P5E_CPU0_P2_TX_DP<3>")
	)
	(segment
		(start 400.63547 -376.517662)
		(end 400.63547 -377.1265)
		(width 0.14224)
		(layer "In13.Cu")
		(net "P5E_CPU0_P2_TX_DP<3>")
	)
	(segment
		(start 363.453426 -289.941)
		(end 363.52353 -289.981894)
		(width 0.1143)
		(layer "In13.Cu")
		(net "P5E_CPU0_P2_TX_DP<3>")
	)
	(segment
		(start 362.364782 -272.466054)
		(end 362.662724 -272.466054)
		(width 0.1143)
		(layer "In13.Cu")
		(net "P5E_CPU0_P2_TX_DP<3>")
	)
	(segment
		(start 363.453426 -283.461206)
		(end 363.52353 -283.5021)
		(width 0.1143)
		(layer "In13.Cu")
		(net "P5E_CPU0_P2_TX_DP<3>")
	)
	(segment
		(start 363.523784 -290.58997)
		(end 363.453426 -290.630864)
		(width 0.1143)
		(layer "In13.Cu")
		(net "P5E_CPU0_P2_TX_DP<3>")
	)
	(segment
		(start 363.523784 -288.969958)
		(end 363.453426 -289.010852)
		(width 0.1143)
		(layer "In13.Cu")
		(net "P5E_CPU0_P2_TX_DP<3>")
	)
	(segment
		(start 363.523784 -284.110176)
		(end 363.453426 -284.15107)
		(width 0.1143)
		(layer "In13.Cu")
		(net "P5E_CPU0_P2_TX_DP<3>")
	)
	(segment
		(start 400.447256 -376.329448)
		(end 400.63547 -376.517662)
		(width 0.14224)
		(layer "In13.Cu")
		(net "P5E_CPU0_P2_TX_DP<3>")
	)
	(segment
		(start 362.662724 -272.466054)
		(end 362.745528 -272.548858)
		(width 0.1143)
		(layer "In13.Cu")
		(net "P5E_CPU0_P2_TX_DP<3>")
	)
	(segment
		(start 363.523784 -282.490164)
		(end 363.453426 -282.531058)
		(width 0.1143)
		(layer "In13.Cu")
		(net "P5E_CPU0_P2_TX_DP<3>")
	)
	(segment
		(start 363.453426 -275.361146)
		(end 363.52353 -275.40204)
		(width 0.1143)
		(layer "In13.Cu")
		(net "P5E_CPU0_P2_TX_DP<3>")
	)
	(segment
		(start 400.63547 -377.1265)
		(end 400.34464 -377.41733)
		(width 0.14224)
		(layer "In13.Cu")
		(net "P5E_CPU0_P2_TX_DP<3>")
	)
	(segment
		(start 364.120684 -300.194726)
		(end 391.706862 -366.791748)
		(width 0.14224)
		(layer "In13.Cu")
		(net "P5E_CPU0_P2_TX_DP<3>")
	)
	(segment
		(start 363.52353 -274.390358)
		(end 363.453426 -274.430998)
		(width 0.1143)
		(layer "In13.Cu")
		(net "P5E_CPU0_P2_TX_DP<3>")
	)
	(segment
		(start 363.02188 -272.95348)
		(end 363.05236 -272.97126)
		(width 0.1143)
		(layer "In13.Cu")
		(net "P5E_CPU0_P2_TX_DP<3>")
	)
	(segment
		(start 363.453426 -294.801036)
		(end 363.52353 -294.84193)
		(width 0.1143)
		(layer "In13.Cu")
		(net "P5E_CPU0_P2_TX_DP<3>")
	)
	(segment
		(start 363.523784 -277.630128)
		(end 363.453426 -277.671022)
		(width 0.1143)
		(layer "In13.Cu")
		(net "P5E_CPU0_P2_TX_DP<3>")
	)
	(segment
		(start 363.454188 -293.181532)
		(end 363.52353 -293.221918)
		(width 0.1143)
		(layer "In13.Cu")
		(net "P5E_CPU0_P2_TX_DP<3>")
	)
	(segment
		(start 397.22806 -374.563386)
		(end 397.908526 -375.243852)
		(width 0.14224)
		(layer "In13.Cu")
		(net "P5E_CPU0_P2_TX_DP<3>")
	)
	(segment
		(start 363.450886 -288.31921)
		(end 363.52353 -288.361882)
		(width 0.1143)
		(layer "In13.Cu")
		(net "P5E_CPU0_P2_TX_DP<3>")
	)
	(segment
		(start 391.792206 -366.952276)
		(end 395.343126 -372.26621)
		(width 0.14224)
		(layer "In13.Cu")
		(net "P5E_CPU0_P2_TX_DP<3>")
	)
	(segment
		(start 363.523784 -285.730188)
		(end 363.453426 -285.771082)
		(width 0.1143)
		(layer "In13.Cu")
		(net "P5E_CPU0_P2_TX_DP<3>")
	)
	(segment
		(start 363.453426 -276.981158)
		(end 363.52353 -277.022052)
		(width 0.1143)
		(layer "In13.Cu")
		(net "P5E_CPU0_P2_TX_DP<3>")
	)
	(segment
		(start 363.493812 -273.764756)
		(end 363.52353 -273.781774)
		(width 0.1143)
		(layer "In13.Cu")
		(net "P5E_CPU0_P2_TX_DP<3>")
	)
	(segment
		(start 363.453426 -285.081218)
		(end 363.52353 -285.122112)
		(width 0.1143)
		(layer "In13.Cu")
		(net "P5E_CPU0_P2_TX_DP<3>")
	)
	(segment
		(start 363.453426 -281.841194)
		(end 363.52353 -281.882088)
		(width 0.1143)
		(layer "In13.Cu")
		(net "P5E_CPU0_P2_TX_DP<3>")
	)
	(segment
		(start 363.924342 -295.61155)
		(end 364.038642 -295.67886)
		(width 0.1143)
		(layer "In13.Cu")
		(net "P5E_CPU0_P2_TX_DP<3>")
	)
	(segment
		(start 363.492542 -273.763994)
		(end 363.493812 -273.764756)
		(width 0.1143)
		(layer "In13.Cu")
		(net "P5E_CPU0_P2_TX_DP<3>")
	)
	(segment
		(start 363.523784 -279.25014)
		(end 363.453426 -279.291034)
		(width 0.1143)
		(layer "In13.Cu")
		(net "P5E_CPU0_P2_TX_DP<3>")
	)
	(segment
		(start 364.038642 -295.67886)
		(end 364.060994 -295.701212)
		(width 0.1143)
		(layer "In13.Cu")
		(net "P5E_CPU0_P2_TX_DP<3>")
	)
	(segment
		(start 363.453426 -280.221182)
		(end 363.52353 -280.262076)
		(width 0.1143)
		(layer "In13.Cu")
		(net "P5E_CPU0_P2_TX_DP<3>")
	)
	(segment
		(start 364.12043 -295.844214)
		(end 364.12043 -296.29989)
		(width 0.1143)
		(layer "In13.Cu")
		(net "P5E_CPU0_P2_TX_DP<3>")
	)
	(segment
		(start 363.450886 -286.699198)
		(end 363.52353 -286.74187)
		(width 0.1143)
		(layer "In13.Cu")
		(net "P5E_CPU0_P2_TX_DP<3>")
	)
	(segment
		(start 363.49178 -273.763486)
		(end 363.492542 -273.763994)
		(width 0.1143)
		(layer "In13.Cu")
		(net "P5E_CPU0_P2_TX_DP<3>")
	)
	(segment
		(start 364.12043 -296.29989)
		(end 364.07471 -296.34561)
		(width 0.1143)
		(layer "In13.Cu")
		(net "P5E_CPU0_P2_TX_DP<3>")
	)
	(segment
		(start 363.523784 -292.209982)
		(end 363.453426 -292.250876)
		(width 0.1143)
		(layer "In13.Cu")
		(net "P5E_CPU0_P2_TX_DP<3>")
	)
	(segment
		(start 395.343126 -372.26621)
		(end 397.22806 -374.563386)
		(width 0.14224)
		(layer "In13.Cu")
		(net "P5E_CPU0_P2_TX_DP<3>")
	)
	(segment
		(start 364.07471 -296.34561)
		(end 364.07471 -296.374058)
		(width 0.1143)
		(layer "In13.Cu")
		(net "P5E_CPU0_P2_TX_DP<3>")
	)
	(segment
		(start 363.521752 -287.35147)
		(end 363.453426 -287.391094)
		(width 0.1143)
		(layer "In13.Cu")
		(net "P5E_CPU0_P2_TX_DP<3>")
	)
	(segment
		(start 363.453426 -278.60117)
		(end 363.52353 -278.642064)
		(width 0.1143)
		(layer "In13.Cu")
		(net "P5E_CPU0_P2_TX_DP<3>")
	)
	(segment
		(start 362.982764 -272.93062)
		(end 363.02188 -272.95348)
		(width 0.1143)
		(layer "In13.Cu")
		(net "P5E_CPU0_P2_TX_DP<3>")
	)
	(segment
		(start 363.523784 -280.870152)
		(end 363.453426 -280.911046)
		(width 0.1143)
		(layer "In13.Cu")
		(net "P5E_CPU0_P2_TX_DP<3>")
	)
	(segment
		(start 363.523784 -276.010116)
		(end 363.453426 -276.05101)
		(width 0.1143)
		(layer "In13.Cu")
		(net "P5E_CPU0_P2_TX_DP<3>")
	)
	(segment
		(start 363.453426 -291.561012)
		(end 363.52353 -291.601906)
		(width 0.1143)
		(layer "In13.Cu")
		(net "P5E_CPU0_P2_TX_DP<3>")
	)
	(segment
		(start 363.452664 -273.740626)
		(end 363.49178 -273.763486)
		(width 0.1143)
		(layer "In13.Cu")
		(net "P5E_CPU0_P2_TX_DP<3>")
	)
	(segment
		(start 363.52353 -293.829994)
		(end 363.454188 -293.87038)
		(width 0.1143)
		(layer "In13.Cu")
		(net "P5E_CPU0_P2_TX_DP<3>")
	)
	(segment
		(start 398.0434 -375.334022)
		(end 400.447256 -376.329448)
		(width 0.14224)
		(layer "In13.Cu")
		(net "P5E_CPU0_P2_TX_DP<3>")
	)
	(segment
		(start 364.07471 -296.374058)
		(end 364.07471 -299.963586)
		(width 0.14224)
		(layer "In13.Cu")
		(net "P5E_CPU0_P2_TX_DP<3>")
	)
	(arc
		(start 363.209586 -286.236156)
		(mid 363.273532 -286.497225)
		(end 363.450886 -286.699198)
		(width 0.1143)
		(layer "In13.Cu")
		(net "P5E_CPU0_P2_TX_DP<3>")
	)
	(arc
		(start 363.52353 -281.882088)
		(mid 363.679463 -282.186023)
		(end 363.523784 -282.490164)
		(width 0.1143)
		(layer "In13.Cu")
		(net "P5E_CPU0_P2_TX_DP<3>")
	)
	(arc
		(start 363.453426 -279.291034)
		(mid 363.209572 -279.756108)
		(end 363.453426 -280.221182)
		(width 0.1143)
		(layer "In13.Cu")
		(net "P5E_CPU0_P2_TX_DP<3>")
	)
	(arc
		(start 363.05236 -272.97126)
		(mid 363.167787 -273.104636)
		(end 363.209332 -273.27606)
		(width 0.1143)
		(layer "In13.Cu")
		(net "P5E_CPU0_P2_TX_DP<3>")
	)
	(arc
		(start 363.453426 -287.391094)
		(mid 363.274233 -287.593604)
		(end 363.209586 -287.856168)
		(width 0.1143)
		(layer "In13.Cu")
		(net "P5E_CPU0_P2_TX_DP<3>")
	)
	(arc
		(start 397.908526 -375.243852)
		(mid 397.971516 -375.295591)
		(end 398.0434 -375.334022)
		(width 0.14224)
		(layer "In13.Cu")
		(net "P5E_CPU0_P2_TX_DP<3>")
	)
	(arc
		(start 363.52353 -285.122112)
		(mid 363.679463 -285.426047)
		(end 363.523784 -285.730188)
		(width 0.1143)
		(layer "In13.Cu")
		(net "P5E_CPU0_P2_TX_DP<3>")
	)
	(arc
		(start 363.52353 -288.361882)
		(mid 363.679463 -288.665817)
		(end 363.523784 -288.969958)
		(width 0.1143)
		(layer "In13.Cu")
		(net "P5E_CPU0_P2_TX_DP<3>")
	)
	(arc
		(start 364.07471 -299.963586)
		(mid 364.086311 -300.081422)
		(end 364.120684 -300.194726)
		(width 0.14224)
		(layer "In13.Cu")
		(net "P5E_CPU0_P2_TX_DP<3>")
	)
	(arc
		(start 363.454188 -293.87038)
		(mid 363.274396 -294.072968)
		(end 363.209586 -294.335962)
		(width 0.1143)
		(layer "In13.Cu")
		(net "P5E_CPU0_P2_TX_DP<3>")
	)
	(arc
		(start 363.453426 -282.531058)
		(mid 363.209572 -282.996132)
		(end 363.453426 -283.461206)
		(width 0.1143)
		(layer "In13.Cu")
		(net "P5E_CPU0_P2_TX_DP<3>")
	)
	(arc
		(start 363.52353 -273.781774)
		(mid 363.679458 -274.086066)
		(end 363.52353 -274.390358)
		(width 0.1143)
		(layer "In13.Cu")
		(net "P5E_CPU0_P2_TX_DP<3>")
	)
	(arc
		(start 391.706862 -366.791748)
		(mid 391.745579 -366.874115)
		(end 391.792206 -366.952276)
		(width 0.14224)
		(layer "In13.Cu")
		(net "P5E_CPU0_P2_TX_DP<3>")
	)
	(arc
		(start 363.67974 -295.145968)
		(mid 363.744558 -295.408957)
		(end 363.924342 -295.61155)
		(width 0.1143)
		(layer "In13.Cu")
		(net "P5E_CPU0_P2_TX_DP<3>")
	)
	(arc
		(start 363.52353 -277.022052)
		(mid 363.679463 -277.325987)
		(end 363.523784 -277.630128)
		(width 0.1143)
		(layer "In13.Cu")
		(net "P5E_CPU0_P2_TX_DP<3>")
	)
	(arc
		(start 363.453426 -289.010852)
		(mid 363.209572 -289.475926)
		(end 363.453426 -289.941)
		(width 0.1143)
		(layer "In13.Cu")
		(net "P5E_CPU0_P2_TX_DP<3>")
	)
	(arc
		(start 363.209332 -273.27606)
		(mid 363.273847 -273.538279)
		(end 363.452664 -273.740626)
		(width 0.1143)
		(layer "In13.Cu")
		(net "P5E_CPU0_P2_TX_DP<3>")
	)
	(arc
		(start 363.453426 -277.671022)
		(mid 363.209572 -278.136096)
		(end 363.453426 -278.60117)
		(width 0.1143)
		(layer "In13.Cu")
		(net "P5E_CPU0_P2_TX_DP<3>")
	)
	(arc
		(start 363.209586 -287.856168)
		(mid 363.273532 -288.117237)
		(end 363.450886 -288.31921)
		(width 0.1143)
		(layer "In13.Cu")
		(net "P5E_CPU0_P2_TX_DP<3>")
	)
	(arc
		(start 363.209586 -294.335962)
		(mid 363.274245 -294.598519)
		(end 363.453426 -294.801036)
		(width 0.1143)
		(layer "In13.Cu")
		(net "P5E_CPU0_P2_TX_DP<3>")
	)
	(arc
		(start 363.52353 -291.601906)
		(mid 363.679463 -291.905841)
		(end 363.523784 -292.209982)
		(width 0.1143)
		(layer "In13.Cu")
		(net "P5E_CPU0_P2_TX_DP<3>")
	)
	(arc
		(start 363.52353 -293.221918)
		(mid 363.679463 -293.525956)
		(end 363.52353 -293.829994)
		(width 0.1143)
		(layer "In13.Cu")
		(net "P5E_CPU0_P2_TX_DP<3>")
	)
	(arc
		(start 363.52353 -289.981894)
		(mid 363.679463 -290.285829)
		(end 363.523784 -290.58997)
		(width 0.1143)
		(layer "In13.Cu")
		(net "P5E_CPU0_P2_TX_DP<3>")
	)
	(arc
		(start 363.52353 -283.5021)
		(mid 363.679463 -283.806035)
		(end 363.523784 -284.110176)
		(width 0.1143)
		(layer "In13.Cu")
		(net "P5E_CPU0_P2_TX_DP<3>")
	)
	(arc
		(start 363.52353 -275.40204)
		(mid 363.679463 -275.705975)
		(end 363.523784 -276.010116)
		(width 0.1143)
		(layer "In13.Cu")
		(net "P5E_CPU0_P2_TX_DP<3>")
	)
	(arc
		(start 363.453426 -290.630864)
		(mid 363.209572 -291.095938)
		(end 363.453426 -291.561012)
		(width 0.1143)
		(layer "In13.Cu")
		(net "P5E_CPU0_P2_TX_DP<3>")
	)
	(arc
		(start 363.453426 -285.771082)
		(mid 363.274233 -285.973592)
		(end 363.209586 -286.236156)
		(width 0.1143)
		(layer "In13.Cu")
		(net "P5E_CPU0_P2_TX_DP<3>")
	)
	(arc
		(start 363.52353 -294.84193)
		(mid 363.638373 -294.975078)
		(end 363.67974 -295.145968)
		(width 0.1143)
		(layer "In13.Cu")
		(net "P5E_CPU0_P2_TX_DP<3>")
	)
	(arc
		(start 363.52353 -280.262076)
		(mid 363.679463 -280.566011)
		(end 363.523784 -280.870152)
		(width 0.1143)
		(layer "In13.Cu")
		(net "P5E_CPU0_P2_TX_DP<3>")
	)
	(arc
		(start 363.453426 -274.430998)
		(mid 363.209572 -274.896072)
		(end 363.453426 -275.361146)
		(width 0.1143)
		(layer "In13.Cu")
		(net "P5E_CPU0_P2_TX_DP<3>")
	)
	(arc
		(start 363.52353 -286.74187)
		(mid 363.679668 -287.047181)
		(end 363.521752 -287.35147)
		(width 0.1143)
		(layer "In13.Cu")
		(net "P5E_CPU0_P2_TX_DP<3>")
	)
	(arc
		(start 363.52353 -278.642064)
		(mid 363.679463 -278.945999)
		(end 363.523784 -279.25014)
		(width 0.1143)
		(layer "In13.Cu")
		(net "P5E_CPU0_P2_TX_DP<3>")
	)
	(arc
		(start 363.453426 -284.15107)
		(mid 363.209572 -284.616144)
		(end 363.453426 -285.081218)
		(width 0.1143)
		(layer "In13.Cu")
		(net "P5E_CPU0_P2_TX_DP<3>")
	)
	(arc
		(start 362.745528 -272.548858)
		(mid 362.824607 -272.764303)
		(end 362.982764 -272.93062)
		(width 0.1143)
		(layer "In13.Cu")
		(net "P5E_CPU0_P2_TX_DP<3>")
	)
	(arc
		(start 364.060994 -295.701212)
		(mid 364.104916 -295.766807)
		(end 364.12043 -295.844214)
		(width 0.1143)
		(layer "In13.Cu")
		(net "P5E_CPU0_P2_TX_DP<3>")
	)
	(arc
		(start 363.453426 -276.05101)
		(mid 363.209572 -276.516084)
		(end 363.453426 -276.981158)
		(width 0.1143)
		(layer "In13.Cu")
		(net "P5E_CPU0_P2_TX_DP<3>")
	)
	(arc
		(start 363.453426 -292.250876)
		(mid 363.274233 -292.453386)
		(end 363.209586 -292.71595)
		(width 0.1143)
		(layer "In13.Cu")
		(net "P5E_CPU0_P2_TX_DP<3>")
	)
	(arc
		(start 363.209586 -292.71595)
		(mid 363.274404 -292.978939)
		(end 363.454188 -293.181532)
		(width 0.1143)
		(layer "In13.Cu")
		(net "P5E_CPU0_P2_TX_DP<3>")
	)
	(arc
		(start 363.453426 -280.911046)
		(mid 363.209572 -281.37612)
		(end 363.453426 -281.841194)
		(width 0.1143)
		(layer "In13.Cu")
		(net "P5E_CPU0_P2_TX_DP<3>")
	)
	(segment
		(start 398.91335 -380.15164)
		(end 398.91335 -380.85522)
		(width 0.12954)
		(layer "F.Cu")
		(net "P5E_CPU0_P2_TX_DP<2>")
	)
	(segment
		(start 361.89793 -273.820128)
		(end 362.364782 -274.086066)
		(width 0.12954)
		(layer "F.Cu")
		(net "P5E_CPU0_P2_TX_DP<2>")
	)
	(segment
		(start 398.64284 -379.88113)
		(end 398.91335 -380.15164)
		(width 0.12954)
		(layer "F.Cu")
		(net "P5E_CPU0_P2_TX_DP<2>")
	)
	(segment
		(start 398.91335 -380.85522)
		(end 398.61744 -381.15113)
		(width 0.12954)
		(layer "F.Cu")
		(net "P5E_CPU0_P2_TX_DP<2>")
	)
	(segment
		(start 362.583476 -287.3502)
		(end 362.512102 -287.391856)
		(width 0.1143)
		(layer "In13.Cu")
		(net "P5E_CPU0_P2_TX_DP<2>")
	)
	(segment
		(start 362.54944 -285.749746)
		(end 362.54944 -285.75)
		(width 0.1143)
		(layer "In13.Cu")
		(net "P5E_CPU0_P2_TX_DP<2>")
	)
	(segment
		(start 362.583476 -279.250394)
		(end 362.515404 -279.289764)
		(width 0.1143)
		(layer "In13.Cu")
		(net "P5E_CPU0_P2_TX_DP<2>")
	)
	(segment
		(start 362.583476 -290.590224)
		(end 362.515404 -290.629594)
		(width 0.1143)
		(layer "In13.Cu")
		(net "P5E_CPU0_P2_TX_DP<2>")
	)
	(segment
		(start 362.559346 -293.207694)
		(end 362.583476 -293.221664)
		(width 0.1143)
		(layer "In13.Cu")
		(net "P5E_CPU0_P2_TX_DP<2>")
	)
	(segment
		(start 362.739686 -295.145968)
		(end 362.739686 -295.22547)
		(width 0.1143)
		(layer "In13.Cu")
		(net "P5E_CPU0_P2_TX_DP<2>")
	)
	(segment
		(start 362.54944 -286.722312)
		(end 362.551726 -286.723582)
		(width 0.1143)
		(layer "In13.Cu")
		(net "P5E_CPU0_P2_TX_DP<2>")
	)
	(segment
		(start 362.662724 -274.086066)
		(end 362.732574 -274.155916)
		(width 0.1143)
		(layer "In13.Cu")
		(net "P5E_CPU0_P2_TX_DP<2>")
	)
	(segment
		(start 362.51261 -293.180516)
		(end 362.551726 -293.203376)
		(width 0.1143)
		(layer "In13.Cu")
		(net "P5E_CPU0_P2_TX_DP<2>")
	)
	(segment
		(start 362.583476 -292.210236)
		(end 362.556044 -292.225984)
		(width 0.1143)
		(layer "In13.Cu")
		(net "P5E_CPU0_P2_TX_DP<2>")
	)
	(segment
		(start 362.553504 -285.104586)
		(end 362.583476 -285.121858)
		(width 0.1143)
		(layer "In13.Cu")
		(net "P5E_CPU0_P2_TX_DP<2>")
	)
	(segment
		(start 362.364782 -274.086066)
		(end 362.662724 -274.086066)
		(width 0.1143)
		(layer "In13.Cu")
		(net "P5E_CPU0_P2_TX_DP<2>")
	)
	(segment
		(start 362.515404 -275.362416)
		(end 362.583476 -275.401786)
		(width 0.1143)
		(layer "In13.Cu")
		(net "P5E_CPU0_P2_TX_DP<2>")
	)
	(segment
		(start 362.535216 -294.813736)
		(end 362.580682 -294.840152)
		(width 0.1143)
		(layer "In13.Cu")
		(net "P5E_CPU0_P2_TX_DP<2>")
	)
	(segment
		(start 362.552742 -285.104078)
		(end 362.553504 -285.104586)
		(width 0.1143)
		(layer "In13.Cu")
		(net "P5E_CPU0_P2_TX_DP<2>")
	)
	(segment
		(start 363.194854 -300.797976)
		(end 390.603232 -366.93983)
		(width 0.14224)
		(layer "In13.Cu")
		(net "P5E_CPU0_P2_TX_DP<2>")
	)
	(segment
		(start 362.515404 -280.222452)
		(end 362.551726 -280.243534)
		(width 0.1143)
		(layer "In13.Cu")
		(net "P5E_CPU0_P2_TX_DP<2>")
	)
	(segment
		(start 398.93367 -377.99137)
		(end 398.93367 -379.5903)
		(width 0.14224)
		(layer "In13.Cu")
		(net "P5E_CPU0_P2_TX_DP<2>")
	)
	(segment
		(start 362.553504 -284.127702)
		(end 362.552742 -284.12821)
		(width 0.1143)
		(layer "In13.Cu")
		(net "P5E_CPU0_P2_TX_DP<2>")
	)
	(segment
		(start 362.583476 -288.970212)
		(end 362.513372 -289.010852)
		(width 0.1143)
		(layer "In13.Cu")
		(net "P5E_CPU0_P2_TX_DP<2>")
	)
	(segment
		(start 398.93367 -379.5903)
		(end 398.64284 -379.88113)
		(width 0.14224)
		(layer "In13.Cu")
		(net "P5E_CPU0_P2_TX_DP<2>")
	)
	(segment
		(start 362.515404 -276.982428)
		(end 362.583476 -277.021798)
		(width 0.1143)
		(layer "In13.Cu")
		(net "P5E_CPU0_P2_TX_DP<2>")
	)
	(segment
		(start 363.18825 -295.909238)
		(end 363.18825 -296.235628)
		(width 0.1143)
		(layer "In13.Cu")
		(net "P5E_CPU0_P2_TX_DP<2>")
	)
	(segment
		(start 362.546392 -293.839138)
		(end 362.54436 -293.840408)
		(width 0.1143)
		(layer "In13.Cu")
		(net "P5E_CPU0_P2_TX_DP<2>")
	)
	(segment
		(start 362.556044 -292.225984)
		(end 362.550202 -292.229286)
		(width 0.1143)
		(layer "In13.Cu")
		(net "P5E_CPU0_P2_TX_DP<2>")
	)
	(segment
		(start 362.580682 -294.840152)
		(end 362.583476 -294.841676)
		(width 0.1143)
		(layer "In13.Cu")
		(net "P5E_CPU0_P2_TX_DP<2>")
	)
	(segment
		(start 396.380716 -375.043446)
		(end 398.610074 -377.272804)
		(width 0.14224)
		(layer "In13.Cu")
		(net "P5E_CPU0_P2_TX_DP<2>")
	)
	(segment
		(start 362.585254 -286.74314)
		(end 362.595922 -286.751014)
		(width 0.1143)
		(layer "In13.Cu")
		(net "P5E_CPU0_P2_TX_DP<2>")
	)
	(segment
		(start 362.586016 -285.728664)
		(end 362.550202 -285.749238)
		(width 0.1143)
		(layer "In13.Cu")
		(net "P5E_CPU0_P2_TX_DP<2>")
	)
	(segment
		(start 362.551726 -280.243534)
		(end 362.583476 -280.261822)
		(width 0.1143)
		(layer "In13.Cu")
		(net "P5E_CPU0_P2_TX_DP<2>")
	)
	(segment
		(start 362.583984 -285.122112)
		(end 362.584746 -285.12262)
		(width 0.1143)
		(layer "In13.Cu")
		(net "P5E_CPU0_P2_TX_DP<2>")
	)
	(segment
		(start 362.583476 -293.221664)
		(end 362.597954 -293.232078)
		(width 0.1143)
		(layer "In13.Cu")
		(net "P5E_CPU0_P2_TX_DP<2>")
	)
	(segment
		(start 362.583476 -274.390358)
		(end 362.515404 -274.429728)
		(width 0.1143)
		(layer "In13.Cu")
		(net "P5E_CPU0_P2_TX_DP<2>")
	)
	(segment
		(start 362.544614 -292.232588)
		(end 362.51261 -292.251384)
		(width 0.1143)
		(layer "In13.Cu")
		(net "P5E_CPU0_P2_TX_DP<2>")
	)
	(segment
		(start 363.14253 -296.309796)
		(end 363.14253 -300.534832)
		(width 0.14224)
		(layer "In13.Cu")
		(net "P5E_CPU0_P2_TX_DP<2>")
	)
	(segment
		(start 362.583476 -285.121858)
		(end 362.583984 -285.122112)
		(width 0.1143)
		(layer "In13.Cu")
		(net "P5E_CPU0_P2_TX_DP<2>")
	)
	(segment
		(start 362.512102 -287.391856)
		(end 362.50118 -287.399476)
		(width 0.1143)
		(layer "In13.Cu")
		(net "P5E_CPU0_P2_TX_DP<2>")
	)
	(segment
		(start 362.515404 -291.562282)
		(end 362.583476 -291.601652)
		(width 0.1143)
		(layer "In13.Cu")
		(net "P5E_CPU0_P2_TX_DP<2>")
	)
	(segment
		(start 362.54563 -282.512008)
		(end 362.544106 -282.513024)
		(width 0.1143)
		(layer "In13.Cu")
		(net "P5E_CPU0_P2_TX_DP<2>")
	)
	(segment
		(start 363.18825 -296.235628)
		(end 363.14253 -296.281348)
		(width 0.1143)
		(layer "In13.Cu")
		(net "P5E_CPU0_P2_TX_DP<2>")
	)
	(segment
		(start 390.689084 -367.09985)
		(end 394.271754 -372.46179)
		(width 0.14224)
		(layer "In13.Cu")
		(net "P5E_CPU0_P2_TX_DP<2>")
	)
	(segment
		(start 362.555282 -284.126686)
		(end 362.55452 -284.127194)
		(width 0.1143)
		(layer "In13.Cu")
		(net "P5E_CPU0_P2_TX_DP<2>")
	)
	(segment
		(start 362.50118 -289.932364)
		(end 362.513372 -289.941)
		(width 0.1143)
		(layer "In13.Cu")
		(net "P5E_CPU0_P2_TX_DP<2>")
	)
	(segment
		(start 394.363448 -372.585742)
		(end 396.380716 -375.043446)
		(width 0.14224)
		(layer "In13.Cu")
		(net "P5E_CPU0_P2_TX_DP<2>")
	)
	(segment
		(start 362.845604 -295.480994)
		(end 363.127544 -295.763188)
		(width 0.1143)
		(layer "In13.Cu")
		(net "P5E_CPU0_P2_TX_DP<2>")
	)
	(segment
		(start 362.739432 -287.0327)
		(end 362.739432 -287.045908)
		(width 0.1143)
		(layer "In13.Cu")
		(net "P5E_CPU0_P2_TX_DP<2>")
	)
	(segment
		(start 398.749774 -377.4821)
		(end 398.909286 -377.86818)
		(width 0.14224)
		(layer "In13.Cu")
		(net "P5E_CPU0_P2_TX_DP<2>")
	)
	(segment
		(start 362.583476 -282.490418)
		(end 362.54563 -282.512008)
		(width 0.1143)
		(layer "In13.Cu")
		(net "P5E_CPU0_P2_TX_DP<2>")
	)
	(segment
		(start 362.269532 -287.853374)
		(end 362.269532 -287.856168)
		(width 0.1143)
		(layer "In13.Cu")
		(net "P5E_CPU0_P2_TX_DP<2>")
	)
	(segment
		(start 362.55452 -284.127194)
		(end 362.553504 -284.127702)
		(width 0.1143)
		(layer "In13.Cu")
		(net "P5E_CPU0_P2_TX_DP<2>")
	)
	(segment
		(start 362.513372 -289.010852)
		(end 362.50118 -289.019488)
		(width 0.1143)
		(layer "In13.Cu")
		(net "P5E_CPU0_P2_TX_DP<2>")
	)
	(segment
		(start 362.549694 -285.102554)
		(end 362.552742 -285.104078)
		(width 0.1143)
		(layer "In13.Cu")
		(net "P5E_CPU0_P2_TX_DP<2>")
	)
	(segment
		(start 362.567982 -293.826692)
		(end 362.550456 -293.836852)
		(width 0.1143)
		(layer "In13.Cu")
		(net "P5E_CPU0_P2_TX_DP<2>")
	)
	(segment
		(start 362.51007 -288.318956)
		(end 362.585254 -288.363152)
		(width 0.1143)
		(layer "In13.Cu")
		(net "P5E_CPU0_P2_TX_DP<2>")
	)
	(segment
		(start 362.583476 -277.630382)
		(end 362.515404 -277.669752)
		(width 0.1143)
		(layer "In13.Cu")
		(net "P5E_CPU0_P2_TX_DP<2>")
	)
	(segment
		(start 362.513372 -289.941)
		(end 362.583222 -289.98164)
		(width 0.1143)
		(layer "In13.Cu")
		(net "P5E_CPU0_P2_TX_DP<2>")
	)
	(segment
		(start 362.583476 -284.11043)
		(end 362.555282 -284.126686)
		(width 0.1143)
		(layer "In13.Cu")
		(net "P5E_CPU0_P2_TX_DP<2>")
	)
	(segment
		(start 362.541058 -281.85745)
		(end 362.583476 -281.881834)
		(width 0.1143)
		(layer "In13.Cu")
		(net "P5E_CPU0_P2_TX_DP<2>")
	)
	(segment
		(start 362.548678 -292.230302)
		(end 362.544614 -292.232588)
		(width 0.1143)
		(layer "In13.Cu")
		(net "P5E_CPU0_P2_TX_DP<2>")
	)
	(segment
		(start 362.550202 -285.749238)
		(end 362.54944 -285.749746)
		(width 0.1143)
		(layer "In13.Cu")
		(net "P5E_CPU0_P2_TX_DP<2>")
	)
	(segment
		(start 362.551726 -286.723582)
		(end 362.585254 -286.74314)
		(width 0.1143)
		(layer "In13.Cu")
		(net "P5E_CPU0_P2_TX_DP<2>")
	)
	(segment
		(start 362.515404 -278.60244)
		(end 362.583476 -278.64181)
		(width 0.1143)
		(layer "In13.Cu")
		(net "P5E_CPU0_P2_TX_DP<2>")
	)
	(segment
		(start 362.551726 -293.203376)
		(end 362.559346 -293.207694)
		(width 0.1143)
		(layer "In13.Cu")
		(net "P5E_CPU0_P2_TX_DP<2>")
	)
	(segment
		(start 363.14253 -296.281348)
		(end 363.14253 -296.309796)
		(width 0.1143)
		(layer "In13.Cu")
		(net "P5E_CPU0_P2_TX_DP<2>")
	)
	(segment
		(start 362.583476 -280.870406)
		(end 362.541058 -280.89479)
		(width 0.1143)
		(layer "In13.Cu")
		(net "P5E_CPU0_P2_TX_DP<2>")
	)
	(segment
		(start 362.552742 -284.12821)
		(end 362.549694 -284.129734)
		(width 0.1143)
		(layer "In13.Cu")
		(net "P5E_CPU0_P2_TX_DP<2>")
	)
	(segment
		(start 362.583222 -289.98164)
		(end 362.583476 -289.98164)
		(width 0.1143)
		(layer "In13.Cu")
		(net "P5E_CPU0_P2_TX_DP<2>")
	)
	(segment
		(start 362.583476 -276.01037)
		(end 362.515404 -276.04974)
		(width 0.1143)
		(layer "In13.Cu")
		(net "P5E_CPU0_P2_TX_DP<2>")
	)
	(segment
		(start 362.550202 -292.229286)
		(end 362.548678 -292.230302)
		(width 0.1143)
		(layer "In13.Cu")
		(net "P5E_CPU0_P2_TX_DP<2>")
	)
	(segment
		(start 362.535978 -293.845742)
		(end 362.50499 -293.86657)
		(width 0.1143)
		(layer "In13.Cu")
		(net "P5E_CPU0_P2_TX_DP<2>")
	)
	(segment
		(start 362.544106 -283.47924)
		(end 362.583476 -283.501846)
		(width 0.1143)
		(layer "In13.Cu")
		(net "P5E_CPU0_P2_TX_DP<2>")
	)
	(segment
		(start 362.550456 -293.836852)
		(end 362.546392 -293.839138)
		(width 0.1143)
		(layer "In13.Cu")
		(net "P5E_CPU0_P2_TX_DP<2>")
	)
	(arc
		(start 362.583476 -280.261822)
		(mid 362.739404 -280.566114)
		(end 362.583476 -280.870406)
		(width 0.1143)
		(layer "In13.Cu")
		(net "P5E_CPU0_P2_TX_DP<2>")
	)
	(arc
		(start 362.595922 -286.751014)
		(mid 362.701479 -286.874634)
		(end 362.739432 -287.0327)
		(width 0.1143)
		(layer "In13.Cu")
		(net "P5E_CPU0_P2_TX_DP<2>")
	)
	(arc
		(start 362.515404 -277.669752)
		(mid 362.508255 -277.674652)
		(end 362.50118 -277.679658)
		(width 0.1143)
		(layer "In13.Cu")
		(net "P5E_CPU0_P2_TX_DP<2>")
	)
	(arc
		(start 362.585254 -288.363152)
		(mid 362.698661 -288.496041)
		(end 362.739432 -288.66592)
		(width 0.1143)
		(layer "In13.Cu")
		(net "P5E_CPU0_P2_TX_DP<2>")
	)
	(arc
		(start 362.583476 -281.881834)
		(mid 362.739404 -282.186126)
		(end 362.583476 -282.490418)
		(width 0.1143)
		(layer "In13.Cu")
		(net "P5E_CPU0_P2_TX_DP<2>")
	)
	(arc
		(start 362.739432 -287.045908)
		(mid 362.698177 -287.216879)
		(end 362.583476 -287.3502)
		(width 0.1143)
		(layer "In13.Cu")
		(net "P5E_CPU0_P2_TX_DP<2>")
	)
	(arc
		(start 362.583476 -275.401786)
		(mid 362.739404 -275.706078)
		(end 362.583476 -276.01037)
		(width 0.1143)
		(layer "In13.Cu")
		(net "P5E_CPU0_P2_TX_DP<2>")
	)
	(arc
		(start 390.603232 -366.93983)
		(mid 390.642234 -367.021945)
		(end 390.689084 -367.09985)
		(width 0.14224)
		(layer "In13.Cu")
		(net "P5E_CPU0_P2_TX_DP<2>")
	)
	(arc
		(start 362.50118 -276.059646)
		(mid 362.273797 -276.516084)
		(end 362.50118 -276.972522)
		(width 0.1143)
		(layer "In13.Cu")
		(net "P5E_CPU0_P2_TX_DP<2>")
	)
	(arc
		(start 362.583476 -289.98164)
		(mid 362.739404 -290.285932)
		(end 362.583476 -290.590224)
		(width 0.1143)
		(layer "In13.Cu")
		(net "P5E_CPU0_P2_TX_DP<2>")
	)
	(arc
		(start 362.515404 -290.629594)
		(mid 362.507226 -290.635237)
		(end 362.499148 -290.641024)
		(width 0.1143)
		(layer "In13.Cu")
		(net "P5E_CPU0_P2_TX_DP<2>")
	)
	(arc
		(start 398.610074 -377.272804)
		(mid 398.690257 -377.370555)
		(end 398.749774 -377.4821)
		(width 0.14224)
		(layer "In13.Cu")
		(net "P5E_CPU0_P2_TX_DP<2>")
	)
	(arc
		(start 362.549694 -284.129734)
		(mid 362.269673 -284.616144)
		(end 362.549694 -285.102554)
		(width 0.1143)
		(layer "In13.Cu")
		(net "P5E_CPU0_P2_TX_DP<2>")
	)
	(arc
		(start 362.515404 -279.289764)
		(mid 362.508255 -279.294664)
		(end 362.50118 -279.29967)
		(width 0.1143)
		(layer "In13.Cu")
		(net "P5E_CPU0_P2_TX_DP<2>")
	)
	(arc
		(start 394.271754 -372.46179)
		(mid 394.316084 -372.524888)
		(end 394.363448 -372.585742)
		(width 0.14224)
		(layer "In13.Cu")
		(net "P5E_CPU0_P2_TX_DP<2>")
	)
	(arc
		(start 362.597954 -293.232078)
		(mid 362.744788 -293.537496)
		(end 362.567982 -293.826692)
		(width 0.1143)
		(layer "In13.Cu")
		(net "P5E_CPU0_P2_TX_DP<2>")
	)
	(arc
		(start 362.739686 -295.22547)
		(mid 362.767214 -295.363774)
		(end 362.845604 -295.480994)
		(width 0.1143)
		(layer "In13.Cu")
		(net "P5E_CPU0_P2_TX_DP<2>")
	)
	(arc
		(start 362.50118 -279.29967)
		(mid 362.273797 -279.756108)
		(end 362.50118 -280.212546)
		(width 0.1143)
		(layer "In13.Cu")
		(net "P5E_CPU0_P2_TX_DP<2>")
	)
	(arc
		(start 362.544106 -282.513024)
		(mid 362.265929 -282.996132)
		(end 362.544106 -283.47924)
		(width 0.1143)
		(layer "In13.Cu")
		(net "P5E_CPU0_P2_TX_DP<2>")
	)
	(arc
		(start 362.50118 -278.592534)
		(mid 362.508254 -278.597541)
		(end 362.515404 -278.60244)
		(width 0.1143)
		(layer "In13.Cu")
		(net "P5E_CPU0_P2_TX_DP<2>")
	)
	(arc
		(start 362.499148 -291.550852)
		(mid 362.507226 -291.556638)
		(end 362.515404 -291.562282)
		(width 0.1143)
		(layer "In13.Cu")
		(net "P5E_CPU0_P2_TX_DP<2>")
	)
	(arc
		(start 362.51261 -292.251384)
		(mid 362.269283 -292.71595)
		(end 362.51261 -293.180516)
		(width 0.1143)
		(layer "In13.Cu")
		(net "P5E_CPU0_P2_TX_DP<2>")
	)
	(arc
		(start 362.54944 -285.75)
		(mid 362.269512 -286.236156)
		(end 362.54944 -286.722312)
		(width 0.1143)
		(layer "In13.Cu")
		(net "P5E_CPU0_P2_TX_DP<2>")
	)
	(arc
		(start 362.541058 -280.89479)
		(mid 362.263912 -281.37612)
		(end 362.541058 -281.85745)
		(width 0.1143)
		(layer "In13.Cu")
		(net "P5E_CPU0_P2_TX_DP<2>")
	)
	(arc
		(start 362.515404 -276.04974)
		(mid 362.508255 -276.05464)
		(end 362.50118 -276.059646)
		(width 0.1143)
		(layer "In13.Cu")
		(net "P5E_CPU0_P2_TX_DP<2>")
	)
	(arc
		(start 362.50118 -275.35251)
		(mid 362.508254 -275.357517)
		(end 362.515404 -275.362416)
		(width 0.1143)
		(layer "In13.Cu")
		(net "P5E_CPU0_P2_TX_DP<2>")
	)
	(arc
		(start 362.583476 -283.501846)
		(mid 362.739404 -283.806138)
		(end 362.583476 -284.11043)
		(width 0.1143)
		(layer "In13.Cu")
		(net "P5E_CPU0_P2_TX_DP<2>")
	)
	(arc
		(start 362.583476 -278.64181)
		(mid 362.739404 -278.946102)
		(end 362.583476 -279.250394)
		(width 0.1143)
		(layer "In13.Cu")
		(net "P5E_CPU0_P2_TX_DP<2>")
	)
	(arc
		(start 362.54436 -293.840408)
		(mid 362.540157 -293.843057)
		(end 362.535978 -293.845742)
		(width 0.1143)
		(layer "In13.Cu")
		(net "P5E_CPU0_P2_TX_DP<2>")
	)
	(arc
		(start 362.732574 -274.155916)
		(mid 362.680525 -274.287435)
		(end 362.583476 -274.390358)
		(width 0.1143)
		(layer "In13.Cu")
		(net "P5E_CPU0_P2_TX_DP<2>")
	)
	(arc
		(start 362.739432 -288.66592)
		(mid 362.698177 -288.836891)
		(end 362.583476 -288.970212)
		(width 0.1143)
		(layer "In13.Cu")
		(net "P5E_CPU0_P2_TX_DP<2>")
	)
	(arc
		(start 398.909286 -377.86818)
		(mid 398.927517 -377.92858)
		(end 398.93367 -377.99137)
		(width 0.14224)
		(layer "In13.Cu")
		(net "P5E_CPU0_P2_TX_DP<2>")
	)
	(arc
		(start 362.584746 -285.12262)
		(mid 362.740902 -285.425338)
		(end 362.586016 -285.728664)
		(width 0.1143)
		(layer "In13.Cu")
		(net "P5E_CPU0_P2_TX_DP<2>")
	)
	(arc
		(start 362.50118 -276.972522)
		(mid 362.508254 -276.977529)
		(end 362.515404 -276.982428)
		(width 0.1143)
		(layer "In13.Cu")
		(net "P5E_CPU0_P2_TX_DP<2>")
	)
	(arc
		(start 362.50118 -289.019488)
		(mid 362.266759 -289.475926)
		(end 362.50118 -289.932364)
		(width 0.1143)
		(layer "In13.Cu")
		(net "P5E_CPU0_P2_TX_DP<2>")
	)
	(arc
		(start 362.50499 -293.86657)
		(mid 362.257259 -294.348489)
		(end 362.535216 -294.813736)
		(width 0.1143)
		(layer "In13.Cu")
		(net "P5E_CPU0_P2_TX_DP<2>")
	)
	(arc
		(start 362.50118 -280.212546)
		(mid 362.508254 -280.217553)
		(end 362.515404 -280.222452)
		(width 0.1143)
		(layer "In13.Cu")
		(net "P5E_CPU0_P2_TX_DP<2>")
	)
	(arc
		(start 363.127544 -295.763188)
		(mid 363.172425 -295.830168)
		(end 363.18825 -295.909238)
		(width 0.1143)
		(layer "In13.Cu")
		(net "P5E_CPU0_P2_TX_DP<2>")
	)
	(arc
		(start 362.583476 -277.021798)
		(mid 362.739404 -277.32609)
		(end 362.583476 -277.630382)
		(width 0.1143)
		(layer "In13.Cu")
		(net "P5E_CPU0_P2_TX_DP<2>")
	)
	(arc
		(start 362.515404 -274.429728)
		(mid 362.508255 -274.434628)
		(end 362.50118 -274.439634)
		(width 0.1143)
		(layer "In13.Cu")
		(net "P5E_CPU0_P2_TX_DP<2>")
	)
	(arc
		(start 362.50118 -274.439634)
		(mid 362.273797 -274.896072)
		(end 362.50118 -275.35251)
		(width 0.1143)
		(layer "In13.Cu")
		(net "P5E_CPU0_P2_TX_DP<2>")
	)
	(arc
		(start 362.499148 -290.641024)
		(mid 362.276264 -291.095938)
		(end 362.499148 -291.550852)
		(width 0.1143)
		(layer "In13.Cu")
		(net "P5E_CPU0_P2_TX_DP<2>")
	)
	(arc
		(start 362.50118 -287.399476)
		(mid 362.330637 -287.598497)
		(end 362.269532 -287.853374)
		(width 0.1143)
		(layer "In13.Cu")
		(net "P5E_CPU0_P2_TX_DP<2>")
	)
	(arc
		(start 362.583476 -294.841676)
		(mid 362.698377 -294.974937)
		(end 362.739686 -295.145968)
		(width 0.1143)
		(layer "In13.Cu")
		(net "P5E_CPU0_P2_TX_DP<2>")
	)
	(arc
		(start 362.583476 -291.601652)
		(mid 362.739404 -291.905944)
		(end 362.583476 -292.210236)
		(width 0.1143)
		(layer "In13.Cu")
		(net "P5E_CPU0_P2_TX_DP<2>")
	)
	(arc
		(start 362.269532 -287.856168)
		(mid 362.333208 -288.116972)
		(end 362.51007 -288.318956)
		(width 0.1143)
		(layer "In13.Cu")
		(net "P5E_CPU0_P2_TX_DP<2>")
	)
	(arc
		(start 363.14253 -300.534832)
		(mid 363.155767 -300.668973)
		(end 363.194854 -300.797976)
		(width 0.14224)
		(layer "In13.Cu")
		(net "P5E_CPU0_P2_TX_DP<2>")
	)
	(arc
		(start 362.50118 -277.679658)
		(mid 362.273797 -278.136096)
		(end 362.50118 -278.592534)
		(width 0.1143)
		(layer "In13.Cu")
		(net "P5E_CPU0_P2_TX_DP<2>")
	)
	(segment
		(start 397.058388 -384.35026)
		(end 397.328898 -384.62077)
		(width 0.12954)
		(layer "F.Cu")
		(net "P5E_CPU0_P2_TX_DP<1>")
	)
	(segment
		(start 361.89793 -270.580104)
		(end 362.364782 -270.846042)
		(width 0.12954)
		(layer "F.Cu")
		(net "P5E_CPU0_P2_TX_DP<1>")
	)
	(segment
		(start 397.328898 -384.62077)
		(end 398.032478 -384.62077)
		(width 0.12954)
		(layer "F.Cu")
		(net "P5E_CPU0_P2_TX_DP<1>")
	)
	(segment
		(start 398.032478 -384.62077)
		(end 398.328388 -384.32486)
		(width 0.12954)
		(layer "F.Cu")
		(net "P5E_CPU0_P2_TX_DP<1>")
	)
	(segment
		(start 396.986252 -381.283464)
		(end 396.986252 -381.710184)
		(width 0.14224)
		(layer "In13.Cu")
		(net "P5E_CPU0_P2_TX_DP<1>")
	)
	(segment
		(start 361.569508 -279.29332)
		(end 361.559602 -279.300686)
		(width 0.1143)
		(layer "In13.Cu")
		(net "P5E_CPU0_P2_TX_DP<1>")
	)
	(segment
		(start 361.612688 -281.864054)
		(end 361.642406 -281.881326)
		(width 0.1143)
		(layer "In13.Cu")
		(net "P5E_CPU0_P2_TX_DP<1>")
	)
	(segment
		(start 361.612688 -292.228016)
		(end 361.60964 -292.22954)
		(width 0.1143)
		(layer "In13.Cu")
		(net "P5E_CPU0_P2_TX_DP<1>")
	)
	(segment
		(start 362.583476 -271.150334)
		(end 362.553758 -271.167352)
		(width 0.1143)
		(layer "In13.Cu")
		(net "P5E_CPU0_P2_TX_DP<1>")
	)
	(segment
		(start 361.611926 -274.408646)
		(end 361.57281 -274.431506)
		(width 0.1143)
		(layer "In13.Cu")
		(net "P5E_CPU0_P2_TX_DP<1>")
	)
	(segment
		(start 361.61345 -292.227508)
		(end 361.612688 -292.228016)
		(width 0.1143)
		(layer "In13.Cu")
		(net "P5E_CPU0_P2_TX_DP<1>")
	)
	(segment
		(start 362.364782 -270.846042)
		(end 362.662724 -270.846042)
		(width 0.1143)
		(layer "In13.Cu")
		(net "P5E_CPU0_P2_TX_DP<1>")
	)
	(segment
		(start 361.611926 -276.028658)
		(end 361.57281 -276.051518)
		(width 0.1143)
		(layer "In13.Cu")
		(net "P5E_CPU0_P2_TX_DP<1>")
	)
	(segment
		(start 361.559602 -280.21153)
		(end 361.569508 -280.218896)
		(width 0.1143)
		(layer "In13.Cu")
		(net "P5E_CPU0_P2_TX_DP<1>")
	)
	(segment
		(start 397.123412 -380.719584)
		(end 397.123412 -381.146304)
		(width 0.14224)
		(layer "In13.Cu")
		(net "P5E_CPU0_P2_TX_DP<1>")
	)
	(segment
		(start 397.123412 -380.018544)
		(end 396.986252 -380.155704)
		(width 0.14224)
		(layer "In13.Cu")
		(net "P5E_CPU0_P2_TX_DP<1>")
	)
	(segment
		(start 361.616244 -293.205916)
		(end 361.643422 -293.221664)
		(width 0.1143)
		(layer "In13.Cu")
		(net "P5E_CPU0_P2_TX_DP<1>")
	)
	(segment
		(start 361.57281 -273.740626)
		(end 361.611926 -273.763486)
		(width 0.1143)
		(layer "In13.Cu")
		(net "P5E_CPU0_P2_TX_DP<1>")
	)
	(segment
		(start 361.575604 -289.94227)
		(end 361.611926 -289.963352)
		(width 0.1143)
		(layer "In13.Cu")
		(net "P5E_CPU0_P2_TX_DP<1>")
	)
	(segment
		(start 361.57281 -275.360638)
		(end 361.611926 -275.383498)
		(width 0.1143)
		(layer "In13.Cu")
		(net "P5E_CPU0_P2_TX_DP<1>")
	)
	(segment
		(start 397.123412 -379.591824)
		(end 397.123412 -380.018544)
		(width 0.14224)
		(layer "In13.Cu")
		(net "P5E_CPU0_P2_TX_DP<1>")
	)
	(segment
		(start 361.611926 -273.763486)
		(end 361.642406 -273.781266)
		(width 0.1143)
		(layer "In13.Cu")
		(net "P5E_CPU0_P2_TX_DP<1>")
	)
	(segment
		(start 396.986252 -379.027944)
		(end 396.986252 -379.454664)
		(width 0.14224)
		(layer "In13.Cu")
		(net "P5E_CPU0_P2_TX_DP<1>")
	)
	(segment
		(start 362.074714 -271.982692)
		(end 362.04271 -272.001488)
		(width 0.1143)
		(layer "In13.Cu")
		(net "P5E_CPU0_P2_TX_DP<1>")
	)
	(segment
		(start 361.329732 -286.236156)
		(end 361.329732 -286.23895)
		(width 0.1143)
		(layer "In13.Cu")
		(net "P5E_CPU0_P2_TX_DP<1>")
	)
	(segment
		(start 398.21993 -384.64109)
		(end 397.349218 -384.64109)
		(width 0.14224)
		(layer "In13.Cu")
		(net "P5E_CPU0_P2_TX_DP<1>")
	)
	(segment
		(start 362.203238 -296.545762)
		(end 362.203238 -296.57421)
		(width 0.1143)
		(layer "In13.Cu")
		(net "P5E_CPU0_P2_TX_DP<1>")
	)
	(segment
		(start 396.986252 -379.454664)
		(end 397.123412 -379.591824)
		(width 0.14224)
		(layer "In13.Cu")
		(net "P5E_CPU0_P2_TX_DP<1>")
	)
	(segment
		(start 362.079286 -271.980152)
		(end 362.074714 -271.982692)
		(width 0.1143)
		(layer "In13.Cu")
		(net "P5E_CPU0_P2_TX_DP<1>")
	)
	(segment
		(start 361.642406 -293.830756)
		(end 361.611926 -293.848536)
		(width 0.1143)
		(layer "In13.Cu")
		(net "P5E_CPU0_P2_TX_DP<1>")
	)
	(segment
		(start 361.611926 -272.788634)
		(end 361.57281 -272.811494)
		(width 0.1143)
		(layer "In13.Cu")
		(net "P5E_CPU0_P2_TX_DP<1>")
	)
	(segment
		(start 361.57281 -278.600662)
		(end 361.611926 -278.623522)
		(width 0.1143)
		(layer "In13.Cu")
		(net "P5E_CPU0_P2_TX_DP<1>")
	)
	(segment
		(start 361.611926 -291.583364)
		(end 361.642406 -291.601144)
		(width 0.1143)
		(layer "In13.Cu")
		(net "P5E_CPU0_P2_TX_DP<1>")
	)
	(segment
		(start 362.081826 -271.978628)
		(end 362.08081 -271.979136)
		(width 0.1143)
		(layer "In13.Cu")
		(net "P5E_CPU0_P2_TX_DP<1>")
	)
	(segment
		(start 361.612688 -284.12821)
		(end 361.611926 -284.128718)
		(width 0.1143)
		(layer "In13.Cu")
		(net "P5E_CPU0_P2_TX_DP<1>")
	)
	(segment
		(start 362.553758 -271.167352)
		(end 362.552488 -271.168114)
		(width 0.1143)
		(layer "In13.Cu")
		(net "P5E_CPU0_P2_TX_DP<1>")
	)
	(segment
		(start 393.208002 -372.650512)
		(end 395.981174 -376.029474)
		(width 0.14224)
		(layer "In13.Cu")
		(net "P5E_CPU0_P2_TX_DP<1>")
	)
	(segment
		(start 396.986252 -381.710184)
		(end 397.123412 -381.847344)
		(width 0.14224)
		(layer "In13.Cu")
		(net "P5E_CPU0_P2_TX_DP<1>")
	)
	(segment
		(start 361.642406 -285.73095)
		(end 361.57281 -285.77159)
		(width 0.1143)
		(layer "In13.Cu")
		(net "P5E_CPU0_P2_TX_DP<1>")
	)
	(segment
		(start 361.612942 -282.508198)
		(end 361.611926 -282.508706)
		(width 0.1143)
		(layer "In13.Cu")
		(net "P5E_CPU0_P2_TX_DP<1>")
	)
	(segment
		(start 361.62615 -288.979864)
		(end 361.61345 -288.987738)
		(width 0.1143)
		(layer "In13.Cu")
		(net "P5E_CPU0_P2_TX_DP<1>")
	)
	(segment
		(start 361.611926 -293.848536)
		(end 361.575604 -293.869618)
		(width 0.1143)
		(layer "In13.Cu")
		(net "P5E_CPU0_P2_TX_DP<1>")
	)
	(segment
		(start 361.611926 -290.608512)
		(end 361.575604 -290.629594)
		(width 0.1143)
		(layer "In13.Cu")
		(net "P5E_CPU0_P2_TX_DP<1>")
	)
	(segment
		(start 361.642406 -272.770854)
		(end 361.611926 -272.788634)
		(width 0.1143)
		(layer "In13.Cu")
		(net "P5E_CPU0_P2_TX_DP<1>")
	)
	(segment
		(start 361.608116 -281.86126)
		(end 361.612688 -281.864054)
		(width 0.1143)
		(layer "In13.Cu")
		(net "P5E_CPU0_P2_TX_DP<1>")
	)
	(segment
		(start 361.575604 -288.322512)
		(end 361.611418 -288.343086)
		(width 0.1143)
		(layer "In13.Cu")
		(net "P5E_CPU0_P2_TX_DP<1>")
	)
	(segment
		(start 361.611926 -284.128718)
		(end 361.611672 -284.128972)
		(width 0.1143)
		(layer "In13.Cu")
		(net "P5E_CPU0_P2_TX_DP<1>")
	)
	(segment
		(start 361.614466 -293.2049)
		(end 361.615228 -293.205408)
		(width 0.1143)
		(layer "In13.Cu")
		(net "P5E_CPU0_P2_TX_DP<1>")
	)
	(segment
		(start 397.349218 -384.64109)
		(end 397.058388 -384.35026)
		(width 0.14224)
		(layer "In13.Cu")
		(net "P5E_CPU0_P2_TX_DP<1>")
	)
	(segment
		(start 398.362424 -383.565654)
		(end 398.362424 -384.498596)
		(width 0.14224)
		(layer "In13.Cu")
		(net "P5E_CPU0_P2_TX_DP<1>")
	)
	(segment
		(start 397.123412 -377.224544)
		(end 397.123412 -377.701556)
		(width 0.14224)
		(layer "In13.Cu")
		(net "P5E_CPU0_P2_TX_DP<1>")
	)
	(segment
		(start 361.575604 -291.562282)
		(end 361.611926 -291.583364)
		(width 0.1143)
		(layer "In13.Cu")
		(net "P5E_CPU0_P2_TX_DP<1>")
	)
	(segment
		(start 361.611926 -277.00351)
		(end 361.642406 -277.02129)
		(width 0.1143)
		(layer "In13.Cu")
		(net "P5E_CPU0_P2_TX_DP<1>")
	)
	(segment
		(start 362.28147 -301.097188)
		(end 389.850376 -367.625122)
		(width 0.14224)
		(layer "In13.Cu")
		(net "P5E_CPU0_P2_TX_DP<1>")
	)
	(segment
		(start 396.986252 -377.838716)
		(end 396.986252 -378.265436)
		(width 0.14224)
		(layer "In13.Cu")
		(net "P5E_CPU0_P2_TX_DP<1>")
	)
	(segment
		(start 361.611926 -282.508706)
		(end 361.608116 -282.510992)
		(width 0.1143)
		(layer "In13.Cu")
		(net "P5E_CPU0_P2_TX_DP<1>")
	)
	(segment
		(start 362.082588 -271.97812)
		(end 362.081826 -271.978628)
		(width 0.1143)
		(layer "In13.Cu")
		(net "P5E_CPU0_P2_TX_DP<1>")
	)
	(segment
		(start 361.642406 -290.590732)
		(end 361.611926 -290.608512)
		(width 0.1143)
		(layer "In13.Cu")
		(net "P5E_CPU0_P2_TX_DP<1>")
	)
	(segment
		(start 361.612434 -288.988246)
		(end 361.574334 -289.010344)
		(width 0.1143)
		(layer "In13.Cu")
		(net "P5E_CPU0_P2_TX_DP<1>")
	)
	(segment
		(start 397.123412 -381.146304)
		(end 396.986252 -381.283464)
		(width 0.14224)
		(layer "In13.Cu")
		(net "P5E_CPU0_P2_TX_DP<1>")
	)
	(segment
		(start 362.113576 -271.96034)
		(end 362.082588 -271.97812)
		(width 0.1143)
		(layer "In13.Cu")
		(net "P5E_CPU0_P2_TX_DP<1>")
	)
	(segment
		(start 397.123412 -378.402596)
		(end 397.123412 -378.890784)
		(width 0.14224)
		(layer "In13.Cu")
		(net "P5E_CPU0_P2_TX_DP<1>")
	)
	(segment
		(start 361.642406 -274.390866)
		(end 361.611926 -274.408646)
		(width 0.1143)
		(layer "In13.Cu")
		(net "P5E_CPU0_P2_TX_DP<1>")
	)
	(segment
		(start 361.611926 -278.623522)
		(end 361.642406 -278.641302)
		(width 0.1143)
		(layer "In13.Cu")
		(net "P5E_CPU0_P2_TX_DP<1>")
	)
	(segment
		(start 361.643422 -292.210236)
		(end 361.615228 -292.226492)
		(width 0.1143)
		(layer "In13.Cu")
		(net "P5E_CPU0_P2_TX_DP<1>")
	)
	(segment
		(start 398.362424 -384.498596)
		(end 398.21993 -384.64109)
		(width 0.14224)
		(layer "In13.Cu")
		(net "P5E_CPU0_P2_TX_DP<1>")
	)
	(segment
		(start 361.799378 -295.145968)
		(end 361.799632 -295.145968)
		(width 0.1143)
		(layer "In13.Cu")
		(net "P5E_CPU0_P2_TX_DP<1>")
	)
	(segment
		(start 397.123412 -381.847344)
		(end 397.123412 -382.023112)
		(width 0.14224)
		(layer "In13.Cu")
		(net "P5E_CPU0_P2_TX_DP<1>")
	)
	(segment
		(start 361.611926 -275.383498)
		(end 361.642406 -275.401278)
		(width 0.1143)
		(layer "In13.Cu")
		(net "P5E_CPU0_P2_TX_DP<1>")
	)
	(segment
		(start 361.569508 -280.218896)
		(end 361.642406 -280.261568)
		(width 0.1143)
		(layer "In13.Cu")
		(net "P5E_CPU0_P2_TX_DP<1>")
	)
	(segment
		(start 361.642406 -277.63089)
		(end 361.611926 -277.64867)
		(width 0.1143)
		(layer "In13.Cu")
		(net "P5E_CPU0_P2_TX_DP<1>")
	)
	(segment
		(start 361.61345 -293.204392)
		(end 361.614466 -293.2049)
		(width 0.1143)
		(layer "In13.Cu")
		(net "P5E_CPU0_P2_TX_DP<1>")
	)
	(segment
		(start 395.981174 -376.029474)
		(end 397.086074 -377.134374)
		(width 0.14224)
		(layer "In13.Cu")
		(net "P5E_CPU0_P2_TX_DP<1>")
	)
	(segment
		(start 361.611418 -288.343086)
		(end 361.616498 -288.346134)
		(width 0.1143)
		(layer "In13.Cu")
		(net "P5E_CPU0_P2_TX_DP<1>")
	)
	(segment
		(start 396.986252 -380.582424)
		(end 397.123412 -380.719584)
		(width 0.14224)
		(layer "In13.Cu")
		(net "P5E_CPU0_P2_TX_DP<1>")
	)
	(segment
		(start 361.573318 -286.700976)
		(end 361.644438 -286.742378)
		(width 0.1143)
		(layer "In13.Cu")
		(net "P5E_CPU0_P2_TX_DP<1>")
	)
	(segment
		(start 361.611926 -277.64867)
		(end 361.57281 -277.67153)
		(width 0.1143)
		(layer "In13.Cu")
		(net "P5E_CPU0_P2_TX_DP<1>")
	)
	(segment
		(start 389.850376 -367.625122)
		(end 393.208002 -372.650512)
		(width 0.14224)
		(layer "In13.Cu")
		(net "P5E_CPU0_P2_TX_DP<1>")
	)
	(segment
		(start 361.611926 -285.10357)
		(end 361.642406 -285.12135)
		(width 0.1143)
		(layer "In13.Cu")
		(net "P5E_CPU0_P2_TX_DP<1>")
	)
	(segment
		(start 361.608116 -283.481272)
		(end 361.612688 -283.484066)
		(width 0.1143)
		(layer "In13.Cu")
		(net "P5E_CPU0_P2_TX_DP<1>")
	)
	(segment
		(start 397.123412 -377.701556)
		(end 396.986252 -377.838716)
		(width 0.14224)
		(layer "In13.Cu")
		(net "P5E_CPU0_P2_TX_DP<1>")
	)
	(segment
		(start 362.044234 -295.61155)
		(end 362.051092 -295.61536)
		(width 0.1143)
		(layer "In13.Cu")
		(net "P5E_CPU0_P2_TX_DP<1>")
	)
	(segment
		(start 361.611926 -289.963352)
		(end 361.642406 -289.981132)
		(width 0.1143)
		(layer "In13.Cu")
		(net "P5E_CPU0_P2_TX_DP<1>")
	)
	(segment
		(start 362.662724 -270.846042)
		(end 362.732574 -270.915892)
		(width 0.1143)
		(layer "In13.Cu")
		(net "P5E_CPU0_P2_TX_DP<1>")
	)
	(segment
		(start 361.642406 -280.870914)
		(end 361.611926 -280.888694)
		(width 0.1143)
		(layer "In13.Cu")
		(net "P5E_CPU0_P2_TX_DP<1>")
	)
	(segment
		(start 361.642406 -280.261568)
		(end 361.642406 -280.261314)
		(width 0.1143)
		(layer "In13.Cu")
		(net "P5E_CPU0_P2_TX_DP<1>")
	)
	(segment
		(start 361.614466 -292.227)
		(end 361.61345 -292.227508)
		(width 0.1143)
		(layer "In13.Cu")
		(net "P5E_CPU0_P2_TX_DP<1>")
	)
	(segment
		(start 361.642406 -279.250902)
		(end 361.569508 -279.29332)
		(width 0.1143)
		(layer "In13.Cu")
		(net "P5E_CPU0_P2_TX_DP<1>")
	)
	(segment
		(start 361.61345 -288.987738)
		(end 361.612434 -288.988246)
		(width 0.1143)
		(layer "In13.Cu")
		(net "P5E_CPU0_P2_TX_DP<1>")
	)
	(segment
		(start 361.642406 -276.010878)
		(end 361.611926 -276.028658)
		(width 0.1143)
		(layer "In13.Cu")
		(net "P5E_CPU0_P2_TX_DP<1>")
	)
	(segment
		(start 362.552488 -271.168114)
		(end 362.551726 -271.168622)
		(width 0.1143)
		(layer "In13.Cu")
		(net "P5E_CPU0_P2_TX_DP<1>")
	)
	(segment
		(start 361.611926 -280.888694)
		(end 361.608116 -280.89098)
		(width 0.1143)
		(layer "In13.Cu")
		(net "P5E_CPU0_P2_TX_DP<1>")
	)
	(segment
		(start 362.237782 -295.806114)
		(end 362.23829 -295.80713)
		(width 0.1143)
		(layer "In13.Cu")
		(net "P5E_CPU0_P2_TX_DP<1>")
	)
	(segment
		(start 361.611926 -294.823388)
		(end 361.642406 -294.841168)
		(width 0.1143)
		(layer "In13.Cu")
		(net "P5E_CPU0_P2_TX_DP<1>")
	)
	(segment
		(start 361.642406 -284.110938)
		(end 361.612688 -284.12821)
		(width 0.1143)
		(layer "In13.Cu")
		(net "P5E_CPU0_P2_TX_DP<1>")
	)
	(segment
		(start 361.57281 -276.98065)
		(end 361.611926 -277.00351)
		(width 0.1143)
		(layer "In13.Cu")
		(net "P5E_CPU0_P2_TX_DP<1>")
	)
	(segment
		(start 361.611672 -285.10357)
		(end 361.611926 -285.10357)
		(width 0.1143)
		(layer "In13.Cu")
		(net "P5E_CPU0_P2_TX_DP<1>")
	)
	(segment
		(start 362.248958 -295.85793)
		(end 362.248958 -296.500042)
		(width 0.1143)
		(layer "In13.Cu")
		(net "P5E_CPU0_P2_TX_DP<1>")
	)
	(segment
		(start 361.329478 -286.236156)
		(end 361.329732 -286.236156)
		(width 0.1143)
		(layer "In13.Cu")
		(net "P5E_CPU0_P2_TX_DP<1>")
	)
	(segment
		(start 362.08081 -271.979136)
		(end 362.079286 -271.980152)
		(width 0.1143)
		(layer "In13.Cu")
		(net "P5E_CPU0_P2_TX_DP<1>")
	)
	(segment
		(start 396.986252 -380.155704)
		(end 396.986252 -380.582424)
		(width 0.14224)
		(layer "In13.Cu")
		(net "P5E_CPU0_P2_TX_DP<1>")
	)
	(segment
		(start 361.615228 -292.226492)
		(end 361.614466 -292.227)
		(width 0.1143)
		(layer "In13.Cu")
		(net "P5E_CPU0_P2_TX_DP<1>")
	)
	(segment
		(start 362.248958 -296.500042)
		(end 362.203238 -296.545762)
		(width 0.1143)
		(layer "In13.Cu")
		(net "P5E_CPU0_P2_TX_DP<1>")
	)
	(segment
		(start 361.60964 -293.20236)
		(end 361.612688 -293.203884)
		(width 0.1143)
		(layer "In13.Cu")
		(net "P5E_CPU0_P2_TX_DP<1>")
	)
	(segment
		(start 396.986252 -378.265436)
		(end 397.123412 -378.402596)
		(width 0.14224)
		(layer "In13.Cu")
		(net "P5E_CPU0_P2_TX_DP<1>")
	)
	(segment
		(start 362.551726 -271.168622)
		(end 362.551218 -271.168876)
		(width 0.1143)
		(layer "In13.Cu")
		(net "P5E_CPU0_P2_TX_DP<1>")
	)
	(segment
		(start 397.300704 -382.451356)
		(end 398.325086 -383.475738)
		(width 0.14224)
		(layer "In13.Cu")
		(net "P5E_CPU0_P2_TX_DP<1>")
	)
	(segment
		(start 361.612688 -283.484066)
		(end 361.642406 -283.501338)
		(width 0.1143)
		(layer "In13.Cu")
		(net "P5E_CPU0_P2_TX_DP<1>")
	)
	(segment
		(start 362.051092 -295.61536)
		(end 362.112052 -295.651174)
		(width 0.1143)
		(layer "In13.Cu")
		(net "P5E_CPU0_P2_TX_DP<1>")
	)
	(segment
		(start 362.551218 -271.168876)
		(end 362.515404 -271.189704)
		(width 0.1143)
		(layer "In13.Cu")
		(net "P5E_CPU0_P2_TX_DP<1>")
	)
	(segment
		(start 362.203238 -296.57421)
		(end 362.203238 -300.703234)
		(width 0.14224)
		(layer "In13.Cu")
		(net "P5E_CPU0_P2_TX_DP<1>")
	)
	(segment
		(start 361.615228 -293.205408)
		(end 361.616244 -293.205916)
		(width 0.1143)
		(layer "In13.Cu")
		(net "P5E_CPU0_P2_TX_DP<1>")
	)
	(segment
		(start 361.575604 -294.802306)
		(end 361.611926 -294.823388)
		(width 0.1143)
		(layer "In13.Cu")
		(net "P5E_CPU0_P2_TX_DP<1>")
	)
	(segment
		(start 397.123412 -378.890784)
		(end 396.986252 -379.027944)
		(width 0.14224)
		(layer "In13.Cu")
		(net "P5E_CPU0_P2_TX_DP<1>")
	)
	(segment
		(start 361.642406 -287.350708)
		(end 361.578398 -287.388046)
		(width 0.1143)
		(layer "In13.Cu")
		(net "P5E_CPU0_P2_TX_DP<1>")
	)
	(segment
		(start 361.612688 -293.203884)
		(end 361.61345 -293.204392)
		(width 0.1143)
		(layer "In13.Cu")
		(net "P5E_CPU0_P2_TX_DP<1>")
	)
	(segment
		(start 361.642406 -282.490926)
		(end 361.612942 -282.508198)
		(width 0.1143)
		(layer "In13.Cu")
		(net "P5E_CPU0_P2_TX_DP<1>")
	)
	(arc
		(start 361.799378 -291.905944)
		(mid 361.758123 -292.076915)
		(end 361.643422 -292.210236)
		(width 0.1143)
		(layer "In13.Cu")
		(net "P5E_CPU0_P2_TX_DP<1>")
	)
	(arc
		(start 361.574334 -289.010344)
		(mid 361.329514 -289.476665)
		(end 361.575604 -289.94227)
		(width 0.1143)
		(layer "In13.Cu")
		(net "P5E_CPU0_P2_TX_DP<1>")
	)
	(arc
		(start 361.57281 -272.811494)
		(mid 361.329483 -273.27606)
		(end 361.57281 -273.740626)
		(width 0.1143)
		(layer "In13.Cu")
		(net "P5E_CPU0_P2_TX_DP<1>")
	)
	(arc
		(start 361.642406 -278.641302)
		(mid 361.799383 -278.946102)
		(end 361.642406 -279.250902)
		(width 0.1143)
		(layer "In13.Cu")
		(net "P5E_CPU0_P2_TX_DP<1>")
	)
	(arc
		(start 361.799632 -295.145968)
		(mid 361.86445 -295.408957)
		(end 362.044234 -295.61155)
		(width 0.1143)
		(layer "In13.Cu")
		(net "P5E_CPU0_P2_TX_DP<1>")
	)
	(arc
		(start 361.642406 -275.401278)
		(mid 361.799383 -275.706078)
		(end 361.642406 -276.010878)
		(width 0.1143)
		(layer "In13.Cu")
		(net "P5E_CPU0_P2_TX_DP<1>")
	)
	(arc
		(start 361.575604 -293.869618)
		(mid 361.329714 -294.335962)
		(end 361.575604 -294.802306)
		(width 0.1143)
		(layer "In13.Cu")
		(net "P5E_CPU0_P2_TX_DP<1>")
	)
	(arc
		(start 361.611672 -284.128972)
		(mid 361.331908 -284.616334)
		(end 361.611672 -285.10357)
		(width 0.1143)
		(layer "In13.Cu")
		(net "P5E_CPU0_P2_TX_DP<1>")
	)
	(arc
		(start 361.60964 -292.22954)
		(mid 361.329619 -292.71595)
		(end 361.60964 -293.20236)
		(width 0.1143)
		(layer "In13.Cu")
		(net "P5E_CPU0_P2_TX_DP<1>")
	)
	(arc
		(start 361.57281 -277.67153)
		(mid 361.329483 -278.136096)
		(end 361.57281 -278.600662)
		(width 0.1143)
		(layer "In13.Cu")
		(net "P5E_CPU0_P2_TX_DP<1>")
	)
	(arc
		(start 361.608116 -282.510992)
		(mid 361.329697 -282.996132)
		(end 361.608116 -283.481272)
		(width 0.1143)
		(layer "In13.Cu")
		(net "P5E_CPU0_P2_TX_DP<1>")
	)
	(arc
		(start 361.642406 -273.781266)
		(mid 361.799383 -274.086066)
		(end 361.642406 -274.390866)
		(width 0.1143)
		(layer "In13.Cu")
		(net "P5E_CPU0_P2_TX_DP<1>")
	)
	(arc
		(start 362.203238 -300.703234)
		(mid 362.22297 -300.904058)
		(end 362.28147 -301.097188)
		(width 0.14224)
		(layer "In13.Cu")
		(net "P5E_CPU0_P2_TX_DP<1>")
	)
	(arc
		(start 361.57281 -285.77159)
		(mid 361.393997 -285.97394)
		(end 361.329478 -286.236156)
		(width 0.1143)
		(layer "In13.Cu")
		(net "P5E_CPU0_P2_TX_DP<1>")
	)
	(arc
		(start 361.643422 -293.221664)
		(mid 361.758098 -293.354998)
		(end 361.799378 -293.525956)
		(width 0.1143)
		(layer "In13.Cu")
		(net "P5E_CPU0_P2_TX_DP<1>")
	)
	(arc
		(start 361.642406 -281.881326)
		(mid 361.799383 -282.186126)
		(end 361.642406 -282.490926)
		(width 0.1143)
		(layer "In13.Cu")
		(net "P5E_CPU0_P2_TX_DP<1>")
	)
	(arc
		(start 362.732574 -270.915892)
		(mid 362.680525 -271.047411)
		(end 362.583476 -271.150334)
		(width 0.1143)
		(layer "In13.Cu")
		(net "P5E_CPU0_P2_TX_DP<1>")
	)
	(arc
		(start 398.325086 -383.475738)
		(mid 398.352705 -383.516978)
		(end 398.362424 -383.565654)
		(width 0.14224)
		(layer "In13.Cu")
		(net "P5E_CPU0_P2_TX_DP<1>")
	)
	(arc
		(start 361.329732 -286.23895)
		(mid 361.39435 -286.500112)
		(end 361.573318 -286.700976)
		(width 0.1143)
		(layer "In13.Cu")
		(net "P5E_CPU0_P2_TX_DP<1>")
	)
	(arc
		(start 362.515404 -271.189704)
		(mid 362.503869 -271.197943)
		(end 362.492544 -271.206468)
		(width 0.1143)
		(layer "In13.Cu")
		(net "P5E_CPU0_P2_TX_DP<1>")
	)
	(arc
		(start 397.123412 -382.023112)
		(mid 397.169491 -382.254855)
		(end 397.300704 -382.451356)
		(width 0.14224)
		(layer "In13.Cu")
		(net "P5E_CPU0_P2_TX_DP<1>")
	)
	(arc
		(start 361.642406 -277.02129)
		(mid 361.799383 -277.32609)
		(end 361.642406 -277.63089)
		(width 0.1143)
		(layer "In13.Cu")
		(net "P5E_CPU0_P2_TX_DP<1>")
	)
	(arc
		(start 361.642406 -283.501338)
		(mid 361.799383 -283.806138)
		(end 361.642406 -284.110938)
		(width 0.1143)
		(layer "In13.Cu")
		(net "P5E_CPU0_P2_TX_DP<1>")
	)
	(arc
		(start 361.57281 -274.431506)
		(mid 361.329483 -274.896072)
		(end 361.57281 -275.360638)
		(width 0.1143)
		(layer "In13.Cu")
		(net "P5E_CPU0_P2_TX_DP<1>")
	)
	(arc
		(start 362.27004 -271.639284)
		(mid 362.269466 -271.647911)
		(end 362.269278 -271.656556)
		(width 0.1143)
		(layer "In13.Cu")
		(net "P5E_CPU0_P2_TX_DP<1>")
	)
	(arc
		(start 361.799378 -293.525956)
		(mid 361.757829 -293.697378)
		(end 361.642406 -293.830756)
		(width 0.1143)
		(layer "In13.Cu")
		(net "P5E_CPU0_P2_TX_DP<1>")
	)
	(arc
		(start 361.642406 -289.981132)
		(mid 361.799383 -290.285932)
		(end 361.642406 -290.590732)
		(width 0.1143)
		(layer "In13.Cu")
		(net "P5E_CPU0_P2_TX_DP<1>")
	)
	(arc
		(start 361.559602 -279.300686)
		(mid 361.328003 -279.756108)
		(end 361.559602 -280.21153)
		(width 0.1143)
		(layer "In13.Cu")
		(net "P5E_CPU0_P2_TX_DP<1>")
	)
	(arc
		(start 362.269278 -271.656556)
		(mid 362.225133 -271.825707)
		(end 362.113576 -271.96034)
		(width 0.1143)
		(layer "In13.Cu")
		(net "P5E_CPU0_P2_TX_DP<1>")
	)
	(arc
		(start 361.57281 -276.051518)
		(mid 361.329483 -276.516084)
		(end 361.57281 -276.98065)
		(width 0.1143)
		(layer "In13.Cu")
		(net "P5E_CPU0_P2_TX_DP<1>")
	)
	(arc
		(start 361.644438 -286.742378)
		(mid 361.758367 -286.875525)
		(end 361.799378 -287.045908)
		(width 0.1143)
		(layer "In13.Cu")
		(net "P5E_CPU0_P2_TX_DP<1>")
	)
	(arc
		(start 361.575604 -290.629594)
		(mid 361.329714 -291.095938)
		(end 361.575604 -291.562282)
		(width 0.1143)
		(layer "In13.Cu")
		(net "P5E_CPU0_P2_TX_DP<1>")
	)
	(arc
		(start 361.642406 -280.261314)
		(mid 361.799383 -280.566114)
		(end 361.642406 -280.870914)
		(width 0.1143)
		(layer "In13.Cu")
		(net "P5E_CPU0_P2_TX_DP<1>")
	)
	(arc
		(start 361.642406 -285.12135)
		(mid 361.799383 -285.42615)
		(end 361.642406 -285.73095)
		(width 0.1143)
		(layer "In13.Cu")
		(net "P5E_CPU0_P2_TX_DP<1>")
	)
	(arc
		(start 362.492544 -271.206468)
		(mid 362.338248 -271.400757)
		(end 362.27004 -271.639284)
		(width 0.1143)
		(layer "In13.Cu")
		(net "P5E_CPU0_P2_TX_DP<1>")
	)
	(arc
		(start 362.04271 -272.001488)
		(mid 361.863897 -272.203838)
		(end 361.799378 -272.466054)
		(width 0.1143)
		(layer "In13.Cu")
		(net "P5E_CPU0_P2_TX_DP<1>")
	)
	(arc
		(start 361.578398 -287.388046)
		(mid 361.395736 -287.591127)
		(end 361.329732 -287.856168)
		(width 0.1143)
		(layer "In13.Cu")
		(net "P5E_CPU0_P2_TX_DP<1>")
	)
	(arc
		(start 362.112052 -295.651174)
		(mid 362.185451 -295.720097)
		(end 362.237782 -295.806114)
		(width 0.1143)
		(layer "In13.Cu")
		(net "P5E_CPU0_P2_TX_DP<1>")
	)
	(arc
		(start 361.642406 -291.601144)
		(mid 361.757833 -291.73452)
		(end 361.799378 -291.905944)
		(width 0.1143)
		(layer "In13.Cu")
		(net "P5E_CPU0_P2_TX_DP<1>")
	)
	(arc
		(start 361.329732 -287.856168)
		(mid 361.394968 -288.119759)
		(end 361.575604 -288.322512)
		(width 0.1143)
		(layer "In13.Cu")
		(net "P5E_CPU0_P2_TX_DP<1>")
	)
	(arc
		(start 397.086074 -377.134374)
		(mid 397.113717 -377.175744)
		(end 397.123412 -377.224544)
		(width 0.14224)
		(layer "In13.Cu")
		(net "P5E_CPU0_P2_TX_DP<1>")
	)
	(arc
		(start 361.616498 -288.346134)
		(mid 361.800183 -288.660279)
		(end 361.62615 -288.979864)
		(width 0.1143)
		(layer "In13.Cu")
		(net "P5E_CPU0_P2_TX_DP<1>")
	)
	(arc
		(start 361.799378 -272.466054)
		(mid 361.757829 -272.637476)
		(end 361.642406 -272.770854)
		(width 0.1143)
		(layer "In13.Cu")
		(net "P5E_CPU0_P2_TX_DP<1>")
	)
	(arc
		(start 361.642406 -294.841168)
		(mid 361.757833 -294.974544)
		(end 361.799378 -295.145968)
		(width 0.1143)
		(layer "In13.Cu")
		(net "P5E_CPU0_P2_TX_DP<1>")
	)
	(arc
		(start 362.23829 -295.80713)
		(mid 362.24622 -295.831984)
		(end 362.248958 -295.85793)
		(width 0.1143)
		(layer "In13.Cu")
		(net "P5E_CPU0_P2_TX_DP<1>")
	)
	(arc
		(start 361.799378 -287.045908)
		(mid 361.757829 -287.21733)
		(end 361.642406 -287.350708)
		(width 0.1143)
		(layer "In13.Cu")
		(net "P5E_CPU0_P2_TX_DP<1>")
	)
	(arc
		(start 361.608116 -280.89098)
		(mid 361.329697 -281.37612)
		(end 361.608116 -281.86126)
		(width 0.1143)
		(layer "In13.Cu")
		(net "P5E_CPU0_P2_TX_DP<1>")
	)
	(segment
		(start 372.707916 -271.39011)
		(end 373.174768 -271.656048)
		(width 0.12954)
		(layer "F.Cu")
		(net "P5E_CPU0_P2_TX_DP<15>")
	)
	(segment
		(start 426.63491 -388.149338)
		(end 425.93133 -388.149338)
		(width 0.12954)
		(layer "F.Cu")
		(net "P5E_CPU0_P2_TX_DP<15>")
	)
	(segment
		(start 425.93133 -388.149338)
		(end 425.63542 -387.853428)
		(width 0.12954)
		(layer "F.Cu")
		(net "P5E_CPU0_P2_TX_DP<15>")
	)
	(segment
		(start 426.90542 -387.878828)
		(end 426.63491 -388.149338)
		(width 0.12954)
		(layer "F.Cu")
		(net "P5E_CPU0_P2_TX_DP<15>")
	)
	(segment
		(start 374.8024 -279.250902)
		(end 374.77192 -279.268682)
		(width 0.1143)
		(layer "In13.Cu")
		(net "P5E_CPU0_P2_TX_DP<15>")
	)
	(segment
		(start 374.8024 -292.210744)
		(end 374.77192 -292.228524)
		(width 0.1143)
		(layer "In13.Cu")
		(net "P5E_CPU0_P2_TX_DP<15>")
	)
	(segment
		(start 428.769018 -387.726682)
		(end 428.36338 -388.13232)
		(width 0.14224)
		(layer "In13.Cu")
		(net "P5E_CPU0_P2_TX_DP<15>")
	)
	(segment
		(start 374.77192 -293.848536)
		(end 374.732804 -293.871396)
		(width 0.1143)
		(layer "In13.Cu")
		(net "P5E_CPU0_P2_TX_DP<15>")
	)
	(segment
		(start 406.597612 -366.588548)
		(end 418.807138 -371.645942)
		(width 0.14224)
		(layer "In13.Cu")
		(net "P5E_CPU0_P2_TX_DP<15>")
	)
	(segment
		(start 374.732804 -294.800528)
		(end 374.733312 -294.800782)
		(width 0.1143)
		(layer "In13.Cu")
		(net "P5E_CPU0_P2_TX_DP<15>")
	)
	(segment
		(start 374.959372 -295.145968)
		(end 374.959372 -295.32961)
		(width 0.1143)
		(layer "In13.Cu")
		(net "P5E_CPU0_P2_TX_DP<15>")
	)
	(segment
		(start 374.732804 -293.180516)
		(end 374.77192 -293.203376)
		(width 0.1143)
		(layer "In13.Cu")
		(net "P5E_CPU0_P2_TX_DP<15>")
	)
	(segment
		(start 422.914064 -371.783102)
		(end 423.340784 -371.783102)
		(width 0.14224)
		(layer "In13.Cu")
		(net "P5E_CPU0_P2_TX_DP<15>")
	)
	(segment
		(start 373.47271 -271.656048)
		(end 373.555514 -271.738852)
		(width 0.1143)
		(layer "In13.Cu")
		(net "P5E_CPU0_P2_TX_DP<15>")
	)
	(segment
		(start 374.77192 -273.763486)
		(end 374.8024 -273.781266)
		(width 0.1143)
		(layer "In13.Cu")
		(net "P5E_CPU0_P2_TX_DP<15>")
	)
	(segment
		(start 374.732804 -276.98065)
		(end 374.77192 -277.00351)
		(width 0.1143)
		(layer "In13.Cu")
		(net "P5E_CPU0_P2_TX_DP<15>")
	)
	(segment
		(start 374.77192 -280.888694)
		(end 374.732804 -280.911554)
		(width 0.1143)
		(layer "In13.Cu")
		(net "P5E_CPU0_P2_TX_DP<15>")
	)
	(segment
		(start 374.959372 -295.32961)
		(end 375.009664 -295.459404)
		(width 0.1143)
		(layer "In13.Cu")
		(net "P5E_CPU0_P2_TX_DP<15>")
	)
	(segment
		(start 374.8024 -285.73095)
		(end 374.77192 -285.74873)
		(width 0.1143)
		(layer "In13.Cu")
		(net "P5E_CPU0_P2_TX_DP<15>")
	)
	(segment
		(start 374.77192 -276.028658)
		(end 374.732804 -276.051518)
		(width 0.1143)
		(layer "In13.Cu")
		(net "P5E_CPU0_P2_TX_DP<15>")
	)
	(segment
		(start 374.77192 -285.74873)
		(end 374.732804 -285.77159)
		(width 0.1143)
		(layer "In13.Cu")
		(net "P5E_CPU0_P2_TX_DP<15>")
	)
	(segment
		(start 425.313094 -371.68328)
		(end 426.75937 -373.129556)
		(width 0.14224)
		(layer "In13.Cu")
		(net "P5E_CPU0_P2_TX_DP<15>")
	)
	(segment
		(start 419.530784 -371.783102)
		(end 419.957504 -371.783102)
		(width 0.14224)
		(layer "In13.Cu")
		(net "P5E_CPU0_P2_TX_DP<15>")
	)
	(segment
		(start 420.094664 -371.645942)
		(end 420.521384 -371.645942)
		(width 0.14224)
		(layer "In13.Cu")
		(net "P5E_CPU0_P2_TX_DP<15>")
	)
	(segment
		(start 423.340784 -371.783102)
		(end 423.477944 -371.645942)
		(width 0.14224)
		(layer "In13.Cu")
		(net "P5E_CPU0_P2_TX_DP<15>")
	)
	(segment
		(start 374.732804 -288.320734)
		(end 374.77192 -288.343594)
		(width 0.1143)
		(layer "In13.Cu")
		(net "P5E_CPU0_P2_TX_DP<15>")
	)
	(segment
		(start 405.766524 -366.033558)
		(end 406.597612 -366.588548)
		(width 0.14224)
		(layer "In13.Cu")
		(net "P5E_CPU0_P2_TX_DP<15>")
	)
	(segment
		(start 374.77192 -290.608512)
		(end 374.732804 -290.631372)
		(width 0.1143)
		(layer "In13.Cu")
		(net "P5E_CPU0_P2_TX_DP<15>")
	)
	(segment
		(start 374.8024 -277.63089)
		(end 374.77192 -277.64867)
		(width 0.1143)
		(layer "In13.Cu")
		(net "P5E_CPU0_P2_TX_DP<15>")
	)
	(segment
		(start 374.77192 -274.408646)
		(end 374.732804 -274.431506)
		(width 0.1143)
		(layer "In13.Cu")
		(net "P5E_CPU0_P2_TX_DP<15>")
	)
	(segment
		(start 374.77192 -284.128718)
		(end 374.732804 -284.151578)
		(width 0.1143)
		(layer "In13.Cu")
		(net "P5E_CPU0_P2_TX_DP<15>")
	)
	(segment
		(start 374.732804 -286.700722)
		(end 374.77192 -286.723582)
		(width 0.1143)
		(layer "In13.Cu")
		(net "P5E_CPU0_P2_TX_DP<15>")
	)
	(segment
		(start 374.01754 -272.441924)
		(end 374.01754 -272.463006)
		(width 0.1143)
		(layer "In13.Cu")
		(net "P5E_CPU0_P2_TX_DP<15>")
	)
	(segment
		(start 374.732804 -273.740626)
		(end 374.77192 -273.763486)
		(width 0.1143)
		(layer "In13.Cu")
		(net "P5E_CPU0_P2_TX_DP<15>")
	)
	(segment
		(start 374.8024 -276.010878)
		(end 374.77192 -276.028658)
		(width 0.1143)
		(layer "In13.Cu")
		(net "P5E_CPU0_P2_TX_DP<15>")
	)
	(segment
		(start 374.77192 -286.723582)
		(end 374.804432 -286.742378)
		(width 0.1143)
		(layer "In13.Cu")
		(net "P5E_CPU0_P2_TX_DP<15>")
	)
	(segment
		(start 374.8024 -282.490926)
		(end 374.77192 -282.508706)
		(width 0.1143)
		(layer "In13.Cu")
		(net "P5E_CPU0_P2_TX_DP<15>")
	)
	(segment
		(start 428.806356 -376.99823)
		(end 428.806356 -387.636766)
		(width 0.14224)
		(layer "In13.Cu")
		(net "P5E_CPU0_P2_TX_DP<15>")
	)
	(segment
		(start 421.649144 -371.645942)
		(end 421.786304 -371.783102)
		(width 0.14224)
		(layer "In13.Cu")
		(net "P5E_CPU0_P2_TX_DP<15>")
	)
	(segment
		(start 374.8024 -280.870914)
		(end 374.77192 -280.888694)
		(width 0.1143)
		(layer "In13.Cu")
		(net "P5E_CPU0_P2_TX_DP<15>")
	)
	(segment
		(start 375.4247 -296.61231)
		(end 375.4247 -296.88155)
		(width 0.14224)
		(layer "In13.Cu")
		(net "P5E_CPU0_P2_TX_DP<15>")
	)
	(segment
		(start 374.77192 -281.863546)
		(end 374.8024 -281.881326)
		(width 0.1143)
		(layer "In13.Cu")
		(net "P5E_CPU0_P2_TX_DP<15>")
	)
	(segment
		(start 374.732804 -283.460698)
		(end 374.77192 -283.483558)
		(width 0.1143)
		(layer "In13.Cu")
		(net "P5E_CPU0_P2_TX_DP<15>")
	)
	(segment
		(start 374.8024 -287.350708)
		(end 374.735344 -287.389824)
		(width 0.1143)
		(layer "In13.Cu")
		(net "P5E_CPU0_P2_TX_DP<15>")
	)
	(segment
		(start 422.776904 -371.645942)
		(end 422.914064 -371.783102)
		(width 0.14224)
		(layer "In13.Cu")
		(net "P5E_CPU0_P2_TX_DP<15>")
	)
	(segment
		(start 374.8024 -284.110938)
		(end 374.77192 -284.128718)
		(width 0.1143)
		(layer "In13.Cu")
		(net "P5E_CPU0_P2_TX_DP<15>")
	)
	(segment
		(start 374.77192 -288.343594)
		(end 374.804432 -288.36239)
		(width 0.1143)
		(layer "In13.Cu")
		(net "P5E_CPU0_P2_TX_DP<15>")
	)
	(segment
		(start 419.393624 -371.645942)
		(end 419.530784 -371.783102)
		(width 0.14224)
		(layer "In13.Cu")
		(net "P5E_CPU0_P2_TX_DP<15>")
	)
	(segment
		(start 374.77192 -289.963352)
		(end 374.8024 -289.981132)
		(width 0.1143)
		(layer "In13.Cu")
		(net "P5E_CPU0_P2_TX_DP<15>")
	)
	(segment
		(start 420.658544 -371.783102)
		(end 421.085264 -371.783102)
		(width 0.14224)
		(layer "In13.Cu")
		(net "P5E_CPU0_P2_TX_DP<15>")
	)
	(segment
		(start 374.77192 -283.483558)
		(end 374.8024 -283.501338)
		(width 0.1143)
		(layer "In13.Cu")
		(net "P5E_CPU0_P2_TX_DP<15>")
	)
	(segment
		(start 375.26341 -295.640252)
		(end 375.387362 -295.74998)
		(width 0.1143)
		(layer "In13.Cu")
		(net "P5E_CPU0_P2_TX_DP<15>")
	)
	(segment
		(start 420.521384 -371.645942)
		(end 420.658544 -371.783102)
		(width 0.14224)
		(layer "In13.Cu")
		(net "P5E_CPU0_P2_TX_DP<15>")
	)
	(segment
		(start 374.301766 -272.95348)
		(end 374.333516 -272.971768)
		(width 0.1143)
		(layer "In13.Cu")
		(net "P5E_CPU0_P2_TX_DP<15>")
	)
	(segment
		(start 374.732804 -289.940492)
		(end 374.77192 -289.963352)
		(width 0.1143)
		(layer "In13.Cu")
		(net "P5E_CPU0_P2_TX_DP<15>")
	)
	(segment
		(start 427.064932 -375.204228)
		(end 428.769018 -376.908314)
		(width 0.14224)
		(layer "In13.Cu")
		(net "P5E_CPU0_P2_TX_DP<15>")
	)
	(segment
		(start 374.77192 -292.228524)
		(end 374.732804 -292.251384)
		(width 0.1143)
		(layer "In13.Cu")
		(net "P5E_CPU0_P2_TX_DP<15>")
	)
	(segment
		(start 374.8024 -290.590732)
		(end 374.77192 -290.608512)
		(width 0.1143)
		(layer "In13.Cu")
		(net "P5E_CPU0_P2_TX_DP<15>")
	)
	(segment
		(start 418.807138 -371.645942)
		(end 419.393624 -371.645942)
		(width 0.14224)
		(layer "In13.Cu")
		(net "P5E_CPU0_P2_TX_DP<15>")
	)
	(segment
		(start 375.4247 -296.583862)
		(end 375.4247 -296.61231)
		(width 0.1143)
		(layer "In13.Cu")
		(net "P5E_CPU0_P2_TX_DP<15>")
	)
	(segment
		(start 374.77192 -280.243534)
		(end 374.8024 -280.261314)
		(width 0.1143)
		(layer "In13.Cu")
		(net "P5E_CPU0_P2_TX_DP<15>")
	)
	(segment
		(start 374.77192 -277.00351)
		(end 374.8024 -277.02129)
		(width 0.1143)
		(layer "In13.Cu")
		(net "P5E_CPU0_P2_TX_DP<15>")
	)
	(segment
		(start 374.8024 -288.97072)
		(end 374.77192 -288.9885)
		(width 0.1143)
		(layer "In13.Cu")
		(net "P5E_CPU0_P2_TX_DP<15>")
	)
	(segment
		(start 373.79275 -272.120614)
		(end 373.851678 -272.154904)
		(width 0.1143)
		(layer "In13.Cu")
		(net "P5E_CPU0_P2_TX_DP<15>")
	)
	(segment
		(start 422.213024 -371.783102)
		(end 422.350184 -371.645942)
		(width 0.14224)
		(layer "In13.Cu")
		(net "P5E_CPU0_P2_TX_DP<15>")
	)
	(segment
		(start 375.109994 -295.576244)
		(end 375.26341 -295.640252)
		(width 0.1143)
		(layer "In13.Cu")
		(net "P5E_CPU0_P2_TX_DP<15>")
	)
	(segment
		(start 427.19625 -388.169658)
		(end 426.90542 -387.878828)
		(width 0.14224)
		(layer "In13.Cu")
		(net "P5E_CPU0_P2_TX_DP<15>")
	)
	(segment
		(start 374.298972 -272.951956)
		(end 374.301766 -272.95348)
		(width 0.1143)
		(layer "In13.Cu")
		(net "P5E_CPU0_P2_TX_DP<15>")
	)
	(segment
		(start 373.174768 -271.656048)
		(end 373.47271 -271.656048)
		(width 0.1143)
		(layer "In13.Cu")
		(net "P5E_CPU0_P2_TX_DP<15>")
	)
	(segment
		(start 374.77192 -293.203376)
		(end 374.8024 -293.221156)
		(width 0.1143)
		(layer "In13.Cu")
		(net "P5E_CPU0_P2_TX_DP<15>")
	)
	(segment
		(start 421.786304 -371.783102)
		(end 422.213024 -371.783102)
		(width 0.14224)
		(layer "In13.Cu")
		(net "P5E_CPU0_P2_TX_DP<15>")
	)
	(segment
		(start 374.77192 -282.508706)
		(end 374.732804 -282.531566)
		(width 0.1143)
		(layer "In13.Cu")
		(net "P5E_CPU0_P2_TX_DP<15>")
	)
	(segment
		(start 375.47042 -295.933622)
		(end 375.47042 -296.538142)
		(width 0.1143)
		(layer "In13.Cu")
		(net "P5E_CPU0_P2_TX_DP<15>")
	)
	(segment
		(start 375.47042 -296.538142)
		(end 375.4247 -296.583862)
		(width 0.1143)
		(layer "In13.Cu")
		(net "P5E_CPU0_P2_TX_DP<15>")
	)
	(segment
		(start 426.796708 -373.219726)
		(end 426.796708 -374.556782)
		(width 0.14224)
		(layer "In13.Cu")
		(net "P5E_CPU0_P2_TX_DP<15>")
	)
	(segment
		(start 375.470674 -297.112182)
		(end 401.347432 -359.558336)
		(width 0.14224)
		(layer "In13.Cu")
		(net "P5E_CPU0_P2_TX_DP<15>")
	)
	(segment
		(start 421.222424 -371.645942)
		(end 421.649144 -371.645942)
		(width 0.14224)
		(layer "In13.Cu")
		(net "P5E_CPU0_P2_TX_DP<15>")
	)
	(segment
		(start 374.732804 -275.360638)
		(end 374.77192 -275.383498)
		(width 0.1143)
		(layer "In13.Cu")
		(net "P5E_CPU0_P2_TX_DP<15>")
	)
	(segment
		(start 374.732804 -281.840686)
		(end 374.77192 -281.863546)
		(width 0.1143)
		(layer "In13.Cu")
		(net "P5E_CPU0_P2_TX_DP<15>")
	)
	(segment
		(start 375.009664 -295.459404)
		(end 375.109994 -295.576244)
		(width 0.1143)
		(layer "In13.Cu")
		(net "P5E_CPU0_P2_TX_DP<15>")
	)
	(segment
		(start 374.732804 -280.220674)
		(end 374.77192 -280.243534)
		(width 0.1143)
		(layer "In13.Cu")
		(net "P5E_CPU0_P2_TX_DP<15>")
	)
	(segment
		(start 428.273464 -388.169658)
		(end 427.19625 -388.169658)
		(width 0.14224)
		(layer "In13.Cu")
		(net "P5E_CPU0_P2_TX_DP<15>")
	)
	(segment
		(start 401.433284 -359.718356)
		(end 405.449024 -365.729266)
		(width 0.14224)
		(layer "In13.Cu")
		(net "P5E_CPU0_P2_TX_DP<15>")
	)
	(segment
		(start 374.732804 -291.560504)
		(end 374.77192 -291.583364)
		(width 0.1143)
		(layer "In13.Cu")
		(net "P5E_CPU0_P2_TX_DP<15>")
	)
	(segment
		(start 374.77192 -291.583364)
		(end 374.8024 -291.601144)
		(width 0.1143)
		(layer "In13.Cu")
		(net "P5E_CPU0_P2_TX_DP<15>")
	)
	(segment
		(start 374.8024 -274.390866)
		(end 374.77192 -274.408646)
		(width 0.1143)
		(layer "In13.Cu")
		(net "P5E_CPU0_P2_TX_DP<15>")
	)
	(segment
		(start 374.77192 -288.9885)
		(end 374.732804 -289.01136)
		(width 0.1143)
		(layer "In13.Cu")
		(net "P5E_CPU0_P2_TX_DP<15>")
	)
	(segment
		(start 422.350184 -371.645942)
		(end 422.776904 -371.645942)
		(width 0.14224)
		(layer "In13.Cu")
		(net "P5E_CPU0_P2_TX_DP<15>")
	)
	(segment
		(start 374.77192 -279.268682)
		(end 374.732804 -279.291542)
		(width 0.1143)
		(layer "In13.Cu")
		(net "P5E_CPU0_P2_TX_DP<15>")
	)
	(segment
		(start 374.77192 -277.64867)
		(end 374.732804 -277.67153)
		(width 0.1143)
		(layer "In13.Cu")
		(net "P5E_CPU0_P2_TX_DP<15>")
	)
	(segment
		(start 374.732804 -285.08071)
		(end 374.77192 -285.10357)
		(width 0.1143)
		(layer "In13.Cu")
		(net "P5E_CPU0_P2_TX_DP<15>")
	)
	(segment
		(start 421.085264 -371.783102)
		(end 421.222424 -371.645942)
		(width 0.14224)
		(layer "In13.Cu")
		(net "P5E_CPU0_P2_TX_DP<15>")
	)
	(segment
		(start 375.387362 -295.74998)
		(end 375.47042 -295.933622)
		(width 0.1143)
		(layer "In13.Cu")
		(net "P5E_CPU0_P2_TX_DP<15>")
	)
	(segment
		(start 374.732804 -278.600662)
		(end 374.77192 -278.623522)
		(width 0.1143)
		(layer "In13.Cu")
		(net "P5E_CPU0_P2_TX_DP<15>")
	)
	(segment
		(start 423.477944 -371.645942)
		(end 425.222924 -371.645942)
		(width 0.14224)
		(layer "In13.Cu")
		(net "P5E_CPU0_P2_TX_DP<15>")
	)
	(segment
		(start 374.8024 -293.830756)
		(end 374.77192 -293.848536)
		(width 0.1143)
		(layer "In13.Cu")
		(net "P5E_CPU0_P2_TX_DP<15>")
	)
	(segment
		(start 374.77192 -275.383498)
		(end 374.8024 -275.401278)
		(width 0.1143)
		(layer "In13.Cu")
		(net "P5E_CPU0_P2_TX_DP<15>")
	)
	(segment
		(start 374.77192 -285.10357)
		(end 374.8024 -285.12135)
		(width 0.1143)
		(layer "In13.Cu")
		(net "P5E_CPU0_P2_TX_DP<15>")
	)
	(segment
		(start 374.733312 -294.800782)
		(end 374.8024 -294.841168)
		(width 0.1143)
		(layer "In13.Cu")
		(net "P5E_CPU0_P2_TX_DP<15>")
	)
	(segment
		(start 374.77192 -278.623522)
		(end 374.8024 -278.641302)
		(width 0.1143)
		(layer "In13.Cu")
		(net "P5E_CPU0_P2_TX_DP<15>")
	)
	(segment
		(start 419.957504 -371.783102)
		(end 420.094664 -371.645942)
		(width 0.14224)
		(layer "In13.Cu")
		(net "P5E_CPU0_P2_TX_DP<15>")
	)
	(arc
		(start 374.732804 -290.631372)
		(mid 374.489477 -291.095938)
		(end 374.732804 -291.560504)
		(width 0.1143)
		(layer "In13.Cu")
		(net "P5E_CPU0_P2_TX_DP<15>")
	)
	(arc
		(start 374.735344 -287.389824)
		(mid 374.554692 -287.592569)
		(end 374.489472 -287.856168)
		(width 0.1143)
		(layer "In13.Cu")
		(net "P5E_CPU0_P2_TX_DP<15>")
	)
	(arc
		(start 374.8024 -291.601144)
		(mid 374.959377 -291.905944)
		(end 374.8024 -292.210744)
		(width 0.1143)
		(layer "In13.Cu")
		(net "P5E_CPU0_P2_TX_DP<15>")
	)
	(arc
		(start 374.8024 -280.261314)
		(mid 374.959377 -280.566114)
		(end 374.8024 -280.870914)
		(width 0.1143)
		(layer "In13.Cu")
		(net "P5E_CPU0_P2_TX_DP<15>")
	)
	(arc
		(start 374.489472 -287.856168)
		(mid 374.553987 -288.118387)
		(end 374.732804 -288.320734)
		(width 0.1143)
		(layer "In13.Cu")
		(net "P5E_CPU0_P2_TX_DP<15>")
	)
	(arc
		(start 428.36338 -388.13232)
		(mid 428.32214 -388.159939)
		(end 428.273464 -388.169658)
		(width 0.14224)
		(layer "In13.Cu")
		(net "P5E_CPU0_P2_TX_DP<15>")
	)
	(arc
		(start 374.8024 -275.401278)
		(mid 374.959377 -275.706078)
		(end 374.8024 -276.010878)
		(width 0.1143)
		(layer "In13.Cu")
		(net "P5E_CPU0_P2_TX_DP<15>")
	)
	(arc
		(start 374.732804 -279.291542)
		(mid 374.489477 -279.756108)
		(end 374.732804 -280.220674)
		(width 0.1143)
		(layer "In13.Cu")
		(net "P5E_CPU0_P2_TX_DP<15>")
	)
	(arc
		(start 405.449024 -365.729266)
		(mid 405.504178 -365.803158)
		(end 405.566626 -365.870998)
		(width 0.14224)
		(layer "In13.Cu")
		(net "P5E_CPU0_P2_TX_DP<15>")
	)
	(arc
		(start 405.566626 -365.870998)
		(mid 405.662766 -365.956961)
		(end 405.766524 -366.033558)
		(width 0.14224)
		(layer "In13.Cu")
		(net "P5E_CPU0_P2_TX_DP<15>")
	)
	(arc
		(start 373.851678 -272.154904)
		(mid 373.973112 -272.276168)
		(end 374.01754 -272.441924)
		(width 0.1143)
		(layer "In13.Cu")
		(net "P5E_CPU0_P2_TX_DP<15>")
	)
	(arc
		(start 401.347432 -359.558336)
		(mid 401.386434 -359.640451)
		(end 401.433284 -359.718356)
		(width 0.14224)
		(layer "In13.Cu")
		(net "P5E_CPU0_P2_TX_DP<15>")
	)
	(arc
		(start 373.559324 -271.761712)
		(mid 373.640757 -271.96411)
		(end 373.79275 -272.120614)
		(width 0.1143)
		(layer "In13.Cu")
		(net "P5E_CPU0_P2_TX_DP<15>")
	)
	(arc
		(start 374.8024 -285.12135)
		(mid 374.959377 -285.42615)
		(end 374.8024 -285.73095)
		(width 0.1143)
		(layer "In13.Cu")
		(net "P5E_CPU0_P2_TX_DP<15>")
	)
	(arc
		(start 374.732804 -274.431506)
		(mid 374.489477 -274.896072)
		(end 374.732804 -275.360638)
		(width 0.1143)
		(layer "In13.Cu")
		(net "P5E_CPU0_P2_TX_DP<15>")
	)
	(arc
		(start 374.959372 -288.66592)
		(mid 374.917823 -288.837342)
		(end 374.8024 -288.97072)
		(width 0.1143)
		(layer "In13.Cu")
		(net "P5E_CPU0_P2_TX_DP<15>")
	)
	(arc
		(start 374.8024 -281.881326)
		(mid 374.959377 -282.186126)
		(end 374.8024 -282.490926)
		(width 0.1143)
		(layer "In13.Cu")
		(net "P5E_CPU0_P2_TX_DP<15>")
	)
	(arc
		(start 374.8024 -277.02129)
		(mid 374.959377 -277.32609)
		(end 374.8024 -277.63089)
		(width 0.1143)
		(layer "In13.Cu")
		(net "P5E_CPU0_P2_TX_DP<15>")
	)
	(arc
		(start 374.01754 -272.463006)
		(mid 374.092927 -272.745079)
		(end 374.298972 -272.951956)
		(width 0.1143)
		(layer "In13.Cu")
		(net "P5E_CPU0_P2_TX_DP<15>")
	)
	(arc
		(start 426.796708 -374.556782)
		(mid 426.866424 -374.907179)
		(end 427.064932 -375.204228)
		(width 0.14224)
		(layer "In13.Cu")
		(net "P5E_CPU0_P2_TX_DP<15>")
	)
	(arc
		(start 374.732804 -293.871396)
		(mid 374.489477 -294.335962)
		(end 374.732804 -294.800528)
		(width 0.1143)
		(layer "In13.Cu")
		(net "P5E_CPU0_P2_TX_DP<15>")
	)
	(arc
		(start 374.8024 -278.641302)
		(mid 374.959377 -278.946102)
		(end 374.8024 -279.250902)
		(width 0.1143)
		(layer "In13.Cu")
		(net "P5E_CPU0_P2_TX_DP<15>")
	)
	(arc
		(start 373.555514 -271.738852)
		(mid 373.557302 -271.750301)
		(end 373.559324 -271.761712)
		(width 0.1143)
		(layer "In13.Cu")
		(net "P5E_CPU0_P2_TX_DP<15>")
	)
	(arc
		(start 374.732804 -292.251384)
		(mid 374.489477 -292.71595)
		(end 374.732804 -293.180516)
		(width 0.1143)
		(layer "In13.Cu")
		(net "P5E_CPU0_P2_TX_DP<15>")
	)
	(arc
		(start 374.8024 -294.841168)
		(mid 374.917827 -294.974544)
		(end 374.959372 -295.145968)
		(width 0.1143)
		(layer "In13.Cu")
		(net "P5E_CPU0_P2_TX_DP<15>")
	)
	(arc
		(start 374.804432 -288.36239)
		(mid 374.918361 -288.495537)
		(end 374.959372 -288.66592)
		(width 0.1143)
		(layer "In13.Cu")
		(net "P5E_CPU0_P2_TX_DP<15>")
	)
	(arc
		(start 374.732804 -277.67153)
		(mid 374.489477 -278.136096)
		(end 374.732804 -278.600662)
		(width 0.1143)
		(layer "In13.Cu")
		(net "P5E_CPU0_P2_TX_DP<15>")
	)
	(arc
		(start 374.959372 -287.045908)
		(mid 374.917823 -287.21733)
		(end 374.8024 -287.350708)
		(width 0.1143)
		(layer "In13.Cu")
		(net "P5E_CPU0_P2_TX_DP<15>")
	)
	(arc
		(start 374.8024 -289.981132)
		(mid 374.959377 -290.285932)
		(end 374.8024 -290.590732)
		(width 0.1143)
		(layer "In13.Cu")
		(net "P5E_CPU0_P2_TX_DP<15>")
	)
	(arc
		(start 374.8024 -283.501338)
		(mid 374.959377 -283.806138)
		(end 374.8024 -284.110938)
		(width 0.1143)
		(layer "In13.Cu")
		(net "P5E_CPU0_P2_TX_DP<15>")
	)
	(arc
		(start 374.732804 -289.01136)
		(mid 374.489477 -289.475926)
		(end 374.732804 -289.940492)
		(width 0.1143)
		(layer "In13.Cu")
		(net "P5E_CPU0_P2_TX_DP<15>")
	)
	(arc
		(start 374.804432 -286.742378)
		(mid 374.918361 -286.875525)
		(end 374.959372 -287.045908)
		(width 0.1143)
		(layer "In13.Cu")
		(net "P5E_CPU0_P2_TX_DP<15>")
	)
	(arc
		(start 426.75937 -373.129556)
		(mid 426.787013 -373.170926)
		(end 426.796708 -373.219726)
		(width 0.14224)
		(layer "In13.Cu")
		(net "P5E_CPU0_P2_TX_DP<15>")
	)
	(arc
		(start 374.8024 -273.781266)
		(mid 374.959377 -274.086066)
		(end 374.8024 -274.390866)
		(width 0.1143)
		(layer "In13.Cu")
		(net "P5E_CPU0_P2_TX_DP<15>")
	)
	(arc
		(start 374.732804 -282.531566)
		(mid 374.489477 -282.996132)
		(end 374.732804 -283.460698)
		(width 0.1143)
		(layer "In13.Cu")
		(net "P5E_CPU0_P2_TX_DP<15>")
	)
	(arc
		(start 374.333516 -272.971768)
		(mid 374.448192 -273.105102)
		(end 374.489472 -273.27606)
		(width 0.1143)
		(layer "In13.Cu")
		(net "P5E_CPU0_P2_TX_DP<15>")
	)
	(arc
		(start 374.732804 -276.051518)
		(mid 374.489477 -276.516084)
		(end 374.732804 -276.98065)
		(width 0.1143)
		(layer "In13.Cu")
		(net "P5E_CPU0_P2_TX_DP<15>")
	)
	(arc
		(start 374.8024 -293.221156)
		(mid 374.959377 -293.525956)
		(end 374.8024 -293.830756)
		(width 0.1143)
		(layer "In13.Cu")
		(net "P5E_CPU0_P2_TX_DP<15>")
	)
	(arc
		(start 428.806356 -387.636766)
		(mid 428.796654 -387.68545)
		(end 428.769018 -387.726682)
		(width 0.14224)
		(layer "In13.Cu")
		(net "P5E_CPU0_P2_TX_DP<15>")
	)
	(arc
		(start 425.222924 -371.645942)
		(mid 425.271719 -371.655648)
		(end 425.313094 -371.68328)
		(width 0.14224)
		(layer "In13.Cu")
		(net "P5E_CPU0_P2_TX_DP<15>")
	)
	(arc
		(start 374.489472 -273.27606)
		(mid 374.553987 -273.538279)
		(end 374.732804 -273.740626)
		(width 0.1143)
		(layer "In13.Cu")
		(net "P5E_CPU0_P2_TX_DP<15>")
	)
	(arc
		(start 374.732804 -285.77159)
		(mid 374.489477 -286.236156)
		(end 374.732804 -286.700722)
		(width 0.1143)
		(layer "In13.Cu")
		(net "P5E_CPU0_P2_TX_DP<15>")
	)
	(arc
		(start 375.4247 -296.88155)
		(mid 375.43635 -296.999127)
		(end 375.470674 -297.112182)
		(width 0.14224)
		(layer "In13.Cu")
		(net "P5E_CPU0_P2_TX_DP<15>")
	)
	(arc
		(start 374.732804 -284.151578)
		(mid 374.489477 -284.616144)
		(end 374.732804 -285.08071)
		(width 0.1143)
		(layer "In13.Cu")
		(net "P5E_CPU0_P2_TX_DP<15>")
	)
	(arc
		(start 428.769018 -376.908314)
		(mid 428.796637 -376.949554)
		(end 428.806356 -376.99823)
		(width 0.14224)
		(layer "In13.Cu")
		(net "P5E_CPU0_P2_TX_DP<15>")
	)
	(arc
		(start 374.732804 -280.911554)
		(mid 374.489477 -281.37612)
		(end 374.732804 -281.840686)
		(width 0.1143)
		(layer "In13.Cu")
		(net "P5E_CPU0_P2_TX_DP<15>")
	)
	(segment
		(start 425.93133 -384.745738)
		(end 425.63542 -384.449828)
		(width 0.12954)
		(layer "F.Cu")
		(net "P5E_CPU0_P2_TX_DP<14>")
	)
	(segment
		(start 426.90542 -384.475228)
		(end 426.63491 -384.745738)
		(width 0.12954)
		(layer "F.Cu")
		(net "P5E_CPU0_P2_TX_DP<14>")
	)
	(segment
		(start 372.707916 -273.010122)
		(end 373.174768 -273.27606)
		(width 0.12954)
		(layer "F.Cu")
		(net "P5E_CPU0_P2_TX_DP<14>")
	)
	(segment
		(start 426.63491 -384.745738)
		(end 425.93133 -384.745738)
		(width 0.12954)
		(layer "F.Cu")
		(net "P5E_CPU0_P2_TX_DP<14>")
	)
	(segment
		(start 373.79275 -291.560504)
		(end 373.83085 -291.582856)
		(width 0.1143)
		(layer "In13.Cu")
		(net "P5E_CPU0_P2_TX_DP<14>")
	)
	(segment
		(start 373.83085 -281.863038)
		(end 373.831866 -281.863546)
		(width 0.1143)
		(layer "In13.Cu")
		(net "P5E_CPU0_P2_TX_DP<14>")
	)
	(segment
		(start 373.83085 -277.649178)
		(end 373.829326 -277.650194)
		(width 0.1143)
		(layer "In13.Cu")
		(net "P5E_CPU0_P2_TX_DP<14>")
	)
	(segment
		(start 373.821198 -293.854632)
		(end 373.79275 -293.871396)
		(width 0.1143)
		(layer "In13.Cu")
		(net "P5E_CPU0_P2_TX_DP<14>")
	)
	(segment
		(start 373.832628 -289.96386)
		(end 373.83466 -289.96513)
		(width 0.1143)
		(layer "In13.Cu")
		(net "P5E_CPU0_P2_TX_DP<14>")
	)
	(segment
		(start 373.83085 -291.582856)
		(end 373.831866 -291.583364)
		(width 0.1143)
		(layer "In13.Cu")
		(net "P5E_CPU0_P2_TX_DP<14>")
	)
	(segment
		(start 427.736 -381.481838)
		(end 427.87316 -381.618998)
		(width 0.14224)
		(layer "In13.Cu")
		(net "P5E_CPU0_P2_TX_DP<14>")
	)
	(segment
		(start 373.815864 -293.194486)
		(end 373.83085 -293.202868)
		(width 0.1143)
		(layer "In13.Cu")
		(net "P5E_CPU0_P2_TX_DP<14>")
	)
	(segment
		(start 373.867426 -287.347406)
		(end 373.863616 -287.3502)
		(width 0.1143)
		(layer "In13.Cu")
		(net "P5E_CPU0_P2_TX_DP<14>")
	)
	(segment
		(start 425.434506 -374.69445)
		(end 425.78655 -375.046494)
		(width 0.14224)
		(layer "In13.Cu")
		(net "P5E_CPU0_P2_TX_DP<14>")
	)
	(segment
		(start 373.863616 -280.870406)
		(end 373.831866 -280.888694)
		(width 0.1143)
		(layer "In13.Cu")
		(net "P5E_CPU0_P2_TX_DP<14>")
	)
	(segment
		(start 373.79275 -288.320734)
		(end 373.798846 -288.32429)
		(width 0.1143)
		(layer "In13.Cu")
		(net "P5E_CPU0_P2_TX_DP<14>")
	)
	(segment
		(start 420.007542 -373.210074)
		(end 423.897298 -373.210074)
		(width 0.14224)
		(layer "In13.Cu")
		(net "P5E_CPU0_P2_TX_DP<14>")
	)
	(segment
		(start 373.83085 -274.409154)
		(end 373.829326 -274.41017)
		(width 0.1143)
		(layer "In13.Cu")
		(net "P5E_CPU0_P2_TX_DP<14>")
	)
	(segment
		(start 373.835422 -293.846758)
		(end 373.834914 -293.846758)
		(width 0.1143)
		(layer "In13.Cu")
		(net "P5E_CPU0_P2_TX_DP<14>")
	)
	(segment
		(start 373.863616 -278.64181)
		(end 373.883428 -278.656034)
		(width 0.1143)
		(layer "In13.Cu")
		(net "P5E_CPU0_P2_TX_DP<14>")
	)
	(segment
		(start 373.832628 -293.203884)
		(end 373.83466 -293.205154)
		(width 0.1143)
		(layer "In13.Cu")
		(net "P5E_CPU0_P2_TX_DP<14>")
	)
	(segment
		(start 373.823738 -292.23335)
		(end 373.822214 -292.234112)
		(width 0.1143)
		(layer "In13.Cu")
		(net "P5E_CPU0_P2_TX_DP<14>")
	)
	(segment
		(start 373.79275 -281.840686)
		(end 373.83085 -281.863038)
		(width 0.1143)
		(layer "In13.Cu")
		(net "P5E_CPU0_P2_TX_DP<14>")
	)
	(segment
		(start 373.8245 -288.992564)
		(end 373.821198 -288.994596)
		(width 0.1143)
		(layer "In13.Cu")
		(net "P5E_CPU0_P2_TX_DP<14>")
	)
	(segment
		(start 373.83085 -276.029166)
		(end 373.829326 -276.030182)
		(width 0.1143)
		(layer "In13.Cu")
		(net "P5E_CPU0_P2_TX_DP<14>")
	)
	(segment
		(start 373.832628 -279.268174)
		(end 373.831866 -279.268682)
		(width 0.1143)
		(layer "In13.Cu")
		(net "P5E_CPU0_P2_TX_DP<14>")
	)
	(segment
		(start 373.825262 -290.612068)
		(end 373.8245 -290.612576)
		(width 0.1143)
		(layer "In13.Cu")
		(net "P5E_CPU0_P2_TX_DP<14>")
	)
	(segment
		(start 373.863616 -287.3502)
		(end 373.79529 -287.389824)
		(width 0.1143)
		(layer "In13.Cu")
		(net "P5E_CPU0_P2_TX_DP<14>")
	)
	(segment
		(start 373.79275 -289.940492)
		(end 373.83085 -289.962844)
		(width 0.1143)
		(layer "In13.Cu")
		(net "P5E_CPU0_P2_TX_DP<14>")
	)
	(segment
		(start 373.831866 -289.963352)
		(end 373.832628 -289.96386)
		(width 0.1143)
		(layer "In13.Cu")
		(net "P5E_CPU0_P2_TX_DP<14>")
	)
	(segment
		(start 373.829326 -274.41017)
		(end 373.822976 -274.413726)
		(width 0.1143)
		(layer "In13.Cu")
		(net "P5E_CPU0_P2_TX_DP<14>")
	)
	(segment
		(start 373.831866 -292.228524)
		(end 373.83085 -292.229032)
		(width 0.1143)
		(layer "In13.Cu")
		(net "P5E_CPU0_P2_TX_DP<14>")
	)
	(segment
		(start 373.799608 -273.74469)
		(end 373.80037 -273.745198)
		(width 0.1143)
		(layer "In13.Cu")
		(net "P5E_CPU0_P2_TX_DP<14>")
	)
	(segment
		(start 373.834914 -290.606734)
		(end 373.832628 -290.608258)
		(width 0.1143)
		(layer "In13.Cu")
		(net "P5E_CPU0_P2_TX_DP<14>")
	)
	(segment
		(start 373.831866 -288.9885)
		(end 373.827294 -288.990786)
		(width 0.1143)
		(layer "In13.Cu")
		(net "P5E_CPU0_P2_TX_DP<14>")
	)
	(segment
		(start 374.444006 -296.583862)
		(end 374.444006 -296.61231)
		(width 0.1143)
		(layer "In13.Cu")
		(net "P5E_CPU0_P2_TX_DP<14>")
	)
	(segment
		(start 373.83085 -293.202868)
		(end 373.831866 -293.203376)
		(width 0.1143)
		(layer "In13.Cu")
		(net "P5E_CPU0_P2_TX_DP<14>")
	)
	(segment
		(start 373.835422 -288.986722)
		(end 373.834914 -288.986722)
		(width 0.1143)
		(layer "In13.Cu")
		(net "P5E_CPU0_P2_TX_DP<14>")
	)
	(segment
		(start 373.834914 -285.746952)
		(end 373.832628 -285.748476)
		(width 0.1143)
		(layer "In13.Cu")
		(net "P5E_CPU0_P2_TX_DP<14>")
	)
	(segment
		(start 373.795544 -280.222706)
		(end 373.831866 -280.243534)
		(width 0.1143)
		(layer "In13.Cu")
		(net "P5E_CPU0_P2_TX_DP<14>")
	)
	(segment
		(start 373.821198 -282.514802)
		(end 373.79275 -282.531566)
		(width 0.1143)
		(layer "In13.Cu")
		(net "P5E_CPU0_P2_TX_DP<14>")
	)
	(segment
		(start 373.832628 -285.748476)
		(end 373.831866 -285.74873)
		(width 0.1143)
		(layer "In13.Cu")
		(net "P5E_CPU0_P2_TX_DP<14>")
	)
	(segment
		(start 427.87316 -377.923044)
		(end 427.87316 -380.917958)
		(width 0.14224)
		(layer "In13.Cu")
		(net "P5E_CPU0_P2_TX_DP<14>")
	)
	(segment
		(start 373.792242 -292.251384)
		(end 373.765826 -292.270688)
		(width 0.1143)
		(layer "In13.Cu")
		(net "P5E_CPU0_P2_TX_DP<14>")
	)
	(segment
		(start 373.834914 -288.345118)
		(end 373.835168 -288.345118)
		(width 0.1143)
		(layer "In13.Cu")
		(net "P5E_CPU0_P2_TX_DP<14>")
	)
	(segment
		(start 427.835822 -384.676396)
		(end 427.783498 -384.72872)
		(width 0.14224)
		(layer "In13.Cu")
		(net "P5E_CPU0_P2_TX_DP<14>")
	)
	(segment
		(start 427.87316 -381.618998)
		(end 427.87316 -382.42748)
		(width 0.14224)
		(layer "In13.Cu")
		(net "P5E_CPU0_P2_TX_DP<14>")
	)
	(segment
		(start 373.825262 -288.992056)
		(end 373.8245 -288.992564)
		(width 0.1143)
		(layer "In13.Cu")
		(net "P5E_CPU0_P2_TX_DP<14>")
	)
	(segment
		(start 373.832628 -281.864054)
		(end 373.83466 -281.865324)
		(width 0.1143)
		(layer "In13.Cu")
		(net "P5E_CPU0_P2_TX_DP<14>")
	)
	(segment
		(start 373.827294 -288.990786)
		(end 373.825262 -288.992056)
		(width 0.1143)
		(layer "In13.Cu")
		(net "P5E_CPU0_P2_TX_DP<14>")
	)
	(segment
		(start 373.819674 -292.235636)
		(end 373.792242 -292.251384)
		(width 0.1143)
		(layer "In13.Cu")
		(net "P5E_CPU0_P2_TX_DP<14>")
	)
	(segment
		(start 373.832628 -277.004018)
		(end 373.863616 -277.021798)
		(width 0.1143)
		(layer "In13.Cu")
		(net "P5E_CPU0_P2_TX_DP<14>")
	)
	(segment
		(start 373.832628 -284.128464)
		(end 373.831866 -284.128718)
		(width 0.1143)
		(layer "In13.Cu")
		(net "P5E_CPU0_P2_TX_DP<14>")
	)
	(segment
		(start 373.883428 -279.23617)
		(end 373.863616 -279.250394)
		(width 0.1143)
		(layer "In13.Cu")
		(net "P5E_CPU0_P2_TX_DP<14>")
	)
	(segment
		(start 373.821198 -288.994596)
		(end 373.79275 -289.01136)
		(width 0.1143)
		(layer "In13.Cu")
		(net "P5E_CPU0_P2_TX_DP<14>")
	)
	(segment
		(start 373.79275 -285.08071)
		(end 373.83085 -285.103062)
		(width 0.1143)
		(layer "In13.Cu")
		(net "P5E_CPU0_P2_TX_DP<14>")
	)
	(segment
		(start 373.832628 -274.408138)
		(end 373.831866 -274.408646)
		(width 0.1143)
		(layer "In13.Cu")
		(net "P5E_CPU0_P2_TX_DP<14>")
	)
	(segment
		(start 373.831866 -293.203376)
		(end 373.832628 -293.203884)
		(width 0.1143)
		(layer "In13.Cu")
		(net "P5E_CPU0_P2_TX_DP<14>")
	)
	(segment
		(start 373.829326 -276.030182)
		(end 373.822976 -276.033738)
		(width 0.1143)
		(layer "In13.Cu")
		(net "P5E_CPU0_P2_TX_DP<14>")
	)
	(segment
		(start 373.863616 -274.390358)
		(end 373.832628 -274.408138)
		(width 0.1143)
		(layer "In13.Cu")
		(net "P5E_CPU0_P2_TX_DP<14>")
	)
	(segment
		(start 373.835422 -290.606734)
		(end 373.834914 -290.606734)
		(width 0.1143)
		(layer "In13.Cu")
		(net "P5E_CPU0_P2_TX_DP<14>")
	)
	(segment
		(start 427.87316 -383.12852)
		(end 427.87316 -384.58648)
		(width 0.14224)
		(layer "In13.Cu")
		(net "P5E_CPU0_P2_TX_DP<14>")
	)
	(segment
		(start 373.828818 -292.230302)
		(end 373.827294 -292.231318)
		(width 0.1143)
		(layer "In13.Cu")
		(net "P5E_CPU0_P2_TX_DP<14>")
	)
	(segment
		(start 373.799608 -283.464762)
		(end 373.80037 -283.46527)
		(width 0.1143)
		(layer "In13.Cu")
		(net "P5E_CPU0_P2_TX_DP<14>")
	)
	(segment
		(start 373.831866 -280.243534)
		(end 373.863616 -280.261822)
		(width 0.1143)
		(layer "In13.Cu")
		(net "P5E_CPU0_P2_TX_DP<14>")
	)
	(segment
		(start 427.736 -382.56464)
		(end 427.736 -382.99136)
		(width 0.14224)
		(layer "In13.Cu")
		(net "P5E_CPU0_P2_TX_DP<14>")
	)
	(segment
		(start 374.475248 -297.30446)
		(end 400.56181 -360.256074)
		(width 0.14224)
		(layer "In13.Cu")
		(net "P5E_CPU0_P2_TX_DP<14>")
	)
	(segment
		(start 373.80037 -276.985222)
		(end 373.831866 -277.00351)
		(width 0.1143)
		(layer "In13.Cu")
		(net "P5E_CPU0_P2_TX_DP<14>")
	)
	(segment
		(start 373.832628 -291.583872)
		(end 373.862092 -291.60089)
		(width 0.1143)
		(layer "In13.Cu")
		(net "P5E_CPU0_P2_TX_DP<14>")
	)
	(segment
		(start 374.489726 -295.955974)
		(end 374.489726 -296.538142)
		(width 0.1143)
		(layer "In13.Cu")
		(net "P5E_CPU0_P2_TX_DP<14>")
	)
	(segment
		(start 427.87316 -382.42748)
		(end 427.736 -382.56464)
		(width 0.14224)
		(layer "In13.Cu")
		(net "P5E_CPU0_P2_TX_DP<14>")
	)
	(segment
		(start 373.821198 -290.614608)
		(end 373.79275 -290.631372)
		(width 0.1143)
		(layer "In13.Cu")
		(net "P5E_CPU0_P2_TX_DP<14>")
	)
	(segment
		(start 373.832628 -288.988246)
		(end 373.831866 -288.9885)
		(width 0.1143)
		(layer "In13.Cu")
		(net "P5E_CPU0_P2_TX_DP<14>")
	)
	(segment
		(start 373.792242 -293.180516)
		(end 373.812816 -293.192454)
		(width 0.1143)
		(layer "In13.Cu")
		(net "P5E_CPU0_P2_TX_DP<14>")
	)
	(segment
		(start 373.862092 -292.210998)
		(end 373.832628 -292.228016)
		(width 0.1143)
		(layer "In13.Cu")
		(net "P5E_CPU0_P2_TX_DP<14>")
	)
	(segment
		(start 373.831866 -280.888694)
		(end 373.795544 -280.909522)
		(width 0.1143)
		(layer "In13.Cu")
		(net "P5E_CPU0_P2_TX_DP<14>")
	)
	(segment
		(start 373.79275 -280.220674)
		(end 373.795544 -280.222706)
		(width 0.1143)
		(layer "In13.Cu")
		(net "P5E_CPU0_P2_TX_DP<14>")
	)
	(segment
		(start 373.83085 -292.229032)
		(end 373.828818 -292.230302)
		(width 0.1143)
		(layer "In13.Cu")
		(net "P5E_CPU0_P2_TX_DP<14>")
	)
	(segment
		(start 373.835422 -284.12694)
		(end 373.834914 -284.12694)
		(width 0.1143)
		(layer "In13.Cu")
		(net "P5E_CPU0_P2_TX_DP<14>")
	)
	(segment
		(start 373.834914 -282.506928)
		(end 373.832628 -282.508452)
		(width 0.1143)
		(layer "In13.Cu")
		(net "P5E_CPU0_P2_TX_DP<14>")
	)
	(segment
		(start 373.863616 -277.021798)
		(end 373.883428 -277.036022)
		(width 0.1143)
		(layer "In13.Cu")
		(net "P5E_CPU0_P2_TX_DP<14>")
	)
	(segment
		(start 373.834914 -284.12694)
		(end 373.832628 -284.128464)
		(width 0.1143)
		(layer "In13.Cu")
		(net "P5E_CPU0_P2_TX_DP<14>")
	)
	(segment
		(start 425.960032 -375.957338)
		(end 426.619416 -376.616722)
		(width 0.14224)
		(layer "In13.Cu")
		(net "P5E_CPU0_P2_TX_DP<14>")
	)
	(segment
		(start 373.831866 -274.408646)
		(end 373.83085 -274.409154)
		(width 0.1143)
		(layer "In13.Cu")
		(net "P5E_CPU0_P2_TX_DP<14>")
	)
	(segment
		(start 373.83466 -281.865324)
		(end 373.835168 -281.865324)
		(width 0.1143)
		(layer "In13.Cu")
		(net "P5E_CPU0_P2_TX_DP<14>")
	)
	(segment
		(start 373.834406 -294.824658)
		(end 373.864632 -294.842692)
		(width 0.1143)
		(layer "In13.Cu")
		(net "P5E_CPU0_P2_TX_DP<14>")
	)
	(segment
		(start 373.835422 -282.506928)
		(end 373.834914 -282.506928)
		(width 0.1143)
		(layer "In13.Cu")
		(net "P5E_CPU0_P2_TX_DP<14>")
	)
	(segment
		(start 373.832628 -283.484066)
		(end 373.83466 -283.485336)
		(width 0.1143)
		(layer "In13.Cu")
		(net "P5E_CPU0_P2_TX_DP<14>")
	)
	(segment
		(start 373.827294 -285.751016)
		(end 373.825262 -285.752286)
		(width 0.1143)
		(layer "In13.Cu")
		(net "P5E_CPU0_P2_TX_DP<14>")
	)
	(segment
		(start 373.812816 -293.192454)
		(end 373.815864 -293.194486)
		(width 0.1143)
		(layer "In13.Cu")
		(net "P5E_CPU0_P2_TX_DP<14>")
	)
	(segment
		(start 373.799608 -275.364702)
		(end 373.80037 -275.36521)
		(width 0.1143)
		(layer "In13.Cu")
		(net "P5E_CPU0_P2_TX_DP<14>")
	)
	(segment
		(start 373.83085 -289.962844)
		(end 373.831866 -289.963352)
		(width 0.1143)
		(layer "In13.Cu")
		(net "P5E_CPU0_P2_TX_DP<14>")
	)
	(segment
		(start 373.832628 -293.848282)
		(end 373.831866 -293.848536)
		(width 0.1143)
		(layer "In13.Cu")
		(net "P5E_CPU0_P2_TX_DP<14>")
	)
	(segment
		(start 427.736 -382.99136)
		(end 427.87316 -383.12852)
		(width 0.14224)
		(layer "In13.Cu")
		(net "P5E_CPU0_P2_TX_DP<14>")
	)
	(segment
		(start 404.84298 -366.562386)
		(end 406.53589 -367.693448)
		(width 0.14224)
		(layer "In13.Cu")
		(net "P5E_CPU0_P2_TX_DP<14>")
	)
	(segment
		(start 373.827294 -290.610798)
		(end 373.825262 -290.612068)
		(width 0.1143)
		(layer "In13.Cu")
		(net "P5E_CPU0_P2_TX_DP<14>")
	)
	(segment
		(start 426.619416 -376.810524)
		(end 426.921422 -377.11253)
		(width 0.14224)
		(layer "In13.Cu")
		(net "P5E_CPU0_P2_TX_DP<14>")
	)
	(segment
		(start 373.832628 -275.384006)
		(end 373.863616 -275.401786)
		(width 0.1143)
		(layer "In13.Cu")
		(net "P5E_CPU0_P2_TX_DP<14>")
	)
	(segment
		(start 373.821198 -285.754826)
		(end 373.79275 -285.77159)
		(width 0.1143)
		(layer "In13.Cu")
		(net "P5E_CPU0_P2_TX_DP<14>")
	)
	(segment
		(start 406.53589 -367.693448)
		(end 419.712648 -373.1514)
		(width 0.14224)
		(layer "In13.Cu")
		(net "P5E_CPU0_P2_TX_DP<14>")
	)
	(segment
		(start 373.79275 -273.740626)
		(end 373.799608 -273.74469)
		(width 0.1143)
		(layer "In13.Cu")
		(net "P5E_CPU0_P2_TX_DP<14>")
	)
	(segment
		(start 373.831866 -283.483558)
		(end 373.832628 -283.484066)
		(width 0.1143)
		(layer "In13.Cu")
		(net "P5E_CPU0_P2_TX_DP<14>")
	)
	(segment
		(start 373.863616 -279.250394)
		(end 373.832628 -279.268174)
		(width 0.1143)
		(layer "In13.Cu")
		(net "P5E_CPU0_P2_TX_DP<14>")
	)
	(segment
		(start 373.831866 -273.763486)
		(end 373.832628 -273.763994)
		(width 0.1143)
		(layer "In13.Cu")
		(net "P5E_CPU0_P2_TX_DP<14>")
	)
	(segment
		(start 373.831866 -290.608512)
		(end 373.827294 -290.610798)
		(width 0.1143)
		(layer "In13.Cu")
		(net "P5E_CPU0_P2_TX_DP<14>")
	)
	(segment
		(start 373.8245 -285.752794)
		(end 373.821198 -285.754826)
		(width 0.1143)
		(layer "In13.Cu")
		(net "P5E_CPU0_P2_TX_DP<14>")
	)
	(segment
		(start 427.736 -381.055118)
		(end 427.736 -381.481838)
		(width 0.14224)
		(layer "In13.Cu")
		(net "P5E_CPU0_P2_TX_DP<14>")
	)
	(segment
		(start 373.829326 -277.650194)
		(end 373.822976 -277.65375)
		(width 0.1143)
		(layer "In13.Cu")
		(net "P5E_CPU0_P2_TX_DP<14>")
	)
	(segment
		(start 373.831866 -278.623522)
		(end 373.832628 -278.62403)
		(width 0.1143)
		(layer "In13.Cu")
		(net "P5E_CPU0_P2_TX_DP<14>")
	)
	(segment
		(start 373.8245 -282.51277)
		(end 373.821198 -282.514802)
		(width 0.1143)
		(layer "In13.Cu")
		(net "P5E_CPU0_P2_TX_DP<14>")
	)
	(segment
		(start 373.832628 -282.508452)
		(end 373.831866 -282.508706)
		(width 0.1143)
		(layer "In13.Cu")
		(net "P5E_CPU0_P2_TX_DP<14>")
	)
	(segment
		(start 373.7991 -288.32429)
		(end 373.834914 -288.345118)
		(width 0.1143)
		(layer "In13.Cu")
		(net "P5E_CPU0_P2_TX_DP<14>")
	)
	(segment
		(start 373.822976 -274.413726)
		(end 373.79275 -274.431506)
		(width 0.1143)
		(layer "In13.Cu")
		(net "P5E_CPU0_P2_TX_DP<14>")
	)
	(segment
		(start 373.822214 -292.234112)
		(end 373.819674 -292.235636)
		(width 0.1143)
		(layer "In13.Cu")
		(net "P5E_CPU0_P2_TX_DP<14>")
	)
	(segment
		(start 426.921422 -377.11253)
		(end 427.115224 -377.11253)
		(width 0.14224)
		(layer "In13.Cu")
		(net "P5E_CPU0_P2_TX_DP<14>")
	)
	(segment
		(start 373.831866 -276.028658)
		(end 373.83085 -276.029166)
		(width 0.1143)
		(layer "In13.Cu")
		(net "P5E_CPU0_P2_TX_DP<14>")
	)
	(segment
		(start 373.795544 -280.909522)
		(end 373.79275 -280.911554)
		(width 0.1143)
		(layer "In13.Cu")
		(net "P5E_CPU0_P2_TX_DP<14>")
	)
	(segment
		(start 424.938444 -374.392444)
		(end 425.24045 -374.69445)
		(width 0.14224)
		(layer "In13.Cu")
		(net "P5E_CPU0_P2_TX_DP<14>")
	)
	(segment
		(start 374.303798 -295.63441)
		(end 374.334024 -295.651682)
		(width 0.1143)
		(layer "In13.Cu")
		(net "P5E_CPU0_P2_TX_DP<14>")
	)
	(segment
		(start 373.827294 -284.131004)
		(end 373.825262 -284.132274)
		(width 0.1143)
		(layer "In13.Cu")
		(net "P5E_CPU0_P2_TX_DP<14>")
	)
	(segment
		(start 373.83466 -283.485336)
		(end 373.835168 -283.485336)
		(width 0.1143)
		(layer "In13.Cu")
		(net "P5E_CPU0_P2_TX_DP<14>")
	)
	(segment
		(start 373.831866 -285.10357)
		(end 373.832628 -285.104078)
		(width 0.1143)
		(layer "In13.Cu")
		(net "P5E_CPU0_P2_TX_DP<14>")
	)
	(segment
		(start 373.765826 -293.161466)
		(end 373.792242 -293.180516)
		(width 0.1143)
		(layer "In13.Cu")
		(net "P5E_CPU0_P2_TX_DP<14>")
	)
	(segment
		(start 373.80037 -275.36521)
		(end 373.831866 -275.383498)
		(width 0.1143)
		(layer "In13.Cu")
		(net "P5E_CPU0_P2_TX_DP<14>")
	)
	(segment
		(start 373.822976 -279.273762)
		(end 373.79275 -279.291542)
		(width 0.1143)
		(layer "In13.Cu")
		(net "P5E_CPU0_P2_TX_DP<14>")
	)
	(segment
		(start 373.863616 -276.01037)
		(end 373.832628 -276.02815)
		(width 0.1143)
		(layer "In13.Cu")
		(net "P5E_CPU0_P2_TX_DP<14>")
	)
	(segment
		(start 373.822976 -277.65375)
		(end 373.79275 -277.67153)
		(width 0.1143)
		(layer "In13.Cu")
		(net "P5E_CPU0_P2_TX_DP<14>")
	)
	(segment
		(start 427.19625 -384.766058)
		(end 426.90542 -384.475228)
		(width 0.14224)
		(layer "In13.Cu")
		(net "P5E_CPU0_P2_TX_DP<14>")
	)
	(segment
		(start 425.823888 -375.13641)
		(end 425.823888 -375.628662)
		(width 0.14224)
		(layer "In13.Cu")
		(net "P5E_CPU0_P2_TX_DP<14>")
	)
	(segment
		(start 373.826278 -292.231826)
		(end 373.823738 -292.23335)
		(width 0.1143)
		(layer "In13.Cu")
		(net "P5E_CPU0_P2_TX_DP<14>")
	)
	(segment
		(start 425.24045 -374.69445)
		(end 425.434506 -374.69445)
		(width 0.14224)
		(layer "In13.Cu")
		(net "P5E_CPU0_P2_TX_DP<14>")
	)
	(segment
		(start 400.56181 -360.256074)
		(end 404.63978 -366.359186)
		(width 0.14224)
		(layer "In13.Cu")
		(net "P5E_CPU0_P2_TX_DP<14>")
	)
	(segment
		(start 373.80037 -273.745198)
		(end 373.831866 -273.763486)
		(width 0.1143)
		(layer "In13.Cu")
		(net "P5E_CPU0_P2_TX_DP<14>")
	)
	(segment
		(start 373.8245 -284.132782)
		(end 373.821198 -284.134814)
		(width 0.1143)
		(layer "In13.Cu")
		(net "P5E_CPU0_P2_TX_DP<14>")
	)
	(segment
		(start 373.83466 -285.105348)
		(end 373.835168 -285.105348)
		(width 0.1143)
		(layer "In13.Cu")
		(net "P5E_CPU0_P2_TX_DP<14>")
	)
	(segment
		(start 373.8245 -293.8526)
		(end 373.821198 -293.854632)
		(width 0.1143)
		(layer "In13.Cu")
		(net "P5E_CPU0_P2_TX_DP<14>")
	)
	(segment
		(start 373.831866 -282.508706)
		(end 373.827294 -282.510992)
		(width 0.1143)
		(layer "In13.Cu")
		(net "P5E_CPU0_P2_TX_DP<14>")
	)
	(segment
		(start 373.825262 -284.132274)
		(end 373.8245 -284.132782)
		(width 0.1143)
		(layer "In13.Cu")
		(net "P5E_CPU0_P2_TX_DP<14>")
	)
	(segment
		(start 373.831866 -279.268682)
		(end 373.83085 -279.26919)
		(width 0.1143)
		(layer "In13.Cu")
		(net "P5E_CPU0_P2_TX_DP<14>")
	)
	(segment
		(start 373.80037 -278.605234)
		(end 373.831866 -278.623522)
		(width 0.1143)
		(layer "In13.Cu")
		(net "P5E_CPU0_P2_TX_DP<14>")
	)
	(segment
		(start 373.831866 -285.74873)
		(end 373.827294 -285.751016)
		(width 0.1143)
		(layer "In13.Cu")
		(net "P5E_CPU0_P2_TX_DP<14>")
	)
	(segment
		(start 373.79275 -294.800528)
		(end 373.83085 -294.82288)
		(width 0.1143)
		(layer "In13.Cu")
		(net "P5E_CPU0_P2_TX_DP<14>")
	)
	(segment
		(start 373.83085 -285.103062)
		(end 373.831866 -285.10357)
		(width 0.1143)
		(layer "In13.Cu")
		(net "P5E_CPU0_P2_TX_DP<14>")
	)
	(segment
		(start 373.827294 -293.850822)
		(end 373.825262 -293.852092)
		(width 0.1143)
		(layer "In13.Cu")
		(net "P5E_CPU0_P2_TX_DP<14>")
	)
	(segment
		(start 373.832628 -278.62403)
		(end 373.863616 -278.64181)
		(width 0.1143)
		(layer "In13.Cu")
		(net "P5E_CPU0_P2_TX_DP<14>")
	)
	(segment
		(start 373.83085 -294.82288)
		(end 373.833136 -294.823896)
		(width 0.1143)
		(layer "In13.Cu")
		(net "P5E_CPU0_P2_TX_DP<14>")
	)
	(segment
		(start 373.833136 -294.823896)
		(end 373.834406 -294.824658)
		(width 0.1143)
		(layer "In13.Cu")
		(net "P5E_CPU0_P2_TX_DP<14>")
	)
	(segment
		(start 373.83085 -279.26919)
		(end 373.829326 -279.270206)
		(width 0.1143)
		(layer "In13.Cu")
		(net "P5E_CPU0_P2_TX_DP<14>")
	)
	(segment
		(start 373.799608 -278.604726)
		(end 373.80037 -278.605234)
		(width 0.1143)
		(layer "In13.Cu")
		(net "P5E_CPU0_P2_TX_DP<14>")
	)
	(segment
		(start 423.987468 -373.247412)
		(end 424.938444 -374.198388)
		(width 0.14224)
		(layer "In13.Cu")
		(net "P5E_CPU0_P2_TX_DP<14>")
	)
	(segment
		(start 373.79275 -286.700722)
		(end 373.865394 -286.74314)
		(width 0.1143)
		(layer "In13.Cu")
		(net "P5E_CPU0_P2_TX_DP<14>")
	)
	(segment
		(start 373.834914 -288.986722)
		(end 373.832628 -288.988246)
		(width 0.1143)
		(layer "In13.Cu")
		(net "P5E_CPU0_P2_TX_DP<14>")
	)
	(segment
		(start 373.83466 -293.205154)
		(end 373.835168 -293.205154)
		(width 0.1143)
		(layer "In13.Cu")
		(net "P5E_CPU0_P2_TX_DP<14>")
	)
	(segment
		(start 373.825262 -285.752286)
		(end 373.8245 -285.752794)
		(width 0.1143)
		(layer "In13.Cu")
		(net "P5E_CPU0_P2_TX_DP<14>")
	)
	(segment
		(start 373.174768 -273.27606)
		(end 373.47271 -273.27606)
		(width 0.1143)
		(layer "In13.Cu")
		(net "P5E_CPU0_P2_TX_DP<14>")
	)
	(segment
		(start 373.831866 -277.64867)
		(end 373.83085 -277.649178)
		(width 0.1143)
		(layer "In13.Cu")
		(net "P5E_CPU0_P2_TX_DP<14>")
	)
	(segment
		(start 373.831866 -275.383498)
		(end 373.832628 -275.384006)
		(width 0.1143)
		(layer "In13.Cu")
		(net "P5E_CPU0_P2_TX_DP<14>")
	)
	(segment
		(start 373.825262 -282.512262)
		(end 373.8245 -282.51277)
		(width 0.1143)
		(layer "In13.Cu")
		(net "P5E_CPU0_P2_TX_DP<14>")
	)
	(segment
		(start 373.79275 -276.98065)
		(end 373.799608 -276.984714)
		(width 0.1143)
		(layer "In13.Cu")
		(net "P5E_CPU0_P2_TX_DP<14>")
	)
	(segment
		(start 373.79275 -278.600662)
		(end 373.799608 -278.604726)
		(width 0.1143)
		(layer "In13.Cu")
		(net "P5E_CPU0_P2_TX_DP<14>")
	)
	(segment
		(start 373.821198 -284.134814)
		(end 373.79275 -284.151578)
		(width 0.1143)
		(layer "In13.Cu")
		(net "P5E_CPU0_P2_TX_DP<14>")
	)
	(segment
		(start 427.87316 -380.917958)
		(end 427.736 -381.055118)
		(width 0.14224)
		(layer "In13.Cu")
		(net "P5E_CPU0_P2_TX_DP<14>")
	)
	(segment
		(start 373.831866 -281.863546)
		(end 373.832628 -281.864054)
		(width 0.1143)
		(layer "In13.Cu")
		(net "P5E_CPU0_P2_TX_DP<14>")
	)
	(segment
		(start 373.831866 -293.848536)
		(end 373.827294 -293.850822)
		(width 0.1143)
		(layer "In13.Cu")
		(net "P5E_CPU0_P2_TX_DP<14>")
	)
	(segment
		(start 373.832628 -273.763994)
		(end 373.863616 -273.781774)
		(width 0.1143)
		(layer "In13.Cu")
		(net "P5E_CPU0_P2_TX_DP<14>")
	)
	(segment
		(start 424.938444 -374.198388)
		(end 424.938444 -374.392444)
		(width 0.14224)
		(layer "In13.Cu")
		(net "P5E_CPU0_P2_TX_DP<14>")
	)
	(segment
		(start 373.827294 -292.231318)
		(end 373.826278 -292.231826)
		(width 0.1143)
		(layer "In13.Cu")
		(net "P5E_CPU0_P2_TX_DP<14>")
	)
	(segment
		(start 373.835422 -285.746952)
		(end 373.834914 -285.746952)
		(width 0.1143)
		(layer "In13.Cu")
		(net "P5E_CPU0_P2_TX_DP<14>")
	)
	(segment
		(start 373.832628 -276.02815)
		(end 373.831866 -276.028658)
		(width 0.1143)
		(layer "In13.Cu")
		(net "P5E_CPU0_P2_TX_DP<14>")
	)
	(segment
		(start 373.798846 -288.32429)
		(end 373.7991 -288.32429)
		(width 0.1143)
		(layer "In13.Cu")
		(net "P5E_CPU0_P2_TX_DP<14>")
	)
	(segment
		(start 373.832628 -290.608258)
		(end 373.831866 -290.608512)
		(width 0.1143)
		(layer "In13.Cu")
		(net "P5E_CPU0_P2_TX_DP<14>")
	)
	(segment
		(start 373.799608 -276.984714)
		(end 373.80037 -276.985222)
		(width 0.1143)
		(layer "In13.Cu")
		(net "P5E_CPU0_P2_TX_DP<14>")
	)
	(segment
		(start 373.834914 -293.846758)
		(end 373.832628 -293.848282)
		(width 0.1143)
		(layer "In13.Cu")
		(net "P5E_CPU0_P2_TX_DP<14>")
	)
	(segment
		(start 374.019572 -287.045908)
		(end 374.019572 -287.05048)
		(width 0.1143)
		(layer "In13.Cu")
		(net "P5E_CPU0_P2_TX_DP<14>")
	)
	(segment
		(start 373.83466 -289.96513)
		(end 373.835168 -289.96513)
		(width 0.1143)
		(layer "In13.Cu")
		(net "P5E_CPU0_P2_TX_DP<14>")
	)
	(segment
		(start 373.832628 -285.104078)
		(end 373.83466 -285.105348)
		(width 0.1143)
		(layer "In13.Cu")
		(net "P5E_CPU0_P2_TX_DP<14>")
	)
	(segment
		(start 373.831866 -277.00351)
		(end 373.832628 -277.004018)
		(width 0.1143)
		(layer "In13.Cu")
		(net "P5E_CPU0_P2_TX_DP<14>")
	)
	(segment
		(start 427.693582 -384.766058)
		(end 427.19625 -384.766058)
		(width 0.14224)
		(layer "In13.Cu")
		(net "P5E_CPU0_P2_TX_DP<14>")
	)
	(segment
		(start 373.863616 -277.630382)
		(end 373.832628 -277.648162)
		(width 0.1143)
		(layer "In13.Cu")
		(net "P5E_CPU0_P2_TX_DP<14>")
	)
	(segment
		(start 373.831866 -291.583364)
		(end 373.832628 -291.583872)
		(width 0.1143)
		(layer "In13.Cu")
		(net "P5E_CPU0_P2_TX_DP<14>")
	)
	(segment
		(start 373.822976 -276.033738)
		(end 373.79275 -276.051518)
		(width 0.1143)
		(layer "In13.Cu")
		(net "P5E_CPU0_P2_TX_DP<14>")
	)
	(segment
		(start 374.444006 -296.61231)
		(end 374.444006 -297.147742)
		(width 0.14224)
		(layer "In13.Cu")
		(net "P5E_CPU0_P2_TX_DP<14>")
	)
	(segment
		(start 373.79275 -283.460698)
		(end 373.799608 -283.464762)
		(width 0.1143)
		(layer "In13.Cu")
		(net "P5E_CPU0_P2_TX_DP<14>")
	)
	(segment
		(start 373.80037 -283.46527)
		(end 373.831866 -283.483558)
		(width 0.1143)
		(layer "In13.Cu")
		(net "P5E_CPU0_P2_TX_DP<14>")
	)
	(segment
		(start 373.831866 -284.128718)
		(end 373.827294 -284.131004)
		(width 0.1143)
		(layer "In13.Cu")
		(net "P5E_CPU0_P2_TX_DP<14>")
	)
	(segment
		(start 373.47271 -273.27606)
		(end 373.555514 -273.358864)
		(width 0.1143)
		(layer "In13.Cu")
		(net "P5E_CPU0_P2_TX_DP<14>")
	)
	(segment
		(start 373.8245 -290.612576)
		(end 373.821198 -290.614608)
		(width 0.1143)
		(layer "In13.Cu")
		(net "P5E_CPU0_P2_TX_DP<14>")
	)
	(segment
		(start 373.825262 -293.852092)
		(end 373.8245 -293.8526)
		(width 0.1143)
		(layer "In13.Cu")
		(net "P5E_CPU0_P2_TX_DP<14>")
	)
	(segment
		(start 373.79275 -275.360638)
		(end 373.799608 -275.364702)
		(width 0.1143)
		(layer "In13.Cu")
		(net "P5E_CPU0_P2_TX_DP<14>")
	)
	(segment
		(start 373.832628 -277.648162)
		(end 373.831866 -277.64867)
		(width 0.1143)
		(layer "In13.Cu")
		(net "P5E_CPU0_P2_TX_DP<14>")
	)
	(segment
		(start 374.489726 -296.538142)
		(end 374.444006 -296.583862)
		(width 0.1143)
		(layer "In13.Cu")
		(net "P5E_CPU0_P2_TX_DP<14>")
	)
	(segment
		(start 373.827294 -282.510992)
		(end 373.825262 -282.512262)
		(width 0.1143)
		(layer "In13.Cu")
		(net "P5E_CPU0_P2_TX_DP<14>")
	)
	(segment
		(start 373.832628 -292.228016)
		(end 373.831866 -292.228524)
		(width 0.1143)
		(layer "In13.Cu")
		(net "P5E_CPU0_P2_TX_DP<14>")
	)
	(segment
		(start 373.829326 -279.270206)
		(end 373.822976 -279.273762)
		(width 0.1143)
		(layer "In13.Cu")
		(net "P5E_CPU0_P2_TX_DP<14>")
	)
	(segment
		(start 427.115224 -377.11253)
		(end 427.835822 -377.833128)
		(width 0.14224)
		(layer "In13.Cu")
		(net "P5E_CPU0_P2_TX_DP<14>")
	)
	(segment
		(start 426.619416 -376.616722)
		(end 426.619416 -376.810524)
		(width 0.14224)
		(layer "In13.Cu")
		(net "P5E_CPU0_P2_TX_DP<14>")
	)
	(segment
		(start 373.883428 -277.616158)
		(end 373.863616 -277.630382)
		(width 0.1143)
		(layer "In13.Cu")
		(net "P5E_CPU0_P2_TX_DP<14>")
	)
	(arc
		(start 373.765826 -292.270688)
		(mid 373.53763 -292.71613)
		(end 373.765826 -293.161466)
		(width 0.1143)
		(layer "In13.Cu")
		(net "P5E_CPU0_P2_TX_DP<14>")
	)
	(arc
		(start 373.559324 -273.381724)
		(mid 373.640757 -273.584122)
		(end 373.79275 -273.740626)
		(width 0.1143)
		(layer "In13.Cu")
		(net "P5E_CPU0_P2_TX_DP<14>")
	)
	(arc
		(start 373.835168 -283.485336)
		(mid 374.019901 -283.806028)
		(end 373.835422 -284.12694)
		(width 0.1143)
		(layer "In13.Cu")
		(net "P5E_CPU0_P2_TX_DP<14>")
	)
	(arc
		(start 425.823888 -375.628662)
		(mid 425.85927 -375.806541)
		(end 425.960032 -375.957338)
		(width 0.14224)
		(layer "In13.Cu")
		(net "P5E_CPU0_P2_TX_DP<14>")
	)
	(arc
		(start 419.712648 -373.1514)
		(mid 419.857206 -373.195269)
		(end 420.007542 -373.210074)
		(width 0.14224)
		(layer "In13.Cu")
		(net "P5E_CPU0_P2_TX_DP<14>")
	)
	(arc
		(start 373.549418 -287.856168)
		(mid 373.613933 -288.118387)
		(end 373.79275 -288.320734)
		(width 0.1143)
		(layer "In13.Cu")
		(net "P5E_CPU0_P2_TX_DP<14>")
	)
	(arc
		(start 374.444006 -297.147742)
		(mid 374.451927 -297.227634)
		(end 374.475248 -297.30446)
		(width 0.14224)
		(layer "In13.Cu")
		(net "P5E_CPU0_P2_TX_DP<14>")
	)
	(arc
		(start 373.79275 -276.051518)
		(mid 373.549423 -276.516084)
		(end 373.79275 -276.98065)
		(width 0.1143)
		(layer "In13.Cu")
		(net "P5E_CPU0_P2_TX_DP<14>")
	)
	(arc
		(start 423.897298 -373.210074)
		(mid 423.946093 -373.21978)
		(end 423.987468 -373.247412)
		(width 0.14224)
		(layer "In13.Cu")
		(net "P5E_CPU0_P2_TX_DP<14>")
	)
	(arc
		(start 404.63978 -366.359186)
		(mid 404.731374 -366.470792)
		(end 404.84298 -366.562386)
		(width 0.14224)
		(layer "In13.Cu")
		(net "P5E_CPU0_P2_TX_DP<14>")
	)
	(arc
		(start 374.334024 -295.651682)
		(mid 374.369496 -295.681109)
		(end 374.40108 -295.714674)
		(width 0.1143)
		(layer "In13.Cu")
		(net "P5E_CPU0_P2_TX_DP<14>")
	)
	(arc
		(start 373.883428 -277.036022)
		(mid 374.032142 -277.32609)
		(end 373.883428 -277.616158)
		(width 0.1143)
		(layer "In13.Cu")
		(net "P5E_CPU0_P2_TX_DP<14>")
	)
	(arc
		(start 373.835168 -293.205154)
		(mid 374.019901 -293.525846)
		(end 373.835422 -293.846758)
		(width 0.1143)
		(layer "In13.Cu")
		(net "P5E_CPU0_P2_TX_DP<14>")
	)
	(arc
		(start 373.864632 -294.842692)
		(mid 373.978515 -294.973306)
		(end 374.019572 -295.14165)
		(width 0.1143)
		(layer "In13.Cu")
		(net "P5E_CPU0_P2_TX_DP<14>")
	)
	(arc
		(start 373.79275 -282.531566)
		(mid 373.549423 -282.996132)
		(end 373.79275 -283.460698)
		(width 0.1143)
		(layer "In13.Cu")
		(net "P5E_CPU0_P2_TX_DP<14>")
	)
	(arc
		(start 373.835168 -281.865324)
		(mid 374.019901 -282.186016)
		(end 373.835422 -282.506928)
		(width 0.1143)
		(layer "In13.Cu")
		(net "P5E_CPU0_P2_TX_DP<14>")
	)
	(arc
		(start 427.835822 -377.833128)
		(mid 427.863441 -377.874368)
		(end 427.87316 -377.923044)
		(width 0.14224)
		(layer "In13.Cu")
		(net "P5E_CPU0_P2_TX_DP<14>")
	)
	(arc
		(start 373.865394 -286.74314)
		(mid 373.978801 -286.876029)
		(end 374.019572 -287.045908)
		(width 0.1143)
		(layer "In13.Cu")
		(net "P5E_CPU0_P2_TX_DP<14>")
	)
	(arc
		(start 373.835168 -289.96513)
		(mid 374.019901 -290.285822)
		(end 373.835422 -290.606734)
		(width 0.1143)
		(layer "In13.Cu")
		(net "P5E_CPU0_P2_TX_DP<14>")
	)
	(arc
		(start 373.79275 -290.631372)
		(mid 373.549423 -291.095938)
		(end 373.79275 -291.560504)
		(width 0.1143)
		(layer "In13.Cu")
		(net "P5E_CPU0_P2_TX_DP<14>")
	)
	(arc
		(start 373.863616 -273.781774)
		(mid 374.014001 -274.086066)
		(end 373.863616 -274.390358)
		(width 0.1143)
		(layer "In13.Cu")
		(net "P5E_CPU0_P2_TX_DP<14>")
	)
	(arc
		(start 373.79275 -289.01136)
		(mid 373.549423 -289.475926)
		(end 373.79275 -289.940492)
		(width 0.1143)
		(layer "In13.Cu")
		(net "P5E_CPU0_P2_TX_DP<14>")
	)
	(arc
		(start 373.883428 -278.656034)
		(mid 374.032142 -278.946102)
		(end 373.883428 -279.23617)
		(width 0.1143)
		(layer "In13.Cu")
		(net "P5E_CPU0_P2_TX_DP<14>")
	)
	(arc
		(start 373.835168 -288.345118)
		(mid 374.019901 -288.66581)
		(end 373.835422 -288.986722)
		(width 0.1143)
		(layer "In13.Cu")
		(net "P5E_CPU0_P2_TX_DP<14>")
	)
	(arc
		(start 373.79275 -284.151578)
		(mid 373.549423 -284.616144)
		(end 373.79275 -285.08071)
		(width 0.1143)
		(layer "In13.Cu")
		(net "P5E_CPU0_P2_TX_DP<14>")
	)
	(arc
		(start 373.79275 -285.77159)
		(mid 373.549423 -286.236156)
		(end 373.79275 -286.700722)
		(width 0.1143)
		(layer "In13.Cu")
		(net "P5E_CPU0_P2_TX_DP<14>")
	)
	(arc
		(start 373.79529 -287.389824)
		(mid 373.614638 -287.592569)
		(end 373.549418 -287.856168)
		(width 0.1143)
		(layer "In13.Cu")
		(net "P5E_CPU0_P2_TX_DP<14>")
	)
	(arc
		(start 373.79275 -277.67153)
		(mid 373.549423 -278.136096)
		(end 373.79275 -278.600662)
		(width 0.1143)
		(layer "In13.Cu")
		(net "P5E_CPU0_P2_TX_DP<14>")
	)
	(arc
		(start 374.019572 -287.05048)
		(mid 373.979317 -287.217293)
		(end 373.867426 -287.347406)
		(width 0.1143)
		(layer "In13.Cu")
		(net "P5E_CPU0_P2_TX_DP<14>")
	)
	(arc
		(start 427.87316 -384.58648)
		(mid 427.863458 -384.635164)
		(end 427.835822 -384.676396)
		(width 0.14224)
		(layer "In13.Cu")
		(net "P5E_CPU0_P2_TX_DP<14>")
	)
	(arc
		(start 373.79275 -293.871396)
		(mid 373.549423 -294.335962)
		(end 373.79275 -294.800528)
		(width 0.1143)
		(layer "In13.Cu")
		(net "P5E_CPU0_P2_TX_DP<14>")
	)
	(arc
		(start 373.835168 -285.105348)
		(mid 374.019901 -285.42604)
		(end 373.835422 -285.746952)
		(width 0.1143)
		(layer "In13.Cu")
		(net "P5E_CPU0_P2_TX_DP<14>")
	)
	(arc
		(start 374.40108 -295.714674)
		(mid 374.466732 -295.827482)
		(end 374.489726 -295.955974)
		(width 0.1143)
		(layer "In13.Cu")
		(net "P5E_CPU0_P2_TX_DP<14>")
	)
	(arc
		(start 373.79275 -279.291542)
		(mid 373.549423 -279.756108)
		(end 373.79275 -280.220674)
		(width 0.1143)
		(layer "In13.Cu")
		(net "P5E_CPU0_P2_TX_DP<14>")
	)
	(arc
		(start 373.555514 -273.358864)
		(mid 373.557302 -273.370313)
		(end 373.559324 -273.381724)
		(width 0.1143)
		(layer "In13.Cu")
		(net "P5E_CPU0_P2_TX_DP<14>")
	)
	(arc
		(start 373.79275 -280.911554)
		(mid 373.549423 -281.37612)
		(end 373.79275 -281.840686)
		(width 0.1143)
		(layer "In13.Cu")
		(net "P5E_CPU0_P2_TX_DP<14>")
	)
	(arc
		(start 425.78655 -375.046494)
		(mid 425.814169 -375.087734)
		(end 425.823888 -375.13641)
		(width 0.14224)
		(layer "In13.Cu")
		(net "P5E_CPU0_P2_TX_DP<14>")
	)
	(arc
		(start 373.863616 -280.261822)
		(mid 374.014001 -280.566114)
		(end 373.863616 -280.870406)
		(width 0.1143)
		(layer "In13.Cu")
		(net "P5E_CPU0_P2_TX_DP<14>")
	)
	(arc
		(start 427.783498 -384.72872)
		(mid 427.742258 -384.756339)
		(end 427.693582 -384.766058)
		(width 0.14224)
		(layer "In13.Cu")
		(net "P5E_CPU0_P2_TX_DP<14>")
	)
	(arc
		(start 374.019572 -295.14165)
		(mid 374.095726 -295.426072)
		(end 374.303798 -295.63441)
		(width 0.1143)
		(layer "In13.Cu")
		(net "P5E_CPU0_P2_TX_DP<14>")
	)
	(arc
		(start 373.862092 -291.60089)
		(mid 374.011006 -291.905944)
		(end 373.862092 -292.210998)
		(width 0.1143)
		(layer "In13.Cu")
		(net "P5E_CPU0_P2_TX_DP<14>")
	)
	(arc
		(start 373.79275 -274.431506)
		(mid 373.549423 -274.896072)
		(end 373.79275 -275.360638)
		(width 0.1143)
		(layer "In13.Cu")
		(net "P5E_CPU0_P2_TX_DP<14>")
	)
	(arc
		(start 373.863616 -275.401786)
		(mid 374.015205 -275.706078)
		(end 373.863616 -276.01037)
		(width 0.1143)
		(layer "In13.Cu")
		(net "P5E_CPU0_P2_TX_DP<14>")
	)
	(segment
		(start 424.44035 -378.39142)
		(end 424.14444 -378.68733)
		(width 0.12954)
		(layer "F.Cu")
		(net "P5E_CPU0_P2_TX_DP<13>")
	)
	(segment
		(start 372.707916 -269.770098)
		(end 373.174768 -270.036036)
		(width 0.12954)
		(layer "F.Cu")
		(net "P5E_CPU0_P2_TX_DP<13>")
	)
	(segment
		(start 424.44035 -377.68784)
		(end 424.44035 -378.39142)
		(width 0.12954)
		(layer "F.Cu")
		(net "P5E_CPU0_P2_TX_DP<13>")
	)
	(segment
		(start 424.16984 -377.41733)
		(end 424.44035 -377.68784)
		(width 0.12954)
		(layer "F.Cu")
		(net "P5E_CPU0_P2_TX_DP<13>")
	)
	(segment
		(start 372.852696 -280.220674)
		(end 372.890034 -280.242518)
		(width 0.1143)
		(layer "In13.Cu")
		(net "P5E_CPU0_P2_TX_DP<13>")
	)
	(segment
		(start 372.884192 -285.753302)
		(end 372.852696 -285.77159)
		(width 0.1143)
		(layer "In13.Cu")
		(net "P5E_CPU0_P2_TX_DP<13>")
	)
	(segment
		(start 372.885462 -279.272492)
		(end 372.852696 -279.291542)
		(width 0.1143)
		(layer "In13.Cu")
		(net "P5E_CPU0_P2_TX_DP<13>")
	)
	(segment
		(start 372.893844 -291.584634)
		(end 372.923562 -291.601652)
		(width 0.1143)
		(layer "In13.Cu")
		(net "P5E_CPU0_P2_TX_DP<13>")
	)
	(segment
		(start 372.852696 -283.460698)
		(end 372.890796 -283.48305)
		(width 0.1143)
		(layer "In13.Cu")
		(net "P5E_CPU0_P2_TX_DP<13>")
	)
	(segment
		(start 372.923562 -282.490418)
		(end 372.893844 -282.507436)
		(width 0.1143)
		(layer "In13.Cu")
		(net "P5E_CPU0_P2_TX_DP<13>")
	)
	(segment
		(start 372.892574 -291.583872)
		(end 372.893844 -291.584634)
		(width 0.1143)
		(layer "In13.Cu")
		(net "P5E_CPU0_P2_TX_DP<13>")
	)
	(segment
		(start 372.896638 -293.20617)
		(end 372.8974 -293.206678)
		(width 0.1143)
		(layer "In13.Cu")
		(net "P5E_CPU0_P2_TX_DP<13>")
	)
	(segment
		(start 372.923562 -290.590224)
		(end 372.893844 -290.607242)
		(width 0.1143)
		(layer "In13.Cu")
		(net "P5E_CPU0_P2_TX_DP<13>")
	)
	(segment
		(start 372.902226 -273.769328)
		(end 372.923562 -273.781774)
		(width 0.1143)
		(layer "In13.Cu")
		(net "P5E_CPU0_P2_TX_DP<13>")
	)
	(segment
		(start 372.898416 -289.967162)
		(end 372.899686 -289.967924)
		(width 0.1143)
		(layer "In13.Cu")
		(net "P5E_CPU0_P2_TX_DP<13>")
	)
	(segment
		(start 372.890034 -280.242518)
		(end 372.890796 -280.243026)
		(width 0.1143)
		(layer "In13.Cu")
		(net "P5E_CPU0_P2_TX_DP<13>")
	)
	(segment
		(start 372.897654 -277.006812)
		(end 372.898416 -277.00732)
		(width 0.1143)
		(layer "In13.Cu")
		(net "P5E_CPU0_P2_TX_DP<13>")
	)
	(segment
		(start 372.859554 -281.84475)
		(end 372.860316 -281.845258)
		(width 0.1143)
		(layer "In13.Cu")
		(net "P5E_CPU0_P2_TX_DP<13>")
	)
	(segment
		(start 372.852696 -285.08071)
		(end 372.890796 -285.103062)
		(width 0.1143)
		(layer "In13.Cu")
		(net "P5E_CPU0_P2_TX_DP<13>")
	)
	(segment
		(start 372.891812 -272.788634)
		(end 372.890796 -272.789142)
		(width 0.1143)
		(layer "In13.Cu")
		(net "P5E_CPU0_P2_TX_DP<13>")
	)
	(segment
		(start 372.892574 -285.104078)
		(end 372.893844 -285.10484)
		(width 0.1143)
		(layer "In13.Cu")
		(net "P5E_CPU0_P2_TX_DP<13>")
	)
	(segment
		(start 372.896638 -294.826182)
		(end 372.8974 -294.82669)
		(width 0.1143)
		(layer "In13.Cu")
		(net "P5E_CPU0_P2_TX_DP<13>")
	)
	(segment
		(start 372.884954 -285.752794)
		(end 372.884192 -285.753302)
		(width 0.1143)
		(layer "In13.Cu")
		(net "P5E_CPU0_P2_TX_DP<13>")
	)
	(segment
		(start 419.946582 -374.16867)
		(end 422.6433 -374.16867)
		(width 0.14224)
		(layer "In13.Cu")
		(net "P5E_CPU0_P2_TX_DP<13>")
	)
	(segment
		(start 372.893844 -282.507436)
		(end 372.892574 -282.508198)
		(width 0.1143)
		(layer "In13.Cu")
		(net "P5E_CPU0_P2_TX_DP<13>")
	)
	(segment
		(start 372.888256 -290.610544)
		(end 372.887494 -290.611052)
		(width 0.1143)
		(layer "In13.Cu")
		(net "P5E_CPU0_P2_TX_DP<13>")
	)
	(segment
		(start 372.923562 -284.11043)
		(end 372.893844 -284.127448)
		(width 0.1143)
		(layer "In13.Cu")
		(net "P5E_CPU0_P2_TX_DP<13>")
	)
	(segment
		(start 373.361966 -295.633394)
		(end 373.391938 -295.65092)
		(width 0.1143)
		(layer "In13.Cu")
		(net "P5E_CPU0_P2_TX_DP<13>")
	)
	(segment
		(start 372.859554 -276.984714)
		(end 372.860316 -276.985222)
		(width 0.1143)
		(layer "In13.Cu")
		(net "P5E_CPU0_P2_TX_DP<13>")
	)
	(segment
		(start 372.895368 -293.205408)
		(end 372.896638 -293.20617)
		(width 0.1143)
		(layer "In13.Cu")
		(net "P5E_CPU0_P2_TX_DP<13>")
	)
	(segment
		(start 373.361966 -270.358616)
		(end 373.32285 -270.381476)
		(width 0.1143)
		(layer "In13.Cu")
		(net "P5E_CPU0_P2_TX_DP<13>")
	)
	(segment
		(start 372.887494 -272.791174)
		(end 372.886224 -272.791936)
		(width 0.1143)
		(layer "In13.Cu")
		(net "P5E_CPU0_P2_TX_DP<13>")
	)
	(segment
		(start 372.85549 -280.909522)
		(end 372.852696 -280.911554)
		(width 0.1143)
		(layer "In13.Cu")
		(net "P5E_CPU0_P2_TX_DP<13>")
	)
	(segment
		(start 372.890796 -272.789142)
		(end 372.889272 -272.790158)
		(width 0.1143)
		(layer "In13.Cu")
		(net "P5E_CPU0_P2_TX_DP<13>")
	)
	(segment
		(start 372.887494 -290.611052)
		(end 372.884954 -290.612576)
		(width 0.1143)
		(layer "In13.Cu")
		(net "P5E_CPU0_P2_TX_DP<13>")
	)
	(segment
		(start 372.891812 -284.128718)
		(end 372.890796 -284.129226)
		(width 0.1143)
		(layer "In13.Cu")
		(net "P5E_CPU0_P2_TX_DP<13>")
	)
	(segment
		(start 372.889272 -290.610036)
		(end 372.888256 -290.610544)
		(width 0.1143)
		(layer "In13.Cu")
		(net "P5E_CPU0_P2_TX_DP<13>")
	)
	(segment
		(start 373.549672 -295.955974)
		(end 373.549672 -296.538142)
		(width 0.1143)
		(layer "In13.Cu")
		(net "P5E_CPU0_P2_TX_DP<13>")
	)
	(segment
		(start 372.892574 -274.408138)
		(end 372.891812 -274.408646)
		(width 0.1143)
		(layer "In13.Cu")
		(net "P5E_CPU0_P2_TX_DP<13>")
	)
	(segment
		(start 372.852696 -276.98065)
		(end 372.859554 -276.984714)
		(width 0.1143)
		(layer "In13.Cu")
		(net "P5E_CPU0_P2_TX_DP<13>")
	)
	(segment
		(start 372.852696 -278.600662)
		(end 372.859554 -278.604726)
		(width 0.1143)
		(layer "In13.Cu")
		(net "P5E_CPU0_P2_TX_DP<13>")
	)
	(segment
		(start 372.895368 -277.005542)
		(end 372.89613 -277.00605)
		(width 0.1143)
		(layer "In13.Cu")
		(net "P5E_CPU0_P2_TX_DP<13>")
	)
	(segment
		(start 372.923562 -274.390358)
		(end 372.892574 -274.408138)
		(width 0.1143)
		(layer "In13.Cu")
		(net "P5E_CPU0_P2_TX_DP<13>")
	)
	(segment
		(start 372.923562 -279.250394)
		(end 372.892574 -279.268174)
		(width 0.1143)
		(layer "In13.Cu")
		(net "P5E_CPU0_P2_TX_DP<13>")
	)
	(segment
		(start 372.889272 -279.270206)
		(end 372.887494 -279.271222)
		(width 0.1143)
		(layer "In13.Cu")
		(net "P5E_CPU0_P2_TX_DP<13>")
	)
	(segment
		(start 372.889272 -285.750254)
		(end 372.888256 -285.750762)
		(width 0.1143)
		(layer "In13.Cu")
		(net "P5E_CPU0_P2_TX_DP<13>")
	)
	(segment
		(start 372.889272 -293.85006)
		(end 372.852696 -293.871396)
		(width 0.1143)
		(layer "In13.Cu")
		(net "P5E_CPU0_P2_TX_DP<13>")
	)
	(segment
		(start 372.887494 -279.271222)
		(end 372.886224 -279.271984)
		(width 0.1143)
		(layer "In13.Cu")
		(net "P5E_CPU0_P2_TX_DP<13>")
	)
	(segment
		(start 372.902226 -293.209218)
		(end 372.923562 -293.221664)
		(width 0.1143)
		(layer "In13.Cu")
		(net "P5E_CPU0_P2_TX_DP<13>")
	)
	(segment
		(start 372.899686 -289.967924)
		(end 372.902226 -289.969194)
		(width 0.1143)
		(layer "In13.Cu")
		(net "P5E_CPU0_P2_TX_DP<13>")
	)
	(segment
		(start 372.860316 -293.185088)
		(end 372.891812 -293.203376)
		(width 0.1143)
		(layer "In13.Cu")
		(net "P5E_CPU0_P2_TX_DP<13>")
	)
	(segment
		(start 372.892574 -282.508198)
		(end 372.891812 -282.508706)
		(width 0.1143)
		(layer "In13.Cu")
		(net "P5E_CPU0_P2_TX_DP<13>")
	)
	(segment
		(start 372.884192 -284.13329)
		(end 372.852696 -284.151578)
		(width 0.1143)
		(layer "In13.Cu")
		(net "P5E_CPU0_P2_TX_DP<13>")
	)
	(segment
		(start 372.891812 -288.343594)
		(end 372.92534 -288.363152)
		(width 0.1143)
		(layer "In13.Cu")
		(net "P5E_CPU0_P2_TX_DP<13>")
	)
	(segment
		(start 372.887494 -292.231064)
		(end 372.884954 -292.232588)
		(width 0.1143)
		(layer "In13.Cu")
		(net "P5E_CPU0_P2_TX_DP<13>")
	)
	(segment
		(start 372.891812 -294.823388)
		(end 372.892574 -294.823896)
		(width 0.1143)
		(layer "In13.Cu")
		(net "P5E_CPU0_P2_TX_DP<13>")
	)
	(segment
		(start 372.890796 -291.582856)
		(end 372.891812 -291.583364)
		(width 0.1143)
		(layer "In13.Cu")
		(net "P5E_CPU0_P2_TX_DP<13>")
	)
	(segment
		(start 372.892574 -278.62403)
		(end 372.895368 -278.625554)
		(width 0.1143)
		(layer "In13.Cu")
		(net "P5E_CPU0_P2_TX_DP<13>")
	)
	(segment
		(start 372.889272 -271.170146)
		(end 372.887494 -271.171162)
		(width 0.1143)
		(layer "In13.Cu")
		(net "P5E_CPU0_P2_TX_DP<13>")
	)
	(segment
		(start 372.891812 -286.723582)
		(end 372.92534 -286.74314)
		(width 0.1143)
		(layer "In13.Cu")
		(net "P5E_CPU0_P2_TX_DP<13>")
	)
	(segment
		(start 372.852696 -293.180516)
		(end 372.859554 -293.18458)
		(width 0.1143)
		(layer "In13.Cu")
		(net "P5E_CPU0_P2_TX_DP<13>")
	)
	(segment
		(start 372.890796 -292.229032)
		(end 372.889272 -292.230048)
		(width 0.1143)
		(layer "In13.Cu")
		(net "P5E_CPU0_P2_TX_DP<13>")
	)
	(segment
		(start 372.852696 -286.700722)
		(end 372.891812 -286.723582)
		(width 0.1143)
		(layer "In13.Cu")
		(net "P5E_CPU0_P2_TX_DP<13>")
	)
	(segment
		(start 372.892574 -277.004018)
		(end 372.895368 -277.005542)
		(width 0.1143)
		(layer "In13.Cu")
		(net "P5E_CPU0_P2_TX_DP<13>")
	)
	(segment
		(start 372.890796 -282.509214)
		(end 372.889272 -282.51023)
		(width 0.1143)
		(layer "In13.Cu")
		(net "P5E_CPU0_P2_TX_DP<13>")
	)
	(segment
		(start 422.83634 -374.24868)
		(end 424.423332 -375.835672)
		(width 0.14224)
		(layer "In13.Cu")
		(net "P5E_CPU0_P2_TX_DP<13>")
	)
	(segment
		(start 372.891812 -273.763486)
		(end 372.892574 -273.763994)
		(width 0.1143)
		(layer "In13.Cu")
		(net "P5E_CPU0_P2_TX_DP<13>")
	)
	(segment
		(start 372.923562 -288.970212)
		(end 372.893844 -288.98723)
		(width 0.1143)
		(layer "In13.Cu")
		(net "P5E_CPU0_P2_TX_DP<13>")
	)
	(segment
		(start 372.893844 -293.204646)
		(end 372.895368 -293.205408)
		(width 0.1143)
		(layer "In13.Cu")
		(net "P5E_CPU0_P2_TX_DP<13>")
	)
	(segment
		(start 372.897654 -275.3868)
		(end 372.898416 -275.387308)
		(width 0.1143)
		(layer "In13.Cu")
		(net "P5E_CPU0_P2_TX_DP<13>")
	)
	(segment
		(start 372.923562 -293.830248)
		(end 372.891812 -293.848536)
		(width 0.1143)
		(layer "In13.Cu")
		(net "P5E_CPU0_P2_TX_DP<13>")
	)
	(segment
		(start 372.889272 -288.990024)
		(end 372.888256 -288.990532)
		(width 0.1143)
		(layer "In13.Cu")
		(net "P5E_CPU0_P2_TX_DP<13>")
	)
	(segment
		(start 372.888256 -284.13075)
		(end 372.887494 -284.131258)
		(width 0.1143)
		(layer "In13.Cu")
		(net "P5E_CPU0_P2_TX_DP<13>")
	)
	(segment
		(start 372.884954 -290.612576)
		(end 372.884192 -290.613084)
		(width 0.1143)
		(layer "In13.Cu")
		(net "P5E_CPU0_P2_TX_DP<13>")
	)
	(segment
		(start 372.884192 -292.233096)
		(end 372.852696 -292.251384)
		(width 0.1143)
		(layer "In13.Cu")
		(net "P5E_CPU0_P2_TX_DP<13>")
	)
	(segment
		(start 372.891812 -277.64867)
		(end 372.890796 -277.649178)
		(width 0.1143)
		(layer "In13.Cu")
		(net "P5E_CPU0_P2_TX_DP<13>")
	)
	(segment
		(start 372.887494 -274.411186)
		(end 372.886224 -274.411948)
		(width 0.1143)
		(layer "In13.Cu")
		(net "P5E_CPU0_P2_TX_DP<13>")
	)
	(segment
		(start 372.923562 -280.870406)
		(end 372.891812 -280.888694)
		(width 0.1143)
		(layer "In13.Cu")
		(net "P5E_CPU0_P2_TX_DP<13>")
	)
	(segment
		(start 372.893844 -288.98723)
		(end 372.892574 -288.987992)
		(width 0.1143)
		(layer "In13.Cu")
		(net "P5E_CPU0_P2_TX_DP<13>")
	)
	(segment
		(start 372.902226 -275.38934)
		(end 372.923562 -275.401786)
		(width 0.1143)
		(layer "In13.Cu")
		(net "P5E_CPU0_P2_TX_DP<13>")
	)
	(segment
		(start 373.535194 -297.55973)
		(end 399.683224 -360.660696)
		(width 0.14224)
		(layer "In13.Cu")
		(net "P5E_CPU0_P2_TX_DP<13>")
	)
	(segment
		(start 372.892574 -283.484066)
		(end 372.893844 -283.484828)
		(width 0.1143)
		(layer "In13.Cu")
		(net "P5E_CPU0_P2_TX_DP<13>")
	)
	(segment
		(start 372.890796 -293.849044)
		(end 372.889272 -293.85006)
		(width 0.1143)
		(layer "In13.Cu")
		(net "P5E_CPU0_P2_TX_DP<13>")
	)
	(segment
		(start 372.893844 -292.227254)
		(end 372.892574 -292.228016)
		(width 0.1143)
		(layer "In13.Cu")
		(net "P5E_CPU0_P2_TX_DP<13>")
	)
	(segment
		(start 372.852696 -291.560504)
		(end 372.890796 -291.582856)
		(width 0.1143)
		(layer "In13.Cu")
		(net "P5E_CPU0_P2_TX_DP<13>")
	)
	(segment
		(start 372.889272 -274.41017)
		(end 372.887494 -274.411186)
		(width 0.1143)
		(layer "In13.Cu")
		(net "P5E_CPU0_P2_TX_DP<13>")
	)
	(segment
		(start 372.890796 -283.48305)
		(end 372.891812 -283.483558)
		(width 0.1143)
		(layer "In13.Cu")
		(net "P5E_CPU0_P2_TX_DP<13>")
	)
	(segment
		(start 372.852696 -273.740626)
		(end 372.859554 -273.74469)
		(width 0.1143)
		(layer "In13.Cu")
		(net "P5E_CPU0_P2_TX_DP<13>")
	)
	(segment
		(start 372.893844 -281.864816)
		(end 372.895368 -281.865578)
		(width 0.1143)
		(layer "In13.Cu")
		(net "P5E_CPU0_P2_TX_DP<13>")
	)
	(segment
		(start 372.860316 -273.745198)
		(end 372.891812 -273.763486)
		(width 0.1143)
		(layer "In13.Cu")
		(net "P5E_CPU0_P2_TX_DP<13>")
	)
	(segment
		(start 372.895368 -273.765518)
		(end 372.89613 -273.766026)
		(width 0.1143)
		(layer "In13.Cu")
		(net "P5E_CPU0_P2_TX_DP<13>")
	)
	(segment
		(start 372.923562 -292.210236)
		(end 372.893844 -292.227254)
		(width 0.1143)
		(layer "In13.Cu")
		(net "P5E_CPU0_P2_TX_DP<13>")
	)
	(segment
		(start 372.890796 -277.649178)
		(end 372.889272 -277.650194)
		(width 0.1143)
		(layer "In13.Cu")
		(net "P5E_CPU0_P2_TX_DP<13>")
	)
	(segment
		(start 372.891812 -293.848536)
		(end 372.890796 -293.849044)
		(width 0.1143)
		(layer "In13.Cu")
		(net "P5E_CPU0_P2_TX_DP<13>")
	)
	(segment
		(start 372.898416 -281.867356)
		(end 372.899686 -281.868118)
		(width 0.1143)
		(layer "In13.Cu")
		(net "P5E_CPU0_P2_TX_DP<13>")
	)
	(segment
		(start 372.895368 -294.82542)
		(end 372.896638 -294.826182)
		(width 0.1143)
		(layer "In13.Cu")
		(net "P5E_CPU0_P2_TX_DP<13>")
	)
	(segment
		(start 372.891812 -285.74873)
		(end 372.890796 -285.749238)
		(width 0.1143)
		(layer "In13.Cu")
		(net "P5E_CPU0_P2_TX_DP<13>")
	)
	(segment
		(start 372.884192 -290.613084)
		(end 372.852696 -290.631372)
		(width 0.1143)
		(layer "In13.Cu")
		(net "P5E_CPU0_P2_TX_DP<13>")
	)
	(segment
		(start 372.891812 -278.623522)
		(end 372.892574 -278.62403)
		(width 0.1143)
		(layer "In13.Cu")
		(net "P5E_CPU0_P2_TX_DP<13>")
	)
	(segment
		(start 372.896638 -281.86634)
		(end 372.8974 -281.866848)
		(width 0.1143)
		(layer "In13.Cu")
		(net "P5E_CPU0_P2_TX_DP<13>")
	)
	(segment
		(start 372.896638 -289.966146)
		(end 372.8974 -289.966654)
		(width 0.1143)
		(layer "In13.Cu")
		(net "P5E_CPU0_P2_TX_DP<13>")
	)
	(segment
		(start 372.852696 -281.840686)
		(end 372.859554 -281.84475)
		(width 0.1143)
		(layer "In13.Cu")
		(net "P5E_CPU0_P2_TX_DP<13>")
	)
	(segment
		(start 372.893844 -294.824658)
		(end 372.895368 -294.82542)
		(width 0.1143)
		(layer "In13.Cu")
		(net "P5E_CPU0_P2_TX_DP<13>")
	)
	(segment
		(start 372.852696 -289.940492)
		(end 372.859554 -289.944556)
		(width 0.1143)
		(layer "In13.Cu")
		(net "P5E_CPU0_P2_TX_DP<13>")
	)
	(segment
		(start 372.895368 -275.38553)
		(end 372.89613 -275.386038)
		(width 0.1143)
		(layer "In13.Cu")
		(net "P5E_CPU0_P2_TX_DP<13>")
	)
	(segment
		(start 372.890796 -285.749238)
		(end 372.889272 -285.750254)
		(width 0.1143)
		(layer "In13.Cu")
		(net "P5E_CPU0_P2_TX_DP<13>")
	)
	(segment
		(start 372.892574 -277.648162)
		(end 372.891812 -277.64867)
		(width 0.1143)
		(layer "In13.Cu")
		(net "P5E_CPU0_P2_TX_DP<13>")
	)
	(segment
		(start 372.8974 -293.206678)
		(end 372.898416 -293.207186)
		(width 0.1143)
		(layer "In13.Cu")
		(net "P5E_CPU0_P2_TX_DP<13>")
	)
	(segment
		(start 372.8974 -281.866848)
		(end 372.898416 -281.867356)
		(width 0.1143)
		(layer "In13.Cu")
		(net "P5E_CPU0_P2_TX_DP<13>")
	)
	(segment
		(start 372.898416 -273.767296)
		(end 372.899686 -273.768058)
		(width 0.1143)
		(layer "In13.Cu")
		(net "P5E_CPU0_P2_TX_DP<13>")
	)
	(segment
		(start 372.890796 -288.989008)
		(end 372.889272 -288.990024)
		(width 0.1143)
		(layer "In13.Cu")
		(net "P5E_CPU0_P2_TX_DP<13>")
	)
	(segment
		(start 372.892574 -284.12821)
		(end 372.891812 -284.128718)
		(width 0.1143)
		(layer "In13.Cu")
		(net "P5E_CPU0_P2_TX_DP<13>")
	)
	(segment
		(start 372.897654 -272.146776)
		(end 372.898416 -272.147284)
		(width 0.1143)
		(layer "In13.Cu")
		(net "P5E_CPU0_P2_TX_DP<13>")
	)
	(segment
		(start 372.891812 -272.143474)
		(end 372.892574 -272.143982)
		(width 0.1143)
		(layer "In13.Cu")
		(net "P5E_CPU0_P2_TX_DP<13>")
	)
	(segment
		(start 373.534686 -297.55973)
		(end 373.535194 -297.55973)
		(width 0.14224)
		(layer "In13.Cu")
		(net "P5E_CPU0_P2_TX_DP<13>")
	)
	(segment
		(start 372.898416 -278.627332)
		(end 372.899686 -278.628094)
		(width 0.1143)
		(layer "In13.Cu")
		(net "P5E_CPU0_P2_TX_DP<13>")
	)
	(segment
		(start 406.103582 -368.535712)
		(end 419.475666 -374.075198)
		(width 0.14224)
		(layer "In13.Cu")
		(net "P5E_CPU0_P2_TX_DP<13>")
	)
	(segment
		(start 372.885462 -272.792444)
		(end 372.852696 -272.811494)
		(width 0.1143)
		(layer "In13.Cu")
		(net "P5E_CPU0_P2_TX_DP<13>")
	)
	(segment
		(start 372.892574 -290.608004)
		(end 372.891812 -290.608512)
		(width 0.1143)
		(layer "In13.Cu")
		(net "P5E_CPU0_P2_TX_DP<13>")
	)
	(segment
		(start 372.89613 -275.386038)
		(end 372.897654 -275.3868)
		(width 0.1143)
		(layer "In13.Cu")
		(net "P5E_CPU0_P2_TX_DP<13>")
	)
	(segment
		(start 372.8974 -294.82669)
		(end 372.898416 -294.827198)
		(width 0.1143)
		(layer "In13.Cu")
		(net "P5E_CPU0_P2_TX_DP<13>")
	)
	(segment
		(start 372.860316 -281.845258)
		(end 372.891812 -281.863546)
		(width 0.1143)
		(layer "In13.Cu")
		(net "P5E_CPU0_P2_TX_DP<13>")
	)
	(segment
		(start 372.89613 -272.146014)
		(end 372.897654 -272.146776)
		(width 0.1143)
		(layer "In13.Cu")
		(net "P5E_CPU0_P2_TX_DP<13>")
	)
	(segment
		(start 372.886224 -271.171924)
		(end 372.885462 -271.172432)
		(width 0.1143)
		(layer "In13.Cu")
		(net "P5E_CPU0_P2_TX_DP<13>")
	)
	(segment
		(start 372.890796 -279.26919)
		(end 372.889272 -279.270206)
		(width 0.1143)
		(layer "In13.Cu")
		(net "P5E_CPU0_P2_TX_DP<13>")
	)
	(segment
		(start 372.893844 -289.964622)
		(end 372.895368 -289.965384)
		(width 0.1143)
		(layer "In13.Cu")
		(net "P5E_CPU0_P2_TX_DP<13>")
	)
	(segment
		(start 372.860316 -275.36521)
		(end 372.891812 -275.383498)
		(width 0.1143)
		(layer "In13.Cu")
		(net "P5E_CPU0_P2_TX_DP<13>")
	)
	(segment
		(start 372.888256 -292.230556)
		(end 372.887494 -292.231064)
		(width 0.1143)
		(layer "In13.Cu")
		(net "P5E_CPU0_P2_TX_DP<13>")
	)
	(segment
		(start 372.859554 -275.364702)
		(end 372.860316 -275.36521)
		(width 0.1143)
		(layer "In13.Cu")
		(net "P5E_CPU0_P2_TX_DP<13>")
	)
	(segment
		(start 372.889272 -292.230048)
		(end 372.888256 -292.230556)
		(width 0.1143)
		(layer "In13.Cu")
		(net "P5E_CPU0_P2_TX_DP<13>")
	)
	(segment
		(start 372.889272 -276.030182)
		(end 372.887494 -276.031198)
		(width 0.1143)
		(layer "In13.Cu")
		(net "P5E_CPU0_P2_TX_DP<13>")
	)
	(segment
		(start 373.174768 -270.036036)
		(end 373.47271 -270.036036)
		(width 0.1143)
		(layer "In13.Cu")
		(net "P5E_CPU0_P2_TX_DP<13>")
	)
	(segment
		(start 372.895368 -278.625554)
		(end 372.89613 -278.626062)
		(width 0.1143)
		(layer "In13.Cu")
		(net "P5E_CPU0_P2_TX_DP<13>")
	)
	(segment
		(start 372.884954 -292.232588)
		(end 372.884192 -292.233096)
		(width 0.1143)
		(layer "In13.Cu")
		(net "P5E_CPU0_P2_TX_DP<13>")
	)
	(segment
		(start 372.891812 -283.483558)
		(end 372.892574 -283.484066)
		(width 0.1143)
		(layer "In13.Cu")
		(net "P5E_CPU0_P2_TX_DP<13>")
	)
	(segment
		(start 372.892574 -272.788126)
		(end 372.891812 -272.788634)
		(width 0.1143)
		(layer "In13.Cu")
		(net "P5E_CPU0_P2_TX_DP<13>")
	)
	(segment
		(start 372.859554 -278.604726)
		(end 372.860316 -278.605234)
		(width 0.1143)
		(layer "In13.Cu")
		(net "P5E_CPU0_P2_TX_DP<13>")
	)
	(segment
		(start 372.852696 -275.360638)
		(end 372.859554 -275.364702)
		(width 0.1143)
		(layer "In13.Cu")
		(net "P5E_CPU0_P2_TX_DP<13>")
	)
	(segment
		(start 372.923562 -277.630382)
		(end 372.892574 -277.648162)
		(width 0.1143)
		(layer "In13.Cu")
		(net "P5E_CPU0_P2_TX_DP<13>")
	)
	(segment
		(start 372.884954 -282.51277)
		(end 372.884192 -282.513278)
		(width 0.1143)
		(layer "In13.Cu")
		(net "P5E_CPU0_P2_TX_DP<13>")
	)
	(segment
		(start 372.890796 -285.103062)
		(end 372.891812 -285.10357)
		(width 0.1143)
		(layer "In13.Cu")
		(net "P5E_CPU0_P2_TX_DP<13>")
	)
	(segment
		(start 372.891812 -293.203376)
		(end 372.892574 -293.203884)
		(width 0.1143)
		(layer "In13.Cu")
		(net "P5E_CPU0_P2_TX_DP<13>")
	)
	(segment
		(start 372.899686 -278.628094)
		(end 372.902226 -278.629364)
		(width 0.1143)
		(layer "In13.Cu")
		(net "P5E_CPU0_P2_TX_DP<13>")
	)
	(segment
		(start 372.897654 -273.766788)
		(end 372.898416 -273.767296)
		(width 0.1143)
		(layer "In13.Cu")
		(net "P5E_CPU0_P2_TX_DP<13>")
	)
	(segment
		(start 372.898416 -272.147284)
		(end 372.899686 -272.148046)
		(width 0.1143)
		(layer "In13.Cu")
		(net "P5E_CPU0_P2_TX_DP<13>")
	)
	(segment
		(start 372.889272 -282.51023)
		(end 372.888256 -282.510738)
		(width 0.1143)
		(layer "In13.Cu")
		(net "P5E_CPU0_P2_TX_DP<13>")
	)
	(segment
		(start 372.902226 -272.149316)
		(end 372.923562 -272.161762)
		(width 0.1143)
		(layer "In13.Cu")
		(net "P5E_CPU0_P2_TX_DP<13>")
	)
	(segment
		(start 372.899686 -281.868118)
		(end 372.902226 -281.869388)
		(width 0.1143)
		(layer "In13.Cu")
		(net "P5E_CPU0_P2_TX_DP<13>")
	)
	(segment
		(start 372.899686 -293.207948)
		(end 372.902226 -293.209218)
		(width 0.1143)
		(layer "In13.Cu")
		(net "P5E_CPU0_P2_TX_DP<13>")
	)
	(segment
		(start 373.32412 -295.61155)
		(end 373.361712 -295.633394)
		(width 0.1143)
		(layer "In13.Cu")
		(net "P5E_CPU0_P2_TX_DP<13>")
	)
	(segment
		(start 372.890796 -271.16913)
		(end 372.889272 -271.170146)
		(width 0.1143)
		(layer "In13.Cu")
		(net "P5E_CPU0_P2_TX_DP<13>")
	)
	(segment
		(start 372.890796 -284.129226)
		(end 372.889272 -284.130242)
		(width 0.1143)
		(layer "In13.Cu")
		(net "P5E_CPU0_P2_TX_DP<13>")
	)
	(segment
		(start 372.885462 -271.172432)
		(end 372.852696 -271.191482)
		(width 0.1143)
		(layer "In13.Cu")
		(net "P5E_CPU0_P2_TX_DP<13>")
	)
	(segment
		(start 372.887494 -284.131258)
		(end 372.884954 -284.132782)
		(width 0.1143)
		(layer "In13.Cu")
		(net "P5E_CPU0_P2_TX_DP<13>")
	)
	(segment
		(start 372.923562 -285.730442)
		(end 372.893844 -285.74746)
		(width 0.1143)
		(layer "In13.Cu")
		(net "P5E_CPU0_P2_TX_DP<13>")
	)
	(segment
		(start 372.885462 -274.412456)
		(end 372.852696 -274.431506)
		(width 0.1143)
		(layer "In13.Cu")
		(net "P5E_CPU0_P2_TX_DP<13>")
	)
	(segment
		(start 372.891812 -280.888694)
		(end 372.85549 -280.909522)
		(width 0.1143)
		(layer "In13.Cu")
		(net "P5E_CPU0_P2_TX_DP<13>")
	)
	(segment
		(start 372.860316 -294.8051)
		(end 372.891812 -294.823388)
		(width 0.1143)
		(layer "In13.Cu")
		(net "P5E_CPU0_P2_TX_DP<13>")
	)
	(segment
		(start 372.89613 -277.00605)
		(end 372.897654 -277.006812)
		(width 0.1143)
		(layer "In13.Cu")
		(net "P5E_CPU0_P2_TX_DP<13>")
	)
	(segment
		(start 372.860316 -272.125186)
		(end 372.891812 -272.143474)
		(width 0.1143)
		(layer "In13.Cu")
		(net "P5E_CPU0_P2_TX_DP<13>")
	)
	(segment
		(start 372.89613 -273.766026)
		(end 372.897654 -273.766788)
		(width 0.1143)
		(layer "In13.Cu")
		(net "P5E_CPU0_P2_TX_DP<13>")
	)
	(segment
		(start 372.888256 -285.750762)
		(end 372.887494 -285.75127)
		(width 0.1143)
		(layer "In13.Cu")
		(net "P5E_CPU0_P2_TX_DP<13>")
	)
	(segment
		(start 372.852696 -288.320734)
		(end 372.891812 -288.343594)
		(width 0.1143)
		(layer "In13.Cu")
		(net "P5E_CPU0_P2_TX_DP<13>")
	)
	(segment
		(start 372.892574 -272.143982)
		(end 372.895368 -272.145506)
		(width 0.1143)
		(layer "In13.Cu")
		(net "P5E_CPU0_P2_TX_DP<13>")
	)
	(segment
		(start 372.891812 -290.608512)
		(end 372.890796 -290.60902)
		(width 0.1143)
		(layer "In13.Cu")
		(net "P5E_CPU0_P2_TX_DP<13>")
	)
	(segment
		(start 372.886224 -274.411948)
		(end 372.885462 -274.412456)
		(width 0.1143)
		(layer "In13.Cu")
		(net "P5E_CPU0_P2_TX_DP<13>")
	)
	(segment
		(start 372.893844 -285.74746)
		(end 372.892574 -285.748222)
		(width 0.1143)
		(layer "In13.Cu")
		(net "P5E_CPU0_P2_TX_DP<13>")
	)
	(segment
		(start 373.47271 -270.036036)
		(end 373.54256 -270.105886)
		(width 0.1143)
		(layer "In13.Cu")
		(net "P5E_CPU0_P2_TX_DP<13>")
	)
	(segment
		(start 372.891812 -287.368488)
		(end 372.855236 -287.389824)
		(width 0.1143)
		(layer "In13.Cu")
		(net "P5E_CPU0_P2_TX_DP<13>")
	)
	(segment
		(start 372.887494 -276.031198)
		(end 372.886224 -276.03196)
		(width 0.1143)
		(layer "In13.Cu")
		(net "P5E_CPU0_P2_TX_DP<13>")
	)
	(segment
		(start 372.892574 -271.168114)
		(end 372.891812 -271.168622)
		(width 0.1143)
		(layer "In13.Cu")
		(net "P5E_CPU0_P2_TX_DP<13>")
	)
	(segment
		(start 372.898416 -275.387308)
		(end 372.899686 -275.38807)
		(width 0.1143)
		(layer "In13.Cu")
		(net "P5E_CPU0_P2_TX_DP<13>")
	)
	(segment
		(start 372.892574 -289.96386)
		(end 372.893844 -289.964622)
		(width 0.1143)
		(layer "In13.Cu")
		(net "P5E_CPU0_P2_TX_DP<13>")
	)
	(segment
		(start 372.888256 -288.990532)
		(end 372.887494 -288.99104)
		(width 0.1143)
		(layer "In13.Cu")
		(net "P5E_CPU0_P2_TX_DP<13>")
	)
	(segment
		(start 372.892574 -294.823896)
		(end 372.893844 -294.824658)
		(width 0.1143)
		(layer "In13.Cu")
		(net "P5E_CPU0_P2_TX_DP<13>")
	)
	(segment
		(start 372.887494 -288.99104)
		(end 372.884954 -288.992564)
		(width 0.1143)
		(layer "In13.Cu")
		(net "P5E_CPU0_P2_TX_DP<13>")
	)
	(segment
		(start 372.889272 -284.130242)
		(end 372.888256 -284.13075)
		(width 0.1143)
		(layer "In13.Cu")
		(net "P5E_CPU0_P2_TX_DP<13>")
	)
	(segment
		(start 372.893844 -284.127448)
		(end 372.892574 -284.12821)
		(width 0.1143)
		(layer "In13.Cu")
		(net "P5E_CPU0_P2_TX_DP<13>")
	)
	(segment
		(start 372.885462 -277.65248)
		(end 372.852696 -277.67153)
		(width 0.1143)
		(layer "In13.Cu")
		(net "P5E_CPU0_P2_TX_DP<13>")
	)
	(segment
		(start 372.859554 -272.124678)
		(end 372.860316 -272.125186)
		(width 0.1143)
		(layer "In13.Cu")
		(net "P5E_CPU0_P2_TX_DP<13>")
	)
	(segment
		(start 372.893844 -285.10484)
		(end 372.923562 -285.121858)
		(width 0.1143)
		(layer "In13.Cu")
		(net "P5E_CPU0_P2_TX_DP<13>")
	)
	(segment
		(start 372.892574 -288.987992)
		(end 372.891812 -288.9885)
		(width 0.1143)
		(layer "In13.Cu")
		(net "P5E_CPU0_P2_TX_DP<13>")
	)
	(segment
		(start 373.503952 -296.61231)
		(end 373.503952 -297.403774)
		(width 0.14224)
		(layer "In13.Cu")
		(net "P5E_CPU0_P2_TX_DP<13>")
	)
	(segment
		(start 372.893844 -290.607242)
		(end 372.892574 -290.608004)
		(width 0.1143)
		(layer "In13.Cu")
		(net "P5E_CPU0_P2_TX_DP<13>")
	)
	(segment
		(start 372.892574 -285.748222)
		(end 372.891812 -285.74873)
		(width 0.1143)
		(layer "In13.Cu")
		(net "P5E_CPU0_P2_TX_DP<13>")
	)
	(segment
		(start 372.897654 -278.626824)
		(end 372.898416 -278.627332)
		(width 0.1143)
		(layer "In13.Cu")
		(net "P5E_CPU0_P2_TX_DP<13>")
	)
	(segment
		(start 372.886224 -276.03196)
		(end 372.885462 -276.032468)
		(width 0.1143)
		(layer "In13.Cu")
		(net "P5E_CPU0_P2_TX_DP<13>")
	)
	(segment
		(start 372.887494 -282.511246)
		(end 372.884954 -282.51277)
		(width 0.1143)
		(layer "In13.Cu")
		(net "P5E_CPU0_P2_TX_DP<13>")
	)
	(segment
		(start 372.899686 -275.38807)
		(end 372.902226 -275.38934)
		(width 0.1143)
		(layer "In13.Cu")
		(net "P5E_CPU0_P2_TX_DP<13>")
	)
	(segment
		(start 372.860316 -278.605234)
		(end 372.891812 -278.623522)
		(width 0.1143)
		(layer "In13.Cu")
		(net "P5E_CPU0_P2_TX_DP<13>")
	)
	(segment
		(start 372.902226 -278.629364)
		(end 372.923562 -278.64181)
		(width 0.1143)
		(layer "In13.Cu")
		(net "P5E_CPU0_P2_TX_DP<13>")
	)
	(segment
		(start 372.888256 -282.510738)
		(end 372.887494 -282.511246)
		(width 0.1143)
		(layer "In13.Cu")
		(net "P5E_CPU0_P2_TX_DP<13>")
	)
	(segment
		(start 372.891812 -285.10357)
		(end 372.892574 -285.104078)
		(width 0.1143)
		(layer "In13.Cu")
		(net "P5E_CPU0_P2_TX_DP<13>")
	)
	(segment
		(start 372.923562 -271.150334)
		(end 372.892574 -271.168114)
		(width 0.1143)
		(layer "In13.Cu")
		(net "P5E_CPU0_P2_TX_DP<13>")
	)
	(segment
		(start 372.891812 -281.863546)
		(end 372.892574 -281.864054)
		(width 0.1143)
		(layer "In13.Cu")
		(net "P5E_CPU0_P2_TX_DP<13>")
	)
	(segment
		(start 372.891812 -277.00351)
		(end 372.892574 -277.004018)
		(width 0.1143)
		(layer "In13.Cu")
		(net "P5E_CPU0_P2_TX_DP<13>")
	)
	(segment
		(start 372.860316 -289.945064)
		(end 372.891812 -289.963352)
		(width 0.1143)
		(layer "In13.Cu")
		(net "P5E_CPU0_P2_TX_DP<13>")
	)
	(segment
		(start 372.89613 -278.626062)
		(end 372.897654 -278.626824)
		(width 0.1143)
		(layer "In13.Cu")
		(net "P5E_CPU0_P2_TX_DP<13>")
	)
	(segment
		(start 372.891812 -288.9885)
		(end 372.890796 -288.989008)
		(width 0.1143)
		(layer "In13.Cu")
		(net "P5E_CPU0_P2_TX_DP<13>")
	)
	(segment
		(start 372.859554 -293.18458)
		(end 372.860316 -293.185088)
		(width 0.1143)
		(layer "In13.Cu")
		(net "P5E_CPU0_P2_TX_DP<13>")
	)
	(segment
		(start 372.8974 -289.966654)
		(end 372.898416 -289.967162)
		(width 0.1143)
		(layer "In13.Cu")
		(net "P5E_CPU0_P2_TX_DP<13>")
	)
	(segment
		(start 372.892574 -276.02815)
		(end 372.891812 -276.028658)
		(width 0.1143)
		(layer "In13.Cu")
		(net "P5E_CPU0_P2_TX_DP<13>")
	)
	(segment
		(start 372.887494 -285.75127)
		(end 372.884954 -285.752794)
		(width 0.1143)
		(layer "In13.Cu")
		(net "P5E_CPU0_P2_TX_DP<13>")
	)
	(segment
		(start 399.683224 -360.660696)
		(end 403.966426 -367.070132)
		(width 0.14224)
		(layer "In13.Cu")
		(net "P5E_CPU0_P2_TX_DP<13>")
	)
	(segment
		(start 372.887494 -277.65121)
		(end 372.886224 -277.651972)
		(width 0.1143)
		(layer "In13.Cu")
		(net "P5E_CPU0_P2_TX_DP<13>")
	)
	(segment
		(start 373.503952 -296.583862)
		(end 373.503952 -296.61231)
		(width 0.1143)
		(layer "In13.Cu")
		(net "P5E_CPU0_P2_TX_DP<13>")
	)
	(segment
		(start 372.891812 -291.583364)
		(end 372.892574 -291.583872)
		(width 0.1143)
		(layer "In13.Cu")
		(net "P5E_CPU0_P2_TX_DP<13>")
	)
	(segment
		(start 372.852696 -294.800528)
		(end 372.859554 -294.804592)
		(width 0.1143)
		(layer "In13.Cu")
		(net "P5E_CPU0_P2_TX_DP<13>")
	)
	(segment
		(start 372.860316 -276.985222)
		(end 372.891812 -277.00351)
		(width 0.1143)
		(layer "In13.Cu")
		(net "P5E_CPU0_P2_TX_DP<13>")
	)
	(segment
		(start 372.895368 -272.145506)
		(end 372.89613 -272.146014)
		(width 0.1143)
		(layer "In13.Cu")
		(net "P5E_CPU0_P2_TX_DP<13>")
	)
	(segment
		(start 372.886224 -272.791936)
		(end 372.885462 -272.792444)
		(width 0.1143)
		(layer "In13.Cu")
		(net "P5E_CPU0_P2_TX_DP<13>")
	)
	(segment
		(start 372.886224 -277.651972)
		(end 372.885462 -277.65248)
		(width 0.1143)
		(layer "In13.Cu")
		(net "P5E_CPU0_P2_TX_DP<13>")
	)
	(segment
		(start 372.895368 -289.965384)
		(end 372.896638 -289.966146)
		(width 0.1143)
		(layer "In13.Cu")
		(net "P5E_CPU0_P2_TX_DP<13>")
	)
	(segment
		(start 372.889272 -272.790158)
		(end 372.887494 -272.791174)
		(width 0.1143)
		(layer "In13.Cu")
		(net "P5E_CPU0_P2_TX_DP<13>")
	)
	(segment
		(start 372.891812 -292.228524)
		(end 372.890796 -292.229032)
		(width 0.1143)
		(layer "In13.Cu")
		(net "P5E_CPU0_P2_TX_DP<13>")
	)
	(segment
		(start 372.895368 -281.865578)
		(end 372.896638 -281.86634)
		(width 0.1143)
		(layer "In13.Cu")
		(net "P5E_CPU0_P2_TX_DP<13>")
	)
	(segment
		(start 372.898416 -294.827198)
		(end 372.899686 -294.82796)
		(width 0.1143)
		(layer "In13.Cu")
		(net "P5E_CPU0_P2_TX_DP<13>")
	)
	(segment
		(start 372.902226 -277.009352)
		(end 372.923562 -277.021798)
		(width 0.1143)
		(layer "In13.Cu")
		(net "P5E_CPU0_P2_TX_DP<13>")
	)
	(segment
		(start 372.892574 -281.864054)
		(end 372.893844 -281.864816)
		(width 0.1143)
		(layer "In13.Cu")
		(net "P5E_CPU0_P2_TX_DP<13>")
	)
	(segment
		(start 372.891812 -276.028658)
		(end 372.890796 -276.029166)
		(width 0.1143)
		(layer "In13.Cu")
		(net "P5E_CPU0_P2_TX_DP<13>")
	)
	(segment
		(start 372.884192 -288.993072)
		(end 372.852696 -289.01136)
		(width 0.1143)
		(layer "In13.Cu")
		(net "P5E_CPU0_P2_TX_DP<13>")
	)
	(segment
		(start 372.892574 -293.203884)
		(end 372.893844 -293.204646)
		(width 0.1143)
		(layer "In13.Cu")
		(net "P5E_CPU0_P2_TX_DP<13>")
	)
	(segment
		(start 372.899686 -272.148046)
		(end 372.902226 -272.149316)
		(width 0.1143)
		(layer "In13.Cu")
		(net "P5E_CPU0_P2_TX_DP<13>")
	)
	(segment
		(start 372.884192 -282.513278)
		(end 372.852696 -282.531566)
		(width 0.1143)
		(layer "In13.Cu")
		(net "P5E_CPU0_P2_TX_DP<13>")
	)
	(segment
		(start 372.891812 -271.168622)
		(end 372.890796 -271.16913)
		(width 0.1143)
		(layer "In13.Cu")
		(net "P5E_CPU0_P2_TX_DP<13>")
	)
	(segment
		(start 372.859554 -294.804592)
		(end 372.860316 -294.8051)
		(width 0.1143)
		(layer "In13.Cu")
		(net "P5E_CPU0_P2_TX_DP<13>")
	)
	(segment
		(start 373.392446 -270.340836)
		(end 373.361966 -270.358616)
		(width 0.1143)
		(layer "In13.Cu")
		(net "P5E_CPU0_P2_TX_DP<13>")
	)
	(segment
		(start 372.884954 -288.992564)
		(end 372.884192 -288.993072)
		(width 0.1143)
		(layer "In13.Cu")
		(net "P5E_CPU0_P2_TX_DP<13>")
	)
	(segment
		(start 372.885462 -276.032468)
		(end 372.852696 -276.051518)
		(width 0.1143)
		(layer "In13.Cu")
		(net "P5E_CPU0_P2_TX_DP<13>")
	)
	(segment
		(start 372.891812 -279.268682)
		(end 372.890796 -279.26919)
		(width 0.1143)
		(layer "In13.Cu")
		(net "P5E_CPU0_P2_TX_DP<13>")
	)
	(segment
		(start 424.46067 -375.925842)
		(end 424.46067 -377.1265)
		(width 0.14224)
		(layer "In13.Cu")
		(net "P5E_CPU0_P2_TX_DP<13>")
	)
	(segment
		(start 373.391938 -295.65092)
		(end 373.393462 -295.651936)
		(width 0.1143)
		(layer "In13.Cu")
		(net "P5E_CPU0_P2_TX_DP<13>")
	)
	(segment
		(start 372.892574 -279.268174)
		(end 372.891812 -279.268682)
		(width 0.1143)
		(layer "In13.Cu")
		(net "P5E_CPU0_P2_TX_DP<13>")
	)
	(segment
		(start 372.902226 -281.869388)
		(end 372.923562 -281.881834)
		(width 0.1143)
		(layer "In13.Cu")
		(net "P5E_CPU0_P2_TX_DP<13>")
	)
	(segment
		(start 372.902226 -294.82923)
		(end 372.923562 -294.841676)
		(width 0.1143)
		(layer "In13.Cu")
		(net "P5E_CPU0_P2_TX_DP<13>")
	)
	(segment
		(start 372.892574 -292.228016)
		(end 372.891812 -292.228524)
		(width 0.1143)
		(layer "In13.Cu")
		(net "P5E_CPU0_P2_TX_DP<13>")
	)
	(segment
		(start 372.893844 -283.484828)
		(end 372.923562 -283.501846)
		(width 0.1143)
		(layer "In13.Cu")
		(net "P5E_CPU0_P2_TX_DP<13>")
	)
	(segment
		(start 372.852696 -272.120614)
		(end 372.859554 -272.124678)
		(width 0.1143)
		(layer "In13.Cu")
		(net "P5E_CPU0_P2_TX_DP<13>")
	)
	(segment
		(start 372.859554 -273.74469)
		(end 372.860316 -273.745198)
		(width 0.1143)
		(layer "In13.Cu")
		(net "P5E_CPU0_P2_TX_DP<13>")
	)
	(segment
		(start 372.891812 -289.963352)
		(end 372.892574 -289.96386)
		(width 0.1143)
		(layer "In13.Cu")
		(net "P5E_CPU0_P2_TX_DP<13>")
	)
	(segment
		(start 372.892574 -273.763994)
		(end 372.895368 -273.765518)
		(width 0.1143)
		(layer "In13.Cu")
		(net "P5E_CPU0_P2_TX_DP<13>")
	)
	(segment
		(start 373.549672 -296.538142)
		(end 373.503952 -296.583862)
		(width 0.1143)
		(layer "In13.Cu")
		(net "P5E_CPU0_P2_TX_DP<13>")
	)
	(segment
		(start 372.884954 -284.132782)
		(end 372.884192 -284.13329)
		(width 0.1143)
		(layer "In13.Cu")
		(net "P5E_CPU0_P2_TX_DP<13>")
	)
	(segment
		(start 372.890796 -280.243026)
		(end 372.891812 -280.243534)
		(width 0.1143)
		(layer "In13.Cu")
		(net "P5E_CPU0_P2_TX_DP<13>")
	)
	(segment
		(start 372.859554 -289.944556)
		(end 372.860316 -289.945064)
		(width 0.1143)
		(layer "In13.Cu")
		(net "P5E_CPU0_P2_TX_DP<13>")
	)
	(segment
		(start 372.890796 -276.029166)
		(end 372.889272 -276.030182)
		(width 0.1143)
		(layer "In13.Cu")
		(net "P5E_CPU0_P2_TX_DP<13>")
	)
	(segment
		(start 372.899686 -294.82796)
		(end 372.902226 -294.82923)
		(width 0.1143)
		(layer "In13.Cu")
		(net "P5E_CPU0_P2_TX_DP<13>")
	)
	(segment
		(start 372.892574 -275.384006)
		(end 372.895368 -275.38553)
		(width 0.1143)
		(layer "In13.Cu")
		(net "P5E_CPU0_P2_TX_DP<13>")
	)
	(segment
		(start 372.923562 -276.01037)
		(end 372.892574 -276.02815)
		(width 0.1143)
		(layer "In13.Cu")
		(net "P5E_CPU0_P2_TX_DP<13>")
	)
	(segment
		(start 373.361712 -295.633394)
		(end 373.361966 -295.633394)
		(width 0.1143)
		(layer "In13.Cu")
		(net "P5E_CPU0_P2_TX_DP<13>")
	)
	(segment
		(start 372.923562 -272.770346)
		(end 372.892574 -272.788126)
		(width 0.1143)
		(layer "In13.Cu")
		(net "P5E_CPU0_P2_TX_DP<13>")
	)
	(segment
		(start 404.079202 -367.182908)
		(end 406.103582 -368.535712)
		(width 0.14224)
		(layer "In13.Cu")
		(net "P5E_CPU0_P2_TX_DP<13>")
	)
	(segment
		(start 372.887494 -271.171162)
		(end 372.886224 -271.171924)
		(width 0.1143)
		(layer "In13.Cu")
		(net "P5E_CPU0_P2_TX_DP<13>")
	)
	(segment
		(start 372.923562 -287.3502)
		(end 372.891812 -287.368488)
		(width 0.1143)
		(layer "In13.Cu")
		(net "P5E_CPU0_P2_TX_DP<13>")
	)
	(segment
		(start 372.898416 -277.00732)
		(end 372.899686 -277.008082)
		(width 0.1143)
		(layer "In13.Cu")
		(net "P5E_CPU0_P2_TX_DP<13>")
	)
	(segment
		(start 372.886224 -279.271984)
		(end 372.885462 -279.272492)
		(width 0.1143)
		(layer "In13.Cu")
		(net "P5E_CPU0_P2_TX_DP<13>")
	)
	(segment
		(start 372.902226 -289.969194)
		(end 372.923562 -289.98164)
		(width 0.1143)
		(layer "In13.Cu")
		(net "P5E_CPU0_P2_TX_DP<13>")
	)
	(segment
		(start 372.890796 -274.409154)
		(end 372.889272 -274.41017)
		(width 0.1143)
		(layer "In13.Cu")
		(net "P5E_CPU0_P2_TX_DP<13>")
	)
	(segment
		(start 372.898416 -293.207186)
		(end 372.899686 -293.207948)
		(width 0.1143)
		(layer "In13.Cu")
		(net "P5E_CPU0_P2_TX_DP<13>")
	)
	(segment
		(start 372.890796 -290.60902)
		(end 372.889272 -290.610036)
		(width 0.1143)
		(layer "In13.Cu")
		(net "P5E_CPU0_P2_TX_DP<13>")
	)
	(segment
		(start 424.46067 -377.1265)
		(end 424.16984 -377.41733)
		(width 0.14224)
		(layer "In13.Cu")
		(net "P5E_CPU0_P2_TX_DP<13>")
	)
	(segment
		(start 372.891812 -274.408646)
		(end 372.890796 -274.409154)
		(width 0.1143)
		(layer "In13.Cu")
		(net "P5E_CPU0_P2_TX_DP<13>")
	)
	(segment
		(start 372.891812 -282.508706)
		(end 372.890796 -282.509214)
		(width 0.1143)
		(layer "In13.Cu")
		(net "P5E_CPU0_P2_TX_DP<13>")
	)
	(segment
		(start 372.899686 -277.008082)
		(end 372.902226 -277.009352)
		(width 0.1143)
		(layer "In13.Cu")
		(net "P5E_CPU0_P2_TX_DP<13>")
	)
	(segment
		(start 372.899686 -273.768058)
		(end 372.902226 -273.769328)
		(width 0.1143)
		(layer "In13.Cu")
		(net "P5E_CPU0_P2_TX_DP<13>")
	)
	(segment
		(start 372.891812 -275.383498)
		(end 372.892574 -275.384006)
		(width 0.1143)
		(layer "In13.Cu")
		(net "P5E_CPU0_P2_TX_DP<13>")
	)
	(segment
		(start 372.891812 -280.243534)
		(end 372.923562 -280.261822)
		(width 0.1143)
		(layer "In13.Cu")
		(net "P5E_CPU0_P2_TX_DP<13>")
	)
	(segment
		(start 372.889272 -277.650194)
		(end 372.887494 -277.65121)
		(width 0.1143)
		(layer "In13.Cu")
		(net "P5E_CPU0_P2_TX_DP<13>")
	)
	(arc
		(start 372.852696 -282.531566)
		(mid 372.609369 -282.996132)
		(end 372.852696 -283.460698)
		(width 0.1143)
		(layer "In13.Cu")
		(net "P5E_CPU0_P2_TX_DP<13>")
	)
	(arc
		(start 372.923562 -281.881834)
		(mid 373.07949 -282.186126)
		(end 372.923562 -282.490418)
		(width 0.1143)
		(layer "In13.Cu")
		(net "P5E_CPU0_P2_TX_DP<13>")
	)
	(arc
		(start 372.852696 -284.151578)
		(mid 372.609369 -284.616144)
		(end 372.852696 -285.08071)
		(width 0.1143)
		(layer "In13.Cu")
		(net "P5E_CPU0_P2_TX_DP<13>")
	)
	(arc
		(start 372.92534 -288.363152)
		(mid 373.038747 -288.496041)
		(end 373.079518 -288.66592)
		(width 0.1143)
		(layer "In13.Cu")
		(net "P5E_CPU0_P2_TX_DP<13>")
	)
	(arc
		(start 372.852696 -293.871396)
		(mid 372.609369 -294.335962)
		(end 372.852696 -294.800528)
		(width 0.1143)
		(layer "In13.Cu")
		(net "P5E_CPU0_P2_TX_DP<13>")
	)
	(arc
		(start 373.503952 -297.403774)
		(mid 373.51169 -297.483254)
		(end 373.534686 -297.55973)
		(width 0.14224)
		(layer "In13.Cu")
		(net "P5E_CPU0_P2_TX_DP<13>")
	)
	(arc
		(start 372.923562 -283.501846)
		(mid 373.07949 -283.806138)
		(end 372.923562 -284.11043)
		(width 0.1143)
		(layer "In13.Cu")
		(net "P5E_CPU0_P2_TX_DP<13>")
	)
	(arc
		(start 372.923562 -285.121858)
		(mid 373.07949 -285.42615)
		(end 372.923562 -285.730442)
		(width 0.1143)
		(layer "In13.Cu")
		(net "P5E_CPU0_P2_TX_DP<13>")
	)
	(arc
		(start 372.855236 -287.389824)
		(mid 372.674584 -287.592569)
		(end 372.609364 -287.856168)
		(width 0.1143)
		(layer "In13.Cu")
		(net "P5E_CPU0_P2_TX_DP<13>")
	)
	(arc
		(start 422.6433 -374.16867)
		(mid 422.747777 -374.18947)
		(end 422.83634 -374.24868)
		(width 0.14224)
		(layer "In13.Cu")
		(net "P5E_CPU0_P2_TX_DP<13>")
	)
	(arc
		(start 372.852696 -276.051518)
		(mid 372.609369 -276.516084)
		(end 372.852696 -276.98065)
		(width 0.1143)
		(layer "In13.Cu")
		(net "P5E_CPU0_P2_TX_DP<13>")
	)
	(arc
		(start 372.923562 -293.221664)
		(mid 373.07949 -293.525956)
		(end 372.923562 -293.830248)
		(width 0.1143)
		(layer "In13.Cu")
		(net "P5E_CPU0_P2_TX_DP<13>")
	)
	(arc
		(start 373.393462 -295.651936)
		(mid 373.401027 -295.657557)
		(end 373.408448 -295.663366)
		(width 0.1143)
		(layer "In13.Cu")
		(net "P5E_CPU0_P2_TX_DP<13>")
	)
	(arc
		(start 372.852696 -277.67153)
		(mid 372.609369 -278.136096)
		(end 372.852696 -278.600662)
		(width 0.1143)
		(layer "In13.Cu")
		(net "P5E_CPU0_P2_TX_DP<13>")
	)
	(arc
		(start 372.923562 -272.161762)
		(mid 373.07949 -272.466054)
		(end 372.923562 -272.770346)
		(width 0.1143)
		(layer "In13.Cu")
		(net "P5E_CPU0_P2_TX_DP<13>")
	)
	(arc
		(start 373.079518 -295.145968)
		(mid 373.14439 -295.408931)
		(end 373.32412 -295.61155)
		(width 0.1143)
		(layer "In13.Cu")
		(net "P5E_CPU0_P2_TX_DP<13>")
	)
	(arc
		(start 373.079518 -287.045908)
		(mid 373.038263 -287.216879)
		(end 372.923562 -287.3502)
		(width 0.1143)
		(layer "In13.Cu")
		(net "P5E_CPU0_P2_TX_DP<13>")
	)
	(arc
		(start 372.923562 -280.261822)
		(mid 373.07949 -280.566114)
		(end 372.923562 -280.870406)
		(width 0.1143)
		(layer "In13.Cu")
		(net "P5E_CPU0_P2_TX_DP<13>")
	)
	(arc
		(start 372.852696 -279.291542)
		(mid 372.609369 -279.756108)
		(end 372.852696 -280.220674)
		(width 0.1143)
		(layer "In13.Cu")
		(net "P5E_CPU0_P2_TX_DP<13>")
	)
	(arc
		(start 419.475666 -374.075198)
		(mid 419.706515 -374.145148)
		(end 419.946582 -374.16867)
		(width 0.14224)
		(layer "In13.Cu")
		(net "P5E_CPU0_P2_TX_DP<13>")
	)
	(arc
		(start 372.852696 -280.911554)
		(mid 372.609369 -281.37612)
		(end 372.852696 -281.840686)
		(width 0.1143)
		(layer "In13.Cu")
		(net "P5E_CPU0_P2_TX_DP<13>")
	)
	(arc
		(start 372.852696 -285.77159)
		(mid 372.609369 -286.236156)
		(end 372.852696 -286.700722)
		(width 0.1143)
		(layer "In13.Cu")
		(net "P5E_CPU0_P2_TX_DP<13>")
	)
	(arc
		(start 372.923562 -277.021798)
		(mid 373.07949 -277.32609)
		(end 372.923562 -277.630382)
		(width 0.1143)
		(layer "In13.Cu")
		(net "P5E_CPU0_P2_TX_DP<13>")
	)
	(arc
		(start 372.852696 -272.811494)
		(mid 372.609369 -273.27606)
		(end 372.852696 -273.740626)
		(width 0.1143)
		(layer "In13.Cu")
		(net "P5E_CPU0_P2_TX_DP<13>")
	)
	(arc
		(start 373.54256 -270.105886)
		(mid 373.490143 -270.237817)
		(end 373.392446 -270.340836)
		(width 0.1143)
		(layer "In13.Cu")
		(net "P5E_CPU0_P2_TX_DP<13>")
	)
	(arc
		(start 372.923562 -294.841676)
		(mid 373.038238 -294.97501)
		(end 373.079518 -295.145968)
		(width 0.1143)
		(layer "In13.Cu")
		(net "P5E_CPU0_P2_TX_DP<13>")
	)
	(arc
		(start 372.923562 -278.64181)
		(mid 373.07949 -278.946102)
		(end 372.923562 -279.250394)
		(width 0.1143)
		(layer "In13.Cu")
		(net "P5E_CPU0_P2_TX_DP<13>")
	)
	(arc
		(start 403.966426 -367.070132)
		(mid 404.017265 -367.132069)
		(end 404.079202 -367.182908)
		(width 0.14224)
		(layer "In13.Cu")
		(net "P5E_CPU0_P2_TX_DP<13>")
	)
	(arc
		(start 372.92534 -286.74314)
		(mid 373.038747 -286.876029)
		(end 373.079518 -287.045908)
		(width 0.1143)
		(layer "In13.Cu")
		(net "P5E_CPU0_P2_TX_DP<13>")
	)
	(arc
		(start 372.923562 -275.401786)
		(mid 373.07949 -275.706078)
		(end 372.923562 -276.01037)
		(width 0.1143)
		(layer "In13.Cu")
		(net "P5E_CPU0_P2_TX_DP<13>")
	)
	(arc
		(start 424.423332 -375.835672)
		(mid 424.450975 -375.877042)
		(end 424.46067 -375.925842)
		(width 0.14224)
		(layer "In13.Cu")
		(net "P5E_CPU0_P2_TX_DP<13>")
	)
	(arc
		(start 372.923562 -289.98164)
		(mid 373.07949 -290.285932)
		(end 372.923562 -290.590224)
		(width 0.1143)
		(layer "In13.Cu")
		(net "P5E_CPU0_P2_TX_DP<13>")
	)
	(arc
		(start 372.852696 -271.191482)
		(mid 372.609369 -271.656048)
		(end 372.852696 -272.120614)
		(width 0.1143)
		(layer "In13.Cu")
		(net "P5E_CPU0_P2_TX_DP<13>")
	)
	(arc
		(start 372.852696 -289.01136)
		(mid 372.609369 -289.475926)
		(end 372.852696 -289.940492)
		(width 0.1143)
		(layer "In13.Cu")
		(net "P5E_CPU0_P2_TX_DP<13>")
	)
	(arc
		(start 372.923562 -291.601652)
		(mid 373.07949 -291.905944)
		(end 372.923562 -292.210236)
		(width 0.1143)
		(layer "In13.Cu")
		(net "P5E_CPU0_P2_TX_DP<13>")
	)
	(arc
		(start 373.079518 -288.66592)
		(mid 373.038263 -288.836891)
		(end 372.923562 -288.970212)
		(width 0.1143)
		(layer "In13.Cu")
		(net "P5E_CPU0_P2_TX_DP<13>")
	)
	(arc
		(start 372.923562 -273.781774)
		(mid 373.07949 -274.086066)
		(end 372.923562 -274.390358)
		(width 0.1143)
		(layer "In13.Cu")
		(net "P5E_CPU0_P2_TX_DP<13>")
	)
	(arc
		(start 373.408448 -295.663366)
		(mid 373.512434 -295.793557)
		(end 373.549672 -295.955974)
		(width 0.1143)
		(layer "In13.Cu")
		(net "P5E_CPU0_P2_TX_DP<13>")
	)
	(arc
		(start 372.852696 -292.251384)
		(mid 372.609369 -292.71595)
		(end 372.852696 -293.180516)
		(width 0.1143)
		(layer "In13.Cu")
		(net "P5E_CPU0_P2_TX_DP<13>")
	)
	(arc
		(start 372.609364 -287.856168)
		(mid 372.673879 -288.118387)
		(end 372.852696 -288.320734)
		(width 0.1143)
		(layer "In13.Cu")
		(net "P5E_CPU0_P2_TX_DP<13>")
	)
	(arc
		(start 372.852696 -274.431506)
		(mid 372.609369 -274.896072)
		(end 372.852696 -275.360638)
		(width 0.1143)
		(layer "In13.Cu")
		(net "P5E_CPU0_P2_TX_DP<13>")
	)
	(arc
		(start 372.852696 -290.631372)
		(mid 372.609369 -291.095938)
		(end 372.852696 -291.560504)
		(width 0.1143)
		(layer "In13.Cu")
		(net "P5E_CPU0_P2_TX_DP<13>")
	)
	(arc
		(start 373.32285 -270.381476)
		(mid 373.144037 -270.583826)
		(end 373.079518 -270.846042)
		(width 0.1143)
		(layer "In13.Cu")
		(net "P5E_CPU0_P2_TX_DP<13>")
	)
	(arc
		(start 373.079518 -270.846042)
		(mid 373.038263 -271.017013)
		(end 372.923562 -271.150334)
		(width 0.1143)
		(layer "In13.Cu")
		(net "P5E_CPU0_P2_TX_DP<13>")
	)
	(segment
		(start 369.888008 -271.39011)
		(end 370.35486 -271.656048)
		(width 0.12954)
		(layer "F.Cu")
		(net "P5E_CPU0_P2_TX_DP<12>")
	)
	(segment
		(start 420.76624 -377.41733)
		(end 421.03675 -377.68784)
		(width 0.12954)
		(layer "F.Cu")
		(net "P5E_CPU0_P2_TX_DP<12>")
	)
	(segment
		(start 421.03675 -378.39142)
		(end 420.74084 -378.68733)
		(width 0.12954)
		(layer "F.Cu")
		(net "P5E_CPU0_P2_TX_DP<12>")
	)
	(segment
		(start 421.03675 -377.68784)
		(end 421.03675 -378.39142)
		(width 0.12954)
		(layer "F.Cu")
		(net "P5E_CPU0_P2_TX_DP<12>")
	)
	(segment
		(start 371.952012 -288.9885)
		(end 371.912896 -289.01136)
		(width 0.1143)
		(layer "In13.Cu")
		(net "P5E_CPU0_P2_TX_DP<12>")
	)
	(segment
		(start 371.912896 -289.940492)
		(end 371.952012 -289.963352)
		(width 0.1143)
		(layer "In13.Cu")
		(net "P5E_CPU0_P2_TX_DP<12>")
	)
	(segment
		(start 371.952012 -290.608512)
		(end 371.912896 -290.631372)
		(width 0.1143)
		(layer "In13.Cu")
		(net "P5E_CPU0_P2_TX_DP<12>")
	)
	(segment
		(start 371.442742 -272.93062)
		(end 371.481858 -272.95348)
		(width 0.1143)
		(layer "In13.Cu")
		(net "P5E_CPU0_P2_TX_DP<12>")
	)
	(segment
		(start 370.972842 -272.120614)
		(end 371.011958 -272.143474)
		(width 0.1143)
		(layer "In13.Cu")
		(net "P5E_CPU0_P2_TX_DP<12>")
	)
	(segment
		(start 372.468902 -295.663874)
		(end 372.469156 -295.66362)
		(width 0.1143)
		(layer "In13.Cu")
		(net "P5E_CPU0_P2_TX_DP<12>")
	)
	(segment
		(start 371.951758 -278.623522)
		(end 371.983508 -278.64181)
		(width 0.1143)
		(layer "In13.Cu")
		(net "P5E_CPU0_P2_TX_DP<12>")
	)
	(segment
		(start 371.952012 -284.128718)
		(end 371.912896 -284.151578)
		(width 0.1143)
		(layer "In13.Cu")
		(net "P5E_CPU0_P2_TX_DP<12>")
	)
	(segment
		(start 372.563898 -296.56659)
		(end 372.563898 -296.595038)
		(width 0.1143)
		(layer "In13.Cu")
		(net "P5E_CPU0_P2_TX_DP<12>")
	)
	(segment
		(start 371.982492 -282.490926)
		(end 371.952012 -282.508706)
		(width 0.1143)
		(layer "In13.Cu")
		(net "P5E_CPU0_P2_TX_DP<12>")
	)
	(segment
		(start 372.609872 -297.854878)
		(end 398.731994 -360.893106)
		(width 0.14224)
		(layer "In13.Cu")
		(net "P5E_CPU0_P2_TX_DP<12>")
	)
	(segment
		(start 371.983508 -280.870406)
		(end 371.951758 -280.888694)
		(width 0.1143)
		(layer "In13.Cu")
		(net "P5E_CPU0_P2_TX_DP<12>")
	)
	(segment
		(start 403.500844 -367.937288)
		(end 405.506174 -369.277392)
		(width 0.14224)
		(layer "In13.Cu")
		(net "P5E_CPU0_P2_TX_DP<12>")
	)
	(segment
		(start 371.982492 -284.110938)
		(end 371.952012 -284.128718)
		(width 0.1143)
		(layer "In13.Cu")
		(net "P5E_CPU0_P2_TX_DP<12>")
	)
	(segment
		(start 371.011958 -272.143474)
		(end 371.042438 -272.161254)
		(width 0.1143)
		(layer "In13.Cu")
		(net "P5E_CPU0_P2_TX_DP<12>")
	)
	(segment
		(start 371.951758 -280.243534)
		(end 371.983508 -280.261822)
		(width 0.1143)
		(layer "In13.Cu")
		(net "P5E_CPU0_P2_TX_DP<12>")
	)
	(segment
		(start 371.912896 -294.800528)
		(end 371.952012 -294.823388)
		(width 0.1143)
		(layer "In13.Cu")
		(net "P5E_CPU0_P2_TX_DP<12>")
	)
	(segment
		(start 419.871652 -375.280174)
		(end 420.156894 -375.470166)
		(width 0.14224)
		(layer "In13.Cu")
		(net "P5E_CPU0_P2_TX_DP<12>")
	)
	(segment
		(start 371.952012 -285.10357)
		(end 371.982492 -285.12135)
		(width 0.1143)
		(layer "In13.Cu")
		(net "P5E_CPU0_P2_TX_DP<12>")
	)
	(segment
		(start 370.35486 -271.656048)
		(end 370.652802 -271.656048)
		(width 0.1143)
		(layer "In13.Cu")
		(net "P5E_CPU0_P2_TX_DP<12>")
	)
	(segment
		(start 371.91696 -280.90876)
		(end 371.912896 -280.911554)
		(width 0.1143)
		(layer "In13.Cu")
		(net "P5E_CPU0_P2_TX_DP<12>")
	)
	(segment
		(start 371.952012 -288.343594)
		(end 371.984524 -288.36239)
		(width 0.1143)
		(layer "In13.Cu")
		(net "P5E_CPU0_P2_TX_DP<12>")
	)
	(segment
		(start 371.952012 -289.963352)
		(end 371.982492 -289.981132)
		(width 0.1143)
		(layer "In13.Cu")
		(net "P5E_CPU0_P2_TX_DP<12>")
	)
	(segment
		(start 371.983254 -275.401786)
		(end 371.983508 -275.401786)
		(width 0.1143)
		(layer "In13.Cu")
		(net "P5E_CPU0_P2_TX_DP<12>")
	)
	(segment
		(start 371.983508 -279.250394)
		(end 371.951758 -279.268682)
		(width 0.1143)
		(layer "In13.Cu")
		(net "P5E_CPU0_P2_TX_DP<12>")
	)
	(segment
		(start 405.826722 -369.448842)
		(end 419.760146 -375.220484)
		(width 0.14224)
		(layer "In13.Cu")
		(net "P5E_CPU0_P2_TX_DP<12>")
	)
	(segment
		(start 371.481858 -272.95348)
		(end 371.513608 -272.971768)
		(width 0.1143)
		(layer "In13.Cu")
		(net "P5E_CPU0_P2_TX_DP<12>")
	)
	(segment
		(start 371.982492 -287.350708)
		(end 371.915436 -287.389824)
		(width 0.1143)
		(layer "In13.Cu")
		(net "P5E_CPU0_P2_TX_DP<12>")
	)
	(segment
		(start 371.952012 -282.508706)
		(end 371.912896 -282.531566)
		(width 0.1143)
		(layer "In13.Cu")
		(net "P5E_CPU0_P2_TX_DP<12>")
	)
	(segment
		(start 371.952012 -294.823388)
		(end 371.982492 -294.841168)
		(width 0.1143)
		(layer "In13.Cu")
		(net "P5E_CPU0_P2_TX_DP<12>")
	)
	(segment
		(start 371.952012 -286.723582)
		(end 371.984524 -286.742378)
		(width 0.1143)
		(layer "In13.Cu")
		(net "P5E_CPU0_P2_TX_DP<12>")
	)
	(segment
		(start 371.951758 -280.888694)
		(end 371.91696 -280.90876)
		(width 0.1143)
		(layer "In13.Cu")
		(net "P5E_CPU0_P2_TX_DP<12>")
	)
	(segment
		(start 371.951758 -276.028658)
		(end 371.915436 -276.04974)
		(width 0.1143)
		(layer "In13.Cu")
		(net "P5E_CPU0_P2_TX_DP<12>")
	)
	(segment
		(start 371.915436 -280.222452)
		(end 371.951758 -280.243534)
		(width 0.1143)
		(layer "In13.Cu")
		(net "P5E_CPU0_P2_TX_DP<12>")
	)
	(segment
		(start 371.982492 -285.73095)
		(end 371.952012 -285.74873)
		(width 0.1143)
		(layer "In13.Cu")
		(net "P5E_CPU0_P2_TX_DP<12>")
	)
	(segment
		(start 371.915436 -276.982428)
		(end 371.951758 -277.00351)
		(width 0.1143)
		(layer "In13.Cu")
		(net "P5E_CPU0_P2_TX_DP<12>")
	)
	(segment
		(start 372.382796 -295.610534)
		(end 372.452392 -295.651174)
		(width 0.1143)
		(layer "In13.Cu")
		(net "P5E_CPU0_P2_TX_DP<12>")
	)
	(segment
		(start 371.982492 -292.210744)
		(end 371.952012 -292.228524)
		(width 0.1143)
		(layer "In13.Cu")
		(net "P5E_CPU0_P2_TX_DP<12>")
	)
	(segment
		(start 371.952012 -281.863546)
		(end 371.982492 -281.881326)
		(width 0.1143)
		(layer "In13.Cu")
		(net "P5E_CPU0_P2_TX_DP<12>")
	)
	(segment
		(start 371.912896 -286.700722)
		(end 371.952012 -286.723582)
		(width 0.1143)
		(layer "In13.Cu")
		(net "P5E_CPU0_P2_TX_DP<12>")
	)
	(segment
		(start 371.915436 -278.60244)
		(end 371.951758 -278.623522)
		(width 0.1143)
		(layer "In13.Cu")
		(net "P5E_CPU0_P2_TX_DP<12>")
	)
	(segment
		(start 371.913404 -275.361146)
		(end 371.983254 -275.401786)
		(width 0.1143)
		(layer "In13.Cu")
		(net "P5E_CPU0_P2_TX_DP<12>")
	)
	(segment
		(start 371.951758 -279.268682)
		(end 371.915436 -279.289764)
		(width 0.1143)
		(layer "In13.Cu")
		(net "P5E_CPU0_P2_TX_DP<12>")
	)
	(segment
		(start 420.254684 -375.55043)
		(end 421.05707 -376.352816)
		(width 0.14224)
		(layer "In13.Cu")
		(net "P5E_CPU0_P2_TX_DP<12>")
	)
	(segment
		(start 371.952012 -293.848536)
		(end 371.912896 -293.871396)
		(width 0.1143)
		(layer "In13.Cu")
		(net "P5E_CPU0_P2_TX_DP<12>")
	)
	(segment
		(start 421.05707 -376.352816)
		(end 421.05707 -377.1265)
		(width 0.14224)
		(layer "In13.Cu")
		(net "P5E_CPU0_P2_TX_DP<12>")
	)
	(segment
		(start 371.912896 -285.08071)
		(end 371.952012 -285.10357)
		(width 0.1143)
		(layer "In13.Cu")
		(net "P5E_CPU0_P2_TX_DP<12>")
	)
	(segment
		(start 371.912896 -291.560504)
		(end 371.952012 -291.583364)
		(width 0.1143)
		(layer "In13.Cu")
		(net "P5E_CPU0_P2_TX_DP<12>")
	)
	(segment
		(start 372.609618 -295.955974)
		(end 372.609618 -296.52087)
		(width 0.1143)
		(layer "In13.Cu")
		(net "P5E_CPU0_P2_TX_DP<12>")
	)
	(segment
		(start 371.896894 -275.349462)
		(end 371.913404 -275.361146)
		(width 0.1143)
		(layer "In13.Cu")
		(net "P5E_CPU0_P2_TX_DP<12>")
	)
	(segment
		(start 371.952012 -293.203376)
		(end 371.982492 -293.221156)
		(width 0.1143)
		(layer "In13.Cu")
		(net "P5E_CPU0_P2_TX_DP<12>")
	)
	(segment
		(start 372.563898 -296.595038)
		(end 372.563898 -297.623738)
		(width 0.14224)
		(layer "In13.Cu")
		(net "P5E_CPU0_P2_TX_DP<12>")
	)
	(segment
		(start 371.983508 -277.630382)
		(end 371.951758 -277.64867)
		(width 0.1143)
		(layer "In13.Cu")
		(net "P5E_CPU0_P2_TX_DP<12>")
	)
	(segment
		(start 371.983508 -274.390358)
		(end 371.913404 -274.430998)
		(width 0.1143)
		(layer "In13.Cu")
		(net "P5E_CPU0_P2_TX_DP<12>")
	)
	(segment
		(start 371.913404 -274.430998)
		(end 371.896894 -274.442682)
		(width 0.1143)
		(layer "In13.Cu")
		(net "P5E_CPU0_P2_TX_DP<12>")
	)
	(segment
		(start 371.952012 -283.483558)
		(end 371.982492 -283.501338)
		(width 0.1143)
		(layer "In13.Cu")
		(net "P5E_CPU0_P2_TX_DP<12>")
	)
	(segment
		(start 371.982492 -288.97072)
		(end 371.952012 -288.9885)
		(width 0.1143)
		(layer "In13.Cu")
		(net "P5E_CPU0_P2_TX_DP<12>")
	)
	(segment
		(start 371.912896 -283.460698)
		(end 371.952012 -283.483558)
		(width 0.1143)
		(layer "In13.Cu")
		(net "P5E_CPU0_P2_TX_DP<12>")
	)
	(segment
		(start 371.952012 -285.74873)
		(end 371.912896 -285.77159)
		(width 0.1143)
		(layer "In13.Cu")
		(net "P5E_CPU0_P2_TX_DP<12>")
	)
	(segment
		(start 421.05707 -377.1265)
		(end 420.76624 -377.41733)
		(width 0.14224)
		(layer "In13.Cu")
		(net "P5E_CPU0_P2_TX_DP<12>")
	)
	(segment
		(start 371.952012 -292.228524)
		(end 371.912896 -292.251384)
		(width 0.1143)
		(layer "In13.Cu")
		(net "P5E_CPU0_P2_TX_DP<12>")
	)
	(segment
		(start 370.652802 -271.656048)
		(end 370.735606 -271.738852)
		(width 0.1143)
		(layer "In13.Cu")
		(net "P5E_CPU0_P2_TX_DP<12>")
	)
	(segment
		(start 371.951758 -277.00351)
		(end 371.983508 -277.021798)
		(width 0.1143)
		(layer "In13.Cu")
		(net "P5E_CPU0_P2_TX_DP<12>")
	)
	(segment
		(start 371.952012 -291.583364)
		(end 371.982492 -291.601144)
		(width 0.1143)
		(layer "In13.Cu")
		(net "P5E_CPU0_P2_TX_DP<12>")
	)
	(segment
		(start 372.609618 -296.52087)
		(end 372.563898 -296.56659)
		(width 0.1143)
		(layer "In13.Cu")
		(net "P5E_CPU0_P2_TX_DP<12>")
	)
	(segment
		(start 371.982492 -293.830756)
		(end 371.952012 -293.848536)
		(width 0.1143)
		(layer "In13.Cu")
		(net "P5E_CPU0_P2_TX_DP<12>")
	)
	(segment
		(start 371.912896 -288.320734)
		(end 371.952012 -288.343594)
		(width 0.1143)
		(layer "In13.Cu")
		(net "P5E_CPU0_P2_TX_DP<12>")
	)
	(segment
		(start 371.951758 -277.64867)
		(end 371.915436 -277.669752)
		(width 0.1143)
		(layer "In13.Cu")
		(net "P5E_CPU0_P2_TX_DP<12>")
	)
	(segment
		(start 371.982492 -290.590732)
		(end 371.952012 -290.608512)
		(width 0.1143)
		(layer "In13.Cu")
		(net "P5E_CPU0_P2_TX_DP<12>")
	)
	(segment
		(start 371.915436 -273.742404)
		(end 371.983508 -273.781774)
		(width 0.1143)
		(layer "In13.Cu")
		(net "P5E_CPU0_P2_TX_DP<12>")
	)
	(segment
		(start 371.912896 -293.180516)
		(end 371.952012 -293.203376)
		(width 0.1143)
		(layer "In13.Cu")
		(net "P5E_CPU0_P2_TX_DP<12>")
	)
	(segment
		(start 398.819878 -361.056936)
		(end 403.249892 -367.686336)
		(width 0.14224)
		(layer "In13.Cu")
		(net "P5E_CPU0_P2_TX_DP<12>")
	)
	(segment
		(start 371.912896 -281.840686)
		(end 371.952012 -281.863546)
		(width 0.1143)
		(layer "In13.Cu")
		(net "P5E_CPU0_P2_TX_DP<12>")
	)
	(segment
		(start 371.983508 -276.01037)
		(end 371.951758 -276.028658)
		(width 0.1143)
		(layer "In13.Cu")
		(net "P5E_CPU0_P2_TX_DP<12>")
	)
	(arc
		(start 419.760146 -375.220484)
		(mid 419.817362 -375.247597)
		(end 419.871652 -375.280174)
		(width 0.14224)
		(layer "In13.Cu")
		(net "P5E_CPU0_P2_TX_DP<12>")
	)
	(arc
		(start 372.563898 -297.623738)
		(mid 372.575499 -297.741574)
		(end 372.609872 -297.854878)
		(width 0.14224)
		(layer "In13.Cu")
		(net "P5E_CPU0_P2_TX_DP<12>")
	)
	(arc
		(start 371.915436 -287.389824)
		(mid 371.734784 -287.592569)
		(end 371.669564 -287.856168)
		(width 0.1143)
		(layer "In13.Cu")
		(net "P5E_CPU0_P2_TX_DP<12>")
	)
	(arc
		(start 371.915436 -279.289764)
		(mid 371.908287 -279.294664)
		(end 371.901212 -279.29967)
		(width 0.1143)
		(layer "In13.Cu")
		(net "P5E_CPU0_P2_TX_DP<12>")
	)
	(arc
		(start 372.452392 -295.651174)
		(mid 372.460735 -295.657409)
		(end 372.468902 -295.663874)
		(width 0.1143)
		(layer "In13.Cu")
		(net "P5E_CPU0_P2_TX_DP<12>")
	)
	(arc
		(start 371.984524 -286.742378)
		(mid 372.098453 -286.875525)
		(end 372.139464 -287.045908)
		(width 0.1143)
		(layer "In13.Cu")
		(net "P5E_CPU0_P2_TX_DP<12>")
	)
	(arc
		(start 371.982492 -289.981132)
		(mid 372.139469 -290.285932)
		(end 371.982492 -290.590732)
		(width 0.1143)
		(layer "In13.Cu")
		(net "P5E_CPU0_P2_TX_DP<12>")
	)
	(arc
		(start 371.901212 -280.212546)
		(mid 371.908286 -280.217553)
		(end 371.915436 -280.222452)
		(width 0.1143)
		(layer "In13.Cu")
		(net "P5E_CPU0_P2_TX_DP<12>")
	)
	(arc
		(start 371.983508 -277.021798)
		(mid 372.139436 -277.32609)
		(end 371.983508 -277.630382)
		(width 0.1143)
		(layer "In13.Cu")
		(net "P5E_CPU0_P2_TX_DP<12>")
	)
	(arc
		(start 371.982492 -294.841168)
		(mid 372.097919 -294.974544)
		(end 372.139464 -295.145968)
		(width 0.1143)
		(layer "In13.Cu")
		(net "P5E_CPU0_P2_TX_DP<12>")
	)
	(arc
		(start 371.983508 -273.781774)
		(mid 372.139436 -274.086066)
		(end 371.983508 -274.390358)
		(width 0.1143)
		(layer "In13.Cu")
		(net "P5E_CPU0_P2_TX_DP<12>")
	)
	(arc
		(start 371.513608 -272.971768)
		(mid 371.62505 -273.09841)
		(end 371.669818 -273.261074)
		(width 0.1143)
		(layer "In13.Cu")
		(net "P5E_CPU0_P2_TX_DP<12>")
	)
	(arc
		(start 371.912896 -290.631372)
		(mid 371.669569 -291.095938)
		(end 371.912896 -291.560504)
		(width 0.1143)
		(layer "In13.Cu")
		(net "P5E_CPU0_P2_TX_DP<12>")
	)
	(arc
		(start 371.901212 -277.679658)
		(mid 371.673829 -278.136096)
		(end 371.901212 -278.592534)
		(width 0.1143)
		(layer "In13.Cu")
		(net "P5E_CPU0_P2_TX_DP<12>")
	)
	(arc
		(start 372.139464 -295.145968)
		(mid 372.203979 -295.408187)
		(end 372.382796 -295.610534)
		(width 0.1143)
		(layer "In13.Cu")
		(net "P5E_CPU0_P2_TX_DP<12>")
	)
	(arc
		(start 372.469156 -295.66362)
		(mid 372.572657 -295.793817)
		(end 372.609618 -295.955974)
		(width 0.1143)
		(layer "In13.Cu")
		(net "P5E_CPU0_P2_TX_DP<12>")
	)
	(arc
		(start 371.912896 -282.531566)
		(mid 371.669569 -282.996132)
		(end 371.912896 -283.460698)
		(width 0.1143)
		(layer "In13.Cu")
		(net "P5E_CPU0_P2_TX_DP<12>")
	)
	(arc
		(start 371.896894 -274.442682)
		(mid 371.663996 -274.896072)
		(end 371.896894 -275.349462)
		(width 0.1143)
		(layer "In13.Cu")
		(net "P5E_CPU0_P2_TX_DP<12>")
	)
	(arc
		(start 371.912896 -293.871396)
		(mid 371.669569 -294.335962)
		(end 371.912896 -294.800528)
		(width 0.1143)
		(layer "In13.Cu")
		(net "P5E_CPU0_P2_TX_DP<12>")
	)
	(arc
		(start 371.982492 -293.221156)
		(mid 372.139469 -293.525956)
		(end 371.982492 -293.830756)
		(width 0.1143)
		(layer "In13.Cu")
		(net "P5E_CPU0_P2_TX_DP<12>")
	)
	(arc
		(start 403.249892 -367.686336)
		(mid 403.363007 -367.824173)
		(end 403.500844 -367.937288)
		(width 0.14224)
		(layer "In13.Cu")
		(net "P5E_CPU0_P2_TX_DP<12>")
	)
	(arc
		(start 371.983508 -280.261822)
		(mid 372.139436 -280.566114)
		(end 371.983508 -280.870406)
		(width 0.1143)
		(layer "In13.Cu")
		(net "P5E_CPU0_P2_TX_DP<12>")
	)
	(arc
		(start 371.901212 -276.972522)
		(mid 371.908286 -276.977529)
		(end 371.915436 -276.982428)
		(width 0.1143)
		(layer "In13.Cu")
		(net "P5E_CPU0_P2_TX_DP<12>")
	)
	(arc
		(start 371.19941 -272.466054)
		(mid 371.263925 -272.728273)
		(end 371.442742 -272.93062)
		(width 0.1143)
		(layer "In13.Cu")
		(net "P5E_CPU0_P2_TX_DP<12>")
	)
	(arc
		(start 371.983508 -275.401786)
		(mid 372.139436 -275.706078)
		(end 371.983508 -276.01037)
		(width 0.1143)
		(layer "In13.Cu")
		(net "P5E_CPU0_P2_TX_DP<12>")
	)
	(arc
		(start 371.901212 -278.592534)
		(mid 371.908286 -278.597541)
		(end 371.915436 -278.60244)
		(width 0.1143)
		(layer "In13.Cu")
		(net "P5E_CPU0_P2_TX_DP<12>")
	)
	(arc
		(start 372.139464 -287.045908)
		(mid 372.097915 -287.21733)
		(end 371.982492 -287.350708)
		(width 0.1143)
		(layer "In13.Cu")
		(net "P5E_CPU0_P2_TX_DP<12>")
	)
	(arc
		(start 371.912896 -284.151578)
		(mid 371.669569 -284.616144)
		(end 371.912896 -285.08071)
		(width 0.1143)
		(layer "In13.Cu")
		(net "P5E_CPU0_P2_TX_DP<12>")
	)
	(arc
		(start 371.982492 -281.881326)
		(mid 372.139469 -282.186126)
		(end 371.982492 -282.490926)
		(width 0.1143)
		(layer "In13.Cu")
		(net "P5E_CPU0_P2_TX_DP<12>")
	)
	(arc
		(start 371.983508 -278.64181)
		(mid 372.139436 -278.946102)
		(end 371.983508 -279.250394)
		(width 0.1143)
		(layer "In13.Cu")
		(net "P5E_CPU0_P2_TX_DP<12>")
	)
	(arc
		(start 371.669564 -287.856168)
		(mid 371.734079 -288.118387)
		(end 371.912896 -288.320734)
		(width 0.1143)
		(layer "In13.Cu")
		(net "P5E_CPU0_P2_TX_DP<12>")
	)
	(arc
		(start 371.912896 -289.01136)
		(mid 371.669569 -289.475926)
		(end 371.912896 -289.940492)
		(width 0.1143)
		(layer "In13.Cu")
		(net "P5E_CPU0_P2_TX_DP<12>")
	)
	(arc
		(start 371.669818 -273.261074)
		(mid 371.67099 -273.286529)
		(end 371.673628 -273.311874)
		(width 0.1143)
		(layer "In13.Cu")
		(net "P5E_CPU0_P2_TX_DP<12>")
	)
	(arc
		(start 371.982492 -285.12135)
		(mid 372.139469 -285.42615)
		(end 371.982492 -285.73095)
		(width 0.1143)
		(layer "In13.Cu")
		(net "P5E_CPU0_P2_TX_DP<12>")
	)
	(arc
		(start 371.982492 -291.601144)
		(mid 372.139469 -291.905944)
		(end 371.982492 -292.210744)
		(width 0.1143)
		(layer "In13.Cu")
		(net "P5E_CPU0_P2_TX_DP<12>")
	)
	(arc
		(start 371.912896 -280.911554)
		(mid 371.669569 -281.37612)
		(end 371.912896 -281.840686)
		(width 0.1143)
		(layer "In13.Cu")
		(net "P5E_CPU0_P2_TX_DP<12>")
	)
	(arc
		(start 398.731994 -360.893106)
		(mid 398.771918 -360.977177)
		(end 398.819878 -361.056936)
		(width 0.14224)
		(layer "In13.Cu")
		(net "P5E_CPU0_P2_TX_DP<12>")
	)
	(arc
		(start 371.673628 -273.311874)
		(mid 371.754296 -273.549746)
		(end 371.915436 -273.742404)
		(width 0.1143)
		(layer "In13.Cu")
		(net "P5E_CPU0_P2_TX_DP<12>")
	)
	(arc
		(start 372.139464 -288.66592)
		(mid 372.097915 -288.837342)
		(end 371.982492 -288.97072)
		(width 0.1143)
		(layer "In13.Cu")
		(net "P5E_CPU0_P2_TX_DP<12>")
	)
	(arc
		(start 370.739416 -271.761712)
		(mid 370.820849 -271.96411)
		(end 370.972842 -272.120614)
		(width 0.1143)
		(layer "In13.Cu")
		(net "P5E_CPU0_P2_TX_DP<12>")
	)
	(arc
		(start 371.915436 -277.669752)
		(mid 371.908287 -277.674652)
		(end 371.901212 -277.679658)
		(width 0.1143)
		(layer "In13.Cu")
		(net "P5E_CPU0_P2_TX_DP<12>")
	)
	(arc
		(start 371.901212 -276.059646)
		(mid 371.673829 -276.516084)
		(end 371.901212 -276.972522)
		(width 0.1143)
		(layer "In13.Cu")
		(net "P5E_CPU0_P2_TX_DP<12>")
	)
	(arc
		(start 371.042438 -272.161254)
		(mid 371.157865 -272.29463)
		(end 371.19941 -272.466054)
		(width 0.1143)
		(layer "In13.Cu")
		(net "P5E_CPU0_P2_TX_DP<12>")
	)
	(arc
		(start 405.506174 -369.277392)
		(mid 405.662234 -369.370994)
		(end 405.826722 -369.448842)
		(width 0.14224)
		(layer "In13.Cu")
		(net "P5E_CPU0_P2_TX_DP<12>")
	)
	(arc
		(start 370.735606 -271.738852)
		(mid 370.737394 -271.750301)
		(end 370.739416 -271.761712)
		(width 0.1143)
		(layer "In13.Cu")
		(net "P5E_CPU0_P2_TX_DP<12>")
	)
	(arc
		(start 420.156894 -375.470166)
		(mid 420.207783 -375.50787)
		(end 420.254684 -375.55043)
		(width 0.14224)
		(layer "In13.Cu")
		(net "P5E_CPU0_P2_TX_DP<12>")
	)
	(arc
		(start 371.915436 -276.04974)
		(mid 371.908287 -276.05464)
		(end 371.901212 -276.059646)
		(width 0.1143)
		(layer "In13.Cu")
		(net "P5E_CPU0_P2_TX_DP<12>")
	)
	(arc
		(start 371.984524 -288.36239)
		(mid 372.098453 -288.495537)
		(end 372.139464 -288.66592)
		(width 0.1143)
		(layer "In13.Cu")
		(net "P5E_CPU0_P2_TX_DP<12>")
	)
	(arc
		(start 371.982492 -283.501338)
		(mid 372.139469 -283.806138)
		(end 371.982492 -284.110938)
		(width 0.1143)
		(layer "In13.Cu")
		(net "P5E_CPU0_P2_TX_DP<12>")
	)
	(arc
		(start 371.912896 -285.77159)
		(mid 371.669569 -286.236156)
		(end 371.912896 -286.700722)
		(width 0.1143)
		(layer "In13.Cu")
		(net "P5E_CPU0_P2_TX_DP<12>")
	)
	(arc
		(start 371.912896 -292.251384)
		(mid 371.669569 -292.71595)
		(end 371.912896 -293.180516)
		(width 0.1143)
		(layer "In13.Cu")
		(net "P5E_CPU0_P2_TX_DP<12>")
	)
	(arc
		(start 371.901212 -279.29967)
		(mid 371.673829 -279.756108)
		(end 371.901212 -280.212546)
		(width 0.1143)
		(layer "In13.Cu")
		(net "P5E_CPU0_P2_TX_DP<12>")
	)
	(segment
		(start 419.33495 -380.15164)
		(end 419.33495 -380.85522)
		(width 0.12954)
		(layer "F.Cu")
		(net "P5E_CPU0_P2_TX_DP<11>")
	)
	(segment
		(start 419.33495 -380.85522)
		(end 419.03904 -381.15113)
		(width 0.12954)
		(layer "F.Cu")
		(net "P5E_CPU0_P2_TX_DP<11>")
	)
	(segment
		(start 419.06444 -379.88113)
		(end 419.33495 -380.15164)
		(width 0.12954)
		(layer "F.Cu")
		(net "P5E_CPU0_P2_TX_DP<11>")
	)
	(segment
		(start 369.888008 -273.010122)
		(end 370.35486 -273.27606)
		(width 0.12954)
		(layer "F.Cu")
		(net "P5E_CPU0_P2_TX_DP<11>")
	)
	(segment
		(start 371.015006 -284.12694)
		(end 371.01272 -284.128464)
		(width 0.1143)
		(layer "In13.Cu")
		(net "P5E_CPU0_P2_TX_DP<11>")
	)
	(segment
		(start 371.011958 -290.608512)
		(end 371.010942 -290.60902)
		(width 0.1143)
		(layer "In13.Cu")
		(net "P5E_CPU0_P2_TX_DP<11>")
	)
	(segment
		(start 370.35486 -273.27606)
		(end 370.652802 -273.27606)
		(width 0.1143)
		(layer "In13.Cu")
		(net "P5E_CPU0_P2_TX_DP<11>")
	)
	(segment
		(start 371.01272 -289.96386)
		(end 371.014752 -289.96513)
		(width 0.1143)
		(layer "In13.Cu")
		(net "P5E_CPU0_P2_TX_DP<11>")
	)
	(segment
		(start 371.198394 -295.145206)
		(end 371.198394 -295.146476)
		(width 0.1143)
		(layer "In13.Cu")
		(net "P5E_CPU0_P2_TX_DP<11>")
	)
	(segment
		(start 371.01272 -291.583872)
		(end 371.043708 -291.601652)
		(width 0.1143)
		(layer "In13.Cu")
		(net "P5E_CPU0_P2_TX_DP<11>")
	)
	(segment
		(start 370.972842 -285.08071)
		(end 371.010942 -285.103062)
		(width 0.1143)
		(layer "In13.Cu")
		(net "P5E_CPU0_P2_TX_DP<11>")
	)
	(segment
		(start 371.015006 -288.345118)
		(end 371.01526 -288.345118)
		(width 0.1143)
		(layer "In13.Cu")
		(net "P5E_CPU0_P2_TX_DP<11>")
	)
	(segment
		(start 418.381942 -376.192288)
		(end 418.770054 -376.192288)
		(width 0.14224)
		(layer "In13.Cu")
		(net "P5E_CPU0_P2_TX_DP<11>")
	)
	(segment
		(start 419.35527 -379.5903)
		(end 419.06444 -379.88113)
		(width 0.14224)
		(layer "In13.Cu")
		(net "P5E_CPU0_P2_TX_DP<11>")
	)
	(segment
		(start 371.669564 -295.831514)
		(end 371.669564 -296.538142)
		(width 0.1143)
		(layer "In13.Cu")
		(net "P5E_CPU0_P2_TX_DP<11>")
	)
	(segment
		(start 417.161472 -375.16435)
		(end 418.053266 -376.056144)
		(width 0.14224)
		(layer "In13.Cu")
		(net "P5E_CPU0_P2_TX_DP<11>")
	)
	(segment
		(start 371.015514 -293.846758)
		(end 370.85524 -293.939468)
		(width 0.1143)
		(layer "In13.Cu")
		(net "P5E_CPU0_P2_TX_DP<11>")
	)
	(segment
		(start 371.010942 -285.103062)
		(end 371.011958 -285.10357)
		(width 0.1143)
		(layer "In13.Cu")
		(net "P5E_CPU0_P2_TX_DP<11>")
	)
	(segment
		(start 371.623844 -296.61231)
		(end 371.623844 -297.75023)
		(width 0.14224)
		(layer "In13.Cu")
		(net "P5E_CPU0_P2_TX_DP<11>")
	)
	(segment
		(start 371.583204 -295.692576)
		(end 371.632226 -295.741598)
		(width 0.1143)
		(layer "In13.Cu")
		(net "P5E_CPU0_P2_TX_DP<11>")
	)
	(segment
		(start 371.015006 -290.606734)
		(end 371.01272 -290.608258)
		(width 0.1143)
		(layer "In13.Cu")
		(net "P5E_CPU0_P2_TX_DP<11>")
	)
	(segment
		(start 371.043708 -291.601652)
		(end 371.048788 -291.605208)
		(width 0.1143)
		(layer "In13.Cu")
		(net "P5E_CPU0_P2_TX_DP<11>")
	)
	(segment
		(start 371.01272 -292.228016)
		(end 371.00637 -292.231826)
		(width 0.1143)
		(layer "In13.Cu")
		(net "P5E_CPU0_P2_TX_DP<11>")
	)
	(segment
		(start 371.01272 -285.748476)
		(end 371.011958 -285.74873)
		(width 0.1143)
		(layer "In13.Cu")
		(net "P5E_CPU0_P2_TX_DP<11>")
	)
	(segment
		(start 370.972842 -286.700722)
		(end 371.045486 -286.74314)
		(width 0.1143)
		(layer "In13.Cu")
		(net "P5E_CPU0_P2_TX_DP<11>")
	)
	(segment
		(start 370.972842 -289.940492)
		(end 371.010942 -289.962844)
		(width 0.1143)
		(layer "In13.Cu")
		(net "P5E_CPU0_P2_TX_DP<11>")
	)
	(segment
		(start 371.015006 -282.506928)
		(end 371.01272 -282.508452)
		(width 0.1143)
		(layer "In13.Cu")
		(net "P5E_CPU0_P2_TX_DP<11>")
	)
	(segment
		(start 370.85524 -293.939468)
		(end 370.816378 -293.996872)
		(width 0.1143)
		(layer "In13.Cu")
		(net "P5E_CPU0_P2_TX_DP<11>")
	)
	(segment
		(start 371.015514 -284.12694)
		(end 371.015006 -284.12694)
		(width 0.1143)
		(layer "In13.Cu")
		(net "P5E_CPU0_P2_TX_DP<11>")
	)
	(segment
		(start 371.199664 -287.045908)
		(end 371.199664 -287.05048)
		(width 0.1143)
		(layer "In13.Cu")
		(net "P5E_CPU0_P2_TX_DP<11>")
	)
	(segment
		(start 419.35527 -376.777504)
		(end 419.35527 -379.5903)
		(width 0.14224)
		(layer "In13.Cu")
		(net "P5E_CPU0_P2_TX_DP<11>")
	)
	(segment
		(start 371.042438 -279.250902)
		(end 370.972842 -279.291542)
		(width 0.1143)
		(layer "In13.Cu")
		(net "P5E_CPU0_P2_TX_DP<11>")
	)
	(segment
		(start 371.042438 -277.63089)
		(end 370.972842 -277.67153)
		(width 0.1143)
		(layer "In13.Cu")
		(net "P5E_CPU0_P2_TX_DP<11>")
	)
	(segment
		(start 371.010942 -291.582856)
		(end 371.01272 -291.583872)
		(width 0.1143)
		(layer "In13.Cu")
		(net "P5E_CPU0_P2_TX_DP<11>")
	)
	(segment
		(start 371.011958 -288.9885)
		(end 371.010942 -288.989008)
		(width 0.1143)
		(layer "In13.Cu")
		(net "P5E_CPU0_P2_TX_DP<11>")
	)
	(segment
		(start 371.046756 -292.20795)
		(end 371.01272 -292.228016)
		(width 0.1143)
		(layer "In13.Cu")
		(net "P5E_CPU0_P2_TX_DP<11>")
	)
	(segment
		(start 371.047518 -287.347406)
		(end 371.043708 -287.3502)
		(width 0.1143)
		(layer "In13.Cu")
		(net "P5E_CPU0_P2_TX_DP<11>")
	)
	(segment
		(start 370.972842 -278.600662)
		(end 371.042438 -278.641302)
		(width 0.1143)
		(layer "In13.Cu")
		(net "P5E_CPU0_P2_TX_DP<11>")
	)
	(segment
		(start 371.014752 -283.485336)
		(end 371.01526 -283.485336)
		(width 0.1143)
		(layer "In13.Cu")
		(net "P5E_CPU0_P2_TX_DP<11>")
	)
	(segment
		(start 371.010942 -288.989008)
		(end 370.972842 -289.01136)
		(width 0.1143)
		(layer "In13.Cu")
		(net "P5E_CPU0_P2_TX_DP<11>")
	)
	(segment
		(start 371.014752 -285.105348)
		(end 371.01526 -285.105348)
		(width 0.1143)
		(layer "In13.Cu")
		(net "P5E_CPU0_P2_TX_DP<11>")
	)
	(segment
		(start 371.01272 -282.508452)
		(end 371.011958 -282.508706)
		(width 0.1143)
		(layer "In13.Cu")
		(net "P5E_CPU0_P2_TX_DP<11>")
	)
	(segment
		(start 371.011958 -285.74873)
		(end 371.010942 -285.749238)
		(width 0.1143)
		(layer "In13.Cu")
		(net "P5E_CPU0_P2_TX_DP<11>")
	)
	(segment
		(start 370.972842 -283.460698)
		(end 370.9797 -283.464762)
		(width 0.1143)
		(layer "In13.Cu")
		(net "P5E_CPU0_P2_TX_DP<11>")
	)
	(segment
		(start 370.968016 -294.801798)
		(end 371.043708 -294.846248)
		(width 0.1143)
		(layer "In13.Cu")
		(net "P5E_CPU0_P2_TX_DP<11>")
	)
	(segment
		(start 371.015006 -288.986722)
		(end 371.01272 -288.988246)
		(width 0.1143)
		(layer "In13.Cu")
		(net "P5E_CPU0_P2_TX_DP<11>")
	)
	(segment
		(start 371.01272 -281.864054)
		(end 371.014752 -281.865324)
		(width 0.1143)
		(layer "In13.Cu")
		(net "P5E_CPU0_P2_TX_DP<11>")
	)
	(segment
		(start 371.043708 -287.3502)
		(end 370.975382 -287.389824)
		(width 0.1143)
		(layer "In13.Cu")
		(net "P5E_CPU0_P2_TX_DP<11>")
	)
	(segment
		(start 371.015514 -282.506928)
		(end 371.015006 -282.506928)
		(width 0.1143)
		(layer "In13.Cu")
		(net "P5E_CPU0_P2_TX_DP<11>")
	)
	(segment
		(start 370.652802 -273.27606)
		(end 370.735606 -273.358864)
		(width 0.1143)
		(layer "In13.Cu")
		(net "P5E_CPU0_P2_TX_DP<11>")
	)
	(segment
		(start 370.972842 -276.98065)
		(end 371.042438 -277.02129)
		(width 0.1143)
		(layer "In13.Cu")
		(net "P5E_CPU0_P2_TX_DP<11>")
	)
	(segment
		(start 370.972842 -291.560504)
		(end 371.010942 -291.582856)
		(width 0.1143)
		(layer "In13.Cu")
		(net "P5E_CPU0_P2_TX_DP<11>")
	)
	(segment
		(start 371.01272 -290.608258)
		(end 371.011958 -290.608512)
		(width 0.1143)
		(layer "In13.Cu")
		(net "P5E_CPU0_P2_TX_DP<11>")
	)
	(segment
		(start 370.9797 -283.464762)
		(end 370.980462 -283.46527)
		(width 0.1143)
		(layer "In13.Cu")
		(net "P5E_CPU0_P2_TX_DP<11>")
	)
	(segment
		(start 371.014752 -281.865324)
		(end 371.01526 -281.865324)
		(width 0.1143)
		(layer "In13.Cu")
		(net "P5E_CPU0_P2_TX_DP<11>")
	)
	(segment
		(start 371.010942 -282.509214)
		(end 370.972842 -282.531566)
		(width 0.1143)
		(layer "In13.Cu")
		(net "P5E_CPU0_P2_TX_DP<11>")
	)
	(segment
		(start 370.972842 -293.180516)
		(end 371.010942 -293.202868)
		(width 0.1143)
		(layer "In13.Cu")
		(net "P5E_CPU0_P2_TX_DP<11>")
	)
	(segment
		(start 370.97335 -280.9113)
		(end 370.972842 -280.911554)
		(width 0.1143)
		(layer "In13.Cu")
		(net "P5E_CPU0_P2_TX_DP<11>")
	)
	(segment
		(start 371.048788 -292.20668)
		(end 371.046756 -292.20795)
		(width 0.1143)
		(layer "In13.Cu")
		(net "P5E_CPU0_P2_TX_DP<11>")
	)
	(segment
		(start 371.01272 -288.988246)
		(end 371.011958 -288.9885)
		(width 0.1143)
		(layer "In13.Cu")
		(net "P5E_CPU0_P2_TX_DP<11>")
	)
	(segment
		(start 370.972842 -273.740626)
		(end 371.042438 -273.781266)
		(width 0.1143)
		(layer "In13.Cu")
		(net "P5E_CPU0_P2_TX_DP<11>")
	)
	(segment
		(start 371.669564 -296.538142)
		(end 371.623844 -296.583862)
		(width 0.1143)
		(layer "In13.Cu")
		(net "P5E_CPU0_P2_TX_DP<11>")
	)
	(segment
		(start 371.015006 -285.746952)
		(end 371.01272 -285.748476)
		(width 0.1143)
		(layer "In13.Cu")
		(net "P5E_CPU0_P2_TX_DP<11>")
	)
	(segment
		(start 371.015514 -288.986722)
		(end 371.015006 -288.986722)
		(width 0.1143)
		(layer "In13.Cu")
		(net "P5E_CPU0_P2_TX_DP<11>")
	)
	(segment
		(start 371.011958 -282.508706)
		(end 371.010942 -282.509214)
		(width 0.1143)
		(layer "In13.Cu")
		(net "P5E_CPU0_P2_TX_DP<11>")
	)
	(segment
		(start 370.972842 -275.360638)
		(end 371.042438 -275.401278)
		(width 0.1143)
		(layer "In13.Cu")
		(net "P5E_CPU0_P2_TX_DP<11>")
	)
	(segment
		(start 371.015514 -285.746952)
		(end 371.015006 -285.746952)
		(width 0.1143)
		(layer "In13.Cu")
		(net "P5E_CPU0_P2_TX_DP<11>")
	)
	(segment
		(start 371.01272 -285.104078)
		(end 371.014752 -285.105348)
		(width 0.1143)
		(layer "In13.Cu")
		(net "P5E_CPU0_P2_TX_DP<11>")
	)
	(segment
		(start 370.972842 -280.220674)
		(end 371.042438 -280.261314)
		(width 0.1143)
		(layer "In13.Cu")
		(net "P5E_CPU0_P2_TX_DP<11>")
	)
	(segment
		(start 371.475762 -295.629838)
		(end 371.583204 -295.692576)
		(width 0.1143)
		(layer "In13.Cu")
		(net "P5E_CPU0_P2_TX_DP<11>")
	)
	(segment
		(start 371.010942 -285.749238)
		(end 370.972842 -285.77159)
		(width 0.1143)
		(layer "In13.Cu")
		(net "P5E_CPU0_P2_TX_DP<11>")
	)
	(segment
		(start 371.010942 -289.962844)
		(end 371.011958 -289.963352)
		(width 0.1143)
		(layer "In13.Cu")
		(net "P5E_CPU0_P2_TX_DP<11>")
	)
	(segment
		(start 397.966438 -361.544362)
		(end 402.488908 -368.312446)
		(width 0.14224)
		(layer "In13.Cu")
		(net "P5E_CPU0_P2_TX_DP<11>")
	)
	(segment
		(start 371.011958 -283.483558)
		(end 371.01272 -283.484066)
		(width 0.1143)
		(layer "In13.Cu")
		(net "P5E_CPU0_P2_TX_DP<11>")
	)
	(segment
		(start 371.010942 -293.202868)
		(end 371.011958 -293.203376)
		(width 0.1143)
		(layer "In13.Cu")
		(net "P5E_CPU0_P2_TX_DP<11>")
	)
	(segment
		(start 402.70938 -368.532918)
		(end 405.247348 -370.22913)
		(width 0.14224)
		(layer "In13.Cu")
		(net "P5E_CPU0_P2_TX_DP<11>")
	)
	(segment
		(start 371.042438 -276.010878)
		(end 370.972842 -276.051518)
		(width 0.1143)
		(layer "In13.Cu")
		(net "P5E_CPU0_P2_TX_DP<11>")
	)
	(segment
		(start 371.014752 -293.205154)
		(end 371.01526 -293.205154)
		(width 0.1143)
		(layer "In13.Cu")
		(net "P5E_CPU0_P2_TX_DP<11>")
	)
	(segment
		(start 371.01272 -293.203884)
		(end 371.014752 -293.205154)
		(width 0.1143)
		(layer "In13.Cu")
		(net "P5E_CPU0_P2_TX_DP<11>")
	)
	(segment
		(start 371.011958 -289.963352)
		(end 371.01272 -289.96386)
		(width 0.1143)
		(layer "In13.Cu")
		(net "P5E_CPU0_P2_TX_DP<11>")
	)
	(segment
		(start 371.010942 -281.863038)
		(end 371.011958 -281.863546)
		(width 0.1143)
		(layer "In13.Cu")
		(net "P5E_CPU0_P2_TX_DP<11>")
	)
	(segment
		(start 371.01272 -284.128464)
		(end 371.011958 -284.128718)
		(width 0.1143)
		(layer "In13.Cu")
		(net "P5E_CPU0_P2_TX_DP<11>")
	)
	(segment
		(start 370.980462 -283.46527)
		(end 371.011958 -283.483558)
		(width 0.1143)
		(layer "In13.Cu")
		(net "P5E_CPU0_P2_TX_DP<11>")
	)
	(segment
		(start 371.010942 -284.129226)
		(end 370.972842 -284.151578)
		(width 0.1143)
		(layer "In13.Cu")
		(net "P5E_CPU0_P2_TX_DP<11>")
	)
	(segment
		(start 371.042438 -280.870914)
		(end 370.97335 -280.9113)
		(width 0.1143)
		(layer "In13.Cu")
		(net "P5E_CPU0_P2_TX_DP<11>")
	)
	(segment
		(start 371.010942 -290.60902)
		(end 370.972842 -290.631372)
		(width 0.1143)
		(layer "In13.Cu")
		(net "P5E_CPU0_P2_TX_DP<11>")
	)
	(segment
		(start 371.011958 -293.203376)
		(end 371.01272 -293.203884)
		(width 0.1143)
		(layer "In13.Cu")
		(net "P5E_CPU0_P2_TX_DP<11>")
	)
	(segment
		(start 371.011958 -284.128718)
		(end 371.010942 -284.129226)
		(width 0.1143)
		(layer "In13.Cu")
		(net "P5E_CPU0_P2_TX_DP<11>")
	)
	(segment
		(start 371.623844 -296.583862)
		(end 371.623844 -296.61231)
		(width 0.1143)
		(layer "In13.Cu")
		(net "P5E_CPU0_P2_TX_DP<11>")
	)
	(segment
		(start 371.011958 -285.10357)
		(end 371.01272 -285.104078)
		(width 0.1143)
		(layer "In13.Cu")
		(net "P5E_CPU0_P2_TX_DP<11>")
	)
	(segment
		(start 370.972842 -288.320734)
		(end 370.979192 -288.32429)
		(width 0.1143)
		(layer "In13.Cu")
		(net "P5E_CPU0_P2_TX_DP<11>")
	)
	(segment
		(start 371.014752 -289.96513)
		(end 371.01526 -289.96513)
		(width 0.1143)
		(layer "In13.Cu")
		(net "P5E_CPU0_P2_TX_DP<11>")
	)
	(segment
		(start 371.015514 -290.606734)
		(end 371.015006 -290.606734)
		(width 0.1143)
		(layer "In13.Cu")
		(net "P5E_CPU0_P2_TX_DP<11>")
	)
	(segment
		(start 371.01272 -283.484066)
		(end 371.014752 -283.485336)
		(width 0.1143)
		(layer "In13.Cu")
		(net "P5E_CPU0_P2_TX_DP<11>")
	)
	(segment
		(start 405.247348 -370.22913)
		(end 417.161472 -375.16435)
		(width 0.14224)
		(layer "In13.Cu")
		(net "P5E_CPU0_P2_TX_DP<11>")
	)
	(segment
		(start 370.979192 -288.32429)
		(end 371.015006 -288.345118)
		(width 0.1143)
		(layer "In13.Cu")
		(net "P5E_CPU0_P2_TX_DP<11>")
	)
	(segment
		(start 371.042438 -274.390866)
		(end 370.972842 -274.431506)
		(width 0.1143)
		(layer "In13.Cu")
		(net "P5E_CPU0_P2_TX_DP<11>")
	)
	(segment
		(start 418.860224 -376.229626)
		(end 419.317932 -376.687334)
		(width 0.14224)
		(layer "In13.Cu")
		(net "P5E_CPU0_P2_TX_DP<11>")
	)
	(segment
		(start 370.972842 -281.840686)
		(end 371.010942 -281.863038)
		(width 0.1143)
		(layer "In13.Cu")
		(net "P5E_CPU0_P2_TX_DP<11>")
	)
	(segment
		(start 371.709696 -298.181522)
		(end 397.966438 -361.544362)
		(width 0.14224)
		(layer "In13.Cu")
		(net "P5E_CPU0_P2_TX_DP<11>")
	)
	(segment
		(start 371.011958 -281.863546)
		(end 371.01272 -281.864054)
		(width 0.1143)
		(layer "In13.Cu")
		(net "P5E_CPU0_P2_TX_DP<11>")
	)
	(segment
		(start 371.00637 -292.231826)
		(end 370.972842 -292.251384)
		(width 0.1143)
		(layer "In13.Cu")
		(net "P5E_CPU0_P2_TX_DP<11>")
	)
	(arc
		(start 370.972842 -274.431506)
		(mid 370.729515 -274.896072)
		(end 370.972842 -275.360638)
		(width 0.1143)
		(layer "In13.Cu")
		(net "P5E_CPU0_P2_TX_DP<11>")
	)
	(arc
		(start 371.01526 -289.96513)
		(mid 371.199993 -290.285822)
		(end 371.015514 -290.606734)
		(width 0.1143)
		(layer "In13.Cu")
		(net "P5E_CPU0_P2_TX_DP<11>")
	)
	(arc
		(start 371.042438 -273.781266)
		(mid 371.199415 -274.086066)
		(end 371.042438 -274.390866)
		(width 0.1143)
		(layer "In13.Cu")
		(net "P5E_CPU0_P2_TX_DP<11>")
	)
	(arc
		(start 371.623844 -297.75023)
		(mid 371.645541 -297.970102)
		(end 371.709696 -298.181522)
		(width 0.14224)
		(layer "In13.Cu")
		(net "P5E_CPU0_P2_TX_DP<11>")
	)
	(arc
		(start 370.972842 -289.01136)
		(mid 370.729515 -289.475926)
		(end 370.972842 -289.940492)
		(width 0.1143)
		(layer "In13.Cu")
		(net "P5E_CPU0_P2_TX_DP<11>")
	)
	(arc
		(start 371.042438 -275.401278)
		(mid 371.199415 -275.706078)
		(end 371.042438 -276.010878)
		(width 0.1143)
		(layer "In13.Cu")
		(net "P5E_CPU0_P2_TX_DP<11>")
	)
	(arc
		(start 418.053266 -376.056144)
		(mid 418.204064 -376.156904)
		(end 418.381942 -376.192288)
		(width 0.14224)
		(layer "In13.Cu")
		(net "P5E_CPU0_P2_TX_DP<11>")
	)
	(arc
		(start 370.739416 -273.381724)
		(mid 370.820849 -273.584122)
		(end 370.972842 -273.740626)
		(width 0.1143)
		(layer "In13.Cu")
		(net "P5E_CPU0_P2_TX_DP<11>")
	)
	(arc
		(start 370.816378 -293.996872)
		(mid 370.727384 -294.430363)
		(end 370.968016 -294.801798)
		(width 0.1143)
		(layer "In13.Cu")
		(net "P5E_CPU0_P2_TX_DP<11>")
	)
	(arc
		(start 402.488908 -368.312446)
		(mid 402.588292 -368.433534)
		(end 402.70938 -368.532918)
		(width 0.14224)
		(layer "In13.Cu")
		(net "P5E_CPU0_P2_TX_DP<11>")
	)
	(arc
		(start 371.045486 -286.74314)
		(mid 371.158893 -286.876029)
		(end 371.199664 -287.045908)
		(width 0.1143)
		(layer "In13.Cu")
		(net "P5E_CPU0_P2_TX_DP<11>")
	)
	(arc
		(start 370.972842 -290.631372)
		(mid 370.729515 -291.095938)
		(end 370.972842 -291.560504)
		(width 0.1143)
		(layer "In13.Cu")
		(net "P5E_CPU0_P2_TX_DP<11>")
	)
	(arc
		(start 371.042438 -278.641302)
		(mid 371.199415 -278.946102)
		(end 371.042438 -279.250902)
		(width 0.1143)
		(layer "In13.Cu")
		(net "P5E_CPU0_P2_TX_DP<11>")
	)
	(arc
		(start 371.043708 -294.846248)
		(mid 371.157423 -294.976906)
		(end 371.198394 -295.145206)
		(width 0.1143)
		(layer "In13.Cu")
		(net "P5E_CPU0_P2_TX_DP<11>")
	)
	(arc
		(start 370.972842 -277.67153)
		(mid 370.729515 -278.136096)
		(end 370.972842 -278.600662)
		(width 0.1143)
		(layer "In13.Cu")
		(net "P5E_CPU0_P2_TX_DP<11>")
	)
	(arc
		(start 370.972842 -280.911554)
		(mid 370.729515 -281.37612)
		(end 370.972842 -281.840686)
		(width 0.1143)
		(layer "In13.Cu")
		(net "P5E_CPU0_P2_TX_DP<11>")
	)
	(arc
		(start 371.042438 -277.02129)
		(mid 371.199415 -277.32609)
		(end 371.042438 -277.63089)
		(width 0.1143)
		(layer "In13.Cu")
		(net "P5E_CPU0_P2_TX_DP<11>")
	)
	(arc
		(start 370.972842 -292.251384)
		(mid 370.729515 -292.71595)
		(end 370.972842 -293.180516)
		(width 0.1143)
		(layer "In13.Cu")
		(net "P5E_CPU0_P2_TX_DP<11>")
	)
	(arc
		(start 371.01526 -293.205154)
		(mid 371.199993 -293.525846)
		(end 371.015514 -293.846758)
		(width 0.1143)
		(layer "In13.Cu")
		(net "P5E_CPU0_P2_TX_DP<11>")
	)
	(arc
		(start 371.198394 -295.146476)
		(mid 371.272665 -295.425116)
		(end 371.475762 -295.629838)
		(width 0.1143)
		(layer "In13.Cu")
		(net "P5E_CPU0_P2_TX_DP<11>")
	)
	(arc
		(start 370.972842 -279.291542)
		(mid 370.729515 -279.756108)
		(end 370.972842 -280.220674)
		(width 0.1143)
		(layer "In13.Cu")
		(net "P5E_CPU0_P2_TX_DP<11>")
	)
	(arc
		(start 418.770054 -376.192288)
		(mid 418.818849 -376.201994)
		(end 418.860224 -376.229626)
		(width 0.14224)
		(layer "In13.Cu")
		(net "P5E_CPU0_P2_TX_DP<11>")
	)
	(arc
		(start 419.317932 -376.687334)
		(mid 419.345575 -376.728704)
		(end 419.35527 -376.777504)
		(width 0.14224)
		(layer "In13.Cu")
		(net "P5E_CPU0_P2_TX_DP<11>")
	)
	(arc
		(start 371.632226 -295.741598)
		(mid 371.659845 -295.782838)
		(end 371.669564 -295.831514)
		(width 0.1143)
		(layer "In13.Cu")
		(net "P5E_CPU0_P2_TX_DP<11>")
	)
	(arc
		(start 371.042438 -280.261314)
		(mid 371.199415 -280.566114)
		(end 371.042438 -280.870914)
		(width 0.1143)
		(layer "In13.Cu")
		(net "P5E_CPU0_P2_TX_DP<11>")
	)
	(arc
		(start 371.048788 -291.605208)
		(mid 371.202886 -291.905944)
		(end 371.048788 -292.20668)
		(width 0.1143)
		(layer "In13.Cu")
		(net "P5E_CPU0_P2_TX_DP<11>")
	)
	(arc
		(start 371.01526 -283.485336)
		(mid 371.199993 -283.806028)
		(end 371.015514 -284.12694)
		(width 0.1143)
		(layer "In13.Cu")
		(net "P5E_CPU0_P2_TX_DP<11>")
	)
	(arc
		(start 370.972842 -284.151578)
		(mid 370.729515 -284.616144)
		(end 370.972842 -285.08071)
		(width 0.1143)
		(layer "In13.Cu")
		(net "P5E_CPU0_P2_TX_DP<11>")
	)
	(arc
		(start 370.735606 -273.358864)
		(mid 370.737394 -273.370313)
		(end 370.739416 -273.381724)
		(width 0.1143)
		(layer "In13.Cu")
		(net "P5E_CPU0_P2_TX_DP<11>")
	)
	(arc
		(start 371.01526 -288.345118)
		(mid 371.199993 -288.66581)
		(end 371.015514 -288.986722)
		(width 0.1143)
		(layer "In13.Cu")
		(net "P5E_CPU0_P2_TX_DP<11>")
	)
	(arc
		(start 370.972842 -276.051518)
		(mid 370.729515 -276.516084)
		(end 370.972842 -276.98065)
		(width 0.1143)
		(layer "In13.Cu")
		(net "P5E_CPU0_P2_TX_DP<11>")
	)
	(arc
		(start 371.01526 -285.105348)
		(mid 371.199993 -285.42604)
		(end 371.015514 -285.746952)
		(width 0.1143)
		(layer "In13.Cu")
		(net "P5E_CPU0_P2_TX_DP<11>")
	)
	(arc
		(start 370.972842 -285.77159)
		(mid 370.729515 -286.236156)
		(end 370.972842 -286.700722)
		(width 0.1143)
		(layer "In13.Cu")
		(net "P5E_CPU0_P2_TX_DP<11>")
	)
	(arc
		(start 370.972842 -282.531566)
		(mid 370.729515 -282.996132)
		(end 370.972842 -283.460698)
		(width 0.1143)
		(layer "In13.Cu")
		(net "P5E_CPU0_P2_TX_DP<11>")
	)
	(arc
		(start 371.199664 -287.05048)
		(mid 371.159409 -287.217293)
		(end 371.047518 -287.347406)
		(width 0.1143)
		(layer "In13.Cu")
		(net "P5E_CPU0_P2_TX_DP<11>")
	)
	(arc
		(start 370.975382 -287.389824)
		(mid 370.729494 -287.854618)
		(end 370.972842 -288.320734)
		(width 0.1143)
		(layer "In13.Cu")
		(net "P5E_CPU0_P2_TX_DP<11>")
	)
	(arc
		(start 371.01526 -281.865324)
		(mid 371.199993 -282.186016)
		(end 371.015514 -282.506928)
		(width 0.1143)
		(layer "In13.Cu")
		(net "P5E_CPU0_P2_TX_DP<11>")
	)
	(segment
		(start 369.888008 -269.770098)
		(end 370.35486 -270.036036)
		(width 0.12954)
		(layer "F.Cu")
		(net "P5E_CPU0_P2_TX_DP<10>")
	)
	(segment
		(start 417.63315 -382.61544)
		(end 417.63315 -383.31902)
		(width 0.12954)
		(layer "F.Cu")
		(net "P5E_CPU0_P2_TX_DP<10>")
	)
	(segment
		(start 417.63315 -383.31902)
		(end 417.33724 -383.61493)
		(width 0.12954)
		(layer "F.Cu")
		(net "P5E_CPU0_P2_TX_DP<10>")
	)
	(segment
		(start 417.36264 -382.34493)
		(end 417.63315 -382.61544)
		(width 0.12954)
		(layer "F.Cu")
		(net "P5E_CPU0_P2_TX_DP<10>")
	)
	(segment
		(start 370.065046 -285.752794)
		(end 370.064284 -285.753302)
		(width 0.1143)
		(layer "In13.Cu")
		(net "P5E_CPU0_P2_TX_DP<10>")
	)
	(segment
		(start 370.082318 -289.969194)
		(end 370.103654 -289.98164)
		(width 0.1143)
		(layer "In13.Cu")
		(net "P5E_CPU0_P2_TX_DP<10>")
	)
	(segment
		(start 370.032788 -286.700722)
		(end 370.105432 -286.74314)
		(width 0.1143)
		(layer "In13.Cu")
		(net "P5E_CPU0_P2_TX_DP<10>")
	)
	(segment
		(start 370.103654 -290.590224)
		(end 370.073936 -290.607242)
		(width 0.1143)
		(layer "In13.Cu")
		(net "P5E_CPU0_P2_TX_DP<10>")
	)
	(segment
		(start 370.032788 -278.600662)
		(end 370.102384 -278.641302)
		(width 0.1143)
		(layer "In13.Cu")
		(net "P5E_CPU0_P2_TX_DP<10>")
	)
	(segment
		(start 370.07546 -289.965384)
		(end 370.07673 -289.966146)
		(width 0.1143)
		(layer "In13.Cu")
		(net "P5E_CPU0_P2_TX_DP<10>")
	)
	(segment
		(start 370.064284 -288.993072)
		(end 370.032788 -289.01136)
		(width 0.1143)
		(layer "In13.Cu")
		(net "P5E_CPU0_P2_TX_DP<10>")
	)
	(segment
		(start 370.071904 -289.963352)
		(end 370.072666 -289.96386)
		(width 0.1143)
		(layer "In13.Cu")
		(net "P5E_CPU0_P2_TX_DP<10>")
	)
	(segment
		(start 370.714778 -298.256706)
		(end 370.715286 -298.256706)
		(width 0.14224)
		(layer "In13.Cu")
		(net "P5E_CPU0_P2_TX_DP<10>")
	)
	(segment
		(start 370.573554 -270.340328)
		(end 370.541042 -270.35887)
		(width 0.1143)
		(layer "In13.Cu")
		(net "P5E_CPU0_P2_TX_DP<10>")
	)
	(segment
		(start 417.65347 -382.0541)
		(end 417.36264 -382.34493)
		(width 0.14224)
		(layer "In13.Cu")
		(net "P5E_CPU0_P2_TX_DP<10>")
	)
	(segment
		(start 370.078508 -294.827198)
		(end 370.079778 -294.82796)
		(width 0.1143)
		(layer "In13.Cu")
		(net "P5E_CPU0_P2_TX_DP<10>")
	)
	(segment
		(start 370.546122 -295.635934)
		(end 370.547646 -295.636696)
		(width 0.1143)
		(layer "In13.Cu")
		(net "P5E_CPU0_P2_TX_DP<10>")
	)
	(segment
		(start 370.068348 -292.230556)
		(end 370.067586 -292.231064)
		(width 0.1143)
		(layer "In13.Cu")
		(net "P5E_CPU0_P2_TX_DP<10>")
	)
	(segment
		(start 370.072666 -292.228016)
		(end 370.071904 -292.228524)
		(width 0.1143)
		(layer "In13.Cu")
		(net "P5E_CPU0_P2_TX_DP<10>")
	)
	(segment
		(start 370.534438 -270.362934)
		(end 370.528596 -270.366236)
		(width 0.1143)
		(layer "In13.Cu")
		(net "P5E_CPU0_P2_TX_DP<10>")
	)
	(segment
		(start 370.072666 -288.987992)
		(end 370.071904 -288.9885)
		(width 0.1143)
		(layer "In13.Cu")
		(net "P5E_CPU0_P2_TX_DP<10>")
	)
	(segment
		(start 370.078508 -289.967162)
		(end 370.079778 -289.967924)
		(width 0.1143)
		(layer "In13.Cu")
		(net "P5E_CPU0_P2_TX_DP<10>")
	)
	(segment
		(start 370.065046 -292.232588)
		(end 370.064284 -292.233096)
		(width 0.1143)
		(layer "In13.Cu")
		(net "P5E_CPU0_P2_TX_DP<10>")
	)
	(segment
		(start 370.103654 -284.11043)
		(end 370.073936 -284.127448)
		(width 0.1143)
		(layer "In13.Cu")
		(net "P5E_CPU0_P2_TX_DP<10>")
	)
	(segment
		(start 370.072666 -281.864054)
		(end 370.073936 -281.864816)
		(width 0.1143)
		(layer "In13.Cu")
		(net "P5E_CPU0_P2_TX_DP<10>")
	)
	(segment
		(start 397.140684 -362.025946)
		(end 401.795488 -368.991642)
		(width 0.14224)
		(layer "In13.Cu")
		(net "P5E_CPU0_P2_TX_DP<10>")
	)
	(segment
		(start 370.082318 -281.869388)
		(end 370.103654 -281.881834)
		(width 0.1143)
		(layer "In13.Cu")
		(net "P5E_CPU0_P2_TX_DP<10>")
	)
	(segment
		(start 370.032788 -294.800528)
		(end 370.069364 -294.821864)
		(width 0.1143)
		(layer "In13.Cu")
		(net "P5E_CPU0_P2_TX_DP<10>")
	)
	(segment
		(start 370.071904 -293.203376)
		(end 370.072666 -293.203884)
		(width 0.1143)
		(layer "In13.Cu")
		(net "P5E_CPU0_P2_TX_DP<10>")
	)
	(segment
		(start 370.547646 -295.636696)
		(end 370.548408 -295.637204)
		(width 0.1143)
		(layer "In13.Cu")
		(net "P5E_CPU0_P2_TX_DP<10>")
	)
	(segment
		(start 370.072666 -285.748222)
		(end 370.071904 -285.74873)
		(width 0.1143)
		(layer "In13.Cu")
		(net "P5E_CPU0_P2_TX_DP<10>")
	)
	(segment
		(start 370.079778 -289.967924)
		(end 370.082318 -289.969194)
		(width 0.1143)
		(layer "In13.Cu")
		(net "P5E_CPU0_P2_TX_DP<10>")
	)
	(segment
		(start 370.077492 -281.866848)
		(end 370.078508 -281.867356)
		(width 0.1143)
		(layer "In13.Cu")
		(net "P5E_CPU0_P2_TX_DP<10>")
	)
	(segment
		(start 370.542566 -295.633902)
		(end 370.54536 -295.635426)
		(width 0.1143)
		(layer "In13.Cu")
		(net "P5E_CPU0_P2_TX_DP<10>")
	)
	(segment
		(start 370.07673 -281.86634)
		(end 370.077492 -281.866848)
		(width 0.1143)
		(layer "In13.Cu")
		(net "P5E_CPU0_P2_TX_DP<10>")
	)
	(segment
		(start 370.071904 -290.608512)
		(end 370.070888 -290.60902)
		(width 0.1143)
		(layer "In13.Cu")
		(net "P5E_CPU0_P2_TX_DP<10>")
	)
	(segment
		(start 370.069364 -284.130242)
		(end 370.068348 -284.13075)
		(width 0.1143)
		(layer "In13.Cu")
		(net "P5E_CPU0_P2_TX_DP<10>")
	)
	(segment
		(start 370.068348 -285.750762)
		(end 370.067586 -285.75127)
		(width 0.1143)
		(layer "In13.Cu")
		(net "P5E_CPU0_P2_TX_DP<10>")
	)
	(segment
		(start 370.078508 -293.207186)
		(end 370.079778 -293.207948)
		(width 0.1143)
		(layer "In13.Cu")
		(net "P5E_CPU0_P2_TX_DP<10>")
	)
	(segment
		(start 370.069364 -289.961828)
		(end 370.070888 -289.962844)
		(width 0.1143)
		(layer "In13.Cu")
		(net "P5E_CPU0_P2_TX_DP<10>")
	)
	(segment
		(start 370.071904 -288.9885)
		(end 370.070888 -288.989008)
		(width 0.1143)
		(layer "In13.Cu")
		(net "P5E_CPU0_P2_TX_DP<10>")
	)
	(segment
		(start 370.684044 -296.463466)
		(end 370.684044 -296.491914)
		(width 0.1143)
		(layer "In13.Cu")
		(net "P5E_CPU0_P2_TX_DP<10>")
	)
	(segment
		(start 370.064284 -292.233096)
		(end 370.032788 -292.251384)
		(width 0.1143)
		(layer "In13.Cu")
		(net "P5E_CPU0_P2_TX_DP<10>")
	)
	(segment
		(start 370.069364 -288.990024)
		(end 370.068348 -288.990532)
		(width 0.1143)
		(layer "In13.Cu")
		(net "P5E_CPU0_P2_TX_DP<10>")
	)
	(segment
		(start 370.077492 -294.82669)
		(end 370.078508 -294.827198)
		(width 0.1143)
		(layer "In13.Cu")
		(net "P5E_CPU0_P2_TX_DP<10>")
	)
	(segment
		(start 370.073936 -282.507436)
		(end 370.072666 -282.508198)
		(width 0.1143)
		(layer "In13.Cu")
		(net "P5E_CPU0_P2_TX_DP<10>")
	)
	(segment
		(start 370.064284 -284.13329)
		(end 370.032788 -284.151578)
		(width 0.1143)
		(layer "In13.Cu")
		(net "P5E_CPU0_P2_TX_DP<10>")
	)
	(segment
		(start 370.07673 -289.966146)
		(end 370.077492 -289.966654)
		(width 0.1143)
		(layer "In13.Cu")
		(net "P5E_CPU0_P2_TX_DP<10>")
	)
	(segment
		(start 370.071904 -281.863546)
		(end 370.072666 -281.864054)
		(width 0.1143)
		(layer "In13.Cu")
		(net "P5E_CPU0_P2_TX_DP<10>")
	)
	(segment
		(start 370.073936 -289.964622)
		(end 370.07546 -289.965384)
		(width 0.1143)
		(layer "In13.Cu")
		(net "P5E_CPU0_P2_TX_DP<10>")
	)
	(segment
		(start 370.032788 -283.460698)
		(end 370.103654 -283.501846)
		(width 0.1143)
		(layer "In13.Cu")
		(net "P5E_CPU0_P2_TX_DP<10>")
	)
	(segment
		(start 370.078508 -281.867356)
		(end 370.079778 -281.868118)
		(width 0.1143)
		(layer "In13.Cu")
		(net "P5E_CPU0_P2_TX_DP<10>")
	)
	(segment
		(start 370.032788 -281.840686)
		(end 370.069364 -281.862022)
		(width 0.1143)
		(layer "In13.Cu")
		(net "P5E_CPU0_P2_TX_DP<10>")
	)
	(segment
		(start 370.103654 -285.730442)
		(end 370.073936 -285.74746)
		(width 0.1143)
		(layer "In13.Cu")
		(net "P5E_CPU0_P2_TX_DP<10>")
	)
	(segment
		(start 370.082318 -293.209218)
		(end 370.103654 -293.221664)
		(width 0.1143)
		(layer "In13.Cu")
		(net "P5E_CPU0_P2_TX_DP<10>")
	)
	(segment
		(start 370.073936 -290.607242)
		(end 370.072666 -290.608004)
		(width 0.1143)
		(layer "In13.Cu")
		(net "P5E_CPU0_P2_TX_DP<10>")
	)
	(segment
		(start 370.103654 -293.830248)
		(end 370.032788 -293.871396)
		(width 0.1143)
		(layer "In13.Cu")
		(net "P5E_CPU0_P2_TX_DP<10>")
	)
	(segment
		(start 370.073936 -288.98723)
		(end 370.072666 -288.987992)
		(width 0.1143)
		(layer "In13.Cu")
		(net "P5E_CPU0_P2_TX_DP<10>")
	)
	(segment
		(start 370.073936 -285.74746)
		(end 370.072666 -285.748222)
		(width 0.1143)
		(layer "In13.Cu")
		(net "P5E_CPU0_P2_TX_DP<10>")
	)
	(segment
		(start 370.07673 -293.20617)
		(end 370.077492 -293.206678)
		(width 0.1143)
		(layer "In13.Cu")
		(net "P5E_CPU0_P2_TX_DP<10>")
	)
	(segment
		(start 370.032788 -276.98065)
		(end 370.102384 -277.02129)
		(width 0.1143)
		(layer "In13.Cu")
		(net "P5E_CPU0_P2_TX_DP<10>")
	)
	(segment
		(start 370.073936 -284.127448)
		(end 370.072666 -284.12821)
		(width 0.1143)
		(layer "In13.Cu")
		(net "P5E_CPU0_P2_TX_DP<10>")
	)
	(segment
		(start 370.729764 -296.417746)
		(end 370.684044 -296.463466)
		(width 0.1143)
		(layer "In13.Cu")
		(net "P5E_CPU0_P2_TX_DP<10>")
	)
	(segment
		(start 370.067586 -290.611052)
		(end 370.065046 -290.612576)
		(width 0.1143)
		(layer "In13.Cu")
		(net "P5E_CPU0_P2_TX_DP<10>")
	)
	(segment
		(start 370.102384 -277.63089)
		(end 370.032788 -277.67153)
		(width 0.1143)
		(layer "In13.Cu")
		(net "P5E_CPU0_P2_TX_DP<10>")
	)
	(segment
		(start 370.032788 -275.360638)
		(end 370.102384 -275.401278)
		(width 0.1143)
		(layer "In13.Cu")
		(net "P5E_CPU0_P2_TX_DP<10>")
	)
	(segment
		(start 370.070888 -285.749238)
		(end 370.069364 -285.750254)
		(width 0.1143)
		(layer "In13.Cu")
		(net "P5E_CPU0_P2_TX_DP<10>")
	)
	(segment
		(start 370.103654 -288.970212)
		(end 370.073936 -288.98723)
		(width 0.1143)
		(layer "In13.Cu")
		(net "P5E_CPU0_P2_TX_DP<10>")
	)
	(segment
		(start 370.068348 -282.510738)
		(end 370.067586 -282.511246)
		(width 0.1143)
		(layer "In13.Cu")
		(net "P5E_CPU0_P2_TX_DP<10>")
	)
	(segment
		(start 370.729764 -295.95572)
		(end 370.729764 -296.417746)
		(width 0.1143)
		(layer "In13.Cu")
		(net "P5E_CPU0_P2_TX_DP<10>")
	)
	(segment
		(start 402.02612 -369.222274)
		(end 404.78964 -371.069362)
		(width 0.14224)
		(layer "In13.Cu")
		(net "P5E_CPU0_P2_TX_DP<10>")
	)
	(segment
		(start 370.071904 -282.508706)
		(end 370.070888 -282.509214)
		(width 0.1143)
		(layer "In13.Cu")
		(net "P5E_CPU0_P2_TX_DP<10>")
	)
	(segment
		(start 370.069364 -282.51023)
		(end 370.068348 -282.510738)
		(width 0.1143)
		(layer "In13.Cu")
		(net "P5E_CPU0_P2_TX_DP<10>")
	)
	(segment
		(start 370.069364 -281.862022)
		(end 370.070888 -281.863038)
		(width 0.1143)
		(layer "In13.Cu")
		(net "P5E_CPU0_P2_TX_DP<10>")
	)
	(segment
		(start 370.073936 -292.227254)
		(end 370.072666 -292.228016)
		(width 0.1143)
		(layer "In13.Cu")
		(net "P5E_CPU0_P2_TX_DP<10>")
	)
	(segment
		(start 370.073936 -294.824658)
		(end 370.07546 -294.82542)
		(width 0.1143)
		(layer "In13.Cu")
		(net "P5E_CPU0_P2_TX_DP<10>")
	)
	(segment
		(start 370.069364 -294.821864)
		(end 370.070888 -294.82288)
		(width 0.1143)
		(layer "In13.Cu")
		(net "P5E_CPU0_P2_TX_DP<10>")
	)
	(segment
		(start 370.07546 -293.205408)
		(end 370.07673 -293.20617)
		(width 0.1143)
		(layer "In13.Cu")
		(net "P5E_CPU0_P2_TX_DP<10>")
	)
	(segment
		(start 370.032788 -293.180516)
		(end 370.069364 -293.201852)
		(width 0.1143)
		(layer "In13.Cu")
		(net "P5E_CPU0_P2_TX_DP<10>")
	)
	(segment
		(start 370.652802 -270.036036)
		(end 370.722652 -270.105886)
		(width 0.1143)
		(layer "In13.Cu")
		(net "P5E_CPU0_P2_TX_DP<10>")
	)
	(segment
		(start 370.07546 -294.82542)
		(end 370.07673 -294.826182)
		(width 0.1143)
		(layer "In13.Cu")
		(net "P5E_CPU0_P2_TX_DP<10>")
	)
	(segment
		(start 370.552218 -295.639236)
		(end 370.573554 -295.651682)
		(width 0.1143)
		(layer "In13.Cu")
		(net "P5E_CPU0_P2_TX_DP<10>")
	)
	(segment
		(start 370.082318 -294.82923)
		(end 370.103654 -294.841676)
		(width 0.1143)
		(layer "In13.Cu")
		(net "P5E_CPU0_P2_TX_DP<10>")
	)
	(segment
		(start 370.070888 -289.962844)
		(end 370.071904 -289.963352)
		(width 0.1143)
		(layer "In13.Cu")
		(net "P5E_CPU0_P2_TX_DP<10>")
	)
	(segment
		(start 370.102384 -280.870914)
		(end 370.033296 -280.9113)
		(width 0.1143)
		(layer "In13.Cu")
		(net "P5E_CPU0_P2_TX_DP<10>")
	)
	(segment
		(start 370.033296 -280.9113)
		(end 370.032788 -280.911554)
		(width 0.1143)
		(layer "In13.Cu")
		(net "P5E_CPU0_P2_TX_DP<10>")
	)
	(segment
		(start 370.067586 -292.231064)
		(end 370.065046 -292.232588)
		(width 0.1143)
		(layer "In13.Cu")
		(net "P5E_CPU0_P2_TX_DP<10>")
	)
	(segment
		(start 370.070888 -293.202868)
		(end 370.071904 -293.203376)
		(width 0.1143)
		(layer "In13.Cu")
		(net "P5E_CPU0_P2_TX_DP<10>")
	)
	(segment
		(start 417.35248 -378.865638)
		(end 417.616132 -379.12929)
		(width 0.14224)
		(layer "In13.Cu")
		(net "P5E_CPU0_P2_TX_DP<10>")
	)
	(segment
		(start 370.072666 -293.203884)
		(end 370.073936 -293.204646)
		(width 0.1143)
		(layer "In13.Cu")
		(net "P5E_CPU0_P2_TX_DP<10>")
	)
	(segment
		(start 370.5352 -270.362426)
		(end 370.534438 -270.362934)
		(width 0.1143)
		(layer "In13.Cu")
		(net "P5E_CPU0_P2_TX_DP<10>")
	)
	(segment
		(start 370.067586 -282.511246)
		(end 370.065046 -282.51277)
		(width 0.1143)
		(layer "In13.Cu")
		(net "P5E_CPU0_P2_TX_DP<10>")
	)
	(segment
		(start 370.070888 -284.129226)
		(end 370.069364 -284.130242)
		(width 0.1143)
		(layer "In13.Cu")
		(net "P5E_CPU0_P2_TX_DP<10>")
	)
	(segment
		(start 370.103654 -287.3502)
		(end 370.035328 -287.389824)
		(width 0.1143)
		(layer "In13.Cu")
		(net "P5E_CPU0_P2_TX_DP<10>")
	)
	(segment
		(start 370.072666 -282.508198)
		(end 370.071904 -282.508706)
		(width 0.1143)
		(layer "In13.Cu")
		(net "P5E_CPU0_P2_TX_DP<10>")
	)
	(segment
		(start 370.032788 -273.740626)
		(end 370.102384 -273.781266)
		(width 0.1143)
		(layer "In13.Cu")
		(net "P5E_CPU0_P2_TX_DP<10>")
	)
	(segment
		(start 370.548408 -295.637204)
		(end 370.549678 -295.637966)
		(width 0.1143)
		(layer "In13.Cu")
		(net "P5E_CPU0_P2_TX_DP<10>")
	)
	(segment
		(start 370.072666 -294.823896)
		(end 370.073936 -294.824658)
		(width 0.1143)
		(layer "In13.Cu")
		(net "P5E_CPU0_P2_TX_DP<10>")
	)
	(segment
		(start 370.069364 -292.230048)
		(end 370.068348 -292.230556)
		(width 0.1143)
		(layer "In13.Cu")
		(net "P5E_CPU0_P2_TX_DP<10>")
	)
	(segment
		(start 370.064284 -285.753302)
		(end 370.032788 -285.77159)
		(width 0.1143)
		(layer "In13.Cu")
		(net "P5E_CPU0_P2_TX_DP<10>")
	)
	(segment
		(start 370.07673 -294.826182)
		(end 370.077492 -294.82669)
		(width 0.1143)
		(layer "In13.Cu")
		(net "P5E_CPU0_P2_TX_DP<10>")
	)
	(segment
		(start 370.073936 -293.204646)
		(end 370.07546 -293.205408)
		(width 0.1143)
		(layer "In13.Cu")
		(net "P5E_CPU0_P2_TX_DP<10>")
	)
	(segment
		(start 370.069364 -293.201852)
		(end 370.070888 -293.202868)
		(width 0.1143)
		(layer "In13.Cu")
		(net "P5E_CPU0_P2_TX_DP<10>")
	)
	(segment
		(start 370.068348 -288.990532)
		(end 370.067586 -288.99104)
		(width 0.1143)
		(layer "In13.Cu")
		(net "P5E_CPU0_P2_TX_DP<10>")
	)
	(segment
		(start 370.070888 -294.82288)
		(end 370.071904 -294.823388)
		(width 0.1143)
		(layer "In13.Cu")
		(net "P5E_CPU0_P2_TX_DP<10>")
	)
	(segment
		(start 370.070888 -282.509214)
		(end 370.069364 -282.51023)
		(width 0.1143)
		(layer "In13.Cu")
		(net "P5E_CPU0_P2_TX_DP<10>")
	)
	(segment
		(start 370.071904 -292.228524)
		(end 370.070888 -292.229032)
		(width 0.1143)
		(layer "In13.Cu")
		(net "P5E_CPU0_P2_TX_DP<10>")
	)
	(segment
		(start 370.032788 -280.220674)
		(end 370.102384 -280.261314)
		(width 0.1143)
		(layer "In13.Cu")
		(net "P5E_CPU0_P2_TX_DP<10>")
	)
	(segment
		(start 370.070888 -290.60902)
		(end 370.069364 -290.610036)
		(width 0.1143)
		(layer "In13.Cu")
		(net "P5E_CPU0_P2_TX_DP<10>")
	)
	(segment
		(start 370.068348 -290.610544)
		(end 370.067586 -290.611052)
		(width 0.1143)
		(layer "In13.Cu")
		(net "P5E_CPU0_P2_TX_DP<10>")
	)
	(segment
		(start 370.072666 -289.96386)
		(end 370.073936 -289.964622)
		(width 0.1143)
		(layer "In13.Cu")
		(net "P5E_CPU0_P2_TX_DP<10>")
	)
	(segment
		(start 370.071904 -294.823388)
		(end 370.072666 -294.823896)
		(width 0.1143)
		(layer "In13.Cu")
		(net "P5E_CPU0_P2_TX_DP<10>")
	)
	(segment
		(start 370.065046 -284.132782)
		(end 370.064284 -284.13329)
		(width 0.1143)
		(layer "In13.Cu")
		(net "P5E_CPU0_P2_TX_DP<10>")
	)
	(segment
		(start 370.071904 -284.128718)
		(end 370.070888 -284.129226)
		(width 0.1143)
		(layer "In13.Cu")
		(net "P5E_CPU0_P2_TX_DP<10>")
	)
	(segment
		(start 370.079778 -294.82796)
		(end 370.082318 -294.82923)
		(width 0.1143)
		(layer "In13.Cu")
		(net "P5E_CPU0_P2_TX_DP<10>")
	)
	(segment
		(start 370.715286 -298.256706)
		(end 397.140684 -362.025946)
		(width 0.14224)
		(layer "In13.Cu")
		(net "P5E_CPU0_P2_TX_DP<10>")
	)
	(segment
		(start 370.684044 -296.491914)
		(end 370.684044 -298.10075)
		(width 0.14224)
		(layer "In13.Cu")
		(net "P5E_CPU0_P2_TX_DP<10>")
	)
	(segment
		(start 370.541042 -270.35887)
		(end 370.5352 -270.362426)
		(width 0.1143)
		(layer "In13.Cu")
		(net "P5E_CPU0_P2_TX_DP<10>")
	)
	(segment
		(start 370.065046 -282.51277)
		(end 370.064284 -282.513278)
		(width 0.1143)
		(layer "In13.Cu")
		(net "P5E_CPU0_P2_TX_DP<10>")
	)
	(segment
		(start 370.077492 -289.966654)
		(end 370.078508 -289.967162)
		(width 0.1143)
		(layer "In13.Cu")
		(net "P5E_CPU0_P2_TX_DP<10>")
	)
	(segment
		(start 370.070888 -288.989008)
		(end 370.069364 -288.990024)
		(width 0.1143)
		(layer "In13.Cu")
		(net "P5E_CPU0_P2_TX_DP<10>")
	)
	(segment
		(start 370.072666 -284.12821)
		(end 370.071904 -284.128718)
		(width 0.1143)
		(layer "In13.Cu")
		(net "P5E_CPU0_P2_TX_DP<10>")
	)
	(segment
		(start 370.071904 -285.74873)
		(end 370.070888 -285.749238)
		(width 0.1143)
		(layer "In13.Cu")
		(net "P5E_CPU0_P2_TX_DP<10>")
	)
	(segment
		(start 370.065046 -290.612576)
		(end 370.064284 -290.613084)
		(width 0.1143)
		(layer "In13.Cu")
		(net "P5E_CPU0_P2_TX_DP<10>")
	)
	(segment
		(start 404.78964 -371.069362)
		(end 415.043112 -375.31675)
		(width 0.14224)
		(layer "In13.Cu")
		(net "P5E_CPU0_P2_TX_DP<10>")
	)
	(segment
		(start 370.541804 -295.633394)
		(end 370.542566 -295.633902)
		(width 0.1143)
		(layer "In13.Cu")
		(net "P5E_CPU0_P2_TX_DP<10>")
	)
	(segment
		(start 370.079778 -281.868118)
		(end 370.082318 -281.869388)
		(width 0.1143)
		(layer "In13.Cu")
		(net "P5E_CPU0_P2_TX_DP<10>")
	)
	(segment
		(start 370.032788 -288.320734)
		(end 370.105432 -288.363152)
		(width 0.1143)
		(layer "In13.Cu")
		(net "P5E_CPU0_P2_TX_DP<10>")
	)
	(segment
		(start 370.103654 -292.210236)
		(end 370.073936 -292.227254)
		(width 0.1143)
		(layer "In13.Cu")
		(net "P5E_CPU0_P2_TX_DP<10>")
	)
	(segment
		(start 370.032788 -272.120614)
		(end 370.102384 -272.161254)
		(width 0.1143)
		(layer "In13.Cu")
		(net "P5E_CPU0_P2_TX_DP<10>")
	)
	(segment
		(start 370.070888 -292.229032)
		(end 370.069364 -292.230048)
		(width 0.1143)
		(layer "In13.Cu")
		(net "P5E_CPU0_P2_TX_DP<10>")
	)
	(segment
		(start 370.032788 -285.08071)
		(end 370.103654 -285.121858)
		(width 0.1143)
		(layer "In13.Cu")
		(net "P5E_CPU0_P2_TX_DP<10>")
	)
	(segment
		(start 417.147502 -378.8283)
		(end 417.26231 -378.8283)
		(width 0.14224)
		(layer "In13.Cu")
		(net "P5E_CPU0_P2_TX_DP<10>")
	)
	(segment
		(start 370.072666 -290.608004)
		(end 370.071904 -290.608512)
		(width 0.1143)
		(layer "In13.Cu")
		(net "P5E_CPU0_P2_TX_DP<10>")
	)
	(segment
		(start 415.043112 -375.31675)
		(end 415.918396 -376.192034)
		(width 0.14224)
		(layer "In13.Cu")
		(net "P5E_CPU0_P2_TX_DP<10>")
	)
	(segment
		(start 370.064284 -290.613084)
		(end 370.032788 -290.631372)
		(width 0.1143)
		(layer "In13.Cu")
		(net "P5E_CPU0_P2_TX_DP<10>")
	)
	(segment
		(start 370.540788 -295.632886)
		(end 370.541804 -295.633394)
		(width 0.1143)
		(layer "In13.Cu")
		(net "P5E_CPU0_P2_TX_DP<10>")
	)
	(segment
		(start 370.549678 -295.637966)
		(end 370.552218 -295.639236)
		(width 0.1143)
		(layer "In13.Cu")
		(net "P5E_CPU0_P2_TX_DP<10>")
	)
	(segment
		(start 370.064284 -282.513278)
		(end 370.032788 -282.531566)
		(width 0.1143)
		(layer "In13.Cu")
		(net "P5E_CPU0_P2_TX_DP<10>")
	)
	(segment
		(start 370.102384 -274.390866)
		(end 370.032788 -274.431506)
		(width 0.1143)
		(layer "In13.Cu")
		(net "P5E_CPU0_P2_TX_DP<10>")
	)
	(segment
		(start 370.102384 -276.010878)
		(end 370.032788 -276.051518)
		(width 0.1143)
		(layer "In13.Cu")
		(net "P5E_CPU0_P2_TX_DP<10>")
	)
	(segment
		(start 370.065046 -288.992564)
		(end 370.064284 -288.993072)
		(width 0.1143)
		(layer "In13.Cu")
		(net "P5E_CPU0_P2_TX_DP<10>")
	)
	(segment
		(start 370.073936 -281.864816)
		(end 370.07546 -281.865578)
		(width 0.1143)
		(layer "In13.Cu")
		(net "P5E_CPU0_P2_TX_DP<10>")
	)
	(segment
		(start 370.069364 -285.750254)
		(end 370.068348 -285.750762)
		(width 0.1143)
		(layer "In13.Cu")
		(net "P5E_CPU0_P2_TX_DP<10>")
	)
	(segment
		(start 370.067586 -288.99104)
		(end 370.065046 -288.992564)
		(width 0.1143)
		(layer "In13.Cu")
		(net "P5E_CPU0_P2_TX_DP<10>")
	)
	(segment
		(start 370.070888 -281.863038)
		(end 370.071904 -281.863546)
		(width 0.1143)
		(layer "In13.Cu")
		(net "P5E_CPU0_P2_TX_DP<10>")
	)
	(segment
		(start 370.54536 -295.635426)
		(end 370.546122 -295.635934)
		(width 0.1143)
		(layer "In13.Cu")
		(net "P5E_CPU0_P2_TX_DP<10>")
	)
	(segment
		(start 370.067586 -284.131258)
		(end 370.065046 -284.132782)
		(width 0.1143)
		(layer "In13.Cu")
		(net "P5E_CPU0_P2_TX_DP<10>")
	)
	(segment
		(start 370.079778 -293.207948)
		(end 370.082318 -293.209218)
		(width 0.1143)
		(layer "In13.Cu")
		(net "P5E_CPU0_P2_TX_DP<10>")
	)
	(segment
		(start 370.032788 -291.560504)
		(end 370.103654 -291.601652)
		(width 0.1143)
		(layer "In13.Cu")
		(net "P5E_CPU0_P2_TX_DP<10>")
	)
	(segment
		(start 370.067586 -285.75127)
		(end 370.065046 -285.752794)
		(width 0.1143)
		(layer "In13.Cu")
		(net "P5E_CPU0_P2_TX_DP<10>")
	)
	(segment
		(start 370.502688 -295.610534)
		(end 370.540788 -295.632886)
		(width 0.1143)
		(layer "In13.Cu")
		(net "P5E_CPU0_P2_TX_DP<10>")
	)
	(segment
		(start 370.102384 -272.770854)
		(end 370.032788 -272.811494)
		(width 0.1143)
		(layer "In13.Cu")
		(net "P5E_CPU0_P2_TX_DP<10>")
	)
	(segment
		(start 370.528596 -270.366236)
		(end 370.502688 -270.381476)
		(width 0.1143)
		(layer "In13.Cu")
		(net "P5E_CPU0_P2_TX_DP<10>")
	)
	(segment
		(start 417.65347 -379.21946)
		(end 417.65347 -382.0541)
		(width 0.14224)
		(layer "In13.Cu")
		(net "P5E_CPU0_P2_TX_DP<10>")
	)
	(segment
		(start 370.102384 -271.150842)
		(end 370.032788 -271.191482)
		(width 0.1143)
		(layer "In13.Cu")
		(net "P5E_CPU0_P2_TX_DP<10>")
	)
	(segment
		(start 370.102384 -279.250902)
		(end 370.032788 -279.291542)
		(width 0.1143)
		(layer "In13.Cu")
		(net "P5E_CPU0_P2_TX_DP<10>")
	)
	(segment
		(start 370.032788 -289.940492)
		(end 370.069364 -289.961828)
		(width 0.1143)
		(layer "In13.Cu")
		(net "P5E_CPU0_P2_TX_DP<10>")
	)
	(segment
		(start 370.068348 -284.13075)
		(end 370.067586 -284.131258)
		(width 0.1143)
		(layer "In13.Cu")
		(net "P5E_CPU0_P2_TX_DP<10>")
	)
	(segment
		(start 370.069364 -290.610036)
		(end 370.068348 -290.610544)
		(width 0.1143)
		(layer "In13.Cu")
		(net "P5E_CPU0_P2_TX_DP<10>")
	)
	(segment
		(start 416.075622 -378.1933)
		(end 416.401504 -378.519182)
		(width 0.14224)
		(layer "In13.Cu")
		(net "P5E_CPU0_P2_TX_DP<10>")
	)
	(segment
		(start 370.35486 -270.036036)
		(end 370.652802 -270.036036)
		(width 0.1143)
		(layer "In13.Cu")
		(net "P5E_CPU0_P2_TX_DP<10>")
	)
	(segment
		(start 415.955734 -376.282204)
		(end 415.955734 -377.90374)
		(width 0.14224)
		(layer "In13.Cu")
		(net "P5E_CPU0_P2_TX_DP<10>")
	)
	(segment
		(start 370.07546 -281.865578)
		(end 370.07673 -281.86634)
		(width 0.1143)
		(layer "In13.Cu")
		(net "P5E_CPU0_P2_TX_DP<10>")
	)
	(segment
		(start 370.077492 -293.206678)
		(end 370.078508 -293.207186)
		(width 0.1143)
		(layer "In13.Cu")
		(net "P5E_CPU0_P2_TX_DP<10>")
	)
	(segment
		(start 370.25961 -295.145968)
		(end 370.259356 -295.145968)
		(width 0.1143)
		(layer "In13.Cu")
		(net "P5E_CPU0_P2_TX_DP<10>")
	)
	(segment
		(start 370.103654 -282.490418)
		(end 370.073936 -282.507436)
		(width 0.1143)
		(layer "In13.Cu")
		(net "P5E_CPU0_P2_TX_DP<10>")
	)
	(arc
		(start 370.032788 -276.051518)
		(mid 369.789461 -276.516084)
		(end 370.032788 -276.98065)
		(width 0.1143)
		(layer "In13.Cu")
		(net "P5E_CPU0_P2_TX_DP<10>")
	)
	(arc
		(start 370.259356 -270.846042)
		(mid 370.217807 -271.017464)
		(end 370.102384 -271.150842)
		(width 0.1143)
		(layer "In13.Cu")
		(net "P5E_CPU0_P2_TX_DP<10>")
	)
	(arc
		(start 370.032788 -272.811494)
		(mid 369.789461 -273.27606)
		(end 370.032788 -273.740626)
		(width 0.1143)
		(layer "In13.Cu")
		(net "P5E_CPU0_P2_TX_DP<10>")
	)
	(arc
		(start 370.102384 -280.261314)
		(mid 370.259361 -280.566114)
		(end 370.102384 -280.870914)
		(width 0.1143)
		(layer "In13.Cu")
		(net "P5E_CPU0_P2_TX_DP<10>")
	)
	(arc
		(start 370.641372 -295.714674)
		(mid 370.70686 -295.827386)
		(end 370.729764 -295.95572)
		(width 0.1143)
		(layer "In13.Cu")
		(net "P5E_CPU0_P2_TX_DP<10>")
	)
	(arc
		(start 370.259356 -295.145968)
		(mid 370.323871 -295.408187)
		(end 370.502688 -295.610534)
		(width 0.1143)
		(layer "In13.Cu")
		(net "P5E_CPU0_P2_TX_DP<10>")
	)
	(arc
		(start 370.102384 -278.641302)
		(mid 370.259361 -278.946102)
		(end 370.102384 -279.250902)
		(width 0.1143)
		(layer "In13.Cu")
		(net "P5E_CPU0_P2_TX_DP<10>")
	)
	(arc
		(start 370.105432 -288.363152)
		(mid 370.218839 -288.496041)
		(end 370.25961 -288.66592)
		(width 0.1143)
		(layer "In13.Cu")
		(net "P5E_CPU0_P2_TX_DP<10>")
	)
	(arc
		(start 370.102384 -272.161254)
		(mid 370.259361 -272.466054)
		(end 370.102384 -272.770854)
		(width 0.1143)
		(layer "In13.Cu")
		(net "P5E_CPU0_P2_TX_DP<10>")
	)
	(arc
		(start 370.103654 -291.601652)
		(mid 370.259582 -291.905944)
		(end 370.103654 -292.210236)
		(width 0.1143)
		(layer "In13.Cu")
		(net "P5E_CPU0_P2_TX_DP<10>")
	)
	(arc
		(start 370.035328 -287.389824)
		(mid 369.78944 -287.854618)
		(end 370.032788 -288.320734)
		(width 0.1143)
		(layer "In13.Cu")
		(net "P5E_CPU0_P2_TX_DP<10>")
	)
	(arc
		(start 370.102384 -277.02129)
		(mid 370.259361 -277.32609)
		(end 370.102384 -277.63089)
		(width 0.1143)
		(layer "In13.Cu")
		(net "P5E_CPU0_P2_TX_DP<10>")
	)
	(arc
		(start 370.25961 -287.045908)
		(mid 370.218355 -287.216879)
		(end 370.103654 -287.3502)
		(width 0.1143)
		(layer "In13.Cu")
		(net "P5E_CPU0_P2_TX_DP<10>")
	)
	(arc
		(start 370.684044 -298.10075)
		(mid 370.691782 -298.18023)
		(end 370.714778 -298.256706)
		(width 0.14224)
		(layer "In13.Cu")
		(net "P5E_CPU0_P2_TX_DP<10>")
	)
	(arc
		(start 370.032788 -293.871396)
		(mid 369.789461 -294.335962)
		(end 370.032788 -294.800528)
		(width 0.1143)
		(layer "In13.Cu")
		(net "P5E_CPU0_P2_TX_DP<10>")
	)
	(arc
		(start 417.616132 -379.12929)
		(mid 417.643775 -379.17066)
		(end 417.65347 -379.21946)
		(width 0.14224)
		(layer "In13.Cu")
		(net "P5E_CPU0_P2_TX_DP<10>")
	)
	(arc
		(start 370.103654 -293.221664)
		(mid 370.259582 -293.525956)
		(end 370.103654 -293.830248)
		(width 0.1143)
		(layer "In13.Cu")
		(net "P5E_CPU0_P2_TX_DP<10>")
	)
	(arc
		(start 370.103654 -285.121858)
		(mid 370.259582 -285.42615)
		(end 370.103654 -285.730442)
		(width 0.1143)
		(layer "In13.Cu")
		(net "P5E_CPU0_P2_TX_DP<10>")
	)
	(arc
		(start 370.032788 -271.191482)
		(mid 369.789461 -271.656048)
		(end 370.032788 -272.120614)
		(width 0.1143)
		(layer "In13.Cu")
		(net "P5E_CPU0_P2_TX_DP<10>")
	)
	(arc
		(start 415.955734 -377.90374)
		(mid 415.986886 -378.060443)
		(end 416.075622 -378.1933)
		(width 0.14224)
		(layer "In13.Cu")
		(net "P5E_CPU0_P2_TX_DP<10>")
	)
	(arc
		(start 370.103654 -283.501846)
		(mid 370.259582 -283.806138)
		(end 370.103654 -284.11043)
		(width 0.1143)
		(layer "In13.Cu")
		(net "P5E_CPU0_P2_TX_DP<10>")
	)
	(arc
		(start 370.502688 -270.381476)
		(mid 370.323875 -270.583826)
		(end 370.259356 -270.846042)
		(width 0.1143)
		(layer "In13.Cu")
		(net "P5E_CPU0_P2_TX_DP<10>")
	)
	(arc
		(start 370.032788 -285.77159)
		(mid 369.789461 -286.236156)
		(end 370.032788 -286.700722)
		(width 0.1143)
		(layer "In13.Cu")
		(net "P5E_CPU0_P2_TX_DP<10>")
	)
	(arc
		(start 401.795488 -368.991642)
		(mid 401.899454 -369.118308)
		(end 402.02612 -369.222274)
		(width 0.14224)
		(layer "In13.Cu")
		(net "P5E_CPU0_P2_TX_DP<10>")
	)
	(arc
		(start 370.032788 -290.631372)
		(mid 369.789461 -291.095938)
		(end 370.032788 -291.560504)
		(width 0.1143)
		(layer "In13.Cu")
		(net "P5E_CPU0_P2_TX_DP<10>")
	)
	(arc
		(start 370.25961 -288.66592)
		(mid 370.218355 -288.836891)
		(end 370.103654 -288.970212)
		(width 0.1143)
		(layer "In13.Cu")
		(net "P5E_CPU0_P2_TX_DP<10>")
	)
	(arc
		(start 370.103654 -294.841676)
		(mid 370.21833 -294.97501)
		(end 370.25961 -295.145968)
		(width 0.1143)
		(layer "In13.Cu")
		(net "P5E_CPU0_P2_TX_DP<10>")
	)
	(arc
		(start 370.032788 -279.291542)
		(mid 369.789461 -279.756108)
		(end 370.032788 -280.220674)
		(width 0.1143)
		(layer "In13.Cu")
		(net "P5E_CPU0_P2_TX_DP<10>")
	)
	(arc
		(start 370.573554 -295.651682)
		(mid 370.609417 -295.681074)
		(end 370.641372 -295.714674)
		(width 0.1143)
		(layer "In13.Cu")
		(net "P5E_CPU0_P2_TX_DP<10>")
	)
	(arc
		(start 370.102384 -273.781266)
		(mid 370.259361 -274.086066)
		(end 370.102384 -274.390866)
		(width 0.1143)
		(layer "In13.Cu")
		(net "P5E_CPU0_P2_TX_DP<10>")
	)
	(arc
		(start 370.102384 -275.401278)
		(mid 370.259361 -275.706078)
		(end 370.102384 -276.010878)
		(width 0.1143)
		(layer "In13.Cu")
		(net "P5E_CPU0_P2_TX_DP<10>")
	)
	(arc
		(start 417.26231 -378.8283)
		(mid 417.311105 -378.838006)
		(end 417.35248 -378.865638)
		(width 0.14224)
		(layer "In13.Cu")
		(net "P5E_CPU0_P2_TX_DP<10>")
	)
	(arc
		(start 370.103654 -289.98164)
		(mid 370.259582 -290.285932)
		(end 370.103654 -290.590224)
		(width 0.1143)
		(layer "In13.Cu")
		(net "P5E_CPU0_P2_TX_DP<10>")
	)
	(arc
		(start 370.103654 -281.881834)
		(mid 370.259582 -282.186126)
		(end 370.103654 -282.490418)
		(width 0.1143)
		(layer "In13.Cu")
		(net "P5E_CPU0_P2_TX_DP<10>")
	)
	(arc
		(start 370.722652 -270.105886)
		(mid 370.670603 -270.237405)
		(end 370.573554 -270.340328)
		(width 0.1143)
		(layer "In13.Cu")
		(net "P5E_CPU0_P2_TX_DP<10>")
	)
	(arc
		(start 416.401504 -378.519182)
		(mid 416.743756 -378.74796)
		(end 417.147502 -378.8283)
		(width 0.14224)
		(layer "In13.Cu")
		(net "P5E_CPU0_P2_TX_DP<10>")
	)
	(arc
		(start 370.032788 -280.911554)
		(mid 369.789461 -281.37612)
		(end 370.032788 -281.840686)
		(width 0.1143)
		(layer "In13.Cu")
		(net "P5E_CPU0_P2_TX_DP<10>")
	)
	(arc
		(start 370.032788 -277.67153)
		(mid 369.789461 -278.136096)
		(end 370.032788 -278.600662)
		(width 0.1143)
		(layer "In13.Cu")
		(net "P5E_CPU0_P2_TX_DP<10>")
	)
	(arc
		(start 370.032788 -282.531566)
		(mid 369.789461 -282.996132)
		(end 370.032788 -283.460698)
		(width 0.1143)
		(layer "In13.Cu")
		(net "P5E_CPU0_P2_TX_DP<10>")
	)
	(arc
		(start 370.032788 -284.151578)
		(mid 369.789461 -284.616144)
		(end 370.032788 -285.08071)
		(width 0.1143)
		(layer "In13.Cu")
		(net "P5E_CPU0_P2_TX_DP<10>")
	)
	(arc
		(start 415.918396 -376.192034)
		(mid 415.946039 -376.233404)
		(end 415.955734 -376.282204)
		(width 0.14224)
		(layer "In13.Cu")
		(net "P5E_CPU0_P2_TX_DP<10>")
	)
	(arc
		(start 370.032788 -292.251384)
		(mid 369.789461 -292.71595)
		(end 370.032788 -293.180516)
		(width 0.1143)
		(layer "In13.Cu")
		(net "P5E_CPU0_P2_TX_DP<10>")
	)
	(arc
		(start 370.105432 -286.74314)
		(mid 370.218839 -286.876029)
		(end 370.25961 -287.045908)
		(width 0.1143)
		(layer "In13.Cu")
		(net "P5E_CPU0_P2_TX_DP<10>")
	)
	(arc
		(start 370.032788 -274.431506)
		(mid 369.789461 -274.896072)
		(end 370.032788 -275.360638)
		(width 0.1143)
		(layer "In13.Cu")
		(net "P5E_CPU0_P2_TX_DP<10>")
	)
	(arc
		(start 370.032788 -289.01136)
		(mid 369.789461 -289.475926)
		(end 370.032788 -289.940492)
		(width 0.1143)
		(layer "In13.Cu")
		(net "P5E_CPU0_P2_TX_DP<10>")
	)
	(segment
		(start 398.032478 -390.48055)
		(end 398.328388 -390.77646)
		(width 0.12954)
		(layer "F.Cu")
		(net "P5E_CPU0_P2_TX_DP<0>")
	)
	(segment
		(start 397.058388 -390.75106)
		(end 397.328898 -390.48055)
		(width 0.12954)
		(layer "F.Cu")
		(net "P5E_CPU0_P2_TX_DP<0>")
	)
	(segment
		(start 397.328898 -390.48055)
		(end 398.032478 -390.48055)
		(width 0.12954)
		(layer "F.Cu")
		(net "P5E_CPU0_P2_TX_DP<0>")
	)
	(segment
		(start 361.89793 -268.960092)
		(end 362.364782 -269.22603)
		(width 0.12954)
		(layer "F.Cu")
		(net "P5E_CPU0_P2_TX_DP<0>")
	)
	(segment
		(start 361.188 -296.573702)
		(end 361.188 -300.900592)
		(width 0.14224)
		(layer "In13.Cu")
		(net "P5E_CPU0_P2_TX_DP<0>")
	)
	(segment
		(start 362.662724 -269.22603)
		(end 362.732574 -269.29588)
		(width 0.1143)
		(layer "In13.Cu")
		(net "P5E_CPU0_P2_TX_DP<0>")
	)
	(segment
		(start 361.642406 -271.150842)
		(end 361.575096 -271.190212)
		(width 0.1143)
		(layer "In13.Cu")
		(net "P5E_CPU0_P2_TX_DP<0>")
	)
	(segment
		(start 362.083858 -270.357346)
		(end 362.082588 -270.358108)
		(width 0.1143)
		(layer "In13.Cu")
		(net "P5E_CPU0_P2_TX_DP<0>")
	)
	(segment
		(start 362.364782 -269.22603)
		(end 362.662724 -269.22603)
		(width 0.1143)
		(layer "In13.Cu")
		(net "P5E_CPU0_P2_TX_DP<0>")
	)
	(segment
		(start 396.767558 -390.46023)
		(end 397.058388 -390.75106)
		(width 0.14224)
		(layer "In13.Cu")
		(net "P5E_CPU0_P2_TX_DP<0>")
	)
	(segment
		(start 362.552996 -269.547848)
		(end 362.550456 -269.549372)
		(width 0.1143)
		(layer "In13.Cu")
		(net "P5E_CPU0_P2_TX_DP<0>")
	)
	(segment
		(start 395.624812 -390.16813)
		(end 395.916912 -390.46023)
		(width 0.14224)
		(layer "In13.Cu")
		(net "P5E_CPU0_P2_TX_DP<0>")
	)
	(segment
		(start 360.66984 -295.2496)
		(end 360.66984 -296.055542)
		(width 0.14224)
		(layer "In13.Cu")
		(net "P5E_CPU0_P2_TX_DP<0>")
	)
	(segment
		(start 362.550456 -269.549372)
		(end 362.549694 -269.54988)
		(width 0.1143)
		(layer "In13.Cu")
		(net "P5E_CPU0_P2_TX_DP<0>")
	)
	(segment
		(start 395.916912 -390.46023)
		(end 396.767558 -390.46023)
		(width 0.14224)
		(layer "In13.Cu")
		(net "P5E_CPU0_P2_TX_DP<0>")
	)
	(segment
		(start 360.71556 -295.175432)
		(end 360.66984 -295.221152)
		(width 0.1143)
		(layer "In13.Cu")
		(net "P5E_CPU0_P2_TX_DP<0>")
	)
	(segment
		(start 395.624812 -377.206764)
		(end 395.624812 -390.16813)
		(width 0.14224)
		(layer "In13.Cu")
		(net "P5E_CPU0_P2_TX_DP<0>")
	)
	(segment
		(start 362.081826 -270.358616)
		(end 362.04271 -270.381476)
		(width 0.1143)
		(layer "In13.Cu")
		(net "P5E_CPU0_P2_TX_DP<0>")
	)
	(segment
		(start 360.71556 -273.100546)
		(end 360.71556 -295.175432)
		(width 0.1143)
		(layer "In13.Cu")
		(net "P5E_CPU0_P2_TX_DP<0>")
	)
	(segment
		(start 362.555282 -269.546578)
		(end 362.55452 -269.547086)
		(width 0.1143)
		(layer "In13.Cu")
		(net "P5E_CPU0_P2_TX_DP<0>")
	)
	(segment
		(start 361.237022 -301.147734)
		(end 389.122158 -368.446812)
		(width 0.14224)
		(layer "In13.Cu")
		(net "P5E_CPU0_P2_TX_DP<0>")
	)
	(segment
		(start 362.082588 -270.358108)
		(end 362.081826 -270.358616)
		(width 0.1143)
		(layer "In13.Cu")
		(net "P5E_CPU0_P2_TX_DP<0>")
	)
	(segment
		(start 360.66984 -296.055542)
		(end 361.188 -296.573702)
		(width 0.14224)
		(layer "In13.Cu")
		(net "P5E_CPU0_P2_TX_DP<0>")
	)
	(segment
		(start 389.122158 -368.446812)
		(end 393.03706 -374.302782)
		(width 0.14224)
		(layer "In13.Cu")
		(net "P5E_CPU0_P2_TX_DP<0>")
	)
	(segment
		(start 393.03706 -374.302782)
		(end 395.586712 -377.115578)
		(width 0.14224)
		(layer "In13.Cu")
		(net "P5E_CPU0_P2_TX_DP<0>")
	)
	(segment
		(start 362.583476 -269.530322)
		(end 362.555282 -269.546578)
		(width 0.1143)
		(layer "In13.Cu")
		(net "P5E_CPU0_P2_TX_DP<0>")
	)
	(segment
		(start 361.575096 -271.190212)
		(end 361.458256 -271.306798)
		(width 0.1143)
		(layer "In13.Cu")
		(net "P5E_CPU0_P2_TX_DP<0>")
	)
	(segment
		(start 362.55452 -269.547086)
		(end 362.552996 -269.547848)
		(width 0.1143)
		(layer "In13.Cu")
		(net "P5E_CPU0_P2_TX_DP<0>")
	)
	(segment
		(start 360.66984 -295.221152)
		(end 360.66984 -295.2496)
		(width 0.1143)
		(layer "In13.Cu")
		(net "P5E_CPU0_P2_TX_DP<0>")
	)
	(segment
		(start 395.586712 -377.115578)
		(end 395.589252 -377.118626)
		(width 0.14224)
		(layer "In13.Cu")
		(net "P5E_CPU0_P2_TX_DP<0>")
	)
	(arc
		(start 395.589252 -377.118626)
		(mid 395.615568 -377.159255)
		(end 395.624812 -377.206764)
		(width 0.14224)
		(layer "In13.Cu")
		(net "P5E_CPU0_P2_TX_DP<0>")
	)
	(arc
		(start 361.799378 -270.846042)
		(mid 361.757829 -271.017464)
		(end 361.642406 -271.150842)
		(width 0.1143)
		(layer "In13.Cu")
		(net "P5E_CPU0_P2_TX_DP<0>")
	)
	(arc
		(start 362.04271 -270.381476)
		(mid 361.863897 -270.583826)
		(end 361.799378 -270.846042)
		(width 0.1143)
		(layer "In13.Cu")
		(net "P5E_CPU0_P2_TX_DP<0>")
	)
	(arc
		(start 362.549694 -269.54988)
		(mid 362.343626 -269.756743)
		(end 362.268262 -270.03883)
		(width 0.1143)
		(layer "In13.Cu")
		(net "P5E_CPU0_P2_TX_DP<0>")
	)
	(arc
		(start 361.458256 -271.306798)
		(mid 360.908496 -272.129806)
		(end 360.71556 -273.100546)
		(width 0.1143)
		(layer "In13.Cu")
		(net "P5E_CPU0_P2_TX_DP<0>")
	)
	(arc
		(start 361.188 -300.900592)
		(mid 361.200359 -301.026571)
		(end 361.237022 -301.147734)
		(width 0.14224)
		(layer "In13.Cu")
		(net "P5E_CPU0_P2_TX_DP<0>")
	)
	(arc
		(start 362.732574 -269.29588)
		(mid 362.680525 -269.427399)
		(end 362.583476 -269.530322)
		(width 0.1143)
		(layer "In13.Cu")
		(net "P5E_CPU0_P2_TX_DP<0>")
	)
	(arc
		(start 362.268262 -270.03883)
		(mid 362.218835 -270.222853)
		(end 362.083858 -270.357346)
		(width 0.1143)
		(layer "In13.Cu")
		(net "P5E_CPU0_P2_TX_DP<0>")
	)
	(segment
		(start 368.0079 -271.39011)
		(end 368.474752 -271.656048)
		(width 0.12954)
		(layer "F.Cu")
		(net "P5E_CPU0_P2_TX_DN<9>")
	)
	(segment
		(start 414.55213 -377.68784)
		(end 414.55213 -378.39142)
		(width 0.12954)
		(layer "F.Cu")
		(net "P5E_CPU0_P2_TX_DN<9>")
	)
	(segment
		(start 414.82264 -377.41733)
		(end 414.55213 -377.68784)
		(width 0.12954)
		(layer "F.Cu")
		(net "P5E_CPU0_P2_TX_DN<9>")
	)
	(segment
		(start 414.55213 -378.39142)
		(end 414.84804 -378.68733)
		(width 0.12954)
		(layer "F.Cu")
		(net "P5E_CPU0_P2_TX_DN<9>")
	)
	(segment
		(start 369.2271 -277.814024)
		(end 369.22583 -277.814786)
		(width 0.1143)
		(layer "In13.Cu")
		(net "P5E_CPU0_P2_TX_DN<9>")
	)
	(segment
		(start 369.227862 -278.458676)
		(end 369.230656 -278.460454)
		(width 0.1143)
		(layer "In13.Cu")
		(net "P5E_CPU0_P2_TX_DN<9>")
	)
	(segment
		(start 369.229386 -279.432512)
		(end 369.2271 -279.434036)
		(width 0.1143)
		(layer "In13.Cu")
		(net "P5E_CPU0_P2_TX_DN<9>")
	)
	(segment
		(start 369.266724 -290.750498)
		(end 369.227608 -290.773358)
		(width 0.1143)
		(layer "In13.Cu")
		(net "P5E_CPU0_P2_TX_DN<9>")
	)
	(segment
		(start 368.256058 -271.96034)
		(end 368.287046 -271.97812)
		(width 0.1143)
		(layer "In13.Cu")
		(net "P5E_CPU0_P2_TX_DN<9>")
	)
	(segment
		(start 396.65783 -362.583984)
		(end 401.240244 -369.441984)
		(width 0.14224)
		(layer "In13.Cu")
		(net "P5E_CPU0_P2_TX_DN<9>")
	)
	(segment
		(start 369.22583 -277.814786)
		(end 369.196112 -277.831804)
		(width 0.1143)
		(layer "In13.Cu")
		(net "P5E_CPU0_P2_TX_DN<9>")
	)
	(segment
		(start 369.264184 -277.792434)
		(end 369.227862 -277.813516)
		(width 0.1143)
		(layer "In13.Cu")
		(net "P5E_CPU0_P2_TX_DN<9>")
	)
	(segment
		(start 369.266978 -281.030934)
		(end 369.198906 -281.07005)
		(width 0.1143)
		(layer "In13.Cu")
		(net "P5E_CPU0_P2_TX_DN<9>")
	)
	(segment
		(start 369.266724 -284.270704)
		(end 369.227608 -284.293564)
		(width 0.1143)
		(layer "In13.Cu")
		(net "P5E_CPU0_P2_TX_DN<9>")
	)
	(segment
		(start 369.196112 -278.440388)
		(end 369.2271 -278.458168)
		(width 0.1143)
		(layer "In13.Cu")
		(net "P5E_CPU0_P2_TX_DN<9>")
	)
	(segment
		(start 369.227862 -276.838664)
		(end 369.264184 -276.859746)
		(width 0.1143)
		(layer "In13.Cu")
		(net "P5E_CPU0_P2_TX_DN<9>")
	)
	(segment
		(start 368.757708 -272.788634)
		(end 368.796824 -272.811494)
		(width 0.1143)
		(layer "In13.Cu")
		(net "P5E_CPU0_P2_TX_DN<9>")
	)
	(segment
		(start 370.02593 -296.492422)
		(end 370.02593 -298.285154)
		(width 0.14224)
		(layer "In13.Cu")
		(net "P5E_CPU0_P2_TX_DN<9>")
	)
	(segment
		(start 369.227862 -273.59864)
		(end 369.264184 -273.619722)
		(width 0.1143)
		(layer "In13.Cu")
		(net "P5E_CPU0_P2_TX_DN<9>")
	)
	(segment
		(start 401.390612 -369.592352)
		(end 404.55215 -371.705378)
		(width 0.14224)
		(layer "In13.Cu")
		(net "P5E_CPU0_P2_TX_DN<9>")
	)
	(segment
		(start 369.294664 -279.390856)
		(end 369.266724 -279.410922)
		(width 0.1143)
		(layer "In13.Cu")
		(net "P5E_CPU0_P2_TX_DN<9>")
	)
	(segment
		(start 369.266724 -278.481282)
		(end 369.294664 -278.501348)
		(width 0.1143)
		(layer "In13.Cu")
		(net "P5E_CPU0_P2_TX_DN<9>")
	)
	(segment
		(start 368.474752 -271.656048)
		(end 368.17681 -271.656048)
		(width 0.1143)
		(layer "In13.Cu")
		(net "P5E_CPU0_P2_TX_DN<9>")
	)
	(segment
		(start 369.230656 -280.080466)
		(end 369.266724 -280.101294)
		(width 0.1143)
		(layer "In13.Cu")
		(net "P5E_CPU0_P2_TX_DN<9>")
	)
	(segment
		(start 369.197128 -284.920944)
		(end 369.227608 -284.938724)
		(width 0.1143)
		(layer "In13.Cu")
		(net "P5E_CPU0_P2_TX_DN<9>")
	)
	(segment
		(start 369.197128 -293.02075)
		(end 369.227608 -293.03853)
		(width 0.1143)
		(layer "In13.Cu")
		(net "P5E_CPU0_P2_TX_DN<9>")
	)
	(segment
		(start 368.287808 -271.978628)
		(end 368.288824 -271.979136)
		(width 0.1143)
		(layer "In13.Cu")
		(net "P5E_CPU0_P2_TX_DN<9>")
	)
	(segment
		(start 369.227608 -291.418518)
		(end 369.266724 -291.441378)
		(width 0.1143)
		(layer "In13.Cu")
		(net "P5E_CPU0_P2_TX_DN<9>")
	)
	(segment
		(start 414.08985 -375.730516)
		(end 414.53181 -376.391932)
		(width 0.14224)
		(layer "In13.Cu")
		(net "P5E_CPU0_P2_TX_DN<9>")
	)
	(segment
		(start 369.196112 -275.200364)
		(end 369.2271 -275.218144)
		(width 0.1143)
		(layer "In13.Cu")
		(net "P5E_CPU0_P2_TX_DN<9>")
	)
	(segment
		(start 369.227608 -293.03853)
		(end 369.266724 -293.06139)
		(width 0.1143)
		(layer "In13.Cu")
		(net "P5E_CPU0_P2_TX_DN<9>")
	)
	(segment
		(start 369.2271 -275.218144)
		(end 369.227862 -275.218652)
		(width 0.1143)
		(layer "In13.Cu")
		(net "P5E_CPU0_P2_TX_DN<9>")
	)
	(segment
		(start 370.02593 -296.463974)
		(end 370.02593 -296.492422)
		(width 0.1143)
		(layer "In13.Cu")
		(net "P5E_CPU0_P2_TX_DN<9>")
	)
	(segment
		(start 369.227862 -274.573492)
		(end 369.2271 -274.574)
		(width 0.1143)
		(layer "In13.Cu")
		(net "P5E_CPU0_P2_TX_DN<9>")
	)
	(segment
		(start 369.266724 -293.990522)
		(end 369.227608 -294.013382)
		(width 0.1143)
		(layer "In13.Cu")
		(net "P5E_CPU0_P2_TX_DN<9>")
	)
	(segment
		(start 369.195096 -288.159698)
		(end 369.227608 -288.178494)
		(width 0.1143)
		(layer "In13.Cu")
		(net "P5E_CPU0_P2_TX_DN<9>")
	)
	(segment
		(start 369.196112 -273.580352)
		(end 369.2271 -273.598132)
		(width 0.1143)
		(layer "In13.Cu")
		(net "P5E_CPU0_P2_TX_DN<9>")
	)
	(segment
		(start 369.22583 -276.194774)
		(end 369.196112 -276.211792)
		(width 0.1143)
		(layer "In13.Cu")
		(net "P5E_CPU0_P2_TX_DN<9>")
	)
	(segment
		(start 368.727228 -272.770854)
		(end 368.757708 -272.788634)
		(width 0.1143)
		(layer "In13.Cu")
		(net "P5E_CPU0_P2_TX_DN<9>")
	)
	(segment
		(start 369.2271 -278.458168)
		(end 369.227862 -278.458676)
		(width 0.1143)
		(layer "In13.Cu")
		(net "P5E_CPU0_P2_TX_DN<9>")
	)
	(segment
		(start 369.294664 -281.010868)
		(end 369.266978 -281.030934)
		(width 0.1143)
		(layer "In13.Cu")
		(net "P5E_CPU0_P2_TX_DN<9>")
	)
	(segment
		(start 369.227608 -285.913576)
		(end 369.197128 -285.931356)
		(width 0.1143)
		(layer "In13.Cu")
		(net "P5E_CPU0_P2_TX_DN<9>")
	)
	(segment
		(start 369.2271 -280.07818)
		(end 369.227862 -280.078688)
		(width 0.1143)
		(layer "In13.Cu")
		(net "P5E_CPU0_P2_TX_DN<9>")
	)
	(segment
		(start 369.264184 -276.172422)
		(end 369.227862 -276.193504)
		(width 0.1143)
		(layer "In13.Cu")
		(net "P5E_CPU0_P2_TX_DN<9>")
	)
	(segment
		(start 369.227608 -286.558482)
		(end 369.266724 -286.581342)
		(width 0.1143)
		(layer "In13.Cu")
		(net "P5E_CPU0_P2_TX_DN<9>")
	)
	(segment
		(start 369.667536 -295.451022)
		(end 369.736878 -295.491408)
		(width 0.1143)
		(layer "In13.Cu")
		(net "P5E_CPU0_P2_TX_DN<9>")
	)
	(segment
		(start 369.227862 -277.813516)
		(end 369.2271 -277.814024)
		(width 0.1143)
		(layer "In13.Cu")
		(net "P5E_CPU0_P2_TX_DN<9>")
	)
	(segment
		(start 368.17681 -271.656048)
		(end 368.10696 -271.725898)
		(width 0.1143)
		(layer "In13.Cu")
		(net "P5E_CPU0_P2_TX_DN<9>")
	)
	(segment
		(start 369.22583 -279.434798)
		(end 369.196112 -279.451816)
		(width 0.1143)
		(layer "In13.Cu")
		(net "P5E_CPU0_P2_TX_DN<9>")
	)
	(segment
		(start 369.227608 -292.39337)
		(end 369.197128 -292.41115)
		(width 0.1143)
		(layer "In13.Cu")
		(net "P5E_CPU0_P2_TX_DN<9>")
	)
	(segment
		(start 369.98021 -295.952164)
		(end 369.98021 -296.418254)
		(width 0.1143)
		(layer "In13.Cu")
		(net "P5E_CPU0_P2_TX_DN<9>")
	)
	(segment
		(start 369.2271 -273.598132)
		(end 369.227862 -273.59864)
		(width 0.1143)
		(layer "In13.Cu")
		(net "P5E_CPU0_P2_TX_DN<9>")
	)
	(segment
		(start 369.227608 -282.673552)
		(end 369.197128 -282.691332)
		(width 0.1143)
		(layer "In13.Cu")
		(net "P5E_CPU0_P2_TX_DN<9>")
	)
	(segment
		(start 369.227608 -281.6987)
		(end 369.266724 -281.72156)
		(width 0.1143)
		(layer "In13.Cu")
		(net "P5E_CPU0_P2_TX_DN<9>")
	)
	(segment
		(start 369.227862 -275.218652)
		(end 369.264184 -275.239734)
		(width 0.1143)
		(layer "In13.Cu")
		(net "P5E_CPU0_P2_TX_DN<9>")
	)
	(segment
		(start 369.227608 -294.658542)
		(end 369.266724 -294.681402)
		(width 0.1143)
		(layer "In13.Cu")
		(net "P5E_CPU0_P2_TX_DN<9>")
	)
	(segment
		(start 369.227862 -276.193504)
		(end 369.2271 -276.194012)
		(width 0.1143)
		(layer "In13.Cu")
		(net "P5E_CPU0_P2_TX_DN<9>")
	)
	(segment
		(start 369.227608 -290.773358)
		(end 369.197128 -290.791138)
		(width 0.1143)
		(layer "In13.Cu")
		(net "P5E_CPU0_P2_TX_DN<9>")
	)
	(segment
		(start 369.266724 -289.130486)
		(end 369.227608 -289.153346)
		(width 0.1143)
		(layer "In13.Cu")
		(net "P5E_CPU0_P2_TX_DN<9>")
	)
	(segment
		(start 369.196112 -280.0604)
		(end 369.2271 -280.07818)
		(width 0.1143)
		(layer "In13.Cu")
		(net "P5E_CPU0_P2_TX_DN<9>")
	)
	(segment
		(start 369.227608 -289.798506)
		(end 369.266724 -289.821366)
		(width 0.1143)
		(layer "In13.Cu")
		(net "P5E_CPU0_P2_TX_DN<9>")
	)
	(segment
		(start 369.2271 -276.838156)
		(end 369.227862 -276.838664)
		(width 0.1143)
		(layer "In13.Cu")
		(net "P5E_CPU0_P2_TX_DN<9>")
	)
	(segment
		(start 369.197128 -291.400738)
		(end 369.227608 -291.418518)
		(width 0.1143)
		(layer "In13.Cu")
		(net "P5E_CPU0_P2_TX_DN<9>")
	)
	(segment
		(start 368.291364 -271.98066)
		(end 368.293904 -271.982184)
		(width 0.1143)
		(layer "In13.Cu")
		(net "P5E_CPU0_P2_TX_DN<9>")
	)
	(segment
		(start 369.197128 -294.640762)
		(end 369.227608 -294.658542)
		(width 0.1143)
		(layer "In13.Cu")
		(net "P5E_CPU0_P2_TX_DN<9>")
	)
	(segment
		(start 368.293904 -271.982184)
		(end 368.295428 -271.9832)
		(width 0.1143)
		(layer "In13.Cu")
		(net "P5E_CPU0_P2_TX_DN<9>")
	)
	(segment
		(start 369.195096 -286.539686)
		(end 369.227608 -286.558482)
		(width 0.1143)
		(layer "In13.Cu")
		(net "P5E_CPU0_P2_TX_DN<9>")
	)
	(segment
		(start 404.55215 -371.705378)
		(end 413.906462 -375.579894)
		(width 0.14224)
		(layer "In13.Cu")
		(net "P5E_CPU0_P2_TX_DN<9>")
	)
	(segment
		(start 369.2271 -274.574)
		(end 369.22583 -274.574762)
		(width 0.1143)
		(layer "In13.Cu")
		(net "P5E_CPU0_P2_TX_DN<9>")
	)
	(segment
		(start 369.227608 -283.318712)
		(end 369.266724 -283.341572)
		(width 0.1143)
		(layer "In13.Cu")
		(net "P5E_CPU0_P2_TX_DN<9>")
	)
	(segment
		(start 369.266724 -292.37051)
		(end 369.227608 -292.39337)
		(width 0.1143)
		(layer "In13.Cu")
		(net "P5E_CPU0_P2_TX_DN<9>")
	)
	(segment
		(start 369.266724 -280.101294)
		(end 369.294664 -280.12136)
		(width 0.1143)
		(layer "In13.Cu")
		(net "P5E_CPU0_P2_TX_DN<9>")
	)
	(segment
		(start 369.264184 -287.512252)
		(end 369.197128 -287.551368)
		(width 0.1143)
		(layer "In13.Cu")
		(net "P5E_CPU0_P2_TX_DN<9>")
	)
	(segment
		(start 369.264184 -274.55241)
		(end 369.227862 -274.573492)
		(width 0.1143)
		(layer "In13.Cu")
		(net "P5E_CPU0_P2_TX_DN<9>")
	)
	(segment
		(start 369.266724 -279.410922)
		(end 369.229386 -279.432512)
		(width 0.1143)
		(layer "In13.Cu")
		(net "P5E_CPU0_P2_TX_DN<9>")
	)
	(segment
		(start 369.2271 -276.194012)
		(end 369.22583 -276.194774)
		(width 0.1143)
		(layer "In13.Cu")
		(net "P5E_CPU0_P2_TX_DN<9>")
	)
	(segment
		(start 368.290348 -271.980152)
		(end 368.291364 -271.98066)
		(width 0.1143)
		(layer "In13.Cu")
		(net "P5E_CPU0_P2_TX_DN<9>")
	)
	(segment
		(start 370.050568 -298.408344)
		(end 396.59814 -362.472478)
		(width 0.14224)
		(layer "In13.Cu")
		(net "P5E_CPU0_P2_TX_DN<9>")
	)
	(segment
		(start 369.198906 -281.07005)
		(end 369.197128 -281.07132)
		(width 0.1143)
		(layer "In13.Cu")
		(net "P5E_CPU0_P2_TX_DN<9>")
	)
	(segment
		(start 414.53181 -377.1265)
		(end 414.82264 -377.41733)
		(width 0.14224)
		(layer "In13.Cu")
		(net "P5E_CPU0_P2_TX_DN<9>")
	)
	(segment
		(start 369.266724 -282.650692)
		(end 369.227608 -282.673552)
		(width 0.1143)
		(layer "In13.Cu")
		(net "P5E_CPU0_P2_TX_DN<9>")
	)
	(segment
		(start 369.227608 -284.293564)
		(end 369.197128 -284.311344)
		(width 0.1143)
		(layer "In13.Cu")
		(net "P5E_CPU0_P2_TX_DN<9>")
	)
	(segment
		(start 369.266724 -285.890716)
		(end 369.227608 -285.913576)
		(width 0.1143)
		(layer "In13.Cu")
		(net "P5E_CPU0_P2_TX_DN<9>")
	)
	(segment
		(start 368.288824 -271.979136)
		(end 368.290348 -271.980152)
		(width 0.1143)
		(layer "In13.Cu")
		(net "P5E_CPU0_P2_TX_DN<9>")
	)
	(segment
		(start 369.197128 -289.780726)
		(end 369.227608 -289.798506)
		(width 0.1143)
		(layer "In13.Cu")
		(net "P5E_CPU0_P2_TX_DN<9>")
	)
	(segment
		(start 369.227608 -289.153346)
		(end 369.197128 -289.171126)
		(width 0.1143)
		(layer "In13.Cu")
		(net "P5E_CPU0_P2_TX_DN<9>")
	)
	(segment
		(start 369.2271 -279.434036)
		(end 369.22583 -279.434798)
		(width 0.1143)
		(layer "In13.Cu")
		(net "P5E_CPU0_P2_TX_DN<9>")
	)
	(segment
		(start 369.230656 -278.460454)
		(end 369.266724 -278.481282)
		(width 0.1143)
		(layer "In13.Cu")
		(net "P5E_CPU0_P2_TX_DN<9>")
	)
	(segment
		(start 368.287046 -271.97812)
		(end 368.287808 -271.978628)
		(width 0.1143)
		(layer "In13.Cu")
		(net "P5E_CPU0_P2_TX_DN<9>")
	)
	(segment
		(start 369.196112 -276.820376)
		(end 369.2271 -276.838156)
		(width 0.1143)
		(layer "In13.Cu")
		(net "P5E_CPU0_P2_TX_DN<9>")
	)
	(segment
		(start 369.98021 -296.418254)
		(end 370.02593 -296.463974)
		(width 0.1143)
		(layer "In13.Cu")
		(net "P5E_CPU0_P2_TX_DN<9>")
	)
	(segment
		(start 414.53181 -376.391932)
		(end 414.53181 -377.1265)
		(width 0.14224)
		(layer "In13.Cu")
		(net "P5E_CPU0_P2_TX_DN<9>")
	)
	(segment
		(start 368.295428 -271.9832)
		(end 368.326924 -272.001488)
		(width 0.1143)
		(layer "In13.Cu")
		(net "P5E_CPU0_P2_TX_DN<9>")
	)
	(segment
		(start 369.197128 -283.300932)
		(end 369.227608 -283.318712)
		(width 0.1143)
		(layer "In13.Cu")
		(net "P5E_CPU0_P2_TX_DN<9>")
	)
	(segment
		(start 369.22583 -274.574762)
		(end 369.196112 -274.59178)
		(width 0.1143)
		(layer "In13.Cu")
		(net "P5E_CPU0_P2_TX_DN<9>")
	)
	(segment
		(start 369.227608 -284.938724)
		(end 369.266724 -284.961584)
		(width 0.1143)
		(layer "In13.Cu")
		(net "P5E_CPU0_P2_TX_DN<9>")
	)
	(segment
		(start 369.227608 -294.013382)
		(end 369.197128 -294.031162)
		(width 0.1143)
		(layer "In13.Cu")
		(net "P5E_CPU0_P2_TX_DN<9>")
	)
	(segment
		(start 369.227862 -280.078688)
		(end 369.230656 -280.080466)
		(width 0.1143)
		(layer "In13.Cu")
		(net "P5E_CPU0_P2_TX_DN<9>")
	)
	(segment
		(start 369.197128 -281.68092)
		(end 369.227608 -281.6987)
		(width 0.1143)
		(layer "In13.Cu")
		(net "P5E_CPU0_P2_TX_DN<9>")
	)
	(segment
		(start 369.227608 -288.178494)
		(end 369.266724 -288.201354)
		(width 0.1143)
		(layer "In13.Cu")
		(net "P5E_CPU0_P2_TX_DN<9>")
	)
	(arc
		(start 369.266724 -294.681402)
		(mid 369.445537 -294.883752)
		(end 369.510056 -295.145968)
		(width 0.1143)
		(layer "In13.Cu")
		(net "P5E_CPU0_P2_TX_DN<9>")
	)
	(arc
		(start 369.278408 -277.782528)
		(mid 369.271334 -277.787535)
		(end 369.264184 -277.792434)
		(width 0.1143)
		(layer "In13.Cu")
		(net "P5E_CPU0_P2_TX_DN<9>")
	)
	(arc
		(start 369.264184 -276.859746)
		(mid 369.271333 -276.864646)
		(end 369.278408 -276.869652)
		(width 0.1143)
		(layer "In13.Cu")
		(net "P5E_CPU0_P2_TX_DN<9>")
	)
	(arc
		(start 369.197128 -289.171126)
		(mid 369.040151 -289.475926)
		(end 369.197128 -289.780726)
		(width 0.1143)
		(layer "In13.Cu")
		(net "P5E_CPU0_P2_TX_DN<9>")
	)
	(arc
		(start 369.266724 -293.06139)
		(mid 369.510051 -293.525956)
		(end 369.266724 -293.990522)
		(width 0.1143)
		(layer "In13.Cu")
		(net "P5E_CPU0_P2_TX_DN<9>")
	)
	(arc
		(start 369.510056 -287.045908)
		(mid 369.44482 -287.309499)
		(end 369.264184 -287.512252)
		(width 0.1143)
		(layer "In13.Cu")
		(net "P5E_CPU0_P2_TX_DN<9>")
	)
	(arc
		(start 401.240244 -369.441984)
		(mid 401.308027 -369.524569)
		(end 401.390612 -369.592352)
		(width 0.14224)
		(layer "In13.Cu")
		(net "P5E_CPU0_P2_TX_DN<9>")
	)
	(arc
		(start 368.10696 -271.725898)
		(mid 368.159009 -271.857417)
		(end 368.256058 -271.96034)
		(width 0.1143)
		(layer "In13.Cu")
		(net "P5E_CPU0_P2_TX_DN<9>")
	)
	(arc
		(start 369.736878 -295.491408)
		(mid 369.798129 -295.540601)
		(end 369.85194 -295.597834)
		(width 0.1143)
		(layer "In13.Cu")
		(net "P5E_CPU0_P2_TX_DN<9>")
	)
	(arc
		(start 369.266724 -281.72156)
		(mid 369.510051 -282.186126)
		(end 369.266724 -282.650692)
		(width 0.1143)
		(layer "In13.Cu")
		(net "P5E_CPU0_P2_TX_DN<9>")
	)
	(arc
		(start 369.264184 -273.619722)
		(mid 369.271333 -273.624622)
		(end 369.278408 -273.629628)
		(width 0.1143)
		(layer "In13.Cu")
		(net "P5E_CPU0_P2_TX_DN<9>")
	)
	(arc
		(start 369.278408 -273.629628)
		(mid 369.505791 -274.086066)
		(end 369.278408 -274.542504)
		(width 0.1143)
		(layer "In13.Cu")
		(net "P5E_CPU0_P2_TX_DN<9>")
	)
	(arc
		(start 369.278408 -274.542504)
		(mid 369.271334 -274.547511)
		(end 369.264184 -274.55241)
		(width 0.1143)
		(layer "In13.Cu")
		(net "P5E_CPU0_P2_TX_DN<9>")
	)
	(arc
		(start 369.266724 -283.341572)
		(mid 369.510051 -283.806138)
		(end 369.266724 -284.270704)
		(width 0.1143)
		(layer "In13.Cu")
		(net "P5E_CPU0_P2_TX_DN<9>")
	)
	(arc
		(start 368.570256 -272.466054)
		(mid 368.611805 -272.637476)
		(end 368.727228 -272.770854)
		(width 0.1143)
		(layer "In13.Cu")
		(net "P5E_CPU0_P2_TX_DN<9>")
	)
	(arc
		(start 369.85194 -295.597834)
		(mid 369.943959 -295.764902)
		(end 369.98021 -295.952164)
		(width 0.1143)
		(layer "In13.Cu")
		(net "P5E_CPU0_P2_TX_DN<9>")
	)
	(arc
		(start 413.906462 -375.579894)
		(mid 414.009314 -375.641617)
		(end 414.08985 -375.730516)
		(width 0.14224)
		(layer "In13.Cu")
		(net "P5E_CPU0_P2_TX_DN<9>")
	)
	(arc
		(start 369.266724 -291.441378)
		(mid 369.510051 -291.905944)
		(end 369.266724 -292.37051)
		(width 0.1143)
		(layer "In13.Cu")
		(net "P5E_CPU0_P2_TX_DN<9>")
	)
	(arc
		(start 369.197128 -285.931356)
		(mid 369.081701 -286.064732)
		(end 369.040156 -286.236156)
		(width 0.1143)
		(layer "In13.Cu")
		(net "P5E_CPU0_P2_TX_DN<9>")
	)
	(arc
		(start 369.510056 -295.145968)
		(mid 369.551807 -295.317588)
		(end 369.667536 -295.451022)
		(width 0.1143)
		(layer "In13.Cu")
		(net "P5E_CPU0_P2_TX_DN<9>")
	)
	(arc
		(start 396.59814 -362.472478)
		(mid 396.625257 -362.529691)
		(end 396.65783 -362.583984)
		(width 0.14224)
		(layer "In13.Cu")
		(net "P5E_CPU0_P2_TX_DN<9>")
	)
	(arc
		(start 369.196112 -279.451816)
		(mid 369.040184 -279.756108)
		(end 369.196112 -280.0604)
		(width 0.1143)
		(layer "In13.Cu")
		(net "P5E_CPU0_P2_TX_DN<9>")
	)
	(arc
		(start 369.264184 -275.239734)
		(mid 369.271848 -275.245005)
		(end 369.279424 -275.250402)
		(width 0.1143)
		(layer "In13.Cu")
		(net "P5E_CPU0_P2_TX_DN<9>")
	)
	(arc
		(start 369.294664 -278.501348)
		(mid 369.522664 -278.946102)
		(end 369.294664 -279.390856)
		(width 0.1143)
		(layer "In13.Cu")
		(net "P5E_CPU0_P2_TX_DN<9>")
	)
	(arc
		(start 369.197128 -281.07132)
		(mid 369.040151 -281.37612)
		(end 369.197128 -281.68092)
		(width 0.1143)
		(layer "In13.Cu")
		(net "P5E_CPU0_P2_TX_DN<9>")
	)
	(arc
		(start 369.196112 -276.211792)
		(mid 369.040184 -276.516084)
		(end 369.196112 -276.820376)
		(width 0.1143)
		(layer "In13.Cu")
		(net "P5E_CPU0_P2_TX_DN<9>")
	)
	(arc
		(start 369.266724 -284.961584)
		(mid 369.510051 -285.42615)
		(end 369.266724 -285.890716)
		(width 0.1143)
		(layer "In13.Cu")
		(net "P5E_CPU0_P2_TX_DN<9>")
	)
	(arc
		(start 369.196112 -274.59178)
		(mid 369.040184 -274.896072)
		(end 369.196112 -275.200364)
		(width 0.1143)
		(layer "In13.Cu")
		(net "P5E_CPU0_P2_TX_DN<9>")
	)
	(arc
		(start 369.040156 -287.856168)
		(mid 369.081122 -288.026574)
		(end 369.195096 -288.159698)
		(width 0.1143)
		(layer "In13.Cu")
		(net "P5E_CPU0_P2_TX_DN<9>")
	)
	(arc
		(start 370.02593 -298.285154)
		(mid 370.032208 -298.347955)
		(end 370.050568 -298.408344)
		(width 0.14224)
		(layer "In13.Cu")
		(net "P5E_CPU0_P2_TX_DN<9>")
	)
	(arc
		(start 369.278408 -276.869652)
		(mid 369.505791 -277.32609)
		(end 369.278408 -277.782528)
		(width 0.1143)
		(layer "In13.Cu")
		(net "P5E_CPU0_P2_TX_DN<9>")
	)
	(arc
		(start 368.326924 -272.001488)
		(mid 368.505737 -272.203838)
		(end 368.570256 -272.466054)
		(width 0.1143)
		(layer "In13.Cu")
		(net "P5E_CPU0_P2_TX_DN<9>")
	)
	(arc
		(start 369.197128 -282.691332)
		(mid 369.040151 -282.996132)
		(end 369.197128 -283.300932)
		(width 0.1143)
		(layer "In13.Cu")
		(net "P5E_CPU0_P2_TX_DN<9>")
	)
	(arc
		(start 369.040156 -286.236156)
		(mid 369.081122 -286.406562)
		(end 369.195096 -286.539686)
		(width 0.1143)
		(layer "In13.Cu")
		(net "P5E_CPU0_P2_TX_DN<9>")
	)
	(arc
		(start 369.279424 -276.161754)
		(mid 369.271848 -276.16715)
		(end 369.264184 -276.172422)
		(width 0.1143)
		(layer "In13.Cu")
		(net "P5E_CPU0_P2_TX_DN<9>")
	)
	(arc
		(start 369.197128 -294.031162)
		(mid 369.040151 -294.335962)
		(end 369.197128 -294.640762)
		(width 0.1143)
		(layer "In13.Cu")
		(net "P5E_CPU0_P2_TX_DN<9>")
	)
	(arc
		(start 369.266724 -286.581342)
		(mid 369.445537 -286.783692)
		(end 369.510056 -287.045908)
		(width 0.1143)
		(layer "In13.Cu")
		(net "P5E_CPU0_P2_TX_DN<9>")
	)
	(arc
		(start 368.796824 -272.811494)
		(mid 368.975637 -273.013844)
		(end 369.040156 -273.27606)
		(width 0.1143)
		(layer "In13.Cu")
		(net "P5E_CPU0_P2_TX_DN<9>")
	)
	(arc
		(start 369.279424 -275.250402)
		(mid 369.504595 -275.706078)
		(end 369.279424 -276.161754)
		(width 0.1143)
		(layer "In13.Cu")
		(net "P5E_CPU0_P2_TX_DN<9>")
	)
	(arc
		(start 369.197128 -292.41115)
		(mid 369.040151 -292.71595)
		(end 369.197128 -293.02075)
		(width 0.1143)
		(layer "In13.Cu")
		(net "P5E_CPU0_P2_TX_DN<9>")
	)
	(arc
		(start 369.196112 -277.831804)
		(mid 369.040184 -278.136096)
		(end 369.196112 -278.440388)
		(width 0.1143)
		(layer "In13.Cu")
		(net "P5E_CPU0_P2_TX_DN<9>")
	)
	(arc
		(start 369.040156 -273.27606)
		(mid 369.081411 -273.447031)
		(end 369.196112 -273.580352)
		(width 0.1143)
		(layer "In13.Cu")
		(net "P5E_CPU0_P2_TX_DN<9>")
	)
	(arc
		(start 369.197128 -290.791138)
		(mid 369.040151 -291.095938)
		(end 369.197128 -291.400738)
		(width 0.1143)
		(layer "In13.Cu")
		(net "P5E_CPU0_P2_TX_DN<9>")
	)
	(arc
		(start 369.266724 -289.821366)
		(mid 369.510051 -290.285932)
		(end 369.266724 -290.750498)
		(width 0.1143)
		(layer "In13.Cu")
		(net "P5E_CPU0_P2_TX_DN<9>")
	)
	(arc
		(start 369.197128 -287.551368)
		(mid 369.081701 -287.684744)
		(end 369.040156 -287.856168)
		(width 0.1143)
		(layer "In13.Cu")
		(net "P5E_CPU0_P2_TX_DN<9>")
	)
	(arc
		(start 369.266724 -288.201354)
		(mid 369.510051 -288.66592)
		(end 369.266724 -289.130486)
		(width 0.1143)
		(layer "In13.Cu")
		(net "P5E_CPU0_P2_TX_DN<9>")
	)
	(arc
		(start 369.294664 -280.12136)
		(mid 369.522664 -280.566114)
		(end 369.294664 -281.010868)
		(width 0.1143)
		(layer "In13.Cu")
		(net "P5E_CPU0_P2_TX_DN<9>")
	)
	(arc
		(start 369.197128 -284.311344)
		(mid 369.040151 -284.616144)
		(end 369.197128 -284.920944)
		(width 0.1143)
		(layer "In13.Cu")
		(net "P5E_CPU0_P2_TX_DN<9>")
	)
	(segment
		(start 368.0079 -273.010122)
		(end 368.474752 -273.27606)
		(width 0.12954)
		(layer "F.Cu")
		(net "P5E_CPU0_P2_TX_DN<8>")
	)
	(segment
		(start 412.85033 -380.15164)
		(end 412.85033 -380.85522)
		(width 0.12954)
		(layer "F.Cu")
		(net "P5E_CPU0_P2_TX_DN<8>")
	)
	(segment
		(start 412.85033 -380.85522)
		(end 413.14624 -381.15113)
		(width 0.12954)
		(layer "F.Cu")
		(net "P5E_CPU0_P2_TX_DN<8>")
	)
	(segment
		(start 413.12084 -379.88113)
		(end 412.85033 -380.15164)
		(width 0.12954)
		(layer "F.Cu")
		(net "P5E_CPU0_P2_TX_DN<8>")
	)
	(segment
		(start 368.291364 -275.220684)
		(end 368.326924 -275.241512)
		(width 0.1143)
		(layer "In13.Cu")
		(net "P5E_CPU0_P2_TX_DN<8>")
	)
	(segment
		(start 368.277902 -276.199092)
		(end 368.256058 -276.211792)
		(width 0.1143)
		(layer "In13.Cu")
		(net "P5E_CPU0_P2_TX_DN<8>")
	)
	(segment
		(start 368.28222 -277.816818)
		(end 368.28095 -277.81758)
		(width 0.1143)
		(layer "In13.Cu")
		(net "P5E_CPU0_P2_TX_DN<8>")
	)
	(segment
		(start 368.287046 -274.574)
		(end 368.285776 -274.574762)
		(width 0.1143)
		(layer "In13.Cu")
		(net "P5E_CPU0_P2_TX_DN<8>")
	)
	(segment
		(start 369.043204 -296.36339)
		(end 369.088924 -296.40911)
		(width 0.1143)
		(layer "In13.Cu")
		(net "P5E_CPU0_P2_TX_DN<8>")
	)
	(segment
		(start 368.290856 -289.151568)
		(end 368.256058 -289.171634)
		(width 0.1143)
		(layer "In13.Cu")
		(net "P5E_CPU0_P2_TX_DN<8>")
	)
	(segment
		(start 368.287046 -280.07818)
		(end 368.287808 -280.078688)
		(width 0.1143)
		(layer "In13.Cu")
		(net "P5E_CPU0_P2_TX_DN<8>")
	)
	(segment
		(start 368.256058 -291.40023)
		(end 368.287808 -291.418518)
		(width 0.1143)
		(layer "In13.Cu")
		(net "P5E_CPU0_P2_TX_DN<8>")
	)
	(segment
		(start 368.282982 -277.81631)
		(end 368.28222 -277.816818)
		(width 0.1143)
		(layer "In13.Cu")
		(net "P5E_CPU0_P2_TX_DN<8>")
	)
	(segment
		(start 368.287808 -288.178494)
		(end 368.290856 -288.180272)
		(width 0.1143)
		(layer "In13.Cu")
		(net "P5E_CPU0_P2_TX_DN<8>")
	)
	(segment
		(start 368.287808 -293.03853)
		(end 368.290856 -293.040308)
		(width 0.1143)
		(layer "In13.Cu")
		(net "P5E_CPU0_P2_TX_DN<8>")
	)
	(segment
		(start 368.287808 -275.218652)
		(end 368.288824 -275.21916)
		(width 0.1143)
		(layer "In13.Cu")
		(net "P5E_CPU0_P2_TX_DN<8>")
	)
	(segment
		(start 368.28095 -277.81758)
		(end 368.277902 -277.819104)
		(width 0.1143)
		(layer "In13.Cu")
		(net "P5E_CPU0_P2_TX_DN<8>")
	)
	(segment
		(start 368.287808 -291.418772)
		(end 368.325908 -291.440362)
		(width 0.1143)
		(layer "In13.Cu")
		(net "P5E_CPU0_P2_TX_DN<8>")
	)
	(segment
		(start 368.256058 -283.300424)
		(end 368.287046 -283.318204)
		(width 0.1143)
		(layer "In13.Cu")
		(net "P5E_CPU0_P2_TX_DN<8>")
	)
	(segment
		(start 395.833346 -363.198664)
		(end 400.331686 -369.931188)
		(width 0.14224)
		(layer "In13.Cu")
		(net "P5E_CPU0_P2_TX_DN<8>")
	)
	(segment
		(start 368.285776 -274.574762)
		(end 368.284252 -274.575524)
		(width 0.1143)
		(layer "In13.Cu")
		(net "P5E_CPU0_P2_TX_DN<8>")
	)
	(segment
		(start 368.284252 -276.195536)
		(end 368.282982 -276.196298)
		(width 0.1143)
		(layer "In13.Cu")
		(net "P5E_CPU0_P2_TX_DN<8>")
	)
	(segment
		(start 368.28222 -276.196806)
		(end 368.28095 -276.197568)
		(width 0.1143)
		(layer "In13.Cu")
		(net "P5E_CPU0_P2_TX_DN<8>")
	)
	(segment
		(start 368.17681 -273.27606)
		(end 368.10696 -273.34591)
		(width 0.1143)
		(layer "In13.Cu")
		(net "P5E_CPU0_P2_TX_DN<8>")
	)
	(segment
		(start 412.302452 -376.186446)
		(end 412.76143 -376.872754)
		(width 0.14224)
		(layer "In13.Cu")
		(net "P5E_CPU0_P2_TX_DN<8>")
	)
	(segment
		(start 368.570002 -295.14165)
		(end 368.570002 -295.145968)
		(width 0.1143)
		(layer "In13.Cu")
		(net "P5E_CPU0_P2_TX_DN<8>")
	)
	(segment
		(start 368.287046 -276.838156)
		(end 368.287808 -276.838664)
		(width 0.1143)
		(layer "In13.Cu")
		(net "P5E_CPU0_P2_TX_DN<8>")
	)
	(segment
		(start 368.256058 -284.920436)
		(end 368.287808 -284.938724)
		(width 0.1143)
		(layer "In13.Cu")
		(net "P5E_CPU0_P2_TX_DN<8>")
	)
	(segment
		(start 368.28095 -274.577556)
		(end 368.277902 -274.57908)
		(width 0.1143)
		(layer "In13.Cu")
		(net "P5E_CPU0_P2_TX_DN<8>")
	)
	(segment
		(start 368.287808 -283.318712)
		(end 368.290856 -283.32049)
		(width 0.1143)
		(layer "In13.Cu")
		(net "P5E_CPU0_P2_TX_DN<8>")
	)
	(segment
		(start 368.474752 -273.27606)
		(end 368.17681 -273.27606)
		(width 0.1143)
		(layer "In13.Cu")
		(net "P5E_CPU0_P2_TX_DN<8>")
	)
	(segment
		(start 368.277902 -274.57908)
		(end 368.256058 -274.59178)
		(width 0.1143)
		(layer "In13.Cu")
		(net "P5E_CPU0_P2_TX_DN<8>")
	)
	(segment
		(start 368.287808 -279.433528)
		(end 368.287046 -279.434036)
		(width 0.1143)
		(layer "In13.Cu")
		(net "P5E_CPU0_P2_TX_DN<8>")
	)
	(segment
		(start 368.282982 -274.576286)
		(end 368.28222 -274.576794)
		(width 0.1143)
		(layer "In13.Cu")
		(net "P5E_CPU0_P2_TX_DN<8>")
	)
	(segment
		(start 368.326924 -277.790656)
		(end 368.287808 -277.813516)
		(width 0.1143)
		(layer "In13.Cu")
		(net "P5E_CPU0_P2_TX_DN<8>")
	)
	(segment
		(start 368.290348 -276.840188)
		(end 368.291364 -276.840696)
		(width 0.1143)
		(layer "In13.Cu")
		(net "P5E_CPU0_P2_TX_DN<8>")
	)
	(segment
		(start 368.570002 -287.045908)
		(end 368.570002 -287.05048)
		(width 0.1143)
		(layer "In13.Cu")
		(net "P5E_CPU0_P2_TX_DN<8>")
	)
	(segment
		(start 368.325908 -292.371526)
		(end 368.256058 -292.411658)
		(width 0.1143)
		(layer "In13.Cu")
		(net "P5E_CPU0_P2_TX_DN<8>")
	)
	(segment
		(start 368.290856 -285.911798)
		(end 368.256058 -285.931864)
		(width 0.1143)
		(layer "In13.Cu")
		(net "P5E_CPU0_P2_TX_DN<8>")
	)
	(segment
		(start 368.288824 -278.459184)
		(end 368.290348 -278.4602)
		(width 0.1143)
		(layer "In13.Cu")
		(net "P5E_CPU0_P2_TX_DN<8>")
	)
	(segment
		(start 369.088924 -296.40911)
		(end 369.088924 -296.437558)
		(width 0.1143)
		(layer "In13.Cu")
		(net "P5E_CPU0_P2_TX_DN<8>")
	)
	(segment
		(start 368.570002 -295.145968)
		(end 368.570256 -295.145968)
		(width 0.1143)
		(layer "In13.Cu")
		(net "P5E_CPU0_P2_TX_DN<8>")
	)
	(segment
		(start 368.287046 -276.194012)
		(end 368.285776 -276.194774)
		(width 0.1143)
		(layer "In13.Cu")
		(net "P5E_CPU0_P2_TX_DN<8>")
	)
	(segment
		(start 400.61896 -370.218462)
		(end 404.178516 -372.596664)
		(width 0.14224)
		(layer "In13.Cu")
		(net "P5E_CPU0_P2_TX_DN<8>")
	)
	(segment
		(start 368.287808 -289.798506)
		(end 368.290856 -289.800284)
		(width 0.1143)
		(layer "In13.Cu")
		(net "P5E_CPU0_P2_TX_DN<8>")
	)
	(segment
		(start 368.338862 -292.362128)
		(end 368.325908 -292.371526)
		(width 0.1143)
		(layer "In13.Cu")
		(net "P5E_CPU0_P2_TX_DN<8>")
	)
	(segment
		(start 368.291364 -273.600672)
		(end 368.326924 -273.6215)
		(width 0.1143)
		(layer "In13.Cu")
		(net "P5E_CPU0_P2_TX_DN<8>")
	)
	(segment
		(start 368.287046 -277.814024)
		(end 368.285776 -277.814786)
		(width 0.1143)
		(layer "In13.Cu")
		(net "P5E_CPU0_P2_TX_DN<8>")
	)
	(segment
		(start 368.282982 -276.196298)
		(end 368.28222 -276.196806)
		(width 0.1143)
		(layer "In13.Cu")
		(net "P5E_CPU0_P2_TX_DN<8>")
	)
	(segment
		(start 369.098576 -298.68241)
		(end 395.833346 -363.198664)
		(width 0.14224)
		(layer "In13.Cu")
		(net "P5E_CPU0_P2_TX_DN<8>")
	)
	(segment
		(start 368.287046 -283.318204)
		(end 368.287808 -283.318712)
		(width 0.1143)
		(layer "In13.Cu")
		(net "P5E_CPU0_P2_TX_DN<8>")
	)
	(segment
		(start 368.287808 -281.6987)
		(end 368.290856 -281.700478)
		(width 0.1143)
		(layer "In13.Cu")
		(net "P5E_CPU0_P2_TX_DN<8>")
	)
	(segment
		(start 368.290348 -275.220176)
		(end 368.291364 -275.220684)
		(width 0.1143)
		(layer "In13.Cu")
		(net "P5E_CPU0_P2_TX_DN<8>")
	)
	(segment
		(start 412.83001 -377.100338)
		(end 412.83001 -379.5903)
		(width 0.14224)
		(layer "In13.Cu")
		(net "P5E_CPU0_P2_TX_DN<8>")
	)
	(segment
		(start 368.256058 -294.640254)
		(end 368.287808 -294.658542)
		(width 0.1143)
		(layer "In13.Cu")
		(net "P5E_CPU0_P2_TX_DN<8>")
	)
	(segment
		(start 368.288824 -275.21916)
		(end 368.290348 -275.220176)
		(width 0.1143)
		(layer "In13.Cu")
		(net "P5E_CPU0_P2_TX_DN<8>")
	)
	(segment
		(start 368.277902 -279.439116)
		(end 368.256058 -279.451816)
		(width 0.1143)
		(layer "In13.Cu")
		(net "P5E_CPU0_P2_TX_DN<8>")
	)
	(segment
		(start 368.290856 -294.011604)
		(end 368.256058 -294.03167)
		(width 0.1143)
		(layer "In13.Cu")
		(net "P5E_CPU0_P2_TX_DN<8>")
	)
	(segment
		(start 368.288824 -276.839172)
		(end 368.290348 -276.840188)
		(width 0.1143)
		(layer "In13.Cu")
		(net "P5E_CPU0_P2_TX_DN<8>")
	)
	(segment
		(start 368.287046 -273.598132)
		(end 368.287808 -273.59864)
		(width 0.1143)
		(layer "In13.Cu")
		(net "P5E_CPU0_P2_TX_DN<8>")
	)
	(segment
		(start 368.33937 -287.501584)
		(end 368.32794 -287.51022)
		(width 0.1143)
		(layer "In13.Cu")
		(net "P5E_CPU0_P2_TX_DN<8>")
	)
	(segment
		(start 368.28222 -279.43683)
		(end 368.28095 -279.437592)
		(width 0.1143)
		(layer "In13.Cu")
		(net "P5E_CPU0_P2_TX_DN<8>")
	)
	(segment
		(start 368.255042 -288.159444)
		(end 368.287808 -288.178494)
		(width 0.1143)
		(layer "In13.Cu")
		(net "P5E_CPU0_P2_TX_DN<8>")
	)
	(segment
		(start 368.256058 -289.780218)
		(end 368.287808 -289.798506)
		(width 0.1143)
		(layer "In13.Cu")
		(net "P5E_CPU0_P2_TX_DN<8>")
	)
	(segment
		(start 368.256058 -280.0604)
		(end 368.287046 -280.07818)
		(width 0.1143)
		(layer "In13.Cu")
		(net "P5E_CPU0_P2_TX_DN<8>")
	)
	(segment
		(start 404.178516 -372.596664)
		(end 411.749494 -375.732802)
		(width 0.14224)
		(layer "In13.Cu")
		(net "P5E_CPU0_P2_TX_DN<8>")
	)
	(segment
		(start 368.287808 -284.938724)
		(end 368.290856 -284.940502)
		(width 0.1143)
		(layer "In13.Cu")
		(net "P5E_CPU0_P2_TX_DN<8>")
	)
	(segment
		(start 368.28222 -274.576794)
		(end 368.28095 -274.577556)
		(width 0.1143)
		(layer "In13.Cu")
		(net "P5E_CPU0_P2_TX_DN<8>")
	)
	(segment
		(start 368.285776 -276.194774)
		(end 368.284252 -276.195536)
		(width 0.1143)
		(layer "In13.Cu")
		(net "P5E_CPU0_P2_TX_DN<8>")
	)
	(segment
		(start 368.256058 -293.020242)
		(end 368.287808 -293.03853)
		(width 0.1143)
		(layer "In13.Cu")
		(net "P5E_CPU0_P2_TX_DN<8>")
	)
	(segment
		(start 368.291364 -276.840696)
		(end 368.326924 -276.861524)
		(width 0.1143)
		(layer "In13.Cu")
		(net "P5E_CPU0_P2_TX_DN<8>")
	)
	(segment
		(start 368.326924 -281.03068)
		(end 368.287808 -281.05354)
		(width 0.1143)
		(layer "In13.Cu")
		(net "P5E_CPU0_P2_TX_DN<8>")
	)
	(segment
		(start 368.32794 -287.51022)
		(end 368.256058 -287.551876)
		(width 0.1143)
		(layer "In13.Cu")
		(net "P5E_CPU0_P2_TX_DN<8>")
	)
	(segment
		(start 368.727228 -295.450768)
		(end 368.796824 -295.491408)
		(width 0.1143)
		(layer "In13.Cu")
		(net "P5E_CPU0_P2_TX_DN<8>")
	)
	(segment
		(start 368.290348 -273.600164)
		(end 368.291364 -273.600672)
		(width 0.1143)
		(layer "In13.Cu")
		(net "P5E_CPU0_P2_TX_DN<8>")
	)
	(segment
		(start 368.285776 -277.814786)
		(end 368.284252 -277.815548)
		(width 0.1143)
		(layer "In13.Cu")
		(net "P5E_CPU0_P2_TX_DN<8>")
	)
	(segment
		(start 368.287808 -274.573492)
		(end 368.287046 -274.574)
		(width 0.1143)
		(layer "In13.Cu")
		(net "P5E_CPU0_P2_TX_DN<8>")
	)
	(segment
		(start 368.287808 -276.838664)
		(end 368.288824 -276.839172)
		(width 0.1143)
		(layer "In13.Cu")
		(net "P5E_CPU0_P2_TX_DN<8>")
	)
	(segment
		(start 368.288824 -273.599148)
		(end 368.290348 -273.600164)
		(width 0.1143)
		(layer "In13.Cu")
		(net "P5E_CPU0_P2_TX_DN<8>")
	)
	(segment
		(start 368.326924 -276.170644)
		(end 368.287808 -276.193504)
		(width 0.1143)
		(layer "In13.Cu")
		(net "P5E_CPU0_P2_TX_DN<8>")
	)
	(segment
		(start 368.28095 -276.197568)
		(end 368.277902 -276.199092)
		(width 0.1143)
		(layer "In13.Cu")
		(net "P5E_CPU0_P2_TX_DN<8>")
	)
	(segment
		(start 368.287808 -277.813516)
		(end 368.287046 -277.814024)
		(width 0.1143)
		(layer "In13.Cu")
		(net "P5E_CPU0_P2_TX_DN<8>")
	)
	(segment
		(start 368.325908 -291.440362)
		(end 368.338862 -291.44976)
		(width 0.1143)
		(layer "In13.Cu")
		(net "P5E_CPU0_P2_TX_DN<8>")
	)
	(segment
		(start 412.83001 -379.5903)
		(end 413.12084 -379.88113)
		(width 0.14224)
		(layer "In13.Cu")
		(net "P5E_CPU0_P2_TX_DN<8>")
	)
	(segment
		(start 368.282982 -279.436322)
		(end 368.28222 -279.43683)
		(width 0.1143)
		(layer "In13.Cu")
		(net "P5E_CPU0_P2_TX_DN<8>")
	)
	(segment
		(start 368.256058 -273.580352)
		(end 368.287046 -273.598132)
		(width 0.1143)
		(layer "In13.Cu")
		(net "P5E_CPU0_P2_TX_DN<8>")
	)
	(segment
		(start 369.088924 -296.437558)
		(end 369.088924 -298.633642)
		(width 0.14224)
		(layer "In13.Cu")
		(net "P5E_CPU0_P2_TX_DN<8>")
	)
	(segment
		(start 368.290348 -278.4602)
		(end 368.326924 -278.481536)
		(width 0.1143)
		(layer "In13.Cu")
		(net "P5E_CPU0_P2_TX_DN<8>")
	)
	(segment
		(start 369.043204 -295.9608)
		(end 369.043204 -296.36339)
		(width 0.1143)
		(layer "In13.Cu")
		(net "P5E_CPU0_P2_TX_DN<8>")
	)
	(segment
		(start 368.287808 -278.458676)
		(end 368.288824 -278.459184)
		(width 0.1143)
		(layer "In13.Cu")
		(net "P5E_CPU0_P2_TX_DN<8>")
	)
	(segment
		(start 368.326924 -279.410668)
		(end 368.287808 -279.433528)
		(width 0.1143)
		(layer "In13.Cu")
		(net "P5E_CPU0_P2_TX_DN<8>")
	)
	(segment
		(start 368.287808 -273.59864)
		(end 368.288824 -273.599148)
		(width 0.1143)
		(layer "In13.Cu")
		(net "P5E_CPU0_P2_TX_DN<8>")
	)
	(segment
		(start 368.285776 -279.434798)
		(end 368.284252 -279.43556)
		(width 0.1143)
		(layer "In13.Cu")
		(net "P5E_CPU0_P2_TX_DN<8>")
	)
	(segment
		(start 368.287808 -280.078688)
		(end 368.288824 -280.079196)
		(width 0.1143)
		(layer "In13.Cu")
		(net "P5E_CPU0_P2_TX_DN<8>")
	)
	(segment
		(start 368.287808 -281.05354)
		(end 368.256058 -281.071828)
		(width 0.1143)
		(layer "In13.Cu")
		(net "P5E_CPU0_P2_TX_DN<8>")
	)
	(segment
		(start 368.256058 -276.820376)
		(end 368.287046 -276.838156)
		(width 0.1143)
		(layer "In13.Cu")
		(net "P5E_CPU0_P2_TX_DN<8>")
	)
	(segment
		(start 368.290856 -284.291786)
		(end 368.256058 -284.311852)
		(width 0.1143)
		(layer "In13.Cu")
		(net "P5E_CPU0_P2_TX_DN<8>")
	)
	(segment
		(start 368.28095 -279.437592)
		(end 368.277902 -279.439116)
		(width 0.1143)
		(layer "In13.Cu")
		(net "P5E_CPU0_P2_TX_DN<8>")
	)
	(segment
		(start 368.287046 -275.218144)
		(end 368.287808 -275.218652)
		(width 0.1143)
		(layer "In13.Cu")
		(net "P5E_CPU0_P2_TX_DN<8>")
	)
	(segment
		(start 368.284252 -277.815548)
		(end 368.282982 -277.81631)
		(width 0.1143)
		(layer "In13.Cu")
		(net "P5E_CPU0_P2_TX_DN<8>")
	)
	(segment
		(start 368.287808 -276.193504)
		(end 368.287046 -276.194012)
		(width 0.1143)
		(layer "In13.Cu")
		(net "P5E_CPU0_P2_TX_DN<8>")
	)
	(segment
		(start 368.290856 -282.671774)
		(end 368.256058 -282.69184)
		(width 0.1143)
		(layer "In13.Cu")
		(net "P5E_CPU0_P2_TX_DN<8>")
	)
	(segment
		(start 368.284252 -274.575524)
		(end 368.282982 -274.576286)
		(width 0.1143)
		(layer "In13.Cu")
		(net "P5E_CPU0_P2_TX_DN<8>")
	)
	(segment
		(start 368.287046 -279.434036)
		(end 368.285776 -279.434798)
		(width 0.1143)
		(layer "In13.Cu")
		(net "P5E_CPU0_P2_TX_DN<8>")
	)
	(segment
		(start 368.25428 -288.158936)
		(end 368.255042 -288.159444)
		(width 0.1143)
		(layer "In13.Cu")
		(net "P5E_CPU0_P2_TX_DN<8>")
	)
	(segment
		(start 368.326924 -274.550632)
		(end 368.287808 -274.573492)
		(width 0.1143)
		(layer "In13.Cu")
		(net "P5E_CPU0_P2_TX_DN<8>")
	)
	(segment
		(start 368.256058 -281.680412)
		(end 368.287808 -281.6987)
		(width 0.1143)
		(layer "In13.Cu")
		(net "P5E_CPU0_P2_TX_DN<8>")
	)
	(segment
		(start 368.25428 -286.538924)
		(end 368.328956 -286.582866)
		(width 0.1143)
		(layer "In13.Cu")
		(net "P5E_CPU0_P2_TX_DN<8>")
	)
	(segment
		(start 368.290856 -290.77158)
		(end 368.256058 -290.791646)
		(width 0.1143)
		(layer "In13.Cu")
		(net "P5E_CPU0_P2_TX_DN<8>")
	)
	(segment
		(start 368.287808 -294.658542)
		(end 368.327686 -294.682164)
		(width 0.1143)
		(layer "In13.Cu")
		(net "P5E_CPU0_P2_TX_DN<8>")
	)
	(segment
		(start 368.288824 -280.079196)
		(end 368.326924 -280.101548)
		(width 0.1143)
		(layer "In13.Cu")
		(net "P5E_CPU0_P2_TX_DN<8>")
	)
	(segment
		(start 368.277902 -277.819104)
		(end 368.256058 -277.831804)
		(width 0.1143)
		(layer "In13.Cu")
		(net "P5E_CPU0_P2_TX_DN<8>")
	)
	(segment
		(start 368.256058 -275.200364)
		(end 368.287046 -275.218144)
		(width 0.1143)
		(layer "In13.Cu")
		(net "P5E_CPU0_P2_TX_DN<8>")
	)
	(segment
		(start 368.287808 -291.418518)
		(end 368.287808 -291.418772)
		(width 0.1143)
		(layer "In13.Cu")
		(net "P5E_CPU0_P2_TX_DN<8>")
	)
	(segment
		(start 368.256058 -278.440388)
		(end 368.287808 -278.458676)
		(width 0.1143)
		(layer "In13.Cu")
		(net "P5E_CPU0_P2_TX_DN<8>")
	)
	(segment
		(start 368.284252 -279.43556)
		(end 368.282982 -279.436322)
		(width 0.1143)
		(layer "In13.Cu")
		(net "P5E_CPU0_P2_TX_DN<8>")
	)
	(arc
		(start 368.290856 -283.32049)
		(mid 368.570471 -283.806138)
		(end 368.290856 -284.291786)
		(width 0.1143)
		(layer "In13.Cu")
		(net "P5E_CPU0_P2_TX_DN<8>")
	)
	(arc
		(start 368.100102 -287.856168)
		(mid 368.140864 -288.026052)
		(end 368.25428 -288.158936)
		(width 0.1143)
		(layer "In13.Cu")
		(net "P5E_CPU0_P2_TX_DN<8>")
	)
	(arc
		(start 368.10696 -273.34591)
		(mid 368.159009 -273.477429)
		(end 368.256058 -273.580352)
		(width 0.1143)
		(layer "In13.Cu")
		(net "P5E_CPU0_P2_TX_DN<8>")
	)
	(arc
		(start 368.256058 -282.69184)
		(mid 368.10013 -282.996132)
		(end 368.256058 -283.300424)
		(width 0.1143)
		(layer "In13.Cu")
		(net "P5E_CPU0_P2_TX_DN<8>")
	)
	(arc
		(start 368.256058 -277.831804)
		(mid 368.10013 -278.136096)
		(end 368.256058 -278.440388)
		(width 0.1143)
		(layer "In13.Cu")
		(net "P5E_CPU0_P2_TX_DN<8>")
	)
	(arc
		(start 412.76143 -376.872754)
		(mid 412.812624 -376.981455)
		(end 412.83001 -377.100338)
		(width 0.14224)
		(layer "In13.Cu")
		(net "P5E_CPU0_P2_TX_DN<8>")
	)
	(arc
		(start 368.326924 -280.101548)
		(mid 368.570251 -280.566114)
		(end 368.326924 -281.03068)
		(width 0.1143)
		(layer "In13.Cu")
		(net "P5E_CPU0_P2_TX_DN<8>")
	)
	(arc
		(start 400.331686 -369.931188)
		(mid 400.461174 -370.088974)
		(end 400.61896 -370.218462)
		(width 0.14224)
		(layer "In13.Cu")
		(net "P5E_CPU0_P2_TX_DN<8>")
	)
	(arc
		(start 368.326924 -278.481536)
		(mid 368.570251 -278.946102)
		(end 368.326924 -279.410668)
		(width 0.1143)
		(layer "In13.Cu")
		(net "P5E_CPU0_P2_TX_DN<8>")
	)
	(arc
		(start 368.570002 -287.05048)
		(mid 368.509003 -287.303804)
		(end 368.33937 -287.501584)
		(width 0.1143)
		(layer "In13.Cu")
		(net "P5E_CPU0_P2_TX_DN<8>")
	)
	(arc
		(start 368.256058 -290.791646)
		(mid 368.10013 -291.095938)
		(end 368.256058 -291.40023)
		(width 0.1143)
		(layer "In13.Cu")
		(net "P5E_CPU0_P2_TX_DN<8>")
	)
	(arc
		(start 369.088924 -298.633642)
		(mid 369.091322 -298.658509)
		(end 369.098576 -298.68241)
		(width 0.14224)
		(layer "In13.Cu")
		(net "P5E_CPU0_P2_TX_DN<8>")
	)
	(arc
		(start 368.326924 -275.241512)
		(mid 368.570251 -275.706078)
		(end 368.326924 -276.170644)
		(width 0.1143)
		(layer "In13.Cu")
		(net "P5E_CPU0_P2_TX_DN<8>")
	)
	(arc
		(start 368.256058 -274.59178)
		(mid 368.10013 -274.896072)
		(end 368.256058 -275.200364)
		(width 0.1143)
		(layer "In13.Cu")
		(net "P5E_CPU0_P2_TX_DN<8>")
	)
	(arc
		(start 368.338862 -291.44976)
		(mid 368.573289 -291.905944)
		(end 368.338862 -292.362128)
		(width 0.1143)
		(layer "In13.Cu")
		(net "P5E_CPU0_P2_TX_DN<8>")
	)
	(arc
		(start 368.290856 -293.040308)
		(mid 368.570471 -293.525956)
		(end 368.290856 -294.011604)
		(width 0.1143)
		(layer "In13.Cu")
		(net "P5E_CPU0_P2_TX_DN<8>")
	)
	(arc
		(start 368.256058 -287.551876)
		(mid 368.141382 -287.68521)
		(end 368.100102 -287.856168)
		(width 0.1143)
		(layer "In13.Cu")
		(net "P5E_CPU0_P2_TX_DN<8>")
	)
	(arc
		(start 368.256058 -292.411658)
		(mid 368.10013 -292.71595)
		(end 368.256058 -293.020242)
		(width 0.1143)
		(layer "In13.Cu")
		(net "P5E_CPU0_P2_TX_DN<8>")
	)
	(arc
		(start 368.256058 -284.311852)
		(mid 368.10013 -284.616144)
		(end 368.256058 -284.920436)
		(width 0.1143)
		(layer "In13.Cu")
		(net "P5E_CPU0_P2_TX_DN<8>")
	)
	(arc
		(start 368.290856 -289.800284)
		(mid 368.570471 -290.285932)
		(end 368.290856 -290.77158)
		(width 0.1143)
		(layer "In13.Cu")
		(net "P5E_CPU0_P2_TX_DN<8>")
	)
	(arc
		(start 368.796824 -295.491408)
		(mid 368.977769 -295.695791)
		(end 369.043204 -295.9608)
		(width 0.1143)
		(layer "In13.Cu")
		(net "P5E_CPU0_P2_TX_DN<8>")
	)
	(arc
		(start 368.256058 -289.171634)
		(mid 368.10013 -289.475926)
		(end 368.256058 -289.780218)
		(width 0.1143)
		(layer "In13.Cu")
		(net "P5E_CPU0_P2_TX_DN<8>")
	)
	(arc
		(start 368.290856 -288.180272)
		(mid 368.570471 -288.66592)
		(end 368.290856 -289.151568)
		(width 0.1143)
		(layer "In13.Cu")
		(net "P5E_CPU0_P2_TX_DN<8>")
	)
	(arc
		(start 368.256058 -281.071828)
		(mid 368.10013 -281.37612)
		(end 368.256058 -281.680412)
		(width 0.1143)
		(layer "In13.Cu")
		(net "P5E_CPU0_P2_TX_DN<8>")
	)
	(arc
		(start 368.290856 -281.700478)
		(mid 368.570471 -282.186126)
		(end 368.290856 -282.671774)
		(width 0.1143)
		(layer "In13.Cu")
		(net "P5E_CPU0_P2_TX_DN<8>")
	)
	(arc
		(start 368.100102 -286.236156)
		(mid 368.140864 -286.40604)
		(end 368.25428 -286.538924)
		(width 0.1143)
		(layer "In13.Cu")
		(net "P5E_CPU0_P2_TX_DN<8>")
	)
	(arc
		(start 368.256058 -276.211792)
		(mid 368.10013 -276.516084)
		(end 368.256058 -276.820376)
		(width 0.1143)
		(layer "In13.Cu")
		(net "P5E_CPU0_P2_TX_DN<8>")
	)
	(arc
		(start 368.290856 -284.940502)
		(mid 368.570471 -285.42615)
		(end 368.290856 -285.911798)
		(width 0.1143)
		(layer "In13.Cu")
		(net "P5E_CPU0_P2_TX_DN<8>")
	)
	(arc
		(start 368.328956 -286.582866)
		(mid 368.506152 -286.784878)
		(end 368.570002 -287.045908)
		(width 0.1143)
		(layer "In13.Cu")
		(net "P5E_CPU0_P2_TX_DN<8>")
	)
	(arc
		(start 368.326924 -273.6215)
		(mid 368.570251 -274.086066)
		(end 368.326924 -274.550632)
		(width 0.1143)
		(layer "In13.Cu")
		(net "P5E_CPU0_P2_TX_DN<8>")
	)
	(arc
		(start 368.256058 -285.931864)
		(mid 368.141382 -286.065198)
		(end 368.100102 -286.236156)
		(width 0.1143)
		(layer "In13.Cu")
		(net "P5E_CPU0_P2_TX_DN<8>")
	)
	(arc
		(start 368.327686 -294.682164)
		(mid 368.505722 -294.881914)
		(end 368.570002 -295.14165)
		(width 0.1143)
		(layer "In13.Cu")
		(net "P5E_CPU0_P2_TX_DN<8>")
	)
	(arc
		(start 411.749494 -375.732802)
		(mid 412.059608 -375.918624)
		(end 412.302452 -376.186446)
		(width 0.14224)
		(layer "In13.Cu")
		(net "P5E_CPU0_P2_TX_DN<8>")
	)
	(arc
		(start 368.326924 -276.861524)
		(mid 368.570251 -277.32609)
		(end 368.326924 -277.790656)
		(width 0.1143)
		(layer "In13.Cu")
		(net "P5E_CPU0_P2_TX_DN<8>")
	)
	(arc
		(start 368.256058 -294.03167)
		(mid 368.10013 -294.335962)
		(end 368.256058 -294.640254)
		(width 0.1143)
		(layer "In13.Cu")
		(net "P5E_CPU0_P2_TX_DN<8>")
	)
	(arc
		(start 368.570256 -295.145968)
		(mid 368.611805 -295.31739)
		(end 368.727228 -295.450768)
		(width 0.1143)
		(layer "In13.Cu")
		(net "P5E_CPU0_P2_TX_DN<8>")
	)
	(arc
		(start 368.256058 -279.451816)
		(mid 368.10013 -279.756108)
		(end 368.256058 -280.0604)
		(width 0.1143)
		(layer "In13.Cu")
		(net "P5E_CPU0_P2_TX_DN<8>")
	)
	(segment
		(start 411.14853 -382.61544)
		(end 411.14853 -383.31902)
		(width 0.12954)
		(layer "F.Cu")
		(net "P5E_CPU0_P2_TX_DN<7>")
	)
	(segment
		(start 411.41904 -382.34493)
		(end 411.14853 -382.61544)
		(width 0.12954)
		(layer "F.Cu")
		(net "P5E_CPU0_P2_TX_DN<7>")
	)
	(segment
		(start 368.0079 -269.770098)
		(end 368.474752 -270.036036)
		(width 0.12954)
		(layer "F.Cu")
		(net "P5E_CPU0_P2_TX_DN<7>")
	)
	(segment
		(start 411.14853 -383.31902)
		(end 411.44444 -383.61493)
		(width 0.12954)
		(layer "F.Cu")
		(net "P5E_CPU0_P2_TX_DN<7>")
	)
	(segment
		(start 367.345976 -286.557974)
		(end 367.347246 -286.558736)
		(width 0.1143)
		(layer "In13.Cu")
		(net "P5E_CPU0_P2_TX_DN<7>")
	)
	(segment
		(start 368.155728 -296.336466)
		(end 368.155728 -296.364914)
		(width 0.1143)
		(layer "In13.Cu")
		(net "P5E_CPU0_P2_TX_DN<7>")
	)
	(segment
		(start 367.347754 -281.05354)
		(end 367.346484 -281.054048)
		(width 0.1143)
		(layer "In13.Cu")
		(net "P5E_CPU0_P2_TX_DN<7>")
	)
	(segment
		(start 367.350802 -287.529016)
		(end 367.346738 -287.531556)
		(width 0.1143)
		(layer "In13.Cu")
		(net "P5E_CPU0_P2_TX_DN<7>")
	)
	(segment
		(start 367.347754 -274.573492)
		(end 367.316004 -274.59178)
		(width 0.1143)
		(layer "In13.Cu")
		(net "P5E_CPU0_P2_TX_DN<7>")
	)
	(segment
		(start 367.346992 -280.07818)
		(end 367.347754 -280.078688)
		(width 0.1143)
		(layer "In13.Cu")
		(net "P5E_CPU0_P2_TX_DN<7>")
	)
	(segment
		(start 367.354866 -293.042594)
		(end 367.35639 -293.04361)
		(width 0.1143)
		(layer "In13.Cu")
		(net "P5E_CPU0_P2_TX_DN<7>")
	)
	(segment
		(start 367.347754 -271.333468)
		(end 367.316004 -271.351756)
		(width 0.1143)
		(layer "In13.Cu")
		(net "P5E_CPU0_P2_TX_DN<7>")
	)
	(segment
		(start 399.700496 -370.735606)
		(end 403.766274 -373.452644)
		(width 0.14224)
		(layer "In13.Cu")
		(net "P5E_CPU0_P2_TX_DN<7>")
	)
	(segment
		(start 367.368836 -285.90113)
		(end 367.345468 -285.914592)
		(width 0.1143)
		(layer "In13.Cu")
		(net "P5E_CPU0_P2_TX_DN<7>")
	)
	(segment
		(start 367.38687 -290.750498)
		(end 367.347246 -290.773612)
		(width 0.1143)
		(layer "In13.Cu")
		(net "P5E_CPU0_P2_TX_DN<7>")
	)
	(segment
		(start 368.17681 -270.036036)
		(end 368.094006 -270.11884)
		(width 0.1143)
		(layer "In13.Cu")
		(net "P5E_CPU0_P2_TX_DN<7>")
	)
	(segment
		(start 367.366042 -288.189162)
		(end 367.38687 -288.201354)
		(width 0.1143)
		(layer "In13.Cu")
		(net "P5E_CPU0_P2_TX_DN<7>")
	)
	(segment
		(start 367.347754 -279.433528)
		(end 367.316004 -279.451816)
		(width 0.1143)
		(layer "In13.Cu")
		(net "P5E_CPU0_P2_TX_DN<7>")
	)
	(segment
		(start 367.347754 -275.218652)
		(end 367.38687 -275.241512)
		(width 0.1143)
		(layer "In13.Cu")
		(net "P5E_CPU0_P2_TX_DN<7>")
	)
	(segment
		(start 367.347754 -271.978628)
		(end 367.38687 -272.001488)
		(width 0.1143)
		(layer "In13.Cu")
		(net "P5E_CPU0_P2_TX_DN<7>")
	)
	(segment
		(start 367.32972 -294.648382)
		(end 367.386108 -294.680894)
		(width 0.1143)
		(layer "In13.Cu")
		(net "P5E_CPU0_P2_TX_DN<7>")
	)
	(segment
		(start 367.34877 -289.799014)
		(end 367.350294 -289.80003)
		(width 0.1143)
		(layer "In13.Cu")
		(net "P5E_CPU0_P2_TX_DN<7>")
	)
	(segment
		(start 368.110008 -296.290746)
		(end 368.155728 -296.336466)
		(width 0.1143)
		(layer "In13.Cu")
		(net "P5E_CPU0_P2_TX_DN<7>")
	)
	(segment
		(start 367.38687 -289.130486)
		(end 367.34496 -289.15487)
		(width 0.1143)
		(layer "In13.Cu")
		(net "P5E_CPU0_P2_TX_DN<7>")
	)
	(segment
		(start 367.347754 -276.838664)
		(end 367.38687 -276.861524)
		(width 0.1143)
		(layer "In13.Cu")
		(net "P5E_CPU0_P2_TX_DN<7>")
	)
	(segment
		(start 367.347754 -273.59864)
		(end 367.38687 -273.6215)
		(width 0.1143)
		(layer "In13.Cu")
		(net "P5E_CPU0_P2_TX_DN<7>")
	)
	(segment
		(start 367.347754 -289.798506)
		(end 367.34877 -289.799014)
		(width 0.1143)
		(layer "In13.Cu")
		(net "P5E_CPU0_P2_TX_DN<7>")
	)
	(segment
		(start 367.317782 -283.30144)
		(end 367.386362 -283.341064)
		(width 0.1143)
		(layer "In13.Cu")
		(net "P5E_CPU0_P2_TX_DN<7>")
	)
	(segment
		(start 367.38687 -277.790656)
		(end 367.347754 -277.813516)
		(width 0.1143)
		(layer "In13.Cu")
		(net "P5E_CPU0_P2_TX_DN<7>")
	)
	(segment
		(start 367.85677 -270.500602)
		(end 367.817654 -270.523462)
		(width 0.1143)
		(layer "In13.Cu")
		(net "P5E_CPU0_P2_TX_DN<7>")
	)
	(segment
		(start 368.155728 -296.364914)
		(end 368.155728 -298.795948)
		(width 0.14224)
		(layer "In13.Cu")
		(net "P5E_CPU0_P2_TX_DN<7>")
	)
	(segment
		(start 367.38687 -274.550632)
		(end 367.347754 -274.573492)
		(width 0.1143)
		(layer "In13.Cu")
		(net "P5E_CPU0_P2_TX_DN<7>")
	)
	(segment
		(start 411.12821 -379.460506)
		(end 411.12821 -382.0541)
		(width 0.14224)
		(layer "In13.Cu")
		(net "P5E_CPU0_P2_TX_DN<7>")
	)
	(segment
		(start 367.316004 -271.96034)
		(end 367.347754 -271.978628)
		(width 0.1143)
		(layer "In13.Cu")
		(net "P5E_CPU0_P2_TX_DN<7>")
	)
	(segment
		(start 367.38687 -279.410668)
		(end 367.347754 -279.433528)
		(width 0.1143)
		(layer "In13.Cu")
		(net "P5E_CPU0_P2_TX_DN<7>")
	)
	(segment
		(start 407.929588 -375.244614)
		(end 409.267152 -376.582178)
		(width 0.14224)
		(layer "In13.Cu")
		(net "P5E_CPU0_P2_TX_DN<7>")
	)
	(segment
		(start 367.318036 -284.921452)
		(end 367.370106 -284.951932)
		(width 0.1143)
		(layer "In13.Cu")
		(net "P5E_CPU0_P2_TX_DN<7>")
	)
	(segment
		(start 367.347754 -286.55899)
		(end 367.388902 -286.582866)
		(width 0.1143)
		(layer "In13.Cu")
		(net "P5E_CPU0_P2_TX_DN<7>")
	)
	(segment
		(start 367.817654 -270.523462)
		(end 367.787174 -270.541242)
		(width 0.1143)
		(layer "In13.Cu")
		(net "P5E_CPU0_P2_TX_DN<7>")
	)
	(segment
		(start 367.777268 -295.443402)
		(end 367.787174 -295.451022)
		(width 0.1143)
		(layer "In13.Cu")
		(net "P5E_CPU0_P2_TX_DN<7>")
	)
	(segment
		(start 367.347754 -277.813516)
		(end 367.316004 -277.831804)
		(width 0.1143)
		(layer "In13.Cu")
		(net "P5E_CPU0_P2_TX_DN<7>")
	)
	(segment
		(start 367.347246 -288.178748)
		(end 367.347754 -288.178494)
		(width 0.1143)
		(layer "In13.Cu")
		(net "P5E_CPU0_P2_TX_DN<7>")
	)
	(segment
		(start 367.787174 -295.451022)
		(end 368.017044 -295.680892)
		(width 0.1143)
		(layer "In13.Cu")
		(net "P5E_CPU0_P2_TX_DN<7>")
	)
	(segment
		(start 367.347754 -291.418518)
		(end 367.34877 -291.419026)
		(width 0.1143)
		(layer "In13.Cu")
		(net "P5E_CPU0_P2_TX_DN<7>")
	)
	(segment
		(start 367.38687 -281.03068)
		(end 367.350294 -281.052016)
		(width 0.1143)
		(layer "In13.Cu")
		(net "P5E_CPU0_P2_TX_DN<7>")
	)
	(segment
		(start 409.42514 -376.963432)
		(end 409.42514 -378.01042)
		(width 0.14224)
		(layer "In13.Cu")
		(net "P5E_CPU0_P2_TX_DN<7>")
	)
	(segment
		(start 367.38687 -272.93062)
		(end 367.347754 -272.95348)
		(width 0.1143)
		(layer "In13.Cu")
		(net "P5E_CPU0_P2_TX_DN<7>")
	)
	(segment
		(start 367.316004 -276.820376)
		(end 367.347754 -276.838664)
		(width 0.1143)
		(layer "In13.Cu")
		(net "P5E_CPU0_P2_TX_DN<7>")
	)
	(segment
		(start 367.317782 -281.681428)
		(end 367.386362 -281.721052)
		(width 0.1143)
		(layer "In13.Cu")
		(net "P5E_CPU0_P2_TX_DN<7>")
	)
	(segment
		(start 367.350294 -291.420042)
		(end 367.38687 -291.441378)
		(width 0.1143)
		(layer "In13.Cu")
		(net "P5E_CPU0_P2_TX_DN<7>")
	)
	(segment
		(start 367.34877 -280.079196)
		(end 367.38687 -280.101548)
		(width 0.1143)
		(layer "In13.Cu")
		(net "P5E_CPU0_P2_TX_DN<7>")
	)
	(segment
		(start 367.34877 -292.392862)
		(end 367.347246 -292.393624)
		(width 0.1143)
		(layer "In13.Cu")
		(net "P5E_CPU0_P2_TX_DN<7>")
	)
	(segment
		(start 368.110008 -295.905936)
		(end 368.110008 -296.290746)
		(width 0.1143)
		(layer "In13.Cu")
		(net "P5E_CPU0_P2_TX_DN<7>")
	)
	(segment
		(start 368.20094 -299.023786)
		(end 395.130274 -364.001558)
		(width 0.14224)
		(layer "In13.Cu")
		(net "P5E_CPU0_P2_TX_DN<7>")
	)
	(segment
		(start 367.347246 -291.418518)
		(end 367.347754 -291.418518)
		(width 0.1143)
		(layer "In13.Cu")
		(net "P5E_CPU0_P2_TX_DN<7>")
	)
	(segment
		(start 367.34496 -289.15487)
		(end 367.342928 -289.15614)
		(width 0.1143)
		(layer "In13.Cu")
		(net "P5E_CPU0_P2_TX_DN<7>")
	)
	(segment
		(start 395.130274 -364.001558)
		(end 399.489168 -370.524278)
		(width 0.14224)
		(layer "In13.Cu")
		(net "P5E_CPU0_P2_TX_DN<7>")
	)
	(segment
		(start 403.86 -373.502682)
		(end 407.710132 -375.097548)
		(width 0.14224)
		(layer "In13.Cu")
		(net "P5E_CPU0_P2_TX_DN<7>")
	)
	(segment
		(start 411.12821 -382.0541)
		(end 411.41904 -382.34493)
		(width 0.14224)
		(layer "In13.Cu")
		(net "P5E_CPU0_P2_TX_DN<7>")
	)
	(segment
		(start 367.35639 -293.04361)
		(end 367.386108 -293.060882)
		(width 0.1143)
		(layer "In13.Cu")
		(net "P5E_CPU0_P2_TX_DN<7>")
	)
	(segment
		(start 367.34369 -286.556704)
		(end 367.345976 -286.557974)
		(width 0.1143)
		(layer "In13.Cu")
		(net "P5E_CPU0_P2_TX_DN<7>")
	)
	(segment
		(start 367.316004 -280.0604)
		(end 367.346992 -280.07818)
		(width 0.1143)
		(layer "In13.Cu")
		(net "P5E_CPU0_P2_TX_DN<7>")
	)
	(segment
		(start 367.347246 -286.558736)
		(end 367.347754 -286.55899)
		(width 0.1143)
		(layer "In13.Cu")
		(net "P5E_CPU0_P2_TX_DN<7>")
	)
	(segment
		(start 367.38687 -271.310608)
		(end 367.347754 -271.333468)
		(width 0.1143)
		(layer "In13.Cu")
		(net "P5E_CPU0_P2_TX_DN<7>")
	)
	(segment
		(start 367.347754 -272.95348)
		(end 367.316004 -272.971768)
		(width 0.1143)
		(layer "In13.Cu")
		(net "P5E_CPU0_P2_TX_DN<7>")
	)
	(segment
		(start 367.34877 -281.053032)
		(end 367.347754 -281.05354)
		(width 0.1143)
		(layer "In13.Cu")
		(net "P5E_CPU0_P2_TX_DN<7>")
	)
	(segment
		(start 367.347754 -276.193504)
		(end 367.316004 -276.211792)
		(width 0.1143)
		(layer "In13.Cu")
		(net "P5E_CPU0_P2_TX_DN<7>")
	)
	(segment
		(start 367.38687 -293.990522)
		(end 367.329974 -294.023542)
		(width 0.1143)
		(layer "In13.Cu")
		(net "P5E_CPU0_P2_TX_DN<7>")
	)
	(segment
		(start 367.347754 -278.458676)
		(end 367.38687 -278.481536)
		(width 0.1143)
		(layer "In13.Cu")
		(net "P5E_CPU0_P2_TX_DN<7>")
	)
	(segment
		(start 368.474752 -270.036036)
		(end 368.17681 -270.036036)
		(width 0.1143)
		(layer "In13.Cu")
		(net "P5E_CPU0_P2_TX_DN<7>")
	)
	(segment
		(start 367.38687 -292.37051)
		(end 367.34877 -292.392862)
		(width 0.1143)
		(layer "In13.Cu")
		(net "P5E_CPU0_P2_TX_DN<7>")
	)
	(segment
		(start 367.38687 -276.170644)
		(end 367.347754 -276.193504)
		(width 0.1143)
		(layer "In13.Cu")
		(net "P5E_CPU0_P2_TX_DN<7>")
	)
	(segment
		(start 367.347754 -280.078688)
		(end 367.34877 -280.079196)
		(width 0.1143)
		(layer "In13.Cu")
		(net "P5E_CPU0_P2_TX_DN<7>")
	)
	(segment
		(start 367.34877 -291.419026)
		(end 367.350294 -291.420042)
		(width 0.1143)
		(layer "In13.Cu")
		(net "P5E_CPU0_P2_TX_DN<7>")
	)
	(segment
		(start 367.33988 -293.033958)
		(end 367.354866 -293.042594)
		(width 0.1143)
		(layer "In13.Cu")
		(net "P5E_CPU0_P2_TX_DN<7>")
	)
	(segment
		(start 367.316004 -273.580352)
		(end 367.347754 -273.59864)
		(width 0.1143)
		(layer "In13.Cu")
		(net "P5E_CPU0_P2_TX_DN<7>")
	)
	(segment
		(start 410.47416 -378.636784)
		(end 411.008322 -379.170946)
		(width 0.14224)
		(layer "In13.Cu")
		(net "P5E_CPU0_P2_TX_DN<7>")
	)
	(segment
		(start 367.316004 -275.200364)
		(end 367.347754 -275.218652)
		(width 0.1143)
		(layer "In13.Cu")
		(net "P5E_CPU0_P2_TX_DN<7>")
	)
	(segment
		(start 367.345468 -285.914592)
		(end 367.343944 -285.915608)
		(width 0.1143)
		(layer "In13.Cu")
		(net "P5E_CPU0_P2_TX_DN<7>")
	)
	(segment
		(start 367.350294 -289.80003)
		(end 367.38687 -289.821366)
		(width 0.1143)
		(layer "In13.Cu")
		(net "P5E_CPU0_P2_TX_DN<7>")
	)
	(segment
		(start 367.342674 -289.795712)
		(end 367.347754 -289.798506)
		(width 0.1143)
		(layer "In13.Cu")
		(net "P5E_CPU0_P2_TX_DN<7>")
	)
	(segment
		(start 367.347754 -288.178494)
		(end 367.366042 -288.189162)
		(width 0.1143)
		(layer "In13.Cu")
		(net "P5E_CPU0_P2_TX_DN<7>")
	)
	(segment
		(start 367.350294 -281.052016)
		(end 367.34877 -281.053032)
		(width 0.1143)
		(layer "In13.Cu")
		(net "P5E_CPU0_P2_TX_DN<7>")
	)
	(segment
		(start 367.316004 -278.440388)
		(end 367.347754 -278.458676)
		(width 0.1143)
		(layer "In13.Cu")
		(net "P5E_CPU0_P2_TX_DN<7>")
	)
	(segment
		(start 367.318036 -288.16173)
		(end 367.347246 -288.178748)
		(width 0.1143)
		(layer "In13.Cu")
		(net "P5E_CPU0_P2_TX_DN<7>")
	)
	(arc
		(start 368.094006 -270.11884)
		(mid 368.092218 -270.130289)
		(end 368.090196 -270.1417)
		(width 0.1143)
		(layer "In13.Cu")
		(net "P5E_CPU0_P2_TX_DN<7>")
	)
	(arc
		(start 367.342674 -284.294072)
		(mid 367.160359 -284.601128)
		(end 367.318036 -284.921452)
		(width 0.1143)
		(layer "In13.Cu")
		(net "P5E_CPU0_P2_TX_DN<7>")
	)
	(arc
		(start 367.160048 -287.856168)
		(mid 367.201888 -288.028154)
		(end 367.318036 -288.16173)
		(width 0.1143)
		(layer "In13.Cu")
		(net "P5E_CPU0_P2_TX_DN<7>")
	)
	(arc
		(start 367.38687 -273.6215)
		(mid 367.630197 -274.086066)
		(end 367.38687 -274.550632)
		(width 0.1143)
		(layer "In13.Cu")
		(net "P5E_CPU0_P2_TX_DN<7>")
	)
	(arc
		(start 367.388902 -286.582866)
		(mid 367.566098 -286.784878)
		(end 367.629948 -287.045908)
		(width 0.1143)
		(layer "In13.Cu")
		(net "P5E_CPU0_P2_TX_DN<7>")
	)
	(arc
		(start 367.347246 -290.773612)
		(mid 367.161608 -291.096128)
		(end 367.347246 -291.418518)
		(width 0.1143)
		(layer "In13.Cu")
		(net "P5E_CPU0_P2_TX_DN<7>")
	)
	(arc
		(start 367.38687 -289.821366)
		(mid 367.630197 -290.285932)
		(end 367.38687 -290.750498)
		(width 0.1143)
		(layer "In13.Cu")
		(net "P5E_CPU0_P2_TX_DN<7>")
	)
	(arc
		(start 367.316004 -271.351756)
		(mid 367.164415 -271.656048)
		(end 367.316004 -271.96034)
		(width 0.1143)
		(layer "In13.Cu")
		(net "P5E_CPU0_P2_TX_DN<7>")
	)
	(arc
		(start 367.386362 -281.721052)
		(mid 367.628401 -282.209631)
		(end 367.342674 -282.67406)
		(width 0.1143)
		(layer "In13.Cu")
		(net "P5E_CPU0_P2_TX_DN<7>")
	)
	(arc
		(start 367.38687 -278.481536)
		(mid 367.630197 -278.946102)
		(end 367.38687 -279.410668)
		(width 0.1143)
		(layer "In13.Cu")
		(net "P5E_CPU0_P2_TX_DN<7>")
	)
	(arc
		(start 367.630202 -295.145968)
		(mid 367.669024 -295.311852)
		(end 367.777268 -295.443402)
		(width 0.1143)
		(layer "In13.Cu")
		(net "P5E_CPU0_P2_TX_DN<7>")
	)
	(arc
		(start 367.787174 -270.541242)
		(mid 367.671747 -270.674618)
		(end 367.630202 -270.846042)
		(width 0.1143)
		(layer "In13.Cu")
		(net "P5E_CPU0_P2_TX_DN<7>")
	)
	(arc
		(start 367.38687 -291.441378)
		(mid 367.630197 -291.905944)
		(end 367.38687 -292.37051)
		(width 0.1143)
		(layer "In13.Cu")
		(net "P5E_CPU0_P2_TX_DN<7>")
	)
	(arc
		(start 367.343944 -285.915608)
		(mid 367.160187 -286.236046)
		(end 367.34369 -286.556704)
		(width 0.1143)
		(layer "In13.Cu")
		(net "P5E_CPU0_P2_TX_DN<7>")
	)
	(arc
		(start 367.629948 -287.045908)
		(mid 367.555137 -287.324875)
		(end 367.350802 -287.529016)
		(width 0.1143)
		(layer "In13.Cu")
		(net "P5E_CPU0_P2_TX_DN<7>")
	)
	(arc
		(start 367.342928 -289.15614)
		(mid 367.160079 -289.475817)
		(end 367.342674 -289.795712)
		(width 0.1143)
		(layer "In13.Cu")
		(net "P5E_CPU0_P2_TX_DN<7>")
	)
	(arc
		(start 409.42514 -378.01042)
		(mid 409.452546 -378.136127)
		(end 409.529788 -378.23902)
		(width 0.14224)
		(layer "In13.Cu")
		(net "P5E_CPU0_P2_TX_DN<7>")
	)
	(arc
		(start 367.38687 -272.001488)
		(mid 367.630197 -272.466054)
		(end 367.38687 -272.93062)
		(width 0.1143)
		(layer "In13.Cu")
		(net "P5E_CPU0_P2_TX_DN<7>")
	)
	(arc
		(start 368.017044 -295.680892)
		(mid 368.085898 -295.784172)
		(end 368.110008 -295.905936)
		(width 0.1143)
		(layer "In13.Cu")
		(net "P5E_CPU0_P2_TX_DN<7>")
	)
	(arc
		(start 367.386108 -293.060882)
		(mid 367.386489 -293.061136)
		(end 367.38687 -293.06139)
		(width 0.1143)
		(layer "In13.Cu")
		(net "P5E_CPU0_P2_TX_DN<7>")
	)
	(arc
		(start 409.529788 -378.23902)
		(mid 409.844005 -378.43247)
		(end 410.203142 -378.51715)
		(width 0.14224)
		(layer "In13.Cu")
		(net "P5E_CPU0_P2_TX_DN<7>")
	)
	(arc
		(start 407.710132 -375.097548)
		(mid 407.827065 -375.160334)
		(end 407.929588 -375.244614)
		(width 0.14224)
		(layer "In13.Cu")
		(net "P5E_CPU0_P2_TX_DN<7>")
	)
	(arc
		(start 367.342674 -282.67406)
		(mid 367.160363 -282.981013)
		(end 367.317782 -283.30144)
		(width 0.1143)
		(layer "In13.Cu")
		(net "P5E_CPU0_P2_TX_DN<7>")
	)
	(arc
		(start 411.008322 -379.170946)
		(mid 411.097037 -379.303811)
		(end 411.12821 -379.460506)
		(width 0.14224)
		(layer "In13.Cu")
		(net "P5E_CPU0_P2_TX_DN<7>")
	)
	(arc
		(start 367.38687 -294.681402)
		(mid 367.565683 -294.883752)
		(end 367.630202 -295.145968)
		(width 0.1143)
		(layer "In13.Cu")
		(net "P5E_CPU0_P2_TX_DN<7>")
	)
	(arc
		(start 367.386108 -294.680894)
		(mid 367.386489 -294.681148)
		(end 367.38687 -294.681402)
		(width 0.1143)
		(layer "In13.Cu")
		(net "P5E_CPU0_P2_TX_DN<7>")
	)
	(arc
		(start 367.38687 -288.201354)
		(mid 367.630197 -288.66592)
		(end 367.38687 -289.130486)
		(width 0.1143)
		(layer "In13.Cu")
		(net "P5E_CPU0_P2_TX_DN<7>")
	)
	(arc
		(start 367.370106 -284.951932)
		(mid 367.642493 -285.42689)
		(end 367.368836 -285.90113)
		(width 0.1143)
		(layer "In13.Cu")
		(net "P5E_CPU0_P2_TX_DN<7>")
	)
	(arc
		(start 367.316004 -277.831804)
		(mid 367.164415 -278.136096)
		(end 367.316004 -278.440388)
		(width 0.1143)
		(layer "In13.Cu")
		(net "P5E_CPU0_P2_TX_DN<7>")
	)
	(arc
		(start 409.267152 -376.582178)
		(mid 409.384084 -376.757085)
		(end 409.42514 -376.963432)
		(width 0.14224)
		(layer "In13.Cu")
		(net "P5E_CPU0_P2_TX_DN<7>")
	)
	(arc
		(start 367.316004 -274.59178)
		(mid 367.164415 -274.896072)
		(end 367.316004 -275.200364)
		(width 0.1143)
		(layer "In13.Cu")
		(net "P5E_CPU0_P2_TX_DN<7>")
	)
	(arc
		(start 367.329974 -294.023542)
		(mid 367.150087 -294.335852)
		(end 367.32972 -294.648382)
		(width 0.1143)
		(layer "In13.Cu")
		(net "P5E_CPU0_P2_TX_DN<7>")
	)
	(arc
		(start 367.38687 -276.861524)
		(mid 367.630197 -277.32609)
		(end 367.38687 -277.790656)
		(width 0.1143)
		(layer "In13.Cu")
		(net "P5E_CPU0_P2_TX_DN<7>")
	)
	(arc
		(start 367.347246 -292.393624)
		(mid 367.161726 -292.711681)
		(end 367.33988 -293.033958)
		(width 0.1143)
		(layer "In13.Cu")
		(net "P5E_CPU0_P2_TX_DN<7>")
	)
	(arc
		(start 367.346738 -287.531556)
		(mid 367.21008 -287.668958)
		(end 367.160048 -287.856168)
		(width 0.1143)
		(layer "In13.Cu")
		(net "P5E_CPU0_P2_TX_DN<7>")
	)
	(arc
		(start 403.766274 -373.452644)
		(mid 403.811929 -373.479927)
		(end 403.86 -373.502682)
		(width 0.14224)
		(layer "In13.Cu")
		(net "P5E_CPU0_P2_TX_DN<7>")
	)
	(arc
		(start 367.346484 -281.054048)
		(mid 367.161141 -281.359869)
		(end 367.317782 -281.681428)
		(width 0.1143)
		(layer "In13.Cu")
		(net "P5E_CPU0_P2_TX_DN<7>")
	)
	(arc
		(start 410.203142 -378.51715)
		(mid 410.349829 -378.551633)
		(end 410.47416 -378.636784)
		(width 0.14224)
		(layer "In13.Cu")
		(net "P5E_CPU0_P2_TX_DN<7>")
	)
	(arc
		(start 367.386362 -283.341064)
		(mid 367.628401 -283.829643)
		(end 367.342674 -284.294072)
		(width 0.1143)
		(layer "In13.Cu")
		(net "P5E_CPU0_P2_TX_DN<7>")
	)
	(arc
		(start 367.630202 -270.846042)
		(mid 367.565687 -271.108261)
		(end 367.38687 -271.310608)
		(width 0.1143)
		(layer "In13.Cu")
		(net "P5E_CPU0_P2_TX_DN<7>")
	)
	(arc
		(start 367.316004 -279.451816)
		(mid 367.164415 -279.756108)
		(end 367.316004 -280.0604)
		(width 0.1143)
		(layer "In13.Cu")
		(net "P5E_CPU0_P2_TX_DN<7>")
	)
	(arc
		(start 368.155728 -298.795948)
		(mid 368.1671 -298.912094)
		(end 368.20094 -299.023786)
		(width 0.14224)
		(layer "In13.Cu")
		(net "P5E_CPU0_P2_TX_DN<7>")
	)
	(arc
		(start 367.38687 -275.241512)
		(mid 367.630197 -275.706078)
		(end 367.38687 -276.170644)
		(width 0.1143)
		(layer "In13.Cu")
		(net "P5E_CPU0_P2_TX_DN<7>")
	)
	(arc
		(start 399.489168 -370.524278)
		(mid 399.584428 -370.640346)
		(end 399.700496 -370.735606)
		(width 0.14224)
		(layer "In13.Cu")
		(net "P5E_CPU0_P2_TX_DN<7>")
	)
	(arc
		(start 367.38687 -293.06139)
		(mid 367.630197 -293.525956)
		(end 367.38687 -293.990522)
		(width 0.1143)
		(layer "In13.Cu")
		(net "P5E_CPU0_P2_TX_DN<7>")
	)
	(arc
		(start 367.316004 -272.971768)
		(mid 367.164415 -273.27606)
		(end 367.316004 -273.580352)
		(width 0.1143)
		(layer "In13.Cu")
		(net "P5E_CPU0_P2_TX_DN<7>")
	)
	(arc
		(start 367.316004 -276.211792)
		(mid 367.164415 -276.516084)
		(end 367.316004 -276.820376)
		(width 0.1143)
		(layer "In13.Cu")
		(net "P5E_CPU0_P2_TX_DN<7>")
	)
	(arc
		(start 368.090196 -270.1417)
		(mid 368.008763 -270.344098)
		(end 367.85677 -270.500602)
		(width 0.1143)
		(layer "In13.Cu")
		(net "P5E_CPU0_P2_TX_DN<7>")
	)
	(arc
		(start 367.38687 -280.101548)
		(mid 367.630197 -280.566114)
		(end 367.38687 -281.03068)
		(width 0.1143)
		(layer "In13.Cu")
		(net "P5E_CPU0_P2_TX_DN<7>")
	)
	(segment
		(start 407.74493 -377.68784)
		(end 407.74493 -378.39142)
		(width 0.12954)
		(layer "F.Cu")
		(net "P5E_CPU0_P2_TX_DN<6>")
	)
	(segment
		(start 408.01544 -377.41733)
		(end 407.74493 -377.68784)
		(width 0.12954)
		(layer "F.Cu")
		(net "P5E_CPU0_P2_TX_DN<6>")
	)
	(segment
		(start 365.187992 -271.39011)
		(end 365.654844 -271.656048)
		(width 0.12954)
		(layer "F.Cu")
		(net "P5E_CPU0_P2_TX_DN<6>")
	)
	(segment
		(start 407.74493 -378.39142)
		(end 408.04084 -378.68733)
		(width 0.12954)
		(layer "F.Cu")
		(net "P5E_CPU0_P2_TX_DN<6>")
	)
	(segment
		(start 366.37722 -289.780726)
		(end 366.4077 -289.798506)
		(width 0.1143)
		(layer "In13.Cu")
		(net "P5E_CPU0_P2_TX_DN<6>")
	)
	(segment
		(start 366.4077 -294.658542)
		(end 366.446816 -294.681402)
		(width 0.1143)
		(layer "In13.Cu")
		(net "P5E_CPU0_P2_TX_DN<6>")
	)
	(segment
		(start 366.4077 -289.798506)
		(end 366.446816 -289.821366)
		(width 0.1143)
		(layer "In13.Cu")
		(net "P5E_CPU0_P2_TX_DN<6>")
	)
	(segment
		(start 365.9378 -272.788634)
		(end 365.976916 -272.811494)
		(width 0.1143)
		(layer "In13.Cu")
		(net "P5E_CPU0_P2_TX_DN<6>")
	)
	(segment
		(start 365.467646 -271.978628)
		(end 365.506762 -272.001488)
		(width 0.1143)
		(layer "In13.Cu")
		(net "P5E_CPU0_P2_TX_DN<6>")
	)
	(segment
		(start 365.90605 -272.770346)
		(end 365.937038 -272.788126)
		(width 0.1143)
		(layer "In13.Cu")
		(net "P5E_CPU0_P2_TX_DN<6>")
	)
	(segment
		(start 366.4077 -275.218652)
		(end 366.446816 -275.241512)
		(width 0.1143)
		(layer "In13.Cu")
		(net "P5E_CPU0_P2_TX_DN<6>")
	)
	(segment
		(start 366.4077 -278.458676)
		(end 366.446816 -278.481536)
		(width 0.1143)
		(layer "In13.Cu")
		(net "P5E_CPU0_P2_TX_DN<6>")
	)
	(segment
		(start 366.4077 -276.838664)
		(end 366.446816 -276.861524)
		(width 0.1143)
		(layer "In13.Cu")
		(net "P5E_CPU0_P2_TX_DN<6>")
	)
	(segment
		(start 366.37722 -293.02075)
		(end 366.4077 -293.03853)
		(width 0.1143)
		(layer "In13.Cu")
		(net "P5E_CPU0_P2_TX_DN<6>")
	)
	(segment
		(start 367.160302 -295.955974)
		(end 367.160048 -295.956228)
		(width 0.1143)
		(layer "In13.Cu")
		(net "P5E_CPU0_P2_TX_DN<6>")
	)
	(segment
		(start 366.37722 -273.58086)
		(end 366.4077 -273.59864)
		(width 0.1143)
		(layer "In13.Cu")
		(net "P5E_CPU0_P2_TX_DN<6>")
	)
	(segment
		(start 366.4077 -292.39337)
		(end 366.37722 -292.41115)
		(width 0.1143)
		(layer "In13.Cu")
		(net "P5E_CPU0_P2_TX_DN<6>")
	)
	(segment
		(start 366.446816 -293.990522)
		(end 366.4077 -294.013382)
		(width 0.1143)
		(layer "In13.Cu")
		(net "P5E_CPU0_P2_TX_DN<6>")
	)
	(segment
		(start 366.446816 -284.270704)
		(end 366.4077 -284.293564)
		(width 0.1143)
		(layer "In13.Cu")
		(net "P5E_CPU0_P2_TX_DN<6>")
	)
	(segment
		(start 366.446816 -290.750498)
		(end 366.4077 -290.773358)
		(width 0.1143)
		(layer "In13.Cu")
		(net "P5E_CPU0_P2_TX_DN<6>")
	)
	(segment
		(start 366.846104 -295.45026)
		(end 366.877092 -295.46804)
		(width 0.1143)
		(layer "In13.Cu")
		(net "P5E_CPU0_P2_TX_DN<6>")
	)
	(segment
		(start 407.72461 -376.410474)
		(end 407.72461 -377.1265)
		(width 0.14224)
		(layer "In13.Cu")
		(net "P5E_CPU0_P2_TX_DN<6>")
	)
	(segment
		(start 407.72461 -377.1265)
		(end 408.01544 -377.41733)
		(width 0.14224)
		(layer "In13.Cu")
		(net "P5E_CPU0_P2_TX_DN<6>")
	)
	(segment
		(start 366.4077 -273.59864)
		(end 366.446816 -273.6215)
		(width 0.1143)
		(layer "In13.Cu")
		(net "P5E_CPU0_P2_TX_DN<6>")
	)
	(segment
		(start 366.446816 -277.790656)
		(end 366.4077 -277.813516)
		(width 0.1143)
		(layer "In13.Cu")
		(net "P5E_CPU0_P2_TX_DN<6>")
	)
	(segment
		(start 366.4077 -288.178494)
		(end 366.446816 -288.201354)
		(width 0.1143)
		(layer "In13.Cu")
		(net "P5E_CPU0_P2_TX_DN<6>")
	)
	(segment
		(start 403.34311 -374.301004)
		(end 407.22169 -375.907554)
		(width 0.14224)
		(layer "In13.Cu")
		(net "P5E_CPU0_P2_TX_DN<6>")
	)
	(segment
		(start 366.4077 -274.573492)
		(end 366.37722 -274.591272)
		(width 0.1143)
		(layer "In13.Cu")
		(net "P5E_CPU0_P2_TX_DN<6>")
	)
	(segment
		(start 366.4077 -277.813516)
		(end 366.37722 -277.831296)
		(width 0.1143)
		(layer "In13.Cu")
		(net "P5E_CPU0_P2_TX_DN<6>")
	)
	(segment
		(start 366.877854 -295.468548)
		(end 366.91697 -295.491408)
		(width 0.1143)
		(layer "In13.Cu")
		(net "P5E_CPU0_P2_TX_DN<6>")
	)
	(segment
		(start 366.446816 -292.37051)
		(end 366.4077 -292.39337)
		(width 0.1143)
		(layer "In13.Cu")
		(net "P5E_CPU0_P2_TX_DN<6>")
	)
	(segment
		(start 366.446816 -276.170644)
		(end 366.4077 -276.193504)
		(width 0.1143)
		(layer "In13.Cu")
		(net "P5E_CPU0_P2_TX_DN<6>")
	)
	(segment
		(start 366.444276 -287.512252)
		(end 366.37722 -287.551368)
		(width 0.1143)
		(layer "In13.Cu")
		(net "P5E_CPU0_P2_TX_DN<6>")
	)
	(segment
		(start 365.437166 -271.960848)
		(end 365.467646 -271.978628)
		(width 0.1143)
		(layer "In13.Cu")
		(net "P5E_CPU0_P2_TX_DN<6>")
	)
	(segment
		(start 366.37722 -278.440896)
		(end 366.4077 -278.458676)
		(width 0.1143)
		(layer "In13.Cu")
		(net "P5E_CPU0_P2_TX_DN<6>")
	)
	(segment
		(start 367.205768 -296.314114)
		(end 367.205768 -296.342562)
		(width 0.1143)
		(layer "In13.Cu")
		(net "P5E_CPU0_P2_TX_DN<6>")
	)
	(segment
		(start 366.4077 -283.318712)
		(end 366.446816 -283.341572)
		(width 0.1143)
		(layer "In13.Cu")
		(net "P5E_CPU0_P2_TX_DN<6>")
	)
	(segment
		(start 366.4077 -291.418518)
		(end 366.446816 -291.441378)
		(width 0.1143)
		(layer "In13.Cu")
		(net "P5E_CPU0_P2_TX_DN<6>")
	)
	(segment
		(start 365.937038 -272.788126)
		(end 365.9378 -272.788634)
		(width 0.1143)
		(layer "In13.Cu")
		(net "P5E_CPU0_P2_TX_DN<6>")
	)
	(segment
		(start 366.37722 -276.820884)
		(end 366.4077 -276.838664)
		(width 0.1143)
		(layer "In13.Cu")
		(net "P5E_CPU0_P2_TX_DN<6>")
	)
	(segment
		(start 366.37722 -275.200872)
		(end 366.4077 -275.218652)
		(width 0.1143)
		(layer "In13.Cu")
		(net "P5E_CPU0_P2_TX_DN<6>")
	)
	(segment
		(start 366.446816 -279.410668)
		(end 366.4077 -279.433528)
		(width 0.1143)
		(layer "In13.Cu")
		(net "P5E_CPU0_P2_TX_DN<6>")
	)
	(segment
		(start 366.375188 -286.539686)
		(end 366.4077 -286.558482)
		(width 0.1143)
		(layer "In13.Cu")
		(net "P5E_CPU0_P2_TX_DN<6>")
	)
	(segment
		(start 366.446816 -289.130486)
		(end 366.4077 -289.153346)
		(width 0.1143)
		(layer "In13.Cu")
		(net "P5E_CPU0_P2_TX_DN<6>")
	)
	(segment
		(start 366.37722 -283.300932)
		(end 366.4077 -283.318712)
		(width 0.1143)
		(layer "In13.Cu")
		(net "P5E_CPU0_P2_TX_DN<6>")
	)
	(segment
		(start 366.4077 -281.05354)
		(end 366.37722 -281.07132)
		(width 0.1143)
		(layer "In13.Cu")
		(net "P5E_CPU0_P2_TX_DN<6>")
	)
	(segment
		(start 366.4077 -289.153346)
		(end 366.37722 -289.171126)
		(width 0.1143)
		(layer "In13.Cu")
		(net "P5E_CPU0_P2_TX_DN<6>")
	)
	(segment
		(start 367.21542 -299.09897)
		(end 394.37437 -364.638336)
		(width 0.14224)
		(layer "In13.Cu")
		(net "P5E_CPU0_P2_TX_DN<6>")
	)
	(segment
		(start 398.960086 -371.372892)
		(end 403.34311 -374.301004)
		(width 0.14224)
		(layer "In13.Cu")
		(net "P5E_CPU0_P2_TX_DN<6>")
	)
	(segment
		(start 366.4077 -293.03853)
		(end 366.446816 -293.06139)
		(width 0.1143)
		(layer "In13.Cu")
		(net "P5E_CPU0_P2_TX_DN<6>")
	)
	(segment
		(start 366.877092 -295.46804)
		(end 366.877854 -295.468548)
		(width 0.1143)
		(layer "In13.Cu")
		(net "P5E_CPU0_P2_TX_DN<6>")
	)
	(segment
		(start 366.4077 -284.938724)
		(end 366.446816 -284.961584)
		(width 0.1143)
		(layer "In13.Cu")
		(net "P5E_CPU0_P2_TX_DN<6>")
	)
	(segment
		(start 366.4077 -286.558482)
		(end 366.446816 -286.581342)
		(width 0.1143)
		(layer "In13.Cu")
		(net "P5E_CPU0_P2_TX_DN<6>")
	)
	(segment
		(start 366.37722 -294.640762)
		(end 366.4077 -294.658542)
		(width 0.1143)
		(layer "In13.Cu")
		(net "P5E_CPU0_P2_TX_DN<6>")
	)
	(segment
		(start 366.37722 -284.920944)
		(end 366.4077 -284.938724)
		(width 0.1143)
		(layer "In13.Cu")
		(net "P5E_CPU0_P2_TX_DN<6>")
	)
	(segment
		(start 394.37437 -364.638336)
		(end 398.700498 -371.113304)
		(width 0.14224)
		(layer "In13.Cu")
		(net "P5E_CPU0_P2_TX_DN<6>")
	)
	(segment
		(start 367.160048 -296.268394)
		(end 367.205768 -296.314114)
		(width 0.1143)
		(layer "In13.Cu")
		(net "P5E_CPU0_P2_TX_DN<6>")
	)
	(segment
		(start 366.4077 -280.078688)
		(end 366.446816 -280.101548)
		(width 0.1143)
		(layer "In13.Cu")
		(net "P5E_CPU0_P2_TX_DN<6>")
	)
	(segment
		(start 366.375188 -288.159698)
		(end 366.4077 -288.178494)
		(width 0.1143)
		(layer "In13.Cu")
		(net "P5E_CPU0_P2_TX_DN<6>")
	)
	(segment
		(start 367.160048 -295.956228)
		(end 367.160048 -296.268394)
		(width 0.1143)
		(layer "In13.Cu")
		(net "P5E_CPU0_P2_TX_DN<6>")
	)
	(segment
		(start 365.654844 -271.656048)
		(end 365.356902 -271.656048)
		(width 0.1143)
		(layer "In13.Cu")
		(net "P5E_CPU0_P2_TX_DN<6>")
	)
	(segment
		(start 366.446816 -281.03068)
		(end 366.4077 -281.05354)
		(width 0.1143)
		(layer "In13.Cu")
		(net "P5E_CPU0_P2_TX_DN<6>")
	)
	(segment
		(start 366.4077 -294.013382)
		(end 366.37722 -294.031162)
		(width 0.1143)
		(layer "In13.Cu")
		(net "P5E_CPU0_P2_TX_DN<6>")
	)
	(segment
		(start 366.4077 -285.913576)
		(end 366.37722 -285.931356)
		(width 0.1143)
		(layer "In13.Cu")
		(net "P5E_CPU0_P2_TX_DN<6>")
	)
	(segment
		(start 366.446816 -282.650692)
		(end 366.4077 -282.673552)
		(width 0.1143)
		(layer "In13.Cu")
		(net "P5E_CPU0_P2_TX_DN<6>")
	)
	(segment
		(start 366.4077 -281.6987)
		(end 366.446816 -281.72156)
		(width 0.1143)
		(layer "In13.Cu")
		(net "P5E_CPU0_P2_TX_DN<6>")
	)
	(segment
		(start 367.205768 -296.342562)
		(end 367.205768 -299.050202)
		(width 0.14224)
		(layer "In13.Cu")
		(net "P5E_CPU0_P2_TX_DN<6>")
	)
	(segment
		(start 365.356902 -271.656048)
		(end 365.287052 -271.725898)
		(width 0.1143)
		(layer "In13.Cu")
		(net "P5E_CPU0_P2_TX_DN<6>")
	)
	(segment
		(start 366.37722 -281.68092)
		(end 366.4077 -281.6987)
		(width 0.1143)
		(layer "In13.Cu")
		(net "P5E_CPU0_P2_TX_DN<6>")
	)
	(segment
		(start 366.4077 -279.433528)
		(end 366.37722 -279.451308)
		(width 0.1143)
		(layer "In13.Cu")
		(net "P5E_CPU0_P2_TX_DN<6>")
	)
	(segment
		(start 407.22169 -375.907554)
		(end 407.72461 -376.410474)
		(width 0.14224)
		(layer "In13.Cu")
		(net "P5E_CPU0_P2_TX_DN<6>")
	)
	(segment
		(start 366.4077 -290.773358)
		(end 366.37722 -290.791138)
		(width 0.1143)
		(layer "In13.Cu")
		(net "P5E_CPU0_P2_TX_DN<6>")
	)
	(segment
		(start 366.446816 -274.550632)
		(end 366.4077 -274.573492)
		(width 0.1143)
		(layer "In13.Cu")
		(net "P5E_CPU0_P2_TX_DN<6>")
	)
	(segment
		(start 366.37722 -280.060908)
		(end 366.4077 -280.078688)
		(width 0.1143)
		(layer "In13.Cu")
		(net "P5E_CPU0_P2_TX_DN<6>")
	)
	(segment
		(start 366.4077 -284.293564)
		(end 366.37722 -284.311344)
		(width 0.1143)
		(layer "In13.Cu")
		(net "P5E_CPU0_P2_TX_DN<6>")
	)
	(segment
		(start 366.37722 -291.400738)
		(end 366.4077 -291.418518)
		(width 0.1143)
		(layer "In13.Cu")
		(net "P5E_CPU0_P2_TX_DN<6>")
	)
	(segment
		(start 366.4077 -276.193504)
		(end 366.37722 -276.211284)
		(width 0.1143)
		(layer "In13.Cu")
		(net "P5E_CPU0_P2_TX_DN<6>")
	)
	(segment
		(start 366.4077 -282.673552)
		(end 366.37722 -282.691332)
		(width 0.1143)
		(layer "In13.Cu")
		(net "P5E_CPU0_P2_TX_DN<6>")
	)
	(segment
		(start 366.446816 -285.890716)
		(end 366.4077 -285.913576)
		(width 0.1143)
		(layer "In13.Cu")
		(net "P5E_CPU0_P2_TX_DN<6>")
	)
	(arc
		(start 366.446816 -273.6215)
		(mid 366.690143 -274.086066)
		(end 366.446816 -274.550632)
		(width 0.1143)
		(layer "In13.Cu")
		(net "P5E_CPU0_P2_TX_DN<6>")
	)
	(arc
		(start 366.37722 -279.451308)
		(mid 366.220243 -279.756108)
		(end 366.37722 -280.060908)
		(width 0.1143)
		(layer "In13.Cu")
		(net "P5E_CPU0_P2_TX_DN<6>")
	)
	(arc
		(start 366.446816 -278.481536)
		(mid 366.690143 -278.946102)
		(end 366.446816 -279.410668)
		(width 0.1143)
		(layer "In13.Cu")
		(net "P5E_CPU0_P2_TX_DN<6>")
	)
	(arc
		(start 366.37722 -290.791138)
		(mid 366.220243 -291.095938)
		(end 366.37722 -291.400738)
		(width 0.1143)
		(layer "In13.Cu")
		(net "P5E_CPU0_P2_TX_DN<6>")
	)
	(arc
		(start 366.37722 -285.931356)
		(mid 366.261793 -286.064732)
		(end 366.220248 -286.236156)
		(width 0.1143)
		(layer "In13.Cu")
		(net "P5E_CPU0_P2_TX_DN<6>")
	)
	(arc
		(start 367.205768 -299.050202)
		(mid 367.208166 -299.075069)
		(end 367.21542 -299.09897)
		(width 0.14224)
		(layer "In13.Cu")
		(net "P5E_CPU0_P2_TX_DN<6>")
	)
	(arc
		(start 366.446816 -293.06139)
		(mid 366.690143 -293.525956)
		(end 366.446816 -293.990522)
		(width 0.1143)
		(layer "In13.Cu")
		(net "P5E_CPU0_P2_TX_DN<6>")
	)
	(arc
		(start 366.446816 -283.341572)
		(mid 366.690143 -283.806138)
		(end 366.446816 -284.270704)
		(width 0.1143)
		(layer "In13.Cu")
		(net "P5E_CPU0_P2_TX_DN<6>")
	)
	(arc
		(start 366.37722 -274.591272)
		(mid 366.220243 -274.896072)
		(end 366.37722 -275.200872)
		(width 0.1143)
		(layer "In13.Cu")
		(net "P5E_CPU0_P2_TX_DN<6>")
	)
	(arc
		(start 366.37722 -277.831296)
		(mid 366.220243 -278.136096)
		(end 366.37722 -278.440896)
		(width 0.1143)
		(layer "In13.Cu")
		(net "P5E_CPU0_P2_TX_DN<6>")
	)
	(arc
		(start 366.37722 -276.211284)
		(mid 366.220243 -276.516084)
		(end 366.37722 -276.820884)
		(width 0.1143)
		(layer "In13.Cu")
		(net "P5E_CPU0_P2_TX_DN<6>")
	)
	(arc
		(start 366.690148 -287.045908)
		(mid 366.624912 -287.309499)
		(end 366.444276 -287.512252)
		(width 0.1143)
		(layer "In13.Cu")
		(net "P5E_CPU0_P2_TX_DN<6>")
	)
	(arc
		(start 366.37722 -287.551368)
		(mid 366.261793 -287.684744)
		(end 366.220248 -287.856168)
		(width 0.1143)
		(layer "In13.Cu")
		(net "P5E_CPU0_P2_TX_DN<6>")
	)
	(arc
		(start 366.37722 -289.171126)
		(mid 366.220243 -289.475926)
		(end 366.37722 -289.780726)
		(width 0.1143)
		(layer "In13.Cu")
		(net "P5E_CPU0_P2_TX_DN<6>")
	)
	(arc
		(start 366.91697 -295.491408)
		(mid 367.095783 -295.693758)
		(end 367.160302 -295.955974)
		(width 0.1143)
		(layer "In13.Cu")
		(net "P5E_CPU0_P2_TX_DN<6>")
	)
	(arc
		(start 366.37722 -281.07132)
		(mid 366.220243 -281.37612)
		(end 366.37722 -281.68092)
		(width 0.1143)
		(layer "In13.Cu")
		(net "P5E_CPU0_P2_TX_DN<6>")
	)
	(arc
		(start 366.446816 -291.441378)
		(mid 366.690143 -291.905944)
		(end 366.446816 -292.37051)
		(width 0.1143)
		(layer "In13.Cu")
		(net "P5E_CPU0_P2_TX_DN<6>")
	)
	(arc
		(start 366.446816 -294.681402)
		(mid 366.625629 -294.883752)
		(end 366.690148 -295.145968)
		(width 0.1143)
		(layer "In13.Cu")
		(net "P5E_CPU0_P2_TX_DN<6>")
	)
	(arc
		(start 365.287052 -271.725898)
		(mid 365.339469 -271.857829)
		(end 365.437166 -271.960848)
		(width 0.1143)
		(layer "In13.Cu")
		(net "P5E_CPU0_P2_TX_DN<6>")
	)
	(arc
		(start 366.37722 -282.691332)
		(mid 366.220243 -282.996132)
		(end 366.37722 -283.300932)
		(width 0.1143)
		(layer "In13.Cu")
		(net "P5E_CPU0_P2_TX_DN<6>")
	)
	(arc
		(start 366.690148 -295.145968)
		(mid 366.731403 -295.316939)
		(end 366.846104 -295.45026)
		(width 0.1143)
		(layer "In13.Cu")
		(net "P5E_CPU0_P2_TX_DN<6>")
	)
	(arc
		(start 365.506762 -272.001488)
		(mid 365.685575 -272.203838)
		(end 365.750094 -272.466054)
		(width 0.1143)
		(layer "In13.Cu")
		(net "P5E_CPU0_P2_TX_DN<6>")
	)
	(arc
		(start 366.446816 -288.201354)
		(mid 366.690143 -288.66592)
		(end 366.446816 -289.130486)
		(width 0.1143)
		(layer "In13.Cu")
		(net "P5E_CPU0_P2_TX_DN<6>")
	)
	(arc
		(start 365.750094 -272.466054)
		(mid 365.791349 -272.637025)
		(end 365.90605 -272.770346)
		(width 0.1143)
		(layer "In13.Cu")
		(net "P5E_CPU0_P2_TX_DN<6>")
	)
	(arc
		(start 366.446816 -284.961584)
		(mid 366.690143 -285.42615)
		(end 366.446816 -285.890716)
		(width 0.1143)
		(layer "In13.Cu")
		(net "P5E_CPU0_P2_TX_DN<6>")
	)
	(arc
		(start 366.446816 -281.72156)
		(mid 366.690143 -282.186126)
		(end 366.446816 -282.650692)
		(width 0.1143)
		(layer "In13.Cu")
		(net "P5E_CPU0_P2_TX_DN<6>")
	)
	(arc
		(start 366.37722 -284.311344)
		(mid 366.220243 -284.616144)
		(end 366.37722 -284.920944)
		(width 0.1143)
		(layer "In13.Cu")
		(net "P5E_CPU0_P2_TX_DN<6>")
	)
	(arc
		(start 398.700498 -371.113304)
		(mid 398.817499 -371.255891)
		(end 398.960086 -371.372892)
		(width 0.14224)
		(layer "In13.Cu")
		(net "P5E_CPU0_P2_TX_DN<6>")
	)
	(arc
		(start 366.446816 -280.101548)
		(mid 366.690143 -280.566114)
		(end 366.446816 -281.03068)
		(width 0.1143)
		(layer "In13.Cu")
		(net "P5E_CPU0_P2_TX_DN<6>")
	)
	(arc
		(start 366.37722 -292.41115)
		(mid 366.220243 -292.71595)
		(end 366.37722 -293.02075)
		(width 0.1143)
		(layer "In13.Cu")
		(net "P5E_CPU0_P2_TX_DN<6>")
	)
	(arc
		(start 366.446816 -276.861524)
		(mid 366.690143 -277.32609)
		(end 366.446816 -277.790656)
		(width 0.1143)
		(layer "In13.Cu")
		(net "P5E_CPU0_P2_TX_DN<6>")
	)
	(arc
		(start 366.220248 -287.856168)
		(mid 366.261214 -288.026574)
		(end 366.375188 -288.159698)
		(width 0.1143)
		(layer "In13.Cu")
		(net "P5E_CPU0_P2_TX_DN<6>")
	)
	(arc
		(start 366.220248 -286.236156)
		(mid 366.261214 -286.406562)
		(end 366.375188 -286.539686)
		(width 0.1143)
		(layer "In13.Cu")
		(net "P5E_CPU0_P2_TX_DN<6>")
	)
	(arc
		(start 366.446816 -275.241512)
		(mid 366.690143 -275.706078)
		(end 366.446816 -276.170644)
		(width 0.1143)
		(layer "In13.Cu")
		(net "P5E_CPU0_P2_TX_DN<6>")
	)
	(arc
		(start 365.976916 -272.811494)
		(mid 366.155729 -273.013844)
		(end 366.220248 -273.27606)
		(width 0.1143)
		(layer "In13.Cu")
		(net "P5E_CPU0_P2_TX_DN<6>")
	)
	(arc
		(start 366.446816 -286.581342)
		(mid 366.625629 -286.783692)
		(end 366.690148 -287.045908)
		(width 0.1143)
		(layer "In13.Cu")
		(net "P5E_CPU0_P2_TX_DN<6>")
	)
	(arc
		(start 366.37722 -294.031162)
		(mid 366.220243 -294.335962)
		(end 366.37722 -294.640762)
		(width 0.1143)
		(layer "In13.Cu")
		(net "P5E_CPU0_P2_TX_DN<6>")
	)
	(arc
		(start 366.446816 -289.821366)
		(mid 366.690143 -290.285932)
		(end 366.446816 -290.750498)
		(width 0.1143)
		(layer "In13.Cu")
		(net "P5E_CPU0_P2_TX_DN<6>")
	)
	(arc
		(start 366.220248 -273.27606)
		(mid 366.261797 -273.447482)
		(end 366.37722 -273.58086)
		(width 0.1143)
		(layer "In13.Cu")
		(net "P5E_CPU0_P2_TX_DN<6>")
	)
	(segment
		(start 365.187992 -273.010122)
		(end 365.654844 -273.27606)
		(width 0.12954)
		(layer "F.Cu")
		(net "P5E_CPU0_P2_TX_DN<5>")
	)
	(segment
		(start 406.31364 -379.88113)
		(end 406.04313 -380.15164)
		(width 0.12954)
		(layer "F.Cu")
		(net "P5E_CPU0_P2_TX_DN<5>")
	)
	(segment
		(start 406.04313 -380.85522)
		(end 406.33904 -381.15113)
		(width 0.12954)
		(layer "F.Cu")
		(net "P5E_CPU0_P2_TX_DN<5>")
	)
	(segment
		(start 406.04313 -380.15164)
		(end 406.04313 -380.85522)
		(width 0.12954)
		(layer "F.Cu")
		(net "P5E_CPU0_P2_TX_DN<5>")
	)
	(segment
		(start 365.467646 -280.078688)
		(end 365.506762 -280.101548)
		(width 0.1143)
		(layer "In13.Cu")
		(net "P5E_CPU0_P2_TX_DN<5>")
	)
	(segment
		(start 366.207802 -295.878504)
		(end 366.207802 -296.413174)
		(width 0.1143)
		(layer "In13.Cu")
		(net "P5E_CPU0_P2_TX_DN<5>")
	)
	(segment
		(start 365.519462 -287.501584)
		(end 365.508032 -287.51022)
		(width 0.1143)
		(layer "In13.Cu")
		(net "P5E_CPU0_P2_TX_DN<5>")
	)
	(segment
		(start 365.73841 -295.129204)
		(end 365.73841 -295.224708)
		(width 0.1143)
		(layer "In13.Cu")
		(net "P5E_CPU0_P2_TX_DN<5>")
	)
	(segment
		(start 365.4679 -288.178494)
		(end 365.470948 -288.180272)
		(width 0.1143)
		(layer "In13.Cu")
		(net "P5E_CPU0_P2_TX_DN<5>")
	)
	(segment
		(start 406.02281 -377.064778)
		(end 406.02281 -379.5903)
		(width 0.14224)
		(layer "In13.Cu")
		(net "P5E_CPU0_P2_TX_DN<5>")
	)
	(segment
		(start 365.4679 -291.418518)
		(end 365.4679 -291.418772)
		(width 0.1143)
		(layer "In13.Cu")
		(net "P5E_CPU0_P2_TX_DN<5>")
	)
	(segment
		(start 365.470948 -289.151568)
		(end 365.43615 -289.171634)
		(width 0.1143)
		(layer "In13.Cu")
		(net "P5E_CPU0_P2_TX_DN<5>")
	)
	(segment
		(start 365.508032 -287.51022)
		(end 365.43615 -287.551876)
		(width 0.1143)
		(layer "In13.Cu")
		(net "P5E_CPU0_P2_TX_DN<5>")
	)
	(segment
		(start 365.470948 -285.911798)
		(end 365.43615 -285.931864)
		(width 0.1143)
		(layer "In13.Cu")
		(net "P5E_CPU0_P2_TX_DN<5>")
	)
	(segment
		(start 365.506762 -276.170644)
		(end 365.467646 -276.193504)
		(width 0.1143)
		(layer "In13.Cu")
		(net "P5E_CPU0_P2_TX_DN<5>")
	)
	(segment
		(start 365.470948 -290.77158)
		(end 365.43615 -290.791646)
		(width 0.1143)
		(layer "In13.Cu")
		(net "P5E_CPU0_P2_TX_DN<5>")
	)
	(segment
		(start 365.467646 -274.573492)
		(end 365.437166 -274.591272)
		(width 0.1143)
		(layer "In13.Cu")
		(net "P5E_CPU0_P2_TX_DN<5>")
	)
	(segment
		(start 365.4679 -283.318712)
		(end 365.470948 -283.32049)
		(width 0.1143)
		(layer "In13.Cu")
		(net "P5E_CPU0_P2_TX_DN<5>")
	)
	(segment
		(start 365.43615 -281.680412)
		(end 365.4679 -281.6987)
		(width 0.1143)
		(layer "In13.Cu")
		(net "P5E_CPU0_P2_TX_DN<5>")
	)
	(segment
		(start 366.253522 -296.458894)
		(end 366.253522 -296.487342)
		(width 0.1143)
		(layer "In13.Cu")
		(net "P5E_CPU0_P2_TX_DN<5>")
	)
	(segment
		(start 365.467646 -281.05354)
		(end 365.43615 -281.071828)
		(width 0.1143)
		(layer "In13.Cu")
		(net "P5E_CPU0_P2_TX_DN<5>")
	)
	(segment
		(start 365.464852 -294.012874)
		(end 365.4552 -294.018462)
		(width 0.1143)
		(layer "In13.Cu")
		(net "P5E_CPU0_P2_TX_DN<5>")
	)
	(segment
		(start 365.775748 -295.314624)
		(end 366.114838 -295.65346)
		(width 0.1143)
		(layer "In13.Cu")
		(net "P5E_CPU0_P2_TX_DN<5>")
	)
	(segment
		(start 365.506762 -277.790656)
		(end 365.467646 -277.813516)
		(width 0.1143)
		(layer "In13.Cu")
		(net "P5E_CPU0_P2_TX_DN<5>")
	)
	(segment
		(start 365.437166 -278.440896)
		(end 365.467646 -278.458676)
		(width 0.1143)
		(layer "In13.Cu")
		(net "P5E_CPU0_P2_TX_DN<5>")
	)
	(segment
		(start 365.43615 -289.780218)
		(end 365.4679 -289.798506)
		(width 0.1143)
		(layer "In13.Cu")
		(net "P5E_CPU0_P2_TX_DN<5>")
	)
	(segment
		(start 365.467646 -275.218652)
		(end 365.506762 -275.241512)
		(width 0.1143)
		(layer "In13.Cu")
		(net "P5E_CPU0_P2_TX_DN<5>")
	)
	(segment
		(start 365.467646 -293.038276)
		(end 365.470186 -293.0398)
		(width 0.1143)
		(layer "In13.Cu")
		(net "P5E_CPU0_P2_TX_DN<5>")
	)
	(segment
		(start 365.467646 -278.458676)
		(end 365.506762 -278.481536)
		(width 0.1143)
		(layer "In13.Cu")
		(net "P5E_CPU0_P2_TX_DN<5>")
	)
	(segment
		(start 365.750094 -287.045908)
		(end 365.750094 -287.05048)
		(width 0.1143)
		(layer "In13.Cu")
		(net "P5E_CPU0_P2_TX_DN<5>")
	)
	(segment
		(start 365.43615 -291.40023)
		(end 365.4679 -291.418518)
		(width 0.1143)
		(layer "In13.Cu")
		(net "P5E_CPU0_P2_TX_DN<5>")
	)
	(segment
		(start 365.437166 -280.060908)
		(end 365.467646 -280.078688)
		(width 0.1143)
		(layer "In13.Cu")
		(net "P5E_CPU0_P2_TX_DN<5>")
	)
	(segment
		(start 365.506762 -279.410668)
		(end 365.467646 -279.433528)
		(width 0.1143)
		(layer "In13.Cu")
		(net "P5E_CPU0_P2_TX_DN<5>")
	)
	(segment
		(start 365.43615 -284.920436)
		(end 365.4679 -284.938724)
		(width 0.1143)
		(layer "In13.Cu")
		(net "P5E_CPU0_P2_TX_DN<5>")
	)
	(segment
		(start 365.467646 -277.813516)
		(end 365.437166 -277.831296)
		(width 0.1143)
		(layer "In13.Cu")
		(net "P5E_CPU0_P2_TX_DN<5>")
	)
	(segment
		(start 405.147526 -376.070622)
		(end 405.300688 -376.17273)
		(width 0.14224)
		(layer "In13.Cu")
		(net "P5E_CPU0_P2_TX_DN<5>")
	)
	(segment
		(start 405.300688 -376.17273)
		(end 405.902922 -376.775218)
		(width 0.14224)
		(layer "In13.Cu")
		(net "P5E_CPU0_P2_TX_DN<5>")
	)
	(segment
		(start 365.506762 -281.03068)
		(end 365.467646 -281.05354)
		(width 0.1143)
		(layer "In13.Cu")
		(net "P5E_CPU0_P2_TX_DN<5>")
	)
	(segment
		(start 365.356902 -273.27606)
		(end 365.287052 -273.34591)
		(width 0.1143)
		(layer "In13.Cu")
		(net "P5E_CPU0_P2_TX_DN<5>")
	)
	(segment
		(start 366.253522 -296.487342)
		(end 366.253522 -299.18279)
		(width 0.14224)
		(layer "In13.Cu")
		(net "P5E_CPU0_P2_TX_DN<5>")
	)
	(segment
		(start 365.43615 -283.300424)
		(end 365.467138 -283.318204)
		(width 0.1143)
		(layer "In13.Cu")
		(net "P5E_CPU0_P2_TX_DN<5>")
	)
	(segment
		(start 365.467646 -279.433528)
		(end 365.437166 -279.451308)
		(width 0.1143)
		(layer "In13.Cu")
		(net "P5E_CPU0_P2_TX_DN<5>")
	)
	(segment
		(start 365.467646 -276.193504)
		(end 365.437166 -276.211284)
		(width 0.1143)
		(layer "In13.Cu")
		(net "P5E_CPU0_P2_TX_DN<5>")
	)
	(segment
		(start 365.437166 -273.58086)
		(end 365.467646 -273.59864)
		(width 0.1143)
		(layer "In13.Cu")
		(net "P5E_CPU0_P2_TX_DN<5>")
	)
	(segment
		(start 365.506 -291.440362)
		(end 365.518954 -291.44976)
		(width 0.1143)
		(layer "In13.Cu")
		(net "P5E_CPU0_P2_TX_DN<5>")
	)
	(segment
		(start 365.4679 -289.798506)
		(end 365.470948 -289.800284)
		(width 0.1143)
		(layer "In13.Cu")
		(net "P5E_CPU0_P2_TX_DN<5>")
	)
	(segment
		(start 365.437166 -275.200872)
		(end 365.467646 -275.218652)
		(width 0.1143)
		(layer "In13.Cu")
		(net "P5E_CPU0_P2_TX_DN<5>")
	)
	(segment
		(start 406.02281 -379.5903)
		(end 406.31364 -379.88113)
		(width 0.14224)
		(layer "In13.Cu")
		(net "P5E_CPU0_P2_TX_DN<5>")
	)
	(segment
		(start 393.80922 -365.75746)
		(end 397.683736 -371.555772)
		(width 0.14224)
		(layer "In13.Cu")
		(net "P5E_CPU0_P2_TX_DN<5>")
	)
	(segment
		(start 365.467646 -273.59864)
		(end 365.506762 -273.6215)
		(width 0.1143)
		(layer "In13.Cu")
		(net "P5E_CPU0_P2_TX_DN<5>")
	)
	(segment
		(start 366.283748 -299.333666)
		(end 393.80922 -365.75746)
		(width 0.14224)
		(layer "In13.Cu")
		(net "P5E_CPU0_P2_TX_DN<5>")
	)
	(segment
		(start 365.4679 -281.6987)
		(end 365.470948 -281.700478)
		(width 0.1143)
		(layer "In13.Cu")
		(net "P5E_CPU0_P2_TX_DN<5>")
	)
	(segment
		(start 365.4679 -291.418772)
		(end 365.506 -291.440362)
		(width 0.1143)
		(layer "In13.Cu")
		(net "P5E_CPU0_P2_TX_DN<5>")
	)
	(segment
		(start 365.467138 -283.318204)
		(end 365.4679 -283.318712)
		(width 0.1143)
		(layer "In13.Cu")
		(net "P5E_CPU0_P2_TX_DN<5>")
	)
	(segment
		(start 365.467646 -276.838664)
		(end 365.506762 -276.861524)
		(width 0.1143)
		(layer "In13.Cu")
		(net "P5E_CPU0_P2_TX_DN<5>")
	)
	(segment
		(start 402.415756 -374.93829)
		(end 405.147526 -376.070622)
		(width 0.14224)
		(layer "In13.Cu")
		(net "P5E_CPU0_P2_TX_DN<5>")
	)
	(segment
		(start 398.347946 -372.219982)
		(end 402.415756 -374.93829)
		(width 0.14224)
		(layer "In13.Cu")
		(net "P5E_CPU0_P2_TX_DN<5>")
	)
	(segment
		(start 365.506762 -274.550632)
		(end 365.467646 -274.573492)
		(width 0.1143)
		(layer "In13.Cu")
		(net "P5E_CPU0_P2_TX_DN<5>")
	)
	(segment
		(start 365.43615 -293.020242)
		(end 365.467646 -293.038276)
		(width 0.1143)
		(layer "In13.Cu")
		(net "P5E_CPU0_P2_TX_DN<5>")
	)
	(segment
		(start 365.506 -292.371526)
		(end 365.43615 -292.411658)
		(width 0.1143)
		(layer "In13.Cu")
		(net "P5E_CPU0_P2_TX_DN<5>")
	)
	(segment
		(start 365.4679 -284.938724)
		(end 365.470948 -284.940502)
		(width 0.1143)
		(layer "In13.Cu")
		(net "P5E_CPU0_P2_TX_DN<5>")
	)
	(segment
		(start 365.437166 -276.820884)
		(end 365.467646 -276.838664)
		(width 0.1143)
		(layer "In13.Cu")
		(net "P5E_CPU0_P2_TX_DN<5>")
	)
	(segment
		(start 365.654844 -273.27606)
		(end 365.356902 -273.27606)
		(width 0.1143)
		(layer "In13.Cu")
		(net "P5E_CPU0_P2_TX_DN<5>")
	)
	(segment
		(start 365.470948 -284.291786)
		(end 365.43615 -284.311852)
		(width 0.1143)
		(layer "In13.Cu")
		(net "P5E_CPU0_P2_TX_DN<5>")
	)
	(segment
		(start 365.434372 -288.158936)
		(end 365.435134 -288.159444)
		(width 0.1143)
		(layer "In13.Cu")
		(net "P5E_CPU0_P2_TX_DN<5>")
	)
	(segment
		(start 365.470948 -282.671774)
		(end 365.43615 -282.69184)
		(width 0.1143)
		(layer "In13.Cu")
		(net "P5E_CPU0_P2_TX_DN<5>")
	)
	(segment
		(start 365.518954 -292.362128)
		(end 365.506 -292.371526)
		(width 0.1143)
		(layer "In13.Cu")
		(net "P5E_CPU0_P2_TX_DN<5>")
	)
	(segment
		(start 365.435134 -288.159444)
		(end 365.4679 -288.178494)
		(width 0.1143)
		(layer "In13.Cu")
		(net "P5E_CPU0_P2_TX_DN<5>")
	)
	(segment
		(start 365.424466 -294.628062)
		(end 365.496094 -294.669972)
		(width 0.1143)
		(layer "In13.Cu")
		(net "P5E_CPU0_P2_TX_DN<5>")
	)
	(segment
		(start 366.207802 -296.413174)
		(end 366.253522 -296.458894)
		(width 0.1143)
		(layer "In13.Cu")
		(net "P5E_CPU0_P2_TX_DN<5>")
	)
	(segment
		(start 365.434372 -286.538924)
		(end 365.509048 -286.582866)
		(width 0.1143)
		(layer "In13.Cu")
		(net "P5E_CPU0_P2_TX_DN<5>")
	)
	(arc
		(start 365.43615 -281.071828)
		(mid 365.280222 -281.37612)
		(end 365.43615 -281.680412)
		(width 0.1143)
		(layer "In13.Cu")
		(net "P5E_CPU0_P2_TX_DN<5>")
	)
	(arc
		(start 365.43615 -290.791646)
		(mid 365.280222 -291.095938)
		(end 365.43615 -291.40023)
		(width 0.1143)
		(layer "In13.Cu")
		(net "P5E_CPU0_P2_TX_DN<5>")
	)
	(arc
		(start 365.437166 -274.591272)
		(mid 365.280189 -274.896072)
		(end 365.437166 -275.200872)
		(width 0.1143)
		(layer "In13.Cu")
		(net "P5E_CPU0_P2_TX_DN<5>")
	)
	(arc
		(start 365.506762 -278.481536)
		(mid 365.750089 -278.946102)
		(end 365.506762 -279.410668)
		(width 0.1143)
		(layer "In13.Cu")
		(net "P5E_CPU0_P2_TX_DN<5>")
	)
	(arc
		(start 365.280194 -286.236156)
		(mid 365.320956 -286.40604)
		(end 365.434372 -286.538924)
		(width 0.1143)
		(layer "In13.Cu")
		(net "P5E_CPU0_P2_TX_DN<5>")
	)
	(arc
		(start 365.496094 -294.669972)
		(mid 365.674071 -294.869609)
		(end 365.73841 -295.129204)
		(width 0.1143)
		(layer "In13.Cu")
		(net "P5E_CPU0_P2_TX_DN<5>")
	)
	(arc
		(start 365.509048 -286.582866)
		(mid 365.686244 -286.784878)
		(end 365.750094 -287.045908)
		(width 0.1143)
		(layer "In13.Cu")
		(net "P5E_CPU0_P2_TX_DN<5>")
	)
	(arc
		(start 365.43615 -292.411658)
		(mid 365.280222 -292.71595)
		(end 365.43615 -293.020242)
		(width 0.1143)
		(layer "In13.Cu")
		(net "P5E_CPU0_P2_TX_DN<5>")
	)
	(arc
		(start 365.518954 -291.44976)
		(mid 365.753381 -291.905944)
		(end 365.518954 -292.362128)
		(width 0.1143)
		(layer "In13.Cu")
		(net "P5E_CPU0_P2_TX_DN<5>")
	)
	(arc
		(start 365.470948 -288.180272)
		(mid 365.750563 -288.66592)
		(end 365.470948 -289.151568)
		(width 0.1143)
		(layer "In13.Cu")
		(net "P5E_CPU0_P2_TX_DN<5>")
	)
	(arc
		(start 365.280194 -287.856168)
		(mid 365.320956 -288.026052)
		(end 365.434372 -288.158936)
		(width 0.1143)
		(layer "In13.Cu")
		(net "P5E_CPU0_P2_TX_DN<5>")
	)
	(arc
		(start 365.470948 -283.32049)
		(mid 365.750563 -283.806138)
		(end 365.470948 -284.291786)
		(width 0.1143)
		(layer "In13.Cu")
		(net "P5E_CPU0_P2_TX_DN<5>")
	)
	(arc
		(start 365.750094 -287.05048)
		(mid 365.689095 -287.303804)
		(end 365.519462 -287.501584)
		(width 0.1143)
		(layer "In13.Cu")
		(net "P5E_CPU0_P2_TX_DN<5>")
	)
	(arc
		(start 365.43615 -289.171634)
		(mid 365.280222 -289.475926)
		(end 365.43615 -289.780218)
		(width 0.1143)
		(layer "In13.Cu")
		(net "P5E_CPU0_P2_TX_DN<5>")
	)
	(arc
		(start 365.437166 -276.211284)
		(mid 365.280189 -276.516084)
		(end 365.437166 -276.820884)
		(width 0.1143)
		(layer "In13.Cu")
		(net "P5E_CPU0_P2_TX_DN<5>")
	)
	(arc
		(start 365.506762 -280.101548)
		(mid 365.750089 -280.566114)
		(end 365.506762 -281.03068)
		(width 0.1143)
		(layer "In13.Cu")
		(net "P5E_CPU0_P2_TX_DN<5>")
	)
	(arc
		(start 365.506762 -275.241512)
		(mid 365.750089 -275.706078)
		(end 365.506762 -276.170644)
		(width 0.1143)
		(layer "In13.Cu")
		(net "P5E_CPU0_P2_TX_DN<5>")
	)
	(arc
		(start 365.43615 -284.311852)
		(mid 365.280222 -284.616144)
		(end 365.43615 -284.920436)
		(width 0.1143)
		(layer "In13.Cu")
		(net "P5E_CPU0_P2_TX_DN<5>")
	)
	(arc
		(start 365.506762 -273.6215)
		(mid 365.750089 -274.086066)
		(end 365.506762 -274.550632)
		(width 0.1143)
		(layer "In13.Cu")
		(net "P5E_CPU0_P2_TX_DN<5>")
	)
	(arc
		(start 397.683736 -371.555772)
		(mid 397.983133 -371.920585)
		(end 398.347946 -372.219982)
		(width 0.14224)
		(layer "In13.Cu")
		(net "P5E_CPU0_P2_TX_DN<5>")
	)
	(arc
		(start 365.470948 -284.940502)
		(mid 365.750563 -285.42615)
		(end 365.470948 -285.911798)
		(width 0.1143)
		(layer "In13.Cu")
		(net "P5E_CPU0_P2_TX_DN<5>")
	)
	(arc
		(start 365.43615 -287.551876)
		(mid 365.321474 -287.68521)
		(end 365.280194 -287.856168)
		(width 0.1143)
		(layer "In13.Cu")
		(net "P5E_CPU0_P2_TX_DN<5>")
	)
	(arc
		(start 365.437166 -277.831296)
		(mid 365.280189 -278.136096)
		(end 365.437166 -278.440896)
		(width 0.1143)
		(layer "In13.Cu")
		(net "P5E_CPU0_P2_TX_DN<5>")
	)
	(arc
		(start 365.470948 -289.800284)
		(mid 365.750563 -290.285932)
		(end 365.470948 -290.77158)
		(width 0.1143)
		(layer "In13.Cu")
		(net "P5E_CPU0_P2_TX_DN<5>")
	)
	(arc
		(start 405.902922 -376.775218)
		(mid 405.991637 -376.908083)
		(end 406.02281 -377.064778)
		(width 0.14224)
		(layer "In13.Cu")
		(net "P5E_CPU0_P2_TX_DN<5>")
	)
	(arc
		(start 365.43615 -282.69184)
		(mid 365.280222 -282.996132)
		(end 365.43615 -283.300424)
		(width 0.1143)
		(layer "In13.Cu")
		(net "P5E_CPU0_P2_TX_DN<5>")
	)
	(arc
		(start 365.470186 -293.0398)
		(mid 365.748629 -293.527821)
		(end 365.464852 -294.012874)
		(width 0.1143)
		(layer "In13.Cu")
		(net "P5E_CPU0_P2_TX_DN<5>")
	)
	(arc
		(start 365.506762 -276.861524)
		(mid 365.750089 -277.32609)
		(end 365.506762 -277.790656)
		(width 0.1143)
		(layer "In13.Cu")
		(net "P5E_CPU0_P2_TX_DN<5>")
	)
	(arc
		(start 366.114838 -295.65346)
		(mid 366.183692 -295.75674)
		(end 366.207802 -295.878504)
		(width 0.1143)
		(layer "In13.Cu")
		(net "P5E_CPU0_P2_TX_DN<5>")
	)
	(arc
		(start 365.437166 -279.451308)
		(mid 365.280189 -279.756108)
		(end 365.437166 -280.060908)
		(width 0.1143)
		(layer "In13.Cu")
		(net "P5E_CPU0_P2_TX_DN<5>")
	)
	(arc
		(start 365.43615 -285.931864)
		(mid 365.321474 -286.065198)
		(end 365.280194 -286.236156)
		(width 0.1143)
		(layer "In13.Cu")
		(net "P5E_CPU0_P2_TX_DN<5>")
	)
	(arc
		(start 365.287052 -273.34591)
		(mid 365.339469 -273.477841)
		(end 365.437166 -273.58086)
		(width 0.1143)
		(layer "In13.Cu")
		(net "P5E_CPU0_P2_TX_DN<5>")
	)
	(arc
		(start 365.470948 -281.700478)
		(mid 365.750563 -282.186126)
		(end 365.470948 -282.671774)
		(width 0.1143)
		(layer "In13.Cu")
		(net "P5E_CPU0_P2_TX_DN<5>")
	)
	(arc
		(start 365.4552 -294.018462)
		(mid 365.273795 -294.314885)
		(end 365.424466 -294.628062)
		(width 0.1143)
		(layer "In13.Cu")
		(net "P5E_CPU0_P2_TX_DN<5>")
	)
	(arc
		(start 366.253522 -299.18279)
		(mid 366.261207 -299.259715)
		(end 366.283748 -299.333666)
		(width 0.14224)
		(layer "In13.Cu")
		(net "P5E_CPU0_P2_TX_DN<5>")
	)
	(arc
		(start 365.73841 -295.224708)
		(mid 365.748112 -295.273392)
		(end 365.775748 -295.314624)
		(width 0.1143)
		(layer "In13.Cu")
		(net "P5E_CPU0_P2_TX_DN<5>")
	)
	(segment
		(start 404.34133 -383.31902)
		(end 404.63724 -383.61493)
		(width 0.12954)
		(layer "F.Cu")
		(net "P5E_CPU0_P2_TX_DN<4>")
	)
	(segment
		(start 365.187992 -269.770098)
		(end 365.654844 -270.036036)
		(width 0.12954)
		(layer "F.Cu")
		(net "P5E_CPU0_P2_TX_DN<4>")
	)
	(segment
		(start 404.34133 -382.61544)
		(end 404.34133 -383.31902)
		(width 0.12954)
		(layer "F.Cu")
		(net "P5E_CPU0_P2_TX_DN<4>")
	)
	(segment
		(start 404.61184 -382.34493)
		(end 404.34133 -382.61544)
		(width 0.12954)
		(layer "F.Cu")
		(net "P5E_CPU0_P2_TX_DN<4>")
	)
	(segment
		(start 364.527846 -282.673552)
		(end 364.527592 -282.673806)
		(width 0.1143)
		(layer "In13.Cu")
		(net "P5E_CPU0_P2_TX_DN<4>")
	)
	(segment
		(start 364.521496 -279.437084)
		(end 364.496096 -279.451816)
		(width 0.1143)
		(layer "In13.Cu")
		(net "P5E_CPU0_P2_TX_DN<4>")
	)
	(segment
		(start 364.494318 -288.158936)
		(end 364.527846 -288.178494)
		(width 0.1143)
		(layer "In13.Cu")
		(net "P5E_CPU0_P2_TX_DN<4>")
	)
	(segment
		(start 364.496096 -276.820376)
		(end 364.527084 -276.838156)
		(width 0.1143)
		(layer "In13.Cu")
		(net "P5E_CPU0_P2_TX_DN<4>")
	)
	(segment
		(start 364.496096 -271.96034)
		(end 364.564168 -271.99971)
		(width 0.1143)
		(layer "In13.Cu")
		(net "P5E_CPU0_P2_TX_DN<4>")
	)
	(segment
		(start 364.496096 -293.020242)
		(end 364.527084 -293.038022)
		(width 0.1143)
		(layer "In13.Cu")
		(net "P5E_CPU0_P2_TX_DN<4>")
	)
	(segment
		(start 364.49508 -286.539432)
		(end 364.564168 -286.579564)
		(width 0.1143)
		(layer "In13.Cu")
		(net "P5E_CPU0_P2_TX_DN<4>")
	)
	(segment
		(start 403.545548 -378.577602)
		(end 403.805644 -378.701046)
		(width 0.14224)
		(layer "In13.Cu")
		(net "P5E_CPU0_P2_TX_DN<4>")
	)
	(segment
		(start 364.528608 -283.31922)
		(end 364.545372 -283.328872)
		(width 0.1143)
		(layer "In13.Cu")
		(net "P5E_CPU0_P2_TX_DN<4>")
	)
	(segment
		(start 364.541562 -284.28569)
		(end 364.540038 -284.286706)
		(width 0.1143)
		(layer "In13.Cu")
		(net "P5E_CPU0_P2_TX_DN<4>")
	)
	(segment
		(start 364.506764 -283.306774)
		(end 364.520734 -283.314648)
		(width 0.1143)
		(layer "In13.Cu")
		(net "P5E_CPU0_P2_TX_DN<4>")
	)
	(segment
		(start 364.527084 -276.838156)
		(end 364.527846 -276.838664)
		(width 0.1143)
		(layer "In13.Cu")
		(net "P5E_CPU0_P2_TX_DN<4>")
	)
	(segment
		(start 364.594648 -281.010868)
		(end 364.566962 -281.030934)
		(width 0.1143)
		(layer "In13.Cu")
		(net "P5E_CPU0_P2_TX_DN<4>")
	)
	(segment
		(start 364.987332 -270.529304)
		(end 364.987078 -270.529558)
		(width 0.1143)
		(layer "In13.Cu")
		(net "P5E_CPU0_P2_TX_DN<4>")
	)
	(segment
		(start 364.527084 -277.814024)
		(end 364.52429 -277.815548)
		(width 0.1143)
		(layer "In13.Cu")
		(net "P5E_CPU0_P2_TX_DN<4>")
	)
	(segment
		(start 401.273772 -375.40819)
		(end 402.485606 -376.620024)
		(width 0.14224)
		(layer "In13.Cu")
		(net "P5E_CPU0_P2_TX_DN<4>")
	)
	(segment
		(start 364.53064 -280.080466)
		(end 364.566708 -280.101294)
		(width 0.1143)
		(layer "In13.Cu")
		(net "P5E_CPU0_P2_TX_DN<4>")
	)
	(segment
		(start 364.527084 -272.953988)
		(end 364.52429 -272.955512)
		(width 0.1143)
		(layer "In13.Cu")
		(net "P5E_CPU0_P2_TX_DN<4>")
	)
	(segment
		(start 364.496096 -281.680412)
		(end 364.527084 -281.698192)
		(width 0.1143)
		(layer "In13.Cu")
		(net "P5E_CPU0_P2_TX_DN<4>")
	)
	(segment
		(start 364.527846 -281.6987)
		(end 364.530894 -281.700478)
		(width 0.1143)
		(layer "In13.Cu")
		(net "P5E_CPU0_P2_TX_DN<4>")
	)
	(segment
		(start 364.582202 -287.500568)
		(end 364.494826 -287.554162)
		(width 0.1143)
		(layer "In13.Cu")
		(net "P5E_CPU0_P2_TX_DN<4>")
	)
	(segment
		(start 392.97483 -366.321086)
		(end 396.653258 -371.826028)
		(width 0.14224)
		(layer "In13.Cu")
		(net "P5E_CPU0_P2_TX_DN<4>")
	)
	(segment
		(start 364.527846 -274.573492)
		(end 364.527084 -274.574)
		(width 0.1143)
		(layer "In13.Cu")
		(net "P5E_CPU0_P2_TX_DN<4>")
	)
	(segment
		(start 364.527846 -284.938724)
		(end 364.564168 -284.959806)
		(width 0.1143)
		(layer "In13.Cu")
		(net "P5E_CPU0_P2_TX_DN<4>")
	)
	(segment
		(start 364.496096 -289.780218)
		(end 364.527084 -289.797998)
		(width 0.1143)
		(layer "In13.Cu")
		(net "P5E_CPU0_P2_TX_DN<4>")
	)
	(segment
		(start 364.521496 -285.917132)
		(end 364.496096 -285.931864)
		(width 0.1143)
		(layer "In13.Cu")
		(net "P5E_CPU0_P2_TX_DN<4>")
	)
	(segment
		(start 364.523528 -279.436068)
		(end 364.521496 -279.437084)
		(width 0.1143)
		(layer "In13.Cu")
		(net "P5E_CPU0_P2_TX_DN<4>")
	)
	(segment
		(start 364.800388 -270.853662)
		(end 364.800388 -270.862044)
		(width 0.1143)
		(layer "In13.Cu")
		(net "P5E_CPU0_P2_TX_DN<4>")
	)
	(segment
		(start 364.523528 -283.316172)
		(end 364.52429 -283.31668)
		(width 0.1143)
		(layer "In13.Cu")
		(net "P5E_CPU0_P2_TX_DN<4>")
	)
	(segment
		(start 364.566708 -276.86127)
		(end 364.594648 -276.881336)
		(width 0.1143)
		(layer "In13.Cu")
		(net "P5E_CPU0_P2_TX_DN<4>")
	)
	(segment
		(start 364.527084 -289.153854)
		(end 364.52429 -289.155378)
		(width 0.1143)
		(layer "In13.Cu")
		(net "P5E_CPU0_P2_TX_DN<4>")
	)
	(segment
		(start 404.32101 -379.476254)
		(end 404.32101 -382.0541)
		(width 0.14224)
		(layer "In13.Cu")
		(net "P5E_CPU0_P2_TX_DN<4>")
	)
	(segment
		(start 364.527084 -293.038022)
		(end 364.527846 -293.03853)
		(width 0.1143)
		(layer "In13.Cu")
		(net "P5E_CPU0_P2_TX_DN<4>")
	)
	(segment
		(start 364.564168 -274.55241)
		(end 364.527846 -274.573492)
		(width 0.1143)
		(layer "In13.Cu")
		(net "P5E_CPU0_P2_TX_DN<4>")
	)
	(segment
		(start 364.527846 -290.773358)
		(end 364.527084 -290.773866)
		(width 0.1143)
		(layer "In13.Cu")
		(net "P5E_CPU0_P2_TX_DN<4>")
	)
	(segment
		(start 364.524036 -282.675584)
		(end 364.521242 -282.677108)
		(width 0.1143)
		(layer "In13.Cu")
		(net "P5E_CPU0_P2_TX_DN<4>")
	)
	(segment
		(start 364.496096 -278.440388)
		(end 364.527846 -278.458676)
		(width 0.1143)
		(layer "In13.Cu")
		(net "P5E_CPU0_P2_TX_DN<4>")
	)
	(segment
		(start 364.52429 -276.195536)
		(end 364.523528 -276.196044)
		(width 0.1143)
		(layer "In13.Cu")
		(net "P5E_CPU0_P2_TX_DN<4>")
	)
	(segment
		(start 364.521496 -290.776914)
		(end 364.496096 -290.791646)
		(width 0.1143)
		(layer "In13.Cu")
		(net "P5E_CPU0_P2_TX_DN<4>")
	)
	(segment
		(start 364.523528 -285.916116)
		(end 364.521496 -285.917132)
		(width 0.1143)
		(layer "In13.Cu")
		(net "P5E_CPU0_P2_TX_DN<4>")
	)
	(segment
		(start 404.32101 -382.0541)
		(end 404.61184 -382.34493)
		(width 0.14224)
		(layer "In13.Cu")
		(net "P5E_CPU0_P2_TX_DN<4>")
	)
	(segment
		(start 364.527846 -279.433528)
		(end 364.527084 -279.434036)
		(width 0.1143)
		(layer "In13.Cu")
		(net "P5E_CPU0_P2_TX_DN<4>")
	)
	(segment
		(start 365.270542 -295.851072)
		(end 365.270542 -296.43451)
		(width 0.1143)
		(layer "In13.Cu")
		(net "P5E_CPU0_P2_TX_DN<4>")
	)
	(segment
		(start 364.52429 -274.575524)
		(end 364.523528 -274.576032)
		(width 0.1143)
		(layer "In13.Cu")
		(net "P5E_CPU0_P2_TX_DN<4>")
	)
	(segment
		(start 364.532926 -271.33042)
		(end 364.49762 -271.350994)
		(width 0.1143)
		(layer "In13.Cu")
		(net "P5E_CPU0_P2_TX_DN<4>")
	)
	(segment
		(start 399.507456 -374.625616)
		(end 401.074382 -375.274586)
		(width 0.14224)
		(layer "In13.Cu")
		(net "P5E_CPU0_P2_TX_DN<4>")
	)
	(segment
		(start 364.494318 -286.538924)
		(end 364.49508 -286.539432)
		(width 0.1143)
		(layer "In13.Cu")
		(net "P5E_CPU0_P2_TX_DN<4>")
	)
	(segment
		(start 364.564168 -272.932398)
		(end 364.527846 -272.95348)
		(width 0.1143)
		(layer "In13.Cu")
		(net "P5E_CPU0_P2_TX_DN<4>")
	)
	(segment
		(start 403.986746 -378.829062)
		(end 404.099776 -378.942092)
		(width 0.14224)
		(layer "In13.Cu")
		(net "P5E_CPU0_P2_TX_DN<4>")
	)
	(segment
		(start 364.527084 -279.434036)
		(end 364.52429 -279.43556)
		(width 0.1143)
		(layer "In13.Cu")
		(net "P5E_CPU0_P2_TX_DN<4>")
	)
	(segment
		(start 364.992158 -295.461944)
		(end 365.042196 -295.491154)
		(width 0.1143)
		(layer "In13.Cu")
		(net "P5E_CPU0_P2_TX_DN<4>")
	)
	(segment
		(start 364.522004 -283.31541)
		(end 364.523528 -283.316172)
		(width 0.1143)
		(layer "In13.Cu")
		(net "P5E_CPU0_P2_TX_DN<4>")
	)
	(segment
		(start 365.042196 -295.491154)
		(end 365.177324 -295.626282)
		(width 0.1143)
		(layer "In13.Cu")
		(net "P5E_CPU0_P2_TX_DN<4>")
	)
	(segment
		(start 364.523528 -292.39591)
		(end 364.521496 -292.396926)
		(width 0.1143)
		(layer "In13.Cu")
		(net "P5E_CPU0_P2_TX_DN<4>")
	)
	(segment
		(start 364.525306 -284.9372)
		(end 364.527084 -284.938216)
		(width 0.1143)
		(layer "In13.Cu")
		(net "P5E_CPU0_P2_TX_DN<4>")
	)
	(segment
		(start 364.522258 -284.935422)
		(end 364.524544 -284.936692)
		(width 0.1143)
		(layer "In13.Cu")
		(net "P5E_CPU0_P2_TX_DN<4>")
	)
	(segment
		(start 364.523528 -276.196044)
		(end 364.521496 -276.19706)
		(width 0.1143)
		(layer "In13.Cu")
		(net "P5E_CPU0_P2_TX_DN<4>")
	)
	(segment
		(start 364.496096 -275.200364)
		(end 364.564168 -275.239734)
		(width 0.1143)
		(layer "In13.Cu")
		(net "P5E_CPU0_P2_TX_DN<4>")
	)
	(segment
		(start 402.61286 -376.927364)
		(end 402.61286 -377.844558)
		(width 0.14224)
		(layer "In13.Cu")
		(net "P5E_CPU0_P2_TX_DN<4>")
	)
	(segment
		(start 364.527846 -272.95348)
		(end 364.527084 -272.953988)
		(width 0.1143)
		(layer "In13.Cu")
		(net "P5E_CPU0_P2_TX_DN<4>")
	)
	(segment
		(start 364.517432 -284.932882)
		(end 364.52048 -284.93466)
		(width 0.1143)
		(layer "In13.Cu")
		(net "P5E_CPU0_P2_TX_DN<4>")
	)
	(segment
		(start 364.521496 -274.577048)
		(end 364.496096 -274.59178)
		(width 0.1143)
		(layer "In13.Cu")
		(net "P5E_CPU0_P2_TX_DN<4>")
	)
	(segment
		(start 364.523528 -272.95602)
		(end 364.521496 -272.957036)
		(width 0.1143)
		(layer "In13.Cu")
		(net "P5E_CPU0_P2_TX_DN<4>")
	)
	(segment
		(start 364.566962 -281.030934)
		(end 364.496096 -281.071828)
		(width 0.1143)
		(layer "In13.Cu")
		(net "P5E_CPU0_P2_TX_DN<4>")
	)
	(segment
		(start 365.316262 -296.48023)
		(end 365.316262 -296.508678)
		(width 0.1143)
		(layer "In13.Cu")
		(net "P5E_CPU0_P2_TX_DN<4>")
	)
	(segment
		(start 364.52429 -289.155378)
		(end 364.523528 -289.155886)
		(width 0.1143)
		(layer "In13.Cu")
		(net "P5E_CPU0_P2_TX_DN<4>")
	)
	(segment
		(start 364.564168 -285.892494)
		(end 364.527846 -285.913576)
		(width 0.1143)
		(layer "In13.Cu")
		(net "P5E_CPU0_P2_TX_DN<4>")
	)
	(segment
		(start 364.52429 -272.955512)
		(end 364.523528 -272.95602)
		(width 0.1143)
		(layer "In13.Cu")
		(net "P5E_CPU0_P2_TX_DN<4>")
	)
	(segment
		(start 364.521496 -292.396926)
		(end 364.496096 -292.411658)
		(width 0.1143)
		(layer "In13.Cu")
		(net "P5E_CPU0_P2_TX_DN<4>")
	)
	(segment
		(start 364.520734 -283.314648)
		(end 364.522004 -283.31541)
		(width 0.1143)
		(layer "In13.Cu")
		(net "P5E_CPU0_P2_TX_DN<4>")
	)
	(segment
		(start 364.521496 -276.19706)
		(end 364.496096 -276.211792)
		(width 0.1143)
		(layer "In13.Cu")
		(net "P5E_CPU0_P2_TX_DN<4>")
	)
	(segment
		(start 364.527084 -283.318458)
		(end 364.527084 -283.318204)
		(width 0.1143)
		(layer "In13.Cu")
		(net "P5E_CPU0_P2_TX_DN<4>")
	)
	(segment
		(start 364.540038 -284.286706)
		(end 364.53699 -284.288484)
		(width 0.1143)
		(layer "In13.Cu")
		(net "P5E_CPU0_P2_TX_DN<4>")
	)
	(segment
		(start 364.524544 -284.936692)
		(end 364.525306 -284.9372)
		(width 0.1143)
		(layer "In13.Cu")
		(net "P5E_CPU0_P2_TX_DN<4>")
	)
	(segment
		(start 364.594648 -277.770844)
		(end 364.566708 -277.79091)
		(width 0.1143)
		(layer "In13.Cu")
		(net "P5E_CPU0_P2_TX_DN<4>")
	)
	(segment
		(start 364.527846 -276.838664)
		(end 364.53064 -276.840442)
		(width 0.1143)
		(layer "In13.Cu")
		(net "P5E_CPU0_P2_TX_DN<4>")
	)
	(segment
		(start 364.546134 -284.282896)
		(end 364.544102 -284.284166)
		(width 0.1143)
		(layer "In13.Cu")
		(net "P5E_CPU0_P2_TX_DN<4>")
	)
	(segment
		(start 364.527084 -276.194012)
		(end 364.52429 -276.195536)
		(width 0.1143)
		(layer "In13.Cu")
		(net "P5E_CPU0_P2_TX_DN<4>")
	)
	(segment
		(start 364.526322 -283.31795)
		(end 364.527084 -283.318458)
		(width 0.1143)
		(layer "In13.Cu")
		(net "P5E_CPU0_P2_TX_DN<4>")
	)
	(segment
		(start 364.527084 -280.07818)
		(end 364.527846 -280.078688)
		(width 0.1143)
		(layer "In13.Cu")
		(net "P5E_CPU0_P2_TX_DN<4>")
	)
	(segment
		(start 365.270542 -296.43451)
		(end 365.316262 -296.48023)
		(width 0.1143)
		(layer "In13.Cu")
		(net "P5E_CPU0_P2_TX_DN<4>")
	)
	(segment
		(start 364.53699 -284.288484)
		(end 364.536228 -284.288992)
		(width 0.1143)
		(layer "In13.Cu")
		(net "P5E_CPU0_P2_TX_DN<4>")
	)
	(segment
		(start 364.496096 -280.0604)
		(end 364.527084 -280.07818)
		(width 0.1143)
		(layer "In13.Cu")
		(net "P5E_CPU0_P2_TX_DN<4>")
	)
	(segment
		(start 364.527084 -289.797998)
		(end 364.527846 -289.798506)
		(width 0.1143)
		(layer "In13.Cu")
		(net "P5E_CPU0_P2_TX_DN<4>")
	)
	(segment
		(start 364.528608 -289.152838)
		(end 364.527084 -289.153854)
		(width 0.1143)
		(layer "In13.Cu")
		(net "P5E_CPU0_P2_TX_DN<4>")
	)
	(segment
		(start 402.650198 -377.934728)
		(end 403.035008 -378.319284)
		(width 0.14224)
		(layer "In13.Cu")
		(net "P5E_CPU0_P2_TX_DN<4>")
	)
	(segment
		(start 364.527084 -294.01389)
		(end 364.52429 -294.015414)
		(width 0.1143)
		(layer "In13.Cu")
		(net "P5E_CPU0_P2_TX_DN<4>")
	)
	(segment
		(start 364.523528 -290.775898)
		(end 364.521496 -290.776914)
		(width 0.1143)
		(layer "In13.Cu")
		(net "P5E_CPU0_P2_TX_DN<4>")
	)
	(segment
		(start 364.527846 -280.078688)
		(end 364.53064 -280.080466)
		(width 0.1143)
		(layer "In13.Cu")
		(net "P5E_CPU0_P2_TX_DN<4>")
	)
	(segment
		(start 364.54334 -284.284674)
		(end 364.541562 -284.28569)
		(width 0.1143)
		(layer "In13.Cu")
		(net "P5E_CPU0_P2_TX_DN<4>")
	)
	(segment
		(start 364.527084 -285.914084)
		(end 364.52429 -285.915608)
		(width 0.1143)
		(layer "In13.Cu")
		(net "P5E_CPU0_P2_TX_DN<4>")
	)
	(segment
		(start 364.545372 -283.328872)
		(end 364.546134 -283.32938)
		(width 0.1143)
		(layer "In13.Cu")
		(net "P5E_CPU0_P2_TX_DN<4>")
	)
	(segment
		(start 364.527084 -290.773866)
		(end 364.52429 -290.77539)
		(width 0.1143)
		(layer "In13.Cu")
		(net "P5E_CPU0_P2_TX_DN<4>")
	)
	(segment
		(start 364.52937 -277.8125)
		(end 364.527084 -277.814024)
		(width 0.1143)
		(layer "In13.Cu")
		(net "P5E_CPU0_P2_TX_DN<4>")
	)
	(segment
		(start 397.047212 -372.305834)
		(end 399.083022 -374.341898)
		(width 0.14224)
		(layer "In13.Cu")
		(net "P5E_CPU0_P2_TX_DN<4>")
	)
	(segment
		(start 364.566708 -280.101294)
		(end 364.594648 -280.12136)
		(width 0.1143)
		(layer "In13.Cu")
		(net "P5E_CPU0_P2_TX_DN<4>")
	)
	(segment
		(start 365.356902 -270.036036)
		(end 365.274098 -270.11884)
		(width 0.1143)
		(layer "In13.Cu")
		(net "P5E_CPU0_P2_TX_DN<4>")
	)
	(segment
		(start 364.527084 -291.41801)
		(end 364.527846 -291.418518)
		(width 0.1143)
		(layer "In13.Cu")
		(net "P5E_CPU0_P2_TX_DN<4>")
	)
	(segment
		(start 364.533434 -271.329912)
		(end 364.532926 -271.33042)
		(width 0.1143)
		(layer "In13.Cu")
		(net "P5E_CPU0_P2_TX_DN<4>")
	)
	(segment
		(start 364.496096 -291.40023)
		(end 364.527084 -291.41801)
		(width 0.1143)
		(layer "In13.Cu")
		(net "P5E_CPU0_P2_TX_DN<4>")
	)
	(segment
		(start 364.527846 -278.458676)
		(end 364.564168 -278.479758)
		(width 0.1143)
		(layer "In13.Cu")
		(net "P5E_CPU0_P2_TX_DN<4>")
	)
	(segment
		(start 364.527084 -292.393878)
		(end 364.52429 -292.395402)
		(width 0.1143)
		(layer "In13.Cu")
		(net "P5E_CPU0_P2_TX_DN<4>")
	)
	(segment
		(start 364.521496 -272.957036)
		(end 364.496096 -272.971768)
		(width 0.1143)
		(layer "In13.Cu")
		(net "P5E_CPU0_P2_TX_DN<4>")
	)
	(segment
		(start 364.527084 -281.698192)
		(end 364.527846 -281.6987)
		(width 0.1143)
		(layer "In13.Cu")
		(net "P5E_CPU0_P2_TX_DN<4>")
	)
	(segment
		(start 364.52302 -294.656002)
		(end 364.52556 -294.657526)
		(width 0.1143)
		(layer "In13.Cu")
		(net "P5E_CPU0_P2_TX_DN<4>")
	)
	(segment
		(start 364.52429 -285.915608)
		(end 364.523528 -285.916116)
		(width 0.1143)
		(layer "In13.Cu")
		(net "P5E_CPU0_P2_TX_DN<4>")
	)
	(segment
		(start 364.52429 -283.31668)
		(end 364.526322 -283.31795)
		(width 0.1143)
		(layer "In13.Cu")
		(net "P5E_CPU0_P2_TX_DN<4>")
	)
	(segment
		(start 364.530894 -282.671774)
		(end 364.528862 -282.673044)
		(width 0.1143)
		(layer "In13.Cu")
		(net "P5E_CPU0_P2_TX_DN<4>")
	)
	(segment
		(start 364.527846 -294.013382)
		(end 364.527084 -294.01389)
		(width 0.1143)
		(layer "In13.Cu")
		(net "P5E_CPU0_P2_TX_DN<4>")
	)
	(segment
		(start 364.527846 -285.913576)
		(end 364.527084 -285.914084)
		(width 0.1143)
		(layer "In13.Cu")
		(net "P5E_CPU0_P2_TX_DN<4>")
	)
	(segment
		(start 365.32947 -299.606716)
		(end 392.97483 -366.321086)
		(width 0.14224)
		(layer "In13.Cu")
		(net "P5E_CPU0_P2_TX_DN<4>")
	)
	(segment
		(start 364.52556 -294.657526)
		(end 364.525814 -294.657272)
		(width 0.1143)
		(layer "In13.Cu")
		(net "P5E_CPU0_P2_TX_DN<4>")
	)
	(segment
		(start 364.544102 -284.284166)
		(end 364.54334 -284.284674)
		(width 0.1143)
		(layer "In13.Cu")
		(net "P5E_CPU0_P2_TX_DN<4>")
	)
	(segment
		(start 396.653258 -371.826028)
		(end 397.047212 -372.305834)
		(width 0.14224)
		(layer "In13.Cu")
		(net "P5E_CPU0_P2_TX_DN<4>")
	)
	(segment
		(start 364.527846 -292.39337)
		(end 364.527084 -292.393878)
		(width 0.1143)
		(layer "In13.Cu")
		(net "P5E_CPU0_P2_TX_DN<4>")
	)
	(segment
		(start 365.036862 -270.500602)
		(end 364.987332 -270.529304)
		(width 0.1143)
		(layer "In13.Cu")
		(net "P5E_CPU0_P2_TX_DN<4>")
	)
	(segment
		(start 364.521242 -282.677108)
		(end 364.50778 -282.684982)
		(width 0.1143)
		(layer "In13.Cu")
		(net "P5E_CPU0_P2_TX_DN<4>")
	)
	(segment
		(start 364.527084 -274.574)
		(end 364.52429 -274.575524)
		(width 0.1143)
		(layer "In13.Cu")
		(net "P5E_CPU0_P2_TX_DN<4>")
	)
	(segment
		(start 364.523528 -289.155886)
		(end 364.521496 -289.156902)
		(width 0.1143)
		(layer "In13.Cu")
		(net "P5E_CPU0_P2_TX_DN<4>")
	)
	(segment
		(start 364.521496 -277.817072)
		(end 364.496096 -277.831804)
		(width 0.1143)
		(layer "In13.Cu")
		(net "P5E_CPU0_P2_TX_DN<4>")
	)
	(segment
		(start 365.316262 -296.508678)
		(end 365.316262 -299.540168)
		(width 0.14224)
		(layer "In13.Cu")
		(net "P5E_CPU0_P2_TX_DN<4>")
	)
	(segment
		(start 364.52429 -277.815548)
		(end 364.523528 -277.816056)
		(width 0.1143)
		(layer "In13.Cu")
		(net "P5E_CPU0_P2_TX_DN<4>")
	)
	(segment
		(start 364.52429 -292.395402)
		(end 364.523528 -292.39591)
		(width 0.1143)
		(layer "In13.Cu")
		(net "P5E_CPU0_P2_TX_DN<4>")
	)
	(segment
		(start 364.49762 -271.350994)
		(end 364.496096 -271.351756)
		(width 0.1143)
		(layer "In13.Cu")
		(net "P5E_CPU0_P2_TX_DN<4>")
	)
	(segment
		(start 364.566708 -277.79091)
		(end 364.52937 -277.8125)
		(width 0.1143)
		(layer "In13.Cu")
		(net "P5E_CPU0_P2_TX_DN<4>")
	)
	(segment
		(start 364.528862 -282.673044)
		(end 364.527846 -282.673552)
		(width 0.1143)
		(layer "In13.Cu")
		(net "P5E_CPU0_P2_TX_DN<4>")
	)
	(segment
		(start 364.521496 -289.156902)
		(end 364.496096 -289.171634)
		(width 0.1143)
		(layer "In13.Cu")
		(net "P5E_CPU0_P2_TX_DN<4>")
	)
	(segment
		(start 364.527084 -283.318204)
		(end 364.528608 -283.31922)
		(width 0.1143)
		(layer "In13.Cu")
		(net "P5E_CPU0_P2_TX_DN<4>")
	)
	(segment
		(start 364.527846 -288.178494)
		(end 364.528608 -288.179002)
		(width 0.1143)
		(layer "In13.Cu")
		(net "P5E_CPU0_P2_TX_DN<4>")
	)
	(segment
		(start 364.52429 -279.43556)
		(end 364.523528 -279.436068)
		(width 0.1143)
		(layer "In13.Cu")
		(net "P5E_CPU0_P2_TX_DN<4>")
	)
	(segment
		(start 364.536228 -284.288992)
		(end 364.524544 -284.295342)
		(width 0.1143)
		(layer "In13.Cu")
		(net "P5E_CPU0_P2_TX_DN<4>")
	)
	(segment
		(start 364.527592 -282.673806)
		(end 364.524036 -282.675584)
		(width 0.1143)
		(layer "In13.Cu")
		(net "P5E_CPU0_P2_TX_DN<4>")
	)
	(segment
		(start 401.074382 -375.274586)
		(end 401.273772 -375.40819)
		(width 0.14224)
		(layer "In13.Cu")
		(net "P5E_CPU0_P2_TX_DN<4>")
	)
	(segment
		(start 364.52429 -290.77539)
		(end 364.523528 -290.775898)
		(width 0.1143)
		(layer "In13.Cu")
		(net "P5E_CPU0_P2_TX_DN<4>")
	)
	(segment
		(start 364.523528 -274.576032)
		(end 364.521496 -274.577048)
		(width 0.1143)
		(layer "In13.Cu")
		(net "P5E_CPU0_P2_TX_DN<4>")
	)
	(segment
		(start 364.564168 -276.172422)
		(end 364.527846 -276.193504)
		(width 0.1143)
		(layer "In13.Cu")
		(net "P5E_CPU0_P2_TX_DN<4>")
	)
	(segment
		(start 364.81004 -287.045908)
		(end 364.807246 -287.076896)
		(width 0.1143)
		(layer "In13.Cu")
		(net "P5E_CPU0_P2_TX_DN<4>")
	)
	(segment
		(start 364.564168 -279.412446)
		(end 364.527846 -279.433528)
		(width 0.1143)
		(layer "In13.Cu")
		(net "P5E_CPU0_P2_TX_DN<4>")
	)
	(segment
		(start 364.52048 -284.93466)
		(end 364.522258 -284.935422)
		(width 0.1143)
		(layer "In13.Cu")
		(net "P5E_CPU0_P2_TX_DN<4>")
	)
	(segment
		(start 364.53064 -276.840442)
		(end 364.566708 -276.86127)
		(width 0.1143)
		(layer "In13.Cu")
		(net "P5E_CPU0_P2_TX_DN<4>")
	)
	(segment
		(start 364.496096 -273.580352)
		(end 364.564168 -273.619722)
		(width 0.1143)
		(layer "In13.Cu")
		(net "P5E_CPU0_P2_TX_DN<4>")
	)
	(segment
		(start 364.527084 -284.938216)
		(end 364.527846 -284.938724)
		(width 0.1143)
		(layer "In13.Cu")
		(net "P5E_CPU0_P2_TX_DN<4>")
	)
	(segment
		(start 365.654844 -270.036036)
		(end 365.356902 -270.036036)
		(width 0.1143)
		(layer "In13.Cu")
		(net "P5E_CPU0_P2_TX_DN<4>")
	)
	(segment
		(start 364.527846 -276.193504)
		(end 364.527084 -276.194012)
		(width 0.1143)
		(layer "In13.Cu")
		(net "P5E_CPU0_P2_TX_DN<4>")
	)
	(segment
		(start 364.525814 -294.657272)
		(end 364.555786 -294.676576)
		(width 0.1143)
		(layer "In13.Cu")
		(net "P5E_CPU0_P2_TX_DN<4>")
	)
	(segment
		(start 364.523528 -277.816056)
		(end 364.521496 -277.817072)
		(width 0.1143)
		(layer "In13.Cu")
		(net "P5E_CPU0_P2_TX_DN<4>")
	)
	(arc
		(start 364.564168 -273.619722)
		(mid 364.571317 -273.624622)
		(end 364.578392 -273.629628)
		(width 0.1143)
		(layer "In13.Cu")
		(net "P5E_CPU0_P2_TX_DN<4>")
	)
	(arc
		(start 364.81004 -295.145968)
		(mid 364.858822 -295.328329)
		(end 364.992158 -295.461944)
		(width 0.1143)
		(layer "In13.Cu")
		(net "P5E_CPU0_P2_TX_DN<4>")
	)
	(arc
		(start 364.496096 -290.791646)
		(mid 364.340168 -291.095938)
		(end 364.496096 -291.40023)
		(width 0.1143)
		(layer "In13.Cu")
		(net "P5E_CPU0_P2_TX_DN<4>")
	)
	(arc
		(start 364.496096 -271.351756)
		(mid 364.340168 -271.656048)
		(end 364.496096 -271.96034)
		(width 0.1143)
		(layer "In13.Cu")
		(net "P5E_CPU0_P2_TX_DN<4>")
	)
	(arc
		(start 364.494826 -287.554162)
		(mid 364.381047 -287.686505)
		(end 364.34014 -287.856168)
		(width 0.1143)
		(layer "In13.Cu")
		(net "P5E_CPU0_P2_TX_DN<4>")
	)
	(arc
		(start 365.274098 -270.11884)
		(mid 365.27231 -270.130289)
		(end 365.270288 -270.1417)
		(width 0.1143)
		(layer "In13.Cu")
		(net "P5E_CPU0_P2_TX_DN<4>")
	)
	(arc
		(start 364.579408 -279.401778)
		(mid 364.571832 -279.407174)
		(end 364.564168 -279.412446)
		(width 0.1143)
		(layer "In13.Cu")
		(net "P5E_CPU0_P2_TX_DN<4>")
	)
	(arc
		(start 364.496096 -289.171634)
		(mid 364.340168 -289.475926)
		(end 364.496096 -289.780218)
		(width 0.1143)
		(layer "In13.Cu")
		(net "P5E_CPU0_P2_TX_DN<4>")
	)
	(arc
		(start 399.083022 -374.341898)
		(mid 399.281256 -374.504679)
		(end 399.507456 -374.625616)
		(width 0.14224)
		(layer "In13.Cu")
		(net "P5E_CPU0_P2_TX_DN<4>")
	)
	(arc
		(start 364.52429 -294.015414)
		(mid 364.340156 -294.335286)
		(end 364.52302 -294.656002)
		(width 0.1143)
		(layer "In13.Cu")
		(net "P5E_CPU0_P2_TX_DN<4>")
	)
	(arc
		(start 364.564168 -275.239734)
		(mid 364.571317 -275.244634)
		(end 364.578392 -275.24964)
		(width 0.1143)
		(layer "In13.Cu")
		(net "P5E_CPU0_P2_TX_DN<4>")
	)
	(arc
		(start 364.594648 -276.881336)
		(mid 364.822648 -277.32609)
		(end 364.594648 -277.770844)
		(width 0.1143)
		(layer "In13.Cu")
		(net "P5E_CPU0_P2_TX_DN<4>")
	)
	(arc
		(start 364.496096 -272.971768)
		(mid 364.340168 -273.27606)
		(end 364.496096 -273.580352)
		(width 0.1143)
		(layer "In13.Cu")
		(net "P5E_CPU0_P2_TX_DN<4>")
	)
	(arc
		(start 402.485606 -376.620024)
		(mid 402.579771 -376.761047)
		(end 402.61286 -376.927364)
		(width 0.14224)
		(layer "In13.Cu")
		(net "P5E_CPU0_P2_TX_DN<4>")
	)
	(arc
		(start 364.527846 -289.798506)
		(mid 364.808493 -290.285932)
		(end 364.527846 -290.773358)
		(width 0.1143)
		(layer "In13.Cu")
		(net "P5E_CPU0_P2_TX_DN<4>")
	)
	(arc
		(start 364.564168 -278.479758)
		(mid 364.571832 -278.485029)
		(end 364.579408 -278.490426)
		(width 0.1143)
		(layer "In13.Cu")
		(net "P5E_CPU0_P2_TX_DN<4>")
	)
	(arc
		(start 364.564168 -284.959806)
		(mid 364.571832 -284.965077)
		(end 364.579408 -284.970474)
		(width 0.1143)
		(layer "In13.Cu")
		(net "P5E_CPU0_P2_TX_DN<4>")
	)
	(arc
		(start 403.346412 -378.502418)
		(mid 403.447541 -378.535875)
		(end 403.545548 -378.577602)
		(width 0.14224)
		(layer "In13.Cu")
		(net "P5E_CPU0_P2_TX_DN<4>")
	)
	(arc
		(start 403.035008 -378.319284)
		(mid 403.179031 -378.430705)
		(end 403.346412 -378.502418)
		(width 0.14224)
		(layer "In13.Cu")
		(net "P5E_CPU0_P2_TX_DN<4>")
	)
	(arc
		(start 364.530894 -281.700478)
		(mid 364.810509 -282.186126)
		(end 364.530894 -282.671774)
		(width 0.1143)
		(layer "In13.Cu")
		(net "P5E_CPU0_P2_TX_DN<4>")
	)
	(arc
		(start 364.800388 -270.862044)
		(mid 364.728962 -271.131389)
		(end 364.533434 -271.329912)
		(width 0.1143)
		(layer "In13.Cu")
		(net "P5E_CPU0_P2_TX_DN<4>")
	)
	(arc
		(start 364.594648 -280.12136)
		(mid 364.822648 -280.566114)
		(end 364.594648 -281.010868)
		(width 0.1143)
		(layer "In13.Cu")
		(net "P5E_CPU0_P2_TX_DN<4>")
	)
	(arc
		(start 365.270288 -270.1417)
		(mid 365.188855 -270.344098)
		(end 365.036862 -270.500602)
		(width 0.1143)
		(layer "In13.Cu")
		(net "P5E_CPU0_P2_TX_DN<4>")
	)
	(arc
		(start 365.316262 -299.540168)
		(mid 365.319601 -299.574089)
		(end 365.32947 -299.606716)
		(width 0.14224)
		(layer "In13.Cu")
		(net "P5E_CPU0_P2_TX_DN<4>")
	)
	(arc
		(start 364.546134 -283.32938)
		(mid 364.820717 -283.806138)
		(end 364.546134 -284.282896)
		(width 0.1143)
		(layer "In13.Cu")
		(net "P5E_CPU0_P2_TX_DN<4>")
	)
	(arc
		(start 364.564168 -271.99971)
		(mid 364.571317 -272.00461)
		(end 364.578392 -272.009616)
		(width 0.1143)
		(layer "In13.Cu")
		(net "P5E_CPU0_P2_TX_DN<4>")
	)
	(arc
		(start 364.496096 -274.59178)
		(mid 364.340168 -274.896072)
		(end 364.496096 -275.200364)
		(width 0.1143)
		(layer "In13.Cu")
		(net "P5E_CPU0_P2_TX_DN<4>")
	)
	(arc
		(start 364.528608 -288.179002)
		(mid 364.808942 -288.66592)
		(end 364.528608 -289.152838)
		(width 0.1143)
		(layer "In13.Cu")
		(net "P5E_CPU0_P2_TX_DN<4>")
	)
	(arc
		(start 364.527846 -291.418518)
		(mid 364.808493 -291.905944)
		(end 364.527846 -292.39337)
		(width 0.1143)
		(layer "In13.Cu")
		(net "P5E_CPU0_P2_TX_DN<4>")
	)
	(arc
		(start 364.496096 -292.411658)
		(mid 364.340168 -292.71595)
		(end 364.496096 -293.020242)
		(width 0.1143)
		(layer "In13.Cu")
		(net "P5E_CPU0_P2_TX_DN<4>")
	)
	(arc
		(start 364.34014 -287.856168)
		(mid 364.380902 -288.026052)
		(end 364.494318 -288.158936)
		(width 0.1143)
		(layer "In13.Cu")
		(net "P5E_CPU0_P2_TX_DN<4>")
	)
	(arc
		(start 364.34014 -286.236156)
		(mid 364.380902 -286.40604)
		(end 364.494318 -286.538924)
		(width 0.1143)
		(layer "In13.Cu")
		(net "P5E_CPU0_P2_TX_DN<4>")
	)
	(arc
		(start 364.578392 -272.922492)
		(mid 364.571318 -272.927499)
		(end 364.564168 -272.932398)
		(width 0.1143)
		(layer "In13.Cu")
		(net "P5E_CPU0_P2_TX_DN<4>")
	)
	(arc
		(start 364.578392 -275.24964)
		(mid 364.805775 -275.706078)
		(end 364.578392 -276.162516)
		(width 0.1143)
		(layer "In13.Cu")
		(net "P5E_CPU0_P2_TX_DN<4>")
	)
	(arc
		(start 364.579408 -278.490426)
		(mid 364.804579 -278.946102)
		(end 364.579408 -279.401778)
		(width 0.1143)
		(layer "In13.Cu")
		(net "P5E_CPU0_P2_TX_DN<4>")
	)
	(arc
		(start 364.578392 -274.542504)
		(mid 364.571318 -274.547511)
		(end 364.564168 -274.55241)
		(width 0.1143)
		(layer "In13.Cu")
		(net "P5E_CPU0_P2_TX_DN<4>")
	)
	(arc
		(start 364.50778 -282.684982)
		(mid 364.329244 -282.995565)
		(end 364.506764 -283.306774)
		(width 0.1143)
		(layer "In13.Cu")
		(net "P5E_CPU0_P2_TX_DN<4>")
	)
	(arc
		(start 364.578392 -273.629628)
		(mid 364.805775 -274.086066)
		(end 364.578392 -274.542504)
		(width 0.1143)
		(layer "In13.Cu")
		(net "P5E_CPU0_P2_TX_DN<4>")
	)
	(arc
		(start 364.579408 -285.881826)
		(mid 364.571832 -285.887222)
		(end 364.564168 -285.892494)
		(width 0.1143)
		(layer "In13.Cu")
		(net "P5E_CPU0_P2_TX_DN<4>")
	)
	(arc
		(start 404.099776 -378.942092)
		(mid 404.26353 -379.187168)
		(end 404.32101 -379.476254)
		(width 0.14224)
		(layer "In13.Cu")
		(net "P5E_CPU0_P2_TX_DN<4>")
	)
	(arc
		(start 364.807246 -287.076896)
		(mid 364.737658 -287.311538)
		(end 364.582202 -287.500568)
		(width 0.1143)
		(layer "In13.Cu")
		(net "P5E_CPU0_P2_TX_DN<4>")
	)
	(arc
		(start 402.61286 -377.844558)
		(mid 402.622566 -377.893353)
		(end 402.650198 -377.934728)
		(width 0.14224)
		(layer "In13.Cu")
		(net "P5E_CPU0_P2_TX_DN<4>")
	)
	(arc
		(start 364.524544 -284.295342)
		(mid 364.340339 -284.61205)
		(end 364.517432 -284.932882)
		(width 0.1143)
		(layer "In13.Cu")
		(net "P5E_CPU0_P2_TX_DN<4>")
	)
	(arc
		(start 364.57763 -286.589216)
		(mid 364.7486 -286.789693)
		(end 364.81004 -287.045908)
		(width 0.1143)
		(layer "In13.Cu")
		(net "P5E_CPU0_P2_TX_DN<4>")
	)
	(arc
		(start 364.496096 -285.931864)
		(mid 364.38142 -286.065198)
		(end 364.34014 -286.236156)
		(width 0.1143)
		(layer "In13.Cu")
		(net "P5E_CPU0_P2_TX_DN<4>")
	)
	(arc
		(start 364.496096 -277.831804)
		(mid 364.340168 -278.136096)
		(end 364.496096 -278.440388)
		(width 0.1143)
		(layer "In13.Cu")
		(net "P5E_CPU0_P2_TX_DN<4>")
	)
	(arc
		(start 364.527846 -293.03853)
		(mid 364.808493 -293.525956)
		(end 364.527846 -294.013382)
		(width 0.1143)
		(layer "In13.Cu")
		(net "P5E_CPU0_P2_TX_DN<4>")
	)
	(arc
		(start 403.805644 -378.701046)
		(mid 403.901665 -378.757314)
		(end 403.986746 -378.829062)
		(width 0.14224)
		(layer "In13.Cu")
		(net "P5E_CPU0_P2_TX_DN<4>")
	)
	(arc
		(start 364.496096 -281.071828)
		(mid 364.340168 -281.37612)
		(end 364.496096 -281.680412)
		(width 0.1143)
		(layer "In13.Cu")
		(net "P5E_CPU0_P2_TX_DN<4>")
	)
	(arc
		(start 364.564168 -286.579564)
		(mid 364.570934 -286.584341)
		(end 364.57763 -286.589216)
		(width 0.1143)
		(layer "In13.Cu")
		(net "P5E_CPU0_P2_TX_DN<4>")
	)
	(arc
		(start 364.578392 -272.009616)
		(mid 364.805775 -272.466054)
		(end 364.578392 -272.922492)
		(width 0.1143)
		(layer "In13.Cu")
		(net "P5E_CPU0_P2_TX_DN<4>")
	)
	(arc
		(start 364.578392 -276.162516)
		(mid 364.571318 -276.167523)
		(end 364.564168 -276.172422)
		(width 0.1143)
		(layer "In13.Cu")
		(net "P5E_CPU0_P2_TX_DN<4>")
	)
	(arc
		(start 364.579408 -284.970474)
		(mid 364.804579 -285.42615)
		(end 364.579408 -285.881826)
		(width 0.1143)
		(layer "In13.Cu")
		(net "P5E_CPU0_P2_TX_DN<4>")
	)
	(arc
		(start 365.177324 -295.626282)
		(mid 365.24629 -295.729402)
		(end 365.270542 -295.851072)
		(width 0.1143)
		(layer "In13.Cu")
		(net "P5E_CPU0_P2_TX_DN<4>")
	)
	(arc
		(start 364.496096 -279.451816)
		(mid 364.340168 -279.756108)
		(end 364.496096 -280.0604)
		(width 0.1143)
		(layer "In13.Cu")
		(net "P5E_CPU0_P2_TX_DN<4>")
	)
	(arc
		(start 364.555786 -294.676576)
		(mid 364.742422 -294.879044)
		(end 364.81004 -295.145968)
		(width 0.1143)
		(layer "In13.Cu")
		(net "P5E_CPU0_P2_TX_DN<4>")
	)
	(arc
		(start 364.987078 -270.529558)
		(mid 364.850389 -270.666645)
		(end 364.800388 -270.853662)
		(width 0.1143)
		(layer "In13.Cu")
		(net "P5E_CPU0_P2_TX_DN<4>")
	)
	(arc
		(start 364.496096 -276.211792)
		(mid 364.340168 -276.516084)
		(end 364.496096 -276.820376)
		(width 0.1143)
		(layer "In13.Cu")
		(net "P5E_CPU0_P2_TX_DN<4>")
	)
	(segment
		(start 400.93773 -378.39142)
		(end 401.23364 -378.68733)
		(width 0.12954)
		(layer "F.Cu")
		(net "P5E_CPU0_P2_TX_DN<3>")
	)
	(segment
		(start 401.20824 -377.41733)
		(end 400.93773 -377.68784)
		(width 0.12954)
		(layer "F.Cu")
		(net "P5E_CPU0_P2_TX_DN<3>")
	)
	(segment
		(start 400.93773 -377.68784)
		(end 400.93773 -378.39142)
		(width 0.12954)
		(layer "F.Cu")
		(net "P5E_CPU0_P2_TX_DN<3>")
	)
	(segment
		(start 362.837984 -272.200116)
		(end 363.304836 -272.466054)
		(width 0.12954)
		(layer "F.Cu")
		(net "P5E_CPU0_P2_TX_DN<3>")
	)
	(segment
		(start 400.607022 -376.090434)
		(end 400.91741 -376.400822)
		(width 0.14224)
		(layer "In13.Cu")
		(net "P5E_CPU0_P2_TX_DN<3>")
	)
	(segment
		(start 364.35665 -296.34561)
		(end 364.35665 -296.374058)
		(width 0.1143)
		(layer "In13.Cu")
		(net "P5E_CPU0_P2_TX_DN<3>")
	)
	(segment
		(start 363.587792 -283.318712)
		(end 363.626908 -283.341572)
		(width 0.1143)
		(layer "In13.Cu")
		(net "P5E_CPU0_P2_TX_DN<3>")
	)
	(segment
		(start 363.626908 -284.270704)
		(end 363.587792 -284.293564)
		(width 0.1143)
		(layer "In13.Cu")
		(net "P5E_CPU0_P2_TX_DN<3>")
	)
	(segment
		(start 363.587792 -291.418518)
		(end 363.626908 -291.441378)
		(width 0.1143)
		(layer "In13.Cu")
		(net "P5E_CPU0_P2_TX_DN<3>")
	)
	(segment
		(start 363.556042 -275.200364)
		(end 363.587792 -275.218652)
		(width 0.1143)
		(layer "In13.Cu")
		(net "P5E_CPU0_P2_TX_DN<3>")
	)
	(segment
		(start 363.590332 -273.600164)
		(end 363.626908 -273.6215)
		(width 0.1143)
		(layer "In13.Cu")
		(net "P5E_CPU0_P2_TX_DN<3>")
	)
	(segment
		(start 363.587792 -281.6987)
		(end 363.626908 -281.72156)
		(width 0.1143)
		(layer "In13.Cu")
		(net "P5E_CPU0_P2_TX_DN<3>")
	)
	(segment
		(start 363.626908 -292.37051)
		(end 363.587792 -292.39337)
		(width 0.1143)
		(layer "In13.Cu")
		(net "P5E_CPU0_P2_TX_DN<3>")
	)
	(segment
		(start 363.587792 -289.798506)
		(end 363.626908 -289.821366)
		(width 0.1143)
		(layer "In13.Cu")
		(net "P5E_CPU0_P2_TX_DN<3>")
	)
	(segment
		(start 364.35665 -296.374058)
		(end 364.35665 -299.963332)
		(width 0.14224)
		(layer "In13.Cu")
		(net "P5E_CPU0_P2_TX_DN<3>")
	)
	(segment
		(start 363.626654 -293.990522)
		(end 363.587538 -294.013382)
		(width 0.1143)
		(layer "In13.Cu")
		(net "P5E_CPU0_P2_TX_DN<3>")
	)
	(segment
		(start 363.117638 -272.788634)
		(end 363.156754 -272.811494)
		(width 0.1143)
		(layer "In13.Cu")
		(net "P5E_CPU0_P2_TX_DN<3>")
	)
	(segment
		(start 363.556042 -273.580352)
		(end 363.58703 -273.598132)
		(width 0.1143)
		(layer "In13.Cu")
		(net "P5E_CPU0_P2_TX_DN<3>")
	)
	(segment
		(start 400.91741 -376.400822)
		(end 400.91741 -377.1265)
		(width 0.14224)
		(layer "In13.Cu")
		(net "P5E_CPU0_P2_TX_DN<3>")
	)
	(segment
		(start 363.556042 -278.440388)
		(end 363.587792 -278.458676)
		(width 0.1143)
		(layer "In13.Cu")
		(net "P5E_CPU0_P2_TX_DN<3>")
	)
	(segment
		(start 363.626908 -279.410668)
		(end 363.587792 -279.433528)
		(width 0.1143)
		(layer "In13.Cu")
		(net "P5E_CPU0_P2_TX_DN<3>")
	)
	(segment
		(start 363.626908 -281.03068)
		(end 363.587792 -281.05354)
		(width 0.1143)
		(layer "In13.Cu")
		(net "P5E_CPU0_P2_TX_DN<3>")
	)
	(segment
		(start 363.626908 -276.170644)
		(end 363.587792 -276.193504)
		(width 0.1143)
		(layer "In13.Cu")
		(net "P5E_CPU0_P2_TX_DN<3>")
	)
	(segment
		(start 364.31093 -295.844214)
		(end 364.31093 -296.29989)
		(width 0.1143)
		(layer "In13.Cu")
		(net "P5E_CPU0_P2_TX_DN<3>")
	)
	(segment
		(start 363.587792 -290.773358)
		(end 363.556042 -290.791646)
		(width 0.1143)
		(layer "In13.Cu")
		(net "P5E_CPU0_P2_TX_DN<3>")
	)
	(segment
		(start 363.626908 -290.750498)
		(end 363.587792 -290.773358)
		(width 0.1143)
		(layer "In13.Cu")
		(net "P5E_CPU0_P2_TX_DN<3>")
	)
	(segment
		(start 363.587538 -294.013382)
		(end 363.557058 -294.031162)
		(width 0.1143)
		(layer "In13.Cu")
		(net "P5E_CPU0_P2_TX_DN<3>")
	)
	(segment
		(start 363.587792 -277.813516)
		(end 363.556042 -277.831804)
		(width 0.1143)
		(layer "In13.Cu")
		(net "P5E_CPU0_P2_TX_DN<3>")
	)
	(segment
		(start 363.626908 -285.890716)
		(end 363.587792 -285.913576)
		(width 0.1143)
		(layer "In13.Cu")
		(net "P5E_CPU0_P2_TX_DN<3>")
	)
	(segment
		(start 363.587792 -285.913576)
		(end 363.556042 -285.931864)
		(width 0.1143)
		(layer "In13.Cu")
		(net "P5E_CPU0_P2_TX_DN<3>")
	)
	(segment
		(start 363.587792 -275.218652)
		(end 363.626908 -275.241512)
		(width 0.1143)
		(layer "In13.Cu")
		(net "P5E_CPU0_P2_TX_DN<3>")
	)
	(segment
		(start 363.587792 -294.658542)
		(end 363.626908 -294.681402)
		(width 0.1143)
		(layer "In13.Cu")
		(net "P5E_CPU0_P2_TX_DN<3>")
	)
	(segment
		(start 363.587792 -288.178494)
		(end 363.626908 -288.201354)
		(width 0.1143)
		(layer "In13.Cu")
		(net "P5E_CPU0_P2_TX_DN<3>")
	)
	(segment
		(start 363.556042 -283.300424)
		(end 363.587792 -283.318712)
		(width 0.1143)
		(layer "In13.Cu")
		(net "P5E_CPU0_P2_TX_DN<3>")
	)
	(segment
		(start 364.027212 -295.450768)
		(end 364.155482 -295.525952)
		(width 0.1143)
		(layer "In13.Cu")
		(net "P5E_CPU0_P2_TX_DN<3>")
	)
	(segment
		(start 363.626908 -277.790656)
		(end 363.587792 -277.813516)
		(width 0.1143)
		(layer "In13.Cu")
		(net "P5E_CPU0_P2_TX_DN<3>")
	)
	(segment
		(start 363.587792 -276.193504)
		(end 363.556042 -276.211792)
		(width 0.1143)
		(layer "In13.Cu")
		(net "P5E_CPU0_P2_TX_DN<3>")
	)
	(segment
		(start 363.304836 -272.466054)
		(end 363.006894 -272.466054)
		(width 0.1143)
		(layer "In13.Cu")
		(net "P5E_CPU0_P2_TX_DN<3>")
	)
	(segment
		(start 363.554264 -286.538924)
		(end 363.587792 -286.558482)
		(width 0.1143)
		(layer "In13.Cu")
		(net "P5E_CPU0_P2_TX_DN<3>")
	)
	(segment
		(start 363.587792 -289.153346)
		(end 363.556042 -289.171634)
		(width 0.1143)
		(layer "In13.Cu")
		(net "P5E_CPU0_P2_TX_DN<3>")
	)
	(segment
		(start 363.006894 -272.466054)
		(end 362.937044 -272.535904)
		(width 0.1143)
		(layer "In13.Cu")
		(net "P5E_CPU0_P2_TX_DN<3>")
	)
	(segment
		(start 363.624368 -287.512252)
		(end 363.587792 -287.533588)
		(width 0.1143)
		(layer "In13.Cu")
		(net "P5E_CPU0_P2_TX_DN<3>")
	)
	(segment
		(start 364.31093 -296.29989)
		(end 364.35665 -296.34561)
		(width 0.1143)
		(layer "In13.Cu")
		(net "P5E_CPU0_P2_TX_DN<3>")
	)
	(segment
		(start 392.026902 -366.795558)
		(end 395.569948 -372.098062)
		(width 0.14224)
		(layer "In13.Cu")
		(net "P5E_CPU0_P2_TX_DN<3>")
	)
	(segment
		(start 363.556042 -289.780218)
		(end 363.587792 -289.798506)
		(width 0.1143)
		(layer "In13.Cu")
		(net "P5E_CPU0_P2_TX_DN<3>")
	)
	(segment
		(start 363.587792 -279.433528)
		(end 363.556042 -279.451816)
		(width 0.1143)
		(layer "In13.Cu")
		(net "P5E_CPU0_P2_TX_DN<3>")
	)
	(segment
		(start 363.587792 -280.078688)
		(end 363.626908 -280.101548)
		(width 0.1143)
		(layer "In13.Cu")
		(net "P5E_CPU0_P2_TX_DN<3>")
	)
	(segment
		(start 364.381288 -300.086522)
		(end 391.967466 -366.684052)
		(width 0.14224)
		(layer "In13.Cu")
		(net "P5E_CPU0_P2_TX_DN<3>")
	)
	(segment
		(start 363.626908 -274.550632)
		(end 363.556042 -274.59178)
		(width 0.1143)
		(layer "In13.Cu")
		(net "P5E_CPU0_P2_TX_DN<3>")
	)
	(segment
		(start 400.91741 -377.1265)
		(end 401.20824 -377.41733)
		(width 0.14224)
		(layer "In13.Cu")
		(net "P5E_CPU0_P2_TX_DN<3>")
	)
	(segment
		(start 363.587792 -278.458676)
		(end 363.626908 -278.481536)
		(width 0.1143)
		(layer "In13.Cu")
		(net "P5E_CPU0_P2_TX_DN<3>")
	)
	(segment
		(start 363.626908 -282.650692)
		(end 363.587792 -282.673552)
		(width 0.1143)
		(layer "In13.Cu")
		(net "P5E_CPU0_P2_TX_DN<3>")
	)
	(segment
		(start 363.556042 -291.40023)
		(end 363.587792 -291.418518)
		(width 0.1143)
		(layer "In13.Cu")
		(net "P5E_CPU0_P2_TX_DN<3>")
	)
	(segment
		(start 363.556042 -280.0604)
		(end 363.587792 -280.078688)
		(width 0.1143)
		(layer "In13.Cu")
		(net "P5E_CPU0_P2_TX_DN<3>")
	)
	(segment
		(start 363.587792 -284.293564)
		(end 363.556042 -284.311852)
		(width 0.1143)
		(layer "In13.Cu")
		(net "P5E_CPU0_P2_TX_DN<3>")
	)
	(segment
		(start 363.626908 -289.130486)
		(end 363.587792 -289.153346)
		(width 0.1143)
		(layer "In13.Cu")
		(net "P5E_CPU0_P2_TX_DN<3>")
	)
	(segment
		(start 398.15135 -375.073418)
		(end 400.607022 -376.090434)
		(width 0.14224)
		(layer "In13.Cu")
		(net "P5E_CPU0_P2_TX_DN<3>")
	)
	(segment
		(start 363.587792 -286.558482)
		(end 363.626908 -286.581342)
		(width 0.1143)
		(layer "In13.Cu")
		(net "P5E_CPU0_P2_TX_DN<3>")
	)
	(segment
		(start 363.554264 -288.158936)
		(end 363.587792 -288.178494)
		(width 0.1143)
		(layer "In13.Cu")
		(net "P5E_CPU0_P2_TX_DN<3>")
	)
	(segment
		(start 363.587792 -282.673552)
		(end 363.556042 -282.69184)
		(width 0.1143)
		(layer "In13.Cu")
		(net "P5E_CPU0_P2_TX_DN<3>")
	)
	(segment
		(start 363.587792 -287.533588)
		(end 363.556042 -287.551876)
		(width 0.1143)
		(layer "In13.Cu")
		(net "P5E_CPU0_P2_TX_DN<3>")
	)
	(segment
		(start 363.087158 -272.770854)
		(end 363.117638 -272.788634)
		(width 0.1143)
		(layer "In13.Cu")
		(net "P5E_CPU0_P2_TX_DN<3>")
	)
	(segment
		(start 363.587792 -292.39337)
		(end 363.556042 -292.411658)
		(width 0.1143)
		(layer "In13.Cu")
		(net "P5E_CPU0_P2_TX_DN<3>")
	)
	(segment
		(start 363.588808 -273.599148)
		(end 363.590332 -273.600164)
		(width 0.1143)
		(layer "In13.Cu")
		(net "P5E_CPU0_P2_TX_DN<3>")
	)
	(segment
		(start 364.155482 -295.525952)
		(end 364.195868 -295.566338)
		(width 0.1143)
		(layer "In13.Cu")
		(net "P5E_CPU0_P2_TX_DN<3>")
	)
	(segment
		(start 363.556042 -284.920436)
		(end 363.587792 -284.938724)
		(width 0.1143)
		(layer "In13.Cu")
		(net "P5E_CPU0_P2_TX_DN<3>")
	)
	(segment
		(start 363.587792 -281.05354)
		(end 363.556042 -281.071828)
		(width 0.1143)
		(layer "In13.Cu")
		(net "P5E_CPU0_P2_TX_DN<3>")
	)
	(segment
		(start 363.556042 -294.640254)
		(end 363.587792 -294.658542)
		(width 0.1143)
		(layer "In13.Cu")
		(net "P5E_CPU0_P2_TX_DN<3>")
	)
	(segment
		(start 363.556042 -281.680412)
		(end 363.587792 -281.6987)
		(width 0.1143)
		(layer "In13.Cu")
		(net "P5E_CPU0_P2_TX_DN<3>")
	)
	(segment
		(start 363.556042 -276.820376)
		(end 363.587792 -276.838664)
		(width 0.1143)
		(layer "In13.Cu")
		(net "P5E_CPU0_P2_TX_DN<3>")
	)
	(segment
		(start 363.587792 -284.938724)
		(end 363.626908 -284.961584)
		(width 0.1143)
		(layer "In13.Cu")
		(net "P5E_CPU0_P2_TX_DN<3>")
	)
	(segment
		(start 397.437356 -374.373648)
		(end 398.107916 -375.044462)
		(width 0.14224)
		(layer "In13.Cu")
		(net "P5E_CPU0_P2_TX_DN<3>")
	)
	(segment
		(start 395.569948 -372.098062)
		(end 397.437356 -374.373648)
		(width 0.14224)
		(layer "In13.Cu")
		(net "P5E_CPU0_P2_TX_DN<3>")
	)
	(segment
		(start 363.587792 -276.838664)
		(end 363.626908 -276.861524)
		(width 0.1143)
		(layer "In13.Cu")
		(net "P5E_CPU0_P2_TX_DN<3>")
	)
	(segment
		(start 363.58703 -273.598132)
		(end 363.587792 -273.59864)
		(width 0.1143)
		(layer "In13.Cu")
		(net "P5E_CPU0_P2_TX_DN<3>")
	)
	(segment
		(start 363.557058 -293.02075)
		(end 363.626654 -293.06139)
		(width 0.1143)
		(layer "In13.Cu")
		(net "P5E_CPU0_P2_TX_DN<3>")
	)
	(segment
		(start 363.587792 -273.59864)
		(end 363.588808 -273.599148)
		(width 0.1143)
		(layer "In13.Cu")
		(net "P5E_CPU0_P2_TX_DN<3>")
	)
	(arc
		(start 363.626908 -284.961584)
		(mid 363.870235 -285.42615)
		(end 363.626908 -285.890716)
		(width 0.1143)
		(layer "In13.Cu")
		(net "P5E_CPU0_P2_TX_DN<3>")
	)
	(arc
		(start 363.626908 -280.101548)
		(mid 363.870235 -280.566114)
		(end 363.626908 -281.03068)
		(width 0.1143)
		(layer "In13.Cu")
		(net "P5E_CPU0_P2_TX_DN<3>")
	)
	(arc
		(start 363.626908 -281.72156)
		(mid 363.870235 -282.186126)
		(end 363.626908 -282.650692)
		(width 0.1143)
		(layer "In13.Cu")
		(net "P5E_CPU0_P2_TX_DN<3>")
	)
	(arc
		(start 363.556042 -281.071828)
		(mid 363.400114 -281.37612)
		(end 363.556042 -281.680412)
		(width 0.1143)
		(layer "In13.Cu")
		(net "P5E_CPU0_P2_TX_DN<3>")
	)
	(arc
		(start 363.556042 -285.931864)
		(mid 363.441366 -286.065198)
		(end 363.400086 -286.236156)
		(width 0.1143)
		(layer "In13.Cu")
		(net "P5E_CPU0_P2_TX_DN<3>")
	)
	(arc
		(start 363.626654 -293.06139)
		(mid 363.869981 -293.525956)
		(end 363.626654 -293.990522)
		(width 0.1143)
		(layer "In13.Cu")
		(net "P5E_CPU0_P2_TX_DN<3>")
	)
	(arc
		(start 363.400086 -286.236156)
		(mid 363.440848 -286.40604)
		(end 363.554264 -286.538924)
		(width 0.1143)
		(layer "In13.Cu")
		(net "P5E_CPU0_P2_TX_DN<3>")
	)
	(arc
		(start 363.556042 -287.551876)
		(mid 363.441366 -287.68521)
		(end 363.400086 -287.856168)
		(width 0.1143)
		(layer "In13.Cu")
		(net "P5E_CPU0_P2_TX_DN<3>")
	)
	(arc
		(start 363.626908 -278.481536)
		(mid 363.870235 -278.946102)
		(end 363.626908 -279.410668)
		(width 0.1143)
		(layer "In13.Cu")
		(net "P5E_CPU0_P2_TX_DN<3>")
	)
	(arc
		(start 363.400086 -294.335962)
		(mid 363.441341 -294.506933)
		(end 363.556042 -294.640254)
		(width 0.1143)
		(layer "In13.Cu")
		(net "P5E_CPU0_P2_TX_DN<3>")
	)
	(arc
		(start 363.87024 -295.145968)
		(mid 363.911789 -295.31739)
		(end 364.027212 -295.450768)
		(width 0.1143)
		(layer "In13.Cu")
		(net "P5E_CPU0_P2_TX_DN<3>")
	)
	(arc
		(start 363.626908 -276.861524)
		(mid 363.870235 -277.32609)
		(end 363.626908 -277.790656)
		(width 0.1143)
		(layer "In13.Cu")
		(net "P5E_CPU0_P2_TX_DN<3>")
	)
	(arc
		(start 363.626908 -283.341572)
		(mid 363.870235 -283.806138)
		(end 363.626908 -284.270704)
		(width 0.1143)
		(layer "In13.Cu")
		(net "P5E_CPU0_P2_TX_DN<3>")
	)
	(arc
		(start 363.626908 -289.821366)
		(mid 363.870235 -290.285932)
		(end 363.626908 -290.750498)
		(width 0.1143)
		(layer "In13.Cu")
		(net "P5E_CPU0_P2_TX_DN<3>")
	)
	(arc
		(start 363.556042 -279.451816)
		(mid 363.400114 -279.756108)
		(end 363.556042 -280.0604)
		(width 0.1143)
		(layer "In13.Cu")
		(net "P5E_CPU0_P2_TX_DN<3>")
	)
	(arc
		(start 363.156754 -272.811494)
		(mid 363.335567 -273.013844)
		(end 363.400086 -273.27606)
		(width 0.1143)
		(layer "In13.Cu")
		(net "P5E_CPU0_P2_TX_DN<3>")
	)
	(arc
		(start 363.626908 -286.581342)
		(mid 363.805721 -286.783692)
		(end 363.87024 -287.045908)
		(width 0.1143)
		(layer "In13.Cu")
		(net "P5E_CPU0_P2_TX_DN<3>")
	)
	(arc
		(start 363.87024 -287.045908)
		(mid 363.805004 -287.309499)
		(end 363.624368 -287.512252)
		(width 0.1143)
		(layer "In13.Cu")
		(net "P5E_CPU0_P2_TX_DN<3>")
	)
	(arc
		(start 363.556042 -289.171634)
		(mid 363.400114 -289.475926)
		(end 363.556042 -289.780218)
		(width 0.1143)
		(layer "In13.Cu")
		(net "P5E_CPU0_P2_TX_DN<3>")
	)
	(arc
		(start 363.556042 -274.59178)
		(mid 363.400114 -274.896072)
		(end 363.556042 -275.200364)
		(width 0.1143)
		(layer "In13.Cu")
		(net "P5E_CPU0_P2_TX_DN<3>")
	)
	(arc
		(start 363.400086 -292.71595)
		(mid 363.441635 -292.887372)
		(end 363.557058 -293.02075)
		(width 0.1143)
		(layer "In13.Cu")
		(net "P5E_CPU0_P2_TX_DN<3>")
	)
	(arc
		(start 363.556042 -277.831804)
		(mid 363.400114 -278.136096)
		(end 363.556042 -278.440388)
		(width 0.1143)
		(layer "In13.Cu")
		(net "P5E_CPU0_P2_TX_DN<3>")
	)
	(arc
		(start 363.556042 -284.311852)
		(mid 363.400114 -284.616144)
		(end 363.556042 -284.920436)
		(width 0.1143)
		(layer "In13.Cu")
		(net "P5E_CPU0_P2_TX_DN<3>")
	)
	(arc
		(start 363.556042 -282.69184)
		(mid 363.400114 -282.996132)
		(end 363.556042 -283.300424)
		(width 0.1143)
		(layer "In13.Cu")
		(net "P5E_CPU0_P2_TX_DN<3>")
	)
	(arc
		(start 363.556042 -276.211792)
		(mid 363.400114 -276.516084)
		(end 363.556042 -276.820376)
		(width 0.1143)
		(layer "In13.Cu")
		(net "P5E_CPU0_P2_TX_DN<3>")
	)
	(arc
		(start 363.626908 -288.201354)
		(mid 363.870235 -288.66592)
		(end 363.626908 -289.130486)
		(width 0.1143)
		(layer "In13.Cu")
		(net "P5E_CPU0_P2_TX_DN<3>")
	)
	(arc
		(start 398.107916 -375.044462)
		(mid 398.128211 -375.061072)
		(end 398.15135 -375.073418)
		(width 0.14224)
		(layer "In13.Cu")
		(net "P5E_CPU0_P2_TX_DN<3>")
	)
	(arc
		(start 363.400086 -273.27606)
		(mid 363.441341 -273.447031)
		(end 363.556042 -273.580352)
		(width 0.1143)
		(layer "In13.Cu")
		(net "P5E_CPU0_P2_TX_DN<3>")
	)
	(arc
		(start 363.626908 -273.6215)
		(mid 363.870235 -274.086066)
		(end 363.626908 -274.550632)
		(width 0.1143)
		(layer "In13.Cu")
		(net "P5E_CPU0_P2_TX_DN<3>")
	)
	(arc
		(start 363.626908 -291.441378)
		(mid 363.870235 -291.905944)
		(end 363.626908 -292.37051)
		(width 0.1143)
		(layer "In13.Cu")
		(net "P5E_CPU0_P2_TX_DN<3>")
	)
	(arc
		(start 363.626908 -275.241512)
		(mid 363.870235 -275.706078)
		(end 363.626908 -276.170644)
		(width 0.1143)
		(layer "In13.Cu")
		(net "P5E_CPU0_P2_TX_DN<3>")
	)
	(arc
		(start 363.556042 -290.791646)
		(mid 363.400114 -291.095938)
		(end 363.556042 -291.40023)
		(width 0.1143)
		(layer "In13.Cu")
		(net "P5E_CPU0_P2_TX_DN<3>")
	)
	(arc
		(start 364.35665 -299.963332)
		(mid 364.362928 -300.026133)
		(end 364.381288 -300.086522)
		(width 0.14224)
		(layer "In13.Cu")
		(net "P5E_CPU0_P2_TX_DN<3>")
	)
	(arc
		(start 362.937044 -272.535904)
		(mid 362.989461 -272.667835)
		(end 363.087158 -272.770854)
		(width 0.1143)
		(layer "In13.Cu")
		(net "P5E_CPU0_P2_TX_DN<3>")
	)
	(arc
		(start 391.967466 -366.684052)
		(mid 391.994453 -366.74126)
		(end 392.026902 -366.795558)
		(width 0.14224)
		(layer "In13.Cu")
		(net "P5E_CPU0_P2_TX_DN<3>")
	)
	(arc
		(start 363.557058 -294.031162)
		(mid 363.441631 -294.164538)
		(end 363.400086 -294.335962)
		(width 0.1143)
		(layer "In13.Cu")
		(net "P5E_CPU0_P2_TX_DN<3>")
	)
	(arc
		(start 363.626908 -294.681402)
		(mid 363.805721 -294.883752)
		(end 363.87024 -295.145968)
		(width 0.1143)
		(layer "In13.Cu")
		(net "P5E_CPU0_P2_TX_DN<3>")
	)
	(arc
		(start 363.556042 -292.411658)
		(mid 363.441366 -292.544992)
		(end 363.400086 -292.71595)
		(width 0.1143)
		(layer "In13.Cu")
		(net "P5E_CPU0_P2_TX_DN<3>")
	)
	(arc
		(start 363.400086 -287.856168)
		(mid 363.440848 -288.026052)
		(end 363.554264 -288.158936)
		(width 0.1143)
		(layer "In13.Cu")
		(net "P5E_CPU0_P2_TX_DN<3>")
	)
	(arc
		(start 364.195868 -295.566338)
		(mid 364.281001 -295.693843)
		(end 364.31093 -295.844214)
		(width 0.1143)
		(layer "In13.Cu")
		(net "P5E_CPU0_P2_TX_DN<3>")
	)
	(segment
		(start 399.23593 -380.15164)
		(end 399.23593 -380.85522)
		(width 0.12954)
		(layer "F.Cu")
		(net "P5E_CPU0_P2_TX_DN<2>")
	)
	(segment
		(start 399.50644 -379.88113)
		(end 399.23593 -380.15164)
		(width 0.12954)
		(layer "F.Cu")
		(net "P5E_CPU0_P2_TX_DN<2>")
	)
	(segment
		(start 399.23593 -380.85522)
		(end 399.53184 -381.15113)
		(width 0.12954)
		(layer "F.Cu")
		(net "P5E_CPU0_P2_TX_DN<2>")
	)
	(segment
		(start 362.837984 -273.820128)
		(end 363.304836 -274.086066)
		(width 0.12954)
		(layer "F.Cu")
		(net "P5E_CPU0_P2_TX_DN<2>")
	)
	(segment
		(start 362.615988 -289.780218)
		(end 362.686854 -289.821366)
		(width 0.1143)
		(layer "In13.Cu")
		(net "P5E_CPU0_P2_TX_DN<2>")
	)
	(segment
		(start 362.646976 -292.393878)
		(end 362.645706 -292.39464)
		(width 0.1143)
		(layer "In13.Cu")
		(net "P5E_CPU0_P2_TX_DN<2>")
	)
	(segment
		(start 362.646468 -283.31795)
		(end 362.649008 -283.319474)
		(width 0.1143)
		(layer "In13.Cu")
		(net "P5E_CPU0_P2_TX_DN<2>")
	)
	(segment
		(start 363.37875 -295.908984)
		(end 363.37875 -296.235628)
		(width 0.1143)
		(layer "In13.Cu")
		(net "P5E_CPU0_P2_TX_DN<2>")
	)
	(segment
		(start 362.64596 -286.557974)
		(end 362.690156 -286.583628)
		(width 0.1143)
		(layer "In13.Cu")
		(net "P5E_CPU0_P2_TX_DN<2>")
	)
	(segment
		(start 362.61421 -288.158936)
		(end 362.686854 -288.201354)
		(width 0.1143)
		(layer "In13.Cu")
		(net "P5E_CPU0_P2_TX_DN<2>")
	)
	(segment
		(start 363.006894 -274.086066)
		(end 362.92409 -274.16887)
		(width 0.1143)
		(layer "In13.Cu")
		(net "P5E_CPU0_P2_TX_DN<2>")
	)
	(segment
		(start 362.663486 -293.991792)
		(end 362.646214 -294.001698)
		(width 0.1143)
		(layer "In13.Cu")
		(net "P5E_CPU0_P2_TX_DN<2>")
	)
	(segment
		(start 362.639102 -283.313886)
		(end 362.646468 -283.31795)
		(width 0.1143)
		(layer "In13.Cu")
		(net "P5E_CPU0_P2_TX_DN<2>")
	)
	(segment
		(start 362.686854 -290.750498)
		(end 362.615988 -290.791646)
		(width 0.1143)
		(layer "In13.Cu")
		(net "P5E_CPU0_P2_TX_DN<2>")
	)
	(segment
		(start 362.643674 -286.55645)
		(end 362.64596 -286.557974)
		(width 0.1143)
		(layer "In13.Cu")
		(net "P5E_CPU0_P2_TX_DN<2>")
	)
	(segment
		(start 362.686854 -289.130486)
		(end 362.615988 -289.171634)
		(width 0.1143)
		(layer "In13.Cu")
		(net "P5E_CPU0_P2_TX_DN<2>")
	)
	(segment
		(start 362.64215 -282.6766)
		(end 362.639102 -282.678378)
		(width 0.1143)
		(layer "In13.Cu")
		(net "P5E_CPU0_P2_TX_DN<2>")
	)
	(segment
		(start 362.61167 -289.77717)
		(end 362.615988 -289.780218)
		(width 0.1143)
		(layer "In13.Cu")
		(net "P5E_CPU0_P2_TX_DN<2>")
	)
	(segment
		(start 362.646976 -280.07818)
		(end 362.648754 -280.079196)
		(width 0.1143)
		(layer "In13.Cu")
		(net "P5E_CPU0_P2_TX_DN<2>")
	)
	(segment
		(start 394.581634 -372.406672)
		(end 396.590012 -374.853708)
		(width 0.14224)
		(layer "In13.Cu")
		(net "P5E_CPU0_P2_TX_DN<2>")
	)
	(segment
		(start 362.650278 -292.391846)
		(end 362.648754 -292.392862)
		(width 0.1143)
		(layer "In13.Cu")
		(net "P5E_CPU0_P2_TX_DN<2>")
	)
	(segment
		(start 362.648754 -280.079196)
		(end 362.686854 -280.101548)
		(width 0.1143)
		(layer "In13.Cu")
		(net "P5E_CPU0_P2_TX_DN<2>")
	)
	(segment
		(start 362.686854 -277.790656)
		(end 362.615988 -277.831804)
		(width 0.1143)
		(layer "In13.Cu")
		(net "P5E_CPU0_P2_TX_DN<2>")
	)
	(segment
		(start 399.21561 -377.991624)
		(end 399.21561 -379.5903)
		(width 0.14224)
		(layer "In13.Cu")
		(net "P5E_CPU0_P2_TX_DN<2>")
	)
	(segment
		(start 399.010378 -377.374404)
		(end 399.170144 -377.760484)
		(width 0.14224)
		(layer "In13.Cu")
		(net "P5E_CPU0_P2_TX_DN<2>")
	)
	(segment
		(start 362.615988 -287.551876)
		(end 362.613194 -287.553908)
		(width 0.1143)
		(layer "In13.Cu")
		(net "P5E_CPU0_P2_TX_DN<2>")
	)
	(segment
		(start 363.304836 -274.086066)
		(end 363.006894 -274.086066)
		(width 0.1143)
		(layer "In13.Cu")
		(net "P5E_CPU0_P2_TX_DN<2>")
	)
	(segment
		(start 396.590012 -374.853708)
		(end 398.809464 -377.073414)
		(width 0.14224)
		(layer "In13.Cu")
		(net "P5E_CPU0_P2_TX_DN<2>")
	)
	(segment
		(start 362.650532 -283.32049)
		(end 362.678726 -283.336746)
		(width 0.1143)
		(layer "In13.Cu")
		(net "P5E_CPU0_P2_TX_DN<2>")
	)
	(segment
		(start 362.686854 -284.961584)
		(end 362.688886 -284.962854)
		(width 0.1143)
		(layer "In13.Cu")
		(net "P5E_CPU0_P2_TX_DN<2>")
	)
	(segment
		(start 362.64342 -292.39591)
		(end 362.640626 -292.397434)
		(width 0.1143)
		(layer "In13.Cu")
		(net "P5E_CPU0_P2_TX_DN<2>")
	)
	(segment
		(start 362.64088 -284.934914)
		(end 362.686092 -284.961076)
		(width 0.1143)
		(layer "In13.Cu")
		(net "P5E_CPU0_P2_TX_DN<2>")
	)
	(segment
		(start 362.655358 -293.043102)
		(end 362.687108 -293.06139)
		(width 0.1143)
		(layer "In13.Cu")
		(net "P5E_CPU0_P2_TX_DN<2>")
	)
	(segment
		(start 362.686854 -274.550632)
		(end 362.615988 -274.59178)
		(width 0.1143)
		(layer "In13.Cu")
		(net "P5E_CPU0_P2_TX_DN<2>")
	)
	(segment
		(start 362.646976 -293.038022)
		(end 362.647738 -293.03853)
		(width 0.1143)
		(layer "In13.Cu")
		(net "P5E_CPU0_P2_TX_DN<2>")
	)
	(segment
		(start 362.686854 -282.650692)
		(end 362.646468 -282.674314)
		(width 0.1143)
		(layer "In13.Cu")
		(net "P5E_CPU0_P2_TX_DN<2>")
	)
	(segment
		(start 362.6866 -287.510728)
		(end 362.615988 -287.551876)
		(width 0.1143)
		(layer "In13.Cu")
		(net "P5E_CPU0_P2_TX_DN<2>")
	)
	(segment
		(start 362.615988 -289.171634)
		(end 362.61167 -289.174682)
		(width 0.1143)
		(layer "In13.Cu")
		(net "P5E_CPU0_P2_TX_DN<2>")
	)
	(segment
		(start 362.636308 -281.69235)
		(end 362.686092 -281.721052)
		(width 0.1143)
		(layer "In13.Cu")
		(net "P5E_CPU0_P2_TX_DN<2>")
	)
	(segment
		(start 362.615988 -276.820376)
		(end 362.686854 -276.861524)
		(width 0.1143)
		(layer "In13.Cu")
		(net "P5E_CPU0_P2_TX_DN<2>")
	)
	(segment
		(start 362.647738 -292.39337)
		(end 362.646976 -292.393878)
		(width 0.1143)
		(layer "In13.Cu")
		(net "P5E_CPU0_P2_TX_DN<2>")
	)
	(segment
		(start 362.648754 -293.039038)
		(end 362.653834 -293.042086)
		(width 0.1143)
		(layer "In13.Cu")
		(net "P5E_CPU0_P2_TX_DN<2>")
	)
	(segment
		(start 362.615988 -275.200364)
		(end 362.686854 -275.241512)
		(width 0.1143)
		(layer "In13.Cu")
		(net "P5E_CPU0_P2_TX_DN<2>")
	)
	(segment
		(start 362.615988 -280.0604)
		(end 362.646976 -280.07818)
		(width 0.1143)
		(layer "In13.Cu")
		(net "P5E_CPU0_P2_TX_DN<2>")
	)
	(segment
		(start 362.686854 -281.03068)
		(end 362.647738 -281.05354)
		(width 0.1143)
		(layer "In13.Cu")
		(net "P5E_CPU0_P2_TX_DN<2>")
	)
	(segment
		(start 362.647738 -293.03853)
		(end 362.648754 -293.039038)
		(width 0.1143)
		(layer "In13.Cu")
		(net "P5E_CPU0_P2_TX_DN<2>")
	)
	(segment
		(start 362.648754 -292.392862)
		(end 362.647738 -292.39337)
		(width 0.1143)
		(layer "In13.Cu")
		(net "P5E_CPU0_P2_TX_DN<2>")
	)
	(segment
		(start 362.615988 -291.40023)
		(end 362.686854 -291.441378)
		(width 0.1143)
		(layer "In13.Cu")
		(net "P5E_CPU0_P2_TX_DN<2>")
	)
	(segment
		(start 362.643674 -286.556704)
		(end 362.643674 -286.55645)
		(width 0.1143)
		(layer "In13.Cu")
		(net "P5E_CPU0_P2_TX_DN<2>")
	)
	(segment
		(start 362.460032 -287.85312)
		(end 362.460032 -287.856168)
		(width 0.1143)
		(layer "In13.Cu")
		(net "P5E_CPU0_P2_TX_DN<2>")
	)
	(segment
		(start 362.980224 -295.34612)
		(end 363.262418 -295.628314)
		(width 0.1143)
		(layer "In13.Cu")
		(net "P5E_CPU0_P2_TX_DN<2>")
	)
	(segment
		(start 362.615988 -293.020242)
		(end 362.646976 -293.038022)
		(width 0.1143)
		(layer "In13.Cu")
		(net "P5E_CPU0_P2_TX_DN<2>")
	)
	(segment
		(start 362.647738 -281.05354)
		(end 362.636308 -281.05989)
		(width 0.1143)
		(layer "In13.Cu")
		(net "P5E_CPU0_P2_TX_DN<2>")
	)
	(segment
		(start 362.930186 -295.145968)
		(end 362.930186 -295.22547)
		(width 0.1143)
		(layer "In13.Cu")
		(net "P5E_CPU0_P2_TX_DN<2>")
	)
	(segment
		(start 362.64215 -284.296866)
		(end 362.64088 -284.297374)
		(width 0.1143)
		(layer "In13.Cu")
		(net "P5E_CPU0_P2_TX_DN<2>")
	)
	(segment
		(start 362.646468 -282.674314)
		(end 362.64215 -282.6766)
		(width 0.1143)
		(layer "In13.Cu")
		(net "P5E_CPU0_P2_TX_DN<2>")
	)
	(segment
		(start 399.21561 -379.5903)
		(end 399.50644 -379.88113)
		(width 0.14224)
		(layer "In13.Cu")
		(net "P5E_CPU0_P2_TX_DN<2>")
	)
	(segment
		(start 362.650786 -284.291786)
		(end 362.64215 -284.296866)
		(width 0.1143)
		(layer "In13.Cu")
		(net "P5E_CPU0_P2_TX_DN<2>")
	)
	(segment
		(start 362.686854 -284.270704)
		(end 362.65231 -284.29077)
		(width 0.1143)
		(layer "In13.Cu")
		(net "P5E_CPU0_P2_TX_DN<2>")
	)
	(segment
		(start 362.686854 -279.410668)
		(end 362.615988 -279.451816)
		(width 0.1143)
		(layer "In13.Cu")
		(net "P5E_CPU0_P2_TX_DN<2>")
	)
	(segment
		(start 362.649008 -283.319474)
		(end 362.650532 -283.32049)
		(width 0.1143)
		(layer "In13.Cu")
		(net "P5E_CPU0_P2_TX_DN<2>")
	)
	(segment
		(start 362.653834 -293.042086)
		(end 362.655358 -293.043102)
		(width 0.1143)
		(layer "In13.Cu")
		(net "P5E_CPU0_P2_TX_DN<2>")
	)
	(segment
		(start 390.923526 -366.943132)
		(end 394.506196 -372.305072)
		(width 0.14224)
		(layer "In13.Cu")
		(net "P5E_CPU0_P2_TX_DN<2>")
	)
	(segment
		(start 363.455458 -300.69028)
		(end 390.863836 -366.831626)
		(width 0.14224)
		(layer "In13.Cu")
		(net "P5E_CPU0_P2_TX_DN<2>")
	)
	(segment
		(start 362.679488 -283.337254)
		(end 362.686092 -283.341064)
		(width 0.1143)
		(layer "In13.Cu")
		(net "P5E_CPU0_P2_TX_DN<2>")
	)
	(segment
		(start 362.690156 -286.583628)
		(end 362.708698 -286.59709)
		(width 0.1143)
		(layer "In13.Cu")
		(net "P5E_CPU0_P2_TX_DN<2>")
	)
	(segment
		(start 363.37875 -296.235628)
		(end 363.42447 -296.281348)
		(width 0.1143)
		(layer "In13.Cu")
		(net "P5E_CPU0_P2_TX_DN<2>")
	)
	(segment
		(start 362.65231 -284.29077)
		(end 362.650786 -284.291786)
		(width 0.1143)
		(layer "In13.Cu")
		(net "P5E_CPU0_P2_TX_DN<2>")
	)
	(segment
		(start 362.640626 -292.397434)
		(end 362.615988 -292.411658)
		(width 0.1143)
		(layer "In13.Cu")
		(net "P5E_CPU0_P2_TX_DN<2>")
	)
	(segment
		(start 362.615988 -278.440388)
		(end 362.686854 -278.481536)
		(width 0.1143)
		(layer "In13.Cu")
		(net "P5E_CPU0_P2_TX_DN<2>")
	)
	(segment
		(start 362.678726 -283.336746)
		(end 362.679488 -283.337254)
		(width 0.1143)
		(layer "In13.Cu")
		(net "P5E_CPU0_P2_TX_DN<2>")
	)
	(segment
		(start 362.686854 -292.37051)
		(end 362.650278 -292.391846)
		(width 0.1143)
		(layer "In13.Cu")
		(net "P5E_CPU0_P2_TX_DN<2>")
	)
	(segment
		(start 362.645706 -292.39464)
		(end 362.644182 -292.395402)
		(width 0.1143)
		(layer "In13.Cu")
		(net "P5E_CPU0_P2_TX_DN<2>")
	)
	(segment
		(start 363.42447 -296.281348)
		(end 363.42447 -296.309796)
		(width 0.1143)
		(layer "In13.Cu")
		(net "P5E_CPU0_P2_TX_DN<2>")
	)
	(segment
		(start 362.688886 -285.889446)
		(end 362.645452 -285.914592)
		(width 0.1143)
		(layer "In13.Cu")
		(net "P5E_CPU0_P2_TX_DN<2>")
	)
	(segment
		(start 362.641134 -294.004746)
		(end 362.640626 -294.005)
		(width 0.1143)
		(layer "In13.Cu")
		(net "P5E_CPU0_P2_TX_DN<2>")
	)
	(segment
		(start 362.640626 -294.005)
		(end 362.611162 -294.024812)
		(width 0.1143)
		(layer "In13.Cu")
		(net "P5E_CPU0_P2_TX_DN<2>")
	)
	(segment
		(start 362.644182 -292.395402)
		(end 362.64342 -292.39591)
		(width 0.1143)
		(layer "In13.Cu")
		(net "P5E_CPU0_P2_TX_DN<2>")
	)
	(segment
		(start 362.929932 -287.0327)
		(end 362.929932 -287.045908)
		(width 0.1143)
		(layer "In13.Cu")
		(net "P5E_CPU0_P2_TX_DN<2>")
	)
	(segment
		(start 362.686854 -276.170644)
		(end 362.615988 -276.211792)
		(width 0.1143)
		(layer "In13.Cu")
		(net "P5E_CPU0_P2_TX_DN<2>")
	)
	(segment
		(start 363.42447 -296.309796)
		(end 363.42447 -300.534578)
		(width 0.14224)
		(layer "In13.Cu")
		(net "P5E_CPU0_P2_TX_DN<2>")
	)
	(segment
		(start 362.646214 -294.001698)
		(end 362.641134 -294.004746)
		(width 0.1143)
		(layer "In13.Cu")
		(net "P5E_CPU0_P2_TX_DN<2>")
	)
	(segment
		(start 362.63072 -294.64889)
		(end 362.686092 -294.680894)
		(width 0.1143)
		(layer "In13.Cu")
		(net "P5E_CPU0_P2_TX_DN<2>")
	)
	(segment
		(start 362.645452 -285.914592)
		(end 362.643928 -285.915608)
		(width 0.1143)
		(layer "In13.Cu")
		(net "P5E_CPU0_P2_TX_DN<2>")
	)
	(segment
		(start 362.687108 -293.06139)
		(end 362.709206 -293.077138)
		(width 0.1143)
		(layer "In13.Cu")
		(net "P5E_CPU0_P2_TX_DN<2>")
	)
	(arc
		(start 363.42447 -300.534578)
		(mid 363.432292 -300.613956)
		(end 363.455458 -300.69028)
		(width 0.14224)
		(layer "In13.Cu")
		(net "P5E_CPU0_P2_TX_DN<2>")
	)
	(arc
		(start 362.686854 -275.241512)
		(mid 362.930181 -275.706078)
		(end 362.686854 -276.170644)
		(width 0.1143)
		(layer "In13.Cu")
		(net "P5E_CPU0_P2_TX_DN<2>")
	)
	(arc
		(start 362.686854 -288.201354)
		(mid 362.930181 -288.66592)
		(end 362.686854 -289.130486)
		(width 0.1143)
		(layer "In13.Cu")
		(net "P5E_CPU0_P2_TX_DN<2>")
	)
	(arc
		(start 362.686854 -283.341572)
		(mid 362.930181 -283.806138)
		(end 362.686854 -284.270704)
		(width 0.1143)
		(layer "In13.Cu")
		(net "P5E_CPU0_P2_TX_DN<2>")
	)
	(arc
		(start 399.170144 -377.760484)
		(mid 399.204224 -377.873821)
		(end 399.21561 -377.991624)
		(width 0.14224)
		(layer "In13.Cu")
		(net "P5E_CPU0_P2_TX_DN<2>")
	)
	(arc
		(start 362.686854 -276.861524)
		(mid 362.930181 -277.32609)
		(end 362.686854 -277.790656)
		(width 0.1143)
		(layer "In13.Cu")
		(net "P5E_CPU0_P2_TX_DN<2>")
	)
	(arc
		(start 362.92028 -274.19173)
		(mid 362.838847 -274.394128)
		(end 362.686854 -274.550632)
		(width 0.1143)
		(layer "In13.Cu")
		(net "P5E_CPU0_P2_TX_DN<2>")
	)
	(arc
		(start 362.929932 -287.045908)
		(mid 362.865423 -287.308242)
		(end 362.6866 -287.510728)
		(width 0.1143)
		(layer "In13.Cu")
		(net "P5E_CPU0_P2_TX_DN<2>")
	)
	(arc
		(start 362.686854 -280.101548)
		(mid 362.930181 -280.566114)
		(end 362.686854 -281.03068)
		(width 0.1143)
		(layer "In13.Cu")
		(net "P5E_CPU0_P2_TX_DN<2>")
	)
	(arc
		(start 362.686092 -284.961076)
		(mid 362.686473 -284.96133)
		(end 362.686854 -284.961584)
		(width 0.1143)
		(layer "In13.Cu")
		(net "P5E_CPU0_P2_TX_DN<2>")
	)
	(arc
		(start 362.64088 -284.297374)
		(mid 362.460395 -284.616144)
		(end 362.64088 -284.934914)
		(width 0.1143)
		(layer "In13.Cu")
		(net "P5E_CPU0_P2_TX_DN<2>")
	)
	(arc
		(start 394.506196 -372.305072)
		(mid 394.542667 -372.356798)
		(end 394.581634 -372.406672)
		(width 0.14224)
		(layer "In13.Cu")
		(net "P5E_CPU0_P2_TX_DN<2>")
	)
	(arc
		(start 362.611162 -294.024812)
		(mid 362.447499 -294.342341)
		(end 362.63072 -294.64889)
		(width 0.1143)
		(layer "In13.Cu")
		(net "P5E_CPU0_P2_TX_DN<2>")
	)
	(arc
		(start 362.686854 -281.72156)
		(mid 362.930181 -282.186126)
		(end 362.686854 -282.650692)
		(width 0.1143)
		(layer "In13.Cu")
		(net "P5E_CPU0_P2_TX_DN<2>")
	)
	(arc
		(start 362.615988 -277.831804)
		(mid 362.464399 -278.136096)
		(end 362.615988 -278.440388)
		(width 0.1143)
		(layer "In13.Cu")
		(net "P5E_CPU0_P2_TX_DN<2>")
	)
	(arc
		(start 362.613194 -287.553908)
		(mid 362.500553 -287.685044)
		(end 362.460032 -287.85312)
		(width 0.1143)
		(layer "In13.Cu")
		(net "P5E_CPU0_P2_TX_DN<2>")
	)
	(arc
		(start 362.686092 -281.721052)
		(mid 362.686473 -281.721306)
		(end 362.686854 -281.72156)
		(width 0.1143)
		(layer "In13.Cu")
		(net "P5E_CPU0_P2_TX_DN<2>")
	)
	(arc
		(start 362.615988 -279.451816)
		(mid 362.464399 -279.756108)
		(end 362.615988 -280.0604)
		(width 0.1143)
		(layer "In13.Cu")
		(net "P5E_CPU0_P2_TX_DN<2>")
	)
	(arc
		(start 398.809464 -377.073414)
		(mid 398.924778 -377.213991)
		(end 399.010378 -377.374404)
		(width 0.14224)
		(layer "In13.Cu")
		(net "P5E_CPU0_P2_TX_DN<2>")
	)
	(arc
		(start 362.636308 -281.05989)
		(mid 362.454517 -281.37612)
		(end 362.636308 -281.69235)
		(width 0.1143)
		(layer "In13.Cu")
		(net "P5E_CPU0_P2_TX_DN<2>")
	)
	(arc
		(start 362.686092 -294.680894)
		(mid 362.686473 -294.681148)
		(end 362.686854 -294.681402)
		(width 0.1143)
		(layer "In13.Cu")
		(net "P5E_CPU0_P2_TX_DN<2>")
	)
	(arc
		(start 362.92409 -274.16887)
		(mid 362.922302 -274.180319)
		(end 362.92028 -274.19173)
		(width 0.1143)
		(layer "In13.Cu")
		(net "P5E_CPU0_P2_TX_DN<2>")
	)
	(arc
		(start 362.643928 -285.915608)
		(mid 362.460171 -286.236046)
		(end 362.643674 -286.556704)
		(width 0.1143)
		(layer "In13.Cu")
		(net "P5E_CPU0_P2_TX_DN<2>")
	)
	(arc
		(start 362.930186 -295.22547)
		(mid 362.943194 -295.290775)
		(end 362.980224 -295.34612)
		(width 0.1143)
		(layer "In13.Cu")
		(net "P5E_CPU0_P2_TX_DN<2>")
	)
	(arc
		(start 363.262418 -295.628314)
		(mid 363.348461 -295.757086)
		(end 363.37875 -295.908984)
		(width 0.1143)
		(layer "In13.Cu")
		(net "P5E_CPU0_P2_TX_DN<2>")
	)
	(arc
		(start 362.615988 -274.59178)
		(mid 362.464399 -274.896072)
		(end 362.615988 -275.200364)
		(width 0.1143)
		(layer "In13.Cu")
		(net "P5E_CPU0_P2_TX_DN<2>")
	)
	(arc
		(start 362.709206 -293.077138)
		(mid 362.935407 -293.546866)
		(end 362.663486 -293.991792)
		(width 0.1143)
		(layer "In13.Cu")
		(net "P5E_CPU0_P2_TX_DN<2>")
	)
	(arc
		(start 362.615988 -276.211792)
		(mid 362.464399 -276.516084)
		(end 362.615988 -276.820376)
		(width 0.1143)
		(layer "In13.Cu")
		(net "P5E_CPU0_P2_TX_DN<2>")
	)
	(arc
		(start 362.686854 -291.441378)
		(mid 362.930181 -291.905944)
		(end 362.686854 -292.37051)
		(width 0.1143)
		(layer "In13.Cu")
		(net "P5E_CPU0_P2_TX_DN<2>")
	)
	(arc
		(start 362.686854 -289.821366)
		(mid 362.930181 -290.285932)
		(end 362.686854 -290.750498)
		(width 0.1143)
		(layer "In13.Cu")
		(net "P5E_CPU0_P2_TX_DN<2>")
	)
	(arc
		(start 390.863836 -366.831626)
		(mid 390.890953 -366.888839)
		(end 390.923526 -366.943132)
		(width 0.14224)
		(layer "In13.Cu")
		(net "P5E_CPU0_P2_TX_DN<2>")
	)
	(arc
		(start 362.686092 -283.341064)
		(mid 362.686473 -283.341318)
		(end 362.686854 -283.341572)
		(width 0.1143)
		(layer "In13.Cu")
		(net "P5E_CPU0_P2_TX_DN<2>")
	)
	(arc
		(start 362.615988 -290.791646)
		(mid 362.466891 -291.095938)
		(end 362.615988 -291.40023)
		(width 0.1143)
		(layer "In13.Cu")
		(net "P5E_CPU0_P2_TX_DN<2>")
	)
	(arc
		(start 362.61167 -289.174682)
		(mid 362.457265 -289.475926)
		(end 362.61167 -289.77717)
		(width 0.1143)
		(layer "In13.Cu")
		(net "P5E_CPU0_P2_TX_DN<2>")
	)
	(arc
		(start 362.686854 -294.681402)
		(mid 362.865667 -294.883752)
		(end 362.930186 -295.145968)
		(width 0.1143)
		(layer "In13.Cu")
		(net "P5E_CPU0_P2_TX_DN<2>")
	)
	(arc
		(start 362.460032 -287.856168)
		(mid 362.500794 -288.026052)
		(end 362.61421 -288.158936)
		(width 0.1143)
		(layer "In13.Cu")
		(net "P5E_CPU0_P2_TX_DN<2>")
	)
	(arc
		(start 362.615988 -292.411658)
		(mid 362.46006 -292.71595)
		(end 362.615988 -293.020242)
		(width 0.1143)
		(layer "In13.Cu")
		(net "P5E_CPU0_P2_TX_DN<2>")
	)
	(arc
		(start 362.708698 -286.59709)
		(mid 362.871505 -286.788389)
		(end 362.929932 -287.0327)
		(width 0.1143)
		(layer "In13.Cu")
		(net "P5E_CPU0_P2_TX_DN<2>")
	)
	(arc
		(start 362.639102 -282.678378)
		(mid 362.456625 -282.996132)
		(end 362.639102 -283.313886)
		(width 0.1143)
		(layer "In13.Cu")
		(net "P5E_CPU0_P2_TX_DN<2>")
	)
	(arc
		(start 362.686854 -278.481536)
		(mid 362.930181 -278.946102)
		(end 362.686854 -279.410668)
		(width 0.1143)
		(layer "In13.Cu")
		(net "P5E_CPU0_P2_TX_DN<2>")
	)
	(arc
		(start 362.688886 -284.962854)
		(mid 362.931606 -285.42615)
		(end 362.688886 -285.889446)
		(width 0.1143)
		(layer "In13.Cu")
		(net "P5E_CPU0_P2_TX_DN<2>")
	)
	(segment
		(start 397.328898 -384.94335)
		(end 398.032478 -384.94335)
		(width 0.12954)
		(layer "F.Cu")
		(net "P5E_CPU0_P2_TX_DN<1>")
	)
	(segment
		(start 398.032478 -384.94335)
		(end 398.328388 -385.23926)
		(width 0.12954)
		(layer "F.Cu")
		(net "P5E_CPU0_P2_TX_DN<1>")
	)
	(segment
		(start 397.058388 -385.21386)
		(end 397.328898 -384.94335)
		(width 0.12954)
		(layer "F.Cu")
		(net "P5E_CPU0_P2_TX_DN<1>")
	)
	(segment
		(start 362.837984 -270.580104)
		(end 363.304836 -270.846042)
		(width 0.12954)
		(layer "F.Cu")
		(net "P5E_CPU0_P2_TX_DN<1>")
	)
	(segment
		(start 361.707684 -276.193504)
		(end 361.677204 -276.211284)
		(width 0.1143)
		(layer "In13.Cu")
		(net "P5E_CPU0_P2_TX_DN<1>")
	)
	(segment
		(start 361.707684 -276.838664)
		(end 361.7468 -276.861524)
		(width 0.1143)
		(layer "In13.Cu")
		(net "P5E_CPU0_P2_TX_DN<1>")
	)
	(segment
		(start 362.485178 -296.545762)
		(end 362.485178 -296.57421)
		(width 0.1143)
		(layer "In13.Cu")
		(net "P5E_CPU0_P2_TX_DN<1>")
	)
	(segment
		(start 396.19047 -375.839736)
		(end 397.285464 -376.934984)
		(width 0.14224)
		(layer "In13.Cu")
		(net "P5E_CPU0_P2_TX_DN<1>")
	)
	(segment
		(start 362.647738 -271.333468)
		(end 362.64723 -271.333468)
		(width 0.1143)
		(layer "In13.Cu")
		(net "P5E_CPU0_P2_TX_DN<1>")
	)
	(segment
		(start 361.69981 -284.933898)
		(end 361.745276 -284.960568)
		(width 0.1143)
		(layer "In13.Cu")
		(net "P5E_CPU0_P2_TX_DN<1>")
	)
	(segment
		(start 361.712256 -289.15106)
		(end 361.712256 -289.150806)
		(width 0.1143)
		(layer "In13.Cu")
		(net "P5E_CPU0_P2_TX_DN<1>")
	)
	(segment
		(start 361.7468 -285.890716)
		(end 361.676188 -285.932118)
		(width 0.1143)
		(layer "In13.Cu")
		(net "P5E_CPU0_P2_TX_DN<1>")
	)
	(segment
		(start 362.439458 -296.500042)
		(end 362.485178 -296.545762)
		(width 0.1143)
		(layer "In13.Cu")
		(net "P5E_CPU0_P2_TX_DN<1>")
	)
	(segment
		(start 361.7468 -292.37051)
		(end 361.712256 -292.390576)
		(width 0.1143)
		(layer "In13.Cu")
		(net "P5E_CPU0_P2_TX_DN<1>")
	)
	(segment
		(start 362.147104 -295.450768)
		(end 362.21543 -295.490646)
		(width 0.1143)
		(layer "In13.Cu")
		(net "P5E_CPU0_P2_TX_DN<1>")
	)
	(segment
		(start 361.677712 -288.161222)
		(end 361.71378 -288.18205)
		(width 0.1143)
		(layer "In13.Cu")
		(net "P5E_CPU0_P2_TX_DN<1>")
	)
	(segment
		(start 362.41228 -295.729406)
		(end 362.412534 -295.72966)
		(width 0.1143)
		(layer "In13.Cu")
		(net "P5E_CPU0_P2_TX_DN<1>")
	)
	(segment
		(start 361.727242 -289.141408)
		(end 361.726734 -289.141662)
		(width 0.1143)
		(layer "In13.Cu")
		(net "P5E_CPU0_P2_TX_DN<1>")
	)
	(segment
		(start 361.676188 -286.540194)
		(end 361.7468 -286.581342)
		(width 0.1143)
		(layer "In13.Cu")
		(net "P5E_CPU0_P2_TX_DN<1>")
	)
	(segment
		(start 361.707684 -274.573492)
		(end 361.677204 -274.591272)
		(width 0.1143)
		(layer "In13.Cu")
		(net "P5E_CPU0_P2_TX_DN<1>")
	)
	(segment
		(start 361.707684 -289.153346)
		(end 361.677204 -289.171126)
		(width 0.1143)
		(layer "In13.Cu")
		(net "P5E_CPU0_P2_TX_DN<1>")
	)
	(segment
		(start 361.707684 -294.658542)
		(end 361.7468 -294.681402)
		(width 0.1143)
		(layer "In13.Cu")
		(net "P5E_CPU0_P2_TX_DN<1>")
	)
	(segment
		(start 361.707684 -278.458676)
		(end 361.7468 -278.481536)
		(width 0.1143)
		(layer "In13.Cu")
		(net "P5E_CPU0_P2_TX_DN<1>")
	)
	(segment
		(start 398.33677 -384.92303)
		(end 397.349218 -384.92303)
		(width 0.14224)
		(layer "In13.Cu")
		(net "P5E_CPU0_P2_TX_DN<1>")
	)
	(segment
		(start 361.7468 -279.410668)
		(end 361.707684 -279.433528)
		(width 0.1143)
		(layer "In13.Cu")
		(net "P5E_CPU0_P2_TX_DN<1>")
	)
	(segment
		(start 361.708954 -283.319474)
		(end 361.745276 -283.340556)
		(width 0.1143)
		(layer "In13.Cu")
		(net "P5E_CPU0_P2_TX_DN<1>")
	)
	(segment
		(start 362.485178 -296.57421)
		(end 362.485178 -300.703234)
		(width 0.14224)
		(layer "In13.Cu")
		(net "P5E_CPU0_P2_TX_DN<1>")
	)
	(segment
		(start 361.707684 -281.05354)
		(end 361.704382 -281.055572)
		(width 0.1143)
		(layer "In13.Cu")
		(net "P5E_CPU0_P2_TX_DN<1>")
	)
	(segment
		(start 397.405352 -377.224544)
		(end 397.405352 -382.023112)
		(width 0.14224)
		(layer "In13.Cu")
		(net "P5E_CPU0_P2_TX_DN<1>")
	)
	(segment
		(start 361.7468 -293.990522)
		(end 361.707684 -294.013382)
		(width 0.1143)
		(layer "In13.Cu")
		(net "P5E_CPU0_P2_TX_DN<1>")
	)
	(segment
		(start 362.170726 -272.147538)
		(end 362.146088 -272.161762)
		(width 0.1143)
		(layer "In13.Cu")
		(net "P5E_CPU0_P2_TX_DN<1>")
	)
	(segment
		(start 361.708954 -281.699462)
		(end 361.745276 -281.720544)
		(width 0.1143)
		(layer "In13.Cu")
		(net "P5E_CPU0_P2_TX_DN<1>")
	)
	(segment
		(start 362.542074 -300.989238)
		(end 390.100312 -367.491518)
		(width 0.14224)
		(layer "In13.Cu")
		(net "P5E_CPU0_P2_TX_DN<1>")
	)
	(segment
		(start 361.7468 -277.790656)
		(end 361.707684 -277.813516)
		(width 0.1143)
		(layer "In13.Cu")
		(net "P5E_CPU0_P2_TX_DN<1>")
	)
	(segment
		(start 361.708954 -282.67279)
		(end 361.705398 -282.675076)
		(width 0.1143)
		(layer "In13.Cu")
		(net "P5E_CPU0_P2_TX_DN<1>")
	)
	(segment
		(start 362.171742 -272.14703)
		(end 362.170726 -272.147538)
		(width 0.1143)
		(layer "In13.Cu")
		(net "P5E_CPU0_P2_TX_DN<1>")
	)
	(segment
		(start 361.677204 -275.200872)
		(end 361.707684 -275.218652)
		(width 0.1143)
		(layer "In13.Cu")
		(net "P5E_CPU0_P2_TX_DN<1>")
	)
	(segment
		(start 361.705398 -283.317188)
		(end 361.708954 -283.319474)
		(width 0.1143)
		(layer "In13.Cu")
		(net "P5E_CPU0_P2_TX_DN<1>")
	)
	(segment
		(start 361.711494 -293.040816)
		(end 361.746038 -293.060882)
		(width 0.1143)
		(layer "In13.Cu")
		(net "P5E_CPU0_P2_TX_DN<1>")
	)
	(segment
		(start 362.21416 -272.122392)
		(end 362.177838 -272.143474)
		(width 0.1143)
		(layer "In13.Cu")
		(net "P5E_CPU0_P2_TX_DN<1>")
	)
	(segment
		(start 361.74426 -287.512252)
		(end 361.680252 -287.549336)
		(width 0.1143)
		(layer "In13.Cu")
		(net "P5E_CPU0_P2_TX_DN<1>")
	)
	(segment
		(start 362.174282 -272.145506)
		(end 362.17352 -272.146014)
		(width 0.1143)
		(layer "In13.Cu")
		(net "P5E_CPU0_P2_TX_DN<1>")
	)
	(segment
		(start 361.705398 -282.675076)
		(end 361.704382 -282.675584)
		(width 0.1143)
		(layer "In13.Cu")
		(net "P5E_CPU0_P2_TX_DN<1>")
	)
	(segment
		(start 362.686854 -271.310608)
		(end 362.648754 -271.33296)
		(width 0.1143)
		(layer "In13.Cu")
		(net "P5E_CPU0_P2_TX_DN<1>")
	)
	(segment
		(start 361.674918 -280.059638)
		(end 361.7468 -280.101548)
		(width 0.1143)
		(layer "In13.Cu")
		(net "P5E_CPU0_P2_TX_DN<1>")
	)
	(segment
		(start 361.677204 -276.820884)
		(end 361.707684 -276.838664)
		(width 0.1143)
		(layer "In13.Cu")
		(net "P5E_CPU0_P2_TX_DN<1>")
	)
	(segment
		(start 361.7468 -282.650692)
		(end 361.708954 -282.67279)
		(width 0.1143)
		(layer "In13.Cu")
		(net "P5E_CPU0_P2_TX_DN<1>")
	)
	(segment
		(start 363.304836 -270.846042)
		(end 363.006894 -270.846042)
		(width 0.1143)
		(layer "In13.Cu")
		(net "P5E_CPU0_P2_TX_DN<1>")
	)
	(segment
		(start 361.677204 -294.640762)
		(end 361.707684 -294.658542)
		(width 0.1143)
		(layer "In13.Cu")
		(net "P5E_CPU0_P2_TX_DN<1>")
	)
	(segment
		(start 361.677204 -291.400738)
		(end 361.707684 -291.418518)
		(width 0.1143)
		(layer "In13.Cu")
		(net "P5E_CPU0_P2_TX_DN<1>")
	)
	(segment
		(start 363.006894 -270.846042)
		(end 362.92409 -270.928846)
		(width 0.1143)
		(layer "In13.Cu")
		(net "P5E_CPU0_P2_TX_DN<1>")
	)
	(segment
		(start 362.17352 -272.146014)
		(end 362.172504 -272.146522)
		(width 0.1143)
		(layer "In13.Cu")
		(net "P5E_CPU0_P2_TX_DN<1>")
	)
	(segment
		(start 361.707684 -273.59864)
		(end 361.7468 -273.6215)
		(width 0.1143)
		(layer "In13.Cu")
		(net "P5E_CPU0_P2_TX_DN<1>")
	)
	(segment
		(start 361.674918 -279.452578)
		(end 361.672886 -279.454102)
		(width 0.1143)
		(layer "In13.Cu")
		(net "P5E_CPU0_P2_TX_DN<1>")
	)
	(segment
		(start 362.172504 -272.146522)
		(end 362.171742 -272.14703)
		(width 0.1143)
		(layer "In13.Cu")
		(net "P5E_CPU0_P2_TX_DN<1>")
	)
	(segment
		(start 361.705398 -281.697176)
		(end 361.708954 -281.699462)
		(width 0.1143)
		(layer "In13.Cu")
		(net "P5E_CPU0_P2_TX_DN<1>")
	)
	(segment
		(start 361.707684 -291.418518)
		(end 361.7468 -291.441378)
		(width 0.1143)
		(layer "In13.Cu")
		(net "P5E_CPU0_P2_TX_DN<1>")
	)
	(segment
		(start 361.7468 -281.03068)
		(end 361.707684 -281.05354)
		(width 0.1143)
		(layer "In13.Cu")
		(net "P5E_CPU0_P2_TX_DN<1>")
	)
	(segment
		(start 361.707684 -289.798506)
		(end 361.7468 -289.821366)
		(width 0.1143)
		(layer "In13.Cu")
		(net "P5E_CPU0_P2_TX_DN<1>")
	)
	(segment
		(start 361.7087 -284.293056)
		(end 361.707938 -284.293564)
		(width 0.1143)
		(layer "In13.Cu")
		(net "P5E_CPU0_P2_TX_DN<1>")
	)
	(segment
		(start 398.644364 -383.565654)
		(end 398.644364 -384.615436)
		(width 0.14224)
		(layer "In13.Cu")
		(net "P5E_CPU0_P2_TX_DN<1>")
	)
	(segment
		(start 361.710732 -293.040308)
		(end 361.711494 -293.040816)
		(width 0.1143)
		(layer "In13.Cu")
		(net "P5E_CPU0_P2_TX_DN<1>")
	)
	(segment
		(start 361.677204 -289.780726)
		(end 361.707684 -289.798506)
		(width 0.1143)
		(layer "In13.Cu")
		(net "P5E_CPU0_P2_TX_DN<1>")
	)
	(segment
		(start 361.726734 -289.141662)
		(end 361.712256 -289.15106)
		(width 0.1143)
		(layer "In13.Cu")
		(net "P5E_CPU0_P2_TX_DN<1>")
	)
	(segment
		(start 390.100312 -367.491518)
		(end 393.434824 -372.482364)
		(width 0.14224)
		(layer "In13.Cu")
		(net "P5E_CPU0_P2_TX_DN<1>")
	)
	(segment
		(start 398.644364 -384.615436)
		(end 398.33677 -384.92303)
		(width 0.14224)
		(layer "In13.Cu")
		(net "P5E_CPU0_P2_TX_DN<1>")
	)
	(segment
		(start 361.712256 -289.150806)
		(end 361.707684 -289.153346)
		(width 0.1143)
		(layer "In13.Cu")
		(net "P5E_CPU0_P2_TX_DN<1>")
	)
	(segment
		(start 361.520232 -286.22244)
		(end 361.520232 -286.23895)
		(width 0.1143)
		(layer "In13.Cu")
		(net "P5E_CPU0_P2_TX_DN<1>")
	)
	(segment
		(start 362.439458 -295.858184)
		(end 362.439458 -296.500042)
		(width 0.1143)
		(layer "In13.Cu")
		(net "P5E_CPU0_P2_TX_DN<1>")
	)
	(segment
		(start 361.7468 -276.170644)
		(end 361.707684 -276.193504)
		(width 0.1143)
		(layer "In13.Cu")
		(net "P5E_CPU0_P2_TX_DN<1>")
	)
	(segment
		(start 361.707684 -290.773358)
		(end 361.677204 -290.791138)
		(width 0.1143)
		(layer "In13.Cu")
		(net "P5E_CPU0_P2_TX_DN<1>")
	)
	(segment
		(start 361.672886 -280.058114)
		(end 361.674918 -280.059638)
		(width 0.1143)
		(layer "In13.Cu")
		(net "P5E_CPU0_P2_TX_DN<1>")
	)
	(segment
		(start 361.711494 -292.391084)
		(end 361.702096 -292.396672)
		(width 0.1143)
		(layer "In13.Cu")
		(net "P5E_CPU0_P2_TX_DN<1>")
	)
	(segment
		(start 361.702096 -292.396672)
		(end 361.700826 -292.39718)
		(width 0.1143)
		(layer "In13.Cu")
		(net "P5E_CPU0_P2_TX_DN<1>")
	)
	(segment
		(start 361.7468 -284.270704)
		(end 361.7087 -284.293056)
		(width 0.1143)
		(layer "In13.Cu")
		(net "P5E_CPU0_P2_TX_DN<1>")
	)
	(segment
		(start 362.648754 -271.33296)
		(end 362.647738 -271.333468)
		(width 0.1143)
		(layer "In13.Cu")
		(net "P5E_CPU0_P2_TX_DN<1>")
	)
	(segment
		(start 361.707684 -272.95348)
		(end 361.677204 -272.97126)
		(width 0.1143)
		(layer "In13.Cu")
		(net "P5E_CPU0_P2_TX_DN<1>")
	)
	(segment
		(start 362.177838 -272.143474)
		(end 362.177076 -272.143982)
		(width 0.1143)
		(layer "In13.Cu")
		(net "P5E_CPU0_P2_TX_DN<1>")
	)
	(segment
		(start 361.712256 -292.390576)
		(end 361.711494 -292.391084)
		(width 0.1143)
		(layer "In13.Cu")
		(net "P5E_CPU0_P2_TX_DN<1>")
	)
	(segment
		(start 393.434824 -372.482364)
		(end 396.19047 -375.839736)
		(width 0.14224)
		(layer "In13.Cu")
		(net "P5E_CPU0_P2_TX_DN<1>")
	)
	(segment
		(start 361.704128 -283.31668)
		(end 361.705398 -283.317188)
		(width 0.1143)
		(layer "In13.Cu")
		(net "P5E_CPU0_P2_TX_DN<1>")
	)
	(segment
		(start 361.7468 -274.550632)
		(end 361.707684 -274.573492)
		(width 0.1143)
		(layer "In13.Cu")
		(net "P5E_CPU0_P2_TX_DN<1>")
	)
	(segment
		(start 397.349218 -384.92303)
		(end 397.058388 -385.21386)
		(width 0.14224)
		(layer "In13.Cu")
		(net "P5E_CPU0_P2_TX_DN<1>")
	)
	(segment
		(start 362.177076 -272.143982)
		(end 362.174282 -272.145506)
		(width 0.1143)
		(layer "In13.Cu")
		(net "P5E_CPU0_P2_TX_DN<1>")
	)
	(segment
		(start 361.707684 -279.433528)
		(end 361.674918 -279.452578)
		(width 0.1143)
		(layer "In13.Cu")
		(net "P5E_CPU0_P2_TX_DN<1>")
	)
	(segment
		(start 361.707684 -277.813516)
		(end 361.677204 -277.831296)
		(width 0.1143)
		(layer "In13.Cu")
		(net "P5E_CPU0_P2_TX_DN<1>")
	)
	(segment
		(start 361.704128 -281.696668)
		(end 361.705398 -281.697176)
		(width 0.1143)
		(layer "In13.Cu")
		(net "P5E_CPU0_P2_TX_DN<1>")
	)
	(segment
		(start 361.702096 -293.035228)
		(end 361.710732 -293.040308)
		(width 0.1143)
		(layer "In13.Cu")
		(net "P5E_CPU0_P2_TX_DN<1>")
	)
	(segment
		(start 397.500094 -382.251966)
		(end 398.524476 -383.276348)
		(width 0.14224)
		(layer "In13.Cu")
		(net "P5E_CPU0_P2_TX_DN<1>")
	)
	(segment
		(start 361.7468 -290.750498)
		(end 361.707684 -290.773358)
		(width 0.1143)
		(layer "In13.Cu")
		(net "P5E_CPU0_P2_TX_DN<1>")
	)
	(segment
		(start 361.707684 -294.013382)
		(end 361.677204 -294.031162)
		(width 0.1143)
		(layer "In13.Cu")
		(net "P5E_CPU0_P2_TX_DN<1>")
	)
	(segment
		(start 361.700826 -293.03472)
		(end 361.702096 -293.035228)
		(width 0.1143)
		(layer "In13.Cu")
		(net "P5E_CPU0_P2_TX_DN<1>")
	)
	(segment
		(start 361.7468 -272.93062)
		(end 361.707684 -272.95348)
		(width 0.1143)
		(layer "In13.Cu")
		(net "P5E_CPU0_P2_TX_DN<1>")
	)
	(segment
		(start 361.677204 -278.440896)
		(end 361.707684 -278.458676)
		(width 0.1143)
		(layer "In13.Cu")
		(net "P5E_CPU0_P2_TX_DN<1>")
	)
	(segment
		(start 361.707684 -275.218652)
		(end 361.7468 -275.241512)
		(width 0.1143)
		(layer "In13.Cu")
		(net "P5E_CPU0_P2_TX_DN<1>")
	)
	(segment
		(start 361.677204 -273.58086)
		(end 361.707684 -273.59864)
		(width 0.1143)
		(layer "In13.Cu")
		(net "P5E_CPU0_P2_TX_DN<1>")
	)
	(segment
		(start 362.64723 -271.333468)
		(end 362.618528 -271.350232)
		(width 0.1143)
		(layer "In13.Cu")
		(net "P5E_CPU0_P2_TX_DN<1>")
	)
	(arc
		(start 362.460032 -271.655032)
		(mid 362.396777 -271.908968)
		(end 362.230416 -272.110962)
		(width 0.1143)
		(layer "In13.Cu")
		(net "P5E_CPU0_P2_TX_DN<1>")
	)
	(arc
		(start 361.704382 -282.675584)
		(mid 361.5205 -282.996022)
		(end 361.704128 -283.31668)
		(width 0.1143)
		(layer "In13.Cu")
		(net "P5E_CPU0_P2_TX_DN<1>")
	)
	(arc
		(start 361.704382 -281.055572)
		(mid 361.5205 -281.37601)
		(end 361.704128 -281.696668)
		(width 0.1143)
		(layer "In13.Cu")
		(net "P5E_CPU0_P2_TX_DN<1>")
	)
	(arc
		(start 361.520232 -287.856168)
		(mid 361.561983 -288.027788)
		(end 361.677712 -288.161222)
		(width 0.1143)
		(layer "In13.Cu")
		(net "P5E_CPU0_P2_TX_DN<1>")
	)
	(arc
		(start 361.7468 -289.821366)
		(mid 361.990127 -290.285932)
		(end 361.7468 -290.750498)
		(width 0.1143)
		(layer "In13.Cu")
		(net "P5E_CPU0_P2_TX_DN<1>")
	)
	(arc
		(start 361.7468 -281.72156)
		(mid 361.990127 -282.186126)
		(end 361.7468 -282.650692)
		(width 0.1143)
		(layer "In13.Cu")
		(net "P5E_CPU0_P2_TX_DN<1>")
	)
	(arc
		(start 362.618528 -271.350232)
		(mid 362.615595 -271.352503)
		(end 362.612686 -271.354804)
		(width 0.1143)
		(layer "In13.Cu")
		(net "P5E_CPU0_P2_TX_DN<1>")
	)
	(arc
		(start 361.7468 -293.06139)
		(mid 361.990127 -293.525956)
		(end 361.7468 -293.990522)
		(width 0.1143)
		(layer "In13.Cu")
		(net "P5E_CPU0_P2_TX_DN<1>")
	)
	(arc
		(start 362.146088 -272.161762)
		(mid 362.031412 -272.295096)
		(end 361.990132 -272.466054)
		(width 0.1143)
		(layer "In13.Cu")
		(net "P5E_CPU0_P2_TX_DN<1>")
	)
	(arc
		(start 361.707938 -284.293564)
		(mid 361.52296 -284.611418)
		(end 361.69981 -284.933898)
		(width 0.1143)
		(layer "In13.Cu")
		(net "P5E_CPU0_P2_TX_DN<1>")
	)
	(arc
		(start 398.524476 -383.276348)
		(mid 398.61322 -383.409068)
		(end 398.644364 -383.565654)
		(width 0.14224)
		(layer "In13.Cu")
		(net "P5E_CPU0_P2_TX_DN<1>")
	)
	(arc
		(start 362.230416 -272.110962)
		(mid 362.222338 -272.116748)
		(end 362.21416 -272.122392)
		(width 0.1143)
		(layer "In13.Cu")
		(net "P5E_CPU0_P2_TX_DN<1>")
	)
	(arc
		(start 361.7468 -286.581342)
		(mid 361.925613 -286.783692)
		(end 361.990132 -287.045908)
		(width 0.1143)
		(layer "In13.Cu")
		(net "P5E_CPU0_P2_TX_DN<1>")
	)
	(arc
		(start 361.745276 -283.340556)
		(mid 361.746038 -283.341063)
		(end 361.7468 -283.341572)
		(width 0.1143)
		(layer "In13.Cu")
		(net "P5E_CPU0_P2_TX_DN<1>")
	)
	(arc
		(start 361.7468 -278.481536)
		(mid 361.990127 -278.946102)
		(end 361.7468 -279.410668)
		(width 0.1143)
		(layer "In13.Cu")
		(net "P5E_CPU0_P2_TX_DN<1>")
	)
	(arc
		(start 362.92028 -270.951706)
		(mid 362.838847 -271.154104)
		(end 362.686854 -271.310608)
		(width 0.1143)
		(layer "In13.Cu")
		(net "P5E_CPU0_P2_TX_DN<1>")
	)
	(arc
		(start 397.285464 -376.934984)
		(mid 397.374179 -377.067849)
		(end 397.405352 -377.224544)
		(width 0.14224)
		(layer "In13.Cu")
		(net "P5E_CPU0_P2_TX_DN<1>")
	)
	(arc
		(start 361.676188 -285.932118)
		(mid 361.564608 -286.059219)
		(end 361.520232 -286.22244)
		(width 0.1143)
		(layer "In13.Cu")
		(net "P5E_CPU0_P2_TX_DN<1>")
	)
	(arc
		(start 361.677204 -276.211284)
		(mid 361.520227 -276.516084)
		(end 361.677204 -276.820884)
		(width 0.1143)
		(layer "In13.Cu")
		(net "P5E_CPU0_P2_TX_DN<1>")
	)
	(arc
		(start 361.680252 -287.549336)
		(mid 361.562629 -287.683138)
		(end 361.520232 -287.856168)
		(width 0.1143)
		(layer "In13.Cu")
		(net "P5E_CPU0_P2_TX_DN<1>")
	)
	(arc
		(start 361.7468 -294.681402)
		(mid 361.925613 -294.883752)
		(end 361.990132 -295.145968)
		(width 0.1143)
		(layer "In13.Cu")
		(net "P5E_CPU0_P2_TX_DN<1>")
	)
	(arc
		(start 361.745276 -284.960568)
		(mid 361.746038 -284.961075)
		(end 361.7468 -284.961584)
		(width 0.1143)
		(layer "In13.Cu")
		(net "P5E_CPU0_P2_TX_DN<1>")
	)
	(arc
		(start 361.7468 -275.241512)
		(mid 361.990127 -275.706078)
		(end 361.7468 -276.170644)
		(width 0.1143)
		(layer "In13.Cu")
		(net "P5E_CPU0_P2_TX_DN<1>")
	)
	(arc
		(start 362.92409 -270.928846)
		(mid 362.922302 -270.940295)
		(end 362.92028 -270.951706)
		(width 0.1143)
		(layer "In13.Cu")
		(net "P5E_CPU0_P2_TX_DN<1>")
	)
	(arc
		(start 362.612686 -271.354804)
		(mid 362.506876 -271.489936)
		(end 362.460032 -271.655032)
		(width 0.1143)
		(layer "In13.Cu")
		(net "P5E_CPU0_P2_TX_DN<1>")
	)
	(arc
		(start 361.700826 -292.39718)
		(mid 361.520341 -292.71595)
		(end 361.700826 -293.03472)
		(width 0.1143)
		(layer "In13.Cu")
		(net "P5E_CPU0_P2_TX_DN<1>")
	)
	(arc
		(start 361.7468 -284.961584)
		(mid 361.990127 -285.42615)
		(end 361.7468 -285.890716)
		(width 0.1143)
		(layer "In13.Cu")
		(net "P5E_CPU0_P2_TX_DN<1>")
	)
	(arc
		(start 361.677204 -294.031162)
		(mid 361.520227 -294.335962)
		(end 361.677204 -294.640762)
		(width 0.1143)
		(layer "In13.Cu")
		(net "P5E_CPU0_P2_TX_DN<1>")
	)
	(arc
		(start 361.746038 -293.060882)
		(mid 361.746419 -293.061136)
		(end 361.7468 -293.06139)
		(width 0.1143)
		(layer "In13.Cu")
		(net "P5E_CPU0_P2_TX_DN<1>")
	)
	(arc
		(start 361.672886 -279.454102)
		(mid 361.518706 -279.756108)
		(end 361.672886 -280.058114)
		(width 0.1143)
		(layer "In13.Cu")
		(net "P5E_CPU0_P2_TX_DN<1>")
	)
	(arc
		(start 361.7468 -283.341572)
		(mid 361.990127 -283.806138)
		(end 361.7468 -284.270704)
		(width 0.1143)
		(layer "In13.Cu")
		(net "P5E_CPU0_P2_TX_DN<1>")
	)
	(arc
		(start 361.677204 -272.97126)
		(mid 361.520227 -273.27606)
		(end 361.677204 -273.58086)
		(width 0.1143)
		(layer "In13.Cu")
		(net "P5E_CPU0_P2_TX_DN<1>")
	)
	(arc
		(start 397.405352 -382.023112)
		(mid 397.429969 -382.146961)
		(end 397.500094 -382.251966)
		(width 0.14224)
		(layer "In13.Cu")
		(net "P5E_CPU0_P2_TX_DN<1>")
	)
	(arc
		(start 361.677204 -277.831296)
		(mid 361.520227 -278.136096)
		(end 361.677204 -278.440896)
		(width 0.1143)
		(layer "In13.Cu")
		(net "P5E_CPU0_P2_TX_DN<1>")
	)
	(arc
		(start 361.7468 -273.6215)
		(mid 361.990127 -274.086066)
		(end 361.7468 -274.550632)
		(width 0.1143)
		(layer "In13.Cu")
		(net "P5E_CPU0_P2_TX_DN<1>")
	)
	(arc
		(start 362.485178 -300.703234)
		(mid 362.49954 -300.849038)
		(end 362.542074 -300.989238)
		(width 0.14224)
		(layer "In13.Cu")
		(net "P5E_CPU0_P2_TX_DN<1>")
	)
	(arc
		(start 361.7468 -276.861524)
		(mid 361.990127 -277.32609)
		(end 361.7468 -277.790656)
		(width 0.1143)
		(layer "In13.Cu")
		(net "P5E_CPU0_P2_TX_DN<1>")
	)
	(arc
		(start 361.990132 -272.466054)
		(mid 361.925617 -272.728273)
		(end 361.7468 -272.93062)
		(width 0.1143)
		(layer "In13.Cu")
		(net "P5E_CPU0_P2_TX_DN<1>")
	)
	(arc
		(start 361.990132 -295.145968)
		(mid 362.031681 -295.31739)
		(end 362.147104 -295.450768)
		(width 0.1143)
		(layer "In13.Cu")
		(net "P5E_CPU0_P2_TX_DN<1>")
	)
	(arc
		(start 362.21543 -295.490646)
		(mid 362.330533 -295.596276)
		(end 362.41228 -295.729406)
		(width 0.1143)
		(layer "In13.Cu")
		(net "P5E_CPU0_P2_TX_DN<1>")
	)
	(arc
		(start 361.745276 -281.720544)
		(mid 361.746038 -281.721051)
		(end 361.7468 -281.72156)
		(width 0.1143)
		(layer "In13.Cu")
		(net "P5E_CPU0_P2_TX_DN<1>")
	)
	(arc
		(start 361.677204 -289.171126)
		(mid 361.520227 -289.475926)
		(end 361.677204 -289.780726)
		(width 0.1143)
		(layer "In13.Cu")
		(net "P5E_CPU0_P2_TX_DN<1>")
	)
	(arc
		(start 361.520232 -286.23895)
		(mid 361.561595 -286.408523)
		(end 361.676188 -286.540194)
		(width 0.1143)
		(layer "In13.Cu")
		(net "P5E_CPU0_P2_TX_DN<1>")
	)
	(arc
		(start 361.677204 -274.591272)
		(mid 361.520227 -274.896072)
		(end 361.677204 -275.200872)
		(width 0.1143)
		(layer "In13.Cu")
		(net "P5E_CPU0_P2_TX_DN<1>")
	)
	(arc
		(start 361.71378 -288.18205)
		(mid 361.990921 -288.65799)
		(end 361.727242 -289.141408)
		(width 0.1143)
		(layer "In13.Cu")
		(net "P5E_CPU0_P2_TX_DN<1>")
	)
	(arc
		(start 361.7468 -280.101548)
		(mid 361.990127 -280.566114)
		(end 361.7468 -281.03068)
		(width 0.1143)
		(layer "In13.Cu")
		(net "P5E_CPU0_P2_TX_DN<1>")
	)
	(arc
		(start 361.990132 -287.045908)
		(mid 361.924896 -287.309499)
		(end 361.74426 -287.512252)
		(width 0.1143)
		(layer "In13.Cu")
		(net "P5E_CPU0_P2_TX_DN<1>")
	)
	(arc
		(start 362.412534 -295.72966)
		(mid 362.432677 -295.79252)
		(end 362.439458 -295.858184)
		(width 0.1143)
		(layer "In13.Cu")
		(net "P5E_CPU0_P2_TX_DN<1>")
	)
	(arc
		(start 361.7468 -291.441378)
		(mid 361.990127 -291.905944)
		(end 361.7468 -292.37051)
		(width 0.1143)
		(layer "In13.Cu")
		(net "P5E_CPU0_P2_TX_DN<1>")
	)
	(arc
		(start 361.677204 -290.791138)
		(mid 361.520227 -291.095938)
		(end 361.677204 -291.400738)
		(width 0.1143)
		(layer "In13.Cu")
		(net "P5E_CPU0_P2_TX_DN<1>")
	)
	(segment
		(start 426.90542 -388.742428)
		(end 426.63491 -388.471918)
		(width 0.12954)
		(layer "F.Cu")
		(net "P5E_CPU0_P2_TX_DN<15>")
	)
	(segment
		(start 426.63491 -388.471918)
		(end 425.93133 -388.471918)
		(width 0.12954)
		(layer "F.Cu")
		(net "P5E_CPU0_P2_TX_DN<15>")
	)
	(segment
		(start 373.64797 -271.39011)
		(end 374.114822 -271.656048)
		(width 0.12954)
		(layer "F.Cu")
		(net "P5E_CPU0_P2_TX_DN<15>")
	)
	(segment
		(start 425.93133 -388.471918)
		(end 425.63542 -388.767828)
		(width 0.12954)
		(layer "F.Cu")
		(net "P5E_CPU0_P2_TX_DN<15>")
	)
	(segment
		(start 374.867932 -276.19325)
		(end 374.835928 -276.212046)
		(width 0.1143)
		(layer "In13.Cu")
		(net "P5E_CPU0_P2_TX_DN<15>")
	)
	(segment
		(start 427.19625 -388.451598)
		(end 426.90542 -388.742428)
		(width 0.14224)
		(layer "In13.Cu")
		(net "P5E_CPU0_P2_TX_DN<15>")
	)
	(segment
		(start 375.149872 -295.145968)
		(end 375.149872 -295.293796)
		(width 0.1143)
		(layer "In13.Cu")
		(net "P5E_CPU0_P2_TX_DN<15>")
	)
	(segment
		(start 374.867678 -286.558736)
		(end 374.907556 -286.581596)
		(width 0.1143)
		(layer "In13.Cu")
		(net "P5E_CPU0_P2_TX_DN<15>")
	)
	(segment
		(start 374.867932 -289.79876)
		(end 374.90527 -289.82035)
		(width 0.1143)
		(layer "In13.Cu")
		(net "P5E_CPU0_P2_TX_DN<15>")
	)
	(segment
		(start 375.544334 -295.634156)
		(end 375.66092 -295.892474)
		(width 0.1143)
		(layer "In13.Cu")
		(net "P5E_CPU0_P2_TX_DN<15>")
	)
	(segment
		(start 375.731278 -297.004486)
		(end 401.608036 -359.450132)
		(width 0.14224)
		(layer "In13.Cu")
		(net "P5E_CPU0_P2_TX_DN<15>")
	)
	(segment
		(start 374.867932 -281.698954)
		(end 374.90527 -281.720544)
		(width 0.1143)
		(layer "In13.Cu")
		(net "P5E_CPU0_P2_TX_DN<15>")
	)
	(segment
		(start 375.70664 -296.583862)
		(end 375.70664 -296.61231)
		(width 0.1143)
		(layer "In13.Cu")
		(net "P5E_CPU0_P2_TX_DN<15>")
	)
	(segment
		(start 374.867932 -281.053286)
		(end 374.835928 -281.072082)
		(width 0.1143)
		(layer "In13.Cu")
		(net "P5E_CPU0_P2_TX_DN<15>")
	)
	(segment
		(start 374.835928 -275.20011)
		(end 374.867932 -275.218906)
		(width 0.1143)
		(layer "In13.Cu")
		(net "P5E_CPU0_P2_TX_DN<15>")
	)
	(segment
		(start 374.867932 -278.45893)
		(end 374.90527 -278.48052)
		(width 0.1143)
		(layer "In13.Cu")
		(net "P5E_CPU0_P2_TX_DN<15>")
	)
	(segment
		(start 374.867932 -293.038784)
		(end 374.90527 -293.060374)
		(width 0.1143)
		(layer "In13.Cu")
		(net "P5E_CPU0_P2_TX_DN<15>")
	)
	(segment
		(start 375.70664 -296.61231)
		(end 375.70664 -296.881296)
		(width 0.14224)
		(layer "In13.Cu")
		(net "P5E_CPU0_P2_TX_DN<15>")
	)
	(segment
		(start 375.66092 -295.892474)
		(end 375.66092 -296.538142)
		(width 0.1143)
		(layer "In13.Cu")
		(net "P5E_CPU0_P2_TX_DN<15>")
	)
	(segment
		(start 375.149872 -295.293796)
		(end 375.175526 -295.36009)
		(width 0.1143)
		(layer "In13.Cu")
		(net "P5E_CPU0_P2_TX_DN<15>")
	)
	(segment
		(start 406.731216 -366.338612)
		(end 418.863272 -371.364002)
		(width 0.14224)
		(layer "In13.Cu")
		(net "P5E_CPU0_P2_TX_DN<15>")
	)
	(segment
		(start 374.867932 -283.318966)
		(end 374.90527 -283.340556)
		(width 0.1143)
		(layer "In13.Cu")
		(net "P5E_CPU0_P2_TX_DN<15>")
	)
	(segment
		(start 374.867932 -290.773104)
		(end 374.835928 -290.7919)
		(width 0.1143)
		(layer "In13.Cu")
		(net "P5E_CPU0_P2_TX_DN<15>")
	)
	(segment
		(start 374.835928 -273.580098)
		(end 374.867932 -273.598894)
		(width 0.1143)
		(layer "In13.Cu")
		(net "P5E_CPU0_P2_TX_DN<15>")
	)
	(segment
		(start 374.835928 -281.680158)
		(end 374.867932 -281.698954)
		(width 0.1143)
		(layer "In13.Cu")
		(net "P5E_CPU0_P2_TX_DN<15>")
	)
	(segment
		(start 373.81688 -271.656048)
		(end 373.746776 -271.726152)
		(width 0.1143)
		(layer "In13.Cu")
		(net "P5E_CPU0_P2_TX_DN<15>")
	)
	(segment
		(start 374.397016 -272.78838)
		(end 374.436132 -272.810986)
		(width 0.1143)
		(layer "In13.Cu")
		(net "P5E_CPU0_P2_TX_DN<15>")
	)
	(segment
		(start 374.90527 -281.031696)
		(end 374.867932 -281.053286)
		(width 0.1143)
		(layer "In13.Cu")
		(net "P5E_CPU0_P2_TX_DN<15>")
	)
	(segment
		(start 374.835928 -276.820122)
		(end 374.867932 -276.838918)
		(width 0.1143)
		(layer "In13.Cu")
		(net "P5E_CPU0_P2_TX_DN<15>")
	)
	(segment
		(start 375.66092 -296.538142)
		(end 375.70664 -296.583862)
		(width 0.1143)
		(layer "In13.Cu")
		(net "P5E_CPU0_P2_TX_DN<15>")
	)
	(segment
		(start 374.114822 -271.656048)
		(end 373.81688 -271.656048)
		(width 0.1143)
		(layer "In13.Cu")
		(net "P5E_CPU0_P2_TX_DN<15>")
	)
	(segment
		(start 374.20804 -272.441924)
		(end 374.20804 -272.463006)
		(width 0.1143)
		(layer "In13.Cu")
		(net "P5E_CPU0_P2_TX_DN<15>")
	)
	(segment
		(start 374.867678 -288.178748)
		(end 374.907556 -288.201608)
		(width 0.1143)
		(layer "In13.Cu")
		(net "P5E_CPU0_P2_TX_DN<15>")
	)
	(segment
		(start 374.835928 -293.019988)
		(end 374.867932 -293.038784)
		(width 0.1143)
		(layer "In13.Cu")
		(net "P5E_CPU0_P2_TX_DN<15>")
	)
	(segment
		(start 375.225056 -295.417748)
		(end 375.366026 -295.476422)
		(width 0.1143)
		(layer "In13.Cu")
		(net "P5E_CPU0_P2_TX_DN<15>")
	)
	(segment
		(start 374.867932 -294.013128)
		(end 374.835928 -294.031924)
		(width 0.1143)
		(layer "In13.Cu")
		(net "P5E_CPU0_P2_TX_DN<15>")
	)
	(segment
		(start 374.867932 -285.913322)
		(end 374.836182 -285.932118)
		(width 0.1143)
		(layer "In13.Cu")
		(net "P5E_CPU0_P2_TX_DN<15>")
	)
	(segment
		(start 425.512484 -371.48389)
		(end 426.95876 -372.930166)
		(width 0.14224)
		(layer "In13.Cu")
		(net "P5E_CPU0_P2_TX_DN<15>")
	)
	(segment
		(start 374.90527 -285.891732)
		(end 374.867932 -285.913322)
		(width 0.1143)
		(layer "In13.Cu")
		(net "P5E_CPU0_P2_TX_DN<15>")
	)
	(segment
		(start 374.90527 -293.991538)
		(end 374.867932 -294.013128)
		(width 0.1143)
		(layer "In13.Cu")
		(net "P5E_CPU0_P2_TX_DN<15>")
	)
	(segment
		(start 374.90527 -289.131502)
		(end 374.867932 -289.153092)
		(width 0.1143)
		(layer "In13.Cu")
		(net "P5E_CPU0_P2_TX_DN<15>")
	)
	(segment
		(start 374.90527 -274.551648)
		(end 374.867932 -274.573238)
		(width 0.1143)
		(layer "In13.Cu")
		(net "P5E_CPU0_P2_TX_DN<15>")
	)
	(segment
		(start 374.393206 -272.786348)
		(end 374.397016 -272.78838)
		(width 0.1143)
		(layer "In13.Cu")
		(net "P5E_CPU0_P2_TX_DN<15>")
	)
	(segment
		(start 374.90527 -284.27172)
		(end 374.867932 -284.29331)
		(width 0.1143)
		(layer "In13.Cu")
		(net "P5E_CPU0_P2_TX_DN<15>")
	)
	(segment
		(start 374.835928 -286.540194)
		(end 374.867678 -286.558736)
		(width 0.1143)
		(layer "In13.Cu")
		(net "P5E_CPU0_P2_TX_DN<15>")
	)
	(segment
		(start 374.867932 -273.598894)
		(end 374.90527 -273.620484)
		(width 0.1143)
		(layer "In13.Cu")
		(net "P5E_CPU0_P2_TX_DN<15>")
	)
	(segment
		(start 374.835928 -291.399976)
		(end 374.867932 -291.418772)
		(width 0.1143)
		(layer "In13.Cu")
		(net "P5E_CPU0_P2_TX_DN<15>")
	)
	(segment
		(start 374.90527 -282.651708)
		(end 374.867932 -282.673298)
		(width 0.1143)
		(layer "In13.Cu")
		(net "P5E_CPU0_P2_TX_DN<15>")
	)
	(segment
		(start 429.088296 -376.99823)
		(end 429.088296 -387.636766)
		(width 0.14224)
		(layer "In13.Cu")
		(net "P5E_CPU0_P2_TX_DN<15>")
	)
	(segment
		(start 374.835928 -284.920182)
		(end 374.867932 -284.938978)
		(width 0.1143)
		(layer "In13.Cu")
		(net "P5E_CPU0_P2_TX_DN<15>")
	)
	(segment
		(start 374.867932 -284.29331)
		(end 374.835928 -284.312106)
		(width 0.1143)
		(layer "In13.Cu")
		(net "P5E_CPU0_P2_TX_DN<15>")
	)
	(segment
		(start 374.90527 -287.51149)
		(end 374.83796 -287.550606)
		(width 0.1143)
		(layer "In13.Cu")
		(net "P5E_CPU0_P2_TX_DN<15>")
	)
	(segment
		(start 375.366026 -295.476422)
		(end 375.544334 -295.634156)
		(width 0.1143)
		(layer "In13.Cu")
		(net "P5E_CPU0_P2_TX_DN<15>")
	)
	(segment
		(start 427.078648 -373.219726)
		(end 427.078648 -374.556782)
		(width 0.14224)
		(layer "In13.Cu")
		(net "P5E_CPU0_P2_TX_DN<15>")
	)
	(segment
		(start 374.835928 -278.440134)
		(end 374.867932 -278.45893)
		(width 0.1143)
		(layer "In13.Cu")
		(net "P5E_CPU0_P2_TX_DN<15>")
	)
	(segment
		(start 374.835928 -280.060146)
		(end 374.867932 -280.078942)
		(width 0.1143)
		(layer "In13.Cu")
		(net "P5E_CPU0_P2_TX_DN<15>")
	)
	(segment
		(start 374.867932 -292.393116)
		(end 374.835928 -292.411912)
		(width 0.1143)
		(layer "In13.Cu")
		(net "P5E_CPU0_P2_TX_DN<15>")
	)
	(segment
		(start 401.667726 -359.561638)
		(end 405.68372 -365.572548)
		(width 0.14224)
		(layer "In13.Cu")
		(net "P5E_CPU0_P2_TX_DN<15>")
	)
	(segment
		(start 374.835928 -283.30017)
		(end 374.867932 -283.318966)
		(width 0.1143)
		(layer "In13.Cu")
		(net "P5E_CPU0_P2_TX_DN<15>")
	)
	(segment
		(start 374.90527 -279.411684)
		(end 374.867932 -279.433274)
		(width 0.1143)
		(layer "In13.Cu")
		(net "P5E_CPU0_P2_TX_DN<15>")
	)
	(segment
		(start 428.273464 -388.451598)
		(end 427.19625 -388.451598)
		(width 0.14224)
		(layer "In13.Cu")
		(net "P5E_CPU0_P2_TX_DN<15>")
	)
	(segment
		(start 375.175526 -295.36009)
		(end 375.225056 -295.417748)
		(width 0.1143)
		(layer "In13.Cu")
		(net "P5E_CPU0_P2_TX_DN<15>")
	)
	(segment
		(start 374.867932 -284.938978)
		(end 374.90527 -284.960568)
		(width 0.1143)
		(layer "In13.Cu")
		(net "P5E_CPU0_P2_TX_DN<15>")
	)
	(segment
		(start 374.867932 -276.838918)
		(end 374.90527 -276.860508)
		(width 0.1143)
		(layer "In13.Cu")
		(net "P5E_CPU0_P2_TX_DN<15>")
	)
	(segment
		(start 374.835928 -289.779964)
		(end 374.867932 -289.79876)
		(width 0.1143)
		(layer "In13.Cu")
		(net "P5E_CPU0_P2_TX_DN<15>")
	)
	(segment
		(start 427.264322 -375.004838)
		(end 428.968408 -376.708924)
		(width 0.14224)
		(layer "In13.Cu")
		(net "P5E_CPU0_P2_TX_DN<15>")
	)
	(segment
		(start 374.867932 -274.573238)
		(end 374.835928 -274.592034)
		(width 0.1143)
		(layer "In13.Cu")
		(net "P5E_CPU0_P2_TX_DN<15>")
	)
	(segment
		(start 374.867932 -280.078942)
		(end 374.90527 -280.100532)
		(width 0.1143)
		(layer "In13.Cu")
		(net "P5E_CPU0_P2_TX_DN<15>")
	)
	(segment
		(start 405.923242 -365.799116)
		(end 406.731216 -366.338612)
		(width 0.14224)
		(layer "In13.Cu")
		(net "P5E_CPU0_P2_TX_DN<15>")
	)
	(segment
		(start 374.391428 -272.785332)
		(end 374.393206 -272.786348)
		(width 0.1143)
		(layer "In13.Cu")
		(net "P5E_CPU0_P2_TX_DN<15>")
	)
	(segment
		(start 428.968408 -387.926072)
		(end 428.56277 -388.33171)
		(width 0.14224)
		(layer "In13.Cu")
		(net "P5E_CPU0_P2_TX_DN<15>")
	)
	(segment
		(start 418.863272 -371.364002)
		(end 425.222924 -371.364002)
		(width 0.14224)
		(layer "In13.Cu")
		(net "P5E_CPU0_P2_TX_DN<15>")
	)
	(segment
		(start 374.90527 -290.751514)
		(end 374.867932 -290.773104)
		(width 0.1143)
		(layer "In13.Cu")
		(net "P5E_CPU0_P2_TX_DN<15>")
	)
	(segment
		(start 374.90527 -292.371526)
		(end 374.867932 -292.393116)
		(width 0.1143)
		(layer "In13.Cu")
		(net "P5E_CPU0_P2_TX_DN<15>")
	)
	(segment
		(start 374.867932 -289.153092)
		(end 374.835928 -289.171888)
		(width 0.1143)
		(layer "In13.Cu")
		(net "P5E_CPU0_P2_TX_DN<15>")
	)
	(segment
		(start 374.867932 -275.218906)
		(end 374.90527 -275.240496)
		(width 0.1143)
		(layer "In13.Cu")
		(net "P5E_CPU0_P2_TX_DN<15>")
	)
	(segment
		(start 373.895874 -271.959832)
		(end 373.947182 -271.990058)
		(width 0.1143)
		(layer "In13.Cu")
		(net "P5E_CPU0_P2_TX_DN<15>")
	)
	(segment
		(start 374.835928 -288.160206)
		(end 374.867678 -288.178748)
		(width 0.1143)
		(layer "In13.Cu")
		(net "P5E_CPU0_P2_TX_DN<15>")
	)
	(segment
		(start 374.835928 -294.64)
		(end 374.90527 -294.680386)
		(width 0.1143)
		(layer "In13.Cu")
		(net "P5E_CPU0_P2_TX_DN<15>")
	)
	(segment
		(start 374.867932 -277.813262)
		(end 374.835928 -277.832058)
		(width 0.1143)
		(layer "In13.Cu")
		(net "P5E_CPU0_P2_TX_DN<15>")
	)
	(segment
		(start 374.867932 -279.433274)
		(end 374.835928 -279.45207)
		(width 0.1143)
		(layer "In13.Cu")
		(net "P5E_CPU0_P2_TX_DN<15>")
	)
	(segment
		(start 374.867932 -291.418772)
		(end 374.90527 -291.440362)
		(width 0.1143)
		(layer "In13.Cu")
		(net "P5E_CPU0_P2_TX_DN<15>")
	)
	(segment
		(start 374.90527 -277.791672)
		(end 374.867932 -277.813262)
		(width 0.1143)
		(layer "In13.Cu")
		(net "P5E_CPU0_P2_TX_DN<15>")
	)
	(segment
		(start 374.867932 -282.673298)
		(end 374.835928 -282.692094)
		(width 0.1143)
		(layer "In13.Cu")
		(net "P5E_CPU0_P2_TX_DN<15>")
	)
	(segment
		(start 374.90527 -276.17166)
		(end 374.867932 -276.19325)
		(width 0.1143)
		(layer "In13.Cu")
		(net "P5E_CPU0_P2_TX_DN<15>")
	)
	(arc
		(start 401.608036 -359.450132)
		(mid 401.635144 -359.50735)
		(end 401.667726 -359.561638)
		(width 0.14224)
		(layer "In13.Cu")
		(net "P5E_CPU0_P2_TX_DN<15>")
	)
	(arc
		(start 374.90527 -273.620484)
		(mid 375.150091 -274.086066)
		(end 374.90527 -274.551648)
		(width 0.1143)
		(layer "In13.Cu")
		(net "P5E_CPU0_P2_TX_DN<15>")
	)
	(arc
		(start 374.836182 -285.932118)
		(mid 374.721339 -286.065266)
		(end 374.679972 -286.236156)
		(width 0.1143)
		(layer "In13.Cu")
		(net "P5E_CPU0_P2_TX_DN<15>")
	)
	(arc
		(start 374.90527 -280.100532)
		(mid 375.150091 -280.566114)
		(end 374.90527 -281.031696)
		(width 0.1143)
		(layer "In13.Cu")
		(net "P5E_CPU0_P2_TX_DN<15>")
	)
	(arc
		(start 428.56277 -388.33171)
		(mid 428.43005 -388.420454)
		(end 428.273464 -388.451598)
		(width 0.14224)
		(layer "In13.Cu")
		(net "P5E_CPU0_P2_TX_DN<15>")
	)
	(arc
		(start 375.70664 -296.881296)
		(mid 375.712918 -296.944097)
		(end 375.731278 -297.004486)
		(width 0.14224)
		(layer "In13.Cu")
		(net "P5E_CPU0_P2_TX_DN<15>")
	)
	(arc
		(start 428.968408 -376.708924)
		(mid 429.057152 -376.841644)
		(end 429.088296 -376.99823)
		(width 0.14224)
		(layer "In13.Cu")
		(net "P5E_CPU0_P2_TX_DN<15>")
	)
	(arc
		(start 374.835928 -284.312106)
		(mid 374.680101 -284.616144)
		(end 374.835928 -284.920182)
		(width 0.1143)
		(layer "In13.Cu")
		(net "P5E_CPU0_P2_TX_DN<15>")
	)
	(arc
		(start 374.835928 -289.171888)
		(mid 374.680101 -289.475926)
		(end 374.835928 -289.779964)
		(width 0.1143)
		(layer "In13.Cu")
		(net "P5E_CPU0_P2_TX_DN<15>")
	)
	(arc
		(start 427.078648 -374.556782)
		(mid 427.126903 -374.799286)
		(end 427.264322 -375.004838)
		(width 0.14224)
		(layer "In13.Cu")
		(net "P5E_CPU0_P2_TX_DN<15>")
	)
	(arc
		(start 374.436132 -272.810986)
		(mid 374.615325 -273.013496)
		(end 374.679972 -273.27606)
		(width 0.1143)
		(layer "In13.Cu")
		(net "P5E_CPU0_P2_TX_DN<15>")
	)
	(arc
		(start 426.95876 -372.930166)
		(mid 427.047475 -373.063031)
		(end 427.078648 -373.219726)
		(width 0.14224)
		(layer "In13.Cu")
		(net "P5E_CPU0_P2_TX_DN<15>")
	)
	(arc
		(start 373.947182 -271.990058)
		(mid 374.138172 -272.181036)
		(end 374.20804 -272.441924)
		(width 0.1143)
		(layer "In13.Cu")
		(net "P5E_CPU0_P2_TX_DN<15>")
	)
	(arc
		(start 374.90527 -294.680386)
		(mid 375.085062 -294.882974)
		(end 375.149872 -295.145968)
		(width 0.1143)
		(layer "In13.Cu")
		(net "P5E_CPU0_P2_TX_DN<15>")
	)
	(arc
		(start 374.83796 -287.550606)
		(mid 374.721779 -287.684165)
		(end 374.679972 -287.856168)
		(width 0.1143)
		(layer "In13.Cu")
		(net "P5E_CPU0_P2_TX_DN<15>")
	)
	(arc
		(start 374.835928 -281.072082)
		(mid 374.680101 -281.37612)
		(end 374.835928 -281.680158)
		(width 0.1143)
		(layer "In13.Cu")
		(net "P5E_CPU0_P2_TX_DN<15>")
	)
	(arc
		(start 429.088296 -387.636766)
		(mid 429.057133 -387.793344)
		(end 428.968408 -387.926072)
		(width 0.14224)
		(layer "In13.Cu")
		(net "P5E_CPU0_P2_TX_DN<15>")
	)
	(arc
		(start 374.835928 -274.592034)
		(mid 374.680101 -274.896072)
		(end 374.835928 -275.20011)
		(width 0.1143)
		(layer "In13.Cu")
		(net "P5E_CPU0_P2_TX_DN<15>")
	)
	(arc
		(start 374.835928 -276.212046)
		(mid 374.680101 -276.516084)
		(end 374.835928 -276.820122)
		(width 0.1143)
		(layer "In13.Cu")
		(net "P5E_CPU0_P2_TX_DN<15>")
	)
	(arc
		(start 374.835928 -279.45207)
		(mid 374.680101 -279.756108)
		(end 374.835928 -280.060146)
		(width 0.1143)
		(layer "In13.Cu")
		(net "P5E_CPU0_P2_TX_DN<15>")
	)
	(arc
		(start 374.679972 -273.27606)
		(mid 374.721231 -273.446917)
		(end 374.835928 -273.580098)
		(width 0.1143)
		(layer "In13.Cu")
		(net "P5E_CPU0_P2_TX_DN<15>")
	)
	(arc
		(start 374.90527 -291.440362)
		(mid 375.150091 -291.905944)
		(end 374.90527 -292.371526)
		(width 0.1143)
		(layer "In13.Cu")
		(net "P5E_CPU0_P2_TX_DN<15>")
	)
	(arc
		(start 374.835928 -282.692094)
		(mid 374.680101 -282.996132)
		(end 374.835928 -283.30017)
		(width 0.1143)
		(layer "In13.Cu")
		(net "P5E_CPU0_P2_TX_DN<15>")
	)
	(arc
		(start 374.835928 -277.832058)
		(mid 374.680101 -278.136096)
		(end 374.835928 -278.440134)
		(width 0.1143)
		(layer "In13.Cu")
		(net "P5E_CPU0_P2_TX_DN<15>")
	)
	(arc
		(start 374.90527 -281.720544)
		(mid 375.150091 -282.186126)
		(end 374.90527 -282.651708)
		(width 0.1143)
		(layer "In13.Cu")
		(net "P5E_CPU0_P2_TX_DN<15>")
	)
	(arc
		(start 374.20804 -272.463006)
		(mid 374.2571 -272.648422)
		(end 374.391428 -272.785332)
		(width 0.1143)
		(layer "In13.Cu")
		(net "P5E_CPU0_P2_TX_DN<15>")
	)
	(arc
		(start 374.90527 -293.060374)
		(mid 375.150091 -293.525956)
		(end 374.90527 -293.991538)
		(width 0.1143)
		(layer "In13.Cu")
		(net "P5E_CPU0_P2_TX_DN<15>")
	)
	(arc
		(start 405.764238 -365.66983)
		(mid 405.840708 -365.738202)
		(end 405.923242 -365.799116)
		(width 0.14224)
		(layer "In13.Cu")
		(net "P5E_CPU0_P2_TX_DN<15>")
	)
	(arc
		(start 374.679972 -287.856168)
		(mid 374.721231 -288.027025)
		(end 374.835928 -288.160206)
		(width 0.1143)
		(layer "In13.Cu")
		(net "P5E_CPU0_P2_TX_DN<15>")
	)
	(arc
		(start 374.90527 -276.860508)
		(mid 375.150091 -277.32609)
		(end 374.90527 -277.791672)
		(width 0.1143)
		(layer "In13.Cu")
		(net "P5E_CPU0_P2_TX_DN<15>")
	)
	(arc
		(start 405.68372 -365.572548)
		(mid 405.721476 -365.623261)
		(end 405.764238 -365.66983)
		(width 0.14224)
		(layer "In13.Cu")
		(net "P5E_CPU0_P2_TX_DN<15>")
	)
	(arc
		(start 373.746776 -271.726152)
		(mid 373.798906 -271.857301)
		(end 373.895874 -271.959832)
		(width 0.1143)
		(layer "In13.Cu")
		(net "P5E_CPU0_P2_TX_DN<15>")
	)
	(arc
		(start 375.149872 -288.66592)
		(mid 375.085054 -288.928909)
		(end 374.90527 -289.131502)
		(width 0.1143)
		(layer "In13.Cu")
		(net "P5E_CPU0_P2_TX_DN<15>")
	)
	(arc
		(start 374.679972 -286.236156)
		(mid 374.721231 -286.407013)
		(end 374.835928 -286.540194)
		(width 0.1143)
		(layer "In13.Cu")
		(net "P5E_CPU0_P2_TX_DN<15>")
	)
	(arc
		(start 374.90527 -289.82035)
		(mid 375.150091 -290.285932)
		(end 374.90527 -290.751514)
		(width 0.1143)
		(layer "In13.Cu")
		(net "P5E_CPU0_P2_TX_DN<15>")
	)
	(arc
		(start 374.835928 -290.7919)
		(mid 374.680101 -291.095938)
		(end 374.835928 -291.399976)
		(width 0.1143)
		(layer "In13.Cu")
		(net "P5E_CPU0_P2_TX_DN<15>")
	)
	(arc
		(start 374.835928 -292.411912)
		(mid 374.680101 -292.71595)
		(end 374.835928 -293.019988)
		(width 0.1143)
		(layer "In13.Cu")
		(net "P5E_CPU0_P2_TX_DN<15>")
	)
	(arc
		(start 374.907556 -288.201608)
		(mid 375.085738 -288.404011)
		(end 375.149872 -288.66592)
		(width 0.1143)
		(layer "In13.Cu")
		(net "P5E_CPU0_P2_TX_DN<15>")
	)
	(arc
		(start 374.835928 -294.031924)
		(mid 374.680101 -294.335962)
		(end 374.835928 -294.64)
		(width 0.1143)
		(layer "In13.Cu")
		(net "P5E_CPU0_P2_TX_DN<15>")
	)
	(arc
		(start 375.149872 -287.045908)
		(mid 375.085054 -287.308897)
		(end 374.90527 -287.51149)
		(width 0.1143)
		(layer "In13.Cu")
		(net "P5E_CPU0_P2_TX_DN<15>")
	)
	(arc
		(start 374.90527 -283.340556)
		(mid 375.150091 -283.806138)
		(end 374.90527 -284.27172)
		(width 0.1143)
		(layer "In13.Cu")
		(net "P5E_CPU0_P2_TX_DN<15>")
	)
	(arc
		(start 374.90527 -278.48052)
		(mid 375.150091 -278.946102)
		(end 374.90527 -279.411684)
		(width 0.1143)
		(layer "In13.Cu")
		(net "P5E_CPU0_P2_TX_DN<15>")
	)
	(arc
		(start 425.222924 -371.364002)
		(mid 425.379627 -371.395154)
		(end 425.512484 -371.48389)
		(width 0.14224)
		(layer "In13.Cu")
		(net "P5E_CPU0_P2_TX_DN<15>")
	)
	(arc
		(start 374.90527 -275.240496)
		(mid 375.150091 -275.706078)
		(end 374.90527 -276.17166)
		(width 0.1143)
		(layer "In13.Cu")
		(net "P5E_CPU0_P2_TX_DN<15>")
	)
	(arc
		(start 374.90527 -284.960568)
		(mid 375.150091 -285.42615)
		(end 374.90527 -285.891732)
		(width 0.1143)
		(layer "In13.Cu")
		(net "P5E_CPU0_P2_TX_DN<15>")
	)
	(arc
		(start 374.907556 -286.581596)
		(mid 375.085738 -286.783999)
		(end 375.149872 -287.045908)
		(width 0.1143)
		(layer "In13.Cu")
		(net "P5E_CPU0_P2_TX_DN<15>")
	)
	(segment
		(start 426.63491 -385.068318)
		(end 425.93133 -385.068318)
		(width 0.12954)
		(layer "F.Cu")
		(net "P5E_CPU0_P2_TX_DN<14>")
	)
	(segment
		(start 426.90542 -385.338828)
		(end 426.63491 -385.068318)
		(width 0.12954)
		(layer "F.Cu")
		(net "P5E_CPU0_P2_TX_DN<14>")
	)
	(segment
		(start 373.64797 -273.010122)
		(end 374.114822 -273.27606)
		(width 0.12954)
		(layer "F.Cu")
		(net "P5E_CPU0_P2_TX_DN<14>")
	)
	(segment
		(start 425.93133 -385.068318)
		(end 425.63542 -385.364228)
		(width 0.12954)
		(layer "F.Cu")
		(net "P5E_CPU0_P2_TX_DN<14>")
	)
	(segment
		(start 374.680226 -295.95572)
		(end 374.680226 -296.538142)
		(width 0.1143)
		(layer "In13.Cu")
		(net "P5E_CPU0_P2_TX_DN<14>")
	)
	(segment
		(start 400.811746 -360.12247)
		(end 404.874222 -366.202468)
		(width 0.14224)
		(layer "In13.Cu")
		(net "P5E_CPU0_P2_TX_DN<14>")
	)
	(segment
		(start 373.927878 -276.193504)
		(end 373.927116 -276.194012)
		(width 0.1143)
		(layer "In13.Cu")
		(net "P5E_CPU0_P2_TX_DN<14>")
	)
	(segment
		(start 373.896128 -291.40023)
		(end 373.921274 -291.414708)
		(width 0.1143)
		(layer "In13.Cu")
		(net "P5E_CPU0_P2_TX_DN<14>")
	)
	(segment
		(start 373.922036 -290.77666)
		(end 373.921274 -290.777168)
		(width 0.1143)
		(layer "In13.Cu")
		(net "P5E_CPU0_P2_TX_DN<14>")
	)
	(segment
		(start 373.915432 -276.200616)
		(end 373.914162 -276.201378)
		(width 0.1143)
		(layer "In13.Cu")
		(net "P5E_CPU0_P2_TX_DN<14>")
	)
	(segment
		(start 373.912638 -276.20214)
		(end 373.896128 -276.211792)
		(width 0.1143)
		(layer "In13.Cu")
		(net "P5E_CPU0_P2_TX_DN<14>")
	)
	(segment
		(start 427.693582 -385.047998)
		(end 427.19625 -385.047998)
		(width 0.14224)
		(layer "In13.Cu")
		(net "P5E_CPU0_P2_TX_DN<14>")
	)
	(segment
		(start 373.930672 -278.460454)
		(end 373.96674 -278.481282)
		(width 0.1143)
		(layer "In13.Cu")
		(net "P5E_CPU0_P2_TX_DN<14>")
	)
	(segment
		(start 373.930926 -285.911798)
		(end 373.922036 -285.916878)
		(width 0.1143)
		(layer "In13.Cu")
		(net "P5E_CPU0_P2_TX_DN<14>")
	)
	(segment
		(start 373.923306 -274.576286)
		(end 373.920004 -274.578064)
		(width 0.1143)
		(layer "In13.Cu")
		(net "P5E_CPU0_P2_TX_DN<14>")
	)
	(segment
		(start 373.920004 -274.578064)
		(end 373.919242 -274.578572)
		(width 0.1143)
		(layer "In13.Cu")
		(net "P5E_CPU0_P2_TX_DN<14>")
	)
	(segment
		(start 374.735852 -297.196002)
		(end 400.811746 -360.12247)
		(width 0.14224)
		(layer "In13.Cu")
		(net "P5E_CPU0_P2_TX_DN<14>")
	)
	(segment
		(start 373.916194 -277.82012)
		(end 373.915432 -277.820628)
		(width 0.1143)
		(layer "In13.Cu")
		(net "P5E_CPU0_P2_TX_DN<14>")
	)
	(segment
		(start 373.916194 -276.200108)
		(end 373.915432 -276.200616)
		(width 0.1143)
		(layer "In13.Cu")
		(net "P5E_CPU0_P2_TX_DN<14>")
	)
	(segment
		(start 373.918226 -284.298898)
		(end 373.896128 -284.311852)
		(width 0.1143)
		(layer "In13.Cu")
		(net "P5E_CPU0_P2_TX_DN<14>")
	)
	(segment
		(start 373.927116 -276.194012)
		(end 373.923306 -276.196298)
		(width 0.1143)
		(layer "In13.Cu")
		(net "P5E_CPU0_P2_TX_DN<14>")
	)
	(segment
		(start 373.927878 -281.05354)
		(end 373.896128 -281.071828)
		(width 0.1143)
		(layer "In13.Cu")
		(net "P5E_CPU0_P2_TX_DN<14>")
	)
	(segment
		(start 373.927878 -293.03853)
		(end 373.930926 -293.040308)
		(width 0.1143)
		(layer "In13.Cu")
		(net "P5E_CPU0_P2_TX_DN<14>")
	)
	(segment
		(start 373.927878 -281.6987)
		(end 373.930926 -281.700478)
		(width 0.1143)
		(layer "In13.Cu")
		(net "P5E_CPU0_P2_TX_DN<14>")
	)
	(segment
		(start 373.921274 -289.794696)
		(end 373.922036 -289.795204)
		(width 0.1143)
		(layer "In13.Cu")
		(net "P5E_CPU0_P2_TX_DN<14>")
	)
	(segment
		(start 373.930926 -282.671774)
		(end 373.922036 -282.676854)
		(width 0.1143)
		(layer "In13.Cu")
		(net "P5E_CPU0_P2_TX_DN<14>")
	)
	(segment
		(start 373.914162 -279.441402)
		(end 373.912638 -279.442164)
		(width 0.1143)
		(layer "In13.Cu")
		(net "P5E_CPU0_P2_TX_DN<14>")
	)
	(segment
		(start 373.914162 -274.581366)
		(end 373.912638 -274.582128)
		(width 0.1143)
		(layer "In13.Cu")
		(net "P5E_CPU0_P2_TX_DN<14>")
	)
	(segment
		(start 373.922036 -289.156648)
		(end 373.921274 -289.157156)
		(width 0.1143)
		(layer "In13.Cu")
		(net "P5E_CPU0_P2_TX_DN<14>")
	)
	(segment
		(start 373.96674 -276.86127)
		(end 373.99468 -276.881336)
		(width 0.1143)
		(layer "In13.Cu")
		(net "P5E_CPU0_P2_TX_DN<14>")
	)
	(segment
		(start 373.918226 -290.778692)
		(end 373.896128 -290.791646)
		(width 0.1143)
		(layer "In13.Cu")
		(net "P5E_CPU0_P2_TX_DN<14>")
	)
	(segment
		(start 373.919242 -274.578572)
		(end 373.916194 -274.580096)
		(width 0.1143)
		(layer "In13.Cu")
		(net "P5E_CPU0_P2_TX_DN<14>")
	)
	(segment
		(start 373.922036 -289.795204)
		(end 373.92356 -289.795966)
		(width 0.1143)
		(layer "In13.Cu")
		(net "P5E_CPU0_P2_TX_DN<14>")
	)
	(segment
		(start 373.877586 -293.00678)
		(end 373.896128 -293.020242)
		(width 0.1143)
		(layer "In13.Cu")
		(net "P5E_CPU0_P2_TX_DN<14>")
	)
	(segment
		(start 373.92356 -291.415978)
		(end 373.927878 -291.418518)
		(width 0.1143)
		(layer "In13.Cu")
		(net "P5E_CPU0_P2_TX_DN<14>")
	)
	(segment
		(start 373.918226 -294.018716)
		(end 373.896128 -294.03167)
		(width 0.1143)
		(layer "In13.Cu")
		(net "P5E_CPU0_P2_TX_DN<14>")
	)
	(segment
		(start 373.99468 -277.770844)
		(end 373.96674 -277.79091)
		(width 0.1143)
		(layer "In13.Cu")
		(net "P5E_CPU0_P2_TX_DN<14>")
	)
	(segment
		(start 428.035212 -384.875786)
		(end 427.982888 -384.92811)
		(width 0.14224)
		(layer "In13.Cu")
		(net "P5E_CPU0_P2_TX_DN<14>")
	)
	(segment
		(start 373.96674 -279.410922)
		(end 373.929402 -279.432512)
		(width 0.1143)
		(layer "In13.Cu")
		(net "P5E_CPU0_P2_TX_DN<14>")
	)
	(segment
		(start 373.927878 -276.838664)
		(end 373.930672 -276.840442)
		(width 0.1143)
		(layer "In13.Cu")
		(net "P5E_CPU0_P2_TX_DN<14>")
	)
	(segment
		(start 373.921274 -281.69489)
		(end 373.922036 -281.695398)
		(width 0.1143)
		(layer "In13.Cu")
		(net "P5E_CPU0_P2_TX_DN<14>")
	)
	(segment
		(start 373.914162 -277.82139)
		(end 373.912638 -277.822152)
		(width 0.1143)
		(layer "In13.Cu")
		(net "P5E_CPU0_P2_TX_DN<14>")
	)
	(segment
		(start 373.921274 -294.654732)
		(end 373.922036 -294.65524)
		(width 0.1143)
		(layer "In13.Cu")
		(net "P5E_CPU0_P2_TX_DN<14>")
	)
	(segment
		(start 373.89435 -286.538924)
		(end 373.969026 -286.582866)
		(width 0.1143)
		(layer "In13.Cu")
		(net "P5E_CPU0_P2_TX_DN<14>")
	)
	(segment
		(start 373.921274 -290.777168)
		(end 373.918226 -290.778692)
		(width 0.1143)
		(layer "In13.Cu")
		(net "P5E_CPU0_P2_TX_DN<14>")
	)
	(segment
		(start 373.912638 -274.582128)
		(end 373.896128 -274.59178)
		(width 0.1143)
		(layer "In13.Cu")
		(net "P5E_CPU0_P2_TX_DN<14>")
	)
	(segment
		(start 373.92356 -284.936184)
		(end 373.927878 -284.938724)
		(width 0.1143)
		(layer "In13.Cu")
		(net "P5E_CPU0_P2_TX_DN<14>")
	)
	(segment
		(start 373.915432 -274.580604)
		(end 373.914162 -274.581366)
		(width 0.1143)
		(layer "In13.Cu")
		(net "P5E_CPU0_P2_TX_DN<14>")
	)
	(segment
		(start 426.105828 -375.13641)
		(end 426.105828 -375.628662)
		(width 0.14224)
		(layer "In13.Cu")
		(net "P5E_CPU0_P2_TX_DN<14>")
	)
	(segment
		(start 373.918226 -285.91891)
		(end 373.896128 -285.931864)
		(width 0.1143)
		(layer "In13.Cu")
		(net "P5E_CPU0_P2_TX_DN<14>")
	)
	(segment
		(start 373.927878 -280.078688)
		(end 373.9642 -280.09977)
		(width 0.1143)
		(layer "In13.Cu")
		(net "P5E_CPU0_P2_TX_DN<14>")
	)
	(segment
		(start 420.007796 -372.928134)
		(end 423.897298 -372.928134)
		(width 0.14224)
		(layer "In13.Cu")
		(net "P5E_CPU0_P2_TX_DN<14>")
	)
	(segment
		(start 374.725946 -296.61231)
		(end 374.725946 -297.147234)
		(width 0.14224)
		(layer "In13.Cu")
		(net "P5E_CPU0_P2_TX_DN<14>")
	)
	(segment
		(start 373.915432 -277.820628)
		(end 373.914162 -277.82139)
		(width 0.1143)
		(layer "In13.Cu")
		(net "P5E_CPU0_P2_TX_DN<14>")
	)
	(segment
		(start 373.921274 -284.297374)
		(end 373.918226 -284.298898)
		(width 0.1143)
		(layer "In13.Cu")
		(net "P5E_CPU0_P2_TX_DN<14>")
	)
	(segment
		(start 373.923306 -277.81631)
		(end 373.920004 -277.818088)
		(width 0.1143)
		(layer "In13.Cu")
		(net "P5E_CPU0_P2_TX_DN<14>")
	)
	(segment
		(start 374.680226 -296.538142)
		(end 374.725946 -296.583862)
		(width 0.1143)
		(layer "In13.Cu")
		(net "P5E_CPU0_P2_TX_DN<14>")
	)
	(segment
		(start 373.930672 -276.840442)
		(end 373.96674 -276.86127)
		(width 0.1143)
		(layer "In13.Cu")
		(net "P5E_CPU0_P2_TX_DN<14>")
	)
	(segment
		(start 373.927878 -288.178494)
		(end 373.930926 -288.180272)
		(width 0.1143)
		(layer "In13.Cu")
		(net "P5E_CPU0_P2_TX_DN<14>")
	)
	(segment
		(start 373.932196 -294.661082)
		(end 373.96801 -294.682164)
		(width 0.1143)
		(layer "In13.Cu")
		(net "P5E_CPU0_P2_TX_DN<14>")
	)
	(segment
		(start 373.896128 -284.920436)
		(end 373.921274 -284.934914)
		(width 0.1143)
		(layer "In13.Cu")
		(net "P5E_CPU0_P2_TX_DN<14>")
	)
	(segment
		(start 373.922036 -293.035228)
		(end 373.92356 -293.03599)
		(width 0.1143)
		(layer "In13.Cu")
		(net "P5E_CPU0_P2_TX_DN<14>")
	)
	(segment
		(start 373.92356 -294.656002)
		(end 373.931434 -294.660574)
		(width 0.1143)
		(layer "In13.Cu")
		(net "P5E_CPU0_P2_TX_DN<14>")
	)
	(segment
		(start 373.929402 -279.432512)
		(end 373.927116 -279.434036)
		(width 0.1143)
		(layer "In13.Cu")
		(net "P5E_CPU0_P2_TX_DN<14>")
	)
	(segment
		(start 373.99468 -279.390856)
		(end 373.96674 -279.410922)
		(width 0.1143)
		(layer "In13.Cu")
		(net "P5E_CPU0_P2_TX_DN<14>")
	)
	(segment
		(start 428.1551 -377.923044)
		(end 428.1551 -384.58648)
		(width 0.14224)
		(layer "In13.Cu")
		(net "P5E_CPU0_P2_TX_DN<14>")
	)
	(segment
		(start 373.927878 -291.418772)
		(end 373.965978 -291.440362)
		(width 0.1143)
		(layer "In13.Cu")
		(net "P5E_CPU0_P2_TX_DN<14>")
	)
	(segment
		(start 406.669494 -367.443512)
		(end 419.820598 -372.890796)
		(width 0.14224)
		(layer "In13.Cu")
		(net "P5E_CPU0_P2_TX_DN<14>")
	)
	(segment
		(start 373.922036 -294.65524)
		(end 373.92356 -294.656002)
		(width 0.1143)
		(layer "In13.Cu")
		(net "P5E_CPU0_P2_TX_DN<14>")
	)
	(segment
		(start 373.920004 -279.4381)
		(end 373.919242 -279.438608)
		(width 0.1143)
		(layer "In13.Cu")
		(net "P5E_CPU0_P2_TX_DN<14>")
	)
	(segment
		(start 373.919242 -279.438608)
		(end 373.916194 -279.440132)
		(width 0.1143)
		(layer "In13.Cu")
		(net "P5E_CPU0_P2_TX_DN<14>")
	)
	(segment
		(start 373.927116 -275.218144)
		(end 373.927878 -275.218652)
		(width 0.1143)
		(layer "In13.Cu")
		(net "P5E_CPU0_P2_TX_DN<14>")
	)
	(segment
		(start 374.114822 -273.27606)
		(end 373.81688 -273.27606)
		(width 0.1143)
		(layer "In13.Cu")
		(net "P5E_CPU0_P2_TX_DN<14>")
	)
	(segment
		(start 373.927878 -274.573492)
		(end 373.927116 -274.574)
		(width 0.1143)
		(layer "In13.Cu")
		(net "P5E_CPU0_P2_TX_DN<14>")
	)
	(segment
		(start 373.930926 -289.151568)
		(end 373.922036 -289.156648)
		(width 0.1143)
		(layer "In13.Cu")
		(net "P5E_CPU0_P2_TX_DN<14>")
	)
	(segment
		(start 373.921274 -285.917386)
		(end 373.918226 -285.91891)
		(width 0.1143)
		(layer "In13.Cu")
		(net "P5E_CPU0_P2_TX_DN<14>")
	)
	(segment
		(start 373.921274 -282.677362)
		(end 373.918226 -282.678886)
		(width 0.1143)
		(layer "In13.Cu")
		(net "P5E_CPU0_P2_TX_DN<14>")
	)
	(segment
		(start 373.96674 -278.481282)
		(end 373.99468 -278.501348)
		(width 0.1143)
		(layer "In13.Cu")
		(net "P5E_CPU0_P2_TX_DN<14>")
	)
	(segment
		(start 373.922036 -285.916878)
		(end 373.921274 -285.917386)
		(width 0.1143)
		(layer "In13.Cu")
		(net "P5E_CPU0_P2_TX_DN<14>")
	)
	(segment
		(start 373.927878 -283.318712)
		(end 373.930926 -283.32049)
		(width 0.1143)
		(layer "In13.Cu")
		(net "P5E_CPU0_P2_TX_DN<14>")
	)
	(segment
		(start 426.159422 -375.757948)
		(end 428.035212 -377.633738)
		(width 0.14224)
		(layer "In13.Cu")
		(net "P5E_CPU0_P2_TX_DN<14>")
	)
	(segment
		(start 373.9642 -274.55241)
		(end 373.927878 -274.573492)
		(width 0.1143)
		(layer "In13.Cu")
		(net "P5E_CPU0_P2_TX_DN<14>")
	)
	(segment
		(start 373.92356 -289.795966)
		(end 373.927878 -289.798506)
		(width 0.1143)
		(layer "In13.Cu")
		(net "P5E_CPU0_P2_TX_DN<14>")
	)
	(segment
		(start 373.922036 -291.415216)
		(end 373.92356 -291.415978)
		(width 0.1143)
		(layer "In13.Cu")
		(net "P5E_CPU0_P2_TX_DN<14>")
	)
	(segment
		(start 373.927116 -278.458168)
		(end 373.927878 -278.458676)
		(width 0.1143)
		(layer "In13.Cu")
		(net "P5E_CPU0_P2_TX_DN<14>")
	)
	(segment
		(start 373.929402 -277.8125)
		(end 373.927116 -277.814024)
		(width 0.1143)
		(layer "In13.Cu")
		(net "P5E_CPU0_P2_TX_DN<14>")
	)
	(segment
		(start 373.921274 -289.157156)
		(end 373.918226 -289.15868)
		(width 0.1143)
		(layer "In13.Cu")
		(net "P5E_CPU0_P2_TX_DN<14>")
	)
	(segment
		(start 373.81688 -273.27606)
		(end 373.74703 -273.34591)
		(width 0.1143)
		(layer "In13.Cu")
		(net "P5E_CPU0_P2_TX_DN<14>")
	)
	(segment
		(start 373.927116 -283.318204)
		(end 373.927878 -283.318712)
		(width 0.1143)
		(layer "In13.Cu")
		(net "P5E_CPU0_P2_TX_DN<14>")
	)
	(segment
		(start 374.399302 -295.469564)
		(end 374.43664 -295.4909)
		(width 0.1143)
		(layer "In13.Cu")
		(net "P5E_CPU0_P2_TX_DN<14>")
	)
	(segment
		(start 373.927116 -276.838156)
		(end 373.927878 -276.838664)
		(width 0.1143)
		(layer "In13.Cu")
		(net "P5E_CPU0_P2_TX_DN<14>")
	)
	(segment
		(start 373.918226 -282.678886)
		(end 373.896128 -282.69184)
		(width 0.1143)
		(layer "In13.Cu")
		(net "P5E_CPU0_P2_TX_DN<14>")
	)
	(segment
		(start 373.896128 -294.640254)
		(end 373.921274 -294.654732)
		(width 0.1143)
		(layer "In13.Cu")
		(net "P5E_CPU0_P2_TX_DN<14>")
	)
	(segment
		(start 427.19625 -385.047998)
		(end 426.90542 -385.338828)
		(width 0.14224)
		(layer "In13.Cu")
		(net "P5E_CPU0_P2_TX_DN<14>")
	)
	(segment
		(start 373.922036 -284.296866)
		(end 373.921274 -284.297374)
		(width 0.1143)
		(layer "In13.Cu")
		(net "P5E_CPU0_P2_TX_DN<14>")
	)
	(segment
		(start 373.920004 -276.198076)
		(end 373.919242 -276.198584)
		(width 0.1143)
		(layer "In13.Cu")
		(net "P5E_CPU0_P2_TX_DN<14>")
	)
	(segment
		(start 373.921274 -284.934914)
		(end 373.922036 -284.935422)
		(width 0.1143)
		(layer "In13.Cu")
		(net "P5E_CPU0_P2_TX_DN<14>")
	)
	(segment
		(start 373.909844 -293.028116)
		(end 373.921274 -293.03472)
		(width 0.1143)
		(layer "In13.Cu")
		(net "P5E_CPU0_P2_TX_DN<14>")
	)
	(segment
		(start 373.922036 -294.016684)
		(end 373.921274 -294.017192)
		(width 0.1143)
		(layer "In13.Cu")
		(net "P5E_CPU0_P2_TX_DN<14>")
	)
	(segment
		(start 404.999698 -366.327944)
		(end 406.669494 -367.443512)
		(width 0.14224)
		(layer "In13.Cu")
		(net "P5E_CPU0_P2_TX_DN<14>")
	)
	(segment
		(start 373.930926 -290.77158)
		(end 373.922036 -290.77666)
		(width 0.1143)
		(layer "In13.Cu")
		(net "P5E_CPU0_P2_TX_DN<14>")
	)
	(segment
		(start 373.923306 -279.436322)
		(end 373.920004 -279.4381)
		(width 0.1143)
		(layer "In13.Cu")
		(net "P5E_CPU0_P2_TX_DN<14>")
	)
	(segment
		(start 424.186858 -373.048022)
		(end 425.98594 -374.847104)
		(width 0.14224)
		(layer "In13.Cu")
		(net "P5E_CPU0_P2_TX_DN<14>")
	)
	(segment
		(start 373.916194 -274.580096)
		(end 373.915432 -274.580604)
		(width 0.1143)
		(layer "In13.Cu")
		(net "P5E_CPU0_P2_TX_DN<14>")
	)
	(segment
		(start 373.896128 -283.300424)
		(end 373.927116 -283.318204)
		(width 0.1143)
		(layer "In13.Cu")
		(net "P5E_CPU0_P2_TX_DN<14>")
	)
	(segment
		(start 373.927878 -278.458676)
		(end 373.930672 -278.460454)
		(width 0.1143)
		(layer "In13.Cu")
		(net "P5E_CPU0_P2_TX_DN<14>")
	)
	(segment
		(start 373.965978 -292.371526)
		(end 373.896128 -292.411658)
		(width 0.1143)
		(layer "In13.Cu")
		(net "P5E_CPU0_P2_TX_DN<14>")
	)
	(segment
		(start 373.921274 -293.03472)
		(end 373.922036 -293.035228)
		(width 0.1143)
		(layer "In13.Cu")
		(net "P5E_CPU0_P2_TX_DN<14>")
	)
	(segment
		(start 373.909082 -293.027608)
		(end 373.909844 -293.028116)
		(width 0.1143)
		(layer "In13.Cu")
		(net "P5E_CPU0_P2_TX_DN<14>")
	)
	(segment
		(start 373.927116 -279.434036)
		(end 373.923306 -279.436322)
		(width 0.1143)
		(layer "In13.Cu")
		(net "P5E_CPU0_P2_TX_DN<14>")
	)
	(segment
		(start 373.920004 -277.818088)
		(end 373.919242 -277.818596)
		(width 0.1143)
		(layer "In13.Cu")
		(net "P5E_CPU0_P2_TX_DN<14>")
	)
	(segment
		(start 373.919242 -277.818596)
		(end 373.916194 -277.82012)
		(width 0.1143)
		(layer "In13.Cu")
		(net "P5E_CPU0_P2_TX_DN<14>")
	)
	(segment
		(start 373.927878 -284.938724)
		(end 373.930926 -284.940502)
		(width 0.1143)
		(layer "In13.Cu")
		(net "P5E_CPU0_P2_TX_DN<14>")
	)
	(segment
		(start 373.896128 -280.0604)
		(end 373.927878 -280.078688)
		(width 0.1143)
		(layer "In13.Cu")
		(net "P5E_CPU0_P2_TX_DN<14>")
	)
	(segment
		(start 373.930926 -294.011604)
		(end 373.922036 -294.016684)
		(width 0.1143)
		(layer "In13.Cu")
		(net "P5E_CPU0_P2_TX_DN<14>")
	)
	(segment
		(start 373.921274 -294.017192)
		(end 373.918226 -294.018716)
		(width 0.1143)
		(layer "In13.Cu")
		(net "P5E_CPU0_P2_TX_DN<14>")
	)
	(segment
		(start 373.919242 -276.198584)
		(end 373.916194 -276.200108)
		(width 0.1143)
		(layer "In13.Cu")
		(net "P5E_CPU0_P2_TX_DN<14>")
	)
	(segment
		(start 374.210072 -287.045908)
		(end 374.210072 -287.05048)
		(width 0.1143)
		(layer "In13.Cu")
		(net "P5E_CPU0_P2_TX_DN<14>")
	)
	(segment
		(start 373.918226 -289.15868)
		(end 373.896128 -289.171634)
		(width 0.1143)
		(layer "In13.Cu")
		(net "P5E_CPU0_P2_TX_DN<14>")
	)
	(segment
		(start 373.927878 -275.218652)
		(end 373.9642 -275.239734)
		(width 0.1143)
		(layer "In13.Cu")
		(net "P5E_CPU0_P2_TX_DN<14>")
	)
	(segment
		(start 373.927116 -273.598132)
		(end 373.927878 -273.59864)
		(width 0.1143)
		(layer "In13.Cu")
		(net "P5E_CPU0_P2_TX_DN<14>")
	)
	(segment
		(start 373.97944 -287.501584)
		(end 373.96801 -287.51022)
		(width 0.1143)
		(layer "In13.Cu")
		(net "P5E_CPU0_P2_TX_DN<14>")
	)
	(segment
		(start 373.921274 -291.414708)
		(end 373.922036 -291.415216)
		(width 0.1143)
		(layer "In13.Cu")
		(net "P5E_CPU0_P2_TX_DN<14>")
	)
	(segment
		(start 373.92356 -293.03599)
		(end 373.927878 -293.03853)
		(width 0.1143)
		(layer "In13.Cu")
		(net "P5E_CPU0_P2_TX_DN<14>")
	)
	(segment
		(start 373.927116 -274.574)
		(end 373.923306 -274.576286)
		(width 0.1143)
		(layer "In13.Cu")
		(net "P5E_CPU0_P2_TX_DN<14>")
	)
	(segment
		(start 373.927878 -291.418518)
		(end 373.927878 -291.418772)
		(width 0.1143)
		(layer "In13.Cu")
		(net "P5E_CPU0_P2_TX_DN<14>")
	)
	(segment
		(start 373.895112 -288.159444)
		(end 373.927878 -288.178494)
		(width 0.1143)
		(layer "In13.Cu")
		(net "P5E_CPU0_P2_TX_DN<14>")
	)
	(segment
		(start 373.927878 -289.798506)
		(end 373.930926 -289.800284)
		(width 0.1143)
		(layer "In13.Cu")
		(net "P5E_CPU0_P2_TX_DN<14>")
	)
	(segment
		(start 373.96801 -287.51022)
		(end 373.896128 -287.551876)
		(width 0.1143)
		(layer "In13.Cu")
		(net "P5E_CPU0_P2_TX_DN<14>")
	)
	(segment
		(start 373.896128 -273.580352)
		(end 373.927116 -273.598132)
		(width 0.1143)
		(layer "In13.Cu")
		(net "P5E_CPU0_P2_TX_DN<14>")
	)
	(segment
		(start 373.912638 -279.442164)
		(end 373.896128 -279.451816)
		(width 0.1143)
		(layer "In13.Cu")
		(net "P5E_CPU0_P2_TX_DN<14>")
	)
	(segment
		(start 373.896128 -275.200364)
		(end 373.927116 -275.218144)
		(width 0.1143)
		(layer "In13.Cu")
		(net "P5E_CPU0_P2_TX_DN<14>")
	)
	(segment
		(start 373.896128 -289.780218)
		(end 373.921274 -289.794696)
		(width 0.1143)
		(layer "In13.Cu")
		(net "P5E_CPU0_P2_TX_DN<14>")
	)
	(segment
		(start 373.914162 -276.201378)
		(end 373.912638 -276.20214)
		(width 0.1143)
		(layer "In13.Cu")
		(net "P5E_CPU0_P2_TX_DN<14>")
	)
	(segment
		(start 373.9642 -276.172422)
		(end 373.927878 -276.193504)
		(width 0.1143)
		(layer "In13.Cu")
		(net "P5E_CPU0_P2_TX_DN<14>")
	)
	(segment
		(start 373.92356 -281.69616)
		(end 373.927878 -281.6987)
		(width 0.1143)
		(layer "In13.Cu")
		(net "P5E_CPU0_P2_TX_DN<14>")
	)
	(segment
		(start 373.927878 -273.59864)
		(end 373.9642 -273.619722)
		(width 0.1143)
		(layer "In13.Cu")
		(net "P5E_CPU0_P2_TX_DN<14>")
	)
	(segment
		(start 373.931434 -294.660574)
		(end 373.932196 -294.661082)
		(width 0.1143)
		(layer "In13.Cu")
		(net "P5E_CPU0_P2_TX_DN<14>")
	)
	(segment
		(start 373.896128 -292.411658)
		(end 373.877586 -292.42512)
		(width 0.1143)
		(layer "In13.Cu")
		(net "P5E_CPU0_P2_TX_DN<14>")
	)
	(segment
		(start 373.922036 -282.676854)
		(end 373.921274 -282.677362)
		(width 0.1143)
		(layer "In13.Cu")
		(net "P5E_CPU0_P2_TX_DN<14>")
	)
	(segment
		(start 373.896128 -293.020242)
		(end 373.909082 -293.027608)
		(width 0.1143)
		(layer "In13.Cu")
		(net "P5E_CPU0_P2_TX_DN<14>")
	)
	(segment
		(start 373.896128 -278.440388)
		(end 373.927116 -278.458168)
		(width 0.1143)
		(layer "In13.Cu")
		(net "P5E_CPU0_P2_TX_DN<14>")
	)
	(segment
		(start 373.930926 -284.291786)
		(end 373.922036 -284.296866)
		(width 0.1143)
		(layer "In13.Cu")
		(net "P5E_CPU0_P2_TX_DN<14>")
	)
	(segment
		(start 374.725946 -296.583862)
		(end 374.725946 -296.61231)
		(width 0.1143)
		(layer "In13.Cu")
		(net "P5E_CPU0_P2_TX_DN<14>")
	)
	(segment
		(start 373.912638 -277.822152)
		(end 373.896128 -277.831804)
		(width 0.1143)
		(layer "In13.Cu")
		(net "P5E_CPU0_P2_TX_DN<14>")
	)
	(segment
		(start 373.915432 -279.44064)
		(end 373.914162 -279.441402)
		(width 0.1143)
		(layer "In13.Cu")
		(net "P5E_CPU0_P2_TX_DN<14>")
	)
	(segment
		(start 373.9642 -281.032458)
		(end 373.927878 -281.05354)
		(width 0.1143)
		(layer "In13.Cu")
		(net "P5E_CPU0_P2_TX_DN<14>")
	)
	(segment
		(start 373.896128 -276.820376)
		(end 373.927116 -276.838156)
		(width 0.1143)
		(layer "In13.Cu")
		(net "P5E_CPU0_P2_TX_DN<14>")
	)
	(segment
		(start 373.916194 -279.440132)
		(end 373.915432 -279.44064)
		(width 0.1143)
		(layer "In13.Cu")
		(net "P5E_CPU0_P2_TX_DN<14>")
	)
	(segment
		(start 373.927116 -277.814024)
		(end 373.923306 -277.81631)
		(width 0.1143)
		(layer "In13.Cu")
		(net "P5E_CPU0_P2_TX_DN<14>")
	)
	(segment
		(start 373.89435 -288.158936)
		(end 373.895112 -288.159444)
		(width 0.1143)
		(layer "In13.Cu")
		(net "P5E_CPU0_P2_TX_DN<14>")
	)
	(segment
		(start 373.96674 -277.79091)
		(end 373.929402 -277.8125)
		(width 0.1143)
		(layer "In13.Cu")
		(net "P5E_CPU0_P2_TX_DN<14>")
	)
	(segment
		(start 373.922036 -284.935422)
		(end 373.92356 -284.936184)
		(width 0.1143)
		(layer "In13.Cu")
		(net "P5E_CPU0_P2_TX_DN<14>")
	)
	(segment
		(start 373.896128 -281.680412)
		(end 373.921274 -281.69489)
		(width 0.1143)
		(layer "In13.Cu")
		(net "P5E_CPU0_P2_TX_DN<14>")
	)
	(segment
		(start 373.923306 -276.196298)
		(end 373.920004 -276.198076)
		(width 0.1143)
		(layer "In13.Cu")
		(net "P5E_CPU0_P2_TX_DN<14>")
	)
	(segment
		(start 373.922036 -281.695398)
		(end 373.92356 -281.69616)
		(width 0.1143)
		(layer "In13.Cu")
		(net "P5E_CPU0_P2_TX_DN<14>")
	)
	(arc
		(start 425.98594 -374.847104)
		(mid 426.074684 -374.979824)
		(end 426.105828 -375.13641)
		(width 0.14224)
		(layer "In13.Cu")
		(net "P5E_CPU0_P2_TX_DN<14>")
	)
	(arc
		(start 373.965978 -291.440362)
		(mid 374.20172 -291.905944)
		(end 373.965978 -292.371526)
		(width 0.1143)
		(layer "In13.Cu")
		(net "P5E_CPU0_P2_TX_DN<14>")
	)
	(arc
		(start 374.210326 -295.14165)
		(mid 374.260879 -295.33094)
		(end 374.399302 -295.469564)
		(width 0.1143)
		(layer "In13.Cu")
		(net "P5E_CPU0_P2_TX_DN<14>")
	)
	(arc
		(start 373.877586 -292.42512)
		(mid 373.728571 -292.71595)
		(end 373.877586 -293.00678)
		(width 0.1143)
		(layer "In13.Cu")
		(net "P5E_CPU0_P2_TX_DN<14>")
	)
	(arc
		(start 373.896128 -284.311852)
		(mid 373.7402 -284.616144)
		(end 373.896128 -284.920436)
		(width 0.1143)
		(layer "In13.Cu")
		(net "P5E_CPU0_P2_TX_DN<14>")
	)
	(arc
		(start 373.896128 -277.831804)
		(mid 373.7402 -278.136096)
		(end 373.896128 -278.440388)
		(width 0.1143)
		(layer "In13.Cu")
		(net "P5E_CPU0_P2_TX_DN<14>")
	)
	(arc
		(start 373.96801 -294.682164)
		(mid 374.145968 -294.881939)
		(end 374.210326 -295.14165)
		(width 0.1143)
		(layer "In13.Cu")
		(net "P5E_CPU0_P2_TX_DN<14>")
	)
	(arc
		(start 373.896128 -287.551876)
		(mid 373.781452 -287.68521)
		(end 373.740172 -287.856168)
		(width 0.1143)
		(layer "In13.Cu")
		(net "P5E_CPU0_P2_TX_DN<14>")
	)
	(arc
		(start 373.97944 -273.63039)
		(mid 374.204611 -274.086066)
		(end 373.97944 -274.541742)
		(width 0.1143)
		(layer "In13.Cu")
		(net "P5E_CPU0_P2_TX_DN<14>")
	)
	(arc
		(start 374.43664 -295.4909)
		(mid 374.495247 -295.537771)
		(end 374.54713 -295.591992)
		(width 0.1143)
		(layer "In13.Cu")
		(net "P5E_CPU0_P2_TX_DN<14>")
	)
	(arc
		(start 373.930926 -283.32049)
		(mid 374.210541 -283.806138)
		(end 373.930926 -284.291786)
		(width 0.1143)
		(layer "In13.Cu")
		(net "P5E_CPU0_P2_TX_DN<14>")
	)
	(arc
		(start 373.930926 -284.940502)
		(mid 374.210541 -285.42615)
		(end 373.930926 -285.911798)
		(width 0.1143)
		(layer "In13.Cu")
		(net "P5E_CPU0_P2_TX_DN<14>")
	)
	(arc
		(start 373.99468 -276.881336)
		(mid 374.22268 -277.32609)
		(end 373.99468 -277.770844)
		(width 0.1143)
		(layer "In13.Cu")
		(net "P5E_CPU0_P2_TX_DN<14>")
	)
	(arc
		(start 373.930926 -289.800284)
		(mid 374.210541 -290.285932)
		(end 373.930926 -290.77158)
		(width 0.1143)
		(layer "In13.Cu")
		(net "P5E_CPU0_P2_TX_DN<14>")
	)
	(arc
		(start 373.896128 -279.451816)
		(mid 373.7402 -279.756108)
		(end 373.896128 -280.0604)
		(width 0.1143)
		(layer "In13.Cu")
		(net "P5E_CPU0_P2_TX_DN<14>")
	)
	(arc
		(start 373.978424 -276.162516)
		(mid 373.97135 -276.167523)
		(end 373.9642 -276.172422)
		(width 0.1143)
		(layer "In13.Cu")
		(net "P5E_CPU0_P2_TX_DN<14>")
	)
	(arc
		(start 374.210072 -287.05048)
		(mid 374.149073 -287.303804)
		(end 373.97944 -287.501584)
		(width 0.1143)
		(layer "In13.Cu")
		(net "P5E_CPU0_P2_TX_DN<14>")
	)
	(arc
		(start 373.99468 -278.501348)
		(mid 374.22268 -278.946102)
		(end 373.99468 -279.390856)
		(width 0.1143)
		(layer "In13.Cu")
		(net "P5E_CPU0_P2_TX_DN<14>")
	)
	(arc
		(start 428.1551 -384.58648)
		(mid 428.123937 -384.743058)
		(end 428.035212 -384.875786)
		(width 0.14224)
		(layer "In13.Cu")
		(net "P5E_CPU0_P2_TX_DN<14>")
	)
	(arc
		(start 426.105828 -375.628662)
		(mid 426.119764 -375.698633)
		(end 426.159422 -375.757948)
		(width 0.14224)
		(layer "In13.Cu")
		(net "P5E_CPU0_P2_TX_DN<14>")
	)
	(arc
		(start 373.740172 -287.856168)
		(mid 373.780934 -288.026052)
		(end 373.89435 -288.158936)
		(width 0.1143)
		(layer "In13.Cu")
		(net "P5E_CPU0_P2_TX_DN<14>")
	)
	(arc
		(start 374.54713 -295.591992)
		(mid 374.64583 -295.762092)
		(end 374.680226 -295.95572)
		(width 0.1143)
		(layer "In13.Cu")
		(net "P5E_CPU0_P2_TX_DN<14>")
	)
	(arc
		(start 373.896128 -281.071828)
		(mid 373.7402 -281.37612)
		(end 373.896128 -281.680412)
		(width 0.1143)
		(layer "In13.Cu")
		(net "P5E_CPU0_P2_TX_DN<14>")
	)
	(arc
		(start 373.97944 -274.541742)
		(mid 373.971864 -274.547138)
		(end 373.9642 -274.55241)
		(width 0.1143)
		(layer "In13.Cu")
		(net "P5E_CPU0_P2_TX_DN<14>")
	)
	(arc
		(start 373.896128 -274.59178)
		(mid 373.7402 -274.896072)
		(end 373.896128 -275.200364)
		(width 0.1143)
		(layer "In13.Cu")
		(net "P5E_CPU0_P2_TX_DN<14>")
	)
	(arc
		(start 373.896128 -294.03167)
		(mid 373.7402 -294.335962)
		(end 373.896128 -294.640254)
		(width 0.1143)
		(layer "In13.Cu")
		(net "P5E_CPU0_P2_TX_DN<14>")
	)
	(arc
		(start 373.969026 -286.582866)
		(mid 374.146222 -286.784878)
		(end 374.210072 -287.045908)
		(width 0.1143)
		(layer "In13.Cu")
		(net "P5E_CPU0_P2_TX_DN<14>")
	)
	(arc
		(start 404.874222 -366.202468)
		(mid 404.930777 -366.271389)
		(end 404.999698 -366.327944)
		(width 0.14224)
		(layer "In13.Cu")
		(net "P5E_CPU0_P2_TX_DN<14>")
	)
	(arc
		(start 373.978424 -275.24964)
		(mid 374.205807 -275.706078)
		(end 373.978424 -276.162516)
		(width 0.1143)
		(layer "In13.Cu")
		(net "P5E_CPU0_P2_TX_DN<14>")
	)
	(arc
		(start 428.035212 -377.633738)
		(mid 428.123956 -377.766458)
		(end 428.1551 -377.923044)
		(width 0.14224)
		(layer "In13.Cu")
		(net "P5E_CPU0_P2_TX_DN<14>")
	)
	(arc
		(start 423.897298 -372.928134)
		(mid 424.054001 -372.959286)
		(end 424.186858 -373.048022)
		(width 0.14224)
		(layer "In13.Cu")
		(net "P5E_CPU0_P2_TX_DN<14>")
	)
	(arc
		(start 373.896128 -282.69184)
		(mid 373.7402 -282.996132)
		(end 373.896128 -283.300424)
		(width 0.1143)
		(layer "In13.Cu")
		(net "P5E_CPU0_P2_TX_DN<14>")
	)
	(arc
		(start 373.930926 -293.040308)
		(mid 374.210541 -293.525956)
		(end 373.930926 -294.011604)
		(width 0.1143)
		(layer "In13.Cu")
		(net "P5E_CPU0_P2_TX_DN<14>")
	)
	(arc
		(start 373.896128 -285.931864)
		(mid 373.781452 -286.065198)
		(end 373.740172 -286.236156)
		(width 0.1143)
		(layer "In13.Cu")
		(net "P5E_CPU0_P2_TX_DN<14>")
	)
	(arc
		(start 373.896128 -276.211792)
		(mid 373.7402 -276.516084)
		(end 373.896128 -276.820376)
		(width 0.1143)
		(layer "In13.Cu")
		(net "P5E_CPU0_P2_TX_DN<14>")
	)
	(arc
		(start 419.820598 -372.890796)
		(mid 419.912358 -372.918684)
		(end 420.007796 -372.928134)
		(width 0.14224)
		(layer "In13.Cu")
		(net "P5E_CPU0_P2_TX_DN<14>")
	)
	(arc
		(start 373.896128 -289.171634)
		(mid 373.7402 -289.475926)
		(end 373.896128 -289.780218)
		(width 0.1143)
		(layer "In13.Cu")
		(net "P5E_CPU0_P2_TX_DN<14>")
	)
	(arc
		(start 373.9642 -280.09977)
		(mid 373.971864 -280.105041)
		(end 373.97944 -280.110438)
		(width 0.1143)
		(layer "In13.Cu")
		(net "P5E_CPU0_P2_TX_DN<14>")
	)
	(arc
		(start 373.930926 -288.180272)
		(mid 374.210541 -288.66592)
		(end 373.930926 -289.151568)
		(width 0.1143)
		(layer "In13.Cu")
		(net "P5E_CPU0_P2_TX_DN<14>")
	)
	(arc
		(start 373.740172 -286.236156)
		(mid 373.780934 -286.40604)
		(end 373.89435 -286.538924)
		(width 0.1143)
		(layer "In13.Cu")
		(net "P5E_CPU0_P2_TX_DN<14>")
	)
	(arc
		(start 374.725946 -297.147234)
		(mid 374.728496 -297.172106)
		(end 374.735852 -297.196002)
		(width 0.14224)
		(layer "In13.Cu")
		(net "P5E_CPU0_P2_TX_DN<14>")
	)
	(arc
		(start 427.982888 -384.92811)
		(mid 427.850168 -385.016854)
		(end 427.693582 -385.047998)
		(width 0.14224)
		(layer "In13.Cu")
		(net "P5E_CPU0_P2_TX_DN<14>")
	)
	(arc
		(start 373.930926 -281.700478)
		(mid 374.210541 -282.186126)
		(end 373.930926 -282.671774)
		(width 0.1143)
		(layer "In13.Cu")
		(net "P5E_CPU0_P2_TX_DN<14>")
	)
	(arc
		(start 373.74703 -273.34591)
		(mid 373.799079 -273.477429)
		(end 373.896128 -273.580352)
		(width 0.1143)
		(layer "In13.Cu")
		(net "P5E_CPU0_P2_TX_DN<14>")
	)
	(arc
		(start 373.97944 -281.02179)
		(mid 373.971864 -281.027186)
		(end 373.9642 -281.032458)
		(width 0.1143)
		(layer "In13.Cu")
		(net "P5E_CPU0_P2_TX_DN<14>")
	)
	(arc
		(start 373.896128 -290.791646)
		(mid 373.7402 -291.095938)
		(end 373.896128 -291.40023)
		(width 0.1143)
		(layer "In13.Cu")
		(net "P5E_CPU0_P2_TX_DN<14>")
	)
	(arc
		(start 373.9642 -273.619722)
		(mid 373.971864 -273.624993)
		(end 373.97944 -273.63039)
		(width 0.1143)
		(layer "In13.Cu")
		(net "P5E_CPU0_P2_TX_DN<14>")
	)
	(arc
		(start 373.9642 -275.239734)
		(mid 373.971349 -275.244634)
		(end 373.978424 -275.24964)
		(width 0.1143)
		(layer "In13.Cu")
		(net "P5E_CPU0_P2_TX_DN<14>")
	)
	(arc
		(start 373.97944 -280.110438)
		(mid 374.204611 -280.566114)
		(end 373.97944 -281.02179)
		(width 0.1143)
		(layer "In13.Cu")
		(net "P5E_CPU0_P2_TX_DN<14>")
	)
	(segment
		(start 373.64797 -269.770098)
		(end 374.114822 -270.036036)
		(width 0.12954)
		(layer "F.Cu")
		(net "P5E_CPU0_P2_TX_DN<13>")
	)
	(segment
		(start 424.76293 -378.39142)
		(end 425.05884 -378.68733)
		(width 0.12954)
		(layer "F.Cu")
		(net "P5E_CPU0_P2_TX_DN<13>")
	)
	(segment
		(start 424.76293 -377.68784)
		(end 424.76293 -378.39142)
		(width 0.12954)
		(layer "F.Cu")
		(net "P5E_CPU0_P2_TX_DN<13>")
	)
	(segment
		(start 425.03344 -377.41733)
		(end 424.76293 -377.68784)
		(width 0.12954)
		(layer "F.Cu")
		(net "P5E_CPU0_P2_TX_DN<13>")
	)
	(segment
		(start 372.98122 -285.917386)
		(end 372.980204 -285.917894)
		(width 0.1143)
		(layer "In13.Cu")
		(net "P5E_CPU0_P2_TX_DN<13>")
	)
	(segment
		(start 372.984268 -284.295596)
		(end 372.983506 -284.296104)
		(width 0.1143)
		(layer "In13.Cu")
		(net "P5E_CPU0_P2_TX_DN<13>")
	)
	(segment
		(start 373.785892 -296.61231)
		(end 373.785892 -297.403266)
		(width 0.14224)
		(layer "In13.Cu")
		(net "P5E_CPU0_P2_TX_DN<13>")
	)
	(segment
		(start 372.990364 -282.672028)
		(end 372.98884 -282.673044)
		(width 0.1143)
		(layer "In13.Cu")
		(net "P5E_CPU0_P2_TX_DN<13>")
	)
	(segment
		(start 372.956074 -293.020242)
		(end 372.987062 -293.038022)
		(width 0.1143)
		(layer "In13.Cu")
		(net "P5E_CPU0_P2_TX_DN<13>")
	)
	(segment
		(start 373.49684 -270.500602)
		(end 373.457724 -270.523462)
		(width 0.1143)
		(layer "In13.Cu")
		(net "P5E_CPU0_P2_TX_DN<13>")
	)
	(segment
		(start 372.987824 -280.078688)
		(end 372.98884 -280.079196)
		(width 0.1143)
		(layer "In13.Cu")
		(net "P5E_CPU0_P2_TX_DN<13>")
	)
	(segment
		(start 372.981982 -285.916878)
		(end 372.98122 -285.917386)
		(width 0.1143)
		(layer "In13.Cu")
		(net "P5E_CPU0_P2_TX_DN<13>")
	)
	(segment
		(start 372.987824 -291.418518)
		(end 372.98884 -291.419026)
		(width 0.1143)
		(layer "In13.Cu")
		(net "P5E_CPU0_P2_TX_DN<13>")
	)
	(segment
		(start 372.987062 -281.698192)
		(end 372.987824 -281.6987)
		(width 0.1143)
		(layer "In13.Cu")
		(net "P5E_CPU0_P2_TX_DN<13>")
	)
	(segment
		(start 372.985792 -272.95475)
		(end 372.984268 -272.955512)
		(width 0.1143)
		(layer "In13.Cu")
		(net "P5E_CPU0_P2_TX_DN<13>")
	)
	(segment
		(start 372.990364 -281.700224)
		(end 372.99138 -281.700732)
		(width 0.1143)
		(layer "In13.Cu")
		(net "P5E_CPU0_P2_TX_DN<13>")
	)
	(segment
		(start 372.990364 -278.4602)
		(end 372.99138 -278.460708)
		(width 0.1143)
		(layer "In13.Cu")
		(net "P5E_CPU0_P2_TX_DN<13>")
	)
	(segment
		(start 372.980204 -290.777676)
		(end 372.956074 -290.791646)
		(width 0.1143)
		(layer "In13.Cu")
		(net "P5E_CPU0_P2_TX_DN<13>")
	)
	(segment
		(start 372.983506 -276.196044)
		(end 372.981474 -276.19706)
		(width 0.1143)
		(layer "In13.Cu")
		(net "P5E_CPU0_P2_TX_DN<13>")
	)
	(segment
		(start 372.987824 -273.59864)
		(end 372.98884 -273.599148)
		(width 0.1143)
		(layer "In13.Cu")
		(net "P5E_CPU0_P2_TX_DN<13>")
	)
	(segment
		(start 372.99138 -275.220684)
		(end 373.02694 -275.241512)
		(width 0.1143)
		(layer "In13.Cu")
		(net "P5E_CPU0_P2_TX_DN<13>")
	)
	(segment
		(start 372.987062 -294.658034)
		(end 372.987824 -294.658542)
		(width 0.1143)
		(layer "In13.Cu")
		(net "P5E_CPU0_P2_TX_DN<13>")
	)
	(segment
		(start 372.983506 -272.95602)
		(end 372.981474 -272.957036)
		(width 0.1143)
		(layer "In13.Cu")
		(net "P5E_CPU0_P2_TX_DN<13>")
	)
	(segment
		(start 372.987062 -271.333976)
		(end 372.985792 -271.334738)
		(width 0.1143)
		(layer "In13.Cu")
		(net "P5E_CPU0_P2_TX_DN<13>")
	)
	(segment
		(start 372.987824 -294.013382)
		(end 372.987062 -294.01389)
		(width 0.1143)
		(layer "In13.Cu")
		(net "P5E_CPU0_P2_TX_DN<13>")
	)
	(segment
		(start 372.990364 -285.912052)
		(end 372.98884 -285.913068)
		(width 0.1143)
		(layer "In13.Cu")
		(net "P5E_CPU0_P2_TX_DN<13>")
	)
	(segment
		(start 373.02694 -284.270704)
		(end 372.990364 -284.29204)
		(width 0.1143)
		(layer "In13.Cu")
		(net "P5E_CPU0_P2_TX_DN<13>")
	)
	(segment
		(start 372.987062 -289.797998)
		(end 372.987824 -289.798506)
		(width 0.1143)
		(layer "In13.Cu")
		(net "P5E_CPU0_P2_TX_DN<13>")
	)
	(segment
		(start 372.981474 -279.437084)
		(end 372.956074 -279.451816)
		(width 0.1143)
		(layer "In13.Cu")
		(net "P5E_CPU0_P2_TX_DN<13>")
	)
	(segment
		(start 372.987062 -277.814024)
		(end 372.985792 -277.814786)
		(width 0.1143)
		(layer "In13.Cu")
		(net "P5E_CPU0_P2_TX_DN<13>")
	)
	(segment
		(start 372.954296 -288.158936)
		(end 372.987824 -288.178494)
		(width 0.1143)
		(layer "In13.Cu")
		(net "P5E_CPU0_P2_TX_DN<13>")
	)
	(segment
		(start 372.985792 -285.914846)
		(end 372.984268 -285.915608)
		(width 0.1143)
		(layer "In13.Cu")
		(net "P5E_CPU0_P2_TX_DN<13>")
	)
	(segment
		(start 372.987824 -287.533588)
		(end 372.956074 -287.551876)
		(width 0.1143)
		(layer "In13.Cu")
		(net "P5E_CPU0_P2_TX_DN<13>")
	)
	(segment
		(start 372.98122 -282.677362)
		(end 372.980204 -282.67787)
		(width 0.1143)
		(layer "In13.Cu")
		(net "P5E_CPU0_P2_TX_DN<13>")
	)
	(segment
		(start 372.98884 -280.079196)
		(end 373.02694 -280.101548)
		(width 0.1143)
		(layer "In13.Cu")
		(net "P5E_CPU0_P2_TX_DN<13>")
	)
	(segment
		(start 372.981982 -290.77666)
		(end 372.98122 -290.777168)
		(width 0.1143)
		(layer "In13.Cu")
		(net "P5E_CPU0_P2_TX_DN<13>")
	)
	(segment
		(start 372.98884 -294.012874)
		(end 372.987824 -294.013382)
		(width 0.1143)
		(layer "In13.Cu")
		(net "P5E_CPU0_P2_TX_DN<13>")
	)
	(segment
		(start 372.983506 -279.436068)
		(end 372.981474 -279.437084)
		(width 0.1143)
		(layer "In13.Cu")
		(net "P5E_CPU0_P2_TX_DN<13>")
	)
	(segment
		(start 372.987824 -272.95348)
		(end 372.987062 -272.953988)
		(width 0.1143)
		(layer "In13.Cu")
		(net "P5E_CPU0_P2_TX_DN<13>")
	)
	(segment
		(start 372.985792 -276.194774)
		(end 372.984268 -276.195536)
		(width 0.1143)
		(layer "In13.Cu")
		(net "P5E_CPU0_P2_TX_DN<13>")
	)
	(segment
		(start 372.983506 -271.336008)
		(end 372.981474 -271.337024)
		(width 0.1143)
		(layer "In13.Cu")
		(net "P5E_CPU0_P2_TX_DN<13>")
	)
	(segment
		(start 372.983506 -292.39591)
		(end 372.981982 -292.396672)
		(width 0.1143)
		(layer "In13.Cu")
		(net "P5E_CPU0_P2_TX_DN<13>")
	)
	(segment
		(start 372.980204 -289.157664)
		(end 372.956074 -289.171634)
		(width 0.1143)
		(layer "In13.Cu")
		(net "P5E_CPU0_P2_TX_DN<13>")
	)
	(segment
		(start 424.74261 -377.1265)
		(end 425.03344 -377.41733)
		(width 0.14224)
		(layer "In13.Cu")
		(net "P5E_CPU0_P2_TX_DN<13>")
	)
	(segment
		(start 373.785892 -296.583862)
		(end 373.785892 -296.61231)
		(width 0.1143)
		(layer "In13.Cu")
		(net "P5E_CPU0_P2_TX_DN<13>")
	)
	(segment
		(start 373.02694 -293.990522)
		(end 372.98884 -294.012874)
		(width 0.1143)
		(layer "In13.Cu")
		(net "P5E_CPU0_P2_TX_DN<13>")
	)
	(segment
		(start 372.98884 -289.799014)
		(end 372.990364 -289.80003)
		(width 0.1143)
		(layer "In13.Cu")
		(net "P5E_CPU0_P2_TX_DN<13>")
	)
	(segment
		(start 372.98884 -282.673044)
		(end 372.987824 -282.673552)
		(width 0.1143)
		(layer "In13.Cu")
		(net "P5E_CPU0_P2_TX_DN<13>")
	)
	(segment
		(start 372.99138 -281.700732)
		(end 373.02694 -281.72156)
		(width 0.1143)
		(layer "In13.Cu")
		(net "P5E_CPU0_P2_TX_DN<13>")
	)
	(segment
		(start 372.956074 -275.200364)
		(end 372.987062 -275.218144)
		(width 0.1143)
		(layer "In13.Cu")
		(net "P5E_CPU0_P2_TX_DN<13>")
	)
	(segment
		(start 406.237186 -368.285776)
		(end 419.583616 -373.814594)
		(width 0.14224)
		(layer "In13.Cu")
		(net "P5E_CPU0_P2_TX_DN<13>")
	)
	(segment
		(start 372.987824 -294.658542)
		(end 372.98884 -294.65905)
		(width 0.1143)
		(layer "In13.Cu")
		(net "P5E_CPU0_P2_TX_DN<13>")
	)
	(segment
		(start 372.987824 -284.293564)
		(end 372.987062 -284.294072)
		(width 0.1143)
		(layer "In13.Cu")
		(net "P5E_CPU0_P2_TX_DN<13>")
	)
	(segment
		(start 372.98884 -278.459184)
		(end 372.990364 -278.4602)
		(width 0.1143)
		(layer "In13.Cu")
		(net "P5E_CPU0_P2_TX_DN<13>")
	)
	(segment
		(start 372.985792 -284.294834)
		(end 372.984268 -284.295596)
		(width 0.1143)
		(layer "In13.Cu")
		(net "P5E_CPU0_P2_TX_DN<13>")
	)
	(segment
		(start 372.987824 -282.673552)
		(end 372.987062 -282.67406)
		(width 0.1143)
		(layer "In13.Cu")
		(net "P5E_CPU0_P2_TX_DN<13>")
	)
	(segment
		(start 373.81688 -270.036036)
		(end 373.734076 -270.11884)
		(width 0.1143)
		(layer "In13.Cu")
		(net "P5E_CPU0_P2_TX_DN<13>")
	)
	(segment
		(start 372.956074 -273.580352)
		(end 372.987062 -273.598132)
		(width 0.1143)
		(layer "In13.Cu")
		(net "P5E_CPU0_P2_TX_DN<13>")
	)
	(segment
		(start 373.02694 -289.130486)
		(end 372.990364 -289.151822)
		(width 0.1143)
		(layer "In13.Cu")
		(net "P5E_CPU0_P2_TX_DN<13>")
	)
	(segment
		(start 372.990364 -293.040054)
		(end 372.99138 -293.040562)
		(width 0.1143)
		(layer "In13.Cu")
		(net "P5E_CPU0_P2_TX_DN<13>")
	)
	(segment
		(start 372.99138 -278.460708)
		(end 373.02694 -278.481536)
		(width 0.1143)
		(layer "In13.Cu")
		(net "P5E_CPU0_P2_TX_DN<13>")
	)
	(segment
		(start 373.02694 -282.650692)
		(end 372.990364 -282.672028)
		(width 0.1143)
		(layer "In13.Cu")
		(net "P5E_CPU0_P2_TX_DN<13>")
	)
	(segment
		(start 372.987824 -278.458676)
		(end 372.98884 -278.459184)
		(width 0.1143)
		(layer "In13.Cu")
		(net "P5E_CPU0_P2_TX_DN<13>")
	)
	(segment
		(start 372.987824 -281.05354)
		(end 372.956074 -281.071828)
		(width 0.1143)
		(layer "In13.Cu")
		(net "P5E_CPU0_P2_TX_DN<13>")
	)
	(segment
		(start 372.984268 -272.955512)
		(end 372.983506 -272.95602)
		(width 0.1143)
		(layer "In13.Cu")
		(net "P5E_CPU0_P2_TX_DN<13>")
	)
	(segment
		(start 372.987824 -276.838664)
		(end 372.98884 -276.839172)
		(width 0.1143)
		(layer "In13.Cu")
		(net "P5E_CPU0_P2_TX_DN<13>")
	)
	(segment
		(start 372.987824 -271.333468)
		(end 372.987062 -271.333976)
		(width 0.1143)
		(layer "In13.Cu")
		(net "P5E_CPU0_P2_TX_DN<13>")
	)
	(segment
		(start 372.990364 -284.940248)
		(end 373.02694 -284.961584)
		(width 0.1143)
		(layer "In13.Cu")
		(net "P5E_CPU0_P2_TX_DN<13>")
	)
	(segment
		(start 372.98884 -285.913068)
		(end 372.987824 -285.913576)
		(width 0.1143)
		(layer "In13.Cu")
		(net "P5E_CPU0_P2_TX_DN<13>")
	)
	(segment
		(start 372.987062 -285.914084)
		(end 372.985792 -285.914846)
		(width 0.1143)
		(layer "In13.Cu")
		(net "P5E_CPU0_P2_TX_DN<13>")
	)
	(segment
		(start 372.985792 -294.014652)
		(end 372.956074 -294.03167)
		(width 0.1143)
		(layer "In13.Cu")
		(net "P5E_CPU0_P2_TX_DN<13>")
	)
	(segment
		(start 372.99138 -273.600672)
		(end 373.02694 -273.6215)
		(width 0.1143)
		(layer "In13.Cu")
		(net "P5E_CPU0_P2_TX_DN<13>")
	)
	(segment
		(start 372.98884 -283.31922)
		(end 372.990364 -283.320236)
		(width 0.1143)
		(layer "In13.Cu")
		(net "P5E_CPU0_P2_TX_DN<13>")
	)
	(segment
		(start 372.987824 -284.938724)
		(end 372.98884 -284.939232)
		(width 0.1143)
		(layer "In13.Cu")
		(net "P5E_CPU0_P2_TX_DN<13>")
	)
	(segment
		(start 372.984268 -279.43556)
		(end 372.983506 -279.436068)
		(width 0.1143)
		(layer "In13.Cu")
		(net "P5E_CPU0_P2_TX_DN<13>")
	)
	(segment
		(start 372.987824 -289.798506)
		(end 372.98884 -289.799014)
		(width 0.1143)
		(layer "In13.Cu")
		(net "P5E_CPU0_P2_TX_DN<13>")
	)
	(segment
		(start 372.956074 -276.820376)
		(end 372.987062 -276.838156)
		(width 0.1143)
		(layer "In13.Cu")
		(net "P5E_CPU0_P2_TX_DN<13>")
	)
	(segment
		(start 372.987824 -271.978628)
		(end 372.98884 -271.979136)
		(width 0.1143)
		(layer "In13.Cu")
		(net "P5E_CPU0_P2_TX_DN<13>")
	)
	(segment
		(start 372.990364 -284.29204)
		(end 372.98884 -284.293056)
		(width 0.1143)
		(layer "In13.Cu")
		(net "P5E_CPU0_P2_TX_DN<13>")
	)
	(segment
		(start 373.02694 -272.93062)
		(end 372.987824 -272.95348)
		(width 0.1143)
		(layer "In13.Cu")
		(net "P5E_CPU0_P2_TX_DN<13>")
	)
	(segment
		(start 373.02694 -279.410668)
		(end 372.987824 -279.433528)
		(width 0.1143)
		(layer "In13.Cu")
		(net "P5E_CPU0_P2_TX_DN<13>")
	)
	(segment
		(start 373.02694 -271.310608)
		(end 372.987824 -271.333468)
		(width 0.1143)
		(layer "In13.Cu")
		(net "P5E_CPU0_P2_TX_DN<13>")
	)
	(segment
		(start 372.954296 -286.538924)
		(end 372.987824 -286.558482)
		(width 0.1143)
		(layer "In13.Cu")
		(net "P5E_CPU0_P2_TX_DN<13>")
	)
	(segment
		(start 404.23592 -366.948466)
		(end 406.237186 -368.285776)
		(width 0.14224)
		(layer "In13.Cu")
		(net "P5E_CPU0_P2_TX_DN<13>")
	)
	(segment
		(start 372.98884 -284.293056)
		(end 372.987824 -284.293564)
		(width 0.1143)
		(layer "In13.Cu")
		(net "P5E_CPU0_P2_TX_DN<13>")
	)
	(segment
		(start 372.985792 -277.814786)
		(end 372.984268 -277.815548)
		(width 0.1143)
		(layer "In13.Cu")
		(net "P5E_CPU0_P2_TX_DN<13>")
	)
	(segment
		(start 372.956074 -280.0604)
		(end 372.987062 -280.07818)
		(width 0.1143)
		(layer "In13.Cu")
		(net "P5E_CPU0_P2_TX_DN<13>")
	)
	(segment
		(start 372.985792 -274.574762)
		(end 372.984268 -274.575524)
		(width 0.1143)
		(layer "In13.Cu")
		(net "P5E_CPU0_P2_TX_DN<13>")
	)
	(segment
		(start 372.984268 -289.155378)
		(end 372.983506 -289.155886)
		(width 0.1143)
		(layer "In13.Cu")
		(net "P5E_CPU0_P2_TX_DN<13>")
	)
	(segment
		(start 372.984268 -282.675584)
		(end 372.983506 -282.676092)
		(width 0.1143)
		(layer "In13.Cu")
		(net "P5E_CPU0_P2_TX_DN<13>")
	)
	(segment
		(start 372.980204 -292.397688)
		(end 372.956074 -292.411658)
		(width 0.1143)
		(layer "In13.Cu")
		(net "P5E_CPU0_P2_TX_DN<13>")
	)
	(segment
		(start 372.98884 -290.77285)
		(end 372.987824 -290.773358)
		(width 0.1143)
		(layer "In13.Cu")
		(net "P5E_CPU0_P2_TX_DN<13>")
	)
	(segment
		(start 372.985792 -279.434798)
		(end 372.984268 -279.43556)
		(width 0.1143)
		(layer "In13.Cu")
		(net "P5E_CPU0_P2_TX_DN<13>")
	)
	(segment
		(start 372.981474 -276.19706)
		(end 372.956074 -276.211792)
		(width 0.1143)
		(layer "In13.Cu")
		(net "P5E_CPU0_P2_TX_DN<13>")
	)
	(segment
		(start 372.98122 -292.39718)
		(end 372.980204 -292.397688)
		(width 0.1143)
		(layer "In13.Cu")
		(net "P5E_CPU0_P2_TX_DN<13>")
	)
	(segment
		(start 372.987062 -279.434036)
		(end 372.985792 -279.434798)
		(width 0.1143)
		(layer "In13.Cu")
		(net "P5E_CPU0_P2_TX_DN<13>")
	)
	(segment
		(start 372.984268 -271.3355)
		(end 372.983506 -271.336008)
		(width 0.1143)
		(layer "In13.Cu")
		(net "P5E_CPU0_P2_TX_DN<13>")
	)
	(segment
		(start 372.981474 -277.817072)
		(end 372.956074 -277.831804)
		(width 0.1143)
		(layer "In13.Cu")
		(net "P5E_CPU0_P2_TX_DN<13>")
	)
	(segment
		(start 372.983506 -282.676092)
		(end 372.981982 -282.676854)
		(width 0.1143)
		(layer "In13.Cu")
		(net "P5E_CPU0_P2_TX_DN<13>")
	)
	(segment
		(start 372.98884 -292.392862)
		(end 372.987824 -292.39337)
		(width 0.1143)
		(layer "In13.Cu")
		(net "P5E_CPU0_P2_TX_DN<13>")
	)
	(segment
		(start 372.956074 -294.640254)
		(end 372.987062 -294.658034)
		(width 0.1143)
		(layer "In13.Cu")
		(net "P5E_CPU0_P2_TX_DN<13>")
	)
	(segment
		(start 373.02694 -276.170644)
		(end 372.987824 -276.193504)
		(width 0.1143)
		(layer "In13.Cu")
		(net "P5E_CPU0_P2_TX_DN<13>")
	)
	(segment
		(start 372.981474 -272.957036)
		(end 372.956074 -272.971768)
		(width 0.1143)
		(layer "In13.Cu")
		(net "P5E_CPU0_P2_TX_DN<13>")
	)
	(segment
		(start 372.987062 -276.838156)
		(end 372.987824 -276.838664)
		(width 0.1143)
		(layer "In13.Cu")
		(net "P5E_CPU0_P2_TX_DN<13>")
	)
	(segment
		(start 372.985792 -282.674822)
		(end 372.984268 -282.675584)
		(width 0.1143)
		(layer "In13.Cu")
		(net "P5E_CPU0_P2_TX_DN<13>")
	)
	(segment
		(start 372.987062 -284.294072)
		(end 372.985792 -284.294834)
		(width 0.1143)
		(layer "In13.Cu")
		(net "P5E_CPU0_P2_TX_DN<13>")
	)
	(segment
		(start 373.427244 -295.450768)
		(end 373.49684 -295.491408)
		(width 0.1143)
		(layer "In13.Cu")
		(net "P5E_CPU0_P2_TX_DN<13>")
	)
	(segment
		(start 372.987824 -277.813516)
		(end 372.987062 -277.814024)
		(width 0.1143)
		(layer "In13.Cu")
		(net "P5E_CPU0_P2_TX_DN<13>")
	)
	(segment
		(start 373.02694 -281.03068)
		(end 372.987824 -281.05354)
		(width 0.1143)
		(layer "In13.Cu")
		(net "P5E_CPU0_P2_TX_DN<13>")
	)
	(segment
		(start 372.990364 -273.600164)
		(end 372.99138 -273.600672)
		(width 0.1143)
		(layer "In13.Cu")
		(net "P5E_CPU0_P2_TX_DN<13>")
	)
	(segment
		(start 372.990364 -271.980152)
		(end 372.99138 -271.98066)
		(width 0.1143)
		(layer "In13.Cu")
		(net "P5E_CPU0_P2_TX_DN<13>")
	)
	(segment
		(start 372.984268 -290.77539)
		(end 372.983506 -290.775898)
		(width 0.1143)
		(layer "In13.Cu")
		(net "P5E_CPU0_P2_TX_DN<13>")
	)
	(segment
		(start 372.981982 -289.156648)
		(end 372.98122 -289.157156)
		(width 0.1143)
		(layer "In13.Cu")
		(net "P5E_CPU0_P2_TX_DN<13>")
	)
	(segment
		(start 372.990364 -289.151822)
		(end 372.98884 -289.152838)
		(width 0.1143)
		(layer "In13.Cu")
		(net "P5E_CPU0_P2_TX_DN<13>")
	)
	(segment
		(start 372.987824 -275.218652)
		(end 372.98884 -275.21916)
		(width 0.1143)
		(layer "In13.Cu")
		(net "P5E_CPU0_P2_TX_DN<13>")
	)
	(segment
		(start 373.02694 -290.750498)
		(end 372.990364 -290.771834)
		(width 0.1143)
		(layer "In13.Cu")
		(net "P5E_CPU0_P2_TX_DN<13>")
	)
	(segment
		(start 372.956074 -289.780218)
		(end 372.987062 -289.797998)
		(width 0.1143)
		(layer "In13.Cu")
		(net "P5E_CPU0_P2_TX_DN<13>")
	)
	(segment
		(start 419.946328 -373.88673)
		(end 422.6433 -373.88673)
		(width 0.14224)
		(layer "In13.Cu")
		(net "P5E_CPU0_P2_TX_DN<13>")
	)
	(segment
		(start 372.98884 -291.419026)
		(end 372.990364 -291.420042)
		(width 0.1143)
		(layer "In13.Cu")
		(net "P5E_CPU0_P2_TX_DN<13>")
	)
	(segment
		(start 372.987062 -292.393878)
		(end 372.985792 -292.39464)
		(width 0.1143)
		(layer "In13.Cu")
		(net "P5E_CPU0_P2_TX_DN<13>")
	)
	(segment
		(start 372.984268 -274.575524)
		(end 372.983506 -274.576032)
		(width 0.1143)
		(layer "In13.Cu")
		(net "P5E_CPU0_P2_TX_DN<13>")
	)
	(segment
		(start 372.987062 -280.07818)
		(end 372.987824 -280.078688)
		(width 0.1143)
		(layer "In13.Cu")
		(net "P5E_CPU0_P2_TX_DN<13>")
	)
	(segment
		(start 372.983506 -290.775898)
		(end 372.981982 -290.77666)
		(width 0.1143)
		(layer "In13.Cu")
		(net "P5E_CPU0_P2_TX_DN<13>")
	)
	(segment
		(start 373.457724 -270.523462)
		(end 373.427244 -270.541242)
		(width 0.1143)
		(layer "In13.Cu")
		(net "P5E_CPU0_P2_TX_DN<13>")
	)
	(segment
		(start 372.99138 -293.040562)
		(end 373.02694 -293.06139)
		(width 0.1143)
		(layer "In13.Cu")
		(net "P5E_CPU0_P2_TX_DN<13>")
	)
	(segment
		(start 374.114822 -270.036036)
		(end 373.81688 -270.036036)
		(width 0.1143)
		(layer "In13.Cu")
		(net "P5E_CPU0_P2_TX_DN<13>")
	)
	(segment
		(start 372.987062 -290.773866)
		(end 372.985792 -290.774628)
		(width 0.1143)
		(layer "In13.Cu")
		(net "P5E_CPU0_P2_TX_DN<13>")
	)
	(segment
		(start 372.987062 -275.218144)
		(end 372.987824 -275.218652)
		(width 0.1143)
		(layer "In13.Cu")
		(net "P5E_CPU0_P2_TX_DN<13>")
	)
	(segment
		(start 372.956074 -291.40023)
		(end 372.987824 -291.418518)
		(width 0.1143)
		(layer "In13.Cu")
		(net "P5E_CPU0_P2_TX_DN<13>")
	)
	(segment
		(start 372.987062 -274.574)
		(end 372.985792 -274.574762)
		(width 0.1143)
		(layer "In13.Cu")
		(net "P5E_CPU0_P2_TX_DN<13>")
	)
	(segment
		(start 372.983506 -277.816056)
		(end 372.981474 -277.817072)
		(width 0.1143)
		(layer "In13.Cu")
		(net "P5E_CPU0_P2_TX_DN<13>")
	)
	(segment
		(start 373.02694 -274.550632)
		(end 372.987824 -274.573492)
		(width 0.1143)
		(layer "In13.Cu")
		(net "P5E_CPU0_P2_TX_DN<13>")
	)
	(segment
		(start 373.02694 -292.37051)
		(end 372.990364 -292.391846)
		(width 0.1143)
		(layer "In13.Cu")
		(net "P5E_CPU0_P2_TX_DN<13>")
	)
	(segment
		(start 372.984268 -285.915608)
		(end 372.983506 -285.916116)
		(width 0.1143)
		(layer "In13.Cu")
		(net "P5E_CPU0_P2_TX_DN<13>")
	)
	(segment
		(start 372.987824 -276.193504)
		(end 372.987062 -276.194012)
		(width 0.1143)
		(layer "In13.Cu")
		(net "P5E_CPU0_P2_TX_DN<13>")
	)
	(segment
		(start 372.99138 -294.660574)
		(end 373.02694 -294.681402)
		(width 0.1143)
		(layer "In13.Cu")
		(net "P5E_CPU0_P2_TX_DN<13>")
	)
	(segment
		(start 372.985792 -289.154616)
		(end 372.984268 -289.155378)
		(width 0.1143)
		(layer "In13.Cu")
		(net "P5E_CPU0_P2_TX_DN<13>")
	)
	(segment
		(start 372.987824 -274.573492)
		(end 372.987062 -274.574)
		(width 0.1143)
		(layer "In13.Cu")
		(net "P5E_CPU0_P2_TX_DN<13>")
	)
	(segment
		(start 372.956074 -281.680412)
		(end 372.987062 -281.698192)
		(width 0.1143)
		(layer "In13.Cu")
		(net "P5E_CPU0_P2_TX_DN<13>")
	)
	(segment
		(start 372.980204 -284.297882)
		(end 372.956074 -284.311852)
		(width 0.1143)
		(layer "In13.Cu")
		(net "P5E_CPU0_P2_TX_DN<13>")
	)
	(segment
		(start 373.02694 -277.790656)
		(end 372.987824 -277.813516)
		(width 0.1143)
		(layer "In13.Cu")
		(net "P5E_CPU0_P2_TX_DN<13>")
	)
	(segment
		(start 372.987062 -289.153854)
		(end 372.985792 -289.154616)
		(width 0.1143)
		(layer "In13.Cu")
		(net "P5E_CPU0_P2_TX_DN<13>")
	)
	(segment
		(start 372.98884 -289.152838)
		(end 372.987824 -289.153346)
		(width 0.1143)
		(layer "In13.Cu")
		(net "P5E_CPU0_P2_TX_DN<13>")
	)
	(segment
		(start 372.98884 -294.65905)
		(end 372.990364 -294.660066)
		(width 0.1143)
		(layer "In13.Cu")
		(net "P5E_CPU0_P2_TX_DN<13>")
	)
	(segment
		(start 372.987062 -293.038022)
		(end 372.987824 -293.03853)
		(width 0.1143)
		(layer "In13.Cu")
		(net "P5E_CPU0_P2_TX_DN<13>")
	)
	(segment
		(start 372.98122 -289.157156)
		(end 372.980204 -289.157664)
		(width 0.1143)
		(layer "In13.Cu")
		(net "P5E_CPU0_P2_TX_DN<13>")
	)
	(segment
		(start 372.985792 -271.334738)
		(end 372.984268 -271.3355)
		(width 0.1143)
		(layer "In13.Cu")
		(net "P5E_CPU0_P2_TX_DN<13>")
	)
	(segment
		(start 372.99138 -276.840696)
		(end 373.02694 -276.861524)
		(width 0.1143)
		(layer "In13.Cu")
		(net "P5E_CPU0_P2_TX_DN<13>")
	)
	(segment
		(start 372.990364 -294.660066)
		(end 372.99138 -294.660574)
		(width 0.1143)
		(layer "In13.Cu")
		(net "P5E_CPU0_P2_TX_DN<13>")
	)
	(segment
		(start 372.983506 -289.155886)
		(end 372.981982 -289.156648)
		(width 0.1143)
		(layer "In13.Cu")
		(net "P5E_CPU0_P2_TX_DN<13>")
	)
	(segment
		(start 373.740172 -295.95572)
		(end 373.740172 -296.538142)
		(width 0.1143)
		(layer "In13.Cu")
		(net "P5E_CPU0_P2_TX_DN<13>")
	)
	(segment
		(start 399.93316 -360.527092)
		(end 404.200868 -366.913414)
		(width 0.14224)
		(layer "In13.Cu")
		(net "P5E_CPU0_P2_TX_DN<13>")
	)
	(segment
		(start 372.956074 -278.440388)
		(end 372.987062 -278.458168)
		(width 0.1143)
		(layer "In13.Cu")
		(net "P5E_CPU0_P2_TX_DN<13>")
	)
	(segment
		(start 372.987824 -292.39337)
		(end 372.987062 -292.393878)
		(width 0.1143)
		(layer "In13.Cu")
		(net "P5E_CPU0_P2_TX_DN<13>")
	)
	(segment
		(start 372.956074 -271.96034)
		(end 372.987062 -271.97812)
		(width 0.1143)
		(layer "In13.Cu")
		(net "P5E_CPU0_P2_TX_DN<13>")
	)
	(segment
		(start 372.987062 -278.458168)
		(end 372.987824 -278.458676)
		(width 0.1143)
		(layer "In13.Cu")
		(net "P5E_CPU0_P2_TX_DN<13>")
	)
	(segment
		(start 372.99138 -289.800538)
		(end 373.02694 -289.821366)
		(width 0.1143)
		(layer "In13.Cu")
		(net "P5E_CPU0_P2_TX_DN<13>")
	)
	(segment
		(start 372.987824 -293.03853)
		(end 372.98884 -293.039038)
		(width 0.1143)
		(layer "In13.Cu")
		(net "P5E_CPU0_P2_TX_DN<13>")
	)
	(segment
		(start 372.981474 -271.337024)
		(end 372.956074 -271.351756)
		(width 0.1143)
		(layer "In13.Cu")
		(net "P5E_CPU0_P2_TX_DN<13>")
	)
	(segment
		(start 372.983506 -285.916116)
		(end 372.981982 -285.916878)
		(width 0.1143)
		(layer "In13.Cu")
		(net "P5E_CPU0_P2_TX_DN<13>")
	)
	(segment
		(start 372.987062 -276.194012)
		(end 372.985792 -276.194774)
		(width 0.1143)
		(layer "In13.Cu")
		(net "P5E_CPU0_P2_TX_DN<13>")
	)
	(segment
		(start 372.980204 -285.917894)
		(end 372.956074 -285.931864)
		(width 0.1143)
		(layer "In13.Cu")
		(net "P5E_CPU0_P2_TX_DN<13>")
	)
	(segment
		(start 372.987062 -271.97812)
		(end 372.987824 -271.978628)
		(width 0.1143)
		(layer "In13.Cu")
		(net "P5E_CPU0_P2_TX_DN<13>")
	)
	(segment
		(start 372.99138 -271.98066)
		(end 373.02694 -272.001488)
		(width 0.1143)
		(layer "In13.Cu")
		(net "P5E_CPU0_P2_TX_DN<13>")
	)
	(segment
		(start 372.984268 -292.395402)
		(end 372.983506 -292.39591)
		(width 0.1143)
		(layer "In13.Cu")
		(net "P5E_CPU0_P2_TX_DN<13>")
	)
	(segment
		(start 372.987824 -288.178494)
		(end 373.02694 -288.201354)
		(width 0.1143)
		(layer "In13.Cu")
		(net "P5E_CPU0_P2_TX_DN<13>")
	)
	(segment
		(start 372.98884 -271.979136)
		(end 372.990364 -271.980152)
		(width 0.1143)
		(layer "In13.Cu")
		(net "P5E_CPU0_P2_TX_DN<13>")
	)
	(segment
		(start 373.795798 -297.452034)
		(end 399.93316 -360.527092)
		(width 0.14224)
		(layer "In13.Cu")
		(net "P5E_CPU0_P2_TX_DN<13>")
	)
	(segment
		(start 372.990364 -290.771834)
		(end 372.98884 -290.77285)
		(width 0.1143)
		(layer "In13.Cu")
		(net "P5E_CPU0_P2_TX_DN<13>")
	)
	(segment
		(start 372.981474 -274.577048)
		(end 372.956074 -274.59178)
		(width 0.1143)
		(layer "In13.Cu")
		(net "P5E_CPU0_P2_TX_DN<13>")
	)
	(segment
		(start 373.02694 -285.890716)
		(end 372.990364 -285.912052)
		(width 0.1143)
		(layer "In13.Cu")
		(net "P5E_CPU0_P2_TX_DN<13>")
	)
	(segment
		(start 423.03573 -374.04929)
		(end 424.622722 -375.636282)
		(width 0.14224)
		(layer "In13.Cu")
		(net "P5E_CPU0_P2_TX_DN<13>")
	)
	(segment
		(start 372.990364 -291.420042)
		(end 373.02694 -291.441378)
		(width 0.1143)
		(layer "In13.Cu")
		(net "P5E_CPU0_P2_TX_DN<13>")
	)
	(segment
		(start 372.987824 -289.153346)
		(end 372.987062 -289.153854)
		(width 0.1143)
		(layer "In13.Cu")
		(net "P5E_CPU0_P2_TX_DN<13>")
	)
	(segment
		(start 372.990364 -289.80003)
		(end 372.99138 -289.800538)
		(width 0.1143)
		(layer "In13.Cu")
		(net "P5E_CPU0_P2_TX_DN<13>")
	)
	(segment
		(start 372.987062 -294.01389)
		(end 372.985792 -294.014652)
		(width 0.1143)
		(layer "In13.Cu")
		(net "P5E_CPU0_P2_TX_DN<13>")
	)
	(segment
		(start 372.987824 -286.558482)
		(end 373.02694 -286.581342)
		(width 0.1143)
		(layer "In13.Cu")
		(net "P5E_CPU0_P2_TX_DN<13>")
	)
	(segment
		(start 372.983506 -284.296104)
		(end 372.981982 -284.296866)
		(width 0.1143)
		(layer "In13.Cu")
		(net "P5E_CPU0_P2_TX_DN<13>")
	)
	(segment
		(start 372.956074 -284.920436)
		(end 372.987824 -284.938724)
		(width 0.1143)
		(layer "In13.Cu")
		(net "P5E_CPU0_P2_TX_DN<13>")
	)
	(segment
		(start 372.98122 -290.777168)
		(end 372.980204 -290.777676)
		(width 0.1143)
		(layer "In13.Cu")
		(net "P5E_CPU0_P2_TX_DN<13>")
	)
	(segment
		(start 372.990364 -275.220176)
		(end 372.99138 -275.220684)
		(width 0.1143)
		(layer "In13.Cu")
		(net "P5E_CPU0_P2_TX_DN<13>")
	)
	(segment
		(start 372.98884 -276.839172)
		(end 372.990364 -276.840188)
		(width 0.1143)
		(layer "In13.Cu")
		(net "P5E_CPU0_P2_TX_DN<13>")
	)
	(segment
		(start 372.981982 -284.296866)
		(end 372.98122 -284.297374)
		(width 0.1143)
		(layer "In13.Cu")
		(net "P5E_CPU0_P2_TX_DN<13>")
	)
	(segment
		(start 372.981982 -292.396672)
		(end 372.98122 -292.39718)
		(width 0.1143)
		(layer "In13.Cu")
		(net "P5E_CPU0_P2_TX_DN<13>")
	)
	(segment
		(start 372.987062 -282.67406)
		(end 372.985792 -282.674822)
		(width 0.1143)
		(layer "In13.Cu")
		(net "P5E_CPU0_P2_TX_DN<13>")
	)
	(segment
		(start 372.987824 -279.433528)
		(end 372.987062 -279.434036)
		(width 0.1143)
		(layer "In13.Cu")
		(net "P5E_CPU0_P2_TX_DN<13>")
	)
	(segment
		(start 372.987824 -290.773358)
		(end 372.987062 -290.773866)
		(width 0.1143)
		(layer "In13.Cu")
		(net "P5E_CPU0_P2_TX_DN<13>")
	)
	(segment
		(start 372.987062 -273.598132)
		(end 372.987824 -273.59864)
		(width 0.1143)
		(layer "In13.Cu")
		(net "P5E_CPU0_P2_TX_DN<13>")
	)
	(segment
		(start 372.985792 -292.39464)
		(end 372.984268 -292.395402)
		(width 0.1143)
		(layer "In13.Cu")
		(net "P5E_CPU0_P2_TX_DN<13>")
	)
	(segment
		(start 372.987824 -281.6987)
		(end 372.98884 -281.699208)
		(width 0.1143)
		(layer "In13.Cu")
		(net "P5E_CPU0_P2_TX_DN<13>")
	)
	(segment
		(start 372.987062 -272.953988)
		(end 372.985792 -272.95475)
		(width 0.1143)
		(layer "In13.Cu")
		(net "P5E_CPU0_P2_TX_DN<13>")
	)
	(segment
		(start 372.98122 -284.297374)
		(end 372.980204 -284.297882)
		(width 0.1143)
		(layer "In13.Cu")
		(net "P5E_CPU0_P2_TX_DN<13>")
	)
	(segment
		(start 372.990364 -283.320236)
		(end 373.02694 -283.341572)
		(width 0.1143)
		(layer "In13.Cu")
		(net "P5E_CPU0_P2_TX_DN<13>")
	)
	(segment
		(start 372.98884 -273.599148)
		(end 372.990364 -273.600164)
		(width 0.1143)
		(layer "In13.Cu")
		(net "P5E_CPU0_P2_TX_DN<13>")
	)
	(segment
		(start 372.98884 -284.939232)
		(end 372.990364 -284.940248)
		(width 0.1143)
		(layer "In13.Cu")
		(net "P5E_CPU0_P2_TX_DN<13>")
	)
	(segment
		(start 372.987824 -285.913576)
		(end 372.987062 -285.914084)
		(width 0.1143)
		(layer "In13.Cu")
		(net "P5E_CPU0_P2_TX_DN<13>")
	)
	(segment
		(start 372.98884 -275.21916)
		(end 372.990364 -275.220176)
		(width 0.1143)
		(layer "In13.Cu")
		(net "P5E_CPU0_P2_TX_DN<13>")
	)
	(segment
		(start 372.985792 -290.774628)
		(end 372.984268 -290.77539)
		(width 0.1143)
		(layer "In13.Cu")
		(net "P5E_CPU0_P2_TX_DN<13>")
	)
	(segment
		(start 372.98884 -281.699208)
		(end 372.990364 -281.700224)
		(width 0.1143)
		(layer "In13.Cu")
		(net "P5E_CPU0_P2_TX_DN<13>")
	)
	(segment
		(start 372.956074 -283.300424)
		(end 372.987824 -283.318712)
		(width 0.1143)
		(layer "In13.Cu")
		(net "P5E_CPU0_P2_TX_DN<13>")
	)
	(segment
		(start 372.984268 -276.195536)
		(end 372.983506 -276.196044)
		(width 0.1143)
		(layer "In13.Cu")
		(net "P5E_CPU0_P2_TX_DN<13>")
	)
	(segment
		(start 372.987824 -283.318712)
		(end 372.98884 -283.31922)
		(width 0.1143)
		(layer "In13.Cu")
		(net "P5E_CPU0_P2_TX_DN<13>")
	)
	(segment
		(start 372.98884 -293.039038)
		(end 372.990364 -293.040054)
		(width 0.1143)
		(layer "In13.Cu")
		(net "P5E_CPU0_P2_TX_DN<13>")
	)
	(segment
		(start 373.0244 -287.512252)
		(end 372.987824 -287.533588)
		(width 0.1143)
		(layer "In13.Cu")
		(net "P5E_CPU0_P2_TX_DN<13>")
	)
	(segment
		(start 372.990364 -292.391846)
		(end 372.98884 -292.392862)
		(width 0.1143)
		(layer "In13.Cu")
		(net "P5E_CPU0_P2_TX_DN<13>")
	)
	(segment
		(start 372.980204 -282.67787)
		(end 372.956074 -282.69184)
		(width 0.1143)
		(layer "In13.Cu")
		(net "P5E_CPU0_P2_TX_DN<13>")
	)
	(segment
		(start 372.981982 -282.676854)
		(end 372.98122 -282.677362)
		(width 0.1143)
		(layer "In13.Cu")
		(net "P5E_CPU0_P2_TX_DN<13>")
	)
	(segment
		(start 373.740172 -296.538142)
		(end 373.785892 -296.583862)
		(width 0.1143)
		(layer "In13.Cu")
		(net "P5E_CPU0_P2_TX_DN<13>")
	)
	(segment
		(start 372.990364 -276.840188)
		(end 372.99138 -276.840696)
		(width 0.1143)
		(layer "In13.Cu")
		(net "P5E_CPU0_P2_TX_DN<13>")
	)
	(segment
		(start 372.983506 -274.576032)
		(end 372.981474 -274.577048)
		(width 0.1143)
		(layer "In13.Cu")
		(net "P5E_CPU0_P2_TX_DN<13>")
	)
	(segment
		(start 424.74261 -375.925842)
		(end 424.74261 -377.1265)
		(width 0.14224)
		(layer "In13.Cu")
		(net "P5E_CPU0_P2_TX_DN<13>")
	)
	(segment
		(start 372.984268 -277.815548)
		(end 372.983506 -277.816056)
		(width 0.1143)
		(layer "In13.Cu")
		(net "P5E_CPU0_P2_TX_DN<13>")
	)
	(arc
		(start 373.02694 -281.72156)
		(mid 373.270267 -282.186126)
		(end 373.02694 -282.650692)
		(width 0.1143)
		(layer "In13.Cu")
		(net "P5E_CPU0_P2_TX_DN<13>")
	)
	(arc
		(start 373.02694 -284.961584)
		(mid 373.270267 -285.42615)
		(end 373.02694 -285.890716)
		(width 0.1143)
		(layer "In13.Cu")
		(net "P5E_CPU0_P2_TX_DN<13>")
	)
	(arc
		(start 372.956074 -276.211792)
		(mid 372.800146 -276.516084)
		(end 372.956074 -276.820376)
		(width 0.1143)
		(layer "In13.Cu")
		(net "P5E_CPU0_P2_TX_DN<13>")
	)
	(arc
		(start 372.956074 -274.59178)
		(mid 372.800146 -274.896072)
		(end 372.956074 -275.200364)
		(width 0.1143)
		(layer "In13.Cu")
		(net "P5E_CPU0_P2_TX_DN<13>")
	)
	(arc
		(start 372.956074 -285.931864)
		(mid 372.841398 -286.065198)
		(end 372.800118 -286.236156)
		(width 0.1143)
		(layer "In13.Cu")
		(net "P5E_CPU0_P2_TX_DN<13>")
	)
	(arc
		(start 373.02694 -283.341572)
		(mid 373.270267 -283.806138)
		(end 373.02694 -284.270704)
		(width 0.1143)
		(layer "In13.Cu")
		(net "P5E_CPU0_P2_TX_DN<13>")
	)
	(arc
		(start 373.270272 -270.846042)
		(mid 373.205757 -271.108261)
		(end 373.02694 -271.310608)
		(width 0.1143)
		(layer "In13.Cu")
		(net "P5E_CPU0_P2_TX_DN<13>")
	)
	(arc
		(start 373.02694 -293.06139)
		(mid 373.270267 -293.525956)
		(end 373.02694 -293.990522)
		(width 0.1143)
		(layer "In13.Cu")
		(net "P5E_CPU0_P2_TX_DN<13>")
	)
	(arc
		(start 373.528082 -295.51503)
		(mid 373.684299 -295.711231)
		(end 373.740172 -295.95572)
		(width 0.1143)
		(layer "In13.Cu")
		(net "P5E_CPU0_P2_TX_DN<13>")
	)
	(arc
		(start 372.956074 -271.351756)
		(mid 372.800146 -271.656048)
		(end 372.956074 -271.96034)
		(width 0.1143)
		(layer "In13.Cu")
		(net "P5E_CPU0_P2_TX_DN<13>")
	)
	(arc
		(start 372.956074 -289.171634)
		(mid 372.800146 -289.475926)
		(end 372.956074 -289.780218)
		(width 0.1143)
		(layer "In13.Cu")
		(net "P5E_CPU0_P2_TX_DN<13>")
	)
	(arc
		(start 372.956074 -294.03167)
		(mid 372.800146 -294.335962)
		(end 372.956074 -294.640254)
		(width 0.1143)
		(layer "In13.Cu")
		(net "P5E_CPU0_P2_TX_DN<13>")
	)
	(arc
		(start 372.956074 -284.311852)
		(mid 372.800146 -284.616144)
		(end 372.956074 -284.920436)
		(width 0.1143)
		(layer "In13.Cu")
		(net "P5E_CPU0_P2_TX_DN<13>")
	)
	(arc
		(start 372.956074 -272.971768)
		(mid 372.800146 -273.27606)
		(end 372.956074 -273.580352)
		(width 0.1143)
		(layer "In13.Cu")
		(net "P5E_CPU0_P2_TX_DN<13>")
	)
	(arc
		(start 372.800118 -287.856168)
		(mid 372.84088 -288.026052)
		(end 372.954296 -288.158936)
		(width 0.1143)
		(layer "In13.Cu")
		(net "P5E_CPU0_P2_TX_DN<13>")
	)
	(arc
		(start 373.02694 -273.6215)
		(mid 373.270267 -274.086066)
		(end 373.02694 -274.550632)
		(width 0.1143)
		(layer "In13.Cu")
		(net "P5E_CPU0_P2_TX_DN<13>")
	)
	(arc
		(start 373.02694 -275.241512)
		(mid 373.270267 -275.706078)
		(end 373.02694 -276.170644)
		(width 0.1143)
		(layer "In13.Cu")
		(net "P5E_CPU0_P2_TX_DN<13>")
	)
	(arc
		(start 373.02694 -288.201354)
		(mid 373.270267 -288.66592)
		(end 373.02694 -289.130486)
		(width 0.1143)
		(layer "In13.Cu")
		(net "P5E_CPU0_P2_TX_DN<13>")
	)
	(arc
		(start 372.956074 -292.411658)
		(mid 372.800146 -292.71595)
		(end 372.956074 -293.020242)
		(width 0.1143)
		(layer "In13.Cu")
		(net "P5E_CPU0_P2_TX_DN<13>")
	)
	(arc
		(start 373.02694 -289.821366)
		(mid 373.270267 -290.285932)
		(end 373.02694 -290.750498)
		(width 0.1143)
		(layer "In13.Cu")
		(net "P5E_CPU0_P2_TX_DN<13>")
	)
	(arc
		(start 404.200868 -366.913414)
		(mid 404.216668 -366.932666)
		(end 404.23592 -366.948466)
		(width 0.14224)
		(layer "In13.Cu")
		(net "P5E_CPU0_P2_TX_DN<13>")
	)
	(arc
		(start 373.02694 -276.861524)
		(mid 373.270267 -277.32609)
		(end 373.02694 -277.790656)
		(width 0.1143)
		(layer "In13.Cu")
		(net "P5E_CPU0_P2_TX_DN<13>")
	)
	(arc
		(start 372.956074 -287.551876)
		(mid 372.841398 -287.68521)
		(end 372.800118 -287.856168)
		(width 0.1143)
		(layer "In13.Cu")
		(net "P5E_CPU0_P2_TX_DN<13>")
	)
	(arc
		(start 372.956074 -279.451816)
		(mid 372.800146 -279.756108)
		(end 372.956074 -280.0604)
		(width 0.1143)
		(layer "In13.Cu")
		(net "P5E_CPU0_P2_TX_DN<13>")
	)
	(arc
		(start 372.956074 -282.69184)
		(mid 372.800146 -282.996132)
		(end 372.956074 -283.300424)
		(width 0.1143)
		(layer "In13.Cu")
		(net "P5E_CPU0_P2_TX_DN<13>")
	)
	(arc
		(start 373.02694 -286.581342)
		(mid 373.205753 -286.783692)
		(end 373.270272 -287.045908)
		(width 0.1143)
		(layer "In13.Cu")
		(net "P5E_CPU0_P2_TX_DN<13>")
	)
	(arc
		(start 373.785892 -297.403266)
		(mid 373.788447 -297.428136)
		(end 373.795798 -297.452034)
		(width 0.14224)
		(layer "In13.Cu")
		(net "P5E_CPU0_P2_TX_DN<13>")
	)
	(arc
		(start 372.956074 -290.791646)
		(mid 372.800146 -291.095938)
		(end 372.956074 -291.40023)
		(width 0.1143)
		(layer "In13.Cu")
		(net "P5E_CPU0_P2_TX_DN<13>")
	)
	(arc
		(start 373.02694 -278.481536)
		(mid 373.270267 -278.946102)
		(end 373.02694 -279.410668)
		(width 0.1143)
		(layer "In13.Cu")
		(net "P5E_CPU0_P2_TX_DN<13>")
	)
	(arc
		(start 419.583616 -373.814594)
		(mid 419.761413 -373.868561)
		(end 419.946328 -373.88673)
		(width 0.14224)
		(layer "In13.Cu")
		(net "P5E_CPU0_P2_TX_DN<13>")
	)
	(arc
		(start 373.270272 -295.145968)
		(mid 373.311821 -295.31739)
		(end 373.427244 -295.450768)
		(width 0.1143)
		(layer "In13.Cu")
		(net "P5E_CPU0_P2_TX_DN<13>")
	)
	(arc
		(start 373.02694 -280.101548)
		(mid 373.270267 -280.566114)
		(end 373.02694 -281.03068)
		(width 0.1143)
		(layer "In13.Cu")
		(net "P5E_CPU0_P2_TX_DN<13>")
	)
	(arc
		(start 424.622722 -375.636282)
		(mid 424.711437 -375.769147)
		(end 424.74261 -375.925842)
		(width 0.14224)
		(layer "In13.Cu")
		(net "P5E_CPU0_P2_TX_DN<13>")
	)
	(arc
		(start 372.800118 -286.236156)
		(mid 372.84088 -286.40604)
		(end 372.954296 -286.538924)
		(width 0.1143)
		(layer "In13.Cu")
		(net "P5E_CPU0_P2_TX_DN<13>")
	)
	(arc
		(start 373.49684 -295.491408)
		(mid 373.512668 -295.502946)
		(end 373.528082 -295.51503)
		(width 0.1143)
		(layer "In13.Cu")
		(net "P5E_CPU0_P2_TX_DN<13>")
	)
	(arc
		(start 373.02694 -291.441378)
		(mid 373.270267 -291.905944)
		(end 373.02694 -292.37051)
		(width 0.1143)
		(layer "In13.Cu")
		(net "P5E_CPU0_P2_TX_DN<13>")
	)
	(arc
		(start 373.270272 -287.045908)
		(mid 373.205036 -287.309499)
		(end 373.0244 -287.512252)
		(width 0.1143)
		(layer "In13.Cu")
		(net "P5E_CPU0_P2_TX_DN<13>")
	)
	(arc
		(start 422.6433 -373.88673)
		(mid 422.855685 -373.928976)
		(end 423.03573 -374.04929)
		(width 0.14224)
		(layer "In13.Cu")
		(net "P5E_CPU0_P2_TX_DN<13>")
	)
	(arc
		(start 373.427244 -270.541242)
		(mid 373.311817 -270.674618)
		(end 373.270272 -270.846042)
		(width 0.1143)
		(layer "In13.Cu")
		(net "P5E_CPU0_P2_TX_DN<13>")
	)
	(arc
		(start 373.730266 -270.1417)
		(mid 373.648833 -270.344098)
		(end 373.49684 -270.500602)
		(width 0.1143)
		(layer "In13.Cu")
		(net "P5E_CPU0_P2_TX_DN<13>")
	)
	(arc
		(start 373.734076 -270.11884)
		(mid 373.732288 -270.130289)
		(end 373.730266 -270.1417)
		(width 0.1143)
		(layer "In13.Cu")
		(net "P5E_CPU0_P2_TX_DN<13>")
	)
	(arc
		(start 373.02694 -272.001488)
		(mid 373.270267 -272.466054)
		(end 373.02694 -272.93062)
		(width 0.1143)
		(layer "In13.Cu")
		(net "P5E_CPU0_P2_TX_DN<13>")
	)
	(arc
		(start 373.02694 -294.681402)
		(mid 373.205753 -294.883752)
		(end 373.270272 -295.145968)
		(width 0.1143)
		(layer "In13.Cu")
		(net "P5E_CPU0_P2_TX_DN<13>")
	)
	(arc
		(start 372.956074 -277.831804)
		(mid 372.800146 -278.136096)
		(end 372.956074 -278.440388)
		(width 0.1143)
		(layer "In13.Cu")
		(net "P5E_CPU0_P2_TX_DN<13>")
	)
	(arc
		(start 372.956074 -281.071828)
		(mid 372.800146 -281.37612)
		(end 372.956074 -281.680412)
		(width 0.1143)
		(layer "In13.Cu")
		(net "P5E_CPU0_P2_TX_DN<13>")
	)
	(segment
		(start 421.62984 -377.41733)
		(end 421.35933 -377.68784)
		(width 0.12954)
		(layer "F.Cu")
		(net "P5E_CPU0_P2_TX_DN<12>")
	)
	(segment
		(start 370.828062 -271.39011)
		(end 371.294914 -271.656048)
		(width 0.12954)
		(layer "F.Cu")
		(net "P5E_CPU0_P2_TX_DN<12>")
	)
	(segment
		(start 421.35933 -378.39142)
		(end 421.65524 -378.68733)
		(width 0.12954)
		(layer "F.Cu")
		(net "P5E_CPU0_P2_TX_DN<12>")
	)
	(segment
		(start 421.35933 -377.68784)
		(end 421.35933 -378.39142)
		(width 0.12954)
		(layer "F.Cu")
		(net "P5E_CPU0_P2_TX_DN<12>")
	)
	(segment
		(start 372.086886 -274.550632)
		(end 372.04777 -274.573492)
		(width 0.1143)
		(layer "In13.Cu")
		(net "P5E_CPU0_P2_TX_DN<12>")
	)
	(segment
		(start 372.04777 -274.573492)
		(end 372.01602 -274.59178)
		(width 0.1143)
		(layer "In13.Cu")
		(net "P5E_CPU0_P2_TX_DN<12>")
	)
	(segment
		(start 372.01729 -284.920944)
		(end 372.04777 -284.938724)
		(width 0.1143)
		(layer "In13.Cu")
		(net "P5E_CPU0_P2_TX_DN<12>")
	)
	(segment
		(start 372.48719 -295.450768)
		(end 372.51767 -295.468548)
		(width 0.1143)
		(layer "In13.Cu")
		(net "P5E_CPU0_P2_TX_DN<12>")
	)
	(segment
		(start 372.04777 -294.658542)
		(end 372.086886 -294.681402)
		(width 0.1143)
		(layer "In13.Cu")
		(net "P5E_CPU0_P2_TX_DN<12>")
	)
	(segment
		(start 371.54612 -272.770346)
		(end 371.577108 -272.78838)
		(width 0.1143)
		(layer "In13.Cu")
		(net "P5E_CPU0_P2_TX_DN<12>")
	)
	(segment
		(start 372.845838 -296.595038)
		(end 372.845838 -297.623484)
		(width 0.14224)
		(layer "In13.Cu")
		(net "P5E_CPU0_P2_TX_DN<12>")
	)
	(segment
		(start 372.04777 -285.913576)
		(end 372.01729 -285.931356)
		(width 0.1143)
		(layer "In13.Cu")
		(net "P5E_CPU0_P2_TX_DN<12>")
	)
	(segment
		(start 372.086886 -293.990522)
		(end 372.04777 -294.013382)
		(width 0.1143)
		(layer "In13.Cu")
		(net "P5E_CPU0_P2_TX_DN<12>")
	)
	(segment
		(start 372.04777 -288.178494)
		(end 372.086886 -288.201354)
		(width 0.1143)
		(layer "In13.Cu")
		(net "P5E_CPU0_P2_TX_DN<12>")
	)
	(segment
		(start 372.04777 -276.838664)
		(end 372.086886 -276.861524)
		(width 0.1143)
		(layer "In13.Cu")
		(net "P5E_CPU0_P2_TX_DN<12>")
	)
	(segment
		(start 372.04777 -284.938724)
		(end 372.086886 -284.961584)
		(width 0.1143)
		(layer "In13.Cu")
		(net "P5E_CPU0_P2_TX_DN<12>")
	)
	(segment
		(start 371.294914 -271.656048)
		(end 370.996972 -271.656048)
		(width 0.1143)
		(layer "In13.Cu")
		(net "P5E_CPU0_P2_TX_DN<12>")
	)
	(segment
		(start 372.086886 -282.650692)
		(end 372.04777 -282.673552)
		(width 0.1143)
		(layer "In13.Cu")
		(net "P5E_CPU0_P2_TX_DN<12>")
	)
	(segment
		(start 372.04777 -292.39337)
		(end 372.01729 -292.41115)
		(width 0.1143)
		(layer "In13.Cu")
		(net "P5E_CPU0_P2_TX_DN<12>")
	)
	(segment
		(start 372.04777 -283.318712)
		(end 372.086886 -283.341572)
		(width 0.1143)
		(layer "In13.Cu")
		(net "P5E_CPU0_P2_TX_DN<12>")
	)
	(segment
		(start 372.04777 -278.458676)
		(end 372.086886 -278.481536)
		(width 0.1143)
		(layer "In13.Cu")
		(net "P5E_CPU0_P2_TX_DN<12>")
	)
	(segment
		(start 372.01729 -291.400738)
		(end 372.04777 -291.418518)
		(width 0.1143)
		(layer "In13.Cu")
		(net "P5E_CPU0_P2_TX_DN<12>")
	)
	(segment
		(start 370.996972 -271.656048)
		(end 370.927122 -271.725898)
		(width 0.1143)
		(layer "In13.Cu")
		(net "P5E_CPU0_P2_TX_DN<12>")
	)
	(segment
		(start 372.01602 -278.440388)
		(end 372.04777 -278.458676)
		(width 0.1143)
		(layer "In13.Cu")
		(net "P5E_CPU0_P2_TX_DN<12>")
	)
	(segment
		(start 372.51767 -295.468548)
		(end 372.556786 -295.491408)
		(width 0.1143)
		(layer "In13.Cu")
		(net "P5E_CPU0_P2_TX_DN<12>")
	)
	(segment
		(start 372.01729 -289.780726)
		(end 372.04777 -289.798506)
		(width 0.1143)
		(layer "In13.Cu")
		(net "P5E_CPU0_P2_TX_DN<12>")
	)
	(segment
		(start 372.04777 -276.193504)
		(end 372.01602 -276.211792)
		(width 0.1143)
		(layer "In13.Cu")
		(net "P5E_CPU0_P2_TX_DN<12>")
	)
	(segment
		(start 372.04777 -286.558482)
		(end 372.086886 -286.581342)
		(width 0.1143)
		(layer "In13.Cu")
		(net "P5E_CPU0_P2_TX_DN<12>")
	)
	(segment
		(start 372.086886 -276.170644)
		(end 372.04777 -276.193504)
		(width 0.1143)
		(layer "In13.Cu")
		(net "P5E_CPU0_P2_TX_DN<12>")
	)
	(segment
		(start 372.01729 -281.68092)
		(end 372.04777 -281.6987)
		(width 0.1143)
		(layer "In13.Cu")
		(net "P5E_CPU0_P2_TX_DN<12>")
	)
	(segment
		(start 372.01602 -274.59178)
		(end 372.007384 -274.597876)
		(width 0.1143)
		(layer "In13.Cu")
		(net "P5E_CPU0_P2_TX_DN<12>")
	)
	(segment
		(start 372.04777 -284.293564)
		(end 372.01729 -284.311344)
		(width 0.1143)
		(layer "In13.Cu")
		(net "P5E_CPU0_P2_TX_DN<12>")
	)
	(segment
		(start 420.454074 -375.35104)
		(end 421.33901 -376.235976)
		(width 0.14224)
		(layer "In13.Cu")
		(net "P5E_CPU0_P2_TX_DN<12>")
	)
	(segment
		(start 372.04777 -281.6987)
		(end 372.086886 -281.72156)
		(width 0.1143)
		(layer "In13.Cu")
		(net "P5E_CPU0_P2_TX_DN<12>")
	)
	(segment
		(start 421.33901 -377.1265)
		(end 421.62984 -377.41733)
		(width 0.14224)
		(layer "In13.Cu")
		(net "P5E_CPU0_P2_TX_DN<12>")
	)
	(segment
		(start 372.086886 -290.750498)
		(end 372.04777 -290.773358)
		(width 0.1143)
		(layer "In13.Cu")
		(net "P5E_CPU0_P2_TX_DN<12>")
	)
	(segment
		(start 372.800118 -296.52087)
		(end 372.845838 -296.56659)
		(width 0.1143)
		(layer "In13.Cu")
		(net "P5E_CPU0_P2_TX_DN<12>")
	)
	(segment
		(start 372.007384 -275.194268)
		(end 372.01602 -275.200364)
		(width 0.1143)
		(layer "In13.Cu")
		(net "P5E_CPU0_P2_TX_DN<12>")
	)
	(segment
		(start 371.577108 -272.78838)
		(end 371.616224 -272.810732)
		(width 0.1143)
		(layer "In13.Cu")
		(net "P5E_CPU0_P2_TX_DN<12>")
	)
	(segment
		(start 372.01729 -293.02075)
		(end 372.04777 -293.03853)
		(width 0.1143)
		(layer "In13.Cu")
		(net "P5E_CPU0_P2_TX_DN<12>")
	)
	(segment
		(start 372.04777 -281.05354)
		(end 372.018814 -281.070304)
		(width 0.1143)
		(layer "In13.Cu")
		(net "P5E_CPU0_P2_TX_DN<12>")
	)
	(segment
		(start 372.086886 -284.270704)
		(end 372.04777 -284.293564)
		(width 0.1143)
		(layer "In13.Cu")
		(net "P5E_CPU0_P2_TX_DN<12>")
	)
	(segment
		(start 372.048786 -280.079196)
		(end 372.086886 -280.101548)
		(width 0.1143)
		(layer "In13.Cu")
		(net "P5E_CPU0_P2_TX_DN<12>")
	)
	(segment
		(start 372.04777 -282.673552)
		(end 372.01729 -282.691332)
		(width 0.1143)
		(layer "In13.Cu")
		(net "P5E_CPU0_P2_TX_DN<12>")
	)
	(segment
		(start 372.086886 -285.890716)
		(end 372.04777 -285.913576)
		(width 0.1143)
		(layer "In13.Cu")
		(net "P5E_CPU0_P2_TX_DN<12>")
	)
	(segment
		(start 372.04777 -293.03853)
		(end 372.086886 -293.06139)
		(width 0.1143)
		(layer "In13.Cu")
		(net "P5E_CPU0_P2_TX_DN<12>")
	)
	(segment
		(start 372.086886 -277.790656)
		(end 372.04777 -277.813516)
		(width 0.1143)
		(layer "In13.Cu")
		(net "P5E_CPU0_P2_TX_DN<12>")
	)
	(segment
		(start 372.01729 -294.640762)
		(end 372.04777 -294.658542)
		(width 0.1143)
		(layer "In13.Cu")
		(net "P5E_CPU0_P2_TX_DN<12>")
	)
	(segment
		(start 372.01602 -280.0604)
		(end 372.047008 -280.07818)
		(width 0.1143)
		(layer "In13.Cu")
		(net "P5E_CPU0_P2_TX_DN<12>")
	)
	(segment
		(start 372.04777 -291.418518)
		(end 372.086886 -291.441378)
		(width 0.1143)
		(layer "In13.Cu")
		(net "P5E_CPU0_P2_TX_DN<12>")
	)
	(segment
		(start 371.107716 -271.978628)
		(end 371.146832 -272.001488)
		(width 0.1143)
		(layer "In13.Cu")
		(net "P5E_CPU0_P2_TX_DN<12>")
	)
	(segment
		(start 372.04777 -277.813516)
		(end 372.01602 -277.831804)
		(width 0.1143)
		(layer "In13.Cu")
		(net "P5E_CPU0_P2_TX_DN<12>")
	)
	(segment
		(start 420.02837 -375.045478)
		(end 420.313358 -375.23547)
		(width 0.14224)
		(layer "In13.Cu")
		(net "P5E_CPU0_P2_TX_DN<12>")
	)
	(segment
		(start 372.018814 -281.070304)
		(end 372.01729 -281.07132)
		(width 0.1143)
		(layer "In13.Cu")
		(net "P5E_CPU0_P2_TX_DN<12>")
	)
	(segment
		(start 372.086886 -289.130486)
		(end 372.04777 -289.153346)
		(width 0.1143)
		(layer "In13.Cu")
		(net "P5E_CPU0_P2_TX_DN<12>")
	)
	(segment
		(start 371.077236 -271.960848)
		(end 371.107716 -271.978628)
		(width 0.1143)
		(layer "In13.Cu")
		(net "P5E_CPU0_P2_TX_DN<12>")
	)
	(segment
		(start 372.04777 -280.078688)
		(end 372.048786 -280.079196)
		(width 0.1143)
		(layer "In13.Cu")
		(net "P5E_CPU0_P2_TX_DN<12>")
	)
	(segment
		(start 421.33901 -376.235976)
		(end 421.33901 -377.1265)
		(width 0.14224)
		(layer "In13.Cu")
		(net "P5E_CPU0_P2_TX_DN<12>")
	)
	(segment
		(start 372.025164 -273.585432)
		(end 372.086886 -273.6215)
		(width 0.1143)
		(layer "In13.Cu")
		(net "P5E_CPU0_P2_TX_DN<12>")
	)
	(segment
		(start 372.01729 -283.300932)
		(end 372.04777 -283.318712)
		(width 0.1143)
		(layer "In13.Cu")
		(net "P5E_CPU0_P2_TX_DN<12>")
	)
	(segment
		(start 403.657562 -367.702846)
		(end 405.662892 -369.04295)
		(width 0.14224)
		(layer "In13.Cu")
		(net "P5E_CPU0_P2_TX_DN<12>")
	)
	(segment
		(start 372.015258 -288.159698)
		(end 372.04777 -288.178494)
		(width 0.1143)
		(layer "In13.Cu")
		(net "P5E_CPU0_P2_TX_DN<12>")
	)
	(segment
		(start 399.05432 -360.900218)
		(end 403.484334 -367.529618)
		(width 0.14224)
		(layer "In13.Cu")
		(net "P5E_CPU0_P2_TX_DN<12>")
	)
	(segment
		(start 372.01602 -275.200364)
		(end 372.086886 -275.241512)
		(width 0.1143)
		(layer "In13.Cu")
		(net "P5E_CPU0_P2_TX_DN<12>")
	)
	(segment
		(start 372.086886 -279.410668)
		(end 372.04777 -279.433528)
		(width 0.1143)
		(layer "In13.Cu")
		(net "P5E_CPU0_P2_TX_DN<12>")
	)
	(segment
		(start 372.086886 -292.37051)
		(end 372.04777 -292.39337)
		(width 0.1143)
		(layer "In13.Cu")
		(net "P5E_CPU0_P2_TX_DN<12>")
	)
	(segment
		(start 372.04777 -290.773358)
		(end 372.01729 -290.791138)
		(width 0.1143)
		(layer "In13.Cu")
		(net "P5E_CPU0_P2_TX_DN<12>")
	)
	(segment
		(start 372.086886 -281.03068)
		(end 372.04777 -281.05354)
		(width 0.1143)
		(layer "In13.Cu")
		(net "P5E_CPU0_P2_TX_DN<12>")
	)
	(segment
		(start 372.084346 -287.512252)
		(end 372.01729 -287.551368)
		(width 0.1143)
		(layer "In13.Cu")
		(net "P5E_CPU0_P2_TX_DN<12>")
	)
	(segment
		(start 405.934672 -369.188238)
		(end 419.86835 -374.95988)
		(width 0.14224)
		(layer "In13.Cu")
		(net "P5E_CPU0_P2_TX_DN<12>")
	)
	(segment
		(start 372.04777 -289.798506)
		(end 372.086886 -289.821366)
		(width 0.1143)
		(layer "In13.Cu")
		(net "P5E_CPU0_P2_TX_DN<12>")
	)
	(segment
		(start 372.015258 -286.539686)
		(end 372.04777 -286.558482)
		(width 0.1143)
		(layer "In13.Cu")
		(net "P5E_CPU0_P2_TX_DN<12>")
	)
	(segment
		(start 372.800118 -295.95572)
		(end 372.800118 -296.52087)
		(width 0.1143)
		(layer "In13.Cu")
		(net "P5E_CPU0_P2_TX_DN<12>")
	)
	(segment
		(start 372.047008 -280.07818)
		(end 372.04777 -280.078688)
		(width 0.1143)
		(layer "In13.Cu")
		(net "P5E_CPU0_P2_TX_DN<12>")
	)
	(segment
		(start 372.04777 -294.013382)
		(end 372.01729 -294.031162)
		(width 0.1143)
		(layer "In13.Cu")
		(net "P5E_CPU0_P2_TX_DN<12>")
	)
	(segment
		(start 372.04777 -279.433528)
		(end 372.01602 -279.451816)
		(width 0.1143)
		(layer "In13.Cu")
		(net "P5E_CPU0_P2_TX_DN<12>")
	)
	(segment
		(start 372.04777 -289.153346)
		(end 372.01729 -289.171126)
		(width 0.1143)
		(layer "In13.Cu")
		(net "P5E_CPU0_P2_TX_DN<12>")
	)
	(segment
		(start 372.870476 -297.746674)
		(end 398.992598 -360.784902)
		(width 0.14224)
		(layer "In13.Cu")
		(net "P5E_CPU0_P2_TX_DN<12>")
	)
	(segment
		(start 372.01602 -276.820376)
		(end 372.04777 -276.838664)
		(width 0.1143)
		(layer "In13.Cu")
		(net "P5E_CPU0_P2_TX_DN<12>")
	)
	(segment
		(start 372.845838 -296.56659)
		(end 372.845838 -296.595038)
		(width 0.1143)
		(layer "In13.Cu")
		(net "P5E_CPU0_P2_TX_DN<12>")
	)
	(arc
		(start 372.01602 -277.831804)
		(mid 371.864431 -278.136096)
		(end 372.01602 -278.440388)
		(width 0.1143)
		(layer "In13.Cu")
		(net "P5E_CPU0_P2_TX_DN<12>")
	)
	(arc
		(start 405.662892 -369.04295)
		(mid 405.79521 -369.122277)
		(end 405.934672 -369.188238)
		(width 0.14224)
		(layer "In13.Cu")
		(net "P5E_CPU0_P2_TX_DN<12>")
	)
	(arc
		(start 372.01729 -282.691332)
		(mid 371.860313 -282.996132)
		(end 372.01729 -283.300932)
		(width 0.1143)
		(layer "In13.Cu")
		(net "P5E_CPU0_P2_TX_DN<12>")
	)
	(arc
		(start 372.01729 -281.07132)
		(mid 371.860313 -281.37612)
		(end 372.01729 -281.68092)
		(width 0.1143)
		(layer "In13.Cu")
		(net "P5E_CPU0_P2_TX_DN<12>")
	)
	(arc
		(start 372.01602 -276.211792)
		(mid 371.864431 -276.516084)
		(end 372.01602 -276.820376)
		(width 0.1143)
		(layer "In13.Cu")
		(net "P5E_CPU0_P2_TX_DN<12>")
	)
	(arc
		(start 372.086886 -275.241512)
		(mid 372.330213 -275.706078)
		(end 372.086886 -276.170644)
		(width 0.1143)
		(layer "In13.Cu")
		(net "P5E_CPU0_P2_TX_DN<12>")
	)
	(arc
		(start 372.01602 -279.451816)
		(mid 371.864431 -279.756108)
		(end 372.01602 -280.0604)
		(width 0.1143)
		(layer "In13.Cu")
		(net "P5E_CPU0_P2_TX_DN<12>")
	)
	(arc
		(start 371.146832 -272.001488)
		(mid 371.325645 -272.203838)
		(end 371.390164 -272.466054)
		(width 0.1143)
		(layer "In13.Cu")
		(net "P5E_CPU0_P2_TX_DN<12>")
	)
	(arc
		(start 372.01729 -284.311344)
		(mid 371.860313 -284.616144)
		(end 372.01729 -284.920944)
		(width 0.1143)
		(layer "In13.Cu")
		(net "P5E_CPU0_P2_TX_DN<12>")
	)
	(arc
		(start 371.86235 -273.285712)
		(mid 371.917033 -273.450089)
		(end 372.025164 -273.585432)
		(width 0.1143)
		(layer "In13.Cu")
		(net "P5E_CPU0_P2_TX_DN<12>")
	)
	(arc
		(start 372.086886 -293.06139)
		(mid 372.330213 -293.525956)
		(end 372.086886 -293.990522)
		(width 0.1143)
		(layer "In13.Cu")
		(net "P5E_CPU0_P2_TX_DN<12>")
	)
	(arc
		(start 372.086886 -281.72156)
		(mid 372.330213 -282.186126)
		(end 372.086886 -282.650692)
		(width 0.1143)
		(layer "In13.Cu")
		(net "P5E_CPU0_P2_TX_DN<12>")
	)
	(arc
		(start 372.01729 -287.551368)
		(mid 371.901863 -287.684744)
		(end 371.860318 -287.856168)
		(width 0.1143)
		(layer "In13.Cu")
		(net "P5E_CPU0_P2_TX_DN<12>")
	)
	(arc
		(start 371.860318 -287.856168)
		(mid 371.901284 -288.026574)
		(end 372.015258 -288.159698)
		(width 0.1143)
		(layer "In13.Cu")
		(net "P5E_CPU0_P2_TX_DN<12>")
	)
	(arc
		(start 419.86835 -374.95988)
		(mid 419.950458 -374.998758)
		(end 420.02837 -375.045478)
		(width 0.14224)
		(layer "In13.Cu")
		(net "P5E_CPU0_P2_TX_DN<12>")
	)
	(arc
		(start 371.860318 -286.236156)
		(mid 371.901284 -286.406562)
		(end 372.015258 -286.539686)
		(width 0.1143)
		(layer "In13.Cu")
		(net "P5E_CPU0_P2_TX_DN<12>")
	)
	(arc
		(start 372.01729 -289.171126)
		(mid 371.860313 -289.475926)
		(end 372.01729 -289.780726)
		(width 0.1143)
		(layer "In13.Cu")
		(net "P5E_CPU0_P2_TX_DN<12>")
	)
	(arc
		(start 370.927122 -271.725898)
		(mid 370.979539 -271.857829)
		(end 371.077236 -271.960848)
		(width 0.1143)
		(layer "In13.Cu")
		(net "P5E_CPU0_P2_TX_DN<12>")
	)
	(arc
		(start 372.01729 -292.41115)
		(mid 371.860313 -292.71595)
		(end 372.01729 -293.02075)
		(width 0.1143)
		(layer "In13.Cu")
		(net "P5E_CPU0_P2_TX_DN<12>")
	)
	(arc
		(start 372.556786 -295.491408)
		(mid 372.572737 -295.502818)
		(end 372.588282 -295.514776)
		(width 0.1143)
		(layer "In13.Cu")
		(net "P5E_CPU0_P2_TX_DN<12>")
	)
	(arc
		(start 372.330218 -295.145968)
		(mid 372.371767 -295.31739)
		(end 372.48719 -295.450768)
		(width 0.1143)
		(layer "In13.Cu")
		(net "P5E_CPU0_P2_TX_DN<12>")
	)
	(arc
		(start 372.01729 -290.791138)
		(mid 371.860313 -291.095938)
		(end 372.01729 -291.400738)
		(width 0.1143)
		(layer "In13.Cu")
		(net "P5E_CPU0_P2_TX_DN<12>")
	)
	(arc
		(start 372.330218 -287.045908)
		(mid 372.264982 -287.309499)
		(end 372.084346 -287.512252)
		(width 0.1143)
		(layer "In13.Cu")
		(net "P5E_CPU0_P2_TX_DN<12>")
	)
	(arc
		(start 372.086886 -278.481536)
		(mid 372.330213 -278.946102)
		(end 372.086886 -279.410668)
		(width 0.1143)
		(layer "In13.Cu")
		(net "P5E_CPU0_P2_TX_DN<12>")
	)
	(arc
		(start 372.01729 -285.931356)
		(mid 371.901863 -286.064732)
		(end 371.860318 -286.236156)
		(width 0.1143)
		(layer "In13.Cu")
		(net "P5E_CPU0_P2_TX_DN<12>")
	)
	(arc
		(start 372.086886 -289.821366)
		(mid 372.330213 -290.285932)
		(end 372.086886 -290.750498)
		(width 0.1143)
		(layer "In13.Cu")
		(net "P5E_CPU0_P2_TX_DN<12>")
	)
	(arc
		(start 371.616224 -272.810732)
		(mid 371.790995 -273.004449)
		(end 371.860318 -273.255994)
		(width 0.1143)
		(layer "In13.Cu")
		(net "P5E_CPU0_P2_TX_DN<12>")
	)
	(arc
		(start 420.313358 -375.23547)
		(mid 420.386564 -375.289786)
		(end 420.454074 -375.35104)
		(width 0.14224)
		(layer "In13.Cu")
		(net "P5E_CPU0_P2_TX_DN<12>")
	)
	(arc
		(start 403.484334 -367.529618)
		(mid 403.562411 -367.624769)
		(end 403.657562 -367.702846)
		(width 0.14224)
		(layer "In13.Cu")
		(net "P5E_CPU0_P2_TX_DN<12>")
	)
	(arc
		(start 372.845838 -297.623484)
		(mid 372.852116 -297.686285)
		(end 372.870476 -297.746674)
		(width 0.14224)
		(layer "In13.Cu")
		(net "P5E_CPU0_P2_TX_DN<12>")
	)
	(arc
		(start 372.588282 -295.514776)
		(mid 372.74435 -295.711153)
		(end 372.800118 -295.95572)
		(width 0.1143)
		(layer "In13.Cu")
		(net "P5E_CPU0_P2_TX_DN<12>")
	)
	(arc
		(start 372.086886 -286.581342)
		(mid 372.265699 -286.783692)
		(end 372.330218 -287.045908)
		(width 0.1143)
		(layer "In13.Cu")
		(net "P5E_CPU0_P2_TX_DN<12>")
	)
	(arc
		(start 372.086886 -283.341572)
		(mid 372.330213 -283.806138)
		(end 372.086886 -284.270704)
		(width 0.1143)
		(layer "In13.Cu")
		(net "P5E_CPU0_P2_TX_DN<12>")
	)
	(arc
		(start 371.390164 -272.466054)
		(mid 371.431419 -272.637025)
		(end 371.54612 -272.770346)
		(width 0.1143)
		(layer "In13.Cu")
		(net "P5E_CPU0_P2_TX_DN<12>")
	)
	(arc
		(start 372.086886 -273.6215)
		(mid 372.330213 -274.086066)
		(end 372.086886 -274.550632)
		(width 0.1143)
		(layer "In13.Cu")
		(net "P5E_CPU0_P2_TX_DN<12>")
	)
	(arc
		(start 372.086886 -276.861524)
		(mid 372.330213 -277.32609)
		(end 372.086886 -277.790656)
		(width 0.1143)
		(layer "In13.Cu")
		(net "P5E_CPU0_P2_TX_DN<12>")
	)
	(arc
		(start 372.01729 -294.031162)
		(mid 371.860313 -294.335962)
		(end 372.01729 -294.640762)
		(width 0.1143)
		(layer "In13.Cu")
		(net "P5E_CPU0_P2_TX_DN<12>")
	)
	(arc
		(start 372.086886 -284.961584)
		(mid 372.330213 -285.42615)
		(end 372.086886 -285.890716)
		(width 0.1143)
		(layer "In13.Cu")
		(net "P5E_CPU0_P2_TX_DN<12>")
	)
	(arc
		(start 372.086886 -288.201354)
		(mid 372.330213 -288.66592)
		(end 372.086886 -289.130486)
		(width 0.1143)
		(layer "In13.Cu")
		(net "P5E_CPU0_P2_TX_DN<12>")
	)
	(arc
		(start 372.086886 -294.681402)
		(mid 372.265699 -294.883752)
		(end 372.330218 -295.145968)
		(width 0.1143)
		(layer "In13.Cu")
		(net "P5E_CPU0_P2_TX_DN<12>")
	)
	(arc
		(start 372.086886 -280.101548)
		(mid 372.330213 -280.566114)
		(end 372.086886 -281.03068)
		(width 0.1143)
		(layer "In13.Cu")
		(net "P5E_CPU0_P2_TX_DN<12>")
	)
	(arc
		(start 398.992598 -360.784902)
		(mid 399.020636 -360.84407)
		(end 399.05432 -360.900218)
		(width 0.14224)
		(layer "In13.Cu")
		(net "P5E_CPU0_P2_TX_DN<12>")
	)
	(arc
		(start 372.007384 -274.597876)
		(mid 371.854503 -274.896072)
		(end 372.007384 -275.194268)
		(width 0.1143)
		(layer "In13.Cu")
		(net "P5E_CPU0_P2_TX_DN<12>")
	)
	(arc
		(start 371.860318 -273.255994)
		(mid 371.860891 -273.270883)
		(end 371.86235 -273.285712)
		(width 0.1143)
		(layer "In13.Cu")
		(net "P5E_CPU0_P2_TX_DN<12>")
	)
	(arc
		(start 372.086886 -291.441378)
		(mid 372.330213 -291.905944)
		(end 372.086886 -292.37051)
		(width 0.1143)
		(layer "In13.Cu")
		(net "P5E_CPU0_P2_TX_DN<12>")
	)
	(segment
		(start 370.828062 -273.010122)
		(end 371.294914 -273.27606)
		(width 0.12954)
		(layer "F.Cu")
		(net "P5E_CPU0_P2_TX_DN<11>")
	)
	(segment
		(start 419.65753 -380.85522)
		(end 419.95344 -381.15113)
		(width 0.12954)
		(layer "F.Cu")
		(net "P5E_CPU0_P2_TX_DN<11>")
	)
	(segment
		(start 419.65753 -380.15164)
		(end 419.65753 -380.85522)
		(width 0.12954)
		(layer "F.Cu")
		(net "P5E_CPU0_P2_TX_DN<11>")
	)
	(segment
		(start 419.92804 -379.88113)
		(end 419.65753 -380.15164)
		(width 0.12954)
		(layer "F.Cu")
		(net "P5E_CPU0_P2_TX_DN<11>")
	)
	(segment
		(start 371.571774 -295.465246)
		(end 371.700552 -295.54043)
		(width 0.1143)
		(layer "In13.Cu")
		(net "P5E_CPU0_P2_TX_DN<11>")
	)
	(segment
		(start 419.63721 -376.777504)
		(end 419.63721 -379.5903)
		(width 0.14224)
		(layer "In13.Cu")
		(net "P5E_CPU0_P2_TX_DN<11>")
	)
	(segment
		(start 417.321238 -374.925336)
		(end 418.252656 -375.856754)
		(width 0.14224)
		(layer "In13.Cu")
		(net "P5E_CPU0_P2_TX_DN<11>")
	)
	(segment
		(start 371.159532 -287.501584)
		(end 371.148102 -287.51022)
		(width 0.1143)
		(layer "In13.Cu")
		(net "P5E_CPU0_P2_TX_DN<11>")
	)
	(segment
		(start 371.146832 -279.410668)
		(end 371.077236 -279.451308)
		(width 0.1143)
		(layer "In13.Cu")
		(net "P5E_CPU0_P2_TX_DN<11>")
	)
	(segment
		(start 402.866098 -368.298476)
		(end 405.380952 -369.979194)
		(width 0.14224)
		(layer "In13.Cu")
		(net "P5E_CPU0_P2_TX_DN<11>")
	)
	(segment
		(start 371.07622 -293.020242)
		(end 371.111018 -293.040308)
		(width 0.1143)
		(layer "In13.Cu")
		(net "P5E_CPU0_P2_TX_DN<11>")
	)
	(segment
		(start 371.107208 -283.318204)
		(end 371.10797 -283.318712)
		(width 0.1143)
		(layer "In13.Cu")
		(net "P5E_CPU0_P2_TX_DN<11>")
	)
	(segment
		(start 371.144292 -292.372542)
		(end 371.07622 -292.411658)
		(width 0.1143)
		(layer "In13.Cu")
		(net "P5E_CPU0_P2_TX_DN<11>")
	)
	(segment
		(start 371.14607 -291.440362)
		(end 371.159024 -291.44976)
		(width 0.1143)
		(layer "In13.Cu")
		(net "P5E_CPU0_P2_TX_DN<11>")
	)
	(segment
		(start 371.146832 -277.790656)
		(end 371.077236 -277.831296)
		(width 0.1143)
		(layer "In13.Cu")
		(net "P5E_CPU0_P2_TX_DN<11>")
	)
	(segment
		(start 371.159024 -292.362128)
		(end 371.14607 -292.371526)
		(width 0.1143)
		(layer "In13.Cu")
		(net "P5E_CPU0_P2_TX_DN<11>")
	)
	(segment
		(start 371.074442 -286.538924)
		(end 371.149118 -286.582866)
		(width 0.1143)
		(layer "In13.Cu")
		(net "P5E_CPU0_P2_TX_DN<11>")
	)
	(segment
		(start 371.07622 -283.300424)
		(end 371.107208 -283.318204)
		(width 0.1143)
		(layer "In13.Cu")
		(net "P5E_CPU0_P2_TX_DN<11>")
	)
	(segment
		(start 371.111018 -290.77158)
		(end 371.07622 -290.791646)
		(width 0.1143)
		(layer "In13.Cu")
		(net "P5E_CPU0_P2_TX_DN<11>")
	)
	(segment
		(start 371.111018 -289.151568)
		(end 371.07622 -289.171634)
		(width 0.1143)
		(layer "In13.Cu")
		(net "P5E_CPU0_P2_TX_DN<11>")
	)
	(segment
		(start 371.077236 -280.060908)
		(end 371.146832 -280.101548)
		(width 0.1143)
		(layer "In13.Cu")
		(net "P5E_CPU0_P2_TX_DN<11>")
	)
	(segment
		(start 371.07622 -284.920436)
		(end 371.111018 -284.940502)
		(width 0.1143)
		(layer "In13.Cu")
		(net "P5E_CPU0_P2_TX_DN<11>")
	)
	(segment
		(start 371.10797 -283.318712)
		(end 371.111018 -283.32049)
		(width 0.1143)
		(layer "In13.Cu")
		(net "P5E_CPU0_P2_TX_DN<11>")
	)
	(segment
		(start 371.111018 -284.291786)
		(end 371.07622 -284.311852)
		(width 0.1143)
		(layer "In13.Cu")
		(net "P5E_CPU0_P2_TX_DN<11>")
	)
	(segment
		(start 371.111018 -285.911798)
		(end 371.07622 -285.931864)
		(width 0.1143)
		(layer "In13.Cu")
		(net "P5E_CPU0_P2_TX_DN<11>")
	)
	(segment
		(start 370.98859 -294.08247)
		(end 370.97462 -294.103298)
		(width 0.1143)
		(layer "In13.Cu")
		(net "P5E_CPU0_P2_TX_DN<11>")
	)
	(segment
		(start 371.111018 -282.671774)
		(end 371.07622 -282.69184)
		(width 0.1143)
		(layer "In13.Cu")
		(net "P5E_CPU0_P2_TX_DN<11>")
	)
	(segment
		(start 371.077236 -275.200872)
		(end 371.146832 -275.241512)
		(width 0.1143)
		(layer "In13.Cu")
		(net "P5E_CPU0_P2_TX_DN<11>")
	)
	(segment
		(start 371.860064 -296.538142)
		(end 371.905784 -296.583862)
		(width 0.1143)
		(layer "In13.Cu")
		(net "P5E_CPU0_P2_TX_DN<11>")
	)
	(segment
		(start 371.074442 -288.158936)
		(end 371.075204 -288.159444)
		(width 0.1143)
		(layer "In13.Cu")
		(net "P5E_CPU0_P2_TX_DN<11>")
	)
	(segment
		(start 419.63721 -379.5903)
		(end 419.92804 -379.88113)
		(width 0.14224)
		(layer "In13.Cu")
		(net "P5E_CPU0_P2_TX_DN<11>")
	)
	(segment
		(start 371.077236 -276.820884)
		(end 371.146832 -276.861524)
		(width 0.1143)
		(layer "In13.Cu")
		(net "P5E_CPU0_P2_TX_DN<11>")
	)
	(segment
		(start 371.146832 -276.170644)
		(end 371.077236 -276.211284)
		(width 0.1143)
		(layer "In13.Cu")
		(net "P5E_CPU0_P2_TX_DN<11>")
	)
	(segment
		(start 419.059614 -376.030236)
		(end 419.517322 -376.487944)
		(width 0.14224)
		(layer "In13.Cu")
		(net "P5E_CPU0_P2_TX_DN<11>")
	)
	(segment
		(start 371.294914 -273.27606)
		(end 370.996972 -273.27606)
		(width 0.1143)
		(layer "In13.Cu")
		(net "P5E_CPU0_P2_TX_DN<11>")
	)
	(segment
		(start 371.905784 -296.61231)
		(end 371.905784 -297.749976)
		(width 0.14224)
		(layer "In13.Cu")
		(net "P5E_CPU0_P2_TX_DN<11>")
	)
	(segment
		(start 371.07622 -289.780218)
		(end 371.111018 -289.800284)
		(width 0.1143)
		(layer "In13.Cu")
		(net "P5E_CPU0_P2_TX_DN<11>")
	)
	(segment
		(start 371.148102 -287.51022)
		(end 371.07622 -287.551876)
		(width 0.1143)
		(layer "In13.Cu")
		(net "P5E_CPU0_P2_TX_DN<11>")
	)
	(segment
		(start 371.146832 -281.03068)
		(end 371.07622 -281.071828)
		(width 0.1143)
		(layer "In13.Cu")
		(net "P5E_CPU0_P2_TX_DN<11>")
	)
	(segment
		(start 371.388894 -295.145206)
		(end 371.388894 -295.146476)
		(width 0.1143)
		(layer "In13.Cu")
		(net "P5E_CPU0_P2_TX_DN<11>")
	)
	(segment
		(start 371.905784 -296.583862)
		(end 371.905784 -296.61231)
		(width 0.1143)
		(layer "In13.Cu")
		(net "P5E_CPU0_P2_TX_DN<11>")
	)
	(segment
		(start 371.10797 -291.418518)
		(end 371.10797 -291.418772)
		(width 0.1143)
		(layer "In13.Cu")
		(net "P5E_CPU0_P2_TX_DN<11>")
	)
	(segment
		(start 405.380952 -369.979194)
		(end 417.321238 -374.925336)
		(width 0.14224)
		(layer "In13.Cu")
		(net "P5E_CPU0_P2_TX_DN<11>")
	)
	(segment
		(start 371.111018 -294.011604)
		(end 370.988844 -294.08247)
		(width 0.1143)
		(layer "In13.Cu")
		(net "P5E_CPU0_P2_TX_DN<11>")
	)
	(segment
		(start 370.988844 -294.08247)
		(end 370.98859 -294.08247)
		(width 0.1143)
		(layer "In13.Cu")
		(net "P5E_CPU0_P2_TX_DN<11>")
	)
	(segment
		(start 371.111018 -293.040308)
		(end 371.110764 -293.040308)
		(width 0.1143)
		(layer "In13.Cu")
		(net "P5E_CPU0_P2_TX_DN<11>")
	)
	(segment
		(start 371.07622 -291.40023)
		(end 371.10797 -291.418518)
		(width 0.1143)
		(layer "In13.Cu")
		(net "P5E_CPU0_P2_TX_DN<11>")
	)
	(segment
		(start 371.07622 -281.680412)
		(end 371.111018 -281.700478)
		(width 0.1143)
		(layer "In13.Cu")
		(net "P5E_CPU0_P2_TX_DN<11>")
	)
	(segment
		(start 371.9703 -298.073572)
		(end 398.216374 -361.410758)
		(width 0.14224)
		(layer "In13.Cu")
		(net "P5E_CPU0_P2_TX_DN<11>")
	)
	(segment
		(start 371.700552 -295.54043)
		(end 371.766846 -295.606724)
		(width 0.1143)
		(layer "In13.Cu")
		(net "P5E_CPU0_P2_TX_DN<11>")
	)
	(segment
		(start 371.390164 -287.045908)
		(end 371.390164 -287.05048)
		(width 0.1143)
		(layer "In13.Cu")
		(net "P5E_CPU0_P2_TX_DN<11>")
	)
	(segment
		(start 371.071394 -294.641524)
		(end 371.146578 -294.685466)
		(width 0.1143)
		(layer "In13.Cu")
		(net "P5E_CPU0_P2_TX_DN<11>")
	)
	(segment
		(start 370.996972 -273.27606)
		(end 370.927122 -273.34591)
		(width 0.1143)
		(layer "In13.Cu")
		(net "P5E_CPU0_P2_TX_DN<11>")
	)
	(segment
		(start 398.216374 -361.410758)
		(end 402.72335 -368.155728)
		(width 0.14224)
		(layer "In13.Cu")
		(net "P5E_CPU0_P2_TX_DN<11>")
	)
	(segment
		(start 371.10797 -291.418772)
		(end 371.14607 -291.440362)
		(width 0.1143)
		(layer "In13.Cu")
		(net "P5E_CPU0_P2_TX_DN<11>")
	)
	(segment
		(start 418.381942 -375.910348)
		(end 418.770054 -375.910348)
		(width 0.14224)
		(layer "In13.Cu")
		(net "P5E_CPU0_P2_TX_DN<11>")
	)
	(segment
		(start 371.860064 -295.831514)
		(end 371.860064 -296.538142)
		(width 0.1143)
		(layer "In13.Cu")
		(net "P5E_CPU0_P2_TX_DN<11>")
	)
	(segment
		(start 371.14607 -292.371526)
		(end 371.144292 -292.372542)
		(width 0.1143)
		(layer "In13.Cu")
		(net "P5E_CPU0_P2_TX_DN<11>")
	)
	(segment
		(start 371.077236 -273.58086)
		(end 371.146832 -273.6215)
		(width 0.1143)
		(layer "In13.Cu")
		(net "P5E_CPU0_P2_TX_DN<11>")
	)
	(segment
		(start 371.077236 -278.440896)
		(end 371.146832 -278.481536)
		(width 0.1143)
		(layer "In13.Cu")
		(net "P5E_CPU0_P2_TX_DN<11>")
	)
	(segment
		(start 371.146832 -274.550632)
		(end 371.077236 -274.591272)
		(width 0.1143)
		(layer "In13.Cu")
		(net "P5E_CPU0_P2_TX_DN<11>")
	)
	(segment
		(start 371.075204 -288.159444)
		(end 371.111018 -288.180272)
		(width 0.1143)
		(layer "In13.Cu")
		(net "P5E_CPU0_P2_TX_DN<11>")
	)
	(arc
		(start 371.07622 -282.69184)
		(mid 370.920292 -282.996132)
		(end 371.07622 -283.300424)
		(width 0.1143)
		(layer "In13.Cu")
		(net "P5E_CPU0_P2_TX_DN<11>")
	)
	(arc
		(start 371.07622 -289.171634)
		(mid 370.920292 -289.475926)
		(end 371.07622 -289.780218)
		(width 0.1143)
		(layer "In13.Cu")
		(net "P5E_CPU0_P2_TX_DN<11>")
	)
	(arc
		(start 371.149118 -286.582866)
		(mid 371.326314 -286.784878)
		(end 371.390164 -287.045908)
		(width 0.1143)
		(layer "In13.Cu")
		(net "P5E_CPU0_P2_TX_DN<11>")
	)
	(arc
		(start 371.110764 -293.040308)
		(mid 371.390506 -293.525846)
		(end 371.111018 -294.011604)
		(width 0.1143)
		(layer "In13.Cu")
		(net "P5E_CPU0_P2_TX_DN<11>")
	)
	(arc
		(start 371.146832 -273.6215)
		(mid 371.390159 -274.086066)
		(end 371.146832 -274.550632)
		(width 0.1143)
		(layer "In13.Cu")
		(net "P5E_CPU0_P2_TX_DN<11>")
	)
	(arc
		(start 371.766846 -295.606724)
		(mid 371.835812 -295.709844)
		(end 371.860064 -295.831514)
		(width 0.1143)
		(layer "In13.Cu")
		(net "P5E_CPU0_P2_TX_DN<11>")
	)
	(arc
		(start 418.770054 -375.910348)
		(mid 418.926757 -375.9415)
		(end 419.059614 -376.030236)
		(width 0.14224)
		(layer "In13.Cu")
		(net "P5E_CPU0_P2_TX_DN<11>")
	)
	(arc
		(start 371.111018 -281.700478)
		(mid 371.390633 -282.186126)
		(end 371.111018 -282.671774)
		(width 0.1143)
		(layer "In13.Cu")
		(net "P5E_CPU0_P2_TX_DN<11>")
	)
	(arc
		(start 418.252656 -375.856754)
		(mid 418.311959 -375.896442)
		(end 418.381942 -375.910348)
		(width 0.14224)
		(layer "In13.Cu")
		(net "P5E_CPU0_P2_TX_DN<11>")
	)
	(arc
		(start 370.920264 -287.856168)
		(mid 370.961026 -288.026052)
		(end 371.074442 -288.158936)
		(width 0.1143)
		(layer "In13.Cu")
		(net "P5E_CPU0_P2_TX_DN<11>")
	)
	(arc
		(start 371.077236 -277.831296)
		(mid 370.920259 -278.136096)
		(end 371.077236 -278.440896)
		(width 0.1143)
		(layer "In13.Cu")
		(net "P5E_CPU0_P2_TX_DN<11>")
	)
	(arc
		(start 371.07622 -292.411658)
		(mid 370.920292 -292.71595)
		(end 371.07622 -293.020242)
		(width 0.1143)
		(layer "In13.Cu")
		(net "P5E_CPU0_P2_TX_DN<11>")
	)
	(arc
		(start 371.159024 -291.44976)
		(mid 371.393451 -291.905944)
		(end 371.159024 -292.362128)
		(width 0.1143)
		(layer "In13.Cu")
		(net "P5E_CPU0_P2_TX_DN<11>")
	)
	(arc
		(start 371.905784 -297.749976)
		(mid 371.922086 -297.914957)
		(end 371.9703 -298.073572)
		(width 0.14224)
		(layer "In13.Cu")
		(net "P5E_CPU0_P2_TX_DN<11>")
	)
	(arc
		(start 371.146832 -275.241512)
		(mid 371.390159 -275.706078)
		(end 371.146832 -276.170644)
		(width 0.1143)
		(layer "In13.Cu")
		(net "P5E_CPU0_P2_TX_DN<11>")
	)
	(arc
		(start 370.927122 -273.34591)
		(mid 370.979539 -273.477841)
		(end 371.077236 -273.58086)
		(width 0.1143)
		(layer "In13.Cu")
		(net "P5E_CPU0_P2_TX_DN<11>")
	)
	(arc
		(start 371.111018 -288.180272)
		(mid 371.390633 -288.66592)
		(end 371.111018 -289.151568)
		(width 0.1143)
		(layer "In13.Cu")
		(net "P5E_CPU0_P2_TX_DN<11>")
	)
	(arc
		(start 371.388894 -295.146476)
		(mid 371.437856 -295.330235)
		(end 371.571774 -295.465246)
		(width 0.1143)
		(layer "In13.Cu")
		(net "P5E_CPU0_P2_TX_DN<11>")
	)
	(arc
		(start 371.07622 -287.551876)
		(mid 370.961544 -287.68521)
		(end 370.920264 -287.856168)
		(width 0.1143)
		(layer "In13.Cu")
		(net "P5E_CPU0_P2_TX_DN<11>")
	)
	(arc
		(start 370.920264 -286.236156)
		(mid 370.961026 -286.40604)
		(end 371.074442 -286.538924)
		(width 0.1143)
		(layer "In13.Cu")
		(net "P5E_CPU0_P2_TX_DN<11>")
	)
	(arc
		(start 371.146832 -276.861524)
		(mid 371.390159 -277.32609)
		(end 371.146832 -277.790656)
		(width 0.1143)
		(layer "In13.Cu")
		(net "P5E_CPU0_P2_TX_DN<11>")
	)
	(arc
		(start 371.146832 -280.101548)
		(mid 371.390159 -280.566114)
		(end 371.146832 -281.03068)
		(width 0.1143)
		(layer "In13.Cu")
		(net "P5E_CPU0_P2_TX_DN<11>")
	)
	(arc
		(start 371.390164 -287.05048)
		(mid 371.329165 -287.303804)
		(end 371.159532 -287.501584)
		(width 0.1143)
		(layer "In13.Cu")
		(net "P5E_CPU0_P2_TX_DN<11>")
	)
	(arc
		(start 371.07622 -281.071828)
		(mid 370.920292 -281.37612)
		(end 371.07622 -281.680412)
		(width 0.1143)
		(layer "In13.Cu")
		(net "P5E_CPU0_P2_TX_DN<11>")
	)
	(arc
		(start 371.07622 -284.311852)
		(mid 370.920292 -284.616144)
		(end 371.07622 -284.920436)
		(width 0.1143)
		(layer "In13.Cu")
		(net "P5E_CPU0_P2_TX_DN<11>")
	)
	(arc
		(start 371.07622 -285.931864)
		(mid 370.961544 -286.065198)
		(end 370.920264 -286.236156)
		(width 0.1143)
		(layer "In13.Cu")
		(net "P5E_CPU0_P2_TX_DN<11>")
	)
	(arc
		(start 371.07622 -290.791646)
		(mid 370.920292 -291.095938)
		(end 371.07622 -291.40023)
		(width 0.1143)
		(layer "In13.Cu")
		(net "P5E_CPU0_P2_TX_DN<11>")
	)
	(arc
		(start 402.72335 -368.155728)
		(mid 402.787696 -368.23413)
		(end 402.866098 -368.298476)
		(width 0.14224)
		(layer "In13.Cu")
		(net "P5E_CPU0_P2_TX_DN<11>")
	)
	(arc
		(start 371.111018 -283.32049)
		(mid 371.390633 -283.806138)
		(end 371.111018 -284.291786)
		(width 0.1143)
		(layer "In13.Cu")
		(net "P5E_CPU0_P2_TX_DN<11>")
	)
	(arc
		(start 371.146578 -294.685466)
		(mid 371.324673 -294.885328)
		(end 371.388894 -295.145206)
		(width 0.1143)
		(layer "In13.Cu")
		(net "P5E_CPU0_P2_TX_DN<11>")
	)
	(arc
		(start 419.517322 -376.487944)
		(mid 419.606037 -376.620809)
		(end 419.63721 -376.777504)
		(width 0.14224)
		(layer "In13.Cu")
		(net "P5E_CPU0_P2_TX_DN<11>")
	)
	(arc
		(start 371.111018 -284.940502)
		(mid 371.390633 -285.42615)
		(end 371.111018 -285.911798)
		(width 0.1143)
		(layer "In13.Cu")
		(net "P5E_CPU0_P2_TX_DN<11>")
	)
	(arc
		(start 371.146832 -278.481536)
		(mid 371.390159 -278.946102)
		(end 371.146832 -279.410668)
		(width 0.1143)
		(layer "In13.Cu")
		(net "P5E_CPU0_P2_TX_DN<11>")
	)
	(arc
		(start 371.077236 -276.211284)
		(mid 370.920259 -276.516084)
		(end 371.077236 -276.820884)
		(width 0.1143)
		(layer "In13.Cu")
		(net "P5E_CPU0_P2_TX_DN<11>")
	)
	(arc
		(start 371.077236 -274.591272)
		(mid 370.920259 -274.896072)
		(end 371.077236 -275.200872)
		(width 0.1143)
		(layer "In13.Cu")
		(net "P5E_CPU0_P2_TX_DN<11>")
	)
	(arc
		(start 371.111018 -289.800284)
		(mid 371.390633 -290.285932)
		(end 371.111018 -290.77158)
		(width 0.1143)
		(layer "In13.Cu")
		(net "P5E_CPU0_P2_TX_DN<11>")
	)
	(arc
		(start 371.077236 -279.451308)
		(mid 370.920259 -279.756108)
		(end 371.077236 -280.060908)
		(width 0.1143)
		(layer "In13.Cu")
		(net "P5E_CPU0_P2_TX_DN<11>")
	)
	(arc
		(start 370.97462 -294.103298)
		(mid 370.91408 -294.39203)
		(end 371.071394 -294.641524)
		(width 0.1143)
		(layer "In13.Cu")
		(net "P5E_CPU0_P2_TX_DN<11>")
	)
	(segment
		(start 370.828062 -269.770098)
		(end 371.294914 -270.036036)
		(width 0.12954)
		(layer "F.Cu")
		(net "P5E_CPU0_P2_TX_DN<10>")
	)
	(segment
		(start 417.95573 -382.61544)
		(end 417.95573 -383.31902)
		(width 0.12954)
		(layer "F.Cu")
		(net "P5E_CPU0_P2_TX_DN<10>")
	)
	(segment
		(start 417.95573 -383.31902)
		(end 418.25164 -383.61493)
		(width 0.12954)
		(layer "F.Cu")
		(net "P5E_CPU0_P2_TX_DN<10>")
	)
	(segment
		(start 418.22624 -382.34493)
		(end 417.95573 -382.61544)
		(width 0.12954)
		(layer "F.Cu")
		(net "P5E_CPU0_P2_TX_DN<10>")
	)
	(segment
		(start 370.168932 -292.392608)
		(end 370.16436 -292.395402)
		(width 0.1143)
		(layer "In13.Cu")
		(net "P5E_CPU0_P2_TX_DN<10>")
	)
	(segment
		(start 370.160296 -289.157664)
		(end 370.136166 -289.171634)
		(width 0.1143)
		(layer "In13.Cu")
		(net "P5E_CPU0_P2_TX_DN<10>")
	)
	(segment
		(start 370.676932 -270.500602)
		(end 370.637816 -270.523462)
		(width 0.1143)
		(layer "In13.Cu")
		(net "P5E_CPU0_P2_TX_DN<10>")
	)
	(segment
		(start 370.160296 -292.397688)
		(end 370.136166 -292.411658)
		(width 0.1143)
		(layer "In13.Cu")
		(net "P5E_CPU0_P2_TX_DN<10>")
	)
	(segment
		(start 370.178838 -293.04488)
		(end 370.207032 -293.06139)
		(width 0.1143)
		(layer "In13.Cu")
		(net "P5E_CPU0_P2_TX_DN<10>")
	)
	(segment
		(start 370.996972 -270.036036)
		(end 370.914168 -270.11884)
		(width 0.1143)
		(layer "In13.Cu")
		(net "P5E_CPU0_P2_TX_DN<10>")
	)
	(segment
		(start 370.137182 -271.960848)
		(end 370.206778 -272.001488)
		(width 0.1143)
		(layer "In13.Cu")
		(net "P5E_CPU0_P2_TX_DN<10>")
	)
	(segment
		(start 370.160296 -290.777676)
		(end 370.136166 -290.791646)
		(width 0.1143)
		(layer "In13.Cu")
		(net "P5E_CPU0_P2_TX_DN<10>")
	)
	(segment
		(start 370.175282 -294.66286)
		(end 370.178838 -294.664892)
		(width 0.1143)
		(layer "In13.Cu")
		(net "P5E_CPU0_P2_TX_DN<10>")
	)
	(segment
		(start 370.172742 -293.041324)
		(end 370.17452 -293.04234)
		(width 0.1143)
		(layer "In13.Cu")
		(net "P5E_CPU0_P2_TX_DN<10>")
	)
	(segment
		(start 370.172742 -281.701494)
		(end 370.17452 -281.70251)
		(width 0.1143)
		(layer "In13.Cu")
		(net "P5E_CPU0_P2_TX_DN<10>")
	)
	(segment
		(start 415.202878 -375.077736)
		(end 416.117786 -375.992644)
		(width 0.14224)
		(layer "In13.Cu")
		(net "P5E_CPU0_P2_TX_DN<10>")
	)
	(segment
		(start 370.787168 -295.591738)
		(end 370.786914 -295.591738)
		(width 0.1143)
		(layer "In13.Cu")
		(net "P5E_CPU0_P2_TX_DN<10>")
	)
	(segment
		(start 370.17452 -281.70251)
		(end 370.175282 -281.703018)
		(width 0.1143)
		(layer "In13.Cu")
		(net "P5E_CPU0_P2_TX_DN<10>")
	)
	(segment
		(start 370.63426 -270.525494)
		(end 370.63299 -270.526256)
		(width 0.1143)
		(layer "In13.Cu")
		(net "P5E_CPU0_P2_TX_DN<10>")
	)
	(segment
		(start 370.17198 -294.660828)
		(end 370.172742 -294.661336)
		(width 0.1143)
		(layer "In13.Cu")
		(net "P5E_CPU0_P2_TX_DN<10>")
	)
	(segment
		(start 370.170456 -289.151822)
		(end 370.168932 -289.152584)
		(width 0.1143)
		(layer "In13.Cu")
		(net "P5E_CPU0_P2_TX_DN<10>")
	)
	(segment
		(start 370.170456 -292.391846)
		(end 370.168932 -292.392608)
		(width 0.1143)
		(layer "In13.Cu")
		(net "P5E_CPU0_P2_TX_DN<10>")
	)
	(segment
		(start 370.160296 -284.297882)
		(end 370.136166 -284.311852)
		(width 0.1143)
		(layer "In13.Cu")
		(net "P5E_CPU0_P2_TX_DN<10>")
	)
	(segment
		(start 370.168932 -290.772596)
		(end 370.16436 -290.77539)
		(width 0.1143)
		(layer "In13.Cu")
		(net "P5E_CPU0_P2_TX_DN<10>")
	)
	(segment
		(start 370.965984 -296.491914)
		(end 370.965984 -298.100242)
		(width 0.14224)
		(layer "In13.Cu")
		(net "P5E_CPU0_P2_TX_DN<10>")
	)
	(segment
		(start 370.206778 -281.03068)
		(end 370.136166 -281.071828)
		(width 0.1143)
		(layer "In13.Cu")
		(net "P5E_CPU0_P2_TX_DN<10>")
	)
	(segment
		(start 370.17452 -294.662352)
		(end 370.175282 -294.66286)
		(width 0.1143)
		(layer "In13.Cu")
		(net "P5E_CPU0_P2_TX_DN<10>")
	)
	(segment
		(start 370.137182 -276.820884)
		(end 370.206778 -276.861524)
		(width 0.1143)
		(layer "In13.Cu")
		(net "P5E_CPU0_P2_TX_DN<10>")
	)
	(segment
		(start 370.178838 -281.70505)
		(end 370.207032 -281.72156)
		(width 0.1143)
		(layer "In13.Cu")
		(net "P5E_CPU0_P2_TX_DN<10>")
	)
	(segment
		(start 370.16436 -290.77539)
		(end 370.160296 -290.777676)
		(width 0.1143)
		(layer "In13.Cu")
		(net "P5E_CPU0_P2_TX_DN<10>")
	)
	(segment
		(start 370.178838 -289.804856)
		(end 370.207032 -289.821366)
		(width 0.1143)
		(layer "In13.Cu")
		(net "P5E_CPU0_P2_TX_DN<10>")
	)
	(segment
		(start 370.63299 -270.526256)
		(end 370.632228 -270.526764)
		(width 0.1143)
		(layer "In13.Cu")
		(net "P5E_CPU0_P2_TX_DN<10>")
	)
	(segment
		(start 370.16436 -289.155378)
		(end 370.160296 -289.157664)
		(width 0.1143)
		(layer "In13.Cu")
		(net "P5E_CPU0_P2_TX_DN<10>")
	)
	(segment
		(start 370.137182 -278.440896)
		(end 370.206778 -278.481536)
		(width 0.1143)
		(layer "In13.Cu")
		(net "P5E_CPU0_P2_TX_DN<10>")
	)
	(segment
		(start 370.207032 -284.270704)
		(end 370.170456 -284.29204)
		(width 0.1143)
		(layer "In13.Cu")
		(net "P5E_CPU0_P2_TX_DN<10>")
	)
	(segment
		(start 370.17198 -281.700986)
		(end 370.172742 -281.701494)
		(width 0.1143)
		(layer "In13.Cu")
		(net "P5E_CPU0_P2_TX_DN<10>")
	)
	(segment
		(start 370.637816 -270.523462)
		(end 370.637054 -270.52397)
		(width 0.1143)
		(layer "In13.Cu")
		(net "P5E_CPU0_P2_TX_DN<10>")
	)
	(segment
		(start 370.630958 -270.527526)
		(end 370.626894 -270.529558)
		(width 0.1143)
		(layer "In13.Cu")
		(net "P5E_CPU0_P2_TX_DN<10>")
	)
	(segment
		(start 370.137182 -273.58086)
		(end 370.206778 -273.6215)
		(width 0.1143)
		(layer "In13.Cu")
		(net "P5E_CPU0_P2_TX_DN<10>")
	)
	(segment
		(start 370.134388 -288.158936)
		(end 370.207032 -288.201354)
		(width 0.1143)
		(layer "In13.Cu")
		(net "P5E_CPU0_P2_TX_DN<10>")
	)
	(segment
		(start 370.206778 -271.310608)
		(end 370.137182 -271.351248)
		(width 0.1143)
		(layer "In13.Cu")
		(net "P5E_CPU0_P2_TX_DN<10>")
	)
	(segment
		(start 370.160296 -282.67787)
		(end 370.136166 -282.69184)
		(width 0.1143)
		(layer "In13.Cu")
		(net "P5E_CPU0_P2_TX_DN<10>")
	)
	(segment
		(start 404.923244 -370.819426)
		(end 415.202878 -375.077736)
		(width 0.14224)
		(layer "In13.Cu")
		(net "P5E_CPU0_P2_TX_DN<10>")
	)
	(segment
		(start 370.170456 -282.672028)
		(end 370.168932 -282.67279)
		(width 0.1143)
		(layer "In13.Cu")
		(net "P5E_CPU0_P2_TX_DN<10>")
	)
	(segment
		(start 370.206778 -276.170644)
		(end 370.137182 -276.211284)
		(width 0.1143)
		(layer "In13.Cu")
		(net "P5E_CPU0_P2_TX_DN<10>")
	)
	(segment
		(start 370.606066 -295.45026)
		(end 370.637816 -295.468548)
		(width 0.1143)
		(layer "In13.Cu")
		(net "P5E_CPU0_P2_TX_DN<10>")
	)
	(segment
		(start 370.206778 -279.410668)
		(end 370.137182 -279.451308)
		(width 0.1143)
		(layer "In13.Cu")
		(net "P5E_CPU0_P2_TX_DN<10>")
	)
	(segment
		(start 417.147756 -378.54636)
		(end 417.26231 -378.54636)
		(width 0.14224)
		(layer "In13.Cu")
		(net "P5E_CPU0_P2_TX_DN<10>")
	)
	(segment
		(start 370.175282 -281.703018)
		(end 370.178838 -281.70505)
		(width 0.1143)
		(layer "In13.Cu")
		(net "P5E_CPU0_P2_TX_DN<10>")
	)
	(segment
		(start 370.97589 -298.14901)
		(end 397.39062 -361.892342)
		(width 0.14224)
		(layer "In13.Cu")
		(net "P5E_CPU0_P2_TX_DN<10>")
	)
	(segment
		(start 370.206778 -274.550632)
		(end 370.137182 -274.591272)
		(width 0.1143)
		(layer "In13.Cu")
		(net "P5E_CPU0_P2_TX_DN<10>")
	)
	(segment
		(start 370.965984 -296.463466)
		(end 370.965984 -296.491914)
		(width 0.1143)
		(layer "In13.Cu")
		(net "P5E_CPU0_P2_TX_DN<10>")
	)
	(segment
		(start 370.207032 -293.990522)
		(end 370.136166 -294.03167)
		(width 0.1143)
		(layer "In13.Cu")
		(net "P5E_CPU0_P2_TX_DN<10>")
	)
	(segment
		(start 370.17198 -293.040816)
		(end 370.172742 -293.041324)
		(width 0.1143)
		(layer "In13.Cu")
		(net "P5E_CPU0_P2_TX_DN<10>")
	)
	(segment
		(start 370.16436 -282.675584)
		(end 370.160296 -282.67787)
		(width 0.1143)
		(layer "In13.Cu")
		(net "P5E_CPU0_P2_TX_DN<10>")
	)
	(segment
		(start 370.160296 -285.917894)
		(end 370.136166 -285.931864)
		(width 0.1143)
		(layer "In13.Cu")
		(net "P5E_CPU0_P2_TX_DN<10>")
	)
	(segment
		(start 370.626894 -270.529558)
		(end 370.624862 -270.530828)
		(width 0.1143)
		(layer "In13.Cu")
		(net "P5E_CPU0_P2_TX_DN<10>")
	)
	(segment
		(start 370.640356 -295.470072)
		(end 370.641372 -295.47058)
		(width 0.1143)
		(layer "In13.Cu")
		(net "P5E_CPU0_P2_TX_DN<10>")
	)
	(segment
		(start 370.168932 -285.912814)
		(end 370.16436 -285.915608)
		(width 0.1143)
		(layer "In13.Cu")
		(net "P5E_CPU0_P2_TX_DN<10>")
	)
	(segment
		(start 370.136166 -291.40023)
		(end 370.207032 -291.441378)
		(width 0.1143)
		(layer "In13.Cu")
		(net "P5E_CPU0_P2_TX_DN<10>")
	)
	(segment
		(start 370.163598 -293.03599)
		(end 370.17198 -293.040816)
		(width 0.1143)
		(layer "In13.Cu")
		(net "P5E_CPU0_P2_TX_DN<10>")
	)
	(segment
		(start 416.275012 -377.99391)
		(end 416.600894 -378.319792)
		(width 0.14224)
		(layer "In13.Cu")
		(net "P5E_CPU0_P2_TX_DN<10>")
	)
	(segment
		(start 370.172742 -289.8013)
		(end 370.17452 -289.802316)
		(width 0.1143)
		(layer "In13.Cu")
		(net "P5E_CPU0_P2_TX_DN<10>")
	)
	(segment
		(start 370.136166 -284.920436)
		(end 370.207032 -284.961584)
		(width 0.1143)
		(layer "In13.Cu")
		(net "P5E_CPU0_P2_TX_DN<10>")
	)
	(segment
		(start 370.206778 -272.93062)
		(end 370.137182 -272.97126)
		(width 0.1143)
		(layer "In13.Cu")
		(net "P5E_CPU0_P2_TX_DN<10>")
	)
	(segment
		(start 370.175282 -289.802824)
		(end 370.178838 -289.804856)
		(width 0.1143)
		(layer "In13.Cu")
		(net "P5E_CPU0_P2_TX_DN<10>")
	)
	(segment
		(start 370.163598 -289.795966)
		(end 370.17198 -289.800792)
		(width 0.1143)
		(layer "In13.Cu")
		(net "P5E_CPU0_P2_TX_DN<10>")
	)
	(segment
		(start 417.93541 -382.0541)
		(end 418.22624 -382.34493)
		(width 0.14224)
		(layer "In13.Cu")
		(net "P5E_CPU0_P2_TX_DN<10>")
	)
	(segment
		(start 370.920264 -296.417746)
		(end 370.965984 -296.463466)
		(width 0.1143)
		(layer "In13.Cu")
		(net "P5E_CPU0_P2_TX_DN<10>")
	)
	(segment
		(start 370.137182 -280.060908)
		(end 370.206778 -280.101548)
		(width 0.1143)
		(layer "In13.Cu")
		(net "P5E_CPU0_P2_TX_DN<10>")
	)
	(segment
		(start 370.175282 -293.042848)
		(end 370.178838 -293.04488)
		(width 0.1143)
		(layer "In13.Cu")
		(net "P5E_CPU0_P2_TX_DN<10>")
	)
	(segment
		(start 370.16436 -284.295596)
		(end 370.160296 -284.297882)
		(width 0.1143)
		(layer "In13.Cu")
		(net "P5E_CPU0_P2_TX_DN<10>")
	)
	(segment
		(start 370.632228 -270.526764)
		(end 370.630958 -270.527526)
		(width 0.1143)
		(layer "In13.Cu")
		(net "P5E_CPU0_P2_TX_DN<10>")
	)
	(segment
		(start 370.207032 -289.130486)
		(end 370.170456 -289.151822)
		(width 0.1143)
		(layer "In13.Cu")
		(net "P5E_CPU0_P2_TX_DN<10>")
	)
	(segment
		(start 416.237674 -376.282204)
		(end 416.237674 -377.90374)
		(width 0.14224)
		(layer "In13.Cu")
		(net "P5E_CPU0_P2_TX_DN<10>")
	)
	(segment
		(start 370.136166 -293.020242)
		(end 370.163598 -293.03599)
		(width 0.1143)
		(layer "In13.Cu")
		(net "P5E_CPU0_P2_TX_DN<10>")
	)
	(segment
		(start 370.16436 -292.395402)
		(end 370.160296 -292.397688)
		(width 0.1143)
		(layer "In13.Cu")
		(net "P5E_CPU0_P2_TX_DN<10>")
	)
	(segment
		(start 370.136166 -283.300424)
		(end 370.207032 -283.341572)
		(width 0.1143)
		(layer "In13.Cu")
		(net "P5E_CPU0_P2_TX_DN<10>")
	)
	(segment
		(start 402.182838 -368.987832)
		(end 404.923244 -370.819426)
		(width 0.14224)
		(layer "In13.Cu")
		(net "P5E_CPU0_P2_TX_DN<10>")
	)
	(segment
		(start 370.168932 -282.67279)
		(end 370.16436 -282.675584)
		(width 0.1143)
		(layer "In13.Cu")
		(net "P5E_CPU0_P2_TX_DN<10>")
	)
	(segment
		(start 370.168932 -289.152584)
		(end 370.16436 -289.155378)
		(width 0.1143)
		(layer "In13.Cu")
		(net "P5E_CPU0_P2_TX_DN<10>")
	)
	(segment
		(start 370.163598 -294.656002)
		(end 370.17198 -294.660828)
		(width 0.1143)
		(layer "In13.Cu")
		(net "P5E_CPU0_P2_TX_DN<10>")
	)
	(segment
		(start 370.134388 -286.538924)
		(end 370.207032 -286.581342)
		(width 0.1143)
		(layer "In13.Cu")
		(net "P5E_CPU0_P2_TX_DN<10>")
	)
	(segment
		(start 370.137182 -275.200872)
		(end 370.206778 -275.241512)
		(width 0.1143)
		(layer "In13.Cu")
		(net "P5E_CPU0_P2_TX_DN<10>")
	)
	(segment
		(start 397.39062 -361.892342)
		(end 402.02993 -368.834924)
		(width 0.14224)
		(layer "In13.Cu")
		(net "P5E_CPU0_P2_TX_DN<10>")
	)
	(segment
		(start 370.170456 -290.771834)
		(end 370.168932 -290.772596)
		(width 0.1143)
		(layer "In13.Cu")
		(net "P5E_CPU0_P2_TX_DN<10>")
	)
	(segment
		(start 370.207032 -282.650692)
		(end 370.170456 -282.672028)
		(width 0.1143)
		(layer "In13.Cu")
		(net "P5E_CPU0_P2_TX_DN<10>")
	)
	(segment
		(start 370.17198 -289.800792)
		(end 370.172742 -289.8013)
		(width 0.1143)
		(layer "In13.Cu")
		(net "P5E_CPU0_P2_TX_DN<10>")
	)
	(segment
		(start 370.637054 -270.52397)
		(end 370.635784 -270.524732)
		(width 0.1143)
		(layer "In13.Cu")
		(net "P5E_CPU0_P2_TX_DN<10>")
	)
	(segment
		(start 370.163598 -281.69616)
		(end 370.17198 -281.700986)
		(width 0.1143)
		(layer "In13.Cu")
		(net "P5E_CPU0_P2_TX_DN<10>")
	)
	(segment
		(start 370.17452 -289.802316)
		(end 370.175282 -289.802824)
		(width 0.1143)
		(layer "In13.Cu")
		(net "P5E_CPU0_P2_TX_DN<10>")
	)
	(segment
		(start 370.207032 -292.37051)
		(end 370.170456 -292.391846)
		(width 0.1143)
		(layer "In13.Cu")
		(net "P5E_CPU0_P2_TX_DN<10>")
	)
	(segment
		(start 370.207032 -290.750498)
		(end 370.170456 -290.771834)
		(width 0.1143)
		(layer "In13.Cu")
		(net "P5E_CPU0_P2_TX_DN<10>")
	)
	(segment
		(start 370.17452 -293.04234)
		(end 370.175282 -293.042848)
		(width 0.1143)
		(layer "In13.Cu")
		(net "P5E_CPU0_P2_TX_DN<10>")
	)
	(segment
		(start 370.178838 -294.664892)
		(end 370.207032 -294.681402)
		(width 0.1143)
		(layer "In13.Cu")
		(net "P5E_CPU0_P2_TX_DN<10>")
	)
	(segment
		(start 370.16436 -285.915608)
		(end 370.160296 -285.917894)
		(width 0.1143)
		(layer "In13.Cu")
		(net "P5E_CPU0_P2_TX_DN<10>")
	)
	(segment
		(start 370.450364 -295.145968)
		(end 370.45011 -295.145968)
		(width 0.1143)
		(layer "In13.Cu")
		(net "P5E_CPU0_P2_TX_DN<10>")
	)
	(segment
		(start 370.920264 -295.955466)
		(end 370.920264 -296.417746)
		(width 0.1143)
		(layer "In13.Cu")
		(net "P5E_CPU0_P2_TX_DN<10>")
	)
	(segment
		(start 370.207032 -285.890716)
		(end 370.170456 -285.912052)
		(width 0.1143)
		(layer "In13.Cu")
		(net "P5E_CPU0_P2_TX_DN<10>")
	)
	(segment
		(start 370.170456 -284.29204)
		(end 370.168932 -284.292802)
		(width 0.1143)
		(layer "In13.Cu")
		(net "P5E_CPU0_P2_TX_DN<10>")
	)
	(segment
		(start 370.638832 -295.469056)
		(end 370.640356 -295.470072)
		(width 0.1143)
		(layer "In13.Cu")
		(net "P5E_CPU0_P2_TX_DN<10>")
	)
	(segment
		(start 370.635784 -270.524732)
		(end 370.63426 -270.525494)
		(width 0.1143)
		(layer "In13.Cu")
		(net "P5E_CPU0_P2_TX_DN<10>")
	)
	(segment
		(start 370.168932 -284.292802)
		(end 370.16436 -284.295596)
		(width 0.1143)
		(layer "In13.Cu")
		(net "P5E_CPU0_P2_TX_DN<10>")
	)
	(segment
		(start 370.624862 -270.530828)
		(end 370.606066 -270.54175)
		(width 0.1143)
		(layer "In13.Cu")
		(net "P5E_CPU0_P2_TX_DN<10>")
	)
	(segment
		(start 370.136166 -294.640254)
		(end 370.163598 -294.656002)
		(width 0.1143)
		(layer "In13.Cu")
		(net "P5E_CPU0_P2_TX_DN<10>")
	)
	(segment
		(start 370.206778 -277.790656)
		(end 370.137182 -277.831296)
		(width 0.1143)
		(layer "In13.Cu")
		(net "P5E_CPU0_P2_TX_DN<10>")
	)
	(segment
		(start 370.136166 -281.680412)
		(end 370.163598 -281.69616)
		(width 0.1143)
		(layer "In13.Cu")
		(net "P5E_CPU0_P2_TX_DN<10>")
	)
	(segment
		(start 417.55187 -378.666248)
		(end 417.815522 -378.9299)
		(width 0.14224)
		(layer "In13.Cu")
		(net "P5E_CPU0_P2_TX_DN<10>")
	)
	(segment
		(start 371.294914 -270.036036)
		(end 370.996972 -270.036036)
		(width 0.1143)
		(layer "In13.Cu")
		(net "P5E_CPU0_P2_TX_DN<10>")
	)
	(segment
		(start 370.204492 -287.512252)
		(end 370.136166 -287.551876)
		(width 0.1143)
		(layer "In13.Cu")
		(net "P5E_CPU0_P2_TX_DN<10>")
	)
	(segment
		(start 417.93541 -379.21946)
		(end 417.93541 -382.0541)
		(width 0.14224)
		(layer "In13.Cu")
		(net "P5E_CPU0_P2_TX_DN<10>")
	)
	(segment
		(start 370.641372 -295.47058)
		(end 370.676932 -295.491408)
		(width 0.1143)
		(layer "In13.Cu")
		(net "P5E_CPU0_P2_TX_DN<10>")
	)
	(segment
		(start 370.136166 -289.780218)
		(end 370.163598 -289.795966)
		(width 0.1143)
		(layer "In13.Cu")
		(net "P5E_CPU0_P2_TX_DN<10>")
	)
	(segment
		(start 370.637816 -295.468548)
		(end 370.638832 -295.469056)
		(width 0.1143)
		(layer "In13.Cu")
		(net "P5E_CPU0_P2_TX_DN<10>")
	)
	(segment
		(start 370.172742 -294.661336)
		(end 370.17452 -294.662352)
		(width 0.1143)
		(layer "In13.Cu")
		(net "P5E_CPU0_P2_TX_DN<10>")
	)
	(segment
		(start 370.170456 -285.912052)
		(end 370.168932 -285.912814)
		(width 0.1143)
		(layer "In13.Cu")
		(net "P5E_CPU0_P2_TX_DN<10>")
	)
	(arc
		(start 370.206778 -276.861524)
		(mid 370.450105 -277.32609)
		(end 370.206778 -277.790656)
		(width 0.1143)
		(layer "In13.Cu")
		(net "P5E_CPU0_P2_TX_DN<10>")
	)
	(arc
		(start 370.207032 -291.441378)
		(mid 370.450359 -291.905944)
		(end 370.207032 -292.37051)
		(width 0.1143)
		(layer "In13.Cu")
		(net "P5E_CPU0_P2_TX_DN<10>")
	)
	(arc
		(start 370.45011 -270.846042)
		(mid 370.385595 -271.108261)
		(end 370.206778 -271.310608)
		(width 0.1143)
		(layer "In13.Cu")
		(net "P5E_CPU0_P2_TX_DN<10>")
	)
	(arc
		(start 370.137182 -276.211284)
		(mid 369.980205 -276.516084)
		(end 370.137182 -276.820884)
		(width 0.1143)
		(layer "In13.Cu")
		(net "P5E_CPU0_P2_TX_DN<10>")
	)
	(arc
		(start 370.207032 -284.961584)
		(mid 370.450359 -285.42615)
		(end 370.207032 -285.890716)
		(width 0.1143)
		(layer "In13.Cu")
		(net "P5E_CPU0_P2_TX_DN<10>")
	)
	(arc
		(start 370.137182 -279.451308)
		(mid 369.980205 -279.756108)
		(end 370.137182 -280.060908)
		(width 0.1143)
		(layer "In13.Cu")
		(net "P5E_CPU0_P2_TX_DN<10>")
	)
	(arc
		(start 370.136166 -285.931864)
		(mid 370.02149 -286.065198)
		(end 369.98021 -286.236156)
		(width 0.1143)
		(layer "In13.Cu")
		(net "P5E_CPU0_P2_TX_DN<10>")
	)
	(arc
		(start 370.136166 -292.411658)
		(mid 369.980238 -292.71595)
		(end 370.136166 -293.020242)
		(width 0.1143)
		(layer "In13.Cu")
		(net "P5E_CPU0_P2_TX_DN<10>")
	)
	(arc
		(start 370.206778 -272.001488)
		(mid 370.450105 -272.466054)
		(end 370.206778 -272.93062)
		(width 0.1143)
		(layer "In13.Cu")
		(net "P5E_CPU0_P2_TX_DN<10>")
	)
	(arc
		(start 370.676932 -295.491408)
		(mid 370.735369 -295.537926)
		(end 370.787168 -295.591738)
		(width 0.1143)
		(layer "In13.Cu")
		(net "P5E_CPU0_P2_TX_DN<10>")
	)
	(arc
		(start 370.206778 -275.241512)
		(mid 370.450105 -275.706078)
		(end 370.206778 -276.170644)
		(width 0.1143)
		(layer "In13.Cu")
		(net "P5E_CPU0_P2_TX_DN<10>")
	)
	(arc
		(start 370.207032 -286.581342)
		(mid 370.450356 -287.047458)
		(end 370.204492 -287.512252)
		(width 0.1143)
		(layer "In13.Cu")
		(net "P5E_CPU0_P2_TX_DN<10>")
	)
	(arc
		(start 370.136166 -281.071828)
		(mid 369.980238 -281.37612)
		(end 370.136166 -281.680412)
		(width 0.1143)
		(layer "In13.Cu")
		(net "P5E_CPU0_P2_TX_DN<10>")
	)
	(arc
		(start 370.207032 -283.341572)
		(mid 370.450359 -283.806138)
		(end 370.207032 -284.270704)
		(width 0.1143)
		(layer "In13.Cu")
		(net "P5E_CPU0_P2_TX_DN<10>")
	)
	(arc
		(start 370.914168 -270.11884)
		(mid 370.91238 -270.130289)
		(end 370.910358 -270.1417)
		(width 0.1143)
		(layer "In13.Cu")
		(net "P5E_CPU0_P2_TX_DN<10>")
	)
	(arc
		(start 370.606066 -270.54175)
		(mid 370.49139 -270.675084)
		(end 370.45011 -270.846042)
		(width 0.1143)
		(layer "In13.Cu")
		(net "P5E_CPU0_P2_TX_DN<10>")
	)
	(arc
		(start 370.137182 -271.351248)
		(mid 369.980205 -271.656048)
		(end 370.137182 -271.960848)
		(width 0.1143)
		(layer "In13.Cu")
		(net "P5E_CPU0_P2_TX_DN<10>")
	)
	(arc
		(start 370.136166 -284.311852)
		(mid 369.980238 -284.616144)
		(end 370.136166 -284.920436)
		(width 0.1143)
		(layer "In13.Cu")
		(net "P5E_CPU0_P2_TX_DN<10>")
	)
	(arc
		(start 417.815522 -378.9299)
		(mid 417.904237 -379.062765)
		(end 417.93541 -379.21946)
		(width 0.14224)
		(layer "In13.Cu")
		(net "P5E_CPU0_P2_TX_DN<10>")
	)
	(arc
		(start 370.207032 -289.821366)
		(mid 370.450359 -290.285932)
		(end 370.207032 -290.750498)
		(width 0.1143)
		(layer "In13.Cu")
		(net "P5E_CPU0_P2_TX_DN<10>")
	)
	(arc
		(start 416.237674 -377.90374)
		(mid 416.24738 -377.952535)
		(end 416.275012 -377.99391)
		(width 0.14224)
		(layer "In13.Cu")
		(net "P5E_CPU0_P2_TX_DN<10>")
	)
	(arc
		(start 369.98021 -286.236156)
		(mid 370.020972 -286.40604)
		(end 370.134388 -286.538924)
		(width 0.1143)
		(layer "In13.Cu")
		(net "P5E_CPU0_P2_TX_DN<10>")
	)
	(arc
		(start 370.206778 -278.481536)
		(mid 370.450105 -278.946102)
		(end 370.206778 -279.410668)
		(width 0.1143)
		(layer "In13.Cu")
		(net "P5E_CPU0_P2_TX_DN<10>")
	)
	(arc
		(start 370.207032 -281.72156)
		(mid 370.450359 -282.186126)
		(end 370.207032 -282.650692)
		(width 0.1143)
		(layer "In13.Cu")
		(net "P5E_CPU0_P2_TX_DN<10>")
	)
	(arc
		(start 402.02993 -368.834924)
		(mid 402.098858 -368.918904)
		(end 402.182838 -368.987832)
		(width 0.14224)
		(layer "In13.Cu")
		(net "P5E_CPU0_P2_TX_DN<10>")
	)
	(arc
		(start 416.117786 -375.992644)
		(mid 416.206501 -376.125509)
		(end 416.237674 -376.282204)
		(width 0.14224)
		(layer "In13.Cu")
		(net "P5E_CPU0_P2_TX_DN<10>")
	)
	(arc
		(start 370.207032 -288.201354)
		(mid 370.450359 -288.66592)
		(end 370.207032 -289.130486)
		(width 0.1143)
		(layer "In13.Cu")
		(net "P5E_CPU0_P2_TX_DN<10>")
	)
	(arc
		(start 370.910358 -270.1417)
		(mid 370.828925 -270.344098)
		(end 370.676932 -270.500602)
		(width 0.1143)
		(layer "In13.Cu")
		(net "P5E_CPU0_P2_TX_DN<10>")
	)
	(arc
		(start 370.137182 -274.591272)
		(mid 369.980205 -274.896072)
		(end 370.137182 -275.200872)
		(width 0.1143)
		(layer "In13.Cu")
		(net "P5E_CPU0_P2_TX_DN<10>")
	)
	(arc
		(start 370.136166 -289.171634)
		(mid 369.980238 -289.475926)
		(end 370.136166 -289.780218)
		(width 0.1143)
		(layer "In13.Cu")
		(net "P5E_CPU0_P2_TX_DN<10>")
	)
	(arc
		(start 370.137182 -277.831296)
		(mid 369.980205 -278.136096)
		(end 370.137182 -278.440896)
		(width 0.1143)
		(layer "In13.Cu")
		(net "P5E_CPU0_P2_TX_DN<10>")
	)
	(arc
		(start 370.136166 -294.03167)
		(mid 369.980238 -294.335962)
		(end 370.136166 -294.640254)
		(width 0.1143)
		(layer "In13.Cu")
		(net "P5E_CPU0_P2_TX_DN<10>")
	)
	(arc
		(start 370.206778 -280.101548)
		(mid 370.450105 -280.566114)
		(end 370.206778 -281.03068)
		(width 0.1143)
		(layer "In13.Cu")
		(net "P5E_CPU0_P2_TX_DN<10>")
	)
	(arc
		(start 370.786914 -295.591738)
		(mid 370.885734 -295.761815)
		(end 370.920264 -295.955466)
		(width 0.1143)
		(layer "In13.Cu")
		(net "P5E_CPU0_P2_TX_DN<10>")
	)
	(arc
		(start 370.137182 -272.97126)
		(mid 369.980205 -273.27606)
		(end 370.137182 -273.58086)
		(width 0.1143)
		(layer "In13.Cu")
		(net "P5E_CPU0_P2_TX_DN<10>")
	)
	(arc
		(start 370.207032 -293.06139)
		(mid 370.450359 -293.525956)
		(end 370.207032 -293.990522)
		(width 0.1143)
		(layer "In13.Cu")
		(net "P5E_CPU0_P2_TX_DN<10>")
	)
	(arc
		(start 370.136166 -287.551876)
		(mid 370.02149 -287.68521)
		(end 369.98021 -287.856168)
		(width 0.1143)
		(layer "In13.Cu")
		(net "P5E_CPU0_P2_TX_DN<10>")
	)
	(arc
		(start 370.45011 -295.145968)
		(mid 370.491365 -295.316939)
		(end 370.606066 -295.45026)
		(width 0.1143)
		(layer "In13.Cu")
		(net "P5E_CPU0_P2_TX_DN<10>")
	)
	(arc
		(start 416.600894 -378.319792)
		(mid 416.851782 -378.487493)
		(end 417.147756 -378.54636)
		(width 0.14224)
		(layer "In13.Cu")
		(net "P5E_CPU0_P2_TX_DN<10>")
	)
	(arc
		(start 369.98021 -287.856168)
		(mid 370.020972 -288.026052)
		(end 370.134388 -288.158936)
		(width 0.1143)
		(layer "In13.Cu")
		(net "P5E_CPU0_P2_TX_DN<10>")
	)
	(arc
		(start 370.207032 -294.681402)
		(mid 370.385845 -294.883752)
		(end 370.450364 -295.145968)
		(width 0.1143)
		(layer "In13.Cu")
		(net "P5E_CPU0_P2_TX_DN<10>")
	)
	(arc
		(start 417.26231 -378.54636)
		(mid 417.419013 -378.577512)
		(end 417.55187 -378.666248)
		(width 0.14224)
		(layer "In13.Cu")
		(net "P5E_CPU0_P2_TX_DN<10>")
	)
	(arc
		(start 370.206778 -273.6215)
		(mid 370.450105 -274.086066)
		(end 370.206778 -274.550632)
		(width 0.1143)
		(layer "In13.Cu")
		(net "P5E_CPU0_P2_TX_DN<10>")
	)
	(arc
		(start 370.136166 -282.69184)
		(mid 369.980238 -282.996132)
		(end 370.136166 -283.300424)
		(width 0.1143)
		(layer "In13.Cu")
		(net "P5E_CPU0_P2_TX_DN<10>")
	)
	(arc
		(start 370.965984 -298.100242)
		(mid 370.968539 -298.125112)
		(end 370.97589 -298.14901)
		(width 0.14224)
		(layer "In13.Cu")
		(net "P5E_CPU0_P2_TX_DN<10>")
	)
	(arc
		(start 370.136166 -290.791646)
		(mid 369.980238 -291.095938)
		(end 370.136166 -291.40023)
		(width 0.1143)
		(layer "In13.Cu")
		(net "P5E_CPU0_P2_TX_DN<10>")
	)
	(segment
		(start 362.837984 -268.960092)
		(end 363.304836 -269.22603)
		(width 0.12954)
		(layer "F.Cu")
		(net "P5E_CPU0_P2_TX_DN<0>")
	)
	(segment
		(start 398.032478 -390.15797)
		(end 398.328388 -389.86206)
		(width 0.12954)
		(layer "F.Cu")
		(net "P5E_CPU0_P2_TX_DN<0>")
	)
	(segment
		(start 397.058388 -389.88746)
		(end 397.328898 -390.15797)
		(width 0.12954)
		(layer "F.Cu")
		(net "P5E_CPU0_P2_TX_DN<0>")
	)
	(segment
		(start 397.328898 -390.15797)
		(end 398.032478 -390.15797)
		(width 0.12954)
		(layer "F.Cu")
		(net "P5E_CPU0_P2_TX_DN<0>")
	)
	(segment
		(start 395.906752 -379.294898)
		(end 396.043912 -379.432058)
		(width 0.14224)
		(layer "In13.Cu")
		(net "P5E_CPU0_P2_TX_DN<0>")
	)
	(segment
		(start 395.906752 -383.379218)
		(end 395.906752 -390.05129)
		(width 0.14224)
		(layer "In13.Cu")
		(net "P5E_CPU0_P2_TX_DN<0>")
	)
	(segment
		(start 362.651548 -269.71117)
		(end 362.650532 -269.711678)
		(width 0.1143)
		(layer "In13.Cu")
		(net "P5E_CPU0_P2_TX_DN<0>")
	)
	(segment
		(start 396.043912 -380.986538)
		(end 395.906752 -381.123698)
		(width 0.14224)
		(layer "In13.Cu")
		(net "P5E_CPU0_P2_TX_DN<0>")
	)
	(segment
		(start 361.7468 -271.310608)
		(end 361.692444 -271.342358)
		(width 0.1143)
		(layer "In13.Cu")
		(net "P5E_CPU0_P2_TX_DN<0>")
	)
	(segment
		(start 396.043912 -379.858778)
		(end 395.906752 -379.995938)
		(width 0.14224)
		(layer "In13.Cu")
		(net "P5E_CPU0_P2_TX_DN<0>")
	)
	(segment
		(start 395.906752 -390.05129)
		(end 396.033752 -390.17829)
		(width 0.14224)
		(layer "In13.Cu")
		(net "P5E_CPU0_P2_TX_DN<0>")
	)
	(segment
		(start 395.906752 -380.422658)
		(end 396.043912 -380.559818)
		(width 0.14224)
		(layer "In13.Cu")
		(net "P5E_CPU0_P2_TX_DN<0>")
	)
	(segment
		(start 393.260072 -374.128792)
		(end 395.793214 -376.923554)
		(width 0.14224)
		(layer "In13.Cu")
		(net "P5E_CPU0_P2_TX_DN<0>")
	)
	(segment
		(start 362.147612 -270.540988)
		(end 362.146088 -270.54175)
		(width 0.1143)
		(layer "In13.Cu")
		(net "P5E_CPU0_P2_TX_DN<0>")
	)
	(segment
		(start 362.65231 -269.710662)
		(end 362.651548 -269.71117)
		(width 0.1143)
		(layer "In13.Cu")
		(net "P5E_CPU0_P2_TX_DN<0>")
	)
	(segment
		(start 360.95178 -295.2496)
		(end 360.95178 -295.938702)
		(width 0.14224)
		(layer "In13.Cu")
		(net "P5E_CPU0_P2_TX_DN<0>")
	)
	(segment
		(start 396.043912 -379.432058)
		(end 396.043912 -379.858778)
		(width 0.14224)
		(layer "In13.Cu")
		(net "P5E_CPU0_P2_TX_DN<0>")
	)
	(segment
		(start 362.177838 -270.523462)
		(end 362.147612 -270.540988)
		(width 0.1143)
		(layer "In13.Cu")
		(net "P5E_CPU0_P2_TX_DN<0>")
	)
	(segment
		(start 396.033752 -390.17829)
		(end 396.767558 -390.17829)
		(width 0.14224)
		(layer "In13.Cu")
		(net "P5E_CPU0_P2_TX_DN<0>")
	)
	(segment
		(start 360.95178 -295.938702)
		(end 361.46994 -296.456862)
		(width 0.14224)
		(layer "In13.Cu")
		(net "P5E_CPU0_P2_TX_DN<0>")
	)
	(segment
		(start 360.90606 -295.175432)
		(end 360.95178 -295.221152)
		(width 0.1143)
		(layer "In13.Cu")
		(net "P5E_CPU0_P2_TX_DN<0>")
	)
	(segment
		(start 360.90606 -273.100546)
		(end 360.90606 -295.175432)
		(width 0.1143)
		(layer "In13.Cu")
		(net "P5E_CPU0_P2_TX_DN<0>")
	)
	(segment
		(start 396.043912 -381.687578)
		(end 396.043912 -382.114298)
		(width 0.14224)
		(layer "In13.Cu")
		(net "P5E_CPU0_P2_TX_DN<0>")
	)
	(segment
		(start 362.182918 -270.520414)
		(end 362.179362 -270.522446)
		(width 0.1143)
		(layer "In13.Cu")
		(net "P5E_CPU0_P2_TX_DN<0>")
	)
	(segment
		(start 395.906752 -381.550418)
		(end 396.043912 -381.687578)
		(width 0.14224)
		(layer "In13.Cu")
		(net "P5E_CPU0_P2_TX_DN<0>")
	)
	(segment
		(start 395.906752 -379.995938)
		(end 395.906752 -380.422658)
		(width 0.14224)
		(layer "In13.Cu")
		(net "P5E_CPU0_P2_TX_DN<0>")
	)
	(segment
		(start 395.906752 -382.251458)
		(end 395.906752 -382.678178)
		(width 0.14224)
		(layer "In13.Cu")
		(net "P5E_CPU0_P2_TX_DN<0>")
	)
	(segment
		(start 363.304836 -269.22603)
		(end 363.006894 -269.22603)
		(width 0.1143)
		(layer "In13.Cu")
		(net "P5E_CPU0_P2_TX_DN<0>")
	)
	(segment
		(start 362.183934 -270.519906)
		(end 362.182918 -270.520414)
		(width 0.1143)
		(layer "In13.Cu")
		(net "P5E_CPU0_P2_TX_DN<0>")
	)
	(segment
		(start 396.767558 -390.17829)
		(end 397.058388 -389.88746)
		(width 0.14224)
		(layer "In13.Cu")
		(net "P5E_CPU0_P2_TX_DN<0>")
	)
	(segment
		(start 360.95178 -295.221152)
		(end 360.95178 -295.2496)
		(width 0.1143)
		(layer "In13.Cu")
		(net "P5E_CPU0_P2_TX_DN<0>")
	)
	(segment
		(start 396.043912 -382.114298)
		(end 395.906752 -382.251458)
		(width 0.14224)
		(layer "In13.Cu")
		(net "P5E_CPU0_P2_TX_DN<0>")
	)
	(segment
		(start 396.043912 -382.815338)
		(end 396.043912 -383.242058)
		(width 0.14224)
		(layer "In13.Cu")
		(net "P5E_CPU0_P2_TX_DN<0>")
	)
	(segment
		(start 362.179362 -270.522446)
		(end 362.177838 -270.523462)
		(width 0.1143)
		(layer "In13.Cu")
		(net "P5E_CPU0_P2_TX_DN<0>")
	)
	(segment
		(start 362.648246 -269.713202)
		(end 362.645452 -269.714726)
		(width 0.1143)
		(layer "In13.Cu")
		(net "P5E_CPU0_P2_TX_DN<0>")
	)
	(segment
		(start 395.906752 -377.206764)
		(end 395.906752 -379.294898)
		(width 0.14224)
		(layer "In13.Cu")
		(net "P5E_CPU0_P2_TX_DN<0>")
	)
	(segment
		(start 362.686854 -269.690596)
		(end 362.65231 -269.710662)
		(width 0.1143)
		(layer "In13.Cu")
		(net "P5E_CPU0_P2_TX_DN<0>")
	)
	(segment
		(start 389.372094 -368.313208)
		(end 393.260072 -374.128792)
		(width 0.14224)
		(layer "In13.Cu")
		(net "P5E_CPU0_P2_TX_DN<0>")
	)
	(segment
		(start 361.46994 -296.456862)
		(end 361.46994 -300.900592)
		(width 0.14224)
		(layer "In13.Cu")
		(net "P5E_CPU0_P2_TX_DN<0>")
	)
	(segment
		(start 361.692444 -271.342358)
		(end 361.59313 -271.441672)
		(width 0.1143)
		(layer "In13.Cu")
		(net "P5E_CPU0_P2_TX_DN<0>")
	)
	(segment
		(start 363.006894 -269.22603)
		(end 362.92409 -269.308834)
		(width 0.1143)
		(layer "In13.Cu")
		(net "P5E_CPU0_P2_TX_DN<0>")
	)
	(segment
		(start 361.497626 -301.039784)
		(end 389.372094 -368.313208)
		(width 0.14224)
		(layer "In13.Cu")
		(net "P5E_CPU0_P2_TX_DN<0>")
	)
	(segment
		(start 362.650532 -269.711678)
		(end 362.648246 -269.713202)
		(width 0.1143)
		(layer "In13.Cu")
		(net "P5E_CPU0_P2_TX_DN<0>")
	)
	(segment
		(start 396.043912 -380.559818)
		(end 396.043912 -380.986538)
		(width 0.14224)
		(layer "In13.Cu")
		(net "P5E_CPU0_P2_TX_DN<0>")
	)
	(segment
		(start 395.906752 -381.123698)
		(end 395.906752 -381.550418)
		(width 0.14224)
		(layer "In13.Cu")
		(net "P5E_CPU0_P2_TX_DN<0>")
	)
	(segment
		(start 395.906752 -382.678178)
		(end 396.043912 -382.815338)
		(width 0.14224)
		(layer "In13.Cu")
		(net "P5E_CPU0_P2_TX_DN<0>")
	)
	(segment
		(start 396.043912 -383.242058)
		(end 395.906752 -383.379218)
		(width 0.14224)
		(layer "In13.Cu")
		(net "P5E_CPU0_P2_TX_DN<0>")
	)
	(arc
		(start 362.458762 -270.03883)
		(mid 362.385272 -270.315887)
		(end 362.183934 -270.519906)
		(width 0.1143)
		(layer "In13.Cu")
		(net "P5E_CPU0_P2_TX_DN<0>")
	)
	(arc
		(start 361.46994 -300.900592)
		(mid 361.476929 -300.971551)
		(end 361.497626 -301.039784)
		(width 0.14224)
		(layer "In13.Cu")
		(net "P5E_CPU0_P2_TX_DN<0>")
	)
	(arc
		(start 395.793214 -376.923554)
		(mid 395.877337 -377.05419)
		(end 395.906752 -377.206764)
		(width 0.14224)
		(layer "In13.Cu")
		(net "P5E_CPU0_P2_TX_DN<0>")
	)
	(arc
		(start 362.92028 -269.331694)
		(mid 362.838847 -269.534092)
		(end 362.686854 -269.690596)
		(width 0.1143)
		(layer "In13.Cu")
		(net "P5E_CPU0_P2_TX_DN<0>")
	)
	(arc
		(start 362.146088 -270.54175)
		(mid 362.031412 -270.675084)
		(end 361.990132 -270.846042)
		(width 0.1143)
		(layer "In13.Cu")
		(net "P5E_CPU0_P2_TX_DN<0>")
	)
	(arc
		(start 362.645452 -269.714726)
		(mid 362.508763 -269.851813)
		(end 362.458762 -270.03883)
		(width 0.1143)
		(layer "In13.Cu")
		(net "P5E_CPU0_P2_TX_DN<0>")
	)
	(arc
		(start 361.990132 -270.846042)
		(mid 361.925617 -271.108261)
		(end 361.7468 -271.310608)
		(width 0.1143)
		(layer "In13.Cu")
		(net "P5E_CPU0_P2_TX_DN<0>")
	)
	(arc
		(start 362.92409 -269.308834)
		(mid 362.922302 -269.320283)
		(end 362.92028 -269.331694)
		(width 0.1143)
		(layer "In13.Cu")
		(net "P5E_CPU0_P2_TX_DN<0>")
	)
	(arc
		(start 361.59313 -271.441672)
		(mid 361.084634 -272.202784)
		(end 360.90606 -273.100546)
		(width 0.1143)
		(layer "In13.Cu")
		(net "P5E_CPU0_P2_TX_DN<0>")
	)
	(segment
		(start 414.098232 -394.385292)
		(end 414.618932 -394.385292)
		(width 0.127)
		(layer "F.Cu")
		(net "P5E_CPU0_P2_RX_DP<9>")
	)
	(segment
		(start 370.828062 -281.110182)
		(end 371.294914 -281.37612)
		(width 0.12954)
		(layer "F.Cu")
		(net "P5E_CPU0_P2_RX_DP<9>")
	)
	(segment
		(start 369.736878 -285.77159)
		(end 369.666012 -285.730442)
		(width 0.1143)
		(layer "In6.Cu")
		(net "P5E_CPU0_P2_RX_DP<9>")
	)
	(segment
		(start 369.196112 -289.171634)
		(end 369.254024 -289.137852)
		(width 0.1143)
		(layer "In6.Cu")
		(net "P5E_CPU0_P2_RX_DP<9>")
	)
	(segment
		(start 369.224306 -289.796474)
		(end 369.22329 -289.795966)
		(width 0.1143)
		(layer "In6.Cu")
		(net "P5E_CPU0_P2_RX_DP<9>")
	)
	(segment
		(start 369.226084 -294.014398)
		(end 369.2271 -294.01389)
		(width 0.1143)
		(layer "In6.Cu")
		(net "P5E_CPU0_P2_RX_DP<9>")
	)
	(segment
		(start 370.637054 -281.864054)
		(end 370.637816 -281.863546)
		(width 0.1143)
		(layer "In6.Cu")
		(net "P5E_CPU0_P2_RX_DP<9>")
	)
	(segment
		(start 380.504446 -312.163714)
		(end 380.041912 -311.471564)
		(width 0.14224)
		(layer "In6.Cu")
		(net "P5E_CPU0_P2_RX_DP<9>")
	)
	(segment
		(start 369.221766 -294.016938)
		(end 369.222528 -294.01643)
		(width 0.1143)
		(layer "In6.Cu")
		(net "P5E_CPU0_P2_RX_DP<9>")
	)
	(segment
		(start 369.226846 -290.773866)
		(end 369.229386 -290.772596)
		(width 0.1143)
		(layer "In6.Cu")
		(net "P5E_CPU0_P2_RX_DP<9>")
	)
	(segment
		(start 369.219988 -294.017954)
		(end 369.22075 -294.017446)
		(width 0.1143)
		(layer "In6.Cu")
		(net "P5E_CPU0_P2_RX_DP<9>")
	)
	(segment
		(start 369.264184 -288.199576)
		(end 369.256818 -288.195512)
		(width 0.1143)
		(layer "In6.Cu")
		(net "P5E_CPU0_P2_RX_DP<9>")
	)
	(segment
		(start 369.223544 -294.015922)
		(end 369.224306 -294.015414)
		(width 0.1143)
		(layer "In6.Cu")
		(net "P5E_CPU0_P2_RX_DP<9>")
	)
	(segment
		(start 369.221512 -289.79495)
		(end 369.196112 -289.780218)
		(width 0.1143)
		(layer "In6.Cu")
		(net "P5E_CPU0_P2_RX_DP<9>")
	)
	(segment
		(start 414.663382 -392.7348)
		(end 414.968182 -392.430254)
		(width 0.14224)
		(layer "In6.Cu")
		(net "P5E_CPU0_P2_RX_DP<9>")
	)
	(segment
		(start 415.468816 -381.294132)
		(end 416.06851 -379.846332)
		(width 0.14224)
		(layer "In6.Cu")
		(net "P5E_CPU0_P2_RX_DP<9>")
	)
	(segment
		(start 369.980718 -296.007282)
		(end 369.98021 -296.006774)
		(width 0.1143)
		(layer "In6.Cu")
		(net "P5E_CPU0_P2_RX_DP<9>")
	)
	(segment
		(start 369.26901 -294.682164)
		(end 369.267994 -294.680132)
		(width 0.1143)
		(layer "In6.Cu")
		(net "P5E_CPU0_P2_RX_DP<9>")
	)
	(segment
		(start 380.041912 -311.471564)
		(end 373.739918 -303.79289)
		(width 0.14224)
		(layer "In6.Cu")
		(net "P5E_CPU0_P2_RX_DP<9>")
	)
	(segment
		(start 370.631466 -281.867102)
		(end 370.633498 -281.866086)
		(width 0.1143)
		(layer "In6.Cu")
		(net "P5E_CPU0_P2_RX_DP<9>")
	)
	(segment
		(start 370.606066 -281.881834)
		(end 370.631466 -281.867102)
		(width 0.1143)
		(layer "In6.Cu")
		(net "P5E_CPU0_P2_RX_DP<9>")
	)
	(segment
		(start 370.026438 -296.325036)
		(end 369.980718 -296.279316)
		(width 0.1143)
		(layer "In6.Cu")
		(net "P5E_CPU0_P2_RX_DP<9>")
	)
	(segment
		(start 414.44418 -374.624092)
		(end 408.727402 -373.194326)
		(width 0.14224)
		(layer "In6.Cu")
		(net "P5E_CPU0_P2_RX_DP<9>")
	)
	(segment
		(start 414.660334 -393.113006)
		(end 414.663382 -392.7348)
		(width 0.14224)
		(layer "In6.Cu")
		(net "P5E_CPU0_P2_RX_DP<9>")
	)
	(segment
		(start 414.968182 -392.430254)
		(end 414.968182 -387.82752)
		(width 0.14224)
		(layer "In6.Cu")
		(net "P5E_CPU0_P2_RX_DP<9>")
	)
	(segment
		(start 415.99358 -376.090688)
		(end 414.634426 -374.731534)
		(width 0.14224)
		(layer "In6.Cu")
		(net "P5E_CPU0_P2_RX_DP<9>")
	)
	(segment
		(start 369.222528 -294.01643)
		(end 369.223544 -294.015922)
		(width 0.1143)
		(layer "In6.Cu")
		(net "P5E_CPU0_P2_RX_DP<9>")
	)
	(segment
		(start 370.996972 -281.37612)
		(end 371.294914 -281.37612)
		(width 0.1143)
		(layer "In6.Cu")
		(net "P5E_CPU0_P2_RX_DP<9>")
	)
	(segment
		(start 370.63426 -281.865578)
		(end 370.637054 -281.864054)
		(width 0.1143)
		(layer "In6.Cu")
		(net "P5E_CPU0_P2_RX_DP<9>")
	)
	(segment
		(start 369.697 -283.484066)
		(end 369.698778 -283.48305)
		(width 0.1143)
		(layer "In6.Cu")
		(net "P5E_CPU0_P2_RX_DP<9>")
	)
	(segment
		(start 398.367504 -366.49787)
		(end 391.350246 -349.556578)
		(width 0.14224)
		(layer "In6.Cu")
		(net "P5E_CPU0_P2_RX_DP<9>")
	)
	(segment
		(start 370.995956 -299.686218)
		(end 370.026438 -297.345608)
		(width 0.14224)
		(layer "In6.Cu")
		(net "P5E_CPU0_P2_RX_DP<9>")
	)
	(segment
		(start 369.22075 -294.017446)
		(end 369.221766 -294.016938)
		(width 0.1143)
		(layer "In6.Cu")
		(net "P5E_CPU0_P2_RX_DP<9>")
	)
	(segment
		(start 369.196112 -292.411658)
		(end 369.248436 -292.381432)
		(width 0.1143)
		(layer "In6.Cu")
		(net "P5E_CPU0_P2_RX_DP<9>")
	)
	(segment
		(start 414.888172 -393.930632)
		(end 414.97631 -393.842494)
		(width 0.14224)
		(layer "In6.Cu")
		(net "P5E_CPU0_P2_RX_DP<9>")
	)
	(segment
		(start 369.216178 -294.019986)
		(end 369.21821 -294.01897)
		(width 0.1143)
		(layer "In6.Cu")
		(net "P5E_CPU0_P2_RX_DP<9>")
	)
	(segment
		(start 414.97631 -393.842494)
		(end 414.97631 -393.428982)
		(width 0.14224)
		(layer "In6.Cu")
		(net "P5E_CPU0_P2_RX_DP<9>")
	)
	(segment
		(start 369.980718 -296.279316)
		(end 369.980718 -296.007282)
		(width 0.1143)
		(layer "In6.Cu")
		(net "P5E_CPU0_P2_RX_DP<9>")
	)
	(segment
		(start 369.196112 -287.551876)
		(end 369.262406 -287.513268)
		(width 0.1143)
		(layer "In6.Cu")
		(net "P5E_CPU0_P2_RX_DP<9>")
	)
	(segment
		(start 369.736878 -295.491408)
		(end 369.664996 -295.449498)
		(width 0.1143)
		(layer "In6.Cu")
		(net "P5E_CPU0_P2_RX_DP<9>")
	)
	(segment
		(start 369.196874 -293.020496)
		(end 369.196874 -293.02075)
		(width 0.1143)
		(layer "In6.Cu")
		(net "P5E_CPU0_P2_RX_DP<9>")
	)
	(segment
		(start 369.21821 -294.01897)
		(end 369.218972 -294.018462)
		(width 0.1143)
		(layer "In6.Cu")
		(net "P5E_CPU0_P2_RX_DP<9>")
	)
	(segment
		(start 369.225322 -294.014906)
		(end 369.226084 -294.014398)
		(width 0.1143)
		(layer "In6.Cu")
		(net "P5E_CPU0_P2_RX_DP<9>")
	)
	(segment
		(start 369.196112 -294.03167)
		(end 369.216178 -294.019986)
		(width 0.1143)
		(layer "In6.Cu")
		(net "P5E_CPU0_P2_RX_DP<9>")
	)
	(segment
		(start 370.638832 -281.863038)
		(end 370.640356 -281.862022)
		(width 0.1143)
		(layer "In6.Cu")
		(net "P5E_CPU0_P2_RX_DP<9>")
	)
	(segment
		(start 369.22837 -293.03853)
		(end 369.228116 -293.038784)
		(width 0.1143)
		(layer "In6.Cu")
		(net "P5E_CPU0_P2_RX_DP<9>")
	)
	(segment
		(start 369.224306 -294.015414)
		(end 369.225322 -294.014906)
		(width 0.1143)
		(layer "In6.Cu")
		(net "P5E_CPU0_P2_RX_DP<9>")
	)
	(segment
		(start 369.218972 -294.018462)
		(end 369.219988 -294.017954)
		(width 0.1143)
		(layer "In6.Cu")
		(net "P5E_CPU0_P2_RX_DP<9>")
	)
	(segment
		(start 369.226846 -289.797998)
		(end 369.226084 -289.79749)
		(width 0.1143)
		(layer "In6.Cu")
		(net "P5E_CPU0_P2_RX_DP<9>")
	)
	(segment
		(start 369.196112 -284.311852)
		(end 369.266216 -284.271466)
		(width 0.1143)
		(layer "In6.Cu")
		(net "P5E_CPU0_P2_RX_DP<9>")
	)
	(segment
		(start 369.196112 -290.791646)
		(end 369.225068 -290.774882)
		(width 0.1143)
		(layer "In6.Cu")
		(net "P5E_CPU0_P2_RX_DP<9>")
	)
	(segment
		(start 370.914168 -281.458924)
		(end 370.996972 -281.37612)
		(width 0.1143)
		(layer "In6.Cu")
		(net "P5E_CPU0_P2_RX_DP<9>")
	)
	(segment
		(start 391.207498 -349.086678)
		(end 389.831834 -342.170004)
		(width 0.14224)
		(layer "In6.Cu")
		(net "P5E_CPU0_P2_RX_DP<9>")
	)
	(segment
		(start 414.713928 -394.031216)
		(end 414.888172 -393.930632)
		(width 0.14224)
		(layer "In6.Cu")
		(net "P5E_CPU0_P2_RX_DP<9>")
	)
	(segment
		(start 369.510056 -295.149524)
		(end 369.510056 -295.142666)
		(width 0.1143)
		(layer "In6.Cu")
		(net "P5E_CPU0_P2_RX_DP<9>")
	)
	(segment
		(start 386.66293 -323.6849)
		(end 380.504446 -312.163714)
		(width 0.14224)
		(layer "In6.Cu")
		(net "P5E_CPU0_P2_RX_DP<9>")
	)
	(segment
		(start 414.968182 -387.82752)
		(end 415.238692 -382.318514)
		(width 0.14224)
		(layer "In6.Cu")
		(net "P5E_CPU0_P2_RX_DP<9>")
	)
	(segment
		(start 369.248436 -292.381432)
		(end 369.249198 -292.380924)
		(width 0.1143)
		(layer "In6.Cu")
		(net "P5E_CPU0_P2_RX_DP<9>")
	)
	(segment
		(start 400.213322 -368.35715)
		(end 398.39519 -366.539018)
		(width 0.14224)
		(layer "In6.Cu")
		(net "P5E_CPU0_P2_RX_DP<9>")
	)
	(segment
		(start 370.137182 -282.691332)
		(end 370.206778 -282.650692)
		(width 0.1143)
		(layer "In6.Cu")
		(net "P5E_CPU0_P2_RX_DP<9>")
	)
	(segment
		(start 369.225068 -290.774882)
		(end 369.226846 -290.773866)
		(width 0.1143)
		(layer "In6.Cu")
		(net "P5E_CPU0_P2_RX_DP<9>")
	)
	(segment
		(start 370.633498 -281.866086)
		(end 370.63426 -281.865578)
		(width 0.1143)
		(layer "In6.Cu")
		(net "P5E_CPU0_P2_RX_DP<9>")
	)
	(segment
		(start 369.196874 -293.02075)
		(end 369.196112 -293.020242)
		(width 0.1143)
		(layer "In6.Cu")
		(net "P5E_CPU0_P2_RX_DP<9>")
	)
	(segment
		(start 369.229386 -289.799268)
		(end 369.226846 -289.797998)
		(width 0.1143)
		(layer "In6.Cu")
		(net "P5E_CPU0_P2_RX_DP<9>")
	)
	(segment
		(start 369.98021 -296.006774)
		(end 369.98021 -295.955974)
		(width 0.1143)
		(layer "In6.Cu")
		(net "P5E_CPU0_P2_RX_DP<9>")
	)
	(segment
		(start 369.254024 -289.137852)
		(end 369.264184 -289.132264)
		(width 0.1143)
		(layer "In6.Cu")
		(net "P5E_CPU0_P2_RX_DP<9>")
	)
	(segment
		(start 389.33247 -337.107784)
		(end 386.66293 -323.6849)
		(width 0.14224)
		(layer "In6.Cu")
		(net "P5E_CPU0_P2_RX_DP<9>")
	)
	(segment
		(start 414.618932 -394.385292)
		(end 414.713928 -394.031216)
		(width 0.14224)
		(layer "In6.Cu")
		(net "P5E_CPU0_P2_RX_DP<9>")
	)
	(segment
		(start 369.228116 -293.038784)
		(end 369.196874 -293.020496)
		(width 0.1143)
		(layer "In6.Cu")
		(net "P5E_CPU0_P2_RX_DP<9>")
	)
	(segment
		(start 369.256818 -288.195512)
		(end 369.194334 -288.158936)
		(width 0.1143)
		(layer "In6.Cu")
		(net "P5E_CPU0_P2_RX_DP<9>")
	)
	(segment
		(start 369.698778 -283.48305)
		(end 369.700302 -283.482034)
		(width 0.1143)
		(layer "In6.Cu")
		(net "P5E_CPU0_P2_RX_DP<9>")
	)
	(segment
		(start 370.026438 -297.345608)
		(end 370.026438 -296.353484)
		(width 0.14224)
		(layer "In6.Cu")
		(net "P5E_CPU0_P2_RX_DP<9>")
	)
	(segment
		(start 370.637816 -281.863546)
		(end 370.638832 -281.863038)
		(width 0.1143)
		(layer "In6.Cu")
		(net "P5E_CPU0_P2_RX_DP<9>")
	)
	(segment
		(start 416.235388 -379.00737)
		(end 416.235388 -376.674634)
		(width 0.14224)
		(layer "In6.Cu")
		(net "P5E_CPU0_P2_RX_DP<9>")
	)
	(segment
		(start 369.675156 -283.496766)
		(end 369.697 -283.484066)
		(width 0.1143)
		(layer "In6.Cu")
		(net "P5E_CPU0_P2_RX_DP<9>")
	)
	(segment
		(start 370.640356 -281.862022)
		(end 370.676932 -281.840686)
		(width 0.1143)
		(layer "In6.Cu")
		(net "P5E_CPU0_P2_RX_DP<9>")
	)
	(segment
		(start 369.664234 -286.74314)
		(end 369.736878 -286.700722)
		(width 0.1143)
		(layer "In6.Cu")
		(net "P5E_CPU0_P2_RX_DP<9>")
	)
	(segment
		(start 389.830056 -342.157812)
		(end 389.33247 -337.107784)
		(width 0.14224)
		(layer "In6.Cu")
		(net "P5E_CPU0_P2_RX_DP<9>")
	)
	(segment
		(start 408.50439 -373.105172)
		(end 400.404838 -368.517424)
		(width 0.14224)
		(layer "In6.Cu")
		(net "P5E_CPU0_P2_RX_DP<9>")
	)
	(segment
		(start 414.97631 -393.428982)
		(end 414.660334 -393.113006)
		(width 0.14224)
		(layer "In6.Cu")
		(net "P5E_CPU0_P2_RX_DP<9>")
	)
	(segment
		(start 369.267994 -294.680132)
		(end 369.196112 -294.640254)
		(width 0.1143)
		(layer "In6.Cu")
		(net "P5E_CPU0_P2_RX_DP<9>")
	)
	(segment
		(start 369.700302 -283.482034)
		(end 369.736878 -283.460698)
		(width 0.1143)
		(layer "In6.Cu")
		(net "P5E_CPU0_P2_RX_DP<9>")
	)
	(segment
		(start 369.225068 -289.796982)
		(end 369.224306 -289.796474)
		(width 0.1143)
		(layer "In6.Cu")
		(net "P5E_CPU0_P2_RX_DP<9>")
	)
	(segment
		(start 369.227862 -294.013382)
		(end 369.22837 -294.013382)
		(width 0.1143)
		(layer "In6.Cu")
		(net "P5E_CPU0_P2_RX_DP<9>")
	)
	(segment
		(start 369.264184 -284.959806)
		(end 369.196112 -284.920436)
		(width 0.1143)
		(layer "In6.Cu")
		(net "P5E_CPU0_P2_RX_DP<9>")
	)
	(segment
		(start 370.026438 -296.353484)
		(end 370.026438 -296.325036)
		(width 0.1143)
		(layer "In6.Cu")
		(net "P5E_CPU0_P2_RX_DP<9>")
	)
	(segment
		(start 369.2271 -294.01389)
		(end 369.227862 -294.013382)
		(width 0.1143)
		(layer "In6.Cu")
		(net "P5E_CPU0_P2_RX_DP<9>")
	)
	(segment
		(start 369.249198 -291.430964)
		(end 369.196112 -291.40023)
		(width 0.1143)
		(layer "In6.Cu")
		(net "P5E_CPU0_P2_RX_DP<9>")
	)
	(segment
		(start 373.739918 -303.79289)
		(end 370.995956 -299.686218)
		(width 0.14224)
		(layer "In6.Cu")
		(net "P5E_CPU0_P2_RX_DP<9>")
	)
	(segment
		(start 369.22329 -289.795966)
		(end 369.222528 -289.795458)
		(width 0.1143)
		(layer "In6.Cu")
		(net "P5E_CPU0_P2_RX_DP<9>")
	)
	(segment
		(start 369.222528 -289.795458)
		(end 369.221512 -289.79495)
		(width 0.1143)
		(layer "In6.Cu")
		(net "P5E_CPU0_P2_RX_DP<9>")
	)
	(segment
		(start 369.226084 -289.79749)
		(end 369.225068 -289.796982)
		(width 0.1143)
		(layer "In6.Cu")
		(net "P5E_CPU0_P2_RX_DP<9>")
	)
	(arc
		(start 369.229386 -290.772596)
		(mid 369.509627 -290.285932)
		(end 369.229386 -289.799268)
		(width 0.1143)
		(layer "In6.Cu")
		(net "P5E_CPU0_P2_RX_DP<9>")
	)
	(arc
		(start 369.736878 -286.700722)
		(mid 369.980205 -286.236156)
		(end 369.736878 -285.77159)
		(width 0.1143)
		(layer "In6.Cu")
		(net "P5E_CPU0_P2_RX_DP<9>")
	)
	(arc
		(start 369.736878 -283.460698)
		(mid 369.915691 -283.258348)
		(end 369.98021 -282.996132)
		(width 0.1143)
		(layer "In6.Cu")
		(net "P5E_CPU0_P2_RX_DP<9>")
	)
	(arc
		(start 370.45011 -282.186126)
		(mid 370.491365 -282.015155)
		(end 370.606066 -281.881834)
		(width 0.1143)
		(layer "In6.Cu")
		(net "P5E_CPU0_P2_RX_DP<9>")
	)
	(arc
		(start 370.676932 -281.840686)
		(mid 370.828919 -281.684178)
		(end 370.910358 -281.481784)
		(width 0.1143)
		(layer "In6.Cu")
		(net "P5E_CPU0_P2_RX_DP<9>")
	)
	(arc
		(start 369.5065 -287.081214)
		(mid 369.508855 -287.058908)
		(end 369.510056 -287.03651)
		(width 0.1143)
		(layer "In6.Cu")
		(net "P5E_CPU0_P2_RX_DP<9>")
	)
	(arc
		(start 370.206778 -282.650692)
		(mid 370.385591 -282.448342)
		(end 370.45011 -282.186126)
		(width 0.1143)
		(layer "In6.Cu")
		(net "P5E_CPU0_P2_RX_DP<9>")
	)
	(arc
		(start 369.281456 -289.118802)
		(mid 369.497446 -288.654971)
		(end 369.264184 -288.199576)
		(width 0.1143)
		(layer "In6.Cu")
		(net "P5E_CPU0_P2_RX_DP<9>")
	)
	(arc
		(start 369.249198 -292.380924)
		(mid 369.522749 -291.905944)
		(end 369.249198 -291.430964)
		(width 0.1143)
		(layer "In6.Cu")
		(net "P5E_CPU0_P2_RX_DP<9>")
	)
	(arc
		(start 369.196112 -293.020242)
		(mid 369.040184 -292.71595)
		(end 369.196112 -292.411658)
		(width 0.1143)
		(layer "In6.Cu")
		(net "P5E_CPU0_P2_RX_DP<9>")
	)
	(arc
		(start 369.510056 -295.142666)
		(mid 369.442701 -294.88459)
		(end 369.26901 -294.682164)
		(width 0.1143)
		(layer "In6.Cu")
		(net "P5E_CPU0_P2_RX_DP<9>")
	)
	(arc
		(start 369.509802 -285.441136)
		(mid 369.50863 -285.415681)
		(end 369.505992 -285.390336)
		(width 0.1143)
		(layer "In6.Cu")
		(net "P5E_CPU0_P2_RX_DP<9>")
	)
	(arc
		(start 369.664996 -295.449498)
		(mid 369.55106 -295.318343)
		(end 369.510056 -295.149524)
		(width 0.1143)
		(layer "In6.Cu")
		(net "P5E_CPU0_P2_RX_DP<9>")
	)
	(arc
		(start 389.831834 -342.170004)
		(mid 389.830798 -342.163929)
		(end 389.830056 -342.157812)
		(width 0.14224)
		(layer "In6.Cu")
		(net "P5E_CPU0_P2_RX_DP<9>")
	)
	(arc
		(start 369.98021 -282.996132)
		(mid 370.021759 -282.82471)
		(end 370.137182 -282.691332)
		(width 0.1143)
		(layer "In6.Cu")
		(net "P5E_CPU0_P2_RX_DP<9>")
	)
	(arc
		(start 391.350246 -349.556578)
		(mid 391.267332 -349.325134)
		(end 391.207498 -349.086678)
		(width 0.14224)
		(layer "In6.Cu")
		(net "P5E_CPU0_P2_RX_DP<9>")
	)
	(arc
		(start 369.196112 -289.780218)
		(mid 369.040184 -289.475926)
		(end 369.196112 -289.171634)
		(width 0.1143)
		(layer "In6.Cu")
		(net "P5E_CPU0_P2_RX_DP<9>")
	)
	(arc
		(start 408.727402 -373.194326)
		(mid 408.612879 -373.157295)
		(end 408.50439 -373.105172)
		(width 0.14224)
		(layer "In6.Cu")
		(net "P5E_CPU0_P2_RX_DP<9>")
	)
	(arc
		(start 369.194334 -288.158936)
		(mid 369.080927 -288.026047)
		(end 369.040156 -287.856168)
		(width 0.1143)
		(layer "In6.Cu")
		(net "P5E_CPU0_P2_RX_DP<9>")
	)
	(arc
		(start 369.666012 -285.730442)
		(mid 369.55457 -285.6038)
		(end 369.509802 -285.441136)
		(width 0.1143)
		(layer "In6.Cu")
		(net "P5E_CPU0_P2_RX_DP<9>")
	)
	(arc
		(start 369.196112 -291.40023)
		(mid 369.040184 -291.095938)
		(end 369.196112 -290.791646)
		(width 0.1143)
		(layer "In6.Cu")
		(net "P5E_CPU0_P2_RX_DP<9>")
	)
	(arc
		(start 370.910358 -281.481784)
		(mid 370.912381 -281.470374)
		(end 370.914168 -281.458924)
		(width 0.1143)
		(layer "In6.Cu")
		(net "P5E_CPU0_P2_RX_DP<9>")
	)
	(arc
		(start 369.266216 -284.271466)
		(mid 369.441109 -284.077526)
		(end 369.51031 -283.825696)
		(width 0.1143)
		(layer "In6.Cu")
		(net "P5E_CPU0_P2_RX_DP<9>")
	)
	(arc
		(start 369.510056 -287.03651)
		(mid 369.552871 -286.871796)
		(end 369.664234 -286.74314)
		(width 0.1143)
		(layer "In6.Cu")
		(net "P5E_CPU0_P2_RX_DP<9>")
	)
	(arc
		(start 416.235388 -376.674634)
		(mid 416.172599 -376.358592)
		(end 415.99358 -376.090688)
		(width 0.14224)
		(layer "In6.Cu")
		(net "P5E_CPU0_P2_RX_DP<9>")
	)
	(arc
		(start 369.262406 -287.513268)
		(mid 369.425196 -287.32026)
		(end 369.5065 -287.081214)
		(width 0.1143)
		(layer "In6.Cu")
		(net "P5E_CPU0_P2_RX_DP<9>")
	)
	(arc
		(start 369.505992 -285.390336)
		(mid 369.425324 -285.152464)
		(end 369.264184 -284.959806)
		(width 0.1143)
		(layer "In6.Cu")
		(net "P5E_CPU0_P2_RX_DP<9>")
	)
	(arc
		(start 398.39519 -366.539018)
		(mid 398.379328 -366.519803)
		(end 398.367504 -366.49787)
		(width 0.14224)
		(layer "In6.Cu")
		(net "P5E_CPU0_P2_RX_DP<9>")
	)
	(arc
		(start 369.196112 -284.920436)
		(mid 369.040184 -284.616144)
		(end 369.196112 -284.311852)
		(width 0.1143)
		(layer "In6.Cu")
		(net "P5E_CPU0_P2_RX_DP<9>")
	)
	(arc
		(start 400.404838 -368.517424)
		(mid 400.351512 -368.483163)
		(end 400.302476 -368.443002)
		(width 0.14224)
		(layer "In6.Cu")
		(net "P5E_CPU0_P2_RX_DP<9>")
	)
	(arc
		(start 369.040156 -287.856168)
		(mid 369.081411 -287.685197)
		(end 369.196112 -287.551876)
		(width 0.1143)
		(layer "In6.Cu")
		(net "P5E_CPU0_P2_RX_DP<9>")
	)
	(arc
		(start 369.22837 -294.013382)
		(mid 369.509017 -293.525956)
		(end 369.22837 -293.03853)
		(width 0.1143)
		(layer "In6.Cu")
		(net "P5E_CPU0_P2_RX_DP<9>")
	)
	(arc
		(start 369.51031 -283.825696)
		(mid 369.510977 -283.810294)
		(end 369.512596 -283.794962)
		(width 0.1143)
		(layer "In6.Cu")
		(net "P5E_CPU0_P2_RX_DP<9>")
	)
	(arc
		(start 415.238692 -382.318514)
		(mid 415.30964 -381.796413)
		(end 415.468816 -381.294132)
		(width 0.14224)
		(layer "In6.Cu")
		(net "P5E_CPU0_P2_RX_DP<9>")
	)
	(arc
		(start 400.302476 -368.443002)
		(mid 400.257469 -368.400523)
		(end 400.213322 -368.35715)
		(width 0.14224)
		(layer "In6.Cu")
		(net "P5E_CPU0_P2_RX_DP<9>")
	)
	(arc
		(start 369.196112 -294.640254)
		(mid 369.040184 -294.335962)
		(end 369.196112 -294.03167)
		(width 0.1143)
		(layer "In6.Cu")
		(net "P5E_CPU0_P2_RX_DP<9>")
	)
	(arc
		(start 416.06851 -379.846332)
		(mid 416.193267 -379.435069)
		(end 416.235388 -379.00737)
		(width 0.14224)
		(layer "In6.Cu")
		(net "P5E_CPU0_P2_RX_DP<9>")
	)
	(arc
		(start 369.264184 -289.132264)
		(mid 369.272882 -289.125613)
		(end 369.281456 -289.118802)
		(width 0.1143)
		(layer "In6.Cu")
		(net "P5E_CPU0_P2_RX_DP<9>")
	)
	(arc
		(start 369.512596 -283.794962)
		(mid 369.537384 -283.69831)
		(end 369.580922 -283.608526)
		(width 0.1143)
		(layer "In6.Cu")
		(net "P5E_CPU0_P2_RX_DP<9>")
	)
	(arc
		(start 369.580922 -283.608526)
		(mid 369.623909 -283.549163)
		(end 369.675156 -283.496766)
		(width 0.1143)
		(layer "In6.Cu")
		(net "P5E_CPU0_P2_RX_DP<9>")
	)
	(arc
		(start 369.98021 -295.955974)
		(mid 369.915622 -295.693807)
		(end 369.736878 -295.491408)
		(width 0.1143)
		(layer "In6.Cu")
		(net "P5E_CPU0_P2_RX_DP<9>")
	)
	(arc
		(start 414.634426 -374.731534)
		(mid 414.546597 -374.664904)
		(end 414.44418 -374.624092)
		(width 0.14224)
		(layer "In6.Cu")
		(net "P5E_CPU0_P2_RX_DP<9>")
	)
	(segment
		(start 368.0079 -284.350206)
		(end 368.474752 -284.616144)
		(width 0.12954)
		(layer "F.Cu")
		(net "P5E_CPU0_P2_RX_DP<8>")
	)
	(segment
		(start 412.898336 -394.385292)
		(end 413.419036 -394.385292)
		(width 0.127)
		(layer "F.Cu")
		(net "P5E_CPU0_P2_RX_DP<8>")
	)
	(segment
		(start 413.776414 -393.428982)
		(end 413.460438 -393.113006)
		(width 0.14224)
		(layer "In6.Cu")
		(net "P5E_CPU0_P2_RX_DP<8>")
	)
	(segment
		(start 368.288824 -284.939232)
		(end 368.287808 -284.938724)
		(width 0.1143)
		(layer "In6.Cu")
		(net "P5E_CPU0_P2_RX_DP<8>")
	)
	(segment
		(start 368.257074 -292.41115)
		(end 368.287554 -292.39337)
		(width 0.1143)
		(layer "In6.Cu")
		(net "P5E_CPU0_P2_RX_DP<8>")
	)
	(segment
		(start 373.017034 -304.39995)
		(end 370.181378 -300.156372)
		(width 0.14224)
		(layer "In6.Cu")
		(net "P5E_CPU0_P2_RX_DP<8>")
	)
	(segment
		(start 368.287554 -292.39337)
		(end 368.32667 -292.37051)
		(width 0.1143)
		(layer "In6.Cu")
		(net "P5E_CPU0_P2_RX_DP<8>")
	)
	(segment
		(start 368.287554 -288.178494)
		(end 368.255042 -288.159698)
		(width 0.1143)
		(layer "In6.Cu")
		(net "P5E_CPU0_P2_RX_DP<8>")
	)
	(segment
		(start 413.460438 -393.113006)
		(end 413.463486 -392.734546)
		(width 0.14224)
		(layer "In6.Cu")
		(net "P5E_CPU0_P2_RX_DP<8>")
	)
	(segment
		(start 370.181378 -300.156372)
		(end 369.088416 -297.51782)
		(width 0.14224)
		(layer "In6.Cu")
		(net "P5E_CPU0_P2_RX_DP<8>")
	)
	(segment
		(start 368.290602 -284.940248)
		(end 368.288824 -284.939232)
		(width 0.1143)
		(layer "In6.Cu")
		(net "P5E_CPU0_P2_RX_DP<8>")
	)
	(segment
		(start 413.776414 -393.842494)
		(end 413.776414 -393.428982)
		(width 0.14224)
		(layer "In6.Cu")
		(net "P5E_CPU0_P2_RX_DP<8>")
	)
	(segment
		(start 414.53181 -380.249176)
		(end 414.53181 -379.638052)
		(width 0.14224)
		(layer "In6.Cu")
		(net "P5E_CPU0_P2_RX_DP<8>")
	)
	(segment
		(start 368.757708 -285.74873)
		(end 368.727228 -285.73095)
		(width 0.1143)
		(layer "In6.Cu")
		(net "P5E_CPU0_P2_RX_DP<8>")
	)
	(segment
		(start 369.088416 -296.325036)
		(end 369.042696 -296.279316)
		(width 0.1143)
		(layer "In6.Cu")
		(net "P5E_CPU0_P2_RX_DP<8>")
	)
	(segment
		(start 412.227014 -375.477532)
		(end 412.088838 -375.339356)
		(width 0.14224)
		(layer "In6.Cu")
		(net "P5E_CPU0_P2_RX_DP<8>")
	)
	(segment
		(start 368.294666 -284.942788)
		(end 368.293142 -284.941772)
		(width 0.1143)
		(layer "In6.Cu")
		(net "P5E_CPU0_P2_RX_DP<8>")
	)
	(segment
		(start 397.482568 -367.061242)
		(end 397.481806 -367.059718)
		(width 0.14224)
		(layer "In6.Cu")
		(net "P5E_CPU0_P2_RX_DP<8>")
	)
	(segment
		(start 368.293142 -284.941772)
		(end 368.292126 -284.941264)
		(width 0.1143)
		(layer "In6.Cu")
		(net "P5E_CPU0_P2_RX_DP<8>")
	)
	(segment
		(start 368.279934 -284.934152)
		(end 368.277394 -284.932882)
		(width 0.1143)
		(layer "In6.Cu")
		(net "P5E_CPU0_P2_RX_DP<8>")
	)
	(segment
		(start 388.358126 -337.029806)
		(end 385.769612 -324.016116)
		(width 0.14224)
		(layer "In6.Cu")
		(net "P5E_CPU0_P2_RX_DP<8>")
	)
	(segment
		(start 413.257238 -378.34316)
		(end 413.036512 -378.122434)
		(width 0.14224)
		(layer "In6.Cu")
		(net "P5E_CPU0_P2_RX_DP<8>")
	)
	(segment
		(start 368.287046 -284.938216)
		(end 368.284252 -284.936692)
		(width 0.1143)
		(layer "In6.Cu")
		(net "P5E_CPU0_P2_RX_DP<8>")
	)
	(segment
		(start 369.088416 -296.353484)
		(end 369.088416 -296.325036)
		(width 0.1143)
		(layer "In6.Cu")
		(net "P5E_CPU0_P2_RX_DP<8>")
	)
	(segment
		(start 379.349254 -312.115708)
		(end 373.017034 -304.39995)
		(width 0.14224)
		(layer "In6.Cu")
		(net "P5E_CPU0_P2_RX_DP<8>")
	)
	(segment
		(start 368.287554 -294.658542)
		(end 368.257074 -294.640762)
		(width 0.1143)
		(layer "In6.Cu")
		(net "P5E_CPU0_P2_RX_DP<8>")
	)
	(segment
		(start 411.020514 -374.734074)
		(end 408.1145 -374.006872)
		(width 0.14224)
		(layer "In6.Cu")
		(net "P5E_CPU0_P2_RX_DP<8>")
	)
	(segment
		(start 390.500108 -350.204278)
		(end 390.500108 -350.204024)
		(width 0.14224)
		(layer "In6.Cu")
		(net "P5E_CPU0_P2_RX_DP<8>")
	)
	(segment
		(start 413.768286 -386.335016)
		(end 414.206436 -381.885444)
		(width 0.14224)
		(layer "In6.Cu")
		(net "P5E_CPU0_P2_RX_DP<8>")
	)
	(segment
		(start 368.288824 -287.53308)
		(end 368.290094 -287.532318)
		(width 0.1143)
		(layer "In6.Cu")
		(net "P5E_CPU0_P2_RX_DP<8>")
	)
	(segment
		(start 368.287554 -294.013382)
		(end 368.32667 -293.990522)
		(width 0.1143)
		(layer "In6.Cu")
		(net "P5E_CPU0_P2_RX_DP<8>")
	)
	(segment
		(start 368.287554 -289.798506)
		(end 368.257074 -289.780726)
		(width 0.1143)
		(layer "In6.Cu")
		(net "P5E_CPU0_P2_RX_DP<8>")
	)
	(segment
		(start 368.284252 -284.936692)
		(end 368.28349 -284.936184)
		(width 0.1143)
		(layer "In6.Cu")
		(net "P5E_CPU0_P2_RX_DP<8>")
	)
	(segment
		(start 368.277394 -284.932882)
		(end 368.256058 -284.920436)
		(width 0.1143)
		(layer "In6.Cu")
		(net "P5E_CPU0_P2_RX_DP<8>")
	)
	(segment
		(start 368.292126 -284.941264)
		(end 368.290602 -284.940248)
		(width 0.1143)
		(layer "In6.Cu")
		(net "P5E_CPU0_P2_RX_DP<8>")
	)
	(segment
		(start 413.688276 -393.930632)
		(end 413.776414 -393.842494)
		(width 0.14224)
		(layer "In6.Cu")
		(net "P5E_CPU0_P2_RX_DP<8>")
	)
	(segment
		(start 385.769612 -324.016116)
		(end 379.643132 -312.555382)
		(width 0.14224)
		(layer "In6.Cu")
		(net "P5E_CPU0_P2_RX_DP<8>")
	)
	(segment
		(start 368.290856 -287.53181)
		(end 368.292126 -287.531048)
		(width 0.1143)
		(layer "In6.Cu")
		(net "P5E_CPU0_P2_RX_DP<8>")
	)
	(segment
		(start 368.290094 -287.532318)
		(end 368.290856 -287.53181)
		(width 0.1143)
		(layer "In6.Cu")
		(net "P5E_CPU0_P2_RX_DP<8>")
	)
	(segment
		(start 368.285776 -287.534858)
		(end 368.287046 -287.534096)
		(width 0.1143)
		(layer "In6.Cu")
		(net "P5E_CPU0_P2_RX_DP<8>")
	)
	(segment
		(start 413.924242 -378.658882)
		(end 413.626808 -378.55652)
		(width 0.14224)
		(layer "In6.Cu")
		(net "P5E_CPU0_P2_RX_DP<8>")
	)
	(segment
		(start 368.326924 -284.961584)
		(end 368.320066 -284.95752)
		(width 0.1143)
		(layer "In6.Cu")
		(net "P5E_CPU0_P2_RX_DP<8>")
	)
	(segment
		(start 408.1145 -374.006872)
		(end 400.305524 -369.583462)
		(width 0.14224)
		(layer "In6.Cu")
		(net "P5E_CPU0_P2_RX_DP<8>")
	)
	(segment
		(start 368.287554 -290.773358)
		(end 368.32667 -290.750498)
		(width 0.1143)
		(layer "In6.Cu")
		(net "P5E_CPU0_P2_RX_DP<8>")
	)
	(segment
		(start 413.768286 -392.429746)
		(end 413.768286 -386.335016)
		(width 0.14224)
		(layer "In6.Cu")
		(net "P5E_CPU0_P2_RX_DP<8>")
	)
	(segment
		(start 368.287808 -284.938724)
		(end 368.287046 -284.938216)
		(width 0.1143)
		(layer "In6.Cu")
		(net "P5E_CPU0_P2_RX_DP<8>")
	)
	(segment
		(start 368.725196 -286.742378)
		(end 368.757708 -286.723582)
		(width 0.1143)
		(layer "In6.Cu")
		(net "P5E_CPU0_P2_RX_DP<8>")
	)
	(segment
		(start 413.514032 -394.031216)
		(end 413.688276 -393.930632)
		(width 0.14224)
		(layer "In6.Cu")
		(net "P5E_CPU0_P2_RX_DP<8>")
	)
	(segment
		(start 368.570256 -295.145968)
		(end 368.570002 -295.145968)
		(width 0.1143)
		(layer "In6.Cu")
		(net "P5E_CPU0_P2_RX_DP<8>")
	)
	(segment
		(start 368.287554 -291.418518)
		(end 368.257074 -291.400738)
		(width 0.1143)
		(layer "In6.Cu")
		(net "P5E_CPU0_P2_RX_DP<8>")
	)
	(segment
		(start 368.32667 -288.201354)
		(end 368.287554 -288.178494)
		(width 0.1143)
		(layer "In6.Cu")
		(net "P5E_CPU0_P2_RX_DP<8>")
	)
	(segment
		(start 368.257074 -289.171126)
		(end 368.287554 -289.153346)
		(width 0.1143)
		(layer "In6.Cu")
		(net "P5E_CPU0_P2_RX_DP<8>")
	)
	(segment
		(start 368.320066 -284.95752)
		(end 368.319304 -284.957012)
		(width 0.1143)
		(layer "In6.Cu")
		(net "P5E_CPU0_P2_RX_DP<8>")
	)
	(segment
		(start 412.830264 -377.624594)
		(end 412.830264 -376.933968)
		(width 0.14224)
		(layer "In6.Cu")
		(net "P5E_CPU0_P2_RX_DP<8>")
	)
	(segment
		(start 388.87146 -342.237822)
		(end 388.358126 -337.029806)
		(width 0.14224)
		(layer "In6.Cu")
		(net "P5E_CPU0_P2_RX_DP<8>")
	)
	(segment
		(start 368.287046 -287.534096)
		(end 368.287808 -287.533588)
		(width 0.1143)
		(layer "In6.Cu")
		(net "P5E_CPU0_P2_RX_DP<8>")
	)
	(segment
		(start 413.419036 -394.385292)
		(end 413.514032 -394.031216)
		(width 0.14224)
		(layer "In6.Cu")
		(net "P5E_CPU0_P2_RX_DP<8>")
	)
	(segment
		(start 368.287808 -287.533588)
		(end 368.288824 -287.53308)
		(width 0.1143)
		(layer "In6.Cu")
		(net "P5E_CPU0_P2_RX_DP<8>")
	)
	(segment
		(start 368.281966 -284.935422)
		(end 368.281204 -284.934914)
		(width 0.1143)
		(layer "In6.Cu")
		(net "P5E_CPU0_P2_RX_DP<8>")
	)
	(segment
		(start 368.17681 -284.616144)
		(end 368.474752 -284.616144)
		(width 0.1143)
		(layer "In6.Cu")
		(net "P5E_CPU0_P2_RX_DP<8>")
	)
	(segment
		(start 368.28349 -284.936184)
		(end 368.281966 -284.935422)
		(width 0.1143)
		(layer "In6.Cu")
		(net "P5E_CPU0_P2_RX_DP<8>")
	)
	(segment
		(start 379.643132 -312.555382)
		(end 379.349254 -312.115708)
		(width 0.14224)
		(layer "In6.Cu")
		(net "P5E_CPU0_P2_RX_DP<8>")
	)
	(segment
		(start 368.257074 -294.031162)
		(end 368.287554 -294.013382)
		(width 0.1143)
		(layer "In6.Cu")
		(net "P5E_CPU0_P2_RX_DP<8>")
	)
	(segment
		(start 413.463486 -392.734546)
		(end 413.768286 -392.429746)
		(width 0.14224)
		(layer "In6.Cu")
		(net "P5E_CPU0_P2_RX_DP<8>")
	)
	(segment
		(start 368.284252 -287.53562)
		(end 368.285776 -287.534858)
		(width 0.1143)
		(layer "In6.Cu")
		(net "P5E_CPU0_P2_RX_DP<8>")
	)
	(segment
		(start 368.32667 -294.681402)
		(end 368.287554 -294.658542)
		(width 0.1143)
		(layer "In6.Cu")
		(net "P5E_CPU0_P2_RX_DP<8>")
	)
	(segment
		(start 414.212278 -378.866654)
		(end 414.138364 -378.79274)
		(width 0.14224)
		(layer "In6.Cu")
		(net "P5E_CPU0_P2_RX_DP<8>")
	)
	(segment
		(start 368.794792 -286.702246)
		(end 368.796824 -286.700722)
		(width 0.1143)
		(layer "In6.Cu")
		(net "P5E_CPU0_P2_RX_DP<8>")
	)
	(segment
		(start 368.281204 -284.934914)
		(end 368.279934 -284.934152)
		(width 0.1143)
		(layer "In6.Cu")
		(net "P5E_CPU0_P2_RX_DP<8>")
	)
	(segment
		(start 390.369552 -349.77324)
		(end 388.873238 -342.250014)
		(width 0.14224)
		(layer "In6.Cu")
		(net "P5E_CPU0_P2_RX_DP<8>")
	)
	(segment
		(start 368.757708 -295.468548)
		(end 368.727228 -295.450768)
		(width 0.1143)
		(layer "In6.Cu")
		(net "P5E_CPU0_P2_RX_DP<8>")
	)
	(segment
		(start 368.32667 -293.06139)
		(end 368.287554 -293.03853)
		(width 0.1143)
		(layer "In6.Cu")
		(net "P5E_CPU0_P2_RX_DP<8>")
	)
	(segment
		(start 368.287554 -293.03853)
		(end 368.257074 -293.02075)
		(width 0.1143)
		(layer "In6.Cu")
		(net "P5E_CPU0_P2_RX_DP<8>")
	)
	(segment
		(start 369.088416 -297.51782)
		(end 369.088416 -296.353484)
		(width 0.14224)
		(layer "In6.Cu")
		(net "P5E_CPU0_P2_RX_DP<8>")
	)
	(segment
		(start 397.481806 -367.059718)
		(end 390.500108 -350.204278)
		(width 0.14224)
		(layer "In6.Cu")
		(net "P5E_CPU0_P2_RX_DP<8>")
	)
	(segment
		(start 368.256058 -287.551876)
		(end 368.284252 -287.53562)
		(width 0.1143)
		(layer "In6.Cu")
		(net "P5E_CPU0_P2_RX_DP<8>")
	)
	(segment
		(start 369.040156 -296.006774)
		(end 369.040156 -295.955974)
		(width 0.1143)
		(layer "In6.Cu")
		(net "P5E_CPU0_P2_RX_DP<8>")
	)
	(segment
		(start 368.292888 -287.53054)
		(end 368.324384 -287.512252)
		(width 0.1143)
		(layer "In6.Cu")
		(net "P5E_CPU0_P2_RX_DP<8>")
	)
	(segment
		(start 398.987264 -368.58067)
		(end 397.510508 -367.103914)
		(width 0.14224)
		(layer "In6.Cu")
		(net "P5E_CPU0_P2_RX_DP<8>")
	)
	(segment
		(start 414.206436 -381.885444)
		(end 414.53181 -380.249176)
		(width 0.14224)
		(layer "In6.Cu")
		(net "P5E_CPU0_P2_RX_DP<8>")
	)
	(segment
		(start 368.257074 -290.791138)
		(end 368.287554 -290.773358)
		(width 0.1143)
		(layer "In6.Cu")
		(net "P5E_CPU0_P2_RX_DP<8>")
	)
	(segment
		(start 368.757708 -286.723582)
		(end 368.794792 -286.702246)
		(width 0.1143)
		(layer "In6.Cu")
		(net "P5E_CPU0_P2_RX_DP<8>")
	)
	(segment
		(start 369.042696 -296.279316)
		(end 369.042696 -296.009314)
		(width 0.1143)
		(layer "In6.Cu")
		(net "P5E_CPU0_P2_RX_DP<8>")
	)
	(segment
		(start 368.796824 -285.77159)
		(end 368.757708 -285.74873)
		(width 0.1143)
		(layer "In6.Cu")
		(net "P5E_CPU0_P2_RX_DP<8>")
	)
	(segment
		(start 368.796824 -295.491408)
		(end 368.757708 -295.468548)
		(width 0.1143)
		(layer "In6.Cu")
		(net "P5E_CPU0_P2_RX_DP<8>")
	)
	(segment
		(start 368.32667 -289.821366)
		(end 368.287554 -289.798506)
		(width 0.1143)
		(layer "In6.Cu")
		(net "P5E_CPU0_P2_RX_DP<8>")
	)
	(segment
		(start 368.292126 -287.531048)
		(end 368.292888 -287.53054)
		(width 0.1143)
		(layer "In6.Cu")
		(net "P5E_CPU0_P2_RX_DP<8>")
	)
	(segment
		(start 368.32667 -291.441378)
		(end 368.287554 -291.418518)
		(width 0.1143)
		(layer "In6.Cu")
		(net "P5E_CPU0_P2_RX_DP<8>")
	)
	(segment
		(start 369.042696 -296.009314)
		(end 369.040156 -296.006774)
		(width 0.1143)
		(layer "In6.Cu")
		(net "P5E_CPU0_P2_RX_DP<8>")
	)
	(segment
		(start 368.287554 -289.153346)
		(end 368.32667 -289.130486)
		(width 0.1143)
		(layer "In6.Cu")
		(net "P5E_CPU0_P2_RX_DP<8>")
	)
	(segment
		(start 368.10696 -284.685994)
		(end 368.17681 -284.616144)
		(width 0.1143)
		(layer "In6.Cu")
		(net "P5E_CPU0_P2_RX_DP<8>")
	)
	(segment
		(start 368.319304 -284.957012)
		(end 368.294666 -284.942788)
		(width 0.1143)
		(layer "In6.Cu")
		(net "P5E_CPU0_P2_RX_DP<8>")
	)
	(arc
		(start 412.088838 -375.339356)
		(mid 411.595795 -374.96414)
		(end 411.020514 -374.734074)
		(width 0.14224)
		(layer "In6.Cu")
		(net "P5E_CPU0_P2_RX_DP<8>")
	)
	(arc
		(start 413.036512 -378.122434)
		(mid 412.883893 -377.894023)
		(end 412.830264 -377.624594)
		(width 0.14224)
		(layer "In6.Cu")
		(net "P5E_CPU0_P2_RX_DP<8>")
	)
	(arc
		(start 368.32667 -290.750498)
		(mid 368.569997 -290.285932)
		(end 368.32667 -289.821366)
		(width 0.1143)
		(layer "In6.Cu")
		(net "P5E_CPU0_P2_RX_DP<8>")
	)
	(arc
		(start 368.570256 -285.42615)
		(mid 368.505741 -285.163931)
		(end 368.326924 -284.961584)
		(width 0.1143)
		(layer "In6.Cu")
		(net "P5E_CPU0_P2_RX_DP<8>")
	)
	(arc
		(start 368.570002 -295.145968)
		(mid 368.505487 -294.883749)
		(end 368.32667 -294.681402)
		(width 0.1143)
		(layer "In6.Cu")
		(net "P5E_CPU0_P2_RX_DP<8>")
	)
	(arc
		(start 368.256058 -284.920436)
		(mid 368.158923 -284.817567)
		(end 368.10696 -284.685994)
		(width 0.1143)
		(layer "In6.Cu")
		(net "P5E_CPU0_P2_RX_DP<8>")
	)
	(arc
		(start 368.257074 -289.780726)
		(mid 368.100097 -289.475926)
		(end 368.257074 -289.171126)
		(width 0.1143)
		(layer "In6.Cu")
		(net "P5E_CPU0_P2_RX_DP<8>")
	)
	(arc
		(start 368.257074 -293.02075)
		(mid 368.100097 -292.71595)
		(end 368.257074 -292.41115)
		(width 0.1143)
		(layer "In6.Cu")
		(net "P5E_CPU0_P2_RX_DP<8>")
	)
	(arc
		(start 368.324384 -287.512252)
		(mid 368.505036 -287.309507)
		(end 368.570256 -287.045908)
		(width 0.1143)
		(layer "In6.Cu")
		(net "P5E_CPU0_P2_RX_DP<8>")
	)
	(arc
		(start 412.830264 -376.933968)
		(mid 412.67348 -376.14576)
		(end 412.227014 -375.477532)
		(width 0.14224)
		(layer "In6.Cu")
		(net "P5E_CPU0_P2_RX_DP<8>")
	)
	(arc
		(start 400.305524 -369.583462)
		(mid 399.612503 -369.126618)
		(end 398.987264 -368.58067)
		(width 0.14224)
		(layer "In6.Cu")
		(net "P5E_CPU0_P2_RX_DP<8>")
	)
	(arc
		(start 368.257074 -291.400738)
		(mid 368.100097 -291.095938)
		(end 368.257074 -290.791138)
		(width 0.1143)
		(layer "In6.Cu")
		(net "P5E_CPU0_P2_RX_DP<8>")
	)
	(arc
		(start 397.510508 -367.103914)
		(mid 397.494377 -367.083992)
		(end 397.482568 -367.061242)
		(width 0.14224)
		(layer "In6.Cu")
		(net "P5E_CPU0_P2_RX_DP<8>")
	)
	(arc
		(start 413.508444 -378.511562)
		(mid 413.374611 -378.43964)
		(end 413.257238 -378.34316)
		(width 0.14224)
		(layer "In6.Cu")
		(net "P5E_CPU0_P2_RX_DP<8>")
	)
	(arc
		(start 368.570256 -287.045908)
		(mid 368.611222 -286.875502)
		(end 368.725196 -286.742378)
		(width 0.1143)
		(layer "In6.Cu")
		(net "P5E_CPU0_P2_RX_DP<8>")
	)
	(arc
		(start 368.32667 -293.990522)
		(mid 368.569997 -293.525956)
		(end 368.32667 -293.06139)
		(width 0.1143)
		(layer "In6.Cu")
		(net "P5E_CPU0_P2_RX_DP<8>")
	)
	(arc
		(start 368.32667 -289.130486)
		(mid 368.569997 -288.66592)
		(end 368.32667 -288.201354)
		(width 0.1143)
		(layer "In6.Cu")
		(net "P5E_CPU0_P2_RX_DP<8>")
	)
	(arc
		(start 368.100102 -287.856168)
		(mid 368.141357 -287.685197)
		(end 368.256058 -287.551876)
		(width 0.1143)
		(layer "In6.Cu")
		(net "P5E_CPU0_P2_RX_DP<8>")
	)
	(arc
		(start 413.626808 -378.55652)
		(mid 413.56726 -378.535004)
		(end 413.508444 -378.511562)
		(width 0.14224)
		(layer "In6.Cu")
		(net "P5E_CPU0_P2_RX_DP<8>")
	)
	(arc
		(start 368.727228 -295.450768)
		(mid 368.611801 -295.317392)
		(end 368.570256 -295.145968)
		(width 0.1143)
		(layer "In6.Cu")
		(net "P5E_CPU0_P2_RX_DP<8>")
	)
	(arc
		(start 414.53181 -379.638052)
		(mid 414.448768 -379.220571)
		(end 414.212278 -378.866654)
		(width 0.14224)
		(layer "In6.Cu")
		(net "P5E_CPU0_P2_RX_DP<8>")
	)
	(arc
		(start 368.796824 -286.700722)
		(mid 369.040151 -286.236156)
		(end 368.796824 -285.77159)
		(width 0.1143)
		(layer "In6.Cu")
		(net "P5E_CPU0_P2_RX_DP<8>")
	)
	(arc
		(start 414.138364 -378.79274)
		(mid 414.038932 -378.713608)
		(end 413.924242 -378.658882)
		(width 0.14224)
		(layer "In6.Cu")
		(net "P5E_CPU0_P2_RX_DP<8>")
	)
	(arc
		(start 390.500108 -350.204024)
		(mid 390.42425 -349.991839)
		(end 390.369552 -349.77324)
		(width 0.14224)
		(layer "In6.Cu")
		(net "P5E_CPU0_P2_RX_DP<8>")
	)
	(arc
		(start 368.727228 -285.73095)
		(mid 368.611801 -285.597574)
		(end 368.570256 -285.42615)
		(width 0.1143)
		(layer "In6.Cu")
		(net "P5E_CPU0_P2_RX_DP<8>")
	)
	(arc
		(start 368.257074 -294.640762)
		(mid 368.100097 -294.335962)
		(end 368.257074 -294.031162)
		(width 0.1143)
		(layer "In6.Cu")
		(net "P5E_CPU0_P2_RX_DP<8>")
	)
	(arc
		(start 369.040156 -295.955974)
		(mid 368.975715 -295.693703)
		(end 368.796824 -295.491408)
		(width 0.1143)
		(layer "In6.Cu")
		(net "P5E_CPU0_P2_RX_DP<8>")
	)
	(arc
		(start 368.255042 -288.159698)
		(mid 368.141113 -288.026551)
		(end 368.100102 -287.856168)
		(width 0.1143)
		(layer "In6.Cu")
		(net "P5E_CPU0_P2_RX_DP<8>")
	)
	(arc
		(start 368.32667 -292.37051)
		(mid 368.569997 -291.905944)
		(end 368.32667 -291.441378)
		(width 0.1143)
		(layer "In6.Cu")
		(net "P5E_CPU0_P2_RX_DP<8>")
	)
	(arc
		(start 388.873238 -342.250014)
		(mid 388.872204 -342.243939)
		(end 388.87146 -342.237822)
		(width 0.14224)
		(layer "In6.Cu")
		(net "P5E_CPU0_P2_RX_DP<8>")
	)
	(segment
		(start 368.0079 -285.970218)
		(end 368.474752 -286.236156)
		(width 0.12954)
		(layer "F.Cu")
		(net "P5E_CPU0_P2_RX_DP<7>")
	)
	(segment
		(start 411.698186 -394.385292)
		(end 412.218886 -394.385292)
		(width 0.127)
		(layer "F.Cu")
		(net "P5E_CPU0_P2_RX_DP<7>")
	)
	(segment
		(start 367.31702 -290.791138)
		(end 367.386616 -290.750498)
		(width 0.1143)
		(layer "In6.Cu")
		(net "P5E_CPU0_P2_RX_DP<7>")
	)
	(segment
		(start 372.495318 -305.29784)
		(end 369.355624 -300.599348)
		(width 0.14224)
		(layer "In6.Cu")
		(net "P5E_CPU0_P2_RX_DP<7>")
	)
	(segment
		(start 367.817908 -295.468548)
		(end 367.817654 -295.468548)
		(width 0.1143)
		(layer "In6.Cu")
		(net "P5E_CPU0_P2_RX_DP<7>")
	)
	(segment
		(start 367.350802 -287.53181)
		(end 367.352072 -287.531048)
		(width 0.1143)
		(layer "In6.Cu")
		(net "P5E_CPU0_P2_RX_DP<7>")
	)
	(segment
		(start 367.352072 -287.531048)
		(end 367.352834 -287.53054)
		(width 0.1143)
		(layer "In6.Cu")
		(net "P5E_CPU0_P2_RX_DP<7>")
	)
	(segment
		(start 367.35004 -287.532318)
		(end 367.350802 -287.53181)
		(width 0.1143)
		(layer "In6.Cu")
		(net "P5E_CPU0_P2_RX_DP<7>")
	)
	(segment
		(start 389.382 -349.723964)
		(end 387.925818 -342.404192)
		(width 0.14224)
		(layer "In6.Cu")
		(net "P5E_CPU0_P2_RX_DP<7>")
	)
	(segment
		(start 367.316004 -287.551876)
		(end 367.341404 -287.537144)
		(width 0.1143)
		(layer "In6.Cu")
		(net "P5E_CPU0_P2_RX_DP<7>")
	)
	(segment
		(start 367.85423 -295.48963)
		(end 367.81867 -295.469056)
		(width 0.1143)
		(layer "In6.Cu")
		(net "P5E_CPU0_P2_RX_DP<7>")
	)
	(segment
		(start 411.12821 -380.558802)
		(end 411.12821 -376.520456)
		(width 0.14224)
		(layer "In6.Cu")
		(net "P5E_CPU0_P2_RX_DP<7>")
	)
	(segment
		(start 368.156236 -296.325036)
		(end 368.110516 -296.279316)
		(width 0.1143)
		(layer "In6.Cu")
		(net "P5E_CPU0_P2_RX_DP<7>")
	)
	(segment
		(start 412.218886 -394.385292)
		(end 412.313882 -394.031216)
		(width 0.14224)
		(layer "In6.Cu")
		(net "P5E_CPU0_P2_RX_DP<7>")
	)
	(segment
		(start 409.580334 -375.34469)
		(end 407.793444 -374.897142)
		(width 0.14224)
		(layer "In6.Cu")
		(net "P5E_CPU0_P2_RX_DP<7>")
	)
	(segment
		(start 368.110516 -296.279316)
		(end 368.110516 -296.007282)
		(width 0.1143)
		(layer "In6.Cu")
		(net "P5E_CPU0_P2_RX_DP<7>")
	)
	(segment
		(start 367.81867 -295.469056)
		(end 367.817908 -295.468548)
		(width 0.1143)
		(layer "In6.Cu")
		(net "P5E_CPU0_P2_RX_DP<7>")
	)
	(segment
		(start 387.384036 -336.91322)
		(end 384.882136 -324.334632)
		(width 0.14224)
		(layer "In6.Cu")
		(net "P5E_CPU0_P2_RX_DP<7>")
	)
	(segment
		(start 367.31702 -294.031162)
		(end 367.386616 -293.990522)
		(width 0.1143)
		(layer "In6.Cu")
		(net "P5E_CPU0_P2_RX_DP<7>")
	)
	(segment
		(start 367.386616 -291.441378)
		(end 367.31702 -291.400738)
		(width 0.1143)
		(layer "In6.Cu")
		(net "P5E_CPU0_P2_RX_DP<7>")
	)
	(segment
		(start 367.386616 -294.681402)
		(end 367.31702 -294.640762)
		(width 0.1143)
		(layer "In6.Cu")
		(net "P5E_CPU0_P2_RX_DP<7>")
	)
	(segment
		(start 367.325402 -289.1663)
		(end 367.327688 -289.164776)
		(width 0.1143)
		(layer "In6.Cu")
		(net "P5E_CPU0_P2_RX_DP<7>")
	)
	(segment
		(start 367.386616 -293.06139)
		(end 367.31702 -293.02075)
		(width 0.1143)
		(layer "In6.Cu")
		(net "P5E_CPU0_P2_RX_DP<7>")
	)
	(segment
		(start 412.263336 -392.7348)
		(end 412.568136 -392.43)
		(width 0.14224)
		(layer "In6.Cu")
		(net "P5E_CPU0_P2_RX_DP<7>")
	)
	(segment
		(start 412.576264 -393.428982)
		(end 412.260288 -393.113006)
		(width 0.14224)
		(layer "In6.Cu")
		(net "P5E_CPU0_P2_RX_DP<7>")
	)
	(segment
		(start 367.342166 -287.536636)
		(end 367.343436 -287.536128)
		(width 0.1143)
		(layer "In6.Cu")
		(net "P5E_CPU0_P2_RX_DP<7>")
	)
	(segment
		(start 367.320576 -289.169094)
		(end 367.322608 -289.168078)
		(width 0.1143)
		(layer "In6.Cu")
		(net "P5E_CPU0_P2_RX_DP<7>")
	)
	(segment
		(start 411.008322 -376.230896)
		(end 410.82722 -376.050048)
		(width 0.14224)
		(layer "In6.Cu")
		(net "P5E_CPU0_P2_RX_DP<7>")
	)
	(segment
		(start 367.343436 -287.536128)
		(end 367.344198 -287.53562)
		(width 0.1143)
		(layer "In6.Cu")
		(net "P5E_CPU0_P2_RX_DP<7>")
	)
	(segment
		(start 367.31702 -292.41115)
		(end 367.386616 -292.37051)
		(width 0.1143)
		(layer "In6.Cu")
		(net "P5E_CPU0_P2_RX_DP<7>")
	)
	(segment
		(start 412.568136 -390.157208)
		(end 412.905702 -382.1303)
		(width 0.14224)
		(layer "In6.Cu")
		(net "P5E_CPU0_P2_RX_DP<7>")
	)
	(segment
		(start 368.156236 -296.353484)
		(end 368.156236 -296.325036)
		(width 0.1143)
		(layer "In6.Cu")
		(net "P5E_CPU0_P2_RX_DP<7>")
	)
	(segment
		(start 367.322608 -289.168078)
		(end 367.324132 -289.167062)
		(width 0.1143)
		(layer "In6.Cu")
		(net "P5E_CPU0_P2_RX_DP<7>")
	)
	(segment
		(start 367.327688 -289.164776)
		(end 367.38687 -289.130486)
		(width 0.1143)
		(layer "In6.Cu")
		(net "P5E_CPU0_P2_RX_DP<7>")
	)
	(segment
		(start 412.576264 -393.842494)
		(end 412.576264 -393.428982)
		(width 0.14224)
		(layer "In6.Cu")
		(net "P5E_CPU0_P2_RX_DP<7>")
	)
	(segment
		(start 398.765776 -369.78209)
		(end 396.926562 -367.942876)
		(width 0.14224)
		(layer "In6.Cu")
		(net "P5E_CPU0_P2_RX_DP<7>")
	)
	(segment
		(start 367.344198 -287.53562)
		(end 367.345722 -287.534858)
		(width 0.1143)
		(layer "In6.Cu")
		(net "P5E_CPU0_P2_RX_DP<7>")
	)
	(segment
		(start 412.260288 -393.113006)
		(end 412.263336 -392.7348)
		(width 0.14224)
		(layer "In6.Cu")
		(net "P5E_CPU0_P2_RX_DP<7>")
	)
	(segment
		(start 412.568136 -392.43)
		(end 412.568136 -390.157208)
		(width 0.14224)
		(layer "In6.Cu")
		(net "P5E_CPU0_P2_RX_DP<7>")
	)
	(segment
		(start 367.341404 -287.537144)
		(end 367.342166 -287.536636)
		(width 0.1143)
		(layer "In6.Cu")
		(net "P5E_CPU0_P2_RX_DP<7>")
	)
	(segment
		(start 412.905702 -382.1303)
		(end 412.905702 -381.88646)
		(width 0.14224)
		(layer "In6.Cu")
		(net "P5E_CPU0_P2_RX_DP<7>")
	)
	(segment
		(start 367.324132 -289.167062)
		(end 367.325402 -289.1663)
		(width 0.1143)
		(layer "In6.Cu")
		(net "P5E_CPU0_P2_RX_DP<7>")
	)
	(segment
		(start 367.319052 -289.17011)
		(end 367.320576 -289.169094)
		(width 0.1143)
		(layer "In6.Cu")
		(net "P5E_CPU0_P2_RX_DP<7>")
	)
	(segment
		(start 367.352834 -287.53054)
		(end 367.38433 -287.512252)
		(width 0.1143)
		(layer "In6.Cu")
		(net "P5E_CPU0_P2_RX_DP<7>")
	)
	(segment
		(start 367.630202 -295.145968)
		(end 367.629948 -295.145968)
		(width 0.1143)
		(layer "In6.Cu")
		(net "P5E_CPU0_P2_RX_DP<7>")
	)
	(segment
		(start 367.386616 -289.821366)
		(end 367.31702 -289.780726)
		(width 0.1143)
		(layer "In6.Cu")
		(net "P5E_CPU0_P2_RX_DP<7>")
	)
	(segment
		(start 367.34877 -287.53308)
		(end 367.35004 -287.532318)
		(width 0.1143)
		(layer "In6.Cu")
		(net "P5E_CPU0_P2_RX_DP<7>")
	)
	(segment
		(start 368.17681 -286.236156)
		(end 368.474752 -286.236156)
		(width 0.1143)
		(layer "In6.Cu")
		(net "P5E_CPU0_P2_RX_DP<7>")
	)
	(segment
		(start 367.31702 -289.171126)
		(end 367.319052 -289.17011)
		(width 0.1143)
		(layer "In6.Cu")
		(net "P5E_CPU0_P2_RX_DP<7>")
	)
	(segment
		(start 396.65275 -367.53292)
		(end 389.670544 -350.675194)
		(width 0.14224)
		(layer "In6.Cu")
		(net "P5E_CPU0_P2_RX_DP<7>")
	)
	(segment
		(start 367.345722 -287.534858)
		(end 367.346992 -287.534096)
		(width 0.1143)
		(layer "In6.Cu")
		(net "P5E_CPU0_P2_RX_DP<7>")
	)
	(segment
		(start 368.094006 -286.31896)
		(end 368.17681 -286.236156)
		(width 0.1143)
		(layer "In6.Cu")
		(net "P5E_CPU0_P2_RX_DP<7>")
	)
	(segment
		(start 368.110516 -296.007282)
		(end 368.110008 -296.006774)
		(width 0.1143)
		(layer "In6.Cu")
		(net "P5E_CPU0_P2_RX_DP<7>")
	)
	(segment
		(start 367.38687 -288.201354)
		(end 367.314226 -288.158936)
		(width 0.1143)
		(layer "In6.Cu")
		(net "P5E_CPU0_P2_RX_DP<7>")
	)
	(segment
		(start 412.785814 -381.597154)
		(end 412.387796 -381.198882)
		(width 0.14224)
		(layer "In6.Cu")
		(net "P5E_CPU0_P2_RX_DP<7>")
	)
	(segment
		(start 407.67635 -374.850152)
		(end 398.866106 -369.858544)
		(width 0.14224)
		(layer "In6.Cu")
		(net "P5E_CPU0_P2_RX_DP<7>")
	)
	(segment
		(start 412.313882 -394.031216)
		(end 412.488126 -393.930632)
		(width 0.14224)
		(layer "In6.Cu")
		(net "P5E_CPU0_P2_RX_DP<7>")
	)
	(segment
		(start 369.355624 -300.599348)
		(end 368.156236 -297.703494)
		(width 0.14224)
		(layer "In6.Cu")
		(net "P5E_CPU0_P2_RX_DP<7>")
	)
	(segment
		(start 368.110008 -296.006774)
		(end 368.110008 -295.96588)
		(width 0.1143)
		(layer "In6.Cu")
		(net "P5E_CPU0_P2_RX_DP<7>")
	)
	(segment
		(start 412.255208 -381.11049)
		(end 411.20695 -380.67615)
		(width 0.14224)
		(layer "In6.Cu")
		(net "P5E_CPU0_P2_RX_DP<7>")
	)
	(segment
		(start 367.817654 -295.468548)
		(end 367.787174 -295.450768)
		(width 0.1143)
		(layer "In6.Cu")
		(net "P5E_CPU0_P2_RX_DP<7>")
	)
	(segment
		(start 412.488126 -393.930632)
		(end 412.576264 -393.842494)
		(width 0.14224)
		(layer "In6.Cu")
		(net "P5E_CPU0_P2_RX_DP<7>")
	)
	(segment
		(start 379.385068 -314.050934)
		(end 378.09805 -312.124852)
		(width 0.14224)
		(layer "In6.Cu")
		(net "P5E_CPU0_P2_RX_DP<7>")
	)
	(segment
		(start 378.09805 -312.124852)
		(end 372.495318 -305.29784)
		(width 0.14224)
		(layer "In6.Cu")
		(net "P5E_CPU0_P2_RX_DP<7>")
	)
	(segment
		(start 367.347754 -287.533588)
		(end 367.34877 -287.53308)
		(width 0.1143)
		(layer "In6.Cu")
		(net "P5E_CPU0_P2_RX_DP<7>")
	)
	(segment
		(start 367.785142 -286.742378)
		(end 367.85677 -286.700722)
		(width 0.1143)
		(layer "In6.Cu")
		(net "P5E_CPU0_P2_RX_DP<7>")
	)
	(segment
		(start 387.92404 -342.392)
		(end 387.384036 -336.91322)
		(width 0.14224)
		(layer "In6.Cu")
		(net "P5E_CPU0_P2_RX_DP<7>")
	)
	(segment
		(start 384.882136 -324.334632)
		(end 379.385068 -314.050934)
		(width 0.14224)
		(layer "In6.Cu")
		(net "P5E_CPU0_P2_RX_DP<7>")
	)
	(segment
		(start 368.156236 -297.703494)
		(end 368.156236 -296.353484)
		(width 0.14224)
		(layer "In6.Cu")
		(net "P5E_CPU0_P2_RX_DP<7>")
	)
	(segment
		(start 367.346992 -287.534096)
		(end 367.347754 -287.533588)
		(width 0.1143)
		(layer "In6.Cu")
		(net "P5E_CPU0_P2_RX_DP<7>")
	)
	(arc
		(start 367.38433 -287.512252)
		(mid 367.564982 -287.309507)
		(end 367.630202 -287.045908)
		(width 0.1143)
		(layer "In6.Cu")
		(net "P5E_CPU0_P2_RX_DP<7>")
	)
	(arc
		(start 367.31702 -294.640762)
		(mid 367.160043 -294.335962)
		(end 367.31702 -294.031162)
		(width 0.1143)
		(layer "In6.Cu")
		(net "P5E_CPU0_P2_RX_DP<7>")
	)
	(arc
		(start 367.31702 -291.400738)
		(mid 367.160043 -291.095938)
		(end 367.31702 -290.791138)
		(width 0.1143)
		(layer "In6.Cu")
		(net "P5E_CPU0_P2_RX_DP<7>")
	)
	(arc
		(start 367.38687 -289.130486)
		(mid 367.630197 -288.66592)
		(end 367.38687 -288.201354)
		(width 0.1143)
		(layer "In6.Cu")
		(net "P5E_CPU0_P2_RX_DP<7>")
	)
	(arc
		(start 367.386616 -292.37051)
		(mid 367.629943 -291.905944)
		(end 367.386616 -291.441378)
		(width 0.1143)
		(layer "In6.Cu")
		(net "P5E_CPU0_P2_RX_DP<7>")
	)
	(arc
		(start 367.787174 -295.450768)
		(mid 367.671747 -295.317392)
		(end 367.630202 -295.145968)
		(width 0.1143)
		(layer "In6.Cu")
		(net "P5E_CPU0_P2_RX_DP<7>")
	)
	(arc
		(start 389.670544 -350.675194)
		(mid 389.502913 -350.206665)
		(end 389.382 -349.723964)
		(width 0.14224)
		(layer "In6.Cu")
		(net "P5E_CPU0_P2_RX_DP<7>")
	)
	(arc
		(start 410.82722 -376.050048)
		(mid 410.251638 -375.612768)
		(end 409.580334 -375.34469)
		(width 0.14224)
		(layer "In6.Cu")
		(net "P5E_CPU0_P2_RX_DP<7>")
	)
	(arc
		(start 367.31702 -289.780726)
		(mid 367.160043 -289.475926)
		(end 367.31702 -289.171126)
		(width 0.1143)
		(layer "In6.Cu")
		(net "P5E_CPU0_P2_RX_DP<7>")
	)
	(arc
		(start 367.86312 -295.49598)
		(mid 367.858691 -295.492783)
		(end 367.85423 -295.48963)
		(width 0.1143)
		(layer "In6.Cu")
		(net "P5E_CPU0_P2_RX_DP<7>")
	)
	(arc
		(start 367.85677 -286.700722)
		(mid 368.008757 -286.544214)
		(end 368.090196 -286.34182)
		(width 0.1143)
		(layer "In6.Cu")
		(net "P5E_CPU0_P2_RX_DP<7>")
	)
	(arc
		(start 368.110008 -295.96588)
		(mid 368.042028 -295.701789)
		(end 367.86312 -295.49598)
		(width 0.1143)
		(layer "In6.Cu")
		(net "P5E_CPU0_P2_RX_DP<7>")
	)
	(arc
		(start 411.12821 -376.520456)
		(mid 411.097096 -376.363742)
		(end 411.008322 -376.230896)
		(width 0.14224)
		(layer "In6.Cu")
		(net "P5E_CPU0_P2_RX_DP<7>")
	)
	(arc
		(start 367.31702 -293.02075)
		(mid 367.160043 -292.71595)
		(end 367.31702 -292.41115)
		(width 0.1143)
		(layer "In6.Cu")
		(net "P5E_CPU0_P2_RX_DP<7>")
	)
	(arc
		(start 367.630202 -287.045908)
		(mid 367.671168 -286.875502)
		(end 367.785142 -286.742378)
		(width 0.1143)
		(layer "In6.Cu")
		(net "P5E_CPU0_P2_RX_DP<7>")
	)
	(arc
		(start 367.386616 -293.990522)
		(mid 367.629943 -293.525956)
		(end 367.386616 -293.06139)
		(width 0.1143)
		(layer "In6.Cu")
		(net "P5E_CPU0_P2_RX_DP<7>")
	)
	(arc
		(start 398.866106 -369.858544)
		(mid 398.813366 -369.823697)
		(end 398.765776 -369.78209)
		(width 0.14224)
		(layer "In6.Cu")
		(net "P5E_CPU0_P2_RX_DP<7>")
	)
	(arc
		(start 411.20695 -380.67615)
		(mid 411.149701 -380.629451)
		(end 411.12821 -380.558802)
		(width 0.14224)
		(layer "In6.Cu")
		(net "P5E_CPU0_P2_RX_DP<7>")
	)
	(arc
		(start 367.160048 -287.856168)
		(mid 367.20218 -287.685663)
		(end 367.316004 -287.551876)
		(width 0.1143)
		(layer "In6.Cu")
		(net "P5E_CPU0_P2_RX_DP<7>")
	)
	(arc
		(start 396.926562 -367.942876)
		(mid 396.76945 -367.751391)
		(end 396.65275 -367.53292)
		(width 0.14224)
		(layer "In6.Cu")
		(net "P5E_CPU0_P2_RX_DP<7>")
	)
	(arc
		(start 387.925818 -342.404192)
		(mid 387.924782 -342.398117)
		(end 387.92404 -342.392)
		(width 0.14224)
		(layer "In6.Cu")
		(net "P5E_CPU0_P2_RX_DP<7>")
	)
	(arc
		(start 367.386616 -290.750498)
		(mid 367.629943 -290.285932)
		(end 367.386616 -289.821366)
		(width 0.1143)
		(layer "In6.Cu")
		(net "P5E_CPU0_P2_RX_DP<7>")
	)
	(arc
		(start 412.387796 -381.198882)
		(mid 412.325836 -381.148187)
		(end 412.255208 -381.11049)
		(width 0.14224)
		(layer "In6.Cu")
		(net "P5E_CPU0_P2_RX_DP<7>")
	)
	(arc
		(start 407.793444 -374.897142)
		(mid 407.733313 -374.877595)
		(end 407.67635 -374.850152)
		(width 0.14224)
		(layer "In6.Cu")
		(net "P5E_CPU0_P2_RX_DP<7>")
	)
	(arc
		(start 412.905702 -381.88646)
		(mid 412.874539 -381.729882)
		(end 412.785814 -381.597154)
		(width 0.14224)
		(layer "In6.Cu")
		(net "P5E_CPU0_P2_RX_DP<7>")
	)
	(arc
		(start 367.314226 -288.158936)
		(mid 367.200819 -288.026047)
		(end 367.160048 -287.856168)
		(width 0.1143)
		(layer "In6.Cu")
		(net "P5E_CPU0_P2_RX_DP<7>")
	)
	(arc
		(start 367.629948 -295.145968)
		(mid 367.565433 -294.883749)
		(end 367.386616 -294.681402)
		(width 0.1143)
		(layer "In6.Cu")
		(net "P5E_CPU0_P2_RX_DP<7>")
	)
	(arc
		(start 368.090196 -286.34182)
		(mid 368.092219 -286.33041)
		(end 368.094006 -286.31896)
		(width 0.1143)
		(layer "In6.Cu")
		(net "P5E_CPU0_P2_RX_DP<7>")
	)
	(segment
		(start 368.0079 -282.730194)
		(end 368.474752 -282.996132)
		(width 0.12954)
		(layer "F.Cu")
		(net "P5E_CPU0_P2_RX_DP<6>")
	)
	(segment
		(start 410.49829 -394.385292)
		(end 411.01899 -394.385292)
		(width 0.127)
		(layer "F.Cu")
		(net "P5E_CPU0_P2_RX_DP<6>")
	)
	(segment
		(start 366.877854 -295.468548)
		(end 366.846104 -295.45026)
		(width 0.1143)
		(layer "In6.Cu")
		(net "P5E_CPU0_P2_RX_DP<6>")
	)
	(segment
		(start 366.446816 -288.201354)
		(end 366.4077 -288.178494)
		(width 0.1143)
		(layer "In6.Cu")
		(net "P5E_CPU0_P2_RX_DP<6>")
	)
	(segment
		(start 366.4077 -294.658542)
		(end 366.37722 -294.640762)
		(width 0.1143)
		(layer "In6.Cu")
		(net "P5E_CPU0_P2_RX_DP<6>")
	)
	(segment
		(start 366.37722 -287.551368)
		(end 366.444276 -287.512252)
		(width 0.1143)
		(layer "In6.Cu")
		(net "P5E_CPU0_P2_RX_DP<6>")
	)
	(segment
		(start 367.205768 -296.325036)
		(end 367.160048 -296.279316)
		(width 0.1143)
		(layer "In6.Cu")
		(net "P5E_CPU0_P2_RX_DP<6>")
	)
	(segment
		(start 386.434076 -336.917538)
		(end 383.996692 -324.663054)
		(width 0.14224)
		(layer "In6.Cu")
		(net "P5E_CPU0_P2_RX_DP<6>")
	)
	(segment
		(start 411.06344 -392.734546)
		(end 411.36824 -392.429746)
		(width 0.14224)
		(layer "In6.Cu")
		(net "P5E_CPU0_P2_RX_DP<6>")
	)
	(segment
		(start 411.376368 -393.842494)
		(end 411.376368 -393.428982)
		(width 0.14224)
		(layer "In6.Cu")
		(net "P5E_CPU0_P2_RX_DP<6>")
	)
	(segment
		(start 411.355286 -391.063988)
		(end 409.629864 -384.4671)
		(width 0.14224)
		(layer "In6.Cu")
		(net "P5E_CPU0_P2_RX_DP<6>")
	)
	(segment
		(start 378.714508 -314.7822)
		(end 377.219718 -312.54446)
		(width 0.14224)
		(layer "In6.Cu")
		(net "P5E_CPU0_P2_RX_DP<6>")
	)
	(segment
		(start 367.346992 -284.294072)
		(end 367.347754 -284.293564)
		(width 0.1143)
		(layer "In6.Cu")
		(net "P5E_CPU0_P2_RX_DP<6>")
	)
	(segment
		(start 366.37722 -292.41115)
		(end 366.4077 -292.39337)
		(width 0.1143)
		(layer "In6.Cu")
		(net "P5E_CPU0_P2_RX_DP<6>")
	)
	(segment
		(start 367.160048 -296.279316)
		(end 367.160048 -296.086022)
		(width 0.1143)
		(layer "In6.Cu")
		(net "P5E_CPU0_P2_RX_DP<6>")
	)
	(segment
		(start 366.882172 -295.471088)
		(end 366.880648 -295.470072)
		(width 0.1143)
		(layer "In6.Cu")
		(net "P5E_CPU0_P2_RX_DP<6>")
	)
	(segment
		(start 366.4077 -292.39337)
		(end 366.446816 -292.37051)
		(width 0.1143)
		(layer "In6.Cu")
		(net "P5E_CPU0_P2_RX_DP<6>")
	)
	(segment
		(start 367.34877 -284.293056)
		(end 367.349786 -284.292294)
		(width 0.1143)
		(layer "In6.Cu")
		(net "P5E_CPU0_P2_RX_DP<6>")
	)
	(segment
		(start 366.37722 -289.171126)
		(end 366.4077 -289.153346)
		(width 0.1143)
		(layer "In6.Cu")
		(net "P5E_CPU0_P2_RX_DP<6>")
	)
	(segment
		(start 366.4077 -288.178494)
		(end 366.375188 -288.159698)
		(width 0.1143)
		(layer "In6.Cu")
		(net "P5E_CPU0_P2_RX_DP<6>")
	)
	(segment
		(start 377.219718 -312.54446)
		(end 371.756686 -305.881278)
		(width 0.14224)
		(layer "In6.Cu")
		(net "P5E_CPU0_P2_RX_DP<6>")
	)
	(segment
		(start 367.787174 -283.501338)
		(end 367.85677 -283.460698)
		(width 0.1143)
		(layer "In6.Cu")
		(net "P5E_CPU0_P2_RX_DP<6>")
	)
	(segment
		(start 367.163858 -284.628082)
		(end 367.163858 -284.610302)
		(width 0.1143)
		(layer "In6.Cu")
		(net "P5E_CPU0_P2_RX_DP<6>")
	)
	(segment
		(start 368.437922 -300.903894)
		(end 367.205768 -297.911774)
		(width 0.14224)
		(layer "In6.Cu")
		(net "P5E_CPU0_P2_RX_DP<6>")
	)
	(segment
		(start 366.446816 -293.06139)
		(end 366.4077 -293.03853)
		(width 0.1143)
		(layer "In6.Cu")
		(net "P5E_CPU0_P2_RX_DP<6>")
	)
	(segment
		(start 366.877854 -285.104332)
		(end 366.896142 -285.092902)
		(width 0.1143)
		(layer "In6.Cu")
		(net "P5E_CPU0_P2_RX_DP<6>")
	)
	(segment
		(start 407.37917 -375.763028)
		(end 398.257268 -370.596668)
		(width 0.14224)
		(layer "In6.Cu")
		(net "P5E_CPU0_P2_RX_DP<6>")
	)
	(segment
		(start 366.446816 -291.441378)
		(end 366.4077 -291.418518)
		(width 0.1143)
		(layer "In6.Cu")
		(net "P5E_CPU0_P2_RX_DP<6>")
	)
	(segment
		(start 411.01899 -394.385292)
		(end 411.113986 -394.031216)
		(width 0.14224)
		(layer "In6.Cu")
		(net "P5E_CPU0_P2_RX_DP<6>")
	)
	(segment
		(start 366.910112 -295.487344)
		(end 366.90935 -295.486836)
		(width 0.1143)
		(layer "In6.Cu")
		(net "P5E_CPU0_P2_RX_DP<6>")
	)
	(segment
		(start 366.4077 -293.03853)
		(end 366.37722 -293.02075)
		(width 0.1143)
		(layer "In6.Cu")
		(net "P5E_CPU0_P2_RX_DP<6>")
	)
	(segment
		(start 366.4077 -290.773358)
		(end 366.446816 -290.750498)
		(width 0.1143)
		(layer "In6.Cu")
		(net "P5E_CPU0_P2_RX_DP<6>")
	)
	(segment
		(start 367.205768 -297.911774)
		(end 367.205768 -296.353484)
		(width 0.14224)
		(layer "In6.Cu")
		(net "P5E_CPU0_P2_RX_DP<6>")
	)
	(segment
		(start 366.878616 -285.746952)
		(end 366.8776 -285.746444)
		(width 0.1143)
		(layer "In6.Cu")
		(net "P5E_CPU0_P2_RX_DP<6>")
	)
	(segment
		(start 366.446816 -289.821366)
		(end 366.4077 -289.798506)
		(width 0.1143)
		(layer "In6.Cu")
		(net "P5E_CPU0_P2_RX_DP<6>")
	)
	(segment
		(start 367.160048 -296.086022)
		(end 367.160302 -296.085768)
		(width 0.1143)
		(layer "In6.Cu")
		(net "P5E_CPU0_P2_RX_DP<6>")
	)
	(segment
		(start 383.996692 -324.663054)
		(end 378.714508 -314.7822)
		(width 0.14224)
		(layer "In6.Cu")
		(net "P5E_CPU0_P2_RX_DP<6>")
	)
	(segment
		(start 366.880648 -295.470072)
		(end 366.87887 -295.469056)
		(width 0.1143)
		(layer "In6.Cu")
		(net "P5E_CPU0_P2_RX_DP<6>")
	)
	(segment
		(start 366.37722 -294.031162)
		(end 366.4077 -294.013382)
		(width 0.1143)
		(layer "In6.Cu")
		(net "P5E_CPU0_P2_RX_DP<6>")
	)
	(segment
		(start 408.456384 -376.032776)
		(end 407.37917 -375.763028)
		(width 0.14224)
		(layer "In6.Cu")
		(net "P5E_CPU0_P2_RX_DP<6>")
	)
	(segment
		(start 398.23009 -370.576094)
		(end 396.189708 -368.535712)
		(width 0.14224)
		(layer "In6.Cu")
		(net "P5E_CPU0_P2_RX_DP<6>")
	)
	(segment
		(start 366.87887 -295.469056)
		(end 366.877854 -295.468548)
		(width 0.1143)
		(layer "In6.Cu")
		(net "P5E_CPU0_P2_RX_DP<6>")
	)
	(segment
		(start 386.979414 -342.450928)
		(end 386.434076 -336.917538)
		(width 0.14224)
		(layer "In6.Cu")
		(net "P5E_CPU0_P2_RX_DP<6>")
	)
	(segment
		(start 366.37722 -290.791138)
		(end 366.4077 -290.773358)
		(width 0.1143)
		(layer "In6.Cu")
		(net "P5E_CPU0_P2_RX_DP<6>")
	)
	(segment
		(start 366.4077 -289.798506)
		(end 366.37722 -289.780726)
		(width 0.1143)
		(layer "In6.Cu")
		(net "P5E_CPU0_P2_RX_DP<6>")
	)
	(segment
		(start 368.17681 -282.996132)
		(end 368.474752 -282.996132)
		(width 0.1143)
		(layer "In6.Cu")
		(net "P5E_CPU0_P2_RX_DP<6>")
	)
	(segment
		(start 366.4077 -291.418518)
		(end 366.37722 -291.400738)
		(width 0.1143)
		(layer "In6.Cu")
		(net "P5E_CPU0_P2_RX_DP<6>")
	)
	(segment
		(start 366.91697 -295.491408)
		(end 366.910112 -295.487344)
		(width 0.1143)
		(layer "In6.Cu")
		(net "P5E_CPU0_P2_RX_DP<6>")
	)
	(segment
		(start 411.376368 -393.428982)
		(end 411.060392 -393.113006)
		(width 0.14224)
		(layer "In6.Cu")
		(net "P5E_CPU0_P2_RX_DP<6>")
	)
	(segment
		(start 367.205768 -296.353484)
		(end 367.205768 -296.325036)
		(width 0.1143)
		(layer "In6.Cu")
		(net "P5E_CPU0_P2_RX_DP<6>")
	)
	(segment
		(start 367.350802 -284.291786)
		(end 367.35258 -284.29077)
		(width 0.1143)
		(layer "In6.Cu")
		(net "P5E_CPU0_P2_RX_DP<6>")
	)
	(segment
		(start 367.160302 -296.085768)
		(end 367.160302 -295.955974)
		(width 0.1143)
		(layer "In6.Cu")
		(net "P5E_CPU0_P2_RX_DP<6>")
	)
	(segment
		(start 411.113986 -394.031216)
		(end 411.28823 -393.930632)
		(width 0.14224)
		(layer "In6.Cu")
		(net "P5E_CPU0_P2_RX_DP<6>")
	)
	(segment
		(start 368.094006 -283.078936)
		(end 368.17681 -282.996132)
		(width 0.1143)
		(layer "In6.Cu")
		(net "P5E_CPU0_P2_RX_DP<6>")
	)
	(segment
		(start 366.90935 -295.486836)
		(end 366.884712 -295.472612)
		(width 0.1143)
		(layer "In6.Cu")
		(net "P5E_CPU0_P2_RX_DP<6>")
	)
	(segment
		(start 411.28823 -393.930632)
		(end 411.376368 -393.842494)
		(width 0.14224)
		(layer "In6.Cu")
		(net "P5E_CPU0_P2_RX_DP<6>")
	)
	(segment
		(start 371.756686 -305.881278)
		(end 368.437922 -300.903894)
		(width 0.14224)
		(layer "In6.Cu")
		(net "P5E_CPU0_P2_RX_DP<6>")
	)
	(segment
		(start 409.430728 -382.915922)
		(end 409.430474 -382.916176)
		(width 0.14224)
		(layer "In6.Cu")
		(net "P5E_CPU0_P2_RX_DP<6>")
	)
	(segment
		(start 366.446816 -294.681402)
		(end 366.4077 -294.658542)
		(width 0.1143)
		(layer "In6.Cu")
		(net "P5E_CPU0_P2_RX_DP<6>")
	)
	(segment
		(start 367.349786 -284.292294)
		(end 367.350802 -284.291786)
		(width 0.1143)
		(layer "In6.Cu")
		(net "P5E_CPU0_P2_RX_DP<6>")
	)
	(segment
		(start 388.442962 -349.812864)
		(end 386.981192 -342.46312)
		(width 0.14224)
		(layer "In6.Cu")
		(net "P5E_CPU0_P2_RX_DP<6>")
	)
	(segment
		(start 411.36824 -392.429746)
		(end 411.36824 -391.16762)
		(width 0.14224)
		(layer "In6.Cu")
		(net "P5E_CPU0_P2_RX_DP<6>")
	)
	(segment
		(start 366.4077 -289.153346)
		(end 366.446816 -289.130486)
		(width 0.1143)
		(layer "In6.Cu")
		(net "P5E_CPU0_P2_RX_DP<6>")
	)
	(segment
		(start 367.347754 -284.293564)
		(end 367.34877 -284.293056)
		(width 0.1143)
		(layer "In6.Cu")
		(net "P5E_CPU0_P2_RX_DP<6>")
	)
	(segment
		(start 366.884712 -295.472612)
		(end 366.883188 -295.471596)
		(width 0.1143)
		(layer "In6.Cu")
		(net "P5E_CPU0_P2_RX_DP<6>")
	)
	(segment
		(start 366.876584 -285.105094)
		(end 366.877854 -285.104332)
		(width 0.1143)
		(layer "In6.Cu")
		(net "P5E_CPU0_P2_RX_DP<6>")
	)
	(segment
		(start 366.4077 -294.013382)
		(end 366.446816 -293.990522)
		(width 0.1143)
		(layer "In6.Cu")
		(net "P5E_CPU0_P2_RX_DP<6>")
	)
	(segment
		(start 409.430474 -382.916176)
		(end 409.430474 -377.288044)
		(width 0.14224)
		(layer "In6.Cu")
		(net "P5E_CPU0_P2_RX_DP<6>")
	)
	(segment
		(start 366.883188 -295.471596)
		(end 366.882172 -295.471088)
		(width 0.1143)
		(layer "In6.Cu")
		(net "P5E_CPU0_P2_RX_DP<6>")
	)
	(segment
		(start 411.060392 -393.113006)
		(end 411.06344 -392.734546)
		(width 0.14224)
		(layer "In6.Cu")
		(net "P5E_CPU0_P2_RX_DP<6>")
	)
	(segment
		(start 395.585188 -367.630964)
		(end 389.09498 -351.961704)
		(width 0.14224)
		(layer "In6.Cu")
		(net "P5E_CPU0_P2_RX_DP<6>")
	)
	(segment
		(start 366.844326 -286.74314)
		(end 366.914176 -286.7025)
		(width 0.1143)
		(layer "In6.Cu")
		(net "P5E_CPU0_P2_RX_DP<6>")
	)
	(arc
		(start 368.090196 -283.101796)
		(mid 368.092219 -283.090386)
		(end 368.094006 -283.078936)
		(width 0.1143)
		(layer "In6.Cu")
		(net "P5E_CPU0_P2_RX_DP<6>")
	)
	(arc
		(start 396.189708 -368.535712)
		(mid 395.84292 -368.113094)
		(end 395.585188 -367.630964)
		(width 0.14224)
		(layer "In6.Cu")
		(net "P5E_CPU0_P2_RX_DP<6>")
	)
	(arc
		(start 367.060734 -295.635426)
		(mid 366.995382 -295.556899)
		(end 366.91697 -295.491408)
		(width 0.1143)
		(layer "In6.Cu")
		(net "P5E_CPU0_P2_RX_DP<6>")
	)
	(arc
		(start 366.37722 -291.400738)
		(mid 366.220243 -291.095938)
		(end 366.37722 -290.791138)
		(width 0.1143)
		(layer "In6.Cu")
		(net "P5E_CPU0_P2_RX_DP<6>")
	)
	(arc
		(start 366.37722 -294.640762)
		(mid 366.220243 -294.335962)
		(end 366.37722 -294.031162)
		(width 0.1143)
		(layer "In6.Cu")
		(net "P5E_CPU0_P2_RX_DP<6>")
	)
	(arc
		(start 366.446816 -290.750498)
		(mid 366.690143 -290.285932)
		(end 366.446816 -289.821366)
		(width 0.1143)
		(layer "In6.Cu")
		(net "P5E_CPU0_P2_RX_DP<6>")
	)
	(arc
		(start 367.35258 -284.29077)
		(mid 367.555868 -284.085392)
		(end 367.630202 -283.806138)
		(width 0.1143)
		(layer "In6.Cu")
		(net "P5E_CPU0_P2_RX_DP<6>")
	)
	(arc
		(start 366.375188 -288.159698)
		(mid 366.261259 -288.026551)
		(end 366.220248 -287.856168)
		(width 0.1143)
		(layer "In6.Cu")
		(net "P5E_CPU0_P2_RX_DP<6>")
	)
	(arc
		(start 366.220248 -287.856168)
		(mid 366.261797 -287.684746)
		(end 366.37722 -287.551368)
		(width 0.1143)
		(layer "In6.Cu")
		(net "P5E_CPU0_P2_RX_DP<6>")
	)
	(arc
		(start 366.446816 -292.37051)
		(mid 366.690143 -291.905944)
		(end 366.446816 -291.441378)
		(width 0.1143)
		(layer "In6.Cu")
		(net "P5E_CPU0_P2_RX_DP<6>")
	)
	(arc
		(start 366.444276 -287.512252)
		(mid 366.624928 -287.309507)
		(end 366.690148 -287.045908)
		(width 0.1143)
		(layer "In6.Cu")
		(net "P5E_CPU0_P2_RX_DP<6>")
	)
	(arc
		(start 386.981192 -342.46312)
		(mid 386.980158 -342.457045)
		(end 386.979414 -342.450928)
		(width 0.14224)
		(layer "In6.Cu")
		(net "P5E_CPU0_P2_RX_DP<6>")
	)
	(arc
		(start 367.85677 -283.460698)
		(mid 368.008757 -283.30419)
		(end 368.090196 -283.101796)
		(width 0.1143)
		(layer "In6.Cu")
		(net "P5E_CPU0_P2_RX_DP<6>")
	)
	(arc
		(start 366.37722 -289.780726)
		(mid 366.220243 -289.475926)
		(end 366.37722 -289.171126)
		(width 0.1143)
		(layer "In6.Cu")
		(net "P5E_CPU0_P2_RX_DP<6>")
	)
	(arc
		(start 409.049728 -376.368818)
		(mid 408.775874 -376.160505)
		(end 408.456384 -376.032776)
		(width 0.14224)
		(layer "In6.Cu")
		(net "P5E_CPU0_P2_RX_DP<6>")
	)
	(arc
		(start 366.846104 -295.45026)
		(mid 366.731428 -295.316926)
		(end 366.690148 -295.145968)
		(width 0.1143)
		(layer "In6.Cu")
		(net "P5E_CPU0_P2_RX_DP<6>")
	)
	(arc
		(start 366.896142 -285.092902)
		(mid 367.092114 -284.896273)
		(end 367.163858 -284.628082)
		(width 0.1143)
		(layer "In6.Cu")
		(net "P5E_CPU0_P2_RX_DP<6>")
	)
	(arc
		(start 409.629864 -384.4671)
		(mid 409.480614 -383.697888)
		(end 409.430728 -382.915922)
		(width 0.14224)
		(layer "In6.Cu")
		(net "P5E_CPU0_P2_RX_DP<6>")
	)
	(arc
		(start 367.160302 -295.955974)
		(mid 367.134882 -295.788129)
		(end 367.060734 -295.635426)
		(width 0.1143)
		(layer "In6.Cu")
		(net "P5E_CPU0_P2_RX_DP<6>")
	)
	(arc
		(start 366.8776 -285.746444)
		(mid 366.692014 -285.426019)
		(end 366.876584 -285.105094)
		(width 0.1143)
		(layer "In6.Cu")
		(net "P5E_CPU0_P2_RX_DP<6>")
	)
	(arc
		(start 411.36824 -391.16762)
		(mid 411.365091 -391.115387)
		(end 411.355286 -391.063988)
		(width 0.14224)
		(layer "In6.Cu")
		(net "P5E_CPU0_P2_RX_DP<6>")
	)
	(arc
		(start 367.163858 -284.610302)
		(mid 367.212955 -284.4276)
		(end 367.346992 -284.294072)
		(width 0.1143)
		(layer "In6.Cu")
		(net "P5E_CPU0_P2_RX_DP<6>")
	)
	(arc
		(start 389.09498 -351.961704)
		(mid 388.716189 -350.9033)
		(end 388.442962 -349.812864)
		(width 0.14224)
		(layer "In6.Cu")
		(net "P5E_CPU0_P2_RX_DP<6>")
	)
	(arc
		(start 398.257268 -370.596668)
		(mid 398.242988 -370.587294)
		(end 398.23009 -370.576094)
		(width 0.14224)
		(layer "In6.Cu")
		(net "P5E_CPU0_P2_RX_DP<6>")
	)
	(arc
		(start 366.446816 -289.130486)
		(mid 366.690143 -288.66592)
		(end 366.446816 -288.201354)
		(width 0.1143)
		(layer "In6.Cu")
		(net "P5E_CPU0_P2_RX_DP<6>")
	)
	(arc
		(start 366.690148 -287.045908)
		(mid 366.73091 -286.876024)
		(end 366.844326 -286.74314)
		(width 0.1143)
		(layer "In6.Cu")
		(net "P5E_CPU0_P2_RX_DP<6>")
	)
	(arc
		(start 367.630202 -283.806138)
		(mid 367.671751 -283.634716)
		(end 367.787174 -283.501338)
		(width 0.1143)
		(layer "In6.Cu")
		(net "P5E_CPU0_P2_RX_DP<6>")
	)
	(arc
		(start 366.690148 -295.145968)
		(mid 366.625633 -294.883749)
		(end 366.446816 -294.681402)
		(width 0.1143)
		(layer "In6.Cu")
		(net "P5E_CPU0_P2_RX_DP<6>")
	)
	(arc
		(start 409.430474 -377.288044)
		(mid 409.33152 -376.790566)
		(end 409.049728 -376.368818)
		(width 0.14224)
		(layer "In6.Cu")
		(net "P5E_CPU0_P2_RX_DP<6>")
	)
	(arc
		(start 366.914176 -286.7025)
		(mid 367.159775 -286.2149)
		(end 366.878616 -285.746952)
		(width 0.1143)
		(layer "In6.Cu")
		(net "P5E_CPU0_P2_RX_DP<6>")
	)
	(arc
		(start 366.446816 -293.990522)
		(mid 366.690143 -293.525956)
		(end 366.446816 -293.06139)
		(width 0.1143)
		(layer "In6.Cu")
		(net "P5E_CPU0_P2_RX_DP<6>")
	)
	(arc
		(start 366.37722 -293.02075)
		(mid 366.220243 -292.71595)
		(end 366.37722 -292.41115)
		(width 0.1143)
		(layer "In6.Cu")
		(net "P5E_CPU0_P2_RX_DP<6>")
	)
	(segment
		(start 365.187992 -284.350206)
		(end 365.654844 -284.616144)
		(width 0.12954)
		(layer "F.Cu")
		(net "P5E_CPU0_P2_RX_DP<5>")
	)
	(segment
		(start 409.298394 -394.385292)
		(end 409.819094 -394.385292)
		(width 0.127)
		(layer "F.Cu")
		(net "P5E_CPU0_P2_RX_DP<5>")
	)
	(segment
		(start 365.467646 -293.03853)
		(end 365.437166 -293.02075)
		(width 0.1143)
		(layer "In6.Cu")
		(net "P5E_CPU0_P2_RX_DP<5>")
	)
	(segment
		(start 405.305514 -375.660412)
		(end 397.654018 -371.326664)
		(width 0.14224)
		(layer "In6.Cu")
		(net "P5E_CPU0_P2_RX_DP<5>")
	)
	(segment
		(start 365.506762 -291.441378)
		(end 365.467646 -291.418518)
		(width 0.1143)
		(layer "In6.Cu")
		(net "P5E_CPU0_P2_RX_DP<5>")
	)
	(segment
		(start 406.513792 -378.406914)
		(end 406.229312 -378.122434)
		(width 0.14224)
		(layer "In6.Cu")
		(net "P5E_CPU0_P2_RX_DP<5>")
	)
	(segment
		(start 405.597106 -375.952004)
		(end 405.305514 -375.660412)
		(width 0.14224)
		(layer "In6.Cu")
		(net "P5E_CPU0_P2_RX_DP<5>")
	)
	(segment
		(start 365.467646 -292.39337)
		(end 365.506762 -292.37051)
		(width 0.1143)
		(layer "In6.Cu")
		(net "P5E_CPU0_P2_RX_DP<5>")
	)
	(segment
		(start 387.757162 -351.188782)
		(end 386.049266 -342.602566)
		(width 0.14224)
		(layer "In6.Cu")
		(net "P5E_CPU0_P2_RX_DP<5>")
	)
	(segment
		(start 365.970058 -295.487344)
		(end 365.969296 -295.486836)
		(width 0.1143)
		(layer "In6.Cu")
		(net "P5E_CPU0_P2_RX_DP<5>")
	)
	(segment
		(start 406.023064 -377.624594)
		(end 406.023064 -376.98045)
		(width 0.14224)
		(layer "In6.Cu")
		(net "P5E_CPU0_P2_RX_DP<5>")
	)
	(segment
		(start 365.976916 -295.491408)
		(end 365.970058 -295.487344)
		(width 0.1143)
		(layer "In6.Cu")
		(net "P5E_CPU0_P2_RX_DP<5>")
	)
	(segment
		(start 365.942118 -295.471088)
		(end 365.940594 -295.470072)
		(width 0.1143)
		(layer "In6.Cu")
		(net "P5E_CPU0_P2_RX_DP<5>")
	)
	(segment
		(start 365.506762 -289.821366)
		(end 365.467646 -289.798506)
		(width 0.1143)
		(layer "In6.Cu")
		(net "P5E_CPU0_P2_RX_DP<5>")
	)
	(segment
		(start 409.819094 -394.385292)
		(end 409.91409 -394.031216)
		(width 0.14224)
		(layer "In6.Cu")
		(net "P5E_CPU0_P2_RX_DP<5>")
	)
	(segment
		(start 387.757162 -351.189036)
		(end 387.757162 -351.188782)
		(width 0.14224)
		(layer "In6.Cu")
		(net "P5E_CPU0_P2_RX_DP<5>")
	)
	(segment
		(start 365.467646 -289.153346)
		(end 365.506762 -289.130486)
		(width 0.1143)
		(layer "In6.Cu")
		(net "P5E_CPU0_P2_RX_DP<5>")
	)
	(segment
		(start 365.9378 -295.468548)
		(end 365.90605 -295.45026)
		(width 0.1143)
		(layer "In6.Cu")
		(net "P5E_CPU0_P2_RX_DP<5>")
	)
	(segment
		(start 410.168344 -392.429746)
		(end 410.168344 -391.085324)
		(width 0.14224)
		(layer "In6.Cu")
		(net "P5E_CPU0_P2_RX_DP<5>")
	)
	(segment
		(start 365.943134 -295.471596)
		(end 365.942118 -295.471088)
		(width 0.1143)
		(layer "In6.Cu")
		(net "P5E_CPU0_P2_RX_DP<5>")
	)
	(segment
		(start 366.220248 -296.279316)
		(end 366.220248 -295.955974)
		(width 0.1143)
		(layer "In6.Cu")
		(net "P5E_CPU0_P2_RX_DP<5>")
	)
	(segment
		(start 407.72461 -382.070356)
		(end 407.72461 -379.638052)
		(width 0.14224)
		(layer "In6.Cu")
		(net "P5E_CPU0_P2_RX_DP<5>")
	)
	(segment
		(start 365.904272 -286.74314)
		(end 365.974122 -286.7025)
		(width 0.1143)
		(layer "In6.Cu")
		(net "P5E_CPU0_P2_RX_DP<5>")
	)
	(segment
		(start 371.049042 -306.509928)
		(end 367.600738 -301.349156)
		(width 0.14224)
		(layer "In6.Cu")
		(net "P5E_CPU0_P2_RX_DP<5>")
	)
	(segment
		(start 365.356902 -284.616144)
		(end 365.654844 -284.616144)
		(width 0.1143)
		(layer "In6.Cu")
		(net "P5E_CPU0_P2_RX_DP<5>")
	)
	(segment
		(start 386.047488 -342.590374)
		(end 385.493768 -336.969354)
		(width 0.14224)
		(layer "In6.Cu")
		(net "P5E_CPU0_P2_RX_DP<5>")
	)
	(segment
		(start 365.940594 -295.470072)
		(end 365.938816 -295.469056)
		(width 0.1143)
		(layer "In6.Cu")
		(net "P5E_CPU0_P2_RX_DP<5>")
	)
	(segment
		(start 378.03582 -315.497464)
		(end 376.329702 -312.94451)
		(width 0.14224)
		(layer "In6.Cu")
		(net "P5E_CPU0_P2_RX_DP<5>")
	)
	(segment
		(start 367.600738 -301.349156)
		(end 366.265968 -298.125896)
		(width 0.14224)
		(layer "In6.Cu")
		(net "P5E_CPU0_P2_RX_DP<5>")
	)
	(segment
		(start 366.265968 -296.353484)
		(end 366.265968 -296.325036)
		(width 0.1143)
		(layer "In6.Cu")
		(net "P5E_CPU0_P2_RX_DP<5>")
	)
	(segment
		(start 365.467646 -294.658542)
		(end 365.437166 -294.640762)
		(width 0.1143)
		(layer "In6.Cu")
		(net "P5E_CPU0_P2_RX_DP<5>")
	)
	(segment
		(start 365.467646 -294.013382)
		(end 365.506762 -293.990522)
		(width 0.1143)
		(layer "In6.Cu")
		(net "P5E_CPU0_P2_RX_DP<5>")
	)
	(segment
		(start 383.11201 -324.995032)
		(end 378.03582 -315.497464)
		(width 0.14224)
		(layer "In6.Cu")
		(net "P5E_CPU0_P2_RX_DP<5>")
	)
	(segment
		(start 410.176472 -393.842494)
		(end 410.176472 -393.428982)
		(width 0.14224)
		(layer "In6.Cu")
		(net "P5E_CPU0_P2_RX_DP<5>")
	)
	(segment
		(start 365.938816 -295.469056)
		(end 365.9378 -295.468548)
		(width 0.1143)
		(layer "In6.Cu")
		(net "P5E_CPU0_P2_RX_DP<5>")
	)
	(segment
		(start 365.467646 -289.798506)
		(end 365.437166 -289.780726)
		(width 0.1143)
		(layer "In6.Cu")
		(net "P5E_CPU0_P2_RX_DP<5>")
	)
	(segment
		(start 409.860496 -393.113006)
		(end 409.863544 -392.734546)
		(width 0.14224)
		(layer "In6.Cu")
		(net "P5E_CPU0_P2_RX_DP<5>")
	)
	(segment
		(start 365.437166 -289.171126)
		(end 365.467646 -289.153346)
		(width 0.1143)
		(layer "In6.Cu")
		(net "P5E_CPU0_P2_RX_DP<5>")
	)
	(segment
		(start 397.62684 -371.30609)
		(end 395.013942 -368.693192)
		(width 0.14224)
		(layer "In6.Cu")
		(net "P5E_CPU0_P2_RX_DP<5>")
	)
	(segment
		(start 376.329702 -312.94451)
		(end 371.049042 -306.509928)
		(width 0.14224)
		(layer "In6.Cu")
		(net "P5E_CPU0_P2_RX_DP<5>")
	)
	(segment
		(start 409.44673 -388.389622)
		(end 407.729182 -382.103884)
		(width 0.14224)
		(layer "In6.Cu")
		(net "P5E_CPU0_P2_RX_DP<5>")
	)
	(segment
		(start 365.287052 -284.685994)
		(end 365.356902 -284.616144)
		(width 0.1143)
		(layer "In6.Cu")
		(net "P5E_CPU0_P2_RX_DP<5>")
	)
	(segment
		(start 409.863544 -392.734546)
		(end 410.168344 -392.429746)
		(width 0.14224)
		(layer "In6.Cu")
		(net "P5E_CPU0_P2_RX_DP<5>")
	)
	(segment
		(start 410.088334 -393.930632)
		(end 410.176472 -393.842494)
		(width 0.14224)
		(layer "In6.Cu")
		(net "P5E_CPU0_P2_RX_DP<5>")
	)
	(segment
		(start 365.506762 -293.06139)
		(end 365.467646 -293.03853)
		(width 0.1143)
		(layer "In6.Cu")
		(net "P5E_CPU0_P2_RX_DP<5>")
	)
	(segment
		(start 409.91409 -394.031216)
		(end 410.088334 -393.930632)
		(width 0.14224)
		(layer "In6.Cu")
		(net "P5E_CPU0_P2_RX_DP<5>")
	)
	(segment
		(start 366.265968 -298.125896)
		(end 366.265968 -296.353484)
		(width 0.14224)
		(layer "In6.Cu")
		(net "P5E_CPU0_P2_RX_DP<5>")
	)
	(segment
		(start 407.017728 -378.622814)
		(end 406.652984 -378.49429)
		(width 0.14224)
		(layer "In6.Cu")
		(net "P5E_CPU0_P2_RX_DP<5>")
	)
	(segment
		(start 365.506762 -288.201354)
		(end 365.467646 -288.178494)
		(width 0.1143)
		(layer "In6.Cu")
		(net "P5E_CPU0_P2_RX_DP<5>")
	)
	(segment
		(start 365.467646 -290.773358)
		(end 365.506762 -290.750498)
		(width 0.1143)
		(layer "In6.Cu")
		(net "P5E_CPU0_P2_RX_DP<5>")
	)
	(segment
		(start 365.437166 -292.41115)
		(end 365.467646 -292.39337)
		(width 0.1143)
		(layer "In6.Cu")
		(net "P5E_CPU0_P2_RX_DP<5>")
	)
	(segment
		(start 365.506762 -284.961584)
		(end 365.437166 -284.920944)
		(width 0.1143)
		(layer "In6.Cu")
		(net "P5E_CPU0_P2_RX_DP<5>")
	)
	(segment
		(start 365.938562 -285.746952)
		(end 365.93399 -285.744412)
		(width 0.1143)
		(layer "In6.Cu")
		(net "P5E_CPU0_P2_RX_DP<5>")
	)
	(segment
		(start 365.437166 -290.791138)
		(end 365.467646 -290.773358)
		(width 0.1143)
		(layer "In6.Cu")
		(net "P5E_CPU0_P2_RX_DP<5>")
	)
	(segment
		(start 410.153866 -390.977628)
		(end 409.446984 -388.390638)
		(width 0.14224)
		(layer "In6.Cu")
		(net "P5E_CPU0_P2_RX_DP<5>")
	)
	(segment
		(start 394.98651 -368.652044)
		(end 387.7691 -351.22866)
		(width 0.14224)
		(layer "In6.Cu")
		(net "P5E_CPU0_P2_RX_DP<5>")
	)
	(segment
		(start 409.446984 -388.390638)
		(end 409.44673 -388.389622)
		(width 0.14224)
		(layer "In6.Cu")
		(net "P5E_CPU0_P2_RX_DP<5>")
	)
	(segment
		(start 365.467646 -288.178494)
		(end 365.435134 -288.159698)
		(width 0.1143)
		(layer "In6.Cu")
		(net "P5E_CPU0_P2_RX_DP<5>")
	)
	(segment
		(start 365.969296 -295.486836)
		(end 365.944658 -295.472612)
		(width 0.1143)
		(layer "In6.Cu")
		(net "P5E_CPU0_P2_RX_DP<5>")
	)
	(segment
		(start 410.176472 -393.428982)
		(end 409.860496 -393.113006)
		(width 0.14224)
		(layer "In6.Cu")
		(net "P5E_CPU0_P2_RX_DP<5>")
	)
	(segment
		(start 366.265968 -296.325036)
		(end 366.220248 -296.279316)
		(width 0.1143)
		(layer "In6.Cu")
		(net "P5E_CPU0_P2_RX_DP<5>")
	)
	(segment
		(start 365.437166 -294.031162)
		(end 365.467646 -294.013382)
		(width 0.1143)
		(layer "In6.Cu")
		(net "P5E_CPU0_P2_RX_DP<5>")
	)
	(segment
		(start 385.493768 -336.969354)
		(end 383.11201 -324.995032)
		(width 0.14224)
		(layer "In6.Cu")
		(net "P5E_CPU0_P2_RX_DP<5>")
	)
	(segment
		(start 365.437166 -287.551368)
		(end 365.504222 -287.512252)
		(width 0.1143)
		(layer "In6.Cu")
		(net "P5E_CPU0_P2_RX_DP<5>")
	)
	(segment
		(start 365.467646 -291.418518)
		(end 365.437166 -291.400738)
		(width 0.1143)
		(layer "In6.Cu")
		(net "P5E_CPU0_P2_RX_DP<5>")
	)
	(segment
		(start 365.944658 -295.472612)
		(end 365.943134 -295.471596)
		(width 0.1143)
		(layer "In6.Cu")
		(net "P5E_CPU0_P2_RX_DP<5>")
	)
	(segment
		(start 365.506762 -294.681402)
		(end 365.467646 -294.658542)
		(width 0.1143)
		(layer "In6.Cu")
		(net "P5E_CPU0_P2_RX_DP<5>")
	)
	(arc
		(start 407.72461 -379.638052)
		(mid 407.641568 -379.220571)
		(end 407.405078 -378.866654)
		(width 0.14224)
		(layer "In6.Cu")
		(net "P5E_CPU0_P2_RX_DP<5>")
	)
	(arc
		(start 365.90605 -295.45026)
		(mid 365.791374 -295.316926)
		(end 365.750094 -295.145968)
		(width 0.1143)
		(layer "In6.Cu")
		(net "P5E_CPU0_P2_RX_DP<5>")
	)
	(arc
		(start 365.437166 -289.780726)
		(mid 365.280189 -289.475926)
		(end 365.437166 -289.171126)
		(width 0.1143)
		(layer "In6.Cu")
		(net "P5E_CPU0_P2_RX_DP<5>")
	)
	(arc
		(start 386.049266 -342.602566)
		(mid 386.04823 -342.596491)
		(end 386.047488 -342.590374)
		(width 0.14224)
		(layer "In6.Cu")
		(net "P5E_CPU0_P2_RX_DP<5>")
	)
	(arc
		(start 365.506762 -290.750498)
		(mid 365.750089 -290.285932)
		(end 365.506762 -289.821366)
		(width 0.1143)
		(layer "In6.Cu")
		(net "P5E_CPU0_P2_RX_DP<5>")
	)
	(arc
		(start 365.437166 -294.640762)
		(mid 365.280189 -294.335962)
		(end 365.437166 -294.031162)
		(width 0.1143)
		(layer "In6.Cu")
		(net "P5E_CPU0_P2_RX_DP<5>")
	)
	(arc
		(start 365.506762 -292.37051)
		(mid 365.750089 -291.905944)
		(end 365.506762 -291.441378)
		(width 0.1143)
		(layer "In6.Cu")
		(net "P5E_CPU0_P2_RX_DP<5>")
	)
	(arc
		(start 365.750094 -295.145968)
		(mid 365.685579 -294.883749)
		(end 365.506762 -294.681402)
		(width 0.1143)
		(layer "In6.Cu")
		(net "P5E_CPU0_P2_RX_DP<5>")
	)
	(arc
		(start 406.229312 -378.122434)
		(mid 406.076693 -377.894023)
		(end 406.023064 -377.624594)
		(width 0.14224)
		(layer "In6.Cu")
		(net "P5E_CPU0_P2_RX_DP<5>")
	)
	(arc
		(start 366.12068 -295.635426)
		(mid 366.055328 -295.556899)
		(end 365.976916 -295.491408)
		(width 0.1143)
		(layer "In6.Cu")
		(net "P5E_CPU0_P2_RX_DP<5>")
	)
	(arc
		(start 365.280194 -287.856168)
		(mid 365.321743 -287.684746)
		(end 365.437166 -287.551368)
		(width 0.1143)
		(layer "In6.Cu")
		(net "P5E_CPU0_P2_RX_DP<5>")
	)
	(arc
		(start 365.506762 -289.130486)
		(mid 365.750089 -288.66592)
		(end 365.506762 -288.201354)
		(width 0.1143)
		(layer "In6.Cu")
		(net "P5E_CPU0_P2_RX_DP<5>")
	)
	(arc
		(start 365.750094 -285.42615)
		(mid 365.685579 -285.163931)
		(end 365.506762 -284.961584)
		(width 0.1143)
		(layer "In6.Cu")
		(net "P5E_CPU0_P2_RX_DP<5>")
	)
	(arc
		(start 365.437166 -291.400738)
		(mid 365.280189 -291.095938)
		(end 365.437166 -290.791138)
		(width 0.1143)
		(layer "In6.Cu")
		(net "P5E_CPU0_P2_RX_DP<5>")
	)
	(arc
		(start 365.435134 -288.159698)
		(mid 365.321205 -288.026551)
		(end 365.280194 -287.856168)
		(width 0.1143)
		(layer "In6.Cu")
		(net "P5E_CPU0_P2_RX_DP<5>")
	)
	(arc
		(start 406.652984 -378.49429)
		(mid 406.578486 -378.458413)
		(end 406.513792 -378.406914)
		(width 0.14224)
		(layer "In6.Cu")
		(net "P5E_CPU0_P2_RX_DP<5>")
	)
	(arc
		(start 407.729182 -382.103884)
		(mid 407.72578 -382.087272)
		(end 407.72461 -382.070356)
		(width 0.14224)
		(layer "In6.Cu")
		(net "P5E_CPU0_P2_RX_DP<5>")
	)
	(arc
		(start 365.504222 -287.512252)
		(mid 365.684874 -287.309507)
		(end 365.750094 -287.045908)
		(width 0.1143)
		(layer "In6.Cu")
		(net "P5E_CPU0_P2_RX_DP<5>")
	)
	(arc
		(start 397.654018 -371.326664)
		(mid 397.639738 -371.31729)
		(end 397.62684 -371.30609)
		(width 0.14224)
		(layer "In6.Cu")
		(net "P5E_CPU0_P2_RX_DP<5>")
	)
	(arc
		(start 366.220248 -295.955974)
		(mid 366.194828 -295.788129)
		(end 366.12068 -295.635426)
		(width 0.1143)
		(layer "In6.Cu")
		(net "P5E_CPU0_P2_RX_DP<5>")
	)
	(arc
		(start 365.437166 -293.02075)
		(mid 365.280189 -292.71595)
		(end 365.437166 -292.41115)
		(width 0.1143)
		(layer "In6.Cu")
		(net "P5E_CPU0_P2_RX_DP<5>")
	)
	(arc
		(start 387.7691 -351.22866)
		(mid 387.762155 -351.209142)
		(end 387.757162 -351.189036)
		(width 0.14224)
		(layer "In6.Cu")
		(net "P5E_CPU0_P2_RX_DP<5>")
	)
	(arc
		(start 406.023064 -376.98045)
		(mid 405.912369 -376.423859)
		(end 405.597106 -375.952004)
		(width 0.14224)
		(layer "In6.Cu")
		(net "P5E_CPU0_P2_RX_DP<5>")
	)
	(arc
		(start 365.750094 -287.045908)
		(mid 365.790856 -286.876024)
		(end 365.904272 -286.74314)
		(width 0.1143)
		(layer "In6.Cu")
		(net "P5E_CPU0_P2_RX_DP<5>")
	)
	(arc
		(start 407.405078 -378.866654)
		(mid 407.225093 -378.722982)
		(end 407.017728 -378.622814)
		(width 0.14224)
		(layer "In6.Cu")
		(net "P5E_CPU0_P2_RX_DP<5>")
	)
	(arc
		(start 410.168344 -391.085324)
		(mid 410.164687 -391.030995)
		(end 410.153866 -390.977628)
		(width 0.14224)
		(layer "In6.Cu")
		(net "P5E_CPU0_P2_RX_DP<5>")
	)
	(arc
		(start 365.93399 -285.744412)
		(mid 365.79935 -285.609944)
		(end 365.750094 -285.42615)
		(width 0.1143)
		(layer "In6.Cu")
		(net "P5E_CPU0_P2_RX_DP<5>")
	)
	(arc
		(start 365.506762 -293.990522)
		(mid 365.750089 -293.525956)
		(end 365.506762 -293.06139)
		(width 0.1143)
		(layer "In6.Cu")
		(net "P5E_CPU0_P2_RX_DP<5>")
	)
	(arc
		(start 395.013942 -368.693192)
		(mid 394.998197 -368.673969)
		(end 394.98651 -368.652044)
		(width 0.14224)
		(layer "In6.Cu")
		(net "P5E_CPU0_P2_RX_DP<5>")
	)
	(arc
		(start 365.974122 -286.7025)
		(mid 366.219721 -286.2149)
		(end 365.938562 -285.746952)
		(width 0.1143)
		(layer "In6.Cu")
		(net "P5E_CPU0_P2_RX_DP<5>")
	)
	(arc
		(start 365.437166 -284.920944)
		(mid 365.339401 -284.817968)
		(end 365.287052 -284.685994)
		(width 0.1143)
		(layer "In6.Cu")
		(net "P5E_CPU0_P2_RX_DP<5>")
	)
	(segment
		(start 408.098244 -394.385292)
		(end 408.618944 -394.385292)
		(width 0.127)
		(layer "F.Cu")
		(net "P5E_CPU0_P2_RX_DP<4>")
	)
	(segment
		(start 365.187992 -285.970218)
		(end 365.654844 -286.236156)
		(width 0.12954)
		(layer "F.Cu")
		(net "P5E_CPU0_P2_RX_DP<4>")
	)
	(segment
		(start 365.004858 -295.472612)
		(end 364.965996 -295.45026)
		(width 0.1143)
		(layer "In6.Cu")
		(net "P5E_CPU0_P2_RX_DP<4>")
	)
	(segment
		(start 364.530132 -287.532318)
		(end 364.529878 -287.532064)
		(width 0.1143)
		(layer "In6.Cu")
		(net "P5E_CPU0_P2_RX_DP<4>")
	)
	(segment
		(start 364.527592 -289.153346)
		(end 364.566708 -289.130486)
		(width 0.1143)
		(layer "In6.Cu")
		(net "P5E_CPU0_P2_RX_DP<4>")
	)
	(segment
		(start 408.976322 -393.428982)
		(end 408.660346 -393.113006)
		(width 0.14224)
		(layer "In6.Cu")
		(net "P5E_CPU0_P2_RX_DP<4>")
	)
	(segment
		(start 364.527592 -291.418518)
		(end 364.497112 -291.400738)
		(width 0.1143)
		(layer "In6.Cu")
		(net "P5E_CPU0_P2_RX_DP<4>")
	)
	(segment
		(start 404.570184 -380.70409)
		(end 404.437088 -380.570994)
		(width 0.14224)
		(layer "In6.Cu")
		(net "P5E_CPU0_P2_RX_DP<4>")
	)
	(segment
		(start 386.881624 -351.660206)
		(end 385.122928 -342.819228)
		(width 0.14224)
		(layer "In6.Cu")
		(net "P5E_CPU0_P2_RX_DP<4>")
	)
	(segment
		(start 400.463258 -374.09247)
		(end 397.035274 -372.151402)
		(width 0.14224)
		(layer "In6.Cu")
		(net "P5E_CPU0_P2_RX_DP<4>")
	)
	(segment
		(start 365.280194 -296.085768)
		(end 365.280194 -295.952672)
		(width 0.1143)
		(layer "In6.Cu")
		(net "P5E_CPU0_P2_RX_DP<4>")
	)
	(segment
		(start 364.566708 -293.06139)
		(end 364.527592 -293.03853)
		(width 0.1143)
		(layer "In6.Cu")
		(net "P5E_CPU0_P2_RX_DP<4>")
	)
	(segment
		(start 385.12115 -342.807036)
		(end 384.549142 -337.000342)
		(width 0.14224)
		(layer "In6.Cu")
		(net "P5E_CPU0_P2_RX_DP<4>")
	)
	(segment
		(start 408.618944 -394.385292)
		(end 408.71394 -394.031216)
		(width 0.14224)
		(layer "In6.Cu")
		(net "P5E_CPU0_P2_RX_DP<4>")
	)
	(segment
		(start 364.527846 -287.533588)
		(end 364.528862 -287.53308)
		(width 0.1143)
		(layer "In6.Cu")
		(net "P5E_CPU0_P2_RX_DP<4>")
	)
	(segment
		(start 404.117556 -376.162316)
		(end 402.29028 -375.12752)
		(width 0.14224)
		(layer "In6.Cu")
		(net "P5E_CPU0_P2_RX_DP<4>")
	)
	(segment
		(start 364.566708 -289.821366)
		(end 364.527592 -289.798506)
		(width 0.1143)
		(layer "In6.Cu")
		(net "P5E_CPU0_P2_RX_DP<4>")
	)
	(segment
		(start 364.527592 -294.013382)
		(end 364.566708 -293.990522)
		(width 0.1143)
		(layer "In6.Cu")
		(net "P5E_CPU0_P2_RX_DP<4>")
	)
	(segment
		(start 408.663394 -392.734546)
		(end 408.968194 -392.429746)
		(width 0.14224)
		(layer "In6.Cu")
		(net "P5E_CPU0_P2_RX_DP<4>")
	)
	(segment
		(start 364.497112 -289.171126)
		(end 364.527592 -289.153346)
		(width 0.1143)
		(layer "In6.Cu")
		(net "P5E_CPU0_P2_RX_DP<4>")
	)
	(segment
		(start 384.549142 -337.000342)
		(end 382.22682 -325.324724)
		(width 0.14224)
		(layer "In6.Cu")
		(net "P5E_CPU0_P2_RX_DP<4>")
	)
	(segment
		(start 406.527254 -382.178052)
		(end 406.527 -382.177036)
		(width 0.14224)
		(layer "In6.Cu")
		(net "P5E_CPU0_P2_RX_DP<4>")
	)
	(segment
		(start 365.275622 -296.279316)
		(end 365.275622 -296.09034)
		(width 0.1143)
		(layer "In6.Cu")
		(net "P5E_CPU0_P2_RX_DP<4>")
	)
	(segment
		(start 364.566708 -288.201354)
		(end 364.527592 -288.178494)
		(width 0.1143)
		(layer "In6.Cu")
		(net "P5E_CPU0_P2_RX_DP<4>")
	)
	(segment
		(start 364.52429 -287.53562)
		(end 364.525814 -287.534858)
		(width 0.1143)
		(layer "In6.Cu")
		(net "P5E_CPU0_P2_RX_DP<4>")
	)
	(segment
		(start 364.566708 -291.441378)
		(end 364.527592 -291.418518)
		(width 0.1143)
		(layer "In6.Cu")
		(net "P5E_CPU0_P2_RX_DP<4>")
	)
	(segment
		(start 407.671778 -386.303266)
		(end 406.527254 -382.178052)
		(width 0.14224)
		(layer "In6.Cu")
		(net "P5E_CPU0_P2_RX_DP<4>")
	)
	(segment
		(start 408.968194 -392.429746)
		(end 408.968194 -391.219944)
		(width 0.14224)
		(layer "In6.Cu")
		(net "P5E_CPU0_P2_RX_DP<4>")
	)
	(segment
		(start 408.903424 -390.742424)
		(end 407.671778 -386.303266)
		(width 0.14224)
		(layer "In6.Cu")
		(net "P5E_CPU0_P2_RX_DP<4>")
	)
	(segment
		(start 364.527592 -288.178494)
		(end 364.49508 -288.159698)
		(width 0.1143)
		(layer "In6.Cu")
		(net "P5E_CPU0_P2_RX_DP<4>")
	)
	(segment
		(start 365.321342 -298.28236)
		(end 365.321342 -296.353484)
		(width 0.14224)
		(layer "In6.Cu")
		(net "P5E_CPU0_P2_RX_DP<4>")
	)
	(segment
		(start 364.527084 -287.534096)
		(end 364.527846 -287.533588)
		(width 0.1143)
		(layer "In6.Cu")
		(net "P5E_CPU0_P2_RX_DP<4>")
	)
	(segment
		(start 377.333002 -316.16904)
		(end 375.450608 -313.351926)
		(width 0.14224)
		(layer "In6.Cu")
		(net "P5E_CPU0_P2_RX_DP<4>")
	)
	(segment
		(start 408.660346 -393.113006)
		(end 408.663394 -392.734546)
		(width 0.14224)
		(layer "In6.Cu")
		(net "P5E_CPU0_P2_RX_DP<4>")
	)
	(segment
		(start 370.307108 -307.084984)
		(end 366.78235 -301.809658)
		(width 0.14224)
		(layer "In6.Cu")
		(net "P5E_CPU0_P2_RX_DP<4>")
	)
	(segment
		(start 408.888184 -393.930632)
		(end 408.976322 -393.842494)
		(width 0.14224)
		(layer "In6.Cu")
		(net "P5E_CPU0_P2_RX_DP<4>")
	)
	(segment
		(start 364.497112 -290.791138)
		(end 364.527592 -290.773358)
		(width 0.1143)
		(layer "In6.Cu")
		(net "P5E_CPU0_P2_RX_DP<4>")
	)
	(segment
		(start 364.497112 -294.031162)
		(end 364.527592 -294.013382)
		(width 0.1143)
		(layer "In6.Cu")
		(net "P5E_CPU0_P2_RX_DP<4>")
	)
	(segment
		(start 405.602948 -381.177546)
		(end 404.75027 -380.824232)
		(width 0.14224)
		(layer "In6.Cu")
		(net "P5E_CPU0_P2_RX_DP<4>")
	)
	(segment
		(start 364.996222 -286.724344)
		(end 365.036354 -286.700976)
		(width 0.1143)
		(layer "In6.Cu")
		(net "P5E_CPU0_P2_RX_DP<4>")
	)
	(segment
		(start 365.275622 -296.09034)
		(end 365.280194 -296.085768)
		(width 0.1143)
		(layer "In6.Cu")
		(net "P5E_CPU0_P2_RX_DP<4>")
	)
	(segment
		(start 364.528862 -287.53308)
		(end 364.530132 -287.532318)
		(width 0.1143)
		(layer "In6.Cu")
		(net "P5E_CPU0_P2_RX_DP<4>")
	)
	(segment
		(start 364.497112 -292.41115)
		(end 364.527592 -292.39337)
		(width 0.1143)
		(layer "In6.Cu")
		(net "P5E_CPU0_P2_RX_DP<4>")
	)
	(segment
		(start 364.527592 -294.658542)
		(end 364.497112 -294.640762)
		(width 0.1143)
		(layer "In6.Cu")
		(net "P5E_CPU0_P2_RX_DP<4>")
	)
	(segment
		(start 364.496096 -287.551876)
		(end 364.52429 -287.53562)
		(width 0.1143)
		(layer "In6.Cu")
		(net "P5E_CPU0_P2_RX_DP<4>")
	)
	(segment
		(start 364.527592 -292.39337)
		(end 364.566708 -292.37051)
		(width 0.1143)
		(layer "In6.Cu")
		(net "P5E_CPU0_P2_RX_DP<4>")
	)
	(segment
		(start 394.209524 -369.358164)
		(end 386.88899 -351.683828)
		(width 0.14224)
		(layer "In6.Cu")
		(net "P5E_CPU0_P2_RX_DP<4>")
	)
	(segment
		(start 364.525814 -287.534858)
		(end 364.527084 -287.534096)
		(width 0.1143)
		(layer "In6.Cu")
		(net "P5E_CPU0_P2_RX_DP<4>")
	)
	(segment
		(start 366.78235 -301.809658)
		(end 365.321342 -298.28236)
		(width 0.14224)
		(layer "In6.Cu")
		(net "P5E_CPU0_P2_RX_DP<4>")
	)
	(segment
		(start 365.036354 -286.700976)
		(end 365.036862 -286.700722)
		(width 0.1143)
		(layer "In6.Cu")
		(net "P5E_CPU0_P2_RX_DP<4>")
	)
	(segment
		(start 364.527592 -289.798506)
		(end 364.497112 -289.780726)
		(width 0.1143)
		(layer "In6.Cu")
		(net "P5E_CPU0_P2_RX_DP<4>")
	)
	(segment
		(start 364.566708 -294.681402)
		(end 364.527592 -294.658542)
		(width 0.1143)
		(layer "In6.Cu")
		(net "P5E_CPU0_P2_RX_DP<4>")
	)
	(segment
		(start 375.450608 -313.351926)
		(end 370.307108 -307.084984)
		(width 0.14224)
		(layer "In6.Cu")
		(net "P5E_CPU0_P2_RX_DP<4>")
	)
	(segment
		(start 404.325074 -380.300738)
		(end 404.325074 -376.518424)
		(width 0.14224)
		(layer "In6.Cu")
		(net "P5E_CPU0_P2_RX_DP<4>")
	)
	(segment
		(start 365.321342 -296.353484)
		(end 365.321342 -296.325036)
		(width 0.1143)
		(layer "In6.Cu")
		(net "P5E_CPU0_P2_RX_DP<4>")
	)
	(segment
		(start 365.321342 -296.325036)
		(end 365.275622 -296.279316)
		(width 0.1143)
		(layer "In6.Cu")
		(net "P5E_CPU0_P2_RX_DP<4>")
	)
	(segment
		(start 396.625572 -371.839744)
		(end 394.341604 -369.555776)
		(width 0.14224)
		(layer "In6.Cu")
		(net "P5E_CPU0_P2_RX_DP<4>")
	)
	(segment
		(start 408.71394 -394.031216)
		(end 408.888184 -393.930632)
		(width 0.14224)
		(layer "In6.Cu")
		(net "P5E_CPU0_P2_RX_DP<4>")
	)
	(segment
		(start 406.366472 -381.896874)
		(end 405.735536 -381.265938)
		(width 0.14224)
		(layer "In6.Cu")
		(net "P5E_CPU0_P2_RX_DP<4>")
	)
	(segment
		(start 386.88899 -351.683828)
		(end 386.888736 -351.683574)
		(width 0.14224)
		(layer "In6.Cu")
		(net "P5E_CPU0_P2_RX_DP<4>")
	)
	(segment
		(start 364.994952 -286.724852)
		(end 364.996222 -286.724344)
		(width 0.1143)
		(layer "In6.Cu")
		(net "P5E_CPU0_P2_RX_DP<4>")
	)
	(segment
		(start 364.527592 -293.03853)
		(end 364.497112 -293.02075)
		(width 0.1143)
		(layer "In6.Cu")
		(net "P5E_CPU0_P2_RX_DP<4>")
	)
	(segment
		(start 382.22682 -325.324724)
		(end 377.333002 -316.16904)
		(width 0.14224)
		(layer "In6.Cu")
		(net "P5E_CPU0_P2_RX_DP<4>")
	)
	(segment
		(start 365.274098 -286.31896)
		(end 365.356902 -286.236156)
		(width 0.1143)
		(layer "In6.Cu")
		(net "P5E_CPU0_P2_RX_DP<4>")
	)
	(segment
		(start 364.527592 -290.773358)
		(end 364.566708 -290.750498)
		(width 0.1143)
		(layer "In6.Cu")
		(net "P5E_CPU0_P2_RX_DP<4>")
	)
	(segment
		(start 402.29028 -375.12752)
		(end 400.463258 -374.092978)
		(width 0.14224)
		(layer "In6.Cu")
		(net "P5E_CPU0_P2_RX_DP<4>")
	)
	(segment
		(start 400.463258 -374.092978)
		(end 400.463258 -374.09247)
		(width 0.14224)
		(layer "In6.Cu")
		(net "P5E_CPU0_P2_RX_DP<4>")
	)
	(segment
		(start 408.976322 -393.842494)
		(end 408.976322 -393.428982)
		(width 0.14224)
		(layer "In6.Cu")
		(net "P5E_CPU0_P2_RX_DP<4>")
	)
	(segment
		(start 365.356902 -286.236156)
		(end 365.654844 -286.236156)
		(width 0.1143)
		(layer "In6.Cu")
		(net "P5E_CPU0_P2_RX_DP<4>")
	)
	(arc
		(start 394.341604 -369.555776)
		(mid 394.265846 -369.463467)
		(end 394.209524 -369.358164)
		(width 0.14224)
		(layer "In6.Cu")
		(net "P5E_CPU0_P2_RX_DP<4>")
	)
	(arc
		(start 364.566708 -290.750498)
		(mid 364.810035 -290.285932)
		(end 364.566708 -289.821366)
		(width 0.1143)
		(layer "In6.Cu")
		(net "P5E_CPU0_P2_RX_DP<4>")
	)
	(arc
		(start 365.270288 -286.34182)
		(mid 365.272311 -286.33041)
		(end 365.274098 -286.31896)
		(width 0.1143)
		(layer "In6.Cu")
		(net "P5E_CPU0_P2_RX_DP<4>")
	)
	(arc
		(start 364.49508 -288.159698)
		(mid 364.381151 -288.026551)
		(end 364.34014 -287.856168)
		(width 0.1143)
		(layer "In6.Cu")
		(net "P5E_CPU0_P2_RX_DP<4>")
	)
	(arc
		(start 364.497112 -289.780726)
		(mid 364.340135 -289.475926)
		(end 364.497112 -289.171126)
		(width 0.1143)
		(layer "In6.Cu")
		(net "P5E_CPU0_P2_RX_DP<4>")
	)
	(arc
		(start 364.566708 -293.990522)
		(mid 364.810035 -293.525956)
		(end 364.566708 -293.06139)
		(width 0.1143)
		(layer "In6.Cu")
		(net "P5E_CPU0_P2_RX_DP<4>")
	)
	(arc
		(start 364.529878 -287.532064)
		(mid 364.734842 -287.326554)
		(end 364.809786 -287.046162)
		(width 0.1143)
		(layer "In6.Cu")
		(net "P5E_CPU0_P2_RX_DP<4>")
	)
	(arc
		(start 364.809786 -287.046162)
		(mid 364.859391 -286.860741)
		(end 364.994952 -286.724852)
		(width 0.1143)
		(layer "In6.Cu")
		(net "P5E_CPU0_P2_RX_DP<4>")
	)
	(arc
		(start 404.437088 -380.570994)
		(mid 404.354184 -380.447014)
		(end 404.325074 -380.300738)
		(width 0.14224)
		(layer "In6.Cu")
		(net "P5E_CPU0_P2_RX_DP<4>")
	)
	(arc
		(start 365.036862 -286.700722)
		(mid 365.188849 -286.544214)
		(end 365.270288 -286.34182)
		(width 0.1143)
		(layer "In6.Cu")
		(net "P5E_CPU0_P2_RX_DP<4>")
	)
	(arc
		(start 364.566708 -292.37051)
		(mid 364.810035 -291.905944)
		(end 364.566708 -291.441378)
		(width 0.1143)
		(layer "In6.Cu")
		(net "P5E_CPU0_P2_RX_DP<4>")
	)
	(arc
		(start 408.968194 -391.219944)
		(mid 408.952004 -390.978986)
		(end 408.903424 -390.742424)
		(width 0.14224)
		(layer "In6.Cu")
		(net "P5E_CPU0_P2_RX_DP<4>")
	)
	(arc
		(start 364.81004 -295.145968)
		(mid 364.745525 -294.883749)
		(end 364.566708 -294.681402)
		(width 0.1143)
		(layer "In6.Cu")
		(net "P5E_CPU0_P2_RX_DP<4>")
	)
	(arc
		(start 364.965996 -295.45026)
		(mid 364.85132 -295.316926)
		(end 364.81004 -295.145968)
		(width 0.1143)
		(layer "In6.Cu")
		(net "P5E_CPU0_P2_RX_DP<4>")
	)
	(arc
		(start 365.280194 -295.952672)
		(mid 365.206482 -295.675954)
		(end 365.004858 -295.472612)
		(width 0.1143)
		(layer "In6.Cu")
		(net "P5E_CPU0_P2_RX_DP<4>")
	)
	(arc
		(start 385.122928 -342.819228)
		(mid 385.121892 -342.813153)
		(end 385.12115 -342.807036)
		(width 0.14224)
		(layer "In6.Cu")
		(net "P5E_CPU0_P2_RX_DP<4>")
	)
	(arc
		(start 364.566708 -289.130486)
		(mid 364.810035 -288.66592)
		(end 364.566708 -288.201354)
		(width 0.1143)
		(layer "In6.Cu")
		(net "P5E_CPU0_P2_RX_DP<4>")
	)
	(arc
		(start 386.888736 -351.683574)
		(mid 386.884614 -351.672062)
		(end 386.881624 -351.660206)
		(width 0.14224)
		(layer "In6.Cu")
		(net "P5E_CPU0_P2_RX_DP<4>")
	)
	(arc
		(start 404.325074 -376.518424)
		(mid 404.2694 -376.312358)
		(end 404.117556 -376.162316)
		(width 0.14224)
		(layer "In6.Cu")
		(net "P5E_CPU0_P2_RX_DP<4>")
	)
	(arc
		(start 406.527 -382.177036)
		(mid 406.465377 -382.026273)
		(end 406.366472 -381.896874)
		(width 0.14224)
		(layer "In6.Cu")
		(net "P5E_CPU0_P2_RX_DP<4>")
	)
	(arc
		(start 404.75027 -380.824232)
		(mid 404.654321 -380.773017)
		(end 404.570184 -380.70409)
		(width 0.14224)
		(layer "In6.Cu")
		(net "P5E_CPU0_P2_RX_DP<4>")
	)
	(arc
		(start 364.497112 -293.02075)
		(mid 364.340135 -292.71595)
		(end 364.497112 -292.41115)
		(width 0.1143)
		(layer "In6.Cu")
		(net "P5E_CPU0_P2_RX_DP<4>")
	)
	(arc
		(start 364.497112 -294.640762)
		(mid 364.340135 -294.335962)
		(end 364.497112 -294.031162)
		(width 0.1143)
		(layer "In6.Cu")
		(net "P5E_CPU0_P2_RX_DP<4>")
	)
	(arc
		(start 405.735536 -381.265938)
		(mid 405.673592 -381.215215)
		(end 405.602948 -381.177546)
		(width 0.14224)
		(layer "In6.Cu")
		(net "P5E_CPU0_P2_RX_DP<4>")
	)
	(arc
		(start 397.035274 -372.151402)
		(mid 396.819873 -372.00944)
		(end 396.625572 -371.839744)
		(width 0.14224)
		(layer "In6.Cu")
		(net "P5E_CPU0_P2_RX_DP<4>")
	)
	(arc
		(start 364.497112 -291.400738)
		(mid 364.340135 -291.095938)
		(end 364.497112 -290.791138)
		(width 0.1143)
		(layer "In6.Cu")
		(net "P5E_CPU0_P2_RX_DP<4>")
	)
	(arc
		(start 364.34014 -287.856168)
		(mid 364.381395 -287.685197)
		(end 364.496096 -287.551876)
		(width 0.1143)
		(layer "In6.Cu")
		(net "P5E_CPU0_P2_RX_DP<4>")
	)
	(segment
		(start 365.187992 -282.730194)
		(end 365.654844 -282.996132)
		(width 0.12954)
		(layer "F.Cu")
		(net "P5E_CPU0_P2_RX_DP<3>")
	)
	(segment
		(start 406.898348 -394.385292)
		(end 407.419048 -394.385292)
		(width 0.127)
		(layer "F.Cu")
		(net "P5E_CPU0_P2_RX_DP<3>")
	)
	(segment
		(start 363.579156 -291.413692)
		(end 363.556042 -291.40023)
		(width 0.1143)
		(layer "In6.Cu")
		(net "P5E_CPU0_P2_RX_DP<3>")
	)
	(segment
		(start 363.619288 -289.816794)
		(end 363.59465 -289.80257)
		(width 0.1143)
		(layer "In6.Cu")
		(net "P5E_CPU0_P2_RX_DP<3>")
	)
	(segment
		(start 363.588808 -293.039038)
		(end 363.587792 -293.03853)
		(width 0.1143)
		(layer "In6.Cu")
		(net "P5E_CPU0_P2_RX_DP<3>")
	)
	(segment
		(start 407.683716 -390.16051)
		(end 402.960078 -383.158746)
		(width 0.14224)
		(layer "In6.Cu")
		(net "P5E_CPU0_P2_RX_DP<3>")
	)
	(segment
		(start 363.590332 -289.151822)
		(end 363.626908 -289.130486)
		(width 0.1143)
		(layer "In6.Cu")
		(net "P5E_CPU0_P2_RX_DP<3>")
	)
	(segment
		(start 363.582458 -294.655494)
		(end 363.581696 -294.654986)
		(width 0.1143)
		(layer "In6.Cu")
		(net "P5E_CPU0_P2_RX_DP<3>")
	)
	(segment
		(start 407.463498 -392.7348)
		(end 407.721054 -392.477498)
		(width 0.14224)
		(layer "In6.Cu")
		(net "P5E_CPU0_P2_RX_DP<3>")
	)
	(segment
		(start 363.626908 -291.441378)
		(end 363.62005 -291.437314)
		(width 0.1143)
		(layer "In6.Cu")
		(net "P5E_CPU0_P2_RX_DP<3>")
	)
	(segment
		(start 363.58576 -290.774628)
		(end 363.58703 -290.773866)
		(width 0.1143)
		(layer "In6.Cu")
		(net "P5E_CPU0_P2_RX_DP<3>")
	)
	(segment
		(start 407.776426 -393.842494)
		(end 407.776426 -393.428982)
		(width 0.14224)
		(layer "In6.Cu")
		(net "P5E_CPU0_P2_RX_DP<3>")
	)
	(segment
		(start 385.946904 -351.913698)
		(end 384.224276 -343.252806)
		(width 0.14224)
		(layer "In6.Cu")
		(net "P5E_CPU0_P2_RX_DP<3>")
	)
	(segment
		(start 364.341156 -296.200322)
		(end 364.34014 -296.199306)
		(width 0.1143)
		(layer "In6.Cu")
		(net "P5E_CPU0_P2_RX_DP<3>")
	)
	(segment
		(start 364.34014 -296.199306)
		(end 364.34014 -295.95572)
		(width 0.1143)
		(layer "In6.Cu")
		(net "P5E_CPU0_P2_RX_DP<3>")
	)
	(segment
		(start 363.590332 -292.391846)
		(end 363.626908 -292.37051)
		(width 0.1143)
		(layer "In6.Cu")
		(net "P5E_CPU0_P2_RX_DP<3>")
	)
	(segment
		(start 364.386622 -296.353484)
		(end 364.386622 -296.325036)
		(width 0.1143)
		(layer "In6.Cu")
		(net "P5E_CPU0_P2_RX_DP<3>")
	)
	(segment
		(start 364.965996 -283.501846)
		(end 364.996984 -283.484066)
		(width 0.1143)
		(layer "In6.Cu")
		(net "P5E_CPU0_P2_RX_DP<3>")
	)
	(segment
		(start 363.59465 -291.422582)
		(end 363.593126 -291.421566)
		(width 0.1143)
		(layer "In6.Cu")
		(net "P5E_CPU0_P2_RX_DP<3>")
	)
	(segment
		(start 363.582458 -289.795458)
		(end 363.581696 -289.79495)
		(width 0.1143)
		(layer "In6.Cu")
		(net "P5E_CPU0_P2_RX_DP<3>")
	)
	(segment
		(start 363.590586 -291.420042)
		(end 363.588808 -291.419026)
		(width 0.1143)
		(layer "In6.Cu")
		(net "P5E_CPU0_P2_RX_DP<3>")
	)
	(segment
		(start 363.626908 -294.681402)
		(end 363.62005 -294.677338)
		(width 0.1143)
		(layer "In6.Cu")
		(net "P5E_CPU0_P2_RX_DP<3>")
	)
	(segment
		(start 363.588808 -289.152838)
		(end 363.590332 -289.151822)
		(width 0.1143)
		(layer "In6.Cu")
		(net "P5E_CPU0_P2_RX_DP<3>")
	)
	(segment
		(start 407.46045 -393.113006)
		(end 407.463498 -392.7348)
		(width 0.14224)
		(layer "In6.Cu")
		(net "P5E_CPU0_P2_RX_DP<3>")
	)
	(segment
		(start 407.419048 -394.385292)
		(end 407.514044 -394.031216)
		(width 0.14224)
		(layer "In6.Cu")
		(net "P5E_CPU0_P2_RX_DP<3>")
	)
	(segment
		(start 363.59211 -289.801046)
		(end 363.590586 -289.80003)
		(width 0.1143)
		(layer "In6.Cu")
		(net "P5E_CPU0_P2_RX_DP<3>")
	)
	(segment
		(start 363.58576 -289.154616)
		(end 363.58703 -289.153854)
		(width 0.1143)
		(layer "In6.Cu")
		(net "P5E_CPU0_P2_RX_DP<3>")
	)
	(segment
		(start 364.386622 -296.325036)
		(end 364.340902 -296.279316)
		(width 0.1143)
		(layer "In6.Cu")
		(net "P5E_CPU0_P2_RX_DP<3>")
	)
	(segment
		(start 396.41653 -372.956328)
		(end 393.538964 -370.078762)
		(width 0.14224)
		(layer "In6.Cu")
		(net "P5E_CPU0_P2_RX_DP<3>")
	)
	(segment
		(start 363.593126 -294.66159)
		(end 363.59211 -294.661082)
		(width 0.1143)
		(layer "In6.Cu")
		(net "P5E_CPU0_P2_RX_DP<3>")
	)
	(segment
		(start 365.356902 -282.996132)
		(end 365.654844 -282.996132)
		(width 0.1143)
		(layer "In6.Cu")
		(net "P5E_CPU0_P2_RX_DP<3>")
	)
	(segment
		(start 363.556042 -292.411658)
		(end 363.58576 -292.39464)
		(width 0.1143)
		(layer "In6.Cu")
		(net "P5E_CPU0_P2_RX_DP<3>")
	)
	(segment
		(start 364.496096 -284.311852)
		(end 364.56493 -284.271974)
		(width 0.1143)
		(layer "In6.Cu")
		(net "P5E_CPU0_P2_RX_DP<3>")
	)
	(segment
		(start 364.027212 -285.12135)
		(end 364.057692 -285.10357)
		(width 0.1143)
		(layer "In6.Cu")
		(net "P5E_CPU0_P2_RX_DP<3>")
	)
	(segment
		(start 363.588808 -292.392862)
		(end 363.590332 -292.391846)
		(width 0.1143)
		(layer "In6.Cu")
		(net "P5E_CPU0_P2_RX_DP<3>")
	)
	(segment
		(start 363.581696 -293.034974)
		(end 363.579156 -293.033704)
		(width 0.1143)
		(layer "In6.Cu")
		(net "P5E_CPU0_P2_RX_DP<3>")
	)
	(segment
		(start 407.514044 -394.031216)
		(end 407.688288 -393.930632)
		(width 0.14224)
		(layer "In6.Cu")
		(net "P5E_CPU0_P2_RX_DP<3>")
	)
	(segment
		(start 363.584236 -293.036498)
		(end 363.583474 -293.03599)
		(width 0.1143)
		(layer "In6.Cu")
		(net "P5E_CPU0_P2_RX_DP<3>")
	)
	(segment
		(start 363.583474 -294.656002)
		(end 363.582458 -294.655494)
		(width 0.1143)
		(layer "In6.Cu")
		(net "P5E_CPU0_P2_RX_DP<3>")
	)
	(segment
		(start 374.720358 -313.948826)
		(end 369.61699 -307.730652)
		(width 0.14224)
		(layer "In6.Cu")
		(net "P5E_CPU0_P2_RX_DP<3>")
	)
	(segment
		(start 363.587792 -290.773358)
		(end 363.588808 -290.77285)
		(width 0.1143)
		(layer "In6.Cu")
		(net "P5E_CPU0_P2_RX_DP<3>")
	)
	(segment
		(start 363.579156 -289.79368)
		(end 363.556042 -289.780218)
		(width 0.1143)
		(layer "In6.Cu")
		(net "P5E_CPU0_P2_RX_DP<3>")
	)
	(segment
		(start 363.583474 -293.03599)
		(end 363.582458 -293.035482)
		(width 0.1143)
		(layer "In6.Cu")
		(net "P5E_CPU0_P2_RX_DP<3>")
	)
	(segment
		(start 363.587792 -289.798506)
		(end 363.58703 -289.797998)
		(width 0.1143)
		(layer "In6.Cu")
		(net "P5E_CPU0_P2_RX_DP<3>")
	)
	(segment
		(start 363.584236 -289.796474)
		(end 363.583474 -289.795966)
		(width 0.1143)
		(layer "In6.Cu")
		(net "P5E_CPU0_P2_RX_DP<3>")
	)
	(segment
		(start 363.62005 -294.677338)
		(end 363.619288 -294.67683)
		(width 0.1143)
		(layer "In6.Cu")
		(net "P5E_CPU0_P2_RX_DP<3>")
	)
	(segment
		(start 407.688288 -393.930632)
		(end 407.776426 -393.842494)
		(width 0.14224)
		(layer "In6.Cu")
		(net "P5E_CPU0_P2_RX_DP<3>")
	)
	(segment
		(start 364.386622 -298.24045)
		(end 364.386622 -296.353484)
		(width 0.14224)
		(layer "In6.Cu")
		(net "P5E_CPU0_P2_RX_DP<3>")
	)
	(segment
		(start 363.556042 -287.551876)
		(end 363.587792 -287.533588)
		(width 0.1143)
		(layer "In6.Cu")
		(net "P5E_CPU0_P2_RX_DP<3>")
	)
	(segment
		(start 363.588808 -285.913068)
		(end 363.590332 -285.912052)
		(width 0.1143)
		(layer "In6.Cu")
		(net "P5E_CPU0_P2_RX_DP<3>")
	)
	(segment
		(start 365.000286 -283.482034)
		(end 365.036862 -283.460698)
		(width 0.1143)
		(layer "In6.Cu")
		(net "P5E_CPU0_P2_RX_DP<3>")
	)
	(segment
		(start 364.998762 -283.48305)
		(end 365.000286 -283.482034)
		(width 0.1143)
		(layer "In6.Cu")
		(net "P5E_CPU0_P2_RX_DP<3>")
	)
	(segment
		(start 364.096808 -295.491408)
		(end 364.057692 -295.468548)
		(width 0.1143)
		(layer "In6.Cu")
		(net "P5E_CPU0_P2_RX_DP<3>")
	)
	(segment
		(start 364.386114 -298.460668)
		(end 364.386114 -298.24045)
		(width 0.14224)
		(layer "In6.Cu")
		(net "P5E_CPU0_P2_RX_DP<3>")
	)
	(segment
		(start 363.583474 -289.795966)
		(end 363.582458 -289.795458)
		(width 0.1143)
		(layer "In6.Cu")
		(net "P5E_CPU0_P2_RX_DP<3>")
	)
	(segment
		(start 363.583474 -291.415978)
		(end 363.582458 -291.41547)
		(width 0.1143)
		(layer "In6.Cu")
		(net "P5E_CPU0_P2_RX_DP<3>")
	)
	(segment
		(start 363.59465 -289.80257)
		(end 363.593126 -289.801554)
		(width 0.1143)
		(layer "In6.Cu")
		(net "P5E_CPU0_P2_RX_DP<3>")
	)
	(segment
		(start 376.498612 -316.609476)
		(end 374.720358 -313.948826)
		(width 0.14224)
		(layer "In6.Cu")
		(net "P5E_CPU0_P2_RX_DP<3>")
	)
	(segment
		(start 363.58703 -294.01389)
		(end 363.587792 -294.013382)
		(width 0.1143)
		(layer "In6.Cu")
		(net "P5E_CPU0_P2_RX_DP<3>")
	)
	(segment
		(start 401.369276 -375.766584)
		(end 396.443708 -372.976902)
		(width 0.14224)
		(layer "In6.Cu")
		(net "P5E_CPU0_P2_RX_DP<3>")
	)
	(segment
		(start 363.58703 -289.797998)
		(end 363.584236 -289.796474)
		(width 0.1143)
		(layer "In6.Cu")
		(net "P5E_CPU0_P2_RX_DP<3>")
	)
	(segment
		(start 401.676362 -375.94794)
		(end 401.676108 -375.94794)
		(width 0.14224)
		(layer "In6.Cu")
		(net "P5E_CPU0_P2_RX_DP<3>")
	)
	(segment
		(start 363.584236 -294.65651)
		(end 363.583474 -294.656002)
		(width 0.1143)
		(layer "In6.Cu")
		(net "P5E_CPU0_P2_RX_DP<3>")
	)
	(segment
		(start 363.58576 -292.39464)
		(end 363.58703 -292.393878)
		(width 0.1143)
		(layer "In6.Cu")
		(net "P5E_CPU0_P2_RX_DP<3>")
	)
	(segment
		(start 364.340902 -296.279316)
		(end 364.341156 -296.279062)
		(width 0.1143)
		(layer "In6.Cu")
		(net "P5E_CPU0_P2_RX_DP<3>")
	)
	(segment
		(start 363.62005 -293.057326)
		(end 363.619288 -293.056818)
		(width 0.1143)
		(layer "In6.Cu")
		(net "P5E_CPU0_P2_RX_DP<3>")
	)
	(segment
		(start 363.58703 -293.038022)
		(end 363.584236 -293.036498)
		(width 0.1143)
		(layer "In6.Cu")
		(net "P5E_CPU0_P2_RX_DP<3>")
	)
	(segment
		(start 363.58703 -290.773866)
		(end 363.587792 -290.773358)
		(width 0.1143)
		(layer "In6.Cu")
		(net "P5E_CPU0_P2_RX_DP<3>")
	)
	(segment
		(start 363.579156 -294.653716)
		(end 363.556042 -294.640254)
		(width 0.1143)
		(layer "In6.Cu")
		(net "P5E_CPU0_P2_RX_DP<3>")
	)
	(segment
		(start 363.593126 -291.421566)
		(end 363.59211 -291.421058)
		(width 0.1143)
		(layer "In6.Cu")
		(net "P5E_CPU0_P2_RX_DP<3>")
	)
	(segment
		(start 363.587792 -294.658542)
		(end 363.58703 -294.658034)
		(width 0.1143)
		(layer "In6.Cu")
		(net "P5E_CPU0_P2_RX_DP<3>")
	)
	(segment
		(start 363.59211 -294.661082)
		(end 363.590586 -294.660066)
		(width 0.1143)
		(layer "In6.Cu")
		(net "P5E_CPU0_P2_RX_DP<3>")
	)
	(segment
		(start 363.619288 -294.67683)
		(end 363.59465 -294.662606)
		(width 0.1143)
		(layer "In6.Cu")
		(net "P5E_CPU0_P2_RX_DP<3>")
	)
	(segment
		(start 363.581696 -289.79495)
		(end 363.579156 -289.79368)
		(width 0.1143)
		(layer "In6.Cu")
		(net "P5E_CPU0_P2_RX_DP<3>")
	)
	(segment
		(start 363.556042 -285.931864)
		(end 363.58576 -285.914846)
		(width 0.1143)
		(layer "In6.Cu")
		(net "P5E_CPU0_P2_RX_DP<3>")
	)
	(segment
		(start 363.59465 -294.662606)
		(end 363.593126 -294.66159)
		(width 0.1143)
		(layer "In6.Cu")
		(net "P5E_CPU0_P2_RX_DP<3>")
	)
	(segment
		(start 363.590332 -285.912052)
		(end 363.626908 -285.890716)
		(width 0.1143)
		(layer "In6.Cu")
		(net "P5E_CPU0_P2_RX_DP<3>")
	)
	(segment
		(start 363.58703 -285.914084)
		(end 363.587792 -285.913576)
		(width 0.1143)
		(layer "In6.Cu")
		(net "P5E_CPU0_P2_RX_DP<3>")
	)
	(segment
		(start 363.62005 -289.817302)
		(end 363.619288 -289.816794)
		(width 0.1143)
		(layer "In6.Cu")
		(net "P5E_CPU0_P2_RX_DP<3>")
	)
	(segment
		(start 364.386114 -298.24045)
		(end 364.386622 -298.24045)
		(width 0.14224)
		(layer "In6.Cu")
		(net "P5E_CPU0_P2_RX_DP<3>")
	)
	(segment
		(start 363.556042 -290.791646)
		(end 363.58576 -290.774628)
		(width 0.1143)
		(layer "In6.Cu")
		(net "P5E_CPU0_P2_RX_DP<3>")
	)
	(segment
		(start 363.590586 -293.040054)
		(end 363.588808 -293.039038)
		(width 0.1143)
		(layer "In6.Cu")
		(net "P5E_CPU0_P2_RX_DP<3>")
	)
	(segment
		(start 363.587792 -292.39337)
		(end 363.588808 -292.392862)
		(width 0.1143)
		(layer "In6.Cu")
		(net "P5E_CPU0_P2_RX_DP<3>")
	)
	(segment
		(start 363.58703 -289.153854)
		(end 363.587792 -289.153346)
		(width 0.1143)
		(layer "In6.Cu")
		(net "P5E_CPU0_P2_RX_DP<3>")
	)
	(segment
		(start 363.619288 -291.436806)
		(end 363.59465 -291.422582)
		(width 0.1143)
		(layer "In6.Cu")
		(net "P5E_CPU0_P2_RX_DP<3>")
	)
	(segment
		(start 363.626908 -288.201354)
		(end 363.587792 -288.178494)
		(width 0.1143)
		(layer "In6.Cu")
		(net "P5E_CPU0_P2_RX_DP<3>")
	)
	(segment
		(start 363.588808 -290.77285)
		(end 363.590332 -290.771834)
		(width 0.1143)
		(layer "In6.Cu")
		(net "P5E_CPU0_P2_RX_DP<3>")
	)
	(segment
		(start 363.587792 -294.013382)
		(end 363.588808 -294.012874)
		(width 0.1143)
		(layer "In6.Cu")
		(net "P5E_CPU0_P2_RX_DP<3>")
	)
	(segment
		(start 363.587792 -293.03853)
		(end 363.58703 -293.038022)
		(width 0.1143)
		(layer "In6.Cu")
		(net "P5E_CPU0_P2_RX_DP<3>")
	)
	(segment
		(start 363.588808 -294.012874)
		(end 363.590332 -294.011858)
		(width 0.1143)
		(layer "In6.Cu")
		(net "P5E_CPU0_P2_RX_DP<3>")
	)
	(segment
		(start 365.274098 -283.078936)
		(end 365.356902 -282.996132)
		(width 0.1143)
		(layer "In6.Cu")
		(net "P5E_CPU0_P2_RX_DP<3>")
	)
	(segment
		(start 363.626908 -289.821366)
		(end 363.62005 -289.817302)
		(width 0.1143)
		(layer "In6.Cu")
		(net "P5E_CPU0_P2_RX_DP<3>")
	)
	(segment
		(start 363.58576 -285.914846)
		(end 363.58703 -285.914084)
		(width 0.1143)
		(layer "In6.Cu")
		(net "P5E_CPU0_P2_RX_DP<3>")
	)
	(segment
		(start 364.996984 -283.484066)
		(end 364.997746 -283.483558)
		(width 0.1143)
		(layer "In6.Cu")
		(net "P5E_CPU0_P2_RX_DP<3>")
	)
	(segment
		(start 363.59211 -291.421058)
		(end 363.590586 -291.420042)
		(width 0.1143)
		(layer "In6.Cu")
		(net "P5E_CPU0_P2_RX_DP<3>")
	)
	(segment
		(start 363.59465 -293.042594)
		(end 363.593126 -293.041578)
		(width 0.1143)
		(layer "In6.Cu")
		(net "P5E_CPU0_P2_RX_DP<3>")
	)
	(segment
		(start 383.614422 -337.081368)
		(end 381.345948 -325.676768)
		(width 0.14224)
		(layer "In6.Cu")
		(net "P5E_CPU0_P2_RX_DP<3>")
	)
	(segment
		(start 364.997746 -283.483558)
		(end 364.998762 -283.48305)
		(width 0.1143)
		(layer "In6.Cu")
		(net "P5E_CPU0_P2_RX_DP<3>")
	)
	(segment
		(start 363.619288 -293.056818)
		(end 363.59465 -293.042594)
		(width 0.1143)
		(layer "In6.Cu")
		(net "P5E_CPU0_P2_RX_DP<3>")
	)
	(segment
		(start 363.588808 -291.419026)
		(end 363.587792 -291.418518)
		(width 0.1143)
		(layer "In6.Cu")
		(net "P5E_CPU0_P2_RX_DP<3>")
	)
	(segment
		(start 364.057692 -295.468548)
		(end 364.027212 -295.450768)
		(width 0.1143)
		(layer "In6.Cu")
		(net "P5E_CPU0_P2_RX_DP<3>")
	)
	(segment
		(start 384.21945 -343.22131)
		(end 383.614422 -337.081368)
		(width 0.14224)
		(layer "In6.Cu")
		(net "P5E_CPU0_P2_RX_DP<3>")
	)
	(segment
		(start 363.58703 -294.658034)
		(end 363.584236 -294.65651)
		(width 0.1143)
		(layer "In6.Cu")
		(net "P5E_CPU0_P2_RX_DP<3>")
	)
	(segment
		(start 364.341156 -296.279062)
		(end 364.341156 -296.200322)
		(width 0.1143)
		(layer "In6.Cu")
		(net "P5E_CPU0_P2_RX_DP<3>")
	)
	(segment
		(start 363.588808 -289.799014)
		(end 363.587792 -289.798506)
		(width 0.1143)
		(layer "In6.Cu")
		(net "P5E_CPU0_P2_RX_DP<3>")
	)
	(segment
		(start 363.58576 -294.014652)
		(end 363.58703 -294.01389)
		(width 0.1143)
		(layer "In6.Cu")
		(net "P5E_CPU0_P2_RX_DP<3>")
	)
	(segment
		(start 369.61699 -307.730652)
		(end 365.956596 -302.25238)
		(width 0.14224)
		(layer "In6.Cu")
		(net "P5E_CPU0_P2_RX_DP<3>")
	)
	(segment
		(start 363.593126 -289.801554)
		(end 363.59211 -289.801046)
		(width 0.1143)
		(layer "In6.Cu")
		(net "P5E_CPU0_P2_RX_DP<3>")
	)
	(segment
		(start 363.556042 -289.171634)
		(end 363.58576 -289.154616)
		(width 0.1143)
		(layer "In6.Cu")
		(net "P5E_CPU0_P2_RX_DP<3>")
	)
	(segment
		(start 407.768298 -392.363452)
		(end 407.768298 -390.437624)
		(width 0.14224)
		(layer "In6.Cu")
		(net "P5E_CPU0_P2_RX_DP<3>")
	)
	(segment
		(start 364.057692 -285.10357)
		(end 364.096808 -285.08071)
		(width 0.1143)
		(layer "In6.Cu")
		(net "P5E_CPU0_P2_RX_DP<3>")
	)
	(segment
		(start 363.626908 -286.581342)
		(end 363.587792 -286.558482)
		(width 0.1143)
		(layer "In6.Cu")
		(net "P5E_CPU0_P2_RX_DP<3>")
	)
	(segment
		(start 363.581696 -291.414962)
		(end 363.579156 -291.413692)
		(width 0.1143)
		(layer "In6.Cu")
		(net "P5E_CPU0_P2_RX_DP<3>")
	)
	(segment
		(start 363.59211 -293.04107)
		(end 363.590586 -293.040054)
		(width 0.1143)
		(layer "In6.Cu")
		(net "P5E_CPU0_P2_RX_DP<3>")
	)
	(segment
		(start 363.588808 -294.65905)
		(end 363.587792 -294.658542)
		(width 0.1143)
		(layer "In6.Cu")
		(net "P5E_CPU0_P2_RX_DP<3>")
	)
	(segment
		(start 401.676108 -375.94794)
		(end 401.369276 -375.766584)
		(width 0.14224)
		(layer "In6.Cu")
		(net "P5E_CPU0_P2_RX_DP<3>")
	)
	(segment
		(start 363.587792 -289.153346)
		(end 363.588808 -289.152838)
		(width 0.1143)
		(layer "In6.Cu")
		(net "P5E_CPU0_P2_RX_DP<3>")
	)
	(segment
		(start 363.590586 -294.660066)
		(end 363.588808 -294.65905)
		(width 0.1143)
		(layer "In6.Cu")
		(net "P5E_CPU0_P2_RX_DP<3>")
	)
	(segment
		(start 363.626908 -293.06139)
		(end 363.62005 -293.057326)
		(width 0.1143)
		(layer "In6.Cu")
		(net "P5E_CPU0_P2_RX_DP<3>")
	)
	(segment
		(start 401.778216 -376.008138)
		(end 401.676362 -375.94794)
		(width 0.14224)
		(layer "In6.Cu")
		(net "P5E_CPU0_P2_RX_DP<3>")
	)
	(segment
		(start 363.58703 -292.393878)
		(end 363.587792 -292.39337)
		(width 0.1143)
		(layer "In6.Cu")
		(net "P5E_CPU0_P2_RX_DP<3>")
	)
	(segment
		(start 363.587792 -285.913576)
		(end 363.588808 -285.913068)
		(width 0.1143)
		(layer "In6.Cu")
		(net "P5E_CPU0_P2_RX_DP<3>")
	)
	(segment
		(start 407.776426 -393.428982)
		(end 407.46045 -393.113006)
		(width 0.14224)
		(layer "In6.Cu")
		(net "P5E_CPU0_P2_RX_DP<3>")
	)
	(segment
		(start 363.581696 -294.654986)
		(end 363.579156 -294.653716)
		(width 0.1143)
		(layer "In6.Cu")
		(net "P5E_CPU0_P2_RX_DP<3>")
	)
	(segment
		(start 363.584236 -291.416486)
		(end 363.583474 -291.415978)
		(width 0.1143)
		(layer "In6.Cu")
		(net "P5E_CPU0_P2_RX_DP<3>")
	)
	(segment
		(start 393.289282 -369.704874)
		(end 386.020818 -352.157284)
		(width 0.14224)
		(layer "In6.Cu")
		(net "P5E_CPU0_P2_RX_DP<3>")
	)
	(segment
		(start 363.582458 -293.035482)
		(end 363.581696 -293.034974)
		(width 0.1143)
		(layer "In6.Cu")
		(net "P5E_CPU0_P2_RX_DP<3>")
	)
	(segment
		(start 363.590586 -289.80003)
		(end 363.588808 -289.799014)
		(width 0.1143)
		(layer "In6.Cu")
		(net "P5E_CPU0_P2_RX_DP<3>")
	)
	(segment
		(start 363.593126 -293.041578)
		(end 363.59211 -293.04107)
		(width 0.1143)
		(layer "In6.Cu")
		(net "P5E_CPU0_P2_RX_DP<3>")
	)
	(segment
		(start 363.590332 -290.771834)
		(end 363.626908 -290.750498)
		(width 0.1143)
		(layer "In6.Cu")
		(net "P5E_CPU0_P2_RX_DP<3>")
	)
	(segment
		(start 363.587792 -287.533588)
		(end 363.624368 -287.512252)
		(width 0.1143)
		(layer "In6.Cu")
		(net "P5E_CPU0_P2_RX_DP<3>")
	)
	(segment
		(start 381.345948 -325.676768)
		(end 376.498612 -316.609476)
		(width 0.14224)
		(layer "In6.Cu")
		(net "P5E_CPU0_P2_RX_DP<3>")
	)
	(segment
		(start 363.590332 -294.011858)
		(end 363.626908 -293.990522)
		(width 0.1143)
		(layer "In6.Cu")
		(net "P5E_CPU0_P2_RX_DP<3>")
	)
	(segment
		(start 363.579156 -293.033704)
		(end 363.556042 -293.020242)
		(width 0.1143)
		(layer "In6.Cu")
		(net "P5E_CPU0_P2_RX_DP<3>")
	)
	(segment
		(start 363.556042 -294.03167)
		(end 363.58576 -294.014652)
		(width 0.1143)
		(layer "In6.Cu")
		(net "P5E_CPU0_P2_RX_DP<3>")
	)
	(segment
		(start 363.582458 -291.41547)
		(end 363.581696 -291.414962)
		(width 0.1143)
		(layer "In6.Cu")
		(net "P5E_CPU0_P2_RX_DP<3>")
	)
	(segment
		(start 402.623274 -382.530858)
		(end 402.623274 -377.288044)
		(width 0.14224)
		(layer "In6.Cu")
		(net "P5E_CPU0_P2_RX_DP<3>")
	)
	(segment
		(start 363.587792 -288.178494)
		(end 363.554264 -288.158936)
		(width 0.1143)
		(layer "In6.Cu")
		(net "P5E_CPU0_P2_RX_DP<3>")
	)
	(segment
		(start 363.587792 -291.418518)
		(end 363.58703 -291.41801)
		(width 0.1143)
		(layer "In6.Cu")
		(net "P5E_CPU0_P2_RX_DP<3>")
	)
	(segment
		(start 365.956596 -302.25238)
		(end 364.386114 -298.460668)
		(width 0.14224)
		(layer "In6.Cu")
		(net "P5E_CPU0_P2_RX_DP<3>")
	)
	(segment
		(start 363.62005 -291.437314)
		(end 363.619288 -291.436806)
		(width 0.1143)
		(layer "In6.Cu")
		(net "P5E_CPU0_P2_RX_DP<3>")
	)
	(segment
		(start 363.58703 -291.41801)
		(end 363.584236 -291.416486)
		(width 0.1143)
		(layer "In6.Cu")
		(net "P5E_CPU0_P2_RX_DP<3>")
	)
	(segment
		(start 363.587792 -286.558482)
		(end 363.554264 -286.538924)
		(width 0.1143)
		(layer "In6.Cu")
		(net "P5E_CPU0_P2_RX_DP<3>")
	)
	(arc
		(start 393.538964 -370.078762)
		(mid 393.395719 -369.904109)
		(end 393.289282 -369.704874)
		(width 0.14224)
		(layer "In6.Cu")
		(net "P5E_CPU0_P2_RX_DP<3>")
	)
	(arc
		(start 363.400086 -287.856168)
		(mid 363.441341 -287.685197)
		(end 363.556042 -287.551876)
		(width 0.1143)
		(layer "In6.Cu")
		(net "P5E_CPU0_P2_RX_DP<3>")
	)
	(arc
		(start 365.036862 -283.460698)
		(mid 365.188849 -283.30419)
		(end 365.270288 -283.101796)
		(width 0.1143)
		(layer "In6.Cu")
		(net "P5E_CPU0_P2_RX_DP<3>")
	)
	(arc
		(start 364.81004 -283.796486)
		(mid 364.853433 -283.630854)
		(end 364.965996 -283.501846)
		(width 0.1143)
		(layer "In6.Cu")
		(net "P5E_CPU0_P2_RX_DP<3>")
	)
	(arc
		(start 364.096808 -285.08071)
		(mid 364.275621 -284.87836)
		(end 364.34014 -284.616144)
		(width 0.1143)
		(layer "In6.Cu")
		(net "P5E_CPU0_P2_RX_DP<3>")
	)
	(arc
		(start 396.443708 -372.976902)
		(mid 396.429428 -372.967528)
		(end 396.41653 -372.956328)
		(width 0.14224)
		(layer "In6.Cu")
		(net "P5E_CPU0_P2_RX_DP<3>")
	)
	(arc
		(start 363.624368 -287.512252)
		(mid 363.80502 -287.309507)
		(end 363.87024 -287.045908)
		(width 0.1143)
		(layer "In6.Cu")
		(net "P5E_CPU0_P2_RX_DP<3>")
	)
	(arc
		(start 364.34014 -295.95572)
		(mid 364.27564 -295.693591)
		(end 364.096808 -295.491408)
		(width 0.1143)
		(layer "In6.Cu")
		(net "P5E_CPU0_P2_RX_DP<3>")
	)
	(arc
		(start 363.626908 -285.890716)
		(mid 363.805721 -285.688366)
		(end 363.87024 -285.42615)
		(width 0.1143)
		(layer "In6.Cu")
		(net "P5E_CPU0_P2_RX_DP<3>")
	)
	(arc
		(start 402.623274 -377.288044)
		(mid 402.52432 -376.790566)
		(end 402.242528 -376.368818)
		(width 0.14224)
		(layer "In6.Cu")
		(net "P5E_CPU0_P2_RX_DP<3>")
	)
	(arc
		(start 402.960078 -383.158746)
		(mid 402.784939 -382.849123)
		(end 402.623528 -382.532128)
		(width 0.14224)
		(layer "In6.Cu")
		(net "P5E_CPU0_P2_RX_DP<3>")
	)
	(arc
		(start 363.87024 -285.42615)
		(mid 363.911789 -285.254728)
		(end 364.027212 -285.12135)
		(width 0.1143)
		(layer "In6.Cu")
		(net "P5E_CPU0_P2_RX_DP<3>")
	)
	(arc
		(start 363.556042 -289.780218)
		(mid 363.400114 -289.475926)
		(end 363.556042 -289.171634)
		(width 0.1143)
		(layer "In6.Cu")
		(net "P5E_CPU0_P2_RX_DP<3>")
	)
	(arc
		(start 363.626908 -292.37051)
		(mid 363.870235 -291.905944)
		(end 363.626908 -291.441378)
		(width 0.1143)
		(layer "In6.Cu")
		(net "P5E_CPU0_P2_RX_DP<3>")
	)
	(arc
		(start 363.87024 -287.045908)
		(mid 363.805725 -286.783689)
		(end 363.626908 -286.581342)
		(width 0.1143)
		(layer "In6.Cu")
		(net "P5E_CPU0_P2_RX_DP<3>")
	)
	(arc
		(start 364.34014 -284.616144)
		(mid 364.381395 -284.445173)
		(end 364.496096 -284.311852)
		(width 0.1143)
		(layer "In6.Cu")
		(net "P5E_CPU0_P2_RX_DP<3>")
	)
	(arc
		(start 402.242528 -376.368818)
		(mid 402.021691 -376.173906)
		(end 401.778216 -376.008138)
		(width 0.14224)
		(layer "In6.Cu")
		(net "P5E_CPU0_P2_RX_DP<3>")
	)
	(arc
		(start 364.027212 -295.450768)
		(mid 363.911785 -295.317392)
		(end 363.87024 -295.145968)
		(width 0.1143)
		(layer "In6.Cu")
		(net "P5E_CPU0_P2_RX_DP<3>")
	)
	(arc
		(start 363.554264 -286.538924)
		(mid 363.440857 -286.406035)
		(end 363.400086 -286.236156)
		(width 0.1143)
		(layer "In6.Cu")
		(net "P5E_CPU0_P2_RX_DP<3>")
	)
	(arc
		(start 386.020818 -352.157284)
		(mid 385.977888 -352.037304)
		(end 385.946904 -351.913698)
		(width 0.14224)
		(layer "In6.Cu")
		(net "P5E_CPU0_P2_RX_DP<3>")
	)
	(arc
		(start 407.721054 -392.477498)
		(mid 407.75607 -392.425188)
		(end 407.768298 -392.363452)
		(width 0.14224)
		(layer "In6.Cu")
		(net "P5E_CPU0_P2_RX_DP<3>")
	)
	(arc
		(start 363.554264 -288.158936)
		(mid 363.440857 -288.026047)
		(end 363.400086 -287.856168)
		(width 0.1143)
		(layer "In6.Cu")
		(net "P5E_CPU0_P2_RX_DP<3>")
	)
	(arc
		(start 363.626908 -290.750498)
		(mid 363.870235 -290.285932)
		(end 363.626908 -289.821366)
		(width 0.1143)
		(layer "In6.Cu")
		(net "P5E_CPU0_P2_RX_DP<3>")
	)
	(arc
		(start 363.626908 -293.990522)
		(mid 363.870235 -293.525956)
		(end 363.626908 -293.06139)
		(width 0.1143)
		(layer "In6.Cu")
		(net "P5E_CPU0_P2_RX_DP<3>")
	)
	(arc
		(start 364.806484 -283.840936)
		(mid 364.808828 -283.818756)
		(end 364.81004 -283.796486)
		(width 0.1143)
		(layer "In6.Cu")
		(net "P5E_CPU0_P2_RX_DP<3>")
	)
	(arc
		(start 363.556042 -293.020242)
		(mid 363.400114 -292.71595)
		(end 363.556042 -292.411658)
		(width 0.1143)
		(layer "In6.Cu")
		(net "P5E_CPU0_P2_RX_DP<3>")
	)
	(arc
		(start 363.87024 -295.145968)
		(mid 363.805725 -294.883749)
		(end 363.626908 -294.681402)
		(width 0.1143)
		(layer "In6.Cu")
		(net "P5E_CPU0_P2_RX_DP<3>")
	)
	(arc
		(start 363.400086 -286.236156)
		(mid 363.441341 -286.065185)
		(end 363.556042 -285.931864)
		(width 0.1143)
		(layer "In6.Cu")
		(net "P5E_CPU0_P2_RX_DP<3>")
	)
	(arc
		(start 384.224276 -343.252806)
		(mid 384.22147 -343.237118)
		(end 384.21945 -343.22131)
		(width 0.14224)
		(layer "In6.Cu")
		(net "P5E_CPU0_P2_RX_DP<3>")
	)
	(arc
		(start 402.623528 -382.532128)
		(mid 402.623344 -382.531509)
		(end 402.623274 -382.530858)
		(width 0.14224)
		(layer "In6.Cu")
		(net "P5E_CPU0_P2_RX_DP<3>")
	)
	(arc
		(start 363.556042 -294.640254)
		(mid 363.400114 -294.335962)
		(end 363.556042 -294.03167)
		(width 0.1143)
		(layer "In6.Cu")
		(net "P5E_CPU0_P2_RX_DP<3>")
	)
	(arc
		(start 363.556042 -291.40023)
		(mid 363.400114 -291.095938)
		(end 363.556042 -290.791646)
		(width 0.1143)
		(layer "In6.Cu")
		(net "P5E_CPU0_P2_RX_DP<3>")
	)
	(arc
		(start 407.768298 -390.437624)
		(mid 407.746714 -390.292748)
		(end 407.683716 -390.16051)
		(width 0.14224)
		(layer "In6.Cu")
		(net "P5E_CPU0_P2_RX_DP<3>")
	)
	(arc
		(start 364.56493 -284.271974)
		(mid 364.726144 -284.079116)
		(end 364.806484 -283.840936)
		(width 0.1143)
		(layer "In6.Cu")
		(net "P5E_CPU0_P2_RX_DP<3>")
	)
	(arc
		(start 363.626908 -289.130486)
		(mid 363.870235 -288.66592)
		(end 363.626908 -288.201354)
		(width 0.1143)
		(layer "In6.Cu")
		(net "P5E_CPU0_P2_RX_DP<3>")
	)
	(arc
		(start 365.270288 -283.101796)
		(mid 365.272311 -283.090386)
		(end 365.274098 -283.078936)
		(width 0.1143)
		(layer "In6.Cu")
		(net "P5E_CPU0_P2_RX_DP<3>")
	)
	(segment
		(start 362.837984 -285.160212)
		(end 363.304836 -285.42615)
		(width 0.12954)
		(layer "F.Cu")
		(net "P5E_CPU0_P2_RX_DP<2>")
	)
	(segment
		(start 405.698198 -394.385292)
		(end 406.218898 -394.385292)
		(width 0.127)
		(layer "F.Cu")
		(net "P5E_CPU0_P2_RX_DP<2>")
	)
	(segment
		(start 406.2603 -393.113006)
		(end 406.263348 -392.734546)
		(width 0.14224)
		(layer "In6.Cu")
		(net "P5E_CPU0_P2_RX_DP<2>")
	)
	(segment
		(start 362.647738 -290.773358)
		(end 362.648754 -290.77285)
		(width 0.1143)
		(layer "In6.Cu")
		(net "P5E_CPU0_P2_RX_DP<2>")
	)
	(segment
		(start 362.61167 -290.794948)
		(end 362.615988 -290.791646)
		(width 0.1143)
		(layer "In6.Cu")
		(net "P5E_CPU0_P2_RX_DP<2>")
	)
	(segment
		(start 362.647738 -292.39337)
		(end 362.648754 -292.392862)
		(width 0.1143)
		(layer "In6.Cu")
		(net "P5E_CPU0_P2_RX_DP<2>")
	)
	(segment
		(start 375.66727 -317.05423)
		(end 373.98325 -314.534042)
		(width 0.14224)
		(layer "In6.Cu")
		(net "P5E_CPU0_P2_RX_DP<2>")
	)
	(segment
		(start 362.643674 -294.015414)
		(end 362.648754 -294.012874)
		(width 0.1143)
		(layer "In6.Cu")
		(net "P5E_CPU0_P2_RX_DP<2>")
	)
	(segment
		(start 362.686854 -286.581342)
		(end 362.647738 -286.558482)
		(width 0.1143)
		(layer "In6.Cu")
		(net "P5E_CPU0_P2_RX_DP<2>")
	)
	(segment
		(start 362.653072 -294.66159)
		(end 362.652056 -294.661082)
		(width 0.1143)
		(layer "In6.Cu")
		(net "P5E_CPU0_P2_RX_DP<2>")
	)
	(segment
		(start 402.076666 -383.57683)
		(end 401.714462 -382.855216)
		(width 0.14224)
		(layer "In6.Cu")
		(net "P5E_CPU0_P2_RX_DP<2>")
	)
	(segment
		(start 362.645706 -292.39464)
		(end 362.646976 -292.393878)
		(width 0.1143)
		(layer "In6.Cu")
		(net "P5E_CPU0_P2_RX_DP<2>")
	)
	(segment
		(start 362.681774 -294.678354)
		(end 362.679234 -294.67683)
		(width 0.1143)
		(layer "In6.Cu")
		(net "P5E_CPU0_P2_RX_DP<2>")
	)
	(segment
		(start 362.653072 -293.041578)
		(end 362.652056 -293.04107)
		(width 0.1143)
		(layer "In6.Cu")
		(net "P5E_CPU0_P2_RX_DP<2>")
	)
	(segment
		(start 362.648754 -292.392862)
		(end 362.650278 -292.391846)
		(width 0.1143)
		(layer "In6.Cu")
		(net "P5E_CPU0_P2_RX_DP<2>")
	)
	(segment
		(start 362.637324 -293.032688)
		(end 362.615988 -293.020242)
		(width 0.1143)
		(layer "In6.Cu")
		(net "P5E_CPU0_P2_RX_DP<2>")
	)
	(segment
		(start 406.488138 -393.930632)
		(end 406.576276 -393.842494)
		(width 0.14224)
		(layer "In6.Cu")
		(net "P5E_CPU0_P2_RX_DP<2>")
	)
	(segment
		(start 363.445806 -297.299634)
		(end 363.445298 -297.299126)
		(width 0.14224)
		(layer "In6.Cu")
		(net "P5E_CPU0_P2_RX_DP<2>")
	)
	(segment
		(start 362.686854 -291.441378)
		(end 362.679996 -291.437314)
		(width 0.1143)
		(layer "In6.Cu")
		(net "P5E_CPU0_P2_RX_DP<2>")
	)
	(segment
		(start 362.650532 -293.040054)
		(end 362.648754 -293.039038)
		(width 0.1143)
		(layer "In6.Cu")
		(net "P5E_CPU0_P2_RX_DP<2>")
	)
	(segment
		(start 363.006894 -285.42615)
		(end 363.304836 -285.42615)
		(width 0.1143)
		(layer "In6.Cu")
		(net "P5E_CPU0_P2_RX_DP<2>")
	)
	(segment
		(start 362.679234 -293.056818)
		(end 362.654596 -293.042594)
		(width 0.1143)
		(layer "In6.Cu")
		(net "P5E_CPU0_P2_RX_DP<2>")
	)
	(segment
		(start 406.568148 -392.429746)
		(end 406.568148 -390.459468)
		(width 0.14224)
		(layer "In6.Cu")
		(net "P5E_CPU0_P2_RX_DP<2>")
	)
	(segment
		(start 363.155992 -295.499282)
		(end 363.08919 -295.452546)
		(width 0.1143)
		(layer "In6.Cu")
		(net "P5E_CPU0_P2_RX_DP<2>")
	)
	(segment
		(start 362.648754 -285.913068)
		(end 362.650278 -285.912052)
		(width 0.1143)
		(layer "In6.Cu")
		(net "P5E_CPU0_P2_RX_DP<2>")
	)
	(segment
		(start 362.650532 -294.660066)
		(end 362.648754 -294.65905)
		(width 0.1143)
		(layer "In6.Cu")
		(net "P5E_CPU0_P2_RX_DP<2>")
	)
	(segment
		(start 383.281174 -343.340944)
		(end 382.682242 -337.260438)
		(width 0.14224)
		(layer "In6.Cu")
		(net "P5E_CPU0_P2_RX_DP<2>")
	)
	(segment
		(start 362.670598 -288.191956)
		(end 362.61421 -288.158936)
		(width 0.1143)
		(layer "In6.Cu")
		(net "P5E_CPU0_P2_RX_DP<2>")
	)
	(segment
		(start 401.622006 -382.60147)
		(end 400.926554 -379.670056)
		(width 0.14224)
		(layer "In6.Cu")
		(net "P5E_CPU0_P2_RX_DP<2>")
	)
	(segment
		(start 362.652056 -294.661082)
		(end 362.650532 -294.660066)
		(width 0.1143)
		(layer "In6.Cu")
		(net "P5E_CPU0_P2_RX_DP<2>")
	)
	(segment
		(start 362.654596 -289.80257)
		(end 362.653072 -289.801554)
		(width 0.1143)
		(layer "In6.Cu")
		(net "P5E_CPU0_P2_RX_DP<2>")
	)
	(segment
		(start 362.653072 -289.801554)
		(end 362.652056 -289.801046)
		(width 0.1143)
		(layer "In6.Cu")
		(net "P5E_CPU0_P2_RX_DP<2>")
	)
	(segment
		(start 362.648754 -294.012874)
		(end 362.650278 -294.011858)
		(width 0.1143)
		(layer "In6.Cu")
		(net "P5E_CPU0_P2_RX_DP<2>")
	)
	(segment
		(start 406.218898 -394.385292)
		(end 406.313894 -394.031216)
		(width 0.14224)
		(layer "In6.Cu")
		(net "P5E_CPU0_P2_RX_DP<2>")
	)
	(segment
		(start 406.492202 -390.22147)
		(end 403.887432 -386.577332)
		(width 0.14224)
		(layer "In6.Cu")
		(net "P5E_CPU0_P2_RX_DP<2>")
	)
	(segment
		(start 362.650278 -294.011858)
		(end 362.686854 -293.990522)
		(width 0.1143)
		(layer "In6.Cu")
		(net "P5E_CPU0_P2_RX_DP<2>")
	)
	(segment
		(start 362.652056 -289.801046)
		(end 362.650532 -289.80003)
		(width 0.1143)
		(layer "In6.Cu")
		(net "P5E_CPU0_P2_RX_DP<2>")
	)
	(segment
		(start 362.650278 -290.771834)
		(end 362.686854 -290.750498)
		(width 0.1143)
		(layer "In6.Cu")
		(net "P5E_CPU0_P2_RX_DP<2>")
	)
	(segment
		(start 362.644182 -293.036498)
		(end 362.64342 -293.03599)
		(width 0.1143)
		(layer "In6.Cu")
		(net "P5E_CPU0_P2_RX_DP<2>")
	)
	(segment
		(start 362.639864 -293.033958)
		(end 362.637324 -293.032688)
		(width 0.1143)
		(layer "In6.Cu")
		(net "P5E_CPU0_P2_RX_DP<2>")
	)
	(segment
		(start 362.647738 -291.418518)
		(end 362.646976 -291.41801)
		(width 0.1143)
		(layer "In6.Cu")
		(net "P5E_CPU0_P2_RX_DP<2>")
	)
	(segment
		(start 400.74723 -379.182884)
		(end 400.332956 -378.76861)
		(width 0.14224)
		(layer "In6.Cu")
		(net "P5E_CPU0_P2_RX_DP<2>")
	)
	(segment
		(start 363.445298 -296.353484)
		(end 363.445298 -296.325036)
		(width 0.1143)
		(layer "In6.Cu")
		(net "P5E_CPU0_P2_RX_DP<2>")
	)
	(segment
		(start 380.438914 -325.981314)
		(end 375.66727 -317.05423)
		(width 0.14224)
		(layer "In6.Cu")
		(net "P5E_CPU0_P2_RX_DP<2>")
	)
	(segment
		(start 363.445298 -296.325036)
		(end 363.399578 -296.279316)
		(width 0.1143)
		(layer "In6.Cu")
		(net "P5E_CPU0_P2_RX_DP<2>")
	)
	(segment
		(start 392.449812 -370.244624)
		(end 385.109212 -352.523044)
		(width 0.14224)
		(layer "In6.Cu")
		(net "P5E_CPU0_P2_RX_DP<2>")
	)
	(segment
		(start 362.615988 -290.791646)
		(end 362.646976 -290.773866)
		(width 0.1143)
		(layer "In6.Cu")
		(net "P5E_CPU0_P2_RX_DP<2>")
	)
	(segment
		(start 362.647738 -293.03853)
		(end 362.646976 -293.038022)
		(width 0.1143)
		(layer "In6.Cu")
		(net "P5E_CPU0_P2_RX_DP<2>")
	)
	(segment
		(start 406.576276 -393.428982)
		(end 406.2603 -393.113006)
		(width 0.14224)
		(layer "In6.Cu")
		(net "P5E_CPU0_P2_RX_DP<2>")
	)
	(segment
		(start 362.615988 -287.551876)
		(end 362.647738 -287.533588)
		(width 0.1143)
		(layer "In6.Cu")
		(net "P5E_CPU0_P2_RX_DP<2>")
	)
	(segment
		(start 363.399578 -295.888918)
		(end 363.325918 -295.711372)
		(width 0.1143)
		(layer "In6.Cu")
		(net "P5E_CPU0_P2_RX_DP<2>")
	)
	(segment
		(start 368.915188 -308.358794)
		(end 365.130588 -302.694848)
		(width 0.14224)
		(layer "In6.Cu")
		(net "P5E_CPU0_P2_RX_DP<2>")
	)
	(segment
		(start 406.576276 -393.842494)
		(end 406.576276 -393.428982)
		(width 0.14224)
		(layer "In6.Cu")
		(net "P5E_CPU0_P2_RX_DP<2>")
	)
	(segment
		(start 362.648754 -290.77285)
		(end 362.650278 -290.771834)
		(width 0.1143)
		(layer "In6.Cu")
		(net "P5E_CPU0_P2_RX_DP<2>")
	)
	(segment
		(start 362.647738 -286.558482)
		(end 362.61421 -286.538924)
		(width 0.1143)
		(layer "In6.Cu")
		(net "P5E_CPU0_P2_RX_DP<2>")
	)
	(segment
		(start 362.679996 -293.057326)
		(end 362.679234 -293.056818)
		(width 0.1143)
		(layer "In6.Cu")
		(net "P5E_CPU0_P2_RX_DP<2>")
	)
	(segment
		(start 362.647738 -289.798506)
		(end 362.646976 -289.797998)
		(width 0.1143)
		(layer "In6.Cu")
		(net "P5E_CPU0_P2_RX_DP<2>")
	)
	(segment
		(start 362.654596 -291.422582)
		(end 362.653072 -291.421566)
		(width 0.1143)
		(layer "In6.Cu")
		(net "P5E_CPU0_P2_RX_DP<2>")
	)
	(segment
		(start 362.654596 -293.042594)
		(end 362.653072 -293.041578)
		(width 0.1143)
		(layer "In6.Cu")
		(net "P5E_CPU0_P2_RX_DP<2>")
	)
	(segment
		(start 406.263348 -392.734546)
		(end 406.568148 -392.429746)
		(width 0.14224)
		(layer "In6.Cu")
		(net "P5E_CPU0_P2_RX_DP<2>")
	)
	(segment
		(start 362.646976 -292.393878)
		(end 362.647738 -292.39337)
		(width 0.1143)
		(layer "In6.Cu")
		(net "P5E_CPU0_P2_RX_DP<2>")
	)
	(segment
		(start 362.650278 -292.391846)
		(end 362.686854 -292.37051)
		(width 0.1143)
		(layer "In6.Cu")
		(net "P5E_CPU0_P2_RX_DP<2>")
	)
	(segment
		(start 362.679234 -291.436806)
		(end 362.654596 -291.422582)
		(width 0.1143)
		(layer "In6.Cu")
		(net "P5E_CPU0_P2_RX_DP<2>")
	)
	(segment
		(start 363.399578 -296.279316)
		(end 363.399578 -295.888918)
		(width 0.1143)
		(layer "In6.Cu")
		(net "P5E_CPU0_P2_RX_DP<2>")
	)
	(segment
		(start 362.652056 -293.04107)
		(end 362.650532 -293.040054)
		(width 0.1143)
		(layer "In6.Cu")
		(net "P5E_CPU0_P2_RX_DP<2>")
	)
	(segment
		(start 399.14449 -378.048012)
		(end 399.011394 -377.914916)
		(width 0.14224)
		(layer "In6.Cu")
		(net "P5E_CPU0_P2_RX_DP<2>")
	)
	(segment
		(start 362.64342 -293.03599)
		(end 362.641896 -293.035228)
		(width 0.1143)
		(layer "In6.Cu")
		(net "P5E_CPU0_P2_RX_DP<2>")
	)
	(segment
		(start 362.654596 -294.662606)
		(end 362.653072 -294.66159)
		(width 0.1143)
		(layer "In6.Cu")
		(net "P5E_CPU0_P2_RX_DP<2>")
	)
	(segment
		(start 382.682242 -337.260438)
		(end 380.438914 -325.981314)
		(width 0.14224)
		(layer "In6.Cu")
		(net "P5E_CPU0_P2_RX_DP<2>")
	)
	(segment
		(start 362.686854 -289.821366)
		(end 362.679996 -289.817302)
		(width 0.1143)
		(layer "In6.Cu")
		(net "P5E_CPU0_P2_RX_DP<2>")
	)
	(segment
		(start 398.96415 -377.80087)
		(end 398.96415 -377.026678)
		(width 0.14224)
		(layer "In6.Cu")
		(net "P5E_CPU0_P2_RX_DP<2>")
	)
	(segment
		(start 362.647738 -285.913576)
		(end 362.648754 -285.913068)
		(width 0.1143)
		(layer "In6.Cu")
		(net "P5E_CPU0_P2_RX_DP<2>")
	)
	(segment
		(start 362.648754 -294.65905)
		(end 362.647738 -294.658542)
		(width 0.1143)
		(layer "In6.Cu")
		(net "P5E_CPU0_P2_RX_DP<2>")
	)
	(segment
		(start 363.445298 -297.299634)
		(end 363.445806 -297.299634)
		(width 0.14224)
		(layer "In6.Cu")
		(net "P5E_CPU0_P2_RX_DP<2>")
	)
	(segment
		(start 398.83461 -376.712988)
		(end 392.618468 -370.4971)
		(width 0.14224)
		(layer "In6.Cu")
		(net "P5E_CPU0_P2_RX_DP<2>")
	)
	(segment
		(start 362.679234 -294.67683)
		(end 362.654596 -294.662606)
		(width 0.1143)
		(layer "In6.Cu")
		(net "P5E_CPU0_P2_RX_DP<2>")
	)
	(segment
		(start 362.641896 -293.035228)
		(end 362.641134 -293.03472)
		(width 0.1143)
		(layer "In6.Cu")
		(net "P5E_CPU0_P2_RX_DP<2>")
	)
	(segment
		(start 362.648754 -291.419026)
		(end 362.647738 -291.418518)
		(width 0.1143)
		(layer "In6.Cu")
		(net "P5E_CPU0_P2_RX_DP<2>")
	)
	(segment
		(start 362.648754 -293.039038)
		(end 362.647738 -293.03853)
		(width 0.1143)
		(layer "In6.Cu")
		(net "P5E_CPU0_P2_RX_DP<2>")
	)
	(segment
		(start 362.648754 -289.799014)
		(end 362.647738 -289.798506)
		(width 0.1143)
		(layer "In6.Cu")
		(net "P5E_CPU0_P2_RX_DP<2>")
	)
	(segment
		(start 362.615988 -291.40023)
		(end 362.61167 -291.396928)
		(width 0.1143)
		(layer "In6.Cu")
		(net "P5E_CPU0_P2_RX_DP<2>")
	)
	(segment
		(start 362.679996 -291.437314)
		(end 362.679234 -291.436806)
		(width 0.1143)
		(layer "In6.Cu")
		(net "P5E_CPU0_P2_RX_DP<2>")
	)
	(segment
		(start 362.647738 -294.658542)
		(end 362.646976 -294.658034)
		(width 0.1143)
		(layer "In6.Cu")
		(net "P5E_CPU0_P2_RX_DP<2>")
	)
	(segment
		(start 362.641134 -293.03472)
		(end 362.639864 -293.033958)
		(width 0.1143)
		(layer "In6.Cu")
		(net "P5E_CPU0_P2_RX_DP<2>")
	)
	(segment
		(start 362.646976 -285.914084)
		(end 362.647738 -285.913576)
		(width 0.1143)
		(layer "In6.Cu")
		(net "P5E_CPU0_P2_RX_DP<2>")
	)
	(segment
		(start 362.646468 -289.153854)
		(end 362.673646 -289.13836)
		(width 0.1143)
		(layer "In6.Cu")
		(net "P5E_CPU0_P2_RX_DP<2>")
	)
	(segment
		(start 362.92409 -285.508954)
		(end 363.006894 -285.42615)
		(width 0.1143)
		(layer "In6.Cu")
		(net "P5E_CPU0_P2_RX_DP<2>")
	)
	(segment
		(start 362.650532 -289.80003)
		(end 362.648754 -289.799014)
		(width 0.1143)
		(layer "In6.Cu")
		(net "P5E_CPU0_P2_RX_DP<2>")
	)
	(segment
		(start 362.650278 -285.912052)
		(end 362.686854 -285.890716)
		(width 0.1143)
		(layer "In6.Cu")
		(net "P5E_CPU0_P2_RX_DP<2>")
	)
	(segment
		(start 400.926554 -379.670056)
		(end 400.913346 -379.583696)
		(width 0.14224)
		(layer "In6.Cu")
		(net "P5E_CPU0_P2_RX_DP<2>")
	)
	(segment
		(start 373.98325 -314.534042)
		(end 368.915188 -308.358794)
		(width 0.14224)
		(layer "In6.Cu")
		(net "P5E_CPU0_P2_RX_DP<2>")
	)
	(segment
		(start 385.1021 -352.499422)
		(end 383.282952 -343.353136)
		(width 0.14224)
		(layer "In6.Cu")
		(net "P5E_CPU0_P2_RX_DP<2>")
	)
	(segment
		(start 403.887432 -386.577332)
		(end 402.076666 -383.57683)
		(width 0.14224)
		(layer "In6.Cu")
		(net "P5E_CPU0_P2_RX_DP<2>")
	)
	(segment
		(start 362.646976 -289.797998)
		(end 362.643928 -289.796474)
		(width 0.1143)
		(layer "In6.Cu")
		(net "P5E_CPU0_P2_RX_DP<2>")
	)
	(segment
		(start 362.646976 -291.41801)
		(end 362.615988 -291.40023)
		(width 0.1143)
		(layer "In6.Cu")
		(net "P5E_CPU0_P2_RX_DP<2>")
	)
	(segment
		(start 362.615988 -292.411658)
		(end 362.645706 -292.39464)
		(width 0.1143)
		(layer "In6.Cu")
		(net "P5E_CPU0_P2_RX_DP<2>")
	)
	(segment
		(start 362.686854 -293.06139)
		(end 362.679996 -293.057326)
		(width 0.1143)
		(layer "In6.Cu")
		(net "P5E_CPU0_P2_RX_DP<2>")
	)
	(segment
		(start 362.650532 -291.420042)
		(end 362.648754 -291.419026)
		(width 0.1143)
		(layer "In6.Cu")
		(net "P5E_CPU0_P2_RX_DP<2>")
	)
	(segment
		(start 362.646976 -290.773866)
		(end 362.647738 -290.773358)
		(width 0.1143)
		(layer "In6.Cu")
		(net "P5E_CPU0_P2_RX_DP<2>")
	)
	(segment
		(start 362.646976 -293.038022)
		(end 362.644182 -293.036498)
		(width 0.1143)
		(layer "In6.Cu")
		(net "P5E_CPU0_P2_RX_DP<2>")
	)
	(segment
		(start 362.643674 -289.155378)
		(end 362.646468 -289.153854)
		(width 0.1143)
		(layer "In6.Cu")
		(net "P5E_CPU0_P2_RX_DP<2>")
	)
	(segment
		(start 362.679234 -289.816794)
		(end 362.654596 -289.80257)
		(width 0.1143)
		(layer "In6.Cu")
		(net "P5E_CPU0_P2_RX_DP<2>")
	)
	(segment
		(start 362.647738 -287.533588)
		(end 362.684314 -287.512252)
		(width 0.1143)
		(layer "In6.Cu")
		(net "P5E_CPU0_P2_RX_DP<2>")
	)
	(segment
		(start 406.313894 -394.031216)
		(end 406.488138 -393.930632)
		(width 0.14224)
		(layer "In6.Cu")
		(net "P5E_CPU0_P2_RX_DP<2>")
	)
	(segment
		(start 363.445298 -297.299126)
		(end 363.445298 -296.353484)
		(width 0.14224)
		(layer "In6.Cu")
		(net "P5E_CPU0_P2_RX_DP<2>")
	)
	(segment
		(start 362.652056 -291.421058)
		(end 362.650532 -291.420042)
		(width 0.1143)
		(layer "In6.Cu")
		(net "P5E_CPU0_P2_RX_DP<2>")
	)
	(segment
		(start 362.615988 -285.931864)
		(end 362.646976 -285.914084)
		(width 0.1143)
		(layer "In6.Cu")
		(net "P5E_CPU0_P2_RX_DP<2>")
	)
	(segment
		(start 400.913346 -379.583696)
		(end 400.913346 -379.58395)
		(width 0.14224)
		(layer "In6.Cu")
		(net "P5E_CPU0_P2_RX_DP<2>")
	)
	(segment
		(start 365.130588 -302.694848)
		(end 363.445298 -298.625768)
		(width 0.14224)
		(layer "In6.Cu")
		(net "P5E_CPU0_P2_RX_DP<2>")
	)
	(segment
		(start 362.646976 -294.658034)
		(end 362.643928 -294.65651)
		(width 0.1143)
		(layer "In6.Cu")
		(net "P5E_CPU0_P2_RX_DP<2>")
	)
	(segment
		(start 362.653072 -291.421566)
		(end 362.652056 -291.421058)
		(width 0.1143)
		(layer "In6.Cu")
		(net "P5E_CPU0_P2_RX_DP<2>")
	)
	(segment
		(start 362.679996 -289.817302)
		(end 362.679234 -289.816794)
		(width 0.1143)
		(layer "In6.Cu")
		(net "P5E_CPU0_P2_RX_DP<2>")
	)
	(segment
		(start 363.445298 -298.625768)
		(end 363.445298 -297.299634)
		(width 0.14224)
		(layer "In6.Cu")
		(net "P5E_CPU0_P2_RX_DP<2>")
	)
	(segment
		(start 362.686092 -294.680894)
		(end 362.681774 -294.678354)
		(width 0.1143)
		(layer "In6.Cu")
		(net "P5E_CPU0_P2_RX_DP<2>")
	)
	(arc
		(start 399.011394 -377.914916)
		(mid 398.976432 -377.862591)
		(end 398.96415 -377.80087)
		(width 0.14224)
		(layer "In6.Cu")
		(net "P5E_CPU0_P2_RX_DP<2>")
	)
	(arc
		(start 399.73885 -378.408184)
		(mid 399.419926 -378.263981)
		(end 399.14449 -378.048012)
		(width 0.14224)
		(layer "In6.Cu")
		(net "P5E_CPU0_P2_RX_DP<2>")
	)
	(arc
		(start 383.282952 -343.353136)
		(mid 383.281916 -343.347061)
		(end 383.281174 -343.340944)
		(width 0.14224)
		(layer "In6.Cu")
		(net "P5E_CPU0_P2_RX_DP<2>")
	)
	(arc
		(start 400.332956 -378.76861)
		(mid 400.057649 -378.552558)
		(end 399.73885 -378.408184)
		(width 0.14224)
		(layer "In6.Cu")
		(net "P5E_CPU0_P2_RX_DP<2>")
	)
	(arc
		(start 362.92028 -285.531814)
		(mid 362.922303 -285.520404)
		(end 362.92409 -285.508954)
		(width 0.1143)
		(layer "In6.Cu")
		(net "P5E_CPU0_P2_RX_DP<2>")
	)
	(arc
		(start 362.684314 -287.512252)
		(mid 362.864966 -287.309507)
		(end 362.930186 -287.045908)
		(width 0.1143)
		(layer "In6.Cu")
		(net "P5E_CPU0_P2_RX_DP<2>")
	)
	(arc
		(start 398.96415 -377.026678)
		(mid 398.930577 -376.856954)
		(end 398.83461 -376.712988)
		(width 0.14224)
		(layer "In6.Cu")
		(net "P5E_CPU0_P2_RX_DP<2>")
	)
	(arc
		(start 400.913346 -379.58395)
		(mid 400.870172 -379.366899)
		(end 400.74723 -379.182884)
		(width 0.14224)
		(layer "In6.Cu")
		(net "P5E_CPU0_P2_RX_DP<2>")
	)
	(arc
		(start 362.643928 -289.796474)
		(mid 362.460171 -289.476036)
		(end 362.643674 -289.155378)
		(width 0.1143)
		(layer "In6.Cu")
		(net "P5E_CPU0_P2_RX_DP<2>")
	)
	(arc
		(start 362.678472 -288.196782)
		(mid 362.674545 -288.194352)
		(end 362.670598 -288.191956)
		(width 0.1143)
		(layer "In6.Cu")
		(net "P5E_CPU0_P2_RX_DP<2>")
	)
	(arc
		(start 363.08919 -295.452546)
		(mid 362.972102 -295.318712)
		(end 362.929932 -295.145968)
		(width 0.1143)
		(layer "In6.Cu")
		(net "P5E_CPU0_P2_RX_DP<2>")
	)
	(arc
		(start 385.109212 -352.523044)
		(mid 385.105084 -352.511405)
		(end 385.1021 -352.499422)
		(width 0.14224)
		(layer "In6.Cu")
		(net "P5E_CPU0_P2_RX_DP<2>")
	)
	(arc
		(start 362.61421 -288.158936)
		(mid 362.500803 -288.026047)
		(end 362.460032 -287.856168)
		(width 0.1143)
		(layer "In6.Cu")
		(net "P5E_CPU0_P2_RX_DP<2>")
	)
	(arc
		(start 362.930186 -287.045908)
		(mid 362.865671 -286.783689)
		(end 362.686854 -286.581342)
		(width 0.1143)
		(layer "In6.Cu")
		(net "P5E_CPU0_P2_RX_DP<2>")
	)
	(arc
		(start 362.460032 -287.856168)
		(mid 362.503092 -287.686113)
		(end 362.615988 -287.551876)
		(width 0.1143)
		(layer "In6.Cu")
		(net "P5E_CPU0_P2_RX_DP<2>")
	)
	(arc
		(start 362.686854 -293.990522)
		(mid 362.930181 -293.525956)
		(end 362.686854 -293.06139)
		(width 0.1143)
		(layer "In6.Cu")
		(net "P5E_CPU0_P2_RX_DP<2>")
	)
	(arc
		(start 401.714462 -382.855216)
		(mid 401.660859 -382.731031)
		(end 401.622006 -382.60147)
		(width 0.14224)
		(layer "In6.Cu")
		(net "P5E_CPU0_P2_RX_DP<2>")
	)
	(arc
		(start 362.686854 -285.890716)
		(mid 362.838841 -285.734208)
		(end 362.92028 -285.531814)
		(width 0.1143)
		(layer "In6.Cu")
		(net "P5E_CPU0_P2_RX_DP<2>")
	)
	(arc
		(start 362.61421 -286.538924)
		(mid 362.500803 -286.406035)
		(end 362.460032 -286.236156)
		(width 0.1143)
		(layer "In6.Cu")
		(net "P5E_CPU0_P2_RX_DP<2>")
	)
	(arc
		(start 363.325918 -295.711372)
		(mid 363.256047 -295.59324)
		(end 363.155992 -295.499282)
		(width 0.1143)
		(layer "In6.Cu")
		(net "P5E_CPU0_P2_RX_DP<2>")
	)
	(arc
		(start 362.686854 -290.750498)
		(mid 362.930181 -290.285932)
		(end 362.686854 -289.821366)
		(width 0.1143)
		(layer "In6.Cu")
		(net "P5E_CPU0_P2_RX_DP<2>")
	)
	(arc
		(start 392.618468 -370.4971)
		(mid 392.521721 -370.37916)
		(end 392.449812 -370.244624)
		(width 0.14224)
		(layer "In6.Cu")
		(net "P5E_CPU0_P2_RX_DP<2>")
	)
	(arc
		(start 362.643928 -294.65651)
		(mid 362.460171 -294.336072)
		(end 362.643674 -294.015414)
		(width 0.1143)
		(layer "In6.Cu")
		(net "P5E_CPU0_P2_RX_DP<2>")
	)
	(arc
		(start 362.460032 -286.236156)
		(mid 362.504103 -286.06662)
		(end 362.615988 -285.931864)
		(width 0.1143)
		(layer "In6.Cu")
		(net "P5E_CPU0_P2_RX_DP<2>")
	)
	(arc
		(start 362.686854 -292.37051)
		(mid 362.930181 -291.905944)
		(end 362.686854 -291.441378)
		(width 0.1143)
		(layer "In6.Cu")
		(net "P5E_CPU0_P2_RX_DP<2>")
	)
	(arc
		(start 362.929932 -295.145968)
		(mid 362.865273 -294.883411)
		(end 362.686092 -294.680894)
		(width 0.1143)
		(layer "In6.Cu")
		(net "P5E_CPU0_P2_RX_DP<2>")
	)
	(arc
		(start 406.568148 -390.459468)
		(mid 406.548773 -390.334536)
		(end 406.492202 -390.22147)
		(width 0.14224)
		(layer "In6.Cu")
		(net "P5E_CPU0_P2_RX_DP<2>")
	)
	(arc
		(start 362.61167 -291.396928)
		(mid 362.457366 -291.095938)
		(end 362.61167 -290.794948)
		(width 0.1143)
		(layer "In6.Cu")
		(net "P5E_CPU0_P2_RX_DP<2>")
	)
	(arc
		(start 362.673646 -289.13836)
		(mid 362.932353 -288.668843)
		(end 362.678472 -288.196782)
		(width 0.1143)
		(layer "In6.Cu")
		(net "P5E_CPU0_P2_RX_DP<2>")
	)
	(arc
		(start 362.615988 -293.020242)
		(mid 362.46006 -292.71595)
		(end 362.615988 -292.411658)
		(width 0.1143)
		(layer "In6.Cu")
		(net "P5E_CPU0_P2_RX_DP<2>")
	)
	(segment
		(start 362.837984 -283.5402)
		(end 363.304836 -283.806138)
		(width 0.12954)
		(layer "F.Cu")
		(net "P5E_CPU0_P2_RX_DP<1>")
	)
	(segment
		(start 404.498302 -394.385292)
		(end 405.019002 -394.385292)
		(width 0.127)
		(layer "F.Cu")
		(net "P5E_CPU0_P2_RX_DP<1>")
	)
	(segment
		(start 361.7087 -293.039038)
		(end 361.707684 -293.03853)
		(width 0.1143)
		(layer "In6.Cu")
		(net "P5E_CPU0_P2_RX_DP<1>")
	)
	(segment
		(start 361.739942 -286.577532)
		(end 361.704128 -286.556704)
		(width 0.1143)
		(layer "In6.Cu")
		(net "P5E_CPU0_P2_RX_DP<1>")
	)
	(segment
		(start 405.019002 -394.385292)
		(end 405.113998 -394.031216)
		(width 0.14224)
		(layer "In6.Cu")
		(net "P5E_CPU0_P2_RX_DP<1>")
	)
	(segment
		(start 374.769126 -317.388494)
		(end 373.27967 -315.15939)
		(width 0.14224)
		(layer "In6.Cu")
		(net "P5E_CPU0_P2_RX_DP<1>")
	)
	(segment
		(start 361.707938 -285.913322)
		(end 361.745276 -285.891732)
		(width 0.1143)
		(layer "In6.Cu")
		(net "P5E_CPU0_P2_RX_DP<1>")
	)
	(segment
		(start 362.177584 -295.468548)
		(end 362.147104 -295.450768)
		(width 0.1143)
		(layer "In6.Cu")
		(net "P5E_CPU0_P2_RX_DP<1>")
	)
	(segment
		(start 361.7468 -289.821366)
		(end 361.707684 -289.798506)
		(width 0.1143)
		(layer "In6.Cu")
		(net "P5E_CPU0_P2_RX_DP<1>")
	)
	(segment
		(start 362.646976 -284.294072)
		(end 362.649262 -284.292548)
		(width 0.1143)
		(layer "In6.Cu")
		(net "P5E_CPU0_P2_RX_DP<1>")
	)
	(segment
		(start 362.505752 -296.353484)
		(end 362.505752 -296.325036)
		(width 0.1143)
		(layer "In6.Cu")
		(net "P5E_CPU0_P2_RX_DP<1>")
	)
	(segment
		(start 362.649262 -284.292548)
		(end 362.686854 -284.270704)
		(width 0.1143)
		(layer "In6.Cu")
		(net "P5E_CPU0_P2_RX_DP<1>")
	)
	(segment
		(start 362.146088 -285.121858)
		(end 362.177076 -285.103824)
		(width 0.1143)
		(layer "In6.Cu")
		(net "P5E_CPU0_P2_RX_DP<1>")
	)
	(segment
		(start 384.183636 -352.790252)
		(end 382.375918 -343.702894)
		(width 0.14224)
		(layer "In6.Cu")
		(net "P5E_CPU0_P2_RX_DP<1>")
	)
	(segment
		(start 397.075914 -376.27306)
		(end 391.623804 -370.82095)
		(width 0.14224)
		(layer "In6.Cu")
		(net "P5E_CPU0_P2_RX_DP<1>")
	)
	(segment
		(start 361.7468 -294.681402)
		(end 361.707684 -294.658542)
		(width 0.1143)
		(layer "In6.Cu")
		(net "P5E_CPU0_P2_RX_DP<1>")
	)
	(segment
		(start 391.596118 -370.779548)
		(end 384.289554 -353.139756)
		(width 0.14224)
		(layer "In6.Cu")
		(net "P5E_CPU0_P2_RX_DP<1>")
	)
	(segment
		(start 361.677204 -294.031162)
		(end 361.707684 -294.013382)
		(width 0.1143)
		(layer "In6.Cu")
		(net "P5E_CPU0_P2_RX_DP<1>")
	)
	(segment
		(start 405.27605 -390.244584)
		(end 397.286226 -380.451614)
		(width 0.14224)
		(layer "In6.Cu")
		(net "P5E_CPU0_P2_RX_DP<1>")
	)
	(segment
		(start 405.063452 -392.7348)
		(end 405.368252 -392.430254)
		(width 0.14224)
		(layer "In6.Cu")
		(net "P5E_CPU0_P2_RX_DP<1>")
	)
	(segment
		(start 361.707684 -294.013382)
		(end 361.7468 -293.990522)
		(width 0.1143)
		(layer "In6.Cu")
		(net "P5E_CPU0_P2_RX_DP<1>")
	)
	(segment
		(start 361.707684 -292.39337)
		(end 361.7087 -292.392862)
		(width 0.1143)
		(layer "In6.Cu")
		(net "P5E_CPU0_P2_RX_DP<1>")
	)
	(segment
		(start 373.27967 -315.15939)
		(end 368.208814 -308.98084)
		(width 0.14224)
		(layer "In6.Cu")
		(net "P5E_CPU0_P2_RX_DP<1>")
	)
	(segment
		(start 362.460032 -296.279316)
		(end 362.460032 -295.955974)
		(width 0.1143)
		(layer "In6.Cu")
		(net "P5E_CPU0_P2_RX_DP<1>")
	)
	(segment
		(start 405.060404 -393.113006)
		(end 405.063452 -392.7348)
		(width 0.14224)
		(layer "In6.Cu")
		(net "P5E_CPU0_P2_RX_DP<1>")
	)
	(segment
		(start 397.195802 -380.197614)
		(end 397.195802 -376.56262)
		(width 0.14224)
		(layer "In6.Cu")
		(net "P5E_CPU0_P2_RX_DP<1>")
	)
	(segment
		(start 361.7468 -291.441378)
		(end 361.707684 -291.418518)
		(width 0.1143)
		(layer "In6.Cu")
		(net "P5E_CPU0_P2_RX_DP<1>")
	)
	(segment
		(start 361.710224 -293.040054)
		(end 361.7087 -293.039038)
		(width 0.1143)
		(layer "In6.Cu")
		(net "P5E_CPU0_P2_RX_DP<1>")
	)
	(segment
		(start 405.37638 -393.842494)
		(end 405.37638 -393.428982)
		(width 0.14224)
		(layer "In6.Cu")
		(net "P5E_CPU0_P2_RX_DP<1>")
	)
	(segment
		(start 405.288242 -393.930632)
		(end 405.37638 -393.842494)
		(width 0.14224)
		(layer "In6.Cu")
		(net "P5E_CPU0_P2_RX_DP<1>")
	)
	(segment
		(start 361.707684 -293.03853)
		(end 361.706922 -293.038022)
		(width 0.1143)
		(layer "In6.Cu")
		(net "P5E_CPU0_P2_RX_DP<1>")
	)
	(segment
		(start 361.706922 -293.038022)
		(end 361.675934 -293.020242)
		(width 0.1143)
		(layer "In6.Cu")
		(net "P5E_CPU0_P2_RX_DP<1>")
	)
	(segment
		(start 362.92409 -283.888942)
		(end 363.006894 -283.806138)
		(width 0.1143)
		(layer "In6.Cu")
		(net "P5E_CPU0_P2_RX_DP<1>")
	)
	(segment
		(start 379.563376 -326.361044)
		(end 374.769126 -317.388494)
		(width 0.14224)
		(layer "In6.Cu")
		(net "P5E_CPU0_P2_RX_DP<1>")
	)
	(segment
		(start 361.677204 -290.791138)
		(end 361.707684 -290.773358)
		(width 0.1143)
		(layer "In6.Cu")
		(net "P5E_CPU0_P2_RX_DP<1>")
	)
	(segment
		(start 361.707176 -285.91383)
		(end 361.707938 -285.913322)
		(width 0.1143)
		(layer "In6.Cu")
		(net "P5E_CPU0_P2_RX_DP<1>")
	)
	(segment
		(start 405.113998 -394.031216)
		(end 405.288242 -393.930632)
		(width 0.14224)
		(layer "In6.Cu")
		(net "P5E_CPU0_P2_RX_DP<1>")
	)
	(segment
		(start 361.707684 -290.773358)
		(end 361.7468 -290.750498)
		(width 0.1143)
		(layer "In6.Cu")
		(net "P5E_CPU0_P2_RX_DP<1>")
	)
	(segment
		(start 381.750062 -337.355434)
		(end 379.563376 -326.361044)
		(width 0.14224)
		(layer "In6.Cu")
		(net "P5E_CPU0_P2_RX_DP<1>")
	)
	(segment
		(start 361.707684 -294.658542)
		(end 361.677204 -294.640762)
		(width 0.1143)
		(layer "In6.Cu")
		(net "P5E_CPU0_P2_RX_DP<1>")
	)
	(segment
		(start 362.2167 -295.491408)
		(end 362.177584 -295.468548)
		(width 0.1143)
		(layer "In6.Cu")
		(net "P5E_CPU0_P2_RX_DP<1>")
	)
	(segment
		(start 361.675934 -292.411658)
		(end 361.706922 -292.393878)
		(width 0.1143)
		(layer "In6.Cu")
		(net "P5E_CPU0_P2_RX_DP<1>")
	)
	(segment
		(start 382.37414 -343.690702)
		(end 381.750062 -337.355434)
		(width 0.14224)
		(layer "In6.Cu")
		(net "P5E_CPU0_P2_RX_DP<1>")
	)
	(segment
		(start 361.7468 -286.581342)
		(end 361.739942 -286.577532)
		(width 0.1143)
		(layer "In6.Cu")
		(net "P5E_CPU0_P2_RX_DP<1>")
	)
	(segment
		(start 405.368252 -392.430254)
		(end 405.368252 -390.503156)
		(width 0.14224)
		(layer "In6.Cu")
		(net "P5E_CPU0_P2_RX_DP<1>")
	)
	(segment
		(start 361.706922 -292.393878)
		(end 361.707684 -292.39337)
		(width 0.1143)
		(layer "In6.Cu")
		(net "P5E_CPU0_P2_RX_DP<1>")
	)
	(segment
		(start 364.305342 -303.13884)
		(end 362.505752 -298.79417)
		(width 0.14224)
		(layer "In6.Cu")
		(net "P5E_CPU0_P2_RX_DP<1>")
	)
	(segment
		(start 361.7087 -292.392862)
		(end 361.710224 -292.391846)
		(width 0.1143)
		(layer "In6.Cu")
		(net "P5E_CPU0_P2_RX_DP<1>")
	)
	(segment
		(start 362.624116 -284.30728)
		(end 362.646976 -284.294072)
		(width 0.1143)
		(layer "In6.Cu")
		(net "P5E_CPU0_P2_RX_DP<1>")
	)
	(segment
		(start 361.707684 -289.153346)
		(end 361.712256 -289.150806)
		(width 0.1143)
		(layer "In6.Cu")
		(net "P5E_CPU0_P2_RX_DP<1>")
	)
	(segment
		(start 363.006894 -283.806138)
		(end 363.304836 -283.806138)
		(width 0.1143)
		(layer "In6.Cu")
		(net "P5E_CPU0_P2_RX_DP<1>")
	)
	(segment
		(start 361.7468 -293.06139)
		(end 361.710224 -293.040054)
		(width 0.1143)
		(layer "In6.Cu")
		(net "P5E_CPU0_P2_RX_DP<1>")
	)
	(segment
		(start 362.177076 -285.103824)
		(end 362.216192 -285.081472)
		(width 0.1143)
		(layer "In6.Cu")
		(net "P5E_CPU0_P2_RX_DP<1>")
	)
	(segment
		(start 361.707684 -291.418518)
		(end 361.677204 -291.400738)
		(width 0.1143)
		(layer "In6.Cu")
		(net "P5E_CPU0_P2_RX_DP<1>")
	)
	(segment
		(start 361.712256 -288.181034)
		(end 361.675172 -288.159698)
		(width 0.1143)
		(layer "In6.Cu")
		(net "P5E_CPU0_P2_RX_DP<1>")
	)
	(segment
		(start 361.671616 -292.41496)
		(end 361.675934 -292.411658)
		(width 0.1143)
		(layer "In6.Cu")
		(net "P5E_CPU0_P2_RX_DP<1>")
	)
	(segment
		(start 361.703874 -285.915608)
		(end 361.707176 -285.91383)
		(width 0.1143)
		(layer "In6.Cu")
		(net "P5E_CPU0_P2_RX_DP<1>")
	)
	(segment
		(start 362.505752 -296.325036)
		(end 362.460032 -296.279316)
		(width 0.1143)
		(layer "In6.Cu")
		(net "P5E_CPU0_P2_RX_DP<1>")
	)
	(segment
		(start 361.707684 -289.798506)
		(end 361.677204 -289.780726)
		(width 0.1143)
		(layer "In6.Cu")
		(net "P5E_CPU0_P2_RX_DP<1>")
	)
	(segment
		(start 368.208814 -308.98084)
		(end 364.305342 -303.13884)
		(width 0.14224)
		(layer "In6.Cu")
		(net "P5E_CPU0_P2_RX_DP<1>")
	)
	(segment
		(start 361.677204 -287.551368)
		(end 361.74426 -287.512252)
		(width 0.1143)
		(layer "In6.Cu")
		(net "P5E_CPU0_P2_RX_DP<1>")
	)
	(segment
		(start 361.677204 -289.171126)
		(end 361.707684 -289.153346)
		(width 0.1143)
		(layer "In6.Cu")
		(net "P5E_CPU0_P2_RX_DP<1>")
	)
	(segment
		(start 361.675934 -293.020242)
		(end 361.671616 -293.01694)
		(width 0.1143)
		(layer "In6.Cu")
		(net "P5E_CPU0_P2_RX_DP<1>")
	)
	(segment
		(start 405.37638 -393.428982)
		(end 405.060404 -393.113006)
		(width 0.14224)
		(layer "In6.Cu")
		(net "P5E_CPU0_P2_RX_DP<1>")
	)
	(segment
		(start 362.505752 -298.79417)
		(end 362.505752 -296.353484)
		(width 0.14224)
		(layer "In6.Cu")
		(net "P5E_CPU0_P2_RX_DP<1>")
	)
	(segment
		(start 361.710224 -292.391846)
		(end 361.7468 -292.37051)
		(width 0.1143)
		(layer "In6.Cu")
		(net "P5E_CPU0_P2_RX_DP<1>")
	)
	(arc
		(start 361.704128 -286.556704)
		(mid 361.520371 -286.236266)
		(end 361.703874 -285.915608)
		(width 0.1143)
		(layer "In6.Cu")
		(net "P5E_CPU0_P2_RX_DP<1>")
	)
	(arc
		(start 361.677204 -294.640762)
		(mid 361.520227 -294.335962)
		(end 361.677204 -294.031162)
		(width 0.1143)
		(layer "In6.Cu")
		(net "P5E_CPU0_P2_RX_DP<1>")
	)
	(arc
		(start 361.7468 -290.750498)
		(mid 361.990127 -290.285932)
		(end 361.7468 -289.821366)
		(width 0.1143)
		(layer "In6.Cu")
		(net "P5E_CPU0_P2_RX_DP<1>")
	)
	(arc
		(start 362.460286 -284.633162)
		(mid 362.460668 -284.619679)
		(end 362.46181 -284.606238)
		(width 0.1143)
		(layer "In6.Cu")
		(net "P5E_CPU0_P2_RX_DP<1>")
	)
	(arc
		(start 384.289554 -353.139756)
		(mid 384.228018 -352.967604)
		(end 384.183636 -352.790252)
		(width 0.14224)
		(layer "In6.Cu")
		(net "P5E_CPU0_P2_RX_DP<1>")
	)
	(arc
		(start 362.686854 -284.270704)
		(mid 362.838841 -284.114196)
		(end 362.92028 -283.911802)
		(width 0.1143)
		(layer "In6.Cu")
		(net "P5E_CPU0_P2_RX_DP<1>")
	)
	(arc
		(start 361.7468 -293.990522)
		(mid 361.990127 -293.525956)
		(end 361.7468 -293.06139)
		(width 0.1143)
		(layer "In6.Cu")
		(net "P5E_CPU0_P2_RX_DP<1>")
	)
	(arc
		(start 361.677204 -289.780726)
		(mid 361.520227 -289.475926)
		(end 361.677204 -289.171126)
		(width 0.1143)
		(layer "In6.Cu")
		(net "P5E_CPU0_P2_RX_DP<1>")
	)
	(arc
		(start 397.195802 -376.56262)
		(mid 397.16465 -376.405917)
		(end 397.075914 -376.27306)
		(width 0.14224)
		(layer "In6.Cu")
		(net "P5E_CPU0_P2_RX_DP<1>")
	)
	(arc
		(start 382.375918 -343.702894)
		(mid 382.374882 -343.696819)
		(end 382.37414 -343.690702)
		(width 0.14224)
		(layer "In6.Cu")
		(net "P5E_CPU0_P2_RX_DP<1>")
	)
	(arc
		(start 361.7468 -292.37051)
		(mid 361.990127 -291.905944)
		(end 361.7468 -291.441378)
		(width 0.1143)
		(layer "In6.Cu")
		(net "P5E_CPU0_P2_RX_DP<1>")
	)
	(arc
		(start 362.46181 -284.606238)
		(mid 362.508155 -284.455774)
		(end 362.601002 -284.328616)
		(width 0.1143)
		(layer "In6.Cu")
		(net "P5E_CPU0_P2_RX_DP<1>")
	)
	(arc
		(start 391.623804 -370.82095)
		(mid 391.607933 -370.801607)
		(end 391.596118 -370.779548)
		(width 0.14224)
		(layer "In6.Cu")
		(net "P5E_CPU0_P2_RX_DP<1>")
	)
	(arc
		(start 397.286226 -380.451614)
		(mid 397.219062 -380.332426)
		(end 397.195802 -380.197614)
		(width 0.14224)
		(layer "In6.Cu")
		(net "P5E_CPU0_P2_RX_DP<1>")
	)
	(arc
		(start 361.520232 -287.856168)
		(mid 361.561781 -287.684746)
		(end 361.677204 -287.551368)
		(width 0.1143)
		(layer "In6.Cu")
		(net "P5E_CPU0_P2_RX_DP<1>")
	)
	(arc
		(start 361.990132 -287.045908)
		(mid 361.925617 -286.783689)
		(end 361.7468 -286.581342)
		(width 0.1143)
		(layer "In6.Cu")
		(net "P5E_CPU0_P2_RX_DP<1>")
	)
	(arc
		(start 361.677204 -291.400738)
		(mid 361.520227 -291.095938)
		(end 361.677204 -290.791138)
		(width 0.1143)
		(layer "In6.Cu")
		(net "P5E_CPU0_P2_RX_DP<1>")
	)
	(arc
		(start 361.990132 -295.145968)
		(mid 361.925617 -294.883749)
		(end 361.7468 -294.681402)
		(width 0.1143)
		(layer "In6.Cu")
		(net "P5E_CPU0_P2_RX_DP<1>")
	)
	(arc
		(start 361.671616 -293.01694)
		(mid 361.517312 -292.71595)
		(end 361.671616 -292.41496)
		(width 0.1143)
		(layer "In6.Cu")
		(net "P5E_CPU0_P2_RX_DP<1>")
	)
	(arc
		(start 361.675172 -288.159698)
		(mid 361.561243 -288.026551)
		(end 361.520232 -287.856168)
		(width 0.1143)
		(layer "In6.Cu")
		(net "P5E_CPU0_P2_RX_DP<1>")
	)
	(arc
		(start 362.216192 -285.081472)
		(mid 362.391693 -284.886418)
		(end 362.460286 -284.633162)
		(width 0.1143)
		(layer "In6.Cu")
		(net "P5E_CPU0_P2_RX_DP<1>")
	)
	(arc
		(start 361.990132 -285.42615)
		(mid 362.031387 -285.255179)
		(end 362.146088 -285.121858)
		(width 0.1143)
		(layer "In6.Cu")
		(net "P5E_CPU0_P2_RX_DP<1>")
	)
	(arc
		(start 362.460032 -295.955974)
		(mid 362.395591 -295.693703)
		(end 362.2167 -295.491408)
		(width 0.1143)
		(layer "In6.Cu")
		(net "P5E_CPU0_P2_RX_DP<1>")
	)
	(arc
		(start 361.74426 -287.512252)
		(mid 361.924912 -287.309507)
		(end 361.990132 -287.045908)
		(width 0.1143)
		(layer "In6.Cu")
		(net "P5E_CPU0_P2_RX_DP<1>")
	)
	(arc
		(start 362.601002 -284.328616)
		(mid 362.612381 -284.317755)
		(end 362.624116 -284.30728)
		(width 0.1143)
		(layer "In6.Cu")
		(net "P5E_CPU0_P2_RX_DP<1>")
	)
	(arc
		(start 362.92028 -283.911802)
		(mid 362.922303 -283.900392)
		(end 362.92409 -283.888942)
		(width 0.1143)
		(layer "In6.Cu")
		(net "P5E_CPU0_P2_RX_DP<1>")
	)
	(arc
		(start 362.147104 -295.450768)
		(mid 362.031677 -295.317392)
		(end 361.990132 -295.145968)
		(width 0.1143)
		(layer "In6.Cu")
		(net "P5E_CPU0_P2_RX_DP<1>")
	)
	(arc
		(start 361.7468 -285.890716)
		(mid 361.925613 -285.688366)
		(end 361.990132 -285.42615)
		(width 0.1143)
		(layer "In6.Cu")
		(net "P5E_CPU0_P2_RX_DP<1>")
	)
	(arc
		(start 405.368252 -390.503156)
		(mid 405.344462 -390.365918)
		(end 405.27605 -390.244584)
		(width 0.14224)
		(layer "In6.Cu")
		(net "P5E_CPU0_P2_RX_DP<1>")
	)
	(arc
		(start 361.745276 -285.891732)
		(mid 361.746038 -285.891225)
		(end 361.7468 -285.890716)
		(width 0.1143)
		(layer "In6.Cu")
		(net "P5E_CPU0_P2_RX_DP<1>")
	)
	(arc
		(start 361.712256 -289.150806)
		(mid 361.990456 -288.66592)
		(end 361.712256 -288.181034)
		(width 0.1143)
		(layer "In6.Cu")
		(net "P5E_CPU0_P2_RX_DP<1>")
	)
	(segment
		(start 421.29837 -394.385292)
		(end 421.81907 -394.385292)
		(width 0.127)
		(layer "F.Cu")
		(net "P5E_CPU0_P2_RX_DP<15>")
	)
	(segment
		(start 373.64797 -282.730194)
		(end 374.114822 -282.996132)
		(width 0.12954)
		(layer "F.Cu")
		(net "P5E_CPU0_P2_RX_DP<15>")
	)
	(segment
		(start 374.906794 -291.441378)
		(end 374.837198 -291.400738)
		(width 0.1143)
		(layer "In6.Cu")
		(net "P5E_CPU0_P2_RX_DP<15>")
	)
	(segment
		(start 373.81688 -282.996132)
		(end 374.114822 -282.996132)
		(width 0.1143)
		(layer "In6.Cu")
		(net "P5E_CPU0_P2_RX_DP<15>")
	)
	(segment
		(start 375.34469 -295.472612)
		(end 375.336308 -295.467786)
		(width 0.1143)
		(layer "In6.Cu")
		(net "P5E_CPU0_P2_RX_DP<15>")
	)
	(segment
		(start 375.818908 -296.604182)
		(end 375.8184 -296.603674)
		(width 0.1143)
		(layer "In6.Cu")
		(net "P5E_CPU0_P2_RX_DP<15>")
	)
	(segment
		(start 374.837198 -287.551368)
		(end 374.904254 -287.512252)
		(width 0.1143)
		(layer "In6.Cu")
		(net "P5E_CPU0_P2_RX_DP<15>")
	)
	(segment
		(start 374.837198 -294.031162)
		(end 374.906794 -293.990522)
		(width 0.1143)
		(layer "In6.Cu")
		(net "P5E_CPU0_P2_RX_DP<15>")
	)
	(segment
		(start 375.330466 -295.464484)
		(end 375.329196 -295.463722)
		(width 0.1143)
		(layer "In6.Cu")
		(net "P5E_CPU0_P2_RX_DP<15>")
	)
	(segment
		(start 375.8184 -296.575734)
		(end 375.77268 -296.530014)
		(width 0.1143)
		(layer "In6.Cu")
		(net "P5E_CPU0_P2_RX_DP<15>")
	)
	(segment
		(start 424.23715 -388.710932)
		(end 425.424854 -384.584448)
		(width 0.14224)
		(layer "In6.Cu")
		(net "P5E_CPU0_P2_RX_DP<15>")
	)
	(segment
		(start 374.430036 -284.147514)
		(end 374.429274 -284.147006)
		(width 0.1143)
		(layer "In6.Cu")
		(net "P5E_CPU0_P2_RX_DP<15>")
	)
	(segment
		(start 421.914066 -394.031216)
		(end 422.08831 -393.930632)
		(width 0.14224)
		(layer "In6.Cu")
		(net "P5E_CPU0_P2_RX_DP<15>")
	)
	(segment
		(start 403.259036 -363.281214)
		(end 396.706344 -347.461332)
		(width 0.14224)
		(layer "In6.Cu")
		(net "P5E_CPU0_P2_RX_DP<15>")
	)
	(segment
		(start 374.404636 -284.132782)
		(end 374.397016 -284.12821)
		(width 0.1143)
		(layer "In6.Cu")
		(net "P5E_CPU0_P2_RX_DP<15>")
	)
	(segment
		(start 425.424854 -384.584448)
		(end 426.897292 -381.029464)
		(width 0.14224)
		(layer "In6.Cu")
		(net "P5E_CPU0_P2_RX_DP<15>")
	)
	(segment
		(start 403.658578 -363.694726)
		(end 403.658578 -363.694472)
		(width 0.14224)
		(layer "In6.Cu")
		(net "P5E_CPU0_P2_RX_DP<15>")
	)
	(segment
		(start 374.906794 -289.821366)
		(end 374.837198 -289.780726)
		(width 0.1143)
		(layer "In6.Cu")
		(net "P5E_CPU0_P2_RX_DP<15>")
	)
	(segment
		(start 392.3919 -322.074286)
		(end 386.08508 -310.275732)
		(width 0.14224)
		(layer "In6.Cu")
		(net "P5E_CPU0_P2_RX_DP<15>")
	)
	(segment
		(start 422.176448 -393.842494)
		(end 422.176448 -393.3698)
		(width 0.14224)
		(layer "In6.Cu")
		(net "P5E_CPU0_P2_RX_DP<15>")
	)
	(segment
		(start 428.38243 -377.541028)
		(end 428.382176 -377.54052)
		(width 0.14224)
		(layer "In6.Cu")
		(net "P5E_CPU0_P2_RX_DP<15>")
	)
	(segment
		(start 396.698978 -347.43771)
		(end 395.503908 -341.429086)
		(width 0.14224)
		(layer "In6.Cu")
		(net "P5E_CPU0_P2_RX_DP<15>")
	)
	(segment
		(start 375.818908 -296.710862)
		(end 375.818908 -296.604182)
		(width 0.14224)
		(layer "In6.Cu")
		(net "P5E_CPU0_P2_RX_DP<15>")
	)
	(segment
		(start 374.906794 -294.681402)
		(end 374.837198 -294.640762)
		(width 0.1143)
		(layer "In6.Cu")
		(net "P5E_CPU0_P2_RX_DP<15>")
	)
	(segment
		(start 375.335546 -295.467278)
		(end 375.33453 -295.46677)
		(width 0.1143)
		(layer "In6.Cu")
		(net "P5E_CPU0_P2_RX_DP<15>")
	)
	(segment
		(start 375.33453 -295.46677)
		(end 375.333768 -295.466262)
		(width 0.1143)
		(layer "In6.Cu")
		(net "P5E_CPU0_P2_RX_DP<15>")
	)
	(segment
		(start 427.389544 -374.906794)
		(end 425.538138 -373.108728)
		(width 0.14224)
		(layer "In6.Cu")
		(net "P5E_CPU0_P2_RX_DP<15>")
	)
	(segment
		(start 423.428922 -392.029188)
		(end 423.77233 -391.457434)
		(width 0.14224)
		(layer "In6.Cu")
		(net "P5E_CPU0_P2_RX_DP<15>")
	)
	(segment
		(start 375.952258 -297.03268)
		(end 375.818908 -296.710862)
		(width 0.14224)
		(layer "In6.Cu")
		(net "P5E_CPU0_P2_RX_DP<15>")
	)
	(segment
		(start 422.176448 -393.3698)
		(end 423.428922 -392.029188)
		(width 0.14224)
		(layer "In6.Cu")
		(net "P5E_CPU0_P2_RX_DP<15>")
	)
	(segment
		(start 375.324878 -295.461436)
		(end 375.306082 -295.45026)
		(width 0.1143)
		(layer "In6.Cu")
		(net "P5E_CPU0_P2_RX_DP<15>")
	)
	(segment
		(start 375.366026 -285.768542)
		(end 375.30278 -285.727902)
		(width 0.1143)
		(layer "In6.Cu")
		(net "P5E_CPU0_P2_RX_DP<15>")
	)
	(segment
		(start 374.429274 -284.147006)
		(end 374.404636 -284.132782)
		(width 0.1143)
		(layer "In6.Cu")
		(net "P5E_CPU0_P2_RX_DP<15>")
	)
	(segment
		(start 375.327164 -295.462706)
		(end 375.324878 -295.461436)
		(width 0.1143)
		(layer "In6.Cu")
		(net "P5E_CPU0_P2_RX_DP<15>")
	)
	(segment
		(start 374.436894 -284.151578)
		(end 374.430036 -284.147514)
		(width 0.1143)
		(layer "In6.Cu")
		(net "P5E_CPU0_P2_RX_DP<15>")
	)
	(segment
		(start 374.837198 -289.171126)
		(end 374.906794 -289.130486)
		(width 0.1143)
		(layer "In6.Cu")
		(net "P5E_CPU0_P2_RX_DP<15>")
	)
	(segment
		(start 421.757856 -370.943886)
		(end 415.98088 -368.976656)
		(width 0.14224)
		(layer "In6.Cu")
		(net "P5E_CPU0_P2_RX_DP<15>")
	)
	(segment
		(start 428.387764 -379.355858)
		(end 428.387764 -377.585478)
		(width 0.14224)
		(layer "In6.Cu")
		(net "P5E_CPU0_P2_RX_DP<15>")
	)
	(segment
		(start 374.906794 -284.961584)
		(end 374.837198 -284.920944)
		(width 0.1143)
		(layer "In6.Cu")
		(net "P5E_CPU0_P2_RX_DP<15>")
	)
	(segment
		(start 373.74703 -283.065982)
		(end 373.81688 -282.996132)
		(width 0.1143)
		(layer "In6.Cu")
		(net "P5E_CPU0_P2_RX_DP<15>")
	)
	(segment
		(start 375.498868 -295.62933)
		(end 375.345198 -295.472866)
		(width 0.1143)
		(layer "In6.Cu")
		(net "P5E_CPU0_P2_RX_DP<15>")
	)
	(segment
		(start 428.387764 -377.585478)
		(end 428.383954 -377.562364)
		(width 0.14224)
		(layer "In6.Cu")
		(net "P5E_CPU0_P2_RX_DP<15>")
	)
	(segment
		(start 375.304304 -286.74314)
		(end 375.34596 -286.718756)
		(width 0.1143)
		(layer "In6.Cu")
		(net "P5E_CPU0_P2_RX_DP<15>")
	)
	(segment
		(start 375.333768 -295.466262)
		(end 375.331228 -295.464992)
		(width 0.1143)
		(layer "In6.Cu")
		(net "P5E_CPU0_P2_RX_DP<15>")
	)
	(segment
		(start 428.382176 -377.54052)
		(end 428.382176 -377.300998)
		(width 0.14224)
		(layer "In6.Cu")
		(net "P5E_CPU0_P2_RX_DP<15>")
	)
	(segment
		(start 378.052584 -300.175676)
		(end 375.952258 -297.03268)
		(width 0.14224)
		(layer "In6.Cu")
		(net "P5E_CPU0_P2_RX_DP<15>")
	)
	(segment
		(start 374.837198 -290.791138)
		(end 374.906794 -290.750498)
		(width 0.1143)
		(layer "In6.Cu")
		(net "P5E_CPU0_P2_RX_DP<15>")
	)
	(segment
		(start 421.81907 -394.385292)
		(end 421.914066 -394.031216)
		(width 0.14224)
		(layer "In6.Cu")
		(net "P5E_CPU0_P2_RX_DP<15>")
	)
	(segment
		(start 395.50213 -341.416894)
		(end 395.026388 -336.590386)
		(width 0.14224)
		(layer "In6.Cu")
		(net "P5E_CPU0_P2_RX_DP<15>")
	)
	(segment
		(start 374.906794 -293.06139)
		(end 374.837198 -293.02075)
		(width 0.1143)
		(layer "In6.Cu")
		(net "P5E_CPU0_P2_RX_DP<15>")
	)
	(segment
		(start 374.837198 -292.41115)
		(end 374.906794 -292.37051)
		(width 0.1143)
		(layer "In6.Cu")
		(net "P5E_CPU0_P2_RX_DP<15>")
	)
	(segment
		(start 375.329196 -295.463722)
		(end 375.327164 -295.462706)
		(width 0.1143)
		(layer "In6.Cu")
		(net "P5E_CPU0_P2_RX_DP<15>")
	)
	(segment
		(start 373.9642 -283.339794)
		(end 373.896128 -283.300424)
		(width 0.1143)
		(layer "In6.Cu")
		(net "P5E_CPU0_P2_RX_DP<15>")
	)
	(segment
		(start 375.8184 -296.603674)
		(end 375.8184 -296.575734)
		(width 0.1143)
		(layer "In6.Cu")
		(net "P5E_CPU0_P2_RX_DP<15>")
	)
	(segment
		(start 403.658578 -363.694472)
		(end 403.286722 -363.322616)
		(width 0.14224)
		(layer "In6.Cu")
		(net "P5E_CPU0_P2_RX_DP<15>")
	)
	(segment
		(start 415.98088 -368.976656)
		(end 410.580078 -367.622582)
		(width 0.14224)
		(layer "In6.Cu")
		(net "P5E_CPU0_P2_RX_DP<15>")
	)
	(segment
		(start 426.924978 -380.988062)
		(end 428.267876 -379.645164)
		(width 0.14224)
		(layer "In6.Cu")
		(net "P5E_CPU0_P2_RX_DP<15>")
	)
	(segment
		(start 425.538138 -373.108728)
		(end 421.757856 -370.943886)
		(width 0.14224)
		(layer "In6.Cu")
		(net "P5E_CPU0_P2_RX_DP<15>")
	)
	(segment
		(start 375.345198 -295.472866)
		(end 375.34469 -295.472612)
		(width 0.1143)
		(layer "In6.Cu")
		(net "P5E_CPU0_P2_RX_DP<15>")
	)
	(segment
		(start 410.580078 -367.622582)
		(end 403.685756 -363.7153)
		(width 0.14224)
		(layer "In6.Cu")
		(net "P5E_CPU0_P2_RX_DP<15>")
	)
	(segment
		(start 375.77268 -296.530014)
		(end 375.77268 -296.446194)
		(width 0.1143)
		(layer "In6.Cu")
		(net "P5E_CPU0_P2_RX_DP<15>")
	)
	(segment
		(start 374.906794 -288.201354)
		(end 374.835166 -288.159698)
		(width 0.1143)
		(layer "In6.Cu")
		(net "P5E_CPU0_P2_RX_DP<15>")
	)
	(segment
		(start 423.77233 -391.457434)
		(end 424.23715 -388.710932)
		(width 0.14224)
		(layer "In6.Cu")
		(net "P5E_CPU0_P2_RX_DP<15>")
	)
	(segment
		(start 375.336308 -295.467786)
		(end 375.335546 -295.467278)
		(width 0.1143)
		(layer "In6.Cu")
		(net "P5E_CPU0_P2_RX_DP<15>")
	)
	(segment
		(start 384.958844 -308.590442)
		(end 378.052584 -300.175676)
		(width 0.14224)
		(layer "In6.Cu")
		(net "P5E_CPU0_P2_RX_DP<15>")
	)
	(segment
		(start 375.331228 -295.464992)
		(end 375.330466 -295.464484)
		(width 0.1143)
		(layer "In6.Cu")
		(net "P5E_CPU0_P2_RX_DP<15>")
	)
	(segment
		(start 386.08508 -310.275732)
		(end 384.958844 -308.590442)
		(width 0.14224)
		(layer "In6.Cu")
		(net "P5E_CPU0_P2_RX_DP<15>")
	)
	(segment
		(start 374.397016 -284.12821)
		(end 374.366028 -284.11043)
		(width 0.1143)
		(layer "In6.Cu")
		(net "P5E_CPU0_P2_RX_DP<15>")
	)
	(segment
		(start 422.08831 -393.930632)
		(end 422.176448 -393.842494)
		(width 0.14224)
		(layer "In6.Cu")
		(net "P5E_CPU0_P2_RX_DP<15>")
	)
	(segment
		(start 395.026388 -336.590386)
		(end 392.3919 -322.074286)
		(width 0.14224)
		(layer "In6.Cu")
		(net "P5E_CPU0_P2_RX_DP<15>")
	)
	(arc
		(start 374.906794 -290.750498)
		(mid 375.150121 -290.285932)
		(end 374.906794 -289.821366)
		(width 0.1143)
		(layer "In6.Cu")
		(net "P5E_CPU0_P2_RX_DP<15>")
	)
	(arc
		(start 374.837198 -293.02075)
		(mid 374.680221 -292.71595)
		(end 374.837198 -292.41115)
		(width 0.1143)
		(layer "In6.Cu")
		(net "P5E_CPU0_P2_RX_DP<15>")
	)
	(arc
		(start 374.680226 -284.616144)
		(mid 374.615711 -284.353925)
		(end 374.436894 -284.151578)
		(width 0.1143)
		(layer "In6.Cu")
		(net "P5E_CPU0_P2_RX_DP<15>")
	)
	(arc
		(start 403.286722 -363.322616)
		(mid 403.270851 -363.303273)
		(end 403.259036 -363.281214)
		(width 0.14224)
		(layer "In6.Cu")
		(net "P5E_CPU0_P2_RX_DP<15>")
	)
	(arc
		(start 396.706344 -347.461332)
		(mid 396.702072 -347.449704)
		(end 396.698978 -347.43771)
		(width 0.14224)
		(layer "In6.Cu")
		(net "P5E_CPU0_P2_RX_DP<15>")
	)
	(arc
		(start 374.906794 -292.37051)
		(mid 375.150121 -291.905944)
		(end 374.906794 -291.441378)
		(width 0.1143)
		(layer "In6.Cu")
		(net "P5E_CPU0_P2_RX_DP<15>")
	)
	(arc
		(start 375.30278 -285.727902)
		(mid 375.190486 -285.595226)
		(end 375.150126 -285.42615)
		(width 0.1143)
		(layer "In6.Cu")
		(net "P5E_CPU0_P2_RX_DP<15>")
	)
	(arc
		(start 374.837198 -291.400738)
		(mid 374.680221 -291.095938)
		(end 374.837198 -290.791138)
		(width 0.1143)
		(layer "In6.Cu")
		(net "P5E_CPU0_P2_RX_DP<15>")
	)
	(arc
		(start 374.837198 -289.780726)
		(mid 374.680221 -289.475926)
		(end 374.837198 -289.171126)
		(width 0.1143)
		(layer "In6.Cu")
		(net "P5E_CPU0_P2_RX_DP<15>")
	)
	(arc
		(start 375.616724 -286.17291)
		(mid 375.536888 -285.942524)
		(end 375.366026 -285.768542)
		(width 0.1143)
		(layer "In6.Cu")
		(net "P5E_CPU0_P2_RX_DP<15>")
	)
	(arc
		(start 374.906794 -289.130486)
		(mid 375.150121 -288.66592)
		(end 374.906794 -288.201354)
		(width 0.1143)
		(layer "In6.Cu")
		(net "P5E_CPU0_P2_RX_DP<15>")
	)
	(arc
		(start 374.904254 -287.512252)
		(mid 375.084906 -287.309507)
		(end 375.150126 -287.045908)
		(width 0.1143)
		(layer "In6.Cu")
		(net "P5E_CPU0_P2_RX_DP<15>")
	)
	(arc
		(start 375.150126 -287.045908)
		(mid 375.190888 -286.876024)
		(end 375.304304 -286.74314)
		(width 0.1143)
		(layer "In6.Cu")
		(net "P5E_CPU0_P2_RX_DP<15>")
	)
	(arc
		(start 375.605548 -295.774618)
		(mid 375.557409 -295.698155)
		(end 375.498868 -295.62933)
		(width 0.1143)
		(layer "In6.Cu")
		(net "P5E_CPU0_P2_RX_DP<15>")
	)
	(arc
		(start 375.306082 -295.45026)
		(mid 375.191406 -295.316926)
		(end 375.150126 -295.145968)
		(width 0.1143)
		(layer "In6.Cu")
		(net "P5E_CPU0_P2_RX_DP<15>")
	)
	(arc
		(start 374.680226 -287.856168)
		(mid 374.721775 -287.684746)
		(end 374.837198 -287.551368)
		(width 0.1143)
		(layer "In6.Cu")
		(net "P5E_CPU0_P2_RX_DP<15>")
	)
	(arc
		(start 428.383954 -377.562364)
		(mid 428.382746 -377.551728)
		(end 428.38243 -377.541028)
		(width 0.14224)
		(layer "In6.Cu")
		(net "P5E_CPU0_P2_RX_DP<15>")
	)
	(arc
		(start 375.482612 -286.605726)
		(mid 375.594918 -286.403345)
		(end 375.616724 -286.17291)
		(width 0.1143)
		(layer "In6.Cu")
		(net "P5E_CPU0_P2_RX_DP<15>")
	)
	(arc
		(start 426.897292 -381.029464)
		(mid 426.909083 -381.007389)
		(end 426.924978 -380.988062)
		(width 0.14224)
		(layer "In6.Cu")
		(net "P5E_CPU0_P2_RX_DP<15>")
	)
	(arc
		(start 374.210072 -283.812742)
		(mid 374.209862 -283.804606)
		(end 374.20931 -283.796486)
		(width 0.1143)
		(layer "In6.Cu")
		(net "P5E_CPU0_P2_RX_DP<15>")
	)
	(arc
		(start 374.206008 -283.769054)
		(mid 374.125098 -283.531893)
		(end 373.9642 -283.339794)
		(width 0.1143)
		(layer "In6.Cu")
		(net "P5E_CPU0_P2_RX_DP<15>")
	)
	(arc
		(start 375.150126 -295.145968)
		(mid 375.085611 -294.883749)
		(end 374.906794 -294.681402)
		(width 0.1143)
		(layer "In6.Cu")
		(net "P5E_CPU0_P2_RX_DP<15>")
	)
	(arc
		(start 374.835166 -288.159698)
		(mid 374.721237 -288.026551)
		(end 374.680226 -287.856168)
		(width 0.1143)
		(layer "In6.Cu")
		(net "P5E_CPU0_P2_RX_DP<15>")
	)
	(arc
		(start 374.837198 -284.920944)
		(mid 374.721771 -284.787568)
		(end 374.680226 -284.616144)
		(width 0.1143)
		(layer "In6.Cu")
		(net "P5E_CPU0_P2_RX_DP<15>")
	)
	(arc
		(start 374.366028 -284.11043)
		(mid 374.25287 -283.980028)
		(end 374.210072 -283.812742)
		(width 0.1143)
		(layer "In6.Cu")
		(net "P5E_CPU0_P2_RX_DP<15>")
	)
	(arc
		(start 374.20931 -283.796486)
		(mid 374.207797 -283.782753)
		(end 374.206008 -283.769054)
		(width 0.1143)
		(layer "In6.Cu")
		(net "P5E_CPU0_P2_RX_DP<15>")
	)
	(arc
		(start 375.77268 -296.446194)
		(mid 375.730374 -296.100134)
		(end 375.605548 -295.774618)
		(width 0.1143)
		(layer "In6.Cu")
		(net "P5E_CPU0_P2_RX_DP<15>")
	)
	(arc
		(start 395.503908 -341.429086)
		(mid 395.502874 -341.423011)
		(end 395.50213 -341.416894)
		(width 0.14224)
		(layer "In6.Cu")
		(net "P5E_CPU0_P2_RX_DP<15>")
	)
	(arc
		(start 374.906794 -293.990522)
		(mid 375.150121 -293.525956)
		(end 374.906794 -293.06139)
		(width 0.1143)
		(layer "In6.Cu")
		(net "P5E_CPU0_P2_RX_DP<15>")
	)
	(arc
		(start 375.34596 -286.718756)
		(mid 375.418969 -286.667903)
		(end 375.482612 -286.605726)
		(width 0.1143)
		(layer "In6.Cu")
		(net "P5E_CPU0_P2_RX_DP<15>")
	)
	(arc
		(start 403.685756 -363.7153)
		(mid 403.671476 -363.705926)
		(end 403.658578 -363.694726)
		(width 0.14224)
		(layer "In6.Cu")
		(net "P5E_CPU0_P2_RX_DP<15>")
	)
	(arc
		(start 375.150126 -285.42615)
		(mid 375.085611 -285.163931)
		(end 374.906794 -284.961584)
		(width 0.1143)
		(layer "In6.Cu")
		(net "P5E_CPU0_P2_RX_DP<15>")
	)
	(arc
		(start 373.896128 -283.300424)
		(mid 373.798993 -283.197555)
		(end 373.74703 -283.065982)
		(width 0.1143)
		(layer "In6.Cu")
		(net "P5E_CPU0_P2_RX_DP<15>")
	)
	(arc
		(start 428.382176 -377.300998)
		(mid 428.124188 -376.005083)
		(end 427.389544 -374.906794)
		(width 0.14224)
		(layer "In6.Cu")
		(net "P5E_CPU0_P2_RX_DP<15>")
	)
	(arc
		(start 428.267876 -379.645164)
		(mid 428.35662 -379.512444)
		(end 428.387764 -379.355858)
		(width 0.14224)
		(layer "In6.Cu")
		(net "P5E_CPU0_P2_RX_DP<15>")
	)
	(arc
		(start 374.837198 -294.640762)
		(mid 374.680221 -294.335962)
		(end 374.837198 -294.031162)
		(width 0.1143)
		(layer "In6.Cu")
		(net "P5E_CPU0_P2_RX_DP<15>")
	)
	(segment
		(start 373.64797 -284.350206)
		(end 374.114822 -284.616144)
		(width 0.12954)
		(layer "F.Cu")
		(net "P5E_CPU0_P2_RX_DP<14>")
	)
	(segment
		(start 420.09822 -394.385292)
		(end 420.61892 -394.385292)
		(width 0.127)
		(layer "F.Cu")
		(net "P5E_CPU0_P2_RX_DP<14>")
	)
	(segment
		(start 374.397016 -285.748222)
		(end 374.366028 -285.730442)
		(width 0.1143)
		(layer "In6.Cu")
		(net "P5E_CPU0_P2_RX_DP<14>")
	)
	(segment
		(start 377.301506 -300.730158)
		(end 375.12625 -297.474894)
		(width 0.14224)
		(layer "In6.Cu")
		(net "P5E_CPU0_P2_RX_DP<14>")
	)
	(segment
		(start 426.639482 -375.49836)
		(end 426.54601 -375.404888)
		(width 0.14224)
		(layer "In6.Cu")
		(net "P5E_CPU0_P2_RX_DP<14>")
	)
	(segment
		(start 373.927624 -289.155632)
		(end 373.92864 -289.155124)
		(width 0.1143)
		(layer "In6.Cu")
		(net "P5E_CPU0_P2_RX_DP<14>")
	)
	(segment
		(start 420.61892 -394.385292)
		(end 420.713916 -394.031216)
		(width 0.14224)
		(layer "In6.Cu")
		(net "P5E_CPU0_P2_RX_DP<14>")
	)
	(segment
		(start 373.928386 -289.798506)
		(end 373.927878 -289.798506)
		(width 0.1143)
		(layer "In6.Cu")
		(net "P5E_CPU0_P2_RX_DP<14>")
	)
	(segment
		(start 391.1473 -322.03771)
		(end 384.608578 -309.804054)
		(width 0.14224)
		(layer "In6.Cu")
		(net "P5E_CPU0_P2_RX_DP<14>")
	)
	(segment
		(start 373.81688 -284.616144)
		(end 374.114822 -284.616144)
		(width 0.1143)
		(layer "In6.Cu")
		(net "P5E_CPU0_P2_RX_DP<14>")
	)
	(segment
		(start 383.995168 -308.886352)
		(end 377.301506 -300.730158)
		(width 0.14224)
		(layer "In6.Cu")
		(net "P5E_CPU0_P2_RX_DP<14>")
	)
	(segment
		(start 374.397778 -295.468548)
		(end 374.39727 -295.468294)
		(width 0.1143)
		(layer "In6.Cu")
		(net "P5E_CPU0_P2_RX_DP<14>")
	)
	(segment
		(start 373.896128 -292.411658)
		(end 373.966232 -292.371018)
		(width 0.1143)
		(layer "In6.Cu")
		(net "P5E_CPU0_P2_RX_DP<14>")
	)
	(segment
		(start 374.436894 -295.491408)
		(end 374.397778 -295.468548)
		(width 0.1143)
		(layer "In6.Cu")
		(net "P5E_CPU0_P2_RX_DP<14>")
	)
	(segment
		(start 373.927116 -290.773866)
		(end 373.927878 -290.773358)
		(width 0.1143)
		(layer "In6.Cu")
		(net "P5E_CPU0_P2_RX_DP<14>")
	)
	(segment
		(start 374.444768 -295.49725)
		(end 374.436894 -295.491408)
		(width 0.1143)
		(layer "In6.Cu")
		(net "P5E_CPU0_P2_RX_DP<14>")
	)
	(segment
		(start 373.927116 -293.038022)
		(end 373.9261 -293.037514)
		(width 0.1143)
		(layer "In6.Cu")
		(net "P5E_CPU0_P2_RX_DP<14>")
	)
	(segment
		(start 373.9642 -288.199576)
		(end 373.961406 -288.198052)
		(width 0.1143)
		(layer "In6.Cu")
		(net "P5E_CPU0_P2_RX_DP<14>")
	)
	(segment
		(start 373.9261 -294.014398)
		(end 373.927116 -294.01389)
		(width 0.1143)
		(layer "In6.Cu")
		(net "P5E_CPU0_P2_RX_DP<14>")
	)
	(segment
		(start 403.090126 -364.450376)
		(end 402.43887 -363.79912)
		(width 0.14224)
		(layer "In6.Cu")
		(net "P5E_CPU0_P2_RX_DP<14>")
	)
	(segment
		(start 420.976298 -393.842494)
		(end 420.976298 -393.428982)
		(width 0.14224)
		(layer "In6.Cu")
		(net "P5E_CPU0_P2_RX_DP<14>")
	)
	(segment
		(start 374.770396 -296.423842)
		(end 374.680226 -296.20591)
		(width 0.1143)
		(layer "In6.Cu")
		(net "P5E_CPU0_P2_RX_DP<14>")
	)
	(segment
		(start 373.927878 -293.03853)
		(end 373.927116 -293.038022)
		(width 0.1143)
		(layer "In6.Cu")
		(net "P5E_CPU0_P2_RX_DP<14>")
	)
	(segment
		(start 373.925338 -294.014906)
		(end 373.9261 -294.014398)
		(width 0.1143)
		(layer "In6.Cu")
		(net "P5E_CPU0_P2_RX_DP<14>")
	)
	(segment
		(start 373.911114 -290.78301)
		(end 373.927116 -290.773866)
		(width 0.1143)
		(layer "In6.Cu")
		(net "P5E_CPU0_P2_RX_DP<14>")
	)
	(segment
		(start 373.924322 -294.015414)
		(end 373.925338 -294.014906)
		(width 0.1143)
		(layer "In6.Cu")
		(net "P5E_CPU0_P2_RX_DP<14>")
	)
	(segment
		(start 426.546264 -375.404888)
		(end 426.542454 -375.401078)
		(width 0.14224)
		(layer "In6.Cu")
		(net "P5E_CPU0_P2_RX_DP<14>")
	)
	(segment
		(start 373.92356 -294.015922)
		(end 373.924322 -294.015414)
		(width 0.1143)
		(layer "In6.Cu")
		(net "P5E_CPU0_P2_RX_DP<14>")
	)
	(segment
		(start 373.927116 -289.797998)
		(end 373.896128 -289.780218)
		(width 0.1143)
		(layer "In6.Cu")
		(net "P5E_CPU0_P2_RX_DP<14>")
	)
	(segment
		(start 373.896128 -294.03167)
		(end 373.921528 -294.016938)
		(width 0.1143)
		(layer "In6.Cu")
		(net "P5E_CPU0_P2_RX_DP<14>")
	)
	(segment
		(start 374.816116 -296.556176)
		(end 374.816116 -296.528236)
		(width 0.1143)
		(layer "In6.Cu")
		(net "P5E_CPU0_P2_RX_DP<14>")
	)
	(segment
		(start 427.449742 -378.80036)
		(end 427.449742 -377.454414)
		(width 0.14224)
		(layer "In6.Cu")
		(net "P5E_CPU0_P2_RX_DP<14>")
	)
	(segment
		(start 373.921528 -294.016938)
		(end 373.92356 -294.015922)
		(width 0.1143)
		(layer "In6.Cu")
		(net "P5E_CPU0_P2_RX_DP<14>")
	)
	(segment
		(start 374.816624 -296.727372)
		(end 374.816624 -296.556684)
		(width 0.14224)
		(layer "In6.Cu")
		(net "P5E_CPU0_P2_RX_DP<14>")
	)
	(segment
		(start 373.931434 -294.660574)
		(end 373.896128 -294.640254)
		(width 0.1143)
		(layer "In6.Cu")
		(net "P5E_CPU0_P2_RX_DP<14>")
	)
	(segment
		(start 395.788134 -347.751146)
		(end 394.73124 -342.436958)
		(width 0.14224)
		(layer "In6.Cu")
		(net "P5E_CPU0_P2_RX_DP<14>")
	)
	(segment
		(start 373.896128 -287.551876)
		(end 373.962422 -287.513268)
		(width 0.1143)
		(layer "In6.Cu")
		(net "P5E_CPU0_P2_RX_DP<14>")
	)
	(segment
		(start 420.660322 -393.113006)
		(end 420.66337 -392.7348)
		(width 0.14224)
		(layer "In6.Cu")
		(net "P5E_CPU0_P2_RX_DP<14>")
	)
	(segment
		(start 384.608578 -309.804054)
		(end 383.995168 -308.886352)
		(width 0.14224)
		(layer "In6.Cu")
		(net "P5E_CPU0_P2_RX_DP<14>")
	)
	(segment
		(start 374.770396 -296.482516)
		(end 374.770396 -296.423842)
		(width 0.1143)
		(layer "In6.Cu")
		(net "P5E_CPU0_P2_RX_DP<14>")
	)
	(segment
		(start 373.9261 -293.037514)
		(end 373.925338 -293.037006)
		(width 0.1143)
		(layer "In6.Cu")
		(net "P5E_CPU0_P2_RX_DP<14>")
	)
	(segment
		(start 374.816116 -296.528236)
		(end 374.770396 -296.482516)
		(width 0.1143)
		(layer "In6.Cu")
		(net "P5E_CPU0_P2_RX_DP<14>")
	)
	(segment
		(start 375.12625 -297.474894)
		(end 374.816624 -296.727372)
		(width 0.14224)
		(layer "In6.Cu")
		(net "P5E_CPU0_P2_RX_DP<14>")
	)
	(segment
		(start 373.9642 -284.959806)
		(end 373.896128 -284.920436)
		(width 0.1143)
		(layer "In6.Cu")
		(net "P5E_CPU0_P2_RX_DP<14>")
	)
	(segment
		(start 420.977822 -391.10793)
		(end 424.97502 -381.45847)
		(width 0.14224)
		(layer "In6.Cu")
		(net "P5E_CPU0_P2_RX_DP<14>")
	)
	(segment
		(start 373.927116 -294.01389)
		(end 373.927878 -294.013382)
		(width 0.1143)
		(layer "In6.Cu")
		(net "P5E_CPU0_P2_RX_DP<14>")
	)
	(segment
		(start 373.925338 -293.037006)
		(end 373.924322 -293.036498)
		(width 0.1143)
		(layer "In6.Cu")
		(net "P5E_CPU0_P2_RX_DP<14>")
	)
	(segment
		(start 394.079222 -336.77733)
		(end 391.1473 -322.03771)
		(width 0.14224)
		(layer "In6.Cu")
		(net "P5E_CPU0_P2_RX_DP<14>")
	)
	(segment
		(start 373.895874 -290.7919)
		(end 373.911114 -290.78301)
		(width 0.1143)
		(layer "In6.Cu")
		(net "P5E_CPU0_P2_RX_DP<14>")
	)
	(segment
		(start 373.930418 -291.425376)
		(end 373.925846 -291.422582)
		(width 0.1143)
		(layer "In6.Cu")
		(net "P5E_CPU0_P2_RX_DP<14>")
	)
	(segment
		(start 373.927878 -289.798506)
		(end 373.927116 -289.797998)
		(width 0.1143)
		(layer "In6.Cu")
		(net "P5E_CPU0_P2_RX_DP<14>")
	)
	(segment
		(start 374.36425 -286.74314)
		(end 374.436894 -286.700722)
		(width 0.1143)
		(layer "In6.Cu")
		(net "P5E_CPU0_P2_RX_DP<14>")
	)
	(segment
		(start 374.398794 -285.749238)
		(end 374.397778 -285.74873)
		(width 0.1143)
		(layer "In6.Cu")
		(net "P5E_CPU0_P2_RX_DP<14>")
	)
	(segment
		(start 373.924322 -293.036498)
		(end 373.896128 -293.020242)
		(width 0.1143)
		(layer "In6.Cu")
		(net "P5E_CPU0_P2_RX_DP<14>")
	)
	(segment
		(start 395.849602 -347.95333)
		(end 395.849602 -347.953076)
		(width 0.14224)
		(layer "In6.Cu")
		(net "P5E_CPU0_P2_RX_DP<14>")
	)
	(segment
		(start 421.433498 -371.833902)
		(end 417.42233 -370.452904)
		(width 0.14224)
		(layer "In6.Cu")
		(net "P5E_CPU0_P2_RX_DP<14>")
	)
	(segment
		(start 424.97502 -381.45847)
		(end 424.97502 -381.458216)
		(width 0.14224)
		(layer "In6.Cu")
		(net "P5E_CPU0_P2_RX_DP<14>")
	)
	(segment
		(start 374.397778 -285.74873)
		(end 374.397016 -285.748222)
		(width 0.1143)
		(layer "In6.Cu")
		(net "P5E_CPU0_P2_RX_DP<14>")
	)
	(segment
		(start 373.927878 -294.013382)
		(end 373.928386 -294.013382)
		(width 0.1143)
		(layer "In6.Cu")
		(net "P5E_CPU0_P2_RX_DP<14>")
	)
	(segment
		(start 410.711396 -368.773202)
		(end 403.117304 -364.471204)
		(width 0.14224)
		(layer "In6.Cu")
		(net "P5E_CPU0_P2_RX_DP<14>")
	)
	(segment
		(start 373.927878 -290.773358)
		(end 373.928386 -290.773358)
		(width 0.1143)
		(layer "In6.Cu")
		(net "P5E_CPU0_P2_RX_DP<14>")
	)
	(segment
		(start 417.42233 -370.452904)
		(end 410.711396 -368.773202)
		(width 0.14224)
		(layer "In6.Cu")
		(net "P5E_CPU0_P2_RX_DP<14>")
	)
	(segment
		(start 420.713916 -394.031216)
		(end 420.88816 -393.930632)
		(width 0.14224)
		(layer "In6.Cu")
		(net "P5E_CPU0_P2_RX_DP<14>")
	)
	(segment
		(start 373.928386 -293.03853)
		(end 373.927878 -293.03853)
		(width 0.1143)
		(layer "In6.Cu")
		(net "P5E_CPU0_P2_RX_DP<14>")
	)
	(segment
		(start 426.54601 -375.404888)
		(end 426.546264 -375.404888)
		(width 0.14224)
		(layer "In6.Cu")
		(net "P5E_CPU0_P2_RX_DP<14>")
	)
	(segment
		(start 394.450062 -340.542626)
		(end 394.079222 -336.77733)
		(width 0.14224)
		(layer "In6.Cu")
		(net "P5E_CPU0_P2_RX_DP<14>")
	)
	(segment
		(start 373.74703 -284.685994)
		(end 373.81688 -284.616144)
		(width 0.1143)
		(layer "In6.Cu")
		(net "P5E_CPU0_P2_RX_DP<14>")
	)
	(segment
		(start 425.002706 -381.416814)
		(end 427.329854 -379.089666)
		(width 0.14224)
		(layer "In6.Cu")
		(net "P5E_CPU0_P2_RX_DP<14>")
	)
	(segment
		(start 374.400318 -285.750254)
		(end 374.398794 -285.749238)
		(width 0.1143)
		(layer "In6.Cu")
		(net "P5E_CPU0_P2_RX_DP<14>")
	)
	(segment
		(start 374.680226 -296.20591)
		(end 374.680226 -295.955974)
		(width 0.1143)
		(layer "In6.Cu")
		(net "P5E_CPU0_P2_RX_DP<14>")
	)
	(segment
		(start 420.976298 -393.428982)
		(end 420.660322 -393.113006)
		(width 0.14224)
		(layer "In6.Cu")
		(net "P5E_CPU0_P2_RX_DP<14>")
	)
	(segment
		(start 402.371814 -363.69879)
		(end 395.849602 -347.95333)
		(width 0.14224)
		(layer "In6.Cu")
		(net "P5E_CPU0_P2_RX_DP<14>")
	)
	(segment
		(start 374.436894 -285.77159)
		(end 374.400318 -285.750254)
		(width 0.1143)
		(layer "In6.Cu")
		(net "P5E_CPU0_P2_RX_DP<14>")
	)
	(segment
		(start 425.009564 -373.9769)
		(end 421.433498 -371.833902)
		(width 0.14224)
		(layer "In6.Cu")
		(net "P5E_CPU0_P2_RX_DP<14>")
	)
	(segment
		(start 403.090126 -364.45063)
		(end 403.090126 -364.450376)
		(width 0.14224)
		(layer "In6.Cu")
		(net "P5E_CPU0_P2_RX_DP<14>")
	)
	(segment
		(start 373.961406 -288.198052)
		(end 373.89435 -288.158936)
		(width 0.1143)
		(layer "In6.Cu")
		(net "P5E_CPU0_P2_RX_DP<14>")
	)
	(segment
		(start 426.542454 -375.401078)
		(end 425.009564 -373.9769)
		(width 0.14224)
		(layer "In6.Cu")
		(net "P5E_CPU0_P2_RX_DP<14>")
	)
	(segment
		(start 374.816624 -296.556684)
		(end 374.816116 -296.556176)
		(width 0.1143)
		(layer "In6.Cu")
		(net "P5E_CPU0_P2_RX_DP<14>")
	)
	(segment
		(start 420.88816 -393.930632)
		(end 420.976298 -393.842494)
		(width 0.14224)
		(layer "In6.Cu")
		(net "P5E_CPU0_P2_RX_DP<14>")
	)
	(segment
		(start 420.66337 -392.7348)
		(end 420.96817 -392.430254)
		(width 0.14224)
		(layer "In6.Cu")
		(net "P5E_CPU0_P2_RX_DP<14>")
	)
	(segment
		(start 420.96817 -392.430254)
		(end 420.96817 -391.156698)
		(width 0.14224)
		(layer "In6.Cu")
		(net "P5E_CPU0_P2_RX_DP<14>")
	)
	(arc
		(start 373.925846 -291.422582)
		(mid 373.7397 -291.115358)
		(end 373.895874 -290.7919)
		(width 0.1143)
		(layer "In6.Cu")
		(net "P5E_CPU0_P2_RX_DP<14>")
	)
	(arc
		(start 374.209818 -285.441136)
		(mid 374.208646 -285.415681)
		(end 374.206008 -285.390336)
		(width 0.1143)
		(layer "In6.Cu")
		(net "P5E_CPU0_P2_RX_DP<14>")
	)
	(arc
		(start 373.89435 -288.158936)
		(mid 373.780943 -288.026047)
		(end 373.740172 -287.856168)
		(width 0.1143)
		(layer "In6.Cu")
		(net "P5E_CPU0_P2_RX_DP<14>")
	)
	(arc
		(start 373.92864 -289.155124)
		(mid 374.209709 -288.687173)
		(end 373.9642 -288.199576)
		(width 0.1143)
		(layer "In6.Cu")
		(net "P5E_CPU0_P2_RX_DP<14>")
	)
	(arc
		(start 374.366028 -285.730442)
		(mid 374.254586 -285.6038)
		(end 374.209818 -285.441136)
		(width 0.1143)
		(layer "In6.Cu")
		(net "P5E_CPU0_P2_RX_DP<14>")
	)
	(arc
		(start 373.740172 -287.856168)
		(mid 373.781427 -287.685197)
		(end 373.896128 -287.551876)
		(width 0.1143)
		(layer "In6.Cu")
		(net "P5E_CPU0_P2_RX_DP<14>")
	)
	(arc
		(start 374.680226 -295.955974)
		(mid 374.617875 -295.698183)
		(end 374.444768 -295.49725)
		(width 0.1143)
		(layer "In6.Cu")
		(net "P5E_CPU0_P2_RX_DP<14>")
	)
	(arc
		(start 374.39727 -295.468294)
		(mid 374.261189 -295.332446)
		(end 374.211342 -295.14673)
		(width 0.1143)
		(layer "In6.Cu")
		(net "P5E_CPU0_P2_RX_DP<14>")
	)
	(arc
		(start 373.896128 -293.020242)
		(mid 373.7402 -292.71595)
		(end 373.896128 -292.411658)
		(width 0.1143)
		(layer "In6.Cu")
		(net "P5E_CPU0_P2_RX_DP<14>")
	)
	(arc
		(start 373.896128 -284.920436)
		(mid 373.798993 -284.817567)
		(end 373.74703 -284.685994)
		(width 0.1143)
		(layer "In6.Cu")
		(net "P5E_CPU0_P2_RX_DP<14>")
	)
	(arc
		(start 374.211342 -295.14673)
		(mid 374.136362 -294.866246)
		(end 373.931434 -294.660574)
		(width 0.1143)
		(layer "In6.Cu")
		(net "P5E_CPU0_P2_RX_DP<14>")
	)
	(arc
		(start 395.849602 -347.953076)
		(mid 395.813903 -347.853622)
		(end 395.788134 -347.751146)
		(width 0.14224)
		(layer "In6.Cu")
		(net "P5E_CPU0_P2_RX_DP<14>")
	)
	(arc
		(start 424.97502 -381.458216)
		(mid 424.986811 -381.436141)
		(end 425.002706 -381.416814)
		(width 0.14224)
		(layer "In6.Cu")
		(net "P5E_CPU0_P2_RX_DP<14>")
	)
	(arc
		(start 394.73124 -342.436958)
		(mid 394.567407 -341.493242)
		(end 394.450062 -340.542626)
		(width 0.14224)
		(layer "In6.Cu")
		(net "P5E_CPU0_P2_RX_DP<14>")
	)
	(arc
		(start 374.210072 -287.03651)
		(mid 374.252887 -286.871796)
		(end 374.36425 -286.74314)
		(width 0.1143)
		(layer "In6.Cu")
		(net "P5E_CPU0_P2_RX_DP<14>")
	)
	(arc
		(start 373.896128 -294.640254)
		(mid 373.7402 -294.335962)
		(end 373.896128 -294.03167)
		(width 0.1143)
		(layer "In6.Cu")
		(net "P5E_CPU0_P2_RX_DP<14>")
	)
	(arc
		(start 374.206008 -285.390336)
		(mid 374.12534 -285.152464)
		(end 373.9642 -284.959806)
		(width 0.1143)
		(layer "In6.Cu")
		(net "P5E_CPU0_P2_RX_DP<14>")
	)
	(arc
		(start 373.962422 -287.513268)
		(mid 374.125212 -287.32026)
		(end 374.206516 -287.081214)
		(width 0.1143)
		(layer "In6.Cu")
		(net "P5E_CPU0_P2_RX_DP<14>")
	)
	(arc
		(start 373.928386 -294.013382)
		(mid 374.209033 -293.525956)
		(end 373.928386 -293.03853)
		(width 0.1143)
		(layer "In6.Cu")
		(net "P5E_CPU0_P2_RX_DP<14>")
	)
	(arc
		(start 373.896128 -289.780218)
		(mid 373.741792 -289.459408)
		(end 373.927624 -289.155632)
		(width 0.1143)
		(layer "In6.Cu")
		(net "P5E_CPU0_P2_RX_DP<14>")
	)
	(arc
		(start 420.96817 -391.156698)
		(mid 420.970616 -391.131845)
		(end 420.977822 -391.10793)
		(width 0.14224)
		(layer "In6.Cu")
		(net "P5E_CPU0_P2_RX_DP<14>")
	)
	(arc
		(start 403.117304 -364.471204)
		(mid 403.103024 -364.46183)
		(end 403.090126 -364.45063)
		(width 0.14224)
		(layer "In6.Cu")
		(net "P5E_CPU0_P2_RX_DP<14>")
	)
	(arc
		(start 374.206516 -287.081214)
		(mid 374.208871 -287.058908)
		(end 374.210072 -287.03651)
		(width 0.1143)
		(layer "In6.Cu")
		(net "P5E_CPU0_P2_RX_DP<14>")
	)
	(arc
		(start 402.43887 -363.79912)
		(mid 402.400408 -363.752254)
		(end 402.371814 -363.69879)
		(width 0.14224)
		(layer "In6.Cu")
		(net "P5E_CPU0_P2_RX_DP<14>")
	)
	(arc
		(start 373.966232 -292.371018)
		(mid 374.207966 -291.888321)
		(end 373.930418 -291.425376)
		(width 0.1143)
		(layer "In6.Cu")
		(net "P5E_CPU0_P2_RX_DP<14>")
	)
	(arc
		(start 374.436894 -286.700722)
		(mid 374.680221 -286.236156)
		(end 374.436894 -285.77159)
		(width 0.1143)
		(layer "In6.Cu")
		(net "P5E_CPU0_P2_RX_DP<14>")
	)
	(arc
		(start 373.928386 -290.773358)
		(mid 374.209033 -290.285932)
		(end 373.928386 -289.798506)
		(width 0.1143)
		(layer "In6.Cu")
		(net "P5E_CPU0_P2_RX_DP<14>")
	)
	(arc
		(start 427.329854 -379.089666)
		(mid 427.418598 -378.956946)
		(end 427.449742 -378.80036)
		(width 0.14224)
		(layer "In6.Cu")
		(net "P5E_CPU0_P2_RX_DP<14>")
	)
	(arc
		(start 427.449742 -377.454414)
		(mid 427.239169 -376.395791)
		(end 426.639482 -375.49836)
		(width 0.14224)
		(layer "In6.Cu")
		(net "P5E_CPU0_P2_RX_DP<14>")
	)
	(segment
		(start 373.64797 -281.110182)
		(end 374.114822 -281.37612)
		(width 0.12954)
		(layer "F.Cu")
		(net "P5E_CPU0_P2_RX_DP<13>")
	)
	(segment
		(start 418.898324 -394.385292)
		(end 419.419024 -394.385292)
		(width 0.127)
		(layer "F.Cu")
		(net "P5E_CPU0_P2_RX_DP<13>")
	)
	(segment
		(start 419.460426 -393.113006)
		(end 419.463474 -392.7348)
		(width 0.14224)
		(layer "In6.Cu")
		(net "P5E_CPU0_P2_RX_DP<13>")
	)
	(segment
		(start 372.990364 -284.29204)
		(end 373.02694 -284.270704)
		(width 0.1143)
		(layer "In6.Cu")
		(net "P5E_CPU0_P2_RX_DP<13>")
	)
	(segment
		(start 372.956074 -292.411658)
		(end 372.985792 -292.39464)
		(width 0.1143)
		(layer "In6.Cu")
		(net "P5E_CPU0_P2_RX_DP<13>")
	)
	(segment
		(start 419.776402 -393.842494)
		(end 419.776402 -393.428982)
		(width 0.14224)
		(layer "In6.Cu")
		(net "P5E_CPU0_P2_RX_DP<13>")
	)
	(segment
		(start 419.51402 -394.031216)
		(end 419.688264 -393.930632)
		(width 0.14224)
		(layer "In6.Cu")
		(net "P5E_CPU0_P2_RX_DP<13>")
	)
	(segment
		(start 373.02694 -293.06139)
		(end 372.990364 -293.040054)
		(width 0.1143)
		(layer "In6.Cu")
		(net "P5E_CPU0_P2_RX_DP<13>")
	)
	(segment
		(start 373.785892 -296.344086)
		(end 373.740172 -296.298366)
		(width 0.1143)
		(layer "In6.Cu")
		(net "P5E_CPU0_P2_RX_DP<13>")
	)
	(segment
		(start 373.427244 -281.881326)
		(end 373.457724 -281.863546)
		(width 0.1143)
		(layer "In6.Cu")
		(net "P5E_CPU0_P2_RX_DP<13>")
	)
	(segment
		(start 372.987824 -294.013382)
		(end 372.98884 -294.012874)
		(width 0.1143)
		(layer "In6.Cu")
		(net "P5E_CPU0_P2_RX_DP<13>")
	)
	(segment
		(start 372.97995 -291.413946)
		(end 372.977918 -291.412676)
		(width 0.1143)
		(layer "In6.Cu")
		(net "P5E_CPU0_P2_RX_DP<13>")
	)
	(segment
		(start 372.990364 -293.040054)
		(end 372.98884 -293.039038)
		(width 0.1143)
		(layer "In6.Cu")
		(net "P5E_CPU0_P2_RX_DP<13>")
	)
	(segment
		(start 373.02694 -291.441378)
		(end 372.990364 -291.420042)
		(width 0.1143)
		(layer "In6.Cu")
		(net "P5E_CPU0_P2_RX_DP<13>")
	)
	(segment
		(start 372.98122 -291.414708)
		(end 372.97995 -291.413946)
		(width 0.1143)
		(layer "In6.Cu")
		(net "P5E_CPU0_P2_RX_DP<13>")
	)
	(segment
		(start 373.457724 -281.863546)
		(end 373.49684 -281.840686)
		(width 0.1143)
		(layer "In6.Cu")
		(net "P5E_CPU0_P2_RX_DP<13>")
	)
	(segment
		(start 372.987062 -289.153854)
		(end 372.987824 -289.153346)
		(width 0.1143)
		(layer "In6.Cu")
		(net "P5E_CPU0_P2_RX_DP<13>")
	)
	(segment
		(start 372.985792 -294.014652)
		(end 372.987062 -294.01389)
		(width 0.1143)
		(layer "In6.Cu")
		(net "P5E_CPU0_P2_RX_DP<13>")
	)
	(segment
		(start 372.987824 -291.418518)
		(end 372.987062 -291.41801)
		(width 0.1143)
		(layer "In6.Cu")
		(net "P5E_CPU0_P2_RX_DP<13>")
	)
	(segment
		(start 373.7864 -296.676826)
		(end 373.7864 -296.486072)
		(width 0.14224)
		(layer "In6.Cu")
		(net "P5E_CPU0_P2_RX_DP<13>")
	)
	(segment
		(start 372.956074 -290.791646)
		(end 372.985792 -290.774628)
		(width 0.1143)
		(layer "In6.Cu")
		(net "P5E_CPU0_P2_RX_DP<13>")
	)
	(segment
		(start 372.98884 -290.77285)
		(end 372.990364 -290.771834)
		(width 0.1143)
		(layer "In6.Cu")
		(net "P5E_CPU0_P2_RX_DP<13>")
	)
	(segment
		(start 372.98884 -284.293056)
		(end 372.990364 -284.29204)
		(width 0.1143)
		(layer "In6.Cu")
		(net "P5E_CPU0_P2_RX_DP<13>")
	)
	(segment
		(start 373.02694 -289.821366)
		(end 372.990364 -289.80003)
		(width 0.1143)
		(layer "In6.Cu")
		(net "P5E_CPU0_P2_RX_DP<13>")
	)
	(segment
		(start 372.987824 -282.673552)
		(end 372.98884 -282.673044)
		(width 0.1143)
		(layer "In6.Cu")
		(net "P5E_CPU0_P2_RX_DP<13>")
	)
	(segment
		(start 372.98122 -283.314902)
		(end 372.97995 -283.31414)
		(width 0.1143)
		(layer "In6.Cu")
		(net "P5E_CPU0_P2_RX_DP<13>")
	)
	(segment
		(start 372.977918 -294.6527)
		(end 372.976902 -294.652192)
		(width 0.1143)
		(layer "In6.Cu")
		(net "P5E_CPU0_P2_RX_DP<13>")
	)
	(segment
		(start 419.776402 -393.428982)
		(end 419.460426 -393.113006)
		(width 0.14224)
		(layer "In6.Cu")
		(net "P5E_CPU0_P2_RX_DP<13>")
	)
	(segment
		(start 372.956074 -287.551876)
		(end 372.987824 -287.533588)
		(width 0.1143)
		(layer "In6.Cu")
		(net "P5E_CPU0_P2_RX_DP<13>")
	)
	(segment
		(start 393.094718 -336.676238)
		(end 390.200642 -322.250816)
		(width 0.14224)
		(layer "In6.Cu")
		(net "P5E_CPU0_P2_RX_DP<13>")
	)
	(segment
		(start 373.81688 -281.37612)
		(end 374.114822 -281.37612)
		(width 0.1143)
		(layer "In6.Cu")
		(net "P5E_CPU0_P2_RX_DP<13>")
	)
	(segment
		(start 419.419024 -394.385292)
		(end 419.51402 -394.031216)
		(width 0.14224)
		(layer "In6.Cu")
		(net "P5E_CPU0_P2_RX_DP<13>")
	)
	(segment
		(start 373.02694 -284.961584)
		(end 372.990364 -284.940248)
		(width 0.1143)
		(layer "In6.Cu")
		(net "P5E_CPU0_P2_RX_DP<13>")
	)
	(segment
		(start 372.956074 -284.311852)
		(end 372.985792 -284.294834)
		(width 0.1143)
		(layer "In6.Cu")
		(net "P5E_CPU0_P2_RX_DP<13>")
	)
	(segment
		(start 372.985792 -290.774628)
		(end 372.987062 -290.773866)
		(width 0.1143)
		(layer "In6.Cu")
		(net "P5E_CPU0_P2_RX_DP<13>")
	)
	(segment
		(start 372.98884 -284.939232)
		(end 372.987824 -284.938724)
		(width 0.1143)
		(layer "In6.Cu")
		(net "P5E_CPU0_P2_RX_DP<13>")
	)
	(segment
		(start 372.987824 -284.938724)
		(end 372.987062 -284.938216)
		(width 0.1143)
		(layer "In6.Cu")
		(net "P5E_CPU0_P2_RX_DP<13>")
	)
	(segment
		(start 426.020484 -376.357134)
		(end 424.048428 -374.783858)
		(width 0.14224)
		(layer "In6.Cu")
		(net "P5E_CPU0_P2_RX_DP<13>")
	)
	(segment
		(start 372.98122 -284.934914)
		(end 372.97995 -284.934152)
		(width 0.1143)
		(layer "In6.Cu")
		(net "P5E_CPU0_P2_RX_DP<13>")
	)
	(segment
		(start 372.987824 -289.153346)
		(end 372.98884 -289.152838)
		(width 0.1143)
		(layer "In6.Cu")
		(net "P5E_CPU0_P2_RX_DP<13>")
	)
	(segment
		(start 373.49684 -295.491408)
		(end 373.457724 -295.468548)
		(width 0.1143)
		(layer "In6.Cu")
		(net "P5E_CPU0_P2_RX_DP<13>")
	)
	(segment
		(start 383.128012 -309.311802)
		(end 376.590814 -301.346362)
		(width 0.14224)
		(layer "In6.Cu")
		(net "P5E_CPU0_P2_RX_DP<13>")
	)
	(segment
		(start 372.98884 -291.419026)
		(end 372.987824 -291.418518)
		(width 0.1143)
		(layer "In6.Cu")
		(net "P5E_CPU0_P2_RX_DP<13>")
	)
	(segment
		(start 372.981982 -294.65524)
		(end 372.98122 -294.654732)
		(width 0.1143)
		(layer "In6.Cu")
		(net "P5E_CPU0_P2_RX_DP<13>")
	)
	(segment
		(start 373.740172 -296.298366)
		(end 373.740172 -295.955974)
		(width 0.1143)
		(layer "In6.Cu")
		(net "P5E_CPU0_P2_RX_DP<13>")
	)
	(segment
		(start 373.49684 -285.77159)
		(end 373.457724 -285.74873)
		(width 0.1143)
		(layer "In6.Cu")
		(net "P5E_CPU0_P2_RX_DP<13>")
	)
	(segment
		(start 372.987824 -293.03853)
		(end 372.956074 -293.020242)
		(width 0.1143)
		(layer "In6.Cu")
		(net "P5E_CPU0_P2_RX_DP<13>")
	)
	(segment
		(start 419.768274 -392.430254)
		(end 419.768274 -391.263886)
		(width 0.14224)
		(layer "In6.Cu")
		(net "P5E_CPU0_P2_RX_DP<13>")
	)
	(segment
		(start 383.135632 -309.322978)
		(end 383.128012 -309.311802)
		(width 0.14224)
		(layer "In6.Cu")
		(net "P5E_CPU0_P2_RX_DP<13>")
	)
	(segment
		(start 383.135632 -309.323232)
		(end 383.135632 -309.322978)
		(width 0.14224)
		(layer "In6.Cu")
		(net "P5E_CPU0_P2_RX_DP<13>")
	)
	(segment
		(start 424.01871 -380.84887)
		(end 426.384212 -378.483368)
		(width 0.14224)
		(layer "In6.Cu")
		(net "P5E_CPU0_P2_RX_DP<13>")
	)
	(segment
		(start 372.976902 -283.312362)
		(end 372.975632 -283.3116)
		(width 0.1143)
		(layer "In6.Cu")
		(net "P5E_CPU0_P2_RX_DP<13>")
	)
	(segment
		(start 372.98884 -292.392862)
		(end 372.990364 -292.391846)
		(width 0.1143)
		(layer "In6.Cu")
		(net "P5E_CPU0_P2_RX_DP<13>")
	)
	(segment
		(start 372.975632 -284.931612)
		(end 372.956074 -284.920436)
		(width 0.1143)
		(layer "In6.Cu")
		(net "P5E_CPU0_P2_RX_DP<13>")
	)
	(segment
		(start 372.977918 -284.932882)
		(end 372.976902 -284.932374)
		(width 0.1143)
		(layer "In6.Cu")
		(net "P5E_CPU0_P2_RX_DP<13>")
	)
	(segment
		(start 372.987824 -294.658542)
		(end 372.987062 -294.658034)
		(width 0.1143)
		(layer "In6.Cu")
		(net "P5E_CPU0_P2_RX_DP<13>")
	)
	(segment
		(start 373.785892 -296.372534)
		(end 373.785892 -296.344086)
		(width 0.1143)
		(layer "In6.Cu")
		(net "P5E_CPU0_P2_RX_DP<13>")
	)
	(segment
		(start 373.425212 -286.742378)
		(end 373.457724 -286.723582)
		(width 0.1143)
		(layer "In6.Cu")
		(net "P5E_CPU0_P2_RX_DP<13>")
	)
	(segment
		(start 419.688264 -393.930632)
		(end 419.776402 -393.842494)
		(width 0.14224)
		(layer "In6.Cu")
		(net "P5E_CPU0_P2_RX_DP<13>")
	)
	(segment
		(start 373.7864 -296.486072)
		(end 373.785892 -296.486072)
		(width 0.14224)
		(layer "In6.Cu")
		(net "P5E_CPU0_P2_RX_DP<13>")
	)
	(segment
		(start 372.983506 -283.316172)
		(end 372.981982 -283.31541)
		(width 0.1143)
		(layer "In6.Cu")
		(net "P5E_CPU0_P2_RX_DP<13>")
	)
	(segment
		(start 372.956074 -282.69184)
		(end 372.985792 -282.674822)
		(width 0.1143)
		(layer "In6.Cu")
		(net "P5E_CPU0_P2_RX_DP<13>")
	)
	(segment
		(start 372.985792 -284.294834)
		(end 372.987062 -284.294072)
		(width 0.1143)
		(layer "In6.Cu")
		(net "P5E_CPU0_P2_RX_DP<13>")
	)
	(segment
		(start 419.463474 -392.7348)
		(end 419.768274 -392.430254)
		(width 0.14224)
		(layer "In6.Cu")
		(net "P5E_CPU0_P2_RX_DP<13>")
	)
	(segment
		(start 372.990364 -290.771834)
		(end 373.02694 -290.750498)
		(width 0.1143)
		(layer "In6.Cu")
		(net "P5E_CPU0_P2_RX_DP<13>")
	)
	(segment
		(start 372.98884 -294.012874)
		(end 372.990364 -294.011858)
		(width 0.1143)
		(layer "In6.Cu")
		(net "P5E_CPU0_P2_RX_DP<13>")
	)
	(segment
		(start 372.987824 -290.773358)
		(end 372.98884 -290.77285)
		(width 0.1143)
		(layer "In6.Cu")
		(net "P5E_CPU0_P2_RX_DP<13>")
	)
	(segment
		(start 372.983506 -284.936184)
		(end 372.981982 -284.935422)
		(width 0.1143)
		(layer "In6.Cu")
		(net "P5E_CPU0_P2_RX_DP<13>")
	)
	(segment
		(start 372.984268 -294.65651)
		(end 372.983506 -294.656002)
		(width 0.1143)
		(layer "In6.Cu")
		(net "P5E_CPU0_P2_RX_DP<13>")
	)
	(segment
		(start 372.985792 -289.154616)
		(end 372.987062 -289.153854)
		(width 0.1143)
		(layer "In6.Cu")
		(net "P5E_CPU0_P2_RX_DP<13>")
	)
	(segment
		(start 372.983506 -291.415978)
		(end 372.981982 -291.415216)
		(width 0.1143)
		(layer "In6.Cu")
		(net "P5E_CPU0_P2_RX_DP<13>")
	)
	(segment
		(start 372.990364 -284.940248)
		(end 372.98884 -284.939232)
		(width 0.1143)
		(layer "In6.Cu")
		(net "P5E_CPU0_P2_RX_DP<13>")
	)
	(segment
		(start 372.977918 -291.412676)
		(end 372.976902 -291.412168)
		(width 0.1143)
		(layer "In6.Cu")
		(net "P5E_CPU0_P2_RX_DP<13>")
	)
	(segment
		(start 426.5041 -378.194062)
		(end 426.5041 -377.36145)
		(width 0.14224)
		(layer "In6.Cu")
		(net "P5E_CPU0_P2_RX_DP<13>")
	)
	(segment
		(start 373.457724 -295.468548)
		(end 373.427244 -295.450768)
		(width 0.1143)
		(layer "In6.Cu")
		(net "P5E_CPU0_P2_RX_DP<13>")
	)
	(segment
		(start 372.987824 -292.39337)
		(end 372.98884 -292.392862)
		(width 0.1143)
		(layer "In6.Cu")
		(net "P5E_CPU0_P2_RX_DP<13>")
	)
	(segment
		(start 402.381974 -365.10087)
		(end 401.609052 -364.327948)
		(width 0.14224)
		(layer "In6.Cu")
		(net "P5E_CPU0_P2_RX_DP<13>")
	)
	(segment
		(start 372.987062 -294.658034)
		(end 372.984268 -294.65651)
		(width 0.1143)
		(layer "In6.Cu")
		(net "P5E_CPU0_P2_RX_DP<13>")
	)
	(segment
		(start 372.976902 -291.412168)
		(end 372.975632 -291.411406)
		(width 0.1143)
		(layer "In6.Cu")
		(net "P5E_CPU0_P2_RX_DP<13>")
	)
	(segment
		(start 372.975632 -294.65143)
		(end 372.956074 -294.640254)
		(width 0.1143)
		(layer "In6.Cu")
		(net "P5E_CPU0_P2_RX_DP<13>")
	)
	(segment
		(start 372.987062 -283.318204)
		(end 372.984268 -283.31668)
		(width 0.1143)
		(layer "In6.Cu")
		(net "P5E_CPU0_P2_RX_DP<13>")
	)
	(segment
		(start 372.983506 -294.656002)
		(end 372.981982 -294.65524)
		(width 0.1143)
		(layer "In6.Cu")
		(net "P5E_CPU0_P2_RX_DP<13>")
	)
	(segment
		(start 373.457724 -286.723582)
		(end 373.49684 -286.700722)
		(width 0.1143)
		(layer "In6.Cu")
		(net "P5E_CPU0_P2_RX_DP<13>")
	)
	(segment
		(start 373.734076 -281.458924)
		(end 373.81688 -281.37612)
		(width 0.1143)
		(layer "In6.Cu")
		(net "P5E_CPU0_P2_RX_DP<13>")
	)
	(segment
		(start 372.97995 -284.934152)
		(end 372.977918 -284.932882)
		(width 0.1143)
		(layer "In6.Cu")
		(net "P5E_CPU0_P2_RX_DP<13>")
	)
	(segment
		(start 372.98884 -282.673044)
		(end 372.990364 -282.672028)
		(width 0.1143)
		(layer "In6.Cu")
		(net "P5E_CPU0_P2_RX_DP<13>")
	)
	(segment
		(start 393.563094 -341.429086)
		(end 393.094718 -336.676238)
		(width 0.14224)
		(layer "In6.Cu")
		(net "P5E_CPU0_P2_RX_DP<13>")
	)
	(segment
		(start 395.052042 -348.523306)
		(end 395.051788 -348.523052)
		(width 0.14224)
		(layer "In6.Cu")
		(net "P5E_CPU0_P2_RX_DP<13>")
	)
	(segment
		(start 372.987824 -283.318712)
		(end 372.987062 -283.318204)
		(width 0.1143)
		(layer "In6.Cu")
		(net "P5E_CPU0_P2_RX_DP<13>")
	)
	(segment
		(start 372.981982 -291.415216)
		(end 372.98122 -291.414708)
		(width 0.1143)
		(layer "In6.Cu")
		(net "P5E_CPU0_P2_RX_DP<13>")
	)
	(segment
		(start 372.98884 -283.31922)
		(end 372.987824 -283.318712)
		(width 0.1143)
		(layer "In6.Cu")
		(net "P5E_CPU0_P2_RX_DP<13>")
	)
	(segment
		(start 372.97995 -294.65397)
		(end 372.977918 -294.6527)
		(width 0.1143)
		(layer "In6.Cu")
		(net "P5E_CPU0_P2_RX_DP<13>")
	)
	(segment
		(start 372.990364 -282.672028)
		(end 373.02694 -282.650692)
		(width 0.1143)
		(layer "In6.Cu")
		(net "P5E_CPU0_P2_RX_DP<13>")
	)
	(segment
		(start 372.984268 -291.416486)
		(end 372.983506 -291.415978)
		(width 0.1143)
		(layer "In6.Cu")
		(net "P5E_CPU0_P2_RX_DP<13>")
	)
	(segment
		(start 372.990364 -294.011858)
		(end 373.02694 -293.990522)
		(width 0.1143)
		(layer "In6.Cu")
		(net "P5E_CPU0_P2_RX_DP<13>")
	)
	(segment
		(start 395.051788 -348.523306)
		(end 395.052042 -348.523306)
		(width 0.14224)
		(layer "In6.Cu")
		(net "P5E_CPU0_P2_RX_DP<13>")
	)
	(segment
		(start 372.977918 -283.31287)
		(end 372.976902 -283.312362)
		(width 0.1143)
		(layer "In6.Cu")
		(net "P5E_CPU0_P2_RX_DP<13>")
	)
	(segment
		(start 373.457724 -285.74873)
		(end 373.427244 -285.73095)
		(width 0.1143)
		(layer "In6.Cu")
		(net "P5E_CPU0_P2_RX_DP<13>")
	)
	(segment
		(start 394.824204 -347.77299)
		(end 393.564872 -341.441278)
		(width 0.14224)
		(layer "In6.Cu")
		(net "P5E_CPU0_P2_RX_DP<13>")
	)
	(segment
		(start 373.02694 -283.341572)
		(end 372.990364 -283.320236)
		(width 0.1143)
		(layer "In6.Cu")
		(net "P5E_CPU0_P2_RX_DP<13>")
	)
	(segment
		(start 372.976902 -294.652192)
		(end 372.975632 -294.65143)
		(width 0.1143)
		(layer "In6.Cu")
		(net "P5E_CPU0_P2_RX_DP<13>")
	)
	(segment
		(start 372.987824 -289.798506)
		(end 372.956074 -289.780218)
		(width 0.1143)
		(layer "In6.Cu")
		(net "P5E_CPU0_P2_RX_DP<13>")
	)
	(segment
		(start 372.98884 -289.799014)
		(end 372.987824 -289.798506)
		(width 0.1143)
		(layer "In6.Cu")
		(net "P5E_CPU0_P2_RX_DP<13>")
	)
	(segment
		(start 372.987062 -284.294072)
		(end 372.987824 -284.293564)
		(width 0.1143)
		(layer "In6.Cu")
		(net "P5E_CPU0_P2_RX_DP<13>")
	)
	(segment
		(start 383.906268 -310.476138)
		(end 383.135632 -309.323232)
		(width 0.14224)
		(layer "In6.Cu")
		(net "P5E_CPU0_P2_RX_DP<13>")
	)
	(segment
		(start 372.987062 -282.67406)
		(end 372.987824 -282.673552)
		(width 0.1143)
		(layer "In6.Cu")
		(net "P5E_CPU0_P2_RX_DP<13>")
	)
	(segment
		(start 372.987824 -288.178494)
		(end 372.954296 -288.158936)
		(width 0.1143)
		(layer "In6.Cu")
		(net "P5E_CPU0_P2_RX_DP<13>")
	)
	(segment
		(start 372.987062 -291.41801)
		(end 372.984268 -291.416486)
		(width 0.1143)
		(layer "In6.Cu")
		(net "P5E_CPU0_P2_RX_DP<13>")
	)
	(segment
		(start 372.975632 -283.3116)
		(end 372.956074 -283.300424)
		(width 0.1143)
		(layer "In6.Cu")
		(net "P5E_CPU0_P2_RX_DP<13>")
	)
	(segment
		(start 373.02694 -288.201354)
		(end 372.987824 -288.178494)
		(width 0.1143)
		(layer "In6.Cu")
		(net "P5E_CPU0_P2_RX_DP<13>")
	)
	(segment
		(start 390.200642 -322.250816)
		(end 383.906268 -310.476138)
		(width 0.14224)
		(layer "In6.Cu")
		(net "P5E_CPU0_P2_RX_DP<13>")
	)
	(segment
		(start 417.180014 -371.429788)
		(end 410.733494 -369.796314)
		(width 0.14224)
		(layer "In6.Cu")
		(net "P5E_CPU0_P2_RX_DP<13>")
	)
	(segment
		(start 372.984268 -283.31668)
		(end 372.983506 -283.316172)
		(width 0.1143)
		(layer "In6.Cu")
		(net "P5E_CPU0_P2_RX_DP<13>")
	)
	(segment
		(start 372.98884 -293.039038)
		(end 372.987824 -293.03853)
		(width 0.1143)
		(layer "In6.Cu")
		(net "P5E_CPU0_P2_RX_DP<13>")
	)
	(segment
		(start 373.02694 -294.681402)
		(end 372.990364 -294.660066)
		(width 0.1143)
		(layer "In6.Cu")
		(net "P5E_CPU0_P2_RX_DP<13>")
	)
	(segment
		(start 372.990364 -294.660066)
		(end 372.98884 -294.65905)
		(width 0.1143)
		(layer "In6.Cu")
		(net "P5E_CPU0_P2_RX_DP<13>")
	)
	(segment
		(start 372.990364 -292.391846)
		(end 373.02694 -292.37051)
		(width 0.1143)
		(layer "In6.Cu")
		(net "P5E_CPU0_P2_RX_DP<13>")
	)
	(segment
		(start 372.985792 -292.39464)
		(end 372.987062 -292.393878)
		(width 0.1143)
		(layer "In6.Cu")
		(net "P5E_CPU0_P2_RX_DP<13>")
	)
	(segment
		(start 419.890702 -372.430294)
		(end 417.526724 -371.548914)
		(width 0.14224)
		(layer "In6.Cu")
		(net "P5E_CPU0_P2_RX_DP<13>")
	)
	(segment
		(start 372.987824 -284.293564)
		(end 372.98884 -284.293056)
		(width 0.1143)
		(layer "In6.Cu")
		(net "P5E_CPU0_P2_RX_DP<13>")
	)
	(segment
		(start 419.885876 -390.672828)
		(end 423.851578 -381.098806)
		(width 0.14224)
		(layer "In6.Cu")
		(net "P5E_CPU0_P2_RX_DP<13>")
	)
	(segment
		(start 372.987062 -284.938216)
		(end 372.984268 -284.936692)
		(width 0.1143)
		(layer "In6.Cu")
		(net "P5E_CPU0_P2_RX_DP<13>")
	)
	(segment
		(start 372.990364 -289.151822)
		(end 373.02694 -289.130486)
		(width 0.1143)
		(layer "In6.Cu")
		(net "P5E_CPU0_P2_RX_DP<13>")
	)
	(segment
		(start 372.981982 -283.31541)
		(end 372.98122 -283.314902)
		(width 0.1143)
		(layer "In6.Cu")
		(net "P5E_CPU0_P2_RX_DP<13>")
	)
	(segment
		(start 372.97995 -283.31414)
		(end 372.977918 -283.31287)
		(width 0.1143)
		(layer "In6.Cu")
		(net "P5E_CPU0_P2_RX_DP<13>")
	)
	(segment
		(start 401.581366 -364.286546)
		(end 395.051788 -348.523306)
		(width 0.14224)
		(layer "In6.Cu")
		(net "P5E_CPU0_P2_RX_DP<13>")
	)
	(segment
		(start 372.976902 -284.932374)
		(end 372.975632 -284.931612)
		(width 0.1143)
		(layer "In6.Cu")
		(net "P5E_CPU0_P2_RX_DP<13>")
	)
	(segment
		(start 372.98122 -294.654732)
		(end 372.97995 -294.65397)
		(width 0.1143)
		(layer "In6.Cu")
		(net "P5E_CPU0_P2_RX_DP<13>")
	)
	(segment
		(start 372.975632 -291.411406)
		(end 372.956074 -291.40023)
		(width 0.1143)
		(layer "In6.Cu")
		(net "P5E_CPU0_P2_RX_DP<13>")
	)
	(segment
		(start 372.987824 -287.533588)
		(end 373.0244 -287.512252)
		(width 0.1143)
		(layer "In6.Cu")
		(net "P5E_CPU0_P2_RX_DP<13>")
	)
	(segment
		(start 372.984268 -284.936692)
		(end 372.983506 -284.936184)
		(width 0.1143)
		(layer "In6.Cu")
		(net "P5E_CPU0_P2_RX_DP<13>")
	)
	(segment
		(start 372.98884 -289.152838)
		(end 372.990364 -289.151822)
		(width 0.1143)
		(layer "In6.Cu")
		(net "P5E_CPU0_P2_RX_DP<13>")
	)
	(segment
		(start 372.987062 -294.01389)
		(end 372.987824 -294.013382)
		(width 0.1143)
		(layer "In6.Cu")
		(net "P5E_CPU0_P2_RX_DP<13>")
	)
	(segment
		(start 372.956074 -289.171634)
		(end 372.985792 -289.154616)
		(width 0.1143)
		(layer "In6.Cu")
		(net "P5E_CPU0_P2_RX_DP<13>")
	)
	(segment
		(start 372.990364 -289.80003)
		(end 372.98884 -289.799014)
		(width 0.1143)
		(layer "In6.Cu")
		(net "P5E_CPU0_P2_RX_DP<13>")
	)
	(segment
		(start 373.785892 -296.486072)
		(end 373.785892 -296.372534)
		(width 0.14224)
		(layer "In6.Cu")
		(net "P5E_CPU0_P2_RX_DP<13>")
	)
	(segment
		(start 372.990364 -291.420042)
		(end 372.98884 -291.419026)
		(width 0.1143)
		(layer "In6.Cu")
		(net "P5E_CPU0_P2_RX_DP<13>")
	)
	(segment
		(start 372.98884 -294.65905)
		(end 372.987824 -294.658542)
		(width 0.1143)
		(layer "In6.Cu")
		(net "P5E_CPU0_P2_RX_DP<13>")
	)
	(segment
		(start 376.590814 -301.346362)
		(end 374.301512 -297.920156)
		(width 0.14224)
		(layer "In6.Cu")
		(net "P5E_CPU0_P2_RX_DP<13>")
	)
	(segment
		(start 372.990364 -283.320236)
		(end 372.98884 -283.31922)
		(width 0.1143)
		(layer "In6.Cu")
		(net "P5E_CPU0_P2_RX_DP<13>")
	)
	(segment
		(start 372.985792 -282.674822)
		(end 372.987062 -282.67406)
		(width 0.1143)
		(layer "In6.Cu")
		(net "P5E_CPU0_P2_RX_DP<13>")
	)
	(segment
		(start 410.245814 -369.599972)
		(end 402.628608 -365.288576)
		(width 0.14224)
		(layer "In6.Cu")
		(net "P5E_CPU0_P2_RX_DP<13>")
	)
	(segment
		(start 410.246068 -369.600226)
		(end 410.245814 -369.599972)
		(width 0.14224)
		(layer "In6.Cu")
		(net "P5E_CPU0_P2_RX_DP<13>")
	)
	(segment
		(start 372.981982 -284.935422)
		(end 372.98122 -284.934914)
		(width 0.1143)
		(layer "In6.Cu")
		(net "P5E_CPU0_P2_RX_DP<13>")
	)
	(segment
		(start 372.956074 -294.03167)
		(end 372.985792 -294.014652)
		(width 0.1143)
		(layer "In6.Cu")
		(net "P5E_CPU0_P2_RX_DP<13>")
	)
	(segment
		(start 374.301512 -297.920156)
		(end 373.7864 -296.676826)
		(width 0.14224)
		(layer "In6.Cu")
		(net "P5E_CPU0_P2_RX_DP<13>")
	)
	(segment
		(start 372.987062 -292.393878)
		(end 372.987824 -292.39337)
		(width 0.1143)
		(layer "In6.Cu")
		(net "P5E_CPU0_P2_RX_DP<13>")
	)
	(segment
		(start 372.987062 -290.773866)
		(end 372.987824 -290.773358)
		(width 0.1143)
		(layer "In6.Cu")
		(net "P5E_CPU0_P2_RX_DP<13>")
	)
	(arc
		(start 393.564872 -341.441278)
		(mid 393.563836 -341.435203)
		(end 393.563094 -341.429086)
		(width 0.14224)
		(layer "In6.Cu")
		(net "P5E_CPU0_P2_RX_DP<13>")
	)
	(arc
		(start 402.628608 -365.288576)
		(mid 402.562258 -365.247981)
		(end 402.498814 -365.202978)
		(width 0.14224)
		(layer "In6.Cu")
		(net "P5E_CPU0_P2_RX_DP<13>")
	)
	(arc
		(start 419.768274 -391.263886)
		(mid 419.797961 -390.962564)
		(end 419.885876 -390.672828)
		(width 0.14224)
		(layer "In6.Cu")
		(net "P5E_CPU0_P2_RX_DP<13>")
	)
	(arc
		(start 373.427244 -285.73095)
		(mid 373.311817 -285.597574)
		(end 373.270272 -285.42615)
		(width 0.1143)
		(layer "In6.Cu")
		(net "P5E_CPU0_P2_RX_DP<13>")
	)
	(arc
		(start 373.270272 -285.42615)
		(mid 373.205757 -285.163931)
		(end 373.02694 -284.961584)
		(width 0.1143)
		(layer "In6.Cu")
		(net "P5E_CPU0_P2_RX_DP<13>")
	)
	(arc
		(start 426.5041 -377.36145)
		(mid 426.376906 -376.804096)
		(end 426.020484 -376.357134)
		(width 0.14224)
		(layer "In6.Cu")
		(net "P5E_CPU0_P2_RX_DP<13>")
	)
	(arc
		(start 373.427244 -295.450768)
		(mid 373.311817 -295.317392)
		(end 373.270272 -295.145968)
		(width 0.1143)
		(layer "In6.Cu")
		(net "P5E_CPU0_P2_RX_DP<13>")
	)
	(arc
		(start 424.048428 -374.783858)
		(mid 422.062885 -373.442219)
		(end 419.890702 -372.430294)
		(width 0.14224)
		(layer "In6.Cu")
		(net "P5E_CPU0_P2_RX_DP<13>")
	)
	(arc
		(start 372.956074 -291.40023)
		(mid 372.800146 -291.095938)
		(end 372.956074 -290.791646)
		(width 0.1143)
		(layer "In6.Cu")
		(net "P5E_CPU0_P2_RX_DP<13>")
	)
	(arc
		(start 395.051788 -348.523052)
		(mid 394.919557 -348.153615)
		(end 394.824204 -347.77299)
		(width 0.14224)
		(layer "In6.Cu")
		(net "P5E_CPU0_P2_RX_DP<13>")
	)
	(arc
		(start 373.02694 -284.270704)
		(mid 373.270267 -283.806138)
		(end 373.02694 -283.341572)
		(width 0.1143)
		(layer "In6.Cu")
		(net "P5E_CPU0_P2_RX_DP<13>")
	)
	(arc
		(start 373.02694 -282.650692)
		(mid 373.205753 -282.448342)
		(end 373.270272 -282.186126)
		(width 0.1143)
		(layer "In6.Cu")
		(net "P5E_CPU0_P2_RX_DP<13>")
	)
	(arc
		(start 372.800118 -287.856168)
		(mid 372.841373 -287.685197)
		(end 372.956074 -287.551876)
		(width 0.1143)
		(layer "In6.Cu")
		(net "P5E_CPU0_P2_RX_DP<13>")
	)
	(arc
		(start 402.498814 -365.202978)
		(mid 402.438671 -365.153896)
		(end 402.381974 -365.10087)
		(width 0.14224)
		(layer "In6.Cu")
		(net "P5E_CPU0_P2_RX_DP<13>")
	)
	(arc
		(start 373.02694 -293.990522)
		(mid 373.270267 -293.525956)
		(end 373.02694 -293.06139)
		(width 0.1143)
		(layer "In6.Cu")
		(net "P5E_CPU0_P2_RX_DP<13>")
	)
	(arc
		(start 373.528336 -295.514776)
		(mid 373.51279 -295.502819)
		(end 373.49684 -295.491408)
		(width 0.1143)
		(layer "In6.Cu")
		(net "P5E_CPU0_P2_RX_DP<13>")
	)
	(arc
		(start 373.49684 -281.840686)
		(mid 373.648827 -281.684178)
		(end 373.730266 -281.481784)
		(width 0.1143)
		(layer "In6.Cu")
		(net "P5E_CPU0_P2_RX_DP<13>")
	)
	(arc
		(start 372.956074 -284.920436)
		(mid 372.800146 -284.616144)
		(end 372.956074 -284.311852)
		(width 0.1143)
		(layer "In6.Cu")
		(net "P5E_CPU0_P2_RX_DP<13>")
	)
	(arc
		(start 373.740172 -295.955974)
		(mid 373.684472 -295.711262)
		(end 373.528336 -295.514776)
		(width 0.1143)
		(layer "In6.Cu")
		(net "P5E_CPU0_P2_RX_DP<13>")
	)
	(arc
		(start 426.384212 -378.483368)
		(mid 426.472956 -378.350648)
		(end 426.5041 -378.194062)
		(width 0.14224)
		(layer "In6.Cu")
		(net "P5E_CPU0_P2_RX_DP<13>")
	)
	(arc
		(start 372.954296 -288.158936)
		(mid 372.840889 -288.026047)
		(end 372.800118 -287.856168)
		(width 0.1143)
		(layer "In6.Cu")
		(net "P5E_CPU0_P2_RX_DP<13>")
	)
	(arc
		(start 372.956074 -283.300424)
		(mid 372.800146 -282.996132)
		(end 372.956074 -282.69184)
		(width 0.1143)
		(layer "In6.Cu")
		(net "P5E_CPU0_P2_RX_DP<13>")
	)
	(arc
		(start 373.270272 -287.045908)
		(mid 373.311238 -286.875502)
		(end 373.425212 -286.742378)
		(width 0.1143)
		(layer "In6.Cu")
		(net "P5E_CPU0_P2_RX_DP<13>")
	)
	(arc
		(start 410.733494 -369.796314)
		(mid 410.48318 -369.714677)
		(end 410.246068 -369.600226)
		(width 0.14224)
		(layer "In6.Cu")
		(net "P5E_CPU0_P2_RX_DP<13>")
	)
	(arc
		(start 373.02694 -292.37051)
		(mid 373.270267 -291.905944)
		(end 373.02694 -291.441378)
		(width 0.1143)
		(layer "In6.Cu")
		(net "P5E_CPU0_P2_RX_DP<13>")
	)
	(arc
		(start 373.49684 -286.700722)
		(mid 373.740167 -286.236156)
		(end 373.49684 -285.77159)
		(width 0.1143)
		(layer "In6.Cu")
		(net "P5E_CPU0_P2_RX_DP<13>")
	)
	(arc
		(start 423.851578 -381.098806)
		(mid 423.922812 -380.96559)
		(end 424.01871 -380.84887)
		(width 0.14224)
		(layer "In6.Cu")
		(net "P5E_CPU0_P2_RX_DP<13>")
	)
	(arc
		(start 372.956074 -289.780218)
		(mid 372.800146 -289.475926)
		(end 372.956074 -289.171634)
		(width 0.1143)
		(layer "In6.Cu")
		(net "P5E_CPU0_P2_RX_DP<13>")
	)
	(arc
		(start 417.317174 -371.471952)
		(mid 417.249066 -371.449335)
		(end 417.180014 -371.429788)
		(width 0.14224)
		(layer "In6.Cu")
		(net "P5E_CPU0_P2_RX_DP<13>")
	)
	(arc
		(start 372.956074 -293.020242)
		(mid 372.800146 -292.71595)
		(end 372.956074 -292.411658)
		(width 0.1143)
		(layer "In6.Cu")
		(net "P5E_CPU0_P2_RX_DP<13>")
	)
	(arc
		(start 401.609052 -364.327948)
		(mid 401.593181 -364.308605)
		(end 401.581366 -364.286546)
		(width 0.14224)
		(layer "In6.Cu")
		(net "P5E_CPU0_P2_RX_DP<13>")
	)
	(arc
		(start 373.0244 -287.512252)
		(mid 373.205052 -287.309507)
		(end 373.270272 -287.045908)
		(width 0.1143)
		(layer "In6.Cu")
		(net "P5E_CPU0_P2_RX_DP<13>")
	)
	(arc
		(start 372.956074 -294.640254)
		(mid 372.800146 -294.335962)
		(end 372.956074 -294.03167)
		(width 0.1143)
		(layer "In6.Cu")
		(net "P5E_CPU0_P2_RX_DP<13>")
	)
	(arc
		(start 373.730266 -281.481784)
		(mid 373.732289 -281.470374)
		(end 373.734076 -281.458924)
		(width 0.1143)
		(layer "In6.Cu")
		(net "P5E_CPU0_P2_RX_DP<13>")
	)
	(arc
		(start 373.270272 -282.186126)
		(mid 373.311821 -282.014704)
		(end 373.427244 -281.881326)
		(width 0.1143)
		(layer "In6.Cu")
		(net "P5E_CPU0_P2_RX_DP<13>")
	)
	(arc
		(start 417.526724 -371.548914)
		(mid 417.42208 -371.510075)
		(end 417.317174 -371.471952)
		(width 0.14224)
		(layer "In6.Cu")
		(net "P5E_CPU0_P2_RX_DP<13>")
	)
	(arc
		(start 373.02694 -290.750498)
		(mid 373.270267 -290.285932)
		(end 373.02694 -289.821366)
		(width 0.1143)
		(layer "In6.Cu")
		(net "P5E_CPU0_P2_RX_DP<13>")
	)
	(arc
		(start 373.270272 -295.145968)
		(mid 373.205757 -294.883749)
		(end 373.02694 -294.681402)
		(width 0.1143)
		(layer "In6.Cu")
		(net "P5E_CPU0_P2_RX_DP<13>")
	)
	(arc
		(start 373.02694 -289.130486)
		(mid 373.270267 -288.66592)
		(end 373.02694 -288.201354)
		(width 0.1143)
		(layer "In6.Cu")
		(net "P5E_CPU0_P2_RX_DP<13>")
	)
	(segment
		(start 417.698174 -394.385292)
		(end 418.218874 -394.385292)
		(width 0.127)
		(layer "F.Cu")
		(net "P5E_CPU0_P2_RX_DP<12>")
	)
	(segment
		(start 370.828062 -282.730194)
		(end 371.294914 -282.996132)
		(width 0.12954)
		(layer "F.Cu")
		(net "P5E_CPU0_P2_RX_DP<12>")
	)
	(segment
		(start 372.846346 -296.348658)
		(end 372.800626 -296.302938)
		(width 0.1143)
		(layer "In6.Cu")
		(net "P5E_CPU0_P2_RX_DP<12>")
	)
	(segment
		(start 371.577108 -284.12821)
		(end 371.54612 -284.11043)
		(width 0.1143)
		(layer "In6.Cu")
		(net "P5E_CPU0_P2_RX_DP<12>")
	)
	(segment
		(start 418.31387 -394.031216)
		(end 418.488114 -393.930632)
		(width 0.14224)
		(layer "In6.Cu")
		(net "P5E_CPU0_P2_RX_DP<12>")
	)
	(segment
		(start 402.279866 -366.31753)
		(end 400.799046 -364.83671)
		(width 0.14224)
		(layer "In6.Cu")
		(net "P5E_CPU0_P2_RX_DP<12>")
	)
	(segment
		(start 393.935966 -348.189296)
		(end 392.636756 -341.657686)
		(width 0.14224)
		(layer "In6.Cu")
		(net "P5E_CPU0_P2_RX_DP<12>")
	)
	(segment
		(start 372.513606 -285.74619)
		(end 372.512844 -285.745682)
		(width 0.1143)
		(layer "In6.Cu")
		(net "P5E_CPU0_P2_RX_DP<12>")
	)
	(segment
		(start 392.61669 -341.52205)
		(end 392.171174 -336.999834)
		(width 0.14224)
		(layer "In6.Cu")
		(net "P5E_CPU0_P2_RX_DP<12>")
	)
	(segment
		(start 370.927122 -283.065982)
		(end 370.996972 -282.996132)
		(width 0.1143)
		(layer "In6.Cu")
		(net "P5E_CPU0_P2_RX_DP<12>")
	)
	(segment
		(start 372.01729 -290.791138)
		(end 372.086886 -290.750498)
		(width 0.1143)
		(layer "In6.Cu")
		(net "P5E_CPU0_P2_RX_DP<12>")
	)
	(segment
		(start 372.524274 -285.752286)
		(end 372.52021 -285.75)
		(width 0.1143)
		(layer "In6.Cu")
		(net "P5E_CPU0_P2_RX_DP<12>")
	)
	(segment
		(start 372.509542 -285.743904)
		(end 372.486174 -285.730442)
		(width 0.1143)
		(layer "In6.Cu")
		(net "P5E_CPU0_P2_RX_DP<12>")
	)
	(segment
		(start 418.260276 -393.113006)
		(end 418.263324 -392.7348)
		(width 0.14224)
		(layer "In6.Cu")
		(net "P5E_CPU0_P2_RX_DP<12>")
	)
	(segment
		(start 372.01729 -289.171126)
		(end 372.086886 -289.130486)
		(width 0.1143)
		(layer "In6.Cu")
		(net "P5E_CPU0_P2_RX_DP<12>")
	)
	(segment
		(start 372.800626 -296.302938)
		(end 372.800626 -295.956482)
		(width 0.1143)
		(layer "In6.Cu")
		(net "P5E_CPU0_P2_RX_DP<12>")
	)
	(segment
		(start 372.086886 -293.06139)
		(end 372.01729 -293.02075)
		(width 0.1143)
		(layer "In6.Cu")
		(net "P5E_CPU0_P2_RX_DP<12>")
	)
	(segment
		(start 372.086886 -284.961584)
		(end 372.01729 -284.920944)
		(width 0.1143)
		(layer "In6.Cu")
		(net "P5E_CPU0_P2_RX_DP<12>")
	)
	(segment
		(start 372.484396 -286.74314)
		(end 372.55704 -286.700722)
		(width 0.1143)
		(layer "In6.Cu")
		(net "P5E_CPU0_P2_RX_DP<12>")
	)
	(segment
		(start 372.01729 -292.41115)
		(end 372.086886 -292.37051)
		(width 0.1143)
		(layer "In6.Cu")
		(net "P5E_CPU0_P2_RX_DP<12>")
	)
	(segment
		(start 418.576252 -393.842494)
		(end 418.576252 -393.428982)
		(width 0.14224)
		(layer "In6.Cu")
		(net "P5E_CPU0_P2_RX_DP<12>")
	)
	(segment
		(start 371.583204 -284.131766)
		(end 371.582188 -284.131258)
		(width 0.1143)
		(layer "In6.Cu")
		(net "P5E_CPU0_P2_RX_DP<12>")
	)
	(segment
		(start 372.086886 -289.821366)
		(end 372.01729 -289.780726)
		(width 0.1143)
		(layer "In6.Cu")
		(net "P5E_CPU0_P2_RX_DP<12>")
	)
	(segment
		(start 372.086886 -294.681402)
		(end 372.01729 -294.640762)
		(width 0.1143)
		(layer "In6.Cu")
		(net "P5E_CPU0_P2_RX_DP<12>")
	)
	(segment
		(start 372.846346 -296.843704)
		(end 372.846346 -296.377106)
		(width 0.14224)
		(layer "In6.Cu")
		(net "P5E_CPU0_P2_RX_DP<12>")
	)
	(segment
		(start 373.47525 -298.361862)
		(end 372.846346 -296.843704)
		(width 0.14224)
		(layer "In6.Cu")
		(net "P5E_CPU0_P2_RX_DP<12>")
	)
	(segment
		(start 372.846346 -296.377106)
		(end 372.846346 -296.348658)
		(width 0.1143)
		(layer "In6.Cu")
		(net "P5E_CPU0_P2_RX_DP<12>")
	)
	(segment
		(start 371.610128 -284.147514)
		(end 371.609366 -284.147006)
		(width 0.1143)
		(layer "In6.Cu")
		(net "P5E_CPU0_P2_RX_DP<12>")
	)
	(segment
		(start 370.996972 -282.996132)
		(end 371.294914 -282.996132)
		(width 0.1143)
		(layer "In6.Cu")
		(net "P5E_CPU0_P2_RX_DP<12>")
	)
	(segment
		(start 372.01729 -287.551368)
		(end 372.084346 -287.512252)
		(width 0.1143)
		(layer "In6.Cu")
		(net "P5E_CPU0_P2_RX_DP<12>")
	)
	(segment
		(start 372.800626 -295.956482)
		(end 372.800118 -295.955974)
		(width 0.1143)
		(layer "In6.Cu")
		(net "P5E_CPU0_P2_RX_DP<12>")
	)
	(segment
		(start 423.009568 -380.28499)
		(end 423.009822 -380.284482)
		(width 0.14224)
		(layer "In6.Cu")
		(net "P5E_CPU0_P2_RX_DP<12>")
	)
	(segment
		(start 392.171174 -336.999834)
		(end 389.31469 -322.638928)
		(width 0.14224)
		(layer "In6.Cu")
		(net "P5E_CPU0_P2_RX_DP<12>")
	)
	(segment
		(start 418.263324 -392.7348)
		(end 418.568124 -392.43)
		(width 0.14224)
		(layer "In6.Cu")
		(net "P5E_CPU0_P2_RX_DP<12>")
	)
	(segment
		(start 400.799046 -364.83671)
		(end 400.799046 -364.836456)
		(width 0.14224)
		(layer "In6.Cu")
		(net "P5E_CPU0_P2_RX_DP<12>")
	)
	(segment
		(start 372.086886 -288.201354)
		(end 372.015258 -288.159698)
		(width 0.1143)
		(layer "In6.Cu")
		(net "P5E_CPU0_P2_RX_DP<12>")
	)
	(segment
		(start 371.144292 -283.339794)
		(end 371.07622 -283.300424)
		(width 0.1143)
		(layer "In6.Cu")
		(net "P5E_CPU0_P2_RX_DP<12>")
	)
	(segment
		(start 418.577776 -390.9695)
		(end 423.009568 -380.28499)
		(width 0.14224)
		(layer "In6.Cu")
		(net "P5E_CPU0_P2_RX_DP<12>")
	)
	(segment
		(start 372.086886 -291.441378)
		(end 372.01729 -291.400738)
		(width 0.1143)
		(layer "In6.Cu")
		(net "P5E_CPU0_P2_RX_DP<12>")
	)
	(segment
		(start 415.921952 -372.097554)
		(end 409.711906 -370.543074)
		(width 0.14224)
		(layer "In6.Cu")
		(net "P5E_CPU0_P2_RX_DP<12>")
	)
	(segment
		(start 422.660572 -375.945908)
		(end 422.58742 -375.872756)
		(width 0.14224)
		(layer "In6.Cu")
		(net "P5E_CPU0_P2_RX_DP<12>")
	)
	(segment
		(start 400.77136 -364.795054)
		(end 394.053568 -348.576392)
		(width 0.14224)
		(layer "In6.Cu")
		(net "P5E_CPU0_P2_RX_DP<12>")
	)
	(segment
		(start 371.616986 -284.151578)
		(end 371.610128 -284.147514)
		(width 0.1143)
		(layer "In6.Cu")
		(net "P5E_CPU0_P2_RX_DP<12>")
	)
	(segment
		(start 389.31469 -322.638928)
		(end 383.101596 -311.014872)
		(width 0.14224)
		(layer "In6.Cu")
		(net "P5E_CPU0_P2_RX_DP<12>")
	)
	(segment
		(start 371.582188 -284.131258)
		(end 371.580664 -284.130242)
		(width 0.1143)
		(layer "In6.Cu")
		(net "P5E_CPU0_P2_RX_DP<12>")
	)
	(segment
		(start 372.51767 -295.468548)
		(end 372.48719 -295.450768)
		(width 0.1143)
		(layer "In6.Cu")
		(net "P5E_CPU0_P2_RX_DP<12>")
	)
	(segment
		(start 418.488114 -393.930632)
		(end 418.576252 -393.842494)
		(width 0.14224)
		(layer "In6.Cu")
		(net "P5E_CPU0_P2_RX_DP<12>")
	)
	(segment
		(start 383.101596 -311.014872)
		(end 382.18618 -309.645304)
		(width 0.14224)
		(layer "In6.Cu")
		(net "P5E_CPU0_P2_RX_DP<12>")
	)
	(segment
		(start 372.517162 -285.748222)
		(end 372.513606 -285.74619)
		(width 0.1143)
		(layer "In6.Cu")
		(net "P5E_CPU0_P2_RX_DP<12>")
	)
	(segment
		(start 372.512844 -285.745682)
		(end 372.511574 -285.74492)
		(width 0.1143)
		(layer "In6.Cu")
		(net "P5E_CPU0_P2_RX_DP<12>")
	)
	(segment
		(start 423.04081 -380.12751)
		(end 423.04081 -376.864118)
		(width 0.14224)
		(layer "In6.Cu")
		(net "P5E_CPU0_P2_RX_DP<12>")
	)
	(segment
		(start 371.609366 -284.147006)
		(end 371.584728 -284.132782)
		(width 0.1143)
		(layer "In6.Cu")
		(net "P5E_CPU0_P2_RX_DP<12>")
	)
	(segment
		(start 375.874026 -301.951644)
		(end 373.47525 -298.361862)
		(width 0.14224)
		(layer "In6.Cu")
		(net "P5E_CPU0_P2_RX_DP<12>")
	)
	(segment
		(start 415.922206 -372.097554)
		(end 415.921952 -372.097554)
		(width 0.14224)
		(layer "In6.Cu")
		(net "P5E_CPU0_P2_RX_DP<12>")
	)
	(segment
		(start 372.55704 -285.77159)
		(end 372.524274 -285.752286)
		(width 0.1143)
		(layer "In6.Cu")
		(net "P5E_CPU0_P2_RX_DP<12>")
	)
	(segment
		(start 409.711906 -370.543074)
		(end 402.368766 -366.385094)
		(width 0.14224)
		(layer "In6.Cu")
		(net "P5E_CPU0_P2_RX_DP<12>")
	)
	(segment
		(start 372.556786 -295.491408)
		(end 372.51767 -295.468548)
		(width 0.1143)
		(layer "In6.Cu")
		(net "P5E_CPU0_P2_RX_DP<12>")
	)
	(segment
		(start 372.52021 -285.75)
		(end 372.517162 -285.748222)
		(width 0.1143)
		(layer "In6.Cu")
		(net "P5E_CPU0_P2_RX_DP<12>")
	)
	(segment
		(start 418.218874 -394.385292)
		(end 418.31387 -394.031216)
		(width 0.14224)
		(layer "In6.Cu")
		(net "P5E_CPU0_P2_RX_DP<12>")
	)
	(segment
		(start 371.580664 -284.130242)
		(end 371.577108 -284.12821)
		(width 0.1143)
		(layer "In6.Cu")
		(net "P5E_CPU0_P2_RX_DP<12>")
	)
	(segment
		(start 423.009822 -380.284482)
		(end 423.009568 -380.284482)
		(width 0.14224)
		(layer "In6.Cu")
		(net "P5E_CPU0_P2_RX_DP<12>")
	)
	(segment
		(start 382.18618 -309.645304)
		(end 382.18618 -309.64505)
		(width 0.14224)
		(layer "In6.Cu")
		(net "P5E_CPU0_P2_RX_DP<12>")
	)
	(segment
		(start 382.18618 -309.64505)
		(end 382.17856 -309.633874)
		(width 0.14224)
		(layer "In6.Cu")
		(net "P5E_CPU0_P2_RX_DP<12>")
	)
	(segment
		(start 371.584728 -284.132782)
		(end 371.583204 -284.131766)
		(width 0.1143)
		(layer "In6.Cu")
		(net "P5E_CPU0_P2_RX_DP<12>")
	)
	(segment
		(start 372.511574 -285.74492)
		(end 372.509542 -285.743904)
		(width 0.1143)
		(layer "In6.Cu")
		(net "P5E_CPU0_P2_RX_DP<12>")
	)
	(segment
		(start 418.576252 -393.428982)
		(end 418.260276 -393.113006)
		(width 0.14224)
		(layer "In6.Cu")
		(net "P5E_CPU0_P2_RX_DP<12>")
	)
	(segment
		(start 418.568124 -392.43)
		(end 418.568124 -391.018268)
		(width 0.14224)
		(layer "In6.Cu")
		(net "P5E_CPU0_P2_RX_DP<12>")
	)
	(segment
		(start 382.17856 -309.633874)
		(end 375.874026 -301.951644)
		(width 0.14224)
		(layer "In6.Cu")
		(net "P5E_CPU0_P2_RX_DP<12>")
	)
	(segment
		(start 372.01729 -294.031162)
		(end 372.086886 -293.990522)
		(width 0.1143)
		(layer "In6.Cu")
		(net "P5E_CPU0_P2_RX_DP<12>")
	)
	(arc
		(start 392.636756 -341.657686)
		(mid 392.625062 -341.590114)
		(end 392.61669 -341.52205)
		(width 0.14224)
		(layer "In6.Cu")
		(net "P5E_CPU0_P2_RX_DP<12>")
	)
	(arc
		(start 371.54612 -284.11043)
		(mid 371.432962 -283.980028)
		(end 371.390164 -283.812742)
		(width 0.1143)
		(layer "In6.Cu")
		(net "P5E_CPU0_P2_RX_DP<12>")
	)
	(arc
		(start 372.01729 -291.400738)
		(mid 371.860313 -291.095938)
		(end 372.01729 -290.791138)
		(width 0.1143)
		(layer "In6.Cu")
		(net "P5E_CPU0_P2_RX_DP<12>")
	)
	(arc
		(start 371.860318 -287.856168)
		(mid 371.901867 -287.684746)
		(end 372.01729 -287.551368)
		(width 0.1143)
		(layer "In6.Cu")
		(net "P5E_CPU0_P2_RX_DP<12>")
	)
	(arc
		(start 423.009568 -380.284482)
		(mid 423.032924 -380.207535)
		(end 423.04081 -380.12751)
		(width 0.14224)
		(layer "In6.Cu")
		(net "P5E_CPU0_P2_RX_DP<12>")
	)
	(arc
		(start 402.368766 -366.385094)
		(mid 402.322034 -366.354315)
		(end 402.279866 -366.31753)
		(width 0.14224)
		(layer "In6.Cu")
		(net "P5E_CPU0_P2_RX_DP<12>")
	)
	(arc
		(start 372.086886 -292.37051)
		(mid 372.330213 -291.905944)
		(end 372.086886 -291.441378)
		(width 0.1143)
		(layer "In6.Cu")
		(net "P5E_CPU0_P2_RX_DP<12>")
	)
	(arc
		(start 372.55704 -286.700722)
		(mid 372.800367 -286.236156)
		(end 372.55704 -285.77159)
		(width 0.1143)
		(layer "In6.Cu")
		(net "P5E_CPU0_P2_RX_DP<12>")
	)
	(arc
		(start 400.799046 -364.836456)
		(mid 400.783175 -364.817113)
		(end 400.77136 -364.795054)
		(width 0.14224)
		(layer "In6.Cu")
		(net "P5E_CPU0_P2_RX_DP<12>")
	)
	(arc
		(start 372.086886 -290.750498)
		(mid 372.330213 -290.285932)
		(end 372.086886 -289.821366)
		(width 0.1143)
		(layer "In6.Cu")
		(net "P5E_CPU0_P2_RX_DP<12>")
	)
	(arc
		(start 372.588282 -295.514776)
		(mid 372.572736 -295.502819)
		(end 372.556786 -295.491408)
		(width 0.1143)
		(layer "In6.Cu")
		(net "P5E_CPU0_P2_RX_DP<12>")
	)
	(arc
		(start 371.389402 -283.796486)
		(mid 371.387889 -283.782753)
		(end 371.3861 -283.769054)
		(width 0.1143)
		(layer "In6.Cu")
		(net "P5E_CPU0_P2_RX_DP<12>")
	)
	(arc
		(start 372.086886 -293.990522)
		(mid 372.330213 -293.525956)
		(end 372.086886 -293.06139)
		(width 0.1143)
		(layer "In6.Cu")
		(net "P5E_CPU0_P2_RX_DP<12>")
	)
	(arc
		(start 372.330218 -295.145968)
		(mid 372.265703 -294.883749)
		(end 372.086886 -294.681402)
		(width 0.1143)
		(layer "In6.Cu")
		(net "P5E_CPU0_P2_RX_DP<12>")
	)
	(arc
		(start 371.3861 -283.769054)
		(mid 371.30519 -283.531893)
		(end 371.144292 -283.339794)
		(width 0.1143)
		(layer "In6.Cu")
		(net "P5E_CPU0_P2_RX_DP<12>")
	)
	(arc
		(start 372.086886 -289.130486)
		(mid 372.330213 -288.66592)
		(end 372.086886 -288.201354)
		(width 0.1143)
		(layer "In6.Cu")
		(net "P5E_CPU0_P2_RX_DP<12>")
	)
	(arc
		(start 372.330218 -285.42615)
		(mid 372.265703 -285.163931)
		(end 372.086886 -284.961584)
		(width 0.1143)
		(layer "In6.Cu")
		(net "P5E_CPU0_P2_RX_DP<12>")
	)
	(arc
		(start 371.390164 -283.812742)
		(mid 371.389954 -283.804606)
		(end 371.389402 -283.796486)
		(width 0.1143)
		(layer "In6.Cu")
		(net "P5E_CPU0_P2_RX_DP<12>")
	)
	(arc
		(start 372.084346 -287.512252)
		(mid 372.264998 -287.309507)
		(end 372.330218 -287.045908)
		(width 0.1143)
		(layer "In6.Cu")
		(net "P5E_CPU0_P2_RX_DP<12>")
	)
	(arc
		(start 394.053568 -348.576392)
		(mid 393.985267 -348.385731)
		(end 393.935966 -348.189296)
		(width 0.14224)
		(layer "In6.Cu")
		(net "P5E_CPU0_P2_RX_DP<12>")
	)
	(arc
		(start 418.568124 -391.018268)
		(mid 418.570526 -390.993402)
		(end 418.577776 -390.9695)
		(width 0.14224)
		(layer "In6.Cu")
		(net "P5E_CPU0_P2_RX_DP<12>")
	)
	(arc
		(start 372.48719 -295.450768)
		(mid 372.371763 -295.317392)
		(end 372.330218 -295.145968)
		(width 0.1143)
		(layer "In6.Cu")
		(net "P5E_CPU0_P2_RX_DP<12>")
	)
	(arc
		(start 423.04081 -376.864118)
		(mid 422.941987 -376.367209)
		(end 422.660572 -375.945908)
		(width 0.14224)
		(layer "In6.Cu")
		(net "P5E_CPU0_P2_RX_DP<12>")
	)
	(arc
		(start 372.800118 -295.955974)
		(mid 372.744418 -295.711262)
		(end 372.588282 -295.514776)
		(width 0.1143)
		(layer "In6.Cu")
		(net "P5E_CPU0_P2_RX_DP<12>")
	)
	(arc
		(start 371.860318 -284.616144)
		(mid 371.795803 -284.353925)
		(end 371.616986 -284.151578)
		(width 0.1143)
		(layer "In6.Cu")
		(net "P5E_CPU0_P2_RX_DP<12>")
	)
	(arc
		(start 372.015258 -288.159698)
		(mid 371.901329 -288.026551)
		(end 371.860318 -287.856168)
		(width 0.1143)
		(layer "In6.Cu")
		(net "P5E_CPU0_P2_RX_DP<12>")
	)
	(arc
		(start 372.01729 -284.920944)
		(mid 371.901863 -284.787568)
		(end 371.860318 -284.616144)
		(width 0.1143)
		(layer "In6.Cu")
		(net "P5E_CPU0_P2_RX_DP<12>")
	)
	(arc
		(start 372.01729 -293.02075)
		(mid 371.860313 -292.71595)
		(end 372.01729 -292.41115)
		(width 0.1143)
		(layer "In6.Cu")
		(net "P5E_CPU0_P2_RX_DP<12>")
	)
	(arc
		(start 372.01729 -289.780726)
		(mid 371.860313 -289.475926)
		(end 372.01729 -289.171126)
		(width 0.1143)
		(layer "In6.Cu")
		(net "P5E_CPU0_P2_RX_DP<12>")
	)
	(arc
		(start 372.486174 -285.730442)
		(mid 372.371498 -285.597108)
		(end 372.330218 -285.42615)
		(width 0.1143)
		(layer "In6.Cu")
		(net "P5E_CPU0_P2_RX_DP<12>")
	)
	(arc
		(start 371.07622 -283.300424)
		(mid 370.979085 -283.197555)
		(end 370.927122 -283.065982)
		(width 0.1143)
		(layer "In6.Cu")
		(net "P5E_CPU0_P2_RX_DP<12>")
	)
	(arc
		(start 422.58742 -375.872756)
		(mid 419.51124 -373.532437)
		(end 415.922206 -372.097554)
		(width 0.14224)
		(layer "In6.Cu")
		(net "P5E_CPU0_P2_RX_DP<12>")
	)
	(arc
		(start 372.01729 -294.640762)
		(mid 371.860313 -294.335962)
		(end 372.01729 -294.031162)
		(width 0.1143)
		(layer "In6.Cu")
		(net "P5E_CPU0_P2_RX_DP<12>")
	)
	(arc
		(start 372.330218 -287.045908)
		(mid 372.37098 -286.876024)
		(end 372.484396 -286.74314)
		(width 0.1143)
		(layer "In6.Cu")
		(net "P5E_CPU0_P2_RX_DP<12>")
	)
	(segment
		(start 370.828062 -284.350206)
		(end 371.294914 -284.616144)
		(width 0.12954)
		(layer "F.Cu")
		(net "P5E_CPU0_P2_RX_DP<11>")
	)
	(segment
		(start 416.498278 -394.385292)
		(end 417.018978 -394.385292)
		(width 0.127)
		(layer "F.Cu")
		(net "P5E_CPU0_P2_RX_DP<11>")
	)
	(segment
		(start 417.376864 -390.954006)
		(end 417.642548 -390.273794)
		(width 0.14224)
		(layer "In6.Cu")
		(net "P5E_CPU0_P2_RX_DP<11>")
	)
	(segment
		(start 371.146832 -291.441378)
		(end 371.107716 -291.418518)
		(width 0.1143)
		(layer "In6.Cu")
		(net "P5E_CPU0_P2_RX_DP<11>")
	)
	(segment
		(start 371.077236 -292.41115)
		(end 371.107716 -292.39337)
		(width 0.1143)
		(layer "In6.Cu")
		(net "P5E_CPU0_P2_RX_DP<11>")
	)
	(segment
		(start 370.927122 -284.685994)
		(end 370.996972 -284.616144)
		(width 0.1143)
		(layer "In6.Cu")
		(net "P5E_CPU0_P2_RX_DP<11>")
	)
	(segment
		(start 417.642548 -390.273794)
		(end 418.6682 -387.797802)
		(width 0.14224)
		(layer "In6.Cu")
		(net "P5E_CPU0_P2_RX_DP<11>")
	)
	(segment
		(start 417.376356 -393.842494)
		(end 417.376356 -393.428982)
		(width 0.14224)
		(layer "In6.Cu")
		(net "P5E_CPU0_P2_RX_DP<11>")
	)
	(segment
		(start 371.077236 -290.791138)
		(end 371.107716 -290.773358)
		(width 0.1143)
		(layer "In6.Cu")
		(net "P5E_CPU0_P2_RX_DP<11>")
	)
	(segment
		(start 371.107716 -293.03853)
		(end 371.077236 -293.02075)
		(width 0.1143)
		(layer "In6.Cu")
		(net "P5E_CPU0_P2_RX_DP<11>")
	)
	(segment
		(start 417.018978 -394.385292)
		(end 417.113974 -394.031216)
		(width 0.14224)
		(layer "In6.Cu")
		(net "P5E_CPU0_P2_RX_DP<11>")
	)
	(segment
		(start 409.367736 -371.42293)
		(end 401.582128 -367.013744)
		(width 0.14224)
		(layer "In6.Cu")
		(net "P5E_CPU0_P2_RX_DP<11>")
	)
	(segment
		(start 401.55495 -366.992916)
		(end 400.019774 -365.45774)
		(width 0.14224)
		(layer "In6.Cu")
		(net "P5E_CPU0_P2_RX_DP<11>")
	)
	(segment
		(start 399.992088 -365.416338)
		(end 393.284964 -349.223838)
		(width 0.14224)
		(layer "In6.Cu")
		(net "P5E_CPU0_P2_RX_DP<11>")
	)
	(segment
		(start 371.077236 -287.551368)
		(end 371.144292 -287.512252)
		(width 0.1143)
		(layer "In6.Cu")
		(net "P5E_CPU0_P2_RX_DP<11>")
	)
	(segment
		(start 417.063428 -392.7348)
		(end 417.368228 -392.43)
		(width 0.14224)
		(layer "In6.Cu")
		(net "P5E_CPU0_P2_RX_DP<11>")
	)
	(segment
		(start 388.435342 -322.997576)
		(end 382.22936 -311.387998)
		(width 0.14224)
		(layer "In6.Cu")
		(net "P5E_CPU0_P2_RX_DP<11>")
	)
	(segment
		(start 381.461518 -310.23941)
		(end 381.461518 -310.239156)
		(width 0.14224)
		(layer "In6.Cu")
		(net "P5E_CPU0_P2_RX_DP<11>")
	)
	(segment
		(start 420.112698 -378.38888)
		(end 419.765734 -378.041916)
		(width 0.14224)
		(layer "In6.Cu")
		(net "P5E_CPU0_P2_RX_DP<11>")
	)
	(segment
		(start 381.461518 -310.239156)
		(end 381.453898 -310.22798)
		(width 0.14224)
		(layer "In6.Cu")
		(net "P5E_CPU0_P2_RX_DP<11>")
	)
	(segment
		(start 421.33901 -381.268224)
		(end 421.33901 -379.36805)
		(width 0.14224)
		(layer "In6.Cu")
		(net "P5E_CPU0_P2_RX_DP<11>")
	)
	(segment
		(start 371.146832 -289.821366)
		(end 371.107716 -289.798506)
		(width 0.1143)
		(layer "In6.Cu")
		(net "P5E_CPU0_P2_RX_DP<11>")
	)
	(segment
		(start 371.906292 -296.325036)
		(end 371.860572 -296.279316)
		(width 0.1143)
		(layer "In6.Cu")
		(net "P5E_CPU0_P2_RX_DP<11>")
	)
	(segment
		(start 371.107716 -284.938724)
		(end 371.077236 -284.920944)
		(width 0.1143)
		(layer "In6.Cu")
		(net "P5E_CPU0_P2_RX_DP<11>")
	)
	(segment
		(start 371.107716 -294.013382)
		(end 371.146832 -293.990522)
		(width 0.1143)
		(layer "In6.Cu")
		(net "P5E_CPU0_P2_RX_DP<11>")
	)
	(segment
		(start 381.453898 -310.22798)
		(end 375.151396 -302.548544)
		(width 0.14224)
		(layer "In6.Cu")
		(net "P5E_CPU0_P2_RX_DP<11>")
	)
	(segment
		(start 371.57787 -295.468548)
		(end 371.54612 -295.45026)
		(width 0.1143)
		(layer "In6.Cu")
		(net "P5E_CPU0_P2_RX_DP<11>")
	)
	(segment
		(start 371.107716 -292.39337)
		(end 371.146832 -292.37051)
		(width 0.1143)
		(layer "In6.Cu")
		(net "P5E_CPU0_P2_RX_DP<11>")
	)
	(segment
		(start 417.288218 -393.930632)
		(end 417.376356 -393.842494)
		(width 0.14224)
		(layer "In6.Cu")
		(net "P5E_CPU0_P2_RX_DP<11>")
	)
	(segment
		(start 371.544342 -286.74314)
		(end 371.614192 -286.7025)
		(width 0.1143)
		(layer "In6.Cu")
		(net "P5E_CPU0_P2_RX_DP<11>")
	)
	(segment
		(start 371.57787 -285.74873)
		(end 371.54612 -285.730442)
		(width 0.1143)
		(layer "In6.Cu")
		(net "P5E_CPU0_P2_RX_DP<11>")
	)
	(segment
		(start 371.146832 -288.201354)
		(end 371.107716 -288.178494)
		(width 0.1143)
		(layer "In6.Cu")
		(net "P5E_CPU0_P2_RX_DP<11>")
	)
	(segment
		(start 371.107716 -291.418518)
		(end 371.077236 -291.400738)
		(width 0.1143)
		(layer "In6.Cu")
		(net "P5E_CPU0_P2_RX_DP<11>")
	)
	(segment
		(start 417.368228 -392.43)
		(end 417.368228 -391.000488)
		(width 0.14224)
		(layer "In6.Cu")
		(net "P5E_CPU0_P2_RX_DP<11>")
	)
	(segment
		(start 391.23874 -337.091782)
		(end 388.435342 -322.997576)
		(width 0.14224)
		(layer "In6.Cu")
		(net "P5E_CPU0_P2_RX_DP<11>")
	)
	(segment
		(start 417.113974 -394.031216)
		(end 417.288218 -393.930632)
		(width 0.14224)
		(layer "In6.Cu")
		(net "P5E_CPU0_P2_RX_DP<11>")
	)
	(segment
		(start 371.077236 -294.031162)
		(end 371.107716 -294.013382)
		(width 0.1143)
		(layer "In6.Cu")
		(net "P5E_CPU0_P2_RX_DP<11>")
	)
	(segment
		(start 372.648988 -298.803568)
		(end 371.906292 -297.010328)
		(width 0.14224)
		(layer "In6.Cu")
		(net "P5E_CPU0_P2_RX_DP<11>")
	)
	(segment
		(start 371.146832 -293.06139)
		(end 371.107716 -293.03853)
		(width 0.1143)
		(layer "In6.Cu")
		(net "P5E_CPU0_P2_RX_DP<11>")
	)
	(segment
		(start 371.860572 -296.007282)
		(end 371.860064 -296.006774)
		(width 0.1143)
		(layer "In6.Cu")
		(net "P5E_CPU0_P2_RX_DP<11>")
	)
	(segment
		(start 371.107716 -288.178494)
		(end 371.075204 -288.159698)
		(width 0.1143)
		(layer "In6.Cu")
		(net "P5E_CPU0_P2_RX_DP<11>")
	)
	(segment
		(start 417.06038 -393.113006)
		(end 417.063428 -392.7348)
		(width 0.14224)
		(layer "In6.Cu")
		(net "P5E_CPU0_P2_RX_DP<11>")
	)
	(segment
		(start 421.166036 -378.950474)
		(end 420.922958 -378.707396)
		(width 0.14224)
		(layer "In6.Cu")
		(net "P5E_CPU0_P2_RX_DP<11>")
	)
	(segment
		(start 375.151396 -302.548544)
		(end 372.648988 -298.803568)
		(width 0.14224)
		(layer "In6.Cu")
		(net "P5E_CPU0_P2_RX_DP<11>")
	)
	(segment
		(start 371.107716 -290.773358)
		(end 371.146832 -290.750498)
		(width 0.1143)
		(layer "In6.Cu")
		(net "P5E_CPU0_P2_RX_DP<11>")
	)
	(segment
		(start 418.6682 -387.797802)
		(end 421.307768 -381.424942)
		(width 0.14224)
		(layer "In6.Cu")
		(net "P5E_CPU0_P2_RX_DP<11>")
	)
	(segment
		(start 370.996972 -284.616144)
		(end 371.294914 -284.616144)
		(width 0.1143)
		(layer "In6.Cu")
		(net "P5E_CPU0_P2_RX_DP<11>")
	)
	(segment
		(start 371.860064 -296.006774)
		(end 371.860064 -295.955974)
		(width 0.1143)
		(layer "In6.Cu")
		(net "P5E_CPU0_P2_RX_DP<11>")
	)
	(segment
		(start 371.906292 -297.010328)
		(end 371.906292 -296.353484)
		(width 0.14224)
		(layer "In6.Cu")
		(net "P5E_CPU0_P2_RX_DP<11>")
	)
	(segment
		(start 371.906292 -296.353484)
		(end 371.906292 -296.325036)
		(width 0.1143)
		(layer "In6.Cu")
		(net "P5E_CPU0_P2_RX_DP<11>")
	)
	(segment
		(start 392.924538 -348.03588)
		(end 391.721594 -341.98814)
		(width 0.14224)
		(layer "In6.Cu")
		(net "P5E_CPU0_P2_RX_DP<11>")
	)
	(segment
		(start 391.719816 -341.975948)
		(end 391.23874 -337.091782)
		(width 0.14224)
		(layer "In6.Cu")
		(net "P5E_CPU0_P2_RX_DP<11>")
	)
	(segment
		(start 417.376356 -393.428982)
		(end 417.06038 -393.113006)
		(width 0.14224)
		(layer "In6.Cu")
		(net "P5E_CPU0_P2_RX_DP<11>")
	)
	(segment
		(start 382.22936 -311.387998)
		(end 381.461518 -310.23941)
		(width 0.14224)
		(layer "In6.Cu")
		(net "P5E_CPU0_P2_RX_DP<11>")
	)
	(segment
		(start 420.52875 -378.544074)
		(end 420.487602 -378.544074)
		(width 0.14224)
		(layer "In6.Cu")
		(net "P5E_CPU0_P2_RX_DP<11>")
	)
	(segment
		(start 419.629844 -377.714002)
		(end 419.629844 -376.632978)
		(width 0.14224)
		(layer "In6.Cu")
		(net "P5E_CPU0_P2_RX_DP<11>")
	)
	(segment
		(start 371.614192 -285.769812)
		(end 371.57787 -285.74873)
		(width 0.1143)
		(layer "In6.Cu")
		(net "P5E_CPU0_P2_RX_DP<11>")
	)
	(segment
		(start 371.860572 -296.279316)
		(end 371.860572 -296.007282)
		(width 0.1143)
		(layer "In6.Cu")
		(net "P5E_CPU0_P2_RX_DP<11>")
	)
	(segment
		(start 371.107716 -289.153346)
		(end 371.146832 -289.130486)
		(width 0.1143)
		(layer "In6.Cu")
		(net "P5E_CPU0_P2_RX_DP<11>")
	)
	(segment
		(start 371.146832 -294.681402)
		(end 371.107716 -294.658542)
		(width 0.1143)
		(layer "In6.Cu")
		(net "P5E_CPU0_P2_RX_DP<11>")
	)
	(segment
		(start 371.077236 -289.171126)
		(end 371.107716 -289.153346)
		(width 0.1143)
		(layer "In6.Cu")
		(net "P5E_CPU0_P2_RX_DP<11>")
	)
	(segment
		(start 415.099754 -372.857776)
		(end 409.367736 -371.42293)
		(width 0.14224)
		(layer "In6.Cu")
		(net "P5E_CPU0_P2_RX_DP<11>")
	)
	(segment
		(start 371.107716 -289.798506)
		(end 371.077236 -289.780726)
		(width 0.1143)
		(layer "In6.Cu")
		(net "P5E_CPU0_P2_RX_DP<11>")
	)
	(segment
		(start 371.146832 -284.961584)
		(end 371.107716 -284.938724)
		(width 0.1143)
		(layer "In6.Cu")
		(net "P5E_CPU0_P2_RX_DP<11>")
	)
	(segment
		(start 371.107716 -294.658542)
		(end 371.077236 -294.640762)
		(width 0.1143)
		(layer "In6.Cu")
		(net "P5E_CPU0_P2_RX_DP<11>")
	)
	(segment
		(start 371.614192 -295.48963)
		(end 371.57787 -295.468548)
		(width 0.1143)
		(layer "In6.Cu")
		(net "P5E_CPU0_P2_RX_DP<11>")
	)
	(arc
		(start 421.33901 -379.36805)
		(mid 421.294057 -379.142056)
		(end 421.166036 -378.950474)
		(width 0.14224)
		(layer "In6.Cu")
		(net "P5E_CPU0_P2_RX_DP<11>")
	)
	(arc
		(start 371.144292 -287.512252)
		(mid 371.324774 -287.309462)
		(end 371.38991 -287.045908)
		(width 0.1143)
		(layer "In6.Cu")
		(net "P5E_CPU0_P2_RX_DP<11>")
	)
	(arc
		(start 371.146832 -293.990522)
		(mid 371.390159 -293.525956)
		(end 371.146832 -293.06139)
		(width 0.1143)
		(layer "In6.Cu")
		(net "P5E_CPU0_P2_RX_DP<11>")
	)
	(arc
		(start 371.390164 -285.42615)
		(mid 371.325649 -285.163931)
		(end 371.146832 -284.961584)
		(width 0.1143)
		(layer "In6.Cu")
		(net "P5E_CPU0_P2_RX_DP<11>")
	)
	(arc
		(start 371.077236 -293.02075)
		(mid 370.920259 -292.71595)
		(end 371.077236 -292.41115)
		(width 0.1143)
		(layer "In6.Cu")
		(net "P5E_CPU0_P2_RX_DP<11>")
	)
	(arc
		(start 371.077236 -294.640762)
		(mid 370.920259 -294.335962)
		(end 371.077236 -294.031162)
		(width 0.1143)
		(layer "In6.Cu")
		(net "P5E_CPU0_P2_RX_DP<11>")
	)
	(arc
		(start 370.920264 -287.856168)
		(mid 370.961813 -287.684746)
		(end 371.077236 -287.551368)
		(width 0.1143)
		(layer "In6.Cu")
		(net "P5E_CPU0_P2_RX_DP<11>")
	)
	(arc
		(start 371.146832 -290.750498)
		(mid 371.390159 -290.285932)
		(end 371.146832 -289.821366)
		(width 0.1143)
		(layer "In6.Cu")
		(net "P5E_CPU0_P2_RX_DP<11>")
	)
	(arc
		(start 419.075362 -375.153936)
		(mid 419.024438 -375.08806)
		(end 418.968174 -375.026682)
		(width 0.14224)
		(layer "In6.Cu")
		(net "P5E_CPU0_P2_RX_DP<11>")
	)
	(arc
		(start 421.307768 -381.424942)
		(mid 421.331128 -381.348124)
		(end 421.33901 -381.268224)
		(width 0.14224)
		(layer "In6.Cu")
		(net "P5E_CPU0_P2_RX_DP<11>")
	)
	(arc
		(start 418.960808 -375.01957)
		(mid 417.174418 -373.681243)
		(end 415.099754 -372.857776)
		(width 0.14224)
		(layer "In6.Cu")
		(net "P5E_CPU0_P2_RX_DP<11>")
	)
	(arc
		(start 371.54612 -285.730442)
		(mid 371.431444 -285.597108)
		(end 371.390164 -285.42615)
		(width 0.1143)
		(layer "In6.Cu")
		(net "P5E_CPU0_P2_RX_DP<11>")
	)
	(arc
		(start 371.390164 -295.145968)
		(mid 371.325649 -294.883749)
		(end 371.146832 -294.681402)
		(width 0.1143)
		(layer "In6.Cu")
		(net "P5E_CPU0_P2_RX_DP<11>")
	)
	(arc
		(start 419.61562 -376.459496)
		(mid 419.419039 -375.77628)
		(end 419.075362 -375.153936)
		(width 0.14224)
		(layer "In6.Cu")
		(net "P5E_CPU0_P2_RX_DP<11>")
	)
	(arc
		(start 371.860064 -295.955974)
		(mid 371.794828 -295.692383)
		(end 371.614192 -295.48963)
		(width 0.1143)
		(layer "In6.Cu")
		(net "P5E_CPU0_P2_RX_DP<11>")
	)
	(arc
		(start 418.968174 -375.026682)
		(mid 418.964492 -375.023125)
		(end 418.960808 -375.01957)
		(width 0.14224)
		(layer "In6.Cu")
		(net "P5E_CPU0_P2_RX_DP<11>")
	)
	(arc
		(start 371.38991 -287.045908)
		(mid 371.43081 -286.876007)
		(end 371.544342 -286.74314)
		(width 0.1143)
		(layer "In6.Cu")
		(net "P5E_CPU0_P2_RX_DP<11>")
	)
	(arc
		(start 371.860064 -286.229552)
		(mid 371.795192 -285.97981)
		(end 371.630448 -285.781242)
		(width 0.1143)
		(layer "In6.Cu")
		(net "P5E_CPU0_P2_RX_DP<11>")
	)
	(arc
		(start 371.54612 -295.45026)
		(mid 371.431444 -295.316926)
		(end 371.390164 -295.145968)
		(width 0.1143)
		(layer "In6.Cu")
		(net "P5E_CPU0_P2_RX_DP<11>")
	)
	(arc
		(start 391.721594 -341.98814)
		(mid 391.720558 -341.982065)
		(end 391.719816 -341.975948)
		(width 0.14224)
		(layer "In6.Cu")
		(net "P5E_CPU0_P2_RX_DP<11>")
	)
	(arc
		(start 371.614192 -286.7025)
		(mid 371.796376 -286.49683)
		(end 371.860064 -286.229552)
		(width 0.1143)
		(layer "In6.Cu")
		(net "P5E_CPU0_P2_RX_DP<11>")
	)
	(arc
		(start 419.765734 -378.041916)
		(mid 419.665154 -377.891482)
		(end 419.629844 -377.714002)
		(width 0.14224)
		(layer "In6.Cu")
		(net "P5E_CPU0_P2_RX_DP<11>")
	)
	(arc
		(start 417.368228 -391.000488)
		(mid 417.370387 -390.976847)
		(end 417.376864 -390.954006)
		(width 0.14224)
		(layer "In6.Cu")
		(net "P5E_CPU0_P2_RX_DP<11>")
	)
	(arc
		(start 371.077236 -291.400738)
		(mid 370.920259 -291.095938)
		(end 371.077236 -290.791138)
		(width 0.1143)
		(layer "In6.Cu")
		(net "P5E_CPU0_P2_RX_DP<11>")
	)
	(arc
		(start 393.284964 -349.223838)
		(mid 393.075569 -348.638713)
		(end 392.924538 -348.03588)
		(width 0.14224)
		(layer "In6.Cu")
		(net "P5E_CPU0_P2_RX_DP<11>")
	)
	(arc
		(start 420.487602 -378.544074)
		(mid 420.284728 -378.503738)
		(end 420.112698 -378.38888)
		(width 0.14224)
		(layer "In6.Cu")
		(net "P5E_CPU0_P2_RX_DP<11>")
	)
	(arc
		(start 371.077236 -289.780726)
		(mid 370.920259 -289.475926)
		(end 371.077236 -289.171126)
		(width 0.1143)
		(layer "In6.Cu")
		(net "P5E_CPU0_P2_RX_DP<11>")
	)
	(arc
		(start 371.146832 -292.37051)
		(mid 371.390159 -291.905944)
		(end 371.146832 -291.441378)
		(width 0.1143)
		(layer "In6.Cu")
		(net "P5E_CPU0_P2_RX_DP<11>")
	)
	(arc
		(start 371.077236 -284.920944)
		(mid 370.979471 -284.817968)
		(end 370.927122 -284.685994)
		(width 0.1143)
		(layer "In6.Cu")
		(net "P5E_CPU0_P2_RX_DP<11>")
	)
	(arc
		(start 371.146832 -289.130486)
		(mid 371.390159 -288.66592)
		(end 371.146832 -288.201354)
		(width 0.1143)
		(layer "In6.Cu")
		(net "P5E_CPU0_P2_RX_DP<11>")
	)
	(arc
		(start 371.630448 -285.781242)
		(mid 371.62237 -285.775456)
		(end 371.614192 -285.769812)
		(width 0.1143)
		(layer "In6.Cu")
		(net "P5E_CPU0_P2_RX_DP<11>")
	)
	(arc
		(start 400.019774 -365.45774)
		(mid 400.003903 -365.438397)
		(end 399.992088 -365.416338)
		(width 0.14224)
		(layer "In6.Cu")
		(net "P5E_CPU0_P2_RX_DP<11>")
	)
	(arc
		(start 420.922958 -378.707396)
		(mid 420.742094 -378.586546)
		(end 420.52875 -378.544074)
		(width 0.14224)
		(layer "In6.Cu")
		(net "P5E_CPU0_P2_RX_DP<11>")
	)
	(arc
		(start 419.629844 -376.632978)
		(mid 419.626376 -376.545938)
		(end 419.61562 -376.459496)
		(width 0.14224)
		(layer "In6.Cu")
		(net "P5E_CPU0_P2_RX_DP<11>")
	)
	(arc
		(start 401.582128 -367.013744)
		(mid 401.567827 -367.004258)
		(end 401.55495 -366.992916)
		(width 0.14224)
		(layer "In6.Cu")
		(net "P5E_CPU0_P2_RX_DP<11>")
	)
	(arc
		(start 371.075204 -288.159698)
		(mid 370.961275 -288.026551)
		(end 370.920264 -287.856168)
		(width 0.1143)
		(layer "In6.Cu")
		(net "P5E_CPU0_P2_RX_DP<11>")
	)
	(segment
		(start 370.828062 -285.970218)
		(end 371.294914 -286.236156)
		(width 0.12954)
		(layer "F.Cu")
		(net "P5E_CPU0_P2_RX_DP<10>")
	)
	(segment
		(start 415.298382 -394.385292)
		(end 415.819082 -394.385292)
		(width 0.127)
		(layer "F.Cu")
		(net "P5E_CPU0_P2_RX_DP<10>")
	)
	(segment
		(start 415.819082 -394.385292)
		(end 415.914078 -394.031216)
		(width 0.14224)
		(layer "In6.Cu")
		(net "P5E_CPU0_P2_RX_DP<10>")
	)
	(segment
		(start 370.206778 -294.681402)
		(end 370.167662 -294.658542)
		(width 0.1143)
		(layer "In6.Cu")
		(net "P5E_CPU0_P2_RX_DP<10>")
	)
	(segment
		(start 370.64061 -295.470072)
		(end 370.638832 -295.469056)
		(width 0.1143)
		(layer "In6.Cu")
		(net "P5E_CPU0_P2_RX_DP<10>")
	)
	(segment
		(start 390.308846 -337.210146)
		(end 387.544056 -323.309234)
		(width 0.14224)
		(layer "In6.Cu")
		(net "P5E_CPU0_P2_RX_DP<10>")
	)
	(segment
		(start 380.736856 -310.833516)
		(end 380.736856 -310.833262)
		(width 0.14224)
		(layer "In6.Cu")
		(net "P5E_CPU0_P2_RX_DP<10>")
	)
	(segment
		(start 370.966492 -296.325036)
		(end 370.920772 -296.279316)
		(width 0.1143)
		(layer "In6.Cu")
		(net "P5E_CPU0_P2_RX_DP<10>")
	)
	(segment
		(start 387.544056 -323.309234)
		(end 381.429514 -311.869836)
		(width 0.14224)
		(layer "In6.Cu")
		(net "P5E_CPU0_P2_RX_DP<10>")
	)
	(segment
		(start 408.997404 -372.29034)
		(end 401.052284 -367.78946)
		(width 0.14224)
		(layer "In6.Cu")
		(net "P5E_CPU0_P2_RX_DP<10>")
	)
	(segment
		(start 370.670074 -295.487344)
		(end 370.669312 -295.486836)
		(width 0.1143)
		(layer "In6.Cu")
		(net "P5E_CPU0_P2_RX_DP<10>")
	)
	(segment
		(start 370.137182 -294.031162)
		(end 370.167662 -294.013382)
		(width 0.1143)
		(layer "In6.Cu")
		(net "P5E_CPU0_P2_RX_DP<10>")
	)
	(segment
		(start 370.167662 -289.153346)
		(end 370.206778 -289.130486)
		(width 0.1143)
		(layer "In6.Cu")
		(net "P5E_CPU0_P2_RX_DP<10>")
	)
	(segment
		(start 415.914078 -394.031216)
		(end 416.088322 -393.930632)
		(width 0.14224)
		(layer "In6.Cu")
		(net "P5E_CPU0_P2_RX_DP<10>")
	)
	(segment
		(start 370.206778 -289.821366)
		(end 370.167662 -289.798506)
		(width 0.1143)
		(layer "In6.Cu")
		(net "P5E_CPU0_P2_RX_DP<10>")
	)
	(segment
		(start 370.206778 -291.441378)
		(end 370.167662 -291.418518)
		(width 0.1143)
		(layer "In6.Cu")
		(net "P5E_CPU0_P2_RX_DP<10>")
	)
	(segment
		(start 416.088322 -393.930632)
		(end 416.17646 -393.842494)
		(width 0.14224)
		(layer "In6.Cu")
		(net "P5E_CPU0_P2_RX_DP<10>")
	)
	(segment
		(start 416.168332 -392.43)
		(end 416.168332 -382.578102)
		(width 0.14224)
		(layer "In6.Cu")
		(net "P5E_CPU0_P2_RX_DP<10>")
	)
	(segment
		(start 370.914168 -286.31896)
		(end 370.996972 -286.236156)
		(width 0.1143)
		(layer "In6.Cu")
		(net "P5E_CPU0_P2_RX_DP<10>")
	)
	(segment
		(start 414.64865 -373.710454)
		(end 409.040584 -372.307358)
		(width 0.14224)
		(layer "In6.Cu")
		(net "P5E_CPU0_P2_RX_DP<10>")
	)
	(segment
		(start 415.863532 -392.7348)
		(end 416.168332 -392.43)
		(width 0.14224)
		(layer "In6.Cu")
		(net "P5E_CPU0_P2_RX_DP<10>")
	)
	(segment
		(start 370.920772 -296.007282)
		(end 370.920264 -296.006774)
		(width 0.1143)
		(layer "In6.Cu")
		(net "P5E_CPU0_P2_RX_DP<10>")
	)
	(segment
		(start 417.31184 -379.275594)
		(end 417.31184 -375.722388)
		(width 0.14224)
		(layer "In6.Cu")
		(net "P5E_CPU0_P2_RX_DP<10>")
	)
	(segment
		(start 370.167662 -292.39337)
		(end 370.206778 -292.37051)
		(width 0.1143)
		(layer "In6.Cu")
		(net "P5E_CPU0_P2_RX_DP<10>")
	)
	(segment
		(start 381.429514 -311.869836)
		(end 380.736856 -310.833516)
		(width 0.14224)
		(layer "In6.Cu")
		(net "P5E_CPU0_P2_RX_DP<10>")
	)
	(segment
		(start 416.17646 -393.842494)
		(end 416.17646 -393.428982)
		(width 0.14224)
		(layer "In6.Cu")
		(net "P5E_CPU0_P2_RX_DP<10>")
	)
	(segment
		(start 416.17646 -393.428982)
		(end 415.860484 -393.113006)
		(width 0.14224)
		(layer "In6.Cu")
		(net "P5E_CPU0_P2_RX_DP<10>")
	)
	(segment
		(start 370.966492 -297.177968)
		(end 370.966492 -296.353484)
		(width 0.14224)
		(layer "In6.Cu")
		(net "P5E_CPU0_P2_RX_DP<10>")
	)
	(segment
		(start 370.920772 -296.279316)
		(end 370.920772 -296.007282)
		(width 0.1143)
		(layer "In6.Cu")
		(net "P5E_CPU0_P2_RX_DP<10>")
	)
	(segment
		(start 370.669312 -295.486836)
		(end 370.644674 -295.472612)
		(width 0.1143)
		(layer "In6.Cu")
		(net "P5E_CPU0_P2_RX_DP<10>")
	)
	(segment
		(start 370.137182 -292.41115)
		(end 370.167662 -292.39337)
		(width 0.1143)
		(layer "In6.Cu")
		(net "P5E_CPU0_P2_RX_DP<10>")
	)
	(segment
		(start 370.167662 -294.013382)
		(end 370.206778 -293.990522)
		(width 0.1143)
		(layer "In6.Cu")
		(net "P5E_CPU0_P2_RX_DP<10>")
	)
	(segment
		(start 399.104104 -365.830866)
		(end 392.193018 -349.146368)
		(width 0.14224)
		(layer "In6.Cu")
		(net "P5E_CPU0_P2_RX_DP<10>")
	)
	(segment
		(start 417.26358 -375.487184)
		(end 417.048696 -374.98909)
		(width 0.14224)
		(layer "In6.Cu")
		(net "P5E_CPU0_P2_RX_DP<10>")
	)
	(segment
		(start 370.966492 -296.353484)
		(end 370.966492 -296.325036)
		(width 0.1143)
		(layer "In6.Cu")
		(net "P5E_CPU0_P2_RX_DP<10>")
	)
	(segment
		(start 370.206778 -293.06139)
		(end 370.167662 -293.03853)
		(width 0.1143)
		(layer "In6.Cu")
		(net "P5E_CPU0_P2_RX_DP<10>")
	)
	(segment
		(start 370.206778 -288.201354)
		(end 370.167662 -288.178494)
		(width 0.1143)
		(layer "In6.Cu")
		(net "P5E_CPU0_P2_RX_DP<10>")
	)
	(segment
		(start 416.329368 -381.76835)
		(end 417.265612 -379.506988)
		(width 0.14224)
		(layer "In6.Cu")
		(net "P5E_CPU0_P2_RX_DP<10>")
	)
	(segment
		(start 370.996972 -286.236156)
		(end 371.294914 -286.236156)
		(width 0.1143)
		(layer "In6.Cu")
		(net "P5E_CPU0_P2_RX_DP<10>")
	)
	(segment
		(start 370.137182 -287.551368)
		(end 370.204238 -287.512252)
		(width 0.1143)
		(layer "In6.Cu")
		(net "P5E_CPU0_P2_RX_DP<10>")
	)
	(segment
		(start 370.137182 -289.171126)
		(end 370.167662 -289.153346)
		(width 0.1143)
		(layer "In6.Cu")
		(net "P5E_CPU0_P2_RX_DP<10>")
	)
	(segment
		(start 370.167662 -288.178494)
		(end 370.13515 -288.159698)
		(width 0.1143)
		(layer "In6.Cu")
		(net "P5E_CPU0_P2_RX_DP<10>")
	)
	(segment
		(start 370.167662 -293.03853)
		(end 370.137182 -293.02075)
		(width 0.1143)
		(layer "In6.Cu")
		(net "P5E_CPU0_P2_RX_DP<10>")
	)
	(segment
		(start 370.637816 -286.723582)
		(end 370.676932 -286.700722)
		(width 0.1143)
		(layer "In6.Cu")
		(net "P5E_CPU0_P2_RX_DP<10>")
	)
	(segment
		(start 380.736856 -310.833262)
		(end 380.729236 -310.822086)
		(width 0.14224)
		(layer "In6.Cu")
		(net "P5E_CPU0_P2_RX_DP<10>")
	)
	(segment
		(start 390.771634 -341.909146)
		(end 390.308846 -337.210146)
		(width 0.14224)
		(layer "In6.Cu")
		(net "P5E_CPU0_P2_RX_DP<10>")
	)
	(segment
		(start 370.167662 -294.658542)
		(end 370.137182 -294.640762)
		(width 0.1143)
		(layer "In6.Cu")
		(net "P5E_CPU0_P2_RX_DP<10>")
	)
	(segment
		(start 371.822726 -299.245274)
		(end 370.966492 -297.177968)
		(width 0.14224)
		(layer "In6.Cu")
		(net "P5E_CPU0_P2_RX_DP<10>")
	)
	(segment
		(start 370.676932 -295.491408)
		(end 370.670074 -295.487344)
		(width 0.1143)
		(layer "In6.Cu")
		(net "P5E_CPU0_P2_RX_DP<10>")
	)
	(segment
		(start 392.185906 -349.122492)
		(end 390.831832 -342.313768)
		(width 0.14224)
		(layer "In6.Cu")
		(net "P5E_CPU0_P2_RX_DP<10>")
	)
	(segment
		(start 370.167662 -289.798506)
		(end 370.137182 -289.780726)
		(width 0.1143)
		(layer "In6.Cu")
		(net "P5E_CPU0_P2_RX_DP<10>")
	)
	(segment
		(start 370.920264 -296.006774)
		(end 370.920264 -295.955974)
		(width 0.1143)
		(layer "In6.Cu")
		(net "P5E_CPU0_P2_RX_DP<10>")
	)
	(segment
		(start 415.860484 -393.113006)
		(end 415.863532 -392.7348)
		(width 0.14224)
		(layer "In6.Cu")
		(net "P5E_CPU0_P2_RX_DP<10>")
	)
	(segment
		(start 370.637816 -295.468548)
		(end 370.606066 -295.45026)
		(width 0.1143)
		(layer "In6.Cu")
		(net "P5E_CPU0_P2_RX_DP<10>")
	)
	(segment
		(start 374.426988 -303.142904)
		(end 371.822726 -299.245274)
		(width 0.14224)
		(layer "In6.Cu")
		(net "P5E_CPU0_P2_RX_DP<10>")
	)
	(segment
		(start 370.167662 -291.418518)
		(end 370.137182 -291.400738)
		(width 0.1143)
		(layer "In6.Cu")
		(net "P5E_CPU0_P2_RX_DP<10>")
	)
	(segment
		(start 370.64315 -295.471596)
		(end 370.642134 -295.471088)
		(width 0.1143)
		(layer "In6.Cu")
		(net "P5E_CPU0_P2_RX_DP<10>")
	)
	(segment
		(start 370.167662 -290.773358)
		(end 370.206778 -290.750498)
		(width 0.1143)
		(layer "In6.Cu")
		(net "P5E_CPU0_P2_RX_DP<10>")
	)
	(segment
		(start 400.9517 -367.713006)
		(end 399.174208 -365.935514)
		(width 0.14224)
		(layer "In6.Cu")
		(net "P5E_CPU0_P2_RX_DP<10>")
	)
	(segment
		(start 370.638832 -295.469056)
		(end 370.637816 -295.468548)
		(width 0.1143)
		(layer "In6.Cu")
		(net "P5E_CPU0_P2_RX_DP<10>")
	)
	(segment
		(start 380.729236 -310.822086)
		(end 374.426988 -303.142904)
		(width 0.14224)
		(layer "In6.Cu")
		(net "P5E_CPU0_P2_RX_DP<10>")
	)
	(segment
		(start 370.604288 -286.74314)
		(end 370.637816 -286.723582)
		(width 0.1143)
		(layer "In6.Cu")
		(net "P5E_CPU0_P2_RX_DP<10>")
	)
	(segment
		(start 370.642134 -295.471088)
		(end 370.64061 -295.470072)
		(width 0.1143)
		(layer "In6.Cu")
		(net "P5E_CPU0_P2_RX_DP<10>")
	)
	(segment
		(start 370.644674 -295.472612)
		(end 370.64315 -295.471596)
		(width 0.1143)
		(layer "In6.Cu")
		(net "P5E_CPU0_P2_RX_DP<10>")
	)
	(segment
		(start 370.137182 -290.791138)
		(end 370.167662 -290.773358)
		(width 0.1143)
		(layer "In6.Cu")
		(net "P5E_CPU0_P2_RX_DP<10>")
	)
	(arc
		(start 370.137182 -294.640762)
		(mid 369.980205 -294.335962)
		(end 370.137182 -294.031162)
		(width 0.1143)
		(layer "In6.Cu")
		(net "P5E_CPU0_P2_RX_DP<10>")
	)
	(arc
		(start 370.137182 -293.02075)
		(mid 369.980205 -292.71595)
		(end 370.137182 -292.41115)
		(width 0.1143)
		(layer "In6.Cu")
		(net "P5E_CPU0_P2_RX_DP<10>")
	)
	(arc
		(start 409.040584 -372.307358)
		(mid 409.018462 -372.300198)
		(end 408.997404 -372.29034)
		(width 0.14224)
		(layer "In6.Cu")
		(net "P5E_CPU0_P2_RX_DP<10>")
	)
	(arc
		(start 370.206778 -293.990522)
		(mid 370.450105 -293.525956)
		(end 370.206778 -293.06139)
		(width 0.1143)
		(layer "In6.Cu")
		(net "P5E_CPU0_P2_RX_DP<10>")
	)
	(arc
		(start 416.168332 -382.578102)
		(mid 416.208944 -382.165287)
		(end 416.329368 -381.76835)
		(width 0.14224)
		(layer "In6.Cu")
		(net "P5E_CPU0_P2_RX_DP<10>")
	)
	(arc
		(start 370.206778 -292.37051)
		(mid 370.450105 -291.905944)
		(end 370.206778 -291.441378)
		(width 0.1143)
		(layer "In6.Cu")
		(net "P5E_CPU0_P2_RX_DP<10>")
	)
	(arc
		(start 370.910358 -286.34182)
		(mid 370.912381 -286.33041)
		(end 370.914168 -286.31896)
		(width 0.1143)
		(layer "In6.Cu")
		(net "P5E_CPU0_P2_RX_DP<10>")
	)
	(arc
		(start 370.204238 -287.512252)
		(mid 370.38489 -287.309507)
		(end 370.45011 -287.045908)
		(width 0.1143)
		(layer "In6.Cu")
		(net "P5E_CPU0_P2_RX_DP<10>")
	)
	(arc
		(start 417.048696 -374.98909)
		(mid 416.968384 -374.859098)
		(end 416.853624 -374.758204)
		(width 0.14224)
		(layer "In6.Cu")
		(net "P5E_CPU0_P2_RX_DP<10>")
	)
	(arc
		(start 370.606066 -295.45026)
		(mid 370.49139 -295.316926)
		(end 370.45011 -295.145968)
		(width 0.1143)
		(layer "In6.Cu")
		(net "P5E_CPU0_P2_RX_DP<10>")
	)
	(arc
		(start 390.831832 -342.313768)
		(mid 390.796767 -342.112196)
		(end 390.771634 -341.909146)
		(width 0.14224)
		(layer "In6.Cu")
		(net "P5E_CPU0_P2_RX_DP<10>")
	)
	(arc
		(start 370.137182 -291.400738)
		(mid 369.980205 -291.095938)
		(end 370.137182 -290.791138)
		(width 0.1143)
		(layer "In6.Cu")
		(net "P5E_CPU0_P2_RX_DP<10>")
	)
	(arc
		(start 369.98021 -287.856168)
		(mid 370.021759 -287.684746)
		(end 370.137182 -287.551368)
		(width 0.1143)
		(layer "In6.Cu")
		(net "P5E_CPU0_P2_RX_DP<10>")
	)
	(arc
		(start 414.7947 -373.754142)
		(mid 414.722173 -373.730633)
		(end 414.64865 -373.710454)
		(width 0.14224)
		(layer "In6.Cu")
		(net "P5E_CPU0_P2_RX_DP<10>")
	)
	(arc
		(start 370.45011 -295.145968)
		(mid 370.385595 -294.883749)
		(end 370.206778 -294.681402)
		(width 0.1143)
		(layer "In6.Cu")
		(net "P5E_CPU0_P2_RX_DP<10>")
	)
	(arc
		(start 370.13515 -288.159698)
		(mid 370.021221 -288.026551)
		(end 369.98021 -287.856168)
		(width 0.1143)
		(layer "In6.Cu")
		(net "P5E_CPU0_P2_RX_DP<10>")
	)
	(arc
		(start 370.206778 -290.750498)
		(mid 370.450105 -290.285932)
		(end 370.206778 -289.821366)
		(width 0.1143)
		(layer "In6.Cu")
		(net "P5E_CPU0_P2_RX_DP<10>")
	)
	(arc
		(start 399.174208 -365.935514)
		(mid 399.133984 -365.886653)
		(end 399.104104 -365.830866)
		(width 0.14224)
		(layer "In6.Cu")
		(net "P5E_CPU0_P2_RX_DP<10>")
	)
	(arc
		(start 416.853624 -374.758204)
		(mid 415.853688 -374.195628)
		(end 414.7947 -373.754142)
		(width 0.14224)
		(layer "In6.Cu")
		(net "P5E_CPU0_P2_RX_DP<10>")
	)
	(arc
		(start 370.676932 -286.700722)
		(mid 370.828919 -286.544214)
		(end 370.910358 -286.34182)
		(width 0.1143)
		(layer "In6.Cu")
		(net "P5E_CPU0_P2_RX_DP<10>")
	)
	(arc
		(start 370.137182 -289.780726)
		(mid 369.980205 -289.475926)
		(end 370.137182 -289.171126)
		(width 0.1143)
		(layer "In6.Cu")
		(net "P5E_CPU0_P2_RX_DP<10>")
	)
	(arc
		(start 401.052284 -367.78946)
		(mid 400.999404 -367.754638)
		(end 400.9517 -367.713006)
		(width 0.14224)
		(layer "In6.Cu")
		(net "P5E_CPU0_P2_RX_DP<10>")
	)
	(arc
		(start 370.206778 -289.130486)
		(mid 370.450105 -288.66592)
		(end 370.206778 -288.201354)
		(width 0.1143)
		(layer "In6.Cu")
		(net "P5E_CPU0_P2_RX_DP<10>")
	)
	(arc
		(start 417.265612 -379.506988)
		(mid 417.30015 -379.393571)
		(end 417.31184 -379.275594)
		(width 0.14224)
		(layer "In6.Cu")
		(net "P5E_CPU0_P2_RX_DP<10>")
	)
	(arc
		(start 370.45011 -287.045908)
		(mid 370.490872 -286.876024)
		(end 370.604288 -286.74314)
		(width 0.1143)
		(layer "In6.Cu")
		(net "P5E_CPU0_P2_RX_DP<10>")
	)
	(arc
		(start 417.31184 -375.722388)
		(mid 417.299718 -375.602324)
		(end 417.26358 -375.487184)
		(width 0.14224)
		(layer "In6.Cu")
		(net "P5E_CPU0_P2_RX_DP<10>")
	)
	(arc
		(start 392.193018 -349.146368)
		(mid 392.188877 -349.134604)
		(end 392.185906 -349.122492)
		(width 0.14224)
		(layer "In6.Cu")
		(net "P5E_CPU0_P2_RX_DP<10>")
	)
	(arc
		(start 370.920264 -295.955974)
		(mid 370.855676 -295.693807)
		(end 370.676932 -295.491408)
		(width 0.1143)
		(layer "In6.Cu")
		(net "P5E_CPU0_P2_RX_DP<10>")
	)
	(segment
		(start 362.837984 -281.920188)
		(end 363.304836 -282.186126)
		(width 0.12954)
		(layer "F.Cu")
		(net "P5E_CPU0_P2_RX_DP<0>")
	)
	(segment
		(start 403.298406 -394.385292)
		(end 403.819106 -394.385292)
		(width 0.127)
		(layer "F.Cu")
		(net "P5E_CPU0_P2_RX_DP<0>")
	)
	(segment
		(start 362.177838 -283.483558)
		(end 362.217716 -283.459936)
		(width 0.1143)
		(layer "In6.Cu")
		(net "P5E_CPU0_P2_RX_DP<0>")
	)
	(segment
		(start 372.530624 -315.71692)
		(end 367.393728 -309.457598)
		(width 0.14224)
		(layer "In6.Cu")
		(net "P5E_CPU0_P2_RX_DP<0>")
	)
	(segment
		(start 381.428244 -343.811098)
		(end 380.817882 -337.615276)
		(width 0.14224)
		(layer "In6.Cu")
		(net "P5E_CPU0_P2_RX_DP<0>")
	)
	(segment
		(start 380.817882 -337.615276)
		(end 378.62256 -326.578722)
		(width 0.14224)
		(layer "In6.Cu")
		(net "P5E_CPU0_P2_RX_DP<0>")
	)
	(segment
		(start 360.896408 -295.510204)
		(end 360.896408 -285.152338)
		(width 0.14224)
		(layer "In6.Cu")
		(net "P5E_CPU0_P2_RX_DP<0>")
	)
	(segment
		(start 362.615988 -282.69184)
		(end 362.647738 -282.673552)
		(width 0.1143)
		(layer "In6.Cu")
		(net "P5E_CPU0_P2_RX_DP<0>")
	)
	(segment
		(start 403.914102 -394.031216)
		(end 404.088346 -393.930632)
		(width 0.14224)
		(layer "In6.Cu")
		(net "P5E_CPU0_P2_RX_DP<0>")
	)
	(segment
		(start 404.168356 -392.430254)
		(end 404.168356 -391.141458)
		(width 0.14224)
		(layer "In6.Cu")
		(net "P5E_CPU0_P2_RX_DP<0>")
	)
	(segment
		(start 403.863556 -392.7348)
		(end 404.168356 -392.430254)
		(width 0.14224)
		(layer "In6.Cu")
		(net "P5E_CPU0_P2_RX_DP<0>")
	)
	(segment
		(start 361.707684 -284.293564)
		(end 361.7468 -284.270704)
		(width 0.1143)
		(layer "In6.Cu")
		(net "P5E_CPU0_P2_RX_DP<0>")
	)
	(segment
		(start 360.896408 -285.152338)
		(end 361.206796 -284.84195)
		(width 0.14224)
		(layer "In6.Cu")
		(net "P5E_CPU0_P2_RX_DP<0>")
	)
	(segment
		(start 367.393728 -309.457598)
		(end 363.47019 -303.585372)
		(width 0.14224)
		(layer "In6.Cu")
		(net "P5E_CPU0_P2_RX_DP<0>")
	)
	(segment
		(start 363.47019 -303.585372)
		(end 361.609132 -299.093382)
		(width 0.14224)
		(layer "In6.Cu")
		(net "P5E_CPU0_P2_RX_DP<0>")
	)
	(segment
		(start 362.67644 -282.656788)
		(end 362.677202 -282.65628)
		(width 0.1143)
		(layer "In6.Cu")
		(net "P5E_CPU0_P2_RX_DP<0>")
	)
	(segment
		(start 362.551472 -282.738322)
		(end 362.615988 -282.69184)
		(width 0.1143)
		(layer "In6.Cu")
		(net "P5E_CPU0_P2_RX_DP<0>")
	)
	(segment
		(start 404.176484 -393.428982)
		(end 403.860508 -393.113006)
		(width 0.14224)
		(layer "In6.Cu")
		(net "P5E_CPU0_P2_RX_DP<0>")
	)
	(segment
		(start 383.33807 -353.415854)
		(end 381.430022 -343.82329)
		(width 0.14224)
		(layer "In6.Cu")
		(net "P5E_CPU0_P2_RX_DP<0>")
	)
	(segment
		(start 362.92409 -282.26893)
		(end 363.006894 -282.186126)
		(width 0.1143)
		(layer "In6.Cu")
		(net "P5E_CPU0_P2_RX_DP<0>")
	)
	(segment
		(start 362.460032 -283.00045)
		(end 362.460032 -282.916884)
		(width 0.1143)
		(layer "In6.Cu")
		(net "P5E_CPU0_P2_RX_DP<0>")
	)
	(segment
		(start 361.206796 -284.84195)
		(end 361.226862 -284.821884)
		(width 0.1143)
		(layer "In6.Cu")
		(net "P5E_CPU0_P2_RX_DP<0>")
	)
	(segment
		(start 390.614408 -370.990876)
		(end 383.346706 -353.444556)
		(width 0.14224)
		(layer "In6.Cu")
		(net "P5E_CPU0_P2_RX_DP<0>")
	)
	(segment
		(start 378.62256 -326.578722)
		(end 373.963184 -317.860934)
		(width 0.14224)
		(layer "In6.Cu")
		(net "P5E_CPU0_P2_RX_DP<0>")
	)
	(segment
		(start 404.176484 -393.842494)
		(end 404.176484 -393.428982)
		(width 0.14224)
		(layer "In6.Cu")
		(net "P5E_CPU0_P2_RX_DP<0>")
	)
	(segment
		(start 361.226862 -284.75686)
		(end 361.63123 -284.352492)
		(width 0.1143)
		(layer "In6.Cu")
		(net "P5E_CPU0_P2_RX_DP<0>")
	)
	(segment
		(start 361.609132 -299.093382)
		(end 360.896408 -295.510204)
		(width 0.14224)
		(layer "In6.Cu")
		(net "P5E_CPU0_P2_RX_DP<0>")
	)
	(segment
		(start 372.538244 -315.728096)
		(end 372.530624 -315.71692)
		(width 0.14224)
		(layer "In6.Cu")
		(net "P5E_CPU0_P2_RX_DP<0>")
	)
	(segment
		(start 404.088346 -393.930632)
		(end 404.176484 -393.842494)
		(width 0.14224)
		(layer "In6.Cu")
		(net "P5E_CPU0_P2_RX_DP<0>")
	)
	(segment
		(start 372.538244 -315.72835)
		(end 372.538244 -315.728096)
		(width 0.14224)
		(layer "In6.Cu")
		(net "P5E_CPU0_P2_RX_DP<0>")
	)
	(segment
		(start 403.819106 -394.385292)
		(end 403.914102 -394.031216)
		(width 0.14224)
		(layer "In6.Cu")
		(net "P5E_CPU0_P2_RX_DP<0>")
	)
	(segment
		(start 403.864572 -390.304782)
		(end 395.919198 -380.798324)
		(width 0.14224)
		(layer "In6.Cu")
		(net "P5E_CPU0_P2_RX_DP<0>")
	)
	(segment
		(start 373.963184 -317.860934)
		(end 372.538244 -315.72835)
		(width 0.14224)
		(layer "In6.Cu")
		(net "P5E_CPU0_P2_RX_DP<0>")
	)
	(segment
		(start 362.647738 -282.673552)
		(end 362.67644 -282.656788)
		(width 0.1143)
		(layer "In6.Cu")
		(net "P5E_CPU0_P2_RX_DP<0>")
	)
	(segment
		(start 395.889734 -380.71679)
		(end 395.889734 -377.53925)
		(width 0.14224)
		(layer "In6.Cu")
		(net "P5E_CPU0_P2_RX_DP<0>")
	)
	(segment
		(start 361.226862 -284.821884)
		(end 361.226862 -284.75686)
		(width 0.1143)
		(layer "In6.Cu")
		(net "P5E_CPU0_P2_RX_DP<0>")
	)
	(segment
		(start 395.105636 -375.621296)
		(end 390.894824 -371.410484)
		(width 0.14224)
		(layer "In6.Cu")
		(net "P5E_CPU0_P2_RX_DP<0>")
	)
	(segment
		(start 362.146088 -283.501846)
		(end 362.177838 -283.483558)
		(width 0.1143)
		(layer "In6.Cu")
		(net "P5E_CPU0_P2_RX_DP<0>")
	)
	(segment
		(start 395.88186 -377.531376)
		(end 395.88186 -377.495308)
		(width 0.14224)
		(layer "In6.Cu")
		(net "P5E_CPU0_P2_RX_DP<0>")
	)
	(segment
		(start 403.860508 -393.113006)
		(end 403.863556 -392.7348)
		(width 0.14224)
		(layer "In6.Cu")
		(net "P5E_CPU0_P2_RX_DP<0>")
	)
	(segment
		(start 362.677202 -282.65628)
		(end 362.686854 -282.650692)
		(width 0.1143)
		(layer "In6.Cu")
		(net "P5E_CPU0_P2_RX_DP<0>")
	)
	(segment
		(start 363.006894 -282.186126)
		(end 363.304836 -282.186126)
		(width 0.1143)
		(layer "In6.Cu")
		(net "P5E_CPU0_P2_RX_DP<0>")
	)
	(segment
		(start 395.889734 -377.53925)
		(end 395.88186 -377.531376)
		(width 0.14224)
		(layer "In6.Cu")
		(net "P5E_CPU0_P2_RX_DP<0>")
	)
	(arc
		(start 362.783628 -282.565602)
		(mid 362.87085 -282.438124)
		(end 362.92028 -282.29179)
		(width 0.1143)
		(layer "In6.Cu")
		(net "P5E_CPU0_P2_RX_DP<0>")
	)
	(arc
		(start 381.430022 -343.82329)
		(mid 381.428986 -343.817215)
		(end 381.428244 -343.811098)
		(width 0.14224)
		(layer "In6.Cu")
		(net "P5E_CPU0_P2_RX_DP<0>")
	)
	(arc
		(start 361.7468 -284.270704)
		(mid 361.925613 -284.068354)
		(end 361.990132 -283.806138)
		(width 0.1143)
		(layer "In6.Cu")
		(net "P5E_CPU0_P2_RX_DP<0>")
	)
	(arc
		(start 390.894824 -371.410484)
		(mid 390.733939 -371.214497)
		(end 390.614408 -370.990876)
		(width 0.14224)
		(layer "In6.Cu")
		(net "P5E_CPU0_P2_RX_DP<0>")
	)
	(arc
		(start 395.919198 -380.798324)
		(mid 395.897311 -380.760146)
		(end 395.889734 -380.71679)
		(width 0.14224)
		(layer "In6.Cu")
		(net "P5E_CPU0_P2_RX_DP<0>")
	)
	(arc
		(start 395.88186 -377.495308)
		(mid 395.680191 -376.481067)
		(end 395.105636 -375.621296)
		(width 0.14224)
		(layer "In6.Cu")
		(net "P5E_CPU0_P2_RX_DP<0>")
	)
	(arc
		(start 362.92028 -282.29179)
		(mid 362.922303 -282.28038)
		(end 362.92409 -282.26893)
		(width 0.1143)
		(layer "In6.Cu")
		(net "P5E_CPU0_P2_RX_DP<0>")
	)
	(arc
		(start 362.217716 -283.459936)
		(mid 362.395752 -283.260186)
		(end 362.460032 -283.00045)
		(width 0.1143)
		(layer "In6.Cu")
		(net "P5E_CPU0_P2_RX_DP<0>")
	)
	(arc
		(start 404.168356 -391.141458)
		(mid 404.089941 -390.696438)
		(end 403.864572 -390.304782)
		(width 0.14224)
		(layer "In6.Cu")
		(net "P5E_CPU0_P2_RX_DP<0>")
	)
	(arc
		(start 362.686854 -282.650692)
		(mid 362.737666 -282.610906)
		(end 362.783628 -282.565602)
		(width 0.1143)
		(layer "In6.Cu")
		(net "P5E_CPU0_P2_RX_DP<0>")
	)
	(arc
		(start 362.460032 -282.916884)
		(mid 362.484229 -282.816587)
		(end 362.551472 -282.738322)
		(width 0.1143)
		(layer "In6.Cu")
		(net "P5E_CPU0_P2_RX_DP<0>")
	)
	(arc
		(start 383.346706 -353.444556)
		(mid 383.341688 -353.430416)
		(end 383.33807 -353.415854)
		(width 0.14224)
		(layer "In6.Cu")
		(net "P5E_CPU0_P2_RX_DP<0>")
	)
	(arc
		(start 361.63123 -284.352492)
		(mid 361.667545 -284.320548)
		(end 361.707684 -284.293564)
		(width 0.1143)
		(layer "In6.Cu")
		(net "P5E_CPU0_P2_RX_DP<0>")
	)
	(arc
		(start 361.990132 -283.806138)
		(mid 362.031387 -283.635167)
		(end 362.146088 -283.501846)
		(width 0.1143)
		(layer "In6.Cu")
		(net "P5E_CPU0_P2_RX_DP<0>")
	)
	(segment
		(start 369.888008 -281.110182)
		(end 370.35486 -281.37612)
		(width 0.12954)
		(layer "F.Cu")
		(net "P5E_CPU0_P2_RX_DN<9>")
	)
	(segment
		(start 413.698182 -393.69238)
		(end 414.218882 -393.69238)
		(width 0.127)
		(layer "F.Cu")
		(net "P5E_CPU0_P2_RX_DN<9>")
	)
	(segment
		(start 414.549082 -390.83488)
		(end 414.549082 -390.40816)
		(width 0.14224)
		(layer "In6.Cu")
		(net "P5E_CPU0_P2_RX_DN<9>")
	)
	(segment
		(start 414.69437 -393.716764)
		(end 414.69437 -393.545822)
		(width 0.14224)
		(layer "In6.Cu")
		(net "P5E_CPU0_P2_RX_DN<9>")
	)
	(segment
		(start 369.126262 -289.96005)
		(end 369.093496 -289.941)
		(width 0.1143)
		(layer "In6.Cu")
		(net "P5E_CPU0_P2_RX_DN<9>")
	)
	(segment
		(start 369.565428 -283.339794)
		(end 369.60175 -283.318712)
		(width 0.1143)
		(layer "In6.Cu")
		(net "P5E_CPU0_P2_RX_DN<9>")
	)
	(segment
		(start 369.6335 -295.651682)
		(end 369.56238 -295.61028)
		(width 0.1143)
		(layer "In6.Cu")
		(net "P5E_CPU0_P2_RX_DN<9>")
	)
	(segment
		(start 369.603782 -283.317442)
		(end 369.6335 -283.300424)
		(width 0.1143)
		(layer "In6.Cu")
		(net "P5E_CPU0_P2_RX_DN<9>")
	)
	(segment
		(start 415.953448 -379.00737)
		(end 415.953448 -376.67438)
		(width 0.14224)
		(layer "In6.Cu")
		(net "P5E_CPU0_P2_RX_DN<9>")
	)
	(segment
		(start 370.74602 -299.819822)
		(end 369.744498 -297.401742)
		(width 0.14224)
		(layer "In6.Cu")
		(net "P5E_CPU0_P2_RX_DN<9>")
	)
	(segment
		(start 369.568222 -286.57804)
		(end 369.635278 -286.538924)
		(width 0.1143)
		(layer "In6.Cu")
		(net "P5E_CPU0_P2_RX_DN<9>")
	)
	(segment
		(start 414.576768 -387.250686)
		(end 414.597596 -386.82422)
		(width 0.14224)
		(layer "In6.Cu")
		(net "P5E_CPU0_P2_RX_DN<9>")
	)
	(segment
		(start 369.60175 -283.318712)
		(end 369.602512 -283.318204)
		(width 0.1143)
		(layer "In6.Cu")
		(net "P5E_CPU0_P2_RX_DN<9>")
	)
	(segment
		(start 414.686242 -389.14324)
		(end 414.686242 -387.820408)
		(width 0.14224)
		(layer "In6.Cu")
		(net "P5E_CPU0_P2_RX_DN<9>")
	)
	(segment
		(start 389.549386 -342.185244)
		(end 389.05307 -337.149186)
		(width 0.14224)
		(layer "In6.Cu")
		(net "P5E_CPU0_P2_RX_DN<9>")
	)
	(segment
		(start 414.549082 -389.70712)
		(end 414.549082 -389.2804)
		(width 0.14224)
		(layer "In6.Cu")
		(net "P5E_CPU0_P2_RX_DN<9>")
	)
	(segment
		(start 369.602512 -283.318204)
		(end 369.603782 -283.317442)
		(width 0.1143)
		(layer "In6.Cu")
		(net "P5E_CPU0_P2_RX_DN<9>")
	)
	(segment
		(start 370.652802 -281.37612)
		(end 370.35486 -281.37612)
		(width 0.1143)
		(layer "In6.Cu")
		(net "P5E_CPU0_P2_RX_DN<9>")
	)
	(segment
		(start 414.686242 -389.84428)
		(end 414.549082 -389.70712)
		(width 0.14224)
		(layer "In6.Cu")
		(net "P5E_CPU0_P2_RX_DN<9>")
	)
	(segment
		(start 414.597596 -386.82422)
		(end 414.741614 -386.693918)
		(width 0.14224)
		(layer "In6.Cu")
		(net "P5E_CPU0_P2_RX_DN<9>")
	)
	(segment
		(start 369.09248 -294.800528)
		(end 369.092734 -294.800528)
		(width 0.1143)
		(layer "In6.Cu")
		(net "P5E_CPU0_P2_RX_DN<9>")
	)
	(segment
		(start 369.109244 -294.809926)
		(end 369.098576 -294.804592)
		(width 0.1143)
		(layer "In6.Cu")
		(net "P5E_CPU0_P2_RX_DN<9>")
	)
	(segment
		(start 369.095528 -285.082742)
		(end 369.092734 -285.08071)
		(width 0.1143)
		(layer "In6.Cu")
		(net "P5E_CPU0_P2_RX_DN<9>")
	)
	(segment
		(start 369.127024 -289.960558)
		(end 369.126262 -289.96005)
		(width 0.1143)
		(layer "In6.Cu")
		(net "P5E_CPU0_P2_RX_DN<9>")
	)
	(segment
		(start 414.70707 -387.39445)
		(end 414.576768 -387.250686)
		(width 0.14224)
		(layer "In6.Cu")
		(net "P5E_CPU0_P2_RX_DN<9>")
	)
	(segment
		(start 369.160552 -288.360358)
		(end 369.092734 -288.320734)
		(width 0.1143)
		(layer "In6.Cu")
		(net "P5E_CPU0_P2_RX_DN<9>")
	)
	(segment
		(start 369.110006 -294.810434)
		(end 369.109244 -294.809926)
		(width 0.1143)
		(layer "In6.Cu")
		(net "P5E_CPU0_P2_RX_DN<9>")
	)
	(segment
		(start 369.092734 -293.871396)
		(end 369.14328 -293.841932)
		(width 0.1143)
		(layer "In6.Cu")
		(net "P5E_CPU0_P2_RX_DN<9>")
	)
	(segment
		(start 369.744498 -296.353484)
		(end 369.744498 -296.325036)
		(width 0.1143)
		(layer "In6.Cu")
		(net "P5E_CPU0_P2_RX_DN<9>")
	)
	(segment
		(start 369.153186 -291.59581)
		(end 369.093496 -291.561012)
		(width 0.1143)
		(layer "In6.Cu")
		(net "P5E_CPU0_P2_RX_DN<9>")
	)
	(segment
		(start 369.129818 -290.609782)
		(end 369.137438 -290.60521)
		(width 0.1143)
		(layer "In6.Cu")
		(net "P5E_CPU0_P2_RX_DN<9>")
	)
	(segment
		(start 414.572196 -393.787376)
		(end 414.572704 -393.786868)
		(width 0.14224)
		(layer "In6.Cu")
		(net "P5E_CPU0_P2_RX_DN<9>")
	)
	(segment
		(start 369.744498 -297.401742)
		(end 369.744498 -296.353484)
		(width 0.14224)
		(layer "In6.Cu")
		(net "P5E_CPU0_P2_RX_DN<9>")
	)
	(segment
		(start 369.137438 -290.60521)
		(end 369.1382 -290.604956)
		(width 0.1143)
		(layer "In6.Cu")
		(net "P5E_CPU0_P2_RX_DN<9>")
	)
	(segment
		(start 386.394452 -323.780912)
		(end 380.26213 -312.309002)
		(width 0.14224)
		(layer "In6.Cu")
		(net "P5E_CPU0_P2_RX_DN<9>")
	)
	(segment
		(start 369.092734 -290.631372)
		(end 369.129056 -290.61029)
		(width 0.1143)
		(layer "In6.Cu")
		(net "P5E_CPU0_P2_RX_DN<9>")
	)
	(segment
		(start 369.092734 -292.251384)
		(end 369.152424 -292.216586)
		(width 0.1143)
		(layer "In6.Cu")
		(net "P5E_CPU0_P2_RX_DN<9>")
	)
	(segment
		(start 414.549082 -389.2804)
		(end 414.686242 -389.14324)
		(width 0.14224)
		(layer "In6.Cu")
		(net "P5E_CPU0_P2_RX_DN<9>")
	)
	(segment
		(start 370.502688 -281.72156)
		(end 370.573554 -281.680412)
		(width 0.1143)
		(layer "In6.Cu")
		(net "P5E_CPU0_P2_RX_DN<9>")
	)
	(segment
		(start 369.129056 -290.61029)
		(end 369.129818 -290.609782)
		(width 0.1143)
		(layer "In6.Cu")
		(net "P5E_CPU0_P2_RX_DN<9>")
	)
	(segment
		(start 369.092734 -289.01136)
		(end 369.158012 -288.97326)
		(width 0.1143)
		(layer "In6.Cu")
		(net "P5E_CPU0_P2_RX_DN<9>")
	)
	(segment
		(start 414.686242 -392.312906)
		(end 414.686242 -390.97204)
		(width 0.14224)
		(layer "In6.Cu")
		(net "P5E_CPU0_P2_RX_DN<9>")
	)
	(segment
		(start 369.78971 -296.085768)
		(end 369.78971 -295.955974)
		(width 0.1143)
		(layer "In6.Cu")
		(net "P5E_CPU0_P2_RX_DN<9>")
	)
	(segment
		(start 369.157504 -294.83685)
		(end 369.110006 -294.810434)
		(width 0.1143)
		(layer "In6.Cu")
		(net "P5E_CPU0_P2_RX_DN<9>")
	)
	(segment
		(start 415.208212 -381.186182)
		(end 415.807906 -379.738382)
		(width 0.14224)
		(layer "In6.Cu")
		(net "P5E_CPU0_P2_RX_DN<9>")
	)
	(segment
		(start 415.953448 -376.67438)
		(end 415.953194 -376.674634)
		(width 0.14224)
		(layer "In6.Cu")
		(net "P5E_CPU0_P2_RX_DN<9>")
	)
	(segment
		(start 398.1069 -366.606074)
		(end 391.089642 -349.664528)
		(width 0.14224)
		(layer "In6.Cu")
		(net "P5E_CPU0_P2_RX_DN<9>")
	)
	(segment
		(start 414.741614 -386.693918)
		(end 414.74136 -386.693918)
		(width 0.14224)
		(layer "In6.Cu")
		(net "P5E_CPU0_P2_RX_DN<9>")
	)
	(segment
		(start 414.382204 -392.616944)
		(end 414.686242 -392.312906)
		(width 0.14224)
		(layer "In6.Cu")
		(net "P5E_CPU0_P2_RX_DN<9>")
	)
	(segment
		(start 369.6335 -285.931864)
		(end 369.56365 -285.891478)
		(width 0.1143)
		(layer "In6.Cu")
		(net "P5E_CPU0_P2_RX_DN<9>")
	)
	(segment
		(start 390.930892 -349.141796)
		(end 389.555228 -342.224868)
		(width 0.14224)
		(layer "In6.Cu")
		(net "P5E_CPU0_P2_RX_DN<9>")
	)
	(segment
		(start 414.377378 -393.22883)
		(end 414.382204 -392.616944)
		(width 0.14224)
		(layer "In6.Cu")
		(net "P5E_CPU0_P2_RX_DN<9>")
	)
	(segment
		(start 369.100608 -285.08579)
		(end 369.095528 -285.082742)
		(width 0.1143)
		(layer "In6.Cu")
		(net "P5E_CPU0_P2_RX_DN<9>")
	)
	(segment
		(start 414.686242 -390.271)
		(end 414.686242 -389.84428)
		(width 0.14224)
		(layer "In6.Cu")
		(net "P5E_CPU0_P2_RX_DN<9>")
	)
	(segment
		(start 414.376108 -374.897904)
		(end 408.833574 -373.511572)
		(width 0.14224)
		(layer "In6.Cu")
		(net "P5E_CPU0_P2_RX_DN<9>")
	)
	(segment
		(start 370.722652 -281.44597)
		(end 370.652802 -281.37612)
		(width 0.1143)
		(layer "In6.Cu")
		(net "P5E_CPU0_P2_RX_DN<9>")
	)
	(segment
		(start 369.092226 -287.391602)
		(end 369.152932 -287.356296)
		(width 0.1143)
		(layer "In6.Cu")
		(net "P5E_CPU0_P2_RX_DN<9>")
	)
	(segment
		(start 408.365452 -373.350536)
		(end 400.2659 -368.763042)
		(width 0.14224)
		(layer "In6.Cu")
		(net "P5E_CPU0_P2_RX_DN<9>")
	)
	(segment
		(start 379.81509 -311.639712)
		(end 373.513096 -303.961038)
		(width 0.14224)
		(layer "In6.Cu")
		(net "P5E_CPU0_P2_RX_DN<9>")
	)
	(segment
		(start 370.032788 -282.531566)
		(end 370.102384 -282.490926)
		(width 0.1143)
		(layer "In6.Cu")
		(net "P5E_CPU0_P2_RX_DN<9>")
	)
	(segment
		(start 369.153694 -291.59581)
		(end 369.153186 -291.59581)
		(width 0.1143)
		(layer "In6.Cu")
		(net "P5E_CPU0_P2_RX_DN<9>")
	)
	(segment
		(start 400.013678 -368.556286)
		(end 398.196054 -366.738662)
		(width 0.14224)
		(layer "In6.Cu")
		(net "P5E_CPU0_P2_RX_DN<9>")
	)
	(segment
		(start 414.218882 -393.69238)
		(end 414.572196 -393.787376)
		(width 0.14224)
		(layer "In6.Cu")
		(net "P5E_CPU0_P2_RX_DN<9>")
	)
	(segment
		(start 369.154456 -285.116778)
		(end 369.100608 -285.08579)
		(width 0.1143)
		(layer "In6.Cu")
		(net "P5E_CPU0_P2_RX_DN<9>")
	)
	(segment
		(start 414.549082 -390.40816)
		(end 414.686242 -390.271)
		(width 0.14224)
		(layer "In6.Cu")
		(net "P5E_CPU0_P2_RX_DN<9>")
	)
	(segment
		(start 369.153186 -292.216078)
		(end 369.15344 -292.216078)
		(width 0.1143)
		(layer "In6.Cu")
		(net "P5E_CPU0_P2_RX_DN<9>")
	)
	(segment
		(start 414.686242 -387.820408)
		(end 414.70707 -387.39445)
		(width 0.14224)
		(layer "In6.Cu")
		(net "P5E_CPU0_P2_RX_DN<9>")
	)
	(segment
		(start 369.1382 -289.966908)
		(end 369.137438 -289.966654)
		(width 0.1143)
		(layer "In6.Cu")
		(net "P5E_CPU0_P2_RX_DN<9>")
	)
	(segment
		(start 369.092734 -284.151578)
		(end 369.1636 -284.11043)
		(width 0.1143)
		(layer "In6.Cu")
		(net "P5E_CPU0_P2_RX_DN<9>")
	)
	(segment
		(start 369.14328 -293.20998)
		(end 369.093496 -293.181024)
		(width 0.1143)
		(layer "In6.Cu")
		(net "P5E_CPU0_P2_RX_DN<9>")
	)
	(segment
		(start 369.744498 -296.325036)
		(end 369.790218 -296.279316)
		(width 0.1143)
		(layer "In6.Cu")
		(net "P5E_CPU0_P2_RX_DN<9>")
	)
	(segment
		(start 414.74136 -386.693918)
		(end 414.957006 -382.304798)
		(width 0.14224)
		(layer "In6.Cu")
		(net "P5E_CPU0_P2_RX_DN<9>")
	)
	(segment
		(start 369.137438 -289.966654)
		(end 369.127024 -289.960558)
		(width 0.1143)
		(layer "In6.Cu")
		(net "P5E_CPU0_P2_RX_DN<9>")
	)
	(segment
		(start 373.513096 -303.961038)
		(end 370.74602 -299.819822)
		(width 0.14224)
		(layer "In6.Cu")
		(net "P5E_CPU0_P2_RX_DN<9>")
	)
	(segment
		(start 414.686242 -390.97204)
		(end 414.549082 -390.83488)
		(width 0.14224)
		(layer "In6.Cu")
		(net "P5E_CPU0_P2_RX_DN<9>")
	)
	(segment
		(start 369.790218 -296.086276)
		(end 369.78971 -296.085768)
		(width 0.1143)
		(layer "In6.Cu")
		(net "P5E_CPU0_P2_RX_DN<9>")
	)
	(segment
		(start 369.565428 -286.579564)
		(end 369.568222 -286.57804)
		(width 0.1143)
		(layer "In6.Cu")
		(net "P5E_CPU0_P2_RX_DN<9>")
	)
	(segment
		(start 369.152424 -292.216586)
		(end 369.153186 -292.216078)
		(width 0.1143)
		(layer "In6.Cu")
		(net "P5E_CPU0_P2_RX_DN<9>")
	)
	(segment
		(start 414.572704 -393.786868)
		(end 414.69437 -393.716764)
		(width 0.14224)
		(layer "In6.Cu")
		(net "P5E_CPU0_P2_RX_DN<9>")
	)
	(segment
		(start 369.319556 -295.149524)
		(end 369.319556 -295.145714)
		(width 0.1143)
		(layer "In6.Cu")
		(net "P5E_CPU0_P2_RX_DN<9>")
	)
	(segment
		(start 415.79419 -376.290078)
		(end 414.43529 -374.931178)
		(width 0.14224)
		(layer "In6.Cu")
		(net "P5E_CPU0_P2_RX_DN<9>")
	)
	(segment
		(start 369.158012 -288.97326)
		(end 369.161568 -288.970466)
		(width 0.1143)
		(layer "In6.Cu")
		(net "P5E_CPU0_P2_RX_DN<9>")
	)
	(segment
		(start 414.69437 -393.545822)
		(end 414.377378 -393.22883)
		(width 0.14224)
		(layer "In6.Cu")
		(net "P5E_CPU0_P2_RX_DN<9>")
	)
	(segment
		(start 369.790218 -296.279316)
		(end 369.790218 -296.086276)
		(width 0.1143)
		(layer "In6.Cu")
		(net "P5E_CPU0_P2_RX_DN<9>")
	)
	(segment
		(start 389.05307 -337.149186)
		(end 386.394452 -323.780912)
		(width 0.14224)
		(layer "In6.Cu")
		(net "P5E_CPU0_P2_RX_DN<9>")
	)
	(segment
		(start 380.26213 -312.309002)
		(end 379.81509 -311.639712)
		(width 0.14224)
		(layer "In6.Cu")
		(net "P5E_CPU0_P2_RX_DN<9>")
	)
	(arc
		(start 414.957006 -382.304798)
		(mid 415.034419 -381.734666)
		(end 415.208212 -381.186182)
		(width 0.14224)
		(layer "In6.Cu")
		(net "P5E_CPU0_P2_RX_DN<9>")
	)
	(arc
		(start 369.1382 -290.604956)
		(mid 369.318902 -290.285932)
		(end 369.1382 -289.966908)
		(width 0.1143)
		(layer "In6.Cu")
		(net "P5E_CPU0_P2_RX_DN<9>")
	)
	(arc
		(start 414.43529 -374.931178)
		(mid 414.407963 -374.910513)
		(end 414.376108 -374.897904)
		(width 0.14224)
		(layer "In6.Cu")
		(net "P5E_CPU0_P2_RX_DN<9>")
	)
	(arc
		(start 369.098576 -294.804592)
		(mid 369.095522 -294.802569)
		(end 369.09248 -294.800528)
		(width 0.1143)
		(layer "In6.Cu")
		(net "P5E_CPU0_P2_RX_DN<9>")
	)
	(arc
		(start 369.1636 -284.11043)
		(mid 369.275102 -283.983677)
		(end 369.31981 -283.82087)
		(width 0.1143)
		(layer "In6.Cu")
		(net "P5E_CPU0_P2_RX_DN<9>")
	)
	(arc
		(start 369.56365 -285.891478)
		(mid 369.388714 -285.697804)
		(end 369.319302 -285.446216)
		(width 0.1143)
		(layer "In6.Cu")
		(net "P5E_CPU0_P2_RX_DN<9>")
	)
	(arc
		(start 369.56238 -295.61028)
		(mid 369.383975 -295.409938)
		(end 369.319556 -295.149524)
		(width 0.1143)
		(layer "In6.Cu")
		(net "P5E_CPU0_P2_RX_DN<9>")
	)
	(arc
		(start 370.573554 -281.680412)
		(mid 370.670689 -281.577543)
		(end 370.722652 -281.44597)
		(width 0.1143)
		(layer "In6.Cu")
		(net "P5E_CPU0_P2_RX_DN<9>")
	)
	(arc
		(start 391.089642 -349.664528)
		(mid 390.997415 -349.407065)
		(end 390.930892 -349.141796)
		(width 0.14224)
		(layer "In6.Cu")
		(net "P5E_CPU0_P2_RX_DN<9>")
	)
	(arc
		(start 400.2659 -368.763042)
		(mid 400.189347 -368.714107)
		(end 400.11858 -368.657124)
		(width 0.14224)
		(layer "In6.Cu")
		(net "P5E_CPU0_P2_RX_DN<9>")
	)
	(arc
		(start 369.092734 -291.560504)
		(mid 368.849407 -291.095938)
		(end 369.092734 -290.631372)
		(width 0.1143)
		(layer "In6.Cu")
		(net "P5E_CPU0_P2_RX_DN<9>")
	)
	(arc
		(start 400.11858 -368.657124)
		(mid 400.065584 -368.607272)
		(end 400.013678 -368.556286)
		(width 0.14224)
		(layer "In6.Cu")
		(net "P5E_CPU0_P2_RX_DN<9>")
	)
	(arc
		(start 369.092734 -285.08071)
		(mid 368.849407 -284.616144)
		(end 369.092734 -284.151578)
		(width 0.1143)
		(layer "In6.Cu")
		(net "P5E_CPU0_P2_RX_DN<9>")
	)
	(arc
		(start 369.55222 -286.588962)
		(mid 369.55879 -286.584215)
		(end 369.565428 -286.579564)
		(width 0.1143)
		(layer "In6.Cu")
		(net "P5E_CPU0_P2_RX_DN<9>")
	)
	(arc
		(start 369.319556 -295.145714)
		(mid 369.273803 -294.972772)
		(end 369.157504 -294.83685)
		(width 0.1143)
		(layer "In6.Cu")
		(net "P5E_CPU0_P2_RX_DN<9>")
	)
	(arc
		(start 369.319556 -287.03143)
		(mid 369.384263 -286.783048)
		(end 369.55222 -286.588962)
		(width 0.1143)
		(layer "In6.Cu")
		(net "P5E_CPU0_P2_RX_DN<9>")
	)
	(arc
		(start 369.093496 -289.941)
		(mid 369.093115 -289.940746)
		(end 369.092734 -289.940492)
		(width 0.1143)
		(layer "In6.Cu")
		(net "P5E_CPU0_P2_RX_DN<9>")
	)
	(arc
		(start 369.31727 -285.416498)
		(mid 369.262587 -285.252121)
		(end 369.154456 -285.116778)
		(width 0.1143)
		(layer "In6.Cu")
		(net "P5E_CPU0_P2_RX_DN<9>")
	)
	(arc
		(start 369.31981 -283.82087)
		(mid 369.321033 -283.794265)
		(end 369.323874 -283.767784)
		(width 0.1143)
		(layer "In6.Cu")
		(net "P5E_CPU0_P2_RX_DN<9>")
	)
	(arc
		(start 415.953194 -376.674634)
		(mid 415.911984 -376.466515)
		(end 415.79419 -376.290078)
		(width 0.14224)
		(layer "In6.Cu")
		(net "P5E_CPU0_P2_RX_DN<9>")
	)
	(arc
		(start 370.102384 -282.490926)
		(mid 370.217811 -282.35755)
		(end 370.259356 -282.186126)
		(width 0.1143)
		(layer "In6.Cu")
		(net "P5E_CPU0_P2_RX_DN<9>")
	)
	(arc
		(start 369.093496 -293.181024)
		(mid 369.093115 -293.18077)
		(end 369.092734 -293.180516)
		(width 0.1143)
		(layer "In6.Cu")
		(net "P5E_CPU0_P2_RX_DN<9>")
	)
	(arc
		(start 369.092734 -288.320734)
		(mid 368.913921 -288.118384)
		(end 368.849402 -287.856168)
		(width 0.1143)
		(layer "In6.Cu")
		(net "P5E_CPU0_P2_RX_DN<9>")
	)
	(arc
		(start 369.418616 -283.50845)
		(mid 369.48511 -283.418103)
		(end 369.565428 -283.339794)
		(width 0.1143)
		(layer "In6.Cu")
		(net "P5E_CPU0_P2_RX_DN<9>")
	)
	(arc
		(start 415.807906 -379.738382)
		(mid 415.916658 -379.380041)
		(end 415.953448 -379.00737)
		(width 0.14224)
		(layer "In6.Cu")
		(net "P5E_CPU0_P2_RX_DN<9>")
	)
	(arc
		(start 369.093496 -291.561012)
		(mid 369.093115 -291.560758)
		(end 369.092734 -291.560504)
		(width 0.1143)
		(layer "In6.Cu")
		(net "P5E_CPU0_P2_RX_DN<9>")
	)
	(arc
		(start 369.15344 -292.216078)
		(mid 369.331982 -291.906054)
		(end 369.153694 -291.59581)
		(width 0.1143)
		(layer "In6.Cu")
		(net "P5E_CPU0_P2_RX_DN<9>")
	)
	(arc
		(start 369.323874 -283.767784)
		(mid 369.358088 -283.633308)
		(end 369.418616 -283.50845)
		(width 0.1143)
		(layer "In6.Cu")
		(net "P5E_CPU0_P2_RX_DN<9>")
	)
	(arc
		(start 369.78971 -295.955974)
		(mid 369.766882 -295.827493)
		(end 369.701318 -295.714674)
		(width 0.1143)
		(layer "In6.Cu")
		(net "P5E_CPU0_P2_RX_DN<9>")
	)
	(arc
		(start 369.092734 -289.940492)
		(mid 368.849407 -289.475926)
		(end 369.092734 -289.01136)
		(width 0.1143)
		(layer "In6.Cu")
		(net "P5E_CPU0_P2_RX_DN<9>")
	)
	(arc
		(start 408.659076 -373.467884)
		(mid 408.508294 -373.419143)
		(end 408.365452 -373.350536)
		(width 0.14224)
		(layer "In6.Cu")
		(net "P5E_CPU0_P2_RX_DN<9>")
	)
	(arc
		(start 369.092734 -293.180516)
		(mid 368.849407 -292.71595)
		(end 369.092734 -292.251384)
		(width 0.1143)
		(layer "In6.Cu")
		(net "P5E_CPU0_P2_RX_DN<9>")
	)
	(arc
		(start 368.849402 -287.856168)
		(mid 368.913781 -287.594084)
		(end 369.092226 -287.391602)
		(width 0.1143)
		(layer "In6.Cu")
		(net "P5E_CPU0_P2_RX_DN<9>")
	)
	(arc
		(start 369.14328 -293.841932)
		(mid 369.31823 -293.525956)
		(end 369.14328 -293.20998)
		(width 0.1143)
		(layer "In6.Cu")
		(net "P5E_CPU0_P2_RX_DN<9>")
	)
	(arc
		(start 369.789456 -286.236156)
		(mid 369.748201 -286.065185)
		(end 369.6335 -285.931864)
		(width 0.1143)
		(layer "In6.Cu")
		(net "P5E_CPU0_P2_RX_DN<9>")
	)
	(arc
		(start 389.555228 -342.224868)
		(mid 389.551817 -342.205128)
		(end 389.549386 -342.185244)
		(width 0.14224)
		(layer "In6.Cu")
		(net "P5E_CPU0_P2_RX_DN<9>")
	)
	(arc
		(start 369.161568 -288.970466)
		(mid 369.306822 -288.665206)
		(end 369.160552 -288.360358)
		(width 0.1143)
		(layer "In6.Cu")
		(net "P5E_CPU0_P2_RX_DN<9>")
	)
	(arc
		(start 408.833574 -373.511572)
		(mid 408.746098 -373.490633)
		(end 408.659076 -373.467884)
		(width 0.14224)
		(layer "In6.Cu")
		(net "P5E_CPU0_P2_RX_DN<9>")
	)
	(arc
		(start 369.701318 -295.714674)
		(mid 369.669359 -295.681079)
		(end 369.6335 -295.651682)
		(width 0.1143)
		(layer "In6.Cu")
		(net "P5E_CPU0_P2_RX_DN<9>")
	)
	(arc
		(start 369.789456 -282.996132)
		(mid 369.853971 -282.733913)
		(end 370.032788 -282.531566)
		(width 0.1143)
		(layer "In6.Cu")
		(net "P5E_CPU0_P2_RX_DN<9>")
	)
	(arc
		(start 370.259356 -282.186126)
		(mid 370.323871 -281.923907)
		(end 370.502688 -281.72156)
		(width 0.1143)
		(layer "In6.Cu")
		(net "P5E_CPU0_P2_RX_DN<9>")
	)
	(arc
		(start 369.152932 -287.356296)
		(mid 369.262398 -287.220656)
		(end 369.317524 -287.055306)
		(width 0.1143)
		(layer "In6.Cu")
		(net "P5E_CPU0_P2_RX_DN<9>")
	)
	(arc
		(start 369.635278 -286.538924)
		(mid 369.748685 -286.406035)
		(end 369.789456 -286.236156)
		(width 0.1143)
		(layer "In6.Cu")
		(net "P5E_CPU0_P2_RX_DN<9>")
	)
	(arc
		(start 369.317524 -287.055306)
		(mid 369.318834 -287.043393)
		(end 369.319556 -287.03143)
		(width 0.1143)
		(layer "In6.Cu")
		(net "P5E_CPU0_P2_RX_DN<9>")
	)
	(arc
		(start 369.092734 -294.800528)
		(mid 368.849407 -294.335962)
		(end 369.092734 -293.871396)
		(width 0.1143)
		(layer "In6.Cu")
		(net "P5E_CPU0_P2_RX_DN<9>")
	)
	(arc
		(start 369.6335 -283.300424)
		(mid 369.748176 -283.16709)
		(end 369.789456 -282.996132)
		(width 0.1143)
		(layer "In6.Cu")
		(net "P5E_CPU0_P2_RX_DN<9>")
	)
	(arc
		(start 369.319302 -285.446216)
		(mid 369.318729 -285.431327)
		(end 369.31727 -285.416498)
		(width 0.1143)
		(layer "In6.Cu")
		(net "P5E_CPU0_P2_RX_DN<9>")
	)
	(arc
		(start 398.196054 -366.738662)
		(mid 398.14494 -366.676763)
		(end 398.1069 -366.606074)
		(width 0.14224)
		(layer "In6.Cu")
		(net "P5E_CPU0_P2_RX_DN<9>")
	)
	(segment
		(start 412.498286 -393.69238)
		(end 413.018986 -393.69238)
		(width 0.127)
		(layer "F.Cu")
		(net "P5E_CPU0_P2_RX_DN<8>")
	)
	(segment
		(start 367.067846 -284.350206)
		(end 367.534698 -284.616144)
		(width 0.12954)
		(layer "F.Cu")
		(net "P5E_CPU0_P2_RX_DN<8>")
	)
	(segment
		(start 379.122432 -312.283856)
		(end 372.790212 -304.568098)
		(width 0.14224)
		(layer "In6.Cu")
		(net "P5E_CPU0_P2_RX_DN<8>")
	)
	(segment
		(start 368.223546 -285.121858)
		(end 368.198908 -285.107634)
		(width 0.1143)
		(layer "In6.Cu")
		(net "P5E_CPU0_P2_RX_DN<8>")
	)
	(segment
		(start 367.915444 -284.698948)
		(end 367.83264 -284.616144)
		(width 0.1143)
		(layer "In6.Cu")
		(net "P5E_CPU0_P2_RX_DN<8>")
	)
	(segment
		(start 368.852196 -296.088308)
		(end 368.849656 -296.085768)
		(width 0.1143)
		(layer "In6.Cu")
		(net "P5E_CPU0_P2_RX_DN<8>")
	)
	(segment
		(start 368.66195 -285.913576)
		(end 368.622834 -285.890716)
		(width 0.1143)
		(layer "In6.Cu")
		(net "P5E_CPU0_P2_RX_DN<8>")
	)
	(segment
		(start 368.224308 -288.36239)
		(end 368.191796 -288.343594)
		(width 0.1143)
		(layer "In6.Cu")
		(net "P5E_CPU0_P2_RX_DN<8>")
	)
	(segment
		(start 413.349186 -388.62254)
		(end 413.349186 -388.19582)
		(width 0.14224)
		(layer "In6.Cu")
		(net "P5E_CPU0_P2_RX_DN<8>")
	)
	(segment
		(start 413.486346 -392.312906)
		(end 413.486346 -391.01522)
		(width 0.14224)
		(layer "In6.Cu")
		(net "P5E_CPU0_P2_RX_DN<8>")
	)
	(segment
		(start 368.191796 -288.343594)
		(end 368.15268 -288.320734)
		(width 0.1143)
		(layer "In6.Cu")
		(net "P5E_CPU0_P2_RX_DN<8>")
	)
	(segment
		(start 368.15268 -292.251384)
		(end 368.191796 -292.228524)
		(width 0.1143)
		(layer "In6.Cu")
		(net "P5E_CPU0_P2_RX_DN<8>")
	)
	(segment
		(start 368.189256 -285.102046)
		(end 368.18824 -285.101538)
		(width 0.1143)
		(layer "In6.Cu")
		(net "P5E_CPU0_P2_RX_DN<8>")
	)
	(segment
		(start 412.027624 -375.676922)
		(end 411.889448 -375.538746)
		(width 0.14224)
		(layer "In6.Cu")
		(net "P5E_CPU0_P2_RX_DN<8>")
	)
	(segment
		(start 368.15268 -289.01136)
		(end 368.191796 -288.9885)
		(width 0.1143)
		(layer "In6.Cu")
		(net "P5E_CPU0_P2_RX_DN<8>")
	)
	(segment
		(start 368.18824 -287.37052)
		(end 368.189256 -287.370012)
		(width 0.1143)
		(layer "In6.Cu")
		(net "P5E_CPU0_P2_RX_DN<8>")
	)
	(segment
		(start 368.191796 -292.228524)
		(end 368.222276 -292.210744)
		(width 0.1143)
		(layer "In6.Cu")
		(net "P5E_CPU0_P2_RX_DN<8>")
	)
	(segment
		(start 413.349186 -389.7503)
		(end 413.349186 -389.32358)
		(width 0.14224)
		(layer "In6.Cu")
		(net "P5E_CPU0_P2_RX_DN<8>")
	)
	(segment
		(start 368.69243 -295.651174)
		(end 368.622834 -295.610534)
		(width 0.1143)
		(layer "In6.Cu")
		(net "P5E_CPU0_P2_RX_DN<8>")
	)
	(segment
		(start 398.787874 -368.78006)
		(end 397.310864 -367.30305)
		(width 0.14224)
		(layer "In6.Cu")
		(net "P5E_CPU0_P2_RX_DN<8>")
	)
	(segment
		(start 368.191796 -288.9885)
		(end 368.222276 -288.97072)
		(width 0.1143)
		(layer "In6.Cu")
		(net "P5E_CPU0_P2_RX_DN<8>")
	)
	(segment
		(start 413.486346 -391.01522)
		(end 413.349186 -390.87806)
		(width 0.14224)
		(layer "In6.Cu")
		(net "P5E_CPU0_P2_RX_DN<8>")
	)
	(segment
		(start 368.622834 -286.581342)
		(end 368.66195 -286.558482)
		(width 0.1143)
		(layer "In6.Cu")
		(net "P5E_CPU0_P2_RX_DN<8>")
	)
	(segment
		(start 413.832548 -378.925582)
		(end 413.535114 -378.82322)
		(width 0.14224)
		(layer "In6.Cu")
		(net "P5E_CPU0_P2_RX_DN<8>")
	)
	(segment
		(start 367.83264 -284.616144)
		(end 367.534698 -284.616144)
		(width 0.1143)
		(layer "In6.Cu")
		(net "P5E_CPU0_P2_RX_DN<8>")
	)
	(segment
		(start 368.18824 -285.101538)
		(end 368.15268 -285.08071)
		(width 0.1143)
		(layer "In6.Cu")
		(net "P5E_CPU0_P2_RX_DN<8>")
	)
	(segment
		(start 368.196368 -285.10611)
		(end 368.193828 -285.10484)
		(width 0.1143)
		(layer "In6.Cu")
		(net "P5E_CPU0_P2_RX_DN<8>")
	)
	(segment
		(start 368.191796 -287.368488)
		(end 368.192558 -287.36798)
		(width 0.1143)
		(layer "In6.Cu")
		(net "P5E_CPU0_P2_RX_DN<8>")
	)
	(segment
		(start 368.806476 -296.325036)
		(end 368.852196 -296.279316)
		(width 0.1143)
		(layer "In6.Cu")
		(net "P5E_CPU0_P2_RX_DN<8>")
	)
	(segment
		(start 413.018986 -393.69238)
		(end 413.3723 -393.787376)
		(width 0.14224)
		(layer "In6.Cu")
		(net "P5E_CPU0_P2_RX_DN<8>")
	)
	(segment
		(start 368.15522 -287.389824)
		(end 368.18824 -287.37052)
		(width 0.1143)
		(layer "In6.Cu")
		(net "P5E_CPU0_P2_RX_DN<8>")
	)
	(segment
		(start 368.19078 -287.368996)
		(end 368.191796 -287.368488)
		(width 0.1143)
		(layer "In6.Cu")
		(net "P5E_CPU0_P2_RX_DN<8>")
	)
	(segment
		(start 368.191796 -291.583364)
		(end 368.15268 -291.560504)
		(width 0.1143)
		(layer "In6.Cu")
		(net "P5E_CPU0_P2_RX_DN<8>")
	)
	(segment
		(start 368.193828 -285.10484)
		(end 368.192558 -285.104078)
		(width 0.1143)
		(layer "In6.Cu")
		(net "P5E_CPU0_P2_RX_DN<8>")
	)
	(segment
		(start 413.927036 -381.844042)
		(end 414.24987 -380.221236)
		(width 0.14224)
		(layer "In6.Cu")
		(net "P5E_CPU0_P2_RX_DN<8>")
	)
	(segment
		(start 368.196622 -287.365694)
		(end 368.197638 -287.365186)
		(width 0.1143)
		(layer "In6.Cu")
		(net "P5E_CPU0_P2_RX_DN<8>")
	)
	(segment
		(start 413.349186 -390.45134)
		(end 413.486346 -390.31418)
		(width 0.14224)
		(layer "In6.Cu")
		(net "P5E_CPU0_P2_RX_DN<8>")
	)
	(segment
		(start 413.372808 -393.786868)
		(end 413.494474 -393.716764)
		(width 0.14224)
		(layer "In6.Cu")
		(net "P5E_CPU0_P2_RX_DN<8>")
	)
	(segment
		(start 388.078726 -337.071208)
		(end 385.501134 -324.112128)
		(width 0.14224)
		(layer "In6.Cu")
		(net "P5E_CPU0_P2_RX_DN<8>")
	)
	(segment
		(start 397.220694 -367.166144)
		(end 390.239504 -350.311974)
		(width 0.14224)
		(layer "In6.Cu")
		(net "P5E_CPU0_P2_RX_DN<8>")
	)
	(segment
		(start 413.3723 -393.787376)
		(end 413.372808 -393.786868)
		(width 0.14224)
		(layer "In6.Cu")
		(net "P5E_CPU0_P2_RX_DN<8>")
	)
	(segment
		(start 368.19586 -287.366202)
		(end 368.196622 -287.365694)
		(width 0.1143)
		(layer "In6.Cu")
		(net "P5E_CPU0_P2_RX_DN<8>")
	)
	(segment
		(start 368.222276 -289.981132)
		(end 368.191796 -289.963352)
		(width 0.1143)
		(layer "In6.Cu")
		(net "P5E_CPU0_P2_RX_DN<8>")
	)
	(segment
		(start 369.946936 -300.31309)
		(end 369.946682 -300.31309)
		(width 0.14224)
		(layer "In6.Cu")
		(net "P5E_CPU0_P2_RX_DN<8>")
	)
	(segment
		(start 413.182308 -392.61669)
		(end 413.486346 -392.312906)
		(width 0.14224)
		(layer "In6.Cu")
		(net "P5E_CPU0_P2_RX_DN<8>")
	)
	(segment
		(start 413.494474 -393.545822)
		(end 413.177482 -393.22883)
		(width 0.14224)
		(layer "In6.Cu")
		(net "P5E_CPU0_P2_RX_DN<8>")
	)
	(segment
		(start 369.931442 -300.289976)
		(end 368.806476 -297.573954)
		(width 0.14224)
		(layer "In6.Cu")
		(net "P5E_CPU0_P2_RX_DN<8>")
	)
	(segment
		(start 390.092946 -349.828104)
		(end 388.596632 -342.304878)
		(width 0.14224)
		(layer "In6.Cu")
		(net "P5E_CPU0_P2_RX_DN<8>")
	)
	(segment
		(start 413.177482 -393.22883)
		(end 413.182308 -392.61669)
		(width 0.14224)
		(layer "In6.Cu")
		(net "P5E_CPU0_P2_RX_DN<8>")
	)
	(segment
		(start 412.548324 -377.624594)
		(end 412.548324 -376.933968)
		(width 0.14224)
		(layer "In6.Cu")
		(net "P5E_CPU0_P2_RX_DN<8>")
	)
	(segment
		(start 368.191796 -293.848536)
		(end 368.222276 -293.830756)
		(width 0.1143)
		(layer "In6.Cu")
		(net "P5E_CPU0_P2_RX_DN<8>")
	)
	(segment
		(start 368.197892 -285.107126)
		(end 368.196368 -285.10611)
		(width 0.1143)
		(layer "In6.Cu")
		(net "P5E_CPU0_P2_RX_DN<8>")
	)
	(segment
		(start 369.946682 -300.31309)
		(end 369.931442 -300.289976)
		(width 0.14224)
		(layer "In6.Cu")
		(net "P5E_CPU0_P2_RX_DN<8>")
	)
	(segment
		(start 414.24987 -380.221236)
		(end 414.24987 -379.638052)
		(width 0.14224)
		(layer "In6.Cu")
		(net "P5E_CPU0_P2_RX_DN<8>")
	)
	(segment
		(start 368.15268 -290.631372)
		(end 368.191796 -290.608512)
		(width 0.1143)
		(layer "In6.Cu")
		(net "P5E_CPU0_P2_RX_DN<8>")
	)
	(segment
		(start 413.057848 -378.54255)
		(end 412.837122 -378.321824)
		(width 0.14224)
		(layer "In6.Cu")
		(net "P5E_CPU0_P2_RX_DN<8>")
	)
	(segment
		(start 368.19078 -285.103062)
		(end 368.189256 -285.102046)
		(width 0.1143)
		(layer "In6.Cu")
		(net "P5E_CPU0_P2_RX_DN<8>")
	)
	(segment
		(start 379.400816 -312.70067)
		(end 379.122432 -312.283856)
		(width 0.14224)
		(layer "In6.Cu")
		(net "P5E_CPU0_P2_RX_DN<8>")
	)
	(segment
		(start 368.806476 -296.353484)
		(end 368.806476 -296.325036)
		(width 0.1143)
		(layer "In6.Cu")
		(net "P5E_CPU0_P2_RX_DN<8>")
	)
	(segment
		(start 368.222276 -293.221156)
		(end 368.191796 -293.203376)
		(width 0.1143)
		(layer "In6.Cu")
		(net "P5E_CPU0_P2_RX_DN<8>")
	)
	(segment
		(start 368.189256 -287.370012)
		(end 368.19078 -287.368996)
		(width 0.1143)
		(layer "In6.Cu")
		(net "P5E_CPU0_P2_RX_DN<8>")
	)
	(segment
		(start 368.192558 -287.36798)
		(end 368.19586 -287.366202)
		(width 0.1143)
		(layer "In6.Cu")
		(net "P5E_CPU0_P2_RX_DN<8>")
	)
	(segment
		(start 368.66195 -286.558482)
		(end 368.694462 -286.539686)
		(width 0.1143)
		(layer "In6.Cu")
		(net "P5E_CPU0_P2_RX_DN<8>")
	)
	(segment
		(start 368.222276 -294.841168)
		(end 368.191796 -294.823388)
		(width 0.1143)
		(layer "In6.Cu")
		(net "P5E_CPU0_P2_RX_DN<8>")
	)
	(segment
		(start 368.69243 -285.931356)
		(end 368.66195 -285.913576)
		(width 0.1143)
		(layer "In6.Cu")
		(net "P5E_CPU0_P2_RX_DN<8>")
	)
	(segment
		(start 368.191796 -285.10357)
		(end 368.19078 -285.103062)
		(width 0.1143)
		(layer "In6.Cu")
		(net "P5E_CPU0_P2_RX_DN<8>")
	)
	(segment
		(start 368.191796 -290.608512)
		(end 368.222276 -290.590732)
		(width 0.1143)
		(layer "In6.Cu")
		(net "P5E_CPU0_P2_RX_DN<8>")
	)
	(segment
		(start 368.191796 -294.823388)
		(end 368.15268 -294.800528)
		(width 0.1143)
		(layer "In6.Cu")
		(net "P5E_CPU0_P2_RX_DN<8>")
	)
	(segment
		(start 368.849656 -296.085768)
		(end 368.849656 -295.955974)
		(width 0.1143)
		(layer "In6.Cu")
		(net "P5E_CPU0_P2_RX_DN<8>")
	)
	(segment
		(start 388.59079 -342.265254)
		(end 388.078726 -337.071208)
		(width 0.14224)
		(layer "In6.Cu")
		(net "P5E_CPU0_P2_RX_DN<8>")
	)
	(segment
		(start 413.486346 -389.88746)
		(end 413.349186 -389.7503)
		(width 0.14224)
		(layer "In6.Cu")
		(net "P5E_CPU0_P2_RX_DN<8>")
	)
	(segment
		(start 368.15268 -293.871396)
		(end 368.191796 -293.848536)
		(width 0.1143)
		(layer "In6.Cu")
		(net "P5E_CPU0_P2_RX_DN<8>")
	)
	(segment
		(start 410.951934 -375.007632)
		(end 408.008836 -374.271286)
		(width 0.14224)
		(layer "In6.Cu")
		(net "P5E_CPU0_P2_RX_DN<8>")
	)
	(segment
		(start 413.486346 -390.31418)
		(end 413.486346 -389.88746)
		(width 0.14224)
		(layer "In6.Cu")
		(net "P5E_CPU0_P2_RX_DN<8>")
	)
	(segment
		(start 408.008836 -374.271286)
		(end 400.166586 -369.828826)
		(width 0.14224)
		(layer "In6.Cu")
		(net "P5E_CPU0_P2_RX_DN<8>")
	)
	(segment
		(start 368.852196 -296.279316)
		(end 368.852196 -296.088308)
		(width 0.1143)
		(layer "In6.Cu")
		(net "P5E_CPU0_P2_RX_DN<8>")
	)
	(segment
		(start 413.486346 -388.7597)
		(end 413.349186 -388.62254)
		(width 0.14224)
		(layer "In6.Cu")
		(net "P5E_CPU0_P2_RX_DN<8>")
	)
	(segment
		(start 414.012888 -379.066044)
		(end 413.938974 -378.99213)
		(width 0.14224)
		(layer "In6.Cu")
		(net "P5E_CPU0_P2_RX_DN<8>")
	)
	(segment
		(start 368.198908 -285.107634)
		(end 368.197892 -285.107126)
		(width 0.1143)
		(layer "In6.Cu")
		(net "P5E_CPU0_P2_RX_DN<8>")
	)
	(segment
		(start 413.494474 -393.716764)
		(end 413.494474 -393.545822)
		(width 0.14224)
		(layer "In6.Cu")
		(net "P5E_CPU0_P2_RX_DN<8>")
	)
	(segment
		(start 368.222276 -291.601144)
		(end 368.191796 -291.583364)
		(width 0.1143)
		(layer "In6.Cu")
		(net "P5E_CPU0_P2_RX_DN<8>")
	)
	(segment
		(start 368.191796 -293.203376)
		(end 368.15268 -293.180516)
		(width 0.1143)
		(layer "In6.Cu")
		(net "P5E_CPU0_P2_RX_DN<8>")
	)
	(segment
		(start 372.790212 -304.568098)
		(end 369.946936 -300.31309)
		(width 0.14224)
		(layer "In6.Cu")
		(net "P5E_CPU0_P2_RX_DN<8>")
	)
	(segment
		(start 368.197638 -287.365186)
		(end 368.223546 -287.3502)
		(width 0.1143)
		(layer "In6.Cu")
		(net "P5E_CPU0_P2_RX_DN<8>")
	)
	(segment
		(start 368.379502 -295.145968)
		(end 368.379248 -295.145968)
		(width 0.1143)
		(layer "In6.Cu")
		(net "P5E_CPU0_P2_RX_DN<8>")
	)
	(segment
		(start 413.486346 -388.05866)
		(end 413.486346 -386.321046)
		(width 0.14224)
		(layer "In6.Cu")
		(net "P5E_CPU0_P2_RX_DN<8>")
	)
	(segment
		(start 368.192558 -285.104078)
		(end 368.191796 -285.10357)
		(width 0.1143)
		(layer "In6.Cu")
		(net "P5E_CPU0_P2_RX_DN<8>")
	)
	(segment
		(start 368.806476 -297.573954)
		(end 368.806476 -296.353484)
		(width 0.14224)
		(layer "In6.Cu")
		(net "P5E_CPU0_P2_RX_DN<8>")
	)
	(segment
		(start 413.349186 -390.87806)
		(end 413.349186 -390.45134)
		(width 0.14224)
		(layer "In6.Cu")
		(net "P5E_CPU0_P2_RX_DN<8>")
	)
	(segment
		(start 413.349186 -389.32358)
		(end 413.486346 -389.18642)
		(width 0.14224)
		(layer "In6.Cu")
		(net "P5E_CPU0_P2_RX_DN<8>")
	)
	(segment
		(start 413.349186 -388.19582)
		(end 413.486346 -388.05866)
		(width 0.14224)
		(layer "In6.Cu")
		(net "P5E_CPU0_P2_RX_DN<8>")
	)
	(segment
		(start 413.486346 -389.18642)
		(end 413.486346 -388.7597)
		(width 0.14224)
		(layer "In6.Cu")
		(net "P5E_CPU0_P2_RX_DN<8>")
	)
	(segment
		(start 368.191796 -289.963352)
		(end 368.15268 -289.940492)
		(width 0.1143)
		(layer "In6.Cu")
		(net "P5E_CPU0_P2_RX_DN<8>")
	)
	(segment
		(start 385.501134 -324.112128)
		(end 379.400816 -312.70067)
		(width 0.14224)
		(layer "In6.Cu")
		(net "P5E_CPU0_P2_RX_DN<8>")
	)
	(segment
		(start 413.486346 -386.321046)
		(end 413.927036 -381.844042)
		(width 0.14224)
		(layer "In6.Cu")
		(net "P5E_CPU0_P2_RX_DN<8>")
	)
	(arc
		(start 368.849402 -286.236156)
		(mid 368.807853 -286.064734)
		(end 368.69243 -285.931356)
		(width 0.1143)
		(layer "In6.Cu")
		(net "P5E_CPU0_P2_RX_DN<8>")
	)
	(arc
		(start 368.15268 -289.940492)
		(mid 367.909353 -289.475926)
		(end 368.15268 -289.01136)
		(width 0.1143)
		(layer "In6.Cu")
		(net "P5E_CPU0_P2_RX_DN<8>")
	)
	(arc
		(start 412.548324 -376.933968)
		(mid 412.413001 -376.253654)
		(end 412.027624 -375.676922)
		(width 0.14224)
		(layer "In6.Cu")
		(net "P5E_CPU0_P2_RX_DN<8>")
	)
	(arc
		(start 368.223546 -287.3502)
		(mid 368.338222 -287.216866)
		(end 368.379502 -287.045908)
		(width 0.1143)
		(layer "In6.Cu")
		(net "P5E_CPU0_P2_RX_DN<8>")
	)
	(arc
		(start 400.166586 -369.828826)
		(mid 399.441787 -369.351036)
		(end 398.787874 -368.78006)
		(width 0.14224)
		(layer "In6.Cu")
		(net "P5E_CPU0_P2_RX_DN<8>")
	)
	(arc
		(start 368.379502 -287.045908)
		(mid 368.444017 -286.783689)
		(end 368.622834 -286.581342)
		(width 0.1143)
		(layer "In6.Cu")
		(net "P5E_CPU0_P2_RX_DN<8>")
	)
	(arc
		(start 367.909348 -287.856168)
		(mid 367.974584 -287.592577)
		(end 368.15522 -287.389824)
		(width 0.1143)
		(layer "In6.Cu")
		(net "P5E_CPU0_P2_RX_DN<8>")
	)
	(arc
		(start 390.239504 -350.311974)
		(mid 390.154328 -350.073642)
		(end 390.092946 -349.828104)
		(width 0.14224)
		(layer "In6.Cu")
		(net "P5E_CPU0_P2_RX_DN<8>")
	)
	(arc
		(start 368.721894 -295.674542)
		(mid 368.707459 -295.662483)
		(end 368.69243 -295.651174)
		(width 0.1143)
		(layer "In6.Cu")
		(net "P5E_CPU0_P2_RX_DN<8>")
	)
	(arc
		(start 397.309848 -367.302034)
		(mid 397.258446 -367.238564)
		(end 397.220694 -367.166144)
		(width 0.14224)
		(layer "In6.Cu")
		(net "P5E_CPU0_P2_RX_DN<8>")
	)
	(arc
		(start 413.535114 -378.82322)
		(mid 413.467005 -378.798669)
		(end 413.399732 -378.771912)
		(width 0.14224)
		(layer "In6.Cu")
		(net "P5E_CPU0_P2_RX_DN<8>")
	)
	(arc
		(start 368.15268 -288.320734)
		(mid 367.973867 -288.118384)
		(end 367.909348 -287.856168)
		(width 0.1143)
		(layer "In6.Cu")
		(net "P5E_CPU0_P2_RX_DN<8>")
	)
	(arc
		(start 368.622834 -285.890716)
		(mid 368.444021 -285.688366)
		(end 368.379502 -285.42615)
		(width 0.1143)
		(layer "In6.Cu")
		(net "P5E_CPU0_P2_RX_DN<8>")
	)
	(arc
		(start 367.919254 -284.721808)
		(mid 367.917231 -284.710398)
		(end 367.915444 -284.698948)
		(width 0.1143)
		(layer "In6.Cu")
		(net "P5E_CPU0_P2_RX_DN<8>")
	)
	(arc
		(start 368.15268 -293.180516)
		(mid 367.909353 -292.71595)
		(end 368.15268 -292.251384)
		(width 0.1143)
		(layer "In6.Cu")
		(net "P5E_CPU0_P2_RX_DN<8>")
	)
	(arc
		(start 368.849656 -295.955974)
		(mid 368.81617 -295.80146)
		(end 368.721894 -295.674542)
		(width 0.1143)
		(layer "In6.Cu")
		(net "P5E_CPU0_P2_RX_DN<8>")
	)
	(arc
		(start 368.15268 -291.560504)
		(mid 367.909353 -291.095938)
		(end 368.15268 -290.631372)
		(width 0.1143)
		(layer "In6.Cu")
		(net "P5E_CPU0_P2_RX_DN<8>")
	)
	(arc
		(start 368.222276 -293.830756)
		(mid 368.379253 -293.525956)
		(end 368.222276 -293.221156)
		(width 0.1143)
		(layer "In6.Cu")
		(net "P5E_CPU0_P2_RX_DN<8>")
	)
	(arc
		(start 368.15268 -285.08071)
		(mid 368.000693 -284.924202)
		(end 367.919254 -284.721808)
		(width 0.1143)
		(layer "In6.Cu")
		(net "P5E_CPU0_P2_RX_DN<8>")
	)
	(arc
		(start 414.24987 -379.638052)
		(mid 414.188274 -379.328479)
		(end 414.012888 -379.066044)
		(width 0.14224)
		(layer "In6.Cu")
		(net "P5E_CPU0_P2_RX_DN<8>")
	)
	(arc
		(start 368.694462 -286.539686)
		(mid 368.808391 -286.406539)
		(end 368.849402 -286.236156)
		(width 0.1143)
		(layer "In6.Cu")
		(net "P5E_CPU0_P2_RX_DN<8>")
	)
	(arc
		(start 368.622834 -295.610534)
		(mid 368.444021 -295.408184)
		(end 368.379502 -295.145968)
		(width 0.1143)
		(layer "In6.Cu")
		(net "P5E_CPU0_P2_RX_DN<8>")
	)
	(arc
		(start 368.222276 -292.210744)
		(mid 368.379253 -291.905944)
		(end 368.222276 -291.601144)
		(width 0.1143)
		(layer "In6.Cu")
		(net "P5E_CPU0_P2_RX_DN<8>")
	)
	(arc
		(start 388.596632 -342.304878)
		(mid 388.593221 -342.285138)
		(end 388.59079 -342.265254)
		(width 0.14224)
		(layer "In6.Cu")
		(net "P5E_CPU0_P2_RX_DN<8>")
	)
	(arc
		(start 368.379502 -285.42615)
		(mid 368.338247 -285.255179)
		(end 368.223546 -285.121858)
		(width 0.1143)
		(layer "In6.Cu")
		(net "P5E_CPU0_P2_RX_DN<8>")
	)
	(arc
		(start 368.222276 -288.97072)
		(mid 368.337703 -288.837344)
		(end 368.379248 -288.66592)
		(width 0.1143)
		(layer "In6.Cu")
		(net "P5E_CPU0_P2_RX_DN<8>")
	)
	(arc
		(start 412.837122 -378.321824)
		(mid 412.623377 -378.001932)
		(end 412.548324 -377.624594)
		(width 0.14224)
		(layer "In6.Cu")
		(net "P5E_CPU0_P2_RX_DN<8>")
	)
	(arc
		(start 411.889448 -375.538746)
		(mid 411.456767 -375.209511)
		(end 410.951934 -375.007632)
		(width 0.14224)
		(layer "In6.Cu")
		(net "P5E_CPU0_P2_RX_DN<8>")
	)
	(arc
		(start 397.310864 -367.30305)
		(mid 397.310356 -367.302542)
		(end 397.309848 -367.302034)
		(width 0.14224)
		(layer "In6.Cu")
		(net "P5E_CPU0_P2_RX_DN<8>")
	)
	(arc
		(start 368.379248 -288.66592)
		(mid 368.338282 -288.495514)
		(end 368.224308 -288.36239)
		(width 0.1143)
		(layer "In6.Cu")
		(net "P5E_CPU0_P2_RX_DN<8>")
	)
	(arc
		(start 413.399732 -378.771912)
		(mid 413.217573 -378.673951)
		(end 413.057848 -378.54255)
		(width 0.14224)
		(layer "In6.Cu")
		(net "P5E_CPU0_P2_RX_DN<8>")
	)
	(arc
		(start 413.938974 -378.99213)
		(mid 413.889545 -378.952808)
		(end 413.832548 -378.925582)
		(width 0.14224)
		(layer "In6.Cu")
		(net "P5E_CPU0_P2_RX_DN<8>")
	)
	(arc
		(start 368.222276 -290.590732)
		(mid 368.379253 -290.285932)
		(end 368.222276 -289.981132)
		(width 0.1143)
		(layer "In6.Cu")
		(net "P5E_CPU0_P2_RX_DN<8>")
	)
	(arc
		(start 368.15268 -294.800528)
		(mid 367.909353 -294.335962)
		(end 368.15268 -293.871396)
		(width 0.1143)
		(layer "In6.Cu")
		(net "P5E_CPU0_P2_RX_DN<8>")
	)
	(arc
		(start 368.379248 -295.145968)
		(mid 368.337699 -294.974546)
		(end 368.222276 -294.841168)
		(width 0.1143)
		(layer "In6.Cu")
		(net "P5E_CPU0_P2_RX_DN<8>")
	)
	(segment
		(start 367.067846 -285.970218)
		(end 367.534698 -286.236156)
		(width 0.12954)
		(layer "F.Cu")
		(net "P5E_CPU0_P2_RX_DN<7>")
	)
	(segment
		(start 411.29839 -393.69238)
		(end 411.81909 -393.69238)
		(width 0.127)
		(layer "F.Cu")
		(net "P5E_CPU0_P2_RX_DN<7>")
	)
	(segment
		(start 367.212626 -290.631372)
		(end 367.282222 -290.590732)
		(width 0.1143)
		(layer "In6.Cu")
		(net "P5E_CPU0_P2_RX_DN<7>")
	)
	(segment
		(start 412.427928 -386.770118)
		(end 412.428182 -386.768848)
		(width 0.14224)
		(layer "In6.Cu")
		(net "P5E_CPU0_P2_RX_DN<7>")
	)
	(segment
		(start 367.219484 -287.387284)
		(end 367.220246 -287.386776)
		(width 0.1143)
		(layer "In6.Cu")
		(net "P5E_CPU0_P2_RX_DN<7>")
	)
	(segment
		(start 367.282222 -289.981132)
		(end 367.212626 -289.940492)
		(width 0.1143)
		(layer "In6.Cu")
		(net "P5E_CPU0_P2_RX_DN<7>")
	)
	(segment
		(start 367.224056 -289.004248)
		(end 367.22558 -289.003486)
		(width 0.1143)
		(layer "In6.Cu")
		(net "P5E_CPU0_P2_RX_DN<7>")
	)
	(segment
		(start 412.33344 -389.021828)
		(end 412.35122 -388.597902)
		(width 0.14224)
		(layer "In6.Cu")
		(net "P5E_CPU0_P2_RX_DN<7>")
	)
	(segment
		(start 367.230914 -289.000438)
		(end 367.23193 -288.99993)
		(width 0.1143)
		(layer "In6.Cu")
		(net "P5E_CPU0_P2_RX_DN<7>")
	)
	(segment
		(start 412.303976 -389.7249)
		(end 412.172658 -389.582152)
		(width 0.14224)
		(layer "In6.Cu")
		(net "P5E_CPU0_P2_RX_DN<7>")
	)
	(segment
		(start 398.566386 -369.98148)
		(end 396.727172 -368.142266)
		(width 0.14224)
		(layer "In6.Cu")
		(net "P5E_CPU0_P2_RX_DN<7>")
	)
	(segment
		(start 367.212626 -289.01136)
		(end 367.21542 -289.009328)
		(width 0.1143)
		(layer "In6.Cu")
		(net "P5E_CPU0_P2_RX_DN<7>")
	)
	(segment
		(start 412.294324 -393.545822)
		(end 411.977332 -393.22883)
		(width 0.14224)
		(layer "In6.Cu")
		(net "P5E_CPU0_P2_RX_DN<7>")
	)
	(segment
		(start 412.398464 -387.471158)
		(end 412.398972 -387.470904)
		(width 0.14224)
		(layer "In6.Cu")
		(net "P5E_CPU0_P2_RX_DN<7>")
	)
	(segment
		(start 367.23193 -288.99993)
		(end 367.283492 -288.970212)
		(width 0.1143)
		(layer "In6.Cu")
		(net "P5E_CPU0_P2_RX_DN<7>")
	)
	(segment
		(start 367.90249 -286.306006)
		(end 367.83264 -286.236156)
		(width 0.1143)
		(layer "In6.Cu")
		(net "P5E_CPU0_P2_RX_DN<7>")
	)
	(segment
		(start 412.190692 -389.155432)
		(end 412.333694 -389.024114)
		(width 0.14224)
		(layer "In6.Cu")
		(net "P5E_CPU0_P2_RX_DN<7>")
	)
	(segment
		(start 367.21542 -289.009328)
		(end 367.222024 -289.005518)
		(width 0.1143)
		(layer "In6.Cu")
		(net "P5E_CPU0_P2_RX_DN<7>")
	)
	(segment
		(start 412.286196 -390.151112)
		(end 412.303976 -389.7249)
		(width 0.14224)
		(layer "In6.Cu")
		(net "P5E_CPU0_P2_RX_DN<7>")
	)
	(segment
		(start 411.81909 -393.69238)
		(end 412.17215 -393.787376)
		(width 0.14224)
		(layer "In6.Cu")
		(net "P5E_CPU0_P2_RX_DN<7>")
	)
	(segment
		(start 367.68278 -286.581342)
		(end 367.754408 -286.539686)
		(width 0.1143)
		(layer "In6.Cu")
		(net "P5E_CPU0_P2_RX_DN<7>")
	)
	(segment
		(start 412.398972 -387.470904)
		(end 412.267654 -387.328156)
		(width 0.14224)
		(layer "In6.Cu")
		(net "P5E_CPU0_P2_RX_DN<7>")
	)
	(segment
		(start 367.230152 -289.000946)
		(end 367.230914 -289.000438)
		(width 0.1143)
		(layer "In6.Cu")
		(net "P5E_CPU0_P2_RX_DN<7>")
	)
	(segment
		(start 367.920016 -296.086276)
		(end 367.919508 -296.085768)
		(width 0.1143)
		(layer "In6.Cu")
		(net "P5E_CPU0_P2_RX_DN<7>")
	)
	(segment
		(start 387.104636 -336.954622)
		(end 384.613658 -324.430644)
		(width 0.14224)
		(layer "In6.Cu")
		(net "P5E_CPU0_P2_RX_DN<7>")
	)
	(segment
		(start 367.874296 -297.789854)
		(end 367.874296 -296.353484)
		(width 0.14224)
		(layer "In6.Cu")
		(net "P5E_CPU0_P2_RX_DN<7>")
	)
	(segment
		(start 367.256568 -287.365694)
		(end 367.257584 -287.365186)
		(width 0.1143)
		(layer "In6.Cu")
		(net "P5E_CPU0_P2_RX_DN<7>")
	)
	(segment
		(start 412.333694 -389.024114)
		(end 412.333186 -389.024114)
		(width 0.14224)
		(layer "In6.Cu")
		(net "P5E_CPU0_P2_RX_DN<7>")
	)
	(segment
		(start 367.227612 -289.002216)
		(end 367.230152 -289.000946)
		(width 0.1143)
		(layer "In6.Cu")
		(net "P5E_CPU0_P2_RX_DN<7>")
	)
	(segment
		(start 367.252504 -287.36798)
		(end 367.255806 -287.366202)
		(width 0.1143)
		(layer "In6.Cu")
		(net "P5E_CPU0_P2_RX_DN<7>")
	)
	(segment
		(start 367.439448 -295.145968)
		(end 367.439194 -295.145968)
		(width 0.1143)
		(layer "In6.Cu")
		(net "P5E_CPU0_P2_RX_DN<7>")
	)
	(segment
		(start 367.222024 -289.005518)
		(end 367.222786 -289.00501)
		(width 0.1143)
		(layer "In6.Cu")
		(net "P5E_CPU0_P2_RX_DN<7>")
	)
	(segment
		(start 367.83264 -286.236156)
		(end 367.534698 -286.236156)
		(width 0.1143)
		(layer "In6.Cu")
		(net "P5E_CPU0_P2_RX_DN<7>")
	)
	(segment
		(start 367.751868 -295.650666)
		(end 367.723674 -295.63441)
		(width 0.1143)
		(layer "In6.Cu")
		(net "P5E_CPU0_P2_RX_DN<7>")
	)
	(segment
		(start 412.381192 -387.897116)
		(end 412.380684 -387.896862)
		(width 0.14224)
		(layer "In6.Cu")
		(net "P5E_CPU0_P2_RX_DN<7>")
	)
	(segment
		(start 367.226342 -289.002978)
		(end 367.227612 -289.002216)
		(width 0.1143)
		(layer "In6.Cu")
		(net "P5E_CPU0_P2_RX_DN<7>")
	)
	(segment
		(start 412.220156 -388.455154)
		(end 412.23819 -388.028434)
		(width 0.14224)
		(layer "In6.Cu")
		(net "P5E_CPU0_P2_RX_DN<7>")
	)
	(segment
		(start 367.222786 -289.00501)
		(end 367.224056 -289.004248)
		(width 0.1143)
		(layer "In6.Cu")
		(net "P5E_CPU0_P2_RX_DN<7>")
	)
	(segment
		(start 412.586424 -381.796544)
		(end 412.188406 -381.398526)
		(width 0.14224)
		(layer "In6.Cu")
		(net "P5E_CPU0_P2_RX_DN<7>")
	)
	(segment
		(start 367.257584 -287.365186)
		(end 367.283492 -287.3502)
		(width 0.1143)
		(layer "In6.Cu")
		(net "P5E_CPU0_P2_RX_DN<7>")
	)
	(segment
		(start 412.267654 -387.328156)
		(end 412.285688 -386.901436)
		(width 0.14224)
		(layer "In6.Cu")
		(net "P5E_CPU0_P2_RX_DN<7>")
	)
	(segment
		(start 412.42869 -386.770118)
		(end 412.427928 -386.770118)
		(width 0.14224)
		(layer "In6.Cu")
		(net "P5E_CPU0_P2_RX_DN<7>")
	)
	(segment
		(start 367.874296 -296.353484)
		(end 367.874296 -296.325036)
		(width 0.1143)
		(layer "In6.Cu")
		(net "P5E_CPU0_P2_RX_DN<7>")
	)
	(segment
		(start 377.871228 -312.293)
		(end 372.268496 -305.465988)
		(width 0.14224)
		(layer "In6.Cu")
		(net "P5E_CPU0_P2_RX_DN<7>")
	)
	(segment
		(start 412.17215 -393.787376)
		(end 412.172658 -393.786868)
		(width 0.14224)
		(layer "In6.Cu")
		(net "P5E_CPU0_P2_RX_DN<7>")
	)
	(segment
		(start 412.428182 -386.768848)
		(end 412.623762 -382.124204)
		(width 0.14224)
		(layer "In6.Cu")
		(net "P5E_CPU0_P2_RX_DN<7>")
	)
	(segment
		(start 384.613658 -324.430644)
		(end 379.142752 -314.196222)
		(width 0.14224)
		(layer "In6.Cu")
		(net "P5E_CPU0_P2_RX_DN<7>")
	)
	(segment
		(start 367.212626 -292.251384)
		(end 367.282222 -292.210744)
		(width 0.1143)
		(layer "In6.Cu")
		(net "P5E_CPU0_P2_RX_DN<7>")
	)
	(segment
		(start 412.172658 -393.786868)
		(end 412.294324 -393.716764)
		(width 0.14224)
		(layer "In6.Cu")
		(net "P5E_CPU0_P2_RX_DN<7>")
	)
	(segment
		(start 367.723674 -295.63441)
		(end 367.721896 -295.633394)
		(width 0.1143)
		(layer "In6.Cu")
		(net "P5E_CPU0_P2_RX_DN<7>")
	)
	(segment
		(start 379.142752 -314.196222)
		(end 377.871228 -312.293)
		(width 0.14224)
		(layer "In6.Cu")
		(net "P5E_CPU0_P2_RX_DN<7>")
	)
	(segment
		(start 387.64337 -342.419432)
		(end 387.104636 -336.954622)
		(width 0.14224)
		(layer "In6.Cu")
		(net "P5E_CPU0_P2_RX_DN<7>")
	)
	(segment
		(start 367.212626 -293.871396)
		(end 367.282222 -293.830756)
		(width 0.1143)
		(layer "In6.Cu")
		(net "P5E_CPU0_P2_RX_DN<7>")
	)
	(segment
		(start 367.721896 -295.633394)
		(end 367.68405 -295.61155)
		(width 0.1143)
		(layer "In6.Cu")
		(net "P5E_CPU0_P2_RX_DN<7>")
	)
	(segment
		(start 367.282222 -294.841168)
		(end 367.212626 -294.800528)
		(width 0.1143)
		(layer "In6.Cu")
		(net "P5E_CPU0_P2_RX_DN<7>")
	)
	(segment
		(start 410.84627 -380.558802)
		(end 410.84627 -376.520456)
		(width 0.14224)
		(layer "In6.Cu")
		(net "P5E_CPU0_P2_RX_DN<7>")
	)
	(segment
		(start 412.380684 -387.896862)
		(end 412.398464 -387.471158)
		(width 0.14224)
		(layer "In6.Cu")
		(net "P5E_CPU0_P2_RX_DN<7>")
	)
	(segment
		(start 412.147258 -381.371094)
		(end 411.098746 -380.936754)
		(width 0.14224)
		(layer "In6.Cu")
		(net "P5E_CPU0_P2_RX_DN<7>")
	)
	(segment
		(start 409.512008 -375.618248)
		(end 407.724864 -375.1707)
		(width 0.14224)
		(layer "In6.Cu")
		(net "P5E_CPU0_P2_RX_DN<7>")
	)
	(segment
		(start 367.255806 -287.366202)
		(end 367.256568 -287.365694)
		(width 0.1143)
		(layer "In6.Cu")
		(net "P5E_CPU0_P2_RX_DN<7>")
	)
	(segment
		(start 396.392146 -367.64087)
		(end 389.40994 -350.783144)
		(width 0.14224)
		(layer "In6.Cu")
		(net "P5E_CPU0_P2_RX_DN<7>")
	)
	(segment
		(start 367.919508 -296.085768)
		(end 367.919508 -295.977818)
		(width 0.1143)
		(layer "In6.Cu")
		(net "P5E_CPU0_P2_RX_DN<7>")
	)
	(segment
		(start 367.218214 -287.388046)
		(end 367.219484 -287.387284)
		(width 0.1143)
		(layer "In6.Cu")
		(net "P5E_CPU0_P2_RX_DN<7>")
	)
	(segment
		(start 367.220246 -287.386776)
		(end 367.248694 -287.370012)
		(width 0.1143)
		(layer "In6.Cu")
		(net "P5E_CPU0_P2_RX_DN<7>")
	)
	(segment
		(start 367.28527 -288.363152)
		(end 367.284508 -288.362644)
		(width 0.1143)
		(layer "In6.Cu")
		(net "P5E_CPU0_P2_RX_DN<7>")
	)
	(segment
		(start 367.282222 -293.221156)
		(end 367.212626 -293.180516)
		(width 0.1143)
		(layer "In6.Cu")
		(net "P5E_CPU0_P2_RX_DN<7>")
	)
	(segment
		(start 411.977332 -393.22883)
		(end 411.982158 -392.616944)
		(width 0.14224)
		(layer "In6.Cu")
		(net "P5E_CPU0_P2_RX_DN<7>")
	)
	(segment
		(start 407.537158 -375.095516)
		(end 398.726914 -370.103908)
		(width 0.14224)
		(layer "In6.Cu")
		(net "P5E_CPU0_P2_RX_DN<7>")
	)
	(segment
		(start 369.105688 -300.732952)
		(end 367.895632 -297.81119)
		(width 0.14224)
		(layer "In6.Cu")
		(net "P5E_CPU0_P2_RX_DN<7>")
	)
	(segment
		(start 367.920016 -296.279316)
		(end 367.920016 -296.086276)
		(width 0.1143)
		(layer "In6.Cu")
		(net "P5E_CPU0_P2_RX_DN<7>")
	)
	(segment
		(start 367.284508 -288.362644)
		(end 367.21542 -288.322512)
		(width 0.1143)
		(layer "In6.Cu")
		(net "P5E_CPU0_P2_RX_DN<7>")
	)
	(segment
		(start 367.22558 -289.003486)
		(end 367.226342 -289.002978)
		(width 0.1143)
		(layer "In6.Cu")
		(net "P5E_CPU0_P2_RX_DN<7>")
	)
	(segment
		(start 412.35122 -388.597902)
		(end 412.351474 -388.597902)
		(width 0.14224)
		(layer "In6.Cu")
		(net "P5E_CPU0_P2_RX_DN<7>")
	)
	(segment
		(start 411.982158 -392.616944)
		(end 412.286196 -392.312906)
		(width 0.14224)
		(layer "In6.Cu")
		(net "P5E_CPU0_P2_RX_DN<7>")
	)
	(segment
		(start 389.105394 -349.779082)
		(end 387.649212 -342.459056)
		(width 0.14224)
		(layer "In6.Cu")
		(net "P5E_CPU0_P2_RX_DN<7>")
	)
	(segment
		(start 412.172658 -389.582152)
		(end 412.190692 -389.155432)
		(width 0.14224)
		(layer "In6.Cu")
		(net "P5E_CPU0_P2_RX_DN<7>")
	)
	(segment
		(start 412.294324 -393.716764)
		(end 412.294324 -393.545822)
		(width 0.14224)
		(layer "In6.Cu")
		(net "P5E_CPU0_P2_RX_DN<7>")
	)
	(segment
		(start 367.251742 -287.368488)
		(end 367.252504 -287.36798)
		(width 0.1143)
		(layer "In6.Cu")
		(net "P5E_CPU0_P2_RX_DN<7>")
	)
	(segment
		(start 367.874296 -296.325036)
		(end 367.920016 -296.279316)
		(width 0.1143)
		(layer "In6.Cu")
		(net "P5E_CPU0_P2_RX_DN<7>")
	)
	(segment
		(start 412.333186 -389.024114)
		(end 412.33344 -389.021828)
		(width 0.14224)
		(layer "In6.Cu")
		(net "P5E_CPU0_P2_RX_DN<7>")
	)
	(segment
		(start 410.808932 -376.43054)
		(end 410.62783 -376.249438)
		(width 0.14224)
		(layer "In6.Cu")
		(net "P5E_CPU0_P2_RX_DN<7>")
	)
	(segment
		(start 372.268496 -305.465988)
		(end 369.105688 -300.732952)
		(width 0.14224)
		(layer "In6.Cu")
		(net "P5E_CPU0_P2_RX_DN<7>")
	)
	(segment
		(start 412.623762 -382.124204)
		(end 412.623762 -381.88646)
		(width 0.14224)
		(layer "In6.Cu")
		(net "P5E_CPU0_P2_RX_DN<7>")
	)
	(segment
		(start 367.895632 -297.81119)
		(end 367.874296 -297.789854)
		(width 0.14224)
		(layer "In6.Cu")
		(net "P5E_CPU0_P2_RX_DN<7>")
	)
	(segment
		(start 412.351474 -388.597902)
		(end 412.220156 -388.455154)
		(width 0.14224)
		(layer "In6.Cu")
		(net "P5E_CPU0_P2_RX_DN<7>")
	)
	(segment
		(start 367.282222 -291.601144)
		(end 367.212626 -291.560504)
		(width 0.1143)
		(layer "In6.Cu")
		(net "P5E_CPU0_P2_RX_DN<7>")
	)
	(segment
		(start 412.23819 -388.028434)
		(end 412.381192 -387.897116)
		(width 0.14224)
		(layer "In6.Cu")
		(net "P5E_CPU0_P2_RX_DN<7>")
	)
	(segment
		(start 412.286196 -392.312906)
		(end 412.286196 -390.151112)
		(width 0.14224)
		(layer "In6.Cu")
		(net "P5E_CPU0_P2_RX_DN<7>")
	)
	(segment
		(start 367.248694 -287.370012)
		(end 367.251742 -287.368488)
		(width 0.1143)
		(layer "In6.Cu")
		(net "P5E_CPU0_P2_RX_DN<7>")
	)
	(segment
		(start 412.285688 -386.901436)
		(end 412.42869 -386.770118)
		(width 0.14224)
		(layer "In6.Cu")
		(net "P5E_CPU0_P2_RX_DN<7>")
	)
	(arc
		(start 396.727172 -368.142266)
		(mid 396.534993 -367.908052)
		(end 396.392146 -367.64087)
		(width 0.14224)
		(layer "In6.Cu")
		(net "P5E_CPU0_P2_RX_DN<7>")
	)
	(arc
		(start 367.283492 -288.970212)
		(mid 367.398168 -288.836878)
		(end 367.439448 -288.66592)
		(width 0.1143)
		(layer "In6.Cu")
		(net "P5E_CPU0_P2_RX_DN<7>")
	)
	(arc
		(start 398.726914 -370.103908)
		(mid 398.642518 -370.048112)
		(end 398.566386 -369.98148)
		(width 0.14224)
		(layer "In6.Cu")
		(net "P5E_CPU0_P2_RX_DN<7>")
	)
	(arc
		(start 367.282222 -290.590732)
		(mid 367.439199 -290.285932)
		(end 367.282222 -289.981132)
		(width 0.1143)
		(layer "In6.Cu")
		(net "P5E_CPU0_P2_RX_DN<7>")
	)
	(arc
		(start 407.724864 -375.1707)
		(mid 407.628474 -375.139443)
		(end 407.537158 -375.095516)
		(width 0.14224)
		(layer "In6.Cu")
		(net "P5E_CPU0_P2_RX_DN<7>")
	)
	(arc
		(start 367.754408 -286.539686)
		(mid 367.850848 -286.437031)
		(end 367.90249 -286.306006)
		(width 0.1143)
		(layer "In6.Cu")
		(net "P5E_CPU0_P2_RX_DN<7>")
	)
	(arc
		(start 367.439194 -295.145968)
		(mid 367.397645 -294.974546)
		(end 367.282222 -294.841168)
		(width 0.1143)
		(layer "In6.Cu")
		(net "P5E_CPU0_P2_RX_DN<7>")
	)
	(arc
		(start 367.439448 -287.045908)
		(mid 367.503963 -286.783689)
		(end 367.68278 -286.581342)
		(width 0.1143)
		(layer "In6.Cu")
		(net "P5E_CPU0_P2_RX_DN<7>")
	)
	(arc
		(start 367.212626 -293.180516)
		(mid 366.969299 -292.71595)
		(end 367.212626 -292.251384)
		(width 0.1143)
		(layer "In6.Cu")
		(net "P5E_CPU0_P2_RX_DN<7>")
	)
	(arc
		(start 412.623762 -381.88646)
		(mid 412.61406 -381.837776)
		(end 412.586424 -381.796544)
		(width 0.14224)
		(layer "In6.Cu")
		(net "P5E_CPU0_P2_RX_DN<7>")
	)
	(arc
		(start 367.282222 -292.210744)
		(mid 367.439199 -291.905944)
		(end 367.282222 -291.601144)
		(width 0.1143)
		(layer "In6.Cu")
		(net "P5E_CPU0_P2_RX_DN<7>")
	)
	(arc
		(start 366.969548 -287.856168)
		(mid 366.969548 -287.855279)
		(end 366.969548 -287.85439)
		(width 0.1143)
		(layer "In6.Cu")
		(net "P5E_CPU0_P2_RX_DN<7>")
	)
	(arc
		(start 387.649212 -342.459056)
		(mid 387.645801 -342.439316)
		(end 387.64337 -342.419432)
		(width 0.14224)
		(layer "In6.Cu")
		(net "P5E_CPU0_P2_RX_DN<7>")
	)
	(arc
		(start 367.212626 -289.940492)
		(mid 366.969299 -289.475926)
		(end 367.212626 -289.01136)
		(width 0.1143)
		(layer "In6.Cu")
		(net "P5E_CPU0_P2_RX_DN<7>")
	)
	(arc
		(start 367.68405 -295.61155)
		(mid 367.504321 -295.40893)
		(end 367.439448 -295.145968)
		(width 0.1143)
		(layer "In6.Cu")
		(net "P5E_CPU0_P2_RX_DN<7>")
	)
	(arc
		(start 367.919508 -295.977818)
		(mid 367.875143 -295.794035)
		(end 367.751868 -295.650666)
		(width 0.1143)
		(layer "In6.Cu")
		(net "P5E_CPU0_P2_RX_DN<7>")
	)
	(arc
		(start 366.969548 -287.85439)
		(mid 367.032462 -287.598874)
		(end 367.202974 -287.39846)
		(width 0.1143)
		(layer "In6.Cu")
		(net "P5E_CPU0_P2_RX_DN<7>")
	)
	(arc
		(start 367.283492 -287.3502)
		(mid 367.398168 -287.216866)
		(end 367.439448 -287.045908)
		(width 0.1143)
		(layer "In6.Cu")
		(net "P5E_CPU0_P2_RX_DN<7>")
	)
	(arc
		(start 367.212626 -291.560504)
		(mid 366.969299 -291.095938)
		(end 367.212626 -290.631372)
		(width 0.1143)
		(layer "In6.Cu")
		(net "P5E_CPU0_P2_RX_DN<7>")
	)
	(arc
		(start 389.40994 -350.783144)
		(mid 389.233019 -350.28859)
		(end 389.105394 -349.779082)
		(width 0.14224)
		(layer "In6.Cu")
		(net "P5E_CPU0_P2_RX_DN<7>")
	)
	(arc
		(start 410.84627 -376.520456)
		(mid 410.836568 -376.471772)
		(end 410.808932 -376.43054)
		(width 0.14224)
		(layer "In6.Cu")
		(net "P5E_CPU0_P2_RX_DN<7>")
	)
	(arc
		(start 367.212626 -294.800528)
		(mid 366.969299 -294.335962)
		(end 367.212626 -293.871396)
		(width 0.1143)
		(layer "In6.Cu")
		(net "P5E_CPU0_P2_RX_DN<7>")
	)
	(arc
		(start 411.098746 -380.936754)
		(mid 410.915221 -380.786053)
		(end 410.84627 -380.558802)
		(width 0.14224)
		(layer "In6.Cu")
		(net "P5E_CPU0_P2_RX_DN<7>")
	)
	(arc
		(start 367.439448 -288.66592)
		(mid 367.398686 -288.496036)
		(end 367.28527 -288.363152)
		(width 0.1143)
		(layer "In6.Cu")
		(net "P5E_CPU0_P2_RX_DN<7>")
	)
	(arc
		(start 367.282222 -293.830756)
		(mid 367.439199 -293.525956)
		(end 367.282222 -293.221156)
		(width 0.1143)
		(layer "In6.Cu")
		(net "P5E_CPU0_P2_RX_DN<7>")
	)
	(arc
		(start 410.62783 -376.249438)
		(mid 410.112754 -375.858111)
		(end 409.512008 -375.618248)
		(width 0.14224)
		(layer "In6.Cu")
		(net "P5E_CPU0_P2_RX_DN<7>")
	)
	(arc
		(start 367.21542 -288.322512)
		(mid 367.034768 -288.119767)
		(end 366.969548 -287.856168)
		(width 0.1143)
		(layer "In6.Cu")
		(net "P5E_CPU0_P2_RX_DN<7>")
	)
	(arc
		(start 412.188406 -381.398526)
		(mid 412.169183 -381.382781)
		(end 412.147258 -381.371094)
		(width 0.14224)
		(layer "In6.Cu")
		(net "P5E_CPU0_P2_RX_DN<7>")
	)
	(arc
		(start 367.202974 -287.39846)
		(mid 367.210551 -287.393191)
		(end 367.218214 -287.388046)
		(width 0.1143)
		(layer "In6.Cu")
		(net "P5E_CPU0_P2_RX_DN<7>")
	)
	(segment
		(start 367.067846 -282.730194)
		(end 367.534698 -282.996132)
		(width 0.12954)
		(layer "F.Cu")
		(net "P5E_CPU0_P2_RX_DN<6>")
	)
	(segment
		(start 410.09824 -393.69238)
		(end 410.61894 -393.69238)
		(width 0.127)
		(layer "F.Cu")
		(net "P5E_CPU0_P2_RX_DN<6>")
	)
	(segment
		(start 366.342422 -289.981132)
		(end 366.311942 -289.963352)
		(width 0.1143)
		(layer "In6.Cu")
		(net "P5E_CPU0_P2_RX_DN<6>")
	)
	(segment
		(start 366.742726 -286.581342)
		(end 366.811814 -286.541464)
		(width 0.1143)
		(layer "In6.Cu")
		(net "P5E_CPU0_P2_RX_DN<6>")
	)
	(segment
		(start 366.311942 -288.343594)
		(end 366.272826 -288.320734)
		(width 0.1143)
		(layer "In6.Cu")
		(net "P5E_CPU0_P2_RX_DN<6>")
	)
	(segment
		(start 366.311942 -293.203376)
		(end 366.272826 -293.180516)
		(width 0.1143)
		(layer "In6.Cu")
		(net "P5E_CPU0_P2_RX_DN<6>")
	)
	(segment
		(start 368.187732 -301.03699)
		(end 366.923828 -297.967908)
		(width 0.14224)
		(layer "In6.Cu")
		(net "P5E_CPU0_P2_RX_DN<6>")
	)
	(segment
		(start 366.342422 -293.221156)
		(end 366.311942 -293.203376)
		(width 0.1143)
		(layer "In6.Cu")
		(net "P5E_CPU0_P2_RX_DN<6>")
	)
	(segment
		(start 410.972762 -393.786868)
		(end 411.094428 -393.716764)
		(width 0.14224)
		(layer "In6.Cu")
		(net "P5E_CPU0_P2_RX_DN<6>")
	)
	(segment
		(start 366.311942 -290.608512)
		(end 366.342422 -290.590732)
		(width 0.1143)
		(layer "In6.Cu")
		(net "P5E_CPU0_P2_RX_DN<6>")
	)
	(segment
		(start 366.923828 -297.967908)
		(end 366.923828 -296.353484)
		(width 0.14224)
		(layer "In6.Cu")
		(net "P5E_CPU0_P2_RX_DN<6>")
	)
	(segment
		(start 367.255806 -284.126432)
		(end 367.25606 -284.126178)
		(width 0.1143)
		(layer "In6.Cu")
		(net "P5E_CPU0_P2_RX_DN<6>")
	)
	(segment
		(start 366.969802 -295.95572)
		(end 366.969548 -295.955974)
		(width 0.1143)
		(layer "In6.Cu")
		(net "P5E_CPU0_P2_RX_DN<6>")
	)
	(segment
		(start 366.342422 -294.841168)
		(end 366.311942 -294.823388)
		(width 0.1143)
		(layer "In6.Cu")
		(net "P5E_CPU0_P2_RX_DN<6>")
	)
	(segment
		(start 366.79505 -284.931104)
		(end 366.80013 -284.928056)
		(width 0.1143)
		(layer "In6.Cu")
		(net "P5E_CPU0_P2_RX_DN<6>")
	)
	(segment
		(start 410.52115 -389.53313)
		(end 410.4132 -389.120126)
		(width 0.14224)
		(layer "In6.Cu")
		(net "P5E_CPU0_P2_RX_DN<6>")
	)
	(segment
		(start 366.783874 -295.634664)
		(end 366.782604 -295.633902)
		(width 0.1143)
		(layer "In6.Cu")
		(net "P5E_CPU0_P2_RX_DN<6>")
	)
	(segment
		(start 366.782604 -295.633902)
		(end 366.781842 -295.633394)
		(width 0.1143)
		(layer "In6.Cu")
		(net "P5E_CPU0_P2_RX_DN<6>")
	)
	(segment
		(start 366.275366 -287.389824)
		(end 366.342422 -287.350708)
		(width 0.1143)
		(layer "In6.Cu")
		(net "P5E_CPU0_P2_RX_DN<6>")
	)
	(segment
		(start 386.154676 -336.95894)
		(end 383.728214 -324.759066)
		(width 0.14224)
		(layer "In6.Cu")
		(net "P5E_CPU0_P2_RX_DN<6>")
	)
	(segment
		(start 366.923828 -296.325036)
		(end 366.969548 -296.279316)
		(width 0.1143)
		(layer "In6.Cu")
		(net "P5E_CPU0_P2_RX_DN<6>")
	)
	(segment
		(start 410.974286 -390.722358)
		(end 410.806646 -390.624314)
		(width 0.14224)
		(layer "In6.Cu")
		(net "P5E_CPU0_P2_RX_DN<6>")
	)
	(segment
		(start 366.781842 -295.633394)
		(end 366.780826 -295.632886)
		(width 0.1143)
		(layer "In6.Cu")
		(net "P5E_CPU0_P2_RX_DN<6>")
	)
	(segment
		(start 410.4132 -389.120126)
		(end 410.511244 -388.95274)
		(width 0.14224)
		(layer "In6.Cu")
		(net "P5E_CPU0_P2_RX_DN<6>")
	)
	(segment
		(start 376.992896 -312.712608)
		(end 371.52961 -306.049426)
		(width 0.14224)
		(layer "In6.Cu")
		(net "P5E_CPU0_P2_RX_DN<6>")
	)
	(segment
		(start 410.61894 -393.69238)
		(end 410.972254 -393.787376)
		(width 0.14224)
		(layer "In6.Cu")
		(net "P5E_CPU0_P2_RX_DN<6>")
	)
	(segment
		(start 398.030446 -370.77523)
		(end 395.990318 -368.735102)
		(width 0.14224)
		(layer "In6.Cu")
		(net "P5E_CPU0_P2_RX_DN<6>")
	)
	(segment
		(start 366.344454 -288.36239)
		(end 366.311942 -288.343594)
		(width 0.1143)
		(layer "In6.Cu")
		(net "P5E_CPU0_P2_RX_DN<6>")
	)
	(segment
		(start 366.79505 -284.931358)
		(end 366.79505 -284.931104)
		(width 0.1143)
		(layer "In6.Cu")
		(net "P5E_CPU0_P2_RX_DN<6>")
	)
	(segment
		(start 410.806646 -390.624314)
		(end 410.698696 -390.21131)
		(width 0.14224)
		(layer "In6.Cu")
		(net "P5E_CPU0_P2_RX_DN<6>")
	)
	(segment
		(start 366.923828 -296.353484)
		(end 366.923828 -296.325036)
		(width 0.1143)
		(layer "In6.Cu")
		(net "P5E_CPU0_P2_RX_DN<6>")
	)
	(segment
		(start 388.166356 -349.867982)
		(end 386.704586 -342.517984)
		(width 0.14224)
		(layer "In6.Cu")
		(net "P5E_CPU0_P2_RX_DN<6>")
	)
	(segment
		(start 366.80013 -284.928056)
		(end 366.800384 -284.928056)
		(width 0.1143)
		(layer "In6.Cu")
		(net "P5E_CPU0_P2_RX_DN<6>")
	)
	(segment
		(start 366.311942 -294.823388)
		(end 366.272826 -294.800528)
		(width 0.1143)
		(layer "In6.Cu")
		(net "P5E_CPU0_P2_RX_DN<6>")
	)
	(segment
		(start 410.777436 -393.22883)
		(end 410.782262 -392.616944)
		(width 0.14224)
		(layer "In6.Cu")
		(net "P5E_CPU0_P2_RX_DN<6>")
	)
	(segment
		(start 366.973358 -284.628082)
		(end 366.973358 -284.610302)
		(width 0.1143)
		(layer "In6.Cu")
		(net "P5E_CPU0_P2_RX_DN<6>")
	)
	(segment
		(start 367.241836 -284.134814)
		(end 367.251742 -284.128718)
		(width 0.1143)
		(layer "In6.Cu")
		(net "P5E_CPU0_P2_RX_DN<6>")
	)
	(segment
		(start 410.972254 -393.787376)
		(end 410.972762 -393.786868)
		(width 0.14224)
		(layer "In6.Cu")
		(net "P5E_CPU0_P2_RX_DN<6>")
	)
	(segment
		(start 366.969802 -296.006774)
		(end 366.969802 -295.95572)
		(width 0.1143)
		(layer "In6.Cu")
		(net "P5E_CPU0_P2_RX_DN<6>")
	)
	(segment
		(start 410.782262 -392.616944)
		(end 411.0863 -392.312906)
		(width 0.14224)
		(layer "In6.Cu")
		(net "P5E_CPU0_P2_RX_DN<6>")
	)
	(segment
		(start 366.311942 -288.9885)
		(end 366.342422 -288.97072)
		(width 0.1143)
		(layer "In6.Cu")
		(net "P5E_CPU0_P2_RX_DN<6>")
	)
	(segment
		(start 410.79674 -390.043924)
		(end 410.68879 -389.631174)
		(width 0.14224)
		(layer "In6.Cu")
		(net "P5E_CPU0_P2_RX_DN<6>")
	)
	(segment
		(start 395.324584 -367.738914)
		(end 388.834376 -352.069654)
		(width 0.14224)
		(layer "In6.Cu")
		(net "P5E_CPU0_P2_RX_DN<6>")
	)
	(segment
		(start 366.272826 -290.631372)
		(end 366.311942 -290.608512)
		(width 0.1143)
		(layer "In6.Cu")
		(net "P5E_CPU0_P2_RX_DN<6>")
	)
	(segment
		(start 367.252504 -284.12821)
		(end 367.253774 -284.127448)
		(width 0.1143)
		(layer "In6.Cu")
		(net "P5E_CPU0_P2_RX_DN<6>")
	)
	(segment
		(start 410.698696 -390.21131)
		(end 410.79674 -390.043924)
		(width 0.14224)
		(layer "In6.Cu")
		(net "P5E_CPU0_P2_RX_DN<6>")
	)
	(segment
		(start 411.082236 -391.135108)
		(end 410.974286 -390.722358)
		(width 0.14224)
		(layer "In6.Cu")
		(net "P5E_CPU0_P2_RX_DN<6>")
	)
	(segment
		(start 366.786414 -295.635934)
		(end 366.783874 -295.634664)
		(width 0.1143)
		(layer "In6.Cu")
		(net "P5E_CPU0_P2_RX_DN<6>")
	)
	(segment
		(start 371.52961 -306.049426)
		(end 368.187732 -301.03699)
		(width 0.14224)
		(layer "In6.Cu")
		(net "P5E_CPU0_P2_RX_DN<6>")
	)
	(segment
		(start 367.90249 -283.065982)
		(end 367.83264 -282.996132)
		(width 0.1143)
		(layer "In6.Cu")
		(net "P5E_CPU0_P2_RX_DN<6>")
	)
	(segment
		(start 410.68879 -389.631174)
		(end 410.52115 -389.53313)
		(width 0.14224)
		(layer "In6.Cu")
		(net "P5E_CPU0_P2_RX_DN<6>")
	)
	(segment
		(start 410.226002 -387.861048)
		(end 409.357068 -384.538474)
		(width 0.14224)
		(layer "In6.Cu")
		(net "P5E_CPU0_P2_RX_DN<6>")
	)
	(segment
		(start 366.311942 -292.228524)
		(end 366.342422 -292.210744)
		(width 0.1143)
		(layer "In6.Cu")
		(net "P5E_CPU0_P2_RX_DN<6>")
	)
	(segment
		(start 366.342422 -291.601144)
		(end 366.311942 -291.583364)
		(width 0.1143)
		(layer "In6.Cu")
		(net "P5E_CPU0_P2_RX_DN<6>")
	)
	(segment
		(start 411.094428 -393.545822)
		(end 410.777436 -393.22883)
		(width 0.14224)
		(layer "In6.Cu")
		(net "P5E_CPU0_P2_RX_DN<6>")
	)
	(segment
		(start 367.83264 -282.996132)
		(end 367.534698 -282.996132)
		(width 0.1143)
		(layer "In6.Cu")
		(net "P5E_CPU0_P2_RX_DN<6>")
	)
	(segment
		(start 367.251742 -284.128718)
		(end 367.252504 -284.12821)
		(width 0.1143)
		(layer "In6.Cu")
		(net "P5E_CPU0_P2_RX_DN<6>")
	)
	(segment
		(start 366.272826 -289.01136)
		(end 366.311942 -288.9885)
		(width 0.1143)
		(layer "In6.Cu")
		(net "P5E_CPU0_P2_RX_DN<6>")
	)
	(segment
		(start 411.094428 -393.716764)
		(end 411.094428 -393.545822)
		(width 0.14224)
		(layer "In6.Cu")
		(net "P5E_CPU0_P2_RX_DN<6>")
	)
	(segment
		(start 366.780826 -295.632886)
		(end 366.742726 -295.610534)
		(width 0.1143)
		(layer "In6.Cu")
		(net "P5E_CPU0_P2_RX_DN<6>")
	)
	(segment
		(start 367.253774 -284.127448)
		(end 367.255806 -284.126432)
		(width 0.1143)
		(layer "In6.Cu")
		(net "P5E_CPU0_P2_RX_DN<6>")
	)
	(segment
		(start 366.311942 -289.963352)
		(end 366.272826 -289.940492)
		(width 0.1143)
		(layer "In6.Cu")
		(net "P5E_CPU0_P2_RX_DN<6>")
	)
	(segment
		(start 366.813592 -295.651682)
		(end 366.787938 -295.63695)
		(width 0.1143)
		(layer "In6.Cu")
		(net "P5E_CPU0_P2_RX_DN<6>")
	)
	(segment
		(start 366.969548 -296.007028)
		(end 366.969802 -296.006774)
		(width 0.1143)
		(layer "In6.Cu")
		(net "P5E_CPU0_P2_RX_DN<6>")
	)
	(segment
		(start 366.311942 -291.583364)
		(end 366.272826 -291.560504)
		(width 0.1143)
		(layer "In6.Cu")
		(net "P5E_CPU0_P2_RX_DN<6>")
	)
	(segment
		(start 366.311942 -293.848536)
		(end 366.342422 -293.830756)
		(width 0.1143)
		(layer "In6.Cu")
		(net "P5E_CPU0_P2_RX_DN<6>")
	)
	(segment
		(start 367.684304 -283.340556)
		(end 367.752376 -283.300932)
		(width 0.1143)
		(layer "In6.Cu")
		(net "P5E_CPU0_P2_RX_DN<6>")
	)
	(segment
		(start 410.403548 -388.53999)
		(end 410.235654 -388.441946)
		(width 0.14224)
		(layer "In6.Cu")
		(net "P5E_CPU0_P2_RX_DN<6>")
	)
	(segment
		(start 366.787938 -295.63695)
		(end 366.786414 -295.635934)
		(width 0.1143)
		(layer "In6.Cu")
		(net "P5E_CPU0_P2_RX_DN<6>")
	)
	(segment
		(start 383.728214 -324.759066)
		(end 378.472192 -314.927488)
		(width 0.14224)
		(layer "In6.Cu")
		(net "P5E_CPU0_P2_RX_DN<6>")
	)
	(segment
		(start 410.511244 -388.95274)
		(end 410.403548 -388.53999)
		(width 0.14224)
		(layer "In6.Cu")
		(net "P5E_CPU0_P2_RX_DN<6>")
	)
	(segment
		(start 409.148534 -382.915922)
		(end 409.148534 -377.288044)
		(width 0.14224)
		(layer "In6.Cu")
		(net "P5E_CPU0_P2_RX_DN<6>")
	)
	(segment
		(start 366.272826 -292.251384)
		(end 366.311942 -292.228524)
		(width 0.1143)
		(layer "In6.Cu")
		(net "P5E_CPU0_P2_RX_DN<6>")
	)
	(segment
		(start 408.387804 -376.306334)
		(end 407.273506 -376.027442)
		(width 0.14224)
		(layer "In6.Cu")
		(net "P5E_CPU0_P2_RX_DN<6>")
	)
	(segment
		(start 378.472192 -314.927488)
		(end 376.992896 -312.712608)
		(width 0.14224)
		(layer "In6.Cu")
		(net "P5E_CPU0_P2_RX_DN<6>")
	)
	(segment
		(start 407.273506 -376.027442)
		(end 398.118076 -370.842032)
		(width 0.14224)
		(layer "In6.Cu")
		(net "P5E_CPU0_P2_RX_DN<6>")
	)
	(segment
		(start 410.127958 -388.028942)
		(end 410.225748 -387.861556)
		(width 0.14224)
		(layer "In6.Cu")
		(net "P5E_CPU0_P2_RX_DN<6>")
	)
	(segment
		(start 366.272826 -293.871396)
		(end 366.311942 -293.848536)
		(width 0.1143)
		(layer "In6.Cu")
		(net "P5E_CPU0_P2_RX_DN<6>")
	)
	(segment
		(start 366.779556 -284.94101)
		(end 366.79505 -284.931358)
		(width 0.1143)
		(layer "In6.Cu")
		(net "P5E_CPU0_P2_RX_DN<6>")
	)
	(segment
		(start 411.0863 -392.312906)
		(end 411.0863 -391.167366)
		(width 0.14224)
		(layer "In6.Cu")
		(net "P5E_CPU0_P2_RX_DN<6>")
	)
	(segment
		(start 410.235654 -388.441946)
		(end 410.127958 -388.028942)
		(width 0.14224)
		(layer "In6.Cu")
		(net "P5E_CPU0_P2_RX_DN<6>")
	)
	(segment
		(start 386.698744 -342.47836)
		(end 386.154676 -336.95894)
		(width 0.14224)
		(layer "In6.Cu")
		(net "P5E_CPU0_P2_RX_DN<6>")
	)
	(segment
		(start 410.225748 -387.861556)
		(end 410.226002 -387.861048)
		(width 0.14224)
		(layer "In6.Cu")
		(net "P5E_CPU0_P2_RX_DN<6>")
	)
	(segment
		(start 366.969548 -296.279316)
		(end 366.969548 -296.007028)
		(width 0.1143)
		(layer "In6.Cu")
		(net "P5E_CPU0_P2_RX_DN<6>")
	)
	(arc
		(start 367.25606 -284.126178)
		(mid 367.390486 -283.990602)
		(end 367.439702 -283.806138)
		(width 0.1143)
		(layer "In6.Cu")
		(net "P5E_CPU0_P2_RX_DN<6>")
	)
	(arc
		(start 366.969548 -295.955974)
		(mid 366.965513 -295.90141)
		(end 366.953546 -295.848024)
		(width 0.1143)
		(layer "In6.Cu")
		(net "P5E_CPU0_P2_RX_DN<6>")
	)
	(arc
		(start 366.499394 -295.145968)
		(mid 366.457845 -294.974546)
		(end 366.342422 -294.841168)
		(width 0.1143)
		(layer "In6.Cu")
		(net "P5E_CPU0_P2_RX_DN<6>")
	)
	(arc
		(start 366.499394 -288.66592)
		(mid 366.458428 -288.495514)
		(end 366.344454 -288.36239)
		(width 0.1143)
		(layer "In6.Cu")
		(net "P5E_CPU0_P2_RX_DN<6>")
	)
	(arc
		(start 409.148534 -377.288044)
		(mid 409.071041 -376.89846)
		(end 408.850338 -376.568208)
		(width 0.14224)
		(layer "In6.Cu")
		(net "P5E_CPU0_P2_RX_DN<6>")
	)
	(arc
		(start 386.704586 -342.517984)
		(mid 386.701175 -342.498244)
		(end 386.698744 -342.47836)
		(width 0.14224)
		(layer "In6.Cu")
		(net "P5E_CPU0_P2_RX_DN<6>")
	)
	(arc
		(start 366.499394 -287.045908)
		(mid 366.563909 -286.783689)
		(end 366.742726 -286.581342)
		(width 0.1143)
		(layer "In6.Cu")
		(net "P5E_CPU0_P2_RX_DN<6>")
	)
	(arc
		(start 366.272826 -288.320734)
		(mid 366.094013 -288.118384)
		(end 366.029494 -287.856168)
		(width 0.1143)
		(layer "In6.Cu")
		(net "P5E_CPU0_P2_RX_DN<6>")
	)
	(arc
		(start 409.357068 -384.538474)
		(mid 409.200838 -383.733876)
		(end 409.148534 -382.915922)
		(width 0.14224)
		(layer "In6.Cu")
		(net "P5E_CPU0_P2_RX_DN<6>")
	)
	(arc
		(start 408.850338 -376.568208)
		(mid 408.636863 -376.405838)
		(end 408.387804 -376.306334)
		(width 0.14224)
		(layer "In6.Cu")
		(net "P5E_CPU0_P2_RX_DN<6>")
	)
	(arc
		(start 366.903508 -295.74363)
		(mid 366.862525 -295.693768)
		(end 366.813592 -295.651682)
		(width 0.1143)
		(layer "In6.Cu")
		(net "P5E_CPU0_P2_RX_DN<6>")
	)
	(arc
		(start 366.272826 -294.800528)
		(mid 366.029499 -294.335962)
		(end 366.272826 -293.871396)
		(width 0.1143)
		(layer "In6.Cu")
		(net "P5E_CPU0_P2_RX_DN<6>")
	)
	(arc
		(start 411.0863 -391.167366)
		(mid 411.085292 -391.151109)
		(end 411.082236 -391.135108)
		(width 0.14224)
		(layer "In6.Cu")
		(net "P5E_CPU0_P2_RX_DN<6>")
	)
	(arc
		(start 388.834376 -352.069654)
		(mid 388.446295 -350.985225)
		(end 388.166356 -349.867982)
		(width 0.14224)
		(layer "In6.Cu")
		(net "P5E_CPU0_P2_RX_DN<6>")
	)
	(arc
		(start 366.342422 -293.830756)
		(mid 366.499399 -293.525956)
		(end 366.342422 -293.221156)
		(width 0.1143)
		(layer "In6.Cu")
		(net "P5E_CPU0_P2_RX_DN<6>")
	)
	(arc
		(start 366.342422 -288.97072)
		(mid 366.457849 -288.837344)
		(end 366.499394 -288.66592)
		(width 0.1143)
		(layer "In6.Cu")
		(net "P5E_CPU0_P2_RX_DN<6>")
	)
	(arc
		(start 366.342422 -292.210744)
		(mid 366.499399 -291.905944)
		(end 366.342422 -291.601144)
		(width 0.1143)
		(layer "In6.Cu")
		(net "P5E_CPU0_P2_RX_DN<6>")
	)
	(arc
		(start 366.342422 -290.590732)
		(mid 366.499399 -290.285932)
		(end 366.342422 -289.981132)
		(width 0.1143)
		(layer "In6.Cu")
		(net "P5E_CPU0_P2_RX_DN<6>")
	)
	(arc
		(start 366.786922 -285.914084)
		(mid 366.501481 -285.429657)
		(end 366.779556 -284.94101)
		(width 0.1143)
		(layer "In6.Cu")
		(net "P5E_CPU0_P2_RX_DN<6>")
	)
	(arc
		(start 366.973358 -284.610302)
		(mid 367.045118 -284.337284)
		(end 367.241836 -284.134814)
		(width 0.1143)
		(layer "In6.Cu")
		(net "P5E_CPU0_P2_RX_DN<6>")
	)
	(arc
		(start 366.342422 -287.350708)
		(mid 366.457849 -287.217332)
		(end 366.499394 -287.045908)
		(width 0.1143)
		(layer "In6.Cu")
		(net "P5E_CPU0_P2_RX_DN<6>")
	)
	(arc
		(start 366.742726 -295.610534)
		(mid 366.563913 -295.408184)
		(end 366.499394 -295.145968)
		(width 0.1143)
		(layer "In6.Cu")
		(net "P5E_CPU0_P2_RX_DN<6>")
	)
	(arc
		(start 366.272826 -291.560504)
		(mid 366.029499 -291.095938)
		(end 366.272826 -290.631372)
		(width 0.1143)
		(layer "In6.Cu")
		(net "P5E_CPU0_P2_RX_DN<6>")
	)
	(arc
		(start 366.800384 -284.928056)
		(mid 366.926977 -284.801204)
		(end 366.973358 -284.628082)
		(width 0.1143)
		(layer "In6.Cu")
		(net "P5E_CPU0_P2_RX_DN<6>")
	)
	(arc
		(start 366.953546 -295.848024)
		(mid 366.932588 -295.79388)
		(end 366.903508 -295.74363)
		(width 0.1143)
		(layer "In6.Cu")
		(net "P5E_CPU0_P2_RX_DN<6>")
	)
	(arc
		(start 366.029494 -287.856168)
		(mid 366.09473 -287.592577)
		(end 366.275366 -287.389824)
		(width 0.1143)
		(layer "In6.Cu")
		(net "P5E_CPU0_P2_RX_DN<6>")
	)
	(arc
		(start 367.439702 -283.806138)
		(mid 367.50452 -283.543149)
		(end 367.684304 -283.340556)
		(width 0.1143)
		(layer "In6.Cu")
		(net "P5E_CPU0_P2_RX_DN<6>")
	)
	(arc
		(start 395.990318 -368.735102)
		(mid 395.608401 -368.269788)
		(end 395.324584 -367.738914)
		(width 0.14224)
		(layer "In6.Cu")
		(net "P5E_CPU0_P2_RX_DN<6>")
	)
	(arc
		(start 366.811814 -286.541464)
		(mid 366.969224 -286.221037)
		(end 366.786922 -285.914084)
		(width 0.1143)
		(layer "In6.Cu")
		(net "P5E_CPU0_P2_RX_DN<6>")
	)
	(arc
		(start 367.752376 -283.300932)
		(mid 367.850141 -283.197956)
		(end 367.90249 -283.065982)
		(width 0.1143)
		(layer "In6.Cu")
		(net "P5E_CPU0_P2_RX_DN<6>")
	)
	(arc
		(start 366.272826 -293.180516)
		(mid 366.029499 -292.71595)
		(end 366.272826 -292.251384)
		(width 0.1143)
		(layer "In6.Cu")
		(net "P5E_CPU0_P2_RX_DN<6>")
	)
	(arc
		(start 366.272826 -289.940492)
		(mid 366.029499 -289.475926)
		(end 366.272826 -289.01136)
		(width 0.1143)
		(layer "In6.Cu")
		(net "P5E_CPU0_P2_RX_DN<6>")
	)
	(arc
		(start 398.118076 -370.842032)
		(mid 398.071997 -370.8116)
		(end 398.030446 -370.77523)
		(width 0.14224)
		(layer "In6.Cu")
		(net "P5E_CPU0_P2_RX_DN<6>")
	)
	(segment
		(start 408.898344 -393.69238)
		(end 409.419044 -393.69238)
		(width 0.127)
		(layer "F.Cu")
		(net "P5E_CPU0_P2_RX_DN<5>")
	)
	(segment
		(start 364.247938 -284.350206)
		(end 364.71479 -284.616144)
		(width 0.12954)
		(layer "F.Cu")
		(net "P5E_CPU0_P2_RX_DN<5>")
	)
	(segment
		(start 377.793504 -315.642752)
		(end 376.10288 -313.112658)
		(width 0.14224)
		(layer "In6.Cu")
		(net "P5E_CPU0_P2_RX_DN<5>")
	)
	(segment
		(start 365.371888 -291.583364)
		(end 365.332772 -291.560504)
		(width 0.1143)
		(layer "In6.Cu")
		(net "P5E_CPU0_P2_RX_DN<5>")
	)
	(segment
		(start 365.012732 -284.616144)
		(end 364.71479 -284.616144)
		(width 0.1143)
		(layer "In6.Cu")
		(net "P5E_CPU0_P2_RX_DN<5>")
	)
	(segment
		(start 365.841788 -295.633394)
		(end 365.840772 -295.632886)
		(width 0.1143)
		(layer "In6.Cu")
		(net "P5E_CPU0_P2_RX_DN<5>")
	)
	(segment
		(start 409.582366 -392.616944)
		(end 409.886404 -392.312906)
		(width 0.14224)
		(layer "In6.Cu")
		(net "P5E_CPU0_P2_RX_DN<5>")
	)
	(segment
		(start 365.802672 -286.581342)
		(end 365.871506 -286.541464)
		(width 0.1143)
		(layer "In6.Cu")
		(net "P5E_CPU0_P2_RX_DN<5>")
	)
	(segment
		(start 365.371888 -290.608512)
		(end 365.402368 -290.590732)
		(width 0.1143)
		(layer "In6.Cu")
		(net "P5E_CPU0_P2_RX_DN<5>")
	)
	(segment
		(start 380.318264 -320.366898)
		(end 380.318518 -320.366898)
		(width 0.14224)
		(layer "In6.Cu")
		(net "P5E_CPU0_P2_RX_DN<5>")
	)
	(segment
		(start 365.371888 -288.343594)
		(end 365.332772 -288.320734)
		(width 0.1143)
		(layer "In6.Cu")
		(net "P5E_CPU0_P2_RX_DN<5>")
	)
	(segment
		(start 367.350802 -301.48276)
		(end 365.984028 -298.182284)
		(width 0.14224)
		(layer "In6.Cu")
		(net "P5E_CPU0_P2_RX_DN<5>")
	)
	(segment
		(start 365.402368 -294.841168)
		(end 365.371888 -294.823388)
		(width 0.1143)
		(layer "In6.Cu")
		(net "P5E_CPU0_P2_RX_DN<5>")
	)
	(segment
		(start 365.371888 -292.228524)
		(end 365.402368 -292.210744)
		(width 0.1143)
		(layer "In6.Cu")
		(net "P5E_CPU0_P2_RX_DN<5>")
	)
	(segment
		(start 365.095536 -284.698948)
		(end 365.012732 -284.616144)
		(width 0.1143)
		(layer "In6.Cu")
		(net "P5E_CPU0_P2_RX_DN<5>")
	)
	(segment
		(start 385.766818 -342.617806)
		(end 385.214368 -337.010756)
		(width 0.14224)
		(layer "In6.Cu")
		(net "P5E_CPU0_P2_RX_DN<5>")
	)
	(segment
		(start 365.844328 -285.91256)
		(end 365.840264 -285.910274)
		(width 0.1143)
		(layer "In6.Cu")
		(net "P5E_CPU0_P2_RX_DN<5>")
	)
	(segment
		(start 409.584398 -389.964168)
		(end 409.47213 -389.552688)
		(width 0.14224)
		(layer "In6.Cu")
		(net "P5E_CPU0_P2_RX_DN<5>")
	)
	(segment
		(start 405.741124 -377.624594)
		(end 405.741124 -376.98045)
		(width 0.14224)
		(layer "In6.Cu")
		(net "P5E_CPU0_P2_RX_DN<5>")
	)
	(segment
		(start 409.772358 -393.787376)
		(end 409.772866 -393.786868)
		(width 0.14224)
		(layer "In6.Cu")
		(net "P5E_CPU0_P2_RX_DN<5>")
	)
	(segment
		(start 409.769564 -390.64057)
		(end 409.600654 -390.544304)
		(width 0.14224)
		(layer "In6.Cu")
		(net "P5E_CPU0_P2_RX_DN<5>")
	)
	(segment
		(start 370.82222 -306.678076)
		(end 367.350802 -301.48276)
		(width 0.14224)
		(layer "In6.Cu")
		(net "P5E_CPU0_P2_RX_DN<5>")
	)
	(segment
		(start 365.84382 -295.634664)
		(end 365.84255 -295.633902)
		(width 0.1143)
		(layer "In6.Cu")
		(net "P5E_CPU0_P2_RX_DN<5>")
	)
	(segment
		(start 409.894532 -393.716764)
		(end 409.894532 -393.545822)
		(width 0.14224)
		(layer "In6.Cu")
		(net "P5E_CPU0_P2_RX_DN<5>")
	)
	(segment
		(start 365.403638 -285.122112)
		(end 365.332772 -285.08071)
		(width 0.1143)
		(layer "In6.Cu")
		(net "P5E_CPU0_P2_RX_DN<5>")
	)
	(segment
		(start 408.893518 -387.956552)
		(end 408.98953 -387.787896)
		(width 0.14224)
		(layer "In6.Cu")
		(net "P5E_CPU0_P2_RX_DN<5>")
	)
	(segment
		(start 405.133302 -375.88698)
		(end 397.514826 -371.572028)
		(width 0.14224)
		(layer "In6.Cu")
		(net "P5E_CPU0_P2_RX_DN<5>")
	)
	(segment
		(start 409.47213 -389.552688)
		(end 409.30322 -389.456422)
		(width 0.14224)
		(layer "In6.Cu")
		(net "P5E_CPU0_P2_RX_DN<5>")
	)
	(segment
		(start 387.480556 -351.243646)
		(end 385.77266 -342.65743)
		(width 0.14224)
		(layer "In6.Cu")
		(net "P5E_CPU0_P2_RX_DN<5>")
	)
	(segment
		(start 409.174696 -388.464552)
		(end 409.00604 -388.368286)
		(width 0.14224)
		(layer "In6.Cu")
		(net "P5E_CPU0_P2_RX_DN<5>")
	)
	(segment
		(start 408.98953 -387.787896)
		(end 408.989784 -387.787642)
		(width 0.14224)
		(layer "In6.Cu")
		(net "P5E_CPU0_P2_RX_DN<5>")
	)
	(segment
		(start 376.10288 -313.112658)
		(end 370.82222 -306.678076)
		(width 0.14224)
		(layer "In6.Cu")
		(net "P5E_CPU0_P2_RX_DN<5>")
	)
	(segment
		(start 365.335312 -287.389824)
		(end 365.402368 -287.350708)
		(width 0.1143)
		(layer "In6.Cu")
		(net "P5E_CPU0_P2_RX_DN<5>")
	)
	(segment
		(start 365.332772 -290.631372)
		(end 365.371888 -290.608512)
		(width 0.1143)
		(layer "In6.Cu")
		(net "P5E_CPU0_P2_RX_DN<5>")
	)
	(segment
		(start 365.332772 -289.01136)
		(end 365.371888 -288.9885)
		(width 0.1143)
		(layer "In6.Cu")
		(net "P5E_CPU0_P2_RX_DN<5>")
	)
	(segment
		(start 365.371888 -294.823388)
		(end 365.332772 -294.800528)
		(width 0.1143)
		(layer "In6.Cu")
		(net "P5E_CPU0_P2_RX_DN<5>")
	)
	(segment
		(start 366.029748 -296.279316)
		(end 366.029748 -295.955974)
		(width 0.1143)
		(layer "In6.Cu")
		(net "P5E_CPU0_P2_RX_DN<5>")
	)
	(segment
		(start 365.371888 -289.963352)
		(end 365.332772 -289.940492)
		(width 0.1143)
		(layer "In6.Cu")
		(net "P5E_CPU0_P2_RX_DN<5>")
	)
	(segment
		(start 408.989784 -387.787642)
		(end 407.457148 -382.178306)
		(width 0.14224)
		(layer "In6.Cu")
		(net "P5E_CPU0_P2_RX_DN<5>")
	)
	(segment
		(start 409.772866 -393.786868)
		(end 409.894532 -393.716764)
		(width 0.14224)
		(layer "In6.Cu")
		(net "P5E_CPU0_P2_RX_DN<5>")
	)
	(segment
		(start 365.847884 -295.63695)
		(end 365.84636 -295.635934)
		(width 0.1143)
		(layer "In6.Cu")
		(net "P5E_CPU0_P2_RX_DN<5>")
	)
	(segment
		(start 409.190952 -389.044688)
		(end 409.286964 -388.876032)
		(width 0.14224)
		(layer "In6.Cu")
		(net "P5E_CPU0_P2_RX_DN<5>")
	)
	(segment
		(start 365.4044 -288.36239)
		(end 365.371888 -288.343594)
		(width 0.1143)
		(layer "In6.Cu")
		(net "P5E_CPU0_P2_RX_DN<5>")
	)
	(segment
		(start 365.371888 -288.9885)
		(end 365.402368 -288.97072)
		(width 0.1143)
		(layer "In6.Cu")
		(net "P5E_CPU0_P2_RX_DN<5>")
	)
	(segment
		(start 365.402368 -291.601144)
		(end 365.371888 -291.583364)
		(width 0.1143)
		(layer "In6.Cu")
		(net "P5E_CPU0_P2_RX_DN<5>")
	)
	(segment
		(start 365.984028 -296.325036)
		(end 366.029748 -296.279316)
		(width 0.1143)
		(layer "In6.Cu")
		(net "P5E_CPU0_P2_RX_DN<5>")
	)
	(segment
		(start 409.600654 -390.544304)
		(end 409.488386 -390.13257)
		(width 0.14224)
		(layer "In6.Cu")
		(net "P5E_CPU0_P2_RX_DN<5>")
	)
	(segment
		(start 409.886404 -392.312906)
		(end 409.886404 -391.085578)
		(width 0.14224)
		(layer "In6.Cu")
		(net "P5E_CPU0_P2_RX_DN<5>")
	)
	(segment
		(start 365.984028 -296.353484)
		(end 365.984028 -296.325036)
		(width 0.1143)
		(layer "In6.Cu")
		(net "P5E_CPU0_P2_RX_DN<5>")
	)
	(segment
		(start 380.318518 -320.366898)
		(end 377.793504 -315.642752)
		(width 0.14224)
		(layer "In6.Cu")
		(net "P5E_CPU0_P2_RX_DN<5>")
	)
	(segment
		(start 365.84255 -295.633902)
		(end 365.841788 -295.633394)
		(width 0.1143)
		(layer "In6.Cu")
		(net "P5E_CPU0_P2_RX_DN<5>")
	)
	(segment
		(start 382.843532 -325.091044)
		(end 380.318264 -320.366898)
		(width 0.14224)
		(layer "In6.Cu")
		(net "P5E_CPU0_P2_RX_DN<5>")
	)
	(segment
		(start 405.397716 -376.151394)
		(end 405.133302 -375.88698)
		(width 0.14224)
		(layer "In6.Cu")
		(net "P5E_CPU0_P2_RX_DN<5>")
	)
	(segment
		(start 365.332772 -292.251384)
		(end 365.371888 -292.228524)
		(width 0.1143)
		(layer "In6.Cu")
		(net "P5E_CPU0_P2_RX_DN<5>")
	)
	(segment
		(start 394.725906 -368.75974)
		(end 387.508496 -351.336356)
		(width 0.14224)
		(layer "In6.Cu")
		(net "P5E_CPU0_P2_RX_DN<5>")
	)
	(segment
		(start 409.488386 -390.13257)
		(end 409.584398 -389.964168)
		(width 0.14224)
		(layer "In6.Cu")
		(net "P5E_CPU0_P2_RX_DN<5>")
	)
	(segment
		(start 365.873538 -295.651682)
		(end 365.847884 -295.63695)
		(width 0.1143)
		(layer "In6.Cu")
		(net "P5E_CPU0_P2_RX_DN<5>")
	)
	(segment
		(start 406.314402 -378.606304)
		(end 406.029922 -378.321824)
		(width 0.14224)
		(layer "In6.Cu")
		(net "P5E_CPU0_P2_RX_DN<5>")
	)
	(segment
		(start 365.402368 -293.221156)
		(end 365.371888 -293.203376)
		(width 0.1143)
		(layer "In6.Cu")
		(net "P5E_CPU0_P2_RX_DN<5>")
	)
	(segment
		(start 365.984028 -298.182284)
		(end 365.984028 -296.353484)
		(width 0.14224)
		(layer "In6.Cu")
		(net "P5E_CPU0_P2_RX_DN<5>")
	)
	(segment
		(start 406.924002 -378.888752)
		(end 406.559258 -378.760482)
		(width 0.14224)
		(layer "In6.Cu")
		(net "P5E_CPU0_P2_RX_DN<5>")
	)
	(segment
		(start 409.57754 -393.22883)
		(end 409.582366 -392.616944)
		(width 0.14224)
		(layer "In6.Cu")
		(net "P5E_CPU0_P2_RX_DN<5>")
	)
	(segment
		(start 409.894532 -393.545822)
		(end 409.57754 -393.22883)
		(width 0.14224)
		(layer "In6.Cu")
		(net "P5E_CPU0_P2_RX_DN<5>")
	)
	(segment
		(start 407.44267 -382.07061)
		(end 407.44267 -379.638052)
		(width 0.14224)
		(layer "In6.Cu")
		(net "P5E_CPU0_P2_RX_DN<5>")
	)
	(segment
		(start 409.00604 -388.368286)
		(end 408.893518 -387.956552)
		(width 0.14224)
		(layer "In6.Cu")
		(net "P5E_CPU0_P2_RX_DN<5>")
	)
	(segment
		(start 409.286964 -388.876032)
		(end 409.174696 -388.464552)
		(width 0.14224)
		(layer "In6.Cu")
		(net "P5E_CPU0_P2_RX_DN<5>")
	)
	(segment
		(start 365.840772 -295.632886)
		(end 365.802672 -295.610534)
		(width 0.1143)
		(layer "In6.Cu")
		(net "P5E_CPU0_P2_RX_DN<5>")
	)
	(segment
		(start 409.881832 -391.05205)
		(end 409.769564 -390.64057)
		(width 0.14224)
		(layer "In6.Cu")
		(net "P5E_CPU0_P2_RX_DN<5>")
	)
	(segment
		(start 397.427196 -371.505226)
		(end 394.814552 -368.892582)
		(width 0.14224)
		(layer "In6.Cu")
		(net "P5E_CPU0_P2_RX_DN<5>")
	)
	(segment
		(start 385.214368 -337.010756)
		(end 382.843532 -325.091044)
		(width 0.14224)
		(layer "In6.Cu")
		(net "P5E_CPU0_P2_RX_DN<5>")
	)
	(segment
		(start 409.30322 -389.456422)
		(end 409.190952 -389.044688)
		(width 0.14224)
		(layer "In6.Cu")
		(net "P5E_CPU0_P2_RX_DN<5>")
	)
	(segment
		(start 409.419044 -393.69238)
		(end 409.772358 -393.787376)
		(width 0.14224)
		(layer "In6.Cu")
		(net "P5E_CPU0_P2_RX_DN<5>")
	)
	(segment
		(start 365.371888 -293.848536)
		(end 365.402368 -293.830756)
		(width 0.1143)
		(layer "In6.Cu")
		(net "P5E_CPU0_P2_RX_DN<5>")
	)
	(segment
		(start 365.402368 -289.981132)
		(end 365.371888 -289.963352)
		(width 0.1143)
		(layer "In6.Cu")
		(net "P5E_CPU0_P2_RX_DN<5>")
	)
	(segment
		(start 365.332772 -293.871396)
		(end 365.371888 -293.848536)
		(width 0.1143)
		(layer "In6.Cu")
		(net "P5E_CPU0_P2_RX_DN<5>")
	)
	(segment
		(start 365.84636 -295.635934)
		(end 365.84382 -295.634664)
		(width 0.1143)
		(layer "In6.Cu")
		(net "P5E_CPU0_P2_RX_DN<5>")
	)
	(segment
		(start 365.371888 -293.203376)
		(end 365.332772 -293.180516)
		(width 0.1143)
		(layer "In6.Cu")
		(net "P5E_CPU0_P2_RX_DN<5>")
	)
	(arc
		(start 365.099346 -284.721808)
		(mid 365.097323 -284.710398)
		(end 365.095536 -284.698948)
		(width 0.1143)
		(layer "In6.Cu")
		(net "P5E_CPU0_P2_RX_DN<5>")
	)
	(arc
		(start 365.55934 -295.145968)
		(mid 365.517791 -294.974546)
		(end 365.402368 -294.841168)
		(width 0.1143)
		(layer "In6.Cu")
		(net "P5E_CPU0_P2_RX_DN<5>")
	)
	(arc
		(start 365.55934 -287.045908)
		(mid 365.623855 -286.783689)
		(end 365.802672 -286.581342)
		(width 0.1143)
		(layer "In6.Cu")
		(net "P5E_CPU0_P2_RX_DN<5>")
	)
	(arc
		(start 397.514826 -371.572028)
		(mid 397.468747 -371.541596)
		(end 397.427196 -371.505226)
		(width 0.14224)
		(layer "In6.Cu")
		(net "P5E_CPU0_P2_RX_DN<5>")
	)
	(arc
		(start 365.332772 -285.08071)
		(mid 365.180785 -284.924202)
		(end 365.099346 -284.721808)
		(width 0.1143)
		(layer "In6.Cu")
		(net "P5E_CPU0_P2_RX_DN<5>")
	)
	(arc
		(start 406.029922 -378.321824)
		(mid 405.816177 -378.001932)
		(end 405.741124 -377.624594)
		(width 0.14224)
		(layer "In6.Cu")
		(net "P5E_CPU0_P2_RX_DN<5>")
	)
	(arc
		(start 365.402368 -293.830756)
		(mid 365.559345 -293.525956)
		(end 365.402368 -293.221156)
		(width 0.1143)
		(layer "In6.Cu")
		(net "P5E_CPU0_P2_RX_DN<5>")
	)
	(arc
		(start 365.402368 -287.350708)
		(mid 365.517795 -287.217332)
		(end 365.55934 -287.045908)
		(width 0.1143)
		(layer "In6.Cu")
		(net "P5E_CPU0_P2_RX_DN<5>")
	)
	(arc
		(start 365.332772 -291.560504)
		(mid 365.089445 -291.095938)
		(end 365.332772 -290.631372)
		(width 0.1143)
		(layer "In6.Cu")
		(net "P5E_CPU0_P2_RX_DN<5>")
	)
	(arc
		(start 365.08944 -287.856168)
		(mid 365.154676 -287.592577)
		(end 365.335312 -287.389824)
		(width 0.1143)
		(layer "In6.Cu")
		(net "P5E_CPU0_P2_RX_DN<5>")
	)
	(arc
		(start 365.963454 -295.74363)
		(mid 365.922471 -295.693768)
		(end 365.873538 -295.651682)
		(width 0.1143)
		(layer "In6.Cu")
		(net "P5E_CPU0_P2_RX_DN<5>")
	)
	(arc
		(start 365.332772 -294.800528)
		(mid 365.089445 -294.335962)
		(end 365.332772 -293.871396)
		(width 0.1143)
		(layer "In6.Cu")
		(net "P5E_CPU0_P2_RX_DN<5>")
	)
	(arc
		(start 385.77266 -342.65743)
		(mid 385.769249 -342.63769)
		(end 385.766818 -342.617806)
		(width 0.14224)
		(layer "In6.Cu")
		(net "P5E_CPU0_P2_RX_DN<5>")
	)
	(arc
		(start 407.205688 -379.066044)
		(mid 407.074802 -378.961573)
		(end 406.924002 -378.888752)
		(width 0.14224)
		(layer "In6.Cu")
		(net "P5E_CPU0_P2_RX_DN<5>")
	)
	(arc
		(start 365.332772 -293.180516)
		(mid 365.089445 -292.71595)
		(end 365.332772 -292.251384)
		(width 0.1143)
		(layer "In6.Cu")
		(net "P5E_CPU0_P2_RX_DN<5>")
	)
	(arc
		(start 394.814552 -368.892582)
		(mid 394.763675 -368.830533)
		(end 394.725906 -368.75974)
		(width 0.14224)
		(layer "In6.Cu")
		(net "P5E_CPU0_P2_RX_DN<5>")
	)
	(arc
		(start 365.871506 -286.541464)
		(mid 366.028966 -286.219667)
		(end 365.844328 -285.91256)
		(width 0.1143)
		(layer "In6.Cu")
		(net "P5E_CPU0_P2_RX_DN<5>")
	)
	(arc
		(start 409.886404 -391.085578)
		(mid 409.88524 -391.068661)
		(end 409.881832 -391.05205)
		(width 0.14224)
		(layer "In6.Cu")
		(net "P5E_CPU0_P2_RX_DN<5>")
	)
	(arc
		(start 365.332772 -288.320734)
		(mid 365.153959 -288.118384)
		(end 365.08944 -287.856168)
		(width 0.1143)
		(layer "In6.Cu")
		(net "P5E_CPU0_P2_RX_DN<5>")
	)
	(arc
		(start 387.508496 -351.336356)
		(mid 387.492247 -351.290688)
		(end 387.480556 -351.243646)
		(width 0.14224)
		(layer "In6.Cu")
		(net "P5E_CPU0_P2_RX_DN<5>")
	)
	(arc
		(start 407.457148 -382.178306)
		(mid 407.44631 -382.124941)
		(end 407.44267 -382.07061)
		(width 0.14224)
		(layer "In6.Cu")
		(net "P5E_CPU0_P2_RX_DN<5>")
	)
	(arc
		(start 365.402368 -290.590732)
		(mid 365.559345 -290.285932)
		(end 365.402368 -289.981132)
		(width 0.1143)
		(layer "In6.Cu")
		(net "P5E_CPU0_P2_RX_DN<5>")
	)
	(arc
		(start 365.559594 -285.42615)
		(mid 365.518335 -285.255293)
		(end 365.403638 -285.122112)
		(width 0.1143)
		(layer "In6.Cu")
		(net "P5E_CPU0_P2_RX_DN<5>")
	)
	(arc
		(start 365.55934 -288.66592)
		(mid 365.518374 -288.495514)
		(end 365.4044 -288.36239)
		(width 0.1143)
		(layer "In6.Cu")
		(net "P5E_CPU0_P2_RX_DN<5>")
	)
	(arc
		(start 366.029748 -295.955974)
		(mid 366.012698 -295.844783)
		(end 365.963454 -295.74363)
		(width 0.1143)
		(layer "In6.Cu")
		(net "P5E_CPU0_P2_RX_DN<5>")
	)
	(arc
		(start 365.840264 -285.910274)
		(mid 365.634807 -285.70596)
		(end 365.559594 -285.42615)
		(width 0.1143)
		(layer "In6.Cu")
		(net "P5E_CPU0_P2_RX_DN<5>")
	)
	(arc
		(start 365.332772 -289.940492)
		(mid 365.089445 -289.475926)
		(end 365.332772 -289.01136)
		(width 0.1143)
		(layer "In6.Cu")
		(net "P5E_CPU0_P2_RX_DN<5>")
	)
	(arc
		(start 365.802672 -295.610534)
		(mid 365.623859 -295.408184)
		(end 365.55934 -295.145968)
		(width 0.1143)
		(layer "In6.Cu")
		(net "P5E_CPU0_P2_RX_DN<5>")
	)
	(arc
		(start 405.741124 -376.98045)
		(mid 405.651875 -376.531767)
		(end 405.397716 -376.151394)
		(width 0.14224)
		(layer "In6.Cu")
		(net "P5E_CPU0_P2_RX_DN<5>")
	)
	(arc
		(start 365.402368 -288.97072)
		(mid 365.517795 -288.837344)
		(end 365.55934 -288.66592)
		(width 0.1143)
		(layer "In6.Cu")
		(net "P5E_CPU0_P2_RX_DN<5>")
	)
	(arc
		(start 407.44267 -379.638052)
		(mid 407.381074 -379.328479)
		(end 407.205688 -379.066044)
		(width 0.14224)
		(layer "In6.Cu")
		(net "P5E_CPU0_P2_RX_DN<5>")
	)
	(arc
		(start 365.402368 -292.210744)
		(mid 365.559345 -291.905944)
		(end 365.402368 -291.601144)
		(width 0.1143)
		(layer "In6.Cu")
		(net "P5E_CPU0_P2_RX_DN<5>")
	)
	(arc
		(start 406.559258 -378.760482)
		(mid 406.428188 -378.697121)
		(end 406.314402 -378.606304)
		(width 0.14224)
		(layer "In6.Cu")
		(net "P5E_CPU0_P2_RX_DN<5>")
	)
	(segment
		(start 407.698194 -393.69238)
		(end 408.218894 -393.69238)
		(width 0.127)
		(layer "F.Cu")
		(net "P5E_CPU0_P2_RX_DN<4>")
	)
	(segment
		(start 364.247938 -285.970218)
		(end 364.71479 -286.236156)
		(width 0.12954)
		(layer "F.Cu")
		(net "P5E_CPU0_P2_RX_DN<4>")
	)
	(segment
		(start 400.32432 -374.338342)
		(end 400.32432 -374.338088)
		(width 0.14224)
		(layer "In6.Cu")
		(net "P5E_CPU0_P2_RX_DN<4>")
	)
	(segment
		(start 364.428278 -287.37052)
		(end 364.429294 -287.370012)
		(width 0.1143)
		(layer "In6.Cu")
		(net "P5E_CPU0_P2_RX_DN<4>")
	)
	(segment
		(start 364.431834 -293.848536)
		(end 364.462314 -293.830756)
		(width 0.1143)
		(layer "In6.Cu")
		(net "P5E_CPU0_P2_RX_DN<4>")
	)
	(segment
		(start 364.395258 -287.389824)
		(end 364.428278 -287.37052)
		(width 0.1143)
		(layer "In6.Cu")
		(net "P5E_CPU0_P2_RX_DN<4>")
	)
	(segment
		(start 364.430818 -287.368996)
		(end 364.431834 -287.368488)
		(width 0.1143)
		(layer "In6.Cu")
		(net "P5E_CPU0_P2_RX_DN<4>")
	)
	(segment
		(start 364.9345 -286.539432)
		(end 364.935262 -286.538924)
		(width 0.1143)
		(layer "In6.Cu")
		(net "P5E_CPU0_P2_RX_DN<4>")
	)
	(segment
		(start 364.462314 -294.841168)
		(end 364.431834 -294.823388)
		(width 0.1143)
		(layer "In6.Cu")
		(net "P5E_CPU0_P2_RX_DN<4>")
	)
	(segment
		(start 364.462314 -293.221156)
		(end 364.431834 -293.203376)
		(width 0.1143)
		(layer "In6.Cu")
		(net "P5E_CPU0_P2_RX_DN<4>")
	)
	(segment
		(start 364.462314 -289.981132)
		(end 364.431834 -289.963352)
		(width 0.1143)
		(layer "In6.Cu")
		(net "P5E_CPU0_P2_RX_DN<4>")
	)
	(segment
		(start 377.090686 -316.314328)
		(end 375.223786 -313.520074)
		(width 0.14224)
		(layer "In6.Cu")
		(net "P5E_CPU0_P2_RX_DN<4>")
	)
	(segment
		(start 364.61954 -295.145968)
		(end 364.619286 -295.145968)
		(width 0.1143)
		(layer "In6.Cu")
		(net "P5E_CPU0_P2_RX_DN<4>")
	)
	(segment
		(start 364.464346 -288.36239)
		(end 364.431834 -288.343594)
		(width 0.1143)
		(layer "In6.Cu")
		(net "P5E_CPU0_P2_RX_DN<4>")
	)
	(segment
		(start 364.392718 -293.871396)
		(end 364.431834 -293.848536)
		(width 0.1143)
		(layer "In6.Cu")
		(net "P5E_CPU0_P2_RX_DN<4>")
	)
	(segment
		(start 384.269742 -337.041744)
		(end 381.958342 -325.420736)
		(width 0.14224)
		(layer "In6.Cu")
		(net "P5E_CPU0_P2_RX_DN<4>")
	)
	(segment
		(start 364.431834 -291.583364)
		(end 364.392718 -291.560504)
		(width 0.1143)
		(layer "In6.Cu")
		(net "P5E_CPU0_P2_RX_DN<4>")
	)
	(segment
		(start 407.39949 -386.37718)
		(end 406.255474 -382.253236)
		(width 0.14224)
		(layer "In6.Cu")
		(net "P5E_CPU0_P2_RX_DN<4>")
	)
	(segment
		(start 407.605992 -387.633972)
		(end 407.701496 -387.465062)
		(width 0.14224)
		(layer "In6.Cu")
		(net "P5E_CPU0_P2_RX_DN<4>")
	)
	(segment
		(start 364.431834 -288.9885)
		(end 364.462314 -288.97072)
		(width 0.1143)
		(layer "In6.Cu")
		(net "P5E_CPU0_P2_RX_DN<4>")
	)
	(segment
		(start 408.694382 -393.545822)
		(end 408.37739 -393.22883)
		(width 0.14224)
		(layer "In6.Cu")
		(net "P5E_CPU0_P2_RX_DN<4>")
	)
	(segment
		(start 408.694382 -393.716764)
		(end 408.694382 -393.545822)
		(width 0.14224)
		(layer "In6.Cu")
		(net "P5E_CPU0_P2_RX_DN<4>")
	)
	(segment
		(start 364.431834 -289.963352)
		(end 364.392718 -289.940492)
		(width 0.1143)
		(layer "In6.Cu")
		(net "P5E_CPU0_P2_RX_DN<4>")
	)
	(segment
		(start 396.426182 -372.039134)
		(end 394.142214 -369.755166)
		(width 0.14224)
		(layer "In6.Cu")
		(net "P5E_CPU0_P2_RX_DN<4>")
	)
	(segment
		(start 365.039402 -298.338494)
		(end 365.039402 -296.353484)
		(width 0.14224)
		(layer "In6.Cu")
		(net "P5E_CPU0_P2_RX_DN<4>")
	)
	(segment
		(start 364.392718 -290.631372)
		(end 364.431834 -290.608512)
		(width 0.1143)
		(layer "In6.Cu")
		(net "P5E_CPU0_P2_RX_DN<4>")
	)
	(segment
		(start 364.431834 -288.343594)
		(end 364.392718 -288.320734)
		(width 0.1143)
		(layer "In6.Cu")
		(net "P5E_CPU0_P2_RX_DN<4>")
	)
	(segment
		(start 365.082582 -286.306006)
		(end 365.012732 -286.236156)
		(width 0.1143)
		(layer "In6.Cu")
		(net "P5E_CPU0_P2_RX_DN<4>")
	)
	(segment
		(start 400.32432 -374.338088)
		(end 396.896336 -372.396766)
		(width 0.14224)
		(layer "In6.Cu")
		(net "P5E_CPU0_P2_RX_DN<4>")
	)
	(segment
		(start 364.899194 -286.560006)
		(end 364.90021 -286.559498)
		(width 0.1143)
		(layer "In6.Cu")
		(net "P5E_CPU0_P2_RX_DN<4>")
	)
	(segment
		(start 408.218894 -393.69238)
		(end 408.572208 -393.787376)
		(width 0.14224)
		(layer "In6.Cu")
		(net "P5E_CPU0_P2_RX_DN<4>")
	)
	(segment
		(start 365.039402 -296.353484)
		(end 365.039402 -296.325036)
		(width 0.1143)
		(layer "In6.Cu")
		(net "P5E_CPU0_P2_RX_DN<4>")
	)
	(segment
		(start 365.085122 -296.011346)
		(end 365.089694 -296.006774)
		(width 0.1143)
		(layer "In6.Cu")
		(net "P5E_CPU0_P2_RX_DN<4>")
	)
	(segment
		(start 406.167082 -382.096264)
		(end 405.5364 -381.465582)
		(width 0.14224)
		(layer "In6.Cu")
		(net "P5E_CPU0_P2_RX_DN<4>")
	)
	(segment
		(start 365.085122 -296.279316)
		(end 365.085122 -296.011346)
		(width 0.1143)
		(layer "In6.Cu")
		(net "P5E_CPU0_P2_RX_DN<4>")
	)
	(segment
		(start 364.909354 -295.637458)
		(end 364.86338 -295.611042)
		(width 0.1143)
		(layer "In6.Cu")
		(net "P5E_CPU0_P2_RX_DN<4>")
	)
	(segment
		(start 406.255474 -382.253236)
		(end 406.252934 -382.250696)
		(width 0.14224)
		(layer "In6.Cu")
		(net "P5E_CPU0_P2_RX_DN<4>")
	)
	(segment
		(start 407.888948 -388.140956)
		(end 407.720038 -388.045452)
		(width 0.14224)
		(layer "In6.Cu")
		(net "P5E_CPU0_P2_RX_DN<4>")
	)
	(segment
		(start 407.90749 -388.720838)
		(end 408.002994 -388.551928)
		(width 0.14224)
		(layer "In6.Cu")
		(net "P5E_CPU0_P2_RX_DN<4>")
	)
	(segment
		(start 384.84048 -342.834468)
		(end 384.269742 -337.041744)
		(width 0.14224)
		(layer "In6.Cu")
		(net "P5E_CPU0_P2_RX_DN<4>")
	)
	(segment
		(start 404.043134 -380.300738)
		(end 404.043134 -376.518424)
		(width 0.14224)
		(layer "In6.Cu")
		(net "P5E_CPU0_P2_RX_DN<4>")
	)
	(segment
		(start 364.431834 -290.608512)
		(end 364.462314 -290.590732)
		(width 0.1143)
		(layer "In6.Cu")
		(net "P5E_CPU0_P2_RX_DN<4>")
	)
	(segment
		(start 364.429294 -287.370012)
		(end 364.430818 -287.368996)
		(width 0.1143)
		(layer "In6.Cu")
		(net "P5E_CPU0_P2_RX_DN<4>")
	)
	(segment
		(start 364.462314 -291.601144)
		(end 364.431834 -291.583364)
		(width 0.1143)
		(layer "In6.Cu")
		(net "P5E_CPU0_P2_RX_DN<4>")
	)
	(segment
		(start 403.978618 -376.40768)
		(end 400.32432 -374.338342)
		(width 0.14224)
		(layer "In6.Cu")
		(net "P5E_CPU0_P2_RX_DN<4>")
	)
	(segment
		(start 407.720038 -388.045452)
		(end 407.605992 -387.633972)
		(width 0.14224)
		(layer "In6.Cu")
		(net "P5E_CPU0_P2_RX_DN<4>")
	)
	(segment
		(start 408.572208 -393.787376)
		(end 408.572716 -393.786868)
		(width 0.14224)
		(layer "In6.Cu")
		(net "P5E_CPU0_P2_RX_DN<4>")
	)
	(segment
		(start 364.392718 -292.251384)
		(end 364.431834 -292.228524)
		(width 0.1143)
		(layer "In6.Cu")
		(net "P5E_CPU0_P2_RX_DN<4>")
	)
	(segment
		(start 370.080286 -307.253132)
		(end 366.532414 -301.943262)
		(width 0.14224)
		(layer "In6.Cu")
		(net "P5E_CPU0_P2_RX_DN<4>")
	)
	(segment
		(start 408.1907 -389.227822)
		(end 408.021536 -389.132318)
		(width 0.14224)
		(layer "In6.Cu")
		(net "P5E_CPU0_P2_RX_DN<4>")
	)
	(segment
		(start 364.431834 -287.368488)
		(end 364.433612 -287.367472)
		(width 0.1143)
		(layer "In6.Cu")
		(net "P5E_CPU0_P2_RX_DN<4>")
	)
	(segment
		(start 381.958342 -325.420736)
		(end 377.090686 -316.314328)
		(width 0.14224)
		(layer "In6.Cu")
		(net "P5E_CPU0_P2_RX_DN<4>")
	)
	(segment
		(start 364.90021 -286.559498)
		(end 364.9345 -286.539432)
		(width 0.1143)
		(layer "In6.Cu")
		(net "P5E_CPU0_P2_RX_DN<4>")
	)
	(segment
		(start 408.686254 -392.312906)
		(end 408.686254 -391.219944)
		(width 0.14224)
		(layer "In6.Cu")
		(net "P5E_CPU0_P2_RX_DN<4>")
	)
	(segment
		(start 408.631644 -390.817862)
		(end 408.190446 -389.227822)
		(width 0.14224)
		(layer "In6.Cu")
		(net "P5E_CPU0_P2_RX_DN<4>")
	)
	(segment
		(start 407.701496 -387.465062)
		(end 407.58745 -387.05409)
		(width 0.14224)
		(layer "In6.Cu")
		(net "P5E_CPU0_P2_RX_DN<4>")
	)
	(segment
		(start 364.392718 -289.01136)
		(end 364.431834 -288.9885)
		(width 0.1143)
		(layer "In6.Cu")
		(net "P5E_CPU0_P2_RX_DN<4>")
	)
	(segment
		(start 407.399744 -386.378196)
		(end 407.39949 -386.37718)
		(width 0.14224)
		(layer "In6.Cu")
		(net "P5E_CPU0_P2_RX_DN<4>")
	)
	(segment
		(start 406.252934 -382.250696)
		(end 406.252934 -382.243584)
		(width 0.14224)
		(layer "In6.Cu")
		(net "P5E_CPU0_P2_RX_DN<4>")
	)
	(segment
		(start 364.431834 -292.228524)
		(end 364.462314 -292.210744)
		(width 0.1143)
		(layer "In6.Cu")
		(net "P5E_CPU0_P2_RX_DN<4>")
	)
	(segment
		(start 408.021536 -389.132318)
		(end 407.90749 -388.720838)
		(width 0.14224)
		(layer "In6.Cu")
		(net "P5E_CPU0_P2_RX_DN<4>")
	)
	(segment
		(start 364.431834 -293.203376)
		(end 364.392718 -293.180516)
		(width 0.1143)
		(layer "In6.Cu")
		(net "P5E_CPU0_P2_RX_DN<4>")
	)
	(segment
		(start 364.431834 -294.823388)
		(end 364.392718 -294.800528)
		(width 0.1143)
		(layer "In6.Cu")
		(net "P5E_CPU0_P2_RX_DN<4>")
	)
	(segment
		(start 365.089694 -296.006774)
		(end 365.089694 -295.952672)
		(width 0.1143)
		(layer "In6.Cu")
		(net "P5E_CPU0_P2_RX_DN<4>")
	)
	(segment
		(start 393.94892 -369.466114)
		(end 386.628386 -351.792032)
		(width 0.14224)
		(layer "In6.Cu")
		(net "P5E_CPU0_P2_RX_DN<4>")
	)
	(segment
		(start 408.37739 -393.22883)
		(end 408.382216 -392.616944)
		(width 0.14224)
		(layer "In6.Cu")
		(net "P5E_CPU0_P2_RX_DN<4>")
	)
	(segment
		(start 407.58745 -387.05409)
		(end 407.41854 -386.958586)
		(width 0.14224)
		(layer "In6.Cu")
		(net "P5E_CPU0_P2_RX_DN<4>")
	)
	(segment
		(start 375.223786 -313.520074)
		(end 370.080286 -307.253132)
		(width 0.14224)
		(layer "In6.Cu")
		(net "P5E_CPU0_P2_RX_DN<4>")
	)
	(segment
		(start 405.494998 -381.43815)
		(end 404.64232 -381.084836)
		(width 0.14224)
		(layer "In6.Cu")
		(net "P5E_CPU0_P2_RX_DN<4>")
	)
	(segment
		(start 408.572716 -393.786868)
		(end 408.694382 -393.716764)
		(width 0.14224)
		(layer "In6.Cu")
		(net "P5E_CPU0_P2_RX_DN<4>")
	)
	(segment
		(start 365.039402 -296.325036)
		(end 365.085122 -296.279316)
		(width 0.1143)
		(layer "In6.Cu")
		(net "P5E_CPU0_P2_RX_DN<4>")
	)
	(segment
		(start 366.532414 -301.943262)
		(end 365.039402 -298.338494)
		(width 0.14224)
		(layer "In6.Cu")
		(net "P5E_CPU0_P2_RX_DN<4>")
	)
	(segment
		(start 386.605018 -351.715578)
		(end 384.846322 -342.874092)
		(width 0.14224)
		(layer "In6.Cu")
		(net "P5E_CPU0_P2_RX_DN<4>")
	)
	(segment
		(start 365.012732 -286.236156)
		(end 364.71479 -286.236156)
		(width 0.1143)
		(layer "In6.Cu")
		(net "P5E_CPU0_P2_RX_DN<4>")
	)
	(segment
		(start 407.304494 -386.547106)
		(end 407.399998 -386.378196)
		(width 0.14224)
		(layer "In6.Cu")
		(net "P5E_CPU0_P2_RX_DN<4>")
	)
	(segment
		(start 408.190446 -389.227822)
		(end 408.1907 -389.227822)
		(width 0.14224)
		(layer "In6.Cu")
		(net "P5E_CPU0_P2_RX_DN<4>")
	)
	(segment
		(start 408.002994 -388.551928)
		(end 407.888948 -388.140956)
		(width 0.14224)
		(layer "In6.Cu")
		(net "P5E_CPU0_P2_RX_DN<4>")
	)
	(segment
		(start 404.370794 -380.90348)
		(end 404.237698 -380.770384)
		(width 0.14224)
		(layer "In6.Cu")
		(net "P5E_CPU0_P2_RX_DN<4>")
	)
	(segment
		(start 408.382216 -392.616944)
		(end 408.686254 -392.312906)
		(width 0.14224)
		(layer "In6.Cu")
		(net "P5E_CPU0_P2_RX_DN<4>")
	)
	(segment
		(start 407.399998 -386.378196)
		(end 407.399744 -386.378196)
		(width 0.14224)
		(layer "In6.Cu")
		(net "P5E_CPU0_P2_RX_DN<4>")
	)
	(segment
		(start 407.41854 -386.958586)
		(end 407.304494 -386.547106)
		(width 0.14224)
		(layer "In6.Cu")
		(net "P5E_CPU0_P2_RX_DN<4>")
	)
	(arc
		(start 406.252934 -382.243584)
		(mid 406.219539 -382.164367)
		(end 406.167082 -382.096264)
		(width 0.14224)
		(layer "In6.Cu")
		(net "P5E_CPU0_P2_RX_DN<4>")
	)
	(arc
		(start 364.619286 -295.145968)
		(mid 364.577737 -294.974546)
		(end 364.462314 -294.841168)
		(width 0.1143)
		(layer "In6.Cu")
		(net "P5E_CPU0_P2_RX_DN<4>")
	)
	(arc
		(start 364.392718 -288.320734)
		(mid 364.213905 -288.118384)
		(end 364.149386 -287.856168)
		(width 0.1143)
		(layer "In6.Cu")
		(net "P5E_CPU0_P2_RX_DN<4>")
	)
	(arc
		(start 364.462314 -293.830756)
		(mid 364.619291 -293.525956)
		(end 364.462314 -293.221156)
		(width 0.1143)
		(layer "In6.Cu")
		(net "P5E_CPU0_P2_RX_DN<4>")
	)
	(arc
		(start 396.896336 -372.396766)
		(mid 396.649158 -372.233858)
		(end 396.426182 -372.039134)
		(width 0.14224)
		(layer "In6.Cu")
		(net "P5E_CPU0_P2_RX_DN<4>")
	)
	(arc
		(start 364.392718 -293.180516)
		(mid 364.149391 -292.71595)
		(end 364.392718 -292.251384)
		(width 0.1143)
		(layer "In6.Cu")
		(net "P5E_CPU0_P2_RX_DN<4>")
	)
	(arc
		(start 364.462314 -292.210744)
		(mid 364.619291 -291.905944)
		(end 364.462314 -291.601144)
		(width 0.1143)
		(layer "In6.Cu")
		(net "P5E_CPU0_P2_RX_DN<4>")
	)
	(arc
		(start 394.142214 -369.755166)
		(mid 394.031328 -369.620162)
		(end 393.94892 -369.466114)
		(width 0.14224)
		(layer "In6.Cu")
		(net "P5E_CPU0_P2_RX_DN<4>")
	)
	(arc
		(start 364.433612 -287.367472)
		(mid 364.569534 -287.231713)
		(end 364.619286 -287.046162)
		(width 0.1143)
		(layer "In6.Cu")
		(net "P5E_CPU0_P2_RX_DN<4>")
	)
	(arc
		(start 364.392718 -294.800528)
		(mid 364.149391 -294.335962)
		(end 364.392718 -293.871396)
		(width 0.1143)
		(layer "In6.Cu")
		(net "P5E_CPU0_P2_RX_DN<4>")
	)
	(arc
		(start 364.462314 -290.590732)
		(mid 364.619291 -290.285932)
		(end 364.462314 -289.981132)
		(width 0.1143)
		(layer "In6.Cu")
		(net "P5E_CPU0_P2_RX_DN<4>")
	)
	(arc
		(start 386.628386 -351.792032)
		(mid 386.614823 -351.754379)
		(end 386.605018 -351.715578)
		(width 0.14224)
		(layer "In6.Cu")
		(net "P5E_CPU0_P2_RX_DN<4>")
	)
	(arc
		(start 364.392718 -289.940492)
		(mid 364.149391 -289.475926)
		(end 364.392718 -289.01136)
		(width 0.1143)
		(layer "In6.Cu")
		(net "P5E_CPU0_P2_RX_DN<4>")
	)
	(arc
		(start 404.043134 -376.518424)
		(mid 404.025825 -376.454348)
		(end 403.978618 -376.40768)
		(width 0.14224)
		(layer "In6.Cu")
		(net "P5E_CPU0_P2_RX_DN<4>")
	)
	(arc
		(start 364.86338 -295.611042)
		(mid 364.684187 -295.408532)
		(end 364.61954 -295.145968)
		(width 0.1143)
		(layer "In6.Cu")
		(net "P5E_CPU0_P2_RX_DN<4>")
	)
	(arc
		(start 364.619286 -288.66592)
		(mid 364.57832 -288.495514)
		(end 364.464346 -288.36239)
		(width 0.1143)
		(layer "In6.Cu")
		(net "P5E_CPU0_P2_RX_DN<4>")
	)
	(arc
		(start 364.392718 -291.560504)
		(mid 364.149391 -291.095938)
		(end 364.392718 -290.631372)
		(width 0.1143)
		(layer "In6.Cu")
		(net "P5E_CPU0_P2_RX_DN<4>")
	)
	(arc
		(start 364.462314 -288.97072)
		(mid 364.577741 -288.837344)
		(end 364.619286 -288.66592)
		(width 0.1143)
		(layer "In6.Cu")
		(net "P5E_CPU0_P2_RX_DN<4>")
	)
	(arc
		(start 408.686254 -391.219944)
		(mid 408.672575 -391.017052)
		(end 408.631644 -390.817862)
		(width 0.14224)
		(layer "In6.Cu")
		(net "P5E_CPU0_P2_RX_DN<4>")
	)
	(arc
		(start 365.089694 -295.952672)
		(mid 365.041432 -295.77108)
		(end 364.909354 -295.637458)
		(width 0.1143)
		(layer "In6.Cu")
		(net "P5E_CPU0_P2_RX_DN<4>")
	)
	(arc
		(start 364.149386 -287.856168)
		(mid 364.214622 -287.592577)
		(end 364.395258 -287.389824)
		(width 0.1143)
		(layer "In6.Cu")
		(net "P5E_CPU0_P2_RX_DN<4>")
	)
	(arc
		(start 404.237698 -380.770384)
		(mid 404.093722 -380.554909)
		(end 404.043134 -380.300738)
		(width 0.14224)
		(layer "In6.Cu")
		(net "P5E_CPU0_P2_RX_DN<4>")
	)
	(arc
		(start 384.846322 -342.874092)
		(mid 384.842911 -342.854352)
		(end 384.84048 -342.834468)
		(width 0.14224)
		(layer "In6.Cu")
		(net "P5E_CPU0_P2_RX_DN<4>")
	)
	(arc
		(start 404.64232 -381.084836)
		(mid 404.49762 -381.007536)
		(end 404.370794 -380.90348)
		(width 0.14224)
		(layer "In6.Cu")
		(net "P5E_CPU0_P2_RX_DN<4>")
	)
	(arc
		(start 364.935262 -286.538924)
		(mid 365.03115 -286.436516)
		(end 365.082582 -286.306006)
		(width 0.1143)
		(layer "In6.Cu")
		(net "P5E_CPU0_P2_RX_DN<4>")
	)
	(arc
		(start 405.5364 -381.465582)
		(mid 405.517046 -381.449834)
		(end 405.494998 -381.43815)
		(width 0.14224)
		(layer "In6.Cu")
		(net "P5E_CPU0_P2_RX_DN<4>")
	)
	(arc
		(start 364.619286 -287.046162)
		(mid 364.694266 -286.765678)
		(end 364.899194 -286.560006)
		(width 0.1143)
		(layer "In6.Cu")
		(net "P5E_CPU0_P2_RX_DN<4>")
	)
	(segment
		(start 406.498298 -393.69238)
		(end 407.018998 -393.69238)
		(width 0.127)
		(layer "F.Cu")
		(net "P5E_CPU0_P2_RX_DN<3>")
	)
	(segment
		(start 364.247938 -282.730194)
		(end 364.71479 -282.996132)
		(width 0.12954)
		(layer "F.Cu")
		(net "P5E_CPU0_P2_RX_DN<3>")
	)
	(segment
		(start 401.634452 -376.250962)
		(end 401.228052 -376.010678)
		(width 0.14224)
		(layer "In6.Cu")
		(net "P5E_CPU0_P2_RX_DN<3>")
	)
	(segment
		(start 363.490764 -288.989008)
		(end 363.49178 -288.9885)
		(width 0.1143)
		(layer "In6.Cu")
		(net "P5E_CPU0_P2_RX_DN<3>")
	)
	(segment
		(start 363.483652 -294.818562)
		(end 363.452664 -294.800528)
		(width 0.1143)
		(layer "In6.Cu")
		(net "P5E_CPU0_P2_RX_DN<3>")
	)
	(segment
		(start 363.485176 -289.959542)
		(end 363.483652 -289.958526)
		(width 0.1143)
		(layer "In6.Cu")
		(net "P5E_CPU0_P2_RX_DN<3>")
	)
	(segment
		(start 363.485176 -294.819578)
		(end 363.483652 -294.818562)
		(width 0.1143)
		(layer "In6.Cu")
		(net "P5E_CPU0_P2_RX_DN<3>")
	)
	(segment
		(start 407.494486 -393.716764)
		(end 407.494486 -393.545822)
		(width 0.14224)
		(layer "In6.Cu")
		(net "P5E_CPU0_P2_RX_DN<3>")
	)
	(segment
		(start 363.493812 -293.847266)
		(end 363.52353 -293.830248)
		(width 0.1143)
		(layer "In6.Cu")
		(net "P5E_CPU0_P2_RX_DN<3>")
	)
	(segment
		(start 363.485176 -293.199566)
		(end 363.483652 -293.19855)
		(width 0.1143)
		(layer "In6.Cu")
		(net "P5E_CPU0_P2_RX_DN<3>")
	)
	(segment
		(start 363.49178 -288.9885)
		(end 363.492542 -288.987992)
		(width 0.1143)
		(layer "In6.Cu")
		(net "P5E_CPU0_P2_RX_DN<3>")
	)
	(segment
		(start 376.256296 -316.754764)
		(end 374.493536 -314.116974)
		(width 0.14224)
		(layer "In6.Cu")
		(net "P5E_CPU0_P2_RX_DN<3>")
	)
	(segment
		(start 363.490764 -294.82288)
		(end 363.48924 -294.821864)
		(width 0.1143)
		(layer "In6.Cu")
		(net "P5E_CPU0_P2_RX_DN<3>")
	)
	(segment
		(start 363.961934 -284.938724)
		(end 363.992414 -284.920944)
		(width 0.1143)
		(layer "In6.Cu")
		(net "P5E_CPU0_P2_RX_DN<3>")
	)
	(segment
		(start 364.865412 -283.339794)
		(end 364.901734 -283.318712)
		(width 0.1143)
		(layer "In6.Cu")
		(net "P5E_CPU0_P2_RX_DN<3>")
	)
	(segment
		(start 363.49178 -289.963352)
		(end 363.490764 -289.962844)
		(width 0.1143)
		(layer "In6.Cu")
		(net "P5E_CPU0_P2_RX_DN<3>")
	)
	(segment
		(start 381.07747 -325.77278)
		(end 376.256296 -316.754764)
		(width 0.14224)
		(layer "In6.Cu")
		(net "P5E_CPU0_P2_RX_DN<3>")
	)
	(segment
		(start 363.496352 -294.825928)
		(end 363.493812 -294.824658)
		(width 0.1143)
		(layer "In6.Cu")
		(net "P5E_CPU0_P2_RX_DN<3>")
	)
	(segment
		(start 363.48924 -293.201852)
		(end 363.486446 -293.200328)
		(width 0.1143)
		(layer "In6.Cu")
		(net "P5E_CPU0_P2_RX_DN<3>")
	)
	(segment
		(start 407.37282 -393.786868)
		(end 407.494486 -393.716764)
		(width 0.14224)
		(layer "In6.Cu")
		(net "P5E_CPU0_P2_RX_DN<3>")
	)
	(segment
		(start 363.492542 -285.748222)
		(end 363.493812 -285.74746)
		(width 0.1143)
		(layer "In6.Cu")
		(net "P5E_CPU0_P2_RX_DN<3>")
	)
	(segment
		(start 383.335022 -337.12277)
		(end 381.07747 -325.77278)
		(width 0.14224)
		(layer "In6.Cu")
		(net "P5E_CPU0_P2_RX_DN<3>")
	)
	(segment
		(start 363.497876 -289.966908)
		(end 363.496352 -289.965892)
		(width 0.1143)
		(layer "In6.Cu")
		(net "P5E_CPU0_P2_RX_DN<3>")
	)
	(segment
		(start 363.525308 -286.74314)
		(end 363.49178 -286.723582)
		(width 0.1143)
		(layer "In6.Cu")
		(net "P5E_CPU0_P2_RX_DN<3>")
	)
	(segment
		(start 407.229564 -392.5697)
		(end 407.444702 -392.354562)
		(width 0.14224)
		(layer "In6.Cu")
		(net "P5E_CPU0_P2_RX_DN<3>")
	)
	(segment
		(start 402.341334 -382.530604)
		(end 402.341334 -381.71374)
		(width 0.14224)
		(layer "In6.Cu")
		(net "P5E_CPU0_P2_RX_DN<3>")
	)
	(segment
		(start 363.486446 -293.200328)
		(end 363.485176 -293.199566)
		(width 0.1143)
		(layer "In6.Cu")
		(net "P5E_CPU0_P2_RX_DN<3>")
	)
	(segment
		(start 402.341334 -381.0127)
		(end 402.341334 -380.58598)
		(width 0.14224)
		(layer "In6.Cu")
		(net "P5E_CPU0_P2_RX_DN<3>")
	)
	(segment
		(start 363.452664 -285.77159)
		(end 363.48924 -285.750254)
		(width 0.1143)
		(layer "In6.Cu")
		(net "P5E_CPU0_P2_RX_DN<3>")
	)
	(segment
		(start 363.525308 -288.363152)
		(end 363.49178 -288.343594)
		(width 0.1143)
		(layer "In6.Cu")
		(net "P5E_CPU0_P2_RX_DN<3>")
	)
	(segment
		(start 363.49178 -290.608512)
		(end 363.492542 -290.608004)
		(width 0.1143)
		(layer "In6.Cu")
		(net "P5E_CPU0_P2_RX_DN<3>")
	)
	(segment
		(start 401.228052 -376.010678)
		(end 396.304516 -373.222266)
		(width 0.14224)
		(layer "In6.Cu")
		(net "P5E_CPU0_P2_RX_DN<3>")
	)
	(segment
		(start 363.483652 -291.578538)
		(end 363.452664 -291.560504)
		(width 0.1143)
		(layer "In6.Cu")
		(net "P5E_CPU0_P2_RX_DN<3>")
	)
	(segment
		(start 363.48924 -293.85006)
		(end 363.490764 -293.849044)
		(width 0.1143)
		(layer "In6.Cu")
		(net "P5E_CPU0_P2_RX_DN<3>")
	)
	(segment
		(start 383.93878 -343.249504)
		(end 383.335022 -337.12277)
		(width 0.14224)
		(layer "In6.Cu")
		(net "P5E_CPU0_P2_RX_DN<3>")
	)
	(segment
		(start 363.490764 -293.849044)
		(end 363.49178 -293.848536)
		(width 0.1143)
		(layer "In6.Cu")
		(net "P5E_CPU0_P2_RX_DN<3>")
	)
	(segment
		(start 402.204174 -380.0221)
		(end 402.341334 -379.88494)
		(width 0.14224)
		(layer "In6.Cu")
		(net "P5E_CPU0_P2_RX_DN<3>")
	)
	(segment
		(start 363.490764 -285.749238)
		(end 363.49178 -285.74873)
		(width 0.1143)
		(layer "In6.Cu")
		(net "P5E_CPU0_P2_RX_DN<3>")
	)
	(segment
		(start 407.372312 -393.787376)
		(end 407.37282 -393.786868)
		(width 0.14224)
		(layer "In6.Cu")
		(net "P5E_CPU0_P2_RX_DN<3>")
	)
	(segment
		(start 364.903766 -283.317442)
		(end 364.933484 -283.300424)
		(width 0.1143)
		(layer "In6.Cu")
		(net "P5E_CPU0_P2_RX_DN<3>")
	)
	(segment
		(start 402.204174 -381.57658)
		(end 402.204174 -381.14986)
		(width 0.14224)
		(layer "In6.Cu")
		(net "P5E_CPU0_P2_RX_DN<3>")
	)
	(segment
		(start 402.341334 -378.75718)
		(end 402.341334 -377.288044)
		(width 0.14224)
		(layer "In6.Cu")
		(net "P5E_CPU0_P2_RX_DN<3>")
	)
	(segment
		(start 363.49178 -291.583364)
		(end 363.490764 -291.582856)
		(width 0.1143)
		(layer "In6.Cu")
		(net "P5E_CPU0_P2_RX_DN<3>")
	)
	(segment
		(start 402.204174 -380.44882)
		(end 402.204174 -380.0221)
		(width 0.14224)
		(layer "In6.Cu")
		(net "P5E_CPU0_P2_RX_DN<3>")
	)
	(segment
		(start 363.52353 -291.601652)
		(end 363.498892 -291.587428)
		(width 0.1143)
		(layer "In6.Cu")
		(net "P5E_CPU0_P2_RX_DN<3>")
	)
	(segment
		(start 363.490764 -291.582856)
		(end 363.48924 -291.58184)
		(width 0.1143)
		(layer "In6.Cu")
		(net "P5E_CPU0_P2_RX_DN<3>")
	)
	(segment
		(start 363.483652 -293.19855)
		(end 363.452664 -293.180516)
		(width 0.1143)
		(layer "In6.Cu")
		(net "P5E_CPU0_P2_RX_DN<3>")
	)
	(segment
		(start 363.483652 -289.958526)
		(end 363.452664 -289.940492)
		(width 0.1143)
		(layer "In6.Cu")
		(net "P5E_CPU0_P2_RX_DN<3>")
	)
	(segment
		(start 363.493812 -294.824658)
		(end 363.492542 -294.823896)
		(width 0.1143)
		(layer "In6.Cu")
		(net "P5E_CPU0_P2_RX_DN<3>")
	)
	(segment
		(start 363.485176 -291.579554)
		(end 363.483652 -291.578538)
		(width 0.1143)
		(layer "In6.Cu")
		(net "P5E_CPU0_P2_RX_DN<3>")
	)
	(segment
		(start 364.104174 -298.517056)
		(end 364.104174 -297.95851)
		(width 0.14224)
		(layer "In6.Cu")
		(net "P5E_CPU0_P2_RX_DN<3>")
	)
	(segment
		(start 402.341334 -380.58598)
		(end 402.204174 -380.44882)
		(width 0.14224)
		(layer "In6.Cu")
		(net "P5E_CPU0_P2_RX_DN<3>")
	)
	(segment
		(start 364.14964 -296.278554)
		(end 364.14964 -295.955974)
		(width 0.1143)
		(layer "In6.Cu")
		(net "P5E_CPU0_P2_RX_DN<3>")
	)
	(segment
		(start 363.49178 -288.343594)
		(end 363.452664 -288.320734)
		(width 0.1143)
		(layer "In6.Cu")
		(net "P5E_CPU0_P2_RX_DN<3>")
	)
	(segment
		(start 396.216886 -373.155464)
		(end 393.339574 -370.278152)
		(width 0.14224)
		(layer "In6.Cu")
		(net "P5E_CPU0_P2_RX_DN<3>")
	)
	(segment
		(start 363.48924 -290.610036)
		(end 363.490764 -290.60902)
		(width 0.1143)
		(layer "In6.Cu")
		(net "P5E_CPU0_P2_RX_DN<3>")
	)
	(segment
		(start 374.493536 -314.116974)
		(end 369.390168 -307.8988)
		(width 0.14224)
		(layer "In6.Cu")
		(net "P5E_CPU0_P2_RX_DN<3>")
	)
	(segment
		(start 402.341334 -379.45822)
		(end 402.204174 -379.32106)
		(width 0.14224)
		(layer "In6.Cu")
		(net "P5E_CPU0_P2_RX_DN<3>")
	)
	(segment
		(start 363.497876 -291.58692)
		(end 363.496352 -291.585904)
		(width 0.1143)
		(layer "In6.Cu")
		(net "P5E_CPU0_P2_RX_DN<3>")
	)
	(segment
		(start 364.902496 -283.318204)
		(end 364.903766 -283.317442)
		(width 0.1143)
		(layer "In6.Cu")
		(net "P5E_CPU0_P2_RX_DN<3>")
	)
	(segment
		(start 402.204174 -381.14986)
		(end 402.341334 -381.0127)
		(width 0.14224)
		(layer "In6.Cu")
		(net "P5E_CPU0_P2_RX_DN<3>")
	)
	(segment
		(start 363.496352 -291.585904)
		(end 363.493812 -291.584634)
		(width 0.1143)
		(layer "In6.Cu")
		(net "P5E_CPU0_P2_RX_DN<3>")
	)
	(segment
		(start 363.48924 -288.990024)
		(end 363.490764 -288.989008)
		(width 0.1143)
		(layer "In6.Cu")
		(net "P5E_CPU0_P2_RX_DN<3>")
	)
	(segment
		(start 363.497876 -293.206932)
		(end 363.496352 -293.205916)
		(width 0.1143)
		(layer "In6.Cu")
		(net "P5E_CPU0_P2_RX_DN<3>")
	)
	(segment
		(start 407.494486 -393.545822)
		(end 407.177494 -393.22883)
		(width 0.14224)
		(layer "In6.Cu")
		(net "P5E_CPU0_P2_RX_DN<3>")
	)
	(segment
		(start 363.490764 -293.202868)
		(end 363.48924 -293.201852)
		(width 0.1143)
		(layer "In6.Cu")
		(net "P5E_CPU0_P2_RX_DN<3>")
	)
	(segment
		(start 363.493812 -288.98723)
		(end 363.52353 -288.970212)
		(width 0.1143)
		(layer "In6.Cu")
		(net "P5E_CPU0_P2_RX_DN<3>")
	)
	(segment
		(start 363.493812 -285.74746)
		(end 363.52353 -285.730442)
		(width 0.1143)
		(layer "In6.Cu")
		(net "P5E_CPU0_P2_RX_DN<3>")
	)
	(segment
		(start 363.52353 -289.98164)
		(end 363.498892 -289.967416)
		(width 0.1143)
		(layer "In6.Cu")
		(net "P5E_CPU0_P2_RX_DN<3>")
	)
	(segment
		(start 363.492542 -293.203884)
		(end 363.49178 -293.203376)
		(width 0.1143)
		(layer "In6.Cu")
		(net "P5E_CPU0_P2_RX_DN<3>")
	)
	(segment
		(start 363.498892 -291.587428)
		(end 363.497876 -291.58692)
		(width 0.1143)
		(layer "In6.Cu")
		(net "P5E_CPU0_P2_RX_DN<3>")
	)
	(segment
		(start 363.48924 -292.230048)
		(end 363.490764 -292.229032)
		(width 0.1143)
		(layer "In6.Cu")
		(net "P5E_CPU0_P2_RX_DN<3>")
	)
	(segment
		(start 363.492542 -289.96386)
		(end 363.49178 -289.963352)
		(width 0.1143)
		(layer "In6.Cu")
		(net "P5E_CPU0_P2_RX_DN<3>")
	)
	(segment
		(start 385.670298 -351.968816)
		(end 383.94767 -343.308432)
		(width 0.14224)
		(layer "In6.Cu")
		(net "P5E_CPU0_P2_RX_DN<3>")
	)
	(segment
		(start 363.992414 -295.651174)
		(end 363.922818 -295.610534)
		(width 0.1143)
		(layer "In6.Cu")
		(net "P5E_CPU0_P2_RX_DN<3>")
	)
	(segment
		(start 363.492542 -294.823896)
		(end 363.49178 -294.823388)
		(width 0.1143)
		(layer "In6.Cu")
		(net "P5E_CPU0_P2_RX_DN<3>")
	)
	(segment
		(start 364.392718 -284.151324)
		(end 364.454948 -284.115256)
		(width 0.1143)
		(layer "In6.Cu")
		(net "P5E_CPU0_P2_RX_DN<3>")
	)
	(segment
		(start 363.496352 -289.965892)
		(end 363.493812 -289.964622)
		(width 0.1143)
		(layer "In6.Cu")
		(net "P5E_CPU0_P2_RX_DN<3>")
	)
	(segment
		(start 407.018998 -393.69238)
		(end 407.372312 -393.787376)
		(width 0.14224)
		(layer "In6.Cu")
		(net "P5E_CPU0_P2_RX_DN<3>")
	)
	(segment
		(start 363.486446 -291.580316)
		(end 363.485176 -291.579554)
		(width 0.1143)
		(layer "In6.Cu")
		(net "P5E_CPU0_P2_RX_DN<3>")
	)
	(segment
		(start 364.104682 -297.95851)
		(end 364.104682 -296.353484)
		(width 0.14224)
		(layer "In6.Cu")
		(net "P5E_CPU0_P2_RX_DN<3>")
	)
	(segment
		(start 365.70666 -302.385984)
		(end 364.104174 -298.517056)
		(width 0.14224)
		(layer "In6.Cu")
		(net "P5E_CPU0_P2_RX_DN<3>")
	)
	(segment
		(start 363.48924 -291.58184)
		(end 363.486446 -291.580316)
		(width 0.1143)
		(layer "In6.Cu")
		(net "P5E_CPU0_P2_RX_DN<3>")
	)
	(segment
		(start 363.48924 -289.961828)
		(end 363.486446 -289.960304)
		(width 0.1143)
		(layer "In6.Cu")
		(net "P5E_CPU0_P2_RX_DN<3>")
	)
	(segment
		(start 363.49178 -286.723582)
		(end 363.452664 -286.700722)
		(width 0.1143)
		(layer "In6.Cu")
		(net "P5E_CPU0_P2_RX_DN<3>")
	)
	(segment
		(start 365.082582 -283.065982)
		(end 365.012732 -282.996132)
		(width 0.1143)
		(layer "In6.Cu")
		(net "P5E_CPU0_P2_RX_DN<3>")
	)
	(segment
		(start 363.498892 -294.827452)
		(end 363.497876 -294.826944)
		(width 0.1143)
		(layer "In6.Cu")
		(net "P5E_CPU0_P2_RX_DN<3>")
	)
	(segment
		(start 363.452664 -289.01136)
		(end 363.48924 -288.990024)
		(width 0.1143)
		(layer "In6.Cu")
		(net "P5E_CPU0_P2_RX_DN<3>")
	)
	(segment
		(start 363.492542 -291.583872)
		(end 363.49178 -291.583364)
		(width 0.1143)
		(layer "In6.Cu")
		(net "P5E_CPU0_P2_RX_DN<3>")
	)
	(segment
		(start 363.486446 -289.960304)
		(end 363.485176 -289.959542)
		(width 0.1143)
		(layer "In6.Cu")
		(net "P5E_CPU0_P2_RX_DN<3>")
	)
	(segment
		(start 363.496352 -293.205916)
		(end 363.493812 -293.204646)
		(width 0.1143)
		(layer "In6.Cu")
		(net "P5E_CPU0_P2_RX_DN<3>")
	)
	(segment
		(start 402.341334 -381.71374)
		(end 402.204174 -381.57658)
		(width 0.14224)
		(layer "In6.Cu")
		(net "P5E_CPU0_P2_RX_DN<3>")
	)
	(segment
		(start 363.493812 -290.607242)
		(end 363.52353 -290.590224)
		(width 0.1143)
		(layer "In6.Cu")
		(net "P5E_CPU0_P2_RX_DN<3>")
	)
	(segment
		(start 363.492542 -293.848028)
		(end 363.493812 -293.847266)
		(width 0.1143)
		(layer "In6.Cu")
		(net "P5E_CPU0_P2_RX_DN<3>")
	)
	(segment
		(start 363.922818 -284.961584)
		(end 363.961934 -284.938724)
		(width 0.1143)
		(layer "In6.Cu")
		(net "P5E_CPU0_P2_RX_DN<3>")
	)
	(segment
		(start 363.452664 -292.251384)
		(end 363.48924 -292.230048)
		(width 0.1143)
		(layer "In6.Cu")
		(net "P5E_CPU0_P2_RX_DN<3>")
	)
	(segment
		(start 393.028678 -369.812824)
		(end 385.760214 -352.265234)
		(width 0.14224)
		(layer "In6.Cu")
		(net "P5E_CPU0_P2_RX_DN<3>")
	)
	(segment
		(start 363.492542 -288.987992)
		(end 363.493812 -288.98723)
		(width 0.1143)
		(layer "In6.Cu")
		(net "P5E_CPU0_P2_RX_DN<3>")
	)
	(segment
		(start 363.452664 -290.631372)
		(end 363.48924 -290.610036)
		(width 0.1143)
		(layer "In6.Cu")
		(net "P5E_CPU0_P2_RX_DN<3>")
	)
	(segment
		(start 363.49178 -293.848536)
		(end 363.492542 -293.848028)
		(width 0.1143)
		(layer "In6.Cu")
		(net "P5E_CPU0_P2_RX_DN<3>")
	)
	(segment
		(start 363.49178 -287.368488)
		(end 363.52353 -287.3502)
		(width 0.1143)
		(layer "In6.Cu")
		(net "P5E_CPU0_P2_RX_DN<3>")
	)
	(segment
		(start 363.48924 -285.750254)
		(end 363.490764 -285.749238)
		(width 0.1143)
		(layer "In6.Cu")
		(net "P5E_CPU0_P2_RX_DN<3>")
	)
	(segment
		(start 364.104174 -297.95851)
		(end 364.104682 -297.95851)
		(width 0.14224)
		(layer "In6.Cu")
		(net "P5E_CPU0_P2_RX_DN<3>")
	)
	(segment
		(start 407.449782 -390.318244)
		(end 402.721826 -383.309876)
		(width 0.14224)
		(layer "In6.Cu")
		(net "P5E_CPU0_P2_RX_DN<3>")
	)
	(segment
		(start 363.493812 -291.584634)
		(end 363.492542 -291.583872)
		(width 0.1143)
		(layer "In6.Cu")
		(net "P5E_CPU0_P2_RX_DN<3>")
	)
	(segment
		(start 363.49178 -292.228524)
		(end 363.492542 -292.228016)
		(width 0.1143)
		(layer "In6.Cu")
		(net "P5E_CPU0_P2_RX_DN<3>")
	)
	(segment
		(start 363.498892 -293.20744)
		(end 363.497876 -293.206932)
		(width 0.1143)
		(layer "In6.Cu")
		(net "P5E_CPU0_P2_RX_DN<3>")
	)
	(segment
		(start 363.498892 -289.967416)
		(end 363.497876 -289.966908)
		(width 0.1143)
		(layer "In6.Cu")
		(net "P5E_CPU0_P2_RX_DN<3>")
	)
	(segment
		(start 363.490764 -292.229032)
		(end 363.49178 -292.228524)
		(width 0.1143)
		(layer "In6.Cu")
		(net "P5E_CPU0_P2_RX_DN<3>")
	)
	(segment
		(start 402.341334 -379.88494)
		(end 402.341334 -379.45822)
		(width 0.14224)
		(layer "In6.Cu")
		(net "P5E_CPU0_P2_RX_DN<3>")
	)
	(segment
		(start 363.486446 -294.82034)
		(end 363.485176 -294.819578)
		(width 0.1143)
		(layer "In6.Cu")
		(net "P5E_CPU0_P2_RX_DN<3>")
	)
	(segment
		(start 363.49178 -293.203376)
		(end 363.490764 -293.202868)
		(width 0.1143)
		(layer "In6.Cu")
		(net "P5E_CPU0_P2_RX_DN<3>")
	)
	(segment
		(start 365.012732 -282.996132)
		(end 364.71479 -282.996132)
		(width 0.1143)
		(layer "In6.Cu")
		(net "P5E_CPU0_P2_RX_DN<3>")
	)
	(segment
		(start 363.490764 -289.962844)
		(end 363.48924 -289.961828)
		(width 0.1143)
		(layer "In6.Cu")
		(net "P5E_CPU0_P2_RX_DN<3>")
	)
	(segment
		(start 369.390168 -307.8988)
		(end 365.70666 -302.385984)
		(width 0.14224)
		(layer "In6.Cu")
		(net "P5E_CPU0_P2_RX_DN<3>")
	)
	(segment
		(start 407.486358 -392.246612)
		(end 407.486358 -390.437878)
		(width 0.14224)
		(layer "In6.Cu")
		(net "P5E_CPU0_P2_RX_DN<3>")
	)
	(segment
		(start 363.452664 -293.871396)
		(end 363.48924 -293.85006)
		(width 0.1143)
		(layer "In6.Cu")
		(net "P5E_CPU0_P2_RX_DN<3>")
	)
	(segment
		(start 407.177494 -393.22883)
		(end 407.181812 -392.683746)
		(width 0.14224)
		(layer "In6.Cu")
		(net "P5E_CPU0_P2_RX_DN<3>")
	)
	(segment
		(start 363.492542 -290.608004)
		(end 363.493812 -290.607242)
		(width 0.1143)
		(layer "In6.Cu")
		(net "P5E_CPU0_P2_RX_DN<3>")
	)
	(segment
		(start 402.204174 -378.89434)
		(end 402.341334 -378.75718)
		(width 0.14224)
		(layer "In6.Cu")
		(net "P5E_CPU0_P2_RX_DN<3>")
	)
	(segment
		(start 363.497876 -294.826944)
		(end 363.496352 -294.825928)
		(width 0.1143)
		(layer "In6.Cu")
		(net "P5E_CPU0_P2_RX_DN<3>")
	)
	(segment
		(start 363.52353 -294.841676)
		(end 363.498892 -294.827452)
		(width 0.1143)
		(layer "In6.Cu")
		(net "P5E_CPU0_P2_RX_DN<3>")
	)
	(segment
		(start 363.493812 -289.964622)
		(end 363.492542 -289.96386)
		(width 0.1143)
		(layer "In6.Cu")
		(net "P5E_CPU0_P2_RX_DN<3>")
	)
	(segment
		(start 363.49178 -285.74873)
		(end 363.492542 -285.748222)
		(width 0.1143)
		(layer "In6.Cu")
		(net "P5E_CPU0_P2_RX_DN<3>")
	)
	(segment
		(start 363.492542 -292.228016)
		(end 363.493812 -292.227254)
		(width 0.1143)
		(layer "In6.Cu")
		(net "P5E_CPU0_P2_RX_DN<3>")
	)
	(segment
		(start 363.490764 -290.60902)
		(end 363.49178 -290.608512)
		(width 0.1143)
		(layer "In6.Cu")
		(net "P5E_CPU0_P2_RX_DN<3>")
	)
	(segment
		(start 363.493812 -292.227254)
		(end 363.52353 -292.210236)
		(width 0.1143)
		(layer "In6.Cu")
		(net "P5E_CPU0_P2_RX_DN<3>")
	)
	(segment
		(start 402.204174 -379.32106)
		(end 402.204174 -378.89434)
		(width 0.14224)
		(layer "In6.Cu")
		(net "P5E_CPU0_P2_RX_DN<3>")
	)
	(segment
		(start 364.150402 -296.279316)
		(end 364.14964 -296.278554)
		(width 0.1143)
		(layer "In6.Cu")
		(net "P5E_CPU0_P2_RX_DN<3>")
	)
	(segment
		(start 407.449782 -390.318498)
		(end 407.449782 -390.318244)
		(width 0.14224)
		(layer "In6.Cu")
		(net "P5E_CPU0_P2_RX_DN<3>")
	)
	(segment
		(start 364.901734 -283.318712)
		(end 364.902496 -283.318204)
		(width 0.1143)
		(layer "In6.Cu")
		(net "P5E_CPU0_P2_RX_DN<3>")
	)
	(segment
		(start 363.49178 -294.823388)
		(end 363.490764 -294.82288)
		(width 0.1143)
		(layer "In6.Cu")
		(net "P5E_CPU0_P2_RX_DN<3>")
	)
	(segment
		(start 364.104682 -296.325036)
		(end 364.150402 -296.279316)
		(width 0.1143)
		(layer "In6.Cu")
		(net "P5E_CPU0_P2_RX_DN<3>")
	)
	(segment
		(start 363.48924 -294.821864)
		(end 363.486446 -294.82034)
		(width 0.1143)
		(layer "In6.Cu")
		(net "P5E_CPU0_P2_RX_DN<3>")
	)
	(segment
		(start 364.104682 -296.353484)
		(end 364.104682 -296.325036)
		(width 0.1143)
		(layer "In6.Cu")
		(net "P5E_CPU0_P2_RX_DN<3>")
	)
	(segment
		(start 363.455204 -287.389824)
		(end 363.49178 -287.368488)
		(width 0.1143)
		(layer "In6.Cu")
		(net "P5E_CPU0_P2_RX_DN<3>")
	)
	(segment
		(start 363.52353 -293.221664)
		(end 363.498892 -293.20744)
		(width 0.1143)
		(layer "In6.Cu")
		(net "P5E_CPU0_P2_RX_DN<3>")
	)
	(segment
		(start 363.493812 -293.204646)
		(end 363.492542 -293.203884)
		(width 0.1143)
		(layer "In6.Cu")
		(net "P5E_CPU0_P2_RX_DN<3>")
	)
	(arc
		(start 364.021878 -295.674542)
		(mid 364.007443 -295.662483)
		(end 363.992414 -295.651174)
		(width 0.1143)
		(layer "In6.Cu")
		(net "P5E_CPU0_P2_RX_DN<3>")
	)
	(arc
		(start 363.209332 -287.856168)
		(mid 363.274568 -287.592577)
		(end 363.455204 -287.389824)
		(width 0.1143)
		(layer "In6.Cu")
		(net "P5E_CPU0_P2_RX_DN<3>")
	)
	(arc
		(start 402.043138 -376.568208)
		(mid 401.848745 -376.396767)
		(end 401.634452 -376.250962)
		(width 0.14224)
		(layer "In6.Cu")
		(net "P5E_CPU0_P2_RX_DN<3>")
	)
	(arc
		(start 363.52353 -293.830248)
		(mid 363.679458 -293.525956)
		(end 363.52353 -293.221664)
		(width 0.1143)
		(layer "In6.Cu")
		(net "P5E_CPU0_P2_RX_DN<3>")
	)
	(arc
		(start 402.341334 -377.288044)
		(mid 402.263841 -376.89846)
		(end 402.043138 -376.568208)
		(width 0.14224)
		(layer "In6.Cu")
		(net "P5E_CPU0_P2_RX_DN<3>")
	)
	(arc
		(start 364.933484 -283.300424)
		(mid 365.030619 -283.197555)
		(end 365.082582 -283.065982)
		(width 0.1143)
		(layer "In6.Cu")
		(net "P5E_CPU0_P2_RX_DN<3>")
	)
	(arc
		(start 407.181812 -392.683746)
		(mid 407.19448 -392.622039)
		(end 407.229564 -392.5697)
		(width 0.14224)
		(layer "In6.Cu")
		(net "P5E_CPU0_P2_RX_DN<3>")
	)
	(arc
		(start 383.94767 -343.308432)
		(mid 383.942503 -343.279077)
		(end 383.93878 -343.249504)
		(width 0.14224)
		(layer "In6.Cu")
		(net "P5E_CPU0_P2_RX_DN<3>")
	)
	(arc
		(start 363.52353 -285.730442)
		(mid 363.638206 -285.597108)
		(end 363.679486 -285.42615)
		(width 0.1143)
		(layer "In6.Cu")
		(net "P5E_CPU0_P2_RX_DN<3>")
	)
	(arc
		(start 402.721826 -383.309876)
		(mid 402.538279 -382.98587)
		(end 402.369274 -382.654048)
		(width 0.14224)
		(layer "In6.Cu")
		(net "P5E_CPU0_P2_RX_DN<3>")
	)
	(arc
		(start 363.452664 -294.800528)
		(mid 363.209337 -294.335962)
		(end 363.452664 -293.871396)
		(width 0.1143)
		(layer "In6.Cu")
		(net "P5E_CPU0_P2_RX_DN<3>")
	)
	(arc
		(start 363.679486 -288.66592)
		(mid 363.638724 -288.496036)
		(end 363.525308 -288.363152)
		(width 0.1143)
		(layer "In6.Cu")
		(net "P5E_CPU0_P2_RX_DN<3>")
	)
	(arc
		(start 364.61954 -283.791152)
		(mid 364.68516 -283.541634)
		(end 364.854744 -283.34716)
		(width 0.1143)
		(layer "In6.Cu")
		(net "P5E_CPU0_P2_RX_DN<3>")
	)
	(arc
		(start 385.760214 -352.265234)
		(mid 385.707971 -352.119235)
		(end 385.670298 -351.968816)
		(width 0.14224)
		(layer "In6.Cu")
		(net "P5E_CPU0_P2_RX_DN<3>")
	)
	(arc
		(start 363.679486 -287.045908)
		(mid 363.638724 -286.876024)
		(end 363.525308 -286.74314)
		(width 0.1143)
		(layer "In6.Cu")
		(net "P5E_CPU0_P2_RX_DN<3>")
	)
	(arc
		(start 363.679486 -295.145968)
		(mid 363.638231 -294.974997)
		(end 363.52353 -294.841676)
		(width 0.1143)
		(layer "In6.Cu")
		(net "P5E_CPU0_P2_RX_DN<3>")
	)
	(arc
		(start 364.617508 -283.815282)
		(mid 364.618817 -283.803242)
		(end 364.61954 -283.791152)
		(width 0.1143)
		(layer "In6.Cu")
		(net "P5E_CPU0_P2_RX_DN<3>")
	)
	(arc
		(start 363.452664 -291.560504)
		(mid 363.209337 -291.095938)
		(end 363.452664 -290.631372)
		(width 0.1143)
		(layer "In6.Cu")
		(net "P5E_CPU0_P2_RX_DN<3>")
	)
	(arc
		(start 407.486358 -390.437878)
		(mid 407.477018 -390.375443)
		(end 407.449782 -390.318498)
		(width 0.14224)
		(layer "In6.Cu")
		(net "P5E_CPU0_P2_RX_DN<3>")
	)
	(arc
		(start 363.452664 -286.700722)
		(mid 363.209337 -286.236156)
		(end 363.452664 -285.77159)
		(width 0.1143)
		(layer "In6.Cu")
		(net "P5E_CPU0_P2_RX_DN<3>")
	)
	(arc
		(start 363.52353 -288.970212)
		(mid 363.638206 -288.836878)
		(end 363.679486 -288.66592)
		(width 0.1143)
		(layer "In6.Cu")
		(net "P5E_CPU0_P2_RX_DN<3>")
	)
	(arc
		(start 363.452664 -293.180516)
		(mid 363.209337 -292.71595)
		(end 363.452664 -292.251384)
		(width 0.1143)
		(layer "In6.Cu")
		(net "P5E_CPU0_P2_RX_DN<3>")
	)
	(arc
		(start 363.52353 -287.3502)
		(mid 363.638206 -287.216866)
		(end 363.679486 -287.045908)
		(width 0.1143)
		(layer "In6.Cu")
		(net "P5E_CPU0_P2_RX_DN<3>")
	)
	(arc
		(start 364.14964 -284.616144)
		(mid 364.214028 -284.353851)
		(end 364.392718 -284.151324)
		(width 0.1143)
		(layer "In6.Cu")
		(net "P5E_CPU0_P2_RX_DN<3>")
	)
	(arc
		(start 364.454948 -284.115256)
		(mid 364.563148 -283.979854)
		(end 364.617508 -283.815282)
		(width 0.1143)
		(layer "In6.Cu")
		(net "P5E_CPU0_P2_RX_DN<3>")
	)
	(arc
		(start 407.444702 -392.354562)
		(mid 407.4756 -392.304464)
		(end 407.486358 -392.246612)
		(width 0.14224)
		(layer "In6.Cu")
		(net "P5E_CPU0_P2_RX_DN<3>")
	)
	(arc
		(start 364.854744 -283.34716)
		(mid 364.860058 -283.343448)
		(end 364.865412 -283.339794)
		(width 0.1143)
		(layer "In6.Cu")
		(net "P5E_CPU0_P2_RX_DN<3>")
	)
	(arc
		(start 396.304516 -373.222266)
		(mid 396.258437 -373.191834)
		(end 396.216886 -373.155464)
		(width 0.14224)
		(layer "In6.Cu")
		(net "P5E_CPU0_P2_RX_DN<3>")
	)
	(arc
		(start 363.452664 -288.320734)
		(mid 363.273851 -288.118384)
		(end 363.209332 -287.856168)
		(width 0.1143)
		(layer "In6.Cu")
		(net "P5E_CPU0_P2_RX_DN<3>")
	)
	(arc
		(start 363.452664 -289.940492)
		(mid 363.209337 -289.475926)
		(end 363.452664 -289.01136)
		(width 0.1143)
		(layer "In6.Cu")
		(net "P5E_CPU0_P2_RX_DN<3>")
	)
	(arc
		(start 402.369274 -382.654048)
		(mid 402.348354 -382.593899)
		(end 402.341334 -382.530604)
		(width 0.14224)
		(layer "In6.Cu")
		(net "P5E_CPU0_P2_RX_DN<3>")
	)
	(arc
		(start 363.922818 -295.610534)
		(mid 363.744005 -295.408184)
		(end 363.679486 -295.145968)
		(width 0.1143)
		(layer "In6.Cu")
		(net "P5E_CPU0_P2_RX_DN<3>")
	)
	(arc
		(start 363.52353 -292.210236)
		(mid 363.679458 -291.905944)
		(end 363.52353 -291.601652)
		(width 0.1143)
		(layer "In6.Cu")
		(net "P5E_CPU0_P2_RX_DN<3>")
	)
	(arc
		(start 363.679486 -285.42615)
		(mid 363.744001 -285.163931)
		(end 363.922818 -284.961584)
		(width 0.1143)
		(layer "In6.Cu")
		(net "P5E_CPU0_P2_RX_DN<3>")
	)
	(arc
		(start 363.52353 -290.590224)
		(mid 363.679458 -290.285932)
		(end 363.52353 -289.98164)
		(width 0.1143)
		(layer "In6.Cu")
		(net "P5E_CPU0_P2_RX_DN<3>")
	)
	(arc
		(start 393.339574 -370.278152)
		(mid 393.1612 -370.060804)
		(end 393.028678 -369.812824)
		(width 0.14224)
		(layer "In6.Cu")
		(net "P5E_CPU0_P2_RX_DN<3>")
	)
	(arc
		(start 363.992414 -284.920944)
		(mid 364.107933 -284.787587)
		(end 364.14964 -284.616144)
		(width 0.1143)
		(layer "In6.Cu")
		(net "P5E_CPU0_P2_RX_DN<3>")
	)
	(arc
		(start 364.14964 -295.955974)
		(mid 364.116154 -295.80146)
		(end 364.021878 -295.674542)
		(width 0.1143)
		(layer "In6.Cu")
		(net "P5E_CPU0_P2_RX_DN<3>")
	)
	(segment
		(start 361.89793 -285.160212)
		(end 362.364782 -285.42615)
		(width 0.12954)
		(layer "F.Cu")
		(net "P5E_CPU0_P2_RX_DN<2>")
	)
	(segment
		(start 405.298402 -393.69238)
		(end 405.819102 -393.69238)
		(width 0.127)
		(layer "F.Cu")
		(net "P5E_CPU0_P2_RX_DN<2>")
	)
	(segment
		(start 362.552488 -285.748222)
		(end 362.553758 -285.74746)
		(width 0.1143)
		(layer "In6.Cu")
		(net "P5E_CPU0_P2_RX_DN<2>")
	)
	(segment
		(start 402.439378 -384.989324)
		(end 402.48586 -384.80111)
		(width 0.14224)
		(layer "In6.Cu")
		(net "P5E_CPU0_P2_RX_DN<2>")
	)
	(segment
		(start 362.556298 -293.205916)
		(end 362.553758 -293.204646)
		(width 0.1143)
		(layer "In6.Cu")
		(net "P5E_CPU0_P2_RX_DN<2>")
	)
	(segment
		(start 375.424954 -317.199518)
		(end 373.756428 -314.70219)
		(width 0.14224)
		(layer "In6.Cu")
		(net "P5E_CPU0_P2_RX_DN<2>")
	)
	(segment
		(start 406.294336 -393.545822)
		(end 405.977344 -393.22883)
		(width 0.14224)
		(layer "In6.Cu")
		(net "P5E_CPU0_P2_RX_DN<2>")
	)
	(segment
		(start 362.557822 -293.206932)
		(end 362.556298 -293.205916)
		(width 0.1143)
		(layer "In6.Cu")
		(net "P5E_CPU0_P2_RX_DN<2>")
	)
	(segment
		(start 398.9451 -378.247402)
		(end 398.812004 -378.114306)
		(width 0.14224)
		(layer "In6.Cu")
		(net "P5E_CPU0_P2_RX_DN<2>")
	)
	(segment
		(start 363.046518 -295.655238)
		(end 362.979716 -295.608502)
		(width 0.1143)
		(layer "In6.Cu")
		(net "P5E_CPU0_P2_RX_DN<2>")
	)
	(segment
		(start 405.819102 -393.69238)
		(end 406.172162 -393.787376)
		(width 0.14224)
		(layer "In6.Cu")
		(net "P5E_CPU0_P2_RX_DN<2>")
	)
	(segment
		(start 401.08378 -382.149604)
		(end 400.985228 -381.73406)
		(width 0.14224)
		(layer "In6.Cu")
		(net "P5E_CPU0_P2_RX_DN<2>")
	)
	(segment
		(start 362.553758 -294.824658)
		(end 362.552488 -294.823896)
		(width 0.1143)
		(layer "In6.Cu")
		(net "P5E_CPU0_P2_RX_DN<2>")
	)
	(segment
		(start 362.518198 -287.388046)
		(end 362.551726 -287.368488)
		(width 0.1143)
		(layer "In6.Cu")
		(net "P5E_CPU0_P2_RX_DN<2>")
	)
	(segment
		(start 403.022054 -385.955032)
		(end 403.06879 -385.766818)
		(width 0.14224)
		(layer "In6.Cu")
		(net "P5E_CPU0_P2_RX_DN<2>")
	)
	(segment
		(start 400.649694 -379.724666)
		(end 400.631406 -379.605794)
		(width 0.14224)
		(layer "In6.Cu")
		(net "P5E_CPU0_P2_RX_DN<2>")
	)
	(segment
		(start 400.64944 -379.724666)
		(end 400.649694 -379.724666)
		(width 0.14224)
		(layer "In6.Cu")
		(net "P5E_CPU0_P2_RX_DN<2>")
	)
	(segment
		(start 362.552488 -293.203884)
		(end 362.551726 -293.203376)
		(width 0.1143)
		(layer "In6.Cu")
		(net "P5E_CPU0_P2_RX_DN<2>")
	)
	(segment
		(start 373.756428 -314.70219)
		(end 368.688366 -308.526942)
		(width 0.14224)
		(layer "In6.Cu")
		(net "P5E_CPU0_P2_RX_DN<2>")
	)
	(segment
		(start 362.553758 -285.74746)
		(end 362.583476 -285.730442)
		(width 0.1143)
		(layer "In6.Cu")
		(net "P5E_CPU0_P2_RX_DN<2>")
	)
	(segment
		(start 363.163358 -296.325036)
		(end 363.209078 -296.279316)
		(width 0.1143)
		(layer "In6.Cu")
		(net "P5E_CPU0_P2_RX_DN<2>")
	)
	(segment
		(start 398.68221 -377.026424)
		(end 398.681956 -377.026424)
		(width 0.14224)
		(layer "In6.Cu")
		(net "P5E_CPU0_P2_RX_DN<2>")
	)
	(segment
		(start 363.163358 -296.353484)
		(end 363.163358 -296.325036)
		(width 0.1143)
		(layer "In6.Cu")
		(net "P5E_CPU0_P2_RX_DN<2>")
	)
	(segment
		(start 362.556298 -289.965892)
		(end 362.553758 -289.964622)
		(width 0.1143)
		(layer "In6.Cu")
		(net "P5E_CPU0_P2_RX_DN<2>")
	)
	(segment
		(start 382.402842 -337.30184)
		(end 380.170436 -326.077326)
		(width 0.14224)
		(layer "In6.Cu")
		(net "P5E_CPU0_P2_RX_DN<2>")
	)
	(segment
		(start 362.552488 -290.608004)
		(end 362.553758 -290.607242)
		(width 0.1143)
		(layer "In6.Cu")
		(net "P5E_CPU0_P2_RX_DN<2>")
	)
	(segment
		(start 362.51007 -290.632388)
		(end 362.551726 -290.608512)
		(width 0.1143)
		(layer "In6.Cu")
		(net "P5E_CPU0_P2_RX_DN<2>")
	)
	(segment
		(start 362.558838 -293.20744)
		(end 362.557822 -293.206932)
		(width 0.1143)
		(layer "In6.Cu")
		(net "P5E_CPU0_P2_RX_DN<2>")
	)
	(segment
		(start 392.189208 -370.352574)
		(end 384.848862 -352.631248)
		(width 0.14224)
		(layer "In6.Cu")
		(net "P5E_CPU0_P2_RX_DN<2>")
	)
	(segment
		(start 362.549186 -291.581586)
		(end 362.51007 -291.559488)
		(width 0.1143)
		(layer "In6.Cu")
		(net "P5E_CPU0_P2_RX_DN<2>")
	)
	(segment
		(start 362.585254 -286.74314)
		(end 362.551726 -286.723582)
		(width 0.1143)
		(layer "In6.Cu")
		(net "P5E_CPU0_P2_RX_DN<2>")
	)
	(segment
		(start 362.552488 -293.848028)
		(end 362.553758 -293.847266)
		(width 0.1143)
		(layer "In6.Cu")
		(net "P5E_CPU0_P2_RX_DN<2>")
	)
	(segment
		(start 401.249134 -382.251458)
		(end 401.08378 -382.149604)
		(width 0.14224)
		(layer "In6.Cu")
		(net "P5E_CPU0_P2_RX_DN<2>")
	)
	(segment
		(start 362.497878 -290.64204)
		(end 362.51007 -290.632388)
		(width 0.1143)
		(layer "In6.Cu")
		(net "P5E_CPU0_P2_RX_DN<2>")
	)
	(segment
		(start 401.347432 -382.666494)
		(end 401.249134 -382.251458)
		(width 0.14224)
		(layer "In6.Cu")
		(net "P5E_CPU0_P2_RX_DN<2>")
	)
	(segment
		(start 362.557822 -291.58692)
		(end 362.556298 -291.585904)
		(width 0.1143)
		(layer "In6.Cu")
		(net "P5E_CPU0_P2_RX_DN<2>")
	)
	(segment
		(start 362.552488 -292.228016)
		(end 362.553758 -292.227254)
		(width 0.1143)
		(layer "In6.Cu")
		(net "P5E_CPU0_P2_RX_DN<2>")
	)
	(segment
		(start 362.551726 -291.583364)
		(end 362.549186 -291.581586)
		(width 0.1143)
		(layer "In6.Cu")
		(net "P5E_CPU0_P2_RX_DN<2>")
	)
	(segment
		(start 362.583476 -291.601652)
		(end 362.558838 -291.587428)
		(width 0.1143)
		(layer "In6.Cu")
		(net "P5E_CPU0_P2_RX_DN<2>")
	)
	(segment
		(start 362.51261 -292.251384)
		(end 362.549186 -292.230048)
		(width 0.1143)
		(layer "In6.Cu")
		(net "P5E_CPU0_P2_RX_DN<2>")
	)
	(segment
		(start 362.551726 -286.723582)
		(end 362.515404 -286.7025)
		(width 0.1143)
		(layer "In6.Cu")
		(net "P5E_CPU0_P2_RX_DN<2>")
	)
	(segment
		(start 398.68221 -377.800616)
		(end 398.68221 -377.026424)
		(width 0.14224)
		(layer "In6.Cu")
		(net "P5E_CPU0_P2_RX_DN<2>")
	)
	(segment
		(start 363.209078 -296.279316)
		(end 363.209078 -295.927018)
		(width 0.1143)
		(layer "In6.Cu")
		(net "P5E_CPU0_P2_RX_DN<2>")
	)
	(segment
		(start 362.553758 -293.204646)
		(end 362.552488 -293.203884)
		(width 0.1143)
		(layer "In6.Cu")
		(net "P5E_CPU0_P2_RX_DN<2>")
	)
	(segment
		(start 400.54784 -379.382274)
		(end 400.133566 -378.968)
		(width 0.14224)
		(layer "In6.Cu")
		(net "P5E_CPU0_P2_RX_DN<2>")
	)
	(segment
		(start 402.848318 -385.401566)
		(end 402.65985 -385.355084)
		(width 0.14224)
		(layer "In6.Cu")
		(net "P5E_CPU0_P2_RX_DN<2>")
	)
	(segment
		(start 405.977344 -393.22883)
		(end 405.98217 -392.616944)
		(width 0.14224)
		(layer "In6.Cu")
		(net "P5E_CPU0_P2_RX_DN<2>")
	)
	(segment
		(start 362.553758 -292.227254)
		(end 362.583476 -292.210236)
		(width 0.1143)
		(layer "In6.Cu")
		(net "P5E_CPU0_P2_RX_DN<2>")
	)
	(segment
		(start 384.825494 -352.554286)
		(end 383.006346 -343.408)
		(width 0.14224)
		(layer "In6.Cu")
		(net "P5E_CPU0_P2_RX_DN<2>")
	)
	(segment
		(start 406.17267 -393.786868)
		(end 406.294336 -393.716764)
		(width 0.14224)
		(layer "In6.Cu")
		(net "P5E_CPU0_P2_RX_DN<2>")
	)
	(segment
		(start 383.000504 -343.368376)
		(end 382.402842 -337.30184)
		(width 0.14224)
		(layer "In6.Cu")
		(net "P5E_CPU0_P2_RX_DN<2>")
	)
	(segment
		(start 362.552488 -291.583872)
		(end 362.551726 -291.583364)
		(width 0.1143)
		(layer "In6.Cu")
		(net "P5E_CPU0_P2_RX_DN<2>")
	)
	(segment
		(start 400.631406 -379.605794)
		(end 400.631406 -379.58395)
		(width 0.14224)
		(layer "In6.Cu")
		(net "P5E_CPU0_P2_RX_DN<2>")
	)
	(segment
		(start 362.556298 -291.585904)
		(end 362.553758 -291.584634)
		(width 0.1143)
		(layer "In6.Cu")
		(net "P5E_CPU0_P2_RX_DN<2>")
	)
	(segment
		(start 402.48586 -384.80111)
		(end 401.829524 -383.713228)
		(width 0.14224)
		(layer "In6.Cu")
		(net "P5E_CPU0_P2_RX_DN<2>")
	)
	(segment
		(start 362.552488 -289.96386)
		(end 362.551726 -289.963352)
		(width 0.1143)
		(layer "In6.Cu")
		(net "P5E_CPU0_P2_RX_DN<2>")
	)
	(segment
		(start 363.163358 -298.682156)
		(end 363.163358 -296.353484)
		(width 0.14224)
		(layer "In6.Cu")
		(net "P5E_CPU0_P2_RX_DN<2>")
	)
	(segment
		(start 362.551726 -287.368488)
		(end 362.583476 -287.3502)
		(width 0.1143)
		(layer "In6.Cu")
		(net "P5E_CPU0_P2_RX_DN<2>")
	)
	(segment
		(start 362.552488 -288.987992)
		(end 362.574078 -288.975546)
		(width 0.1143)
		(layer "In6.Cu")
		(net "P5E_CPU0_P2_RX_DN<2>")
	)
	(segment
		(start 403.242526 -386.320792)
		(end 403.022054 -385.955032)
		(width 0.14224)
		(layer "In6.Cu")
		(net "P5E_CPU0_P2_RX_DN<2>")
	)
	(segment
		(start 362.551726 -285.74873)
		(end 362.552488 -285.748222)
		(width 0.1143)
		(layer "In6.Cu")
		(net "P5E_CPU0_P2_RX_DN<2>")
	)
	(segment
		(start 403.06879 -385.766818)
		(end 402.848318 -385.401566)
		(width 0.14224)
		(layer "In6.Cu")
		(net "P5E_CPU0_P2_RX_DN<2>")
	)
	(segment
		(start 403.651466 -386.732526)
		(end 403.431248 -386.367274)
		(width 0.14224)
		(layer "In6.Cu")
		(net "P5E_CPU0_P2_RX_DN<2>")
	)
	(segment
		(start 362.551726 -292.228524)
		(end 362.552488 -292.228016)
		(width 0.1143)
		(layer "In6.Cu")
		(net "P5E_CPU0_P2_RX_DN<2>")
	)
	(segment
		(start 362.55071 -292.229032)
		(end 362.551726 -292.228524)
		(width 0.1143)
		(layer "In6.Cu")
		(net "P5E_CPU0_P2_RX_DN<2>")
	)
	(segment
		(start 400.985228 -381.73406)
		(end 401.087082 -381.56896)
		(width 0.14224)
		(layer "In6.Cu")
		(net "P5E_CPU0_P2_RX_DN<2>")
	)
	(segment
		(start 362.552488 -294.823896)
		(end 362.551726 -294.823388)
		(width 0.1143)
		(layer "In6.Cu")
		(net "P5E_CPU0_P2_RX_DN<2>")
	)
	(segment
		(start 362.553758 -290.607242)
		(end 362.583476 -290.590224)
		(width 0.1143)
		(layer "In6.Cu")
		(net "P5E_CPU0_P2_RX_DN<2>")
	)
	(segment
		(start 362.556298 -294.825928)
		(end 362.553758 -294.824658)
		(width 0.1143)
		(layer "In6.Cu")
		(net "P5E_CPU0_P2_RX_DN<2>")
	)
	(segment
		(start 362.662724 -285.42615)
		(end 362.364782 -285.42615)
		(width 0.1143)
		(layer "In6.Cu")
		(net "P5E_CPU0_P2_RX_DN<2>")
	)
	(segment
		(start 401.829524 -383.713228)
		(end 401.46224 -382.981962)
		(width 0.14224)
		(layer "In6.Cu")
		(net "P5E_CPU0_P2_RX_DN<2>")
	)
	(segment
		(start 362.551726 -293.203376)
		(end 362.55071 -293.202868)
		(width 0.1143)
		(layer "In6.Cu")
		(net "P5E_CPU0_P2_RX_DN<2>")
	)
	(segment
		(start 362.553758 -291.584634)
		(end 362.552488 -291.583872)
		(width 0.1143)
		(layer "In6.Cu")
		(net "P5E_CPU0_P2_RX_DN<2>")
	)
	(segment
		(start 362.551726 -288.9885)
		(end 362.552488 -288.987992)
		(width 0.1143)
		(layer "In6.Cu")
		(net "P5E_CPU0_P2_RX_DN<2>")
	)
	(segment
		(start 362.551726 -293.848536)
		(end 362.552488 -293.848028)
		(width 0.1143)
		(layer "In6.Cu")
		(net "P5E_CPU0_P2_RX_DN<2>")
	)
	(segment
		(start 403.431248 -386.367274)
		(end 403.242526 -386.320792)
		(width 0.14224)
		(layer "In6.Cu")
		(net "P5E_CPU0_P2_RX_DN<2>")
	)
	(segment
		(start 362.583476 -293.221664)
		(end 362.558838 -293.20744)
		(width 0.1143)
		(layer "In6.Cu")
		(net "P5E_CPU0_P2_RX_DN<2>")
	)
	(segment
		(start 380.170436 -326.077326)
		(end 375.424954 -317.199518)
		(width 0.14224)
		(layer "In6.Cu")
		(net "P5E_CPU0_P2_RX_DN<2>")
	)
	(segment
		(start 406.294336 -393.716764)
		(end 406.294336 -393.545822)
		(width 0.14224)
		(layer "In6.Cu")
		(net "P5E_CPU0_P2_RX_DN<2>")
	)
	(segment
		(start 362.557822 -289.966908)
		(end 362.556298 -289.965892)
		(width 0.1143)
		(layer "In6.Cu")
		(net "P5E_CPU0_P2_RX_DN<2>")
	)
	(segment
		(start 401.087082 -381.56896)
		(end 400.64944 -379.724666)
		(width 0.14224)
		(layer "In6.Cu")
		(net "P5E_CPU0_P2_RX_DN<2>")
	)
	(segment
		(start 362.732574 -285.496)
		(end 362.662724 -285.42615)
		(width 0.1143)
		(layer "In6.Cu")
		(net "P5E_CPU0_P2_RX_DN<2>")
	)
	(segment
		(start 364.880652 -302.828452)
		(end 363.163358 -298.682156)
		(width 0.14224)
		(layer "In6.Cu")
		(net "P5E_CPU0_P2_RX_DN<2>")
	)
	(segment
		(start 406.286208 -392.312906)
		(end 406.286208 -390.459468)
		(width 0.14224)
		(layer "In6.Cu")
		(net "P5E_CPU0_P2_RX_DN<2>")
	)
	(segment
		(start 402.65985 -385.355084)
		(end 402.439378 -384.989324)
		(width 0.14224)
		(layer "In6.Cu")
		(net "P5E_CPU0_P2_RX_DN<2>")
	)
	(segment
		(start 362.515404 -285.769812)
		(end 362.551726 -285.74873)
		(width 0.1143)
		(layer "In6.Cu")
		(net "P5E_CPU0_P2_RX_DN<2>")
	)
	(segment
		(start 362.553758 -293.847266)
		(end 362.583476 -293.830248)
		(width 0.1143)
		(layer "In6.Cu")
		(net "P5E_CPU0_P2_RX_DN<2>")
	)
	(segment
		(start 368.688366 -308.526942)
		(end 364.880652 -302.828452)
		(width 0.14224)
		(layer "In6.Cu")
		(net "P5E_CPU0_P2_RX_DN<2>")
	)
	(segment
		(start 362.549186 -292.230048)
		(end 362.55071 -292.229032)
		(width 0.1143)
		(layer "In6.Cu")
		(net "P5E_CPU0_P2_RX_DN<2>")
	)
	(segment
		(start 406.262586 -390.385554)
		(end 403.651466 -386.732526)
		(width 0.14224)
		(layer "In6.Cu")
		(net "P5E_CPU0_P2_RX_DN<2>")
	)
	(segment
		(start 362.551726 -289.963352)
		(end 362.54944 -289.962082)
		(width 0.1143)
		(layer "In6.Cu")
		(net "P5E_CPU0_P2_RX_DN<2>")
	)
	(segment
		(start 405.98217 -392.616944)
		(end 406.286208 -392.312906)
		(width 0.14224)
		(layer "In6.Cu")
		(net "P5E_CPU0_P2_RX_DN<2>")
	)
	(segment
		(start 398.634966 -376.912378)
		(end 392.419078 -370.69649)
		(width 0.14224)
		(layer "In6.Cu")
		(net "P5E_CPU0_P2_RX_DN<2>")
	)
	(segment
		(start 362.51007 -291.559488)
		(end 362.497878 -291.549836)
		(width 0.1143)
		(layer "In6.Cu")
		(net "P5E_CPU0_P2_RX_DN<2>")
	)
	(segment
		(start 362.558838 -291.587428)
		(end 362.557822 -291.58692)
		(width 0.1143)
		(layer "In6.Cu")
		(net "P5E_CPU0_P2_RX_DN<2>")
	)
	(segment
		(start 362.54944 -293.849806)
		(end 362.551726 -293.848536)
		(width 0.1143)
		(layer "In6.Cu")
		(net "P5E_CPU0_P2_RX_DN<2>")
	)
	(segment
		(start 362.558838 -294.827452)
		(end 362.557822 -294.826944)
		(width 0.1143)
		(layer "In6.Cu")
		(net "P5E_CPU0_P2_RX_DN<2>")
	)
	(segment
		(start 363.209078 -295.927018)
		(end 363.149896 -295.78427)
		(width 0.1143)
		(layer "In6.Cu")
		(net "P5E_CPU0_P2_RX_DN<2>")
	)
	(segment
		(start 362.551726 -294.823388)
		(end 362.54944 -294.822118)
		(width 0.1143)
		(layer "In6.Cu")
		(net "P5E_CPU0_P2_RX_DN<2>")
	)
	(segment
		(start 362.54944 -288.98977)
		(end 362.551726 -288.9885)
		(width 0.1143)
		(layer "In6.Cu")
		(net "P5E_CPU0_P2_RX_DN<2>")
	)
	(segment
		(start 362.583476 -294.841676)
		(end 362.558838 -294.827452)
		(width 0.1143)
		(layer "In6.Cu")
		(net "P5E_CPU0_P2_RX_DN<2>")
	)
	(segment
		(start 406.172162 -393.787376)
		(end 406.17267 -393.786868)
		(width 0.14224)
		(layer "In6.Cu")
		(net "P5E_CPU0_P2_RX_DN<2>")
	)
	(segment
		(start 362.549186 -293.201852)
		(end 362.54817 -293.201344)
		(width 0.1143)
		(layer "In6.Cu")
		(net "P5E_CPU0_P2_RX_DN<2>")
	)
	(segment
		(start 362.55071 -293.202868)
		(end 362.549186 -293.201852)
		(width 0.1143)
		(layer "In6.Cu")
		(net "P5E_CPU0_P2_RX_DN<2>")
	)
	(segment
		(start 362.558838 -289.967416)
		(end 362.557822 -289.966908)
		(width 0.1143)
		(layer "In6.Cu")
		(net "P5E_CPU0_P2_RX_DN<2>")
	)
	(segment
		(start 362.583476 -289.98164)
		(end 362.558838 -289.967416)
		(width 0.1143)
		(layer "In6.Cu")
		(net "P5E_CPU0_P2_RX_DN<2>")
	)
	(segment
		(start 362.54817 -293.201344)
		(end 362.51261 -293.180516)
		(width 0.1143)
		(layer "In6.Cu")
		(net "P5E_CPU0_P2_RX_DN<2>")
	)
	(segment
		(start 362.551726 -290.608512)
		(end 362.552488 -290.608004)
		(width 0.1143)
		(layer "In6.Cu")
		(net "P5E_CPU0_P2_RX_DN<2>")
	)
	(segment
		(start 362.553758 -289.964622)
		(end 362.552488 -289.96386)
		(width 0.1143)
		(layer "In6.Cu")
		(net "P5E_CPU0_P2_RX_DN<2>")
	)
	(segment
		(start 362.574078 -288.356294)
		(end 362.510578 -288.31921)
		(width 0.1143)
		(layer "In6.Cu")
		(net "P5E_CPU0_P2_RX_DN<2>")
	)
	(segment
		(start 362.557822 -294.826944)
		(end 362.556298 -294.825928)
		(width 0.1143)
		(layer "In6.Cu")
		(net "P5E_CPU0_P2_RX_DN<2>")
	)
	(arc
		(start 384.848354 -352.630232)
		(mid 384.835091 -352.592811)
		(end 384.825494 -352.554286)
		(width 0.14224)
		(layer "In6.Cu")
		(net "P5E_CPU0_P2_RX_DN<2>")
	)
	(arc
		(start 362.50118 -287.39973)
		(mid 362.509637 -287.393812)
		(end 362.518198 -287.388046)
		(width 0.1143)
		(layer "In6.Cu")
		(net "P5E_CPU0_P2_RX_DN<2>")
	)
	(arc
		(start 362.269532 -286.236156)
		(mid 362.269522 -286.232854)
		(end 362.269532 -286.229552)
		(width 0.1143)
		(layer "In6.Cu")
		(net "P5E_CPU0_P2_RX_DN<2>")
	)
	(arc
		(start 392.419078 -370.69649)
		(mid 392.287202 -370.535855)
		(end 392.189208 -370.352574)
		(width 0.14224)
		(layer "In6.Cu")
		(net "P5E_CPU0_P2_RX_DN<2>")
	)
	(arc
		(start 362.583476 -287.3502)
		(mid 362.698152 -287.216866)
		(end 362.739432 -287.045908)
		(width 0.1143)
		(layer "In6.Cu")
		(net "P5E_CPU0_P2_RX_DN<2>")
	)
	(arc
		(start 362.583476 -292.210236)
		(mid 362.739404 -291.905944)
		(end 362.583476 -291.601652)
		(width 0.1143)
		(layer "In6.Cu")
		(net "P5E_CPU0_P2_RX_DN<2>")
	)
	(arc
		(start 362.515404 -286.7025)
		(mid 362.334752 -286.499755)
		(end 362.269532 -286.236156)
		(width 0.1143)
		(layer "In6.Cu")
		(net "P5E_CPU0_P2_RX_DN<2>")
	)
	(arc
		(start 363.149896 -295.78427)
		(mid 363.10739 -295.712399)
		(end 363.046518 -295.655238)
		(width 0.1143)
		(layer "In6.Cu")
		(net "P5E_CPU0_P2_RX_DN<2>")
	)
	(arc
		(start 362.51261 -293.180516)
		(mid 362.269283 -292.71595)
		(end 362.51261 -292.251384)
		(width 0.1143)
		(layer "In6.Cu")
		(net "P5E_CPU0_P2_RX_DN<2>")
	)
	(arc
		(start 362.574078 -288.975546)
		(mid 362.741457 -288.66592)
		(end 362.574078 -288.356294)
		(width 0.1143)
		(layer "In6.Cu")
		(net "P5E_CPU0_P2_RX_DN<2>")
	)
	(arc
		(start 362.583476 -290.590224)
		(mid 362.739404 -290.285932)
		(end 362.583476 -289.98164)
		(width 0.1143)
		(layer "In6.Cu")
		(net "P5E_CPU0_P2_RX_DN<2>")
	)
	(arc
		(start 362.269532 -287.85185)
		(mid 362.333509 -287.59922)
		(end 362.50118 -287.39973)
		(width 0.1143)
		(layer "In6.Cu")
		(net "P5E_CPU0_P2_RX_DN<2>")
	)
	(arc
		(start 383.006346 -343.408)
		(mid 383.002935 -343.38826)
		(end 383.000504 -343.368376)
		(width 0.14224)
		(layer "In6.Cu")
		(net "P5E_CPU0_P2_RX_DN<2>")
	)
	(arc
		(start 384.848862 -352.631248)
		(mid 384.848608 -352.63074)
		(end 384.848354 -352.630232)
		(width 0.14224)
		(layer "In6.Cu")
		(net "P5E_CPU0_P2_RX_DN<2>")
	)
	(arc
		(start 362.499148 -285.781242)
		(mid 362.507226 -285.775456)
		(end 362.515404 -285.769812)
		(width 0.1143)
		(layer "In6.Cu")
		(net "P5E_CPU0_P2_RX_DN<2>")
	)
	(arc
		(start 398.681956 -377.026424)
		(mid 398.669781 -376.964744)
		(end 398.634966 -376.912378)
		(width 0.14224)
		(layer "In6.Cu")
		(net "P5E_CPU0_P2_RX_DN<2>")
	)
	(arc
		(start 401.46224 -382.981962)
		(mid 401.39566 -382.827568)
		(end 401.347432 -382.666494)
		(width 0.14224)
		(layer "In6.Cu")
		(net "P5E_CPU0_P2_RX_DN<2>")
	)
	(arc
		(start 400.631406 -379.58395)
		(mid 400.609693 -379.474793)
		(end 400.54784 -379.382274)
		(width 0.14224)
		(layer "In6.Cu")
		(net "P5E_CPU0_P2_RX_DN<2>")
	)
	(arc
		(start 362.979716 -295.608502)
		(mid 362.803112 -295.406571)
		(end 362.739432 -295.145968)
		(width 0.1143)
		(layer "In6.Cu")
		(net "P5E_CPU0_P2_RX_DN<2>")
	)
	(arc
		(start 362.583476 -293.830248)
		(mid 362.739404 -293.525956)
		(end 362.583476 -293.221664)
		(width 0.1143)
		(layer "In6.Cu")
		(net "P5E_CPU0_P2_RX_DN<2>")
	)
	(arc
		(start 399.654268 -378.67717)
		(mid 399.27374 -378.505098)
		(end 398.9451 -378.247402)
		(width 0.14224)
		(layer "In6.Cu")
		(net "P5E_CPU0_P2_RX_DN<2>")
	)
	(arc
		(start 362.54944 -294.822118)
		(mid 362.269512 -294.335962)
		(end 362.54944 -293.849806)
		(width 0.1143)
		(layer "In6.Cu")
		(net "P5E_CPU0_P2_RX_DN<2>")
	)
	(arc
		(start 362.269532 -286.229552)
		(mid 362.334404 -285.97981)
		(end 362.499148 -285.781242)
		(width 0.1143)
		(layer "In6.Cu")
		(net "P5E_CPU0_P2_RX_DN<2>")
	)
	(arc
		(start 400.133566 -378.968)
		(mid 399.911458 -378.793683)
		(end 399.654268 -378.67717)
		(width 0.14224)
		(layer "In6.Cu")
		(net "P5E_CPU0_P2_RX_DN<2>")
	)
	(arc
		(start 362.739432 -295.145968)
		(mid 362.698177 -294.974997)
		(end 362.583476 -294.841676)
		(width 0.1143)
		(layer "In6.Cu")
		(net "P5E_CPU0_P2_RX_DN<2>")
	)
	(arc
		(start 362.269532 -287.856168)
		(mid 362.269528 -287.854009)
		(end 362.269532 -287.85185)
		(width 0.1143)
		(layer "In6.Cu")
		(net "P5E_CPU0_P2_RX_DN<2>")
	)
	(arc
		(start 362.583476 -285.730442)
		(mid 362.680611 -285.627573)
		(end 362.732574 -285.496)
		(width 0.1143)
		(layer "In6.Cu")
		(net "P5E_CPU0_P2_RX_DN<2>")
	)
	(arc
		(start 362.739432 -287.045908)
		(mid 362.69867 -286.876024)
		(end 362.585254 -286.74314)
		(width 0.1143)
		(layer "In6.Cu")
		(net "P5E_CPU0_P2_RX_DN<2>")
	)
	(arc
		(start 362.510578 -288.31921)
		(mid 362.333382 -288.117198)
		(end 362.269532 -287.856168)
		(width 0.1143)
		(layer "In6.Cu")
		(net "P5E_CPU0_P2_RX_DN<2>")
	)
	(arc
		(start 398.812004 -378.114306)
		(mid 398.715868 -377.970383)
		(end 398.68221 -377.800616)
		(width 0.14224)
		(layer "In6.Cu")
		(net "P5E_CPU0_P2_RX_DN<2>")
	)
	(arc
		(start 406.286208 -390.459468)
		(mid 406.280141 -390.420682)
		(end 406.262586 -390.385554)
		(width 0.14224)
		(layer "In6.Cu")
		(net "P5E_CPU0_P2_RX_DN<2>")
	)
	(arc
		(start 362.497878 -291.549836)
		(mid 362.26678 -291.095938)
		(end 362.497878 -290.64204)
		(width 0.1143)
		(layer "In6.Cu")
		(net "P5E_CPU0_P2_RX_DN<2>")
	)
	(arc
		(start 362.54944 -289.962082)
		(mid 362.269512 -289.475926)
		(end 362.54944 -288.98977)
		(width 0.1143)
		(layer "In6.Cu")
		(net "P5E_CPU0_P2_RX_DN<2>")
	)
	(segment
		(start 361.89793 -283.5402)
		(end 362.364782 -283.806138)
		(width 0.12954)
		(layer "F.Cu")
		(net "P5E_CPU0_P2_RX_DN<1>")
	)
	(segment
		(start 404.098252 -393.69238)
		(end 404.618952 -393.69238)
		(width 0.127)
		(layer "F.Cu")
		(net "P5E_CPU0_P2_RX_DN<1>")
	)
	(segment
		(start 361.581192 -289.006534)
		(end 361.61345 -288.987738)
		(width 0.1143)
		(layer "In6.Cu")
		(net "P5E_CPU0_P2_RX_DN<1>")
	)
	(segment
		(start 361.575604 -289.009582)
		(end 361.581192 -289.006534)
		(width 0.1143)
		(layer "In6.Cu")
		(net "P5E_CPU0_P2_RX_DN<1>")
	)
	(segment
		(start 364.055406 -303.272444)
		(end 362.223812 -298.850304)
		(width 0.14224)
		(layer "In6.Cu")
		(net "P5E_CPU0_P2_RX_DN<1>")
	)
	(segment
		(start 361.60964 -285.75)
		(end 361.611926 -285.74873)
		(width 0.1143)
		(layer "In6.Cu")
		(net "P5E_CPU0_P2_RX_DN<1>")
	)
	(segment
		(start 403.882098 -389.198866)
		(end 403.612096 -388.867904)
		(width 0.14224)
		(layer "In6.Cu")
		(net "P5E_CPU0_P2_RX_DN<1>")
	)
	(segment
		(start 405.05761 -390.422892)
		(end 404.787862 -390.092438)
		(width 0.14224)
		(layer "In6.Cu")
		(net "P5E_CPU0_P2_RX_DN<1>")
	)
	(segment
		(start 362.223812 -296.353484)
		(end 362.223812 -296.325036)
		(width 0.1143)
		(layer "In6.Cu")
		(net "P5E_CPU0_P2_RX_DN<1>")
	)
	(segment
		(start 405.086312 -392.31316)
		(end 405.086312 -390.50341)
		(width 0.14224)
		(layer "In6.Cu")
		(net "P5E_CPU0_P2_RX_DN<1>")
	)
	(segment
		(start 403.631654 -388.675118)
		(end 403.361652 -388.34441)
		(width 0.14224)
		(layer "In6.Cu")
		(net "P5E_CPU0_P2_RX_DN<1>")
	)
	(segment
		(start 362.081826 -284.938724)
		(end 362.113576 -284.920436)
		(width 0.1143)
		(layer "In6.Cu")
		(net "P5E_CPU0_P2_RX_DN<1>")
	)
	(segment
		(start 362.732574 -283.875988)
		(end 362.662724 -283.806138)
		(width 0.1143)
		(layer "In6.Cu")
		(net "P5E_CPU0_P2_RX_DN<1>")
	)
	(segment
		(start 366.022636 -306.216558)
		(end 364.055406 -303.272444)
		(width 0.14224)
		(layer "In6.Cu")
		(net "P5E_CPU0_P2_RX_DN<1>")
	)
	(segment
		(start 381.470662 -337.396836)
		(end 379.294898 -326.457056)
		(width 0.14224)
		(layer "In6.Cu")
		(net "P5E_CPU0_P2_RX_DN<1>")
	)
	(segment
		(start 383.90703 -352.845116)
		(end 382.099312 -343.757758)
		(width 0.14224)
		(layer "In6.Cu")
		(net "P5E_CPU0_P2_RX_DN<1>")
	)
	(segment
		(start 362.515404 -284.1498)
		(end 362.551472 -284.128972)
		(width 0.1143)
		(layer "In6.Cu")
		(net "P5E_CPU0_P2_RX_DN<1>")
	)
	(segment
		(start 361.613704 -288.344356)
		(end 361.572048 -288.32048)
		(width 0.1143)
		(layer "In6.Cu")
		(net "P5E_CPU0_P2_RX_DN<1>")
	)
	(segment
		(start 396.876524 -376.47245)
		(end 391.424414 -371.02034)
		(width 0.14224)
		(layer "In6.Cu")
		(net "P5E_CPU0_P2_RX_DN<1>")
	)
	(segment
		(start 403.361652 -388.34441)
		(end 403.361906 -388.34441)
		(width 0.14224)
		(layer "In6.Cu")
		(net "P5E_CPU0_P2_RX_DN<1>")
	)
	(segment
		(start 361.611672 -293.203376)
		(end 361.609132 -293.201598)
		(width 0.1143)
		(layer "In6.Cu")
		(net "P5E_CPU0_P2_RX_DN<1>")
	)
	(segment
		(start 404.325074 -389.741918)
		(end 404.344632 -389.549132)
		(width 0.14224)
		(layer "In6.Cu")
		(net "P5E_CPU0_P2_RX_DN<1>")
	)
	(segment
		(start 362.223812 -298.850304)
		(end 362.223812 -296.353484)
		(width 0.14224)
		(layer "In6.Cu")
		(net "P5E_CPU0_P2_RX_DN<1>")
	)
	(segment
		(start 361.642406 -289.981132)
		(end 361.611926 -289.963352)
		(width 0.1143)
		(layer "In6.Cu")
		(net "P5E_CPU0_P2_RX_DN<1>")
	)
	(segment
		(start 361.641644 -285.731458)
		(end 361.642406 -285.73095)
		(width 0.1143)
		(layer "In6.Cu")
		(net "P5E_CPU0_P2_RX_DN<1>")
	)
	(segment
		(start 361.557824 -292.262052)
		(end 361.570016 -292.2524)
		(width 0.1143)
		(layer "In6.Cu")
		(net "P5E_CPU0_P2_RX_DN<1>")
	)
	(segment
		(start 361.611926 -294.823388)
		(end 361.575604 -294.802306)
		(width 0.1143)
		(layer "In6.Cu")
		(net "P5E_CPU0_P2_RX_DN<1>")
	)
	(segment
		(start 361.611926 -293.848536)
		(end 361.642406 -293.830756)
		(width 0.1143)
		(layer "In6.Cu")
		(net "P5E_CPU0_P2_RX_DN<1>")
	)
	(segment
		(start 404.595076 -390.07288)
		(end 404.325074 -389.741918)
		(width 0.14224)
		(layer "In6.Cu")
		(net "P5E_CPU0_P2_RX_DN<1>")
	)
	(segment
		(start 361.611926 -285.74873)
		(end 361.641644 -285.731458)
		(width 0.1143)
		(layer "In6.Cu")
		(net "P5E_CPU0_P2_RX_DN<1>")
	)
	(segment
		(start 361.611672 -292.228524)
		(end 361.612434 -292.228016)
		(width 0.1143)
		(layer "In6.Cu")
		(net "P5E_CPU0_P2_RX_DN<1>")
	)
	(segment
		(start 382.09347 -343.718134)
		(end 381.470662 -337.396836)
		(width 0.14224)
		(layer "In6.Cu")
		(net "P5E_CPU0_P2_RX_DN<1>")
	)
	(segment
		(start 362.223812 -296.325036)
		(end 362.269532 -296.279316)
		(width 0.1143)
		(layer "In6.Cu")
		(net "P5E_CPU0_P2_RX_DN<1>")
	)
	(segment
		(start 361.644438 -286.742378)
		(end 361.611926 -286.723582)
		(width 0.1143)
		(layer "In6.Cu")
		(net "P5E_CPU0_P2_RX_DN<1>")
	)
	(segment
		(start 404.07463 -389.218424)
		(end 404.074884 -389.218424)
		(width 0.14224)
		(layer "In6.Cu")
		(net "P5E_CPU0_P2_RX_DN<1>")
	)
	(segment
		(start 391.335514 -370.887498)
		(end 384.02895 -353.247706)
		(width 0.14224)
		(layer "In6.Cu")
		(net "P5E_CPU0_P2_RX_DN<1>")
	)
	(segment
		(start 361.611926 -291.583364)
		(end 361.575604 -291.562282)
		(width 0.1143)
		(layer "In6.Cu")
		(net "P5E_CPU0_P2_RX_DN<1>")
	)
	(segment
		(start 366.022382 -306.216558)
		(end 366.022636 -306.216558)
		(width 0.14224)
		(layer "In6.Cu")
		(net "P5E_CPU0_P2_RX_DN<1>")
	)
	(segment
		(start 361.609132 -293.201598)
		(end 361.570016 -293.1795)
		(width 0.1143)
		(layer "In6.Cu")
		(net "P5E_CPU0_P2_RX_DN<1>")
	)
	(segment
		(start 361.578398 -287.388046)
		(end 361.642406 -287.350708)
		(width 0.1143)
		(layer "In6.Cu")
		(net "P5E_CPU0_P2_RX_DN<1>")
	)
	(segment
		(start 361.611926 -286.723582)
		(end 361.60964 -286.722312)
		(width 0.1143)
		(layer "In6.Cu")
		(net "P5E_CPU0_P2_RX_DN<1>")
	)
	(segment
		(start 373.052848 -315.327538)
		(end 367.981992 -309.148988)
		(width 0.14224)
		(layer "In6.Cu")
		(net "P5E_CPU0_P2_RX_DN<1>")
	)
	(segment
		(start 362.55325 -284.127956)
		(end 362.583476 -284.11043)
		(width 0.1143)
		(layer "In6.Cu")
		(net "P5E_CPU0_P2_RX_DN<1>")
	)
	(segment
		(start 404.074884 -389.218424)
		(end 403.882098 -389.198866)
		(width 0.14224)
		(layer "In6.Cu")
		(net "P5E_CPU0_P2_RX_DN<1>")
	)
	(segment
		(start 404.787862 -390.092438)
		(end 404.595076 -390.07288)
		(width 0.14224)
		(layer "In6.Cu")
		(net "P5E_CPU0_P2_RX_DN<1>")
	)
	(segment
		(start 361.643422 -293.221664)
		(end 361.613704 -293.204646)
		(width 0.1143)
		(layer "In6.Cu")
		(net "P5E_CPU0_P2_RX_DN<1>")
	)
	(segment
		(start 361.570016 -293.1795)
		(end 361.557824 -293.169848)
		(width 0.1143)
		(layer "In6.Cu")
		(net "P5E_CPU0_P2_RX_DN<1>")
	)
	(segment
		(start 402.899118 -387.99389)
		(end 402.918676 -387.80085)
		(width 0.14224)
		(layer "In6.Cu")
		(net "P5E_CPU0_P2_RX_DN<1>")
	)
	(segment
		(start 361.612434 -292.228016)
		(end 361.613704 -292.227254)
		(width 0.1143)
		(layer "In6.Cu")
		(net "P5E_CPU0_P2_RX_DN<1>")
	)
	(segment
		(start 361.61345 -288.987738)
		(end 361.617514 -288.985198)
		(width 0.1143)
		(layer "In6.Cu")
		(net "P5E_CPU0_P2_RX_DN<1>")
	)
	(segment
		(start 361.611926 -290.608512)
		(end 361.642406 -290.590732)
		(width 0.1143)
		(layer "In6.Cu")
		(net "P5E_CPU0_P2_RX_DN<1>")
	)
	(segment
		(start 362.552234 -284.128464)
		(end 362.55325 -284.127956)
		(width 0.1143)
		(layer "In6.Cu")
		(net "P5E_CPU0_P2_RX_DN<1>")
	)
	(segment
		(start 361.612434 -293.203884)
		(end 361.611672 -293.203376)
		(width 0.1143)
		(layer "In6.Cu")
		(net "P5E_CPU0_P2_RX_DN<1>")
	)
	(segment
		(start 361.613704 -292.227254)
		(end 361.643422 -292.210236)
		(width 0.1143)
		(layer "In6.Cu")
		(net "P5E_CPU0_P2_RX_DN<1>")
	)
	(segment
		(start 403.16912 -388.324852)
		(end 402.899118 -387.99389)
		(width 0.14224)
		(layer "In6.Cu")
		(net "P5E_CPU0_P2_RX_DN<1>")
	)
	(segment
		(start 361.613704 -293.204646)
		(end 361.612434 -293.203884)
		(width 0.1143)
		(layer "In6.Cu")
		(net "P5E_CPU0_P2_RX_DN<1>")
	)
	(segment
		(start 362.551472 -284.128972)
		(end 362.552234 -284.128464)
		(width 0.1143)
		(layer "In6.Cu")
		(net "P5E_CPU0_P2_RX_DN<1>")
	)
	(segment
		(start 361.642406 -294.841168)
		(end 361.611926 -294.823388)
		(width 0.1143)
		(layer "In6.Cu")
		(net "P5E_CPU0_P2_RX_DN<1>")
	)
	(segment
		(start 404.618952 -393.69238)
		(end 404.972266 -393.787376)
		(width 0.14224)
		(layer "In6.Cu")
		(net "P5E_CPU0_P2_RX_DN<1>")
	)
	(segment
		(start 361.575604 -293.869618)
		(end 361.611926 -293.848536)
		(width 0.1143)
		(layer "In6.Cu")
		(net "P5E_CPU0_P2_RX_DN<1>")
	)
	(segment
		(start 402.918676 -387.80085)
		(end 402.918168 -387.80085)
		(width 0.14224)
		(layer "In6.Cu")
		(net "P5E_CPU0_P2_RX_DN<1>")
	)
	(segment
		(start 361.575604 -290.629594)
		(end 361.611926 -290.608512)
		(width 0.1143)
		(layer "In6.Cu")
		(net "P5E_CPU0_P2_RX_DN<1>")
	)
	(segment
		(start 361.611926 -289.963352)
		(end 361.575604 -289.94227)
		(width 0.1143)
		(layer "In6.Cu")
		(net "P5E_CPU0_P2_RX_DN<1>")
	)
	(segment
		(start 362.662724 -283.806138)
		(end 362.364782 -283.806138)
		(width 0.1143)
		(layer "In6.Cu")
		(net "P5E_CPU0_P2_RX_DN<1>")
	)
	(segment
		(start 402.918168 -387.80085)
		(end 397.067532 -380.629922)
		(width 0.14224)
		(layer "In6.Cu")
		(net "P5E_CPU0_P2_RX_DN<1>")
	)
	(segment
		(start 405.09444 -393.545822)
		(end 404.777448 -393.22883)
		(width 0.14224)
		(layer "In6.Cu")
		(net "P5E_CPU0_P2_RX_DN<1>")
	)
	(segment
		(start 405.09444 -393.716764)
		(end 405.09444 -393.545822)
		(width 0.14224)
		(layer "In6.Cu")
		(net "P5E_CPU0_P2_RX_DN<1>")
	)
	(segment
		(start 403.612096 -388.867904)
		(end 403.631654 -388.675118)
		(width 0.14224)
		(layer "In6.Cu")
		(net "P5E_CPU0_P2_RX_DN<1>")
	)
	(segment
		(start 361.617514 -288.346642)
		(end 361.613704 -288.344356)
		(width 0.1143)
		(layer "In6.Cu")
		(net "P5E_CPU0_P2_RX_DN<1>")
	)
	(segment
		(start 404.777448 -393.22883)
		(end 404.782274 -392.616944)
		(width 0.14224)
		(layer "In6.Cu")
		(net "P5E_CPU0_P2_RX_DN<1>")
	)
	(segment
		(start 361.642406 -291.601144)
		(end 361.611926 -291.583364)
		(width 0.1143)
		(layer "In6.Cu")
		(net "P5E_CPU0_P2_RX_DN<1>")
	)
	(segment
		(start 404.972266 -393.787376)
		(end 404.972774 -393.786868)
		(width 0.14224)
		(layer "In6.Cu")
		(net "P5E_CPU0_P2_RX_DN<1>")
	)
	(segment
		(start 396.913862 -380.197614)
		(end 396.913862 -376.56262)
		(width 0.14224)
		(layer "In6.Cu")
		(net "P5E_CPU0_P2_RX_DN<1>")
	)
	(segment
		(start 404.782274 -392.616944)
		(end 405.086312 -392.31316)
		(width 0.14224)
		(layer "In6.Cu")
		(net "P5E_CPU0_P2_RX_DN<1>")
	)
	(segment
		(start 404.972774 -393.786868)
		(end 405.09444 -393.716764)
		(width 0.14224)
		(layer "In6.Cu")
		(net "P5E_CPU0_P2_RX_DN<1>")
	)
	(segment
		(start 361.570016 -292.2524)
		(end 361.611672 -292.228524)
		(width 0.1143)
		(layer "In6.Cu")
		(net "P5E_CPU0_P2_RX_DN<1>")
	)
	(segment
		(start 362.269532 -296.279316)
		(end 362.269532 -295.95572)
		(width 0.1143)
		(layer "In6.Cu")
		(net "P5E_CPU0_P2_RX_DN<1>")
	)
	(segment
		(start 374.52681 -317.533782)
		(end 373.052848 -315.327538)
		(width 0.14224)
		(layer "In6.Cu")
		(net "P5E_CPU0_P2_RX_DN<1>")
	)
	(segment
		(start 403.361906 -388.34441)
		(end 403.16912 -388.324852)
		(width 0.14224)
		(layer "In6.Cu")
		(net "P5E_CPU0_P2_RX_DN<1>")
	)
	(segment
		(start 367.981992 -309.148988)
		(end 366.022382 -306.216558)
		(width 0.14224)
		(layer "In6.Cu")
		(net "P5E_CPU0_P2_RX_DN<1>")
	)
	(segment
		(start 362.269532 -295.95572)
		(end 362.269278 -295.955974)
		(width 0.1143)
		(layer "In6.Cu")
		(net "P5E_CPU0_P2_RX_DN<1>")
	)
	(segment
		(start 404.344632 -389.549132)
		(end 404.07463 -389.218424)
		(width 0.14224)
		(layer "In6.Cu")
		(net "P5E_CPU0_P2_RX_DN<1>")
	)
	(segment
		(start 362.04271 -284.961584)
		(end 362.081826 -284.938724)
		(width 0.1143)
		(layer "In6.Cu")
		(net "P5E_CPU0_P2_RX_DN<1>")
	)
	(segment
		(start 379.294898 -326.457056)
		(end 374.52681 -317.533782)
		(width 0.14224)
		(layer "In6.Cu")
		(net "P5E_CPU0_P2_RX_DN<1>")
	)
	(segment
		(start 362.112306 -295.651174)
		(end 362.04271 -295.610534)
		(width 0.1143)
		(layer "In6.Cu")
		(net "P5E_CPU0_P2_RX_DN<1>")
	)
	(arc
		(start 361.617514 -288.985198)
		(mid 361.799675 -288.66592)
		(end 361.617514 -288.346642)
		(width 0.1143)
		(layer "In6.Cu")
		(net "P5E_CPU0_P2_RX_DN<1>")
	)
	(arc
		(start 361.575604 -294.802306)
		(mid 361.329714 -294.335962)
		(end 361.575604 -293.869618)
		(width 0.1143)
		(layer "In6.Cu")
		(net "P5E_CPU0_P2_RX_DN<1>")
	)
	(arc
		(start 361.575604 -289.94227)
		(mid 361.329714 -289.475926)
		(end 361.575604 -289.009582)
		(width 0.1143)
		(layer "In6.Cu")
		(net "P5E_CPU0_P2_RX_DN<1>")
	)
	(arc
		(start 362.238036 -295.806368)
		(mid 362.185693 -295.720251)
		(end 362.112306 -295.651174)
		(width 0.1143)
		(layer "In6.Cu")
		(net "P5E_CPU0_P2_RX_DN<1>")
	)
	(arc
		(start 405.086312 -390.50341)
		(mid 405.078908 -390.460681)
		(end 405.05761 -390.422892)
		(width 0.14224)
		(layer "In6.Cu")
		(net "P5E_CPU0_P2_RX_DN<1>")
	)
	(arc
		(start 361.642406 -290.590732)
		(mid 361.799383 -290.285932)
		(end 361.642406 -289.981132)
		(width 0.1143)
		(layer "In6.Cu")
		(net "P5E_CPU0_P2_RX_DN<1>")
	)
	(arc
		(start 361.642406 -285.73095)
		(mid 361.757833 -285.597574)
		(end 361.799378 -285.42615)
		(width 0.1143)
		(layer "In6.Cu")
		(net "P5E_CPU0_P2_RX_DN<1>")
	)
	(arc
		(start 397.067532 -380.629922)
		(mid 396.95335 -380.42704)
		(end 396.913862 -380.197614)
		(width 0.14224)
		(layer "In6.Cu")
		(net "P5E_CPU0_P2_RX_DN<1>")
	)
	(arc
		(start 361.575604 -291.562282)
		(mid 361.329714 -291.095938)
		(end 361.575604 -290.629594)
		(width 0.1143)
		(layer "In6.Cu")
		(net "P5E_CPU0_P2_RX_DN<1>")
	)
	(arc
		(start 391.424414 -371.02034)
		(mid 391.373442 -370.958286)
		(end 391.335514 -370.887498)
		(width 0.14224)
		(layer "In6.Cu")
		(net "P5E_CPU0_P2_RX_DN<1>")
	)
	(arc
		(start 382.099312 -343.757758)
		(mid 382.095901 -343.738018)
		(end 382.09347 -343.718134)
		(width 0.14224)
		(layer "In6.Cu")
		(net "P5E_CPU0_P2_RX_DN<1>")
	)
	(arc
		(start 362.269278 -295.955974)
		(mid 362.261395 -295.879552)
		(end 362.238036 -295.806368)
		(width 0.1143)
		(layer "In6.Cu")
		(net "P5E_CPU0_P2_RX_DN<1>")
	)
	(arc
		(start 361.642406 -293.830756)
		(mid 361.757833 -293.69738)
		(end 361.799378 -293.525956)
		(width 0.1143)
		(layer "In6.Cu")
		(net "P5E_CPU0_P2_RX_DN<1>")
	)
	(arc
		(start 361.799378 -295.145968)
		(mid 361.757829 -294.974546)
		(end 361.642406 -294.841168)
		(width 0.1143)
		(layer "In6.Cu")
		(net "P5E_CPU0_P2_RX_DN<1>")
	)
	(arc
		(start 362.269786 -284.62986)
		(mid 362.27055 -284.606454)
		(end 362.27258 -284.583124)
		(width 0.1143)
		(layer "In6.Cu")
		(net "P5E_CPU0_P2_RX_DN<1>")
	)
	(arc
		(start 361.799378 -287.045908)
		(mid 361.758412 -286.875502)
		(end 361.644438 -286.742378)
		(width 0.1143)
		(layer "In6.Cu")
		(net "P5E_CPU0_P2_RX_DN<1>")
	)
	(arc
		(start 361.557824 -293.169848)
		(mid 361.326726 -292.71595)
		(end 361.557824 -292.262052)
		(width 0.1143)
		(layer "In6.Cu")
		(net "P5E_CPU0_P2_RX_DN<1>")
	)
	(arc
		(start 396.913862 -376.56262)
		(mid 396.904156 -376.513825)
		(end 396.876524 -376.47245)
		(width 0.14224)
		(layer "In6.Cu")
		(net "P5E_CPU0_P2_RX_DN<1>")
	)
	(arc
		(start 361.643422 -292.210236)
		(mid 361.758098 -292.076902)
		(end 361.799378 -291.905944)
		(width 0.1143)
		(layer "In6.Cu")
		(net "P5E_CPU0_P2_RX_DN<1>")
	)
	(arc
		(start 362.583476 -284.11043)
		(mid 362.680611 -284.007561)
		(end 362.732574 -283.875988)
		(width 0.1143)
		(layer "In6.Cu")
		(net "P5E_CPU0_P2_RX_DN<1>")
	)
	(arc
		(start 361.329732 -287.856168)
		(mid 361.395762 -287.59114)
		(end 361.578398 -287.388046)
		(width 0.1143)
		(layer "In6.Cu")
		(net "P5E_CPU0_P2_RX_DN<1>")
	)
	(arc
		(start 361.642406 -287.350708)
		(mid 361.757833 -287.217332)
		(end 361.799378 -287.045908)
		(width 0.1143)
		(layer "In6.Cu")
		(net "P5E_CPU0_P2_RX_DN<1>")
	)
	(arc
		(start 361.572048 -288.32048)
		(mid 361.393866 -288.118077)
		(end 361.329732 -287.856168)
		(width 0.1143)
		(layer "In6.Cu")
		(net "P5E_CPU0_P2_RX_DN<1>")
	)
	(arc
		(start 362.27258 -284.583124)
		(mid 362.352123 -284.342993)
		(end 362.515404 -284.1498)
		(width 0.1143)
		(layer "In6.Cu")
		(net "P5E_CPU0_P2_RX_DN<1>")
	)
	(arc
		(start 362.113576 -284.920436)
		(mid 362.225319 -284.793236)
		(end 362.269786 -284.62986)
		(width 0.1143)
		(layer "In6.Cu")
		(net "P5E_CPU0_P2_RX_DN<1>")
	)
	(arc
		(start 361.60964 -286.722312)
		(mid 361.329712 -286.236156)
		(end 361.60964 -285.75)
		(width 0.1143)
		(layer "In6.Cu")
		(net "P5E_CPU0_P2_RX_DN<1>")
	)
	(arc
		(start 362.04271 -295.610534)
		(mid 361.863897 -295.408184)
		(end 361.799378 -295.145968)
		(width 0.1143)
		(layer "In6.Cu")
		(net "P5E_CPU0_P2_RX_DN<1>")
	)
	(arc
		(start 361.799378 -285.42615)
		(mid 361.863893 -285.163931)
		(end 362.04271 -284.961584)
		(width 0.1143)
		(layer "In6.Cu")
		(net "P5E_CPU0_P2_RX_DN<1>")
	)
	(arc
		(start 384.02895 -353.247706)
		(mid 383.958088 -353.049409)
		(end 383.90703 -352.845116)
		(width 0.14224)
		(layer "In6.Cu")
		(net "P5E_CPU0_P2_RX_DN<1>")
	)
	(arc
		(start 361.799378 -293.525956)
		(mid 361.758123 -293.354985)
		(end 361.643422 -293.221664)
		(width 0.1143)
		(layer "In6.Cu")
		(net "P5E_CPU0_P2_RX_DN<1>")
	)
	(arc
		(start 361.799378 -291.905944)
		(mid 361.757829 -291.734522)
		(end 361.642406 -291.601144)
		(width 0.1143)
		(layer "In6.Cu")
		(net "P5E_CPU0_P2_RX_DN<1>")
	)
	(segment
		(start 420.89832 -393.69238)
		(end 421.41902 -393.69238)
		(width 0.127)
		(layer "F.Cu")
		(net "P5E_CPU0_P2_RX_DN<15>")
	)
	(segment
		(start 372.707916 -282.730194)
		(end 373.174768 -282.996132)
		(width 0.12954)
		(layer "F.Cu")
		(net "P5E_CPU0_P2_RX_DN<15>")
	)
	(segment
		(start 374.80367 -293.221918)
		(end 374.734328 -293.181532)
		(width 0.1143)
		(layer "In6.Cu")
		(net "P5E_CPU0_P2_RX_DN<15>")
	)
	(segment
		(start 415.901124 -369.24742)
		(end 410.47416 -367.886996)
		(width 0.14224)
		(layer "In6.Cu")
		(net "P5E_CPU0_P2_RX_DN<15>")
	)
	(segment
		(start 423.762424 -389.82523)
		(end 423.650156 -389.667242)
		(width 0.14224)
		(layer "In6.Cu")
		(net "P5E_CPU0_P2_RX_DN<15>")
	)
	(segment
		(start 403.458934 -363.893862)
		(end 403.087332 -363.52226)
		(width 0.14224)
		(layer "In6.Cu")
		(net "P5E_CPU0_P2_RX_DN<15>")
	)
	(segment
		(start 374.306338 -284.296104)
		(end 374.303798 -284.294834)
		(width 0.1143)
		(layer "In6.Cu")
		(net "P5E_CPU0_P2_RX_DN<15>")
	)
	(segment
		(start 424.273726 -387.564376)
		(end 425.158154 -384.49123)
		(width 0.14224)
		(layer "In6.Cu")
		(net "P5E_CPU0_P2_RX_DN<15>")
	)
	(segment
		(start 426.636688 -380.921768)
		(end 426.636434 -380.921768)
		(width 0.14224)
		(layer "In6.Cu")
		(net "P5E_CPU0_P2_RX_DN<15>")
	)
	(segment
		(start 423.202354 -391.858246)
		(end 423.50309 -391.357866)
		(width 0.14224)
		(layer "In6.Cu")
		(net "P5E_CPU0_P2_RX_DN<15>")
	)
	(segment
		(start 384.732022 -308.75859)
		(end 377.825762 -300.343824)
		(width 0.14224)
		(layer "In6.Cu")
		(net "P5E_CPU0_P2_RX_DN<15>")
	)
	(segment
		(start 375.536968 -296.589704)
		(end 375.581926 -296.544746)
		(width 0.1143)
		(layer "In6.Cu")
		(net "P5E_CPU0_P2_RX_DN<15>")
	)
	(segment
		(start 421.894508 -393.716764)
		(end 421.894508 -393.258548)
		(width 0.14224)
		(layer "In6.Cu")
		(net "P5E_CPU0_P2_RX_DN<15>")
	)
	(segment
		(start 428.105824 -379.355858)
		(end 428.105824 -377.608592)
		(width 0.14224)
		(layer "In6.Cu")
		(net "P5E_CPU0_P2_RX_DN<15>")
	)
	(segment
		(start 423.985944 -388.068566)
		(end 424.1038 -387.658102)
		(width 0.14224)
		(layer "In6.Cu")
		(net "P5E_CPU0_P2_RX_DN<15>")
	)
	(segment
		(start 375.362978 -295.762934)
		(end 375.227342 -295.625266)
		(width 0.1143)
		(layer "In6.Cu")
		(net "P5E_CPU0_P2_RX_DN<15>")
	)
	(segment
		(start 374.302528 -284.294072)
		(end 374.301766 -284.293564)
		(width 0.1143)
		(layer "In6.Cu")
		(net "P5E_CPU0_P2_RX_DN<15>")
	)
	(segment
		(start 421.772334 -393.787376)
		(end 421.772842 -393.786868)
		(width 0.14224)
		(layer "In6.Cu")
		(net "P5E_CPU0_P2_RX_DN<15>")
	)
	(segment
		(start 375.536968 -296.766996)
		(end 375.536968 -296.604182)
		(width 0.14224)
		(layer "In6.Cu")
		(net "P5E_CPU0_P2_RX_DN<15>")
	)
	(segment
		(start 423.721276 -389.24611)
		(end 423.879772 -389.133842)
		(width 0.14224)
		(layer "In6.Cu")
		(net "P5E_CPU0_P2_RX_DN<15>")
	)
	(segment
		(start 373.555514 -283.078936)
		(end 373.47271 -282.996132)
		(width 0.1143)
		(layer "In6.Cu")
		(net "P5E_CPU0_P2_RX_DN<15>")
	)
	(segment
		(start 421.41902 -393.69238)
		(end 421.772334 -393.787376)
		(width 0.14224)
		(layer "In6.Cu")
		(net "P5E_CPU0_P2_RX_DN<15>")
	)
	(segment
		(start 423.879772 -389.133842)
		(end 423.879264 -389.133842)
		(width 0.14224)
		(layer "In6.Cu")
		(net "P5E_CPU0_P2_RX_DN<15>")
	)
	(segment
		(start 375.19483 -285.885128)
		(end 375.194576 -285.885128)
		(width 0.1143)
		(layer "In6.Cu")
		(net "P5E_CPU0_P2_RX_DN<15>")
	)
	(segment
		(start 395.22146 -341.444326)
		(end 394.746734 -336.629502)
		(width 0.14224)
		(layer "In6.Cu")
		(net "P5E_CPU0_P2_RX_DN<15>")
	)
	(segment
		(start 375.200926 -286.582866)
		(end 375.250456 -286.55391)
		(width 0.1143)
		(layer "In6.Cu")
		(net "P5E_CPU0_P2_RX_DN<15>")
	)
	(segment
		(start 423.961814 -388.648194)
		(end 424.07967 -388.238238)
		(width 0.14224)
		(layer "In6.Cu")
		(net "P5E_CPU0_P2_RX_DN<15>")
	)
	(segment
		(start 374.734328 -292.250368)
		(end 374.80367 -292.209982)
		(width 0.1143)
		(layer "In6.Cu")
		(net "P5E_CPU0_P2_RX_DN<15>")
	)
	(segment
		(start 375.581926 -296.544746)
		(end 375.581926 -296.446194)
		(width 0.1143)
		(layer "In6.Cu")
		(net "P5E_CPU0_P2_RX_DN<15>")
	)
	(segment
		(start 374.80367 -291.601906)
		(end 374.734328 -291.56152)
		(width 0.1143)
		(layer "In6.Cu")
		(net "P5E_CPU0_P2_RX_DN<15>")
	)
	(segment
		(start 374.8024 -285.12135)
		(end 374.732804 -285.08071)
		(width 0.1143)
		(layer "In6.Cu")
		(net "P5E_CPU0_P2_RX_DN<15>")
	)
	(segment
		(start 421.772842 -393.786868)
		(end 421.894508 -393.716764)
		(width 0.14224)
		(layer "In6.Cu")
		(net "P5E_CPU0_P2_RX_DN<15>")
	)
	(segment
		(start 373.854218 -283.496512)
		(end 373.79275 -283.460698)
		(width 0.1143)
		(layer "In6.Cu")
		(net "P5E_CPU0_P2_RX_DN<15>")
	)
	(segment
		(start 396.422626 -347.49359)
		(end 395.227302 -341.48395)
		(width 0.14224)
		(layer "In6.Cu")
		(net "P5E_CPU0_P2_RX_DN<15>")
	)
	(segment
		(start 375.536968 -296.604182)
		(end 375.536968 -296.589704)
		(width 0.1143)
		(layer "In6.Cu")
		(net "P5E_CPU0_P2_RX_DN<15>")
	)
	(segment
		(start 425.367196 -373.335804)
		(end 421.64127 -371.202204)
		(width 0.14224)
		(layer "In6.Cu")
		(net "P5E_CPU0_P2_RX_DN<15>")
	)
	(segment
		(start 392.122406 -322.168266)
		(end 385.842764 -310.42102)
		(width 0.14224)
		(layer "In6.Cu")
		(net "P5E_CPU0_P2_RX_DN<15>")
	)
	(segment
		(start 385.842764 -310.42102)
		(end 384.732022 -308.75859)
		(width 0.14224)
		(layer "In6.Cu")
		(net "P5E_CPU0_P2_RX_DN<15>")
	)
	(segment
		(start 375.227342 -295.625266)
		(end 375.202196 -295.61028)
		(width 0.1143)
		(layer "In6.Cu")
		(net "P5E_CPU0_P2_RX_DN<15>")
	)
	(segment
		(start 427.191678 -375.107708)
		(end 425.367196 -373.335804)
		(width 0.14224)
		(layer "In6.Cu")
		(net "P5E_CPU0_P2_RX_DN<15>")
	)
	(segment
		(start 426.636434 -380.921768)
		(end 426.636688 -380.921514)
		(width 0.14224)
		(layer "In6.Cu")
		(net "P5E_CPU0_P2_RX_DN<15>")
	)
	(segment
		(start 423.650156 -389.667242)
		(end 423.721276 -389.24611)
		(width 0.14224)
		(layer "In6.Cu")
		(net "P5E_CPU0_P2_RX_DN<15>")
	)
	(segment
		(start 410.47416 -367.886996)
		(end 403.546564 -363.960664)
		(width 0.14224)
		(layer "In6.Cu")
		(net "P5E_CPU0_P2_RX_DN<15>")
	)
	(segment
		(start 394.746734 -336.629502)
		(end 392.122406 -322.168266)
		(width 0.14224)
		(layer "In6.Cu")
		(net "P5E_CPU0_P2_RX_DN<15>")
	)
	(segment
		(start 374.301766 -284.293564)
		(end 374.265444 -284.272482)
		(width 0.1143)
		(layer "In6.Cu")
		(net "P5E_CPU0_P2_RX_DN<15>")
	)
	(segment
		(start 426.725588 -380.788672)
		(end 428.068486 -379.445774)
		(width 0.14224)
		(layer "In6.Cu")
		(net "P5E_CPU0_P2_RX_DN<15>")
	)
	(segment
		(start 423.50309 -391.357866)
		(end 423.762424 -389.82523)
		(width 0.14224)
		(layer "In6.Cu")
		(net "P5E_CPU0_P2_RX_DN<15>")
	)
	(segment
		(start 402.998432 -363.389418)
		(end 396.445994 -347.570044)
		(width 0.14224)
		(layer "In6.Cu")
		(net "P5E_CPU0_P2_RX_DN<15>")
	)
	(segment
		(start 375.702322 -297.166284)
		(end 375.536968 -296.766996)
		(width 0.14224)
		(layer "In6.Cu")
		(net "P5E_CPU0_P2_RX_DN<15>")
	)
	(segment
		(start 374.308878 -284.297628)
		(end 374.306338 -284.296104)
		(width 0.1143)
		(layer "In6.Cu")
		(net "P5E_CPU0_P2_RX_DN<15>")
	)
	(segment
		(start 428.105824 -377.608592)
		(end 428.10557 -377.607322)
		(width 0.14224)
		(layer "In6.Cu")
		(net "P5E_CPU0_P2_RX_DN<15>")
	)
	(segment
		(start 373.47271 -282.996132)
		(end 373.174768 -282.996132)
		(width 0.1143)
		(layer "In6.Cu")
		(net "P5E_CPU0_P2_RX_DN<15>")
	)
	(segment
		(start 421.64127 -371.202204)
		(end 415.901124 -369.24742)
		(width 0.14224)
		(layer "In6.Cu")
		(net "P5E_CPU0_P2_RX_DN<15>")
	)
	(segment
		(start 374.734328 -287.390586)
		(end 374.801638 -287.35147)
		(width 0.1143)
		(layer "In6.Cu")
		(net "P5E_CPU0_P2_RX_DN<15>")
	)
	(segment
		(start 423.879518 -389.133588)
		(end 423.961814 -388.648194)
		(width 0.14224)
		(layer "In6.Cu")
		(net "P5E_CPU0_P2_RX_DN<15>")
	)
	(segment
		(start 375.262648 -285.928816)
		(end 375.19483 -285.885128)
		(width 0.1143)
		(layer "In6.Cu")
		(net "P5E_CPU0_P2_RX_DN<15>")
	)
	(segment
		(start 425.158154 -384.49123)
		(end 426.636688 -380.921768)
		(width 0.14224)
		(layer "In6.Cu")
		(net "P5E_CPU0_P2_RX_DN<15>")
	)
	(segment
		(start 377.825762 -300.343824)
		(end 375.702322 -297.166284)
		(width 0.14224)
		(layer "In6.Cu")
		(net "P5E_CPU0_P2_RX_DN<15>")
	)
	(segment
		(start 374.80367 -289.981894)
		(end 374.734328 -289.941508)
		(width 0.1143)
		(layer "In6.Cu")
		(net "P5E_CPU0_P2_RX_DN<15>")
	)
	(segment
		(start 424.07967 -388.238238)
		(end 423.985944 -388.068566)
		(width 0.14224)
		(layer "In6.Cu")
		(net "P5E_CPU0_P2_RX_DN<15>")
	)
	(segment
		(start 421.894508 -393.258548)
		(end 423.202354 -391.858246)
		(width 0.14224)
		(layer "In6.Cu")
		(net "P5E_CPU0_P2_RX_DN<15>")
	)
	(segment
		(start 374.80367 -288.362136)
		(end 374.731788 -288.320226)
		(width 0.1143)
		(layer "In6.Cu")
		(net "P5E_CPU0_P2_RX_DN<15>")
	)
	(segment
		(start 374.734328 -289.010344)
		(end 374.80367 -288.969958)
		(width 0.1143)
		(layer "In6.Cu")
		(net "P5E_CPU0_P2_RX_DN<15>")
	)
	(segment
		(start 374.333516 -284.311852)
		(end 374.308878 -284.297628)
		(width 0.1143)
		(layer "In6.Cu")
		(net "P5E_CPU0_P2_RX_DN<15>")
	)
	(segment
		(start 374.303798 -284.294834)
		(end 374.302528 -284.294072)
		(width 0.1143)
		(layer "In6.Cu")
		(net "P5E_CPU0_P2_RX_DN<15>")
	)
	(segment
		(start 374.734328 -293.87038)
		(end 374.80367 -293.829994)
		(width 0.1143)
		(layer "In6.Cu")
		(net "P5E_CPU0_P2_RX_DN<15>")
	)
	(segment
		(start 428.100236 -377.540774)
		(end 428.100236 -377.300998)
		(width 0.14224)
		(layer "In6.Cu")
		(net "P5E_CPU0_P2_RX_DN<15>")
	)
	(segment
		(start 424.1038 -387.658102)
		(end 424.273726 -387.564376)
		(width 0.14224)
		(layer "In6.Cu")
		(net "P5E_CPU0_P2_RX_DN<15>")
	)
	(segment
		(start 374.80367 -294.84193)
		(end 374.734328 -294.801544)
		(width 0.1143)
		(layer "In6.Cu")
		(net "P5E_CPU0_P2_RX_DN<15>")
	)
	(segment
		(start 374.734328 -290.630356)
		(end 374.80367 -290.58997)
		(width 0.1143)
		(layer "In6.Cu")
		(net "P5E_CPU0_P2_RX_DN<15>")
	)
	(segment
		(start 423.879264 -389.133842)
		(end 423.879518 -389.133588)
		(width 0.14224)
		(layer "In6.Cu")
		(net "P5E_CPU0_P2_RX_DN<15>")
	)
	(arc
		(start 375.338594 -286.481012)
		(mid 375.412866 -286.346896)
		(end 375.42724 -286.194246)
		(width 0.1143)
		(layer "In6.Cu")
		(net "P5E_CPU0_P2_RX_DN<15>")
	)
	(arc
		(start 374.734328 -294.801544)
		(mid 374.489507 -294.335962)
		(end 374.734328 -293.87038)
		(width 0.1143)
		(layer "In6.Cu")
		(net "P5E_CPU0_P2_RX_DN<15>")
	)
	(arc
		(start 374.80367 -293.829994)
		(mid 374.959497 -293.525956)
		(end 374.80367 -293.221918)
		(width 0.1143)
		(layer "In6.Cu")
		(net "P5E_CPU0_P2_RX_DN<15>")
	)
	(arc
		(start 374.017286 -283.796486)
		(mid 373.962518 -283.631952)
		(end 373.854218 -283.496512)
		(width 0.1143)
		(layer "In6.Cu")
		(net "P5E_CPU0_P2_RX_DN<15>")
	)
	(arc
		(start 374.254776 -284.265116)
		(mid 374.085643 -284.072083)
		(end 374.019318 -283.824172)
		(width 0.1143)
		(layer "In6.Cu")
		(net "P5E_CPU0_P2_RX_DN<15>")
	)
	(arc
		(start 374.959626 -287.045908)
		(mid 375.023572 -286.784839)
		(end 375.200926 -286.582866)
		(width 0.1143)
		(layer "In6.Cu")
		(net "P5E_CPU0_P2_RX_DN<15>")
	)
	(arc
		(start 428.100236 -377.300998)
		(mid 427.864107 -376.113986)
		(end 427.191678 -375.107708)
		(width 0.14224)
		(layer "In6.Cu")
		(net "P5E_CPU0_P2_RX_DN<15>")
	)
	(arc
		(start 403.087332 -363.52226)
		(mid 403.03636 -363.460206)
		(end 402.998432 -363.389418)
		(width 0.14224)
		(layer "In6.Cu")
		(net "P5E_CPU0_P2_RX_DN<15>")
	)
	(arc
		(start 375.250456 -286.55391)
		(mid 375.297538 -286.521104)
		(end 375.338594 -286.481012)
		(width 0.1143)
		(layer "In6.Cu")
		(net "P5E_CPU0_P2_RX_DN<15>")
	)
	(arc
		(start 374.734328 -293.181532)
		(mid 374.489507 -292.71595)
		(end 374.734328 -292.250368)
		(width 0.1143)
		(layer "In6.Cu")
		(net "P5E_CPU0_P2_RX_DN<15>")
	)
	(arc
		(start 375.202196 -295.61028)
		(mid 375.023921 -295.407897)
		(end 374.959626 -295.145968)
		(width 0.1143)
		(layer "In6.Cu")
		(net "P5E_CPU0_P2_RX_DN<15>")
	)
	(arc
		(start 374.265444 -284.272482)
		(mid 374.260088 -284.268831)
		(end 374.254776 -284.265116)
		(width 0.1143)
		(layer "In6.Cu")
		(net "P5E_CPU0_P2_RX_DN<15>")
	)
	(arc
		(start 403.546564 -363.960664)
		(mid 403.500485 -363.930232)
		(end 403.458934 -363.893862)
		(width 0.14224)
		(layer "In6.Cu")
		(net "P5E_CPU0_P2_RX_DN<15>")
	)
	(arc
		(start 374.959626 -295.145968)
		(mid 374.918367 -294.975111)
		(end 374.80367 -294.84193)
		(width 0.1143)
		(layer "In6.Cu")
		(net "P5E_CPU0_P2_RX_DN<15>")
	)
	(arc
		(start 374.959372 -285.42615)
		(mid 374.917823 -285.254728)
		(end 374.8024 -285.12135)
		(width 0.1143)
		(layer "In6.Cu")
		(net "P5E_CPU0_P2_RX_DN<15>")
	)
	(arc
		(start 395.227302 -341.48395)
		(mid 395.223891 -341.46421)
		(end 395.22146 -341.444326)
		(width 0.14224)
		(layer "In6.Cu")
		(net "P5E_CPU0_P2_RX_DN<15>")
	)
	(arc
		(start 374.80367 -292.209982)
		(mid 374.959497 -291.905944)
		(end 374.80367 -291.601906)
		(width 0.1143)
		(layer "In6.Cu")
		(net "P5E_CPU0_P2_RX_DN<15>")
	)
	(arc
		(start 374.019318 -283.824172)
		(mid 374.018699 -283.8103)
		(end 374.017286 -283.796486)
		(width 0.1143)
		(layer "In6.Cu")
		(net "P5E_CPU0_P2_RX_DN<15>")
	)
	(arc
		(start 374.734328 -289.941508)
		(mid 374.489507 -289.475926)
		(end 374.734328 -289.010344)
		(width 0.1143)
		(layer "In6.Cu")
		(net "P5E_CPU0_P2_RX_DN<15>")
	)
	(arc
		(start 373.79275 -283.460698)
		(mid 373.640763 -283.30419)
		(end 373.559324 -283.101796)
		(width 0.1143)
		(layer "In6.Cu")
		(net "P5E_CPU0_P2_RX_DN<15>")
	)
	(arc
		(start 375.581926 -296.446194)
		(mid 375.545371 -296.14637)
		(end 375.4374 -295.86428)
		(width 0.1143)
		(layer "In6.Cu")
		(net "P5E_CPU0_P2_RX_DN<15>")
	)
	(arc
		(start 374.489472 -284.616144)
		(mid 374.448217 -284.445173)
		(end 374.333516 -284.311852)
		(width 0.1143)
		(layer "In6.Cu")
		(net "P5E_CPU0_P2_RX_DN<15>")
	)
	(arc
		(start 428.068486 -379.445774)
		(mid 428.096105 -379.404534)
		(end 428.105824 -379.355858)
		(width 0.14224)
		(layer "In6.Cu")
		(net "P5E_CPU0_P2_RX_DN<15>")
	)
	(arc
		(start 374.801638 -287.35147)
		(mid 374.917819 -287.217911)
		(end 374.959626 -287.045908)
		(width 0.1143)
		(layer "In6.Cu")
		(net "P5E_CPU0_P2_RX_DN<15>")
	)
	(arc
		(start 374.80367 -288.969958)
		(mid 374.959291 -288.6661)
		(end 374.80367 -288.362136)
		(width 0.1143)
		(layer "In6.Cu")
		(net "P5E_CPU0_P2_RX_DN<15>")
	)
	(arc
		(start 374.734328 -291.56152)
		(mid 374.489507 -291.095938)
		(end 374.734328 -290.630356)
		(width 0.1143)
		(layer "In6.Cu")
		(net "P5E_CPU0_P2_RX_DN<15>")
	)
	(arc
		(start 426.636688 -380.921514)
		(mid 426.67458 -380.850702)
		(end 426.725588 -380.788672)
		(width 0.14224)
		(layer "In6.Cu")
		(net "P5E_CPU0_P2_RX_DN<15>")
	)
	(arc
		(start 375.194576 -285.885128)
		(mid 375.02159 -285.684019)
		(end 374.959372 -285.42615)
		(width 0.1143)
		(layer "In6.Cu")
		(net "P5E_CPU0_P2_RX_DN<15>")
	)
	(arc
		(start 375.4374 -295.86428)
		(mid 375.403814 -295.810945)
		(end 375.362978 -295.762934)
		(width 0.1143)
		(layer "In6.Cu")
		(net "P5E_CPU0_P2_RX_DN<15>")
	)
	(arc
		(start 373.559324 -283.101796)
		(mid 373.557301 -283.090386)
		(end 373.555514 -283.078936)
		(width 0.1143)
		(layer "In6.Cu")
		(net "P5E_CPU0_P2_RX_DN<15>")
	)
	(arc
		(start 396.445994 -347.570044)
		(mid 396.432431 -347.532391)
		(end 396.422626 -347.49359)
		(width 0.14224)
		(layer "In6.Cu")
		(net "P5E_CPU0_P2_RX_DN<15>")
	)
	(arc
		(start 375.42724 -286.194246)
		(mid 375.374855 -286.042978)
		(end 375.262648 -285.928816)
		(width 0.1143)
		(layer "In6.Cu")
		(net "P5E_CPU0_P2_RX_DN<15>")
	)
	(arc
		(start 374.489726 -287.856168)
		(mid 374.554544 -287.593179)
		(end 374.734328 -287.390586)
		(width 0.1143)
		(layer "In6.Cu")
		(net "P5E_CPU0_P2_RX_DN<15>")
	)
	(arc
		(start 374.731788 -288.320226)
		(mid 374.553834 -288.117891)
		(end 374.489726 -287.856168)
		(width 0.1143)
		(layer "In6.Cu")
		(net "P5E_CPU0_P2_RX_DN<15>")
	)
	(arc
		(start 374.80367 -290.58997)
		(mid 374.959497 -290.285932)
		(end 374.80367 -289.981894)
		(width 0.1143)
		(layer "In6.Cu")
		(net "P5E_CPU0_P2_RX_DN<15>")
	)
	(arc
		(start 428.10557 -377.607322)
		(mid 428.101541 -377.574157)
		(end 428.100236 -377.540774)
		(width 0.14224)
		(layer "In6.Cu")
		(net "P5E_CPU0_P2_RX_DN<15>")
	)
	(arc
		(start 374.732804 -285.08071)
		(mid 374.553991 -284.87836)
		(end 374.489472 -284.616144)
		(width 0.1143)
		(layer "In6.Cu")
		(net "P5E_CPU0_P2_RX_DN<15>")
	)
	(segment
		(start 372.707916 -284.350206)
		(end 373.174768 -284.616144)
		(width 0.12954)
		(layer "F.Cu")
		(net "P5E_CPU0_P2_RX_DN<14>")
	)
	(segment
		(start 419.698424 -393.69238)
		(end 420.219124 -393.69238)
		(width 0.127)
		(layer "F.Cu")
		(net "P5E_CPU0_P2_RX_DN<14>")
	)
	(segment
		(start 374.268238 -286.57804)
		(end 374.335294 -286.538924)
		(width 0.1143)
		(layer "In6.Cu")
		(net "P5E_CPU0_P2_RX_DN<14>")
	)
	(segment
		(start 374.876314 -297.608498)
		(end 374.534684 -296.783506)
		(width 0.14224)
		(layer "In6.Cu")
		(net "P5E_CPU0_P2_RX_DN<14>")
	)
	(segment
		(start 394.169392 -340.570312)
		(end 393.799822 -336.818732)
		(width 0.14224)
		(layer "In6.Cu")
		(net "P5E_CPU0_P2_RX_DN<14>")
	)
	(segment
		(start 420.717218 -391.000234)
		(end 420.940484 -390.460738)
		(width 0.14224)
		(layer "In6.Cu")
		(net "P5E_CPU0_P2_RX_DN<14>")
	)
	(segment
		(start 373.792242 -287.391602)
		(end 373.852948 -287.356296)
		(width 0.1143)
		(layer "In6.Cu")
		(net "P5E_CPU0_P2_RX_DN<14>")
	)
	(segment
		(start 373.848376 -288.352992)
		(end 373.848376 -288.353246)
		(width 0.1143)
		(layer "In6.Cu")
		(net "P5E_CPU0_P2_RX_DN<14>")
	)
	(segment
		(start 374.333516 -295.651936)
		(end 374.305068 -295.635172)
		(width 0.1143)
		(layer "In6.Cu")
		(net "P5E_CPU0_P2_RX_DN<14>")
	)
	(segment
		(start 383.768346 -309.0545)
		(end 377.074684 -300.898306)
		(width 0.14224)
		(layer "In6.Cu")
		(net "P5E_CPU0_P2_RX_DN<14>")
	)
	(segment
		(start 373.836184 -294.825674)
		(end 373.793512 -294.801036)
		(width 0.1143)
		(layer "In6.Cu")
		(net "P5E_CPU0_P2_RX_DN<14>")
	)
	(segment
		(start 420.940484 -390.460738)
		(end 420.866316 -390.281668)
		(width 0.14224)
		(layer "In6.Cu")
		(net "P5E_CPU0_P2_RX_DN<14>")
	)
	(segment
		(start 420.866316 -390.281668)
		(end 421.029638 -389.887206)
		(width 0.14224)
		(layer "In6.Cu")
		(net "P5E_CPU0_P2_RX_DN<14>")
	)
	(segment
		(start 421.029638 -389.887206)
		(end 421.209216 -389.812784)
		(width 0.14224)
		(layer "In6.Cu")
		(net "P5E_CPU0_P2_RX_DN<14>")
	)
	(segment
		(start 395.511528 -347.806264)
		(end 394.454634 -342.492076)
		(width 0.14224)
		(layer "In6.Cu")
		(net "P5E_CPU0_P2_RX_DN<14>")
	)
	(segment
		(start 421.209216 -389.812784)
		(end 421.372284 -389.418576)
		(width 0.14224)
		(layer "In6.Cu")
		(net "P5E_CPU0_P2_RX_DN<14>")
	)
	(segment
		(start 373.848376 -288.353246)
		(end 373.79275 -288.320734)
		(width 0.1143)
		(layer "In6.Cu")
		(net "P5E_CPU0_P2_RX_DN<14>")
	)
	(segment
		(start 373.79275 -290.631372)
		(end 373.843296 -290.601908)
		(width 0.1143)
		(layer "In6.Cu")
		(net "P5E_CPU0_P2_RX_DN<14>")
	)
	(segment
		(start 374.579896 -296.482516)
		(end 374.579896 -296.461942)
		(width 0.1143)
		(layer "In6.Cu")
		(net "P5E_CPU0_P2_RX_DN<14>")
	)
	(segment
		(start 420.68623 -392.31316)
		(end 420.68623 -391.156698)
		(width 0.14224)
		(layer "In6.Cu")
		(net "P5E_CPU0_P2_RX_DN<14>")
	)
	(segment
		(start 393.799822 -336.818732)
		(end 390.878822 -322.133722)
		(width 0.14224)
		(layer "In6.Cu")
		(net "P5E_CPU0_P2_RX_DN<14>")
	)
	(segment
		(start 373.831866 -292.228524)
		(end 373.863616 -292.210236)
		(width 0.1143)
		(layer "In6.Cu")
		(net "P5E_CPU0_P2_RX_DN<14>")
	)
	(segment
		(start 421.804084 -388.376414)
		(end 421.729916 -388.197344)
		(width 0.14224)
		(layer "In6.Cu")
		(net "P5E_CPU0_P2_RX_DN<14>")
	)
	(segment
		(start 373.79275 -293.871396)
		(end 373.843296 -293.841932)
		(width 0.1143)
		(layer "In6.Cu")
		(net "P5E_CPU0_P2_RX_DN<14>")
	)
	(segment
		(start 377.074684 -300.898306)
		(end 374.876314 -297.608498)
		(width 0.14224)
		(layer "In6.Cu")
		(net "P5E_CPU0_P2_RX_DN<14>")
	)
	(segment
		(start 373.843296 -293.20998)
		(end 373.83085 -293.202868)
		(width 0.1143)
		(layer "In6.Cu")
		(net "P5E_CPU0_P2_RX_DN<14>")
	)
	(segment
		(start 374.534684 -296.783506)
		(end 374.534684 -296.556684)
		(width 0.14224)
		(layer "In6.Cu")
		(net "P5E_CPU0_P2_RX_DN<14>")
	)
	(segment
		(start 373.47271 -284.616144)
		(end 373.174768 -284.616144)
		(width 0.1143)
		(layer "In6.Cu")
		(net "P5E_CPU0_P2_RX_DN<14>")
	)
	(segment
		(start 373.843296 -289.969956)
		(end 373.793512 -289.941254)
		(width 0.1143)
		(layer "In6.Cu")
		(net "P5E_CPU0_P2_RX_DN<14>")
	)
	(segment
		(start 374.302528 -285.914084)
		(end 374.301766 -285.913576)
		(width 0.1143)
		(layer "In6.Cu")
		(net "P5E_CPU0_P2_RX_DN<14>")
	)
	(segment
		(start 374.534684 -296.556684)
		(end 374.534176 -296.556176)
		(width 0.1143)
		(layer "In6.Cu")
		(net "P5E_CPU0_P2_RX_DN<14>")
	)
	(segment
		(start 373.862346 -288.36112)
		(end 373.848376 -288.352992)
		(width 0.1143)
		(layer "In6.Cu")
		(net "P5E_CPU0_P2_RX_DN<14>")
	)
	(segment
		(start 374.534176 -296.556176)
		(end 374.534176 -296.528236)
		(width 0.1143)
		(layer "In6.Cu")
		(net "P5E_CPU0_P2_RX_DN<14>")
	)
	(segment
		(start 427.167802 -378.80036)
		(end 427.167802 -377.454414)
		(width 0.14224)
		(layer "In6.Cu")
		(net "P5E_CPU0_P2_RX_DN<14>")
	)
	(segment
		(start 417.342066 -370.723668)
		(end 410.605732 -369.037616)
		(width 0.14224)
		(layer "In6.Cu")
		(net "P5E_CPU0_P2_RX_DN<14>")
	)
	(segment
		(start 424.803316 -381.217424)
		(end 427.130464 -378.890276)
		(width 0.14224)
		(layer "In6.Cu")
		(net "P5E_CPU0_P2_RX_DN<14>")
	)
	(segment
		(start 420.572692 -393.786868)
		(end 420.694358 -393.716764)
		(width 0.14224)
		(layer "In6.Cu")
		(net "P5E_CPU0_P2_RX_DN<14>")
	)
	(segment
		(start 373.83212 -291.588698)
		(end 373.829834 -291.587428)
		(width 0.1143)
		(layer "In6.Cu")
		(net "P5E_CPU0_P2_RX_DN<14>")
	)
	(segment
		(start 420.219124 -393.69238)
		(end 420.572184 -393.787376)
		(width 0.14224)
		(layer "In6.Cu")
		(net "P5E_CPU0_P2_RX_DN<14>")
	)
	(segment
		(start 395.588998 -348.06128)
		(end 395.589252 -348.06128)
		(width 0.14224)
		(layer "In6.Cu")
		(net "P5E_CPU0_P2_RX_DN<14>")
	)
	(segment
		(start 374.333516 -285.931864)
		(end 374.303798 -285.914846)
		(width 0.1143)
		(layer "In6.Cu")
		(net "P5E_CPU0_P2_RX_DN<14>")
	)
	(segment
		(start 420.694358 -393.545822)
		(end 420.377366 -393.22883)
		(width 0.14224)
		(layer "In6.Cu")
		(net "P5E_CPU0_P2_RX_DN<14>")
	)
	(segment
		(start 422.072562 -387.727952)
		(end 424.714416 -381.350774)
		(width 0.14224)
		(layer "In6.Cu")
		(net "P5E_CPU0_P2_RX_DN<14>")
	)
	(segment
		(start 426.440092 -375.69775)
		(end 426.34662 -375.604278)
		(width 0.14224)
		(layer "In6.Cu")
		(net "P5E_CPU0_P2_RX_DN<14>")
	)
	(segment
		(start 373.854472 -285.116778)
		(end 373.79275 -285.08071)
		(width 0.1143)
		(layer "In6.Cu")
		(net "P5E_CPU0_P2_RX_DN<14>")
	)
	(segment
		(start 374.301766 -285.913576)
		(end 374.263666 -285.891478)
		(width 0.1143)
		(layer "In6.Cu")
		(net "P5E_CPU0_P2_RX_DN<14>")
	)
	(segment
		(start 420.382192 -392.616944)
		(end 420.68623 -392.31316)
		(width 0.14224)
		(layer "In6.Cu")
		(net "P5E_CPU0_P2_RX_DN<14>")
	)
	(segment
		(start 421.640508 -388.76986)
		(end 421.80383 -388.376414)
		(width 0.14224)
		(layer "In6.Cu")
		(net "P5E_CPU0_P2_RX_DN<14>")
	)
	(segment
		(start 374.579896 -296.461942)
		(end 374.489726 -296.24401)
		(width 0.1143)
		(layer "In6.Cu")
		(net "P5E_CPU0_P2_RX_DN<14>")
	)
	(segment
		(start 402.890482 -364.649766)
		(end 402.23948 -363.99851)
		(width 0.14224)
		(layer "In6.Cu")
		(net "P5E_CPU0_P2_RX_DN<14>")
	)
	(segment
		(start 373.829834 -291.587428)
		(end 373.82958 -291.587174)
		(width 0.1143)
		(layer "In6.Cu")
		(net "P5E_CPU0_P2_RX_DN<14>")
	)
	(segment
		(start 373.79275 -292.251384)
		(end 373.831866 -292.228524)
		(width 0.1143)
		(layer "In6.Cu")
		(net "P5E_CPU0_P2_RX_DN<14>")
	)
	(segment
		(start 421.298116 -389.239506)
		(end 421.461438 -388.845044)
		(width 0.14224)
		(layer "In6.Cu")
		(net "P5E_CPU0_P2_RX_DN<14>")
	)
	(segment
		(start 426.34662 -375.604278)
		(end 424.83913 -374.203722)
		(width 0.14224)
		(layer "In6.Cu")
		(net "P5E_CPU0_P2_RX_DN<14>")
	)
	(segment
		(start 421.893238 -387.802882)
		(end 422.072816 -387.72846)
		(width 0.14224)
		(layer "In6.Cu")
		(net "P5E_CPU0_P2_RX_DN<14>")
	)
	(segment
		(start 421.729916 -388.197344)
		(end 421.893238 -387.802882)
		(width 0.14224)
		(layer "In6.Cu")
		(net "P5E_CPU0_P2_RX_DN<14>")
	)
	(segment
		(start 390.878822 -322.133722)
		(end 384.366262 -309.949342)
		(width 0.14224)
		(layer "In6.Cu")
		(net "P5E_CPU0_P2_RX_DN<14>")
	)
	(segment
		(start 420.694358 -393.716764)
		(end 420.694358 -393.545822)
		(width 0.14224)
		(layer "In6.Cu")
		(net "P5E_CPU0_P2_RX_DN<14>")
	)
	(segment
		(start 421.80383 -388.376414)
		(end 421.804084 -388.376414)
		(width 0.14224)
		(layer "In6.Cu")
		(net "P5E_CPU0_P2_RX_DN<14>")
	)
	(segment
		(start 420.377366 -393.22883)
		(end 420.382192 -392.616944)
		(width 0.14224)
		(layer "In6.Cu")
		(net "P5E_CPU0_P2_RX_DN<14>")
	)
	(segment
		(start 420.572184 -393.787376)
		(end 420.572692 -393.786868)
		(width 0.14224)
		(layer "In6.Cu")
		(net "P5E_CPU0_P2_RX_DN<14>")
	)
	(segment
		(start 422.072816 -387.72846)
		(end 422.072308 -387.728206)
		(width 0.14224)
		(layer "In6.Cu")
		(net "P5E_CPU0_P2_RX_DN<14>")
	)
	(segment
		(start 421.461438 -388.845044)
		(end 421.641016 -388.770622)
		(width 0.14224)
		(layer "In6.Cu")
		(net "P5E_CPU0_P2_RX_DN<14>")
	)
	(segment
		(start 402.11121 -363.80674)
		(end 395.588998 -348.06128)
		(width 0.14224)
		(layer "In6.Cu")
		(net "P5E_CPU0_P2_RX_DN<14>")
	)
	(segment
		(start 421.641016 -388.770622)
		(end 421.640508 -388.76986)
		(width 0.14224)
		(layer "In6.Cu")
		(net "P5E_CPU0_P2_RX_DN<14>")
	)
	(segment
		(start 424.83913 -374.203722)
		(end 421.313864 -372.09095)
		(width 0.14224)
		(layer "In6.Cu")
		(net "P5E_CPU0_P2_RX_DN<14>")
	)
	(segment
		(start 373.555514 -284.698948)
		(end 373.47271 -284.616144)
		(width 0.1143)
		(layer "In6.Cu")
		(net "P5E_CPU0_P2_RX_DN<14>")
	)
	(segment
		(start 421.372284 -389.418576)
		(end 421.298116 -389.239506)
		(width 0.14224)
		(layer "In6.Cu")
		(net "P5E_CPU0_P2_RX_DN<14>")
	)
	(segment
		(start 374.303798 -285.914846)
		(end 374.302528 -285.914084)
		(width 0.1143)
		(layer "In6.Cu")
		(net "P5E_CPU0_P2_RX_DN<14>")
	)
	(segment
		(start 421.313864 -372.09095)
		(end 417.342066 -370.723668)
		(width 0.14224)
		(layer "In6.Cu")
		(net "P5E_CPU0_P2_RX_DN<14>")
	)
	(segment
		(start 373.83085 -293.202868)
		(end 373.828564 -293.201344)
		(width 0.1143)
		(layer "In6.Cu")
		(net "P5E_CPU0_P2_RX_DN<14>")
	)
	(segment
		(start 384.366262 -309.949342)
		(end 383.768346 -309.0545)
		(width 0.14224)
		(layer "In6.Cu")
		(net "P5E_CPU0_P2_RX_DN<14>")
	)
	(segment
		(start 422.072308 -387.728206)
		(end 422.072562 -387.727952)
		(width 0.14224)
		(layer "In6.Cu")
		(net "P5E_CPU0_P2_RX_DN<14>")
	)
	(segment
		(start 374.265444 -286.579564)
		(end 374.268238 -286.57804)
		(width 0.1143)
		(layer "In6.Cu")
		(net "P5E_CPU0_P2_RX_DN<14>")
	)
	(segment
		(start 374.534176 -296.528236)
		(end 374.579896 -296.482516)
		(width 0.1143)
		(layer "In6.Cu")
		(net "P5E_CPU0_P2_RX_DN<14>")
	)
	(segment
		(start 424.714416 -381.350774)
		(end 424.714416 -381.350266)
		(width 0.14224)
		(layer "In6.Cu")
		(net "P5E_CPU0_P2_RX_DN<14>")
	)
	(segment
		(start 374.489726 -296.24401)
		(end 374.489726 -295.956228)
		(width 0.1143)
		(layer "In6.Cu")
		(net "P5E_CPU0_P2_RX_DN<14>")
	)
	(segment
		(start 373.828564 -293.201344)
		(end 373.793512 -293.181024)
		(width 0.1143)
		(layer "In6.Cu")
		(net "P5E_CPU0_P2_RX_DN<14>")
	)
	(segment
		(start 410.605732 -369.037616)
		(end 402.978112 -364.716568)
		(width 0.14224)
		(layer "In6.Cu")
		(net "P5E_CPU0_P2_RX_DN<14>")
	)
	(arc
		(start 373.843296 -290.601908)
		(mid 374.018246 -290.285932)
		(end 373.843296 -289.969956)
		(width 0.1143)
		(layer "In6.Cu")
		(net "P5E_CPU0_P2_RX_DN<14>")
	)
	(arc
		(start 374.01754 -287.055306)
		(mid 374.018852 -287.043393)
		(end 374.019572 -287.03143)
		(width 0.1143)
		(layer "In6.Cu")
		(net "P5E_CPU0_P2_RX_DN<14>")
	)
	(arc
		(start 394.454634 -342.492076)
		(mid 394.288438 -341.534693)
		(end 394.169392 -340.570312)
		(width 0.14224)
		(layer "In6.Cu")
		(net "P5E_CPU0_P2_RX_DN<14>")
	)
	(arc
		(start 373.836946 -288.987992)
		(mid 374.019242 -288.681393)
		(end 373.862346 -288.36112)
		(width 0.1143)
		(layer "In6.Cu")
		(net "P5E_CPU0_P2_RX_DN<14>")
	)
	(arc
		(start 373.863616 -292.210236)
		(mid 374.017348 -291.890823)
		(end 373.83212 -291.588698)
		(width 0.1143)
		(layer "In6.Cu")
		(net "P5E_CPU0_P2_RX_DN<14>")
	)
	(arc
		(start 427.130464 -378.890276)
		(mid 427.158083 -378.849036)
		(end 427.167802 -378.80036)
		(width 0.14224)
		(layer "In6.Cu")
		(net "P5E_CPU0_P2_RX_DN<14>")
	)
	(arc
		(start 374.020842 -295.14673)
		(mid 373.971378 -294.961554)
		(end 373.836184 -294.825674)
		(width 0.1143)
		(layer "In6.Cu")
		(net "P5E_CPU0_P2_RX_DN<14>")
	)
	(arc
		(start 427.167802 -377.454414)
		(mid 426.978675 -376.503699)
		(end 426.440092 -375.69775)
		(width 0.14224)
		(layer "In6.Cu")
		(net "P5E_CPU0_P2_RX_DN<14>")
	)
	(arc
		(start 373.843296 -293.841932)
		(mid 374.018246 -293.525956)
		(end 373.843296 -293.20998)
		(width 0.1143)
		(layer "In6.Cu")
		(net "P5E_CPU0_P2_RX_DN<14>")
	)
	(arc
		(start 373.852948 -287.356296)
		(mid 373.962414 -287.220656)
		(end 374.01754 -287.055306)
		(width 0.1143)
		(layer "In6.Cu")
		(net "P5E_CPU0_P2_RX_DN<14>")
	)
	(arc
		(start 374.019572 -287.03143)
		(mid 374.084279 -286.783048)
		(end 374.252236 -286.588962)
		(width 0.1143)
		(layer "In6.Cu")
		(net "P5E_CPU0_P2_RX_DN<14>")
	)
	(arc
		(start 402.978112 -364.716568)
		(mid 402.932033 -364.686136)
		(end 402.890482 -364.649766)
		(width 0.14224)
		(layer "In6.Cu")
		(net "P5E_CPU0_P2_RX_DN<14>")
	)
	(arc
		(start 373.79275 -285.08071)
		(mid 373.640763 -284.924202)
		(end 373.559324 -284.721808)
		(width 0.1143)
		(layer "In6.Cu")
		(net "P5E_CPU0_P2_RX_DN<14>")
	)
	(arc
		(start 373.79275 -288.320734)
		(mid 373.613937 -288.118384)
		(end 373.549418 -287.856168)
		(width 0.1143)
		(layer "In6.Cu")
		(net "P5E_CPU0_P2_RX_DN<14>")
	)
	(arc
		(start 374.017286 -285.416498)
		(mid 373.962603 -285.252121)
		(end 373.854472 -285.116778)
		(width 0.1143)
		(layer "In6.Cu")
		(net "P5E_CPU0_P2_RX_DN<14>")
	)
	(arc
		(start 374.335294 -286.538924)
		(mid 374.448701 -286.406035)
		(end 374.489472 -286.236156)
		(width 0.1143)
		(layer "In6.Cu")
		(net "P5E_CPU0_P2_RX_DN<14>")
	)
	(arc
		(start 374.019318 -285.446216)
		(mid 374.018745 -285.431327)
		(end 374.017286 -285.416498)
		(width 0.1143)
		(layer "In6.Cu")
		(net "P5E_CPU0_P2_RX_DN<14>")
	)
	(arc
		(start 373.79275 -294.800528)
		(mid 373.549423 -294.335962)
		(end 373.79275 -293.871396)
		(width 0.1143)
		(layer "In6.Cu")
		(net "P5E_CPU0_P2_RX_DN<14>")
	)
	(arc
		(start 374.305068 -295.635172)
		(mid 374.097085 -295.429284)
		(end 374.020842 -295.14673)
		(width 0.1143)
		(layer "In6.Cu")
		(net "P5E_CPU0_P2_RX_DN<14>")
	)
	(arc
		(start 424.714416 -381.350266)
		(mid 424.752308 -381.279454)
		(end 424.803316 -381.217424)
		(width 0.14224)
		(layer "In6.Cu")
		(net "P5E_CPU0_P2_RX_DN<14>")
	)
	(arc
		(start 373.559324 -284.721808)
		(mid 373.557301 -284.710398)
		(end 373.555514 -284.698948)
		(width 0.1143)
		(layer "In6.Cu")
		(net "P5E_CPU0_P2_RX_DN<14>")
	)
	(arc
		(start 395.589252 -348.06128)
		(mid 395.54412 -347.935683)
		(end 395.511528 -347.806264)
		(width 0.14224)
		(layer "In6.Cu")
		(net "P5E_CPU0_P2_RX_DN<14>")
	)
	(arc
		(start 374.489472 -286.236156)
		(mid 374.448217 -286.065185)
		(end 374.333516 -285.931864)
		(width 0.1143)
		(layer "In6.Cu")
		(net "P5E_CPU0_P2_RX_DN<14>")
	)
	(arc
		(start 373.79275 -293.180516)
		(mid 373.549423 -292.71595)
		(end 373.79275 -292.251384)
		(width 0.1143)
		(layer "In6.Cu")
		(net "P5E_CPU0_P2_RX_DN<14>")
	)
	(arc
		(start 373.549418 -287.856168)
		(mid 373.613797 -287.594084)
		(end 373.792242 -287.391602)
		(width 0.1143)
		(layer "In6.Cu")
		(net "P5E_CPU0_P2_RX_DN<14>")
	)
	(arc
		(start 373.82958 -291.587174)
		(mid 373.54902 -291.119341)
		(end 373.79275 -290.631372)
		(width 0.1143)
		(layer "In6.Cu")
		(net "P5E_CPU0_P2_RX_DN<14>")
	)
	(arc
		(start 373.793512 -293.181024)
		(mid 373.793131 -293.18077)
		(end 373.79275 -293.180516)
		(width 0.1143)
		(layer "In6.Cu")
		(net "P5E_CPU0_P2_RX_DN<14>")
	)
	(arc
		(start 373.793512 -289.941254)
		(mid 373.551146 -289.452594)
		(end 373.836946 -288.987992)
		(width 0.1143)
		(layer "In6.Cu")
		(net "P5E_CPU0_P2_RX_DN<14>")
	)
	(arc
		(start 373.793512 -294.801036)
		(mid 373.793131 -294.800782)
		(end 373.79275 -294.800528)
		(width 0.1143)
		(layer "In6.Cu")
		(net "P5E_CPU0_P2_RX_DN<14>")
	)
	(arc
		(start 374.263666 -285.891478)
		(mid 374.08873 -285.697804)
		(end 374.019318 -285.446216)
		(width 0.1143)
		(layer "In6.Cu")
		(net "P5E_CPU0_P2_RX_DN<14>")
	)
	(arc
		(start 374.489726 -295.956228)
		(mid 374.448405 -295.785189)
		(end 374.333516 -295.651936)
		(width 0.1143)
		(layer "In6.Cu")
		(net "P5E_CPU0_P2_RX_DN<14>")
	)
	(arc
		(start 420.68623 -391.156698)
		(mid 420.694023 -391.07694)
		(end 420.717218 -391.000234)
		(width 0.14224)
		(layer "In6.Cu")
		(net "P5E_CPU0_P2_RX_DN<14>")
	)
	(arc
		(start 374.252236 -286.588962)
		(mid 374.258806 -286.584215)
		(end 374.265444 -286.579564)
		(width 0.1143)
		(layer "In6.Cu")
		(net "P5E_CPU0_P2_RX_DN<14>")
	)
	(arc
		(start 402.23948 -363.99851)
		(mid 402.165889 -363.908948)
		(end 402.11121 -363.80674)
		(width 0.14224)
		(layer "In6.Cu")
		(net "P5E_CPU0_P2_RX_DN<14>")
	)
	(segment
		(start 418.498274 -393.69238)
		(end 419.018974 -393.69238)
		(width 0.127)
		(layer "F.Cu")
		(net "P5E_CPU0_P2_RX_DN<13>")
	)
	(segment
		(start 372.707916 -281.110182)
		(end 373.174768 -281.37612)
		(width 0.12954)
		(layer "F.Cu")
		(net "P5E_CPU0_P2_RX_DN<13>")
	)
	(segment
		(start 372.893844 -293.847266)
		(end 372.923562 -293.830248)
		(width 0.1143)
		(layer "In6.Cu")
		(net "P5E_CPU0_P2_RX_DN<13>")
	)
	(segment
		(start 372.892574 -293.203884)
		(end 372.891812 -293.203376)
		(width 0.1143)
		(layer "In6.Cu")
		(net "P5E_CPU0_P2_RX_DN<13>")
	)
	(segment
		(start 389.932164 -322.347082)
		(end 383.663952 -310.621426)
		(width 0.14224)
		(layer "In6.Cu")
		(net "P5E_CPU0_P2_RX_DN<13>")
	)
	(segment
		(start 373.32285 -286.581342)
		(end 373.361966 -286.558482)
		(width 0.1143)
		(layer "In6.Cu")
		(net "P5E_CPU0_P2_RX_DN<13>")
	)
	(segment
		(start 372.923562 -285.121858)
		(end 372.893844 -285.10484)
		(width 0.1143)
		(layer "In6.Cu")
		(net "P5E_CPU0_P2_RX_DN<13>")
	)
	(segment
		(start 372.893844 -288.98723)
		(end 372.923562 -288.970212)
		(width 0.1143)
		(layer "In6.Cu")
		(net "P5E_CPU0_P2_RX_DN<13>")
	)
	(segment
		(start 409.125166 -369.289584)
		(end 408.753818 -369.079526)
		(width 0.14224)
		(layer "In6.Cu")
		(net "P5E_CPU0_P2_RX_DN<13>")
	)
	(segment
		(start 372.923562 -294.841676)
		(end 372.893844 -294.824658)
		(width 0.1143)
		(layer "In6.Cu")
		(net "P5E_CPU0_P2_RX_DN<13>")
	)
	(segment
		(start 372.890796 -293.849044)
		(end 372.891812 -293.848536)
		(width 0.1143)
		(layer "In6.Cu")
		(net "P5E_CPU0_P2_RX_DN<13>")
	)
	(segment
		(start 372.923562 -291.601652)
		(end 372.893844 -291.584634)
		(width 0.1143)
		(layer "In6.Cu")
		(net "P5E_CPU0_P2_RX_DN<13>")
	)
	(segment
		(start 373.50446 -296.486072)
		(end 373.503952 -296.486072)
		(width 0.14224)
		(layer "In6.Cu")
		(net "P5E_CPU0_P2_RX_DN<13>")
	)
	(segment
		(start 408.753818 -369.079526)
		(end 408.567128 -369.131342)
		(width 0.14224)
		(layer "In6.Cu")
		(net "P5E_CPU0_P2_RX_DN<13>")
	)
	(segment
		(start 372.891812 -282.508706)
		(end 372.892574 -282.508198)
		(width 0.1143)
		(layer "In6.Cu")
		(net "P5E_CPU0_P2_RX_DN<13>")
	)
	(segment
		(start 372.893844 -294.824658)
		(end 372.892574 -294.823896)
		(width 0.1143)
		(layer "In6.Cu")
		(net "P5E_CPU0_P2_RX_DN<13>")
	)
	(segment
		(start 410.106622 -369.845336)
		(end 409.735274 -369.635278)
		(width 0.14224)
		(layer "In6.Cu")
		(net "P5E_CPU0_P2_RX_DN<13>")
	)
	(segment
		(start 419.182296 -392.616944)
		(end 419.486334 -392.312906)
		(width 0.14224)
		(layer "In6.Cu")
		(net "P5E_CPU0_P2_RX_DN<13>")
	)
	(segment
		(start 372.889272 -292.230048)
		(end 372.890796 -292.229032)
		(width 0.1143)
		(layer "In6.Cu")
		(net "P5E_CPU0_P2_RX_DN<13>")
	)
	(segment
		(start 372.889272 -290.610036)
		(end 372.890796 -290.60902)
		(width 0.1143)
		(layer "In6.Cu")
		(net "P5E_CPU0_P2_RX_DN<13>")
	)
	(segment
		(start 372.889272 -291.58184)
		(end 372.888256 -291.581332)
		(width 0.1143)
		(layer "In6.Cu")
		(net "P5E_CPU0_P2_RX_DN<13>")
	)
	(segment
		(start 372.88343 -291.578538)
		(end 372.881906 -291.577522)
		(width 0.1143)
		(layer "In6.Cu")
		(net "P5E_CPU0_P2_RX_DN<13>")
	)
	(segment
		(start 382.90119 -309.47995)
		(end 376.363992 -301.51451)
		(width 0.14224)
		(layer "In6.Cu")
		(net "P5E_CPU0_P2_RX_DN<13>")
	)
	(segment
		(start 407.771854 -368.523774)
		(end 407.585164 -368.57559)
		(width 0.14224)
		(layer "In6.Cu")
		(net "P5E_CPU0_P2_RX_DN<13>")
	)
	(segment
		(start 372.881906 -285.097728)
		(end 372.88089 -285.09722)
		(width 0.1143)
		(layer "In6.Cu")
		(net "P5E_CPU0_P2_RX_DN<13>")
	)
	(segment
		(start 372.892574 -294.823896)
		(end 372.891812 -294.823388)
		(width 0.1143)
		(layer "In6.Cu")
		(net "P5E_CPU0_P2_RX_DN<13>")
	)
	(segment
		(start 373.549672 -296.298366)
		(end 373.549672 -295.955974)
		(width 0.1143)
		(layer "In6.Cu")
		(net "P5E_CPU0_P2_RX_DN<13>")
	)
	(segment
		(start 373.361966 -286.558482)
		(end 373.394478 -286.539686)
		(width 0.1143)
		(layer "In6.Cu")
		(net "P5E_CPU0_P2_RX_DN<13>")
	)
	(segment
		(start 372.890796 -285.103062)
		(end 372.889272 -285.102046)
		(width 0.1143)
		(layer "In6.Cu")
		(net "P5E_CPU0_P2_RX_DN<13>")
	)
	(segment
		(start 373.392446 -295.651174)
		(end 373.361966 -295.633394)
		(width 0.1143)
		(layer "In6.Cu")
		(net "P5E_CPU0_P2_RX_DN<13>")
	)
	(segment
		(start 372.891812 -285.10357)
		(end 372.890796 -285.103062)
		(width 0.1143)
		(layer "In6.Cu")
		(net "P5E_CPU0_P2_RX_DN<13>")
	)
	(segment
		(start 372.890796 -291.582856)
		(end 372.889272 -291.58184)
		(width 0.1143)
		(layer "In6.Cu")
		(net "P5E_CPU0_P2_RX_DN<13>")
	)
	(segment
		(start 372.888256 -285.101538)
		(end 372.88343 -285.098744)
		(width 0.1143)
		(layer "In6.Cu")
		(net "P5E_CPU0_P2_RX_DN<13>")
	)
	(segment
		(start 372.891812 -288.343594)
		(end 372.852696 -288.320734)
		(width 0.1143)
		(layer "In6.Cu")
		(net "P5E_CPU0_P2_RX_DN<13>")
	)
	(segment
		(start 372.892574 -284.12821)
		(end 372.893844 -284.127448)
		(width 0.1143)
		(layer "In6.Cu")
		(net "P5E_CPU0_P2_RX_DN<13>")
	)
	(segment
		(start 372.891812 -291.583364)
		(end 372.890796 -291.582856)
		(width 0.1143)
		(layer "In6.Cu")
		(net "P5E_CPU0_P2_RX_DN<13>")
	)
	(segment
		(start 372.88089 -283.477208)
		(end 372.852696 -283.460698)
		(width 0.1143)
		(layer "In6.Cu")
		(net "P5E_CPU0_P2_RX_DN<13>")
	)
	(segment
		(start 373.361966 -281.6987)
		(end 373.392446 -281.68092)
		(width 0.1143)
		(layer "In6.Cu")
		(net "P5E_CPU0_P2_RX_DN<13>")
	)
	(segment
		(start 372.893844 -285.10484)
		(end 372.892574 -285.104078)
		(width 0.1143)
		(layer "In6.Cu")
		(net "P5E_CPU0_P2_RX_DN<13>")
	)
	(segment
		(start 409.176728 -369.476782)
		(end 409.125166 -369.289584)
		(width 0.14224)
		(layer "In6.Cu")
		(net "P5E_CPU0_P2_RX_DN<13>")
	)
	(segment
		(start 372.890796 -289.962844)
		(end 372.852696 -289.940492)
		(width 0.1143)
		(layer "In6.Cu")
		(net "P5E_CPU0_P2_RX_DN<13>")
	)
	(segment
		(start 419.018974 -393.69238)
		(end 419.372288 -393.787376)
		(width 0.14224)
		(layer "In6.Cu")
		(net "P5E_CPU0_P2_RX_DN<13>")
	)
	(segment
		(start 408.143456 -368.733832)
		(end 408.143202 -368.733832)
		(width 0.14224)
		(layer "In6.Cu")
		(net "P5E_CPU0_P2_RX_DN<13>")
	)
	(segment
		(start 408.567128 -369.131342)
		(end 408.195272 -368.92103)
		(width 0.14224)
		(layer "In6.Cu")
		(net "P5E_CPU0_P2_RX_DN<13>")
	)
	(segment
		(start 417.427918 -371.813074)
		(end 417.428172 -371.813074)
		(width 0.14224)
		(layer "In6.Cu")
		(net "P5E_CPU0_P2_RX_DN<13>")
	)
	(segment
		(start 372.889272 -293.85006)
		(end 372.890796 -293.849044)
		(width 0.1143)
		(layer "In6.Cu")
		(net "P5E_CPU0_P2_RX_DN<13>")
	)
	(segment
		(start 372.890796 -294.82288)
		(end 372.889272 -294.821864)
		(width 0.1143)
		(layer "In6.Cu")
		(net "P5E_CPU0_P2_RX_DN<13>")
	)
	(segment
		(start 372.855236 -287.389824)
		(end 372.891812 -287.368488)
		(width 0.1143)
		(layer "In6.Cu")
		(net "P5E_CPU0_P2_RX_DN<13>")
	)
	(segment
		(start 372.893844 -290.607242)
		(end 372.923562 -290.590224)
		(width 0.1143)
		(layer "In6.Cu")
		(net "P5E_CPU0_P2_RX_DN<13>")
	)
	(segment
		(start 372.891812 -292.228524)
		(end 372.892574 -292.228016)
		(width 0.1143)
		(layer "In6.Cu")
		(net "P5E_CPU0_P2_RX_DN<13>")
	)
	(segment
		(start 372.891812 -289.963352)
		(end 372.890796 -289.962844)
		(width 0.1143)
		(layer "In6.Cu")
		(net "P5E_CPU0_P2_RX_DN<13>")
	)
	(segment
		(start 373.361966 -285.913576)
		(end 373.32285 -285.890716)
		(width 0.1143)
		(layer "In6.Cu")
		(net "P5E_CPU0_P2_RX_DN<13>")
	)
	(segment
		(start 373.361966 -295.633394)
		(end 373.361712 -295.633394)
		(width 0.1143)
		(layer "In6.Cu")
		(net "P5E_CPU0_P2_RX_DN<13>")
	)
	(segment
		(start 372.891812 -283.483558)
		(end 372.890796 -283.48305)
		(width 0.1143)
		(layer "In6.Cu")
		(net "P5E_CPU0_P2_RX_DN<13>")
	)
	(segment
		(start 372.893844 -283.484828)
		(end 372.892574 -283.484066)
		(width 0.1143)
		(layer "In6.Cu")
		(net "P5E_CPU0_P2_RX_DN<13>")
	)
	(segment
		(start 401.320762 -364.39475)
		(end 394.791184 -348.631002)
		(width 0.14224)
		(layer "In6.Cu")
		(net "P5E_CPU0_P2_RX_DN<13>")
	)
	(segment
		(start 373.32285 -281.72156)
		(end 373.361966 -281.6987)
		(width 0.1143)
		(layer "In6.Cu")
		(net "P5E_CPU0_P2_RX_DN<13>")
	)
	(segment
		(start 372.892574 -293.848028)
		(end 372.893844 -293.847266)
		(width 0.1143)
		(layer "In6.Cu")
		(net "P5E_CPU0_P2_RX_DN<13>")
	)
	(segment
		(start 372.891812 -284.128718)
		(end 372.892574 -284.12821)
		(width 0.1143)
		(layer "In6.Cu")
		(net "P5E_CPU0_P2_RX_DN<13>")
	)
	(segment
		(start 372.893844 -291.584634)
		(end 372.892574 -291.583872)
		(width 0.1143)
		(layer "In6.Cu")
		(net "P5E_CPU0_P2_RX_DN<13>")
	)
	(segment
		(start 372.889272 -285.102046)
		(end 372.888256 -285.101538)
		(width 0.1143)
		(layer "In6.Cu")
		(net "P5E_CPU0_P2_RX_DN<13>")
	)
	(segment
		(start 372.888256 -291.581332)
		(end 372.88343 -291.578538)
		(width 0.1143)
		(layer "In6.Cu")
		(net "P5E_CPU0_P2_RX_DN<13>")
	)
	(segment
		(start 372.88089 -294.817038)
		(end 372.852696 -294.800528)
		(width 0.1143)
		(layer "In6.Cu")
		(net "P5E_CPU0_P2_RX_DN<13>")
	)
	(segment
		(start 372.852696 -290.631372)
		(end 372.889272 -290.610036)
		(width 0.1143)
		(layer "In6.Cu")
		(net "P5E_CPU0_P2_RX_DN<13>")
	)
	(segment
		(start 372.891812 -293.848536)
		(end 372.892574 -293.848028)
		(width 0.1143)
		(layer "In6.Cu")
		(net "P5E_CPU0_P2_RX_DN<13>")
	)
	(segment
		(start 372.889272 -284.130242)
		(end 372.890796 -284.129226)
		(width 0.1143)
		(layer "In6.Cu")
		(net "P5E_CPU0_P2_RX_DN<13>")
	)
	(segment
		(start 372.893844 -282.507436)
		(end 372.923562 -282.490418)
		(width 0.1143)
		(layer "In6.Cu")
		(net "P5E_CPU0_P2_RX_DN<13>")
	)
	(segment
		(start 372.923562 -283.501846)
		(end 372.893844 -283.484828)
		(width 0.1143)
		(layer "In6.Cu")
		(net "P5E_CPU0_P2_RX_DN<13>")
	)
	(segment
		(start 372.852696 -282.531566)
		(end 372.889272 -282.51023)
		(width 0.1143)
		(layer "In6.Cu")
		(net "P5E_CPU0_P2_RX_DN<13>")
	)
	(segment
		(start 373.503952 -296.372534)
		(end 373.503952 -296.344086)
		(width 0.1143)
		(layer "In6.Cu")
		(net "P5E_CPU0_P2_RX_DN<13>")
	)
	(segment
		(start 372.891812 -290.608512)
		(end 372.892574 -290.608004)
		(width 0.1143)
		(layer "In6.Cu")
		(net "P5E_CPU0_P2_RX_DN<13>")
	)
	(segment
		(start 372.893844 -293.204646)
		(end 372.892574 -293.203884)
		(width 0.1143)
		(layer "In6.Cu")
		(net "P5E_CPU0_P2_RX_DN<13>")
	)
	(segment
		(start 423.81932 -380.64948)
		(end 426.184822 -378.283978)
		(width 0.14224)
		(layer "In6.Cu")
		(net "P5E_CPU0_P2_RX_DN<13>")
	)
	(segment
		(start 376.363992 -301.51451)
		(end 374.051576 -298.05376)
		(width 0.14224)
		(layer "In6.Cu")
		(net "P5E_CPU0_P2_RX_DN<13>")
	)
	(segment
		(start 372.888256 -294.821356)
		(end 372.88343 -294.818562)
		(width 0.1143)
		(layer "In6.Cu")
		(net "P5E_CPU0_P2_RX_DN<13>")
	)
	(segment
		(start 372.881906 -291.577522)
		(end 372.88089 -291.577014)
		(width 0.1143)
		(layer "In6.Cu")
		(net "P5E_CPU0_P2_RX_DN<13>")
	)
	(segment
		(start 426.22216 -378.194062)
		(end 426.22216 -377.36145)
		(width 0.14224)
		(layer "In6.Cu")
		(net "P5E_CPU0_P2_RX_DN<13>")
	)
	(segment
		(start 372.88343 -283.478732)
		(end 372.881906 -283.477716)
		(width 0.1143)
		(layer "In6.Cu")
		(net "P5E_CPU0_P2_RX_DN<13>")
	)
	(segment
		(start 373.503952 -296.486072)
		(end 373.503952 -296.372534)
		(width 0.14224)
		(layer "In6.Cu")
		(net "P5E_CPU0_P2_RX_DN<13>")
	)
	(segment
		(start 372.893844 -284.127448)
		(end 372.923562 -284.11043)
		(width 0.1143)
		(layer "In6.Cu")
		(net "P5E_CPU0_P2_RX_DN<13>")
	)
	(segment
		(start 393.282424 -341.456518)
		(end 392.815318 -336.717894)
		(width 0.14224)
		(layer "In6.Cu")
		(net "P5E_CPU0_P2_RX_DN<13>")
	)
	(segment
		(start 372.852696 -292.251384)
		(end 372.889272 -292.230048)
		(width 0.1143)
		(layer "In6.Cu")
		(net "P5E_CPU0_P2_RX_DN<13>")
	)
	(segment
		(start 373.392446 -285.931356)
		(end 373.361966 -285.913576)
		(width 0.1143)
		(layer "In6.Cu")
		(net "P5E_CPU0_P2_RX_DN<13>")
	)
	(segment
		(start 419.625272 -390.564878)
		(end 423.590974 -380.990856)
		(width 0.14224)
		(layer "In6.Cu")
		(net "P5E_CPU0_P2_RX_DN<13>")
	)
	(segment
		(start 372.891812 -288.9885)
		(end 372.892574 -288.987992)
		(width 0.1143)
		(layer "In6.Cu")
		(net "P5E_CPU0_P2_RX_DN<13>")
	)
	(segment
		(start 372.892574 -291.583872)
		(end 372.891812 -291.583364)
		(width 0.1143)
		(layer "In6.Cu")
		(net "P5E_CPU0_P2_RX_DN<13>")
	)
	(segment
		(start 372.890796 -293.202868)
		(end 372.852696 -293.180516)
		(width 0.1143)
		(layer "In6.Cu")
		(net "P5E_CPU0_P2_RX_DN<13>")
	)
	(segment
		(start 372.923562 -293.221664)
		(end 372.893844 -293.204646)
		(width 0.1143)
		(layer "In6.Cu")
		(net "P5E_CPU0_P2_RX_DN<13>")
	)
	(segment
		(start 402.182584 -365.30026)
		(end 401.409662 -364.527338)
		(width 0.14224)
		(layer "In6.Cu")
		(net "P5E_CPU0_P2_RX_DN<13>")
	)
	(segment
		(start 372.88089 -285.09722)
		(end 372.852696 -285.08071)
		(width 0.1143)
		(layer "In6.Cu")
		(net "P5E_CPU0_P2_RX_DN<13>")
	)
	(segment
		(start 372.892574 -283.484066)
		(end 372.891812 -283.483558)
		(width 0.1143)
		(layer "In6.Cu")
		(net "P5E_CPU0_P2_RX_DN<13>")
	)
	(segment
		(start 372.890796 -283.48305)
		(end 372.889272 -283.482034)
		(width 0.1143)
		(layer "In6.Cu")
		(net "P5E_CPU0_P2_RX_DN<13>")
	)
	(segment
		(start 407.161492 -368.17808)
		(end 407.161238 -368.17808)
		(width 0.14224)
		(layer "In6.Cu")
		(net "P5E_CPU0_P2_RX_DN<13>")
	)
	(segment
		(start 419.17747 -393.22883)
		(end 419.182296 -392.616944)
		(width 0.14224)
		(layer "In6.Cu")
		(net "P5E_CPU0_P2_RX_DN<13>")
	)
	(segment
		(start 372.88343 -285.098744)
		(end 372.881906 -285.097728)
		(width 0.1143)
		(layer "In6.Cu")
		(net "P5E_CPU0_P2_RX_DN<13>")
	)
	(segment
		(start 372.889272 -294.821864)
		(end 372.888256 -294.821356)
		(width 0.1143)
		(layer "In6.Cu")
		(net "P5E_CPU0_P2_RX_DN<13>")
	)
	(segment
		(start 372.881906 -294.817546)
		(end 372.88089 -294.817038)
		(width 0.1143)
		(layer "In6.Cu")
		(net "P5E_CPU0_P2_RX_DN<13>")
	)
	(segment
		(start 372.892574 -292.228016)
		(end 372.893844 -292.227254)
		(width 0.1143)
		(layer "In6.Cu")
		(net "P5E_CPU0_P2_RX_DN<13>")
	)
	(segment
		(start 372.891812 -293.203376)
		(end 372.890796 -293.202868)
		(width 0.1143)
		(layer "In6.Cu")
		(net "P5E_CPU0_P2_RX_DN<13>")
	)
	(segment
		(start 372.889272 -282.51023)
		(end 372.890796 -282.509214)
		(width 0.1143)
		(layer "In6.Cu")
		(net "P5E_CPU0_P2_RX_DN<13>")
	)
	(segment
		(start 373.54256 -281.44597)
		(end 373.47271 -281.37612)
		(width 0.1143)
		(layer "In6.Cu")
		(net "P5E_CPU0_P2_RX_DN<13>")
	)
	(segment
		(start 373.361712 -295.633394)
		(end 373.32412 -295.61155)
		(width 0.1143)
		(layer "In6.Cu")
		(net "P5E_CPU0_P2_RX_DN<13>")
	)
	(segment
		(start 419.494462 -393.716764)
		(end 419.494462 -393.545822)
		(width 0.14224)
		(layer "In6.Cu")
		(net "P5E_CPU0_P2_RX_DN<13>")
	)
	(segment
		(start 407.213308 -368.365278)
		(end 407.161492 -368.17808)
		(width 0.14224)
		(layer "In6.Cu")
		(net "P5E_CPU0_P2_RX_DN<13>")
	)
	(segment
		(start 372.892574 -289.96386)
		(end 372.891812 -289.963352)
		(width 0.1143)
		(layer "In6.Cu")
		(net "P5E_CPU0_P2_RX_DN<13>")
	)
	(segment
		(start 372.892574 -282.508198)
		(end 372.893844 -282.507436)
		(width 0.1143)
		(layer "In6.Cu")
		(net "P5E_CPU0_P2_RX_DN<13>")
	)
	(segment
		(start 408.143202 -368.733832)
		(end 407.771854 -368.523774)
		(width 0.14224)
		(layer "In6.Cu")
		(net "P5E_CPU0_P2_RX_DN<13>")
	)
	(segment
		(start 372.893844 -292.227254)
		(end 372.923562 -292.210236)
		(width 0.1143)
		(layer "In6.Cu")
		(net "P5E_CPU0_P2_RX_DN<13>")
	)
	(segment
		(start 409.735274 -369.635278)
		(end 409.548584 -369.687094)
		(width 0.14224)
		(layer "In6.Cu")
		(net "P5E_CPU0_P2_RX_DN<13>")
	)
	(segment
		(start 392.815318 -336.717894)
		(end 389.932164 -322.347082)
		(width 0.14224)
		(layer "In6.Cu")
		(net "P5E_CPU0_P2_RX_DN<13>")
	)
	(segment
		(start 372.890796 -292.229032)
		(end 372.891812 -292.228524)
		(width 0.1143)
		(layer "In6.Cu")
		(net "P5E_CPU0_P2_RX_DN<13>")
	)
	(segment
		(start 417.101274 -371.700806)
		(end 410.664152 -370.069618)
		(width 0.14224)
		(layer "In6.Cu")
		(net "P5E_CPU0_P2_RX_DN<13>")
	)
	(segment
		(start 372.892574 -285.104078)
		(end 372.891812 -285.10357)
		(width 0.1143)
		(layer "In6.Cu")
		(net "P5E_CPU0_P2_RX_DN<13>")
	)
	(segment
		(start 372.891812 -294.823388)
		(end 372.890796 -294.82288)
		(width 0.1143)
		(layer "In6.Cu")
		(net "P5E_CPU0_P2_RX_DN<13>")
	)
	(segment
		(start 407.161238 -368.17808)
		(end 402.48967 -365.53394)
		(width 0.14224)
		(layer "In6.Cu")
		(net "P5E_CPU0_P2_RX_DN<13>")
	)
	(segment
		(start 419.486334 -392.312906)
		(end 419.486334 -391.263632)
		(width 0.14224)
		(layer "In6.Cu")
		(net "P5E_CPU0_P2_RX_DN<13>")
	)
	(segment
		(start 373.50446 -296.73296)
		(end 373.50446 -296.486072)
		(width 0.14224)
		(layer "In6.Cu")
		(net "P5E_CPU0_P2_RX_DN<13>")
	)
	(segment
		(start 372.890796 -282.509214)
		(end 372.891812 -282.508706)
		(width 0.1143)
		(layer "In6.Cu")
		(net "P5E_CPU0_P2_RX_DN<13>")
	)
	(segment
		(start 372.892574 -288.987992)
		(end 372.893844 -288.98723)
		(width 0.1143)
		(layer "In6.Cu")
		(net "P5E_CPU0_P2_RX_DN<13>")
	)
	(segment
		(start 372.88343 -294.818562)
		(end 372.881906 -294.817546)
		(width 0.1143)
		(layer "In6.Cu")
		(net "P5E_CPU0_P2_RX_DN<13>")
	)
	(segment
		(start 372.891812 -287.368488)
		(end 372.923562 -287.3502)
		(width 0.1143)
		(layer "In6.Cu")
		(net "P5E_CPU0_P2_RX_DN<13>")
	)
	(segment
		(start 372.888256 -283.481526)
		(end 372.88343 -283.478732)
		(width 0.1143)
		(layer "In6.Cu")
		(net "P5E_CPU0_P2_RX_DN<13>")
	)
	(segment
		(start 408.195272 -368.92103)
		(end 408.143456 -368.733832)
		(width 0.14224)
		(layer "In6.Cu")
		(net "P5E_CPU0_P2_RX_DN<13>")
	)
	(segment
		(start 372.92534 -288.363152)
		(end 372.891812 -288.343594)
		(width 0.1143)
		(layer "In6.Cu")
		(net "P5E_CPU0_P2_RX_DN<13>")
	)
	(segment
		(start 419.372288 -393.787376)
		(end 419.372796 -393.786868)
		(width 0.14224)
		(layer "In6.Cu")
		(net "P5E_CPU0_P2_RX_DN<13>")
	)
	(segment
		(start 372.852696 -284.151578)
		(end 372.889272 -284.130242)
		(width 0.1143)
		(layer "In6.Cu")
		(net "P5E_CPU0_P2_RX_DN<13>")
	)
	(segment
		(start 374.051576 -298.05376)
		(end 373.50446 -296.73296)
		(width 0.14224)
		(layer "In6.Cu")
		(net "P5E_CPU0_P2_RX_DN<13>")
	)
	(segment
		(start 373.47271 -281.37612)
		(end 373.174768 -281.37612)
		(width 0.1143)
		(layer "In6.Cu")
		(net "P5E_CPU0_P2_RX_DN<13>")
	)
	(segment
		(start 372.890796 -284.129226)
		(end 372.891812 -284.128718)
		(width 0.1143)
		(layer "In6.Cu")
		(net "P5E_CPU0_P2_RX_DN<13>")
	)
	(segment
		(start 372.88089 -291.577014)
		(end 372.852696 -291.560504)
		(width 0.1143)
		(layer "In6.Cu")
		(net "P5E_CPU0_P2_RX_DN<13>")
	)
	(segment
		(start 372.852696 -289.01136)
		(end 372.889272 -288.990024)
		(width 0.1143)
		(layer "In6.Cu")
		(net "P5E_CPU0_P2_RX_DN<13>")
	)
	(segment
		(start 372.893844 -289.964622)
		(end 372.892574 -289.96386)
		(width 0.1143)
		(layer "In6.Cu")
		(net "P5E_CPU0_P2_RX_DN<13>")
	)
	(segment
		(start 383.663952 -310.621426)
		(end 382.90119 -309.47995)
		(width 0.14224)
		(layer "In6.Cu")
		(net "P5E_CPU0_P2_RX_DN<13>")
	)
	(segment
		(start 372.892574 -290.608004)
		(end 372.893844 -290.607242)
		(width 0.1143)
		(layer "In6.Cu")
		(net "P5E_CPU0_P2_RX_DN<13>")
	)
	(segment
		(start 372.889272 -288.990024)
		(end 372.890796 -288.989008)
		(width 0.1143)
		(layer "In6.Cu")
		(net "P5E_CPU0_P2_RX_DN<13>")
	)
	(segment
		(start 419.372796 -393.786868)
		(end 419.494462 -393.716764)
		(width 0.14224)
		(layer "In6.Cu")
		(net "P5E_CPU0_P2_RX_DN<13>")
	)
	(segment
		(start 372.889272 -283.482034)
		(end 372.888256 -283.481526)
		(width 0.1143)
		(layer "In6.Cu")
		(net "P5E_CPU0_P2_RX_DN<13>")
	)
	(segment
		(start 419.494462 -393.545822)
		(end 419.17747 -393.22883)
		(width 0.14224)
		(layer "In6.Cu")
		(net "P5E_CPU0_P2_RX_DN<13>")
	)
	(segment
		(start 409.548584 -369.687094)
		(end 409.176728 -369.476782)
		(width 0.14224)
		(layer "In6.Cu")
		(net "P5E_CPU0_P2_RX_DN<13>")
	)
	(segment
		(start 372.881906 -283.477716)
		(end 372.88089 -283.477208)
		(width 0.1143)
		(layer "In6.Cu")
		(net "P5E_CPU0_P2_RX_DN<13>")
	)
	(segment
		(start 372.890796 -290.60902)
		(end 372.891812 -290.608512)
		(width 0.1143)
		(layer "In6.Cu")
		(net "P5E_CPU0_P2_RX_DN<13>")
	)
	(segment
		(start 372.852696 -293.871396)
		(end 372.889272 -293.85006)
		(width 0.1143)
		(layer "In6.Cu")
		(net "P5E_CPU0_P2_RX_DN<13>")
	)
	(segment
		(start 425.844716 -376.577606)
		(end 423.87266 -375.00433)
		(width 0.14224)
		(layer "In6.Cu")
		(net "P5E_CPU0_P2_RX_DN<13>")
	)
	(segment
		(start 407.585164 -368.57559)
		(end 407.213308 -368.365278)
		(width 0.14224)
		(layer "In6.Cu")
		(net "P5E_CPU0_P2_RX_DN<13>")
	)
	(segment
		(start 373.503952 -296.344086)
		(end 373.549672 -296.298366)
		(width 0.1143)
		(layer "In6.Cu")
		(net "P5E_CPU0_P2_RX_DN<13>")
	)
	(segment
		(start 372.890796 -288.989008)
		(end 372.891812 -288.9885)
		(width 0.1143)
		(layer "In6.Cu")
		(net "P5E_CPU0_P2_RX_DN<13>")
	)
	(segment
		(start 419.79215 -372.694454)
		(end 417.427918 -371.813074)
		(width 0.14224)
		(layer "In6.Cu")
		(net "P5E_CPU0_P2_RX_DN<13>")
	)
	(segment
		(start 394.547598 -347.828108)
		(end 393.288266 -341.496142)
		(width 0.14224)
		(layer "In6.Cu")
		(net "P5E_CPU0_P2_RX_DN<13>")
	)
	(segment
		(start 372.923562 -289.98164)
		(end 372.893844 -289.964622)
		(width 0.1143)
		(layer "In6.Cu")
		(net "P5E_CPU0_P2_RX_DN<13>")
	)
	(arc
		(start 410.664152 -370.069618)
		(mid 410.377845 -369.976226)
		(end 410.106622 -369.845336)
		(width 0.14224)
		(layer "In6.Cu")
		(net "P5E_CPU0_P2_RX_DN<13>")
	)
	(arc
		(start 419.486334 -391.263632)
		(mid 419.521411 -390.907418)
		(end 419.625272 -390.564878)
		(width 0.14224)
		(layer "In6.Cu")
		(net "P5E_CPU0_P2_RX_DN<13>")
	)
	(arc
		(start 373.408956 -295.663874)
		(mid 373.400789 -295.657409)
		(end 373.392446 -295.651174)
		(width 0.1143)
		(layer "In6.Cu")
		(net "P5E_CPU0_P2_RX_DN<13>")
	)
	(arc
		(start 372.923562 -284.11043)
		(mid 373.07949 -283.806138)
		(end 372.923562 -283.501846)
		(width 0.1143)
		(layer "In6.Cu")
		(net "P5E_CPU0_P2_RX_DN<13>")
	)
	(arc
		(start 372.852696 -288.320734)
		(mid 372.673883 -288.118384)
		(end 372.609364 -287.856168)
		(width 0.1143)
		(layer "In6.Cu")
		(net "P5E_CPU0_P2_RX_DN<13>")
	)
	(arc
		(start 373.079518 -282.186126)
		(mid 373.144033 -281.923907)
		(end 373.32285 -281.72156)
		(width 0.1143)
		(layer "In6.Cu")
		(net "P5E_CPU0_P2_RX_DN<13>")
	)
	(arc
		(start 372.852696 -293.180516)
		(mid 372.609369 -292.71595)
		(end 372.852696 -292.251384)
		(width 0.1143)
		(layer "In6.Cu")
		(net "P5E_CPU0_P2_RX_DN<13>")
	)
	(arc
		(start 417.222432 -371.737636)
		(mid 417.162292 -371.717777)
		(end 417.101274 -371.700806)
		(width 0.14224)
		(layer "In6.Cu")
		(net "P5E_CPU0_P2_RX_DN<13>")
	)
	(arc
		(start 372.852696 -289.940492)
		(mid 372.609369 -289.475926)
		(end 372.852696 -289.01136)
		(width 0.1143)
		(layer "In6.Cu")
		(net "P5E_CPU0_P2_RX_DN<13>")
	)
	(arc
		(start 372.923562 -292.210236)
		(mid 373.07949 -291.905944)
		(end 372.923562 -291.601652)
		(width 0.1143)
		(layer "In6.Cu")
		(net "P5E_CPU0_P2_RX_DN<13>")
	)
	(arc
		(start 372.923562 -293.830248)
		(mid 373.07949 -293.525956)
		(end 372.923562 -293.221664)
		(width 0.1143)
		(layer "In6.Cu")
		(net "P5E_CPU0_P2_RX_DN<13>")
	)
	(arc
		(start 373.549418 -286.236156)
		(mid 373.507869 -286.064734)
		(end 373.392446 -285.931356)
		(width 0.1143)
		(layer "In6.Cu")
		(net "P5E_CPU0_P2_RX_DN<13>")
	)
	(arc
		(start 372.852696 -291.560504)
		(mid 372.609369 -291.095938)
		(end 372.852696 -290.631372)
		(width 0.1143)
		(layer "In6.Cu")
		(net "P5E_CPU0_P2_RX_DN<13>")
	)
	(arc
		(start 402.48967 -365.53394)
		(mid 402.407088 -365.483341)
		(end 402.328126 -365.42726)
		(width 0.14224)
		(layer "In6.Cu")
		(net "P5E_CPU0_P2_RX_DN<13>")
	)
	(arc
		(start 402.328126 -365.42726)
		(mid 402.253209 -365.36622)
		(end 402.182584 -365.30026)
		(width 0.14224)
		(layer "In6.Cu")
		(net "P5E_CPU0_P2_RX_DN<13>")
	)
	(arc
		(start 373.079518 -288.66592)
		(mid 373.038756 -288.496036)
		(end 372.92534 -288.363152)
		(width 0.1143)
		(layer "In6.Cu")
		(net "P5E_CPU0_P2_RX_DN<13>")
	)
	(arc
		(start 373.32285 -285.890716)
		(mid 373.144037 -285.688366)
		(end 373.079518 -285.42615)
		(width 0.1143)
		(layer "In6.Cu")
		(net "P5E_CPU0_P2_RX_DN<13>")
	)
	(arc
		(start 426.22216 -377.36145)
		(mid 426.122877 -376.926465)
		(end 425.844716 -376.577606)
		(width 0.14224)
		(layer "In6.Cu")
		(net "P5E_CPU0_P2_RX_DN<13>")
	)
	(arc
		(start 372.852696 -294.800528)
		(mid 372.609369 -294.335962)
		(end 372.852696 -293.871396)
		(width 0.1143)
		(layer "In6.Cu")
		(net "P5E_CPU0_P2_RX_DN<13>")
	)
	(arc
		(start 372.923562 -290.590224)
		(mid 373.07949 -290.285932)
		(end 372.923562 -289.98164)
		(width 0.1143)
		(layer "In6.Cu")
		(net "P5E_CPU0_P2_RX_DN<13>")
	)
	(arc
		(start 423.87266 -375.00433)
		(mid 421.923992 -373.687599)
		(end 419.79215 -372.694454)
		(width 0.14224)
		(layer "In6.Cu")
		(net "P5E_CPU0_P2_RX_DN<13>")
	)
	(arc
		(start 417.428172 -371.813074)
		(mid 417.325431 -371.775003)
		(end 417.222432 -371.737636)
		(width 0.14224)
		(layer "In6.Cu")
		(net "P5E_CPU0_P2_RX_DN<13>")
	)
	(arc
		(start 372.923562 -288.970212)
		(mid 373.038238 -288.836878)
		(end 373.079518 -288.66592)
		(width 0.1143)
		(layer "In6.Cu")
		(net "P5E_CPU0_P2_RX_DN<13>")
	)
	(arc
		(start 372.852696 -285.08071)
		(mid 372.609369 -284.616144)
		(end 372.852696 -284.151578)
		(width 0.1143)
		(layer "In6.Cu")
		(net "P5E_CPU0_P2_RX_DN<13>")
	)
	(arc
		(start 373.392446 -281.68092)
		(mid 373.490211 -281.577944)
		(end 373.54256 -281.44597)
		(width 0.1143)
		(layer "In6.Cu")
		(net "P5E_CPU0_P2_RX_DN<13>")
	)
	(arc
		(start 426.184822 -378.283978)
		(mid 426.212441 -378.242738)
		(end 426.22216 -378.194062)
		(width 0.14224)
		(layer "In6.Cu")
		(net "P5E_CPU0_P2_RX_DN<13>")
	)
	(arc
		(start 394.791184 -348.631002)
		(mid 394.649663 -348.23554)
		(end 394.547598 -347.828108)
		(width 0.14224)
		(layer "In6.Cu")
		(net "P5E_CPU0_P2_RX_DN<13>")
	)
	(arc
		(start 401.409662 -364.527338)
		(mid 401.358693 -364.465415)
		(end 401.320762 -364.39475)
		(width 0.14224)
		(layer "In6.Cu")
		(net "P5E_CPU0_P2_RX_DN<13>")
	)
	(arc
		(start 372.852696 -283.460698)
		(mid 372.609369 -282.996132)
		(end 372.852696 -282.531566)
		(width 0.1143)
		(layer "In6.Cu")
		(net "P5E_CPU0_P2_RX_DN<13>")
	)
	(arc
		(start 373.32412 -295.61155)
		(mid 373.144391 -295.40893)
		(end 373.079518 -295.145968)
		(width 0.1143)
		(layer "In6.Cu")
		(net "P5E_CPU0_P2_RX_DN<13>")
	)
	(arc
		(start 372.923562 -287.3502)
		(mid 373.038238 -287.216866)
		(end 373.079518 -287.045908)
		(width 0.1143)
		(layer "In6.Cu")
		(net "P5E_CPU0_P2_RX_DN<13>")
	)
	(arc
		(start 372.609364 -287.856168)
		(mid 372.6746 -287.592577)
		(end 372.855236 -287.389824)
		(width 0.1143)
		(layer "In6.Cu")
		(net "P5E_CPU0_P2_RX_DN<13>")
	)
	(arc
		(start 373.079518 -295.145968)
		(mid 373.038263 -294.974997)
		(end 372.923562 -294.841676)
		(width 0.1143)
		(layer "In6.Cu")
		(net "P5E_CPU0_P2_RX_DN<13>")
	)
	(arc
		(start 373.079518 -285.42615)
		(mid 373.038263 -285.255179)
		(end 372.923562 -285.121858)
		(width 0.1143)
		(layer "In6.Cu")
		(net "P5E_CPU0_P2_RX_DN<13>")
	)
	(arc
		(start 373.394478 -286.539686)
		(mid 373.508407 -286.406539)
		(end 373.549418 -286.236156)
		(width 0.1143)
		(layer "In6.Cu")
		(net "P5E_CPU0_P2_RX_DN<13>")
	)
	(arc
		(start 373.079518 -287.045908)
		(mid 373.144033 -286.783689)
		(end 373.32285 -286.581342)
		(width 0.1143)
		(layer "In6.Cu")
		(net "P5E_CPU0_P2_RX_DN<13>")
	)
	(arc
		(start 372.923562 -282.490418)
		(mid 373.038238 -282.357084)
		(end 373.079518 -282.186126)
		(width 0.1143)
		(layer "In6.Cu")
		(net "P5E_CPU0_P2_RX_DN<13>")
	)
	(arc
		(start 423.590974 -380.990856)
		(mid 423.688326 -380.808917)
		(end 423.81932 -380.64948)
		(width 0.14224)
		(layer "In6.Cu")
		(net "P5E_CPU0_P2_RX_DN<13>")
	)
	(arc
		(start 393.288266 -341.496142)
		(mid 393.284855 -341.476402)
		(end 393.282424 -341.456518)
		(width 0.14224)
		(layer "In6.Cu")
		(net "P5E_CPU0_P2_RX_DN<13>")
	)
	(arc
		(start 373.549672 -295.955974)
		(mid 373.512542 -295.793926)
		(end 373.408956 -295.663874)
		(width 0.1143)
		(layer "In6.Cu")
		(net "P5E_CPU0_P2_RX_DN<13>")
	)
	(segment
		(start 369.888008 -282.730194)
		(end 370.35486 -282.996132)
		(width 0.12954)
		(layer "F.Cu")
		(net "P5E_CPU0_P2_RX_DN<12>")
	)
	(segment
		(start 417.298378 -393.69238)
		(end 417.819078 -393.69238)
		(width 0.127)
		(layer "F.Cu")
		(net "P5E_CPU0_P2_RX_DN<12>")
	)
	(segment
		(start 372.610126 -296.035476)
		(end 372.609618 -296.034968)
		(width 0.1143)
		(layer "In6.Cu")
		(net "P5E_CPU0_P2_RX_DN<12>")
	)
	(segment
		(start 422.75887 -380.12751)
		(end 422.75887 -376.864118)
		(width 0.14224)
		(layer "In6.Cu")
		(net "P5E_CPU0_P2_RX_DN<12>")
	)
	(segment
		(start 418.172646 -393.786868)
		(end 418.294312 -393.716764)
		(width 0.14224)
		(layer "In6.Cu")
		(net "P5E_CPU0_P2_RX_DN<12>")
	)
	(segment
		(start 371.03431 -283.496512)
		(end 370.972842 -283.460698)
		(width 0.1143)
		(layer "In6.Cu")
		(net "P5E_CPU0_P2_RX_DN<12>")
	)
	(segment
		(start 415.853626 -372.371112)
		(end 409.606242 -370.807488)
		(width 0.14224)
		(layer "In6.Cu")
		(net "P5E_CPU0_P2_RX_DN<12>")
	)
	(segment
		(start 419.568376 -387.486144)
		(end 419.747954 -387.411976)
		(width 0.14224)
		(layer "In6.Cu")
		(net "P5E_CPU0_P2_RX_DN<12>")
	)
	(segment
		(start 370.652802 -282.996132)
		(end 370.35486 -282.996132)
		(width 0.1143)
		(layer "In6.Cu")
		(net "P5E_CPU0_P2_RX_DN<12>")
	)
	(segment
		(start 418.704268 -389.570214)
		(end 418.883592 -389.496046)
		(width 0.14224)
		(layer "In6.Cu")
		(net "P5E_CPU0_P2_RX_DN<12>")
	)
	(segment
		(start 419.478968 -388.05993)
		(end 419.4048 -387.880606)
		(width 0.14224)
		(layer "In6.Cu")
		(net "P5E_CPU0_P2_RX_DN<12>")
	)
	(segment
		(start 371.982492 -293.221156)
		(end 371.912896 -293.180516)
		(width 0.1143)
		(layer "In6.Cu")
		(net "P5E_CPU0_P2_RX_DN<12>")
	)
	(segment
		(start 381.951738 -309.802022)
		(end 375.647204 -302.119792)
		(width 0.14224)
		(layer "In6.Cu")
		(net "P5E_CPU0_P2_RX_DN<12>")
	)
	(segment
		(start 419.747954 -387.411976)
		(end 422.748964 -380.176532)
		(width 0.14224)
		(layer "In6.Cu")
		(net "P5E_CPU0_P2_RX_DN<12>")
	)
	(segment
		(start 371.912896 -292.251384)
		(end 371.982492 -292.210744)
		(width 0.1143)
		(layer "In6.Cu")
		(net "P5E_CPU0_P2_RX_DN<12>")
	)
	(segment
		(start 372.422674 -285.914084)
		(end 372.420642 -285.912814)
		(width 0.1143)
		(layer "In6.Cu")
		(net "P5E_CPU0_P2_RX_DN<12>")
	)
	(segment
		(start 418.172138 -393.787376)
		(end 418.172646 -393.786868)
		(width 0.14224)
		(layer "In6.Cu")
		(net "P5E_CPU0_P2_RX_DN<12>")
	)
	(segment
		(start 389.046212 -322.73494)
		(end 382.85928 -311.16016)
		(width 0.14224)
		(layer "In6.Cu")
		(net "P5E_CPU0_P2_RX_DN<12>")
	)
	(segment
		(start 418.317172 -390.86155)
		(end 418.61486 -390.143746)
		(width 0.14224)
		(layer "In6.Cu")
		(net "P5E_CPU0_P2_RX_DN<12>")
	)
	(segment
		(start 372.564406 -296.899838)
		(end 372.564406 -296.377106)
		(width 0.14224)
		(layer "In6.Cu")
		(net "P5E_CPU0_P2_RX_DN<12>")
	)
	(segment
		(start 372.428008 -285.916878)
		(end 372.425976 -285.915862)
		(width 0.1143)
		(layer "In6.Cu")
		(net "P5E_CPU0_P2_RX_DN<12>")
	)
	(segment
		(start 371.487954 -284.29712)
		(end 371.48643 -284.296104)
		(width 0.1143)
		(layer "In6.Cu")
		(net "P5E_CPU0_P2_RX_DN<12>")
	)
	(segment
		(start 372.564406 -296.348658)
		(end 372.610126 -296.302938)
		(width 0.1143)
		(layer "In6.Cu")
		(net "P5E_CPU0_P2_RX_DN<12>")
	)
	(segment
		(start 418.883592 -389.496046)
		(end 419.046914 -389.102092)
		(width 0.14224)
		(layer "In6.Cu")
		(net "P5E_CPU0_P2_RX_DN<12>")
	)
	(segment
		(start 419.136322 -388.528306)
		(end 419.3159 -388.454138)
		(width 0.14224)
		(layer "In6.Cu")
		(net "P5E_CPU0_P2_RX_DN<12>")
	)
	(segment
		(start 400.510756 -364.903258)
		(end 393.792964 -348.684342)
		(width 0.14224)
		(layer "In6.Cu")
		(net "P5E_CPU0_P2_RX_DN<12>")
	)
	(segment
		(start 392.33602 -341.549736)
		(end 391.891774 -337.041236)
		(width 0.14224)
		(layer "In6.Cu")
		(net "P5E_CPU0_P2_RX_DN<12>")
	)
	(segment
		(start 372.610126 -296.302938)
		(end 372.610126 -296.035476)
		(width 0.1143)
		(layer "In6.Cu")
		(net "P5E_CPU0_P2_RX_DN<12>")
	)
	(segment
		(start 418.294312 -393.716764)
		(end 418.294312 -393.545822)
		(width 0.14224)
		(layer "In6.Cu")
		(net "P5E_CPU0_P2_RX_DN<12>")
	)
	(segment
		(start 372.417086 -285.910528)
		(end 372.41607 -285.91002)
		(width 0.1143)
		(layer "In6.Cu")
		(net "P5E_CPU0_P2_RX_DN<12>")
	)
	(segment
		(start 372.425976 -285.915862)
		(end 372.425214 -285.915354)
		(width 0.1143)
		(layer "In6.Cu")
		(net "P5E_CPU0_P2_RX_DN<12>")
	)
	(segment
		(start 417.819078 -393.69238)
		(end 418.172138 -393.787376)
		(width 0.14224)
		(layer "In6.Cu")
		(net "P5E_CPU0_P2_RX_DN<12>")
	)
	(segment
		(start 402.080476 -366.51692)
		(end 400.599656 -365.0361)
		(width 0.14224)
		(layer "In6.Cu")
		(net "P5E_CPU0_P2_RX_DN<12>")
	)
	(segment
		(start 371.915436 -287.389824)
		(end 371.982492 -287.350708)
		(width 0.1143)
		(layer "In6.Cu")
		(net "P5E_CPU0_P2_RX_DN<12>")
	)
	(segment
		(start 419.4048 -387.880606)
		(end 419.568376 -387.486144)
		(width 0.14224)
		(layer "In6.Cu")
		(net "P5E_CPU0_P2_RX_DN<12>")
	)
	(segment
		(start 371.982492 -285.12135)
		(end 371.912896 -285.08071)
		(width 0.1143)
		(layer "In6.Cu")
		(net "P5E_CPU0_P2_RX_DN<12>")
	)
	(segment
		(start 372.564406 -296.377106)
		(end 372.564406 -296.348658)
		(width 0.1143)
		(layer "In6.Cu")
		(net "P5E_CPU0_P2_RX_DN<12>")
	)
	(segment
		(start 418.294312 -393.545822)
		(end 417.97732 -393.22883)
		(width 0.14224)
		(layer "In6.Cu")
		(net "P5E_CPU0_P2_RX_DN<12>")
	)
	(segment
		(start 371.912896 -293.871396)
		(end 371.982492 -293.830756)
		(width 0.1143)
		(layer "In6.Cu")
		(net "P5E_CPU0_P2_RX_DN<12>")
	)
	(segment
		(start 372.419372 -285.912052)
		(end 372.417086 -285.910528)
		(width 0.1143)
		(layer "In6.Cu")
		(net "P5E_CPU0_P2_RX_DN<12>")
	)
	(segment
		(start 371.912896 -290.631372)
		(end 371.982492 -290.590732)
		(width 0.1143)
		(layer "In6.Cu")
		(net "P5E_CPU0_P2_RX_DN<12>")
	)
	(segment
		(start 372.420642 -285.912814)
		(end 372.419372 -285.912052)
		(width 0.1143)
		(layer "In6.Cu")
		(net "P5E_CPU0_P2_RX_DN<12>")
	)
	(segment
		(start 422.461182 -376.145298)
		(end 422.38803 -376.072146)
		(width 0.14224)
		(layer "In6.Cu")
		(net "P5E_CPU0_P2_RX_DN<12>")
	)
	(segment
		(start 393.65936 -348.244414)
		(end 392.36015 -341.71255)
		(width 0.14224)
		(layer "In6.Cu")
		(net "P5E_CPU0_P2_RX_DN<12>")
	)
	(segment
		(start 372.609618 -296.034968)
		(end 372.609618 -295.955974)
		(width 0.1143)
		(layer "In6.Cu")
		(net "P5E_CPU0_P2_RX_DN<12>")
	)
	(segment
		(start 372.41607 -285.91002)
		(end 372.413784 -285.90875)
		(width 0.1143)
		(layer "In6.Cu")
		(net "P5E_CPU0_P2_RX_DN<12>")
	)
	(segment
		(start 419.046914 -389.102092)
		(end 418.972746 -388.922768)
		(width 0.14224)
		(layer "In6.Cu")
		(net "P5E_CPU0_P2_RX_DN<12>")
	)
	(segment
		(start 371.513608 -284.311852)
		(end 371.48897 -284.297628)
		(width 0.1143)
		(layer "In6.Cu")
		(net "P5E_CPU0_P2_RX_DN<12>")
	)
	(segment
		(start 371.481858 -284.293564)
		(end 371.445536 -284.272482)
		(width 0.1143)
		(layer "In6.Cu")
		(net "P5E_CPU0_P2_RX_DN<12>")
	)
	(segment
		(start 372.413784 -285.90875)
		(end 372.382796 -285.890716)
		(width 0.1143)
		(layer "In6.Cu")
		(net "P5E_CPU0_P2_RX_DN<12>")
	)
	(segment
		(start 418.286184 -392.31316)
		(end 418.286184 -391.018268)
		(width 0.14224)
		(layer "In6.Cu")
		(net "P5E_CPU0_P2_RX_DN<12>")
	)
	(segment
		(start 382.85928 -311.16016)
		(end 381.951738 -309.802022)
		(width 0.14224)
		(layer "In6.Cu")
		(net "P5E_CPU0_P2_RX_DN<12>")
	)
	(segment
		(start 370.735606 -283.078936)
		(end 370.652802 -282.996132)
		(width 0.1143)
		(layer "In6.Cu")
		(net "P5E_CPU0_P2_RX_DN<12>")
	)
	(segment
		(start 418.540692 -389.964422)
		(end 418.704268 -389.570214)
		(width 0.14224)
		(layer "In6.Cu")
		(net "P5E_CPU0_P2_RX_DN<12>")
	)
	(segment
		(start 371.48643 -284.296104)
		(end 371.48389 -284.294834)
		(width 0.1143)
		(layer "In6.Cu")
		(net "P5E_CPU0_P2_RX_DN<12>")
	)
	(segment
		(start 417.982146 -392.616944)
		(end 418.286184 -392.31316)
		(width 0.14224)
		(layer "In6.Cu")
		(net "P5E_CPU0_P2_RX_DN<12>")
	)
	(segment
		(start 417.97732 -393.22883)
		(end 417.982146 -392.616944)
		(width 0.14224)
		(layer "In6.Cu")
		(net "P5E_CPU0_P2_RX_DN<12>")
	)
	(segment
		(start 418.972746 -388.922768)
		(end 419.136322 -388.528306)
		(width 0.14224)
		(layer "In6.Cu")
		(net "P5E_CPU0_P2_RX_DN<12>")
	)
	(segment
		(start 371.48262 -284.294072)
		(end 371.481858 -284.293564)
		(width 0.1143)
		(layer "In6.Cu")
		(net "P5E_CPU0_P2_RX_DN<12>")
	)
	(segment
		(start 371.912896 -289.01136)
		(end 371.982492 -288.97072)
		(width 0.1143)
		(layer "In6.Cu")
		(net "P5E_CPU0_P2_RX_DN<12>")
	)
	(segment
		(start 375.647204 -302.119792)
		(end 373.225314 -298.495466)
		(width 0.14224)
		(layer "In6.Cu")
		(net "P5E_CPU0_P2_RX_DN<12>")
	)
	(segment
		(start 391.891774 -337.041236)
		(end 389.046212 -322.73494)
		(width 0.14224)
		(layer "In6.Cu")
		(net "P5E_CPU0_P2_RX_DN<12>")
	)
	(segment
		(start 371.982492 -289.981132)
		(end 371.912896 -289.940492)
		(width 0.1143)
		(layer "In6.Cu")
		(net "P5E_CPU0_P2_RX_DN<12>")
	)
	(segment
		(start 371.48389 -284.294834)
		(end 371.48262 -284.294072)
		(width 0.1143)
		(layer "In6.Cu")
		(net "P5E_CPU0_P2_RX_DN<12>")
	)
	(segment
		(start 409.606242 -370.807488)
		(end 402.229828 -366.630458)
		(width 0.14224)
		(layer "In6.Cu")
		(net "P5E_CPU0_P2_RX_DN<12>")
	)
	(segment
		(start 372.452392 -295.651174)
		(end 372.382796 -295.610534)
		(width 0.1143)
		(layer "In6.Cu")
		(net "P5E_CPU0_P2_RX_DN<12>")
	)
	(segment
		(start 419.315646 -388.453884)
		(end 419.478968 -388.05993)
		(width 0.14224)
		(layer "In6.Cu")
		(net "P5E_CPU0_P2_RX_DN<12>")
	)
	(segment
		(start 371.982492 -294.841168)
		(end 371.912896 -294.800528)
		(width 0.1143)
		(layer "In6.Cu")
		(net "P5E_CPU0_P2_RX_DN<12>")
	)
	(segment
		(start 372.382796 -286.581342)
		(end 372.45544 -286.538924)
		(width 0.1143)
		(layer "In6.Cu")
		(net "P5E_CPU0_P2_RX_DN<12>")
	)
	(segment
		(start 418.61486 -390.143746)
		(end 418.540692 -389.964422)
		(width 0.14224)
		(layer "In6.Cu")
		(net "P5E_CPU0_P2_RX_DN<12>")
	)
	(segment
		(start 419.3159 -388.454138)
		(end 419.315646 -388.453884)
		(width 0.14224)
		(layer "In6.Cu")
		(net "P5E_CPU0_P2_RX_DN<12>")
	)
	(segment
		(start 372.425214 -285.915354)
		(end 372.422674 -285.914084)
		(width 0.1143)
		(layer "In6.Cu")
		(net "P5E_CPU0_P2_RX_DN<12>")
	)
	(segment
		(start 371.984524 -288.36239)
		(end 371.912896 -288.320734)
		(width 0.1143)
		(layer "In6.Cu")
		(net "P5E_CPU0_P2_RX_DN<12>")
	)
	(segment
		(start 371.48897 -284.297628)
		(end 371.487954 -284.29712)
		(width 0.1143)
		(layer "In6.Cu")
		(net "P5E_CPU0_P2_RX_DN<12>")
	)
	(segment
		(start 372.453662 -285.931864)
		(end 372.428008 -285.916878)
		(width 0.1143)
		(layer "In6.Cu")
		(net "P5E_CPU0_P2_RX_DN<12>")
	)
	(segment
		(start 373.225314 -298.495466)
		(end 372.564406 -296.899838)
		(width 0.14224)
		(layer "In6.Cu")
		(net "P5E_CPU0_P2_RX_DN<12>")
	)
	(segment
		(start 371.982492 -291.601144)
		(end 371.912896 -291.560504)
		(width 0.1143)
		(layer "In6.Cu")
		(net "P5E_CPU0_P2_RX_DN<12>")
	)
	(arc
		(start 371.982492 -292.210744)
		(mid 372.139469 -291.905944)
		(end 371.982492 -291.601144)
		(width 0.1143)
		(layer "In6.Cu")
		(net "P5E_CPU0_P2_RX_DN<12>")
	)
	(arc
		(start 371.669564 -284.616144)
		(mid 371.628309 -284.445173)
		(end 371.513608 -284.311852)
		(width 0.1143)
		(layer "In6.Cu")
		(net "P5E_CPU0_P2_RX_DN<12>")
	)
	(arc
		(start 371.434868 -284.265116)
		(mid 371.265735 -284.072083)
		(end 371.19941 -283.824172)
		(width 0.1143)
		(layer "In6.Cu")
		(net "P5E_CPU0_P2_RX_DN<12>")
	)
	(arc
		(start 371.912896 -294.800528)
		(mid 371.669569 -294.335962)
		(end 371.912896 -293.871396)
		(width 0.1143)
		(layer "In6.Cu")
		(net "P5E_CPU0_P2_RX_DN<12>")
	)
	(arc
		(start 372.382796 -295.610534)
		(mid 372.203983 -295.408184)
		(end 372.139464 -295.145968)
		(width 0.1143)
		(layer "In6.Cu")
		(net "P5E_CPU0_P2_RX_DN<12>")
	)
	(arc
		(start 371.445536 -284.272482)
		(mid 371.44018 -284.268831)
		(end 371.434868 -284.265116)
		(width 0.1143)
		(layer "In6.Cu")
		(net "P5E_CPU0_P2_RX_DN<12>")
	)
	(arc
		(start 372.139464 -295.145968)
		(mid 372.097915 -294.974546)
		(end 371.982492 -294.841168)
		(width 0.1143)
		(layer "In6.Cu")
		(net "P5E_CPU0_P2_RX_DN<12>")
	)
	(arc
		(start 370.739416 -283.101796)
		(mid 370.737393 -283.090386)
		(end 370.735606 -283.078936)
		(width 0.1143)
		(layer "In6.Cu")
		(net "P5E_CPU0_P2_RX_DN<12>")
	)
	(arc
		(start 371.912896 -285.08071)
		(mid 371.734083 -284.87836)
		(end 371.669564 -284.616144)
		(width 0.1143)
		(layer "In6.Cu")
		(net "P5E_CPU0_P2_RX_DN<12>")
	)
	(arc
		(start 418.286184 -391.018268)
		(mid 418.293957 -390.938382)
		(end 418.317172 -390.86155)
		(width 0.14224)
		(layer "In6.Cu")
		(net "P5E_CPU0_P2_RX_DN<12>")
	)
	(arc
		(start 372.139464 -288.66592)
		(mid 372.098498 -288.495514)
		(end 371.984524 -288.36239)
		(width 0.1143)
		(layer "In6.Cu")
		(net "P5E_CPU0_P2_RX_DN<12>")
	)
	(arc
		(start 372.468902 -295.663874)
		(mid 372.460735 -295.657409)
		(end 372.452392 -295.651174)
		(width 0.1143)
		(layer "In6.Cu")
		(net "P5E_CPU0_P2_RX_DN<12>")
	)
	(arc
		(start 400.599656 -365.0361)
		(mid 400.548684 -364.974046)
		(end 400.510756 -364.903258)
		(width 0.14224)
		(layer "In6.Cu")
		(net "P5E_CPU0_P2_RX_DN<12>")
	)
	(arc
		(start 372.139464 -287.045908)
		(mid 372.203979 -286.783689)
		(end 372.382796 -286.581342)
		(width 0.1143)
		(layer "In6.Cu")
		(net "P5E_CPU0_P2_RX_DN<12>")
	)
	(arc
		(start 371.982492 -287.350708)
		(mid 372.097919 -287.217332)
		(end 372.139464 -287.045908)
		(width 0.1143)
		(layer "In6.Cu")
		(net "P5E_CPU0_P2_RX_DN<12>")
	)
	(arc
		(start 372.609618 -295.955974)
		(mid 372.572488 -295.793926)
		(end 372.468902 -295.663874)
		(width 0.1143)
		(layer "In6.Cu")
		(net "P5E_CPU0_P2_RX_DN<12>")
	)
	(arc
		(start 422.38803 -376.072146)
		(mid 419.372228 -373.77777)
		(end 415.853626 -372.371112)
		(width 0.14224)
		(layer "In6.Cu")
		(net "P5E_CPU0_P2_RX_DN<12>")
	)
	(arc
		(start 371.19941 -283.824172)
		(mid 371.198791 -283.8103)
		(end 371.197378 -283.796486)
		(width 0.1143)
		(layer "In6.Cu")
		(net "P5E_CPU0_P2_RX_DN<12>")
	)
	(arc
		(start 422.748964 -380.176532)
		(mid 422.756315 -380.152508)
		(end 422.75887 -380.12751)
		(width 0.14224)
		(layer "In6.Cu")
		(net "P5E_CPU0_P2_RX_DN<12>")
	)
	(arc
		(start 372.45544 -286.538924)
		(mid 372.568847 -286.406035)
		(end 372.609618 -286.236156)
		(width 0.1143)
		(layer "In6.Cu")
		(net "P5E_CPU0_P2_RX_DN<12>")
	)
	(arc
		(start 392.36015 -341.71255)
		(mid 392.346087 -341.631439)
		(end 392.33602 -341.549736)
		(width 0.14224)
		(layer "In6.Cu")
		(net "P5E_CPU0_P2_RX_DN<12>")
	)
	(arc
		(start 371.912896 -293.180516)
		(mid 371.669569 -292.71595)
		(end 371.912896 -292.251384)
		(width 0.1143)
		(layer "In6.Cu")
		(net "P5E_CPU0_P2_RX_DN<12>")
	)
	(arc
		(start 372.382796 -285.890716)
		(mid 372.203983 -285.688366)
		(end 372.139464 -285.42615)
		(width 0.1143)
		(layer "In6.Cu")
		(net "P5E_CPU0_P2_RX_DN<12>")
	)
	(arc
		(start 371.912896 -289.940492)
		(mid 371.669569 -289.475926)
		(end 371.912896 -289.01136)
		(width 0.1143)
		(layer "In6.Cu")
		(net "P5E_CPU0_P2_RX_DN<12>")
	)
	(arc
		(start 371.912896 -288.320734)
		(mid 371.669572 -287.854618)
		(end 371.915436 -287.389824)
		(width 0.1143)
		(layer "In6.Cu")
		(net "P5E_CPU0_P2_RX_DN<12>")
	)
	(arc
		(start 372.139464 -285.42615)
		(mid 372.097915 -285.254728)
		(end 371.982492 -285.12135)
		(width 0.1143)
		(layer "In6.Cu")
		(net "P5E_CPU0_P2_RX_DN<12>")
	)
	(arc
		(start 393.792964 -348.684342)
		(mid 393.715351 -348.467661)
		(end 393.65936 -348.244414)
		(width 0.14224)
		(layer "In6.Cu")
		(net "P5E_CPU0_P2_RX_DN<12>")
	)
	(arc
		(start 422.75887 -376.864118)
		(mid 422.681508 -376.475103)
		(end 422.461182 -376.145298)
		(width 0.14224)
		(layer "In6.Cu")
		(net "P5E_CPU0_P2_RX_DN<12>")
	)
	(arc
		(start 371.982492 -293.830756)
		(mid 372.139469 -293.525956)
		(end 371.982492 -293.221156)
		(width 0.1143)
		(layer "In6.Cu")
		(net "P5E_CPU0_P2_RX_DN<12>")
	)
	(arc
		(start 371.912896 -291.560504)
		(mid 371.669569 -291.095938)
		(end 371.912896 -290.631372)
		(width 0.1143)
		(layer "In6.Cu")
		(net "P5E_CPU0_P2_RX_DN<12>")
	)
	(arc
		(start 371.197378 -283.796486)
		(mid 371.14261 -283.631952)
		(end 371.03431 -283.496512)
		(width 0.1143)
		(layer "In6.Cu")
		(net "P5E_CPU0_P2_RX_DN<12>")
	)
	(arc
		(start 371.982492 -290.590732)
		(mid 372.139469 -290.285932)
		(end 371.982492 -289.981132)
		(width 0.1143)
		(layer "In6.Cu")
		(net "P5E_CPU0_P2_RX_DN<12>")
	)
	(arc
		(start 372.609618 -286.236156)
		(mid 372.568363 -286.065185)
		(end 372.453662 -285.931864)
		(width 0.1143)
		(layer "In6.Cu")
		(net "P5E_CPU0_P2_RX_DN<12>")
	)
	(arc
		(start 370.972842 -283.460698)
		(mid 370.820855 -283.30419)
		(end 370.739416 -283.101796)
		(width 0.1143)
		(layer "In6.Cu")
		(net "P5E_CPU0_P2_RX_DN<12>")
	)
	(arc
		(start 371.982492 -288.97072)
		(mid 372.097919 -288.837344)
		(end 372.139464 -288.66592)
		(width 0.1143)
		(layer "In6.Cu")
		(net "P5E_CPU0_P2_RX_DN<12>")
	)
	(arc
		(start 402.229828 -366.630458)
		(mid 402.151299 -366.578755)
		(end 402.080476 -366.51692)
		(width 0.14224)
		(layer "In6.Cu")
		(net "P5E_CPU0_P2_RX_DN<12>")
	)
	(segment
		(start 416.098228 -393.69238)
		(end 416.618928 -393.69238)
		(width 0.127)
		(layer "F.Cu")
		(net "P5E_CPU0_P2_RX_DN<11>")
	)
	(segment
		(start 369.888008 -284.350206)
		(end 370.35486 -284.616144)
		(width 0.12954)
		(layer "F.Cu")
		(net "P5E_CPU0_P2_RX_DN<11>")
	)
	(segment
		(start 371.624352 -296.325036)
		(end 371.670072 -296.279316)
		(width 0.1143)
		(layer "In6.Cu")
		(net "P5E_CPU0_P2_RX_DN<11>")
	)
	(segment
		(start 371.011958 -285.10357)
		(end 370.972842 -285.08071)
		(width 0.1143)
		(layer "In6.Cu")
		(net "P5E_CPU0_P2_RX_DN<11>")
	)
	(segment
		(start 419.913308 -378.58827)
		(end 419.566344 -378.241306)
		(width 0.14224)
		(layer "In6.Cu")
		(net "P5E_CPU0_P2_RX_DN<11>")
	)
	(segment
		(start 371.042438 -285.12135)
		(end 371.011958 -285.10357)
		(width 0.1143)
		(layer "In6.Cu")
		(net "P5E_CPU0_P2_RX_DN<11>")
	)
	(segment
		(start 421.047164 -381.316992)
		(end 421.047164 -381.316738)
		(width 0.14224)
		(layer "In6.Cu")
		(net "P5E_CPU0_P2_RX_DN<11>")
	)
	(segment
		(start 371.669564 -296.085768)
		(end 371.669564 -295.955974)
		(width 0.1143)
		(layer "In6.Cu")
		(net "P5E_CPU0_P2_RX_DN<11>")
	)
	(segment
		(start 371.011958 -294.823388)
		(end 370.972842 -294.800528)
		(width 0.1143)
		(layer "In6.Cu")
		(net "P5E_CPU0_P2_RX_DN<11>")
	)
	(segment
		(start 371.48262 -295.633902)
		(end 371.480842 -295.632886)
		(width 0.1143)
		(layer "In6.Cu")
		(net "P5E_CPU0_P2_RX_DN<11>")
	)
	(segment
		(start 421.05707 -381.26797)
		(end 421.05707 -379.36805)
		(width 0.14224)
		(layer "In6.Cu")
		(net "P5E_CPU0_P2_RX_DN<11>")
	)
	(segment
		(start 371.011958 -292.228524)
		(end 371.042438 -292.210744)
		(width 0.1143)
		(layer "In6.Cu")
		(net "P5E_CPU0_P2_RX_DN<11>")
	)
	(segment
		(start 420.966646 -379.149864)
		(end 420.723568 -378.906786)
		(width 0.14224)
		(layer "In6.Cu")
		(net "P5E_CPU0_P2_RX_DN<11>")
	)
	(segment
		(start 371.042438 -291.601144)
		(end 371.011958 -291.583364)
		(width 0.1143)
		(layer "In6.Cu")
		(net "P5E_CPU0_P2_RX_DN<11>")
	)
	(segment
		(start 371.042438 -289.981132)
		(end 371.011958 -289.963352)
		(width 0.1143)
		(layer "In6.Cu")
		(net "P5E_CPU0_P2_RX_DN<11>")
	)
	(segment
		(start 390.95934 -337.133184)
		(end 388.166864 -323.093588)
		(width 0.14224)
		(layer "In6.Cu")
		(net "P5E_CPU0_P2_RX_DN<11>")
	)
	(segment
		(start 371.011958 -288.343594)
		(end 370.972842 -288.320734)
		(width 0.1143)
		(layer "In6.Cu")
		(net "P5E_CPU0_P2_RX_DN<11>")
	)
	(segment
		(start 371.481858 -285.913576)
		(end 371.442742 -285.890716)
		(width 0.1143)
		(layer "In6.Cu")
		(net "P5E_CPU0_P2_RX_DN<11>")
	)
	(segment
		(start 418.06495 -388.158736)
		(end 418.244274 -388.084314)
		(width 0.14224)
		(layer "In6.Cu")
		(net "P5E_CPU0_P2_RX_DN<11>")
	)
	(segment
		(start 371.011958 -289.963352)
		(end 370.972842 -289.940492)
		(width 0.1143)
		(layer "In6.Cu")
		(net "P5E_CPU0_P2_RX_DN<11>")
	)
	(segment
		(start 371.042438 -293.221156)
		(end 371.011958 -293.203376)
		(width 0.1143)
		(layer "In6.Cu")
		(net "P5E_CPU0_P2_RX_DN<11>")
	)
	(segment
		(start 417.812728 -389.126476)
		(end 417.975796 -388.732268)
		(width 0.14224)
		(layer "In6.Cu")
		(net "P5E_CPU0_P2_RX_DN<11>")
	)
	(segment
		(start 371.512592 -286.540956)
		(end 371.515386 -286.538924)
		(width 0.1143)
		(layer "In6.Cu")
		(net "P5E_CPU0_P2_RX_DN<11>")
	)
	(segment
		(start 417.901628 -388.553198)
		(end 418.06495 -388.158736)
		(width 0.14224)
		(layer "In6.Cu")
		(net "P5E_CPU0_P2_RX_DN<11>")
	)
	(segment
		(start 371.011958 -293.203376)
		(end 370.972842 -293.180516)
		(width 0.1143)
		(layer "In6.Cu")
		(net "P5E_CPU0_P2_RX_DN<11>")
	)
	(segment
		(start 409.262072 -371.687344)
		(end 401.442682 -367.259108)
		(width 0.14224)
		(layer "In6.Cu")
		(net "P5E_CPU0_P2_RX_DN<11>")
	)
	(segment
		(start 417.380928 -390.168638)
		(end 417.543996 -389.77443)
		(width 0.14224)
		(layer "In6.Cu")
		(net "P5E_CPU0_P2_RX_DN<11>")
	)
	(segment
		(start 371.011958 -291.583364)
		(end 370.972842 -291.560504)
		(width 0.1143)
		(layer "In6.Cu")
		(net "P5E_CPU0_P2_RX_DN<11>")
	)
	(segment
		(start 371.011958 -293.848536)
		(end 371.042438 -293.830756)
		(width 0.1143)
		(layer "In6.Cu")
		(net "P5E_CPU0_P2_RX_DN<11>")
	)
	(segment
		(start 371.624352 -296.353484)
		(end 371.624352 -296.325036)
		(width 0.1143)
		(layer "In6.Cu")
		(net "P5E_CPU0_P2_RX_DN<11>")
	)
	(segment
		(start 415.031174 -373.131334)
		(end 415.031428 -373.131334)
		(width 0.14224)
		(layer "In6.Cu")
		(net "P5E_CPU0_P2_RX_DN<11>")
	)
	(segment
		(start 371.624352 -297.066462)
		(end 371.624352 -296.353484)
		(width 0.14224)
		(layer "In6.Cu")
		(net "P5E_CPU0_P2_RX_DN<11>")
	)
	(segment
		(start 417.975796 -388.732268)
		(end 417.901628 -388.553198)
		(width 0.14224)
		(layer "In6.Cu")
		(net "P5E_CPU0_P2_RX_DN<11>")
	)
	(segment
		(start 381.227076 -310.396128)
		(end 374.924574 -302.716692)
		(width 0.14224)
		(layer "In6.Cu")
		(net "P5E_CPU0_P2_RX_DN<11>")
	)
	(segment
		(start 417.469828 -389.59536)
		(end 417.63315 -389.200898)
		(width 0.14224)
		(layer "In6.Cu")
		(net "P5E_CPU0_P2_RX_DN<11>")
	)
	(segment
		(start 417.094416 -393.716764)
		(end 417.094416 -393.545822)
		(width 0.14224)
		(layer "In6.Cu")
		(net "P5E_CPU0_P2_RX_DN<11>")
	)
	(segment
		(start 370.972842 -293.871396)
		(end 371.011958 -293.848536)
		(width 0.1143)
		(layer "In6.Cu")
		(net "P5E_CPU0_P2_RX_DN<11>")
	)
	(segment
		(start 418.244274 -388.084314)
		(end 421.047164 -381.316992)
		(width 0.14224)
		(layer "In6.Cu")
		(net "P5E_CPU0_P2_RX_DN<11>")
	)
	(segment
		(start 399.731484 -365.524288)
		(end 393.02436 -349.331788)
		(width 0.14224)
		(layer "In6.Cu")
		(net "P5E_CPU0_P2_RX_DN<11>")
	)
	(segment
		(start 417.543996 -389.77443)
		(end 417.469828 -389.59536)
		(width 0.14224)
		(layer "In6.Cu")
		(net "P5E_CPU0_P2_RX_DN<11>")
	)
	(segment
		(start 416.972242 -393.787376)
		(end 416.97275 -393.786868)
		(width 0.14224)
		(layer "In6.Cu")
		(net "P5E_CPU0_P2_RX_DN<11>")
	)
	(segment
		(start 415.031428 -373.131334)
		(end 409.262072 -371.687344)
		(width 0.14224)
		(layer "In6.Cu")
		(net "P5E_CPU0_P2_RX_DN<11>")
	)
	(segment
		(start 371.011958 -290.608512)
		(end 371.042438 -290.590732)
		(width 0.1143)
		(layer "In6.Cu")
		(net "P5E_CPU0_P2_RX_DN<11>")
	)
	(segment
		(start 371.442742 -286.581342)
		(end 371.512592 -286.540956)
		(width 0.1143)
		(layer "In6.Cu")
		(net "P5E_CPU0_P2_RX_DN<11>")
	)
	(segment
		(start 370.972842 -289.01136)
		(end 371.011958 -288.9885)
		(width 0.1143)
		(layer "In6.Cu")
		(net "P5E_CPU0_P2_RX_DN<11>")
	)
	(segment
		(start 371.04447 -288.36239)
		(end 371.011958 -288.343594)
		(width 0.1143)
		(layer "In6.Cu")
		(net "P5E_CPU0_P2_RX_DN<11>")
	)
	(segment
		(start 417.113974 -390.851644)
		(end 417.380928 -390.168638)
		(width 0.14224)
		(layer "In6.Cu")
		(net "P5E_CPU0_P2_RX_DN<11>")
	)
	(segment
		(start 370.975382 -287.389824)
		(end 371.042438 -287.350708)
		(width 0.1143)
		(layer "In6.Cu")
		(net "P5E_CPU0_P2_RX_DN<11>")
	)
	(segment
		(start 417.086288 -392.31316)
		(end 417.086288 -391.000488)
		(width 0.14224)
		(layer "In6.Cu")
		(net "P5E_CPU0_P2_RX_DN<11>")
	)
	(segment
		(start 417.094416 -393.545822)
		(end 416.777424 -393.22883)
		(width 0.14224)
		(layer "In6.Cu")
		(net "P5E_CPU0_P2_RX_DN<11>")
	)
	(segment
		(start 416.78225 -392.616944)
		(end 417.086288 -392.31316)
		(width 0.14224)
		(layer "In6.Cu")
		(net "P5E_CPU0_P2_RX_DN<11>")
	)
	(segment
		(start 392.647932 -348.090998)
		(end 391.444988 -342.043004)
		(width 0.14224)
		(layer "In6.Cu")
		(net "P5E_CPU0_P2_RX_DN<11>")
	)
	(segment
		(start 372.399052 -298.937172)
		(end 371.624352 -297.066462)
		(width 0.14224)
		(layer "In6.Cu")
		(net "P5E_CPU0_P2_RX_DN<11>")
	)
	(segment
		(start 371.042438 -294.841168)
		(end 371.011958 -294.823388)
		(width 0.1143)
		(layer "In6.Cu")
		(net "P5E_CPU0_P2_RX_DN<11>")
	)
	(segment
		(start 371.670072 -296.279316)
		(end 371.670072 -296.086276)
		(width 0.1143)
		(layer "In6.Cu")
		(net "P5E_CPU0_P2_RX_DN<11>")
	)
	(segment
		(start 388.166864 -323.093588)
		(end 381.987044 -311.533286)
		(width 0.14224)
		(layer "In6.Cu")
		(net "P5E_CPU0_P2_RX_DN<11>")
	)
	(segment
		(start 381.987044 -311.533286)
		(end 381.227076 -310.396128)
		(width 0.14224)
		(layer "In6.Cu")
		(net "P5E_CPU0_P2_RX_DN<11>")
	)
	(segment
		(start 391.439146 -342.00338)
		(end 390.95934 -337.133184)
		(width 0.14224)
		(layer "In6.Cu")
		(net "P5E_CPU0_P2_RX_DN<11>")
	)
	(segment
		(start 416.97275 -393.786868)
		(end 417.094416 -393.716764)
		(width 0.14224)
		(layer "In6.Cu")
		(net "P5E_CPU0_P2_RX_DN<11>")
	)
	(segment
		(start 419.347904 -377.714002)
		(end 419.347904 -376.632724)
		(width 0.14224)
		(layer "In6.Cu")
		(net "P5E_CPU0_P2_RX_DN<11>")
	)
	(segment
		(start 371.511576 -295.650666)
		(end 371.48262 -295.633902)
		(width 0.1143)
		(layer "In6.Cu")
		(net "P5E_CPU0_P2_RX_DN<11>")
	)
	(segment
		(start 370.972842 -292.251384)
		(end 371.011958 -292.228524)
		(width 0.1143)
		(layer "In6.Cu")
		(net "P5E_CPU0_P2_RX_DN<11>")
	)
	(segment
		(start 416.777424 -393.22883)
		(end 416.78225 -392.616944)
		(width 0.14224)
		(layer "In6.Cu")
		(net "P5E_CPU0_P2_RX_DN<11>")
	)
	(segment
		(start 370.972842 -290.631372)
		(end 371.011958 -290.608512)
		(width 0.1143)
		(layer "In6.Cu")
		(net "P5E_CPU0_P2_RX_DN<11>")
	)
	(segment
		(start 371.513608 -285.931864)
		(end 371.481858 -285.913576)
		(width 0.1143)
		(layer "In6.Cu")
		(net "P5E_CPU0_P2_RX_DN<11>")
	)
	(segment
		(start 418.772086 -375.229628)
		(end 418.764212 -375.221754)
		(width 0.14224)
		(layer "In6.Cu")
		(net "P5E_CPU0_P2_RX_DN<11>")
	)
	(segment
		(start 371.480842 -295.632886)
		(end 371.442742 -295.610534)
		(width 0.1143)
		(layer "In6.Cu")
		(net "P5E_CPU0_P2_RX_DN<11>")
	)
	(segment
		(start 370.735606 -284.698948)
		(end 370.652802 -284.616144)
		(width 0.1143)
		(layer "In6.Cu")
		(net "P5E_CPU0_P2_RX_DN<11>")
	)
	(segment
		(start 371.011958 -288.9885)
		(end 371.042438 -288.97072)
		(width 0.1143)
		(layer "In6.Cu")
		(net "P5E_CPU0_P2_RX_DN<11>")
	)
	(segment
		(start 420.52875 -378.826014)
		(end 420.487602 -378.826014)
		(width 0.14224)
		(layer "In6.Cu")
		(net "P5E_CPU0_P2_RX_DN<11>")
	)
	(segment
		(start 374.924574 -302.716692)
		(end 372.399052 -298.937172)
		(width 0.14224)
		(layer "In6.Cu")
		(net "P5E_CPU0_P2_RX_DN<11>")
	)
	(segment
		(start 401.355306 -367.192052)
		(end 399.820384 -365.65713)
		(width 0.14224)
		(layer "In6.Cu")
		(net "P5E_CPU0_P2_RX_DN<11>")
	)
	(segment
		(start 416.618928 -393.69238)
		(end 416.972242 -393.787376)
		(width 0.14224)
		(layer "In6.Cu")
		(net "P5E_CPU0_P2_RX_DN<11>")
	)
	(segment
		(start 417.63315 -389.200898)
		(end 417.812728 -389.126476)
		(width 0.14224)
		(layer "In6.Cu")
		(net "P5E_CPU0_P2_RX_DN<11>")
	)
	(segment
		(start 371.670072 -296.086276)
		(end 371.669564 -296.085768)
		(width 0.1143)
		(layer "In6.Cu")
		(net "P5E_CPU0_P2_RX_DN<11>")
	)
	(segment
		(start 370.652802 -284.616144)
		(end 370.35486 -284.616144)
		(width 0.1143)
		(layer "In6.Cu")
		(net "P5E_CPU0_P2_RX_DN<11>")
	)
	(arc
		(start 420.487602 -378.826014)
		(mid 420.17682 -378.764231)
		(end 419.913308 -378.58827)
		(width 0.14224)
		(layer "In6.Cu")
		(net "P5E_CPU0_P2_RX_DN<11>")
	)
	(arc
		(start 371.19941 -288.66592)
		(mid 371.158444 -288.495514)
		(end 371.04447 -288.36239)
		(width 0.1143)
		(layer "In6.Cu")
		(net "P5E_CPU0_P2_RX_DN<11>")
	)
	(arc
		(start 418.845238 -375.317004)
		(mid 418.810416 -375.271848)
		(end 418.772086 -375.229628)
		(width 0.14224)
		(layer "In6.Cu")
		(net "P5E_CPU0_P2_RX_DN<11>")
	)
	(arc
		(start 418.764212 -375.221754)
		(mid 417.037116 -373.927567)
		(end 415.031174 -373.131334)
		(width 0.14224)
		(layer "In6.Cu")
		(net "P5E_CPU0_P2_RX_DN<11>")
	)
	(arc
		(start 421.047164 -381.316738)
		(mid 421.054519 -381.292842)
		(end 421.05707 -381.26797)
		(width 0.14224)
		(layer "In6.Cu")
		(net "P5E_CPU0_P2_RX_DN<11>")
	)
	(arc
		(start 391.444988 -342.043004)
		(mid 391.441577 -342.023264)
		(end 391.439146 -342.00338)
		(width 0.14224)
		(layer "In6.Cu")
		(net "P5E_CPU0_P2_RX_DN<11>")
	)
	(arc
		(start 417.086288 -391.000488)
		(mid 417.093201 -390.924777)
		(end 417.113974 -390.851644)
		(width 0.14224)
		(layer "In6.Cu")
		(net "P5E_CPU0_P2_RX_DN<11>")
	)
	(arc
		(start 370.972842 -291.560504)
		(mid 370.729515 -291.095938)
		(end 370.972842 -290.631372)
		(width 0.1143)
		(layer "In6.Cu")
		(net "P5E_CPU0_P2_RX_DN<11>")
	)
	(arc
		(start 370.972842 -294.800528)
		(mid 370.729515 -294.335962)
		(end 370.972842 -293.871396)
		(width 0.1143)
		(layer "In6.Cu")
		(net "P5E_CPU0_P2_RX_DN<11>")
	)
	(arc
		(start 371.042438 -290.590732)
		(mid 371.199415 -290.285932)
		(end 371.042438 -289.981132)
		(width 0.1143)
		(layer "In6.Cu")
		(net "P5E_CPU0_P2_RX_DN<11>")
	)
	(arc
		(start 371.042438 -287.350708)
		(mid 371.157865 -287.217332)
		(end 371.19941 -287.045908)
		(width 0.1143)
		(layer "In6.Cu")
		(net "P5E_CPU0_P2_RX_DN<11>")
	)
	(arc
		(start 371.669564 -295.955974)
		(mid 371.627685 -295.784105)
		(end 371.511576 -295.650666)
		(width 0.1143)
		(layer "In6.Cu")
		(net "P5E_CPU0_P2_RX_DN<11>")
	)
	(arc
		(start 421.05707 -379.36805)
		(mid 421.033563 -379.249964)
		(end 420.966646 -379.149864)
		(width 0.14224)
		(layer "In6.Cu")
		(net "P5E_CPU0_P2_RX_DN<11>")
	)
	(arc
		(start 420.723568 -378.906786)
		(mid 420.634199 -378.847008)
		(end 420.52875 -378.826014)
		(width 0.14224)
		(layer "In6.Cu")
		(net "P5E_CPU0_P2_RX_DN<11>")
	)
	(arc
		(start 370.972842 -285.08071)
		(mid 370.820855 -284.924202)
		(end 370.739416 -284.721808)
		(width 0.1143)
		(layer "In6.Cu")
		(net "P5E_CPU0_P2_RX_DN<11>")
	)
	(arc
		(start 371.042438 -293.830756)
		(mid 371.199415 -293.525956)
		(end 371.042438 -293.221156)
		(width 0.1143)
		(layer "In6.Cu")
		(net "P5E_CPU0_P2_RX_DN<11>")
	)
	(arc
		(start 371.669564 -286.236156)
		(mid 371.625493 -286.06662)
		(end 371.513608 -285.931864)
		(width 0.1143)
		(layer "In6.Cu")
		(net "P5E_CPU0_P2_RX_DN<11>")
	)
	(arc
		(start 371.042438 -288.97072)
		(mid 371.157865 -288.837344)
		(end 371.19941 -288.66592)
		(width 0.1143)
		(layer "In6.Cu")
		(net "P5E_CPU0_P2_RX_DN<11>")
	)
	(arc
		(start 370.739416 -284.721808)
		(mid 370.737393 -284.710398)
		(end 370.735606 -284.698948)
		(width 0.1143)
		(layer "In6.Cu")
		(net "P5E_CPU0_P2_RX_DN<11>")
	)
	(arc
		(start 371.442742 -295.610534)
		(mid 371.263929 -295.408184)
		(end 371.19941 -295.145968)
		(width 0.1143)
		(layer "In6.Cu")
		(net "P5E_CPU0_P2_RX_DN<11>")
	)
	(arc
		(start 370.972842 -288.320734)
		(mid 370.794029 -288.118384)
		(end 370.72951 -287.856168)
		(width 0.1143)
		(layer "In6.Cu")
		(net "P5E_CPU0_P2_RX_DN<11>")
	)
	(arc
		(start 401.442682 -367.259108)
		(mid 401.396722 -367.228539)
		(end 401.355306 -367.192052)
		(width 0.14224)
		(layer "In6.Cu")
		(net "P5E_CPU0_P2_RX_DN<11>")
	)
	(arc
		(start 393.02436 -349.331788)
		(mid 392.805675 -348.720638)
		(end 392.647932 -348.090998)
		(width 0.14224)
		(layer "In6.Cu")
		(net "P5E_CPU0_P2_RX_DN<11>")
	)
	(arc
		(start 370.972842 -293.180516)
		(mid 370.729515 -292.71595)
		(end 370.972842 -292.251384)
		(width 0.1143)
		(layer "In6.Cu")
		(net "P5E_CPU0_P2_RX_DN<11>")
	)
	(arc
		(start 419.566344 -378.241306)
		(mid 419.404692 -377.999377)
		(end 419.347904 -377.714002)
		(width 0.14224)
		(layer "In6.Cu")
		(net "P5E_CPU0_P2_RX_DN<11>")
	)
	(arc
		(start 419.33749 -376.506486)
		(mid 419.158356 -375.884022)
		(end 418.845238 -375.317004)
		(width 0.14224)
		(layer "In6.Cu")
		(net "P5E_CPU0_P2_RX_DN<11>")
	)
	(arc
		(start 371.19941 -295.145968)
		(mid 371.157861 -294.974546)
		(end 371.042438 -294.841168)
		(width 0.1143)
		(layer "In6.Cu")
		(net "P5E_CPU0_P2_RX_DN<11>")
	)
	(arc
		(start 371.19941 -287.045908)
		(mid 371.263925 -286.783689)
		(end 371.442742 -286.581342)
		(width 0.1143)
		(layer "In6.Cu")
		(net "P5E_CPU0_P2_RX_DN<11>")
	)
	(arc
		(start 371.042438 -292.210744)
		(mid 371.199415 -291.905944)
		(end 371.042438 -291.601144)
		(width 0.1143)
		(layer "In6.Cu")
		(net "P5E_CPU0_P2_RX_DN<11>")
	)
	(arc
		(start 371.442742 -285.890716)
		(mid 371.263929 -285.688366)
		(end 371.19941 -285.42615)
		(width 0.1143)
		(layer "In6.Cu")
		(net "P5E_CPU0_P2_RX_DN<11>")
	)
	(arc
		(start 399.820384 -365.65713)
		(mid 399.769412 -365.595076)
		(end 399.731484 -365.524288)
		(width 0.14224)
		(layer "In6.Cu")
		(net "P5E_CPU0_P2_RX_DN<11>")
	)
	(arc
		(start 371.515386 -286.538924)
		(mid 371.628793 -286.406035)
		(end 371.669564 -286.236156)
		(width 0.1143)
		(layer "In6.Cu")
		(net "P5E_CPU0_P2_RX_DN<11>")
	)
	(arc
		(start 370.972842 -289.940492)
		(mid 370.729515 -289.475926)
		(end 370.972842 -289.01136)
		(width 0.1143)
		(layer "In6.Cu")
		(net "P5E_CPU0_P2_RX_DN<11>")
	)
	(arc
		(start 371.19941 -285.42615)
		(mid 371.157861 -285.254728)
		(end 371.042438 -285.12135)
		(width 0.1143)
		(layer "In6.Cu")
		(net "P5E_CPU0_P2_RX_DN<11>")
	)
	(arc
		(start 370.72951 -287.856168)
		(mid 370.794746 -287.592577)
		(end 370.975382 -287.389824)
		(width 0.1143)
		(layer "In6.Cu")
		(net "P5E_CPU0_P2_RX_DN<11>")
	)
	(arc
		(start 419.347904 -376.632724)
		(mid 419.345348 -376.569386)
		(end 419.33749 -376.506486)
		(width 0.14224)
		(layer "In6.Cu")
		(net "P5E_CPU0_P2_RX_DN<11>")
	)
	(segment
		(start 369.888008 -285.970218)
		(end 370.35486 -286.236156)
		(width 0.12954)
		(layer "F.Cu")
		(net "P5E_CPU0_P2_RX_DN<10>")
	)
	(segment
		(start 414.898332 -393.69238)
		(end 415.419032 -393.69238)
		(width 0.127)
		(layer "F.Cu")
		(net "P5E_CPU0_P2_RX_DN<10>")
	)
	(segment
		(start 380.502414 -310.990234)
		(end 374.200166 -303.311052)
		(width 0.14224)
		(layer "In6.Cu")
		(net "P5E_CPU0_P2_RX_DN<10>")
	)
	(segment
		(start 370.652802 -286.236156)
		(end 370.35486 -286.236156)
		(width 0.1143)
		(layer "In6.Cu")
		(net "P5E_CPU0_P2_RX_DN<10>")
	)
	(segment
		(start 374.200166 -303.311052)
		(end 371.57279 -299.378878)
		(width 0.14224)
		(layer "In6.Cu")
		(net "P5E_CPU0_P2_RX_DN<10>")
	)
	(segment
		(start 416.068764 -381.660654)
		(end 417.005262 -379.398784)
		(width 0.14224)
		(layer "In6.Cu")
		(net "P5E_CPU0_P2_RX_DN<10>")
	)
	(segment
		(start 415.582354 -392.616944)
		(end 415.886392 -392.31316)
		(width 0.14224)
		(layer "In6.Cu")
		(net "P5E_CPU0_P2_RX_DN<10>")
	)
	(segment
		(start 370.729764 -296.085768)
		(end 370.729764 -295.955974)
		(width 0.1143)
		(layer "In6.Cu")
		(net "P5E_CPU0_P2_RX_DN<10>")
	)
	(segment
		(start 415.89452 -393.716764)
		(end 415.89452 -393.545822)
		(width 0.14224)
		(layer "In6.Cu")
		(net "P5E_CPU0_P2_RX_DN<10>")
	)
	(segment
		(start 370.071904 -289.963352)
		(end 370.032788 -289.940492)
		(width 0.1143)
		(layer "In6.Cu")
		(net "P5E_CPU0_P2_RX_DN<10>")
	)
	(segment
		(start 370.104416 -288.36239)
		(end 370.071904 -288.343594)
		(width 0.1143)
		(layer "In6.Cu")
		(net "P5E_CPU0_P2_RX_DN<10>")
	)
	(segment
		(start 415.419032 -393.69238)
		(end 415.772346 -393.787376)
		(width 0.14224)
		(layer "In6.Cu")
		(net "P5E_CPU0_P2_RX_DN<10>")
	)
	(segment
		(start 415.886392 -388.6327)
		(end 415.749232 -388.49554)
		(width 0.14224)
		(layer "In6.Cu")
		(net "P5E_CPU0_P2_RX_DN<10>")
	)
	(segment
		(start 390.490964 -341.936832)
		(end 390.029446 -337.251548)
		(width 0.14224)
		(layer "In6.Cu")
		(net "P5E_CPU0_P2_RX_DN<10>")
	)
	(segment
		(start 370.543836 -295.634664)
		(end 370.542566 -295.633902)
		(width 0.1143)
		(layer "In6.Cu")
		(net "P5E_CPU0_P2_RX_DN<10>")
	)
	(segment
		(start 370.684552 -296.353484)
		(end 370.684552 -296.325036)
		(width 0.1143)
		(layer "In6.Cu")
		(net "P5E_CPU0_P2_RX_DN<10>")
	)
	(segment
		(start 415.749232 -387.36778)
		(end 415.749232 -386.94106)
		(width 0.14224)
		(layer "In6.Cu")
		(net "P5E_CPU0_P2_RX_DN<10>")
	)
	(segment
		(start 370.546376 -295.635934)
		(end 370.543836 -295.634664)
		(width 0.1143)
		(layer "In6.Cu")
		(net "P5E_CPU0_P2_RX_DN<10>")
	)
	(segment
		(start 417.0045 -375.598944)
		(end 416.789616 -375.100342)
		(width 0.14224)
		(layer "In6.Cu")
		(net "P5E_CPU0_P2_RX_DN<10>")
	)
	(segment
		(start 415.749232 -389.6233)
		(end 415.749232 -389.19658)
		(width 0.14224)
		(layer "In6.Cu")
		(net "P5E_CPU0_P2_RX_DN<10>")
	)
	(segment
		(start 415.772854 -393.786868)
		(end 415.89452 -393.716764)
		(width 0.14224)
		(layer "In6.Cu")
		(net "P5E_CPU0_P2_RX_DN<10>")
	)
	(segment
		(start 415.886392 -387.93166)
		(end 415.886392 -387.50494)
		(width 0.14224)
		(layer "In6.Cu")
		(net "P5E_CPU0_P2_RX_DN<10>")
	)
	(segment
		(start 381.187198 -312.015124)
		(end 380.502414 -310.990234)
		(width 0.14224)
		(layer "In6.Cu")
		(net "P5E_CPU0_P2_RX_DN<10>")
	)
	(segment
		(start 398.8435 -365.93907)
		(end 391.93216 -349.25381)
		(width 0.14224)
		(layer "In6.Cu")
		(net "P5E_CPU0_P2_RX_DN<10>")
	)
	(segment
		(start 370.730272 -296.086276)
		(end 370.729764 -296.085768)
		(width 0.1143)
		(layer "In6.Cu")
		(net "P5E_CPU0_P2_RX_DN<10>")
	)
	(segment
		(start 415.886392 -389.76046)
		(end 415.749232 -389.6233)
		(width 0.14224)
		(layer "In6.Cu")
		(net "P5E_CPU0_P2_RX_DN<10>")
	)
	(segment
		(start 370.542566 -295.633902)
		(end 370.541804 -295.633394)
		(width 0.1143)
		(layer "In6.Cu")
		(net "P5E_CPU0_P2_RX_DN<10>")
	)
	(segment
		(start 370.541804 -286.558482)
		(end 370.575332 -286.538924)
		(width 0.1143)
		(layer "In6.Cu")
		(net "P5E_CPU0_P2_RX_DN<10>")
	)
	(segment
		(start 415.577528 -393.22883)
		(end 415.582354 -392.616944)
		(width 0.14224)
		(layer "In6.Cu")
		(net "P5E_CPU0_P2_RX_DN<10>")
	)
	(segment
		(start 415.749232 -389.19658)
		(end 415.886392 -389.05942)
		(width 0.14224)
		(layer "In6.Cu")
		(net "P5E_CPU0_P2_RX_DN<10>")
	)
	(segment
		(start 370.102384 -294.841168)
		(end 370.071904 -294.823388)
		(width 0.1143)
		(layer "In6.Cu")
		(net "P5E_CPU0_P2_RX_DN<10>")
	)
	(segment
		(start 370.722652 -286.306006)
		(end 370.652802 -286.236156)
		(width 0.1143)
		(layer "In6.Cu")
		(net "P5E_CPU0_P2_RX_DN<10>")
	)
	(segment
		(start 414.580324 -373.984012)
		(end 408.972004 -372.580916)
		(width 0.14224)
		(layer "In6.Cu")
		(net "P5E_CPU0_P2_RX_DN<10>")
	)
	(segment
		(start 408.858466 -372.535704)
		(end 400.913346 -368.034824)
		(width 0.14224)
		(layer "In6.Cu")
		(net "P5E_CPU0_P2_RX_DN<10>")
	)
	(segment
		(start 370.071904 -288.343594)
		(end 370.032788 -288.320734)
		(width 0.1143)
		(layer "In6.Cu")
		(net "P5E_CPU0_P2_RX_DN<10>")
	)
	(segment
		(start 370.071904 -293.848536)
		(end 370.102384 -293.830756)
		(width 0.1143)
		(layer "In6.Cu")
		(net "P5E_CPU0_P2_RX_DN<10>")
	)
	(segment
		(start 400.75231 -367.912396)
		(end 398.974818 -366.135158)
		(width 0.14224)
		(layer "In6.Cu")
		(net "P5E_CPU0_P2_RX_DN<10>")
	)
	(segment
		(start 415.886392 -387.50494)
		(end 415.749232 -387.36778)
		(width 0.14224)
		(layer "In6.Cu")
		(net "P5E_CPU0_P2_RX_DN<10>")
	)
	(segment
		(start 415.772346 -393.787376)
		(end 415.772854 -393.786868)
		(width 0.14224)
		(layer "In6.Cu")
		(net "P5E_CPU0_P2_RX_DN<10>")
	)
	(segment
		(start 370.5479 -295.63695)
		(end 370.546376 -295.635934)
		(width 0.1143)
		(layer "In6.Cu")
		(net "P5E_CPU0_P2_RX_DN<10>")
	)
	(segment
		(start 370.071904 -291.583364)
		(end 370.032788 -291.560504)
		(width 0.1143)
		(layer "In6.Cu")
		(net "P5E_CPU0_P2_RX_DN<10>")
	)
	(segment
		(start 415.749232 -386.94106)
		(end 415.886392 -386.8039)
		(width 0.14224)
		(layer "In6.Cu")
		(net "P5E_CPU0_P2_RX_DN<10>")
	)
	(segment
		(start 370.684552 -296.325036)
		(end 370.730272 -296.279316)
		(width 0.1143)
		(layer "In6.Cu")
		(net "P5E_CPU0_P2_RX_DN<10>")
	)
	(segment
		(start 370.035328 -287.389824)
		(end 370.102384 -287.350708)
		(width 0.1143)
		(layer "In6.Cu")
		(net "P5E_CPU0_P2_RX_DN<10>")
	)
	(segment
		(start 370.102384 -291.601144)
		(end 370.071904 -291.583364)
		(width 0.1143)
		(layer "In6.Cu")
		(net "P5E_CPU0_P2_RX_DN<10>")
	)
	(segment
		(start 415.89452 -393.545822)
		(end 415.577528 -393.22883)
		(width 0.14224)
		(layer "In6.Cu")
		(net "P5E_CPU0_P2_RX_DN<10>")
	)
	(segment
		(start 370.541804 -295.633394)
		(end 370.540788 -295.632886)
		(width 0.1143)
		(layer "In6.Cu")
		(net "P5E_CPU0_P2_RX_DN<10>")
	)
	(segment
		(start 415.886392 -392.31316)
		(end 415.886392 -389.76046)
		(width 0.14224)
		(layer "In6.Cu")
		(net "P5E_CPU0_P2_RX_DN<10>")
	)
	(segment
		(start 370.102384 -293.221156)
		(end 370.071904 -293.203376)
		(width 0.1143)
		(layer "In6.Cu")
		(net "P5E_CPU0_P2_RX_DN<10>")
	)
	(segment
		(start 415.886392 -386.8039)
		(end 415.886392 -382.578102)
		(width 0.14224)
		(layer "In6.Cu")
		(net "P5E_CPU0_P2_RX_DN<10>")
	)
	(segment
		(start 371.57279 -299.378878)
		(end 370.684552 -297.234102)
		(width 0.14224)
		(layer "In6.Cu")
		(net "P5E_CPU0_P2_RX_DN<10>")
	)
	(segment
		(start 370.502688 -286.581342)
		(end 370.541804 -286.558482)
		(width 0.1143)
		(layer "In6.Cu")
		(net "P5E_CPU0_P2_RX_DN<10>")
	)
	(segment
		(start 370.032788 -290.631372)
		(end 370.071904 -290.608512)
		(width 0.1143)
		(layer "In6.Cu")
		(net "P5E_CPU0_P2_RX_DN<10>")
	)
	(segment
		(start 387.275578 -323.405246)
		(end 381.187198 -312.015124)
		(width 0.14224)
		(layer "In6.Cu")
		(net "P5E_CPU0_P2_RX_DN<10>")
	)
	(segment
		(start 415.749232 -388.06882)
		(end 415.886392 -387.93166)
		(width 0.14224)
		(layer "In6.Cu")
		(net "P5E_CPU0_P2_RX_DN<10>")
	)
	(segment
		(start 390.029446 -337.251548)
		(end 387.275578 -323.405246)
		(width 0.14224)
		(layer "In6.Cu")
		(net "P5E_CPU0_P2_RX_DN<10>")
	)
	(segment
		(start 417.0299 -379.27534)
		(end 417.0299 -375.722134)
		(width 0.14224)
		(layer "In6.Cu")
		(net "P5E_CPU0_P2_RX_DN<10>")
	)
	(segment
		(start 370.032788 -292.251384)
		(end 370.071904 -292.228524)
		(width 0.1143)
		(layer "In6.Cu")
		(net "P5E_CPU0_P2_RX_DN<10>")
	)
	(segment
		(start 370.071904 -294.823388)
		(end 370.032788 -294.800528)
		(width 0.1143)
		(layer "In6.Cu")
		(net "P5E_CPU0_P2_RX_DN<10>")
	)
	(segment
		(start 370.032788 -289.01136)
		(end 370.071904 -288.9885)
		(width 0.1143)
		(layer "In6.Cu")
		(net "P5E_CPU0_P2_RX_DN<10>")
	)
	(segment
		(start 415.749232 -388.49554)
		(end 415.749232 -388.06882)
		(width 0.14224)
		(layer "In6.Cu")
		(net "P5E_CPU0_P2_RX_DN<10>")
	)
	(segment
		(start 370.032788 -293.871396)
		(end 370.071904 -293.848536)
		(width 0.1143)
		(layer "In6.Cu")
		(net "P5E_CPU0_P2_RX_DN<10>")
	)
	(segment
		(start 391.9093 -349.177102)
		(end 390.555226 -342.368886)
		(width 0.14224)
		(layer "In6.Cu")
		(net "P5E_CPU0_P2_RX_DN<10>")
	)
	(segment
		(start 370.730272 -296.279316)
		(end 370.730272 -296.086276)
		(width 0.1143)
		(layer "In6.Cu")
		(net "P5E_CPU0_P2_RX_DN<10>")
	)
	(segment
		(start 370.071904 -290.608512)
		(end 370.102384 -290.590732)
		(width 0.1143)
		(layer "In6.Cu")
		(net "P5E_CPU0_P2_RX_DN<10>")
	)
	(segment
		(start 370.102384 -289.981132)
		(end 370.071904 -289.963352)
		(width 0.1143)
		(layer "In6.Cu")
		(net "P5E_CPU0_P2_RX_DN<10>")
	)
	(segment
		(start 370.071904 -292.228524)
		(end 370.102384 -292.210744)
		(width 0.1143)
		(layer "In6.Cu")
		(net "P5E_CPU0_P2_RX_DN<10>")
	)
	(segment
		(start 370.071904 -293.203376)
		(end 370.032788 -293.180516)
		(width 0.1143)
		(layer "In6.Cu")
		(net "P5E_CPU0_P2_RX_DN<10>")
	)
	(segment
		(start 370.684552 -297.234102)
		(end 370.684552 -296.353484)
		(width 0.14224)
		(layer "In6.Cu")
		(net "P5E_CPU0_P2_RX_DN<10>")
	)
	(segment
		(start 370.540788 -295.632886)
		(end 370.502688 -295.610534)
		(width 0.1143)
		(layer "In6.Cu")
		(net "P5E_CPU0_P2_RX_DN<10>")
	)
	(segment
		(start 415.886392 -389.05942)
		(end 415.886392 -388.6327)
		(width 0.14224)
		(layer "In6.Cu")
		(net "P5E_CPU0_P2_RX_DN<10>")
	)
	(segment
		(start 370.071904 -288.9885)
		(end 370.102384 -288.97072)
		(width 0.1143)
		(layer "In6.Cu")
		(net "P5E_CPU0_P2_RX_DN<10>")
	)
	(segment
		(start 370.573554 -295.651682)
		(end 370.5479 -295.63695)
		(width 0.1143)
		(layer "In6.Cu")
		(net "P5E_CPU0_P2_RX_DN<10>")
	)
	(arc
		(start 391.93216 -349.25381)
		(mid 391.918844 -349.216018)
		(end 391.9093 -349.177102)
		(width 0.14224)
		(layer "In6.Cu")
		(net "P5E_CPU0_P2_RX_DN<10>")
	)
	(arc
		(start 370.032788 -289.940492)
		(mid 369.789461 -289.475926)
		(end 370.032788 -289.01136)
		(width 0.1143)
		(layer "In6.Cu")
		(net "P5E_CPU0_P2_RX_DN<10>")
	)
	(arc
		(start 370.259356 -288.66592)
		(mid 370.21839 -288.495514)
		(end 370.104416 -288.36239)
		(width 0.1143)
		(layer "In6.Cu")
		(net "P5E_CPU0_P2_RX_DN<10>")
	)
	(arc
		(start 415.886392 -382.578102)
		(mid 415.932399 -382.110397)
		(end 416.068764 -381.660654)
		(width 0.14224)
		(layer "In6.Cu")
		(net "P5E_CPU0_P2_RX_DN<10>")
	)
	(arc
		(start 370.102384 -293.830756)
		(mid 370.259361 -293.525956)
		(end 370.102384 -293.221156)
		(width 0.1143)
		(layer "In6.Cu")
		(net "P5E_CPU0_P2_RX_DN<10>")
	)
	(arc
		(start 417.005262 -379.398784)
		(mid 417.023685 -379.338278)
		(end 417.0299 -379.27534)
		(width 0.14224)
		(layer "In6.Cu")
		(net "P5E_CPU0_P2_RX_DN<10>")
	)
	(arc
		(start 370.259356 -287.045908)
		(mid 370.323871 -286.783689)
		(end 370.502688 -286.581342)
		(width 0.1143)
		(layer "In6.Cu")
		(net "P5E_CPU0_P2_RX_DN<10>")
	)
	(arc
		(start 370.032788 -294.800528)
		(mid 369.789461 -294.335962)
		(end 370.032788 -293.871396)
		(width 0.1143)
		(layer "In6.Cu")
		(net "P5E_CPU0_P2_RX_DN<10>")
	)
	(arc
		(start 398.974818 -366.135158)
		(mid 398.899493 -366.043587)
		(end 398.8435 -365.93907)
		(width 0.14224)
		(layer "In6.Cu")
		(net "P5E_CPU0_P2_RX_DN<10>")
	)
	(arc
		(start 370.502688 -295.610534)
		(mid 370.323875 -295.408184)
		(end 370.259356 -295.145968)
		(width 0.1143)
		(layer "In6.Cu")
		(net "P5E_CPU0_P2_RX_DN<10>")
	)
	(arc
		(start 370.729764 -295.955974)
		(mid 370.706936 -295.827493)
		(end 370.641372 -295.714674)
		(width 0.1143)
		(layer "In6.Cu")
		(net "P5E_CPU0_P2_RX_DN<10>")
	)
	(arc
		(start 370.032788 -293.180516)
		(mid 369.789461 -292.71595)
		(end 370.032788 -292.251384)
		(width 0.1143)
		(layer "In6.Cu")
		(net "P5E_CPU0_P2_RX_DN<10>")
	)
	(arc
		(start 416.70097 -374.99544)
		(mid 415.730022 -374.44911)
		(end 414.701736 -374.020334)
		(width 0.14224)
		(layer "In6.Cu")
		(net "P5E_CPU0_P2_RX_DN<10>")
	)
	(arc
		(start 370.032788 -288.320734)
		(mid 369.853975 -288.118384)
		(end 369.789456 -287.856168)
		(width 0.1143)
		(layer "In6.Cu")
		(net "P5E_CPU0_P2_RX_DN<10>")
	)
	(arc
		(start 369.789456 -287.856168)
		(mid 369.854692 -287.592577)
		(end 370.035328 -287.389824)
		(width 0.1143)
		(layer "In6.Cu")
		(net "P5E_CPU0_P2_RX_DN<10>")
	)
	(arc
		(start 370.102384 -292.210744)
		(mid 370.259361 -291.905944)
		(end 370.102384 -291.601144)
		(width 0.1143)
		(layer "In6.Cu")
		(net "P5E_CPU0_P2_RX_DN<10>")
	)
	(arc
		(start 408.972004 -372.580916)
		(mid 408.913758 -372.56202)
		(end 408.858466 -372.535704)
		(width 0.14224)
		(layer "In6.Cu")
		(net "P5E_CPU0_P2_RX_DN<10>")
	)
	(arc
		(start 370.102384 -287.350708)
		(mid 370.217811 -287.217332)
		(end 370.259356 -287.045908)
		(width 0.1143)
		(layer "In6.Cu")
		(net "P5E_CPU0_P2_RX_DN<10>")
	)
	(arc
		(start 390.555226 -342.368886)
		(mid 390.517796 -342.153647)
		(end 390.490964 -341.936832)
		(width 0.14224)
		(layer "In6.Cu")
		(net "P5E_CPU0_P2_RX_DN<10>")
	)
	(arc
		(start 400.913346 -368.034824)
		(mid 400.828688 -367.979056)
		(end 400.75231 -367.912396)
		(width 0.14224)
		(layer "In6.Cu")
		(net "P5E_CPU0_P2_RX_DN<10>")
	)
	(arc
		(start 370.641372 -295.714674)
		(mid 370.609413 -295.681079)
		(end 370.573554 -295.651682)
		(width 0.1143)
		(layer "In6.Cu")
		(net "P5E_CPU0_P2_RX_DN<10>")
	)
	(arc
		(start 370.102384 -288.97072)
		(mid 370.217811 -288.837344)
		(end 370.259356 -288.66592)
		(width 0.1143)
		(layer "In6.Cu")
		(net "P5E_CPU0_P2_RX_DN<10>")
	)
	(arc
		(start 414.701736 -374.020334)
		(mid 414.641445 -374.000787)
		(end 414.580324 -373.984012)
		(width 0.14224)
		(layer "In6.Cu")
		(net "P5E_CPU0_P2_RX_DN<10>")
	)
	(arc
		(start 416.789616 -375.100342)
		(mid 416.753109 -375.041286)
		(end 416.70097 -374.99544)
		(width 0.14224)
		(layer "In6.Cu")
		(net "P5E_CPU0_P2_RX_DN<10>")
	)
	(arc
		(start 370.102384 -290.590732)
		(mid 370.259361 -290.285932)
		(end 370.102384 -289.981132)
		(width 0.1143)
		(layer "In6.Cu")
		(net "P5E_CPU0_P2_RX_DN<10>")
	)
	(arc
		(start 370.259356 -295.145968)
		(mid 370.217807 -294.974546)
		(end 370.102384 -294.841168)
		(width 0.1143)
		(layer "In6.Cu")
		(net "P5E_CPU0_P2_RX_DN<10>")
	)
	(arc
		(start 417.0299 -375.722134)
		(mid 417.023478 -375.659246)
		(end 417.0045 -375.598944)
		(width 0.14224)
		(layer "In6.Cu")
		(net "P5E_CPU0_P2_RX_DN<10>")
	)
	(arc
		(start 370.032788 -291.560504)
		(mid 369.789461 -291.095938)
		(end 370.032788 -290.631372)
		(width 0.1143)
		(layer "In6.Cu")
		(net "P5E_CPU0_P2_RX_DN<10>")
	)
	(arc
		(start 370.575332 -286.538924)
		(mid 370.67122 -286.436516)
		(end 370.722652 -286.306006)
		(width 0.1143)
		(layer "In6.Cu")
		(net "P5E_CPU0_P2_RX_DN<10>")
	)
	(segment
		(start 402.898356 -393.69238)
		(end 403.419056 -393.69238)
		(width 0.127)
		(layer "F.Cu")
		(net "P5E_CPU0_P2_RX_DN<0>")
	)
	(segment
		(start 361.89793 -281.920188)
		(end 362.364782 -282.186126)
		(width 0.12954)
		(layer "F.Cu")
		(net "P5E_CPU0_P2_RX_DN<0>")
	)
	(segment
		(start 402.20138 -388.754874)
		(end 395.702536 -380.979172)
		(width 0.14224)
		(layer "In6.Cu")
		(net "P5E_CPU0_P2_RX_DN<0>")
	)
	(segment
		(start 378.354082 -326.674734)
		(end 373.720868 -318.006222)
		(width 0.14224)
		(layer "In6.Cu")
		(net "P5E_CPU0_P2_RX_DN<0>")
	)
	(segment
		(start 362.269532 -283.00045)
		(end 362.269532 -282.916884)
		(width 0.1143)
		(layer "In6.Cu")
		(net "P5E_CPU0_P2_RX_DN<0>")
	)
	(segment
		(start 361.027472 -284.622494)
		(end 361.09148 -284.622748)
		(width 0.1143)
		(layer "In6.Cu")
		(net "P5E_CPU0_P2_RX_DN<0>")
	)
	(segment
		(start 403.894544 -393.716764)
		(end 403.894544 -393.545822)
		(width 0.14224)
		(layer "In6.Cu")
		(net "P5E_CPU0_P2_RX_DN<0>")
	)
	(segment
		(start 381.147574 -343.83853)
		(end 380.538482 -337.656678)
		(width 0.14224)
		(layer "In6.Cu")
		(net "P5E_CPU0_P2_RX_DN<0>")
	)
	(segment
		(start 403.374606 -390.158224)
		(end 403.181312 -390.140952)
		(width 0.14224)
		(layer "In6.Cu")
		(net "P5E_CPU0_P2_RX_DN<0>")
	)
	(segment
		(start 402.651214 -389.292846)
		(end 402.45792 -389.275574)
		(width 0.14224)
		(layer "In6.Cu")
		(net "P5E_CPU0_P2_RX_DN<0>")
	)
	(segment
		(start 360.619802 -295.565068)
		(end 360.614468 -295.559734)
		(width 0.14224)
		(layer "In6.Cu")
		(net "P5E_CPU0_P2_RX_DN<0>")
	)
	(segment
		(start 403.419056 -393.69238)
		(end 403.77237 -393.787376)
		(width 0.14224)
		(layer "In6.Cu")
		(net "P5E_CPU0_P2_RX_DN<0>")
	)
	(segment
		(start 363.220254 -303.718976)
		(end 361.33786 -299.175678)
		(width 0.14224)
		(layer "In6.Cu")
		(net "P5E_CPU0_P2_RX_DN<0>")
	)
	(segment
		(start 403.894544 -393.545822)
		(end 403.577552 -393.22883)
		(width 0.14224)
		(layer "In6.Cu")
		(net "P5E_CPU0_P2_RX_DN<0>")
	)
	(segment
		(start 361.611672 -284.128972)
		(end 361.611926 -284.128718)
		(width 0.1143)
		(layer "In6.Cu")
		(net "P5E_CPU0_P2_RX_DN<0>")
	)
	(segment
		(start 403.181312 -390.140952)
		(end 402.9075 -389.813292)
		(width 0.14224)
		(layer "In6.Cu")
		(net "P5E_CPU0_P2_RX_DN<0>")
	)
	(segment
		(start 373.720868 -318.006222)
		(end 372.303802 -315.885068)
		(width 0.14224)
		(layer "In6.Cu")
		(net "P5E_CPU0_P2_RX_DN<0>")
	)
	(segment
		(start 360.614468 -295.559734)
		(end 360.614468 -285.035498)
		(width 0.14224)
		(layer "In6.Cu")
		(net "P5E_CPU0_P2_RX_DN<0>")
	)
	(segment
		(start 380.538482 -337.656678)
		(end 378.354082 -326.674734)
		(width 0.14224)
		(layer "In6.Cu")
		(net "P5E_CPU0_P2_RX_DN<0>")
	)
	(segment
		(start 395.59992 -377.648216)
		(end 395.59992 -377.495054)
		(width 0.14224)
		(layer "In6.Cu")
		(net "P5E_CPU0_P2_RX_DN<0>")
	)
	(segment
		(start 362.732574 -282.255976)
		(end 362.662724 -282.186126)
		(width 0.1143)
		(layer "In6.Cu")
		(net "P5E_CPU0_P2_RX_DN<0>")
	)
	(segment
		(start 362.512356 -282.531312)
		(end 362.552234 -282.508706)
		(width 0.1143)
		(layer "In6.Cu")
		(net "P5E_CPU0_P2_RX_DN<0>")
	)
	(segment
		(start 403.648164 -390.48563)
		(end 403.374606 -390.158224)
		(width 0.14224)
		(layer "In6.Cu")
		(net "P5E_CPU0_P2_RX_DN<0>")
	)
	(segment
		(start 362.580936 -282.491688)
		(end 362.58246 -282.490672)
		(width 0.1143)
		(layer "In6.Cu")
		(net "P5E_CPU0_P2_RX_DN<0>")
	)
	(segment
		(start 403.582378 -392.616944)
		(end 403.886416 -392.31316)
		(width 0.14224)
		(layer "In6.Cu")
		(net "P5E_CPU0_P2_RX_DN<0>")
	)
	(segment
		(start 394.906246 -375.820686)
		(end 390.695434 -371.609874)
		(width 0.14224)
		(layer "In6.Cu")
		(net "P5E_CPU0_P2_RX_DN<0>")
	)
	(segment
		(start 402.9075 -389.813292)
		(end 402.924772 -389.620252)
		(width 0.14224)
		(layer "In6.Cu")
		(net "P5E_CPU0_P2_RX_DN<0>")
	)
	(segment
		(start 361.611926 -284.128718)
		(end 361.642406 -284.110938)
		(width 0.1143)
		(layer "In6.Cu")
		(net "P5E_CPU0_P2_RX_DN<0>")
	)
	(segment
		(start 402.924772 -389.620252)
		(end 402.651214 -389.292846)
		(width 0.14224)
		(layer "In6.Cu")
		(net "P5E_CPU0_P2_RX_DN<0>")
	)
	(segment
		(start 362.58246 -282.490672)
		(end 362.583476 -282.490164)
		(width 0.1143)
		(layer "In6.Cu")
		(net "P5E_CPU0_P2_RX_DN<0>")
	)
	(segment
		(start 395.607794 -380.716536)
		(end 395.607794 -377.65609)
		(width 0.14224)
		(layer "In6.Cu")
		(net "P5E_CPU0_P2_RX_DN<0>")
	)
	(segment
		(start 360.614468 -285.035498)
		(end 361.007406 -284.64256)
		(width 0.14224)
		(layer "In6.Cu")
		(net "P5E_CPU0_P2_RX_DN<0>")
	)
	(segment
		(start 361.33786 -299.175678)
		(end 360.619802 -295.565068)
		(width 0.14224)
		(layer "In6.Cu")
		(net "P5E_CPU0_P2_RX_DN<0>")
	)
	(segment
		(start 372.303802 -315.885068)
		(end 367.166906 -309.625746)
		(width 0.14224)
		(layer "In6.Cu")
		(net "P5E_CPU0_P2_RX_DN<0>")
	)
	(segment
		(start 390.353804 -371.098826)
		(end 383.086102 -353.552252)
		(width 0.14224)
		(layer "In6.Cu")
		(net "P5E_CPU0_P2_RX_DN<0>")
	)
	(segment
		(start 361.007406 -284.64256)
		(end 361.027472 -284.622494)
		(width 0.1143)
		(layer "In6.Cu")
		(net "P5E_CPU0_P2_RX_DN<0>")
	)
	(segment
		(start 403.577552 -393.22883)
		(end 403.582378 -392.616944)
		(width 0.14224)
		(layer "In6.Cu")
		(net "P5E_CPU0_P2_RX_DN<0>")
	)
	(segment
		(start 362.57992 -282.492196)
		(end 362.580936 -282.491688)
		(width 0.1143)
		(layer "In6.Cu")
		(net "P5E_CPU0_P2_RX_DN<0>")
	)
	(segment
		(start 367.166906 -309.625746)
		(end 363.220254 -303.718976)
		(width 0.14224)
		(layer "In6.Cu")
		(net "P5E_CPU0_P2_RX_DN<0>")
	)
	(segment
		(start 395.607794 -377.65609)
		(end 395.59992 -377.648216)
		(width 0.14224)
		(layer "In6.Cu")
		(net "P5E_CPU0_P2_RX_DN<0>")
	)
	(segment
		(start 402.45792 -389.275574)
		(end 402.184108 -388.947914)
		(width 0.14224)
		(layer "In6.Cu")
		(net "P5E_CPU0_P2_RX_DN<0>")
	)
	(segment
		(start 403.886416 -392.31316)
		(end 403.886416 -391.141712)
		(width 0.14224)
		(layer "In6.Cu")
		(net "P5E_CPU0_P2_RX_DN<0>")
	)
	(segment
		(start 383.061464 -353.470718)
		(end 381.153416 -343.878154)
		(width 0.14224)
		(layer "In6.Cu")
		(net "P5E_CPU0_P2_RX_DN<0>")
	)
	(segment
		(start 402.184108 -388.947914)
		(end 402.20138 -388.754874)
		(width 0.14224)
		(layer "In6.Cu")
		(net "P5E_CPU0_P2_RX_DN<0>")
	)
	(segment
		(start 403.772878 -393.786868)
		(end 403.894544 -393.716764)
		(width 0.14224)
		(layer "In6.Cu")
		(net "P5E_CPU0_P2_RX_DN<0>")
	)
	(segment
		(start 362.04271 -283.341572)
		(end 362.114592 -283.299408)
		(width 0.1143)
		(layer "In6.Cu")
		(net "P5E_CPU0_P2_RX_DN<0>")
	)
	(segment
		(start 403.77237 -393.787376)
		(end 403.772878 -393.786868)
		(width 0.14224)
		(layer "In6.Cu")
		(net "P5E_CPU0_P2_RX_DN<0>")
	)
	(segment
		(start 362.44022 -282.583636)
		(end 362.512356 -282.531312)
		(width 0.1143)
		(layer "In6.Cu")
		(net "P5E_CPU0_P2_RX_DN<0>")
	)
	(segment
		(start 361.09148 -284.622748)
		(end 361.496356 -284.217872)
		(width 0.1143)
		(layer "In6.Cu")
		(net "P5E_CPU0_P2_RX_DN<0>")
	)
	(segment
		(start 362.552234 -282.508706)
		(end 362.57865 -282.492958)
		(width 0.1143)
		(layer "In6.Cu")
		(net "P5E_CPU0_P2_RX_DN<0>")
	)
	(segment
		(start 362.57865 -282.492958)
		(end 362.57992 -282.492196)
		(width 0.1143)
		(layer "In6.Cu")
		(net "P5E_CPU0_P2_RX_DN<0>")
	)
	(segment
		(start 362.662724 -282.186126)
		(end 362.364782 -282.186126)
		(width 0.1143)
		(layer "In6.Cu")
		(net "P5E_CPU0_P2_RX_DN<0>")
	)
	(arc
		(start 362.269532 -282.916884)
		(mid 362.314682 -282.729669)
		(end 362.44022 -282.583636)
		(width 0.1143)
		(layer "In6.Cu")
		(net "P5E_CPU0_P2_RX_DN<0>")
	)
	(arc
		(start 362.642404 -282.437586)
		(mid 362.700023 -282.353002)
		(end 362.732574 -282.255976)
		(width 0.1143)
		(layer "In6.Cu")
		(net "P5E_CPU0_P2_RX_DN<0>")
	)
	(arc
		(start 395.59992 -377.495054)
		(mid 395.419581 -376.588897)
		(end 394.906246 -375.820686)
		(width 0.14224)
		(layer "In6.Cu")
		(net "P5E_CPU0_P2_RX_DN<0>")
	)
	(arc
		(start 383.086102 -353.552252)
		(mid 383.071794 -353.512087)
		(end 383.061464 -353.470718)
		(width 0.14224)
		(layer "In6.Cu")
		(net "P5E_CPU0_P2_RX_DN<0>")
	)
	(arc
		(start 403.886416 -391.141712)
		(mid 403.824874 -390.792763)
		(end 403.648164 -390.48563)
		(width 0.14224)
		(layer "In6.Cu")
		(net "P5E_CPU0_P2_RX_DN<0>")
	)
	(arc
		(start 361.799378 -283.806138)
		(mid 361.863893 -283.543919)
		(end 362.04271 -283.341572)
		(width 0.1143)
		(layer "In6.Cu")
		(net "P5E_CPU0_P2_RX_DN<0>")
	)
	(arc
		(start 381.153416 -343.878154)
		(mid 381.150005 -343.858414)
		(end 381.147574 -343.83853)
		(width 0.14224)
		(layer "In6.Cu")
		(net "P5E_CPU0_P2_RX_DN<0>")
	)
	(arc
		(start 395.702536 -380.979172)
		(mid 395.632062 -380.856186)
		(end 395.607794 -380.716536)
		(width 0.14224)
		(layer "In6.Cu")
		(net "P5E_CPU0_P2_RX_DN<0>")
	)
	(arc
		(start 390.695434 -371.609874)
		(mid 390.499448 -371.371176)
		(end 390.353804 -371.098826)
		(width 0.14224)
		(layer "In6.Cu")
		(net "P5E_CPU0_P2_RX_DN<0>")
	)
	(arc
		(start 362.114592 -283.299408)
		(mid 362.228475 -283.168794)
		(end 362.269532 -283.00045)
		(width 0.1143)
		(layer "In6.Cu")
		(net "P5E_CPU0_P2_RX_DN<0>")
	)
	(arc
		(start 361.496356 -284.217872)
		(mid 361.551129 -284.16968)
		(end 361.611672 -284.128972)
		(width 0.1143)
		(layer "In6.Cu")
		(net "P5E_CPU0_P2_RX_DN<0>")
	)
	(arc
		(start 361.642406 -284.110938)
		(mid 361.757833 -283.977562)
		(end 361.799378 -283.806138)
		(width 0.1143)
		(layer "In6.Cu")
		(net "P5E_CPU0_P2_RX_DN<0>")
	)
	(arc
		(start 362.583476 -282.490164)
		(mid 362.614323 -282.465425)
		(end 362.642404 -282.437586)
		(width 0.1143)
		(layer "In6.Cu")
		(net "P5E_CPU0_P2_RX_DN<0>")
	)
	(segment
		(start 346.833444 -378.68733)
		(end 347.129354 -378.39142)
		(width 0.12954)
		(layer "F.Cu")
		(net "P5E_CPU0_P1_TX_DP<9>")
	)
	(segment
		(start 347.129354 -378.39142)
		(end 347.129354 -377.68784)
		(width 0.12954)
		(layer "F.Cu")
		(net "P5E_CPU0_P1_TX_DP<9>")
	)
	(segment
		(start 347.129354 -377.68784)
		(end 346.858844 -377.41733)
		(width 0.12954)
		(layer "F.Cu")
		(net "P5E_CPU0_P1_TX_DP<9>")
	)
	(segment
		(start 352.027998 -287.59023)
		(end 351.561146 -287.856168)
		(width 0.12954)
		(layer "F.Cu")
		(net "P5E_CPU0_P1_TX_DP<9>")
	)
	(segment
		(start 347.149674 -376.161808)
		(end 347.149674 -377.1265)
		(width 0.14224)
		(layer "In4.Cu")
		(net "P5E_CPU0_P1_TX_DP<9>")
	)
	(segment
		(start 352.942906 -298.445428)
		(end 356.103174 -306.074826)
		(width 0.14224)
		(layer "In4.Cu")
		(net "P5E_CPU0_P1_TX_DP<9>")
	)
	(segment
		(start 352.655886 -289.13455)
		(end 352.656648 -289.135058)
		(width 0.1143)
		(layer "In4.Cu")
		(net "P5E_CPU0_P1_TX_DP<9>")
	)
	(segment
		(start 372.94439 -348.241112)
		(end 372.358158 -350.781366)
		(width 0.14224)
		(layer "In4.Cu")
		(net "P5E_CPU0_P1_TX_DP<9>")
	)
	(segment
		(start 352.649028 -289.130486)
		(end 352.655886 -289.13455)
		(width 0.1143)
		(layer "In4.Cu")
		(net "P5E_CPU0_P1_TX_DP<9>")
	)
	(segment
		(start 353.628198 -293.03853)
		(end 353.589082 -293.06139)
		(width 0.1143)
		(layer "In4.Cu")
		(net "P5E_CPU0_P1_TX_DP<9>")
	)
	(segment
		(start 361.94746 -365.846614)
		(end 347.504512 -375.497598)
		(width 0.14224)
		(layer "In4.Cu")
		(net "P5E_CPU0_P1_TX_DP<9>")
	)
	(segment
		(start 353.163378 -291.586412)
		(end 353.16414 -291.58692)
		(width 0.1143)
		(layer "In4.Cu")
		(net "P5E_CPU0_P1_TX_DP<9>")
	)
	(segment
		(start 353.263708 -295.48201)
		(end 353.050856 -295.694862)
		(width 0.1143)
		(layer "In4.Cu")
		(net "P5E_CPU0_P1_TX_DP<9>")
	)
	(segment
		(start 353.589082 -292.37051)
		(end 353.628198 -292.39337)
		(width 0.1143)
		(layer "In4.Cu")
		(net "P5E_CPU0_P1_TX_DP<9>")
	)
	(segment
		(start 347.149674 -377.1265)
		(end 346.858844 -377.41733)
		(width 0.14224)
		(layer "In4.Cu")
		(net "P5E_CPU0_P1_TX_DP<9>")
	)
	(segment
		(start 353.179126 -290.59632)
		(end 353.158044 -290.608512)
		(width 0.1143)
		(layer "In4.Cu")
		(net "P5E_CPU0_P1_TX_DP<9>")
	)
	(segment
		(start 353.16414 -291.58692)
		(end 353.16668 -291.58819)
		(width 0.1143)
		(layer "In4.Cu")
		(net "P5E_CPU0_P1_TX_DP<9>")
	)
	(segment
		(start 356.103174 -306.074826)
		(end 359.394252 -310.999886)
		(width 0.14224)
		(layer "In4.Cu")
		(net "P5E_CPU0_P1_TX_DP<9>")
	)
	(segment
		(start 351.561146 -287.856168)
		(end 351.859088 -287.856168)
		(width 0.1143)
		(layer "In4.Cu")
		(net "P5E_CPU0_P1_TX_DP<9>")
	)
	(segment
		(start 352.957638 -296.032936)
		(end 352.911918 -296.078656)
		(width 0.1143)
		(layer "In4.Cu")
		(net "P5E_CPU0_P1_TX_DP<9>")
	)
	(segment
		(start 352.911918 -296.078656)
		(end 352.911918 -296.107104)
		(width 0.1143)
		(layer "In4.Cu")
		(net "P5E_CPU0_P1_TX_DP<9>")
	)
	(segment
		(start 353.158044 -290.608512)
		(end 353.15779 -290.608766)
		(width 0.1143)
		(layer "In4.Cu")
		(net "P5E_CPU0_P1_TX_DP<9>")
	)
	(segment
		(start 352.688144 -289.153092)
		(end 352.688652 -289.153346)
		(width 0.1143)
		(layer "In4.Cu")
		(net "P5E_CPU0_P1_TX_DP<9>")
	)
	(segment
		(start 351.859088 -287.856168)
		(end 351.941892 -287.938972)
		(width 0.1143)
		(layer "In4.Cu")
		(net "P5E_CPU0_P1_TX_DP<9>")
	)
	(segment
		(start 353.628198 -294.013382)
		(end 353.658678 -294.031162)
		(width 0.1143)
		(layer "In4.Cu")
		(net "P5E_CPU0_P1_TX_DP<9>")
	)
	(segment
		(start 353.628198 -292.39337)
		(end 353.658678 -292.41115)
		(width 0.1143)
		(layer "In4.Cu")
		(net "P5E_CPU0_P1_TX_DP<9>")
	)
	(segment
		(start 372.20017 -333.685134)
		(end 372.938294 -337.7946)
		(width 0.14224)
		(layer "In4.Cu")
		(net "P5E_CPU0_P1_TX_DP<9>")
	)
	(segment
		(start 352.656648 -289.135058)
		(end 352.688144 -289.153346)
		(width 0.1143)
		(layer "In4.Cu")
		(net "P5E_CPU0_P1_TX_DP<9>")
	)
	(segment
		(start 352.18116 -288.322258)
		(end 352.218244 -288.343594)
		(width 0.1143)
		(layer "In4.Cu")
		(net "P5E_CPU0_P1_TX_DP<9>")
	)
	(segment
		(start 372.949724 -337.92033)
		(end 372.949724 -348.187772)
		(width 0.14224)
		(layer "In4.Cu")
		(net "P5E_CPU0_P1_TX_DP<9>")
	)
	(segment
		(start 359.394252 -310.999886)
		(end 367.488724 -320.862452)
		(width 0.14224)
		(layer "In4.Cu")
		(net "P5E_CPU0_P1_TX_DP<9>")
	)
	(segment
		(start 353.158806 -291.583872)
		(end 353.159822 -291.58438)
		(width 0.1143)
		(layer "In4.Cu")
		(net "P5E_CPU0_P1_TX_DP<9>")
	)
	(segment
		(start 352.179128 -288.320734)
		(end 352.18116 -288.322258)
		(width 0.1143)
		(layer "In4.Cu")
		(net "P5E_CPU0_P1_TX_DP<9>")
	)
	(segment
		(start 353.160584 -291.584888)
		(end 353.1616 -291.585396)
		(width 0.1143)
		(layer "In4.Cu")
		(net "P5E_CPU0_P1_TX_DP<9>")
	)
	(segment
		(start 368.425222 -322.655184)
		(end 372.20017 -333.685134)
		(width 0.14224)
		(layer "In4.Cu")
		(net "P5E_CPU0_P1_TX_DP<9>")
	)
	(segment
		(start 353.658678 -293.02075)
		(end 353.628198 -293.03853)
		(width 0.1143)
		(layer "In4.Cu")
		(net "P5E_CPU0_P1_TX_DP<9>")
	)
	(segment
		(start 353.16668 -291.58819)
		(end 353.189794 -291.601652)
		(width 0.1143)
		(layer "In4.Cu")
		(net "P5E_CPU0_P1_TX_DP<9>")
	)
	(segment
		(start 353.34575 -295.145968)
		(end 353.34575 -295.284144)
		(width 0.1143)
		(layer "In4.Cu")
		(net "P5E_CPU0_P1_TX_DP<9>")
	)
	(segment
		(start 372.307104 -350.896682)
		(end 361.94746 -365.846614)
		(width 0.14224)
		(layer "In4.Cu")
		(net "P5E_CPU0_P1_TX_DP<9>")
	)
	(segment
		(start 353.189794 -290.590224)
		(end 353.179888 -290.595812)
		(width 0.1143)
		(layer "In4.Cu")
		(net "P5E_CPU0_P1_TX_DP<9>")
	)
	(segment
		(start 352.86315 -289.456622)
		(end 352.86315 -289.466274)
		(width 0.1143)
		(layer "In4.Cu")
		(net "P5E_CPU0_P1_TX_DP<9>")
	)
	(segment
		(start 353.162362 -291.585904)
		(end 353.163378 -291.586412)
		(width 0.1143)
		(layer "In4.Cu")
		(net "P5E_CPU0_P1_TX_DP<9>")
	)
	(segment
		(start 353.179888 -290.595812)
		(end 353.179126 -290.59632)
		(width 0.1143)
		(layer "In4.Cu")
		(net "P5E_CPU0_P1_TX_DP<9>")
	)
	(segment
		(start 353.158044 -291.583364)
		(end 353.158806 -291.583872)
		(width 0.1143)
		(layer "In4.Cu")
		(net "P5E_CPU0_P1_TX_DP<9>")
	)
	(segment
		(start 352.957638 -295.919652)
		(end 352.957638 -296.032936)
		(width 0.1143)
		(layer "In4.Cu")
		(net "P5E_CPU0_P1_TX_DP<9>")
	)
	(segment
		(start 353.145852 -289.955986)
		(end 353.189794 -289.981894)
		(width 0.1143)
		(layer "In4.Cu")
		(net "P5E_CPU0_P1_TX_DP<9>")
	)
	(segment
		(start 353.15779 -291.583364)
		(end 353.158044 -291.583364)
		(width 0.1143)
		(layer "In4.Cu")
		(net "P5E_CPU0_P1_TX_DP<9>")
	)
	(segment
		(start 352.688144 -289.153346)
		(end 352.688144 -289.153092)
		(width 0.1143)
		(layer "In4.Cu")
		(net "P5E_CPU0_P1_TX_DP<9>")
	)
	(segment
		(start 352.218244 -288.343594)
		(end 352.250756 -288.36239)
		(width 0.1143)
		(layer "In4.Cu")
		(net "P5E_CPU0_P1_TX_DP<9>")
	)
	(segment
		(start 353.658678 -294.640762)
		(end 353.628198 -294.658542)
		(width 0.1143)
		(layer "In4.Cu")
		(net "P5E_CPU0_P1_TX_DP<9>")
	)
	(segment
		(start 372.307104 -350.896428)
		(end 372.307104 -350.896682)
		(width 0.14224)
		(layer "In4.Cu")
		(net "P5E_CPU0_P1_TX_DP<9>")
	)
	(segment
		(start 353.628198 -294.658542)
		(end 353.589082 -294.681402)
		(width 0.1143)
		(layer "In4.Cu")
		(net "P5E_CPU0_P1_TX_DP<9>")
	)
	(segment
		(start 353.1616 -291.585396)
		(end 353.162362 -291.585904)
		(width 0.1143)
		(layer "In4.Cu")
		(net "P5E_CPU0_P1_TX_DP<9>")
	)
	(segment
		(start 353.589082 -293.990522)
		(end 353.628198 -294.013382)
		(width 0.1143)
		(layer "In4.Cu")
		(net "P5E_CPU0_P1_TX_DP<9>")
	)
	(segment
		(start 352.911918 -296.107104)
		(end 352.911918 -298.288964)
		(width 0.14224)
		(layer "In4.Cu")
		(net "P5E_CPU0_P1_TX_DP<9>")
	)
	(segment
		(start 353.159822 -291.58438)
		(end 353.160584 -291.584888)
		(width 0.1143)
		(layer "In4.Cu")
		(net "P5E_CPU0_P1_TX_DP<9>")
	)
	(segment
		(start 367.488724 -320.862452)
		(end 368.425222 -322.655184)
		(width 0.14224)
		(layer "In4.Cu")
		(net "P5E_CPU0_P1_TX_DP<9>")
	)
	(arc
		(start 351.945702 -287.961832)
		(mid 352.027135 -288.16423)
		(end 352.179128 -288.320734)
		(width 0.1143)
		(layer "In4.Cu")
		(net "P5E_CPU0_P1_TX_DP<9>")
	)
	(arc
		(start 353.589082 -294.681402)
		(mid 353.410192 -294.883726)
		(end 353.34575 -295.145968)
		(width 0.1143)
		(layer "In4.Cu")
		(net "P5E_CPU0_P1_TX_DP<9>")
	)
	(arc
		(start 372.358158 -350.781366)
		(mid 372.338099 -350.841323)
		(end 372.307104 -350.896428)
		(width 0.14224)
		(layer "In4.Cu")
		(net "P5E_CPU0_P1_TX_DP<9>")
	)
	(arc
		(start 372.949724 -348.187772)
		(mid 372.948346 -348.21457)
		(end 372.94439 -348.241112)
		(width 0.14224)
		(layer "In4.Cu")
		(net "P5E_CPU0_P1_TX_DP<9>")
	)
	(arc
		(start 353.658678 -294.031162)
		(mid 353.815655 -294.335962)
		(end 353.658678 -294.640762)
		(width 0.1143)
		(layer "In4.Cu")
		(net "P5E_CPU0_P1_TX_DP<9>")
	)
	(arc
		(start 372.938294 -337.7946)
		(mid 372.946795 -337.857211)
		(end 372.949724 -337.92033)
		(width 0.14224)
		(layer "In4.Cu")
		(net "P5E_CPU0_P1_TX_DP<9>")
	)
	(arc
		(start 353.189794 -291.601652)
		(mid 353.30447 -291.734986)
		(end 353.34575 -291.905944)
		(width 0.1143)
		(layer "In4.Cu")
		(net "P5E_CPU0_P1_TX_DP<9>")
	)
	(arc
		(start 353.050856 -295.694862)
		(mid 352.98189 -295.797982)
		(end 352.957638 -295.919652)
		(width 0.1143)
		(layer "In4.Cu")
		(net "P5E_CPU0_P1_TX_DP<9>")
	)
	(arc
		(start 347.504512 -375.497598)
		(mid 347.243947 -375.785284)
		(end 347.149674 -376.161808)
		(width 0.14224)
		(layer "In4.Cu")
		(net "P5E_CPU0_P1_TX_DP<9>")
	)
	(arc
		(start 352.405696 -288.66592)
		(mid 352.470211 -288.928139)
		(end 352.649028 -289.130486)
		(width 0.1143)
		(layer "In4.Cu")
		(net "P5E_CPU0_P1_TX_DP<9>")
	)
	(arc
		(start 353.32543 -290.164266)
		(mid 353.328051 -290.399675)
		(end 353.189794 -290.590224)
		(width 0.1143)
		(layer "In4.Cu")
		(net "P5E_CPU0_P1_TX_DP<9>")
	)
	(arc
		(start 353.189794 -289.981894)
		(mid 353.271775 -290.062544)
		(end 353.32543 -290.164266)
		(width 0.1143)
		(layer "In4.Cu")
		(net "P5E_CPU0_P1_TX_DP<9>")
	)
	(arc
		(start 353.34575 -291.905944)
		(mid 353.410265 -292.168163)
		(end 353.589082 -292.37051)
		(width 0.1143)
		(layer "In4.Cu")
		(net "P5E_CPU0_P1_TX_DP<9>")
	)
	(arc
		(start 353.15779 -290.608766)
		(mid 352.877143 -291.096128)
		(end 353.15779 -291.583364)
		(width 0.1143)
		(layer "In4.Cu")
		(net "P5E_CPU0_P1_TX_DP<9>")
	)
	(arc
		(start 352.911918 -298.288964)
		(mid 352.919711 -298.368722)
		(end 352.942906 -298.445428)
		(width 0.14224)
		(layer "In4.Cu")
		(net "P5E_CPU0_P1_TX_DP<9>")
	)
	(arc
		(start 352.86315 -289.466274)
		(mid 352.938907 -289.748989)
		(end 353.145852 -289.955986)
		(width 0.1143)
		(layer "In4.Cu")
		(net "P5E_CPU0_P1_TX_DP<9>")
	)
	(arc
		(start 352.688652 -289.153346)
		(mid 352.816419 -289.281672)
		(end 352.86315 -289.456622)
		(width 0.1143)
		(layer "In4.Cu")
		(net "P5E_CPU0_P1_TX_DP<9>")
	)
	(arc
		(start 352.250756 -288.36239)
		(mid 352.364685 -288.495537)
		(end 352.405696 -288.66592)
		(width 0.1143)
		(layer "In4.Cu")
		(net "P5E_CPU0_P1_TX_DP<9>")
	)
	(arc
		(start 353.34575 -295.284144)
		(mid 353.324428 -295.391246)
		(end 353.263708 -295.48201)
		(width 0.1143)
		(layer "In4.Cu")
		(net "P5E_CPU0_P1_TX_DP<9>")
	)
	(arc
		(start 353.658678 -292.41115)
		(mid 353.815655 -292.71595)
		(end 353.658678 -293.02075)
		(width 0.1143)
		(layer "In4.Cu")
		(net "P5E_CPU0_P1_TX_DP<9>")
	)
	(arc
		(start 351.941892 -287.938972)
		(mid 351.94368 -287.950421)
		(end 351.945702 -287.961832)
		(width 0.1143)
		(layer "In4.Cu")
		(net "P5E_CPU0_P1_TX_DP<9>")
	)
	(arc
		(start 353.589082 -293.06139)
		(mid 353.345755 -293.525956)
		(end 353.589082 -293.990522)
		(width 0.1143)
		(layer "In4.Cu")
		(net "P5E_CPU0_P1_TX_DP<9>")
	)
	(segment
		(start 345.131644 -381.15113)
		(end 345.427554 -380.85522)
		(width 0.12954)
		(layer "F.Cu")
		(net "P5E_CPU0_P1_TX_DP<8>")
	)
	(segment
		(start 345.427554 -380.15164)
		(end 345.157044 -379.88113)
		(width 0.12954)
		(layer "F.Cu")
		(net "P5E_CPU0_P1_TX_DP<8>")
	)
	(segment
		(start 352.027998 -290.83)
		(end 351.561146 -291.095938)
		(width 0.12954)
		(layer "F.Cu")
		(net "P5E_CPU0_P1_TX_DP<8>")
	)
	(segment
		(start 345.427554 -380.85522)
		(end 345.427554 -380.15164)
		(width 0.12954)
		(layer "F.Cu")
		(net "P5E_CPU0_P1_TX_DP<8>")
	)
	(segment
		(start 345.447874 -379.5903)
		(end 345.157044 -379.88113)
		(width 0.14224)
		(layer "In4.Cu")
		(net "P5E_CPU0_P1_TX_DP<8>")
	)
	(segment
		(start 352.40595 -295.145968)
		(end 352.40595 -295.34739)
		(width 0.1143)
		(layer "In4.Cu")
		(net "P5E_CPU0_P1_TX_DP<8>")
	)
	(segment
		(start 352.651822 -292.372288)
		(end 352.688144 -292.39337)
		(width 0.1143)
		(layer "In4.Cu")
		(net "P5E_CPU0_P1_TX_DP<8>")
	)
	(segment
		(start 351.966784 -296.078656)
		(end 351.966784 -296.107104)
		(width 0.1143)
		(layer "In4.Cu")
		(net "P5E_CPU0_P1_TX_DP<8>")
	)
	(segment
		(start 371.999256 -337.974686)
		(end 371.999256 -348.15272)
		(width 0.14224)
		(layer "In4.Cu")
		(net "P5E_CPU0_P1_TX_DP<8>")
	)
	(segment
		(start 351.561146 -291.095938)
		(end 351.859088 -291.095938)
		(width 0.1143)
		(layer "In4.Cu")
		(net "P5E_CPU0_P1_TX_DP<8>")
	)
	(segment
		(start 366.70615 -321.381628)
		(end 367.484152 -322.870068)
		(width 0.14224)
		(layer "In4.Cu")
		(net "P5E_CPU0_P1_TX_DP<8>")
	)
	(segment
		(start 371.474492 -350.299782)
		(end 371.474492 -350.30029)
		(width 0.14224)
		(layer "In4.Cu")
		(net "P5E_CPU0_P1_TX_DP<8>")
	)
	(segment
		(start 351.966784 -296.107104)
		(end 351.966784 -298.41063)
		(width 0.14224)
		(layer "In4.Cu")
		(net "P5E_CPU0_P1_TX_DP<8>")
	)
	(segment
		(start 355.278944 -306.521612)
		(end 358.643428 -311.556908)
		(width 0.14224)
		(layer "In4.Cu")
		(net "P5E_CPU0_P1_TX_DP<8>")
	)
	(segment
		(start 352.719894 -293.020242)
		(end 352.688144 -293.03853)
		(width 0.1143)
		(layer "In4.Cu")
		(net "P5E_CPU0_P1_TX_DP<8>")
	)
	(segment
		(start 361.056936 -365.311436)
		(end 346.084144 -375.316242)
		(width 0.14224)
		(layer "In4.Cu")
		(net "P5E_CPU0_P1_TX_DP<8>")
	)
	(segment
		(start 352.688144 -293.03853)
		(end 352.66757 -293.050468)
		(width 0.1143)
		(layer "In4.Cu")
		(net "P5E_CPU0_P1_TX_DP<8>")
	)
	(segment
		(start 371.299232 -334.015588)
		(end 371.987826 -337.848956)
		(width 0.14224)
		(layer "In4.Cu")
		(net "P5E_CPU0_P1_TX_DP<8>")
	)
	(segment
		(start 352.721672 -294.63873)
		(end 352.649282 -294.681148)
		(width 0.1143)
		(layer "In4.Cu")
		(net "P5E_CPU0_P1_TX_DP<8>")
	)
	(segment
		(start 352.368612 -295.437306)
		(end 352.105722 -295.699434)
		(width 0.1143)
		(layer "In4.Cu")
		(net "P5E_CPU0_P1_TX_DP<8>")
	)
	(segment
		(start 352.179128 -291.560504)
		(end 352.185986 -291.564568)
		(width 0.1143)
		(layer "In4.Cu")
		(net "P5E_CPU0_P1_TX_DP<8>")
	)
	(segment
		(start 351.859088 -291.095938)
		(end 351.941892 -291.178742)
		(width 0.1143)
		(layer "In4.Cu")
		(net "P5E_CPU0_P1_TX_DP<8>")
	)
	(segment
		(start 352.688144 -292.39337)
		(end 352.719894 -292.411658)
		(width 0.1143)
		(layer "In4.Cu")
		(net "P5E_CPU0_P1_TX_DP<8>")
	)
	(segment
		(start 352.012504 -296.032936)
		(end 351.966784 -296.078656)
		(width 0.1143)
		(layer "In4.Cu")
		(net "P5E_CPU0_P1_TX_DP<8>")
	)
	(segment
		(start 352.012504 -295.924478)
		(end 352.012504 -296.032936)
		(width 0.1143)
		(layer "In4.Cu")
		(net "P5E_CPU0_P1_TX_DP<8>")
	)
	(segment
		(start 352.186748 -291.565076)
		(end 352.218244 -291.583364)
		(width 0.1143)
		(layer "In4.Cu")
		(net "P5E_CPU0_P1_TX_DP<8>")
	)
	(segment
		(start 367.484152 -322.870068)
		(end 371.299232 -334.015588)
		(width 0.14224)
		(layer "In4.Cu")
		(net "P5E_CPU0_P1_TX_DP<8>")
	)
	(segment
		(start 358.643428 -311.556908)
		(end 366.70615 -321.381628)
		(width 0.14224)
		(layer "In4.Cu")
		(net "P5E_CPU0_P1_TX_DP<8>")
	)
	(segment
		(start 352.218244 -291.583364)
		(end 352.24085 -291.596826)
		(width 0.1143)
		(layer "In4.Cu")
		(net "P5E_CPU0_P1_TX_DP<8>")
	)
	(segment
		(start 352.66757 -293.050468)
		(end 352.666808 -293.050976)
		(width 0.1143)
		(layer "In4.Cu")
		(net "P5E_CPU0_P1_TX_DP<8>")
	)
	(segment
		(start 371.474492 -350.30029)
		(end 361.056936 -365.311436)
		(width 0.14224)
		(layer "In4.Cu")
		(net "P5E_CPU0_P1_TX_DP<8>")
	)
	(segment
		(start 371.992906 -348.208854)
		(end 371.5258 -350.185228)
		(width 0.14224)
		(layer "In4.Cu")
		(net "P5E_CPU0_P1_TX_DP<8>")
	)
	(segment
		(start 352.010472 -298.630848)
		(end 355.278944 -306.521612)
		(width 0.14224)
		(layer "In4.Cu")
		(net "P5E_CPU0_P1_TX_DP<8>")
	)
	(segment
		(start 345.447874 -376.50674)
		(end 345.447874 -379.5903)
		(width 0.14224)
		(layer "In4.Cu")
		(net "P5E_CPU0_P1_TX_DP<8>")
	)
	(segment
		(start 352.666808 -294.000936)
		(end 352.7171 -294.030146)
		(width 0.1143)
		(layer "In4.Cu")
		(net "P5E_CPU0_P1_TX_DP<8>")
	)
	(segment
		(start 352.185986 -291.564568)
		(end 352.186748 -291.565076)
		(width 0.1143)
		(layer "In4.Cu")
		(net "P5E_CPU0_P1_TX_DP<8>")
	)
	(arc
		(start 352.40595 -291.92093)
		(mid 352.47157 -292.170448)
		(end 352.641154 -292.364922)
		(width 0.1143)
		(layer "In4.Cu")
		(net "P5E_CPU0_P1_TX_DP<8>")
	)
	(arc
		(start 352.24085 -291.596826)
		(mid 352.34931 -291.732177)
		(end 352.403918 -291.8968)
		(width 0.1143)
		(layer "In4.Cu")
		(net "P5E_CPU0_P1_TX_DP<8>")
	)
	(arc
		(start 352.666808 -293.050976)
		(mid 352.393257 -293.525956)
		(end 352.666808 -294.000936)
		(width 0.1143)
		(layer "In4.Cu")
		(net "P5E_CPU0_P1_TX_DP<8>")
	)
	(arc
		(start 352.40595 -295.34739)
		(mid 352.396248 -295.396074)
		(end 352.368612 -295.437306)
		(width 0.1143)
		(layer "In4.Cu")
		(net "P5E_CPU0_P1_TX_DP<8>")
	)
	(arc
		(start 352.649282 -294.681148)
		(mid 352.470473 -294.883642)
		(end 352.40595 -295.145968)
		(width 0.1143)
		(layer "In4.Cu")
		(net "P5E_CPU0_P1_TX_DP<8>")
	)
	(arc
		(start 352.403918 -291.8968)
		(mid 352.405227 -291.90884)
		(end 352.40595 -291.92093)
		(width 0.1143)
		(layer "In4.Cu")
		(net "P5E_CPU0_P1_TX_DP<8>")
	)
	(arc
		(start 371.999256 -348.15272)
		(mid 371.997601 -348.180959)
		(end 371.992906 -348.208854)
		(width 0.14224)
		(layer "In4.Cu")
		(net "P5E_CPU0_P1_TX_DP<8>")
	)
	(arc
		(start 352.719894 -292.411658)
		(mid 352.875822 -292.71595)
		(end 352.719894 -293.020242)
		(width 0.1143)
		(layer "In4.Cu")
		(net "P5E_CPU0_P1_TX_DP<8>")
	)
	(arc
		(start 351.941892 -291.178742)
		(mid 351.94368 -291.190191)
		(end 351.945702 -291.201602)
		(width 0.1143)
		(layer "In4.Cu")
		(net "P5E_CPU0_P1_TX_DP<8>")
	)
	(arc
		(start 351.966784 -298.41063)
		(mid 351.977796 -298.522886)
		(end 352.010472 -298.630848)
		(width 0.14224)
		(layer "In4.Cu")
		(net "P5E_CPU0_P1_TX_DP<8>")
	)
	(arc
		(start 371.5258 -350.185228)
		(mid 371.505505 -350.244905)
		(end 371.474492 -350.299782)
		(width 0.14224)
		(layer "In4.Cu")
		(net "P5E_CPU0_P1_TX_DP<8>")
	)
	(arc
		(start 352.641154 -292.364922)
		(mid 352.646468 -292.368634)
		(end 352.651822 -292.372288)
		(width 0.1143)
		(layer "In4.Cu")
		(net "P5E_CPU0_P1_TX_DP<8>")
	)
	(arc
		(start 352.7171 -294.030146)
		(mid 352.876945 -294.333216)
		(end 352.721672 -294.63873)
		(width 0.1143)
		(layer "In4.Cu")
		(net "P5E_CPU0_P1_TX_DP<8>")
	)
	(arc
		(start 346.084144 -375.316242)
		(mid 345.616894 -375.831801)
		(end 345.447874 -376.50674)
		(width 0.14224)
		(layer "In4.Cu")
		(net "P5E_CPU0_P1_TX_DP<8>")
	)
	(arc
		(start 352.105722 -295.699434)
		(mid 352.036732 -295.802685)
		(end 352.012504 -295.924478)
		(width 0.1143)
		(layer "In4.Cu")
		(net "P5E_CPU0_P1_TX_DP<8>")
	)
	(arc
		(start 351.945702 -291.201602)
		(mid 352.027135 -291.404)
		(end 352.179128 -291.560504)
		(width 0.1143)
		(layer "In4.Cu")
		(net "P5E_CPU0_P1_TX_DP<8>")
	)
	(arc
		(start 371.987826 -337.848956)
		(mid 371.996327 -337.911567)
		(end 371.999256 -337.974686)
		(width 0.14224)
		(layer "In4.Cu")
		(net "P5E_CPU0_P1_TX_DP<8>")
	)
	(segment
		(start 343.725754 -382.61544)
		(end 343.455244 -382.34493)
		(width 0.12954)
		(layer "F.Cu")
		(net "P5E_CPU0_P1_TX_DP<7>")
	)
	(segment
		(start 343.725754 -383.31902)
		(end 343.725754 -382.61544)
		(width 0.12954)
		(layer "F.Cu")
		(net "P5E_CPU0_P1_TX_DP<7>")
	)
	(segment
		(start 343.429844 -383.61493)
		(end 343.725754 -383.31902)
		(width 0.12954)
		(layer "F.Cu")
		(net "P5E_CPU0_P1_TX_DP<7>")
	)
	(segment
		(start 352.027998 -289.209988)
		(end 351.561146 -289.475926)
		(width 0.12954)
		(layer "F.Cu")
		(net "P5E_CPU0_P1_TX_DP<7>")
	)
	(segment
		(start 343.69883 -382.101344)
		(end 343.455244 -382.34493)
		(width 0.14224)
		(layer "In4.Cu")
		(net "P5E_CPU0_P1_TX_DP<7>")
	)
	(segment
		(start 351.748344 -294.658542)
		(end 351.709228 -294.681402)
		(width 0.1143)
		(layer "In4.Cu")
		(net "P5E_CPU0_P1_TX_DP<7>")
	)
	(segment
		(start 351.246694 -291.565076)
		(end 351.27819 -291.583364)
		(width 0.1143)
		(layer "In4.Cu")
		(net "P5E_CPU0_P1_TX_DP<7>")
	)
	(segment
		(start 370.266976 -333.963518)
		(end 371.047264 -338.30641)
		(width 0.14224)
		(layer "In4.Cu")
		(net "P5E_CPU0_P1_TX_DP<7>")
	)
	(segment
		(start 350.99117 -298.606464)
		(end 354.456746 -306.973224)
		(width 0.14224)
		(layer "In4.Cu")
		(net "P5E_CPU0_P1_TX_DP<7>")
	)
	(segment
		(start 351.465896 -295.145968)
		(end 351.465896 -295.261792)
		(width 0.1143)
		(layer "In4.Cu")
		(net "P5E_CPU0_P1_TX_DP<7>")
	)
	(segment
		(start 366.546384 -323.093334)
		(end 370.266976 -333.963518)
		(width 0.14224)
		(layer "In4.Cu")
		(net "P5E_CPU0_P1_TX_DP<7>")
	)
	(segment
		(start 351.748344 -293.03853)
		(end 351.709228 -293.06139)
		(width 0.1143)
		(layer "In4.Cu")
		(net "P5E_CPU0_P1_TX_DP<7>")
	)
	(segment
		(start 351.27819 -291.583364)
		(end 351.278952 -291.583872)
		(width 0.1143)
		(layer "In4.Cu")
		(net "P5E_CPU0_P1_TX_DP<7>")
	)
	(segment
		(start 365.92764 -321.909186)
		(end 366.546384 -323.093334)
		(width 0.14224)
		(layer "In4.Cu")
		(net "P5E_CPU0_P1_TX_DP<7>")
	)
	(segment
		(start 351.561146 -289.475926)
		(end 351.859088 -289.475926)
		(width 0.1143)
		(layer "In4.Cu")
		(net "P5E_CPU0_P1_TX_DP<7>")
	)
	(segment
		(start 351.748344 -292.39337)
		(end 351.778824 -292.41115)
		(width 0.1143)
		(layer "In4.Cu")
		(net "P5E_CPU0_P1_TX_DP<7>")
	)
	(segment
		(start 351.005902 -295.991534)
		(end 351.005902 -296.032936)
		(width 0.1143)
		(layer "In4.Cu")
		(net "P5E_CPU0_P1_TX_DP<7>")
	)
	(segment
		(start 354.456746 -306.973224)
		(end 357.904542 -312.133488)
		(width 0.14224)
		(layer "In4.Cu")
		(net "P5E_CPU0_P1_TX_DP<7>")
	)
	(segment
		(start 350.960182 -296.078656)
		(end 350.960182 -296.107104)
		(width 0.1143)
		(layer "In4.Cu")
		(net "P5E_CPU0_P1_TX_DP<7>")
	)
	(segment
		(start 351.278698 -290.608258)
		(end 351.277936 -290.608766)
		(width 0.1143)
		(layer "In4.Cu")
		(net "P5E_CPU0_P1_TX_DP<7>")
	)
	(segment
		(start 351.778824 -293.02075)
		(end 351.748344 -293.03853)
		(width 0.1143)
		(layer "In4.Cu")
		(net "P5E_CPU0_P1_TX_DP<7>")
	)
	(segment
		(start 351.748344 -294.013382)
		(end 351.778824 -294.031162)
		(width 0.1143)
		(layer "In4.Cu")
		(net "P5E_CPU0_P1_TX_DP<7>")
	)
	(segment
		(start 351.005902 -296.032936)
		(end 350.960182 -296.078656)
		(width 0.1143)
		(layer "In4.Cu")
		(net "P5E_CPU0_P1_TX_DP<7>")
	)
	(segment
		(start 351.778824 -294.640762)
		(end 351.748344 -294.658542)
		(width 0.1143)
		(layer "In4.Cu")
		(net "P5E_CPU0_P1_TX_DP<7>")
	)
	(segment
		(start 351.239074 -291.560504)
		(end 351.245932 -291.564568)
		(width 0.1143)
		(layer "In4.Cu")
		(net "P5E_CPU0_P1_TX_DP<7>")
	)
	(segment
		(start 351.709228 -292.37051)
		(end 351.748344 -292.39337)
		(width 0.1143)
		(layer "In4.Cu")
		(net "P5E_CPU0_P1_TX_DP<7>")
	)
	(segment
		(start 343.746074 -376.446542)
		(end 343.746074 -381.987298)
		(width 0.14224)
		(layer "In4.Cu")
		(net "P5E_CPU0_P1_TX_DP<7>")
	)
	(segment
		(start 351.280222 -290.607496)
		(end 351.278698 -290.608258)
		(width 0.1143)
		(layer "In4.Cu")
		(net "P5E_CPU0_P1_TX_DP<7>")
	)
	(segment
		(start 351.368106 -295.497758)
		(end 351.09912 -295.766744)
		(width 0.1143)
		(layer "In4.Cu")
		(net "P5E_CPU0_P1_TX_DP<7>")
	)
	(segment
		(start 351.709228 -293.990522)
		(end 351.748344 -294.013382)
		(width 0.1143)
		(layer "In4.Cu")
		(net "P5E_CPU0_P1_TX_DP<7>")
	)
	(segment
		(start 351.859088 -289.475926)
		(end 351.928938 -289.545776)
		(width 0.1143)
		(layer "In4.Cu")
		(net "P5E_CPU0_P1_TX_DP<7>")
	)
	(segment
		(start 351.780094 -289.779964)
		(end 351.750376 -289.797236)
		(width 0.1143)
		(layer "In4.Cu")
		(net "P5E_CPU0_P1_TX_DP<7>")
	)
	(segment
		(start 371.05336 -348.097094)
		(end 370.643404 -349.751396)
		(width 0.14224)
		(layer "In4.Cu")
		(net "P5E_CPU0_P1_TX_DP<7>")
	)
	(segment
		(start 351.750376 -289.797236)
		(end 351.748344 -289.798506)
		(width 0.1143)
		(layer "In4.Cu")
		(net "P5E_CPU0_P1_TX_DP<7>")
	)
	(segment
		(start 371.058694 -338.43214)
		(end 371.058694 -348.04731)
		(width 0.14224)
		(layer "In4.Cu")
		(net "P5E_CPU0_P1_TX_DP<7>")
	)
	(segment
		(start 357.904542 -312.133488)
		(end 365.92764 -321.909186)
		(width 0.14224)
		(layer "In4.Cu")
		(net "P5E_CPU0_P1_TX_DP<7>")
	)
	(segment
		(start 350.960182 -296.107104)
		(end 350.960182 -298.45)
		(width 0.14224)
		(layer "In4.Cu")
		(net "P5E_CPU0_P1_TX_DP<7>")
	)
	(segment
		(start 360.627422 -364.26013)
		(end 344.499438 -375.037096)
		(width 0.14224)
		(layer "In4.Cu")
		(net "P5E_CPU0_P1_TX_DP<7>")
	)
	(segment
		(start 370.591588 -349.866204)
		(end 360.627422 -364.26013)
		(width 0.14224)
		(layer "In4.Cu")
		(net "P5E_CPU0_P1_TX_DP<7>")
	)
	(segment
		(start 351.277936 -290.608766)
		(end 351.239836 -290.630864)
		(width 0.1143)
		(layer "In4.Cu")
		(net "P5E_CPU0_P1_TX_DP<7>")
	)
	(segment
		(start 351.278952 -291.583872)
		(end 351.30994 -291.601652)
		(width 0.1143)
		(layer "In4.Cu")
		(net "P5E_CPU0_P1_TX_DP<7>")
	)
	(segment
		(start 351.245932 -291.564568)
		(end 351.246694 -291.565076)
		(width 0.1143)
		(layer "In4.Cu")
		(net "P5E_CPU0_P1_TX_DP<7>")
	)
	(arc
		(start 351.239836 -290.630864)
		(mid 351.239455 -290.631118)
		(end 351.239074 -290.631372)
		(width 0.1143)
		(layer "In4.Cu")
		(net "P5E_CPU0_P1_TX_DP<7>")
	)
	(arc
		(start 351.709228 -294.681402)
		(mid 351.530338 -294.883726)
		(end 351.465896 -295.145968)
		(width 0.1143)
		(layer "In4.Cu")
		(net "P5E_CPU0_P1_TX_DP<7>")
	)
	(arc
		(start 351.09912 -295.766744)
		(mid 351.030154 -295.869864)
		(end 351.005902 -295.991534)
		(width 0.1143)
		(layer "In4.Cu")
		(net "P5E_CPU0_P1_TX_DP<7>")
	)
	(arc
		(start 351.465896 -291.905944)
		(mid 351.530411 -292.168163)
		(end 351.709228 -292.37051)
		(width 0.1143)
		(layer "In4.Cu")
		(net "P5E_CPU0_P1_TX_DP<7>")
	)
	(arc
		(start 351.778824 -294.031162)
		(mid 351.935801 -294.335962)
		(end 351.778824 -294.640762)
		(width 0.1143)
		(layer "In4.Cu")
		(net "P5E_CPU0_P1_TX_DP<7>")
	)
	(arc
		(start 370.643404 -349.751396)
		(mid 370.622732 -349.811165)
		(end 370.591588 -349.866204)
		(width 0.14224)
		(layer "In4.Cu")
		(net "P5E_CPU0_P1_TX_DP<7>")
	)
	(arc
		(start 351.748344 -289.798506)
		(mid 351.539349 -290.005781)
		(end 351.462848 -290.289996)
		(width 0.1143)
		(layer "In4.Cu")
		(net "P5E_CPU0_P1_TX_DP<7>")
	)
	(arc
		(start 351.239074 -290.631372)
		(mid 350.995747 -291.095938)
		(end 351.239074 -291.560504)
		(width 0.1143)
		(layer "In4.Cu")
		(net "P5E_CPU0_P1_TX_DP<7>")
	)
	(arc
		(start 344.499438 -375.037096)
		(mid 343.946254 -375.647472)
		(end 343.746074 -376.446542)
		(width 0.14224)
		(layer "In4.Cu")
		(net "P5E_CPU0_P1_TX_DP<7>")
	)
	(arc
		(start 351.928938 -289.545776)
		(mid 351.876984 -289.677145)
		(end 351.780094 -289.779964)
		(width 0.1143)
		(layer "In4.Cu")
		(net "P5E_CPU0_P1_TX_DP<7>")
	)
	(arc
		(start 343.746074 -381.987298)
		(mid 343.733797 -382.049021)
		(end 343.69883 -382.101344)
		(width 0.14224)
		(layer "In4.Cu")
		(net "P5E_CPU0_P1_TX_DP<7>")
	)
	(arc
		(start 371.047264 -338.30641)
		(mid 371.055768 -338.369021)
		(end 371.058694 -338.43214)
		(width 0.14224)
		(layer "In4.Cu")
		(net "P5E_CPU0_P1_TX_DP<7>")
	)
	(arc
		(start 351.465896 -295.261792)
		(mid 351.440475 -295.389501)
		(end 351.368106 -295.497758)
		(width 0.1143)
		(layer "In4.Cu")
		(net "P5E_CPU0_P1_TX_DP<7>")
	)
	(arc
		(start 371.058694 -348.04731)
		(mid 371.057326 -348.072341)
		(end 371.05336 -348.097094)
		(width 0.14224)
		(layer "In4.Cu")
		(net "P5E_CPU0_P1_TX_DP<7>")
	)
	(arc
		(start 351.778824 -292.41115)
		(mid 351.935801 -292.71595)
		(end 351.778824 -293.02075)
		(width 0.1143)
		(layer "In4.Cu")
		(net "P5E_CPU0_P1_TX_DP<7>")
	)
	(arc
		(start 351.30994 -291.601652)
		(mid 351.424616 -291.734986)
		(end 351.465896 -291.905944)
		(width 0.1143)
		(layer "In4.Cu")
		(net "P5E_CPU0_P1_TX_DP<7>")
	)
	(arc
		(start 350.960182 -298.45)
		(mid 350.967975 -298.529758)
		(end 350.99117 -298.606464)
		(width 0.14224)
		(layer "In4.Cu")
		(net "P5E_CPU0_P1_TX_DP<7>")
	)
	(arc
		(start 351.709228 -293.06139)
		(mid 351.465901 -293.525956)
		(end 351.709228 -293.990522)
		(width 0.1143)
		(layer "In4.Cu")
		(net "P5E_CPU0_P1_TX_DP<7>")
	)
	(arc
		(start 351.462848 -290.289996)
		(mid 351.414007 -290.473189)
		(end 351.280222 -290.607496)
		(width 0.1143)
		(layer "In4.Cu")
		(net "P5E_CPU0_P1_TX_DP<7>")
	)
	(segment
		(start 349.20809 -287.59023)
		(end 348.741238 -287.856168)
		(width 0.12954)
		(layer "F.Cu")
		(net "P5E_CPU0_P1_TX_DP<6>")
	)
	(segment
		(start 340.322154 -377.68784)
		(end 340.051644 -377.41733)
		(width 0.12954)
		(layer "F.Cu")
		(net "P5E_CPU0_P1_TX_DP<6>")
	)
	(segment
		(start 340.322154 -378.39142)
		(end 340.322154 -377.68784)
		(width 0.12954)
		(layer "F.Cu")
		(net "P5E_CPU0_P1_TX_DP<6>")
	)
	(segment
		(start 340.026244 -378.68733)
		(end 340.322154 -378.39142)
		(width 0.12954)
		(layer "F.Cu")
		(net "P5E_CPU0_P1_TX_DP<6>")
	)
	(segment
		(start 350.80829 -294.658542)
		(end 350.769174 -294.681402)
		(width 0.1143)
		(layer "In4.Cu")
		(net "P5E_CPU0_P1_TX_DP<6>")
	)
	(segment
		(start 348.741238 -287.856168)
		(end 349.03918 -287.856168)
		(width 0.1143)
		(layer "In4.Cu")
		(net "P5E_CPU0_P1_TX_DP<6>")
	)
	(segment
		(start 350.83877 -293.02075)
		(end 350.80829 -293.03853)
		(width 0.1143)
		(layer "In4.Cu")
		(net "P5E_CPU0_P1_TX_DP<6>")
	)
	(segment
		(start 350.337882 -291.583364)
		(end 350.338136 -291.583364)
		(width 0.1143)
		(layer "In4.Cu")
		(net "P5E_CPU0_P1_TX_DP<6>")
	)
	(segment
		(start 350.338898 -291.583872)
		(end 350.339914 -291.58438)
		(width 0.1143)
		(layer "In4.Cu")
		(net "P5E_CPU0_P1_TX_DP<6>")
	)
	(segment
		(start 350.043242 -289.456622)
		(end 350.043242 -289.466274)
		(width 0.1143)
		(layer "In4.Cu")
		(net "P5E_CPU0_P1_TX_DP<6>")
	)
	(segment
		(start 369.667536 -349.562928)
		(end 360.340402 -363.005624)
		(width 0.14224)
		(layer "In4.Cu")
		(net "P5E_CPU0_P1_TX_DP<6>")
	)
	(segment
		(start 350.342454 -291.585904)
		(end 350.34347 -291.586412)
		(width 0.1143)
		(layer "In4.Cu")
		(net "P5E_CPU0_P1_TX_DP<6>")
	)
	(segment
		(start 350.344232 -291.58692)
		(end 350.346772 -291.58819)
		(width 0.1143)
		(layer "In4.Cu")
		(net "P5E_CPU0_P1_TX_DP<6>")
	)
	(segment
		(start 350.80829 -292.39337)
		(end 350.83877 -292.41115)
		(width 0.1143)
		(layer "In4.Cu")
		(net "P5E_CPU0_P1_TX_DP<6>")
	)
	(segment
		(start 350.015302 -296.234104)
		(end 350.015302 -298.59859)
		(width 0.14224)
		(layer "In4.Cu")
		(net "P5E_CPU0_P1_TX_DP<6>")
	)
	(segment
		(start 350.061022 -295.996868)
		(end 350.061022 -296.159936)
		(width 0.1143)
		(layer "In4.Cu")
		(net "P5E_CPU0_P1_TX_DP<6>")
	)
	(segment
		(start 349.83674 -289.135058)
		(end 349.868236 -289.153346)
		(width 0.1143)
		(layer "In4.Cu")
		(net "P5E_CPU0_P1_TX_DP<6>")
	)
	(segment
		(start 360.340402 -363.005624)
		(end 340.524338 -376.24639)
		(width 0.14224)
		(layer "In4.Cu")
		(net "P5E_CPU0_P1_TX_DP<6>")
	)
	(segment
		(start 350.339914 -291.58438)
		(end 350.340676 -291.584888)
		(width 0.1143)
		(layer "In4.Cu")
		(net "P5E_CPU0_P1_TX_DP<6>")
	)
	(segment
		(start 340.342474 -377.1265)
		(end 340.051644 -377.41733)
		(width 0.14224)
		(layer "In4.Cu")
		(net "P5E_CPU0_P1_TX_DP<6>")
	)
	(segment
		(start 350.346772 -291.58819)
		(end 350.369886 -291.601652)
		(width 0.1143)
		(layer "In4.Cu")
		(net "P5E_CPU0_P1_TX_DP<6>")
	)
	(segment
		(start 365.127286 -322.404994)
		(end 365.551974 -323.218048)
		(width 0.14224)
		(layer "In4.Cu")
		(net "P5E_CPU0_P1_TX_DP<6>")
	)
	(segment
		(start 350.488504 -295.43756)
		(end 350.153986 -295.771824)
		(width 0.1143)
		(layer "In4.Cu")
		(net "P5E_CPU0_P1_TX_DP<6>")
	)
	(segment
		(start 350.325944 -289.955986)
		(end 350.369886 -289.981894)
		(width 0.1143)
		(layer "In4.Cu")
		(net "P5E_CPU0_P1_TX_DP<6>")
	)
	(segment
		(start 349.398336 -288.343594)
		(end 349.430848 -288.36239)
		(width 0.1143)
		(layer "In4.Cu")
		(net "P5E_CPU0_P1_TX_DP<6>")
	)
	(segment
		(start 350.04883 -298.768008)
		(end 353.643184 -307.445664)
		(width 0.14224)
		(layer "In4.Cu")
		(net "P5E_CPU0_P1_TX_DP<6>")
	)
	(segment
		(start 349.868236 -289.153092)
		(end 349.868744 -289.153346)
		(width 0.1143)
		(layer "In4.Cu")
		(net "P5E_CPU0_P1_TX_DP<6>")
	)
	(segment
		(start 350.80829 -294.013382)
		(end 350.83877 -294.031162)
		(width 0.1143)
		(layer "In4.Cu")
		(net "P5E_CPU0_P1_TX_DP<6>")
	)
	(segment
		(start 357.117904 -312.64606)
		(end 365.127286 -322.404994)
		(width 0.14224)
		(layer "In4.Cu")
		(net "P5E_CPU0_P1_TX_DP<6>")
	)
	(segment
		(start 350.341692 -291.585396)
		(end 350.342454 -291.585904)
		(width 0.1143)
		(layer "In4.Cu")
		(net "P5E_CPU0_P1_TX_DP<6>")
	)
	(segment
		(start 350.338136 -290.608512)
		(end 350.337882 -290.608766)
		(width 0.1143)
		(layer "In4.Cu")
		(net "P5E_CPU0_P1_TX_DP<6>")
	)
	(segment
		(start 350.369886 -290.590224)
		(end 350.35998 -290.595812)
		(width 0.1143)
		(layer "In4.Cu")
		(net "P5E_CPU0_P1_TX_DP<6>")
	)
	(segment
		(start 350.35998 -290.595812)
		(end 350.359218 -290.59632)
		(width 0.1143)
		(layer "In4.Cu")
		(net "P5E_CPU0_P1_TX_DP<6>")
	)
	(segment
		(start 350.769174 -292.37051)
		(end 350.80829 -292.39337)
		(width 0.1143)
		(layer "In4.Cu")
		(net "P5E_CPU0_P1_TX_DP<6>")
	)
	(segment
		(start 370.08308 -338.346288)
		(end 370.08308 -347.907102)
		(width 0.14224)
		(layer "In4.Cu")
		(net "P5E_CPU0_P1_TX_DP<6>")
	)
	(segment
		(start 365.551974 -323.218048)
		(end 369.391946 -334.437736)
		(width 0.14224)
		(layer "In4.Cu")
		(net "P5E_CPU0_P1_TX_DP<6>")
	)
	(segment
		(start 350.061022 -296.159936)
		(end 350.015302 -296.205656)
		(width 0.1143)
		(layer "In4.Cu")
		(net "P5E_CPU0_P1_TX_DP<6>")
	)
	(segment
		(start 350.769174 -293.990522)
		(end 350.80829 -294.013382)
		(width 0.1143)
		(layer "In4.Cu")
		(net "P5E_CPU0_P1_TX_DP<6>")
	)
	(segment
		(start 370.076984 -347.961712)
		(end 369.719352 -349.447866)
		(width 0.14224)
		(layer "In4.Cu")
		(net "P5E_CPU0_P1_TX_DP<6>")
	)
	(segment
		(start 353.643184 -307.445664)
		(end 357.117904 -312.64606)
		(width 0.14224)
		(layer "In4.Cu")
		(net "P5E_CPU0_P1_TX_DP<6>")
	)
	(segment
		(start 369.667536 -349.562674)
		(end 369.667536 -349.562928)
		(width 0.14224)
		(layer "In4.Cu")
		(net "P5E_CPU0_P1_TX_DP<6>")
	)
	(segment
		(start 340.342474 -376.586496)
		(end 340.342474 -377.1265)
		(width 0.14224)
		(layer "In4.Cu")
		(net "P5E_CPU0_P1_TX_DP<6>")
	)
	(segment
		(start 349.868236 -289.153346)
		(end 349.868236 -289.153092)
		(width 0.1143)
		(layer "In4.Cu")
		(net "P5E_CPU0_P1_TX_DP<6>")
	)
	(segment
		(start 349.82912 -289.130486)
		(end 349.835978 -289.13455)
		(width 0.1143)
		(layer "In4.Cu")
		(net "P5E_CPU0_P1_TX_DP<6>")
	)
	(segment
		(start 369.391946 -334.437736)
		(end 370.07165 -338.220558)
		(width 0.14224)
		(layer "In4.Cu")
		(net "P5E_CPU0_P1_TX_DP<6>")
	)
	(segment
		(start 350.359218 -290.59632)
		(end 350.338136 -290.608512)
		(width 0.1143)
		(layer "In4.Cu")
		(net "P5E_CPU0_P1_TX_DP<6>")
	)
	(segment
		(start 350.525842 -295.145968)
		(end 350.525842 -295.34739)
		(width 0.1143)
		(layer "In4.Cu")
		(net "P5E_CPU0_P1_TX_DP<6>")
	)
	(segment
		(start 349.835978 -289.13455)
		(end 349.83674 -289.135058)
		(width 0.1143)
		(layer "In4.Cu")
		(net "P5E_CPU0_P1_TX_DP<6>")
	)
	(segment
		(start 350.80829 -293.03853)
		(end 350.769174 -293.06139)
		(width 0.1143)
		(layer "In4.Cu")
		(net "P5E_CPU0_P1_TX_DP<6>")
	)
	(segment
		(start 350.338136 -291.583364)
		(end 350.338898 -291.583872)
		(width 0.1143)
		(layer "In4.Cu")
		(net "P5E_CPU0_P1_TX_DP<6>")
	)
	(segment
		(start 350.015302 -296.205656)
		(end 350.015302 -296.234104)
		(width 0.1143)
		(layer "In4.Cu")
		(net "P5E_CPU0_P1_TX_DP<6>")
	)
	(segment
		(start 349.35922 -288.320734)
		(end 349.398336 -288.343594)
		(width 0.1143)
		(layer "In4.Cu")
		(net "P5E_CPU0_P1_TX_DP<6>")
	)
	(segment
		(start 350.340676 -291.584888)
		(end 350.341692 -291.585396)
		(width 0.1143)
		(layer "In4.Cu")
		(net "P5E_CPU0_P1_TX_DP<6>")
	)
	(segment
		(start 350.83877 -294.640762)
		(end 350.80829 -294.658542)
		(width 0.1143)
		(layer "In4.Cu")
		(net "P5E_CPU0_P1_TX_DP<6>")
	)
	(segment
		(start 350.34347 -291.586412)
		(end 350.344232 -291.58692)
		(width 0.1143)
		(layer "In4.Cu")
		(net "P5E_CPU0_P1_TX_DP<6>")
	)
	(segment
		(start 349.03918 -287.856168)
		(end 349.121984 -287.938972)
		(width 0.1143)
		(layer "In4.Cu")
		(net "P5E_CPU0_P1_TX_DP<6>")
	)
	(arc
		(start 350.83877 -292.41115)
		(mid 350.995747 -292.71595)
		(end 350.83877 -293.02075)
		(width 0.1143)
		(layer "In4.Cu")
		(net "P5E_CPU0_P1_TX_DP<6>")
	)
	(arc
		(start 349.868744 -289.153346)
		(mid 349.996511 -289.281672)
		(end 350.043242 -289.456622)
		(width 0.1143)
		(layer "In4.Cu")
		(net "P5E_CPU0_P1_TX_DP<6>")
	)
	(arc
		(start 349.430848 -288.36239)
		(mid 349.544777 -288.495537)
		(end 349.585788 -288.66592)
		(width 0.1143)
		(layer "In4.Cu")
		(net "P5E_CPU0_P1_TX_DP<6>")
	)
	(arc
		(start 350.369886 -291.601652)
		(mid 350.484562 -291.734986)
		(end 350.525842 -291.905944)
		(width 0.1143)
		(layer "In4.Cu")
		(net "P5E_CPU0_P1_TX_DP<6>")
	)
	(arc
		(start 350.043242 -289.466274)
		(mid 350.118999 -289.748989)
		(end 350.325944 -289.955986)
		(width 0.1143)
		(layer "In4.Cu")
		(net "P5E_CPU0_P1_TX_DP<6>")
	)
	(arc
		(start 349.585788 -288.66592)
		(mid 349.650303 -288.928139)
		(end 349.82912 -289.130486)
		(width 0.1143)
		(layer "In4.Cu")
		(net "P5E_CPU0_P1_TX_DP<6>")
	)
	(arc
		(start 350.525842 -295.34739)
		(mid 350.516151 -295.396199)
		(end 350.488504 -295.43756)
		(width 0.1143)
		(layer "In4.Cu")
		(net "P5E_CPU0_P1_TX_DP<6>")
	)
	(arc
		(start 350.769174 -294.681402)
		(mid 350.590284 -294.883726)
		(end 350.525842 -295.145968)
		(width 0.1143)
		(layer "In4.Cu")
		(net "P5E_CPU0_P1_TX_DP<6>")
	)
	(arc
		(start 370.08308 -347.907102)
		(mid 370.081506 -347.934571)
		(end 370.076984 -347.961712)
		(width 0.14224)
		(layer "In4.Cu")
		(net "P5E_CPU0_P1_TX_DP<6>")
	)
	(arc
		(start 350.505522 -290.164266)
		(mid 350.508143 -290.399675)
		(end 350.369886 -290.590224)
		(width 0.1143)
		(layer "In4.Cu")
		(net "P5E_CPU0_P1_TX_DP<6>")
	)
	(arc
		(start 350.525842 -291.905944)
		(mid 350.590357 -292.168163)
		(end 350.769174 -292.37051)
		(width 0.1143)
		(layer "In4.Cu")
		(net "P5E_CPU0_P1_TX_DP<6>")
	)
	(arc
		(start 350.337882 -290.608766)
		(mid 350.057235 -291.096128)
		(end 350.337882 -291.583364)
		(width 0.1143)
		(layer "In4.Cu")
		(net "P5E_CPU0_P1_TX_DP<6>")
	)
	(arc
		(start 349.121984 -287.938972)
		(mid 349.123772 -287.950421)
		(end 349.125794 -287.961832)
		(width 0.1143)
		(layer "In4.Cu")
		(net "P5E_CPU0_P1_TX_DP<6>")
	)
	(arc
		(start 350.015302 -298.59859)
		(mid 350.023745 -298.684945)
		(end 350.04883 -298.768008)
		(width 0.14224)
		(layer "In4.Cu")
		(net "P5E_CPU0_P1_TX_DP<6>")
	)
	(arc
		(start 350.769174 -293.06139)
		(mid 350.525847 -293.525956)
		(end 350.769174 -293.990522)
		(width 0.1143)
		(layer "In4.Cu")
		(net "P5E_CPU0_P1_TX_DP<6>")
	)
	(arc
		(start 350.153986 -295.771824)
		(mid 350.085132 -295.875104)
		(end 350.061022 -295.996868)
		(width 0.1143)
		(layer "In4.Cu")
		(net "P5E_CPU0_P1_TX_DP<6>")
	)
	(arc
		(start 340.524338 -376.24639)
		(mid 340.390792 -376.393657)
		(end 340.342474 -376.586496)
		(width 0.14224)
		(layer "In4.Cu")
		(net "P5E_CPU0_P1_TX_DP<6>")
	)
	(arc
		(start 350.369886 -289.981894)
		(mid 350.451867 -290.062544)
		(end 350.505522 -290.164266)
		(width 0.1143)
		(layer "In4.Cu")
		(net "P5E_CPU0_P1_TX_DP<6>")
	)
	(arc
		(start 349.125794 -287.961832)
		(mid 349.207227 -288.16423)
		(end 349.35922 -288.320734)
		(width 0.1143)
		(layer "In4.Cu")
		(net "P5E_CPU0_P1_TX_DP<6>")
	)
	(arc
		(start 370.07165 -338.220558)
		(mid 370.080154 -338.283169)
		(end 370.08308 -338.346288)
		(width 0.14224)
		(layer "In4.Cu")
		(net "P5E_CPU0_P1_TX_DP<6>")
	)
	(arc
		(start 350.83877 -294.031162)
		(mid 350.995747 -294.335962)
		(end 350.83877 -294.640762)
		(width 0.1143)
		(layer "In4.Cu")
		(net "P5E_CPU0_P1_TX_DP<6>")
	)
	(arc
		(start 369.719352 -349.447866)
		(mid 369.698788 -349.507683)
		(end 369.667536 -349.562674)
		(width 0.14224)
		(layer "In4.Cu")
		(net "P5E_CPU0_P1_TX_DP<6>")
	)
	(segment
		(start 338.620354 -380.85522)
		(end 338.620354 -380.15164)
		(width 0.12954)
		(layer "F.Cu")
		(net "P5E_CPU0_P1_TX_DP<5>")
	)
	(segment
		(start 338.620354 -380.15164)
		(end 338.349844 -379.88113)
		(width 0.12954)
		(layer "F.Cu")
		(net "P5E_CPU0_P1_TX_DP<5>")
	)
	(segment
		(start 338.324444 -381.15113)
		(end 338.620354 -380.85522)
		(width 0.12954)
		(layer "F.Cu")
		(net "P5E_CPU0_P1_TX_DP<5>")
	)
	(segment
		(start 349.20809 -290.83)
		(end 348.741238 -291.095938)
		(width 0.12954)
		(layer "F.Cu")
		(net "P5E_CPU0_P1_TX_DP<5>")
	)
	(segment
		(start 349.8469 -294.000936)
		(end 349.897192 -294.030146)
		(width 0.1143)
		(layer "In4.Cu")
		(net "P5E_CPU0_P1_TX_DP<5>")
	)
	(segment
		(start 349.36176 -291.562282)
		(end 349.398082 -291.583364)
		(width 0.1143)
		(layer "In4.Cu")
		(net "P5E_CPU0_P1_TX_DP<5>")
	)
	(segment
		(start 352.933508 -308.169056)
		(end 355.637338 -312.215276)
		(width 0.14224)
		(layer "In4.Cu")
		(net "P5E_CPU0_P1_TX_DP<5>")
	)
	(segment
		(start 349.070422 -296.205656)
		(end 349.070422 -296.234104)
		(width 0.1143)
		(layer "In4.Cu")
		(net "P5E_CPU0_P1_TX_DP<5>")
	)
	(segment
		(start 356.50805 -313.388756)
		(end 364.36808 -322.96608)
		(width 0.14224)
		(layer "In4.Cu")
		(net "P5E_CPU0_P1_TX_DP<5>")
	)
	(segment
		(start 369.132612 -338.399374)
		(end 369.132612 -347.867224)
		(width 0.14224)
		(layer "In4.Cu")
		(net "P5E_CPU0_P1_TX_DP<5>")
	)
	(segment
		(start 349.430848 -295.449498)
		(end 349.372174 -295.48328)
		(width 0.1143)
		(layer "In4.Cu")
		(net "P5E_CPU0_P1_TX_DP<5>")
	)
	(segment
		(start 349.10141 -298.917106)
		(end 352.933508 -308.169056)
		(width 0.14224)
		(layer "In4.Cu")
		(net "P5E_CPU0_P1_TX_DP<5>")
	)
	(segment
		(start 349.03918 -291.095938)
		(end 349.121984 -291.178742)
		(width 0.1143)
		(layer "In4.Cu")
		(net "P5E_CPU0_P1_TX_DP<5>")
	)
	(segment
		(start 338.640674 -376.918728)
		(end 338.640674 -379.5903)
		(width 0.14224)
		(layer "In4.Cu")
		(net "P5E_CPU0_P1_TX_DP<5>")
	)
	(segment
		(start 349.398082 -291.583364)
		(end 349.400114 -291.584634)
		(width 0.1143)
		(layer "In4.Cu")
		(net "P5E_CPU0_P1_TX_DP<5>")
	)
	(segment
		(start 364.36808 -322.96608)
		(end 364.645702 -323.497956)
		(width 0.14224)
		(layer "In4.Cu")
		(net "P5E_CPU0_P1_TX_DP<5>")
	)
	(segment
		(start 338.640674 -379.5903)
		(end 338.349844 -379.88113)
		(width 0.14224)
		(layer "In4.Cu")
		(net "P5E_CPU0_P1_TX_DP<5>")
	)
	(segment
		(start 356.503478 -313.383422)
		(end 356.50805 -313.388756)
		(width 0.14224)
		(layer "In4.Cu")
		(net "P5E_CPU0_P1_TX_DP<5>")
	)
	(segment
		(start 349.070422 -296.234104)
		(end 349.070422 -298.760642)
		(width 0.14224)
		(layer "In4.Cu")
		(net "P5E_CPU0_P1_TX_DP<5>")
	)
	(segment
		(start 348.741238 -291.095938)
		(end 349.03918 -291.095938)
		(width 0.1143)
		(layer "In4.Cu")
		(net "P5E_CPU0_P1_TX_DP<5>")
	)
	(segment
		(start 368.796316 -349.183198)
		(end 359.676954 -362.30941)
		(width 0.14224)
		(layer "In4.Cu")
		(net "P5E_CPU0_P1_TX_DP<5>")
	)
	(segment
		(start 356.070662 -312.799476)
		(end 356.503478 -313.383422)
		(width 0.14224)
		(layer "In4.Cu")
		(net "P5E_CPU0_P1_TX_DP<5>")
	)
	(segment
		(start 364.645702 -323.497956)
		(end 368.478054 -334.695038)
		(width 0.14224)
		(layer "In4.Cu")
		(net "P5E_CPU0_P1_TX_DP<5>")
	)
	(segment
		(start 349.116142 -296.159936)
		(end 349.070422 -296.205656)
		(width 0.1143)
		(layer "In4.Cu")
		(net "P5E_CPU0_P1_TX_DP<5>")
	)
	(segment
		(start 368.478054 -334.695038)
		(end 369.121182 -338.273644)
		(width 0.14224)
		(layer "In4.Cu")
		(net "P5E_CPU0_P1_TX_DP<5>")
	)
	(segment
		(start 349.901764 -294.63873)
		(end 349.829882 -294.680894)
		(width 0.1143)
		(layer "In4.Cu")
		(net "P5E_CPU0_P1_TX_DP<5>")
	)
	(segment
		(start 349.372174 -295.48328)
		(end 349.241872 -295.613328)
		(width 0.1143)
		(layer "In4.Cu")
		(net "P5E_CPU0_P1_TX_DP<5>")
	)
	(segment
		(start 359.676954 -362.30941)
		(end 339.099652 -376.0597)
		(width 0.14224)
		(layer "In4.Cu")
		(net "P5E_CPU0_P1_TX_DP<5>")
	)
	(segment
		(start 356.070662 -312.799222)
		(end 356.070662 -312.799476)
		(width 0.14224)
		(layer "In4.Cu")
		(net "P5E_CPU0_P1_TX_DP<5>")
	)
	(segment
		(start 349.898716 -293.02075)
		(end 349.8469 -293.050976)
		(width 0.1143)
		(layer "In4.Cu")
		(net "P5E_CPU0_P1_TX_DP<5>")
	)
	(segment
		(start 355.637338 -312.215276)
		(end 356.070662 -312.799222)
		(width 0.14224)
		(layer "In4.Cu")
		(net "P5E_CPU0_P1_TX_DP<5>")
	)
	(segment
		(start 369.127024 -347.918786)
		(end 368.847878 -349.06839)
		(width 0.14224)
		(layer "In4.Cu")
		(net "P5E_CPU0_P1_TX_DP<5>")
	)
	(segment
		(start 349.864172 -292.391084)
		(end 349.898716 -292.41115)
		(width 0.1143)
		(layer "In4.Cu")
		(net "P5E_CPU0_P1_TX_DP<5>")
	)
	(segment
		(start 349.116142 -295.91762)
		(end 349.116142 -296.159936)
		(width 0.1143)
		(layer "In4.Cu")
		(net "P5E_CPU0_P1_TX_DP<5>")
	)
	(arc
		(start 369.132612 -347.867224)
		(mid 369.131153 -347.893149)
		(end 369.127024 -347.918786)
		(width 0.14224)
		(layer "In4.Cu")
		(net "P5E_CPU0_P1_TX_DP<5>")
	)
	(arc
		(start 349.121984 -291.178742)
		(mid 349.201859 -291.395512)
		(end 349.36176 -291.562282)
		(width 0.1143)
		(layer "In4.Cu")
		(net "P5E_CPU0_P1_TX_DP<5>")
	)
	(arc
		(start 349.897192 -294.030146)
		(mid 350.057037 -294.333216)
		(end 349.901764 -294.63873)
		(width 0.1143)
		(layer "In4.Cu")
		(net "P5E_CPU0_P1_TX_DP<5>")
	)
	(arc
		(start 349.829882 -294.680894)
		(mid 349.650689 -294.883404)
		(end 349.586042 -295.145968)
		(width 0.1143)
		(layer "In4.Cu")
		(net "P5E_CPU0_P1_TX_DP<5>")
	)
	(arc
		(start 349.586042 -291.906198)
		(mid 349.660501 -292.185707)
		(end 349.864172 -292.391084)
		(width 0.1143)
		(layer "In4.Cu")
		(net "P5E_CPU0_P1_TX_DP<5>")
	)
	(arc
		(start 349.070422 -298.760642)
		(mid 349.078215 -298.8404)
		(end 349.10141 -298.917106)
		(width 0.14224)
		(layer "In4.Cu")
		(net "P5E_CPU0_P1_TX_DP<5>")
	)
	(arc
		(start 339.099652 -376.0597)
		(mid 338.762582 -376.43174)
		(end 338.640674 -376.918728)
		(width 0.14224)
		(layer "In4.Cu")
		(net "P5E_CPU0_P1_TX_DP<5>")
	)
	(arc
		(start 349.241872 -295.613328)
		(mid 349.148724 -295.752968)
		(end 349.116142 -295.91762)
		(width 0.1143)
		(layer "In4.Cu")
		(net "P5E_CPU0_P1_TX_DP<5>")
	)
	(arc
		(start 349.898716 -292.41115)
		(mid 350.055693 -292.71595)
		(end 349.898716 -293.02075)
		(width 0.1143)
		(layer "In4.Cu")
		(net "P5E_CPU0_P1_TX_DP<5>")
	)
	(arc
		(start 349.8469 -293.050976)
		(mid 349.573349 -293.525956)
		(end 349.8469 -294.000936)
		(width 0.1143)
		(layer "In4.Cu")
		(net "P5E_CPU0_P1_TX_DP<5>")
	)
	(arc
		(start 369.121182 -338.273644)
		(mid 369.129689 -338.336255)
		(end 369.132612 -338.399374)
		(width 0.14224)
		(layer "In4.Cu")
		(net "P5E_CPU0_P1_TX_DP<5>")
	)
	(arc
		(start 349.586042 -295.145968)
		(mid 349.544992 -295.316418)
		(end 349.430848 -295.449498)
		(width 0.1143)
		(layer "In4.Cu")
		(net "P5E_CPU0_P1_TX_DP<5>")
	)
	(arc
		(start 349.400114 -291.584634)
		(mid 349.536195 -291.720482)
		(end 349.586042 -291.906198)
		(width 0.1143)
		(layer "In4.Cu")
		(net "P5E_CPU0_P1_TX_DP<5>")
	)
	(arc
		(start 368.847878 -349.06839)
		(mid 368.827409 -349.12818)
		(end 368.796316 -349.183198)
		(width 0.14224)
		(layer "In4.Cu")
		(net "P5E_CPU0_P1_TX_DP<5>")
	)
	(segment
		(start 336.918554 -382.61544)
		(end 336.648044 -382.34493)
		(width 0.12954)
		(layer "F.Cu")
		(net "P5E_CPU0_P1_TX_DP<4>")
	)
	(segment
		(start 336.622644 -383.61493)
		(end 336.918554 -383.31902)
		(width 0.12954)
		(layer "F.Cu")
		(net "P5E_CPU0_P1_TX_DP<4>")
	)
	(segment
		(start 336.918554 -383.31902)
		(end 336.918554 -382.61544)
		(width 0.12954)
		(layer "F.Cu")
		(net "P5E_CPU0_P1_TX_DP<4>")
	)
	(segment
		(start 349.20809 -289.209988)
		(end 348.741238 -289.475926)
		(width 0.12954)
		(layer "F.Cu")
		(net "P5E_CPU0_P1_TX_DP<4>")
	)
	(segment
		(start 348.125288 -296.078656)
		(end 348.125288 -296.107104)
		(width 0.1143)
		(layer "In4.Cu")
		(net "P5E_CPU0_P1_TX_DP<4>")
	)
	(segment
		(start 365.620808 -352.056192)
		(end 360.152696 -358.83596)
		(width 0.14224)
		(layer "In4.Cu")
		(net "P5E_CPU0_P1_TX_DP<4>")
	)
	(segment
		(start 348.426786 -291.565076)
		(end 348.458282 -291.583364)
		(width 0.1143)
		(layer "In4.Cu")
		(net "P5E_CPU0_P1_TX_DP<4>")
	)
	(segment
		(start 363.585506 -323.482716)
		(end 363.651038 -323.607938)
		(width 0.14224)
		(layer "In4.Cu")
		(net "P5E_CPU0_P1_TX_DP<4>")
	)
	(segment
		(start 336.89163 -382.101344)
		(end 336.648044 -382.34493)
		(width 0.14224)
		(layer "In4.Cu")
		(net "P5E_CPU0_P1_TX_DP<4>")
	)
	(segment
		(start 368.174524 -338.410042)
		(end 368.174524 -347.795342)
		(width 0.14224)
		(layer "In4.Cu")
		(net "P5E_CPU0_P1_TX_DP<4>")
	)
	(segment
		(start 348.958916 -294.640762)
		(end 348.88932 -294.681402)
		(width 0.1143)
		(layer "In4.Cu")
		(net "P5E_CPU0_P1_TX_DP<4>")
	)
	(segment
		(start 348.459044 -290.608004)
		(end 348.458282 -290.608512)
		(width 0.1143)
		(layer "In4.Cu")
		(net "P5E_CPU0_P1_TX_DP<4>")
	)
	(segment
		(start 348.88932 -292.37051)
		(end 348.928436 -292.39337)
		(width 0.1143)
		(layer "In4.Cu")
		(net "P5E_CPU0_P1_TX_DP<4>")
	)
	(segment
		(start 352.14941 -308.712616)
		(end 355.153214 -313.208162)
		(width 0.14224)
		(layer "In4.Cu")
		(net "P5E_CPU0_P1_TX_DP<4>")
	)
	(segment
		(start 348.928436 -294.013382)
		(end 348.958916 -294.031162)
		(width 0.1143)
		(layer "In4.Cu")
		(net "P5E_CPU0_P1_TX_DP<4>")
	)
	(segment
		(start 365.660178 -329.478132)
		(end 367.597944 -335.13903)
		(width 0.14224)
		(layer "In4.Cu")
		(net "P5E_CPU0_P1_TX_DP<4>")
	)
	(segment
		(start 336.938874 -377.166886)
		(end 336.938874 -381.987298)
		(width 0.14224)
		(layer "In4.Cu")
		(net "P5E_CPU0_P1_TX_DP<4>")
	)
	(segment
		(start 348.171008 -296.032936)
		(end 348.125288 -296.078656)
		(width 0.1143)
		(layer "In4.Cu")
		(net "P5E_CPU0_P1_TX_DP<4>")
	)
	(segment
		(start 349.03918 -289.475926)
		(end 349.10903 -289.545776)
		(width 0.1143)
		(layer "In4.Cu")
		(net "P5E_CPU0_P1_TX_DP<4>")
	)
	(segment
		(start 348.608904 -295.358566)
		(end 348.301818 -295.665398)
		(width 0.1143)
		(layer "In4.Cu")
		(net "P5E_CPU0_P1_TX_DP<4>")
	)
	(segment
		(start 363.651038 -323.607938)
		(end 365.659924 -329.478132)
		(width 0.14224)
		(layer "In4.Cu")
		(net "P5E_CPU0_P1_TX_DP<4>")
	)
	(segment
		(start 348.4626 -291.585904)
		(end 348.464124 -291.586666)
		(width 0.1143)
		(layer "In4.Cu")
		(net "P5E_CPU0_P1_TX_DP<4>")
	)
	(segment
		(start 348.458282 -291.583364)
		(end 348.459044 -291.583872)
		(width 0.1143)
		(layer "In4.Cu")
		(net "P5E_CPU0_P1_TX_DP<4>")
	)
	(segment
		(start 348.459044 -291.583872)
		(end 348.461838 -291.585396)
		(width 0.1143)
		(layer "In4.Cu")
		(net "P5E_CPU0_P1_TX_DP<4>")
	)
	(segment
		(start 348.419166 -291.560504)
		(end 348.426024 -291.564568)
		(width 0.1143)
		(layer "In4.Cu")
		(net "P5E_CPU0_P1_TX_DP<4>")
	)
	(segment
		(start 365.659924 -329.478132)
		(end 365.660178 -329.478132)
		(width 0.14224)
		(layer "In4.Cu")
		(net "P5E_CPU0_P1_TX_DP<4>")
	)
	(segment
		(start 348.958916 -289.780726)
		(end 348.928436 -289.798506)
		(width 0.1143)
		(layer "In4.Cu")
		(net "P5E_CPU0_P1_TX_DP<4>")
	)
	(segment
		(start 348.928436 -292.39337)
		(end 348.958916 -292.41115)
		(width 0.1143)
		(layer "In4.Cu")
		(net "P5E_CPU0_P1_TX_DP<4>")
	)
	(segment
		(start 348.741238 -289.475926)
		(end 349.03918 -289.475926)
		(width 0.1143)
		(layer "In4.Cu")
		(net "P5E_CPU0_P1_TX_DP<4>")
	)
	(segment
		(start 348.171008 -295.981628)
		(end 348.171008 -296.032936)
		(width 0.1143)
		(layer "In4.Cu")
		(net "P5E_CPU0_P1_TX_DP<4>")
	)
	(segment
		(start 348.458282 -290.608512)
		(end 348.457266 -290.60902)
		(width 0.1143)
		(layer "In4.Cu")
		(net "P5E_CPU0_P1_TX_DP<4>")
	)
	(segment
		(start 367.597944 -335.13903)
		(end 368.163094 -338.284312)
		(width 0.14224)
		(layer "In4.Cu")
		(net "P5E_CPU0_P1_TX_DP<4>")
	)
	(segment
		(start 348.928436 -293.03853)
		(end 348.88932 -293.06139)
		(width 0.1143)
		(layer "In4.Cu")
		(net "P5E_CPU0_P1_TX_DP<4>")
	)
	(segment
		(start 368.167412 -347.849698)
		(end 367.96091 -348.65056)
		(width 0.14224)
		(layer "In4.Cu")
		(net "P5E_CPU0_P1_TX_DP<4>")
	)
	(segment
		(start 348.125288 -296.107104)
		(end 348.125288 -298.915836)
		(width 0.14224)
		(layer "In4.Cu")
		(net "P5E_CPU0_P1_TX_DP<4>")
	)
	(segment
		(start 348.457266 -290.60902)
		(end 348.455742 -290.610036)
		(width 0.1143)
		(layer "In4.Cu")
		(net "P5E_CPU0_P1_TX_DP<4>")
	)
	(segment
		(start 348.646242 -295.145968)
		(end 348.646242 -295.268396)
		(width 0.1143)
		(layer "In4.Cu")
		(net "P5E_CPU0_P1_TX_DP<4>")
	)
	(segment
		(start 348.455742 -290.610036)
		(end 348.419166 -290.631372)
		(width 0.1143)
		(layer "In4.Cu")
		(net "P5E_CPU0_P1_TX_DP<4>")
	)
	(segment
		(start 367.908332 -348.76486)
		(end 365.620808 -352.056192)
		(width 0.14224)
		(layer "In4.Cu")
		(net "P5E_CPU0_P1_TX_DP<4>")
	)
	(segment
		(start 355.153214 -313.208162)
		(end 363.585506 -323.482716)
		(width 0.14224)
		(layer "In4.Cu")
		(net "P5E_CPU0_P1_TX_DP<4>")
	)
	(segment
		(start 357.085392 -362.128054)
		(end 339.48116 -372.679214)
		(width 0.14224)
		(layer "In4.Cu")
		(net "P5E_CPU0_P1_TX_DP<4>")
	)
	(segment
		(start 348.88932 -293.990522)
		(end 348.928436 -294.013382)
		(width 0.1143)
		(layer "In4.Cu")
		(net "P5E_CPU0_P1_TX_DP<4>")
	)
	(segment
		(start 348.928436 -289.798506)
		(end 348.88932 -289.821366)
		(width 0.1143)
		(layer "In4.Cu")
		(net "P5E_CPU0_P1_TX_DP<4>")
	)
	(segment
		(start 348.426024 -291.564568)
		(end 348.426786 -291.565076)
		(width 0.1143)
		(layer "In4.Cu")
		(net "P5E_CPU0_P1_TX_DP<4>")
	)
	(segment
		(start 348.156276 -299.0723)
		(end 352.14941 -308.712616)
		(width 0.14224)
		(layer "In4.Cu")
		(net "P5E_CPU0_P1_TX_DP<4>")
	)
	(segment
		(start 348.464124 -291.586666)
		(end 348.464886 -291.587174)
		(width 0.1143)
		(layer "In4.Cu")
		(net "P5E_CPU0_P1_TX_DP<4>")
	)
	(segment
		(start 348.465902 -291.587682)
		(end 348.490032 -291.601652)
		(width 0.1143)
		(layer "In4.Cu")
		(net "P5E_CPU0_P1_TX_DP<4>")
	)
	(segment
		(start 348.460314 -290.607242)
		(end 348.459044 -290.608004)
		(width 0.1143)
		(layer "In4.Cu")
		(net "P5E_CPU0_P1_TX_DP<4>")
	)
	(segment
		(start 348.464886 -291.587174)
		(end 348.465902 -291.587682)
		(width 0.1143)
		(layer "In4.Cu")
		(net "P5E_CPU0_P1_TX_DP<4>")
	)
	(segment
		(start 360.152696 -358.83596)
		(end 357.085392 -362.128054)
		(width 0.14224)
		(layer "In4.Cu")
		(net "P5E_CPU0_P1_TX_DP<4>")
	)
	(segment
		(start 348.958916 -293.02075)
		(end 348.928436 -293.03853)
		(width 0.1143)
		(layer "In4.Cu")
		(net "P5E_CPU0_P1_TX_DP<4>")
	)
	(segment
		(start 348.490032 -290.590224)
		(end 348.460314 -290.607242)
		(width 0.1143)
		(layer "In4.Cu")
		(net "P5E_CPU0_P1_TX_DP<4>")
	)
	(segment
		(start 348.461838 -291.585396)
		(end 348.4626 -291.585904)
		(width 0.1143)
		(layer "In4.Cu")
		(net "P5E_CPU0_P1_TX_DP<4>")
	)
	(arc
		(start 348.88932 -294.681402)
		(mid 348.710677 -294.883797)
		(end 348.646242 -295.145968)
		(width 0.1143)
		(layer "In4.Cu")
		(net "P5E_CPU0_P1_TX_DP<4>")
	)
	(arc
		(start 368.174524 -347.795342)
		(mid 368.172674 -347.822743)
		(end 368.167412 -347.849698)
		(width 0.14224)
		(layer "In4.Cu")
		(net "P5E_CPU0_P1_TX_DP<4>")
	)
	(arc
		(start 339.48116 -372.679214)
		(mid 337.618567 -374.587998)
		(end 336.938874 -377.166886)
		(width 0.14224)
		(layer "In4.Cu")
		(net "P5E_CPU0_P1_TX_DP<4>")
	)
	(arc
		(start 348.125288 -298.915836)
		(mid 348.133081 -298.995594)
		(end 348.156276 -299.0723)
		(width 0.14224)
		(layer "In4.Cu")
		(net "P5E_CPU0_P1_TX_DP<4>")
	)
	(arc
		(start 348.958916 -294.031162)
		(mid 349.115893 -294.335962)
		(end 348.958916 -294.640762)
		(width 0.1143)
		(layer "In4.Cu")
		(net "P5E_CPU0_P1_TX_DP<4>")
	)
	(arc
		(start 348.646242 -295.268396)
		(mid 348.636551 -295.317205)
		(end 348.608904 -295.358566)
		(width 0.1143)
		(layer "In4.Cu")
		(net "P5E_CPU0_P1_TX_DP<4>")
	)
	(arc
		(start 349.10903 -289.545776)
		(mid 349.056613 -289.677707)
		(end 348.958916 -289.780726)
		(width 0.1143)
		(layer "In4.Cu")
		(net "P5E_CPU0_P1_TX_DP<4>")
	)
	(arc
		(start 348.645988 -291.905944)
		(mid 348.710503 -292.168163)
		(end 348.88932 -292.37051)
		(width 0.1143)
		(layer "In4.Cu")
		(net "P5E_CPU0_P1_TX_DP<4>")
	)
	(arc
		(start 336.938874 -381.987298)
		(mid 336.926597 -382.049021)
		(end 336.89163 -382.101344)
		(width 0.14224)
		(layer "In4.Cu")
		(net "P5E_CPU0_P1_TX_DP<4>")
	)
	(arc
		(start 348.88932 -293.06139)
		(mid 348.645993 -293.525956)
		(end 348.88932 -293.990522)
		(width 0.1143)
		(layer "In4.Cu")
		(net "P5E_CPU0_P1_TX_DP<4>")
	)
	(arc
		(start 348.301818 -295.665398)
		(mid 348.204957 -295.810501)
		(end 348.171008 -295.981628)
		(width 0.1143)
		(layer "In4.Cu")
		(net "P5E_CPU0_P1_TX_DP<4>")
	)
	(arc
		(start 367.96091 -348.65056)
		(mid 367.939697 -348.710045)
		(end 367.908332 -348.76486)
		(width 0.14224)
		(layer "In4.Cu")
		(net "P5E_CPU0_P1_TX_DP<4>")
	)
	(arc
		(start 348.419166 -290.631372)
		(mid 348.175839 -291.095938)
		(end 348.419166 -291.560504)
		(width 0.1143)
		(layer "In4.Cu")
		(net "P5E_CPU0_P1_TX_DP<4>")
	)
	(arc
		(start 348.490032 -291.601652)
		(mid 348.604708 -291.734986)
		(end 348.645988 -291.905944)
		(width 0.1143)
		(layer "In4.Cu")
		(net "P5E_CPU0_P1_TX_DP<4>")
	)
	(arc
		(start 348.645988 -290.285932)
		(mid 348.604733 -290.456903)
		(end 348.490032 -290.590224)
		(width 0.1143)
		(layer "In4.Cu")
		(net "P5E_CPU0_P1_TX_DP<4>")
	)
	(arc
		(start 348.958916 -292.41115)
		(mid 349.115893 -292.71595)
		(end 348.958916 -293.02075)
		(width 0.1143)
		(layer "In4.Cu")
		(net "P5E_CPU0_P1_TX_DP<4>")
	)
	(arc
		(start 348.88932 -289.821366)
		(mid 348.710507 -290.023716)
		(end 348.645988 -290.285932)
		(width 0.1143)
		(layer "In4.Cu")
		(net "P5E_CPU0_P1_TX_DP<4>")
	)
	(arc
		(start 368.163094 -338.284312)
		(mid 368.171598 -338.346923)
		(end 368.174524 -338.410042)
		(width 0.14224)
		(layer "In4.Cu")
		(net "P5E_CPU0_P1_TX_DP<4>")
	)
	(segment
		(start 333.219044 -378.68733)
		(end 333.514954 -378.39142)
		(width 0.12954)
		(layer "F.Cu")
		(net "P5E_CPU0_P1_TX_DP<3>")
	)
	(segment
		(start 333.514954 -378.39142)
		(end 333.514954 -377.68784)
		(width 0.12954)
		(layer "F.Cu")
		(net "P5E_CPU0_P1_TX_DP<3>")
	)
	(segment
		(start 333.514954 -377.68784)
		(end 333.244444 -377.41733)
		(width 0.12954)
		(layer "F.Cu")
		(net "P5E_CPU0_P1_TX_DP<3>")
	)
	(segment
		(start 346.387928 -287.59023)
		(end 345.921076 -287.856168)
		(width 0.12954)
		(layer "F.Cu")
		(net "P5E_CPU0_P1_TX_DP<3>")
	)
	(segment
		(start 358.819704 -358.752394)
		(end 357.140002 -360.609642)
		(width 0.14224)
		(layer "In4.Cu")
		(net "P5E_CPU0_P1_TX_DP<3>")
	)
	(segment
		(start 347.988128 -293.03853)
		(end 347.949012 -293.06139)
		(width 0.1143)
		(layer "In4.Cu")
		(net "P5E_CPU0_P1_TX_DP<3>")
	)
	(segment
		(start 345.921076 -287.856168)
		(end 346.219018 -287.856168)
		(width 0.1143)
		(layer "In4.Cu")
		(net "P5E_CPU0_P1_TX_DP<3>")
	)
	(segment
		(start 347.190568 -296.078656)
		(end 347.190568 -296.107104)
		(width 0.1143)
		(layer "In4.Cu")
		(net "P5E_CPU0_P1_TX_DP<3>")
	)
	(segment
		(start 347.518228 -290.608512)
		(end 347.479112 -290.631372)
		(width 0.1143)
		(layer "In4.Cu")
		(net "P5E_CPU0_P1_TX_DP<3>")
	)
	(segment
		(start 347.988128 -294.658542)
		(end 347.949012 -294.681402)
		(width 0.1143)
		(layer "In4.Cu")
		(net "P5E_CPU0_P1_TX_DP<3>")
	)
	(segment
		(start 354.380546 -313.744864)
		(end 362.800138 -324.003416)
		(width 0.14224)
		(layer "In4.Cu")
		(net "P5E_CPU0_P1_TX_DP<3>")
	)
	(segment
		(start 347.518228 -291.583364)
		(end 347.548708 -291.601144)
		(width 0.1143)
		(layer "In4.Cu")
		(net "P5E_CPU0_P1_TX_DP<3>")
	)
	(segment
		(start 333.535274 -377.1265)
		(end 333.244444 -377.41733)
		(width 0.14224)
		(layer "In4.Cu")
		(net "P5E_CPU0_P1_TX_DP<3>")
	)
	(segment
		(start 347.668342 -295.437306)
		(end 347.329506 -295.776142)
		(width 0.1143)
		(layer "In4.Cu")
		(net "P5E_CPU0_P1_TX_DP<3>")
	)
	(segment
		(start 347.548708 -290.590732)
		(end 347.518228 -290.608512)
		(width 0.1143)
		(layer "In4.Cu")
		(net "P5E_CPU0_P1_TX_DP<3>")
	)
	(segment
		(start 347.479112 -291.560504)
		(end 347.518228 -291.583364)
		(width 0.1143)
		(layer "In4.Cu")
		(net "P5E_CPU0_P1_TX_DP<3>")
	)
	(segment
		(start 367.078514 -348.11716)
		(end 365.103664 -351.072196)
		(width 0.14224)
		(layer "In4.Cu")
		(net "P5E_CPU0_P1_TX_DP<3>")
	)
	(segment
		(start 347.949012 -293.990522)
		(end 347.988128 -294.013382)
		(width 0.1143)
		(layer "In4.Cu")
		(net "P5E_CPU0_P1_TX_DP<3>")
	)
	(segment
		(start 347.988128 -292.39337)
		(end 348.018608 -292.41115)
		(width 0.1143)
		(layer "In4.Cu")
		(net "P5E_CPU0_P1_TX_DP<3>")
	)
	(segment
		(start 347.190568 -296.107104)
		(end 347.190568 -299.176948)
		(width 0.14224)
		(layer "In4.Cu")
		(net "P5E_CPU0_P1_TX_DP<3>")
	)
	(segment
		(start 351.338642 -309.191914)
		(end 354.380546 -313.744864)
		(width 0.14224)
		(layer "In4.Cu")
		(net "P5E_CPU0_P1_TX_DP<3>")
	)
	(segment
		(start 348.018608 -294.640762)
		(end 347.988128 -294.658542)
		(width 0.1143)
		(layer "In4.Cu")
		(net "P5E_CPU0_P1_TX_DP<3>")
	)
	(segment
		(start 348.018608 -293.02075)
		(end 347.988128 -293.03853)
		(width 0.1143)
		(layer "In4.Cu")
		(net "P5E_CPU0_P1_TX_DP<3>")
	)
	(segment
		(start 347.949012 -292.37051)
		(end 347.988128 -292.39337)
		(width 0.1143)
		(layer "In4.Cu")
		(net "P5E_CPU0_P1_TX_DP<3>")
	)
	(segment
		(start 346.219018 -287.856168)
		(end 346.301822 -287.938972)
		(width 0.1143)
		(layer "In4.Cu")
		(net "P5E_CPU0_P1_TX_DP<3>")
	)
	(segment
		(start 347.70568 -295.145968)
		(end 347.70568 -295.347136)
		(width 0.1143)
		(layer "In4.Cu")
		(net "P5E_CPU0_P1_TX_DP<3>")
	)
	(segment
		(start 367.224056 -338.40801)
		(end 367.224056 -347.637354)
		(width 0.14224)
		(layer "In4.Cu")
		(net "P5E_CPU0_P1_TX_DP<3>")
	)
	(segment
		(start 357.070406 -360.679746)
		(end 356.04069 -361.614466)
		(width 0.14224)
		(layer "In4.Cu")
		(net "P5E_CPU0_P1_TX_DP<3>")
	)
	(segment
		(start 362.800138 -324.003416)
		(end 366.666272 -335.296764)
		(width 0.14224)
		(layer "In4.Cu")
		(net "P5E_CPU0_P1_TX_DP<3>")
	)
	(segment
		(start 347.190568 -299.176948)
		(end 351.338642 -309.191914)
		(width 0.14224)
		(layer "In4.Cu")
		(net "P5E_CPU0_P1_TX_DP<3>")
	)
	(segment
		(start 366.698022 -335.419192)
		(end 367.212626 -338.28228)
		(width 0.14224)
		(layer "In4.Cu")
		(net "P5E_CPU0_P1_TX_DP<3>")
	)
	(segment
		(start 347.236288 -296.032936)
		(end 347.190568 -296.078656)
		(width 0.1143)
		(layer "In4.Cu")
		(net "P5E_CPU0_P1_TX_DP<3>")
	)
	(segment
		(start 347.520006 -289.964368)
		(end 347.548708 -289.981132)
		(width 0.1143)
		(layer "In4.Cu")
		(net "P5E_CPU0_P1_TX_DP<3>")
	)
	(segment
		(start 333.535274 -375.413016)
		(end 333.535274 -377.1265)
		(width 0.14224)
		(layer "In4.Cu")
		(net "P5E_CPU0_P1_TX_DP<3>")
	)
	(segment
		(start 365.02848 -351.17405)
		(end 358.902254 -358.656382)
		(width 0.14224)
		(layer "In4.Cu")
		(net "P5E_CPU0_P1_TX_DP<3>")
	)
	(segment
		(start 347.988128 -294.013382)
		(end 348.018608 -294.031162)
		(width 0.1143)
		(layer "In4.Cu")
		(net "P5E_CPU0_P1_TX_DP<3>")
	)
	(segment
		(start 356.019608 -361.630214)
		(end 333.776066 -374.987312)
		(width 0.14224)
		(layer "In4.Cu")
		(net "P5E_CPU0_P1_TX_DP<3>")
	)
	(segment
		(start 347.236288 -296.000932)
		(end 347.236288 -296.032936)
		(width 0.1143)
		(layer "In4.Cu")
		(net "P5E_CPU0_P1_TX_DP<3>")
	)
	(segment
		(start 347.055948 -289.17011)
		(end 347.121226 -289.20821)
		(width 0.1143)
		(layer "In4.Cu")
		(net "P5E_CPU0_P1_TX_DP<3>")
	)
	(segment
		(start 346.539058 -288.320734)
		(end 346.611702 -288.363152)
		(width 0.1143)
		(layer "In4.Cu")
		(net "P5E_CPU0_P1_TX_DP<3>")
	)
	(arc
		(start 347.23578 -289.479228)
		(mid 347.314246 -289.759097)
		(end 347.520006 -289.964368)
		(width 0.1143)
		(layer "In4.Cu")
		(net "P5E_CPU0_P1_TX_DP<3>")
	)
	(arc
		(start 346.611702 -288.363152)
		(mid 346.725109 -288.496041)
		(end 346.76588 -288.66592)
		(width 0.1143)
		(layer "In4.Cu")
		(net "P5E_CPU0_P1_TX_DP<3>")
	)
	(arc
		(start 347.121226 -289.20821)
		(mid 347.204766 -289.332609)
		(end 347.23578 -289.479228)
		(width 0.1143)
		(layer "In4.Cu")
		(net "P5E_CPU0_P1_TX_DP<3>")
	)
	(arc
		(start 366.666272 -335.296764)
		(mid 366.684475 -335.357374)
		(end 366.698022 -335.419192)
		(width 0.14224)
		(layer "In4.Cu")
		(net "P5E_CPU0_P1_TX_DP<3>")
	)
	(arc
		(start 347.479112 -290.631372)
		(mid 347.235785 -291.095938)
		(end 347.479112 -291.560504)
		(width 0.1143)
		(layer "In4.Cu")
		(net "P5E_CPU0_P1_TX_DP<3>")
	)
	(arc
		(start 347.70568 -295.347136)
		(mid 347.695974 -295.395931)
		(end 347.668342 -295.437306)
		(width 0.1143)
		(layer "In4.Cu")
		(net "P5E_CPU0_P1_TX_DP<3>")
	)
	(arc
		(start 367.212626 -338.28228)
		(mid 367.221133 -338.344891)
		(end 367.224056 -338.40801)
		(width 0.14224)
		(layer "In4.Cu")
		(net "P5E_CPU0_P1_TX_DP<3>")
	)
	(arc
		(start 347.329506 -295.776142)
		(mid 347.26054 -295.879262)
		(end 347.236288 -296.000932)
		(width 0.1143)
		(layer "In4.Cu")
		(net "P5E_CPU0_P1_TX_DP<3>")
	)
	(arc
		(start 346.301822 -287.938972)
		(mid 346.30361 -287.950421)
		(end 346.305632 -287.961832)
		(width 0.1143)
		(layer "In4.Cu")
		(net "P5E_CPU0_P1_TX_DP<3>")
	)
	(arc
		(start 365.103664 -351.072196)
		(mid 365.067308 -351.124035)
		(end 365.02848 -351.17405)
		(width 0.14224)
		(layer "In4.Cu")
		(net "P5E_CPU0_P1_TX_DP<3>")
	)
	(arc
		(start 346.305632 -287.961832)
		(mid 346.387065 -288.16423)
		(end 346.539058 -288.320734)
		(width 0.1143)
		(layer "In4.Cu")
		(net "P5E_CPU0_P1_TX_DP<3>")
	)
	(arc
		(start 358.902254 -358.656382)
		(mid 358.86157 -358.704896)
		(end 358.819704 -358.752394)
		(width 0.14224)
		(layer "In4.Cu")
		(net "P5E_CPU0_P1_TX_DP<3>")
	)
	(arc
		(start 347.70568 -291.905944)
		(mid 347.770195 -292.168163)
		(end 347.949012 -292.37051)
		(width 0.1143)
		(layer "In4.Cu")
		(net "P5E_CPU0_P1_TX_DP<3>")
	)
	(arc
		(start 347.949012 -294.681402)
		(mid 347.770122 -294.883726)
		(end 347.70568 -295.145968)
		(width 0.1143)
		(layer "In4.Cu")
		(net "P5E_CPU0_P1_TX_DP<3>")
	)
	(arc
		(start 347.548708 -291.601144)
		(mid 347.664135 -291.73452)
		(end 347.70568 -291.905944)
		(width 0.1143)
		(layer "In4.Cu")
		(net "P5E_CPU0_P1_TX_DP<3>")
	)
	(arc
		(start 347.548708 -289.981132)
		(mid 347.705685 -290.285932)
		(end 347.548708 -290.590732)
		(width 0.1143)
		(layer "In4.Cu")
		(net "P5E_CPU0_P1_TX_DP<3>")
	)
	(arc
		(start 357.140002 -360.609642)
		(mid 357.106062 -360.645545)
		(end 357.070406 -360.679746)
		(width 0.14224)
		(layer "In4.Cu")
		(net "P5E_CPU0_P1_TX_DP<3>")
	)
	(arc
		(start 333.776066 -374.987312)
		(mid 333.599684 -375.168488)
		(end 333.535274 -375.413016)
		(width 0.14224)
		(layer "In4.Cu")
		(net "P5E_CPU0_P1_TX_DP<3>")
	)
	(arc
		(start 348.018608 -294.031162)
		(mid 348.175585 -294.335962)
		(end 348.018608 -294.640762)
		(width 0.1143)
		(layer "In4.Cu")
		(net "P5E_CPU0_P1_TX_DP<3>")
	)
	(arc
		(start 367.224056 -347.637354)
		(mid 367.186858 -347.888044)
		(end 367.078514 -348.11716)
		(width 0.14224)
		(layer "In4.Cu")
		(net "P5E_CPU0_P1_TX_DP<3>")
	)
	(arc
		(start 346.76588 -288.66592)
		(mid 346.843575 -288.956754)
		(end 347.055948 -289.17011)
		(width 0.1143)
		(layer "In4.Cu")
		(net "P5E_CPU0_P1_TX_DP<3>")
	)
	(arc
		(start 347.949012 -293.06139)
		(mid 347.705685 -293.525956)
		(end 347.949012 -293.990522)
		(width 0.1143)
		(layer "In4.Cu")
		(net "P5E_CPU0_P1_TX_DP<3>")
	)
	(arc
		(start 356.04069 -361.614466)
		(mid 356.030538 -361.622861)
		(end 356.019608 -361.630214)
		(width 0.14224)
		(layer "In4.Cu")
		(net "P5E_CPU0_P1_TX_DP<3>")
	)
	(arc
		(start 348.018608 -292.41115)
		(mid 348.175585 -292.71595)
		(end 348.018608 -293.02075)
		(width 0.1143)
		(layer "In4.Cu")
		(net "P5E_CPU0_P1_TX_DP<3>")
	)
	(segment
		(start 331.517244 -381.15113)
		(end 331.813154 -380.85522)
		(width 0.12954)
		(layer "F.Cu")
		(net "P5E_CPU0_P1_TX_DP<2>")
	)
	(segment
		(start 346.387928 -290.83)
		(end 345.921076 -291.095938)
		(width 0.12954)
		(layer "F.Cu")
		(net "P5E_CPU0_P1_TX_DP<2>")
	)
	(segment
		(start 331.813154 -380.85522)
		(end 331.813154 -380.15164)
		(width 0.12954)
		(layer "F.Cu")
		(net "P5E_CPU0_P1_TX_DP<2>")
	)
	(segment
		(start 331.813154 -380.15164)
		(end 331.542644 -379.88113)
		(width 0.12954)
		(layer "F.Cu")
		(net "P5E_CPU0_P1_TX_DP<2>")
	)
	(segment
		(start 347.048074 -292.39337)
		(end 347.079824 -292.411658)
		(width 0.1143)
		(layer "In4.Cu")
		(net "P5E_CPU0_P1_TX_DP<2>")
	)
	(segment
		(start 346.25026 -296.107104)
		(end 346.25026 -299.262292)
		(width 0.14224)
		(layer "In4.Cu")
		(net "P5E_CPU0_P1_TX_DP<2>")
	)
	(segment
		(start 355.676962 -360.671364)
		(end 332.596236 -374.505474)
		(width 0.14224)
		(layer "In4.Cu")
		(net "P5E_CPU0_P1_TX_DP<2>")
	)
	(segment
		(start 331.833474 -375.851928)
		(end 331.833474 -379.5903)
		(width 0.14224)
		(layer "In4.Cu")
		(net "P5E_CPU0_P1_TX_DP<2>")
	)
	(segment
		(start 346.29598 -296.00144)
		(end 346.29598 -296.032936)
		(width 0.1143)
		(layer "In4.Cu")
		(net "P5E_CPU0_P1_TX_DP<2>")
	)
	(segment
		(start 346.546678 -291.565076)
		(end 346.578174 -291.583364)
		(width 0.1143)
		(layer "In4.Cu")
		(net "P5E_CPU0_P1_TX_DP<2>")
	)
	(segment
		(start 347.026738 -294.000936)
		(end 347.07703 -294.030146)
		(width 0.1143)
		(layer "In4.Cu")
		(net "P5E_CPU0_P1_TX_DP<2>")
	)
	(segment
		(start 347.081602 -294.63873)
		(end 347.00972 -294.680894)
		(width 0.1143)
		(layer "In4.Cu")
		(net "P5E_CPU0_P1_TX_DP<2>")
	)
	(segment
		(start 366.26165 -338.368386)
		(end 366.26165 -346.635324)
		(width 0.14224)
		(layer "In4.Cu")
		(net "P5E_CPU0_P1_TX_DP<2>")
	)
	(segment
		(start 350.555306 -309.736998)
		(end 353.675188 -314.40628)
		(width 0.14224)
		(layer "In4.Cu")
		(net "P5E_CPU0_P1_TX_DP<2>")
	)
	(segment
		(start 347.0275 -293.050468)
		(end 347.026738 -293.050976)
		(width 0.1143)
		(layer "In4.Cu")
		(net "P5E_CPU0_P1_TX_DP<2>")
	)
	(segment
		(start 347.079824 -293.020242)
		(end 347.048074 -293.03853)
		(width 0.1143)
		(layer "In4.Cu")
		(net "P5E_CPU0_P1_TX_DP<2>")
	)
	(segment
		(start 346.578936 -291.583872)
		(end 346.589096 -291.589714)
		(width 0.1143)
		(layer "In4.Cu")
		(net "P5E_CPU0_P1_TX_DP<2>")
	)
	(segment
		(start 366.245394 -346.7608)
		(end 365.874808 -348.163642)
		(width 0.14224)
		(layer "In4.Cu")
		(net "P5E_CPU0_P1_TX_DP<2>")
	)
	(segment
		(start 353.675188 -314.40628)
		(end 361.975908 -324.521068)
		(width 0.14224)
		(layer "In4.Cu")
		(net "P5E_CPU0_P1_TX_DP<2>")
	)
	(segment
		(start 331.833474 -379.5903)
		(end 331.542644 -379.88113)
		(width 0.14224)
		(layer "In4.Cu")
		(net "P5E_CPU0_P1_TX_DP<2>")
	)
	(segment
		(start 346.728542 -295.437306)
		(end 346.389198 -295.77665)
		(width 0.1143)
		(layer "In4.Cu")
		(net "P5E_CPU0_P1_TX_DP<2>")
	)
	(segment
		(start 365.782098 -335.638394)
		(end 366.25022 -338.242656)
		(width 0.14224)
		(layer "In4.Cu")
		(net "P5E_CPU0_P1_TX_DP<2>")
	)
	(segment
		(start 361.975908 -324.521068)
		(end 365.782098 -335.638394)
		(width 0.14224)
		(layer "In4.Cu")
		(net "P5E_CPU0_P1_TX_DP<2>")
	)
	(segment
		(start 346.77731 -291.914834)
		(end 346.77731 -291.923216)
		(width 0.1143)
		(layer "In4.Cu")
		(net "P5E_CPU0_P1_TX_DP<2>")
	)
	(segment
		(start 346.25026 -296.078656)
		(end 346.25026 -296.107104)
		(width 0.1143)
		(layer "In4.Cu")
		(net "P5E_CPU0_P1_TX_DP<2>")
	)
	(segment
		(start 346.29598 -296.032936)
		(end 346.25026 -296.078656)
		(width 0.1143)
		(layer "In4.Cu")
		(net "P5E_CPU0_P1_TX_DP<2>")
	)
	(segment
		(start 347.048074 -293.03853)
		(end 347.0275 -293.050468)
		(width 0.1143)
		(layer "In4.Cu")
		(net "P5E_CPU0_P1_TX_DP<2>")
	)
	(segment
		(start 345.921076 -291.095938)
		(end 346.219018 -291.095938)
		(width 0.1143)
		(layer "In4.Cu")
		(net "P5E_CPU0_P1_TX_DP<2>")
	)
	(segment
		(start 346.545916 -291.564568)
		(end 346.546678 -291.565076)
		(width 0.1143)
		(layer "In4.Cu")
		(net "P5E_CPU0_P1_TX_DP<2>")
	)
	(segment
		(start 365.817912 -348.275402)
		(end 355.676962 -360.671364)
		(width 0.14224)
		(layer "In4.Cu")
		(net "P5E_CPU0_P1_TX_DP<2>")
	)
	(segment
		(start 366.245394 -346.760546)
		(end 366.245394 -346.7608)
		(width 0.14224)
		(layer "In4.Cu")
		(net "P5E_CPU0_P1_TX_DP<2>")
	)
	(segment
		(start 346.76588 -295.145968)
		(end 346.76588 -295.347136)
		(width 0.1143)
		(layer "In4.Cu")
		(net "P5E_CPU0_P1_TX_DP<2>")
	)
	(segment
		(start 346.539058 -291.560504)
		(end 346.545916 -291.564568)
		(width 0.1143)
		(layer "In4.Cu")
		(net "P5E_CPU0_P1_TX_DP<2>")
	)
	(segment
		(start 346.578174 -291.583364)
		(end 346.578936 -291.583872)
		(width 0.1143)
		(layer "In4.Cu")
		(net "P5E_CPU0_P1_TX_DP<2>")
	)
	(segment
		(start 346.281502 -299.42028)
		(end 350.555306 -309.736998)
		(width 0.14224)
		(layer "In4.Cu")
		(net "P5E_CPU0_P1_TX_DP<2>")
	)
	(segment
		(start 346.219018 -291.095938)
		(end 346.301822 -291.178742)
		(width 0.1143)
		(layer "In4.Cu")
		(net "P5E_CPU0_P1_TX_DP<2>")
	)
	(arc
		(start 366.26165 -346.635324)
		(mid 366.257567 -346.69846)
		(end 366.245394 -346.760546)
		(width 0.14224)
		(layer "In4.Cu")
		(net "P5E_CPU0_P1_TX_DP<2>")
	)
	(arc
		(start 346.76588 -295.347136)
		(mid 346.756174 -295.395931)
		(end 346.728542 -295.437306)
		(width 0.1143)
		(layer "In4.Cu")
		(net "P5E_CPU0_P1_TX_DP<2>")
	)
	(arc
		(start 346.389198 -295.77665)
		(mid 346.320232 -295.87977)
		(end 346.29598 -296.00144)
		(width 0.1143)
		(layer "In4.Cu")
		(net "P5E_CPU0_P1_TX_DP<2>")
	)
	(arc
		(start 366.25022 -338.242656)
		(mid 366.25873 -338.305267)
		(end 366.26165 -338.368386)
		(width 0.14224)
		(layer "In4.Cu")
		(net "P5E_CPU0_P1_TX_DP<2>")
	)
	(arc
		(start 346.77731 -291.923216)
		(mid 346.849841 -292.194489)
		(end 347.048074 -292.39337)
		(width 0.1143)
		(layer "In4.Cu")
		(net "P5E_CPU0_P1_TX_DP<2>")
	)
	(arc
		(start 347.00972 -294.680894)
		(mid 346.830527 -294.883404)
		(end 346.76588 -295.145968)
		(width 0.1143)
		(layer "In4.Cu")
		(net "P5E_CPU0_P1_TX_DP<2>")
	)
	(arc
		(start 347.07703 -294.030146)
		(mid 347.236875 -294.333216)
		(end 347.081602 -294.63873)
		(width 0.1143)
		(layer "In4.Cu")
		(net "P5E_CPU0_P1_TX_DP<2>")
	)
	(arc
		(start 365.874808 -348.163642)
		(mid 365.852351 -348.222573)
		(end 365.817912 -348.275402)
		(width 0.14224)
		(layer "In4.Cu")
		(net "P5E_CPU0_P1_TX_DP<2>")
	)
	(arc
		(start 346.305632 -291.201602)
		(mid 346.387065 -291.404)
		(end 346.539058 -291.560504)
		(width 0.1143)
		(layer "In4.Cu")
		(net "P5E_CPU0_P1_TX_DP<2>")
	)
	(arc
		(start 332.596236 -374.505474)
		(mid 332.03739 -375.078172)
		(end 331.833474 -375.851928)
		(width 0.14224)
		(layer "In4.Cu")
		(net "P5E_CPU0_P1_TX_DP<2>")
	)
	(arc
		(start 347.079824 -292.411658)
		(mid 347.235752 -292.71595)
		(end 347.079824 -293.020242)
		(width 0.1143)
		(layer "In4.Cu")
		(net "P5E_CPU0_P1_TX_DP<2>")
	)
	(arc
		(start 346.589096 -291.589714)
		(mid 346.726865 -291.726998)
		(end 346.77731 -291.914834)
		(width 0.1143)
		(layer "In4.Cu")
		(net "P5E_CPU0_P1_TX_DP<2>")
	)
	(arc
		(start 346.301822 -291.178742)
		(mid 346.30361 -291.190191)
		(end 346.305632 -291.201602)
		(width 0.1143)
		(layer "In4.Cu")
		(net "P5E_CPU0_P1_TX_DP<2>")
	)
	(arc
		(start 346.25026 -299.262292)
		(mid 346.258097 -299.342825)
		(end 346.281502 -299.42028)
		(width 0.14224)
		(layer "In4.Cu")
		(net "P5E_CPU0_P1_TX_DP<2>")
	)
	(arc
		(start 347.026738 -293.050976)
		(mid 346.753187 -293.525956)
		(end 347.026738 -294.000936)
		(width 0.1143)
		(layer "In4.Cu")
		(net "P5E_CPU0_P1_TX_DP<2>")
	)
	(segment
		(start 330.932282 -384.62077)
		(end 330.228702 -384.62077)
		(width 0.12954)
		(layer "F.Cu")
		(net "P5E_CPU0_P1_TX_DP<1>")
	)
	(segment
		(start 346.387928 -289.209988)
		(end 345.921076 -289.475926)
		(width 0.12954)
		(layer "F.Cu")
		(net "P5E_CPU0_P1_TX_DP<1>")
	)
	(segment
		(start 331.228192 -384.32486)
		(end 330.932282 -384.62077)
		(width 0.12954)
		(layer "F.Cu")
		(net "P5E_CPU0_P1_TX_DP<1>")
	)
	(segment
		(start 330.228702 -384.62077)
		(end 329.958192 -384.35026)
		(width 0.12954)
		(layer "F.Cu")
		(net "P5E_CPU0_P1_TX_DP<1>")
	)
	(segment
		(start 345.310206 -296.107104)
		(end 345.310206 -299.42917)
		(width 0.14224)
		(layer "In4.Cu")
		(net "P5E_CPU0_P1_TX_DP<1>")
	)
	(segment
		(start 345.63558 -290.610036)
		(end 345.599004 -290.631372)
		(width 0.1143)
		(layer "In4.Cu")
		(net "P5E_CPU0_P1_TX_DP<1>")
	)
	(segment
		(start 365.32947 -346.044012)
		(end 365.329216 -346.043758)
		(width 0.14224)
		(layer "In4.Cu")
		(net "P5E_CPU0_P1_TX_DP<1>")
	)
	(segment
		(start 329.904852 -379.179836)
		(end 329.904852 -379.606556)
		(width 0.14224)
		(layer "In4.Cu")
		(net "P5E_CPU0_P1_TX_DP<1>")
	)
	(segment
		(start 345.64574 -291.587682)
		(end 345.66987 -291.601652)
		(width 0.1143)
		(layer "In4.Cu")
		(net "P5E_CPU0_P1_TX_DP<1>")
	)
	(segment
		(start 345.637104 -290.60902)
		(end 345.63558 -290.610036)
		(width 0.1143)
		(layer "In4.Cu")
		(net "P5E_CPU0_P1_TX_DP<1>")
	)
	(segment
		(start 346.108274 -293.03853)
		(end 346.069158 -293.06139)
		(width 0.1143)
		(layer "In4.Cu")
		(net "P5E_CPU0_P1_TX_DP<1>")
	)
	(segment
		(start 330.042012 -379.743716)
		(end 330.042012 -380.170436)
		(width 0.14224)
		(layer "In4.Cu")
		(net "P5E_CPU0_P1_TX_DP<1>")
	)
	(segment
		(start 330.243688 -381.819404)
		(end 331.016102 -382.591818)
		(width 0.14224)
		(layer "In4.Cu")
		(net "P5E_CPU0_P1_TX_DP<1>")
	)
	(segment
		(start 345.345258 -299.606208)
		(end 349.719392 -310.166512)
		(width 0.14224)
		(layer "In4.Cu")
		(net "P5E_CPU0_P1_TX_DP<1>")
	)
	(segment
		(start 346.108274 -292.39337)
		(end 346.138754 -292.41115)
		(width 0.1143)
		(layer "In4.Cu")
		(net "P5E_CPU0_P1_TX_DP<1>")
	)
	(segment
		(start 329.904852 -379.606556)
		(end 330.042012 -379.743716)
		(width 0.14224)
		(layer "In4.Cu")
		(net "P5E_CPU0_P1_TX_DP<1>")
	)
	(segment
		(start 345.637104 -291.582856)
		(end 345.63812 -291.583364)
		(width 0.1143)
		(layer "In4.Cu")
		(net "P5E_CPU0_P1_TX_DP<1>")
	)
	(segment
		(start 345.310206 -296.078656)
		(end 345.310206 -296.107104)
		(width 0.1143)
		(layer "In4.Cu")
		(net "P5E_CPU0_P1_TX_DP<1>")
	)
	(segment
		(start 345.599004 -291.560504)
		(end 345.637104 -291.582856)
		(width 0.1143)
		(layer "In4.Cu")
		(net "P5E_CPU0_P1_TX_DP<1>")
	)
	(segment
		(start 357.034846 -319.99174)
		(end 361.0737 -324.913244)
		(width 0.14224)
		(layer "In4.Cu")
		(net "P5E_CPU0_P1_TX_DP<1>")
	)
	(segment
		(start 345.643962 -291.586666)
		(end 345.644724 -291.587174)
		(width 0.1143)
		(layer "In4.Cu")
		(net "P5E_CPU0_P1_TX_DP<1>")
	)
	(segment
		(start 346.138754 -293.02075)
		(end 346.108274 -293.03853)
		(width 0.1143)
		(layer "In4.Cu")
		(net "P5E_CPU0_P1_TX_DP<1>")
	)
	(segment
		(start 330.042012 -380.170436)
		(end 329.904852 -380.307596)
		(width 0.14224)
		(layer "In4.Cu")
		(net "P5E_CPU0_P1_TX_DP<1>")
	)
	(segment
		(start 345.63812 -290.608512)
		(end 345.637104 -290.60902)
		(width 0.1143)
		(layer "In4.Cu")
		(net "P5E_CPU0_P1_TX_DP<1>")
	)
	(segment
		(start 364.53953 -348.255082)
		(end 354.915724 -360.003852)
		(width 0.14224)
		(layer "In4.Cu")
		(net "P5E_CPU0_P1_TX_DP<1>")
	)
	(segment
		(start 330.042012 -378.615956)
		(end 330.042012 -379.042676)
		(width 0.14224)
		(layer "In4.Cu")
		(net "P5E_CPU0_P1_TX_DP<1>")
	)
	(segment
		(start 345.825826 -295.145968)
		(end 345.825826 -295.347136)
		(width 0.1143)
		(layer "In4.Cu")
		(net "P5E_CPU0_P1_TX_DP<1>")
	)
	(segment
		(start 345.638882 -290.608004)
		(end 345.63812 -290.608512)
		(width 0.1143)
		(layer "In4.Cu")
		(net "P5E_CPU0_P1_TX_DP<1>")
	)
	(segment
		(start 364.539276 -348.255082)
		(end 364.53953 -348.255082)
		(width 0.14224)
		(layer "In4.Cu")
		(net "P5E_CPU0_P1_TX_DP<1>")
	)
	(segment
		(start 345.641676 -291.585396)
		(end 345.642438 -291.585904)
		(width 0.1143)
		(layer "In4.Cu")
		(net "P5E_CPU0_P1_TX_DP<1>")
	)
	(segment
		(start 329.904852 -378.052076)
		(end 329.904852 -378.478796)
		(width 0.14224)
		(layer "In4.Cu")
		(net "P5E_CPU0_P1_TX_DP<1>")
	)
	(segment
		(start 345.788488 -295.437306)
		(end 345.449144 -295.77665)
		(width 0.1143)
		(layer "In4.Cu")
		(net "P5E_CPU0_P1_TX_DP<1>")
	)
	(segment
		(start 331.154278 -383.2225)
		(end 331.043534 -383.333244)
		(width 0.14224)
		(layer "In4.Cu")
		(net "P5E_CPU0_P1_TX_DP<1>")
	)
	(segment
		(start 329.904852 -378.478796)
		(end 330.042012 -378.615956)
		(width 0.14224)
		(layer "In4.Cu")
		(net "P5E_CPU0_P1_TX_DP<1>")
	)
	(segment
		(start 357.034846 -319.991994)
		(end 357.034846 -319.99174)
		(width 0.14224)
		(layer "In4.Cu")
		(net "P5E_CPU0_P1_TX_DP<1>")
	)
	(segment
		(start 345.355926 -296.032936)
		(end 345.310206 -296.078656)
		(width 0.1143)
		(layer "In4.Cu")
		(net "P5E_CPU0_P1_TX_DP<1>")
	)
	(segment
		(start 346.108274 -289.798506)
		(end 346.069158 -289.821366)
		(width 0.1143)
		(layer "In4.Cu")
		(net "P5E_CPU0_P1_TX_DP<1>")
	)
	(segment
		(start 349.719392 -310.166512)
		(end 352.995738 -315.070236)
		(width 0.14224)
		(layer "In4.Cu")
		(net "P5E_CPU0_P1_TX_DP<1>")
	)
	(segment
		(start 330.042012 -376.06605)
		(end 330.042012 -377.914916)
		(width 0.14224)
		(layer "In4.Cu")
		(net "P5E_CPU0_P1_TX_DP<1>")
	)
	(segment
		(start 345.355926 -296.00144)
		(end 345.355926 -296.032936)
		(width 0.1143)
		(layer "In4.Cu")
		(net "P5E_CPU0_P1_TX_DP<1>")
	)
	(segment
		(start 329.904852 -380.307596)
		(end 329.904852 -380.734316)
		(width 0.14224)
		(layer "In4.Cu")
		(net "P5E_CPU0_P1_TX_DP<1>")
	)
	(segment
		(start 330.249022 -384.64109)
		(end 329.958192 -384.35026)
		(width 0.14224)
		(layer "In4.Cu")
		(net "P5E_CPU0_P1_TX_DP<1>")
	)
	(segment
		(start 345.63812 -291.583364)
		(end 345.638882 -291.583872)
		(width 0.1143)
		(layer "In4.Cu")
		(net "P5E_CPU0_P1_TX_DP<1>")
	)
	(segment
		(start 331.043534 -383.759964)
		(end 331.154278 -383.870708)
		(width 0.14224)
		(layer "In4.Cu")
		(net "P5E_CPU0_P1_TX_DP<1>")
	)
	(segment
		(start 346.219018 -289.475926)
		(end 346.288868 -289.545776)
		(width 0.1143)
		(layer "In4.Cu")
		(net "P5E_CPU0_P1_TX_DP<1>")
	)
	(segment
		(start 330.882752 -384.64109)
		(end 330.249022 -384.64109)
		(width 0.14224)
		(layer "In4.Cu")
		(net "P5E_CPU0_P1_TX_DP<1>")
	)
	(segment
		(start 361.0737 -324.913244)
		(end 364.900718 -336.091784)
		(width 0.14224)
		(layer "In4.Cu")
		(net "P5E_CPU0_P1_TX_DP<1>")
	)
	(segment
		(start 346.138754 -289.780726)
		(end 346.108274 -289.798506)
		(width 0.1143)
		(layer "In4.Cu")
		(net "P5E_CPU0_P1_TX_DP<1>")
	)
	(segment
		(start 330.042012 -380.871476)
		(end 330.042012 -381.332486)
		(width 0.14224)
		(layer "In4.Cu")
		(net "P5E_CPU0_P1_TX_DP<1>")
	)
	(segment
		(start 354.915724 -360.003852)
		(end 331.030326 -374.320562)
		(width 0.14224)
		(layer "In4.Cu")
		(net "P5E_CPU0_P1_TX_DP<1>")
	)
	(segment
		(start 346.069158 -293.990522)
		(end 346.108274 -294.013382)
		(width 0.1143)
		(layer "In4.Cu")
		(net "P5E_CPU0_P1_TX_DP<1>")
	)
	(segment
		(start 345.644724 -291.587174)
		(end 345.64574 -291.587682)
		(width 0.1143)
		(layer "In4.Cu")
		(net "P5E_CPU0_P1_TX_DP<1>")
	)
	(segment
		(start 331.11694 -384.519932)
		(end 331.075792 -384.56108)
		(width 0.14224)
		(layer "In4.Cu")
		(net "P5E_CPU0_P1_TX_DP<1>")
	)
	(segment
		(start 331.043534 -383.333244)
		(end 331.043534 -383.759964)
		(width 0.14224)
		(layer "In4.Cu")
		(net "P5E_CPU0_P1_TX_DP<1>")
	)
	(segment
		(start 330.042012 -379.042676)
		(end 329.904852 -379.179836)
		(width 0.14224)
		(layer "In4.Cu")
		(net "P5E_CPU0_P1_TX_DP<1>")
	)
	(segment
		(start 345.66987 -290.590224)
		(end 345.640152 -290.607242)
		(width 0.1143)
		(layer "In4.Cu")
		(net "P5E_CPU0_P1_TX_DP<1>")
	)
	(segment
		(start 329.904852 -380.734316)
		(end 330.042012 -380.871476)
		(width 0.14224)
		(layer "In4.Cu")
		(net "P5E_CPU0_P1_TX_DP<1>")
	)
	(segment
		(start 365.32947 -338.477098)
		(end 365.32947 -346.044012)
		(width 0.14224)
		(layer "In4.Cu")
		(net "P5E_CPU0_P1_TX_DP<1>")
	)
	(segment
		(start 346.069158 -292.37051)
		(end 346.108274 -292.39337)
		(width 0.1143)
		(layer "In4.Cu")
		(net "P5E_CPU0_P1_TX_DP<1>")
	)
	(segment
		(start 330.042012 -377.914916)
		(end 329.904852 -378.052076)
		(width 0.14224)
		(layer "In4.Cu")
		(net "P5E_CPU0_P1_TX_DP<1>")
	)
	(segment
		(start 345.642438 -291.585904)
		(end 345.643962 -291.586666)
		(width 0.1143)
		(layer "In4.Cu")
		(net "P5E_CPU0_P1_TX_DP<1>")
	)
	(segment
		(start 364.900718 -336.091784)
		(end 365.32947 -338.477098)
		(width 0.14224)
		(layer "In4.Cu")
		(net "P5E_CPU0_P1_TX_DP<1>")
	)
	(segment
		(start 331.154278 -383.870708)
		(end 331.154278 -384.430016)
		(width 0.14224)
		(layer "In4.Cu")
		(net "P5E_CPU0_P1_TX_DP<1>")
	)
	(segment
		(start 346.108274 -294.658542)
		(end 346.069158 -294.681402)
		(width 0.1143)
		(layer "In4.Cu")
		(net "P5E_CPU0_P1_TX_DP<1>")
	)
	(segment
		(start 346.138754 -294.640762)
		(end 346.108274 -294.658542)
		(width 0.1143)
		(layer "In4.Cu")
		(net "P5E_CPU0_P1_TX_DP<1>")
	)
	(segment
		(start 345.638882 -291.583872)
		(end 345.641676 -291.585396)
		(width 0.1143)
		(layer "In4.Cu")
		(net "P5E_CPU0_P1_TX_DP<1>")
	)
	(segment
		(start 352.995738 -315.070236)
		(end 357.034846 -319.991994)
		(width 0.14224)
		(layer "In4.Cu")
		(net "P5E_CPU0_P1_TX_DP<1>")
	)
	(segment
		(start 331.154278 -382.92532)
		(end 331.154278 -383.2225)
		(width 0.14224)
		(layer "In4.Cu")
		(net "P5E_CPU0_P1_TX_DP<1>")
	)
	(segment
		(start 345.640152 -290.607242)
		(end 345.638882 -290.608004)
		(width 0.1143)
		(layer "In4.Cu")
		(net "P5E_CPU0_P1_TX_DP<1>")
	)
	(segment
		(start 345.921076 -289.475926)
		(end 346.219018 -289.475926)
		(width 0.1143)
		(layer "In4.Cu")
		(net "P5E_CPU0_P1_TX_DP<1>")
	)
	(segment
		(start 346.108274 -294.013382)
		(end 346.138754 -294.031162)
		(width 0.1143)
		(layer "In4.Cu")
		(net "P5E_CPU0_P1_TX_DP<1>")
	)
	(arc
		(start 365.329216 -346.043758)
		(mid 365.125796 -347.217843)
		(end 364.539276 -348.255082)
		(width 0.14224)
		(layer "In4.Cu")
		(net "P5E_CPU0_P1_TX_DP<1>")
	)
	(arc
		(start 345.825826 -291.905944)
		(mid 345.890341 -292.168163)
		(end 346.069158 -292.37051)
		(width 0.1143)
		(layer "In4.Cu")
		(net "P5E_CPU0_P1_TX_DP<1>")
	)
	(arc
		(start 346.069158 -293.06139)
		(mid 345.825831 -293.525956)
		(end 346.069158 -293.990522)
		(width 0.1143)
		(layer "In4.Cu")
		(net "P5E_CPU0_P1_TX_DP<1>")
	)
	(arc
		(start 330.042012 -381.332486)
		(mid 330.094428 -381.596)
		(end 330.243688 -381.819404)
		(width 0.14224)
		(layer "In4.Cu")
		(net "P5E_CPU0_P1_TX_DP<1>")
	)
	(arc
		(start 345.449144 -295.77665)
		(mid 345.380178 -295.87977)
		(end 345.355926 -296.00144)
		(width 0.1143)
		(layer "In4.Cu")
		(net "P5E_CPU0_P1_TX_DP<1>")
	)
	(arc
		(start 345.599004 -290.631372)
		(mid 345.355677 -291.095938)
		(end 345.599004 -291.560504)
		(width 0.1143)
		(layer "In4.Cu")
		(net "P5E_CPU0_P1_TX_DP<1>")
	)
	(arc
		(start 345.825826 -290.285932)
		(mid 345.784571 -290.456903)
		(end 345.66987 -290.590224)
		(width 0.1143)
		(layer "In4.Cu")
		(net "P5E_CPU0_P1_TX_DP<1>")
	)
	(arc
		(start 346.288868 -289.545776)
		(mid 346.236451 -289.677707)
		(end 346.138754 -289.780726)
		(width 0.1143)
		(layer "In4.Cu")
		(net "P5E_CPU0_P1_TX_DP<1>")
	)
	(arc
		(start 345.310206 -299.42917)
		(mid 345.319034 -299.51941)
		(end 345.345258 -299.606208)
		(width 0.14224)
		(layer "In4.Cu")
		(net "P5E_CPU0_P1_TX_DP<1>")
	)
	(arc
		(start 331.154278 -384.430016)
		(mid 331.144576 -384.4787)
		(end 331.11694 -384.519932)
		(width 0.14224)
		(layer "In4.Cu")
		(net "P5E_CPU0_P1_TX_DP<1>")
	)
	(arc
		(start 331.075792 -384.56108)
		(mid 330.987239 -384.620313)
		(end 330.882752 -384.64109)
		(width 0.14224)
		(layer "In4.Cu")
		(net "P5E_CPU0_P1_TX_DP<1>")
	)
	(arc
		(start 346.138754 -294.031162)
		(mid 346.295731 -294.335962)
		(end 346.138754 -294.640762)
		(width 0.1143)
		(layer "In4.Cu")
		(net "P5E_CPU0_P1_TX_DP<1>")
	)
	(arc
		(start 346.138754 -292.41115)
		(mid 346.295731 -292.71595)
		(end 346.138754 -293.02075)
		(width 0.1143)
		(layer "In4.Cu")
		(net "P5E_CPU0_P1_TX_DP<1>")
	)
	(arc
		(start 331.030326 -374.320562)
		(mid 330.30609 -375.06304)
		(end 330.042012 -376.06605)
		(width 0.14224)
		(layer "In4.Cu")
		(net "P5E_CPU0_P1_TX_DP<1>")
	)
	(arc
		(start 346.069158 -289.821366)
		(mid 345.890345 -290.023716)
		(end 345.825826 -290.285932)
		(width 0.1143)
		(layer "In4.Cu")
		(net "P5E_CPU0_P1_TX_DP<1>")
	)
	(arc
		(start 345.66987 -291.601652)
		(mid 345.784546 -291.734986)
		(end 345.825826 -291.905944)
		(width 0.1143)
		(layer "In4.Cu")
		(net "P5E_CPU0_P1_TX_DP<1>")
	)
	(arc
		(start 345.825826 -295.347136)
		(mid 345.81612 -295.395931)
		(end 345.788488 -295.437306)
		(width 0.1143)
		(layer "In4.Cu")
		(net "P5E_CPU0_P1_TX_DP<1>")
	)
	(arc
		(start 331.016102 -382.591818)
		(mid 331.118341 -382.74483)
		(end 331.154278 -382.92532)
		(width 0.14224)
		(layer "In4.Cu")
		(net "P5E_CPU0_P1_TX_DP<1>")
	)
	(arc
		(start 346.069158 -294.681402)
		(mid 345.89036 -294.883746)
		(end 345.825826 -295.145968)
		(width 0.1143)
		(layer "In4.Cu")
		(net "P5E_CPU0_P1_TX_DP<1>")
	)
	(segment
		(start 358.831134 -388.149338)
		(end 359.534714 -388.149338)
		(width 0.12954)
		(layer "F.Cu")
		(net "P5E_CPU0_P1_TX_DP<15>")
	)
	(segment
		(start 359.534714 -388.149338)
		(end 359.805224 -387.878828)
		(width 0.12954)
		(layer "F.Cu")
		(net "P5E_CPU0_P1_TX_DP<15>")
	)
	(segment
		(start 358.535224 -387.853428)
		(end 358.831134 -388.149338)
		(width 0.12954)
		(layer "F.Cu")
		(net "P5E_CPU0_P1_TX_DP<15>")
	)
	(segment
		(start 357.197914 -286.780224)
		(end 356.731062 -287.045908)
		(width 0.12954)
		(layer "F.Cu")
		(net "P5E_CPU0_P1_TX_DP<15>")
	)
	(segment
		(start 361.289854 -383.646934)
		(end 361.427014 -383.784094)
		(width 0.14224)
		(layer "In4.Cu")
		(net "P5E_CPU0_P1_TX_DP<15>")
	)
	(segment
		(start 357.853996 -288.341816)
		(end 357.86441 -288.34715)
		(width 0.1143)
		(layer "In4.Cu")
		(net "P5E_CPU0_P1_TX_DP<15>")
	)
	(segment
		(start 361.427014 -382.717802)
		(end 361.427014 -383.083054)
		(width 0.14224)
		(layer "In4.Cu")
		(net "P5E_CPU0_P1_TX_DP<15>")
	)
	(segment
		(start 361.389676 -387.642354)
		(end 360.93908 -388.09295)
		(width 0.14224)
		(layer "In4.Cu")
		(net "P5E_CPU0_P1_TX_DP<15>")
	)
	(segment
		(start 361.427014 -383.784094)
		(end 361.427014 -384.221736)
		(width 0.14224)
		(layer "In4.Cu")
		(net "P5E_CPU0_P1_TX_DP<15>")
	)
	(segment
		(start 361.289854 -384.785616)
		(end 361.427014 -384.922776)
		(width 0.14224)
		(layer "In4.Cu")
		(net "P5E_CPU0_P1_TX_DP<15>")
	)
	(segment
		(start 363.666278 -307.271928)
		(end 372.18112 -317.646558)
		(width 0.14224)
		(layer "In4.Cu")
		(net "P5E_CPU0_P1_TX_DP<15>")
	)
	(segment
		(start 361.289854 -384.358896)
		(end 361.289854 -384.785616)
		(width 0.14224)
		(layer "In4.Cu")
		(net "P5E_CPU0_P1_TX_DP<15>")
	)
	(segment
		(start 359.13949 -290.281868)
		(end 359.13949 -298.69892)
		(width 0.14224)
		(layer "In4.Cu")
		(net "P5E_CPU0_P1_TX_DP<15>")
	)
	(segment
		(start 359.18521 -290.2077)
		(end 359.13949 -290.25342)
		(width 0.1143)
		(layer "In4.Cu")
		(net "P5E_CPU0_P1_TX_DP<15>")
	)
	(segment
		(start 373.647208 -320.445892)
		(end 373.647462 -320.446146)
		(width 0.14224)
		(layer "In4.Cu")
		(net "P5E_CPU0_P1_TX_DP<15>")
	)
	(segment
		(start 361.289854 -387.041136)
		(end 361.427014 -387.178296)
		(width 0.14224)
		(layer "In4.Cu")
		(net "P5E_CPU0_P1_TX_DP<15>")
	)
	(segment
		(start 361.71378 -382.098804)
		(end 361.661964 -382.15062)
		(width 0.14224)
		(layer "In4.Cu")
		(net "P5E_CPU0_P1_TX_DP<15>")
	)
	(segment
		(start 358.290622 -289.131502)
		(end 358.32796 -289.153346)
		(width 0.1143)
		(layer "In4.Cu")
		(net "P5E_CPU0_P1_TX_DP<15>")
	)
	(segment
		(start 358.412796 -289.220402)
		(end 359.18521 -289.85464)
		(width 0.1143)
		(layer "In4.Cu")
		(net "P5E_CPU0_P1_TX_DP<15>")
	)
	(segment
		(start 361.909614 -377.550426)
		(end 361.909614 -381.626364)
		(width 0.14224)
		(layer "In4.Cu")
		(net "P5E_CPU0_P1_TX_DP<15>")
	)
	(segment
		(start 360.754168 -388.169658)
		(end 360.096054 -388.169658)
		(width 0.14224)
		(layer "In4.Cu")
		(net "P5E_CPU0_P1_TX_DP<15>")
	)
	(segment
		(start 378.661676 -349.018098)
		(end 377.871228 -352.87966)
		(width 0.14224)
		(layer "In4.Cu")
		(net "P5E_CPU0_P1_TX_DP<15>")
	)
	(segment
		(start 361.289854 -385.486656)
		(end 361.289854 -385.913376)
		(width 0.14224)
		(layer "In4.Cu")
		(net "P5E_CPU0_P1_TX_DP<15>")
	)
	(segment
		(start 377.61926 -332.054962)
		(end 378.6505 -337.795108)
		(width 0.14224)
		(layer "In4.Cu")
		(net "P5E_CPU0_P1_TX_DP<15>")
	)
	(segment
		(start 356.731062 -287.045908)
		(end 357.029004 -287.045908)
		(width 0.1143)
		(layer "In4.Cu")
		(net "P5E_CPU0_P1_TX_DP<15>")
	)
	(segment
		(start 372.18112 -317.646558)
		(end 372.18112 -317.646812)
		(width 0.14224)
		(layer "In4.Cu")
		(net "P5E_CPU0_P1_TX_DP<15>")
	)
	(segment
		(start 357.029004 -287.045908)
		(end 357.111808 -287.128712)
		(width 0.1143)
		(layer "In4.Cu")
		(net "P5E_CPU0_P1_TX_DP<15>")
	)
	(segment
		(start 361.289854 -386.614416)
		(end 361.289854 -387.041136)
		(width 0.14224)
		(layer "In4.Cu")
		(net "P5E_CPU0_P1_TX_DP<15>")
	)
	(segment
		(start 373.654828 -320.463926)
		(end 377.614434 -332.036166)
		(width 0.14224)
		(layer "In4.Cu")
		(net "P5E_CPU0_P1_TX_DP<15>")
	)
	(segment
		(start 361.014264 -303.30648)
		(end 362.332016 -305.27879)
		(width 0.14224)
		(layer "In4.Cu")
		(net "P5E_CPU0_P1_TX_DP<15>")
	)
	(segment
		(start 361.427014 -384.221736)
		(end 361.289854 -384.358896)
		(width 0.14224)
		(layer "In4.Cu")
		(net "P5E_CPU0_P1_TX_DP<15>")
	)
	(segment
		(start 359.18521 -289.85464)
		(end 359.18521 -290.2077)
		(width 0.1143)
		(layer "In4.Cu")
		(net "P5E_CPU0_P1_TX_DP<15>")
	)
	(segment
		(start 361.427014 -387.178296)
		(end 361.427014 -387.552438)
		(width 0.14224)
		(layer "In4.Cu")
		(net "P5E_CPU0_P1_TX_DP<15>")
	)
	(segment
		(start 360.096054 -388.169658)
		(end 359.805224 -387.878828)
		(width 0.14224)
		(layer "In4.Cu")
		(net "P5E_CPU0_P1_TX_DP<15>")
	)
	(segment
		(start 361.427014 -383.083054)
		(end 361.289854 -383.220214)
		(width 0.14224)
		(layer "In4.Cu")
		(net "P5E_CPU0_P1_TX_DP<15>")
	)
	(segment
		(start 378.661676 -337.921346)
		(end 378.661676 -349.018098)
		(width 0.14224)
		(layer "In4.Cu")
		(net "P5E_CPU0_P1_TX_DP<15>")
	)
	(segment
		(start 361.289854 -385.913376)
		(end 361.427014 -386.050536)
		(width 0.14224)
		(layer "In4.Cu")
		(net "P5E_CPU0_P1_TX_DP<15>")
	)
	(segment
		(start 377.871228 -352.87966)
		(end 362.49229 -375.64568)
		(width 0.14224)
		(layer "In4.Cu")
		(net "P5E_CPU0_P1_TX_DP<15>")
	)
	(segment
		(start 361.427014 -386.050536)
		(end 361.427014 -386.477256)
		(width 0.14224)
		(layer "In4.Cu")
		(net "P5E_CPU0_P1_TX_DP<15>")
	)
	(segment
		(start 357.853488 -288.341054)
		(end 357.853996 -288.341816)
		(width 0.1143)
		(layer "In4.Cu")
		(net "P5E_CPU0_P1_TX_DP<15>")
	)
	(segment
		(start 357.349298 -287.510728)
		(end 357.408734 -287.545526)
		(width 0.1143)
		(layer "In4.Cu")
		(net "P5E_CPU0_P1_TX_DP<15>")
	)
	(segment
		(start 361.427014 -385.349496)
		(end 361.289854 -385.486656)
		(width 0.14224)
		(layer "In4.Cu")
		(net "P5E_CPU0_P1_TX_DP<15>")
	)
	(segment
		(start 362.332016 -305.27879)
		(end 363.63402 -307.227732)
		(width 0.14224)
		(layer "In4.Cu")
		(net "P5E_CPU0_P1_TX_DP<15>")
	)
	(segment
		(start 358.404668 -289.212274)
		(end 358.412796 -289.220402)
		(width 0.1143)
		(layer "In4.Cu")
		(net "P5E_CPU0_P1_TX_DP<15>")
	)
	(segment
		(start 357.873046 -288.351976)
		(end 357.88981 -288.361628)
		(width 0.1143)
		(layer "In4.Cu")
		(net "P5E_CPU0_P1_TX_DP<15>")
	)
	(segment
		(start 357.86441 -288.34715)
		(end 357.873046 -288.351976)
		(width 0.1143)
		(layer "In4.Cu")
		(net "P5E_CPU0_P1_TX_DP<15>")
	)
	(segment
		(start 358.32796 -289.153346)
		(end 358.328214 -289.153346)
		(width 0.1143)
		(layer "In4.Cu")
		(net "P5E_CPU0_P1_TX_DP<15>")
	)
	(segment
		(start 361.427014 -384.922776)
		(end 361.427014 -385.349496)
		(width 0.14224)
		(layer "In4.Cu")
		(net "P5E_CPU0_P1_TX_DP<15>")
	)
	(segment
		(start 359.170478 -298.855384)
		(end 361.014264 -303.30648)
		(width 0.14224)
		(layer "In4.Cu")
		(net "P5E_CPU0_P1_TX_DP<15>")
	)
	(segment
		(start 372.195598 -317.668402)
		(end 373.647208 -320.445892)
		(width 0.14224)
		(layer "In4.Cu")
		(net "P5E_CPU0_P1_TX_DP<15>")
	)
	(segment
		(start 361.289854 -383.220214)
		(end 361.289854 -383.646934)
		(width 0.14224)
		(layer "In4.Cu")
		(net "P5E_CPU0_P1_TX_DP<15>")
	)
	(segment
		(start 361.427014 -386.477256)
		(end 361.289854 -386.614416)
		(width 0.14224)
		(layer "In4.Cu")
		(net "P5E_CPU0_P1_TX_DP<15>")
	)
	(segment
		(start 359.13949 -290.25342)
		(end 359.13949 -290.281868)
		(width 0.1143)
		(layer "In4.Cu")
		(net "P5E_CPU0_P1_TX_DP<15>")
	)
	(arc
		(start 361.909614 -381.626364)
		(mid 361.858715 -381.882073)
		(end 361.71378 -382.098804)
		(width 0.14224)
		(layer "In4.Cu")
		(net "P5E_CPU0_P1_TX_DP<15>")
	)
	(arc
		(start 372.18112 -317.646812)
		(mid 372.188921 -317.657231)
		(end 372.195598 -317.668402)
		(width 0.14224)
		(layer "In4.Cu")
		(net "P5E_CPU0_P1_TX_DP<15>")
	)
	(arc
		(start 361.661964 -382.15062)
		(mid 361.488087 -382.410845)
		(end 361.427014 -382.717802)
		(width 0.14224)
		(layer "In4.Cu")
		(net "P5E_CPU0_P1_TX_DP<15>")
	)
	(arc
		(start 357.111808 -287.128712)
		(mid 357.113498 -287.138507)
		(end 357.115364 -287.14827)
		(width 0.1143)
		(layer "In4.Cu")
		(net "P5E_CPU0_P1_TX_DP<15>")
	)
	(arc
		(start 358.04602 -288.66592)
		(mid 358.110838 -288.928909)
		(end 358.290622 -289.131502)
		(width 0.1143)
		(layer "In4.Cu")
		(net "P5E_CPU0_P1_TX_DP<15>")
	)
	(arc
		(start 357.573834 -287.84677)
		(mid 357.575146 -287.858683)
		(end 357.575866 -287.870646)
		(width 0.1143)
		(layer "In4.Cu")
		(net "P5E_CPU0_P1_TX_DP<15>")
	)
	(arc
		(start 359.13949 -298.69892)
		(mid 359.147283 -298.778678)
		(end 359.170478 -298.855384)
		(width 0.14224)
		(layer "In4.Cu")
		(net "P5E_CPU0_P1_TX_DP<15>")
	)
	(arc
		(start 361.427014 -387.552438)
		(mid 361.417312 -387.601122)
		(end 361.389676 -387.642354)
		(width 0.14224)
		(layer "In4.Cu")
		(net "P5E_CPU0_P1_TX_DP<15>")
	)
	(arc
		(start 373.647462 -320.446146)
		(mid 373.65148 -320.454897)
		(end 373.654828 -320.463926)
		(width 0.14224)
		(layer "In4.Cu")
		(net "P5E_CPU0_P1_TX_DP<15>")
	)
	(arc
		(start 363.63402 -307.227732)
		(mid 363.649677 -307.250175)
		(end 363.666278 -307.271928)
		(width 0.14224)
		(layer "In4.Cu")
		(net "P5E_CPU0_P1_TX_DP<15>")
	)
	(arc
		(start 378.6505 -337.795108)
		(mid 378.658903 -337.857978)
		(end 378.661676 -337.921346)
		(width 0.14224)
		(layer "In4.Cu")
		(net "P5E_CPU0_P1_TX_DP<15>")
	)
	(arc
		(start 362.49229 -375.64568)
		(mid 362.058454 -376.554463)
		(end 361.909614 -377.550426)
		(width 0.14224)
		(layer "In4.Cu")
		(net "P5E_CPU0_P1_TX_DP<15>")
	)
	(arc
		(start 357.575866 -287.870646)
		(mid 357.653672 -288.14187)
		(end 357.853488 -288.341054)
		(width 0.1143)
		(layer "In4.Cu")
		(net "P5E_CPU0_P1_TX_DP<15>")
	)
	(arc
		(start 357.88981 -288.361628)
		(mid 358.004711 -288.494889)
		(end 358.04602 -288.66592)
		(width 0.1143)
		(layer "In4.Cu")
		(net "P5E_CPU0_P1_TX_DP<15>")
	)
	(arc
		(start 377.614434 -332.036166)
		(mid 377.617205 -332.045472)
		(end 377.61926 -332.054962)
		(width 0.14224)
		(layer "In4.Cu")
		(net "P5E_CPU0_P1_TX_DP<15>")
	)
	(arc
		(start 357.115364 -287.14827)
		(mid 357.196391 -287.352697)
		(end 357.349298 -287.510728)
		(width 0.1143)
		(layer "In4.Cu")
		(net "P5E_CPU0_P1_TX_DP<15>")
	)
	(arc
		(start 357.408734 -287.545526)
		(mid 357.518506 -287.681225)
		(end 357.573834 -287.84677)
		(width 0.1143)
		(layer "In4.Cu")
		(net "P5E_CPU0_P1_TX_DP<15>")
	)
	(arc
		(start 360.93908 -388.09295)
		(mid 360.85427 -388.149745)
		(end 360.754168 -388.169658)
		(width 0.14224)
		(layer "In4.Cu")
		(net "P5E_CPU0_P1_TX_DP<15>")
	)
	(arc
		(start 358.328214 -289.153346)
		(mid 358.368359 -289.180322)
		(end 358.404668 -289.212274)
		(width 0.1143)
		(layer "In4.Cu")
		(net "P5E_CPU0_P1_TX_DP<15>")
	)
	(segment
		(start 357.197914 -288.399982)
		(end 356.731062 -288.66592)
		(width 0.12954)
		(layer "F.Cu")
		(net "P5E_CPU0_P1_TX_DP<14>")
	)
	(segment
		(start 358.831134 -385.068318)
		(end 359.534714 -385.068318)
		(width 0.12954)
		(layer "F.Cu")
		(net "P5E_CPU0_P1_TX_DP<14>")
	)
	(segment
		(start 359.534714 -385.068318)
		(end 359.805224 -385.338828)
		(width 0.12954)
		(layer "F.Cu")
		(net "P5E_CPU0_P1_TX_DP<14>")
	)
	(segment
		(start 358.535224 -385.364228)
		(end 358.831134 -385.068318)
		(width 0.12954)
		(layer "F.Cu")
		(net "P5E_CPU0_P1_TX_DP<14>")
	)
	(segment
		(start 358.359456 -293.020242)
		(end 358.328214 -293.03853)
		(width 0.1143)
		(layer "In4.Cu")
		(net "P5E_CPU0_P1_TX_DP<14>")
	)
	(segment
		(start 358.045766 -295.483026)
		(end 358.000046 -295.528746)
		(width 0.1143)
		(layer "In4.Cu")
		(net "P5E_CPU0_P1_TX_DP<14>")
	)
	(segment
		(start 358.045766 -295.145968)
		(end 358.045766 -295.483026)
		(width 0.1143)
		(layer "In4.Cu")
		(net "P5E_CPU0_P1_TX_DP<14>")
	)
	(segment
		(start 358.289098 -292.37051)
		(end 358.32669 -292.392354)
		(width 0.1143)
		(layer "In4.Cu")
		(net "P5E_CPU0_P1_TX_DP<14>")
	)
	(segment
		(start 377.716796 -337.872832)
		(end 377.716796 -348.762828)
		(width 0.14224)
		(layer "In4.Cu")
		(net "P5E_CPU0_P1_TX_DP<14>")
	)
	(segment
		(start 358.938322 -385.047998)
		(end 359.514394 -385.047998)
		(width 0.14224)
		(layer "In4.Cu")
		(net "P5E_CPU0_P1_TX_DP<14>")
	)
	(segment
		(start 357.349044 -289.13074)
		(end 357.411274 -289.166808)
		(width 0.1143)
		(layer "In4.Cu")
		(net "P5E_CPU0_P1_TX_DP<14>")
	)
	(segment
		(start 358.328214 -294.013382)
		(end 358.359964 -294.031924)
		(width 0.1143)
		(layer "In4.Cu")
		(net "P5E_CPU0_P1_TX_DP<14>")
	)
	(segment
		(start 358.360218 -293.019734)
		(end 358.359456 -293.020242)
		(width 0.1143)
		(layer "In4.Cu")
		(net "P5E_CPU0_P1_TX_DP<14>")
	)
	(segment
		(start 358.000046 -295.528746)
		(end 358.000046 -295.557194)
		(width 0.1143)
		(layer "In4.Cu")
		(net "P5E_CPU0_P1_TX_DP<14>")
	)
	(segment
		(start 377.716796 -348.762828)
		(end 376.868436 -352.69678)
		(width 0.14224)
		(layer "In4.Cu")
		(net "P5E_CPU0_P1_TX_DP<14>")
	)
	(segment
		(start 357.029004 -288.66592)
		(end 357.111808 -288.748724)
		(width 0.1143)
		(layer "In4.Cu")
		(net "P5E_CPU0_P1_TX_DP<14>")
	)
	(segment
		(start 358.40797 -384.687064)
		(end 358.649016 -384.92811)
		(width 0.14224)
		(layer "In4.Cu")
		(net "P5E_CPU0_P1_TX_DP<14>")
	)
	(segment
		(start 362.907834 -372.958106)
		(end 361.435142 -375.095516)
		(width 0.14224)
		(layer "In4.Cu")
		(net "P5E_CPU0_P1_TX_DP<14>")
	)
	(segment
		(start 358.288082 -384.046984)
		(end 358.288082 -384.397758)
		(width 0.14224)
		(layer "In4.Cu")
		(net "P5E_CPU0_P1_TX_DP<14>")
	)
	(segment
		(start 360.20121 -303.78019)
		(end 362.891578 -307.806598)
		(width 0.14224)
		(layer "In4.Cu")
		(net "P5E_CPU0_P1_TX_DP<14>")
	)
	(segment
		(start 362.891578 -307.806598)
		(end 367.15573 -313.002168)
		(width 0.14224)
		(layer "In4.Cu")
		(net "P5E_CPU0_P1_TX_DP<14>")
	)
	(segment
		(start 357.821738 -289.94227)
		(end 357.85806 -289.963352)
		(width 0.1143)
		(layer "In4.Cu")
		(net "P5E_CPU0_P1_TX_DP<14>")
	)
	(segment
		(start 358.336088 -291.413692)
		(end 358.290622 -291.440362)
		(width 0.1143)
		(layer "In4.Cu")
		(net "P5E_CPU0_P1_TX_DP<14>")
	)
	(segment
		(start 358.060752 -298.61256)
		(end 360.20121 -303.78019)
		(width 0.14224)
		(layer "In4.Cu")
		(net "P5E_CPU0_P1_TX_DP<14>")
	)
	(segment
		(start 356.731062 -288.66592)
		(end 357.029004 -288.66592)
		(width 0.1143)
		(layer "In4.Cu")
		(net "P5E_CPU0_P1_TX_DP<14>")
	)
	(segment
		(start 358.327198 -290.77285)
		(end 358.32796 -290.773358)
		(width 0.1143)
		(layer "In4.Cu")
		(net "P5E_CPU0_P1_TX_DP<14>")
	)
	(segment
		(start 376.712226 -332.279244)
		(end 377.716796 -337.872832)
		(width 0.14224)
		(layer "In4.Cu")
		(net "P5E_CPU0_P1_TX_DP<14>")
	)
	(segment
		(start 376.868436 -352.69678)
		(end 362.907834 -372.958106)
		(width 0.14224)
		(layer "In4.Cu")
		(net "P5E_CPU0_P1_TX_DP<14>")
	)
	(segment
		(start 358.32796 -294.013382)
		(end 358.328214 -294.013382)
		(width 0.1143)
		(layer "In4.Cu")
		(net "P5E_CPU0_P1_TX_DP<14>")
	)
	(segment
		(start 358.396032 -294.615108)
		(end 358.324912 -294.660574)
		(width 0.1143)
		(layer "In4.Cu")
		(net "P5E_CPU0_P1_TX_DP<14>")
	)
	(segment
		(start 358.328214 -293.03853)
		(end 358.32796 -293.038784)
		(width 0.1143)
		(layer "In4.Cu")
		(net "P5E_CPU0_P1_TX_DP<14>")
	)
	(segment
		(start 360.785664 -381.206756)
		(end 358.530398 -383.462022)
		(width 0.14224)
		(layer "In4.Cu")
		(net "P5E_CPU0_P1_TX_DP<14>")
	)
	(segment
		(start 358.289098 -290.750498)
		(end 358.327198 -290.77285)
		(width 0.1143)
		(layer "In4.Cu")
		(net "P5E_CPU0_P1_TX_DP<14>")
	)
	(segment
		(start 358.324912 -294.660574)
		(end 358.290622 -294.680132)
		(width 0.1143)
		(layer "In4.Cu")
		(net "P5E_CPU0_P1_TX_DP<14>")
	)
	(segment
		(start 358.515412 -292.702742)
		(end 358.515412 -292.72992)
		(width 0.1143)
		(layer "In4.Cu")
		(net "P5E_CPU0_P1_TX_DP<14>")
	)
	(segment
		(start 372.79199 -320.822828)
		(end 376.712226 -332.279244)
		(width 0.14224)
		(layer "In4.Cu")
		(net "P5E_CPU0_P1_TX_DP<14>")
	)
	(segment
		(start 358.000046 -295.557194)
		(end 358.000046 -298.306744)
		(width 0.14224)
		(layer "In4.Cu")
		(net "P5E_CPU0_P1_TX_DP<14>")
	)
	(segment
		(start 367.15573 -313.001914)
		(end 371.419628 -318.196976)
		(width 0.14224)
		(layer "In4.Cu")
		(net "P5E_CPU0_P1_TX_DP<14>")
	)
	(segment
		(start 359.514394 -385.047998)
		(end 359.805224 -385.338828)
		(width 0.14224)
		(layer "In4.Cu")
		(net "P5E_CPU0_P1_TX_DP<14>")
	)
	(segment
		(start 367.15573 -313.002168)
		(end 367.15573 -313.001914)
		(width 0.14224)
		(layer "In4.Cu")
		(net "P5E_CPU0_P1_TX_DP<14>")
	)
	(segment
		(start 357.85806 -289.963352)
		(end 357.88981 -289.98164)
		(width 0.1143)
		(layer "In4.Cu")
		(net "P5E_CPU0_P1_TX_DP<14>")
	)
	(segment
		(start 358.359964 -294.031924)
		(end 358.393238 -294.055038)
		(width 0.1143)
		(layer "In4.Cu")
		(net "P5E_CPU0_P1_TX_DP<14>")
	)
	(segment
		(start 371.419628 -318.196976)
		(end 372.79199 -320.822828)
		(width 0.14224)
		(layer "In4.Cu")
		(net "P5E_CPU0_P1_TX_DP<14>")
	)
	(segment
		(start 360.976164 -376.570494)
		(end 360.976164 -380.747016)
		(width 0.14224)
		(layer "In4.Cu")
		(net "P5E_CPU0_P1_TX_DP<14>")
	)
	(segment
		(start 358.32669 -292.392354)
		(end 358.367584 -292.417246)
		(width 0.1143)
		(layer "In4.Cu")
		(net "P5E_CPU0_P1_TX_DP<14>")
	)
	(arc
		(start 358.045766 -290.285932)
		(mid 358.110281 -290.548151)
		(end 358.289098 -290.750498)
		(width 0.1143)
		(layer "In4.Cu")
		(net "P5E_CPU0_P1_TX_DP<14>")
	)
	(arc
		(start 358.367584 -292.417246)
		(mid 358.476276 -292.541978)
		(end 358.515412 -292.702742)
		(width 0.1143)
		(layer "In4.Cu")
		(net "P5E_CPU0_P1_TX_DP<14>")
	)
	(arc
		(start 360.976164 -380.747016)
		(mid 360.926652 -380.995838)
		(end 360.785664 -381.206756)
		(width 0.14224)
		(layer "In4.Cu")
		(net "P5E_CPU0_P1_TX_DP<14>")
	)
	(arc
		(start 358.290622 -294.680132)
		(mid 358.110678 -294.882813)
		(end 358.045766 -295.145968)
		(width 0.1143)
		(layer "In4.Cu")
		(net "P5E_CPU0_P1_TX_DP<14>")
	)
	(arc
		(start 358.289098 -291.441378)
		(mid 358.045771 -291.905944)
		(end 358.289098 -292.37051)
		(width 0.1143)
		(layer "In4.Cu")
		(net "P5E_CPU0_P1_TX_DP<14>")
	)
	(arc
		(start 357.88981 -289.98164)
		(mid 358.004486 -290.114974)
		(end 358.045766 -290.285932)
		(width 0.1143)
		(layer "In4.Cu")
		(net "P5E_CPU0_P1_TX_DP<14>")
	)
	(arc
		(start 357.81107 -289.934904)
		(mid 357.816384 -289.938616)
		(end 357.821738 -289.94227)
		(width 0.1143)
		(layer "In4.Cu")
		(net "P5E_CPU0_P1_TX_DP<14>")
	)
	(arc
		(start 358.290622 -291.440362)
		(mid 358.28986 -291.440869)
		(end 358.289098 -291.441378)
		(width 0.1143)
		(layer "In4.Cu")
		(net "P5E_CPU0_P1_TX_DP<14>")
	)
	(arc
		(start 358.288082 -384.397758)
		(mid 358.319245 -384.554336)
		(end 358.40797 -384.687064)
		(width 0.14224)
		(layer "In4.Cu")
		(net "P5E_CPU0_P1_TX_DP<14>")
	)
	(arc
		(start 358.32796 -290.773358)
		(mid 358.512938 -291.091212)
		(end 358.336088 -291.413692)
		(width 0.1143)
		(layer "In4.Cu")
		(net "P5E_CPU0_P1_TX_DP<14>")
	)
	(arc
		(start 357.411274 -289.166808)
		(mid 357.519474 -289.30221)
		(end 357.573834 -289.466782)
		(width 0.1143)
		(layer "In4.Cu")
		(net "P5E_CPU0_P1_TX_DP<14>")
	)
	(arc
		(start 357.116126 -288.77133)
		(mid 357.197253 -288.973926)
		(end 357.349044 -289.13074)
		(width 0.1143)
		(layer "In4.Cu")
		(net "P5E_CPU0_P1_TX_DP<14>")
	)
	(arc
		(start 358.393238 -294.055038)
		(mid 358.540391 -294.334308)
		(end 358.396032 -294.615108)
		(width 0.1143)
		(layer "In4.Cu")
		(net "P5E_CPU0_P1_TX_DP<14>")
	)
	(arc
		(start 357.111808 -288.748724)
		(mid 357.113853 -288.760049)
		(end 357.116126 -288.77133)
		(width 0.1143)
		(layer "In4.Cu")
		(net "P5E_CPU0_P1_TX_DP<14>")
	)
	(arc
		(start 358.32796 -293.038784)
		(mid 358.048196 -293.526146)
		(end 358.32796 -294.013382)
		(width 0.1143)
		(layer "In4.Cu")
		(net "P5E_CPU0_P1_TX_DP<14>")
	)
	(arc
		(start 361.435142 -375.095516)
		(mid 361.093552 -375.798123)
		(end 360.976164 -376.570494)
		(width 0.14224)
		(layer "In4.Cu")
		(net "P5E_CPU0_P1_TX_DP<14>")
	)
	(arc
		(start 357.575866 -289.490912)
		(mid 357.641486 -289.74043)
		(end 357.81107 -289.934904)
		(width 0.1143)
		(layer "In4.Cu")
		(net "P5E_CPU0_P1_TX_DP<14>")
	)
	(arc
		(start 358.649016 -384.92811)
		(mid 358.781736 -385.016854)
		(end 358.938322 -385.047998)
		(width 0.14224)
		(layer "In4.Cu")
		(net "P5E_CPU0_P1_TX_DP<14>")
	)
	(arc
		(start 358.000046 -298.306744)
		(mid 358.015354 -298.462636)
		(end 358.060752 -298.61256)
		(width 0.14224)
		(layer "In4.Cu")
		(net "P5E_CPU0_P1_TX_DP<14>")
	)
	(arc
		(start 358.530398 -383.462022)
		(mid 358.35107 -383.730405)
		(end 358.288082 -384.046984)
		(width 0.14224)
		(layer "In4.Cu")
		(net "P5E_CPU0_P1_TX_DP<14>")
	)
	(arc
		(start 358.515412 -292.72992)
		(mid 358.471299 -292.89275)
		(end 358.360218 -293.019734)
		(width 0.1143)
		(layer "In4.Cu")
		(net "P5E_CPU0_P1_TX_DP<14>")
	)
	(arc
		(start 357.573834 -289.466782)
		(mid 357.575143 -289.478822)
		(end 357.575866 -289.490912)
		(width 0.1143)
		(layer "In4.Cu")
		(net "P5E_CPU0_P1_TX_DP<14>")
	)
	(segment
		(start 357.340154 -378.39142)
		(end 357.044244 -378.68733)
		(width 0.12954)
		(layer "F.Cu")
		(net "P5E_CPU0_P1_TX_DP<13>")
	)
	(segment
		(start 357.069644 -377.41733)
		(end 357.340154 -377.68784)
		(width 0.12954)
		(layer "F.Cu")
		(net "P5E_CPU0_P1_TX_DP<13>")
	)
	(segment
		(start 357.197914 -290.019994)
		(end 356.731062 -290.285932)
		(width 0.12954)
		(layer "F.Cu")
		(net "P5E_CPU0_P1_TX_DP<13>")
	)
	(segment
		(start 357.340154 -377.68784)
		(end 357.340154 -378.39142)
		(width 0.12954)
		(layer "F.Cu")
		(net "P5E_CPU0_P1_TX_DP<13>")
	)
	(segment
		(start 370.644928 -318.741044)
		(end 371.945154 -321.228466)
		(width 0.14224)
		(layer "In4.Cu")
		(net "P5E_CPU0_P1_TX_DP<13>")
	)
	(segment
		(start 375.919746 -352.388424)
		(end 375.919746 -352.388678)
		(width 0.14224)
		(layer "In4.Cu")
		(net "P5E_CPU0_P1_TX_DP<13>")
	)
	(segment
		(start 375.868692 -352.50374)
		(end 375.868692 -352.503994)
		(width 0.14224)
		(layer "In4.Cu")
		(net "P5E_CPU0_P1_TX_DP<13>")
	)
	(segment
		(start 357.349044 -292.37051)
		(end 357.38562 -292.391846)
		(width 0.1143)
		(layer "In4.Cu")
		(net "P5E_CPU0_P1_TX_DP<13>")
	)
	(segment
		(start 376.771916 -337.950556)
		(end 376.771916 -348.634558)
		(width 0.14224)
		(layer "In4.Cu")
		(net "P5E_CPU0_P1_TX_DP<13>")
	)
	(segment
		(start 356.731062 -290.285932)
		(end 357.029004 -290.285932)
		(width 0.1143)
		(layer "In4.Cu")
		(net "P5E_CPU0_P1_TX_DP<13>")
	)
	(segment
		(start 357.41991 -291.40023)
		(end 357.388922 -291.41801)
		(width 0.1143)
		(layer "In4.Cu")
		(net "P5E_CPU0_P1_TX_DP<13>")
	)
	(segment
		(start 357.387144 -291.419026)
		(end 357.349044 -291.441378)
		(width 0.1143)
		(layer "In4.Cu")
		(net "P5E_CPU0_P1_TX_DP<13>")
	)
	(segment
		(start 357.38816 -293.03853)
		(end 357.387906 -293.03853)
		(width 0.1143)
		(layer "In4.Cu")
		(net "P5E_CPU0_P1_TX_DP<13>")
	)
	(segment
		(start 357.389938 -294.014398)
		(end 357.3907 -294.014906)
		(width 0.1143)
		(layer "In4.Cu")
		(net "P5E_CPU0_P1_TX_DP<13>")
	)
	(segment
		(start 357.387144 -292.392862)
		(end 357.38816 -292.39337)
		(width 0.1143)
		(layer "In4.Cu")
		(net "P5E_CPU0_P1_TX_DP<13>")
	)
	(segment
		(start 357.392224 -294.65651)
		(end 357.361236 -294.674036)
		(width 0.1143)
		(layer "In4.Cu")
		(net "P5E_CPU0_P1_TX_DP<13>")
	)
	(segment
		(start 357.392732 -293.03599)
		(end 357.389684 -293.037514)
		(width 0.1143)
		(layer "In4.Cu")
		(net "P5E_CPU0_P1_TX_DP<13>")
	)
	(segment
		(start 357.105712 -295.145968)
		(end 357.105712 -295.483026)
		(width 0.1143)
		(layer "In4.Cu")
		(net "P5E_CPU0_P1_TX_DP<13>")
	)
	(segment
		(start 357.389684 -293.037514)
		(end 357.38816 -293.03853)
		(width 0.1143)
		(layer "In4.Cu")
		(net "P5E_CPU0_P1_TX_DP<13>")
	)
	(segment
		(start 357.361236 -294.674036)
		(end 357.35387 -294.678608)
		(width 0.1143)
		(layer "In4.Cu")
		(net "P5E_CPU0_P1_TX_DP<13>")
	)
	(segment
		(start 357.349044 -290.750498)
		(end 357.41991 -290.791646)
		(width 0.1143)
		(layer "In4.Cu")
		(net "P5E_CPU0_P1_TX_DP<13>")
	)
	(segment
		(start 366.407954 -313.57951)
		(end 366.408208 -313.579256)
		(width 0.14224)
		(layer "In4.Cu")
		(net "P5E_CPU0_P1_TX_DP<13>")
	)
	(segment
		(start 357.38816 -291.418518)
		(end 357.387144 -291.419026)
		(width 0.1143)
		(layer "In4.Cu")
		(net "P5E_CPU0_P1_TX_DP<13>")
	)
	(segment
		(start 357.059992 -295.557194)
		(end 357.059992 -298.557188)
		(width 0.14224)
		(layer "In4.Cu")
		(net "P5E_CPU0_P1_TX_DP<13>")
	)
	(segment
		(start 357.105712 -295.483026)
		(end 357.059992 -295.528746)
		(width 0.1143)
		(layer "In4.Cu")
		(net "P5E_CPU0_P1_TX_DP<13>")
	)
	(segment
		(start 357.35387 -294.678608)
		(end 357.349044 -294.681402)
		(width 0.1143)
		(layer "In4.Cu")
		(net "P5E_CPU0_P1_TX_DP<13>")
	)
	(segment
		(start 357.387144 -294.012874)
		(end 357.38816 -294.013382)
		(width 0.1143)
		(layer "In4.Cu")
		(net "P5E_CPU0_P1_TX_DP<13>")
	)
	(segment
		(start 357.388922 -291.41801)
		(end 357.38816 -291.418518)
		(width 0.1143)
		(layer "In4.Cu")
		(net "P5E_CPU0_P1_TX_DP<13>")
	)
	(segment
		(start 357.38562 -292.391846)
		(end 357.387144 -292.392862)
		(width 0.1143)
		(layer "In4.Cu")
		(net "P5E_CPU0_P1_TX_DP<13>")
	)
	(segment
		(start 357.360474 -377.1265)
		(end 357.069644 -377.41733)
		(width 0.14224)
		(layer "In4.Cu")
		(net "P5E_CPU0_P1_TX_DP<13>")
	)
	(segment
		(start 357.059992 -295.528746)
		(end 357.059992 -295.557194)
		(width 0.1143)
		(layer "In4.Cu")
		(net "P5E_CPU0_P1_TX_DP<13>")
	)
	(segment
		(start 357.09098 -298.713652)
		(end 359.379774 -304.239422)
		(width 0.14224)
		(layer "In4.Cu")
		(net "P5E_CPU0_P1_TX_DP<13>")
	)
	(segment
		(start 376.757438 -348.760542)
		(end 375.919746 -352.388424)
		(width 0.14224)
		(layer "In4.Cu")
		(net "P5E_CPU0_P1_TX_DP<13>")
	)
	(segment
		(start 357.029004 -290.285932)
		(end 357.111808 -290.368736)
		(width 0.1143)
		(layer "In4.Cu")
		(net "P5E_CPU0_P1_TX_DP<13>")
	)
	(segment
		(start 359.379774 -304.239422)
		(end 362.171234 -308.417468)
		(width 0.14224)
		(layer "In4.Cu")
		(net "P5E_CPU0_P1_TX_DP<13>")
	)
	(segment
		(start 375.868692 -352.503994)
		(end 363.667802 -370.13134)
		(width 0.14224)
		(layer "In4.Cu")
		(net "P5E_CPU0_P1_TX_DP<13>")
	)
	(segment
		(start 357.388922 -294.01389)
		(end 357.389938 -294.014398)
		(width 0.1143)
		(layer "In4.Cu")
		(net "P5E_CPU0_P1_TX_DP<13>")
	)
	(segment
		(start 375.818146 -332.577694)
		(end 376.760486 -337.824826)
		(width 0.14224)
		(layer "In4.Cu")
		(net "P5E_CPU0_P1_TX_DP<13>")
	)
	(segment
		(start 371.945154 -321.228466)
		(end 375.786396 -332.455266)
		(width 0.14224)
		(layer "In4.Cu")
		(net "P5E_CPU0_P1_TX_DP<13>")
	)
	(segment
		(start 357.38816 -294.013382)
		(end 357.388922 -294.01389)
		(width 0.1143)
		(layer "In4.Cu")
		(net "P5E_CPU0_P1_TX_DP<13>")
	)
	(segment
		(start 362.171234 -308.417468)
		(end 366.407954 -313.57951)
		(width 0.14224)
		(layer "In4.Cu")
		(net "P5E_CPU0_P1_TX_DP<13>")
	)
	(segment
		(start 366.408208 -313.579256)
		(end 370.644928 -318.741044)
		(width 0.14224)
		(layer "In4.Cu")
		(net "P5E_CPU0_P1_TX_DP<13>")
	)
	(segment
		(start 363.667802 -370.13134)
		(end 357.480362 -376.31878)
		(width 0.14224)
		(layer "In4.Cu")
		(net "P5E_CPU0_P1_TX_DP<13>")
	)
	(segment
		(start 357.41991 -290.791646)
		(end 357.439722 -290.80587)
		(width 0.1143)
		(layer "In4.Cu")
		(net "P5E_CPU0_P1_TX_DP<13>")
	)
	(segment
		(start 357.439722 -291.386006)
		(end 357.41991 -291.40023)
		(width 0.1143)
		(layer "In4.Cu")
		(net "P5E_CPU0_P1_TX_DP<13>")
	)
	(segment
		(start 357.360474 -376.60834)
		(end 357.360474 -377.1265)
		(width 0.14224)
		(layer "In4.Cu")
		(net "P5E_CPU0_P1_TX_DP<13>")
	)
	(segment
		(start 357.38816 -292.39337)
		(end 357.388922 -292.393878)
		(width 0.1143)
		(layer "In4.Cu")
		(net "P5E_CPU0_P1_TX_DP<13>")
	)
	(arc
		(start 375.786396 -332.455266)
		(mid 375.804599 -332.515876)
		(end 375.818146 -332.577694)
		(width 0.14224)
		(layer "In4.Cu")
		(net "P5E_CPU0_P1_TX_DP<13>")
	)
	(arc
		(start 357.349044 -291.441378)
		(mid 357.105717 -291.905944)
		(end 357.349044 -292.37051)
		(width 0.1143)
		(layer "In4.Cu")
		(net "P5E_CPU0_P1_TX_DP<13>")
	)
	(arc
		(start 357.186738 -294.85463)
		(mid 357.126374 -294.994779)
		(end 357.105712 -295.145968)
		(width 0.1143)
		(layer "In4.Cu")
		(net "P5E_CPU0_P1_TX_DP<13>")
	)
	(arc
		(start 357.439722 -290.80587)
		(mid 357.588436 -291.095938)
		(end 357.439722 -291.386006)
		(width 0.1143)
		(layer "In4.Cu")
		(net "P5E_CPU0_P1_TX_DP<13>")
	)
	(arc
		(start 357.059992 -298.557188)
		(mid 357.067785 -298.636946)
		(end 357.09098 -298.713652)
		(width 0.14224)
		(layer "In4.Cu")
		(net "P5E_CPU0_P1_TX_DP<13>")
	)
	(arc
		(start 357.115618 -290.391596)
		(mid 357.197051 -290.593994)
		(end 357.349044 -290.750498)
		(width 0.1143)
		(layer "In4.Cu")
		(net "P5E_CPU0_P1_TX_DP<13>")
	)
	(arc
		(start 375.919746 -352.388678)
		(mid 375.899687 -352.448636)
		(end 375.868692 -352.50374)
		(width 0.14224)
		(layer "In4.Cu")
		(net "P5E_CPU0_P1_TX_DP<13>")
	)
	(arc
		(start 376.760486 -337.824826)
		(mid 376.768987 -337.887437)
		(end 376.771916 -337.950556)
		(width 0.14224)
		(layer "In4.Cu")
		(net "P5E_CPU0_P1_TX_DP<13>")
	)
	(arc
		(start 357.388922 -292.393878)
		(mid 357.396079 -292.397992)
		(end 357.403146 -292.40226)
		(width 0.1143)
		(layer "In4.Cu")
		(net "P5E_CPU0_P1_TX_DP<13>")
	)
	(arc
		(start 357.480362 -376.31878)
		(mid 357.391647 -376.451645)
		(end 357.360474 -376.60834)
		(width 0.14224)
		(layer "In4.Cu")
		(net "P5E_CPU0_P1_TX_DP<13>")
	)
	(arc
		(start 376.771916 -348.634558)
		(mid 376.768259 -348.697962)
		(end 376.757438 -348.760542)
		(width 0.14224)
		(layer "In4.Cu")
		(net "P5E_CPU0_P1_TX_DP<13>")
	)
	(arc
		(start 357.111808 -290.368736)
		(mid 357.113596 -290.380185)
		(end 357.115618 -290.391596)
		(width 0.1143)
		(layer "In4.Cu")
		(net "P5E_CPU0_P1_TX_DP<13>")
	)
	(arc
		(start 357.403146 -292.40226)
		(mid 357.576466 -292.722048)
		(end 357.392732 -293.03599)
		(width 0.1143)
		(layer "In4.Cu")
		(net "P5E_CPU0_P1_TX_DP<13>")
	)
	(arc
		(start 357.349044 -294.681402)
		(mid 357.258705 -294.759407)
		(end 357.186738 -294.85463)
		(width 0.1143)
		(layer "In4.Cu")
		(net "P5E_CPU0_P1_TX_DP<13>")
	)
	(arc
		(start 357.3907 -294.014906)
		(mid 357.575744 -294.335302)
		(end 357.392224 -294.65651)
		(width 0.1143)
		(layer "In4.Cu")
		(net "P5E_CPU0_P1_TX_DP<13>")
	)
	(arc
		(start 357.387906 -293.03853)
		(mid 357.108268 -293.525499)
		(end 357.387144 -294.012874)
		(width 0.1143)
		(layer "In4.Cu")
		(net "P5E_CPU0_P1_TX_DP<13>")
	)
	(segment
		(start 353.640644 -378.68733)
		(end 353.936554 -378.39142)
		(width 0.12954)
		(layer "F.Cu")
		(net "P5E_CPU0_P1_TX_DP<12>")
	)
	(segment
		(start 354.847906 -287.59023)
		(end 354.381054 -287.856168)
		(width 0.12954)
		(layer "F.Cu")
		(net "P5E_CPU0_P1_TX_DP<12>")
	)
	(segment
		(start 353.936554 -377.68784)
		(end 353.666044 -377.41733)
		(width 0.12954)
		(layer "F.Cu")
		(net "P5E_CPU0_P1_TX_DP<12>")
	)
	(segment
		(start 353.936554 -378.39142)
		(end 353.936554 -377.68784)
		(width 0.12954)
		(layer "F.Cu")
		(net "P5E_CPU0_P1_TX_DP<12>")
	)
	(segment
		(start 356.41661 -290.75507)
		(end 356.448106 -290.773358)
		(width 0.1143)
		(layer "In4.Cu")
		(net "P5E_CPU0_P1_TX_DP<12>")
	)
	(segment
		(start 356.438962 -291.423852)
		(end 356.436422 -291.425122)
		(width 0.1143)
		(layer "In4.Cu")
		(net "P5E_CPU0_P1_TX_DP<12>")
	)
	(segment
		(start 356.448106 -294.013382)
		(end 356.448868 -294.01389)
		(width 0.1143)
		(layer "In4.Cu")
		(net "P5E_CPU0_P1_TX_DP<12>")
	)
	(segment
		(start 363.592618 -368.489484)
		(end 354.10648 -376.276362)
		(width 0.14224)
		(layer "In4.Cu")
		(net "P5E_CPU0_P1_TX_DP<12>")
	)
	(segment
		(start 356.435152 -291.425884)
		(end 356.43439 -291.426392)
		(width 0.1143)
		(layer "In4.Cu")
		(net "P5E_CPU0_P1_TX_DP<12>")
	)
	(segment
		(start 356.438962 -294.663876)
		(end 356.436422 -294.665146)
		(width 0.1143)
		(layer "In4.Cu")
		(net "P5E_CPU0_P1_TX_DP<12>")
	)
	(segment
		(start 356.430072 -294.668956)
		(end 356.42931 -294.669464)
		(width 0.1143)
		(layer "In4.Cu")
		(net "P5E_CPU0_P1_TX_DP<12>")
	)
	(segment
		(start 356.45471 -292.39718)
		(end 356.45598 -292.397942)
		(width 0.1143)
		(layer "In4.Cu")
		(net "P5E_CPU0_P1_TX_DP<12>")
	)
	(segment
		(start 356.452424 -290.775898)
		(end 356.453948 -290.77666)
		(width 0.1143)
		(layer "In4.Cu")
		(net "P5E_CPU0_P1_TX_DP<12>")
	)
	(segment
		(start 356.452424 -292.39591)
		(end 356.453948 -292.396672)
		(width 0.1143)
		(layer "In4.Cu")
		(net "P5E_CPU0_P1_TX_DP<12>")
	)
	(segment
		(start 356.44455 -293.040562)
		(end 356.44328 -293.041324)
		(width 0.1143)
		(layer "In4.Cu")
		(net "P5E_CPU0_P1_TX_DP<12>")
	)
	(segment
		(start 356.165658 -295.483026)
		(end 356.119938 -295.528746)
		(width 0.1143)
		(layer "In4.Cu")
		(net "P5E_CPU0_P1_TX_DP<12>")
	)
	(segment
		(start 356.42931 -294.669464)
		(end 356.427024 -294.670734)
		(width 0.1143)
		(layer "In4.Cu")
		(net "P5E_CPU0_P1_TX_DP<12>")
	)
	(segment
		(start 356.453948 -290.77666)
		(end 356.45471 -290.777168)
		(width 0.1143)
		(layer "In4.Cu")
		(net "P5E_CPU0_P1_TX_DP<12>")
	)
	(segment
		(start 356.451662 -293.036498)
		(end 356.448868 -293.038022)
		(width 0.1143)
		(layer "In4.Cu")
		(net "P5E_CPU0_P1_TX_DP<12>")
	)
	(segment
		(start 356.436422 -293.045134)
		(end 356.435152 -293.045896)
		(width 0.1143)
		(layer "In4.Cu")
		(net "P5E_CPU0_P1_TX_DP<12>")
	)
	(segment
		(start 356.440486 -291.422836)
		(end 356.438962 -291.423852)
		(width 0.1143)
		(layer "In4.Cu")
		(net "P5E_CPU0_P1_TX_DP<12>")
	)
	(segment
		(start 356.448868 -293.038022)
		(end 356.448106 -293.03853)
		(width 0.1143)
		(layer "In4.Cu")
		(net "P5E_CPU0_P1_TX_DP<12>")
	)
	(segment
		(start 374.953022 -333.039466)
		(end 375.795032 -337.72856)
		(width 0.14224)
		(layer "In4.Cu")
		(net "P5E_CPU0_P1_TX_DP<12>")
	)
	(segment
		(start 356.430072 -293.048944)
		(end 356.42931 -293.049452)
		(width 0.1143)
		(layer "In4.Cu")
		(net "P5E_CPU0_P1_TX_DP<12>")
	)
	(segment
		(start 355.974396 -289.961066)
		(end 355.978968 -289.96386)
		(width 0.1143)
		(layer "In4.Cu")
		(net "P5E_CPU0_P1_TX_DP<12>")
	)
	(segment
		(start 356.45852 -292.399212)
		(end 356.479856 -292.411658)
		(width 0.1143)
		(layer "In4.Cu")
		(net "P5E_CPU0_P1_TX_DP<12>")
	)
	(segment
		(start 356.427024 -293.050722)
		(end 356.423722 -293.052754)
		(width 0.1143)
		(layer "In4.Cu")
		(net "P5E_CPU0_P1_TX_DP<12>")
	)
	(segment
		(start 356.427024 -294.670734)
		(end 356.423722 -294.672766)
		(width 0.1143)
		(layer "In4.Cu")
		(net "P5E_CPU0_P1_TX_DP<12>")
	)
	(segment
		(start 356.43439 -291.426392)
		(end 356.430072 -291.428932)
		(width 0.1143)
		(layer "In4.Cu")
		(net "P5E_CPU0_P1_TX_DP<12>")
	)
	(segment
		(start 356.448106 -291.418518)
		(end 356.44709 -291.419026)
		(width 0.1143)
		(layer "In4.Cu")
		(net "P5E_CPU0_P1_TX_DP<12>")
	)
	(segment
		(start 374.969532 -352.16465)
		(end 363.592618 -368.489484)
		(width 0.14224)
		(layer "In4.Cu")
		(net "P5E_CPU0_P1_TX_DP<12>")
	)
	(segment
		(start 356.445566 -291.420042)
		(end 356.44455 -291.42055)
		(width 0.1143)
		(layer "In4.Cu")
		(net "P5E_CPU0_P1_TX_DP<12>")
	)
	(segment
		(start 356.445566 -293.040054)
		(end 356.44455 -293.040562)
		(width 0.1143)
		(layer "In4.Cu")
		(net "P5E_CPU0_P1_TX_DP<12>")
	)
	(segment
		(start 356.40899 -293.990522)
		(end 356.415848 -293.994586)
		(width 0.1143)
		(layer "In4.Cu")
		(net "P5E_CPU0_P1_TX_DP<12>")
	)
	(segment
		(start 356.40899 -290.750498)
		(end 356.415848 -290.754562)
		(width 0.1143)
		(layer "In4.Cu")
		(net "P5E_CPU0_P1_TX_DP<12>")
	)
	(segment
		(start 356.44455 -294.660574)
		(end 356.44328 -294.661336)
		(width 0.1143)
		(layer "In4.Cu")
		(net "P5E_CPU0_P1_TX_DP<12>")
	)
	(segment
		(start 356.442264 -291.42182)
		(end 356.440486 -291.422836)
		(width 0.1143)
		(layer "In4.Cu")
		(net "P5E_CPU0_P1_TX_DP<12>")
	)
	(segment
		(start 356.41661 -292.375082)
		(end 356.448106 -292.39337)
		(width 0.1143)
		(layer "In4.Cu")
		(net "P5E_CPU0_P1_TX_DP<12>")
	)
	(segment
		(start 356.435152 -294.665908)
		(end 356.43439 -294.666416)
		(width 0.1143)
		(layer "In4.Cu")
		(net "P5E_CPU0_P1_TX_DP<12>")
	)
	(segment
		(start 375.792492 -348.632526)
		(end 375.020332 -352.049588)
		(width 0.14224)
		(layer "In4.Cu")
		(net "P5E_CPU0_P1_TX_DP<12>")
	)
	(segment
		(start 356.45598 -292.397942)
		(end 356.45852 -292.399212)
		(width 0.1143)
		(layer "In4.Cu")
		(net "P5E_CPU0_P1_TX_DP<12>")
	)
	(segment
		(start 356.453948 -292.396672)
		(end 356.45471 -292.39718)
		(width 0.1143)
		(layer "In4.Cu")
		(net "P5E_CPU0_P1_TX_DP<12>")
	)
	(segment
		(start 356.415848 -290.754562)
		(end 356.41661 -290.75507)
		(width 0.1143)
		(layer "In4.Cu")
		(net "P5E_CPU0_P1_TX_DP<12>")
	)
	(segment
		(start 356.435152 -293.045896)
		(end 356.43439 -293.046404)
		(width 0.1143)
		(layer "In4.Cu")
		(net "P5E_CPU0_P1_TX_DP<12>")
	)
	(segment
		(start 356.44709 -293.039038)
		(end 356.445566 -293.040054)
		(width 0.1143)
		(layer "In4.Cu")
		(net "P5E_CPU0_P1_TX_DP<12>")
	)
	(segment
		(start 356.119938 -295.528746)
		(end 356.119938 -295.557194)
		(width 0.1143)
		(layer "In4.Cu")
		(net "P5E_CPU0_P1_TX_DP<12>")
	)
	(segment
		(start 356.422198 -291.433504)
		(end 356.40899 -291.441378)
		(width 0.1143)
		(layer "In4.Cu")
		(net "P5E_CPU0_P1_TX_DP<12>")
	)
	(segment
		(start 356.45852 -294.019224)
		(end 356.479856 -294.03167)
		(width 0.1143)
		(layer "In4.Cu")
		(net "P5E_CPU0_P1_TX_DP<12>")
	)
	(segment
		(start 358.56799 -304.715926)
		(end 361.391708 -308.941724)
		(width 0.14224)
		(layer "In4.Cu")
		(net "P5E_CPU0_P1_TX_DP<12>")
	)
	(segment
		(start 356.427024 -291.43071)
		(end 356.423722 -291.432742)
		(width 0.1143)
		(layer "In4.Cu")
		(net "P5E_CPU0_P1_TX_DP<12>")
	)
	(segment
		(start 369.793266 -319.17767)
		(end 371.178582 -321.868038)
		(width 0.14224)
		(layer "In4.Cu")
		(net "P5E_CPU0_P1_TX_DP<12>")
	)
	(segment
		(start 356.453948 -294.016684)
		(end 356.45471 -294.017192)
		(width 0.1143)
		(layer "In4.Cu")
		(net "P5E_CPU0_P1_TX_DP<12>")
	)
	(segment
		(start 356.448868 -294.01389)
		(end 356.451662 -294.015414)
		(width 0.1143)
		(layer "In4.Cu")
		(net "P5E_CPU0_P1_TX_DP<12>")
	)
	(segment
		(start 356.423722 -293.052754)
		(end 356.422198 -293.053516)
		(width 0.1143)
		(layer "In4.Cu")
		(net "P5E_CPU0_P1_TX_DP<12>")
	)
	(segment
		(start 355.47173 -289.132264)
		(end 355.508052 -289.153346)
		(width 0.1143)
		(layer "In4.Cu")
		(net "P5E_CPU0_P1_TX_DP<12>")
	)
	(segment
		(start 356.42931 -291.42944)
		(end 356.427024 -291.43071)
		(width 0.1143)
		(layer "In4.Cu")
		(net "P5E_CPU0_P1_TX_DP<12>")
	)
	(segment
		(start 356.45852 -290.7792)
		(end 356.479856 -290.791646)
		(width 0.1143)
		(layer "In4.Cu")
		(net "P5E_CPU0_P1_TX_DP<12>")
	)
	(segment
		(start 354.999036 -288.320734)
		(end 355.038152 -288.343594)
		(width 0.1143)
		(layer "In4.Cu")
		(net "P5E_CPU0_P1_TX_DP<12>")
	)
	(segment
		(start 356.448106 -292.39337)
		(end 356.448868 -292.393878)
		(width 0.1143)
		(layer "In4.Cu")
		(net "P5E_CPU0_P1_TX_DP<12>")
	)
	(segment
		(start 355.508052 -289.153346)
		(end 355.510084 -289.154616)
		(width 0.1143)
		(layer "In4.Cu")
		(net "P5E_CPU0_P1_TX_DP<12>")
	)
	(segment
		(start 353.956874 -376.592592)
		(end 353.956874 -377.1265)
		(width 0.14224)
		(layer "In4.Cu")
		(net "P5E_CPU0_P1_TX_DP<12>")
	)
	(segment
		(start 356.415848 -293.994586)
		(end 356.41661 -293.995094)
		(width 0.1143)
		(layer "In4.Cu")
		(net "P5E_CPU0_P1_TX_DP<12>")
	)
	(segment
		(start 356.45471 -290.777168)
		(end 356.45598 -290.77793)
		(width 0.1143)
		(layer "In4.Cu")
		(net "P5E_CPU0_P1_TX_DP<12>")
	)
	(segment
		(start 356.438962 -293.043864)
		(end 356.436422 -293.045134)
		(width 0.1143)
		(layer "In4.Cu")
		(net "P5E_CPU0_P1_TX_DP<12>")
	)
	(segment
		(start 354.381054 -287.856168)
		(end 354.678996 -287.856168)
		(width 0.1143)
		(layer "In4.Cu")
		(net "P5E_CPU0_P1_TX_DP<12>")
	)
	(segment
		(start 356.479856 -291.40023)
		(end 356.452424 -291.415978)
		(width 0.1143)
		(layer "In4.Cu")
		(net "P5E_CPU0_P1_TX_DP<12>")
	)
	(segment
		(start 356.440486 -293.042848)
		(end 356.438962 -293.043864)
		(width 0.1143)
		(layer "In4.Cu")
		(net "P5E_CPU0_P1_TX_DP<12>")
	)
	(segment
		(start 356.422198 -293.053516)
		(end 356.40899 -293.06139)
		(width 0.1143)
		(layer "In4.Cu")
		(net "P5E_CPU0_P1_TX_DP<12>")
	)
	(segment
		(start 356.44328 -293.041324)
		(end 356.442264 -293.041832)
		(width 0.1143)
		(layer "In4.Cu")
		(net "P5E_CPU0_P1_TX_DP<12>")
	)
	(segment
		(start 356.451662 -291.416486)
		(end 356.448868 -291.41801)
		(width 0.1143)
		(layer "In4.Cu")
		(net "P5E_CPU0_P1_TX_DP<12>")
	)
	(segment
		(start 371.178582 -321.868038)
		(end 374.921526 -332.917038)
		(width 0.14224)
		(layer "In4.Cu")
		(net "P5E_CPU0_P1_TX_DP<12>")
	)
	(segment
		(start 356.40899 -292.37051)
		(end 356.415848 -292.374574)
		(width 0.1143)
		(layer "In4.Cu")
		(net "P5E_CPU0_P1_TX_DP<12>")
	)
	(segment
		(start 356.451662 -294.015414)
		(end 356.452424 -294.015922)
		(width 0.1143)
		(layer "In4.Cu")
		(net "P5E_CPU0_P1_TX_DP<12>")
	)
	(segment
		(start 356.44709 -294.65905)
		(end 356.445566 -294.660066)
		(width 0.1143)
		(layer "In4.Cu")
		(net "P5E_CPU0_P1_TX_DP<12>")
	)
	(segment
		(start 355.978968 -289.96386)
		(end 356.008686 -289.981132)
		(width 0.1143)
		(layer "In4.Cu")
		(net "P5E_CPU0_P1_TX_DP<12>")
	)
	(segment
		(start 361.391708 -308.941724)
		(end 365.59236 -314.059824)
		(width 0.14224)
		(layer "In4.Cu")
		(net "P5E_CPU0_P1_TX_DP<12>")
	)
	(segment
		(start 356.423722 -291.432742)
		(end 356.422198 -291.433504)
		(width 0.1143)
		(layer "In4.Cu")
		(net "P5E_CPU0_P1_TX_DP<12>")
	)
	(segment
		(start 356.452424 -293.03599)
		(end 356.451662 -293.036498)
		(width 0.1143)
		(layer "In4.Cu")
		(net "P5E_CPU0_P1_TX_DP<12>")
	)
	(segment
		(start 356.423722 -294.672766)
		(end 356.422198 -294.673528)
		(width 0.1143)
		(layer "In4.Cu")
		(net "P5E_CPU0_P1_TX_DP<12>")
	)
	(segment
		(start 356.43439 -293.046404)
		(end 356.430072 -293.048944)
		(width 0.1143)
		(layer "In4.Cu")
		(net "P5E_CPU0_P1_TX_DP<12>")
	)
	(segment
		(start 356.45598 -294.017954)
		(end 356.45852 -294.019224)
		(width 0.1143)
		(layer "In4.Cu")
		(net "P5E_CPU0_P1_TX_DP<12>")
	)
	(segment
		(start 356.415848 -292.374574)
		(end 356.41661 -292.375082)
		(width 0.1143)
		(layer "In4.Cu")
		(net "P5E_CPU0_P1_TX_DP<12>")
	)
	(segment
		(start 356.451662 -292.395402)
		(end 356.452424 -292.39591)
		(width 0.1143)
		(layer "In4.Cu")
		(net "P5E_CPU0_P1_TX_DP<12>")
	)
	(segment
		(start 375.806462 -337.85429)
		(end 375.806462 -348.506796)
		(width 0.14224)
		(layer "In4.Cu")
		(net "P5E_CPU0_P1_TX_DP<12>")
	)
	(segment
		(start 356.448868 -292.393878)
		(end 356.451662 -292.395402)
		(width 0.1143)
		(layer "In4.Cu")
		(net "P5E_CPU0_P1_TX_DP<12>")
	)
	(segment
		(start 356.44455 -291.42055)
		(end 356.44328 -291.421312)
		(width 0.1143)
		(layer "In4.Cu")
		(net "P5E_CPU0_P1_TX_DP<12>")
	)
	(segment
		(start 356.436422 -291.425122)
		(end 356.435152 -291.425884)
		(width 0.1143)
		(layer "In4.Cu")
		(net "P5E_CPU0_P1_TX_DP<12>")
	)
	(segment
		(start 356.442264 -294.661844)
		(end 356.440486 -294.66286)
		(width 0.1143)
		(layer "In4.Cu")
		(net "P5E_CPU0_P1_TX_DP<12>")
	)
	(segment
		(start 356.451662 -294.65651)
		(end 356.448868 -294.658034)
		(width 0.1143)
		(layer "In4.Cu")
		(net "P5E_CPU0_P1_TX_DP<12>")
	)
	(segment
		(start 356.436422 -294.665146)
		(end 356.435152 -294.665908)
		(width 0.1143)
		(layer "In4.Cu")
		(net "P5E_CPU0_P1_TX_DP<12>")
	)
	(segment
		(start 356.44328 -291.421312)
		(end 356.442264 -291.42182)
		(width 0.1143)
		(layer "In4.Cu")
		(net "P5E_CPU0_P1_TX_DP<12>")
	)
	(segment
		(start 356.440486 -294.66286)
		(end 356.438962 -294.663876)
		(width 0.1143)
		(layer "In4.Cu")
		(net "P5E_CPU0_P1_TX_DP<12>")
	)
	(segment
		(start 356.165658 -295.145968)
		(end 356.165658 -295.483026)
		(width 0.1143)
		(layer "In4.Cu")
		(net "P5E_CPU0_P1_TX_DP<12>")
	)
	(segment
		(start 356.452424 -294.656002)
		(end 356.451662 -294.65651)
		(width 0.1143)
		(layer "In4.Cu")
		(net "P5E_CPU0_P1_TX_DP<12>")
	)
	(segment
		(start 355.038152 -288.343594)
		(end 355.07168 -288.363152)
		(width 0.1143)
		(layer "In4.Cu")
		(net "P5E_CPU0_P1_TX_DP<12>")
	)
	(segment
		(start 356.119938 -295.557194)
		(end 356.119938 -298.72432)
		(width 0.14224)
		(layer "In4.Cu")
		(net "P5E_CPU0_P1_TX_DP<12>")
	)
	(segment
		(start 356.422198 -294.673528)
		(end 356.40899 -294.681402)
		(width 0.1143)
		(layer "In4.Cu")
		(net "P5E_CPU0_P1_TX_DP<12>")
	)
	(segment
		(start 356.45471 -294.017192)
		(end 356.45598 -294.017954)
		(width 0.1143)
		(layer "In4.Cu")
		(net "P5E_CPU0_P1_TX_DP<12>")
	)
	(segment
		(start 356.448106 -290.773358)
		(end 356.448868 -290.773866)
		(width 0.1143)
		(layer "In4.Cu")
		(net "P5E_CPU0_P1_TX_DP<12>")
	)
	(segment
		(start 356.448106 -294.658542)
		(end 356.44709 -294.65905)
		(width 0.1143)
		(layer "In4.Cu")
		(net "P5E_CPU0_P1_TX_DP<12>")
	)
	(segment
		(start 356.448868 -294.658034)
		(end 356.448106 -294.658542)
		(width 0.1143)
		(layer "In4.Cu")
		(net "P5E_CPU0_P1_TX_DP<12>")
	)
	(segment
		(start 365.592614 -314.059824)
		(end 369.793266 -319.17767)
		(width 0.14224)
		(layer "In4.Cu")
		(net "P5E_CPU0_P1_TX_DP<12>")
	)
	(segment
		(start 356.45598 -290.77793)
		(end 356.45852 -290.7792)
		(width 0.1143)
		(layer "In4.Cu")
		(net "P5E_CPU0_P1_TX_DP<12>")
	)
	(segment
		(start 356.479856 -294.640254)
		(end 356.452424 -294.656002)
		(width 0.1143)
		(layer "In4.Cu")
		(net "P5E_CPU0_P1_TX_DP<12>")
	)
	(segment
		(start 354.678996 -287.856168)
		(end 354.7618 -287.938972)
		(width 0.1143)
		(layer "In4.Cu")
		(net "P5E_CPU0_P1_TX_DP<12>")
	)
	(segment
		(start 356.44709 -291.419026)
		(end 356.445566 -291.420042)
		(width 0.1143)
		(layer "In4.Cu")
		(net "P5E_CPU0_P1_TX_DP<12>")
	)
	(segment
		(start 356.150926 -298.880784)
		(end 358.56799 -304.715926)
		(width 0.14224)
		(layer "In4.Cu")
		(net "P5E_CPU0_P1_TX_DP<12>")
	)
	(segment
		(start 356.442264 -293.041832)
		(end 356.440486 -293.042848)
		(width 0.1143)
		(layer "In4.Cu")
		(net "P5E_CPU0_P1_TX_DP<12>")
	)
	(segment
		(start 356.448868 -290.773866)
		(end 356.451662 -290.77539)
		(width 0.1143)
		(layer "In4.Cu")
		(net "P5E_CPU0_P1_TX_DP<12>")
	)
	(segment
		(start 356.41661 -293.995094)
		(end 356.448106 -294.013382)
		(width 0.1143)
		(layer "In4.Cu")
		(net "P5E_CPU0_P1_TX_DP<12>")
	)
	(segment
		(start 356.445566 -294.660066)
		(end 356.44455 -294.660574)
		(width 0.1143)
		(layer "In4.Cu")
		(net "P5E_CPU0_P1_TX_DP<12>")
	)
	(segment
		(start 356.448868 -291.41801)
		(end 356.448106 -291.418518)
		(width 0.1143)
		(layer "In4.Cu")
		(net "P5E_CPU0_P1_TX_DP<12>")
	)
	(segment
		(start 356.448106 -293.03853)
		(end 356.44709 -293.039038)
		(width 0.1143)
		(layer "In4.Cu")
		(net "P5E_CPU0_P1_TX_DP<12>")
	)
	(segment
		(start 356.430072 -291.428932)
		(end 356.42931 -291.42944)
		(width 0.1143)
		(layer "In4.Cu")
		(net "P5E_CPU0_P1_TX_DP<12>")
	)
	(segment
		(start 356.43439 -294.666416)
		(end 356.430072 -294.668956)
		(width 0.1143)
		(layer "In4.Cu")
		(net "P5E_CPU0_P1_TX_DP<12>")
	)
	(segment
		(start 356.42931 -293.049452)
		(end 356.427024 -293.050722)
		(width 0.1143)
		(layer "In4.Cu")
		(net "P5E_CPU0_P1_TX_DP<12>")
	)
	(segment
		(start 365.59236 -314.059824)
		(end 365.592614 -314.059824)
		(width 0.14224)
		(layer "In4.Cu")
		(net "P5E_CPU0_P1_TX_DP<12>")
	)
	(segment
		(start 353.956874 -377.1265)
		(end 353.666044 -377.41733)
		(width 0.14224)
		(layer "In4.Cu")
		(net "P5E_CPU0_P1_TX_DP<12>")
	)
	(segment
		(start 356.44328 -294.661336)
		(end 356.442264 -294.661844)
		(width 0.1143)
		(layer "In4.Cu")
		(net "P5E_CPU0_P1_TX_DP<12>")
	)
	(segment
		(start 356.452424 -291.415978)
		(end 356.451662 -291.416486)
		(width 0.1143)
		(layer "In4.Cu")
		(net "P5E_CPU0_P1_TX_DP<12>")
	)
	(segment
		(start 356.479856 -293.020242)
		(end 356.452424 -293.03599)
		(width 0.1143)
		(layer "In4.Cu")
		(net "P5E_CPU0_P1_TX_DP<12>")
	)
	(segment
		(start 356.451662 -290.77539)
		(end 356.452424 -290.775898)
		(width 0.1143)
		(layer "In4.Cu")
		(net "P5E_CPU0_P1_TX_DP<12>")
	)
	(segment
		(start 356.452424 -294.015922)
		(end 356.453948 -294.016684)
		(width 0.1143)
		(layer "In4.Cu")
		(net "P5E_CPU0_P1_TX_DP<12>")
	)
	(arc
		(start 356.479856 -294.03167)
		(mid 356.635784 -294.335962)
		(end 356.479856 -294.640254)
		(width 0.1143)
		(layer "In4.Cu")
		(net "P5E_CPU0_P1_TX_DP<12>")
	)
	(arc
		(start 374.921526 -332.917038)
		(mid 374.939563 -332.977664)
		(end 374.953022 -333.039466)
		(width 0.14224)
		(layer "In4.Cu")
		(net "P5E_CPU0_P1_TX_DP<12>")
	)
	(arc
		(start 375.806462 -348.506796)
		(mid 375.802968 -348.570048)
		(end 375.792492 -348.632526)
		(width 0.14224)
		(layer "In4.Cu")
		(net "P5E_CPU0_P1_TX_DP<12>")
	)
	(arc
		(start 356.119938 -298.72432)
		(mid 356.127731 -298.804078)
		(end 356.150926 -298.880784)
		(width 0.14224)
		(layer "In4.Cu")
		(net "P5E_CPU0_P1_TX_DP<12>")
	)
	(arc
		(start 356.40899 -291.441378)
		(mid 356.165663 -291.905944)
		(end 356.40899 -292.37051)
		(width 0.1143)
		(layer "In4.Cu")
		(net "P5E_CPU0_P1_TX_DP<12>")
	)
	(arc
		(start 355.225858 -288.66592)
		(mid 355.291094 -288.929511)
		(end 355.47173 -289.132264)
		(width 0.1143)
		(layer "In4.Cu")
		(net "P5E_CPU0_P1_TX_DP<12>")
	)
	(arc
		(start 356.40899 -293.06139)
		(mid 356.165663 -293.525956)
		(end 356.40899 -293.990522)
		(width 0.1143)
		(layer "In4.Cu")
		(net "P5E_CPU0_P1_TX_DP<12>")
	)
	(arc
		(start 356.265226 -294.82542)
		(mid 356.191112 -294.978134)
		(end 356.165658 -295.145968)
		(width 0.1143)
		(layer "In4.Cu")
		(net "P5E_CPU0_P1_TX_DP<12>")
	)
	(arc
		(start 354.7618 -287.938972)
		(mid 354.763588 -287.950421)
		(end 354.76561 -287.961832)
		(width 0.1143)
		(layer "In4.Cu")
		(net "P5E_CPU0_P1_TX_DP<12>")
	)
	(arc
		(start 356.40899 -294.681402)
		(mid 356.330567 -294.746883)
		(end 356.265226 -294.82542)
		(width 0.1143)
		(layer "In4.Cu")
		(net "P5E_CPU0_P1_TX_DP<12>")
	)
	(arc
		(start 354.76561 -287.961832)
		(mid 354.847043 -288.16423)
		(end 354.999036 -288.320734)
		(width 0.1143)
		(layer "In4.Cu")
		(net "P5E_CPU0_P1_TX_DP<12>")
	)
	(arc
		(start 356.008686 -289.981132)
		(mid 356.124113 -290.114508)
		(end 356.165658 -290.285932)
		(width 0.1143)
		(layer "In4.Cu")
		(net "P5E_CPU0_P1_TX_DP<12>")
	)
	(arc
		(start 356.479856 -292.411658)
		(mid 356.635784 -292.71595)
		(end 356.479856 -293.020242)
		(width 0.1143)
		(layer "In4.Cu")
		(net "P5E_CPU0_P1_TX_DP<12>")
	)
	(arc
		(start 356.165658 -290.285932)
		(mid 356.230173 -290.548151)
		(end 356.40899 -290.750498)
		(width 0.1143)
		(layer "In4.Cu")
		(net "P5E_CPU0_P1_TX_DP<12>")
	)
	(arc
		(start 354.10648 -376.276362)
		(mid 353.996142 -376.417669)
		(end 353.956874 -376.592592)
		(width 0.14224)
		(layer "In4.Cu")
		(net "P5E_CPU0_P1_TX_DP<12>")
	)
	(arc
		(start 355.510084 -289.154616)
		(mid 355.64678 -289.290972)
		(end 355.696774 -289.47745)
		(width 0.1143)
		(layer "In4.Cu")
		(net "P5E_CPU0_P1_TX_DP<12>")
	)
	(arc
		(start 356.479856 -290.791646)
		(mid 356.635784 -291.095938)
		(end 356.479856 -291.40023)
		(width 0.1143)
		(layer "In4.Cu")
		(net "P5E_CPU0_P1_TX_DP<12>")
	)
	(arc
		(start 355.07168 -288.363152)
		(mid 355.185087 -288.496041)
		(end 355.225858 -288.66592)
		(width 0.1143)
		(layer "In4.Cu")
		(net "P5E_CPU0_P1_TX_DP<12>")
	)
	(arc
		(start 375.795032 -337.72856)
		(mid 375.80353 -337.791172)
		(end 375.806462 -337.85429)
		(width 0.14224)
		(layer "In4.Cu")
		(net "P5E_CPU0_P1_TX_DP<12>")
	)
	(arc
		(start 355.696774 -289.47745)
		(mid 355.771111 -289.756272)
		(end 355.974396 -289.961066)
		(width 0.1143)
		(layer "In4.Cu")
		(net "P5E_CPU0_P1_TX_DP<12>")
	)
	(arc
		(start 375.020332 -352.049588)
		(mid 375.000496 -352.109574)
		(end 374.969532 -352.16465)
		(width 0.14224)
		(layer "In4.Cu")
		(net "P5E_CPU0_P1_TX_DP<12>")
	)
	(segment
		(start 351.938844 -381.15113)
		(end 352.234754 -380.85522)
		(width 0.12954)
		(layer "F.Cu")
		(net "P5E_CPU0_P1_TX_DP<11>")
	)
	(segment
		(start 352.234754 -380.15164)
		(end 351.964244 -379.88113)
		(width 0.12954)
		(layer "F.Cu")
		(net "P5E_CPU0_P1_TX_DP<11>")
	)
	(segment
		(start 354.847906 -290.83)
		(end 354.381054 -291.095938)
		(width 0.12954)
		(layer "F.Cu")
		(net "P5E_CPU0_P1_TX_DP<11>")
	)
	(segment
		(start 352.234754 -380.85522)
		(end 352.234754 -380.15164)
		(width 0.12954)
		(layer "F.Cu")
		(net "P5E_CPU0_P1_TX_DP<11>")
	)
	(segment
		(start 355.486716 -294.000936)
		(end 355.537008 -294.030146)
		(width 0.1143)
		(layer "In4.Cu")
		(net "P5E_CPU0_P1_TX_DP<11>")
	)
	(segment
		(start 374.108726 -351.717102)
		(end 374.092724 -351.749868)
		(width 0.14224)
		(layer "In4.Cu")
		(net "P5E_CPU0_P1_TX_DP<11>")
	)
	(segment
		(start 355.541834 -294.033702)
		(end 355.543358 -294.034972)
		(width 0.1143)
		(layer "In4.Cu")
		(net "P5E_CPU0_P1_TX_DP<11>")
	)
	(segment
		(start 374.021604 -333.167736)
		(end 374.021604 -333.167482)
		(width 0.14224)
		(layer "In4.Cu")
		(net "P5E_CPU0_P1_TX_DP<11>")
	)
	(segment
		(start 355.539802 -293.020242)
		(end 355.508052 -293.03853)
		(width 0.1143)
		(layer "In4.Cu")
		(net "P5E_CPU0_P1_TX_DP<11>")
	)
	(segment
		(start 354.954332 -296.61231)
		(end 354.954332 -298.346368)
		(width 0.14224)
		(layer "In4.Cu")
		(net "P5E_CPU0_P1_TX_DP<11>")
	)
	(segment
		(start 355.47173 -292.372288)
		(end 355.508052 -292.39337)
		(width 0.1143)
		(layer "In4.Cu")
		(net "P5E_CPU0_P1_TX_DP<11>")
	)
	(segment
		(start 370.219732 -322.05676)
		(end 374.021604 -333.167736)
		(width 0.14224)
		(layer "In4.Cu")
		(net "P5E_CPU0_P1_TX_DP<11>")
	)
	(segment
		(start 355.540056 -294.63873)
		(end 355.455474 -294.68953)
		(width 0.1143)
		(layer "In4.Cu")
		(net "P5E_CPU0_P1_TX_DP<11>")
	)
	(segment
		(start 354.954332 -296.583862)
		(end 354.954332 -296.61231)
		(width 0.1143)
		(layer "In4.Cu")
		(net "P5E_CPU0_P1_TX_DP<11>")
	)
	(segment
		(start 355.543358 -294.034972)
		(end 355.54666 -294.037258)
		(width 0.1143)
		(layer "In4.Cu")
		(net "P5E_CPU0_P1_TX_DP<11>")
	)
	(segment
		(start 354.999036 -291.560504)
		(end 355.005894 -291.564568)
		(width 0.1143)
		(layer "In4.Cu")
		(net "P5E_CPU0_P1_TX_DP<11>")
	)
	(segment
		(start 352.255074 -376.77471)
		(end 352.255074 -379.5903)
		(width 0.14224)
		(layer "In4.Cu")
		(net "P5E_CPU0_P1_TX_DP<11>")
	)
	(segment
		(start 374.122188 -351.657412)
		(end 374.121934 -351.658428)
		(width 0.14224)
		(layer "In4.Cu")
		(net "P5E_CPU0_P1_TX_DP<11>")
	)
	(segment
		(start 354.920804 -296.344848)
		(end 354.962714 -296.386758)
		(width 0.1143)
		(layer "In4.Cu")
		(net "P5E_CPU0_P1_TX_DP<11>")
	)
	(segment
		(start 362.909866 -367.836958)
		(end 352.404426 -376.458226)
		(width 0.14224)
		(layer "In4.Cu")
		(net "P5E_CPU0_P1_TX_DP<11>")
	)
	(segment
		(start 355.069902 -291.601652)
		(end 355.07168 -291.602922)
		(width 0.1143)
		(layer "In4.Cu")
		(net "P5E_CPU0_P1_TX_DP<11>")
	)
	(segment
		(start 355.005894 -291.564568)
		(end 355.006656 -291.565076)
		(width 0.1143)
		(layer "In4.Cu")
		(net "P5E_CPU0_P1_TX_DP<11>")
	)
	(segment
		(start 374.125236 -351.64395)
		(end 374.122188 -351.657412)
		(width 0.14224)
		(layer "In4.Cu")
		(net "P5E_CPU0_P1_TX_DP<11>")
	)
	(segment
		(start 360.621326 -309.472584)
		(end 368.940334 -319.609724)
		(width 0.14224)
		(layer "In4.Cu")
		(net "P5E_CPU0_P1_TX_DP<11>")
	)
	(segment
		(start 354.381054 -291.095938)
		(end 354.678996 -291.095938)
		(width 0.1143)
		(layer "In4.Cu")
		(net "P5E_CPU0_P1_TX_DP<11>")
	)
	(segment
		(start 355.066854 -295.452038)
		(end 355.065838 -295.452546)
		(width 0.1143)
		(layer "In4.Cu")
		(net "P5E_CPU0_P1_TX_DP<11>")
	)
	(segment
		(start 355.000052 -296.476674)
		(end 355.000052 -296.538142)
		(width 0.1143)
		(layer "In4.Cu")
		(net "P5E_CPU0_P1_TX_DP<11>")
	)
	(segment
		(start 355.064314 -295.453562)
		(end 355.061774 -295.454832)
		(width 0.1143)
		(layer "In4.Cu")
		(net "P5E_CPU0_P1_TX_DP<11>")
	)
	(segment
		(start 355.061774 -295.454832)
		(end 355.056694 -295.458642)
		(width 0.1143)
		(layer "In4.Cu")
		(net "P5E_CPU0_P1_TX_DP<11>")
	)
	(segment
		(start 352.255074 -379.5903)
		(end 351.964244 -379.88113)
		(width 0.14224)
		(layer "In4.Cu")
		(net "P5E_CPU0_P1_TX_DP<11>")
	)
	(segment
		(start 355.000052 -296.538142)
		(end 354.954332 -296.583862)
		(width 0.1143)
		(layer "In4.Cu")
		(net "P5E_CPU0_P1_TX_DP<11>")
	)
	(segment
		(start 354.678996 -291.095938)
		(end 354.7618 -291.178742)
		(width 0.1143)
		(layer "In4.Cu")
		(net "P5E_CPU0_P1_TX_DP<11>")
	)
	(segment
		(start 355.038914 -291.583872)
		(end 355.069902 -291.601652)
		(width 0.1143)
		(layer "In4.Cu")
		(net "P5E_CPU0_P1_TX_DP<11>")
	)
	(segment
		(start 374.12549 -351.643188)
		(end 374.125236 -351.64395)
		(width 0.14224)
		(layer "In4.Cu")
		(net "P5E_CPU0_P1_TX_DP<11>")
	)
	(segment
		(start 374.042686 -333.248508)
		(end 374.839484 -337.68284)
		(width 0.14224)
		(layer "In4.Cu")
		(net "P5E_CPU0_P1_TX_DP<11>")
	)
	(segment
		(start 355.225858 -291.903912)
		(end 355.225858 -291.905944)
		(width 0.1143)
		(layer "In4.Cu")
		(net "P5E_CPU0_P1_TX_DP<11>")
	)
	(segment
		(start 374.041416 -351.865438)
		(end 362.909866 -367.836958)
		(width 0.14224)
		(layer "In4.Cu")
		(net "P5E_CPU0_P1_TX_DP<11>")
	)
	(segment
		(start 374.12803 -351.632012)
		(end 374.12549 -351.643188)
		(width 0.14224)
		(layer "In4.Cu")
		(net "P5E_CPU0_P1_TX_DP<11>")
	)
	(segment
		(start 355.038152 -291.583364)
		(end 355.038914 -291.583872)
		(width 0.1143)
		(layer "In4.Cu")
		(net "P5E_CPU0_P1_TX_DP<11>")
	)
	(segment
		(start 355.539294 -294.031924)
		(end 355.541834 -294.033702)
		(width 0.1143)
		(layer "In4.Cu")
		(net "P5E_CPU0_P1_TX_DP<11>")
	)
	(segment
		(start 374.828562 -348.570804)
		(end 374.12803 -351.632012)
		(width 0.14224)
		(layer "In4.Cu")
		(net "P5E_CPU0_P1_TX_DP<11>")
	)
	(segment
		(start 355.537008 -294.030146)
		(end 355.539294 -294.031924)
		(width 0.1143)
		(layer "In4.Cu")
		(net "P5E_CPU0_P1_TX_DP<11>")
	)
	(segment
		(start 354.98532 -298.502832)
		(end 357.747824 -305.172618)
		(width 0.14224)
		(layer "In4.Cu")
		(net "P5E_CPU0_P1_TX_DP<11>")
	)
	(segment
		(start 355.508052 -292.39337)
		(end 355.539802 -292.411658)
		(width 0.1143)
		(layer "In4.Cu")
		(net "P5E_CPU0_P1_TX_DP<11>")
	)
	(segment
		(start 355.508052 -293.03853)
		(end 355.486716 -293.050976)
		(width 0.1143)
		(layer "In4.Cu")
		(net "P5E_CPU0_P1_TX_DP<11>")
	)
	(segment
		(start 355.090476 -295.43629)
		(end 355.066854 -295.452038)
		(width 0.1143)
		(layer "In4.Cu")
		(net "P5E_CPU0_P1_TX_DP<11>")
	)
	(segment
		(start 368.940334 -319.609724)
		(end 370.219732 -322.05676)
		(width 0.14224)
		(layer "In4.Cu")
		(net "P5E_CPU0_P1_TX_DP<11>")
	)
	(segment
		(start 374.85066 -337.808824)
		(end 374.85066 -348.37751)
		(width 0.14224)
		(layer "In4.Cu")
		(net "P5E_CPU0_P1_TX_DP<11>")
	)
	(segment
		(start 355.065838 -295.452546)
		(end 355.064314 -295.453562)
		(width 0.1143)
		(layer "In4.Cu")
		(net "P5E_CPU0_P1_TX_DP<11>")
	)
	(segment
		(start 355.213158 -295.153588)
		(end 355.213158 -295.206928)
		(width 0.1143)
		(layer "In4.Cu")
		(net "P5E_CPU0_P1_TX_DP<11>")
	)
	(segment
		(start 374.121934 -351.658428)
		(end 374.108726 -351.717102)
		(width 0.14224)
		(layer "In4.Cu")
		(net "P5E_CPU0_P1_TX_DP<11>")
	)
	(segment
		(start 355.006656 -291.565076)
		(end 355.038152 -291.583364)
		(width 0.1143)
		(layer "In4.Cu")
		(net "P5E_CPU0_P1_TX_DP<11>")
	)
	(segment
		(start 357.747824 -305.172618)
		(end 360.621326 -309.472584)
		(width 0.14224)
		(layer "In4.Cu")
		(net "P5E_CPU0_P1_TX_DP<11>")
	)
	(segment
		(start 355.056694 -295.458642)
		(end 355.04628 -295.4655)
		(width 0.1143)
		(layer "In4.Cu")
		(net "P5E_CPU0_P1_TX_DP<11>")
	)
	(arc
		(start 354.954332 -298.346368)
		(mid 354.962125 -298.426126)
		(end 354.98532 -298.502832)
		(width 0.14224)
		(layer "In4.Cu")
		(net "P5E_CPU0_P1_TX_DP<11>")
	)
	(arc
		(start 354.76561 -291.201602)
		(mid 354.847043 -291.404)
		(end 354.999036 -291.560504)
		(width 0.1143)
		(layer "In4.Cu")
		(net "P5E_CPU0_P1_TX_DP<11>")
	)
	(arc
		(start 374.85066 -348.37751)
		(mid 374.845014 -348.474774)
		(end 374.828562 -348.570804)
		(width 0.14224)
		(layer "In4.Cu")
		(net "P5E_CPU0_P1_TX_DP<11>")
	)
	(arc
		(start 354.975668 -295.508426)
		(mid 354.937829 -295.546535)
		(end 354.90023 -295.58488)
		(width 0.1143)
		(layer "In4.Cu")
		(net "P5E_CPU0_P1_TX_DP<11>")
	)
	(arc
		(start 355.04628 -295.4655)
		(mid 355.026403 -295.475583)
		(end 355.007164 -295.486836)
		(width 0.1143)
		(layer "In4.Cu")
		(net "P5E_CPU0_P1_TX_DP<11>")
	)
	(arc
		(start 354.797614 -295.742614)
		(mid 354.768605 -296.062263)
		(end 354.920804 -296.344848)
		(width 0.1143)
		(layer "In4.Cu")
		(net "P5E_CPU0_P1_TX_DP<11>")
	)
	(arc
		(start 355.225858 -291.912548)
		(mid 355.29073 -292.16229)
		(end 355.455474 -292.360858)
		(width 0.1143)
		(layer "In4.Cu")
		(net "P5E_CPU0_P1_TX_DP<11>")
	)
	(arc
		(start 355.455474 -294.68953)
		(mid 355.27735 -294.89182)
		(end 355.213158 -295.153588)
		(width 0.1143)
		(layer "In4.Cu")
		(net "P5E_CPU0_P1_TX_DP<11>")
	)
	(arc
		(start 355.54666 -294.037258)
		(mid 355.695786 -294.339618)
		(end 355.540056 -294.63873)
		(width 0.1143)
		(layer "In4.Cu")
		(net "P5E_CPU0_P1_TX_DP<11>")
	)
	(arc
		(start 355.539802 -292.411658)
		(mid 355.69573 -292.71595)
		(end 355.539802 -293.020242)
		(width 0.1143)
		(layer "In4.Cu")
		(net "P5E_CPU0_P1_TX_DP<11>")
	)
	(arc
		(start 374.092724 -351.749868)
		(mid 374.072619 -351.810116)
		(end 374.041416 -351.865438)
		(width 0.14224)
		(layer "In4.Cu")
		(net "P5E_CPU0_P1_TX_DP<11>")
	)
	(arc
		(start 354.80371 -295.728136)
		(mid 354.800612 -295.735354)
		(end 354.797614 -295.742614)
		(width 0.1143)
		(layer "In4.Cu")
		(net "P5E_CPU0_P1_TX_DP<11>")
	)
	(arc
		(start 354.962714 -296.386758)
		(mid 354.990333 -296.427998)
		(end 355.000052 -296.476674)
		(width 0.1143)
		(layer "In4.Cu")
		(net "P5E_CPU0_P1_TX_DP<11>")
	)
	(arc
		(start 374.021604 -333.167482)
		(mid 374.033677 -333.207596)
		(end 374.042686 -333.248508)
		(width 0.14224)
		(layer "In4.Cu")
		(net "P5E_CPU0_P1_TX_DP<11>")
	)
	(arc
		(start 374.839484 -337.68284)
		(mid 374.847879 -337.745583)
		(end 374.85066 -337.808824)
		(width 0.14224)
		(layer "In4.Cu")
		(net "P5E_CPU0_P1_TX_DP<11>")
	)
	(arc
		(start 355.455474 -292.360858)
		(mid 355.463552 -292.366644)
		(end 355.47173 -292.372288)
		(width 0.1143)
		(layer "In4.Cu")
		(net "P5E_CPU0_P1_TX_DP<11>")
	)
	(arc
		(start 352.404426 -376.458226)
		(mid 352.294166 -376.599688)
		(end 352.255074 -376.77471)
		(width 0.14224)
		(layer "In4.Cu")
		(net "P5E_CPU0_P1_TX_DP<11>")
	)
	(arc
		(start 355.213158 -295.206928)
		(mid 355.180568 -295.336994)
		(end 355.090476 -295.43629)
		(width 0.1143)
		(layer "In4.Cu")
		(net "P5E_CPU0_P1_TX_DP<11>")
	)
	(arc
		(start 355.486716 -293.050976)
		(mid 355.213165 -293.525956)
		(end 355.486716 -294.000936)
		(width 0.1143)
		(layer "In4.Cu")
		(net "P5E_CPU0_P1_TX_DP<11>")
	)
	(arc
		(start 355.225858 -291.905944)
		(mid 355.225848 -291.909246)
		(end 355.225858 -291.912548)
		(width 0.1143)
		(layer "In4.Cu")
		(net "P5E_CPU0_P1_TX_DP<11>")
	)
	(arc
		(start 354.7618 -291.178742)
		(mid 354.763588 -291.190191)
		(end 354.76561 -291.201602)
		(width 0.1143)
		(layer "In4.Cu")
		(net "P5E_CPU0_P1_TX_DP<11>")
	)
	(arc
		(start 355.07168 -291.602922)
		(mid 355.185085 -291.734817)
		(end 355.225858 -291.903912)
		(width 0.1143)
		(layer "In4.Cu")
		(net "P5E_CPU0_P1_TX_DP<11>")
	)
	(arc
		(start 355.007164 -295.486836)
		(mid 354.991143 -295.497233)
		(end 354.975668 -295.508426)
		(width 0.1143)
		(layer "In4.Cu")
		(net "P5E_CPU0_P1_TX_DP<11>")
	)
	(arc
		(start 354.90023 -295.58488)
		(mid 354.845569 -295.652196)
		(end 354.80371 -295.728136)
		(width 0.1143)
		(layer "In4.Cu")
		(net "P5E_CPU0_P1_TX_DP<11>")
	)
	(segment
		(start 350.532954 -383.31902)
		(end 350.532954 -382.61544)
		(width 0.12954)
		(layer "F.Cu")
		(net "P5E_CPU0_P1_TX_DP<10>")
	)
	(segment
		(start 350.532954 -382.61544)
		(end 350.262444 -382.34493)
		(width 0.12954)
		(layer "F.Cu")
		(net "P5E_CPU0_P1_TX_DP<10>")
	)
	(segment
		(start 354.847906 -289.209988)
		(end 354.381054 -289.475926)
		(width 0.12954)
		(layer "F.Cu")
		(net "P5E_CPU0_P1_TX_DP<10>")
	)
	(segment
		(start 350.237044 -383.61493)
		(end 350.532954 -383.31902)
		(width 0.12954)
		(layer "F.Cu")
		(net "P5E_CPU0_P1_TX_DP<10>")
	)
	(segment
		(start 373.167148 -351.372932)
		(end 373.167148 -351.373186)
		(width 0.14224)
		(layer "In4.Cu")
		(net "P5E_CPU0_P1_TX_DP<10>")
	)
	(segment
		(start 362.656374 -366.49787)
		(end 351.690178 -374.63095)
		(width 0.14224)
		(layer "In4.Cu")
		(net "P5E_CPU0_P1_TX_DP<10>")
	)
	(segment
		(start 354.09886 -290.608004)
		(end 354.098098 -290.608512)
		(width 0.1143)
		(layer "In4.Cu")
		(net "P5E_CPU0_P1_TX_DP<10>")
	)
	(segment
		(start 354.381054 -289.475926)
		(end 354.678996 -289.475926)
		(width 0.1143)
		(layer "In4.Cu")
		(net "P5E_CPU0_P1_TX_DP<10>")
	)
	(segment
		(start 373.900446 -348.34068)
		(end 373.900192 -348.342204)
		(width 0.14224)
		(layer "In4.Cu")
		(net "P5E_CPU0_P1_TX_DP<10>")
	)
	(segment
		(start 354.129848 -290.590224)
		(end 354.10013 -290.607242)
		(width 0.1143)
		(layer "In4.Cu")
		(net "P5E_CPU0_P1_TX_DP<10>")
	)
	(segment
		(start 354.568252 -293.03853)
		(end 354.529136 -293.06139)
		(width 0.1143)
		(layer "In4.Cu")
		(net "P5E_CPU0_P1_TX_DP<10>")
	)
	(segment
		(start 354.104702 -291.587174)
		(end 354.105718 -291.587682)
		(width 0.1143)
		(layer "In4.Cu")
		(net "P5E_CPU0_P1_TX_DP<10>")
	)
	(segment
		(start 373.113554 -333.424022)
		(end 373.9007 -337.80476)
		(width 0.14224)
		(layer "In4.Cu")
		(net "P5E_CPU0_P1_TX_DP<10>")
	)
	(segment
		(start 354.285804 -295.145968)
		(end 354.285804 -295.304718)
		(width 0.1143)
		(layer "In4.Cu")
		(net "P5E_CPU0_P1_TX_DP<10>")
	)
	(segment
		(start 353.857052 -296.107104)
		(end 353.857052 -298.134532)
		(width 0.14224)
		(layer "In4.Cu")
		(net "P5E_CPU0_P1_TX_DP<10>")
	)
	(segment
		(start 354.058982 -291.560504)
		(end 354.06584 -291.564568)
		(width 0.1143)
		(layer "In4.Cu")
		(net "P5E_CPU0_P1_TX_DP<10>")
	)
	(segment
		(start 354.066602 -291.565076)
		(end 354.098098 -291.583364)
		(width 0.1143)
		(layer "In4.Cu")
		(net "P5E_CPU0_P1_TX_DP<10>")
	)
	(segment
		(start 373.907558 -337.88096)
		(end 373.907558 -348.280736)
		(width 0.14224)
		(layer "In4.Cu")
		(net "P5E_CPU0_P1_TX_DP<10>")
	)
	(segment
		(start 354.598732 -294.640762)
		(end 354.568252 -294.658542)
		(width 0.1143)
		(layer "In4.Cu")
		(net "P5E_CPU0_P1_TX_DP<10>")
	)
	(segment
		(start 356.92334 -305.618642)
		(end 360.079798 -310.343042)
		(width 0.14224)
		(layer "In4.Cu")
		(net "P5E_CPU0_P1_TX_DP<10>")
	)
	(segment
		(start 354.529136 -292.37051)
		(end 354.568252 -292.39337)
		(width 0.1143)
		(layer "In4.Cu")
		(net "P5E_CPU0_P1_TX_DP<10>")
	)
	(segment
		(start 354.678996 -289.475926)
		(end 354.748846 -289.545776)
		(width 0.1143)
		(layer "In4.Cu")
		(net "P5E_CPU0_P1_TX_DP<10>")
	)
	(segment
		(start 353.902772 -296.032936)
		(end 353.857052 -296.078656)
		(width 0.1143)
		(layer "In4.Cu")
		(net "P5E_CPU0_P1_TX_DP<10>")
	)
	(segment
		(start 353.902772 -295.914572)
		(end 353.902772 -296.032936)
		(width 0.1143)
		(layer "In4.Cu")
		(net "P5E_CPU0_P1_TX_DP<10>")
	)
	(segment
		(start 373.081804 -333.301848)
		(end 373.081804 -333.301594)
		(width 0.14224)
		(layer "In4.Cu")
		(net "P5E_CPU0_P1_TX_DP<10>")
	)
	(segment
		(start 354.10394 -291.586666)
		(end 354.104702 -291.587174)
		(width 0.1143)
		(layer "In4.Cu")
		(net "P5E_CPU0_P1_TX_DP<10>")
	)
	(segment
		(start 354.105718 -291.587682)
		(end 354.129848 -291.601652)
		(width 0.1143)
		(layer "In4.Cu")
		(net "P5E_CPU0_P1_TX_DP<10>")
	)
	(segment
		(start 369.342162 -322.39204)
		(end 369.34267 -322.393056)
		(width 0.14224)
		(layer "In4.Cu")
		(net "P5E_CPU0_P1_TX_DP<10>")
	)
	(segment
		(start 354.598732 -293.02075)
		(end 354.568252 -293.03853)
		(width 0.1143)
		(layer "In4.Cu")
		(net "P5E_CPU0_P1_TX_DP<10>")
	)
	(segment
		(start 353.857052 -296.078656)
		(end 353.857052 -296.107104)
		(width 0.1143)
		(layer "In4.Cu")
		(net "P5E_CPU0_P1_TX_DP<10>")
	)
	(segment
		(start 354.598732 -289.780726)
		(end 354.568252 -289.798506)
		(width 0.1143)
		(layer "In4.Cu")
		(net "P5E_CPU0_P1_TX_DP<10>")
	)
	(segment
		(start 354.095558 -290.610036)
		(end 354.058982 -290.631372)
		(width 0.1143)
		(layer "In4.Cu")
		(net "P5E_CPU0_P1_TX_DP<10>")
	)
	(segment
		(start 354.098098 -290.608512)
		(end 354.097082 -290.60902)
		(width 0.1143)
		(layer "In4.Cu")
		(net "P5E_CPU0_P1_TX_DP<10>")
	)
	(segment
		(start 368.241834 -320.287396)
		(end 369.342162 -322.39204)
		(width 0.14224)
		(layer "In4.Cu")
		(net "P5E_CPU0_P1_TX_DP<10>")
	)
	(segment
		(start 354.098098 -291.583364)
		(end 354.09886 -291.583872)
		(width 0.1143)
		(layer "In4.Cu")
		(net "P5E_CPU0_P1_TX_DP<10>")
	)
	(segment
		(start 373.900192 -348.342204)
		(end 373.218456 -351.258124)
		(width 0.14224)
		(layer "In4.Cu")
		(net "P5E_CPU0_P1_TX_DP<10>")
	)
	(segment
		(start 354.568252 -294.013382)
		(end 354.598732 -294.031162)
		(width 0.1143)
		(layer "In4.Cu")
		(net "P5E_CPU0_P1_TX_DP<10>")
	)
	(segment
		(start 353.88804 -298.290996)
		(end 356.92334 -305.618642)
		(width 0.14224)
		(layer "In4.Cu")
		(net "P5E_CPU0_P1_TX_DP<10>")
	)
	(segment
		(start 354.568252 -289.798506)
		(end 354.529136 -289.821366)
		(width 0.1143)
		(layer "In4.Cu")
		(net "P5E_CPU0_P1_TX_DP<10>")
	)
	(segment
		(start 354.101654 -291.585396)
		(end 354.102416 -291.585904)
		(width 0.1143)
		(layer "In4.Cu")
		(net "P5E_CPU0_P1_TX_DP<10>")
	)
	(segment
		(start 354.529136 -293.990522)
		(end 354.568252 -294.013382)
		(width 0.1143)
		(layer "In4.Cu")
		(net "P5E_CPU0_P1_TX_DP<10>")
	)
	(segment
		(start 354.568252 -294.658542)
		(end 354.529136 -294.681402)
		(width 0.1143)
		(layer "In4.Cu")
		(net "P5E_CPU0_P1_TX_DP<10>")
	)
	(segment
		(start 350.553274 -376.889772)
		(end 350.553274 -381.987298)
		(width 0.14224)
		(layer "In4.Cu")
		(net "P5E_CPU0_P1_TX_DP<10>")
	)
	(segment
		(start 354.218494 -295.467278)
		(end 353.99599 -295.689782)
		(width 0.1143)
		(layer "In4.Cu")
		(net "P5E_CPU0_P1_TX_DP<10>")
	)
	(segment
		(start 350.50603 -382.101344)
		(end 350.262444 -382.34493)
		(width 0.14224)
		(layer "In4.Cu")
		(net "P5E_CPU0_P1_TX_DP<10>")
	)
	(segment
		(start 354.09886 -291.583872)
		(end 354.101654 -291.585396)
		(width 0.1143)
		(layer "In4.Cu")
		(net "P5E_CPU0_P1_TX_DP<10>")
	)
	(segment
		(start 354.568252 -292.39337)
		(end 354.598732 -292.41115)
		(width 0.1143)
		(layer "In4.Cu")
		(net "P5E_CPU0_P1_TX_DP<10>")
	)
	(segment
		(start 354.06584 -291.564568)
		(end 354.066602 -291.565076)
		(width 0.1143)
		(layer "In4.Cu")
		(net "P5E_CPU0_P1_TX_DP<10>")
	)
	(segment
		(start 354.10013 -290.607242)
		(end 354.09886 -290.608004)
		(width 0.1143)
		(layer "In4.Cu")
		(net "P5E_CPU0_P1_TX_DP<10>")
	)
	(segment
		(start 373.900954 -348.338902)
		(end 373.900446 -348.34068)
		(width 0.14224)
		(layer "In4.Cu")
		(net "P5E_CPU0_P1_TX_DP<10>")
	)
	(segment
		(start 373.167148 -351.373186)
		(end 362.656374 -366.49787)
		(width 0.14224)
		(layer "In4.Cu")
		(net "P5E_CPU0_P1_TX_DP<10>")
	)
	(segment
		(start 369.34267 -322.393056)
		(end 373.081804 -333.301848)
		(width 0.14224)
		(layer "In4.Cu")
		(net "P5E_CPU0_P1_TX_DP<10>")
	)
	(segment
		(start 354.102416 -291.585904)
		(end 354.10394 -291.586666)
		(width 0.1143)
		(layer "In4.Cu")
		(net "P5E_CPU0_P1_TX_DP<10>")
	)
	(segment
		(start 360.079798 -310.343042)
		(end 368.241834 -320.287396)
		(width 0.14224)
		(layer "In4.Cu")
		(net "P5E_CPU0_P1_TX_DP<10>")
	)
	(segment
		(start 354.097082 -290.60902)
		(end 354.095558 -290.610036)
		(width 0.1143)
		(layer "In4.Cu")
		(net "P5E_CPU0_P1_TX_DP<10>")
	)
	(arc
		(start 354.598732 -294.031162)
		(mid 354.755709 -294.335962)
		(end 354.598732 -294.640762)
		(width 0.1143)
		(layer "In4.Cu")
		(net "P5E_CPU0_P1_TX_DP<10>")
	)
	(arc
		(start 351.690178 -374.63095)
		(mid 350.853499 -375.625363)
		(end 350.553274 -376.889772)
		(width 0.14224)
		(layer "In4.Cu")
		(net "P5E_CPU0_P1_TX_DP<10>")
	)
	(arc
		(start 373.9007 -337.80476)
		(mid 373.905821 -337.842708)
		(end 373.907558 -337.88096)
		(width 0.14224)
		(layer "In4.Cu")
		(net "P5E_CPU0_P1_TX_DP<10>")
	)
	(arc
		(start 350.553274 -381.987298)
		(mid 350.540997 -382.049021)
		(end 350.50603 -382.101344)
		(width 0.14224)
		(layer "In4.Cu")
		(net "P5E_CPU0_P1_TX_DP<10>")
	)
	(arc
		(start 354.748846 -289.545776)
		(mid 354.696429 -289.677707)
		(end 354.598732 -289.780726)
		(width 0.1143)
		(layer "In4.Cu")
		(net "P5E_CPU0_P1_TX_DP<10>")
	)
	(arc
		(start 353.99599 -295.689782)
		(mid 353.927024 -295.792902)
		(end 353.902772 -295.914572)
		(width 0.1143)
		(layer "In4.Cu")
		(net "P5E_CPU0_P1_TX_DP<10>")
	)
	(arc
		(start 354.529136 -294.681402)
		(mid 354.350246 -294.883726)
		(end 354.285804 -295.145968)
		(width 0.1143)
		(layer "In4.Cu")
		(net "P5E_CPU0_P1_TX_DP<10>")
	)
	(arc
		(start 354.285804 -295.304718)
		(mid 354.268306 -295.392685)
		(end 354.218494 -295.467278)
		(width 0.1143)
		(layer "In4.Cu")
		(net "P5E_CPU0_P1_TX_DP<10>")
	)
	(arc
		(start 354.285804 -290.285932)
		(mid 354.244549 -290.456903)
		(end 354.129848 -290.590224)
		(width 0.1143)
		(layer "In4.Cu")
		(net "P5E_CPU0_P1_TX_DP<10>")
	)
	(arc
		(start 353.857052 -298.134532)
		(mid 353.864845 -298.21429)
		(end 353.88804 -298.290996)
		(width 0.14224)
		(layer "In4.Cu")
		(net "P5E_CPU0_P1_TX_DP<10>")
	)
	(arc
		(start 373.907558 -348.280736)
		(mid 373.90585 -348.31)
		(end 373.900954 -348.338902)
		(width 0.14224)
		(layer "In4.Cu")
		(net "P5E_CPU0_P1_TX_DP<10>")
	)
	(arc
		(start 354.058982 -290.631372)
		(mid 353.815655 -291.095938)
		(end 354.058982 -291.560504)
		(width 0.1143)
		(layer "In4.Cu")
		(net "P5E_CPU0_P1_TX_DP<10>")
	)
	(arc
		(start 354.285804 -291.905944)
		(mid 354.350319 -292.168163)
		(end 354.529136 -292.37051)
		(width 0.1143)
		(layer "In4.Cu")
		(net "P5E_CPU0_P1_TX_DP<10>")
	)
	(arc
		(start 373.218456 -351.258124)
		(mid 373.198237 -351.317957)
		(end 373.167148 -351.372932)
		(width 0.14224)
		(layer "In4.Cu")
		(net "P5E_CPU0_P1_TX_DP<10>")
	)
	(arc
		(start 354.529136 -293.06139)
		(mid 354.285809 -293.525956)
		(end 354.529136 -293.990522)
		(width 0.1143)
		(layer "In4.Cu")
		(net "P5E_CPU0_P1_TX_DP<10>")
	)
	(arc
		(start 354.529136 -289.821366)
		(mid 354.350323 -290.023716)
		(end 354.285804 -290.285932)
		(width 0.1143)
		(layer "In4.Cu")
		(net "P5E_CPU0_P1_TX_DP<10>")
	)
	(arc
		(start 373.081804 -333.301594)
		(mid 373.100002 -333.362205)
		(end 373.113554 -333.424022)
		(width 0.14224)
		(layer "In4.Cu")
		(net "P5E_CPU0_P1_TX_DP<10>")
	)
	(arc
		(start 354.129848 -291.601652)
		(mid 354.244524 -291.734986)
		(end 354.285804 -291.905944)
		(width 0.1143)
		(layer "In4.Cu")
		(net "P5E_CPU0_P1_TX_DP<10>")
	)
	(arc
		(start 354.598732 -292.41115)
		(mid 354.755709 -292.71595)
		(end 354.598732 -293.02075)
		(width 0.1143)
		(layer "In4.Cu")
		(net "P5E_CPU0_P1_TX_DP<10>")
	)
	(segment
		(start 346.387928 -285.970218)
		(end 345.921076 -286.236156)
		(width 0.12954)
		(layer "F.Cu")
		(net "P5E_CPU0_P1_TX_DP<0>")
	)
	(segment
		(start 330.228702 -390.48055)
		(end 329.958192 -390.75106)
		(width 0.12954)
		(layer "F.Cu")
		(net "P5E_CPU0_P1_TX_DP<0>")
	)
	(segment
		(start 330.932282 -390.48055)
		(end 330.228702 -390.48055)
		(width 0.12954)
		(layer "F.Cu")
		(net "P5E_CPU0_P1_TX_DP<0>")
	)
	(segment
		(start 331.228192 -390.77646)
		(end 330.932282 -390.48055)
		(width 0.12954)
		(layer "F.Cu")
		(net "P5E_CPU0_P1_TX_DP<0>")
	)
	(segment
		(start 344.848434 -295.437306)
		(end 344.50909 -295.77665)
		(width 0.1143)
		(layer "In4.Cu")
		(net "P5E_CPU0_P1_TX_DP<0>")
	)
	(segment
		(start 348.883732 -310.597296)
		(end 352.322892 -315.744352)
		(width 0.14224)
		(layer "In4.Cu")
		(net "P5E_CPU0_P1_TX_DP<0>")
	)
	(segment
		(start 364.004098 -336.373978)
		(end 364.152688 -337.200494)
		(width 0.14224)
		(layer "In4.Cu")
		(net "P5E_CPU0_P1_TX_DP<0>")
	)
	(segment
		(start 345.16822 -288.178494)
		(end 345.129104 -288.201354)
		(width 0.1143)
		(layer "In4.Cu")
		(net "P5E_CPU0_P1_TX_DP<0>")
	)
	(segment
		(start 345.16822 -292.39337)
		(end 345.1987 -292.41115)
		(width 0.1143)
		(layer "In4.Cu")
		(net "P5E_CPU0_P1_TX_DP<0>")
	)
	(segment
		(start 345.16822 -289.798506)
		(end 345.129104 -289.821366)
		(width 0.1143)
		(layer "In4.Cu")
		(net "P5E_CPU0_P1_TX_DP<0>")
	)
	(segment
		(start 345.1987 -293.02075)
		(end 345.16822 -293.03853)
		(width 0.1143)
		(layer "In4.Cu")
		(net "P5E_CPU0_P1_TX_DP<0>")
	)
	(segment
		(start 345.16822 -293.03853)
		(end 345.129104 -293.06139)
		(width 0.1143)
		(layer "In4.Cu")
		(net "P5E_CPU0_P1_TX_DP<0>")
	)
	(segment
		(start 364.004098 -336.373724)
		(end 364.004098 -336.373978)
		(width 0.14224)
		(layer "In4.Cu")
		(net "P5E_CPU0_P1_TX_DP<0>")
	)
	(segment
		(start 356.291388 -320.580004)
		(end 356.291388 -320.57975)
		(width 0.14224)
		(layer "In4.Cu")
		(net "P5E_CPU0_P1_TX_DP<0>")
	)
	(segment
		(start 344.370152 -299.700188)
		(end 348.883732 -310.597296)
		(width 0.14224)
		(layer "In4.Cu")
		(net "P5E_CPU0_P1_TX_DP<0>")
	)
	(segment
		(start 344.370152 -296.205656)
		(end 344.370152 -296.234104)
		(width 0.1143)
		(layer "In4.Cu")
		(net "P5E_CPU0_P1_TX_DP<0>")
	)
	(segment
		(start 344.698066 -290.608512)
		(end 344.661744 -290.629594)
		(width 0.1143)
		(layer "In4.Cu")
		(net "P5E_CPU0_P1_TX_DP<0>")
	)
	(segment
		(start 328.45756 -375.979436)
		(end 328.45756 -389.763254)
		(width 0.14224)
		(layer "In4.Cu")
		(net "P5E_CPU0_P1_TX_DP<0>")
	)
	(segment
		(start 346.108274 -286.558482)
		(end 346.069158 -286.581342)
		(width 0.1143)
		(layer "In4.Cu")
		(net "P5E_CPU0_P1_TX_DP<0>")
	)
	(segment
		(start 344.415872 -296.159936)
		(end 344.370152 -296.205656)
		(width 0.1143)
		(layer "In4.Cu")
		(net "P5E_CPU0_P1_TX_DP<0>")
	)
	(segment
		(start 352.322892 -315.744352)
		(end 356.291388 -320.580004)
		(width 0.14224)
		(layer "In4.Cu")
		(net "P5E_CPU0_P1_TX_DP<0>")
	)
	(segment
		(start 345.1987 -289.780726)
		(end 345.16822 -289.798506)
		(width 0.1143)
		(layer "In4.Cu")
		(net "P5E_CPU0_P1_TX_DP<0>")
	)
	(segment
		(start 345.66987 -287.3502)
		(end 345.63812 -287.368488)
		(width 0.1143)
		(layer "In4.Cu")
		(net "P5E_CPU0_P1_TX_DP<0>")
	)
	(segment
		(start 346.140786 -286.539686)
		(end 346.108274 -286.558482)
		(width 0.1143)
		(layer "In4.Cu")
		(net "P5E_CPU0_P1_TX_DP<0>")
	)
	(segment
		(start 353.936554 -359.494836)
		(end 329.497436 -374.143524)
		(width 0.14224)
		(layer "In4.Cu")
		(net "P5E_CPU0_P1_TX_DP<0>")
	)
	(segment
		(start 345.63812 -287.368488)
		(end 345.601544 -287.389824)
		(width 0.1143)
		(layer "In4.Cu")
		(net "P5E_CPU0_P1_TX_DP<0>")
	)
	(segment
		(start 363.469936 -347.856048)
		(end 353.936554 -359.494836)
		(width 0.14224)
		(layer "In4.Cu")
		(net "P5E_CPU0_P1_TX_DP<0>")
	)
	(segment
		(start 329.046078 -390.46023)
		(end 329.667362 -390.46023)
		(width 0.14224)
		(layer "In4.Cu")
		(net "P5E_CPU0_P1_TX_DP<0>")
	)
	(segment
		(start 345.16822 -294.013382)
		(end 345.1987 -294.031162)
		(width 0.1143)
		(layer "In4.Cu")
		(net "P5E_CPU0_P1_TX_DP<0>")
	)
	(segment
		(start 345.1987 -294.640762)
		(end 345.16822 -294.658542)
		(width 0.1143)
		(layer "In4.Cu")
		(net "P5E_CPU0_P1_TX_DP<0>")
	)
	(segment
		(start 356.291388 -320.57975)
		(end 360.25963 -325.414894)
		(width 0.14224)
		(layer "In4.Cu")
		(net "P5E_CPU0_P1_TX_DP<0>")
	)
	(segment
		(start 344.415872 -296.00144)
		(end 344.415872 -296.159936)
		(width 0.1143)
		(layer "In4.Cu")
		(net "P5E_CPU0_P1_TX_DP<0>")
	)
	(segment
		(start 345.129104 -293.990522)
		(end 345.16822 -294.013382)
		(width 0.1143)
		(layer "In4.Cu")
		(net "P5E_CPU0_P1_TX_DP<0>")
	)
	(segment
		(start 345.16822 -289.153346)
		(end 345.1987 -289.171126)
		(width 0.1143)
		(layer "In4.Cu")
		(net "P5E_CPU0_P1_TX_DP<0>")
	)
	(segment
		(start 344.370152 -296.234104)
		(end 344.370152 -299.700188)
		(width 0.14224)
		(layer "In4.Cu")
		(net "P5E_CPU0_P1_TX_DP<0>")
	)
	(segment
		(start 345.921076 -286.236156)
		(end 346.219018 -286.236156)
		(width 0.1143)
		(layer "In4.Cu")
		(net "P5E_CPU0_P1_TX_DP<0>")
	)
	(segment
		(start 344.885772 -295.145968)
		(end 344.885772 -295.347136)
		(width 0.1143)
		(layer "In4.Cu")
		(net "P5E_CPU0_P1_TX_DP<0>")
	)
	(segment
		(start 363.996732 -336.33283)
		(end 364.004098 -336.373724)
		(width 0.14224)
		(layer "In4.Cu")
		(net "P5E_CPU0_P1_TX_DP<0>")
	)
	(segment
		(start 364.31982 -339.072474)
		(end 364.31982 -345.951048)
		(width 0.14224)
		(layer "In4.Cu")
		(net "P5E_CPU0_P1_TX_DP<0>")
	)
	(segment
		(start 346.219018 -286.236156)
		(end 346.288868 -286.306006)
		(width 0.1143)
		(layer "In4.Cu")
		(net "P5E_CPU0_P1_TX_DP<0>")
	)
	(segment
		(start 345.16822 -294.658542)
		(end 345.129104 -294.681402)
		(width 0.1143)
		(layer "In4.Cu")
		(net "P5E_CPU0_P1_TX_DP<0>")
	)
	(segment
		(start 360.25963 -325.414894)
		(end 363.996732 -336.33283)
		(width 0.14224)
		(layer "In4.Cu")
		(net "P5E_CPU0_P1_TX_DP<0>")
	)
	(segment
		(start 344.729816 -290.590224)
		(end 344.698066 -290.608512)
		(width 0.1143)
		(layer "In4.Cu")
		(net "P5E_CPU0_P1_TX_DP<0>")
	)
	(segment
		(start 328.654156 -390.237726)
		(end 328.756772 -390.340342)
		(width 0.14224)
		(layer "In4.Cu")
		(net "P5E_CPU0_P1_TX_DP<0>")
	)
	(segment
		(start 345.129104 -292.37051)
		(end 345.16822 -292.39337)
		(width 0.1143)
		(layer "In4.Cu")
		(net "P5E_CPU0_P1_TX_DP<0>")
	)
	(segment
		(start 344.65895 -291.560758)
		(end 344.722196 -291.597334)
		(width 0.1143)
		(layer "In4.Cu")
		(net "P5E_CPU0_P1_TX_DP<0>")
	)
	(segment
		(start 345.129104 -289.130486)
		(end 345.16822 -289.153346)
		(width 0.1143)
		(layer "In4.Cu")
		(net "P5E_CPU0_P1_TX_DP<0>")
	)
	(segment
		(start 345.200732 -288.159698)
		(end 345.16822 -288.178494)
		(width 0.1143)
		(layer "In4.Cu")
		(net "P5E_CPU0_P1_TX_DP<0>")
	)
	(segment
		(start 329.667362 -390.46023)
		(end 329.958192 -390.75106)
		(width 0.14224)
		(layer "In4.Cu")
		(net "P5E_CPU0_P1_TX_DP<0>")
	)
	(arc
		(start 329.497436 -374.143524)
		(mid 328.735623 -374.924471)
		(end 328.45756 -375.979436)
		(width 0.14224)
		(layer "In4.Cu")
		(net "P5E_CPU0_P1_TX_DP<0>")
	)
	(arc
		(start 344.722196 -291.597334)
		(mid 344.828704 -291.732023)
		(end 344.883486 -291.894768)
		(width 0.1143)
		(layer "In4.Cu")
		(net "P5E_CPU0_P1_TX_DP<0>")
	)
	(arc
		(start 344.651076 -290.63696)
		(mid 344.41557 -291.100947)
		(end 344.65895 -291.560758)
		(width 0.1143)
		(layer "In4.Cu")
		(net "P5E_CPU0_P1_TX_DP<0>")
	)
	(arc
		(start 344.886026 -291.922962)
		(mid 344.952591 -292.172221)
		(end 345.123008 -292.365938)
		(width 0.1143)
		(layer "In4.Cu")
		(net "P5E_CPU0_P1_TX_DP<0>")
	)
	(arc
		(start 345.123008 -292.365938)
		(mid 345.126048 -292.368234)
		(end 345.129104 -292.37051)
		(width 0.1143)
		(layer "In4.Cu")
		(net "P5E_CPU0_P1_TX_DP<0>")
	)
	(arc
		(start 345.1987 -289.171126)
		(mid 345.355677 -289.475926)
		(end 345.1987 -289.780726)
		(width 0.1143)
		(layer "In4.Cu")
		(net "P5E_CPU0_P1_TX_DP<0>")
	)
	(arc
		(start 328.45756 -389.763254)
		(mid 328.508657 -390.020046)
		(end 328.654156 -390.237726)
		(width 0.14224)
		(layer "In4.Cu")
		(net "P5E_CPU0_P1_TX_DP<0>")
	)
	(arc
		(start 328.756772 -390.340342)
		(mid 328.889492 -390.429086)
		(end 329.046078 -390.46023)
		(width 0.14224)
		(layer "In4.Cu")
		(net "P5E_CPU0_P1_TX_DP<0>")
	)
	(arc
		(start 344.50909 -295.77665)
		(mid 344.440124 -295.87977)
		(end 344.415872 -296.00144)
		(width 0.1143)
		(layer "In4.Cu")
		(net "P5E_CPU0_P1_TX_DP<0>")
	)
	(arc
		(start 364.31982 -345.951048)
		(mid 364.02239 -346.960432)
		(end 363.469936 -347.856048)
		(width 0.14224)
		(layer "In4.Cu")
		(net "P5E_CPU0_P1_TX_DP<0>")
	)
	(arc
		(start 364.152688 -337.200494)
		(mid 364.2779 -338.132766)
		(end 364.31982 -339.072474)
		(width 0.14224)
		(layer "In4.Cu")
		(net "P5E_CPU0_P1_TX_DP<0>")
	)
	(arc
		(start 345.355672 -287.856168)
		(mid 345.314706 -288.026574)
		(end 345.200732 -288.159698)
		(width 0.1143)
		(layer "In4.Cu")
		(net "P5E_CPU0_P1_TX_DP<0>")
	)
	(arc
		(start 344.661744 -290.629594)
		(mid 344.656388 -290.633245)
		(end 344.651076 -290.63696)
		(width 0.1143)
		(layer "In4.Cu")
		(net "P5E_CPU0_P1_TX_DP<0>")
	)
	(arc
		(start 344.885772 -290.285932)
		(mid 344.844517 -290.456903)
		(end 344.729816 -290.590224)
		(width 0.1143)
		(layer "In4.Cu")
		(net "P5E_CPU0_P1_TX_DP<0>")
	)
	(arc
		(start 345.601544 -287.389824)
		(mid 345.420892 -287.592569)
		(end 345.355672 -287.856168)
		(width 0.1143)
		(layer "In4.Cu")
		(net "P5E_CPU0_P1_TX_DP<0>")
	)
	(arc
		(start 345.1987 -292.41115)
		(mid 345.355677 -292.71595)
		(end 345.1987 -293.02075)
		(width 0.1143)
		(layer "In4.Cu")
		(net "P5E_CPU0_P1_TX_DP<0>")
	)
	(arc
		(start 345.129104 -294.681402)
		(mid 344.950306 -294.883746)
		(end 344.885772 -295.145968)
		(width 0.1143)
		(layer "In4.Cu")
		(net "P5E_CPU0_P1_TX_DP<0>")
	)
	(arc
		(start 344.883486 -291.894768)
		(mid 344.885156 -291.908829)
		(end 344.886026 -291.922962)
		(width 0.1143)
		(layer "In4.Cu")
		(net "P5E_CPU0_P1_TX_DP<0>")
	)
	(arc
		(start 346.288868 -286.306006)
		(mid 346.23716 -286.436989)
		(end 346.140786 -286.539686)
		(width 0.1143)
		(layer "In4.Cu")
		(net "P5E_CPU0_P1_TX_DP<0>")
	)
	(arc
		(start 345.129104 -289.821366)
		(mid 344.950291 -290.023716)
		(end 344.885772 -290.285932)
		(width 0.1143)
		(layer "In4.Cu")
		(net "P5E_CPU0_P1_TX_DP<0>")
	)
	(arc
		(start 345.825826 -287.045908)
		(mid 345.784571 -287.216879)
		(end 345.66987 -287.3502)
		(width 0.1143)
		(layer "In4.Cu")
		(net "P5E_CPU0_P1_TX_DP<0>")
	)
	(arc
		(start 345.129104 -288.201354)
		(mid 344.885777 -288.66592)
		(end 345.129104 -289.130486)
		(width 0.1143)
		(layer "In4.Cu")
		(net "P5E_CPU0_P1_TX_DP<0>")
	)
	(arc
		(start 345.129104 -293.06139)
		(mid 344.885777 -293.525956)
		(end 345.129104 -293.990522)
		(width 0.1143)
		(layer "In4.Cu")
		(net "P5E_CPU0_P1_TX_DP<0>")
	)
	(arc
		(start 344.885772 -295.347136)
		(mid 344.876066 -295.395931)
		(end 344.848434 -295.437306)
		(width 0.1143)
		(layer "In4.Cu")
		(net "P5E_CPU0_P1_TX_DP<0>")
	)
	(arc
		(start 346.069158 -286.581342)
		(mid 345.890345 -286.783692)
		(end 345.825826 -287.045908)
		(width 0.1143)
		(layer "In4.Cu")
		(net "P5E_CPU0_P1_TX_DP<0>")
	)
	(arc
		(start 345.1987 -294.031162)
		(mid 345.355677 -294.335962)
		(end 345.1987 -294.640762)
		(width 0.1143)
		(layer "In4.Cu")
		(net "P5E_CPU0_P1_TX_DP<0>")
	)
	(segment
		(start 347.451934 -378.39142)
		(end 347.451934 -377.68784)
		(width 0.12954)
		(layer "F.Cu")
		(net "P5E_CPU0_P1_TX_DN<9>")
	)
	(segment
		(start 347.747844 -378.68733)
		(end 347.451934 -378.39142)
		(width 0.12954)
		(layer "F.Cu")
		(net "P5E_CPU0_P1_TX_DN<9>")
	)
	(segment
		(start 352.968052 -287.59023)
		(end 352.5012 -287.856168)
		(width 0.12954)
		(layer "F.Cu")
		(net "P5E_CPU0_P1_TX_DN<9>")
	)
	(segment
		(start 347.451934 -377.68784)
		(end 347.722444 -377.41733)
		(width 0.12954)
		(layer "F.Cu")
		(net "P5E_CPU0_P1_TX_DN<9>")
	)
	(segment
		(start 352.783394 -288.987992)
		(end 352.784156 -288.9885)
		(width 0.1143)
		(layer "In4.Cu")
		(net "P5E_CPU0_P1_TX_DN<9>")
	)
	(segment
		(start 359.621074 -310.831738)
		(end 367.725198 -320.705988)
		(width 0.14224)
		(layer "In4.Cu")
		(net "P5E_CPU0_P1_TX_DN<9>")
	)
	(segment
		(start 353.262692 -291.423598)
		(end 353.29241 -291.44087)
		(width 0.1143)
		(layer "In4.Cu")
		(net "P5E_CPU0_P1_TX_DN<9>")
	)
	(segment
		(start 356.35311 -305.941222)
		(end 359.621074 -310.831738)
		(width 0.14224)
		(layer "In4.Cu")
		(net "P5E_CPU0_P1_TX_DN<9>")
	)
	(segment
		(start 373.231664 -337.919822)
		(end 373.231664 -348.187518)
		(width 0.14224)
		(layer "In4.Cu")
		(net "P5E_CPU0_P1_TX_DN<9>")
	)
	(segment
		(start 362.148628 -366.051338)
		(end 347.66123 -375.73204)
		(width 0.14224)
		(layer "In4.Cu")
		(net "P5E_CPU0_P1_TX_DN<9>")
	)
	(segment
		(start 353.53625 -295.145714)
		(end 353.53625 -295.284144)
		(width 0.1143)
		(layer "In4.Cu")
		(net "P5E_CPU0_P1_TX_DN<9>")
	)
	(segment
		(start 353.148138 -295.919652)
		(end 353.148138 -296.032936)
		(width 0.1143)
		(layer "In4.Cu")
		(net "P5E_CPU0_P1_TX_DN<9>")
	)
	(segment
		(start 353.398582 -295.616884)
		(end 353.185476 -295.829736)
		(width 0.1143)
		(layer "In4.Cu")
		(net "P5E_CPU0_P1_TX_DN<9>")
	)
	(segment
		(start 353.261168 -291.422582)
		(end 353.262692 -291.423598)
		(width 0.1143)
		(layer "In4.Cu")
		(net "P5E_CPU0_P1_TX_DN<9>")
	)
	(segment
		(start 347.431614 -377.1265)
		(end 347.722444 -377.41733)
		(width 0.14224)
		(layer "In4.Cu")
		(net "P5E_CPU0_P1_TX_DN<9>")
	)
	(segment
		(start 352.28149 -288.159698)
		(end 352.314002 -288.178494)
		(width 0.1143)
		(layer "In4.Cu")
		(net "P5E_CPU0_P1_TX_DN<9>")
	)
	(segment
		(start 353.193858 -296.078656)
		(end 353.193858 -296.107104)
		(width 0.1143)
		(layer "In4.Cu")
		(net "P5E_CPU0_P1_TX_DN<9>")
	)
	(segment
		(start 353.763072 -293.180516)
		(end 353.723956 -293.203376)
		(width 0.1143)
		(layer "In4.Cu")
		(net "P5E_CPU0_P1_TX_DN<9>")
	)
	(segment
		(start 352.752406 -288.970212)
		(end 352.783394 -288.987992)
		(width 0.1143)
		(layer "In4.Cu")
		(net "P5E_CPU0_P1_TX_DN<9>")
	)
	(segment
		(start 352.203258 -287.856168)
		(end 352.133408 -287.926018)
		(width 0.1143)
		(layer "In4.Cu")
		(net "P5E_CPU0_P1_TX_DN<9>")
	)
	(segment
		(start 373.21744 -348.313248)
		(end 372.632986 -350.84512)
		(width 0.14224)
		(layer "In4.Cu")
		(net "P5E_CPU0_P1_TX_DN<9>")
	)
	(segment
		(start 353.193858 -296.107104)
		(end 353.193858 -298.288964)
		(width 0.14224)
		(layer "In4.Cu")
		(net "P5E_CPU0_P1_TX_DN<9>")
	)
	(segment
		(start 353.275138 -290.761166)
		(end 353.274884 -290.761166)
		(width 0.1143)
		(layer "In4.Cu")
		(net "P5E_CPU0_P1_TX_DN<9>")
	)
	(segment
		(start 353.241356 -289.79114)
		(end 353.293172 -289.821366)
		(width 0.1143)
		(layer "In4.Cu")
		(net "P5E_CPU0_P1_TX_DN<9>")
	)
	(segment
		(start 353.293172 -290.750498)
		(end 353.275138 -290.761166)
		(width 0.1143)
		(layer "In4.Cu")
		(net "P5E_CPU0_P1_TX_DN<9>")
	)
	(segment
		(start 353.723956 -292.228524)
		(end 353.763072 -292.251384)
		(width 0.1143)
		(layer "In4.Cu")
		(net "P5E_CPU0_P1_TX_DN<9>")
	)
	(segment
		(start 353.693476 -293.830756)
		(end 353.723956 -293.848536)
		(width 0.1143)
		(layer "In4.Cu")
		(net "P5E_CPU0_P1_TX_DN<9>")
	)
	(segment
		(start 353.05365 -289.456622)
		(end 353.05365 -289.466274)
		(width 0.1143)
		(layer "In4.Cu")
		(net "P5E_CPU0_P1_TX_DN<9>")
	)
	(segment
		(start 347.431614 -376.161808)
		(end 347.431614 -377.1265)
		(width 0.14224)
		(layer "In4.Cu")
		(net "P5E_CPU0_P1_TX_DN<9>")
	)
	(segment
		(start 353.536504 -295.145968)
		(end 353.53625 -295.145714)
		(width 0.1143)
		(layer "In4.Cu")
		(net "P5E_CPU0_P1_TX_DN<9>")
	)
	(segment
		(start 353.723956 -293.203376)
		(end 353.693476 -293.221156)
		(width 0.1143)
		(layer "In4.Cu")
		(net "P5E_CPU0_P1_TX_DN<9>")
	)
	(segment
		(start 353.723956 -293.848536)
		(end 353.763072 -293.871396)
		(width 0.1143)
		(layer "In4.Cu")
		(net "P5E_CPU0_P1_TX_DN<9>")
	)
	(segment
		(start 372.538752 -351.057464)
		(end 362.148628 -366.051338)
		(width 0.14224)
		(layer "In4.Cu")
		(net "P5E_CPU0_P1_TX_DN<9>")
	)
	(segment
		(start 367.725198 -320.705988)
		(end 368.685318 -322.543424)
		(width 0.14224)
		(layer "In4.Cu")
		(net "P5E_CPU0_P1_TX_DN<9>")
	)
	(segment
		(start 372.485158 -333.676752)
		(end 373.215916 -337.744308)
		(width 0.14224)
		(layer "In4.Cu")
		(net "P5E_CPU0_P1_TX_DN<9>")
	)
	(segment
		(start 353.246182 -291.413946)
		(end 353.261168 -291.422582)
		(width 0.1143)
		(layer "In4.Cu")
		(net "P5E_CPU0_P1_TX_DN<9>")
	)
	(segment
		(start 353.148138 -296.032936)
		(end 353.193858 -296.078656)
		(width 0.1143)
		(layer "In4.Cu")
		(net "P5E_CPU0_P1_TX_DN<9>")
	)
	(segment
		(start 352.5012 -287.856168)
		(end 352.203258 -287.856168)
		(width 0.1143)
		(layer "In4.Cu")
		(net "P5E_CPU0_P1_TX_DN<9>")
	)
	(segment
		(start 353.20351 -298.337732)
		(end 356.35311 -305.941222)
		(width 0.14224)
		(layer "In4.Cu")
		(net "P5E_CPU0_P1_TX_DN<9>")
	)
	(segment
		(start 353.274884 -290.761166)
		(end 353.253548 -290.773612)
		(width 0.1143)
		(layer "In4.Cu")
		(net "P5E_CPU0_P1_TX_DN<9>")
	)
	(segment
		(start 353.763072 -294.800528)
		(end 353.693476 -294.841168)
		(width 0.1143)
		(layer "In4.Cu")
		(net "P5E_CPU0_P1_TX_DN<9>")
	)
	(segment
		(start 368.685318 -322.543424)
		(end 372.453408 -333.554324)
		(width 0.14224)
		(layer "In4.Cu")
		(net "P5E_CPU0_P1_TX_DN<9>")
	)
	(segment
		(start 352.314002 -288.178494)
		(end 352.353118 -288.201354)
		(width 0.1143)
		(layer "In4.Cu")
		(net "P5E_CPU0_P1_TX_DN<9>")
	)
	(segment
		(start 353.693476 -292.210744)
		(end 353.723956 -292.228524)
		(width 0.1143)
		(layer "In4.Cu")
		(net "P5E_CPU0_P1_TX_DN<9>")
	)
	(arc
		(start 352.784156 -288.9885)
		(mid 352.98148 -289.18654)
		(end 353.05365 -289.456622)
		(width 0.1143)
		(layer "In4.Cu")
		(net "P5E_CPU0_P1_TX_DN<9>")
	)
	(arc
		(start 352.133408 -287.926018)
		(mid 352.185116 -288.057001)
		(end 352.28149 -288.159698)
		(width 0.1143)
		(layer "In4.Cu")
		(net "P5E_CPU0_P1_TX_DN<9>")
	)
	(arc
		(start 347.66123 -375.73204)
		(mid 347.492582 -375.918165)
		(end 347.431614 -376.161808)
		(width 0.14224)
		(layer "In4.Cu")
		(net "P5E_CPU0_P1_TX_DN<9>")
	)
	(arc
		(start 353.05365 -289.466274)
		(mid 353.103956 -289.653862)
		(end 353.241356 -289.79114)
		(width 0.1143)
		(layer "In4.Cu")
		(net "P5E_CPU0_P1_TX_DN<9>")
	)
	(arc
		(start 353.293172 -291.441378)
		(mid 353.471985 -291.643728)
		(end 353.536504 -291.905944)
		(width 0.1143)
		(layer "In4.Cu")
		(net "P5E_CPU0_P1_TX_DN<9>")
	)
	(arc
		(start 353.193858 -298.288964)
		(mid 353.196304 -298.313817)
		(end 353.20351 -298.337732)
		(width 0.14224)
		(layer "In4.Cu")
		(net "P5E_CPU0_P1_TX_DN<9>")
	)
	(arc
		(start 353.253548 -290.773612)
		(mid 353.068028 -291.091669)
		(end 353.246182 -291.413946)
		(width 0.1143)
		(layer "In4.Cu")
		(net "P5E_CPU0_P1_TX_DN<9>")
	)
	(arc
		(start 353.763072 -292.251384)
		(mid 354.006399 -292.71595)
		(end 353.763072 -293.180516)
		(width 0.1143)
		(layer "In4.Cu")
		(net "P5E_CPU0_P1_TX_DN<9>")
	)
	(arc
		(start 352.353118 -288.201354)
		(mid 352.531931 -288.403704)
		(end 352.59645 -288.66592)
		(width 0.1143)
		(layer "In4.Cu")
		(net "P5E_CPU0_P1_TX_DN<9>")
	)
	(arc
		(start 353.185476 -295.829736)
		(mid 353.157857 -295.870976)
		(end 353.148138 -295.919652)
		(width 0.1143)
		(layer "In4.Cu")
		(net "P5E_CPU0_P1_TX_DN<9>")
	)
	(arc
		(start 353.293172 -289.821366)
		(mid 353.536389 -290.285932)
		(end 353.293172 -290.750498)
		(width 0.1143)
		(layer "In4.Cu")
		(net "P5E_CPU0_P1_TX_DN<9>")
	)
	(arc
		(start 373.231664 -348.187518)
		(mid 373.228124 -348.250787)
		(end 373.21744 -348.313248)
		(width 0.14224)
		(layer "In4.Cu")
		(net "P5E_CPU0_P1_TX_DN<9>")
	)
	(arc
		(start 352.59645 -288.66592)
		(mid 352.637705 -288.836891)
		(end 352.752406 -288.970212)
		(width 0.1143)
		(layer "In4.Cu")
		(net "P5E_CPU0_P1_TX_DN<9>")
	)
	(arc
		(start 372.632986 -350.84512)
		(mid 372.595967 -350.955773)
		(end 372.538752 -351.057464)
		(width 0.14224)
		(layer "In4.Cu")
		(net "P5E_CPU0_P1_TX_DN<9>")
	)
	(arc
		(start 373.215916 -337.744308)
		(mid 373.227692 -337.831715)
		(end 373.231664 -337.919822)
		(width 0.14224)
		(layer "In4.Cu")
		(net "P5E_CPU0_P1_TX_DN<9>")
	)
	(arc
		(start 353.29241 -291.44087)
		(mid 353.292791 -291.441124)
		(end 353.293172 -291.441378)
		(width 0.1143)
		(layer "In4.Cu")
		(net "P5E_CPU0_P1_TX_DN<9>")
	)
	(arc
		(start 353.536504 -291.905944)
		(mid 353.578053 -292.077366)
		(end 353.693476 -292.210744)
		(width 0.1143)
		(layer "In4.Cu")
		(net "P5E_CPU0_P1_TX_DN<9>")
	)
	(arc
		(start 353.763072 -293.871396)
		(mid 354.006399 -294.335962)
		(end 353.763072 -294.800528)
		(width 0.1143)
		(layer "In4.Cu")
		(net "P5E_CPU0_P1_TX_DN<9>")
	)
	(arc
		(start 372.453408 -333.554324)
		(mid 372.471611 -333.614934)
		(end 372.485158 -333.676752)
		(width 0.14224)
		(layer "In4.Cu")
		(net "P5E_CPU0_P1_TX_DN<9>")
	)
	(arc
		(start 353.693476 -294.841168)
		(mid 353.578049 -294.974544)
		(end 353.536504 -295.145968)
		(width 0.1143)
		(layer "In4.Cu")
		(net "P5E_CPU0_P1_TX_DN<9>")
	)
	(arc
		(start 353.53625 -295.284144)
		(mid 353.50051 -295.464201)
		(end 353.398582 -295.616884)
		(width 0.1143)
		(layer "In4.Cu")
		(net "P5E_CPU0_P1_TX_DN<9>")
	)
	(arc
		(start 353.693476 -293.221156)
		(mid 353.536499 -293.525956)
		(end 353.693476 -293.830756)
		(width 0.1143)
		(layer "In4.Cu")
		(net "P5E_CPU0_P1_TX_DN<9>")
	)
	(segment
		(start 345.750134 -380.85522)
		(end 345.750134 -380.15164)
		(width 0.12954)
		(layer "F.Cu")
		(net "P5E_CPU0_P1_TX_DN<8>")
	)
	(segment
		(start 345.750134 -380.15164)
		(end 346.020644 -379.88113)
		(width 0.12954)
		(layer "F.Cu")
		(net "P5E_CPU0_P1_TX_DN<8>")
	)
	(segment
		(start 346.046044 -381.15113)
		(end 345.750134 -380.85522)
		(width 0.12954)
		(layer "F.Cu")
		(net "P5E_CPU0_P1_TX_DN<8>")
	)
	(segment
		(start 352.968052 -290.83)
		(end 352.5012 -291.095938)
		(width 0.12954)
		(layer "F.Cu")
		(net "P5E_CPU0_P1_TX_DN<8>")
	)
	(segment
		(start 352.248724 -296.078656)
		(end 352.248724 -296.107104)
		(width 0.1143)
		(layer "In4.Cu")
		(net "P5E_CPU0_P1_TX_DN<8>")
	)
	(segment
		(start 352.203004 -295.924478)
		(end 352.203004 -296.032936)
		(width 0.1143)
		(layer "In4.Cu")
		(net "P5E_CPU0_P1_TX_DN<8>")
	)
	(segment
		(start 371.70614 -350.461072)
		(end 361.258104 -365.51616)
		(width 0.14224)
		(layer "In4.Cu")
		(net "P5E_CPU0_P1_TX_DN<8>")
	)
	(segment
		(start 352.314256 -291.418772)
		(end 352.35134 -291.440362)
		(width 0.1143)
		(layer "In4.Cu")
		(net "P5E_CPU0_P1_TX_DN<8>")
	)
	(segment
		(start 352.203258 -291.095938)
		(end 352.133408 -291.165788)
		(width 0.1143)
		(layer "In4.Cu")
		(net "P5E_CPU0_P1_TX_DN<8>")
	)
	(segment
		(start 352.282506 -291.40023)
		(end 352.313494 -291.41801)
		(width 0.1143)
		(layer "In4.Cu")
		(net "P5E_CPU0_P1_TX_DN<8>")
	)
	(segment
		(start 352.823272 -293.871396)
		(end 352.825304 -293.87292)
		(width 0.1143)
		(layer "In4.Cu")
		(net "P5E_CPU0_P1_TX_DN<8>")
	)
	(segment
		(start 352.271076 -298.522898)
		(end 355.52888 -306.388008)
		(width 0.14224)
		(layer "In4.Cu")
		(net "P5E_CPU0_P1_TX_DN<8>")
	)
	(segment
		(start 352.503232 -295.57218)
		(end 352.240342 -295.834308)
		(width 0.1143)
		(layer "In4.Cu")
		(net "P5E_CPU0_P1_TX_DN<8>")
	)
	(segment
		(start 372.266464 -348.27845)
		(end 371.800374 -350.250506)
		(width 0.14224)
		(layer "In4.Cu")
		(net "P5E_CPU0_P1_TX_DN<8>")
	)
	(segment
		(start 352.203004 -296.032936)
		(end 352.248724 -296.078656)
		(width 0.1143)
		(layer "In4.Cu")
		(net "P5E_CPU0_P1_TX_DN<8>")
	)
	(segment
		(start 361.258104 -365.51616)
		(end 346.240862 -375.550684)
		(width 0.14224)
		(layer "In4.Cu")
		(net "P5E_CPU0_P1_TX_DN<8>")
	)
	(segment
		(start 352.248724 -296.107104)
		(end 352.248724 -298.41063)
		(width 0.14224)
		(layer "In4.Cu")
		(net "P5E_CPU0_P1_TX_DN<8>")
	)
	(segment
		(start 355.52888 -306.388008)
		(end 358.87025 -311.38876)
		(width 0.14224)
		(layer "In4.Cu")
		(net "P5E_CPU0_P1_TX_DN<8>")
	)
	(segment
		(start 372.281196 -337.974178)
		(end 372.281196 -348.152974)
		(width 0.14224)
		(layer "In4.Cu")
		(net "P5E_CPU0_P1_TX_DN<8>")
	)
	(segment
		(start 366.942624 -321.225164)
		(end 367.744248 -322.758308)
		(width 0.14224)
		(layer "In4.Cu")
		(net "P5E_CPU0_P1_TX_DN<8>")
	)
	(segment
		(start 352.313494 -291.41801)
		(end 352.314256 -291.418518)
		(width 0.1143)
		(layer "In4.Cu")
		(net "P5E_CPU0_P1_TX_DN<8>")
	)
	(segment
		(start 345.729814 -379.5903)
		(end 346.020644 -379.88113)
		(width 0.14224)
		(layer "In4.Cu")
		(net "P5E_CPU0_P1_TX_DN<8>")
	)
	(segment
		(start 352.76282 -293.83609)
		(end 352.82251 -293.870888)
		(width 0.1143)
		(layer "In4.Cu")
		(net "P5E_CPU0_P1_TX_DN<8>")
	)
	(segment
		(start 352.763582 -293.215314)
		(end 352.76282 -293.215822)
		(width 0.1143)
		(layer "In4.Cu")
		(net "P5E_CPU0_P1_TX_DN<8>")
	)
	(segment
		(start 367.744248 -322.758308)
		(end 371.55247 -333.884778)
		(width 0.14224)
		(layer "In4.Cu")
		(net "P5E_CPU0_P1_TX_DN<8>")
	)
	(segment
		(start 352.825304 -294.799004)
		(end 352.752406 -294.841676)
		(width 0.1143)
		(layer "In4.Cu")
		(net "P5E_CPU0_P1_TX_DN<8>")
	)
	(segment
		(start 352.823272 -293.180516)
		(end 352.763582 -293.215314)
		(width 0.1143)
		(layer "In4.Cu")
		(net "P5E_CPU0_P1_TX_DN<8>")
	)
	(segment
		(start 352.762312 -293.83609)
		(end 352.76282 -293.83609)
		(width 0.1143)
		(layer "In4.Cu")
		(net "P5E_CPU0_P1_TX_DN<8>")
	)
	(segment
		(start 352.76282 -293.215822)
		(end 352.762566 -293.215822)
		(width 0.1143)
		(layer "In4.Cu")
		(net "P5E_CPU0_P1_TX_DN<8>")
	)
	(segment
		(start 345.729814 -376.50674)
		(end 345.729814 -379.5903)
		(width 0.14224)
		(layer "In4.Cu")
		(net "P5E_CPU0_P1_TX_DN<8>")
	)
	(segment
		(start 352.314256 -291.418518)
		(end 352.314256 -291.418772)
		(width 0.1143)
		(layer "In4.Cu")
		(net "P5E_CPU0_P1_TX_DN<8>")
	)
	(segment
		(start 371.58422 -334.007206)
		(end 372.265448 -337.798664)
		(width 0.14224)
		(layer "In4.Cu")
		(net "P5E_CPU0_P1_TX_DN<8>")
	)
	(segment
		(start 352.59645 -295.145968)
		(end 352.59645 -295.34739)
		(width 0.1143)
		(layer "In4.Cu")
		(net "P5E_CPU0_P1_TX_DN<8>")
	)
	(segment
		(start 358.87025 -311.38876)
		(end 366.942624 -321.225164)
		(width 0.14224)
		(layer "In4.Cu")
		(net "P5E_CPU0_P1_TX_DN<8>")
	)
	(segment
		(start 352.752406 -292.210236)
		(end 352.823272 -292.251384)
		(width 0.1143)
		(layer "In4.Cu")
		(net "P5E_CPU0_P1_TX_DN<8>")
	)
	(segment
		(start 352.5012 -291.095938)
		(end 352.203258 -291.095938)
		(width 0.1143)
		(layer "In4.Cu")
		(net "P5E_CPU0_P1_TX_DN<8>")
	)
	(arc
		(start 352.59645 -295.34739)
		(mid 352.572228 -295.469072)
		(end 352.503232 -295.57218)
		(width 0.1143)
		(layer "In4.Cu")
		(net "P5E_CPU0_P1_TX_DN<8>")
	)
	(arc
		(start 346.240862 -375.550684)
		(mid 345.865609 -375.964709)
		(end 345.729814 -376.50674)
		(width 0.14224)
		(layer "In4.Cu")
		(net "P5E_CPU0_P1_TX_DN<8>")
	)
	(arc
		(start 372.265448 -337.798664)
		(mid 372.277224 -337.886071)
		(end 372.281196 -337.974178)
		(width 0.14224)
		(layer "In4.Cu")
		(net "P5E_CPU0_P1_TX_DN<8>")
	)
	(arc
		(start 372.281196 -348.152974)
		(mid 372.277466 -348.216138)
		(end 372.266464 -348.27845)
		(width 0.14224)
		(layer "In4.Cu")
		(net "P5E_CPU0_P1_TX_DN<8>")
	)
	(arc
		(start 352.35134 -291.440362)
		(mid 352.512492 -291.63311)
		(end 352.592894 -291.871146)
		(width 0.1143)
		(layer "In4.Cu")
		(net "P5E_CPU0_P1_TX_DN<8>")
	)
	(arc
		(start 352.240342 -295.834308)
		(mid 352.212699 -295.875678)
		(end 352.203004 -295.924478)
		(width 0.1143)
		(layer "In4.Cu")
		(net "P5E_CPU0_P1_TX_DN<8>")
	)
	(arc
		(start 352.82251 -293.870888)
		(mid 352.822891 -293.871142)
		(end 352.823272 -293.871396)
		(width 0.1143)
		(layer "In4.Cu")
		(net "P5E_CPU0_P1_TX_DN<8>")
	)
	(arc
		(start 352.825304 -293.87292)
		(mid 353.067815 -294.335962)
		(end 352.825304 -294.799004)
		(width 0.1143)
		(layer "In4.Cu")
		(net "P5E_CPU0_P1_TX_DN<8>")
	)
	(arc
		(start 352.762566 -293.215822)
		(mid 352.584024 -293.525846)
		(end 352.762312 -293.83609)
		(width 0.1143)
		(layer "In4.Cu")
		(net "P5E_CPU0_P1_TX_DN<8>")
	)
	(arc
		(start 352.592894 -291.871146)
		(mid 352.595238 -291.893326)
		(end 352.59645 -291.915596)
		(width 0.1143)
		(layer "In4.Cu")
		(net "P5E_CPU0_P1_TX_DN<8>")
	)
	(arc
		(start 352.59645 -291.915596)
		(mid 352.639843 -292.081228)
		(end 352.752406 -292.210236)
		(width 0.1143)
		(layer "In4.Cu")
		(net "P5E_CPU0_P1_TX_DN<8>")
	)
	(arc
		(start 371.800374 -350.250506)
		(mid 371.763149 -350.360218)
		(end 371.70614 -350.461072)
		(width 0.14224)
		(layer "In4.Cu")
		(net "P5E_CPU0_P1_TX_DN<8>")
	)
	(arc
		(start 371.55247 -333.884778)
		(mid 371.570679 -333.945387)
		(end 371.58422 -334.007206)
		(width 0.14224)
		(layer "In4.Cu")
		(net "P5E_CPU0_P1_TX_DN<8>")
	)
	(arc
		(start 352.248724 -298.41063)
		(mid 352.254366 -298.467866)
		(end 352.271076 -298.522898)
		(width 0.14224)
		(layer "In4.Cu")
		(net "P5E_CPU0_P1_TX_DN<8>")
	)
	(arc
		(start 352.823272 -292.251384)
		(mid 353.066599 -292.71595)
		(end 352.823272 -293.180516)
		(width 0.1143)
		(layer "In4.Cu")
		(net "P5E_CPU0_P1_TX_DN<8>")
	)
	(arc
		(start 352.752406 -294.841676)
		(mid 352.63773 -294.97501)
		(end 352.59645 -295.145968)
		(width 0.1143)
		(layer "In4.Cu")
		(net "P5E_CPU0_P1_TX_DN<8>")
	)
	(arc
		(start 352.133408 -291.165788)
		(mid 352.185457 -291.297307)
		(end 352.282506 -291.40023)
		(width 0.1143)
		(layer "In4.Cu")
		(net "P5E_CPU0_P1_TX_DN<8>")
	)
	(segment
		(start 344.048334 -382.61544)
		(end 344.318844 -382.34493)
		(width 0.12954)
		(layer "F.Cu")
		(net "P5E_CPU0_P1_TX_DN<7>")
	)
	(segment
		(start 344.048334 -383.31902)
		(end 344.048334 -382.61544)
		(width 0.12954)
		(layer "F.Cu")
		(net "P5E_CPU0_P1_TX_DN<7>")
	)
	(segment
		(start 344.344244 -383.61493)
		(end 344.048334 -383.31902)
		(width 0.12954)
		(layer "F.Cu")
		(net "P5E_CPU0_P1_TX_DN<7>")
	)
	(segment
		(start 352.968052 -289.209988)
		(end 352.5012 -289.475926)
		(width 0.12954)
		(layer "F.Cu")
		(net "P5E_CPU0_P1_TX_DN<7>")
	)
	(segment
		(start 351.374202 -290.773358)
		(end 351.373186 -290.773866)
		(width 0.1143)
		(layer "In4.Cu")
		(net "P5E_CPU0_P1_TX_DN<7>")
	)
	(segment
		(start 351.251774 -298.498768)
		(end 354.706682 -306.83962)
		(width 0.14224)
		(layer "In4.Cu")
		(net "P5E_CPU0_P1_TX_DN<7>")
	)
	(segment
		(start 351.844102 -289.963352)
		(end 351.841308 -289.964876)
		(width 0.1143)
		(layer "In4.Cu")
		(net "P5E_CPU0_P1_TX_DN<7>")
	)
	(segment
		(start 351.813622 -292.210744)
		(end 351.844102 -292.228524)
		(width 0.1143)
		(layer "In4.Cu")
		(net "P5E_CPU0_P1_TX_DN<7>")
	)
	(segment
		(start 351.883218 -294.800528)
		(end 351.813622 -294.841168)
		(width 0.1143)
		(layer "In4.Cu")
		(net "P5E_CPU0_P1_TX_DN<7>")
	)
	(segment
		(start 351.65665 -295.145968)
		(end 351.656396 -295.145714)
		(width 0.1143)
		(layer "In4.Cu")
		(net "P5E_CPU0_P1_TX_DN<7>")
	)
	(segment
		(start 351.196402 -296.032936)
		(end 351.242122 -296.078656)
		(width 0.1143)
		(layer "In4.Cu")
		(net "P5E_CPU0_P1_TX_DN<7>")
	)
	(segment
		(start 351.410524 -291.439346)
		(end 351.413318 -291.441378)
		(width 0.1143)
		(layer "In4.Cu")
		(net "P5E_CPU0_P1_TX_DN<7>")
	)
	(segment
		(start 370.551964 -333.955136)
		(end 371.324886 -338.256118)
		(width 0.14224)
		(layer "In4.Cu")
		(net "P5E_CPU0_P1_TX_DN<7>")
	)
	(segment
		(start 351.37344 -291.41801)
		(end 351.374202 -291.418518)
		(width 0.1143)
		(layer "In4.Cu")
		(net "P5E_CPU0_P1_TX_DN<7>")
	)
	(segment
		(start 371.327172 -348.164658)
		(end 370.917216 -349.819214)
		(width 0.14224)
		(layer "In4.Cu")
		(net "P5E_CPU0_P1_TX_DN<7>")
	)
	(segment
		(start 351.844102 -292.228524)
		(end 351.883218 -292.251384)
		(width 0.1143)
		(layer "In4.Cu")
		(net "P5E_CPU0_P1_TX_DN<7>")
	)
	(segment
		(start 351.656396 -295.145714)
		(end 351.656396 -295.261792)
		(width 0.1143)
		(layer "In4.Cu")
		(net "P5E_CPU0_P1_TX_DN<7>")
	)
	(segment
		(start 351.844102 -293.848536)
		(end 351.883218 -293.871396)
		(width 0.1143)
		(layer "In4.Cu")
		(net "P5E_CPU0_P1_TX_DN<7>")
	)
	(segment
		(start 351.813622 -293.830756)
		(end 351.844102 -293.848536)
		(width 0.1143)
		(layer "In4.Cu")
		(net "P5E_CPU0_P1_TX_DN<7>")
	)
	(segment
		(start 371.340634 -338.431632)
		(end 371.340634 -348.047056)
		(width 0.14224)
		(layer "In4.Cu")
		(net "P5E_CPU0_P1_TX_DN<7>")
	)
	(segment
		(start 344.028014 -376.446542)
		(end 344.028014 -381.987298)
		(width 0.14224)
		(layer "In4.Cu")
		(net "P5E_CPU0_P1_TX_DN<7>")
	)
	(segment
		(start 351.50298 -295.632632)
		(end 351.23374 -295.901618)
		(width 0.1143)
		(layer "In4.Cu")
		(net "P5E_CPU0_P1_TX_DN<7>")
	)
	(segment
		(start 351.242122 -296.078656)
		(end 351.242122 -296.107104)
		(width 0.1143)
		(layer "In4.Cu")
		(net "P5E_CPU0_P1_TX_DN<7>")
	)
	(segment
		(start 344.075258 -382.101344)
		(end 344.318844 -382.34493)
		(width 0.14224)
		(layer "In4.Cu")
		(net "P5E_CPU0_P1_TX_DN<7>")
	)
	(segment
		(start 351.242122 -296.107104)
		(end 351.242122 -298.45)
		(width 0.14224)
		(layer "In4.Cu")
		(net "P5E_CPU0_P1_TX_DN<7>")
	)
	(segment
		(start 351.883218 -289.940492)
		(end 351.844102 -289.963352)
		(width 0.1143)
		(layer "In4.Cu")
		(net "P5E_CPU0_P1_TX_DN<7>")
	)
	(segment
		(start 351.342452 -291.40023)
		(end 351.37344 -291.41801)
		(width 0.1143)
		(layer "In4.Cu")
		(net "P5E_CPU0_P1_TX_DN<7>")
	)
	(segment
		(start 358.131364 -311.96534)
		(end 366.164114 -321.752722)
		(width 0.14224)
		(layer "In4.Cu")
		(net "P5E_CPU0_P1_TX_DN<7>")
	)
	(segment
		(start 352.5012 -289.475926)
		(end 352.203258 -289.475926)
		(width 0.1143)
		(layer "In4.Cu")
		(net "P5E_CPU0_P1_TX_DN<7>")
	)
	(segment
		(start 351.373186 -290.773866)
		(end 351.342452 -290.791646)
		(width 0.1143)
		(layer "In4.Cu")
		(net "P5E_CPU0_P1_TX_DN<7>")
	)
	(segment
		(start 366.164114 -321.752722)
		(end 366.80648 -322.981574)
		(width 0.14224)
		(layer "In4.Cu")
		(net "P5E_CPU0_P1_TX_DN<7>")
	)
	(segment
		(start 370.82349 -350.026732)
		(end 360.828844 -364.464854)
		(width 0.14224)
		(layer "In4.Cu")
		(net "P5E_CPU0_P1_TX_DN<7>")
	)
	(segment
		(start 354.706682 -306.83962)
		(end 358.131364 -311.96534)
		(width 0.14224)
		(layer "In4.Cu")
		(net "P5E_CPU0_P1_TX_DN<7>")
	)
	(segment
		(start 351.883218 -293.180516)
		(end 351.844102 -293.203376)
		(width 0.1143)
		(layer "In4.Cu")
		(net "P5E_CPU0_P1_TX_DN<7>")
	)
	(segment
		(start 351.196402 -295.991534)
		(end 351.196402 -296.032936)
		(width 0.1143)
		(layer "In4.Cu")
		(net "P5E_CPU0_P1_TX_DN<7>")
	)
	(segment
		(start 351.374202 -291.418518)
		(end 351.410524 -291.439346)
		(width 0.1143)
		(layer "In4.Cu")
		(net "P5E_CPU0_P1_TX_DN<7>")
	)
	(segment
		(start 351.844102 -293.203376)
		(end 351.813622 -293.221156)
		(width 0.1143)
		(layer "In4.Cu")
		(net "P5E_CPU0_P1_TX_DN<7>")
	)
	(segment
		(start 352.203258 -289.475926)
		(end 352.120454 -289.55873)
		(width 0.1143)
		(layer "In4.Cu")
		(net "P5E_CPU0_P1_TX_DN<7>")
	)
	(segment
		(start 351.375726 -290.772342)
		(end 351.374202 -290.773358)
		(width 0.1143)
		(layer "In4.Cu")
		(net "P5E_CPU0_P1_TX_DN<7>")
	)
	(segment
		(start 360.828844 -364.464854)
		(end 344.656156 -375.271538)
		(width 0.14224)
		(layer "In4.Cu")
		(net "P5E_CPU0_P1_TX_DN<7>")
	)
	(segment
		(start 366.80648 -322.981574)
		(end 370.520214 -333.832708)
		(width 0.14224)
		(layer "In4.Cu")
		(net "P5E_CPU0_P1_TX_DN<7>")
	)
	(arc
		(start 351.413318 -291.441378)
		(mid 351.592131 -291.643728)
		(end 351.65665 -291.905944)
		(width 0.1143)
		(layer "In4.Cu")
		(net "P5E_CPU0_P1_TX_DN<7>")
	)
	(arc
		(start 344.028014 -381.987298)
		(mid 344.040291 -382.049021)
		(end 344.075258 -382.101344)
		(width 0.14224)
		(layer "In4.Cu")
		(net "P5E_CPU0_P1_TX_DN<7>")
	)
	(arc
		(start 371.324886 -338.256118)
		(mid 371.336665 -338.343525)
		(end 371.340634 -338.431632)
		(width 0.14224)
		(layer "In4.Cu")
		(net "P5E_CPU0_P1_TX_DN<7>")
	)
	(arc
		(start 351.65665 -291.905944)
		(mid 351.698199 -292.077366)
		(end 351.813622 -292.210744)
		(width 0.1143)
		(layer "In4.Cu")
		(net "P5E_CPU0_P1_TX_DN<7>")
	)
	(arc
		(start 351.813622 -293.221156)
		(mid 351.656645 -293.525956)
		(end 351.813622 -293.830756)
		(width 0.1143)
		(layer "In4.Cu")
		(net "P5E_CPU0_P1_TX_DN<7>")
	)
	(arc
		(start 344.656156 -375.271538)
		(mid 344.194889 -375.780354)
		(end 344.028014 -376.446542)
		(width 0.14224)
		(layer "In4.Cu")
		(net "P5E_CPU0_P1_TX_DN<7>")
	)
	(arc
		(start 370.917216 -349.819214)
		(mid 370.879772 -349.927225)
		(end 370.82349 -350.026732)
		(width 0.14224)
		(layer "In4.Cu")
		(net "P5E_CPU0_P1_TX_DN<7>")
	)
	(arc
		(start 351.883218 -293.871396)
		(mid 352.126545 -294.335962)
		(end 351.883218 -294.800528)
		(width 0.1143)
		(layer "In4.Cu")
		(net "P5E_CPU0_P1_TX_DN<7>")
	)
	(arc
		(start 351.883218 -292.251384)
		(mid 352.126545 -292.71595)
		(end 351.883218 -293.180516)
		(width 0.1143)
		(layer "In4.Cu")
		(net "P5E_CPU0_P1_TX_DN<7>")
	)
	(arc
		(start 352.120454 -289.55873)
		(mid 352.118666 -289.570179)
		(end 352.116644 -289.58159)
		(width 0.1143)
		(layer "In4.Cu")
		(net "P5E_CPU0_P1_TX_DN<7>")
	)
	(arc
		(start 371.340634 -348.047056)
		(mid 371.337261 -348.106242)
		(end 371.327172 -348.164658)
		(width 0.14224)
		(layer "In4.Cu")
		(net "P5E_CPU0_P1_TX_DN<7>")
	)
	(arc
		(start 351.656396 -295.261792)
		(mid 351.616572 -295.46247)
		(end 351.50298 -295.632632)
		(width 0.1143)
		(layer "In4.Cu")
		(net "P5E_CPU0_P1_TX_DN<7>")
	)
	(arc
		(start 352.116644 -289.58159)
		(mid 352.035211 -289.783988)
		(end 351.883218 -289.940492)
		(width 0.1143)
		(layer "In4.Cu")
		(net "P5E_CPU0_P1_TX_DN<7>")
	)
	(arc
		(start 351.813622 -294.841168)
		(mid 351.698195 -294.974544)
		(end 351.65665 -295.145968)
		(width 0.1143)
		(layer "In4.Cu")
		(net "P5E_CPU0_P1_TX_DN<7>")
	)
	(arc
		(start 351.242122 -298.45)
		(mid 351.244568 -298.474853)
		(end 351.251774 -298.498768)
		(width 0.14224)
		(layer "In4.Cu")
		(net "P5E_CPU0_P1_TX_DN<7>")
	)
	(arc
		(start 351.653602 -290.289996)
		(mid 351.579161 -290.568322)
		(end 351.375726 -290.772342)
		(width 0.1143)
		(layer "In4.Cu")
		(net "P5E_CPU0_P1_TX_DN<7>")
	)
	(arc
		(start 370.520214 -333.832708)
		(mid 370.538417 -333.893318)
		(end 370.551964 -333.955136)
		(width 0.14224)
		(layer "In4.Cu")
		(net "P5E_CPU0_P1_TX_DN<7>")
	)
	(arc
		(start 351.23374 -295.901618)
		(mid 351.206121 -295.942858)
		(end 351.196402 -295.991534)
		(width 0.1143)
		(layer "In4.Cu")
		(net "P5E_CPU0_P1_TX_DN<7>")
	)
	(arc
		(start 351.841308 -289.964876)
		(mid 351.703902 -290.102277)
		(end 351.653602 -290.289996)
		(width 0.1143)
		(layer "In4.Cu")
		(net "P5E_CPU0_P1_TX_DN<7>")
	)
	(arc
		(start 351.342452 -290.791646)
		(mid 351.186524 -291.095938)
		(end 351.342452 -291.40023)
		(width 0.1143)
		(layer "In4.Cu")
		(net "P5E_CPU0_P1_TX_DN<7>")
	)
	(segment
		(start 340.644734 -378.39142)
		(end 340.644734 -377.68784)
		(width 0.12954)
		(layer "F.Cu")
		(net "P5E_CPU0_P1_TX_DN<6>")
	)
	(segment
		(start 340.644734 -377.68784)
		(end 340.915244 -377.41733)
		(width 0.12954)
		(layer "F.Cu")
		(net "P5E_CPU0_P1_TX_DN<6>")
	)
	(segment
		(start 350.14789 -287.59023)
		(end 349.681038 -287.856168)
		(width 0.12954)
		(layer "F.Cu")
		(net "P5E_CPU0_P1_TX_DN<6>")
	)
	(segment
		(start 340.940644 -378.68733)
		(end 340.644734 -378.39142)
		(width 0.12954)
		(layer "F.Cu")
		(net "P5E_CPU0_P1_TX_DN<6>")
	)
	(segment
		(start 357.344726 -312.477912)
		(end 365.36376 -322.24853)
		(width 0.14224)
		(layer "In4.Cu")
		(net "P5E_CPU0_P1_TX_DN<6>")
	)
	(segment
		(start 350.421448 -289.79114)
		(end 350.473264 -289.821366)
		(width 0.1143)
		(layer "In4.Cu")
		(net "P5E_CPU0_P1_TX_DN<6>")
	)
	(segment
		(start 350.716596 -295.145968)
		(end 350.716342 -295.145714)
		(width 0.1143)
		(layer "In4.Cu")
		(net "P5E_CPU0_P1_TX_DN<6>")
	)
	(segment
		(start 350.716342 -295.145714)
		(end 350.716342 -295.347136)
		(width 0.1143)
		(layer "In4.Cu")
		(net "P5E_CPU0_P1_TX_DN<6>")
	)
	(segment
		(start 349.932498 -288.970212)
		(end 349.963486 -288.987992)
		(width 0.1143)
		(layer "In4.Cu")
		(net "P5E_CPU0_P1_TX_DN<6>")
	)
	(segment
		(start 350.904048 -293.848536)
		(end 350.943164 -293.871396)
		(width 0.1143)
		(layer "In4.Cu")
		(net "P5E_CPU0_P1_TX_DN<6>")
	)
	(segment
		(start 350.233742 -289.456622)
		(end 350.233742 -289.466274)
		(width 0.1143)
		(layer "In4.Cu")
		(net "P5E_CPU0_P1_TX_DN<6>")
	)
	(segment
		(start 350.309434 -298.660312)
		(end 353.89312 -307.31206)
		(width 0.14224)
		(layer "In4.Cu")
		(net "P5E_CPU0_P1_TX_DN<6>")
	)
	(segment
		(start 350.454976 -290.761166)
		(end 350.43364 -290.773612)
		(width 0.1143)
		(layer "In4.Cu")
		(net "P5E_CPU0_P1_TX_DN<6>")
	)
	(segment
		(start 350.904048 -292.228524)
		(end 350.943164 -292.251384)
		(width 0.1143)
		(layer "In4.Cu")
		(net "P5E_CPU0_P1_TX_DN<6>")
	)
	(segment
		(start 350.873568 -293.830756)
		(end 350.904048 -293.848536)
		(width 0.1143)
		(layer "In4.Cu")
		(net "P5E_CPU0_P1_TX_DN<6>")
	)
	(segment
		(start 350.473264 -290.750498)
		(end 350.45523 -290.761166)
		(width 0.1143)
		(layer "In4.Cu")
		(net "P5E_CPU0_P1_TX_DN<6>")
	)
	(segment
		(start 369.676934 -334.429354)
		(end 370.349272 -338.170266)
		(width 0.14224)
		(layer "In4.Cu")
		(net "P5E_CPU0_P1_TX_DN<6>")
	)
	(segment
		(start 350.45523 -290.761166)
		(end 350.454976 -290.761166)
		(width 0.1143)
		(layer "In4.Cu")
		(net "P5E_CPU0_P1_TX_DN<6>")
	)
	(segment
		(start 349.963486 -288.987992)
		(end 349.964248 -288.9885)
		(width 0.1143)
		(layer "In4.Cu")
		(net "P5E_CPU0_P1_TX_DN<6>")
	)
	(segment
		(start 350.623378 -295.57218)
		(end 350.28886 -295.906698)
		(width 0.1143)
		(layer "In4.Cu")
		(net "P5E_CPU0_P1_TX_DN<6>")
	)
	(segment
		(start 350.904048 -293.203376)
		(end 350.873568 -293.221156)
		(width 0.1143)
		(layer "In4.Cu")
		(net "P5E_CPU0_P1_TX_DN<6>")
	)
	(segment
		(start 370.35105 -348.028768)
		(end 369.993418 -349.51416)
		(width 0.14224)
		(layer "In4.Cu")
		(net "P5E_CPU0_P1_TX_DN<6>")
	)
	(segment
		(start 350.44126 -291.422582)
		(end 350.442784 -291.423598)
		(width 0.1143)
		(layer "In4.Cu")
		(net "P5E_CPU0_P1_TX_DN<6>")
	)
	(segment
		(start 340.624414 -377.1265)
		(end 340.915244 -377.41733)
		(width 0.14224)
		(layer "In4.Cu")
		(net "P5E_CPU0_P1_TX_DN<6>")
	)
	(segment
		(start 370.36502 -338.34578)
		(end 370.36502 -347.907356)
		(width 0.14224)
		(layer "In4.Cu")
		(net "P5E_CPU0_P1_TX_DN<6>")
	)
	(segment
		(start 349.461582 -288.159698)
		(end 349.494094 -288.178494)
		(width 0.1143)
		(layer "In4.Cu")
		(net "P5E_CPU0_P1_TX_DN<6>")
	)
	(segment
		(start 350.297242 -296.205656)
		(end 350.297242 -296.234104)
		(width 0.1143)
		(layer "In4.Cu")
		(net "P5E_CPU0_P1_TX_DN<6>")
	)
	(segment
		(start 350.943164 -294.800528)
		(end 350.873568 -294.841168)
		(width 0.1143)
		(layer "In4.Cu")
		(net "P5E_CPU0_P1_TX_DN<6>")
	)
	(segment
		(start 369.899184 -349.72371)
		(end 360.54157 -363.210348)
		(width 0.14224)
		(layer "In4.Cu")
		(net "P5E_CPU0_P1_TX_DN<6>")
	)
	(segment
		(start 350.943164 -293.180516)
		(end 350.904048 -293.203376)
		(width 0.1143)
		(layer "In4.Cu")
		(net "P5E_CPU0_P1_TX_DN<6>")
	)
	(segment
		(start 360.54157 -363.210348)
		(end 340.681056 -376.481086)
		(width 0.14224)
		(layer "In4.Cu")
		(net "P5E_CPU0_P1_TX_DN<6>")
	)
	(segment
		(start 350.251522 -296.159936)
		(end 350.297242 -296.205656)
		(width 0.1143)
		(layer "In4.Cu")
		(net "P5E_CPU0_P1_TX_DN<6>")
	)
	(segment
		(start 349.494094 -288.178494)
		(end 349.53321 -288.201354)
		(width 0.1143)
		(layer "In4.Cu")
		(net "P5E_CPU0_P1_TX_DN<6>")
	)
	(segment
		(start 365.81207 -323.106288)
		(end 369.645184 -334.306926)
		(width 0.14224)
		(layer "In4.Cu")
		(net "P5E_CPU0_P1_TX_DN<6>")
	)
	(segment
		(start 350.251522 -295.996868)
		(end 350.251522 -296.159936)
		(width 0.1143)
		(layer "In4.Cu")
		(net "P5E_CPU0_P1_TX_DN<6>")
	)
	(segment
		(start 365.36376 -322.24853)
		(end 365.81207 -323.106288)
		(width 0.14224)
		(layer "In4.Cu")
		(net "P5E_CPU0_P1_TX_DN<6>")
	)
	(segment
		(start 340.624414 -376.586496)
		(end 340.624414 -377.1265)
		(width 0.14224)
		(layer "In4.Cu")
		(net "P5E_CPU0_P1_TX_DN<6>")
	)
	(segment
		(start 350.426274 -291.413946)
		(end 350.44126 -291.422582)
		(width 0.1143)
		(layer "In4.Cu")
		(net "P5E_CPU0_P1_TX_DN<6>")
	)
	(segment
		(start 350.297242 -296.234104)
		(end 350.297242 -298.59859)
		(width 0.14224)
		(layer "In4.Cu")
		(net "P5E_CPU0_P1_TX_DN<6>")
	)
	(segment
		(start 350.442784 -291.423598)
		(end 350.472502 -291.44087)
		(width 0.1143)
		(layer "In4.Cu")
		(net "P5E_CPU0_P1_TX_DN<6>")
	)
	(segment
		(start 350.873568 -292.210744)
		(end 350.904048 -292.228524)
		(width 0.1143)
		(layer "In4.Cu")
		(net "P5E_CPU0_P1_TX_DN<6>")
	)
	(segment
		(start 349.38335 -287.856168)
		(end 349.3135 -287.926018)
		(width 0.1143)
		(layer "In4.Cu")
		(net "P5E_CPU0_P1_TX_DN<6>")
	)
	(segment
		(start 349.681038 -287.856168)
		(end 349.38335 -287.856168)
		(width 0.1143)
		(layer "In4.Cu")
		(net "P5E_CPU0_P1_TX_DN<6>")
	)
	(segment
		(start 353.89312 -307.31206)
		(end 357.344726 -312.477912)
		(width 0.14224)
		(layer "In4.Cu")
		(net "P5E_CPU0_P1_TX_DN<6>")
	)
	(arc
		(start 350.473264 -291.441378)
		(mid 350.652077 -291.643728)
		(end 350.716596 -291.905944)
		(width 0.1143)
		(layer "In4.Cu")
		(net "P5E_CPU0_P1_TX_DN<6>")
	)
	(arc
		(start 369.993418 -349.51416)
		(mid 369.956013 -349.6233)
		(end 369.899184 -349.72371)
		(width 0.14224)
		(layer "In4.Cu")
		(net "P5E_CPU0_P1_TX_DN<6>")
	)
	(arc
		(start 350.28886 -295.906698)
		(mid 350.261217 -295.948068)
		(end 350.251522 -295.996868)
		(width 0.1143)
		(layer "In4.Cu")
		(net "P5E_CPU0_P1_TX_DN<6>")
	)
	(arc
		(start 350.943164 -293.871396)
		(mid 351.186491 -294.335962)
		(end 350.943164 -294.800528)
		(width 0.1143)
		(layer "In4.Cu")
		(net "P5E_CPU0_P1_TX_DN<6>")
	)
	(arc
		(start 370.349272 -338.170266)
		(mid 370.361051 -338.257673)
		(end 370.36502 -338.34578)
		(width 0.14224)
		(layer "In4.Cu")
		(net "P5E_CPU0_P1_TX_DN<6>")
	)
	(arc
		(start 350.873568 -294.841168)
		(mid 350.758141 -294.974544)
		(end 350.716596 -295.145968)
		(width 0.1143)
		(layer "In4.Cu")
		(net "P5E_CPU0_P1_TX_DN<6>")
	)
	(arc
		(start 350.873568 -293.221156)
		(mid 350.716591 -293.525956)
		(end 350.873568 -293.830756)
		(width 0.1143)
		(layer "In4.Cu")
		(net "P5E_CPU0_P1_TX_DN<6>")
	)
	(arc
		(start 349.964248 -288.9885)
		(mid 350.161572 -289.18654)
		(end 350.233742 -289.456622)
		(width 0.1143)
		(layer "In4.Cu")
		(net "P5E_CPU0_P1_TX_DN<6>")
	)
	(arc
		(start 350.716596 -291.905944)
		(mid 350.758145 -292.077366)
		(end 350.873568 -292.210744)
		(width 0.1143)
		(layer "In4.Cu")
		(net "P5E_CPU0_P1_TX_DN<6>")
	)
	(arc
		(start 350.943164 -292.251384)
		(mid 351.186491 -292.71595)
		(end 350.943164 -293.180516)
		(width 0.1143)
		(layer "In4.Cu")
		(net "P5E_CPU0_P1_TX_DN<6>")
	)
	(arc
		(start 350.472502 -291.44087)
		(mid 350.472883 -291.441124)
		(end 350.473264 -291.441378)
		(width 0.1143)
		(layer "In4.Cu")
		(net "P5E_CPU0_P1_TX_DN<6>")
	)
	(arc
		(start 369.645184 -334.306926)
		(mid 369.663382 -334.367537)
		(end 369.676934 -334.429354)
		(width 0.14224)
		(layer "In4.Cu")
		(net "P5E_CPU0_P1_TX_DN<6>")
	)
	(arc
		(start 349.776542 -288.66592)
		(mid 349.817797 -288.836891)
		(end 349.932498 -288.970212)
		(width 0.1143)
		(layer "In4.Cu")
		(net "P5E_CPU0_P1_TX_DN<6>")
	)
	(arc
		(start 350.716342 -295.347136)
		(mid 350.692233 -295.4689)
		(end 350.623378 -295.57218)
		(width 0.1143)
		(layer "In4.Cu")
		(net "P5E_CPU0_P1_TX_DN<6>")
	)
	(arc
		(start 370.36502 -347.907356)
		(mid 370.361495 -347.968459)
		(end 370.35105 -348.028768)
		(width 0.14224)
		(layer "In4.Cu")
		(net "P5E_CPU0_P1_TX_DN<6>")
	)
	(arc
		(start 350.297242 -298.59859)
		(mid 350.30029 -298.630054)
		(end 350.309434 -298.660312)
		(width 0.14224)
		(layer "In4.Cu")
		(net "P5E_CPU0_P1_TX_DN<6>")
	)
	(arc
		(start 349.3135 -287.926018)
		(mid 349.365208 -288.057001)
		(end 349.461582 -288.159698)
		(width 0.1143)
		(layer "In4.Cu")
		(net "P5E_CPU0_P1_TX_DN<6>")
	)
	(arc
		(start 350.473264 -289.821366)
		(mid 350.716481 -290.285932)
		(end 350.473264 -290.750498)
		(width 0.1143)
		(layer "In4.Cu")
		(net "P5E_CPU0_P1_TX_DN<6>")
	)
	(arc
		(start 349.53321 -288.201354)
		(mid 349.712023 -288.403704)
		(end 349.776542 -288.66592)
		(width 0.1143)
		(layer "In4.Cu")
		(net "P5E_CPU0_P1_TX_DN<6>")
	)
	(arc
		(start 350.43364 -290.773612)
		(mid 350.24812 -291.091669)
		(end 350.426274 -291.413946)
		(width 0.1143)
		(layer "In4.Cu")
		(net "P5E_CPU0_P1_TX_DN<6>")
	)
	(arc
		(start 340.681056 -376.481086)
		(mid 340.639566 -376.526707)
		(end 340.624414 -376.586496)
		(width 0.14224)
		(layer "In4.Cu")
		(net "P5E_CPU0_P1_TX_DN<6>")
	)
	(arc
		(start 350.233742 -289.466274)
		(mid 350.284048 -289.653862)
		(end 350.421448 -289.79114)
		(width 0.1143)
		(layer "In4.Cu")
		(net "P5E_CPU0_P1_TX_DN<6>")
	)
	(segment
		(start 338.942934 -380.15164)
		(end 339.213444 -379.88113)
		(width 0.12954)
		(layer "F.Cu")
		(net "P5E_CPU0_P1_TX_DN<5>")
	)
	(segment
		(start 339.238844 -381.15113)
		(end 338.942934 -380.85522)
		(width 0.12954)
		(layer "F.Cu")
		(net "P5E_CPU0_P1_TX_DN<5>")
	)
	(segment
		(start 350.14789 -290.83)
		(end 349.681038 -291.095938)
		(width 0.12954)
		(layer "F.Cu")
		(net "P5E_CPU0_P1_TX_DN<5>")
	)
	(segment
		(start 338.942934 -380.85522)
		(end 338.942934 -380.15164)
		(width 0.12954)
		(layer "F.Cu")
		(net "P5E_CPU0_P1_TX_DN<5>")
	)
	(segment
		(start 355.868224 -312.052716)
		(end 356.725982 -313.209686)
		(width 0.14224)
		(layer "In4.Cu")
		(net "P5E_CPU0_P1_TX_DN<5>")
	)
	(segment
		(start 349.963994 -293.203376)
		(end 349.948246 -293.212774)
		(width 0.1143)
		(layer "In4.Cu")
		(net "P5E_CPU0_P1_TX_DN<5>")
	)
	(segment
		(start 359.878122 -362.514134)
		(end 339.25637 -376.294142)
		(width 0.14224)
		(layer "In4.Cu")
		(net "P5E_CPU0_P1_TX_DN<5>")
	)
	(segment
		(start 350.005396 -294.799004)
		(end 349.932498 -294.841676)
		(width 0.1143)
		(layer "In4.Cu")
		(net "P5E_CPU0_P1_TX_DN<5>")
	)
	(segment
		(start 364.905798 -323.386196)
		(end 368.731292 -334.564228)
		(width 0.14224)
		(layer "In4.Cu")
		(net "P5E_CPU0_P1_TX_DN<5>")
	)
	(segment
		(start 350.003364 -293.871396)
		(end 350.005396 -293.87292)
		(width 0.1143)
		(layer "In4.Cu")
		(net "P5E_CPU0_P1_TX_DN<5>")
	)
	(segment
		(start 349.352362 -296.234104)
		(end 349.352362 -298.760642)
		(width 0.14224)
		(layer "In4.Cu")
		(net "P5E_CPU0_P1_TX_DN<5>")
	)
	(segment
		(start 338.922614 -379.5903)
		(end 339.213444 -379.88113)
		(width 0.14224)
		(layer "In4.Cu")
		(net "P5E_CPU0_P1_TX_DN<5>")
	)
	(segment
		(start 349.306642 -295.91762)
		(end 349.306642 -296.159936)
		(width 0.1143)
		(layer "In4.Cu")
		(net "P5E_CPU0_P1_TX_DN<5>")
	)
	(segment
		(start 338.922614 -376.918728)
		(end 338.922614 -379.5903)
		(width 0.14224)
		(layer "In4.Cu")
		(net "P5E_CPU0_P1_TX_DN<5>")
	)
	(segment
		(start 349.362014 -298.80941)
		(end 353.183444 -308.035452)
		(width 0.14224)
		(layer "In4.Cu")
		(net "P5E_CPU0_P1_TX_DN<5>")
	)
	(segment
		(start 368.763042 -334.686656)
		(end 369.398804 -338.223352)
		(width 0.14224)
		(layer "In4.Cu")
		(net "P5E_CPU0_P1_TX_DN<5>")
	)
	(segment
		(start 349.464376 -291.401246)
		(end 349.496634 -291.420042)
		(width 0.1143)
		(layer "In4.Cu")
		(net "P5E_CPU0_P1_TX_DN<5>")
	)
	(segment
		(start 349.496634 -291.420042)
		(end 349.498666 -291.421312)
		(width 0.1143)
		(layer "In4.Cu")
		(net "P5E_CPU0_P1_TX_DN<5>")
	)
	(segment
		(start 364.604554 -322.809616)
		(end 364.905798 -323.386196)
		(width 0.14224)
		(layer "In4.Cu")
		(net "P5E_CPU0_P1_TX_DN<5>")
	)
	(segment
		(start 349.489014 -295.635934)
		(end 349.376746 -295.748202)
		(width 0.1143)
		(layer "In4.Cu")
		(net "P5E_CPU0_P1_TX_DN<5>")
	)
	(segment
		(start 356.725982 -313.209686)
		(end 364.604554 -322.809616)
		(width 0.14224)
		(layer "In4.Cu")
		(net "P5E_CPU0_P1_TX_DN<5>")
	)
	(segment
		(start 369.027964 -349.34398)
		(end 359.878122 -362.514134)
		(width 0.14224)
		(layer "In4.Cu")
		(net "P5E_CPU0_P1_TX_DN<5>")
	)
	(segment
		(start 349.53321 -295.610534)
		(end 349.489014 -295.635934)
		(width 0.1143)
		(layer "In4.Cu")
		(net "P5E_CPU0_P1_TX_DN<5>")
	)
	(segment
		(start 369.399566 -347.992446)
		(end 369.121944 -349.134938)
		(width 0.14224)
		(layer "In4.Cu")
		(net "P5E_CPU0_P1_TX_DN<5>")
	)
	(segment
		(start 349.306642 -296.159936)
		(end 349.352362 -296.205656)
		(width 0.1143)
		(layer "In4.Cu")
		(net "P5E_CPU0_P1_TX_DN<5>")
	)
	(segment
		(start 353.183444 -308.035452)
		(end 355.868224 -312.052716)
		(width 0.14224)
		(layer "In4.Cu")
		(net "P5E_CPU0_P1_TX_DN<5>")
	)
	(segment
		(start 349.352362 -296.205656)
		(end 349.352362 -296.234104)
		(width 0.1143)
		(layer "In4.Cu")
		(net "P5E_CPU0_P1_TX_DN<5>")
	)
	(segment
		(start 349.942912 -293.83609)
		(end 350.002602 -293.870888)
		(width 0.1143)
		(layer "In4.Cu")
		(net "P5E_CPU0_P1_TX_DN<5>")
	)
	(segment
		(start 350.00311 -293.180516)
		(end 349.963994 -293.203376)
		(width 0.1143)
		(layer "In4.Cu")
		(net "P5E_CPU0_P1_TX_DN<5>")
	)
	(segment
		(start 349.948246 -293.212774)
		(end 349.942658 -293.215822)
		(width 0.1143)
		(layer "In4.Cu")
		(net "P5E_CPU0_P1_TX_DN<5>")
	)
	(segment
		(start 349.942404 -293.83609)
		(end 349.942912 -293.83609)
		(width 0.1143)
		(layer "In4.Cu")
		(net "P5E_CPU0_P1_TX_DN<5>")
	)
	(segment
		(start 369.414552 -338.398866)
		(end 369.414552 -347.86697)
		(width 0.14224)
		(layer "In4.Cu")
		(net "P5E_CPU0_P1_TX_DN<5>")
	)
	(segment
		(start 349.383096 -291.095938)
		(end 349.313246 -291.165788)
		(width 0.1143)
		(layer "In4.Cu")
		(net "P5E_CPU0_P1_TX_DN<5>")
	)
	(segment
		(start 349.681038 -291.095938)
		(end 349.383096 -291.095938)
		(width 0.1143)
		(layer "In4.Cu")
		(net "P5E_CPU0_P1_TX_DN<5>")
	)
	(segment
		(start 349.959168 -292.22573)
		(end 350.001586 -292.250368)
		(width 0.1143)
		(layer "In4.Cu")
		(net "P5E_CPU0_P1_TX_DN<5>")
	)
	(arc
		(start 350.002602 -293.870888)
		(mid 350.002983 -293.871142)
		(end 350.003364 -293.871396)
		(width 0.1143)
		(layer "In4.Cu")
		(net "P5E_CPU0_P1_TX_DN<5>")
	)
	(arc
		(start 350.005396 -293.87292)
		(mid 350.247907 -294.335962)
		(end 350.005396 -294.799004)
		(width 0.1143)
		(layer "In4.Cu")
		(net "P5E_CPU0_P1_TX_DN<5>")
	)
	(arc
		(start 350.001586 -292.250368)
		(mid 350.002348 -292.250875)
		(end 350.00311 -292.251384)
		(width 0.1143)
		(layer "In4.Cu")
		(net "P5E_CPU0_P1_TX_DN<5>")
	)
	(arc
		(start 369.414552 -347.86697)
		(mid 369.41081 -347.930156)
		(end 369.399566 -347.992446)
		(width 0.14224)
		(layer "In4.Cu")
		(net "P5E_CPU0_P1_TX_DN<5>")
	)
	(arc
		(start 349.352362 -298.760642)
		(mid 349.354808 -298.785495)
		(end 349.362014 -298.80941)
		(width 0.14224)
		(layer "In4.Cu")
		(net "P5E_CPU0_P1_TX_DN<5>")
	)
	(arc
		(start 349.313246 -291.165788)
		(mid 349.365991 -291.298164)
		(end 349.464376 -291.401246)
		(width 0.1143)
		(layer "In4.Cu")
		(net "P5E_CPU0_P1_TX_DN<5>")
	)
	(arc
		(start 369.121944 -349.134938)
		(mid 369.084629 -349.24381)
		(end 369.027964 -349.34398)
		(width 0.14224)
		(layer "In4.Cu")
		(net "P5E_CPU0_P1_TX_DN<5>")
	)
	(arc
		(start 349.776542 -295.145968)
		(mid 349.712027 -295.408187)
		(end 349.53321 -295.610534)
		(width 0.1143)
		(layer "In4.Cu")
		(net "P5E_CPU0_P1_TX_DN<5>")
	)
	(arc
		(start 349.376746 -295.748202)
		(mid 349.324862 -295.825946)
		(end 349.306642 -295.91762)
		(width 0.1143)
		(layer "In4.Cu")
		(net "P5E_CPU0_P1_TX_DN<5>")
	)
	(arc
		(start 369.398804 -338.223352)
		(mid 369.410586 -338.310759)
		(end 369.414552 -338.398866)
		(width 0.14224)
		(layer "In4.Cu")
		(net "P5E_CPU0_P1_TX_DN<5>")
	)
	(arc
		(start 349.942658 -293.215822)
		(mid 349.764116 -293.525846)
		(end 349.942404 -293.83609)
		(width 0.1143)
		(layer "In4.Cu")
		(net "P5E_CPU0_P1_TX_DN<5>")
	)
	(arc
		(start 349.498666 -291.421312)
		(mid 349.702193 -291.626737)
		(end 349.776542 -291.906198)
		(width 0.1143)
		(layer "In4.Cu")
		(net "P5E_CPU0_P1_TX_DN<5>")
	)
	(arc
		(start 368.731292 -334.564228)
		(mid 368.74949 -334.624839)
		(end 368.763042 -334.686656)
		(width 0.14224)
		(layer "In4.Cu")
		(net "P5E_CPU0_P1_TX_DN<5>")
	)
	(arc
		(start 350.00311 -292.251384)
		(mid 350.246437 -292.71595)
		(end 350.00311 -293.180516)
		(width 0.1143)
		(layer "In4.Cu")
		(net "P5E_CPU0_P1_TX_DN<5>")
	)
	(arc
		(start 349.932498 -294.841676)
		(mid 349.817822 -294.97501)
		(end 349.776542 -295.145968)
		(width 0.1143)
		(layer "In4.Cu")
		(net "P5E_CPU0_P1_TX_DN<5>")
	)
	(arc
		(start 339.25637 -376.294142)
		(mid 339.011296 -376.564648)
		(end 338.922614 -376.918728)
		(width 0.14224)
		(layer "In4.Cu")
		(net "P5E_CPU0_P1_TX_DN<5>")
	)
	(arc
		(start 349.776542 -291.906198)
		(mid 349.825494 -292.09016)
		(end 349.959168 -292.22573)
		(width 0.1143)
		(layer "In4.Cu")
		(net "P5E_CPU0_P1_TX_DN<5>")
	)
	(segment
		(start 337.241134 -382.61544)
		(end 337.511644 -382.34493)
		(width 0.12954)
		(layer "F.Cu")
		(net "P5E_CPU0_P1_TX_DN<4>")
	)
	(segment
		(start 337.241134 -383.31902)
		(end 337.241134 -382.61544)
		(width 0.12954)
		(layer "F.Cu")
		(net "P5E_CPU0_P1_TX_DN<4>")
	)
	(segment
		(start 350.14789 -289.209988)
		(end 349.681038 -289.475926)
		(width 0.12954)
		(layer "F.Cu")
		(net "P5E_CPU0_P1_TX_DN<4>")
	)
	(segment
		(start 337.537044 -383.61493)
		(end 337.241134 -383.31902)
		(width 0.12954)
		(layer "F.Cu")
		(net "P5E_CPU0_P1_TX_DN<4>")
	)
	(segment
		(start 348.993714 -292.210744)
		(end 349.024194 -292.228524)
		(width 0.1143)
		(layer "In4.Cu")
		(net "P5E_CPU0_P1_TX_DN<4>")
	)
	(segment
		(start 337.268058 -382.101344)
		(end 337.511644 -382.34493)
		(width 0.14224)
		(layer "In4.Cu")
		(net "P5E_CPU0_P1_TX_DN<4>")
	)
	(segment
		(start 337.220814 -377.166886)
		(end 337.220814 -381.987298)
		(width 0.14224)
		(layer "In4.Cu")
		(net "P5E_CPU0_P1_TX_DN<4>")
	)
	(segment
		(start 348.407228 -296.078656)
		(end 348.407228 -296.107104)
		(width 0.1143)
		(layer "In4.Cu")
		(net "P5E_CPU0_P1_TX_DN<4>")
	)
	(segment
		(start 348.743778 -295.493186)
		(end 348.436692 -295.800272)
		(width 0.1143)
		(layer "In4.Cu")
		(net "P5E_CPU0_P1_TX_DN<4>")
	)
	(segment
		(start 348.836996 -295.145968)
		(end 348.836742 -295.145714)
		(width 0.1143)
		(layer "In4.Cu")
		(net "P5E_CPU0_P1_TX_DN<4>")
	)
	(segment
		(start 357.264716 -362.349542)
		(end 339.626194 -372.921022)
		(width 0.14224)
		(layer "In4.Cu")
		(net "P5E_CPU0_P1_TX_DN<4>")
	)
	(segment
		(start 348.59341 -290.750498)
		(end 348.55531 -290.77285)
		(width 0.1143)
		(layer "In4.Cu")
		(net "P5E_CPU0_P1_TX_DN<4>")
	)
	(segment
		(start 348.55785 -291.42055)
		(end 348.56039 -291.422074)
		(width 0.1143)
		(layer "In4.Cu")
		(net "P5E_CPU0_P1_TX_DN<4>")
	)
	(segment
		(start 349.024194 -292.228524)
		(end 349.06331 -292.251384)
		(width 0.1143)
		(layer "In4.Cu")
		(net "P5E_CPU0_P1_TX_DN<4>")
	)
	(segment
		(start 348.361508 -296.032936)
		(end 348.407228 -296.078656)
		(width 0.1143)
		(layer "In4.Cu")
		(net "P5E_CPU0_P1_TX_DN<4>")
	)
	(segment
		(start 348.553532 -290.773866)
		(end 348.552262 -290.774628)
		(width 0.1143)
		(layer "In4.Cu")
		(net "P5E_CPU0_P1_TX_DN<4>")
	)
	(segment
		(start 348.56039 -291.422074)
		(end 348.561914 -291.42309)
		(width 0.1143)
		(layer "In4.Cu")
		(net "P5E_CPU0_P1_TX_DN<4>")
	)
	(segment
		(start 360.365802 -359.020872)
		(end 357.264716 -362.349542)
		(width 0.14224)
		(layer "In4.Cu")
		(net "P5E_CPU0_P1_TX_DN<4>")
	)
	(segment
		(start 348.361508 -295.981628)
		(end 348.361508 -296.032936)
		(width 0.1143)
		(layer "In4.Cu")
		(net "P5E_CPU0_P1_TX_DN<4>")
	)
	(segment
		(start 349.06331 -293.180516)
		(end 349.024194 -293.203376)
		(width 0.1143)
		(layer "In4.Cu")
		(net "P5E_CPU0_P1_TX_DN<4>")
	)
	(segment
		(start 363.91088 -323.496178)
		(end 367.851182 -335.007966)
		(width 0.14224)
		(layer "In4.Cu")
		(net "P5E_CPU0_P1_TX_DN<4>")
	)
	(segment
		(start 349.06331 -294.800528)
		(end 349.024194 -294.823388)
		(width 0.1143)
		(layer "In4.Cu")
		(net "P5E_CPU0_P1_TX_DN<4>")
	)
	(segment
		(start 348.55531 -291.419026)
		(end 348.556834 -291.420042)
		(width 0.1143)
		(layer "In4.Cu")
		(net "P5E_CPU0_P1_TX_DN<4>")
	)
	(segment
		(start 367.882932 -335.130394)
		(end 368.440716 -338.23402)
		(width 0.14224)
		(layer "In4.Cu")
		(net "P5E_CPU0_P1_TX_DN<4>")
	)
	(segment
		(start 348.561914 -291.42309)
		(end 348.59341 -291.441378)
		(width 0.1143)
		(layer "In4.Cu")
		(net "P5E_CPU0_P1_TX_DN<4>")
	)
	(segment
		(start 348.993714 -294.841168)
		(end 348.993714 -294.840914)
		(width 0.1143)
		(layer "In4.Cu")
		(net "P5E_CPU0_P1_TX_DN<4>")
	)
	(segment
		(start 348.993714 -293.830756)
		(end 349.024194 -293.848536)
		(width 0.1143)
		(layer "In4.Cu")
		(net "P5E_CPU0_P1_TX_DN<4>")
	)
	(segment
		(start 349.681038 -289.475926)
		(end 349.38335 -289.475926)
		(width 0.1143)
		(layer "In4.Cu")
		(net "P5E_CPU0_P1_TX_DN<4>")
	)
	(segment
		(start 348.407228 -296.107104)
		(end 348.407228 -298.915836)
		(width 0.14224)
		(layer "In4.Cu")
		(net "P5E_CPU0_P1_TX_DN<4>")
	)
	(segment
		(start 349.024194 -289.963352)
		(end 348.993714 -289.981132)
		(width 0.1143)
		(layer "In4.Cu")
		(net "P5E_CPU0_P1_TX_DN<4>")
	)
	(segment
		(start 348.55531 -290.77285)
		(end 348.554294 -290.773358)
		(width 0.1143)
		(layer "In4.Cu")
		(net "P5E_CPU0_P1_TX_DN<4>")
	)
	(segment
		(start 348.554294 -290.773358)
		(end 348.553532 -290.773866)
		(width 0.1143)
		(layer "In4.Cu")
		(net "P5E_CPU0_P1_TX_DN<4>")
	)
	(segment
		(start 349.38335 -289.475926)
		(end 349.300546 -289.55873)
		(width 0.1143)
		(layer "In4.Cu")
		(net "P5E_CPU0_P1_TX_DN<4>")
	)
	(segment
		(start 348.552262 -290.774628)
		(end 348.522544 -290.791646)
		(width 0.1143)
		(layer "In4.Cu")
		(net "P5E_CPU0_P1_TX_DN<4>")
	)
	(segment
		(start 352.399346 -308.579012)
		(end 355.380036 -313.040014)
		(width 0.14224)
		(layer "In4.Cu")
		(net "P5E_CPU0_P1_TX_DN<4>")
	)
	(segment
		(start 348.522544 -291.40023)
		(end 348.553532 -291.41801)
		(width 0.1143)
		(layer "In4.Cu")
		(net "P5E_CPU0_P1_TX_DN<4>")
	)
	(segment
		(start 365.846614 -352.225356)
		(end 360.365802 -359.020872)
		(width 0.14224)
		(layer "In4.Cu")
		(net "P5E_CPU0_P1_TX_DN<4>")
	)
	(segment
		(start 348.556834 -291.420042)
		(end 348.55785 -291.42055)
		(width 0.1143)
		(layer "In4.Cu")
		(net "P5E_CPU0_P1_TX_DN<4>")
	)
	(segment
		(start 368.440462 -347.920818)
		(end 368.23396 -348.721172)
		(width 0.14224)
		(layer "In4.Cu")
		(net "P5E_CPU0_P1_TX_DN<4>")
	)
	(segment
		(start 363.82198 -323.326252)
		(end 363.91088 -323.496178)
		(width 0.14224)
		(layer "In4.Cu")
		(net "P5E_CPU0_P1_TX_DN<4>")
	)
	(segment
		(start 349.06331 -289.940492)
		(end 349.024194 -289.963352)
		(width 0.1143)
		(layer "In4.Cu")
		(net "P5E_CPU0_P1_TX_DN<4>")
	)
	(segment
		(start 349.024194 -293.203376)
		(end 348.993714 -293.221156)
		(width 0.1143)
		(layer "In4.Cu")
		(net "P5E_CPU0_P1_TX_DN<4>")
	)
	(segment
		(start 368.13998 -348.925896)
		(end 365.846614 -352.225356)
		(width 0.14224)
		(layer "In4.Cu")
		(net "P5E_CPU0_P1_TX_DN<4>")
	)
	(segment
		(start 355.380036 -313.040014)
		(end 363.82198 -323.326252)
		(width 0.14224)
		(layer "In4.Cu")
		(net "P5E_CPU0_P1_TX_DN<4>")
	)
	(segment
		(start 348.836742 -295.145714)
		(end 348.836742 -295.268142)
		(width 0.1143)
		(layer "In4.Cu")
		(net "P5E_CPU0_P1_TX_DN<4>")
	)
	(segment
		(start 348.553532 -291.41801)
		(end 348.554294 -291.418518)
		(width 0.1143)
		(layer "In4.Cu")
		(net "P5E_CPU0_P1_TX_DN<4>")
	)
	(segment
		(start 348.41688 -298.964604)
		(end 352.399346 -308.579012)
		(width 0.14224)
		(layer "In4.Cu")
		(net "P5E_CPU0_P1_TX_DN<4>")
	)
	(segment
		(start 349.024194 -293.848536)
		(end 349.06331 -293.871396)
		(width 0.1143)
		(layer "In4.Cu")
		(net "P5E_CPU0_P1_TX_DN<4>")
	)
	(segment
		(start 349.024194 -294.823388)
		(end 348.993714 -294.841168)
		(width 0.1143)
		(layer "In4.Cu")
		(net "P5E_CPU0_P1_TX_DN<4>")
	)
	(segment
		(start 348.554294 -291.418518)
		(end 348.55531 -291.419026)
		(width 0.1143)
		(layer "In4.Cu")
		(net "P5E_CPU0_P1_TX_DN<4>")
	)
	(segment
		(start 368.456464 -338.409534)
		(end 368.456464 -347.795596)
		(width 0.14224)
		(layer "In4.Cu")
		(net "P5E_CPU0_P1_TX_DN<4>")
	)
	(arc
		(start 348.993714 -294.840914)
		(mid 348.878396 -294.974446)
		(end 348.836996 -295.145968)
		(width 0.1143)
		(layer "In4.Cu")
		(net "P5E_CPU0_P1_TX_DN<4>")
	)
	(arc
		(start 348.993714 -289.981132)
		(mid 348.878287 -290.114508)
		(end 348.836742 -290.285932)
		(width 0.1143)
		(layer "In4.Cu")
		(net "P5E_CPU0_P1_TX_DN<4>")
	)
	(arc
		(start 367.851182 -335.007966)
		(mid 367.869391 -335.068575)
		(end 367.882932 -335.130394)
		(width 0.14224)
		(layer "In4.Cu")
		(net "P5E_CPU0_P1_TX_DN<4>")
	)
	(arc
		(start 348.836742 -290.285932)
		(mid 348.772227 -290.548151)
		(end 348.59341 -290.750498)
		(width 0.1143)
		(layer "In4.Cu")
		(net "P5E_CPU0_P1_TX_DN<4>")
	)
	(arc
		(start 348.59341 -291.441378)
		(mid 348.772223 -291.643728)
		(end 348.836742 -291.905944)
		(width 0.1143)
		(layer "In4.Cu")
		(net "P5E_CPU0_P1_TX_DN<4>")
	)
	(arc
		(start 339.626194 -372.921022)
		(mid 337.863925 -374.726942)
		(end 337.220814 -377.166886)
		(width 0.14224)
		(layer "In4.Cu")
		(net "P5E_CPU0_P1_TX_DN<4>")
	)
	(arc
		(start 368.23396 -348.721172)
		(mid 368.19606 -348.827706)
		(end 368.13998 -348.925896)
		(width 0.14224)
		(layer "In4.Cu")
		(net "P5E_CPU0_P1_TX_DN<4>")
	)
	(arc
		(start 348.993714 -293.221156)
		(mid 348.836737 -293.525956)
		(end 348.993714 -293.830756)
		(width 0.1143)
		(layer "In4.Cu")
		(net "P5E_CPU0_P1_TX_DN<4>")
	)
	(arc
		(start 348.436692 -295.800272)
		(mid 348.381041 -295.883465)
		(end 348.361508 -295.981628)
		(width 0.1143)
		(layer "In4.Cu")
		(net "P5E_CPU0_P1_TX_DN<4>")
	)
	(arc
		(start 349.06331 -292.251384)
		(mid 349.306637 -292.71595)
		(end 349.06331 -293.180516)
		(width 0.1143)
		(layer "In4.Cu")
		(net "P5E_CPU0_P1_TX_DN<4>")
	)
	(arc
		(start 368.456464 -347.795596)
		(mid 368.452409 -347.85871)
		(end 368.440462 -347.920818)
		(width 0.14224)
		(layer "In4.Cu")
		(net "P5E_CPU0_P1_TX_DN<4>")
	)
	(arc
		(start 348.836742 -291.905944)
		(mid 348.878291 -292.077366)
		(end 348.993714 -292.210744)
		(width 0.1143)
		(layer "In4.Cu")
		(net "P5E_CPU0_P1_TX_DN<4>")
	)
	(arc
		(start 368.440716 -338.23402)
		(mid 368.452495 -338.321427)
		(end 368.456464 -338.409534)
		(width 0.14224)
		(layer "In4.Cu")
		(net "P5E_CPU0_P1_TX_DN<4>")
	)
	(arc
		(start 349.300546 -289.55873)
		(mid 349.298758 -289.570179)
		(end 349.296736 -289.58159)
		(width 0.1143)
		(layer "In4.Cu")
		(net "P5E_CPU0_P1_TX_DN<4>")
	)
	(arc
		(start 337.220814 -381.987298)
		(mid 337.233091 -382.049021)
		(end 337.268058 -382.101344)
		(width 0.14224)
		(layer "In4.Cu")
		(net "P5E_CPU0_P1_TX_DN<4>")
	)
	(arc
		(start 349.06331 -293.871396)
		(mid 349.306637 -294.335962)
		(end 349.06331 -294.800528)
		(width 0.1143)
		(layer "In4.Cu")
		(net "P5E_CPU0_P1_TX_DN<4>")
	)
	(arc
		(start 349.296736 -289.58159)
		(mid 349.215303 -289.783988)
		(end 349.06331 -289.940492)
		(width 0.1143)
		(layer "In4.Cu")
		(net "P5E_CPU0_P1_TX_DN<4>")
	)
	(arc
		(start 348.836742 -295.268142)
		(mid 348.812633 -295.389906)
		(end 348.743778 -295.493186)
		(width 0.1143)
		(layer "In4.Cu")
		(net "P5E_CPU0_P1_TX_DN<4>")
	)
	(arc
		(start 348.522544 -290.791646)
		(mid 348.366616 -291.095938)
		(end 348.522544 -291.40023)
		(width 0.1143)
		(layer "In4.Cu")
		(net "P5E_CPU0_P1_TX_DN<4>")
	)
	(arc
		(start 348.407228 -298.915836)
		(mid 348.409674 -298.940689)
		(end 348.41688 -298.964604)
		(width 0.14224)
		(layer "In4.Cu")
		(net "P5E_CPU0_P1_TX_DN<4>")
	)
	(segment
		(start 347.327982 -287.59023)
		(end 346.86113 -287.856168)
		(width 0.12954)
		(layer "F.Cu")
		(net "P5E_CPU0_P1_TX_DN<3>")
	)
	(segment
		(start 334.133444 -378.68733)
		(end 333.837534 -378.39142)
		(width 0.12954)
		(layer "F.Cu")
		(net "P5E_CPU0_P1_TX_DN<3>")
	)
	(segment
		(start 333.837534 -378.39142)
		(end 333.837534 -377.68784)
		(width 0.12954)
		(layer "F.Cu")
		(net "P5E_CPU0_P1_TX_DN<3>")
	)
	(segment
		(start 333.837534 -377.68784)
		(end 334.108044 -377.41733)
		(width 0.12954)
		(layer "F.Cu")
		(net "P5E_CPU0_P1_TX_DN<3>")
	)
	(segment
		(start 348.083886 -293.848536)
		(end 348.123002 -293.871396)
		(width 0.1143)
		(layer "In4.Cu")
		(net "P5E_CPU0_P1_TX_DN<3>")
	)
	(segment
		(start 348.083886 -293.203376)
		(end 348.053406 -293.221156)
		(width 0.1143)
		(layer "In4.Cu")
		(net "P5E_CPU0_P1_TX_DN<3>")
	)
	(segment
		(start 348.083886 -292.228524)
		(end 348.123002 -292.251384)
		(width 0.1143)
		(layer "In4.Cu")
		(net "P5E_CPU0_P1_TX_DN<3>")
	)
	(segment
		(start 356.164896 -361.872022)
		(end 333.921354 -375.22912)
		(width 0.14224)
		(layer "In4.Cu")
		(net "P5E_CPU0_P1_TX_DN<3>")
	)
	(segment
		(start 347.472508 -296.107104)
		(end 347.472508 -299.120814)
		(width 0.14224)
		(layer "In4.Cu")
		(net "P5E_CPU0_P1_TX_DN<3>")
	)
	(segment
		(start 347.583506 -291.400738)
		(end 347.613986 -291.418518)
		(width 0.1143)
		(layer "In4.Cu")
		(net "P5E_CPU0_P1_TX_DN<3>")
	)
	(segment
		(start 348.053406 -292.210744)
		(end 348.083886 -292.228524)
		(width 0.1143)
		(layer "In4.Cu")
		(net "P5E_CPU0_P1_TX_DN<3>")
	)
	(segment
		(start 351.588578 -309.05831)
		(end 353.0981 -311.31764)
		(width 0.14224)
		(layer "In4.Cu")
		(net "P5E_CPU0_P1_TX_DN<3>")
	)
	(segment
		(start 346.563188 -287.856168)
		(end 346.493338 -287.926018)
		(width 0.1143)
		(layer "In4.Cu")
		(net "P5E_CPU0_P1_TX_DN<3>")
	)
	(segment
		(start 348.123002 -294.800528)
		(end 348.053406 -294.841168)
		(width 0.1143)
		(layer "In4.Cu")
		(net "P5E_CPU0_P1_TX_DN<3>")
	)
	(segment
		(start 347.472508 -296.078656)
		(end 347.472508 -296.107104)
		(width 0.1143)
		(layer "In4.Cu")
		(net "P5E_CPU0_P1_TX_DN<3>")
	)
	(segment
		(start 333.817214 -375.413016)
		(end 333.817214 -377.1265)
		(width 0.14224)
		(layer "In4.Cu")
		(net "P5E_CPU0_P1_TX_DN<3>")
	)
	(segment
		(start 366.960658 -335.285588)
		(end 367.49482 -338.25688)
		(width 0.14224)
		(layer "In4.Cu")
		(net "P5E_CPU0_P1_TX_DN<3>")
	)
	(segment
		(start 348.053406 -293.830756)
		(end 348.083886 -293.848536)
		(width 0.1143)
		(layer "In4.Cu")
		(net "P5E_CPU0_P1_TX_DN<3>")
	)
	(segment
		(start 367.312956 -348.273878)
		(end 365.33836 -351.228914)
		(width 0.14224)
		(layer "In4.Cu")
		(net "P5E_CPU0_P1_TX_DN<3>")
	)
	(segment
		(start 365.24692 -351.352612)
		(end 359.120694 -358.835198)
		(width 0.14224)
		(layer "In4.Cu")
		(net "P5E_CPU0_P1_TX_DN<3>")
	)
	(segment
		(start 347.653102 -290.750498)
		(end 347.613986 -290.773358)
		(width 0.1143)
		(layer "In4.Cu")
		(net "P5E_CPU0_P1_TX_DN<3>")
	)
	(segment
		(start 347.426788 -296.032936)
		(end 347.472508 -296.078656)
		(width 0.1143)
		(layer "In4.Cu")
		(net "P5E_CPU0_P1_TX_DN<3>")
	)
	(segment
		(start 347.896434 -295.145968)
		(end 347.89618 -295.145714)
		(width 0.1143)
		(layer "In4.Cu")
		(net "P5E_CPU0_P1_TX_DN<3>")
	)
	(segment
		(start 359.029 -358.941624)
		(end 357.349298 -360.798872)
		(width 0.14224)
		(layer "In4.Cu")
		(net "P5E_CPU0_P1_TX_DN<3>")
	)
	(segment
		(start 346.86113 -287.856168)
		(end 346.563188 -287.856168)
		(width 0.1143)
		(layer "In4.Cu")
		(net "P5E_CPU0_P1_TX_DN<3>")
	)
	(segment
		(start 354.607368 -313.576716)
		(end 363.050582 -323.863716)
		(width 0.14224)
		(layer "In4.Cu")
		(net "P5E_CPU0_P1_TX_DN<3>")
	)
	(segment
		(start 347.89618 -295.145714)
		(end 347.89618 -295.347136)
		(width 0.1143)
		(layer "In4.Cu")
		(net "P5E_CPU0_P1_TX_DN<3>")
	)
	(segment
		(start 353.0981 -311.31764)
		(end 354.607368 -313.576716)
		(width 0.14224)
		(layer "In4.Cu")
		(net "P5E_CPU0_P1_TX_DN<3>")
	)
	(segment
		(start 347.613986 -290.773358)
		(end 347.583506 -290.791138)
		(width 0.1143)
		(layer "In4.Cu")
		(net "P5E_CPU0_P1_TX_DN<3>")
	)
	(segment
		(start 333.817214 -377.1265)
		(end 334.108044 -377.41733)
		(width 0.14224)
		(layer "In4.Cu")
		(net "P5E_CPU0_P1_TX_DN<3>")
	)
	(segment
		(start 347.472508 -299.120814)
		(end 351.588578 -309.05831)
		(width 0.14224)
		(layer "In4.Cu")
		(net "P5E_CPU0_P1_TX_DN<3>")
	)
	(segment
		(start 367.505996 -338.38261)
		(end 367.505996 -347.458538)
		(width 0.14224)
		(layer "In4.Cu")
		(net "P5E_CPU0_P1_TX_DN<3>")
	)
	(segment
		(start 347.615764 -289.799522)
		(end 347.653102 -289.821366)
		(width 0.1143)
		(layer "In4.Cu")
		(net "P5E_CPU0_P1_TX_DN<3>")
	)
	(segment
		(start 347.613986 -291.418518)
		(end 347.653102 -291.441378)
		(width 0.1143)
		(layer "In4.Cu")
		(net "P5E_CPU0_P1_TX_DN<3>")
	)
	(segment
		(start 347.426788 -296.000932)
		(end 347.426788 -296.032936)
		(width 0.1143)
		(layer "In4.Cu")
		(net "P5E_CPU0_P1_TX_DN<3>")
	)
	(segment
		(start 347.803216 -295.57218)
		(end 347.464126 -295.911016)
		(width 0.1143)
		(layer "In4.Cu")
		(net "P5E_CPU0_P1_TX_DN<3>")
	)
	(segment
		(start 363.050582 -323.863716)
		(end 366.960658 -335.285588)
		(width 0.14224)
		(layer "In4.Cu")
		(net "P5E_CPU0_P1_TX_DN<3>")
	)
	(segment
		(start 347.151706 -289.005264)
		(end 347.15196 -289.005518)
		(width 0.1143)
		(layer "In4.Cu")
		(net "P5E_CPU0_P1_TX_DN<3>")
	)
	(segment
		(start 348.123002 -293.180516)
		(end 348.083886 -293.203376)
		(width 0.1143)
		(layer "In4.Cu")
		(net "P5E_CPU0_P1_TX_DN<3>")
	)
	(segment
		(start 357.25989 -360.888534)
		(end 356.230428 -361.823254)
		(width 0.14224)
		(layer "In4.Cu")
		(net "P5E_CPU0_P1_TX_DN<3>")
	)
	(segment
		(start 347.15196 -289.005518)
		(end 347.236796 -289.054794)
		(width 0.1143)
		(layer "In4.Cu")
		(net "P5E_CPU0_P1_TX_DN<3>")
	)
	(segment
		(start 346.640658 -288.158936)
		(end 346.715334 -288.202878)
		(width 0.1143)
		(layer "In4.Cu")
		(net "P5E_CPU0_P1_TX_DN<3>")
	)
	(arc
		(start 346.715334 -288.202878)
		(mid 346.89253 -288.40489)
		(end 346.95638 -288.66592)
		(width 0.1143)
		(layer "In4.Cu")
		(net "P5E_CPU0_P1_TX_DN<3>")
	)
	(arc
		(start 347.653102 -289.821366)
		(mid 347.896429 -290.285932)
		(end 347.653102 -290.750498)
		(width 0.1143)
		(layer "In4.Cu")
		(net "P5E_CPU0_P1_TX_DN<3>")
	)
	(arc
		(start 356.230428 -361.823254)
		(mid 356.198859 -361.849246)
		(end 356.164896 -361.872022)
		(width 0.14224)
		(layer "In4.Cu")
		(net "P5E_CPU0_P1_TX_DN<3>")
	)
	(arc
		(start 347.236796 -289.054794)
		(mid 347.37494 -289.245829)
		(end 347.42628 -289.475926)
		(width 0.1143)
		(layer "In4.Cu")
		(net "P5E_CPU0_P1_TX_DN<3>")
	)
	(arc
		(start 348.053406 -293.221156)
		(mid 347.896429 -293.525956)
		(end 348.053406 -293.830756)
		(width 0.1143)
		(layer "In4.Cu")
		(net "P5E_CPU0_P1_TX_DN<3>")
	)
	(arc
		(start 347.653102 -291.441378)
		(mid 347.831915 -291.643728)
		(end 347.896434 -291.905944)
		(width 0.1143)
		(layer "In4.Cu")
		(net "P5E_CPU0_P1_TX_DN<3>")
	)
	(arc
		(start 348.123002 -292.251384)
		(mid 348.366329 -292.71595)
		(end 348.123002 -293.180516)
		(width 0.1143)
		(layer "In4.Cu")
		(net "P5E_CPU0_P1_TX_DN<3>")
	)
	(arc
		(start 347.896434 -291.905944)
		(mid 347.937983 -292.077366)
		(end 348.053406 -292.210744)
		(width 0.1143)
		(layer "In4.Cu")
		(net "P5E_CPU0_P1_TX_DN<3>")
	)
	(arc
		(start 367.505996 -347.458538)
		(mid 367.508011 -347.547819)
		(end 367.505996 -347.6371)
		(width 0.14224)
		(layer "In4.Cu")
		(net "P5E_CPU0_P1_TX_DN<3>")
	)
	(arc
		(start 348.053406 -294.841168)
		(mid 347.937979 -294.974544)
		(end 347.896434 -295.145968)
		(width 0.1143)
		(layer "In4.Cu")
		(net "P5E_CPU0_P1_TX_DN<3>")
	)
	(arc
		(start 357.349298 -360.798872)
		(mid 357.305697 -360.844803)
		(end 357.25989 -360.888534)
		(width 0.14224)
		(layer "In4.Cu")
		(net "P5E_CPU0_P1_TX_DN<3>")
	)
	(arc
		(start 367.49482 -338.25688)
		(mid 367.50321 -338.319496)
		(end 367.505996 -338.38261)
		(width 0.14224)
		(layer "In4.Cu")
		(net "P5E_CPU0_P1_TX_DN<3>")
	)
	(arc
		(start 346.493338 -287.926018)
		(mid 346.544828 -288.056491)
		(end 346.640658 -288.158936)
		(width 0.1143)
		(layer "In4.Cu")
		(net "P5E_CPU0_P1_TX_DN<3>")
	)
	(arc
		(start 347.583506 -290.791138)
		(mid 347.426529 -291.095938)
		(end 347.583506 -291.400738)
		(width 0.1143)
		(layer "In4.Cu")
		(net "P5E_CPU0_P1_TX_DN<3>")
	)
	(arc
		(start 367.505996 -347.6371)
		(mid 367.456754 -347.969824)
		(end 367.312956 -348.273878)
		(width 0.14224)
		(layer "In4.Cu")
		(net "P5E_CPU0_P1_TX_DN<3>")
	)
	(arc
		(start 347.89618 -295.347136)
		(mid 347.872071 -295.4689)
		(end 347.803216 -295.57218)
		(width 0.1143)
		(layer "In4.Cu")
		(net "P5E_CPU0_P1_TX_DN<3>")
	)
	(arc
		(start 347.42628 -289.475926)
		(mid 347.478638 -289.662537)
		(end 347.615764 -289.799522)
		(width 0.1143)
		(layer "In4.Cu")
		(net "P5E_CPU0_P1_TX_DN<3>")
	)
	(arc
		(start 347.464126 -295.911016)
		(mid 347.436507 -295.952256)
		(end 347.426788 -296.000932)
		(width 0.1143)
		(layer "In4.Cu")
		(net "P5E_CPU0_P1_TX_DN<3>")
	)
	(arc
		(start 359.120694 -358.835198)
		(mid 359.075498 -358.888972)
		(end 359.029 -358.941624)
		(width 0.14224)
		(layer "In4.Cu")
		(net "P5E_CPU0_P1_TX_DN<3>")
	)
	(arc
		(start 365.33836 -351.228914)
		(mid 365.294134 -351.291867)
		(end 365.24692 -351.352612)
		(width 0.14224)
		(layer "In4.Cu")
		(net "P5E_CPU0_P1_TX_DN<3>")
	)
	(arc
		(start 348.123002 -293.871396)
		(mid 348.366329 -294.335962)
		(end 348.123002 -294.800528)
		(width 0.1143)
		(layer "In4.Cu")
		(net "P5E_CPU0_P1_TX_DN<3>")
	)
	(arc
		(start 333.921354 -375.22912)
		(mid 333.845036 -375.307341)
		(end 333.817214 -375.413016)
		(width 0.14224)
		(layer "In4.Cu")
		(net "P5E_CPU0_P1_TX_DN<3>")
	)
	(arc
		(start 346.95638 -288.66592)
		(mid 347.0087 -288.861691)
		(end 347.151706 -289.005264)
		(width 0.1143)
		(layer "In4.Cu")
		(net "P5E_CPU0_P1_TX_DN<3>")
	)
	(segment
		(start 347.327982 -290.83)
		(end 346.86113 -291.095938)
		(width 0.12954)
		(layer "F.Cu")
		(net "P5E_CPU0_P1_TX_DN<2>")
	)
	(segment
		(start 332.135734 -380.15164)
		(end 332.406244 -379.88113)
		(width 0.12954)
		(layer "F.Cu")
		(net "P5E_CPU0_P1_TX_DN<2>")
	)
	(segment
		(start 332.431644 -381.15113)
		(end 332.135734 -380.85522)
		(width 0.12954)
		(layer "F.Cu")
		(net "P5E_CPU0_P1_TX_DN<2>")
	)
	(segment
		(start 332.135734 -380.85522)
		(end 332.135734 -380.15164)
		(width 0.12954)
		(layer "F.Cu")
		(net "P5E_CPU0_P1_TX_DN<2>")
	)
	(segment
		(start 347.183202 -293.180516)
		(end 347.123512 -293.215314)
		(width 0.1143)
		(layer "In4.Cu")
		(net "P5E_CPU0_P1_TX_DN<2>")
	)
	(segment
		(start 346.86113 -291.095938)
		(end 346.563188 -291.095938)
		(width 0.1143)
		(layer "In4.Cu")
		(net "P5E_CPU0_P1_TX_DN<2>")
	)
	(segment
		(start 347.122242 -293.83609)
		(end 347.12275 -293.83609)
		(width 0.1143)
		(layer "In4.Cu")
		(net "P5E_CPU0_P1_TX_DN<2>")
	)
	(segment
		(start 346.674186 -291.418518)
		(end 346.684092 -291.42436)
		(width 0.1143)
		(layer "In4.Cu")
		(net "P5E_CPU0_P1_TX_DN<2>")
	)
	(segment
		(start 347.143578 -292.22827)
		(end 347.18244 -292.250876)
		(width 0.1143)
		(layer "In4.Cu")
		(net "P5E_CPU0_P1_TX_DN<2>")
	)
	(segment
		(start 362.226352 -324.381368)
		(end 366.035336 -335.50733)
		(width 0.14224)
		(layer "In4.Cu")
		(net "P5E_CPU0_P1_TX_DN<2>")
	)
	(segment
		(start 355.86416 -360.888026)
		(end 332.74127 -374.747282)
		(width 0.14224)
		(layer "In4.Cu")
		(net "P5E_CPU0_P1_TX_DN<2>")
	)
	(segment
		(start 332.115414 -375.851928)
		(end 332.115414 -379.5903)
		(width 0.14224)
		(layer "In4.Cu")
		(net "P5E_CPU0_P1_TX_DN<2>")
	)
	(segment
		(start 346.95638 -295.145968)
		(end 346.95638 -295.347136)
		(width 0.1143)
		(layer "In4.Cu")
		(net "P5E_CPU0_P1_TX_DN<2>")
	)
	(segment
		(start 366.067086 -335.629758)
		(end 366.527842 -338.192364)
		(width 0.14224)
		(layer "In4.Cu")
		(net "P5E_CPU0_P1_TX_DN<2>")
	)
	(segment
		(start 346.863416 -295.57218)
		(end 346.523818 -295.911524)
		(width 0.1143)
		(layer "In4.Cu")
		(net "P5E_CPU0_P1_TX_DN<2>")
	)
	(segment
		(start 353.90201 -314.238132)
		(end 362.226352 -324.381368)
		(width 0.14224)
		(layer "In4.Cu")
		(net "P5E_CPU0_P1_TX_DN<2>")
	)
	(segment
		(start 347.185234 -294.799004)
		(end 347.113098 -294.841422)
		(width 0.1143)
		(layer "In4.Cu")
		(net "P5E_CPU0_P1_TX_DN<2>")
	)
	(segment
		(start 346.642436 -291.40023)
		(end 346.673424 -291.41801)
		(width 0.1143)
		(layer "In4.Cu")
		(net "P5E_CPU0_P1_TX_DN<2>")
	)
	(segment
		(start 346.96781 -291.914834)
		(end 346.96781 -291.923216)
		(width 0.1143)
		(layer "In4.Cu")
		(net "P5E_CPU0_P1_TX_DN<2>")
	)
	(segment
		(start 350.805242 -309.603394)
		(end 353.90201 -314.238132)
		(width 0.14224)
		(layer "In4.Cu")
		(net "P5E_CPU0_P1_TX_DN<2>")
	)
	(segment
		(start 346.48648 -296.00144)
		(end 346.48648 -296.032936)
		(width 0.1143)
		(layer "In4.Cu")
		(net "P5E_CPU0_P1_TX_DN<2>")
	)
	(segment
		(start 347.12275 -293.215822)
		(end 347.122496 -293.215822)
		(width 0.1143)
		(layer "In4.Cu")
		(net "P5E_CPU0_P1_TX_DN<2>")
	)
	(segment
		(start 346.48648 -296.032936)
		(end 346.5322 -296.078656)
		(width 0.1143)
		(layer "In4.Cu")
		(net "P5E_CPU0_P1_TX_DN<2>")
	)
	(segment
		(start 346.5322 -296.107104)
		(end 346.5322 -299.262292)
		(width 0.14224)
		(layer "In4.Cu")
		(net "P5E_CPU0_P1_TX_DN<2>")
	)
	(segment
		(start 366.036352 -348.453964)
		(end 355.86416 -360.888026)
		(width 0.14224)
		(layer "In4.Cu")
		(net "P5E_CPU0_P1_TX_DN<2>")
	)
	(segment
		(start 346.673424 -291.41801)
		(end 346.674186 -291.418518)
		(width 0.1143)
		(layer "In4.Cu")
		(net "P5E_CPU0_P1_TX_DN<2>")
	)
	(segment
		(start 347.123512 -293.215314)
		(end 347.12275 -293.215822)
		(width 0.1143)
		(layer "In4.Cu")
		(net "P5E_CPU0_P1_TX_DN<2>")
	)
	(segment
		(start 346.5322 -296.078656)
		(end 346.5322 -296.107104)
		(width 0.1143)
		(layer "In4.Cu")
		(net "P5E_CPU0_P1_TX_DN<2>")
	)
	(segment
		(start 346.563188 -291.095938)
		(end 346.493338 -291.165788)
		(width 0.1143)
		(layer "In4.Cu")
		(net "P5E_CPU0_P1_TX_DN<2>")
	)
	(segment
		(start 366.54359 -338.368132)
		(end 366.54359 -346.635324)
		(width 0.14224)
		(layer "In4.Cu")
		(net "P5E_CPU0_P1_TX_DN<2>")
	)
	(segment
		(start 347.12275 -293.83609)
		(end 347.18244 -293.870888)
		(width 0.1143)
		(layer "In4.Cu")
		(net "P5E_CPU0_P1_TX_DN<2>")
	)
	(segment
		(start 346.542106 -299.31233)
		(end 350.805242 -309.603394)
		(width 0.14224)
		(layer "In4.Cu")
		(net "P5E_CPU0_P1_TX_DN<2>")
	)
	(segment
		(start 332.115414 -379.5903)
		(end 332.406244 -379.88113)
		(width 0.14224)
		(layer "In4.Cu")
		(net "P5E_CPU0_P1_TX_DN<2>")
	)
	(segment
		(start 366.51819 -346.832682)
		(end 366.147604 -348.235778)
		(width 0.14224)
		(layer "In4.Cu")
		(net "P5E_CPU0_P1_TX_DN<2>")
	)
	(segment
		(start 347.183202 -293.871396)
		(end 347.185234 -293.87292)
		(width 0.1143)
		(layer "In4.Cu")
		(net "P5E_CPU0_P1_TX_DN<2>")
	)
	(arc
		(start 366.54359 -346.635324)
		(mid 366.537284 -346.734827)
		(end 366.51819 -346.832682)
		(width 0.14224)
		(layer "In4.Cu")
		(net "P5E_CPU0_P1_TX_DN<2>")
	)
	(arc
		(start 346.493338 -291.165788)
		(mid 346.545387 -291.297307)
		(end 346.642436 -291.40023)
		(width 0.1143)
		(layer "In4.Cu")
		(net "P5E_CPU0_P1_TX_DN<2>")
	)
	(arc
		(start 332.74127 -374.747282)
		(mid 332.282747 -375.217116)
		(end 332.115414 -375.851928)
		(width 0.14224)
		(layer "In4.Cu")
		(net "P5E_CPU0_P1_TX_DN<2>")
	)
	(arc
		(start 346.684092 -291.42436)
		(mid 346.891818 -291.631493)
		(end 346.96781 -291.914834)
		(width 0.1143)
		(layer "In4.Cu")
		(net "P5E_CPU0_P1_TX_DN<2>")
	)
	(arc
		(start 346.95638 -295.347136)
		(mid 346.932271 -295.4689)
		(end 346.863416 -295.57218)
		(width 0.1143)
		(layer "In4.Cu")
		(net "P5E_CPU0_P1_TX_DN<2>")
	)
	(arc
		(start 347.113098 -294.841422)
		(mid 346.997955 -294.974758)
		(end 346.95638 -295.145968)
		(width 0.1143)
		(layer "In4.Cu")
		(net "P5E_CPU0_P1_TX_DN<2>")
	)
	(arc
		(start 347.183202 -292.251384)
		(mid 347.426529 -292.71595)
		(end 347.183202 -293.180516)
		(width 0.1143)
		(layer "In4.Cu")
		(net "P5E_CPU0_P1_TX_DN<2>")
	)
	(arc
		(start 366.527842 -338.192364)
		(mid 366.539635 -338.279897)
		(end 366.54359 -338.368132)
		(width 0.14224)
		(layer "In4.Cu")
		(net "P5E_CPU0_P1_TX_DN<2>")
	)
	(arc
		(start 346.5322 -299.262292)
		(mid 346.534667 -299.287805)
		(end 346.542106 -299.31233)
		(width 0.14224)
		(layer "In4.Cu")
		(net "P5E_CPU0_P1_TX_DN<2>")
	)
	(arc
		(start 366.147604 -348.235778)
		(mid 366.103683 -348.350843)
		(end 366.036352 -348.453964)
		(width 0.14224)
		(layer "In4.Cu")
		(net "P5E_CPU0_P1_TX_DN<2>")
	)
	(arc
		(start 347.185234 -293.87292)
		(mid 347.427745 -294.335962)
		(end 347.185234 -294.799004)
		(width 0.1143)
		(layer "In4.Cu")
		(net "P5E_CPU0_P1_TX_DN<2>")
	)
	(arc
		(start 347.18244 -292.250876)
		(mid 347.182821 -292.25113)
		(end 347.183202 -292.251384)
		(width 0.1143)
		(layer "In4.Cu")
		(net "P5E_CPU0_P1_TX_DN<2>")
	)
	(arc
		(start 366.035336 -335.50733)
		(mid 366.053539 -335.56794)
		(end 366.067086 -335.629758)
		(width 0.14224)
		(layer "In4.Cu")
		(net "P5E_CPU0_P1_TX_DN<2>")
	)
	(arc
		(start 347.122496 -293.215822)
		(mid 346.943954 -293.525846)
		(end 347.122242 -293.83609)
		(width 0.1143)
		(layer "In4.Cu")
		(net "P5E_CPU0_P1_TX_DN<2>")
	)
	(arc
		(start 346.96781 -291.923216)
		(mid 347.0149 -292.099244)
		(end 347.143578 -292.22827)
		(width 0.1143)
		(layer "In4.Cu")
		(net "P5E_CPU0_P1_TX_DN<2>")
	)
	(arc
		(start 347.18244 -293.870888)
		(mid 347.182821 -293.871142)
		(end 347.183202 -293.871396)
		(width 0.1143)
		(layer "In4.Cu")
		(net "P5E_CPU0_P1_TX_DN<2>")
	)
	(arc
		(start 346.523818 -295.911524)
		(mid 346.496199 -295.952764)
		(end 346.48648 -296.00144)
		(width 0.1143)
		(layer "In4.Cu")
		(net "P5E_CPU0_P1_TX_DN<2>")
	)
	(segment
		(start 330.932282 -384.94335)
		(end 330.228702 -384.94335)
		(width 0.12954)
		(layer "F.Cu")
		(net "P5E_CPU0_P1_TX_DN<1>")
	)
	(segment
		(start 347.327982 -289.209988)
		(end 346.86113 -289.475926)
		(width 0.12954)
		(layer "F.Cu")
		(net "P5E_CPU0_P1_TX_DN<1>")
	)
	(segment
		(start 331.228192 -385.23926)
		(end 330.932282 -384.94335)
		(width 0.12954)
		(layer "F.Cu")
		(net "P5E_CPU0_P1_TX_DN<1>")
	)
	(segment
		(start 330.228702 -384.94335)
		(end 329.958192 -385.21386)
		(width 0.12954)
		(layer "F.Cu")
		(net "P5E_CPU0_P1_TX_DN<1>")
	)
	(segment
		(start 330.249022 -384.92303)
		(end 329.958192 -385.21386)
		(width 0.14224)
		(layer "In4.Cu")
		(net "P5E_CPU0_P1_TX_DN<1>")
	)
	(segment
		(start 345.546426 -296.00144)
		(end 345.546426 -296.032936)
		(width 0.1143)
		(layer "In4.Cu")
		(net "P5E_CPU0_P1_TX_DN<1>")
	)
	(segment
		(start 330.443078 -381.620014)
		(end 331.215492 -382.392428)
		(width 0.14224)
		(layer "In4.Cu")
		(net "P5E_CPU0_P1_TX_DN<1>")
	)
	(segment
		(start 355.102922 -360.220768)
		(end 331.17536 -374.56237)
		(width 0.14224)
		(layer "In4.Cu")
		(net "P5E_CPU0_P1_TX_DN<1>")
	)
	(segment
		(start 331.31633 -384.719322)
		(end 331.275182 -384.76047)
		(width 0.14224)
		(layer "In4.Cu")
		(net "P5E_CPU0_P1_TX_DN<1>")
	)
	(segment
		(start 346.243148 -293.180516)
		(end 346.204032 -293.203376)
		(width 0.1143)
		(layer "In4.Cu")
		(net "P5E_CPU0_P1_TX_DN<1>")
	)
	(segment
		(start 346.204032 -293.848536)
		(end 346.243148 -293.871396)
		(width 0.1143)
		(layer "In4.Cu")
		(net "P5E_CPU0_P1_TX_DN<1>")
	)
	(segment
		(start 346.173552 -293.830756)
		(end 346.204032 -293.848536)
		(width 0.1143)
		(layer "In4.Cu")
		(net "P5E_CPU0_P1_TX_DN<1>")
	)
	(segment
		(start 361.324144 -324.773544)
		(end 365.17453 -336.020664)
		(width 0.14224)
		(layer "In4.Cu")
		(net "P5E_CPU0_P1_TX_DN<1>")
	)
	(segment
		(start 353.22256 -314.902088)
		(end 361.324144 -324.773544)
		(width 0.14224)
		(layer "In4.Cu")
		(net "P5E_CPU0_P1_TX_DN<1>")
	)
	(segment
		(start 345.737688 -291.42055)
		(end 345.740228 -291.422074)
		(width 0.1143)
		(layer "In4.Cu")
		(net "P5E_CPU0_P1_TX_DN<1>")
	)
	(segment
		(start 346.204032 -289.963352)
		(end 346.173552 -289.981132)
		(width 0.1143)
		(layer "In4.Cu")
		(net "P5E_CPU0_P1_TX_DN<1>")
	)
	(segment
		(start 346.01658 -295.145968)
		(end 346.016326 -295.145714)
		(width 0.1143)
		(layer "In4.Cu")
		(net "P5E_CPU0_P1_TX_DN<1>")
	)
	(segment
		(start 345.736672 -291.420042)
		(end 345.737688 -291.42055)
		(width 0.1143)
		(layer "In4.Cu")
		(net "P5E_CPU0_P1_TX_DN<1>")
	)
	(segment
		(start 330.883006 -384.92303)
		(end 330.249022 -384.92303)
		(width 0.14224)
		(layer "In4.Cu")
		(net "P5E_CPU0_P1_TX_DN<1>")
	)
	(segment
		(start 345.923362 -295.57218)
		(end 345.583764 -295.911524)
		(width 0.1143)
		(layer "In4.Cu")
		(net "P5E_CPU0_P1_TX_DN<1>")
	)
	(segment
		(start 345.546426 -296.032936)
		(end 345.592146 -296.078656)
		(width 0.1143)
		(layer "In4.Cu")
		(net "P5E_CPU0_P1_TX_DN<1>")
	)
	(segment
		(start 346.243148 -289.940492)
		(end 346.204032 -289.963352)
		(width 0.1143)
		(layer "In4.Cu")
		(net "P5E_CPU0_P1_TX_DN<1>")
	)
	(segment
		(start 346.204032 -292.228524)
		(end 346.243148 -292.251384)
		(width 0.1143)
		(layer "In4.Cu")
		(net "P5E_CPU0_P1_TX_DN<1>")
	)
	(segment
		(start 346.173552 -292.210744)
		(end 346.204032 -292.228524)
		(width 0.1143)
		(layer "In4.Cu")
		(net "P5E_CPU0_P1_TX_DN<1>")
	)
	(segment
		(start 345.605862 -299.498512)
		(end 349.969328 -310.032908)
		(width 0.14224)
		(layer "In4.Cu")
		(net "P5E_CPU0_P1_TX_DN<1>")
	)
	(segment
		(start 345.735148 -291.419026)
		(end 345.736672 -291.420042)
		(width 0.1143)
		(layer "In4.Cu")
		(net "P5E_CPU0_P1_TX_DN<1>")
	)
	(segment
		(start 364.757716 -348.433898)
		(end 355.102922 -360.220768)
		(width 0.14224)
		(layer "In4.Cu")
		(net "P5E_CPU0_P1_TX_DN<1>")
	)
	(segment
		(start 345.73337 -290.773866)
		(end 345.7321 -290.774628)
		(width 0.1143)
		(layer "In4.Cu")
		(net "P5E_CPU0_P1_TX_DN<1>")
	)
	(segment
		(start 346.243148 -294.800528)
		(end 346.173552 -294.841168)
		(width 0.1143)
		(layer "In4.Cu")
		(net "P5E_CPU0_P1_TX_DN<1>")
	)
	(segment
		(start 346.204032 -293.203376)
		(end 346.173552 -293.221156)
		(width 0.1143)
		(layer "In4.Cu")
		(net "P5E_CPU0_P1_TX_DN<1>")
	)
	(segment
		(start 345.741752 -291.42309)
		(end 345.773248 -291.441378)
		(width 0.1143)
		(layer "In4.Cu")
		(net "P5E_CPU0_P1_TX_DN<1>")
	)
	(segment
		(start 345.7321 -290.774628)
		(end 345.702382 -290.791646)
		(width 0.1143)
		(layer "In4.Cu")
		(net "P5E_CPU0_P1_TX_DN<1>")
	)
	(segment
		(start 330.323952 -376.065796)
		(end 330.323952 -381.332486)
		(width 0.14224)
		(layer "In4.Cu")
		(net "P5E_CPU0_P1_TX_DN<1>")
	)
	(segment
		(start 345.592146 -296.078656)
		(end 345.592146 -296.107104)
		(width 0.1143)
		(layer "In4.Cu")
		(net "P5E_CPU0_P1_TX_DN<1>")
	)
	(segment
		(start 346.563188 -289.475926)
		(end 346.480384 -289.55873)
		(width 0.1143)
		(layer "In4.Cu")
		(net "P5E_CPU0_P1_TX_DN<1>")
	)
	(segment
		(start 345.702382 -291.40023)
		(end 345.734132 -291.418518)
		(width 0.1143)
		(layer "In4.Cu")
		(net "P5E_CPU0_P1_TX_DN<1>")
	)
	(segment
		(start 346.86113 -289.475926)
		(end 346.563188 -289.475926)
		(width 0.1143)
		(layer "In4.Cu")
		(net "P5E_CPU0_P1_TX_DN<1>")
	)
	(segment
		(start 345.740228 -291.422074)
		(end 345.741752 -291.42309)
		(width 0.1143)
		(layer "In4.Cu")
		(net "P5E_CPU0_P1_TX_DN<1>")
	)
	(segment
		(start 345.734132 -291.418518)
		(end 345.735148 -291.419026)
		(width 0.1143)
		(layer "In4.Cu")
		(net "P5E_CPU0_P1_TX_DN<1>")
	)
	(segment
		(start 331.436218 -382.92532)
		(end 331.436218 -384.430016)
		(width 0.14224)
		(layer "In4.Cu")
		(net "P5E_CPU0_P1_TX_DN<1>")
	)
	(segment
		(start 365.17453 -336.020664)
		(end 365.600234 -338.389722)
		(width 0.14224)
		(layer "In4.Cu")
		(net "P5E_CPU0_P1_TX_DN<1>")
	)
	(segment
		(start 345.734132 -290.773358)
		(end 345.73337 -290.773866)
		(width 0.1143)
		(layer "In4.Cu")
		(net "P5E_CPU0_P1_TX_DN<1>")
	)
	(segment
		(start 346.016326 -295.145714)
		(end 346.016326 -295.347136)
		(width 0.1143)
		(layer "In4.Cu")
		(net "P5E_CPU0_P1_TX_DN<1>")
	)
	(segment
		(start 345.592146 -296.107104)
		(end 345.592146 -299.42917)
		(width 0.14224)
		(layer "In4.Cu")
		(net "P5E_CPU0_P1_TX_DN<1>")
	)
	(segment
		(start 345.736672 -290.771834)
		(end 345.735148 -290.77285)
		(width 0.1143)
		(layer "In4.Cu")
		(net "P5E_CPU0_P1_TX_DN<1>")
	)
	(segment
		(start 345.735148 -290.77285)
		(end 345.734132 -290.773358)
		(width 0.1143)
		(layer "In4.Cu")
		(net "P5E_CPU0_P1_TX_DN<1>")
	)
	(segment
		(start 345.773248 -290.750498)
		(end 345.736672 -290.771834)
		(width 0.1143)
		(layer "In4.Cu")
		(net "P5E_CPU0_P1_TX_DN<1>")
	)
	(segment
		(start 349.969328 -310.032908)
		(end 353.22256 -314.902088)
		(width 0.14224)
		(layer "In4.Cu")
		(net "P5E_CPU0_P1_TX_DN<1>")
	)
	(segment
		(start 365.61141 -338.515452)
		(end 365.61141 -346.043758)
		(width 0.14224)
		(layer "In4.Cu")
		(net "P5E_CPU0_P1_TX_DN<1>")
	)
	(arc
		(start 346.016326 -295.347136)
		(mid 345.992217 -295.4689)
		(end 345.923362 -295.57218)
		(width 0.1143)
		(layer "In4.Cu")
		(net "P5E_CPU0_P1_TX_DN<1>")
	)
	(arc
		(start 345.702382 -290.791646)
		(mid 345.546454 -291.095938)
		(end 345.702382 -291.40023)
		(width 0.1143)
		(layer "In4.Cu")
		(net "P5E_CPU0_P1_TX_DN<1>")
	)
	(arc
		(start 331.17536 -374.56237)
		(mid 330.551511 -375.201874)
		(end 330.323952 -376.065796)
		(width 0.14224)
		(layer "In4.Cu")
		(net "P5E_CPU0_P1_TX_DN<1>")
	)
	(arc
		(start 331.275182 -384.76047)
		(mid 331.095265 -384.88078)
		(end 330.883006 -384.92303)
		(width 0.14224)
		(layer "In4.Cu")
		(net "P5E_CPU0_P1_TX_DN<1>")
	)
	(arc
		(start 346.243148 -292.251384)
		(mid 346.486475 -292.71595)
		(end 346.243148 -293.180516)
		(width 0.1143)
		(layer "In4.Cu")
		(net "P5E_CPU0_P1_TX_DN<1>")
	)
	(arc
		(start 346.173552 -293.221156)
		(mid 346.016575 -293.525956)
		(end 346.173552 -293.830756)
		(width 0.1143)
		(layer "In4.Cu")
		(net "P5E_CPU0_P1_TX_DN<1>")
	)
	(arc
		(start 345.592146 -299.42917)
		(mid 345.595579 -299.464519)
		(end 345.605862 -299.498512)
		(width 0.14224)
		(layer "In4.Cu")
		(net "P5E_CPU0_P1_TX_DN<1>")
	)
	(arc
		(start 346.173552 -289.981132)
		(mid 346.058125 -290.114508)
		(end 346.01658 -290.285932)
		(width 0.1143)
		(layer "In4.Cu")
		(net "P5E_CPU0_P1_TX_DN<1>")
	)
	(arc
		(start 345.773248 -291.441378)
		(mid 345.952061 -291.643728)
		(end 346.01658 -291.905944)
		(width 0.1143)
		(layer "In4.Cu")
		(net "P5E_CPU0_P1_TX_DN<1>")
	)
	(arc
		(start 346.476574 -289.58159)
		(mid 346.395141 -289.783988)
		(end 346.243148 -289.940492)
		(width 0.1143)
		(layer "In4.Cu")
		(net "P5E_CPU0_P1_TX_DN<1>")
	)
	(arc
		(start 330.323952 -381.332486)
		(mid 330.354907 -381.488106)
		(end 330.443078 -381.620014)
		(width 0.14224)
		(layer "In4.Cu")
		(net "P5E_CPU0_P1_TX_DN<1>")
	)
	(arc
		(start 346.01658 -290.285932)
		(mid 345.952065 -290.548151)
		(end 345.773248 -290.750498)
		(width 0.1143)
		(layer "In4.Cu")
		(net "P5E_CPU0_P1_TX_DN<1>")
	)
	(arc
		(start 365.61141 -346.043758)
		(mid 365.391629 -347.312789)
		(end 364.757716 -348.433898)
		(width 0.14224)
		(layer "In4.Cu")
		(net "P5E_CPU0_P1_TX_DN<1>")
	)
	(arc
		(start 346.243148 -293.871396)
		(mid 346.486475 -294.335962)
		(end 346.243148 -294.800528)
		(width 0.1143)
		(layer "In4.Cu")
		(net "P5E_CPU0_P1_TX_DN<1>")
	)
	(arc
		(start 346.173552 -294.841168)
		(mid 346.058049 -294.97452)
		(end 346.01658 -295.145968)
		(width 0.1143)
		(layer "In4.Cu")
		(net "P5E_CPU0_P1_TX_DN<1>")
	)
	(arc
		(start 331.215492 -382.392428)
		(mid 331.378857 -382.636921)
		(end 331.436218 -382.92532)
		(width 0.14224)
		(layer "In4.Cu")
		(net "P5E_CPU0_P1_TX_DN<1>")
	)
	(arc
		(start 345.583764 -295.911524)
		(mid 345.556145 -295.952764)
		(end 345.546426 -296.00144)
		(width 0.1143)
		(layer "In4.Cu")
		(net "P5E_CPU0_P1_TX_DN<1>")
	)
	(arc
		(start 331.436218 -384.430016)
		(mid 331.405055 -384.586594)
		(end 331.31633 -384.719322)
		(width 0.14224)
		(layer "In4.Cu")
		(net "P5E_CPU0_P1_TX_DN<1>")
	)
	(arc
		(start 346.480384 -289.55873)
		(mid 346.478596 -289.570179)
		(end 346.476574 -289.58159)
		(width 0.1143)
		(layer "In4.Cu")
		(net "P5E_CPU0_P1_TX_DN<1>")
	)
	(arc
		(start 365.600234 -338.389722)
		(mid 365.608621 -338.452339)
		(end 365.61141 -338.515452)
		(width 0.14224)
		(layer "In4.Cu")
		(net "P5E_CPU0_P1_TX_DN<1>")
	)
	(arc
		(start 346.01658 -291.905944)
		(mid 346.058129 -292.077366)
		(end 346.173552 -292.210744)
		(width 0.1143)
		(layer "In4.Cu")
		(net "P5E_CPU0_P1_TX_DN<1>")
	)
	(segment
		(start 358.137968 -286.780224)
		(end 357.671116 -287.045908)
		(width 0.12954)
		(layer "F.Cu")
		(net "P5E_CPU0_P1_TX_DN<15>")
	)
	(segment
		(start 358.535224 -388.767828)
		(end 358.831134 -388.471918)
		(width 0.12954)
		(layer "F.Cu")
		(net "P5E_CPU0_P1_TX_DN<15>")
	)
	(segment
		(start 359.534714 -388.471918)
		(end 359.805224 -388.742428)
		(width 0.12954)
		(layer "F.Cu")
		(net "P5E_CPU0_P1_TX_DN<15>")
	)
	(segment
		(start 358.831134 -388.471918)
		(end 359.534714 -388.471918)
		(width 0.12954)
		(layer "F.Cu")
		(net "P5E_CPU0_P1_TX_DN<15>")
	)
	(segment
		(start 357.452422 -287.3502)
		(end 357.518716 -287.388808)
		(width 0.1143)
		(layer "In4.Cu")
		(net "P5E_CPU0_P1_TX_DN<15>")
	)
	(segment
		(start 359.37571 -289.76447)
		(end 359.37571 -290.2077)
		(width 0.1143)
		(layer "In4.Cu")
		(net "P5E_CPU0_P1_TX_DN<15>")
	)
	(segment
		(start 358.423972 -288.9885)
		(end 358.424226 -288.988754)
		(width 0.1143)
		(layer "In4.Cu")
		(net "P5E_CPU0_P1_TX_DN<15>")
	)
	(segment
		(start 358.393492 -288.97072)
		(end 358.423972 -288.9885)
		(width 0.1143)
		(layer "In4.Cu")
		(net "P5E_CPU0_P1_TX_DN<15>")
	)
	(segment
		(start 361.708954 -382.717802)
		(end 361.708954 -387.552438)
		(width 0.14224)
		(layer "In4.Cu")
		(net "P5E_CPU0_P1_TX_DN<15>")
	)
	(segment
		(start 372.445534 -317.537592)
		(end 373.897144 -320.315082)
		(width 0.14224)
		(layer "In4.Cu")
		(net "P5E_CPU0_P1_TX_DN<15>")
	)
	(segment
		(start 378.136404 -352.991166)
		(end 362.726224 -375.803668)
		(width 0.14224)
		(layer "In4.Cu")
		(net "P5E_CPU0_P1_TX_DN<15>")
	)
	(segment
		(start 361.589066 -387.841744)
		(end 361.13847 -388.29234)
		(width 0.14224)
		(layer "In4.Cu")
		(net "P5E_CPU0_P1_TX_DN<15>")
	)
	(segment
		(start 359.42143 -290.281868)
		(end 359.42143 -298.69892)
		(width 0.14224)
		(layer "In4.Cu")
		(net "P5E_CPU0_P1_TX_DN<15>")
	)
	(segment
		(start 363.878622 -307.086)
		(end 372.399052 -317.467488)
		(width 0.14224)
		(layer "In4.Cu")
		(net "P5E_CPU0_P1_TX_DN<15>")
	)
	(segment
		(start 362.191554 -377.550426)
		(end 362.191554 -381.626364)
		(width 0.14224)
		(layer "In4.Cu")
		(net "P5E_CPU0_P1_TX_DN<15>")
	)
	(segment
		(start 360.096054 -388.451598)
		(end 359.805224 -388.742428)
		(width 0.14224)
		(layer "In4.Cu")
		(net "P5E_CPU0_P1_TX_DN<15>")
	)
	(segment
		(start 378.943616 -337.921346)
		(end 378.943616 -349.0468)
		(width 0.14224)
		(layer "In4.Cu")
		(net "P5E_CPU0_P1_TX_DN<15>")
	)
	(segment
		(start 373.921782 -320.372232)
		(end 377.881388 -331.94498)
		(width 0.14224)
		(layer "In4.Cu")
		(net "P5E_CPU0_P1_TX_DN<15>")
	)
	(segment
		(start 360.754168 -388.451598)
		(end 360.096054 -388.451598)
		(width 0.14224)
		(layer "In4.Cu")
		(net "P5E_CPU0_P1_TX_DN<15>")
	)
	(segment
		(start 357.96728 -288.186114)
		(end 357.993188 -288.201354)
		(width 0.1143)
		(layer "In4.Cu")
		(net "P5E_CPU0_P1_TX_DN<15>")
	)
	(segment
		(start 378.943616 -349.0468)
		(end 378.136404 -352.991166)
		(width 0.14224)
		(layer "In4.Cu")
		(net "P5E_CPU0_P1_TX_DN<15>")
	)
	(segment
		(start 357.950008 -288.176716)
		(end 357.951024 -288.177224)
		(width 0.1143)
		(layer "In4.Cu")
		(net "P5E_CPU0_P1_TX_DN<15>")
	)
	(segment
		(start 359.42143 -290.25342)
		(end 359.42143 -290.281868)
		(width 0.1143)
		(layer "In4.Cu")
		(net "P5E_CPU0_P1_TX_DN<15>")
	)
	(segment
		(start 377.881388 -331.94498)
		(end 377.881388 -331.945234)
		(width 0.14224)
		(layer "In4.Cu")
		(net "P5E_CPU0_P1_TX_DN<15>")
	)
	(segment
		(start 357.671116 -287.045908)
		(end 357.373174 -287.045908)
		(width 0.1143)
		(layer "In4.Cu")
		(net "P5E_CPU0_P1_TX_DN<15>")
	)
	(segment
		(start 358.541066 -289.078924)
		(end 359.37571 -289.76447)
		(width 0.1143)
		(layer "In4.Cu")
		(net "P5E_CPU0_P1_TX_DN<15>")
	)
	(segment
		(start 357.951024 -288.177224)
		(end 357.96728 -288.186114)
		(width 0.1143)
		(layer "In4.Cu")
		(net "P5E_CPU0_P1_TX_DN<15>")
	)
	(segment
		(start 361.91317 -382.298194)
		(end 361.861354 -382.35001)
		(width 0.14224)
		(layer "In4.Cu")
		(net "P5E_CPU0_P1_TX_DN<15>")
	)
	(segment
		(start 377.896882 -332.005432)
		(end 378.928122 -337.745324)
		(width 0.14224)
		(layer "In4.Cu")
		(net "P5E_CPU0_P1_TX_DN<15>")
	)
	(segment
		(start 359.37571 -290.2077)
		(end 359.42143 -290.25342)
		(width 0.1143)
		(layer "In4.Cu")
		(net "P5E_CPU0_P1_TX_DN<15>")
	)
	(segment
		(start 357.373174 -287.045908)
		(end 357.303324 -287.115758)
		(width 0.1143)
		(layer "In4.Cu")
		(net "P5E_CPU0_P1_TX_DN<15>")
	)
	(segment
		(start 359.431082 -298.747688)
		(end 361.2642 -303.172876)
		(width 0.14224)
		(layer "In4.Cu")
		(net "P5E_CPU0_P1_TX_DN<15>")
	)
	(segment
		(start 358.539542 -289.0774)
		(end 358.541066 -289.078924)
		(width 0.1143)
		(layer "In4.Cu")
		(net "P5E_CPU0_P1_TX_DN<15>")
	)
	(segment
		(start 361.2642 -303.172876)
		(end 363.878622 -307.086)
		(width 0.14224)
		(layer "In4.Cu")
		(net "P5E_CPU0_P1_TX_DN<15>")
	)
	(arc
		(start 378.928122 -337.745324)
		(mid 378.939777 -337.832991)
		(end 378.943616 -337.921346)
		(width 0.14224)
		(layer "In4.Cu")
		(net "P5E_CPU0_P1_TX_DN<15>")
	)
	(arc
		(start 372.399052 -317.467488)
		(mid 372.4241 -317.501342)
		(end 372.445534 -317.537592)
		(width 0.14224)
		(layer "In4.Cu")
		(net "P5E_CPU0_P1_TX_DN<15>")
	)
	(arc
		(start 358.23652 -288.66592)
		(mid 358.278069 -288.837342)
		(end 358.393492 -288.97072)
		(width 0.1143)
		(layer "In4.Cu")
		(net "P5E_CPU0_P1_TX_DN<15>")
	)
	(arc
		(start 377.881388 -331.945234)
		(mid 377.890284 -331.975037)
		(end 377.896882 -332.005432)
		(width 0.14224)
		(layer "In4.Cu")
		(net "P5E_CPU0_P1_TX_DN<15>")
	)
	(arc
		(start 357.993188 -288.201354)
		(mid 358.172001 -288.403704)
		(end 358.23652 -288.66592)
		(width 0.1143)
		(layer "In4.Cu")
		(net "P5E_CPU0_P1_TX_DN<15>")
	)
	(arc
		(start 362.726224 -375.803668)
		(mid 362.328213 -376.637048)
		(end 362.191554 -377.550426)
		(width 0.14224)
		(layer "In4.Cu")
		(net "P5E_CPU0_P1_TX_DN<15>")
	)
	(arc
		(start 373.897144 -320.315082)
		(mid 373.910558 -320.343185)
		(end 373.921782 -320.372232)
		(width 0.14224)
		(layer "In4.Cu")
		(net "P5E_CPU0_P1_TX_DN<15>")
	)
	(arc
		(start 361.13847 -388.29234)
		(mid 360.962165 -388.410206)
		(end 360.754168 -388.451598)
		(width 0.14224)
		(layer "In4.Cu")
		(net "P5E_CPU0_P1_TX_DN<15>")
	)
	(arc
		(start 357.766366 -287.865566)
		(mid 357.817786 -288.045006)
		(end 357.950008 -288.176716)
		(width 0.1143)
		(layer "In4.Cu")
		(net "P5E_CPU0_P1_TX_DN<15>")
	)
	(arc
		(start 357.303324 -287.115758)
		(mid 357.355373 -287.247277)
		(end 357.452422 -287.3502)
		(width 0.1143)
		(layer "In4.Cu")
		(net "P5E_CPU0_P1_TX_DN<15>")
	)
	(arc
		(start 361.861354 -382.35001)
		(mid 361.748549 -382.51874)
		(end 361.708954 -382.717802)
		(width 0.14224)
		(layer "In4.Cu")
		(net "P5E_CPU0_P1_TX_DN<15>")
	)
	(arc
		(start 359.42143 -298.69892)
		(mid 359.423876 -298.723773)
		(end 359.431082 -298.747688)
		(width 0.14224)
		(layer "In4.Cu")
		(net "P5E_CPU0_P1_TX_DN<15>")
	)
	(arc
		(start 361.708954 -387.552438)
		(mid 361.677791 -387.709016)
		(end 361.589066 -387.841744)
		(width 0.14224)
		(layer "In4.Cu")
		(net "P5E_CPU0_P1_TX_DN<15>")
	)
	(arc
		(start 357.76281 -287.820862)
		(mid 357.765165 -287.843168)
		(end 357.766366 -287.865566)
		(width 0.1143)
		(layer "In4.Cu")
		(net "P5E_CPU0_P1_TX_DN<15>")
	)
	(arc
		(start 358.424226 -288.988754)
		(mid 358.484756 -289.029341)
		(end 358.539542 -289.0774)
		(width 0.1143)
		(layer "In4.Cu")
		(net "P5E_CPU0_P1_TX_DN<15>")
	)
	(arc
		(start 357.518716 -287.388808)
		(mid 357.681506 -287.581816)
		(end 357.76281 -287.820862)
		(width 0.1143)
		(layer "In4.Cu")
		(net "P5E_CPU0_P1_TX_DN<15>")
	)
	(arc
		(start 362.191554 -381.626364)
		(mid 362.119208 -381.989981)
		(end 361.91317 -382.298194)
		(width 0.14224)
		(layer "In4.Cu")
		(net "P5E_CPU0_P1_TX_DN<15>")
	)
	(segment
		(start 358.137968 -288.399982)
		(end 357.671116 -288.66592)
		(width 0.12954)
		(layer "F.Cu")
		(net "P5E_CPU0_P1_TX_DN<14>")
	)
	(segment
		(start 359.534714 -384.745738)
		(end 359.805224 -384.475228)
		(width 0.12954)
		(layer "F.Cu")
		(net "P5E_CPU0_P1_TX_DN<14>")
	)
	(segment
		(start 358.831134 -384.745738)
		(end 359.534714 -384.745738)
		(width 0.12954)
		(layer "F.Cu")
		(net "P5E_CPU0_P1_TX_DN<14>")
	)
	(segment
		(start 358.535224 -384.449828)
		(end 358.831134 -384.745738)
		(width 0.12954)
		(layer "F.Cu")
		(net "P5E_CPU0_P1_TX_DN<14>")
	)
	(segment
		(start 358.281986 -295.557194)
		(end 358.281986 -298.306744)
		(width 0.14224)
		(layer "In4.Cu")
		(net "P5E_CPU0_P1_TX_DN<14>")
	)
	(segment
		(start 358.42321 -290.608004)
		(end 358.423972 -290.608512)
		(width 0.1143)
		(layer "In4.Cu")
		(net "P5E_CPU0_P1_TX_DN<14>")
	)
	(segment
		(start 358.50195 -294.773604)
		(end 358.423972 -294.823388)
		(width 0.1143)
		(layer "In4.Cu")
		(net "P5E_CPU0_P1_TX_DN<14>")
	)
	(segment
		(start 361.258104 -376.570494)
		(end 361.258104 -380.747016)
		(width 0.14224)
		(layer "In4.Cu")
		(net "P5E_CPU0_P1_TX_DN<14>")
	)
	(segment
		(start 358.60736 -384.487674)
		(end 358.848406 -384.72872)
		(width 0.14224)
		(layer "In4.Cu")
		(net "P5E_CPU0_P1_TX_DN<14>")
	)
	(segment
		(start 359.514394 -384.766058)
		(end 359.805224 -384.475228)
		(width 0.14224)
		(layer "In4.Cu")
		(net "P5E_CPU0_P1_TX_DN<14>")
	)
	(segment
		(start 358.463088 -293.180516)
		(end 358.456484 -293.184326)
		(width 0.1143)
		(layer "In4.Cu")
		(net "P5E_CPU0_P1_TX_DN<14>")
	)
	(segment
		(start 359.61193 -382.77927)
		(end 359.61193 -382.973326)
		(width 0.14224)
		(layer "In4.Cu")
		(net "P5E_CPU0_P1_TX_DN<14>")
	)
	(segment
		(start 360.985054 -381.406146)
		(end 360.40949 -381.98171)
		(width 0.14224)
		(layer "In4.Cu")
		(net "P5E_CPU0_P1_TX_DN<14>")
	)
	(segment
		(start 358.393492 -290.590732)
		(end 358.42321 -290.608004)
		(width 0.1143)
		(layer "In4.Cu")
		(net "P5E_CPU0_P1_TX_DN<14>")
	)
	(segment
		(start 362.741972 -373.695722)
		(end 362.30433 -374.330976)
		(width 0.14224)
		(layer "In4.Cu")
		(net "P5E_CPU0_P1_TX_DN<14>")
	)
	(segment
		(start 363.1184 -307.63845)
		(end 371.656102 -318.040512)
		(width 0.14224)
		(layer "In4.Cu")
		(net "P5E_CPU0_P1_TX_DN<14>")
	)
	(segment
		(start 358.423972 -294.823388)
		(end 358.393238 -294.841168)
		(width 0.1143)
		(layer "In4.Cu")
		(net "P5E_CPU0_P1_TX_DN<14>")
	)
	(segment
		(start 359.913428 -382.477772)
		(end 359.61193 -382.77927)
		(width 0.14224)
		(layer "In4.Cu")
		(net "P5E_CPU0_P1_TX_DN<14>")
	)
	(segment
		(start 363.13999 -373.118126)
		(end 363.175042 -373.30888)
		(width 0.14224)
		(layer "In4.Cu")
		(net "P5E_CPU0_P1_TX_DN<14>")
	)
	(segment
		(start 377.998736 -348.793054)
		(end 377.132342 -352.810826)
		(width 0.14224)
		(layer "In4.Cu")
		(net "P5E_CPU0_P1_TX_DN<14>")
	)
	(segment
		(start 377.998736 -337.847686)
		(end 377.998736 -348.793054)
		(width 0.14224)
		(layer "In4.Cu")
		(net "P5E_CPU0_P1_TX_DN<14>")
	)
	(segment
		(start 373.052086 -320.711068)
		(end 376.986038 -332.208378)
		(width 0.14224)
		(layer "In4.Cu")
		(net "P5E_CPU0_P1_TX_DN<14>")
	)
	(segment
		(start 358.706166 -292.702742)
		(end 358.706166 -292.71595)
		(width 0.1143)
		(layer "In4.Cu")
		(net "P5E_CPU0_P1_TX_DN<14>")
	)
	(segment
		(start 363.175042 -373.30888)
		(end 362.932726 -373.66067)
		(width 0.14224)
		(layer "In4.Cu")
		(net "P5E_CPU0_P1_TX_DN<14>")
	)
	(segment
		(start 362.332524 -374.484392)
		(end 362.090208 -374.836182)
		(width 0.14224)
		(layer "In4.Cu")
		(net "P5E_CPU0_P1_TX_DN<14>")
	)
	(segment
		(start 360.40949 -381.98171)
		(end 360.40949 -382.175766)
		(width 0.14224)
		(layer "In4.Cu")
		(net "P5E_CPU0_P1_TX_DN<14>")
	)
	(segment
		(start 358.425242 -293.202868)
		(end 358.424226 -293.203376)
		(width 0.1143)
		(layer "In4.Cu")
		(net "P5E_CPU0_P1_TX_DN<14>")
	)
	(segment
		(start 360.107484 -382.477772)
		(end 359.913428 -382.477772)
		(width 0.14224)
		(layer "In4.Cu")
		(net "P5E_CPU0_P1_TX_DN<14>")
	)
	(segment
		(start 358.423972 -291.583364)
		(end 358.393492 -291.601144)
		(width 0.1143)
		(layer "In4.Cu")
		(net "P5E_CPU0_P1_TX_DN<14>")
	)
	(segment
		(start 358.938322 -384.766058)
		(end 359.514394 -384.766058)
		(width 0.14224)
		(layer "In4.Cu")
		(net "P5E_CPU0_P1_TX_DN<14>")
	)
	(segment
		(start 360.451146 -303.646586)
		(end 363.1184 -307.63845)
		(width 0.14224)
		(layer "In4.Cu")
		(net "P5E_CPU0_P1_TX_DN<14>")
	)
	(segment
		(start 358.236266 -295.483026)
		(end 358.281986 -295.528746)
		(width 0.1143)
		(layer "In4.Cu")
		(net "P5E_CPU0_P1_TX_DN<14>")
	)
	(segment
		(start 362.090208 -374.836182)
		(end 361.936792 -374.864376)
		(width 0.14224)
		(layer "In4.Cu")
		(net "P5E_CPU0_P1_TX_DN<14>")
	)
	(segment
		(start 358.570022 -384.046984)
		(end 358.570022 -384.397758)
		(width 0.14224)
		(layer "In4.Cu")
		(net "P5E_CPU0_P1_TX_DN<14>")
	)
	(segment
		(start 371.656102 -318.040512)
		(end 373.052086 -320.711068)
		(width 0.14224)
		(layer "In4.Cu")
		(net "P5E_CPU0_P1_TX_DN<14>")
	)
	(segment
		(start 362.30433 -374.330976)
		(end 362.332524 -374.484392)
		(width 0.14224)
		(layer "In4.Cu")
		(net "P5E_CPU0_P1_TX_DN<14>")
	)
	(segment
		(start 377.132342 -352.810826)
		(end 363.13999 -373.118126)
		(width 0.14224)
		(layer "In4.Cu")
		(net "P5E_CPU0_P1_TX_DN<14>")
	)
	(segment
		(start 357.452422 -288.970212)
		(end 357.521256 -289.01009)
		(width 0.1143)
		(layer "In4.Cu")
		(net "P5E_CPU0_P1_TX_DN<14>")
	)
	(segment
		(start 357.671116 -288.66592)
		(end 357.373174 -288.66592)
		(width 0.1143)
		(layer "In4.Cu")
		(net "P5E_CPU0_P1_TX_DN<14>")
	)
	(segment
		(start 358.445562 -293.19093)
		(end 358.445308 -293.19093)
		(width 0.1143)
		(layer "In4.Cu")
		(net "P5E_CPU0_P1_TX_DN<14>")
	)
	(segment
		(start 358.456484 -293.184326)
		(end 358.445562 -293.19093)
		(width 0.1143)
		(layer "In4.Cu")
		(net "P5E_CPU0_P1_TX_DN<14>")
	)
	(segment
		(start 360.40949 -382.175766)
		(end 360.107484 -382.477772)
		(width 0.14224)
		(layer "In4.Cu")
		(net "P5E_CPU0_P1_TX_DN<14>")
	)
	(segment
		(start 358.321356 -298.50461)
		(end 360.451146 -303.646586)
		(width 0.14224)
		(layer "In4.Cu")
		(net "P5E_CPU0_P1_TX_DN<14>")
	)
	(segment
		(start 358.463088 -293.871396)
		(end 358.50195 -293.89832)
		(width 0.1143)
		(layer "In4.Cu")
		(net "P5E_CPU0_P1_TX_DN<14>")
	)
	(segment
		(start 358.424226 -291.583364)
		(end 358.423972 -291.583364)
		(width 0.1143)
		(layer "In4.Cu")
		(net "P5E_CPU0_P1_TX_DN<14>")
	)
	(segment
		(start 362.932726 -373.66067)
		(end 362.741972 -373.695722)
		(width 0.14224)
		(layer "In4.Cu")
		(net "P5E_CPU0_P1_TX_DN<14>")
	)
	(segment
		(start 357.922322 -289.780218)
		(end 357.993188 -289.821366)
		(width 0.1143)
		(layer "In4.Cu")
		(net "P5E_CPU0_P1_TX_DN<14>")
	)
	(segment
		(start 357.373174 -288.66592)
		(end 357.303324 -288.73577)
		(width 0.1143)
		(layer "In4.Cu")
		(net "P5E_CPU0_P1_TX_DN<14>")
	)
	(segment
		(start 358.423972 -292.228524)
		(end 358.47147 -292.257226)
		(width 0.1143)
		(layer "In4.Cu")
		(net "P5E_CPU0_P1_TX_DN<14>")
	)
	(segment
		(start 358.236266 -295.145968)
		(end 358.236266 -295.483026)
		(width 0.1143)
		(layer "In4.Cu")
		(net "P5E_CPU0_P1_TX_DN<14>")
	)
	(segment
		(start 358.416098 -293.84371)
		(end 358.461564 -293.87038)
		(width 0.1143)
		(layer "In4.Cu")
		(net "P5E_CPU0_P1_TX_DN<14>")
	)
	(segment
		(start 359.309924 -383.275332)
		(end 359.115868 -383.275332)
		(width 0.14224)
		(layer "In4.Cu")
		(net "P5E_CPU0_P1_TX_DN<14>")
	)
	(segment
		(start 376.986038 -332.208378)
		(end 377.998736 -337.847686)
		(width 0.14224)
		(layer "In4.Cu")
		(net "P5E_CPU0_P1_TX_DN<14>")
	)
	(segment
		(start 358.393492 -292.210744)
		(end 358.423972 -292.228524)
		(width 0.1143)
		(layer "In4.Cu")
		(net "P5E_CPU0_P1_TX_DN<14>")
	)
	(segment
		(start 358.445308 -293.19093)
		(end 358.425242 -293.202868)
		(width 0.1143)
		(layer "In4.Cu")
		(net "P5E_CPU0_P1_TX_DN<14>")
	)
	(segment
		(start 358.423972 -290.608512)
		(end 358.424226 -290.608766)
		(width 0.1143)
		(layer "In4.Cu")
		(net "P5E_CPU0_P1_TX_DN<14>")
	)
	(segment
		(start 358.281986 -295.528746)
		(end 358.281986 -295.557194)
		(width 0.1143)
		(layer "In4.Cu")
		(net "P5E_CPU0_P1_TX_DN<14>")
	)
	(segment
		(start 361.936792 -374.864376)
		(end 361.667298 -375.255536)
		(width 0.14224)
		(layer "In4.Cu")
		(net "P5E_CPU0_P1_TX_DN<14>")
	)
	(segment
		(start 359.115868 -383.275332)
		(end 358.729788 -383.661412)
		(width 0.14224)
		(layer "In4.Cu")
		(net "P5E_CPU0_P1_TX_DN<14>")
	)
	(segment
		(start 359.61193 -382.973326)
		(end 359.309924 -383.275332)
		(width 0.14224)
		(layer "In4.Cu")
		(net "P5E_CPU0_P1_TX_DN<14>")
	)
	(segment
		(start 358.706166 -292.71595)
		(end 358.70642 -292.71595)
		(width 0.1143)
		(layer "In4.Cu")
		(net "P5E_CPU0_P1_TX_DN<14>")
	)
	(arc
		(start 361.667298 -375.255536)
		(mid 361.362775 -375.881919)
		(end 361.258104 -376.570494)
		(width 0.14224)
		(layer "In4.Cu")
		(net "P5E_CPU0_P1_TX_DN<14>")
	)
	(arc
		(start 358.23652 -290.285932)
		(mid 358.278069 -290.457354)
		(end 358.393492 -290.590732)
		(width 0.1143)
		(layer "In4.Cu")
		(net "P5E_CPU0_P1_TX_DN<14>")
	)
	(arc
		(start 358.461564 -293.87038)
		(mid 358.462326 -293.870887)
		(end 358.463088 -293.871396)
		(width 0.1143)
		(layer "In4.Cu")
		(net "P5E_CPU0_P1_TX_DN<14>")
	)
	(arc
		(start 358.424226 -290.608766)
		(mid 358.70399 -291.096128)
		(end 358.424226 -291.583364)
		(width 0.1143)
		(layer "In4.Cu")
		(net "P5E_CPU0_P1_TX_DN<14>")
	)
	(arc
		(start 358.50195 -293.89832)
		(mid 358.731128 -294.335962)
		(end 358.50195 -294.773604)
		(width 0.1143)
		(layer "In4.Cu")
		(net "P5E_CPU0_P1_TX_DN<14>")
	)
	(arc
		(start 358.424226 -293.203376)
		(mid 358.239248 -293.52123)
		(end 358.416098 -293.84371)
		(width 0.1143)
		(layer "In4.Cu")
		(net "P5E_CPU0_P1_TX_DN<14>")
	)
	(arc
		(start 357.766366 -289.485578)
		(mid 357.809759 -289.65121)
		(end 357.922322 -289.780218)
		(width 0.1143)
		(layer "In4.Cu")
		(net "P5E_CPU0_P1_TX_DN<14>")
	)
	(arc
		(start 358.281986 -298.306744)
		(mid 358.291924 -298.407616)
		(end 358.321356 -298.50461)
		(width 0.14224)
		(layer "In4.Cu")
		(net "P5E_CPU0_P1_TX_DN<14>")
	)
	(arc
		(start 358.729788 -383.661412)
		(mid 358.611532 -383.8383)
		(end 358.570022 -384.046984)
		(width 0.14224)
		(layer "In4.Cu")
		(net "P5E_CPU0_P1_TX_DN<14>")
	)
	(arc
		(start 357.76281 -289.441128)
		(mid 357.765154 -289.463308)
		(end 357.766366 -289.485578)
		(width 0.1143)
		(layer "In4.Cu")
		(net "P5E_CPU0_P1_TX_DN<14>")
	)
	(arc
		(start 358.70642 -292.71595)
		(mid 358.706265 -292.726493)
		(end 358.705912 -292.737032)
		(width 0.1143)
		(layer "In4.Cu")
		(net "P5E_CPU0_P1_TX_DN<14>")
	)
	(arc
		(start 357.993188 -289.821366)
		(mid 358.172001 -290.023716)
		(end 358.23652 -290.285932)
		(width 0.1143)
		(layer "In4.Cu")
		(net "P5E_CPU0_P1_TX_DN<14>")
	)
	(arc
		(start 358.705912 -292.737032)
		(mid 358.636825 -292.987409)
		(end 358.463088 -293.180516)
		(width 0.1143)
		(layer "In4.Cu")
		(net "P5E_CPU0_P1_TX_DN<14>")
	)
	(arc
		(start 358.848406 -384.72872)
		(mid 358.889646 -384.756339)
		(end 358.938322 -384.766058)
		(width 0.14224)
		(layer "In4.Cu")
		(net "P5E_CPU0_P1_TX_DN<14>")
	)
	(arc
		(start 358.570022 -384.397758)
		(mid 358.579724 -384.446442)
		(end 358.60736 -384.487674)
		(width 0.14224)
		(layer "In4.Cu")
		(net "P5E_CPU0_P1_TX_DN<14>")
	)
	(arc
		(start 358.393492 -291.601144)
		(mid 358.236515 -291.905944)
		(end 358.393492 -292.210744)
		(width 0.1143)
		(layer "In4.Cu")
		(net "P5E_CPU0_P1_TX_DN<14>")
	)
	(arc
		(start 357.521256 -289.01009)
		(mid 357.68247 -289.202948)
		(end 357.76281 -289.441128)
		(width 0.1143)
		(layer "In4.Cu")
		(net "P5E_CPU0_P1_TX_DN<14>")
	)
	(arc
		(start 358.47147 -292.257226)
		(mid 358.64395 -292.450939)
		(end 358.706166 -292.702742)
		(width 0.1143)
		(layer "In4.Cu")
		(net "P5E_CPU0_P1_TX_DN<14>")
	)
	(arc
		(start 361.258104 -380.747016)
		(mid 361.187146 -381.103746)
		(end 360.985054 -381.406146)
		(width 0.14224)
		(layer "In4.Cu")
		(net "P5E_CPU0_P1_TX_DN<14>")
	)
	(arc
		(start 358.393238 -294.841168)
		(mid 358.277811 -294.974544)
		(end 358.236266 -295.145968)
		(width 0.1143)
		(layer "In4.Cu")
		(net "P5E_CPU0_P1_TX_DN<14>")
	)
	(arc
		(start 357.303324 -288.73577)
		(mid 357.355373 -288.867289)
		(end 357.452422 -288.970212)
		(width 0.1143)
		(layer "In4.Cu")
		(net "P5E_CPU0_P1_TX_DN<14>")
	)
	(segment
		(start 357.662734 -377.68784)
		(end 357.662734 -378.39142)
		(width 0.12954)
		(layer "F.Cu")
		(net "P5E_CPU0_P1_TX_DN<13>")
	)
	(segment
		(start 357.933244 -377.41733)
		(end 357.662734 -377.68784)
		(width 0.12954)
		(layer "F.Cu")
		(net "P5E_CPU0_P1_TX_DN<13>")
	)
	(segment
		(start 357.662734 -378.39142)
		(end 357.958644 -378.68733)
		(width 0.12954)
		(layer "F.Cu")
		(net "P5E_CPU0_P1_TX_DN<13>")
	)
	(segment
		(start 358.137968 -290.019994)
		(end 357.671116 -290.285932)
		(width 0.12954)
		(layer "F.Cu")
		(net "P5E_CPU0_P1_TX_DN<13>")
	)
	(segment
		(start 357.48595 -293.849552)
		(end 357.486458 -293.85006)
		(width 0.1143)
		(layer "In4.Cu")
		(net "P5E_CPU0_P1_TX_DN<13>")
	)
	(segment
		(start 357.48341 -292.228016)
		(end 357.484172 -292.228524)
		(width 0.1143)
		(layer "In4.Cu")
		(net "P5E_CPU0_P1_TX_DN<13>")
	)
	(segment
		(start 357.642414 -377.1265)
		(end 357.933244 -377.41733)
		(width 0.14224)
		(layer "In4.Cu")
		(net "P5E_CPU0_P1_TX_DN<13>")
	)
	(segment
		(start 357.296212 -295.483026)
		(end 357.341932 -295.528746)
		(width 0.1143)
		(layer "In4.Cu")
		(net "P5E_CPU0_P1_TX_DN<13>")
	)
	(segment
		(start 359.62971 -304.105818)
		(end 362.398056 -308.24932)
		(width 0.14224)
		(layer "In4.Cu")
		(net "P5E_CPU0_P1_TX_DN<13>")
	)
	(segment
		(start 357.473758 -293.84244)
		(end 357.48595 -293.849552)
		(width 0.1143)
		(layer "In4.Cu")
		(net "P5E_CPU0_P1_TX_DN<13>")
	)
	(segment
		(start 357.487982 -291.580824)
		(end 357.484172 -291.583364)
		(width 0.1143)
		(layer "In4.Cu")
		(net "P5E_CPU0_P1_TX_DN<13>")
	)
	(segment
		(start 357.296212 -295.145968)
		(end 357.296212 -295.483026)
		(width 0.1143)
		(layer "In4.Cu")
		(net "P5E_CPU0_P1_TX_DN<13>")
	)
	(segment
		(start 376.100594 -352.664522)
		(end 363.885226 -370.312696)
		(width 0.14224)
		(layer "In4.Cu")
		(net "P5E_CPU0_P1_TX_DN<13>")
	)
	(segment
		(start 357.373174 -290.285932)
		(end 357.303324 -290.355782)
		(width 0.1143)
		(layer "In4.Cu")
		(net "P5E_CPU0_P1_TX_DN<13>")
	)
	(segment
		(start 362.398056 -308.24932)
		(end 370.881402 -318.58458)
		(width 0.14224)
		(layer "In4.Cu")
		(net "P5E_CPU0_P1_TX_DN<13>")
	)
	(segment
		(start 357.486458 -294.822118)
		(end 357.456232 -294.83939)
		(width 0.1143)
		(layer "In4.Cu")
		(net "P5E_CPU0_P1_TX_DN<13>")
	)
	(segment
		(start 363.885226 -370.312696)
		(end 357.679752 -376.51817)
		(width 0.14224)
		(layer "In4.Cu")
		(net "P5E_CPU0_P1_TX_DN<13>")
	)
	(segment
		(start 377.053856 -337.950048)
		(end 377.053856 -348.634304)
		(width 0.14224)
		(layer "In4.Cu")
		(net "P5E_CPU0_P1_TX_DN<13>")
	)
	(segment
		(start 376.095768 -332.52791)
		(end 377.038108 -337.774788)
		(width 0.14224)
		(layer "In4.Cu")
		(net "P5E_CPU0_P1_TX_DN<13>")
	)
	(segment
		(start 357.671116 -290.285932)
		(end 357.373174 -290.285932)
		(width 0.1143)
		(layer "In4.Cu")
		(net "P5E_CPU0_P1_TX_DN<13>")
	)
	(segment
		(start 357.484172 -292.228524)
		(end 357.496872 -292.236144)
		(width 0.1143)
		(layer "In4.Cu")
		(net "P5E_CPU0_P1_TX_DN<13>")
	)
	(segment
		(start 357.341932 -295.528746)
		(end 357.341932 -295.557194)
		(width 0.1143)
		(layer "In4.Cu")
		(net "P5E_CPU0_P1_TX_DN<13>")
	)
	(segment
		(start 357.488744 -293.200582)
		(end 357.483918 -293.20363)
		(width 0.1143)
		(layer "In4.Cu")
		(net "P5E_CPU0_P1_TX_DN<13>")
	)
	(segment
		(start 357.523034 -291.560758)
		(end 357.487982 -291.580824)
		(width 0.1143)
		(layer "In4.Cu")
		(net "P5E_CPU0_P1_TX_DN<13>")
	)
	(segment
		(start 370.881402 -318.58458)
		(end 372.175786 -321.060318)
		(width 0.14224)
		(layer "In4.Cu")
		(net "P5E_CPU0_P1_TX_DN<13>")
	)
	(segment
		(start 357.550974 -291.540692)
		(end 357.523034 -291.560758)
		(width 0.1143)
		(layer "In4.Cu")
		(net "P5E_CPU0_P1_TX_DN<13>")
	)
	(segment
		(start 357.484172 -291.583364)
		(end 357.452422 -291.601652)
		(width 0.1143)
		(layer "In4.Cu")
		(net "P5E_CPU0_P1_TX_DN<13>")
	)
	(segment
		(start 377.032266 -348.823788)
		(end 376.194574 -352.451924)
		(width 0.14224)
		(layer "In4.Cu")
		(net "P5E_CPU0_P1_TX_DN<13>")
	)
	(segment
		(start 357.48214 -292.227254)
		(end 357.48341 -292.228016)
		(width 0.1143)
		(layer "In4.Cu")
		(net "P5E_CPU0_P1_TX_DN<13>")
	)
	(segment
		(start 372.225824 -321.176904)
		(end 376.05335 -332.36408)
		(width 0.14224)
		(layer "In4.Cu")
		(net "P5E_CPU0_P1_TX_DN<13>")
	)
	(segment
		(start 357.483918 -293.20363)
		(end 357.477568 -293.207186)
		(width 0.1143)
		(layer "In4.Cu")
		(net "P5E_CPU0_P1_TX_DN<13>")
	)
	(segment
		(start 357.452422 -290.590224)
		(end 357.523288 -290.631118)
		(width 0.1143)
		(layer "In4.Cu")
		(net "P5E_CPU0_P1_TX_DN<13>")
	)
	(segment
		(start 357.452422 -292.210236)
		(end 357.48214 -292.227254)
		(width 0.1143)
		(layer "In4.Cu")
		(net "P5E_CPU0_P1_TX_DN<13>")
	)
	(segment
		(start 357.456232 -294.83939)
		(end 357.452422 -294.841676)
		(width 0.1143)
		(layer "In4.Cu")
		(net "P5E_CPU0_P1_TX_DN<13>")
	)
	(segment
		(start 357.351584 -298.605956)
		(end 359.62971 -304.105818)
		(width 0.14224)
		(layer "In4.Cu")
		(net "P5E_CPU0_P1_TX_DN<13>")
	)
	(segment
		(start 357.523288 -290.631118)
		(end 357.550974 -290.651184)
		(width 0.1143)
		(layer "In4.Cu")
		(net "P5E_CPU0_P1_TX_DN<13>")
	)
	(segment
		(start 357.341932 -295.557194)
		(end 357.341932 -298.557188)
		(width 0.14224)
		(layer "In4.Cu")
		(net "P5E_CPU0_P1_TX_DN<13>")
	)
	(segment
		(start 357.642414 -376.60834)
		(end 357.642414 -377.1265)
		(width 0.14224)
		(layer "In4.Cu")
		(net "P5E_CPU0_P1_TX_DN<13>")
	)
	(arc
		(start 357.341932 -298.557188)
		(mid 357.344378 -298.582041)
		(end 357.351584 -298.605956)
		(width 0.14224)
		(layer "In4.Cu")
		(net "P5E_CPU0_P1_TX_DN<13>")
	)
	(arc
		(start 357.477568 -293.207186)
		(mid 357.299047 -293.523735)
		(end 357.473758 -293.84244)
		(width 0.1143)
		(layer "In4.Cu")
		(net "P5E_CPU0_P1_TX_DN<13>")
	)
	(arc
		(start 357.303324 -290.355782)
		(mid 357.355373 -290.487301)
		(end 357.452422 -290.590224)
		(width 0.1143)
		(layer "In4.Cu")
		(net "P5E_CPU0_P1_TX_DN<13>")
	)
	(arc
		(start 357.679752 -376.51817)
		(mid 357.652109 -376.55954)
		(end 357.642414 -376.60834)
		(width 0.14224)
		(layer "In4.Cu")
		(net "P5E_CPU0_P1_TX_DN<13>")
	)
	(arc
		(start 357.35006 -294.952928)
		(mid 357.309954 -295.045775)
		(end 357.296212 -295.145968)
		(width 0.1143)
		(layer "In4.Cu")
		(net "P5E_CPU0_P1_TX_DN<13>")
	)
	(arc
		(start 357.452422 -291.601652)
		(mid 357.296494 -291.905944)
		(end 357.452422 -292.210236)
		(width 0.1143)
		(layer "In4.Cu")
		(net "P5E_CPU0_P1_TX_DN<13>")
	)
	(arc
		(start 357.496872 -292.236144)
		(mid 357.767089 -292.720676)
		(end 357.488744 -293.200582)
		(width 0.1143)
		(layer "In4.Cu")
		(net "P5E_CPU0_P1_TX_DN<13>")
	)
	(arc
		(start 376.194574 -352.451924)
		(mid 376.157702 -352.562697)
		(end 376.100594 -352.664522)
		(width 0.14224)
		(layer "In4.Cu")
		(net "P5E_CPU0_P1_TX_DN<13>")
	)
	(arc
		(start 357.486458 -293.85006)
		(mid 357.766386 -294.336152)
		(end 357.486458 -294.822118)
		(width 0.1143)
		(layer "In4.Cu")
		(net "P5E_CPU0_P1_TX_DN<13>")
	)
	(arc
		(start 357.452422 -294.841676)
		(mid 357.39556 -294.892077)
		(end 357.35006 -294.952928)
		(width 0.1143)
		(layer "In4.Cu")
		(net "P5E_CPU0_P1_TX_DN<13>")
	)
	(arc
		(start 372.175786 -321.060318)
		(mid 372.203027 -321.117657)
		(end 372.225824 -321.176904)
		(width 0.14224)
		(layer "In4.Cu")
		(net "P5E_CPU0_P1_TX_DN<13>")
	)
	(arc
		(start 357.550974 -290.651184)
		(mid 357.778974 -291.095938)
		(end 357.550974 -291.540692)
		(width 0.1143)
		(layer "In4.Cu")
		(net "P5E_CPU0_P1_TX_DN<13>")
	)
	(arc
		(start 377.053856 -348.634304)
		(mid 377.048441 -348.729659)
		(end 377.032266 -348.823788)
		(width 0.14224)
		(layer "In4.Cu")
		(net "P5E_CPU0_P1_TX_DN<13>")
	)
	(arc
		(start 376.05335 -332.36408)
		(mid 376.077673 -332.445189)
		(end 376.095768 -332.52791)
		(width 0.14224)
		(layer "In4.Cu")
		(net "P5E_CPU0_P1_TX_DN<13>")
	)
	(arc
		(start 377.038108 -337.774788)
		(mid 377.049869 -337.862069)
		(end 377.053856 -337.950048)
		(width 0.14224)
		(layer "In4.Cu")
		(net "P5E_CPU0_P1_TX_DN<13>")
	)
	(segment
		(start 355.78796 -287.59023)
		(end 355.321108 -287.856168)
		(width 0.12954)
		(layer "F.Cu")
		(net "P5E_CPU0_P1_TX_DN<12>")
	)
	(segment
		(start 354.259134 -377.68784)
		(end 354.529644 -377.41733)
		(width 0.12954)
		(layer "F.Cu")
		(net "P5E_CPU0_P1_TX_DN<12>")
	)
	(segment
		(start 354.555044 -378.68733)
		(end 354.259134 -378.39142)
		(width 0.12954)
		(layer "F.Cu")
		(net "P5E_CPU0_P1_TX_DN<12>")
	)
	(segment
		(start 354.259134 -378.39142)
		(end 354.259134 -377.68784)
		(width 0.12954)
		(layer "F.Cu")
		(net "P5E_CPU0_P1_TX_DN<12>")
	)
	(segment
		(start 356.547674 -292.230556)
		(end 356.583234 -292.251384)
		(width 0.1143)
		(layer "In4.Cu")
		(net "P5E_CPU0_P1_TX_DN<12>")
	)
	(segment
		(start 356.529386 -291.592)
		(end 356.527354 -291.59327)
		(width 0.1143)
		(layer "In4.Cu")
		(net "P5E_CPU0_P1_TX_DN<12>")
	)
	(segment
		(start 356.543356 -293.848028)
		(end 356.544118 -293.848536)
		(width 0.1143)
		(layer "In4.Cu")
		(net "P5E_CPU0_P1_TX_DN<12>")
	)
	(segment
		(start 355.100636 -288.158936)
		(end 355.134164 -288.178494)
		(width 0.1143)
		(layer "In4.Cu")
		(net "P5E_CPU0_P1_TX_DN<12>")
	)
	(segment
		(start 358.817926 -304.582322)
		(end 361.61853 -308.773576)
		(width 0.14224)
		(layer "In4.Cu")
		(net "P5E_CPU0_P1_TX_DN<12>")
	)
	(segment
		(start 356.543356 -292.228016)
		(end 356.544118 -292.228524)
		(width 0.1143)
		(layer "In4.Cu")
		(net "P5E_CPU0_P1_TX_DN<12>")
	)
	(segment
		(start 356.527354 -291.59327)
		(end 356.525322 -291.594286)
		(width 0.1143)
		(layer "In4.Cu")
		(net "P5E_CPU0_P1_TX_DN<12>")
	)
	(segment
		(start 356.544118 -293.203376)
		(end 356.543356 -293.203884)
		(width 0.1143)
		(layer "In4.Cu")
		(net "P5E_CPU0_P1_TX_DN<12>")
	)
	(segment
		(start 356.512368 -293.830248)
		(end 356.543356 -293.848028)
		(width 0.1143)
		(layer "In4.Cu")
		(net "P5E_CPU0_P1_TX_DN<12>")
	)
	(segment
		(start 356.523798 -294.835326)
		(end 356.51948 -294.837866)
		(width 0.1143)
		(layer "In4.Cu")
		(net "P5E_CPU0_P1_TX_DN<12>")
	)
	(segment
		(start 355.574346 -288.971228)
		(end 355.606604 -288.990024)
		(width 0.1143)
		(layer "In4.Cu")
		(net "P5E_CPU0_P1_TX_DN<12>")
	)
	(segment
		(start 356.532688 -293.210234)
		(end 356.529386 -293.212012)
		(width 0.1143)
		(layer "In4.Cu")
		(net "P5E_CPU0_P1_TX_DN<12>")
	)
	(segment
		(start 375.200926 -352.32594)
		(end 363.80166 -368.682778)
		(width 0.14224)
		(layer "In4.Cu")
		(net "P5E_CPU0_P1_TX_DN<12>")
	)
	(segment
		(start 356.537768 -294.827198)
		(end 356.53345 -294.829738)
		(width 0.1143)
		(layer "In4.Cu")
		(net "P5E_CPU0_P1_TX_DN<12>")
	)
	(segment
		(start 356.401878 -295.528746)
		(end 356.401878 -295.557194)
		(width 0.1143)
		(layer "In4.Cu")
		(net "P5E_CPU0_P1_TX_DN<12>")
	)
	(segment
		(start 356.545134 -292.229032)
		(end 356.546658 -292.230048)
		(width 0.1143)
		(layer "In4.Cu")
		(net "P5E_CPU0_P1_TX_DN<12>")
	)
	(segment
		(start 356.546658 -294.821864)
		(end 356.545134 -294.82288)
		(width 0.1143)
		(layer "In4.Cu")
		(net "P5E_CPU0_P1_TX_DN<12>")
	)
	(segment
		(start 356.583234 -291.560504)
		(end 356.546658 -291.58184)
		(width 0.1143)
		(layer "In4.Cu")
		(net "P5E_CPU0_P1_TX_DN<12>")
	)
	(segment
		(start 356.546658 -291.58184)
		(end 356.545134 -291.582856)
		(width 0.1143)
		(layer "In4.Cu")
		(net "P5E_CPU0_P1_TX_DN<12>")
	)
	(segment
		(start 356.070408 -289.796474)
		(end 356.071678 -289.796982)
		(width 0.1143)
		(layer "In4.Cu")
		(net "P5E_CPU0_P1_TX_DN<12>")
	)
	(segment
		(start 354.238814 -376.592592)
		(end 354.238814 -377.1265)
		(width 0.14224)
		(layer "In4.Cu")
		(net "P5E_CPU0_P1_TX_DN<12>")
	)
	(segment
		(start 356.546658 -293.201852)
		(end 356.545134 -293.202868)
		(width 0.1143)
		(layer "In4.Cu")
		(net "P5E_CPU0_P1_TX_DN<12>")
	)
	(segment
		(start 370.030248 -319.021968)
		(end 371.409976 -321.701414)
		(width 0.14224)
		(layer "In4.Cu")
		(net "P5E_CPU0_P1_TX_DN<12>")
	)
	(segment
		(start 356.544118 -293.848536)
		(end 356.545134 -293.849044)
		(width 0.1143)
		(layer "In4.Cu")
		(net "P5E_CPU0_P1_TX_DN<12>")
	)
	(segment
		(start 356.41153 -298.773088)
		(end 358.817926 -304.582322)
		(width 0.14224)
		(layer "In4.Cu")
		(net "P5E_CPU0_P1_TX_DN<12>")
	)
	(segment
		(start 356.542086 -291.584634)
		(end 356.540562 -291.585396)
		(width 0.1143)
		(layer "In4.Cu")
		(net "P5E_CPU0_P1_TX_DN<12>")
	)
	(segment
		(start 356.523798 -293.215314)
		(end 356.51948 -293.217854)
		(width 0.1143)
		(layer "In4.Cu")
		(net "P5E_CPU0_P1_TX_DN<12>")
	)
	(segment
		(start 356.525322 -291.594286)
		(end 356.523798 -291.595302)
		(width 0.1143)
		(layer "In4.Cu")
		(net "P5E_CPU0_P1_TX_DN<12>")
	)
	(segment
		(start 356.542086 -294.824658)
		(end 356.540562 -294.82542)
		(width 0.1143)
		(layer "In4.Cu")
		(net "P5E_CPU0_P1_TX_DN<12>")
	)
	(segment
		(start 356.540562 -294.82542)
		(end 356.539292 -294.826182)
		(width 0.1143)
		(layer "In4.Cu")
		(net "P5E_CPU0_P1_TX_DN<12>")
	)
	(segment
		(start 356.529386 -294.832024)
		(end 356.527354 -294.833294)
		(width 0.1143)
		(layer "In4.Cu")
		(net "P5E_CPU0_P1_TX_DN<12>")
	)
	(segment
		(start 356.543356 -290.608004)
		(end 356.544118 -290.608512)
		(width 0.1143)
		(layer "In4.Cu")
		(net "P5E_CPU0_P1_TX_DN<12>")
	)
	(segment
		(start 356.523798 -291.595302)
		(end 356.51948 -291.597842)
		(width 0.1143)
		(layer "In4.Cu")
		(net "P5E_CPU0_P1_TX_DN<12>")
	)
	(segment
		(start 356.525322 -293.214298)
		(end 356.523798 -293.215314)
		(width 0.1143)
		(layer "In4.Cu")
		(net "P5E_CPU0_P1_TX_DN<12>")
	)
	(segment
		(start 355.134164 -288.178494)
		(end 355.170486 -288.199576)
		(width 0.1143)
		(layer "In4.Cu")
		(net "P5E_CPU0_P1_TX_DN<12>")
	)
	(segment
		(start 356.546658 -293.85006)
		(end 356.547674 -293.850568)
		(width 0.1143)
		(layer "In4.Cu")
		(net "P5E_CPU0_P1_TX_DN<12>")
	)
	(segment
		(start 356.547674 -290.610544)
		(end 356.583234 -290.631372)
		(width 0.1143)
		(layer "In4.Cu")
		(net "P5E_CPU0_P1_TX_DN<12>")
	)
	(segment
		(start 355.606604 -288.990024)
		(end 355.608636 -288.991294)
		(width 0.1143)
		(layer "In4.Cu")
		(net "P5E_CPU0_P1_TX_DN<12>")
	)
	(segment
		(start 356.071678 -289.796982)
		(end 356.075234 -289.799268)
		(width 0.1143)
		(layer "In4.Cu")
		(net "P5E_CPU0_P1_TX_DN<12>")
	)
	(segment
		(start 356.539292 -293.20617)
		(end 356.537768 -293.207186)
		(width 0.1143)
		(layer "In4.Cu")
		(net "P5E_CPU0_P1_TX_DN<12>")
	)
	(segment
		(start 356.542086 -293.204646)
		(end 356.540562 -293.205408)
		(width 0.1143)
		(layer "In4.Cu")
		(net "P5E_CPU0_P1_TX_DN<12>")
	)
	(segment
		(start 356.543356 -294.823896)
		(end 356.542086 -294.824658)
		(width 0.1143)
		(layer "In4.Cu")
		(net "P5E_CPU0_P1_TX_DN<12>")
	)
	(segment
		(start 355.321108 -287.856168)
		(end 355.023166 -287.856168)
		(width 0.1143)
		(layer "In4.Cu")
		(net "P5E_CPU0_P1_TX_DN<12>")
	)
	(segment
		(start 356.543356 -293.203884)
		(end 356.542086 -293.204646)
		(width 0.1143)
		(layer "In4.Cu")
		(net "P5E_CPU0_P1_TX_DN<12>")
	)
	(segment
		(start 355.023166 -287.856168)
		(end 354.953316 -287.926018)
		(width 0.1143)
		(layer "In4.Cu")
		(net "P5E_CPU0_P1_TX_DN<12>")
	)
	(segment
		(start 356.543356 -291.583872)
		(end 356.542086 -291.584634)
		(width 0.1143)
		(layer "In4.Cu")
		(net "P5E_CPU0_P1_TX_DN<12>")
	)
	(segment
		(start 356.532688 -294.830246)
		(end 356.529386 -294.832024)
		(width 0.1143)
		(layer "In4.Cu")
		(net "P5E_CPU0_P1_TX_DN<12>")
	)
	(segment
		(start 376.088402 -337.853782)
		(end 376.088402 -348.50705)
		(width 0.14224)
		(layer "In4.Cu")
		(net "P5E_CPU0_P1_TX_DN<12>")
	)
	(segment
		(start 356.401878 -295.557194)
		(end 356.401878 -298.72432)
		(width 0.14224)
		(layer "In4.Cu")
		(net "P5E_CPU0_P1_TX_DN<12>")
	)
	(segment
		(start 356.545134 -290.60902)
		(end 356.546658 -290.610036)
		(width 0.1143)
		(layer "In4.Cu")
		(net "P5E_CPU0_P1_TX_DN<12>")
	)
	(segment
		(start 356.53345 -293.209726)
		(end 356.532688 -293.210234)
		(width 0.1143)
		(layer "In4.Cu")
		(net "P5E_CPU0_P1_TX_DN<12>")
	)
	(segment
		(start 356.537768 -293.207186)
		(end 356.53345 -293.209726)
		(width 0.1143)
		(layer "In4.Cu")
		(net "P5E_CPU0_P1_TX_DN<12>")
	)
	(segment
		(start 356.547674 -293.850568)
		(end 356.583234 -293.871396)
		(width 0.1143)
		(layer "In4.Cu")
		(net "P5E_CPU0_P1_TX_DN<12>")
	)
	(segment
		(start 356.545134 -291.582856)
		(end 356.544118 -291.583364)
		(width 0.1143)
		(layer "In4.Cu")
		(net "P5E_CPU0_P1_TX_DN<12>")
	)
	(segment
		(start 356.529386 -293.212012)
		(end 356.527354 -293.213282)
		(width 0.1143)
		(layer "In4.Cu")
		(net "P5E_CPU0_P1_TX_DN<12>")
	)
	(segment
		(start 356.539292 -294.826182)
		(end 356.537768 -294.827198)
		(width 0.1143)
		(layer "In4.Cu")
		(net "P5E_CPU0_P1_TX_DN<12>")
	)
	(segment
		(start 356.546658 -290.610036)
		(end 356.547674 -290.610544)
		(width 0.1143)
		(layer "In4.Cu")
		(net "P5E_CPU0_P1_TX_DN<12>")
	)
	(segment
		(start 356.51948 -294.837866)
		(end 356.512368 -294.841676)
		(width 0.1143)
		(layer "In4.Cu")
		(net "P5E_CPU0_P1_TX_DN<12>")
	)
	(segment
		(start 354.238814 -377.1265)
		(end 354.529644 -377.41733)
		(width 0.14224)
		(layer "In4.Cu")
		(net "P5E_CPU0_P1_TX_DN<12>")
	)
	(segment
		(start 356.53345 -294.829738)
		(end 356.532688 -294.830246)
		(width 0.1143)
		(layer "In4.Cu")
		(net "P5E_CPU0_P1_TX_DN<12>")
	)
	(segment
		(start 356.545134 -294.82288)
		(end 356.544118 -294.823388)
		(width 0.1143)
		(layer "In4.Cu")
		(net "P5E_CPU0_P1_TX_DN<12>")
	)
	(segment
		(start 376.067574 -348.694502)
		(end 375.295414 -352.111818)
		(width 0.14224)
		(layer "In4.Cu")
		(net "P5E_CPU0_P1_TX_DN<12>")
	)
	(segment
		(start 356.539292 -291.586158)
		(end 356.537768 -291.587174)
		(width 0.1143)
		(layer "In4.Cu")
		(net "P5E_CPU0_P1_TX_DN<12>")
	)
	(segment
		(start 356.075234 -289.799268)
		(end 356.111556 -289.82035)
		(width 0.1143)
		(layer "In4.Cu")
		(net "P5E_CPU0_P1_TX_DN<12>")
	)
	(segment
		(start 356.544118 -292.228524)
		(end 356.545134 -292.229032)
		(width 0.1143)
		(layer "In4.Cu")
		(net "P5E_CPU0_P1_TX_DN<12>")
	)
	(segment
		(start 371.459252 -321.817746)
		(end 375.188734 -332.826868)
		(width 0.14224)
		(layer "In4.Cu")
		(net "P5E_CPU0_P1_TX_DN<12>")
	)
	(segment
		(start 356.537768 -291.587174)
		(end 356.53345 -291.589714)
		(width 0.1143)
		(layer "In4.Cu")
		(net "P5E_CPU0_P1_TX_DN<12>")
	)
	(segment
		(start 356.527354 -294.833294)
		(end 356.525322 -294.83431)
		(width 0.1143)
		(layer "In4.Cu")
		(net "P5E_CPU0_P1_TX_DN<12>")
	)
	(segment
		(start 356.512368 -290.590224)
		(end 356.543356 -290.608004)
		(width 0.1143)
		(layer "In4.Cu")
		(net "P5E_CPU0_P1_TX_DN<12>")
	)
	(segment
		(start 356.527354 -293.213282)
		(end 356.525322 -293.214298)
		(width 0.1143)
		(layer "In4.Cu")
		(net "P5E_CPU0_P1_TX_DN<12>")
	)
	(segment
		(start 356.51948 -291.597842)
		(end 356.512368 -291.601652)
		(width 0.1143)
		(layer "In4.Cu")
		(net "P5E_CPU0_P1_TX_DN<12>")
	)
	(segment
		(start 356.525322 -294.83431)
		(end 356.523798 -294.835326)
		(width 0.1143)
		(layer "In4.Cu")
		(net "P5E_CPU0_P1_TX_DN<12>")
	)
	(segment
		(start 356.545134 -293.202868)
		(end 356.544118 -293.203376)
		(width 0.1143)
		(layer "In4.Cu")
		(net "P5E_CPU0_P1_TX_DN<12>")
	)
	(segment
		(start 356.512368 -292.210236)
		(end 356.543356 -292.228016)
		(width 0.1143)
		(layer "In4.Cu")
		(net "P5E_CPU0_P1_TX_DN<12>")
	)
	(segment
		(start 356.544118 -290.608512)
		(end 356.545134 -290.60902)
		(width 0.1143)
		(layer "In4.Cu")
		(net "P5E_CPU0_P1_TX_DN<12>")
	)
	(segment
		(start 361.61853 -308.773576)
		(end 370.030248 -319.021968)
		(width 0.14224)
		(layer "In4.Cu")
		(net "P5E_CPU0_P1_TX_DN<12>")
	)
	(segment
		(start 356.544118 -294.823388)
		(end 356.543356 -294.823896)
		(width 0.1143)
		(layer "In4.Cu")
		(net "P5E_CPU0_P1_TX_DN<12>")
	)
	(segment
		(start 356.356158 -295.483026)
		(end 356.401878 -295.528746)
		(width 0.1143)
		(layer "In4.Cu")
		(net "P5E_CPU0_P1_TX_DN<12>")
	)
	(segment
		(start 375.230644 -332.989682)
		(end 376.072654 -337.678522)
		(width 0.14224)
		(layer "In4.Cu")
		(net "P5E_CPU0_P1_TX_DN<12>")
	)
	(segment
		(start 356.545134 -293.849044)
		(end 356.546658 -293.85006)
		(width 0.1143)
		(layer "In4.Cu")
		(net "P5E_CPU0_P1_TX_DN<12>")
	)
	(segment
		(start 356.583234 -294.800528)
		(end 356.546658 -294.821864)
		(width 0.1143)
		(layer "In4.Cu")
		(net "P5E_CPU0_P1_TX_DN<12>")
	)
	(segment
		(start 356.356158 -295.145968)
		(end 356.356158 -295.483026)
		(width 0.1143)
		(layer "In4.Cu")
		(net "P5E_CPU0_P1_TX_DN<12>")
	)
	(segment
		(start 356.540562 -291.585396)
		(end 356.539292 -291.586158)
		(width 0.1143)
		(layer "In4.Cu")
		(net "P5E_CPU0_P1_TX_DN<12>")
	)
	(segment
		(start 356.546658 -292.230048)
		(end 356.547674 -292.230556)
		(width 0.1143)
		(layer "In4.Cu")
		(net "P5E_CPU0_P1_TX_DN<12>")
	)
	(segment
		(start 363.80166 -368.682778)
		(end 354.28555 -376.494548)
		(width 0.14224)
		(layer "In4.Cu")
		(net "P5E_CPU0_P1_TX_DN<12>")
	)
	(segment
		(start 356.51948 -293.217854)
		(end 356.512368 -293.221664)
		(width 0.1143)
		(layer "In4.Cu")
		(net "P5E_CPU0_P1_TX_DN<12>")
	)
	(segment
		(start 356.53345 -291.589714)
		(end 356.532688 -291.590222)
		(width 0.1143)
		(layer "In4.Cu")
		(net "P5E_CPU0_P1_TX_DN<12>")
	)
	(segment
		(start 356.583234 -293.180516)
		(end 356.546658 -293.201852)
		(width 0.1143)
		(layer "In4.Cu")
		(net "P5E_CPU0_P1_TX_DN<12>")
	)
	(segment
		(start 356.540562 -293.205408)
		(end 356.539292 -293.20617)
		(width 0.1143)
		(layer "In4.Cu")
		(net "P5E_CPU0_P1_TX_DN<12>")
	)
	(segment
		(start 356.544118 -291.583364)
		(end 356.543356 -291.583872)
		(width 0.1143)
		(layer "In4.Cu")
		(net "P5E_CPU0_P1_TX_DN<12>")
	)
	(segment
		(start 356.532688 -291.590222)
		(end 356.529386 -291.592)
		(width 0.1143)
		(layer "In4.Cu")
		(net "P5E_CPU0_P1_TX_DN<12>")
	)
	(arc
		(start 356.11308 -289.821366)
		(mid 356.291893 -290.023716)
		(end 356.356412 -290.285932)
		(width 0.1143)
		(layer "In4.Cu")
		(net "P5E_CPU0_P1_TX_DN<12>")
	)
	(arc
		(start 371.409976 -321.701414)
		(mid 371.436784 -321.758661)
		(end 371.459252 -321.817746)
		(width 0.14224)
		(layer "In4.Cu")
		(net "P5E_CPU0_P1_TX_DN<12>")
	)
	(arc
		(start 355.416358 -288.66592)
		(mid 355.458237 -288.837789)
		(end 355.574346 -288.971228)
		(width 0.1143)
		(layer "In4.Cu")
		(net "P5E_CPU0_P1_TX_DN<12>")
	)
	(arc
		(start 356.512368 -293.221664)
		(mid 356.35644 -293.525956)
		(end 356.512368 -293.830248)
		(width 0.1143)
		(layer "In4.Cu")
		(net "P5E_CPU0_P1_TX_DN<12>")
	)
	(arc
		(start 356.356412 -290.285932)
		(mid 356.397667 -290.456903)
		(end 356.512368 -290.590224)
		(width 0.1143)
		(layer "In4.Cu")
		(net "P5E_CPU0_P1_TX_DN<12>")
	)
	(arc
		(start 356.583234 -292.251384)
		(mid 356.826561 -292.71595)
		(end 356.583234 -293.180516)
		(width 0.1143)
		(layer "In4.Cu")
		(net "P5E_CPU0_P1_TX_DN<12>")
	)
	(arc
		(start 376.072654 -337.678522)
		(mid 376.084415 -337.765803)
		(end 376.088402 -337.853782)
		(width 0.14224)
		(layer "In4.Cu")
		(net "P5E_CPU0_P1_TX_DN<12>")
	)
	(arc
		(start 356.583234 -293.871396)
		(mid 356.826561 -294.335962)
		(end 356.583234 -294.800528)
		(width 0.1143)
		(layer "In4.Cu")
		(net "P5E_CPU0_P1_TX_DN<12>")
	)
	(arc
		(start 356.111556 -289.82035)
		(mid 356.112318 -289.820857)
		(end 356.11308 -289.821366)
		(width 0.1143)
		(layer "In4.Cu")
		(net "P5E_CPU0_P1_TX_DN<12>")
	)
	(arc
		(start 355.887274 -289.47745)
		(mid 355.936322 -289.66136)
		(end 356.070408 -289.796474)
		(width 0.1143)
		(layer "In4.Cu")
		(net "P5E_CPU0_P1_TX_DN<12>")
	)
	(arc
		(start 356.422452 -294.933624)
		(mid 356.373132 -295.034753)
		(end 356.356158 -295.145968)
		(width 0.1143)
		(layer "In4.Cu")
		(net "P5E_CPU0_P1_TX_DN<12>")
	)
	(arc
		(start 354.953316 -287.926018)
		(mid 355.004806 -288.056491)
		(end 355.100636 -288.158936)
		(width 0.1143)
		(layer "In4.Cu")
		(net "P5E_CPU0_P1_TX_DN<12>")
	)
	(arc
		(start 355.608636 -288.991294)
		(mid 355.81269 -289.19726)
		(end 355.887274 -289.47745)
		(width 0.1143)
		(layer "In4.Cu")
		(net "P5E_CPU0_P1_TX_DN<12>")
	)
	(arc
		(start 375.188734 -332.826868)
		(mid 375.212724 -332.907494)
		(end 375.230644 -332.989682)
		(width 0.14224)
		(layer "In4.Cu")
		(net "P5E_CPU0_P1_TX_DN<12>")
	)
	(arc
		(start 376.088402 -348.50705)
		(mid 376.083193 -348.601354)
		(end 376.067574 -348.694502)
		(width 0.14224)
		(layer "In4.Cu")
		(net "P5E_CPU0_P1_TX_DN<12>")
	)
	(arc
		(start 356.401878 -298.72432)
		(mid 356.404324 -298.749173)
		(end 356.41153 -298.773088)
		(width 0.14224)
		(layer "In4.Cu")
		(net "P5E_CPU0_P1_TX_DN<12>")
	)
	(arc
		(start 356.512368 -291.601652)
		(mid 356.35644 -291.905944)
		(end 356.512368 -292.210236)
		(width 0.1143)
		(layer "In4.Cu")
		(net "P5E_CPU0_P1_TX_DN<12>")
	)
	(arc
		(start 375.295414 -352.111818)
		(mid 375.258561 -352.223466)
		(end 375.200926 -352.32594)
		(width 0.14224)
		(layer "In4.Cu")
		(net "P5E_CPU0_P1_TX_DN<12>")
	)
	(arc
		(start 356.583234 -290.631372)
		(mid 356.826561 -291.095938)
		(end 356.583234 -291.560504)
		(width 0.1143)
		(layer "In4.Cu")
		(net "P5E_CPU0_P1_TX_DN<12>")
	)
	(arc
		(start 355.170486 -288.199576)
		(mid 355.351138 -288.402321)
		(end 355.416358 -288.66592)
		(width 0.1143)
		(layer "In4.Cu")
		(net "P5E_CPU0_P1_TX_DN<12>")
	)
	(arc
		(start 356.512368 -294.841676)
		(mid 356.463436 -294.883764)
		(end 356.422452 -294.933624)
		(width 0.1143)
		(layer "In4.Cu")
		(net "P5E_CPU0_P1_TX_DN<12>")
	)
	(arc
		(start 354.28555 -376.494548)
		(mid 354.251215 -376.53833)
		(end 354.238814 -376.592592)
		(width 0.14224)
		(layer "In4.Cu")
		(net "P5E_CPU0_P1_TX_DN<12>")
	)
	(segment
		(start 355.78796 -290.83)
		(end 355.321108 -291.095938)
		(width 0.12954)
		(layer "F.Cu")
		(net "P5E_CPU0_P1_TX_DN<11>")
	)
	(segment
		(start 352.557334 -380.15164)
		(end 352.827844 -379.88113)
		(width 0.12954)
		(layer "F.Cu")
		(net "P5E_CPU0_P1_TX_DN<11>")
	)
	(segment
		(start 352.557334 -380.85522)
		(end 352.557334 -380.15164)
		(width 0.12954)
		(layer "F.Cu")
		(net "P5E_CPU0_P1_TX_DN<11>")
	)
	(segment
		(start 352.853244 -381.15113)
		(end 352.557334 -380.85522)
		(width 0.12954)
		(layer "F.Cu")
		(net "P5E_CPU0_P1_TX_DN<11>")
	)
	(segment
		(start 374.397524 -351.719388)
		(end 374.39727 -351.72015)
		(width 0.14224)
		(layer "In4.Cu")
		(net "P5E_CPU0_P1_TX_DN<11>")
	)
	(segment
		(start 355.023166 -291.095938)
		(end 354.953316 -291.165788)
		(width 0.1143)
		(layer "In4.Cu")
		(net "P5E_CPU0_P1_TX_DN<11>")
	)
	(segment
		(start 355.403658 -295.153588)
		(end 355.403658 -295.206928)
		(width 0.1143)
		(layer "In4.Cu")
		(net "P5E_CPU0_P1_TX_DN<11>")
	)
	(segment
		(start 352.537014 -376.77471)
		(end 352.537014 -379.5903)
		(width 0.14224)
		(layer "In4.Cu")
		(net "P5E_CPU0_P1_TX_DN<11>")
	)
	(segment
		(start 355.321108 -291.095938)
		(end 355.023166 -291.095938)
		(width 0.1143)
		(layer "In4.Cu")
		(net "P5E_CPU0_P1_TX_DN<11>")
	)
	(segment
		(start 355.196648 -295.594786)
		(end 355.168962 -295.613328)
		(width 0.1143)
		(layer "In4.Cu")
		(net "P5E_CPU0_P1_TX_DN<11>")
	)
	(segment
		(start 374.39727 -351.72015)
		(end 374.375934 -351.81286)
		(width 0.14224)
		(layer "In4.Cu")
		(net "P5E_CPU0_P1_TX_DN<11>")
	)
	(segment
		(start 355.64318 -293.871396)
		(end 355.64953 -293.875968)
		(width 0.1143)
		(layer "In4.Cu")
		(net "P5E_CPU0_P1_TX_DN<11>")
	)
	(segment
		(start 363.118908 -368.030252)
		(end 352.583496 -376.676412)
		(width 0.14224)
		(layer "In4.Cu")
		(net "P5E_CPU0_P1_TX_DN<11>")
	)
	(segment
		(start 369.176808 -319.45326)
		(end 370.479828 -321.945)
		(width 0.14224)
		(layer "In4.Cu")
		(net "P5E_CPU0_P1_TX_DN<11>")
	)
	(segment
		(start 375.103644 -348.633796)
		(end 374.403112 -351.695004)
		(width 0.14224)
		(layer "In4.Cu")
		(net "P5E_CPU0_P1_TX_DN<11>")
	)
	(segment
		(start 355.64318 -293.180516)
		(end 355.604064 -293.203376)
		(width 0.1143)
		(layer "In4.Cu")
		(net "P5E_CPU0_P1_TX_DN<11>")
	)
	(segment
		(start 355.055424 -296.209974)
		(end 355.097334 -296.251884)
		(width 0.1143)
		(layer "In4.Cu")
		(net "P5E_CPU0_P1_TX_DN<11>")
	)
	(segment
		(start 357.99776 -305.039014)
		(end 360.848148 -309.304436)
		(width 0.14224)
		(layer "In4.Cu")
		(net "P5E_CPU0_P1_TX_DN<11>")
	)
	(segment
		(start 355.58222 -293.83609)
		(end 355.582728 -293.83609)
		(width 0.1143)
		(layer "In4.Cu")
		(net "P5E_CPU0_P1_TX_DN<11>")
	)
	(segment
		(start 355.643942 -294.79875)
		(end 355.559614 -294.849296)
		(width 0.1143)
		(layer "In4.Cu")
		(net "P5E_CPU0_P1_TX_DN<11>")
	)
	(segment
		(start 355.64953 -293.875968)
		(end 355.652578 -293.878254)
		(width 0.1143)
		(layer "In4.Cu")
		(net "P5E_CPU0_P1_TX_DN<11>")
	)
	(segment
		(start 355.168962 -295.613328)
		(end 355.168708 -295.613582)
		(width 0.1143)
		(layer "In4.Cu")
		(net "P5E_CPU0_P1_TX_DN<11>")
	)
	(segment
		(start 355.655372 -293.880286)
		(end 355.657404 -293.88181)
		(width 0.1143)
		(layer "In4.Cu")
		(net "P5E_CPU0_P1_TX_DN<11>")
	)
	(segment
		(start 355.190552 -296.538142)
		(end 355.236272 -296.583862)
		(width 0.1143)
		(layer "In4.Cu")
		(net "P5E_CPU0_P1_TX_DN<11>")
	)
	(segment
		(start 352.537014 -379.5903)
		(end 352.827844 -379.88113)
		(width 0.14224)
		(layer "In4.Cu")
		(net "P5E_CPU0_P1_TX_DN<11>")
	)
	(segment
		(start 355.416358 -291.903912)
		(end 355.416358 -291.90696)
		(width 0.1143)
		(layer "In4.Cu")
		(net "P5E_CPU0_P1_TX_DN<11>")
	)
	(segment
		(start 355.604064 -293.203376)
		(end 355.582474 -293.215822)
		(width 0.1143)
		(layer "In4.Cu")
		(net "P5E_CPU0_P1_TX_DN<11>")
	)
	(segment
		(start 355.652578 -293.878254)
		(end 355.654102 -293.87927)
		(width 0.1143)
		(layer "In4.Cu")
		(net "P5E_CPU0_P1_TX_DN<11>")
	)
	(segment
		(start 355.102414 -291.40023)
		(end 355.133402 -291.41801)
		(width 0.1143)
		(layer "In4.Cu")
		(net "P5E_CPU0_P1_TX_DN<11>")
	)
	(segment
		(start 355.236272 -296.583862)
		(end 355.236272 -296.61231)
		(width 0.1143)
		(layer "In4.Cu")
		(net "P5E_CPU0_P1_TX_DN<11>")
	)
	(segment
		(start 355.582728 -293.83609)
		(end 355.642418 -293.870888)
		(width 0.1143)
		(layer "In4.Cu")
		(net "P5E_CPU0_P1_TX_DN<11>")
	)
	(segment
		(start 355.654102 -293.87927)
		(end 355.655372 -293.880286)
		(width 0.1143)
		(layer "In4.Cu")
		(net "P5E_CPU0_P1_TX_DN<11>")
	)
	(segment
		(start 355.117908 -295.646856)
		(end 355.113082 -295.645586)
		(width 0.1143)
		(layer "In4.Cu")
		(net "P5E_CPU0_P1_TX_DN<11>")
	)
	(segment
		(start 355.572314 -292.210236)
		(end 355.604064 -292.228524)
		(width 0.1143)
		(layer "In4.Cu")
		(net "P5E_CPU0_P1_TX_DN<11>")
	)
	(segment
		(start 355.134164 -291.418518)
		(end 355.136958 -291.420296)
		(width 0.1143)
		(layer "In4.Cu")
		(net "P5E_CPU0_P1_TX_DN<11>")
	)
	(segment
		(start 374.403112 -351.695004)
		(end 374.402604 -351.697036)
		(width 0.14224)
		(layer "In4.Cu")
		(net "P5E_CPU0_P1_TX_DN<11>")
	)
	(segment
		(start 374.375934 -351.81286)
		(end 374.367552 -351.81286)
		(width 0.14224)
		(layer "In4.Cu")
		(net "P5E_CPU0_P1_TX_DN<11>")
	)
	(segment
		(start 355.119178 -295.646094)
		(end 355.117908 -295.646856)
		(width 0.1143)
		(layer "In4.Cu")
		(net "P5E_CPU0_P1_TX_DN<11>")
	)
	(segment
		(start 355.162612 -295.617138)
		(end 355.119178 -295.646094)
		(width 0.1143)
		(layer "In4.Cu")
		(net "P5E_CPU0_P1_TX_DN<11>")
	)
	(segment
		(start 374.27281 -352.026728)
		(end 363.118908 -368.030252)
		(width 0.14224)
		(layer "In4.Cu")
		(net "P5E_CPU0_P1_TX_DN<11>")
	)
	(segment
		(start 360.848148 -309.304436)
		(end 369.176808 -319.45326)
		(width 0.14224)
		(layer "In4.Cu")
		(net "P5E_CPU0_P1_TX_DN<11>")
	)
	(segment
		(start 355.416358 -291.90696)
		(end 355.416612 -291.908484)
		(width 0.1143)
		(layer "In4.Cu")
		(net "P5E_CPU0_P1_TX_DN<11>")
	)
	(segment
		(start 375.1326 -337.809078)
		(end 375.1326 -348.377764)
		(width 0.14224)
		(layer "In4.Cu")
		(net "P5E_CPU0_P1_TX_DN<11>")
	)
	(segment
		(start 355.190552 -296.476674)
		(end 355.190552 -296.538142)
		(width 0.1143)
		(layer "In4.Cu")
		(net "P5E_CPU0_P1_TX_DN<11>")
	)
	(segment
		(start 355.604064 -292.228524)
		(end 355.64318 -292.251384)
		(width 0.1143)
		(layer "In4.Cu")
		(net "P5E_CPU0_P1_TX_DN<11>")
	)
	(segment
		(start 355.168708 -295.613582)
		(end 355.162612 -295.617138)
		(width 0.1143)
		(layer "In4.Cu")
		(net "P5E_CPU0_P1_TX_DN<11>")
	)
	(segment
		(start 374.402604 -351.697036)
		(end 374.397524 -351.719388)
		(width 0.14224)
		(layer "In4.Cu")
		(net "P5E_CPU0_P1_TX_DN<11>")
	)
	(segment
		(start 355.236272 -296.61231)
		(end 355.236272 -298.346368)
		(width 0.14224)
		(layer "In4.Cu")
		(net "P5E_CPU0_P1_TX_DN<11>")
	)
	(segment
		(start 355.173026 -291.441124)
		(end 355.182678 -291.447982)
		(width 0.1143)
		(layer "In4.Cu")
		(net "P5E_CPU0_P1_TX_DN<11>")
	)
	(segment
		(start 374.320308 -333.198724)
		(end 375.117106 -337.63331)
		(width 0.14224)
		(layer "In4.Cu")
		(net "P5E_CPU0_P1_TX_DN<11>")
	)
	(segment
		(start 370.479828 -321.945)
		(end 374.288558 -333.076296)
		(width 0.14224)
		(layer "In4.Cu")
		(net "P5E_CPU0_P1_TX_DN<11>")
	)
	(segment
		(start 355.245924 -298.395136)
		(end 357.99776 -305.039014)
		(width 0.14224)
		(layer "In4.Cu")
		(net "P5E_CPU0_P1_TX_DN<11>")
	)
	(segment
		(start 355.136958 -291.420296)
		(end 355.173026 -291.441124)
		(width 0.1143)
		(layer "In4.Cu")
		(net "P5E_CPU0_P1_TX_DN<11>")
	)
	(segment
		(start 355.133402 -291.41801)
		(end 355.134164 -291.418518)
		(width 0.1143)
		(layer "In4.Cu")
		(net "P5E_CPU0_P1_TX_DN<11>")
	)
	(segment
		(start 355.657404 -293.88181)
		(end 355.661214 -293.884858)
		(width 0.1143)
		(layer "In4.Cu")
		(net "P5E_CPU0_P1_TX_DN<11>")
	)
	(arc
		(start 355.642418 -293.870888)
		(mid 355.642799 -293.871142)
		(end 355.64318 -293.871396)
		(width 0.1143)
		(layer "In4.Cu")
		(net "P5E_CPU0_P1_TX_DN<11>")
	)
	(arc
		(start 355.113082 -295.645586)
		(mid 355.106259 -295.64976)
		(end 355.09962 -295.654222)
		(width 0.1143)
		(layer "In4.Cu")
		(net "P5E_CPU0_P1_TX_DN<11>")
	)
	(arc
		(start 374.288558 -333.076296)
		(mid 374.306756 -333.136907)
		(end 374.320308 -333.198724)
		(width 0.14224)
		(layer "In4.Cu")
		(net "P5E_CPU0_P1_TX_DN<11>")
	)
	(arc
		(start 355.64318 -292.251384)
		(mid 355.886507 -292.71595)
		(end 355.64318 -293.180516)
		(width 0.1143)
		(layer "In4.Cu")
		(net "P5E_CPU0_P1_TX_DN<11>")
	)
	(arc
		(start 355.09962 -295.654222)
		(mid 355.068166 -295.685888)
		(end 355.036882 -295.717722)
		(width 0.1143)
		(layer "In4.Cu")
		(net "P5E_CPU0_P1_TX_DN<11>")
	)
	(arc
		(start 355.559614 -294.849296)
		(mid 355.444938 -294.98263)
		(end 355.403658 -295.153588)
		(width 0.1143)
		(layer "In4.Cu")
		(net "P5E_CPU0_P1_TX_DN<11>")
	)
	(arc
		(start 355.403658 -295.206928)
		(mid 355.348667 -295.42675)
		(end 355.196648 -295.594786)
		(width 0.1143)
		(layer "In4.Cu")
		(net "P5E_CPU0_P1_TX_DN<11>")
	)
	(arc
		(start 374.367552 -351.81286)
		(mid 374.330464 -351.924349)
		(end 374.27281 -352.026728)
		(width 0.14224)
		(layer "In4.Cu")
		(net "P5E_CPU0_P1_TX_DN<11>")
	)
	(arc
		(start 354.974398 -295.813734)
		(mid 354.955287 -296.024046)
		(end 355.055424 -296.209974)
		(width 0.1143)
		(layer "In4.Cu")
		(net "P5E_CPU0_P1_TX_DN<11>")
	)
	(arc
		(start 355.661214 -293.884858)
		(mid 355.886359 -294.346171)
		(end 355.643942 -294.79875)
		(width 0.1143)
		(layer "In4.Cu")
		(net "P5E_CPU0_P1_TX_DN<11>")
	)
	(arc
		(start 354.953316 -291.165788)
		(mid 355.005365 -291.297307)
		(end 355.102414 -291.40023)
		(width 0.1143)
		(layer "In4.Cu")
		(net "P5E_CPU0_P1_TX_DN<11>")
	)
	(arc
		(start 352.583496 -376.676412)
		(mid 352.54924 -376.720349)
		(end 352.537014 -376.77471)
		(width 0.14224)
		(layer "In4.Cu")
		(net "P5E_CPU0_P1_TX_DN<11>")
	)
	(arc
		(start 355.097334 -296.251884)
		(mid 355.1663 -296.355004)
		(end 355.190552 -296.476674)
		(width 0.1143)
		(layer "In4.Cu")
		(net "P5E_CPU0_P1_TX_DN<11>")
	)
	(arc
		(start 355.182678 -291.447982)
		(mid 355.354543 -291.647746)
		(end 355.416358 -291.903912)
		(width 0.1143)
		(layer "In4.Cu")
		(net "P5E_CPU0_P1_TX_DN<11>")
	)
	(arc
		(start 355.036882 -295.717722)
		(mid 355.000971 -295.762689)
		(end 354.974398 -295.813734)
		(width 0.1143)
		(layer "In4.Cu")
		(net "P5E_CPU0_P1_TX_DN<11>")
	)
	(arc
		(start 375.117106 -337.63331)
		(mid 375.128753 -337.72085)
		(end 375.1326 -337.809078)
		(width 0.14224)
		(layer "In4.Cu")
		(net "P5E_CPU0_P1_TX_DN<11>")
	)
	(arc
		(start 355.416612 -291.908484)
		(mid 355.461151 -292.076542)
		(end 355.572314 -292.210236)
		(width 0.1143)
		(layer "In4.Cu")
		(net "P5E_CPU0_P1_TX_DN<11>")
	)
	(arc
		(start 375.1326 -348.377764)
		(mid 375.125297 -348.506592)
		(end 375.103644 -348.633796)
		(width 0.14224)
		(layer "In4.Cu")
		(net "P5E_CPU0_P1_TX_DN<11>")
	)
	(arc
		(start 355.582474 -293.215822)
		(mid 355.403932 -293.525846)
		(end 355.58222 -293.83609)
		(width 0.1143)
		(layer "In4.Cu")
		(net "P5E_CPU0_P1_TX_DN<11>")
	)
	(arc
		(start 355.236272 -298.346368)
		(mid 355.238718 -298.371221)
		(end 355.245924 -298.395136)
		(width 0.14224)
		(layer "In4.Cu")
		(net "P5E_CPU0_P1_TX_DN<11>")
	)
	(segment
		(start 350.855534 -382.61544)
		(end 351.126044 -382.34493)
		(width 0.12954)
		(layer "F.Cu")
		(net "P5E_CPU0_P1_TX_DN<10>")
	)
	(segment
		(start 355.78796 -289.209988)
		(end 355.321108 -289.475926)
		(width 0.12954)
		(layer "F.Cu")
		(net "P5E_CPU0_P1_TX_DN<10>")
	)
	(segment
		(start 350.855534 -383.31902)
		(end 350.855534 -382.61544)
		(width 0.12954)
		(layer "F.Cu")
		(net "P5E_CPU0_P1_TX_DN<10>")
	)
	(segment
		(start 351.151444 -383.61493)
		(end 350.855534 -383.31902)
		(width 0.12954)
		(layer "F.Cu")
		(net "P5E_CPU0_P1_TX_DN<10>")
	)
	(segment
		(start 354.148644 -298.1833)
		(end 355.66096 -301.834296)
		(width 0.14224)
		(layer "In4.Cu")
		(net "P5E_CPU0_P1_TX_DN<10>")
	)
	(segment
		(start 374.17502 -348.406466)
		(end 373.49303 -351.322386)
		(width 0.14224)
		(layer "In4.Cu")
		(net "P5E_CPU0_P1_TX_DN<10>")
	)
	(segment
		(start 354.19665 -290.771834)
		(end 354.195126 -290.77285)
		(width 0.1143)
		(layer "In4.Cu")
		(net "P5E_CPU0_P1_TX_DN<10>")
	)
	(segment
		(start 357.173276 -305.485038)
		(end 360.30662 -310.174894)
		(width 0.14224)
		(layer "In4.Cu")
		(net "P5E_CPU0_P1_TX_DN<10>")
	)
	(segment
		(start 354.476558 -295.145968)
		(end 354.476304 -295.145714)
		(width 0.1143)
		(layer "In4.Cu")
		(net "P5E_CPU0_P1_TX_DN<10>")
	)
	(segment
		(start 354.200206 -291.422074)
		(end 354.20173 -291.42309)
		(width 0.1143)
		(layer "In4.Cu")
		(net "P5E_CPU0_P1_TX_DN<10>")
	)
	(segment
		(start 354.66401 -289.963352)
		(end 354.63353 -289.981132)
		(width 0.1143)
		(layer "In4.Cu")
		(net "P5E_CPU0_P1_TX_DN<10>")
	)
	(segment
		(start 355.661214 -301.83455)
		(end 357.173276 -305.485038)
		(width 0.14224)
		(layer "In4.Cu")
		(net "P5E_CPU0_P1_TX_DN<10>")
	)
	(segment
		(start 369.603528 -322.283836)
		(end 373.348758 -333.210662)
		(width 0.14224)
		(layer "In4.Cu")
		(net "P5E_CPU0_P1_TX_DN<10>")
	)
	(segment
		(start 354.476304 -295.145714)
		(end 354.476304 -295.304718)
		(width 0.1143)
		(layer "In4.Cu")
		(net "P5E_CPU0_P1_TX_DN<10>")
	)
	(segment
		(start 354.703126 -289.940492)
		(end 354.66401 -289.963352)
		(width 0.1143)
		(layer "In4.Cu")
		(net "P5E_CPU0_P1_TX_DN<10>")
	)
	(segment
		(start 354.353368 -295.602152)
		(end 354.13061 -295.824656)
		(width 0.1143)
		(layer "In4.Cu")
		(net "P5E_CPU0_P1_TX_DN<10>")
	)
	(segment
		(start 354.63353 -292.210744)
		(end 354.66401 -292.228524)
		(width 0.1143)
		(layer "In4.Cu")
		(net "P5E_CPU0_P1_TX_DN<10>")
	)
	(segment
		(start 354.138992 -296.078656)
		(end 354.138992 -296.107104)
		(width 0.1143)
		(layer "In4.Cu")
		(net "P5E_CPU0_P1_TX_DN<10>")
	)
	(segment
		(start 354.63353 -293.830756)
		(end 354.66401 -293.848536)
		(width 0.1143)
		(layer "In4.Cu")
		(net "P5E_CPU0_P1_TX_DN<10>")
	)
	(segment
		(start 354.138992 -296.107104)
		(end 354.138992 -298.134532)
		(width 0.14224)
		(layer "In4.Cu")
		(net "P5E_CPU0_P1_TX_DN<10>")
	)
	(segment
		(start 374.189498 -337.881214)
		(end 374.189498 -348.28099)
		(width 0.14224)
		(layer "In4.Cu")
		(net "P5E_CPU0_P1_TX_DN<10>")
	)
	(segment
		(start 355.321108 -289.475926)
		(end 355.023166 -289.475926)
		(width 0.1143)
		(layer "In4.Cu")
		(net "P5E_CPU0_P1_TX_DN<10>")
	)
	(segment
		(start 350.882458 -382.101344)
		(end 351.126044 -382.34493)
		(width 0.14224)
		(layer "In4.Cu")
		(net "P5E_CPU0_P1_TX_DN<10>")
	)
	(segment
		(start 373.348758 -333.210662)
		(end 373.348758 -333.210408)
		(width 0.14224)
		(layer "In4.Cu")
		(net "P5E_CPU0_P1_TX_DN<10>")
	)
	(segment
		(start 354.703126 -294.800528)
		(end 354.63353 -294.841168)
		(width 0.1143)
		(layer "In4.Cu")
		(net "P5E_CPU0_P1_TX_DN<10>")
	)
	(segment
		(start 354.19665 -291.420042)
		(end 354.197666 -291.42055)
		(width 0.1143)
		(layer "In4.Cu")
		(net "P5E_CPU0_P1_TX_DN<10>")
	)
	(segment
		(start 369.593368 -322.263516)
		(end 369.603528 -322.283836)
		(width 0.14224)
		(layer "In4.Cu")
		(net "P5E_CPU0_P1_TX_DN<10>")
	)
	(segment
		(start 354.093272 -295.914572)
		(end 354.093272 -296.032936)
		(width 0.1143)
		(layer "In4.Cu")
		(net "P5E_CPU0_P1_TX_DN<10>")
	)
	(segment
		(start 354.192078 -290.774628)
		(end 354.16236 -290.791646)
		(width 0.1143)
		(layer "In4.Cu")
		(net "P5E_CPU0_P1_TX_DN<10>")
	)
	(segment
		(start 362.861606 -366.696752)
		(end 351.858326 -374.857518)
		(width 0.14224)
		(layer "In4.Cu")
		(net "P5E_CPU0_P1_TX_DN<10>")
	)
	(segment
		(start 354.66401 -292.228524)
		(end 354.703126 -292.251384)
		(width 0.1143)
		(layer "In4.Cu")
		(net "P5E_CPU0_P1_TX_DN<10>")
	)
	(segment
		(start 354.193348 -291.41801)
		(end 354.19411 -291.418518)
		(width 0.1143)
		(layer "In4.Cu")
		(net "P5E_CPU0_P1_TX_DN<10>")
	)
	(segment
		(start 373.391176 -333.37373)
		(end 374.178322 -337.75523)
		(width 0.14224)
		(layer "In4.Cu")
		(net "P5E_CPU0_P1_TX_DN<10>")
	)
	(segment
		(start 354.19411 -290.773358)
		(end 354.193348 -290.773866)
		(width 0.1143)
		(layer "In4.Cu")
		(net "P5E_CPU0_P1_TX_DN<10>")
	)
	(segment
		(start 355.023166 -289.475926)
		(end 354.940362 -289.55873)
		(width 0.1143)
		(layer "In4.Cu")
		(net "P5E_CPU0_P1_TX_DN<10>")
	)
	(segment
		(start 354.20173 -291.42309)
		(end 354.233226 -291.441378)
		(width 0.1143)
		(layer "In4.Cu")
		(net "P5E_CPU0_P1_TX_DN<10>")
	)
	(segment
		(start 368.478308 -320.130932)
		(end 369.593368 -322.263516)
		(width 0.14224)
		(layer "In4.Cu")
		(net "P5E_CPU0_P1_TX_DN<10>")
	)
	(segment
		(start 354.197666 -291.42055)
		(end 354.200206 -291.422074)
		(width 0.1143)
		(layer "In4.Cu")
		(net "P5E_CPU0_P1_TX_DN<10>")
	)
	(segment
		(start 354.195126 -291.419026)
		(end 354.19665 -291.420042)
		(width 0.1143)
		(layer "In4.Cu")
		(net "P5E_CPU0_P1_TX_DN<10>")
	)
	(segment
		(start 360.30662 -310.174894)
		(end 368.478308 -320.130932)
		(width 0.14224)
		(layer "In4.Cu")
		(net "P5E_CPU0_P1_TX_DN<10>")
	)
	(segment
		(start 354.66401 -293.848536)
		(end 354.703126 -293.871396)
		(width 0.1143)
		(layer "In4.Cu")
		(net "P5E_CPU0_P1_TX_DN<10>")
	)
	(segment
		(start 354.703126 -293.180516)
		(end 354.66401 -293.203376)
		(width 0.1143)
		(layer "In4.Cu")
		(net "P5E_CPU0_P1_TX_DN<10>")
	)
	(segment
		(start 354.093272 -296.032936)
		(end 354.138992 -296.078656)
		(width 0.1143)
		(layer "In4.Cu")
		(net "P5E_CPU0_P1_TX_DN<10>")
	)
	(segment
		(start 355.66096 -301.834296)
		(end 355.661214 -301.83455)
		(width 0.14224)
		(layer "In4.Cu")
		(net "P5E_CPU0_P1_TX_DN<10>")
	)
	(segment
		(start 354.16236 -291.40023)
		(end 354.193348 -291.41801)
		(width 0.1143)
		(layer "In4.Cu")
		(net "P5E_CPU0_P1_TX_DN<10>")
	)
	(segment
		(start 350.835214 -376.889772)
		(end 350.835214 -381.987298)
		(width 0.14224)
		(layer "In4.Cu")
		(net "P5E_CPU0_P1_TX_DN<10>")
	)
	(segment
		(start 354.233226 -290.750498)
		(end 354.19665 -290.771834)
		(width 0.1143)
		(layer "In4.Cu")
		(net "P5E_CPU0_P1_TX_DN<10>")
	)
	(segment
		(start 354.66401 -293.203376)
		(end 354.63353 -293.221156)
		(width 0.1143)
		(layer "In4.Cu")
		(net "P5E_CPU0_P1_TX_DN<10>")
	)
	(segment
		(start 354.19411 -291.418518)
		(end 354.195126 -291.419026)
		(width 0.1143)
		(layer "In4.Cu")
		(net "P5E_CPU0_P1_TX_DN<10>")
	)
	(segment
		(start 373.398796 -351.533968)
		(end 362.861606 -366.696752)
		(width 0.14224)
		(layer "In4.Cu")
		(net "P5E_CPU0_P1_TX_DN<10>")
	)
	(segment
		(start 354.193348 -290.773866)
		(end 354.192078 -290.774628)
		(width 0.1143)
		(layer "In4.Cu")
		(net "P5E_CPU0_P1_TX_DN<10>")
	)
	(segment
		(start 354.195126 -290.77285)
		(end 354.19411 -290.773358)
		(width 0.1143)
		(layer "In4.Cu")
		(net "P5E_CPU0_P1_TX_DN<10>")
	)
	(arc
		(start 354.703126 -292.251384)
		(mid 354.946453 -292.71595)
		(end 354.703126 -293.180516)
		(width 0.1143)
		(layer "In4.Cu")
		(net "P5E_CPU0_P1_TX_DN<10>")
	)
	(arc
		(start 354.476304 -295.304718)
		(mid 354.444403 -295.465655)
		(end 354.353368 -295.602152)
		(width 0.1143)
		(layer "In4.Cu")
		(net "P5E_CPU0_P1_TX_DN<10>")
	)
	(arc
		(start 354.703126 -293.871396)
		(mid 354.946453 -294.335962)
		(end 354.703126 -294.800528)
		(width 0.1143)
		(layer "In4.Cu")
		(net "P5E_CPU0_P1_TX_DN<10>")
	)
	(arc
		(start 354.936552 -289.58159)
		(mid 354.855119 -289.783988)
		(end 354.703126 -289.940492)
		(width 0.1143)
		(layer "In4.Cu")
		(net "P5E_CPU0_P1_TX_DN<10>")
	)
	(arc
		(start 350.835214 -381.987298)
		(mid 350.847491 -382.049021)
		(end 350.882458 -382.101344)
		(width 0.14224)
		(layer "In4.Cu")
		(net "P5E_CPU0_P1_TX_DN<10>")
	)
	(arc
		(start 374.189498 -348.28099)
		(mid 374.185866 -348.344144)
		(end 374.17502 -348.406466)
		(width 0.14224)
		(layer "In4.Cu")
		(net "P5E_CPU0_P1_TX_DN<10>")
	)
	(arc
		(start 354.138992 -298.134532)
		(mid 354.141438 -298.159385)
		(end 354.148644 -298.1833)
		(width 0.14224)
		(layer "In4.Cu")
		(net "P5E_CPU0_P1_TX_DN<10>")
	)
	(arc
		(start 373.348758 -333.210408)
		(mid 373.373059 -333.291266)
		(end 373.391176 -333.37373)
		(width 0.14224)
		(layer "In4.Cu")
		(net "P5E_CPU0_P1_TX_DN<10>")
	)
	(arc
		(start 354.476558 -291.905944)
		(mid 354.518107 -292.077366)
		(end 354.63353 -292.210744)
		(width 0.1143)
		(layer "In4.Cu")
		(net "P5E_CPU0_P1_TX_DN<10>")
	)
	(arc
		(start 373.49303 -351.322386)
		(mid 373.455912 -351.432629)
		(end 373.398796 -351.533968)
		(width 0.14224)
		(layer "In4.Cu")
		(net "P5E_CPU0_P1_TX_DN<10>")
	)
	(arc
		(start 374.178322 -337.75523)
		(mid 374.186717 -337.817973)
		(end 374.189498 -337.881214)
		(width 0.14224)
		(layer "In4.Cu")
		(net "P5E_CPU0_P1_TX_DN<10>")
	)
	(arc
		(start 354.233226 -291.441378)
		(mid 354.412039 -291.643728)
		(end 354.476558 -291.905944)
		(width 0.1143)
		(layer "In4.Cu")
		(net "P5E_CPU0_P1_TX_DN<10>")
	)
	(arc
		(start 354.940362 -289.55873)
		(mid 354.938574 -289.570179)
		(end 354.936552 -289.58159)
		(width 0.1143)
		(layer "In4.Cu")
		(net "P5E_CPU0_P1_TX_DN<10>")
	)
	(arc
		(start 351.858326 -374.857518)
		(mid 351.105449 -375.75216)
		(end 350.835214 -376.889772)
		(width 0.14224)
		(layer "In4.Cu")
		(net "P5E_CPU0_P1_TX_DN<10>")
	)
	(arc
		(start 354.63353 -289.981132)
		(mid 354.518103 -290.114508)
		(end 354.476558 -290.285932)
		(width 0.1143)
		(layer "In4.Cu")
		(net "P5E_CPU0_P1_TX_DN<10>")
	)
	(arc
		(start 354.63353 -294.841168)
		(mid 354.518103 -294.974544)
		(end 354.476558 -295.145968)
		(width 0.1143)
		(layer "In4.Cu")
		(net "P5E_CPU0_P1_TX_DN<10>")
	)
	(arc
		(start 354.16236 -290.791646)
		(mid 354.006432 -291.095938)
		(end 354.16236 -291.40023)
		(width 0.1143)
		(layer "In4.Cu")
		(net "P5E_CPU0_P1_TX_DN<10>")
	)
	(arc
		(start 354.63353 -293.221156)
		(mid 354.476553 -293.525956)
		(end 354.63353 -293.830756)
		(width 0.1143)
		(layer "In4.Cu")
		(net "P5E_CPU0_P1_TX_DN<10>")
	)
	(arc
		(start 354.476558 -290.285932)
		(mid 354.412043 -290.548151)
		(end 354.233226 -290.750498)
		(width 0.1143)
		(layer "In4.Cu")
		(net "P5E_CPU0_P1_TX_DN<10>")
	)
	(arc
		(start 354.13061 -295.824656)
		(mid 354.102991 -295.865896)
		(end 354.093272 -295.914572)
		(width 0.1143)
		(layer "In4.Cu")
		(net "P5E_CPU0_P1_TX_DN<10>")
	)
	(segment
		(start 347.327982 -285.970218)
		(end 346.86113 -286.236156)
		(width 0.12954)
		(layer "F.Cu")
		(net "P5E_CPU0_P1_TX_DN<0>")
	)
	(segment
		(start 331.228192 -389.86206)
		(end 330.932282 -390.15797)
		(width 0.12954)
		(layer "F.Cu")
		(net "P5E_CPU0_P1_TX_DN<0>")
	)
	(segment
		(start 330.228702 -390.15797)
		(end 329.958192 -389.88746)
		(width 0.12954)
		(layer "F.Cu")
		(net "P5E_CPU0_P1_TX_DN<0>")
	)
	(segment
		(start 330.932282 -390.15797)
		(end 330.228702 -390.15797)
		(width 0.12954)
		(layer "F.Cu")
		(net "P5E_CPU0_P1_TX_DN<0>")
	)
	(segment
		(start 345.076526 -295.145968)
		(end 345.076272 -295.145714)
		(width 0.1143)
		(layer "In4.Cu")
		(net "P5E_CPU0_P1_TX_DN<0>")
	)
	(segment
		(start 345.263978 -288.9885)
		(end 345.303094 -289.01136)
		(width 0.1143)
		(layer "In4.Cu")
		(net "P5E_CPU0_P1_TX_DN<0>")
	)
	(segment
		(start 328.7395 -380.07798)
		(end 328.87666 -380.21514)
		(width 0.14224)
		(layer "In4.Cu")
		(net "P5E_CPU0_P1_TX_DN<0>")
	)
	(segment
		(start 352.549714 -315.576204)
		(end 360.510074 -325.275194)
		(width 0.14224)
		(layer "In4.Cu")
		(net "P5E_CPU0_P1_TX_DN<0>")
	)
	(segment
		(start 346.563188 -286.236156)
		(end 346.480384 -286.31896)
		(width 0.1143)
		(layer "In4.Cu")
		(net "P5E_CPU0_P1_TX_DN<0>")
	)
	(segment
		(start 329.667362 -390.17829)
		(end 329.958192 -389.88746)
		(width 0.14224)
		(layer "In4.Cu")
		(net "P5E_CPU0_P1_TX_DN<0>")
	)
	(segment
		(start 328.7395 -383.967482)
		(end 328.7395 -386.342128)
		(width 0.14224)
		(layer "In4.Cu")
		(net "P5E_CPU0_P1_TX_DN<0>")
	)
	(segment
		(start 345.303094 -293.180516)
		(end 345.263978 -293.203376)
		(width 0.1143)
		(layer "In4.Cu")
		(net "P5E_CPU0_P1_TX_DN<0>")
	)
	(segment
		(start 364.60176 -345.978734)
		(end 364.600744 -345.979242)
		(width 0.14224)
		(layer "In4.Cu")
		(net "P5E_CPU0_P1_TX_DN<0>")
	)
	(segment
		(start 345.233498 -293.830756)
		(end 345.263978 -293.848536)
		(width 0.1143)
		(layer "In4.Cu")
		(net "P5E_CPU0_P1_TX_DN<0>")
	)
	(segment
		(start 345.303094 -289.940492)
		(end 345.263978 -289.963352)
		(width 0.1143)
		(layer "In4.Cu")
		(net "P5E_CPU0_P1_TX_DN<0>")
	)
	(segment
		(start 344.833194 -290.750498)
		(end 344.794078 -290.773358)
		(width 0.1143)
		(layer "In4.Cu")
		(net "P5E_CPU0_P1_TX_DN<0>")
	)
	(segment
		(start 328.87666 -383.403602)
		(end 328.87666 -383.830322)
		(width 0.14224)
		(layer "In4.Cu")
		(net "P5E_CPU0_P1_TX_DN<0>")
	)
	(segment
		(start 328.7395 -386.342128)
		(end 328.87666 -386.479288)
		(width 0.14224)
		(layer "In4.Cu")
		(net "P5E_CPU0_P1_TX_DN<0>")
	)
	(segment
		(start 328.7395 -380.77902)
		(end 328.7395 -382.138682)
		(width 0.14224)
		(layer "In4.Cu")
		(net "P5E_CPU0_P1_TX_DN<0>")
	)
	(segment
		(start 344.652092 -299.644054)
		(end 349.133668 -310.463692)
		(width 0.14224)
		(layer "In4.Cu")
		(net "P5E_CPU0_P1_TX_DN<0>")
	)
	(segment
		(start 345.263978 -289.963352)
		(end 345.233498 -289.981132)
		(width 0.1143)
		(layer "In4.Cu")
		(net "P5E_CPU0_P1_TX_DN<0>")
	)
	(segment
		(start 328.87666 -386.479288)
		(end 328.87666 -386.906008)
		(width 0.14224)
		(layer "In4.Cu")
		(net "P5E_CPU0_P1_TX_DN<0>")
	)
	(segment
		(start 328.7395 -382.839722)
		(end 328.7395 -383.266442)
		(width 0.14224)
		(layer "In4.Cu")
		(net "P5E_CPU0_P1_TX_DN<0>")
	)
	(segment
		(start 328.87666 -386.906008)
		(end 328.7395 -387.043168)
		(width 0.14224)
		(layer "In4.Cu")
		(net "P5E_CPU0_P1_TX_DN<0>")
	)
	(segment
		(start 344.606372 -296.159936)
		(end 344.652092 -296.205656)
		(width 0.1143)
		(layer "In4.Cu")
		(net "P5E_CPU0_P1_TX_DN<0>")
	)
	(segment
		(start 345.303094 -294.800528)
		(end 345.233498 -294.841168)
		(width 0.1143)
		(layer "In4.Cu")
		(net "P5E_CPU0_P1_TX_DN<0>")
	)
	(segment
		(start 329.046078 -390.17829)
		(end 329.667362 -390.17829)
		(width 0.14224)
		(layer "In4.Cu")
		(net "P5E_CPU0_P1_TX_DN<0>")
	)
	(segment
		(start 345.303094 -288.320734)
		(end 345.263978 -288.343594)
		(width 0.1143)
		(layer "In4.Cu")
		(net "P5E_CPU0_P1_TX_DN<0>")
	)
	(segment
		(start 344.652092 -296.234104)
		(end 344.652092 -299.644054)
		(width 0.14224)
		(layer "In4.Cu")
		(net "P5E_CPU0_P1_TX_DN<0>")
	)
	(segment
		(start 344.762328 -291.40023)
		(end 344.833194 -291.441378)
		(width 0.1143)
		(layer "In4.Cu")
		(net "P5E_CPU0_P1_TX_DN<0>")
	)
	(segment
		(start 363.688376 -348.034864)
		(end 354.123752 -359.711752)
		(width 0.14224)
		(layer "In4.Cu")
		(net "P5E_CPU0_P1_TX_DN<0>")
	)
	(segment
		(start 345.734132 -287.533588)
		(end 345.702382 -287.551876)
		(width 0.1143)
		(layer "In4.Cu")
		(net "P5E_CPU0_P1_TX_DN<0>")
	)
	(segment
		(start 345.233498 -292.210744)
		(end 345.303094 -292.251384)
		(width 0.1143)
		(layer "In4.Cu")
		(net "P5E_CPU0_P1_TX_DN<0>")
	)
	(segment
		(start 349.133668 -310.463692)
		(end 352.549714 -315.576204)
		(width 0.14224)
		(layer "In4.Cu")
		(net "P5E_CPU0_P1_TX_DN<0>")
	)
	(segment
		(start 328.87666 -380.64186)
		(end 328.7395 -380.77902)
		(width 0.14224)
		(layer "In4.Cu")
		(net "P5E_CPU0_P1_TX_DN<0>")
	)
	(segment
		(start 354.123752 -359.711752)
		(end 329.64247 -374.385332)
		(width 0.14224)
		(layer "In4.Cu")
		(net "P5E_CPU0_P1_TX_DN<0>")
	)
	(segment
		(start 360.510074 -325.275194)
		(end 364.24997 -336.201766)
		(width 0.14224)
		(layer "In4.Cu")
		(net "P5E_CPU0_P1_TX_DN<0>")
	)
	(segment
		(start 328.7395 -383.266442)
		(end 328.87666 -383.403602)
		(width 0.14224)
		(layer "In4.Cu")
		(net "P5E_CPU0_P1_TX_DN<0>")
	)
	(segment
		(start 344.983308 -295.57218)
		(end 344.64371 -295.911524)
		(width 0.1143)
		(layer "In4.Cu")
		(net "P5E_CPU0_P1_TX_DN<0>")
	)
	(segment
		(start 345.076272 -295.145714)
		(end 345.076272 -295.347136)
		(width 0.1143)
		(layer "In4.Cu")
		(net "P5E_CPU0_P1_TX_DN<0>")
	)
	(segment
		(start 328.7395 -387.043168)
		(end 328.7395 -389.763254)
		(width 0.14224)
		(layer "In4.Cu")
		(net "P5E_CPU0_P1_TX_DN<0>")
	)
	(segment
		(start 328.7395 -382.138682)
		(end 328.87666 -382.275842)
		(width 0.14224)
		(layer "In4.Cu")
		(net "P5E_CPU0_P1_TX_DN<0>")
	)
	(segment
		(start 345.770708 -287.512252)
		(end 345.734132 -287.533588)
		(width 0.1143)
		(layer "In4.Cu")
		(net "P5E_CPU0_P1_TX_DN<0>")
	)
	(segment
		(start 344.794078 -290.773358)
		(end 344.762328 -290.791646)
		(width 0.1143)
		(layer "In4.Cu")
		(net "P5E_CPU0_P1_TX_DN<0>")
	)
	(segment
		(start 364.60176 -339.072728)
		(end 364.60176 -345.978734)
		(width 0.14224)
		(layer "In4.Cu")
		(net "P5E_CPU0_P1_TX_DN<0>")
	)
	(segment
		(start 328.87666 -382.275842)
		(end 328.87666 -382.702562)
		(width 0.14224)
		(layer "In4.Cu")
		(net "P5E_CPU0_P1_TX_DN<0>")
	)
	(segment
		(start 345.263978 -293.848536)
		(end 345.303094 -293.871396)
		(width 0.1143)
		(layer "In4.Cu")
		(net "P5E_CPU0_P1_TX_DN<0>")
	)
	(segment
		(start 328.87666 -380.21514)
		(end 328.87666 -380.64186)
		(width 0.14224)
		(layer "In4.Cu")
		(net "P5E_CPU0_P1_TX_DN<0>")
	)
	(segment
		(start 346.86113 -286.236156)
		(end 346.563188 -286.236156)
		(width 0.1143)
		(layer "In4.Cu")
		(net "P5E_CPU0_P1_TX_DN<0>")
	)
	(segment
		(start 344.652092 -296.205656)
		(end 344.652092 -296.234104)
		(width 0.1143)
		(layer "In4.Cu")
		(net "P5E_CPU0_P1_TX_DN<0>")
	)
	(segment
		(start 364.28172 -336.324194)
		(end 364.43031 -337.150456)
		(width 0.14224)
		(layer "In4.Cu")
		(net "P5E_CPU0_P1_TX_DN<0>")
	)
	(segment
		(start 328.87666 -383.830322)
		(end 328.7395 -383.967482)
		(width 0.14224)
		(layer "In4.Cu")
		(net "P5E_CPU0_P1_TX_DN<0>")
	)
	(segment
		(start 344.606372 -296.00144)
		(end 344.606372 -296.159936)
		(width 0.1143)
		(layer "In4.Cu")
		(net "P5E_CPU0_P1_TX_DN<0>")
	)
	(segment
		(start 328.7395 -375.979436)
		(end 328.7395 -380.07798)
		(width 0.14224)
		(layer "In4.Cu")
		(net "P5E_CPU0_P1_TX_DN<0>")
	)
	(segment
		(start 328.853546 -390.038336)
		(end 328.956162 -390.140952)
		(width 0.14224)
		(layer "In4.Cu")
		(net "P5E_CPU0_P1_TX_DN<0>")
	)
	(segment
		(start 345.263978 -293.203376)
		(end 345.233498 -293.221156)
		(width 0.1143)
		(layer "In4.Cu")
		(net "P5E_CPU0_P1_TX_DN<0>")
	)
	(segment
		(start 345.263978 -288.343594)
		(end 345.231466 -288.36239)
		(width 0.1143)
		(layer "In4.Cu")
		(net "P5E_CPU0_P1_TX_DN<0>")
	)
	(segment
		(start 328.87666 -382.702562)
		(end 328.7395 -382.839722)
		(width 0.14224)
		(layer "In4.Cu")
		(net "P5E_CPU0_P1_TX_DN<0>")
	)
	(segment
		(start 345.233498 -288.97072)
		(end 345.263978 -288.9885)
		(width 0.1143)
		(layer "In4.Cu")
		(net "P5E_CPU0_P1_TX_DN<0>")
	)
	(segment
		(start 346.243148 -286.700722)
		(end 346.204032 -286.723582)
		(width 0.1143)
		(layer "In4.Cu")
		(net "P5E_CPU0_P1_TX_DN<0>")
	)
	(segment
		(start 346.204032 -286.723582)
		(end 346.17152 -286.742378)
		(width 0.1143)
		(layer "In4.Cu")
		(net "P5E_CPU0_P1_TX_DN<0>")
	)
	(arc
		(start 328.956162 -390.140952)
		(mid 328.997402 -390.168571)
		(end 329.046078 -390.17829)
		(width 0.14224)
		(layer "In4.Cu")
		(net "P5E_CPU0_P1_TX_DN<0>")
	)
	(arc
		(start 345.076526 -291.91712)
		(mid 345.120611 -292.082318)
		(end 345.233498 -292.210744)
		(width 0.1143)
		(layer "In4.Cu")
		(net "P5E_CPU0_P1_TX_DN<0>")
	)
	(arc
		(start 345.233498 -289.981132)
		(mid 345.118071 -290.114508)
		(end 345.076526 -290.285932)
		(width 0.1143)
		(layer "In4.Cu")
		(net "P5E_CPU0_P1_TX_DN<0>")
	)
	(arc
		(start 345.076526 -288.66592)
		(mid 345.118075 -288.837342)
		(end 345.233498 -288.97072)
		(width 0.1143)
		(layer "In4.Cu")
		(net "P5E_CPU0_P1_TX_DN<0>")
	)
	(arc
		(start 345.076526 -290.285932)
		(mid 345.012011 -290.548151)
		(end 344.833194 -290.750498)
		(width 0.1143)
		(layer "In4.Cu")
		(net "P5E_CPU0_P1_TX_DN<0>")
	)
	(arc
		(start 344.64371 -295.911524)
		(mid 344.616091 -295.952764)
		(end 344.606372 -296.00144)
		(width 0.1143)
		(layer "In4.Cu")
		(net "P5E_CPU0_P1_TX_DN<0>")
	)
	(arc
		(start 345.702382 -287.551876)
		(mid 345.587706 -287.68521)
		(end 345.546426 -287.856168)
		(width 0.1143)
		(layer "In4.Cu")
		(net "P5E_CPU0_P1_TX_DN<0>")
	)
	(arc
		(start 364.43031 -337.150456)
		(mid 364.558816 -338.107776)
		(end 364.60176 -339.072728)
		(width 0.14224)
		(layer "In4.Cu")
		(net "P5E_CPU0_P1_TX_DN<0>")
	)
	(arc
		(start 345.231466 -288.36239)
		(mid 345.117537 -288.495537)
		(end 345.076526 -288.66592)
		(width 0.1143)
		(layer "In4.Cu")
		(net "P5E_CPU0_P1_TX_DN<0>")
	)
	(arc
		(start 345.303094 -292.251384)
		(mid 345.546421 -292.71595)
		(end 345.303094 -293.180516)
		(width 0.1143)
		(layer "In4.Cu")
		(net "P5E_CPU0_P1_TX_DN<0>")
	)
	(arc
		(start 345.303094 -289.01136)
		(mid 345.546421 -289.475926)
		(end 345.303094 -289.940492)
		(width 0.1143)
		(layer "In4.Cu")
		(net "P5E_CPU0_P1_TX_DN<0>")
	)
	(arc
		(start 345.071954 -291.86632)
		(mid 345.074969 -291.891654)
		(end 345.076526 -291.91712)
		(width 0.1143)
		(layer "In4.Cu")
		(net "P5E_CPU0_P1_TX_DN<0>")
	)
	(arc
		(start 346.480384 -286.31896)
		(mid 346.478596 -286.330409)
		(end 346.476574 -286.34182)
		(width 0.1143)
		(layer "In4.Cu")
		(net "P5E_CPU0_P1_TX_DN<0>")
	)
	(arc
		(start 364.24997 -336.201766)
		(mid 364.268173 -336.262376)
		(end 364.28172 -336.324194)
		(width 0.14224)
		(layer "In4.Cu")
		(net "P5E_CPU0_P1_TX_DN<0>")
	)
	(arc
		(start 328.7395 -389.763254)
		(mid 328.769136 -389.912153)
		(end 328.853546 -390.038336)
		(width 0.14224)
		(layer "In4.Cu")
		(net "P5E_CPU0_P1_TX_DN<0>")
	)
	(arc
		(start 329.64247 -374.385332)
		(mid 328.980894 -375.063385)
		(end 328.7395 -375.979436)
		(width 0.14224)
		(layer "In4.Cu")
		(net "P5E_CPU0_P1_TX_DN<0>")
	)
	(arc
		(start 345.233498 -293.221156)
		(mid 345.076521 -293.525956)
		(end 345.233498 -293.830756)
		(width 0.1143)
		(layer "In4.Cu")
		(net "P5E_CPU0_P1_TX_DN<0>")
	)
	(arc
		(start 345.546426 -287.856168)
		(mid 345.481911 -288.118387)
		(end 345.303094 -288.320734)
		(width 0.1143)
		(layer "In4.Cu")
		(net "P5E_CPU0_P1_TX_DN<0>")
	)
	(arc
		(start 364.600744 -345.979242)
		(mid 364.283126 -347.068558)
		(end 363.688376 -348.034864)
		(width 0.14224)
		(layer "In4.Cu")
		(net "P5E_CPU0_P1_TX_DN<0>")
	)
	(arc
		(start 346.01658 -287.045908)
		(mid 345.951344 -287.309499)
		(end 345.770708 -287.512252)
		(width 0.1143)
		(layer "In4.Cu")
		(net "P5E_CPU0_P1_TX_DN<0>")
	)
	(arc
		(start 345.076272 -295.347136)
		(mid 345.052163 -295.4689)
		(end 344.983308 -295.57218)
		(width 0.1143)
		(layer "In4.Cu")
		(net "P5E_CPU0_P1_TX_DN<0>")
	)
	(arc
		(start 345.233498 -294.841168)
		(mid 345.117995 -294.97452)
		(end 345.076526 -295.145968)
		(width 0.1143)
		(layer "In4.Cu")
		(net "P5E_CPU0_P1_TX_DN<0>")
	)
	(arc
		(start 345.303094 -293.871396)
		(mid 345.546421 -294.335962)
		(end 345.303094 -294.800528)
		(width 0.1143)
		(layer "In4.Cu")
		(net "P5E_CPU0_P1_TX_DN<0>")
	)
	(arc
		(start 344.762328 -290.791646)
		(mid 344.6064 -291.095938)
		(end 344.762328 -291.40023)
		(width 0.1143)
		(layer "In4.Cu")
		(net "P5E_CPU0_P1_TX_DN<0>")
	)
	(arc
		(start 346.17152 -286.742378)
		(mid 346.057591 -286.875525)
		(end 346.01658 -287.045908)
		(width 0.1143)
		(layer "In4.Cu")
		(net "P5E_CPU0_P1_TX_DN<0>")
	)
	(arc
		(start 346.476574 -286.34182)
		(mid 346.395141 -286.544218)
		(end 346.243148 -286.700722)
		(width 0.1143)
		(layer "In4.Cu")
		(net "P5E_CPU0_P1_TX_DN<0>")
	)
	(arc
		(start 344.833194 -291.441378)
		(mid 344.9913 -291.6321)
		(end 345.071954 -291.86632)
		(width 0.1143)
		(layer "In4.Cu")
		(net "P5E_CPU0_P1_TX_DN<0>")
	)
	(segment
		(start 346.998036 -394.385292)
		(end 347.518736 -394.385292)
		(width 0.127)
		(layer "F.Cu")
		(net "P5E_CPU0_P1_RX_DP<9>")
	)
	(segment
		(start 355.78796 -276.250146)
		(end 355.321108 -276.516084)
		(width 0.12954)
		(layer "F.Cu")
		(net "P5E_CPU0_P1_RX_DP<9>")
	)
	(segment
		(start 353.763072 -292.251384)
		(end 353.693476 -292.210744)
		(width 0.1143)
		(layer "In11.Cu")
		(net "P5E_CPU0_P1_RX_DP<9>")
	)
	(segment
		(start 347.613732 -394.031216)
		(end 347.787976 -393.930632)
		(width 0.14224)
		(layer "In11.Cu")
		(net "P5E_CPU0_P1_RX_DP<9>")
	)
	(segment
		(start 353.754944 -285.766764)
		(end 353.754182 -285.766256)
		(width 0.1143)
		(layer "In11.Cu")
		(net "P5E_CPU0_P1_RX_DP<9>")
	)
	(segment
		(start 353.760532 -287.389824)
		(end 353.693476 -287.350708)
		(width 0.1143)
		(layer "In11.Cu")
		(net "P5E_CPU0_P1_RX_DP<9>")
	)
	(segment
		(start 354.195126 -277.813008)
		(end 354.19665 -277.811992)
		(width 0.1143)
		(layer "In11.Cu")
		(net "P5E_CPU0_P1_RX_DP<9>")
	)
	(segment
		(start 353.763072 -280.911554)
		(end 353.693476 -280.870914)
		(width 0.1143)
		(layer "In11.Cu")
		(net "P5E_CPU0_P1_RX_DP<9>")
	)
	(segment
		(start 353.536504 -280.566114)
		(end 353.536504 -280.520394)
		(width 0.1143)
		(layer "In11.Cu")
		(net "P5E_CPU0_P1_RX_DP<9>")
	)
	(segment
		(start 353.288854 -280.099262)
		(end 353.2886 -280.099516)
		(width 0.1143)
		(layer "In11.Cu")
		(net "P5E_CPU0_P1_RX_DP<9>")
	)
	(segment
		(start 353.255072 -279.43302)
		(end 353.256596 -279.432004)
		(width 0.1143)
		(layer "In11.Cu")
		(net "P5E_CPU0_P1_RX_DP<9>")
	)
	(segment
		(start 353.763072 -289.01136)
		(end 353.693476 -288.97072)
		(width 0.1143)
		(layer "In11.Cu")
		(net "P5E_CPU0_P1_RX_DP<9>")
	)
	(segment
		(start 373.539512 -348.371668)
		(end 373.539512 -339.524848)
		(width 0.14224)
		(layer "In11.Cu")
		(net "P5E_CPU0_P1_RX_DP<9>")
	)
	(segment
		(start 373.535194 -339.52053)
		(end 371.351556 -327.369424)
		(width 0.14224)
		(layer "In11.Cu")
		(net "P5E_CPU0_P1_RX_DP<9>")
	)
	(segment
		(start 353.536504 -295.402508)
		(end 353.536504 -295.145968)
		(width 0.1143)
		(layer "In11.Cu")
		(net "P5E_CPU0_P1_RX_DP<9>")
	)
	(segment
		(start 347.563186 -392.7348)
		(end 347.83268 -392.46556)
		(width 0.14224)
		(layer "In11.Cu")
		(net "P5E_CPU0_P1_RX_DP<9>")
	)
	(segment
		(start 353.693476 -285.12135)
		(end 353.763072 -285.08071)
		(width 0.1143)
		(layer "In11.Cu")
		(net "P5E_CPU0_P1_RX_DP<9>")
	)
	(segment
		(start 354.63353 -277.02129)
		(end 354.703126 -276.98065)
		(width 0.1143)
		(layer "In11.Cu")
		(net "P5E_CPU0_P1_RX_DP<9>")
	)
	(segment
		(start 353.723956 -288.343594)
		(end 353.763072 -288.320734)
		(width 0.1143)
		(layer "In11.Cu")
		(net "P5E_CPU0_P1_RX_DP<9>")
	)
	(segment
		(start 350.915732 -374.716802)
		(end 351.493836 -374.477534)
		(width 0.14224)
		(layer "In11.Cu")
		(net "P5E_CPU0_P1_RX_DP<9>")
	)
	(segment
		(start 347.787976 -393.930632)
		(end 347.876114 -393.842494)
		(width 0.14224)
		(layer "In11.Cu")
		(net "P5E_CPU0_P1_RX_DP<9>")
	)
	(segment
		(start 353.330764 -280.12771)
		(end 353.288854 -280.099262)
		(width 0.1143)
		(layer "In11.Cu")
		(net "P5E_CPU0_P1_RX_DP<9>")
	)
	(segment
		(start 354.189792 -277.816056)
		(end 354.190554 -277.815548)
		(width 0.1143)
		(layer "In11.Cu")
		(net "P5E_CPU0_P1_RX_DP<9>")
	)
	(segment
		(start 369.11407 -323.088762)
		(end 362.16717 -314.624212)
		(width 0.14224)
		(layer "In11.Cu")
		(net "P5E_CPU0_P1_RX_DP<9>")
	)
	(segment
		(start 362.16717 -314.624212)
		(end 356.33279 -305.892454)
		(width 0.14224)
		(layer "In11.Cu")
		(net "P5E_CPU0_P1_RX_DP<9>")
	)
	(segment
		(start 353.763072 -293.871396)
		(end 353.693476 -293.830756)
		(width 0.1143)
		(layer "In11.Cu")
		(net "P5E_CPU0_P1_RX_DP<9>")
	)
	(segment
		(start 354.190554 -277.815548)
		(end 354.193348 -277.814024)
		(width 0.1143)
		(layer "In11.Cu")
		(net "P5E_CPU0_P1_RX_DP<9>")
	)
	(segment
		(start 354.186236 -277.818088)
		(end 354.187506 -277.817326)
		(width 0.1143)
		(layer "In11.Cu")
		(net "P5E_CPU0_P1_RX_DP<9>")
	)
	(segment
		(start 348.0816 -382.757426)
		(end 348.0816 -381.461772)
		(width 0.14224)
		(layer "In11.Cu")
		(net "P5E_CPU0_P1_RX_DP<9>")
	)
	(segment
		(start 347.83268 -392.46556)
		(end 347.83268 -387.82498)
		(width 0.14224)
		(layer "In11.Cu")
		(net "P5E_CPU0_P1_RX_DP<9>")
	)
	(segment
		(start 353.754182 -285.766256)
		(end 353.723956 -285.74873)
		(width 0.1143)
		(layer "In11.Cu")
		(net "P5E_CPU0_P1_RX_DP<9>")
	)
	(segment
		(start 370.811806 -354.956872)
		(end 373.539512 -348.371668)
		(width 0.14224)
		(layer "In11.Cu")
		(net "P5E_CPU0_P1_RX_DP<9>")
	)
	(segment
		(start 348.118938 -381.371602)
		(end 349.013526 -380.477014)
		(width 0.14224)
		(layer "In11.Cu")
		(net "P5E_CPU0_P1_RX_DP<9>")
	)
	(segment
		(start 347.876114 -393.428982)
		(end 347.560138 -393.113006)
		(width 0.14224)
		(layer "In11.Cu")
		(net "P5E_CPU0_P1_RX_DP<9>")
	)
	(segment
		(start 353.763072 -282.531566)
		(end 353.693476 -282.490926)
		(width 0.1143)
		(layer "In11.Cu")
		(net "P5E_CPU0_P1_RX_DP<9>")
	)
	(segment
		(start 347.560138 -393.113006)
		(end 347.563186 -392.7348)
		(width 0.14224)
		(layer "In11.Cu")
		(net "P5E_CPU0_P1_RX_DP<9>")
	)
	(segment
		(start 353.193858 -296.37101)
		(end 353.193858 -296.342562)
		(width 0.1143)
		(layer "In11.Cu")
		(net "P5E_CPU0_P1_RX_DP<9>")
	)
	(segment
		(start 353.148138 -296.296842)
		(end 353.148138 -295.790874)
		(width 0.1143)
		(layer "In11.Cu")
		(net "P5E_CPU0_P1_RX_DP<9>")
	)
	(segment
		(start 353.193858 -298.314364)
		(end 353.193858 -296.37101)
		(width 0.14224)
		(layer "In11.Cu")
		(net "P5E_CPU0_P1_RX_DP<9>")
	)
	(segment
		(start 353.763072 -284.151578)
		(end 353.693476 -284.110938)
		(width 0.1143)
		(layer "In11.Cu")
		(net "P5E_CPU0_P1_RX_DP<9>")
	)
	(segment
		(start 355.023166 -276.516084)
		(end 355.321108 -276.516084)
		(width 0.1143)
		(layer "In11.Cu")
		(net "P5E_CPU0_P1_RX_DP<9>")
	)
	(segment
		(start 353.254056 -279.433528)
		(end 353.255072 -279.43302)
		(width 0.1143)
		(layer "In11.Cu")
		(net "P5E_CPU0_P1_RX_DP<9>")
	)
	(segment
		(start 353.2251 -280.058622)
		(end 353.223576 -280.060908)
		(width 0.1143)
		(layer "In11.Cu")
		(net "P5E_CPU0_P1_RX_DP<9>")
	)
	(segment
		(start 353.693476 -283.501338)
		(end 353.763072 -283.460698)
		(width 0.1143)
		(layer "In11.Cu")
		(net "P5E_CPU0_P1_RX_DP<9>")
	)
	(segment
		(start 354.193348 -277.814024)
		(end 354.19411 -277.813516)
		(width 0.1143)
		(layer "In11.Cu")
		(net "P5E_CPU0_P1_RX_DP<9>")
	)
	(segment
		(start 353.693476 -278.641302)
		(end 353.763072 -278.600662)
		(width 0.1143)
		(layer "In11.Cu")
		(net "P5E_CPU0_P1_RX_DP<9>")
	)
	(segment
		(start 353.763072 -285.77159)
		(end 353.754944 -285.766764)
		(width 0.1143)
		(layer "In11.Cu")
		(net "P5E_CPU0_P1_RX_DP<9>")
	)
	(segment
		(start 354.184712 -277.81885)
		(end 354.186236 -277.818088)
		(width 0.1143)
		(layer "In11.Cu")
		(net "P5E_CPU0_P1_RX_DP<9>")
	)
	(segment
		(start 347.518736 -394.385292)
		(end 347.613732 -394.031216)
		(width 0.14224)
		(layer "In11.Cu")
		(net "P5E_CPU0_P1_RX_DP<9>")
	)
	(segment
		(start 353.693476 -291.601144)
		(end 353.763072 -291.560504)
		(width 0.1143)
		(layer "In11.Cu")
		(net "P5E_CPU0_P1_RX_DP<9>")
	)
	(segment
		(start 353.2886 -280.099516)
		(end 353.2251 -280.058622)
		(width 0.1143)
		(layer "In11.Cu")
		(net "P5E_CPU0_P1_RX_DP<9>")
	)
	(segment
		(start 353.693476 -289.981132)
		(end 353.763072 -289.940492)
		(width 0.1143)
		(layer "In11.Cu")
		(net "P5E_CPU0_P1_RX_DP<9>")
	)
	(segment
		(start 349.133414 -380.187708)
		(end 349.133414 -376.747278)
		(width 0.14224)
		(layer "In11.Cu")
		(net "P5E_CPU0_P1_RX_DP<9>")
	)
	(segment
		(start 347.876114 -393.842494)
		(end 347.876114 -393.428982)
		(width 0.14224)
		(layer "In11.Cu")
		(net "P5E_CPU0_P1_RX_DP<9>")
	)
	(segment
		(start 353.691444 -286.742378)
		(end 353.723956 -286.723582)
		(width 0.1143)
		(layer "In11.Cu")
		(net "P5E_CPU0_P1_RX_DP<9>")
	)
	(segment
		(start 353.223576 -279.451308)
		(end 353.253294 -279.434036)
		(width 0.1143)
		(layer "In11.Cu")
		(net "P5E_CPU0_P1_RX_DP<9>")
	)
	(segment
		(start 353.693476 -293.221156)
		(end 353.763072 -293.180516)
		(width 0.1143)
		(layer "In11.Cu")
		(net "P5E_CPU0_P1_RX_DP<9>")
	)
	(segment
		(start 373.539512 -339.524848)
		(end 373.535194 -339.52053)
		(width 0.14224)
		(layer "In11.Cu")
		(net "P5E_CPU0_P1_RX_DP<9>")
	)
	(segment
		(start 354.19665 -277.811992)
		(end 354.233226 -277.790656)
		(width 0.1143)
		(layer "In11.Cu")
		(net "P5E_CPU0_P1_RX_DP<9>")
	)
	(segment
		(start 354.187506 -277.817326)
		(end 354.188268 -277.816818)
		(width 0.1143)
		(layer "In11.Cu")
		(net "P5E_CPU0_P1_RX_DP<9>")
	)
	(segment
		(start 353.693476 -281.881326)
		(end 353.763072 -281.840686)
		(width 0.1143)
		(layer "In11.Cu")
		(net "P5E_CPU0_P1_RX_DP<9>")
	)
	(segment
		(start 353.691444 -288.36239)
		(end 353.723956 -288.343594)
		(width 0.1143)
		(layer "In11.Cu")
		(net "P5E_CPU0_P1_RX_DP<9>")
	)
	(segment
		(start 353.763072 -290.631372)
		(end 353.693476 -290.590732)
		(width 0.1143)
		(layer "In11.Cu")
		(net "P5E_CPU0_P1_RX_DP<9>")
	)
	(segment
		(start 371.351556 -327.369424)
		(end 369.11407 -323.088762)
		(width 0.14224)
		(layer "In11.Cu")
		(net "P5E_CPU0_P1_RX_DP<9>")
	)
	(segment
		(start 354.940362 -276.598888)
		(end 355.023166 -276.516084)
		(width 0.1143)
		(layer "In11.Cu")
		(net "P5E_CPU0_P1_RX_DP<9>")
	)
	(segment
		(start 353.193858 -296.342562)
		(end 353.148138 -296.296842)
		(width 0.1143)
		(layer "In11.Cu")
		(net "P5E_CPU0_P1_RX_DP<9>")
	)
	(segment
		(start 349.485204 -375.897902)
		(end 350.163638 -375.219468)
		(width 0.14224)
		(layer "In11.Cu")
		(net "P5E_CPU0_P1_RX_DP<9>")
	)
	(segment
		(start 353.256596 -279.432004)
		(end 353.293172 -279.410668)
		(width 0.1143)
		(layer "In11.Cu")
		(net "P5E_CPU0_P1_RX_DP<9>")
	)
	(segment
		(start 353.253294 -279.434036)
		(end 353.254056 -279.433528)
		(width 0.1143)
		(layer "In11.Cu")
		(net "P5E_CPU0_P1_RX_DP<9>")
	)
	(segment
		(start 353.723956 -285.74873)
		(end 353.693476 -285.73095)
		(width 0.1143)
		(layer "In11.Cu")
		(net "P5E_CPU0_P1_RX_DP<9>")
	)
	(segment
		(start 357.897684 -370.198904)
		(end 366.124236 -361.972352)
		(width 0.14224)
		(layer "In11.Cu")
		(net "P5E_CPU0_P1_RX_DP<9>")
	)
	(segment
		(start 356.33279 -305.892454)
		(end 353.193858 -298.314364)
		(width 0.14224)
		(layer "In11.Cu")
		(net "P5E_CPU0_P1_RX_DP<9>")
	)
	(segment
		(start 354.19411 -277.813516)
		(end 354.195126 -277.813008)
		(width 0.1143)
		(layer "In11.Cu")
		(net "P5E_CPU0_P1_RX_DP<9>")
	)
	(segment
		(start 354.16236 -277.831804)
		(end 354.184712 -277.81885)
		(width 0.1143)
		(layer "In11.Cu")
		(net "P5E_CPU0_P1_RX_DP<9>")
	)
	(segment
		(start 353.723956 -286.723582)
		(end 353.763072 -286.700722)
		(width 0.1143)
		(layer "In11.Cu")
		(net "P5E_CPU0_P1_RX_DP<9>")
	)
	(segment
		(start 347.83268 -387.82498)
		(end 348.0816 -382.757426)
		(width 0.14224)
		(layer "In11.Cu")
		(net "P5E_CPU0_P1_RX_DP<9>")
	)
	(segment
		(start 353.693476 -294.841168)
		(end 353.763072 -294.800528)
		(width 0.1143)
		(layer "In11.Cu")
		(net "P5E_CPU0_P1_RX_DP<9>")
	)
	(segment
		(start 353.148138 -295.790874)
		(end 353.536504 -295.402508)
		(width 0.1143)
		(layer "In11.Cu")
		(net "P5E_CPU0_P1_RX_DP<9>")
	)
	(segment
		(start 354.188268 -277.816818)
		(end 354.189792 -277.816056)
		(width 0.1143)
		(layer "In11.Cu")
		(net "P5E_CPU0_P1_RX_DP<9>")
	)
	(arc
		(start 353.763072 -289.940492)
		(mid 354.006399 -289.475926)
		(end 353.763072 -289.01136)
		(width 0.1143)
		(layer "In11.Cu")
		(net "P5E_CPU0_P1_RX_DP<9>")
	)
	(arc
		(start 354.476558 -277.32609)
		(mid 354.518107 -277.154668)
		(end 354.63353 -277.02129)
		(width 0.1143)
		(layer "In11.Cu")
		(net "P5E_CPU0_P1_RX_DP<9>")
	)
	(arc
		(start 353.293172 -279.410668)
		(mid 353.471985 -279.208318)
		(end 353.536504 -278.946102)
		(width 0.1143)
		(layer "In11.Cu")
		(net "P5E_CPU0_P1_RX_DP<9>")
	)
	(arc
		(start 353.536504 -295.145968)
		(mid 353.578053 -294.974546)
		(end 353.693476 -294.841168)
		(width 0.1143)
		(layer "In11.Cu")
		(net "P5E_CPU0_P1_RX_DP<9>")
	)
	(arc
		(start 351.493836 -374.477534)
		(mid 354.906529 -372.653675)
		(end 357.897684 -370.198904)
		(width 0.14224)
		(layer "In11.Cu")
		(net "P5E_CPU0_P1_RX_DP<9>")
	)
	(arc
		(start 349.133414 -376.747278)
		(mid 349.224847 -376.287612)
		(end 349.485204 -375.897902)
		(width 0.14224)
		(layer "In11.Cu")
		(net "P5E_CPU0_P1_RX_DP<9>")
	)
	(arc
		(start 353.536504 -278.946102)
		(mid 353.578053 -278.77468)
		(end 353.693476 -278.641302)
		(width 0.1143)
		(layer "In11.Cu")
		(net "P5E_CPU0_P1_RX_DP<9>")
	)
	(arc
		(start 354.006404 -278.136096)
		(mid 354.047659 -277.965125)
		(end 354.16236 -277.831804)
		(width 0.1143)
		(layer "In11.Cu")
		(net "P5E_CPU0_P1_RX_DP<9>")
	)
	(arc
		(start 353.763072 -285.08071)
		(mid 354.006399 -284.616144)
		(end 353.763072 -284.151578)
		(width 0.1143)
		(layer "In11.Cu")
		(net "P5E_CPU0_P1_RX_DP<9>")
	)
	(arc
		(start 353.763072 -293.180516)
		(mid 354.006399 -292.71595)
		(end 353.763072 -292.251384)
		(width 0.1143)
		(layer "In11.Cu")
		(net "P5E_CPU0_P1_RX_DP<9>")
	)
	(arc
		(start 353.693476 -292.210744)
		(mid 353.536499 -291.905944)
		(end 353.693476 -291.601144)
		(width 0.1143)
		(layer "In11.Cu")
		(net "P5E_CPU0_P1_RX_DP<9>")
	)
	(arc
		(start 354.703126 -276.98065)
		(mid 354.855113 -276.824142)
		(end 354.936552 -276.621748)
		(width 0.1143)
		(layer "In11.Cu")
		(net "P5E_CPU0_P1_RX_DP<9>")
	)
	(arc
		(start 353.536504 -288.66592)
		(mid 353.57747 -288.495514)
		(end 353.691444 -288.36239)
		(width 0.1143)
		(layer "In11.Cu")
		(net "P5E_CPU0_P1_RX_DP<9>")
	)
	(arc
		(start 353.763072 -283.460698)
		(mid 354.006399 -282.996132)
		(end 353.763072 -282.531566)
		(width 0.1143)
		(layer "In11.Cu")
		(net "P5E_CPU0_P1_RX_DP<9>")
	)
	(arc
		(start 353.693476 -288.97072)
		(mid 353.578049 -288.837344)
		(end 353.536504 -288.66592)
		(width 0.1143)
		(layer "In11.Cu")
		(net "P5E_CPU0_P1_RX_DP<9>")
	)
	(arc
		(start 353.223576 -280.060908)
		(mid 353.078312 -279.756108)
		(end 353.223576 -279.451308)
		(width 0.1143)
		(layer "In11.Cu")
		(net "P5E_CPU0_P1_RX_DP<9>")
	)
	(arc
		(start 353.536504 -287.045908)
		(mid 353.57747 -286.875502)
		(end 353.691444 -286.742378)
		(width 0.1143)
		(layer "In11.Cu")
		(net "P5E_CPU0_P1_RX_DP<9>")
	)
	(arc
		(start 353.693476 -284.110938)
		(mid 353.536499 -283.806138)
		(end 353.693476 -283.501338)
		(width 0.1143)
		(layer "In11.Cu")
		(net "P5E_CPU0_P1_RX_DP<9>")
	)
	(arc
		(start 353.693476 -293.830756)
		(mid 353.536499 -293.525956)
		(end 353.693476 -293.221156)
		(width 0.1143)
		(layer "In11.Cu")
		(net "P5E_CPU0_P1_RX_DP<9>")
	)
	(arc
		(start 349.013526 -380.477014)
		(mid 349.10227 -380.344294)
		(end 349.133414 -380.187708)
		(width 0.14224)
		(layer "In11.Cu")
		(net "P5E_CPU0_P1_RX_DP<9>")
	)
	(arc
		(start 350.163638 -375.219468)
		(mid 350.514927 -374.931093)
		(end 350.915732 -374.716802)
		(width 0.14224)
		(layer "In11.Cu")
		(net "P5E_CPU0_P1_RX_DP<9>")
	)
	(arc
		(start 354.006404 -287.856168)
		(mid 353.941168 -287.592577)
		(end 353.760532 -287.389824)
		(width 0.1143)
		(layer "In11.Cu")
		(net "P5E_CPU0_P1_RX_DP<9>")
	)
	(arc
		(start 353.536504 -280.520394)
		(mid 353.481946 -280.298745)
		(end 353.330764 -280.12771)
		(width 0.1143)
		(layer "In11.Cu")
		(net "P5E_CPU0_P1_RX_DP<9>")
	)
	(arc
		(start 353.693476 -282.490926)
		(mid 353.536499 -282.186126)
		(end 353.693476 -281.881326)
		(width 0.1143)
		(layer "In11.Cu")
		(net "P5E_CPU0_P1_RX_DP<9>")
	)
	(arc
		(start 353.693476 -285.73095)
		(mid 353.536499 -285.42615)
		(end 353.693476 -285.12135)
		(width 0.1143)
		(layer "In11.Cu")
		(net "P5E_CPU0_P1_RX_DP<9>")
	)
	(arc
		(start 353.763072 -286.700722)
		(mid 354.006399 -286.236156)
		(end 353.763072 -285.77159)
		(width 0.1143)
		(layer "In11.Cu")
		(net "P5E_CPU0_P1_RX_DP<9>")
	)
	(arc
		(start 353.763072 -291.560504)
		(mid 354.006399 -291.095938)
		(end 353.763072 -290.631372)
		(width 0.1143)
		(layer "In11.Cu")
		(net "P5E_CPU0_P1_RX_DP<9>")
	)
	(arc
		(start 353.693476 -280.870914)
		(mid 353.578049 -280.737538)
		(end 353.536504 -280.566114)
		(width 0.1143)
		(layer "In11.Cu")
		(net "P5E_CPU0_P1_RX_DP<9>")
	)
	(arc
		(start 353.693476 -290.590732)
		(mid 353.536499 -290.285932)
		(end 353.693476 -289.981132)
		(width 0.1143)
		(layer "In11.Cu")
		(net "P5E_CPU0_P1_RX_DP<9>")
	)
	(arc
		(start 353.763072 -278.600662)
		(mid 353.941885 -278.398312)
		(end 354.006404 -278.136096)
		(width 0.1143)
		(layer "In11.Cu")
		(net "P5E_CPU0_P1_RX_DP<9>")
	)
	(arc
		(start 353.693476 -287.350708)
		(mid 353.578049 -287.217332)
		(end 353.536504 -287.045908)
		(width 0.1143)
		(layer "In11.Cu")
		(net "P5E_CPU0_P1_RX_DP<9>")
	)
	(arc
		(start 353.763072 -281.840686)
		(mid 354.006399 -281.37612)
		(end 353.763072 -280.911554)
		(width 0.1143)
		(layer "In11.Cu")
		(net "P5E_CPU0_P1_RX_DP<9>")
	)
	(arc
		(start 354.233226 -277.790656)
		(mid 354.412039 -277.588306)
		(end 354.476558 -277.32609)
		(width 0.1143)
		(layer "In11.Cu")
		(net "P5E_CPU0_P1_RX_DP<9>")
	)
	(arc
		(start 348.0816 -381.461772)
		(mid 348.091306 -381.412977)
		(end 348.118938 -381.371602)
		(width 0.14224)
		(layer "In11.Cu")
		(net "P5E_CPU0_P1_RX_DP<9>")
	)
	(arc
		(start 353.763072 -288.320734)
		(mid 353.941885 -288.118384)
		(end 354.006404 -287.856168)
		(width 0.1143)
		(layer "In11.Cu")
		(net "P5E_CPU0_P1_RX_DP<9>")
	)
	(arc
		(start 353.763072 -294.800528)
		(mid 354.006399 -294.335962)
		(end 353.763072 -293.871396)
		(width 0.1143)
		(layer "In11.Cu")
		(net "P5E_CPU0_P1_RX_DP<9>")
	)
	(arc
		(start 366.124236 -361.972352)
		(mid 368.813513 -358.69546)
		(end 370.811806 -354.956872)
		(width 0.14224)
		(layer "In11.Cu")
		(net "P5E_CPU0_P1_RX_DP<9>")
	)
	(arc
		(start 354.936552 -276.621748)
		(mid 354.938575 -276.610338)
		(end 354.940362 -276.598888)
		(width 0.1143)
		(layer "In11.Cu")
		(net "P5E_CPU0_P1_RX_DP<9>")
	)
	(segment
		(start 345.79814 -394.385292)
		(end 346.31884 -394.385292)
		(width 0.127)
		(layer "F.Cu")
		(net "P5E_CPU0_P1_RX_DP<8>")
	)
	(segment
		(start 352.968052 -274.630134)
		(end 352.5012 -274.896072)
		(width 0.12954)
		(layer "F.Cu")
		(net "P5E_CPU0_P1_RX_DP<8>")
	)
	(segment
		(start 352.784156 -287.368488)
		(end 352.783394 -287.36798)
		(width 0.1143)
		(layer "In11.Cu")
		(net "P5E_CPU0_P1_RX_DP<8>")
	)
	(segment
		(start 352.784156 -292.228524)
		(end 352.783394 -292.228016)
		(width 0.1143)
		(layer "In11.Cu")
		(net "P5E_CPU0_P1_RX_DP<8>")
	)
	(segment
		(start 352.784156 -291.583364)
		(end 352.820478 -291.562282)
		(width 0.1143)
		(layer "In11.Cu")
		(net "P5E_CPU0_P1_RX_DP<8>")
	)
	(segment
		(start 352.776282 -291.587936)
		(end 352.777552 -291.587174)
		(width 0.1143)
		(layer "In11.Cu")
		(net "P5E_CPU0_P1_RX_DP<8>")
	)
	(segment
		(start 352.752406 -283.501846)
		(end 352.820478 -283.462476)
		(width 0.1143)
		(layer "In11.Cu")
		(net "P5E_CPU0_P1_RX_DP<8>")
	)
	(segment
		(start 372.597934 -348.079314)
		(end 372.597934 -339.649308)
		(width 0.14224)
		(layer "In11.Cu")
		(net "P5E_CPU0_P1_RX_DP<8>")
	)
	(segment
		(start 352.784664 -287.36925)
		(end 352.783902 -287.368742)
		(width 0.1143)
		(layer "In11.Cu")
		(net "P5E_CPU0_P1_RX_DP<8>")
	)
	(segment
		(start 370.439696 -327.637648)
		(end 368.332004 -323.605652)
		(width 0.14224)
		(layer "In11.Cu")
		(net "P5E_CPU0_P1_RX_DP<8>")
	)
	(segment
		(start 352.820478 -289.009582)
		(end 352.784156 -288.9885)
		(width 0.1143)
		(layer "In11.Cu")
		(net "P5E_CPU0_P1_RX_DP<8>")
	)
	(segment
		(start 349.09252 -374.39727)
		(end 351.090992 -373.569484)
		(width 0.14224)
		(layer "In11.Cu")
		(net "P5E_CPU0_P1_RX_DP<8>")
	)
	(segment
		(start 346.360242 -393.113006)
		(end 346.36329 -392.734546)
		(width 0.14224)
		(layer "In11.Cu")
		(net "P5E_CPU0_P1_RX_DP<8>")
	)
	(segment
		(start 352.783394 -289.96386)
		(end 352.784156 -289.963352)
		(width 0.1143)
		(layer "In11.Cu")
		(net "P5E_CPU0_P1_RX_DP<8>")
	)
	(segment
		(start 368.332004 -323.605652)
		(end 361.418632 -315.181996)
		(width 0.14224)
		(layer "In11.Cu")
		(net "P5E_CPU0_P1_RX_DP<8>")
	)
	(segment
		(start 352.777552 -291.587174)
		(end 352.778314 -291.586666)
		(width 0.1143)
		(layer "In11.Cu")
		(net "P5E_CPU0_P1_RX_DP<8>")
	)
	(segment
		(start 370.329206 -353.55657)
		(end 372.597934 -348.079314)
		(width 0.14224)
		(layer "In11.Cu")
		(net "P5E_CPU0_P1_RX_DP<8>")
	)
	(segment
		(start 352.783394 -288.987992)
		(end 352.782124 -288.98723)
		(width 0.1143)
		(layer "In11.Cu")
		(net "P5E_CPU0_P1_RX_DP<8>")
	)
	(segment
		(start 352.783394 -287.36798)
		(end 352.782124 -287.367218)
		(width 0.1143)
		(layer "In11.Cu")
		(net "P5E_CPU0_P1_RX_DP<8>")
	)
	(segment
		(start 352.752406 -289.98164)
		(end 352.77298 -289.969702)
		(width 0.1143)
		(layer "In11.Cu")
		(net "P5E_CPU0_P1_RX_DP<8>")
	)
	(segment
		(start 346.803218 -381.198882)
		(end 347.22816 -380.77394)
		(width 0.14224)
		(layer "In11.Cu")
		(net "P5E_CPU0_P1_RX_DP<8>")
	)
	(segment
		(start 352.203004 -295.872408)
		(end 352.59645 -295.478962)
		(width 0.1143)
		(layer "In11.Cu")
		(net "P5E_CPU0_P1_RX_DP<8>")
	)
	(segment
		(start 352.783394 -292.228016)
		(end 352.782124 -292.227254)
		(width 0.1143)
		(layer "In11.Cu")
		(net "P5E_CPU0_P1_RX_DP<8>")
	)
	(segment
		(start 352.783394 -291.583872)
		(end 352.784156 -291.583364)
		(width 0.1143)
		(layer "In11.Cu")
		(net "P5E_CPU0_P1_RX_DP<8>")
	)
	(segment
		(start 352.248724 -296.37101)
		(end 352.248724 -296.342562)
		(width 0.1143)
		(layer "In11.Cu")
		(net "P5E_CPU0_P1_RX_DP<8>")
	)
	(segment
		(start 352.823272 -294.800782)
		(end 352.83267 -294.793924)
		(width 0.1143)
		(layer "In11.Cu")
		(net "P5E_CPU0_P1_RX_DP<8>")
	)
	(segment
		(start 352.83267 -293.878)
		(end 352.823272 -293.871142)
		(width 0.1143)
		(layer "In11.Cu")
		(net "P5E_CPU0_P1_RX_DP<8>")
	)
	(segment
		(start 352.820478 -280.909776)
		(end 352.752406 -280.870406)
		(width 0.1143)
		(layer "In11.Cu")
		(net "P5E_CPU0_P1_RX_DP<8>")
	)
	(segment
		(start 352.783394 -290.608004)
		(end 352.782124 -290.607242)
		(width 0.1143)
		(layer "In11.Cu")
		(net "P5E_CPU0_P1_RX_DP<8>")
	)
	(segment
		(start 352.353118 -280.101548)
		(end 352.283522 -280.060908)
		(width 0.1143)
		(layer "In11.Cu")
		(net "P5E_CPU0_P1_RX_DP<8>")
	)
	(segment
		(start 352.783902 -287.368742)
		(end 352.784156 -287.368488)
		(width 0.1143)
		(layer "In11.Cu")
		(net "P5E_CPU0_P1_RX_DP<8>")
	)
	(segment
		(start 352.820478 -282.529788)
		(end 352.752406 -282.490418)
		(width 0.1143)
		(layer "In11.Cu")
		(net "P5E_CPU0_P1_RX_DP<8>")
	)
	(segment
		(start 352.784156 -288.9885)
		(end 352.783394 -288.987992)
		(width 0.1143)
		(layer "In11.Cu")
		(net "P5E_CPU0_P1_RX_DP<8>")
	)
	(segment
		(start 352.782124 -287.367218)
		(end 352.7806 -287.366456)
		(width 0.1143)
		(layer "In11.Cu")
		(net "P5E_CPU0_P1_RX_DP<8>")
	)
	(segment
		(start 346.66809 -392.429746)
		(end 346.66809 -385.959604)
		(width 0.14224)
		(layer "In11.Cu")
		(net "P5E_CPU0_P1_RX_DP<8>")
	)
	(segment
		(start 357.28783 -369.428776)
		(end 364.629446 -362.08716)
		(width 0.14224)
		(layer "In11.Cu")
		(net "P5E_CPU0_P1_RX_DP<8>")
	)
	(segment
		(start 352.784156 -293.203376)
		(end 352.820478 -293.182294)
		(width 0.1143)
		(layer "In11.Cu")
		(net "P5E_CPU0_P1_RX_DP<8>")
	)
	(segment
		(start 352.777552 -289.967162)
		(end 352.778314 -289.966654)
		(width 0.1143)
		(layer "In11.Cu")
		(net "P5E_CPU0_P1_RX_DP<8>")
	)
	(segment
		(start 352.820478 -276.04974)
		(end 352.752406 -276.01037)
		(width 0.1143)
		(layer "In11.Cu")
		(net "P5E_CPU0_P1_RX_DP<8>")
	)
	(segment
		(start 352.774758 -293.20871)
		(end 352.776282 -293.207948)
		(width 0.1143)
		(layer "In11.Cu")
		(net "P5E_CPU0_P1_RX_DP<8>")
	)
	(segment
		(start 352.7806 -289.965384)
		(end 352.783394 -289.96386)
		(width 0.1143)
		(layer "In11.Cu")
		(net "P5E_CPU0_P1_RX_DP<8>")
	)
	(segment
		(start 346.31884 -394.385292)
		(end 346.413836 -394.031216)
		(width 0.14224)
		(layer "In11.Cu")
		(net "P5E_CPU0_P1_RX_DP<8>")
	)
	(segment
		(start 352.248724 -296.342562)
		(end 352.203004 -296.296842)
		(width 0.1143)
		(layer "In11.Cu")
		(net "P5E_CPU0_P1_RX_DP<8>")
	)
	(segment
		(start 352.776282 -293.207948)
		(end 352.777552 -293.207186)
		(width 0.1143)
		(layer "In11.Cu")
		(net "P5E_CPU0_P1_RX_DP<8>")
	)
	(segment
		(start 352.7806 -286.725614)
		(end 352.813874 -286.70631)
		(width 0.1143)
		(layer "In11.Cu")
		(net "P5E_CPU0_P1_RX_DP<8>")
	)
	(segment
		(start 346.66809 -385.959604)
		(end 346.76588 -383.967482)
		(width 0.14224)
		(layer "In11.Cu")
		(net "P5E_CPU0_P1_RX_DP<8>")
	)
	(segment
		(start 352.820478 -292.249606)
		(end 352.784156 -292.228524)
		(width 0.1143)
		(layer "In11.Cu")
		(net "P5E_CPU0_P1_RX_DP<8>")
	)
	(segment
		(start 352.248724 -298.46905)
		(end 352.248724 -296.37101)
		(width 0.14224)
		(layer "In11.Cu")
		(net "P5E_CPU0_P1_RX_DP<8>")
	)
	(segment
		(start 346.676218 -393.428982)
		(end 346.360242 -393.113006)
		(width 0.14224)
		(layer "In11.Cu")
		(net "P5E_CPU0_P1_RX_DP<8>")
	)
	(segment
		(start 352.778314 -291.586666)
		(end 352.779838 -291.585904)
		(width 0.1143)
		(layer "In11.Cu")
		(net "P5E_CPU0_P1_RX_DP<8>")
	)
	(segment
		(start 352.752406 -294.84193)
		(end 352.823272 -294.800782)
		(width 0.1143)
		(layer "In11.Cu")
		(net "P5E_CPU0_P1_RX_DP<8>")
	)
	(segment
		(start 352.774758 -291.588698)
		(end 352.776282 -291.587936)
		(width 0.1143)
		(layer "In11.Cu")
		(net "P5E_CPU0_P1_RX_DP<8>")
	)
	(segment
		(start 352.773996 -289.969194)
		(end 352.774758 -289.968686)
		(width 0.1143)
		(layer "In11.Cu")
		(net "P5E_CPU0_P1_RX_DP<8>")
	)
	(segment
		(start 352.779838 -289.965892)
		(end 352.7806 -289.965384)
		(width 0.1143)
		(layer "In11.Cu")
		(net "P5E_CPU0_P1_RX_DP<8>")
	)
	(segment
		(start 347.431614 -380.282958)
		(end 347.431614 -379.786134)
		(width 0.14224)
		(layer "In11.Cu")
		(net "P5E_CPU0_P1_RX_DP<8>")
	)
	(segment
		(start 352.752406 -291.601652)
		(end 352.77298 -291.589714)
		(width 0.1143)
		(layer "In11.Cu")
		(net "P5E_CPU0_P1_RX_DP<8>")
	)
	(segment
		(start 352.779838 -293.205916)
		(end 352.7806 -293.205408)
		(width 0.1143)
		(layer "In11.Cu")
		(net "P5E_CPU0_P1_RX_DP<8>")
	)
	(segment
		(start 352.752406 -281.881834)
		(end 352.820478 -281.842464)
		(width 0.1143)
		(layer "In11.Cu")
		(net "P5E_CPU0_P1_RX_DP<8>")
	)
	(segment
		(start 352.77298 -289.969702)
		(end 352.773996 -289.969194)
		(width 0.1143)
		(layer "In11.Cu")
		(net "P5E_CPU0_P1_RX_DP<8>")
	)
	(segment
		(start 352.820478 -290.629594)
		(end 352.784156 -290.608512)
		(width 0.1143)
		(layer "In11.Cu")
		(net "P5E_CPU0_P1_RX_DP<8>")
	)
	(segment
		(start 346.36329 -392.734546)
		(end 346.66809 -392.429746)
		(width 0.14224)
		(layer "In11.Cu")
		(net "P5E_CPU0_P1_RX_DP<8>")
	)
	(segment
		(start 352.752406 -277.021798)
		(end 352.820478 -276.982428)
		(width 0.1143)
		(layer "In11.Cu")
		(net "P5E_CPU0_P1_RX_DP<8>")
	)
	(segment
		(start 352.773996 -293.209218)
		(end 352.774758 -293.20871)
		(width 0.1143)
		(layer "In11.Cu")
		(net "P5E_CPU0_P1_RX_DP<8>")
	)
	(segment
		(start 352.203004 -296.296842)
		(end 352.203004 -295.872408)
		(width 0.1143)
		(layer "In11.Cu")
		(net "P5E_CPU0_P1_RX_DP<8>")
	)
	(segment
		(start 352.782124 -288.98723)
		(end 352.752406 -288.970212)
		(width 0.1143)
		(layer "In11.Cu")
		(net "P5E_CPU0_P1_RX_DP<8>")
	)
	(segment
		(start 346.76588 -383.967482)
		(end 346.76588 -381.289052)
		(width 0.14224)
		(layer "In11.Cu")
		(net "P5E_CPU0_P1_RX_DP<8>")
	)
	(segment
		(start 352.59645 -295.478962)
		(end 352.59645 -295.145968)
		(width 0.1143)
		(layer "In11.Cu")
		(net "P5E_CPU0_P1_RX_DP<8>")
	)
	(segment
		(start 352.752406 -285.121858)
		(end 352.820478 -285.082488)
		(width 0.1143)
		(layer "In11.Cu")
		(net "P5E_CPU0_P1_RX_DP<8>")
	)
	(segment
		(start 352.752406 -278.64181)
		(end 352.820478 -278.60244)
		(width 0.1143)
		(layer "In11.Cu")
		(net "P5E_CPU0_P1_RX_DP<8>")
	)
	(segment
		(start 346.413836 -394.031216)
		(end 346.58808 -393.930632)
		(width 0.14224)
		(layer "In11.Cu")
		(net "P5E_CPU0_P1_RX_DP<8>")
	)
	(segment
		(start 352.777552 -293.207186)
		(end 352.778314 -293.206678)
		(width 0.1143)
		(layer "In11.Cu")
		(net "P5E_CPU0_P1_RX_DP<8>")
	)
	(segment
		(start 352.752406 -293.221664)
		(end 352.77298 -293.209726)
		(width 0.1143)
		(layer "In11.Cu")
		(net "P5E_CPU0_P1_RX_DP<8>")
	)
	(segment
		(start 345.731592 -377.991116)
		(end 345.731592 -377.086876)
		(width 0.14224)
		(layer "In11.Cu")
		(net "P5E_CPU0_P1_RX_DP<8>")
	)
	(segment
		(start 352.814636 -286.705802)
		(end 352.820478 -286.7025)
		(width 0.1143)
		(layer "In11.Cu")
		(net "P5E_CPU0_P1_RX_DP<8>")
	)
	(segment
		(start 352.782124 -292.227254)
		(end 352.752406 -292.210236)
		(width 0.1143)
		(layer "In11.Cu")
		(net "P5E_CPU0_P1_RX_DP<8>")
	)
	(segment
		(start 345.92006 -376.631962)
		(end 346.266008 -376.286014)
		(width 0.14224)
		(layer "In11.Cu")
		(net "P5E_CPU0_P1_RX_DP<8>")
	)
	(segment
		(start 352.813874 -286.70631)
		(end 352.814636 -286.705802)
		(width 0.1143)
		(layer "In11.Cu")
		(net "P5E_CPU0_P1_RX_DP<8>")
	)
	(segment
		(start 352.77298 -293.209726)
		(end 352.773996 -293.209218)
		(width 0.1143)
		(layer "In11.Cu")
		(net "P5E_CPU0_P1_RX_DP<8>")
	)
	(segment
		(start 352.820478 -277.669752)
		(end 352.752406 -277.630382)
		(width 0.1143)
		(layer "In11.Cu")
		(net "P5E_CPU0_P1_RX_DP<8>")
	)
	(segment
		(start 352.778314 -289.966654)
		(end 352.779838 -289.965892)
		(width 0.1143)
		(layer "In11.Cu")
		(net "P5E_CPU0_P1_RX_DP<8>")
	)
	(segment
		(start 352.778314 -293.206678)
		(end 352.779838 -293.205916)
		(width 0.1143)
		(layer "In11.Cu")
		(net "P5E_CPU0_P1_RX_DP<8>")
	)
	(segment
		(start 352.7806 -287.366456)
		(end 352.752406 -287.3502)
		(width 0.1143)
		(layer "In11.Cu")
		(net "P5E_CPU0_P1_RX_DP<8>")
	)
	(segment
		(start 352.773996 -291.589206)
		(end 352.774758 -291.588698)
		(width 0.1143)
		(layer "In11.Cu")
		(net "P5E_CPU0_P1_RX_DP<8>")
	)
	(segment
		(start 352.7806 -293.205408)
		(end 352.783394 -293.203884)
		(width 0.1143)
		(layer "In11.Cu")
		(net "P5E_CPU0_P1_RX_DP<8>")
	)
	(segment
		(start 355.506528 -306.33416)
		(end 352.248724 -298.46905)
		(width 0.14224)
		(layer "In11.Cu")
		(net "P5E_CPU0_P1_RX_DP<8>")
	)
	(segment
		(start 352.283522 -279.451308)
		(end 352.353118 -279.410668)
		(width 0.1143)
		(layer "In11.Cu")
		(net "P5E_CPU0_P1_RX_DP<8>")
	)
	(segment
		(start 347.030548 -378.696982)
		(end 346.696538 -378.558806)
		(width 0.14224)
		(layer "In11.Cu")
		(net "P5E_CPU0_P1_RX_DP<8>")
	)
	(segment
		(start 372.597934 -339.649308)
		(end 370.439696 -327.637648)
		(width 0.14224)
		(layer "In11.Cu")
		(net "P5E_CPU0_P1_RX_DP<8>")
	)
	(segment
		(start 352.784156 -289.963352)
		(end 352.820478 -289.94227)
		(width 0.1143)
		(layer "In11.Cu")
		(net "P5E_CPU0_P1_RX_DP<8>")
	)
	(segment
		(start 345.768168 -378.084842)
		(end 345.752928 -378.061728)
		(width 0.14224)
		(layer "In11.Cu")
		(net "P5E_CPU0_P1_RX_DP<8>")
	)
	(segment
		(start 352.783394 -293.203884)
		(end 352.784156 -293.203376)
		(width 0.1143)
		(layer "In11.Cu")
		(net "P5E_CPU0_P1_RX_DP<8>")
	)
	(segment
		(start 352.353118 -275.241512)
		(end 352.283522 -275.200872)
		(width 0.1143)
		(layer "In11.Cu")
		(net "P5E_CPU0_P1_RX_DP<8>")
	)
	(segment
		(start 352.784156 -290.608512)
		(end 352.783394 -290.608004)
		(width 0.1143)
		(layer "In11.Cu")
		(net "P5E_CPU0_P1_RX_DP<8>")
	)
	(segment
		(start 352.203258 -274.896072)
		(end 352.5012 -274.896072)
		(width 0.1143)
		(layer "In11.Cu")
		(net "P5E_CPU0_P1_RX_DP<8>")
	)
	(segment
		(start 352.782124 -290.607242)
		(end 352.752406 -290.590224)
		(width 0.1143)
		(layer "In11.Cu")
		(net "P5E_CPU0_P1_RX_DP<8>")
	)
	(segment
		(start 352.820478 -284.1498)
		(end 352.752406 -284.11043)
		(width 0.1143)
		(layer "In11.Cu")
		(net "P5E_CPU0_P1_RX_DP<8>")
	)
	(segment
		(start 361.418632 -315.181996)
		(end 355.506528 -306.33416)
		(width 0.14224)
		(layer "In11.Cu")
		(net "P5E_CPU0_P1_RX_DP<8>")
	)
	(segment
		(start 346.676218 -393.842494)
		(end 346.676218 -393.428982)
		(width 0.14224)
		(layer "In11.Cu")
		(net "P5E_CPU0_P1_RX_DP<8>")
	)
	(segment
		(start 352.7806 -291.585396)
		(end 352.783394 -291.583872)
		(width 0.1143)
		(layer "In11.Cu")
		(net "P5E_CPU0_P1_RX_DP<8>")
	)
	(segment
		(start 352.133408 -274.965922)
		(end 352.203258 -274.896072)
		(width 0.1143)
		(layer "In11.Cu")
		(net "P5E_CPU0_P1_RX_DP<8>")
	)
	(segment
		(start 352.77298 -291.589714)
		(end 352.773996 -291.589206)
		(width 0.1143)
		(layer "In11.Cu")
		(net "P5E_CPU0_P1_RX_DP<8>")
	)
	(segment
		(start 352.820478 -285.769812)
		(end 352.752406 -285.730442)
		(width 0.1143)
		(layer "In11.Cu")
		(net "P5E_CPU0_P1_RX_DP<8>")
	)
	(segment
		(start 352.776282 -289.967924)
		(end 352.777552 -289.967162)
		(width 0.1143)
		(layer "In11.Cu")
		(net "P5E_CPU0_P1_RX_DP<8>")
	)
	(segment
		(start 352.750628 -288.363152)
		(end 352.820478 -288.322512)
		(width 0.1143)
		(layer "In11.Cu")
		(net "P5E_CPU0_P1_RX_DP<8>")
	)
	(segment
		(start 352.823272 -293.871142)
		(end 352.752406 -293.830248)
		(width 0.1143)
		(layer "In11.Cu")
		(net "P5E_CPU0_P1_RX_DP<8>")
	)
	(segment
		(start 346.58808 -393.930632)
		(end 346.676218 -393.842494)
		(width 0.14224)
		(layer "In11.Cu")
		(net "P5E_CPU0_P1_RX_DP<8>")
	)
	(segment
		(start 352.779838 -291.585904)
		(end 352.7806 -291.585396)
		(width 0.1143)
		(layer "In11.Cu")
		(net "P5E_CPU0_P1_RX_DP<8>")
	)
	(segment
		(start 352.774758 -289.968686)
		(end 352.776282 -289.967924)
		(width 0.1143)
		(layer "In11.Cu")
		(net "P5E_CPU0_P1_RX_DP<8>")
	)
	(arc
		(start 352.59645 -275.706078)
		(mid 352.531935 -275.443859)
		(end 352.353118 -275.241512)
		(width 0.1143)
		(layer "In11.Cu")
		(net "P5E_CPU0_P1_RX_DP<8>")
	)
	(arc
		(start 345.731592 -377.086876)
		(mid 345.780567 -376.840664)
		(end 345.92006 -376.631962)
		(width 0.14224)
		(layer "In11.Cu")
		(net "P5E_CPU0_P1_RX_DP<8>")
	)
	(arc
		(start 352.59645 -280.566114)
		(mid 352.531935 -280.303895)
		(end 352.353118 -280.101548)
		(width 0.1143)
		(layer "In11.Cu")
		(net "P5E_CPU0_P1_RX_DP<8>")
	)
	(arc
		(start 352.752406 -288.970212)
		(mid 352.63773 -288.836878)
		(end 352.59645 -288.66592)
		(width 0.1143)
		(layer "In11.Cu")
		(net "P5E_CPU0_P1_RX_DP<8>")
	)
	(arc
		(start 352.836734 -289.93084)
		(mid 353.059618 -289.475926)
		(end 352.836734 -289.021012)
		(width 0.1143)
		(layer "In11.Cu")
		(net "P5E_CPU0_P1_RX_DP<8>")
	)
	(arc
		(start 352.835718 -285.07182)
		(mid 353.060889 -284.616144)
		(end 352.835718 -284.160468)
		(width 0.1143)
		(layer "In11.Cu")
		(net "P5E_CPU0_P1_RX_DP<8>")
	)
	(arc
		(start 347.270324 -378.926344)
		(mid 347.172021 -378.789097)
		(end 347.030548 -378.696982)
		(width 0.14224)
		(layer "In11.Cu")
		(net "P5E_CPU0_P1_RX_DP<8>")
	)
	(arc
		(start 352.752406 -292.210236)
		(mid 352.596478 -291.905944)
		(end 352.752406 -291.601652)
		(width 0.1143)
		(layer "In11.Cu")
		(net "P5E_CPU0_P1_RX_DP<8>")
	)
	(arc
		(start 352.834702 -293.172388)
		(mid 353.062085 -292.71595)
		(end 352.834702 -292.259512)
		(width 0.1143)
		(layer "In11.Cu")
		(net "P5E_CPU0_P1_RX_DP<8>")
	)
	(arc
		(start 352.834702 -280.919682)
		(mid 352.827628 -280.914675)
		(end 352.820478 -280.909776)
		(width 0.1143)
		(layer "In11.Cu")
		(net "P5E_CPU0_P1_RX_DP<8>")
	)
	(arc
		(start 352.752406 -293.830248)
		(mid 352.596478 -293.525956)
		(end 352.752406 -293.221664)
		(width 0.1143)
		(layer "In11.Cu")
		(net "P5E_CPU0_P1_RX_DP<8>")
	)
	(arc
		(start 352.83267 -294.793924)
		(mid 353.066323 -294.335962)
		(end 352.83267 -293.878)
		(width 0.1143)
		(layer "In11.Cu")
		(net "P5E_CPU0_P1_RX_DP<8>")
	)
	(arc
		(start 352.752406 -282.490418)
		(mid 352.596478 -282.186126)
		(end 352.752406 -281.881834)
		(width 0.1143)
		(layer "In11.Cu")
		(net "P5E_CPU0_P1_RX_DP<8>")
	)
	(arc
		(start 352.834702 -281.832558)
		(mid 353.062085 -281.37612)
		(end 352.834702 -280.919682)
		(width 0.1143)
		(layer "In11.Cu")
		(net "P5E_CPU0_P1_RX_DP<8>")
	)
	(arc
		(start 352.283522 -280.060908)
		(mid 352.126545 -279.756108)
		(end 352.283522 -279.451308)
		(width 0.1143)
		(layer "In11.Cu")
		(net "P5E_CPU0_P1_RX_DP<8>")
	)
	(arc
		(start 352.59645 -288.66592)
		(mid 352.637212 -288.496036)
		(end 352.750628 -288.363152)
		(width 0.1143)
		(layer "In11.Cu")
		(net "P5E_CPU0_P1_RX_DP<8>")
	)
	(arc
		(start 352.834702 -283.45257)
		(mid 353.062085 -282.996132)
		(end 352.834702 -282.539694)
		(width 0.1143)
		(layer "In11.Cu")
		(net "P5E_CPU0_P1_RX_DP<8>")
	)
	(arc
		(start 346.494608 -378.513848)
		(mid 346.431326 -378.508078)
		(end 346.368878 -378.496322)
		(width 0.14224)
		(layer "In11.Cu")
		(net "P5E_CPU0_P1_RX_DP<8>")
	)
	(arc
		(start 352.835718 -284.160468)
		(mid 352.828142 -284.155072)
		(end 352.820478 -284.1498)
		(width 0.1143)
		(layer "In11.Cu")
		(net "P5E_CPU0_P1_RX_DP<8>")
	)
	(arc
		(start 346.001848 -378.340874)
		(mid 345.950793 -378.303275)
		(end 345.905074 -378.25934)
		(width 0.14224)
		(layer "In11.Cu")
		(net "P5E_CPU0_P1_RX_DP<8>")
	)
	(arc
		(start 347.431614 -379.786134)
		(mid 347.420033 -379.628875)
		(end 347.38564 -379.474984)
		(width 0.14224)
		(layer "In11.Cu")
		(net "P5E_CPU0_P1_RX_DP<8>")
	)
	(arc
		(start 346.266008 -376.286014)
		(mid 347.586256 -375.202454)
		(end 349.09252 -374.39727)
		(width 0.14224)
		(layer "In11.Cu")
		(net "P5E_CPU0_P1_RX_DP<8>")
	)
	(arc
		(start 352.752406 -284.11043)
		(mid 352.596478 -283.806138)
		(end 352.752406 -283.501846)
		(width 0.1143)
		(layer "In11.Cu")
		(net "P5E_CPU0_P1_RX_DP<8>")
	)
	(arc
		(start 352.283522 -275.200872)
		(mid 352.185757 -275.097896)
		(end 352.133408 -274.965922)
		(width 0.1143)
		(layer "In11.Cu")
		(net "P5E_CPU0_P1_RX_DP<8>")
	)
	(arc
		(start 345.905074 -378.25934)
		(mid 345.833241 -378.174743)
		(end 345.768168 -378.084842)
		(width 0.14224)
		(layer "In11.Cu")
		(net "P5E_CPU0_P1_RX_DP<8>")
	)
	(arc
		(start 352.59645 -278.946102)
		(mid 352.637705 -278.775131)
		(end 352.752406 -278.64181)
		(width 0.1143)
		(layer "In11.Cu")
		(net "P5E_CPU0_P1_RX_DP<8>")
	)
	(arc
		(start 346.696538 -378.558806)
		(mid 346.597506 -378.527648)
		(end 346.494608 -378.513848)
		(width 0.14224)
		(layer "In11.Cu")
		(net "P5E_CPU0_P1_RX_DP<8>")
	)
	(arc
		(start 352.820478 -291.562282)
		(mid 352.827628 -291.557384)
		(end 352.834702 -291.552376)
		(width 0.1143)
		(layer "In11.Cu")
		(net "P5E_CPU0_P1_RX_DP<8>")
	)
	(arc
		(start 352.834702 -282.539694)
		(mid 352.827628 -282.534687)
		(end 352.820478 -282.529788)
		(width 0.1143)
		(layer "In11.Cu")
		(net "P5E_CPU0_P1_RX_DP<8>")
	)
	(arc
		(start 352.66249 -294.933624)
		(mid 352.703479 -294.883883)
		(end 352.752406 -294.84193)
		(width 0.1143)
		(layer "In11.Cu")
		(net "P5E_CPU0_P1_RX_DP<8>")
	)
	(arc
		(start 352.820478 -283.462476)
		(mid 352.827627 -283.457576)
		(end 352.834702 -283.45257)
		(width 0.1143)
		(layer "In11.Cu")
		(net "P5E_CPU0_P1_RX_DP<8>")
	)
	(arc
		(start 352.834702 -290.6395)
		(mid 352.827629 -290.634491)
		(end 352.820478 -290.629594)
		(width 0.1143)
		(layer "In11.Cu")
		(net "P5E_CPU0_P1_RX_DP<8>")
	)
	(arc
		(start 352.820478 -289.94227)
		(mid 352.828656 -289.936627)
		(end 352.836734 -289.93084)
		(width 0.1143)
		(layer "In11.Cu")
		(net "P5E_CPU0_P1_RX_DP<8>")
	)
	(arc
		(start 352.834702 -276.972522)
		(mid 353.062085 -276.516084)
		(end 352.834702 -276.059646)
		(width 0.1143)
		(layer "In11.Cu")
		(net "P5E_CPU0_P1_RX_DP<8>")
	)
	(arc
		(start 352.752406 -290.590224)
		(mid 352.596478 -290.285932)
		(end 352.752406 -289.98164)
		(width 0.1143)
		(layer "In11.Cu")
		(net "P5E_CPU0_P1_RX_DP<8>")
	)
	(arc
		(start 352.820478 -293.182294)
		(mid 352.827628 -293.177396)
		(end 352.834702 -293.172388)
		(width 0.1143)
		(layer "In11.Cu")
		(net "P5E_CPU0_P1_RX_DP<8>")
	)
	(arc
		(start 352.752406 -277.630382)
		(mid 352.596478 -277.32609)
		(end 352.752406 -277.021798)
		(width 0.1143)
		(layer "In11.Cu")
		(net "P5E_CPU0_P1_RX_DP<8>")
	)
	(arc
		(start 347.38564 -379.474984)
		(mid 347.369868 -379.405764)
		(end 347.363796 -379.33503)
		(width 0.14224)
		(layer "In11.Cu")
		(net "P5E_CPU0_P1_RX_DP<8>")
	)
	(arc
		(start 353.06635 -286.229552)
		(mid 353.001478 -285.97981)
		(end 352.836734 -285.781242)
		(width 0.1143)
		(layer "In11.Cu")
		(net "P5E_CPU0_P1_RX_DP<8>")
	)
	(arc
		(start 352.820478 -288.322512)
		(mid 353.00113 -288.119767)
		(end 353.06635 -287.856168)
		(width 0.1143)
		(layer "In11.Cu")
		(net "P5E_CPU0_P1_RX_DP<8>")
	)
	(arc
		(start 352.834702 -277.679658)
		(mid 352.827628 -277.674651)
		(end 352.820478 -277.669752)
		(width 0.1143)
		(layer "In11.Cu")
		(net "P5E_CPU0_P1_RX_DP<8>")
	)
	(arc
		(start 352.820478 -281.842464)
		(mid 352.827627 -281.837564)
		(end 352.834702 -281.832558)
		(width 0.1143)
		(layer "In11.Cu")
		(net "P5E_CPU0_P1_RX_DP<8>")
	)
	(arc
		(start 352.834702 -278.592534)
		(mid 353.062085 -278.136096)
		(end 352.834702 -277.679658)
		(width 0.1143)
		(layer "In11.Cu")
		(net "P5E_CPU0_P1_RX_DP<8>")
	)
	(arc
		(start 352.752406 -276.01037)
		(mid 352.63773 -275.877036)
		(end 352.59645 -275.706078)
		(width 0.1143)
		(layer "In11.Cu")
		(net "P5E_CPU0_P1_RX_DP<8>")
	)
	(arc
		(start 352.820478 -276.982428)
		(mid 352.827627 -276.977528)
		(end 352.834702 -276.972522)
		(width 0.1143)
		(layer "In11.Cu")
		(net "P5E_CPU0_P1_RX_DP<8>")
	)
	(arc
		(start 352.353118 -279.410668)
		(mid 352.531931 -279.208318)
		(end 352.59645 -278.946102)
		(width 0.1143)
		(layer "In11.Cu")
		(net "P5E_CPU0_P1_RX_DP<8>")
	)
	(arc
		(start 346.76588 -381.289052)
		(mid 346.775586 -381.240257)
		(end 346.803218 -381.198882)
		(width 0.14224)
		(layer "In11.Cu")
		(net "P5E_CPU0_P1_RX_DP<8>")
	)
	(arc
		(start 352.834702 -291.552376)
		(mid 353.062085 -291.095938)
		(end 352.834702 -290.6395)
		(width 0.1143)
		(layer "In11.Cu")
		(net "P5E_CPU0_P1_RX_DP<8>")
	)
	(arc
		(start 352.596196 -287.045908)
		(mid 352.64554 -286.861094)
		(end 352.7806 -286.725614)
		(width 0.1143)
		(layer "In11.Cu")
		(net "P5E_CPU0_P1_RX_DP<8>")
	)
	(arc
		(start 352.752406 -285.730442)
		(mid 352.596478 -285.42615)
		(end 352.752406 -285.121858)
		(width 0.1143)
		(layer "In11.Cu")
		(net "P5E_CPU0_P1_RX_DP<8>")
	)
	(arc
		(start 353.06635 -287.856168)
		(mid 352.990848 -287.574916)
		(end 352.784664 -287.36925)
		(width 0.1143)
		(layer "In11.Cu")
		(net "P5E_CPU0_P1_RX_DP<8>")
	)
	(arc
		(start 346.368878 -378.496322)
		(mid 346.178944 -378.433755)
		(end 346.001848 -378.340874)
		(width 0.14224)
		(layer "In11.Cu")
		(net "P5E_CPU0_P1_RX_DP<8>")
	)
	(arc
		(start 352.752406 -280.870406)
		(mid 352.63773 -280.737072)
		(end 352.59645 -280.566114)
		(width 0.1143)
		(layer "In11.Cu")
		(net "P5E_CPU0_P1_RX_DP<8>")
	)
	(arc
		(start 352.836734 -285.781242)
		(mid 352.828656 -285.775456)
		(end 352.820478 -285.769812)
		(width 0.1143)
		(layer "In11.Cu")
		(net "P5E_CPU0_P1_RX_DP<8>")
	)
	(arc
		(start 352.59645 -295.145968)
		(mid 352.613321 -295.034767)
		(end 352.66249 -294.933624)
		(width 0.1143)
		(layer "In11.Cu")
		(net "P5E_CPU0_P1_RX_DP<8>")
	)
	(arc
		(start 352.820478 -285.082488)
		(mid 352.828142 -285.077217)
		(end 352.835718 -285.07182)
		(width 0.1143)
		(layer "In11.Cu")
		(net "P5E_CPU0_P1_RX_DP<8>")
	)
	(arc
		(start 352.820478 -278.60244)
		(mid 352.827627 -278.59754)
		(end 352.834702 -278.592534)
		(width 0.1143)
		(layer "In11.Cu")
		(net "P5E_CPU0_P1_RX_DP<8>")
	)
	(arc
		(start 347.22816 -380.77394)
		(mid 347.378731 -380.54869)
		(end 347.431614 -380.282958)
		(width 0.14224)
		(layer "In11.Cu")
		(net "P5E_CPU0_P1_RX_DP<8>")
	)
	(arc
		(start 345.752928 -378.061728)
		(mid 345.73701 -378.028005)
		(end 345.731592 -377.991116)
		(width 0.14224)
		(layer "In11.Cu")
		(net "P5E_CPU0_P1_RX_DP<8>")
	)
	(arc
		(start 351.090992 -373.569484)
		(mid 354.39332 -371.804293)
		(end 357.28783 -369.428776)
		(width 0.14224)
		(layer "In11.Cu")
		(net "P5E_CPU0_P1_RX_DP<8>")
	)
	(arc
		(start 352.752406 -287.3502)
		(mid 352.637563 -287.21691)
		(end 352.596196 -287.045908)
		(width 0.1143)
		(layer "In11.Cu")
		(net "P5E_CPU0_P1_RX_DP<8>")
	)
	(arc
		(start 352.836734 -289.021012)
		(mid 352.828656 -289.015226)
		(end 352.820478 -289.009582)
		(width 0.1143)
		(layer "In11.Cu")
		(net "P5E_CPU0_P1_RX_DP<8>")
	)
	(arc
		(start 347.363796 -379.33503)
		(mid 347.338525 -379.125776)
		(end 347.270324 -378.926344)
		(width 0.14224)
		(layer "In11.Cu")
		(net "P5E_CPU0_P1_RX_DP<8>")
	)
	(arc
		(start 352.834702 -292.259512)
		(mid 352.827629 -292.254503)
		(end 352.820478 -292.249606)
		(width 0.1143)
		(layer "In11.Cu")
		(net "P5E_CPU0_P1_RX_DP<8>")
	)
	(arc
		(start 352.820478 -286.7025)
		(mid 353.002662 -286.49683)
		(end 353.06635 -286.229552)
		(width 0.1143)
		(layer "In11.Cu")
		(net "P5E_CPU0_P1_RX_DP<8>")
	)
	(arc
		(start 352.834702 -276.059646)
		(mid 352.827628 -276.054639)
		(end 352.820478 -276.04974)
		(width 0.1143)
		(layer "In11.Cu")
		(net "P5E_CPU0_P1_RX_DP<8>")
	)
	(arc
		(start 364.629446 -362.08716)
		(mid 367.899437 -358.102565)
		(end 370.329206 -353.55657)
		(width 0.14224)
		(layer "In11.Cu")
		(net "P5E_CPU0_P1_RX_DP<8>")
	)
	(segment
		(start 344.59799 -394.385292)
		(end 345.11869 -394.385292)
		(width 0.127)
		(layer "F.Cu")
		(net "P5E_CPU0_P1_RX_DP<7>")
	)
	(segment
		(start 352.968052 -277.870158)
		(end 352.5012 -278.136096)
		(width 0.12954)
		(layer "F.Cu")
		(net "P5E_CPU0_P1_RX_DP<7>")
	)
	(segment
		(start 351.846896 -290.610036)
		(end 351.845118 -290.60902)
		(width 0.1143)
		(layer "In11.Cu")
		(net "P5E_CPU0_P1_RX_DP<7>")
	)
	(segment
		(start 351.849436 -292.231572)
		(end 351.84842 -292.231064)
		(width 0.1143)
		(layer "In11.Cu")
		(net "P5E_CPU0_P1_RX_DP<7>")
	)
	(segment
		(start 351.85096 -285.752794)
		(end 351.849436 -285.751778)
		(width 0.1143)
		(layer "In11.Cu")
		(net "P5E_CPU0_P1_RX_DP<7>")
	)
	(segment
		(start 351.822766 -288.355786)
		(end 351.823528 -288.355278)
		(width 0.1143)
		(layer "In11.Cu")
		(net "P5E_CPU0_P1_RX_DP<7>")
	)
	(segment
		(start 351.845118 -289.962844)
		(end 351.846642 -289.961828)
		(width 0.1143)
		(layer "In11.Cu")
		(net "P5E_CPU0_P1_RX_DP<7>")
	)
	(segment
		(start 351.844102 -292.228524)
		(end 351.84334 -292.228016)
		(width 0.1143)
		(layer "In11.Cu")
		(net "P5E_CPU0_P1_RX_DP<7>")
	)
	(segment
		(start 345.46794 -392.429746)
		(end 345.46794 -389.503412)
		(width 0.14224)
		(layer "In11.Cu")
		(net "P5E_CPU0_P1_RX_DP<7>")
	)
	(segment
		(start 351.84334 -293.848028)
		(end 351.812352 -293.830248)
		(width 0.1143)
		(layer "In11.Cu")
		(net "P5E_CPU0_P1_RX_DP<7>")
	)
	(segment
		(start 351.846896 -280.890218)
		(end 351.845118 -280.889202)
		(width 0.1143)
		(layer "In11.Cu")
		(net "P5E_CPU0_P1_RX_DP<7>")
	)
	(segment
		(start 356.847902 -368.434112)
		(end 363.043724 -362.23829)
		(width 0.14224)
		(layer "In11.Cu")
		(net "P5E_CPU0_P1_RX_DP<7>")
	)
	(segment
		(start 351.84334 -285.748222)
		(end 351.812352 -285.730442)
		(width 0.1143)
		(layer "In11.Cu")
		(net "P5E_CPU0_P1_RX_DP<7>")
	)
	(segment
		(start 351.341944 -279.452324)
		(end 351.386394 -279.426162)
		(width 0.1143)
		(layer "In11.Cu")
		(net "P5E_CPU0_P1_RX_DP<7>")
	)
	(segment
		(start 351.846642 -289.961828)
		(end 351.883218 -289.940492)
		(width 0.1143)
		(layer "In11.Cu")
		(net "P5E_CPU0_P1_RX_DP<7>")
	)
	(segment
		(start 351.844102 -293.203376)
		(end 351.845118 -293.202868)
		(width 0.1143)
		(layer "In11.Cu")
		(net "P5E_CPU0_P1_RX_DP<7>")
	)
	(segment
		(start 351.812352 -283.501846)
		(end 351.84334 -283.484066)
		(width 0.1143)
		(layer "In11.Cu")
		(net "P5E_CPU0_P1_RX_DP<7>")
	)
	(segment
		(start 351.844102 -282.508706)
		(end 351.84334 -282.508198)
		(width 0.1143)
		(layer "In11.Cu")
		(net "P5E_CPU0_P1_RX_DP<7>")
	)
	(segment
		(start 351.87636 -292.24732)
		(end 351.875598 -292.246812)
		(width 0.1143)
		(layer "In11.Cu")
		(net "P5E_CPU0_P1_RX_DP<7>")
	)
	(segment
		(start 351.843594 -278.623522)
		(end 351.844102 -278.623522)
		(width 0.1143)
		(layer "In11.Cu")
		(net "P5E_CPU0_P1_RX_DP<7>")
	)
	(segment
		(start 351.84334 -289.96386)
		(end 351.844102 -289.963352)
		(width 0.1143)
		(layer "In11.Cu")
		(net "P5E_CPU0_P1_RX_DP<7>")
	)
	(segment
		(start 351.844102 -293.848536)
		(end 351.84334 -293.848028)
		(width 0.1143)
		(layer "In11.Cu")
		(net "P5E_CPU0_P1_RX_DP<7>")
	)
	(segment
		(start 351.812352 -289.98164)
		(end 351.84334 -289.96386)
		(width 0.1143)
		(layer "In11.Cu")
		(net "P5E_CPU0_P1_RX_DP<7>")
	)
	(segment
		(start 351.846896 -285.750254)
		(end 351.845118 -285.749238)
		(width 0.1143)
		(layer "In11.Cu")
		(net "P5E_CPU0_P1_RX_DP<7>")
	)
	(segment
		(start 351.84334 -292.228016)
		(end 351.812352 -292.210236)
		(width 0.1143)
		(layer "In11.Cu")
		(net "P5E_CPU0_P1_RX_DP<7>")
	)
	(segment
		(start 351.85096 -290.612576)
		(end 351.849436 -290.61156)
		(width 0.1143)
		(layer "In11.Cu")
		(net "P5E_CPU0_P1_RX_DP<7>")
	)
	(segment
		(start 351.822512 -288.355786)
		(end 351.822766 -288.355786)
		(width 0.1143)
		(layer "In11.Cu")
		(net "P5E_CPU0_P1_RX_DP<7>")
	)
	(segment
		(start 351.84334 -280.888186)
		(end 351.840038 -280.886408)
		(width 0.1143)
		(layer "In11.Cu")
		(net "P5E_CPU0_P1_RX_DP<7>")
	)
	(segment
		(start 351.846896 -292.230048)
		(end 351.845118 -292.229032)
		(width 0.1143)
		(layer "In11.Cu")
		(net "P5E_CPU0_P1_RX_DP<7>")
	)
	(segment
		(start 351.880678 -287.389824)
		(end 351.844102 -287.368488)
		(width 0.1143)
		(layer "In11.Cu")
		(net "P5E_CPU0_P1_RX_DP<7>")
	)
	(segment
		(start 351.84842 -285.75127)
		(end 351.846896 -285.750254)
		(width 0.1143)
		(layer "In11.Cu")
		(net "P5E_CPU0_P1_RX_DP<7>")
	)
	(segment
		(start 351.846642 -278.621998)
		(end 351.883218 -278.600662)
		(width 0.1143)
		(layer "In11.Cu")
		(net "P5E_CPU0_P1_RX_DP<7>")
	)
	(segment
		(start 351.84842 -282.511246)
		(end 351.846896 -282.51023)
		(width 0.1143)
		(layer "In11.Cu")
		(net "P5E_CPU0_P1_RX_DP<7>")
	)
	(segment
		(start 367.550192 -324.122796)
		(end 360.667046 -315.736224)
		(width 0.14224)
		(layer "In11.Cu")
		(net "P5E_CPU0_P1_RX_DP<7>")
	)
	(segment
		(start 360.667046 -315.736224)
		(end 354.681028 -306.77739)
		(width 0.14224)
		(layer "In11.Cu")
		(net "P5E_CPU0_P1_RX_DP<7>")
	)
	(segment
		(start 351.845118 -291.582856)
		(end 351.846642 -291.58184)
		(width 0.1143)
		(layer "In11.Cu")
		(net "P5E_CPU0_P1_RX_DP<7>")
	)
	(segment
		(start 345.250008 -381.16383)
		(end 344.610182 -380.899162)
		(width 0.14224)
		(layer "In11.Cu")
		(net "P5E_CPU0_P1_RX_DP<7>")
	)
	(segment
		(start 351.875598 -290.6268)
		(end 351.85096 -290.612576)
		(width 0.1143)
		(layer "In11.Cu")
		(net "P5E_CPU0_P1_RX_DP<7>")
	)
	(segment
		(start 351.883218 -280.911554)
		(end 351.87636 -280.90749)
		(width 0.1143)
		(layer "In11.Cu")
		(net "P5E_CPU0_P1_RX_DP<7>")
	)
	(segment
		(start 351.883218 -293.871396)
		(end 351.87636 -293.867332)
		(width 0.1143)
		(layer "In11.Cu")
		(net "P5E_CPU0_P1_RX_DP<7>")
	)
	(segment
		(start 351.849436 -290.61156)
		(end 351.84842 -290.611052)
		(width 0.1143)
		(layer "In11.Cu")
		(net "P5E_CPU0_P1_RX_DP<7>")
	)
	(segment
		(start 351.849436 -280.891742)
		(end 351.84842 -280.891234)
		(width 0.1143)
		(layer "In11.Cu")
		(net "P5E_CPU0_P1_RX_DP<7>")
	)
	(segment
		(start 351.883218 -282.531566)
		(end 351.87636 -282.527502)
		(width 0.1143)
		(layer "In11.Cu")
		(net "P5E_CPU0_P1_RX_DP<7>")
	)
	(segment
		(start 351.845118 -294.82288)
		(end 351.883218 -294.800528)
		(width 0.1143)
		(layer "In11.Cu")
		(net "P5E_CPU0_P1_RX_DP<7>")
	)
	(segment
		(start 351.656396 -295.40454)
		(end 351.656396 -295.145206)
		(width 0.1143)
		(layer "In11.Cu")
		(net "P5E_CPU0_P1_RX_DP<7>")
	)
	(segment
		(start 345.476068 -393.428982)
		(end 345.160092 -393.113006)
		(width 0.14224)
		(layer "In11.Cu")
		(net "P5E_CPU0_P1_RX_DP<7>")
	)
	(segment
		(start 351.875598 -284.147006)
		(end 351.85096 -284.132782)
		(width 0.1143)
		(layer "In11.Cu")
		(net "P5E_CPU0_P1_RX_DP<7>")
	)
	(segment
		(start 351.875598 -280.906982)
		(end 351.85096 -280.892758)
		(width 0.1143)
		(layer "In11.Cu")
		(net "P5E_CPU0_P1_RX_DP<7>")
	)
	(segment
		(start 351.823528 -288.355278)
		(end 351.87763 -288.323528)
		(width 0.1143)
		(layer "In11.Cu")
		(net "P5E_CPU0_P1_RX_DP<7>")
	)
	(segment
		(start 351.84334 -285.104078)
		(end 351.844102 -285.10357)
		(width 0.1143)
		(layer "In11.Cu")
		(net "P5E_CPU0_P1_RX_DP<7>")
	)
	(segment
		(start 351.845118 -282.509214)
		(end 351.844102 -282.508706)
		(width 0.1143)
		(layer "In11.Cu")
		(net "P5E_CPU0_P1_RX_DP<7>")
	)
	(segment
		(start 351.846896 -284.130242)
		(end 351.845118 -284.129226)
		(width 0.1143)
		(layer "In11.Cu")
		(net "P5E_CPU0_P1_RX_DP<7>")
	)
	(segment
		(start 351.844102 -291.583364)
		(end 351.845118 -291.582856)
		(width 0.1143)
		(layer "In11.Cu")
		(net "P5E_CPU0_P1_RX_DP<7>")
	)
	(segment
		(start 345.38793 -393.930632)
		(end 345.476068 -393.842494)
		(width 0.14224)
		(layer "In11.Cu")
		(net "P5E_CPU0_P1_RX_DP<7>")
	)
	(segment
		(start 351.849436 -282.511754)
		(end 351.84842 -282.511246)
		(width 0.1143)
		(layer "In11.Cu")
		(net "P5E_CPU0_P1_RX_DP<7>")
	)
	(segment
		(start 351.845118 -293.202868)
		(end 351.846642 -293.201852)
		(width 0.1143)
		(layer "In11.Cu")
		(net "P5E_CPU0_P1_RX_DP<7>")
	)
	(segment
		(start 351.84334 -284.12821)
		(end 351.812352 -284.11043)
		(width 0.1143)
		(layer "In11.Cu")
		(net "P5E_CPU0_P1_RX_DP<7>")
	)
	(segment
		(start 351.810574 -286.74314)
		(end 351.883218 -286.700722)
		(width 0.1143)
		(layer "In11.Cu")
		(net "P5E_CPU0_P1_RX_DP<7>")
	)
	(segment
		(start 345.16314 -392.734546)
		(end 345.46794 -392.429746)
		(width 0.14224)
		(layer "In11.Cu")
		(net "P5E_CPU0_P1_RX_DP<7>")
	)
	(segment
		(start 351.383092 -280.083768)
		(end 351.342452 -280.0604)
		(width 0.1143)
		(layer "In11.Cu")
		(net "P5E_CPU0_P1_RX_DP<7>")
	)
	(segment
		(start 351.845118 -283.48305)
		(end 351.846642 -283.482034)
		(width 0.1143)
		(layer "In11.Cu")
		(net "P5E_CPU0_P1_RX_DP<7>")
	)
	(segment
		(start 351.84334 -281.864054)
		(end 351.844102 -281.863546)
		(width 0.1143)
		(layer "In11.Cu")
		(net "P5E_CPU0_P1_RX_DP<7>")
	)
	(segment
		(start 351.875598 -282.526994)
		(end 351.85096 -282.51277)
		(width 0.1143)
		(layer "In11.Cu")
		(net "P5E_CPU0_P1_RX_DP<7>")
	)
	(segment
		(start 351.845118 -281.863038)
		(end 351.846642 -281.862022)
		(width 0.1143)
		(layer "In11.Cu")
		(net "P5E_CPU0_P1_RX_DP<7>")
	)
	(segment
		(start 351.812352 -285.121858)
		(end 351.84334 -285.104078)
		(width 0.1143)
		(layer "In11.Cu")
		(net "P5E_CPU0_P1_RX_DP<7>")
	)
	(segment
		(start 351.844102 -287.368488)
		(end 351.812352 -287.3502)
		(width 0.1143)
		(layer "In11.Cu")
		(net "P5E_CPU0_P1_RX_DP<7>")
	)
	(segment
		(start 351.196402 -295.864534)
		(end 351.656396 -295.40454)
		(width 0.1143)
		(layer "In11.Cu")
		(net "P5E_CPU0_P1_RX_DP<7>")
	)
	(segment
		(start 351.849436 -285.751778)
		(end 351.84842 -285.75127)
		(width 0.1143)
		(layer "In11.Cu")
		(net "P5E_CPU0_P1_RX_DP<7>")
	)
	(segment
		(start 351.84334 -294.823896)
		(end 351.844102 -294.823388)
		(width 0.1143)
		(layer "In11.Cu")
		(net "P5E_CPU0_P1_RX_DP<7>")
	)
	(segment
		(start 351.844102 -284.128718)
		(end 351.84334 -284.12821)
		(width 0.1143)
		(layer "In11.Cu")
		(net "P5E_CPU0_P1_RX_DP<7>")
	)
	(segment
		(start 351.812352 -293.221664)
		(end 351.84334 -293.203884)
		(width 0.1143)
		(layer "In11.Cu")
		(net "P5E_CPU0_P1_RX_DP<7>")
	)
	(segment
		(start 344.028014 -380.31039)
		(end 344.028014 -376.510804)
		(width 0.14224)
		(layer "In11.Cu")
		(net "P5E_CPU0_P1_RX_DP<7>")
	)
	(segment
		(start 351.875598 -292.246812)
		(end 351.85096 -292.232588)
		(width 0.1143)
		(layer "In11.Cu")
		(net "P5E_CPU0_P1_RX_DP<7>")
	)
	(segment
		(start 351.812352 -294.841676)
		(end 351.84334 -294.823896)
		(width 0.1143)
		(layer "In11.Cu")
		(net "P5E_CPU0_P1_RX_DP<7>")
	)
	(segment
		(start 345.213686 -394.031216)
		(end 345.38793 -393.930632)
		(width 0.14224)
		(layer "In11.Cu")
		(net "P5E_CPU0_P1_RX_DP<7>")
	)
	(segment
		(start 351.84842 -293.851076)
		(end 351.846896 -293.85006)
		(width 0.1143)
		(layer "In11.Cu")
		(net "P5E_CPU0_P1_RX_DP<7>")
	)
	(segment
		(start 345.160092 -393.113006)
		(end 345.16314 -392.734546)
		(width 0.14224)
		(layer "In11.Cu")
		(net "P5E_CPU0_P1_RX_DP<7>")
	)
	(segment
		(start 351.84842 -292.231064)
		(end 351.846896 -292.230048)
		(width 0.1143)
		(layer "In11.Cu")
		(net "P5E_CPU0_P1_RX_DP<7>")
	)
	(segment
		(start 351.844102 -294.823388)
		(end 351.845118 -294.82288)
		(width 0.1143)
		(layer "In11.Cu")
		(net "P5E_CPU0_P1_RX_DP<7>")
	)
	(segment
		(start 345.11869 -394.385292)
		(end 345.213686 -394.031216)
		(width 0.14224)
		(layer "In11.Cu")
		(net "P5E_CPU0_P1_RX_DP<7>")
	)
	(segment
		(start 351.845118 -285.103062)
		(end 351.846642 -285.102046)
		(width 0.1143)
		(layer "In11.Cu")
		(net "P5E_CPU0_P1_RX_DP<7>")
	)
	(segment
		(start 351.846896 -282.51023)
		(end 351.845118 -282.509214)
		(width 0.1143)
		(layer "In11.Cu")
		(net "P5E_CPU0_P1_RX_DP<7>")
	)
	(segment
		(start 351.84334 -291.583872)
		(end 351.844102 -291.583364)
		(width 0.1143)
		(layer "In11.Cu")
		(net "P5E_CPU0_P1_RX_DP<7>")
	)
	(segment
		(start 351.844102 -280.888694)
		(end 351.84334 -280.888186)
		(width 0.1143)
		(layer "In11.Cu")
		(net "P5E_CPU0_P1_RX_DP<7>")
	)
	(segment
		(start 351.845118 -284.129226)
		(end 351.844102 -284.128718)
		(width 0.1143)
		(layer "In11.Cu")
		(net "P5E_CPU0_P1_RX_DP<7>")
	)
	(segment
		(start 351.844102 -281.863546)
		(end 351.845118 -281.863038)
		(width 0.1143)
		(layer "In11.Cu")
		(net "P5E_CPU0_P1_RX_DP<7>")
	)
	(segment
		(start 351.846642 -291.58184)
		(end 351.883218 -291.560504)
		(width 0.1143)
		(layer "In11.Cu")
		(net "P5E_CPU0_P1_RX_DP<7>")
	)
	(segment
		(start 345.46794 -389.503412)
		(end 345.77528 -383.244852)
		(width 0.14224)
		(layer "In11.Cu")
		(net "P5E_CPU0_P1_RX_DP<7>")
	)
	(segment
		(start 351.844102 -283.483558)
		(end 351.845118 -283.48305)
		(width 0.1143)
		(layer "In11.Cu")
		(net "P5E_CPU0_P1_RX_DP<7>")
	)
	(segment
		(start 351.196402 -296.344848)
		(end 351.196402 -295.864534)
		(width 0.1143)
		(layer "In11.Cu")
		(net "P5E_CPU0_P1_RX_DP<7>")
	)
	(segment
		(start 351.846642 -283.482034)
		(end 351.883218 -283.460698)
		(width 0.1143)
		(layer "In11.Cu")
		(net "P5E_CPU0_P1_RX_DP<7>")
	)
	(segment
		(start 352.120454 -278.2189)
		(end 352.203258 -278.136096)
		(width 0.1143)
		(layer "In11.Cu")
		(net "P5E_CPU0_P1_RX_DP<7>")
	)
	(segment
		(start 351.845118 -278.623014)
		(end 351.846642 -278.621998)
		(width 0.1143)
		(layer "In11.Cu")
		(net "P5E_CPU0_P1_RX_DP<7>")
	)
	(segment
		(start 351.812352 -281.881834)
		(end 351.84334 -281.864054)
		(width 0.1143)
		(layer "In11.Cu")
		(net "P5E_CPU0_P1_RX_DP<7>")
	)
	(segment
		(start 351.846642 -281.862022)
		(end 351.883218 -281.840686)
		(width 0.1143)
		(layer "In11.Cu")
		(net "P5E_CPU0_P1_RX_DP<7>")
	)
	(segment
		(start 351.84842 -290.611052)
		(end 351.846896 -290.610036)
		(width 0.1143)
		(layer "In11.Cu")
		(net "P5E_CPU0_P1_RX_DP<7>")
	)
	(segment
		(start 351.85096 -293.8526)
		(end 351.849436 -293.851584)
		(width 0.1143)
		(layer "In11.Cu")
		(net "P5E_CPU0_P1_RX_DP<7>")
	)
	(segment
		(start 351.242122 -296.419016)
		(end 351.242122 -296.390568)
		(width 0.1143)
		(layer "In11.Cu")
		(net "P5E_CPU0_P1_RX_DP<7>")
	)
	(segment
		(start 351.87763 -288.323528)
		(end 351.883218 -288.320734)
		(width 0.1143)
		(layer "In11.Cu")
		(net "P5E_CPU0_P1_RX_DP<7>")
	)
	(segment
		(start 344.069924 -376.409712)
		(end 345.138756 -375.34088)
		(width 0.14224)
		(layer "In11.Cu")
		(net "P5E_CPU0_P1_RX_DP<7>")
	)
	(segment
		(start 351.875598 -285.767018)
		(end 351.85096 -285.752794)
		(width 0.1143)
		(layer "In11.Cu")
		(net "P5E_CPU0_P1_RX_DP<7>")
	)
	(segment
		(start 346.645738 -374.33377)
		(end 350.255586 -372.838726)
		(width 0.14224)
		(layer "In11.Cu")
		(net "P5E_CPU0_P1_RX_DP<7>")
	)
	(segment
		(start 351.85096 -284.132782)
		(end 351.849436 -284.131766)
		(width 0.1143)
		(layer "In11.Cu")
		(net "P5E_CPU0_P1_RX_DP<7>")
	)
	(segment
		(start 344.403426 -380.760986)
		(end 344.081354 -380.438914)
		(width 0.14224)
		(layer "In11.Cu")
		(net "P5E_CPU0_P1_RX_DP<7>")
	)
	(segment
		(start 351.845118 -280.889202)
		(end 351.844102 -280.888694)
		(width 0.1143)
		(layer "In11.Cu")
		(net "P5E_CPU0_P1_RX_DP<7>")
	)
	(segment
		(start 351.882456 -289.010852)
		(end 351.822766 -288.976054)
		(width 0.1143)
		(layer "In11.Cu")
		(net "P5E_CPU0_P1_RX_DP<7>")
	)
	(segment
		(start 351.846896 -293.85006)
		(end 351.845118 -293.849044)
		(width 0.1143)
		(layer "In11.Cu")
		(net "P5E_CPU0_P1_RX_DP<7>")
	)
	(segment
		(start 351.883218 -285.77159)
		(end 351.87636 -285.767526)
		(width 0.1143)
		(layer "In11.Cu")
		(net "P5E_CPU0_P1_RX_DP<7>")
	)
	(segment
		(start 351.849436 -293.851584)
		(end 351.84842 -293.851076)
		(width 0.1143)
		(layer "In11.Cu")
		(net "P5E_CPU0_P1_RX_DP<7>")
	)
	(segment
		(start 351.846642 -293.201852)
		(end 351.883218 -293.180516)
		(width 0.1143)
		(layer "In11.Cu")
		(net "P5E_CPU0_P1_RX_DP<7>")
	)
	(segment
		(start 351.85096 -282.51277)
		(end 351.849436 -282.511754)
		(width 0.1143)
		(layer "In11.Cu")
		(net "P5E_CPU0_P1_RX_DP<7>")
	)
	(segment
		(start 369.432078 -327.724008)
		(end 367.550192 -324.122796)
		(width 0.14224)
		(layer "In11.Cu")
		(net "P5E_CPU0_P1_RX_DP<7>")
	)
	(segment
		(start 352.203258 -278.136096)
		(end 352.5012 -278.136096)
		(width 0.1143)
		(layer "In11.Cu")
		(net "P5E_CPU0_P1_RX_DP<7>")
	)
	(segment
		(start 351.844102 -290.608512)
		(end 351.84334 -290.608004)
		(width 0.1143)
		(layer "In11.Cu")
		(net "P5E_CPU0_P1_RX_DP<7>")
	)
	(segment
		(start 351.883218 -290.631372)
		(end 351.87636 -290.627308)
		(width 0.1143)
		(layer "In11.Cu")
		(net "P5E_CPU0_P1_RX_DP<7>")
	)
	(segment
		(start 351.664524 -280.602436)
		(end 351.664524 -280.572718)
		(width 0.1143)
		(layer "In11.Cu")
		(net "P5E_CPU0_P1_RX_DP<7>")
	)
	(segment
		(start 351.85096 -280.892758)
		(end 351.849436 -280.891742)
		(width 0.1143)
		(layer "In11.Cu")
		(net "P5E_CPU0_P1_RX_DP<7>")
	)
	(segment
		(start 371.618764 -347.459554)
		(end 371.618764 -339.89137)
		(width 0.14224)
		(layer "In11.Cu")
		(net "P5E_CPU0_P1_RX_DP<7>")
	)
	(segment
		(start 351.844102 -285.74873)
		(end 351.84334 -285.748222)
		(width 0.1143)
		(layer "In11.Cu")
		(net "P5E_CPU0_P1_RX_DP<7>")
	)
	(segment
		(start 351.84334 -283.484066)
		(end 351.844102 -283.483558)
		(width 0.1143)
		(layer "In11.Cu")
		(net "P5E_CPU0_P1_RX_DP<7>")
	)
	(segment
		(start 351.883218 -284.151578)
		(end 351.87636 -284.147514)
		(width 0.1143)
		(layer "In11.Cu")
		(net "P5E_CPU0_P1_RX_DP<7>")
	)
	(segment
		(start 371.618764 -339.89137)
		(end 369.432078 -327.724008)
		(width 0.14224)
		(layer "In11.Cu")
		(net "P5E_CPU0_P1_RX_DP<7>")
	)
	(segment
		(start 351.87636 -293.867332)
		(end 351.875598 -293.866824)
		(width 0.1143)
		(layer "In11.Cu")
		(net "P5E_CPU0_P1_RX_DP<7>")
	)
	(segment
		(start 351.883218 -292.251384)
		(end 351.87636 -292.24732)
		(width 0.1143)
		(layer "In11.Cu")
		(net "P5E_CPU0_P1_RX_DP<7>")
	)
	(segment
		(start 345.655392 -381.525018)
		(end 345.38285 -381.25273)
		(width 0.14224)
		(layer "In11.Cu")
		(net "P5E_CPU0_P1_RX_DP<7>")
	)
	(segment
		(start 351.844102 -285.10357)
		(end 351.845118 -285.103062)
		(width 0.1143)
		(layer "In11.Cu")
		(net "P5E_CPU0_P1_RX_DP<7>")
	)
	(segment
		(start 345.77528 -383.244852)
		(end 345.77528 -381.814578)
		(width 0.14224)
		(layer "In11.Cu")
		(net "P5E_CPU0_P1_RX_DP<7>")
	)
	(segment
		(start 351.844102 -278.623522)
		(end 351.845118 -278.623014)
		(width 0.1143)
		(layer "In11.Cu")
		(net "P5E_CPU0_P1_RX_DP<7>")
	)
	(segment
		(start 345.476068 -393.842494)
		(end 345.476068 -393.428982)
		(width 0.14224)
		(layer "In11.Cu")
		(net "P5E_CPU0_P1_RX_DP<7>")
	)
	(segment
		(start 351.84334 -290.608004)
		(end 351.812352 -290.590224)
		(width 0.1143)
		(layer "In11.Cu")
		(net "P5E_CPU0_P1_RX_DP<7>")
	)
	(segment
		(start 351.844102 -289.963352)
		(end 351.845118 -289.962844)
		(width 0.1143)
		(layer "In11.Cu")
		(net "P5E_CPU0_P1_RX_DP<7>")
	)
	(segment
		(start 351.242122 -296.390568)
		(end 351.196402 -296.344848)
		(width 0.1143)
		(layer "In11.Cu")
		(net "P5E_CPU0_P1_RX_DP<7>")
	)
	(segment
		(start 351.84334 -293.203884)
		(end 351.844102 -293.203376)
		(width 0.1143)
		(layer "In11.Cu")
		(net "P5E_CPU0_P1_RX_DP<7>")
	)
	(segment
		(start 351.85096 -292.232588)
		(end 351.849436 -292.231572)
		(width 0.1143)
		(layer "In11.Cu")
		(net "P5E_CPU0_P1_RX_DP<7>")
	)
	(segment
		(start 351.845118 -290.60902)
		(end 351.844102 -290.608512)
		(width 0.1143)
		(layer "In11.Cu")
		(net "P5E_CPU0_P1_RX_DP<7>")
	)
	(segment
		(start 351.845118 -293.849044)
		(end 351.844102 -293.848536)
		(width 0.1143)
		(layer "In11.Cu")
		(net "P5E_CPU0_P1_RX_DP<7>")
	)
	(segment
		(start 354.681028 -306.77739)
		(end 351.242122 -298.4754)
		(width 0.14224)
		(layer "In11.Cu")
		(net "P5E_CPU0_P1_RX_DP<7>")
	)
	(segment
		(start 351.87636 -285.767526)
		(end 351.875598 -285.767018)
		(width 0.1143)
		(layer "In11.Cu")
		(net "P5E_CPU0_P1_RX_DP<7>")
	)
	(segment
		(start 351.845118 -292.229032)
		(end 351.844102 -292.228524)
		(width 0.1143)
		(layer "In11.Cu")
		(net "P5E_CPU0_P1_RX_DP<7>")
	)
	(segment
		(start 351.84842 -280.891234)
		(end 351.846896 -280.890218)
		(width 0.1143)
		(layer "In11.Cu")
		(net "P5E_CPU0_P1_RX_DP<7>")
	)
	(segment
		(start 351.840038 -280.886408)
		(end 351.823274 -280.876756)
		(width 0.1143)
		(layer "In11.Cu")
		(net "P5E_CPU0_P1_RX_DP<7>")
	)
	(segment
		(start 351.812352 -291.601652)
		(end 351.84334 -291.583872)
		(width 0.1143)
		(layer "In11.Cu")
		(net "P5E_CPU0_P1_RX_DP<7>")
	)
	(segment
		(start 351.849436 -284.131766)
		(end 351.84842 -284.131258)
		(width 0.1143)
		(layer "In11.Cu")
		(net "P5E_CPU0_P1_RX_DP<7>")
	)
	(segment
		(start 351.669096 -278.93645)
		(end 351.669096 -278.926798)
		(width 0.1143)
		(layer "In11.Cu")
		(net "P5E_CPU0_P1_RX_DP<7>")
	)
	(segment
		(start 351.822766 -288.976054)
		(end 351.822258 -288.976054)
		(width 0.1143)
		(layer "In11.Cu")
		(net "P5E_CPU0_P1_RX_DP<7>")
	)
	(segment
		(start 351.846642 -285.102046)
		(end 351.883218 -285.08071)
		(width 0.1143)
		(layer "In11.Cu")
		(net "P5E_CPU0_P1_RX_DP<7>")
	)
	(segment
		(start 351.87636 -282.527502)
		(end 351.875598 -282.526994)
		(width 0.1143)
		(layer "In11.Cu")
		(net "P5E_CPU0_P1_RX_DP<7>")
	)
	(segment
		(start 351.84842 -284.131258)
		(end 351.846896 -284.130242)
		(width 0.1143)
		(layer "In11.Cu")
		(net "P5E_CPU0_P1_RX_DP<7>")
	)
	(segment
		(start 351.845118 -285.749238)
		(end 351.844102 -285.74873)
		(width 0.1143)
		(layer "In11.Cu")
		(net "P5E_CPU0_P1_RX_DP<7>")
	)
	(segment
		(start 351.875598 -293.866824)
		(end 351.85096 -293.8526)
		(width 0.1143)
		(layer "In11.Cu")
		(net "P5E_CPU0_P1_RX_DP<7>")
	)
	(segment
		(start 351.242122 -298.4754)
		(end 351.242122 -296.419016)
		(width 0.14224)
		(layer "In11.Cu")
		(net "P5E_CPU0_P1_RX_DP<7>")
	)
	(segment
		(start 351.87636 -284.147514)
		(end 351.875598 -284.147006)
		(width 0.1143)
		(layer "In11.Cu")
		(net "P5E_CPU0_P1_RX_DP<7>")
	)
	(segment
		(start 351.87636 -280.90749)
		(end 351.875598 -280.906982)
		(width 0.1143)
		(layer "In11.Cu")
		(net "P5E_CPU0_P1_RX_DP<7>")
	)
	(segment
		(start 351.84334 -282.508198)
		(end 351.812352 -282.490418)
		(width 0.1143)
		(layer "In11.Cu")
		(net "P5E_CPU0_P1_RX_DP<7>")
	)
	(segment
		(start 369.498626 -352.577654)
		(end 371.618764 -347.459554)
		(width 0.14224)
		(layer "In11.Cu")
		(net "P5E_CPU0_P1_RX_DP<7>")
	)
	(segment
		(start 351.87636 -290.627308)
		(end 351.875598 -290.6268)
		(width 0.1143)
		(layer "In11.Cu")
		(net "P5E_CPU0_P1_RX_DP<7>")
	)
	(arc
		(start 351.883218 -283.460698)
		(mid 352.126545 -282.996132)
		(end 351.883218 -282.531566)
		(width 0.1143)
		(layer "In11.Cu")
		(net "P5E_CPU0_P1_RX_DP<7>")
	)
	(arc
		(start 351.812352 -293.830248)
		(mid 351.661967 -293.525956)
		(end 351.812352 -293.221664)
		(width 0.1143)
		(layer "In11.Cu")
		(net "P5E_CPU0_P1_RX_DP<7>")
	)
	(arc
		(start 351.342452 -280.0604)
		(mid 351.186524 -279.756463)
		(end 351.341944 -279.452324)
		(width 0.1143)
		(layer "In11.Cu")
		(net "P5E_CPU0_P1_RX_DP<7>")
	)
	(arc
		(start 351.883218 -291.560504)
		(mid 352.126545 -291.095938)
		(end 351.883218 -290.631372)
		(width 0.1143)
		(layer "In11.Cu")
		(net "P5E_CPU0_P1_RX_DP<7>")
	)
	(arc
		(start 351.386394 -279.426162)
		(mid 351.593382 -279.21919)
		(end 351.669096 -278.93645)
		(width 0.1143)
		(layer "In11.Cu")
		(net "P5E_CPU0_P1_RX_DP<7>")
	)
	(arc
		(start 351.812352 -285.730442)
		(mid 351.661967 -285.42615)
		(end 351.812352 -285.121858)
		(width 0.1143)
		(layer "In11.Cu")
		(net "P5E_CPU0_P1_RX_DP<7>")
	)
	(arc
		(start 345.77528 -381.814578)
		(mid 345.744166 -381.657864)
		(end 345.655392 -381.525018)
		(width 0.14224)
		(layer "In11.Cu")
		(net "P5E_CPU0_P1_RX_DP<7>")
	)
	(arc
		(start 351.823274 -280.876756)
		(mid 351.707106 -280.760896)
		(end 351.664524 -280.602436)
		(width 0.1143)
		(layer "In11.Cu")
		(net "P5E_CPU0_P1_RX_DP<7>")
	)
	(arc
		(start 352.12655 -287.856168)
		(mid 352.061314 -287.592577)
		(end 351.880678 -287.389824)
		(width 0.1143)
		(layer "In11.Cu")
		(net "P5E_CPU0_P1_RX_DP<7>")
	)
	(arc
		(start 344.610182 -380.899162)
		(mid 344.500005 -380.84025)
		(end 344.403426 -380.760986)
		(width 0.14224)
		(layer "In11.Cu")
		(net "P5E_CPU0_P1_RX_DP<7>")
	)
	(arc
		(start 351.883218 -289.940492)
		(mid 352.126545 -289.475926)
		(end 351.883218 -289.01136)
		(width 0.1143)
		(layer "In11.Cu")
		(net "P5E_CPU0_P1_RX_DP<7>")
	)
	(arc
		(start 351.883218 -281.840686)
		(mid 352.126545 -281.37612)
		(end 351.883218 -280.911554)
		(width 0.1143)
		(layer "In11.Cu")
		(net "P5E_CPU0_P1_RX_DP<7>")
	)
	(arc
		(start 351.812352 -290.590224)
		(mid 351.658411 -290.285932)
		(end 351.812352 -289.98164)
		(width 0.1143)
		(layer "In11.Cu")
		(net "P5E_CPU0_P1_RX_DP<7>")
	)
	(arc
		(start 351.883218 -278.600662)
		(mid 352.035205 -278.444154)
		(end 352.116644 -278.24176)
		(width 0.1143)
		(layer "In11.Cu")
		(net "P5E_CPU0_P1_RX_DP<7>")
	)
	(arc
		(start 351.812352 -282.490418)
		(mid 351.660763 -282.186126)
		(end 351.812352 -281.881834)
		(width 0.1143)
		(layer "In11.Cu")
		(net "P5E_CPU0_P1_RX_DP<7>")
	)
	(arc
		(start 352.116644 -278.24176)
		(mid 352.118667 -278.23035)
		(end 352.120454 -278.2189)
		(width 0.1143)
		(layer "In11.Cu")
		(net "P5E_CPU0_P1_RX_DP<7>")
	)
	(arc
		(start 351.883218 -294.800528)
		(mid 352.126545 -294.335962)
		(end 351.883218 -293.871396)
		(width 0.1143)
		(layer "In11.Cu")
		(net "P5E_CPU0_P1_RX_DP<7>")
	)
	(arc
		(start 351.812352 -287.3502)
		(mid 351.699544 -287.215918)
		(end 351.656396 -287.045908)
		(width 0.1143)
		(layer "In11.Cu")
		(net "P5E_CPU0_P1_RX_DP<7>")
	)
	(arc
		(start 351.883218 -286.700722)
		(mid 352.126545 -286.236156)
		(end 351.883218 -285.77159)
		(width 0.1143)
		(layer "In11.Cu")
		(net "P5E_CPU0_P1_RX_DP<7>")
	)
	(arc
		(start 351.656396 -287.045908)
		(mid 351.697158 -286.876024)
		(end 351.810574 -286.74314)
		(width 0.1143)
		(layer "In11.Cu")
		(net "P5E_CPU0_P1_RX_DP<7>")
	)
	(arc
		(start 351.669096 -278.926798)
		(mid 351.715836 -278.751853)
		(end 351.843594 -278.623522)
		(width 0.1143)
		(layer "In11.Cu")
		(net "P5E_CPU0_P1_RX_DP<7>")
	)
	(arc
		(start 363.043724 -362.23829)
		(mid 366.746935 -357.725857)
		(end 369.498626 -352.577654)
		(width 0.14224)
		(layer "In11.Cu")
		(net "P5E_CPU0_P1_RX_DP<7>")
	)
	(arc
		(start 350.255586 -372.838726)
		(mid 353.768677 -370.961101)
		(end 356.847902 -368.434112)
		(width 0.14224)
		(layer "In11.Cu")
		(net "P5E_CPU0_P1_RX_DP<7>")
	)
	(arc
		(start 345.138756 -375.34088)
		(mid 345.842656 -374.763123)
		(end 346.645738 -374.33377)
		(width 0.14224)
		(layer "In11.Cu")
		(net "P5E_CPU0_P1_RX_DP<7>")
	)
	(arc
		(start 351.883218 -289.01136)
		(mid 351.882837 -289.011106)
		(end 351.882456 -289.010852)
		(width 0.1143)
		(layer "In11.Cu")
		(net "P5E_CPU0_P1_RX_DP<7>")
	)
	(arc
		(start 351.656396 -295.145206)
		(mid 351.656396 -295.144698)
		(end 351.656396 -295.14419)
		(width 0.1143)
		(layer "In11.Cu")
		(net "P5E_CPU0_P1_RX_DP<7>")
	)
	(arc
		(start 344.081354 -380.438914)
		(mid 344.0419 -380.379961)
		(end 344.028014 -380.31039)
		(width 0.14224)
		(layer "In11.Cu")
		(net "P5E_CPU0_P1_RX_DP<7>")
	)
	(arc
		(start 344.028014 -376.510804)
		(mid 344.038899 -376.45608)
		(end 344.069924 -376.409712)
		(width 0.14224)
		(layer "In11.Cu")
		(net "P5E_CPU0_P1_RX_DP<7>")
	)
	(arc
		(start 351.656396 -295.14419)
		(mid 351.69991 -294.975172)
		(end 351.812352 -294.841676)
		(width 0.1143)
		(layer "In11.Cu")
		(net "P5E_CPU0_P1_RX_DP<7>")
	)
	(arc
		(start 351.812352 -292.210236)
		(mid 351.660763 -291.905944)
		(end 351.812352 -291.601652)
		(width 0.1143)
		(layer "In11.Cu")
		(net "P5E_CPU0_P1_RX_DP<7>")
	)
	(arc
		(start 345.38285 -381.25273)
		(mid 345.320812 -381.20173)
		(end 345.250008 -381.16383)
		(width 0.14224)
		(layer "In11.Cu")
		(net "P5E_CPU0_P1_RX_DP<7>")
	)
	(arc
		(start 351.664524 -280.572718)
		(mid 351.589137 -280.290645)
		(end 351.383092 -280.083768)
		(width 0.1143)
		(layer "In11.Cu")
		(net "P5E_CPU0_P1_RX_DP<7>")
	)
	(arc
		(start 351.883218 -293.180516)
		(mid 352.126545 -292.71595)
		(end 351.883218 -292.251384)
		(width 0.1143)
		(layer "In11.Cu")
		(net "P5E_CPU0_P1_RX_DP<7>")
	)
	(arc
		(start 351.883218 -288.320734)
		(mid 352.062031 -288.118384)
		(end 352.12655 -287.856168)
		(width 0.1143)
		(layer "In11.Cu")
		(net "P5E_CPU0_P1_RX_DP<7>")
	)
	(arc
		(start 351.822258 -288.976054)
		(mid 351.643842 -288.66581)
		(end 351.822512 -288.355786)
		(width 0.1143)
		(layer "In11.Cu")
		(net "P5E_CPU0_P1_RX_DP<7>")
	)
	(arc
		(start 351.883218 -285.08071)
		(mid 352.126545 -284.616144)
		(end 351.883218 -284.151578)
		(width 0.1143)
		(layer "In11.Cu")
		(net "P5E_CPU0_P1_RX_DP<7>")
	)
	(arc
		(start 351.812352 -284.11043)
		(mid 351.663255 -283.806138)
		(end 351.812352 -283.501846)
		(width 0.1143)
		(layer "In11.Cu")
		(net "P5E_CPU0_P1_RX_DP<7>")
	)
	(segment
		(start 352.968052 -276.250146)
		(end 352.5012 -276.516084)
		(width 0.12954)
		(layer "F.Cu")
		(net "P5E_CPU0_P1_RX_DP<6>")
	)
	(segment
		(start 343.398094 -394.385292)
		(end 343.918794 -394.385292)
		(width 0.127)
		(layer "F.Cu")
		(net "P5E_CPU0_P1_RX_DP<6>")
	)
	(segment
		(start 350.465644 -280.096976)
		(end 350.435164 -280.079196)
		(width 0.1143)
		(layer "In11.Cu")
		(net "P5E_CPU0_P1_RX_DP<6>")
	)
	(segment
		(start 350.871536 -286.742378)
		(end 350.904048 -286.723582)
		(width 0.1143)
		(layer "In11.Cu")
		(net "P5E_CPU0_P1_RX_DP<6>")
	)
	(segment
		(start 350.402398 -279.451816)
		(end 350.427798 -279.437084)
		(width 0.1143)
		(layer "In11.Cu")
		(net "P5E_CPU0_P1_RX_DP<6>")
	)
	(segment
		(start 350.904048 -286.723582)
		(end 350.943164 -286.700722)
		(width 0.1143)
		(layer "In11.Cu")
		(net "P5E_CPU0_P1_RX_DP<6>")
	)
	(segment
		(start 350.943164 -292.251384)
		(end 350.873568 -292.210744)
		(width 0.1143)
		(layer "In11.Cu")
		(net "P5E_CPU0_P1_RX_DP<6>")
	)
	(segment
		(start 351.374202 -277.813516)
		(end 351.375726 -277.812754)
		(width 0.1143)
		(layer "In11.Cu")
		(net "P5E_CPU0_P1_RX_DP<6>")
	)
	(segment
		(start 355.912674 -367.959386)
		(end 362.424472 -361.447588)
		(width 0.14224)
		(layer "In11.Cu")
		(net "P5E_CPU0_P1_RX_DP<6>")
	)
	(segment
		(start 350.297242 -296.390568)
		(end 350.251522 -296.344848)
		(width 0.1143)
		(layer "In11.Cu")
		(net "P5E_CPU0_P1_RX_DP<6>")
	)
	(segment
		(start 350.430592 -280.076656)
		(end 350.42983 -280.076148)
		(width 0.1143)
		(layer "In11.Cu")
		(net "P5E_CPU0_P1_RX_DP<6>")
	)
	(segment
		(start 352.203258 -276.516084)
		(end 352.5012 -276.516084)
		(width 0.1143)
		(layer "In11.Cu")
		(net "P5E_CPU0_P1_RX_DP<6>")
	)
	(segment
		(start 350.297242 -296.419016)
		(end 350.297242 -296.390568)
		(width 0.1143)
		(layer "In11.Cu")
		(net "P5E_CPU0_P1_RX_DP<6>")
	)
	(segment
		(start 350.251522 -295.943782)
		(end 350.716342 -295.478962)
		(width 0.1143)
		(layer "In11.Cu")
		(net "P5E_CPU0_P1_RX_DP<6>")
	)
	(segment
		(start 350.873568 -289.981132)
		(end 350.943164 -289.940492)
		(width 0.1143)
		(layer "In11.Cu")
		(net "P5E_CPU0_P1_RX_DP<6>")
	)
	(segment
		(start 343.963244 -392.7348)
		(end 344.268044 -392.43)
		(width 0.14224)
		(layer "In11.Cu")
		(net "P5E_CPU0_P1_RX_DP<6>")
	)
	(segment
		(start 368.519964 -327.991724)
		(end 366.767872 -324.639686)
		(width 0.14224)
		(layer "In11.Cu")
		(net "P5E_CPU0_P1_RX_DP<6>")
	)
	(segment
		(start 350.297242 -298.630594)
		(end 350.297242 -296.419016)
		(width 0.14224)
		(layer "In11.Cu")
		(net "P5E_CPU0_P1_RX_DP<6>")
	)
	(segment
		(start 350.428306 -280.075386)
		(end 350.427544 -280.074878)
		(width 0.1143)
		(layer "In11.Cu")
		(net "P5E_CPU0_P1_RX_DP<6>")
	)
	(segment
		(start 350.716596 -295.23944)
		(end 350.716596 -295.145968)
		(width 0.1143)
		(layer "In11.Cu")
		(net "P5E_CPU0_P1_RX_DP<6>")
	)
	(segment
		(start 351.342452 -277.831804)
		(end 351.367852 -277.817072)
		(width 0.1143)
		(layer "In11.Cu")
		(net "P5E_CPU0_P1_RX_DP<6>")
	)
	(segment
		(start 350.435164 -280.079196)
		(end 350.434148 -280.078688)
		(width 0.1143)
		(layer "In11.Cu")
		(net "P5E_CPU0_P1_RX_DP<6>")
	)
	(segment
		(start 344.268044 -392.43)
		(end 344.268044 -390.51357)
		(width 0.14224)
		(layer "In11.Cu")
		(net "P5E_CPU0_P1_RX_DP<6>")
	)
	(segment
		(start 370.642896 -347.210634)
		(end 370.642896 -339.803232)
		(width 0.14224)
		(layer "In11.Cu")
		(net "P5E_CPU0_P1_RX_DP<6>")
	)
	(segment
		(start 370.642896 -339.803232)
		(end 368.519964 -327.991724)
		(width 0.14224)
		(layer "In11.Cu")
		(net "P5E_CPU0_P1_RX_DP<6>")
	)
	(segment
		(start 350.943164 -285.77159)
		(end 350.873568 -285.73095)
		(width 0.1143)
		(layer "In11.Cu")
		(net "P5E_CPU0_P1_RX_DP<6>")
	)
	(segment
		(start 350.433386 -280.07818)
		(end 350.430592 -280.076656)
		(width 0.1143)
		(layer "In11.Cu")
		(net "P5E_CPU0_P1_RX_DP<6>")
	)
	(segment
		(start 350.42983 -279.436068)
		(end 350.430592 -279.43556)
		(width 0.1143)
		(layer "In11.Cu")
		(net "P5E_CPU0_P1_RX_DP<6>")
	)
	(segment
		(start 350.716342 -295.478962)
		(end 350.716342 -295.239694)
		(width 0.1143)
		(layer "In11.Cu")
		(net "P5E_CPU0_P1_RX_DP<6>")
	)
	(segment
		(start 351.37344 -277.814024)
		(end 351.374202 -277.813516)
		(width 0.1143)
		(layer "In11.Cu")
		(net "P5E_CPU0_P1_RX_DP<6>")
	)
	(segment
		(start 350.434148 -279.433528)
		(end 350.435164 -279.43302)
		(width 0.1143)
		(layer "In11.Cu")
		(net "P5E_CPU0_P1_RX_DP<6>")
	)
	(segment
		(start 359.919016 -316.29477)
		(end 353.854766 -307.219096)
		(width 0.14224)
		(layer "In11.Cu")
		(net "P5E_CPU0_P1_RX_DP<6>")
	)
	(segment
		(start 342.326214 -383.197608)
		(end 342.326214 -376.784616)
		(width 0.14224)
		(layer "In11.Cu")
		(net "P5E_CPU0_P1_RX_DP<6>")
	)
	(segment
		(start 343.960196 -393.113006)
		(end 343.963244 -392.7348)
		(width 0.14224)
		(layer "In11.Cu")
		(net "P5E_CPU0_P1_RX_DP<6>")
	)
	(segment
		(start 350.943164 -293.871396)
		(end 350.873568 -293.830756)
		(width 0.1143)
		(layer "In11.Cu")
		(net "P5E_CPU0_P1_RX_DP<6>")
	)
	(segment
		(start 350.473264 -280.101548)
		(end 350.466406 -280.097484)
		(width 0.1143)
		(layer "In11.Cu")
		(net "P5E_CPU0_P1_RX_DP<6>")
	)
	(segment
		(start 344.276172 -393.428982)
		(end 343.960196 -393.113006)
		(width 0.14224)
		(layer "In11.Cu")
		(net "P5E_CPU0_P1_RX_DP<6>")
	)
	(segment
		(start 350.873568 -281.881326)
		(end 350.943164 -281.840686)
		(width 0.1143)
		(layer "In11.Cu")
		(net "P5E_CPU0_P1_RX_DP<6>")
	)
	(segment
		(start 350.427544 -280.074878)
		(end 350.426528 -280.07437)
		(width 0.1143)
		(layer "In11.Cu")
		(net "P5E_CPU0_P1_RX_DP<6>")
	)
	(segment
		(start 350.435164 -279.43302)
		(end 350.436688 -279.432004)
		(width 0.1143)
		(layer "In11.Cu")
		(net "P5E_CPU0_P1_RX_DP<6>")
	)
	(segment
		(start 350.873568 -293.221156)
		(end 350.943164 -293.180516)
		(width 0.1143)
		(layer "In11.Cu")
		(net "P5E_CPU0_P1_RX_DP<6>")
	)
	(segment
		(start 350.873568 -278.641302)
		(end 350.943164 -278.600662)
		(width 0.1143)
		(layer "In11.Cu")
		(net "P5E_CPU0_P1_RX_DP<6>")
	)
	(segment
		(start 351.369884 -277.816056)
		(end 351.370646 -277.815548)
		(width 0.1143)
		(layer "In11.Cu")
		(net "P5E_CPU0_P1_RX_DP<6>")
	)
	(segment
		(start 350.943164 -290.631372)
		(end 350.873568 -290.590732)
		(width 0.1143)
		(layer "In11.Cu")
		(net "P5E_CPU0_P1_RX_DP<6>")
	)
	(segment
		(start 351.370646 -277.815548)
		(end 351.37344 -277.814024)
		(width 0.1143)
		(layer "In11.Cu")
		(net "P5E_CPU0_P1_RX_DP<6>")
	)
	(segment
		(start 350.943164 -289.01136)
		(end 350.873568 -288.97072)
		(width 0.1143)
		(layer "In11.Cu")
		(net "P5E_CPU0_P1_RX_DP<6>")
	)
	(segment
		(start 353.854766 -307.219096)
		(end 350.297242 -298.630594)
		(width 0.14224)
		(layer "In11.Cu")
		(net "P5E_CPU0_P1_RX_DP<6>")
	)
	(segment
		(start 350.873568 -294.841168)
		(end 350.943164 -294.800528)
		(width 0.1143)
		(layer "In11.Cu")
		(net "P5E_CPU0_P1_RX_DP<6>")
	)
	(segment
		(start 350.434148 -280.078688)
		(end 350.433386 -280.07818)
		(width 0.1143)
		(layer "In11.Cu")
		(net "P5E_CPU0_P1_RX_DP<6>")
	)
	(segment
		(start 366.767872 -324.639686)
		(end 359.919016 -316.29477)
		(width 0.14224)
		(layer "In11.Cu")
		(net "P5E_CPU0_P1_RX_DP<6>")
	)
	(segment
		(start 350.436688 -279.432004)
		(end 350.473264 -279.410668)
		(width 0.1143)
		(layer "In11.Cu")
		(net "P5E_CPU0_P1_RX_DP<6>")
	)
	(segment
		(start 350.873568 -291.601144)
		(end 350.943164 -291.560504)
		(width 0.1143)
		(layer "In11.Cu")
		(net "P5E_CPU0_P1_RX_DP<6>")
	)
	(segment
		(start 345.305126 -373.868188)
		(end 349.94723 -371.945408)
		(width 0.14224)
		(layer "In11.Cu")
		(net "P5E_CPU0_P1_RX_DP<6>")
	)
	(segment
		(start 350.873568 -283.501338)
		(end 350.943164 -283.460698)
		(width 0.1143)
		(layer "In11.Cu")
		(net "P5E_CPU0_P1_RX_DP<6>")
	)
	(segment
		(start 350.940624 -287.389824)
		(end 350.873568 -287.350708)
		(width 0.1143)
		(layer "In11.Cu")
		(net "P5E_CPU0_P1_RX_DP<6>")
	)
	(segment
		(start 351.813368 -277.02129)
		(end 351.883218 -276.98065)
		(width 0.1143)
		(layer "In11.Cu")
		(net "P5E_CPU0_P1_RX_DP<6>")
	)
	(segment
		(start 350.42983 -280.076148)
		(end 350.428306 -280.075386)
		(width 0.1143)
		(layer "In11.Cu")
		(net "P5E_CPU0_P1_RX_DP<6>")
	)
	(segment
		(start 350.433386 -279.434036)
		(end 350.434148 -279.433528)
		(width 0.1143)
		(layer "In11.Cu")
		(net "P5E_CPU0_P1_RX_DP<6>")
	)
	(segment
		(start 350.873568 -285.12135)
		(end 350.943164 -285.08071)
		(width 0.1143)
		(layer "In11.Cu")
		(net "P5E_CPU0_P1_RX_DP<6>")
	)
	(segment
		(start 344.188034 -393.930632)
		(end 344.276172 -393.842494)
		(width 0.14224)
		(layer "In11.Cu")
		(net "P5E_CPU0_P1_RX_DP<6>")
	)
	(segment
		(start 344.276172 -393.842494)
		(end 344.276172 -393.428982)
		(width 0.14224)
		(layer "In11.Cu")
		(net "P5E_CPU0_P1_RX_DP<6>")
	)
	(segment
		(start 344.01379 -394.031216)
		(end 344.188034 -393.930632)
		(width 0.14224)
		(layer "In11.Cu")
		(net "P5E_CPU0_P1_RX_DP<6>")
	)
	(segment
		(start 351.367852 -277.817072)
		(end 351.369884 -277.816056)
		(width 0.1143)
		(layer "In11.Cu")
		(net "P5E_CPU0_P1_RX_DP<6>")
	)
	(segment
		(start 350.430592 -279.43556)
		(end 350.433386 -279.434036)
		(width 0.1143)
		(layer "In11.Cu")
		(net "P5E_CPU0_P1_RX_DP<6>")
	)
	(segment
		(start 350.427798 -279.437084)
		(end 350.42983 -279.436068)
		(width 0.1143)
		(layer "In11.Cu")
		(net "P5E_CPU0_P1_RX_DP<6>")
	)
	(segment
		(start 350.466406 -280.097484)
		(end 350.465644 -280.096976)
		(width 0.1143)
		(layer "In11.Cu")
		(net "P5E_CPU0_P1_RX_DP<6>")
	)
	(segment
		(start 352.120454 -276.598888)
		(end 352.203258 -276.516084)
		(width 0.1143)
		(layer "In11.Cu")
		(net "P5E_CPU0_P1_RX_DP<6>")
	)
	(segment
		(start 350.871536 -288.36239)
		(end 350.904048 -288.343594)
		(width 0.1143)
		(layer "In11.Cu")
		(net "P5E_CPU0_P1_RX_DP<6>")
	)
	(segment
		(start 350.426528 -280.07437)
		(end 350.402398 -280.0604)
		(width 0.1143)
		(layer "In11.Cu")
		(net "P5E_CPU0_P1_RX_DP<6>")
	)
	(segment
		(start 351.375726 -277.812754)
		(end 351.410524 -277.792434)
		(width 0.1143)
		(layer "In11.Cu")
		(net "P5E_CPU0_P1_RX_DP<6>")
	)
	(segment
		(start 350.904048 -288.343594)
		(end 350.943164 -288.320734)
		(width 0.1143)
		(layer "In11.Cu")
		(net "P5E_CPU0_P1_RX_DP<6>")
	)
	(segment
		(start 350.251522 -296.344848)
		(end 350.251522 -295.943782)
		(width 0.1143)
		(layer "In11.Cu")
		(net "P5E_CPU0_P1_RX_DP<6>")
	)
	(segment
		(start 343.918794 -394.385292)
		(end 344.01379 -394.031216)
		(width 0.14224)
		(layer "In11.Cu")
		(net "P5E_CPU0_P1_RX_DP<6>")
	)
	(segment
		(start 350.943164 -280.911554)
		(end 350.873568 -280.870914)
		(width 0.1143)
		(layer "In11.Cu")
		(net "P5E_CPU0_P1_RX_DP<6>")
	)
	(segment
		(start 368.532156 -352.306636)
		(end 370.642896 -347.210634)
		(width 0.14224)
		(layer "In11.Cu")
		(net "P5E_CPU0_P1_RX_DP<6>")
	)
	(segment
		(start 342.653366 -375.994676)
		(end 343.722198 -374.925844)
		(width 0.14224)
		(layer "In11.Cu")
		(net "P5E_CPU0_P1_RX_DP<6>")
	)
	(segment
		(start 350.943164 -282.531566)
		(end 350.873568 -282.490926)
		(width 0.1143)
		(layer "In11.Cu")
		(net "P5E_CPU0_P1_RX_DP<6>")
	)
	(segment
		(start 350.943164 -284.151578)
		(end 350.873568 -284.110938)
		(width 0.1143)
		(layer "In11.Cu")
		(net "P5E_CPU0_P1_RX_DP<6>")
	)
	(segment
		(start 344.253312 -390.40435)
		(end 342.391746 -383.680716)
		(width 0.14224)
		(layer "In11.Cu")
		(net "P5E_CPU0_P1_RX_DP<6>")
	)
	(segment
		(start 350.716342 -295.239694)
		(end 350.716596 -295.23944)
		(width 0.1143)
		(layer "In11.Cu")
		(net "P5E_CPU0_P1_RX_DP<6>")
	)
	(arc
		(start 343.722198 -374.925844)
		(mid 344.461573 -374.319056)
		(end 345.305126 -373.868188)
		(width 0.14224)
		(layer "In11.Cu")
		(net "P5E_CPU0_P1_RX_DP<6>")
	)
	(arc
		(start 362.424472 -361.447588)
		(mid 365.928492 -357.177908)
		(end 368.532156 -352.306636)
		(width 0.14224)
		(layer "In11.Cu")
		(net "P5E_CPU0_P1_RX_DP<6>")
	)
	(arc
		(start 350.873568 -280.870914)
		(mid 350.758141 -280.737538)
		(end 350.716596 -280.566114)
		(width 0.1143)
		(layer "In11.Cu")
		(net "P5E_CPU0_P1_RX_DP<6>")
	)
	(arc
		(start 349.94723 -371.945408)
		(mid 353.126251 -370.246177)
		(end 355.912674 -367.959386)
		(width 0.14224)
		(layer "In11.Cu")
		(net "P5E_CPU0_P1_RX_DP<6>")
	)
	(arc
		(start 350.716596 -280.566114)
		(mid 350.652081 -280.303895)
		(end 350.473264 -280.101548)
		(width 0.1143)
		(layer "In11.Cu")
		(net "P5E_CPU0_P1_RX_DP<6>")
	)
	(arc
		(start 351.410524 -277.792434)
		(mid 351.426493 -277.780397)
		(end 351.44202 -277.767796)
		(width 0.1143)
		(layer "In11.Cu")
		(net "P5E_CPU0_P1_RX_DP<6>")
	)
	(arc
		(start 350.943164 -281.840686)
		(mid 351.186491 -281.37612)
		(end 350.943164 -280.911554)
		(width 0.1143)
		(layer "In11.Cu")
		(net "P5E_CPU0_P1_RX_DP<6>")
	)
	(arc
		(start 350.943164 -285.08071)
		(mid 351.186491 -284.616144)
		(end 350.943164 -284.151578)
		(width 0.1143)
		(layer "In11.Cu")
		(net "P5E_CPU0_P1_RX_DP<6>")
	)
	(arc
		(start 350.716596 -288.66592)
		(mid 350.757562 -288.495514)
		(end 350.871536 -288.36239)
		(width 0.1143)
		(layer "In11.Cu")
		(net "P5E_CPU0_P1_RX_DP<6>")
	)
	(arc
		(start 350.716596 -278.946102)
		(mid 350.758145 -278.77468)
		(end 350.873568 -278.641302)
		(width 0.1143)
		(layer "In11.Cu")
		(net "P5E_CPU0_P1_RX_DP<6>")
	)
	(arc
		(start 350.943164 -294.800528)
		(mid 351.186491 -294.335962)
		(end 350.943164 -293.871396)
		(width 0.1143)
		(layer "In11.Cu")
		(net "P5E_CPU0_P1_RX_DP<6>")
	)
	(arc
		(start 350.873568 -287.350708)
		(mid 350.758141 -287.217332)
		(end 350.716596 -287.045908)
		(width 0.1143)
		(layer "In11.Cu")
		(net "P5E_CPU0_P1_RX_DP<6>")
	)
	(arc
		(start 351.656396 -277.314914)
		(mid 351.70046 -277.149691)
		(end 351.813368 -277.02129)
		(width 0.1143)
		(layer "In11.Cu")
		(net "P5E_CPU0_P1_RX_DP<6>")
	)
	(arc
		(start 350.873568 -293.830756)
		(mid 350.716591 -293.525956)
		(end 350.873568 -293.221156)
		(width 0.1143)
		(layer "In11.Cu")
		(net "P5E_CPU0_P1_RX_DP<6>")
	)
	(arc
		(start 351.648522 -277.38959)
		(mid 351.654001 -277.352415)
		(end 351.656396 -277.314914)
		(width 0.1143)
		(layer "In11.Cu")
		(net "P5E_CPU0_P1_RX_DP<6>")
	)
	(arc
		(start 350.943164 -278.600662)
		(mid 351.121977 -278.398312)
		(end 351.186496 -278.136096)
		(width 0.1143)
		(layer "In11.Cu")
		(net "P5E_CPU0_P1_RX_DP<6>")
	)
	(arc
		(start 351.883218 -276.98065)
		(mid 352.035205 -276.824142)
		(end 352.116644 -276.621748)
		(width 0.1143)
		(layer "In11.Cu")
		(net "P5E_CPU0_P1_RX_DP<6>")
	)
	(arc
		(start 350.873568 -290.590732)
		(mid 350.716591 -290.285932)
		(end 350.873568 -289.981132)
		(width 0.1143)
		(layer "In11.Cu")
		(net "P5E_CPU0_P1_RX_DP<6>")
	)
	(arc
		(start 350.873568 -292.210744)
		(mid 350.716591 -291.905944)
		(end 350.873568 -291.601144)
		(width 0.1143)
		(layer "In11.Cu")
		(net "P5E_CPU0_P1_RX_DP<6>")
	)
	(arc
		(start 350.716596 -295.145968)
		(mid 350.758145 -294.974546)
		(end 350.873568 -294.841168)
		(width 0.1143)
		(layer "In11.Cu")
		(net "P5E_CPU0_P1_RX_DP<6>")
	)
	(arc
		(start 350.873568 -288.97072)
		(mid 350.758141 -288.837344)
		(end 350.716596 -288.66592)
		(width 0.1143)
		(layer "In11.Cu")
		(net "P5E_CPU0_P1_RX_DP<6>")
	)
	(arc
		(start 342.391746 -383.680716)
		(mid 342.342664 -383.441376)
		(end 342.326214 -383.197608)
		(width 0.14224)
		(layer "In11.Cu")
		(net "P5E_CPU0_P1_RX_DP<6>")
	)
	(arc
		(start 350.402398 -280.0604)
		(mid 350.24647 -279.756108)
		(end 350.402398 -279.451816)
		(width 0.1143)
		(layer "In11.Cu")
		(net "P5E_CPU0_P1_RX_DP<6>")
	)
	(arc
		(start 350.716596 -287.045908)
		(mid 350.757562 -286.875502)
		(end 350.871536 -286.742378)
		(width 0.1143)
		(layer "In11.Cu")
		(net "P5E_CPU0_P1_RX_DP<6>")
	)
	(arc
		(start 350.943164 -286.700722)
		(mid 351.186491 -286.236156)
		(end 350.943164 -285.77159)
		(width 0.1143)
		(layer "In11.Cu")
		(net "P5E_CPU0_P1_RX_DP<6>")
	)
	(arc
		(start 350.943164 -291.560504)
		(mid 351.186491 -291.095938)
		(end 350.943164 -290.631372)
		(width 0.1143)
		(layer "In11.Cu")
		(net "P5E_CPU0_P1_RX_DP<6>")
	)
	(arc
		(start 352.116644 -276.621748)
		(mid 352.118667 -276.610338)
		(end 352.120454 -276.598888)
		(width 0.1143)
		(layer "In11.Cu")
		(net "P5E_CPU0_P1_RX_DP<6>")
	)
	(arc
		(start 344.268044 -390.51357)
		(mid 344.264385 -390.458459)
		(end 344.253312 -390.40435)
		(width 0.14224)
		(layer "In11.Cu")
		(net "P5E_CPU0_P1_RX_DP<6>")
	)
	(arc
		(start 351.186496 -287.856168)
		(mid 351.12126 -287.592577)
		(end 350.940624 -287.389824)
		(width 0.1143)
		(layer "In11.Cu")
		(net "P5E_CPU0_P1_RX_DP<6>")
	)
	(arc
		(start 351.44202 -277.767796)
		(mid 351.574438 -277.594615)
		(end 351.648522 -277.38959)
		(width 0.1143)
		(layer "In11.Cu")
		(net "P5E_CPU0_P1_RX_DP<6>")
	)
	(arc
		(start 350.873568 -282.490926)
		(mid 350.716591 -282.186126)
		(end 350.873568 -281.881326)
		(width 0.1143)
		(layer "In11.Cu")
		(net "P5E_CPU0_P1_RX_DP<6>")
	)
	(arc
		(start 350.473264 -279.410668)
		(mid 350.652077 -279.208318)
		(end 350.716596 -278.946102)
		(width 0.1143)
		(layer "In11.Cu")
		(net "P5E_CPU0_P1_RX_DP<6>")
	)
	(arc
		(start 350.943164 -288.320734)
		(mid 351.121977 -288.118384)
		(end 351.186496 -287.856168)
		(width 0.1143)
		(layer "In11.Cu")
		(net "P5E_CPU0_P1_RX_DP<6>")
	)
	(arc
		(start 351.186496 -278.136096)
		(mid 351.227751 -277.965125)
		(end 351.342452 -277.831804)
		(width 0.1143)
		(layer "In11.Cu")
		(net "P5E_CPU0_P1_RX_DP<6>")
	)
	(arc
		(start 350.873568 -285.73095)
		(mid 350.716591 -285.42615)
		(end 350.873568 -285.12135)
		(width 0.1143)
		(layer "In11.Cu")
		(net "P5E_CPU0_P1_RX_DP<6>")
	)
	(arc
		(start 350.873568 -284.110938)
		(mid 350.716591 -283.806138)
		(end 350.873568 -283.501338)
		(width 0.1143)
		(layer "In11.Cu")
		(net "P5E_CPU0_P1_RX_DP<6>")
	)
	(arc
		(start 350.943164 -293.180516)
		(mid 351.186491 -292.71595)
		(end 350.943164 -292.251384)
		(width 0.1143)
		(layer "In11.Cu")
		(net "P5E_CPU0_P1_RX_DP<6>")
	)
	(arc
		(start 350.943164 -289.940492)
		(mid 351.186491 -289.475926)
		(end 350.943164 -289.01136)
		(width 0.1143)
		(layer "In11.Cu")
		(net "P5E_CPU0_P1_RX_DP<6>")
	)
	(arc
		(start 342.326214 -376.784616)
		(mid 342.411233 -376.357109)
		(end 342.653366 -375.994676)
		(width 0.14224)
		(layer "In11.Cu")
		(net "P5E_CPU0_P1_RX_DP<6>")
	)
	(arc
		(start 350.943164 -283.460698)
		(mid 351.186491 -282.996132)
		(end 350.943164 -282.531566)
		(width 0.1143)
		(layer "In11.Cu")
		(net "P5E_CPU0_P1_RX_DP<6>")
	)
	(segment
		(start 342.198198 -394.385292)
		(end 342.718898 -394.385292)
		(width 0.127)
		(layer "F.Cu")
		(net "P5E_CPU0_P1_RX_DP<5>")
	)
	(segment
		(start 350.14789 -274.630134)
		(end 349.681038 -274.896072)
		(width 0.12954)
		(layer "F.Cu")
		(net "P5E_CPU0_P1_RX_DP<5>")
	)
	(segment
		(start 349.933514 -294.841168)
		(end 350.00311 -294.800528)
		(width 0.1143)
		(layer "In11.Cu")
		(net "P5E_CPU0_P1_RX_DP<5>")
	)
	(segment
		(start 349.494094 -279.433528)
		(end 349.49511 -279.43302)
		(width 0.1143)
		(layer "In11.Cu")
		(net "P5E_CPU0_P1_RX_DP<5>")
	)
	(segment
		(start 367.60785 -328.25944)
		(end 365.986568 -325.157846)
		(width 0.14224)
		(layer "In11.Cu")
		(net "P5E_CPU0_P1_RX_DP<5>")
	)
	(segment
		(start 342.988138 -393.930632)
		(end 343.076276 -393.842494)
		(width 0.14224)
		(layer "In11.Cu")
		(net "P5E_CPU0_P1_RX_DP<5>")
	)
	(segment
		(start 343.076276 -393.428982)
		(end 342.7603 -393.113006)
		(width 0.14224)
		(layer "In11.Cu")
		(net "P5E_CPU0_P1_RX_DP<5>")
	)
	(segment
		(start 349.462344 -279.451816)
		(end 349.493332 -279.434036)
		(width 0.1143)
		(layer "In11.Cu")
		(net "P5E_CPU0_P1_RX_DP<5>")
	)
	(segment
		(start 349.462344 -280.0604)
		(end 349.442532 -280.046176)
		(width 0.1143)
		(layer "In11.Cu")
		(net "P5E_CPU0_P1_RX_DP<5>")
	)
	(segment
		(start 349.306642 -296.389552)
		(end 349.306642 -295.818306)
		(width 0.1143)
		(layer "In11.Cu")
		(net "P5E_CPU0_P1_RX_DP<5>")
	)
	(segment
		(start 349.306642 -295.818306)
		(end 349.489014 -295.635934)
		(width 0.1143)
		(layer "In11.Cu")
		(net "P5E_CPU0_P1_RX_DP<5>")
	)
	(segment
		(start 349.352362 -296.46372)
		(end 349.352362 -296.435272)
		(width 0.1143)
		(layer "In11.Cu")
		(net "P5E_CPU0_P1_RX_DP<5>")
	)
	(segment
		(start 369.693698 -346.902024)
		(end 369.693698 -339.863176)
		(width 0.14224)
		(layer "In11.Cu")
		(net "P5E_CPU0_P1_RX_DP<5>")
	)
	(segment
		(start 349.933514 -281.881326)
		(end 350.00311 -281.840686)
		(width 0.1143)
		(layer "In11.Cu")
		(net "P5E_CPU0_P1_RX_DP<5>")
	)
	(segment
		(start 340.223348 -378.696982)
		(end 339.889338 -378.558806)
		(width 0.14224)
		(layer "In11.Cu")
		(net "P5E_CPU0_P1_RX_DP<5>")
	)
	(segment
		(start 349.933514 -289.981132)
		(end 350.00311 -289.940492)
		(width 0.1143)
		(layer "In11.Cu")
		(net "P5E_CPU0_P1_RX_DP<5>")
	)
	(segment
		(start 350.00311 -289.01136)
		(end 349.933514 -288.97072)
		(width 0.1143)
		(layer "In11.Cu")
		(net "P5E_CPU0_P1_RX_DP<5>")
	)
	(segment
		(start 342.813894 -394.031216)
		(end 342.988138 -393.930632)
		(width 0.14224)
		(layer "In11.Cu")
		(net "P5E_CPU0_P1_RX_DP<5>")
	)
	(segment
		(start 355.172264 -366.477042)
		(end 359.86466 -361.784646)
		(width 0.14224)
		(layer "In11.Cu")
		(net "P5E_CPU0_P1_RX_DP<5>")
	)
	(segment
		(start 342.7603 -393.113006)
		(end 342.763348 -392.7348)
		(width 0.14224)
		(layer "In11.Cu")
		(net "P5E_CPU0_P1_RX_DP<5>")
	)
	(segment
		(start 350.00311 -293.871396)
		(end 349.933514 -293.830756)
		(width 0.1143)
		(layer "In11.Cu")
		(net "P5E_CPU0_P1_RX_DP<5>")
	)
	(segment
		(start 349.933514 -293.221156)
		(end 350.00311 -293.180516)
		(width 0.1143)
		(layer "In11.Cu")
		(net "P5E_CPU0_P1_RX_DP<5>")
	)
	(segment
		(start 349.53321 -280.101548)
		(end 349.526352 -280.097484)
		(width 0.1143)
		(layer "In11.Cu")
		(net "P5E_CPU0_P1_RX_DP<5>")
	)
	(segment
		(start 349.931482 -288.36239)
		(end 349.963994 -288.343594)
		(width 0.1143)
		(layer "In11.Cu")
		(net "P5E_CPU0_P1_RX_DP<5>")
	)
	(segment
		(start 349.352362 -298.786042)
		(end 349.352362 -296.46372)
		(width 0.14224)
		(layer "In11.Cu")
		(net "P5E_CPU0_P1_RX_DP<5>")
	)
	(segment
		(start 343.054432 -390.300972)
		(end 340.628986 -381.130556)
		(width 0.14224)
		(layer "In11.Cu")
		(net "P5E_CPU0_P1_RX_DP<5>")
	)
	(segment
		(start 349.931482 -286.742378)
		(end 349.963994 -286.723582)
		(width 0.1143)
		(layer "In11.Cu")
		(net "P5E_CPU0_P1_RX_DP<5>")
	)
	(segment
		(start 349.383096 -274.896072)
		(end 349.681038 -274.896072)
		(width 0.1143)
		(layer "In11.Cu")
		(net "P5E_CPU0_P1_RX_DP<5>")
	)
	(segment
		(start 349.49511 -279.43302)
		(end 349.496634 -279.432004)
		(width 0.1143)
		(layer "In11.Cu")
		(net "P5E_CPU0_P1_RX_DP<5>")
	)
	(segment
		(start 349.933514 -278.641302)
		(end 350.00311 -278.600662)
		(width 0.1143)
		(layer "In11.Cu")
		(net "P5E_CPU0_P1_RX_DP<5>")
	)
	(segment
		(start 350.00311 -285.77159)
		(end 349.933514 -285.73095)
		(width 0.1143)
		(layer "In11.Cu")
		(net "P5E_CPU0_P1_RX_DP<5>")
	)
	(segment
		(start 350.00311 -277.67153)
		(end 349.933514 -277.63089)
		(width 0.1143)
		(layer "In11.Cu")
		(net "P5E_CPU0_P1_RX_DP<5>")
	)
	(segment
		(start 343.406476 -373.568976)
		(end 346.437204 -372.313708)
		(width 0.14224)
		(layer "In11.Cu")
		(net "P5E_CPU0_P1_RX_DP<5>")
	)
	(segment
		(start 349.495618 -275.221446)
		(end 349.48749 -275.21662)
		(width 0.1143)
		(layer "In11.Cu")
		(net "P5E_CPU0_P1_RX_DP<5>")
	)
	(segment
		(start 349.493332 -280.07818)
		(end 349.462344 -280.0604)
		(width 0.1143)
		(layer "In11.Cu")
		(net "P5E_CPU0_P1_RX_DP<5>")
	)
	(segment
		(start 353.029012 -307.661818)
		(end 349.352362 -298.786042)
		(width 0.14224)
		(layer "In11.Cu")
		(net "P5E_CPU0_P1_RX_DP<5>")
	)
	(segment
		(start 342.763348 -392.7348)
		(end 343.068148 -392.430254)
		(width 0.14224)
		(layer "In11.Cu")
		(net "P5E_CPU0_P1_RX_DP<5>")
	)
	(segment
		(start 350.00311 -282.531566)
		(end 349.933514 -282.490926)
		(width 0.1143)
		(layer "In11.Cu")
		(net "P5E_CPU0_P1_RX_DP<5>")
	)
	(segment
		(start 349.963994 -288.343594)
		(end 350.00311 -288.320734)
		(width 0.1143)
		(layer "In11.Cu")
		(net "P5E_CPU0_P1_RX_DP<5>")
	)
	(segment
		(start 343.076276 -393.842494)
		(end 343.076276 -393.428982)
		(width 0.14224)
		(layer "In11.Cu")
		(net "P5E_CPU0_P1_RX_DP<5>")
	)
	(segment
		(start 365.986568 -325.157846)
		(end 359.168446 -316.850014)
		(width 0.14224)
		(layer "In11.Cu")
		(net "P5E_CPU0_P1_RX_DP<5>")
	)
	(segment
		(start 350.00311 -290.631372)
		(end 349.933514 -290.590732)
		(width 0.1143)
		(layer "In11.Cu")
		(net "P5E_CPU0_P1_RX_DP<5>")
	)
	(segment
		(start 340.624414 -381.097536)
		(end 340.624414 -379.786134)
		(width 0.14224)
		(layer "In11.Cu")
		(net "P5E_CPU0_P1_RX_DP<5>")
	)
	(segment
		(start 349.526352 -280.097484)
		(end 349.52559 -280.096976)
		(width 0.1143)
		(layer "In11.Cu")
		(net "P5E_CPU0_P1_RX_DP<5>")
	)
	(segment
		(start 338.960968 -378.084842)
		(end 338.945728 -378.061728)
		(width 0.14224)
		(layer "In11.Cu")
		(net "P5E_CPU0_P1_RX_DP<5>")
	)
	(segment
		(start 349.313246 -274.965922)
		(end 349.383096 -274.896072)
		(width 0.1143)
		(layer "In11.Cu")
		(net "P5E_CPU0_P1_RX_DP<5>")
	)
	(segment
		(start 349.49511 -280.079196)
		(end 349.494094 -280.078688)
		(width 0.1143)
		(layer "In11.Cu")
		(net "P5E_CPU0_P1_RX_DP<5>")
	)
	(segment
		(start 349.493332 -279.434036)
		(end 349.494094 -279.433528)
		(width 0.1143)
		(layer "In11.Cu")
		(net "P5E_CPU0_P1_RX_DP<5>")
	)
	(segment
		(start 369.505738 -347.355668)
		(end 369.693698 -346.902024)
		(width 0.14224)
		(layer "In11.Cu")
		(net "P5E_CPU0_P1_RX_DP<5>")
	)
	(segment
		(start 350.00311 -280.911554)
		(end 349.933514 -280.870914)
		(width 0.1143)
		(layer "In11.Cu")
		(net "P5E_CPU0_P1_RX_DP<5>")
	)
	(segment
		(start 342.718898 -394.385292)
		(end 342.813894 -394.031216)
		(width 0.14224)
		(layer "In11.Cu")
		(net "P5E_CPU0_P1_RX_DP<5>")
	)
	(segment
		(start 349.494094 -280.078688)
		(end 349.493332 -280.07818)
		(width 0.1143)
		(layer "In11.Cu")
		(net "P5E_CPU0_P1_RX_DP<5>")
	)
	(segment
		(start 339.084412 -376.771916)
		(end 340.033864 -375.822464)
		(width 0.14224)
		(layer "In11.Cu")
		(net "P5E_CPU0_P1_RX_DP<5>")
	)
	(segment
		(start 349.489014 -295.635934)
		(end 349.496126 -295.63187)
		(width 0.1143)
		(layer "In11.Cu")
		(net "P5E_CPU0_P1_RX_DP<5>")
	)
	(segment
		(start 349.496634 -279.432004)
		(end 349.53321 -279.410668)
		(width 0.1143)
		(layer "In11.Cu")
		(net "P5E_CPU0_P1_RX_DP<5>")
	)
	(segment
		(start 349.52559 -280.096976)
		(end 349.49511 -280.079196)
		(width 0.1143)
		(layer "In11.Cu")
		(net "P5E_CPU0_P1_RX_DP<5>")
	)
	(segment
		(start 349.352362 -296.435272)
		(end 349.306642 -296.389552)
		(width 0.1143)
		(layer "In11.Cu")
		(net "P5E_CPU0_P1_RX_DP<5>")
	)
	(segment
		(start 349.933514 -285.12135)
		(end 350.00311 -285.08071)
		(width 0.1143)
		(layer "In11.Cu")
		(net "P5E_CPU0_P1_RX_DP<5>")
	)
	(segment
		(start 349.933514 -277.02129)
		(end 350.00311 -276.98065)
		(width 0.1143)
		(layer "In11.Cu")
		(net "P5E_CPU0_P1_RX_DP<5>")
	)
	(segment
		(start 350.00057 -287.389824)
		(end 349.933514 -287.350708)
		(width 0.1143)
		(layer "In11.Cu")
		(net "P5E_CPU0_P1_RX_DP<5>")
	)
	(segment
		(start 350.00311 -276.051518)
		(end 349.932498 -276.010116)
		(width 0.1143)
		(layer "In11.Cu")
		(net "P5E_CPU0_P1_RX_DP<5>")
	)
	(segment
		(start 343.068148 -392.430254)
		(end 343.068148 -390.40562)
		(width 0.14224)
		(layer "In11.Cu")
		(net "P5E_CPU0_P1_RX_DP<5>")
	)
	(segment
		(start 349.442532 -279.46604)
		(end 349.462344 -279.451816)
		(width 0.1143)
		(layer "In11.Cu")
		(net "P5E_CPU0_P1_RX_DP<5>")
	)
	(segment
		(start 349.963994 -286.723582)
		(end 350.00311 -286.700722)
		(width 0.1143)
		(layer "In11.Cu")
		(net "P5E_CPU0_P1_RX_DP<5>")
	)
	(segment
		(start 350.00311 -292.251384)
		(end 349.933514 -292.210744)
		(width 0.1143)
		(layer "In11.Cu")
		(net "P5E_CPU0_P1_RX_DP<5>")
	)
	(segment
		(start 369.693698 -339.863176)
		(end 367.60785 -328.25944)
		(width 0.14224)
		(layer "In11.Cu")
		(net "P5E_CPU0_P1_RX_DP<5>")
	)
	(segment
		(start 338.924392 -377.991116)
		(end 338.924392 -377.15825)
		(width 0.14224)
		(layer "In11.Cu")
		(net "P5E_CPU0_P1_RX_DP<5>")
	)
	(segment
		(start 340.628986 -381.130556)
		(end 340.628732 -381.130302)
		(width 0.14224)
		(layer "In11.Cu")
		(net "P5E_CPU0_P1_RX_DP<5>")
	)
	(segment
		(start 350.00311 -284.151578)
		(end 349.933514 -284.110938)
		(width 0.1143)
		(layer "In11.Cu")
		(net "P5E_CPU0_P1_RX_DP<5>")
	)
	(segment
		(start 359.168446 -316.850014)
		(end 353.029012 -307.661818)
		(width 0.14224)
		(layer "In11.Cu")
		(net "P5E_CPU0_P1_RX_DP<5>")
	)
	(segment
		(start 349.933514 -283.501338)
		(end 350.00311 -283.460698)
		(width 0.1143)
		(layer "In11.Cu")
		(net "P5E_CPU0_P1_RX_DP<5>")
	)
	(segment
		(start 349.933514 -291.601144)
		(end 350.00311 -291.560504)
		(width 0.1143)
		(layer "In11.Cu")
		(net "P5E_CPU0_P1_RX_DP<5>")
	)
	(arc
		(start 340.463124 -378.926344)
		(mid 340.364821 -378.789097)
		(end 340.223348 -378.696982)
		(width 0.14224)
		(layer "In11.Cu")
		(net "P5E_CPU0_P1_RX_DP<5>")
	)
	(arc
		(start 339.889338 -378.558806)
		(mid 339.790306 -378.527648)
		(end 339.687408 -378.513848)
		(width 0.14224)
		(layer "In11.Cu")
		(net "P5E_CPU0_P1_RX_DP<5>")
	)
	(arc
		(start 349.932498 -276.010116)
		(mid 349.817655 -275.876968)
		(end 349.776288 -275.706078)
		(width 0.1143)
		(layer "In11.Cu")
		(net "P5E_CPU0_P1_RX_DP<5>")
	)
	(arc
		(start 340.57844 -379.474984)
		(mid 340.562668 -379.405764)
		(end 340.556596 -379.33503)
		(width 0.14224)
		(layer "In11.Cu")
		(net "P5E_CPU0_P1_RX_DP<5>")
	)
	(arc
		(start 349.776542 -287.045908)
		(mid 349.817508 -286.875502)
		(end 349.931482 -286.742378)
		(width 0.1143)
		(layer "In11.Cu")
		(net "P5E_CPU0_P1_RX_DP<5>")
	)
	(arc
		(start 340.628732 -381.130302)
		(mid 340.625511 -381.114059)
		(end 340.624414 -381.097536)
		(width 0.14224)
		(layer "In11.Cu")
		(net "P5E_CPU0_P1_RX_DP<5>")
	)
	(arc
		(start 339.194648 -378.340874)
		(mid 339.143593 -378.303275)
		(end 339.097874 -378.25934)
		(width 0.14224)
		(layer "In11.Cu")
		(net "P5E_CPU0_P1_RX_DP<5>")
	)
	(arc
		(start 349.48749 -275.21662)
		(mid 349.373614 -275.109862)
		(end 349.313246 -274.965922)
		(width 0.1143)
		(layer "In11.Cu")
		(net "P5E_CPU0_P1_RX_DP<5>")
	)
	(arc
		(start 340.624414 -379.786134)
		(mid 340.612833 -379.628875)
		(end 340.57844 -379.474984)
		(width 0.14224)
		(layer "In11.Cu")
		(net "P5E_CPU0_P1_RX_DP<5>")
	)
	(arc
		(start 349.776542 -288.66592)
		(mid 349.817508 -288.495514)
		(end 349.931482 -288.36239)
		(width 0.1143)
		(layer "In11.Cu")
		(net "P5E_CPU0_P1_RX_DP<5>")
	)
	(arc
		(start 340.033864 -375.822464)
		(mid 341.609208 -374.529657)
		(end 343.406476 -373.568976)
		(width 0.14224)
		(layer "In11.Cu")
		(net "P5E_CPU0_P1_RX_DP<5>")
	)
	(arc
		(start 349.933514 -284.110938)
		(mid 349.776537 -283.806138)
		(end 349.933514 -283.501338)
		(width 0.1143)
		(layer "In11.Cu")
		(net "P5E_CPU0_P1_RX_DP<5>")
	)
	(arc
		(start 350.00311 -285.08071)
		(mid 350.246437 -284.616144)
		(end 350.00311 -284.151578)
		(width 0.1143)
		(layer "In11.Cu")
		(net "P5E_CPU0_P1_RX_DP<5>")
	)
	(arc
		(start 349.496126 -295.63187)
		(mid 349.691905 -295.437066)
		(end 349.763588 -295.170352)
		(width 0.1143)
		(layer "In11.Cu")
		(net "P5E_CPU0_P1_RX_DP<5>")
	)
	(arc
		(start 349.763588 -295.170352)
		(mid 349.808698 -294.985198)
		(end 349.933514 -294.841168)
		(width 0.1143)
		(layer "In11.Cu")
		(net "P5E_CPU0_P1_RX_DP<5>")
	)
	(arc
		(start 349.53321 -279.410668)
		(mid 349.712023 -279.208318)
		(end 349.776542 -278.946102)
		(width 0.1143)
		(layer "In11.Cu")
		(net "P5E_CPU0_P1_RX_DP<5>")
	)
	(arc
		(start 349.933514 -280.870914)
		(mid 349.818087 -280.737538)
		(end 349.776542 -280.566114)
		(width 0.1143)
		(layer "In11.Cu")
		(net "P5E_CPU0_P1_RX_DP<5>")
	)
	(arc
		(start 349.933514 -277.63089)
		(mid 349.776537 -277.32609)
		(end 349.933514 -277.02129)
		(width 0.1143)
		(layer "In11.Cu")
		(net "P5E_CPU0_P1_RX_DP<5>")
	)
	(arc
		(start 350.246442 -287.856168)
		(mid 350.181206 -287.592577)
		(end 350.00057 -287.389824)
		(width 0.1143)
		(layer "In11.Cu")
		(net "P5E_CPU0_P1_RX_DP<5>")
	)
	(arc
		(start 349.933514 -292.210744)
		(mid 349.776537 -291.905944)
		(end 349.933514 -291.601144)
		(width 0.1143)
		(layer "In11.Cu")
		(net "P5E_CPU0_P1_RX_DP<5>")
	)
	(arc
		(start 349.776288 -275.706078)
		(mid 349.70106 -275.426051)
		(end 349.495618 -275.221446)
		(width 0.1143)
		(layer "In11.Cu")
		(net "P5E_CPU0_P1_RX_DP<5>")
	)
	(arc
		(start 338.945728 -378.061728)
		(mid 338.92981 -378.028005)
		(end 338.924392 -377.991116)
		(width 0.14224)
		(layer "In11.Cu")
		(net "P5E_CPU0_P1_RX_DP<5>")
	)
	(arc
		(start 343.068148 -390.40562)
		(mid 343.064666 -390.352854)
		(end 343.054432 -390.300972)
		(width 0.14224)
		(layer "In11.Cu")
		(net "P5E_CPU0_P1_RX_DP<5>")
	)
	(arc
		(start 350.00311 -288.320734)
		(mid 350.181923 -288.118384)
		(end 350.246442 -287.856168)
		(width 0.1143)
		(layer "In11.Cu")
		(net "P5E_CPU0_P1_RX_DP<5>")
	)
	(arc
		(start 350.00311 -294.800528)
		(mid 350.246437 -294.335962)
		(end 350.00311 -293.871396)
		(width 0.1143)
		(layer "In11.Cu")
		(net "P5E_CPU0_P1_RX_DP<5>")
	)
	(arc
		(start 349.933514 -288.97072)
		(mid 349.818087 -288.837344)
		(end 349.776542 -288.66592)
		(width 0.1143)
		(layer "In11.Cu")
		(net "P5E_CPU0_P1_RX_DP<5>")
	)
	(arc
		(start 349.776542 -280.566114)
		(mid 349.712027 -280.303895)
		(end 349.53321 -280.101548)
		(width 0.1143)
		(layer "In11.Cu")
		(net "P5E_CPU0_P1_RX_DP<5>")
	)
	(arc
		(start 349.933514 -285.73095)
		(mid 349.776537 -285.42615)
		(end 349.933514 -285.12135)
		(width 0.1143)
		(layer "In11.Cu")
		(net "P5E_CPU0_P1_RX_DP<5>")
	)
	(arc
		(start 350.00311 -276.98065)
		(mid 350.246437 -276.516084)
		(end 350.00311 -276.051518)
		(width 0.1143)
		(layer "In11.Cu")
		(net "P5E_CPU0_P1_RX_DP<5>")
	)
	(arc
		(start 338.924392 -377.15825)
		(mid 338.965981 -376.949169)
		(end 339.084412 -376.771916)
		(width 0.14224)
		(layer "In11.Cu")
		(net "P5E_CPU0_P1_RX_DP<5>")
	)
	(arc
		(start 350.00311 -291.560504)
		(mid 350.246437 -291.095938)
		(end 350.00311 -290.631372)
		(width 0.1143)
		(layer "In11.Cu")
		(net "P5E_CPU0_P1_RX_DP<5>")
	)
	(arc
		(start 340.556596 -379.33503)
		(mid 340.531325 -379.125776)
		(end 340.463124 -378.926344)
		(width 0.14224)
		(layer "In11.Cu")
		(net "P5E_CPU0_P1_RX_DP<5>")
	)
	(arc
		(start 339.687408 -378.513848)
		(mid 339.624126 -378.508078)
		(end 339.561678 -378.496322)
		(width 0.14224)
		(layer "In11.Cu")
		(net "P5E_CPU0_P1_RX_DP<5>")
	)
	(arc
		(start 350.00311 -278.600662)
		(mid 350.246437 -278.136096)
		(end 350.00311 -277.67153)
		(width 0.1143)
		(layer "In11.Cu")
		(net "P5E_CPU0_P1_RX_DP<5>")
	)
	(arc
		(start 349.776542 -278.946102)
		(mid 349.818091 -278.77468)
		(end 349.933514 -278.641302)
		(width 0.1143)
		(layer "In11.Cu")
		(net "P5E_CPU0_P1_RX_DP<5>")
	)
	(arc
		(start 350.00311 -283.460698)
		(mid 350.246437 -282.996132)
		(end 350.00311 -282.531566)
		(width 0.1143)
		(layer "In11.Cu")
		(net "P5E_CPU0_P1_RX_DP<5>")
	)
	(arc
		(start 349.933514 -293.830756)
		(mid 349.776537 -293.525956)
		(end 349.933514 -293.221156)
		(width 0.1143)
		(layer "In11.Cu")
		(net "P5E_CPU0_P1_RX_DP<5>")
	)
	(arc
		(start 350.00311 -293.180516)
		(mid 350.246437 -292.71595)
		(end 350.00311 -292.251384)
		(width 0.1143)
		(layer "In11.Cu")
		(net "P5E_CPU0_P1_RX_DP<5>")
	)
	(arc
		(start 350.00311 -289.940492)
		(mid 350.246437 -289.475926)
		(end 350.00311 -289.01136)
		(width 0.1143)
		(layer "In11.Cu")
		(net "P5E_CPU0_P1_RX_DP<5>")
	)
	(arc
		(start 349.933514 -290.590732)
		(mid 349.776537 -290.285932)
		(end 349.933514 -289.981132)
		(width 0.1143)
		(layer "In11.Cu")
		(net "P5E_CPU0_P1_RX_DP<5>")
	)
	(arc
		(start 349.933514 -287.350708)
		(mid 349.818087 -287.217332)
		(end 349.776542 -287.045908)
		(width 0.1143)
		(layer "In11.Cu")
		(net "P5E_CPU0_P1_RX_DP<5>")
	)
	(arc
		(start 339.561678 -378.496322)
		(mid 339.371744 -378.433755)
		(end 339.194648 -378.340874)
		(width 0.14224)
		(layer "In11.Cu")
		(net "P5E_CPU0_P1_RX_DP<5>")
	)
	(arc
		(start 350.00311 -281.840686)
		(mid 350.246437 -281.37612)
		(end 350.00311 -280.911554)
		(width 0.1143)
		(layer "In11.Cu")
		(net "P5E_CPU0_P1_RX_DP<5>")
	)
	(arc
		(start 350.00311 -286.700722)
		(mid 350.246437 -286.236156)
		(end 350.00311 -285.77159)
		(width 0.1143)
		(layer "In11.Cu")
		(net "P5E_CPU0_P1_RX_DP<5>")
	)
	(arc
		(start 359.86466 -361.784646)
		(mid 365.395777 -355.044947)
		(end 369.505738 -347.355668)
		(width 0.14224)
		(layer "In11.Cu")
		(net "P5E_CPU0_P1_RX_DP<5>")
	)
	(arc
		(start 349.442532 -280.046176)
		(mid 349.293818 -279.756108)
		(end 349.442532 -279.46604)
		(width 0.1143)
		(layer "In11.Cu")
		(net "P5E_CPU0_P1_RX_DP<5>")
	)
	(arc
		(start 349.933514 -282.490926)
		(mid 349.776537 -282.186126)
		(end 349.933514 -281.881326)
		(width 0.1143)
		(layer "In11.Cu")
		(net "P5E_CPU0_P1_RX_DP<5>")
	)
	(arc
		(start 339.097874 -378.25934)
		(mid 339.026041 -378.174743)
		(end 338.960968 -378.084842)
		(width 0.14224)
		(layer "In11.Cu")
		(net "P5E_CPU0_P1_RX_DP<5>")
	)
	(arc
		(start 346.437204 -372.313708)
		(mid 351.092173 -369.825549)
		(end 355.172264 -366.477042)
		(width 0.14224)
		(layer "In11.Cu")
		(net "P5E_CPU0_P1_RX_DP<5>")
	)
	(segment
		(start 350.14789 -277.870158)
		(end 349.681038 -278.136096)
		(width 0.12954)
		(layer "F.Cu")
		(net "P5E_CPU0_P1_RX_DP<4>")
	)
	(segment
		(start 340.998048 -394.385292)
		(end 341.518748 -394.385292)
		(width 0.127)
		(layer "F.Cu")
		(net "P5E_CPU0_P1_RX_DP<4>")
	)
	(segment
		(start 349.072708 -293.877746)
		(end 349.06585 -293.873174)
		(width 0.1143)
		(layer "In11.Cu")
		(net "P5E_CPU0_P1_RX_DP<4>")
	)
	(segment
		(start 341.80526 -389.612124)
		(end 339.564218 -382.226566)
		(width 0.14224)
		(layer "In11.Cu")
		(net "P5E_CPU0_P1_RX_DP<4>")
	)
	(segment
		(start 349.024194 -283.483558)
		(end 349.060516 -283.462476)
		(width 0.1143)
		(layer "In11.Cu")
		(net "P5E_CPU0_P1_RX_DP<4>")
	)
	(segment
		(start 349.01886 -278.62784)
		(end 349.024702 -278.624538)
		(width 0.1143)
		(layer "In11.Cu")
		(net "P5E_CPU0_P1_RX_DP<4>")
	)
	(segment
		(start 348.990666 -286.74314)
		(end 348.991428 -286.742632)
		(width 0.1143)
		(layer "In11.Cu")
		(net "P5E_CPU0_P1_RX_DP<4>")
	)
	(segment
		(start 349.061786 -294.801798)
		(end 349.078042 -294.790114)
		(width 0.1143)
		(layer "In11.Cu")
		(net "P5E_CPU0_P1_RX_DP<4>")
	)
	(segment
		(start 349.024194 -289.963352)
		(end 349.060516 -289.94227)
		(width 0.1143)
		(layer "In11.Cu")
		(net "P5E_CPU0_P1_RX_DP<4>")
	)
	(segment
		(start 339.461856 -382.05537)
		(end 338.7598 -381.353314)
		(width 0.14224)
		(layer "In11.Cu")
		(net "P5E_CPU0_P1_RX_DP<4>")
	)
	(segment
		(start 348.52356 -279.451308)
		(end 348.591632 -279.411684)
		(width 0.1143)
		(layer "In11.Cu")
		(net "P5E_CPU0_P1_RX_DP<4>")
	)
	(segment
		(start 349.022162 -293.204646)
		(end 349.023432 -293.203884)
		(width 0.1143)
		(layer "In11.Cu")
		(net "P5E_CPU0_P1_RX_DP<4>")
	)
	(segment
		(start 349.023432 -287.36798)
		(end 349.021654 -287.366964)
		(width 0.1143)
		(layer "In11.Cu")
		(net "P5E_CPU0_P1_RX_DP<4>")
	)
	(segment
		(start 349.024194 -287.368488)
		(end 349.023432 -287.36798)
		(width 0.1143)
		(layer "In11.Cu")
		(net "P5E_CPU0_P1_RX_DP<4>")
	)
	(segment
		(start 339.564218 -382.226566)
		(end 339.564218 -382.226058)
		(width 0.14224)
		(layer "In11.Cu")
		(net "P5E_CPU0_P1_RX_DP<4>")
	)
	(segment
		(start 349.383096 -278.136096)
		(end 349.681038 -278.136096)
		(width 0.1143)
		(layer "In11.Cu")
		(net "P5E_CPU0_P1_RX_DP<4>")
	)
	(segment
		(start 348.407228 -298.941236)
		(end 348.407228 -296.46372)
		(width 0.14224)
		(layer "In11.Cu")
		(net "P5E_CPU0_P1_RX_DP<4>")
	)
	(segment
		(start 341.787988 -393.930632)
		(end 341.876126 -393.842494)
		(width 0.14224)
		(layer "In11.Cu")
		(net "P5E_CPU0_P1_RX_DP<4>")
	)
	(segment
		(start 340.726522 -373.632984)
		(end 346.093796 -371.409722)
		(width 0.14224)
		(layer "In11.Cu")
		(net "P5E_CPU0_P1_RX_DP<4>")
	)
	(segment
		(start 349.024194 -280.888694)
		(end 348.992444 -280.870406)
		(width 0.1143)
		(layer "In11.Cu")
		(net "P5E_CPU0_P1_RX_DP<4>")
	)
	(segment
		(start 349.018606 -285.745428)
		(end 349.01759 -285.74492)
		(width 0.1143)
		(layer "In11.Cu")
		(net "P5E_CPU0_P1_RX_DP<4>")
	)
	(segment
		(start 349.024194 -284.128718)
		(end 348.992444 -284.11043)
		(width 0.1143)
		(layer "In11.Cu")
		(net "P5E_CPU0_P1_RX_DP<4>")
	)
	(segment
		(start 348.991428 -286.742632)
		(end 349.024194 -286.723582)
		(width 0.1143)
		(layer "In11.Cu")
		(net "P5E_CPU0_P1_RX_DP<4>")
	)
	(segment
		(start 349.023432 -293.203884)
		(end 349.024194 -293.203376)
		(width 0.1143)
		(layer "In11.Cu")
		(net "P5E_CPU0_P1_RX_DP<4>")
	)
	(segment
		(start 349.060516 -280.909776)
		(end 349.024194 -280.888694)
		(width 0.1143)
		(layer "In11.Cu")
		(net "P5E_CPU0_P1_RX_DP<4>")
	)
	(segment
		(start 348.992444 -294.841676)
		(end 349.061786 -294.801798)
		(width 0.1143)
		(layer "In11.Cu")
		(net "P5E_CPU0_P1_RX_DP<4>")
	)
	(segment
		(start 348.407228 -296.435272)
		(end 348.361508 -296.389552)
		(width 0.1143)
		(layer "In11.Cu")
		(net "P5E_CPU0_P1_RX_DP<4>")
	)
	(segment
		(start 341.613744 -394.031216)
		(end 341.787988 -393.930632)
		(width 0.14224)
		(layer "In11.Cu")
		(net "P5E_CPU0_P1_RX_DP<4>")
	)
	(segment
		(start 349.024956 -285.749238)
		(end 349.024194 -285.74873)
		(width 0.1143)
		(layer "In11.Cu")
		(net "P5E_CPU0_P1_RX_DP<4>")
	)
	(segment
		(start 349.063056 -293.871142)
		(end 349.026988 -293.850314)
		(width 0.1143)
		(layer "In11.Cu")
		(net "P5E_CPU0_P1_RX_DP<4>")
	)
	(segment
		(start 349.060516 -284.1498)
		(end 349.024194 -284.128718)
		(width 0.1143)
		(layer "In11.Cu")
		(net "P5E_CPU0_P1_RX_DP<4>")
	)
	(segment
		(start 349.060516 -289.009582)
		(end 349.024194 -288.9885)
		(width 0.1143)
		(layer "In11.Cu")
		(net "P5E_CPU0_P1_RX_DP<4>")
	)
	(segment
		(start 348.992444 -285.121858)
		(end 349.024194 -285.10357)
		(width 0.1143)
		(layer "In11.Cu")
		(net "P5E_CPU0_P1_RX_DP<4>")
	)
	(segment
		(start 337.69173 -380.86665)
		(end 337.255612 -380.430532)
		(width 0.14224)
		(layer "In11.Cu")
		(net "P5E_CPU0_P1_RX_DP<4>")
	)
	(segment
		(start 358.42067 -317.409322)
		(end 352.201988 -308.102762)
		(width 0.14224)
		(layer "In11.Cu")
		(net "P5E_CPU0_P1_RX_DP<4>")
	)
	(segment
		(start 351.780856 -367.609628)
		(end 361.653582 -357.736902)
		(width 0.14224)
		(layer "In11.Cu")
		(net "P5E_CPU0_P1_RX_DP<4>")
	)
	(segment
		(start 349.06585 -293.873174)
		(end 349.063056 -293.871142)
		(width 0.1143)
		(layer "In11.Cu")
		(net "P5E_CPU0_P1_RX_DP<4>")
	)
	(segment
		(start 348.992444 -283.501846)
		(end 349.024194 -283.483558)
		(width 0.1143)
		(layer "In11.Cu")
		(net "P5E_CPU0_P1_RX_DP<4>")
	)
	(segment
		(start 365.205264 -325.676006)
		(end 358.42067 -317.409322)
		(width 0.14224)
		(layer "In11.Cu")
		(net "P5E_CPU0_P1_RX_DP<4>")
	)
	(segment
		(start 349.023432 -289.96386)
		(end 349.024194 -289.963352)
		(width 0.1143)
		(layer "In11.Cu")
		(net "P5E_CPU0_P1_RX_DP<4>")
	)
	(segment
		(start 338.626958 -381.264414)
		(end 337.732878 -380.894082)
		(width 0.14224)
		(layer "In11.Cu")
		(net "P5E_CPU0_P1_RX_DP<4>")
	)
	(segment
		(start 349.023432 -293.848028)
		(end 348.992444 -293.830248)
		(width 0.1143)
		(layer "In11.Cu")
		(net "P5E_CPU0_P1_RX_DP<4>")
	)
	(segment
		(start 349.024194 -285.74873)
		(end 349.019368 -285.745936)
		(width 0.1143)
		(layer "In11.Cu")
		(net "P5E_CPU0_P1_RX_DP<4>")
	)
	(segment
		(start 349.018606 -287.365186)
		(end 349.01759 -287.364678)
		(width 0.1143)
		(layer "In11.Cu")
		(net "P5E_CPU0_P1_RX_DP<4>")
	)
	(segment
		(start 366.696244 -328.528426)
		(end 365.205264 -325.676006)
		(width 0.14224)
		(layer "In11.Cu")
		(net "P5E_CPU0_P1_RX_DP<4>")
	)
	(segment
		(start 348.361508 -296.389552)
		(end 348.361508 -295.875456)
		(width 0.1143)
		(layer "In11.Cu")
		(net "P5E_CPU0_P1_RX_DP<4>")
	)
	(segment
		(start 368.750088 -346.366592)
		(end 368.750088 -339.955886)
		(width 0.14224)
		(layer "In11.Cu")
		(net "P5E_CPU0_P1_RX_DP<4>")
	)
	(segment
		(start 349.024194 -293.848536)
		(end 349.023432 -293.848028)
		(width 0.1143)
		(layer "In11.Cu")
		(net "P5E_CPU0_P1_RX_DP<4>")
	)
	(segment
		(start 349.022162 -291.584634)
		(end 349.023432 -291.583872)
		(width 0.1143)
		(layer "In11.Cu")
		(net "P5E_CPU0_P1_RX_DP<4>")
	)
	(segment
		(start 349.024194 -291.583364)
		(end 349.060516 -291.562282)
		(width 0.1143)
		(layer "In11.Cu")
		(net "P5E_CPU0_P1_RX_DP<4>")
	)
	(segment
		(start 349.026988 -293.850314)
		(end 349.024194 -293.848536)
		(width 0.1143)
		(layer "In11.Cu")
		(net "P5E_CPU0_P1_RX_DP<4>")
	)
	(segment
		(start 349.02394 -287.368742)
		(end 349.024194 -287.368488)
		(width 0.1143)
		(layer "In11.Cu")
		(net "P5E_CPU0_P1_RX_DP<4>")
	)
	(segment
		(start 348.593156 -280.101548)
		(end 348.52356 -280.060908)
		(width 0.1143)
		(layer "In11.Cu")
		(net "P5E_CPU0_P1_RX_DP<4>")
	)
	(segment
		(start 341.867998 -392.430254)
		(end 341.867998 -390.035796)
		(width 0.14224)
		(layer "In11.Cu")
		(net "P5E_CPU0_P1_RX_DP<4>")
	)
	(segment
		(start 349.01759 -287.364678)
		(end 348.992444 -287.3502)
		(width 0.1143)
		(layer "In11.Cu")
		(net "P5E_CPU0_P1_RX_DP<4>")
	)
	(segment
		(start 349.024194 -290.608512)
		(end 349.023432 -290.608004)
		(width 0.1143)
		(layer "In11.Cu")
		(net "P5E_CPU0_P1_RX_DP<4>")
	)
	(segment
		(start 349.024194 -282.508706)
		(end 348.992444 -282.490418)
		(width 0.1143)
		(layer "In11.Cu")
		(net "P5E_CPU0_P1_RX_DP<4>")
	)
	(segment
		(start 349.024194 -286.723582)
		(end 349.024956 -286.723074)
		(width 0.1143)
		(layer "In11.Cu")
		(net "P5E_CPU0_P1_RX_DP<4>")
	)
	(segment
		(start 348.992444 -293.221664)
		(end 349.022162 -293.204646)
		(width 0.1143)
		(layer "In11.Cu")
		(net "P5E_CPU0_P1_RX_DP<4>")
	)
	(segment
		(start 349.060516 -282.529788)
		(end 349.024194 -282.508706)
		(width 0.1143)
		(layer "In11.Cu")
		(net "P5E_CPU0_P1_RX_DP<4>")
	)
	(segment
		(start 349.023432 -288.987992)
		(end 348.992444 -288.970212)
		(width 0.1143)
		(layer "In11.Cu")
		(net "P5E_CPU0_P1_RX_DP<4>")
	)
	(segment
		(start 367.933478 -348.33814)
		(end 368.750088 -346.366592)
		(width 0.14224)
		(layer "In11.Cu")
		(net "P5E_CPU0_P1_RX_DP<4>")
	)
	(segment
		(start 337.332574 -376.275346)
		(end 338.460842 -375.147078)
		(width 0.14224)
		(layer "In11.Cu")
		(net "P5E_CPU0_P1_RX_DP<4>")
	)
	(segment
		(start 349.024702 -287.36925)
		(end 349.02394 -287.368742)
		(width 0.1143)
		(layer "In11.Cu")
		(net "P5E_CPU0_P1_RX_DP<4>")
	)
	(segment
		(start 341.563198 -392.7348)
		(end 341.867998 -392.430254)
		(width 0.14224)
		(layer "In11.Cu")
		(net "P5E_CPU0_P1_RX_DP<4>")
	)
	(segment
		(start 348.990666 -288.363152)
		(end 349.024194 -288.343594)
		(width 0.1143)
		(layer "In11.Cu")
		(net "P5E_CPU0_P1_RX_DP<4>")
	)
	(segment
		(start 352.201988 -308.102762)
		(end 348.407228 -298.941236)
		(width 0.14224)
		(layer "In11.Cu")
		(net "P5E_CPU0_P1_RX_DP<4>")
	)
	(segment
		(start 349.021654 -287.366964)
		(end 349.020892 -287.366456)
		(width 0.1143)
		(layer "In11.Cu")
		(net "P5E_CPU0_P1_RX_DP<4>")
	)
	(segment
		(start 348.407228 -296.46372)
		(end 348.407228 -296.435272)
		(width 0.1143)
		(layer "In11.Cu")
		(net "P5E_CPU0_P1_RX_DP<4>")
	)
	(segment
		(start 348.836488 -295.400476)
		(end 348.836488 -295.145968)
		(width 0.1143)
		(layer "In11.Cu")
		(net "P5E_CPU0_P1_RX_DP<4>")
	)
	(segment
		(start 348.992444 -291.601652)
		(end 349.022162 -291.584634)
		(width 0.1143)
		(layer "In11.Cu")
		(net "P5E_CPU0_P1_RX_DP<4>")
	)
	(segment
		(start 349.024194 -292.228524)
		(end 349.023432 -292.228016)
		(width 0.1143)
		(layer "In11.Cu")
		(net "P5E_CPU0_P1_RX_DP<4>")
	)
	(segment
		(start 349.300292 -278.2189)
		(end 349.383096 -278.136096)
		(width 0.1143)
		(layer "In11.Cu")
		(net "P5E_CPU0_P1_RX_DP<4>")
	)
	(segment
		(start 337.218274 -380.340616)
		(end 337.218274 -376.55119)
		(width 0.14224)
		(layer "In11.Cu")
		(net "P5E_CPU0_P1_RX_DP<4>")
	)
	(segment
		(start 348.992444 -281.881834)
		(end 349.024194 -281.863546)
		(width 0.1143)
		(layer "In11.Cu")
		(net "P5E_CPU0_P1_RX_DP<4>")
	)
	(segment
		(start 349.020892 -287.366456)
		(end 349.019368 -287.365694)
		(width 0.1143)
		(layer "In11.Cu")
		(net "P5E_CPU0_P1_RX_DP<4>")
	)
	(segment
		(start 349.024194 -281.863546)
		(end 349.058992 -281.84348)
		(width 0.1143)
		(layer "In11.Cu")
		(net "P5E_CPU0_P1_RX_DP<4>")
	)
	(segment
		(start 349.023432 -292.228016)
		(end 348.992444 -292.210236)
		(width 0.1143)
		(layer "In11.Cu")
		(net "P5E_CPU0_P1_RX_DP<4>")
	)
	(segment
		(start 349.023432 -291.583872)
		(end 349.024194 -291.583364)
		(width 0.1143)
		(layer "In11.Cu")
		(net "P5E_CPU0_P1_RX_DP<4>")
	)
	(segment
		(start 349.060516 -290.629594)
		(end 349.024194 -290.608512)
		(width 0.1143)
		(layer "In11.Cu")
		(net "P5E_CPU0_P1_RX_DP<4>")
	)
	(segment
		(start 349.022162 -289.964622)
		(end 349.023432 -289.96386)
		(width 0.1143)
		(layer "In11.Cu")
		(net "P5E_CPU0_P1_RX_DP<4>")
	)
	(segment
		(start 349.023432 -290.608004)
		(end 348.992444 -290.590224)
		(width 0.1143)
		(layer "In11.Cu")
		(net "P5E_CPU0_P1_RX_DP<4>")
	)
	(segment
		(start 348.361508 -295.875456)
		(end 348.836488 -295.400476)
		(width 0.1143)
		(layer "In11.Cu")
		(net "P5E_CPU0_P1_RX_DP<4>")
	)
	(segment
		(start 349.019368 -287.365694)
		(end 349.018606 -287.365186)
		(width 0.1143)
		(layer "In11.Cu")
		(net "P5E_CPU0_P1_RX_DP<4>")
	)
	(segment
		(start 348.992444 -289.98164)
		(end 349.022162 -289.964622)
		(width 0.1143)
		(layer "In11.Cu")
		(net "P5E_CPU0_P1_RX_DP<4>")
	)
	(segment
		(start 349.024194 -285.10357)
		(end 349.060516 -285.082488)
		(width 0.1143)
		(layer "In11.Cu")
		(net "P5E_CPU0_P1_RX_DP<4>")
	)
	(segment
		(start 349.060516 -292.249606)
		(end 349.024194 -292.228524)
		(width 0.1143)
		(layer "In11.Cu")
		(net "P5E_CPU0_P1_RX_DP<4>")
	)
	(segment
		(start 349.024194 -288.9885)
		(end 349.023432 -288.987992)
		(width 0.1143)
		(layer "In11.Cu")
		(net "P5E_CPU0_P1_RX_DP<4>")
	)
	(segment
		(start 349.024194 -288.343594)
		(end 349.060516 -288.322512)
		(width 0.1143)
		(layer "In11.Cu")
		(net "P5E_CPU0_P1_RX_DP<4>")
	)
	(segment
		(start 341.876126 -393.842494)
		(end 341.876126 -393.428982)
		(width 0.14224)
		(layer "In11.Cu")
		(net "P5E_CPU0_P1_RX_DP<4>")
	)
	(segment
		(start 349.01759 -285.74492)
		(end 348.992444 -285.730442)
		(width 0.1143)
		(layer "In11.Cu")
		(net "P5E_CPU0_P1_RX_DP<4>")
	)
	(segment
		(start 341.56015 -393.113006)
		(end 341.563198 -392.7348)
		(width 0.14224)
		(layer "In11.Cu")
		(net "P5E_CPU0_P1_RX_DP<4>")
	)
	(segment
		(start 368.750088 -339.955886)
		(end 366.696244 -328.528426)
		(width 0.14224)
		(layer "In11.Cu")
		(net "P5E_CPU0_P1_RX_DP<4>")
	)
	(segment
		(start 341.518748 -394.385292)
		(end 341.613744 -394.031216)
		(width 0.14224)
		(layer "In11.Cu")
		(net "P5E_CPU0_P1_RX_DP<4>")
	)
	(segment
		(start 341.876126 -393.428982)
		(end 341.56015 -393.113006)
		(width 0.14224)
		(layer "In11.Cu")
		(net "P5E_CPU0_P1_RX_DP<4>")
	)
	(segment
		(start 349.024194 -293.203376)
		(end 349.060516 -293.182294)
		(width 0.1143)
		(layer "In11.Cu")
		(net "P5E_CPU0_P1_RX_DP<4>")
	)
	(segment
		(start 349.019368 -285.745936)
		(end 349.018606 -285.745428)
		(width 0.1143)
		(layer "In11.Cu")
		(net "P5E_CPU0_P1_RX_DP<4>")
	)
	(segment
		(start 349.058992 -281.84348)
		(end 349.060516 -281.842464)
		(width 0.1143)
		(layer "In11.Cu")
		(net "P5E_CPU0_P1_RX_DP<4>")
	)
	(arc
		(start 348.992444 -280.870406)
		(mid 348.877768 -280.737072)
		(end 348.836488 -280.566114)
		(width 0.1143)
		(layer "In11.Cu")
		(net "P5E_CPU0_P1_RX_DP<4>")
	)
	(arc
		(start 348.992444 -290.590224)
		(mid 348.836516 -290.285932)
		(end 348.992444 -289.98164)
		(width 0.1143)
		(layer "In11.Cu")
		(net "P5E_CPU0_P1_RX_DP<4>")
	)
	(arc
		(start 337.255612 -380.430532)
		(mid 337.227993 -380.389292)
		(end 337.218274 -380.340616)
		(width 0.14224)
		(layer "In11.Cu")
		(net "P5E_CPU0_P1_RX_DP<4>")
	)
	(arc
		(start 348.836488 -280.566114)
		(mid 348.771973 -280.303895)
		(end 348.593156 -280.101548)
		(width 0.1143)
		(layer "In11.Cu")
		(net "P5E_CPU0_P1_RX_DP<4>")
	)
	(arc
		(start 349.076772 -284.16123)
		(mid 349.068694 -284.155444)
		(end 349.060516 -284.1498)
		(width 0.1143)
		(layer "In11.Cu")
		(net "P5E_CPU0_P1_RX_DP<4>")
	)
	(arc
		(start 349.07474 -292.259512)
		(mid 349.067667 -292.254503)
		(end 349.060516 -292.249606)
		(width 0.1143)
		(layer "In11.Cu")
		(net "P5E_CPU0_P1_RX_DP<4>")
	)
	(arc
		(start 349.07474 -291.552376)
		(mid 349.302123 -291.095938)
		(end 349.07474 -290.6395)
		(width 0.1143)
		(layer "In11.Cu")
		(net "P5E_CPU0_P1_RX_DP<4>")
	)
	(arc
		(start 349.078042 -294.790114)
		(mid 349.302491 -294.332609)
		(end 349.072708 -293.877746)
		(width 0.1143)
		(layer "In11.Cu")
		(net "P5E_CPU0_P1_RX_DP<4>")
	)
	(arc
		(start 349.07474 -290.6395)
		(mid 349.067667 -290.634491)
		(end 349.060516 -290.629594)
		(width 0.1143)
		(layer "In11.Cu")
		(net "P5E_CPU0_P1_RX_DP<4>")
	)
	(arc
		(start 338.7598 -381.353314)
		(mid 338.697746 -381.302342)
		(end 338.626958 -381.264414)
		(width 0.14224)
		(layer "In11.Cu")
		(net "P5E_CPU0_P1_RX_DP<4>")
	)
	(arc
		(start 349.060516 -285.082488)
		(mid 349.068694 -285.076845)
		(end 349.076772 -285.071058)
		(width 0.1143)
		(layer "In11.Cu")
		(net "P5E_CPU0_P1_RX_DP<4>")
	)
	(arc
		(start 361.653582 -357.736902)
		(mid 365.256422 -353.346808)
		(end 367.933478 -348.33814)
		(width 0.14224)
		(layer "In11.Cu")
		(net "P5E_CPU0_P1_RX_DP<4>")
	)
	(arc
		(start 337.732878 -380.894082)
		(mid 337.710968 -380.882372)
		(end 337.69173 -380.86665)
		(width 0.14224)
		(layer "In11.Cu")
		(net "P5E_CPU0_P1_RX_DP<4>")
	)
	(arc
		(start 349.076772 -289.021012)
		(mid 349.068694 -289.015226)
		(end 349.060516 -289.009582)
		(width 0.1143)
		(layer "In11.Cu")
		(net "P5E_CPU0_P1_RX_DP<4>")
	)
	(arc
		(start 349.07474 -293.172388)
		(mid 349.302123 -292.71595)
		(end 349.07474 -292.259512)
		(width 0.1143)
		(layer "In11.Cu")
		(net "P5E_CPU0_P1_RX_DP<4>")
	)
	(arc
		(start 348.992444 -282.490418)
		(mid 348.836516 -282.186126)
		(end 348.992444 -281.881834)
		(width 0.1143)
		(layer "In11.Cu")
		(net "P5E_CPU0_P1_RX_DP<4>")
	)
	(arc
		(start 348.836488 -288.66592)
		(mid 348.87725 -288.496036)
		(end 348.990666 -288.363152)
		(width 0.1143)
		(layer "In11.Cu")
		(net "P5E_CPU0_P1_RX_DP<4>")
	)
	(arc
		(start 349.0722 -282.537916)
		(mid 349.066384 -282.533815)
		(end 349.060516 -282.529788)
		(width 0.1143)
		(layer "In11.Cu")
		(net "P5E_CPU0_P1_RX_DP<4>")
	)
	(arc
		(start 349.0722 -283.454348)
		(mid 349.305117 -282.996132)
		(end 349.0722 -282.537916)
		(width 0.1143)
		(layer "In11.Cu")
		(net "P5E_CPU0_P1_RX_DP<4>")
	)
	(arc
		(start 349.060516 -288.322512)
		(mid 349.241168 -288.119767)
		(end 349.306388 -287.856168)
		(width 0.1143)
		(layer "In11.Cu")
		(net "P5E_CPU0_P1_RX_DP<4>")
	)
	(arc
		(start 339.564218 -382.226058)
		(mid 339.52354 -382.134419)
		(end 339.461856 -382.05537)
		(width 0.14224)
		(layer "In11.Cu")
		(net "P5E_CPU0_P1_RX_DP<4>")
	)
	(arc
		(start 349.060516 -293.182294)
		(mid 349.067666 -293.177396)
		(end 349.07474 -293.172388)
		(width 0.1143)
		(layer "In11.Cu")
		(net "P5E_CPU0_P1_RX_DP<4>")
	)
	(arc
		(start 348.992444 -285.730442)
		(mid 348.836516 -285.42615)
		(end 348.992444 -285.121858)
		(width 0.1143)
		(layer "In11.Cu")
		(net "P5E_CPU0_P1_RX_DP<4>")
	)
	(arc
		(start 348.992444 -284.11043)
		(mid 348.836516 -283.806138)
		(end 348.992444 -283.501846)
		(width 0.1143)
		(layer "In11.Cu")
		(net "P5E_CPU0_P1_RX_DP<4>")
	)
	(arc
		(start 346.093796 -371.409722)
		(mid 349.124459 -369.78973)
		(end 351.780856 -367.609628)
		(width 0.14224)
		(layer "In11.Cu")
		(net "P5E_CPU0_P1_RX_DP<4>")
	)
	(arc
		(start 337.218274 -376.55119)
		(mid 337.247987 -376.401903)
		(end 337.332574 -376.275346)
		(width 0.14224)
		(layer "In11.Cu")
		(net "P5E_CPU0_P1_RX_DP<4>")
	)
	(arc
		(start 349.060516 -281.842464)
		(mid 349.067665 -281.837564)
		(end 349.07474 -281.832558)
		(width 0.1143)
		(layer "In11.Cu")
		(net "P5E_CPU0_P1_RX_DP<4>")
	)
	(arc
		(start 348.52356 -280.060908)
		(mid 348.366583 -279.756108)
		(end 348.52356 -279.451308)
		(width 0.1143)
		(layer "In11.Cu")
		(net "P5E_CPU0_P1_RX_DP<4>")
	)
	(arc
		(start 348.836488 -295.145968)
		(mid 348.877743 -294.974997)
		(end 348.992444 -294.841676)
		(width 0.1143)
		(layer "In11.Cu")
		(net "P5E_CPU0_P1_RX_DP<4>")
	)
	(arc
		(start 349.060516 -283.462476)
		(mid 349.066384 -283.458449)
		(end 349.0722 -283.454348)
		(width 0.1143)
		(layer "In11.Cu")
		(net "P5E_CPU0_P1_RX_DP<4>")
	)
	(arc
		(start 348.992444 -287.3502)
		(mid 348.877768 -287.216866)
		(end 348.836488 -287.045908)
		(width 0.1143)
		(layer "In11.Cu")
		(net "P5E_CPU0_P1_RX_DP<4>")
	)
	(arc
		(start 349.060516 -289.94227)
		(mid 349.068694 -289.936627)
		(end 349.076772 -289.93084)
		(width 0.1143)
		(layer "In11.Cu")
		(net "P5E_CPU0_P1_RX_DP<4>")
	)
	(arc
		(start 348.836488 -287.045908)
		(mid 348.87725 -286.876024)
		(end 348.990666 -286.74314)
		(width 0.1143)
		(layer "In11.Cu")
		(net "P5E_CPU0_P1_RX_DP<4>")
	)
	(arc
		(start 349.076772 -285.071058)
		(mid 349.299656 -284.616144)
		(end 349.076772 -284.16123)
		(width 0.1143)
		(layer "In11.Cu")
		(net "P5E_CPU0_P1_RX_DP<4>")
	)
	(arc
		(start 348.836234 -278.946102)
		(mid 348.88514 -278.762643)
		(end 349.01886 -278.62784)
		(width 0.1143)
		(layer "In11.Cu")
		(net "P5E_CPU0_P1_RX_DP<4>")
	)
	(arc
		(start 349.024956 -286.723074)
		(mid 349.30529 -286.236156)
		(end 349.024956 -285.749238)
		(width 0.1143)
		(layer "In11.Cu")
		(net "P5E_CPU0_P1_RX_DP<4>")
	)
	(arc
		(start 349.306388 -287.856168)
		(mid 349.230886 -287.574916)
		(end 349.024702 -287.36925)
		(width 0.1143)
		(layer "In11.Cu")
		(net "P5E_CPU0_P1_RX_DP<4>")
	)
	(arc
		(start 349.07474 -281.832558)
		(mid 349.302123 -281.37612)
		(end 349.07474 -280.919682)
		(width 0.1143)
		(layer "In11.Cu")
		(net "P5E_CPU0_P1_RX_DP<4>")
	)
	(arc
		(start 338.460842 -375.147078)
		(mid 339.519125 -374.278465)
		(end 340.726522 -373.632984)
		(width 0.14224)
		(layer "In11.Cu")
		(net "P5E_CPU0_P1_RX_DP<4>")
	)
	(arc
		(start 348.992444 -293.830248)
		(mid 348.836516 -293.525956)
		(end 348.992444 -293.221664)
		(width 0.1143)
		(layer "In11.Cu")
		(net "P5E_CPU0_P1_RX_DP<4>")
	)
	(arc
		(start 349.060516 -291.562282)
		(mid 349.067666 -291.557384)
		(end 349.07474 -291.552376)
		(width 0.1143)
		(layer "In11.Cu")
		(net "P5E_CPU0_P1_RX_DP<4>")
	)
	(arc
		(start 349.024702 -278.624538)
		(mid 349.208915 -278.45326)
		(end 349.300292 -278.2189)
		(width 0.1143)
		(layer "In11.Cu")
		(net "P5E_CPU0_P1_RX_DP<4>")
	)
	(arc
		(start 349.076772 -289.93084)
		(mid 349.299656 -289.475926)
		(end 349.076772 -289.021012)
		(width 0.1143)
		(layer "In11.Cu")
		(net "P5E_CPU0_P1_RX_DP<4>")
	)
	(arc
		(start 348.591632 -279.411684)
		(mid 348.771424 -279.209096)
		(end 348.836234 -278.946102)
		(width 0.1143)
		(layer "In11.Cu")
		(net "P5E_CPU0_P1_RX_DP<4>")
	)
	(arc
		(start 341.867998 -390.035796)
		(mid 341.852268 -389.821644)
		(end 341.80526 -389.612124)
		(width 0.14224)
		(layer "In11.Cu")
		(net "P5E_CPU0_P1_RX_DP<4>")
	)
	(arc
		(start 348.992444 -292.210236)
		(mid 348.836516 -291.905944)
		(end 348.992444 -291.601652)
		(width 0.1143)
		(layer "In11.Cu")
		(net "P5E_CPU0_P1_RX_DP<4>")
	)
	(arc
		(start 348.992444 -288.970212)
		(mid 348.877768 -288.836878)
		(end 348.836488 -288.66592)
		(width 0.1143)
		(layer "In11.Cu")
		(net "P5E_CPU0_P1_RX_DP<4>")
	)
	(arc
		(start 349.07474 -280.919682)
		(mid 349.067666 -280.914675)
		(end 349.060516 -280.909776)
		(width 0.1143)
		(layer "In11.Cu")
		(net "P5E_CPU0_P1_RX_DP<4>")
	)
	(segment
		(start 339.798152 -394.385292)
		(end 340.318852 -394.385292)
		(width 0.127)
		(layer "F.Cu")
		(net "P5E_CPU0_P1_RX_DP<3>")
	)
	(segment
		(start 350.14789 -276.250146)
		(end 349.681038 -276.516084)
		(width 0.12954)
		(layer "F.Cu")
		(net "P5E_CPU0_P1_RX_DP<3>")
	)
	(segment
		(start 348.088458 -293.851076)
		(end 348.086934 -293.85006)
		(width 0.1143)
		(layer "In11.Cu")
		(net "P5E_CPU0_P1_RX_DP<3>")
	)
	(segment
		(start 348.090998 -282.51277)
		(end 348.089474 -282.511754)
		(width 0.1143)
		(layer "In11.Cu")
		(net "P5E_CPU0_P1_RX_DP<3>")
	)
	(segment
		(start 348.083378 -291.583872)
		(end 348.08414 -291.583364)
		(width 0.1143)
		(layer "In11.Cu")
		(net "P5E_CPU0_P1_RX_DP<3>")
	)
	(segment
		(start 348.088458 -292.231064)
		(end 348.086934 -292.230048)
		(width 0.1143)
		(layer "In11.Cu")
		(net "P5E_CPU0_P1_RX_DP<3>")
	)
	(segment
		(start 348.076266 -285.744158)
		(end 348.073726 -285.742888)
		(width 0.1143)
		(layer "In11.Cu")
		(net "P5E_CPU0_P1_RX_DP<3>")
	)
	(segment
		(start 348.52356 -277.831296)
		(end 348.55404 -277.813516)
		(width 0.1143)
		(layer "In11.Cu")
		(net "P5E_CPU0_P1_RX_DP<3>")
	)
	(segment
		(start 348.07779 -285.107126)
		(end 348.079822 -285.10611)
		(width 0.1143)
		(layer "In11.Cu")
		(net "P5E_CPU0_P1_RX_DP<3>")
	)
	(segment
		(start 348.07779 -281.867102)
		(end 348.079822 -281.866086)
		(width 0.1143)
		(layer "In11.Cu")
		(net "P5E_CPU0_P1_RX_DP<3>")
	)
	(segment
		(start 348.07779 -278.627078)
		(end 348.079822 -278.626062)
		(width 0.1143)
		(layer "In11.Cu")
		(net "P5E_CPU0_P1_RX_DP<3>")
	)
	(segment
		(start 348.08414 -293.848536)
		(end 348.083378 -293.848028)
		(width 0.1143)
		(layer "In11.Cu")
		(net "P5E_CPU0_P1_RX_DP<3>")
	)
	(segment
		(start 348.088458 -282.511246)
		(end 348.086934 -282.51023)
		(width 0.1143)
		(layer "In11.Cu")
		(net "P5E_CPU0_P1_RX_DP<3>")
	)
	(segment
		(start 348.079822 -285.10611)
		(end 348.080584 -285.105602)
		(width 0.1143)
		(layer "In11.Cu")
		(net "P5E_CPU0_P1_RX_DP<3>")
	)
	(segment
		(start 348.08414 -294.823388)
		(end 348.085156 -294.82288)
		(width 0.1143)
		(layer "In11.Cu")
		(net "P5E_CPU0_P1_RX_DP<3>")
	)
	(segment
		(start 348.085156 -292.229032)
		(end 348.08414 -292.228524)
		(width 0.1143)
		(layer "In11.Cu")
		(net "P5E_CPU0_P1_RX_DP<3>")
	)
	(segment
		(start 348.079822 -291.585904)
		(end 348.080584 -291.585396)
		(width 0.1143)
		(layer "In11.Cu")
		(net "P5E_CPU0_P1_RX_DP<3>")
	)
	(segment
		(start 348.090998 -285.752794)
		(end 348.089474 -285.751778)
		(width 0.1143)
		(layer "In11.Cu")
		(net "P5E_CPU0_P1_RX_DP<3>")
	)
	(segment
		(start 348.08414 -278.623522)
		(end 348.085156 -278.623014)
		(width 0.1143)
		(layer "In11.Cu")
		(net "P5E_CPU0_P1_RX_DP<3>")
	)
	(segment
		(start 348.078298 -282.505404)
		(end 348.077536 -282.504896)
		(width 0.1143)
		(layer "In11.Cu")
		(net "P5E_CPU0_P1_RX_DP<3>")
	)
	(segment
		(start 348.080584 -278.625554)
		(end 348.083378 -278.62403)
		(width 0.1143)
		(layer "In11.Cu")
		(net "P5E_CPU0_P1_RX_DP<3>")
	)
	(segment
		(start 347.613986 -279.433528)
		(end 347.653102 -279.410668)
		(width 0.1143)
		(layer "In11.Cu")
		(net "P5E_CPU0_P1_RX_DP<3>")
	)
	(segment
		(start 348.083378 -293.848028)
		(end 348.082108 -293.847266)
		(width 0.1143)
		(layer "In11.Cu")
		(net "P5E_CPU0_P1_RX_DP<3>")
	)
	(segment
		(start 348.08668 -278.621998)
		(end 348.123256 -278.600662)
		(width 0.1143)
		(layer "In11.Cu")
		(net "P5E_CPU0_P1_RX_DP<3>")
	)
	(segment
		(start 348.089474 -290.61156)
		(end 348.088458 -290.611052)
		(width 0.1143)
		(layer "In11.Cu")
		(net "P5E_CPU0_P1_RX_DP<3>")
	)
	(segment
		(start 348.086934 -293.85006)
		(end 348.085156 -293.849044)
		(width 0.1143)
		(layer "In11.Cu")
		(net "P5E_CPU0_P1_RX_DP<3>")
	)
	(segment
		(start 348.08414 -288.343594)
		(end 348.123256 -288.320734)
		(width 0.1143)
		(layer "In11.Cu")
		(net "P5E_CPU0_P1_RX_DP<3>")
	)
	(segment
		(start 348.079822 -280.886154)
		(end 348.078298 -280.885392)
		(width 0.1143)
		(layer "In11.Cu")
		(net "P5E_CPU0_P1_RX_DP<3>")
	)
	(segment
		(start 348.085156 -288.989008)
		(end 348.08414 -288.9885)
		(width 0.1143)
		(layer "In11.Cu")
		(net "P5E_CPU0_P1_RX_DP<3>")
	)
	(segment
		(start 347.472508 -299.120814)
		(end 347.472508 -296.46372)
		(width 0.14224)
		(layer "In11.Cu")
		(net "P5E_CPU0_P1_RX_DP<3>")
	)
	(segment
		(start 348.080584 -285.746698)
		(end 348.079822 -285.74619)
		(width 0.1143)
		(layer "In11.Cu")
		(net "P5E_CPU0_P1_RX_DP<3>")
	)
	(segment
		(start 348.080584 -282.506674)
		(end 348.079822 -282.506166)
		(width 0.1143)
		(layer "In11.Cu")
		(net "P5E_CPU0_P1_RX_DP<3>")
	)
	(segment
		(start 348.085156 -294.82288)
		(end 348.123256 -294.800528)
		(width 0.1143)
		(layer "In11.Cu")
		(net "P5E_CPU0_P1_RX_DP<3>")
	)
	(segment
		(start 348.05239 -285.121858)
		(end 348.07779 -285.107126)
		(width 0.1143)
		(layer "In11.Cu")
		(net "P5E_CPU0_P1_RX_DP<3>")
	)
	(segment
		(start 348.073726 -280.882852)
		(end 348.05239 -280.870406)
		(width 0.1143)
		(layer "In11.Cu")
		(net "P5E_CPU0_P1_RX_DP<3>")
	)
	(segment
		(start 357.944166 -318.377062)
		(end 351.37852 -308.551326)
		(width 0.14224)
		(layer "In11.Cu")
		(net "P5E_CPU0_P1_RX_DP<3>")
	)
	(segment
		(start 348.076266 -280.884122)
		(end 348.073726 -280.882852)
		(width 0.1143)
		(layer "In11.Cu")
		(net "P5E_CPU0_P1_RX_DP<3>")
	)
	(segment
		(start 348.083378 -282.508198)
		(end 348.080584 -282.506674)
		(width 0.1143)
		(layer "In11.Cu")
		(net "P5E_CPU0_P1_RX_DP<3>")
	)
	(segment
		(start 348.088458 -290.611052)
		(end 348.086934 -290.610036)
		(width 0.1143)
		(layer "In11.Cu")
		(net "P5E_CPU0_P1_RX_DP<3>")
	)
	(segment
		(start 348.073726 -285.742888)
		(end 348.05239 -285.730442)
		(width 0.1143)
		(layer "In11.Cu")
		(net "P5E_CPU0_P1_RX_DP<3>")
	)
	(segment
		(start 348.079822 -281.866086)
		(end 348.080584 -281.865578)
		(width 0.1143)
		(layer "In11.Cu")
		(net "P5E_CPU0_P1_RX_DP<3>")
	)
	(segment
		(start 348.123256 -289.01136)
		(end 348.116398 -289.007296)
		(width 0.1143)
		(layer "In11.Cu")
		(net "P5E_CPU0_P1_RX_DP<3>")
	)
	(segment
		(start 348.085156 -293.202868)
		(end 348.08668 -293.201852)
		(width 0.1143)
		(layer "In11.Cu")
		(net "P5E_CPU0_P1_RX_DP<3>")
	)
	(segment
		(start 348.07779 -289.966908)
		(end 348.079822 -289.965892)
		(width 0.1143)
		(layer "In11.Cu")
		(net "P5E_CPU0_P1_RX_DP<3>")
	)
	(segment
		(start 365.802164 -328.840846)
		(end 364.533942 -326.406764)
		(width 0.14224)
		(layer "In11.Cu")
		(net "P5E_CPU0_P1_RX_DP<3>")
	)
	(segment
		(start 347.426788 -295.948354)
		(end 347.89618 -295.478962)
		(width 0.1143)
		(layer "In11.Cu")
		(net "P5E_CPU0_P1_RX_DP<3>")
	)
	(segment
		(start 347.613986 -280.078688)
		(end 347.583506 -280.060908)
		(width 0.1143)
		(layer "In11.Cu")
		(net "P5E_CPU0_P1_RX_DP<3>")
	)
	(segment
		(start 348.079822 -293.205916)
		(end 348.080584 -293.205408)
		(width 0.1143)
		(layer "In11.Cu")
		(net "P5E_CPU0_P1_RX_DP<3>")
	)
	(segment
		(start 335.519014 -382.405636)
		(end 335.519014 -377.081542)
		(width 0.14224)
		(layer "In11.Cu")
		(net "P5E_CPU0_P1_RX_DP<3>")
	)
	(segment
		(start 348.07779 -293.206932)
		(end 348.079822 -293.205916)
		(width 0.1143)
		(layer "In11.Cu")
		(net "P5E_CPU0_P1_RX_DP<3>")
	)
	(segment
		(start 348.116398 -289.007296)
		(end 348.115636 -289.006788)
		(width 0.1143)
		(layer "In11.Cu")
		(net "P5E_CPU0_P1_RX_DP<3>")
	)
	(segment
		(start 348.08414 -290.608512)
		(end 348.083378 -290.608004)
		(width 0.1143)
		(layer "In11.Cu")
		(net "P5E_CPU0_P1_RX_DP<3>")
	)
	(segment
		(start 348.08668 -291.58184)
		(end 348.123256 -291.560504)
		(width 0.1143)
		(layer "In11.Cu")
		(net "P5E_CPU0_P1_RX_DP<3>")
	)
	(segment
		(start 348.083378 -285.748222)
		(end 348.080584 -285.746698)
		(width 0.1143)
		(layer "In11.Cu")
		(net "P5E_CPU0_P1_RX_DP<3>")
	)
	(segment
		(start 348.083378 -285.104078)
		(end 348.08414 -285.10357)
		(width 0.1143)
		(layer "In11.Cu")
		(net "P5E_CPU0_P1_RX_DP<3>")
	)
	(segment
		(start 348.083378 -280.888186)
		(end 348.080584 -280.886662)
		(width 0.1143)
		(layer "In11.Cu")
		(net "P5E_CPU0_P1_RX_DP<3>")
	)
	(segment
		(start 348.076266 -284.124146)
		(end 348.073726 -284.122876)
		(width 0.1143)
		(layer "In11.Cu")
		(net "P5E_CPU0_P1_RX_DP<3>")
	)
	(segment
		(start 348.05239 -293.221664)
		(end 348.07779 -293.206932)
		(width 0.1143)
		(layer "In11.Cu")
		(net "P5E_CPU0_P1_RX_DP<3>")
	)
	(segment
		(start 348.080584 -281.865578)
		(end 348.083378 -281.864054)
		(width 0.1143)
		(layer "In11.Cu")
		(net "P5E_CPU0_P1_RX_DP<3>")
	)
	(segment
		(start 348.115636 -284.147006)
		(end 348.090998 -284.132782)
		(width 0.1143)
		(layer "In11.Cu")
		(net "P5E_CPU0_P1_RX_DP<3>")
	)
	(segment
		(start 348.55404 -277.813516)
		(end 348.593156 -277.790656)
		(width 0.1143)
		(layer "In11.Cu")
		(net "P5E_CPU0_P1_RX_DP<3>")
	)
	(segment
		(start 348.08414 -291.583364)
		(end 348.085156 -291.582856)
		(width 0.1143)
		(layer "In11.Cu")
		(net "P5E_CPU0_P1_RX_DP<3>")
	)
	(segment
		(start 348.115636 -290.6268)
		(end 348.090998 -290.612576)
		(width 0.1143)
		(layer "In11.Cu")
		(net "P5E_CPU0_P1_RX_DP<3>")
	)
	(segment
		(start 367.813844 -340.031578)
		(end 366.809528 -334.444848)
		(width 0.14224)
		(layer "In11.Cu")
		(net "P5E_CPU0_P1_RX_DP<3>")
	)
	(segment
		(start 348.116398 -280.90749)
		(end 348.115636 -280.906982)
		(width 0.1143)
		(layer "In11.Cu")
		(net "P5E_CPU0_P1_RX_DP<3>")
	)
	(segment
		(start 348.116398 -293.867332)
		(end 348.115636 -293.866824)
		(width 0.1143)
		(layer "In11.Cu")
		(net "P5E_CPU0_P1_RX_DP<3>")
	)
	(segment
		(start 348.116398 -290.627308)
		(end 348.115636 -290.6268)
		(width 0.1143)
		(layer "In11.Cu")
		(net "P5E_CPU0_P1_RX_DP<3>")
	)
	(segment
		(start 348.085156 -289.962844)
		(end 348.08668 -289.961828)
		(width 0.1143)
		(layer "In11.Cu")
		(net "P5E_CPU0_P1_RX_DP<3>")
	)
	(segment
		(start 348.090998 -290.612576)
		(end 348.089474 -290.61156)
		(width 0.1143)
		(layer "In11.Cu")
		(net "P5E_CPU0_P1_RX_DP<3>")
	)
	(segment
		(start 348.123256 -292.251384)
		(end 348.116398 -292.24732)
		(width 0.1143)
		(layer "In11.Cu")
		(net "P5E_CPU0_P1_RX_DP<3>")
	)
	(segment
		(start 348.090998 -288.992564)
		(end 348.089474 -288.991548)
		(width 0.1143)
		(layer "In11.Cu")
		(net "P5E_CPU0_P1_RX_DP<3>")
	)
	(segment
		(start 348.085156 -285.103062)
		(end 348.08668 -285.102046)
		(width 0.1143)
		(layer "In11.Cu")
		(net "P5E_CPU0_P1_RX_DP<3>")
	)
	(segment
		(start 348.08414 -285.10357)
		(end 348.085156 -285.103062)
		(width 0.1143)
		(layer "In11.Cu")
		(net "P5E_CPU0_P1_RX_DP<3>")
	)
	(segment
		(start 348.088458 -280.891234)
		(end 348.086934 -280.890218)
		(width 0.1143)
		(layer "In11.Cu")
		(net "P5E_CPU0_P1_RX_DP<3>")
	)
	(segment
		(start 347.583506 -279.451308)
		(end 347.613986 -279.433528)
		(width 0.1143)
		(layer "In11.Cu")
		(net "P5E_CPU0_P1_RX_DP<3>")
	)
	(segment
		(start 348.116398 -285.767526)
		(end 348.115636 -285.767018)
		(width 0.1143)
		(layer "In11.Cu")
		(net "P5E_CPU0_P1_RX_DP<3>")
	)
	(segment
		(start 348.085156 -284.129226)
		(end 348.08414 -284.128718)
		(width 0.1143)
		(layer "In11.Cu")
		(net "P5E_CPU0_P1_RX_DP<3>")
	)
	(segment
		(start 351.119694 -366.65027)
		(end 361.253786 -356.516178)
		(width 0.14224)
		(layer "In11.Cu")
		(net "P5E_CPU0_P1_RX_DP<3>")
	)
	(segment
		(start 348.085156 -281.863038)
		(end 348.08668 -281.862022)
		(width 0.1143)
		(layer "In11.Cu")
		(net "P5E_CPU0_P1_RX_DP<3>")
	)
	(segment
		(start 348.090998 -284.132782)
		(end 348.089474 -284.131766)
		(width 0.1143)
		(layer "In11.Cu")
		(net "P5E_CPU0_P1_RX_DP<3>")
	)
	(segment
		(start 348.08414 -284.128718)
		(end 348.083378 -284.12821)
		(width 0.1143)
		(layer "In11.Cu")
		(net "P5E_CPU0_P1_RX_DP<3>")
	)
	(segment
		(start 348.079822 -282.506166)
		(end 348.078298 -282.505404)
		(width 0.1143)
		(layer "In11.Cu")
		(net "P5E_CPU0_P1_RX_DP<3>")
	)
	(segment
		(start 348.08414 -282.508706)
		(end 348.083378 -282.508198)
		(width 0.1143)
		(layer "In11.Cu")
		(net "P5E_CPU0_P1_RX_DP<3>")
	)
	(segment
		(start 348.083378 -290.608004)
		(end 348.082108 -290.607242)
		(width 0.1143)
		(layer "In11.Cu")
		(net "P5E_CPU0_P1_RX_DP<3>")
	)
	(segment
		(start 348.088458 -288.99104)
		(end 348.086934 -288.990024)
		(width 0.1143)
		(layer "In11.Cu")
		(net "P5E_CPU0_P1_RX_DP<3>")
	)
	(segment
		(start 348.120716 -287.389824)
		(end 348.08414 -287.368488)
		(width 0.1143)
		(layer "In11.Cu")
		(net "P5E_CPU0_P1_RX_DP<3>")
	)
	(segment
		(start 348.088458 -285.75127)
		(end 348.086934 -285.750254)
		(width 0.1143)
		(layer "In11.Cu")
		(net "P5E_CPU0_P1_RX_DP<3>")
	)
	(segment
		(start 348.08414 -281.863546)
		(end 348.085156 -281.863038)
		(width 0.1143)
		(layer "In11.Cu")
		(net "P5E_CPU0_P1_RX_DP<3>")
	)
	(segment
		(start 348.082108 -292.227254)
		(end 348.05239 -292.210236)
		(width 0.1143)
		(layer "In11.Cu")
		(net "P5E_CPU0_P1_RX_DP<3>")
	)
	(segment
		(start 348.123256 -280.911554)
		(end 348.116398 -280.90749)
		(width 0.1143)
		(layer "In11.Cu")
		(net "P5E_CPU0_P1_RX_DP<3>")
	)
	(segment
		(start 348.08668 -293.201852)
		(end 348.123256 -293.180516)
		(width 0.1143)
		(layer "In11.Cu")
		(net "P5E_CPU0_P1_RX_DP<3>")
	)
	(segment
		(start 348.07779 -283.487114)
		(end 348.079822 -283.486098)
		(width 0.1143)
		(layer "In11.Cu")
		(net "P5E_CPU0_P1_RX_DP<3>")
	)
	(segment
		(start 340.67623 -393.842494)
		(end 340.67623 -393.428982)
		(width 0.14224)
		(layer "In11.Cu")
		(net "P5E_CPU0_P1_RX_DP<3>")
	)
	(segment
		(start 348.992444 -277.021798)
		(end 349.02775 -277.001478)
		(width 0.1143)
		(layer "In11.Cu")
		(net "P5E_CPU0_P1_RX_DP<3>")
	)
	(segment
		(start 348.089474 -282.511754)
		(end 348.088458 -282.511246)
		(width 0.1143)
		(layer "In11.Cu")
		(net "P5E_CPU0_P1_RX_DP<3>")
	)
	(segment
		(start 348.077536 -280.884884)
		(end 348.076266 -280.884122)
		(width 0.1143)
		(layer "In11.Cu")
		(net "P5E_CPU0_P1_RX_DP<3>")
	)
	(segment
		(start 367.813844 -345.347798)
		(end 367.813844 -340.031578)
		(width 0.14224)
		(layer "In11.Cu")
		(net "P5E_CPU0_P1_RX_DP<3>")
	)
	(segment
		(start 348.07779 -291.58692)
		(end 348.079822 -291.585904)
		(width 0.1143)
		(layer "In11.Cu")
		(net "P5E_CPU0_P1_RX_DP<3>")
	)
	(segment
		(start 348.05239 -281.881834)
		(end 348.07779 -281.867102)
		(width 0.1143)
		(layer "In11.Cu")
		(net "P5E_CPU0_P1_RX_DP<3>")
	)
	(segment
		(start 348.083378 -284.12821)
		(end 348.080584 -284.126686)
		(width 0.1143)
		(layer "In11.Cu")
		(net "P5E_CPU0_P1_RX_DP<3>")
	)
	(segment
		(start 348.079822 -283.486098)
		(end 348.080584 -283.48559)
		(width 0.1143)
		(layer "In11.Cu")
		(net "P5E_CPU0_P1_RX_DP<3>")
	)
	(segment
		(start 340.67623 -393.428982)
		(end 340.360254 -393.113006)
		(width 0.14224)
		(layer "In11.Cu")
		(net "P5E_CPU0_P1_RX_DP<3>")
	)
	(segment
		(start 348.115636 -292.246812)
		(end 348.090998 -292.232588)
		(width 0.1143)
		(layer "In11.Cu")
		(net "P5E_CPU0_P1_RX_DP<3>")
	)
	(segment
		(start 348.085156 -278.623014)
		(end 348.08668 -278.621998)
		(width 0.1143)
		(layer "In11.Cu")
		(net "P5E_CPU0_P1_RX_DP<3>")
	)
	(segment
		(start 348.078298 -280.885392)
		(end 348.077536 -280.884884)
		(width 0.1143)
		(layer "In11.Cu")
		(net "P5E_CPU0_P1_RX_DP<3>")
	)
	(segment
		(start 348.079822 -284.126178)
		(end 348.078298 -284.125416)
		(width 0.1143)
		(layer "In11.Cu")
		(net "P5E_CPU0_P1_RX_DP<3>")
	)
	(segment
		(start 348.123256 -290.631372)
		(end 348.116398 -290.627308)
		(width 0.1143)
		(layer "In11.Cu")
		(net "P5E_CPU0_P1_RX_DP<3>")
	)
	(segment
		(start 349.383096 -276.516084)
		(end 349.681038 -276.516084)
		(width 0.1143)
		(layer "In11.Cu")
		(net "P5E_CPU0_P1_RX_DP<3>")
	)
	(segment
		(start 335.853278 -376.274838)
		(end 338.196428 -373.931688)
		(width 0.14224)
		(layer "In11.Cu")
		(net "P5E_CPU0_P1_RX_DP<3>")
	)
	(segment
		(start 348.116398 -292.24732)
		(end 348.115636 -292.246812)
		(width 0.1143)
		(layer "In11.Cu")
		(net "P5E_CPU0_P1_RX_DP<3>")
	)
	(segment
		(start 340.318852 -394.385292)
		(end 340.413848 -394.031216)
		(width 0.14224)
		(layer "In11.Cu")
		(net "P5E_CPU0_P1_RX_DP<3>")
	)
	(segment
		(start 348.080584 -280.886662)
		(end 348.079822 -280.886154)
		(width 0.1143)
		(layer "In11.Cu")
		(net "P5E_CPU0_P1_RX_DP<3>")
	)
	(segment
		(start 348.080584 -284.126686)
		(end 348.079822 -284.126178)
		(width 0.1143)
		(layer "In11.Cu")
		(net "P5E_CPU0_P1_RX_DP<3>")
	)
	(segment
		(start 348.083378 -293.203884)
		(end 348.08414 -293.203376)
		(width 0.1143)
		(layer "In11.Cu")
		(net "P5E_CPU0_P1_RX_DP<3>")
	)
	(segment
		(start 348.089474 -288.991548)
		(end 348.088458 -288.99104)
		(width 0.1143)
		(layer "In11.Cu")
		(net "P5E_CPU0_P1_RX_DP<3>")
	)
	(segment
		(start 348.116398 -282.527502)
		(end 348.115636 -282.526994)
		(width 0.1143)
		(layer "In11.Cu")
		(net "P5E_CPU0_P1_RX_DP<3>")
	)
	(segment
		(start 348.08414 -280.888694)
		(end 348.083378 -280.888186)
		(width 0.1143)
		(layer "In11.Cu")
		(net "P5E_CPU0_P1_RX_DP<3>")
	)
	(segment
		(start 348.079822 -294.825928)
		(end 348.080584 -294.82542)
		(width 0.1143)
		(layer "In11.Cu")
		(net "P5E_CPU0_P1_RX_DP<3>")
	)
	(segment
		(start 348.08414 -283.483558)
		(end 348.085156 -283.48305)
		(width 0.1143)
		(layer "In11.Cu")
		(net "P5E_CPU0_P1_RX_DP<3>")
	)
	(segment
		(start 348.088458 -284.131258)
		(end 348.086934 -284.130242)
		(width 0.1143)
		(layer "In11.Cu")
		(net "P5E_CPU0_P1_RX_DP<3>")
	)
	(segment
		(start 348.080584 -285.105602)
		(end 348.083378 -285.104078)
		(width 0.1143)
		(layer "In11.Cu")
		(net "P5E_CPU0_P1_RX_DP<3>")
	)
	(segment
		(start 348.086934 -292.230048)
		(end 348.085156 -292.229032)
		(width 0.1143)
		(layer "In11.Cu")
		(net "P5E_CPU0_P1_RX_DP<3>")
	)
	(segment
		(start 348.08668 -289.961828)
		(end 348.123256 -289.940492)
		(width 0.1143)
		(layer "In11.Cu")
		(net "P5E_CPU0_P1_RX_DP<3>")
	)
	(segment
		(start 348.08414 -285.74873)
		(end 348.083378 -285.748222)
		(width 0.1143)
		(layer "In11.Cu")
		(net "P5E_CPU0_P1_RX_DP<3>")
	)
	(segment
		(start 351.37852 -308.551326)
		(end 347.472508 -299.120814)
		(width 0.14224)
		(layer "In11.Cu")
		(net "P5E_CPU0_P1_RX_DP<3>")
	)
	(segment
		(start 348.080584 -289.965384)
		(end 348.083378 -289.96386)
		(width 0.1143)
		(layer "In11.Cu")
		(net "P5E_CPU0_P1_RX_DP<3>")
	)
	(segment
		(start 348.080584 -283.48559)
		(end 348.083378 -283.484066)
		(width 0.1143)
		(layer "In11.Cu")
		(net "P5E_CPU0_P1_RX_DP<3>")
	)
	(segment
		(start 348.115636 -289.006788)
		(end 348.090998 -288.992564)
		(width 0.1143)
		(layer "In11.Cu")
		(net "P5E_CPU0_P1_RX_DP<3>")
	)
	(segment
		(start 348.123256 -282.531566)
		(end 348.116398 -282.527502)
		(width 0.1143)
		(layer "In11.Cu")
		(net "P5E_CPU0_P1_RX_DP<3>")
	)
	(segment
		(start 348.083378 -278.62403)
		(end 348.08414 -278.623522)
		(width 0.1143)
		(layer "In11.Cu")
		(net "P5E_CPU0_P1_RX_DP<3>")
	)
	(segment
		(start 348.086934 -290.610036)
		(end 348.085156 -290.60902)
		(width 0.1143)
		(layer "In11.Cu")
		(net "P5E_CPU0_P1_RX_DP<3>")
	)
	(segment
		(start 348.08668 -283.482034)
		(end 348.123256 -283.460698)
		(width 0.1143)
		(layer "In11.Cu")
		(net "P5E_CPU0_P1_RX_DP<3>")
	)
	(segment
		(start 348.090998 -293.8526)
		(end 348.089474 -293.851584)
		(width 0.1143)
		(layer "In11.Cu")
		(net "P5E_CPU0_P1_RX_DP<3>")
	)
	(segment
		(start 340.360254 -393.113006)
		(end 340.363302 -392.7348)
		(width 0.14224)
		(layer "In11.Cu")
		(net "P5E_CPU0_P1_RX_DP<3>")
	)
	(segment
		(start 348.083378 -289.96386)
		(end 348.08414 -289.963352)
		(width 0.1143)
		(layer "In11.Cu")
		(net "P5E_CPU0_P1_RX_DP<3>")
	)
	(segment
		(start 348.082108 -290.607242)
		(end 348.05239 -290.590224)
		(width 0.1143)
		(layer "In11.Cu")
		(net "P5E_CPU0_P1_RX_DP<3>")
	)
	(segment
		(start 348.077536 -282.504896)
		(end 348.076266 -282.504134)
		(width 0.1143)
		(layer "In11.Cu")
		(net "P5E_CPU0_P1_RX_DP<3>")
	)
	(segment
		(start 348.080584 -294.82542)
		(end 348.083378 -294.823896)
		(width 0.1143)
		(layer "In11.Cu")
		(net "P5E_CPU0_P1_RX_DP<3>")
	)
	(segment
		(start 348.073726 -284.122876)
		(end 348.05239 -284.11043)
		(width 0.1143)
		(layer "In11.Cu")
		(net "P5E_CPU0_P1_RX_DP<3>")
	)
	(segment
		(start 347.89618 -295.478962)
		(end 347.89618 -295.192958)
		(width 0.1143)
		(layer "In11.Cu")
		(net "P5E_CPU0_P1_RX_DP<3>")
	)
	(segment
		(start 348.115636 -282.526994)
		(end 348.090998 -282.51277)
		(width 0.1143)
		(layer "In11.Cu")
		(net "P5E_CPU0_P1_RX_DP<3>")
	)
	(segment
		(start 340.363302 -392.7348)
		(end 340.668102 -392.43)
		(width 0.14224)
		(layer "In11.Cu")
		(net "P5E_CPU0_P1_RX_DP<3>")
	)
	(segment
		(start 348.080584 -293.205408)
		(end 348.083378 -293.203884)
		(width 0.1143)
		(layer "In11.Cu")
		(net "P5E_CPU0_P1_RX_DP<3>")
	)
	(segment
		(start 348.050612 -288.363152)
		(end 348.08414 -288.343594)
		(width 0.1143)
		(layer "In11.Cu")
		(net "P5E_CPU0_P1_RX_DP<3>")
	)
	(segment
		(start 340.588092 -393.930632)
		(end 340.67623 -393.842494)
		(width 0.14224)
		(layer "In11.Cu")
		(net "P5E_CPU0_P1_RX_DP<3>")
	)
	(segment
		(start 348.079822 -289.965892)
		(end 348.080584 -289.965384)
		(width 0.1143)
		(layer "In11.Cu")
		(net "P5E_CPU0_P1_RX_DP<3>")
	)
	(segment
		(start 348.090998 -292.232588)
		(end 348.089474 -292.231572)
		(width 0.1143)
		(layer "In11.Cu")
		(net "P5E_CPU0_P1_RX_DP<3>")
	)
	(segment
		(start 348.082108 -293.847266)
		(end 348.05239 -293.830248)
		(width 0.1143)
		(layer "In11.Cu")
		(net "P5E_CPU0_P1_RX_DP<3>")
	)
	(segment
		(start 348.116398 -284.147514)
		(end 348.115636 -284.147006)
		(width 0.1143)
		(layer "In11.Cu")
		(net "P5E_CPU0_P1_RX_DP<3>")
	)
	(segment
		(start 348.089474 -285.751778)
		(end 348.088458 -285.75127)
		(width 0.1143)
		(layer "In11.Cu")
		(net "P5E_CPU0_P1_RX_DP<3>")
	)
	(segment
		(start 339.479636 -373.074184)
		(end 344.810842 -370.865908)
		(width 0.14224)
		(layer "In11.Cu")
		(net "P5E_CPU0_P1_RX_DP<3>")
	)
	(segment
		(start 348.08414 -288.9885)
		(end 348.083378 -288.987992)
		(width 0.1143)
		(layer "In11.Cu")
		(net "P5E_CPU0_P1_RX_DP<3>")
	)
	(segment
		(start 348.05239 -278.64181)
		(end 348.07779 -278.627078)
		(width 0.1143)
		(layer "In11.Cu")
		(net "P5E_CPU0_P1_RX_DP<3>")
	)
	(segment
		(start 349.299784 -276.602952)
		(end 349.383096 -276.516084)
		(width 0.1143)
		(layer "In11.Cu")
		(net "P5E_CPU0_P1_RX_DP<3>")
	)
	(segment
		(start 348.080584 -291.585396)
		(end 348.083378 -291.583872)
		(width 0.1143)
		(layer "In11.Cu")
		(net "P5E_CPU0_P1_RX_DP<3>")
	)
	(segment
		(start 348.115636 -293.866824)
		(end 348.090998 -293.8526)
		(width 0.1143)
		(layer "In11.Cu")
		(net "P5E_CPU0_P1_RX_DP<3>")
	)
	(segment
		(start 348.086934 -285.750254)
		(end 348.085156 -285.749238)
		(width 0.1143)
		(layer "In11.Cu")
		(net "P5E_CPU0_P1_RX_DP<3>")
	)
	(segment
		(start 348.083378 -288.987992)
		(end 348.082108 -288.98723)
		(width 0.1143)
		(layer "In11.Cu")
		(net "P5E_CPU0_P1_RX_DP<3>")
	)
	(segment
		(start 347.653102 -280.101548)
		(end 347.613986 -280.078688)
		(width 0.1143)
		(layer "In11.Cu")
		(net "P5E_CPU0_P1_RX_DP<3>")
	)
	(segment
		(start 348.086934 -288.990024)
		(end 348.085156 -288.989008)
		(width 0.1143)
		(layer "In11.Cu")
		(net "P5E_CPU0_P1_RX_DP<3>")
	)
	(segment
		(start 348.115636 -280.906982)
		(end 348.090998 -280.892758)
		(width 0.1143)
		(layer "In11.Cu")
		(net "P5E_CPU0_P1_RX_DP<3>")
	)
	(segment
		(start 348.085156 -293.849044)
		(end 348.08414 -293.848536)
		(width 0.1143)
		(layer "In11.Cu")
		(net "P5E_CPU0_P1_RX_DP<3>")
	)
	(segment
		(start 348.078298 -284.125416)
		(end 348.077536 -284.124908)
		(width 0.1143)
		(layer "In11.Cu")
		(net "P5E_CPU0_P1_RX_DP<3>")
	)
	(segment
		(start 348.085156 -280.889202)
		(end 348.08414 -280.888694)
		(width 0.1143)
		(layer "In11.Cu")
		(net "P5E_CPU0_P1_RX_DP<3>")
	)
	(segment
		(start 348.083378 -294.823896)
		(end 348.08414 -294.823388)
		(width 0.1143)
		(layer "In11.Cu")
		(net "P5E_CPU0_P1_RX_DP<3>")
	)
	(segment
		(start 348.123256 -284.151578)
		(end 348.116398 -284.147514)
		(width 0.1143)
		(layer "In11.Cu")
		(net "P5E_CPU0_P1_RX_DP<3>")
	)
	(segment
		(start 340.413848 -394.031216)
		(end 340.588092 -393.930632)
		(width 0.14224)
		(layer "In11.Cu")
		(net "P5E_CPU0_P1_RX_DP<3>")
	)
	(segment
		(start 348.077536 -284.124908)
		(end 348.076266 -284.124146)
		(width 0.1143)
		(layer "In11.Cu")
		(net "P5E_CPU0_P1_RX_DP<3>")
	)
	(segment
		(start 348.073726 -282.502864)
		(end 348.05239 -282.490418)
		(width 0.1143)
		(layer "In11.Cu")
		(net "P5E_CPU0_P1_RX_DP<3>")
	)
	(segment
		(start 348.086934 -282.51023)
		(end 348.085156 -282.509214)
		(width 0.1143)
		(layer "In11.Cu")
		(net "P5E_CPU0_P1_RX_DP<3>")
	)
	(segment
		(start 348.05239 -294.841676)
		(end 348.07779 -294.826944)
		(width 0.1143)
		(layer "In11.Cu")
		(net "P5E_CPU0_P1_RX_DP<3>")
	)
	(segment
		(start 348.085156 -282.509214)
		(end 348.08414 -282.508706)
		(width 0.1143)
		(layer "In11.Cu")
		(net "P5E_CPU0_P1_RX_DP<3>")
	)
	(segment
		(start 348.089474 -280.891742)
		(end 348.088458 -280.891234)
		(width 0.1143)
		(layer "In11.Cu")
		(net "P5E_CPU0_P1_RX_DP<3>")
	)
	(segment
		(start 364.533942 -326.406764)
		(end 357.944166 -318.377062)
		(width 0.14224)
		(layer "In11.Cu")
		(net "P5E_CPU0_P1_RX_DP<3>")
	)
	(segment
		(start 348.090998 -280.892758)
		(end 348.089474 -280.891742)
		(width 0.1143)
		(layer "In11.Cu")
		(net "P5E_CPU0_P1_RX_DP<3>")
	)
	(segment
		(start 348.086934 -280.890218)
		(end 348.085156 -280.889202)
		(width 0.1143)
		(layer "In11.Cu")
		(net "P5E_CPU0_P1_RX_DP<3>")
	)
	(segment
		(start 348.07779 -294.826944)
		(end 348.079822 -294.825928)
		(width 0.1143)
		(layer "In11.Cu")
		(net "P5E_CPU0_P1_RX_DP<3>")
	)
	(segment
		(start 348.050612 -286.74314)
		(end 348.08414 -286.723582)
		(width 0.1143)
		(layer "In11.Cu")
		(net "P5E_CPU0_P1_RX_DP<3>")
	)
	(segment
		(start 348.08668 -281.862022)
		(end 348.123256 -281.840686)
		(width 0.1143)
		(layer "In11.Cu")
		(net "P5E_CPU0_P1_RX_DP<3>")
	)
	(segment
		(start 340.668102 -392.43)
		(end 340.668102 -390.571482)
		(width 0.14224)
		(layer "In11.Cu")
		(net "P5E_CPU0_P1_RX_DP<3>")
	)
	(segment
		(start 348.082108 -288.98723)
		(end 348.05239 -288.970212)
		(width 0.1143)
		(layer "In11.Cu")
		(net "P5E_CPU0_P1_RX_DP<3>")
	)
	(segment
		(start 348.089474 -293.851584)
		(end 348.088458 -293.851076)
		(width 0.1143)
		(layer "In11.Cu")
		(net "P5E_CPU0_P1_RX_DP<3>")
	)
	(segment
		(start 347.472508 -296.46372)
		(end 347.472508 -296.435272)
		(width 0.1143)
		(layer "In11.Cu")
		(net "P5E_CPU0_P1_RX_DP<3>")
	)
	(segment
		(start 348.089474 -292.231572)
		(end 348.088458 -292.231064)
		(width 0.1143)
		(layer "In11.Cu")
		(net "P5E_CPU0_P1_RX_DP<3>")
	)
	(segment
		(start 348.089474 -284.131766)
		(end 348.088458 -284.131258)
		(width 0.1143)
		(layer "In11.Cu")
		(net "P5E_CPU0_P1_RX_DP<3>")
	)
	(segment
		(start 348.05239 -291.601652)
		(end 348.07779 -291.58692)
		(width 0.1143)
		(layer "In11.Cu")
		(net "P5E_CPU0_P1_RX_DP<3>")
	)
	(segment
		(start 348.115636 -285.767018)
		(end 348.090998 -285.752794)
		(width 0.1143)
		(layer "In11.Cu")
		(net "P5E_CPU0_P1_RX_DP<3>")
	)
	(segment
		(start 348.077536 -285.74492)
		(end 348.076266 -285.744158)
		(width 0.1143)
		(layer "In11.Cu")
		(net "P5E_CPU0_P1_RX_DP<3>")
	)
	(segment
		(start 348.05239 -283.501846)
		(end 348.07779 -283.487114)
		(width 0.1143)
		(layer "In11.Cu")
		(net "P5E_CPU0_P1_RX_DP<3>")
	)
	(segment
		(start 348.08414 -293.203376)
		(end 348.085156 -293.202868)
		(width 0.1143)
		(layer "In11.Cu")
		(net "P5E_CPU0_P1_RX_DP<3>")
	)
	(segment
		(start 347.472508 -296.435272)
		(end 347.426788 -296.389552)
		(width 0.1143)
		(layer "In11.Cu")
		(net "P5E_CPU0_P1_RX_DP<3>")
	)
	(segment
		(start 348.08414 -287.368488)
		(end 348.05239 -287.3502)
		(width 0.1143)
		(layer "In11.Cu")
		(net "P5E_CPU0_P1_RX_DP<3>")
	)
	(segment
		(start 348.085156 -290.60902)
		(end 348.08414 -290.608512)
		(width 0.1143)
		(layer "In11.Cu")
		(net "P5E_CPU0_P1_RX_DP<3>")
	)
	(segment
		(start 366.809528 -334.444594)
		(end 365.802164 -328.840846)
		(width 0.14224)
		(layer "In11.Cu")
		(net "P5E_CPU0_P1_RX_DP<3>")
	)
	(segment
		(start 348.079822 -278.626062)
		(end 348.080584 -278.625554)
		(width 0.1143)
		(layer "In11.Cu")
		(net "P5E_CPU0_P1_RX_DP<3>")
	)
	(segment
		(start 348.083378 -292.228016)
		(end 348.082108 -292.227254)
		(width 0.1143)
		(layer "In11.Cu")
		(net "P5E_CPU0_P1_RX_DP<3>")
	)
	(segment
		(start 348.083378 -283.484066)
		(end 348.08414 -283.483558)
		(width 0.1143)
		(layer "In11.Cu")
		(net "P5E_CPU0_P1_RX_DP<3>")
	)
	(segment
		(start 347.89618 -295.192958)
		(end 347.896434 -295.145968)
		(width 0.1143)
		(layer "In11.Cu")
		(net "P5E_CPU0_P1_RX_DP<3>")
	)
	(segment
		(start 348.123256 -285.77159)
		(end 348.116398 -285.767526)
		(width 0.1143)
		(layer "In11.Cu")
		(net "P5E_CPU0_P1_RX_DP<3>")
	)
	(segment
		(start 348.123256 -293.871396)
		(end 348.116398 -293.867332)
		(width 0.1143)
		(layer "In11.Cu")
		(net "P5E_CPU0_P1_RX_DP<3>")
	)
	(segment
		(start 348.079822 -285.74619)
		(end 348.078298 -285.745428)
		(width 0.1143)
		(layer "In11.Cu")
		(net "P5E_CPU0_P1_RX_DP<3>")
	)
	(segment
		(start 367.109502 -347.752162)
		(end 367.544858 -346.700856)
		(width 0.14224)
		(layer "In11.Cu")
		(net "P5E_CPU0_P1_RX_DP<3>")
	)
	(segment
		(start 348.085156 -283.48305)
		(end 348.08668 -283.482034)
		(width 0.1143)
		(layer "In11.Cu")
		(net "P5E_CPU0_P1_RX_DP<3>")
	)
	(segment
		(start 348.05239 -289.98164)
		(end 348.07779 -289.966908)
		(width 0.1143)
		(layer "In11.Cu")
		(net "P5E_CPU0_P1_RX_DP<3>")
	)
	(segment
		(start 348.085156 -285.749238)
		(end 348.08414 -285.74873)
		(width 0.1143)
		(layer "In11.Cu")
		(net "P5E_CPU0_P1_RX_DP<3>")
	)
	(segment
		(start 348.08414 -289.963352)
		(end 348.085156 -289.962844)
		(width 0.1143)
		(layer "In11.Cu")
		(net "P5E_CPU0_P1_RX_DP<3>")
	)
	(segment
		(start 366.809528 -334.444848)
		(end 366.809528 -334.444594)
		(width 0.14224)
		(layer "In11.Cu")
		(net "P5E_CPU0_P1_RX_DP<3>")
	)
	(segment
		(start 348.08414 -286.723582)
		(end 348.123256 -286.700722)
		(width 0.1143)
		(layer "In11.Cu")
		(net "P5E_CPU0_P1_RX_DP<3>")
	)
	(segment
		(start 348.08414 -292.228524)
		(end 348.083378 -292.228016)
		(width 0.1143)
		(layer "In11.Cu")
		(net "P5E_CPU0_P1_RX_DP<3>")
	)
	(segment
		(start 348.08668 -285.102046)
		(end 348.123256 -285.08071)
		(width 0.1143)
		(layer "In11.Cu")
		(net "P5E_CPU0_P1_RX_DP<3>")
	)
	(segment
		(start 348.076266 -282.504134)
		(end 348.073726 -282.502864)
		(width 0.1143)
		(layer "In11.Cu")
		(net "P5E_CPU0_P1_RX_DP<3>")
	)
	(segment
		(start 340.449154 -389.848852)
		(end 335.555336 -382.525016)
		(width 0.14224)
		(layer "In11.Cu")
		(net "P5E_CPU0_P1_RX_DP<3>")
	)
	(segment
		(start 348.078298 -285.745428)
		(end 348.077536 -285.74492)
		(width 0.1143)
		(layer "In11.Cu")
		(net "P5E_CPU0_P1_RX_DP<3>")
	)
	(segment
		(start 348.085156 -291.582856)
		(end 348.08668 -291.58184)
		(width 0.1143)
		(layer "In11.Cu")
		(net "P5E_CPU0_P1_RX_DP<3>")
	)
	(segment
		(start 347.426788 -296.389552)
		(end 347.426788 -295.948354)
		(width 0.1143)
		(layer "In11.Cu")
		(net "P5E_CPU0_P1_RX_DP<3>")
	)
	(segment
		(start 348.086934 -284.130242)
		(end 348.085156 -284.129226)
		(width 0.1143)
		(layer "In11.Cu")
		(net "P5E_CPU0_P1_RX_DP<3>")
	)
	(segment
		(start 348.083378 -281.864054)
		(end 348.08414 -281.863546)
		(width 0.1143)
		(layer "In11.Cu")
		(net "P5E_CPU0_P1_RX_DP<3>")
	)
	(arc
		(start 348.05239 -287.3502)
		(mid 347.937714 -287.216866)
		(end 347.896434 -287.045908)
		(width 0.1143)
		(layer "In11.Cu")
		(net "P5E_CPU0_P1_RX_DP<3>")
	)
	(arc
		(start 347.653102 -279.410668)
		(mid 347.831915 -279.208318)
		(end 347.896434 -278.946102)
		(width 0.1143)
		(layer "In11.Cu")
		(net "P5E_CPU0_P1_RX_DP<3>")
	)
	(arc
		(start 349.296482 -276.622002)
		(mid 349.298207 -276.61249)
		(end 349.299784 -276.602952)
		(width 0.1143)
		(layer "In11.Cu")
		(net "P5E_CPU0_P1_RX_DP<3>")
	)
	(arc
		(start 348.123256 -294.800528)
		(mid 348.366583 -294.335962)
		(end 348.123256 -293.871396)
		(width 0.1143)
		(layer "In11.Cu")
		(net "P5E_CPU0_P1_RX_DP<3>")
	)
	(arc
		(start 348.366588 -287.856168)
		(mid 348.301352 -287.592577)
		(end 348.120716 -287.389824)
		(width 0.1143)
		(layer "In11.Cu")
		(net "P5E_CPU0_P1_RX_DP<3>")
	)
	(arc
		(start 367.544858 -346.700856)
		(mid 367.745991 -346.037574)
		(end 367.813844 -345.347798)
		(width 0.14224)
		(layer "In11.Cu")
		(net "P5E_CPU0_P1_RX_DP<3>")
	)
	(arc
		(start 348.05239 -288.970212)
		(mid 347.937714 -288.836878)
		(end 347.896434 -288.66592)
		(width 0.1143)
		(layer "In11.Cu")
		(net "P5E_CPU0_P1_RX_DP<3>")
	)
	(arc
		(start 348.123256 -288.320734)
		(mid 348.302069 -288.118384)
		(end 348.366588 -287.856168)
		(width 0.1143)
		(layer "In11.Cu")
		(net "P5E_CPU0_P1_RX_DP<3>")
	)
	(arc
		(start 348.123256 -286.700722)
		(mid 348.366583 -286.236156)
		(end 348.123256 -285.77159)
		(width 0.1143)
		(layer "In11.Cu")
		(net "P5E_CPU0_P1_RX_DP<3>")
	)
	(arc
		(start 361.253786 -356.516178)
		(mid 364.613322 -352.422596)
		(end 367.109502 -347.752162)
		(width 0.14224)
		(layer "In11.Cu")
		(net "P5E_CPU0_P1_RX_DP<3>")
	)
	(arc
		(start 348.05239 -280.870406)
		(mid 347.937714 -280.737072)
		(end 347.896434 -280.566114)
		(width 0.1143)
		(layer "In11.Cu")
		(net "P5E_CPU0_P1_RX_DP<3>")
	)
	(arc
		(start 347.896434 -287.045908)
		(mid 347.937196 -286.876024)
		(end 348.050612 -286.74314)
		(width 0.1143)
		(layer "In11.Cu")
		(net "P5E_CPU0_P1_RX_DP<3>")
	)
	(arc
		(start 335.519014 -377.081542)
		(mid 335.605948 -376.644966)
		(end 335.853278 -376.274838)
		(width 0.14224)
		(layer "In11.Cu")
		(net "P5E_CPU0_P1_RX_DP<3>")
	)
	(arc
		(start 347.583506 -280.060908)
		(mid 347.426529 -279.756108)
		(end 347.583506 -279.451308)
		(width 0.1143)
		(layer "In11.Cu")
		(net "P5E_CPU0_P1_RX_DP<3>")
	)
	(arc
		(start 344.810842 -370.865908)
		(mid 348.17287 -369.068771)
		(end 351.119694 -366.65027)
		(width 0.14224)
		(layer "In11.Cu")
		(net "P5E_CPU0_P1_RX_DP<3>")
	)
	(arc
		(start 340.668102 -390.571482)
		(mid 340.612272 -390.193914)
		(end 340.449154 -389.848852)
		(width 0.14224)
		(layer "In11.Cu")
		(net "P5E_CPU0_P1_RX_DP<3>")
	)
	(arc
		(start 348.05239 -284.11043)
		(mid 347.896462 -283.806138)
		(end 348.05239 -283.501846)
		(width 0.1143)
		(layer "In11.Cu")
		(net "P5E_CPU0_P1_RX_DP<3>")
	)
	(arc
		(start 335.555336 -382.525016)
		(mid 335.528295 -382.468024)
		(end 335.519014 -382.405636)
		(width 0.14224)
		(layer "In11.Cu")
		(net "P5E_CPU0_P1_RX_DP<3>")
	)
	(arc
		(start 347.896434 -278.946102)
		(mid 347.937689 -278.775131)
		(end 348.05239 -278.64181)
		(width 0.1143)
		(layer "In11.Cu")
		(net "P5E_CPU0_P1_RX_DP<3>")
	)
	(arc
		(start 348.123256 -281.840686)
		(mid 348.366583 -281.37612)
		(end 348.123256 -280.911554)
		(width 0.1143)
		(layer "In11.Cu")
		(net "P5E_CPU0_P1_RX_DP<3>")
	)
	(arc
		(start 348.05239 -292.210236)
		(mid 347.896462 -291.905944)
		(end 348.05239 -291.601652)
		(width 0.1143)
		(layer "In11.Cu")
		(net "P5E_CPU0_P1_RX_DP<3>")
	)
	(arc
		(start 348.05239 -293.830248)
		(mid 347.896462 -293.525956)
		(end 348.05239 -293.221664)
		(width 0.1143)
		(layer "In11.Cu")
		(net "P5E_CPU0_P1_RX_DP<3>")
	)
	(arc
		(start 347.896434 -288.66592)
		(mid 347.937196 -288.496036)
		(end 348.050612 -288.363152)
		(width 0.1143)
		(layer "In11.Cu")
		(net "P5E_CPU0_P1_RX_DP<3>")
	)
	(arc
		(start 348.366588 -278.136096)
		(mid 348.408137 -277.964674)
		(end 348.52356 -277.831296)
		(width 0.1143)
		(layer "In11.Cu")
		(net "P5E_CPU0_P1_RX_DP<3>")
	)
	(arc
		(start 348.123256 -283.460698)
		(mid 348.366583 -282.996132)
		(end 348.123256 -282.531566)
		(width 0.1143)
		(layer "In11.Cu")
		(net "P5E_CPU0_P1_RX_DP<3>")
	)
	(arc
		(start 348.123256 -285.08071)
		(mid 348.366583 -284.616144)
		(end 348.123256 -284.151578)
		(width 0.1143)
		(layer "In11.Cu")
		(net "P5E_CPU0_P1_RX_DP<3>")
	)
	(arc
		(start 348.123256 -291.560504)
		(mid 348.366583 -291.095938)
		(end 348.123256 -290.631372)
		(width 0.1143)
		(layer "In11.Cu")
		(net "P5E_CPU0_P1_RX_DP<3>")
	)
	(arc
		(start 347.896434 -295.145968)
		(mid 347.937689 -294.974997)
		(end 348.05239 -294.841676)
		(width 0.1143)
		(layer "In11.Cu")
		(net "P5E_CPU0_P1_RX_DP<3>")
	)
	(arc
		(start 348.05239 -285.730442)
		(mid 347.896462 -285.42615)
		(end 348.05239 -285.121858)
		(width 0.1143)
		(layer "In11.Cu")
		(net "P5E_CPU0_P1_RX_DP<3>")
	)
	(arc
		(start 348.123256 -278.600662)
		(mid 348.302069 -278.398312)
		(end 348.366588 -278.136096)
		(width 0.1143)
		(layer "In11.Cu")
		(net "P5E_CPU0_P1_RX_DP<3>")
	)
	(arc
		(start 348.836488 -277.32609)
		(mid 348.877743 -277.155119)
		(end 348.992444 -277.021798)
		(width 0.1143)
		(layer "In11.Cu")
		(net "P5E_CPU0_P1_RX_DP<3>")
	)
	(arc
		(start 348.593156 -277.790656)
		(mid 348.771969 -277.588306)
		(end 348.836488 -277.32609)
		(width 0.1143)
		(layer "In11.Cu")
		(net "P5E_CPU0_P1_RX_DP<3>")
	)
	(arc
		(start 349.02775 -277.001478)
		(mid 349.203418 -276.840985)
		(end 349.296482 -276.622002)
		(width 0.1143)
		(layer "In11.Cu")
		(net "P5E_CPU0_P1_RX_DP<3>")
	)
	(arc
		(start 338.196428 -373.931688)
		(mid 338.795803 -373.43974)
		(end 339.479636 -373.074184)
		(width 0.14224)
		(layer "In11.Cu")
		(net "P5E_CPU0_P1_RX_DP<3>")
	)
	(arc
		(start 348.123256 -293.180516)
		(mid 348.366583 -292.71595)
		(end 348.123256 -292.251384)
		(width 0.1143)
		(layer "In11.Cu")
		(net "P5E_CPU0_P1_RX_DP<3>")
	)
	(arc
		(start 347.896434 -280.566114)
		(mid 347.831919 -280.303895)
		(end 347.653102 -280.101548)
		(width 0.1143)
		(layer "In11.Cu")
		(net "P5E_CPU0_P1_RX_DP<3>")
	)
	(arc
		(start 348.123256 -289.940492)
		(mid 348.366583 -289.475926)
		(end 348.123256 -289.01136)
		(width 0.1143)
		(layer "In11.Cu")
		(net "P5E_CPU0_P1_RX_DP<3>")
	)
	(arc
		(start 348.05239 -290.590224)
		(mid 347.896462 -290.285932)
		(end 348.05239 -289.98164)
		(width 0.1143)
		(layer "In11.Cu")
		(net "P5E_CPU0_P1_RX_DP<3>")
	)
	(arc
		(start 348.05239 -282.490418)
		(mid 347.896462 -282.186126)
		(end 348.05239 -281.881834)
		(width 0.1143)
		(layer "In11.Cu")
		(net "P5E_CPU0_P1_RX_DP<3>")
	)
	(segment
		(start 338.598002 -394.385292)
		(end 339.118702 -394.385292)
		(width 0.127)
		(layer "F.Cu")
		(net "P5E_CPU0_P1_RX_DP<2>")
	)
	(segment
		(start 347.327982 -274.630134)
		(end 346.86113 -274.896072)
		(width 0.12954)
		(layer "F.Cu")
		(net "P5E_CPU0_P1_RX_DP<2>")
	)
	(segment
		(start 347.146626 -293.201852)
		(end 347.183202 -293.180516)
		(width 0.1143)
		(layer "In11.Cu")
		(net "P5E_CPU0_P1_RX_DP<2>")
	)
	(segment
		(start 339.118702 -394.385292)
		(end 339.213698 -394.031216)
		(width 0.14224)
		(layer "In11.Cu")
		(net "P5E_CPU0_P1_RX_DP<2>")
	)
	(segment
		(start 347.144086 -277.64867)
		(end 347.143324 -277.648162)
		(width 0.1143)
		(layer "In11.Cu")
		(net "P5E_CPU0_P1_RX_DP<2>")
	)
	(segment
		(start 363.78388 -326.998076)
		(end 357.321612 -319.123822)
		(width 0.14224)
		(layer "In11.Cu")
		(net "P5E_CPU0_P1_RX_DP<2>")
	)
	(segment
		(start 347.144086 -285.10357)
		(end 347.145102 -285.103062)
		(width 0.1143)
		(layer "In11.Cu")
		(net "P5E_CPU0_P1_RX_DP<2>")
	)
	(segment
		(start 347.143324 -280.888186)
		(end 347.141292 -280.88717)
		(width 0.1143)
		(layer "In11.Cu")
		(net "P5E_CPU0_P1_RX_DP<2>")
	)
	(segment
		(start 347.183202 -280.911554)
		(end 347.176344 -280.90749)
		(width 0.1143)
		(layer "In11.Cu")
		(net "P5E_CPU0_P1_RX_DP<2>")
	)
	(segment
		(start 347.110558 -288.363152)
		(end 347.113352 -288.36112)
		(width 0.1143)
		(layer "In11.Cu")
		(net "P5E_CPU0_P1_RX_DP<2>")
	)
	(segment
		(start 347.143324 -288.987992)
		(end 347.112336 -288.970212)
		(width 0.1143)
		(layer "In11.Cu")
		(net "P5E_CPU0_P1_RX_DP<2>")
	)
	(segment
		(start 347.183202 -290.631372)
		(end 347.176344 -290.627308)
		(width 0.1143)
		(layer "In11.Cu")
		(net "P5E_CPU0_P1_RX_DP<2>")
	)
	(segment
		(start 347.143324 -283.484066)
		(end 347.144086 -283.483558)
		(width 0.1143)
		(layer "In11.Cu")
		(net "P5E_CPU0_P1_RX_DP<2>")
	)
	(segment
		(start 347.112336 -277.021798)
		(end 347.143324 -277.004018)
		(width 0.1143)
		(layer "In11.Cu")
		(net "P5E_CPU0_P1_RX_DP<2>")
	)
	(segment
		(start 347.143324 -282.508198)
		(end 347.112336 -282.490418)
		(width 0.1143)
		(layer "In11.Cu")
		(net "P5E_CPU0_P1_RX_DP<2>")
	)
	(segment
		(start 347.144086 -293.203376)
		(end 347.145102 -293.202868)
		(width 0.1143)
		(layer "In11.Cu")
		(net "P5E_CPU0_P1_RX_DP<2>")
	)
	(segment
		(start 347.146626 -291.58184)
		(end 347.183202 -291.560504)
		(width 0.1143)
		(layer "In11.Cu")
		(net "P5E_CPU0_P1_RX_DP<2>")
	)
	(segment
		(start 347.183202 -293.871396)
		(end 347.176344 -293.867332)
		(width 0.1143)
		(layer "In11.Cu")
		(net "P5E_CPU0_P1_RX_DP<2>")
	)
	(segment
		(start 347.144086 -280.888694)
		(end 347.143324 -280.888186)
		(width 0.1143)
		(layer "In11.Cu")
		(net "P5E_CPU0_P1_RX_DP<2>")
	)
	(segment
		(start 347.145102 -284.129226)
		(end 347.144086 -284.128718)
		(width 0.1143)
		(layer "In11.Cu")
		(net "P5E_CPU0_P1_RX_DP<2>")
	)
	(segment
		(start 347.143324 -281.864054)
		(end 347.144086 -281.863546)
		(width 0.1143)
		(layer "In11.Cu")
		(net "P5E_CPU0_P1_RX_DP<2>")
	)
	(segment
		(start 347.113352 -288.36112)
		(end 347.183202 -288.320734)
		(width 0.1143)
		(layer "In11.Cu")
		(net "P5E_CPU0_P1_RX_DP<2>")
	)
	(segment
		(start 347.183202 -284.151578)
		(end 347.176344 -284.147514)
		(width 0.1143)
		(layer "In11.Cu")
		(net "P5E_CPU0_P1_RX_DP<2>")
	)
	(segment
		(start 347.175582 -285.767018)
		(end 347.145102 -285.749238)
		(width 0.1143)
		(layer "In11.Cu")
		(net "P5E_CPU0_P1_RX_DP<2>")
	)
	(segment
		(start 333.817214 -381.085598)
		(end 333.817214 -379.786134)
		(width 0.14224)
		(layer "In11.Cu")
		(net "P5E_CPU0_P1_RX_DP<2>")
	)
	(segment
		(start 347.143324 -277.004018)
		(end 347.144086 -277.00351)
		(width 0.1143)
		(layer "In11.Cu")
		(net "P5E_CPU0_P1_RX_DP<2>")
	)
	(segment
		(start 347.146626 -285.102046)
		(end 347.183202 -285.08071)
		(width 0.1143)
		(layer "In11.Cu")
		(net "P5E_CPU0_P1_RX_DP<2>")
	)
	(segment
		(start 347.183202 -289.01136)
		(end 347.176344 -289.007296)
		(width 0.1143)
		(layer "In11.Cu")
		(net "P5E_CPU0_P1_RX_DP<2>")
	)
	(segment
		(start 347.145102 -294.82288)
		(end 347.183202 -294.800528)
		(width 0.1143)
		(layer "In11.Cu")
		(net "P5E_CPU0_P1_RX_DP<2>")
	)
	(segment
		(start 347.112336 -294.841676)
		(end 347.143324 -294.823896)
		(width 0.1143)
		(layer "In11.Cu")
		(net "P5E_CPU0_P1_RX_DP<2>")
	)
	(segment
		(start 347.145102 -285.749238)
		(end 347.144086 -285.74873)
		(width 0.1143)
		(layer "In11.Cu")
		(net "P5E_CPU0_P1_RX_DP<2>")
	)
	(segment
		(start 347.144086 -291.583364)
		(end 347.145102 -291.582856)
		(width 0.1143)
		(layer "In11.Cu")
		(net "P5E_CPU0_P1_RX_DP<2>")
	)
	(segment
		(start 347.144086 -293.848536)
		(end 347.143324 -293.848028)
		(width 0.1143)
		(layer "In11.Cu")
		(net "P5E_CPU0_P1_RX_DP<2>")
	)
	(segment
		(start 346.95638 -287.053528)
		(end 346.95638 -287.045908)
		(width 0.1143)
		(layer "In11.Cu")
		(net "P5E_CPU0_P1_RX_DP<2>")
	)
	(segment
		(start 346.966794 -280.600404)
		(end 346.966794 -280.573988)
		(width 0.1143)
		(layer "In11.Cu")
		(net "P5E_CPU0_P1_RX_DP<2>")
	)
	(segment
		(start 347.143324 -285.748222)
		(end 347.112336 -285.730442)
		(width 0.1143)
		(layer "In11.Cu")
		(net "P5E_CPU0_P1_RX_DP<2>")
	)
	(segment
		(start 339.467952 -392.430254)
		(end 339.467952 -390.557258)
		(width 0.14224)
		(layer "In11.Cu")
		(net "P5E_CPU0_P1_RX_DP<2>")
	)
	(segment
		(start 347.144086 -277.00351)
		(end 347.145102 -277.003002)
		(width 0.1143)
		(layer "In11.Cu")
		(net "P5E_CPU0_P1_RX_DP<2>")
	)
	(segment
		(start 347.146626 -276.030182)
		(end 347.145102 -276.029166)
		(width 0.1143)
		(layer "In11.Cu")
		(net "P5E_CPU0_P1_RX_DP<2>")
	)
	(segment
		(start 347.183202 -277.67153)
		(end 347.146626 -277.650194)
		(width 0.1143)
		(layer "In11.Cu")
		(net "P5E_CPU0_P1_RX_DP<2>")
	)
	(segment
		(start 347.112336 -293.221664)
		(end 347.143324 -293.203884)
		(width 0.1143)
		(layer "In11.Cu")
		(net "P5E_CPU0_P1_RX_DP<2>")
	)
	(segment
		(start 346.642436 -279.451816)
		(end 346.674186 -279.433528)
		(width 0.1143)
		(layer "In11.Cu")
		(net "P5E_CPU0_P1_RX_DP<2>")
	)
	(segment
		(start 347.175582 -290.6268)
		(end 347.145102 -290.60902)
		(width 0.1143)
		(layer "In11.Cu")
		(net "P5E_CPU0_P1_RX_DP<2>")
	)
	(segment
		(start 334.621124 -383.089912)
		(end 333.841852 -381.208788)
		(width 0.14224)
		(layer "In11.Cu")
		(net "P5E_CPU0_P1_RX_DP<2>")
	)
	(segment
		(start 347.175582 -289.006788)
		(end 347.145102 -288.989008)
		(width 0.1143)
		(layer "In11.Cu")
		(net "P5E_CPU0_P1_RX_DP<2>")
	)
	(segment
		(start 347.112336 -283.501846)
		(end 347.143324 -283.484066)
		(width 0.1143)
		(layer "In11.Cu")
		(net "P5E_CPU0_P1_RX_DP<2>")
	)
	(segment
		(start 347.145102 -280.889202)
		(end 347.144086 -280.888694)
		(width 0.1143)
		(layer "In11.Cu")
		(net "P5E_CPU0_P1_RX_DP<2>")
	)
	(segment
		(start 347.176344 -284.147514)
		(end 347.175582 -284.147006)
		(width 0.1143)
		(layer "In11.Cu")
		(net "P5E_CPU0_P1_RX_DP<2>")
	)
	(segment
		(start 347.146626 -277.001986)
		(end 347.183202 -276.98065)
		(width 0.1143)
		(layer "In11.Cu")
		(net "P5E_CPU0_P1_RX_DP<2>")
	)
	(segment
		(start 347.146626 -289.961828)
		(end 347.183202 -289.940492)
		(width 0.1143)
		(layer "In11.Cu")
		(net "P5E_CPU0_P1_RX_DP<2>")
	)
	(segment
		(start 349.894906 -366.40008)
		(end 360.557826 -355.73716)
		(width 0.14224)
		(layer "In11.Cu")
		(net "P5E_CPU0_P1_RX_DP<2>")
	)
	(segment
		(start 347.112336 -278.64181)
		(end 347.143324 -278.62403)
		(width 0.1143)
		(layer "In11.Cu")
		(net "P5E_CPU0_P1_RX_DP<2>")
	)
	(segment
		(start 347.143324 -293.203884)
		(end 347.144086 -293.203376)
		(width 0.1143)
		(layer "In11.Cu")
		(net "P5E_CPU0_P1_RX_DP<2>")
	)
	(segment
		(start 347.144086 -283.483558)
		(end 347.145102 -283.48305)
		(width 0.1143)
		(layer "In11.Cu")
		(net "P5E_CPU0_P1_RX_DP<2>")
	)
	(segment
		(start 347.145102 -283.48305)
		(end 347.146626 -283.482034)
		(width 0.1143)
		(layer "In11.Cu")
		(net "P5E_CPU0_P1_RX_DP<2>")
	)
	(segment
		(start 357.321612 -319.123822)
		(end 350.552258 -308.993286)
		(width 0.14224)
		(layer "In11.Cu")
		(net "P5E_CPU0_P1_RX_DP<2>")
	)
	(segment
		(start 347.143324 -278.62403)
		(end 347.144086 -278.623522)
		(width 0.1143)
		(layer "In11.Cu")
		(net "P5E_CPU0_P1_RX_DP<2>")
	)
	(segment
		(start 347.144086 -289.963352)
		(end 347.145102 -289.962844)
		(width 0.1143)
		(layer "In11.Cu")
		(net "P5E_CPU0_P1_RX_DP<2>")
	)
	(segment
		(start 347.176344 -282.527502)
		(end 347.175582 -282.526994)
		(width 0.1143)
		(layer "In11.Cu")
		(net "P5E_CPU0_P1_RX_DP<2>")
	)
	(segment
		(start 347.176344 -293.867332)
		(end 347.175582 -293.866824)
		(width 0.1143)
		(layer "In11.Cu")
		(net "P5E_CPU0_P1_RX_DP<2>")
	)
	(segment
		(start 347.144086 -278.623522)
		(end 347.145102 -278.623014)
		(width 0.1143)
		(layer "In11.Cu")
		(net "P5E_CPU0_P1_RX_DP<2>")
	)
	(segment
		(start 347.145102 -277.003002)
		(end 347.146626 -277.001986)
		(width 0.1143)
		(layer "In11.Cu")
		(net "P5E_CPU0_P1_RX_DP<2>")
	)
	(segment
		(start 347.146626 -281.862022)
		(end 347.183202 -281.840686)
		(width 0.1143)
		(layer "In11.Cu")
		(net "P5E_CPU0_P1_RX_DP<2>")
	)
	(segment
		(start 365.9378 -347.685106)
		(end 366.629696 -346.014802)
		(width 0.14224)
		(layer "In11.Cu")
		(net "P5E_CPU0_P1_RX_DP<2>")
	)
	(segment
		(start 339.163152 -392.7348)
		(end 339.467952 -392.430254)
		(width 0.14224)
		(layer "In11.Cu")
		(net "P5E_CPU0_P1_RX_DP<2>")
	)
	(segment
		(start 347.112336 -285.121858)
		(end 347.143324 -285.104078)
		(width 0.1143)
		(layer "In11.Cu")
		(net "P5E_CPU0_P1_RX_DP<2>")
	)
	(segment
		(start 332.153768 -378.084842)
		(end 332.138528 -378.061728)
		(width 0.14224)
		(layer "In11.Cu")
		(net "P5E_CPU0_P1_RX_DP<2>")
	)
	(segment
		(start 347.143324 -289.96386)
		(end 347.144086 -289.963352)
		(width 0.1143)
		(layer "In11.Cu")
		(net "P5E_CPU0_P1_RX_DP<2>")
	)
	(segment
		(start 347.144086 -288.9885)
		(end 347.143324 -288.987992)
		(width 0.1143)
		(layer "In11.Cu")
		(net "P5E_CPU0_P1_RX_DP<2>")
	)
	(segment
		(start 333.416148 -378.696982)
		(end 333.082138 -378.558806)
		(width 0.14224)
		(layer "In11.Cu")
		(net "P5E_CPU0_P1_RX_DP<2>")
	)
	(segment
		(start 347.135958 -280.883868)
		(end 347.128592 -280.879804)
		(width 0.1143)
		(layer "In11.Cu")
		(net "P5E_CPU0_P1_RX_DP<2>")
	)
	(segment
		(start 346.48648 -296.389552)
		(end 346.48648 -295.948862)
		(width 0.1143)
		(layer "In11.Cu")
		(net "P5E_CPU0_P1_RX_DP<2>")
	)
	(segment
		(start 347.145102 -293.849044)
		(end 347.144086 -293.848536)
		(width 0.1143)
		(layer "In11.Cu")
		(net "P5E_CPU0_P1_RX_DP<2>")
	)
	(segment
		(start 347.176344 -289.007296)
		(end 347.175582 -289.006788)
		(width 0.1143)
		(layer "In11.Cu")
		(net "P5E_CPU0_P1_RX_DP<2>")
	)
	(segment
		(start 347.112336 -281.881834)
		(end 347.143324 -281.864054)
		(width 0.1143)
		(layer "In11.Cu")
		(net "P5E_CPU0_P1_RX_DP<2>")
	)
	(segment
		(start 350.552258 -308.993286)
		(end 346.5322 -299.287692)
		(width 0.14224)
		(layer "In11.Cu")
		(net "P5E_CPU0_P1_RX_DP<2>")
	)
	(segment
		(start 347.143324 -293.848028)
		(end 347.112336 -293.830248)
		(width 0.1143)
		(layer "In11.Cu")
		(net "P5E_CPU0_P1_RX_DP<2>")
	)
	(segment
		(start 347.143324 -277.648162)
		(end 347.112336 -277.630382)
		(width 0.1143)
		(layer "In11.Cu")
		(net "P5E_CPU0_P1_RX_DP<2>")
	)
	(segment
		(start 339.160104 -393.113006)
		(end 339.163152 -392.7348)
		(width 0.14224)
		(layer "In11.Cu")
		(net "P5E_CPU0_P1_RX_DP<2>")
	)
	(segment
		(start 346.95638 -295.478962)
		(end 346.95638 -295.145968)
		(width 0.1143)
		(layer "In11.Cu")
		(net "P5E_CPU0_P1_RX_DP<2>")
	)
	(segment
		(start 347.145102 -278.623014)
		(end 347.146626 -278.621998)
		(width 0.1143)
		(layer "In11.Cu")
		(net "P5E_CPU0_P1_RX_DP<2>")
	)
	(segment
		(start 346.48648 -295.948862)
		(end 346.95638 -295.478962)
		(width 0.1143)
		(layer "In11.Cu")
		(net "P5E_CPU0_P1_RX_DP<2>")
	)
	(segment
		(start 339.387942 -393.930632)
		(end 339.47608 -393.842494)
		(width 0.14224)
		(layer "In11.Cu")
		(net "P5E_CPU0_P1_RX_DP<2>")
	)
	(segment
		(start 347.175582 -284.147006)
		(end 347.145102 -284.129226)
		(width 0.1143)
		(layer "In11.Cu")
		(net "P5E_CPU0_P1_RX_DP<2>")
	)
	(segment
		(start 347.183202 -276.051518)
		(end 347.146626 -276.030182)
		(width 0.1143)
		(layer "In11.Cu")
		(net "P5E_CPU0_P1_RX_DP<2>")
	)
	(segment
		(start 347.183202 -285.77159)
		(end 347.176344 -285.767526)
		(width 0.1143)
		(layer "In11.Cu")
		(net "P5E_CPU0_P1_RX_DP<2>")
	)
	(segment
		(start 347.13799 -280.885138)
		(end 347.135958 -280.883868)
		(width 0.1143)
		(layer "In11.Cu")
		(net "P5E_CPU0_P1_RX_DP<2>")
	)
	(segment
		(start 347.176344 -290.627308)
		(end 347.175582 -290.6268)
		(width 0.1143)
		(layer "In11.Cu")
		(net "P5E_CPU0_P1_RX_DP<2>")
	)
	(segment
		(start 347.143324 -285.104078)
		(end 347.144086 -285.10357)
		(width 0.1143)
		(layer "In11.Cu")
		(net "P5E_CPU0_P1_RX_DP<2>")
	)
	(segment
		(start 347.145102 -290.60902)
		(end 347.144086 -290.608512)
		(width 0.1143)
		(layer "In11.Cu")
		(net "P5E_CPU0_P1_RX_DP<2>")
	)
	(segment
		(start 347.180662 -287.389824)
		(end 347.112336 -287.3502)
		(width 0.1143)
		(layer "In11.Cu")
		(net "P5E_CPU0_P1_RX_DP<2>")
	)
	(segment
		(start 347.145102 -282.509214)
		(end 347.144086 -282.508706)
		(width 0.1143)
		(layer "In11.Cu")
		(net "P5E_CPU0_P1_RX_DP<2>")
	)
	(segment
		(start 364.89894 -329.130914)
		(end 363.78388 -326.998076)
		(width 0.14224)
		(layer "In11.Cu")
		(net "P5E_CPU0_P1_RX_DP<2>")
	)
	(segment
		(start 347.139768 -280.886154)
		(end 347.13799 -280.885138)
		(width 0.1143)
		(layer "In11.Cu")
		(net "P5E_CPU0_P1_RX_DP<2>")
	)
	(segment
		(start 346.563188 -274.896072)
		(end 346.86113 -274.896072)
		(width 0.1143)
		(layer "In11.Cu")
		(net "P5E_CPU0_P1_RX_DP<2>")
	)
	(segment
		(start 347.110558 -286.74314)
		(end 347.183202 -286.700722)
		(width 0.1143)
		(layer "In11.Cu")
		(net "P5E_CPU0_P1_RX_DP<2>")
	)
	(segment
		(start 365.887762 -334.631792)
		(end 364.89894 -329.130914)
		(width 0.14224)
		(layer "In11.Cu")
		(net "P5E_CPU0_P1_RX_DP<2>")
	)
	(segment
		(start 347.144086 -285.74873)
		(end 347.143324 -285.748222)
		(width 0.1143)
		(layer "In11.Cu")
		(net "P5E_CPU0_P1_RX_DP<2>")
	)
	(segment
		(start 346.674186 -279.433528)
		(end 346.711778 -279.41143)
		(width 0.1143)
		(layer "In11.Cu")
		(net "P5E_CPU0_P1_RX_DP<2>")
	)
	(segment
		(start 347.144086 -281.863546)
		(end 347.145102 -281.863038)
		(width 0.1143)
		(layer "In11.Cu")
		(net "P5E_CPU0_P1_RX_DP<2>")
	)
	(segment
		(start 347.183202 -282.531566)
		(end 347.176344 -282.527502)
		(width 0.1143)
		(layer "In11.Cu")
		(net "P5E_CPU0_P1_RX_DP<2>")
	)
	(segment
		(start 347.183202 -292.251384)
		(end 347.176344 -292.24732)
		(width 0.1143)
		(layer "In11.Cu")
		(net "P5E_CPU0_P1_RX_DP<2>")
	)
	(segment
		(start 347.143324 -284.12821)
		(end 347.112336 -284.11043)
		(width 0.1143)
		(layer "In11.Cu")
		(net "P5E_CPU0_P1_RX_DP<2>")
	)
	(segment
		(start 347.146626 -278.621998)
		(end 347.183202 -278.600662)
		(width 0.1143)
		(layer "In11.Cu")
		(net "P5E_CPU0_P1_RX_DP<2>")
	)
	(segment
		(start 347.145102 -281.863038)
		(end 347.146626 -281.862022)
		(width 0.1143)
		(layer "In11.Cu")
		(net "P5E_CPU0_P1_RX_DP<2>")
	)
	(segment
		(start 339.399118 -390.329928)
		(end 334.992218 -383.735072)
		(width 0.14224)
		(layer "In11.Cu")
		(net "P5E_CPU0_P1_RX_DP<2>")
	)
	(segment
		(start 347.175582 -280.906982)
		(end 347.145102 -280.889202)
		(width 0.1143)
		(layer "In11.Cu")
		(net "P5E_CPU0_P1_RX_DP<2>")
	)
	(segment
		(start 332.117192 -377.991116)
		(end 332.117192 -377.235466)
		(width 0.14224)
		(layer "In11.Cu")
		(net "P5E_CPU0_P1_RX_DP<2>")
	)
	(segment
		(start 347.143324 -290.608004)
		(end 347.112336 -290.590224)
		(width 0.1143)
		(layer "In11.Cu")
		(net "P5E_CPU0_P1_RX_DP<2>")
	)
	(segment
		(start 366.873536 -344.788998)
		(end 366.873536 -340.115398)
		(width 0.14224)
		(layer "In11.Cu")
		(net "P5E_CPU0_P1_RX_DP<2>")
	)
	(segment
		(start 339.213698 -394.031216)
		(end 339.387942 -393.930632)
		(width 0.14224)
		(layer "In11.Cu")
		(net "P5E_CPU0_P1_RX_DP<2>")
	)
	(segment
		(start 347.145102 -277.649178)
		(end 347.144086 -277.64867)
		(width 0.1143)
		(layer "In11.Cu")
		(net "P5E_CPU0_P1_RX_DP<2>")
	)
	(segment
		(start 346.671392 -280.076656)
		(end 346.642436 -280.0604)
		(width 0.1143)
		(layer "In11.Cu")
		(net "P5E_CPU0_P1_RX_DP<2>")
	)
	(segment
		(start 347.145102 -293.202868)
		(end 347.146626 -293.201852)
		(width 0.1143)
		(layer "In11.Cu")
		(net "P5E_CPU0_P1_RX_DP<2>")
	)
	(segment
		(start 339.47608 -393.428982)
		(end 339.160104 -393.113006)
		(width 0.14224)
		(layer "In11.Cu")
		(net "P5E_CPU0_P1_RX_DP<2>")
	)
	(segment
		(start 347.144086 -292.228524)
		(end 347.143324 -292.228016)
		(width 0.1143)
		(layer "In11.Cu")
		(net "P5E_CPU0_P1_RX_DP<2>")
	)
	(segment
		(start 339.47608 -393.842494)
		(end 339.47608 -393.428982)
		(width 0.14224)
		(layer "In11.Cu")
		(net "P5E_CPU0_P1_RX_DP<2>")
	)
	(segment
		(start 347.144086 -282.508706)
		(end 347.143324 -282.508198)
		(width 0.1143)
		(layer "In11.Cu")
		(net "P5E_CPU0_P1_RX_DP<2>")
	)
	(segment
		(start 332.51775 -376.268488)
		(end 334.216502 -374.569736)
		(width 0.14224)
		(layer "In11.Cu")
		(net "P5E_CPU0_P1_RX_DP<2>")
	)
	(segment
		(start 365.888016 -334.631792)
		(end 365.887762 -334.631792)
		(width 0.14224)
		(layer "In11.Cu")
		(net "P5E_CPU0_P1_RX_DP<2>")
	)
	(segment
		(start 347.146626 -283.482034)
		(end 347.183202 -283.460698)
		(width 0.1143)
		(layer "In11.Cu")
		(net "P5E_CPU0_P1_RX_DP<2>")
	)
	(segment
		(start 347.175582 -282.526994)
		(end 347.145102 -282.509214)
		(width 0.1143)
		(layer "In11.Cu")
		(net "P5E_CPU0_P1_RX_DP<2>")
	)
	(segment
		(start 347.143324 -291.583872)
		(end 347.144086 -291.583364)
		(width 0.1143)
		(layer "In11.Cu")
		(net "P5E_CPU0_P1_RX_DP<2>")
	)
	(segment
		(start 347.146626 -277.650194)
		(end 347.145102 -277.649178)
		(width 0.1143)
		(layer "In11.Cu")
		(net "P5E_CPU0_P1_RX_DP<2>")
	)
	(segment
		(start 347.144086 -276.028658)
		(end 347.143324 -276.02815)
		(width 0.1143)
		(layer "In11.Cu")
		(net "P5E_CPU0_P1_RX_DP<2>")
	)
	(segment
		(start 347.144086 -294.823388)
		(end 347.145102 -294.82288)
		(width 0.1143)
		(layer "In11.Cu")
		(net "P5E_CPU0_P1_RX_DP<2>")
	)
	(segment
		(start 366.873536 -340.115398)
		(end 365.888016 -334.631792)
		(width 0.14224)
		(layer "In11.Cu")
		(net "P5E_CPU0_P1_RX_DP<2>")
	)
	(segment
		(start 347.145102 -289.962844)
		(end 347.146626 -289.961828)
		(width 0.1143)
		(layer "In11.Cu")
		(net "P5E_CPU0_P1_RX_DP<2>")
	)
	(segment
		(start 347.112336 -291.601652)
		(end 347.143324 -291.583872)
		(width 0.1143)
		(layer "In11.Cu")
		(net "P5E_CPU0_P1_RX_DP<2>")
	)
	(segment
		(start 347.175582 -292.246812)
		(end 347.145102 -292.229032)
		(width 0.1143)
		(layer "In11.Cu")
		(net "P5E_CPU0_P1_RX_DP<2>")
	)
	(segment
		(start 347.145102 -291.582856)
		(end 347.146626 -291.58184)
		(width 0.1143)
		(layer "In11.Cu")
		(net "P5E_CPU0_P1_RX_DP<2>")
	)
	(segment
		(start 347.176344 -292.24732)
		(end 347.175582 -292.246812)
		(width 0.1143)
		(layer "In11.Cu")
		(net "P5E_CPU0_P1_RX_DP<2>")
	)
	(segment
		(start 347.175582 -293.866824)
		(end 347.145102 -293.849044)
		(width 0.1143)
		(layer "In11.Cu")
		(net "P5E_CPU0_P1_RX_DP<2>")
	)
	(segment
		(start 347.145102 -292.229032)
		(end 347.144086 -292.228524)
		(width 0.1143)
		(layer "In11.Cu")
		(net "P5E_CPU0_P1_RX_DP<2>")
	)
	(segment
		(start 346.5322 -299.287692)
		(end 346.5322 -296.46372)
		(width 0.14224)
		(layer "In11.Cu")
		(net "P5E_CPU0_P1_RX_DP<2>")
	)
	(segment
		(start 347.144086 -290.608512)
		(end 347.143324 -290.608004)
		(width 0.1143)
		(layer "In11.Cu")
		(net "P5E_CPU0_P1_RX_DP<2>")
	)
	(segment
		(start 346.685362 -280.085038)
		(end 346.671392 -280.076656)
		(width 0.1143)
		(layer "In11.Cu")
		(net "P5E_CPU0_P1_RX_DP<2>")
	)
	(segment
		(start 346.5322 -296.46372)
		(end 346.5322 -296.435272)
		(width 0.1143)
		(layer "In11.Cu")
		(net "P5E_CPU0_P1_RX_DP<2>")
	)
	(segment
		(start 347.144086 -284.128718)
		(end 347.143324 -284.12821)
		(width 0.1143)
		(layer "In11.Cu")
		(net "P5E_CPU0_P1_RX_DP<2>")
	)
	(segment
		(start 347.145102 -288.989008)
		(end 347.144086 -288.9885)
		(width 0.1143)
		(layer "In11.Cu")
		(net "P5E_CPU0_P1_RX_DP<2>")
	)
	(segment
		(start 346.710508 -275.239734)
		(end 346.642436 -275.200364)
		(width 0.1143)
		(layer "In11.Cu")
		(net "P5E_CPU0_P1_RX_DP<2>")
	)
	(segment
		(start 347.141292 -280.88717)
		(end 347.139768 -280.886154)
		(width 0.1143)
		(layer "In11.Cu")
		(net "P5E_CPU0_P1_RX_DP<2>")
	)
	(segment
		(start 346.493338 -274.965922)
		(end 346.563188 -274.896072)
		(width 0.1143)
		(layer "In11.Cu")
		(net "P5E_CPU0_P1_RX_DP<2>")
	)
	(segment
		(start 335.865978 -373.46763)
		(end 344.947748 -369.70589)
		(width 0.14224)
		(layer "In11.Cu")
		(net "P5E_CPU0_P1_RX_DP<2>")
	)
	(segment
		(start 346.5322 -296.435272)
		(end 346.48648 -296.389552)
		(width 0.1143)
		(layer "In11.Cu")
		(net "P5E_CPU0_P1_RX_DP<2>")
	)
	(segment
		(start 347.145102 -285.103062)
		(end 347.146626 -285.102046)
		(width 0.1143)
		(layer "In11.Cu")
		(net "P5E_CPU0_P1_RX_DP<2>")
	)
	(segment
		(start 347.176344 -285.767526)
		(end 347.175582 -285.767018)
		(width 0.1143)
		(layer "In11.Cu")
		(net "P5E_CPU0_P1_RX_DP<2>")
	)
	(segment
		(start 346.95638 -278.947626)
		(end 346.95638 -278.946102)
		(width 0.1143)
		(layer "In11.Cu")
		(net "P5E_CPU0_P1_RX_DP<2>")
	)
	(segment
		(start 347.112336 -289.98164)
		(end 347.143324 -289.96386)
		(width 0.1143)
		(layer "In11.Cu")
		(net "P5E_CPU0_P1_RX_DP<2>")
	)
	(segment
		(start 347.176344 -280.90749)
		(end 347.175582 -280.906982)
		(width 0.1143)
		(layer "In11.Cu")
		(net "P5E_CPU0_P1_RX_DP<2>")
	)
	(segment
		(start 347.143324 -294.823896)
		(end 347.144086 -294.823388)
		(width 0.1143)
		(layer "In11.Cu")
		(net "P5E_CPU0_P1_RX_DP<2>")
	)
	(segment
		(start 347.145102 -276.029166)
		(end 347.144086 -276.028658)
		(width 0.1143)
		(layer "In11.Cu")
		(net "P5E_CPU0_P1_RX_DP<2>")
	)
	(segment
		(start 347.143324 -292.228016)
		(end 347.112336 -292.210236)
		(width 0.1143)
		(layer "In11.Cu")
		(net "P5E_CPU0_P1_RX_DP<2>")
	)
	(segment
		(start 347.112336 -287.3502)
		(end 347.105986 -287.345628)
		(width 0.1143)
		(layer "In11.Cu")
		(net "P5E_CPU0_P1_RX_DP<2>")
	)
	(arc
		(start 332.117192 -377.235466)
		(mid 332.221289 -376.712133)
		(end 332.51775 -376.268488)
		(width 0.14224)
		(layer "In11.Cu")
		(net "P5E_CPU0_P1_RX_DP<2>")
	)
	(arc
		(start 347.183202 -278.600662)
		(mid 347.426529 -278.136096)
		(end 347.183202 -277.67153)
		(width 0.1143)
		(layer "In11.Cu")
		(net "P5E_CPU0_P1_RX_DP<2>")
	)
	(arc
		(start 334.992218 -383.735072)
		(mid 334.827182 -383.474006)
		(end 334.67548 -383.204974)
		(width 0.14224)
		(layer "In11.Cu")
		(net "P5E_CPU0_P1_RX_DP<2>")
	)
	(arc
		(start 347.143324 -276.02815)
		(mid 347.011605 -275.887294)
		(end 346.95638 -275.702522)
		(width 0.1143)
		(layer "In11.Cu")
		(net "P5E_CPU0_P1_RX_DP<2>")
	)
	(arc
		(start 346.95638 -275.69795)
		(mid 346.885003 -275.441173)
		(end 346.710508 -275.239734)
		(width 0.1143)
		(layer "In11.Cu")
		(net "P5E_CPU0_P1_RX_DP<2>")
	)
	(arc
		(start 333.655924 -378.926344)
		(mid 333.557621 -378.789097)
		(end 333.416148 -378.696982)
		(width 0.14224)
		(layer "In11.Cu")
		(net "P5E_CPU0_P1_RX_DP<2>")
	)
	(arc
		(start 333.749396 -379.33503)
		(mid 333.724125 -379.125776)
		(end 333.655924 -378.926344)
		(width 0.14224)
		(layer "In11.Cu")
		(net "P5E_CPU0_P1_RX_DP<2>")
	)
	(arc
		(start 347.112336 -277.630382)
		(mid 346.960747 -277.32609)
		(end 347.112336 -277.021798)
		(width 0.1143)
		(layer "In11.Cu")
		(net "P5E_CPU0_P1_RX_DP<2>")
	)
	(arc
		(start 346.95638 -287.045908)
		(mid 346.997142 -286.876024)
		(end 347.110558 -286.74314)
		(width 0.1143)
		(layer "In11.Cu")
		(net "P5E_CPU0_P1_RX_DP<2>")
	)
	(arc
		(start 347.112336 -282.490418)
		(mid 346.961951 -282.186126)
		(end 347.112336 -281.881834)
		(width 0.1143)
		(layer "In11.Cu")
		(net "P5E_CPU0_P1_RX_DP<2>")
	)
	(arc
		(start 333.082138 -378.558806)
		(mid 332.983106 -378.527648)
		(end 332.880208 -378.513848)
		(width 0.14224)
		(layer "In11.Cu")
		(net "P5E_CPU0_P1_RX_DP<2>")
	)
	(arc
		(start 347.105986 -287.345628)
		(mid 346.995945 -287.217624)
		(end 346.95638 -287.053528)
		(width 0.1143)
		(layer "In11.Cu")
		(net "P5E_CPU0_P1_RX_DP<2>")
	)
	(arc
		(start 344.947748 -369.70589)
		(mid 347.584105 -368.296588)
		(end 349.894906 -366.40008)
		(width 0.14224)
		(layer "In11.Cu")
		(net "P5E_CPU0_P1_RX_DP<2>")
	)
	(arc
		(start 347.183202 -289.940492)
		(mid 347.426529 -289.475926)
		(end 347.183202 -289.01136)
		(width 0.1143)
		(layer "In11.Cu")
		(net "P5E_CPU0_P1_RX_DP<2>")
	)
	(arc
		(start 346.95638 -275.702522)
		(mid 346.956385 -275.700236)
		(end 346.95638 -275.69795)
		(width 0.1143)
		(layer "In11.Cu")
		(net "P5E_CPU0_P1_RX_DP<2>")
	)
	(arc
		(start 346.95638 -288.66592)
		(mid 346.997142 -288.496036)
		(end 347.110558 -288.363152)
		(width 0.1143)
		(layer "In11.Cu")
		(net "P5E_CPU0_P1_RX_DP<2>")
	)
	(arc
		(start 347.112336 -285.730442)
		(mid 346.963239 -285.42615)
		(end 347.112336 -285.121858)
		(width 0.1143)
		(layer "In11.Cu")
		(net "P5E_CPU0_P1_RX_DP<2>")
	)
	(arc
		(start 332.754478 -378.496322)
		(mid 332.564544 -378.433755)
		(end 332.387448 -378.340874)
		(width 0.14224)
		(layer "In11.Cu")
		(net "P5E_CPU0_P1_RX_DP<2>")
	)
	(arc
		(start 347.426534 -287.856168)
		(mid 347.361298 -287.592577)
		(end 347.180662 -287.389824)
		(width 0.1143)
		(layer "In11.Cu")
		(net "P5E_CPU0_P1_RX_DP<2>")
	)
	(arc
		(start 332.138528 -378.061728)
		(mid 332.12261 -378.028005)
		(end 332.117192 -377.991116)
		(width 0.14224)
		(layer "In11.Cu")
		(net "P5E_CPU0_P1_RX_DP<2>")
	)
	(arc
		(start 360.557826 -355.73716)
		(mid 363.644369 -351.976092)
		(end 365.9378 -347.685106)
		(width 0.14224)
		(layer "In11.Cu")
		(net "P5E_CPU0_P1_RX_DP<2>")
	)
	(arc
		(start 347.183202 -286.700722)
		(mid 347.426529 -286.236156)
		(end 347.183202 -285.77159)
		(width 0.1143)
		(layer "In11.Cu")
		(net "P5E_CPU0_P1_RX_DP<2>")
	)
	(arc
		(start 339.467952 -390.557258)
		(mid 339.450411 -390.43848)
		(end 339.399118 -390.329928)
		(width 0.14224)
		(layer "In11.Cu")
		(net "P5E_CPU0_P1_RX_DP<2>")
	)
	(arc
		(start 347.112336 -284.11043)
		(mid 346.961951 -283.806138)
		(end 347.112336 -283.501846)
		(width 0.1143)
		(layer "In11.Cu")
		(net "P5E_CPU0_P1_RX_DP<2>")
	)
	(arc
		(start 333.817214 -379.786134)
		(mid 333.805633 -379.628875)
		(end 333.77124 -379.474984)
		(width 0.14224)
		(layer "In11.Cu")
		(net "P5E_CPU0_P1_RX_DP<2>")
	)
	(arc
		(start 347.128592 -280.879804)
		(mid 347.010139 -280.761846)
		(end 346.966794 -280.600404)
		(width 0.1143)
		(layer "In11.Cu")
		(net "P5E_CPU0_P1_RX_DP<2>")
	)
	(arc
		(start 332.387448 -378.340874)
		(mid 332.336393 -378.303275)
		(end 332.290674 -378.25934)
		(width 0.14224)
		(layer "In11.Cu")
		(net "P5E_CPU0_P1_RX_DP<2>")
	)
	(arc
		(start 346.711778 -279.41143)
		(mid 346.891459 -279.209794)
		(end 346.95638 -278.947626)
		(width 0.1143)
		(layer "In11.Cu")
		(net "P5E_CPU0_P1_RX_DP<2>")
	)
	(arc
		(start 346.642436 -275.200364)
		(mid 346.545301 -275.097495)
		(end 346.493338 -274.965922)
		(width 0.1143)
		(layer "In11.Cu")
		(net "P5E_CPU0_P1_RX_DP<2>")
	)
	(arc
		(start 347.183202 -285.08071)
		(mid 347.426529 -284.616144)
		(end 347.183202 -284.151578)
		(width 0.1143)
		(layer "In11.Cu")
		(net "P5E_CPU0_P1_RX_DP<2>")
	)
	(arc
		(start 347.183202 -294.800528)
		(mid 347.426529 -294.335962)
		(end 347.183202 -293.871396)
		(width 0.1143)
		(layer "In11.Cu")
		(net "P5E_CPU0_P1_RX_DP<2>")
	)
	(arc
		(start 347.183202 -281.840686)
		(mid 347.426529 -281.37612)
		(end 347.183202 -280.911554)
		(width 0.1143)
		(layer "In11.Cu")
		(net "P5E_CPU0_P1_RX_DP<2>")
	)
	(arc
		(start 347.112336 -288.970212)
		(mid 347.000539 -288.835411)
		(end 346.95638 -288.66592)
		(width 0.1143)
		(layer "In11.Cu")
		(net "P5E_CPU0_P1_RX_DP<2>")
	)
	(arc
		(start 347.112336 -292.210236)
		(mid 346.960747 -291.905944)
		(end 347.112336 -291.601652)
		(width 0.1143)
		(layer "In11.Cu")
		(net "P5E_CPU0_P1_RX_DP<2>")
	)
	(arc
		(start 347.183202 -283.460698)
		(mid 347.426529 -282.996132)
		(end 347.183202 -282.531566)
		(width 0.1143)
		(layer "In11.Cu")
		(net "P5E_CPU0_P1_RX_DP<2>")
	)
	(arc
		(start 346.642436 -280.0604)
		(mid 346.486508 -279.756108)
		(end 346.642436 -279.451816)
		(width 0.1143)
		(layer "In11.Cu")
		(net "P5E_CPU0_P1_RX_DP<2>")
	)
	(arc
		(start 332.880208 -378.513848)
		(mid 332.816926 -378.508078)
		(end 332.754478 -378.496322)
		(width 0.14224)
		(layer "In11.Cu")
		(net "P5E_CPU0_P1_RX_DP<2>")
	)
	(arc
		(start 347.112336 -293.830248)
		(mid 346.963239 -293.525956)
		(end 347.112336 -293.221664)
		(width 0.1143)
		(layer "In11.Cu")
		(net "P5E_CPU0_P1_RX_DP<2>")
	)
	(arc
		(start 347.112336 -290.590224)
		(mid 346.963239 -290.285932)
		(end 347.112336 -289.98164)
		(width 0.1143)
		(layer "In11.Cu")
		(net "P5E_CPU0_P1_RX_DP<2>")
	)
	(arc
		(start 347.183202 -293.180516)
		(mid 347.426529 -292.71595)
		(end 347.183202 -292.251384)
		(width 0.1143)
		(layer "In11.Cu")
		(net "P5E_CPU0_P1_RX_DP<2>")
	)
	(arc
		(start 333.77124 -379.474984)
		(mid 333.755468 -379.405764)
		(end 333.749396 -379.33503)
		(width 0.14224)
		(layer "In11.Cu")
		(net "P5E_CPU0_P1_RX_DP<2>")
	)
	(arc
		(start 334.216502 -374.569736)
		(mid 334.986974 -373.937467)
		(end 335.865978 -373.46763)
		(width 0.14224)
		(layer "In11.Cu")
		(net "P5E_CPU0_P1_RX_DP<2>")
	)
	(arc
		(start 332.290674 -378.25934)
		(mid 332.218841 -378.174743)
		(end 332.153768 -378.084842)
		(width 0.14224)
		(layer "In11.Cu")
		(net "P5E_CPU0_P1_RX_DP<2>")
	)
	(arc
		(start 346.966794 -280.573988)
		(mid 346.891407 -280.291915)
		(end 346.685362 -280.085038)
		(width 0.1143)
		(layer "In11.Cu")
		(net "P5E_CPU0_P1_RX_DP<2>")
	)
	(arc
		(start 366.629696 -346.014802)
		(mid 366.811961 -345.413906)
		(end 366.873536 -344.788998)
		(width 0.14224)
		(layer "In11.Cu")
		(net "P5E_CPU0_P1_RX_DP<2>")
	)
	(arc
		(start 346.95638 -295.145968)
		(mid 347.000451 -294.976432)
		(end 347.112336 -294.841676)
		(width 0.1143)
		(layer "In11.Cu")
		(net "P5E_CPU0_P1_RX_DP<2>")
	)
	(arc
		(start 347.183202 -288.320734)
		(mid 347.362015 -288.118384)
		(end 347.426534 -287.856168)
		(width 0.1143)
		(layer "In11.Cu")
		(net "P5E_CPU0_P1_RX_DP<2>")
	)
	(arc
		(start 334.67548 -383.204974)
		(mid 334.646925 -383.148093)
		(end 334.621124 -383.089912)
		(width 0.14224)
		(layer "In11.Cu")
		(net "P5E_CPU0_P1_RX_DP<2>")
	)
	(arc
		(start 346.95638 -278.946102)
		(mid 346.997635 -278.775131)
		(end 347.112336 -278.64181)
		(width 0.1143)
		(layer "In11.Cu")
		(net "P5E_CPU0_P1_RX_DP<2>")
	)
	(arc
		(start 347.183202 -291.560504)
		(mid 347.426529 -291.095938)
		(end 347.183202 -290.631372)
		(width 0.1143)
		(layer "In11.Cu")
		(net "P5E_CPU0_P1_RX_DP<2>")
	)
	(arc
		(start 333.841852 -381.208788)
		(mid 333.823454 -381.148407)
		(end 333.817214 -381.085598)
		(width 0.14224)
		(layer "In11.Cu")
		(net "P5E_CPU0_P1_RX_DP<2>")
	)
	(arc
		(start 347.183202 -276.98065)
		(mid 347.426529 -276.516084)
		(end 347.183202 -276.051518)
		(width 0.1143)
		(layer "In11.Cu")
		(net "P5E_CPU0_P1_RX_DP<2>")
	)
	(segment
		(start 347.327982 -277.870158)
		(end 346.86113 -278.136096)
		(width 0.12954)
		(layer "F.Cu")
		(net "P5E_CPU0_P1_RX_DP<1>")
	)
	(segment
		(start 337.398106 -394.385292)
		(end 337.918806 -394.385292)
		(width 0.127)
		(layer "F.Cu")
		(net "P5E_CPU0_P1_RX_DP<1>")
	)
	(segment
		(start 345.546426 -296.389552)
		(end 345.546426 -295.948862)
		(width 0.1143)
		(layer "In11.Cu")
		(net "P5E_CPU0_P1_RX_DP<1>")
	)
	(segment
		(start 338.199984 -390.589008)
		(end 338.19973 -390.588754)
		(width 0.14224)
		(layer "In11.Cu")
		(net "P5E_CPU0_P1_RX_DP<1>")
	)
	(segment
		(start 356.58298 -319.719706)
		(end 349.750634 -309.494174)
		(width 0.14224)
		(layer "In11.Cu")
		(net "P5E_CPU0_P1_RX_DP<1>")
	)
	(segment
		(start 346.17152 -286.742378)
		(end 346.204032 -286.723582)
		(width 0.1143)
		(layer "In11.Cu")
		(net "P5E_CPU0_P1_RX_DP<1>")
	)
	(segment
		(start 364.540546 -348.235016)
		(end 365.49076 -345.940634)
		(width 0.14224)
		(layer "In11.Cu")
		(net "P5E_CPU0_P1_RX_DP<1>")
	)
	(segment
		(start 345.72829 -280.075386)
		(end 345.727528 -280.074878)
		(width 0.1143)
		(layer "In11.Cu")
		(net "P5E_CPU0_P1_RX_DP<1>")
	)
	(segment
		(start 338.276184 -393.842494)
		(end 338.276184 -393.428982)
		(width 0.14224)
		(layer "In11.Cu")
		(net "P5E_CPU0_P1_RX_DP<1>")
	)
	(segment
		(start 346.173552 -291.601144)
		(end 346.243148 -291.560504)
		(width 0.1143)
		(layer "In11.Cu")
		(net "P5E_CPU0_P1_RX_DP<1>")
	)
	(segment
		(start 346.243148 -285.77159)
		(end 346.173552 -285.73095)
		(width 0.1143)
		(layer "In11.Cu")
		(net "P5E_CPU0_P1_RX_DP<1>")
	)
	(segment
		(start 363.99597 -329.42149)
		(end 363.032548 -327.57872)
		(width 0.14224)
		(layer "In11.Cu")
		(net "P5E_CPU0_P1_RX_DP<1>")
	)
	(segment
		(start 345.592146 -299.45457)
		(end 345.592146 -296.46372)
		(width 0.14224)
		(layer "In11.Cu")
		(net "P5E_CPU0_P1_RX_DP<1>")
	)
	(segment
		(start 345.76639 -280.097484)
		(end 345.765628 -280.096976)
		(width 0.1143)
		(layer "In11.Cu")
		(net "P5E_CPU0_P1_RX_DP<1>")
	)
	(segment
		(start 349.050864 -365.887254)
		(end 360.185716 -354.752402)
		(width 0.14224)
		(layer "In11.Cu")
		(net "P5E_CPU0_P1_RX_DP<1>")
	)
	(segment
		(start 345.726512 -280.07437)
		(end 345.702382 -280.0604)
		(width 0.1143)
		(layer "In11.Cu")
		(net "P5E_CPU0_P1_RX_DP<1>")
	)
	(segment
		(start 346.173552 -289.981132)
		(end 346.243148 -289.940492)
		(width 0.1143)
		(layer "In11.Cu")
		(net "P5E_CPU0_P1_RX_DP<1>")
	)
	(segment
		(start 349.750634 -309.494174)
		(end 345.592146 -299.45457)
		(width 0.14224)
		(layer "In11.Cu")
		(net "P5E_CPU0_P1_RX_DP<1>")
	)
	(segment
		(start 345.592146 -296.435272)
		(end 345.546426 -296.389552)
		(width 0.1143)
		(layer "In11.Cu")
		(net "P5E_CPU0_P1_RX_DP<1>")
	)
	(segment
		(start 345.734132 -280.078688)
		(end 345.73337 -280.07818)
		(width 0.1143)
		(layer "In11.Cu")
		(net "P5E_CPU0_P1_RX_DP<1>")
	)
	(segment
		(start 330.489814 -376.899678)
		(end 333.425038 -373.964454)
		(width 0.14224)
		(layer "In11.Cu")
		(net "P5E_CPU0_P1_RX_DP<1>")
	)
	(segment
		(start 338.268056 -392.43)
		(end 338.268056 -390.815322)
		(width 0.14224)
		(layer "In11.Cu")
		(net "P5E_CPU0_P1_RX_DP<1>")
	)
	(segment
		(start 345.734132 -279.433528)
		(end 345.735148 -279.43302)
		(width 0.1143)
		(layer "In11.Cu")
		(net "P5E_CPU0_P1_RX_DP<1>")
	)
	(segment
		(start 338.276184 -393.428982)
		(end 337.960208 -393.113006)
		(width 0.14224)
		(layer "In11.Cu")
		(net "P5E_CPU0_P1_RX_DP<1>")
	)
	(segment
		(start 345.702382 -279.451816)
		(end 345.727782 -279.437084)
		(width 0.1143)
		(layer "In11.Cu")
		(net "P5E_CPU0_P1_RX_DP<1>")
	)
	(segment
		(start 345.765628 -280.096976)
		(end 345.734132 -280.078688)
		(width 0.1143)
		(layer "In11.Cu")
		(net "P5E_CPU0_P1_RX_DP<1>")
	)
	(segment
		(start 346.016326 -295.478962)
		(end 346.016326 -295.192958)
		(width 0.1143)
		(layer "In11.Cu")
		(net "P5E_CPU0_P1_RX_DP<1>")
	)
	(segment
		(start 346.480384 -278.2189)
		(end 346.563188 -278.136096)
		(width 0.1143)
		(layer "In11.Cu")
		(net "P5E_CPU0_P1_RX_DP<1>")
	)
	(segment
		(start 346.173552 -278.641302)
		(end 346.243148 -278.600662)
		(width 0.1143)
		(layer "In11.Cu")
		(net "P5E_CPU0_P1_RX_DP<1>")
	)
	(segment
		(start 345.727782 -279.437084)
		(end 345.729814 -279.436068)
		(width 0.1143)
		(layer "In11.Cu")
		(net "P5E_CPU0_P1_RX_DP<1>")
	)
	(segment
		(start 346.173552 -281.881326)
		(end 346.243148 -281.840686)
		(width 0.1143)
		(layer "In11.Cu")
		(net "P5E_CPU0_P1_RX_DP<1>")
	)
	(segment
		(start 346.243148 -282.531566)
		(end 346.173552 -282.490926)
		(width 0.1143)
		(layer "In11.Cu")
		(net "P5E_CPU0_P1_RX_DP<1>")
	)
	(segment
		(start 338.19973 -390.589008)
		(end 338.199984 -390.589008)
		(width 0.14224)
		(layer "In11.Cu")
		(net "P5E_CPU0_P1_RX_DP<1>")
	)
	(segment
		(start 346.204032 -286.723582)
		(end 346.243148 -286.700722)
		(width 0.1143)
		(layer "In11.Cu")
		(net "P5E_CPU0_P1_RX_DP<1>")
	)
	(segment
		(start 345.73337 -280.07818)
		(end 345.730576 -280.076656)
		(width 0.1143)
		(layer "In11.Cu")
		(net "P5E_CPU0_P1_RX_DP<1>")
	)
	(segment
		(start 345.773248 -280.101548)
		(end 345.76639 -280.097484)
		(width 0.1143)
		(layer "In11.Cu")
		(net "P5E_CPU0_P1_RX_DP<1>")
	)
	(segment
		(start 346.243148 -284.151578)
		(end 346.173552 -284.110938)
		(width 0.1143)
		(layer "In11.Cu")
		(net "P5E_CPU0_P1_RX_DP<1>")
	)
	(segment
		(start 346.243148 -289.01136)
		(end 346.173552 -288.97072)
		(width 0.1143)
		(layer "In11.Cu")
		(net "P5E_CPU0_P1_RX_DP<1>")
	)
	(segment
		(start 346.243148 -290.631372)
		(end 346.173552 -290.590732)
		(width 0.1143)
		(layer "In11.Cu")
		(net "P5E_CPU0_P1_RX_DP<1>")
	)
	(segment
		(start 345.729814 -279.436068)
		(end 345.730576 -279.43556)
		(width 0.1143)
		(layer "In11.Cu")
		(net "P5E_CPU0_P1_RX_DP<1>")
	)
	(segment
		(start 346.243148 -293.871396)
		(end 346.173552 -293.830756)
		(width 0.1143)
		(layer "In11.Cu")
		(net "P5E_CPU0_P1_RX_DP<1>")
	)
	(segment
		(start 345.592146 -296.46372)
		(end 345.592146 -296.435272)
		(width 0.1143)
		(layer "In11.Cu")
		(net "P5E_CPU0_P1_RX_DP<1>")
	)
	(segment
		(start 345.730576 -279.43556)
		(end 345.73337 -279.434036)
		(width 0.1143)
		(layer "In11.Cu")
		(net "P5E_CPU0_P1_RX_DP<1>")
	)
	(segment
		(start 337.960208 -393.113006)
		(end 337.963256 -392.7348)
		(width 0.14224)
		(layer "In11.Cu")
		(net "P5E_CPU0_P1_RX_DP<1>")
	)
	(segment
		(start 345.73337 -279.434036)
		(end 345.734132 -279.433528)
		(width 0.1143)
		(layer "In11.Cu")
		(net "P5E_CPU0_P1_RX_DP<1>")
	)
	(segment
		(start 345.736672 -279.432004)
		(end 345.773248 -279.410668)
		(width 0.1143)
		(layer "In11.Cu")
		(net "P5E_CPU0_P1_RX_DP<1>")
	)
	(segment
		(start 365.912146 -340.080346)
		(end 363.99597 -329.42149)
		(width 0.14224)
		(layer "In11.Cu")
		(net "P5E_CPU0_P1_RX_DP<1>")
	)
	(segment
		(start 338.013802 -394.031216)
		(end 338.188046 -393.930632)
		(width 0.14224)
		(layer "In11.Cu")
		(net "P5E_CPU0_P1_RX_DP<1>")
	)
	(segment
		(start 346.016326 -295.192958)
		(end 346.01658 -295.145968)
		(width 0.1143)
		(layer "In11.Cu")
		(net "P5E_CPU0_P1_RX_DP<1>")
	)
	(segment
		(start 337.963256 -392.7348)
		(end 338.268056 -392.43)
		(width 0.14224)
		(layer "In11.Cu")
		(net "P5E_CPU0_P1_RX_DP<1>")
	)
	(segment
		(start 346.243148 -280.911554)
		(end 346.173552 -280.870914)
		(width 0.1143)
		(layer "In11.Cu")
		(net "P5E_CPU0_P1_RX_DP<1>")
	)
	(segment
		(start 346.173552 -283.501338)
		(end 346.243148 -283.460698)
		(width 0.1143)
		(layer "In11.Cu")
		(net "P5E_CPU0_P1_RX_DP<1>")
	)
	(segment
		(start 330.400152 -380.619254)
		(end 330.400152 -377.116086)
		(width 0.14224)
		(layer "In11.Cu")
		(net "P5E_CPU0_P1_RX_DP<1>")
	)
	(segment
		(start 346.240608 -287.389824)
		(end 346.173552 -287.350708)
		(width 0.1143)
		(layer "In11.Cu")
		(net "P5E_CPU0_P1_RX_DP<1>")
	)
	(segment
		(start 346.204032 -288.343594)
		(end 346.243148 -288.320734)
		(width 0.1143)
		(layer "In11.Cu")
		(net "P5E_CPU0_P1_RX_DP<1>")
	)
	(segment
		(start 345.735148 -279.43302)
		(end 345.736672 -279.432004)
		(width 0.1143)
		(layer "In11.Cu")
		(net "P5E_CPU0_P1_RX_DP<1>")
	)
	(segment
		(start 363.032548 -327.57872)
		(end 356.58298 -319.719706)
		(width 0.14224)
		(layer "In11.Cu")
		(net "P5E_CPU0_P1_RX_DP<1>")
	)
	(segment
		(start 345.546426 -295.948862)
		(end 346.016326 -295.478962)
		(width 0.1143)
		(layer "In11.Cu")
		(net "P5E_CPU0_P1_RX_DP<1>")
	)
	(segment
		(start 346.173552 -293.221156)
		(end 346.243148 -293.180516)
		(width 0.1143)
		(layer "In11.Cu")
		(net "P5E_CPU0_P1_RX_DP<1>")
	)
	(segment
		(start 345.729814 -280.076148)
		(end 345.72829 -280.075386)
		(width 0.1143)
		(layer "In11.Cu")
		(net "P5E_CPU0_P1_RX_DP<1>")
	)
	(segment
		(start 338.188046 -393.930632)
		(end 338.276184 -393.842494)
		(width 0.14224)
		(layer "In11.Cu")
		(net "P5E_CPU0_P1_RX_DP<1>")
	)
	(segment
		(start 346.173552 -285.12135)
		(end 346.243148 -285.08071)
		(width 0.1143)
		(layer "In11.Cu")
		(net "P5E_CPU0_P1_RX_DP<1>")
	)
	(segment
		(start 365.912146 -343.821766)
		(end 365.912146 -340.080346)
		(width 0.14224)
		(layer "In11.Cu")
		(net "P5E_CPU0_P1_RX_DP<1>")
	)
	(segment
		(start 337.918806 -394.385292)
		(end 338.013802 -394.031216)
		(width 0.14224)
		(layer "In11.Cu")
		(net "P5E_CPU0_P1_RX_DP<1>")
	)
	(segment
		(start 335.447894 -372.61292)
		(end 344.755724 -368.7572)
		(width 0.14224)
		(layer "In11.Cu")
		(net "P5E_CPU0_P1_RX_DP<1>")
	)
	(segment
		(start 346.563188 -278.136096)
		(end 346.86113 -278.136096)
		(width 0.1143)
		(layer "In11.Cu")
		(net "P5E_CPU0_P1_RX_DP<1>")
	)
	(segment
		(start 346.243148 -292.251384)
		(end 346.173552 -292.210744)
		(width 0.1143)
		(layer "In11.Cu")
		(net "P5E_CPU0_P1_RX_DP<1>")
	)
	(segment
		(start 345.727528 -280.074878)
		(end 345.726512 -280.07437)
		(width 0.1143)
		(layer "In11.Cu")
		(net "P5E_CPU0_P1_RX_DP<1>")
	)
	(segment
		(start 333.138526 -383.410206)
		(end 330.43749 -380.70917)
		(width 0.14224)
		(layer "In11.Cu")
		(net "P5E_CPU0_P1_RX_DP<1>")
	)
	(segment
		(start 346.17152 -288.36239)
		(end 346.204032 -288.343594)
		(width 0.1143)
		(layer "In11.Cu")
		(net "P5E_CPU0_P1_RX_DP<1>")
	)
	(segment
		(start 346.173552 -294.841168)
		(end 346.243148 -294.800528)
		(width 0.1143)
		(layer "In11.Cu")
		(net "P5E_CPU0_P1_RX_DP<1>")
	)
	(segment
		(start 345.730576 -280.076656)
		(end 345.729814 -280.076148)
		(width 0.1143)
		(layer "In11.Cu")
		(net "P5E_CPU0_P1_RX_DP<1>")
	)
	(segment
		(start 338.19973 -390.588754)
		(end 334.68818 -385.303522)
		(width 0.14224)
		(layer "In11.Cu")
		(net "P5E_CPU0_P1_RX_DP<1>")
	)
	(arc
		(start 346.01658 -287.045908)
		(mid 346.057546 -286.875502)
		(end 346.17152 -286.742378)
		(width 0.1143)
		(layer "In11.Cu")
		(net "P5E_CPU0_P1_RX_DP<1>")
	)
	(arc
		(start 345.702382 -280.0604)
		(mid 345.546454 -279.756108)
		(end 345.702382 -279.451816)
		(width 0.1143)
		(layer "In11.Cu")
		(net "P5E_CPU0_P1_RX_DP<1>")
	)
	(arc
		(start 346.173552 -293.830756)
		(mid 346.016575 -293.525956)
		(end 346.173552 -293.221156)
		(width 0.1143)
		(layer "In11.Cu")
		(net "P5E_CPU0_P1_RX_DP<1>")
	)
	(arc
		(start 360.185716 -354.752402)
		(mid 362.684114 -351.708183)
		(end 364.540546 -348.235016)
		(width 0.14224)
		(layer "In11.Cu")
		(net "P5E_CPU0_P1_RX_DP<1>")
	)
	(arc
		(start 346.243148 -286.700722)
		(mid 346.486475 -286.236156)
		(end 346.243148 -285.77159)
		(width 0.1143)
		(layer "In11.Cu")
		(net "P5E_CPU0_P1_RX_DP<1>")
	)
	(arc
		(start 346.243148 -283.460698)
		(mid 346.486475 -282.996132)
		(end 346.243148 -282.531566)
		(width 0.1143)
		(layer "In11.Cu")
		(net "P5E_CPU0_P1_RX_DP<1>")
	)
	(arc
		(start 346.173552 -284.110938)
		(mid 346.016575 -283.806138)
		(end 346.173552 -283.501338)
		(width 0.1143)
		(layer "In11.Cu")
		(net "P5E_CPU0_P1_RX_DP<1>")
	)
	(arc
		(start 346.01658 -295.145968)
		(mid 346.058129 -294.974546)
		(end 346.173552 -294.841168)
		(width 0.1143)
		(layer "In11.Cu")
		(net "P5E_CPU0_P1_RX_DP<1>")
	)
	(arc
		(start 346.173552 -287.350708)
		(mid 346.058125 -287.217332)
		(end 346.01658 -287.045908)
		(width 0.1143)
		(layer "In11.Cu")
		(net "P5E_CPU0_P1_RX_DP<1>")
	)
	(arc
		(start 346.48648 -287.856168)
		(mid 346.421244 -287.592577)
		(end 346.240608 -287.389824)
		(width 0.1143)
		(layer "In11.Cu")
		(net "P5E_CPU0_P1_RX_DP<1>")
	)
	(arc
		(start 330.43749 -380.70917)
		(mid 330.409871 -380.66793)
		(end 330.400152 -380.619254)
		(width 0.14224)
		(layer "In11.Cu")
		(net "P5E_CPU0_P1_RX_DP<1>")
	)
	(arc
		(start 346.01658 -278.946102)
		(mid 346.058129 -278.77468)
		(end 346.173552 -278.641302)
		(width 0.1143)
		(layer "In11.Cu")
		(net "P5E_CPU0_P1_RX_DP<1>")
	)
	(arc
		(start 334.68818 -385.303522)
		(mid 333.960491 -384.318282)
		(end 333.138526 -383.410206)
		(width 0.14224)
		(layer "In11.Cu")
		(net "P5E_CPU0_P1_RX_DP<1>")
	)
	(arc
		(start 346.243148 -291.560504)
		(mid 346.486475 -291.095938)
		(end 346.243148 -290.631372)
		(width 0.1143)
		(layer "In11.Cu")
		(net "P5E_CPU0_P1_RX_DP<1>")
	)
	(arc
		(start 346.243148 -288.320734)
		(mid 346.421961 -288.118384)
		(end 346.48648 -287.856168)
		(width 0.1143)
		(layer "In11.Cu")
		(net "P5E_CPU0_P1_RX_DP<1>")
	)
	(arc
		(start 346.243148 -289.940492)
		(mid 346.486475 -289.475926)
		(end 346.243148 -289.01136)
		(width 0.1143)
		(layer "In11.Cu")
		(net "P5E_CPU0_P1_RX_DP<1>")
	)
	(arc
		(start 344.755724 -368.7572)
		(mid 347.044633 -367.533751)
		(end 349.050864 -365.887254)
		(width 0.14224)
		(layer "In11.Cu")
		(net "P5E_CPU0_P1_RX_DP<1>")
	)
	(arc
		(start 346.01658 -280.566114)
		(mid 345.952065 -280.303895)
		(end 345.773248 -280.101548)
		(width 0.1143)
		(layer "In11.Cu")
		(net "P5E_CPU0_P1_RX_DP<1>")
	)
	(arc
		(start 333.425038 -373.964454)
		(mid 334.369905 -373.189061)
		(end 335.447894 -372.61292)
		(width 0.14224)
		(layer "In11.Cu")
		(net "P5E_CPU0_P1_RX_DP<1>")
	)
	(arc
		(start 346.173552 -288.97072)
		(mid 346.058125 -288.837344)
		(end 346.01658 -288.66592)
		(width 0.1143)
		(layer "In11.Cu")
		(net "P5E_CPU0_P1_RX_DP<1>")
	)
	(arc
		(start 345.773248 -279.410668)
		(mid 345.952061 -279.208318)
		(end 346.01658 -278.946102)
		(width 0.1143)
		(layer "In11.Cu")
		(net "P5E_CPU0_P1_RX_DP<1>")
	)
	(arc
		(start 346.243148 -281.840686)
		(mid 346.486475 -281.37612)
		(end 346.243148 -280.911554)
		(width 0.1143)
		(layer "In11.Cu")
		(net "P5E_CPU0_P1_RX_DP<1>")
	)
	(arc
		(start 346.243148 -285.08071)
		(mid 346.486475 -284.616144)
		(end 346.243148 -284.151578)
		(width 0.1143)
		(layer "In11.Cu")
		(net "P5E_CPU0_P1_RX_DP<1>")
	)
	(arc
		(start 346.173552 -280.870914)
		(mid 346.058125 -280.737538)
		(end 346.01658 -280.566114)
		(width 0.1143)
		(layer "In11.Cu")
		(net "P5E_CPU0_P1_RX_DP<1>")
	)
	(arc
		(start 346.476574 -278.24176)
		(mid 346.478597 -278.23035)
		(end 346.480384 -278.2189)
		(width 0.1143)
		(layer "In11.Cu")
		(net "P5E_CPU0_P1_RX_DP<1>")
	)
	(arc
		(start 338.268056 -390.815322)
		(mid 338.250601 -390.697121)
		(end 338.19973 -390.589008)
		(width 0.14224)
		(layer "In11.Cu")
		(net "P5E_CPU0_P1_RX_DP<1>")
	)
	(arc
		(start 365.49076 -345.940634)
		(mid 365.805773 -344.901947)
		(end 365.912146 -343.821766)
		(width 0.14224)
		(layer "In11.Cu")
		(net "P5E_CPU0_P1_RX_DP<1>")
	)
	(arc
		(start 346.173552 -282.490926)
		(mid 346.016575 -282.186126)
		(end 346.173552 -281.881326)
		(width 0.1143)
		(layer "In11.Cu")
		(net "P5E_CPU0_P1_RX_DP<1>")
	)
	(arc
		(start 346.243148 -278.600662)
		(mid 346.395135 -278.444154)
		(end 346.476574 -278.24176)
		(width 0.1143)
		(layer "In11.Cu")
		(net "P5E_CPU0_P1_RX_DP<1>")
	)
	(arc
		(start 346.173552 -290.590732)
		(mid 346.016575 -290.285932)
		(end 346.173552 -289.981132)
		(width 0.1143)
		(layer "In11.Cu")
		(net "P5E_CPU0_P1_RX_DP<1>")
	)
	(arc
		(start 346.243148 -294.800528)
		(mid 346.486475 -294.335962)
		(end 346.243148 -293.871396)
		(width 0.1143)
		(layer "In11.Cu")
		(net "P5E_CPU0_P1_RX_DP<1>")
	)
	(arc
		(start 330.400152 -377.116086)
		(mid 330.42345 -376.998958)
		(end 330.489814 -376.899678)
		(width 0.14224)
		(layer "In11.Cu")
		(net "P5E_CPU0_P1_RX_DP<1>")
	)
	(arc
		(start 346.01658 -288.66592)
		(mid 346.057546 -288.495514)
		(end 346.17152 -288.36239)
		(width 0.1143)
		(layer "In11.Cu")
		(net "P5E_CPU0_P1_RX_DP<1>")
	)
	(arc
		(start 346.173552 -285.73095)
		(mid 346.016575 -285.42615)
		(end 346.173552 -285.12135)
		(width 0.1143)
		(layer "In11.Cu")
		(net "P5E_CPU0_P1_RX_DP<1>")
	)
	(arc
		(start 346.243148 -293.180516)
		(mid 346.486475 -292.71595)
		(end 346.243148 -292.251384)
		(width 0.1143)
		(layer "In11.Cu")
		(net "P5E_CPU0_P1_RX_DP<1>")
	)
	(arc
		(start 346.173552 -292.210744)
		(mid 346.016575 -291.905944)
		(end 346.173552 -291.601144)
		(width 0.1143)
		(layer "In11.Cu")
		(net "P5E_CPU0_P1_RX_DP<1>")
	)
	(segment
		(start 354.198174 -394.385292)
		(end 354.718874 -394.385292)
		(width 0.127)
		(layer "F.Cu")
		(net "P5E_CPU0_P1_RX_DP<15>")
	)
	(segment
		(start 358.137968 -275.44014)
		(end 357.671116 -275.706078)
		(width 0.12954)
		(layer "F.Cu")
		(net "P5E_CPU0_P1_RX_DP<15>")
	)
	(segment
		(start 359.56875 -298.951142)
		(end 359.428796 -295.335706)
		(width 0.14224)
		(layer "In11.Cu")
		(net "P5E_CPU0_P1_RX_DP<15>")
	)
	(segment
		(start 362.295186 -380.955042)
		(end 362.295186 -377.80468)
		(width 0.14224)
		(layer "In11.Cu")
		(net "P5E_CPU0_P1_RX_DP<15>")
	)
	(segment
		(start 357.955088 -276.839172)
		(end 357.954072 -276.838664)
		(width 0.1143)
		(layer "In11.Cu")
		(net "P5E_CPU0_P1_RX_DP<15>")
	)
	(segment
		(start 379.38202 -339.023198)
		(end 377.079256 -326.203056)
		(width 0.14224)
		(layer "In11.Cu")
		(net "P5E_CPU0_P1_RX_DP<15>")
	)
	(segment
		(start 359.428796 -295.335706)
		(end 359.33634 -279.262078)
		(width 0.14224)
		(layer "In11.Cu")
		(net "P5E_CPU0_P1_RX_DP<15>")
	)
	(segment
		(start 379.38202 -350.333564)
		(end 379.38202 -339.023198)
		(width 0.14224)
		(layer "In11.Cu")
		(net "P5E_CPU0_P1_RX_DP<15>")
	)
	(segment
		(start 354.718874 -394.385292)
		(end 354.81387 -394.031216)
		(width 0.14224)
		(layer "In11.Cu")
		(net "P5E_CPU0_P1_RX_DP<15>")
	)
	(segment
		(start 357.98633 -276.85746)
		(end 357.985568 -276.856952)
		(width 0.1143)
		(layer "In11.Cu")
		(net "P5E_CPU0_P1_RX_DP<15>")
	)
	(segment
		(start 358.998266 -278.137366)
		(end 358.977946 -278.117046)
		(width 0.1143)
		(layer "In11.Cu")
		(net "P5E_CPU0_P1_RX_DP<15>")
	)
	(segment
		(start 361.613704 -388.932928)
		(end 361.613704 -384.573526)
		(width 0.14224)
		(layer "In11.Cu")
		(net "P5E_CPU0_P1_RX_DP<15>")
	)
	(segment
		(start 362.274612 -377.383294)
		(end 362.32465 -376.76201)
		(width 0.14224)
		(layer "In11.Cu")
		(net "P5E_CPU0_P1_RX_DP<15>")
	)
	(segment
		(start 358.45496 -277.66645)
		(end 358.423972 -277.648416)
		(width 0.1143)
		(layer "In11.Cu")
		(net "P5E_CPU0_P1_RX_DP<15>")
	)
	(segment
		(start 357.486204 -276.029928)
		(end 357.48214 -276.027388)
		(width 0.1143)
		(layer "In11.Cu")
		(net "P5E_CPU0_P1_RX_DP<15>")
	)
	(segment
		(start 361.40263 -303.400206)
		(end 359.671112 -299.21962)
		(width 0.14224)
		(layer "In11.Cu")
		(net "P5E_CPU0_P1_RX_DP<15>")
	)
	(segment
		(start 358.42321 -277.647908)
		(end 358.393492 -277.63089)
		(width 0.1143)
		(layer "In11.Cu")
		(net "P5E_CPU0_P1_RX_DP<15>")
	)
	(segment
		(start 360.78033 -390.022588)
		(end 361.233974 -389.687054)
		(width 0.14224)
		(layer "In11.Cu")
		(net "P5E_CPU0_P1_RX_DP<15>")
	)
	(segment
		(start 357.303324 -275.775928)
		(end 357.373174 -275.706078)
		(width 0.1143)
		(layer "In11.Cu")
		(net "P5E_CPU0_P1_RX_DP<15>")
	)
	(segment
		(start 366.455706 -310.962548)
		(end 361.40263 -303.400206)
		(width 0.14224)
		(layer "In11.Cu")
		(net "P5E_CPU0_P1_RX_DP<15>")
	)
	(segment
		(start 357.954072 -276.838664)
		(end 357.952548 -276.837648)
		(width 0.1143)
		(layer "In11.Cu")
		(net "P5E_CPU0_P1_RX_DP<15>")
	)
	(segment
		(start 355.076252 -393.234418)
		(end 355.8159 -392.49477)
		(width 0.14224)
		(layer "In11.Cu")
		(net "P5E_CPU0_P1_RX_DP<15>")
	)
	(segment
		(start 357.373174 -275.706078)
		(end 357.671116 -275.706078)
		(width 0.1143)
		(layer "In11.Cu")
		(net "P5E_CPU0_P1_RX_DP<15>")
	)
	(segment
		(start 359.33634 -279.262078)
		(end 359.33634 -278.47544)
		(width 0.14224)
		(layer "In11.Cu")
		(net "P5E_CPU0_P1_RX_DP<15>")
	)
	(segment
		(start 377.079256 -326.203056)
		(end 373.775224 -319.880996)
		(width 0.14224)
		(layer "In11.Cu")
		(net "P5E_CPU0_P1_RX_DP<15>")
	)
	(segment
		(start 357.993188 -276.861524)
		(end 357.98633 -276.85746)
		(width 0.1143)
		(layer "In11.Cu")
		(net "P5E_CPU0_P1_RX_DP<15>")
	)
	(segment
		(start 357.480108 -276.026372)
		(end 357.452422 -276.01037)
		(width 0.1143)
		(layer "In11.Cu")
		(net "P5E_CPU0_P1_RX_DP<15>")
	)
	(segment
		(start 360.38282 -390.153652)
		(end 360.38282 -390.153398)
		(width 0.14224)
		(layer "In11.Cu")
		(net "P5E_CPU0_P1_RX_DP<15>")
	)
	(segment
		(start 359.671112 -299.21962)
		(end 359.56875 -298.951142)
		(width 0.14224)
		(layer "In11.Cu")
		(net "P5E_CPU0_P1_RX_DP<15>")
	)
	(segment
		(start 358.913684 -278.117046)
		(end 358.475026 -277.678388)
		(width 0.1143)
		(layer "In11.Cu")
		(net "P5E_CPU0_P1_RX_DP<15>")
	)
	(segment
		(start 376.505216 -357.27894)
		(end 379.38202 -350.333564)
		(width 0.14224)
		(layer "In11.Cu")
		(net "P5E_CPU0_P1_RX_DP<15>")
	)
	(segment
		(start 358.475026 -277.678388)
		(end 358.45496 -277.66645)
		(width 0.1143)
		(layer "In11.Cu")
		(net "P5E_CPU0_P1_RX_DP<15>")
	)
	(segment
		(start 356.771956 -391.329672)
		(end 357.415592 -390.366758)
		(width 0.14224)
		(layer "In11.Cu")
		(net "P5E_CPU0_P1_RX_DP<15>")
	)
	(segment
		(start 361.62361 -382.879092)
		(end 361.73918 -382.297432)
		(width 0.14224)
		(layer "In11.Cu")
		(net "P5E_CPU0_P1_RX_DP<15>")
	)
	(segment
		(start 361.621578 -384.445002)
		(end 361.62361 -384.419094)
		(width 0.14224)
		(layer "In11.Cu")
		(net "P5E_CPU0_P1_RX_DP<15>")
	)
	(segment
		(start 366.341406 -369.875054)
		(end 371.60708 -364.60938)
		(width 0.14224)
		(layer "In11.Cu")
		(net "P5E_CPU0_P1_RX_DP<15>")
	)
	(segment
		(start 355.076252 -393.879832)
		(end 355.076252 -393.234418)
		(width 0.14224)
		(layer "In11.Cu")
		(net "P5E_CPU0_P1_RX_DP<15>")
	)
	(segment
		(start 357.81488 -390.153398)
		(end 360.382566 -390.153398)
		(width 0.14224)
		(layer "In11.Cu")
		(net "P5E_CPU0_P1_RX_DP<15>")
	)
	(segment
		(start 357.985568 -276.856952)
		(end 357.955088 -276.839172)
		(width 0.1143)
		(layer "In11.Cu")
		(net "P5E_CPU0_P1_RX_DP<15>")
	)
	(segment
		(start 373.775224 -319.880996)
		(end 366.455706 -310.962548)
		(width 0.14224)
		(layer "In11.Cu")
		(net "P5E_CPU0_P1_RX_DP<15>")
	)
	(segment
		(start 357.48214 -276.027388)
		(end 357.480108 -276.026372)
		(width 0.1143)
		(layer "In11.Cu")
		(net "P5E_CPU0_P1_RX_DP<15>")
	)
	(segment
		(start 358.977946 -278.117046)
		(end 358.913684 -278.117046)
		(width 0.1143)
		(layer "In11.Cu")
		(net "P5E_CPU0_P1_RX_DP<15>")
	)
	(segment
		(start 359.33634 -278.47544)
		(end 358.998266 -278.137366)
		(width 0.14224)
		(layer "In11.Cu")
		(net "P5E_CPU0_P1_RX_DP<15>")
	)
	(segment
		(start 360.382566 -390.153398)
		(end 360.38282 -390.153652)
		(width 0.14224)
		(layer "In11.Cu")
		(net "P5E_CPU0_P1_RX_DP<15>")
	)
	(segment
		(start 361.73918 -382.297432)
		(end 362.295186 -380.955042)
		(width 0.14224)
		(layer "In11.Cu")
		(net "P5E_CPU0_P1_RX_DP<15>")
	)
	(segment
		(start 358.423972 -277.648416)
		(end 358.42321 -277.647908)
		(width 0.1143)
		(layer "In11.Cu")
		(net "P5E_CPU0_P1_RX_DP<15>")
	)
	(segment
		(start 361.62361 -384.419094)
		(end 361.62361 -382.879092)
		(width 0.14224)
		(layer "In11.Cu")
		(net "P5E_CPU0_P1_RX_DP<15>")
	)
	(segment
		(start 354.81387 -394.031216)
		(end 355.076252 -393.879832)
		(width 0.14224)
		(layer "In11.Cu")
		(net "P5E_CPU0_P1_RX_DP<15>")
	)
	(arc
		(start 360.38282 -390.153398)
		(mid 360.592091 -390.11994)
		(end 360.78033 -390.022588)
		(width 0.14224)
		(layer "In11.Cu")
		(net "P5E_CPU0_P1_RX_DP<15>")
	)
	(arc
		(start 361.613704 -384.573526)
		(mid 361.615677 -384.509144)
		(end 361.621578 -384.445002)
		(width 0.14224)
		(layer "In11.Cu")
		(net "P5E_CPU0_P1_RX_DP<15>")
	)
	(arc
		(start 357.76535 -276.51456)
		(mid 357.690578 -276.234914)
		(end 357.486204 -276.029928)
		(width 0.1143)
		(layer "In11.Cu")
		(net "P5E_CPU0_P1_RX_DP<15>")
	)
	(arc
		(start 362.32465 -376.76201)
		(mid 362.334158 -376.699354)
		(end 362.352082 -376.638566)
		(width 0.14224)
		(layer "In11.Cu")
		(net "P5E_CPU0_P1_RX_DP<15>")
	)
	(arc
		(start 357.452422 -276.01037)
		(mid 357.355287 -275.907501)
		(end 357.303324 -275.775928)
		(width 0.1143)
		(layer "In11.Cu")
		(net "P5E_CPU0_P1_RX_DP<15>")
	)
	(arc
		(start 362.295186 -377.80468)
		(mid 362.292113 -377.722034)
		(end 362.282994 -377.639834)
		(width 0.14224)
		(layer "In11.Cu")
		(net "P5E_CPU0_P1_RX_DP<15>")
	)
	(arc
		(start 358.23652 -277.32609)
		(mid 358.172005 -277.063871)
		(end 357.993188 -276.861524)
		(width 0.1143)
		(layer "In11.Cu")
		(net "P5E_CPU0_P1_RX_DP<15>")
	)
	(arc
		(start 357.952548 -276.837648)
		(mid 357.815514 -276.701267)
		(end 357.76535 -276.51456)
		(width 0.1143)
		(layer "In11.Cu")
		(net "P5E_CPU0_P1_RX_DP<15>")
	)
	(arc
		(start 361.233974 -389.687054)
		(mid 361.513388 -389.355087)
		(end 361.613704 -388.932928)
		(width 0.14224)
		(layer "In11.Cu")
		(net "P5E_CPU0_P1_RX_DP<15>")
	)
	(arc
		(start 366.255808 -369.967764)
		(mid 366.29767 -369.920544)
		(end 366.341406 -369.875054)
		(width 0.14224)
		(layer "In11.Cu")
		(net "P5E_CPU0_P1_RX_DP<15>")
	)
	(arc
		(start 371.60708 -364.60938)
		(mid 374.417134 -361.185369)
		(end 376.505216 -357.27894)
		(width 0.14224)
		(layer "In11.Cu")
		(net "P5E_CPU0_P1_RX_DP<15>")
	)
	(arc
		(start 358.393492 -277.63089)
		(mid 358.278065 -277.497514)
		(end 358.23652 -277.32609)
		(width 0.1143)
		(layer "In11.Cu")
		(net "P5E_CPU0_P1_RX_DP<15>")
	)
	(arc
		(start 355.8159 -392.49477)
		(mid 356.322533 -391.935694)
		(end 356.771956 -391.329672)
		(width 0.14224)
		(layer "In11.Cu")
		(net "P5E_CPU0_P1_RX_DP<15>")
	)
	(arc
		(start 362.282994 -377.639834)
		(mid 362.271468 -377.511803)
		(end 362.274612 -377.383294)
		(width 0.14224)
		(layer "In11.Cu")
		(net "P5E_CPU0_P1_RX_DP<15>")
	)
	(arc
		(start 357.415592 -390.366758)
		(mid 357.588523 -390.210088)
		(end 357.81488 -390.153398)
		(width 0.14224)
		(layer "In11.Cu")
		(net "P5E_CPU0_P1_RX_DP<15>")
	)
	(arc
		(start 362.352082 -376.638566)
		(mid 364.011178 -373.13184)
		(end 366.255808 -369.967764)
		(width 0.14224)
		(layer "In11.Cu")
		(net "P5E_CPU0_P1_RX_DP<15>")
	)
	(segment
		(start 352.998024 -394.385292)
		(end 353.518724 -394.385292)
		(width 0.127)
		(layer "F.Cu")
		(net "P5E_CPU0_P1_RX_DP<14>")
	)
	(segment
		(start 358.137968 -277.060152)
		(end 357.671116 -277.32609)
		(width 0.12954)
		(layer "F.Cu")
		(net "P5E_CPU0_P1_RX_DP<14>")
	)
	(segment
		(start 353.518724 -394.385292)
		(end 353.61372 -394.031216)
		(width 0.14224)
		(layer "In11.Cu")
		(net "P5E_CPU0_P1_RX_DP<14>")
	)
	(segment
		(start 358.460294 -279.289764)
		(end 358.423972 -279.268682)
		(width 0.1143)
		(layer "In11.Cu")
		(net "P5E_CPU0_P1_RX_DP<14>")
	)
	(segment
		(start 358.461564 -285.770574)
		(end 358.424226 -285.748984)
		(width 0.1143)
		(layer "In11.Cu")
		(net "P5E_CPU0_P1_RX_DP<14>")
	)
	(segment
		(start 353.876102 -393.428982)
		(end 353.560126 -393.113006)
		(width 0.14224)
		(layer "In11.Cu")
		(net "P5E_CPU0_P1_RX_DP<14>")
	)
	(segment
		(start 358.423972 -279.268682)
		(end 358.393492 -279.250902)
		(width 0.1143)
		(layer "In11.Cu")
		(net "P5E_CPU0_P1_RX_DP<14>")
	)
	(segment
		(start 358.460294 -284.1498)
		(end 358.393492 -284.110938)
		(width 0.1143)
		(layer "In11.Cu")
		(net "P5E_CPU0_P1_RX_DP<14>")
	)
	(segment
		(start 357.955088 -278.459184)
		(end 357.954072 -278.458676)
		(width 0.1143)
		(layer "In11.Cu")
		(net "P5E_CPU0_P1_RX_DP<14>")
	)
	(segment
		(start 358.70642 -279.756108)
		(end 358.706166 -279.756108)
		(width 0.1143)
		(layer "In11.Cu")
		(net "P5E_CPU0_P1_RX_DP<14>")
	)
	(segment
		(start 358.236266 -295.62298)
		(end 358.236266 -295.145968)
		(width 0.1143)
		(layer "In11.Cu")
		(net "P5E_CPU0_P1_RX_DP<14>")
	)
	(segment
		(start 358.39146 -286.742378)
		(end 358.47782 -286.692086)
		(width 0.1143)
		(layer "In11.Cu")
		(net "P5E_CPU0_P1_RX_DP<14>")
	)
	(segment
		(start 362.278676 -373.731536)
		(end 364.132622 -370.74729)
		(width 0.14224)
		(layer "In11.Cu")
		(net "P5E_CPU0_P1_RX_DP<14>")
	)
	(segment
		(start 358.445562 -293.19093)
		(end 358.456484 -293.184326)
		(width 0.1143)
		(layer "In11.Cu")
		(net "P5E_CPU0_P1_RX_DP<14>")
	)
	(segment
		(start 358.706166 -284.62859)
		(end 358.706166 -284.616144)
		(width 0.1143)
		(layer "In11.Cu")
		(net "P5E_CPU0_P1_RX_DP<14>")
	)
	(segment
		(start 357.373174 -277.32609)
		(end 357.671116 -277.32609)
		(width 0.1143)
		(layer "In11.Cu")
		(net "P5E_CPU0_P1_RX_DP<14>")
	)
	(segment
		(start 353.787964 -393.930632)
		(end 353.876102 -393.842494)
		(width 0.14224)
		(layer "In11.Cu")
		(net "P5E_CPU0_P1_RX_DP<14>")
	)
	(segment
		(start 358.47147 -292.257226)
		(end 358.423972 -292.228524)
		(width 0.1143)
		(layer "In11.Cu")
		(net "P5E_CPU0_P1_RX_DP<14>")
	)
	(segment
		(start 361.101132 -375.62663)
		(end 361.257088 -375.375424)
		(width 0.14224)
		(layer "In11.Cu")
		(net "P5E_CPU0_P1_RX_DP<14>")
	)
	(segment
		(start 358.393492 -281.881326)
		(end 358.423972 -281.863546)
		(width 0.1143)
		(layer "In11.Cu")
		(net "P5E_CPU0_P1_RX_DP<14>")
	)
	(segment
		(start 358.423972 -288.343594)
		(end 358.424226 -288.343086)
		(width 0.1143)
		(layer "In11.Cu")
		(net "P5E_CPU0_P1_RX_DP<14>")
	)
	(segment
		(start 358.394254 -290.59124)
		(end 358.393492 -290.590732)
		(width 0.1143)
		(layer "In11.Cu")
		(net "P5E_CPU0_P1_RX_DP<14>")
	)
	(segment
		(start 358.423972 -288.9885)
		(end 358.393492 -288.97072)
		(width 0.1143)
		(layer "In11.Cu")
		(net "P5E_CPU0_P1_RX_DP<14>")
	)
	(segment
		(start 357.985568 -278.476964)
		(end 357.955088 -278.459184)
		(width 0.1143)
		(layer "In11.Cu")
		(net "P5E_CPU0_P1_RX_DP<14>")
	)
	(segment
		(start 357.993188 -278.481536)
		(end 357.98633 -278.477472)
		(width 0.1143)
		(layer "In11.Cu")
		(net "P5E_CPU0_P1_RX_DP<14>")
	)
	(segment
		(start 358.706166 -292.71595)
		(end 358.706166 -292.702742)
		(width 0.1143)
		(layer "In11.Cu")
		(net "P5E_CPU0_P1_RX_DP<14>")
	)
	(segment
		(start 376.173746 -326.506586)
		(end 372.960138 -320.357754)
		(width 0.14224)
		(layer "In11.Cu")
		(net "P5E_CPU0_P1_RX_DP<14>")
	)
	(segment
		(start 353.61372 -394.031216)
		(end 353.787964 -393.930632)
		(width 0.14224)
		(layer "In11.Cu")
		(net "P5E_CPU0_P1_RX_DP<14>")
	)
	(segment
		(start 358.460294 -289.009582)
		(end 358.423972 -288.9885)
		(width 0.1143)
		(layer "In11.Cu")
		(net "P5E_CPU0_P1_RX_DP<14>")
	)
	(segment
		(start 358.424226 -293.203376)
		(end 358.425242 -293.202868)
		(width 0.1143)
		(layer "In11.Cu")
		(net "P5E_CPU0_P1_RX_DP<14>")
	)
	(segment
		(start 358.461564 -293.87038)
		(end 358.416098 -293.84371)
		(width 0.1143)
		(layer "In11.Cu")
		(net "P5E_CPU0_P1_RX_DP<14>")
	)
	(segment
		(start 378.43714 -339.107526)
		(end 376.173746 -326.506586)
		(width 0.14224)
		(layer "In11.Cu")
		(net "P5E_CPU0_P1_RX_DP<14>")
	)
	(segment
		(start 357.499158 -277.657052)
		(end 357.495348 -277.654766)
		(width 0.1143)
		(layer "In11.Cu")
		(net "P5E_CPU0_P1_RX_DP<14>")
	)
	(segment
		(start 353.90201 -390.697212)
		(end 360.480864 -379.969268)
		(width 0.14224)
		(layer "In11.Cu")
		(net "P5E_CPU0_P1_RX_DP<14>")
	)
	(segment
		(start 358.393492 -283.501338)
		(end 358.462834 -283.461206)
		(width 0.1143)
		(layer "In11.Cu")
		(net "P5E_CPU0_P1_RX_DP<14>")
	)
	(segment
		(start 358.423972 -291.583364)
		(end 358.460294 -291.562282)
		(width 0.1143)
		(layer "In11.Cu")
		(net "P5E_CPU0_P1_RX_DP<14>")
	)
	(segment
		(start 358.503474 -280.935176)
		(end 358.393492 -280.870914)
		(width 0.1143)
		(layer "In11.Cu")
		(net "P5E_CPU0_P1_RX_DP<14>")
	)
	(segment
		(start 376.084084 -355.85019)
		(end 378.43714 -350.169226)
		(width 0.14224)
		(layer "In11.Cu")
		(net "P5E_CPU0_P1_RX_DP<14>")
	)
	(segment
		(start 358.393492 -291.601144)
		(end 358.423972 -291.583364)
		(width 0.1143)
		(layer "In11.Cu")
		(net "P5E_CPU0_P1_RX_DP<14>")
	)
	(segment
		(start 357.766366 -278.194262)
		(end 357.766366 -278.136096)
		(width 0.1143)
		(layer "In11.Cu")
		(net "P5E_CPU0_P1_RX_DP<14>")
	)
	(segment
		(start 358.423972 -290.608512)
		(end 358.394254 -290.59124)
		(width 0.1143)
		(layer "In11.Cu")
		(net "P5E_CPU0_P1_RX_DP<14>")
	)
	(segment
		(start 358.424226 -285.748984)
		(end 358.424226 -285.74873)
		(width 0.1143)
		(layer "In11.Cu")
		(net "P5E_CPU0_P1_RX_DP<14>")
	)
	(segment
		(start 358.423972 -281.863546)
		(end 358.503474 -281.817064)
		(width 0.1143)
		(layer "In11.Cu")
		(net "P5E_CPU0_P1_RX_DP<14>")
	)
	(segment
		(start 357.495348 -277.654766)
		(end 357.452422 -277.630382)
		(width 0.1143)
		(layer "In11.Cu")
		(net "P5E_CPU0_P1_RX_DP<14>")
	)
	(segment
		(start 358.445308 -293.19093)
		(end 358.445562 -293.19093)
		(width 0.1143)
		(layer "In11.Cu")
		(net "P5E_CPU0_P1_RX_DP<14>")
	)
	(segment
		(start 360.70794 -379.164088)
		(end 360.70794 -377.007882)
		(width 0.14224)
		(layer "In11.Cu")
		(net "P5E_CPU0_P1_RX_DP<14>")
	)
	(segment
		(start 358.423972 -289.963352)
		(end 358.460294 -289.94227)
		(width 0.1143)
		(layer "In11.Cu")
		(net "P5E_CPU0_P1_RX_DP<14>")
	)
	(segment
		(start 358.460294 -290.629594)
		(end 358.423972 -290.608512)
		(width 0.1143)
		(layer "In11.Cu")
		(net "P5E_CPU0_P1_RX_DP<14>")
	)
	(segment
		(start 361.257088 -375.375424)
		(end 362.278676 -373.731282)
		(width 0.14224)
		(layer "In11.Cu")
		(net "P5E_CPU0_P1_RX_DP<14>")
	)
	(segment
		(start 358.424226 -288.343086)
		(end 358.46385 -288.319972)
		(width 0.1143)
		(layer "In11.Cu")
		(net "P5E_CPU0_P1_RX_DP<14>")
	)
	(segment
		(start 358.425242 -293.202868)
		(end 358.445308 -293.19093)
		(width 0.1143)
		(layer "In11.Cu")
		(net "P5E_CPU0_P1_RX_DP<14>")
	)
	(segment
		(start 358.47782 -286.692086)
		(end 358.486456 -286.68345)
		(width 0.1143)
		(layer "In11.Cu")
		(net "P5E_CPU0_P1_RX_DP<14>")
	)
	(segment
		(start 358.281986 -295.6687)
		(end 358.236266 -295.62298)
		(width 0.1143)
		(layer "In11.Cu")
		(net "P5E_CPU0_P1_RX_DP<14>")
	)
	(segment
		(start 357.954072 -278.458676)
		(end 357.879396 -278.410924)
		(width 0.1143)
		(layer "In11.Cu")
		(net "P5E_CPU0_P1_RX_DP<14>")
	)
	(segment
		(start 365.705136 -311.517792)
		(end 360.460544 -303.669192)
		(width 0.14224)
		(layer "In11.Cu")
		(net "P5E_CPU0_P1_RX_DP<14>")
	)
	(segment
		(start 362.278676 -373.731282)
		(end 362.278676 -373.731536)
		(width 0.14224)
		(layer "In11.Cu")
		(net "P5E_CPU0_P1_RX_DP<14>")
	)
	(segment
		(start 358.39146 -288.36239)
		(end 358.423972 -288.343594)
		(width 0.1143)
		(layer "In11.Cu")
		(net "P5E_CPU0_P1_RX_DP<14>")
	)
	(segment
		(start 353.876102 -393.842494)
		(end 353.876102 -393.428982)
		(width 0.14224)
		(layer "In11.Cu")
		(net "P5E_CPU0_P1_RX_DP<14>")
	)
	(segment
		(start 357.499158 -277.657306)
		(end 357.499158 -277.657052)
		(width 0.1143)
		(layer "In11.Cu")
		(net "P5E_CPU0_P1_RX_DP<14>")
	)
	(segment
		(start 358.423972 -285.74873)
		(end 358.393492 -285.73095)
		(width 0.1143)
		(layer "In11.Cu")
		(net "P5E_CPU0_P1_RX_DP<14>")
	)
	(segment
		(start 358.460294 -282.529788)
		(end 358.393492 -282.490926)
		(width 0.1143)
		(layer "In11.Cu")
		(net "P5E_CPU0_P1_RX_DP<14>")
	)
	(segment
		(start 358.393492 -280.261314)
		(end 358.463088 -280.220674)
		(width 0.1143)
		(layer "In11.Cu")
		(net "P5E_CPU0_P1_RX_DP<14>")
	)
	(segment
		(start 358.393238 -294.841168)
		(end 358.393492 -294.841168)
		(width 0.1143)
		(layer "In11.Cu")
		(net "P5E_CPU0_P1_RX_DP<14>")
	)
	(segment
		(start 353.610418 -392.687556)
		(end 353.73818 -392.559794)
		(width 0.14224)
		(layer "In11.Cu")
		(net "P5E_CPU0_P1_RX_DP<14>")
	)
	(segment
		(start 358.706166 -286.236664)
		(end 358.706166 -286.236156)
		(width 0.1143)
		(layer "In11.Cu")
		(net "P5E_CPU0_P1_RX_DP<14>")
	)
	(segment
		(start 358.50195 -293.89832)
		(end 358.463088 -293.871396)
		(width 0.1143)
		(layer "In11.Cu")
		(net "P5E_CPU0_P1_RX_DP<14>")
	)
	(segment
		(start 357.303324 -277.39594)
		(end 357.373174 -277.32609)
		(width 0.1143)
		(layer "In11.Cu")
		(net "P5E_CPU0_P1_RX_DP<14>")
	)
	(segment
		(start 358.70642 -292.71595)
		(end 358.706166 -292.71595)
		(width 0.1143)
		(layer "In11.Cu")
		(net "P5E_CPU0_P1_RX_DP<14>")
	)
	(segment
		(start 364.132622 -370.74729)
		(end 370.152422 -364.72749)
		(width 0.14224)
		(layer "In11.Cu")
		(net "P5E_CPU0_P1_RX_DP<14>")
	)
	(segment
		(start 358.423972 -292.228524)
		(end 358.393492 -292.210744)
		(width 0.1143)
		(layer "In11.Cu")
		(net "P5E_CPU0_P1_RX_DP<14>")
	)
	(segment
		(start 358.281986 -298.409614)
		(end 358.281986 -295.697148)
		(width 0.14224)
		(layer "In11.Cu")
		(net "P5E_CPU0_P1_RX_DP<14>")
	)
	(segment
		(start 358.393492 -294.841168)
		(end 358.423972 -294.823388)
		(width 0.1143)
		(layer "In11.Cu")
		(net "P5E_CPU0_P1_RX_DP<14>")
	)
	(segment
		(start 358.460548 -287.389824)
		(end 358.393492 -287.350708)
		(width 0.1143)
		(layer "In11.Cu")
		(net "P5E_CPU0_P1_RX_DP<14>")
	)
	(segment
		(start 353.560126 -393.113006)
		(end 353.562666 -392.801602)
		(width 0.14224)
		(layer "In11.Cu")
		(net "P5E_CPU0_P1_RX_DP<14>")
	)
	(segment
		(start 357.98633 -278.477472)
		(end 357.985568 -278.476964)
		(width 0.1143)
		(layer "In11.Cu")
		(net "P5E_CPU0_P1_RX_DP<14>")
	)
	(segment
		(start 360.460544 -303.669192)
		(end 358.281986 -298.409614)
		(width 0.14224)
		(layer "In11.Cu")
		(net "P5E_CPU0_P1_RX_DP<14>")
	)
	(segment
		(start 357.522272 -277.670768)
		(end 357.499158 -277.657306)
		(width 0.1143)
		(layer "In11.Cu")
		(net "P5E_CPU0_P1_RX_DP<14>")
	)
	(segment
		(start 357.76662 -278.194008)
		(end 357.766366 -278.194262)
		(width 0.1143)
		(layer "In11.Cu")
		(net "P5E_CPU0_P1_RX_DP<14>")
	)
	(segment
		(start 358.393492 -289.981132)
		(end 358.423972 -289.963352)
		(width 0.1143)
		(layer "In11.Cu")
		(net "P5E_CPU0_P1_RX_DP<14>")
	)
	(segment
		(start 358.281986 -295.697148)
		(end 358.281986 -295.6687)
		(width 0.1143)
		(layer "In11.Cu")
		(net "P5E_CPU0_P1_RX_DP<14>")
	)
	(segment
		(start 378.43714 -350.169226)
		(end 378.43714 -339.107526)
		(width 0.14224)
		(layer "In11.Cu")
		(net "P5E_CPU0_P1_RX_DP<14>")
	)
	(segment
		(start 358.456484 -293.184326)
		(end 358.463088 -293.180516)
		(width 0.1143)
		(layer "In11.Cu")
		(net "P5E_CPU0_P1_RX_DP<14>")
	)
	(segment
		(start 372.960138 -320.357754)
		(end 365.705136 -311.517792)
		(width 0.14224)
		(layer "In11.Cu")
		(net "P5E_CPU0_P1_RX_DP<14>")
	)
	(segment
		(start 358.424226 -285.74873)
		(end 358.423972 -285.74873)
		(width 0.1143)
		(layer "In11.Cu")
		(net "P5E_CPU0_P1_RX_DP<14>")
	)
	(segment
		(start 358.423972 -294.823388)
		(end 358.50195 -294.773604)
		(width 0.1143)
		(layer "In11.Cu")
		(net "P5E_CPU0_P1_RX_DP<14>")
	)
	(segment
		(start 353.867974 -392.246104)
		(end 353.867974 -390.817608)
		(width 0.14224)
		(layer "In11.Cu")
		(net "P5E_CPU0_P1_RX_DP<14>")
	)
	(segment
		(start 358.392222 -285.122366)
		(end 358.464358 -285.079948)
		(width 0.1143)
		(layer "In11.Cu")
		(net "P5E_CPU0_P1_RX_DP<14>")
	)
	(arc
		(start 358.23652 -287.045908)
		(mid 358.277486 -286.875502)
		(end 358.39146 -286.742378)
		(width 0.1143)
		(layer "In11.Cu")
		(net "P5E_CPU0_P1_RX_DP<14>")
	)
	(arc
		(start 358.702356 -287.789874)
		(mid 358.624792 -287.563639)
		(end 358.460548 -287.389824)
		(width 0.1143)
		(layer "In11.Cu")
		(net "P5E_CPU0_P1_RX_DP<14>")
	)
	(arc
		(start 358.706166 -292.702742)
		(mid 358.643962 -292.450933)
		(end 358.47147 -292.257226)
		(width 0.1143)
		(layer "In11.Cu")
		(net "P5E_CPU0_P1_RX_DP<14>")
	)
	(arc
		(start 353.867974 -390.817608)
		(mid 353.876641 -390.755047)
		(end 353.90201 -390.697212)
		(width 0.14224)
		(layer "In11.Cu")
		(net "P5E_CPU0_P1_RX_DP<14>")
	)
	(arc
		(start 358.393492 -290.590732)
		(mid 358.236515 -290.285932)
		(end 358.393492 -289.981132)
		(width 0.1143)
		(layer "In11.Cu")
		(net "P5E_CPU0_P1_RX_DP<14>")
	)
	(arc
		(start 358.393492 -287.350708)
		(mid 358.278065 -287.217332)
		(end 358.23652 -287.045908)
		(width 0.1143)
		(layer "In11.Cu")
		(net "P5E_CPU0_P1_RX_DP<14>")
	)
	(arc
		(start 358.393492 -282.490926)
		(mid 358.236515 -282.186126)
		(end 358.393492 -281.881326)
		(width 0.1143)
		(layer "In11.Cu")
		(net "P5E_CPU0_P1_RX_DP<14>")
	)
	(arc
		(start 358.236266 -295.145968)
		(mid 358.277815 -294.974546)
		(end 358.393238 -294.841168)
		(width 0.1143)
		(layer "In11.Cu")
		(net "P5E_CPU0_P1_RX_DP<14>")
	)
	(arc
		(start 353.562666 -392.801602)
		(mid 353.575334 -392.739895)
		(end 353.610418 -392.687556)
		(width 0.14224)
		(layer "In11.Cu")
		(net "P5E_CPU0_P1_RX_DP<14>")
	)
	(arc
		(start 358.393492 -285.73095)
		(mid 358.236622 -285.426962)
		(end 358.392222 -285.122366)
		(width 0.1143)
		(layer "In11.Cu")
		(net "P5E_CPU0_P1_RX_DP<14>")
	)
	(arc
		(start 358.706166 -282.996386)
		(mid 358.705929 -282.978979)
		(end 358.70515 -282.961588)
		(width 0.1143)
		(layer "In11.Cu")
		(net "P5E_CPU0_P1_RX_DP<14>")
	)
	(arc
		(start 358.503474 -281.817064)
		(mid 358.756445 -281.37612)
		(end 358.503474 -280.935176)
		(width 0.1143)
		(layer "In11.Cu")
		(net "P5E_CPU0_P1_RX_DP<14>")
	)
	(arc
		(start 358.393492 -288.97072)
		(mid 358.278065 -288.837344)
		(end 358.23652 -288.66592)
		(width 0.1143)
		(layer "In11.Cu")
		(net "P5E_CPU0_P1_RX_DP<14>")
	)
	(arc
		(start 358.463088 -293.180516)
		(mid 358.636921 -292.987462)
		(end 358.705912 -292.737032)
		(width 0.1143)
		(layer "In11.Cu")
		(net "P5E_CPU0_P1_RX_DP<14>")
	)
	(arc
		(start 358.393492 -280.870914)
		(mid 358.236515 -280.566114)
		(end 358.393492 -280.261314)
		(width 0.1143)
		(layer "In11.Cu")
		(net "P5E_CPU0_P1_RX_DP<14>")
	)
	(arc
		(start 358.393492 -292.210744)
		(mid 358.236515 -291.905944)
		(end 358.393492 -291.601144)
		(width 0.1143)
		(layer "In11.Cu")
		(net "P5E_CPU0_P1_RX_DP<14>")
	)
	(arc
		(start 357.879396 -278.410924)
		(mid 357.796491 -278.316262)
		(end 357.76662 -278.194008)
		(width 0.1143)
		(layer "In11.Cu")
		(net "P5E_CPU0_P1_RX_DP<14>")
	)
	(arc
		(start 358.706166 -284.616144)
		(mid 358.64093 -284.352553)
		(end 358.460294 -284.1498)
		(width 0.1143)
		(layer "In11.Cu")
		(net "P5E_CPU0_P1_RX_DP<14>")
	)
	(arc
		(start 358.46385 -288.319972)
		(mid 358.630416 -288.113064)
		(end 358.706166 -287.858454)
		(width 0.1143)
		(layer "In11.Cu")
		(net "P5E_CPU0_P1_RX_DP<14>")
	)
	(arc
		(start 358.706166 -286.236156)
		(mid 358.641348 -285.973167)
		(end 358.461564 -285.770574)
		(width 0.1143)
		(layer "In11.Cu")
		(net "P5E_CPU0_P1_RX_DP<14>")
	)
	(arc
		(start 358.486456 -286.68345)
		(mid 358.648266 -286.485607)
		(end 358.706166 -286.236664)
		(width 0.1143)
		(layer "In11.Cu")
		(net "P5E_CPU0_P1_RX_DP<14>")
	)
	(arc
		(start 358.48417 -285.065216)
		(mid 358.638729 -284.87179)
		(end 358.705658 -284.633416)
		(width 0.1143)
		(layer "In11.Cu")
		(net "P5E_CPU0_P1_RX_DP<14>")
	)
	(arc
		(start 358.460294 -291.562282)
		(mid 358.706184 -291.095938)
		(end 358.460294 -290.629594)
		(width 0.1143)
		(layer "In11.Cu")
		(net "P5E_CPU0_P1_RX_DP<14>")
	)
	(arc
		(start 358.705912 -292.737032)
		(mid 358.706264 -292.726493)
		(end 358.70642 -292.71595)
		(width 0.1143)
		(layer "In11.Cu")
		(net "P5E_CPU0_P1_RX_DP<14>")
	)
	(arc
		(start 358.416098 -293.84371)
		(mid 358.23919 -293.521229)
		(end 358.424226 -293.203376)
		(width 0.1143)
		(layer "In11.Cu")
		(net "P5E_CPU0_P1_RX_DP<14>")
	)
	(arc
		(start 360.480864 -379.969268)
		(mid 360.650118 -379.582388)
		(end 360.70794 -379.164088)
		(width 0.14224)
		(layer "In11.Cu")
		(net "P5E_CPU0_P1_RX_DP<14>")
	)
	(arc
		(start 358.23652 -278.946102)
		(mid 358.172005 -278.683883)
		(end 357.993188 -278.481536)
		(width 0.1143)
		(layer "In11.Cu")
		(net "P5E_CPU0_P1_RX_DP<14>")
	)
	(arc
		(start 358.705658 -284.633416)
		(mid 358.705917 -284.631004)
		(end 358.706166 -284.62859)
		(width 0.1143)
		(layer "In11.Cu")
		(net "P5E_CPU0_P1_RX_DP<14>")
	)
	(arc
		(start 358.393492 -284.110938)
		(mid 358.236515 -283.806138)
		(end 358.393492 -283.501338)
		(width 0.1143)
		(layer "In11.Cu")
		(net "P5E_CPU0_P1_RX_DP<14>")
	)
	(arc
		(start 358.462834 -283.461206)
		(mid 358.6308 -283.253031)
		(end 358.706166 -282.996386)
		(width 0.1143)
		(layer "In11.Cu")
		(net "P5E_CPU0_P1_RX_DP<14>")
	)
	(arc
		(start 370.152422 -364.72749)
		(mid 373.555432 -360.580955)
		(end 376.084084 -355.85019)
		(width 0.14224)
		(layer "In11.Cu")
		(net "P5E_CPU0_P1_RX_DP<14>")
	)
	(arc
		(start 358.393492 -279.250902)
		(mid 358.278065 -279.117526)
		(end 358.23652 -278.946102)
		(width 0.1143)
		(layer "In11.Cu")
		(net "P5E_CPU0_P1_RX_DP<14>")
	)
	(arc
		(start 358.70515 -282.961588)
		(mid 358.632673 -282.71736)
		(end 358.460294 -282.529788)
		(width 0.1143)
		(layer "In11.Cu")
		(net "P5E_CPU0_P1_RX_DP<14>")
	)
	(arc
		(start 358.460294 -289.94227)
		(mid 358.706184 -289.475926)
		(end 358.460294 -289.009582)
		(width 0.1143)
		(layer "In11.Cu")
		(net "P5E_CPU0_P1_RX_DP<14>")
	)
	(arc
		(start 353.73818 -392.559794)
		(mid 353.83437 -392.415885)
		(end 353.867974 -392.246104)
		(width 0.14224)
		(layer "In11.Cu")
		(net "P5E_CPU0_P1_RX_DP<14>")
	)
	(arc
		(start 358.463088 -293.871396)
		(mid 358.462326 -293.870887)
		(end 358.461564 -293.87038)
		(width 0.1143)
		(layer "In11.Cu")
		(net "P5E_CPU0_P1_RX_DP<14>")
	)
	(arc
		(start 358.463088 -280.220674)
		(mid 358.638833 -280.016721)
		(end 358.70642 -279.756108)
		(width 0.1143)
		(layer "In11.Cu")
		(net "P5E_CPU0_P1_RX_DP<14>")
	)
	(arc
		(start 360.70794 -377.007882)
		(mid 360.808167 -376.289828)
		(end 361.101132 -375.62663)
		(width 0.14224)
		(layer "In11.Cu")
		(net "P5E_CPU0_P1_RX_DP<14>")
	)
	(arc
		(start 357.452422 -277.630382)
		(mid 357.355287 -277.527513)
		(end 357.303324 -277.39594)
		(width 0.1143)
		(layer "In11.Cu")
		(net "P5E_CPU0_P1_RX_DP<14>")
	)
	(arc
		(start 358.50195 -294.773604)
		(mid 358.731128 -294.335962)
		(end 358.50195 -293.89832)
		(width 0.1143)
		(layer "In11.Cu")
		(net "P5E_CPU0_P1_RX_DP<14>")
	)
	(arc
		(start 358.23652 -288.66592)
		(mid 358.277486 -288.495514)
		(end 358.39146 -288.36239)
		(width 0.1143)
		(layer "In11.Cu")
		(net "P5E_CPU0_P1_RX_DP<14>")
	)
	(arc
		(start 357.766366 -278.136096)
		(mid 357.701644 -277.873357)
		(end 357.522272 -277.670768)
		(width 0.1143)
		(layer "In11.Cu")
		(net "P5E_CPU0_P1_RX_DP<14>")
	)
	(arc
		(start 358.464358 -285.079948)
		(mid 358.474345 -285.072691)
		(end 358.48417 -285.065216)
		(width 0.1143)
		(layer "In11.Cu")
		(net "P5E_CPU0_P1_RX_DP<14>")
	)
	(arc
		(start 358.706166 -279.756108)
		(mid 358.64093 -279.492517)
		(end 358.460294 -279.289764)
		(width 0.1143)
		(layer "In11.Cu")
		(net "P5E_CPU0_P1_RX_DP<14>")
	)
	(arc
		(start 358.706166 -287.858454)
		(mid 358.705306 -287.824106)
		(end 358.702356 -287.789874)
		(width 0.1143)
		(layer "In11.Cu")
		(net "P5E_CPU0_P1_RX_DP<14>")
	)
	(segment
		(start 351.798128 -394.385292)
		(end 352.318828 -394.385292)
		(width 0.127)
		(layer "F.Cu")
		(net "P5E_CPU0_P1_RX_DP<13>")
	)
	(segment
		(start 358.137968 -278.680164)
		(end 357.671116 -278.946102)
		(width 0.12954)
		(layer "F.Cu")
		(net "P5E_CPU0_P1_RX_DP<13>")
	)
	(segment
		(start 357.48214 -289.964622)
		(end 357.48341 -289.96386)
		(width 0.1143)
		(layer "In11.Cu")
		(net "P5E_CPU0_P1_RX_DP<13>")
	)
	(segment
		(start 357.477568 -292.224968)
		(end 357.476806 -292.22446)
		(width 0.1143)
		(layer "In11.Cu")
		(net "P5E_CPU0_P1_RX_DP<13>")
	)
	(segment
		(start 352.687128 -390.389364)
		(end 359.344468 -379.60554)
		(width 0.14224)
		(layer "In11.Cu")
		(net "P5E_CPU0_P1_RX_DP<13>")
	)
	(segment
		(start 359.405428 -376.77725)
		(end 359.398316 -376.770138)
		(width 0.14224)
		(layer "In11.Cu")
		(net "P5E_CPU0_P1_RX_DP<13>")
	)
	(segment
		(start 357.485696 -289.962336)
		(end 357.523034 -289.940746)
		(width 0.1143)
		(layer "In11.Cu")
		(net "P5E_CPU0_P1_RX_DP<13>")
	)
	(segment
		(start 377.49226 -349.87611)
		(end 377.49226 -339.191854)
		(width 0.14224)
		(layer "In11.Cu")
		(net "P5E_CPU0_P1_RX_DP<13>")
	)
	(segment
		(start 357.296466 -295.291764)
		(end 357.296466 -295.145968)
		(width 0.1143)
		(layer "In11.Cu")
		(net "P5E_CPU0_P1_RX_DP<13>")
	)
	(segment
		(start 357.476806 -292.22446)
		(end 357.475536 -292.223698)
		(width 0.1143)
		(layer "In11.Cu")
		(net "P5E_CPU0_P1_RX_DP<13>")
	)
	(segment
		(start 357.484172 -281.863546)
		(end 357.520494 -281.842464)
		(width 0.1143)
		(layer "In11.Cu")
		(net "P5E_CPU0_P1_RX_DP<13>")
	)
	(segment
		(start 357.495856 -293.196518)
		(end 357.523034 -293.18077)
		(width 0.1143)
		(layer "In11.Cu")
		(net "P5E_CPU0_P1_RX_DP<13>")
	)
	(segment
		(start 357.296466 -287.046162)
		(end 357.296212 -287.045908)
		(width 0.1143)
		(layer "In11.Cu")
		(net "P5E_CPU0_P1_RX_DP<13>")
	)
	(segment
		(start 357.452422 -291.601652)
		(end 357.48214 -291.584634)
		(width 0.1143)
		(layer "In11.Cu")
		(net "P5E_CPU0_P1_RX_DP<13>")
	)
	(segment
		(start 357.596948 -287.459674)
		(end 357.459026 -287.361376)
		(width 0.1143)
		(layer "In11.Cu")
		(net "P5E_CPU0_P1_RX_DP<13>")
	)
	(segment
		(start 361.254548 -372.288816)
		(end 369.307364 -364.236)
		(width 0.14224)
		(layer "In11.Cu")
		(net "P5E_CPU0_P1_RX_DP<13>")
	)
	(segment
		(start 357.450644 -288.363152)
		(end 357.484172 -288.343594)
		(width 0.1143)
		(layer "In11.Cu")
		(net "P5E_CPU0_P1_RX_DP<13>")
	)
	(segment
		(start 357.483918 -288.34334)
		(end 357.525828 -288.318956)
		(width 0.1143)
		(layer "In11.Cu")
		(net "P5E_CPU0_P1_RX_DP<13>")
	)
	(segment
		(start 357.523034 -289.940746)
		(end 357.550974 -289.92068)
		(width 0.1143)
		(layer "In11.Cu")
		(net "P5E_CPU0_P1_RX_DP<13>")
	)
	(segment
		(start 357.452422 -293.221664)
		(end 357.467916 -293.212266)
		(width 0.1143)
		(layer "In11.Cu")
		(net "P5E_CPU0_P1_RX_DP<13>")
	)
	(segment
		(start 357.303324 -279.015952)
		(end 357.373174 -278.946102)
		(width 0.1143)
		(layer "In11.Cu")
		(net "P5E_CPU0_P1_RX_DP<13>")
	)
	(segment
		(start 357.484172 -290.608512)
		(end 357.452422 -290.590224)
		(width 0.1143)
		(layer "In11.Cu")
		(net "P5E_CPU0_P1_RX_DP<13>")
	)
	(segment
		(start 357.484172 -284.128718)
		(end 357.452422 -284.11043)
		(width 0.1143)
		(layer "In11.Cu")
		(net "P5E_CPU0_P1_RX_DP<13>")
	)
	(segment
		(start 357.550974 -292.271196)
		(end 357.523034 -292.25113)
		(width 0.1143)
		(layer "In11.Cu")
		(net "P5E_CPU0_P1_RX_DP<13>")
	)
	(segment
		(start 357.484172 -285.74873)
		(end 357.452422 -285.730442)
		(width 0.1143)
		(layer "In11.Cu")
		(net "P5E_CPU0_P1_RX_DP<13>")
	)
	(segment
		(start 352.676206 -393.428982)
		(end 352.36023 -393.113006)
		(width 0.14224)
		(layer "In11.Cu")
		(net "P5E_CPU0_P1_RX_DP<13>")
	)
	(segment
		(start 357.523034 -293.18077)
		(end 357.550974 -293.160704)
		(width 0.1143)
		(layer "In11.Cu")
		(net "P5E_CPU0_P1_RX_DP<13>")
	)
	(segment
		(start 357.452422 -281.881834)
		(end 357.484172 -281.863546)
		(width 0.1143)
		(layer "In11.Cu")
		(net "P5E_CPU0_P1_RX_DP<13>")
	)
	(segment
		(start 357.550974 -289.031172)
		(end 357.523034 -289.011106)
		(width 0.1143)
		(layer "In11.Cu")
		(net "P5E_CPU0_P1_RX_DP<13>")
	)
	(segment
		(start 357.520494 -282.529788)
		(end 357.484172 -282.508706)
		(width 0.1143)
		(layer "In11.Cu")
		(net "P5E_CPU0_P1_RX_DP<13>")
	)
	(segment
		(start 357.504746 -293.860474)
		(end 357.452422 -293.830248)
		(width 0.1143)
		(layer "In11.Cu")
		(net "P5E_CPU0_P1_RX_DP<13>")
	)
	(segment
		(start 357.452422 -294.841676)
		(end 357.505508 -294.810942)
		(width 0.1143)
		(layer "In11.Cu")
		(net "P5E_CPU0_P1_RX_DP<13>")
	)
	(segment
		(start 357.452422 -289.98164)
		(end 357.48214 -289.964622)
		(width 0.1143)
		(layer "In11.Cu")
		(net "P5E_CPU0_P1_RX_DP<13>")
	)
	(segment
		(start 357.478838 -288.985452)
		(end 357.452422 -288.970212)
		(width 0.1143)
		(layer "In11.Cu")
		(net "P5E_CPU0_P1_RX_DP<13>")
	)
	(segment
		(start 357.452422 -283.501846)
		(end 357.484172 -283.483558)
		(width 0.1143)
		(layer "In11.Cu")
		(net "P5E_CPU0_P1_RX_DP<13>")
	)
	(segment
		(start 352.36023 -393.113006)
		(end 352.363278 -392.7348)
		(width 0.14224)
		(layer "In11.Cu")
		(net "P5E_CPU0_P1_RX_DP<13>")
	)
	(segment
		(start 357.505508 -293.860982)
		(end 357.504746 -293.860474)
		(width 0.1143)
		(layer "In11.Cu")
		(net "P5E_CPU0_P1_RX_DP<13>")
	)
	(segment
		(start 357.484172 -282.508706)
		(end 357.452422 -282.490418)
		(width 0.1143)
		(layer "In11.Cu")
		(net "P5E_CPU0_P1_RX_DP<13>")
	)
	(segment
		(start 357.480108 -292.226238)
		(end 357.477568 -292.224968)
		(width 0.1143)
		(layer "In11.Cu")
		(net "P5E_CPU0_P1_RX_DP<13>")
	)
	(segment
		(start 357.451406 -286.742632)
		(end 357.520494 -286.7025)
		(width 0.1143)
		(layer "In11.Cu")
		(net "P5E_CPU0_P1_RX_DP<13>")
	)
	(segment
		(start 357.48214 -288.98723)
		(end 357.480616 -288.986468)
		(width 0.1143)
		(layer "In11.Cu")
		(net "P5E_CPU0_P1_RX_DP<13>")
	)
	(segment
		(start 357.475536 -292.223698)
		(end 357.473504 -292.222682)
		(width 0.1143)
		(layer "In11.Cu")
		(net "P5E_CPU0_P1_RX_DP<13>")
	)
	(segment
		(start 377.49226 -339.191854)
		(end 375.267474 -326.805798)
		(width 0.14224)
		(layer "In11.Cu")
		(net "P5E_CPU0_P1_RX_DP<13>")
	)
	(segment
		(start 357.296212 -295.292018)
		(end 357.296466 -295.291764)
		(width 0.1143)
		(layer "In11.Cu")
		(net "P5E_CPU0_P1_RX_DP<13>")
	)
	(segment
		(start 357.448866 -286.744156)
		(end 357.451406 -286.742632)
		(width 0.1143)
		(layer "In11.Cu")
		(net "P5E_CPU0_P1_RX_DP<13>")
	)
	(segment
		(start 357.484172 -283.483558)
		(end 357.520494 -283.462476)
		(width 0.1143)
		(layer "In11.Cu")
		(net "P5E_CPU0_P1_RX_DP<13>")
	)
	(segment
		(start 357.520494 -280.909776)
		(end 357.484172 -280.888694)
		(width 0.1143)
		(layer "In11.Cu")
		(net "P5E_CPU0_P1_RX_DP<13>")
	)
	(segment
		(start 357.48341 -288.987992)
		(end 357.48214 -288.98723)
		(width 0.1143)
		(layer "In11.Cu")
		(net "P5E_CPU0_P1_RX_DP<13>")
	)
	(segment
		(start 357.452422 -280.261822)
		(end 357.484172 -280.243534)
		(width 0.1143)
		(layer "In11.Cu")
		(net "P5E_CPU0_P1_RX_DP<13>")
	)
	(segment
		(start 352.668078 -392.43)
		(end 352.668078 -390.456166)
		(width 0.14224)
		(layer "In11.Cu")
		(net "P5E_CPU0_P1_RX_DP<13>")
	)
	(segment
		(start 375.267474 -326.805798)
		(end 372.246906 -321.026536)
		(width 0.14224)
		(layer "In11.Cu")
		(net "P5E_CPU0_P1_RX_DP<13>")
	)
	(segment
		(start 357.520494 -279.289764)
		(end 357.484172 -279.268682)
		(width 0.1143)
		(layer "In11.Cu")
		(net "P5E_CPU0_P1_RX_DP<13>")
	)
	(segment
		(start 357.467916 -293.212266)
		(end 357.485188 -293.202614)
		(width 0.1143)
		(layer "In11.Cu")
		(net "P5E_CPU0_P1_RX_DP<13>")
	)
	(segment
		(start 357.341932 -298.582588)
		(end 357.341932 -295.697148)
		(width 0.14224)
		(layer "In11.Cu")
		(net "P5E_CPU0_P1_RX_DP<13>")
	)
	(segment
		(start 357.486966 -288.990278)
		(end 357.484172 -288.9885)
		(width 0.1143)
		(layer "In11.Cu")
		(net "P5E_CPU0_P1_RX_DP<13>")
	)
	(segment
		(start 375.19229 -355.42855)
		(end 377.49226 -349.87611)
		(width 0.14224)
		(layer "In11.Cu")
		(net "P5E_CPU0_P1_RX_DP<13>")
	)
	(segment
		(start 357.520494 -284.1498)
		(end 357.484172 -284.128718)
		(width 0.1143)
		(layer "In11.Cu")
		(net "P5E_CPU0_P1_RX_DP<13>")
	)
	(segment
		(start 357.473504 -292.222682)
		(end 357.452422 -292.210236)
		(width 0.1143)
		(layer "In11.Cu")
		(net "P5E_CPU0_P1_RX_DP<13>")
	)
	(segment
		(start 357.48341 -291.583872)
		(end 357.484172 -291.583364)
		(width 0.1143)
		(layer "In11.Cu")
		(net "P5E_CPU0_P1_RX_DP<13>")
	)
	(segment
		(start 357.484172 -285.10357)
		(end 357.520494 -285.082488)
		(width 0.1143)
		(layer "In11.Cu")
		(net "P5E_CPU0_P1_RX_DP<13>")
	)
	(segment
		(start 357.484172 -288.9885)
		(end 357.48341 -288.987992)
		(width 0.1143)
		(layer "In11.Cu")
		(net "P5E_CPU0_P1_RX_DP<13>")
	)
	(segment
		(start 357.520494 -290.629594)
		(end 357.484172 -290.608512)
		(width 0.1143)
		(layer "In11.Cu")
		(net "P5E_CPU0_P1_RX_DP<13>")
	)
	(segment
		(start 352.676206 -393.842494)
		(end 352.676206 -393.428982)
		(width 0.14224)
		(layer "In11.Cu")
		(net "P5E_CPU0_P1_RX_DP<13>")
	)
	(segment
		(start 357.480616 -288.986468)
		(end 357.479854 -288.98596)
		(width 0.1143)
		(layer "In11.Cu")
		(net "P5E_CPU0_P1_RX_DP<13>")
	)
	(segment
		(start 357.341932 -295.6687)
		(end 357.296212 -295.62298)
		(width 0.1143)
		(layer "In11.Cu")
		(net "P5E_CPU0_P1_RX_DP<13>")
	)
	(segment
		(start 357.482648 -292.227762)
		(end 357.481886 -292.227254)
		(width 0.1143)
		(layer "In11.Cu")
		(net "P5E_CPU0_P1_RX_DP<13>")
	)
	(segment
		(start 372.246906 -321.026536)
		(end 365.175038 -312.410094)
		(width 0.14224)
		(layer "In11.Cu")
		(net "P5E_CPU0_P1_RX_DP<13>")
	)
	(segment
		(start 359.405428 -379.390402)
		(end 359.405428 -376.77725)
		(width 0.14224)
		(layer "In11.Cu")
		(net "P5E_CPU0_P1_RX_DP<13>")
	)
	(segment
		(start 357.523034 -292.25113)
		(end 357.482648 -292.227762)
		(width 0.1143)
		(layer "In11.Cu")
		(net "P5E_CPU0_P1_RX_DP<13>")
	)
	(segment
		(start 357.48214 -291.584634)
		(end 357.48341 -291.583872)
		(width 0.1143)
		(layer "In11.Cu")
		(net "P5E_CPU0_P1_RX_DP<13>")
	)
	(segment
		(start 357.493316 -293.198042)
		(end 357.494332 -293.197534)
		(width 0.1143)
		(layer "In11.Cu")
		(net "P5E_CPU0_P1_RX_DP<13>")
	)
	(segment
		(start 357.489506 -293.200328)
		(end 357.491792 -293.199058)
		(width 0.1143)
		(layer "In11.Cu")
		(net "P5E_CPU0_P1_RX_DP<13>")
	)
	(segment
		(start 352.318828 -394.385292)
		(end 352.413824 -394.031216)
		(width 0.14224)
		(layer "In11.Cu")
		(net "P5E_CPU0_P1_RX_DP<13>")
	)
	(segment
		(start 359.635806 -304.12055)
		(end 357.341932 -298.582588)
		(width 0.14224)
		(layer "In11.Cu")
		(net "P5E_CPU0_P1_RX_DP<13>")
	)
	(segment
		(start 352.363278 -392.7348)
		(end 352.668078 -392.43)
		(width 0.14224)
		(layer "In11.Cu")
		(net "P5E_CPU0_P1_RX_DP<13>")
	)
	(segment
		(start 357.479854 -288.98596)
		(end 357.478838 -288.985452)
		(width 0.1143)
		(layer "In11.Cu")
		(net "P5E_CPU0_P1_RX_DP<13>")
	)
	(segment
		(start 357.484172 -291.583364)
		(end 357.520494 -291.562282)
		(width 0.1143)
		(layer "In11.Cu")
		(net "P5E_CPU0_P1_RX_DP<13>")
	)
	(segment
		(start 357.484172 -280.243534)
		(end 357.520494 -280.222452)
		(width 0.1143)
		(layer "In11.Cu")
		(net "P5E_CPU0_P1_RX_DP<13>")
	)
	(segment
		(start 357.48341 -289.96386)
		(end 357.485696 -289.962336)
		(width 0.1143)
		(layer "In11.Cu")
		(net "P5E_CPU0_P1_RX_DP<13>")
	)
	(segment
		(start 357.484172 -279.268682)
		(end 357.452422 -279.250394)
		(width 0.1143)
		(layer "In11.Cu")
		(net "P5E_CPU0_P1_RX_DP<13>")
	)
	(segment
		(start 357.296212 -295.62298)
		(end 357.296212 -295.292018)
		(width 0.1143)
		(layer "In11.Cu")
		(net "P5E_CPU0_P1_RX_DP<13>")
	)
	(segment
		(start 357.484172 -288.343594)
		(end 357.483918 -288.34334)
		(width 0.1143)
		(layer "In11.Cu")
		(net "P5E_CPU0_P1_RX_DP<13>")
	)
	(segment
		(start 352.588068 -393.930632)
		(end 352.676206 -393.842494)
		(width 0.14224)
		(layer "In11.Cu")
		(net "P5E_CPU0_P1_RX_DP<13>")
	)
	(segment
		(start 357.494332 -293.197534)
		(end 357.495856 -293.196518)
		(width 0.1143)
		(layer "In11.Cu")
		(net "P5E_CPU0_P1_RX_DP<13>")
	)
	(segment
		(start 357.452422 -285.121858)
		(end 357.484172 -285.10357)
		(width 0.1143)
		(layer "In11.Cu")
		(net "P5E_CPU0_P1_RX_DP<13>")
	)
	(segment
		(start 357.523034 -289.011106)
		(end 357.486966 -288.990278)
		(width 0.1143)
		(layer "In11.Cu")
		(net "P5E_CPU0_P1_RX_DP<13>")
	)
	(segment
		(start 352.413824 -394.031216)
		(end 352.588068 -393.930632)
		(width 0.14224)
		(layer "In11.Cu")
		(net "P5E_CPU0_P1_RX_DP<13>")
	)
	(segment
		(start 357.481886 -292.227254)
		(end 357.48087 -292.226746)
		(width 0.1143)
		(layer "In11.Cu")
		(net "P5E_CPU0_P1_RX_DP<13>")
	)
	(segment
		(start 357.48087 -292.226746)
		(end 357.480108 -292.226238)
		(width 0.1143)
		(layer "In11.Cu")
		(net "P5E_CPU0_P1_RX_DP<13>")
	)
	(segment
		(start 357.484172 -280.888694)
		(end 357.452422 -280.870406)
		(width 0.1143)
		(layer "In11.Cu")
		(net "P5E_CPU0_P1_RX_DP<13>")
	)
	(segment
		(start 365.175038 -312.410094)
		(end 359.635806 -304.12055)
		(width 0.14224)
		(layer "In11.Cu")
		(net "P5E_CPU0_P1_RX_DP<13>")
	)
	(segment
		(start 359.344722 -379.605286)
		(end 359.344468 -379.605286)
		(width 0.14224)
		(layer "In11.Cu")
		(net "P5E_CPU0_P1_RX_DP<13>")
	)
	(segment
		(start 357.373174 -278.946102)
		(end 357.671116 -278.946102)
		(width 0.1143)
		(layer "In11.Cu")
		(net "P5E_CPU0_P1_RX_DP<13>")
	)
	(segment
		(start 357.520494 -285.769812)
		(end 357.484172 -285.74873)
		(width 0.1143)
		(layer "In11.Cu")
		(net "P5E_CPU0_P1_RX_DP<13>")
	)
	(segment
		(start 357.341932 -295.697148)
		(end 357.341932 -295.6687)
		(width 0.1143)
		(layer "In11.Cu")
		(net "P5E_CPU0_P1_RX_DP<13>")
	)
	(segment
		(start 357.485188 -293.202614)
		(end 357.489506 -293.200328)
		(width 0.1143)
		(layer "In11.Cu")
		(net "P5E_CPU0_P1_RX_DP<13>")
	)
	(segment
		(start 359.344468 -379.60554)
		(end 359.344722 -379.605286)
		(width 0.14224)
		(layer "In11.Cu")
		(net "P5E_CPU0_P1_RX_DP<13>")
	)
	(segment
		(start 357.766366 -287.856168)
		(end 357.766366 -287.854136)
		(width 0.1143)
		(layer "In11.Cu")
		(net "P5E_CPU0_P1_RX_DP<13>")
	)
	(segment
		(start 357.491792 -293.199058)
		(end 357.493316 -293.198042)
		(width 0.1143)
		(layer "In11.Cu")
		(net "P5E_CPU0_P1_RX_DP<13>")
	)
	(arc
		(start 357.520494 -283.462476)
		(mid 357.527643 -283.457576)
		(end 357.534718 -283.45257)
		(width 0.1143)
		(layer "In11.Cu")
		(net "P5E_CPU0_P1_RX_DP<13>")
	)
	(arc
		(start 357.452422 -292.210236)
		(mid 357.296494 -291.905944)
		(end 357.452422 -291.601652)
		(width 0.1143)
		(layer "In11.Cu")
		(net "P5E_CPU0_P1_RX_DP<13>")
	)
	(arc
		(start 352.668078 -390.456166)
		(mid 352.672977 -390.421449)
		(end 352.687128 -390.389364)
		(width 0.14224)
		(layer "In11.Cu")
		(net "P5E_CPU0_P1_RX_DP<13>")
	)
	(arc
		(start 357.452422 -290.590224)
		(mid 357.296494 -290.285932)
		(end 357.452422 -289.98164)
		(width 0.1143)
		(layer "In11.Cu")
		(net "P5E_CPU0_P1_RX_DP<13>")
	)
	(arc
		(start 357.534718 -283.45257)
		(mid 357.762101 -282.996132)
		(end 357.534718 -282.539694)
		(width 0.1143)
		(layer "In11.Cu")
		(net "P5E_CPU0_P1_RX_DP<13>")
	)
	(arc
		(start 357.452422 -284.11043)
		(mid 357.296494 -283.806138)
		(end 357.452422 -283.501846)
		(width 0.1143)
		(layer "In11.Cu")
		(net "P5E_CPU0_P1_RX_DP<13>")
	)
	(arc
		(start 357.550974 -289.92068)
		(mid 357.778974 -289.475926)
		(end 357.550974 -289.031172)
		(width 0.1143)
		(layer "In11.Cu")
		(net "P5E_CPU0_P1_RX_DP<13>")
	)
	(arc
		(start 357.459026 -287.361376)
		(mid 357.339544 -287.223468)
		(end 357.296466 -287.046162)
		(width 0.1143)
		(layer "In11.Cu")
		(net "P5E_CPU0_P1_RX_DP<13>")
	)
	(arc
		(start 357.452422 -282.490418)
		(mid 357.296494 -282.186126)
		(end 357.452422 -281.881834)
		(width 0.1143)
		(layer "In11.Cu")
		(net "P5E_CPU0_P1_RX_DP<13>")
	)
	(arc
		(start 357.534718 -280.212546)
		(mid 357.762101 -279.756108)
		(end 357.534718 -279.29967)
		(width 0.1143)
		(layer "In11.Cu")
		(net "P5E_CPU0_P1_RX_DP<13>")
	)
	(arc
		(start 357.520494 -291.562282)
		(mid 357.528158 -291.557011)
		(end 357.535734 -291.551614)
		(width 0.1143)
		(layer "In11.Cu")
		(net "P5E_CPU0_P1_RX_DP<13>")
	)
	(arc
		(start 357.520494 -280.222452)
		(mid 357.527643 -280.217552)
		(end 357.534718 -280.212546)
		(width 0.1143)
		(layer "In11.Cu")
		(net "P5E_CPU0_P1_RX_DP<13>")
	)
	(arc
		(start 357.520494 -285.082488)
		(mid 357.528158 -285.077217)
		(end 357.535734 -285.07182)
		(width 0.1143)
		(layer "In11.Cu")
		(net "P5E_CPU0_P1_RX_DP<13>")
	)
	(arc
		(start 357.452422 -293.830248)
		(mid 357.296494 -293.525956)
		(end 357.452422 -293.221664)
		(width 0.1143)
		(layer "In11.Cu")
		(net "P5E_CPU0_P1_RX_DP<13>")
	)
	(arc
		(start 357.535734 -284.160468)
		(mid 357.528158 -284.155072)
		(end 357.520494 -284.1498)
		(width 0.1143)
		(layer "In11.Cu")
		(net "P5E_CPU0_P1_RX_DP<13>")
	)
	(arc
		(start 357.535734 -285.07182)
		(mid 357.760905 -284.616144)
		(end 357.535734 -284.160468)
		(width 0.1143)
		(layer "In11.Cu")
		(net "P5E_CPU0_P1_RX_DP<13>")
	)
	(arc
		(start 357.525828 -288.318956)
		(mid 357.70272 -288.116988)
		(end 357.766366 -287.856168)
		(width 0.1143)
		(layer "In11.Cu")
		(net "P5E_CPU0_P1_RX_DP<13>")
	)
	(arc
		(start 357.534718 -279.29967)
		(mid 357.527644 -279.294663)
		(end 357.520494 -279.289764)
		(width 0.1143)
		(layer "In11.Cu")
		(net "P5E_CPU0_P1_RX_DP<13>")
	)
	(arc
		(start 357.505508 -294.810942)
		(mid 357.779059 -294.335962)
		(end 357.505508 -293.860982)
		(width 0.1143)
		(layer "In11.Cu")
		(net "P5E_CPU0_P1_RX_DP<13>")
	)
	(arc
		(start 357.534718 -281.832558)
		(mid 357.762101 -281.37612)
		(end 357.534718 -280.919682)
		(width 0.1143)
		(layer "In11.Cu")
		(net "P5E_CPU0_P1_RX_DP<13>")
	)
	(arc
		(start 357.296212 -287.045908)
		(mid 357.336541 -286.876816)
		(end 357.448866 -286.744156)
		(width 0.1143)
		(layer "In11.Cu")
		(net "P5E_CPU0_P1_RX_DP<13>")
	)
	(arc
		(start 357.766366 -287.854136)
		(mid 357.722213 -287.639491)
		(end 357.596948 -287.459674)
		(width 0.1143)
		(layer "In11.Cu")
		(net "P5E_CPU0_P1_RX_DP<13>")
	)
	(arc
		(start 359.398316 -376.770138)
		(mid 359.880734 -374.344861)
		(end 361.254548 -372.288816)
		(width 0.14224)
		(layer "In11.Cu")
		(net "P5E_CPU0_P1_RX_DP<13>")
	)
	(arc
		(start 357.534718 -280.919682)
		(mid 357.527644 -280.914675)
		(end 357.520494 -280.909776)
		(width 0.1143)
		(layer "In11.Cu")
		(net "P5E_CPU0_P1_RX_DP<13>")
	)
	(arc
		(start 357.452422 -280.870406)
		(mid 357.296494 -280.566114)
		(end 357.452422 -280.261822)
		(width 0.1143)
		(layer "In11.Cu")
		(net "P5E_CPU0_P1_RX_DP<13>")
	)
	(arc
		(start 357.520494 -286.7025)
		(mid 357.702678 -286.49683)
		(end 357.766366 -286.229552)
		(width 0.1143)
		(layer "In11.Cu")
		(net "P5E_CPU0_P1_RX_DP<13>")
	)
	(arc
		(start 357.766366 -286.229552)
		(mid 357.701494 -285.97981)
		(end 357.53675 -285.781242)
		(width 0.1143)
		(layer "In11.Cu")
		(net "P5E_CPU0_P1_RX_DP<13>")
	)
	(arc
		(start 357.452422 -285.730442)
		(mid 357.296494 -285.42615)
		(end 357.452422 -285.121858)
		(width 0.1143)
		(layer "In11.Cu")
		(net "P5E_CPU0_P1_RX_DP<13>")
	)
	(arc
		(start 357.296466 -288.66592)
		(mid 357.337228 -288.496036)
		(end 357.450644 -288.363152)
		(width 0.1143)
		(layer "In11.Cu")
		(net "P5E_CPU0_P1_RX_DP<13>")
	)
	(arc
		(start 357.296466 -295.145968)
		(mid 357.337721 -294.974997)
		(end 357.452422 -294.841676)
		(width 0.1143)
		(layer "In11.Cu")
		(net "P5E_CPU0_P1_RX_DP<13>")
	)
	(arc
		(start 357.550974 -293.160704)
		(mid 357.778974 -292.71595)
		(end 357.550974 -292.271196)
		(width 0.1143)
		(layer "In11.Cu")
		(net "P5E_CPU0_P1_RX_DP<13>")
	)
	(arc
		(start 357.520494 -281.842464)
		(mid 357.527643 -281.837564)
		(end 357.534718 -281.832558)
		(width 0.1143)
		(layer "In11.Cu")
		(net "P5E_CPU0_P1_RX_DP<13>")
	)
	(arc
		(start 357.53675 -285.781242)
		(mid 357.528672 -285.775456)
		(end 357.520494 -285.769812)
		(width 0.1143)
		(layer "In11.Cu")
		(net "P5E_CPU0_P1_RX_DP<13>")
	)
	(arc
		(start 357.452422 -279.250394)
		(mid 357.355287 -279.147525)
		(end 357.303324 -279.015952)
		(width 0.1143)
		(layer "In11.Cu")
		(net "P5E_CPU0_P1_RX_DP<13>")
	)
	(arc
		(start 357.534718 -282.539694)
		(mid 357.527644 -282.534687)
		(end 357.520494 -282.529788)
		(width 0.1143)
		(layer "In11.Cu")
		(net "P5E_CPU0_P1_RX_DP<13>")
	)
	(arc
		(start 357.535734 -291.551614)
		(mid 357.760905 -291.095938)
		(end 357.535734 -290.640262)
		(width 0.1143)
		(layer "In11.Cu")
		(net "P5E_CPU0_P1_RX_DP<13>")
	)
	(arc
		(start 357.452422 -288.970212)
		(mid 357.337746 -288.836878)
		(end 357.296466 -288.66592)
		(width 0.1143)
		(layer "In11.Cu")
		(net "P5E_CPU0_P1_RX_DP<13>")
	)
	(arc
		(start 359.344468 -379.605286)
		(mid 359.389895 -379.502084)
		(end 359.405428 -379.390402)
		(width 0.14224)
		(layer "In11.Cu")
		(net "P5E_CPU0_P1_RX_DP<13>")
	)
	(arc
		(start 357.535734 -290.640262)
		(mid 357.528158 -290.634866)
		(end 357.520494 -290.629594)
		(width 0.1143)
		(layer "In11.Cu")
		(net "P5E_CPU0_P1_RX_DP<13>")
	)
	(arc
		(start 369.307364 -364.236)
		(mid 372.683532 -360.122069)
		(end 375.19229 -355.42855)
		(width 0.14224)
		(layer "In11.Cu")
		(net "P5E_CPU0_P1_RX_DP<13>")
	)
	(segment
		(start 350.597978 -394.385292)
		(end 351.118678 -394.385292)
		(width 0.127)
		(layer "F.Cu")
		(net "P5E_CPU0_P1_RX_DP<12>")
	)
	(segment
		(start 355.78796 -274.630134)
		(end 355.321108 -274.896072)
		(width 0.12954)
		(layer "F.Cu")
		(net "P5E_CPU0_P1_RX_DP<12>")
	)
	(segment
		(start 356.535482 -280.883868)
		(end 356.512368 -280.870406)
		(width 0.1143)
		(layer "In11.Cu")
		(net "P5E_CPU0_P1_RX_DP<12>")
	)
	(segment
		(start 356.576376 -285.767526)
		(end 356.575614 -285.767018)
		(width 0.1143)
		(layer "In11.Cu")
		(net "P5E_CPU0_P1_RX_DP<12>")
	)
	(segment
		(start 356.542086 -290.607242)
		(end 356.512368 -290.590224)
		(width 0.1143)
		(layer "In11.Cu")
		(net "P5E_CPU0_P1_RX_DP<12>")
	)
	(segment
		(start 356.576376 -290.627308)
		(end 356.575614 -290.6268)
		(width 0.1143)
		(layer "In11.Cu")
		(net "P5E_CPU0_P1_RX_DP<12>")
	)
	(segment
		(start 356.538784 -279.265634)
		(end 356.538022 -279.265126)
		(width 0.1143)
		(layer "In11.Cu")
		(net "P5E_CPU0_P1_RX_DP<12>")
	)
	(segment
		(start 356.529386 -291.591746)
		(end 356.533958 -291.589206)
		(width 0.1143)
		(layer "In11.Cu")
		(net "P5E_CPU0_P1_RX_DP<12>")
	)
	(segment
		(start 356.543356 -285.748222)
		(end 356.540562 -285.746698)
		(width 0.1143)
		(layer "In11.Cu")
		(net "P5E_CPU0_P1_RX_DP<12>")
	)
	(segment
		(start 356.51059 -288.363152)
		(end 356.544118 -288.343594)
		(width 0.1143)
		(layer "In11.Cu")
		(net "P5E_CPU0_P1_RX_DP<12>")
	)
	(segment
		(start 356.548436 -290.611052)
		(end 356.545134 -290.60902)
		(width 0.1143)
		(layer "In11.Cu")
		(net "P5E_CPU0_P1_RX_DP<12>")
	)
	(segment
		(start 356.5398 -285.74619)
		(end 356.538784 -285.745682)
		(width 0.1143)
		(layer "In11.Cu")
		(net "P5E_CPU0_P1_RX_DP<12>")
	)
	(segment
		(start 356.575614 -282.526994)
		(end 356.545134 -282.509214)
		(width 0.1143)
		(layer "In11.Cu")
		(net "P5E_CPU0_P1_RX_DP<12>")
	)
	(segment
		(start 356.554024 -281.857704)
		(end 356.583234 -281.840686)
		(width 0.1143)
		(layer "In11.Cu")
		(net "P5E_CPU0_P1_RX_DP<12>")
	)
	(segment
		(start 356.512368 -289.98164)
		(end 356.580694 -289.942016)
		(width 0.1143)
		(layer "In11.Cu")
		(net "P5E_CPU0_P1_RX_DP<12>")
	)
	(segment
		(start 356.538784 -277.645622)
		(end 356.538022 -277.645114)
		(width 0.1143)
		(layer "In11.Cu")
		(net "P5E_CPU0_P1_RX_DP<12>")
	)
	(segment
		(start 356.575868 -283.465016)
		(end 356.583234 -283.460698)
		(width 0.1143)
		(layer "In11.Cu")
		(net "P5E_CPU0_P1_RX_DP<12>")
	)
	(segment
		(start 351.387918 -393.930632)
		(end 351.476056 -393.842494)
		(width 0.14224)
		(layer "In11.Cu")
		(net "P5E_CPU0_P1_RX_DP<12>")
	)
	(segment
		(start 356.544118 -281.863546)
		(end 356.545134 -281.863038)
		(width 0.1143)
		(layer "In11.Cu")
		(net "P5E_CPU0_P1_RX_DP<12>")
	)
	(segment
		(start 356.583234 -282.531566)
		(end 356.576376 -282.527502)
		(width 0.1143)
		(layer "In11.Cu")
		(net "P5E_CPU0_P1_RX_DP<12>")
	)
	(segment
		(start 351.476056 -393.428982)
		(end 351.16008 -393.113006)
		(width 0.14224)
		(layer "In11.Cu")
		(net "P5E_CPU0_P1_RX_DP<12>")
	)
	(segment
		(start 364.422944 -312.963306)
		(end 358.810052 -304.563526)
		(width 0.14224)
		(layer "In11.Cu")
		(net "P5E_CPU0_P1_RX_DP<12>")
	)
	(segment
		(start 374.217692 -355.21773)
		(end 376.526806 -349.642938)
		(width 0.14224)
		(layer "In11.Cu")
		(net "P5E_CPU0_P1_RX_DP<12>")
	)
	(segment
		(start 356.544118 -284.128718)
		(end 356.543356 -284.12821)
		(width 0.1143)
		(layer "In11.Cu")
		(net "P5E_CPU0_P1_RX_DP<12>")
	)
	(segment
		(start 356.543356 -281.864054)
		(end 356.544118 -281.863546)
		(width 0.1143)
		(layer "In11.Cu")
		(net "P5E_CPU0_P1_RX_DP<12>")
	)
	(segment
		(start 356.545134 -277.649178)
		(end 356.544118 -277.64867)
		(width 0.1143)
		(layer "In11.Cu")
		(net "P5E_CPU0_P1_RX_DP<12>")
	)
	(segment
		(start 356.575614 -284.147006)
		(end 356.545134 -284.129226)
		(width 0.1143)
		(layer "In11.Cu")
		(net "P5E_CPU0_P1_RX_DP<12>")
	)
	(segment
		(start 356.583234 -280.911554)
		(end 356.576376 -280.90749)
		(width 0.1143)
		(layer "In11.Cu")
		(net "P5E_CPU0_P1_RX_DP<12>")
	)
	(segment
		(start 356.538022 -284.125162)
		(end 356.535482 -284.123892)
		(width 0.1143)
		(layer "In11.Cu")
		(net "P5E_CPU0_P1_RX_DP<12>")
	)
	(segment
		(start 356.536244 -291.587936)
		(end 356.537514 -291.587174)
		(width 0.1143)
		(layer "In11.Cu")
		(net "P5E_CPU0_P1_RX_DP<12>")
	)
	(segment
		(start 356.543356 -291.583872)
		(end 356.544118 -291.583364)
		(width 0.1143)
		(layer "In11.Cu")
		(net "P5E_CPU0_P1_RX_DP<12>")
	)
	(segment
		(start 355.023166 -274.896072)
		(end 355.321108 -274.896072)
		(width 0.1143)
		(layer "In11.Cu")
		(net "P5E_CPU0_P1_RX_DP<12>")
	)
	(segment
		(start 356.576376 -282.527502)
		(end 356.575614 -282.526994)
		(width 0.1143)
		(layer "In11.Cu")
		(net "P5E_CPU0_P1_RX_DP<12>")
	)
	(segment
		(start 356.583234 -277.67153)
		(end 356.576376 -277.667466)
		(width 0.1143)
		(layer "In11.Cu")
		(net "P5E_CPU0_P1_RX_DP<12>")
	)
	(segment
		(start 356.512368 -280.261822)
		(end 356.512622 -280.262076)
		(width 0.1143)
		(layer "In11.Cu")
		(net "P5E_CPU0_P1_RX_DP<12>")
	)
	(segment
		(start 356.540562 -279.26665)
		(end 356.5398 -279.266142)
		(width 0.1143)
		(layer "In11.Cu")
		(net "P5E_CPU0_P1_RX_DP<12>")
	)
	(segment
		(start 371.463316 -321.541902)
		(end 364.422944 -312.963306)
		(width 0.14224)
		(layer "In11.Cu")
		(net "P5E_CPU0_P1_RX_DP<12>")
	)
	(segment
		(start 356.544118 -282.508706)
		(end 356.543356 -282.508198)
		(width 0.1143)
		(layer "In11.Cu")
		(net "P5E_CPU0_P1_RX_DP<12>")
	)
	(segment
		(start 356.575614 -290.6268)
		(end 356.548436 -290.611052)
		(width 0.1143)
		(layer "In11.Cu")
		(net "P5E_CPU0_P1_RX_DP<12>")
	)
	(segment
		(start 356.548436 -292.231064)
		(end 356.545134 -292.229032)
		(width 0.1143)
		(layer "In11.Cu")
		(net "P5E_CPU0_P1_RX_DP<12>")
	)
	(segment
		(start 356.11308 -276.861524)
		(end 356.073964 -276.838664)
		(width 0.1143)
		(layer "In11.Cu")
		(net "P5E_CPU0_P1_RX_DP<12>")
	)
	(segment
		(start 356.544118 -293.848536)
		(end 356.543356 -293.848028)
		(width 0.1143)
		(layer "In11.Cu")
		(net "P5E_CPU0_P1_RX_DP<12>")
	)
	(segment
		(start 351.213674 -394.031216)
		(end 351.387918 -393.930632)
		(width 0.14224)
		(layer "In11.Cu")
		(net "P5E_CPU0_P1_RX_DP<12>")
	)
	(segment
		(start 356.548436 -293.851076)
		(end 356.545134 -293.849044)
		(width 0.1143)
		(layer "In11.Cu")
		(net "P5E_CPU0_P1_RX_DP<12>")
	)
	(segment
		(start 356.545134 -279.26919)
		(end 356.544118 -279.268682)
		(width 0.1143)
		(layer "In11.Cu")
		(net "P5E_CPU0_P1_RX_DP<12>")
	)
	(segment
		(start 356.401878 -295.6687)
		(end 356.356158 -295.62298)
		(width 0.1143)
		(layer "In11.Cu")
		(net "P5E_CPU0_P1_RX_DP<12>")
	)
	(segment
		(start 356.545134 -282.509214)
		(end 356.544118 -282.508706)
		(width 0.1143)
		(layer "In11.Cu")
		(net "P5E_CPU0_P1_RX_DP<12>")
	)
	(segment
		(start 356.540562 -277.646638)
		(end 356.5398 -277.64613)
		(width 0.1143)
		(layer "In11.Cu")
		(net "P5E_CPU0_P1_RX_DP<12>")
	)
	(segment
		(start 356.5398 -282.506166)
		(end 356.538784 -282.505658)
		(width 0.1143)
		(layer "In11.Cu")
		(net "P5E_CPU0_P1_RX_DP<12>")
	)
	(segment
		(start 356.545134 -280.889202)
		(end 356.544118 -280.888694)
		(width 0.1143)
		(layer "In11.Cu")
		(net "P5E_CPU0_P1_RX_DP<12>")
	)
	(segment
		(start 356.540562 -291.585396)
		(end 356.543356 -291.583872)
		(width 0.1143)
		(layer "In11.Cu")
		(net "P5E_CPU0_P1_RX_DP<12>")
	)
	(segment
		(start 356.543356 -292.228016)
		(end 356.542086 -292.227254)
		(width 0.1143)
		(layer "In11.Cu")
		(net "P5E_CPU0_P1_RX_DP<12>")
	)
	(segment
		(start 356.547674 -281.861514)
		(end 356.548436 -281.861006)
		(width 0.1143)
		(layer "In11.Cu")
		(net "P5E_CPU0_P1_RX_DP<12>")
	)
	(segment
		(start 356.580694 -287.389824)
		(end 356.544118 -287.368488)
		(width 0.1143)
		(layer "In11.Cu")
		(net "P5E_CPU0_P1_RX_DP<12>")
	)
	(segment
		(start 356.545134 -285.749238)
		(end 356.544118 -285.74873)
		(width 0.1143)
		(layer "In11.Cu")
		(net "P5E_CPU0_P1_RX_DP<12>")
	)
	(segment
		(start 356.548436 -281.861006)
		(end 356.5525 -281.85872)
		(width 0.1143)
		(layer "In11.Cu")
		(net "P5E_CPU0_P1_RX_DP<12>")
	)
	(segment
		(start 356.51059 -286.74314)
		(end 356.544118 -286.723582)
		(width 0.1143)
		(layer "In11.Cu")
		(net "P5E_CPU0_P1_RX_DP<12>")
	)
	(segment
		(start 356.576376 -284.147514)
		(end 356.575614 -284.147006)
		(width 0.1143)
		(layer "In11.Cu")
		(net "P5E_CPU0_P1_RX_DP<12>")
	)
	(segment
		(start 356.576376 -292.24732)
		(end 356.575614 -292.246812)
		(width 0.1143)
		(layer "In11.Cu")
		(net "P5E_CPU0_P1_RX_DP<12>")
	)
	(segment
		(start 356.545134 -293.849044)
		(end 356.544118 -293.848536)
		(width 0.1143)
		(layer "In11.Cu")
		(net "P5E_CPU0_P1_RX_DP<12>")
	)
	(segment
		(start 356.538784 -280.885646)
		(end 356.538022 -280.885138)
		(width 0.1143)
		(layer "In11.Cu")
		(net "P5E_CPU0_P1_RX_DP<12>")
	)
	(segment
		(start 356.575614 -289.006788)
		(end 356.548436 -288.99104)
		(width 0.1143)
		(layer "In11.Cu")
		(net "P5E_CPU0_P1_RX_DP<12>")
	)
	(segment
		(start 356.533958 -281.869388)
		(end 356.53472 -281.86888)
		(width 0.1143)
		(layer "In11.Cu")
		(net "P5E_CPU0_P1_RX_DP<12>")
	)
	(segment
		(start 356.538276 -281.866848)
		(end 356.5398 -281.866086)
		(width 0.1143)
		(layer "In11.Cu")
		(net "P5E_CPU0_P1_RX_DP<12>")
	)
	(segment
		(start 356.545134 -290.60902)
		(end 356.544118 -290.608512)
		(width 0.1143)
		(layer "In11.Cu")
		(net "P5E_CPU0_P1_RX_DP<12>")
	)
	(segment
		(start 356.537514 -291.587174)
		(end 356.538276 -291.586666)
		(width 0.1143)
		(layer "In11.Cu")
		(net "P5E_CPU0_P1_RX_DP<12>")
	)
	(segment
		(start 356.583234 -279.291542)
		(end 356.576376 -279.287478)
		(width 0.1143)
		(layer "In11.Cu")
		(net "P5E_CPU0_P1_RX_DP<12>")
	)
	(segment
		(start 356.535482 -282.50388)
		(end 356.512368 -282.490418)
		(width 0.1143)
		(layer "In11.Cu")
		(net "P5E_CPU0_P1_RX_DP<12>")
	)
	(segment
		(start 356.512622 -283.5021)
		(end 356.513638 -283.501592)
		(width 0.1143)
		(layer "In11.Cu")
		(net "P5E_CPU0_P1_RX_DP<12>")
	)
	(segment
		(start 356.575868 -280.224992)
		(end 356.583234 -280.220674)
		(width 0.1143)
		(layer "In11.Cu")
		(net "P5E_CPU0_P1_RX_DP<12>")
	)
	(segment
		(start 356.583234 -284.151578)
		(end 356.576376 -284.147514)
		(width 0.1143)
		(layer "In11.Cu")
		(net "P5E_CPU0_P1_RX_DP<12>")
	)
	(segment
		(start 356.53472 -281.86888)
		(end 356.536244 -281.868118)
		(width 0.1143)
		(layer "In11.Cu")
		(net "P5E_CPU0_P1_RX_DP<12>")
	)
	(segment
		(start 356.544118 -287.368488)
		(end 356.512368 -287.3502)
		(width 0.1143)
		(layer "In11.Cu")
		(net "P5E_CPU0_P1_RX_DP<12>")
	)
	(segment
		(start 356.57536 -285.085282)
		(end 356.583234 -285.08071)
		(width 0.1143)
		(layer "In11.Cu")
		(net "P5E_CPU0_P1_RX_DP<12>")
	)
	(segment
		(start 356.544118 -291.583364)
		(end 356.545134 -291.582856)
		(width 0.1143)
		(layer "In11.Cu")
		(net "P5E_CPU0_P1_RX_DP<12>")
	)
	(segment
		(start 356.544118 -292.228524)
		(end 356.543356 -292.228016)
		(width 0.1143)
		(layer "In11.Cu")
		(net "P5E_CPU0_P1_RX_DP<12>")
	)
	(segment
		(start 356.575614 -280.906982)
		(end 356.545134 -280.889202)
		(width 0.1143)
		(layer "In11.Cu")
		(net "P5E_CPU0_P1_RX_DP<12>")
	)
	(segment
		(start 356.538022 -285.745174)
		(end 356.535482 -285.743904)
		(width 0.1143)
		(layer "In11.Cu")
		(net "P5E_CPU0_P1_RX_DP<12>")
	)
	(segment
		(start 356.535482 -284.123892)
		(end 356.512368 -284.11043)
		(width 0.1143)
		(layer "In11.Cu")
		(net "P5E_CPU0_P1_RX_DP<12>")
	)
	(segment
		(start 356.540562 -284.126686)
		(end 356.5398 -284.126178)
		(width 0.1143)
		(layer "In11.Cu")
		(net "P5E_CPU0_P1_RX_DP<12>")
	)
	(segment
		(start 356.543356 -293.848028)
		(end 356.542086 -293.847266)
		(width 0.1143)
		(layer "In11.Cu")
		(net "P5E_CPU0_P1_RX_DP<12>")
	)
	(segment
		(start 356.575614 -285.767018)
		(end 356.545134 -285.749238)
		(width 0.1143)
		(layer "In11.Cu")
		(net "P5E_CPU0_P1_RX_DP<12>")
	)
	(segment
		(start 354.953316 -274.965922)
		(end 355.023166 -274.896072)
		(width 0.1143)
		(layer "In11.Cu")
		(net "P5E_CPU0_P1_RX_DP<12>")
	)
	(segment
		(start 356.535482 -285.743904)
		(end 356.512368 -285.730442)
		(width 0.1143)
		(layer "In11.Cu")
		(net "P5E_CPU0_P1_RX_DP<12>")
	)
	(segment
		(start 356.575614 -292.246812)
		(end 356.548436 -292.231064)
		(width 0.1143)
		(layer "In11.Cu")
		(net "P5E_CPU0_P1_RX_DP<12>")
	)
	(segment
		(start 356.512368 -291.601652)
		(end 356.51313 -291.601144)
		(width 0.1143)
		(layer "In11.Cu")
		(net "P5E_CPU0_P1_RX_DP<12>")
	)
	(segment
		(start 355.134164 -275.218652)
		(end 355.102414 -275.200364)
		(width 0.1143)
		(layer "In11.Cu")
		(net "P5E_CPU0_P1_RX_DP<12>")
	)
	(segment
		(start 356.540562 -280.886662)
		(end 356.5398 -280.886154)
		(width 0.1143)
		(layer "In11.Cu")
		(net "P5E_CPU0_P1_RX_DP<12>")
	)
	(segment
		(start 356.512368 -293.221664)
		(end 356.575868 -293.184834)
		(width 0.1143)
		(layer "In11.Cu")
		(net "P5E_CPU0_P1_RX_DP<12>")
	)
	(segment
		(start 356.401878 -295.697148)
		(end 356.401878 -295.6687)
		(width 0.1143)
		(layer "In11.Cu")
		(net "P5E_CPU0_P1_RX_DP<12>")
	)
	(segment
		(start 356.514908 -283.50083)
		(end 356.51567 -283.500322)
		(width 0.1143)
		(layer "In11.Cu")
		(net "P5E_CPU0_P1_RX_DP<12>")
	)
	(segment
		(start 356.533958 -291.589206)
		(end 356.53472 -291.588698)
		(width 0.1143)
		(layer "In11.Cu")
		(net "P5E_CPU0_P1_RX_DP<12>")
	)
	(segment
		(start 356.55885 -283.474922)
		(end 356.575868 -283.465016)
		(width 0.1143)
		(layer "In11.Cu")
		(net "P5E_CPU0_P1_RX_DP<12>")
	)
	(segment
		(start 356.544118 -285.74873)
		(end 356.543356 -285.748222)
		(width 0.1143)
		(layer "In11.Cu")
		(net "P5E_CPU0_P1_RX_DP<12>")
	)
	(segment
		(start 356.537006 -294.827452)
		(end 356.538022 -294.826944)
		(width 0.1143)
		(layer "In11.Cu")
		(net "P5E_CPU0_P1_RX_DP<12>")
	)
	(segment
		(start 356.538022 -279.265126)
		(end 356.535482 -279.263856)
		(width 0.1143)
		(layer "In11.Cu")
		(net "P5E_CPU0_P1_RX_DP<12>")
	)
	(segment
		(start 356.532688 -281.87015)
		(end 356.533958 -281.869388)
		(width 0.1143)
		(layer "In11.Cu")
		(net "P5E_CPU0_P1_RX_DP<12>")
	)
	(segment
		(start 356.543356 -282.508198)
		(end 356.540562 -282.506674)
		(width 0.1143)
		(layer "In11.Cu")
		(net "P5E_CPU0_P1_RX_DP<12>")
	)
	(segment
		(start 356.576376 -277.667466)
		(end 356.575614 -277.666958)
		(width 0.1143)
		(layer "In11.Cu")
		(net "P5E_CPU0_P1_RX_DP<12>")
	)
	(segment
		(start 356.512368 -281.881834)
		(end 356.532688 -281.87015)
		(width 0.1143)
		(layer "In11.Cu")
		(net "P5E_CPU0_P1_RX_DP<12>")
	)
	(segment
		(start 356.513638 -283.501592)
		(end 356.514908 -283.50083)
		(width 0.1143)
		(layer "In11.Cu")
		(net "P5E_CPU0_P1_RX_DP<12>")
	)
	(segment
		(start 356.542086 -288.98723)
		(end 356.512368 -288.970212)
		(width 0.1143)
		(layer "In11.Cu")
		(net "P5E_CPU0_P1_RX_DP<12>")
	)
	(segment
		(start 356.53472 -291.588698)
		(end 356.536244 -291.587936)
		(width 0.1143)
		(layer "In11.Cu")
		(net "P5E_CPU0_P1_RX_DP<12>")
	)
	(segment
		(start 356.073964 -276.838664)
		(end 356.043484 -276.820884)
		(width 0.1143)
		(layer "In11.Cu")
		(net "P5E_CPU0_P1_RX_DP<12>")
	)
	(segment
		(start 376.526806 -349.642938)
		(end 376.526806 -339.278214)
		(width 0.14224)
		(layer "In11.Cu")
		(net "P5E_CPU0_P1_RX_DP<12>")
	)
	(segment
		(start 356.576376 -279.287478)
		(end 356.575614 -279.28697)
		(width 0.1143)
		(layer "In11.Cu")
		(net "P5E_CPU0_P1_RX_DP<12>")
	)
	(segment
		(start 356.544118 -290.608512)
		(end 356.543356 -290.608004)
		(width 0.1143)
		(layer "In11.Cu")
		(net "P5E_CPU0_P1_RX_DP<12>")
	)
	(segment
		(start 356.576376 -293.867332)
		(end 356.575614 -293.866824)
		(width 0.1143)
		(layer "In11.Cu")
		(net "P5E_CPU0_P1_RX_DP<12>")
	)
	(segment
		(start 356.538022 -282.50515)
		(end 356.535482 -282.50388)
		(width 0.1143)
		(layer "In11.Cu")
		(net "P5E_CPU0_P1_RX_DP<12>")
	)
	(segment
		(start 356.544118 -279.268682)
		(end 356.543356 -279.268174)
		(width 0.1143)
		(layer "In11.Cu")
		(net "P5E_CPU0_P1_RX_DP<12>")
	)
	(segment
		(start 375.425208 -333.144876)
		(end 374.331738 -327.058274)
		(width 0.14224)
		(layer "In11.Cu")
		(net "P5E_CPU0_P1_RX_DP<12>")
	)
	(segment
		(start 356.583234 -293.871396)
		(end 356.576376 -293.867332)
		(width 0.1143)
		(layer "In11.Cu")
		(net "P5E_CPU0_P1_RX_DP<12>")
	)
	(segment
		(start 356.543356 -294.823896)
		(end 356.544118 -294.823388)
		(width 0.1143)
		(layer "In11.Cu")
		(net "P5E_CPU0_P1_RX_DP<12>")
	)
	(segment
		(start 356.583234 -289.01136)
		(end 356.576376 -289.007296)
		(width 0.1143)
		(layer "In11.Cu")
		(net "P5E_CPU0_P1_RX_DP<12>")
	)
	(segment
		(start 356.512368 -283.501846)
		(end 356.512622 -283.5021)
		(width 0.1143)
		(layer "In11.Cu")
		(net "P5E_CPU0_P1_RX_DP<12>")
	)
	(segment
		(start 356.575614 -279.28697)
		(end 356.545134 -279.26919)
		(width 0.1143)
		(layer "In11.Cu")
		(net "P5E_CPU0_P1_RX_DP<12>")
	)
	(segment
		(start 356.516432 -278.639778)
		(end 356.583234 -278.600662)
		(width 0.1143)
		(layer "In11.Cu")
		(net "P5E_CPU0_P1_RX_DP<12>")
	)
	(segment
		(start 351.476056 -393.842494)
		(end 351.476056 -393.428982)
		(width 0.14224)
		(layer "In11.Cu")
		(net "P5E_CPU0_P1_RX_DP<12>")
	)
	(segment
		(start 356.576376 -280.90749)
		(end 356.575614 -280.906982)
		(width 0.1143)
		(layer "In11.Cu")
		(net "P5E_CPU0_P1_RX_DP<12>")
	)
	(segment
		(start 356.543356 -288.987992)
		(end 356.542086 -288.98723)
		(width 0.1143)
		(layer "In11.Cu")
		(net "P5E_CPU0_P1_RX_DP<12>")
	)
	(segment
		(start 356.536244 -281.868118)
		(end 356.537514 -281.867356)
		(width 0.1143)
		(layer "In11.Cu")
		(net "P5E_CPU0_P1_RX_DP<12>")
	)
	(segment
		(start 356.583234 -285.77159)
		(end 356.576376 -285.767526)
		(width 0.1143)
		(layer "In11.Cu")
		(net "P5E_CPU0_P1_RX_DP<12>")
	)
	(segment
		(start 351.467928 -392.430254)
		(end 351.467928 -390.59612)
		(width 0.14224)
		(layer "In11.Cu")
		(net "P5E_CPU0_P1_RX_DP<12>")
	)
	(segment
		(start 356.356158 -295.62298)
		(end 356.356158 -295.423336)
		(width 0.1143)
		(layer "In11.Cu")
		(net "P5E_CPU0_P1_RX_DP<12>")
	)
	(segment
		(start 355.940614 -380.265178)
		(end 355.940614 -376.642376)
		(width 0.14224)
		(layer "In11.Cu")
		(net "P5E_CPU0_P1_RX_DP<12>")
	)
	(segment
		(start 356.544118 -288.343594)
		(end 356.583234 -288.320734)
		(width 0.1143)
		(layer "In11.Cu")
		(net "P5E_CPU0_P1_RX_DP<12>")
	)
	(segment
		(start 356.542086 -292.227254)
		(end 356.512368 -292.210236)
		(width 0.1143)
		(layer "In11.Cu")
		(net "P5E_CPU0_P1_RX_DP<12>")
	)
	(segment
		(start 356.401878 -298.74972)
		(end 356.401878 -295.697148)
		(width 0.14224)
		(layer "In11.Cu")
		(net "P5E_CPU0_P1_RX_DP<12>")
	)
	(segment
		(start 356.545134 -292.229032)
		(end 356.544118 -292.228524)
		(width 0.1143)
		(layer "In11.Cu")
		(net "P5E_CPU0_P1_RX_DP<12>")
	)
	(segment
		(start 356.538784 -285.745682)
		(end 356.538022 -285.745174)
		(width 0.1143)
		(layer "In11.Cu")
		(net "P5E_CPU0_P1_RX_DP<12>")
	)
	(segment
		(start 356.538784 -282.505658)
		(end 356.538022 -282.50515)
		(width 0.1143)
		(layer "In11.Cu")
		(net "P5E_CPU0_P1_RX_DP<12>")
	)
	(segment
		(start 356.583234 -290.631372)
		(end 356.576376 -290.627308)
		(width 0.1143)
		(layer "In11.Cu")
		(net "P5E_CPU0_P1_RX_DP<12>")
	)
	(segment
		(start 356.538022 -280.885138)
		(end 356.535482 -280.883868)
		(width 0.1143)
		(layer "In11.Cu")
		(net "P5E_CPU0_P1_RX_DP<12>")
	)
	(segment
		(start 356.580694 -289.942016)
		(end 356.583234 -289.940492)
		(width 0.1143)
		(layer "In11.Cu")
		(net "P5E_CPU0_P1_RX_DP<12>")
	)
	(segment
		(start 356.545134 -281.863038)
		(end 356.546658 -281.862022)
		(width 0.1143)
		(layer "In11.Cu")
		(net "P5E_CPU0_P1_RX_DP<12>")
	)
	(segment
		(start 356.512622 -280.262076)
		(end 356.514908 -280.260552)
		(width 0.1143)
		(layer "In11.Cu")
		(net "P5E_CPU0_P1_RX_DP<12>")
	)
	(segment
		(start 356.544118 -277.64867)
		(end 356.543356 -277.648162)
		(width 0.1143)
		(layer "In11.Cu")
		(net "P5E_CPU0_P1_RX_DP<12>")
	)
	(segment
		(start 356.545134 -291.582856)
		(end 356.546658 -291.58184)
		(width 0.1143)
		(layer "In11.Cu")
		(net "P5E_CPU0_P1_RX_DP<12>")
	)
	(segment
		(start 355.170486 -275.239734)
		(end 355.134164 -275.218652)
		(width 0.1143)
		(layer "In11.Cu")
		(net "P5E_CPU0_P1_RX_DP<12>")
	)
	(segment
		(start 356.575868 -293.184834)
		(end 356.583234 -293.180516)
		(width 0.1143)
		(layer "In11.Cu")
		(net "P5E_CPU0_P1_RX_DP<12>")
	)
	(segment
		(start 356.538022 -277.645114)
		(end 356.535482 -277.643844)
		(width 0.1143)
		(layer "In11.Cu")
		(net "P5E_CPU0_P1_RX_DP<12>")
	)
	(segment
		(start 356.543356 -280.888186)
		(end 356.540562 -280.886662)
		(width 0.1143)
		(layer "In11.Cu")
		(net "P5E_CPU0_P1_RX_DP<12>")
	)
	(segment
		(start 356.540562 -281.865578)
		(end 356.543356 -281.864054)
		(width 0.1143)
		(layer "In11.Cu")
		(net "P5E_CPU0_P1_RX_DP<12>")
	)
	(segment
		(start 356.538022 -294.826944)
		(end 356.540562 -294.82542)
		(width 0.1143)
		(layer "In11.Cu")
		(net "P5E_CPU0_P1_RX_DP<12>")
	)
	(segment
		(start 355.64318 -276.051518)
		(end 355.576632 -276.01291)
		(width 0.1143)
		(layer "In11.Cu")
		(net "P5E_CPU0_P1_RX_DP<12>")
	)
	(segment
		(start 356.538784 -284.12567)
		(end 356.538022 -284.125162)
		(width 0.1143)
		(layer "In11.Cu")
		(net "P5E_CPU0_P1_RX_DP<12>")
	)
	(segment
		(start 375.424954 -333.144876)
		(end 375.425208 -333.144876)
		(width 0.14224)
		(layer "In11.Cu")
		(net "P5E_CPU0_P1_RX_DP<12>")
	)
	(segment
		(start 356.546658 -281.862022)
		(end 356.547674 -281.861514)
		(width 0.1143)
		(layer "In11.Cu")
		(net "P5E_CPU0_P1_RX_DP<12>")
	)
	(segment
		(start 358.810052 -304.563526)
		(end 356.401878 -298.74972)
		(width 0.14224)
		(layer "In11.Cu")
		(net "P5E_CPU0_P1_RX_DP<12>")
	)
	(segment
		(start 356.537514 -281.867356)
		(end 356.538276 -281.866848)
		(width 0.1143)
		(layer "In11.Cu")
		(net "P5E_CPU0_P1_RX_DP<12>")
	)
	(segment
		(start 356.512368 -294.841676)
		(end 356.537006 -294.827452)
		(width 0.1143)
		(layer "In11.Cu")
		(net "P5E_CPU0_P1_RX_DP<12>")
	)
	(segment
		(start 351.16008 -393.113006)
		(end 351.163128 -392.7348)
		(width 0.14224)
		(layer "In11.Cu")
		(net "P5E_CPU0_P1_RX_DP<12>")
	)
	(segment
		(start 356.544118 -286.723582)
		(end 356.583234 -286.700722)
		(width 0.1143)
		(layer "In11.Cu")
		(net "P5E_CPU0_P1_RX_DP<12>")
	)
	(segment
		(start 356.540562 -282.506674)
		(end 356.5398 -282.506166)
		(width 0.1143)
		(layer "In11.Cu")
		(net "P5E_CPU0_P1_RX_DP<12>")
	)
	(segment
		(start 356.535482 -279.263856)
		(end 356.512368 -279.250394)
		(width 0.1143)
		(layer "In11.Cu")
		(net "P5E_CPU0_P1_RX_DP<12>")
	)
	(segment
		(start 356.546658 -291.58184)
		(end 356.583234 -291.560504)
		(width 0.1143)
		(layer "In11.Cu")
		(net "P5E_CPU0_P1_RX_DP<12>")
	)
	(segment
		(start 356.543356 -290.608004)
		(end 356.542086 -290.607242)
		(width 0.1143)
		(layer "In11.Cu")
		(net "P5E_CPU0_P1_RX_DP<12>")
	)
	(segment
		(start 356.544118 -288.9885)
		(end 356.543356 -288.987992)
		(width 0.1143)
		(layer "In11.Cu")
		(net "P5E_CPU0_P1_RX_DP<12>")
	)
	(segment
		(start 356.543356 -284.12821)
		(end 356.540562 -284.126686)
		(width 0.1143)
		(layer "In11.Cu")
		(net "P5E_CPU0_P1_RX_DP<12>")
	)
	(segment
		(start 356.51313 -291.601144)
		(end 356.528624 -291.592254)
		(width 0.1143)
		(layer "In11.Cu")
		(net "P5E_CPU0_P1_RX_DP<12>")
	)
	(segment
		(start 356.543356 -277.648162)
		(end 356.540562 -277.646638)
		(width 0.1143)
		(layer "In11.Cu")
		(net "P5E_CPU0_P1_RX_DP<12>")
	)
	(segment
		(start 356.5398 -284.126178)
		(end 356.538784 -284.12567)
		(width 0.1143)
		(layer "In11.Cu")
		(net "P5E_CPU0_P1_RX_DP<12>")
	)
	(segment
		(start 356.356412 -295.423082)
		(end 356.356412 -295.145968)
		(width 0.1143)
		(layer "In11.Cu")
		(net "P5E_CPU0_P1_RX_DP<12>")
	)
	(segment
		(start 356.528624 -291.592254)
		(end 356.529386 -291.591746)
		(width 0.1143)
		(layer "In11.Cu")
		(net "P5E_CPU0_P1_RX_DP<12>")
	)
	(segment
		(start 356.543356 -279.268174)
		(end 356.540562 -279.26665)
		(width 0.1143)
		(layer "In11.Cu")
		(net "P5E_CPU0_P1_RX_DP<12>")
	)
	(segment
		(start 356.575614 -277.666958)
		(end 356.545134 -277.649178)
		(width 0.1143)
		(layer "In11.Cu")
		(net "P5E_CPU0_P1_RX_DP<12>")
	)
	(segment
		(start 356.583234 -292.251384)
		(end 356.576376 -292.24732)
		(width 0.1143)
		(layer "In11.Cu")
		(net "P5E_CPU0_P1_RX_DP<12>")
	)
	(segment
		(start 356.535482 -277.643844)
		(end 356.512368 -277.630382)
		(width 0.1143)
		(layer "In11.Cu")
		(net "P5E_CPU0_P1_RX_DP<12>")
	)
	(segment
		(start 356.545134 -284.129226)
		(end 356.544118 -284.128718)
		(width 0.1143)
		(layer "In11.Cu")
		(net "P5E_CPU0_P1_RX_DP<12>")
	)
	(segment
		(start 374.323864 -327.014586)
		(end 371.463316 -321.541902)
		(width 0.14224)
		(layer "In11.Cu")
		(net "P5E_CPU0_P1_RX_DP<12>")
	)
	(segment
		(start 351.576386 -390.088882)
		(end 355.9048 -380.432564)
		(width 0.14224)
		(layer "In11.Cu")
		(net "P5E_CPU0_P1_RX_DP<12>")
	)
	(segment
		(start 356.5398 -281.866086)
		(end 356.540562 -281.865578)
		(width 0.1143)
		(layer "In11.Cu")
		(net "P5E_CPU0_P1_RX_DP<12>")
	)
	(segment
		(start 356.542086 -293.847266)
		(end 356.512368 -293.830248)
		(width 0.1143)
		(layer "In11.Cu")
		(net "P5E_CPU0_P1_RX_DP<12>")
	)
	(segment
		(start 356.514908 -280.260552)
		(end 356.575868 -280.224992)
		(width 0.1143)
		(layer "In11.Cu")
		(net "P5E_CPU0_P1_RX_DP<12>")
	)
	(segment
		(start 356.512368 -278.64181)
		(end 356.512368 -278.642064)
		(width 0.1143)
		(layer "In11.Cu")
		(net "P5E_CPU0_P1_RX_DP<12>")
	)
	(segment
		(start 356.356158 -295.423336)
		(end 356.356412 -295.423082)
		(width 0.1143)
		(layer "In11.Cu")
		(net "P5E_CPU0_P1_RX_DP<12>")
	)
	(segment
		(start 356.512368 -285.121858)
		(end 356.574598 -285.08579)
		(width 0.1143)
		(layer "In11.Cu")
		(net "P5E_CPU0_P1_RX_DP<12>")
	)
	(segment
		(start 356.540562 -285.746698)
		(end 356.5398 -285.74619)
		(width 0.1143)
		(layer "In11.Cu")
		(net "P5E_CPU0_P1_RX_DP<12>")
	)
	(segment
		(start 351.163128 -392.7348)
		(end 351.467928 -392.430254)
		(width 0.14224)
		(layer "In11.Cu")
		(net "P5E_CPU0_P1_RX_DP<12>")
	)
	(segment
		(start 356.576376 -289.007296)
		(end 356.575614 -289.006788)
		(width 0.1143)
		(layer "In11.Cu")
		(net "P5E_CPU0_P1_RX_DP<12>")
	)
	(segment
		(start 351.118678 -394.385292)
		(end 351.213674 -394.031216)
		(width 0.14224)
		(layer "In11.Cu")
		(net "P5E_CPU0_P1_RX_DP<12>")
	)
	(segment
		(start 356.51567 -283.500322)
		(end 356.55885 -283.474922)
		(width 0.1143)
		(layer "In11.Cu")
		(net "P5E_CPU0_P1_RX_DP<12>")
	)
	(segment
		(start 356.51567 -278.640286)
		(end 356.516432 -278.639778)
		(width 0.1143)
		(layer "In11.Cu")
		(net "P5E_CPU0_P1_RX_DP<12>")
	)
	(segment
		(start 356.538276 -291.586666)
		(end 356.5398 -291.585904)
		(width 0.1143)
		(layer "In11.Cu")
		(net "P5E_CPU0_P1_RX_DP<12>")
	)
	(segment
		(start 356.542086 -294.824658)
		(end 356.543356 -294.823896)
		(width 0.1143)
		(layer "In11.Cu")
		(net "P5E_CPU0_P1_RX_DP<12>")
	)
	(segment
		(start 356.5398 -279.266142)
		(end 356.538784 -279.265634)
		(width 0.1143)
		(layer "In11.Cu")
		(net "P5E_CPU0_P1_RX_DP<12>")
	)
	(segment
		(start 356.5525 -281.85872)
		(end 356.554024 -281.857704)
		(width 0.1143)
		(layer "In11.Cu")
		(net "P5E_CPU0_P1_RX_DP<12>")
	)
	(segment
		(start 356.544118 -280.888694)
		(end 356.543356 -280.888186)
		(width 0.1143)
		(layer "In11.Cu")
		(net "P5E_CPU0_P1_RX_DP<12>")
	)
	(segment
		(start 374.331738 -327.058274)
		(end 374.323864 -327.014586)
		(width 0.14224)
		(layer "In11.Cu")
		(net "P5E_CPU0_P1_RX_DP<12>")
	)
	(segment
		(start 356.548436 -288.99104)
		(end 356.545134 -288.989008)
		(width 0.1143)
		(layer "In11.Cu")
		(net "P5E_CPU0_P1_RX_DP<12>")
	)
	(segment
		(start 376.526806 -339.278214)
		(end 375.424954 -333.144876)
		(width 0.14224)
		(layer "In11.Cu")
		(net "P5E_CPU0_P1_RX_DP<12>")
	)
	(segment
		(start 356.545134 -294.82288)
		(end 356.583234 -294.800528)
		(width 0.1143)
		(layer "In11.Cu")
		(net "P5E_CPU0_P1_RX_DP<12>")
	)
	(segment
		(start 356.544118 -294.823388)
		(end 356.545134 -294.82288)
		(width 0.1143)
		(layer "In11.Cu")
		(net "P5E_CPU0_P1_RX_DP<12>")
	)
	(segment
		(start 356.512368 -278.642064)
		(end 356.51567 -278.640286)
		(width 0.1143)
		(layer "In11.Cu")
		(net "P5E_CPU0_P1_RX_DP<12>")
	)
	(segment
		(start 356.5398 -280.886154)
		(end 356.538784 -280.885646)
		(width 0.1143)
		(layer "In11.Cu")
		(net "P5E_CPU0_P1_RX_DP<12>")
	)
	(segment
		(start 356.545134 -288.989008)
		(end 356.544118 -288.9885)
		(width 0.1143)
		(layer "In11.Cu")
		(net "P5E_CPU0_P1_RX_DP<12>")
	)
	(segment
		(start 356.575614 -293.866824)
		(end 356.548436 -293.851076)
		(width 0.1143)
		(layer "In11.Cu")
		(net "P5E_CPU0_P1_RX_DP<12>")
	)
	(segment
		(start 356.574598 -285.08579)
		(end 356.57536 -285.085282)
		(width 0.1143)
		(layer "In11.Cu")
		(net "P5E_CPU0_P1_RX_DP<12>")
	)
	(segment
		(start 356.227126 -375.950734)
		(end 368.695224 -363.482636)
		(width 0.14224)
		(layer "In11.Cu")
		(net "P5E_CPU0_P1_RX_DP<12>")
	)
	(segment
		(start 356.5398 -291.585904)
		(end 356.540562 -291.585396)
		(width 0.1143)
		(layer "In11.Cu")
		(net "P5E_CPU0_P1_RX_DP<12>")
	)
	(segment
		(start 356.5398 -277.64613)
		(end 356.538784 -277.645622)
		(width 0.1143)
		(layer "In11.Cu")
		(net "P5E_CPU0_P1_RX_DP<12>")
	)
	(segment
		(start 356.540562 -294.82542)
		(end 356.542086 -294.824658)
		(width 0.1143)
		(layer "In11.Cu")
		(net "P5E_CPU0_P1_RX_DP<12>")
	)
	(arc
		(start 356.583234 -285.08071)
		(mid 356.826561 -284.616144)
		(end 356.583234 -284.151578)
		(width 0.1143)
		(layer "In11.Cu")
		(net "P5E_CPU0_P1_RX_DP<12>")
	)
	(arc
		(start 356.512368 -279.250394)
		(mid 356.35644 -278.946102)
		(end 356.512368 -278.64181)
		(width 0.1143)
		(layer "In11.Cu")
		(net "P5E_CPU0_P1_RX_DP<12>")
	)
	(arc
		(start 356.512368 -280.870406)
		(mid 356.35644 -280.566114)
		(end 356.512368 -280.261822)
		(width 0.1143)
		(layer "In11.Cu")
		(net "P5E_CPU0_P1_RX_DP<12>")
	)
	(arc
		(start 356.356412 -288.66592)
		(mid 356.397174 -288.496036)
		(end 356.51059 -288.363152)
		(width 0.1143)
		(layer "In11.Cu")
		(net "P5E_CPU0_P1_RX_DP<12>")
	)
	(arc
		(start 356.583234 -286.700722)
		(mid 356.826561 -286.236156)
		(end 356.583234 -285.77159)
		(width 0.1143)
		(layer "In11.Cu")
		(net "P5E_CPU0_P1_RX_DP<12>")
	)
	(arc
		(start 356.583234 -281.840686)
		(mid 356.826561 -281.37612)
		(end 356.583234 -280.911554)
		(width 0.1143)
		(layer "In11.Cu")
		(net "P5E_CPU0_P1_RX_DP<12>")
	)
	(arc
		(start 356.512368 -277.630382)
		(mid 356.397692 -277.497048)
		(end 356.356412 -277.32609)
		(width 0.1143)
		(layer "In11.Cu")
		(net "P5E_CPU0_P1_RX_DP<12>")
	)
	(arc
		(start 356.512368 -290.590224)
		(mid 356.35644 -290.285932)
		(end 356.512368 -289.98164)
		(width 0.1143)
		(layer "In11.Cu")
		(net "P5E_CPU0_P1_RX_DP<12>")
	)
	(arc
		(start 351.467928 -390.59612)
		(mid 351.495347 -390.336769)
		(end 351.576386 -390.088882)
		(width 0.14224)
		(layer "In11.Cu")
		(net "P5E_CPU0_P1_RX_DP<12>")
	)
	(arc
		(start 355.186742 -275.251164)
		(mid 355.178664 -275.245378)
		(end 355.170486 -275.239734)
		(width 0.1143)
		(layer "In11.Cu")
		(net "P5E_CPU0_P1_RX_DP<12>")
	)
	(arc
		(start 355.940614 -376.642376)
		(mid 356.015072 -376.268053)
		(end 356.227126 -375.950734)
		(width 0.14224)
		(layer "In11.Cu")
		(net "P5E_CPU0_P1_RX_DP<12>")
	)
	(arc
		(start 356.583234 -280.220674)
		(mid 356.826561 -279.756108)
		(end 356.583234 -279.291542)
		(width 0.1143)
		(layer "In11.Cu")
		(net "P5E_CPU0_P1_RX_DP<12>")
	)
	(arc
		(start 355.416358 -275.706078)
		(mid 355.416368 -275.702776)
		(end 355.416358 -275.699474)
		(width 0.1143)
		(layer "In11.Cu")
		(net "P5E_CPU0_P1_RX_DP<12>")
	)
	(arc
		(start 355.576632 -276.01291)
		(mid 355.57216 -276.009387)
		(end 355.567742 -276.005798)
		(width 0.1143)
		(layer "In11.Cu")
		(net "P5E_CPU0_P1_RX_DP<12>")
	)
	(arc
		(start 356.356412 -295.145968)
		(mid 356.397667 -294.974997)
		(end 356.512368 -294.841676)
		(width 0.1143)
		(layer "In11.Cu")
		(net "P5E_CPU0_P1_RX_DP<12>")
	)
	(arc
		(start 355.9048 -380.432564)
		(mid 355.931552 -380.350764)
		(end 355.940614 -380.265178)
		(width 0.14224)
		(layer "In11.Cu")
		(net "P5E_CPU0_P1_RX_DP<12>")
	)
	(arc
		(start 355.567742 -276.005798)
		(mid 355.46726 -275.868463)
		(end 355.416358 -275.706078)
		(width 0.1143)
		(layer "In11.Cu")
		(net "P5E_CPU0_P1_RX_DP<12>")
	)
	(arc
		(start 356.583234 -289.940492)
		(mid 356.826561 -289.475926)
		(end 356.583234 -289.01136)
		(width 0.1143)
		(layer "In11.Cu")
		(net "P5E_CPU0_P1_RX_DP<12>")
	)
	(arc
		(start 356.512368 -284.11043)
		(mid 356.35644 -283.806138)
		(end 356.512368 -283.501846)
		(width 0.1143)
		(layer "In11.Cu")
		(net "P5E_CPU0_P1_RX_DP<12>")
	)
	(arc
		(start 356.583234 -288.320734)
		(mid 356.762047 -288.118384)
		(end 356.826566 -287.856168)
		(width 0.1143)
		(layer "In11.Cu")
		(net "P5E_CPU0_P1_RX_DP<12>")
	)
	(arc
		(start 356.512368 -288.970212)
		(mid 356.397692 -288.836878)
		(end 356.356412 -288.66592)
		(width 0.1143)
		(layer "In11.Cu")
		(net "P5E_CPU0_P1_RX_DP<12>")
	)
	(arc
		(start 355.416358 -275.699474)
		(mid 355.351486 -275.449732)
		(end 355.186742 -275.251164)
		(width 0.1143)
		(layer "In11.Cu")
		(net "P5E_CPU0_P1_RX_DP<12>")
	)
	(arc
		(start 356.043484 -276.820884)
		(mid 355.928057 -276.687508)
		(end 355.886512 -276.516084)
		(width 0.1143)
		(layer "In11.Cu")
		(net "P5E_CPU0_P1_RX_DP<12>")
	)
	(arc
		(start 356.356412 -277.32609)
		(mid 356.291897 -277.063871)
		(end 356.11308 -276.861524)
		(width 0.1143)
		(layer "In11.Cu")
		(net "P5E_CPU0_P1_RX_DP<12>")
	)
	(arc
		(start 356.583234 -278.600662)
		(mid 356.826561 -278.136096)
		(end 356.583234 -277.67153)
		(width 0.1143)
		(layer "In11.Cu")
		(net "P5E_CPU0_P1_RX_DP<12>")
	)
	(arc
		(start 368.695224 -363.482636)
		(mid 371.863481 -359.622148)
		(end 374.217692 -355.21773)
		(width 0.14224)
		(layer "In11.Cu")
		(net "P5E_CPU0_P1_RX_DP<12>")
	)
	(arc
		(start 356.583234 -294.800528)
		(mid 356.826561 -294.335962)
		(end 356.583234 -293.871396)
		(width 0.1143)
		(layer "In11.Cu")
		(net "P5E_CPU0_P1_RX_DP<12>")
	)
	(arc
		(start 356.512368 -292.210236)
		(mid 356.35644 -291.905944)
		(end 356.512368 -291.601652)
		(width 0.1143)
		(layer "In11.Cu")
		(net "P5E_CPU0_P1_RX_DP<12>")
	)
	(arc
		(start 356.583234 -291.560504)
		(mid 356.826561 -291.095938)
		(end 356.583234 -290.631372)
		(width 0.1143)
		(layer "In11.Cu")
		(net "P5E_CPU0_P1_RX_DP<12>")
	)
	(arc
		(start 356.512368 -285.730442)
		(mid 356.35644 -285.42615)
		(end 356.512368 -285.121858)
		(width 0.1143)
		(layer "In11.Cu")
		(net "P5E_CPU0_P1_RX_DP<12>")
	)
	(arc
		(start 356.583234 -293.180516)
		(mid 356.826561 -292.71595)
		(end 356.583234 -292.251384)
		(width 0.1143)
		(layer "In11.Cu")
		(net "P5E_CPU0_P1_RX_DP<12>")
	)
	(arc
		(start 356.826566 -287.856168)
		(mid 356.76133 -287.592577)
		(end 356.580694 -287.389824)
		(width 0.1143)
		(layer "In11.Cu")
		(net "P5E_CPU0_P1_RX_DP<12>")
	)
	(arc
		(start 356.583234 -283.460698)
		(mid 356.826561 -282.996132)
		(end 356.583234 -282.531566)
		(width 0.1143)
		(layer "In11.Cu")
		(net "P5E_CPU0_P1_RX_DP<12>")
	)
	(arc
		(start 356.512368 -282.490418)
		(mid 356.35644 -282.186126)
		(end 356.512368 -281.881834)
		(width 0.1143)
		(layer "In11.Cu")
		(net "P5E_CPU0_P1_RX_DP<12>")
	)
	(arc
		(start 355.886512 -276.516084)
		(mid 355.821997 -276.253865)
		(end 355.64318 -276.051518)
		(width 0.1143)
		(layer "In11.Cu")
		(net "P5E_CPU0_P1_RX_DP<12>")
	)
	(arc
		(start 355.102414 -275.200364)
		(mid 355.005279 -275.097495)
		(end 354.953316 -274.965922)
		(width 0.1143)
		(layer "In11.Cu")
		(net "P5E_CPU0_P1_RX_DP<12>")
	)
	(arc
		(start 356.512368 -287.3502)
		(mid 356.397692 -287.216866)
		(end 356.356412 -287.045908)
		(width 0.1143)
		(layer "In11.Cu")
		(net "P5E_CPU0_P1_RX_DP<12>")
	)
	(arc
		(start 356.356412 -287.045908)
		(mid 356.397174 -286.876024)
		(end 356.51059 -286.74314)
		(width 0.1143)
		(layer "In11.Cu")
		(net "P5E_CPU0_P1_RX_DP<12>")
	)
	(arc
		(start 356.512368 -293.830248)
		(mid 356.35644 -293.525956)
		(end 356.512368 -293.221664)
		(width 0.1143)
		(layer "In11.Cu")
		(net "P5E_CPU0_P1_RX_DP<12>")
	)
	(segment
		(start 355.78796 -279.49017)
		(end 355.321108 -279.756108)
		(width 0.12954)
		(layer "F.Cu")
		(net "P5E_CPU0_P1_RX_DP<11>")
	)
	(segment
		(start 349.398082 -394.385292)
		(end 349.918782 -394.385292)
		(width 0.127)
		(layer "F.Cu")
		(net "P5E_CPU0_P1_RX_DP<11>")
	)
	(segment
		(start 355.606604 -283.482034)
		(end 355.64318 -283.460698)
		(width 0.1143)
		(layer "In11.Cu")
		(net "P5E_CPU0_P1_RX_DP<11>")
	)
	(segment
		(start 350.268032 -392.430254)
		(end 350.268032 -390.474454)
		(width 0.14224)
		(layer "In11.Cu")
		(net "P5E_CPU0_P1_RX_DP<11>")
	)
	(segment
		(start 355.606604 -285.102046)
		(end 355.64318 -285.08071)
		(width 0.1143)
		(layer "In11.Cu")
		(net "P5E_CPU0_P1_RX_DP<11>")
	)
	(segment
		(start 355.604064 -293.203376)
		(end 355.640386 -293.182548)
		(width 0.1143)
		(layer "In11.Cu")
		(net "P5E_CPU0_P1_RX_DP<11>")
	)
	(segment
		(start 355.604064 -282.508706)
		(end 355.603302 -282.508198)
		(width 0.1143)
		(layer "In11.Cu")
		(net "P5E_CPU0_P1_RX_DP<11>")
	)
	(segment
		(start 353.760786 -375.734834)
		(end 354.720906 -375.336816)
		(width 0.14224)
		(layer "In11.Cu")
		(net "P5E_CPU0_P1_RX_DP<11>")
	)
	(segment
		(start 355.63556 -293.866824)
		(end 355.610922 -293.8526)
		(width 0.1143)
		(layer "In11.Cu")
		(net "P5E_CPU0_P1_RX_DP<11>")
	)
	(segment
		(start 363.669834 -313.515248)
		(end 357.984552 -305.00701)
		(width 0.14224)
		(layer "In11.Cu")
		(net "P5E_CPU0_P1_RX_DP<11>")
	)
	(segment
		(start 355.642418 -289.010852)
		(end 355.59111 -288.981134)
		(width 0.1143)
		(layer "In11.Cu")
		(net "P5E_CPU0_P1_RX_DP<11>")
	)
	(segment
		(start 355.624892 -289.95116)
		(end 355.625146 -289.95116)
		(width 0.1143)
		(layer "In11.Cu")
		(net "P5E_CPU0_P1_RX_DP<11>")
	)
	(segment
		(start 370.678456 -322.055236)
		(end 363.669834 -313.515248)
		(width 0.14224)
		(layer "In11.Cu")
		(net "P5E_CPU0_P1_RX_DP<11>")
	)
	(segment
		(start 355.134164 -295.63314)
		(end 355.162104 -295.616884)
		(width 0.1143)
		(layer "In11.Cu")
		(net "P5E_CPU0_P1_RX_DP<11>")
	)
	(segment
		(start 349.918782 -394.385292)
		(end 350.013778 -394.031216)
		(width 0.14224)
		(layer "In11.Cu")
		(net "P5E_CPU0_P1_RX_DP<11>")
	)
	(segment
		(start 355.134164 -280.078688)
		(end 355.102414 -280.0604)
		(width 0.1143)
		(layer "In11.Cu")
		(net "P5E_CPU0_P1_RX_DP<11>")
	)
	(segment
		(start 355.60508 -283.48305)
		(end 355.606604 -283.482034)
		(width 0.1143)
		(layer "In11.Cu")
		(net "P5E_CPU0_P1_RX_DP<11>")
	)
	(segment
		(start 355.572314 -285.121858)
		(end 355.603302 -285.104078)
		(width 0.1143)
		(layer "In11.Cu")
		(net "P5E_CPU0_P1_RX_DP<11>")
	)
	(segment
		(start 355.636068 -292.247066)
		(end 355.612192 -292.23335)
		(width 0.1143)
		(layer "In11.Cu")
		(net "P5E_CPU0_P1_RX_DP<11>")
	)
	(segment
		(start 355.625146 -291.571172)
		(end 355.64318 -291.560504)
		(width 0.1143)
		(layer "In11.Cu")
		(net "P5E_CPU0_P1_RX_DP<11>")
	)
	(segment
		(start 355.60508 -285.103062)
		(end 355.606604 -285.102046)
		(width 0.1143)
		(layer "In11.Cu")
		(net "P5E_CPU0_P1_RX_DP<11>")
	)
	(segment
		(start 350.27616 -393.428982)
		(end 349.960184 -393.113006)
		(width 0.14224)
		(layer "In11.Cu")
		(net "P5E_CPU0_P1_RX_DP<11>")
	)
	(segment
		(start 355.572314 -293.221664)
		(end 355.604064 -293.203376)
		(width 0.1143)
		(layer "In11.Cu")
		(net "P5E_CPU0_P1_RX_DP<11>")
	)
	(segment
		(start 373.071136 -355.258624)
		(end 375.581926 -349.19666)
		(width 0.14224)
		(layer "In11.Cu")
		(net "P5E_CPU0_P1_RX_DP<11>")
	)
	(segment
		(start 355.642418 -287.39084)
		(end 355.642418 -287.391094)
		(width 0.1143)
		(layer "In11.Cu")
		(net "P5E_CPU0_P1_RX_DP<11>")
	)
	(segment
		(start 355.6127 -290.613592)
		(end 355.611176 -290.612576)
		(width 0.1143)
		(layer "In11.Cu")
		(net "P5E_CPU0_P1_RX_DP<11>")
	)
	(segment
		(start 355.190552 -296.345102)
		(end 354.946458 -296.101008)
		(width 0.1143)
		(layer "In11.Cu")
		(net "P5E_CPU0_P1_RX_DP<11>")
	)
	(segment
		(start 355.603556 -291.583618)
		(end 355.624892 -291.571172)
		(width 0.1143)
		(layer "In11.Cu")
		(net "P5E_CPU0_P1_RX_DP<11>")
	)
	(segment
		(start 355.236272 -296.61231)
		(end 355.236272 -296.583862)
		(width 0.1143)
		(layer "In11.Cu")
		(net "P5E_CPU0_P1_RX_DP<11>")
	)
	(segment
		(start 355.64318 -285.77159)
		(end 355.60635 -285.75)
		(width 0.1143)
		(layer "In11.Cu")
		(net "P5E_CPU0_P1_RX_DP<11>")
	)
	(segment
		(start 355.236272 -296.583862)
		(end 355.190552 -296.538142)
		(width 0.1143)
		(layer "In11.Cu")
		(net "P5E_CPU0_P1_RX_DP<11>")
	)
	(segment
		(start 355.610922 -293.8526)
		(end 355.609398 -293.851584)
		(width 0.1143)
		(layer "In11.Cu")
		(net "P5E_CPU0_P1_RX_DP<11>")
	)
	(segment
		(start 355.606604 -281.862022)
		(end 355.64318 -281.840686)
		(width 0.1143)
		(layer "In11.Cu")
		(net "P5E_CPU0_P1_RX_DP<11>")
	)
	(segment
		(start 355.625146 -289.95116)
		(end 355.64318 -289.940492)
		(width 0.1143)
		(layer "In11.Cu")
		(net "P5E_CPU0_P1_RX_DP<11>")
	)
	(segment
		(start 355.604064 -280.888694)
		(end 355.603302 -280.888186)
		(width 0.1143)
		(layer "In11.Cu")
		(net "P5E_CPU0_P1_RX_DP<11>")
	)
	(segment
		(start 355.60635 -284.129988)
		(end 355.604064 -284.128718)
		(width 0.1143)
		(layer "In11.Cu")
		(net "P5E_CPU0_P1_RX_DP<11>")
	)
	(segment
		(start 355.608636 -292.231064)
		(end 355.59619 -292.223952)
		(width 0.1143)
		(layer "In11.Cu")
		(net "P5E_CPU0_P1_RX_DP<11>")
	)
	(segment
		(start 355.60508 -281.863038)
		(end 355.606604 -281.862022)
		(width 0.1143)
		(layer "In11.Cu")
		(net "P5E_CPU0_P1_RX_DP<11>")
	)
	(segment
		(start 355.642418 -290.630864)
		(end 355.6127 -290.613592)
		(width 0.1143)
		(layer "In11.Cu")
		(net "P5E_CPU0_P1_RX_DP<11>")
	)
	(segment
		(start 355.606604 -294.821864)
		(end 355.64318 -294.800528)
		(width 0.1143)
		(layer "In11.Cu")
		(net "P5E_CPU0_P1_RX_DP<11>")
	)
	(segment
		(start 355.603302 -293.848028)
		(end 355.572314 -293.830248)
		(width 0.1143)
		(layer "In11.Cu")
		(net "P5E_CPU0_P1_RX_DP<11>")
	)
	(segment
		(start 355.59111 -288.981134)
		(end 355.590602 -288.98088)
		(width 0.1143)
		(layer "In11.Cu")
		(net "P5E_CPU0_P1_RX_DP<11>")
	)
	(segment
		(start 352.538792 -377.963938)
		(end 352.538792 -377.051824)
		(width 0.14224)
		(layer "In11.Cu")
		(net "P5E_CPU0_P1_RX_DP<11>")
	)
	(segment
		(start 355.636322 -293.867332)
		(end 355.63556 -293.866824)
		(width 0.1143)
		(layer "In11.Cu")
		(net "P5E_CPU0_P1_RX_DP<11>")
	)
	(segment
		(start 355.612192 -292.23335)
		(end 355.609398 -292.231572)
		(width 0.1143)
		(layer "In11.Cu")
		(net "P5E_CPU0_P1_RX_DP<11>")
	)
	(segment
		(start 354.946458 -296.101008)
		(end 354.946458 -295.946322)
		(width 0.1143)
		(layer "In11.Cu")
		(net "P5E_CPU0_P1_RX_DP<11>")
	)
	(segment
		(start 355.603302 -285.748222)
		(end 355.572314 -285.730442)
		(width 0.1143)
		(layer "In11.Cu")
		(net "P5E_CPU0_P1_RX_DP<11>")
	)
	(segment
		(start 355.604064 -284.128718)
		(end 355.603302 -284.12821)
		(width 0.1143)
		(layer "In11.Cu")
		(net "P5E_CPU0_P1_RX_DP<11>")
	)
	(segment
		(start 355.603556 -289.963606)
		(end 355.624892 -289.95116)
		(width 0.1143)
		(layer "In11.Cu")
		(net "P5E_CPU0_P1_RX_DP<11>")
	)
	(segment
		(start 355.603302 -285.104078)
		(end 355.604064 -285.10357)
		(width 0.1143)
		(layer "In11.Cu")
		(net "P5E_CPU0_P1_RX_DP<11>")
	)
	(segment
		(start 354.238814 -380.800102)
		(end 354.238814 -379.786134)
		(width 0.14224)
		(layer "In11.Cu")
		(net "P5E_CPU0_P1_RX_DP<11>")
	)
	(segment
		(start 353.837748 -378.696982)
		(end 353.503738 -378.558806)
		(width 0.14224)
		(layer "In11.Cu")
		(net "P5E_CPU0_P1_RX_DP<11>")
	)
	(segment
		(start 355.642418 -287.391094)
		(end 355.628956 -287.38322)
		(width 0.1143)
		(layer "In11.Cu")
		(net "P5E_CPU0_P1_RX_DP<11>")
	)
	(segment
		(start 355.162104 -295.616884)
		(end 355.170486 -295.612312)
		(width 0.1143)
		(layer "In11.Cu")
		(net "P5E_CPU0_P1_RX_DP<11>")
	)
	(segment
		(start 350.188022 -393.930632)
		(end 350.27616 -393.842494)
		(width 0.14224)
		(layer "In11.Cu")
		(net "P5E_CPU0_P1_RX_DP<11>")
	)
	(segment
		(start 350.013778 -394.031216)
		(end 350.188022 -393.930632)
		(width 0.14224)
		(layer "In11.Cu")
		(net "P5E_CPU0_P1_RX_DP<11>")
	)
	(segment
		(start 355.640386 -293.182548)
		(end 355.64318 -293.180516)
		(width 0.1143)
		(layer "In11.Cu")
		(net "P5E_CPU0_P1_RX_DP<11>")
	)
	(segment
		(start 355.60635 -285.75)
		(end 355.604064 -285.74873)
		(width 0.1143)
		(layer "In11.Cu")
		(net "P5E_CPU0_P1_RX_DP<11>")
	)
	(segment
		(start 373.412258 -327.285858)
		(end 370.691918 -322.081144)
		(width 0.14224)
		(layer "In11.Cu")
		(net "P5E_CPU0_P1_RX_DP<11>")
	)
	(segment
		(start 355.236272 -298.371768)
		(end 355.236272 -296.61231)
		(width 0.14224)
		(layer "In11.Cu")
		(net "P5E_CPU0_P1_RX_DP<11>")
	)
	(segment
		(start 355.608382 -293.851076)
		(end 355.606858 -293.85006)
		(width 0.1143)
		(layer "In11.Cu")
		(net "P5E_CPU0_P1_RX_DP<11>")
	)
	(segment
		(start 355.64318 -280.911554)
		(end 355.60635 -280.889964)
		(width 0.1143)
		(layer "In11.Cu")
		(net "P5E_CPU0_P1_RX_DP<11>")
	)
	(segment
		(start 355.642418 -292.250876)
		(end 355.636068 -292.247066)
		(width 0.1143)
		(layer "In11.Cu")
		(net "P5E_CPU0_P1_RX_DP<11>")
	)
	(segment
		(start 355.604064 -285.10357)
		(end 355.60508 -285.103062)
		(width 0.1143)
		(layer "In11.Cu")
		(net "P5E_CPU0_P1_RX_DP<11>")
	)
	(segment
		(start 370.691918 -322.08089)
		(end 370.678456 -322.055236)
		(width 0.14224)
		(layer "In11.Cu")
		(net "P5E_CPU0_P1_RX_DP<11>")
	)
	(segment
		(start 355.64318 -284.151578)
		(end 355.60635 -284.129988)
		(width 0.1143)
		(layer "In11.Cu")
		(net "P5E_CPU0_P1_RX_DP<11>")
	)
	(segment
		(start 375.581926 -339.362542)
		(end 373.412258 -327.285858)
		(width 0.14224)
		(layer "In11.Cu")
		(net "P5E_CPU0_P1_RX_DP<11>")
	)
	(segment
		(start 355.604064 -283.483558)
		(end 355.60508 -283.48305)
		(width 0.1143)
		(layer "In11.Cu")
		(net "P5E_CPU0_P1_RX_DP<11>")
	)
	(segment
		(start 355.64318 -282.531566)
		(end 355.60635 -282.509976)
		(width 0.1143)
		(layer "In11.Cu")
		(net "P5E_CPU0_P1_RX_DP<11>")
	)
	(segment
		(start 355.611176 -290.612576)
		(end 355.59619 -290.60394)
		(width 0.1143)
		(layer "In11.Cu")
		(net "P5E_CPU0_P1_RX_DP<11>")
	)
	(segment
		(start 355.64318 -293.871396)
		(end 355.636322 -293.867332)
		(width 0.1143)
		(layer "In11.Cu")
		(net "P5E_CPU0_P1_RX_DP<11>")
	)
	(segment
		(start 355.102414 -295.651682)
		(end 355.134164 -295.633394)
		(width 0.1143)
		(layer "In11.Cu")
		(net "P5E_CPU0_P1_RX_DP<11>")
	)
	(segment
		(start 355.572314 -281.881834)
		(end 355.603302 -281.864054)
		(width 0.1143)
		(layer "In11.Cu")
		(net "P5E_CPU0_P1_RX_DP<11>")
	)
	(segment
		(start 356.957884 -373.841264)
		(end 368.09807 -362.701078)
		(width 0.14224)
		(layer "In11.Cu")
		(net "P5E_CPU0_P1_RX_DP<11>")
	)
	(segment
		(start 355.603302 -283.484066)
		(end 355.604064 -283.483558)
		(width 0.1143)
		(layer "In11.Cu")
		(net "P5E_CPU0_P1_RX_DP<11>")
	)
	(segment
		(start 354.953316 -279.825958)
		(end 355.023166 -279.756108)
		(width 0.1143)
		(layer "In11.Cu")
		(net "P5E_CPU0_P1_RX_DP<11>")
	)
	(segment
		(start 355.603302 -282.508198)
		(end 355.572314 -282.490418)
		(width 0.1143)
		(layer "In11.Cu")
		(net "P5E_CPU0_P1_RX_DP<11>")
	)
	(segment
		(start 357.984552 -305.00701)
		(end 355.236272 -298.371768)
		(width 0.14224)
		(layer "In11.Cu")
		(net "P5E_CPU0_P1_RX_DP<11>")
	)
	(segment
		(start 355.60635 -280.889964)
		(end 355.604064 -280.888694)
		(width 0.1143)
		(layer "In11.Cu")
		(net "P5E_CPU0_P1_RX_DP<11>")
	)
	(segment
		(start 355.609398 -293.851584)
		(end 355.608382 -293.851076)
		(width 0.1143)
		(layer "In11.Cu")
		(net "P5E_CPU0_P1_RX_DP<11>")
	)
	(segment
		(start 355.190552 -296.538142)
		(end 355.190552 -296.345102)
		(width 0.1143)
		(layer "In11.Cu")
		(net "P5E_CPU0_P1_RX_DP<11>")
	)
	(segment
		(start 355.604064 -285.74873)
		(end 355.603302 -285.748222)
		(width 0.1143)
		(layer "In11.Cu")
		(net "P5E_CPU0_P1_RX_DP<11>")
	)
	(segment
		(start 355.603302 -281.864054)
		(end 355.604064 -281.863546)
		(width 0.1143)
		(layer "In11.Cu")
		(net "P5E_CPU0_P1_RX_DP<11>")
	)
	(segment
		(start 350.365568 -390.03097)
		(end 353.885246 -382.408938)
		(width 0.14224)
		(layer "In11.Cu")
		(net "P5E_CPU0_P1_RX_DP<11>")
	)
	(segment
		(start 355.170486 -280.09977)
		(end 355.134164 -280.078688)
		(width 0.1143)
		(layer "In11.Cu")
		(net "P5E_CPU0_P1_RX_DP<11>")
	)
	(segment
		(start 355.604064 -293.848536)
		(end 355.603302 -293.848028)
		(width 0.1143)
		(layer "In11.Cu")
		(net "P5E_CPU0_P1_RX_DP<11>")
	)
	(segment
		(start 375.581926 -349.19666)
		(end 375.581926 -339.362542)
		(width 0.14224)
		(layer "In11.Cu")
		(net "P5E_CPU0_P1_RX_DP<11>")
	)
	(segment
		(start 355.60508 -293.849044)
		(end 355.604064 -293.848536)
		(width 0.1143)
		(layer "In11.Cu")
		(net "P5E_CPU0_P1_RX_DP<11>")
	)
	(segment
		(start 355.590856 -288.35096)
		(end 355.59111 -288.350706)
		(width 0.1143)
		(layer "In11.Cu")
		(net "P5E_CPU0_P1_RX_DP<11>")
	)
	(segment
		(start 355.604064 -294.823388)
		(end 355.60508 -294.82288)
		(width 0.1143)
		(layer "In11.Cu")
		(net "P5E_CPU0_P1_RX_DP<11>")
	)
	(segment
		(start 355.09454 -295.65727)
		(end 355.101144 -295.652698)
		(width 0.1143)
		(layer "In11.Cu")
		(net "P5E_CPU0_P1_RX_DP<11>")
	)
	(segment
		(start 355.572314 -282.490418)
		(end 355.552502 -282.476194)
		(width 0.1143)
		(layer "In11.Cu")
		(net "P5E_CPU0_P1_RX_DP<11>")
	)
	(segment
		(start 355.101144 -295.652698)
		(end 355.102414 -295.651682)
		(width 0.1143)
		(layer "In11.Cu")
		(net "P5E_CPU0_P1_RX_DP<11>")
	)
	(segment
		(start 355.570536 -286.74314)
		(end 355.604064 -286.723582)
		(width 0.1143)
		(layer "In11.Cu")
		(net "P5E_CPU0_P1_RX_DP<11>")
	)
	(segment
		(start 355.552502 -281.896058)
		(end 355.572314 -281.881834)
		(width 0.1143)
		(layer "In11.Cu")
		(net "P5E_CPU0_P1_RX_DP<11>")
	)
	(segment
		(start 355.606858 -293.85006)
		(end 355.60508 -293.849044)
		(width 0.1143)
		(layer "In11.Cu")
		(net "P5E_CPU0_P1_RX_DP<11>")
	)
	(segment
		(start 355.603302 -284.12821)
		(end 355.572314 -284.11043)
		(width 0.1143)
		(layer "In11.Cu")
		(net "P5E_CPU0_P1_RX_DP<11>")
	)
	(segment
		(start 349.960184 -393.113006)
		(end 349.963232 -392.7348)
		(width 0.14224)
		(layer "In11.Cu")
		(net "P5E_CPU0_P1_RX_DP<11>")
	)
	(segment
		(start 355.572314 -283.501846)
		(end 355.603302 -283.484066)
		(width 0.1143)
		(layer "In11.Cu")
		(net "P5E_CPU0_P1_RX_DP<11>")
	)
	(segment
		(start 355.603302 -294.823896)
		(end 355.604064 -294.823388)
		(width 0.1143)
		(layer "In11.Cu")
		(net "P5E_CPU0_P1_RX_DP<11>")
	)
	(segment
		(start 355.609398 -292.231572)
		(end 355.608636 -292.231064)
		(width 0.1143)
		(layer "In11.Cu")
		(net "P5E_CPU0_P1_RX_DP<11>")
	)
	(segment
		(start 349.963232 -392.7348)
		(end 350.268032 -392.430254)
		(width 0.14224)
		(layer "In11.Cu")
		(net "P5E_CPU0_P1_RX_DP<11>")
	)
	(segment
		(start 355.637592 -288.323528)
		(end 355.64318 -288.320734)
		(width 0.1143)
		(layer "In11.Cu")
		(net "P5E_CPU0_P1_RX_DP<11>")
	)
	(segment
		(start 355.60635 -282.509976)
		(end 355.604064 -282.508706)
		(width 0.1143)
		(layer "In11.Cu")
		(net "P5E_CPU0_P1_RX_DP<11>")
	)
	(segment
		(start 355.60508 -294.82288)
		(end 355.606604 -294.821864)
		(width 0.1143)
		(layer "In11.Cu")
		(net "P5E_CPU0_P1_RX_DP<11>")
	)
	(segment
		(start 355.624892 -291.571172)
		(end 355.625146 -291.571172)
		(width 0.1143)
		(layer "In11.Cu")
		(net "P5E_CPU0_P1_RX_DP<11>")
	)
	(segment
		(start 355.604064 -281.863546)
		(end 355.60508 -281.863038)
		(width 0.1143)
		(layer "In11.Cu")
		(net "P5E_CPU0_P1_RX_DP<11>")
	)
	(segment
		(start 355.023166 -279.756108)
		(end 355.321108 -279.756108)
		(width 0.1143)
		(layer "In11.Cu")
		(net "P5E_CPU0_P1_RX_DP<11>")
	)
	(segment
		(start 355.604572 -288.343086)
		(end 355.637592 -288.323528)
		(width 0.1143)
		(layer "In11.Cu")
		(net "P5E_CPU0_P1_RX_DP<11>")
	)
	(segment
		(start 355.59111 -288.350706)
		(end 355.604572 -288.343086)
		(width 0.1143)
		(layer "In11.Cu")
		(net "P5E_CPU0_P1_RX_DP<11>")
	)
	(segment
		(start 350.27616 -393.842494)
		(end 350.27616 -393.428982)
		(width 0.14224)
		(layer "In11.Cu")
		(net "P5E_CPU0_P1_RX_DP<11>")
	)
	(segment
		(start 355.134164 -295.633394)
		(end 355.134164 -295.63314)
		(width 0.1143)
		(layer "In11.Cu")
		(net "P5E_CPU0_P1_RX_DP<11>")
	)
	(segment
		(start 370.691918 -322.081144)
		(end 370.691918 -322.08089)
		(width 0.14224)
		(layer "In11.Cu")
		(net "P5E_CPU0_P1_RX_DP<11>")
	)
	(segment
		(start 355.604064 -286.723582)
		(end 355.64318 -286.700722)
		(width 0.1143)
		(layer "In11.Cu")
		(net "P5E_CPU0_P1_RX_DP<11>")
	)
	(arc
		(start 355.64318 -285.08071)
		(mid 355.886507 -284.616144)
		(end 355.64318 -284.151578)
		(width 0.1143)
		(layer "In11.Cu")
		(net "P5E_CPU0_P1_RX_DP<11>")
	)
	(arc
		(start 355.64318 -288.320734)
		(mid 355.886397 -287.855638)
		(end 355.642418 -287.39084)
		(width 0.1143)
		(layer "In11.Cu")
		(net "P5E_CPU0_P1_RX_DP<11>")
	)
	(arc
		(start 355.102414 -280.0604)
		(mid 355.005279 -279.957531)
		(end 354.953316 -279.825958)
		(width 0.1143)
		(layer "In11.Cu")
		(net "P5E_CPU0_P1_RX_DP<11>")
	)
	(arc
		(start 354.077524 -378.926344)
		(mid 353.979221 -378.789097)
		(end 353.837748 -378.696982)
		(width 0.14224)
		(layer "In11.Cu")
		(net "P5E_CPU0_P1_RX_DP<11>")
	)
	(arc
		(start 355.572314 -285.730442)
		(mid 355.421929 -285.42615)
		(end 355.572314 -285.121858)
		(width 0.1143)
		(layer "In11.Cu")
		(net "P5E_CPU0_P1_RX_DP<11>")
	)
	(arc
		(start 354.170996 -379.33503)
		(mid 354.145725 -379.125776)
		(end 354.077524 -378.926344)
		(width 0.14224)
		(layer "In11.Cu")
		(net "P5E_CPU0_P1_RX_DP<11>")
	)
	(arc
		(start 354.720906 -375.336816)
		(mid 355.912969 -374.699088)
		(end 356.957884 -373.841264)
		(width 0.14224)
		(layer "In11.Cu")
		(net "P5E_CPU0_P1_RX_DP<11>")
	)
	(arc
		(start 355.64318 -289.01136)
		(mid 355.642799 -289.011106)
		(end 355.642418 -289.010852)
		(width 0.1143)
		(layer "In11.Cu")
		(net "P5E_CPU0_P1_RX_DP<11>")
	)
	(arc
		(start 352.575368 -378.085096)
		(mid 352.548139 -378.02722)
		(end 352.538792 -377.963938)
		(width 0.14224)
		(layer "In11.Cu")
		(net "P5E_CPU0_P1_RX_DP<11>")
	)
	(arc
		(start 352.538792 -377.051824)
		(mid 352.542608 -376.988497)
		(end 352.554032 -376.926094)
		(width 0.14224)
		(layer "In11.Cu")
		(net "P5E_CPU0_P1_RX_DP<11>")
	)
	(arc
		(start 355.64318 -293.180516)
		(mid 355.886507 -292.71595)
		(end 355.64318 -292.251384)
		(width 0.1143)
		(layer "In11.Cu")
		(net "P5E_CPU0_P1_RX_DP<11>")
	)
	(arc
		(start 355.59619 -290.60394)
		(mid 355.417973 -290.281663)
		(end 355.603556 -289.963606)
		(width 0.1143)
		(layer "In11.Cu")
		(net "P5E_CPU0_P1_RX_DP<11>")
	)
	(arc
		(start 368.09807 -362.701078)
		(mid 370.951105 -359.22475)
		(end 373.071136 -355.258624)
		(width 0.14224)
		(layer "In11.Cu")
		(net "P5E_CPU0_P1_RX_DP<11>")
	)
	(arc
		(start 352.755708 -376.438922)
		(mid 352.792129 -376.387069)
		(end 352.834956 -376.34037)
		(width 0.14224)
		(layer "In11.Cu")
		(net "P5E_CPU0_P1_RX_DP<11>")
	)
	(arc
		(start 352.809048 -378.340874)
		(mid 352.757993 -378.303275)
		(end 352.712274 -378.25934)
		(width 0.14224)
		(layer "In11.Cu")
		(net "P5E_CPU0_P1_RX_DP<11>")
	)
	(arc
		(start 353.301808 -378.513848)
		(mid 353.238526 -378.508078)
		(end 353.176078 -378.496322)
		(width 0.14224)
		(layer "In11.Cu")
		(net "P5E_CPU0_P1_RX_DP<11>")
	)
	(arc
		(start 352.712274 -378.25934)
		(mid 352.640439 -378.174875)
		(end 352.575368 -378.085096)
		(width 0.14224)
		(layer "In11.Cu")
		(net "P5E_CPU0_P1_RX_DP<11>")
	)
	(arc
		(start 355.64318 -281.840686)
		(mid 355.886507 -281.37612)
		(end 355.64318 -280.911554)
		(width 0.1143)
		(layer "In11.Cu")
		(net "P5E_CPU0_P1_RX_DP<11>")
	)
	(arc
		(start 354.238814 -379.786134)
		(mid 354.227233 -379.628875)
		(end 354.19284 -379.474984)
		(width 0.14224)
		(layer "In11.Cu")
		(net "P5E_CPU0_P1_RX_DP<11>")
	)
	(arc
		(start 355.590602 -288.98088)
		(mid 355.409404 -288.66581)
		(end 355.590856 -288.35096)
		(width 0.1143)
		(layer "In11.Cu")
		(net "P5E_CPU0_P1_RX_DP<11>")
	)
	(arc
		(start 355.552502 -282.476194)
		(mid 355.403788 -282.186126)
		(end 355.552502 -281.896058)
		(width 0.1143)
		(layer "In11.Cu")
		(net "P5E_CPU0_P1_RX_DP<11>")
	)
	(arc
		(start 353.176078 -378.496322)
		(mid 352.986144 -378.433755)
		(end 352.809048 -378.340874)
		(width 0.14224)
		(layer "In11.Cu")
		(net "P5E_CPU0_P1_RX_DP<11>")
	)
	(arc
		(start 355.572314 -284.11043)
		(mid 355.420725 -283.806138)
		(end 355.572314 -283.501846)
		(width 0.1143)
		(layer "In11.Cu")
		(net "P5E_CPU0_P1_RX_DP<11>")
	)
	(arc
		(start 355.64318 -283.460698)
		(mid 355.886507 -282.996132)
		(end 355.64318 -282.531566)
		(width 0.1143)
		(layer "In11.Cu")
		(net "P5E_CPU0_P1_RX_DP<11>")
	)
	(arc
		(start 355.520752 -287.29051)
		(mid 355.453462 -287.179213)
		(end 355.418136 -287.054036)
		(width 0.1143)
		(layer "In11.Cu")
		(net "P5E_CPU0_P1_RX_DP<11>")
	)
	(arc
		(start 355.64318 -286.700722)
		(mid 355.886507 -286.236156)
		(end 355.64318 -285.77159)
		(width 0.1143)
		(layer "In11.Cu")
		(net "P5E_CPU0_P1_RX_DP<11>")
	)
	(arc
		(start 353.885246 -382.408938)
		(mid 354.149376 -381.623716)
		(end 354.238814 -380.800102)
		(width 0.14224)
		(layer "In11.Cu")
		(net "P5E_CPU0_P1_RX_DP<11>")
	)
	(arc
		(start 355.64318 -294.800528)
		(mid 355.886507 -294.335962)
		(end 355.64318 -293.871396)
		(width 0.1143)
		(layer "In11.Cu")
		(net "P5E_CPU0_P1_RX_DP<11>")
	)
	(arc
		(start 355.603302 -280.888186)
		(mid 355.469949 -280.744458)
		(end 355.416104 -280.555954)
		(width 0.1143)
		(layer "In11.Cu")
		(net "P5E_CPU0_P1_RX_DP<11>")
	)
	(arc
		(start 354.946458 -295.946322)
		(mid 354.985636 -295.783938)
		(end 355.09454 -295.65727)
		(width 0.1143)
		(layer "In11.Cu")
		(net "P5E_CPU0_P1_RX_DP<11>")
	)
	(arc
		(start 355.64318 -289.940492)
		(mid 355.886507 -289.475926)
		(end 355.64318 -289.01136)
		(width 0.1143)
		(layer "In11.Cu")
		(net "P5E_CPU0_P1_RX_DP<11>")
	)
	(arc
		(start 355.170486 -295.612312)
		(mid 355.345485 -295.412313)
		(end 355.416104 -295.156128)
		(width 0.1143)
		(layer "In11.Cu")
		(net "P5E_CPU0_P1_RX_DP<11>")
	)
	(arc
		(start 355.416104 -295.156128)
		(mid 355.469936 -294.967589)
		(end 355.603302 -294.823896)
		(width 0.1143)
		(layer "In11.Cu")
		(net "P5E_CPU0_P1_RX_DP<11>")
	)
	(arc
		(start 355.59619 -292.223952)
		(mid 355.417973 -291.901675)
		(end 355.603556 -291.583618)
		(width 0.1143)
		(layer "In11.Cu")
		(net "P5E_CPU0_P1_RX_DP<11>")
	)
	(arc
		(start 352.834956 -376.34037)
		(mid 353.269575 -375.99434)
		(end 353.760786 -375.734834)
		(width 0.14224)
		(layer "In11.Cu")
		(net "P5E_CPU0_P1_RX_DP<11>")
	)
	(arc
		(start 350.268032 -390.474454)
		(mid 350.292736 -390.247421)
		(end 350.365568 -390.03097)
		(width 0.14224)
		(layer "In11.Cu")
		(net "P5E_CPU0_P1_RX_DP<11>")
	)
	(arc
		(start 355.418136 -287.054036)
		(mid 355.416921 -287.03971)
		(end 355.41712 -287.025334)
		(width 0.1143)
		(layer "In11.Cu")
		(net "P5E_CPU0_P1_RX_DP<11>")
	)
	(arc
		(start 355.41712 -287.025334)
		(mid 355.462006 -286.866936)
		(end 355.570536 -286.74314)
		(width 0.1143)
		(layer "In11.Cu")
		(net "P5E_CPU0_P1_RX_DP<11>")
	)
	(arc
		(start 355.64318 -292.251384)
		(mid 355.642799 -292.25113)
		(end 355.642418 -292.250876)
		(width 0.1143)
		(layer "In11.Cu")
		(net "P5E_CPU0_P1_RX_DP<11>")
	)
	(arc
		(start 355.416104 -280.555954)
		(mid 355.345438 -280.299794)
		(end 355.170486 -280.09977)
		(width 0.1143)
		(layer "In11.Cu")
		(net "P5E_CPU0_P1_RX_DP<11>")
	)
	(arc
		(start 354.19284 -379.474984)
		(mid 354.177068 -379.405764)
		(end 354.170996 -379.33503)
		(width 0.14224)
		(layer "In11.Cu")
		(net "P5E_CPU0_P1_RX_DP<11>")
	)
	(arc
		(start 355.628956 -287.38322)
		(mid 355.570576 -287.341857)
		(end 355.520752 -287.29051)
		(width 0.1143)
		(layer "In11.Cu")
		(net "P5E_CPU0_P1_RX_DP<11>")
	)
	(arc
		(start 355.572314 -293.830248)
		(mid 355.420725 -293.525956)
		(end 355.572314 -293.221664)
		(width 0.1143)
		(layer "In11.Cu")
		(net "P5E_CPU0_P1_RX_DP<11>")
	)
	(arc
		(start 355.64318 -291.560504)
		(mid 355.886507 -291.095938)
		(end 355.64318 -290.631372)
		(width 0.1143)
		(layer "In11.Cu")
		(net "P5E_CPU0_P1_RX_DP<11>")
	)
	(arc
		(start 355.64318 -290.631372)
		(mid 355.642799 -290.631118)
		(end 355.642418 -290.630864)
		(width 0.1143)
		(layer "In11.Cu")
		(net "P5E_CPU0_P1_RX_DP<11>")
	)
	(arc
		(start 353.503738 -378.558806)
		(mid 353.404706 -378.527648)
		(end 353.301808 -378.513848)
		(width 0.14224)
		(layer "In11.Cu")
		(net "P5E_CPU0_P1_RX_DP<11>")
	)
	(arc
		(start 352.554032 -376.926094)
		(mid 352.636195 -376.674776)
		(end 352.755708 -376.438922)
		(width 0.14224)
		(layer "In11.Cu")
		(net "P5E_CPU0_P1_RX_DP<11>")
	)
	(segment
		(start 348.198186 -394.385292)
		(end 348.718886 -394.385292)
		(width 0.127)
		(layer "F.Cu")
		(net "P5E_CPU0_P1_RX_DP<10>")
	)
	(segment
		(start 355.78796 -277.870158)
		(end 355.321108 -278.136096)
		(width 0.12954)
		(layer "F.Cu")
		(net "P5E_CPU0_P1_RX_DP<10>")
	)
	(segment
		(start 354.19665 -280.080212)
		(end 354.195126 -280.079196)
		(width 0.1143)
		(layer "In11.Cu")
		(net "P5E_CPU0_P1_RX_DP<10>")
	)
	(segment
		(start 357.158544 -305.449478)
		(end 354.138992 -298.159932)
		(width 0.14224)
		(layer "In11.Cu")
		(net "P5E_CPU0_P1_RX_DP<10>")
	)
	(segment
		(start 372.264178 -327.10247)
		(end 369.895882 -322.571364)
		(width 0.14224)
		(layer "In11.Cu")
		(net "P5E_CPU0_P1_RX_DP<10>")
	)
	(segment
		(start 349.068136 -392.43)
		(end 349.068136 -381.966216)
		(width 0.14224)
		(layer "In11.Cu")
		(net "P5E_CPU0_P1_RX_DP<10>")
	)
	(segment
		(start 354.198682 -279.430734)
		(end 354.233226 -279.410668)
		(width 0.1143)
		(layer "In11.Cu")
		(net "P5E_CPU0_P1_RX_DP<10>")
	)
	(segment
		(start 348.813882 -394.031216)
		(end 348.988126 -393.930632)
		(width 0.14224)
		(layer "In11.Cu")
		(net "P5E_CPU0_P1_RX_DP<10>")
	)
	(segment
		(start 354.639372 -294.837612)
		(end 354.701602 -294.801544)
		(width 0.1143)
		(layer "In11.Cu")
		(net "P5E_CPU0_P1_RX_DP<10>")
	)
	(segment
		(start 348.718886 -394.385292)
		(end 348.813882 -394.031216)
		(width 0.14224)
		(layer "In11.Cu")
		(net "P5E_CPU0_P1_RX_DP<10>")
	)
	(segment
		(start 354.703126 -285.77159)
		(end 354.63353 -285.73095)
		(width 0.1143)
		(layer "In11.Cu")
		(net "P5E_CPU0_P1_RX_DP<10>")
	)
	(segment
		(start 357.777034 -371.672104)
		(end 367.470944 -361.978194)
		(width 0.14224)
		(layer "In11.Cu")
		(net "P5E_CPU0_P1_RX_DP<10>")
	)
	(segment
		(start 349.076264 -393.428982)
		(end 348.760288 -393.113006)
		(width 0.14224)
		(layer "In11.Cu")
		(net "P5E_CPU0_P1_RX_DP<10>")
	)
	(segment
		(start 354.193348 -280.07818)
		(end 354.190554 -280.076656)
		(width 0.1143)
		(layer "In11.Cu")
		(net "P5E_CPU0_P1_RX_DP<10>")
	)
	(segment
		(start 354.138992 -298.159932)
		(end 354.138992 -296.286682)
		(width 0.14224)
		(layer "In11.Cu")
		(net "P5E_CPU0_P1_RX_DP<10>")
	)
	(segment
		(start 354.093272 -295.79697)
		(end 354.476304 -295.413938)
		(width 0.1143)
		(layer "In11.Cu")
		(net "P5E_CPU0_P1_RX_DP<10>")
	)
	(segment
		(start 354.66401 -286.723582)
		(end 354.703126 -286.700722)
		(width 0.1143)
		(layer "In11.Cu")
		(net "P5E_CPU0_P1_RX_DP<10>")
	)
	(segment
		(start 354.19411 -280.078688)
		(end 354.193348 -280.07818)
		(width 0.1143)
		(layer "In11.Cu")
		(net "P5E_CPU0_P1_RX_DP<10>")
	)
	(segment
		(start 371.73281 -355.599746)
		(end 374.484646 -348.956122)
		(width 0.14224)
		(layer "In11.Cu")
		(net "P5E_CPU0_P1_RX_DP<10>")
	)
	(segment
		(start 354.196396 -279.432258)
		(end 354.198682 -279.430734)
		(width 0.1143)
		(layer "In11.Cu")
		(net "P5E_CPU0_P1_RX_DP<10>")
	)
	(segment
		(start 354.631498 -286.742378)
		(end 354.66401 -286.723582)
		(width 0.1143)
		(layer "In11.Cu")
		(net "P5E_CPU0_P1_RX_DP<10>")
	)
	(segment
		(start 369.895882 -322.571364)
		(end 362.92028 -314.07227)
		(width 0.14224)
		(layer "In11.Cu")
		(net "P5E_CPU0_P1_RX_DP<10>")
	)
	(segment
		(start 354.195126 -280.079196)
		(end 354.19411 -280.078688)
		(width 0.1143)
		(layer "In11.Cu")
		(net "P5E_CPU0_P1_RX_DP<10>")
	)
	(segment
		(start 354.189792 -280.076148)
		(end 354.188268 -280.075386)
		(width 0.1143)
		(layer "In11.Cu")
		(net "P5E_CPU0_P1_RX_DP<10>")
	)
	(segment
		(start 349.105474 -381.876046)
		(end 350.715326 -380.266194)
		(width 0.14224)
		(layer "In11.Cu")
		(net "P5E_CPU0_P1_RX_DP<10>")
	)
	(segment
		(start 362.92028 -314.07227)
		(end 357.158544 -305.449478)
		(width 0.14224)
		(layer "In11.Cu")
		(net "P5E_CPU0_P1_RX_DP<10>")
	)
	(segment
		(start 354.16236 -279.451816)
		(end 354.192078 -279.434798)
		(width 0.1143)
		(layer "In11.Cu")
		(net "P5E_CPU0_P1_RX_DP<10>")
	)
	(segment
		(start 351.784158 -375.433336)
		(end 351.999042 -375.316496)
		(width 0.14224)
		(layer "In11.Cu")
		(net "P5E_CPU0_P1_RX_DP<10>")
	)
	(segment
		(start 348.760288 -393.113006)
		(end 348.763336 -392.7348)
		(width 0.14224)
		(layer "In11.Cu")
		(net "P5E_CPU0_P1_RX_DP<10>")
	)
	(segment
		(start 354.63353 -293.221156)
		(end 354.703126 -293.180516)
		(width 0.1143)
		(layer "In11.Cu")
		(net "P5E_CPU0_P1_RX_DP<10>")
	)
	(segment
		(start 349.076264 -393.842494)
		(end 349.076264 -393.428982)
		(width 0.14224)
		(layer "In11.Cu")
		(net "P5E_CPU0_P1_RX_DP<10>")
	)
	(segment
		(start 354.63353 -285.12135)
		(end 354.703126 -285.08071)
		(width 0.1143)
		(layer "In11.Cu")
		(net "P5E_CPU0_P1_RX_DP<10>")
	)
	(segment
		(start 354.193348 -279.434036)
		(end 354.19411 -279.433528)
		(width 0.1143)
		(layer "In11.Cu")
		(net "P5E_CPU0_P1_RX_DP<10>")
	)
	(segment
		(start 354.192078 -279.434798)
		(end 354.193348 -279.434036)
		(width 0.1143)
		(layer "In11.Cu")
		(net "P5E_CPU0_P1_RX_DP<10>")
	)
	(segment
		(start 354.138992 -296.258234)
		(end 354.093272 -296.212514)
		(width 0.1143)
		(layer "In11.Cu")
		(net "P5E_CPU0_P1_RX_DP<10>")
	)
	(segment
		(start 354.63353 -278.641302)
		(end 354.703126 -278.600662)
		(width 0.1143)
		(layer "In11.Cu")
		(net "P5E_CPU0_P1_RX_DP<10>")
	)
	(segment
		(start 352.113088 -375.26214)
		(end 352.880676 -374.943878)
		(width 0.14224)
		(layer "In11.Cu")
		(net "P5E_CPU0_P1_RX_DP<10>")
	)
	(segment
		(start 354.63353 -281.881326)
		(end 354.703126 -281.840686)
		(width 0.1143)
		(layer "In11.Cu")
		(net "P5E_CPU0_P1_RX_DP<10>")
	)
	(segment
		(start 374.484646 -339.460332)
		(end 372.264178 -327.10247)
		(width 0.14224)
		(layer "In11.Cu")
		(net "P5E_CPU0_P1_RX_DP<10>")
	)
	(segment
		(start 354.703126 -290.631372)
		(end 354.63353 -290.590732)
		(width 0.1143)
		(layer "In11.Cu")
		(net "P5E_CPU0_P1_RX_DP<10>")
	)
	(segment
		(start 354.700586 -287.389824)
		(end 354.63353 -287.350708)
		(width 0.1143)
		(layer "In11.Cu")
		(net "P5E_CPU0_P1_RX_DP<10>")
	)
	(segment
		(start 354.703126 -282.531566)
		(end 354.63353 -282.490926)
		(width 0.1143)
		(layer "In11.Cu")
		(net "P5E_CPU0_P1_RX_DP<10>")
	)
	(segment
		(start 354.63353 -291.601144)
		(end 354.703126 -291.560504)
		(width 0.1143)
		(layer "In11.Cu")
		(net "P5E_CPU0_P1_RX_DP<10>")
	)
	(segment
		(start 348.763336 -392.7348)
		(end 349.068136 -392.43)
		(width 0.14224)
		(layer "In11.Cu")
		(net "P5E_CPU0_P1_RX_DP<10>")
	)
	(segment
		(start 354.63353 -283.501338)
		(end 354.703126 -283.460698)
		(width 0.1143)
		(layer "In11.Cu")
		(net "P5E_CPU0_P1_RX_DP<10>")
	)
	(segment
		(start 354.190554 -280.076656)
		(end 354.189792 -280.076148)
		(width 0.1143)
		(layer "In11.Cu")
		(net "P5E_CPU0_P1_RX_DP<10>")
	)
	(segment
		(start 354.703126 -280.911554)
		(end 354.63353 -280.870914)
		(width 0.1143)
		(layer "In11.Cu")
		(net "P5E_CPU0_P1_RX_DP<10>")
	)
	(segment
		(start 354.703126 -293.871396)
		(end 354.63353 -293.830756)
		(width 0.1143)
		(layer "In11.Cu")
		(net "P5E_CPU0_P1_RX_DP<10>")
	)
	(segment
		(start 354.703126 -284.151578)
		(end 354.63353 -284.110938)
		(width 0.1143)
		(layer "In11.Cu")
		(net "P5E_CPU0_P1_RX_DP<10>")
	)
	(segment
		(start 354.66401 -288.343594)
		(end 354.703126 -288.320734)
		(width 0.1143)
		(layer "In11.Cu")
		(net "P5E_CPU0_P1_RX_DP<10>")
	)
	(segment
		(start 354.703126 -289.01136)
		(end 354.63353 -288.97072)
		(width 0.1143)
		(layer "In11.Cu")
		(net "P5E_CPU0_P1_RX_DP<10>")
	)
	(segment
		(start 354.183696 -280.072846)
		(end 354.16236 -280.0604)
		(width 0.1143)
		(layer "In11.Cu")
		(net "P5E_CPU0_P1_RX_DP<10>")
	)
	(segment
		(start 348.988126 -393.930632)
		(end 349.076264 -393.842494)
		(width 0.14224)
		(layer "In11.Cu")
		(net "P5E_CPU0_P1_RX_DP<10>")
	)
	(segment
		(start 354.233226 -280.101548)
		(end 354.19665 -280.080212)
		(width 0.1143)
		(layer "In11.Cu")
		(net "P5E_CPU0_P1_RX_DP<10>")
	)
	(segment
		(start 354.19411 -279.433528)
		(end 354.195126 -279.43302)
		(width 0.1143)
		(layer "In11.Cu")
		(net "P5E_CPU0_P1_RX_DP<10>")
	)
	(segment
		(start 354.703126 -292.251384)
		(end 354.63353 -292.210744)
		(width 0.1143)
		(layer "In11.Cu")
		(net "P5E_CPU0_P1_RX_DP<10>")
	)
	(segment
		(start 350.835214 -379.976888)
		(end 350.835214 -376.435366)
		(width 0.14224)
		(layer "In11.Cu")
		(net "P5E_CPU0_P1_RX_DP<10>")
	)
	(segment
		(start 354.188268 -280.075386)
		(end 354.187506 -280.074878)
		(width 0.1143)
		(layer "In11.Cu")
		(net "P5E_CPU0_P1_RX_DP<10>")
	)
	(segment
		(start 374.484646 -348.956122)
		(end 374.484646 -339.460332)
		(width 0.14224)
		(layer "In11.Cu")
		(net "P5E_CPU0_P1_RX_DP<10>")
	)
	(segment
		(start 354.093272 -296.212514)
		(end 354.093272 -295.79697)
		(width 0.1143)
		(layer "In11.Cu")
		(net "P5E_CPU0_P1_RX_DP<10>")
	)
	(segment
		(start 355.023166 -278.136096)
		(end 355.321108 -278.136096)
		(width 0.1143)
		(layer "In11.Cu")
		(net "P5E_CPU0_P1_RX_DP<10>")
	)
	(segment
		(start 354.138992 -296.286682)
		(end 354.138992 -296.258234)
		(width 0.1143)
		(layer "In11.Cu")
		(net "P5E_CPU0_P1_RX_DP<10>")
	)
	(segment
		(start 354.195126 -279.43302)
		(end 354.196396 -279.432258)
		(width 0.1143)
		(layer "In11.Cu")
		(net "P5E_CPU0_P1_RX_DP<10>")
	)
	(segment
		(start 354.187506 -280.074878)
		(end 354.186236 -280.074116)
		(width 0.1143)
		(layer "In11.Cu")
		(net "P5E_CPU0_P1_RX_DP<10>")
	)
	(segment
		(start 354.186236 -280.074116)
		(end 354.183696 -280.072846)
		(width 0.1143)
		(layer "In11.Cu")
		(net "P5E_CPU0_P1_RX_DP<10>")
	)
	(segment
		(start 354.940362 -278.2189)
		(end 355.023166 -278.136096)
		(width 0.1143)
		(layer "In11.Cu")
		(net "P5E_CPU0_P1_RX_DP<10>")
	)
	(segment
		(start 354.476304 -295.413938)
		(end 354.476304 -295.122092)
		(width 0.1143)
		(layer "In11.Cu")
		(net "P5E_CPU0_P1_RX_DP<10>")
	)
	(segment
		(start 354.631498 -288.36239)
		(end 354.66401 -288.343594)
		(width 0.1143)
		(layer "In11.Cu")
		(net "P5E_CPU0_P1_RX_DP<10>")
	)
	(segment
		(start 354.63353 -289.981132)
		(end 354.703126 -289.940492)
		(width 0.1143)
		(layer "In11.Cu")
		(net "P5E_CPU0_P1_RX_DP<10>")
	)
	(arc
		(start 354.63353 -285.73095)
		(mid 354.476553 -285.42615)
		(end 354.63353 -285.12135)
		(width 0.1143)
		(layer "In11.Cu")
		(net "P5E_CPU0_P1_RX_DP<10>")
	)
	(arc
		(start 354.233226 -279.410668)
		(mid 354.412039 -279.208318)
		(end 354.476558 -278.946102)
		(width 0.1143)
		(layer "In11.Cu")
		(net "P5E_CPU0_P1_RX_DP<10>")
	)
	(arc
		(start 354.476558 -278.946102)
		(mid 354.518107 -278.77468)
		(end 354.63353 -278.641302)
		(width 0.1143)
		(layer "In11.Cu")
		(net "P5E_CPU0_P1_RX_DP<10>")
	)
	(arc
		(start 354.936552 -278.24176)
		(mid 354.938575 -278.23035)
		(end 354.940362 -278.2189)
		(width 0.1143)
		(layer "In11.Cu")
		(net "P5E_CPU0_P1_RX_DP<10>")
	)
	(arc
		(start 354.946458 -287.856168)
		(mid 354.881222 -287.592577)
		(end 354.700586 -287.389824)
		(width 0.1143)
		(layer "In11.Cu")
		(net "P5E_CPU0_P1_RX_DP<10>")
	)
	(arc
		(start 354.63353 -290.590732)
		(mid 354.476553 -290.285932)
		(end 354.63353 -289.981132)
		(width 0.1143)
		(layer "In11.Cu")
		(net "P5E_CPU0_P1_RX_DP<10>")
	)
	(arc
		(start 354.703126 -285.08071)
		(mid 354.946453 -284.616144)
		(end 354.703126 -284.151578)
		(width 0.1143)
		(layer "In11.Cu")
		(net "P5E_CPU0_P1_RX_DP<10>")
	)
	(arc
		(start 350.955864 -376.113294)
		(mid 351.305018 -375.793674)
		(end 351.67697 -375.5009)
		(width 0.14224)
		(layer "In11.Cu")
		(net "P5E_CPU0_P1_RX_DP<10>")
	)
	(arc
		(start 367.470944 -361.978194)
		(mid 369.916001 -358.998857)
		(end 371.73281 -355.599746)
		(width 0.14224)
		(layer "In11.Cu")
		(net "P5E_CPU0_P1_RX_DP<10>")
	)
	(arc
		(start 354.703126 -293.180516)
		(mid 354.946453 -292.71595)
		(end 354.703126 -292.251384)
		(width 0.1143)
		(layer "In11.Cu")
		(net "P5E_CPU0_P1_RX_DP<10>")
	)
	(arc
		(start 354.63353 -293.830756)
		(mid 354.476553 -293.525956)
		(end 354.63353 -293.221156)
		(width 0.1143)
		(layer "In11.Cu")
		(net "P5E_CPU0_P1_RX_DP<10>")
	)
	(arc
		(start 354.476304 -295.122092)
		(mid 354.519961 -294.958139)
		(end 354.639372 -294.837612)
		(width 0.1143)
		(layer "In11.Cu")
		(net "P5E_CPU0_P1_RX_DP<10>")
	)
	(arc
		(start 354.476558 -287.045908)
		(mid 354.517524 -286.875502)
		(end 354.631498 -286.742378)
		(width 0.1143)
		(layer "In11.Cu")
		(net "P5E_CPU0_P1_RX_DP<10>")
	)
	(arc
		(start 354.701602 -294.801544)
		(mid 354.702364 -294.801037)
		(end 354.703126 -294.800528)
		(width 0.1143)
		(layer "In11.Cu")
		(net "P5E_CPU0_P1_RX_DP<10>")
	)
	(arc
		(start 354.63353 -284.110938)
		(mid 354.476553 -283.806138)
		(end 354.63353 -283.501338)
		(width 0.1143)
		(layer "In11.Cu")
		(net "P5E_CPU0_P1_RX_DP<10>")
	)
	(arc
		(start 354.703126 -283.460698)
		(mid 354.946453 -282.996132)
		(end 354.703126 -282.531566)
		(width 0.1143)
		(layer "In11.Cu")
		(net "P5E_CPU0_P1_RX_DP<10>")
	)
	(arc
		(start 354.63353 -287.350708)
		(mid 354.518103 -287.217332)
		(end 354.476558 -287.045908)
		(width 0.1143)
		(layer "In11.Cu")
		(net "P5E_CPU0_P1_RX_DP<10>")
	)
	(arc
		(start 354.63353 -280.870914)
		(mid 354.518103 -280.737538)
		(end 354.476558 -280.566114)
		(width 0.1143)
		(layer "In11.Cu")
		(net "P5E_CPU0_P1_RX_DP<10>")
	)
	(arc
		(start 354.16236 -280.0604)
		(mid 354.006432 -279.756108)
		(end 354.16236 -279.451816)
		(width 0.1143)
		(layer "In11.Cu")
		(net "P5E_CPU0_P1_RX_DP<10>")
	)
	(arc
		(start 354.476558 -288.66592)
		(mid 354.517524 -288.495514)
		(end 354.631498 -288.36239)
		(width 0.1143)
		(layer "In11.Cu")
		(net "P5E_CPU0_P1_RX_DP<10>")
	)
	(arc
		(start 352.880676 -374.943878)
		(mid 355.489966 -373.549098)
		(end 357.777034 -371.672104)
		(width 0.14224)
		(layer "In11.Cu")
		(net "P5E_CPU0_P1_RX_DP<10>")
	)
	(arc
		(start 349.068136 -381.966216)
		(mid 349.077842 -381.917421)
		(end 349.105474 -381.876046)
		(width 0.14224)
		(layer "In11.Cu")
		(net "P5E_CPU0_P1_RX_DP<10>")
	)
	(arc
		(start 354.63353 -292.210744)
		(mid 354.476553 -291.905944)
		(end 354.63353 -291.601144)
		(width 0.1143)
		(layer "In11.Cu")
		(net "P5E_CPU0_P1_RX_DP<10>")
	)
	(arc
		(start 354.703126 -291.560504)
		(mid 354.946453 -291.095938)
		(end 354.703126 -290.631372)
		(width 0.1143)
		(layer "In11.Cu")
		(net "P5E_CPU0_P1_RX_DP<10>")
	)
	(arc
		(start 350.835214 -376.435366)
		(mid 350.847231 -376.3238)
		(end 350.882966 -376.217434)
		(width 0.14224)
		(layer "In11.Cu")
		(net "P5E_CPU0_P1_RX_DP<10>")
	)
	(arc
		(start 351.67697 -375.5009)
		(mid 351.729452 -375.465354)
		(end 351.784158 -375.433336)
		(width 0.14224)
		(layer "In11.Cu")
		(net "P5E_CPU0_P1_RX_DP<10>")
	)
	(arc
		(start 354.703126 -288.320734)
		(mid 354.881939 -288.118384)
		(end 354.946458 -287.856168)
		(width 0.1143)
		(layer "In11.Cu")
		(net "P5E_CPU0_P1_RX_DP<10>")
	)
	(arc
		(start 351.999042 -375.316496)
		(mid 352.055353 -375.287824)
		(end 352.113088 -375.26214)
		(width 0.14224)
		(layer "In11.Cu")
		(net "P5E_CPU0_P1_RX_DP<10>")
	)
	(arc
		(start 350.882966 -376.217434)
		(mid 350.914712 -376.162071)
		(end 350.955864 -376.113294)
		(width 0.14224)
		(layer "In11.Cu")
		(net "P5E_CPU0_P1_RX_DP<10>")
	)
	(arc
		(start 354.703126 -294.800528)
		(mid 354.946453 -294.335962)
		(end 354.703126 -293.871396)
		(width 0.1143)
		(layer "In11.Cu")
		(net "P5E_CPU0_P1_RX_DP<10>")
	)
	(arc
		(start 354.703126 -278.600662)
		(mid 354.855113 -278.444154)
		(end 354.936552 -278.24176)
		(width 0.1143)
		(layer "In11.Cu")
		(net "P5E_CPU0_P1_RX_DP<10>")
	)
	(arc
		(start 354.703126 -289.940492)
		(mid 354.946453 -289.475926)
		(end 354.703126 -289.01136)
		(width 0.1143)
		(layer "In11.Cu")
		(net "P5E_CPU0_P1_RX_DP<10>")
	)
	(arc
		(start 354.63353 -282.490926)
		(mid 354.476553 -282.186126)
		(end 354.63353 -281.881326)
		(width 0.1143)
		(layer "In11.Cu")
		(net "P5E_CPU0_P1_RX_DP<10>")
	)
	(arc
		(start 350.715326 -380.266194)
		(mid 350.80407 -380.133474)
		(end 350.835214 -379.976888)
		(width 0.14224)
		(layer "In11.Cu")
		(net "P5E_CPU0_P1_RX_DP<10>")
	)
	(arc
		(start 354.703126 -286.700722)
		(mid 354.946453 -286.236156)
		(end 354.703126 -285.77159)
		(width 0.1143)
		(layer "In11.Cu")
		(net "P5E_CPU0_P1_RX_DP<10>")
	)
	(arc
		(start 354.476558 -280.566114)
		(mid 354.412043 -280.303895)
		(end 354.233226 -280.101548)
		(width 0.1143)
		(layer "In11.Cu")
		(net "P5E_CPU0_P1_RX_DP<10>")
	)
	(arc
		(start 354.63353 -288.97072)
		(mid 354.518103 -288.837344)
		(end 354.476558 -288.66592)
		(width 0.1143)
		(layer "In11.Cu")
		(net "P5E_CPU0_P1_RX_DP<10>")
	)
	(arc
		(start 354.703126 -281.840686)
		(mid 354.946453 -281.37612)
		(end 354.703126 -280.911554)
		(width 0.1143)
		(layer "In11.Cu")
		(net "P5E_CPU0_P1_RX_DP<10>")
	)
	(segment
		(start 347.327982 -276.250146)
		(end 346.86113 -276.516084)
		(width 0.12954)
		(layer "F.Cu")
		(net "P5E_CPU0_P1_RX_DP<0>")
	)
	(segment
		(start 336.19821 -394.385292)
		(end 336.71891 -394.385292)
		(width 0.127)
		(layer "F.Cu")
		(net "P5E_CPU0_P1_RX_DP<0>")
	)
	(segment
		(start 337.076288 -393.428982)
		(end 336.760312 -393.113006)
		(width 0.14224)
		(layer "In11.Cu")
		(net "P5E_CPU0_P1_RX_DP<0>")
	)
	(segment
		(start 345.231466 -286.742378)
		(end 345.263978 -286.723582)
		(width 0.1143)
		(layer "In11.Cu")
		(net "P5E_CPU0_P1_RX_DP<0>")
	)
	(segment
		(start 345.73337 -277.814024)
		(end 345.734132 -277.813516)
		(width 0.1143)
		(layer "In11.Cu")
		(net "P5E_CPU0_P1_RX_DP<0>")
	)
	(segment
		(start 345.233498 -285.12135)
		(end 345.303094 -285.08071)
		(width 0.1143)
		(layer "In11.Cu")
		(net "P5E_CPU0_P1_RX_DP<0>")
	)
	(segment
		(start 348.924118 -309.935372)
		(end 344.652092 -299.621448)
		(width 0.14224)
		(layer "In11.Cu")
		(net "P5E_CPU0_P1_RX_DP<0>")
	)
	(segment
		(start 345.702382 -277.831804)
		(end 345.727782 -277.817072)
		(width 0.1143)
		(layer "In11.Cu")
		(net "P5E_CPU0_P1_RX_DP<0>")
	)
	(segment
		(start 345.734132 -277.813516)
		(end 345.735148 -277.813008)
		(width 0.1143)
		(layer "In11.Cu")
		(net "P5E_CPU0_P1_RX_DP<0>")
	)
	(segment
		(start 345.729814 -277.816056)
		(end 345.730576 -277.815548)
		(width 0.1143)
		(layer "In11.Cu")
		(net "P5E_CPU0_P1_RX_DP<0>")
	)
	(segment
		(start 344.772742 -280.066242)
		(end 344.772488 -280.066242)
		(width 0.1143)
		(layer "In11.Cu")
		(net "P5E_CPU0_P1_RX_DP<0>")
	)
	(segment
		(start 345.233498 -278.641302)
		(end 345.303094 -278.600662)
		(width 0.1143)
		(layer "In11.Cu")
		(net "P5E_CPU0_P1_RX_DP<0>")
	)
	(segment
		(start 345.303094 -284.151578)
		(end 345.233498 -284.110938)
		(width 0.1143)
		(layer "In11.Cu")
		(net "P5E_CPU0_P1_RX_DP<0>")
	)
	(segment
		(start 345.233498 -294.841168)
		(end 345.303094 -294.800528)
		(width 0.1143)
		(layer "In11.Cu")
		(net "P5E_CPU0_P1_RX_DP<0>")
	)
	(segment
		(start 344.833194 -280.101548)
		(end 344.773504 -280.06675)
		(width 0.1143)
		(layer "In11.Cu")
		(net "P5E_CPU0_P1_RX_DP<0>")
	)
	(segment
		(start 364.979966 -340.2076)
		(end 363.092746 -329.712066)
		(width 0.14224)
		(layer "In11.Cu")
		(net "P5E_CPU0_P1_RX_DP<0>")
	)
	(segment
		(start 355.83495 -320.278506)
		(end 348.924118 -309.935372)
		(width 0.14224)
		(layer "In11.Cu")
		(net "P5E_CPU0_P1_RX_DP<0>")
	)
	(segment
		(start 364.979966 -343.810082)
		(end 364.979966 -340.2076)
		(width 0.14224)
		(layer "In11.Cu")
		(net "P5E_CPU0_P1_RX_DP<0>")
	)
	(segment
		(start 345.303094 -292.251384)
		(end 345.233498 -292.210744)
		(width 0.1143)
		(layer "In11.Cu")
		(net "P5E_CPU0_P1_RX_DP<0>")
	)
	(segment
		(start 345.233498 -291.601144)
		(end 345.303094 -291.560504)
		(width 0.1143)
		(layer "In11.Cu")
		(net "P5E_CPU0_P1_RX_DP<0>")
	)
	(segment
		(start 333.981806 -386.051552)
		(end 329.337924 -381.407924)
		(width 0.14224)
		(layer "In11.Cu")
		(net "P5E_CPU0_P1_RX_DP<0>")
	)
	(segment
		(start 345.233498 -281.881326)
		(end 345.303094 -281.840686)
		(width 0.1143)
		(layer "In11.Cu")
		(net "P5E_CPU0_P1_RX_DP<0>")
	)
	(segment
		(start 344.606372 -295.948862)
		(end 345.076272 -295.478962)
		(width 0.1143)
		(layer "In11.Cu")
		(net "P5E_CPU0_P1_RX_DP<0>")
	)
	(segment
		(start 344.772234 -279.445974)
		(end 344.772742 -279.445974)
		(width 0.1143)
		(layer "In11.Cu")
		(net "P5E_CPU0_P1_RX_DP<0>")
	)
	(segment
		(start 329.29068 -381.293878)
		(end 329.29068 -376.749056)
		(width 0.14224)
		(layer "In11.Cu")
		(net "P5E_CPU0_P1_RX_DP<0>")
	)
	(segment
		(start 345.300554 -287.389824)
		(end 345.233498 -287.350708)
		(width 0.1143)
		(layer "In11.Cu")
		(net "P5E_CPU0_P1_RX_DP<0>")
	)
	(segment
		(start 337.06816 -392.429746)
		(end 337.06816 -390.78027)
		(width 0.14224)
		(layer "In11.Cu")
		(net "P5E_CPU0_P1_RX_DP<0>")
	)
	(segment
		(start 344.652092 -296.46372)
		(end 344.652092 -296.435272)
		(width 0.1143)
		(layer "In11.Cu")
		(net "P5E_CPU0_P1_RX_DP<0>")
	)
	(segment
		(start 344.772742 -279.445974)
		(end 344.832432 -279.411176)
		(width 0.1143)
		(layer "In11.Cu")
		(net "P5E_CPU0_P1_RX_DP<0>")
	)
	(segment
		(start 345.263978 -286.723582)
		(end 345.303094 -286.700722)
		(width 0.1143)
		(layer "In11.Cu")
		(net "P5E_CPU0_P1_RX_DP<0>")
	)
	(segment
		(start 345.303094 -280.911554)
		(end 345.233498 -280.870914)
		(width 0.1143)
		(layer "In11.Cu")
		(net "P5E_CPU0_P1_RX_DP<0>")
	)
	(segment
		(start 345.303094 -293.871396)
		(end 345.233498 -293.830756)
		(width 0.1143)
		(layer "In11.Cu")
		(net "P5E_CPU0_P1_RX_DP<0>")
	)
	(segment
		(start 345.736672 -277.811992)
		(end 345.773248 -277.790656)
		(width 0.1143)
		(layer "In11.Cu")
		(net "P5E_CPU0_P1_RX_DP<0>")
	)
	(segment
		(start 362.243624 -328.087736)
		(end 355.83495 -320.278506)
		(width 0.14224)
		(layer "In11.Cu")
		(net "P5E_CPU0_P1_RX_DP<0>")
	)
	(segment
		(start 336.76336 -392.734546)
		(end 337.06816 -392.429746)
		(width 0.14224)
		(layer "In11.Cu")
		(net "P5E_CPU0_P1_RX_DP<0>")
	)
	(segment
		(start 329.337924 -376.63501)
		(end 332.66126 -373.311674)
		(width 0.14224)
		(layer "In11.Cu")
		(net "P5E_CPU0_P1_RX_DP<0>")
	)
	(segment
		(start 346.480384 -276.598888)
		(end 346.563188 -276.516084)
		(width 0.1143)
		(layer "In11.Cu")
		(net "P5E_CPU0_P1_RX_DP<0>")
	)
	(segment
		(start 336.999326 -390.55294)
		(end 334.03286 -386.113782)
		(width 0.14224)
		(layer "In11.Cu")
		(net "P5E_CPU0_P1_RX_DP<0>")
	)
	(segment
		(start 345.233498 -293.221156)
		(end 345.303094 -293.180516)
		(width 0.1143)
		(layer "In11.Cu")
		(net "P5E_CPU0_P1_RX_DP<0>")
	)
	(segment
		(start 336.98815 -393.930632)
		(end 337.076288 -393.842494)
		(width 0.14224)
		(layer "In11.Cu")
		(net "P5E_CPU0_P1_RX_DP<0>")
	)
	(segment
		(start 348.404434 -365.12627)
		(end 358.903778 -354.626926)
		(width 0.14224)
		(layer "In11.Cu")
		(net "P5E_CPU0_P1_RX_DP<0>")
	)
	(segment
		(start 345.303094 -289.01136)
		(end 345.233498 -288.97072)
		(width 0.1143)
		(layer "In11.Cu")
		(net "P5E_CPU0_P1_RX_DP<0>")
	)
	(segment
		(start 336.71891 -394.385292)
		(end 336.813906 -394.031216)
		(width 0.14224)
		(layer "In11.Cu")
		(net "P5E_CPU0_P1_RX_DP<0>")
	)
	(segment
		(start 346.563188 -276.516084)
		(end 346.86113 -276.516084)
		(width 0.1143)
		(layer "In11.Cu")
		(net "P5E_CPU0_P1_RX_DP<0>")
	)
	(segment
		(start 345.076272 -295.478962)
		(end 345.076272 -295.239694)
		(width 0.1143)
		(layer "In11.Cu")
		(net "P5E_CPU0_P1_RX_DP<0>")
	)
	(segment
		(start 344.773504 -280.06675)
		(end 344.772742 -280.066242)
		(width 0.1143)
		(layer "In11.Cu")
		(net "P5E_CPU0_P1_RX_DP<0>")
	)
	(segment
		(start 334.97266 -371.767608)
		(end 344.148918 -367.9698)
		(width 0.14224)
		(layer "In11.Cu")
		(net "P5E_CPU0_P1_RX_DP<0>")
	)
	(segment
		(start 336.760312 -393.113006)
		(end 336.76336 -392.734546)
		(width 0.14224)
		(layer "In11.Cu")
		(net "P5E_CPU0_P1_RX_DP<0>")
	)
	(segment
		(start 345.233498 -283.501338)
		(end 345.303094 -283.460698)
		(width 0.1143)
		(layer "In11.Cu")
		(net "P5E_CPU0_P1_RX_DP<0>")
	)
	(segment
		(start 344.652092 -299.621448)
		(end 344.652092 -296.46372)
		(width 0.14224)
		(layer "In11.Cu")
		(net "P5E_CPU0_P1_RX_DP<0>")
	)
	(segment
		(start 345.231466 -288.36239)
		(end 345.263978 -288.343594)
		(width 0.1143)
		(layer "In11.Cu")
		(net "P5E_CPU0_P1_RX_DP<0>")
	)
	(segment
		(start 344.606372 -296.389552)
		(end 344.606372 -295.948862)
		(width 0.1143)
		(layer "In11.Cu")
		(net "P5E_CPU0_P1_RX_DP<0>")
	)
	(segment
		(start 345.730576 -277.815548)
		(end 345.73337 -277.814024)
		(width 0.1143)
		(layer "In11.Cu")
		(net "P5E_CPU0_P1_RX_DP<0>")
	)
	(segment
		(start 363.092746 -329.712066)
		(end 362.243624 -328.087736)
		(width 0.14224)
		(layer "In11.Cu")
		(net "P5E_CPU0_P1_RX_DP<0>")
	)
	(segment
		(start 345.735148 -277.813008)
		(end 345.736672 -277.811992)
		(width 0.1143)
		(layer "In11.Cu")
		(net "P5E_CPU0_P1_RX_DP<0>")
	)
	(segment
		(start 337.076288 -393.842494)
		(end 337.076288 -393.428982)
		(width 0.14224)
		(layer "In11.Cu")
		(net "P5E_CPU0_P1_RX_DP<0>")
	)
	(segment
		(start 336.813906 -394.031216)
		(end 336.98815 -393.930632)
		(width 0.14224)
		(layer "In11.Cu")
		(net "P5E_CPU0_P1_RX_DP<0>")
	)
	(segment
		(start 345.076526 -295.23944)
		(end 345.076526 -295.145968)
		(width 0.1143)
		(layer "In11.Cu")
		(net "P5E_CPU0_P1_RX_DP<0>")
	)
	(segment
		(start 345.303094 -282.531566)
		(end 345.233498 -282.490926)
		(width 0.1143)
		(layer "In11.Cu")
		(net "P5E_CPU0_P1_RX_DP<0>")
	)
	(segment
		(start 345.303094 -285.77159)
		(end 345.233498 -285.73095)
		(width 0.1143)
		(layer "In11.Cu")
		(net "P5E_CPU0_P1_RX_DP<0>")
	)
	(segment
		(start 364.01502 -346.978732)
		(end 364.658656 -345.425014)
		(width 0.14224)
		(layer "In11.Cu")
		(net "P5E_CPU0_P1_RX_DP<0>")
	)
	(segment
		(start 346.173552 -277.02129)
		(end 346.243148 -276.98065)
		(width 0.1143)
		(layer "In11.Cu")
		(net "P5E_CPU0_P1_RX_DP<0>")
	)
	(segment
		(start 345.233498 -289.981132)
		(end 345.303094 -289.940492)
		(width 0.1143)
		(layer "In11.Cu")
		(net "P5E_CPU0_P1_RX_DP<0>")
	)
	(segment
		(start 345.303094 -290.631372)
		(end 345.233498 -290.590732)
		(width 0.1143)
		(layer "In11.Cu")
		(net "P5E_CPU0_P1_RX_DP<0>")
	)
	(segment
		(start 345.076272 -295.239694)
		(end 345.076526 -295.23944)
		(width 0.1143)
		(layer "In11.Cu")
		(net "P5E_CPU0_P1_RX_DP<0>")
	)
	(segment
		(start 345.727782 -277.817072)
		(end 345.729814 -277.816056)
		(width 0.1143)
		(layer "In11.Cu")
		(net "P5E_CPU0_P1_RX_DP<0>")
	)
	(segment
		(start 344.652092 -296.435272)
		(end 344.606372 -296.389552)
		(width 0.1143)
		(layer "In11.Cu")
		(net "P5E_CPU0_P1_RX_DP<0>")
	)
	(segment
		(start 345.263978 -288.343594)
		(end 345.303094 -288.320734)
		(width 0.1143)
		(layer "In11.Cu")
		(net "P5E_CPU0_P1_RX_DP<0>")
	)
	(arc
		(start 345.303094 -285.08071)
		(mid 345.546421 -284.616144)
		(end 345.303094 -284.151578)
		(width 0.1143)
		(layer "In11.Cu")
		(net "P5E_CPU0_P1_RX_DP<0>")
	)
	(arc
		(start 345.773248 -277.790656)
		(mid 345.952061 -277.588306)
		(end 346.01658 -277.32609)
		(width 0.1143)
		(layer "In11.Cu")
		(net "P5E_CPU0_P1_RX_DP<0>")
	)
	(arc
		(start 345.303094 -286.700722)
		(mid 345.546421 -286.236156)
		(end 345.303094 -285.77159)
		(width 0.1143)
		(layer "In11.Cu")
		(net "P5E_CPU0_P1_RX_DP<0>")
	)
	(arc
		(start 345.233498 -290.590732)
		(mid 345.076521 -290.285932)
		(end 345.233498 -289.981132)
		(width 0.1143)
		(layer "In11.Cu")
		(net "P5E_CPU0_P1_RX_DP<0>")
	)
	(arc
		(start 345.303094 -291.560504)
		(mid 345.546421 -291.095938)
		(end 345.303094 -290.631372)
		(width 0.1143)
		(layer "In11.Cu")
		(net "P5E_CPU0_P1_RX_DP<0>")
	)
	(arc
		(start 345.233498 -282.490926)
		(mid 345.076521 -282.186126)
		(end 345.233498 -281.881326)
		(width 0.1143)
		(layer "In11.Cu")
		(net "P5E_CPU0_P1_RX_DP<0>")
	)
	(arc
		(start 345.233498 -280.870914)
		(mid 345.118071 -280.737538)
		(end 345.076526 -280.566114)
		(width 0.1143)
		(layer "In11.Cu")
		(net "P5E_CPU0_P1_RX_DP<0>")
	)
	(arc
		(start 358.903778 -354.626926)
		(mid 361.835885 -351.054432)
		(end 364.01502 -346.978732)
		(width 0.14224)
		(layer "In11.Cu")
		(net "P5E_CPU0_P1_RX_DP<0>")
	)
	(arc
		(start 345.303094 -278.600662)
		(mid 345.481907 -278.398312)
		(end 345.546426 -278.136096)
		(width 0.1143)
		(layer "In11.Cu")
		(net "P5E_CPU0_P1_RX_DP<0>")
	)
	(arc
		(start 345.076526 -288.66592)
		(mid 345.117492 -288.495514)
		(end 345.231466 -288.36239)
		(width 0.1143)
		(layer "In11.Cu")
		(net "P5E_CPU0_P1_RX_DP<0>")
	)
	(arc
		(start 345.303094 -288.320734)
		(mid 345.481907 -288.118384)
		(end 345.546426 -287.856168)
		(width 0.1143)
		(layer "In11.Cu")
		(net "P5E_CPU0_P1_RX_DP<0>")
	)
	(arc
		(start 334.03286 -386.113782)
		(mid 334.008864 -386.08141)
		(end 333.981806 -386.051552)
		(width 0.14224)
		(layer "In11.Cu")
		(net "P5E_CPU0_P1_RX_DP<0>")
	)
	(arc
		(start 344.832432 -279.411176)
		(mid 344.832813 -279.410922)
		(end 344.833194 -279.410668)
		(width 0.1143)
		(layer "In11.Cu")
		(net "P5E_CPU0_P1_RX_DP<0>")
	)
	(arc
		(start 345.233498 -288.97072)
		(mid 345.118071 -288.837344)
		(end 345.076526 -288.66592)
		(width 0.1143)
		(layer "In11.Cu")
		(net "P5E_CPU0_P1_RX_DP<0>")
	)
	(arc
		(start 345.233498 -287.350708)
		(mid 345.118071 -287.217332)
		(end 345.076526 -287.045908)
		(width 0.1143)
		(layer "In11.Cu")
		(net "P5E_CPU0_P1_RX_DP<0>")
	)
	(arc
		(start 346.243148 -276.98065)
		(mid 346.395135 -276.824142)
		(end 346.476574 -276.621748)
		(width 0.1143)
		(layer "In11.Cu")
		(net "P5E_CPU0_P1_RX_DP<0>")
	)
	(arc
		(start 345.303094 -294.800528)
		(mid 345.546421 -294.335962)
		(end 345.303094 -293.871396)
		(width 0.1143)
		(layer "In11.Cu")
		(net "P5E_CPU0_P1_RX_DP<0>")
	)
	(arc
		(start 346.01658 -277.32609)
		(mid 346.058129 -277.154668)
		(end 346.173552 -277.02129)
		(width 0.1143)
		(layer "In11.Cu")
		(net "P5E_CPU0_P1_RX_DP<0>")
	)
	(arc
		(start 345.076526 -280.566114)
		(mid 345.012011 -280.303895)
		(end 344.833194 -280.101548)
		(width 0.1143)
		(layer "In11.Cu")
		(net "P5E_CPU0_P1_RX_DP<0>")
	)
	(arc
		(start 345.233498 -284.110938)
		(mid 345.076521 -283.806138)
		(end 345.233498 -283.501338)
		(width 0.1143)
		(layer "In11.Cu")
		(net "P5E_CPU0_P1_RX_DP<0>")
	)
	(arc
		(start 344.833194 -279.410668)
		(mid 345.012007 -279.208318)
		(end 345.076526 -278.946102)
		(width 0.1143)
		(layer "In11.Cu")
		(net "P5E_CPU0_P1_RX_DP<0>")
	)
	(arc
		(start 332.66126 -373.311674)
		(mid 333.740872 -372.425743)
		(end 334.97266 -371.767608)
		(width 0.14224)
		(layer "In11.Cu")
		(net "P5E_CPU0_P1_RX_DP<0>")
	)
	(arc
		(start 345.076526 -295.145968)
		(mid 345.118075 -294.974546)
		(end 345.233498 -294.841168)
		(width 0.1143)
		(layer "In11.Cu")
		(net "P5E_CPU0_P1_RX_DP<0>")
	)
	(arc
		(start 345.303094 -283.460698)
		(mid 345.546421 -282.996132)
		(end 345.303094 -282.531566)
		(width 0.1143)
		(layer "In11.Cu")
		(net "P5E_CPU0_P1_RX_DP<0>")
	)
	(arc
		(start 345.233498 -285.73095)
		(mid 345.076521 -285.42615)
		(end 345.233498 -285.12135)
		(width 0.1143)
		(layer "In11.Cu")
		(net "P5E_CPU0_P1_RX_DP<0>")
	)
	(arc
		(start 345.233498 -292.210744)
		(mid 345.076521 -291.905944)
		(end 345.233498 -291.601144)
		(width 0.1143)
		(layer "In11.Cu")
		(net "P5E_CPU0_P1_RX_DP<0>")
	)
	(arc
		(start 364.658656 -345.425014)
		(mid 364.898865 -344.633376)
		(end 364.979966 -343.810082)
		(width 0.14224)
		(layer "In11.Cu")
		(net "P5E_CPU0_P1_RX_DP<0>")
	)
	(arc
		(start 345.546426 -287.856168)
		(mid 345.48119 -287.592577)
		(end 345.300554 -287.389824)
		(width 0.1143)
		(layer "In11.Cu")
		(net "P5E_CPU0_P1_RX_DP<0>")
	)
	(arc
		(start 329.29068 -376.749056)
		(mid 329.302957 -376.687333)
		(end 329.337924 -376.63501)
		(width 0.14224)
		(layer "In11.Cu")
		(net "P5E_CPU0_P1_RX_DP<0>")
	)
	(arc
		(start 345.233498 -293.830756)
		(mid 345.076521 -293.525956)
		(end 345.233498 -293.221156)
		(width 0.1143)
		(layer "In11.Cu")
		(net "P5E_CPU0_P1_RX_DP<0>")
	)
	(arc
		(start 345.076526 -287.045908)
		(mid 345.117492 -286.875502)
		(end 345.231466 -286.742378)
		(width 0.1143)
		(layer "In11.Cu")
		(net "P5E_CPU0_P1_RX_DP<0>")
	)
	(arc
		(start 346.476574 -276.621748)
		(mid 346.478597 -276.610338)
		(end 346.480384 -276.598888)
		(width 0.1143)
		(layer "In11.Cu")
		(net "P5E_CPU0_P1_RX_DP<0>")
	)
	(arc
		(start 337.06816 -390.78027)
		(mid 337.050619 -390.661492)
		(end 336.999326 -390.55294)
		(width 0.14224)
		(layer "In11.Cu")
		(net "P5E_CPU0_P1_RX_DP<0>")
	)
	(arc
		(start 345.303094 -281.840686)
		(mid 345.546421 -281.37612)
		(end 345.303094 -280.911554)
		(width 0.1143)
		(layer "In11.Cu")
		(net "P5E_CPU0_P1_RX_DP<0>")
	)
	(arc
		(start 329.337924 -381.407924)
		(mid 329.302962 -381.355599)
		(end 329.29068 -381.293878)
		(width 0.14224)
		(layer "In11.Cu")
		(net "P5E_CPU0_P1_RX_DP<0>")
	)
	(arc
		(start 345.303094 -289.940492)
		(mid 345.546421 -289.475926)
		(end 345.303094 -289.01136)
		(width 0.1143)
		(layer "In11.Cu")
		(net "P5E_CPU0_P1_RX_DP<0>")
	)
	(arc
		(start 345.546426 -278.136096)
		(mid 345.587681 -277.965125)
		(end 345.702382 -277.831804)
		(width 0.1143)
		(layer "In11.Cu")
		(net "P5E_CPU0_P1_RX_DP<0>")
	)
	(arc
		(start 344.148918 -367.9698)
		(mid 346.416702 -366.757593)
		(end 348.404434 -365.12627)
		(width 0.14224)
		(layer "In11.Cu")
		(net "P5E_CPU0_P1_RX_DP<0>")
	)
	(arc
		(start 344.772488 -280.066242)
		(mid 344.603178 -279.756215)
		(end 344.772234 -279.445974)
		(width 0.1143)
		(layer "In11.Cu")
		(net "P5E_CPU0_P1_RX_DP<0>")
	)
	(arc
		(start 345.076526 -278.946102)
		(mid 345.118075 -278.77468)
		(end 345.233498 -278.641302)
		(width 0.1143)
		(layer "In11.Cu")
		(net "P5E_CPU0_P1_RX_DP<0>")
	)
	(arc
		(start 345.303094 -293.180516)
		(mid 345.546421 -292.71595)
		(end 345.303094 -292.251384)
		(width 0.1143)
		(layer "In11.Cu")
		(net "P5E_CPU0_P1_RX_DP<0>")
	)
	(segment
		(start 346.597986 -393.69238)
		(end 347.118686 -393.69238)
		(width 0.127)
		(layer "F.Cu")
		(net "P5E_CPU0_P1_RX_DN<9>")
	)
	(segment
		(start 354.847906 -276.250146)
		(end 354.381054 -276.516084)
		(width 0.12954)
		(layer "F.Cu")
		(net "P5E_CPU0_P1_RX_DN<9>")
	)
	(segment
		(start 353.627944 -285.913322)
		(end 353.590606 -285.891732)
		(width 0.1143)
		(layer "In11.Cu")
		(net "P5E_CPU0_P1_RX_DN<9>")
	)
	(segment
		(start 353.627944 -291.418772)
		(end 353.659948 -291.399976)
		(width 0.1143)
		(layer "In11.Cu")
		(net "P5E_CPU0_P1_RX_DN<9>")
	)
	(segment
		(start 353.627944 -284.938978)
		(end 353.659948 -284.920182)
		(width 0.1143)
		(layer "In11.Cu")
		(net "P5E_CPU0_P1_RX_DN<9>")
	)
	(segment
		(start 347.605858 -386.691378)
		(end 347.606112 -386.689092)
		(width 0.14224)
		(layer "In11.Cu")
		(net "P5E_CPU0_P1_RX_DN<9>")
	)
	(segment
		(start 347.55074 -392.348466)
		(end 347.55074 -387.817868)
		(width 0.14224)
		(layer "In11.Cu")
		(net "P5E_CPU0_P1_RX_DN<9>")
	)
	(segment
		(start 347.66123 -385.564888)
		(end 347.682058 -385.13893)
		(width 0.14224)
		(layer "In11.Cu")
		(net "P5E_CPU0_P1_RX_DN<9>")
	)
	(segment
		(start 353.187 -280.260806)
		(end 353.186746 -280.260806)
		(width 0.1143)
		(layer "In11.Cu")
		(net "P5E_CPU0_P1_RX_DN<9>")
	)
	(segment
		(start 353.659694 -282.692094)
		(end 353.627944 -282.673298)
		(width 0.1143)
		(layer "In11.Cu")
		(net "P5E_CPU0_P1_RX_DN<9>")
	)
	(segment
		(start 353.659694 -281.072082)
		(end 353.632516 -281.05608)
		(width 0.1143)
		(layer "In11.Cu")
		(net "P5E_CPU0_P1_RX_DN<9>")
	)
	(segment
		(start 353.590606 -293.060374)
		(end 353.627944 -293.038784)
		(width 0.1143)
		(layer "In11.Cu")
		(net "P5E_CPU0_P1_RX_DN<9>")
	)
	(segment
		(start 373.257572 -339.57006)
		(end 371.081554 -327.46188)
		(width 0.14224)
		(layer "In11.Cu")
		(net "P5E_CPU0_P1_RX_DN<9>")
	)
	(segment
		(start 354.098098 -277.648162)
		(end 354.103178 -277.645622)
		(width 0.1143)
		(layer "In11.Cu")
		(net "P5E_CPU0_P1_RX_DN<9>")
	)
	(segment
		(start 353.659694 -292.411912)
		(end 353.627944 -292.393116)
		(width 0.1143)
		(layer "In11.Cu")
		(net "P5E_CPU0_P1_RX_DN<9>")
	)
	(segment
		(start 354.104956 -277.64486)
		(end 354.130102 -277.630128)
		(width 0.1143)
		(layer "In11.Cu")
		(net "P5E_CPU0_P1_RX_DN<9>")
	)
	(segment
		(start 353.65944 -285.93161)
		(end 353.658424 -285.931102)
		(width 0.1143)
		(layer "In11.Cu")
		(net "P5E_CPU0_P1_RX_DN<9>")
	)
	(segment
		(start 354.05949 -277.671022)
		(end 354.094034 -277.650956)
		(width 0.1143)
		(layer "In11.Cu")
		(net "P5E_CPU0_P1_RX_DN<9>")
	)
	(segment
		(start 353.346004 -295.323514)
		(end 353.346004 -295.145968)
		(width 0.1143)
		(layer "In11.Cu")
		(net "P5E_CPU0_P1_RX_DN<9>")
	)
	(segment
		(start 353.189286 -280.26233)
		(end 353.18827 -280.261568)
		(width 0.1143)
		(layer "In11.Cu")
		(net "P5E_CPU0_P1_RX_DN<9>")
	)
	(segment
		(start 353.627944 -278.45893)
		(end 353.659948 -278.440134)
		(width 0.1143)
		(layer "In11.Cu")
		(net "P5E_CPU0_P1_RX_DN<9>")
	)
	(segment
		(start 354.7491 -276.586188)
		(end 354.678996 -276.516084)
		(width 0.1143)
		(layer "In11.Cu")
		(net "P5E_CPU0_P1_RX_DN<9>")
	)
	(segment
		(start 371.081554 -327.46188)
		(end 368.877596 -323.245226)
		(width 0.14224)
		(layer "In11.Cu")
		(net "P5E_CPU0_P1_RX_DN<9>")
	)
	(segment
		(start 347.472 -393.787376)
		(end 347.472508 -393.786868)
		(width 0.14224)
		(layer "In11.Cu")
		(net "P5E_CPU0_P1_RX_DN<9>")
	)
	(segment
		(start 354.094034 -277.650956)
		(end 354.094542 -277.650702)
		(width 0.1143)
		(layer "In11.Cu")
		(net "P5E_CPU0_P1_RX_DN<9>")
	)
	(segment
		(start 347.594174 -393.716764)
		(end 347.594174 -393.545822)
		(width 0.14224)
		(layer "In11.Cu")
		(net "P5E_CPU0_P1_RX_DN<9>")
	)
	(segment
		(start 353.659694 -294.031924)
		(end 353.627944 -294.013128)
		(width 0.1143)
		(layer "In11.Cu")
		(net "P5E_CPU0_P1_RX_DN<9>")
	)
	(segment
		(start 353.590606 -289.82035)
		(end 353.627944 -289.79876)
		(width 0.1143)
		(layer "In11.Cu")
		(net "P5E_CPU0_P1_RX_DN<9>")
	)
	(segment
		(start 353.627944 -282.673298)
		(end 353.590606 -282.651708)
		(width 0.1143)
		(layer "In11.Cu")
		(net "P5E_CPU0_P1_RX_DN<9>")
	)
	(segment
		(start 353.186746 -280.260806)
		(end 353.117658 -280.220166)
		(width 0.1143)
		(layer "In11.Cu")
		(net "P5E_CPU0_P1_RX_DN<9>")
	)
	(segment
		(start 353.18827 -280.261568)
		(end 353.187 -280.260806)
		(width 0.1143)
		(layer "In11.Cu")
		(net "P5E_CPU0_P1_RX_DN<9>")
	)
	(segment
		(start 353.192588 -280.264616)
		(end 353.190556 -280.263092)
		(width 0.1143)
		(layer "In11.Cu")
		(net "P5E_CPU0_P1_RX_DN<9>")
	)
	(segment
		(start 352.911918 -296.342562)
		(end 352.957638 -296.296842)
		(width 0.1143)
		(layer "In11.Cu")
		(net "P5E_CPU0_P1_RX_DN<9>")
	)
	(segment
		(start 347.682312 -385.13893)
		(end 347.55201 -384.995166)
		(width 0.14224)
		(layer "In11.Cu")
		(net "P5E_CPU0_P1_RX_DN<9>")
	)
	(segment
		(start 353.657916 -287.550606)
		(end 353.590606 -287.51149)
		(width 0.1143)
		(layer "In11.Cu")
		(net "P5E_CPU0_P1_RX_DN<9>")
	)
	(segment
		(start 347.55074 -387.817868)
		(end 347.571568 -387.39191)
		(width 0.14224)
		(layer "In11.Cu")
		(net "P5E_CPU0_P1_RX_DN<9>")
	)
	(segment
		(start 347.282008 -392.616944)
		(end 347.55074 -392.348466)
		(width 0.14224)
		(layer "In11.Cu")
		(net "P5E_CPU0_P1_RX_DN<9>")
	)
	(segment
		(start 348.851474 -380.187708)
		(end 348.851474 -376.747278)
		(width 0.14224)
		(layer "In11.Cu")
		(net "P5E_CPU0_P1_RX_DN<9>")
	)
	(segment
		(start 353.58832 -288.201608)
		(end 353.628198 -288.178748)
		(width 0.1143)
		(layer "In11.Cu")
		(net "P5E_CPU0_P1_RX_DN<9>")
	)
	(segment
		(start 353.58832 -286.581596)
		(end 353.628198 -286.558736)
		(width 0.1143)
		(layer "In11.Cu")
		(net "P5E_CPU0_P1_RX_DN<9>")
	)
	(segment
		(start 347.716856 -384.438398)
		(end 347.716602 -384.438398)
		(width 0.14224)
		(layer "In11.Cu")
		(net "P5E_CPU0_P1_RX_DN<9>")
	)
	(segment
		(start 353.627944 -283.318966)
		(end 353.659948 -283.30017)
		(width 0.1143)
		(layer "In11.Cu")
		(net "P5E_CPU0_P1_RX_DN<9>")
	)
	(segment
		(start 347.661484 -385.564888)
		(end 347.66123 -385.564888)
		(width 0.14224)
		(layer "In11.Cu")
		(net "P5E_CPU0_P1_RX_DN<9>")
	)
	(segment
		(start 349.285814 -375.698512)
		(end 349.964248 -375.020078)
		(width 0.14224)
		(layer "In11.Cu")
		(net "P5E_CPU0_P1_RX_DN<9>")
	)
	(segment
		(start 353.627944 -290.773104)
		(end 353.590606 -290.751514)
		(width 0.1143)
		(layer "In11.Cu")
		(net "P5E_CPU0_P1_RX_DN<9>")
	)
	(segment
		(start 353.590606 -283.340556)
		(end 353.627944 -283.318966)
		(width 0.1143)
		(layer "In11.Cu")
		(net "P5E_CPU0_P1_RX_DN<9>")
	)
	(segment
		(start 353.627944 -293.038784)
		(end 353.659948 -293.019988)
		(width 0.1143)
		(layer "In11.Cu")
		(net "P5E_CPU0_P1_RX_DN<9>")
	)
	(segment
		(start 370.551202 -354.848922)
		(end 373.257572 -348.315534)
		(width 0.14224)
		(layer "In11.Cu")
		(net "P5E_CPU0_P1_RX_DN<9>")
	)
	(segment
		(start 352.957638 -295.71188)
		(end 353.346004 -295.323514)
		(width 0.1143)
		(layer "In11.Cu")
		(net "P5E_CPU0_P1_RX_DN<9>")
	)
	(segment
		(start 353.149662 -279.273762)
		(end 353.15144 -279.272492)
		(width 0.1143)
		(layer "In11.Cu")
		(net "P5E_CPU0_P1_RX_DN<9>")
	)
	(segment
		(start 347.118686 -393.69238)
		(end 347.472 -393.787376)
		(width 0.14224)
		(layer "In11.Cu")
		(net "P5E_CPU0_P1_RX_DN<9>")
	)
	(segment
		(start 347.594174 -393.545822)
		(end 347.277182 -393.22883)
		(width 0.14224)
		(layer "In11.Cu")
		(net "P5E_CPU0_P1_RX_DN<9>")
	)
	(segment
		(start 347.462094 -386.82168)
		(end 347.606112 -386.691378)
		(width 0.14224)
		(layer "In11.Cu")
		(net "P5E_CPU0_P1_RX_DN<9>")
	)
	(segment
		(start 353.117658 -279.29205)
		(end 353.149662 -279.273762)
		(width 0.1143)
		(layer "In11.Cu")
		(net "P5E_CPU0_P1_RX_DN<9>")
	)
	(segment
		(start 353.590606 -291.440362)
		(end 353.627944 -291.418772)
		(width 0.1143)
		(layer "In11.Cu")
		(net "P5E_CPU0_P1_RX_DN<9>")
	)
	(segment
		(start 347.606112 -386.691378)
		(end 347.605858 -386.691378)
		(width 0.14224)
		(layer "In11.Cu")
		(net "P5E_CPU0_P1_RX_DN<9>")
	)
	(segment
		(start 347.496638 -386.121656)
		(end 347.517466 -385.69519)
		(width 0.14224)
		(layer "In11.Cu")
		(net "P5E_CPU0_P1_RX_DN<9>")
	)
	(segment
		(start 353.627944 -281.05354)
		(end 353.590606 -281.031696)
		(width 0.1143)
		(layer "In11.Cu")
		(net "P5E_CPU0_P1_RX_DN<9>")
	)
	(segment
		(start 352.911918 -298.370498)
		(end 352.911918 -296.37101)
		(width 0.14224)
		(layer "In11.Cu")
		(net "P5E_CPU0_P1_RX_DN<9>")
	)
	(segment
		(start 353.627944 -289.79876)
		(end 353.659948 -289.779964)
		(width 0.1143)
		(layer "In11.Cu")
		(net "P5E_CPU0_P1_RX_DN<9>")
	)
	(segment
		(start 361.940348 -314.79236)
		(end 356.082854 -306.026058)
		(width 0.14224)
		(layer "In11.Cu")
		(net "P5E_CPU0_P1_RX_DN<9>")
	)
	(segment
		(start 347.919548 -381.172212)
		(end 348.814136 -380.277624)
		(width 0.14224)
		(layer "In11.Cu")
		(net "P5E_CPU0_P1_RX_DN<9>")
	)
	(segment
		(start 347.55201 -384.995166)
		(end 347.572838 -384.5687)
		(width 0.14224)
		(layer "In11.Cu")
		(net "P5E_CPU0_P1_RX_DN<9>")
	)
	(segment
		(start 353.659694 -289.171888)
		(end 353.627944 -289.153092)
		(width 0.1143)
		(layer "In11.Cu")
		(net "P5E_CPU0_P1_RX_DN<9>")
	)
	(segment
		(start 354.094542 -277.650702)
		(end 354.098098 -277.648162)
		(width 0.1143)
		(layer "In11.Cu")
		(net "P5E_CPU0_P1_RX_DN<9>")
	)
	(segment
		(start 350.807782 -374.456198)
		(end 351.385886 -374.21693)
		(width 0.14224)
		(layer "In11.Cu")
		(net "P5E_CPU0_P1_RX_DN<9>")
	)
	(segment
		(start 347.606112 -386.689092)
		(end 347.626686 -386.26542)
		(width 0.14224)
		(layer "In11.Cu")
		(net "P5E_CPU0_P1_RX_DN<9>")
	)
	(segment
		(start 353.659694 -290.7919)
		(end 353.627944 -290.773104)
		(width 0.1143)
		(layer "In11.Cu")
		(net "P5E_CPU0_P1_RX_DN<9>")
	)
	(segment
		(start 356.082854 -306.026058)
		(end 352.911918 -298.370498)
		(width 0.14224)
		(layer "In11.Cu")
		(net "P5E_CPU0_P1_RX_DN<9>")
	)
	(segment
		(start 347.79966 -382.750314)
		(end 347.79966 -381.461772)
		(width 0.14224)
		(layer "In11.Cu")
		(net "P5E_CPU0_P1_RX_DN<9>")
	)
	(segment
		(start 347.517466 -385.69519)
		(end 347.661484 -385.564888)
		(width 0.14224)
		(layer "In11.Cu")
		(net "P5E_CPU0_P1_RX_DN<9>")
	)
	(segment
		(start 353.658424 -285.931102)
		(end 353.627944 -285.913322)
		(width 0.1143)
		(layer "In11.Cu")
		(net "P5E_CPU0_P1_RX_DN<9>")
	)
	(segment
		(start 352.911918 -296.37101)
		(end 352.911918 -296.342562)
		(width 0.1143)
		(layer "In11.Cu")
		(net "P5E_CPU0_P1_RX_DN<9>")
	)
	(segment
		(start 353.590606 -281.720544)
		(end 353.627944 -281.698954)
		(width 0.1143)
		(layer "In11.Cu")
		(net "P5E_CPU0_P1_RX_DN<9>")
	)
	(segment
		(start 347.626686 -386.26542)
		(end 347.62694 -386.26542)
		(width 0.14224)
		(layer "In11.Cu")
		(net "P5E_CPU0_P1_RX_DN<9>")
	)
	(segment
		(start 353.627944 -289.153092)
		(end 353.590606 -289.131502)
		(width 0.1143)
		(layer "In11.Cu")
		(net "P5E_CPU0_P1_RX_DN<9>")
	)
	(segment
		(start 347.571568 -387.39191)
		(end 347.441266 -387.248146)
		(width 0.14224)
		(layer "In11.Cu")
		(net "P5E_CPU0_P1_RX_DN<9>")
	)
	(segment
		(start 353.628198 -286.558736)
		(end 353.659948 -286.540194)
		(width 0.1143)
		(layer "In11.Cu")
		(net "P5E_CPU0_P1_RX_DN<9>")
	)
	(segment
		(start 353.158044 -279.268174)
		(end 353.164902 -279.264872)
		(width 0.1143)
		(layer "In11.Cu")
		(net "P5E_CPU0_P1_RX_DN<9>")
	)
	(segment
		(start 353.627944 -284.29331)
		(end 353.590606 -284.27172)
		(width 0.1143)
		(layer "In11.Cu")
		(net "P5E_CPU0_P1_RX_DN<9>")
	)
	(segment
		(start 347.62694 -386.26542)
		(end 347.496638 -386.121656)
		(width 0.14224)
		(layer "In11.Cu")
		(net "P5E_CPU0_P1_RX_DN<9>")
	)
	(segment
		(start 353.590606 -278.48052)
		(end 353.627944 -278.45893)
		(width 0.1143)
		(layer "In11.Cu")
		(net "P5E_CPU0_P1_RX_DN<9>")
	)
	(segment
		(start 353.627944 -281.698954)
		(end 353.659948 -281.680158)
		(width 0.1143)
		(layer "In11.Cu")
		(net "P5E_CPU0_P1_RX_DN<9>")
	)
	(segment
		(start 353.628198 -288.178748)
		(end 353.659948 -288.160206)
		(width 0.1143)
		(layer "In11.Cu")
		(net "P5E_CPU0_P1_RX_DN<9>")
	)
	(segment
		(start 347.572838 -384.5687)
		(end 347.716856 -384.438398)
		(width 0.14224)
		(layer "In11.Cu")
		(net "P5E_CPU0_P1_RX_DN<9>")
	)
	(segment
		(start 353.590606 -294.680386)
		(end 353.659948 -294.64)
		(width 0.1143)
		(layer "In11.Cu")
		(net "P5E_CPU0_P1_RX_DN<9>")
	)
	(segment
		(start 354.678996 -276.516084)
		(end 354.381054 -276.516084)
		(width 0.1143)
		(layer "In11.Cu")
		(net "P5E_CPU0_P1_RX_DN<9>")
	)
	(segment
		(start 353.590606 -284.960568)
		(end 353.627944 -284.938978)
		(width 0.1143)
		(layer "In11.Cu")
		(net "P5E_CPU0_P1_RX_DN<9>")
	)
	(segment
		(start 347.441266 -387.248146)
		(end 347.462094 -386.82168)
		(width 0.14224)
		(layer "In11.Cu")
		(net "P5E_CPU0_P1_RX_DN<9>")
	)
	(segment
		(start 357.698294 -369.999514)
		(end 365.924846 -361.772962)
		(width 0.14224)
		(layer "In11.Cu")
		(net "P5E_CPU0_P1_RX_DN<9>")
	)
	(segment
		(start 353.632516 -281.05608)
		(end 353.627944 -281.05354)
		(width 0.1143)
		(layer "In11.Cu")
		(net "P5E_CPU0_P1_RX_DN<9>")
	)
	(segment
		(start 353.164902 -279.264872)
		(end 353.190048 -279.25014)
		(width 0.1143)
		(layer "In11.Cu")
		(net "P5E_CPU0_P1_RX_DN<9>")
	)
	(segment
		(start 353.190556 -280.263092)
		(end 353.189286 -280.26233)
		(width 0.1143)
		(layer "In11.Cu")
		(net "P5E_CPU0_P1_RX_DN<9>")
	)
	(segment
		(start 354.53066 -276.860508)
		(end 354.567998 -276.838918)
		(width 0.1143)
		(layer "In11.Cu")
		(net "P5E_CPU0_P1_RX_DN<9>")
	)
	(segment
		(start 368.877596 -323.245226)
		(end 361.940348 -314.79236)
		(width 0.14224)
		(layer "In11.Cu")
		(net "P5E_CPU0_P1_RX_DN<9>")
	)
	(segment
		(start 353.627944 -294.013128)
		(end 353.590606 -293.991538)
		(width 0.1143)
		(layer "In11.Cu")
		(net "P5E_CPU0_P1_RX_DN<9>")
	)
	(segment
		(start 352.957638 -296.296842)
		(end 352.957638 -295.71188)
		(width 0.1143)
		(layer "In11.Cu")
		(net "P5E_CPU0_P1_RX_DN<9>")
	)
	(segment
		(start 347.277182 -393.22883)
		(end 347.282008 -392.616944)
		(width 0.14224)
		(layer "In11.Cu")
		(net "P5E_CPU0_P1_RX_DN<9>")
	)
	(segment
		(start 353.15144 -279.272492)
		(end 353.158044 -279.268174)
		(width 0.1143)
		(layer "In11.Cu")
		(net "P5E_CPU0_P1_RX_DN<9>")
	)
	(segment
		(start 347.682058 -385.13893)
		(end 347.682312 -385.13893)
		(width 0.14224)
		(layer "In11.Cu")
		(net "P5E_CPU0_P1_RX_DN<9>")
	)
	(segment
		(start 353.222814 -280.284682)
		(end 353.192588 -280.264616)
		(width 0.1143)
		(layer "In11.Cu")
		(net "P5E_CPU0_P1_RX_DN<9>")
	)
	(segment
		(start 354.103178 -277.645622)
		(end 354.104956 -277.64486)
		(width 0.1143)
		(layer "In11.Cu")
		(net "P5E_CPU0_P1_RX_DN<9>")
	)
	(segment
		(start 373.257572 -348.315534)
		(end 373.257572 -339.57006)
		(width 0.14224)
		(layer "In11.Cu")
		(net "P5E_CPU0_P1_RX_DN<9>")
	)
	(segment
		(start 347.472508 -393.786868)
		(end 347.594174 -393.716764)
		(width 0.14224)
		(layer "In11.Cu")
		(net "P5E_CPU0_P1_RX_DN<9>")
	)
	(segment
		(start 353.659694 -284.312106)
		(end 353.627944 -284.29331)
		(width 0.1143)
		(layer "In11.Cu")
		(net "P5E_CPU0_P1_RX_DN<9>")
	)
	(segment
		(start 347.716602 -384.438398)
		(end 347.79966 -382.750314)
		(width 0.14224)
		(layer "In11.Cu")
		(net "P5E_CPU0_P1_RX_DN<9>")
	)
	(segment
		(start 353.346004 -280.566114)
		(end 353.346004 -280.520394)
		(width 0.1143)
		(layer "In11.Cu")
		(net "P5E_CPU0_P1_RX_DN<9>")
	)
	(segment
		(start 353.627944 -292.393116)
		(end 353.590606 -292.371526)
		(width 0.1143)
		(layer "In11.Cu")
		(net "P5E_CPU0_P1_RX_DN<9>")
	)
	(segment
		(start 354.567998 -276.838918)
		(end 354.600002 -276.820122)
		(width 0.1143)
		(layer "In11.Cu")
		(net "P5E_CPU0_P1_RX_DN<9>")
	)
	(arc
		(start 353.590606 -287.51149)
		(mid 353.410814 -287.308902)
		(end 353.346004 -287.045908)
		(width 0.1143)
		(layer "In11.Cu")
		(net "P5E_CPU0_P1_RX_DN<9>")
	)
	(arc
		(start 353.346004 -278.946102)
		(mid 353.410822 -278.683113)
		(end 353.590606 -278.48052)
		(width 0.1143)
		(layer "In11.Cu")
		(net "P5E_CPU0_P1_RX_DN<9>")
	)
	(arc
		(start 354.600002 -276.820122)
		(mid 354.697003 -276.717464)
		(end 354.7491 -276.586188)
		(width 0.1143)
		(layer "In11.Cu")
		(net "P5E_CPU0_P1_RX_DN<9>")
	)
	(arc
		(start 353.659948 -278.440134)
		(mid 353.774624 -278.306943)
		(end 353.815904 -278.136096)
		(width 0.1143)
		(layer "In11.Cu")
		(net "P5E_CPU0_P1_RX_DN<9>")
	)
	(arc
		(start 353.590606 -284.27172)
		(mid 353.345785 -283.806138)
		(end 353.590606 -283.340556)
		(width 0.1143)
		(layer "In11.Cu")
		(net "P5E_CPU0_P1_RX_DN<9>")
	)
	(arc
		(start 349.964248 -375.020078)
		(mid 350.358248 -374.696602)
		(end 350.807782 -374.456198)
		(width 0.14224)
		(layer "In11.Cu")
		(net "P5E_CPU0_P1_RX_DN<9>")
	)
	(arc
		(start 353.659948 -291.399976)
		(mid 353.815775 -291.095835)
		(end 353.659694 -290.7919)
		(width 0.1143)
		(layer "In11.Cu")
		(net "P5E_CPU0_P1_RX_DN<9>")
	)
	(arc
		(start 353.590606 -293.991538)
		(mid 353.345785 -293.525956)
		(end 353.590606 -293.060374)
		(width 0.1143)
		(layer "In11.Cu")
		(net "P5E_CPU0_P1_RX_DN<9>")
	)
	(arc
		(start 353.590606 -290.751514)
		(mid 353.345785 -290.285932)
		(end 353.590606 -289.82035)
		(width 0.1143)
		(layer "In11.Cu")
		(net "P5E_CPU0_P1_RX_DN<9>")
	)
	(arc
		(start 348.814136 -380.277624)
		(mid 348.841755 -380.236384)
		(end 348.851474 -380.187708)
		(width 0.14224)
		(layer "In11.Cu")
		(net "P5E_CPU0_P1_RX_DN<9>")
	)
	(arc
		(start 353.659948 -284.920182)
		(mid 353.815775 -284.616041)
		(end 353.659694 -284.312106)
		(width 0.1143)
		(layer "In11.Cu")
		(net "P5E_CPU0_P1_RX_DN<9>")
	)
	(arc
		(start 353.659948 -288.160206)
		(mid 353.774624 -288.027015)
		(end 353.815904 -287.856168)
		(width 0.1143)
		(layer "In11.Cu")
		(net "P5E_CPU0_P1_RX_DN<9>")
	)
	(arc
		(start 353.590606 -292.371526)
		(mid 353.345785 -291.905944)
		(end 353.590606 -291.440362)
		(width 0.1143)
		(layer "In11.Cu")
		(net "P5E_CPU0_P1_RX_DN<9>")
	)
	(arc
		(start 347.79966 -381.461772)
		(mid 347.830812 -381.305069)
		(end 347.919548 -381.172212)
		(width 0.14224)
		(layer "In11.Cu")
		(net "P5E_CPU0_P1_RX_DN<9>")
	)
	(arc
		(start 353.659948 -286.540194)
		(mid 353.815775 -286.235802)
		(end 353.65944 -285.93161)
		(width 0.1143)
		(layer "In11.Cu")
		(net "P5E_CPU0_P1_RX_DN<9>")
	)
	(arc
		(start 354.130102 -277.630128)
		(mid 354.244778 -277.496937)
		(end 354.286058 -277.32609)
		(width 0.1143)
		(layer "In11.Cu")
		(net "P5E_CPU0_P1_RX_DN<9>")
	)
	(arc
		(start 351.385886 -374.21693)
		(mid 354.749829 -372.419156)
		(end 357.698294 -369.999514)
		(width 0.14224)
		(layer "In11.Cu")
		(net "P5E_CPU0_P1_RX_DN<9>")
	)
	(arc
		(start 353.346004 -280.520394)
		(mid 353.313343 -280.387421)
		(end 353.222814 -280.284682)
		(width 0.1143)
		(layer "In11.Cu")
		(net "P5E_CPU0_P1_RX_DN<9>")
	)
	(arc
		(start 353.590606 -285.891732)
		(mid 353.345785 -285.42615)
		(end 353.590606 -284.960568)
		(width 0.1143)
		(layer "In11.Cu")
		(net "P5E_CPU0_P1_RX_DN<9>")
	)
	(arc
		(start 353.659948 -294.64)
		(mid 353.815775 -294.335859)
		(end 353.659694 -294.031924)
		(width 0.1143)
		(layer "In11.Cu")
		(net "P5E_CPU0_P1_RX_DN<9>")
	)
	(arc
		(start 353.590606 -281.031696)
		(mid 353.410814 -280.829108)
		(end 353.346004 -280.566114)
		(width 0.1143)
		(layer "In11.Cu")
		(net "P5E_CPU0_P1_RX_DN<9>")
	)
	(arc
		(start 353.346004 -287.045908)
		(mid 353.41018 -286.784021)
		(end 353.58832 -286.581596)
		(width 0.1143)
		(layer "In11.Cu")
		(net "P5E_CPU0_P1_RX_DN<9>")
	)
	(arc
		(start 353.190048 -279.25014)
		(mid 353.304724 -279.116949)
		(end 353.346004 -278.946102)
		(width 0.1143)
		(layer "In11.Cu")
		(net "P5E_CPU0_P1_RX_DN<9>")
	)
	(arc
		(start 353.815904 -287.856168)
		(mid 353.774064 -287.684182)
		(end 353.657916 -287.550606)
		(width 0.1143)
		(layer "In11.Cu")
		(net "P5E_CPU0_P1_RX_DN<9>")
	)
	(arc
		(start 354.286058 -277.32609)
		(mid 354.350876 -277.063101)
		(end 354.53066 -276.860508)
		(width 0.1143)
		(layer "In11.Cu")
		(net "P5E_CPU0_P1_RX_DN<9>")
	)
	(arc
		(start 353.815904 -278.136096)
		(mid 353.880422 -277.873554)
		(end 354.05949 -277.671022)
		(width 0.1143)
		(layer "In11.Cu")
		(net "P5E_CPU0_P1_RX_DN<9>")
	)
	(arc
		(start 353.590606 -289.131502)
		(mid 353.410814 -288.928914)
		(end 353.346004 -288.66592)
		(width 0.1143)
		(layer "In11.Cu")
		(net "P5E_CPU0_P1_RX_DN<9>")
	)
	(arc
		(start 353.346004 -295.145968)
		(mid 353.410822 -294.882979)
		(end 353.590606 -294.680386)
		(width 0.1143)
		(layer "In11.Cu")
		(net "P5E_CPU0_P1_RX_DN<9>")
	)
	(arc
		(start 353.117658 -280.220166)
		(mid 352.887522 -279.756108)
		(end 353.117658 -279.29205)
		(width 0.1143)
		(layer "In11.Cu")
		(net "P5E_CPU0_P1_RX_DN<9>")
	)
	(arc
		(start 365.924846 -361.772962)
		(mid 368.579022 -358.53878)
		(end 370.551202 -354.848922)
		(width 0.14224)
		(layer "In11.Cu")
		(net "P5E_CPU0_P1_RX_DN<9>")
	)
	(arc
		(start 353.659948 -283.30017)
		(mid 353.815775 -282.996029)
		(end 353.659694 -282.692094)
		(width 0.1143)
		(layer "In11.Cu")
		(net "P5E_CPU0_P1_RX_DN<9>")
	)
	(arc
		(start 353.659948 -293.019988)
		(mid 353.815775 -292.715847)
		(end 353.659694 -292.411912)
		(width 0.1143)
		(layer "In11.Cu")
		(net "P5E_CPU0_P1_RX_DN<9>")
	)
	(arc
		(start 353.659948 -289.779964)
		(mid 353.815775 -289.475823)
		(end 353.659694 -289.171888)
		(width 0.1143)
		(layer "In11.Cu")
		(net "P5E_CPU0_P1_RX_DN<9>")
	)
	(arc
		(start 353.659948 -281.680158)
		(mid 353.815775 -281.376017)
		(end 353.659694 -281.072082)
		(width 0.1143)
		(layer "In11.Cu")
		(net "P5E_CPU0_P1_RX_DN<9>")
	)
	(arc
		(start 348.851474 -376.747278)
		(mid 348.964354 -376.179704)
		(end 349.285814 -375.698512)
		(width 0.14224)
		(layer "In11.Cu")
		(net "P5E_CPU0_P1_RX_DN<9>")
	)
	(arc
		(start 353.590606 -282.651708)
		(mid 353.345785 -282.186126)
		(end 353.590606 -281.720544)
		(width 0.1143)
		(layer "In11.Cu")
		(net "P5E_CPU0_P1_RX_DN<9>")
	)
	(arc
		(start 353.346004 -288.66592)
		(mid 353.41018 -288.404033)
		(end 353.58832 -288.201608)
		(width 0.1143)
		(layer "In11.Cu")
		(net "P5E_CPU0_P1_RX_DN<9>")
	)
	(segment
		(start 345.39809 -393.69238)
		(end 345.91879 -393.69238)
		(width 0.127)
		(layer "F.Cu")
		(net "P5E_CPU0_P1_RX_DN<8>")
	)
	(segment
		(start 352.027998 -274.630134)
		(end 351.561146 -274.896072)
		(width 0.12954)
		(layer "F.Cu")
		(net "P5E_CPU0_P1_RX_DN<8>")
	)
	(segment
		(start 352.718878 -286.540956)
		(end 352.721672 -286.538924)
		(width 0.1143)
		(layer "In11.Cu")
		(net "P5E_CPU0_P1_RX_DN<8>")
	)
	(segment
		(start 352.685604 -293.040054)
		(end 352.688144 -293.03853)
		(width 0.1143)
		(layer "In11.Cu")
		(net "P5E_CPU0_P1_RX_DN<8>")
	)
	(segment
		(start 371.242844 -333.702152)
		(end 370.169694 -327.730104)
		(width 0.14224)
		(layer "In11.Cu")
		(net "P5E_CPU0_P1_RX_DN<8>")
	)
	(segment
		(start 346.38615 -392.312906)
		(end 346.38615 -390.36498)
		(width 0.14224)
		(layer "In11.Cu")
		(net "P5E_CPU0_P1_RX_DN<8>")
	)
	(segment
		(start 352.718116 -286.541464)
		(end 352.718878 -286.540956)
		(width 0.1143)
		(layer "In11.Cu")
		(net "P5E_CPU0_P1_RX_DN<8>")
	)
	(segment
		(start 352.719894 -284.311852)
		(end 352.649028 -284.270704)
		(width 0.1143)
		(layer "In11.Cu")
		(net "P5E_CPU0_P1_RX_DN<8>")
	)
	(segment
		(start 352.688906 -289.153854)
		(end 352.687128 -289.152838)
		(width 0.1143)
		(layer "In11.Cu")
		(net "P5E_CPU0_P1_RX_DN<8>")
	)
	(segment
		(start 352.687128 -292.392862)
		(end 352.685604 -292.391846)
		(width 0.1143)
		(layer "In11.Cu")
		(net "P5E_CPU0_P1_RX_DN<8>")
	)
	(segment
		(start 352.649028 -283.341572)
		(end 352.719894 -283.300424)
		(width 0.1143)
		(layer "In11.Cu")
		(net "P5E_CPU0_P1_RX_DN<8>")
	)
	(segment
		(start 371.24259 -333.702152)
		(end 371.242844 -333.702152)
		(width 0.14224)
		(layer "In11.Cu")
		(net "P5E_CPU0_P1_RX_DN<8>")
	)
	(segment
		(start 352.67773 -293.044626)
		(end 352.684588 -293.040562)
		(width 0.1143)
		(layer "In11.Cu")
		(net "P5E_CPU0_P1_RX_DN<8>")
	)
	(segment
		(start 346.24899 -387.9723)
		(end 346.24899 -387.54558)
		(width 0.14224)
		(layer "In11.Cu")
		(net "P5E_CPU0_P1_RX_DN<8>")
	)
	(segment
		(start 346.24899 -389.10006)
		(end 346.24899 -388.67334)
		(width 0.14224)
		(layer "In11.Cu")
		(net "P5E_CPU0_P1_RX_DN<8>")
	)
	(segment
		(start 352.688906 -290.773866)
		(end 352.687128 -290.77285)
		(width 0.1143)
		(layer "In11.Cu")
		(net "P5E_CPU0_P1_RX_DN<8>")
	)
	(segment
		(start 352.687128 -290.77285)
		(end 352.685604 -290.771834)
		(width 0.1143)
		(layer "In11.Cu")
		(net "P5E_CPU0_P1_RX_DN<8>")
	)
	(segment
		(start 352.685604 -291.420042)
		(end 352.688144 -291.418518)
		(width 0.1143)
		(layer "In11.Cu")
		(net "P5E_CPU0_P1_RX_DN<8>")
	)
	(segment
		(start 352.649028 -288.201354)
		(end 352.721672 -288.158936)
		(width 0.1143)
		(layer "In11.Cu")
		(net "P5E_CPU0_P1_RX_DN<8>")
	)
	(segment
		(start 346.922852 -378.957586)
		(end 346.588842 -378.819664)
		(width 0.14224)
		(layer "In11.Cu")
		(net "P5E_CPU0_P1_RX_DN<8>")
	)
	(segment
		(start 352.719894 -277.831804)
		(end 352.649028 -277.790656)
		(width 0.1143)
		(layer "In11.Cu")
		(net "P5E_CPU0_P1_RX_DN<8>")
	)
	(segment
		(start 346.38615 -388.10946)
		(end 346.24899 -387.9723)
		(width 0.14224)
		(layer "In11.Cu")
		(net "P5E_CPU0_P1_RX_DN<8>")
	)
	(segment
		(start 352.685096 -286.560768)
		(end 352.718116 -286.541464)
		(width 0.1143)
		(layer "In11.Cu")
		(net "P5E_CPU0_P1_RX_DN<8>")
	)
	(segment
		(start 352.676968 -289.80511)
		(end 352.67773 -289.804602)
		(width 0.1143)
		(layer "In11.Cu")
		(net "P5E_CPU0_P1_RX_DN<8>")
	)
	(segment
		(start 357.08844 -369.229386)
		(end 364.430056 -361.88777)
		(width 0.14224)
		(layer "In11.Cu")
		(net "P5E_CPU0_P1_RX_DN<8>")
	)
	(segment
		(start 361.19181 -315.350144)
		(end 355.256592 -306.467764)
		(width 0.14224)
		(layer "In11.Cu")
		(net "P5E_CPU0_P1_RX_DN<8>")
	)
	(segment
		(start 352.719894 -282.69184)
		(end 352.649028 -282.650692)
		(width 0.1143)
		(layer "In11.Cu")
		(net "P5E_CPU0_P1_RX_DN<8>")
	)
	(segment
		(start 352.649028 -284.961584)
		(end 352.719894 -284.920436)
		(width 0.1143)
		(layer "In11.Cu")
		(net "P5E_CPU0_P1_RX_DN<8>")
	)
	(segment
		(start 351.966784 -298.525184)
		(end 351.966784 -296.37101)
		(width 0.14224)
		(layer "In11.Cu")
		(net "P5E_CPU0_P1_RX_DN<8>")
	)
	(segment
		(start 345.52636 -378.230638)
		(end 345.517978 -378.218192)
		(width 0.14224)
		(layer "In11.Cu")
		(net "P5E_CPU0_P1_RX_DN<8>")
	)
	(segment
		(start 352.685604 -289.151822)
		(end 352.649028 -289.130486)
		(width 0.1143)
		(layer "In11.Cu")
		(net "P5E_CPU0_P1_RX_DN<8>")
	)
	(segment
		(start 370.068602 -353.44862)
		(end 372.315994 -348.02318)
		(width 0.14224)
		(layer "In11.Cu")
		(net "P5E_CPU0_P1_RX_DN<8>")
	)
	(segment
		(start 352.720656 -294.032432)
		(end 352.720656 -294.032178)
		(width 0.1143)
		(layer "In11.Cu")
		(net "P5E_CPU0_P1_RX_DN<8>")
	)
	(segment
		(start 351.966784 -296.37101)
		(end 351.966784 -296.342562)
		(width 0.1143)
		(layer "In11.Cu")
		(net "P5E_CPU0_P1_RX_DN<8>")
	)
	(segment
		(start 345.532964 -378.240798)
		(end 345.52636 -378.230892)
		(width 0.14224)
		(layer "In11.Cu")
		(net "P5E_CPU0_P1_RX_DN<8>")
	)
	(segment
		(start 352.248724 -275.401278)
		(end 352.179128 -275.360638)
		(width 0.1143)
		(layer "In11.Cu")
		(net "P5E_CPU0_P1_RX_DN<8>")
	)
	(segment
		(start 352.688144 -293.03853)
		(end 352.688906 -293.038022)
		(width 0.1143)
		(layer "In11.Cu")
		(net "P5E_CPU0_P1_RX_DN<8>")
	)
	(segment
		(start 346.272104 -393.787376)
		(end 346.272612 -393.786868)
		(width 0.14224)
		(layer "In11.Cu")
		(net "P5E_CPU0_P1_RX_DN<8>")
	)
	(segment
		(start 351.859088 -274.896072)
		(end 351.561146 -274.896072)
		(width 0.1143)
		(layer "In11.Cu")
		(net "P5E_CPU0_P1_RX_DN<8>")
	)
	(segment
		(start 346.38615 -388.53618)
		(end 346.38615 -388.10946)
		(width 0.14224)
		(layer "In11.Cu")
		(net "P5E_CPU0_P1_RX_DN<8>")
	)
	(segment
		(start 352.688144 -289.798506)
		(end 352.688906 -289.797998)
		(width 0.1143)
		(layer "In11.Cu")
		(net "P5E_CPU0_P1_RX_DN<8>")
	)
	(segment
		(start 352.720656 -294.032178)
		(end 352.719132 -294.031162)
		(width 0.1143)
		(layer "In11.Cu")
		(net "P5E_CPU0_P1_RX_DN<8>")
	)
	(segment
		(start 352.720656 -294.639746)
		(end 352.720656 -294.639492)
		(width 0.1143)
		(layer "In11.Cu")
		(net "P5E_CPU0_P1_RX_DN<8>")
	)
	(segment
		(start 346.272612 -393.786868)
		(end 346.394278 -393.716764)
		(width 0.14224)
		(layer "In11.Cu")
		(net "P5E_CPU0_P1_RX_DN<8>")
	)
	(segment
		(start 352.649028 -281.72156)
		(end 352.719894 -281.680412)
		(width 0.1143)
		(layer "In11.Cu")
		(net "P5E_CPU0_P1_RX_DN<8>")
	)
	(segment
		(start 352.719894 -276.211792)
		(end 352.649028 -276.170644)
		(width 0.1143)
		(layer "In11.Cu")
		(net "P5E_CPU0_P1_RX_DN<8>")
	)
	(segment
		(start 352.688906 -292.393878)
		(end 352.687128 -292.392862)
		(width 0.1143)
		(layer "In11.Cu")
		(net "P5E_CPU0_P1_RX_DN<8>")
	)
	(segment
		(start 352.684588 -291.42055)
		(end 352.685604 -291.420042)
		(width 0.1143)
		(layer "In11.Cu")
		(net "P5E_CPU0_P1_RX_DN<8>")
	)
	(segment
		(start 351.966784 -296.342562)
		(end 352.012504 -296.296842)
		(width 0.1143)
		(layer "In11.Cu")
		(net "P5E_CPU0_P1_RX_DN<8>")
	)
	(segment
		(start 352.649028 -276.861524)
		(end 352.719894 -276.820376)
		(width 0.1143)
		(layer "In11.Cu")
		(net "P5E_CPU0_P1_RX_DN<8>")
	)
	(segment
		(start 346.24899 -387.54558)
		(end 346.38615 -387.40842)
		(width 0.14224)
		(layer "In11.Cu")
		(net "P5E_CPU0_P1_RX_DN<8>")
	)
	(segment
		(start 352.688906 -291.41801)
		(end 352.719894 -291.40023)
		(width 0.1143)
		(layer "In11.Cu")
		(net "P5E_CPU0_P1_RX_DN<8>")
	)
	(segment
		(start 352.649028 -278.481536)
		(end 352.719894 -278.440388)
		(width 0.1143)
		(layer "In11.Cu")
		(net "P5E_CPU0_P1_RX_DN<8>")
	)
	(segment
		(start 352.649028 -291.441378)
		(end 352.676968 -291.425122)
		(width 0.1143)
		(layer "In11.Cu")
		(net "P5E_CPU0_P1_RX_DN<8>")
	)
	(segment
		(start 346.24899 -389.8011)
		(end 346.38615 -389.66394)
		(width 0.14224)
		(layer "In11.Cu")
		(net "P5E_CPU0_P1_RX_DN<8>")
	)
	(segment
		(start 345.72067 -376.432572)
		(end 346.066618 -376.086624)
		(width 0.14224)
		(layer "In11.Cu")
		(net "P5E_CPU0_P1_RX_DN<8>")
	)
	(segment
		(start 346.394278 -393.716764)
		(end 346.394278 -393.545822)
		(width 0.14224)
		(layer "In11.Cu")
		(net "P5E_CPU0_P1_RX_DN<8>")
	)
	(segment
		(start 352.685604 -287.532064)
		(end 352.684588 -287.531556)
		(width 0.1143)
		(layer "In11.Cu")
		(net "P5E_CPU0_P1_RX_DN<8>")
	)
	(segment
		(start 352.405696 -295.399714)
		(end 352.405696 -295.145968)
		(width 0.1143)
		(layer "In11.Cu")
		(net "P5E_CPU0_P1_RX_DN<8>")
	)
	(segment
		(start 372.315994 -339.674454)
		(end 371.24259 -333.702152)
		(width 0.14224)
		(layer "In11.Cu")
		(net "P5E_CPU0_P1_RX_DN<8>")
	)
	(segment
		(start 346.24899 -388.67334)
		(end 346.38615 -388.53618)
		(width 0.14224)
		(layer "In11.Cu")
		(net "P5E_CPU0_P1_RX_DN<8>")
	)
	(segment
		(start 346.38615 -387.40842)
		(end 346.38615 -385.952492)
		(width 0.14224)
		(layer "In11.Cu")
		(net "P5E_CPU0_P1_RX_DN<8>")
	)
	(segment
		(start 351.941892 -274.978876)
		(end 351.859088 -274.896072)
		(width 0.1143)
		(layer "In11.Cu")
		(net "P5E_CPU0_P1_RX_DN<8>")
	)
	(segment
		(start 352.684588 -287.531556)
		(end 352.65614 -287.515046)
		(width 0.1143)
		(layer "In11.Cu")
		(net "P5E_CPU0_P1_RX_DN<8>")
	)
	(segment
		(start 372.315994 -348.02318)
		(end 372.315994 -339.674454)
		(width 0.14224)
		(layer "In11.Cu")
		(net "P5E_CPU0_P1_RX_DN<8>")
	)
	(segment
		(start 368.09553 -323.762116)
		(end 361.19181 -315.350144)
		(width 0.14224)
		(layer "In11.Cu")
		(net "P5E_CPU0_P1_RX_DN<8>")
	)
	(segment
		(start 352.676968 -291.425122)
		(end 352.67773 -291.424614)
		(width 0.1143)
		(layer "In11.Cu")
		(net "P5E_CPU0_P1_RX_DN<8>")
	)
	(segment
		(start 346.394278 -393.545822)
		(end 346.077286 -393.22883)
		(width 0.14224)
		(layer "In11.Cu")
		(net "P5E_CPU0_P1_RX_DN<8>")
	)
	(segment
		(start 352.719894 -281.071828)
		(end 352.649028 -281.03068)
		(width 0.1143)
		(layer "In11.Cu")
		(net "P5E_CPU0_P1_RX_DN<8>")
	)
	(segment
		(start 352.719894 -292.411658)
		(end 352.688906 -292.393878)
		(width 0.1143)
		(layer "In11.Cu")
		(net "P5E_CPU0_P1_RX_DN<8>")
	)
	(segment
		(start 352.719132 -294.031162)
		(end 352.649536 -293.99103)
		(width 0.1143)
		(layer "In11.Cu")
		(net "P5E_CPU0_P1_RX_DN<8>")
	)
	(segment
		(start 352.649028 -293.06139)
		(end 352.676968 -293.045134)
		(width 0.1143)
		(layer "In11.Cu")
		(net "P5E_CPU0_P1_RX_DN<8>")
	)
	(segment
		(start 346.38615 -389.23722)
		(end 346.24899 -389.10006)
		(width 0.14224)
		(layer "In11.Cu")
		(net "P5E_CPU0_P1_RX_DN<8>")
	)
	(segment
		(start 352.688144 -291.418518)
		(end 352.688906 -291.41801)
		(width 0.1143)
		(layer "In11.Cu")
		(net "P5E_CPU0_P1_RX_DN<8>")
	)
	(segment
		(start 352.40595 -295.399968)
		(end 352.405696 -295.399714)
		(width 0.1143)
		(layer "In11.Cu")
		(net "P5E_CPU0_P1_RX_DN<8>")
	)
	(segment
		(start 345.52636 -378.230892)
		(end 345.52636 -378.230638)
		(width 0.14224)
		(layer "In11.Cu")
		(net "P5E_CPU0_P1_RX_DN<8>")
	)
	(segment
		(start 370.169694 -327.730104)
		(end 368.09553 -323.762116)
		(width 0.14224)
		(layer "In11.Cu")
		(net "P5E_CPU0_P1_RX_DN<8>")
	)
	(segment
		(start 352.685604 -290.771834)
		(end 352.649028 -290.750498)
		(width 0.1143)
		(layer "In11.Cu")
		(net "P5E_CPU0_P1_RX_DN<8>")
	)
	(segment
		(start 352.687128 -287.53308)
		(end 352.685604 -287.532064)
		(width 0.1143)
		(layer "In11.Cu")
		(net "P5E_CPU0_P1_RX_DN<8>")
	)
	(segment
		(start 345.449652 -377.990862)
		(end 345.449652 -377.086876)
		(width 0.14224)
		(layer "In11.Cu")
		(net "P5E_CPU0_P1_RX_DN<8>")
	)
	(segment
		(start 352.649028 -289.821366)
		(end 352.676968 -289.80511)
		(width 0.1143)
		(layer "In11.Cu")
		(net "P5E_CPU0_P1_RX_DN<8>")
	)
	(segment
		(start 346.38615 -390.36498)
		(end 346.24899 -390.22782)
		(width 0.14224)
		(layer "In11.Cu")
		(net "P5E_CPU0_P1_RX_DN<8>")
	)
	(segment
		(start 352.179128 -279.291542)
		(end 352.248724 -279.250902)
		(width 0.1143)
		(layer "In11.Cu")
		(net "P5E_CPU0_P1_RX_DN<8>")
	)
	(segment
		(start 352.685604 -292.391846)
		(end 352.649028 -292.37051)
		(width 0.1143)
		(layer "In11.Cu")
		(net "P5E_CPU0_P1_RX_DN<8>")
	)
	(segment
		(start 347.149674 -380.282958)
		(end 347.149674 -379.786388)
		(width 0.14224)
		(layer "In11.Cu")
		(net "P5E_CPU0_P1_RX_DN<8>")
	)
	(segment
		(start 352.689922 -287.534604)
		(end 352.687128 -287.53308)
		(width 0.1143)
		(layer "In11.Cu")
		(net "P5E_CPU0_P1_RX_DN<8>")
	)
	(segment
		(start 352.684588 -289.800538)
		(end 352.685604 -289.80003)
		(width 0.1143)
		(layer "In11.Cu")
		(net "P5E_CPU0_P1_RX_DN<8>")
	)
	(segment
		(start 355.256592 -306.467764)
		(end 351.966784 -298.525184)
		(width 0.14224)
		(layer "In11.Cu")
		(net "P5E_CPU0_P1_RX_DN<8>")
	)
	(segment
		(start 352.684588 -293.040562)
		(end 352.685604 -293.040054)
		(width 0.1143)
		(layer "In11.Cu")
		(net "P5E_CPU0_P1_RX_DN<8>")
	)
	(segment
		(start 346.48394 -383.96037)
		(end 346.48394 -381.289052)
		(width 0.14224)
		(layer "In11.Cu")
		(net "P5E_CPU0_P1_RX_DN<8>")
	)
	(segment
		(start 346.603828 -380.999492)
		(end 347.02877 -380.57455)
		(width 0.14224)
		(layer "In11.Cu")
		(net "P5E_CPU0_P1_RX_DN<8>")
	)
	(segment
		(start 352.687128 -289.152838)
		(end 352.685604 -289.151822)
		(width 0.1143)
		(layer "In11.Cu")
		(net "P5E_CPU0_P1_RX_DN<8>")
	)
	(segment
		(start 348.98457 -374.136666)
		(end 350.983042 -373.30888)
		(width 0.14224)
		(layer "In11.Cu")
		(net "P5E_CPU0_P1_RX_DN<8>")
	)
	(segment
		(start 352.012504 -296.296842)
		(end 352.012504 -295.793414)
		(width 0.1143)
		(layer "In11.Cu")
		(net "P5E_CPU0_P1_RX_DN<8>")
	)
	(segment
		(start 346.38615 -389.66394)
		(end 346.38615 -389.23722)
		(width 0.14224)
		(layer "In11.Cu")
		(net "P5E_CPU0_P1_RX_DN<8>")
	)
	(segment
		(start 352.719894 -285.931864)
		(end 352.649028 -285.890716)
		(width 0.1143)
		(layer "In11.Cu")
		(net "P5E_CPU0_P1_RX_DN<8>")
	)
	(segment
		(start 352.719894 -290.791646)
		(end 352.688906 -290.773866)
		(width 0.1143)
		(layer "In11.Cu")
		(net "P5E_CPU0_P1_RX_DN<8>")
	)
	(segment
		(start 346.24899 -390.22782)
		(end 346.24899 -389.8011)
		(width 0.14224)
		(layer "In11.Cu")
		(net "P5E_CPU0_P1_RX_DN<8>")
	)
	(segment
		(start 352.719894 -289.171634)
		(end 352.688906 -289.153854)
		(width 0.1143)
		(layer "In11.Cu")
		(net "P5E_CPU0_P1_RX_DN<8>")
	)
	(segment
		(start 352.67773 -289.804602)
		(end 352.684588 -289.800538)
		(width 0.1143)
		(layer "In11.Cu")
		(net "P5E_CPU0_P1_RX_DN<8>")
	)
	(segment
		(start 352.685604 -289.80003)
		(end 352.688144 -289.798506)
		(width 0.1143)
		(layer "In11.Cu")
		(net "P5E_CPU0_P1_RX_DN<8>")
	)
	(segment
		(start 346.38615 -385.952492)
		(end 346.48394 -383.96037)
		(width 0.14224)
		(layer "In11.Cu")
		(net "P5E_CPU0_P1_RX_DN<8>")
	)
	(segment
		(start 352.688906 -293.038022)
		(end 352.719894 -293.020242)
		(width 0.1143)
		(layer "In11.Cu")
		(net "P5E_CPU0_P1_RX_DN<8>")
	)
	(segment
		(start 352.012504 -295.793414)
		(end 352.40595 -295.399968)
		(width 0.1143)
		(layer "In11.Cu")
		(net "P5E_CPU0_P1_RX_DN<8>")
	)
	(segment
		(start 352.248724 -280.261314)
		(end 352.179128 -280.220674)
		(width 0.1143)
		(layer "In11.Cu")
		(net "P5E_CPU0_P1_RX_DN<8>")
	)
	(segment
		(start 352.67773 -291.424614)
		(end 352.684588 -291.42055)
		(width 0.1143)
		(layer "In11.Cu")
		(net "P5E_CPU0_P1_RX_DN<8>")
	)
	(segment
		(start 346.082112 -392.61669)
		(end 346.38615 -392.312906)
		(width 0.14224)
		(layer "In11.Cu")
		(net "P5E_CPU0_P1_RX_DN<8>")
	)
	(segment
		(start 352.649028 -294.681402)
		(end 352.720656 -294.639746)
		(width 0.1143)
		(layer "In11.Cu")
		(net "P5E_CPU0_P1_RX_DN<8>")
	)
	(segment
		(start 352.688906 -289.797998)
		(end 352.719894 -289.780218)
		(width 0.1143)
		(layer "In11.Cu")
		(net "P5E_CPU0_P1_RX_DN<8>")
	)
	(segment
		(start 352.676968 -293.045134)
		(end 352.67773 -293.044626)
		(width 0.1143)
		(layer "In11.Cu")
		(net "P5E_CPU0_P1_RX_DN<8>")
	)
	(segment
		(start 352.65614 -287.515046)
		(end 352.651568 -287.512252)
		(width 0.1143)
		(layer "In11.Cu")
		(net "P5E_CPU0_P1_RX_DN<8>")
	)
	(segment
		(start 345.91879 -393.69238)
		(end 346.272104 -393.787376)
		(width 0.14224)
		(layer "In11.Cu")
		(net "P5E_CPU0_P1_RX_DN<8>")
	)
	(segment
		(start 346.077286 -393.22883)
		(end 346.082112 -392.61669)
		(width 0.14224)
		(layer "In11.Cu")
		(net "P5E_CPU0_P1_RX_DN<8>")
	)
	(arc
		(start 352.505264 -294.82542)
		(mid 352.570616 -294.746893)
		(end 352.649028 -294.681402)
		(width 0.1143)
		(layer "In11.Cu")
		(net "P5E_CPU0_P1_RX_DN<8>")
	)
	(arc
		(start 352.719894 -283.300424)
		(mid 352.871483 -282.996132)
		(end 352.719894 -282.69184)
		(width 0.1143)
		(layer "In11.Cu")
		(net "P5E_CPU0_P1_RX_DN<8>")
	)
	(arc
		(start 352.641154 -287.504886)
		(mid 352.467909 -287.30384)
		(end 352.405442 -287.045908)
		(width 0.1143)
		(layer "In11.Cu")
		(net "P5E_CPU0_P1_RX_DN<8>")
	)
	(arc
		(start 346.48394 -381.289052)
		(mid 346.515092 -381.132349)
		(end 346.603828 -380.999492)
		(width 0.14224)
		(layer "In11.Cu")
		(net "P5E_CPU0_P1_RX_DN<8>")
	)
	(arc
		(start 352.649028 -282.650692)
		(mid 352.405701 -282.186126)
		(end 352.649028 -281.72156)
		(width 0.1143)
		(layer "In11.Cu")
		(net "P5E_CPU0_P1_RX_DN<8>")
	)
	(arc
		(start 345.697048 -378.44984)
		(mid 345.610951 -378.348502)
		(end 345.532964 -378.240798)
		(width 0.14224)
		(layer "In11.Cu")
		(net "P5E_CPU0_P1_RX_DN<8>")
	)
	(arc
		(start 345.849702 -378.578364)
		(mid 345.769171 -378.519095)
		(end 345.697048 -378.44984)
		(width 0.14224)
		(layer "In11.Cu")
		(net "P5E_CPU0_P1_RX_DN<8>")
	)
	(arc
		(start 352.405442 -287.045908)
		(mid 352.480366 -286.76593)
		(end 352.685096 -286.560768)
		(width 0.1143)
		(layer "In11.Cu")
		(net "P5E_CPU0_P1_RX_DN<8>")
	)
	(arc
		(start 346.066618 -376.086624)
		(mid 347.429561 -374.967936)
		(end 348.98457 -374.136666)
		(width 0.14224)
		(layer "In11.Cu")
		(net "P5E_CPU0_P1_RX_DN<8>")
	)
	(arc
		(start 352.719894 -276.820376)
		(mid 352.871483 -276.516084)
		(end 352.719894 -276.211792)
		(width 0.1143)
		(layer "In11.Cu")
		(net "P5E_CPU0_P1_RX_DN<8>")
	)
	(arc
		(start 352.649028 -292.37051)
		(mid 352.405701 -291.905944)
		(end 352.649028 -291.441378)
		(width 0.1143)
		(layer "In11.Cu")
		(net "P5E_CPU0_P1_RX_DN<8>")
	)
	(arc
		(start 346.303092 -378.770642)
		(mid 346.068441 -378.693266)
		(end 345.849702 -378.578364)
		(width 0.14224)
		(layer "In11.Cu")
		(net "P5E_CPU0_P1_RX_DN<8>")
	)
	(arc
		(start 352.405696 -278.946102)
		(mid 352.470211 -278.683883)
		(end 352.649028 -278.481536)
		(width 0.1143)
		(layer "In11.Cu")
		(net "P5E_CPU0_P1_RX_DN<8>")
	)
	(arc
		(start 352.179128 -280.220674)
		(mid 351.935801 -279.756108)
		(end 352.179128 -279.291542)
		(width 0.1143)
		(layer "In11.Cu")
		(net "P5E_CPU0_P1_RX_DN<8>")
	)
	(arc
		(start 364.430056 -361.88777)
		(mid 367.664946 -357.945886)
		(end 370.068602 -353.44862)
		(width 0.14224)
		(layer "In11.Cu")
		(net "P5E_CPU0_P1_RX_DN<8>")
	)
	(arc
		(start 346.588842 -378.819664)
		(mid 346.536282 -378.803001)
		(end 346.481654 -378.795534)
		(width 0.14224)
		(layer "In11.Cu")
		(net "P5E_CPU0_P1_RX_DN<8>")
	)
	(arc
		(start 347.081856 -379.339602)
		(mid 347.063527 -379.188862)
		(end 347.014292 -379.045216)
		(width 0.14224)
		(layer "In11.Cu")
		(net "P5E_CPU0_P1_RX_DN<8>")
	)
	(arc
		(start 352.719894 -289.780218)
		(mid 352.868991 -289.475926)
		(end 352.719894 -289.171634)
		(width 0.1143)
		(layer "In11.Cu")
		(net "P5E_CPU0_P1_RX_DN<8>")
	)
	(arc
		(start 352.87585 -287.856168)
		(mid 352.826027 -287.670438)
		(end 352.689922 -287.534604)
		(width 0.1143)
		(layer "In11.Cu")
		(net "P5E_CPU0_P1_RX_DN<8>")
	)
	(arc
		(start 352.405696 -280.566114)
		(mid 352.364147 -280.394692)
		(end 352.248724 -280.261314)
		(width 0.1143)
		(layer "In11.Cu")
		(net "P5E_CPU0_P1_RX_DN<8>")
	)
	(arc
		(start 347.014292 -379.045216)
		(mid 346.976806 -378.992813)
		(end 346.922852 -378.957586)
		(width 0.14224)
		(layer "In11.Cu")
		(net "P5E_CPU0_P1_RX_DN<8>")
	)
	(arc
		(start 352.179128 -275.360638)
		(mid 352.027141 -275.20413)
		(end 351.945702 -275.001736)
		(width 0.1143)
		(layer "In11.Cu")
		(net "P5E_CPU0_P1_RX_DN<8>")
	)
	(arc
		(start 347.149674 -379.786388)
		(mid 347.141101 -379.670203)
		(end 347.115638 -379.556518)
		(width 0.14224)
		(layer "In11.Cu")
		(net "P5E_CPU0_P1_RX_DN<8>")
	)
	(arc
		(start 352.649028 -285.890716)
		(mid 352.405701 -285.42615)
		(end 352.649028 -284.961584)
		(width 0.1143)
		(layer "In11.Cu")
		(net "P5E_CPU0_P1_RX_DN<8>")
	)
	(arc
		(start 352.87585 -286.236156)
		(mid 352.831779 -286.06662)
		(end 352.719894 -285.931864)
		(width 0.1143)
		(layer "In11.Cu")
		(net "P5E_CPU0_P1_RX_DN<8>")
	)
	(arc
		(start 352.248724 -279.250902)
		(mid 352.364151 -279.117526)
		(end 352.405696 -278.946102)
		(width 0.1143)
		(layer "In11.Cu")
		(net "P5E_CPU0_P1_RX_DN<8>")
	)
	(arc
		(start 352.649028 -276.170644)
		(mid 352.470215 -275.968294)
		(end 352.405696 -275.706078)
		(width 0.1143)
		(layer "In11.Cu")
		(net "P5E_CPU0_P1_RX_DN<8>")
	)
	(arc
		(start 352.649028 -290.750498)
		(mid 352.405701 -290.285932)
		(end 352.649028 -289.821366)
		(width 0.1143)
		(layer "In11.Cu")
		(net "P5E_CPU0_P1_RX_DN<8>")
	)
	(arc
		(start 345.517978 -378.218192)
		(mid 345.466951 -378.109591)
		(end 345.449652 -377.990862)
		(width 0.14224)
		(layer "In11.Cu")
		(net "P5E_CPU0_P1_RX_DN<8>")
	)
	(arc
		(start 352.721672 -288.158936)
		(mid 352.835079 -288.026047)
		(end 352.87585 -287.856168)
		(width 0.1143)
		(layer "In11.Cu")
		(net "P5E_CPU0_P1_RX_DN<8>")
	)
	(arc
		(start 346.481654 -378.795534)
		(mid 346.391783 -378.787324)
		(end 346.303092 -378.770642)
		(width 0.14224)
		(layer "In11.Cu")
		(net "P5E_CPU0_P1_RX_DN<8>")
	)
	(arc
		(start 352.405696 -275.706078)
		(mid 352.364147 -275.534656)
		(end 352.248724 -275.401278)
		(width 0.1143)
		(layer "In11.Cu")
		(net "P5E_CPU0_P1_RX_DN<8>")
	)
	(arc
		(start 352.651568 -287.512252)
		(mid 352.64634 -287.508599)
		(end 352.641154 -287.504886)
		(width 0.1143)
		(layer "In11.Cu")
		(net "P5E_CPU0_P1_RX_DN<8>")
	)
	(arc
		(start 352.719894 -284.920436)
		(mid 352.870279 -284.616144)
		(end 352.719894 -284.311852)
		(width 0.1143)
		(layer "In11.Cu")
		(net "P5E_CPU0_P1_RX_DN<8>")
	)
	(arc
		(start 352.721672 -286.538924)
		(mid 352.835079 -286.406035)
		(end 352.87585 -286.236156)
		(width 0.1143)
		(layer "In11.Cu")
		(net "P5E_CPU0_P1_RX_DN<8>")
	)
	(arc
		(start 347.02877 -380.57455)
		(mid 347.118269 -380.440795)
		(end 347.149674 -380.282958)
		(width 0.14224)
		(layer "In11.Cu")
		(net "P5E_CPU0_P1_RX_DN<8>")
	)
	(arc
		(start 347.115638 -379.556518)
		(mid 347.091228 -379.449231)
		(end 347.081856 -379.339602)
		(width 0.14224)
		(layer "In11.Cu")
		(net "P5E_CPU0_P1_RX_DN<8>")
	)
	(arc
		(start 352.649028 -281.03068)
		(mid 352.470215 -280.82833)
		(end 352.405696 -280.566114)
		(width 0.1143)
		(layer "In11.Cu")
		(net "P5E_CPU0_P1_RX_DN<8>")
	)
	(arc
		(start 350.983042 -373.30888)
		(mid 354.236648 -371.569808)
		(end 357.08844 -369.229386)
		(width 0.14224)
		(layer "In11.Cu")
		(net "P5E_CPU0_P1_RX_DN<8>")
	)
	(arc
		(start 351.945702 -275.001736)
		(mid 351.943679 -274.990326)
		(end 351.941892 -274.978876)
		(width 0.1143)
		(layer "In11.Cu")
		(net "P5E_CPU0_P1_RX_DN<8>")
	)
	(arc
		(start 352.649536 -293.99103)
		(mid 352.405682 -293.526309)
		(end 352.649028 -293.06139)
		(width 0.1143)
		(layer "In11.Cu")
		(net "P5E_CPU0_P1_RX_DN<8>")
	)
	(arc
		(start 352.649028 -277.790656)
		(mid 352.405701 -277.32609)
		(end 352.649028 -276.861524)
		(width 0.1143)
		(layer "In11.Cu")
		(net "P5E_CPU0_P1_RX_DN<8>")
	)
	(arc
		(start 352.720656 -294.639492)
		(mid 352.875545 -294.335962)
		(end 352.720656 -294.032432)
		(width 0.1143)
		(layer "In11.Cu")
		(net "P5E_CPU0_P1_RX_DN<8>")
	)
	(arc
		(start 352.719894 -278.440388)
		(mid 352.871483 -278.136096)
		(end 352.719894 -277.831804)
		(width 0.1143)
		(layer "In11.Cu")
		(net "P5E_CPU0_P1_RX_DN<8>")
	)
	(arc
		(start 352.405696 -295.145968)
		(mid 352.431116 -294.978123)
		(end 352.505264 -294.82542)
		(width 0.1143)
		(layer "In11.Cu")
		(net "P5E_CPU0_P1_RX_DN<8>")
	)
	(arc
		(start 352.649028 -289.130486)
		(mid 352.405701 -288.66592)
		(end 352.649028 -288.201354)
		(width 0.1143)
		(layer "In11.Cu")
		(net "P5E_CPU0_P1_RX_DN<8>")
	)
	(arc
		(start 352.649028 -284.270704)
		(mid 352.405701 -283.806138)
		(end 352.649028 -283.341572)
		(width 0.1143)
		(layer "In11.Cu")
		(net "P5E_CPU0_P1_RX_DN<8>")
	)
	(arc
		(start 352.719894 -293.020242)
		(mid 352.871483 -292.71595)
		(end 352.719894 -292.411658)
		(width 0.1143)
		(layer "In11.Cu")
		(net "P5E_CPU0_P1_RX_DN<8>")
	)
	(arc
		(start 345.449652 -377.086876)
		(mid 345.520088 -376.732771)
		(end 345.72067 -376.432572)
		(width 0.14224)
		(layer "In11.Cu")
		(net "P5E_CPU0_P1_RX_DN<8>")
	)
	(arc
		(start 352.719894 -281.680412)
		(mid 352.871483 -281.37612)
		(end 352.719894 -281.071828)
		(width 0.1143)
		(layer "In11.Cu")
		(net "P5E_CPU0_P1_RX_DN<8>")
	)
	(arc
		(start 352.719894 -291.40023)
		(mid 352.871483 -291.095938)
		(end 352.719894 -290.791646)
		(width 0.1143)
		(layer "In11.Cu")
		(net "P5E_CPU0_P1_RX_DN<8>")
	)
	(segment
		(start 344.198194 -393.69238)
		(end 344.718894 -393.69238)
		(width 0.127)
		(layer "F.Cu")
		(net "P5E_CPU0_P1_RX_DN<7>")
	)
	(segment
		(start 352.027998 -277.870158)
		(end 351.561146 -278.136096)
		(width 0.12954)
		(layer "F.Cu")
		(net "P5E_CPU0_P1_RX_DN<7>")
	)
	(segment
		(start 345.336368 -386.428234)
		(end 345.336622 -386.428234)
		(width 0.14224)
		(layer "In11.Cu")
		(net "P5E_CPU0_P1_RX_DN<7>")
	)
	(segment
		(start 351.711768 -294.679624)
		(end 351.74809 -294.658542)
		(width 0.1143)
		(layer "In11.Cu")
		(net "P5E_CPU0_P1_RX_DN<7>")
	)
	(segment
		(start 345.315794 -386.854192)
		(end 345.31554 -386.854192)
		(width 0.14224)
		(layer "In11.Cu")
		(net "P5E_CPU0_P1_RX_DN<7>")
	)
	(segment
		(start 356.648512 -368.234722)
		(end 362.844334 -362.0389)
		(width 0.14224)
		(layer "In11.Cu")
		(net "P5E_CPU0_P1_RX_DN<7>")
	)
	(segment
		(start 343.870534 -376.210322)
		(end 344.939366 -375.14149)
		(width 0.14224)
		(layer "In11.Cu")
		(net "P5E_CPU0_P1_RX_DN<7>")
	)
	(segment
		(start 351.748852 -293.038022)
		(end 351.750122 -293.03726)
		(width 0.1143)
		(layer "In11.Cu")
		(net "P5E_CPU0_P1_RX_DN<7>")
	)
	(segment
		(start 351.754186 -281.057096)
		(end 351.752662 -281.05608)
		(width 0.1143)
		(layer "In11.Cu")
		(net "P5E_CPU0_P1_RX_DN<7>")
	)
	(segment
		(start 351.754186 -292.396926)
		(end 351.752662 -292.39591)
		(width 0.1143)
		(layer "In11.Cu")
		(net "P5E_CPU0_P1_RX_DN<7>")
	)
	(segment
		(start 371.336824 -347.40342)
		(end 371.336824 -339.916516)
		(width 0.14224)
		(layer "In11.Cu")
		(net "P5E_CPU0_P1_RX_DN<7>")
	)
	(segment
		(start 351.77984 -292.411658)
		(end 351.754186 -292.396926)
		(width 0.1143)
		(layer "In11.Cu")
		(net "P5E_CPU0_P1_RX_DN<7>")
	)
	(segment
		(start 351.287842 -280.248868)
		(end 351.239836 -280.221182)
		(width 0.1143)
		(layer "In11.Cu")
		(net "P5E_CPU0_P1_RX_DN<7>")
	)
	(segment
		(start 343.746074 -380.31039)
		(end 343.746074 -376.510804)
		(width 0.14224)
		(layer "In11.Cu")
		(net "P5E_CPU0_P1_RX_DN<7>")
	)
	(segment
		(start 351.750122 -283.317442)
		(end 351.77984 -283.300424)
		(width 0.1143)
		(layer "In11.Cu")
		(net "P5E_CPU0_P1_RX_DN<7>")
	)
	(segment
		(start 351.74809 -281.6987)
		(end 351.748852 -281.698192)
		(width 0.1143)
		(layer "In11.Cu")
		(net "P5E_CPU0_P1_RX_DN<7>")
	)
	(segment
		(start 345.370912 -385.727956)
		(end 345.39174 -385.301998)
		(width 0.14224)
		(layer "In11.Cu")
		(net "P5E_CPU0_P1_RX_DN<7>")
	)
	(segment
		(start 351.74809 -294.013382)
		(end 351.711768 -293.9923)
		(width 0.1143)
		(layer "In11.Cu")
		(net "P5E_CPU0_P1_RX_DN<7>")
	)
	(segment
		(start 351.74809 -292.39337)
		(end 351.711768 -292.372288)
		(width 0.1143)
		(layer "In11.Cu")
		(net "P5E_CPU0_P1_RX_DN<7>")
	)
	(segment
		(start 351.748852 -291.41801)
		(end 351.750122 -291.417248)
		(width 0.1143)
		(layer "In11.Cu")
		(net "P5E_CPU0_P1_RX_DN<7>")
	)
	(segment
		(start 369.705636 -330.84135)
		(end 369.162076 -327.816464)
		(width 0.14224)
		(layer "In11.Cu")
		(net "P5E_CPU0_P1_RX_DN<7>")
	)
	(segment
		(start 351.859088 -278.136096)
		(end 351.561146 -278.136096)
		(width 0.1143)
		(layer "In11.Cu")
		(net "P5E_CPU0_P1_RX_DN<7>")
	)
	(segment
		(start 345.336622 -386.428234)
		(end 345.20632 -386.284724)
		(width 0.14224)
		(layer "In11.Cu")
		(net "P5E_CPU0_P1_RX_DN<7>")
	)
	(segment
		(start 351.752662 -284.296104)
		(end 351.750122 -284.294834)
		(width 0.1143)
		(layer "In11.Cu")
		(net "P5E_CPU0_P1_RX_DN<7>")
	)
	(segment
		(start 351.74809 -293.03853)
		(end 351.748852 -293.038022)
		(width 0.1143)
		(layer "In11.Cu")
		(net "P5E_CPU0_P1_RX_DN<7>")
	)
	(segment
		(start 345.186 -389.4963)
		(end 345.28125 -387.554724)
		(width 0.14224)
		(layer "In11.Cu")
		(net "P5E_CPU0_P1_RX_DN<7>")
	)
	(segment
		(start 351.727516 -288.190432)
		(end 351.781618 -288.158936)
		(width 0.1143)
		(layer "In11.Cu")
		(net "P5E_CPU0_P1_RX_DN<7>")
	)
	(segment
		(start 351.750122 -284.294834)
		(end 351.748852 -284.294072)
		(width 0.1143)
		(layer "In11.Cu")
		(net "P5E_CPU0_P1_RX_DN<7>")
	)
	(segment
		(start 367.313718 -324.27926)
		(end 360.440224 -315.904372)
		(width 0.14224)
		(layer "In11.Cu")
		(net "P5E_CPU0_P1_RX_DN<7>")
	)
	(segment
		(start 351.74809 -289.798506)
		(end 351.748852 -289.797998)
		(width 0.1143)
		(layer "In11.Cu")
		(net "P5E_CPU0_P1_RX_DN<7>")
	)
	(segment
		(start 351.711768 -289.819588)
		(end 351.74809 -289.798506)
		(width 0.1143)
		(layer "In11.Cu")
		(net "P5E_CPU0_P1_RX_DN<7>")
	)
	(segment
		(start 345.391994 -385.301998)
		(end 345.261692 -385.158234)
		(width 0.14224)
		(layer "In11.Cu")
		(net "P5E_CPU0_P1_RX_DN<7>")
	)
	(segment
		(start 351.74809 -294.658542)
		(end 351.77984 -294.640254)
		(width 0.1143)
		(layer "In11.Cu")
		(net "P5E_CPU0_P1_RX_DN<7>")
	)
	(segment
		(start 351.748852 -278.458168)
		(end 351.750122 -278.457406)
		(width 0.1143)
		(layer "In11.Cu")
		(net "P5E_CPU0_P1_RX_DN<7>")
	)
	(segment
		(start 351.711768 -281.719782)
		(end 351.74809 -281.6987)
		(width 0.1143)
		(layer "In11.Cu")
		(net "P5E_CPU0_P1_RX_DN<7>")
	)
	(segment
		(start 351.750122 -290.774628)
		(end 351.748852 -290.773866)
		(width 0.1143)
		(layer "In11.Cu")
		(net "P5E_CPU0_P1_RX_DN<7>")
	)
	(segment
		(start 351.748852 -284.938216)
		(end 351.750122 -284.937454)
		(width 0.1143)
		(layer "In11.Cu")
		(net "P5E_CPU0_P1_RX_DN<7>")
	)
	(segment
		(start 369.162076 -327.816464)
		(end 367.313718 -324.27926)
		(width 0.14224)
		(layer "In11.Cu")
		(net "P5E_CPU0_P1_RX_DN<7>")
	)
	(segment
		(start 360.440224 -315.904372)
		(end 354.431092 -306.910994)
		(width 0.14224)
		(layer "In11.Cu")
		(net "P5E_CPU0_P1_RX_DN<7>")
	)
	(segment
		(start 345.171776 -386.984494)
		(end 345.315794 -386.854192)
		(width 0.14224)
		(layer "In11.Cu")
		(net "P5E_CPU0_P1_RX_DN<7>")
	)
	(segment
		(start 351.748852 -281.054048)
		(end 351.745804 -281.052016)
		(width 0.1143)
		(layer "In11.Cu")
		(net "P5E_CPU0_P1_RX_DN<7>")
	)
	(segment
		(start 344.881962 -392.61669)
		(end 345.186 -392.312906)
		(width 0.14224)
		(layer "In11.Cu")
		(net "P5E_CPU0_P1_RX_DN<7>")
	)
	(segment
		(start 351.711768 -293.059612)
		(end 351.74809 -293.03853)
		(width 0.1143)
		(layer "In11.Cu")
		(net "P5E_CPU0_P1_RX_DN<7>")
	)
	(segment
		(start 344.718894 -393.69238)
		(end 345.071954 -393.787376)
		(width 0.14224)
		(layer "In11.Cu")
		(net "P5E_CPU0_P1_RX_DN<7>")
	)
	(segment
		(start 351.711768 -284.959806)
		(end 351.74809 -284.938724)
		(width 0.1143)
		(layer "In11.Cu")
		(net "P5E_CPU0_P1_RX_DN<7>")
	)
	(segment
		(start 351.928938 -278.205946)
		(end 351.859088 -278.136096)
		(width 0.1143)
		(layer "In11.Cu")
		(net "P5E_CPU0_P1_RX_DN<7>")
	)
	(segment
		(start 351.74809 -284.938724)
		(end 351.748852 -284.938216)
		(width 0.1143)
		(layer "In11.Cu")
		(net "P5E_CPU0_P1_RX_DN<7>")
	)
	(segment
		(start 351.750122 -282.674822)
		(end 351.748852 -282.67406)
		(width 0.1143)
		(layer "In11.Cu")
		(net "P5E_CPU0_P1_RX_DN<7>")
	)
	(segment
		(start 351.750122 -293.03726)
		(end 351.77984 -293.020242)
		(width 0.1143)
		(layer "In11.Cu")
		(net "P5E_CPU0_P1_RX_DN<7>")
	)
	(segment
		(start 345.227148 -385.858258)
		(end 345.371166 -385.727956)
		(width 0.14224)
		(layer "In11.Cu")
		(net "P5E_CPU0_P1_RX_DN<7>")
	)
	(segment
		(start 351.754186 -284.29712)
		(end 351.752662 -284.296104)
		(width 0.1143)
		(layer "In11.Cu")
		(net "P5E_CPU0_P1_RX_DN<7>")
	)
	(segment
		(start 351.005902 -295.78554)
		(end 351.465896 -295.325546)
		(width 0.1143)
		(layer "In11.Cu")
		(net "P5E_CPU0_P1_RX_DN<7>")
	)
	(segment
		(start 351.77984 -285.931864)
		(end 351.754186 -285.917132)
		(width 0.1143)
		(layer "In11.Cu")
		(net "P5E_CPU0_P1_RX_DN<7>")
	)
	(segment
		(start 351.750122 -284.937454)
		(end 351.77984 -284.920436)
		(width 0.1143)
		(layer "In11.Cu")
		(net "P5E_CPU0_P1_RX_DN<7>")
	)
	(segment
		(start 351.478596 -278.93645)
		(end 351.478596 -278.926798)
		(width 0.1143)
		(layer "In11.Cu")
		(net "P5E_CPU0_P1_RX_DN<7>")
	)
	(segment
		(start 345.426284 -384.601466)
		(end 345.49334 -383.23774)
		(width 0.14224)
		(layer "In11.Cu")
		(net "P5E_CPU0_P1_RX_DN<7>")
	)
	(segment
		(start 351.74809 -291.418518)
		(end 351.748852 -291.41801)
		(width 0.1143)
		(layer "In11.Cu")
		(net "P5E_CPU0_P1_RX_DN<7>")
	)
	(segment
		(start 351.74809 -283.318712)
		(end 351.748852 -283.318204)
		(width 0.1143)
		(layer "In11.Cu")
		(net "P5E_CPU0_P1_RX_DN<7>")
	)
	(segment
		(start 369.238022 -352.469704)
		(end 371.336824 -347.40342)
		(width 0.14224)
		(layer "In11.Cu")
		(net "P5E_CPU0_P1_RX_DN<7>")
	)
	(segment
		(start 351.74809 -278.458676)
		(end 351.748852 -278.458168)
		(width 0.1143)
		(layer "In11.Cu")
		(net "P5E_CPU0_P1_RX_DN<7>")
	)
	(segment
		(start 351.726754 -288.19094)
		(end 351.727516 -288.190432)
		(width 0.1143)
		(layer "In11.Cu")
		(net "P5E_CPU0_P1_RX_DN<7>")
	)
	(segment
		(start 351.754186 -285.917132)
		(end 351.752662 -285.916116)
		(width 0.1143)
		(layer "In11.Cu")
		(net "P5E_CPU0_P1_RX_DN<7>")
	)
	(segment
		(start 371.336824 -339.916516)
		(end 369.705636 -330.84135)
		(width 0.14224)
		(layer "In11.Cu")
		(net "P5E_CPU0_P1_RX_DN<7>")
	)
	(segment
		(start 351.748852 -294.01389)
		(end 351.74809 -294.013382)
		(width 0.1143)
		(layer "In11.Cu")
		(net "P5E_CPU0_P1_RX_DN<7>")
	)
	(segment
		(start 351.77984 -281.071828)
		(end 351.754186 -281.057096)
		(width 0.1143)
		(layer "In11.Cu")
		(net "P5E_CPU0_P1_RX_DN<7>")
	)
	(segment
		(start 351.77984 -284.311852)
		(end 351.754186 -284.29712)
		(width 0.1143)
		(layer "In11.Cu")
		(net "P5E_CPU0_P1_RX_DN<7>")
	)
	(segment
		(start 351.750122 -281.69743)
		(end 351.77984 -281.680412)
		(width 0.1143)
		(layer "In11.Cu")
		(net "P5E_CPU0_P1_RX_DN<7>")
	)
	(segment
		(start 351.750122 -291.417248)
		(end 351.77984 -291.40023)
		(width 0.1143)
		(layer "In11.Cu")
		(net "P5E_CPU0_P1_RX_DN<7>")
	)
	(segment
		(start 345.194128 -393.545822)
		(end 344.877136 -393.22883)
		(width 0.14224)
		(layer "In11.Cu")
		(net "P5E_CPU0_P1_RX_DN<7>")
	)
	(segment
		(start 344.877136 -393.22883)
		(end 344.881962 -392.61669)
		(width 0.14224)
		(layer "In11.Cu")
		(net "P5E_CPU0_P1_RX_DN<7>")
	)
	(segment
		(start 345.150948 -387.41096)
		(end 345.171776 -386.984494)
		(width 0.14224)
		(layer "In11.Cu")
		(net "P5E_CPU0_P1_RX_DN<7>")
	)
	(segment
		(start 345.371166 -385.727956)
		(end 345.370912 -385.727956)
		(width 0.14224)
		(layer "In11.Cu")
		(net "P5E_CPU0_P1_RX_DN<7>")
	)
	(segment
		(start 351.752662 -282.676092)
		(end 351.750122 -282.674822)
		(width 0.1143)
		(layer "In11.Cu")
		(net "P5E_CPU0_P1_RX_DN<7>")
	)
	(segment
		(start 351.748852 -290.773866)
		(end 351.74809 -290.773358)
		(width 0.1143)
		(layer "In11.Cu")
		(net "P5E_CPU0_P1_RX_DN<7>")
	)
	(segment
		(start 351.74809 -286.558482)
		(end 351.781618 -286.538924)
		(width 0.1143)
		(layer "In11.Cu")
		(net "P5E_CPU0_P1_RX_DN<7>")
	)
	(segment
		(start 350.960182 -298.531534)
		(end 350.960182 -296.419016)
		(width 0.14224)
		(layer "In11.Cu")
		(net "P5E_CPU0_P1_RX_DN<7>")
	)
	(segment
		(start 351.745804 -281.052016)
		(end 351.728532 -281.042364)
		(width 0.1143)
		(layer "In11.Cu")
		(net "P5E_CPU0_P1_RX_DN<7>")
	)
	(segment
		(start 351.752662 -290.775898)
		(end 351.750122 -290.774628)
		(width 0.1143)
		(layer "In11.Cu")
		(net "P5E_CPU0_P1_RX_DN<7>")
	)
	(segment
		(start 351.752662 -285.916116)
		(end 351.750122 -285.914846)
		(width 0.1143)
		(layer "In11.Cu")
		(net "P5E_CPU0_P1_RX_DN<7>")
	)
	(segment
		(start 345.20632 -386.284724)
		(end 345.227148 -385.858258)
		(width 0.14224)
		(layer "In11.Cu")
		(net "P5E_CPU0_P1_RX_DN<7>")
	)
	(segment
		(start 351.750122 -292.39464)
		(end 351.748852 -292.393878)
		(width 0.1143)
		(layer "In11.Cu")
		(net "P5E_CPU0_P1_RX_DN<7>")
	)
	(segment
		(start 351.239074 -279.291542)
		(end 351.29089 -279.261316)
		(width 0.1143)
		(layer "In11.Cu")
		(net "P5E_CPU0_P1_RX_DN<7>")
	)
	(segment
		(start 351.74809 -290.773358)
		(end 351.711768 -290.752276)
		(width 0.1143)
		(layer "In11.Cu")
		(net "P5E_CPU0_P1_RX_DN<7>")
	)
	(segment
		(start 354.431092 -306.910994)
		(end 350.960182 -298.531534)
		(width 0.14224)
		(layer "In11.Cu")
		(net "P5E_CPU0_P1_RX_DN<7>")
	)
	(segment
		(start 351.748852 -289.797998)
		(end 351.750122 -289.797236)
		(width 0.1143)
		(layer "In11.Cu")
		(net "P5E_CPU0_P1_RX_DN<7>")
	)
	(segment
		(start 351.711768 -283.339794)
		(end 351.74809 -283.318712)
		(width 0.1143)
		(layer "In11.Cu")
		(net "P5E_CPU0_P1_RX_DN<7>")
	)
	(segment
		(start 351.465896 -295.325546)
		(end 351.465896 -295.145968)
		(width 0.1143)
		(layer "In11.Cu")
		(net "P5E_CPU0_P1_RX_DN<7>")
	)
	(segment
		(start 345.194128 -393.716764)
		(end 345.194128 -393.545822)
		(width 0.14224)
		(layer "In11.Cu")
		(net "P5E_CPU0_P1_RX_DN<7>")
	)
	(segment
		(start 351.74809 -284.293564)
		(end 351.711768 -284.272482)
		(width 0.1143)
		(layer "In11.Cu")
		(net "P5E_CPU0_P1_RX_DN<7>")
	)
	(segment
		(start 351.474024 -280.602436)
		(end 351.474024 -280.572718)
		(width 0.1143)
		(layer "In11.Cu")
		(net "P5E_CPU0_P1_RX_DN<7>")
	)
	(segment
		(start 351.750122 -294.014652)
		(end 351.748852 -294.01389)
		(width 0.1143)
		(layer "In11.Cu")
		(net "P5E_CPU0_P1_RX_DN<7>")
	)
	(segment
		(start 351.711768 -286.579564)
		(end 351.74809 -286.558482)
		(width 0.1143)
		(layer "In11.Cu")
		(net "P5E_CPU0_P1_RX_DN<7>")
	)
	(segment
		(start 351.77984 -294.03167)
		(end 351.754186 -294.016938)
		(width 0.1143)
		(layer "In11.Cu")
		(net "P5E_CPU0_P1_RX_DN<7>")
	)
	(segment
		(start 351.77984 -282.69184)
		(end 351.754186 -282.677108)
		(width 0.1143)
		(layer "In11.Cu")
		(net "P5E_CPU0_P1_RX_DN<7>")
	)
	(segment
		(start 345.28252 -384.731768)
		(end 345.426538 -384.601466)
		(width 0.14224)
		(layer "In11.Cu")
		(net "P5E_CPU0_P1_RX_DN<7>")
	)
	(segment
		(start 345.456002 -381.724662)
		(end 345.18346 -381.45212)
		(width 0.14224)
		(layer "In11.Cu")
		(net "P5E_CPU0_P1_RX_DN<7>")
	)
	(segment
		(start 345.261692 -385.158234)
		(end 345.28252 -384.731768)
		(width 0.14224)
		(layer "In11.Cu")
		(net "P5E_CPU0_P1_RX_DN<7>")
	)
	(segment
		(start 351.748852 -281.698192)
		(end 351.750122 -281.69743)
		(width 0.1143)
		(layer "In11.Cu")
		(net "P5E_CPU0_P1_RX_DN<7>")
	)
	(segment
		(start 346.537788 -374.073166)
		(end 350.147636 -372.578122)
		(width 0.14224)
		(layer "In11.Cu")
		(net "P5E_CPU0_P1_RX_DN<7>")
	)
	(segment
		(start 345.426538 -384.601466)
		(end 345.426284 -384.601466)
		(width 0.14224)
		(layer "In11.Cu")
		(net "P5E_CPU0_P1_RX_DN<7>")
	)
	(segment
		(start 351.74809 -282.673552)
		(end 351.711768 -282.65247)
		(width 0.1143)
		(layer "In11.Cu")
		(net "P5E_CPU0_P1_RX_DN<7>")
	)
	(segment
		(start 351.754186 -282.677108)
		(end 351.752662 -282.676092)
		(width 0.1143)
		(layer "In11.Cu")
		(net "P5E_CPU0_P1_RX_DN<7>")
	)
	(segment
		(start 344.204036 -380.960376)
		(end 343.881964 -380.638304)
		(width 0.14224)
		(layer "In11.Cu")
		(net "P5E_CPU0_P1_RX_DN<7>")
	)
	(segment
		(start 345.49334 -383.23774)
		(end 345.49334 -381.814578)
		(width 0.14224)
		(layer "In11.Cu")
		(net "P5E_CPU0_P1_RX_DN<7>")
	)
	(segment
		(start 351.711768 -291.4396)
		(end 351.74809 -291.418518)
		(width 0.1143)
		(layer "In11.Cu")
		(net "P5E_CPU0_P1_RX_DN<7>")
	)
	(segment
		(start 351.748852 -292.393878)
		(end 351.74809 -292.39337)
		(width 0.1143)
		(layer "In11.Cu")
		(net "P5E_CPU0_P1_RX_DN<7>")
	)
	(segment
		(start 345.28125 -387.554724)
		(end 345.150948 -387.41096)
		(width 0.14224)
		(layer "In11.Cu")
		(net "P5E_CPU0_P1_RX_DN<7>")
	)
	(segment
		(start 351.752662 -292.39591)
		(end 351.750122 -292.39464)
		(width 0.1143)
		(layer "In11.Cu")
		(net "P5E_CPU0_P1_RX_DN<7>")
	)
	(segment
		(start 351.77984 -289.171634)
		(end 351.726754 -289.1409)
		(width 0.1143)
		(layer "In11.Cu")
		(net "P5E_CPU0_P1_RX_DN<7>")
	)
	(segment
		(start 350.960182 -296.419016)
		(end 350.960182 -296.390568)
		(width 0.1143)
		(layer "In11.Cu")
		(net "P5E_CPU0_P1_RX_DN<7>")
	)
	(segment
		(start 345.315794 -386.851906)
		(end 345.336368 -386.428234)
		(width 0.14224)
		(layer "In11.Cu")
		(net "P5E_CPU0_P1_RX_DN<7>")
	)
	(segment
		(start 351.74809 -285.913576)
		(end 351.711768 -285.892494)
		(width 0.1143)
		(layer "In11.Cu")
		(net "P5E_CPU0_P1_RX_DN<7>")
	)
	(segment
		(start 351.750122 -289.797236)
		(end 351.77984 -289.780218)
		(width 0.1143)
		(layer "In11.Cu")
		(net "P5E_CPU0_P1_RX_DN<7>")
	)
	(segment
		(start 351.748852 -284.294072)
		(end 351.74809 -284.293564)
		(width 0.1143)
		(layer "In11.Cu")
		(net "P5E_CPU0_P1_RX_DN<7>")
	)
	(segment
		(start 351.752662 -294.015922)
		(end 351.750122 -294.014652)
		(width 0.1143)
		(layer "In11.Cu")
		(net "P5E_CPU0_P1_RX_DN<7>")
	)
	(segment
		(start 345.39174 -385.301998)
		(end 345.391994 -385.301998)
		(width 0.14224)
		(layer "In11.Cu")
		(net "P5E_CPU0_P1_RX_DN<7>")
	)
	(segment
		(start 345.142058 -381.424434)
		(end 344.502486 -381.159766)
		(width 0.14224)
		(layer "In11.Cu")
		(net "P5E_CPU0_P1_RX_DN<7>")
	)
	(segment
		(start 351.748852 -283.318204)
		(end 351.750122 -283.317442)
		(width 0.1143)
		(layer "In11.Cu")
		(net "P5E_CPU0_P1_RX_DN<7>")
	)
	(segment
		(start 351.748852 -282.67406)
		(end 351.74809 -282.673552)
		(width 0.1143)
		(layer "In11.Cu")
		(net "P5E_CPU0_P1_RX_DN<7>")
	)
	(segment
		(start 345.072462 -393.786868)
		(end 345.194128 -393.716764)
		(width 0.14224)
		(layer "In11.Cu")
		(net "P5E_CPU0_P1_RX_DN<7>")
	)
	(segment
		(start 351.77984 -290.791646)
		(end 351.754186 -290.776914)
		(width 0.1143)
		(layer "In11.Cu")
		(net "P5E_CPU0_P1_RX_DN<7>")
	)
	(segment
		(start 351.005902 -296.344848)
		(end 351.005902 -295.78554)
		(width 0.1143)
		(layer "In11.Cu")
		(net "P5E_CPU0_P1_RX_DN<7>")
	)
	(segment
		(start 351.752662 -281.05608)
		(end 351.750122 -281.05481)
		(width 0.1143)
		(layer "In11.Cu")
		(net "P5E_CPU0_P1_RX_DN<7>")
	)
	(segment
		(start 351.754186 -290.776914)
		(end 351.752662 -290.775898)
		(width 0.1143)
		(layer "In11.Cu")
		(net "P5E_CPU0_P1_RX_DN<7>")
	)
	(segment
		(start 351.750122 -278.457406)
		(end 351.77984 -278.440388)
		(width 0.1143)
		(layer "In11.Cu")
		(net "P5E_CPU0_P1_RX_DN<7>")
	)
	(segment
		(start 351.74809 -287.533588)
		(end 351.714562 -287.51403)
		(width 0.1143)
		(layer "In11.Cu")
		(net "P5E_CPU0_P1_RX_DN<7>")
	)
	(segment
		(start 351.750122 -281.05481)
		(end 351.748852 -281.054048)
		(width 0.1143)
		(layer "In11.Cu")
		(net "P5E_CPU0_P1_RX_DN<7>")
	)
	(segment
		(start 350.960182 -296.390568)
		(end 351.005902 -296.344848)
		(width 0.1143)
		(layer "In11.Cu")
		(net "P5E_CPU0_P1_RX_DN<7>")
	)
	(segment
		(start 345.31554 -386.854192)
		(end 345.315794 -386.851906)
		(width 0.14224)
		(layer "In11.Cu")
		(net "P5E_CPU0_P1_RX_DN<7>")
	)
	(segment
		(start 351.754186 -294.016938)
		(end 351.752662 -294.015922)
		(width 0.1143)
		(layer "In11.Cu")
		(net "P5E_CPU0_P1_RX_DN<7>")
	)
	(segment
		(start 351.750122 -285.914846)
		(end 351.748852 -285.914084)
		(width 0.1143)
		(layer "In11.Cu")
		(net "P5E_CPU0_P1_RX_DN<7>")
	)
	(segment
		(start 345.186 -392.312906)
		(end 345.186 -389.4963)
		(width 0.14224)
		(layer "In11.Cu")
		(net "P5E_CPU0_P1_RX_DN<7>")
	)
	(segment
		(start 351.748852 -285.914084)
		(end 351.74809 -285.913576)
		(width 0.1143)
		(layer "In11.Cu")
		(net "P5E_CPU0_P1_RX_DN<7>")
	)
	(segment
		(start 351.77984 -287.551876)
		(end 351.74809 -287.533588)
		(width 0.1143)
		(layer "In11.Cu")
		(net "P5E_CPU0_P1_RX_DN<7>")
	)
	(segment
		(start 345.071954 -393.787376)
		(end 345.072462 -393.786868)
		(width 0.14224)
		(layer "In11.Cu")
		(net "P5E_CPU0_P1_RX_DN<7>")
	)
	(arc
		(start 351.695512 -283.351224)
		(mid 351.70359 -283.345438)
		(end 351.711768 -283.339794)
		(width 0.1143)
		(layer "In11.Cu")
		(net "P5E_CPU0_P1_RX_DN<7>")
	)
	(arc
		(start 351.474024 -280.572718)
		(mid 351.424153 -280.385953)
		(end 351.287842 -280.248868)
		(width 0.1143)
		(layer "In11.Cu")
		(net "P5E_CPU0_P1_RX_DN<7>")
	)
	(arc
		(start 351.711768 -285.892494)
		(mid 351.704104 -285.887223)
		(end 351.696528 -285.881826)
		(width 0.1143)
		(layer "In11.Cu")
		(net "P5E_CPU0_P1_RX_DN<7>")
	)
	(arc
		(start 351.781618 -288.158936)
		(mid 351.895025 -288.026047)
		(end 351.935796 -287.856168)
		(width 0.1143)
		(layer "In11.Cu")
		(net "P5E_CPU0_P1_RX_DN<7>")
	)
	(arc
		(start 351.714562 -287.51403)
		(mid 351.705998 -287.508268)
		(end 351.697544 -287.502346)
		(width 0.1143)
		(layer "In11.Cu")
		(net "P5E_CPU0_P1_RX_DN<7>")
	)
	(arc
		(start 351.697544 -292.362382)
		(mid 351.470161 -291.905944)
		(end 351.697544 -291.449506)
		(width 0.1143)
		(layer "In11.Cu")
		(net "P5E_CPU0_P1_RX_DN<7>")
	)
	(arc
		(start 343.881964 -380.638304)
		(mid 343.781384 -380.48787)
		(end 343.746074 -380.31039)
		(width 0.14224)
		(layer "In11.Cu")
		(net "P5E_CPU0_P1_RX_DN<7>")
	)
	(arc
		(start 351.728532 -281.042364)
		(mid 351.542243 -280.856555)
		(end 351.474024 -280.602436)
		(width 0.1143)
		(layer "In11.Cu")
		(net "P5E_CPU0_P1_RX_DN<7>")
	)
	(arc
		(start 351.465896 -287.050226)
		(mid 351.465892 -287.048067)
		(end 351.465896 -287.045908)
		(width 0.1143)
		(layer "In11.Cu")
		(net "P5E_CPU0_P1_RX_DN<7>")
	)
	(arc
		(start 351.697544 -294.68953)
		(mid 351.704617 -294.684521)
		(end 351.711768 -294.679624)
		(width 0.1143)
		(layer "In11.Cu")
		(net "P5E_CPU0_P1_RX_DN<7>")
	)
	(arc
		(start 351.696528 -293.07028)
		(mid 351.704104 -293.064884)
		(end 351.711768 -293.059612)
		(width 0.1143)
		(layer "In11.Cu")
		(net "P5E_CPU0_P1_RX_DN<7>")
	)
	(arc
		(start 345.18346 -381.45212)
		(mid 345.164117 -381.436249)
		(end 345.142058 -381.424434)
		(width 0.14224)
		(layer "In11.Cu")
		(net "P5E_CPU0_P1_RX_DN<7>")
	)
	(arc
		(start 351.697544 -287.502346)
		(mid 351.529913 -287.302835)
		(end 351.465896 -287.050226)
		(width 0.1143)
		(layer "In11.Cu")
		(net "P5E_CPU0_P1_RX_DN<7>")
	)
	(arc
		(start 351.478596 -278.926798)
		(mid 351.550786 -278.656727)
		(end 351.74809 -278.458676)
		(width 0.1143)
		(layer "In11.Cu")
		(net "P5E_CPU0_P1_RX_DN<7>")
	)
	(arc
		(start 351.711768 -284.272482)
		(mid 351.70359 -284.266839)
		(end 351.695512 -284.261052)
		(width 0.1143)
		(layer "In11.Cu")
		(net "P5E_CPU0_P1_RX_DN<7>")
	)
	(arc
		(start 351.77984 -294.640254)
		(mid 351.935768 -294.335962)
		(end 351.77984 -294.03167)
		(width 0.1143)
		(layer "In11.Cu")
		(net "P5E_CPU0_P1_RX_DN<7>")
	)
	(arc
		(start 351.696528 -285.881826)
		(mid 351.471357 -285.42615)
		(end 351.696528 -284.970474)
		(width 0.1143)
		(layer "In11.Cu")
		(net "P5E_CPU0_P1_RX_DN<7>")
	)
	(arc
		(start 351.711768 -290.752276)
		(mid 351.705516 -290.747999)
		(end 351.699322 -290.74364)
		(width 0.1143)
		(layer "In11.Cu")
		(net "P5E_CPU0_P1_RX_DN<7>")
	)
	(arc
		(start 351.77984 -293.020242)
		(mid 351.935768 -292.71595)
		(end 351.77984 -292.411658)
		(width 0.1143)
		(layer "In11.Cu")
		(net "P5E_CPU0_P1_RX_DN<7>")
	)
	(arc
		(start 351.711768 -282.65247)
		(mid 351.704619 -282.64757)
		(end 351.697544 -282.642564)
		(width 0.1143)
		(layer "In11.Cu")
		(net "P5E_CPU0_P1_RX_DN<7>")
	)
	(arc
		(start 351.699322 -290.74364)
		(mid 351.467854 -290.285932)
		(end 351.699322 -289.828224)
		(width 0.1143)
		(layer "In11.Cu")
		(net "P5E_CPU0_P1_RX_DN<7>")
	)
	(arc
		(start 344.939366 -375.14149)
		(mid 345.685961 -374.528604)
		(end 346.537788 -374.073166)
		(width 0.14224)
		(layer "In11.Cu")
		(net "P5E_CPU0_P1_RX_DN<7>")
	)
	(arc
		(start 351.696528 -284.970474)
		(mid 351.704104 -284.965078)
		(end 351.711768 -284.959806)
		(width 0.1143)
		(layer "In11.Cu")
		(net "P5E_CPU0_P1_RX_DN<7>")
	)
	(arc
		(start 344.502486 -381.159766)
		(mid 344.343441 -381.074773)
		(end 344.204036 -380.960376)
		(width 0.14224)
		(layer "In11.Cu")
		(net "P5E_CPU0_P1_RX_DN<7>")
	)
	(arc
		(start 351.77984 -281.680412)
		(mid 351.935768 -281.37612)
		(end 351.77984 -281.071828)
		(width 0.1143)
		(layer "In11.Cu")
		(net "P5E_CPU0_P1_RX_DN<7>")
	)
	(arc
		(start 351.781618 -286.538924)
		(mid 351.895025 -286.406035)
		(end 351.935796 -286.236156)
		(width 0.1143)
		(layer "In11.Cu")
		(net "P5E_CPU0_P1_RX_DN<7>")
	)
	(arc
		(start 351.699322 -289.828224)
		(mid 351.705516 -289.823864)
		(end 351.711768 -289.819588)
		(width 0.1143)
		(layer "In11.Cu")
		(net "P5E_CPU0_P1_RX_DN<7>")
	)
	(arc
		(start 351.697544 -281.729688)
		(mid 351.704618 -281.724681)
		(end 351.711768 -281.719782)
		(width 0.1143)
		(layer "In11.Cu")
		(net "P5E_CPU0_P1_RX_DN<7>")
	)
	(arc
		(start 351.697544 -282.642564)
		(mid 351.470161 -282.186126)
		(end 351.697544 -281.729688)
		(width 0.1143)
		(layer "In11.Cu")
		(net "P5E_CPU0_P1_RX_DN<7>")
	)
	(arc
		(start 343.746074 -376.510804)
		(mid 343.778421 -376.348186)
		(end 343.870534 -376.210322)
		(width 0.14224)
		(layer "In11.Cu")
		(net "P5E_CPU0_P1_RX_DN<7>")
	)
	(arc
		(start 351.77984 -291.40023)
		(mid 351.935768 -291.095938)
		(end 351.77984 -290.791646)
		(width 0.1143)
		(layer "In11.Cu")
		(net "P5E_CPU0_P1_RX_DN<7>")
	)
	(arc
		(start 351.239836 -280.221182)
		(mid 351.239455 -280.220928)
		(end 351.239074 -280.220674)
		(width 0.1143)
		(layer "In11.Cu")
		(net "P5E_CPU0_P1_RX_DN<7>")
	)
	(arc
		(start 345.49334 -381.814578)
		(mid 345.483638 -381.765894)
		(end 345.456002 -381.724662)
		(width 0.14224)
		(layer "In11.Cu")
		(net "P5E_CPU0_P1_RX_DN<7>")
	)
	(arc
		(start 351.77984 -289.780218)
		(mid 351.935768 -289.475926)
		(end 351.77984 -289.171634)
		(width 0.1143)
		(layer "In11.Cu")
		(net "P5E_CPU0_P1_RX_DN<7>")
	)
	(arc
		(start 351.711768 -293.9923)
		(mid 351.704104 -293.987029)
		(end 351.696528 -293.981632)
		(width 0.1143)
		(layer "In11.Cu")
		(net "P5E_CPU0_P1_RX_DN<7>")
	)
	(arc
		(start 351.77984 -283.300424)
		(mid 351.935768 -282.996132)
		(end 351.77984 -282.69184)
		(width 0.1143)
		(layer "In11.Cu")
		(net "P5E_CPU0_P1_RX_DN<7>")
	)
	(arc
		(start 351.239074 -280.220674)
		(mid 350.995747 -279.756108)
		(end 351.239074 -279.291542)
		(width 0.1143)
		(layer "In11.Cu")
		(net "P5E_CPU0_P1_RX_DN<7>")
	)
	(arc
		(start 351.697544 -291.449506)
		(mid 351.704617 -291.444497)
		(end 351.711768 -291.4396)
		(width 0.1143)
		(layer "In11.Cu")
		(net "P5E_CPU0_P1_RX_DN<7>")
	)
	(arc
		(start 350.147636 -372.578122)
		(mid 353.612004 -370.726616)
		(end 356.648512 -368.234722)
		(width 0.14224)
		(layer "In11.Cu")
		(net "P5E_CPU0_P1_RX_DN<7>")
	)
	(arc
		(start 351.711768 -292.372288)
		(mid 351.704618 -292.36739)
		(end 351.697544 -292.362382)
		(width 0.1143)
		(layer "In11.Cu")
		(net "P5E_CPU0_P1_RX_DN<7>")
	)
	(arc
		(start 362.844334 -362.0389)
		(mid 366.512416 -357.569162)
		(end 369.238022 -352.469704)
		(width 0.14224)
		(layer "In11.Cu")
		(net "P5E_CPU0_P1_RX_DN<7>")
	)
	(arc
		(start 351.77984 -278.440388)
		(mid 351.876975 -278.337519)
		(end 351.928938 -278.205946)
		(width 0.1143)
		(layer "In11.Cu")
		(net "P5E_CPU0_P1_RX_DN<7>")
	)
	(arc
		(start 351.465896 -295.14165)
		(mid 351.529873 -294.88902)
		(end 351.697544 -294.68953)
		(width 0.1143)
		(layer "In11.Cu")
		(net "P5E_CPU0_P1_RX_DN<7>")
	)
	(arc
		(start 351.695512 -284.261052)
		(mid 351.472628 -283.806138)
		(end 351.695512 -283.351224)
		(width 0.1143)
		(layer "In11.Cu")
		(net "P5E_CPU0_P1_RX_DN<7>")
	)
	(arc
		(start 351.696528 -293.981632)
		(mid 351.471357 -293.525956)
		(end 351.696528 -293.07028)
		(width 0.1143)
		(layer "In11.Cu")
		(net "P5E_CPU0_P1_RX_DN<7>")
	)
	(arc
		(start 351.465896 -287.045908)
		(mid 351.531132 -286.782317)
		(end 351.711768 -286.579564)
		(width 0.1143)
		(layer "In11.Cu")
		(net "P5E_CPU0_P1_RX_DN<7>")
	)
	(arc
		(start 351.77984 -284.920436)
		(mid 351.935768 -284.616144)
		(end 351.77984 -284.311852)
		(width 0.1143)
		(layer "In11.Cu")
		(net "P5E_CPU0_P1_RX_DN<7>")
	)
	(arc
		(start 351.935796 -287.856168)
		(mid 351.894541 -287.685197)
		(end 351.77984 -287.551876)
		(width 0.1143)
		(layer "In11.Cu")
		(net "P5E_CPU0_P1_RX_DN<7>")
	)
	(arc
		(start 351.29089 -279.261316)
		(mid 351.428322 -279.124057)
		(end 351.478596 -278.93645)
		(width 0.1143)
		(layer "In11.Cu")
		(net "P5E_CPU0_P1_RX_DN<7>")
	)
	(arc
		(start 351.935796 -286.236156)
		(mid 351.894541 -286.065185)
		(end 351.77984 -285.931864)
		(width 0.1143)
		(layer "In11.Cu")
		(net "P5E_CPU0_P1_RX_DN<7>")
	)
	(arc
		(start 351.465896 -295.145968)
		(mid 351.465892 -295.143809)
		(end 351.465896 -295.14165)
		(width 0.1143)
		(layer "In11.Cu")
		(net "P5E_CPU0_P1_RX_DN<7>")
	)
	(arc
		(start 351.726754 -289.1409)
		(mid 351.453203 -288.66592)
		(end 351.726754 -288.19094)
		(width 0.1143)
		(layer "In11.Cu")
		(net "P5E_CPU0_P1_RX_DN<7>")
	)
	(segment
		(start 352.027998 -276.250146)
		(end 351.561146 -276.516084)
		(width 0.12954)
		(layer "F.Cu")
		(net "P5E_CPU0_P1_RX_DN<6>")
	)
	(segment
		(start 342.998044 -393.69238)
		(end 343.518744 -393.69238)
		(width 0.127)
		(layer "F.Cu")
		(net "P5E_CPU0_P1_RX_DN<6>")
	)
	(segment
		(start 350.769174 -281.72156)
		(end 350.83877 -281.68092)
		(width 0.1143)
		(layer "In11.Cu")
		(net "P5E_CPU0_P1_RX_DN<6>")
	)
	(segment
		(start 351.859088 -276.516084)
		(end 351.561146 -276.516084)
		(width 0.1143)
		(layer "In11.Cu")
		(net "P5E_CPU0_P1_RX_DN<6>")
	)
	(segment
		(start 343.26576 -387.894068)
		(end 343.09685 -387.798564)
		(width 0.14224)
		(layer "In11.Cu")
		(net "P5E_CPU0_P1_RX_DN<6>")
	)
	(segment
		(start 350.33712 -279.26919)
		(end 350.338136 -279.268682)
		(width 0.1143)
		(layer "In11.Cu")
		(net "P5E_CPU0_P1_RX_DN<6>")
	)
	(segment
		(start 350.33712 -280.243026)
		(end 350.335596 -280.24201)
		(width 0.1143)
		(layer "In11.Cu")
		(net "P5E_CPU0_P1_RX_DN<6>")
	)
	(segment
		(start 350.344232 -280.24709)
		(end 350.342708 -280.246074)
		(width 0.1143)
		(layer "In11.Cu")
		(net "P5E_CPU0_P1_RX_DN<6>")
	)
	(segment
		(start 350.769174 -278.481536)
		(end 350.83877 -278.440896)
		(width 0.1143)
		(layer "In11.Cu")
		(net "P5E_CPU0_P1_RX_DN<6>")
	)
	(segment
		(start 343.67724 -393.22883)
		(end 343.682066 -392.616944)
		(width 0.14224)
		(layer "In11.Cu")
		(net "P5E_CPU0_P1_RX_DN<6>")
	)
	(segment
		(start 350.015302 -296.419016)
		(end 350.015302 -296.390568)
		(width 0.1143)
		(layer "In11.Cu")
		(net "P5E_CPU0_P1_RX_DN<6>")
	)
	(segment
		(start 368.249962 -328.08418)
		(end 366.531398 -324.79615)
		(width 0.14224)
		(layer "In11.Cu")
		(net "P5E_CPU0_P1_RX_DN<6>")
	)
	(segment
		(start 343.56675 -388.981188)
		(end 343.39784 -388.885684)
		(width 0.14224)
		(layer "In11.Cu")
		(net "P5E_CPU0_P1_RX_DN<6>")
	)
	(segment
		(start 350.83877 -294.031162)
		(end 350.769174 -293.990522)
		(width 0.1143)
		(layer "In11.Cu")
		(net "P5E_CPU0_P1_RX_DN<6>")
	)
	(segment
		(start 350.33458 -280.241502)
		(end 350.33204 -280.239978)
		(width 0.1143)
		(layer "In11.Cu")
		(net "P5E_CPU0_P1_RX_DN<6>")
	)
	(segment
		(start 345.197176 -373.607584)
		(end 349.83928 -371.684804)
		(width 0.14224)
		(layer "In11.Cu")
		(net "P5E_CPU0_P1_RX_DN<6>")
	)
	(segment
		(start 350.769174 -284.961584)
		(end 350.83877 -284.920944)
		(width 0.1143)
		(layer "In11.Cu")
		(net "P5E_CPU0_P1_RX_DN<6>")
	)
	(segment
		(start 351.74809 -276.838664)
		(end 351.77984 -276.820376)
		(width 0.1143)
		(layer "In11.Cu")
		(net "P5E_CPU0_P1_RX_DN<6>")
	)
	(segment
		(start 343.680542 -389.392414)
		(end 343.56675 -388.981188)
		(width 0.14224)
		(layer "In11.Cu")
		(net "P5E_CPU0_P1_RX_DN<6>")
	)
	(segment
		(start 355.713284 -367.759996)
		(end 362.225082 -361.248198)
		(width 0.14224)
		(layer "In11.Cu")
		(net "P5E_CPU0_P1_RX_DN<6>")
	)
	(segment
		(start 343.872058 -393.787376)
		(end 343.872566 -393.786868)
		(width 0.14224)
		(layer "In11.Cu")
		(net "P5E_CPU0_P1_RX_DN<6>")
	)
	(segment
		(start 343.518744 -393.69238)
		(end 343.872058 -393.787376)
		(width 0.14224)
		(layer "In11.Cu")
		(net "P5E_CPU0_P1_RX_DN<6>")
	)
	(segment
		(start 343.981532 -390.479534)
		(end 343.86774 -390.068308)
		(width 0.14224)
		(layer "In11.Cu")
		(net "P5E_CPU0_P1_RX_DN<6>")
	)
	(segment
		(start 350.061022 -295.864788)
		(end 350.525842 -295.399968)
		(width 0.1143)
		(layer "In11.Cu")
		(net "P5E_CPU0_P1_RX_DN<6>")
	)
	(segment
		(start 351.278698 -277.64867)
		(end 351.304606 -277.63343)
		(width 0.1143)
		(layer "In11.Cu")
		(net "P5E_CPU0_P1_RX_DN<6>")
	)
	(segment
		(start 350.769174 -288.201354)
		(end 350.80829 -288.178494)
		(width 0.1143)
		(layer "In11.Cu")
		(net "P5E_CPU0_P1_RX_DN<6>")
	)
	(segment
		(start 353.60483 -307.3527)
		(end 350.015302 -298.686728)
		(width 0.14224)
		(layer "In11.Cu")
		(net "P5E_CPU0_P1_RX_DN<6>")
	)
	(segment
		(start 351.27565 -277.650194)
		(end 351.277174 -277.649178)
		(width 0.1143)
		(layer "In11.Cu")
		(net "P5E_CPU0_P1_RX_DN<6>")
	)
	(segment
		(start 343.584784 -389.561324)
		(end 343.680542 -389.392414)
		(width 0.14224)
		(layer "In11.Cu")
		(net "P5E_CPU0_P1_RX_DN<6>")
	)
	(segment
		(start 350.771206 -286.579818)
		(end 350.80829 -286.558482)
		(width 0.1143)
		(layer "In11.Cu")
		(net "P5E_CPU0_P1_RX_DN<6>")
	)
	(segment
		(start 343.09685 -387.798564)
		(end 342.982804 -387.387084)
		(width 0.14224)
		(layer "In11.Cu")
		(net "P5E_CPU0_P1_RX_DN<6>")
	)
	(segment
		(start 350.769174 -289.821366)
		(end 350.83877 -289.780726)
		(width 0.1143)
		(layer "In11.Cu")
		(net "P5E_CPU0_P1_RX_DN<6>")
	)
	(segment
		(start 369.305332 -333.956152)
		(end 368.249962 -328.08418)
		(width 0.14224)
		(layer "In11.Cu")
		(net "P5E_CPU0_P1_RX_DN<6>")
	)
	(segment
		(start 350.015302 -298.686728)
		(end 350.015302 -296.419016)
		(width 0.14224)
		(layer "In11.Cu")
		(net "P5E_CPU0_P1_RX_DN<6>")
	)
	(segment
		(start 351.711768 -276.859746)
		(end 351.74809 -276.838664)
		(width 0.1143)
		(layer "In11.Cu")
		(net "P5E_CPU0_P1_RX_DN<6>")
	)
	(segment
		(start 350.015302 -296.390568)
		(end 350.061022 -296.344848)
		(width 0.1143)
		(layer "In11.Cu")
		(net "P5E_CPU0_P1_RX_DN<6>")
	)
	(segment
		(start 343.078562 -387.218174)
		(end 342.119966 -383.7559)
		(width 0.14224)
		(layer "In11.Cu")
		(net "P5E_CPU0_P1_RX_DN<6>")
	)
	(segment
		(start 351.27819 -277.64867)
		(end 351.278698 -277.64867)
		(width 0.1143)
		(layer "In11.Cu")
		(net "P5E_CPU0_P1_RX_DN<6>")
	)
	(segment
		(start 343.994232 -393.716764)
		(end 343.994232 -393.545822)
		(width 0.14224)
		(layer "In11.Cu")
		(net "P5E_CPU0_P1_RX_DN<6>")
	)
	(segment
		(start 350.83877 -284.311344)
		(end 350.769174 -284.270704)
		(width 0.1143)
		(layer "In11.Cu")
		(net "P5E_CPU0_P1_RX_DN<6>")
	)
	(segment
		(start 342.982804 -387.387084)
		(end 343.078562 -387.218174)
		(width 0.14224)
		(layer "In11.Cu")
		(net "P5E_CPU0_P1_RX_DN<6>")
	)
	(segment
		(start 350.342708 -280.246074)
		(end 350.340168 -280.244804)
		(width 0.1143)
		(layer "In11.Cu")
		(net "P5E_CPU0_P1_RX_DN<6>")
	)
	(segment
		(start 343.69883 -389.972804)
		(end 343.584784 -389.561324)
		(width 0.14224)
		(layer "In11.Cu")
		(net "P5E_CPU0_P1_RX_DN<6>")
	)
	(segment
		(start 350.33204 -280.239978)
		(end 350.330516 -280.238962)
		(width 0.1143)
		(layer "In11.Cu")
		(net "P5E_CPU0_P1_RX_DN<6>")
	)
	(segment
		(start 350.83877 -289.171126)
		(end 350.769174 -289.130486)
		(width 0.1143)
		(layer "In11.Cu")
		(net "P5E_CPU0_P1_RX_DN<6>")
	)
	(segment
		(start 350.338898 -279.268174)
		(end 350.340168 -279.267412)
		(width 0.1143)
		(layer "In11.Cu")
		(net "P5E_CPU0_P1_RX_DN<6>")
	)
	(segment
		(start 343.872566 -393.786868)
		(end 343.994232 -393.716764)
		(width 0.14224)
		(layer "In11.Cu")
		(net "P5E_CPU0_P1_RX_DN<6>")
	)
	(segment
		(start 350.80829 -286.558482)
		(end 350.840802 -286.539686)
		(width 0.1143)
		(layer "In11.Cu")
		(net "P5E_CPU0_P1_RX_DN<6>")
	)
	(segment
		(start 368.271552 -352.198686)
		(end 370.360956 -347.1545)
		(width 0.14224)
		(layer "In11.Cu")
		(net "P5E_CPU0_P1_RX_DN<6>")
	)
	(segment
		(start 350.80829 -288.178494)
		(end 350.840802 -288.159698)
		(width 0.1143)
		(layer "In11.Cu")
		(net "P5E_CPU0_P1_RX_DN<6>")
	)
	(segment
		(start 350.330516 -280.238962)
		(end 350.29902 -280.220674)
		(width 0.1143)
		(layer "In11.Cu")
		(net "P5E_CPU0_P1_RX_DN<6>")
	)
	(segment
		(start 350.769174 -283.341572)
		(end 350.83877 -283.300932)
		(width 0.1143)
		(layer "In11.Cu")
		(net "P5E_CPU0_P1_RX_DN<6>")
	)
	(segment
		(start 350.369886 -280.261822)
		(end 350.344232 -280.24709)
		(width 0.1143)
		(layer "In11.Cu")
		(net "P5E_CPU0_P1_RX_DN<6>")
	)
	(segment
		(start 350.83877 -281.07132)
		(end 350.769174 -281.03068)
		(width 0.1143)
		(layer "In11.Cu")
		(net "P5E_CPU0_P1_RX_DN<6>")
	)
	(segment
		(start 359.692194 -316.462918)
		(end 353.60483 -307.3527)
		(width 0.14224)
		(layer "In11.Cu")
		(net "P5E_CPU0_P1_RX_DN<6>")
	)
	(segment
		(start 350.769174 -294.681402)
		(end 350.83877 -294.640762)
		(width 0.1143)
		(layer "In11.Cu")
		(net "P5E_CPU0_P1_RX_DN<6>")
	)
	(segment
		(start 342.453976 -375.795286)
		(end 343.522808 -374.726454)
		(width 0.14224)
		(layer "In11.Cu")
		(net "P5E_CPU0_P1_RX_DN<6>")
	)
	(segment
		(start 351.304606 -277.63343)
		(end 351.305368 -277.632922)
		(width 0.1143)
		(layer "In11.Cu")
		(net "P5E_CPU0_P1_RX_DN<6>")
	)
	(segment
		(start 366.531398 -324.79615)
		(end 359.692194 -316.462918)
		(width 0.14224)
		(layer "In11.Cu")
		(net "P5E_CPU0_P1_RX_DN<6>")
	)
	(segment
		(start 343.86774 -390.068308)
		(end 343.69883 -389.972804)
		(width 0.14224)
		(layer "In11.Cu")
		(net "P5E_CPU0_P1_RX_DN<6>")
	)
	(segment
		(start 342.044274 -383.197354)
		(end 342.044274 -376.784616)
		(width 0.14224)
		(layer "In11.Cu")
		(net "P5E_CPU0_P1_RX_DN<6>")
	)
	(segment
		(start 350.769174 -286.581342)
		(end 350.771206 -286.579818)
		(width 0.1143)
		(layer "In11.Cu")
		(net "P5E_CPU0_P1_RX_DN<6>")
	)
	(segment
		(start 350.338136 -279.268682)
		(end 350.338898 -279.268174)
		(width 0.1143)
		(layer "In11.Cu")
		(net "P5E_CPU0_P1_RX_DN<6>")
	)
	(segment
		(start 351.277174 -277.649178)
		(end 351.27819 -277.64867)
		(width 0.1143)
		(layer "In11.Cu")
		(net "P5E_CPU0_P1_RX_DN<6>")
	)
	(segment
		(start 350.769174 -291.441378)
		(end 350.83877 -291.400738)
		(width 0.1143)
		(layer "In11.Cu")
		(net "P5E_CPU0_P1_RX_DN<6>")
	)
	(segment
		(start 350.83877 -287.551368)
		(end 350.771714 -287.512252)
		(width 0.1143)
		(layer "In11.Cu")
		(net "P5E_CPU0_P1_RX_DN<6>")
	)
	(segment
		(start 350.335596 -280.24201)
		(end 350.33458 -280.241502)
		(width 0.1143)
		(layer "In11.Cu")
		(net "P5E_CPU0_P1_RX_DN<6>")
	)
	(segment
		(start 350.340168 -279.267412)
		(end 350.369886 -279.250394)
		(width 0.1143)
		(layer "In11.Cu")
		(net "P5E_CPU0_P1_RX_DN<6>")
	)
	(segment
		(start 343.682066 -392.616944)
		(end 343.986104 -392.31316)
		(width 0.14224)
		(layer "In11.Cu")
		(net "P5E_CPU0_P1_RX_DN<6>")
	)
	(segment
		(start 351.465896 -277.310088)
		(end 351.465896 -277.309834)
		(width 0.1143)
		(layer "In11.Cu")
		(net "P5E_CPU0_P1_RX_DN<6>")
	)
	(segment
		(start 343.986104 -392.31316)
		(end 343.986104 -390.513316)
		(width 0.14224)
		(layer "In11.Cu")
		(net "P5E_CPU0_P1_RX_DN<6>")
	)
	(segment
		(start 350.525842 -295.399968)
		(end 350.525842 -295.145968)
		(width 0.1143)
		(layer "In11.Cu")
		(net "P5E_CPU0_P1_RX_DN<6>")
	)
	(segment
		(start 350.061022 -296.344848)
		(end 350.061022 -295.864788)
		(width 0.1143)
		(layer "In11.Cu")
		(net "P5E_CPU0_P1_RX_DN<6>")
	)
	(segment
		(start 350.340168 -280.244804)
		(end 350.338898 -280.244042)
		(width 0.1143)
		(layer "In11.Cu")
		(net "P5E_CPU0_P1_RX_DN<6>")
	)
	(segment
		(start 350.83877 -290.791138)
		(end 350.769174 -290.750498)
		(width 0.1143)
		(layer "In11.Cu")
		(net "P5E_CPU0_P1_RX_DN<6>")
	)
	(segment
		(start 343.39784 -388.885684)
		(end 343.283794 -388.474204)
		(width 0.14224)
		(layer "In11.Cu")
		(net "P5E_CPU0_P1_RX_DN<6>")
	)
	(segment
		(start 351.239074 -277.67153)
		(end 351.27565 -277.650194)
		(width 0.1143)
		(layer "In11.Cu")
		(net "P5E_CPU0_P1_RX_DN<6>")
	)
	(segment
		(start 350.83877 -285.931356)
		(end 350.769174 -285.890716)
		(width 0.1143)
		(layer "In11.Cu")
		(net "P5E_CPU0_P1_RX_DN<6>")
	)
	(segment
		(start 350.29902 -279.291542)
		(end 350.335596 -279.270206)
		(width 0.1143)
		(layer "In11.Cu")
		(net "P5E_CPU0_P1_RX_DN<6>")
	)
	(segment
		(start 350.338898 -280.244042)
		(end 350.338136 -280.243534)
		(width 0.1143)
		(layer "In11.Cu")
		(net "P5E_CPU0_P1_RX_DN<6>")
	)
	(segment
		(start 350.335596 -279.270206)
		(end 350.33712 -279.26919)
		(width 0.1143)
		(layer "In11.Cu")
		(net "P5E_CPU0_P1_RX_DN<6>")
	)
	(segment
		(start 350.769174 -293.06139)
		(end 350.83877 -293.02075)
		(width 0.1143)
		(layer "In11.Cu")
		(net "P5E_CPU0_P1_RX_DN<6>")
	)
	(segment
		(start 350.83877 -282.691332)
		(end 350.769174 -282.650692)
		(width 0.1143)
		(layer "In11.Cu")
		(net "P5E_CPU0_P1_RX_DN<6>")
	)
	(segment
		(start 343.379552 -388.305294)
		(end 343.26576 -387.894068)
		(width 0.14224)
		(layer "In11.Cu")
		(net "P5E_CPU0_P1_RX_DN<6>")
	)
	(segment
		(start 343.994232 -393.545822)
		(end 343.67724 -393.22883)
		(width 0.14224)
		(layer "In11.Cu")
		(net "P5E_CPU0_P1_RX_DN<6>")
	)
	(segment
		(start 370.360956 -339.828378)
		(end 369.305332 -333.956152)
		(width 0.14224)
		(layer "In11.Cu")
		(net "P5E_CPU0_P1_RX_DN<6>")
	)
	(segment
		(start 343.283794 -388.474204)
		(end 343.379552 -388.305294)
		(width 0.14224)
		(layer "In11.Cu")
		(net "P5E_CPU0_P1_RX_DN<6>")
	)
	(segment
		(start 350.338136 -280.243534)
		(end 350.33712 -280.243026)
		(width 0.1143)
		(layer "In11.Cu")
		(net "P5E_CPU0_P1_RX_DN<6>")
	)
	(segment
		(start 350.83877 -292.41115)
		(end 350.769174 -292.37051)
		(width 0.1143)
		(layer "In11.Cu")
		(net "P5E_CPU0_P1_RX_DN<6>")
	)
	(segment
		(start 351.928938 -276.585934)
		(end 351.859088 -276.516084)
		(width 0.1143)
		(layer "In11.Cu")
		(net "P5E_CPU0_P1_RX_DN<6>")
	)
	(segment
		(start 370.360956 -347.1545)
		(end 370.360956 -339.828378)
		(width 0.14224)
		(layer "In11.Cu")
		(net "P5E_CPU0_P1_RX_DN<6>")
	)
	(arc
		(start 351.314512 -277.62581)
		(mid 351.408429 -277.500726)
		(end 351.461324 -277.353522)
		(width 0.1143)
		(layer "In11.Cu")
		(net "P5E_CPU0_P1_RX_DN<6>")
	)
	(arc
		(start 350.525842 -287.045908)
		(mid 350.590357 -286.783689)
		(end 350.769174 -286.581342)
		(width 0.1143)
		(layer "In11.Cu")
		(net "P5E_CPU0_P1_RX_DN<6>")
	)
	(arc
		(start 342.119966 -383.7559)
		(mid 342.063223 -383.479187)
		(end 342.044274 -383.197354)
		(width 0.14224)
		(layer "In11.Cu")
		(net "P5E_CPU0_P1_RX_DN<6>")
	)
	(arc
		(start 350.83877 -293.02075)
		(mid 350.995747 -292.71595)
		(end 350.83877 -292.41115)
		(width 0.1143)
		(layer "In11.Cu")
		(net "P5E_CPU0_P1_RX_DN<6>")
	)
	(arc
		(start 350.769174 -289.130486)
		(mid 350.525847 -288.66592)
		(end 350.769174 -288.201354)
		(width 0.1143)
		(layer "In11.Cu")
		(net "P5E_CPU0_P1_RX_DN<6>")
	)
	(arc
		(start 350.525842 -280.566114)
		(mid 350.484587 -280.395143)
		(end 350.369886 -280.261822)
		(width 0.1143)
		(layer "In11.Cu")
		(net "P5E_CPU0_P1_RX_DN<6>")
	)
	(arc
		(start 350.769174 -281.03068)
		(mid 350.590361 -280.82833)
		(end 350.525842 -280.566114)
		(width 0.1143)
		(layer "In11.Cu")
		(net "P5E_CPU0_P1_RX_DN<6>")
	)
	(arc
		(start 343.522808 -374.726454)
		(mid 344.304893 -374.084565)
		(end 345.197176 -373.607584)
		(width 0.14224)
		(layer "In11.Cu")
		(net "P5E_CPU0_P1_RX_DN<6>")
	)
	(arc
		(start 350.83877 -294.640762)
		(mid 350.995747 -294.335962)
		(end 350.83877 -294.031162)
		(width 0.1143)
		(layer "In11.Cu")
		(net "P5E_CPU0_P1_RX_DN<6>")
	)
	(arc
		(start 350.769174 -293.990522)
		(mid 350.525847 -293.525956)
		(end 350.769174 -293.06139)
		(width 0.1143)
		(layer "In11.Cu")
		(net "P5E_CPU0_P1_RX_DN<6>")
	)
	(arc
		(start 350.83877 -278.440896)
		(mid 350.954197 -278.30752)
		(end 350.995742 -278.136096)
		(width 0.1143)
		(layer "In11.Cu")
		(net "P5E_CPU0_P1_RX_DN<6>")
	)
	(arc
		(start 350.995742 -278.136096)
		(mid 351.060257 -277.873877)
		(end 351.239074 -277.67153)
		(width 0.1143)
		(layer "In11.Cu")
		(net "P5E_CPU0_P1_RX_DN<6>")
	)
	(arc
		(start 351.305368 -277.632922)
		(mid 351.309968 -277.629401)
		(end 351.314512 -277.62581)
		(width 0.1143)
		(layer "In11.Cu")
		(net "P5E_CPU0_P1_RX_DN<6>")
	)
	(arc
		(start 351.77984 -276.820376)
		(mid 351.876975 -276.717507)
		(end 351.928938 -276.585934)
		(width 0.1143)
		(layer "In11.Cu")
		(net "P5E_CPU0_P1_RX_DN<6>")
	)
	(arc
		(start 351.465896 -277.309834)
		(mid 351.534857 -277.055303)
		(end 351.711768 -276.859746)
		(width 0.1143)
		(layer "In11.Cu")
		(net "P5E_CPU0_P1_RX_DN<6>")
	)
	(arc
		(start 350.769174 -285.890716)
		(mid 350.525847 -285.42615)
		(end 350.769174 -284.961584)
		(width 0.1143)
		(layer "In11.Cu")
		(net "P5E_CPU0_P1_RX_DN<6>")
	)
	(arc
		(start 350.771714 -287.512252)
		(mid 350.591062 -287.309507)
		(end 350.525842 -287.045908)
		(width 0.1143)
		(layer "In11.Cu")
		(net "P5E_CPU0_P1_RX_DN<6>")
	)
	(arc
		(start 350.769174 -282.650692)
		(mid 350.525847 -282.186126)
		(end 350.769174 -281.72156)
		(width 0.1143)
		(layer "In11.Cu")
		(net "P5E_CPU0_P1_RX_DN<6>")
	)
	(arc
		(start 350.83877 -291.400738)
		(mid 350.995747 -291.095938)
		(end 350.83877 -290.791138)
		(width 0.1143)
		(layer "In11.Cu")
		(net "P5E_CPU0_P1_RX_DN<6>")
	)
	(arc
		(start 350.83877 -284.920944)
		(mid 350.995747 -284.616144)
		(end 350.83877 -284.311344)
		(width 0.1143)
		(layer "In11.Cu")
		(net "P5E_CPU0_P1_RX_DN<6>")
	)
	(arc
		(start 350.83877 -283.300932)
		(mid 350.995747 -282.996132)
		(end 350.83877 -282.691332)
		(width 0.1143)
		(layer "In11.Cu")
		(net "P5E_CPU0_P1_RX_DN<6>")
	)
	(arc
		(start 350.83877 -281.68092)
		(mid 350.995747 -281.37612)
		(end 350.83877 -281.07132)
		(width 0.1143)
		(layer "In11.Cu")
		(net "P5E_CPU0_P1_RX_DN<6>")
	)
	(arc
		(start 350.369886 -279.250394)
		(mid 350.484562 -279.11706)
		(end 350.525842 -278.946102)
		(width 0.1143)
		(layer "In11.Cu")
		(net "P5E_CPU0_P1_RX_DN<6>")
	)
	(arc
		(start 350.525842 -278.946102)
		(mid 350.590357 -278.683883)
		(end 350.769174 -278.481536)
		(width 0.1143)
		(layer "In11.Cu")
		(net "P5E_CPU0_P1_RX_DN<6>")
	)
	(arc
		(start 350.29902 -280.220674)
		(mid 350.055693 -279.756108)
		(end 350.29902 -279.291542)
		(width 0.1143)
		(layer "In11.Cu")
		(net "P5E_CPU0_P1_RX_DN<6>")
	)
	(arc
		(start 362.225082 -361.248198)
		(mid 365.694001 -357.021229)
		(end 368.271552 -352.198686)
		(width 0.14224)
		(layer "In11.Cu")
		(net "P5E_CPU0_P1_RX_DN<6>")
	)
	(arc
		(start 350.995742 -287.856168)
		(mid 350.954193 -287.684746)
		(end 350.83877 -287.551368)
		(width 0.1143)
		(layer "In11.Cu")
		(net "P5E_CPU0_P1_RX_DN<6>")
	)
	(arc
		(start 350.83877 -289.780726)
		(mid 350.995747 -289.475926)
		(end 350.83877 -289.171126)
		(width 0.1143)
		(layer "In11.Cu")
		(net "P5E_CPU0_P1_RX_DN<6>")
	)
	(arc
		(start 349.83928 -371.684804)
		(mid 352.969551 -370.011657)
		(end 355.713284 -367.759996)
		(width 0.14224)
		(layer "In11.Cu")
		(net "P5E_CPU0_P1_RX_DN<6>")
	)
	(arc
		(start 350.840802 -288.159698)
		(mid 350.954731 -288.026551)
		(end 350.995742 -287.856168)
		(width 0.1143)
		(layer "In11.Cu")
		(net "P5E_CPU0_P1_RX_DN<6>")
	)
	(arc
		(start 342.044274 -376.784616)
		(mid 342.150754 -376.249215)
		(end 342.453976 -375.795286)
		(width 0.14224)
		(layer "In11.Cu")
		(net "P5E_CPU0_P1_RX_DN<6>")
	)
	(arc
		(start 351.461324 -277.353522)
		(mid 351.464509 -277.3319)
		(end 351.465896 -277.310088)
		(width 0.1143)
		(layer "In11.Cu")
		(net "P5E_CPU0_P1_RX_DN<6>")
	)
	(arc
		(start 350.769174 -284.270704)
		(mid 350.525847 -283.806138)
		(end 350.769174 -283.341572)
		(width 0.1143)
		(layer "In11.Cu")
		(net "P5E_CPU0_P1_RX_DN<6>")
	)
	(arc
		(start 350.525842 -295.145968)
		(mid 350.590357 -294.883749)
		(end 350.769174 -294.681402)
		(width 0.1143)
		(layer "In11.Cu")
		(net "P5E_CPU0_P1_RX_DN<6>")
	)
	(arc
		(start 350.769174 -292.37051)
		(mid 350.525847 -291.905944)
		(end 350.769174 -291.441378)
		(width 0.1143)
		(layer "In11.Cu")
		(net "P5E_CPU0_P1_RX_DN<6>")
	)
	(arc
		(start 350.840802 -286.539686)
		(mid 350.954731 -286.406539)
		(end 350.995742 -286.236156)
		(width 0.1143)
		(layer "In11.Cu")
		(net "P5E_CPU0_P1_RX_DN<6>")
	)
	(arc
		(start 350.995742 -286.236156)
		(mid 350.954193 -286.064734)
		(end 350.83877 -285.931356)
		(width 0.1143)
		(layer "In11.Cu")
		(net "P5E_CPU0_P1_RX_DN<6>")
	)
	(arc
		(start 350.769174 -290.750498)
		(mid 350.525847 -290.285932)
		(end 350.769174 -289.821366)
		(width 0.1143)
		(layer "In11.Cu")
		(net "P5E_CPU0_P1_RX_DN<6>")
	)
	(arc
		(start 343.986104 -390.513316)
		(mid 343.984957 -390.496271)
		(end 343.981532 -390.479534)
		(width 0.14224)
		(layer "In11.Cu")
		(net "P5E_CPU0_P1_RX_DN<6>")
	)
	(segment
		(start 349.20809 -274.630134)
		(end 348.741238 -274.896072)
		(width 0.12954)
		(layer "F.Cu")
		(net "P5E_CPU0_P1_RX_DN<5>")
	)
	(segment
		(start 341.798148 -393.69238)
		(end 342.318848 -393.69238)
		(width 0.127)
		(layer "F.Cu")
		(net "P5E_CPU0_P1_RX_DN<5>")
	)
	(segment
		(start 349.82912 -293.06139)
		(end 349.898716 -293.02075)
		(width 0.1143)
		(layer "In11.Cu")
		(net "P5E_CPU0_P1_RX_DN<5>")
	)
	(segment
		(start 349.898716 -285.931356)
		(end 349.82912 -285.890716)
		(width 0.1143)
		(layer "In11.Cu")
		(net "P5E_CPU0_P1_RX_DN<5>")
	)
	(segment
		(start 349.868236 -286.558482)
		(end 349.900748 -286.539686)
		(width 0.1143)
		(layer "In11.Cu")
		(net "P5E_CPU0_P1_RX_DN<5>")
	)
	(segment
		(start 338.71916 -378.230638)
		(end 338.710778 -378.218192)
		(width 0.14224)
		(layer "In11.Cu")
		(net "P5E_CPU0_P1_RX_DN<5>")
	)
	(segment
		(start 340.115652 -378.957586)
		(end 339.781642 -378.819664)
		(width 0.14224)
		(layer "In11.Cu")
		(net "P5E_CPU0_P1_RX_DN<5>")
	)
	(segment
		(start 349.398336 -279.268174)
		(end 349.398844 -279.268174)
		(width 0.1143)
		(layer "In11.Cu")
		(net "P5E_CPU0_P1_RX_DN<5>")
	)
	(segment
		(start 338.885022 -376.572526)
		(end 339.834474 -375.623074)
		(width 0.14224)
		(layer "In11.Cu")
		(net "P5E_CPU0_P1_RX_DN<5>")
	)
	(segment
		(start 349.868236 -288.178494)
		(end 349.900748 -288.159698)
		(width 0.1143)
		(layer "In11.Cu")
		(net "P5E_CPU0_P1_RX_DN<5>")
	)
	(segment
		(start 349.33128 -279.311354)
		(end 349.35922 -279.291288)
		(width 0.1143)
		(layer "In11.Cu")
		(net "P5E_CPU0_P1_RX_DN<5>")
	)
	(segment
		(start 341.1601 -384.779266)
		(end 341.05088 -384.366516)
		(width 0.14224)
		(layer "In11.Cu")
		(net "P5E_CPU0_P1_RX_DN<5>")
	)
	(segment
		(start 341.05088 -384.366516)
		(end 341.148416 -384.198876)
		(width 0.14224)
		(layer "In11.Cu")
		(net "P5E_CPU0_P1_RX_DN<5>")
	)
	(segment
		(start 342.672162 -393.787376)
		(end 342.67267 -393.786868)
		(width 0.14224)
		(layer "In11.Cu")
		(net "P5E_CPU0_P1_RX_DN<5>")
	)
	(segment
		(start 342.786208 -392.31316)
		(end 342.786208 -390.405874)
		(width 0.14224)
		(layer "In11.Cu")
		(net "P5E_CPU0_P1_RX_DN<5>")
	)
	(segment
		(start 349.400114 -280.244804)
		(end 349.398844 -280.244042)
		(width 0.1143)
		(layer "In11.Cu")
		(net "P5E_CPU0_P1_RX_DN<5>")
	)
	(segment
		(start 341.148416 -384.198876)
		(end 340.35619 -381.202692)
		(width 0.14224)
		(layer "In11.Cu")
		(net "P5E_CPU0_P1_RX_DN<5>")
	)
	(segment
		(start 342.48217 -392.616944)
		(end 342.786208 -392.31316)
		(width 0.14224)
		(layer "In11.Cu")
		(net "P5E_CPU0_P1_RX_DN<5>")
	)
	(segment
		(start 349.82912 -289.821366)
		(end 349.898716 -289.780726)
		(width 0.1143)
		(layer "In11.Cu")
		(net "P5E_CPU0_P1_RX_DN<5>")
	)
	(segment
		(start 341.327994 -384.876802)
		(end 341.1601 -384.779266)
		(width 0.14224)
		(layer "In11.Cu")
		(net "P5E_CPU0_P1_RX_DN<5>")
	)
	(segment
		(start 338.642452 -377.990862)
		(end 338.642452 -377.15825)
		(width 0.14224)
		(layer "In11.Cu")
		(net "P5E_CPU0_P1_RX_DN<5>")
	)
	(segment
		(start 349.898716 -282.691332)
		(end 349.82912 -282.650692)
		(width 0.1143)
		(layer "In11.Cu")
		(net "P5E_CPU0_P1_RX_DN<5>")
	)
	(segment
		(start 349.898716 -290.791138)
		(end 349.82912 -290.750498)
		(width 0.1143)
		(layer "In11.Cu")
		(net "P5E_CPU0_P1_RX_DN<5>")
	)
	(segment
		(start 349.898716 -292.41115)
		(end 349.82912 -292.37051)
		(width 0.1143)
		(layer "In11.Cu")
		(net "P5E_CPU0_P1_RX_DN<5>")
	)
	(segment
		(start 338.71916 -378.230892)
		(end 338.71916 -378.230638)
		(width 0.14224)
		(layer "In11.Cu")
		(net "P5E_CPU0_P1_RX_DN<5>")
	)
	(segment
		(start 342.67267 -393.786868)
		(end 342.794336 -393.716764)
		(width 0.14224)
		(layer "In11.Cu")
		(net "P5E_CPU0_P1_RX_DN<5>")
	)
	(segment
		(start 341.43696 -385.289298)
		(end 341.327994 -384.876802)
		(width 0.14224)
		(layer "In11.Cu")
		(net "P5E_CPU0_P1_RX_DN<5>")
	)
	(segment
		(start 349.82912 -291.441378)
		(end 349.898716 -291.400738)
		(width 0.1143)
		(layer "In11.Cu")
		(net "P5E_CPU0_P1_RX_DN<5>")
	)
	(segment
		(start 349.398844 -279.268174)
		(end 349.400114 -279.267412)
		(width 0.1143)
		(layer "In11.Cu")
		(net "P5E_CPU0_P1_RX_DN<5>")
	)
	(segment
		(start 349.401384 -275.387054)
		(end 349.39732 -275.384768)
		(width 0.1143)
		(layer "In11.Cu")
		(net "P5E_CPU0_P1_RX_DN<5>")
	)
	(segment
		(start 343.298526 -373.308372)
		(end 346.329254 -372.053104)
		(width 0.14224)
		(layer "In11.Cu")
		(net "P5E_CPU0_P1_RX_DN<5>")
	)
	(segment
		(start 349.39732 -275.384768)
		(end 349.397066 -275.384768)
		(width 0.1143)
		(layer "In11.Cu")
		(net "P5E_CPU0_P1_RX_DN<5>")
	)
	(segment
		(start 369.411758 -339.888322)
		(end 367.337848 -328.351896)
		(width 0.14224)
		(layer "In11.Cu")
		(net "P5E_CPU0_P1_RX_DN<5>")
	)
	(segment
		(start 349.82912 -278.481536)
		(end 349.898716 -278.440896)
		(width 0.1143)
		(layer "In11.Cu")
		(net "P5E_CPU0_P1_RX_DN<5>")
	)
	(segment
		(start 349.82912 -288.201354)
		(end 349.868236 -288.178494)
		(width 0.1143)
		(layer "In11.Cu")
		(net "P5E_CPU0_P1_RX_DN<5>")
	)
	(segment
		(start 349.831152 -286.579818)
		(end 349.868236 -286.558482)
		(width 0.1143)
		(layer "In11.Cu")
		(net "P5E_CPU0_P1_RX_DN<5>")
	)
	(segment
		(start 369.411758 -346.84589)
		(end 369.411758 -339.888322)
		(width 0.14224)
		(layer "In11.Cu")
		(net "P5E_CPU0_P1_RX_DN<5>")
	)
	(segment
		(start 349.03918 -274.896072)
		(end 348.741238 -274.896072)
		(width 0.1143)
		(layer "In11.Cu")
		(net "P5E_CPU0_P1_RX_DN<5>")
	)
	(segment
		(start 342.318848 -393.69238)
		(end 342.672162 -393.787376)
		(width 0.14224)
		(layer "In11.Cu")
		(net "P5E_CPU0_P1_RX_DN<5>")
	)
	(segment
		(start 349.395288 -280.241756)
		(end 349.35922 -280.220928)
		(width 0.1143)
		(layer "In11.Cu")
		(net "P5E_CPU0_P1_RX_DN<5>")
	)
	(segment
		(start 349.898716 -277.831296)
		(end 349.82912 -277.790656)
		(width 0.1143)
		(layer "In11.Cu")
		(net "P5E_CPU0_P1_RX_DN<5>")
	)
	(segment
		(start 349.398082 -280.243534)
		(end 349.395288 -280.241756)
		(width 0.1143)
		(layer "In11.Cu")
		(net "P5E_CPU0_P1_RX_DN<5>")
	)
	(segment
		(start 342.794336 -393.545822)
		(end 342.477344 -393.22883)
		(width 0.14224)
		(layer "In11.Cu")
		(net "P5E_CPU0_P1_RX_DN<5>")
	)
	(segment
		(start 349.898716 -289.171126)
		(end 349.82912 -289.130486)
		(width 0.1143)
		(layer "In11.Cu")
		(net "P5E_CPU0_P1_RX_DN<5>")
	)
	(segment
		(start 349.35922 -279.291288)
		(end 349.376492 -279.281382)
		(width 0.1143)
		(layer "In11.Cu")
		(net "P5E_CPU0_P1_RX_DN<5>")
	)
	(segment
		(start 349.376492 -279.281382)
		(end 349.380556 -279.277064)
		(width 0.1143)
		(layer "In11.Cu")
		(net "P5E_CPU0_P1_RX_DN<5>")
	)
	(segment
		(start 338.725764 -378.240798)
		(end 338.71916 -378.230892)
		(width 0.14224)
		(layer "In11.Cu")
		(net "P5E_CPU0_P1_RX_DN<5>")
	)
	(segment
		(start 349.380556 -279.277064)
		(end 349.398336 -279.268174)
		(width 0.1143)
		(layer "In11.Cu")
		(net "P5E_CPU0_P1_RX_DN<5>")
	)
	(segment
		(start 349.402654 -280.246074)
		(end 349.400114 -280.244804)
		(width 0.1143)
		(layer "In11.Cu")
		(net "P5E_CPU0_P1_RX_DN<5>")
	)
	(segment
		(start 349.121984 -274.978876)
		(end 349.03918 -274.896072)
		(width 0.1143)
		(layer "In11.Cu")
		(net "P5E_CPU0_P1_RX_DN<5>")
	)
	(segment
		(start 342.794336 -393.716764)
		(end 342.794336 -393.545822)
		(width 0.14224)
		(layer "In11.Cu")
		(net "P5E_CPU0_P1_RX_DN<5>")
	)
	(segment
		(start 365.750094 -325.31431)
		(end 358.941624 -317.018162)
		(width 0.14224)
		(layer "In11.Cu")
		(net "P5E_CPU0_P1_RX_DN<5>")
	)
	(segment
		(start 358.941624 -317.018162)
		(end 352.779076 -307.795422)
		(width 0.14224)
		(layer "In11.Cu")
		(net "P5E_CPU0_P1_RX_DN<5>")
	)
	(segment
		(start 349.116142 -295.739058)
		(end 349.371666 -295.483534)
		(width 0.1143)
		(layer "In11.Cu")
		(net "P5E_CPU0_P1_RX_DN<5>")
	)
	(segment
		(start 369.245134 -347.247718)
		(end 369.411758 -346.84589)
		(width 0.14224)
		(layer "In11.Cu")
		(net "P5E_CPU0_P1_RX_DN<5>")
	)
	(segment
		(start 341.616284 -385.967224)
		(end 341.44839 -385.869688)
		(width 0.14224)
		(layer "In11.Cu")
		(net "P5E_CPU0_P1_RX_DN<5>")
	)
	(segment
		(start 342.781636 -390.373362)
		(end 341.616284 -385.967224)
		(width 0.14224)
		(layer "In11.Cu")
		(net "P5E_CPU0_P1_RX_DN<5>")
	)
	(segment
		(start 349.82912 -283.341572)
		(end 349.898716 -283.300932)
		(width 0.1143)
		(layer "In11.Cu")
		(net "P5E_CPU0_P1_RX_DN<5>")
	)
	(segment
		(start 349.898716 -284.311344)
		(end 349.82912 -284.270704)
		(width 0.1143)
		(layer "In11.Cu")
		(net "P5E_CPU0_P1_RX_DN<5>")
	)
	(segment
		(start 349.898716 -276.211284)
		(end 349.82912 -276.170644)
		(width 0.1143)
		(layer "In11.Cu")
		(net "P5E_CPU0_P1_RX_DN<5>")
	)
	(segment
		(start 349.398844 -280.244042)
		(end 349.398082 -280.243534)
		(width 0.1143)
		(layer "In11.Cu")
		(net "P5E_CPU0_P1_RX_DN<5>")
	)
	(segment
		(start 342.78189 -390.373362)
		(end 342.781636 -390.373362)
		(width 0.14224)
		(layer "In11.Cu")
		(net "P5E_CPU0_P1_RX_DN<5>")
	)
	(segment
		(start 349.898716 -281.07132)
		(end 349.82912 -281.03068)
		(width 0.1143)
		(layer "In11.Cu")
		(net "P5E_CPU0_P1_RX_DN<5>")
	)
	(segment
		(start 349.82912 -281.72156)
		(end 349.898716 -281.68092)
		(width 0.1143)
		(layer "In11.Cu")
		(net "P5E_CPU0_P1_RX_DN<5>")
	)
	(segment
		(start 349.35922 -280.220928)
		(end 349.33128 -280.200862)
		(width 0.1143)
		(layer "In11.Cu")
		(net "P5E_CPU0_P1_RX_DN<5>")
	)
	(segment
		(start 354.972874 -366.277652)
		(end 359.66527 -361.585256)
		(width 0.14224)
		(layer "In11.Cu")
		(net "P5E_CPU0_P1_RX_DN<5>")
	)
	(segment
		(start 340.342474 -381.09779)
		(end 340.342474 -379.786388)
		(width 0.14224)
		(layer "In11.Cu")
		(net "P5E_CPU0_P1_RX_DN<5>")
	)
	(segment
		(start 349.400114 -279.267412)
		(end 349.429832 -279.250394)
		(width 0.1143)
		(layer "In11.Cu")
		(net "P5E_CPU0_P1_RX_DN<5>")
	)
	(segment
		(start 349.116142 -296.389552)
		(end 349.116142 -295.739058)
		(width 0.1143)
		(layer "In11.Cu")
		(net "P5E_CPU0_P1_RX_DN<5>")
	)
	(segment
		(start 349.82912 -286.581342)
		(end 349.831152 -286.579818)
		(width 0.1143)
		(layer "In11.Cu")
		(net "P5E_CPU0_P1_RX_DN<5>")
	)
	(segment
		(start 349.898716 -287.551368)
		(end 349.83166 -287.512252)
		(width 0.1143)
		(layer "In11.Cu")
		(net "P5E_CPU0_P1_RX_DN<5>")
	)
	(segment
		(start 367.337848 -328.351896)
		(end 365.750094 -325.31431)
		(width 0.14224)
		(layer "In11.Cu")
		(net "P5E_CPU0_P1_RX_DN<5>")
	)
	(segment
		(start 341.339424 -385.456938)
		(end 341.43696 -385.289298)
		(width 0.14224)
		(layer "In11.Cu")
		(net "P5E_CPU0_P1_RX_DN<5>")
	)
	(segment
		(start 342.477344 -393.22883)
		(end 342.48217 -392.616944)
		(width 0.14224)
		(layer "In11.Cu")
		(net "P5E_CPU0_P1_RX_DN<5>")
	)
	(segment
		(start 349.070422 -296.46372)
		(end 349.070422 -296.435272)
		(width 0.1143)
		(layer "In11.Cu")
		(net "P5E_CPU0_P1_RX_DN<5>")
	)
	(segment
		(start 349.371666 -295.483534)
		(end 349.40113 -295.466516)
		(width 0.1143)
		(layer "In11.Cu")
		(net "P5E_CPU0_P1_RX_DN<5>")
	)
	(segment
		(start 349.898716 -294.031162)
		(end 349.82912 -293.990522)
		(width 0.1143)
		(layer "In11.Cu")
		(net "P5E_CPU0_P1_RX_DN<5>")
	)
	(segment
		(start 349.070422 -298.842176)
		(end 349.070422 -296.46372)
		(width 0.14224)
		(layer "In11.Cu")
		(net "P5E_CPU0_P1_RX_DN<5>")
	)
	(segment
		(start 349.82912 -294.681402)
		(end 349.898716 -294.640762)
		(width 0.1143)
		(layer "In11.Cu")
		(net "P5E_CPU0_P1_RX_DN<5>")
	)
	(segment
		(start 341.44839 -385.869688)
		(end 341.339424 -385.456938)
		(width 0.14224)
		(layer "In11.Cu")
		(net "P5E_CPU0_P1_RX_DN<5>")
	)
	(segment
		(start 349.82912 -276.861524)
		(end 349.898716 -276.820884)
		(width 0.1143)
		(layer "In11.Cu")
		(net "P5E_CPU0_P1_RX_DN<5>")
	)
	(segment
		(start 349.82912 -284.961584)
		(end 349.898716 -284.920944)
		(width 0.1143)
		(layer "In11.Cu")
		(net "P5E_CPU0_P1_RX_DN<5>")
	)
	(segment
		(start 349.429832 -280.261822)
		(end 349.404178 -280.24709)
		(width 0.1143)
		(layer "In11.Cu")
		(net "P5E_CPU0_P1_RX_DN<5>")
	)
	(segment
		(start 352.779076 -307.795422)
		(end 349.070422 -298.842176)
		(width 0.14224)
		(layer "In11.Cu")
		(net "P5E_CPU0_P1_RX_DN<5>")
	)
	(segment
		(start 349.404178 -280.24709)
		(end 349.402654 -280.246074)
		(width 0.1143)
		(layer "In11.Cu")
		(net "P5E_CPU0_P1_RX_DN<5>")
	)
	(segment
		(start 349.070422 -296.435272)
		(end 349.116142 -296.389552)
		(width 0.1143)
		(layer "In11.Cu")
		(net "P5E_CPU0_P1_RX_DN<5>")
	)
	(arc
		(start 349.82912 -293.990522)
		(mid 349.585793 -293.525956)
		(end 349.82912 -293.06139)
		(width 0.1143)
		(layer "In11.Cu")
		(net "P5E_CPU0_P1_RX_DN<5>")
	)
	(arc
		(start 349.397066 -275.384768)
		(mid 349.213188 -275.213226)
		(end 349.121984 -274.978876)
		(width 0.1143)
		(layer "In11.Cu")
		(net "P5E_CPU0_P1_RX_DN<5>")
	)
	(arc
		(start 349.585788 -275.706078)
		(mid 349.536361 -275.52185)
		(end 349.401384 -275.387054)
		(width 0.1143)
		(layer "In11.Cu")
		(net "P5E_CPU0_P1_RX_DN<5>")
	)
	(arc
		(start 349.898716 -291.400738)
		(mid 350.055693 -291.095938)
		(end 349.898716 -290.791138)
		(width 0.1143)
		(layer "In11.Cu")
		(net "P5E_CPU0_P1_RX_DN<5>")
	)
	(arc
		(start 349.898716 -276.820884)
		(mid 350.055693 -276.516084)
		(end 349.898716 -276.211284)
		(width 0.1143)
		(layer "In11.Cu")
		(net "P5E_CPU0_P1_RX_DN<5>")
	)
	(arc
		(start 339.834474 -375.623074)
		(mid 341.452513 -374.295138)
		(end 343.298526 -373.308372)
		(width 0.14224)
		(layer "In11.Cu")
		(net "P5E_CPU0_P1_RX_DN<5>")
	)
	(arc
		(start 349.82912 -292.37051)
		(mid 349.585793 -291.905944)
		(end 349.82912 -291.441378)
		(width 0.1143)
		(layer "In11.Cu")
		(net "P5E_CPU0_P1_RX_DN<5>")
	)
	(arc
		(start 349.898716 -294.640762)
		(mid 350.055693 -294.335962)
		(end 349.898716 -294.031162)
		(width 0.1143)
		(layer "In11.Cu")
		(net "P5E_CPU0_P1_RX_DN<5>")
	)
	(arc
		(start 338.889848 -378.44984)
		(mid 338.803751 -378.348502)
		(end 338.725764 -378.240798)
		(width 0.14224)
		(layer "In11.Cu")
		(net "P5E_CPU0_P1_RX_DN<5>")
	)
	(arc
		(start 349.82912 -281.03068)
		(mid 349.650307 -280.82833)
		(end 349.585788 -280.566114)
		(width 0.1143)
		(layer "In11.Cu")
		(net "P5E_CPU0_P1_RX_DN<5>")
	)
	(arc
		(start 340.274656 -379.339602)
		(mid 340.256327 -379.188862)
		(end 340.207092 -379.045216)
		(width 0.14224)
		(layer "In11.Cu")
		(net "P5E_CPU0_P1_RX_DN<5>")
	)
	(arc
		(start 349.898716 -281.68092)
		(mid 350.055693 -281.37612)
		(end 349.898716 -281.07132)
		(width 0.1143)
		(layer "In11.Cu")
		(net "P5E_CPU0_P1_RX_DN<5>")
	)
	(arc
		(start 349.82912 -290.750498)
		(mid 349.585793 -290.285932)
		(end 349.82912 -289.821366)
		(width 0.1143)
		(layer "In11.Cu")
		(net "P5E_CPU0_P1_RX_DN<5>")
	)
	(arc
		(start 349.585788 -280.566114)
		(mid 349.544533 -280.395143)
		(end 349.429832 -280.261822)
		(width 0.1143)
		(layer "In11.Cu")
		(net "P5E_CPU0_P1_RX_DN<5>")
	)
	(arc
		(start 349.83166 -287.512252)
		(mid 349.651008 -287.309507)
		(end 349.585788 -287.045908)
		(width 0.1143)
		(layer "In11.Cu")
		(net "P5E_CPU0_P1_RX_DN<5>")
	)
	(arc
		(start 349.82912 -285.890716)
		(mid 349.585793 -285.42615)
		(end 349.82912 -284.961584)
		(width 0.1143)
		(layer "In11.Cu")
		(net "P5E_CPU0_P1_RX_DN<5>")
	)
	(arc
		(start 349.82912 -284.270704)
		(mid 349.585793 -283.806138)
		(end 349.82912 -283.341572)
		(width 0.1143)
		(layer "In11.Cu")
		(net "P5E_CPU0_P1_RX_DN<5>")
	)
	(arc
		(start 339.781642 -378.819664)
		(mid 339.729082 -378.803001)
		(end 339.674454 -378.795534)
		(width 0.14224)
		(layer "In11.Cu")
		(net "P5E_CPU0_P1_RX_DN<5>")
	)
	(arc
		(start 340.308438 -379.556518)
		(mid 340.284028 -379.449231)
		(end 340.274656 -379.339602)
		(width 0.14224)
		(layer "In11.Cu")
		(net "P5E_CPU0_P1_RX_DN<5>")
	)
	(arc
		(start 349.585788 -278.946102)
		(mid 349.650303 -278.683883)
		(end 349.82912 -278.481536)
		(width 0.1143)
		(layer "In11.Cu")
		(net "P5E_CPU0_P1_RX_DN<5>")
	)
	(arc
		(start 339.674454 -378.795534)
		(mid 339.584583 -378.787324)
		(end 339.495892 -378.770642)
		(width 0.14224)
		(layer "In11.Cu")
		(net "P5E_CPU0_P1_RX_DN<5>")
	)
	(arc
		(start 349.898716 -284.920944)
		(mid 350.055693 -284.616144)
		(end 349.898716 -284.311344)
		(width 0.1143)
		(layer "In11.Cu")
		(net "P5E_CPU0_P1_RX_DN<5>")
	)
	(arc
		(start 349.898716 -283.300932)
		(mid 350.055693 -282.996132)
		(end 349.898716 -282.691332)
		(width 0.1143)
		(layer "In11.Cu")
		(net "P5E_CPU0_P1_RX_DN<5>")
	)
	(arc
		(start 339.042502 -378.578364)
		(mid 338.961971 -378.519095)
		(end 338.889848 -378.44984)
		(width 0.14224)
		(layer "In11.Cu")
		(net "P5E_CPU0_P1_RX_DN<5>")
	)
	(arc
		(start 340.342474 -379.786388)
		(mid 340.333901 -379.670203)
		(end 340.308438 -379.556518)
		(width 0.14224)
		(layer "In11.Cu")
		(net "P5E_CPU0_P1_RX_DN<5>")
	)
	(arc
		(start 349.429832 -279.250394)
		(mid 349.544508 -279.11706)
		(end 349.585788 -278.946102)
		(width 0.1143)
		(layer "In11.Cu")
		(net "P5E_CPU0_P1_RX_DN<5>")
	)
	(arc
		(start 359.66527 -361.585256)
		(mid 365.161259 -354.888252)
		(end 369.245134 -347.247718)
		(width 0.14224)
		(layer "In11.Cu")
		(net "P5E_CPU0_P1_RX_DN<5>")
	)
	(arc
		(start 349.898716 -278.440896)
		(mid 350.055693 -278.136096)
		(end 349.898716 -277.831296)
		(width 0.1143)
		(layer "In11.Cu")
		(net "P5E_CPU0_P1_RX_DN<5>")
	)
	(arc
		(start 346.329254 -372.053104)
		(mid 350.935472 -369.59103)
		(end 354.972874 -366.277652)
		(width 0.14224)
		(layer "In11.Cu")
		(net "P5E_CPU0_P1_RX_DN<5>")
	)
	(arc
		(start 349.40113 -295.466516)
		(mid 349.526856 -295.34154)
		(end 349.572834 -295.170352)
		(width 0.1143)
		(layer "In11.Cu")
		(net "P5E_CPU0_P1_RX_DN<5>")
	)
	(arc
		(start 349.900748 -288.159698)
		(mid 350.014677 -288.026551)
		(end 350.055688 -287.856168)
		(width 0.1143)
		(layer "In11.Cu")
		(net "P5E_CPU0_P1_RX_DN<5>")
	)
	(arc
		(start 349.82912 -289.130486)
		(mid 349.585793 -288.66592)
		(end 349.82912 -288.201354)
		(width 0.1143)
		(layer "In11.Cu")
		(net "P5E_CPU0_P1_RX_DN<5>")
	)
	(arc
		(start 342.786208 -390.405874)
		(mid 342.785114 -390.389476)
		(end 342.78189 -390.373362)
		(width 0.14224)
		(layer "In11.Cu")
		(net "P5E_CPU0_P1_RX_DN<5>")
	)
	(arc
		(start 349.585788 -287.045908)
		(mid 349.650303 -286.783689)
		(end 349.82912 -286.581342)
		(width 0.1143)
		(layer "In11.Cu")
		(net "P5E_CPU0_P1_RX_DN<5>")
	)
	(arc
		(start 338.642452 -377.15825)
		(mid 338.705487 -376.841261)
		(end 338.885022 -376.572526)
		(width 0.14224)
		(layer "In11.Cu")
		(net "P5E_CPU0_P1_RX_DN<5>")
	)
	(arc
		(start 349.900748 -286.539686)
		(mid 350.014677 -286.406539)
		(end 350.055688 -286.236156)
		(width 0.1143)
		(layer "In11.Cu")
		(net "P5E_CPU0_P1_RX_DN<5>")
	)
	(arc
		(start 349.898716 -289.780726)
		(mid 350.055693 -289.475926)
		(end 349.898716 -289.171126)
		(width 0.1143)
		(layer "In11.Cu")
		(net "P5E_CPU0_P1_RX_DN<5>")
	)
	(arc
		(start 349.33128 -280.200862)
		(mid 349.10328 -279.756108)
		(end 349.33128 -279.311354)
		(width 0.1143)
		(layer "In11.Cu")
		(net "P5E_CPU0_P1_RX_DN<5>")
	)
	(arc
		(start 338.710778 -378.218192)
		(mid 338.659751 -378.109591)
		(end 338.642452 -377.990862)
		(width 0.14224)
		(layer "In11.Cu")
		(net "P5E_CPU0_P1_RX_DN<5>")
	)
	(arc
		(start 340.35619 -381.202692)
		(mid 340.34594 -381.150685)
		(end 340.342474 -381.09779)
		(width 0.14224)
		(layer "In11.Cu")
		(net "P5E_CPU0_P1_RX_DN<5>")
	)
	(arc
		(start 349.82912 -282.650692)
		(mid 349.585793 -282.186126)
		(end 349.82912 -281.72156)
		(width 0.1143)
		(layer "In11.Cu")
		(net "P5E_CPU0_P1_RX_DN<5>")
	)
	(arc
		(start 349.572834 -295.170352)
		(mid 349.640838 -294.89435)
		(end 349.82912 -294.681402)
		(width 0.1143)
		(layer "In11.Cu")
		(net "P5E_CPU0_P1_RX_DN<5>")
	)
	(arc
		(start 339.495892 -378.770642)
		(mid 339.261241 -378.693266)
		(end 339.042502 -378.578364)
		(width 0.14224)
		(layer "In11.Cu")
		(net "P5E_CPU0_P1_RX_DN<5>")
	)
	(arc
		(start 349.82912 -276.170644)
		(mid 349.650307 -275.968294)
		(end 349.585788 -275.706078)
		(width 0.1143)
		(layer "In11.Cu")
		(net "P5E_CPU0_P1_RX_DN<5>")
	)
	(arc
		(start 340.207092 -379.045216)
		(mid 340.169606 -378.992813)
		(end 340.115652 -378.957586)
		(width 0.14224)
		(layer "In11.Cu")
		(net "P5E_CPU0_P1_RX_DN<5>")
	)
	(arc
		(start 349.82912 -277.790656)
		(mid 349.585793 -277.32609)
		(end 349.82912 -276.861524)
		(width 0.1143)
		(layer "In11.Cu")
		(net "P5E_CPU0_P1_RX_DN<5>")
	)
	(arc
		(start 350.055688 -286.236156)
		(mid 350.014139 -286.064734)
		(end 349.898716 -285.931356)
		(width 0.1143)
		(layer "In11.Cu")
		(net "P5E_CPU0_P1_RX_DN<5>")
	)
	(arc
		(start 350.055688 -287.856168)
		(mid 350.014139 -287.684746)
		(end 349.898716 -287.551368)
		(width 0.1143)
		(layer "In11.Cu")
		(net "P5E_CPU0_P1_RX_DN<5>")
	)
	(arc
		(start 349.898716 -293.02075)
		(mid 350.055693 -292.71595)
		(end 349.898716 -292.41115)
		(width 0.1143)
		(layer "In11.Cu")
		(net "P5E_CPU0_P1_RX_DN<5>")
	)
	(segment
		(start 340.597998 -393.69238)
		(end 341.118698 -393.69238)
		(width 0.127)
		(layer "F.Cu")
		(net "P5E_CPU0_P1_RX_DN<4>")
	)
	(segment
		(start 349.20809 -277.870158)
		(end 348.741238 -278.136096)
		(width 0.12954)
		(layer "F.Cu")
		(net "P5E_CPU0_P1_RX_DN<4>")
	)
	(segment
		(start 348.928944 -291.41801)
		(end 348.959932 -291.40023)
		(width 0.1143)
		(layer "In11.Cu")
		(net "P5E_CPU0_P1_RX_DN<4>")
	)
	(segment
		(start 348.125288 -298.99737)
		(end 348.125288 -296.46372)
		(width 0.14224)
		(layer "In11.Cu")
		(net "P5E_CPU0_P1_RX_DN<4>")
	)
	(segment
		(start 348.923356 -287.530794)
		(end 348.922594 -287.530286)
		(width 0.1143)
		(layer "In11.Cu")
		(net "P5E_CPU0_P1_RX_DN<4>")
	)
	(segment
		(start 348.889066 -288.201354)
		(end 348.96171 -288.158936)
		(width 0.1143)
		(layer "In11.Cu")
		(net "P5E_CPU0_P1_RX_DN<4>")
	)
	(segment
		(start 348.89186 -283.33954)
		(end 348.928182 -283.318712)
		(width 0.1143)
		(layer "In11.Cu")
		(net "P5E_CPU0_P1_RX_DN<4>")
	)
	(segment
		(start 337.133184 -376.075956)
		(end 338.261452 -374.947688)
		(width 0.14224)
		(layer "In11.Cu")
		(net "P5E_CPU0_P1_RX_DN<4>")
	)
	(segment
		(start 348.928944 -289.153854)
		(end 348.928182 -289.153346)
		(width 0.1143)
		(layer "In11.Cu")
		(net "P5E_CPU0_P1_RX_DN<4>")
	)
	(segment
		(start 340.925404 -387.684772)
		(end 340.92515 -387.684772)
		(width 0.14224)
		(layer "In11.Cu")
		(net "P5E_CPU0_P1_RX_DN<4>")
	)
	(segment
		(start 348.928944 -294.01389)
		(end 348.928182 -294.013382)
		(width 0.1143)
		(layer "In11.Cu")
		(net "P5E_CPU0_P1_RX_DN<4>")
	)
	(segment
		(start 341.456772 -389.435086)
		(end 341.285322 -389.343646)
		(width 0.14224)
		(layer "In11.Cu")
		(net "P5E_CPU0_P1_RX_DN<4>")
	)
	(segment
		(start 348.92996 -287.534604)
		(end 348.927166 -287.53308)
		(width 0.1143)
		(layer "In11.Cu")
		(net "P5E_CPU0_P1_RX_DN<4>")
	)
	(segment
		(start 364.96879 -325.83247)
		(end 358.193848 -317.57747)
		(width 0.14224)
		(layer "In11.Cu")
		(net "P5E_CPU0_P1_RX_DN<4>")
	)
	(segment
		(start 348.959932 -281.071828)
		(end 348.928182 -281.05354)
		(width 0.1143)
		(layer "In11.Cu")
		(net "P5E_CPU0_P1_RX_DN<4>")
	)
	(segment
		(start 348.171008 -296.389552)
		(end 348.171008 -295.796462)
		(width 0.1143)
		(layer "In11.Cu")
		(net "P5E_CPU0_P1_RX_DN<4>")
	)
	(segment
		(start 348.889066 -289.821366)
		(end 348.925642 -289.80003)
		(width 0.1143)
		(layer "In11.Cu")
		(net "P5E_CPU0_P1_RX_DN<4>")
	)
	(segment
		(start 348.928182 -284.938724)
		(end 348.959932 -284.920436)
		(width 0.1143)
		(layer "In11.Cu")
		(net "P5E_CPU0_P1_RX_DN<4>")
	)
	(segment
		(start 348.889066 -286.581342)
		(end 348.895162 -286.577786)
		(width 0.1143)
		(layer "In11.Cu")
		(net "P5E_CPU0_P1_RX_DN<4>")
	)
	(segment
		(start 340.801198 -387.276848)
		(end 340.801706 -387.276594)
		(width 0.14224)
		(layer "In11.Cu")
		(net "P5E_CPU0_P1_RX_DN<4>")
	)
	(segment
		(start 348.928944 -293.038022)
		(end 348.959932 -293.020242)
		(width 0.1143)
		(layer "In11.Cu")
		(net "P5E_CPU0_P1_RX_DN<4>")
	)
	(segment
		(start 348.895924 -293.994586)
		(end 348.889066 -293.990522)
		(width 0.1143)
		(layer "In11.Cu")
		(net "P5E_CPU0_P1_RX_DN<4>")
	)
	(segment
		(start 348.896686 -290.75507)
		(end 348.895924 -290.754562)
		(width 0.1143)
		(layer "In11.Cu")
		(net "P5E_CPU0_P1_RX_DN<4>")
	)
	(segment
		(start 348.924118 -285.911036)
		(end 348.92361 -285.910782)
		(width 0.1143)
		(layer "In11.Cu")
		(net "P5E_CPU0_P1_RX_DN<4>")
	)
	(segment
		(start 348.889066 -283.341572)
		(end 348.89186 -283.33954)
		(width 0.1143)
		(layer "In11.Cu")
		(net "P5E_CPU0_P1_RX_DN<4>")
	)
	(segment
		(start 348.928182 -292.39337)
		(end 348.896686 -292.375082)
		(width 0.1143)
		(layer "In11.Cu")
		(net "P5E_CPU0_P1_RX_DN<4>")
	)
	(segment
		(start 338.56041 -381.552704)
		(end 338.560156 -381.552704)
		(width 0.14224)
		(layer "In11.Cu")
		(net "P5E_CPU0_P1_RX_DN<4>")
	)
	(segment
		(start 348.419166 -279.291542)
		(end 348.488762 -279.250902)
		(width 0.1143)
		(layer "In11.Cu")
		(net "P5E_CPU0_P1_RX_DN<4>")
	)
	(segment
		(start 348.928944 -290.773866)
		(end 348.928182 -290.773358)
		(width 0.1143)
		(layer "In11.Cu")
		(net "P5E_CPU0_P1_RX_DN<4>")
	)
	(segment
		(start 348.896686 -293.995094)
		(end 348.895924 -293.994586)
		(width 0.1143)
		(layer "In11.Cu")
		(net "P5E_CPU0_P1_RX_DN<4>")
	)
	(segment
		(start 340.618572 -373.37238)
		(end 345.985846 -371.149118)
		(width 0.14224)
		(layer "In11.Cu")
		(net "P5E_CPU0_P1_RX_DN<4>")
	)
	(segment
		(start 348.896686 -289.135058)
		(end 348.895924 -289.13455)
		(width 0.1143)
		(layer "In11.Cu")
		(net "P5E_CPU0_P1_RX_DN<4>")
	)
	(segment
		(start 348.896686 -292.375082)
		(end 348.895924 -292.374574)
		(width 0.1143)
		(layer "In11.Cu")
		(net "P5E_CPU0_P1_RX_DN<4>")
	)
	(segment
		(start 338.518754 -381.525018)
		(end 337.624928 -381.154686)
		(width 0.14224)
		(layer "In11.Cu")
		(net "P5E_CPU0_P1_RX_DN<4>")
	)
	(segment
		(start 348.928182 -290.773358)
		(end 348.896686 -290.75507)
		(width 0.1143)
		(layer "In11.Cu")
		(net "P5E_CPU0_P1_RX_DN<4>")
	)
	(segment
		(start 348.951042 -294.645588)
		(end 348.962218 -294.63873)
		(width 0.1143)
		(layer "In11.Cu")
		(net "P5E_CPU0_P1_RX_DN<4>")
	)
	(segment
		(start 348.125288 -296.46372)
		(end 348.125288 -296.435272)
		(width 0.1143)
		(layer "In11.Cu")
		(net "P5E_CPU0_P1_RX_DN<4>")
	)
	(segment
		(start 348.927166 -291.419026)
		(end 348.928182 -291.418518)
		(width 0.1143)
		(layer "In11.Cu")
		(net "P5E_CPU0_P1_RX_DN<4>")
	)
	(segment
		(start 348.929452 -285.914084)
		(end 348.92488 -285.911544)
		(width 0.1143)
		(layer "In11.Cu")
		(net "P5E_CPU0_P1_RX_DN<4>")
	)
	(segment
		(start 348.645988 -295.321482)
		(end 348.645988 -295.145968)
		(width 0.1143)
		(layer "In11.Cu")
		(net "P5E_CPU0_P1_RX_DN<4>")
	)
	(segment
		(start 348.922594 -287.530286)
		(end 348.896686 -287.5153)
		(width 0.1143)
		(layer "In11.Cu")
		(net "P5E_CPU0_P1_RX_DN<4>")
	)
	(segment
		(start 348.925642 -289.80003)
		(end 348.927166 -289.799014)
		(width 0.1143)
		(layer "In11.Cu")
		(net "P5E_CPU0_P1_RX_DN<4>")
	)
	(segment
		(start 341.586058 -390.035542)
		(end 341.585804 -390.035796)
		(width 0.14224)
		(layer "In11.Cu")
		(net "P5E_CPU0_P1_RX_DN<4>")
	)
	(segment
		(start 349.10903 -278.205946)
		(end 349.03918 -278.136096)
		(width 0.1143)
		(layer "In11.Cu")
		(net "P5E_CPU0_P1_RX_DN<4>")
	)
	(segment
		(start 348.923356 -286.561784)
		(end 348.924118 -286.561276)
		(width 0.1143)
		(layer "In11.Cu")
		(net "P5E_CPU0_P1_RX_DN<4>")
	)
	(segment
		(start 349.03918 -278.136096)
		(end 348.741238 -278.136096)
		(width 0.1143)
		(layer "In11.Cu")
		(net "P5E_CPU0_P1_RX_DN<4>")
	)
	(segment
		(start 341.472012 -393.787376)
		(end 341.47252 -393.786868)
		(width 0.14224)
		(layer "In11.Cu")
		(net "P5E_CPU0_P1_RX_DN<4>")
	)
	(segment
		(start 341.535258 -389.693912)
		(end 341.456772 -389.435086)
		(width 0.14224)
		(layer "In11.Cu")
		(net "P5E_CPU0_P1_RX_DN<4>")
	)
	(segment
		(start 348.962218 -294.033194)
		(end 348.959932 -294.03167)
		(width 0.1143)
		(layer "In11.Cu")
		(net "P5E_CPU0_P1_RX_DN<4>")
	)
	(segment
		(start 340.957662 -388.2644)
		(end 340.833964 -387.855714)
		(width 0.14224)
		(layer "In11.Cu")
		(net "P5E_CPU0_P1_RX_DN<4>")
	)
	(segment
		(start 341.47252 -393.786868)
		(end 341.594186 -393.716764)
		(width 0.14224)
		(layer "In11.Cu")
		(net "P5E_CPU0_P1_RX_DN<4>")
	)
	(segment
		(start 348.928944 -289.797998)
		(end 348.959932 -289.780218)
		(width 0.1143)
		(layer "In11.Cu")
		(net "P5E_CPU0_P1_RX_DN<4>")
	)
	(segment
		(start 348.895162 -286.577786)
		(end 348.895924 -286.577786)
		(width 0.1143)
		(layer "In11.Cu")
		(net "P5E_CPU0_P1_RX_DN<4>")
	)
	(segment
		(start 348.959932 -282.69184)
		(end 348.928182 -282.673552)
		(width 0.1143)
		(layer "In11.Cu")
		(net "P5E_CPU0_P1_RX_DN<4>")
	)
	(segment
		(start 348.927166 -289.799014)
		(end 348.928182 -289.798506)
		(width 0.1143)
		(layer "In11.Cu")
		(net "P5E_CPU0_P1_RX_DN<4>")
	)
	(segment
		(start 366.426242 -328.620882)
		(end 364.96879 -325.83247)
		(width 0.14224)
		(layer "In11.Cu")
		(net "P5E_CPU0_P1_RX_DN<4>")
	)
	(segment
		(start 348.92361 -285.910782)
		(end 348.922848 -285.910274)
		(width 0.1143)
		(layer "In11.Cu")
		(net "P5E_CPU0_P1_RX_DN<4>")
	)
	(segment
		(start 348.928182 -281.05354)
		(end 348.889066 -281.03068)
		(width 0.1143)
		(layer "In11.Cu")
		(net "P5E_CPU0_P1_RX_DN<4>")
	)
	(segment
		(start 340.92515 -387.684772)
		(end 340.801198 -387.276848)
		(width 0.14224)
		(layer "In11.Cu")
		(net "P5E_CPU0_P1_RX_DN<4>")
	)
	(segment
		(start 348.889066 -284.961584)
		(end 348.928182 -284.938724)
		(width 0.1143)
		(layer "In11.Cu")
		(net "P5E_CPU0_P1_RX_DN<4>")
	)
	(segment
		(start 348.125288 -296.435272)
		(end 348.171008 -296.389552)
		(width 0.1143)
		(layer "In11.Cu")
		(net "P5E_CPU0_P1_RX_DN<4>")
	)
	(segment
		(start 348.928182 -291.418518)
		(end 348.928944 -291.41801)
		(width 0.1143)
		(layer "In11.Cu")
		(net "P5E_CPU0_P1_RX_DN<4>")
	)
	(segment
		(start 339.262466 -382.25476)
		(end 338.56041 -381.552704)
		(width 0.14224)
		(layer "In11.Cu")
		(net "P5E_CPU0_P1_RX_DN<4>")
	)
	(segment
		(start 348.889066 -281.72156)
		(end 348.928182 -281.6987)
		(width 0.1143)
		(layer "In11.Cu")
		(net "P5E_CPU0_P1_RX_DN<4>")
	)
	(segment
		(start 348.928182 -289.153346)
		(end 348.896686 -289.135058)
		(width 0.1143)
		(layer "In11.Cu")
		(net "P5E_CPU0_P1_RX_DN<4>")
	)
	(segment
		(start 348.959932 -289.171634)
		(end 348.928944 -289.153854)
		(width 0.1143)
		(layer "In11.Cu")
		(net "P5E_CPU0_P1_RX_DN<4>")
	)
	(segment
		(start 348.959932 -294.03167)
		(end 348.928944 -294.01389)
		(width 0.1143)
		(layer "In11.Cu")
		(net "P5E_CPU0_P1_RX_DN<4>")
	)
	(segment
		(start 341.586058 -392.31316)
		(end 341.586058 -390.035542)
		(width 0.14224)
		(layer "In11.Cu")
		(net "P5E_CPU0_P1_RX_DN<4>")
	)
	(segment
		(start 340.506558 -386.776468)
		(end 340.597744 -386.605526)
		(width 0.14224)
		(layer "In11.Cu")
		(net "P5E_CPU0_P1_RX_DN<4>")
	)
	(segment
		(start 358.193848 -317.57747)
		(end 351.952052 -308.236366)
		(width 0.14224)
		(layer "In11.Cu")
		(net "P5E_CPU0_P1_RX_DN<4>")
	)
	(segment
		(start 348.928944 -292.393878)
		(end 348.928182 -292.39337)
		(width 0.1143)
		(layer "In11.Cu")
		(net "P5E_CPU0_P1_RX_DN<4>")
	)
	(segment
		(start 348.927166 -293.039038)
		(end 348.928182 -293.03853)
		(width 0.1143)
		(layer "In11.Cu")
		(net "P5E_CPU0_P1_RX_DN<4>")
	)
	(segment
		(start 348.889066 -291.441378)
		(end 348.925642 -291.420042)
		(width 0.1143)
		(layer "In11.Cu")
		(net "P5E_CPU0_P1_RX_DN<4>")
	)
	(segment
		(start 348.927166 -287.53308)
		(end 348.923356 -287.530794)
		(width 0.1143)
		(layer "In11.Cu")
		(net "P5E_CPU0_P1_RX_DN<4>")
	)
	(segment
		(start 341.285322 -389.343646)
		(end 341.16137 -388.93496)
		(width 0.14224)
		(layer "In11.Cu")
		(net "P5E_CPU0_P1_RX_DN<4>")
	)
	(segment
		(start 340.597744 -386.605526)
		(end 339.294216 -382.3081)
		(width 0.14224)
		(layer "In11.Cu")
		(net "P5E_CPU0_P1_RX_DN<4>")
	)
	(segment
		(start 348.92488 -285.911544)
		(end 348.924118 -285.911036)
		(width 0.1143)
		(layer "In11.Cu")
		(net "P5E_CPU0_P1_RX_DN<4>")
	)
	(segment
		(start 340.801706 -387.276594)
		(end 340.630256 -387.185154)
		(width 0.14224)
		(layer "In11.Cu")
		(net "P5E_CPU0_P1_RX_DN<4>")
	)
	(segment
		(start 348.895924 -286.577786)
		(end 348.923356 -286.561784)
		(width 0.1143)
		(layer "In11.Cu")
		(net "P5E_CPU0_P1_RX_DN<4>")
	)
	(segment
		(start 348.928182 -293.03853)
		(end 348.928944 -293.038022)
		(width 0.1143)
		(layer "In11.Cu")
		(net "P5E_CPU0_P1_RX_DN<4>")
	)
	(segment
		(start 340.630256 -387.185154)
		(end 340.506558 -386.776468)
		(width 0.14224)
		(layer "In11.Cu")
		(net "P5E_CPU0_P1_RX_DN<4>")
	)
	(segment
		(start 341.16137 -388.93496)
		(end 341.25281 -388.764018)
		(width 0.14224)
		(layer "In11.Cu")
		(net "P5E_CPU0_P1_RX_DN<4>")
	)
	(segment
		(start 348.928182 -284.293564)
		(end 348.889066 -284.270704)
		(width 0.1143)
		(layer "In11.Cu")
		(net "P5E_CPU0_P1_RX_DN<4>")
	)
	(segment
		(start 368.468148 -346.310458)
		(end 368.468148 -339.981032)
		(width 0.14224)
		(layer "In11.Cu")
		(net "P5E_CPU0_P1_RX_DN<4>")
	)
	(segment
		(start 341.28202 -392.616944)
		(end 341.586058 -392.31316)
		(width 0.14224)
		(layer "In11.Cu")
		(net "P5E_CPU0_P1_RX_DN<4>")
	)
	(segment
		(start 348.922848 -285.910274)
		(end 348.889828 -285.891224)
		(width 0.1143)
		(layer "In11.Cu")
		(net "P5E_CPU0_P1_RX_DN<4>")
	)
	(segment
		(start 348.959932 -290.791646)
		(end 348.928944 -290.773866)
		(width 0.1143)
		(layer "In11.Cu")
		(net "P5E_CPU0_P1_RX_DN<4>")
	)
	(segment
		(start 348.928182 -281.6987)
		(end 348.959932 -281.680412)
		(width 0.1143)
		(layer "In11.Cu")
		(net "P5E_CPU0_P1_RX_DN<4>")
	)
	(segment
		(start 336.936334 -380.340616)
		(end 336.936334 -376.55119)
		(width 0.14224)
		(layer "In11.Cu")
		(net "P5E_CPU0_P1_RX_DN<4>")
	)
	(segment
		(start 368.468148 -339.981032)
		(end 366.426242 -328.620882)
		(width 0.14224)
		(layer "In11.Cu")
		(net "P5E_CPU0_P1_RX_DN<4>")
	)
	(segment
		(start 348.922848 -278.463248)
		(end 348.928944 -278.459692)
		(width 0.1143)
		(layer "In11.Cu")
		(net "P5E_CPU0_P1_RX_DN<4>")
	)
	(segment
		(start 348.928182 -294.013382)
		(end 348.896686 -293.995094)
		(width 0.1143)
		(layer "In11.Cu")
		(net "P5E_CPU0_P1_RX_DN<4>")
	)
	(segment
		(start 348.925642 -293.040054)
		(end 348.927166 -293.039038)
		(width 0.1143)
		(layer "In11.Cu")
		(net "P5E_CPU0_P1_RX_DN<4>")
	)
	(segment
		(start 348.895924 -287.514792)
		(end 348.891606 -287.512252)
		(width 0.1143)
		(layer "In11.Cu")
		(net "P5E_CPU0_P1_RX_DN<4>")
	)
	(segment
		(start 341.594186 -393.545822)
		(end 341.277194 -393.22883)
		(width 0.14224)
		(layer "In11.Cu")
		(net "P5E_CPU0_P1_RX_DN<4>")
	)
	(segment
		(start 348.889066 -293.06139)
		(end 348.925642 -293.040054)
		(width 0.1143)
		(layer "In11.Cu")
		(net "P5E_CPU0_P1_RX_DN<4>")
	)
	(segment
		(start 348.895924 -289.13455)
		(end 348.889066 -289.130486)
		(width 0.1143)
		(layer "In11.Cu")
		(net "P5E_CPU0_P1_RX_DN<4>")
	)
	(segment
		(start 348.889828 -294.680894)
		(end 348.951042 -294.645588)
		(width 0.1143)
		(layer "In11.Cu")
		(net "P5E_CPU0_P1_RX_DN<4>")
	)
	(segment
		(start 348.171008 -295.796462)
		(end 348.645988 -295.321482)
		(width 0.1143)
		(layer "In11.Cu")
		(net "P5E_CPU0_P1_RX_DN<4>")
	)
	(segment
		(start 348.895924 -292.374574)
		(end 348.889066 -292.37051)
		(width 0.1143)
		(layer "In11.Cu")
		(net "P5E_CPU0_P1_RX_DN<4>")
	)
	(segment
		(start 348.928182 -283.318712)
		(end 348.959932 -283.300424)
		(width 0.1143)
		(layer "In11.Cu")
		(net "P5E_CPU0_P1_RX_DN<4>")
	)
	(segment
		(start 341.594186 -393.716764)
		(end 341.594186 -393.545822)
		(width 0.14224)
		(layer "In11.Cu")
		(net "P5E_CPU0_P1_RX_DN<4>")
	)
	(segment
		(start 348.924118 -286.561276)
		(end 348.92615 -286.560006)
		(width 0.1143)
		(layer "In11.Cu")
		(net "P5E_CPU0_P1_RX_DN<4>")
	)
	(segment
		(start 348.896686 -287.5153)
		(end 348.895924 -287.514792)
		(width 0.1143)
		(layer "In11.Cu")
		(net "P5E_CPU0_P1_RX_DN<4>")
	)
	(segment
		(start 348.928182 -289.798506)
		(end 348.928944 -289.797998)
		(width 0.1143)
		(layer "In11.Cu")
		(net "P5E_CPU0_P1_RX_DN<4>")
	)
	(segment
		(start 348.959932 -292.411658)
		(end 348.928944 -292.393878)
		(width 0.1143)
		(layer "In11.Cu")
		(net "P5E_CPU0_P1_RX_DN<4>")
	)
	(segment
		(start 367.672874 -348.23019)
		(end 368.468148 -346.310458)
		(width 0.14224)
		(layer "In11.Cu")
		(net "P5E_CPU0_P1_RX_DN<4>")
	)
	(segment
		(start 341.252556 -388.763256)
		(end 341.129112 -388.35584)
		(width 0.14224)
		(layer "In11.Cu")
		(net "P5E_CPU0_P1_RX_DN<4>")
	)
	(segment
		(start 351.581466 -367.410238)
		(end 361.454192 -357.537512)
		(width 0.14224)
		(layer "In11.Cu")
		(net "P5E_CPU0_P1_RX_DN<4>")
	)
	(segment
		(start 341.118698 -393.69238)
		(end 341.472012 -393.787376)
		(width 0.14224)
		(layer "In11.Cu")
		(net "P5E_CPU0_P1_RX_DN<4>")
	)
	(segment
		(start 348.92615 -286.560006)
		(end 348.929198 -286.558228)
		(width 0.1143)
		(layer "In11.Cu")
		(net "P5E_CPU0_P1_RX_DN<4>")
	)
	(segment
		(start 348.959932 -284.311852)
		(end 348.928182 -284.293564)
		(width 0.1143)
		(layer "In11.Cu")
		(net "P5E_CPU0_P1_RX_DN<4>")
	)
	(segment
		(start 348.925642 -291.420042)
		(end 348.927166 -291.419026)
		(width 0.1143)
		(layer "In11.Cu")
		(net "P5E_CPU0_P1_RX_DN<4>")
	)
	(segment
		(start 341.277194 -393.22883)
		(end 341.28202 -392.616944)
		(width 0.14224)
		(layer "In11.Cu")
		(net "P5E_CPU0_P1_RX_DN<4>")
	)
	(segment
		(start 341.129112 -388.35584)
		(end 340.957662 -388.2644)
		(width 0.14224)
		(layer "In11.Cu")
		(net "P5E_CPU0_P1_RX_DN<4>")
	)
	(segment
		(start 340.833964 -387.855714)
		(end 340.925404 -387.684772)
		(width 0.14224)
		(layer "In11.Cu")
		(net "P5E_CPU0_P1_RX_DN<4>")
	)
	(segment
		(start 348.488762 -280.261314)
		(end 348.419166 -280.220674)
		(width 0.1143)
		(layer "In11.Cu")
		(net "P5E_CPU0_P1_RX_DN<4>")
	)
	(segment
		(start 351.952052 -308.236366)
		(end 348.125288 -298.99737)
		(width 0.14224)
		(layer "In11.Cu")
		(net "P5E_CPU0_P1_RX_DN<4>")
	)
	(segment
		(start 348.928182 -282.673552)
		(end 348.889066 -282.650692)
		(width 0.1143)
		(layer "In11.Cu")
		(net "P5E_CPU0_P1_RX_DN<4>")
	)
	(segment
		(start 348.895924 -290.754562)
		(end 348.889066 -290.750498)
		(width 0.1143)
		(layer "In11.Cu")
		(net "P5E_CPU0_P1_RX_DN<4>")
	)
	(segment
		(start 341.25281 -388.764018)
		(end 341.252556 -388.763256)
		(width 0.14224)
		(layer "In11.Cu")
		(net "P5E_CPU0_P1_RX_DN<4>")
	)
	(segment
		(start 337.49234 -381.066294)
		(end 337.056222 -380.629922)
		(width 0.14224)
		(layer "In11.Cu")
		(net "P5E_CPU0_P1_RX_DN<4>")
	)
	(arc
		(start 348.889066 -289.130486)
		(mid 348.645739 -288.66592)
		(end 348.889066 -288.201354)
		(width 0.1143)
		(layer "In11.Cu")
		(net "P5E_CPU0_P1_RX_DN<4>")
	)
	(arc
		(start 338.261452 -374.947688)
		(mid 339.36243 -374.043946)
		(end 340.618572 -373.37238)
		(width 0.14224)
		(layer "In11.Cu")
		(net "P5E_CPU0_P1_RX_DN<4>")
	)
	(arc
		(start 338.560156 -381.552704)
		(mid 338.540813 -381.536833)
		(end 338.518754 -381.525018)
		(width 0.14224)
		(layer "In11.Cu")
		(net "P5E_CPU0_P1_RX_DN<4>")
	)
	(arc
		(start 341.585804 -390.035796)
		(mid 341.573159 -389.862986)
		(end 341.535258 -389.693912)
		(width 0.14224)
		(layer "In11.Cu")
		(net "P5E_CPU0_P1_RX_DN<4>")
	)
	(arc
		(start 348.959932 -284.920436)
		(mid 349.109029 -284.616144)
		(end 348.959932 -284.311852)
		(width 0.1143)
		(layer "In11.Cu")
		(net "P5E_CPU0_P1_RX_DN<4>")
	)
	(arc
		(start 349.115888 -287.856168)
		(mid 349.066065 -287.670438)
		(end 348.92996 -287.534604)
		(width 0.1143)
		(layer "In11.Cu")
		(net "P5E_CPU0_P1_RX_DN<4>")
	)
	(arc
		(start 348.959932 -281.680412)
		(mid 349.111521 -281.37612)
		(end 348.959932 -281.071828)
		(width 0.1143)
		(layer "In11.Cu")
		(net "P5E_CPU0_P1_RX_DN<4>")
	)
	(arc
		(start 348.645734 -278.946102)
		(mid 348.719929 -278.667731)
		(end 348.922848 -278.463248)
		(width 0.1143)
		(layer "In11.Cu")
		(net "P5E_CPU0_P1_RX_DN<4>")
	)
	(arc
		(start 348.488762 -279.250902)
		(mid 348.604189 -279.117526)
		(end 348.645734 -278.946102)
		(width 0.1143)
		(layer "In11.Cu")
		(net "P5E_CPU0_P1_RX_DN<4>")
	)
	(arc
		(start 348.962218 -294.63873)
		(mid 349.111791 -294.335962)
		(end 348.962218 -294.033194)
		(width 0.1143)
		(layer "In11.Cu")
		(net "P5E_CPU0_P1_RX_DN<4>")
	)
	(arc
		(start 361.454192 -357.537512)
		(mid 365.021904 -353.190113)
		(end 367.672874 -348.23019)
		(width 0.14224)
		(layer "In11.Cu")
		(net "P5E_CPU0_P1_RX_DN<4>")
	)
	(arc
		(start 336.936334 -376.55119)
		(mid 336.987493 -376.293995)
		(end 337.133184 -376.075956)
		(width 0.14224)
		(layer "In11.Cu")
		(net "P5E_CPU0_P1_RX_DN<4>")
	)
	(arc
		(start 348.889066 -284.270704)
		(mid 348.645739 -283.806138)
		(end 348.889066 -283.341572)
		(width 0.1143)
		(layer "In11.Cu")
		(net "P5E_CPU0_P1_RX_DN<4>")
	)
	(arc
		(start 348.889066 -285.890716)
		(mid 348.645739 -285.42615)
		(end 348.889066 -284.961584)
		(width 0.1143)
		(layer "In11.Cu")
		(net "P5E_CPU0_P1_RX_DN<4>")
	)
	(arc
		(start 348.645734 -287.045908)
		(mid 348.710249 -286.783689)
		(end 348.889066 -286.581342)
		(width 0.1143)
		(layer "In11.Cu")
		(net "P5E_CPU0_P1_RX_DN<4>")
	)
	(arc
		(start 348.959932 -291.40023)
		(mid 349.111521 -291.095938)
		(end 348.959932 -290.791646)
		(width 0.1143)
		(layer "In11.Cu")
		(net "P5E_CPU0_P1_RX_DN<4>")
	)
	(arc
		(start 348.959932 -283.300424)
		(mid 349.1146 -282.996132)
		(end 348.959932 -282.69184)
		(width 0.1143)
		(layer "In11.Cu")
		(net "P5E_CPU0_P1_RX_DN<4>")
	)
	(arc
		(start 348.889828 -285.891224)
		(mid 348.889447 -285.89097)
		(end 348.889066 -285.890716)
		(width 0.1143)
		(layer "In11.Cu")
		(net "P5E_CPU0_P1_RX_DN<4>")
	)
	(arc
		(start 348.419166 -280.220674)
		(mid 348.175839 -279.756108)
		(end 348.419166 -279.291542)
		(width 0.1143)
		(layer "In11.Cu")
		(net "P5E_CPU0_P1_RX_DN<4>")
	)
	(arc
		(start 348.929198 -286.558228)
		(mid 349.11465 -286.236266)
		(end 348.929452 -285.914084)
		(width 0.1143)
		(layer "In11.Cu")
		(net "P5E_CPU0_P1_RX_DN<4>")
	)
	(arc
		(start 348.889066 -282.650692)
		(mid 348.645739 -282.186126)
		(end 348.889066 -281.72156)
		(width 0.1143)
		(layer "In11.Cu")
		(net "P5E_CPU0_P1_RX_DN<4>")
	)
	(arc
		(start 348.889066 -293.990522)
		(mid 348.645739 -293.525956)
		(end 348.889066 -293.06139)
		(width 0.1143)
		(layer "In11.Cu")
		(net "P5E_CPU0_P1_RX_DN<4>")
	)
	(arc
		(start 348.959932 -289.780218)
		(mid 349.109029 -289.475926)
		(end 348.959932 -289.171634)
		(width 0.1143)
		(layer "In11.Cu")
		(net "P5E_CPU0_P1_RX_DN<4>")
	)
	(arc
		(start 348.645734 -280.566114)
		(mid 348.604185 -280.394692)
		(end 348.488762 -280.261314)
		(width 0.1143)
		(layer "In11.Cu")
		(net "P5E_CPU0_P1_RX_DN<4>")
	)
	(arc
		(start 348.928944 -278.459692)
		(mid 349.046709 -278.352501)
		(end 349.10903 -278.205946)
		(width 0.1143)
		(layer "In11.Cu")
		(net "P5E_CPU0_P1_RX_DN<4>")
	)
	(arc
		(start 348.96171 -288.158936)
		(mid 349.075117 -288.026047)
		(end 349.115888 -287.856168)
		(width 0.1143)
		(layer "In11.Cu")
		(net "P5E_CPU0_P1_RX_DN<4>")
	)
	(arc
		(start 348.959932 -293.020242)
		(mid 349.111521 -292.71595)
		(end 348.959932 -292.411658)
		(width 0.1143)
		(layer "In11.Cu")
		(net "P5E_CPU0_P1_RX_DN<4>")
	)
	(arc
		(start 339.294216 -382.3081)
		(mid 339.281641 -382.279465)
		(end 339.262466 -382.25476)
		(width 0.14224)
		(layer "In11.Cu")
		(net "P5E_CPU0_P1_RX_DN<4>")
	)
	(arc
		(start 337.624928 -381.154686)
		(mid 337.5543 -381.116994)
		(end 337.49234 -381.066294)
		(width 0.14224)
		(layer "In11.Cu")
		(net "P5E_CPU0_P1_RX_DN<4>")
	)
	(arc
		(start 348.645988 -295.145968)
		(mid 348.710647 -294.883411)
		(end 348.889828 -294.680894)
		(width 0.1143)
		(layer "In11.Cu")
		(net "P5E_CPU0_P1_RX_DN<4>")
	)
	(arc
		(start 337.056222 -380.629922)
		(mid 336.967478 -380.497202)
		(end 336.936334 -380.340616)
		(width 0.14224)
		(layer "In11.Cu")
		(net "P5E_CPU0_P1_RX_DN<4>")
	)
	(arc
		(start 345.985846 -371.149118)
		(mid 348.967786 -369.555245)
		(end 351.581466 -367.410238)
		(width 0.14224)
		(layer "In11.Cu")
		(net "P5E_CPU0_P1_RX_DN<4>")
	)
	(arc
		(start 348.889066 -292.37051)
		(mid 348.645739 -291.905944)
		(end 348.889066 -291.441378)
		(width 0.1143)
		(layer "In11.Cu")
		(net "P5E_CPU0_P1_RX_DN<4>")
	)
	(arc
		(start 348.891606 -287.512252)
		(mid 348.710954 -287.309507)
		(end 348.645734 -287.045908)
		(width 0.1143)
		(layer "In11.Cu")
		(net "P5E_CPU0_P1_RX_DN<4>")
	)
	(arc
		(start 348.889066 -281.03068)
		(mid 348.710253 -280.82833)
		(end 348.645734 -280.566114)
		(width 0.1143)
		(layer "In11.Cu")
		(net "P5E_CPU0_P1_RX_DN<4>")
	)
	(arc
		(start 348.889066 -290.750498)
		(mid 348.645739 -290.285932)
		(end 348.889066 -289.821366)
		(width 0.1143)
		(layer "In11.Cu")
		(net "P5E_CPU0_P1_RX_DN<4>")
	)
	(segment
		(start 339.398102 -393.69238)
		(end 339.918802 -393.69238)
		(width 0.127)
		(layer "F.Cu")
		(net "P5E_CPU0_P1_RX_DN<3>")
	)
	(segment
		(start 349.20809 -276.250146)
		(end 348.741238 -276.516084)
		(width 0.12954)
		(layer "F.Cu")
		(net "P5E_CPU0_P1_RX_DN<3>")
	)
	(segment
		(start 347.99524 -284.297628)
		(end 347.994224 -284.29712)
		(width 0.1143)
		(layer "In11.Cu")
		(net "P5E_CPU0_P1_RX_DN<3>")
	)
	(segment
		(start 347.985588 -289.80003)
		(end 347.987112 -289.799014)
		(width 0.1143)
		(layer "In11.Cu")
		(net "P5E_CPU0_P1_RX_DN<3>")
	)
	(segment
		(start 347.98889 -289.797998)
		(end 347.99016 -289.797236)
		(width 0.1143)
		(layer "In11.Cu")
		(net "P5E_CPU0_P1_RX_DN<3>")
	)
	(segment
		(start 347.988128 -291.418518)
		(end 347.98889 -291.41801)
		(width 0.1143)
		(layer "In11.Cu")
		(net "P5E_CPU0_P1_RX_DN<3>")
	)
	(segment
		(start 357.717344 -318.54521)
		(end 351.128584 -308.68493)
		(width 0.14224)
		(layer "In11.Cu")
		(net "P5E_CPU0_P1_RX_DN<3>")
	)
	(segment
		(start 347.987112 -284.293056)
		(end 347.985588 -284.29204)
		(width 0.1143)
		(layer "In11.Cu")
		(net "P5E_CPU0_P1_RX_DN<3>")
	)
	(segment
		(start 347.985588 -282.672028)
		(end 347.984572 -282.67152)
		(width 0.1143)
		(layer "In11.Cu")
		(net "P5E_CPU0_P1_RX_DN<3>")
	)
	(segment
		(start 347.985588 -285.912052)
		(end 347.984572 -285.911544)
		(width 0.1143)
		(layer "In11.Cu")
		(net "P5E_CPU0_P1_RX_DN<3>")
	)
	(segment
		(start 339.588094 -389.067802)
		(end 339.351112 -388.713218)
		(width 0.14224)
		(layer "In11.Cu")
		(net "P5E_CPU0_P1_RX_DN<3>")
	)
	(segment
		(start 347.99016 -283.317442)
		(end 348.019878 -283.300424)
		(width 0.1143)
		(layer "In11.Cu")
		(net "P5E_CPU0_P1_RX_DN<3>")
	)
	(segment
		(start 347.99524 -292.397434)
		(end 347.994224 -292.396926)
		(width 0.1143)
		(layer "In11.Cu")
		(net "P5E_CPU0_P1_RX_DN<3>")
	)
	(segment
		(start 347.984572 -285.911544)
		(end 347.949012 -285.890716)
		(width 0.1143)
		(layer "In11.Cu")
		(net "P5E_CPU0_P1_RX_DN<3>")
	)
	(segment
		(start 347.518228 -279.268682)
		(end 347.548708 -279.250902)
		(width 0.1143)
		(layer "In11.Cu")
		(net "P5E_CPU0_P1_RX_DN<3>")
	)
	(segment
		(start 348.458282 -277.64867)
		(end 348.488762 -277.63089)
		(width 0.1143)
		(layer "In11.Cu")
		(net "P5E_CPU0_P1_RX_DN<3>")
	)
	(segment
		(start 347.99016 -281.69743)
		(end 348.019878 -281.680412)
		(width 0.1143)
		(layer "In11.Cu")
		(net "P5E_CPU0_P1_RX_DN<3>")
	)
	(segment
		(start 347.985588 -284.29204)
		(end 347.984572 -284.291532)
		(width 0.1143)
		(layer "In11.Cu")
		(net "P5E_CPU0_P1_RX_DN<3>")
	)
	(segment
		(start 347.70568 -295.399968)
		(end 347.70568 -295.145968)
		(width 0.1143)
		(layer "In11.Cu")
		(net "P5E_CPU0_P1_RX_DN<3>")
	)
	(segment
		(start 347.9927 -285.916116)
		(end 347.99016 -285.914846)
		(width 0.1143)
		(layer "In11.Cu")
		(net "P5E_CPU0_P1_RX_DN<3>")
	)
	(segment
		(start 347.548708 -280.261314)
		(end 347.518228 -280.243534)
		(width 0.1143)
		(layer "In11.Cu")
		(net "P5E_CPU0_P1_RX_DN<3>")
	)
	(segment
		(start 347.988128 -284.293564)
		(end 347.987112 -284.293056)
		(width 0.1143)
		(layer "In11.Cu")
		(net "P5E_CPU0_P1_RX_DN<3>")
	)
	(segment
		(start 347.988128 -293.03853)
		(end 347.98889 -293.038022)
		(width 0.1143)
		(layer "In11.Cu")
		(net "P5E_CPU0_P1_RX_DN<3>")
	)
	(segment
		(start 347.985588 -278.4602)
		(end 347.987112 -278.459184)
		(width 0.1143)
		(layer "In11.Cu")
		(net "P5E_CPU0_P1_RX_DN<3>")
	)
	(segment
		(start 347.994224 -290.776914)
		(end 347.9927 -290.775898)
		(width 0.1143)
		(layer "In11.Cu")
		(net "P5E_CPU0_P1_RX_DN<3>")
	)
	(segment
		(start 347.98889 -283.318204)
		(end 347.99016 -283.317442)
		(width 0.1143)
		(layer "In11.Cu")
		(net "P5E_CPU0_P1_RX_DN<3>")
	)
	(segment
		(start 349.109284 -276.585934)
		(end 349.10903 -276.585934)
		(width 0.1143)
		(layer "In11.Cu")
		(net "P5E_CPU0_P1_RX_DN<3>")
	)
	(segment
		(start 347.949012 -293.06139)
		(end 347.985588 -293.040054)
		(width 0.1143)
		(layer "In11.Cu")
		(net "P5E_CPU0_P1_RX_DN<3>")
	)
	(segment
		(start 347.985588 -291.420042)
		(end 347.987112 -291.419026)
		(width 0.1143)
		(layer "In11.Cu")
		(net "P5E_CPU0_P1_RX_DN<3>")
	)
	(segment
		(start 347.994224 -285.917132)
		(end 347.9927 -285.916116)
		(width 0.1143)
		(layer "In11.Cu")
		(net "P5E_CPU0_P1_RX_DN<3>")
	)
	(segment
		(start 347.190568 -296.46372)
		(end 347.190568 -296.435272)
		(width 0.1143)
		(layer "In11.Cu")
		(net "P5E_CPU0_P1_RX_DN<3>")
	)
	(segment
		(start 339.371686 -372.81358)
		(end 344.702892 -370.605304)
		(width 0.14224)
		(layer "In11.Cu")
		(net "P5E_CPU0_P1_RX_DN<3>")
	)
	(segment
		(start 339.550248 -389.258048)
		(end 339.588094 -389.067802)
		(width 0.14224)
		(layer "In11.Cu")
		(net "P5E_CPU0_P1_RX_DN<3>")
	)
	(segment
		(start 347.988128 -290.773358)
		(end 347.987112 -290.77285)
		(width 0.1143)
		(layer "In11.Cu")
		(net "P5E_CPU0_P1_RX_DN<3>")
	)
	(segment
		(start 348.019878 -289.171634)
		(end 347.99524 -289.15741)
		(width 0.1143)
		(layer "In11.Cu")
		(net "P5E_CPU0_P1_RX_DN<3>")
	)
	(segment
		(start 347.994224 -281.057096)
		(end 347.9927 -281.05608)
		(width 0.1143)
		(layer "In11.Cu")
		(net "P5E_CPU0_P1_RX_DN<3>")
	)
	(segment
		(start 338.334858 -387.192266)
		(end 335.320894 -382.681734)
		(width 0.14224)
		(layer "In11.Cu")
		(net "P5E_CPU0_P1_RX_DN<3>")
	)
	(segment
		(start 347.985588 -281.700224)
		(end 347.987112 -281.699208)
		(width 0.1143)
		(layer "In11.Cu")
		(net "P5E_CPU0_P1_RX_DN<3>")
	)
	(segment
		(start 347.987112 -292.392862)
		(end 347.985588 -292.391846)
		(width 0.1143)
		(layer "In11.Cu")
		(net "P5E_CPU0_P1_RX_DN<3>")
	)
	(segment
		(start 347.994224 -292.396926)
		(end 347.9927 -292.39591)
		(width 0.1143)
		(layer "In11.Cu")
		(net "P5E_CPU0_P1_RX_DN<3>")
	)
	(segment
		(start 347.99524 -294.017446)
		(end 347.994224 -294.016938)
		(width 0.1143)
		(layer "In11.Cu")
		(net "P5E_CPU0_P1_RX_DN<3>")
	)
	(segment
		(start 347.949012 -291.441378)
		(end 347.985588 -291.420042)
		(width 0.1143)
		(layer "In11.Cu")
		(net "P5E_CPU0_P1_RX_DN<3>")
	)
	(segment
		(start 347.987112 -283.31922)
		(end 347.988128 -283.318712)
		(width 0.1143)
		(layer "In11.Cu")
		(net "P5E_CPU0_P1_RX_DN<3>")
	)
	(segment
		(start 347.984572 -281.051508)
		(end 347.949012 -281.03068)
		(width 0.1143)
		(layer "In11.Cu")
		(net "P5E_CPU0_P1_RX_DN<3>")
	)
	(segment
		(start 340.077298 -393.22883)
		(end 340.082124 -392.616944)
		(width 0.14224)
		(layer "In11.Cu")
		(net "P5E_CPU0_P1_RX_DN<3>")
	)
	(segment
		(start 347.985588 -294.660066)
		(end 347.987112 -294.65905)
		(width 0.1143)
		(layer "In11.Cu")
		(net "P5E_CPU0_P1_RX_DN<3>")
	)
	(segment
		(start 347.988128 -282.673552)
		(end 347.987112 -282.673044)
		(width 0.1143)
		(layer "In11.Cu")
		(net "P5E_CPU0_P1_RX_DN<3>")
	)
	(segment
		(start 340.39429 -393.545822)
		(end 340.077298 -393.22883)
		(width 0.14224)
		(layer "In11.Cu")
		(net "P5E_CPU0_P1_RX_DN<3>")
	)
	(segment
		(start 347.988128 -278.458676)
		(end 347.98889 -278.458168)
		(width 0.1143)
		(layer "In11.Cu")
		(net "P5E_CPU0_P1_RX_DN<3>")
	)
	(segment
		(start 347.99016 -284.294834)
		(end 347.98889 -284.294072)
		(width 0.1143)
		(layer "In11.Cu")
		(net "P5E_CPU0_P1_RX_DN<3>")
	)
	(segment
		(start 338.961476 -388.130034)
		(end 338.724494 -387.77545)
		(width 0.14224)
		(layer "In11.Cu")
		(net "P5E_CPU0_P1_RX_DN<3>")
	)
	(segment
		(start 347.98889 -292.393878)
		(end 347.988128 -292.39337)
		(width 0.1143)
		(layer "In11.Cu")
		(net "P5E_CPU0_P1_RX_DN<3>")
	)
	(segment
		(start 347.99016 -292.39464)
		(end 347.98889 -292.393878)
		(width 0.1143)
		(layer "In11.Cu")
		(net "P5E_CPU0_P1_RX_DN<3>")
	)
	(segment
		(start 347.987112 -278.459184)
		(end 347.988128 -278.458676)
		(width 0.1143)
		(layer "In11.Cu")
		(net "P5E_CPU0_P1_RX_DN<3>")
	)
	(segment
		(start 347.99016 -294.014652)
		(end 347.98889 -294.01389)
		(width 0.1143)
		(layer "In11.Cu")
		(net "P5E_CPU0_P1_RX_DN<3>")
	)
	(segment
		(start 351.128584 -308.68493)
		(end 347.190568 -299.176948)
		(width 0.14224)
		(layer "In11.Cu")
		(net "P5E_CPU0_P1_RX_DN<3>")
	)
	(segment
		(start 347.99524 -290.777422)
		(end 347.994224 -290.776914)
		(width 0.1143)
		(layer "In11.Cu")
		(net "P5E_CPU0_P1_RX_DN<3>")
	)
	(segment
		(start 347.98889 -282.67406)
		(end 347.988128 -282.673552)
		(width 0.1143)
		(layer "In11.Cu")
		(net "P5E_CPU0_P1_RX_DN<3>")
	)
	(segment
		(start 347.987112 -293.039038)
		(end 347.988128 -293.03853)
		(width 0.1143)
		(layer "In11.Cu")
		(net "P5E_CPU0_P1_RX_DN<3>")
	)
	(segment
		(start 347.985588 -284.940248)
		(end 347.987112 -284.939232)
		(width 0.1143)
		(layer "In11.Cu")
		(net "P5E_CPU0_P1_RX_DN<3>")
	)
	(segment
		(start 338.297012 -387.382512)
		(end 338.334858 -387.192266)
		(width 0.14224)
		(layer "In11.Cu")
		(net "P5E_CPU0_P1_RX_DN<3>")
	)
	(segment
		(start 347.988128 -289.798506)
		(end 347.98889 -289.797998)
		(width 0.1143)
		(layer "In11.Cu")
		(net "P5E_CPU0_P1_RX_DN<3>")
	)
	(segment
		(start 340.272624 -393.786868)
		(end 340.39429 -393.716764)
		(width 0.14224)
		(layer "In11.Cu")
		(net "P5E_CPU0_P1_RX_DN<3>")
	)
	(segment
		(start 347.987112 -284.939232)
		(end 347.988128 -284.938724)
		(width 0.1143)
		(layer "In11.Cu")
		(net "P5E_CPU0_P1_RX_DN<3>")
	)
	(segment
		(start 347.988128 -281.6987)
		(end 347.98889 -281.698192)
		(width 0.1143)
		(layer "In11.Cu")
		(net "P5E_CPU0_P1_RX_DN<3>")
	)
	(segment
		(start 347.190568 -296.435272)
		(end 347.236288 -296.389552)
		(width 0.1143)
		(layer "In11.Cu")
		(net "P5E_CPU0_P1_RX_DN<3>")
	)
	(segment
		(start 340.386162 -392.31316)
		(end 340.386162 -390.571228)
		(width 0.14224)
		(layer "In11.Cu")
		(net "P5E_CPU0_P1_RX_DN<3>")
	)
	(segment
		(start 347.99016 -284.937454)
		(end 348.019878 -284.920436)
		(width 0.1143)
		(layer "In11.Cu")
		(net "P5E_CPU0_P1_RX_DN<3>")
	)
	(segment
		(start 347.518228 -280.243534)
		(end 347.479112 -280.220674)
		(width 0.1143)
		(layer "In11.Cu")
		(net "P5E_CPU0_P1_RX_DN<3>")
	)
	(segment
		(start 335.653888 -376.075448)
		(end 337.997038 -373.732298)
		(width 0.14224)
		(layer "In11.Cu")
		(net "P5E_CPU0_P1_RX_DN<3>")
	)
	(segment
		(start 347.985588 -292.391846)
		(end 347.949012 -292.37051)
		(width 0.1143)
		(layer "In11.Cu")
		(net "P5E_CPU0_P1_RX_DN<3>")
	)
	(segment
		(start 335.237074 -382.40589)
		(end 335.237074 -377.081288)
		(width 0.14224)
		(layer "In11.Cu")
		(net "P5E_CPU0_P1_RX_DN<3>")
	)
	(segment
		(start 338.92363 -388.32028)
		(end 338.961476 -388.130034)
		(width 0.14224)
		(layer "In11.Cu")
		(net "P5E_CPU0_P1_RX_DN<3>")
	)
	(segment
		(start 347.479112 -279.291542)
		(end 347.518228 -279.268682)
		(width 0.1143)
		(layer "In11.Cu")
		(net "P5E_CPU0_P1_RX_DN<3>")
	)
	(segment
		(start 347.9927 -282.676092)
		(end 347.99016 -282.674822)
		(width 0.1143)
		(layer "In11.Cu")
		(net "P5E_CPU0_P1_RX_DN<3>")
	)
	(segment
		(start 347.9927 -292.39591)
		(end 347.99016 -292.39464)
		(width 0.1143)
		(layer "In11.Cu")
		(net "P5E_CPU0_P1_RX_DN<3>")
	)
	(segment
		(start 347.988128 -284.938724)
		(end 347.98889 -284.938216)
		(width 0.1143)
		(layer "In11.Cu")
		(net "P5E_CPU0_P1_RX_DN<3>")
	)
	(segment
		(start 347.98889 -293.038022)
		(end 347.99016 -293.03726)
		(width 0.1143)
		(layer "In11.Cu")
		(net "P5E_CPU0_P1_RX_DN<3>")
	)
	(segment
		(start 366.531906 -334.494124)
		(end 365.532162 -328.933048)
		(width 0.14224)
		(layer "In11.Cu")
		(net "P5E_CPU0_P1_RX_DN<3>")
	)
	(segment
		(start 347.994224 -289.156902)
		(end 347.9927 -289.155886)
		(width 0.1143)
		(layer "In11.Cu")
		(net "P5E_CPU0_P1_RX_DN<3>")
	)
	(segment
		(start 347.949012 -281.72156)
		(end 347.985588 -281.700224)
		(width 0.1143)
		(layer "In11.Cu")
		(net "P5E_CPU0_P1_RX_DN<3>")
	)
	(segment
		(start 366.848898 -347.644212)
		(end 367.284254 -346.592906)
		(width 0.14224)
		(layer "In11.Cu")
		(net "P5E_CPU0_P1_RX_DN<3>")
	)
	(segment
		(start 347.985588 -283.320236)
		(end 347.987112 -283.31922)
		(width 0.1143)
		(layer "In11.Cu")
		(net "P5E_CPU0_P1_RX_DN<3>")
	)
	(segment
		(start 347.98889 -281.698192)
		(end 347.99016 -281.69743)
		(width 0.1143)
		(layer "In11.Cu")
		(net "P5E_CPU0_P1_RX_DN<3>")
	)
	(segment
		(start 366.531906 -334.494632)
		(end 366.531906 -334.494124)
		(width 0.14224)
		(layer "In11.Cu")
		(net "P5E_CPU0_P1_RX_DN<3>")
	)
	(segment
		(start 347.9927 -289.155886)
		(end 347.99016 -289.154616)
		(width 0.1143)
		(layer "In11.Cu")
		(net "P5E_CPU0_P1_RX_DN<3>")
	)
	(segment
		(start 348.019878 -281.071828)
		(end 347.99524 -281.057604)
		(width 0.1143)
		(layer "In11.Cu")
		(net "P5E_CPU0_P1_RX_DN<3>")
	)
	(segment
		(start 347.9927 -290.775898)
		(end 347.99016 -290.774628)
		(width 0.1143)
		(layer "In11.Cu")
		(net "P5E_CPU0_P1_RX_DN<3>")
	)
	(segment
		(start 347.984572 -284.291532)
		(end 347.949012 -284.270704)
		(width 0.1143)
		(layer "In11.Cu")
		(net "P5E_CPU0_P1_RX_DN<3>")
	)
	(segment
		(start 347.98889 -291.41801)
		(end 347.99016 -291.417248)
		(width 0.1143)
		(layer "In11.Cu")
		(net "P5E_CPU0_P1_RX_DN<3>")
	)
	(segment
		(start 348.019878 -294.03167)
		(end 347.99524 -294.017446)
		(width 0.1143)
		(layer "In11.Cu")
		(net "P5E_CPU0_P1_RX_DN<3>")
	)
	(segment
		(start 347.985588 -294.011858)
		(end 347.949012 -293.990522)
		(width 0.1143)
		(layer "In11.Cu")
		(net "P5E_CPU0_P1_RX_DN<3>")
	)
	(segment
		(start 347.987112 -294.012874)
		(end 347.985588 -294.011858)
		(width 0.1143)
		(layer "In11.Cu")
		(net "P5E_CPU0_P1_RX_DN<3>")
	)
	(segment
		(start 349.03918 -276.516084)
		(end 348.741238 -276.516084)
		(width 0.1143)
		(layer "In11.Cu")
		(net "P5E_CPU0_P1_RX_DN<3>")
	)
	(segment
		(start 347.98889 -285.914084)
		(end 347.988128 -285.913576)
		(width 0.1143)
		(layer "In11.Cu")
		(net "P5E_CPU0_P1_RX_DN<3>")
	)
	(segment
		(start 347.949012 -278.481536)
		(end 347.985588 -278.4602)
		(width 0.1143)
		(layer "In11.Cu")
		(net "P5E_CPU0_P1_RX_DN<3>")
	)
	(segment
		(start 347.99524 -285.91764)
		(end 347.994224 -285.917132)
		(width 0.1143)
		(layer "In11.Cu")
		(net "P5E_CPU0_P1_RX_DN<3>")
	)
	(segment
		(start 349.10903 -276.585934)
		(end 349.03918 -276.516084)
		(width 0.1143)
		(layer "In11.Cu")
		(net "P5E_CPU0_P1_RX_DN<3>")
	)
	(segment
		(start 339.97773 -389.650986)
		(end 339.787484 -389.61314)
		(width 0.14224)
		(layer "In11.Cu")
		(net "P5E_CPU0_P1_RX_DN<3>")
	)
	(segment
		(start 347.985588 -289.151822)
		(end 347.949012 -289.130486)
		(width 0.1143)
		(layer "In11.Cu")
		(net "P5E_CPU0_P1_RX_DN<3>")
	)
	(segment
		(start 347.988128 -294.658542)
		(end 348.019878 -294.640254)
		(width 0.1143)
		(layer "In11.Cu")
		(net "P5E_CPU0_P1_RX_DN<3>")
	)
	(segment
		(start 347.9927 -281.05608)
		(end 347.99016 -281.05481)
		(width 0.1143)
		(layer "In11.Cu")
		(net "P5E_CPU0_P1_RX_DN<3>")
	)
	(segment
		(start 339.787484 -389.61314)
		(end 339.550248 -389.258048)
		(width 0.14224)
		(layer "In11.Cu")
		(net "P5E_CPU0_P1_RX_DN<3>")
	)
	(segment
		(start 347.985588 -290.771834)
		(end 347.949012 -290.750498)
		(width 0.1143)
		(layer "In11.Cu")
		(net "P5E_CPU0_P1_RX_DN<3>")
	)
	(segment
		(start 347.987112 -285.913068)
		(end 347.985588 -285.912052)
		(width 0.1143)
		(layer "In11.Cu")
		(net "P5E_CPU0_P1_RX_DN<3>")
	)
	(segment
		(start 367.531904 -345.347798)
		(end 367.531904 -340.056724)
		(width 0.14224)
		(layer "In11.Cu")
		(net "P5E_CPU0_P1_RX_DN<3>")
	)
	(segment
		(start 347.9927 -284.296104)
		(end 347.99016 -284.294834)
		(width 0.1143)
		(layer "In11.Cu")
		(net "P5E_CPU0_P1_RX_DN<3>")
	)
	(segment
		(start 347.988128 -283.318712)
		(end 347.98889 -283.318204)
		(width 0.1143)
		(layer "In11.Cu")
		(net "P5E_CPU0_P1_RX_DN<3>")
	)
	(segment
		(start 347.99524 -289.15741)
		(end 347.994224 -289.156902)
		(width 0.1143)
		(layer "In11.Cu")
		(net "P5E_CPU0_P1_RX_DN<3>")
	)
	(segment
		(start 347.987112 -291.419026)
		(end 347.988128 -291.418518)
		(width 0.1143)
		(layer "In11.Cu")
		(net "P5E_CPU0_P1_RX_DN<3>")
	)
	(segment
		(start 348.019878 -290.791646)
		(end 347.99524 -290.777422)
		(width 0.1143)
		(layer "In11.Cu")
		(net "P5E_CPU0_P1_RX_DN<3>")
	)
	(segment
		(start 347.994224 -284.29712)
		(end 347.9927 -284.296104)
		(width 0.1143)
		(layer "In11.Cu")
		(net "P5E_CPU0_P1_RX_DN<3>")
	)
	(segment
		(start 347.988128 -289.153346)
		(end 347.987112 -289.152838)
		(width 0.1143)
		(layer "In11.Cu")
		(net "P5E_CPU0_P1_RX_DN<3>")
	)
	(segment
		(start 347.190568 -299.176948)
		(end 347.190568 -296.46372)
		(width 0.14224)
		(layer "In11.Cu")
		(net "P5E_CPU0_P1_RX_DN<3>")
	)
	(segment
		(start 347.988128 -294.013382)
		(end 347.987112 -294.012874)
		(width 0.1143)
		(layer "In11.Cu")
		(net "P5E_CPU0_P1_RX_DN<3>")
	)
	(segment
		(start 340.082124 -392.616944)
		(end 340.386162 -392.31316)
		(width 0.14224)
		(layer "In11.Cu")
		(net "P5E_CPU0_P1_RX_DN<3>")
	)
	(segment
		(start 347.984572 -282.67152)
		(end 347.949012 -282.650692)
		(width 0.1143)
		(layer "In11.Cu")
		(net "P5E_CPU0_P1_RX_DN<3>")
	)
	(segment
		(start 367.531904 -340.056724)
		(end 366.531906 -334.494632)
		(width 0.14224)
		(layer "In11.Cu")
		(net "P5E_CPU0_P1_RX_DN<3>")
	)
	(segment
		(start 348.889066 -276.861524)
		(end 348.9325 -276.836378)
		(width 0.1143)
		(layer "In11.Cu")
		(net "P5E_CPU0_P1_RX_DN<3>")
	)
	(segment
		(start 347.99016 -289.797236)
		(end 348.019878 -289.780218)
		(width 0.1143)
		(layer "In11.Cu")
		(net "P5E_CPU0_P1_RX_DN<3>")
	)
	(segment
		(start 347.99016 -290.774628)
		(end 347.98889 -290.773866)
		(width 0.1143)
		(layer "In11.Cu")
		(net "P5E_CPU0_P1_RX_DN<3>")
	)
	(segment
		(start 347.949012 -286.581342)
		(end 347.988128 -286.558482)
		(width 0.1143)
		(layer "In11.Cu")
		(net "P5E_CPU0_P1_RX_DN<3>")
	)
	(segment
		(start 347.98889 -284.938216)
		(end 347.99016 -284.937454)
		(width 0.1143)
		(layer "In11.Cu")
		(net "P5E_CPU0_P1_RX_DN<3>")
	)
	(segment
		(start 347.99524 -282.677616)
		(end 347.994224 -282.677108)
		(width 0.1143)
		(layer "In11.Cu")
		(net "P5E_CPU0_P1_RX_DN<3>")
	)
	(segment
		(start 347.99016 -282.674822)
		(end 347.98889 -282.67406)
		(width 0.1143)
		(layer "In11.Cu")
		(net "P5E_CPU0_P1_RX_DN<3>")
	)
	(segment
		(start 349.109284 -276.586442)
		(end 349.109284 -276.585934)
		(width 0.1143)
		(layer "In11.Cu")
		(net "P5E_CPU0_P1_RX_DN<3>")
	)
	(segment
		(start 347.98889 -284.294072)
		(end 347.988128 -284.293564)
		(width 0.1143)
		(layer "In11.Cu")
		(net "P5E_CPU0_P1_RX_DN<3>")
	)
	(segment
		(start 347.949012 -283.341572)
		(end 347.985588 -283.320236)
		(width 0.1143)
		(layer "In11.Cu")
		(net "P5E_CPU0_P1_RX_DN<3>")
	)
	(segment
		(start 347.987112 -281.699208)
		(end 347.988128 -281.6987)
		(width 0.1143)
		(layer "In11.Cu")
		(net "P5E_CPU0_P1_RX_DN<3>")
	)
	(segment
		(start 347.99016 -293.03726)
		(end 348.019878 -293.020242)
		(width 0.1143)
		(layer "In11.Cu")
		(net "P5E_CPU0_P1_RX_DN<3>")
	)
	(segment
		(start 348.019878 -287.551876)
		(end 347.988128 -287.533588)
		(width 0.1143)
		(layer "In11.Cu")
		(net "P5E_CPU0_P1_RX_DN<3>")
	)
	(segment
		(start 347.949012 -289.821366)
		(end 347.985588 -289.80003)
		(width 0.1143)
		(layer "In11.Cu")
		(net "P5E_CPU0_P1_RX_DN<3>")
	)
	(segment
		(start 347.949012 -284.961584)
		(end 347.985588 -284.940248)
		(width 0.1143)
		(layer "In11.Cu")
		(net "P5E_CPU0_P1_RX_DN<3>")
	)
	(segment
		(start 347.949012 -288.201354)
		(end 347.988128 -288.178494)
		(width 0.1143)
		(layer "In11.Cu")
		(net "P5E_CPU0_P1_RX_DN<3>")
	)
	(segment
		(start 347.987112 -290.77285)
		(end 347.985588 -290.771834)
		(width 0.1143)
		(layer "In11.Cu")
		(net "P5E_CPU0_P1_RX_DN<3>")
	)
	(segment
		(start 347.98889 -281.054048)
		(end 347.988128 -281.05354)
		(width 0.1143)
		(layer "In11.Cu")
		(net "P5E_CPU0_P1_RX_DN<3>")
	)
	(segment
		(start 348.419166 -277.67153)
		(end 348.458282 -277.64867)
		(width 0.1143)
		(layer "In11.Cu")
		(net "P5E_CPU0_P1_RX_DN<3>")
	)
	(segment
		(start 348.019878 -284.311852)
		(end 347.99524 -284.297628)
		(width 0.1143)
		(layer "In11.Cu")
		(net "P5E_CPU0_P1_RX_DN<3>")
	)
	(segment
		(start 338.724494 -387.77545)
		(end 338.534248 -387.737604)
		(width 0.14224)
		(layer "In11.Cu")
		(net "P5E_CPU0_P1_RX_DN<3>")
	)
	(segment
		(start 348.019878 -285.931864)
		(end 347.99524 -285.91764)
		(width 0.1143)
		(layer "In11.Cu")
		(net "P5E_CPU0_P1_RX_DN<3>")
	)
	(segment
		(start 347.98889 -278.458168)
		(end 347.99016 -278.457406)
		(width 0.1143)
		(layer "In11.Cu")
		(net "P5E_CPU0_P1_RX_DN<3>")
	)
	(segment
		(start 340.272116 -393.787376)
		(end 340.272624 -393.786868)
		(width 0.14224)
		(layer "In11.Cu")
		(net "P5E_CPU0_P1_RX_DN<3>")
	)
	(segment
		(start 339.918802 -393.69238)
		(end 340.272116 -393.787376)
		(width 0.14224)
		(layer "In11.Cu")
		(net "P5E_CPU0_P1_RX_DN<3>")
	)
	(segment
		(start 347.988128 -287.533588)
		(end 347.951552 -287.512252)
		(width 0.1143)
		(layer "In11.Cu")
		(net "P5E_CPU0_P1_RX_DN<3>")
	)
	(segment
		(start 347.236288 -296.389552)
		(end 347.236288 -295.86936)
		(width 0.1143)
		(layer "In11.Cu")
		(net "P5E_CPU0_P1_RX_DN<3>")
	)
	(segment
		(start 347.988128 -285.913576)
		(end 347.987112 -285.913068)
		(width 0.1143)
		(layer "In11.Cu")
		(net "P5E_CPU0_P1_RX_DN<3>")
	)
	(segment
		(start 347.236288 -295.86936)
		(end 347.70568 -295.399968)
		(width 0.1143)
		(layer "In11.Cu")
		(net "P5E_CPU0_P1_RX_DN<3>")
	)
	(segment
		(start 347.99016 -285.914846)
		(end 347.98889 -285.914084)
		(width 0.1143)
		(layer "In11.Cu")
		(net "P5E_CPU0_P1_RX_DN<3>")
	)
	(segment
		(start 347.987112 -282.673044)
		(end 347.985588 -282.672028)
		(width 0.1143)
		(layer "In11.Cu")
		(net "P5E_CPU0_P1_RX_DN<3>")
	)
	(segment
		(start 347.99016 -278.457406)
		(end 348.019878 -278.440388)
		(width 0.1143)
		(layer "In11.Cu")
		(net "P5E_CPU0_P1_RX_DN<3>")
	)
	(segment
		(start 339.351112 -388.713218)
		(end 339.160866 -388.675372)
		(width 0.14224)
		(layer "In11.Cu")
		(net "P5E_CPU0_P1_RX_DN<3>")
	)
	(segment
		(start 347.987112 -289.152838)
		(end 347.985588 -289.151822)
		(width 0.1143)
		(layer "In11.Cu")
		(net "P5E_CPU0_P1_RX_DN<3>")
	)
	(segment
		(start 347.988128 -281.05354)
		(end 347.987112 -281.053032)
		(width 0.1143)
		(layer "In11.Cu")
		(net "P5E_CPU0_P1_RX_DN<3>")
	)
	(segment
		(start 339.160866 -388.675372)
		(end 338.92363 -388.32028)
		(width 0.14224)
		(layer "In11.Cu")
		(net "P5E_CPU0_P1_RX_DN<3>")
	)
	(segment
		(start 347.994224 -294.016938)
		(end 347.9927 -294.015922)
		(width 0.1143)
		(layer "In11.Cu")
		(net "P5E_CPU0_P1_RX_DN<3>")
	)
	(segment
		(start 348.019878 -282.69184)
		(end 347.99524 -282.677616)
		(width 0.1143)
		(layer "In11.Cu")
		(net "P5E_CPU0_P1_RX_DN<3>")
	)
	(segment
		(start 347.985588 -293.040054)
		(end 347.987112 -293.039038)
		(width 0.1143)
		(layer "In11.Cu")
		(net "P5E_CPU0_P1_RX_DN<3>")
	)
	(segment
		(start 350.920304 -366.45088)
		(end 361.054396 -356.316788)
		(width 0.14224)
		(layer "In11.Cu")
		(net "P5E_CPU0_P1_RX_DN<3>")
	)
	(segment
		(start 347.987112 -289.799014)
		(end 347.988128 -289.798506)
		(width 0.1143)
		(layer "In11.Cu")
		(net "P5E_CPU0_P1_RX_DN<3>")
	)
	(segment
		(start 338.534248 -387.737604)
		(end 338.297012 -387.382512)
		(width 0.14224)
		(layer "In11.Cu")
		(net "P5E_CPU0_P1_RX_DN<3>")
	)
	(segment
		(start 347.988128 -292.39337)
		(end 347.987112 -292.392862)
		(width 0.1143)
		(layer "In11.Cu")
		(net "P5E_CPU0_P1_RX_DN<3>")
	)
	(segment
		(start 347.949012 -294.681402)
		(end 347.985588 -294.660066)
		(width 0.1143)
		(layer "In11.Cu")
		(net "P5E_CPU0_P1_RX_DN<3>")
	)
	(segment
		(start 347.99016 -291.417248)
		(end 348.019878 -291.40023)
		(width 0.1143)
		(layer "In11.Cu")
		(net "P5E_CPU0_P1_RX_DN<3>")
	)
	(segment
		(start 347.98889 -289.153854)
		(end 347.988128 -289.153346)
		(width 0.1143)
		(layer "In11.Cu")
		(net "P5E_CPU0_P1_RX_DN<3>")
	)
	(segment
		(start 347.994224 -282.677108)
		(end 347.9927 -282.676092)
		(width 0.1143)
		(layer "In11.Cu")
		(net "P5E_CPU0_P1_RX_DN<3>")
	)
	(segment
		(start 365.532162 -328.933048)
		(end 364.297214 -326.563228)
		(width 0.14224)
		(layer "In11.Cu")
		(net "P5E_CPU0_P1_RX_DN<3>")
	)
	(segment
		(start 348.019878 -292.411658)
		(end 347.99524 -292.397434)
		(width 0.1143)
		(layer "In11.Cu")
		(net "P5E_CPU0_P1_RX_DN<3>")
	)
	(segment
		(start 364.297214 -326.563228)
		(end 357.717344 -318.54521)
		(width 0.14224)
		(layer "In11.Cu")
		(net "P5E_CPU0_P1_RX_DN<3>")
	)
	(segment
		(start 347.99016 -289.154616)
		(end 347.98889 -289.153854)
		(width 0.1143)
		(layer "In11.Cu")
		(net "P5E_CPU0_P1_RX_DN<3>")
	)
	(segment
		(start 347.9927 -294.015922)
		(end 347.99016 -294.014652)
		(width 0.1143)
		(layer "In11.Cu")
		(net "P5E_CPU0_P1_RX_DN<3>")
	)
	(segment
		(start 347.99524 -281.057604)
		(end 347.994224 -281.057096)
		(width 0.1143)
		(layer "In11.Cu")
		(net "P5E_CPU0_P1_RX_DN<3>")
	)
	(segment
		(start 347.988128 -286.558482)
		(end 348.021656 -286.538924)
		(width 0.1143)
		(layer "In11.Cu")
		(net "P5E_CPU0_P1_RX_DN<3>")
	)
	(segment
		(start 340.214712 -390.00557)
		(end 339.97773 -389.650986)
		(width 0.14224)
		(layer "In11.Cu")
		(net "P5E_CPU0_P1_RX_DN<3>")
	)
	(segment
		(start 347.98889 -290.773866)
		(end 347.988128 -290.773358)
		(width 0.1143)
		(layer "In11.Cu")
		(net "P5E_CPU0_P1_RX_DN<3>")
	)
	(segment
		(start 340.39429 -393.716764)
		(end 340.39429 -393.545822)
		(width 0.14224)
		(layer "In11.Cu")
		(net "P5E_CPU0_P1_RX_DN<3>")
	)
	(segment
		(start 347.985588 -281.052016)
		(end 347.984572 -281.051508)
		(width 0.1143)
		(layer "In11.Cu")
		(net "P5E_CPU0_P1_RX_DN<3>")
	)
	(segment
		(start 347.98889 -294.01389)
		(end 347.988128 -294.013382)
		(width 0.1143)
		(layer "In11.Cu")
		(net "P5E_CPU0_P1_RX_DN<3>")
	)
	(segment
		(start 347.987112 -281.053032)
		(end 347.985588 -281.052016)
		(width 0.1143)
		(layer "In11.Cu")
		(net "P5E_CPU0_P1_RX_DN<3>")
	)
	(segment
		(start 347.988128 -288.178494)
		(end 348.021656 -288.158936)
		(width 0.1143)
		(layer "In11.Cu")
		(net "P5E_CPU0_P1_RX_DN<3>")
	)
	(segment
		(start 347.987112 -294.65905)
		(end 347.988128 -294.658542)
		(width 0.1143)
		(layer "In11.Cu")
		(net "P5E_CPU0_P1_RX_DN<3>")
	)
	(segment
		(start 347.99016 -281.05481)
		(end 347.98889 -281.054048)
		(width 0.1143)
		(layer "In11.Cu")
		(net "P5E_CPU0_P1_RX_DN<3>")
	)
	(arc
		(start 347.70568 -278.946102)
		(mid 347.770195 -278.683883)
		(end 347.949012 -278.481536)
		(width 0.1143)
		(layer "In11.Cu")
		(net "P5E_CPU0_P1_RX_DN<3>")
	)
	(arc
		(start 348.175834 -287.856168)
		(mid 348.134579 -287.685197)
		(end 348.019878 -287.551876)
		(width 0.1143)
		(layer "In11.Cu")
		(net "P5E_CPU0_P1_RX_DN<3>")
	)
	(arc
		(start 347.949012 -289.130486)
		(mid 347.705685 -288.66592)
		(end 347.949012 -288.201354)
		(width 0.1143)
		(layer "In11.Cu")
		(net "P5E_CPU0_P1_RX_DN<3>")
	)
	(arc
		(start 347.949012 -293.990522)
		(mid 347.705685 -293.525956)
		(end 347.949012 -293.06139)
		(width 0.1143)
		(layer "In11.Cu")
		(net "P5E_CPU0_P1_RX_DN<3>")
	)
	(arc
		(start 347.70568 -280.566114)
		(mid 347.664131 -280.394692)
		(end 347.548708 -280.261314)
		(width 0.1143)
		(layer "In11.Cu")
		(net "P5E_CPU0_P1_RX_DN<3>")
	)
	(arc
		(start 348.645734 -277.32609)
		(mid 348.710249 -277.063871)
		(end 348.889066 -276.861524)
		(width 0.1143)
		(layer "In11.Cu")
		(net "P5E_CPU0_P1_RX_DN<3>")
	)
	(arc
		(start 347.949012 -282.650692)
		(mid 347.705685 -282.186126)
		(end 347.949012 -281.72156)
		(width 0.1143)
		(layer "In11.Cu")
		(net "P5E_CPU0_P1_RX_DN<3>")
	)
	(arc
		(start 347.949012 -290.750498)
		(mid 347.705685 -290.285932)
		(end 347.949012 -289.821366)
		(width 0.1143)
		(layer "In11.Cu")
		(net "P5E_CPU0_P1_RX_DN<3>")
	)
	(arc
		(start 335.320894 -382.681734)
		(mid 335.258551 -382.550023)
		(end 335.237074 -382.40589)
		(width 0.14224)
		(layer "In11.Cu")
		(net "P5E_CPU0_P1_RX_DN<3>")
	)
	(arc
		(start 348.019878 -283.300424)
		(mid 348.175806 -282.996132)
		(end 348.019878 -282.69184)
		(width 0.1143)
		(layer "In11.Cu")
		(net "P5E_CPU0_P1_RX_DN<3>")
	)
	(arc
		(start 348.019878 -278.440388)
		(mid 348.134554 -278.307054)
		(end 348.175834 -278.136096)
		(width 0.1143)
		(layer "In11.Cu")
		(net "P5E_CPU0_P1_RX_DN<3>")
	)
	(arc
		(start 347.949012 -292.37051)
		(mid 347.705685 -291.905944)
		(end 347.949012 -291.441378)
		(width 0.1143)
		(layer "In11.Cu")
		(net "P5E_CPU0_P1_RX_DN<3>")
	)
	(arc
		(start 348.9325 -276.836378)
		(mid 349.048025 -276.730606)
		(end 349.109284 -276.586442)
		(width 0.1143)
		(layer "In11.Cu")
		(net "P5E_CPU0_P1_RX_DN<3>")
	)
	(arc
		(start 348.019878 -291.40023)
		(mid 348.175806 -291.095938)
		(end 348.019878 -290.791646)
		(width 0.1143)
		(layer "In11.Cu")
		(net "P5E_CPU0_P1_RX_DN<3>")
	)
	(arc
		(start 348.019878 -281.680412)
		(mid 348.175806 -281.37612)
		(end 348.019878 -281.071828)
		(width 0.1143)
		(layer "In11.Cu")
		(net "P5E_CPU0_P1_RX_DN<3>")
	)
	(arc
		(start 348.019878 -294.640254)
		(mid 348.175806 -294.335962)
		(end 348.019878 -294.03167)
		(width 0.1143)
		(layer "In11.Cu")
		(net "P5E_CPU0_P1_RX_DN<3>")
	)
	(arc
		(start 347.479112 -280.220674)
		(mid 347.235785 -279.756108)
		(end 347.479112 -279.291542)
		(width 0.1143)
		(layer "In11.Cu")
		(net "P5E_CPU0_P1_RX_DN<3>")
	)
	(arc
		(start 347.548708 -279.250902)
		(mid 347.664135 -279.117526)
		(end 347.70568 -278.946102)
		(width 0.1143)
		(layer "In11.Cu")
		(net "P5E_CPU0_P1_RX_DN<3>")
	)
	(arc
		(start 347.70568 -295.145968)
		(mid 347.770195 -294.883749)
		(end 347.949012 -294.681402)
		(width 0.1143)
		(layer "In11.Cu")
		(net "P5E_CPU0_P1_RX_DN<3>")
	)
	(arc
		(start 361.054396 -356.316788)
		(mid 364.378831 -352.265916)
		(end 366.848898 -347.644212)
		(width 0.14224)
		(layer "In11.Cu")
		(net "P5E_CPU0_P1_RX_DN<3>")
	)
	(arc
		(start 348.019878 -289.780218)
		(mid 348.175806 -289.475926)
		(end 348.019878 -289.171634)
		(width 0.1143)
		(layer "In11.Cu")
		(net "P5E_CPU0_P1_RX_DN<3>")
	)
	(arc
		(start 347.70568 -287.045908)
		(mid 347.770195 -286.783689)
		(end 347.949012 -286.581342)
		(width 0.1143)
		(layer "In11.Cu")
		(net "P5E_CPU0_P1_RX_DN<3>")
	)
	(arc
		(start 348.019878 -293.020242)
		(mid 348.175806 -292.71595)
		(end 348.019878 -292.411658)
		(width 0.1143)
		(layer "In11.Cu")
		(net "P5E_CPU0_P1_RX_DN<3>")
	)
	(arc
		(start 367.284254 -346.592906)
		(mid 367.469396 -345.982548)
		(end 367.531904 -345.347798)
		(width 0.14224)
		(layer "In11.Cu")
		(net "P5E_CPU0_P1_RX_DN<3>")
	)
	(arc
		(start 348.019878 -284.920436)
		(mid 348.175806 -284.616144)
		(end 348.019878 -284.311852)
		(width 0.1143)
		(layer "In11.Cu")
		(net "P5E_CPU0_P1_RX_DN<3>")
	)
	(arc
		(start 335.237074 -377.081288)
		(mid 335.345435 -376.536901)
		(end 335.653888 -376.075448)
		(width 0.14224)
		(layer "In11.Cu")
		(net "P5E_CPU0_P1_RX_DN<3>")
	)
	(arc
		(start 347.949012 -285.890716)
		(mid 347.705685 -285.42615)
		(end 347.949012 -284.961584)
		(width 0.1143)
		(layer "In11.Cu")
		(net "P5E_CPU0_P1_RX_DN<3>")
	)
	(arc
		(start 344.702892 -370.605304)
		(mid 348.016183 -368.834267)
		(end 350.920304 -366.45088)
		(width 0.14224)
		(layer "In11.Cu")
		(net "P5E_CPU0_P1_RX_DN<3>")
	)
	(arc
		(start 347.949012 -284.270704)
		(mid 347.705685 -283.806138)
		(end 347.949012 -283.341572)
		(width 0.1143)
		(layer "In11.Cu")
		(net "P5E_CPU0_P1_RX_DN<3>")
	)
	(arc
		(start 348.488762 -277.63089)
		(mid 348.604189 -277.497514)
		(end 348.645734 -277.32609)
		(width 0.1143)
		(layer "In11.Cu")
		(net "P5E_CPU0_P1_RX_DN<3>")
	)
	(arc
		(start 340.386162 -390.571228)
		(mid 340.342443 -390.275662)
		(end 340.214712 -390.00557)
		(width 0.14224)
		(layer "In11.Cu")
		(net "P5E_CPU0_P1_RX_DN<3>")
	)
	(arc
		(start 347.949012 -281.03068)
		(mid 347.770199 -280.82833)
		(end 347.70568 -280.566114)
		(width 0.1143)
		(layer "In11.Cu")
		(net "P5E_CPU0_P1_RX_DN<3>")
	)
	(arc
		(start 348.175834 -278.136096)
		(mid 348.240349 -277.873877)
		(end 348.419166 -277.67153)
		(width 0.1143)
		(layer "In11.Cu")
		(net "P5E_CPU0_P1_RX_DN<3>")
	)
	(arc
		(start 348.021656 -286.538924)
		(mid 348.135063 -286.406035)
		(end 348.175834 -286.236156)
		(width 0.1143)
		(layer "In11.Cu")
		(net "P5E_CPU0_P1_RX_DN<3>")
	)
	(arc
		(start 337.997038 -373.732298)
		(mid 338.639126 -373.205256)
		(end 339.371686 -372.81358)
		(width 0.14224)
		(layer "In11.Cu")
		(net "P5E_CPU0_P1_RX_DN<3>")
	)
	(arc
		(start 348.021656 -288.158936)
		(mid 348.135063 -288.026047)
		(end 348.175834 -287.856168)
		(width 0.1143)
		(layer "In11.Cu")
		(net "P5E_CPU0_P1_RX_DN<3>")
	)
	(arc
		(start 348.175834 -286.236156)
		(mid 348.134579 -286.065185)
		(end 348.019878 -285.931864)
		(width 0.1143)
		(layer "In11.Cu")
		(net "P5E_CPU0_P1_RX_DN<3>")
	)
	(arc
		(start 347.951552 -287.512252)
		(mid 347.7709 -287.309507)
		(end 347.70568 -287.045908)
		(width 0.1143)
		(layer "In11.Cu")
		(net "P5E_CPU0_P1_RX_DN<3>")
	)
	(segment
		(start 346.387928 -274.630134)
		(end 345.921076 -274.896072)
		(width 0.12954)
		(layer "F.Cu")
		(net "P5E_CPU0_P1_RX_DN<2>")
	)
	(segment
		(start 338.198206 -393.69238)
		(end 338.718906 -393.69238)
		(width 0.127)
		(layer "F.Cu")
		(net "P5E_CPU0_P1_RX_DN<2>")
	)
	(segment
		(start 337.483958 -388.21868)
		(end 337.246722 -387.863588)
		(width 0.14224)
		(layer "In11.Cu")
		(net "P5E_CPU0_P1_RX_DN<2>")
	)
	(segment
		(start 346.578174 -275.383498)
		(end 346.539058 -275.360638)
		(width 0.1143)
		(layer "In11.Cu")
		(net "P5E_CPU0_P1_RX_DN<2>")
	)
	(segment
		(start 347.052646 -292.39591)
		(end 347.050106 -292.39464)
		(width 0.1143)
		(layer "In11.Cu")
		(net "P5E_CPU0_P1_RX_DN<2>")
	)
	(segment
		(start 347.05417 -285.917132)
		(end 347.052646 -285.916116)
		(width 0.1143)
		(layer "In11.Cu")
		(net "P5E_CPU0_P1_RX_DN<2>")
	)
	(segment
		(start 347.048836 -281.698192)
		(end 347.050106 -281.69743)
		(width 0.1143)
		(layer "In11.Cu")
		(net "P5E_CPU0_P1_RX_DN<2>")
	)
	(segment
		(start 347.052646 -285.916116)
		(end 347.050106 -285.914846)
		(width 0.1143)
		(layer "In11.Cu")
		(net "P5E_CPU0_P1_RX_DN<2>")
	)
	(segment
		(start 347.079824 -281.071828)
		(end 347.046296 -281.052778)
		(width 0.1143)
		(layer "In11.Cu")
		(net "P5E_CPU0_P1_RX_DN<2>")
	)
	(segment
		(start 347.011752 -293.059612)
		(end 347.048074 -293.03853)
		(width 0.1143)
		(layer "In11.Cu")
		(net "P5E_CPU0_P1_RX_DN<2>")
	)
	(segment
		(start 366.591596 -340.140544)
		(end 365.605822 -334.657192)
		(width 0.14224)
		(layer "In11.Cu")
		(net "P5E_CPU0_P1_RX_DN<2>")
	)
	(segment
		(start 339.071966 -393.787376)
		(end 339.072474 -393.786868)
		(width 0.14224)
		(layer "In11.Cu")
		(net "P5E_CPU0_P1_RX_DN<2>")
	)
	(segment
		(start 347.050106 -294.014652)
		(end 347.048836 -294.01389)
		(width 0.1143)
		(layer "In11.Cu")
		(net "P5E_CPU0_P1_RX_DN<2>")
	)
	(segment
		(start 338.300822 -389.194294)
		(end 338.110576 -389.156448)
		(width 0.14224)
		(layer "In11.Cu")
		(net "P5E_CPU0_P1_RX_DN<2>")
	)
	(segment
		(start 347.050106 -290.774628)
		(end 347.048836 -290.773866)
		(width 0.1143)
		(layer "In11.Cu")
		(net "P5E_CPU0_P1_RX_DN<2>")
	)
	(segment
		(start 337.911186 -388.61111)
		(end 337.674204 -388.256526)
		(width 0.14224)
		(layer "In11.Cu")
		(net "P5E_CPU0_P1_RX_DN<2>")
	)
	(segment
		(start 346.25026 -299.343826)
		(end 346.25026 -296.46372)
		(width 0.14224)
		(layer "In11.Cu")
		(net "P5E_CPU0_P1_RX_DN<2>")
	)
	(segment
		(start 347.048836 -291.41801)
		(end 347.050106 -291.417248)
		(width 0.1143)
		(layer "In11.Cu")
		(net "P5E_CPU0_P1_RX_DN<2>")
	)
	(segment
		(start 347.05417 -282.677108)
		(end 347.052646 -282.676092)
		(width 0.1143)
		(layer "In11.Cu")
		(net "P5E_CPU0_P1_RX_DN<2>")
	)
	(segment
		(start 347.050106 -289.797236)
		(end 347.079824 -289.780218)
		(width 0.1143)
		(layer "In11.Cu")
		(net "P5E_CPU0_P1_RX_DN<2>")
	)
	(segment
		(start 346.590366 -280.250392)
		(end 346.579444 -280.244296)
		(width 0.1143)
		(layer "In11.Cu")
		(net "P5E_CPU0_P1_RX_DN<2>")
	)
	(segment
		(start 347.048074 -294.658542)
		(end 347.079824 -294.640254)
		(width 0.1143)
		(layer "In11.Cu")
		(net "P5E_CPU0_P1_RX_DN<2>")
	)
	(segment
		(start 347.048836 -292.393878)
		(end 347.048074 -292.39337)
		(width 0.1143)
		(layer "In11.Cu")
		(net "P5E_CPU0_P1_RX_DN<2>")
	)
	(segment
		(start 347.048836 -289.153854)
		(end 347.048074 -289.153346)
		(width 0.1143)
		(layer "In11.Cu")
		(net "P5E_CPU0_P1_RX_DN<2>")
	)
	(segment
		(start 347.048074 -294.013382)
		(end 347.011752 -293.9923)
		(width 0.1143)
		(layer "In11.Cu")
		(net "P5E_CPU0_P1_RX_DN<2>")
	)
	(segment
		(start 346.25026 -296.435272)
		(end 346.29598 -296.389552)
		(width 0.1143)
		(layer "In11.Cu")
		(net "P5E_CPU0_P1_RX_DN<2>")
	)
	(segment
		(start 350.302322 -309.12689)
		(end 346.25026 -299.343826)
		(width 0.14224)
		(layer "In11.Cu")
		(net "P5E_CPU0_P1_RX_DN<2>")
	)
	(segment
		(start 337.246722 -387.863588)
		(end 337.284568 -387.673342)
		(width 0.14224)
		(layer "In11.Cu")
		(net "P5E_CPU0_P1_RX_DN<2>")
	)
	(segment
		(start 331.91196 -378.230638)
		(end 331.905864 -378.22124)
		(width 0.14224)
		(layer "In11.Cu")
		(net "P5E_CPU0_P1_RX_DN<2>")
	)
	(segment
		(start 347.011752 -291.4396)
		(end 347.048074 -291.418518)
		(width 0.1143)
		(layer "In11.Cu")
		(net "P5E_CPU0_P1_RX_DN<2>")
	)
	(segment
		(start 347.079824 -282.69184)
		(end 347.05417 -282.677108)
		(width 0.1143)
		(layer "In11.Cu")
		(net "P5E_CPU0_P1_RX_DN<2>")
	)
	(segment
		(start 347.046296 -281.052778)
		(end 347.042994 -281.050746)
		(width 0.1143)
		(layer "In11.Cu")
		(net "P5E_CPU0_P1_RX_DN<2>")
	)
	(segment
		(start 349.695516 -366.20069)
		(end 360.358436 -355.53777)
		(width 0.14224)
		(layer "In11.Cu")
		(net "P5E_CPU0_P1_RX_DN<2>")
	)
	(segment
		(start 363.547406 -327.15454)
		(end 357.09479 -319.29197)
		(width 0.14224)
		(layer "In11.Cu")
		(net "P5E_CPU0_P1_RX_DN<2>")
	)
	(segment
		(start 347.050106 -282.674822)
		(end 347.048836 -282.67406)
		(width 0.1143)
		(layer "In11.Cu")
		(net "P5E_CPU0_P1_RX_DN<2>")
	)
	(segment
		(start 347.048074 -277.813516)
		(end 347.011752 -277.792434)
		(width 0.1143)
		(layer "In11.Cu")
		(net "P5E_CPU0_P1_RX_DN<2>")
	)
	(segment
		(start 347.048074 -284.293564)
		(end 347.011752 -284.272482)
		(width 0.1143)
		(layer "In11.Cu")
		(net "P5E_CPU0_P1_RX_DN<2>")
	)
	(segment
		(start 338.877148 -393.22883)
		(end 338.881974 -392.616944)
		(width 0.14224)
		(layer "In11.Cu")
		(net "P5E_CPU0_P1_RX_DN<2>")
	)
	(segment
		(start 346.539058 -279.291542)
		(end 346.608908 -279.250902)
		(width 0.1143)
		(layer "In11.Cu")
		(net "P5E_CPU0_P1_RX_DN<2>")
	)
	(segment
		(start 346.301822 -274.978876)
		(end 346.219018 -274.896072)
		(width 0.1143)
		(layer "In11.Cu")
		(net "P5E_CPU0_P1_RX_DN<2>")
	)
	(segment
		(start 347.050106 -283.317442)
		(end 347.079824 -283.300424)
		(width 0.1143)
		(layer "In11.Cu")
		(net "P5E_CPU0_P1_RX_DN<2>")
	)
	(segment
		(start 347.050106 -281.69743)
		(end 347.079824 -281.680412)
		(width 0.1143)
		(layer "In11.Cu")
		(net "P5E_CPU0_P1_RX_DN<2>")
	)
	(segment
		(start 347.079824 -292.411658)
		(end 347.05417 -292.396926)
		(width 0.1143)
		(layer "In11.Cu")
		(net "P5E_CPU0_P1_RX_DN<2>")
	)
	(segment
		(start 346.219018 -274.896072)
		(end 345.921076 -274.896072)
		(width 0.1143)
		(layer "In11.Cu")
		(net "P5E_CPU0_P1_RX_DN<2>")
	)
	(segment
		(start 346.776294 -280.600404)
		(end 346.776294 -280.573988)
		(width 0.1143)
		(layer "In11.Cu")
		(net "P5E_CPU0_P1_RX_DN<2>")
	)
	(segment
		(start 335.758028 -373.207026)
		(end 344.839798 -369.445286)
		(width 0.14224)
		(layer "In11.Cu")
		(net "P5E_CPU0_P1_RX_DN<2>")
	)
	(segment
		(start 337.284568 -387.673342)
		(end 334.757776 -383.89179)
		(width 0.14224)
		(layer "In11.Cu")
		(net "P5E_CPU0_P1_RX_DN<2>")
	)
	(segment
		(start 365.605822 -334.657192)
		(end 365.605568 -334.657192)
		(width 0.14224)
		(layer "In11.Cu")
		(net "P5E_CPU0_P1_RX_DN<2>")
	)
	(segment
		(start 347.052646 -290.775898)
		(end 347.050106 -290.774628)
		(width 0.1143)
		(layer "In11.Cu")
		(net "P5E_CPU0_P1_RX_DN<2>")
	)
	(segment
		(start 338.110576 -389.156448)
		(end 337.87334 -388.801356)
		(width 0.14224)
		(layer "In11.Cu")
		(net "P5E_CPU0_P1_RX_DN<2>")
	)
	(segment
		(start 347.048074 -292.39337)
		(end 347.011752 -292.372288)
		(width 0.1143)
		(layer "In11.Cu")
		(net "P5E_CPU0_P1_RX_DN<2>")
	)
	(segment
		(start 347.011752 -281.719782)
		(end 347.013276 -281.718766)
		(width 0.1143)
		(layer "In11.Cu")
		(net "P5E_CPU0_P1_RX_DN<2>")
	)
	(segment
		(start 331.918564 -378.240798)
		(end 331.91196 -378.230892)
		(width 0.14224)
		(layer "In11.Cu")
		(net "P5E_CPU0_P1_RX_DN<2>")
	)
	(segment
		(start 347.050106 -284.937454)
		(end 347.079824 -284.920436)
		(width 0.1143)
		(layer "In11.Cu")
		(net "P5E_CPU0_P1_RX_DN<2>")
	)
	(segment
		(start 338.499958 -389.739124)
		(end 338.537804 -389.548878)
		(width 0.14224)
		(layer "In11.Cu")
		(net "P5E_CPU0_P1_RX_DN<2>")
	)
	(segment
		(start 347.079824 -287.551876)
		(end 347.008704 -287.510728)
		(width 0.1143)
		(layer "In11.Cu")
		(net "P5E_CPU0_P1_RX_DN<2>")
	)
	(segment
		(start 347.050106 -285.914846)
		(end 347.048836 -285.914084)
		(width 0.1143)
		(layer "In11.Cu")
		(net "P5E_CPU0_P1_RX_DN<2>")
	)
	(segment
		(start 347.050106 -293.03726)
		(end 347.079824 -293.020242)
		(width 0.1143)
		(layer "In11.Cu")
		(net "P5E_CPU0_P1_RX_DN<2>")
	)
	(segment
		(start 338.92744 -390.132062)
		(end 338.737194 -390.094216)
		(width 0.14224)
		(layer "In11.Cu")
		(net "P5E_CPU0_P1_RX_DN<2>")
	)
	(segment
		(start 347.048074 -290.773358)
		(end 347.011752 -290.752276)
		(width 0.1143)
		(layer "In11.Cu")
		(net "P5E_CPU0_P1_RX_DN<2>")
	)
	(segment
		(start 331.835252 -377.990862)
		(end 331.835252 -377.235466)
		(width 0.14224)
		(layer "In11.Cu")
		(net "P5E_CPU0_P1_RX_DN<2>")
	)
	(segment
		(start 347.050106 -292.39464)
		(end 347.048836 -292.393878)
		(width 0.1143)
		(layer "In11.Cu")
		(net "P5E_CPU0_P1_RX_DN<2>")
	)
	(segment
		(start 347.05417 -289.156902)
		(end 347.052646 -289.155886)
		(width 0.1143)
		(layer "In11.Cu")
		(net "P5E_CPU0_P1_RX_DN<2>")
	)
	(segment
		(start 347.048836 -285.914084)
		(end 347.048074 -285.913576)
		(width 0.1143)
		(layer "In11.Cu")
		(net "P5E_CPU0_P1_RX_DN<2>")
	)
	(segment
		(start 346.76588 -278.947626)
		(end 346.76588 -278.946102)
		(width 0.1143)
		(layer "In11.Cu")
		(net "P5E_CPU0_P1_RX_DN<2>")
	)
	(segment
		(start 347.052646 -284.296104)
		(end 347.050106 -284.294834)
		(width 0.1143)
		(layer "In11.Cu")
		(net "P5E_CPU0_P1_RX_DN<2>")
	)
	(segment
		(start 347.011752 -286.579564)
		(end 347.048074 -286.558482)
		(width 0.1143)
		(layer "In11.Cu")
		(net "P5E_CPU0_P1_RX_DN<2>")
	)
	(segment
		(start 347.05417 -294.016938)
		(end 347.052646 -294.015922)
		(width 0.1143)
		(layer "In11.Cu")
		(net "P5E_CPU0_P1_RX_DN<2>")
	)
	(segment
		(start 347.048836 -284.938216)
		(end 347.050106 -284.937454)
		(width 0.1143)
		(layer "In11.Cu")
		(net "P5E_CPU0_P1_RX_DN<2>")
	)
	(segment
		(start 346.76588 -295.399968)
		(end 346.76588 -295.145968)
		(width 0.1143)
		(layer "In11.Cu")
		(net "P5E_CPU0_P1_RX_DN<2>")
	)
	(segment
		(start 333.535274 -381.085852)
		(end 333.535274 -379.786134)
		(width 0.14224)
		(layer "In11.Cu")
		(net "P5E_CPU0_P1_RX_DN<2>")
	)
	(segment
		(start 347.042994 -281.050746)
		(end 347.03385 -281.045412)
		(width 0.1143)
		(layer "In11.Cu")
		(net "P5E_CPU0_P1_RX_DN<2>")
	)
	(segment
		(start 346.29598 -295.869868)
		(end 346.76588 -295.399968)
		(width 0.1143)
		(layer "In11.Cu")
		(net "P5E_CPU0_P1_RX_DN<2>")
	)
	(segment
		(start 337.674204 -388.256526)
		(end 337.483958 -388.21868)
		(width 0.14224)
		(layer "In11.Cu")
		(net "P5E_CPU0_P1_RX_DN<2>")
	)
	(segment
		(start 347.00972 -278.480774)
		(end 347.048074 -278.458676)
		(width 0.1143)
		(layer "In11.Cu")
		(net "P5E_CPU0_P1_RX_DN<2>")
	)
	(segment
		(start 347.050106 -276.194774)
		(end 347.048836 -276.194012)
		(width 0.1143)
		(layer "In11.Cu")
		(net "P5E_CPU0_P1_RX_DN<2>")
	)
	(segment
		(start 347.048074 -289.153346)
		(end 347.011752 -289.132264)
		(width 0.1143)
		(layer "In11.Cu")
		(net "P5E_CPU0_P1_RX_DN<2>")
	)
	(segment
		(start 347.048836 -289.797998)
		(end 347.050106 -289.797236)
		(width 0.1143)
		(layer "In11.Cu")
		(net "P5E_CPU0_P1_RX_DN<2>")
	)
	(segment
		(start 338.881974 -392.616944)
		(end 339.186012 -392.31316)
		(width 0.14224)
		(layer "In11.Cu")
		(net "P5E_CPU0_P1_RX_DN<2>")
	)
	(segment
		(start 333.308452 -378.957586)
		(end 332.974442 -378.819664)
		(width 0.14224)
		(layer "In11.Cu")
		(net "P5E_CPU0_P1_RX_DN<2>")
	)
	(segment
		(start 347.011752 -284.959806)
		(end 347.048074 -284.938724)
		(width 0.1143)
		(layer "In11.Cu")
		(net "P5E_CPU0_P1_RX_DN<2>")
	)
	(segment
		(start 347.048074 -284.938724)
		(end 347.048836 -284.938216)
		(width 0.1143)
		(layer "In11.Cu")
		(net "P5E_CPU0_P1_RX_DN<2>")
	)
	(segment
		(start 347.079824 -284.311852)
		(end 347.05417 -284.29712)
		(width 0.1143)
		(layer "In11.Cu")
		(net "P5E_CPU0_P1_RX_DN<2>")
	)
	(segment
		(start 346.60586 -275.3995)
		(end 346.578174 -275.383498)
		(width 0.1143)
		(layer "In11.Cu")
		(net "P5E_CPU0_P1_RX_DN<2>")
	)
	(segment
		(start 331.905864 -378.22124)
		(end 331.902054 -378.215652)
		(width 0.14224)
		(layer "In11.Cu")
		(net "P5E_CPU0_P1_RX_DN<2>")
	)
	(segment
		(start 332.31836 -376.069098)
		(end 334.017112 -374.370346)
		(width 0.14224)
		(layer "In11.Cu")
		(net "P5E_CPU0_P1_RX_DN<2>")
	)
	(segment
		(start 339.186012 -390.557004)
		(end 339.185758 -390.557258)
		(width 0.14224)
		(layer "In11.Cu")
		(net "P5E_CPU0_P1_RX_DN<2>")
	)
	(segment
		(start 365.605568 -334.657192)
		(end 364.628938 -329.22337)
		(width 0.14224)
		(layer "In11.Cu")
		(net "P5E_CPU0_P1_RX_DN<2>")
	)
	(segment
		(start 347.048074 -276.838664)
		(end 347.048836 -276.838156)
		(width 0.1143)
		(layer "In11.Cu")
		(net "P5E_CPU0_P1_RX_DN<2>")
	)
	(segment
		(start 339.164422 -390.486646)
		(end 338.92744 -390.132062)
		(width 0.14224)
		(layer "In11.Cu")
		(net "P5E_CPU0_P1_RX_DN<2>")
	)
	(segment
		(start 347.011752 -276.859746)
		(end 347.048074 -276.838664)
		(width 0.1143)
		(layer "In11.Cu")
		(net "P5E_CPU0_P1_RX_DN<2>")
	)
	(segment
		(start 347.079824 -289.171634)
		(end 347.05417 -289.156902)
		(width 0.1143)
		(layer "In11.Cu")
		(net "P5E_CPU0_P1_RX_DN<2>")
	)
	(segment
		(start 347.048836 -276.194012)
		(end 347.048074 -276.193504)
		(width 0.1143)
		(layer "In11.Cu")
		(net "P5E_CPU0_P1_RX_DN<2>")
	)
	(segment
		(start 339.19414 -393.545822)
		(end 338.877148 -393.22883)
		(width 0.14224)
		(layer "In11.Cu")
		(net "P5E_CPU0_P1_RX_DN<2>")
	)
	(segment
		(start 339.186012 -392.31316)
		(end 339.186012 -390.557004)
		(width 0.14224)
		(layer "In11.Cu")
		(net "P5E_CPU0_P1_RX_DN<2>")
	)
	(segment
		(start 346.765626 -275.707094)
		(end 346.76588 -275.706078)
		(width 0.1143)
		(layer "In11.Cu")
		(net "P5E_CPU0_P1_RX_DN<2>")
	)
	(segment
		(start 347.011752 -289.819588)
		(end 347.048074 -289.798506)
		(width 0.1143)
		(layer "In11.Cu")
		(net "P5E_CPU0_P1_RX_DN<2>")
	)
	(segment
		(start 347.079824 -277.831804)
		(end 347.050106 -277.814786)
		(width 0.1143)
		(layer "In11.Cu")
		(net "P5E_CPU0_P1_RX_DN<2>")
	)
	(segment
		(start 347.079824 -294.03167)
		(end 347.05417 -294.016938)
		(width 0.1143)
		(layer "In11.Cu")
		(net "P5E_CPU0_P1_RX_DN<2>")
	)
	(segment
		(start 346.29598 -296.389552)
		(end 346.29598 -295.869868)
		(width 0.1143)
		(layer "In11.Cu")
		(net "P5E_CPU0_P1_RX_DN<2>")
	)
	(segment
		(start 347.011752 -294.679624)
		(end 347.048074 -294.658542)
		(width 0.1143)
		(layer "In11.Cu")
		(net "P5E_CPU0_P1_RX_DN<2>")
	)
	(segment
		(start 347.013276 -281.718766)
		(end 347.048074 -281.6987)
		(width 0.1143)
		(layer "In11.Cu")
		(net "P5E_CPU0_P1_RX_DN<2>")
	)
	(segment
		(start 347.048074 -289.798506)
		(end 347.048836 -289.797998)
		(width 0.1143)
		(layer "In11.Cu")
		(net "P5E_CPU0_P1_RX_DN<2>")
	)
	(segment
		(start 347.079824 -290.791646)
		(end 347.05417 -290.776914)
		(width 0.1143)
		(layer "In11.Cu")
		(net "P5E_CPU0_P1_RX_DN<2>")
	)
	(segment
		(start 347.05417 -284.29712)
		(end 347.052646 -284.296104)
		(width 0.1143)
		(layer "In11.Cu")
		(net "P5E_CPU0_P1_RX_DN<2>")
	)
	(segment
		(start 347.050106 -278.457406)
		(end 347.079824 -278.440388)
		(width 0.1143)
		(layer "In11.Cu")
		(net "P5E_CPU0_P1_RX_DN<2>")
	)
	(segment
		(start 347.050106 -291.417248)
		(end 347.079824 -291.40023)
		(width 0.1143)
		(layer "In11.Cu")
		(net "P5E_CPU0_P1_RX_DN<2>")
	)
	(segment
		(start 347.052646 -289.155886)
		(end 347.050106 -289.154616)
		(width 0.1143)
		(layer "In11.Cu")
		(net "P5E_CPU0_P1_RX_DN<2>")
	)
	(segment
		(start 338.737194 -390.094216)
		(end 338.499958 -389.739124)
		(width 0.14224)
		(layer "In11.Cu")
		(net "P5E_CPU0_P1_RX_DN<2>")
	)
	(segment
		(start 347.008704 -287.510728)
		(end 346.994734 -287.500314)
		(width 0.1143)
		(layer "In11.Cu")
		(net "P5E_CPU0_P1_RX_DN<2>")
	)
	(segment
		(start 347.048836 -277.814024)
		(end 347.048074 -277.813516)
		(width 0.1143)
		(layer "In11.Cu")
		(net "P5E_CPU0_P1_RX_DN<2>")
	)
	(segment
		(start 347.048836 -290.773866)
		(end 347.048074 -290.773358)
		(width 0.1143)
		(layer "In11.Cu")
		(net "P5E_CPU0_P1_RX_DN<2>")
	)
	(segment
		(start 366.591596 -344.788744)
		(end 366.591596 -340.140544)
		(width 0.14224)
		(layer "In11.Cu")
		(net "P5E_CPU0_P1_RX_DN<2>")
	)
	(segment
		(start 347.050106 -277.814786)
		(end 347.048836 -277.814024)
		(width 0.1143)
		(layer "In11.Cu")
		(net "P5E_CPU0_P1_RX_DN<2>")
	)
	(segment
		(start 339.19414 -393.716764)
		(end 339.19414 -393.545822)
		(width 0.14224)
		(layer "In11.Cu")
		(net "P5E_CPU0_P1_RX_DN<2>")
	)
	(segment
		(start 338.718906 -393.69238)
		(end 339.071966 -393.787376)
		(width 0.14224)
		(layer "In11.Cu")
		(net "P5E_CPU0_P1_RX_DN<2>")
	)
	(segment
		(start 339.072474 -393.786868)
		(end 339.19414 -393.716764)
		(width 0.14224)
		(layer "In11.Cu")
		(net "P5E_CPU0_P1_RX_DN<2>")
	)
	(segment
		(start 347.011752 -283.339794)
		(end 347.048074 -283.318712)
		(width 0.1143)
		(layer "In11.Cu")
		(net "P5E_CPU0_P1_RX_DN<2>")
	)
	(segment
		(start 347.050106 -276.837394)
		(end 347.079824 -276.820376)
		(width 0.1143)
		(layer "In11.Cu")
		(net "P5E_CPU0_P1_RX_DN<2>")
	)
	(segment
		(start 347.048836 -278.458168)
		(end 347.050106 -278.457406)
		(width 0.1143)
		(layer "In11.Cu")
		(net "P5E_CPU0_P1_RX_DN<2>")
	)
	(segment
		(start 347.052646 -282.676092)
		(end 347.050106 -282.674822)
		(width 0.1143)
		(layer "In11.Cu")
		(net "P5E_CPU0_P1_RX_DN<2>")
	)
	(segment
		(start 347.048836 -294.01389)
		(end 347.048074 -294.013382)
		(width 0.1143)
		(layer "In11.Cu")
		(net "P5E_CPU0_P1_RX_DN<2>")
	)
	(segment
		(start 347.048074 -293.03853)
		(end 347.048836 -293.038022)
		(width 0.1143)
		(layer "In11.Cu")
		(net "P5E_CPU0_P1_RX_DN<2>")
	)
	(segment
		(start 347.048836 -283.318204)
		(end 347.050106 -283.317442)
		(width 0.1143)
		(layer "In11.Cu")
		(net "P5E_CPU0_P1_RX_DN<2>")
	)
	(segment
		(start 347.052646 -294.015922)
		(end 347.050106 -294.014652)
		(width 0.1143)
		(layer "In11.Cu")
		(net "P5E_CPU0_P1_RX_DN<2>")
	)
	(segment
		(start 347.079824 -276.211792)
		(end 347.050106 -276.194774)
		(width 0.1143)
		(layer "In11.Cu")
		(net "P5E_CPU0_P1_RX_DN<2>")
	)
	(segment
		(start 331.91196 -378.230892)
		(end 331.91196 -378.230638)
		(width 0.14224)
		(layer "In11.Cu")
		(net "P5E_CPU0_P1_RX_DN<2>")
	)
	(segment
		(start 347.05417 -290.776914)
		(end 347.052646 -290.775898)
		(width 0.1143)
		(layer "In11.Cu")
		(net "P5E_CPU0_P1_RX_DN<2>")
	)
	(segment
		(start 347.011752 -288.199576)
		(end 347.081602 -288.158936)
		(width 0.1143)
		(layer "In11.Cu")
		(net "P5E_CPU0_P1_RX_DN<2>")
	)
	(segment
		(start 347.048836 -284.294072)
		(end 347.048074 -284.293564)
		(width 0.1143)
		(layer "In11.Cu")
		(net "P5E_CPU0_P1_RX_DN<2>")
	)
	(segment
		(start 347.050106 -284.294834)
		(end 347.048836 -284.294072)
		(width 0.1143)
		(layer "In11.Cu")
		(net "P5E_CPU0_P1_RX_DN<2>")
	)
	(segment
		(start 347.042232 -276.190202)
		(end 347.038676 -276.187662)
		(width 0.1143)
		(layer "In11.Cu")
		(net "P5E_CPU0_P1_RX_DN<2>")
	)
	(segment
		(start 364.628938 -329.22337)
		(end 363.547406 -327.15454)
		(width 0.14224)
		(layer "In11.Cu")
		(net "P5E_CPU0_P1_RX_DN<2>")
	)
	(segment
		(start 347.050106 -289.154616)
		(end 347.048836 -289.153854)
		(width 0.1143)
		(layer "In11.Cu")
		(net "P5E_CPU0_P1_RX_DN<2>")
	)
	(segment
		(start 346.579444 -280.244296)
		(end 346.53982 -280.221182)
		(width 0.1143)
		(layer "In11.Cu")
		(net "P5E_CPU0_P1_RX_DN<2>")
	)
	(segment
		(start 365.677196 -347.577156)
		(end 366.369092 -345.906852)
		(width 0.14224)
		(layer "In11.Cu")
		(net "P5E_CPU0_P1_RX_DN<2>")
	)
	(segment
		(start 347.048074 -276.193504)
		(end 347.042232 -276.190202)
		(width 0.1143)
		(layer "In11.Cu")
		(net "P5E_CPU0_P1_RX_DN<2>")
	)
	(segment
		(start 337.87334 -388.801356)
		(end 337.911186 -388.61111)
		(width 0.14224)
		(layer "In11.Cu")
		(net "P5E_CPU0_P1_RX_DN<2>")
	)
	(segment
		(start 334.36052 -383.198116)
		(end 333.581248 -381.316738)
		(width 0.14224)
		(layer "In11.Cu")
		(net "P5E_CPU0_P1_RX_DN<2>")
	)
	(segment
		(start 338.537804 -389.548878)
		(end 338.300822 -389.194294)
		(width 0.14224)
		(layer "In11.Cu")
		(net "P5E_CPU0_P1_RX_DN<2>")
	)
	(segment
		(start 347.048074 -291.418518)
		(end 347.048836 -291.41801)
		(width 0.1143)
		(layer "In11.Cu")
		(net "P5E_CPU0_P1_RX_DN<2>")
	)
	(segment
		(start 346.25026 -296.46372)
		(end 346.25026 -296.435272)
		(width 0.1143)
		(layer "In11.Cu")
		(net "P5E_CPU0_P1_RX_DN<2>")
	)
	(segment
		(start 346.76588 -287.053528)
		(end 346.76588 -287.045908)
		(width 0.1143)
		(layer "In11.Cu")
		(net "P5E_CPU0_P1_RX_DN<2>")
	)
	(segment
		(start 347.048074 -278.458676)
		(end 347.048836 -278.458168)
		(width 0.1143)
		(layer "In11.Cu")
		(net "P5E_CPU0_P1_RX_DN<2>")
	)
	(segment
		(start 347.048074 -285.913576)
		(end 347.011752 -285.892494)
		(width 0.1143)
		(layer "In11.Cu")
		(net "P5E_CPU0_P1_RX_DN<2>")
	)
	(segment
		(start 347.048074 -282.673552)
		(end 347.011752 -282.65247)
		(width 0.1143)
		(layer "In11.Cu")
		(net "P5E_CPU0_P1_RX_DN<2>")
	)
	(segment
		(start 347.05417 -292.396926)
		(end 347.052646 -292.39591)
		(width 0.1143)
		(layer "In11.Cu")
		(net "P5E_CPU0_P1_RX_DN<2>")
	)
	(segment
		(start 347.048074 -281.6987)
		(end 347.048836 -281.698192)
		(width 0.1143)
		(layer "In11.Cu")
		(net "P5E_CPU0_P1_RX_DN<2>")
	)
	(segment
		(start 347.048836 -276.838156)
		(end 347.050106 -276.837394)
		(width 0.1143)
		(layer "In11.Cu")
		(net "P5E_CPU0_P1_RX_DN<2>")
	)
	(segment
		(start 347.079824 -285.931864)
		(end 347.05417 -285.917132)
		(width 0.1143)
		(layer "In11.Cu")
		(net "P5E_CPU0_P1_RX_DN<2>")
	)
	(segment
		(start 347.048074 -286.558482)
		(end 347.081602 -286.538924)
		(width 0.1143)
		(layer "In11.Cu")
		(net "P5E_CPU0_P1_RX_DN<2>")
	)
	(segment
		(start 347.048836 -293.038022)
		(end 347.050106 -293.03726)
		(width 0.1143)
		(layer "In11.Cu")
		(net "P5E_CPU0_P1_RX_DN<2>")
	)
	(segment
		(start 347.048836 -282.67406)
		(end 347.048074 -282.673552)
		(width 0.1143)
		(layer "In11.Cu")
		(net "P5E_CPU0_P1_RX_DN<2>")
	)
	(segment
		(start 347.048074 -283.318712)
		(end 347.048836 -283.318204)
		(width 0.1143)
		(layer "In11.Cu")
		(net "P5E_CPU0_P1_RX_DN<2>")
	)
	(segment
		(start 347.038676 -276.187662)
		(end 347.037406 -276.1869)
		(width 0.1143)
		(layer "In11.Cu")
		(net "P5E_CPU0_P1_RX_DN<2>")
	)
	(segment
		(start 357.09479 -319.29197)
		(end 350.302322 -309.12689)
		(width 0.14224)
		(layer "In11.Cu")
		(net "P5E_CPU0_P1_RX_DN<2>")
	)
	(arc
		(start 346.997528 -291.449506)
		(mid 347.004601 -291.444497)
		(end 347.011752 -291.4396)
		(width 0.1143)
		(layer "In11.Cu")
		(net "P5E_CPU0_P1_RX_DN<2>")
	)
	(arc
		(start 346.776294 -280.573988)
		(mid 346.72651 -280.387374)
		(end 346.590366 -280.250392)
		(width 0.1143)
		(layer "In11.Cu")
		(net "P5E_CPU0_P1_RX_DN<2>")
	)
	(arc
		(start 346.995496 -289.120834)
		(mid 346.830829 -288.922227)
		(end 346.76588 -288.672524)
		(width 0.1143)
		(layer "In11.Cu")
		(net "P5E_CPU0_P1_RX_DN<2>")
	)
	(arc
		(start 346.76588 -278.946102)
		(mid 346.83048 -278.683403)
		(end 347.00972 -278.480774)
		(width 0.1143)
		(layer "In11.Cu")
		(net "P5E_CPU0_P1_RX_DN<2>")
	)
	(arc
		(start 347.079824 -281.680412)
		(mid 347.235752 -281.37612)
		(end 347.079824 -281.071828)
		(width 0.1143)
		(layer "In11.Cu")
		(net "P5E_CPU0_P1_RX_DN<2>")
	)
	(arc
		(start 346.539058 -280.220674)
		(mid 346.295731 -279.756108)
		(end 346.539058 -279.291542)
		(width 0.1143)
		(layer "In11.Cu")
		(net "P5E_CPU0_P1_RX_DN<2>")
	)
	(arc
		(start 332.974442 -378.819664)
		(mid 332.921882 -378.803001)
		(end 332.867254 -378.795534)
		(width 0.14224)
		(layer "In11.Cu")
		(net "P5E_CPU0_P1_RX_DN<2>")
	)
	(arc
		(start 346.996512 -281.73045)
		(mid 347.004088 -281.725054)
		(end 347.011752 -281.719782)
		(width 0.1143)
		(layer "In11.Cu")
		(net "P5E_CPU0_P1_RX_DN<2>")
	)
	(arc
		(start 333.581248 -381.316738)
		(mid 333.546917 -381.203555)
		(end 333.535274 -381.085852)
		(width 0.14224)
		(layer "In11.Cu")
		(net "P5E_CPU0_P1_RX_DN<2>")
	)
	(arc
		(start 347.011752 -292.372288)
		(mid 347.004602 -292.36739)
		(end 346.997528 -292.362382)
		(width 0.1143)
		(layer "In11.Cu")
		(net "P5E_CPU0_P1_RX_DN<2>")
	)
	(arc
		(start 339.185758 -390.557258)
		(mid 339.180356 -390.520357)
		(end 339.164422 -390.486646)
		(width 0.14224)
		(layer "In11.Cu")
		(net "P5E_CPU0_P1_RX_DN<2>")
	)
	(arc
		(start 346.997528 -292.362382)
		(mid 346.770145 -291.905944)
		(end 346.997528 -291.449506)
		(width 0.1143)
		(layer "In11.Cu")
		(net "P5E_CPU0_P1_RX_DN<2>")
	)
	(arc
		(start 347.011752 -290.752276)
		(mid 347.003574 -290.746633)
		(end 346.995496 -290.740846)
		(width 0.1143)
		(layer "In11.Cu")
		(net "P5E_CPU0_P1_RX_DN<2>")
	)
	(arc
		(start 331.902054 -378.215652)
		(mid 331.852247 -378.108137)
		(end 331.835252 -377.990862)
		(width 0.14224)
		(layer "In11.Cu")
		(net "P5E_CPU0_P1_RX_DN<2>")
	)
	(arc
		(start 346.997528 -277.782528)
		(mid 346.770145 -277.32609)
		(end 346.997528 -276.869652)
		(width 0.1143)
		(layer "In11.Cu")
		(net "P5E_CPU0_P1_RX_DN<2>")
	)
	(arc
		(start 347.011752 -277.792434)
		(mid 347.004603 -277.787534)
		(end 346.997528 -277.782528)
		(width 0.1143)
		(layer "In11.Cu")
		(net "P5E_CPU0_P1_RX_DN<2>")
	)
	(arc
		(start 347.079824 -278.440388)
		(mid 347.235752 -278.136096)
		(end 347.079824 -277.831804)
		(width 0.1143)
		(layer "In11.Cu")
		(net "P5E_CPU0_P1_RX_DN<2>")
	)
	(arc
		(start 344.839798 -369.445286)
		(mid 347.427433 -368.062102)
		(end 349.695516 -366.20069)
		(width 0.14224)
		(layer "In11.Cu")
		(net "P5E_CPU0_P1_RX_DN<2>")
	)
	(arc
		(start 347.011752 -289.132264)
		(mid 347.003574 -289.126621)
		(end 346.995496 -289.120834)
		(width 0.1143)
		(layer "In11.Cu")
		(net "P5E_CPU0_P1_RX_DN<2>")
	)
	(arc
		(start 347.079824 -283.300424)
		(mid 347.235752 -282.996132)
		(end 347.079824 -282.69184)
		(width 0.1143)
		(layer "In11.Cu")
		(net "P5E_CPU0_P1_RX_DN<2>")
	)
	(arc
		(start 347.011752 -282.65247)
		(mid 347.004088 -282.647199)
		(end 346.996512 -282.641802)
		(width 0.1143)
		(layer "In11.Cu")
		(net "P5E_CPU0_P1_RX_DN<2>")
	)
	(arc
		(start 346.305632 -275.001736)
		(mid 346.303609 -274.990326)
		(end 346.301822 -274.978876)
		(width 0.1143)
		(layer "In11.Cu")
		(net "P5E_CPU0_P1_RX_DN<2>")
	)
	(arc
		(start 347.011752 -285.892494)
		(mid 347.003574 -285.886851)
		(end 346.995496 -285.881064)
		(width 0.1143)
		(layer "In11.Cu")
		(net "P5E_CPU0_P1_RX_DN<2>")
	)
	(arc
		(start 347.037406 -276.1869)
		(mid 346.844402 -275.979333)
		(end 346.765626 -275.707094)
		(width 0.1143)
		(layer "In11.Cu")
		(net "P5E_CPU0_P1_RX_DN<2>")
	)
	(arc
		(start 347.079824 -276.820376)
		(mid 347.235752 -276.516084)
		(end 347.079824 -276.211792)
		(width 0.1143)
		(layer "In11.Cu")
		(net "P5E_CPU0_P1_RX_DN<2>")
	)
	(arc
		(start 332.235302 -378.578364)
		(mid 332.154771 -378.519095)
		(end 332.082648 -378.44984)
		(width 0.14224)
		(layer "In11.Cu")
		(net "P5E_CPU0_P1_RX_DN<2>")
	)
	(arc
		(start 331.835252 -377.235466)
		(mid 331.960811 -376.604239)
		(end 332.31836 -376.069098)
		(width 0.14224)
		(layer "In11.Cu")
		(net "P5E_CPU0_P1_RX_DN<2>")
	)
	(arc
		(start 333.467456 -379.339602)
		(mid 333.449127 -379.188862)
		(end 333.399892 -379.045216)
		(width 0.14224)
		(layer "In11.Cu")
		(net "P5E_CPU0_P1_RX_DN<2>")
	)
	(arc
		(start 347.079824 -289.780218)
		(mid 347.235752 -289.475926)
		(end 347.079824 -289.171634)
		(width 0.1143)
		(layer "In11.Cu")
		(net "P5E_CPU0_P1_RX_DN<2>")
	)
	(arc
		(start 347.081602 -286.538924)
		(mid 347.195009 -286.406035)
		(end 347.23578 -286.236156)
		(width 0.1143)
		(layer "In11.Cu")
		(net "P5E_CPU0_P1_RX_DN<2>")
	)
	(arc
		(start 347.079824 -294.640254)
		(mid 347.235752 -294.335962)
		(end 347.079824 -294.03167)
		(width 0.1143)
		(layer "In11.Cu")
		(net "P5E_CPU0_P1_RX_DN<2>")
	)
	(arc
		(start 346.995496 -285.881064)
		(mid 346.772612 -285.42615)
		(end 346.995496 -284.971236)
		(width 0.1143)
		(layer "In11.Cu")
		(net "P5E_CPU0_P1_RX_DN<2>")
	)
	(arc
		(start 347.236034 -287.856168)
		(mid 347.19464 -287.68518)
		(end 347.079824 -287.551876)
		(width 0.1143)
		(layer "In11.Cu")
		(net "P5E_CPU0_P1_RX_DN<2>")
	)
	(arc
		(start 346.53982 -280.221182)
		(mid 346.539439 -280.220928)
		(end 346.539058 -280.220674)
		(width 0.1143)
		(layer "In11.Cu")
		(net "P5E_CPU0_P1_RX_DN<2>")
	)
	(arc
		(start 333.399892 -379.045216)
		(mid 333.362406 -378.992813)
		(end 333.308452 -378.957586)
		(width 0.14224)
		(layer "In11.Cu")
		(net "P5E_CPU0_P1_RX_DN<2>")
	)
	(arc
		(start 360.358436 -355.53777)
		(mid 363.409878 -351.819412)
		(end 365.677196 -347.577156)
		(width 0.14224)
		(layer "In11.Cu")
		(net "P5E_CPU0_P1_RX_DN<2>")
	)
	(arc
		(start 346.76588 -288.672524)
		(mid 346.82955 -288.405236)
		(end 347.011752 -288.199576)
		(width 0.1143)
		(layer "In11.Cu")
		(net "P5E_CPU0_P1_RX_DN<2>")
	)
	(arc
		(start 346.539058 -275.360638)
		(mid 346.387071 -275.20413)
		(end 346.305632 -275.001736)
		(width 0.1143)
		(layer "In11.Cu")
		(net "P5E_CPU0_P1_RX_DN<2>")
	)
	(arc
		(start 346.994734 -287.500314)
		(mid 346.826458 -287.304511)
		(end 346.76588 -287.053528)
		(width 0.1143)
		(layer "In11.Cu")
		(net "P5E_CPU0_P1_RX_DN<2>")
	)
	(arc
		(start 346.995496 -293.98087)
		(mid 346.772612 -293.525956)
		(end 346.995496 -293.071042)
		(width 0.1143)
		(layer "In11.Cu")
		(net "P5E_CPU0_P1_RX_DN<2>")
	)
	(arc
		(start 333.501238 -379.556518)
		(mid 333.476828 -379.449231)
		(end 333.467456 -379.339602)
		(width 0.14224)
		(layer "In11.Cu")
		(net "P5E_CPU0_P1_RX_DN<2>")
	)
	(arc
		(start 346.996512 -284.261814)
		(mid 346.771341 -283.806138)
		(end 346.996512 -283.350462)
		(width 0.1143)
		(layer "In11.Cu")
		(net "P5E_CPU0_P1_RX_DN<2>")
	)
	(arc
		(start 347.081602 -288.158936)
		(mid 347.195174 -288.02609)
		(end 347.236034 -287.856168)
		(width 0.1143)
		(layer "In11.Cu")
		(net "P5E_CPU0_P1_RX_DN<2>")
	)
	(arc
		(start 347.011752 -284.272482)
		(mid 347.004088 -284.267211)
		(end 346.996512 -284.261814)
		(width 0.1143)
		(layer "In11.Cu")
		(net "P5E_CPU0_P1_RX_DN<2>")
	)
	(arc
		(start 347.03385 -281.045412)
		(mid 346.845281 -280.857516)
		(end 346.776294 -280.600404)
		(width 0.1143)
		(layer "In11.Cu")
		(net "P5E_CPU0_P1_RX_DN<2>")
	)
	(arc
		(start 347.23578 -286.236156)
		(mid 347.194525 -286.065185)
		(end 347.079824 -285.931864)
		(width 0.1143)
		(layer "In11.Cu")
		(net "P5E_CPU0_P1_RX_DN<2>")
	)
	(arc
		(start 334.017112 -374.370346)
		(mid 334.830279 -373.702948)
		(end 335.758028 -373.207026)
		(width 0.14224)
		(layer "In11.Cu")
		(net "P5E_CPU0_P1_RX_DN<2>")
	)
	(arc
		(start 346.995496 -289.831018)
		(mid 347.003574 -289.825232)
		(end 347.011752 -289.819588)
		(width 0.1143)
		(layer "In11.Cu")
		(net "P5E_CPU0_P1_RX_DN<2>")
	)
	(arc
		(start 334.426306 -383.337562)
		(mid 334.391749 -383.268624)
		(end 334.36052 -383.198116)
		(width 0.14224)
		(layer "In11.Cu")
		(net "P5E_CPU0_P1_RX_DN<2>")
	)
	(arc
		(start 346.76588 -295.139364)
		(mid 346.830752 -294.889622)
		(end 346.995496 -294.691054)
		(width 0.1143)
		(layer "In11.Cu")
		(net "P5E_CPU0_P1_RX_DN<2>")
	)
	(arc
		(start 346.995496 -284.971236)
		(mid 347.003574 -284.96545)
		(end 347.011752 -284.959806)
		(width 0.1143)
		(layer "In11.Cu")
		(net "P5E_CPU0_P1_RX_DN<2>")
	)
	(arc
		(start 332.867254 -378.795534)
		(mid 332.777383 -378.787324)
		(end 332.688692 -378.770642)
		(width 0.14224)
		(layer "In11.Cu")
		(net "P5E_CPU0_P1_RX_DN<2>")
	)
	(arc
		(start 333.535274 -379.786134)
		(mid 333.526682 -379.670077)
		(end 333.501238 -379.556518)
		(width 0.14224)
		(layer "In11.Cu")
		(net "P5E_CPU0_P1_RX_DN<2>")
	)
	(arc
		(start 332.082648 -378.44984)
		(mid 331.996551 -378.348502)
		(end 331.918564 -378.240798)
		(width 0.14224)
		(layer "In11.Cu")
		(net "P5E_CPU0_P1_RX_DN<2>")
	)
	(arc
		(start 334.757776 -383.89179)
		(mid 334.585078 -383.618841)
		(end 334.426306 -383.337562)
		(width 0.14224)
		(layer "In11.Cu")
		(net "P5E_CPU0_P1_RX_DN<2>")
	)
	(arc
		(start 346.76588 -287.045908)
		(mid 346.831116 -286.782317)
		(end 347.011752 -286.579564)
		(width 0.1143)
		(layer "In11.Cu")
		(net "P5E_CPU0_P1_RX_DN<2>")
	)
	(arc
		(start 347.079824 -284.920436)
		(mid 347.235752 -284.616144)
		(end 347.079824 -284.311852)
		(width 0.1143)
		(layer "In11.Cu")
		(net "P5E_CPU0_P1_RX_DN<2>")
	)
	(arc
		(start 346.996512 -282.641802)
		(mid 346.771341 -282.186126)
		(end 346.996512 -281.73045)
		(width 0.1143)
		(layer "In11.Cu")
		(net "P5E_CPU0_P1_RX_DN<2>")
	)
	(arc
		(start 346.995496 -290.740846)
		(mid 346.772612 -290.285932)
		(end 346.995496 -289.831018)
		(width 0.1143)
		(layer "In11.Cu")
		(net "P5E_CPU0_P1_RX_DN<2>")
	)
	(arc
		(start 332.688692 -378.770642)
		(mid 332.454041 -378.693266)
		(end 332.235302 -378.578364)
		(width 0.14224)
		(layer "In11.Cu")
		(net "P5E_CPU0_P1_RX_DN<2>")
	)
	(arc
		(start 347.079824 -291.40023)
		(mid 347.235752 -291.095938)
		(end 347.079824 -290.791646)
		(width 0.1143)
		(layer "In11.Cu")
		(net "P5E_CPU0_P1_RX_DN<2>")
	)
	(arc
		(start 347.079824 -293.020242)
		(mid 347.235752 -292.71595)
		(end 347.079824 -292.411658)
		(width 0.1143)
		(layer "In11.Cu")
		(net "P5E_CPU0_P1_RX_DN<2>")
	)
	(arc
		(start 346.76588 -275.706078)
		(mid 346.719185 -275.535399)
		(end 346.60586 -275.3995)
		(width 0.1143)
		(layer "In11.Cu")
		(net "P5E_CPU0_P1_RX_DN<2>")
	)
	(arc
		(start 366.369092 -345.906852)
		(mid 366.535438 -345.35876)
		(end 366.591596 -344.788744)
		(width 0.14224)
		(layer "In11.Cu")
		(net "P5E_CPU0_P1_RX_DN<2>")
	)
	(arc
		(start 346.997528 -276.869652)
		(mid 347.004602 -276.864645)
		(end 347.011752 -276.859746)
		(width 0.1143)
		(layer "In11.Cu")
		(net "P5E_CPU0_P1_RX_DN<2>")
	)
	(arc
		(start 346.996512 -283.350462)
		(mid 347.004088 -283.345066)
		(end 347.011752 -283.339794)
		(width 0.1143)
		(layer "In11.Cu")
		(net "P5E_CPU0_P1_RX_DN<2>")
	)
	(arc
		(start 346.76588 -295.145968)
		(mid 346.76587 -295.142666)
		(end 346.76588 -295.139364)
		(width 0.1143)
		(layer "In11.Cu")
		(net "P5E_CPU0_P1_RX_DN<2>")
	)
	(arc
		(start 346.995496 -293.071042)
		(mid 347.003574 -293.065256)
		(end 347.011752 -293.059612)
		(width 0.1143)
		(layer "In11.Cu")
		(net "P5E_CPU0_P1_RX_DN<2>")
	)
	(arc
		(start 347.011752 -293.9923)
		(mid 347.003574 -293.986657)
		(end 346.995496 -293.98087)
		(width 0.1143)
		(layer "In11.Cu")
		(net "P5E_CPU0_P1_RX_DN<2>")
	)
	(arc
		(start 346.995496 -294.691054)
		(mid 347.003574 -294.685268)
		(end 347.011752 -294.679624)
		(width 0.1143)
		(layer "In11.Cu")
		(net "P5E_CPU0_P1_RX_DN<2>")
	)
	(arc
		(start 346.608908 -279.250902)
		(mid 346.724344 -279.118382)
		(end 346.76588 -278.947626)
		(width 0.1143)
		(layer "In11.Cu")
		(net "P5E_CPU0_P1_RX_DN<2>")
	)
	(segment
		(start 336.998056 -393.69238)
		(end 337.518756 -393.69238)
		(width 0.127)
		(layer "F.Cu")
		(net "P5E_CPU0_P1_RX_DN<1>")
	)
	(segment
		(start 346.387928 -277.870158)
		(end 345.921076 -278.136096)
		(width 0.12954)
		(layer "F.Cu")
		(net "P5E_CPU0_P1_RX_DN<1>")
	)
	(segment
		(start 332.939136 -383.609596)
		(end 332.637638 -383.308098)
		(width 0.14224)
		(layer "In11.Cu")
		(net "P5E_CPU0_P1_RX_DN<1>")
	)
	(segment
		(start 346.069158 -286.581342)
		(end 346.07119 -286.579818)
		(width 0.1143)
		(layer "In11.Cu")
		(net "P5E_CPU0_P1_RX_DN<1>")
	)
	(segment
		(start 345.63558 -279.270206)
		(end 345.637104 -279.26919)
		(width 0.1143)
		(layer "In11.Cu")
		(net "P5E_CPU0_P1_RX_DN<1>")
	)
	(segment
		(start 346.108274 -286.558482)
		(end 346.140786 -286.539686)
		(width 0.1143)
		(layer "In11.Cu")
		(net "P5E_CPU0_P1_RX_DN<1>")
	)
	(segment
		(start 345.310206 -296.435272)
		(end 345.355926 -296.389552)
		(width 0.1143)
		(layer "In11.Cu")
		(net "P5E_CPU0_P1_RX_DN<1>")
	)
	(segment
		(start 345.637104 -280.243026)
		(end 345.63558 -280.24201)
		(width 0.1143)
		(layer "In11.Cu")
		(net "P5E_CPU0_P1_RX_DN<1>")
	)
	(segment
		(start 345.599004 -279.291542)
		(end 345.63558 -279.270206)
		(width 0.1143)
		(layer "In11.Cu")
		(net "P5E_CPU0_P1_RX_DN<1>")
	)
	(segment
		(start 346.069158 -289.821366)
		(end 346.138754 -289.780726)
		(width 0.1143)
		(layer "In11.Cu")
		(net "P5E_CPU0_P1_RX_DN<1>")
	)
	(segment
		(start 331.344016 -382.208532)
		(end 331.344016 -382.014476)
		(width 0.14224)
		(layer "In11.Cu")
		(net "P5E_CPU0_P1_RX_DN<1>")
	)
	(segment
		(start 332.637638 -383.308098)
		(end 332.443582 -383.308098)
		(width 0.14224)
		(layer "In11.Cu")
		(net "P5E_CPU0_P1_RX_DN<1>")
	)
	(segment
		(start 346.138754 -284.311344)
		(end 346.069158 -284.270704)
		(width 0.1143)
		(layer "In11.Cu")
		(net "P5E_CPU0_P1_RX_DN<1>")
	)
	(segment
		(start 331.839824 -382.510538)
		(end 331.646022 -382.510538)
		(width 0.14224)
		(layer "In11.Cu")
		(net "P5E_CPU0_P1_RX_DN<1>")
	)
	(segment
		(start 337.677252 -393.22883)
		(end 337.682078 -392.616944)
		(width 0.14224)
		(layer "In11.Cu")
		(net "P5E_CPU0_P1_RX_DN<1>")
	)
	(segment
		(start 346.138754 -282.691332)
		(end 346.069158 -282.650692)
		(width 0.1143)
		(layer "In11.Cu")
		(net "P5E_CPU0_P1_RX_DN<1>")
	)
	(segment
		(start 349.500698 -309.627778)
		(end 345.310206 -299.510704)
		(width 0.14224)
		(layer "In11.Cu")
		(net "P5E_CPU0_P1_RX_DN<1>")
	)
	(segment
		(start 337.518756 -393.69238)
		(end 337.87207 -393.787376)
		(width 0.14224)
		(layer "In11.Cu")
		(net "P5E_CPU0_P1_RX_DN<1>")
	)
	(segment
		(start 337.682078 -392.616944)
		(end 337.986116 -392.31316)
		(width 0.14224)
		(layer "In11.Cu")
		(net "P5E_CPU0_P1_RX_DN<1>")
	)
	(segment
		(start 330.546456 -381.410972)
		(end 330.546456 -381.216916)
		(width 0.14224)
		(layer "In11.Cu")
		(net "P5E_CPU0_P1_RX_DN<1>")
	)
	(segment
		(start 337.986116 -392.31316)
		(end 337.986116 -390.815322)
		(width 0.14224)
		(layer "In11.Cu")
		(net "P5E_CPU0_P1_RX_DN<1>")
	)
	(segment
		(start 337.872578 -393.786868)
		(end 337.994244 -393.716764)
		(width 0.14224)
		(layer "In11.Cu")
		(net "P5E_CPU0_P1_RX_DN<1>")
	)
	(segment
		(start 345.638882 -279.268174)
		(end 345.640152 -279.267412)
		(width 0.1143)
		(layer "In11.Cu")
		(net "P5E_CPU0_P1_RX_DN<1>")
	)
	(segment
		(start 330.848462 -381.712978)
		(end 330.546456 -381.410972)
		(width 0.14224)
		(layer "In11.Cu")
		(net "P5E_CPU0_P1_RX_DN<1>")
	)
	(segment
		(start 346.069158 -281.72156)
		(end 346.138754 -281.68092)
		(width 0.1143)
		(layer "In11.Cu")
		(net "P5E_CPU0_P1_RX_DN<1>")
	)
	(segment
		(start 345.634564 -280.241502)
		(end 345.632024 -280.239978)
		(width 0.1143)
		(layer "In11.Cu")
		(net "P5E_CPU0_P1_RX_DN<1>")
	)
	(segment
		(start 346.138754 -287.551368)
		(end 346.071698 -287.512252)
		(width 0.1143)
		(layer "In11.Cu")
		(net "P5E_CPU0_P1_RX_DN<1>")
	)
	(segment
		(start 345.825826 -295.399968)
		(end 345.825826 -295.145968)
		(width 0.1143)
		(layer "In11.Cu")
		(net "P5E_CPU0_P1_RX_DN<1>")
	)
	(segment
		(start 346.069158 -278.481536)
		(end 346.138754 -278.440896)
		(width 0.1143)
		(layer "In11.Cu")
		(net "P5E_CPU0_P1_RX_DN<1>")
	)
	(segment
		(start 337.87207 -393.787376)
		(end 337.872578 -393.786868)
		(width 0.14224)
		(layer "In11.Cu")
		(net "P5E_CPU0_P1_RX_DN<1>")
	)
	(segment
		(start 346.138754 -292.41115)
		(end 346.069158 -292.37051)
		(width 0.1143)
		(layer "In11.Cu")
		(net "P5E_CPU0_P1_RX_DN<1>")
	)
	(segment
		(start 363.725968 -329.513946)
		(end 362.796074 -327.735184)
		(width 0.14224)
		(layer "In11.Cu")
		(net "P5E_CPU0_P1_RX_DN<1>")
	)
	(segment
		(start 346.108274 -288.178494)
		(end 346.140786 -288.159698)
		(width 0.1143)
		(layer "In11.Cu")
		(net "P5E_CPU0_P1_RX_DN<1>")
	)
	(segment
		(start 345.640152 -279.267412)
		(end 345.66987 -279.250394)
		(width 0.1143)
		(layer "In11.Cu")
		(net "P5E_CPU0_P1_RX_DN<1>")
	)
	(segment
		(start 346.07119 -286.579818)
		(end 346.108274 -286.558482)
		(width 0.1143)
		(layer "In11.Cu")
		(net "P5E_CPU0_P1_RX_DN<1>")
	)
	(segment
		(start 345.355926 -296.389552)
		(end 345.355926 -295.869868)
		(width 0.1143)
		(layer "In11.Cu")
		(net "P5E_CPU0_P1_RX_DN<1>")
	)
	(segment
		(start 345.632024 -280.239978)
		(end 345.6305 -280.238962)
		(width 0.1143)
		(layer "In11.Cu")
		(net "P5E_CPU0_P1_RX_DN<1>")
	)
	(segment
		(start 345.66987 -280.261822)
		(end 345.638882 -280.244042)
		(width 0.1143)
		(layer "In11.Cu")
		(net "P5E_CPU0_P1_RX_DN<1>")
	)
	(segment
		(start 330.290424 -376.700288)
		(end 333.225648 -373.765064)
		(width 0.14224)
		(layer "In11.Cu")
		(net "P5E_CPU0_P1_RX_DN<1>")
	)
	(segment
		(start 345.63558 -280.24201)
		(end 345.634564 -280.241502)
		(width 0.1143)
		(layer "In11.Cu")
		(net "P5E_CPU0_P1_RX_DN<1>")
	)
	(segment
		(start 335.339944 -372.352316)
		(end 344.647774 -368.496596)
		(width 0.14224)
		(layer "In11.Cu")
		(net "P5E_CPU0_P1_RX_DN<1>")
	)
	(segment
		(start 362.796074 -327.735184)
		(end 356.356158 -319.887854)
		(width 0.14224)
		(layer "In11.Cu")
		(net "P5E_CPU0_P1_RX_DN<1>")
	)
	(segment
		(start 346.069158 -291.441378)
		(end 346.138754 -291.400738)
		(width 0.1143)
		(layer "In11.Cu")
		(net "P5E_CPU0_P1_RX_DN<1>")
	)
	(segment
		(start 331.042264 -381.712978)
		(end 330.848462 -381.712978)
		(width 0.14224)
		(layer "In11.Cu")
		(net "P5E_CPU0_P1_RX_DN<1>")
	)
	(segment
		(start 346.219018 -278.136096)
		(end 345.921076 -278.136096)
		(width 0.1143)
		(layer "In11.Cu")
		(net "P5E_CPU0_P1_RX_DN<1>")
	)
	(segment
		(start 345.6305 -280.238962)
		(end 345.599004 -280.220674)
		(width 0.1143)
		(layer "In11.Cu")
		(net "P5E_CPU0_P1_RX_DN<1>")
	)
	(segment
		(start 346.138754 -281.07132)
		(end 346.069158 -281.03068)
		(width 0.1143)
		(layer "In11.Cu")
		(net "P5E_CPU0_P1_RX_DN<1>")
	)
	(segment
		(start 331.646022 -382.510538)
		(end 331.344016 -382.208532)
		(width 0.14224)
		(layer "In11.Cu")
		(net "P5E_CPU0_P1_RX_DN<1>")
	)
	(segment
		(start 332.141576 -382.812036)
		(end 331.839824 -382.510538)
		(width 0.14224)
		(layer "In11.Cu")
		(net "P5E_CPU0_P1_RX_DN<1>")
	)
	(segment
		(start 330.118212 -380.619254)
		(end 330.118212 -377.116086)
		(width 0.14224)
		(layer "In11.Cu")
		(net "P5E_CPU0_P1_RX_DN<1>")
	)
	(segment
		(start 345.63812 -279.268682)
		(end 345.638882 -279.268174)
		(width 0.1143)
		(layer "In11.Cu")
		(net "P5E_CPU0_P1_RX_DN<1>")
	)
	(segment
		(start 346.138754 -294.031162)
		(end 346.069158 -293.990522)
		(width 0.1143)
		(layer "In11.Cu")
		(net "P5E_CPU0_P1_RX_DN<1>")
	)
	(segment
		(start 345.310206 -296.46372)
		(end 345.310206 -296.435272)
		(width 0.1143)
		(layer "In11.Cu")
		(net "P5E_CPU0_P1_RX_DN<1>")
	)
	(segment
		(start 331.344016 -382.014476)
		(end 331.042264 -381.712978)
		(width 0.14224)
		(layer "In11.Cu")
		(net "P5E_CPU0_P1_RX_DN<1>")
	)
	(segment
		(start 337.96478 -390.744964)
		(end 337.96478 -390.74471)
		(width 0.14224)
		(layer "In11.Cu")
		(net "P5E_CPU0_P1_RX_DN<1>")
	)
	(segment
		(start 346.069158 -294.681402)
		(end 346.138754 -294.640762)
		(width 0.1143)
		(layer "In11.Cu")
		(net "P5E_CPU0_P1_RX_DN<1>")
	)
	(segment
		(start 346.069158 -283.341572)
		(end 346.138754 -283.300932)
		(width 0.1143)
		(layer "In11.Cu")
		(net "P5E_CPU0_P1_RX_DN<1>")
	)
	(segment
		(start 346.069158 -293.06139)
		(end 346.138754 -293.02075)
		(width 0.1143)
		(layer "In11.Cu")
		(net "P5E_CPU0_P1_RX_DN<1>")
	)
	(segment
		(start 348.851474 -365.687864)
		(end 359.986326 -354.553012)
		(width 0.14224)
		(layer "In11.Cu")
		(net "P5E_CPU0_P1_RX_DN<1>")
	)
	(segment
		(start 332.141576 -383.006092)
		(end 332.141576 -382.812036)
		(width 0.14224)
		(layer "In11.Cu")
		(net "P5E_CPU0_P1_RX_DN<1>")
	)
	(segment
		(start 346.069158 -288.201354)
		(end 346.108274 -288.178494)
		(width 0.1143)
		(layer "In11.Cu")
		(net "P5E_CPU0_P1_RX_DN<1>")
	)
	(segment
		(start 337.96478 -390.74471)
		(end 334.45323 -385.459478)
		(width 0.14224)
		(layer "In11.Cu")
		(net "P5E_CPU0_P1_RX_DN<1>")
	)
	(segment
		(start 365.630206 -343.821766)
		(end 365.630206 -340.105492)
		(width 0.14224)
		(layer "In11.Cu")
		(net "P5E_CPU0_P1_RX_DN<1>")
	)
	(segment
		(start 365.630206 -340.105492)
		(end 363.725968 -329.513946)
		(width 0.14224)
		(layer "In11.Cu")
		(net "P5E_CPU0_P1_RX_DN<1>")
	)
	(segment
		(start 345.638882 -280.244042)
		(end 345.63812 -280.243534)
		(width 0.1143)
		(layer "In11.Cu")
		(net "P5E_CPU0_P1_RX_DN<1>")
	)
	(segment
		(start 337.994244 -393.545822)
		(end 337.677252 -393.22883)
		(width 0.14224)
		(layer "In11.Cu")
		(net "P5E_CPU0_P1_RX_DN<1>")
	)
	(segment
		(start 332.443582 -383.308098)
		(end 332.141576 -383.006092)
		(width 0.14224)
		(layer "In11.Cu")
		(net "P5E_CPU0_P1_RX_DN<1>")
	)
	(segment
		(start 330.546456 -381.216916)
		(end 330.2381 -380.908814)
		(width 0.14224)
		(layer "In11.Cu")
		(net "P5E_CPU0_P1_RX_DN<1>")
	)
	(segment
		(start 346.069158 -284.961584)
		(end 346.138754 -284.920944)
		(width 0.1143)
		(layer "In11.Cu")
		(net "P5E_CPU0_P1_RX_DN<1>")
	)
	(segment
		(start 345.355926 -295.869868)
		(end 345.825826 -295.399968)
		(width 0.1143)
		(layer "In11.Cu")
		(net "P5E_CPU0_P1_RX_DN<1>")
	)
	(segment
		(start 346.138754 -289.171126)
		(end 346.069158 -289.130486)
		(width 0.1143)
		(layer "In11.Cu")
		(net "P5E_CPU0_P1_RX_DN<1>")
	)
	(segment
		(start 346.138754 -285.931356)
		(end 346.069158 -285.890716)
		(width 0.1143)
		(layer "In11.Cu")
		(net "P5E_CPU0_P1_RX_DN<1>")
	)
	(segment
		(start 345.63812 -280.243534)
		(end 345.637104 -280.243026)
		(width 0.1143)
		(layer "In11.Cu")
		(net "P5E_CPU0_P1_RX_DN<1>")
	)
	(segment
		(start 337.994244 -393.716764)
		(end 337.994244 -393.545822)
		(width 0.14224)
		(layer "In11.Cu")
		(net "P5E_CPU0_P1_RX_DN<1>")
	)
	(segment
		(start 364.279942 -348.127066)
		(end 365.230156 -345.832684)
		(width 0.14224)
		(layer "In11.Cu")
		(net "P5E_CPU0_P1_RX_DN<1>")
	)
	(segment
		(start 345.310206 -299.510704)
		(end 345.310206 -296.46372)
		(width 0.14224)
		(layer "In11.Cu")
		(net "P5E_CPU0_P1_RX_DN<1>")
	)
	(segment
		(start 345.637104 -279.26919)
		(end 345.63812 -279.268682)
		(width 0.1143)
		(layer "In11.Cu")
		(net "P5E_CPU0_P1_RX_DN<1>")
	)
	(segment
		(start 346.138754 -290.791138)
		(end 346.069158 -290.750498)
		(width 0.1143)
		(layer "In11.Cu")
		(net "P5E_CPU0_P1_RX_DN<1>")
	)
	(segment
		(start 346.288868 -278.205946)
		(end 346.219018 -278.136096)
		(width 0.1143)
		(layer "In11.Cu")
		(net "P5E_CPU0_P1_RX_DN<1>")
	)
	(segment
		(start 356.356158 -319.887854)
		(end 349.500698 -309.627778)
		(width 0.14224)
		(layer "In11.Cu")
		(net "P5E_CPU0_P1_RX_DN<1>")
	)
	(arc
		(start 334.45323 -385.459478)
		(mid 333.74223 -384.496848)
		(end 332.939136 -383.609596)
		(width 0.14224)
		(layer "In11.Cu")
		(net "P5E_CPU0_P1_RX_DN<1>")
	)
	(arc
		(start 359.986326 -354.553012)
		(mid 362.449595 -351.551488)
		(end 364.279942 -348.127066)
		(width 0.14224)
		(layer "In11.Cu")
		(net "P5E_CPU0_P1_RX_DN<1>")
	)
	(arc
		(start 330.118212 -377.116086)
		(mid 330.162972 -376.891064)
		(end 330.290424 -376.700288)
		(width 0.14224)
		(layer "In11.Cu")
		(net "P5E_CPU0_P1_RX_DN<1>")
	)
	(arc
		(start 345.599004 -280.220674)
		(mid 345.355677 -279.756108)
		(end 345.599004 -279.291542)
		(width 0.1143)
		(layer "In11.Cu")
		(net "P5E_CPU0_P1_RX_DN<1>")
	)
	(arc
		(start 346.138754 -289.780726)
		(mid 346.295731 -289.475926)
		(end 346.138754 -289.171126)
		(width 0.1143)
		(layer "In11.Cu")
		(net "P5E_CPU0_P1_RX_DN<1>")
	)
	(arc
		(start 346.138754 -294.640762)
		(mid 346.295731 -294.335962)
		(end 346.138754 -294.031162)
		(width 0.1143)
		(layer "In11.Cu")
		(net "P5E_CPU0_P1_RX_DN<1>")
	)
	(arc
		(start 346.138754 -283.300932)
		(mid 346.295731 -282.996132)
		(end 346.138754 -282.691332)
		(width 0.1143)
		(layer "In11.Cu")
		(net "P5E_CPU0_P1_RX_DN<1>")
	)
	(arc
		(start 346.295726 -287.856168)
		(mid 346.254177 -287.684746)
		(end 346.138754 -287.551368)
		(width 0.1143)
		(layer "In11.Cu")
		(net "P5E_CPU0_P1_RX_DN<1>")
	)
	(arc
		(start 346.140786 -286.539686)
		(mid 346.254715 -286.406539)
		(end 346.295726 -286.236156)
		(width 0.1143)
		(layer "In11.Cu")
		(net "P5E_CPU0_P1_RX_DN<1>")
	)
	(arc
		(start 346.069158 -284.270704)
		(mid 345.825831 -283.806138)
		(end 346.069158 -283.341572)
		(width 0.1143)
		(layer "In11.Cu")
		(net "P5E_CPU0_P1_RX_DN<1>")
	)
	(arc
		(start 346.138754 -284.920944)
		(mid 346.295731 -284.616144)
		(end 346.138754 -284.311344)
		(width 0.1143)
		(layer "In11.Cu")
		(net "P5E_CPU0_P1_RX_DN<1>")
	)
	(arc
		(start 333.225648 -373.765064)
		(mid 334.213225 -372.954571)
		(end 335.339944 -372.352316)
		(width 0.14224)
		(layer "In11.Cu")
		(net "P5E_CPU0_P1_RX_DN<1>")
	)
	(arc
		(start 345.825826 -287.045908)
		(mid 345.890341 -286.783689)
		(end 346.069158 -286.581342)
		(width 0.1143)
		(layer "In11.Cu")
		(net "P5E_CPU0_P1_RX_DN<1>")
	)
	(arc
		(start 346.069158 -292.37051)
		(mid 345.825831 -291.905944)
		(end 346.069158 -291.441378)
		(width 0.1143)
		(layer "In11.Cu")
		(net "P5E_CPU0_P1_RX_DN<1>")
	)
	(arc
		(start 346.138754 -278.440896)
		(mid 346.236519 -278.33792)
		(end 346.288868 -278.205946)
		(width 0.1143)
		(layer "In11.Cu")
		(net "P5E_CPU0_P1_RX_DN<1>")
	)
	(arc
		(start 346.138754 -291.400738)
		(mid 346.295731 -291.095938)
		(end 346.138754 -290.791138)
		(width 0.1143)
		(layer "In11.Cu")
		(net "P5E_CPU0_P1_RX_DN<1>")
	)
	(arc
		(start 346.069158 -289.130486)
		(mid 345.825831 -288.66592)
		(end 346.069158 -288.201354)
		(width 0.1143)
		(layer "In11.Cu")
		(net "P5E_CPU0_P1_RX_DN<1>")
	)
	(arc
		(start 346.069158 -285.890716)
		(mid 345.825831 -285.42615)
		(end 346.069158 -284.961584)
		(width 0.1143)
		(layer "In11.Cu")
		(net "P5E_CPU0_P1_RX_DN<1>")
	)
	(arc
		(start 365.230156 -345.832684)
		(mid 365.529178 -344.846921)
		(end 365.630206 -343.821766)
		(width 0.14224)
		(layer "In11.Cu")
		(net "P5E_CPU0_P1_RX_DN<1>")
	)
	(arc
		(start 346.069158 -293.990522)
		(mid 345.825831 -293.525956)
		(end 346.069158 -293.06139)
		(width 0.1143)
		(layer "In11.Cu")
		(net "P5E_CPU0_P1_RX_DN<1>")
	)
	(arc
		(start 330.2381 -380.908814)
		(mid 330.149307 -380.775976)
		(end 330.118212 -380.619254)
		(width 0.14224)
		(layer "In11.Cu")
		(net "P5E_CPU0_P1_RX_DN<1>")
	)
	(arc
		(start 346.138754 -281.68092)
		(mid 346.295731 -281.37612)
		(end 346.138754 -281.07132)
		(width 0.1143)
		(layer "In11.Cu")
		(net "P5E_CPU0_P1_RX_DN<1>")
	)
	(arc
		(start 345.825826 -295.145968)
		(mid 345.890341 -294.883749)
		(end 346.069158 -294.681402)
		(width 0.1143)
		(layer "In11.Cu")
		(net "P5E_CPU0_P1_RX_DN<1>")
	)
	(arc
		(start 337.986116 -390.815322)
		(mid 337.980667 -390.778559)
		(end 337.96478 -390.744964)
		(width 0.14224)
		(layer "In11.Cu")
		(net "P5E_CPU0_P1_RX_DN<1>")
	)
	(arc
		(start 346.071698 -287.512252)
		(mid 345.891046 -287.309507)
		(end 345.825826 -287.045908)
		(width 0.1143)
		(layer "In11.Cu")
		(net "P5E_CPU0_P1_RX_DN<1>")
	)
	(arc
		(start 346.138754 -293.02075)
		(mid 346.295731 -292.71595)
		(end 346.138754 -292.41115)
		(width 0.1143)
		(layer "In11.Cu")
		(net "P5E_CPU0_P1_RX_DN<1>")
	)
	(arc
		(start 346.069158 -290.750498)
		(mid 345.825831 -290.285932)
		(end 346.069158 -289.821366)
		(width 0.1143)
		(layer "In11.Cu")
		(net "P5E_CPU0_P1_RX_DN<1>")
	)
	(arc
		(start 345.825826 -278.946102)
		(mid 345.890341 -278.683883)
		(end 346.069158 -278.481536)
		(width 0.1143)
		(layer "In11.Cu")
		(net "P5E_CPU0_P1_RX_DN<1>")
	)
	(arc
		(start 346.069158 -281.03068)
		(mid 345.890345 -280.82833)
		(end 345.825826 -280.566114)
		(width 0.1143)
		(layer "In11.Cu")
		(net "P5E_CPU0_P1_RX_DN<1>")
	)
	(arc
		(start 345.66987 -279.250394)
		(mid 345.784546 -279.11706)
		(end 345.825826 -278.946102)
		(width 0.1143)
		(layer "In11.Cu")
		(net "P5E_CPU0_P1_RX_DN<1>")
	)
	(arc
		(start 346.295726 -286.236156)
		(mid 346.254177 -286.064734)
		(end 346.138754 -285.931356)
		(width 0.1143)
		(layer "In11.Cu")
		(net "P5E_CPU0_P1_RX_DN<1>")
	)
	(arc
		(start 345.825826 -280.566114)
		(mid 345.784571 -280.395143)
		(end 345.66987 -280.261822)
		(width 0.1143)
		(layer "In11.Cu")
		(net "P5E_CPU0_P1_RX_DN<1>")
	)
	(arc
		(start 346.140786 -288.159698)
		(mid 346.254715 -288.026551)
		(end 346.295726 -287.856168)
		(width 0.1143)
		(layer "In11.Cu")
		(net "P5E_CPU0_P1_RX_DN<1>")
	)
	(arc
		(start 346.069158 -282.650692)
		(mid 345.825831 -282.186126)
		(end 346.069158 -281.72156)
		(width 0.1143)
		(layer "In11.Cu")
		(net "P5E_CPU0_P1_RX_DN<1>")
	)
	(arc
		(start 344.647774 -368.496596)
		(mid 346.887918 -367.299213)
		(end 348.851474 -365.687864)
		(width 0.14224)
		(layer "In11.Cu")
		(net "P5E_CPU0_P1_RX_DN<1>")
	)
	(segment
		(start 353.798124 -393.69238)
		(end 354.318824 -393.69238)
		(width 0.127)
		(layer "F.Cu")
		(net "P5E_CPU0_P1_RX_DN<15>")
	)
	(segment
		(start 357.197914 -275.44014)
		(end 356.731062 -275.706078)
		(width 0.12954)
		(layer "F.Cu")
		(net "P5E_CPU0_P1_RX_DN<15>")
	)
	(segment
		(start 357.81488 -389.871458)
		(end 360.38282 -389.871458)
		(width 0.14224)
		(layer "In11.Cu")
		(net "P5E_CPU0_P1_RX_DN<15>")
	)
	(segment
		(start 357.356918 -276.17547)
		(end 357.356156 -276.174962)
		(width 0.1143)
		(layer "In11.Cu")
		(net "P5E_CPU0_P1_RX_DN<15>")
	)
	(segment
		(start 361.065826 -389.460486)
		(end 361.06608 -389.460486)
		(width 0.14224)
		(layer "In11.Cu")
		(net "P5E_CPU0_P1_RX_DN<15>")
	)
	(segment
		(start 354.794312 -393.716764)
		(end 354.794312 -393.117578)
		(width 0.14224)
		(layer "In11.Cu")
		(net "P5E_CPU0_P1_RX_DN<15>")
	)
	(segment
		(start 358.309926 -277.802848)
		(end 358.289098 -277.790656)
		(width 0.1143)
		(layer "In11.Cu")
		(net "P5E_CPU0_P1_RX_DN<15>")
	)
	(segment
		(start 361.194604 -388.039356)
		(end 361.194604 -387.612636)
		(width 0.14224)
		(layer "In11.Cu")
		(net "P5E_CPU0_P1_RX_DN<15>")
	)
	(segment
		(start 357.387906 -276.19325)
		(end 357.385874 -276.192234)
		(width 0.1143)
		(layer "In11.Cu")
		(net "P5E_CPU0_P1_RX_DN<15>")
	)
	(segment
		(start 361.152694 -303.53381)
		(end 359.408984 -299.32376)
		(width 0.14224)
		(layer "In11.Cu")
		(net "P5E_CPU0_P1_RX_DN<15>")
	)
	(segment
		(start 359.0544 -279.263094)
		(end 359.0544 -278.59228)
		(width 0.14224)
		(layer "In11.Cu")
		(net "P5E_CPU0_P1_RX_DN<15>")
	)
	(segment
		(start 354.794312 -393.117578)
		(end 355.61651 -392.29538)
		(width 0.14224)
		(layer "In11.Cu")
		(net "P5E_CPU0_P1_RX_DN<15>")
	)
	(segment
		(start 379.10008 -339.048344)
		(end 377.38177 -329.483212)
		(width 0.14224)
		(layer "In11.Cu")
		(net "P5E_CPU0_P1_RX_DN<15>")
	)
	(segment
		(start 358.32542 -277.811738)
		(end 358.309926 -277.802848)
		(width 0.1143)
		(layer "In11.Cu")
		(net "P5E_CPU0_P1_RX_DN<15>")
	)
	(segment
		(start 358.357678 -277.830534)
		(end 358.328468 -277.813516)
		(width 0.1143)
		(layer "In11.Cu")
		(net "P5E_CPU0_P1_RX_DN<15>")
	)
	(segment
		(start 357.848154 -276.997414)
		(end 357.8479 -276.997414)
		(width 0.1143)
		(layer "In11.Cu")
		(net "P5E_CPU0_P1_RX_DN<15>")
	)
	(segment
		(start 357.385874 -276.192234)
		(end 357.385112 -276.191726)
		(width 0.1143)
		(layer "In11.Cu")
		(net "P5E_CPU0_P1_RX_DN<15>")
	)
	(segment
		(start 361.331764 -387.475476)
		(end 361.331764 -387.048756)
		(width 0.14224)
		(layer "In11.Cu")
		(net "P5E_CPU0_P1_RX_DN<15>")
	)
	(segment
		(start 358.798876 -278.336756)
		(end 358.77881 -278.31669)
		(width 0.1143)
		(layer "In11.Cu")
		(net "P5E_CPU0_P1_RX_DN<15>")
	)
	(segment
		(start 357.858822 -277.004018)
		(end 357.85806 -277.00351)
		(width 0.1143)
		(layer "In11.Cu")
		(net "P5E_CPU0_P1_RX_DN<15>")
	)
	(segment
		(start 366.228884 -311.130696)
		(end 361.152694 -303.53381)
		(width 0.14224)
		(layer "In11.Cu")
		(net "P5E_CPU0_P1_RX_DN<15>")
	)
	(segment
		(start 357.029004 -275.706078)
		(end 356.731062 -275.706078)
		(width 0.1143)
		(layer "In11.Cu")
		(net "P5E_CPU0_P1_RX_DN<15>")
	)
	(segment
		(start 361.331764 -388.932674)
		(end 361.331764 -388.176516)
		(width 0.14224)
		(layer "In11.Cu")
		(net "P5E_CPU0_P1_RX_DN<15>")
	)
	(segment
		(start 379.10008 -350.27743)
		(end 379.10008 -339.048344)
		(width 0.14224)
		(layer "In11.Cu")
		(net "P5E_CPU0_P1_RX_DN<15>")
	)
	(segment
		(start 357.860092 -277.00478)
		(end 357.858822 -277.004018)
		(width 0.1143)
		(layer "In11.Cu")
		(net "P5E_CPU0_P1_RX_DN<15>")
	)
	(segment
		(start 357.111808 -275.788882)
		(end 357.029004 -275.706078)
		(width 0.1143)
		(layer "In11.Cu")
		(net "P5E_CPU0_P1_RX_DN<15>")
	)
	(segment
		(start 359.288588 -299.008292)
		(end 359.146856 -295.342056)
		(width 0.14224)
		(layer "In11.Cu")
		(net "P5E_CPU0_P1_RX_DN<15>")
	)
	(segment
		(start 357.3907 -276.194774)
		(end 357.387906 -276.19325)
		(width 0.1143)
		(layer "In11.Cu")
		(net "P5E_CPU0_P1_RX_DN<15>")
	)
	(segment
		(start 361.331764 -386.347716)
		(end 361.331764 -385.388358)
		(width 0.14224)
		(layer "In11.Cu")
		(net "P5E_CPU0_P1_RX_DN<15>")
	)
	(segment
		(start 366.142016 -369.675664)
		(end 371.40769 -364.40999)
		(width 0.14224)
		(layer "In11.Cu")
		(net "P5E_CPU0_P1_RX_DN<15>")
	)
	(segment
		(start 359.408984 -299.32376)
		(end 359.288588 -299.008292)
		(width 0.14224)
		(layer "In11.Cu")
		(net "P5E_CPU0_P1_RX_DN<15>")
	)
	(segment
		(start 358.77881 -278.251666)
		(end 358.357678 -277.830534)
		(width 0.1143)
		(layer "In11.Cu")
		(net "P5E_CPU0_P1_RX_DN<15>")
	)
	(segment
		(start 359.0544 -278.59228)
		(end 358.798876 -278.336756)
		(width 0.14224)
		(layer "In11.Cu")
		(net "P5E_CPU0_P1_RX_DN<15>")
	)
	(segment
		(start 357.88981 -277.021798)
		(end 357.862632 -277.00605)
		(width 0.1143)
		(layer "In11.Cu")
		(net "P5E_CPU0_P1_RX_DN<15>")
	)
	(segment
		(start 376.809254 -326.295512)
		(end 373.53875 -320.03746)
		(width 0.14224)
		(layer "In11.Cu")
		(net "P5E_CPU0_P1_RX_DN<15>")
	)
	(segment
		(start 373.53875 -320.03746)
		(end 366.228884 -311.130696)
		(width 0.14224)
		(layer "In11.Cu")
		(net "P5E_CPU0_P1_RX_DN<15>")
	)
	(segment
		(start 376.244612 -357.17099)
		(end 379.10008 -350.27743)
		(width 0.14224)
		(layer "In11.Cu")
		(net "P5E_CPU0_P1_RX_DN<15>")
	)
	(segment
		(start 361.331764 -387.048756)
		(end 361.194604 -386.911596)
		(width 0.14224)
		(layer "In11.Cu")
		(net "P5E_CPU0_P1_RX_DN<15>")
	)
	(segment
		(start 361.331764 -384.687318)
		(end 361.331764 -384.573526)
		(width 0.14224)
		(layer "In11.Cu")
		(net "P5E_CPU0_P1_RX_DN<15>")
	)
	(segment
		(start 357.862632 -277.00605)
		(end 357.860092 -277.00478)
		(width 0.1143)
		(layer "In11.Cu")
		(net "P5E_CPU0_P1_RX_DN<15>")
	)
	(segment
		(start 358.77881 -278.31669)
		(end 358.77881 -278.251666)
		(width 0.1143)
		(layer "In11.Cu")
		(net "P5E_CPU0_P1_RX_DN<15>")
	)
	(segment
		(start 358.328214 -277.813516)
		(end 358.326944 -277.812754)
		(width 0.1143)
		(layer "In11.Cu")
		(net "P5E_CPU0_P1_RX_DN<15>")
	)
	(segment
		(start 357.85806 -277.00351)
		(end 357.848154 -276.997414)
		(width 0.1143)
		(layer "In11.Cu")
		(net "P5E_CPU0_P1_RX_DN<15>")
	)
	(segment
		(start 354.672138 -393.787376)
		(end 354.672646 -393.786868)
		(width 0.14224)
		(layer "In11.Cu")
		(net "P5E_CPU0_P1_RX_DN<15>")
	)
	(segment
		(start 357.356156 -276.174962)
		(end 357.349806 -276.171152)
		(width 0.1143)
		(layer "In11.Cu")
		(net "P5E_CPU0_P1_RX_DN<15>")
	)
	(segment
		(start 377.381516 -329.483212)
		(end 376.809254 -326.295512)
		(width 0.14224)
		(layer "In11.Cu")
		(net "P5E_CPU0_P1_RX_DN<15>")
	)
	(segment
		(start 354.672646 -393.786868)
		(end 354.673408 -393.78636)
		(width 0.14224)
		(layer "In11.Cu")
		(net "P5E_CPU0_P1_RX_DN<15>")
	)
	(segment
		(start 361.194604 -384.824478)
		(end 361.331764 -384.687318)
		(width 0.14224)
		(layer "In11.Cu")
		(net "P5E_CPU0_P1_RX_DN<15>")
	)
	(segment
		(start 358.328468 -277.813516)
		(end 358.328214 -277.813516)
		(width 0.1143)
		(layer "In11.Cu")
		(net "P5E_CPU0_P1_RX_DN<15>")
	)
	(segment
		(start 361.194604 -387.612636)
		(end 361.331764 -387.475476)
		(width 0.14224)
		(layer "In11.Cu")
		(net "P5E_CPU0_P1_RX_DN<15>")
	)
	(segment
		(start 356.537514 -391.172954)
		(end 357.18115 -390.21004)
		(width 0.14224)
		(layer "In11.Cu")
		(net "P5E_CPU0_P1_RX_DN<15>")
	)
	(segment
		(start 361.331764 -385.388358)
		(end 361.194604 -385.251198)
		(width 0.14224)
		(layer "In11.Cu")
		(net "P5E_CPU0_P1_RX_DN<15>")
	)
	(segment
		(start 362.013246 -380.898908)
		(end 362.013246 -377.804934)
		(width 0.14224)
		(layer "In11.Cu")
		(net "P5E_CPU0_P1_RX_DN<15>")
	)
	(segment
		(start 360.612436 -389.795766)
		(end 361.065826 -389.460486)
		(width 0.14224)
		(layer "In11.Cu")
		(net "P5E_CPU0_P1_RX_DN<15>")
	)
	(segment
		(start 361.331764 -388.176516)
		(end 361.194604 -388.039356)
		(width 0.14224)
		(layer "In11.Cu")
		(net "P5E_CPU0_P1_RX_DN<15>")
	)
	(segment
		(start 361.194604 -386.911596)
		(end 361.194604 -386.484876)
		(width 0.14224)
		(layer "In11.Cu")
		(net "P5E_CPU0_P1_RX_DN<15>")
	)
	(segment
		(start 361.467908 -382.215136)
		(end 362.013246 -380.898908)
		(width 0.14224)
		(layer "In11.Cu")
		(net "P5E_CPU0_P1_RX_DN<15>")
	)
	(segment
		(start 358.326944 -277.812754)
		(end 358.32542 -277.811738)
		(width 0.1143)
		(layer "In11.Cu")
		(net "P5E_CPU0_P1_RX_DN<15>")
	)
	(segment
		(start 357.385112 -276.191726)
		(end 357.356918 -276.17547)
		(width 0.1143)
		(layer "In11.Cu")
		(net "P5E_CPU0_P1_RX_DN<15>")
	)
	(segment
		(start 361.34167 -384.410458)
		(end 361.34167 -382.851152)
		(width 0.14224)
		(layer "In11.Cu")
		(net "P5E_CPU0_P1_RX_DN<15>")
	)
	(segment
		(start 359.146856 -295.342056)
		(end 359.0544 -279.263094)
		(width 0.14224)
		(layer "In11.Cu")
		(net "P5E_CPU0_P1_RX_DN<15>")
	)
	(segment
		(start 354.318824 -393.69238)
		(end 354.672138 -393.787376)
		(width 0.14224)
		(layer "In11.Cu")
		(net "P5E_CPU0_P1_RX_DN<15>")
	)
	(segment
		(start 377.38177 -329.483212)
		(end 377.381516 -329.483212)
		(width 0.14224)
		(layer "In11.Cu")
		(net "P5E_CPU0_P1_RX_DN<15>")
	)
	(segment
		(start 361.34167 -382.851152)
		(end 361.467908 -382.215136)
		(width 0.14224)
		(layer "In11.Cu")
		(net "P5E_CPU0_P1_RX_DN<15>")
	)
	(segment
		(start 361.194604 -385.251198)
		(end 361.194604 -384.824478)
		(width 0.14224)
		(layer "In11.Cu")
		(net "P5E_CPU0_P1_RX_DN<15>")
	)
	(segment
		(start 354.673408 -393.78636)
		(end 354.794312 -393.716764)
		(width 0.14224)
		(layer "In11.Cu")
		(net "P5E_CPU0_P1_RX_DN<15>")
	)
	(segment
		(start 361.194604 -386.484876)
		(end 361.331764 -386.347716)
		(width 0.14224)
		(layer "In11.Cu")
		(net "P5E_CPU0_P1_RX_DN<15>")
	)
	(segment
		(start 361.993434 -377.360434)
		(end 362.043472 -376.73915)
		(width 0.14224)
		(layer "In11.Cu")
		(net "P5E_CPU0_P1_RX_DN<15>")
	)
	(arc
		(start 358.045766 -277.32609)
		(mid 358.004511 -277.155119)
		(end 357.88981 -277.021798)
		(width 0.1143)
		(layer "In11.Cu")
		(net "P5E_CPU0_P1_RX_DN<15>")
	)
	(arc
		(start 357.115618 -275.811742)
		(mid 357.113595 -275.800332)
		(end 357.111808 -275.788882)
		(width 0.1143)
		(layer "In11.Cu")
		(net "P5E_CPU0_P1_RX_DN<15>")
	)
	(arc
		(start 362.043472 -376.73915)
		(mid 362.058768 -376.638323)
		(end 362.087668 -376.540522)
		(width 0.14224)
		(layer "In11.Cu")
		(net "P5E_CPU0_P1_RX_DN<15>")
	)
	(arc
		(start 357.18115 -390.21004)
		(mid 357.455614 -389.961373)
		(end 357.81488 -389.871458)
		(width 0.14224)
		(layer "In11.Cu")
		(net "P5E_CPU0_P1_RX_DN<15>")
	)
	(arc
		(start 357.349044 -276.170644)
		(mid 357.197057 -276.014136)
		(end 357.115618 -275.811742)
		(width 0.1143)
		(layer "In11.Cu")
		(net "P5E_CPU0_P1_RX_DN<15>")
	)
	(arc
		(start 361.331764 -384.573526)
		(mid 361.334222 -384.491841)
		(end 361.34167 -384.410458)
		(width 0.14224)
		(layer "In11.Cu")
		(net "P5E_CPU0_P1_RX_DN<15>")
	)
	(arc
		(start 357.8479 -276.997414)
		(mid 357.647811 -276.791926)
		(end 357.57485 -276.51456)
		(width 0.1143)
		(layer "In11.Cu")
		(net "P5E_CPU0_P1_RX_DN<15>")
	)
	(arc
		(start 357.57485 -276.51456)
		(mid 357.525529 -276.33004)
		(end 357.3907 -276.194774)
		(width 0.1143)
		(layer "In11.Cu")
		(net "P5E_CPU0_P1_RX_DN<15>")
	)
	(arc
		(start 362.013246 -377.804934)
		(mid 362.010815 -377.742913)
		(end 362.003848 -377.681236)
		(width 0.14224)
		(layer "In11.Cu")
		(net "P5E_CPU0_P1_RX_DN<15>")
	)
	(arc
		(start 358.289098 -277.790656)
		(mid 358.110285 -277.588306)
		(end 358.045766 -277.32609)
		(width 0.1143)
		(layer "In11.Cu")
		(net "P5E_CPU0_P1_RX_DN<15>")
	)
	(arc
		(start 355.61651 -392.29538)
		(mid 356.104578 -391.756786)
		(end 356.537514 -391.172954)
		(width 0.14224)
		(layer "In11.Cu")
		(net "P5E_CPU0_P1_RX_DN<15>")
	)
	(arc
		(start 361.06608 -389.460486)
		(mid 361.261677 -389.228154)
		(end 361.331764 -388.932674)
		(width 0.14224)
		(layer "In11.Cu")
		(net "P5E_CPU0_P1_RX_DN<15>")
	)
	(arc
		(start 371.40769 -364.40999)
		(mid 374.182643 -361.02869)
		(end 376.244612 -357.17099)
		(width 0.14224)
		(layer "In11.Cu")
		(net "P5E_CPU0_P1_RX_DN<15>")
	)
	(arc
		(start 362.087668 -376.540522)
		(mid 363.767809 -372.989325)
		(end 366.040924 -369.785138)
		(width 0.14224)
		(layer "In11.Cu")
		(net "P5E_CPU0_P1_RX_DN<15>")
	)
	(arc
		(start 360.38282 -389.871458)
		(mid 360.503704 -389.852045)
		(end 360.612436 -389.795766)
		(width 0.14224)
		(layer "In11.Cu")
		(net "P5E_CPU0_P1_RX_DN<15>")
	)
	(arc
		(start 362.003848 -377.681236)
		(mid 361.989481 -377.521133)
		(end 361.993434 -377.360434)
		(width 0.14224)
		(layer "In11.Cu")
		(net "P5E_CPU0_P1_RX_DN<15>")
	)
	(arc
		(start 357.349806 -276.171152)
		(mid 357.349425 -276.170898)
		(end 357.349044 -276.170644)
		(width 0.1143)
		(layer "In11.Cu")
		(net "P5E_CPU0_P1_RX_DN<15>")
	)
	(arc
		(start 366.040924 -369.785138)
		(mid 366.090365 -369.72938)
		(end 366.142016 -369.675664)
		(width 0.14224)
		(layer "In11.Cu")
		(net "P5E_CPU0_P1_RX_DN<15>")
	)
	(segment
		(start 352.598228 -393.69238)
		(end 353.118928 -393.69238)
		(width 0.127)
		(layer "F.Cu")
		(net "P5E_CPU0_P1_RX_DN<14>")
	)
	(segment
		(start 357.197914 -277.060152)
		(end 356.731062 -277.32609)
		(width 0.12954)
		(layer "F.Cu")
		(net "P5E_CPU0_P1_RX_DN<14>")
	)
	(segment
		(start 372.723664 -320.514218)
		(end 365.478314 -311.68594)
		(width 0.14224)
		(layer "In11.Cu")
		(net "P5E_CPU0_P1_RX_DN<14>")
	)
	(segment
		(start 357.856028 -278.622252)
		(end 357.851456 -278.619204)
		(width 0.1143)
		(layer "In11.Cu")
		(net "P5E_CPU0_P1_RX_DN<14>")
	)
	(segment
		(start 360.210608 -303.802796)
		(end 358.000046 -298.465748)
		(width 0.14224)
		(layer "In11.Cu")
		(net "P5E_CPU0_P1_RX_DN<14>")
	)
	(segment
		(start 358.515412 -292.72992)
		(end 358.515412 -292.702742)
		(width 0.1143)
		(layer "In11.Cu")
		(net "P5E_CPU0_P1_RX_DN<14>")
	)
	(segment
		(start 361.95254 -373.461788)
		(end 362.177838 -373.099076)
		(width 0.14224)
		(layer "In11.Cu")
		(net "P5E_CPU0_P1_RX_DN<14>")
	)
	(segment
		(start 357.851456 -278.619204)
		(end 357.773732 -278.569674)
		(width 0.1143)
		(layer "In11.Cu")
		(net "P5E_CPU0_P1_RX_DN<14>")
	)
	(segment
		(start 357.857298 -278.623014)
		(end 357.856028 -278.622252)
		(width 0.1143)
		(layer "In11.Cu")
		(net "P5E_CPU0_P1_RX_DN<14>")
	)
	(segment
		(start 358.328214 -289.798506)
		(end 358.358694 -289.780726)
		(width 0.1143)
		(layer "In11.Cu")
		(net "P5E_CPU0_P1_RX_DN<14>")
	)
	(segment
		(start 358.289098 -286.581342)
		(end 358.328214 -286.558482)
		(width 0.1143)
		(layer "In11.Cu")
		(net "P5E_CPU0_P1_RX_DN<14>")
	)
	(segment
		(start 357.575866 -278.194008)
		(end 357.575866 -278.136096)
		(width 0.1143)
		(layer "In11.Cu")
		(net "P5E_CPU0_P1_RX_DN<14>")
	)
	(segment
		(start 358.515666 -286.236664)
		(end 358.515666 -286.236156)
		(width 0.1143)
		(layer "In11.Cu")
		(net "P5E_CPU0_P1_RX_DN<14>")
	)
	(segment
		(start 357.860092 -278.624792)
		(end 357.858822 -278.62403)
		(width 0.1143)
		(layer "In11.Cu")
		(net "P5E_CPU0_P1_RX_DN<14>")
	)
	(segment
		(start 362.177838 -373.099076)
		(end 362.366814 -373.05488)
		(width 0.14224)
		(layer "In11.Cu")
		(net "P5E_CPU0_P1_RX_DN<14>")
	)
	(segment
		(start 357.864156 -278.627078)
		(end 357.862632 -278.626062)
		(width 0.1143)
		(layer "In11.Cu")
		(net "P5E_CPU0_P1_RX_DN<14>")
	)
	(segment
		(start 358.000046 -295.6687)
		(end 358.045766 -295.62298)
		(width 0.1143)
		(layer "In11.Cu")
		(net "P5E_CPU0_P1_RX_DN<14>")
	)
	(segment
		(start 358.000046 -295.697148)
		(end 358.000046 -295.6687)
		(width 0.1143)
		(layer "In11.Cu")
		(net "P5E_CPU0_P1_RX_DN<14>")
	)
	(segment
		(start 358.358694 -279.451308)
		(end 358.328214 -279.433528)
		(width 0.1143)
		(layer "In11.Cu")
		(net "P5E_CPU0_P1_RX_DN<14>")
	)
	(segment
		(start 358.000046 -298.465748)
		(end 358.000046 -295.697148)
		(width 0.14224)
		(layer "In11.Cu")
		(net "P5E_CPU0_P1_RX_DN<14>")
	)
	(segment
		(start 358.358694 -289.171126)
		(end 358.328214 -289.153346)
		(width 0.1143)
		(layer "In11.Cu")
		(net "P5E_CPU0_P1_RX_DN<14>")
	)
	(segment
		(start 378.1552 -339.132672)
		(end 375.903744 -326.599042)
		(width 0.14224)
		(layer "In11.Cu")
		(net "P5E_CPU0_P1_RX_DN<14>")
	)
	(segment
		(start 358.358694 -287.551368)
		(end 358.291638 -287.512252)
		(width 0.1143)
		(layer "In11.Cu")
		(net "P5E_CPU0_P1_RX_DN<14>")
	)
	(segment
		(start 363.143038 -371.545612)
		(end 363.368336 -371.1829)
		(width 0.14224)
		(layer "In11.Cu")
		(net "P5E_CPU0_P1_RX_DN<14>")
	)
	(segment
		(start 358.328214 -294.013382)
		(end 358.32796 -294.013382)
		(width 0.1143)
		(layer "In11.Cu")
		(net "P5E_CPU0_P1_RX_DN<14>")
	)
	(segment
		(start 353.472496 -393.786868)
		(end 353.594162 -393.716764)
		(width 0.14224)
		(layer "In11.Cu")
		(net "P5E_CPU0_P1_RX_DN<14>")
	)
	(segment
		(start 358.358694 -282.691332)
		(end 358.289098 -282.650692)
		(width 0.1143)
		(layer "In11.Cu")
		(net "P5E_CPU0_P1_RX_DN<14>")
	)
	(segment
		(start 353.281996 -392.616944)
		(end 353.53879 -392.360404)
		(width 0.14224)
		(layer "In11.Cu")
		(net "P5E_CPU0_P1_RX_DN<14>")
	)
	(segment
		(start 353.471988 -393.787376)
		(end 353.472496 -393.786868)
		(width 0.14224)
		(layer "In11.Cu")
		(net "P5E_CPU0_P1_RX_DN<14>")
	)
	(segment
		(start 358.515666 -284.619446)
		(end 358.515666 -284.616144)
		(width 0.1143)
		(layer "In11.Cu")
		(net "P5E_CPU0_P1_RX_DN<14>")
	)
	(segment
		(start 374.313704 -323.556376)
		(end 374.313704 -323.55663)
		(width 0.14224)
		(layer "In11.Cu")
		(net "P5E_CPU0_P1_RX_DN<14>")
	)
	(segment
		(start 358.358694 -284.311344)
		(end 358.328214 -284.293564)
		(width 0.1143)
		(layer "In11.Cu")
		(net "P5E_CPU0_P1_RX_DN<14>")
	)
	(segment
		(start 358.289098 -283.341572)
		(end 358.35209 -283.304742)
		(width 0.1143)
		(layer "In11.Cu")
		(net "P5E_CPU0_P1_RX_DN<14>")
	)
	(segment
		(start 357.858822 -278.62403)
		(end 357.857298 -278.623014)
		(width 0.1143)
		(layer "In11.Cu")
		(net "P5E_CPU0_P1_RX_DN<14>")
	)
	(segment
		(start 358.290622 -294.680386)
		(end 358.324658 -294.660574)
		(width 0.1143)
		(layer "In11.Cu")
		(net "P5E_CPU0_P1_RX_DN<14>")
	)
	(segment
		(start 357.41991 -277.831804)
		(end 357.349044 -277.790656)
		(width 0.1143)
		(layer "In11.Cu")
		(net "P5E_CPU0_P1_RX_DN<14>")
	)
	(segment
		(start 358.289098 -280.101548)
		(end 358.357932 -280.061416)
		(width 0.1143)
		(layer "In11.Cu")
		(net "P5E_CPU0_P1_RX_DN<14>")
	)
	(segment
		(start 376.98934 -352.927412)
		(end 378.154946 -350.113092)
		(width 0.14224)
		(layer "In11.Cu")
		(net "P5E_CPU0_P1_RX_DN<14>")
	)
	(segment
		(start 353.661472 -390.549892)
		(end 360.240326 -379.821694)
		(width 0.14224)
		(layer "In11.Cu")
		(net "P5E_CPU0_P1_RX_DN<14>")
	)
	(segment
		(start 358.358694 -290.791138)
		(end 358.328214 -290.773358)
		(width 0.1143)
		(layer "In11.Cu")
		(net "P5E_CPU0_P1_RX_DN<14>")
	)
	(segment
		(start 362.77296 -372.140988)
		(end 362.96219 -372.096792)
		(width 0.14224)
		(layer "In11.Cu")
		(net "P5E_CPU0_P1_RX_DN<14>")
	)
	(segment
		(start 363.557312 -371.138704)
		(end 363.910118 -370.57076)
		(width 0.14224)
		(layer "In11.Cu")
		(net "P5E_CPU0_P1_RX_DN<14>")
	)
	(segment
		(start 360.861356 -375.478294)
		(end 360.861356 -375.47804)
		(width 0.14224)
		(layer "In11.Cu")
		(net "P5E_CPU0_P1_RX_DN<14>")
	)
	(segment
		(start 358.289098 -289.821366)
		(end 358.328214 -289.798506)
		(width 0.1143)
		(layer "In11.Cu")
		(net "P5E_CPU0_P1_RX_DN<14>")
	)
	(segment
		(start 360.426 -379.163834)
		(end 360.426 -377.007882)
		(width 0.14224)
		(layer "In11.Cu")
		(net "P5E_CPU0_P1_RX_DN<14>")
	)
	(segment
		(start 358.289098 -288.201354)
		(end 358.328214 -288.178494)
		(width 0.1143)
		(layer "In11.Cu")
		(net "P5E_CPU0_P1_RX_DN<14>")
	)
	(segment
		(start 358.328214 -291.418518)
		(end 358.358694 -291.400738)
		(width 0.1143)
		(layer "In11.Cu")
		(net "P5E_CPU0_P1_RX_DN<14>")
	)
	(segment
		(start 358.32796 -293.038784)
		(end 358.328214 -293.03853)
		(width 0.1143)
		(layer "In11.Cu")
		(net "P5E_CPU0_P1_RX_DN<14>")
	)
	(segment
		(start 353.27717 -393.22883)
		(end 353.281996 -392.616944)
		(width 0.14224)
		(layer "In11.Cu")
		(net "P5E_CPU0_P1_RX_DN<14>")
	)
	(segment
		(start 353.586034 -392.246358)
		(end 353.586034 -390.817354)
		(width 0.14224)
		(layer "In11.Cu")
		(net "P5E_CPU0_P1_RX_DN<14>")
	)
	(segment
		(start 358.367584 -292.417246)
		(end 358.32669 -292.392354)
		(width 0.1143)
		(layer "In11.Cu")
		(net "P5E_CPU0_P1_RX_DN<14>")
	)
	(segment
		(start 361.996736 -373.650764)
		(end 361.996736 -373.65051)
		(width 0.14224)
		(layer "In11.Cu")
		(net "P5E_CPU0_P1_RX_DN<14>")
	)
	(segment
		(start 357.88981 -278.64181)
		(end 357.864156 -278.627078)
		(width 0.1143)
		(layer "In11.Cu")
		(net "P5E_CPU0_P1_RX_DN<14>")
	)
	(segment
		(start 358.289098 -291.441378)
		(end 358.328214 -291.418518)
		(width 0.1143)
		(layer "In11.Cu")
		(net "P5E_CPU0_P1_RX_DN<14>")
	)
	(segment
		(start 357.029004 -277.32609)
		(end 356.731062 -277.32609)
		(width 0.1143)
		(layer "In11.Cu")
		(net "P5E_CPU0_P1_RX_DN<14>")
	)
	(segment
		(start 361.996736 -373.65051)
		(end 361.95254 -373.461788)
		(width 0.14224)
		(layer "In11.Cu")
		(net "P5E_CPU0_P1_RX_DN<14>")
	)
	(segment
		(start 374.313704 -323.55663)
		(end 372.723664 -320.514218)
		(width 0.14224)
		(layer "In11.Cu")
		(net "P5E_CPU0_P1_RX_DN<14>")
	)
	(segment
		(start 358.324658 -294.660574)
		(end 358.396032 -294.615108)
		(width 0.1143)
		(layer "In11.Cu")
		(net "P5E_CPU0_P1_RX_DN<14>")
	)
	(segment
		(start 358.32669 -292.392354)
		(end 358.289098 -292.37051)
		(width 0.1143)
		(layer "In11.Cu")
		(net "P5E_CPU0_P1_RX_DN<14>")
	)
	(segment
		(start 358.328214 -284.293564)
		(end 358.289098 -284.270704)
		(width 0.1143)
		(layer "In11.Cu")
		(net "P5E_CPU0_P1_RX_DN<14>")
	)
	(segment
		(start 375.903744 -326.599042)
		(end 374.313704 -323.556376)
		(width 0.14224)
		(layer "In11.Cu")
		(net "P5E_CPU0_P1_RX_DN<14>")
	)
	(segment
		(start 376.98934 -352.927666)
		(end 376.98934 -352.927412)
		(width 0.14224)
		(layer "In11.Cu")
		(net "P5E_CPU0_P1_RX_DN<14>")
	)
	(segment
		(start 362.591858 -372.692422)
		(end 362.547662 -372.5037)
		(width 0.14224)
		(layer "In11.Cu")
		(net "P5E_CPU0_P1_RX_DN<14>")
	)
	(segment
		(start 358.360726 -286.539686)
		(end 358.361234 -286.539178)
		(width 0.1143)
		(layer "In11.Cu")
		(net "P5E_CPU0_P1_RX_DN<14>")
	)
	(segment
		(start 365.478314 -311.68594)
		(end 360.210608 -303.802796)
		(width 0.14224)
		(layer "In11.Cu")
		(net "P5E_CPU0_P1_RX_DN<14>")
	)
	(segment
		(start 358.407208 -281.099768)
		(end 358.289098 -281.03068)
		(width 0.1143)
		(layer "In11.Cu")
		(net "P5E_CPU0_P1_RX_DN<14>")
	)
	(segment
		(start 353.118928 -393.69238)
		(end 353.471988 -393.787376)
		(width 0.14224)
		(layer "In11.Cu")
		(net "P5E_CPU0_P1_RX_DN<14>")
	)
	(segment
		(start 358.045766 -295.62298)
		(end 358.045766 -295.145968)
		(width 0.1143)
		(layer "In11.Cu")
		(net "P5E_CPU0_P1_RX_DN<14>")
	)
	(segment
		(start 358.393238 -294.055038)
		(end 358.359964 -294.031924)
		(width 0.1143)
		(layer "In11.Cu")
		(net "P5E_CPU0_P1_RX_DN<14>")
	)
	(segment
		(start 375.82348 -355.74224)
		(end 376.98934 -352.927666)
		(width 0.14224)
		(layer "In11.Cu")
		(net "P5E_CPU0_P1_RX_DN<14>")
	)
	(segment
		(start 358.328214 -279.433528)
		(end 358.289098 -279.410668)
		(width 0.1143)
		(layer "In11.Cu")
		(net "P5E_CPU0_P1_RX_DN<14>")
	)
	(segment
		(start 358.359964 -294.031924)
		(end 358.328214 -294.013382)
		(width 0.1143)
		(layer "In11.Cu")
		(net "P5E_CPU0_P1_RX_DN<14>")
	)
	(segment
		(start 362.96219 -372.096792)
		(end 363.187234 -371.734334)
		(width 0.14224)
		(layer "In11.Cu")
		(net "P5E_CPU0_P1_RX_DN<14>")
	)
	(segment
		(start 363.368336 -371.1829)
		(end 363.557312 -371.138704)
		(width 0.14224)
		(layer "In11.Cu")
		(net "P5E_CPU0_P1_RX_DN<14>")
	)
	(segment
		(start 363.187234 -371.734334)
		(end 363.143038 -371.545612)
		(width 0.14224)
		(layer "In11.Cu")
		(net "P5E_CPU0_P1_RX_DN<14>")
	)
	(segment
		(start 357.862632 -278.626062)
		(end 357.860092 -278.624792)
		(width 0.1143)
		(layer "In11.Cu")
		(net "P5E_CPU0_P1_RX_DN<14>")
	)
	(segment
		(start 378.1552 -350.112838)
		(end 378.1552 -339.132672)
		(width 0.14224)
		(layer "In11.Cu")
		(net "P5E_CPU0_P1_RX_DN<14>")
	)
	(segment
		(start 358.328214 -290.773358)
		(end 358.289098 -290.750498)
		(width 0.1143)
		(layer "In11.Cu")
		(net "P5E_CPU0_P1_RX_DN<14>")
	)
	(segment
		(start 358.328214 -293.03853)
		(end 358.359456 -293.020242)
		(width 0.1143)
		(layer "In11.Cu")
		(net "P5E_CPU0_P1_RX_DN<14>")
	)
	(segment
		(start 358.328214 -286.558482)
		(end 358.360726 -286.539686)
		(width 0.1143)
		(layer "In11.Cu")
		(net "P5E_CPU0_P1_RX_DN<14>")
	)
	(segment
		(start 353.594162 -393.716764)
		(end 353.594162 -393.545822)
		(width 0.14224)
		(layer "In11.Cu")
		(net "P5E_CPU0_P1_RX_DN<14>")
	)
	(segment
		(start 358.359456 -293.020242)
		(end 358.360218 -293.019734)
		(width 0.1143)
		(layer "In11.Cu")
		(net "P5E_CPU0_P1_RX_DN<14>")
	)
	(segment
		(start 360.861356 -375.47804)
		(end 361.996736 -373.650764)
		(width 0.14224)
		(layer "In11.Cu")
		(net "P5E_CPU0_P1_RX_DN<14>")
	)
	(segment
		(start 358.358694 -285.931356)
		(end 358.289098 -285.890716)
		(width 0.1143)
		(layer "In11.Cu")
		(net "P5E_CPU0_P1_RX_DN<14>")
	)
	(segment
		(start 362.547662 -372.5037)
		(end 362.77296 -372.140988)
		(width 0.14224)
		(layer "In11.Cu")
		(net "P5E_CPU0_P1_RX_DN<14>")
	)
	(segment
		(start 358.289098 -284.961584)
		(end 358.35971 -284.920436)
		(width 0.1143)
		(layer "In11.Cu")
		(net "P5E_CPU0_P1_RX_DN<14>")
	)
	(segment
		(start 378.154946 -350.113092)
		(end 378.1552 -350.112838)
		(width 0.14224)
		(layer "In11.Cu")
		(net "P5E_CPU0_P1_RX_DN<14>")
	)
	(segment
		(start 357.111808 -277.408894)
		(end 357.029004 -277.32609)
		(width 0.1143)
		(layer "In11.Cu")
		(net "P5E_CPU0_P1_RX_DN<14>")
	)
	(segment
		(start 353.594162 -393.545822)
		(end 353.27717 -393.22883)
		(width 0.14224)
		(layer "In11.Cu")
		(net "P5E_CPU0_P1_RX_DN<14>")
	)
	(segment
		(start 362.366814 -373.05488)
		(end 362.591858 -372.692422)
		(width 0.14224)
		(layer "In11.Cu")
		(net "P5E_CPU0_P1_RX_DN<14>")
	)
	(segment
		(start 358.328214 -288.178494)
		(end 358.352598 -288.16427)
		(width 0.1143)
		(layer "In11.Cu")
		(net "P5E_CPU0_P1_RX_DN<14>")
	)
	(segment
		(start 358.289098 -281.72156)
		(end 358.407208 -281.652472)
		(width 0.1143)
		(layer "In11.Cu")
		(net "P5E_CPU0_P1_RX_DN<14>")
	)
	(segment
		(start 363.910118 -370.57076)
		(end 369.953032 -364.5281)
		(width 0.14224)
		(layer "In11.Cu")
		(net "P5E_CPU0_P1_RX_DN<14>")
	)
	(segment
		(start 358.328214 -289.153346)
		(end 358.289098 -289.130486)
		(width 0.1143)
		(layer "In11.Cu")
		(net "P5E_CPU0_P1_RX_DN<14>")
	)
	(arc
		(start 358.045766 -278.946102)
		(mid 358.004511 -278.775131)
		(end 357.88981 -278.64181)
		(width 0.1143)
		(layer "In11.Cu")
		(net "P5E_CPU0_P1_RX_DN<14>")
	)
	(arc
		(start 358.045766 -295.145968)
		(mid 358.110281 -294.883749)
		(end 358.289098 -294.681402)
		(width 0.1143)
		(layer "In11.Cu")
		(net "P5E_CPU0_P1_RX_DN<14>")
	)
	(arc
		(start 358.361234 -286.539178)
		(mid 358.474789 -286.406479)
		(end 358.515666 -286.236664)
		(width 0.1143)
		(layer "In11.Cu")
		(net "P5E_CPU0_P1_RX_DN<14>")
	)
	(arc
		(start 357.575866 -278.136096)
		(mid 357.534611 -277.965125)
		(end 357.41991 -277.831804)
		(width 0.1143)
		(layer "In11.Cu")
		(net "P5E_CPU0_P1_RX_DN<14>")
	)
	(arc
		(start 358.35971 -284.920436)
		(mid 358.361875 -284.918793)
		(end 358.364028 -284.917134)
		(width 0.1143)
		(layer "In11.Cu")
		(net "P5E_CPU0_P1_RX_DN<14>")
	)
	(arc
		(start 358.291638 -287.512252)
		(mid 358.110986 -287.309507)
		(end 358.045766 -287.045908)
		(width 0.1143)
		(layer "In11.Cu")
		(net "P5E_CPU0_P1_RX_DN<14>")
	)
	(arc
		(start 360.240326 -379.821694)
		(mid 360.378659 -379.505608)
		(end 360.426 -379.163834)
		(width 0.14224)
		(layer "In11.Cu")
		(net "P5E_CPU0_P1_RX_DN<14>")
	)
	(arc
		(start 358.357932 -280.061416)
		(mid 358.471033 -279.926435)
		(end 358.515666 -279.756108)
		(width 0.1143)
		(layer "In11.Cu")
		(net "P5E_CPU0_P1_RX_DN<14>")
	)
	(arc
		(start 358.358694 -289.780726)
		(mid 358.515671 -289.475926)
		(end 358.358694 -289.171126)
		(width 0.1143)
		(layer "In11.Cu")
		(net "P5E_CPU0_P1_RX_DN<14>")
	)
	(arc
		(start 358.289098 -294.681402)
		(mid 358.28986 -294.680893)
		(end 358.290622 -294.680386)
		(width 0.1143)
		(layer "In11.Cu")
		(net "P5E_CPU0_P1_RX_DN<14>")
	)
	(arc
		(start 358.289098 -284.270704)
		(mid 358.045771 -283.806138)
		(end 358.289098 -283.341572)
		(width 0.1143)
		(layer "In11.Cu")
		(net "P5E_CPU0_P1_RX_DN<14>")
	)
	(arc
		(start 358.514904 -282.973018)
		(mid 358.468643 -282.814509)
		(end 358.358694 -282.691332)
		(width 0.1143)
		(layer "In11.Cu")
		(net "P5E_CPU0_P1_RX_DN<14>")
	)
	(arc
		(start 358.407208 -281.652472)
		(mid 358.565769 -281.37612)
		(end 358.407208 -281.099768)
		(width 0.1143)
		(layer "In11.Cu")
		(net "P5E_CPU0_P1_RX_DN<14>")
	)
	(arc
		(start 358.515666 -284.616144)
		(mid 358.474117 -284.444722)
		(end 358.358694 -284.311344)
		(width 0.1143)
		(layer "In11.Cu")
		(net "P5E_CPU0_P1_RX_DN<14>")
	)
	(arc
		(start 358.358694 -291.400738)
		(mid 358.515671 -291.095938)
		(end 358.358694 -290.791138)
		(width 0.1143)
		(layer "In11.Cu")
		(net "P5E_CPU0_P1_RX_DN<14>")
	)
	(arc
		(start 360.426 -377.007882)
		(mid 360.53691 -376.212695)
		(end 360.861356 -375.478294)
		(width 0.14224)
		(layer "In11.Cu")
		(net "P5E_CPU0_P1_RX_DN<14>")
	)
	(arc
		(start 358.289098 -289.130486)
		(mid 358.045771 -288.66592)
		(end 358.289098 -288.201354)
		(width 0.1143)
		(layer "In11.Cu")
		(net "P5E_CPU0_P1_RX_DN<14>")
	)
	(arc
		(start 358.515666 -279.756108)
		(mid 358.474117 -279.584686)
		(end 358.358694 -279.451308)
		(width 0.1143)
		(layer "In11.Cu")
		(net "P5E_CPU0_P1_RX_DN<14>")
	)
	(arc
		(start 357.349044 -277.790656)
		(mid 357.197057 -277.634148)
		(end 357.115618 -277.431754)
		(width 0.1143)
		(layer "In11.Cu")
		(net "P5E_CPU0_P1_RX_DN<14>")
	)
	(arc
		(start 353.53879 -392.360404)
		(mid 353.573806 -392.308094)
		(end 353.586034 -392.246358)
		(width 0.14224)
		(layer "In11.Cu")
		(net "P5E_CPU0_P1_RX_DN<14>")
	)
	(arc
		(start 358.289098 -285.890716)
		(mid 358.045771 -285.42615)
		(end 358.289098 -284.961584)
		(width 0.1143)
		(layer "In11.Cu")
		(net "P5E_CPU0_P1_RX_DN<14>")
	)
	(arc
		(start 358.289098 -290.750498)
		(mid 358.045771 -290.285932)
		(end 358.289098 -289.821366)
		(width 0.1143)
		(layer "In11.Cu")
		(net "P5E_CPU0_P1_RX_DN<14>")
	)
	(arc
		(start 358.35209 -283.304742)
		(mid 358.463305 -283.161612)
		(end 358.515412 -282.988004)
		(width 0.1143)
		(layer "In11.Cu")
		(net "P5E_CPU0_P1_RX_DN<14>")
	)
	(arc
		(start 353.586034 -390.817354)
		(mid 353.605247 -390.678401)
		(end 353.661472 -390.549892)
		(width 0.14224)
		(layer "In11.Cu")
		(net "P5E_CPU0_P1_RX_DN<14>")
	)
	(arc
		(start 358.352598 -288.16427)
		(mid 358.463146 -288.021707)
		(end 358.515412 -287.849056)
		(width 0.1143)
		(layer "In11.Cu")
		(net "P5E_CPU0_P1_RX_DN<14>")
	)
	(arc
		(start 358.512872 -287.812226)
		(mid 358.463381 -287.665477)
		(end 358.358694 -287.551368)
		(width 0.1143)
		(layer "In11.Cu")
		(net "P5E_CPU0_P1_RX_DN<14>")
	)
	(arc
		(start 358.515412 -287.849056)
		(mid 358.514593 -287.83061)
		(end 358.512872 -287.812226)
		(width 0.1143)
		(layer "In11.Cu")
		(net "P5E_CPU0_P1_RX_DN<14>")
	)
	(arc
		(start 358.289098 -292.37051)
		(mid 358.045771 -291.905944)
		(end 358.289098 -291.441378)
		(width 0.1143)
		(layer "In11.Cu")
		(net "P5E_CPU0_P1_RX_DN<14>")
	)
	(arc
		(start 358.289098 -279.410668)
		(mid 358.110285 -279.208318)
		(end 358.045766 -278.946102)
		(width 0.1143)
		(layer "In11.Cu")
		(net "P5E_CPU0_P1_RX_DN<14>")
	)
	(arc
		(start 358.289098 -281.03068)
		(mid 358.045771 -280.566114)
		(end 358.289098 -280.101548)
		(width 0.1143)
		(layer "In11.Cu")
		(net "P5E_CPU0_P1_RX_DN<14>")
	)
	(arc
		(start 358.515412 -292.702742)
		(mid 358.476329 -292.541951)
		(end 358.367584 -292.417246)
		(width 0.1143)
		(layer "In11.Cu")
		(net "P5E_CPU0_P1_RX_DN<14>")
	)
	(arc
		(start 369.953032 -364.5281)
		(mid 373.320913 -360.42426)
		(end 375.82348 -355.74224)
		(width 0.14224)
		(layer "In11.Cu")
		(net "P5E_CPU0_P1_RX_DN<14>")
	)
	(arc
		(start 358.045766 -287.045908)
		(mid 358.110281 -286.783689)
		(end 358.289098 -286.581342)
		(width 0.1143)
		(layer "In11.Cu")
		(net "P5E_CPU0_P1_RX_DN<14>")
	)
	(arc
		(start 358.515666 -286.236156)
		(mid 358.474117 -286.064734)
		(end 358.358694 -285.931356)
		(width 0.1143)
		(layer "In11.Cu")
		(net "P5E_CPU0_P1_RX_DN<14>")
	)
	(arc
		(start 358.396032 -294.615108)
		(mid 358.540536 -294.334307)
		(end 358.393238 -294.055038)
		(width 0.1143)
		(layer "In11.Cu")
		(net "P5E_CPU0_P1_RX_DN<14>")
	)
	(arc
		(start 357.773732 -278.569674)
		(mid 357.628332 -278.406322)
		(end 357.575866 -278.194008)
		(width 0.1143)
		(layer "In11.Cu")
		(net "P5E_CPU0_P1_RX_DN<14>")
	)
	(arc
		(start 357.115618 -277.431754)
		(mid 357.113595 -277.420344)
		(end 357.111808 -277.408894)
		(width 0.1143)
		(layer "In11.Cu")
		(net "P5E_CPU0_P1_RX_DN<14>")
	)
	(arc
		(start 358.360218 -293.019734)
		(mid 358.471353 -292.892778)
		(end 358.515412 -292.72992)
		(width 0.1143)
		(layer "In11.Cu")
		(net "P5E_CPU0_P1_RX_DN<14>")
	)
	(arc
		(start 358.32796 -294.013382)
		(mid 358.048416 -293.526146)
		(end 358.32796 -293.038784)
		(width 0.1143)
		(layer "In11.Cu")
		(net "P5E_CPU0_P1_RX_DN<14>")
	)
	(arc
		(start 358.289098 -282.650692)
		(mid 358.045771 -282.186126)
		(end 358.289098 -281.72156)
		(width 0.1143)
		(layer "In11.Cu")
		(net "P5E_CPU0_P1_RX_DN<14>")
	)
	(arc
		(start 358.364028 -284.917134)
		(mid 358.469783 -284.783546)
		(end 358.515666 -284.619446)
		(width 0.1143)
		(layer "In11.Cu")
		(net "P5E_CPU0_P1_RX_DN<14>")
	)
	(arc
		(start 358.515412 -282.988004)
		(mid 358.515235 -282.980508)
		(end 358.514904 -282.973018)
		(width 0.1143)
		(layer "In11.Cu")
		(net "P5E_CPU0_P1_RX_DN<14>")
	)
	(segment
		(start 357.197914 -278.680164)
		(end 356.731062 -278.946102)
		(width 0.12954)
		(layer "F.Cu")
		(net "P5E_CPU0_P1_RX_DN<13>")
	)
	(segment
		(start 351.398078 -393.69238)
		(end 351.918778 -393.69238)
		(width 0.127)
		(layer "F.Cu")
		(net "P5E_CPU0_P1_RX_DN<13>")
	)
	(segment
		(start 357.409496 -294.646096)
		(end 357.410004 -294.646096)
		(width 0.1143)
		(layer "In11.Cu")
		(net "P5E_CPU0_P1_RX_DN<13>")
	)
	(segment
		(start 357.376984 -292.38702)
		(end 357.349044 -292.37051)
		(width 0.1143)
		(layer "In11.Cu")
		(net "P5E_CPU0_P1_RX_DN<13>")
	)
	(segment
		(start 357.349044 -284.961584)
		(end 357.38816 -284.938724)
		(width 0.1143)
		(layer "In11.Cu")
		(net "P5E_CPU0_P1_RX_DN<13>")
	)
	(segment
		(start 357.388922 -292.393878)
		(end 357.38816 -292.39337)
		(width 0.1143)
		(layer "In11.Cu")
		(net "P5E_CPU0_P1_RX_DN<13>")
	)
	(segment
		(start 357.41991 -284.311852)
		(end 357.38816 -284.293564)
		(width 0.1143)
		(layer "In11.Cu")
		(net "P5E_CPU0_P1_RX_DN<13>")
	)
	(segment
		(start 377.210066 -349.819976)
		(end 377.21032 -349.819722)
		(width 0.14224)
		(layer "In11.Cu")
		(net "P5E_CPU0_P1_RX_DN<13>")
	)
	(segment
		(start 357.38816 -280.078688)
		(end 357.41991 -280.0604)
		(width 0.1143)
		(layer "In11.Cu")
		(net "P5E_CPU0_P1_RX_DN<13>")
	)
	(segment
		(start 357.38562 -291.420042)
		(end 357.387144 -291.419026)
		(width 0.1143)
		(layer "In11.Cu")
		(net "P5E_CPU0_P1_RX_DN<13>")
	)
	(segment
		(start 357.378508 -292.388036)
		(end 357.376984 -292.38702)
		(width 0.1143)
		(layer "In11.Cu")
		(net "P5E_CPU0_P1_RX_DN<13>")
	)
	(segment
		(start 357.41991 -279.451816)
		(end 357.38816 -279.433528)
		(width 0.1143)
		(layer "In11.Cu")
		(net "P5E_CPU0_P1_RX_DN<13>")
	)
	(segment
		(start 354.971604 -386.151882)
		(end 359.104438 -379.457204)
		(width 0.14224)
		(layer "In11.Cu")
		(net "P5E_CPU0_P1_RX_DN<13>")
	)
	(segment
		(start 357.349044 -291.441378)
		(end 357.38562 -291.420042)
		(width 0.1143)
		(layer "In11.Cu")
		(net "P5E_CPU0_P1_RX_DN<13>")
	)
	(segment
		(start 357.372158 -294.004238)
		(end 357.369872 -294.002714)
		(width 0.1143)
		(layer "In11.Cu")
		(net "P5E_CPU0_P1_RX_DN<13>")
	)
	(segment
		(start 357.41991 -290.791646)
		(end 357.388922 -290.773866)
		(width 0.1143)
		(layer "In11.Cu")
		(net "P5E_CPU0_P1_RX_DN<13>")
	)
	(segment
		(start 357.029004 -278.946102)
		(end 356.731062 -278.946102)
		(width 0.1143)
		(layer "In11.Cu")
		(net "P5E_CPU0_P1_RX_DN<13>")
	)
	(segment
		(start 352.394266 -393.545822)
		(end 352.077274 -393.22883)
		(width 0.14224)
		(layer "In11.Cu")
		(net "P5E_CPU0_P1_RX_DN<13>")
	)
	(segment
		(start 357.347774 -293.062152)
		(end 357.372666 -293.047166)
		(width 0.1143)
		(layer "In11.Cu")
		(net "P5E_CPU0_P1_RX_DN<13>")
	)
	(segment
		(start 357.38562 -289.80003)
		(end 357.387144 -289.799014)
		(width 0.1143)
		(layer "In11.Cu")
		(net "P5E_CPU0_P1_RX_DN<13>")
	)
	(segment
		(start 357.575866 -287.856422)
		(end 357.575866 -287.854136)
		(width 0.1143)
		(layer "In11.Cu")
		(net "P5E_CPU0_P1_RX_DN<13>")
	)
	(segment
		(start 357.41991 -289.171634)
		(end 357.388922 -289.153854)
		(width 0.1143)
		(layer "In11.Cu")
		(net "P5E_CPU0_P1_RX_DN<13>")
	)
	(segment
		(start 357.388922 -291.41801)
		(end 357.41991 -291.40023)
		(width 0.1143)
		(layer "In11.Cu")
		(net "P5E_CPU0_P1_RX_DN<13>")
	)
	(segment
		(start 357.40975 -294.025828)
		(end 357.409496 -294.025828)
		(width 0.1143)
		(layer "In11.Cu")
		(net "P5E_CPU0_P1_RX_DN<13>")
	)
	(segment
		(start 354.60305 -386.749036)
		(end 354.558346 -386.560314)
		(width 0.14224)
		(layer "In11.Cu")
		(net "P5E_CPU0_P1_RX_DN<13>")
	)
	(segment
		(start 357.388922 -290.773866)
		(end 357.38816 -290.773358)
		(width 0.1143)
		(layer "In11.Cu")
		(net "P5E_CPU0_P1_RX_DN<13>")
	)
	(segment
		(start 357.474266 -287.606232)
		(end 357.348282 -287.51657)
		(width 0.1143)
		(layer "In11.Cu")
		(net "P5E_CPU0_P1_RX_DN<13>")
	)
	(segment
		(start 354.190046 -387.156706)
		(end 354.379022 -387.112002)
		(width 0.14224)
		(layer "In11.Cu")
		(net "P5E_CPU0_P1_RX_DN<13>")
	)
	(segment
		(start 357.349044 -281.72156)
		(end 357.38816 -281.6987)
		(width 0.1143)
		(layer "In11.Cu")
		(net "P5E_CPU0_P1_RX_DN<13>")
	)
	(segment
		(start 357.408734 -294.02532)
		(end 357.375968 -294.006524)
		(width 0.1143)
		(layer "In11.Cu")
		(net "P5E_CPU0_P1_RX_DN<13>")
	)
	(segment
		(start 357.383842 -289.150806)
		(end 357.356664 -289.135058)
		(width 0.1143)
		(layer "In11.Cu")
		(net "P5E_CPU0_P1_RX_DN<13>")
	)
	(segment
		(start 357.380286 -292.389052)
		(end 357.379524 -292.388544)
		(width 0.1143)
		(layer "In11.Cu")
		(net "P5E_CPU0_P1_RX_DN<13>")
	)
	(segment
		(start 352.272092 -393.787376)
		(end 352.2726 -393.786868)
		(width 0.14224)
		(layer "In11.Cu")
		(net "P5E_CPU0_P1_RX_DN<13>")
	)
	(segment
		(start 353.373436 -388.479792)
		(end 353.597464 -388.116572)
		(width 0.14224)
		(layer "In11.Cu")
		(net "P5E_CPU0_P1_RX_DN<13>")
	)
	(segment
		(start 357.38816 -279.433528)
		(end 357.349044 -279.410668)
		(width 0.1143)
		(layer "In11.Cu")
		(net "P5E_CPU0_P1_RX_DN<13>")
	)
	(segment
		(start 357.384604 -289.151314)
		(end 357.383842 -289.150806)
		(width 0.1143)
		(layer "In11.Cu")
		(net "P5E_CPU0_P1_RX_DN<13>")
	)
	(segment
		(start 352.386138 -392.31316)
		(end 352.386138 -390.455912)
		(width 0.14224)
		(layer "In11.Cu")
		(net "P5E_CPU0_P1_RX_DN<13>")
	)
	(segment
		(start 357.349044 -286.581342)
		(end 357.418894 -286.540956)
		(width 0.1143)
		(layer "In11.Cu")
		(net "P5E_CPU0_P1_RX_DN<13>")
	)
	(segment
		(start 357.41991 -289.780218)
		(end 357.439722 -289.765994)
		(width 0.1143)
		(layer "In11.Cu")
		(net "P5E_CPU0_P1_RX_DN<13>")
	)
	(segment
		(start 377.21032 -339.217)
		(end 374.997472 -326.898254)
		(width 0.14224)
		(layer "In11.Cu")
		(net "P5E_CPU0_P1_RX_DN<13>")
	)
	(segment
		(start 357.41991 -292.411658)
		(end 357.388922 -292.393878)
		(width 0.1143)
		(layer "In11.Cu")
		(net "P5E_CPU0_P1_RX_DN<13>")
	)
	(segment
		(start 357.439722 -289.185858)
		(end 357.41991 -289.171634)
		(width 0.1143)
		(layer "In11.Cu")
		(net "P5E_CPU0_P1_RX_DN<13>")
	)
	(segment
		(start 357.41991 -293.020242)
		(end 357.439722 -293.006018)
		(width 0.1143)
		(layer "In11.Cu")
		(net "P5E_CPU0_P1_RX_DN<13>")
	)
	(segment
		(start 357.059992 -298.638722)
		(end 357.059992 -295.697148)
		(width 0.14224)
		(layer "In11.Cu")
		(net "P5E_CPU0_P1_RX_DN<13>")
	)
	(segment
		(start 357.387144 -291.419026)
		(end 357.38816 -291.418518)
		(width 0.1143)
		(layer "In11.Cu")
		(net "P5E_CPU0_P1_RX_DN<13>")
	)
	(segment
		(start 361.055158 -372.089426)
		(end 369.107974 -364.03661)
		(width 0.14224)
		(layer "In11.Cu")
		(net "P5E_CPU0_P1_RX_DN<13>")
	)
	(segment
		(start 357.38816 -282.673552)
		(end 357.349044 -282.650692)
		(width 0.1143)
		(layer "In11.Cu")
		(net "P5E_CPU0_P1_RX_DN<13>")
	)
	(segment
		(start 352.077274 -393.22883)
		(end 352.0821 -392.616944)
		(width 0.14224)
		(layer "In11.Cu")
		(net "P5E_CPU0_P1_RX_DN<13>")
	)
	(segment
		(start 354.782628 -386.19684)
		(end 354.971604 -386.152136)
		(width 0.14224)
		(layer "In11.Cu")
		(net "P5E_CPU0_P1_RX_DN<13>")
	)
	(segment
		(start 357.38816 -283.318712)
		(end 357.41991 -283.300424)
		(width 0.1143)
		(layer "In11.Cu")
		(net "P5E_CPU0_P1_RX_DN<13>")
	)
	(segment
		(start 357.38816 -284.293564)
		(end 357.349044 -284.270704)
		(width 0.1143)
		(layer "In11.Cu")
		(net "P5E_CPU0_P1_RX_DN<13>")
	)
	(segment
		(start 357.355902 -289.13455)
		(end 357.349044 -289.130486)
		(width 0.1143)
		(layer "In11.Cu")
		(net "P5E_CPU0_P1_RX_DN<13>")
	)
	(segment
		(start 359.123488 -379.390402)
		(end 359.123488 -376.89409)
		(width 0.14224)
		(layer "In11.Cu")
		(net "P5E_CPU0_P1_RX_DN<13>")
	)
	(segment
		(start 357.388922 -289.153854)
		(end 357.38816 -289.153346)
		(width 0.1143)
		(layer "In11.Cu")
		(net "P5E_CPU0_P1_RX_DN<13>")
	)
	(segment
		(start 357.38816 -285.913576)
		(end 357.349044 -285.890716)
		(width 0.1143)
		(layer "In11.Cu")
		(net "P5E_CPU0_P1_RX_DN<13>")
	)
	(segment
		(start 357.409496 -294.025828)
		(end 357.408734 -294.02532)
		(width 0.1143)
		(layer "In11.Cu")
		(net "P5E_CPU0_P1_RX_DN<13>")
	)
	(segment
		(start 357.059992 -295.6687)
		(end 357.105712 -295.62298)
		(width 0.1143)
		(layer "In11.Cu")
		(net "P5E_CPU0_P1_RX_DN<13>")
	)
	(segment
		(start 374.997472 -326.898254)
		(end 372.010432 -321.183)
		(width 0.14224)
		(layer "In11.Cu")
		(net "P5E_CPU0_P1_RX_DN<13>")
	)
	(segment
		(start 357.41991 -285.931864)
		(end 357.38816 -285.913576)
		(width 0.1143)
		(layer "In11.Cu")
		(net "P5E_CPU0_P1_RX_DN<13>")
	)
	(segment
		(start 357.349806 -294.680894)
		(end 357.409496 -294.646096)
		(width 0.1143)
		(layer "In11.Cu")
		(net "P5E_CPU0_P1_RX_DN<13>")
	)
	(segment
		(start 352.0821 -392.616944)
		(end 352.386138 -392.31316)
		(width 0.14224)
		(layer "In11.Cu")
		(net "P5E_CPU0_P1_RX_DN<13>")
	)
	(segment
		(start 357.394764 -293.03472)
		(end 357.395526 -293.034212)
		(width 0.1143)
		(layer "In11.Cu")
		(net "P5E_CPU0_P1_RX_DN<13>")
	)
	(segment
		(start 357.395526 -293.034212)
		(end 357.398066 -293.032688)
		(width 0.1143)
		(layer "In11.Cu")
		(net "P5E_CPU0_P1_RX_DN<13>")
	)
	(segment
		(start 354.971604 -386.152136)
		(end 354.971604 -386.151882)
		(width 0.14224)
		(layer "In11.Cu")
		(net "P5E_CPU0_P1_RX_DN<13>")
	)
	(segment
		(start 357.375968 -294.006524)
		(end 357.373174 -294.004746)
		(width 0.1143)
		(layer "In11.Cu")
		(net "P5E_CPU0_P1_RX_DN<13>")
	)
	(segment
		(start 352.2726 -393.786868)
		(end 352.394266 -393.716764)
		(width 0.14224)
		(layer "In11.Cu")
		(net "P5E_CPU0_P1_RX_DN<13>")
	)
	(segment
		(start 357.059992 -295.697148)
		(end 357.059992 -295.6687)
		(width 0.1143)
		(layer "In11.Cu")
		(net "P5E_CPU0_P1_RX_DN<13>")
	)
	(segment
		(start 357.388922 -289.797998)
		(end 357.41991 -289.780218)
		(width 0.1143)
		(layer "In11.Cu")
		(net "P5E_CPU0_P1_RX_DN<13>")
	)
	(segment
		(start 357.105712 -295.62298)
		(end 357.105712 -295.145968)
		(width 0.1143)
		(layer "In11.Cu")
		(net "P5E_CPU0_P1_RX_DN<13>")
	)
	(segment
		(start 374.931686 -355.3206)
		(end 377.210066 -349.819976)
		(width 0.14224)
		(layer "In11.Cu")
		(net "P5E_CPU0_P1_RX_DN<13>")
	)
	(segment
		(start 357.349044 -289.821366)
		(end 357.38562 -289.80003)
		(width 0.1143)
		(layer "In11.Cu")
		(net "P5E_CPU0_P1_RX_DN<13>")
	)
	(segment
		(start 357.356664 -289.135058)
		(end 357.355902 -289.13455)
		(width 0.1143)
		(layer "In11.Cu")
		(net "P5E_CPU0_P1_RX_DN<13>")
	)
	(segment
		(start 357.381556 -292.389814)
		(end 357.380286 -292.389052)
		(width 0.1143)
		(layer "In11.Cu")
		(net "P5E_CPU0_P1_RX_DN<13>")
	)
	(segment
		(start 351.918778 -393.69238)
		(end 352.272092 -393.787376)
		(width 0.14224)
		(layer "In11.Cu")
		(net "P5E_CPU0_P1_RX_DN<13>")
	)
	(segment
		(start 353.78644 -388.071868)
		(end 354.010468 -387.708902)
		(width 0.14224)
		(layer "In11.Cu")
		(net "P5E_CPU0_P1_RX_DN<13>")
	)
	(segment
		(start 354.602796 -386.749036)
		(end 354.60305 -386.749036)
		(width 0.14224)
		(layer "In11.Cu")
		(net "P5E_CPU0_P1_RX_DN<13>")
	)
	(segment
		(start 359.38587 -304.254154)
		(end 357.059992 -298.638722)
		(width 0.14224)
		(layer "In11.Cu")
		(net "P5E_CPU0_P1_RX_DN<13>")
	)
	(segment
		(start 357.387144 -290.77285)
		(end 357.349044 -290.750498)
		(width 0.1143)
		(layer "In11.Cu")
		(net "P5E_CPU0_P1_RX_DN<13>")
	)
	(segment
		(start 357.388922 -293.038022)
		(end 357.391462 -293.036498)
		(width 0.1143)
		(layer "In11.Cu")
		(net "P5E_CPU0_P1_RX_DN<13>")
	)
	(segment
		(start 357.369872 -294.002714)
		(end 357.35006 -293.991284)
		(width 0.1143)
		(layer "In11.Cu")
		(net "P5E_CPU0_P1_RX_DN<13>")
	)
	(segment
		(start 357.38816 -281.6987)
		(end 357.41991 -281.680412)
		(width 0.1143)
		(layer "In11.Cu")
		(net "P5E_CPU0_P1_RX_DN<13>")
	)
	(segment
		(start 357.38816 -284.938724)
		(end 357.41991 -284.920436)
		(width 0.1143)
		(layer "In11.Cu")
		(net "P5E_CPU0_P1_RX_DN<13>")
	)
	(segment
		(start 357.398066 -293.032688)
		(end 357.39959 -293.031926)
		(width 0.1143)
		(layer "In11.Cu")
		(net "P5E_CPU0_P1_RX_DN<13>")
	)
	(segment
		(start 357.39959 -293.031926)
		(end 357.41991 -293.020242)
		(width 0.1143)
		(layer "In11.Cu")
		(net "P5E_CPU0_P1_RX_DN<13>")
	)
	(segment
		(start 353.417886 -388.668514)
		(end 353.373436 -388.479792)
		(width 0.14224)
		(layer "In11.Cu")
		(net "P5E_CPU0_P1_RX_DN<13>")
	)
	(segment
		(start 357.379524 -292.388544)
		(end 357.378508 -292.388036)
		(width 0.1143)
		(layer "In11.Cu")
		(net "P5E_CPU0_P1_RX_DN<13>")
	)
	(segment
		(start 359.123488 -376.89409)
		(end 359.117392 -376.887994)
		(width 0.14224)
		(layer "In11.Cu")
		(net "P5E_CPU0_P1_RX_DN<13>")
	)
	(segment
		(start 377.21032 -349.819722)
		(end 377.21032 -339.217)
		(width 0.14224)
		(layer "In11.Cu")
		(net "P5E_CPU0_P1_RX_DN<13>")
	)
	(segment
		(start 353.965764 -387.52018)
		(end 354.190046 -387.156706)
		(width 0.14224)
		(layer "In11.Cu")
		(net "P5E_CPU0_P1_RX_DN<13>")
	)
	(segment
		(start 364.948216 -312.578242)
		(end 359.38587 -304.254154)
		(width 0.14224)
		(layer "In11.Cu")
		(net "P5E_CPU0_P1_RX_DN<13>")
	)
	(segment
		(start 357.38816 -289.153346)
		(end 357.387144 -289.152838)
		(width 0.1143)
		(layer "In11.Cu")
		(net "P5E_CPU0_P1_RX_DN<13>")
	)
	(segment
		(start 357.349044 -283.341572)
		(end 357.38816 -283.318712)
		(width 0.1143)
		(layer "In11.Cu")
		(net "P5E_CPU0_P1_RX_DN<13>")
	)
	(segment
		(start 357.387144 -289.799014)
		(end 357.38816 -289.798506)
		(width 0.1143)
		(layer "In11.Cu")
		(net "P5E_CPU0_P1_RX_DN<13>")
	)
	(segment
		(start 357.38816 -291.418518)
		(end 357.388922 -291.41801)
		(width 0.1143)
		(layer "In11.Cu")
		(net "P5E_CPU0_P1_RX_DN<13>")
	)
	(segment
		(start 357.372666 -293.047166)
		(end 357.38816 -293.03853)
		(width 0.1143)
		(layer "In11.Cu")
		(net "P5E_CPU0_P1_RX_DN<13>")
	)
	(segment
		(start 357.439722 -292.425882)
		(end 357.41991 -292.411658)
		(width 0.1143)
		(layer "In11.Cu")
		(net "P5E_CPU0_P1_RX_DN<13>")
	)
	(segment
		(start 354.378768 -387.112002)
		(end 354.379022 -387.111748)
		(width 0.14224)
		(layer "In11.Cu")
		(net "P5E_CPU0_P1_RX_DN<13>")
	)
	(segment
		(start 357.373174 -294.004746)
		(end 357.372158 -294.004238)
		(width 0.1143)
		(layer "In11.Cu")
		(net "P5E_CPU0_P1_RX_DN<13>")
	)
	(segment
		(start 357.387144 -292.392862)
		(end 357.381556 -292.389814)
		(width 0.1143)
		(layer "In11.Cu")
		(net "P5E_CPU0_P1_RX_DN<13>")
	)
	(segment
		(start 357.349044 -288.201354)
		(end 357.368602 -288.189924)
		(width 0.1143)
		(layer "In11.Cu")
		(net "P5E_CPU0_P1_RX_DN<13>")
	)
	(segment
		(start 354.558346 -386.560314)
		(end 354.782628 -386.19684)
		(width 0.14224)
		(layer "In11.Cu")
		(net "P5E_CPU0_P1_RX_DN<13>")
	)
	(segment
		(start 354.010468 -387.708902)
		(end 353.965764 -387.52018)
		(width 0.14224)
		(layer "In11.Cu")
		(net "P5E_CPU0_P1_RX_DN<13>")
	)
	(segment
		(start 353.597464 -388.116572)
		(end 353.78644 -388.071868)
		(width 0.14224)
		(layer "In11.Cu")
		(net "P5E_CPU0_P1_RX_DN<13>")
	)
	(segment
		(start 357.349044 -280.101548)
		(end 357.38816 -280.078688)
		(width 0.1143)
		(layer "In11.Cu")
		(net "P5E_CPU0_P1_RX_DN<13>")
	)
	(segment
		(start 357.38816 -292.39337)
		(end 357.387144 -292.392862)
		(width 0.1143)
		(layer "In11.Cu")
		(net "P5E_CPU0_P1_RX_DN<13>")
	)
	(segment
		(start 357.38816 -290.773358)
		(end 357.387144 -290.77285)
		(width 0.1143)
		(layer "In11.Cu")
		(net "P5E_CPU0_P1_RX_DN<13>")
	)
	(segment
		(start 357.407972 -288.167064)
		(end 357.422196 -288.158428)
		(width 0.1143)
		(layer "In11.Cu")
		(net "P5E_CPU0_P1_RX_DN<13>")
	)
	(segment
		(start 357.38816 -289.798506)
		(end 357.388922 -289.797998)
		(width 0.1143)
		(layer "In11.Cu")
		(net "P5E_CPU0_P1_RX_DN<13>")
	)
	(segment
		(start 354.379022 -387.112002)
		(end 354.378768 -387.112002)
		(width 0.14224)
		(layer "In11.Cu")
		(net "P5E_CPU0_P1_RX_DN<13>")
	)
	(segment
		(start 357.575612 -287.856168)
		(end 357.575866 -287.856422)
		(width 0.1143)
		(layer "In11.Cu")
		(net "P5E_CPU0_P1_RX_DN<13>")
	)
	(segment
		(start 357.38816 -293.03853)
		(end 357.388922 -293.038022)
		(width 0.1143)
		(layer "In11.Cu")
		(net "P5E_CPU0_P1_RX_DN<13>")
	)
	(segment
		(start 357.391462 -293.036498)
		(end 357.394764 -293.03472)
		(width 0.1143)
		(layer "In11.Cu")
		(net "P5E_CPU0_P1_RX_DN<13>")
	)
	(segment
		(start 357.41991 -281.071828)
		(end 357.38816 -281.05354)
		(width 0.1143)
		(layer "In11.Cu")
		(net "P5E_CPU0_P1_RX_DN<13>")
	)
	(segment
		(start 372.010432 -321.183)
		(end 364.948216 -312.578242)
		(width 0.14224)
		(layer "In11.Cu")
		(net "P5E_CPU0_P1_RX_DN<13>")
	)
	(segment
		(start 357.387144 -289.152838)
		(end 357.384604 -289.151314)
		(width 0.1143)
		(layer "In11.Cu")
		(net "P5E_CPU0_P1_RX_DN<13>")
	)
	(segment
		(start 357.38816 -281.05354)
		(end 357.349044 -281.03068)
		(width 0.1143)
		(layer "In11.Cu")
		(net "P5E_CPU0_P1_RX_DN<13>")
	)
	(segment
		(start 357.41991 -282.69184)
		(end 357.38816 -282.673552)
		(width 0.1143)
		(layer "In11.Cu")
		(net "P5E_CPU0_P1_RX_DN<13>")
	)
	(segment
		(start 357.418894 -286.540956)
		(end 357.421688 -286.538924)
		(width 0.1143)
		(layer "In11.Cu")
		(net "P5E_CPU0_P1_RX_DN<13>")
	)
	(segment
		(start 352.447352 -390.241028)
		(end 353.417886 -388.668514)
		(width 0.14224)
		(layer "In11.Cu")
		(net "P5E_CPU0_P1_RX_DN<13>")
	)
	(segment
		(start 357.368602 -288.189924)
		(end 357.407972 -288.167064)
		(width 0.1143)
		(layer "In11.Cu")
		(net "P5E_CPU0_P1_RX_DN<13>")
	)
	(segment
		(start 352.394266 -393.716764)
		(end 352.394266 -393.545822)
		(width 0.14224)
		(layer "In11.Cu")
		(net "P5E_CPU0_P1_RX_DN<13>")
	)
	(segment
		(start 354.379022 -387.111748)
		(end 354.602796 -386.749036)
		(width 0.14224)
		(layer "In11.Cu")
		(net "P5E_CPU0_P1_RX_DN<13>")
	)
	(segment
		(start 357.111808 -279.028906)
		(end 357.029004 -278.946102)
		(width 0.1143)
		(layer "In11.Cu")
		(net "P5E_CPU0_P1_RX_DN<13>")
	)
	(arc
		(start 357.348282 -287.51657)
		(mid 357.169982 -287.310635)
		(end 357.105712 -287.045908)
		(width 0.1143)
		(layer "In11.Cu")
		(net "P5E_CPU0_P1_RX_DN<13>")
	)
	(arc
		(start 357.41991 -281.680412)
		(mid 357.571499 -281.37612)
		(end 357.41991 -281.071828)
		(width 0.1143)
		(layer "In11.Cu")
		(net "P5E_CPU0_P1_RX_DN<13>")
	)
	(arc
		(start 357.421688 -286.538924)
		(mid 357.535095 -286.406035)
		(end 357.575866 -286.236156)
		(width 0.1143)
		(layer "In11.Cu")
		(net "P5E_CPU0_P1_RX_DN<13>")
	)
	(arc
		(start 357.41991 -291.40023)
		(mid 357.570295 -291.095938)
		(end 357.41991 -290.791646)
		(width 0.1143)
		(layer "In11.Cu")
		(net "P5E_CPU0_P1_RX_DN<13>")
	)
	(arc
		(start 357.422196 -288.158428)
		(mid 357.535082 -288.025657)
		(end 357.575612 -287.856168)
		(width 0.1143)
		(layer "In11.Cu")
		(net "P5E_CPU0_P1_RX_DN<13>")
	)
	(arc
		(start 357.349044 -294.681402)
		(mid 357.349425 -294.681148)
		(end 357.349806 -294.680894)
		(width 0.1143)
		(layer "In11.Cu")
		(net "P5E_CPU0_P1_RX_DN<13>")
	)
	(arc
		(start 357.349044 -279.410668)
		(mid 357.197057 -279.25416)
		(end 357.115618 -279.051766)
		(width 0.1143)
		(layer "In11.Cu")
		(net "P5E_CPU0_P1_RX_DN<13>")
	)
	(arc
		(start 357.575866 -287.854136)
		(mid 357.549485 -287.720174)
		(end 357.474266 -287.606232)
		(width 0.1143)
		(layer "In11.Cu")
		(net "P5E_CPU0_P1_RX_DN<13>")
	)
	(arc
		(start 359.117392 -376.887994)
		(mid 359.116621 -376.829068)
		(end 359.116376 -376.770138)
		(width 0.14224)
		(layer "In11.Cu")
		(net "P5E_CPU0_P1_RX_DN<13>")
	)
	(arc
		(start 357.349044 -282.650692)
		(mid 357.105717 -282.186126)
		(end 357.349044 -281.72156)
		(width 0.1143)
		(layer "In11.Cu")
		(net "P5E_CPU0_P1_RX_DN<13>")
	)
	(arc
		(start 369.107974 -364.03661)
		(mid 372.449075 -359.965408)
		(end 374.931686 -355.3206)
		(width 0.14224)
		(layer "In11.Cu")
		(net "P5E_CPU0_P1_RX_DN<13>")
	)
	(arc
		(start 352.386138 -390.455912)
		(mid 352.40182 -390.344222)
		(end 352.447352 -390.241028)
		(width 0.14224)
		(layer "In11.Cu")
		(net "P5E_CPU0_P1_RX_DN<13>")
	)
	(arc
		(start 357.41991 -283.300424)
		(mid 357.571499 -282.996132)
		(end 357.41991 -282.69184)
		(width 0.1143)
		(layer "In11.Cu")
		(net "P5E_CPU0_P1_RX_DN<13>")
	)
	(arc
		(start 357.349044 -281.03068)
		(mid 357.105717 -280.566114)
		(end 357.349044 -280.101548)
		(width 0.1143)
		(layer "In11.Cu")
		(net "P5E_CPU0_P1_RX_DN<13>")
	)
	(arc
		(start 357.349044 -284.270704)
		(mid 357.105717 -283.806138)
		(end 357.349044 -283.341572)
		(width 0.1143)
		(layer "In11.Cu")
		(net "P5E_CPU0_P1_RX_DN<13>")
	)
	(arc
		(start 357.105712 -295.145968)
		(mid 357.170227 -294.883749)
		(end 357.349044 -294.681402)
		(width 0.1143)
		(layer "In11.Cu")
		(net "P5E_CPU0_P1_RX_DN<13>")
	)
	(arc
		(start 357.410004 -294.646096)
		(mid 357.58842 -294.335852)
		(end 357.40975 -294.025828)
		(width 0.1143)
		(layer "In11.Cu")
		(net "P5E_CPU0_P1_RX_DN<13>")
	)
	(arc
		(start 357.349044 -290.750498)
		(mid 357.105717 -290.285932)
		(end 357.349044 -289.821366)
		(width 0.1143)
		(layer "In11.Cu")
		(net "P5E_CPU0_P1_RX_DN<13>")
	)
	(arc
		(start 357.35006 -293.991284)
		(mid 357.10578 -293.527329)
		(end 357.347774 -293.062152)
		(width 0.1143)
		(layer "In11.Cu")
		(net "P5E_CPU0_P1_RX_DN<13>")
	)
	(arc
		(start 357.575866 -286.236156)
		(mid 357.531795 -286.06662)
		(end 357.41991 -285.931864)
		(width 0.1143)
		(layer "In11.Cu")
		(net "P5E_CPU0_P1_RX_DN<13>")
	)
	(arc
		(start 357.349044 -289.130486)
		(mid 357.105717 -288.66592)
		(end 357.349044 -288.201354)
		(width 0.1143)
		(layer "In11.Cu")
		(net "P5E_CPU0_P1_RX_DN<13>")
	)
	(arc
		(start 357.115618 -279.051766)
		(mid 357.113595 -279.040356)
		(end 357.111808 -279.028906)
		(width 0.1143)
		(layer "In11.Cu")
		(net "P5E_CPU0_P1_RX_DN<13>")
	)
	(arc
		(start 359.104438 -379.457204)
		(mid 359.11863 -379.425131)
		(end 359.123488 -379.390402)
		(width 0.14224)
		(layer "In11.Cu")
		(net "P5E_CPU0_P1_RX_DN<13>")
	)
	(arc
		(start 359.116376 -376.770138)
		(mid 359.620255 -374.236967)
		(end 361.055158 -372.089426)
		(width 0.14224)
		(layer "In11.Cu")
		(net "P5E_CPU0_P1_RX_DN<13>")
	)
	(arc
		(start 357.439722 -289.765994)
		(mid 357.588436 -289.475926)
		(end 357.439722 -289.185858)
		(width 0.1143)
		(layer "In11.Cu")
		(net "P5E_CPU0_P1_RX_DN<13>")
	)
	(arc
		(start 357.41991 -284.920436)
		(mid 357.570295 -284.616144)
		(end 357.41991 -284.311852)
		(width 0.1143)
		(layer "In11.Cu")
		(net "P5E_CPU0_P1_RX_DN<13>")
	)
	(arc
		(start 357.41991 -280.0604)
		(mid 357.571499 -279.756108)
		(end 357.41991 -279.451816)
		(width 0.1143)
		(layer "In11.Cu")
		(net "P5E_CPU0_P1_RX_DN<13>")
	)
	(arc
		(start 357.439722 -293.006018)
		(mid 357.588436 -292.71595)
		(end 357.439722 -292.425882)
		(width 0.1143)
		(layer "In11.Cu")
		(net "P5E_CPU0_P1_RX_DN<13>")
	)
	(arc
		(start 357.349044 -292.37051)
		(mid 357.105717 -291.905944)
		(end 357.349044 -291.441378)
		(width 0.1143)
		(layer "In11.Cu")
		(net "P5E_CPU0_P1_RX_DN<13>")
	)
	(arc
		(start 357.105712 -287.045908)
		(mid 357.170227 -286.783689)
		(end 357.349044 -286.581342)
		(width 0.1143)
		(layer "In11.Cu")
		(net "P5E_CPU0_P1_RX_DN<13>")
	)
	(arc
		(start 357.349044 -285.890716)
		(mid 357.105717 -285.42615)
		(end 357.349044 -284.961584)
		(width 0.1143)
		(layer "In11.Cu")
		(net "P5E_CPU0_P1_RX_DN<13>")
	)
	(segment
		(start 350.198182 -393.69238)
		(end 350.718882 -393.69238)
		(width 0.127)
		(layer "F.Cu")
		(net "P5E_CPU0_P1_RX_DN<12>")
	)
	(segment
		(start 354.847906 -274.630134)
		(end 354.381054 -274.896072)
		(width 0.12954)
		(layer "F.Cu")
		(net "P5E_CPU0_P1_RX_DN<12>")
	)
	(segment
		(start 351.194116 -393.716764)
		(end 351.194116 -393.545822)
		(width 0.14224)
		(layer "In11.Cu")
		(net "P5E_CPU0_P1_RX_DN<12>")
	)
	(segment
		(start 356.416864 -280.096976)
		(end 356.417626 -280.096468)
		(width 0.1143)
		(layer "In11.Cu")
		(net "P5E_CPU0_P1_RX_DN<12>")
	)
	(segment
		(start 356.448106 -281.05354)
		(end 356.44709 -281.053032)
		(width 0.1143)
		(layer "In11.Cu")
		(net "P5E_CPU0_P1_RX_DN<12>")
	)
	(segment
		(start 356.454964 -285.91764)
		(end 356.452424 -285.916116)
		(width 0.1143)
		(layer "In11.Cu")
		(net "P5E_CPU0_P1_RX_DN<12>")
	)
	(segment
		(start 376.244612 -349.586804)
		(end 376.244866 -349.58655)
		(width 0.14224)
		(layer "In11.Cu")
		(net "P5E_CPU0_P1_RX_DN<12>")
	)
	(segment
		(start 356.417118 -291.436552)
		(end 356.41788 -291.436044)
		(width 0.1143)
		(layer "In11.Cu")
		(net "P5E_CPU0_P1_RX_DN<12>")
	)
	(segment
		(start 356.439978 -284.288738)
		(end 356.40899 -284.270704)
		(width 0.1143)
		(layer "In11.Cu")
		(net "P5E_CPU0_P1_RX_DN<12>")
	)
	(segment
		(start 356.409498 -289.820858)
		(end 356.479856 -289.780218)
		(width 0.1143)
		(layer "In11.Cu")
		(net "P5E_CPU0_P1_RX_DN<12>")
	)
	(segment
		(start 356.450138 -294.014652)
		(end 356.448868 -294.01389)
		(width 0.1143)
		(layer "In11.Cu")
		(net "P5E_CPU0_P1_RX_DN<12>")
	)
	(segment
		(start 356.442772 -284.290516)
		(end 356.441502 -284.289754)
		(width 0.1143)
		(layer "In11.Cu")
		(net "P5E_CPU0_P1_RX_DN<12>")
	)
	(segment
		(start 356.451662 -289.155378)
		(end 356.450138 -289.154616)
		(width 0.1143)
		(layer "In11.Cu")
		(net "P5E_CPU0_P1_RX_DN<12>")
	)
	(segment
		(start 356.479856 -290.791646)
		(end 356.454964 -290.777422)
		(width 0.1143)
		(layer "In11.Cu")
		(net "P5E_CPU0_P1_RX_DN<12>")
	)
	(segment
		(start 356.442772 -279.43048)
		(end 356.441502 -279.429718)
		(width 0.1143)
		(layer "In11.Cu")
		(net "P5E_CPU0_P1_RX_DN<12>")
	)
	(segment
		(start 356.442772 -281.050492)
		(end 356.441502 -281.04973)
		(width 0.1143)
		(layer "In11.Cu")
		(net "P5E_CPU0_P1_RX_DN<12>")
	)
	(segment
		(start 355.658674 -380.265178)
		(end 355.658674 -376.642376)
		(width 0.14224)
		(layer "In11.Cu")
		(net "P5E_CPU0_P1_RX_DN<12>")
	)
	(segment
		(start 356.40899 -280.101548)
		(end 356.416864 -280.096976)
		(width 0.1143)
		(layer "In11.Cu")
		(net "P5E_CPU0_P1_RX_DN<12>")
	)
	(segment
		(start 356.448106 -282.673552)
		(end 356.44709 -282.673044)
		(width 0.1143)
		(layer "In11.Cu")
		(net "P5E_CPU0_P1_RX_DN<12>")
	)
	(segment
		(start 356.448106 -288.178494)
		(end 356.481634 -288.158936)
		(width 0.1143)
		(layer "In11.Cu")
		(net "P5E_CPU0_P1_RX_DN<12>")
	)
	(segment
		(start 373.957088 -355.10978)
		(end 376.244612 -349.586804)
		(width 0.14224)
		(layer "In11.Cu")
		(net "P5E_CPU0_P1_RX_DN<12>")
	)
	(segment
		(start 356.448868 -282.67406)
		(end 356.448106 -282.673552)
		(width 0.1143)
		(layer "In11.Cu")
		(net "P5E_CPU0_P1_RX_DN<12>")
	)
	(segment
		(start 356.448868 -285.914084)
		(end 356.448106 -285.913576)
		(width 0.1143)
		(layer "In11.Cu")
		(net "P5E_CPU0_P1_RX_DN<12>")
	)
	(segment
		(start 356.44709 -285.913068)
		(end 356.445566 -285.912052)
		(width 0.1143)
		(layer "In11.Cu")
		(net "P5E_CPU0_P1_RX_DN<12>")
	)
	(segment
		(start 356.451662 -290.77539)
		(end 356.450138 -290.774628)
		(width 0.1143)
		(layer "In11.Cu")
		(net "P5E_CPU0_P1_RX_DN<12>")
	)
	(segment
		(start 356.454964 -281.057604)
		(end 356.452424 -281.05608)
		(width 0.1143)
		(layer "In11.Cu")
		(net "P5E_CPU0_P1_RX_DN<12>")
	)
	(segment
		(start 356.452424 -284.296104)
		(end 356.451662 -284.295596)
		(width 0.1143)
		(layer "In11.Cu")
		(net "P5E_CPU0_P1_RX_DN<12>")
	)
	(segment
		(start 356.451662 -284.295596)
		(end 356.450138 -284.294834)
		(width 0.1143)
		(layer "In11.Cu")
		(net "P5E_CPU0_P1_RX_DN<12>")
	)
	(segment
		(start 356.44709 -277.813008)
		(end 356.445566 -277.811992)
		(width 0.1143)
		(layer "In11.Cu")
		(net "P5E_CPU0_P1_RX_DN<12>")
	)
	(segment
		(start 364.196122 -313.131454)
		(end 358.560116 -304.69713)
		(width 0.14224)
		(layer "In11.Cu")
		(net "P5E_CPU0_P1_RX_DN<12>")
	)
	(segment
		(start 356.40899 -288.201354)
		(end 356.448106 -288.178494)
		(width 0.1143)
		(layer "In11.Cu")
		(net "P5E_CPU0_P1_RX_DN<12>")
	)
	(segment
		(start 356.448106 -285.913576)
		(end 356.44709 -285.913068)
		(width 0.1143)
		(layer "In11.Cu")
		(net "P5E_CPU0_P1_RX_DN<12>")
	)
	(segment
		(start 356.417626 -280.096468)
		(end 356.467664 -280.067512)
		(width 0.1143)
		(layer "In11.Cu")
		(net "P5E_CPU0_P1_RX_DN<12>")
	)
	(segment
		(start 351.886012 -388.373874)
		(end 352.06051 -387.984238)
		(width 0.14224)
		(layer "In11.Cu")
		(net "P5E_CPU0_P1_RX_DN<12>")
	)
	(segment
		(start 356.448106 -289.153346)
		(end 356.44709 -289.152838)
		(width 0.1143)
		(layer "In11.Cu")
		(net "P5E_CPU0_P1_RX_DN<12>")
	)
	(segment
		(start 351.319084 -389.973566)
		(end 351.493582 -389.584184)
		(width 0.14224)
		(layer "In11.Cu")
		(net "P5E_CPU0_P1_RX_DN<12>")
	)
	(segment
		(start 356.445566 -294.660066)
		(end 356.44709 -294.65905)
		(width 0.1143)
		(layer "In11.Cu")
		(net "P5E_CPU0_P1_RX_DN<12>")
	)
	(segment
		(start 356.434136 -281.706828)
		(end 356.437438 -281.70505)
		(width 0.1143)
		(layer "In11.Cu")
		(net "P5E_CPU0_P1_RX_DN<12>")
	)
	(segment
		(start 356.40899 -281.72156)
		(end 356.434136 -281.706828)
		(width 0.1143)
		(layer "In11.Cu")
		(net "P5E_CPU0_P1_RX_DN<12>")
	)
	(segment
		(start 356.448868 -294.01389)
		(end 356.448106 -294.013382)
		(width 0.1143)
		(layer "In11.Cu")
		(net "P5E_CPU0_P1_RX_DN<12>")
	)
	(segment
		(start 356.452932 -281.695906)
		(end 356.453694 -281.695398)
		(width 0.1143)
		(layer "In11.Cu")
		(net "P5E_CPU0_P1_RX_DN<12>")
	)
	(segment
		(start 356.452424 -290.775898)
		(end 356.451662 -290.77539)
		(width 0.1143)
		(layer "In11.Cu")
		(net "P5E_CPU0_P1_RX_DN<12>")
	)
	(segment
		(start 356.448868 -289.153854)
		(end 356.448106 -289.153346)
		(width 0.1143)
		(layer "In11.Cu")
		(net "P5E_CPU0_P1_RX_DN<12>")
	)
	(segment
		(start 356.462838 -283.31033)
		(end 356.479856 -283.300424)
		(width 0.1143)
		(layer "In11.Cu")
		(net "P5E_CPU0_P1_RX_DN<12>")
	)
	(segment
		(start 356.445566 -291.420042)
		(end 356.44709 -291.419026)
		(width 0.1143)
		(layer "In11.Cu")
		(net "P5E_CPU0_P1_RX_DN<12>")
	)
	(segment
		(start 356.479094 -284.92069)
		(end 356.479856 -284.920182)
		(width 0.1143)
		(layer "In11.Cu")
		(net "P5E_CPU0_P1_RX_DN<12>")
	)
	(segment
		(start 351.954846 -388.554976)
		(end 351.9551 -388.554976)
		(width 0.14224)
		(layer "In11.Cu")
		(net "P5E_CPU0_P1_RX_DN<12>")
	)
	(segment
		(start 352.70313 -386.885688)
		(end 355.647498 -380.317248)
		(width 0.14224)
		(layer "In11.Cu")
		(net "P5E_CPU0_P1_RX_DN<12>")
	)
	(segment
		(start 356.454964 -294.017446)
		(end 356.452424 -294.015922)
		(width 0.1143)
		(layer "In11.Cu")
		(net "P5E_CPU0_P1_RX_DN<12>")
	)
	(segment
		(start 356.44709 -294.65905)
		(end 356.448106 -294.658542)
		(width 0.1143)
		(layer "In11.Cu")
		(net "P5E_CPU0_P1_RX_DN<12>")
	)
	(segment
		(start 356.479856 -281.071828)
		(end 356.454964 -281.057604)
		(width 0.1143)
		(layer "In11.Cu")
		(net "P5E_CPU0_P1_RX_DN<12>")
	)
	(segment
		(start 356.479856 -282.69184)
		(end 356.454964 -282.677616)
		(width 0.1143)
		(layer "In11.Cu")
		(net "P5E_CPU0_P1_RX_DN<12>")
	)
	(segment
		(start 356.448106 -281.6987)
		(end 356.448868 -281.698192)
		(width 0.1143)
		(layer "In11.Cu")
		(net "P5E_CPU0_P1_RX_DN<12>")
	)
	(segment
		(start 356.445566 -285.912052)
		(end 356.442772 -285.910528)
		(width 0.1143)
		(layer "In11.Cu")
		(net "P5E_CPU0_P1_RX_DN<12>")
	)
	(segment
		(start 356.41788 -291.436044)
		(end 356.433374 -291.427154)
		(width 0.1143)
		(layer "In11.Cu")
		(net "P5E_CPU0_P1_RX_DN<12>")
	)
	(segment
		(start 356.119938 -298.805854)
		(end 356.119938 -295.697148)
		(width 0.14224)
		(layer "In11.Cu")
		(net "P5E_CPU0_P1_RX_DN<12>")
	)
	(segment
		(start 354.7618 -274.978876)
		(end 354.678996 -274.896072)
		(width 0.1143)
		(layer "In11.Cu")
		(net "P5E_CPU0_P1_RX_DN<12>")
	)
	(segment
		(start 351.598992 -389.013446)
		(end 351.780602 -388.944358)
		(width 0.14224)
		(layer "In11.Cu")
		(net "P5E_CPU0_P1_RX_DN<12>")
	)
	(segment
		(start 356.451662 -281.696668)
		(end 356.452932 -281.695906)
		(width 0.1143)
		(layer "In11.Cu")
		(net "P5E_CPU0_P1_RX_DN<12>")
	)
	(segment
		(start 356.448106 -277.813516)
		(end 356.44709 -277.813008)
		(width 0.1143)
		(layer "In11.Cu")
		(net "P5E_CPU0_P1_RX_DN<12>")
	)
	(segment
		(start 356.45598 -281.694128)
		(end 356.45852 -281.692858)
		(width 0.1143)
		(layer "In11.Cu")
		(net "P5E_CPU0_P1_RX_DN<12>")
	)
	(segment
		(start 356.451662 -277.815548)
		(end 356.450138 -277.814786)
		(width 0.1143)
		(layer "In11.Cu")
		(net "P5E_CPU0_P1_RX_DN<12>")
	)
	(segment
		(start 352.703384 -386.885942)
		(end 352.70313 -386.885688)
		(width 0.14224)
		(layer "In11.Cu")
		(net "P5E_CPU0_P1_RX_DN<12>")
	)
	(segment
		(start 356.44709 -294.012874)
		(end 356.445566 -294.011858)
		(width 0.1143)
		(layer "In11.Cu")
		(net "P5E_CPU0_P1_RX_DN<12>")
	)
	(segment
		(start 356.40899 -291.441378)
		(end 356.417118 -291.436552)
		(width 0.1143)
		(layer "In11.Cu")
		(net "P5E_CPU0_P1_RX_DN<12>")
	)
	(segment
		(start 356.44709 -289.152838)
		(end 356.445566 -289.151822)
		(width 0.1143)
		(layer "In11.Cu")
		(net "P5E_CPU0_P1_RX_DN<12>")
	)
	(segment
		(start 356.44201 -294.662098)
		(end 356.443788 -294.661082)
		(width 0.1143)
		(layer "In11.Cu")
		(net "P5E_CPU0_P1_RX_DN<12>")
	)
	(segment
		(start 356.445566 -281.052016)
		(end 356.442772 -281.050492)
		(width 0.1143)
		(layer "In11.Cu")
		(net "P5E_CPU0_P1_RX_DN<12>")
	)
	(segment
		(start 356.454964 -289.15741)
		(end 356.452424 -289.155886)
		(width 0.1143)
		(layer "In11.Cu")
		(net "P5E_CPU0_P1_RX_DN<12>")
	)
	(segment
		(start 356.452424 -279.436068)
		(end 356.451662 -279.43556)
		(width 0.1143)
		(layer "In11.Cu")
		(net "P5E_CPU0_P1_RX_DN<12>")
	)
	(segment
		(start 356.450138 -291.417248)
		(end 356.479856 -291.40023)
		(width 0.1143)
		(layer "In11.Cu")
		(net "P5E_CPU0_P1_RX_DN<12>")
	)
	(segment
		(start 356.448106 -294.658542)
		(end 356.479856 -294.640254)
		(width 0.1143)
		(layer "In11.Cu")
		(net "P5E_CPU0_P1_RX_DN<12>")
	)
	(segment
		(start 356.445566 -282.672028)
		(end 356.442772 -282.670504)
		(width 0.1143)
		(layer "In11.Cu")
		(net "P5E_CPU0_P1_RX_DN<12>")
	)
	(segment
		(start 356.450138 -279.434798)
		(end 356.448868 -279.434036)
		(width 0.1143)
		(layer "In11.Cu")
		(net "P5E_CPU0_P1_RX_DN<12>")
	)
	(segment
		(start 355.038152 -275.383498)
		(end 354.999036 -275.360638)
		(width 0.1143)
		(layer "In11.Cu")
		(net "P5E_CPU0_P1_RX_DN<12>")
	)
	(segment
		(start 356.40899 -294.681402)
		(end 356.441248 -294.662606)
		(width 0.1143)
		(layer "In11.Cu")
		(net "P5E_CPU0_P1_RX_DN<12>")
	)
	(segment
		(start 356.442772 -282.670504)
		(end 356.441502 -282.669742)
		(width 0.1143)
		(layer "In11.Cu")
		(net "P5E_CPU0_P1_RX_DN<12>")
	)
	(segment
		(start 356.467664 -280.067512)
		(end 356.479856 -280.0604)
		(width 0.1143)
		(layer "In11.Cu")
		(net "P5E_CPU0_P1_RX_DN<12>")
	)
	(segment
		(start 356.44709 -281.699208)
		(end 356.448106 -281.6987)
		(width 0.1143)
		(layer "In11.Cu")
		(net "P5E_CPU0_P1_RX_DN<12>")
	)
	(segment
		(start 351.780602 -388.944358)
		(end 351.780348 -388.944358)
		(width 0.14224)
		(layer "In11.Cu")
		(net "P5E_CPU0_P1_RX_DN<12>")
	)
	(segment
		(start 356.479856 -277.831804)
		(end 356.454964 -277.81758)
		(width 0.1143)
		(layer "In11.Cu")
		(net "P5E_CPU0_P1_RX_DN<12>")
	)
	(segment
		(start 356.44455 -291.42055)
		(end 356.445566 -291.420042)
		(width 0.1143)
		(layer "In11.Cu")
		(net "P5E_CPU0_P1_RX_DN<12>")
	)
	(segment
		(start 356.441502 -279.429718)
		(end 356.439978 -279.428702)
		(width 0.1143)
		(layer "In11.Cu")
		(net "P5E_CPU0_P1_RX_DN<12>")
	)
	(segment
		(start 351.424494 -389.403082)
		(end 351.598992 -389.013446)
		(width 0.14224)
		(layer "In11.Cu")
		(net "P5E_CPU0_P1_RX_DN<12>")
	)
	(segment
		(start 356.40899 -286.581342)
		(end 356.448106 -286.558482)
		(width 0.1143)
		(layer "In11.Cu")
		(net "P5E_CPU0_P1_RX_DN<12>")
	)
	(segment
		(start 356.448106 -294.013382)
		(end 356.44709 -294.012874)
		(width 0.1143)
		(layer "In11.Cu")
		(net "P5E_CPU0_P1_RX_DN<12>")
	)
	(segment
		(start 356.438962 -291.423852)
		(end 356.44455 -291.42055)
		(width 0.1143)
		(layer "In11.Cu")
		(net "P5E_CPU0_P1_RX_DN<12>")
	)
	(segment
		(start 355.695758 -276.516084)
		(end 355.696012 -276.516084)
		(width 0.1143)
		(layer "In11.Cu")
		(net "P5E_CPU0_P1_RX_DN<12>")
	)
	(segment
		(start 352.41611 -387.525768)
		(end 352.416618 -387.525768)
		(width 0.14224)
		(layer "In11.Cu")
		(net "P5E_CPU0_P1_RX_DN<12>")
	)
	(segment
		(start 356.460298 -284.931612)
		(end 356.479094 -284.92069)
		(width 0.1143)
		(layer "In11.Cu")
		(net "P5E_CPU0_P1_RX_DN<12>")
	)
	(segment
		(start 356.445566 -289.151822)
		(end 356.40899 -289.130486)
		(width 0.1143)
		(layer "In11.Cu")
		(net "P5E_CPU0_P1_RX_DN<12>")
	)
	(segment
		(start 358.560116 -304.69713)
		(end 356.119938 -298.805854)
		(width 0.14224)
		(layer "In11.Cu")
		(net "P5E_CPU0_P1_RX_DN<12>")
	)
	(segment
		(start 356.438962 -281.704034)
		(end 356.44455 -281.700732)
		(width 0.1143)
		(layer "In11.Cu")
		(net "P5E_CPU0_P1_RX_DN<12>")
	)
	(segment
		(start 356.44709 -290.77285)
		(end 356.445566 -290.771834)
		(width 0.1143)
		(layer "In11.Cu")
		(net "P5E_CPU0_P1_RX_DN<12>")
	)
	(segment
		(start 376.244866 -339.30336)
		(end 375.147332 -333.195422)
		(width 0.14224)
		(layer "In11.Cu")
		(net "P5E_CPU0_P1_RX_DN<12>")
	)
	(segment
		(start 356.40899 -293.06139)
		(end 356.408736 -293.06139)
		(width 0.1143)
		(layer "In11.Cu")
		(net "P5E_CPU0_P1_RX_DN<12>")
	)
	(segment
		(start 356.441502 -284.289754)
		(end 356.439978 -284.288738)
		(width 0.1143)
		(layer "In11.Cu")
		(net "P5E_CPU0_P1_RX_DN<12>")
	)
	(segment
		(start 356.44455 -281.700732)
		(end 356.445566 -281.700224)
		(width 0.1143)
		(layer "In11.Cu")
		(net "P5E_CPU0_P1_RX_DN<12>")
	)
	(segment
		(start 356.008686 -277.02129)
		(end 355.978206 -277.00351)
		(width 0.1143)
		(layer "In11.Cu")
		(net "P5E_CPU0_P1_RX_DN<12>")
	)
	(segment
		(start 351.9551 -388.554976)
		(end 351.886012 -388.373874)
		(width 0.14224)
		(layer "In11.Cu")
		(net "P5E_CPU0_P1_RX_DN<12>")
	)
	(segment
		(start 356.40899 -284.961584)
		(end 356.460298 -284.931612)
		(width 0.1143)
		(layer "In11.Cu")
		(net "P5E_CPU0_P1_RX_DN<12>")
	)
	(segment
		(start 356.450138 -292.39464)
		(end 356.448868 -292.393878)
		(width 0.1143)
		(layer "In11.Cu")
		(net "P5E_CPU0_P1_RX_DN<12>")
	)
	(segment
		(start 356.027736 -375.751344)
		(end 368.495834 -363.283246)
		(width 0.14224)
		(layer "In11.Cu")
		(net "P5E_CPU0_P1_RX_DN<12>")
	)
	(segment
		(start 356.460806 -278.45131)
		(end 356.479856 -278.440134)
		(width 0.1143)
		(layer "In11.Cu")
		(net "P5E_CPU0_P1_RX_DN<12>")
	)
	(segment
		(start 352.24212 -387.91515)
		(end 352.241866 -387.914896)
		(width 0.14224)
		(layer "In11.Cu")
		(net "P5E_CPU0_P1_RX_DN<12>")
	)
	(segment
		(start 356.44709 -291.419026)
		(end 356.448106 -291.418518)
		(width 0.1143)
		(layer "In11.Cu")
		(net "P5E_CPU0_P1_RX_DN<12>")
	)
	(segment
		(start 356.450138 -290.774628)
		(end 356.448868 -290.773866)
		(width 0.1143)
		(layer "In11.Cu")
		(net "P5E_CPU0_P1_RX_DN<12>")
	)
	(segment
		(start 375.147586 -333.195168)
		(end 374.054624 -327.110852)
		(width 0.14224)
		(layer "In11.Cu")
		(net "P5E_CPU0_P1_RX_DN<12>")
	)
	(segment
		(start 356.479856 -294.03167)
		(end 356.454964 -294.017446)
		(width 0.1143)
		(layer "In11.Cu")
		(net "P5E_CPU0_P1_RX_DN<12>")
	)
	(segment
		(start 356.450138 -281.05481)
		(end 356.448868 -281.054048)
		(width 0.1143)
		(layer "In11.Cu")
		(net "P5E_CPU0_P1_RX_DN<12>")
	)
	(segment
		(start 356.165658 -295.62298)
		(end 356.165658 -295.145968)
		(width 0.1143)
		(layer "In11.Cu")
		(net "P5E_CPU0_P1_RX_DN<12>")
	)
	(segment
		(start 356.479856 -278.440134)
		(end 356.479856 -278.440388)
		(width 0.1143)
		(layer "In11.Cu")
		(net "P5E_CPU0_P1_RX_DN<12>")
	)
	(segment
		(start 356.408736 -293.06139)
		(end 356.409498 -293.060882)
		(width 0.1143)
		(layer "In11.Cu")
		(net "P5E_CPU0_P1_RX_DN<12>")
	)
	(segment
		(start 356.44709 -292.392862)
		(end 356.445566 -292.391846)
		(width 0.1143)
		(layer "In11.Cu")
		(net "P5E_CPU0_P1_RX_DN<12>")
	)
	(segment
		(start 356.450138 -281.69743)
		(end 356.451662 -281.696668)
		(width 0.1143)
		(layer "In11.Cu")
		(net "P5E_CPU0_P1_RX_DN<12>")
	)
	(segment
		(start 356.441502 -285.909766)
		(end 356.439978 -285.90875)
		(width 0.1143)
		(layer "In11.Cu")
		(net "P5E_CPU0_P1_RX_DN<12>")
	)
	(segment
		(start 356.479856 -284.920182)
		(end 356.479856 -284.920436)
		(width 0.1143)
		(layer "In11.Cu")
		(net "P5E_CPU0_P1_RX_DN<12>")
	)
	(segment
		(start 355.978206 -277.00351)
		(end 355.93909 -276.98065)
		(width 0.1143)
		(layer "In11.Cu")
		(net "P5E_CPU0_P1_RX_DN<12>")
	)
	(segment
		(start 356.479856 -289.171634)
		(end 356.454964 -289.15741)
		(width 0.1143)
		(layer "In11.Cu")
		(net "P5E_CPU0_P1_RX_DN<12>")
	)
	(segment
		(start 356.451662 -285.915608)
		(end 356.450138 -285.914846)
		(width 0.1143)
		(layer "In11.Cu")
		(net "P5E_CPU0_P1_RX_DN<12>")
	)
	(segment
		(start 356.439978 -281.048714)
		(end 356.40899 -281.03068)
		(width 0.1143)
		(layer "In11.Cu")
		(net "P5E_CPU0_P1_RX_DN<12>")
	)
	(segment
		(start 356.450138 -277.814786)
		(end 356.448868 -277.814024)
		(width 0.1143)
		(layer "In11.Cu")
		(net "P5E_CPU0_P1_RX_DN<12>")
	)
	(segment
		(start 356.452424 -294.015922)
		(end 356.451662 -294.015414)
		(width 0.1143)
		(layer "In11.Cu")
		(net "P5E_CPU0_P1_RX_DN<12>")
	)
	(segment
		(start 356.479856 -284.311852)
		(end 356.454964 -284.297628)
		(width 0.1143)
		(layer "In11.Cu")
		(net "P5E_CPU0_P1_RX_DN<12>")
	)
	(segment
		(start 352.522028 -386.95503)
		(end 352.703384 -386.885942)
		(width 0.14224)
		(layer "In11.Cu")
		(net "P5E_CPU0_P1_RX_DN<12>")
	)
	(segment
		(start 356.439978 -279.428702)
		(end 356.40899 -279.410668)
		(width 0.1143)
		(layer "In11.Cu")
		(net "P5E_CPU0_P1_RX_DN<12>")
	)
	(segment
		(start 356.454964 -284.297628)
		(end 356.452424 -284.296104)
		(width 0.1143)
		(layer "In11.Cu")
		(net "P5E_CPU0_P1_RX_DN<12>")
	)
	(segment
		(start 356.452424 -292.39591)
		(end 356.451662 -292.395402)
		(width 0.1143)
		(layer "In11.Cu")
		(net "P5E_CPU0_P1_RX_DN<12>")
	)
	(segment
		(start 356.44709 -282.673044)
		(end 356.445566 -282.672028)
		(width 0.1143)
		(layer "In11.Cu")
		(net "P5E_CPU0_P1_RX_DN<12>")
	)
	(segment
		(start 356.445566 -277.811992)
		(end 356.442772 -277.810468)
		(width 0.1143)
		(layer "In11.Cu")
		(net "P5E_CPU0_P1_RX_DN<12>")
	)
	(segment
		(start 356.445566 -292.391846)
		(end 356.40899 -292.37051)
		(width 0.1143)
		(layer "In11.Cu")
		(net "P5E_CPU0_P1_RX_DN<12>")
	)
	(segment
		(start 351.071942 -393.787376)
		(end 351.07245 -393.786868)
		(width 0.14224)
		(layer "In11.Cu")
		(net "P5E_CPU0_P1_RX_DN<12>")
	)
	(segment
		(start 376.244866 -349.58655)
		(end 376.244866 -339.30336)
		(width 0.14224)
		(layer "In11.Cu")
		(net "P5E_CPU0_P1_RX_DN<12>")
	)
	(segment
		(start 351.07245 -393.786868)
		(end 351.194116 -393.716764)
		(width 0.14224)
		(layer "In11.Cu")
		(net "P5E_CPU0_P1_RX_DN<12>")
	)
	(segment
		(start 356.434136 -291.426646)
		(end 356.437438 -291.424868)
		(width 0.1143)
		(layer "In11.Cu")
		(net "P5E_CPU0_P1_RX_DN<12>")
	)
	(segment
		(start 356.445566 -279.432004)
		(end 356.442772 -279.43048)
		(width 0.1143)
		(layer "In11.Cu")
		(net "P5E_CPU0_P1_RX_DN<12>")
	)
	(segment
		(start 356.452424 -281.05608)
		(end 356.451662 -281.055572)
		(width 0.1143)
		(layer "In11.Cu")
		(net "P5E_CPU0_P1_RX_DN<12>")
	)
	(segment
		(start 356.44709 -279.43302)
		(end 356.445566 -279.432004)
		(width 0.1143)
		(layer "In11.Cu")
		(net "P5E_CPU0_P1_RX_DN<12>")
	)
	(segment
		(start 356.434136 -278.466804)
		(end 356.460806 -278.45131)
		(width 0.1143)
		(layer "In11.Cu")
		(net "P5E_CPU0_P1_RX_DN<12>")
	)
	(segment
		(start 356.452424 -285.916116)
		(end 356.451662 -285.915608)
		(width 0.1143)
		(layer "In11.Cu")
		(net "P5E_CPU0_P1_RX_DN<12>")
	)
	(segment
		(start 356.441502 -277.809706)
		(end 356.439978 -277.80869)
		(width 0.1143)
		(layer "In11.Cu")
		(net "P5E_CPU0_P1_RX_DN<12>")
	)
	(segment
		(start 351.194116 -393.545822)
		(end 350.877124 -393.22883)
		(width 0.14224)
		(layer "In11.Cu")
		(net "P5E_CPU0_P1_RX_DN<12>")
	)
	(segment
		(start 371.226842 -321.698366)
		(end 364.196122 -313.131454)
		(width 0.14224)
		(layer "In11.Cu")
		(net "P5E_CPU0_P1_RX_DN<12>")
	)
	(segment
		(start 356.451662 -292.395402)
		(end 356.450138 -292.39464)
		(width 0.1143)
		(layer "In11.Cu")
		(net "P5E_CPU0_P1_RX_DN<12>")
	)
	(segment
		(start 356.479856 -292.411658)
		(end 356.454964 -292.397434)
		(width 0.1143)
		(layer "In11.Cu")
		(net "P5E_CPU0_P1_RX_DN<12>")
	)
	(segment
		(start 356.451662 -282.675584)
		(end 356.450138 -282.674822)
		(width 0.1143)
		(layer "In11.Cu")
		(net "P5E_CPU0_P1_RX_DN<12>")
	)
	(segment
		(start 352.416618 -387.525768)
		(end 352.34753 -387.344666)
		(width 0.14224)
		(layer "In11.Cu")
		(net "P5E_CPU0_P1_RX_DN<12>")
	)
	(segment
		(start 356.448868 -290.773866)
		(end 356.448106 -290.773358)
		(width 0.1143)
		(layer "In11.Cu")
		(net "P5E_CPU0_P1_RX_DN<12>")
	)
	(segment
		(start 356.442772 -277.810468)
		(end 356.441502 -277.809706)
		(width 0.1143)
		(layer "In11.Cu")
		(net "P5E_CPU0_P1_RX_DN<12>")
	)
	(segment
		(start 356.454964 -292.397434)
		(end 356.452424 -292.39591)
		(width 0.1143)
		(layer "In11.Cu")
		(net "P5E_CPU0_P1_RX_DN<12>")
	)
	(segment
		(start 356.40899 -283.341572)
		(end 356.462838 -283.31033)
		(width 0.1143)
		(layer "In11.Cu")
		(net "P5E_CPU0_P1_RX_DN<12>")
	)
	(segment
		(start 356.450138 -284.294834)
		(end 356.448868 -284.294072)
		(width 0.1143)
		(layer "In11.Cu")
		(net "P5E_CPU0_P1_RX_DN<12>")
	)
	(segment
		(start 356.448106 -284.293564)
		(end 356.44709 -284.293056)
		(width 0.1143)
		(layer "In11.Cu")
		(net "P5E_CPU0_P1_RX_DN<12>")
	)
	(segment
		(start 374.053862 -327.107042)
		(end 371.226842 -321.698366)
		(width 0.14224)
		(layer "In11.Cu")
		(net "P5E_CPU0_P1_RX_DN<12>")
	)
	(segment
		(start 351.185988 -392.31316)
		(end 351.185988 -390.59612)
		(width 0.14224)
		(layer "In11.Cu")
		(net "P5E_CPU0_P1_RX_DN<12>")
	)
	(segment
		(start 356.40899 -289.821366)
		(end 356.408736 -289.821366)
		(width 0.1143)
		(layer "In11.Cu")
		(net "P5E_CPU0_P1_RX_DN<12>")
	)
	(segment
		(start 356.442772 -285.910528)
		(end 356.441502 -285.909766)
		(width 0.1143)
		(layer "In11.Cu")
		(net "P5E_CPU0_P1_RX_DN<12>")
	)
	(segment
		(start 356.439978 -285.90875)
		(end 356.40899 -285.890716)
		(width 0.1143)
		(layer "In11.Cu")
		(net "P5E_CPU0_P1_RX_DN<12>")
	)
	(segment
		(start 350.88195 -392.616944)
		(end 351.185988 -392.31316)
		(width 0.14224)
		(layer "In11.Cu")
		(net "P5E_CPU0_P1_RX_DN<12>")
	)
	(segment
		(start 354.678996 -274.896072)
		(end 354.381054 -274.896072)
		(width 0.1143)
		(layer "In11.Cu")
		(net "P5E_CPU0_P1_RX_DN<12>")
	)
	(segment
		(start 356.409498 -293.060882)
		(end 356.479856 -293.020242)
		(width 0.1143)
		(layer "In11.Cu")
		(net "P5E_CPU0_P1_RX_DN<12>")
	)
	(segment
		(start 350.718882 -393.69238)
		(end 351.071942 -393.787376)
		(width 0.14224)
		(layer "In11.Cu")
		(net "P5E_CPU0_P1_RX_DN<12>")
	)
	(segment
		(start 356.443788 -294.661082)
		(end 356.44455 -294.660574)
		(width 0.1143)
		(layer "In11.Cu")
		(net "P5E_CPU0_P1_RX_DN<12>")
	)
	(segment
		(start 356.433374 -291.427154)
		(end 356.434136 -291.426646)
		(width 0.1143)
		(layer "In11.Cu")
		(net "P5E_CPU0_P1_RX_DN<12>")
	)
	(segment
		(start 356.451662 -281.055572)
		(end 356.450138 -281.05481)
		(width 0.1143)
		(layer "In11.Cu")
		(net "P5E_CPU0_P1_RX_DN<12>")
	)
	(segment
		(start 356.441248 -294.662606)
		(end 356.44201 -294.662098)
		(width 0.1143)
		(layer "In11.Cu")
		(net "P5E_CPU0_P1_RX_DN<12>")
	)
	(segment
		(start 356.450138 -282.674822)
		(end 356.448868 -282.67406)
		(width 0.1143)
		(layer "In11.Cu")
		(net "P5E_CPU0_P1_RX_DN<12>")
	)
	(segment
		(start 356.448868 -292.393878)
		(end 356.448106 -292.39337)
		(width 0.1143)
		(layer "In11.Cu")
		(net "P5E_CPU0_P1_RX_DN<12>")
	)
	(segment
		(start 356.44455 -294.660574)
		(end 356.445566 -294.660066)
		(width 0.1143)
		(layer "In11.Cu")
		(net "P5E_CPU0_P1_RX_DN<12>")
	)
	(segment
		(start 356.441502 -282.669742)
		(end 356.439978 -282.668726)
		(width 0.1143)
		(layer "In11.Cu")
		(net "P5E_CPU0_P1_RX_DN<12>")
	)
	(segment
		(start 356.445566 -290.771834)
		(end 356.40899 -290.750498)
		(width 0.1143)
		(layer "In11.Cu")
		(net "P5E_CPU0_P1_RX_DN<12>")
	)
	(segment
		(start 356.445566 -284.29204)
		(end 356.442772 -284.290516)
		(width 0.1143)
		(layer "In11.Cu")
		(net "P5E_CPU0_P1_RX_DN<12>")
	)
	(segment
		(start 351.780348 -388.944358)
		(end 351.954846 -388.554976)
		(width 0.14224)
		(layer "In11.Cu")
		(net "P5E_CPU0_P1_RX_DN<12>")
	)
	(segment
		(start 356.452424 -282.676092)
		(end 356.451662 -282.675584)
		(width 0.1143)
		(layer "In11.Cu")
		(net "P5E_CPU0_P1_RX_DN<12>")
	)
	(segment
		(start 356.437438 -291.424868)
		(end 356.438962 -291.423852)
		(width 0.1143)
		(layer "In11.Cu")
		(net "P5E_CPU0_P1_RX_DN<12>")
	)
	(segment
		(start 356.45852 -281.692858)
		(end 356.479856 -281.680412)
		(width 0.1143)
		(layer "In11.Cu")
		(net "P5E_CPU0_P1_RX_DN<12>")
	)
	(segment
		(start 356.479856 -285.931864)
		(end 356.454964 -285.91764)
		(width 0.1143)
		(layer "In11.Cu")
		(net "P5E_CPU0_P1_RX_DN<12>")
	)
	(segment
		(start 374.054624 -327.110852)
		(end 374.053862 -327.107042)
		(width 0.14224)
		(layer "In11.Cu")
		(net "P5E_CPU0_P1_RX_DN<12>")
	)
	(segment
		(start 356.119938 -295.6687)
		(end 356.165658 -295.62298)
		(width 0.1143)
		(layer "In11.Cu")
		(net "P5E_CPU0_P1_RX_DN<12>")
	)
	(segment
		(start 356.454964 -277.81758)
		(end 356.452424 -277.816056)
		(width 0.1143)
		(layer "In11.Cu")
		(net "P5E_CPU0_P1_RX_DN<12>")
	)
	(segment
		(start 352.34753 -387.344666)
		(end 352.522028 -386.95503)
		(width 0.14224)
		(layer "In11.Cu")
		(net "P5E_CPU0_P1_RX_DN<12>")
	)
	(segment
		(start 356.437438 -281.70505)
		(end 356.438962 -281.704034)
		(width 0.1143)
		(layer "In11.Cu")
		(net "P5E_CPU0_P1_RX_DN<12>")
	)
	(segment
		(start 356.448868 -281.054048)
		(end 356.448106 -281.05354)
		(width 0.1143)
		(layer "In11.Cu")
		(net "P5E_CPU0_P1_RX_DN<12>")
	)
	(segment
		(start 356.479856 -279.451816)
		(end 356.454964 -279.437592)
		(width 0.1143)
		(layer "In11.Cu")
		(net "P5E_CPU0_P1_RX_DN<12>")
	)
	(segment
		(start 356.452424 -277.816056)
		(end 356.451662 -277.815548)
		(width 0.1143)
		(layer "In11.Cu")
		(net "P5E_CPU0_P1_RX_DN<12>")
	)
	(segment
		(start 356.454964 -279.437592)
		(end 356.452424 -279.436068)
		(width 0.1143)
		(layer "In11.Cu")
		(net "P5E_CPU0_P1_RX_DN<12>")
	)
	(segment
		(start 356.450138 -289.154616)
		(end 356.448868 -289.153854)
		(width 0.1143)
		(layer "In11.Cu")
		(net "P5E_CPU0_P1_RX_DN<12>")
	)
	(segment
		(start 356.479856 -287.551876)
		(end 356.448106 -287.533588)
		(width 0.1143)
		(layer "In11.Cu")
		(net "P5E_CPU0_P1_RX_DN<12>")
	)
	(segment
		(start 356.439978 -277.80869)
		(end 356.40899 -277.790656)
		(width 0.1143)
		(layer "In11.Cu")
		(net "P5E_CPU0_P1_RX_DN<12>")
	)
	(segment
		(start 356.453694 -281.695398)
		(end 356.45471 -281.69489)
		(width 0.1143)
		(layer "In11.Cu")
		(net "P5E_CPU0_P1_RX_DN<12>")
	)
	(segment
		(start 356.445566 -281.700224)
		(end 356.44709 -281.699208)
		(width 0.1143)
		(layer "In11.Cu")
		(net "P5E_CPU0_P1_RX_DN<12>")
	)
	(segment
		(start 356.119938 -295.697148)
		(end 356.119938 -295.6687)
		(width 0.1143)
		(layer "In11.Cu")
		(net "P5E_CPU0_P1_RX_DN<12>")
	)
	(segment
		(start 356.439978 -282.668726)
		(end 356.40899 -282.650692)
		(width 0.1143)
		(layer "In11.Cu")
		(net "P5E_CPU0_P1_RX_DN<12>")
	)
	(segment
		(start 356.448868 -281.698192)
		(end 356.450138 -281.69743)
		(width 0.1143)
		(layer "In11.Cu")
		(net "P5E_CPU0_P1_RX_DN<12>")
	)
	(segment
		(start 352.06051 -387.984238)
		(end 352.24212 -387.91515)
		(width 0.14224)
		(layer "In11.Cu")
		(net "P5E_CPU0_P1_RX_DN<12>")
	)
	(segment
		(start 356.40899 -278.481536)
		(end 356.434136 -278.466804)
		(width 0.1143)
		(layer "In11.Cu")
		(net "P5E_CPU0_P1_RX_DN<12>")
	)
	(segment
		(start 375.147332 -333.195422)
		(end 375.147586 -333.195168)
		(width 0.14224)
		(layer "In11.Cu")
		(net "P5E_CPU0_P1_RX_DN<12>")
	)
	(segment
		(start 356.452424 -289.155886)
		(end 356.451662 -289.155378)
		(width 0.1143)
		(layer "In11.Cu")
		(net "P5E_CPU0_P1_RX_DN<12>")
	)
	(segment
		(start 356.448868 -277.814024)
		(end 356.448106 -277.813516)
		(width 0.1143)
		(layer "In11.Cu")
		(net "P5E_CPU0_P1_RX_DN<12>")
	)
	(segment
		(start 352.241866 -387.914896)
		(end 352.41611 -387.525768)
		(width 0.14224)
		(layer "In11.Cu")
		(net "P5E_CPU0_P1_RX_DN<12>")
	)
	(segment
		(start 356.448106 -291.418518)
		(end 356.448868 -291.41801)
		(width 0.1143)
		(layer "In11.Cu")
		(net "P5E_CPU0_P1_RX_DN<12>")
	)
	(segment
		(start 356.450138 -285.914846)
		(end 356.448868 -285.914084)
		(width 0.1143)
		(layer "In11.Cu")
		(net "P5E_CPU0_P1_RX_DN<12>")
	)
	(segment
		(start 356.448868 -284.294072)
		(end 356.448106 -284.293564)
		(width 0.1143)
		(layer "In11.Cu")
		(net "P5E_CPU0_P1_RX_DN<12>")
	)
	(segment
		(start 356.451662 -294.015414)
		(end 356.450138 -294.014652)
		(width 0.1143)
		(layer "In11.Cu")
		(net "P5E_CPU0_P1_RX_DN<12>")
	)
	(segment
		(start 356.408736 -289.821366)
		(end 356.409498 -289.820858)
		(width 0.1143)
		(layer "In11.Cu")
		(net "P5E_CPU0_P1_RX_DN<12>")
	)
	(segment
		(start 356.45471 -281.69489)
		(end 356.45598 -281.694128)
		(width 0.1143)
		(layer "In11.Cu")
		(net "P5E_CPU0_P1_RX_DN<12>")
	)
	(segment
		(start 356.445566 -294.011858)
		(end 356.40899 -293.990522)
		(width 0.1143)
		(layer "In11.Cu")
		(net "P5E_CPU0_P1_RX_DN<12>")
	)
	(segment
		(start 356.451662 -279.43556)
		(end 356.450138 -279.434798)
		(width 0.1143)
		(layer "In11.Cu")
		(net "P5E_CPU0_P1_RX_DN<12>")
	)
	(segment
		(start 356.448106 -287.533588)
		(end 356.41153 -287.512252)
		(width 0.1143)
		(layer "In11.Cu")
		(net "P5E_CPU0_P1_RX_DN<12>")
	)
	(segment
		(start 356.448106 -286.558482)
		(end 356.481634 -286.538924)
		(width 0.1143)
		(layer "In11.Cu")
		(net "P5E_CPU0_P1_RX_DN<12>")
	)
	(segment
		(start 356.448106 -279.433528)
		(end 356.44709 -279.43302)
		(width 0.1143)
		(layer "In11.Cu")
		(net "P5E_CPU0_P1_RX_DN<12>")
	)
	(segment
		(start 351.493582 -389.584184)
		(end 351.424494 -389.403082)
		(width 0.14224)
		(layer "In11.Cu")
		(net "P5E_CPU0_P1_RX_DN<12>")
	)
	(segment
		(start 356.448868 -279.434036)
		(end 356.448106 -279.433528)
		(width 0.1143)
		(layer "In11.Cu")
		(net "P5E_CPU0_P1_RX_DN<12>")
	)
	(segment
		(start 356.448106 -290.773358)
		(end 356.44709 -290.77285)
		(width 0.1143)
		(layer "In11.Cu")
		(net "P5E_CPU0_P1_RX_DN<12>")
	)
	(segment
		(start 350.877124 -393.22883)
		(end 350.88195 -392.616944)
		(width 0.14224)
		(layer "In11.Cu")
		(net "P5E_CPU0_P1_RX_DN<12>")
	)
	(segment
		(start 356.441502 -281.04973)
		(end 356.439978 -281.048714)
		(width 0.1143)
		(layer "In11.Cu")
		(net "P5E_CPU0_P1_RX_DN<12>")
	)
	(segment
		(start 356.44709 -284.293056)
		(end 356.445566 -284.29204)
		(width 0.1143)
		(layer "In11.Cu")
		(net "P5E_CPU0_P1_RX_DN<12>")
	)
	(segment
		(start 355.069902 -275.401786)
		(end 355.038152 -275.383498)
		(width 0.1143)
		(layer "In11.Cu")
		(net "P5E_CPU0_P1_RX_DN<12>")
	)
	(segment
		(start 356.454964 -282.677616)
		(end 356.452424 -282.676092)
		(width 0.1143)
		(layer "In11.Cu")
		(net "P5E_CPU0_P1_RX_DN<12>")
	)
	(segment
		(start 356.454964 -290.777422)
		(end 356.452424 -290.775898)
		(width 0.1143)
		(layer "In11.Cu")
		(net "P5E_CPU0_P1_RX_DN<12>")
	)
	(segment
		(start 356.448106 -292.39337)
		(end 356.44709 -292.392862)
		(width 0.1143)
		(layer "In11.Cu")
		(net "P5E_CPU0_P1_RX_DN<12>")
	)
	(segment
		(start 356.448868 -291.41801)
		(end 356.450138 -291.417248)
		(width 0.1143)
		(layer "In11.Cu")
		(net "P5E_CPU0_P1_RX_DN<12>")
	)
	(segment
		(start 356.44709 -281.053032)
		(end 356.445566 -281.052016)
		(width 0.1143)
		(layer "In11.Cu")
		(net "P5E_CPU0_P1_RX_DN<12>")
	)
	(segment
		(start 355.540564 -276.2123)
		(end 355.47173 -276.172422)
		(width 0.1143)
		(layer "In11.Cu")
		(net "P5E_CPU0_P1_RX_DN<12>")
	)
	(arc
		(start 368.495834 -363.283246)
		(mid 371.62899 -359.465469)
		(end 373.957088 -355.10978)
		(width 0.14224)
		(layer "In11.Cu")
		(net "P5E_CPU0_P1_RX_DN<12>")
	)
	(arc
		(start 355.658674 -376.642376)
		(mid 355.754593 -376.160159)
		(end 356.027736 -375.751344)
		(width 0.14224)
		(layer "In11.Cu")
		(net "P5E_CPU0_P1_RX_DN<12>")
	)
	(arc
		(start 356.479856 -283.300424)
		(mid 356.635784 -282.996132)
		(end 356.479856 -282.69184)
		(width 0.1143)
		(layer "In11.Cu")
		(net "P5E_CPU0_P1_RX_DN<12>")
	)
	(arc
		(start 355.227636 -275.73224)
		(mid 355.226296 -275.71919)
		(end 355.225858 -275.706078)
		(width 0.1143)
		(layer "In11.Cu")
		(net "P5E_CPU0_P1_RX_DN<12>")
	)
	(arc
		(start 356.481634 -288.158936)
		(mid 356.595041 -288.026047)
		(end 356.635812 -287.856168)
		(width 0.1143)
		(layer "In11.Cu")
		(net "P5E_CPU0_P1_RX_DN<12>")
	)
	(arc
		(start 355.647498 -380.317248)
		(mid 355.655841 -380.291805)
		(end 355.658674 -380.265178)
		(width 0.14224)
		(layer "In11.Cu")
		(net "P5E_CPU0_P1_RX_DN<12>")
	)
	(arc
		(start 356.40899 -284.270704)
		(mid 356.165663 -283.806138)
		(end 356.40899 -283.341572)
		(width 0.1143)
		(layer "In11.Cu")
		(net "P5E_CPU0_P1_RX_DN<12>")
	)
	(arc
		(start 356.41153 -287.512252)
		(mid 356.230878 -287.309507)
		(end 356.165658 -287.045908)
		(width 0.1143)
		(layer "In11.Cu")
		(net "P5E_CPU0_P1_RX_DN<12>")
	)
	(arc
		(start 356.40899 -293.990522)
		(mid 356.165663 -293.525956)
		(end 356.40899 -293.06139)
		(width 0.1143)
		(layer "In11.Cu")
		(net "P5E_CPU0_P1_RX_DN<12>")
	)
	(arc
		(start 354.76561 -275.001736)
		(mid 354.763587 -274.990326)
		(end 354.7618 -274.978876)
		(width 0.1143)
		(layer "In11.Cu")
		(net "P5E_CPU0_P1_RX_DN<12>")
	)
	(arc
		(start 356.40899 -292.37051)
		(mid 356.165663 -291.905944)
		(end 356.40899 -291.441378)
		(width 0.1143)
		(layer "In11.Cu")
		(net "P5E_CPU0_P1_RX_DN<12>")
	)
	(arc
		(start 355.696012 -276.516084)
		(mid 355.6549 -276.345452)
		(end 355.540564 -276.2123)
		(width 0.1143)
		(layer "In11.Cu")
		(net "P5E_CPU0_P1_RX_DN<12>")
	)
	(arc
		(start 356.479856 -278.440388)
		(mid 356.635784 -278.136096)
		(end 356.479856 -277.831804)
		(width 0.1143)
		(layer "In11.Cu")
		(net "P5E_CPU0_P1_RX_DN<12>")
	)
	(arc
		(start 356.40899 -282.650692)
		(mid 356.165663 -282.186126)
		(end 356.40899 -281.72156)
		(width 0.1143)
		(layer "In11.Cu")
		(net "P5E_CPU0_P1_RX_DN<12>")
	)
	(arc
		(start 356.40899 -279.410668)
		(mid 356.165663 -278.946102)
		(end 356.40899 -278.481536)
		(width 0.1143)
		(layer "In11.Cu")
		(net "P5E_CPU0_P1_RX_DN<12>")
	)
	(arc
		(start 356.479856 -284.920436)
		(mid 356.635784 -284.616144)
		(end 356.479856 -284.311852)
		(width 0.1143)
		(layer "In11.Cu")
		(net "P5E_CPU0_P1_RX_DN<12>")
	)
	(arc
		(start 356.635812 -287.856168)
		(mid 356.594557 -287.685197)
		(end 356.479856 -287.551876)
		(width 0.1143)
		(layer "In11.Cu")
		(net "P5E_CPU0_P1_RX_DN<12>")
	)
	(arc
		(start 355.47173 -276.172422)
		(mid 355.455894 -276.160505)
		(end 355.440488 -276.148038)
		(width 0.1143)
		(layer "In11.Cu")
		(net "P5E_CPU0_P1_RX_DN<12>")
	)
	(arc
		(start 356.165658 -295.145968)
		(mid 356.230173 -294.883749)
		(end 356.40899 -294.681402)
		(width 0.1143)
		(layer "In11.Cu")
		(net "P5E_CPU0_P1_RX_DN<12>")
	)
	(arc
		(start 356.165658 -277.32609)
		(mid 356.124109 -277.154668)
		(end 356.008686 -277.02129)
		(width 0.1143)
		(layer "In11.Cu")
		(net "P5E_CPU0_P1_RX_DN<12>")
	)
	(arc
		(start 356.479856 -291.40023)
		(mid 356.635784 -291.095938)
		(end 356.479856 -290.791646)
		(width 0.1143)
		(layer "In11.Cu")
		(net "P5E_CPU0_P1_RX_DN<12>")
	)
	(arc
		(start 355.440488 -276.148038)
		(mid 355.298967 -275.958105)
		(end 355.227636 -275.73224)
		(width 0.1143)
		(layer "In11.Cu")
		(net "P5E_CPU0_P1_RX_DN<12>")
	)
	(arc
		(start 355.225858 -275.706078)
		(mid 355.181787 -275.536542)
		(end 355.069902 -275.401786)
		(width 0.1143)
		(layer "In11.Cu")
		(net "P5E_CPU0_P1_RX_DN<12>")
	)
	(arc
		(start 354.999036 -275.360638)
		(mid 354.847049 -275.20413)
		(end 354.76561 -275.001736)
		(width 0.1143)
		(layer "In11.Cu")
		(net "P5E_CPU0_P1_RX_DN<12>")
	)
	(arc
		(start 356.40899 -290.750498)
		(mid 356.165663 -290.285932)
		(end 356.40899 -289.821366)
		(width 0.1143)
		(layer "In11.Cu")
		(net "P5E_CPU0_P1_RX_DN<12>")
	)
	(arc
		(start 356.479856 -294.640254)
		(mid 356.635784 -294.335962)
		(end 356.479856 -294.03167)
		(width 0.1143)
		(layer "In11.Cu")
		(net "P5E_CPU0_P1_RX_DN<12>")
	)
	(arc
		(start 356.40899 -281.03068)
		(mid 356.165663 -280.566114)
		(end 356.40899 -280.101548)
		(width 0.1143)
		(layer "In11.Cu")
		(net "P5E_CPU0_P1_RX_DN<12>")
	)
	(arc
		(start 356.479856 -280.0604)
		(mid 356.635784 -279.756108)
		(end 356.479856 -279.451816)
		(width 0.1143)
		(layer "In11.Cu")
		(net "P5E_CPU0_P1_RX_DN<12>")
	)
	(arc
		(start 355.93909 -276.98065)
		(mid 355.760277 -276.7783)
		(end 355.695758 -276.516084)
		(width 0.1143)
		(layer "In11.Cu")
		(net "P5E_CPU0_P1_RX_DN<12>")
	)
	(arc
		(start 356.165658 -287.045908)
		(mid 356.230173 -286.783689)
		(end 356.40899 -286.581342)
		(width 0.1143)
		(layer "In11.Cu")
		(net "P5E_CPU0_P1_RX_DN<12>")
	)
	(arc
		(start 356.481634 -286.538924)
		(mid 356.595041 -286.406035)
		(end 356.635812 -286.236156)
		(width 0.1143)
		(layer "In11.Cu")
		(net "P5E_CPU0_P1_RX_DN<12>")
	)
	(arc
		(start 356.479856 -293.020242)
		(mid 356.635784 -292.71595)
		(end 356.479856 -292.411658)
		(width 0.1143)
		(layer "In11.Cu")
		(net "P5E_CPU0_P1_RX_DN<12>")
	)
	(arc
		(start 356.479856 -281.680412)
		(mid 356.635784 -281.37612)
		(end 356.479856 -281.071828)
		(width 0.1143)
		(layer "In11.Cu")
		(net "P5E_CPU0_P1_RX_DN<12>")
	)
	(arc
		(start 356.479856 -289.780218)
		(mid 356.635784 -289.475926)
		(end 356.479856 -289.171634)
		(width 0.1143)
		(layer "In11.Cu")
		(net "P5E_CPU0_P1_RX_DN<12>")
	)
	(arc
		(start 356.40899 -285.890716)
		(mid 356.165663 -285.42615)
		(end 356.40899 -284.961584)
		(width 0.1143)
		(layer "In11.Cu")
		(net "P5E_CPU0_P1_RX_DN<12>")
	)
	(arc
		(start 356.40899 -289.130486)
		(mid 356.165663 -288.66592)
		(end 356.40899 -288.201354)
		(width 0.1143)
		(layer "In11.Cu")
		(net "P5E_CPU0_P1_RX_DN<12>")
	)
	(arc
		(start 356.40899 -277.790656)
		(mid 356.230177 -277.588306)
		(end 356.165658 -277.32609)
		(width 0.1143)
		(layer "In11.Cu")
		(net "P5E_CPU0_P1_RX_DN<12>")
	)
	(arc
		(start 351.185988 -390.59612)
		(mid 351.219635 -390.277809)
		(end 351.319084 -389.973566)
		(width 0.14224)
		(layer "In11.Cu")
		(net "P5E_CPU0_P1_RX_DN<12>")
	)
	(arc
		(start 356.635812 -286.236156)
		(mid 356.594557 -286.065185)
		(end 356.479856 -285.931864)
		(width 0.1143)
		(layer "In11.Cu")
		(net "P5E_CPU0_P1_RX_DN<12>")
	)
	(segment
		(start 354.847906 -279.49017)
		(end 354.381054 -279.756108)
		(width 0.12954)
		(layer "F.Cu")
		(net "P5E_CPU0_P1_RX_DN<11>")
	)
	(segment
		(start 348.998032 -393.69238)
		(end 349.518732 -393.69238)
		(width 0.127)
		(layer "F.Cu")
		(net "P5E_CPU0_P1_RX_DN<11>")
	)
	(segment
		(start 354.678996 -279.756108)
		(end 354.381054 -279.756108)
		(width 0.1143)
		(layer "In11.Cu")
		(net "P5E_CPU0_P1_RX_DN<11>")
	)
	(segment
		(start 355.512878 -285.91637)
		(end 355.511608 -285.915608)
		(width 0.1143)
		(layer "In11.Cu")
		(net "P5E_CPU0_P1_RX_DN<11>")
	)
	(segment
		(start 355.539802 -290.791646)
		(end 355.516688 -290.778184)
		(width 0.1143)
		(layer "In11.Cu")
		(net "P5E_CPU0_P1_RX_DN<11>")
	)
	(segment
		(start 355.000052 -296.538142)
		(end 355.000052 -296.424096)
		(width 0.1143)
		(layer "In11.Cu")
		(net "P5E_CPU0_P1_RX_DN<11>")
	)
	(segment
		(start 352.695256 -383.986024)
		(end 352.877628 -383.918968)
		(width 0.14224)
		(layer "In11.Cu")
		(net "P5E_CPU0_P1_RX_DN<11>")
	)
	(segment
		(start 355.511608 -292.395402)
		(end 355.510592 -292.394894)
		(width 0.1143)
		(layer "In11.Cu")
		(net "P5E_CPU0_P1_RX_DN<11>")
	)
	(segment
		(start 355.508814 -281.054048)
		(end 355.508052 -281.05354)
		(width 0.1143)
		(layer "In11.Cu")
		(net "P5E_CPU0_P1_RX_DN<11>")
	)
	(segment
		(start 357.734616 -305.140614)
		(end 354.954332 -298.427902)
		(width 0.14224)
		(layer "In11.Cu")
		(net "P5E_CPU0_P1_RX_DN<11>")
	)
	(segment
		(start 355.510084 -282.674822)
		(end 355.508814 -282.67406)
		(width 0.1143)
		(layer "In11.Cu")
		(net "P5E_CPU0_P1_RX_DN<11>")
	)
	(segment
		(start 355.47173 -284.959806)
		(end 355.508052 -284.938724)
		(width 0.1143)
		(layer "In11.Cu")
		(net "P5E_CPU0_P1_RX_DN<11>")
	)
	(segment
		(start 355.508052 -288.178494)
		(end 355.54158 -288.158936)
		(width 0.1143)
		(layer "In11.Cu")
		(net "P5E_CPU0_P1_RX_DN<11>")
	)
	(segment
		(start 355.47173 -286.579564)
		(end 355.474524 -286.57804)
		(width 0.1143)
		(layer "In11.Cu")
		(net "P5E_CPU0_P1_RX_DN<11>")
	)
	(segment
		(start 355.508814 -284.294072)
		(end 355.508052 -284.293564)
		(width 0.1143)
		(layer "In11.Cu")
		(net "P5E_CPU0_P1_RX_DN<11>")
	)
	(segment
		(start 355.507798 -291.418772)
		(end 355.508052 -291.418518)
		(width 0.1143)
		(layer "In11.Cu")
		(net "P5E_CPU0_P1_RX_DN<11>")
	)
	(segment
		(start 355.539802 -287.551876)
		(end 355.533452 -287.54832)
		(width 0.1143)
		(layer "In11.Cu")
		(net "P5E_CPU0_P1_RX_DN<11>")
	)
	(segment
		(start 355.514148 -294.016938)
		(end 355.512624 -294.015922)
		(width 0.1143)
		(layer "In11.Cu")
		(net "P5E_CPU0_P1_RX_DN<11>")
	)
	(segment
		(start 355.513386 -290.776406)
		(end 355.51237 -290.775898)
		(width 0.1143)
		(layer "In11.Cu")
		(net "P5E_CPU0_P1_RX_DN<11>")
	)
	(segment
		(start 355.515164 -294.017446)
		(end 355.514148 -294.016938)
		(width 0.1143)
		(layer "In11.Cu")
		(net "P5E_CPU0_P1_RX_DN<11>")
	)
	(segment
		(start 355.508052 -281.05354)
		(end 355.50221 -281.050238)
		(width 0.1143)
		(layer "In11.Cu")
		(net "P5E_CPU0_P1_RX_DN<11>")
	)
	(segment
		(start 375.299986 -339.387688)
		(end 374.220994 -333.38262)
		(width 0.14224)
		(layer "In11.Cu")
		(net "P5E_CPU0_P1_RX_DN<11>")
	)
	(segment
		(start 352.40468 -384.943096)
		(end 352.404426 -384.943096)
		(width 0.14224)
		(layer "In11.Cu")
		(net "P5E_CPU0_P1_RX_DN<11>")
	)
	(segment
		(start 354.755958 -296.180002)
		(end 354.755958 -295.946322)
		(width 0.1143)
		(layer "In11.Cu")
		(net "P5E_CPU0_P1_RX_DN<11>")
	)
	(segment
		(start 355.512878 -284.296358)
		(end 355.511608 -284.295596)
		(width 0.1143)
		(layer "In11.Cu")
		(net "P5E_CPU0_P1_RX_DN<11>")
	)
	(segment
		(start 355.516688 -290.778184)
		(end 355.514148 -290.776914)
		(width 0.1143)
		(layer "In11.Cu")
		(net "P5E_CPU0_P1_RX_DN<11>")
	)
	(segment
		(start 355.51237 -292.39591)
		(end 355.511608 -292.395402)
		(width 0.1143)
		(layer "In11.Cu")
		(net "P5E_CPU0_P1_RX_DN<11>")
	)
	(segment
		(start 349.872554 -393.786868)
		(end 349.99422 -393.716764)
		(width 0.14224)
		(layer "In11.Cu")
		(net "P5E_CPU0_P1_RX_DN<11>")
	)
	(segment
		(start 355.508052 -284.938724)
		(end 355.508814 -284.938216)
		(width 0.1143)
		(layer "In11.Cu")
		(net "P5E_CPU0_P1_RX_DN<11>")
	)
	(segment
		(start 355.000052 -296.424096)
		(end 354.755958 -296.180002)
		(width 0.1143)
		(layer "In11.Cu")
		(net "P5E_CPU0_P1_RX_DN<11>")
	)
	(segment
		(start 355.511608 -282.675584)
		(end 355.510084 -282.674822)
		(width 0.1143)
		(layer "In11.Cu")
		(net "P5E_CPU0_P1_RX_DN<11>")
	)
	(segment
		(start 354.954332 -296.583862)
		(end 355.000052 -296.538142)
		(width 0.1143)
		(layer "In11.Cu")
		(net "P5E_CPU0_P1_RX_DN<11>")
	)
	(segment
		(start 355.474524 -286.57804)
		(end 355.54158 -286.538924)
		(width 0.1143)
		(layer "In11.Cu")
		(net "P5E_CPU0_P1_RX_DN<11>")
	)
	(segment
		(start 355.513386 -292.396418)
		(end 355.51237 -292.39591)
		(width 0.1143)
		(layer "In11.Cu")
		(net "P5E_CPU0_P1_RX_DN<11>")
	)
	(segment
		(start 355.229414 -287.080452)
		(end 355.22916 -287.079182)
		(width 0.1143)
		(layer "In11.Cu")
		(net "P5E_CPU0_P1_RX_DN<11>")
	)
	(segment
		(start 351.931478 -385.967224)
		(end 352.110294 -385.579874)
		(width 0.14224)
		(layer "In11.Cu")
		(net "P5E_CPU0_P1_RX_DN<11>")
	)
	(segment
		(start 352.110548 -385.579874)
		(end 352.043492 -385.39801)
		(width 0.14224)
		(layer "In11.Cu")
		(net "P5E_CPU0_P1_RX_DN<11>")
	)
	(segment
		(start 355.50983 -292.394386)
		(end 355.508814 -292.393878)
		(width 0.1143)
		(layer "In11.Cu")
		(net "P5E_CPU0_P1_RX_DN<11>")
	)
	(segment
		(start 354.7618 -279.838912)
		(end 354.678996 -279.756108)
		(width 0.1143)
		(layer "In11.Cu")
		(net "P5E_CPU0_P1_RX_DN<11>")
	)
	(segment
		(start 355.510084 -283.317442)
		(end 355.539802 -283.300424)
		(width 0.1143)
		(layer "In11.Cu")
		(net "P5E_CPU0_P1_RX_DN<11>")
	)
	(segment
		(start 355.50983 -290.774374)
		(end 355.508814 -290.773866)
		(width 0.1143)
		(layer "In11.Cu")
		(net "P5E_CPU0_P1_RX_DN<11>")
	)
	(segment
		(start 354.99929 -295.4909)
		(end 354.999544 -295.490646)
		(width 0.1143)
		(layer "In11.Cu")
		(net "P5E_CPU0_P1_RX_DN<11>")
	)
	(segment
		(start 355.508814 -285.914084)
		(end 355.508052 -285.913576)
		(width 0.1143)
		(layer "In11.Cu")
		(net "P5E_CPU0_P1_RX_DN<11>")
	)
	(segment
		(start 355.514148 -292.396926)
		(end 355.513386 -292.396418)
		(width 0.1143)
		(layer "In11.Cu")
		(net "P5E_CPU0_P1_RX_DN<11>")
	)
	(segment
		(start 352.877374 -383.918968)
		(end 353.629214 -382.290828)
		(width 0.14224)
		(layer "In11.Cu")
		(net "P5E_CPU0_P1_RX_DN<11>")
	)
	(segment
		(start 355.529134 -289.786314)
		(end 355.529896 -289.785806)
		(width 0.1143)
		(layer "In11.Cu")
		(net "P5E_CPU0_P1_RX_DN<11>")
	)
	(segment
		(start 372.810532 -355.150674)
		(end 375.299732 -349.140526)
		(width 0.14224)
		(layer "In11.Cu")
		(net "P5E_CPU0_P1_RX_DN<11>")
	)
	(segment
		(start 354.954332 -296.61231)
		(end 354.954332 -296.583862)
		(width 0.1143)
		(layer "In11.Cu")
		(net "P5E_CPU0_P1_RX_DN<11>")
	)
	(segment
		(start 355.508052 -294.013382)
		(end 355.47173 -293.9923)
		(width 0.1143)
		(layer "In11.Cu")
		(net "P5E_CPU0_P1_RX_DN<11>")
	)
	(segment
		(start 355.511608 -284.295596)
		(end 355.510084 -284.294834)
		(width 0.1143)
		(layer "In11.Cu")
		(net "P5E_CPU0_P1_RX_DN<11>")
	)
	(segment
		(start 355.066092 -280.25979)
		(end 354.999036 -280.220674)
		(width 0.1143)
		(layer "In11.Cu")
		(net "P5E_CPU0_P1_RX_DN<11>")
	)
	(segment
		(start 355.46919 -282.650946)
		(end 355.44125 -282.63088)
		(width 0.1143)
		(layer "In11.Cu")
		(net "P5E_CPU0_P1_RX_DN<11>")
	)
	(segment
		(start 355.516688 -292.39845)
		(end 355.514148 -292.396926)
		(width 0.1143)
		(layer "In11.Cu")
		(net "P5E_CPU0_P1_RX_DN<11>")
	)
	(segment
		(start 352.256852 -377.963684)
		(end 352.256852 -377.05157)
		(width 0.14224)
		(layer "In11.Cu")
		(net "P5E_CPU0_P1_RX_DN<11>")
	)
	(segment
		(start 352.222308 -385.010152)
		(end 352.40468 -384.943096)
		(width 0.14224)
		(layer "In11.Cu")
		(net "P5E_CPU0_P1_RX_DN<11>")
	)
	(segment
		(start 355.510084 -284.937454)
		(end 355.539802 -284.920436)
		(width 0.1143)
		(layer "In11.Cu")
		(net "P5E_CPU0_P1_RX_DN<11>")
	)
	(segment
		(start 355.519228 -292.39972)
		(end 355.516688 -292.39845)
		(width 0.1143)
		(layer "In11.Cu")
		(net "P5E_CPU0_P1_RX_DN<11>")
	)
	(segment
		(start 355.497384 -294.6654)
		(end 355.508814 -294.658034)
		(width 0.1143)
		(layer "In11.Cu")
		(net "P5E_CPU0_P1_RX_DN<11>")
	)
	(segment
		(start 349.99422 -393.716764)
		(end 349.99422 -393.545822)
		(width 0.14224)
		(layer "In11.Cu")
		(net "P5E_CPU0_P1_RX_DN<11>")
	)
	(segment
		(start 355.505258 -282.671774)
		(end 355.46919 -282.650946)
		(width 0.1143)
		(layer "In11.Cu")
		(net "P5E_CPU0_P1_RX_DN<11>")
	)
	(segment
		(start 355.510084 -285.914846)
		(end 355.508814 -285.914084)
		(width 0.1143)
		(layer "In11.Cu")
		(net "P5E_CPU0_P1_RX_DN<11>")
	)
	(segment
		(start 355.539802 -282.69184)
		(end 355.512878 -282.676346)
		(width 0.1143)
		(layer "In11.Cu")
		(net "P5E_CPU0_P1_RX_DN<11>")
	)
	(segment
		(start 355.508814 -294.658034)
		(end 355.510084 -294.657272)
		(width 0.1143)
		(layer "In11.Cu")
		(net "P5E_CPU0_P1_RX_DN<11>")
	)
	(segment
		(start 355.508814 -284.938216)
		(end 355.510084 -284.937454)
		(width 0.1143)
		(layer "In11.Cu")
		(net "P5E_CPU0_P1_RX_DN<11>")
	)
	(segment
		(start 351.931732 -385.967224)
		(end 351.931478 -385.967224)
		(width 0.14224)
		(layer "In11.Cu")
		(net "P5E_CPU0_P1_RX_DN<11>")
	)
	(segment
		(start 355.510084 -281.05481)
		(end 355.508814 -281.054048)
		(width 0.1143)
		(layer "In11.Cu")
		(net "P5E_CPU0_P1_RX_DN<11>")
	)
	(segment
		(start 355.529896 -289.785806)
		(end 355.539802 -289.780218)
		(width 0.1143)
		(layer "In11.Cu")
		(net "P5E_CPU0_P1_RX_DN<11>")
	)
	(segment
		(start 349.677228 -393.22883)
		(end 349.682054 -392.616944)
		(width 0.14224)
		(layer "In11.Cu")
		(net "P5E_CPU0_P1_RX_DN<11>")
	)
	(segment
		(start 352.583496 -384.555746)
		(end 352.51644 -384.373882)
		(width 0.14224)
		(layer "In11.Cu")
		(net "P5E_CPU0_P1_RX_DN<11>")
	)
	(segment
		(start 355.47173 -293.059612)
		(end 355.508052 -293.03853)
		(width 0.1143)
		(layer "In11.Cu")
		(net "P5E_CPU0_P1_RX_DN<11>")
	)
	(segment
		(start 355.51237 -290.775898)
		(end 355.511608 -290.77539)
		(width 0.1143)
		(layer "In11.Cu")
		(net "P5E_CPU0_P1_RX_DN<11>")
	)
	(segment
		(start 355.508052 -291.418518)
		(end 355.529134 -291.406326)
		(width 0.1143)
		(layer "In11.Cu")
		(net "P5E_CPU0_P1_RX_DN<11>")
	)
	(segment
		(start 355.53904 -292.41115)
		(end 355.519228 -292.39972)
		(width 0.1143)
		(layer "In11.Cu")
		(net "P5E_CPU0_P1_RX_DN<11>")
	)
	(segment
		(start 375.299732 -349.140526)
		(end 375.299986 -349.140272)
		(width 0.14224)
		(layer "In11.Cu")
		(net "P5E_CPU0_P1_RX_DN<11>")
	)
	(segment
		(start 351.637346 -386.604002)
		(end 351.570544 -386.421884)
		(width 0.14224)
		(layer "In11.Cu")
		(net "P5E_CPU0_P1_RX_DN<11>")
	)
	(segment
		(start 355.514148 -290.776914)
		(end 355.513386 -290.776406)
		(width 0.1143)
		(layer "In11.Cu")
		(net "P5E_CPU0_P1_RX_DN<11>")
	)
	(segment
		(start 355.510592 -290.774882)
		(end 355.50983 -290.774374)
		(width 0.1143)
		(layer "In11.Cu")
		(net "P5E_CPU0_P1_RX_DN<11>")
	)
	(segment
		(start 355.508814 -281.698192)
		(end 355.510084 -281.69743)
		(width 0.1143)
		(layer "In11.Cu")
		(net "P5E_CPU0_P1_RX_DN<11>")
	)
	(segment
		(start 355.511608 -281.055572)
		(end 355.510084 -281.05481)
		(width 0.1143)
		(layer "In11.Cu")
		(net "P5E_CPU0_P1_RX_DN<11>")
	)
	(segment
		(start 355.510084 -284.294834)
		(end 355.508814 -284.294072)
		(width 0.1143)
		(layer "In11.Cu")
		(net "P5E_CPU0_P1_RX_DN<11>")
	)
	(segment
		(start 355.539802 -281.071828)
		(end 355.512878 -281.056334)
		(width 0.1143)
		(layer "In11.Cu")
		(net "P5E_CPU0_P1_RX_DN<11>")
	)
	(segment
		(start 355.539802 -285.931864)
		(end 355.512878 -285.91637)
		(width 0.1143)
		(layer "In11.Cu")
		(net "P5E_CPU0_P1_RX_DN<11>")
	)
	(segment
		(start 355.508052 -290.773358)
		(end 355.507798 -290.773358)
		(width 0.1143)
		(layer "In11.Cu")
		(net "P5E_CPU0_P1_RX_DN<11>")
	)
	(segment
		(start 374.220994 -333.38262)
		(end 374.22074 -333.38262)
		(width 0.14224)
		(layer "In11.Cu")
		(net "P5E_CPU0_P1_RX_DN<11>")
	)
	(segment
		(start 355.512878 -281.056334)
		(end 355.511608 -281.055572)
		(width 0.1143)
		(layer "In11.Cu")
		(net "P5E_CPU0_P1_RX_DN<11>")
	)
	(segment
		(start 355.508814 -292.393878)
		(end 355.508052 -292.39337)
		(width 0.1143)
		(layer "In11.Cu")
		(net "P5E_CPU0_P1_RX_DN<11>")
	)
	(segment
		(start 355.510084 -281.69743)
		(end 355.539802 -281.680412)
		(width 0.1143)
		(layer "In11.Cu")
		(net "P5E_CPU0_P1_RX_DN<11>")
	)
	(segment
		(start 351.570544 -386.421884)
		(end 351.74936 -386.03428)
		(width 0.14224)
		(layer "In11.Cu")
		(net "P5E_CPU0_P1_RX_DN<11>")
	)
	(segment
		(start 352.404426 -384.943096)
		(end 352.583242 -384.555746)
		(width 0.14224)
		(layer "In11.Cu")
		(net "P5E_CPU0_P1_RX_DN<11>")
	)
	(segment
		(start 351.74936 -386.03428)
		(end 351.931732 -385.967224)
		(width 0.14224)
		(layer "In11.Cu")
		(net "P5E_CPU0_P1_RX_DN<11>")
	)
	(segment
		(start 355.508814 -283.318204)
		(end 355.510084 -283.317442)
		(width 0.1143)
		(layer "In11.Cu")
		(net "P5E_CPU0_P1_RX_DN<11>")
	)
	(segment
		(start 350.109536 -389.91286)
		(end 351.637346 -386.604002)
		(width 0.14224)
		(layer "In11.Cu")
		(net "P5E_CPU0_P1_RX_DN<11>")
	)
	(segment
		(start 355.510592 -292.394894)
		(end 355.50983 -292.394386)
		(width 0.1143)
		(layer "In11.Cu")
		(net "P5E_CPU0_P1_RX_DN<11>")
	)
	(segment
		(start 353.652836 -375.47423)
		(end 354.612702 -375.076212)
		(width 0.14224)
		(layer "In11.Cu")
		(net "P5E_CPU0_P1_RX_DN<11>")
	)
	(segment
		(start 354.954332 -298.427902)
		(end 354.954332 -296.61231)
		(width 0.14224)
		(layer "In11.Cu")
		(net "P5E_CPU0_P1_RX_DN<11>")
	)
	(segment
		(start 355.511608 -290.77539)
		(end 355.510592 -290.774882)
		(width 0.1143)
		(layer "In11.Cu")
		(net "P5E_CPU0_P1_RX_DN<11>")
	)
	(segment
		(start 352.583242 -384.555746)
		(end 352.583496 -384.555746)
		(width 0.14224)
		(layer "In11.Cu")
		(net "P5E_CPU0_P1_RX_DN<11>")
	)
	(segment
		(start 355.508052 -285.913576)
		(end 355.47173 -285.892494)
		(width 0.1143)
		(layer "In11.Cu")
		(net "P5E_CPU0_P1_RX_DN<11>")
	)
	(segment
		(start 355.508814 -282.67406)
		(end 355.508052 -282.673552)
		(width 0.1143)
		(layer "In11.Cu")
		(net "P5E_CPU0_P1_RX_DN<11>")
	)
	(segment
		(start 355.512624 -294.015922)
		(end 355.510084 -294.014652)
		(width 0.1143)
		(layer "In11.Cu")
		(net "P5E_CPU0_P1_RX_DN<11>")
	)
	(segment
		(start 355.510084 -294.657272)
		(end 355.539802 -294.640254)
		(width 0.1143)
		(layer "In11.Cu")
		(net "P5E_CPU0_P1_RX_DN<11>")
	)
	(segment
		(start 355.508052 -293.03853)
		(end 355.539802 -293.020242)
		(width 0.1143)
		(layer "In11.Cu")
		(net "P5E_CPU0_P1_RX_DN<11>")
	)
	(segment
		(start 355.508814 -290.773866)
		(end 355.508052 -290.773358)
		(width 0.1143)
		(layer "In11.Cu")
		(net "P5E_CPU0_P1_RX_DN<11>")
	)
	(segment
		(start 352.51644 -384.373882)
		(end 352.695256 -383.986024)
		(width 0.14224)
		(layer "In11.Cu")
		(net "P5E_CPU0_P1_RX_DN<11>")
	)
	(segment
		(start 375.299986 -349.140272)
		(end 375.299986 -339.387688)
		(width 0.14224)
		(layer "In11.Cu")
		(net "P5E_CPU0_P1_RX_DN<11>")
	)
	(segment
		(start 349.682054 -392.616944)
		(end 349.986092 -392.31316)
		(width 0.14224)
		(layer "In11.Cu")
		(net "P5E_CPU0_P1_RX_DN<11>")
	)
	(segment
		(start 355.529896 -291.405818)
		(end 355.539802 -291.40023)
		(width 0.1143)
		(layer "In11.Cu")
		(net "P5E_CPU0_P1_RX_DN<11>")
	)
	(segment
		(start 355.44125 -281.741372)
		(end 355.46919 -281.721306)
		(width 0.1143)
		(layer "In11.Cu")
		(net "P5E_CPU0_P1_RX_DN<11>")
	)
	(segment
		(start 355.508052 -292.39337)
		(end 355.507798 -292.39337)
		(width 0.1143)
		(layer "In11.Cu")
		(net "P5E_CPU0_P1_RX_DN<11>")
	)
	(segment
		(start 355.508052 -289.798506)
		(end 355.529134 -289.786314)
		(width 0.1143)
		(layer "In11.Cu")
		(net "P5E_CPU0_P1_RX_DN<11>")
	)
	(segment
		(start 373.142256 -327.378314)
		(end 370.441982 -322.2117)
		(width 0.14224)
		(layer "In11.Cu")
		(net "P5E_CPU0_P1_RX_DN<11>")
	)
	(segment
		(start 355.508052 -284.293564)
		(end 355.47173 -284.272482)
		(width 0.1143)
		(layer "In11.Cu")
		(net "P5E_CPU0_P1_RX_DN<11>")
	)
	(segment
		(start 355.508052 -282.673552)
		(end 355.505258 -282.671774)
		(width 0.1143)
		(layer "In11.Cu")
		(net "P5E_CPU0_P1_RX_DN<11>")
	)
	(segment
		(start 355.507798 -289.79876)
		(end 355.508052 -289.798506)
		(width 0.1143)
		(layer "In11.Cu")
		(net "P5E_CPU0_P1_RX_DN<11>")
	)
	(segment
		(start 355.539802 -289.171634)
		(end 355.495098 -289.145726)
		(width 0.1143)
		(layer "In11.Cu")
		(net "P5E_CPU0_P1_RX_DN<11>")
	)
	(segment
		(start 352.877628 -383.918968)
		(end 352.877374 -383.918968)
		(width 0.14224)
		(layer "In11.Cu")
		(net "P5E_CPU0_P1_RX_DN<11>")
	)
	(segment
		(start 349.986092 -392.31316)
		(end 349.986092 -390.4742)
		(width 0.14224)
		(layer "In11.Cu")
		(net "P5E_CPU0_P1_RX_DN<11>")
	)
	(segment
		(start 355.46919 -281.721306)
		(end 355.506528 -281.699716)
		(width 0.1143)
		(layer "In11.Cu")
		(net "P5E_CPU0_P1_RX_DN<11>")
	)
	(segment
		(start 352.110294 -385.579874)
		(end 352.110548 -385.579874)
		(width 0.14224)
		(layer "In11.Cu")
		(net "P5E_CPU0_P1_RX_DN<11>")
	)
	(segment
		(start 363.443012 -313.683396)
		(end 357.734616 -305.140614)
		(width 0.14224)
		(layer "In11.Cu")
		(net "P5E_CPU0_P1_RX_DN<11>")
	)
	(segment
		(start 355.498654 -281.047698)
		(end 355.497384 -281.046936)
		(width 0.1143)
		(layer "In11.Cu")
		(net "P5E_CPU0_P1_RX_DN<11>")
	)
	(segment
		(start 355.539802 -292.411658)
		(end 355.53904 -292.41115)
		(width 0.1143)
		(layer "In11.Cu")
		(net "P5E_CPU0_P1_RX_DN<11>")
	)
	(segment
		(start 349.518732 -393.69238)
		(end 349.872046 -393.787376)
		(width 0.14224)
		(layer "In11.Cu")
		(net "P5E_CPU0_P1_RX_DN<11>")
	)
	(segment
		(start 354.999544 -295.490646)
		(end 355.066092 -295.452292)
		(width 0.1143)
		(layer "In11.Cu")
		(net "P5E_CPU0_P1_RX_DN<11>")
	)
	(segment
		(start 355.47173 -283.339794)
		(end 355.508052 -283.318712)
		(width 0.1143)
		(layer "In11.Cu")
		(net "P5E_CPU0_P1_RX_DN<11>")
	)
	(segment
		(start 353.730052 -378.957586)
		(end 353.396042 -378.819664)
		(width 0.14224)
		(layer "In11.Cu")
		(net "P5E_CPU0_P1_RX_DN<11>")
	)
	(segment
		(start 355.511608 -285.915608)
		(end 355.510084 -285.914846)
		(width 0.1143)
		(layer "In11.Cu")
		(net "P5E_CPU0_P1_RX_DN<11>")
	)
	(segment
		(start 352.043492 -385.39801)
		(end 352.222308 -385.010152)
		(width 0.14224)
		(layer "In11.Cu")
		(net "P5E_CPU0_P1_RX_DN<11>")
	)
	(segment
		(start 355.510084 -294.014652)
		(end 355.508814 -294.01389)
		(width 0.1143)
		(layer "In11.Cu")
		(net "P5E_CPU0_P1_RX_DN<11>")
	)
	(segment
		(start 355.508814 -294.01389)
		(end 355.508052 -294.013382)
		(width 0.1143)
		(layer "In11.Cu")
		(net "P5E_CPU0_P1_RX_DN<11>")
	)
	(segment
		(start 356.758494 -373.641874)
		(end 367.89868 -362.501688)
		(width 0.14224)
		(layer "In11.Cu")
		(net "P5E_CPU0_P1_RX_DN<11>")
	)
	(segment
		(start 355.512878 -282.676346)
		(end 355.511608 -282.675584)
		(width 0.1143)
		(layer "In11.Cu")
		(net "P5E_CPU0_P1_RX_DN<11>")
	)
	(segment
		(start 374.22074 -333.38262)
		(end 373.142256 -327.378314)
		(width 0.14224)
		(layer "In11.Cu")
		(net "P5E_CPU0_P1_RX_DN<11>")
	)
	(segment
		(start 355.50221 -281.050238)
		(end 355.498654 -281.047698)
		(width 0.1143)
		(layer "In11.Cu")
		(net "P5E_CPU0_P1_RX_DN<11>")
	)
	(segment
		(start 355.508052 -283.318712)
		(end 355.508814 -283.318204)
		(width 0.1143)
		(layer "In11.Cu")
		(net "P5E_CPU0_P1_RX_DN<11>")
	)
	(segment
		(start 355.539802 -294.03167)
		(end 355.515164 -294.017446)
		(width 0.1143)
		(layer "In11.Cu")
		(net "P5E_CPU0_P1_RX_DN<11>")
	)
	(segment
		(start 370.441982 -322.2117)
		(end 363.443012 -313.683396)
		(width 0.14224)
		(layer "In11.Cu")
		(net "P5E_CPU0_P1_RX_DN<11>")
	)
	(segment
		(start 349.872046 -393.787376)
		(end 349.872554 -393.786868)
		(width 0.14224)
		(layer "In11.Cu")
		(net "P5E_CPU0_P1_RX_DN<11>")
	)
	(segment
		(start 354.983796 -295.502076)
		(end 354.99929 -295.4909)
		(width 0.1143)
		(layer "In11.Cu")
		(net "P5E_CPU0_P1_RX_DN<11>")
	)
	(segment
		(start 355.529134 -291.406326)
		(end 355.529896 -291.405818)
		(width 0.1143)
		(layer "In11.Cu")
		(net "P5E_CPU0_P1_RX_DN<11>")
	)
	(segment
		(start 355.539802 -284.311852)
		(end 355.512878 -284.296358)
		(width 0.1143)
		(layer "In11.Cu")
		(net "P5E_CPU0_P1_RX_DN<11>")
	)
	(segment
		(start 349.99422 -393.545822)
		(end 349.677228 -393.22883)
		(width 0.14224)
		(layer "In11.Cu")
		(net "P5E_CPU0_P1_RX_DN<11>")
	)
	(segment
		(start 355.506528 -281.699716)
		(end 355.508814 -281.698192)
		(width 0.1143)
		(layer "In11.Cu")
		(net "P5E_CPU0_P1_RX_DN<11>")
	)
	(segment
		(start 353.956874 -380.800102)
		(end 353.956874 -379.786388)
		(width 0.14224)
		(layer "In11.Cu")
		(net "P5E_CPU0_P1_RX_DN<11>")
	)
	(segment
		(start 355.495098 -288.186114)
		(end 355.508052 -288.178494)
		(width 0.1143)
		(layer "In11.Cu")
		(net "P5E_CPU0_P1_RX_DN<11>")
	)
	(arc
		(start 355.44125 -282.63088)
		(mid 355.21325 -282.186126)
		(end 355.44125 -281.741372)
		(width 0.1143)
		(layer "In11.Cu")
		(net "P5E_CPU0_P1_RX_DN<11>")
	)
	(arc
		(start 355.54158 -288.158936)
		(mid 355.654987 -288.026047)
		(end 355.695758 -287.856168)
		(width 0.1143)
		(layer "In11.Cu")
		(net "P5E_CPU0_P1_RX_DN<11>")
	)
	(arc
		(start 353.889056 -379.339602)
		(mid 353.870727 -379.188862)
		(end 353.821492 -379.045216)
		(width 0.14224)
		(layer "In11.Cu")
		(net "P5E_CPU0_P1_RX_DN<11>")
	)
	(arc
		(start 355.457506 -283.3497)
		(mid 355.46458 -283.344693)
		(end 355.47173 -283.339794)
		(width 0.1143)
		(layer "In11.Cu")
		(net "P5E_CPU0_P1_RX_DN<11>")
	)
	(arc
		(start 355.45649 -284.970474)
		(mid 355.464066 -284.965078)
		(end 355.47173 -284.959806)
		(width 0.1143)
		(layer "In11.Cu")
		(net "P5E_CPU0_P1_RX_DN<11>")
	)
	(arc
		(start 355.226874 -287.01365)
		(mid 355.294911 -286.775462)
		(end 355.458268 -286.589216)
		(width 0.1143)
		(layer "In11.Cu")
		(net "P5E_CPU0_P1_RX_DN<11>")
	)
	(arc
		(start 355.22916 -287.079182)
		(mid 355.226424 -287.046472)
		(end 355.226874 -287.01365)
		(width 0.1143)
		(layer "In11.Cu")
		(net "P5E_CPU0_P1_RX_DN<11>")
	)
	(arc
		(start 355.066092 -295.452292)
		(mid 355.179747 -295.317772)
		(end 355.225604 -295.147746)
		(width 0.1143)
		(layer "In11.Cu")
		(net "P5E_CPU0_P1_RX_DN<11>")
	)
	(arc
		(start 355.695758 -287.856168)
		(mid 355.654503 -287.685197)
		(end 355.539802 -287.551876)
		(width 0.1143)
		(layer "In11.Cu")
		(net "P5E_CPU0_P1_RX_DN<11>")
	)
	(arc
		(start 353.956874 -379.786388)
		(mid 353.948301 -379.670203)
		(end 353.922838 -379.556518)
		(width 0.14224)
		(layer "In11.Cu")
		(net "P5E_CPU0_P1_RX_DN<11>")
	)
	(arc
		(start 355.495098 -289.145726)
		(mid 355.218765 -288.66592)
		(end 355.495098 -288.186114)
		(width 0.1143)
		(layer "In11.Cu")
		(net "P5E_CPU0_P1_RX_DN<11>")
	)
	(arc
		(start 355.47173 -284.272482)
		(mid 355.464581 -284.267582)
		(end 355.457506 -284.262576)
		(width 0.1143)
		(layer "In11.Cu")
		(net "P5E_CPU0_P1_RX_DN<11>")
	)
	(arc
		(start 355.539802 -294.640254)
		(mid 355.69573 -294.335962)
		(end 355.539802 -294.03167)
		(width 0.1143)
		(layer "In11.Cu")
		(net "P5E_CPU0_P1_RX_DN<11>")
	)
	(arc
		(start 353.396042 -378.819664)
		(mid 353.343482 -378.803001)
		(end 353.288854 -378.795534)
		(width 0.14224)
		(layer "In11.Cu")
		(net "P5E_CPU0_P1_RX_DN<11>")
	)
	(arc
		(start 354.755958 -295.946322)
		(mid 354.816178 -295.696654)
		(end 354.983796 -295.502076)
		(width 0.1143)
		(layer "In11.Cu")
		(net "P5E_CPU0_P1_RX_DN<11>")
	)
	(arc
		(start 353.288854 -378.795534)
		(mid 353.198983 -378.787324)
		(end 353.110292 -378.770642)
		(width 0.14224)
		(layer "In11.Cu")
		(net "P5E_CPU0_P1_RX_DN<11>")
	)
	(arc
		(start 349.986092 -390.4742)
		(mid 350.017382 -390.18684)
		(end 350.109536 -389.91286)
		(width 0.14224)
		(layer "In11.Cu")
		(net "P5E_CPU0_P1_RX_DN<11>")
	)
	(arc
		(start 355.457506 -293.069518)
		(mid 355.46458 -293.064511)
		(end 355.47173 -293.059612)
		(width 0.1143)
		(layer "In11.Cu")
		(net "P5E_CPU0_P1_RX_DN<11>")
	)
	(arc
		(start 355.539802 -291.40023)
		(mid 355.69573 -291.095938)
		(end 355.539802 -290.791646)
		(width 0.1143)
		(layer "In11.Cu")
		(net "P5E_CPU0_P1_RX_DN<11>")
	)
	(arc
		(start 367.89868 -362.501688)
		(mid 370.71662 -359.068073)
		(end 372.810532 -355.150674)
		(width 0.14224)
		(layer "In11.Cu")
		(net "P5E_CPU0_P1_RX_DN<11>")
	)
	(arc
		(start 355.507798 -292.39337)
		(mid 355.227371 -291.906134)
		(end 355.507798 -291.418772)
		(width 0.1143)
		(layer "In11.Cu")
		(net "P5E_CPU0_P1_RX_DN<11>")
	)
	(arc
		(start 355.458268 -286.589216)
		(mid 355.464963 -286.58434)
		(end 355.47173 -286.579564)
		(width 0.1143)
		(layer "In11.Cu")
		(net "P5E_CPU0_P1_RX_DN<11>")
	)
	(arc
		(start 355.47173 -293.9923)
		(mid 355.464581 -293.9874)
		(end 355.457506 -293.982394)
		(width 0.1143)
		(layer "In11.Cu")
		(net "P5E_CPU0_P1_RX_DN<11>")
	)
	(arc
		(start 355.457506 -284.262576)
		(mid 355.230123 -283.806138)
		(end 355.457506 -283.3497)
		(width 0.1143)
		(layer "In11.Cu")
		(net "P5E_CPU0_P1_RX_DN<11>")
	)
	(arc
		(start 355.45649 -285.881826)
		(mid 355.231319 -285.42615)
		(end 355.45649 -284.970474)
		(width 0.1143)
		(layer "In11.Cu")
		(net "P5E_CPU0_P1_RX_DN<11>")
	)
	(arc
		(start 353.110292 -378.770642)
		(mid 352.875641 -378.693266)
		(end 352.656902 -378.578364)
		(width 0.14224)
		(layer "In11.Cu")
		(net "P5E_CPU0_P1_RX_DN<11>")
	)
	(arc
		(start 355.533452 -287.54832)
		(mid 355.446567 -287.486653)
		(end 355.372416 -287.410144)
		(width 0.1143)
		(layer "In11.Cu")
		(net "P5E_CPU0_P1_RX_DN<11>")
	)
	(arc
		(start 355.539802 -284.920436)
		(mid 355.69573 -284.616144)
		(end 355.539802 -284.311852)
		(width 0.1143)
		(layer "In11.Cu")
		(net "P5E_CPU0_P1_RX_DN<11>")
	)
	(arc
		(start 353.821492 -379.045216)
		(mid 353.784006 -378.992813)
		(end 353.730052 -378.957586)
		(width 0.14224)
		(layer "In11.Cu")
		(net "P5E_CPU0_P1_RX_DN<11>")
	)
	(arc
		(start 354.612702 -375.076212)
		(mid 355.756145 -374.464587)
		(end 356.758494 -373.641874)
		(width 0.14224)
		(layer "In11.Cu")
		(net "P5E_CPU0_P1_RX_DN<11>")
	)
	(arc
		(start 352.28022 -376.858784)
		(mid 352.375866 -376.566459)
		(end 352.514916 -376.29211)
		(width 0.14224)
		(layer "In11.Cu")
		(net "P5E_CPU0_P1_RX_DN<11>")
	)
	(arc
		(start 355.695758 -286.236156)
		(mid 355.654503 -286.065185)
		(end 355.539802 -285.931864)
		(width 0.1143)
		(layer "In11.Cu")
		(net "P5E_CPU0_P1_RX_DN<11>")
	)
	(arc
		(start 355.539802 -293.020242)
		(mid 355.69573 -292.71595)
		(end 355.539802 -292.411658)
		(width 0.1143)
		(layer "In11.Cu")
		(net "P5E_CPU0_P1_RX_DN<11>")
	)
	(arc
		(start 352.340672 -378.24156)
		(mid 352.278204 -378.108828)
		(end 352.256852 -377.963684)
		(width 0.14224)
		(layer "In11.Cu")
		(net "P5E_CPU0_P1_RX_DN<11>")
	)
	(arc
		(start 352.514916 -376.29211)
		(mid 352.571896 -376.210763)
		(end 352.638868 -376.137424)
		(width 0.14224)
		(layer "In11.Cu")
		(net "P5E_CPU0_P1_RX_DN<11>")
	)
	(arc
		(start 355.539802 -289.780218)
		(mid 355.69573 -289.475926)
		(end 355.539802 -289.171634)
		(width 0.1143)
		(layer "In11.Cu")
		(net "P5E_CPU0_P1_RX_DN<11>")
	)
	(arc
		(start 355.372416 -287.410144)
		(mid 355.278604 -287.25498)
		(end 355.229414 -287.080452)
		(width 0.1143)
		(layer "In11.Cu")
		(net "P5E_CPU0_P1_RX_DN<11>")
	)
	(arc
		(start 355.225604 -280.564336)
		(mid 355.179734 -280.394316)
		(end 355.066092 -280.25979)
		(width 0.1143)
		(layer "In11.Cu")
		(net "P5E_CPU0_P1_RX_DN<11>")
	)
	(arc
		(start 355.507798 -290.773358)
		(mid 355.227371 -290.286122)
		(end 355.507798 -289.79876)
		(width 0.1143)
		(layer "In11.Cu")
		(net "P5E_CPU0_P1_RX_DN<11>")
	)
	(arc
		(start 355.47173 -285.892494)
		(mid 355.464066 -285.887223)
		(end 355.45649 -285.881826)
		(width 0.1143)
		(layer "In11.Cu")
		(net "P5E_CPU0_P1_RX_DN<11>")
	)
	(arc
		(start 354.76561 -279.861772)
		(mid 354.763587 -279.850362)
		(end 354.7618 -279.838912)
		(width 0.1143)
		(layer "In11.Cu")
		(net "P5E_CPU0_P1_RX_DN<11>")
	)
	(arc
		(start 352.256852 -377.05157)
		(mid 352.262729 -376.954473)
		(end 352.28022 -376.858784)
		(width 0.14224)
		(layer "In11.Cu")
		(net "P5E_CPU0_P1_RX_DN<11>")
	)
	(arc
		(start 353.629214 -382.290828)
		(mid 353.87399 -381.563257)
		(end 353.956874 -380.800102)
		(width 0.14224)
		(layer "In11.Cu")
		(net "P5E_CPU0_P1_RX_DN<11>")
	)
	(arc
		(start 355.54158 -286.538924)
		(mid 355.654987 -286.406035)
		(end 355.695758 -286.236156)
		(width 0.1143)
		(layer "In11.Cu")
		(net "P5E_CPU0_P1_RX_DN<11>")
	)
	(arc
		(start 355.497384 -281.046936)
		(mid 355.30378 -280.838132)
		(end 355.225604 -280.564336)
		(width 0.1143)
		(layer "In11.Cu")
		(net "P5E_CPU0_P1_RX_DN<11>")
	)
	(arc
		(start 355.225604 -295.147746)
		(mid 355.30389 -294.874135)
		(end 355.497384 -294.6654)
		(width 0.1143)
		(layer "In11.Cu")
		(net "P5E_CPU0_P1_RX_DN<11>")
	)
	(arc
		(start 355.539802 -281.680412)
		(mid 355.69573 -281.37612)
		(end 355.539802 -281.071828)
		(width 0.1143)
		(layer "In11.Cu")
		(net "P5E_CPU0_P1_RX_DN<11>")
	)
	(arc
		(start 352.504248 -378.44984)
		(mid 352.418423 -378.34887)
		(end 352.340672 -378.24156)
		(width 0.14224)
		(layer "In11.Cu")
		(net "P5E_CPU0_P1_RX_DN<11>")
	)
	(arc
		(start 353.922838 -379.556518)
		(mid 353.898428 -379.449231)
		(end 353.889056 -379.339602)
		(width 0.14224)
		(layer "In11.Cu")
		(net "P5E_CPU0_P1_RX_DN<11>")
	)
	(arc
		(start 354.999036 -280.220674)
		(mid 354.847049 -280.064166)
		(end 354.76561 -279.861772)
		(width 0.1143)
		(layer "In11.Cu")
		(net "P5E_CPU0_P1_RX_DN<11>")
	)
	(arc
		(start 352.656902 -378.578364)
		(mid 352.576371 -378.519095)
		(end 352.504248 -378.44984)
		(width 0.14224)
		(layer "In11.Cu")
		(net "P5E_CPU0_P1_RX_DN<11>")
	)
	(arc
		(start 355.539802 -283.300424)
		(mid 355.69573 -282.996132)
		(end 355.539802 -282.69184)
		(width 0.1143)
		(layer "In11.Cu")
		(net "P5E_CPU0_P1_RX_DN<11>")
	)
	(arc
		(start 352.638868 -376.137424)
		(mid 353.11483 -375.758395)
		(end 353.652836 -375.47423)
		(width 0.14224)
		(layer "In11.Cu")
		(net "P5E_CPU0_P1_RX_DN<11>")
	)
	(arc
		(start 355.457506 -293.982394)
		(mid 355.230123 -293.525956)
		(end 355.457506 -293.069518)
		(width 0.1143)
		(layer "In11.Cu")
		(net "P5E_CPU0_P1_RX_DN<11>")
	)
	(segment
		(start 354.847906 -277.870158)
		(end 354.381054 -278.136096)
		(width 0.12954)
		(layer "F.Cu")
		(net "P5E_CPU0_P1_RX_DN<10>")
	)
	(segment
		(start 347.798136 -393.69238)
		(end 348.318836 -393.69238)
		(width 0.127)
		(layer "F.Cu")
		(net "P5E_CPU0_P1_RX_DN<10>")
	)
	(segment
		(start 354.10267 -279.266142)
		(end 354.129848 -279.250394)
		(width 0.1143)
		(layer "In11.Cu")
		(net "P5E_CPU0_P1_RX_DN<10>")
	)
	(segment
		(start 354.09886 -280.244042)
		(end 354.098098 -280.243534)
		(width 0.1143)
		(layer "In11.Cu")
		(net "P5E_CPU0_P1_RX_DN<10>")
	)
	(segment
		(start 354.285804 -295.334944)
		(end 354.285804 -295.122092)
		(width 0.1143)
		(layer "In11.Cu")
		(net "P5E_CPU0_P1_RX_DN<10>")
	)
	(segment
		(start 354.098098 -280.243534)
		(end 354.097082 -280.243026)
		(width 0.1143)
		(layer "In11.Cu")
		(net "P5E_CPU0_P1_RX_DN<10>")
	)
	(segment
		(start 354.097082 -279.26919)
		(end 354.098098 -279.268682)
		(width 0.1143)
		(layer "In11.Cu")
		(net "P5E_CPU0_P1_RX_DN<10>")
	)
	(segment
		(start 354.529136 -284.961584)
		(end 354.598732 -284.920944)
		(width 0.1143)
		(layer "In11.Cu")
		(net "P5E_CPU0_P1_RX_DN<10>")
	)
	(segment
		(start 354.54336 -294.67302)
		(end 354.598732 -294.640762)
		(width 0.1143)
		(layer "In11.Cu")
		(net "P5E_CPU0_P1_RX_DN<10>")
	)
	(segment
		(start 354.089716 -280.238708)
		(end 354.088192 -280.237692)
		(width 0.1143)
		(layer "In11.Cu")
		(net "P5E_CPU0_P1_RX_DN<10>")
	)
	(segment
		(start 356.908608 -305.583082)
		(end 353.857052 -298.216066)
		(width 0.14224)
		(layer "In11.Cu")
		(net "P5E_CPU0_P1_RX_DN<10>")
	)
	(segment
		(start 362.693458 -314.240418)
		(end 356.908608 -305.583082)
		(width 0.14224)
		(layer "In11.Cu")
		(net "P5E_CPU0_P1_RX_DN<10>")
	)
	(segment
		(start 354.529136 -289.821366)
		(end 354.598732 -289.780726)
		(width 0.1143)
		(layer "In11.Cu")
		(net "P5E_CPU0_P1_RX_DN<10>")
	)
	(segment
		(start 348.786196 -392.31316)
		(end 348.786196 -389.71728)
		(width 0.14224)
		(layer "In11.Cu")
		(net "P5E_CPU0_P1_RX_DN<10>")
	)
	(segment
		(start 354.531168 -286.579818)
		(end 354.568252 -286.558482)
		(width 0.1143)
		(layer "In11.Cu")
		(net "P5E_CPU0_P1_RX_DN<10>")
	)
	(segment
		(start 372.546118 -330.266802)
		(end 372.545864 -330.266802)
		(width 0.14224)
		(layer "In11.Cu")
		(net "P5E_CPU0_P1_RX_DN<10>")
	)
	(segment
		(start 369.659408 -322.727828)
		(end 362.693458 -314.240418)
		(width 0.14224)
		(layer "In11.Cu")
		(net "P5E_CPU0_P1_RX_DN<10>")
	)
	(segment
		(start 354.568252 -288.178494)
		(end 354.600764 -288.159698)
		(width 0.1143)
		(layer "In11.Cu")
		(net "P5E_CPU0_P1_RX_DN<10>")
	)
	(segment
		(start 371.472206 -355.491796)
		(end 374.202706 -348.899988)
		(width 0.14224)
		(layer "In11.Cu")
		(net "P5E_CPU0_P1_RX_DN<10>")
	)
	(segment
		(start 354.598732 -290.791138)
		(end 354.529136 -290.750498)
		(width 0.1143)
		(layer "In11.Cu")
		(net "P5E_CPU0_P1_RX_DN<10>")
	)
	(segment
		(start 354.529136 -278.481536)
		(end 354.598732 -278.440896)
		(width 0.1143)
		(layer "In11.Cu")
		(net "P5E_CPU0_P1_RX_DN<10>")
	)
	(segment
		(start 348.786196 -389.71728)
		(end 348.649036 -389.58012)
		(width 0.14224)
		(layer "In11.Cu")
		(net "P5E_CPU0_P1_RX_DN<10>")
	)
	(segment
		(start 354.529136 -283.341572)
		(end 354.598732 -283.300932)
		(width 0.1143)
		(layer "In11.Cu")
		(net "P5E_CPU0_P1_RX_DN<10>")
	)
	(segment
		(start 354.10013 -280.244804)
		(end 354.09886 -280.244042)
		(width 0.1143)
		(layer "In11.Cu")
		(net "P5E_CPU0_P1_RX_DN<10>")
	)
	(segment
		(start 354.529136 -286.581342)
		(end 354.531168 -286.579818)
		(width 0.1143)
		(layer "In11.Cu")
		(net "P5E_CPU0_P1_RX_DN<10>")
	)
	(segment
		(start 357.577644 -371.472714)
		(end 367.271554 -361.778804)
		(width 0.14224)
		(layer "In11.Cu")
		(net "P5E_CPU0_P1_RX_DN<10>")
	)
	(segment
		(start 354.598732 -285.931356)
		(end 354.529136 -285.890716)
		(width 0.1143)
		(layer "In11.Cu")
		(net "P5E_CPU0_P1_RX_DN<10>")
	)
	(segment
		(start 348.477332 -393.22883)
		(end 348.482158 -392.616944)
		(width 0.14224)
		(layer "In11.Cu")
		(net "P5E_CPU0_P1_RX_DN<10>")
	)
	(segment
		(start 354.098098 -279.268682)
		(end 354.09886 -279.268174)
		(width 0.1143)
		(layer "In11.Cu")
		(net "P5E_CPU0_P1_RX_DN<10>")
	)
	(segment
		(start 348.649036 -389.1534)
		(end 348.786196 -389.01624)
		(width 0.14224)
		(layer "In11.Cu")
		(net "P5E_CPU0_P1_RX_DN<10>")
	)
	(segment
		(start 374.202706 -339.485478)
		(end 373.374158 -334.87614)
		(width 0.14224)
		(layer "In11.Cu")
		(net "P5E_CPU0_P1_RX_DN<10>")
	)
	(segment
		(start 348.649036 -389.58012)
		(end 348.649036 -389.1534)
		(width 0.14224)
		(layer "In11.Cu")
		(net "P5E_CPU0_P1_RX_DN<10>")
	)
	(segment
		(start 354.09886 -279.268174)
		(end 354.10013 -279.267412)
		(width 0.1143)
		(layer "In11.Cu")
		(net "P5E_CPU0_P1_RX_DN<10>")
	)
	(segment
		(start 354.129848 -280.261822)
		(end 354.10013 -280.244804)
		(width 0.1143)
		(layer "In11.Cu")
		(net "P5E_CPU0_P1_RX_DN<10>")
	)
	(segment
		(start 354.094542 -280.241502)
		(end 354.089716 -280.238708)
		(width 0.1143)
		(layer "In11.Cu")
		(net "P5E_CPU0_P1_RX_DN<10>")
	)
	(segment
		(start 353.902772 -296.212514)
		(end 353.902772 -295.717976)
		(width 0.1143)
		(layer "In11.Cu")
		(net "P5E_CPU0_P1_RX_DN<10>")
	)
	(segment
		(start 348.794324 -393.545822)
		(end 348.477332 -393.22883)
		(width 0.14224)
		(layer "In11.Cu")
		(net "P5E_CPU0_P1_RX_DN<10>")
	)
	(segment
		(start 354.568252 -286.558482)
		(end 354.600764 -286.539686)
		(width 0.1143)
		(layer "In11.Cu")
		(net "P5E_CPU0_P1_RX_DN<10>")
	)
	(segment
		(start 353.857052 -296.258234)
		(end 353.902772 -296.212514)
		(width 0.1143)
		(layer "In11.Cu")
		(net "P5E_CPU0_P1_RX_DN<10>")
	)
	(segment
		(start 354.598732 -292.41115)
		(end 354.529136 -292.37051)
		(width 0.1143)
		(layer "In11.Cu")
		(net "P5E_CPU0_P1_RX_DN<10>")
	)
	(segment
		(start 348.482158 -392.616944)
		(end 348.786196 -392.31316)
		(width 0.14224)
		(layer "In11.Cu")
		(net "P5E_CPU0_P1_RX_DN<10>")
	)
	(segment
		(start 354.748846 -278.205946)
		(end 354.678996 -278.136096)
		(width 0.1143)
		(layer "In11.Cu")
		(net "P5E_CPU0_P1_RX_DN<10>")
	)
	(segment
		(start 348.906084 -381.676656)
		(end 350.515936 -380.066804)
		(width 0.14224)
		(layer "In11.Cu")
		(net "P5E_CPU0_P1_RX_DN<10>")
	)
	(segment
		(start 348.649036 -388.45236)
		(end 348.649036 -388.02564)
		(width 0.14224)
		(layer "In11.Cu")
		(net "P5E_CPU0_P1_RX_DN<10>")
	)
	(segment
		(start 353.857052 -296.286682)
		(end 353.857052 -296.258234)
		(width 0.1143)
		(layer "In11.Cu")
		(net "P5E_CPU0_P1_RX_DN<10>")
	)
	(segment
		(start 348.649036 -387.3246)
		(end 348.649036 -386.89788)
		(width 0.14224)
		(layer "In11.Cu")
		(net "P5E_CPU0_P1_RX_DN<10>")
	)
	(segment
		(start 350.553274 -379.976888)
		(end 350.553274 -376.435366)
		(width 0.14224)
		(layer "In11.Cu")
		(net "P5E_CPU0_P1_RX_DN<10>")
	)
	(segment
		(start 352.00336 -375.002298)
		(end 352.772726 -374.683274)
		(width 0.14224)
		(layer "In11.Cu")
		(net "P5E_CPU0_P1_RX_DN<10>")
	)
	(segment
		(start 374.202706 -348.899988)
		(end 374.202706 -339.485478)
		(width 0.14224)
		(layer "In11.Cu")
		(net "P5E_CPU0_P1_RX_DN<10>")
	)
	(segment
		(start 354.088192 -280.237692)
		(end 354.058982 -280.220674)
		(width 0.1143)
		(layer "In11.Cu")
		(net "P5E_CPU0_P1_RX_DN<10>")
	)
	(segment
		(start 348.786196 -389.01624)
		(end 348.786196 -388.58952)
		(width 0.14224)
		(layer "In11.Cu")
		(net "P5E_CPU0_P1_RX_DN<10>")
	)
	(segment
		(start 348.318836 -393.69238)
		(end 348.67215 -393.787376)
		(width 0.14224)
		(layer "In11.Cu")
		(net "P5E_CPU0_P1_RX_DN<10>")
	)
	(segment
		(start 348.67215 -393.787376)
		(end 348.672658 -393.786868)
		(width 0.14224)
		(layer "In11.Cu")
		(net "P5E_CPU0_P1_RX_DN<10>")
	)
	(segment
		(start 348.786196 -387.46176)
		(end 348.649036 -387.3246)
		(width 0.14224)
		(layer "In11.Cu")
		(net "P5E_CPU0_P1_RX_DN<10>")
	)
	(segment
		(start 373.374158 -334.87614)
		(end 373.374412 -334.87614)
		(width 0.14224)
		(layer "In11.Cu")
		(net "P5E_CPU0_P1_RX_DN<10>")
	)
	(segment
		(start 354.598732 -281.07132)
		(end 354.529136 -281.03068)
		(width 0.1143)
		(layer "In11.Cu")
		(net "P5E_CPU0_P1_RX_DN<10>")
	)
	(segment
		(start 354.097082 -280.243026)
		(end 354.095558 -280.24201)
		(width 0.1143)
		(layer "In11.Cu")
		(net "P5E_CPU0_P1_RX_DN<10>")
	)
	(segment
		(start 354.598732 -287.551368)
		(end 354.531676 -287.512252)
		(width 0.1143)
		(layer "In11.Cu")
		(net "P5E_CPU0_P1_RX_DN<10>")
	)
	(segment
		(start 348.649036 -386.89788)
		(end 348.786196 -386.76072)
		(width 0.14224)
		(layer "In11.Cu")
		(net "P5E_CPU0_P1_RX_DN<10>")
	)
	(segment
		(start 351.649538 -375.185432)
		(end 351.864422 -375.068592)
		(width 0.14224)
		(layer "In11.Cu")
		(net "P5E_CPU0_P1_RX_DN<10>")
	)
	(segment
		(start 373.374412 -334.87614)
		(end 372.546118 -330.266802)
		(width 0.14224)
		(layer "In11.Cu")
		(net "P5E_CPU0_P1_RX_DN<10>")
	)
	(segment
		(start 348.672658 -393.786868)
		(end 348.794324 -393.716764)
		(width 0.14224)
		(layer "In11.Cu")
		(net "P5E_CPU0_P1_RX_DN<10>")
	)
	(segment
		(start 354.598732 -284.311344)
		(end 354.529136 -284.270704)
		(width 0.1143)
		(layer "In11.Cu")
		(net "P5E_CPU0_P1_RX_DN<10>")
	)
	(segment
		(start 354.678996 -278.136096)
		(end 354.381054 -278.136096)
		(width 0.1143)
		(layer "In11.Cu")
		(net "P5E_CPU0_P1_RX_DN<10>")
	)
	(segment
		(start 348.794324 -393.716764)
		(end 348.794324 -393.545822)
		(width 0.14224)
		(layer "In11.Cu")
		(net "P5E_CPU0_P1_RX_DN<10>")
	)
	(segment
		(start 354.529136 -293.06139)
		(end 354.598732 -293.02075)
		(width 0.1143)
		(layer "In11.Cu")
		(net "P5E_CPU0_P1_RX_DN<10>")
	)
	(segment
		(start 353.857052 -298.216066)
		(end 353.857052 -296.286682)
		(width 0.14224)
		(layer "In11.Cu")
		(net "P5E_CPU0_P1_RX_DN<10>")
	)
	(segment
		(start 371.994176 -327.194926)
		(end 369.659408 -322.727828)
		(width 0.14224)
		(layer "In11.Cu")
		(net "P5E_CPU0_P1_RX_DN<10>")
	)
	(segment
		(start 372.545864 -330.266802)
		(end 371.994176 -327.194926)
		(width 0.14224)
		(layer "In11.Cu")
		(net "P5E_CPU0_P1_RX_DN<10>")
	)
	(segment
		(start 354.529136 -281.72156)
		(end 354.598732 -281.68092)
		(width 0.1143)
		(layer "In11.Cu")
		(net "P5E_CPU0_P1_RX_DN<10>")
	)
	(segment
		(start 348.649036 -388.02564)
		(end 348.786196 -387.88848)
		(width 0.14224)
		(layer "In11.Cu")
		(net "P5E_CPU0_P1_RX_DN<10>")
	)
	(segment
		(start 354.529136 -291.441378)
		(end 354.598732 -291.400738)
		(width 0.1143)
		(layer "In11.Cu")
		(net "P5E_CPU0_P1_RX_DN<10>")
	)
	(segment
		(start 354.095558 -280.24201)
		(end 354.094542 -280.241502)
		(width 0.1143)
		(layer "In11.Cu")
		(net "P5E_CPU0_P1_RX_DN<10>")
	)
	(segment
		(start 354.529136 -288.201354)
		(end 354.568252 -288.178494)
		(width 0.1143)
		(layer "In11.Cu")
		(net "P5E_CPU0_P1_RX_DN<10>")
	)
	(segment
		(start 348.786196 -388.58952)
		(end 348.649036 -388.45236)
		(width 0.14224)
		(layer "In11.Cu")
		(net "P5E_CPU0_P1_RX_DN<10>")
	)
	(segment
		(start 348.786196 -387.88848)
		(end 348.786196 -387.46176)
		(width 0.14224)
		(layer "In11.Cu")
		(net "P5E_CPU0_P1_RX_DN<10>")
	)
	(segment
		(start 354.598732 -282.691332)
		(end 354.529136 -282.650692)
		(width 0.1143)
		(layer "In11.Cu")
		(net "P5E_CPU0_P1_RX_DN<10>")
	)
	(segment
		(start 354.598732 -294.031162)
		(end 354.529136 -293.990522)
		(width 0.1143)
		(layer "In11.Cu")
		(net "P5E_CPU0_P1_RX_DN<10>")
	)
	(segment
		(start 354.058982 -279.291542)
		(end 354.095558 -279.270206)
		(width 0.1143)
		(layer "In11.Cu")
		(net "P5E_CPU0_P1_RX_DN<10>")
	)
	(segment
		(start 353.902772 -295.717976)
		(end 354.285804 -295.334944)
		(width 0.1143)
		(layer "In11.Cu")
		(net "P5E_CPU0_P1_RX_DN<10>")
	)
	(segment
		(start 354.10013 -279.267412)
		(end 354.10267 -279.266142)
		(width 0.1143)
		(layer "In11.Cu")
		(net "P5E_CPU0_P1_RX_DN<10>")
	)
	(segment
		(start 354.598732 -289.171126)
		(end 354.529136 -289.130486)
		(width 0.1143)
		(layer "In11.Cu")
		(net "P5E_CPU0_P1_RX_DN<10>")
	)
	(segment
		(start 354.095558 -279.270206)
		(end 354.097082 -279.26919)
		(width 0.1143)
		(layer "In11.Cu")
		(net "P5E_CPU0_P1_RX_DN<10>")
	)
	(segment
		(start 348.786196 -386.76072)
		(end 348.786196 -381.966216)
		(width 0.14224)
		(layer "In11.Cu")
		(net "P5E_CPU0_P1_RX_DN<10>")
	)
	(arc
		(start 350.515936 -380.066804)
		(mid 350.543555 -380.025564)
		(end 350.553274 -379.976888)
		(width 0.14224)
		(layer "In11.Cu")
		(net "P5E_CPU0_P1_RX_DN<10>")
	)
	(arc
		(start 348.786196 -381.966216)
		(mid 348.817348 -381.809513)
		(end 348.906084 -381.676656)
		(width 0.14224)
		(layer "In11.Cu")
		(net "P5E_CPU0_P1_RX_DN<10>")
	)
	(arc
		(start 354.529136 -289.130486)
		(mid 354.285809 -288.66592)
		(end 354.529136 -288.201354)
		(width 0.1143)
		(layer "In11.Cu")
		(net "P5E_CPU0_P1_RX_DN<10>")
	)
	(arc
		(start 367.271554 -361.778804)
		(mid 369.681483 -358.842163)
		(end 371.472206 -355.491796)
		(width 0.14224)
		(layer "In11.Cu")
		(net "P5E_CPU0_P1_RX_DN<10>")
	)
	(arc
		(start 354.529136 -290.750498)
		(mid 354.285809 -290.285932)
		(end 354.529136 -289.821366)
		(width 0.1143)
		(layer "In11.Cu")
		(net "P5E_CPU0_P1_RX_DN<10>")
	)
	(arc
		(start 354.129848 -279.250394)
		(mid 354.244524 -279.11706)
		(end 354.285804 -278.946102)
		(width 0.1143)
		(layer "In11.Cu")
		(net "P5E_CPU0_P1_RX_DN<10>")
	)
	(arc
		(start 350.553274 -376.435366)
		(mid 350.571729 -376.263358)
		(end 350.62668 -376.099324)
		(width 0.14224)
		(layer "In11.Cu")
		(net "P5E_CPU0_P1_RX_DN<10>")
	)
	(arc
		(start 350.755966 -375.914158)
		(mid 350.756854 -375.913395)
		(end 350.757744 -375.912634)
		(width 0.14224)
		(layer "In11.Cu")
		(net "P5E_CPU0_P1_RX_DN<10>")
	)
	(arc
		(start 354.598732 -294.640762)
		(mid 354.755709 -294.335962)
		(end 354.598732 -294.031162)
		(width 0.1143)
		(layer "In11.Cu")
		(net "P5E_CPU0_P1_RX_DN<10>")
	)
	(arc
		(start 354.755704 -286.236156)
		(mid 354.714155 -286.064734)
		(end 354.598732 -285.931356)
		(width 0.1143)
		(layer "In11.Cu")
		(net "P5E_CPU0_P1_RX_DN<10>")
	)
	(arc
		(start 354.598732 -293.02075)
		(mid 354.755709 -292.71595)
		(end 354.598732 -292.41115)
		(width 0.1143)
		(layer "In11.Cu")
		(net "P5E_CPU0_P1_RX_DN<10>")
	)
	(arc
		(start 354.598732 -289.780726)
		(mid 354.755709 -289.475926)
		(end 354.598732 -289.171126)
		(width 0.1143)
		(layer "In11.Cu")
		(net "P5E_CPU0_P1_RX_DN<10>")
	)
	(arc
		(start 354.529136 -293.990522)
		(mid 354.285809 -293.525956)
		(end 354.529136 -293.06139)
		(width 0.1143)
		(layer "In11.Cu")
		(net "P5E_CPU0_P1_RX_DN<10>")
	)
	(arc
		(start 354.285804 -278.946102)
		(mid 354.350319 -278.683883)
		(end 354.529136 -278.481536)
		(width 0.1143)
		(layer "In11.Cu")
		(net "P5E_CPU0_P1_RX_DN<10>")
	)
	(arc
		(start 354.285804 -287.045908)
		(mid 354.350319 -286.783689)
		(end 354.529136 -286.581342)
		(width 0.1143)
		(layer "In11.Cu")
		(net "P5E_CPU0_P1_RX_DN<10>")
	)
	(arc
		(start 354.598732 -284.920944)
		(mid 354.755709 -284.616144)
		(end 354.598732 -284.311344)
		(width 0.1143)
		(layer "In11.Cu")
		(net "P5E_CPU0_P1_RX_DN<10>")
	)
	(arc
		(start 354.598732 -283.300932)
		(mid 354.755709 -282.996132)
		(end 354.598732 -282.691332)
		(width 0.1143)
		(layer "In11.Cu")
		(net "P5E_CPU0_P1_RX_DN<10>")
	)
	(arc
		(start 354.529136 -292.37051)
		(mid 354.285809 -291.905944)
		(end 354.529136 -291.441378)
		(width 0.1143)
		(layer "In11.Cu")
		(net "P5E_CPU0_P1_RX_DN<10>")
	)
	(arc
		(start 351.864422 -375.068592)
		(mid 351.933037 -375.033654)
		(end 352.00336 -375.002298)
		(width 0.14224)
		(layer "In11.Cu")
		(net "P5E_CPU0_P1_RX_DN<10>")
	)
	(arc
		(start 354.600764 -288.159698)
		(mid 354.714693 -288.026551)
		(end 354.755704 -287.856168)
		(width 0.1143)
		(layer "In11.Cu")
		(net "P5E_CPU0_P1_RX_DN<10>")
	)
	(arc
		(start 354.598732 -278.440896)
		(mid 354.696497 -278.33792)
		(end 354.748846 -278.205946)
		(width 0.1143)
		(layer "In11.Cu")
		(net "P5E_CPU0_P1_RX_DN<10>")
	)
	(arc
		(start 354.531676 -287.512252)
		(mid 354.351024 -287.309507)
		(end 354.285804 -287.045908)
		(width 0.1143)
		(layer "In11.Cu")
		(net "P5E_CPU0_P1_RX_DN<10>")
	)
	(arc
		(start 354.285804 -295.122092)
		(mid 354.35477 -294.863258)
		(end 354.54336 -294.67302)
		(width 0.1143)
		(layer "In11.Cu")
		(net "P5E_CPU0_P1_RX_DN<10>")
	)
	(arc
		(start 354.755704 -287.856168)
		(mid 354.714155 -287.684746)
		(end 354.598732 -287.551368)
		(width 0.1143)
		(layer "In11.Cu")
		(net "P5E_CPU0_P1_RX_DN<10>")
	)
	(arc
		(start 351.511108 -375.272808)
		(mid 351.578881 -375.226836)
		(end 351.649538 -375.185432)
		(width 0.14224)
		(layer "In11.Cu")
		(net "P5E_CPU0_P1_RX_DN<10>")
	)
	(arc
		(start 354.600764 -286.539686)
		(mid 354.714693 -286.406539)
		(end 354.755704 -286.236156)
		(width 0.1143)
		(layer "In11.Cu")
		(net "P5E_CPU0_P1_RX_DN<10>")
	)
	(arc
		(start 354.058982 -280.220674)
		(mid 353.815655 -279.756108)
		(end 354.058982 -279.291542)
		(width 0.1143)
		(layer "In11.Cu")
		(net "P5E_CPU0_P1_RX_DN<10>")
	)
	(arc
		(start 350.757744 -375.912634)
		(mid 351.122513 -375.578695)
		(end 351.511108 -375.272808)
		(width 0.14224)
		(layer "In11.Cu")
		(net "P5E_CPU0_P1_RX_DN<10>")
	)
	(arc
		(start 354.598732 -291.400738)
		(mid 354.755709 -291.095938)
		(end 354.598732 -290.791138)
		(width 0.1143)
		(layer "In11.Cu")
		(net "P5E_CPU0_P1_RX_DN<10>")
	)
	(arc
		(start 354.529136 -284.270704)
		(mid 354.285809 -283.806138)
		(end 354.529136 -283.341572)
		(width 0.1143)
		(layer "In11.Cu")
		(net "P5E_CPU0_P1_RX_DN<10>")
	)
	(arc
		(start 354.529136 -285.890716)
		(mid 354.285809 -285.42615)
		(end 354.529136 -284.961584)
		(width 0.1143)
		(layer "In11.Cu")
		(net "P5E_CPU0_P1_RX_DN<10>")
	)
	(arc
		(start 354.529136 -282.650692)
		(mid 354.285809 -282.186126)
		(end 354.529136 -281.72156)
		(width 0.1143)
		(layer "In11.Cu")
		(net "P5E_CPU0_P1_RX_DN<10>")
	)
	(arc
		(start 352.772726 -374.683274)
		(mid 355.333266 -373.314578)
		(end 357.577644 -371.472714)
		(width 0.14224)
		(layer "In11.Cu")
		(net "P5E_CPU0_P1_RX_DN<10>")
	)
	(arc
		(start 354.529136 -281.03068)
		(mid 354.350323 -280.82833)
		(end 354.285804 -280.566114)
		(width 0.1143)
		(layer "In11.Cu")
		(net "P5E_CPU0_P1_RX_DN<10>")
	)
	(arc
		(start 350.62668 -376.099324)
		(mid 350.683054 -376.000967)
		(end 350.755966 -375.914158)
		(width 0.14224)
		(layer "In11.Cu")
		(net "P5E_CPU0_P1_RX_DN<10>")
	)
	(arc
		(start 354.285804 -280.566114)
		(mid 354.244549 -280.395143)
		(end 354.129848 -280.261822)
		(width 0.1143)
		(layer "In11.Cu")
		(net "P5E_CPU0_P1_RX_DN<10>")
	)
	(arc
		(start 354.598732 -281.68092)
		(mid 354.755709 -281.37612)
		(end 354.598732 -281.07132)
		(width 0.1143)
		(layer "In11.Cu")
		(net "P5E_CPU0_P1_RX_DN<10>")
	)
	(segment
		(start 335.79816 -393.69238)
		(end 336.31886 -393.69238)
		(width 0.127)
		(layer "F.Cu")
		(net "P5E_CPU0_P1_RX_DN<0>")
	)
	(segment
		(start 346.387928 -276.250146)
		(end 345.921076 -276.516084)
		(width 0.12954)
		(layer "F.Cu")
		(net "P5E_CPU0_P1_RX_DN<0>")
	)
	(segment
		(start 344.67673 -279.281128)
		(end 344.729816 -279.250394)
		(width 0.1143)
		(layer "In11.Cu")
		(net "P5E_CPU0_P1_RX_DN<0>")
	)
	(segment
		(start 334.84312 -388.081012)
		(end 334.605884 -387.72592)
		(width 0.14224)
		(layer "In11.Cu")
		(net "P5E_CPU0_P1_RX_DN<0>")
	)
	(segment
		(start 336.482182 -392.61669)
		(end 336.78622 -392.312906)
		(width 0.14224)
		(layer "In11.Cu")
		(net "P5E_CPU0_P1_RX_DN<0>")
	)
	(segment
		(start 362.822744 -329.804522)
		(end 362.00715 -328.2442)
		(width 0.14224)
		(layer "In11.Cu")
		(net "P5E_CPU0_P1_RX_DN<0>")
	)
	(segment
		(start 345.63558 -277.650194)
		(end 345.637104 -277.649178)
		(width 0.1143)
		(layer "In11.Cu")
		(net "P5E_CPU0_P1_RX_DN<0>")
	)
	(segment
		(start 329.138534 -376.43562)
		(end 332.46187 -373.112284)
		(width 0.14224)
		(layer "In11.Cu")
		(net "P5E_CPU0_P1_RX_DN<0>")
	)
	(segment
		(start 364.698026 -343.810082)
		(end 364.698026 -340.233)
		(width 0.14224)
		(layer "In11.Cu")
		(net "P5E_CPU0_P1_RX_DN<0>")
	)
	(segment
		(start 345.129104 -283.341572)
		(end 345.1987 -283.300932)
		(width 0.1143)
		(layer "In11.Cu")
		(net "P5E_CPU0_P1_RX_DN<0>")
	)
	(segment
		(start 344.677492 -280.231596)
		(end 344.67673 -280.231088)
		(width 0.1143)
		(layer "In11.Cu")
		(net "P5E_CPU0_P1_RX_DN<0>")
	)
	(segment
		(start 345.16822 -288.178494)
		(end 345.200732 -288.159698)
		(width 0.1143)
		(layer "In11.Cu")
		(net "P5E_CPU0_P1_RX_DN<0>")
	)
	(segment
		(start 348.205044 -364.92688)
		(end 358.704388 -354.427536)
		(width 0.14224)
		(layer "In11.Cu")
		(net "P5E_CPU0_P1_RX_DN<0>")
	)
	(segment
		(start 345.1987 -281.07132)
		(end 345.129104 -281.03068)
		(width 0.1143)
		(layer "In11.Cu")
		(net "P5E_CPU0_P1_RX_DN<0>")
	)
	(segment
		(start 336.794348 -393.545822)
		(end 336.477356 -393.22883)
		(width 0.14224)
		(layer "In11.Cu")
		(net "P5E_CPU0_P1_RX_DN<0>")
	)
	(segment
		(start 335.270348 -388.473442)
		(end 335.033366 -388.118858)
		(width 0.14224)
		(layer "In11.Cu")
		(net "P5E_CPU0_P1_RX_DN<0>")
	)
	(segment
		(start 345.129104 -289.821366)
		(end 345.1987 -289.780726)
		(width 0.1143)
		(layer "In11.Cu")
		(net "P5E_CPU0_P1_RX_DN<0>")
	)
	(segment
		(start 344.370152 -296.435272)
		(end 344.415872 -296.389552)
		(width 0.1143)
		(layer "In11.Cu")
		(net "P5E_CPU0_P1_RX_DN<0>")
	)
	(segment
		(start 364.698026 -340.233)
		(end 362.822744 -329.804522)
		(width 0.14224)
		(layer "In11.Cu")
		(net "P5E_CPU0_P1_RX_DN<0>")
	)
	(segment
		(start 345.1987 -294.031162)
		(end 345.129104 -293.990522)
		(width 0.1143)
		(layer "In11.Cu")
		(net "P5E_CPU0_P1_RX_DN<0>")
	)
	(segment
		(start 336.672682 -393.786868)
		(end 336.794348 -393.716764)
		(width 0.14224)
		(layer "In11.Cu")
		(net "P5E_CPU0_P1_RX_DN<0>")
	)
	(segment
		(start 348.674182 -310.068976)
		(end 344.370152 -299.677582)
		(width 0.14224)
		(layer "In11.Cu")
		(net "P5E_CPU0_P1_RX_DN<0>")
	)
	(segment
		(start 362.00715 -328.2442)
		(end 355.608128 -320.446654)
		(width 0.14224)
		(layer "In11.Cu")
		(net "P5E_CPU0_P1_RX_DN<0>")
	)
	(segment
		(start 344.698066 -280.243534)
		(end 344.677492 -280.231596)
		(width 0.1143)
		(layer "In11.Cu")
		(net "P5E_CPU0_P1_RX_DN<0>")
	)
	(segment
		(start 345.638882 -277.648162)
		(end 345.640152 -277.6474)
		(width 0.1143)
		(layer "In11.Cu")
		(net "P5E_CPU0_P1_RX_DN<0>")
	)
	(segment
		(start 335.896966 -389.41121)
		(end 335.659984 -389.056626)
		(width 0.14224)
		(layer "In11.Cu")
		(net "P5E_CPU0_P1_RX_DN<0>")
	)
	(segment
		(start 336.31886 -393.69238)
		(end 336.672174 -393.787376)
		(width 0.14224)
		(layer "In11.Cu")
		(net "P5E_CPU0_P1_RX_DN<0>")
	)
	(segment
		(start 346.288868 -276.585934)
		(end 346.219018 -276.516084)
		(width 0.1143)
		(layer "In11.Cu")
		(net "P5E_CPU0_P1_RX_DN<0>")
	)
	(segment
		(start 336.78622 -392.312906)
		(end 336.78622 -390.780016)
		(width 0.14224)
		(layer "In11.Cu")
		(net "P5E_CPU0_P1_RX_DN<0>")
	)
	(segment
		(start 345.1987 -289.171126)
		(end 345.129104 -289.130486)
		(width 0.1143)
		(layer "In11.Cu")
		(net "P5E_CPU0_P1_RX_DN<0>")
	)
	(segment
		(start 344.415872 -295.869868)
		(end 344.885772 -295.399968)
		(width 0.1143)
		(layer "In11.Cu")
		(net "P5E_CPU0_P1_RX_DN<0>")
	)
	(segment
		(start 345.129104 -294.681402)
		(end 345.1987 -294.640762)
		(width 0.1143)
		(layer "In11.Cu")
		(net "P5E_CPU0_P1_RX_DN<0>")
	)
	(segment
		(start 345.1987 -282.691332)
		(end 345.129104 -282.650692)
		(width 0.1143)
		(layer "In11.Cu")
		(net "P5E_CPU0_P1_RX_DN<0>")
	)
	(segment
		(start 345.129104 -288.201354)
		(end 345.16822 -288.178494)
		(width 0.1143)
		(layer "In11.Cu")
		(net "P5E_CPU0_P1_RX_DN<0>")
	)
	(segment
		(start 345.129104 -286.581342)
		(end 345.131136 -286.579818)
		(width 0.1143)
		(layer "In11.Cu")
		(net "P5E_CPU0_P1_RX_DN<0>")
	)
	(segment
		(start 333.798418 -386.2705)
		(end 333.798164 -386.2705)
		(width 0.14224)
		(layer "In11.Cu")
		(net "P5E_CPU0_P1_RX_DN<0>")
	)
	(segment
		(start 344.729816 -280.261822)
		(end 344.698066 -280.243534)
		(width 0.1143)
		(layer "In11.Cu")
		(net "P5E_CPU0_P1_RX_DN<0>")
	)
	(segment
		(start 344.370152 -299.677582)
		(end 344.370152 -296.46372)
		(width 0.14224)
		(layer "In11.Cu")
		(net "P5E_CPU0_P1_RX_DN<0>")
	)
	(segment
		(start 336.794348 -393.716764)
		(end 336.794348 -393.545822)
		(width 0.14224)
		(layer "In11.Cu")
		(net "P5E_CPU0_P1_RX_DN<0>")
	)
	(segment
		(start 336.286602 -389.994394)
		(end 336.096356 -389.956548)
		(width 0.14224)
		(layer "In11.Cu")
		(net "P5E_CPU0_P1_RX_DN<0>")
	)
	(segment
		(start 345.1987 -290.791138)
		(end 345.129104 -290.750498)
		(width 0.1143)
		(layer "In11.Cu")
		(net "P5E_CPU0_P1_RX_DN<0>")
	)
	(segment
		(start 345.129104 -284.961584)
		(end 345.1987 -284.920944)
		(width 0.1143)
		(layer "In11.Cu")
		(net "P5E_CPU0_P1_RX_DN<0>")
	)
	(segment
		(start 345.16822 -286.558482)
		(end 345.200732 -286.539686)
		(width 0.1143)
		(layer "In11.Cu")
		(net "P5E_CPU0_P1_RX_DN<0>")
	)
	(segment
		(start 334.86471 -371.507004)
		(end 344.040968 -367.709196)
		(width 0.14224)
		(layer "In11.Cu")
		(net "P5E_CPU0_P1_RX_DN<0>")
	)
	(segment
		(start 345.129104 -291.441378)
		(end 345.1987 -291.400738)
		(width 0.1143)
		(layer "In11.Cu")
		(net "P5E_CPU0_P1_RX_DN<0>")
	)
	(segment
		(start 345.1987 -292.41115)
		(end 345.129104 -292.37051)
		(width 0.1143)
		(layer "In11.Cu")
		(net "P5E_CPU0_P1_RX_DN<0>")
	)
	(segment
		(start 345.1987 -287.551368)
		(end 345.131644 -287.512252)
		(width 0.1143)
		(layer "In11.Cu")
		(net "P5E_CPU0_P1_RX_DN<0>")
	)
	(segment
		(start 345.63812 -277.64867)
		(end 345.638882 -277.648162)
		(width 0.1143)
		(layer "In11.Cu")
		(net "P5E_CPU0_P1_RX_DN<0>")
	)
	(segment
		(start 329.00874 -381.293624)
		(end 329.00874 -376.749056)
		(width 0.14224)
		(layer "In11.Cu")
		(net "P5E_CPU0_P1_RX_DN<0>")
	)
	(segment
		(start 334.64373 -387.535674)
		(end 333.798418 -386.2705)
		(width 0.14224)
		(layer "In11.Cu")
		(net "P5E_CPU0_P1_RX_DN<0>")
	)
	(segment
		(start 346.219018 -276.516084)
		(end 345.921076 -276.516084)
		(width 0.1143)
		(layer "In11.Cu")
		(net "P5E_CPU0_P1_RX_DN<0>")
	)
	(segment
		(start 334.605884 -387.72592)
		(end 334.64373 -387.535674)
		(width 0.14224)
		(layer "In11.Cu")
		(net "P5E_CPU0_P1_RX_DN<0>")
	)
	(segment
		(start 363.754416 -346.870782)
		(end 364.398052 -345.317064)
		(width 0.14224)
		(layer "In11.Cu")
		(net "P5E_CPU0_P1_RX_DN<0>")
	)
	(segment
		(start 345.637104 -277.649178)
		(end 345.63812 -277.64867)
		(width 0.1143)
		(layer "In11.Cu")
		(net "P5E_CPU0_P1_RX_DN<0>")
	)
	(segment
		(start 345.1987 -285.931356)
		(end 345.129104 -285.890716)
		(width 0.1143)
		(layer "In11.Cu")
		(net "P5E_CPU0_P1_RX_DN<0>")
	)
	(segment
		(start 335.232502 -388.663688)
		(end 335.270348 -388.473442)
		(width 0.14224)
		(layer "In11.Cu")
		(net "P5E_CPU0_P1_RX_DN<0>")
	)
	(segment
		(start 345.640152 -277.6474)
		(end 345.66987 -277.630382)
		(width 0.1143)
		(layer "In11.Cu")
		(net "P5E_CPU0_P1_RX_DN<0>")
	)
	(segment
		(start 333.782162 -386.250942)
		(end 329.138534 -381.607314)
		(width 0.14224)
		(layer "In11.Cu")
		(net "P5E_CPU0_P1_RX_DN<0>")
	)
	(segment
		(start 345.129104 -293.06139)
		(end 345.1987 -293.02075)
		(width 0.1143)
		(layer "In11.Cu")
		(net "P5E_CPU0_P1_RX_DN<0>")
	)
	(segment
		(start 345.599004 -277.67153)
		(end 345.63558 -277.650194)
		(width 0.1143)
		(layer "In11.Cu")
		(net "P5E_CPU0_P1_RX_DN<0>")
	)
	(segment
		(start 335.85912 -389.601456)
		(end 335.896966 -389.41121)
		(width 0.14224)
		(layer "In11.Cu")
		(net "P5E_CPU0_P1_RX_DN<0>")
	)
	(segment
		(start 345.131136 -286.579818)
		(end 345.16822 -286.558482)
		(width 0.1143)
		(layer "In11.Cu")
		(net "P5E_CPU0_P1_RX_DN<0>")
	)
	(segment
		(start 336.78622 -390.780016)
		(end 336.785966 -390.78027)
		(width 0.14224)
		(layer "In11.Cu")
		(net "P5E_CPU0_P1_RX_DN<0>")
	)
	(segment
		(start 355.608128 -320.446654)
		(end 348.674182 -310.068976)
		(width 0.14224)
		(layer "In11.Cu")
		(net "P5E_CPU0_P1_RX_DN<0>")
	)
	(segment
		(start 335.469738 -389.01878)
		(end 335.232502 -388.663688)
		(width 0.14224)
		(layer "In11.Cu")
		(net "P5E_CPU0_P1_RX_DN<0>")
	)
	(segment
		(start 336.096356 -389.956548)
		(end 335.85912 -389.601456)
		(width 0.14224)
		(layer "In11.Cu")
		(net "P5E_CPU0_P1_RX_DN<0>")
	)
	(segment
		(start 336.672174 -393.787376)
		(end 336.672682 -393.786868)
		(width 0.14224)
		(layer "In11.Cu")
		(net "P5E_CPU0_P1_RX_DN<0>")
	)
	(segment
		(start 345.129104 -281.72156)
		(end 345.1987 -281.68092)
		(width 0.1143)
		(layer "In11.Cu")
		(net "P5E_CPU0_P1_RX_DN<0>")
	)
	(segment
		(start 346.069158 -276.861524)
		(end 346.138754 -276.820884)
		(width 0.1143)
		(layer "In11.Cu")
		(net "P5E_CPU0_P1_RX_DN<0>")
	)
	(segment
		(start 335.659984 -389.056626)
		(end 335.469738 -389.01878)
		(width 0.14224)
		(layer "In11.Cu")
		(net "P5E_CPU0_P1_RX_DN<0>")
	)
	(segment
		(start 344.885772 -295.399968)
		(end 344.885772 -295.145968)
		(width 0.1143)
		(layer "In11.Cu")
		(net "P5E_CPU0_P1_RX_DN<0>")
	)
	(segment
		(start 345.129104 -278.481536)
		(end 345.1987 -278.440896)
		(width 0.1143)
		(layer "In11.Cu")
		(net "P5E_CPU0_P1_RX_DN<0>")
	)
	(segment
		(start 344.370152 -296.46372)
		(end 344.370152 -296.435272)
		(width 0.1143)
		(layer "In11.Cu")
		(net "P5E_CPU0_P1_RX_DN<0>")
	)
	(segment
		(start 344.415872 -296.389552)
		(end 344.415872 -295.869868)
		(width 0.1143)
		(layer "In11.Cu")
		(net "P5E_CPU0_P1_RX_DN<0>")
	)
	(segment
		(start 336.477356 -393.22883)
		(end 336.482182 -392.61669)
		(width 0.14224)
		(layer "In11.Cu")
		(net "P5E_CPU0_P1_RX_DN<0>")
	)
	(segment
		(start 335.033366 -388.118858)
		(end 334.84312 -388.081012)
		(width 0.14224)
		(layer "In11.Cu")
		(net "P5E_CPU0_P1_RX_DN<0>")
	)
	(segment
		(start 336.76463 -390.709658)
		(end 336.286602 -389.994394)
		(width 0.14224)
		(layer "In11.Cu")
		(net "P5E_CPU0_P1_RX_DN<0>")
	)
	(segment
		(start 345.1987 -284.311344)
		(end 345.129104 -284.270704)
		(width 0.1143)
		(layer "In11.Cu")
		(net "P5E_CPU0_P1_RX_DN<0>")
	)
	(arc
		(start 345.1987 -289.780726)
		(mid 345.355677 -289.475926)
		(end 345.1987 -289.171126)
		(width 0.1143)
		(layer "In11.Cu")
		(net "P5E_CPU0_P1_RX_DN<0>")
	)
	(arc
		(start 344.040968 -367.709196)
		(mid 346.26003 -366.523108)
		(end 348.205044 -364.92688)
		(width 0.14224)
		(layer "In11.Cu")
		(net "P5E_CPU0_P1_RX_DN<0>")
	)
	(arc
		(start 332.46187 -373.112284)
		(mid 333.584177 -372.191224)
		(end 334.86471 -371.507004)
		(width 0.14224)
		(layer "In11.Cu")
		(net "P5E_CPU0_P1_RX_DN<0>")
	)
	(arc
		(start 345.200732 -288.159698)
		(mid 345.314661 -288.026551)
		(end 345.355672 -287.856168)
		(width 0.1143)
		(layer "In11.Cu")
		(net "P5E_CPU0_P1_RX_DN<0>")
	)
	(arc
		(start 345.129104 -282.650692)
		(mid 344.885777 -282.186126)
		(end 345.129104 -281.72156)
		(width 0.1143)
		(layer "In11.Cu")
		(net "P5E_CPU0_P1_RX_DN<0>")
	)
	(arc
		(start 344.885772 -287.045908)
		(mid 344.950287 -286.783689)
		(end 345.129104 -286.581342)
		(width 0.1143)
		(layer "In11.Cu")
		(net "P5E_CPU0_P1_RX_DN<0>")
	)
	(arc
		(start 345.355672 -286.236156)
		(mid 345.314123 -286.064734)
		(end 345.1987 -285.931356)
		(width 0.1143)
		(layer "In11.Cu")
		(net "P5E_CPU0_P1_RX_DN<0>")
	)
	(arc
		(start 345.129104 -293.990522)
		(mid 344.885777 -293.525956)
		(end 345.129104 -293.06139)
		(width 0.1143)
		(layer "In11.Cu")
		(net "P5E_CPU0_P1_RX_DN<0>")
	)
	(arc
		(start 329.138534 -381.607314)
		(mid 329.042398 -381.463391)
		(end 329.00874 -381.293624)
		(width 0.14224)
		(layer "In11.Cu")
		(net "P5E_CPU0_P1_RX_DN<0>")
	)
	(arc
		(start 345.1987 -281.68092)
		(mid 345.355677 -281.37612)
		(end 345.1987 -281.07132)
		(width 0.1143)
		(layer "In11.Cu")
		(net "P5E_CPU0_P1_RX_DN<0>")
	)
	(arc
		(start 336.785966 -390.78027)
		(mid 336.780564 -390.743369)
		(end 336.76463 -390.709658)
		(width 0.14224)
		(layer "In11.Cu")
		(net "P5E_CPU0_P1_RX_DN<0>")
	)
	(arc
		(start 345.129104 -289.130486)
		(mid 344.885777 -288.66592)
		(end 345.129104 -288.201354)
		(width 0.1143)
		(layer "In11.Cu")
		(net "P5E_CPU0_P1_RX_DN<0>")
	)
	(arc
		(start 345.355672 -287.856168)
		(mid 345.314123 -287.684746)
		(end 345.1987 -287.551368)
		(width 0.1143)
		(layer "In11.Cu")
		(net "P5E_CPU0_P1_RX_DN<0>")
	)
	(arc
		(start 345.66987 -277.630382)
		(mid 345.784546 -277.497048)
		(end 345.825826 -277.32609)
		(width 0.1143)
		(layer "In11.Cu")
		(net "P5E_CPU0_P1_RX_DN<0>")
	)
	(arc
		(start 345.1987 -293.02075)
		(mid 345.355677 -292.71595)
		(end 345.1987 -292.41115)
		(width 0.1143)
		(layer "In11.Cu")
		(net "P5E_CPU0_P1_RX_DN<0>")
	)
	(arc
		(start 344.66911 -279.2857)
		(mid 344.672911 -279.283399)
		(end 344.67673 -279.281128)
		(width 0.1143)
		(layer "In11.Cu")
		(net "P5E_CPU0_P1_RX_DN<0>")
	)
	(arc
		(start 345.1987 -284.920944)
		(mid 345.355677 -284.616144)
		(end 345.1987 -284.311344)
		(width 0.1143)
		(layer "In11.Cu")
		(net "P5E_CPU0_P1_RX_DN<0>")
	)
	(arc
		(start 345.1987 -283.300932)
		(mid 345.355677 -282.996132)
		(end 345.1987 -282.691332)
		(width 0.1143)
		(layer "In11.Cu")
		(net "P5E_CPU0_P1_RX_DN<0>")
	)
	(arc
		(start 364.398052 -345.317064)
		(mid 364.622256 -344.578348)
		(end 364.698026 -343.810082)
		(width 0.14224)
		(layer "In11.Cu")
		(net "P5E_CPU0_P1_RX_DN<0>")
	)
	(arc
		(start 345.1987 -278.440896)
		(mid 345.314127 -278.30752)
		(end 345.355672 -278.136096)
		(width 0.1143)
		(layer "In11.Cu")
		(net "P5E_CPU0_P1_RX_DN<0>")
	)
	(arc
		(start 345.825826 -277.32609)
		(mid 345.890341 -277.063871)
		(end 346.069158 -276.861524)
		(width 0.1143)
		(layer "In11.Cu")
		(net "P5E_CPU0_P1_RX_DN<0>")
	)
	(arc
		(start 345.200732 -286.539686)
		(mid 345.314661 -286.406539)
		(end 345.355672 -286.236156)
		(width 0.1143)
		(layer "In11.Cu")
		(net "P5E_CPU0_P1_RX_DN<0>")
	)
	(arc
		(start 345.129104 -285.890716)
		(mid 344.885777 -285.42615)
		(end 345.129104 -284.961584)
		(width 0.1143)
		(layer "In11.Cu")
		(net "P5E_CPU0_P1_RX_DN<0>")
	)
	(arc
		(start 345.355672 -278.136096)
		(mid 345.420187 -277.873877)
		(end 345.599004 -277.67153)
		(width 0.1143)
		(layer "In11.Cu")
		(net "P5E_CPU0_P1_RX_DN<0>")
	)
	(arc
		(start 345.1987 -291.400738)
		(mid 345.355677 -291.095938)
		(end 345.1987 -290.791138)
		(width 0.1143)
		(layer "In11.Cu")
		(net "P5E_CPU0_P1_RX_DN<0>")
	)
	(arc
		(start 345.129104 -290.750498)
		(mid 344.885777 -290.285932)
		(end 345.129104 -289.821366)
		(width 0.1143)
		(layer "In11.Cu")
		(net "P5E_CPU0_P1_RX_DN<0>")
	)
	(arc
		(start 329.00874 -376.749056)
		(mid 329.042479 -376.579439)
		(end 329.138534 -376.43562)
		(width 0.14224)
		(layer "In11.Cu")
		(net "P5E_CPU0_P1_RX_DN<0>")
	)
	(arc
		(start 358.704388 -354.427536)
		(mid 361.601394 -350.897753)
		(end 363.754416 -346.870782)
		(width 0.14224)
		(layer "In11.Cu")
		(net "P5E_CPU0_P1_RX_DN<0>")
	)
	(arc
		(start 345.1987 -294.640762)
		(mid 345.355677 -294.335962)
		(end 345.1987 -294.031162)
		(width 0.1143)
		(layer "In11.Cu")
		(net "P5E_CPU0_P1_RX_DN<0>")
	)
	(arc
		(start 345.129104 -281.03068)
		(mid 344.950291 -280.82833)
		(end 344.885772 -280.566114)
		(width 0.1143)
		(layer "In11.Cu")
		(net "P5E_CPU0_P1_RX_DN<0>")
	)
	(arc
		(start 346.138754 -276.820884)
		(mid 346.236519 -276.717908)
		(end 346.288868 -276.585934)
		(width 0.1143)
		(layer "In11.Cu")
		(net "P5E_CPU0_P1_RX_DN<0>")
	)
	(arc
		(start 344.885772 -278.946102)
		(mid 344.950287 -278.683883)
		(end 345.129104 -278.481536)
		(width 0.1143)
		(layer "In11.Cu")
		(net "P5E_CPU0_P1_RX_DN<0>")
	)
	(arc
		(start 344.729816 -279.250394)
		(mid 344.844492 -279.11706)
		(end 344.885772 -278.946102)
		(width 0.1143)
		(layer "In11.Cu")
		(net "P5E_CPU0_P1_RX_DN<0>")
	)
	(arc
		(start 333.798164 -386.2705)
		(mid 333.790644 -386.260328)
		(end 333.782162 -386.250942)
		(width 0.14224)
		(layer "In11.Cu")
		(net "P5E_CPU0_P1_RX_DN<0>")
	)
	(arc
		(start 345.129104 -284.270704)
		(mid 344.885777 -283.806138)
		(end 345.129104 -283.341572)
		(width 0.1143)
		(layer "In11.Cu")
		(net "P5E_CPU0_P1_RX_DN<0>")
	)
	(arc
		(start 344.669364 -280.226516)
		(mid 344.412478 -279.756215)
		(end 344.66911 -279.2857)
		(width 0.1143)
		(layer "In11.Cu")
		(net "P5E_CPU0_P1_RX_DN<0>")
	)
	(arc
		(start 345.131644 -287.512252)
		(mid 344.950992 -287.309507)
		(end 344.885772 -287.045908)
		(width 0.1143)
		(layer "In11.Cu")
		(net "P5E_CPU0_P1_RX_DN<0>")
	)
	(arc
		(start 344.67673 -280.231088)
		(mid 344.673038 -280.228817)
		(end 344.669364 -280.226516)
		(width 0.1143)
		(layer "In11.Cu")
		(net "P5E_CPU0_P1_RX_DN<0>")
	)
	(arc
		(start 344.885772 -295.145968)
		(mid 344.950287 -294.883749)
		(end 345.129104 -294.681402)
		(width 0.1143)
		(layer "In11.Cu")
		(net "P5E_CPU0_P1_RX_DN<0>")
	)
	(arc
		(start 345.129104 -292.37051)
		(mid 344.885777 -291.905944)
		(end 345.129104 -291.441378)
		(width 0.1143)
		(layer "In11.Cu")
		(net "P5E_CPU0_P1_RX_DN<0>")
	)
	(arc
		(start 344.885772 -280.566114)
		(mid 344.844517 -280.395143)
		(end 344.729816 -280.261822)
		(width 0.1143)
		(layer "In11.Cu")
		(net "P5E_CPU0_P1_RX_DN<0>")
	)
	(segment
		(start 314.601606 -378.39142)
		(end 314.601606 -377.68784)
		(width 0.12954)
		(layer "F.Cu")
		(net "P5E_CPU0_P0_TX_DP<9>")
	)
	(segment
		(start 314.305696 -378.68733)
		(end 314.601606 -378.39142)
		(width 0.12954)
		(layer "F.Cu")
		(net "P5E_CPU0_P0_TX_DP<9>")
	)
	(segment
		(start 314.601606 -377.68784)
		(end 314.331096 -377.41733)
		(width 0.12954)
		(layer "F.Cu")
		(net "P5E_CPU0_P0_TX_DP<9>")
	)
	(segment
		(start 352.027998 -282.730194)
		(end 351.561146 -282.996132)
		(width 0.12954)
		(layer "F.Cu")
		(net "P5E_CPU0_P0_TX_DP<9>")
	)
	(segment
		(start 353.180142 -295.542208)
		(end 353.060762 -295.661588)
		(width 0.1143)
		(layer "In6.Cu")
		(net "P5E_CPU0_P0_TX_DP<9>")
	)
	(segment
		(start 353.121722 -285.082488)
		(end 353.158044 -285.10357)
		(width 0.1143)
		(layer "In6.Cu")
		(net "P5E_CPU0_P0_TX_DP<9>")
	)
	(segment
		(start 353.628198 -288.178494)
		(end 353.589082 -288.201354)
		(width 0.1143)
		(layer "In6.Cu")
		(net "P5E_CPU0_P0_TX_DP<9>")
	)
	(segment
		(start 353.628198 -289.153346)
		(end 353.658678 -289.171126)
		(width 0.1143)
		(layer "In6.Cu")
		(net "P5E_CPU0_P0_TX_DP<9>")
	)
	(segment
		(start 352.957638 -296.206926)
		(end 352.911918 -296.252646)
		(width 0.1143)
		(layer "In6.Cu")
		(net "P5E_CPU0_P0_TX_DP<9>")
	)
	(segment
		(start 353.658678 -289.780726)
		(end 353.628198 -289.798506)
		(width 0.1143)
		(layer "In6.Cu")
		(net "P5E_CPU0_P0_TX_DP<9>")
	)
	(segment
		(start 352.911918 -296.281094)
		(end 352.911918 -298.370498)
		(width 0.14224)
		(layer "In6.Cu")
		(net "P5E_CPU0_P0_TX_DP<9>")
	)
	(segment
		(start 353.658678 -291.400738)
		(end 353.628198 -291.418518)
		(width 0.1143)
		(layer "In6.Cu")
		(net "P5E_CPU0_P0_TX_DP<9>")
	)
	(segment
		(start 361.940348 -314.79236)
		(end 367.891568 -322.043806)
		(width 0.14224)
		(layer "In6.Cu")
		(net "P5E_CPU0_P0_TX_DP<9>")
	)
	(segment
		(start 314.621926 -377.1265)
		(end 314.331096 -377.41733)
		(width 0.14224)
		(layer "In6.Cu")
		(net "P5E_CPU0_P0_TX_DP<9>")
	)
	(segment
		(start 352.649028 -284.270958)
		(end 352.711258 -284.307026)
		(width 0.1143)
		(layer "In6.Cu")
		(net "P5E_CPU0_P0_TX_DP<9>")
	)
	(segment
		(start 353.158044 -285.74873)
		(end 353.13747 -285.760668)
		(width 0.1143)
		(layer "In6.Cu")
		(net "P5E_CPU0_P0_TX_DP<9>")
	)
	(segment
		(start 352.218244 -283.483558)
		(end 352.248724 -283.501338)
		(width 0.1143)
		(layer "In6.Cu")
		(net "P5E_CPU0_P0_TX_DP<9>")
	)
	(segment
		(start 315.101732 -375.948448)
		(end 314.709048 -376.341132)
		(width 0.14224)
		(layer "In6.Cu")
		(net "P5E_CPU0_P0_TX_DP<9>")
	)
	(segment
		(start 353.589082 -293.990522)
		(end 353.628198 -294.013382)
		(width 0.1143)
		(layer "In6.Cu")
		(net "P5E_CPU0_P0_TX_DP<9>")
	)
	(segment
		(start 353.628198 -294.013382)
		(end 353.658678 -294.031162)
		(width 0.1143)
		(layer "In6.Cu")
		(net "P5E_CPU0_P0_TX_DP<9>")
	)
	(segment
		(start 352.911918 -298.370498)
		(end 356.082854 -306.026058)
		(width 0.14224)
		(layer "In6.Cu")
		(net "P5E_CPU0_P0_TX_DP<9>")
	)
	(segment
		(start 373.431308 -340.53653)
		(end 373.431308 -350.65462)
		(width 0.14224)
		(layer "In6.Cu")
		(net "P5E_CPU0_P0_TX_DP<9>")
	)
	(segment
		(start 366.996726 -366.188752)
		(end 360.961432 -372.224046)
		(width 0.14224)
		(layer "In6.Cu")
		(net "P5E_CPU0_P0_TX_DP<9>")
	)
	(segment
		(start 353.658678 -294.640762)
		(end 353.589082 -294.681402)
		(width 0.1143)
		(layer "In6.Cu")
		(net "P5E_CPU0_P0_TX_DP<9>")
	)
	(segment
		(start 351.561146 -282.996132)
		(end 351.859088 -282.996132)
		(width 0.1143)
		(layer "In6.Cu")
		(net "P5E_CPU0_P0_TX_DP<9>")
	)
	(segment
		(start 320.609214 -373.521478)
		(end 315.674756 -375.565416)
		(width 0.14224)
		(layer "In6.Cu")
		(net "P5E_CPU0_P0_TX_DP<9>")
	)
	(segment
		(start 367.891568 -322.043806)
		(end 371.26926 -328.50582)
		(width 0.14224)
		(layer "In6.Cu")
		(net "P5E_CPU0_P0_TX_DP<9>")
	)
	(segment
		(start 352.957638 -295.910254)
		(end 352.957638 -296.206926)
		(width 0.1143)
		(layer "In6.Cu")
		(net "P5E_CPU0_P0_TX_DP<9>")
	)
	(segment
		(start 353.589082 -292.37051)
		(end 353.628198 -292.39337)
		(width 0.1143)
		(layer "In6.Cu")
		(net "P5E_CPU0_P0_TX_DP<9>")
	)
	(segment
		(start 353.591622 -287.512252)
		(end 353.658678 -287.551368)
		(width 0.1143)
		(layer "In6.Cu")
		(net "P5E_CPU0_P0_TX_DP<9>")
	)
	(segment
		(start 353.628198 -289.798506)
		(end 353.589082 -289.821366)
		(width 0.1143)
		(layer "In6.Cu")
		(net "P5E_CPU0_P0_TX_DP<9>")
	)
	(segment
		(start 353.628198 -291.418518)
		(end 353.589082 -291.441378)
		(width 0.1143)
		(layer "In6.Cu")
		(net "P5E_CPU0_P0_TX_DP<9>")
	)
	(segment
		(start 353.589082 -290.750498)
		(end 353.628198 -290.773358)
		(width 0.1143)
		(layer "In6.Cu")
		(net "P5E_CPU0_P0_TX_DP<9>")
	)
	(segment
		(start 353.589082 -289.130486)
		(end 353.628198 -289.153346)
		(width 0.1143)
		(layer "In6.Cu")
		(net "P5E_CPU0_P0_TX_DP<9>")
	)
	(segment
		(start 353.628198 -292.39337)
		(end 353.658678 -292.41115)
		(width 0.1143)
		(layer "In6.Cu")
		(net "P5E_CPU0_P0_TX_DP<9>")
	)
	(segment
		(start 353.66071 -288.159698)
		(end 353.628198 -288.178494)
		(width 0.1143)
		(layer "In6.Cu")
		(net "P5E_CPU0_P0_TX_DP<9>")
	)
	(segment
		(start 358.675178 -373.170958)
		(end 322.37172 -373.170958)
		(width 0.14224)
		(layer "In6.Cu")
		(net "P5E_CPU0_P0_TX_DP<9>")
	)
	(segment
		(start 314.709048 -376.341132)
		(end 314.621926 -376.551444)
		(width 0.14224)
		(layer "In6.Cu")
		(net "P5E_CPU0_P0_TX_DP<9>")
	)
	(segment
		(start 314.621926 -376.551444)
		(end 314.621926 -377.1265)
		(width 0.14224)
		(layer "In6.Cu")
		(net "P5E_CPU0_P0_TX_DP<9>")
	)
	(segment
		(start 353.658678 -293.02075)
		(end 353.628198 -293.03853)
		(width 0.1143)
		(layer "In6.Cu")
		(net "P5E_CPU0_P0_TX_DP<9>")
	)
	(segment
		(start 353.136708 -286.711136)
		(end 353.191572 -286.74314)
		(width 0.1143)
		(layer "In6.Cu")
		(net "P5E_CPU0_P0_TX_DP<9>")
	)
	(segment
		(start 352.179128 -283.460698)
		(end 352.218244 -283.483558)
		(width 0.1143)
		(layer "In6.Cu")
		(net "P5E_CPU0_P0_TX_DP<9>")
	)
	(segment
		(start 353.628198 -293.03853)
		(end 353.589082 -293.06139)
		(width 0.1143)
		(layer "In6.Cu")
		(net "P5E_CPU0_P0_TX_DP<9>")
	)
	(segment
		(start 352.911918 -296.252646)
		(end 352.911918 -296.281094)
		(width 0.1143)
		(layer "In6.Cu")
		(net "P5E_CPU0_P0_TX_DP<9>")
	)
	(segment
		(start 371.26926 -328.50582)
		(end 373.431308 -340.53653)
		(width 0.14224)
		(layer "In6.Cu")
		(net "P5E_CPU0_P0_TX_DP<9>")
	)
	(segment
		(start 353.158044 -285.10357)
		(end 353.189794 -285.121858)
		(width 0.1143)
		(layer "In6.Cu")
		(net "P5E_CPU0_P0_TX_DP<9>")
	)
	(segment
		(start 353.13747 -285.760668)
		(end 353.136708 -285.761176)
		(width 0.1143)
		(layer "In6.Cu")
		(net "P5E_CPU0_P0_TX_DP<9>")
	)
	(segment
		(start 356.082854 -306.026058)
		(end 361.940348 -314.79236)
		(width 0.14224)
		(layer "In6.Cu")
		(net "P5E_CPU0_P0_TX_DP<9>")
	)
	(segment
		(start 353.628198 -290.773358)
		(end 353.658678 -290.791138)
		(width 0.1143)
		(layer "In6.Cu")
		(net "P5E_CPU0_P0_TX_DP<9>")
	)
	(segment
		(start 351.859088 -282.996132)
		(end 351.941892 -283.078936)
		(width 0.1143)
		(layer "In6.Cu")
		(net "P5E_CPU0_P0_TX_DP<9>")
	)
	(segment
		(start 353.189794 -285.730442)
		(end 353.158044 -285.74873)
		(width 0.1143)
		(layer "In6.Cu")
		(net "P5E_CPU0_P0_TX_DP<9>")
	)
	(arc
		(start 353.34575 -287.045908)
		(mid 353.410986 -287.309499)
		(end 353.591622 -287.512252)
		(width 0.1143)
		(layer "In6.Cu")
		(net "P5E_CPU0_P0_TX_DP<9>")
	)
	(arc
		(start 353.191572 -286.74314)
		(mid 353.304979 -286.876029)
		(end 353.34575 -287.045908)
		(width 0.1143)
		(layer "In6.Cu")
		(net "P5E_CPU0_P0_TX_DP<9>")
	)
	(arc
		(start 352.711258 -284.307026)
		(mid 352.819458 -284.442428)
		(end 352.873818 -284.607)
		(width 0.1143)
		(layer "In6.Cu")
		(net "P5E_CPU0_P0_TX_DP<9>")
	)
	(arc
		(start 353.060762 -295.661588)
		(mid 352.984501 -295.775676)
		(end 352.957638 -295.910254)
		(width 0.1143)
		(layer "In6.Cu")
		(net "P5E_CPU0_P0_TX_DP<9>")
	)
	(arc
		(start 351.945702 -283.101796)
		(mid 352.027135 -283.304194)
		(end 352.179128 -283.460698)
		(width 0.1143)
		(layer "In6.Cu")
		(net "P5E_CPU0_P0_TX_DP<9>")
	)
	(arc
		(start 322.37172 -373.170958)
		(mid 321.473204 -373.259426)
		(end 320.609214 -373.521478)
		(width 0.14224)
		(layer "In6.Cu")
		(net "P5E_CPU0_P0_TX_DP<9>")
	)
	(arc
		(start 352.87585 -284.63113)
		(mid 352.94147 -284.880648)
		(end 353.111054 -285.075122)
		(width 0.1143)
		(layer "In6.Cu")
		(net "P5E_CPU0_P0_TX_DP<9>")
	)
	(arc
		(start 352.873818 -284.607)
		(mid 352.875127 -284.61904)
		(end 352.87585 -284.63113)
		(width 0.1143)
		(layer "In6.Cu")
		(net "P5E_CPU0_P0_TX_DP<9>")
	)
	(arc
		(start 353.589082 -291.441378)
		(mid 353.345755 -291.905944)
		(end 353.589082 -292.37051)
		(width 0.1143)
		(layer "In6.Cu")
		(net "P5E_CPU0_P0_TX_DP<9>")
	)
	(arc
		(start 353.81565 -287.856168)
		(mid 353.774684 -288.026574)
		(end 353.66071 -288.159698)
		(width 0.1143)
		(layer "In6.Cu")
		(net "P5E_CPU0_P0_TX_DP<9>")
	)
	(arc
		(start 352.40595 -283.806138)
		(mid 352.470338 -284.068431)
		(end 352.649028 -284.270958)
		(width 0.1143)
		(layer "In6.Cu")
		(net "P5E_CPU0_P0_TX_DP<9>")
	)
	(arc
		(start 315.674756 -375.565416)
		(mid 315.369377 -375.728707)
		(end 315.101732 -375.948448)
		(width 0.14224)
		(layer "In6.Cu")
		(net "P5E_CPU0_P0_TX_DP<9>")
	)
	(arc
		(start 352.248724 -283.501338)
		(mid 352.364243 -283.634695)
		(end 352.40595 -283.806138)
		(width 0.1143)
		(layer "In6.Cu")
		(net "P5E_CPU0_P0_TX_DP<9>")
	)
	(arc
		(start 353.658678 -289.171126)
		(mid 353.815655 -289.475926)
		(end 353.658678 -289.780726)
		(width 0.1143)
		(layer "In6.Cu")
		(net "P5E_CPU0_P0_TX_DP<9>")
	)
	(arc
		(start 353.589082 -289.821366)
		(mid 353.345755 -290.285932)
		(end 353.589082 -290.750498)
		(width 0.1143)
		(layer "In6.Cu")
		(net "P5E_CPU0_P0_TX_DP<9>")
	)
	(arc
		(start 353.658678 -290.791138)
		(mid 353.815655 -291.095938)
		(end 353.658678 -291.400738)
		(width 0.1143)
		(layer "In6.Cu")
		(net "P5E_CPU0_P0_TX_DP<9>")
	)
	(arc
		(start 373.431308 -350.65462)
		(mid 371.758956 -359.061629)
		(end 366.996726 -366.188752)
		(width 0.14224)
		(layer "In6.Cu")
		(net "P5E_CPU0_P0_TX_DP<9>")
	)
	(arc
		(start 353.589082 -293.06139)
		(mid 353.345755 -293.525956)
		(end 353.589082 -293.990522)
		(width 0.1143)
		(layer "In6.Cu")
		(net "P5E_CPU0_P0_TX_DP<9>")
	)
	(arc
		(start 360.961432 -372.224046)
		(mid 359.912476 -372.924873)
		(end 358.675178 -373.170958)
		(width 0.14224)
		(layer "In6.Cu")
		(net "P5E_CPU0_P0_TX_DP<9>")
	)
	(arc
		(start 353.111054 -285.075122)
		(mid 353.116368 -285.078834)
		(end 353.121722 -285.082488)
		(width 0.1143)
		(layer "In6.Cu")
		(net "P5E_CPU0_P0_TX_DP<9>")
	)
	(arc
		(start 353.658678 -294.031162)
		(mid 353.815655 -294.335962)
		(end 353.658678 -294.640762)
		(width 0.1143)
		(layer "In6.Cu")
		(net "P5E_CPU0_P0_TX_DP<9>")
	)
	(arc
		(start 353.589082 -294.681402)
		(mid 353.410682 -294.882965)
		(end 353.34575 -295.14419)
		(width 0.1143)
		(layer "In6.Cu")
		(net "P5E_CPU0_P0_TX_DP<9>")
	)
	(arc
		(start 353.658678 -287.551368)
		(mid 353.774105 -287.684744)
		(end 353.81565 -287.856168)
		(width 0.1143)
		(layer "In6.Cu")
		(net "P5E_CPU0_P0_TX_DP<9>")
	)
	(arc
		(start 351.941892 -283.078936)
		(mid 351.94368 -283.090385)
		(end 351.945702 -283.101796)
		(width 0.1143)
		(layer "In6.Cu")
		(net "P5E_CPU0_P0_TX_DP<9>")
	)
	(arc
		(start 353.658678 -292.41115)
		(mid 353.815655 -292.71595)
		(end 353.658678 -293.02075)
		(width 0.1143)
		(layer "In6.Cu")
		(net "P5E_CPU0_P0_TX_DP<9>")
	)
	(arc
		(start 353.189794 -285.121858)
		(mid 353.345722 -285.42615)
		(end 353.189794 -285.730442)
		(width 0.1143)
		(layer "In6.Cu")
		(net "P5E_CPU0_P0_TX_DP<9>")
	)
	(arc
		(start 353.34575 -295.14419)
		(mid 353.302358 -295.359591)
		(end 353.180142 -295.542208)
		(width 0.1143)
		(layer "In6.Cu")
		(net "P5E_CPU0_P0_TX_DP<9>")
	)
	(arc
		(start 353.136708 -285.761176)
		(mid 352.863157 -286.236156)
		(end 353.136708 -286.711136)
		(width 0.1143)
		(layer "In6.Cu")
		(net "P5E_CPU0_P0_TX_DP<9>")
	)
	(arc
		(start 353.589082 -288.201354)
		(mid 353.345755 -288.66592)
		(end 353.589082 -289.130486)
		(width 0.1143)
		(layer "In6.Cu")
		(net "P5E_CPU0_P0_TX_DP<9>")
	)
	(segment
		(start 312.899806 -380.85522)
		(end 312.899806 -380.15164)
		(width 0.12954)
		(layer "F.Cu")
		(net "P5E_CPU0_P0_TX_DP<8>")
	)
	(segment
		(start 312.899806 -380.15164)
		(end 312.629296 -379.88113)
		(width 0.12954)
		(layer "F.Cu")
		(net "P5E_CPU0_P0_TX_DP<8>")
	)
	(segment
		(start 312.603896 -381.15113)
		(end 312.899806 -380.85522)
		(width 0.12954)
		(layer "F.Cu")
		(net "P5E_CPU0_P0_TX_DP<8>")
	)
	(segment
		(start 352.027998 -285.970218)
		(end 351.561146 -286.236156)
		(width 0.12954)
		(layer "F.Cu")
		(net "P5E_CPU0_P0_TX_DP<8>")
	)
	(segment
		(start 352.656648 -290.75507)
		(end 352.688144 -290.773358)
		(width 0.1143)
		(layer "In6.Cu")
		(net "P5E_CPU0_P0_TX_DP<8>")
	)
	(segment
		(start 352.687128 -291.419026)
		(end 352.685604 -291.420042)
		(width 0.1143)
		(layer "In6.Cu")
		(net "P5E_CPU0_P0_TX_DP<8>")
	)
	(segment
		(start 352.688906 -289.797998)
		(end 352.688144 -289.798506)
		(width 0.1143)
		(layer "In6.Cu")
		(net "P5E_CPU0_P0_TX_DP<8>")
	)
	(segment
		(start 352.719894 -291.40023)
		(end 352.688906 -291.41801)
		(width 0.1143)
		(layer "In6.Cu")
		(net "P5E_CPU0_P0_TX_DP<8>")
	)
	(segment
		(start 352.720656 -294.032178)
		(end 352.720656 -294.032432)
		(width 0.1143)
		(layer "In6.Cu")
		(net "P5E_CPU0_P0_TX_DP<8>")
	)
	(segment
		(start 352.649028 -292.37051)
		(end 352.655886 -292.374574)
		(width 0.1143)
		(layer "In6.Cu")
		(net "P5E_CPU0_P0_TX_DP<8>")
	)
	(segment
		(start 352.655886 -290.754562)
		(end 352.656648 -290.75507)
		(width 0.1143)
		(layer "In6.Cu")
		(net "P5E_CPU0_P0_TX_DP<8>")
	)
	(segment
		(start 352.688144 -291.418518)
		(end 352.687128 -291.419026)
		(width 0.1143)
		(layer "In6.Cu")
		(net "P5E_CPU0_P0_TX_DP<8>")
	)
	(segment
		(start 352.685604 -289.80003)
		(end 352.649028 -289.821366)
		(width 0.1143)
		(layer "In6.Cu")
		(net "P5E_CPU0_P0_TX_DP<8>")
	)
	(segment
		(start 361.19181 -315.350144)
		(end 367.10874 -322.55968)
		(width 0.14224)
		(layer "In6.Cu")
		(net "P5E_CPU0_P0_TX_DP<8>")
	)
	(segment
		(start 352.40595 -295.145714)
		(end 352.40595 -295.209214)
		(width 0.1143)
		(layer "In6.Cu")
		(net "P5E_CPU0_P0_TX_DP<8>")
	)
	(segment
		(start 352.655886 -287.514792)
		(end 352.656648 -287.5153)
		(width 0.1143)
		(layer "In6.Cu")
		(net "P5E_CPU0_P0_TX_DP<8>")
	)
	(segment
		(start 367.10874 -322.55968)
		(end 370.3574 -328.774552)
		(width 0.14224)
		(layer "In6.Cu")
		(net "P5E_CPU0_P0_TX_DP<8>")
	)
	(segment
		(start 352.218244 -286.723582)
		(end 352.250756 -286.742378)
		(width 0.1143)
		(layer "In6.Cu")
		(net "P5E_CPU0_P0_TX_DP<8>")
	)
	(segment
		(start 352.649028 -290.750498)
		(end 352.655886 -290.754562)
		(width 0.1143)
		(layer "In6.Cu")
		(net "P5E_CPU0_P0_TX_DP<8>")
	)
	(segment
		(start 352.688144 -293.03853)
		(end 352.687128 -293.039038)
		(width 0.1143)
		(layer "In6.Cu")
		(net "P5E_CPU0_P0_TX_DP<8>")
	)
	(segment
		(start 352.656648 -287.5153)
		(end 352.687128 -287.53308)
		(width 0.1143)
		(layer "In6.Cu")
		(net "P5E_CPU0_P0_TX_DP<8>")
	)
	(segment
		(start 352.651568 -287.512252)
		(end 352.655886 -287.514792)
		(width 0.1143)
		(layer "In6.Cu")
		(net "P5E_CPU0_P0_TX_DP<8>")
	)
	(segment
		(start 352.685604 -293.040054)
		(end 352.649028 -293.06139)
		(width 0.1143)
		(layer "In6.Cu")
		(net "P5E_CPU0_P0_TX_DP<8>")
	)
	(segment
		(start 352.688144 -292.39337)
		(end 352.688906 -292.393878)
		(width 0.1143)
		(layer "In6.Cu")
		(net "P5E_CPU0_P0_TX_DP<8>")
	)
	(segment
		(start 352.721672 -288.158936)
		(end 352.688144 -288.178494)
		(width 0.1143)
		(layer "In6.Cu")
		(net "P5E_CPU0_P0_TX_DP<8>")
	)
	(segment
		(start 351.966784 -296.281094)
		(end 351.966784 -298.525184)
		(width 0.14224)
		(layer "In6.Cu")
		(net "P5E_CPU0_P0_TX_DP<8>")
	)
	(segment
		(start 352.655886 -289.13455)
		(end 352.656648 -289.135058)
		(width 0.1143)
		(layer "In6.Cu")
		(net "P5E_CPU0_P0_TX_DP<8>")
	)
	(segment
		(start 352.656648 -292.375082)
		(end 352.688144 -292.39337)
		(width 0.1143)
		(layer "In6.Cu")
		(net "P5E_CPU0_P0_TX_DP<8>")
	)
	(segment
		(start 352.720656 -294.639746)
		(end 352.649028 -294.681402)
		(width 0.1143)
		(layer "In6.Cu")
		(net "P5E_CPU0_P0_TX_DP<8>")
	)
	(segment
		(start 352.012504 -296.206926)
		(end 351.966784 -296.252646)
		(width 0.1143)
		(layer "In6.Cu")
		(net "P5E_CPU0_P0_TX_DP<8>")
	)
	(segment
		(start 352.505264 -294.82542)
		(end 352.505518 -294.825674)
		(width 0.1143)
		(layer "In6.Cu")
		(net "P5E_CPU0_P0_TX_DP<8>")
	)
	(segment
		(start 352.719894 -293.020242)
		(end 352.688906 -293.038022)
		(width 0.1143)
		(layer "In6.Cu")
		(net "P5E_CPU0_P0_TX_DP<8>")
	)
	(segment
		(start 351.859088 -286.236156)
		(end 351.941892 -286.31896)
		(width 0.1143)
		(layer "In6.Cu")
		(net "P5E_CPU0_P0_TX_DP<8>")
	)
	(segment
		(start 352.688144 -290.773358)
		(end 352.688906 -290.773866)
		(width 0.1143)
		(layer "In6.Cu")
		(net "P5E_CPU0_P0_TX_DP<8>")
	)
	(segment
		(start 312.920126 -377.246388)
		(end 312.920126 -379.5903)
		(width 0.14224)
		(layer "In6.Cu")
		(net "P5E_CPU0_P0_TX_DP<8>")
	)
	(segment
		(start 352.685604 -291.420042)
		(end 352.649028 -291.441378)
		(width 0.1143)
		(layer "In6.Cu")
		(net "P5E_CPU0_P0_TX_DP<8>")
	)
	(segment
		(start 352.687128 -293.039038)
		(end 352.685604 -293.040054)
		(width 0.1143)
		(layer "In6.Cu")
		(net "P5E_CPU0_P0_TX_DP<8>")
	)
	(segment
		(start 351.966784 -296.252646)
		(end 351.966784 -296.281094)
		(width 0.1143)
		(layer "In6.Cu")
		(net "P5E_CPU0_P0_TX_DP<8>")
	)
	(segment
		(start 315.049662 -374.827546)
		(end 314.765182 -374.995948)
		(width 0.14224)
		(layer "In6.Cu")
		(net "P5E_CPU0_P0_TX_DP<8>")
	)
	(segment
		(start 312.920126 -379.5903)
		(end 312.629296 -379.88113)
		(width 0.14224)
		(layer "In6.Cu")
		(net "P5E_CPU0_P0_TX_DP<8>")
	)
	(segment
		(start 370.3574 -328.774552)
		(end 372.499128 -340.692994)
		(width 0.14224)
		(layer "In6.Cu")
		(net "P5E_CPU0_P0_TX_DP<8>")
	)
	(segment
		(start 352.649028 -289.130486)
		(end 352.655886 -289.13455)
		(width 0.1143)
		(layer "In6.Cu")
		(net "P5E_CPU0_P0_TX_DP<8>")
	)
	(segment
		(start 352.012504 -295.914318)
		(end 352.012504 -296.206926)
		(width 0.1143)
		(layer "In6.Cu")
		(net "P5E_CPU0_P0_TX_DP<8>")
	)
	(segment
		(start 351.966784 -298.525184)
		(end 355.256592 -306.467764)
		(width 0.14224)
		(layer "In6.Cu")
		(net "P5E_CPU0_P0_TX_DP<8>")
	)
	(segment
		(start 352.687128 -287.53308)
		(end 352.689922 -287.534604)
		(width 0.1143)
		(layer "In6.Cu")
		(net "P5E_CPU0_P0_TX_DP<8>")
	)
	(segment
		(start 320.292476 -372.642892)
		(end 315.19876 -374.753124)
		(width 0.14224)
		(layer "In6.Cu")
		(net "P5E_CPU0_P0_TX_DP<8>")
	)
	(segment
		(start 352.655886 -292.374574)
		(end 352.656648 -292.375082)
		(width 0.1143)
		(layer "In6.Cu")
		(net "P5E_CPU0_P0_TX_DP<8>")
	)
	(segment
		(start 352.719132 -294.031162)
		(end 352.720656 -294.032178)
		(width 0.1143)
		(layer "In6.Cu")
		(net "P5E_CPU0_P0_TX_DP<8>")
	)
	(segment
		(start 366.19942 -365.665512)
		(end 360.378502 -371.48643)
		(width 0.14224)
		(layer "In6.Cu")
		(net "P5E_CPU0_P0_TX_DP<8>")
	)
	(segment
		(start 352.688906 -291.41801)
		(end 352.688144 -291.418518)
		(width 0.1143)
		(layer "In6.Cu")
		(net "P5E_CPU0_P0_TX_DP<8>")
	)
	(segment
		(start 352.719894 -289.780218)
		(end 352.688906 -289.797998)
		(width 0.1143)
		(layer "In6.Cu")
		(net "P5E_CPU0_P0_TX_DP<8>")
	)
	(segment
		(start 372.499128 -340.692994)
		(end 372.499128 -350.456754)
		(width 0.14224)
		(layer "In6.Cu")
		(net "P5E_CPU0_P0_TX_DP<8>")
	)
	(segment
		(start 352.688144 -288.178494)
		(end 352.649028 -288.201354)
		(width 0.1143)
		(layer "In6.Cu")
		(net "P5E_CPU0_P0_TX_DP<8>")
	)
	(segment
		(start 352.688906 -292.393878)
		(end 352.719894 -292.411658)
		(width 0.1143)
		(layer "In6.Cu")
		(net "P5E_CPU0_P0_TX_DP<8>")
	)
	(segment
		(start 352.179128 -286.700722)
		(end 352.218244 -286.723582)
		(width 0.1143)
		(layer "In6.Cu")
		(net "P5E_CPU0_P0_TX_DP<8>")
	)
	(segment
		(start 314.609734 -375.116852)
		(end 313.231276 -376.49531)
		(width 0.14224)
		(layer "In6.Cu")
		(net "P5E_CPU0_P0_TX_DP<8>")
	)
	(segment
		(start 352.720656 -294.639492)
		(end 352.720656 -294.639746)
		(width 0.1143)
		(layer "In6.Cu")
		(net "P5E_CPU0_P0_TX_DP<8>")
	)
	(segment
		(start 351.561146 -286.236156)
		(end 351.859088 -286.236156)
		(width 0.1143)
		(layer "In6.Cu")
		(net "P5E_CPU0_P0_TX_DP<8>")
	)
	(segment
		(start 352.688906 -293.038022)
		(end 352.688144 -293.03853)
		(width 0.1143)
		(layer "In6.Cu")
		(net "P5E_CPU0_P0_TX_DP<8>")
	)
	(segment
		(start 358.569006 -372.235984)
		(end 322.338446 -372.235984)
		(width 0.14224)
		(layer "In6.Cu")
		(net "P5E_CPU0_P0_TX_DP<8>")
	)
	(segment
		(start 352.688906 -290.773866)
		(end 352.719894 -290.791646)
		(width 0.1143)
		(layer "In6.Cu")
		(net "P5E_CPU0_P0_TX_DP<8>")
	)
	(segment
		(start 352.656648 -289.135058)
		(end 352.688144 -289.153346)
		(width 0.1143)
		(layer "In6.Cu")
		(net "P5E_CPU0_P0_TX_DP<8>")
	)
	(segment
		(start 352.649028 -293.990522)
		(end 352.719132 -294.031162)
		(width 0.1143)
		(layer "In6.Cu")
		(net "P5E_CPU0_P0_TX_DP<8>")
	)
	(segment
		(start 352.688906 -289.153854)
		(end 352.719894 -289.171634)
		(width 0.1143)
		(layer "In6.Cu")
		(net "P5E_CPU0_P0_TX_DP<8>")
	)
	(segment
		(start 355.256592 -306.467764)
		(end 361.19181 -315.350144)
		(width 0.14224)
		(layer "In6.Cu")
		(net "P5E_CPU0_P0_TX_DP<8>")
	)
	(segment
		(start 352.312224 -295.469056)
		(end 352.115628 -295.665652)
		(width 0.1143)
		(layer "In6.Cu")
		(net "P5E_CPU0_P0_TX_DP<8>")
	)
	(segment
		(start 352.688144 -289.153346)
		(end 352.688906 -289.153854)
		(width 0.1143)
		(layer "In6.Cu")
		(net "P5E_CPU0_P0_TX_DP<8>")
	)
	(segment
		(start 352.687128 -289.799014)
		(end 352.685604 -289.80003)
		(width 0.1143)
		(layer "In6.Cu")
		(net "P5E_CPU0_P0_TX_DP<8>")
	)
	(segment
		(start 352.688144 -289.798506)
		(end 352.687128 -289.799014)
		(width 0.1143)
		(layer "In6.Cu")
		(net "P5E_CPU0_P0_TX_DP<8>")
	)
	(arc
		(start 315.19876 -374.753124)
		(mid 315.122889 -374.787688)
		(end 315.049662 -374.827546)
		(width 0.14224)
		(layer "In6.Cu")
		(net "P5E_CPU0_P0_TX_DP<8>")
	)
	(arc
		(start 352.719894 -292.411658)
		(mid 352.871483 -292.71595)
		(end 352.719894 -293.020242)
		(width 0.1143)
		(layer "In6.Cu")
		(net "P5E_CPU0_P0_TX_DP<8>")
	)
	(arc
		(start 352.649028 -291.441378)
		(mid 352.405701 -291.905944)
		(end 352.649028 -292.37051)
		(width 0.1143)
		(layer "In6.Cu")
		(net "P5E_CPU0_P0_TX_DP<8>")
	)
	(arc
		(start 352.379788 -295.361614)
		(mid 352.352053 -295.419138)
		(end 352.312224 -295.469056)
		(width 0.1143)
		(layer "In6.Cu")
		(net "P5E_CPU0_P0_TX_DP<8>")
	)
	(arc
		(start 313.231276 -376.49531)
		(mid 313.00097 -376.839893)
		(end 312.920126 -377.246388)
		(width 0.14224)
		(layer "In6.Cu")
		(net "P5E_CPU0_P0_TX_DP<8>")
	)
	(arc
		(start 352.40595 -295.209214)
		(mid 352.399328 -295.286524)
		(end 352.379788 -295.361614)
		(width 0.1143)
		(layer "In6.Cu")
		(net "P5E_CPU0_P0_TX_DP<8>")
	)
	(arc
		(start 352.689922 -287.534604)
		(mid 352.826003 -287.670452)
		(end 352.87585 -287.856168)
		(width 0.1143)
		(layer "In6.Cu")
		(net "P5E_CPU0_P0_TX_DP<8>")
	)
	(arc
		(start 351.941892 -286.31896)
		(mid 351.94368 -286.330409)
		(end 351.945702 -286.34182)
		(width 0.1143)
		(layer "In6.Cu")
		(net "P5E_CPU0_P0_TX_DP<8>")
	)
	(arc
		(start 352.87585 -287.856168)
		(mid 352.835088 -288.026052)
		(end 352.721672 -288.158936)
		(width 0.1143)
		(layer "In6.Cu")
		(net "P5E_CPU0_P0_TX_DP<8>")
	)
	(arc
		(start 322.338446 -372.235984)
		(mid 321.295413 -372.338642)
		(end 320.292476 -372.642892)
		(width 0.14224)
		(layer "In6.Cu")
		(net "P5E_CPU0_P0_TX_DP<8>")
	)
	(arc
		(start 351.945702 -286.34182)
		(mid 352.027135 -286.544218)
		(end 352.179128 -286.700722)
		(width 0.1143)
		(layer "In6.Cu")
		(net "P5E_CPU0_P0_TX_DP<8>")
	)
	(arc
		(start 352.720656 -294.032432)
		(mid 352.875545 -294.335962)
		(end 352.720656 -294.639492)
		(width 0.1143)
		(layer "In6.Cu")
		(net "P5E_CPU0_P0_TX_DP<8>")
	)
	(arc
		(start 352.250756 -286.742378)
		(mid 352.364685 -286.875525)
		(end 352.405696 -287.045908)
		(width 0.1143)
		(layer "In6.Cu")
		(net "P5E_CPU0_P0_TX_DP<8>")
	)
	(arc
		(start 352.649028 -288.201354)
		(mid 352.405701 -288.66592)
		(end 352.649028 -289.130486)
		(width 0.1143)
		(layer "In6.Cu")
		(net "P5E_CPU0_P0_TX_DP<8>")
	)
	(arc
		(start 352.649028 -293.06139)
		(mid 352.405701 -293.525956)
		(end 352.649028 -293.990522)
		(width 0.1143)
		(layer "In6.Cu")
		(net "P5E_CPU0_P0_TX_DP<8>")
	)
	(arc
		(start 352.115628 -295.665652)
		(mid 352.039367 -295.77974)
		(end 352.012504 -295.914318)
		(width 0.1143)
		(layer "In6.Cu")
		(net "P5E_CPU0_P0_TX_DP<8>")
	)
	(arc
		(start 352.649028 -289.821366)
		(mid 352.405701 -290.285932)
		(end 352.649028 -290.750498)
		(width 0.1143)
		(layer "In6.Cu")
		(net "P5E_CPU0_P0_TX_DP<8>")
	)
	(arc
		(start 360.378502 -371.48643)
		(mid 359.548298 -372.041154)
		(end 358.569006 -372.235984)
		(width 0.14224)
		(layer "In6.Cu")
		(net "P5E_CPU0_P0_TX_DP<8>")
	)
	(arc
		(start 372.499128 -350.456754)
		(mid 370.861894 -358.687688)
		(end 366.19942 -365.665512)
		(width 0.14224)
		(layer "In6.Cu")
		(net "P5E_CPU0_P0_TX_DP<8>")
	)
	(arc
		(start 352.719894 -290.791646)
		(mid 352.871483 -291.095938)
		(end 352.719894 -291.40023)
		(width 0.1143)
		(layer "In6.Cu")
		(net "P5E_CPU0_P0_TX_DP<8>")
	)
	(arc
		(start 352.405696 -287.045908)
		(mid 352.470932 -287.309499)
		(end 352.651568 -287.512252)
		(width 0.1143)
		(layer "In6.Cu")
		(net "P5E_CPU0_P0_TX_DP<8>")
	)
	(arc
		(start 314.765182 -374.995948)
		(mid 314.683662 -375.05152)
		(end 314.609734 -375.116852)
		(width 0.14224)
		(layer "In6.Cu")
		(net "P5E_CPU0_P0_TX_DP<8>")
	)
	(arc
		(start 352.505518 -294.825674)
		(mid 352.431512 -294.978152)
		(end 352.40595 -295.145714)
		(width 0.1143)
		(layer "In6.Cu")
		(net "P5E_CPU0_P0_TX_DP<8>")
	)
	(arc
		(start 352.649028 -294.681402)
		(mid 352.570605 -294.746883)
		(end 352.505264 -294.82542)
		(width 0.1143)
		(layer "In6.Cu")
		(net "P5E_CPU0_P0_TX_DP<8>")
	)
	(arc
		(start 352.719894 -289.171634)
		(mid 352.868991 -289.475926)
		(end 352.719894 -289.780218)
		(width 0.1143)
		(layer "In6.Cu")
		(net "P5E_CPU0_P0_TX_DP<8>")
	)
	(segment
		(start 352.027998 -284.350206)
		(end 351.561146 -284.616144)
		(width 0.12954)
		(layer "F.Cu")
		(net "P5E_CPU0_P0_TX_DP<7>")
	)
	(segment
		(start 311.198006 -382.61544)
		(end 310.927496 -382.34493)
		(width 0.12954)
		(layer "F.Cu")
		(net "P5E_CPU0_P0_TX_DP<7>")
	)
	(segment
		(start 311.198006 -383.31902)
		(end 311.198006 -382.61544)
		(width 0.12954)
		(layer "F.Cu")
		(net "P5E_CPU0_P0_TX_DP<7>")
	)
	(segment
		(start 310.902096 -383.61493)
		(end 311.198006 -383.31902)
		(width 0.12954)
		(layer "F.Cu")
		(net "P5E_CPU0_P0_TX_DP<7>")
	)
	(segment
		(start 351.711768 -293.9923)
		(end 351.74809 -294.013382)
		(width 0.1143)
		(layer "In6.Cu")
		(net "P5E_CPU0_P0_TX_DP<7>")
	)
	(segment
		(start 351.465896 -285.421578)
		(end 351.465896 -285.427166)
		(width 0.1143)
		(layer "In6.Cu")
		(net "P5E_CPU0_P0_TX_DP<7>")
	)
	(segment
		(start 351.30994 -285.730442)
		(end 351.278952 -285.748222)
		(width 0.1143)
		(layer "In6.Cu")
		(net "P5E_CPU0_P0_TX_DP<7>")
	)
	(segment
		(start 351.77984 -293.020242)
		(end 351.74809 -293.03853)
		(width 0.1143)
		(layer "In6.Cu")
		(net "P5E_CPU0_P0_TX_DP<7>")
	)
	(segment
		(start 311.218326 -377.988068)
		(end 311.218326 -381.987298)
		(width 0.14224)
		(layer "In6.Cu")
		(net "P5E_CPU0_P0_TX_DP<7>")
	)
	(segment
		(start 351.859088 -284.616144)
		(end 351.928938 -284.685994)
		(width 0.1143)
		(layer "In6.Cu")
		(net "P5E_CPU0_P0_TX_DP<7>")
	)
	(segment
		(start 351.561146 -284.616144)
		(end 351.859088 -284.616144)
		(width 0.1143)
		(layer "In6.Cu")
		(net "P5E_CPU0_P0_TX_DP<7>")
	)
	(segment
		(start 350.960182 -298.531534)
		(end 354.431092 -306.910994)
		(width 0.14224)
		(layer "In6.Cu")
		(net "P5E_CPU0_P0_TX_DP<7>")
	)
	(segment
		(start 351.727516 -288.190432)
		(end 351.726754 -288.19094)
		(width 0.1143)
		(layer "In6.Cu")
		(net "P5E_CPU0_P0_TX_DP<7>")
	)
	(segment
		(start 351.77984 -294.640254)
		(end 351.74809 -294.658542)
		(width 0.1143)
		(layer "In6.Cu")
		(net "P5E_CPU0_P0_TX_DP<7>")
	)
	(segment
		(start 351.726754 -289.1409)
		(end 351.77984 -289.171634)
		(width 0.1143)
		(layer "In6.Cu")
		(net "P5E_CPU0_P0_TX_DP<7>")
	)
	(segment
		(start 351.239074 -286.700722)
		(end 351.27819 -286.723582)
		(width 0.1143)
		(layer "In6.Cu")
		(net "P5E_CPU0_P0_TX_DP<7>")
	)
	(segment
		(start 351.74809 -294.658542)
		(end 351.707958 -294.681656)
		(width 0.1143)
		(layer "In6.Cu")
		(net "P5E_CPU0_P0_TX_DP<7>")
	)
	(segment
		(start 365.534956 -365.00943)
		(end 360.172508 -370.371878)
		(width 0.14224)
		(layer "In6.Cu")
		(net "P5E_CPU0_P0_TX_DP<7>")
	)
	(segment
		(start 351.77984 -291.40023)
		(end 351.74809 -291.418518)
		(width 0.1143)
		(layer "In6.Cu")
		(net "P5E_CPU0_P0_TX_DP<7>")
	)
	(segment
		(start 351.74809 -294.013382)
		(end 351.77984 -294.03167)
		(width 0.1143)
		(layer "In6.Cu")
		(net "P5E_CPU0_P0_TX_DP<7>")
	)
	(segment
		(start 360.440224 -315.904372)
		(end 366.327436 -323.077586)
		(width 0.14224)
		(layer "In6.Cu")
		(net "P5E_CPU0_P0_TX_DP<7>")
	)
	(segment
		(start 351.77984 -289.780218)
		(end 351.74809 -289.798506)
		(width 0.1143)
		(layer "In6.Cu")
		(net "P5E_CPU0_P0_TX_DP<7>")
	)
	(segment
		(start 351.74809 -289.798506)
		(end 351.711768 -289.819588)
		(width 0.1143)
		(layer "In6.Cu")
		(net "P5E_CPU0_P0_TX_DP<7>")
	)
	(segment
		(start 351.74809 -293.03853)
		(end 351.711768 -293.059612)
		(width 0.1143)
		(layer "In6.Cu")
		(net "P5E_CPU0_P0_TX_DP<7>")
	)
	(segment
		(start 357.92918 -371.30101)
		(end 322.074032 -371.30101)
		(width 0.14224)
		(layer "In6.Cu")
		(net "P5E_CPU0_P0_TX_DP<7>")
	)
	(segment
		(start 351.295462 -295.526968)
		(end 351.109026 -295.713404)
		(width 0.1143)
		(layer "In6.Cu")
		(net "P5E_CPU0_P0_TX_DP<7>")
	)
	(segment
		(start 351.711768 -292.372288)
		(end 351.74809 -292.39337)
		(width 0.1143)
		(layer "In6.Cu")
		(net "P5E_CPU0_P0_TX_DP<7>")
	)
	(segment
		(start 369.350036 -328.861674)
		(end 371.566948 -341.196676)
		(width 0.14224)
		(layer "In6.Cu")
		(net "P5E_CPU0_P0_TX_DP<7>")
	)
	(segment
		(start 351.74809 -291.418518)
		(end 351.711768 -291.4396)
		(width 0.1143)
		(layer "In6.Cu")
		(net "P5E_CPU0_P0_TX_DP<7>")
	)
	(segment
		(start 350.960182 -296.252646)
		(end 350.960182 -296.281094)
		(width 0.1143)
		(layer "In6.Cu")
		(net "P5E_CPU0_P0_TX_DP<7>")
	)
	(segment
		(start 371.566948 -341.196676)
		(end 371.566948 -350.446848)
		(width 0.14224)
		(layer "In6.Cu")
		(net "P5E_CPU0_P0_TX_DP<7>")
	)
	(segment
		(start 366.327436 -323.077586)
		(end 369.350036 -328.861674)
		(width 0.14224)
		(layer "In6.Cu")
		(net "P5E_CPU0_P0_TX_DP<7>")
	)
	(segment
		(start 351.711768 -290.752276)
		(end 351.74809 -290.773358)
		(width 0.1143)
		(layer "In6.Cu")
		(net "P5E_CPU0_P0_TX_DP<7>")
	)
	(segment
		(start 351.77984 -284.920436)
		(end 351.707958 -284.961838)
		(width 0.1143)
		(layer "In6.Cu")
		(net "P5E_CPU0_P0_TX_DP<7>")
	)
	(segment
		(start 351.74809 -292.39337)
		(end 351.77984 -292.411658)
		(width 0.1143)
		(layer "In6.Cu")
		(net "P5E_CPU0_P0_TX_DP<7>")
	)
	(segment
		(start 351.277174 -285.749238)
		(end 351.27565 -285.750254)
		(width 0.1143)
		(layer "In6.Cu")
		(net "P5E_CPU0_P0_TX_DP<7>")
	)
	(segment
		(start 351.27819 -286.723582)
		(end 351.311718 -286.74314)
		(width 0.1143)
		(layer "In6.Cu")
		(net "P5E_CPU0_P0_TX_DP<7>")
	)
	(segment
		(start 350.960182 -296.281094)
		(end 350.960182 -298.531534)
		(width 0.14224)
		(layer "In6.Cu")
		(net "P5E_CPU0_P0_TX_DP<7>")
	)
	(segment
		(start 351.005902 -295.96207)
		(end 351.005902 -296.206926)
		(width 0.1143)
		(layer "In6.Cu")
		(net "P5E_CPU0_P0_TX_DP<7>")
	)
	(segment
		(start 351.465896 -285.427166)
		(end 351.465642 -285.42869)
		(width 0.1143)
		(layer "In6.Cu")
		(net "P5E_CPU0_P0_TX_DP<7>")
	)
	(segment
		(start 351.005902 -296.206926)
		(end 350.960182 -296.252646)
		(width 0.1143)
		(layer "In6.Cu")
		(net "P5E_CPU0_P0_TX_DP<7>")
	)
	(segment
		(start 311.171082 -382.101344)
		(end 310.927496 -382.34493)
		(width 0.14224)
		(layer "In6.Cu")
		(net "P5E_CPU0_P0_TX_DP<7>")
	)
	(segment
		(start 354.431092 -306.910994)
		(end 360.440224 -315.904372)
		(width 0.14224)
		(layer "In6.Cu")
		(net "P5E_CPU0_P0_TX_DP<7>")
	)
	(segment
		(start 351.781618 -288.158936)
		(end 351.727516 -288.190432)
		(width 0.1143)
		(layer "In6.Cu")
		(net "P5E_CPU0_P0_TX_DP<7>")
	)
	(segment
		(start 351.278952 -285.748222)
		(end 351.27819 -285.74873)
		(width 0.1143)
		(layer "In6.Cu")
		(net "P5E_CPU0_P0_TX_DP<7>")
	)
	(segment
		(start 351.714562 -287.51403)
		(end 351.74809 -287.533588)
		(width 0.1143)
		(layer "In6.Cu")
		(net "P5E_CPU0_P0_TX_DP<7>")
	)
	(segment
		(start 351.707958 -284.961838)
		(end 351.696528 -284.970474)
		(width 0.1143)
		(layer "In6.Cu")
		(net "P5E_CPU0_P0_TX_DP<7>")
	)
	(segment
		(start 351.74809 -290.773358)
		(end 351.77984 -290.791646)
		(width 0.1143)
		(layer "In6.Cu")
		(net "P5E_CPU0_P0_TX_DP<7>")
	)
	(segment
		(start 351.74809 -287.533588)
		(end 351.77984 -287.551876)
		(width 0.1143)
		(layer "In6.Cu")
		(net "P5E_CPU0_P0_TX_DP<7>")
	)
	(segment
		(start 320.182494 -371.677184)
		(end 313.618118 -374.396508)
		(width 0.14224)
		(layer "In6.Cu")
		(net "P5E_CPU0_P0_TX_DP<7>")
	)
	(segment
		(start 351.27819 -285.74873)
		(end 351.277174 -285.749238)
		(width 0.1143)
		(layer "In6.Cu")
		(net "P5E_CPU0_P0_TX_DP<7>")
	)
	(segment
		(start 351.27565 -285.750254)
		(end 351.239074 -285.77159)
		(width 0.1143)
		(layer "In6.Cu")
		(net "P5E_CPU0_P0_TX_DP<7>")
	)
	(arc
		(start 351.697544 -292.362382)
		(mid 351.704618 -292.367389)
		(end 351.711768 -292.372288)
		(width 0.1143)
		(layer "In6.Cu")
		(net "P5E_CPU0_P0_TX_DP<7>")
	)
	(arc
		(start 351.77984 -292.411658)
		(mid 351.935768 -292.71595)
		(end 351.77984 -293.020242)
		(width 0.1143)
		(layer "In6.Cu")
		(net "P5E_CPU0_P0_TX_DP<7>")
	)
	(arc
		(start 351.77984 -287.551876)
		(mid 351.894516 -287.68521)
		(end 351.935796 -287.856168)
		(width 0.1143)
		(layer "In6.Cu")
		(net "P5E_CPU0_P0_TX_DP<7>")
	)
	(arc
		(start 351.77984 -294.03167)
		(mid 351.935768 -294.335962)
		(end 351.77984 -294.640254)
		(width 0.1143)
		(layer "In6.Cu")
		(net "P5E_CPU0_P0_TX_DP<7>")
	)
	(arc
		(start 351.696528 -284.970474)
		(mid 351.526906 -285.16826)
		(end 351.465896 -285.421578)
		(width 0.1143)
		(layer "In6.Cu")
		(net "P5E_CPU0_P0_TX_DP<7>")
	)
	(arc
		(start 351.697544 -291.449506)
		(mid 351.470161 -291.905944)
		(end 351.697544 -292.362382)
		(width 0.1143)
		(layer "In6.Cu")
		(net "P5E_CPU0_P0_TX_DP<7>")
	)
	(arc
		(start 313.618118 -374.396508)
		(mid 311.873474 -375.828303)
		(end 311.218326 -377.988068)
		(width 0.14224)
		(layer "In6.Cu")
		(net "P5E_CPU0_P0_TX_DP<7>")
	)
	(arc
		(start 351.77984 -290.791646)
		(mid 351.935768 -291.095938)
		(end 351.77984 -291.40023)
		(width 0.1143)
		(layer "In6.Cu")
		(net "P5E_CPU0_P0_TX_DP<7>")
	)
	(arc
		(start 351.697544 -287.502346)
		(mid 351.706001 -287.508264)
		(end 351.714562 -287.51403)
		(width 0.1143)
		(layer "In6.Cu")
		(net "P5E_CPU0_P0_TX_DP<7>")
	)
	(arc
		(start 351.465896 -287.045908)
		(mid 351.465891 -287.048067)
		(end 351.465896 -287.050226)
		(width 0.1143)
		(layer "In6.Cu")
		(net "P5E_CPU0_P0_TX_DP<7>")
	)
	(arc
		(start 351.935796 -287.856168)
		(mid 351.895034 -288.026052)
		(end 351.781618 -288.158936)
		(width 0.1143)
		(layer "In6.Cu")
		(net "P5E_CPU0_P0_TX_DP<7>")
	)
	(arc
		(start 351.696528 -293.981632)
		(mid 351.704104 -293.987028)
		(end 351.711768 -293.9923)
		(width 0.1143)
		(layer "In6.Cu")
		(net "P5E_CPU0_P0_TX_DP<7>")
	)
	(arc
		(start 351.711768 -291.4396)
		(mid 351.704619 -291.4445)
		(end 351.697544 -291.449506)
		(width 0.1143)
		(layer "In6.Cu")
		(net "P5E_CPU0_P0_TX_DP<7>")
	)
	(arc
		(start 351.711768 -289.819588)
		(mid 351.705516 -289.823865)
		(end 351.699322 -289.828224)
		(width 0.1143)
		(layer "In6.Cu")
		(net "P5E_CPU0_P0_TX_DP<7>")
	)
	(arc
		(start 351.465896 -295.134538)
		(mid 351.417984 -295.346956)
		(end 351.295462 -295.526968)
		(width 0.1143)
		(layer "In6.Cu")
		(net "P5E_CPU0_P0_TX_DP<7>")
	)
	(arc
		(start 351.707958 -294.681656)
		(mid 351.534377 -294.880011)
		(end 351.465896 -295.134538)
		(width 0.1143)
		(layer "In6.Cu")
		(net "P5E_CPU0_P0_TX_DP<7>")
	)
	(arc
		(start 351.726754 -288.19094)
		(mid 351.453203 -288.66592)
		(end 351.726754 -289.1409)
		(width 0.1143)
		(layer "In6.Cu")
		(net "P5E_CPU0_P0_TX_DP<7>")
	)
	(arc
		(start 351.77984 -289.171634)
		(mid 351.935768 -289.475926)
		(end 351.77984 -289.780218)
		(width 0.1143)
		(layer "In6.Cu")
		(net "P5E_CPU0_P0_TX_DP<7>")
	)
	(arc
		(start 311.218326 -381.987298)
		(mid 311.206049 -382.049021)
		(end 311.171082 -382.101344)
		(width 0.14224)
		(layer "In6.Cu")
		(net "P5E_CPU0_P0_TX_DP<7>")
	)
	(arc
		(start 322.074032 -371.30101)
		(mid 321.109736 -371.395939)
		(end 320.182494 -371.677184)
		(width 0.14224)
		(layer "In6.Cu")
		(net "P5E_CPU0_P0_TX_DP<7>")
	)
	(arc
		(start 351.239074 -285.77159)
		(mid 350.995747 -286.236156)
		(end 351.239074 -286.700722)
		(width 0.1143)
		(layer "In6.Cu")
		(net "P5E_CPU0_P0_TX_DP<7>")
	)
	(arc
		(start 351.696528 -293.07028)
		(mid 351.471357 -293.525956)
		(end 351.696528 -293.981632)
		(width 0.1143)
		(layer "In6.Cu")
		(net "P5E_CPU0_P0_TX_DP<7>")
	)
	(arc
		(start 351.109026 -295.713404)
		(mid 351.032765 -295.827492)
		(end 351.005902 -295.96207)
		(width 0.1143)
		(layer "In6.Cu")
		(net "P5E_CPU0_P0_TX_DP<7>")
	)
	(arc
		(start 351.711768 -293.059612)
		(mid 351.704104 -293.064883)
		(end 351.696528 -293.07028)
		(width 0.1143)
		(layer "In6.Cu")
		(net "P5E_CPU0_P0_TX_DP<7>")
	)
	(arc
		(start 351.311718 -286.74314)
		(mid 351.425125 -286.876029)
		(end 351.465896 -287.045908)
		(width 0.1143)
		(layer "In6.Cu")
		(net "P5E_CPU0_P0_TX_DP<7>")
	)
	(arc
		(start 351.465896 -287.050226)
		(mid 351.529873 -287.302856)
		(end 351.697544 -287.502346)
		(width 0.1143)
		(layer "In6.Cu")
		(net "P5E_CPU0_P0_TX_DP<7>")
	)
	(arc
		(start 351.465642 -285.42869)
		(mid 351.421103 -285.596748)
		(end 351.30994 -285.730442)
		(width 0.1143)
		(layer "In6.Cu")
		(net "P5E_CPU0_P0_TX_DP<7>")
	)
	(arc
		(start 371.566948 -350.446848)
		(mid 369.999279 -358.32805)
		(end 365.534956 -365.00943)
		(width 0.14224)
		(layer "In6.Cu")
		(net "P5E_CPU0_P0_TX_DP<7>")
	)
	(arc
		(start 351.699322 -290.74364)
		(mid 351.705516 -290.748)
		(end 351.711768 -290.752276)
		(width 0.1143)
		(layer "In6.Cu")
		(net "P5E_CPU0_P0_TX_DP<7>")
	)
	(arc
		(start 360.172508 -370.371878)
		(mid 359.143246 -371.059546)
		(end 357.92918 -371.30101)
		(width 0.14224)
		(layer "In6.Cu")
		(net "P5E_CPU0_P0_TX_DP<7>")
	)
	(arc
		(start 351.699322 -289.828224)
		(mid 351.467854 -290.285932)
		(end 351.699322 -290.74364)
		(width 0.1143)
		(layer "In6.Cu")
		(net "P5E_CPU0_P0_TX_DP<7>")
	)
	(arc
		(start 351.928938 -284.685994)
		(mid 351.876889 -284.817513)
		(end 351.77984 -284.920436)
		(width 0.1143)
		(layer "In6.Cu")
		(net "P5E_CPU0_P0_TX_DP<7>")
	)
	(segment
		(start 349.20809 -281.110182)
		(end 348.741238 -281.37612)
		(width 0.12954)
		(layer "F.Cu")
		(net "P5E_CPU0_P0_TX_DP<6>")
	)
	(segment
		(start 307.794406 -377.68784)
		(end 307.523896 -377.41733)
		(width 0.12954)
		(layer "F.Cu")
		(net "P5E_CPU0_P0_TX_DP<6>")
	)
	(segment
		(start 307.794406 -378.39142)
		(end 307.794406 -377.68784)
		(width 0.12954)
		(layer "F.Cu")
		(net "P5E_CPU0_P0_TX_DP<6>")
	)
	(segment
		(start 307.498496 -378.68733)
		(end 307.794406 -378.39142)
		(width 0.12954)
		(layer "F.Cu")
		(net "P5E_CPU0_P0_TX_DP<6>")
	)
	(segment
		(start 350.34474 -283.487368)
		(end 350.34601 -283.48813)
		(width 0.1143)
		(layer "In6.Cu")
		(net "P5E_CPU0_P0_TX_DP<6>")
	)
	(segment
		(start 350.332294 -285.752032)
		(end 350.330516 -285.753048)
		(width 0.1143)
		(layer "In6.Cu")
		(net "P5E_CPU0_P0_TX_DP<6>")
	)
	(segment
		(start 349.03918 -281.37612)
		(end 349.121984 -281.458924)
		(width 0.1143)
		(layer "In6.Cu")
		(net "P5E_CPU0_P0_TX_DP<6>")
	)
	(segment
		(start 350.342454 -283.486098)
		(end 350.343978 -283.48686)
		(width 0.1143)
		(layer "In6.Cu")
		(net "P5E_CPU0_P0_TX_DP<6>")
	)
	(segment
		(start 350.328484 -285.754318)
		(end 350.326198 -285.755588)
		(width 0.1143)
		(layer "In6.Cu")
		(net "P5E_CPU0_P0_TX_DP<6>")
	)
	(segment
		(start 350.80829 -294.013382)
		(end 350.83877 -294.031162)
		(width 0.1143)
		(layer "In6.Cu")
		(net "P5E_CPU0_P0_TX_DP<6>")
	)
	(segment
		(start 350.369886 -285.730442)
		(end 350.338898 -285.748222)
		(width 0.1143)
		(layer "In6.Cu")
		(net "P5E_CPU0_P0_TX_DP<6>")
	)
	(segment
		(start 350.769174 -290.750498)
		(end 350.80829 -290.773358)
		(width 0.1143)
		(layer "In6.Cu")
		(net "P5E_CPU0_P0_TX_DP<6>")
	)
	(segment
		(start 350.015302 -296.281094)
		(end 350.015302 -298.686728)
		(width 0.14224)
		(layer "In6.Cu")
		(net "P5E_CPU0_P0_TX_DP<6>")
	)
	(segment
		(start 350.33712 -285.749238)
		(end 350.335596 -285.750254)
		(width 0.1143)
		(layer "In6.Cu")
		(net "P5E_CPU0_P0_TX_DP<6>")
	)
	(segment
		(start 307.814726 -377.1265)
		(end 307.523896 -377.41733)
		(width 0.14224)
		(layer "In6.Cu")
		(net "P5E_CPU0_P0_TX_DP<6>")
	)
	(segment
		(start 350.015302 -296.252646)
		(end 350.015302 -296.281094)
		(width 0.1143)
		(layer "In6.Cu")
		(net "P5E_CPU0_P0_TX_DP<6>")
	)
	(segment
		(start 368.438176 -329.130914)
		(end 370.634768 -341.351616)
		(width 0.14224)
		(layer "In6.Cu")
		(net "P5E_CPU0_P0_TX_DP<6>")
	)
	(segment
		(start 364.72368 -364.50016)
		(end 359.614216 -369.609624)
		(width 0.14224)
		(layer "In6.Cu")
		(net "P5E_CPU0_P0_TX_DP<6>")
	)
	(segment
		(start 350.80829 -289.153346)
		(end 350.83877 -289.171126)
		(width 0.1143)
		(layer "In6.Cu")
		(net "P5E_CPU0_P0_TX_DP<6>")
	)
	(segment
		(start 350.338136 -286.723582)
		(end 350.371664 -286.74314)
		(width 0.1143)
		(layer "In6.Cu")
		(net "P5E_CPU0_P0_TX_DP<6>")
	)
	(segment
		(start 350.83877 -293.02075)
		(end 350.80829 -293.03853)
		(width 0.1143)
		(layer "In6.Cu")
		(net "P5E_CPU0_P0_TX_DP<6>")
	)
	(segment
		(start 350.80829 -288.178494)
		(end 350.769174 -288.201354)
		(width 0.1143)
		(layer "In6.Cu")
		(net "P5E_CPU0_P0_TX_DP<6>")
	)
	(segment
		(start 350.341692 -283.48559)
		(end 350.342454 -283.486098)
		(width 0.1143)
		(layer "In6.Cu")
		(net "P5E_CPU0_P0_TX_DP<6>")
	)
	(segment
		(start 350.343978 -283.48686)
		(end 350.34474 -283.487368)
		(width 0.1143)
		(layer "In6.Cu")
		(net "P5E_CPU0_P0_TX_DP<6>")
	)
	(segment
		(start 308.3179 -375.518172)
		(end 307.985668 -375.850404)
		(width 0.14224)
		(layer "In6.Cu")
		(net "P5E_CPU0_P0_TX_DP<6>")
	)
	(segment
		(start 350.29902 -286.700722)
		(end 350.338136 -286.723582)
		(width 0.1143)
		(layer "In6.Cu")
		(net "P5E_CPU0_P0_TX_DP<6>")
	)
	(segment
		(start 350.338898 -283.484066)
		(end 350.341692 -283.48559)
		(width 0.1143)
		(layer "In6.Cu")
		(net "P5E_CPU0_P0_TX_DP<6>")
	)
	(segment
		(start 350.33712 -284.129226)
		(end 350.335596 -284.130242)
		(width 0.1143)
		(layer "In6.Cu")
		(net "P5E_CPU0_P0_TX_DP<6>")
	)
	(segment
		(start 350.330516 -284.133036)
		(end 350.328484 -284.134306)
		(width 0.1143)
		(layer "In6.Cu")
		(net "P5E_CPU0_P0_TX_DP<6>")
	)
	(segment
		(start 370.634768 -341.351616)
		(end 370.634768 -350.229678)
		(width 0.14224)
		(layer "In6.Cu")
		(net "P5E_CPU0_P0_TX_DP<6>")
	)
	(segment
		(start 350.338898 -285.104078)
		(end 350.340168 -285.10484)
		(width 0.1143)
		(layer "In6.Cu")
		(net "P5E_CPU0_P0_TX_DP<6>")
	)
	(segment
		(start 350.840802 -288.159698)
		(end 350.80829 -288.178494)
		(width 0.1143)
		(layer "In6.Cu")
		(net "P5E_CPU0_P0_TX_DP<6>")
	)
	(segment
		(start 350.83877 -294.640762)
		(end 350.769174 -294.681402)
		(width 0.1143)
		(layer "In6.Cu")
		(net "P5E_CPU0_P0_TX_DP<6>")
	)
	(segment
		(start 350.338136 -283.483558)
		(end 350.338898 -283.484066)
		(width 0.1143)
		(layer "In6.Cu")
		(net "P5E_CPU0_P0_TX_DP<6>")
	)
	(segment
		(start 350.369886 -284.11043)
		(end 350.338898 -284.12821)
		(width 0.1143)
		(layer "In6.Cu")
		(net "P5E_CPU0_P0_TX_DP<6>")
	)
	(segment
		(start 349.398082 -281.864816)
		(end 349.403416 -281.868118)
		(width 0.1143)
		(layer "In6.Cu")
		(net "P5E_CPU0_P0_TX_DP<6>")
	)
	(segment
		(start 350.330516 -285.753048)
		(end 350.328484 -285.754318)
		(width 0.1143)
		(layer "In6.Cu")
		(net "P5E_CPU0_P0_TX_DP<6>")
	)
	(segment
		(start 359.692194 -316.462918)
		(end 365.543084 -323.591936)
		(width 0.14224)
		(layer "In6.Cu")
		(net "P5E_CPU0_P0_TX_DP<6>")
	)
	(segment
		(start 307.80863 -376.277632)
		(end 307.80863 -376.440954)
		(width 0.14224)
		(layer "In6.Cu")
		(net "P5E_CPU0_P0_TX_DP<6>")
	)
	(segment
		(start 350.338136 -285.74873)
		(end 350.33712 -285.749238)
		(width 0.1143)
		(layer "In6.Cu")
		(net "P5E_CPU0_P0_TX_DP<6>")
	)
	(segment
		(start 350.326198 -285.755588)
		(end 350.29902 -285.77159)
		(width 0.1143)
		(layer "In6.Cu")
		(net "P5E_CPU0_P0_TX_DP<6>")
	)
	(segment
		(start 350.42475 -295.47058)
		(end 350.164146 -295.731184)
		(width 0.1143)
		(layer "In6.Cu")
		(net "P5E_CPU0_P0_TX_DP<6>")
	)
	(segment
		(start 350.33458 -285.750762)
		(end 350.33331 -285.751524)
		(width 0.1143)
		(layer "In6.Cu")
		(net "P5E_CPU0_P0_TX_DP<6>")
	)
	(segment
		(start 350.525842 -295.145968)
		(end 350.525842 -295.180512)
		(width 0.1143)
		(layer "In6.Cu")
		(net "P5E_CPU0_P0_TX_DP<6>")
	)
	(segment
		(start 350.33458 -284.13075)
		(end 350.33331 -284.131512)
		(width 0.1143)
		(layer "In6.Cu")
		(net "P5E_CPU0_P0_TX_DP<6>")
	)
	(segment
		(start 350.80829 -292.39337)
		(end 350.83877 -292.41115)
		(width 0.1143)
		(layer "In6.Cu")
		(net "P5E_CPU0_P0_TX_DP<6>")
	)
	(segment
		(start 349.121984 -281.477466)
		(end 349.126048 -281.48153)
		(width 0.1143)
		(layer "In6.Cu")
		(net "P5E_CPU0_P0_TX_DP<6>")
	)
	(segment
		(start 350.332294 -284.13202)
		(end 350.330516 -284.133036)
		(width 0.1143)
		(layer "In6.Cu")
		(net "P5E_CPU0_P0_TX_DP<6>")
	)
	(segment
		(start 350.335596 -285.750254)
		(end 350.33458 -285.750762)
		(width 0.1143)
		(layer "In6.Cu")
		(net "P5E_CPU0_P0_TX_DP<6>")
	)
	(segment
		(start 350.326198 -284.135576)
		(end 350.29902 -284.151578)
		(width 0.1143)
		(layer "In6.Cu")
		(net "P5E_CPU0_P0_TX_DP<6>")
	)
	(segment
		(start 350.771714 -287.512252)
		(end 350.83877 -287.551368)
		(width 0.1143)
		(layer "In6.Cu")
		(net "P5E_CPU0_P0_TX_DP<6>")
	)
	(segment
		(start 365.543084 -323.591936)
		(end 368.438176 -329.130914)
		(width 0.14224)
		(layer "In6.Cu")
		(net "P5E_CPU0_P0_TX_DP<6>")
	)
	(segment
		(start 350.83877 -291.400738)
		(end 350.80829 -291.418518)
		(width 0.1143)
		(layer "In6.Cu")
		(net "P5E_CPU0_P0_TX_DP<6>")
	)
	(segment
		(start 349.830644 -282.651708)
		(end 349.897446 -282.690824)
		(width 0.1143)
		(layer "In6.Cu")
		(net "P5E_CPU0_P0_TX_DP<6>")
	)
	(segment
		(start 350.769174 -289.130486)
		(end 350.80829 -289.153346)
		(width 0.1143)
		(layer "In6.Cu")
		(net "P5E_CPU0_P0_TX_DP<6>")
	)
	(segment
		(start 353.60483 -307.3527)
		(end 359.692194 -316.462918)
		(width 0.14224)
		(layer "In6.Cu")
		(net "P5E_CPU0_P0_TX_DP<6>")
	)
	(segment
		(start 307.814726 -376.44705)
		(end 307.814726 -377.1265)
		(width 0.14224)
		(layer "In6.Cu")
		(net "P5E_CPU0_P0_TX_DP<6>")
	)
	(segment
		(start 350.338136 -285.10357)
		(end 350.338898 -285.104078)
		(width 0.1143)
		(layer "In6.Cu")
		(net "P5E_CPU0_P0_TX_DP<6>")
	)
	(segment
		(start 350.80829 -289.798506)
		(end 350.769174 -289.821366)
		(width 0.1143)
		(layer "In6.Cu")
		(net "P5E_CPU0_P0_TX_DP<6>")
	)
	(segment
		(start 349.897446 -282.690824)
		(end 349.898716 -282.691332)
		(width 0.1143)
		(layer "In6.Cu")
		(net "P5E_CPU0_P0_TX_DP<6>")
	)
	(segment
		(start 350.30664 -283.46527)
		(end 350.338136 -283.483558)
		(width 0.1143)
		(layer "In6.Cu")
		(net "P5E_CPU0_P0_TX_DP<6>")
	)
	(segment
		(start 350.33331 -285.751524)
		(end 350.332294 -285.752032)
		(width 0.1143)
		(layer "In6.Cu")
		(net "P5E_CPU0_P0_TX_DP<6>")
	)
	(segment
		(start 350.305878 -283.464762)
		(end 350.30664 -283.46527)
		(width 0.1143)
		(layer "In6.Cu")
		(net "P5E_CPU0_P0_TX_DP<6>")
	)
	(segment
		(start 350.328484 -284.134306)
		(end 350.326198 -284.135576)
		(width 0.1143)
		(layer "In6.Cu")
		(net "P5E_CPU0_P0_TX_DP<6>")
	)
	(segment
		(start 350.338136 -284.128718)
		(end 350.33712 -284.129226)
		(width 0.1143)
		(layer "In6.Cu")
		(net "P5E_CPU0_P0_TX_DP<6>")
	)
	(segment
		(start 350.338898 -284.12821)
		(end 350.338136 -284.128718)
		(width 0.1143)
		(layer "In6.Cu")
		(net "P5E_CPU0_P0_TX_DP<6>")
	)
	(segment
		(start 350.335596 -284.130242)
		(end 350.33458 -284.13075)
		(width 0.1143)
		(layer "In6.Cu")
		(net "P5E_CPU0_P0_TX_DP<6>")
	)
	(segment
		(start 350.33712 -285.103062)
		(end 350.338136 -285.10357)
		(width 0.1143)
		(layer "In6.Cu")
		(net "P5E_CPU0_P0_TX_DP<6>")
	)
	(segment
		(start 350.061022 -295.97985)
		(end 350.061022 -296.206926)
		(width 0.1143)
		(layer "In6.Cu")
		(net "P5E_CPU0_P0_TX_DP<6>")
	)
	(segment
		(start 350.769174 -293.990522)
		(end 350.80829 -294.013382)
		(width 0.1143)
		(layer "In6.Cu")
		(net "P5E_CPU0_P0_TX_DP<6>")
	)
	(segment
		(start 350.015302 -298.686728)
		(end 353.60483 -307.3527)
		(width 0.14224)
		(layer "In6.Cu")
		(net "P5E_CPU0_P0_TX_DP<6>")
	)
	(segment
		(start 350.83877 -289.780726)
		(end 350.80829 -289.798506)
		(width 0.1143)
		(layer "In6.Cu")
		(net "P5E_CPU0_P0_TX_DP<6>")
	)
	(segment
		(start 350.80829 -293.03853)
		(end 350.769174 -293.06139)
		(width 0.1143)
		(layer "In6.Cu")
		(net "P5E_CPU0_P0_TX_DP<6>")
	)
	(segment
		(start 319.937638 -370.768626)
		(end 309.837836 -374.942862)
		(width 0.14224)
		(layer "In6.Cu")
		(net "P5E_CPU0_P0_TX_DP<6>")
	)
	(segment
		(start 307.80863 -376.440954)
		(end 307.814726 -376.44705)
		(width 0.14224)
		(layer "In6.Cu")
		(net "P5E_CPU0_P0_TX_DP<6>")
	)
	(segment
		(start 350.29902 -285.08071)
		(end 350.33712 -285.103062)
		(width 0.1143)
		(layer "In6.Cu")
		(net "P5E_CPU0_P0_TX_DP<6>")
	)
	(segment
		(start 350.769174 -292.37051)
		(end 350.80829 -292.39337)
		(width 0.1143)
		(layer "In6.Cu")
		(net "P5E_CPU0_P0_TX_DP<6>")
	)
	(segment
		(start 350.34601 -283.48813)
		(end 350.34855 -283.4894)
		(width 0.1143)
		(layer "In6.Cu")
		(net "P5E_CPU0_P0_TX_DP<6>")
	)
	(segment
		(start 350.34855 -283.4894)
		(end 350.369886 -283.501846)
		(width 0.1143)
		(layer "In6.Cu")
		(net "P5E_CPU0_P0_TX_DP<6>")
	)
	(segment
		(start 348.741238 -281.37612)
		(end 349.03918 -281.37612)
		(width 0.1143)
		(layer "In6.Cu")
		(net "P5E_CPU0_P0_TX_DP<6>")
	)
	(segment
		(start 357.78821 -370.366036)
		(end 321.966336 -370.366036)
		(width 0.14224)
		(layer "In6.Cu")
		(net "P5E_CPU0_P0_TX_DP<6>")
	)
	(segment
		(start 350.80829 -291.418518)
		(end 350.769174 -291.441378)
		(width 0.1143)
		(layer "In6.Cu")
		(net "P5E_CPU0_P0_TX_DP<6>")
	)
	(segment
		(start 350.061022 -296.206926)
		(end 350.015302 -296.252646)
		(width 0.1143)
		(layer "In6.Cu")
		(net "P5E_CPU0_P0_TX_DP<6>")
	)
	(segment
		(start 350.33331 -284.131512)
		(end 350.332294 -284.13202)
		(width 0.1143)
		(layer "In6.Cu")
		(net "P5E_CPU0_P0_TX_DP<6>")
	)
	(segment
		(start 350.340168 -285.10484)
		(end 350.369886 -285.121858)
		(width 0.1143)
		(layer "In6.Cu")
		(net "P5E_CPU0_P0_TX_DP<6>")
	)
	(segment
		(start 350.338898 -285.748222)
		(end 350.338136 -285.74873)
		(width 0.1143)
		(layer "In6.Cu")
		(net "P5E_CPU0_P0_TX_DP<6>")
	)
	(segment
		(start 350.29902 -283.460698)
		(end 350.305878 -283.464762)
		(width 0.1143)
		(layer "In6.Cu")
		(net "P5E_CPU0_P0_TX_DP<6>")
	)
	(segment
		(start 350.80829 -290.773358)
		(end 350.83877 -290.791138)
		(width 0.1143)
		(layer "In6.Cu")
		(net "P5E_CPU0_P0_TX_DP<6>")
	)
	(arc
		(start 370.634768 -350.229678)
		(mid 369.098522 -357.952816)
		(end 364.72368 -364.50016)
		(width 0.14224)
		(layer "In6.Cu")
		(net "P5E_CPU0_P0_TX_DP<6>")
	)
	(arc
		(start 350.525842 -287.045908)
		(mid 350.591078 -287.309499)
		(end 350.771714 -287.512252)
		(width 0.1143)
		(layer "In6.Cu")
		(net "P5E_CPU0_P0_TX_DP<6>")
	)
	(arc
		(start 309.837836 -374.942862)
		(mid 309.681804 -374.990743)
		(end 309.519574 -375.008648)
		(width 0.14224)
		(layer "In6.Cu")
		(net "P5E_CPU0_P0_TX_DP<6>")
	)
	(arc
		(start 350.493076 -295.3639)
		(mid 350.464685 -295.420934)
		(end 350.42475 -295.47058)
		(width 0.1143)
		(layer "In6.Cu")
		(net "P5E_CPU0_P0_TX_DP<6>")
	)
	(arc
		(start 307.985668 -375.850404)
		(mid 307.854642 -376.046404)
		(end 307.80863 -376.277632)
		(width 0.14224)
		(layer "In6.Cu")
		(net "P5E_CPU0_P0_TX_DP<6>")
	)
	(arc
		(start 350.369886 -283.501846)
		(mid 350.525814 -283.806138)
		(end 350.369886 -284.11043)
		(width 0.1143)
		(layer "In6.Cu")
		(net "P5E_CPU0_P0_TX_DP<6>")
	)
	(arc
		(start 349.586042 -282.186126)
		(mid 349.65086 -282.449115)
		(end 349.830644 -282.651708)
		(width 0.1143)
		(layer "In6.Cu")
		(net "P5E_CPU0_P0_TX_DP<6>")
	)
	(arc
		(start 350.371664 -286.74314)
		(mid 350.485071 -286.876029)
		(end 350.525842 -287.045908)
		(width 0.1143)
		(layer "In6.Cu")
		(net "P5E_CPU0_P0_TX_DP<6>")
	)
	(arc
		(start 350.83877 -292.41115)
		(mid 350.995747 -292.71595)
		(end 350.83877 -293.02075)
		(width 0.1143)
		(layer "In6.Cu")
		(net "P5E_CPU0_P0_TX_DP<6>")
	)
	(arc
		(start 350.83877 -289.171126)
		(mid 350.995747 -289.475926)
		(end 350.83877 -289.780726)
		(width 0.1143)
		(layer "In6.Cu")
		(net "P5E_CPU0_P0_TX_DP<6>")
	)
	(arc
		(start 349.126048 -281.48153)
		(mid 349.220153 -281.702935)
		(end 349.398082 -281.864816)
		(width 0.1143)
		(layer "In6.Cu")
		(net "P5E_CPU0_P0_TX_DP<6>")
	)
	(arc
		(start 350.83877 -294.031162)
		(mid 350.995747 -294.335962)
		(end 350.83877 -294.640762)
		(width 0.1143)
		(layer "In6.Cu")
		(net "P5E_CPU0_P0_TX_DP<6>")
	)
	(arc
		(start 350.164146 -295.731184)
		(mid 350.087885 -295.845272)
		(end 350.061022 -295.97985)
		(width 0.1143)
		(layer "In6.Cu")
		(net "P5E_CPU0_P0_TX_DP<6>")
	)
	(arc
		(start 349.898716 -282.691332)
		(mid 350.014143 -282.824708)
		(end 350.055688 -282.996132)
		(width 0.1143)
		(layer "In6.Cu")
		(net "P5E_CPU0_P0_TX_DP<6>")
	)
	(arc
		(start 321.966336 -370.366036)
		(mid 320.932202 -370.467632)
		(end 319.937638 -370.768626)
		(width 0.14224)
		(layer "In6.Cu")
		(net "P5E_CPU0_P0_TX_DP<6>")
	)
	(arc
		(start 350.29902 -285.77159)
		(mid 350.055693 -286.236156)
		(end 350.29902 -286.700722)
		(width 0.1143)
		(layer "In6.Cu")
		(net "P5E_CPU0_P0_TX_DP<6>")
	)
	(arc
		(start 350.769174 -294.681402)
		(mid 350.590361 -294.883752)
		(end 350.525842 -295.145968)
		(width 0.1143)
		(layer "In6.Cu")
		(net "P5E_CPU0_P0_TX_DP<6>")
	)
	(arc
		(start 350.369886 -285.121858)
		(mid 350.525814 -285.42615)
		(end 350.369886 -285.730442)
		(width 0.1143)
		(layer "In6.Cu")
		(net "P5E_CPU0_P0_TX_DP<6>")
	)
	(arc
		(start 350.995742 -287.856168)
		(mid 350.954776 -288.026574)
		(end 350.840802 -288.159698)
		(width 0.1143)
		(layer "In6.Cu")
		(net "P5E_CPU0_P0_TX_DP<6>")
	)
	(arc
		(start 350.769174 -288.201354)
		(mid 350.525847 -288.66592)
		(end 350.769174 -289.130486)
		(width 0.1143)
		(layer "In6.Cu")
		(net "P5E_CPU0_P0_TX_DP<6>")
	)
	(arc
		(start 350.83877 -287.551368)
		(mid 350.954197 -287.684744)
		(end 350.995742 -287.856168)
		(width 0.1143)
		(layer "In6.Cu")
		(net "P5E_CPU0_P0_TX_DP<6>")
	)
	(arc
		(start 350.769174 -293.06139)
		(mid 350.525847 -293.525956)
		(end 350.769174 -293.990522)
		(width 0.1143)
		(layer "In6.Cu")
		(net "P5E_CPU0_P0_TX_DP<6>")
	)
	(arc
		(start 350.769174 -289.821366)
		(mid 350.525847 -290.285932)
		(end 350.769174 -290.750498)
		(width 0.1143)
		(layer "In6.Cu")
		(net "P5E_CPU0_P0_TX_DP<6>")
	)
	(arc
		(start 349.403416 -281.868118)
		(mid 349.537099 -282.002781)
		(end 349.586042 -282.186126)
		(width 0.1143)
		(layer "In6.Cu")
		(net "P5E_CPU0_P0_TX_DP<6>")
	)
	(arc
		(start 359.614216 -369.609624)
		(mid 358.776452 -370.169464)
		(end 357.78821 -370.366036)
		(width 0.14224)
		(layer "In6.Cu")
		(net "P5E_CPU0_P0_TX_DP<6>")
	)
	(arc
		(start 349.121984 -281.458924)
		(mid 349.121905 -281.468195)
		(end 349.121984 -281.477466)
		(width 0.1143)
		(layer "In6.Cu")
		(net "P5E_CPU0_P0_TX_DP<6>")
	)
	(arc
		(start 350.83877 -290.791138)
		(mid 350.995747 -291.095938)
		(end 350.83877 -291.400738)
		(width 0.1143)
		(layer "In6.Cu")
		(net "P5E_CPU0_P0_TX_DP<6>")
	)
	(arc
		(start 350.525842 -295.180512)
		(mid 350.517586 -295.273658)
		(end 350.493076 -295.3639)
		(width 0.1143)
		(layer "In6.Cu")
		(net "P5E_CPU0_P0_TX_DP<6>")
	)
	(arc
		(start 350.29902 -284.151578)
		(mid 350.055693 -284.616144)
		(end 350.29902 -285.08071)
		(width 0.1143)
		(layer "In6.Cu")
		(net "P5E_CPU0_P0_TX_DP<6>")
	)
	(arc
		(start 350.769174 -291.441378)
		(mid 350.525847 -291.905944)
		(end 350.769174 -292.37051)
		(width 0.1143)
		(layer "In6.Cu")
		(net "P5E_CPU0_P0_TX_DP<6>")
	)
	(arc
		(start 350.055688 -282.996132)
		(mid 350.120203 -283.258351)
		(end 350.29902 -283.460698)
		(width 0.1143)
		(layer "In6.Cu")
		(net "P5E_CPU0_P0_TX_DP<6>")
	)
	(arc
		(start 309.519574 -375.008648)
		(mid 308.869147 -375.146449)
		(end 308.3179 -375.518172)
		(width 0.14224)
		(layer "In6.Cu")
		(net "P5E_CPU0_P0_TX_DP<6>")
	)
	(segment
		(start 305.796696 -381.15113)
		(end 306.092606 -380.85522)
		(width 0.12954)
		(layer "F.Cu")
		(net "P5E_CPU0_P0_TX_DP<5>")
	)
	(segment
		(start 349.20809 -285.970218)
		(end 348.741238 -286.236156)
		(width 0.12954)
		(layer "F.Cu")
		(net "P5E_CPU0_P0_TX_DP<5>")
	)
	(segment
		(start 306.092606 -380.15164)
		(end 305.822096 -379.88113)
		(width 0.12954)
		(layer "F.Cu")
		(net "P5E_CPU0_P0_TX_DP<5>")
	)
	(segment
		(start 306.092606 -380.85522)
		(end 306.092606 -380.15164)
		(width 0.12954)
		(layer "F.Cu")
		(net "P5E_CPU0_P0_TX_DP<5>")
	)
	(segment
		(start 307.182012 -374.575832)
		(end 306.418996 -375.338848)
		(width 0.14224)
		(layer "In6.Cu")
		(net "P5E_CPU0_P0_TX_DP<5>")
	)
	(segment
		(start 349.398082 -286.723582)
		(end 349.43161 -286.74314)
		(width 0.1143)
		(layer "In6.Cu")
		(net "P5E_CPU0_P0_TX_DP<5>")
	)
	(segment
		(start 349.868236 -292.39337)
		(end 349.898716 -292.41115)
		(width 0.1143)
		(layer "In6.Cu")
		(net "P5E_CPU0_P0_TX_DP<5>")
	)
	(segment
		(start 309.579518 -374.038876)
		(end 308.478428 -374.038876)
		(width 0.14224)
		(layer "In6.Cu")
		(net "P5E_CPU0_P0_TX_DP<5>")
	)
	(segment
		(start 357.344726 -369.431062)
		(end 321.963288 -369.431062)
		(width 0.14224)
		(layer "In6.Cu")
		(net "P5E_CPU0_P0_TX_DP<5>")
	)
	(segment
		(start 349.868236 -289.153346)
		(end 349.898716 -289.171126)
		(width 0.1143)
		(layer "In6.Cu")
		(net "P5E_CPU0_P0_TX_DP<5>")
	)
	(segment
		(start 349.868236 -294.013382)
		(end 349.898716 -294.031162)
		(width 0.1143)
		(layer "In6.Cu")
		(net "P5E_CPU0_P0_TX_DP<5>")
	)
	(segment
		(start 306.112926 -379.5903)
		(end 305.822096 -379.88113)
		(width 0.14224)
		(layer "In6.Cu")
		(net "P5E_CPU0_P0_TX_DP<5>")
	)
	(segment
		(start 352.779076 -307.795422)
		(end 358.941624 -317.018162)
		(width 0.14224)
		(layer "In6.Cu")
		(net "P5E_CPU0_P0_TX_DP<5>")
	)
	(segment
		(start 348.741238 -286.236156)
		(end 349.03918 -286.236156)
		(width 0.1143)
		(layer "In6.Cu")
		(net "P5E_CPU0_P0_TX_DP<5>")
	)
	(segment
		(start 349.898716 -289.780726)
		(end 349.868236 -289.798506)
		(width 0.1143)
		(layer "In6.Cu")
		(net "P5E_CPU0_P0_TX_DP<5>")
	)
	(segment
		(start 349.82912 -289.130486)
		(end 349.868236 -289.153346)
		(width 0.1143)
		(layer "In6.Cu")
		(net "P5E_CPU0_P0_TX_DP<5>")
	)
	(segment
		(start 358.941624 -317.018162)
		(end 364.76051 -324.108318)
		(width 0.14224)
		(layer "In6.Cu")
		(net "P5E_CPU0_P0_TX_DP<5>")
	)
	(segment
		(start 349.868236 -291.418518)
		(end 349.82912 -291.441378)
		(width 0.1143)
		(layer "In6.Cu")
		(net "P5E_CPU0_P0_TX_DP<5>")
	)
	(segment
		(start 319.539112 -369.913154)
		(end 309.579518 -374.038876)
		(width 0.14224)
		(layer "In6.Cu")
		(net "P5E_CPU0_P0_TX_DP<5>")
	)
	(segment
		(start 306.112926 -376.077988)
		(end 306.112926 -379.5903)
		(width 0.14224)
		(layer "In6.Cu")
		(net "P5E_CPU0_P0_TX_DP<5>")
	)
	(segment
		(start 349.82912 -293.990522)
		(end 349.868236 -294.013382)
		(width 0.1143)
		(layer "In6.Cu")
		(net "P5E_CPU0_P0_TX_DP<5>")
	)
	(segment
		(start 349.868236 -293.03853)
		(end 349.82912 -293.06139)
		(width 0.1143)
		(layer "In6.Cu")
		(net "P5E_CPU0_P0_TX_DP<5>")
	)
	(segment
		(start 349.070422 -296.252646)
		(end 349.070422 -296.281094)
		(width 0.1143)
		(layer "In6.Cu")
		(net "P5E_CPU0_P0_TX_DP<5>")
	)
	(segment
		(start 349.898716 -293.02075)
		(end 349.868236 -293.03853)
		(width 0.1143)
		(layer "In6.Cu")
		(net "P5E_CPU0_P0_TX_DP<5>")
	)
	(segment
		(start 349.900748 -288.159698)
		(end 349.868236 -288.178494)
		(width 0.1143)
		(layer "In6.Cu")
		(net "P5E_CPU0_P0_TX_DP<5>")
	)
	(segment
		(start 349.070422 -296.281094)
		(end 349.070422 -298.842176)
		(width 0.14224)
		(layer "In6.Cu")
		(net "P5E_CPU0_P0_TX_DP<5>")
	)
	(segment
		(start 349.898716 -291.400738)
		(end 349.868236 -291.418518)
		(width 0.1143)
		(layer "In6.Cu")
		(net "P5E_CPU0_P0_TX_DP<5>")
	)
	(segment
		(start 349.116142 -296.206926)
		(end 349.070422 -296.252646)
		(width 0.1143)
		(layer "In6.Cu")
		(net "P5E_CPU0_P0_TX_DP<5>")
	)
	(segment
		(start 349.116142 -295.962578)
		(end 349.116142 -296.206926)
		(width 0.1143)
		(layer "In6.Cu")
		(net "P5E_CPU0_P0_TX_DP<5>")
	)
	(segment
		(start 369.702588 -341.506556)
		(end 369.702588 -350.061784)
		(width 0.14224)
		(layer "In6.Cu")
		(net "P5E_CPU0_P0_TX_DP<5>")
	)
	(segment
		(start 349.83166 -287.512252)
		(end 349.898716 -287.551368)
		(width 0.1143)
		(layer "In6.Cu")
		(net "P5E_CPU0_P0_TX_DP<5>")
	)
	(segment
		(start 349.898716 -294.640762)
		(end 349.868236 -294.658542)
		(width 0.1143)
		(layer "In6.Cu")
		(net "P5E_CPU0_P0_TX_DP<5>")
	)
	(segment
		(start 349.82912 -290.750498)
		(end 349.868236 -290.773358)
		(width 0.1143)
		(layer "In6.Cu")
		(net "P5E_CPU0_P0_TX_DP<5>")
	)
	(segment
		(start 349.868236 -294.658542)
		(end 349.82912 -294.681402)
		(width 0.1143)
		(layer "In6.Cu")
		(net "P5E_CPU0_P0_TX_DP<5>")
	)
	(segment
		(start 349.868236 -288.178494)
		(end 349.82912 -288.201354)
		(width 0.1143)
		(layer "In6.Cu")
		(net "P5E_CPU0_P0_TX_DP<5>")
	)
	(segment
		(start 349.070422 -298.842176)
		(end 352.779076 -307.795422)
		(width 0.14224)
		(layer "In6.Cu")
		(net "P5E_CPU0_P0_TX_DP<5>")
	)
	(segment
		(start 349.03918 -286.236156)
		(end 349.121984 -286.31896)
		(width 0.1143)
		(layer "In6.Cu")
		(net "P5E_CPU0_P0_TX_DP<5>")
	)
	(segment
		(start 349.40113 -295.466516)
		(end 349.371666 -295.483534)
		(width 0.1143)
		(layer "In6.Cu")
		(net "P5E_CPU0_P0_TX_DP<5>")
	)
	(segment
		(start 364.76051 -324.108318)
		(end 367.526316 -329.399646)
		(width 0.14224)
		(layer "In6.Cu")
		(net "P5E_CPU0_P0_TX_DP<5>")
	)
	(segment
		(start 349.82912 -292.37051)
		(end 349.868236 -292.39337)
		(width 0.1143)
		(layer "In6.Cu")
		(net "P5E_CPU0_P0_TX_DP<5>")
	)
	(segment
		(start 349.868236 -290.773358)
		(end 349.898716 -290.791138)
		(width 0.1143)
		(layer "In6.Cu")
		(net "P5E_CPU0_P0_TX_DP<5>")
	)
	(segment
		(start 349.36176 -286.7025)
		(end 349.398082 -286.723582)
		(width 0.1143)
		(layer "In6.Cu")
		(net "P5E_CPU0_P0_TX_DP<5>")
	)
	(segment
		(start 349.371666 -295.483534)
		(end 349.27413 -295.58107)
		(width 0.1143)
		(layer "In6.Cu")
		(net "P5E_CPU0_P0_TX_DP<5>")
	)
	(segment
		(start 349.868236 -289.798506)
		(end 349.82912 -289.821366)
		(width 0.1143)
		(layer "In6.Cu")
		(net "P5E_CPU0_P0_TX_DP<5>")
	)
	(segment
		(start 367.526316 -329.399646)
		(end 369.702588 -341.506556)
		(width 0.14224)
		(layer "In6.Cu")
		(net "P5E_CPU0_P0_TX_DP<5>")
	)
	(segment
		(start 363.947456 -363.955838)
		(end 359.269538 -368.633756)
		(width 0.14224)
		(layer "In6.Cu")
		(net "P5E_CPU0_P0_TX_DP<5>")
	)
	(arc
		(start 349.898716 -292.41115)
		(mid 350.055693 -292.71595)
		(end 349.898716 -293.02075)
		(width 0.1143)
		(layer "In6.Cu")
		(net "P5E_CPU0_P0_TX_DP<5>")
	)
	(arc
		(start 349.121984 -286.31896)
		(mid 349.201834 -286.535758)
		(end 349.36176 -286.7025)
		(width 0.1143)
		(layer "In6.Cu")
		(net "P5E_CPU0_P0_TX_DP<5>")
	)
	(arc
		(start 349.82912 -289.821366)
		(mid 349.585793 -290.285932)
		(end 349.82912 -290.750498)
		(width 0.1143)
		(layer "In6.Cu")
		(net "P5E_CPU0_P0_TX_DP<5>")
	)
	(arc
		(start 349.82912 -288.201354)
		(mid 349.585793 -288.66592)
		(end 349.82912 -289.130486)
		(width 0.1143)
		(layer "In6.Cu")
		(net "P5E_CPU0_P0_TX_DP<5>")
	)
	(arc
		(start 308.478428 -374.038876)
		(mid 307.776827 -374.178433)
		(end 307.182012 -374.575832)
		(width 0.14224)
		(layer "In6.Cu")
		(net "P5E_CPU0_P0_TX_DP<5>")
	)
	(arc
		(start 349.27413 -295.58107)
		(mid 349.157227 -295.756122)
		(end 349.116142 -295.962578)
		(width 0.1143)
		(layer "In6.Cu")
		(net "P5E_CPU0_P0_TX_DP<5>")
	)
	(arc
		(start 349.585788 -287.045908)
		(mid 349.651024 -287.309499)
		(end 349.83166 -287.512252)
		(width 0.1143)
		(layer "In6.Cu")
		(net "P5E_CPU0_P0_TX_DP<5>")
	)
	(arc
		(start 306.418996 -375.338848)
		(mid 306.192457 -375.677983)
		(end 306.112926 -376.077988)
		(width 0.14224)
		(layer "In6.Cu")
		(net "P5E_CPU0_P0_TX_DP<5>")
	)
	(arc
		(start 349.898716 -287.551368)
		(mid 350.014143 -287.684744)
		(end 350.055688 -287.856168)
		(width 0.1143)
		(layer "In6.Cu")
		(net "P5E_CPU0_P0_TX_DP<5>")
	)
	(arc
		(start 349.898716 -294.031162)
		(mid 350.055693 -294.335962)
		(end 349.898716 -294.640762)
		(width 0.1143)
		(layer "In6.Cu")
		(net "P5E_CPU0_P0_TX_DP<5>")
	)
	(arc
		(start 349.898716 -289.171126)
		(mid 350.055693 -289.475926)
		(end 349.898716 -289.780726)
		(width 0.1143)
		(layer "In6.Cu")
		(net "P5E_CPU0_P0_TX_DP<5>")
	)
	(arc
		(start 349.898716 -290.791138)
		(mid 350.055693 -291.095938)
		(end 349.898716 -291.400738)
		(width 0.1143)
		(layer "In6.Cu")
		(net "P5E_CPU0_P0_TX_DP<5>")
	)
	(arc
		(start 359.269538 -368.633756)
		(mid 358.386427 -369.223832)
		(end 357.344726 -369.431062)
		(width 0.14224)
		(layer "In6.Cu")
		(net "P5E_CPU0_P0_TX_DP<5>")
	)
	(arc
		(start 349.572834 -295.170352)
		(mid 349.526791 -295.341502)
		(end 349.40113 -295.466516)
		(width 0.1143)
		(layer "In6.Cu")
		(net "P5E_CPU0_P0_TX_DP<5>")
	)
	(arc
		(start 349.82912 -294.681402)
		(mid 349.640868 -294.894366)
		(end 349.572834 -295.170352)
		(width 0.1143)
		(layer "In6.Cu")
		(net "P5E_CPU0_P0_TX_DP<5>")
	)
	(arc
		(start 349.82912 -291.441378)
		(mid 349.585793 -291.905944)
		(end 349.82912 -292.37051)
		(width 0.1143)
		(layer "In6.Cu")
		(net "P5E_CPU0_P0_TX_DP<5>")
	)
	(arc
		(start 350.055688 -287.856168)
		(mid 350.014722 -288.026574)
		(end 349.900748 -288.159698)
		(width 0.1143)
		(layer "In6.Cu")
		(net "P5E_CPU0_P0_TX_DP<5>")
	)
	(arc
		(start 369.702588 -350.061784)
		(mid 368.206883 -357.581202)
		(end 363.947456 -363.955838)
		(width 0.14224)
		(layer "In6.Cu")
		(net "P5E_CPU0_P0_TX_DP<5>")
	)
	(arc
		(start 321.963288 -369.431062)
		(mid 320.727463 -369.552737)
		(end 319.539112 -369.913154)
		(width 0.14224)
		(layer "In6.Cu")
		(net "P5E_CPU0_P0_TX_DP<5>")
	)
	(arc
		(start 349.43161 -286.74314)
		(mid 349.545017 -286.876029)
		(end 349.585788 -287.045908)
		(width 0.1143)
		(layer "In6.Cu")
		(net "P5E_CPU0_P0_TX_DP<5>")
	)
	(arc
		(start 349.82912 -293.06139)
		(mid 349.585793 -293.525956)
		(end 349.82912 -293.990522)
		(width 0.1143)
		(layer "In6.Cu")
		(net "P5E_CPU0_P0_TX_DP<5>")
	)
	(segment
		(start 304.390806 -382.61544)
		(end 304.120296 -382.34493)
		(width 0.12954)
		(layer "F.Cu")
		(net "P5E_CPU0_P0_TX_DP<4>")
	)
	(segment
		(start 304.094896 -383.61493)
		(end 304.390806 -383.31902)
		(width 0.12954)
		(layer "F.Cu")
		(net "P5E_CPU0_P0_TX_DP<4>")
	)
	(segment
		(start 349.20809 -284.350206)
		(end 348.741238 -284.616144)
		(width 0.12954)
		(layer "F.Cu")
		(net "P5E_CPU0_P0_TX_DP<4>")
	)
	(segment
		(start 304.390806 -383.31902)
		(end 304.390806 -382.61544)
		(width 0.12954)
		(layer "F.Cu")
		(net "P5E_CPU0_P0_TX_DP<4>")
	)
	(segment
		(start 348.896686 -293.995094)
		(end 348.928182 -294.013382)
		(width 0.1143)
		(layer "In6.Cu")
		(net "P5E_CPU0_P0_TX_DP<4>")
	)
	(segment
		(start 348.959932 -289.780218)
		(end 348.928944 -289.797998)
		(width 0.1143)
		(layer "In6.Cu")
		(net "P5E_CPU0_P0_TX_DP<4>")
	)
	(segment
		(start 348.962218 -294.63873)
		(end 348.951042 -294.645588)
		(width 0.1143)
		(layer "In6.Cu")
		(net "P5E_CPU0_P0_TX_DP<4>")
	)
	(segment
		(start 348.928182 -290.773358)
		(end 348.928944 -290.773866)
		(width 0.1143)
		(layer "In6.Cu")
		(net "P5E_CPU0_P0_TX_DP<4>")
	)
	(segment
		(start 348.891606 -287.512252)
		(end 348.895924 -287.514792)
		(width 0.1143)
		(layer "In6.Cu")
		(net "P5E_CPU0_P0_TX_DP<4>")
	)
	(segment
		(start 348.125288 -298.99737)
		(end 351.952052 -308.236366)
		(width 0.14224)
		(layer "In6.Cu")
		(net "P5E_CPU0_P0_TX_DP<4>")
	)
	(segment
		(start 348.889066 -292.37051)
		(end 348.895924 -292.374574)
		(width 0.1143)
		(layer "In6.Cu")
		(net "P5E_CPU0_P0_TX_DP<4>")
	)
	(segment
		(start 348.459044 -285.748222)
		(end 348.458282 -285.74873)
		(width 0.1143)
		(layer "In6.Cu")
		(net "P5E_CPU0_P0_TX_DP<4>")
	)
	(segment
		(start 356.855522 -368.496088)
		(end 321.964304 -368.496088)
		(width 0.14224)
		(layer "In6.Cu")
		(net "P5E_CPU0_P0_TX_DP<4>")
	)
	(segment
		(start 348.928944 -290.773866)
		(end 348.959932 -290.791646)
		(width 0.1143)
		(layer "In6.Cu")
		(net "P5E_CPU0_P0_TX_DP<4>")
	)
	(segment
		(start 348.889066 -289.130486)
		(end 348.895924 -289.13455)
		(width 0.1143)
		(layer "In6.Cu")
		(net "P5E_CPU0_P0_TX_DP<4>")
	)
	(segment
		(start 348.895924 -292.374574)
		(end 348.896686 -292.375082)
		(width 0.1143)
		(layer "In6.Cu")
		(net "P5E_CPU0_P0_TX_DP<4>")
	)
	(segment
		(start 348.458282 -285.74873)
		(end 348.419166 -285.77159)
		(width 0.1143)
		(layer "In6.Cu")
		(net "P5E_CPU0_P0_TX_DP<4>")
	)
	(segment
		(start 348.896686 -287.5153)
		(end 348.927166 -287.53308)
		(width 0.1143)
		(layer "In6.Cu")
		(net "P5E_CPU0_P0_TX_DP<4>")
	)
	(segment
		(start 348.171008 -295.91)
		(end 348.171008 -296.206926)
		(width 0.1143)
		(layer "In6.Cu")
		(net "P5E_CPU0_P0_TX_DP<4>")
	)
	(segment
		(start 348.927166 -291.419026)
		(end 348.925642 -291.420042)
		(width 0.1143)
		(layer "In6.Cu")
		(net "P5E_CPU0_P0_TX_DP<4>")
	)
	(segment
		(start 348.927166 -287.53308)
		(end 348.92996 -287.534604)
		(width 0.1143)
		(layer "In6.Cu")
		(net "P5E_CPU0_P0_TX_DP<4>")
	)
	(segment
		(start 305.084734 -374.647714)
		(end 304.627788 -375.191528)
		(width 0.14224)
		(layer "In6.Cu")
		(net "P5E_CPU0_P0_TX_DP<4>")
	)
	(segment
		(start 348.925642 -291.420042)
		(end 348.889066 -291.441378)
		(width 0.1143)
		(layer "In6.Cu")
		(net "P5E_CPU0_P0_TX_DP<4>")
	)
	(segment
		(start 348.928182 -292.39337)
		(end 348.928944 -292.393878)
		(width 0.1143)
		(layer "In6.Cu")
		(net "P5E_CPU0_P0_TX_DP<4>")
	)
	(segment
		(start 348.125288 -296.252646)
		(end 348.125288 -296.281094)
		(width 0.1143)
		(layer "In6.Cu")
		(net "P5E_CPU0_P0_TX_DP<4>")
	)
	(segment
		(start 368.770408 -341.662766)
		(end 368.770408 -349.856552)
		(width 0.14224)
		(layer "In6.Cu")
		(net "P5E_CPU0_P0_TX_DP<4>")
	)
	(segment
		(start 305.084734 -374.647968)
		(end 305.084734 -374.647714)
		(width 0.14224)
		(layer "In6.Cu")
		(net "P5E_CPU0_P0_TX_DP<4>")
	)
	(segment
		(start 348.96171 -288.158936)
		(end 348.928182 -288.178494)
		(width 0.1143)
		(layer "In6.Cu")
		(net "P5E_CPU0_P0_TX_DP<4>")
	)
	(segment
		(start 366.614202 -329.668124)
		(end 368.770408 -341.662766)
		(width 0.14224)
		(layer "In6.Cu")
		(net "P5E_CPU0_P0_TX_DP<4>")
	)
	(segment
		(start 348.928182 -291.418518)
		(end 348.927166 -291.419026)
		(width 0.1143)
		(layer "In6.Cu")
		(net "P5E_CPU0_P0_TX_DP<4>")
	)
	(segment
		(start 348.959932 -293.020242)
		(end 348.928944 -293.038022)
		(width 0.1143)
		(layer "In6.Cu")
		(net "P5E_CPU0_P0_TX_DP<4>")
	)
	(segment
		(start 348.928182 -293.03853)
		(end 348.927166 -293.039038)
		(width 0.1143)
		(layer "In6.Cu")
		(net "P5E_CPU0_P0_TX_DP<4>")
	)
	(segment
		(start 363.97946 -324.626986)
		(end 366.614202 -329.668124)
		(width 0.14224)
		(layer "In6.Cu")
		(net "P5E_CPU0_P0_TX_DP<4>")
	)
	(segment
		(start 348.925642 -293.040054)
		(end 348.889066 -293.06139)
		(width 0.1143)
		(layer "In6.Cu")
		(net "P5E_CPU0_P0_TX_DP<4>")
	)
	(segment
		(start 351.952052 -308.236366)
		(end 358.193848 -317.57747)
		(width 0.14224)
		(layer "In6.Cu")
		(net "P5E_CPU0_P0_TX_DP<4>")
	)
	(segment
		(start 348.927166 -289.799014)
		(end 348.925642 -289.80003)
		(width 0.1143)
		(layer "In6.Cu")
		(net "P5E_CPU0_P0_TX_DP<4>")
	)
	(segment
		(start 348.490032 -285.729934)
		(end 348.459044 -285.748222)
		(width 0.1143)
		(layer "In6.Cu")
		(net "P5E_CPU0_P0_TX_DP<4>")
	)
	(segment
		(start 348.928944 -294.01389)
		(end 348.959932 -294.03167)
		(width 0.1143)
		(layer "In6.Cu")
		(net "P5E_CPU0_P0_TX_DP<4>")
	)
	(segment
		(start 348.896686 -292.375082)
		(end 348.928182 -292.39337)
		(width 0.1143)
		(layer "In6.Cu")
		(net "P5E_CPU0_P0_TX_DP<4>")
	)
	(segment
		(start 304.363882 -382.101344)
		(end 304.120296 -382.34493)
		(width 0.14224)
		(layer "In6.Cu")
		(net "P5E_CPU0_P0_TX_DP<4>")
	)
	(segment
		(start 348.895924 -287.514792)
		(end 348.896686 -287.5153)
		(width 0.1143)
		(layer "In6.Cu")
		(net "P5E_CPU0_P0_TX_DP<4>")
	)
	(segment
		(start 348.171008 -296.206926)
		(end 348.125288 -296.252646)
		(width 0.1143)
		(layer "In6.Cu")
		(net "P5E_CPU0_P0_TX_DP<4>")
	)
	(segment
		(start 348.928182 -289.153346)
		(end 348.928944 -289.153854)
		(width 0.1143)
		(layer "In6.Cu")
		(net "P5E_CPU0_P0_TX_DP<4>")
	)
	(segment
		(start 349.10903 -284.685994)
		(end 349.109284 -284.685994)
		(width 0.1143)
		(layer "In6.Cu")
		(net "P5E_CPU0_P0_TX_DP<4>")
	)
	(segment
		(start 349.03918 -284.616144)
		(end 349.10903 -284.685994)
		(width 0.1143)
		(layer "In6.Cu")
		(net "P5E_CPU0_P0_TX_DP<4>")
	)
	(segment
		(start 348.895924 -290.754562)
		(end 348.896686 -290.75507)
		(width 0.1143)
		(layer "In6.Cu")
		(net "P5E_CPU0_P0_TX_DP<4>")
	)
	(segment
		(start 348.889066 -290.750498)
		(end 348.895924 -290.754562)
		(width 0.1143)
		(layer "In6.Cu")
		(net "P5E_CPU0_P0_TX_DP<4>")
	)
	(segment
		(start 348.959932 -291.40023)
		(end 348.928944 -291.41801)
		(width 0.1143)
		(layer "In6.Cu")
		(net "P5E_CPU0_P0_TX_DP<4>")
	)
	(segment
		(start 348.125288 -296.281094)
		(end 348.125288 -298.99737)
		(width 0.14224)
		(layer "In6.Cu")
		(net "P5E_CPU0_P0_TX_DP<4>")
	)
	(segment
		(start 348.896686 -290.75507)
		(end 348.928182 -290.773358)
		(width 0.1143)
		(layer "In6.Cu")
		(net "P5E_CPU0_P0_TX_DP<4>")
	)
	(segment
		(start 348.889066 -293.990522)
		(end 348.895924 -293.994586)
		(width 0.1143)
		(layer "In6.Cu")
		(net "P5E_CPU0_P0_TX_DP<4>")
	)
	(segment
		(start 348.928182 -288.178494)
		(end 348.889066 -288.201354)
		(width 0.1143)
		(layer "In6.Cu")
		(net "P5E_CPU0_P0_TX_DP<4>")
	)
	(segment
		(start 348.933262 -284.935422)
		(end 348.924626 -284.939994)
		(width 0.1143)
		(layer "In6.Cu")
		(net "P5E_CPU0_P0_TX_DP<4>")
	)
	(segment
		(start 348.951042 -294.645588)
		(end 348.889828 -294.680894)
		(width 0.1143)
		(layer "In6.Cu")
		(net "P5E_CPU0_P0_TX_DP<4>")
	)
	(segment
		(start 348.419166 -286.700722)
		(end 348.458282 -286.723582)
		(width 0.1143)
		(layer "In6.Cu")
		(net "P5E_CPU0_P0_TX_DP<4>")
	)
	(segment
		(start 348.959932 -294.03167)
		(end 348.962218 -294.033194)
		(width 0.1143)
		(layer "In6.Cu")
		(net "P5E_CPU0_P0_TX_DP<4>")
	)
	(segment
		(start 319.184528 -369.048792)
		(end 310.096154 -372.813072)
		(width 0.14224)
		(layer "In6.Cu")
		(net "P5E_CPU0_P0_TX_DP<4>")
	)
	(segment
		(start 304.411126 -375.750582)
		(end 304.411126 -381.987298)
		(width 0.14224)
		(layer "In6.Cu")
		(net "P5E_CPU0_P0_TX_DP<4>")
	)
	(segment
		(start 308.669182 -373.09679)
		(end 307.62067 -373.09679)
		(width 0.14224)
		(layer "In6.Cu")
		(net "P5E_CPU0_P0_TX_DP<4>")
	)
	(segment
		(start 348.928944 -293.038022)
		(end 348.928182 -293.03853)
		(width 0.1143)
		(layer "In6.Cu")
		(net "P5E_CPU0_P0_TX_DP<4>")
	)
	(segment
		(start 348.925642 -289.80003)
		(end 348.889066 -289.821366)
		(width 0.1143)
		(layer "In6.Cu")
		(net "P5E_CPU0_P0_TX_DP<4>")
	)
	(segment
		(start 348.458282 -286.723582)
		(end 348.490794 -286.742378)
		(width 0.1143)
		(layer "In6.Cu")
		(net "P5E_CPU0_P0_TX_DP<4>")
	)
	(segment
		(start 348.928182 -289.798506)
		(end 348.927166 -289.799014)
		(width 0.1143)
		(layer "In6.Cu")
		(net "P5E_CPU0_P0_TX_DP<4>")
	)
	(segment
		(start 348.928182 -294.013382)
		(end 348.928944 -294.01389)
		(width 0.1143)
		(layer "In6.Cu")
		(net "P5E_CPU0_P0_TX_DP<4>")
	)
	(segment
		(start 363.144816 -363.437932)
		(end 358.957118 -367.62563)
		(width 0.14224)
		(layer "In6.Cu")
		(net "P5E_CPU0_P0_TX_DP<4>")
	)
	(segment
		(start 348.928944 -291.41801)
		(end 348.928182 -291.418518)
		(width 0.1143)
		(layer "In6.Cu")
		(net "P5E_CPU0_P0_TX_DP<4>")
	)
	(segment
		(start 348.928944 -289.153854)
		(end 348.959932 -289.171634)
		(width 0.1143)
		(layer "In6.Cu")
		(net "P5E_CPU0_P0_TX_DP<4>")
	)
	(segment
		(start 348.895924 -289.13455)
		(end 348.896686 -289.135058)
		(width 0.1143)
		(layer "In6.Cu")
		(net "P5E_CPU0_P0_TX_DP<4>")
	)
	(segment
		(start 348.928944 -289.797998)
		(end 348.928182 -289.798506)
		(width 0.1143)
		(layer "In6.Cu")
		(net "P5E_CPU0_P0_TX_DP<4>")
	)
	(segment
		(start 358.193848 -317.57747)
		(end 363.97946 -324.626986)
		(width 0.14224)
		(layer "In6.Cu")
		(net "P5E_CPU0_P0_TX_DP<4>")
	)
	(segment
		(start 348.544388 -295.391078)
		(end 348.274132 -295.661334)
		(width 0.1143)
		(layer "In6.Cu")
		(net "P5E_CPU0_P0_TX_DP<4>")
	)
	(segment
		(start 348.928944 -292.393878)
		(end 348.959932 -292.411658)
		(width 0.1143)
		(layer "In6.Cu")
		(net "P5E_CPU0_P0_TX_DP<4>")
	)
	(segment
		(start 348.895924 -293.994586)
		(end 348.896686 -293.995094)
		(width 0.1143)
		(layer "In6.Cu")
		(net "P5E_CPU0_P0_TX_DP<4>")
	)
	(segment
		(start 304.517806 -375.372376)
		(end 304.456846 -375.519188)
		(width 0.14224)
		(layer "In6.Cu")
		(net "P5E_CPU0_P0_TX_DP<4>")
	)
	(segment
		(start 348.927166 -293.039038)
		(end 348.925642 -293.040054)
		(width 0.1143)
		(layer "In6.Cu")
		(net "P5E_CPU0_P0_TX_DP<4>")
	)
	(segment
		(start 307.35016 -373.175276)
		(end 305.244754 -374.508268)
		(width 0.14224)
		(layer "In6.Cu")
		(net "P5E_CPU0_P0_TX_DP<4>")
	)
	(segment
		(start 348.741238 -284.616144)
		(end 349.03918 -284.616144)
		(width 0.1143)
		(layer "In6.Cu")
		(net "P5E_CPU0_P0_TX_DP<4>")
	)
	(segment
		(start 348.896686 -289.135058)
		(end 348.928182 -289.153346)
		(width 0.1143)
		(layer "In6.Cu")
		(net "P5E_CPU0_P0_TX_DP<4>")
	)
	(arc
		(start 348.645988 -295.145968)
		(mid 348.619581 -295.278634)
		(end 348.544388 -295.391078)
		(width 0.1143)
		(layer "In6.Cu")
		(net "P5E_CPU0_P0_TX_DP<4>")
	)
	(arc
		(start 348.645734 -287.045908)
		(mid 348.71097 -287.309499)
		(end 348.891606 -287.512252)
		(width 0.1143)
		(layer "In6.Cu")
		(net "P5E_CPU0_P0_TX_DP<4>")
	)
	(arc
		(start 348.889066 -291.441378)
		(mid 348.645739 -291.905944)
		(end 348.889066 -292.37051)
		(width 0.1143)
		(layer "In6.Cu")
		(net "P5E_CPU0_P0_TX_DP<4>")
	)
	(arc
		(start 304.411126 -381.987298)
		(mid 304.398849 -382.049021)
		(end 304.363882 -382.101344)
		(width 0.14224)
		(layer "In6.Cu")
		(net "P5E_CPU0_P0_TX_DP<4>")
	)
	(arc
		(start 348.274132 -295.661334)
		(mid 348.197871 -295.775422)
		(end 348.171008 -295.91)
		(width 0.1143)
		(layer "In6.Cu")
		(net "P5E_CPU0_P0_TX_DP<4>")
	)
	(arc
		(start 310.096154 -372.813072)
		(mid 309.396638 -373.02519)
		(end 308.669182 -373.09679)
		(width 0.14224)
		(layer "In6.Cu")
		(net "P5E_CPU0_P0_TX_DP<4>")
	)
	(arc
		(start 321.964304 -368.496088)
		(mid 320.547199 -368.635554)
		(end 319.184528 -369.048792)
		(width 0.14224)
		(layer "In6.Cu")
		(net "P5E_CPU0_P0_TX_DP<4>")
	)
	(arc
		(start 307.62067 -373.09679)
		(mid 307.479849 -373.116845)
		(end 307.35016 -373.175276)
		(width 0.14224)
		(layer "In6.Cu")
		(net "P5E_CPU0_P0_TX_DP<4>")
	)
	(arc
		(start 348.962218 -294.033194)
		(mid 349.111791 -294.335962)
		(end 348.962218 -294.63873)
		(width 0.1143)
		(layer "In6.Cu")
		(net "P5E_CPU0_P0_TX_DP<4>")
	)
	(arc
		(start 305.244754 -374.508268)
		(mid 305.159379 -374.571971)
		(end 305.084734 -374.647968)
		(width 0.14224)
		(layer "In6.Cu")
		(net "P5E_CPU0_P0_TX_DP<4>")
	)
	(arc
		(start 348.92996 -287.534604)
		(mid 349.066041 -287.670452)
		(end 349.115888 -287.856168)
		(width 0.1143)
		(layer "In6.Cu")
		(net "P5E_CPU0_P0_TX_DP<4>")
	)
	(arc
		(start 368.770408 -349.856552)
		(mid 367.308364 -357.206742)
		(end 363.144816 -363.437932)
		(width 0.14224)
		(layer "In6.Cu")
		(net "P5E_CPU0_P0_TX_DP<4>")
	)
	(arc
		(start 348.645988 -285.42615)
		(mid 348.604671 -285.596866)
		(end 348.490032 -285.729934)
		(width 0.1143)
		(layer "In6.Cu")
		(net "P5E_CPU0_P0_TX_DP<4>")
	)
	(arc
		(start 304.456846 -375.519188)
		(mid 304.422604 -375.632635)
		(end 304.411126 -375.750582)
		(width 0.14224)
		(layer "In6.Cu")
		(net "P5E_CPU0_P0_TX_DP<4>")
	)
	(arc
		(start 304.627788 -375.191528)
		(mid 304.565903 -375.277758)
		(end 304.517806 -375.372376)
		(width 0.14224)
		(layer "In6.Cu")
		(net "P5E_CPU0_P0_TX_DP<4>")
	)
	(arc
		(start 349.109284 -284.685994)
		(mid 349.048333 -284.829807)
		(end 348.933262 -284.935422)
		(width 0.1143)
		(layer "In6.Cu")
		(net "P5E_CPU0_P0_TX_DP<4>")
	)
	(arc
		(start 348.924626 -284.939994)
		(mid 348.720484 -285.145928)
		(end 348.645988 -285.42615)
		(width 0.1143)
		(layer "In6.Cu")
		(net "P5E_CPU0_P0_TX_DP<4>")
	)
	(arc
		(start 348.889066 -293.06139)
		(mid 348.645739 -293.525956)
		(end 348.889066 -293.990522)
		(width 0.1143)
		(layer "In6.Cu")
		(net "P5E_CPU0_P0_TX_DP<4>")
	)
	(arc
		(start 348.419166 -285.77159)
		(mid 348.175839 -286.236156)
		(end 348.419166 -286.700722)
		(width 0.1143)
		(layer "In6.Cu")
		(net "P5E_CPU0_P0_TX_DP<4>")
	)
	(arc
		(start 348.889066 -288.201354)
		(mid 348.645739 -288.66592)
		(end 348.889066 -289.130486)
		(width 0.1143)
		(layer "In6.Cu")
		(net "P5E_CPU0_P0_TX_DP<4>")
	)
	(arc
		(start 348.490794 -286.742378)
		(mid 348.604723 -286.875525)
		(end 348.645734 -287.045908)
		(width 0.1143)
		(layer "In6.Cu")
		(net "P5E_CPU0_P0_TX_DP<4>")
	)
	(arc
		(start 348.959932 -292.411658)
		(mid 349.111521 -292.71595)
		(end 348.959932 -293.020242)
		(width 0.1143)
		(layer "In6.Cu")
		(net "P5E_CPU0_P0_TX_DP<4>")
	)
	(arc
		(start 358.957118 -367.62563)
		(mid 357.992883 -368.269848)
		(end 356.855522 -368.496088)
		(width 0.14224)
		(layer "In6.Cu")
		(net "P5E_CPU0_P0_TX_DP<4>")
	)
	(arc
		(start 348.889066 -289.821366)
		(mid 348.645739 -290.285932)
		(end 348.889066 -290.750498)
		(width 0.1143)
		(layer "In6.Cu")
		(net "P5E_CPU0_P0_TX_DP<4>")
	)
	(arc
		(start 348.889828 -294.680894)
		(mid 348.710635 -294.883404)
		(end 348.645988 -295.145968)
		(width 0.1143)
		(layer "In6.Cu")
		(net "P5E_CPU0_P0_TX_DP<4>")
	)
	(arc
		(start 349.115888 -287.856168)
		(mid 349.075126 -288.026052)
		(end 348.96171 -288.158936)
		(width 0.1143)
		(layer "In6.Cu")
		(net "P5E_CPU0_P0_TX_DP<4>")
	)
	(arc
		(start 348.959932 -290.791646)
		(mid 349.111521 -291.095938)
		(end 348.959932 -291.40023)
		(width 0.1143)
		(layer "In6.Cu")
		(net "P5E_CPU0_P0_TX_DP<4>")
	)
	(arc
		(start 348.959932 -289.171634)
		(mid 349.109029 -289.475926)
		(end 348.959932 -289.780218)
		(width 0.1143)
		(layer "In6.Cu")
		(net "P5E_CPU0_P0_TX_DP<4>")
	)
	(segment
		(start 300.987206 -378.39142)
		(end 300.987206 -377.68784)
		(width 0.12954)
		(layer "F.Cu")
		(net "P5E_CPU0_P0_TX_DP<3>")
	)
	(segment
		(start 300.691296 -378.68733)
		(end 300.987206 -378.39142)
		(width 0.12954)
		(layer "F.Cu")
		(net "P5E_CPU0_P0_TX_DP<3>")
	)
	(segment
		(start 300.987206 -377.68784)
		(end 300.716696 -377.41733)
		(width 0.12954)
		(layer "F.Cu")
		(net "P5E_CPU0_P0_TX_DP<3>")
	)
	(segment
		(start 349.20809 -282.730194)
		(end 348.741238 -282.996132)
		(width 0.12954)
		(layer "F.Cu")
		(net "P5E_CPU0_P0_TX_DP<3>")
	)
	(segment
		(start 347.98635 -292.392354)
		(end 347.987112 -292.392862)
		(width 0.1143)
		(layer "In6.Cu")
		(net "P5E_CPU0_P0_TX_DP<3>")
	)
	(segment
		(start 347.98254 -291.42182)
		(end 347.97619 -291.425376)
		(width 0.1143)
		(layer "In6.Cu")
		(net "P5E_CPU0_P0_TX_DP<3>")
	)
	(segment
		(start 347.705934 -295.049702)
		(end 347.705934 -295.066974)
		(width 0.1143)
		(layer "In6.Cu")
		(net "P5E_CPU0_P0_TX_DP<3>")
	)
	(segment
		(start 367.838228 -341.761572)
		(end 367.838228 -349.515684)
		(width 0.14224)
		(layer "In6.Cu")
		(net "P5E_CPU0_P0_TX_DP<3>")
	)
	(segment
		(start 347.97619 -291.425376)
		(end 347.949012 -291.441378)
		(width 0.1143)
		(layer "In6.Cu")
		(net "P5E_CPU0_P0_TX_DP<3>")
	)
	(segment
		(start 347.988382 -292.393624)
		(end 347.989398 -292.394132)
		(width 0.1143)
		(layer "In6.Cu")
		(net "P5E_CPU0_P0_TX_DP<3>")
	)
	(segment
		(start 347.98635 -290.772342)
		(end 347.987112 -290.77285)
		(width 0.1143)
		(layer "In6.Cu")
		(net "P5E_CPU0_P0_TX_DP<3>")
	)
	(segment
		(start 347.705934 -295.066974)
		(end 347.70568 -295.067228)
		(width 0.1143)
		(layer "In6.Cu")
		(net "P5E_CPU0_P0_TX_DP<3>")
	)
	(segment
		(start 347.236288 -296.206926)
		(end 347.190568 -296.252646)
		(width 0.1143)
		(layer "In6.Cu")
		(net "P5E_CPU0_P0_TX_DP<3>")
	)
	(segment
		(start 348.490032 -284.110176)
		(end 348.419166 -284.151578)
		(width 0.1143)
		(layer "In6.Cu")
		(net "P5E_CPU0_P0_TX_DP<3>")
	)
	(segment
		(start 362.246164 -363.016038)
		(end 358.518206 -366.743996)
		(width 0.14224)
		(layer "In6.Cu")
		(net "P5E_CPU0_P0_TX_DP<3>")
	)
	(segment
		(start 347.479112 -286.700722)
		(end 347.55074 -286.742378)
		(width 0.1143)
		(layer "In6.Cu")
		(net "P5E_CPU0_P0_TX_DP<3>")
	)
	(segment
		(start 347.987112 -294.012874)
		(end 347.988382 -294.013636)
		(width 0.1143)
		(layer "In6.Cu")
		(net "P5E_CPU0_P0_TX_DP<3>")
	)
	(segment
		(start 347.984826 -294.660574)
		(end 347.98381 -294.661082)
		(width 0.1143)
		(layer "In6.Cu")
		(net "P5E_CPU0_P0_TX_DP<3>")
	)
	(segment
		(start 347.98508 -284.940502)
		(end 347.983302 -284.941518)
		(width 0.1143)
		(layer "In6.Cu")
		(net "P5E_CPU0_P0_TX_DP<3>")
	)
	(segment
		(start 347.988128 -293.03853)
		(end 347.987112 -293.039038)
		(width 0.1143)
		(layer "In6.Cu")
		(net "P5E_CPU0_P0_TX_DP<3>")
	)
	(segment
		(start 347.98381 -294.661082)
		(end 347.981778 -294.662352)
		(width 0.1143)
		(layer "In6.Cu")
		(net "P5E_CPU0_P0_TX_DP<3>")
	)
	(segment
		(start 347.981778 -294.662352)
		(end 347.948504 -294.681402)
		(width 0.1143)
		(layer "In6.Cu")
		(net "P5E_CPU0_P0_TX_DP<3>")
	)
	(segment
		(start 347.987112 -290.77285)
		(end 347.988382 -290.773612)
		(width 0.1143)
		(layer "In6.Cu")
		(net "P5E_CPU0_P0_TX_DP<3>")
	)
	(segment
		(start 347.995748 -292.397688)
		(end 348.019878 -292.411658)
		(width 0.1143)
		(layer "In6.Cu")
		(net "P5E_CPU0_P0_TX_DP<3>")
	)
	(segment
		(start 347.990668 -294.014906)
		(end 347.99143 -294.015414)
		(width 0.1143)
		(layer "In6.Cu")
		(net "P5E_CPU0_P0_TX_DP<3>")
	)
	(segment
		(start 347.988128 -291.418518)
		(end 347.987112 -291.419026)
		(width 0.1143)
		(layer "In6.Cu")
		(net "P5E_CPU0_P0_TX_DP<3>")
	)
	(segment
		(start 348.741238 -282.996132)
		(end 349.03918 -282.996132)
		(width 0.1143)
		(layer "In6.Cu")
		(net "P5E_CPU0_P0_TX_DP<3>")
	)
	(segment
		(start 347.988382 -290.773612)
		(end 347.989398 -290.77412)
		(width 0.1143)
		(layer "In6.Cu")
		(net "P5E_CPU0_P0_TX_DP<3>")
	)
	(segment
		(start 347.988128 -289.798506)
		(end 347.987112 -289.799014)
		(width 0.1143)
		(layer "In6.Cu")
		(net "P5E_CPU0_P0_TX_DP<3>")
	)
	(segment
		(start 348.019878 -284.920436)
		(end 347.98889 -284.938216)
		(width 0.1143)
		(layer "In6.Cu")
		(net "P5E_CPU0_P0_TX_DP<3>")
	)
	(segment
		(start 347.949012 -290.750498)
		(end 347.98635 -290.772342)
		(width 0.1143)
		(layer "In6.Cu")
		(net "P5E_CPU0_P0_TX_DP<3>")
	)
	(segment
		(start 302.413162 -373.839486)
		(end 301.680118 -374.57253)
		(width 0.14224)
		(layer "In6.Cu")
		(net "P5E_CPU0_P0_TX_DP<3>")
	)
	(segment
		(start 363.31144 -325.361808)
		(end 365.724694 -330.004166)
		(width 0.14224)
		(layer "In6.Cu")
		(net "P5E_CPU0_P0_TX_DP<3>")
	)
	(segment
		(start 347.97619 -284.945582)
		(end 347.949012 -284.961584)
		(width 0.1143)
		(layer "In6.Cu")
		(net "P5E_CPU0_P0_TX_DP<3>")
	)
	(segment
		(start 347.98508 -293.040308)
		(end 347.983302 -293.041324)
		(width 0.1143)
		(layer "In6.Cu")
		(net "P5E_CPU0_P0_TX_DP<3>")
	)
	(segment
		(start 347.995748 -290.777676)
		(end 348.019878 -290.791646)
		(width 0.1143)
		(layer "In6.Cu")
		(net "P5E_CPU0_P0_TX_DP<3>")
	)
	(segment
		(start 348.933262 -283.31541)
		(end 348.924626 -283.319982)
		(width 0.1143)
		(layer "In6.Cu")
		(net "P5E_CPU0_P0_TX_DP<3>")
	)
	(segment
		(start 347.988128 -294.658542)
		(end 347.98635 -294.659558)
		(width 0.1143)
		(layer "In6.Cu")
		(net "P5E_CPU0_P0_TX_DP<3>")
	)
	(segment
		(start 347.98254 -289.801808)
		(end 347.97619 -289.805364)
		(width 0.1143)
		(layer "In6.Cu")
		(net "P5E_CPU0_P0_TX_DP<3>")
	)
	(segment
		(start 347.98508 -291.420296)
		(end 347.983302 -291.421312)
		(width 0.1143)
		(layer "In6.Cu")
		(net "P5E_CPU0_P0_TX_DP<3>")
	)
	(segment
		(start 347.988128 -284.938724)
		(end 347.987112 -284.939232)
		(width 0.1143)
		(layer "In6.Cu")
		(net "P5E_CPU0_P0_TX_DP<3>")
	)
	(segment
		(start 349.03918 -282.996132)
		(end 349.10903 -283.065982)
		(width 0.1143)
		(layer "In6.Cu")
		(net "P5E_CPU0_P0_TX_DP<3>")
	)
	(segment
		(start 348.021656 -288.158936)
		(end 347.949012 -288.201354)
		(width 0.1143)
		(layer "In6.Cu")
		(net "P5E_CPU0_P0_TX_DP<3>")
	)
	(segment
		(start 351.128584 -308.68493)
		(end 357.717344 -318.54521)
		(width 0.14224)
		(layer "In6.Cu")
		(net "P5E_CPU0_P0_TX_DP<3>")
	)
	(segment
		(start 347.987112 -292.392862)
		(end 347.988382 -292.393624)
		(width 0.1143)
		(layer "In6.Cu")
		(net "P5E_CPU0_P0_TX_DP<3>")
	)
	(segment
		(start 365.724694 -330.004166)
		(end 367.838228 -341.761572)
		(width 0.14224)
		(layer "In6.Cu")
		(net "P5E_CPU0_P0_TX_DP<3>")
	)
	(segment
		(start 318.929512 -368.144552)
		(end 309.86476 -371.89918)
		(width 0.14224)
		(layer "In6.Cu")
		(net "P5E_CPU0_P0_TX_DP<3>")
	)
	(segment
		(start 348.019878 -294.640254)
		(end 347.988128 -294.658542)
		(width 0.1143)
		(layer "In6.Cu")
		(net "P5E_CPU0_P0_TX_DP<3>")
	)
	(segment
		(start 347.987112 -284.939232)
		(end 347.98508 -284.940502)
		(width 0.1143)
		(layer "In6.Cu")
		(net "P5E_CPU0_P0_TX_DP<3>")
	)
	(segment
		(start 347.990668 -290.774882)
		(end 347.99143 -290.77539)
		(width 0.1143)
		(layer "In6.Cu")
		(net "P5E_CPU0_P0_TX_DP<3>")
	)
	(segment
		(start 347.99397 -292.396672)
		(end 347.995748 -292.397688)
		(width 0.1143)
		(layer "In6.Cu")
		(net "P5E_CPU0_P0_TX_DP<3>")
	)
	(segment
		(start 347.983302 -284.941518)
		(end 347.98254 -284.942026)
		(width 0.1143)
		(layer "In6.Cu")
		(net "P5E_CPU0_P0_TX_DP<3>")
	)
	(segment
		(start 347.97619 -289.805364)
		(end 347.949012 -289.821366)
		(width 0.1143)
		(layer "In6.Cu")
		(net "P5E_CPU0_P0_TX_DP<3>")
	)
	(segment
		(start 347.97619 -293.045388)
		(end 347.949012 -293.06139)
		(width 0.1143)
		(layer "In6.Cu")
		(net "P5E_CPU0_P0_TX_DP<3>")
	)
	(segment
		(start 348.019878 -291.40023)
		(end 347.98889 -291.41801)
		(width 0.1143)
		(layer "In6.Cu")
		(net "P5E_CPU0_P0_TX_DP<3>")
	)
	(segment
		(start 347.98635 -294.659558)
		(end 347.984826 -294.660574)
		(width 0.1143)
		(layer "In6.Cu")
		(net "P5E_CPU0_P0_TX_DP<3>")
	)
	(segment
		(start 301.007526 -376.196352)
		(end 301.007526 -377.1265)
		(width 0.14224)
		(layer "In6.Cu")
		(net "P5E_CPU0_P0_TX_DP<3>")
	)
	(segment
		(start 347.948504 -294.681402)
		(end 347.862652 -294.743378)
		(width 0.1143)
		(layer "In6.Cu")
		(net "P5E_CPU0_P0_TX_DP<3>")
	)
	(segment
		(start 347.995748 -294.0177)
		(end 348.019878 -294.03167)
		(width 0.1143)
		(layer "In6.Cu")
		(net "P5E_CPU0_P0_TX_DP<3>")
	)
	(segment
		(start 347.98508 -289.800284)
		(end 347.983302 -289.8013)
		(width 0.1143)
		(layer "In6.Cu")
		(net "P5E_CPU0_P0_TX_DP<3>")
	)
	(segment
		(start 347.99397 -290.77666)
		(end 347.995748 -290.777676)
		(width 0.1143)
		(layer "In6.Cu")
		(net "P5E_CPU0_P0_TX_DP<3>")
	)
	(segment
		(start 347.190568 -299.176948)
		(end 351.128584 -308.68493)
		(width 0.14224)
		(layer "In6.Cu")
		(net "P5E_CPU0_P0_TX_DP<3>")
	)
	(segment
		(start 347.987112 -291.419026)
		(end 347.98508 -291.420296)
		(width 0.1143)
		(layer "In6.Cu")
		(net "P5E_CPU0_P0_TX_DP<3>")
	)
	(segment
		(start 347.99143 -292.395402)
		(end 347.99397 -292.396672)
		(width 0.1143)
		(layer "In6.Cu")
		(net "P5E_CPU0_P0_TX_DP<3>")
	)
	(segment
		(start 347.989398 -294.014144)
		(end 347.990668 -294.014906)
		(width 0.1143)
		(layer "In6.Cu")
		(net "P5E_CPU0_P0_TX_DP<3>")
	)
	(segment
		(start 347.98889 -284.938216)
		(end 347.988128 -284.938724)
		(width 0.1143)
		(layer "In6.Cu")
		(net "P5E_CPU0_P0_TX_DP<3>")
	)
	(segment
		(start 347.983302 -289.8013)
		(end 347.98254 -289.801808)
		(width 0.1143)
		(layer "In6.Cu")
		(net "P5E_CPU0_P0_TX_DP<3>")
	)
	(segment
		(start 347.983302 -291.421312)
		(end 347.98254 -291.42182)
		(width 0.1143)
		(layer "In6.Cu")
		(net "P5E_CPU0_P0_TX_DP<3>")
	)
	(segment
		(start 347.190568 -296.252646)
		(end 347.190568 -296.281094)
		(width 0.1143)
		(layer "In6.Cu")
		(net "P5E_CPU0_P0_TX_DP<3>")
	)
	(segment
		(start 347.98889 -289.797998)
		(end 347.988128 -289.798506)
		(width 0.1143)
		(layer "In6.Cu")
		(net "P5E_CPU0_P0_TX_DP<3>")
	)
	(segment
		(start 347.949012 -289.130486)
		(end 348.019878 -289.171634)
		(width 0.1143)
		(layer "In6.Cu")
		(net "P5E_CPU0_P0_TX_DP<3>")
	)
	(segment
		(start 347.98889 -291.41801)
		(end 347.988128 -291.418518)
		(width 0.1143)
		(layer "In6.Cu")
		(net "P5E_CPU0_P0_TX_DP<3>")
	)
	(segment
		(start 347.99143 -290.77539)
		(end 347.99397 -290.77666)
		(width 0.1143)
		(layer "In6.Cu")
		(net "P5E_CPU0_P0_TX_DP<3>")
	)
	(segment
		(start 357.717344 -318.54521)
		(end 363.31144 -325.361808)
		(width 0.14224)
		(layer "In6.Cu")
		(net "P5E_CPU0_P0_TX_DP<3>")
	)
	(segment
		(start 347.98254 -293.041832)
		(end 347.97619 -293.045388)
		(width 0.1143)
		(layer "In6.Cu")
		(net "P5E_CPU0_P0_TX_DP<3>")
	)
	(segment
		(start 301.007526 -377.1265)
		(end 300.716696 -377.41733)
		(width 0.14224)
		(layer "In6.Cu")
		(net "P5E_CPU0_P0_TX_DP<3>")
	)
	(segment
		(start 347.658436 -295.439084)
		(end 347.339412 -295.758108)
		(width 0.1143)
		(layer "In6.Cu")
		(net "P5E_CPU0_P0_TX_DP<3>")
	)
	(segment
		(start 347.949012 -292.37051)
		(end 347.98635 -292.392354)
		(width 0.1143)
		(layer "In6.Cu")
		(net "P5E_CPU0_P0_TX_DP<3>")
	)
	(segment
		(start 347.987112 -293.039038)
		(end 347.98508 -293.040308)
		(width 0.1143)
		(layer "In6.Cu")
		(net "P5E_CPU0_P0_TX_DP<3>")
	)
	(segment
		(start 347.983302 -293.041324)
		(end 347.98254 -293.041832)
		(width 0.1143)
		(layer "In6.Cu")
		(net "P5E_CPU0_P0_TX_DP<3>")
	)
	(segment
		(start 347.987112 -289.799014)
		(end 347.98508 -289.800284)
		(width 0.1143)
		(layer "In6.Cu")
		(net "P5E_CPU0_P0_TX_DP<3>")
	)
	(segment
		(start 347.989398 -292.394132)
		(end 347.990668 -292.394894)
		(width 0.1143)
		(layer "In6.Cu")
		(net "P5E_CPU0_P0_TX_DP<3>")
	)
	(segment
		(start 347.190568 -296.281094)
		(end 347.190568 -299.176948)
		(width 0.14224)
		(layer "In6.Cu")
		(net "P5E_CPU0_P0_TX_DP<3>")
	)
	(segment
		(start 347.236288 -296.006774)
		(end 347.236288 -296.206926)
		(width 0.1143)
		(layer "In6.Cu")
		(net "P5E_CPU0_P0_TX_DP<3>")
	)
	(segment
		(start 348.019878 -289.780218)
		(end 347.98889 -289.797998)
		(width 0.1143)
		(layer "In6.Cu")
		(net "P5E_CPU0_P0_TX_DP<3>")
	)
	(segment
		(start 347.98635 -294.012366)
		(end 347.987112 -294.012874)
		(width 0.1143)
		(layer "In6.Cu")
		(net "P5E_CPU0_P0_TX_DP<3>")
	)
	(segment
		(start 348.019878 -293.020242)
		(end 347.98889 -293.038022)
		(width 0.1143)
		(layer "In6.Cu")
		(net "P5E_CPU0_P0_TX_DP<3>")
	)
	(segment
		(start 347.949012 -293.990522)
		(end 347.98635 -294.012366)
		(width 0.1143)
		(layer "In6.Cu")
		(net "P5E_CPU0_P0_TX_DP<3>")
	)
	(segment
		(start 347.548708 -285.73095)
		(end 347.479112 -285.77159)
		(width 0.1143)
		(layer "In6.Cu")
		(net "P5E_CPU0_P0_TX_DP<3>")
	)
	(segment
		(start 347.951552 -287.512252)
		(end 348.019878 -287.551876)
		(width 0.1143)
		(layer "In6.Cu")
		(net "P5E_CPU0_P0_TX_DP<3>")
	)
	(segment
		(start 347.989398 -290.77412)
		(end 347.990668 -290.774882)
		(width 0.1143)
		(layer "In6.Cu")
		(net "P5E_CPU0_P0_TX_DP<3>")
	)
	(segment
		(start 349.10903 -283.065982)
		(end 349.109284 -283.065982)
		(width 0.1143)
		(layer "In6.Cu")
		(net "P5E_CPU0_P0_TX_DP<3>")
	)
	(segment
		(start 347.99143 -294.015414)
		(end 347.99397 -294.016684)
		(width 0.1143)
		(layer "In6.Cu")
		(net "P5E_CPU0_P0_TX_DP<3>")
	)
	(segment
		(start 347.990668 -292.394894)
		(end 347.99143 -292.395402)
		(width 0.1143)
		(layer "In6.Cu")
		(net "P5E_CPU0_P0_TX_DP<3>")
	)
	(segment
		(start 347.99397 -294.016684)
		(end 347.995748 -294.0177)
		(width 0.1143)
		(layer "In6.Cu")
		(net "P5E_CPU0_P0_TX_DP<3>")
	)
	(segment
		(start 347.98889 -293.038022)
		(end 347.988128 -293.03853)
		(width 0.1143)
		(layer "In6.Cu")
		(net "P5E_CPU0_P0_TX_DP<3>")
	)
	(segment
		(start 356.545642 -367.561114)
		(end 321.863466 -367.561114)
		(width 0.14224)
		(layer "In6.Cu")
		(net "P5E_CPU0_P0_TX_DP<3>")
	)
	(segment
		(start 347.988382 -294.013636)
		(end 347.989398 -294.014144)
		(width 0.1143)
		(layer "In6.Cu")
		(net "P5E_CPU0_P0_TX_DP<3>")
	)
	(segment
		(start 347.70568 -295.067228)
		(end 347.70568 -295.325038)
		(width 0.1143)
		(layer "In6.Cu")
		(net "P5E_CPU0_P0_TX_DP<3>")
	)
	(segment
		(start 308.558692 -372.159022)
		(end 306.470304 -372.159022)
		(width 0.14224)
		(layer "In6.Cu")
		(net "P5E_CPU0_P0_TX_DP<3>")
	)
	(segment
		(start 347.98254 -284.942026)
		(end 347.97619 -284.945582)
		(width 0.1143)
		(layer "In6.Cu")
		(net "P5E_CPU0_P0_TX_DP<3>")
	)
	(arc
		(start 348.175834 -287.856168)
		(mid 348.135072 -288.026052)
		(end 348.021656 -288.158936)
		(width 0.1143)
		(layer "In6.Cu")
		(net "P5E_CPU0_P0_TX_DP<3>")
	)
	(arc
		(start 347.862652 -294.743378)
		(mid 347.747378 -294.877656)
		(end 347.705934 -295.049702)
		(width 0.1143)
		(layer "In6.Cu")
		(net "P5E_CPU0_P0_TX_DP<3>")
	)
	(arc
		(start 347.70568 -285.42615)
		(mid 347.664131 -285.597572)
		(end 347.548708 -285.73095)
		(width 0.1143)
		(layer "In6.Cu")
		(net "P5E_CPU0_P0_TX_DP<3>")
	)
	(arc
		(start 358.518206 -366.743996)
		(mid 357.6132 -367.348765)
		(end 356.545642 -367.561114)
		(width 0.14224)
		(layer "In6.Cu")
		(net "P5E_CPU0_P0_TX_DP<3>")
	)
	(arc
		(start 348.019878 -290.791646)
		(mid 348.175806 -291.095938)
		(end 348.019878 -291.40023)
		(width 0.1143)
		(layer "In6.Cu")
		(net "P5E_CPU0_P0_TX_DP<3>")
	)
	(arc
		(start 347.949012 -291.441378)
		(mid 347.705685 -291.905944)
		(end 347.949012 -292.37051)
		(width 0.1143)
		(layer "In6.Cu")
		(net "P5E_CPU0_P0_TX_DP<3>")
	)
	(arc
		(start 306.470304 -372.159022)
		(mid 304.274603 -372.595756)
		(end 302.413162 -373.839486)
		(width 0.14224)
		(layer "In6.Cu")
		(net "P5E_CPU0_P0_TX_DP<3>")
	)
	(arc
		(start 301.680118 -374.57253)
		(mid 301.182314 -375.317546)
		(end 301.007526 -376.196352)
		(width 0.14224)
		(layer "In6.Cu")
		(net "P5E_CPU0_P0_TX_DP<3>")
	)
	(arc
		(start 321.863466 -367.561114)
		(mid 320.367764 -367.708372)
		(end 318.929512 -368.144552)
		(width 0.14224)
		(layer "In6.Cu")
		(net "P5E_CPU0_P0_TX_DP<3>")
	)
	(arc
		(start 309.86476 -371.89918)
		(mid 309.224521 -372.093408)
		(end 308.558692 -372.159022)
		(width 0.14224)
		(layer "In6.Cu")
		(net "P5E_CPU0_P0_TX_DP<3>")
	)
	(arc
		(start 347.339412 -295.758108)
		(mid 347.263151 -295.872196)
		(end 347.236288 -296.006774)
		(width 0.1143)
		(layer "In6.Cu")
		(net "P5E_CPU0_P0_TX_DP<3>")
	)
	(arc
		(start 348.645988 -283.806138)
		(mid 348.604729 -283.976995)
		(end 348.490032 -284.110176)
		(width 0.1143)
		(layer "In6.Cu")
		(net "P5E_CPU0_P0_TX_DP<3>")
	)
	(arc
		(start 347.949012 -289.821366)
		(mid 347.705685 -290.285932)
		(end 347.949012 -290.750498)
		(width 0.1143)
		(layer "In6.Cu")
		(net "P5E_CPU0_P0_TX_DP<3>")
	)
	(arc
		(start 347.70568 -295.325038)
		(mid 347.693418 -295.386775)
		(end 347.658436 -295.439084)
		(width 0.1143)
		(layer "In6.Cu")
		(net "P5E_CPU0_P0_TX_DP<3>")
	)
	(arc
		(start 348.019878 -292.411658)
		(mid 348.175806 -292.71595)
		(end 348.019878 -293.020242)
		(width 0.1143)
		(layer "In6.Cu")
		(net "P5E_CPU0_P0_TX_DP<3>")
	)
	(arc
		(start 348.019878 -289.171634)
		(mid 348.175806 -289.475926)
		(end 348.019878 -289.780218)
		(width 0.1143)
		(layer "In6.Cu")
		(net "P5E_CPU0_P0_TX_DP<3>")
	)
	(arc
		(start 347.949012 -288.201354)
		(mid 347.705685 -288.66592)
		(end 347.949012 -289.130486)
		(width 0.1143)
		(layer "In6.Cu")
		(net "P5E_CPU0_P0_TX_DP<3>")
	)
	(arc
		(start 348.419166 -284.151578)
		(mid 348.240353 -284.353928)
		(end 348.175834 -284.616144)
		(width 0.1143)
		(layer "In6.Cu")
		(net "P5E_CPU0_P0_TX_DP<3>")
	)
	(arc
		(start 347.949012 -293.06139)
		(mid 347.705685 -293.525956)
		(end 347.949012 -293.990522)
		(width 0.1143)
		(layer "In6.Cu")
		(net "P5E_CPU0_P0_TX_DP<3>")
	)
	(arc
		(start 347.949012 -284.961584)
		(mid 347.770199 -285.163934)
		(end 347.70568 -285.42615)
		(width 0.1143)
		(layer "In6.Cu")
		(net "P5E_CPU0_P0_TX_DP<3>")
	)
	(arc
		(start 367.838228 -349.515684)
		(mid 366.384904 -356.822036)
		(end 362.246164 -363.016038)
		(width 0.14224)
		(layer "In6.Cu")
		(net "P5E_CPU0_P0_TX_DP<3>")
	)
	(arc
		(start 347.479112 -285.77159)
		(mid 347.235785 -286.236156)
		(end 347.479112 -286.700722)
		(width 0.1143)
		(layer "In6.Cu")
		(net "P5E_CPU0_P0_TX_DP<3>")
	)
	(arc
		(start 347.70568 -287.045908)
		(mid 347.770916 -287.309499)
		(end 347.951552 -287.512252)
		(width 0.1143)
		(layer "In6.Cu")
		(net "P5E_CPU0_P0_TX_DP<3>")
	)
	(arc
		(start 348.924626 -283.319982)
		(mid 348.720484 -283.525916)
		(end 348.645988 -283.806138)
		(width 0.1143)
		(layer "In6.Cu")
		(net "P5E_CPU0_P0_TX_DP<3>")
	)
	(arc
		(start 348.019878 -294.03167)
		(mid 348.175806 -294.335962)
		(end 348.019878 -294.640254)
		(width 0.1143)
		(layer "In6.Cu")
		(net "P5E_CPU0_P0_TX_DP<3>")
	)
	(arc
		(start 349.109284 -283.065982)
		(mid 349.048333 -283.209795)
		(end 348.933262 -283.31541)
		(width 0.1143)
		(layer "In6.Cu")
		(net "P5E_CPU0_P0_TX_DP<3>")
	)
	(arc
		(start 348.019878 -287.551876)
		(mid 348.134554 -287.68521)
		(end 348.175834 -287.856168)
		(width 0.1143)
		(layer "In6.Cu")
		(net "P5E_CPU0_P0_TX_DP<3>")
	)
	(arc
		(start 348.175834 -284.616144)
		(mid 348.134579 -284.787115)
		(end 348.019878 -284.920436)
		(width 0.1143)
		(layer "In6.Cu")
		(net "P5E_CPU0_P0_TX_DP<3>")
	)
	(arc
		(start 347.55074 -286.742378)
		(mid 347.664669 -286.875525)
		(end 347.70568 -287.045908)
		(width 0.1143)
		(layer "In6.Cu")
		(net "P5E_CPU0_P0_TX_DP<3>")
	)
	(segment
		(start 298.989496 -381.15113)
		(end 299.285406 -380.85522)
		(width 0.12954)
		(layer "F.Cu")
		(net "P5E_CPU0_P0_TX_DP<2>")
	)
	(segment
		(start 346.387928 -281.110182)
		(end 345.921076 -281.37612)
		(width 0.12954)
		(layer "F.Cu")
		(net "P5E_CPU0_P0_TX_DP<2>")
	)
	(segment
		(start 299.285406 -380.15164)
		(end 299.014896 -379.88113)
		(width 0.12954)
		(layer "F.Cu")
		(net "P5E_CPU0_P0_TX_DP<2>")
	)
	(segment
		(start 299.285406 -380.85522)
		(end 299.285406 -380.15164)
		(width 0.12954)
		(layer "F.Cu")
		(net "P5E_CPU0_P0_TX_DP<2>")
	)
	(segment
		(start 346.580968 -281.864816)
		(end 346.581222 -281.864816)
		(width 0.1143)
		(layer "In6.Cu")
		(net "P5E_CPU0_P0_TX_DP<2>")
	)
	(segment
		(start 346.219018 -281.37612)
		(end 346.301822 -281.458924)
		(width 0.1143)
		(layer "In6.Cu")
		(net "P5E_CPU0_P0_TX_DP<2>")
	)
	(segment
		(start 362.54309 -325.930768)
		(end 364.819946 -330.285598)
		(width 0.14224)
		(layer "In6.Cu")
		(net "P5E_CPU0_P0_TX_DP<2>")
	)
	(segment
		(start 347.011752 -292.372288)
		(end 347.048074 -292.39337)
		(width 0.1143)
		(layer "In6.Cu")
		(net "P5E_CPU0_P0_TX_DP<2>")
	)
	(segment
		(start 347.060012 -283.311854)
		(end 347.016832 -283.336746)
		(width 0.1143)
		(layer "In6.Cu")
		(net "P5E_CPU0_P0_TX_DP<2>")
	)
	(segment
		(start 347.048836 -284.938216)
		(end 347.048074 -284.938724)
		(width 0.1143)
		(layer "In6.Cu")
		(net "P5E_CPU0_P0_TX_DP<2>")
	)
	(segment
		(start 347.011752 -293.9923)
		(end 347.048074 -294.013382)
		(width 0.1143)
		(layer "In6.Cu")
		(net "P5E_CPU0_P0_TX_DP<2>")
	)
	(segment
		(start 347.081602 -288.158936)
		(end 347.011752 -288.199576)
		(width 0.1143)
		(layer "In6.Cu")
		(net "P5E_CPU0_P0_TX_DP<2>")
	)
	(segment
		(start 301.436278 -372.966234)
		(end 300.39691 -374.005602)
		(width 0.14224)
		(layer "In6.Cu")
		(net "P5E_CPU0_P0_TX_DP<2>")
	)
	(segment
		(start 346.29598 -295.983914)
		(end 346.29598 -296.206926)
		(width 0.1143)
		(layer "In6.Cu")
		(net "P5E_CPU0_P0_TX_DP<2>")
	)
	(segment
		(start 346.539058 -281.840686)
		(end 346.578174 -281.863546)
		(width 0.1143)
		(layer "In6.Cu")
		(net "P5E_CPU0_P0_TX_DP<2>")
	)
	(segment
		(start 364.819946 -330.285598)
		(end 366.906048 -341.889842)
		(width 0.14224)
		(layer "In6.Cu")
		(net "P5E_CPU0_P0_TX_DP<2>")
	)
	(segment
		(start 346.29598 -296.206926)
		(end 346.25026 -296.252646)
		(width 0.1143)
		(layer "In6.Cu")
		(net "P5E_CPU0_P0_TX_DP<2>")
	)
	(segment
		(start 346.718636 -295.415716)
		(end 346.399104 -295.735248)
		(width 0.1143)
		(layer "In6.Cu")
		(net "P5E_CPU0_P0_TX_DP<2>")
	)
	(segment
		(start 346.577158 -285.749238)
		(end 346.539058 -285.77159)
		(width 0.1143)
		(layer "In6.Cu")
		(net "P5E_CPU0_P0_TX_DP<2>")
	)
	(segment
		(start 347.048074 -284.938724)
		(end 347.04655 -284.939486)
		(width 0.1143)
		(layer "In6.Cu")
		(net "P5E_CPU0_P0_TX_DP<2>")
	)
	(segment
		(start 361.432348 -362.509308)
		(end 357.973122 -365.968534)
		(width 0.14224)
		(layer "In6.Cu")
		(net "P5E_CPU0_P0_TX_DP<2>")
	)
	(segment
		(start 347.011752 -289.132264)
		(end 347.048074 -289.153346)
		(width 0.1143)
		(layer "In6.Cu")
		(net "P5E_CPU0_P0_TX_DP<2>")
	)
	(segment
		(start 346.578174 -281.863546)
		(end 346.578936 -281.864054)
		(width 0.1143)
		(layer "In6.Cu")
		(net "P5E_CPU0_P0_TX_DP<2>")
	)
	(segment
		(start 366.906048 -341.889842)
		(end 366.906048 -349.29445)
		(width 0.14224)
		(layer "In6.Cu")
		(net "P5E_CPU0_P0_TX_DP<2>")
	)
	(segment
		(start 347.03766 -282.66771)
		(end 347.082618 -282.695904)
		(width 0.1143)
		(layer "In6.Cu")
		(net "P5E_CPU0_P0_TX_DP<2>")
	)
	(segment
		(start 346.608908 -285.73095)
		(end 346.578936 -285.748222)
		(width 0.1143)
		(layer "In6.Cu")
		(net "P5E_CPU0_P0_TX_DP<2>")
	)
	(segment
		(start 346.76588 -287.045908)
		(end 346.76588 -287.053528)
		(width 0.1143)
		(layer "In6.Cu")
		(net "P5E_CPU0_P0_TX_DP<2>")
	)
	(segment
		(start 346.25026 -296.252646)
		(end 346.25026 -296.281094)
		(width 0.1143)
		(layer "In6.Cu")
		(net "P5E_CPU0_P0_TX_DP<2>")
	)
	(segment
		(start 346.578174 -285.74873)
		(end 346.577158 -285.749238)
		(width 0.1143)
		(layer "In6.Cu")
		(net "P5E_CPU0_P0_TX_DP<2>")
	)
	(segment
		(start 318.593216 -367.272062)
		(end 309.7784 -370.924582)
		(width 0.14224)
		(layer "In6.Cu")
		(net "P5E_CPU0_P0_TX_DP<2>")
	)
	(segment
		(start 347.079824 -291.40023)
		(end 347.048074 -291.418518)
		(width 0.1143)
		(layer "In6.Cu")
		(net "P5E_CPU0_P0_TX_DP<2>")
	)
	(segment
		(start 346.539058 -286.700722)
		(end 346.541852 -286.702246)
		(width 0.1143)
		(layer "In6.Cu")
		(net "P5E_CPU0_P0_TX_DP<2>")
	)
	(segment
		(start 347.008704 -287.510728)
		(end 347.079824 -287.551876)
		(width 0.1143)
		(layer "In6.Cu")
		(net "P5E_CPU0_P0_TX_DP<2>")
	)
	(segment
		(start 347.048074 -290.773358)
		(end 347.079824 -290.791646)
		(width 0.1143)
		(layer "In6.Cu")
		(net "P5E_CPU0_P0_TX_DP<2>")
	)
	(segment
		(start 347.048074 -291.418518)
		(end 347.011752 -291.4396)
		(width 0.1143)
		(layer "In6.Cu")
		(net "P5E_CPU0_P0_TX_DP<2>")
	)
	(segment
		(start 346.547948 -286.705548)
		(end 346.607892 -286.7406)
		(width 0.1143)
		(layer "In6.Cu")
		(net "P5E_CPU0_P0_TX_DP<2>")
	)
	(segment
		(start 347.048074 -284.293564)
		(end 347.079824 -284.311852)
		(width 0.1143)
		(layer "In6.Cu")
		(net "P5E_CPU0_P0_TX_DP<2>")
	)
	(segment
		(start 345.921076 -281.37612)
		(end 346.219018 -281.37612)
		(width 0.1143)
		(layer "In6.Cu")
		(net "P5E_CPU0_P0_TX_DP<2>")
	)
	(segment
		(start 347.079824 -294.640254)
		(end 347.048074 -294.658542)
		(width 0.1143)
		(layer "In6.Cu")
		(net "P5E_CPU0_P0_TX_DP<2>")
	)
	(segment
		(start 346.76588 -295.145968)
		(end 346.76588 -295.30167)
		(width 0.1143)
		(layer "In6.Cu")
		(net "P5E_CPU0_P0_TX_DP<2>")
	)
	(segment
		(start 347.079824 -289.780218)
		(end 347.048074 -289.798506)
		(width 0.1143)
		(layer "In6.Cu")
		(net "P5E_CPU0_P0_TX_DP<2>")
	)
	(segment
		(start 346.25026 -296.281094)
		(end 346.25026 -299.343826)
		(width 0.14224)
		(layer "In6.Cu")
		(net "P5E_CPU0_P0_TX_DP<2>")
	)
	(segment
		(start 347.011752 -290.752276)
		(end 347.048074 -290.773358)
		(width 0.1143)
		(layer "In6.Cu")
		(net "P5E_CPU0_P0_TX_DP<2>")
	)
	(segment
		(start 347.079824 -284.920436)
		(end 347.048836 -284.938216)
		(width 0.1143)
		(layer "In6.Cu")
		(net "P5E_CPU0_P0_TX_DP<2>")
	)
	(segment
		(start 347.048074 -293.03853)
		(end 347.011752 -293.059612)
		(width 0.1143)
		(layer "In6.Cu")
		(net "P5E_CPU0_P0_TX_DP<2>")
	)
	(segment
		(start 347.048074 -294.013382)
		(end 347.079824 -294.03167)
		(width 0.1143)
		(layer "In6.Cu")
		(net "P5E_CPU0_P0_TX_DP<2>")
	)
	(segment
		(start 347.016832 -283.336746)
		(end 347.011752 -283.339794)
		(width 0.1143)
		(layer "In6.Cu")
		(net "P5E_CPU0_P0_TX_DP<2>")
	)
	(segment
		(start 350.302322 -309.12689)
		(end 357.09479 -319.29197)
		(width 0.14224)
		(layer "In6.Cu")
		(net "P5E_CPU0_P0_TX_DP<2>")
	)
	(segment
		(start 346.25026 -299.343826)
		(end 350.302322 -309.12689)
		(width 0.14224)
		(layer "In6.Cu")
		(net "P5E_CPU0_P0_TX_DP<2>")
	)
	(segment
		(start 299.305726 -376.639836)
		(end 299.305726 -379.5903)
		(width 0.14224)
		(layer "In6.Cu")
		(net "P5E_CPU0_P0_TX_DP<2>")
	)
	(segment
		(start 347.079824 -293.020242)
		(end 347.048074 -293.03853)
		(width 0.1143)
		(layer "In6.Cu")
		(net "P5E_CPU0_P0_TX_DP<2>")
	)
	(segment
		(start 299.305726 -379.5903)
		(end 299.014896 -379.88113)
		(width 0.14224)
		(layer "In6.Cu")
		(net "P5E_CPU0_P0_TX_DP<2>")
	)
	(segment
		(start 357.09479 -319.29197)
		(end 362.54309 -325.930768)
		(width 0.14224)
		(layer "In6.Cu")
		(net "P5E_CPU0_P0_TX_DP<2>")
	)
	(segment
		(start 346.578936 -281.8638)
		(end 346.580968 -281.864816)
		(width 0.1143)
		(layer "In6.Cu")
		(net "P5E_CPU0_P0_TX_DP<2>")
	)
	(segment
		(start 347.04655 -284.939486)
		(end 347.011752 -284.959806)
		(width 0.1143)
		(layer "In6.Cu")
		(net "P5E_CPU0_P0_TX_DP<2>")
	)
	(segment
		(start 347.048074 -289.798506)
		(end 347.011752 -289.819588)
		(width 0.1143)
		(layer "In6.Cu")
		(net "P5E_CPU0_P0_TX_DP<2>")
	)
	(segment
		(start 347.048074 -294.658542)
		(end 347.011752 -294.679624)
		(width 0.1143)
		(layer "In6.Cu")
		(net "P5E_CPU0_P0_TX_DP<2>")
	)
	(segment
		(start 308.290468 -371.220492)
		(end 305.6509 -371.220492)
		(width 0.14224)
		(layer "In6.Cu")
		(net "P5E_CPU0_P0_TX_DP<2>")
	)
	(segment
		(start 346.994734 -287.500314)
		(end 347.008704 -287.510728)
		(width 0.1143)
		(layer "In6.Cu")
		(net "P5E_CPU0_P0_TX_DP<2>")
	)
	(segment
		(start 346.578936 -281.864054)
		(end 346.578936 -281.8638)
		(width 0.1143)
		(layer "In6.Cu")
		(net "P5E_CPU0_P0_TX_DP<2>")
	)
	(segment
		(start 346.578936 -285.748222)
		(end 346.578174 -285.74873)
		(width 0.1143)
		(layer "In6.Cu")
		(net "P5E_CPU0_P0_TX_DP<2>")
	)
	(segment
		(start 347.048074 -292.39337)
		(end 347.079824 -292.411658)
		(width 0.1143)
		(layer "In6.Cu")
		(net "P5E_CPU0_P0_TX_DP<2>")
	)
	(segment
		(start 347.079824 -283.300424)
		(end 347.060774 -283.311346)
		(width 0.1143)
		(layer "In6.Cu")
		(net "P5E_CPU0_P0_TX_DP<2>")
	)
	(segment
		(start 356.385622 -366.62614)
		(end 321.841114 -366.62614)
		(width 0.14224)
		(layer "In6.Cu")
		(net "P5E_CPU0_P0_TX_DP<2>")
	)
	(segment
		(start 346.546932 -286.705294)
		(end 346.547948 -286.705548)
		(width 0.1143)
		(layer "In6.Cu")
		(net "P5E_CPU0_P0_TX_DP<2>")
	)
	(segment
		(start 347.048074 -289.153346)
		(end 347.079824 -289.171634)
		(width 0.1143)
		(layer "In6.Cu")
		(net "P5E_CPU0_P0_TX_DP<2>")
	)
	(segment
		(start 346.767658 -282.189174)
		(end 346.767658 -282.199588)
		(width 0.1143)
		(layer "In6.Cu")
		(net "P5E_CPU0_P0_TX_DP<2>")
	)
	(segment
		(start 346.541852 -286.702246)
		(end 346.546932 -286.705294)
		(width 0.1143)
		(layer "In6.Cu")
		(net "P5E_CPU0_P0_TX_DP<2>")
	)
	(segment
		(start 347.011752 -284.272482)
		(end 347.048074 -284.293564)
		(width 0.1143)
		(layer "In6.Cu")
		(net "P5E_CPU0_P0_TX_DP<2>")
	)
	(segment
		(start 347.060774 -283.311346)
		(end 347.060012 -283.311854)
		(width 0.1143)
		(layer "In6.Cu")
		(net "P5E_CPU0_P0_TX_DP<2>")
	)
	(arc
		(start 321.841114 -366.62614)
		(mid 320.185347 -366.789112)
		(end 318.593216 -367.272062)
		(width 0.14224)
		(layer "In6.Cu")
		(net "P5E_CPU0_P0_TX_DP<2>")
	)
	(arc
		(start 346.773754 -285.36265)
		(mid 346.768275 -285.399825)
		(end 346.76588 -285.437326)
		(width 0.1143)
		(layer "In6.Cu")
		(net "P5E_CPU0_P0_TX_DP<2>")
	)
	(arc
		(start 347.079824 -284.311852)
		(mid 347.235752 -284.616144)
		(end 347.079824 -284.920436)
		(width 0.1143)
		(layer "In6.Cu")
		(net "P5E_CPU0_P0_TX_DP<2>")
	)
	(arc
		(start 347.079824 -292.411658)
		(mid 347.235752 -292.71595)
		(end 347.079824 -293.020242)
		(width 0.1143)
		(layer "In6.Cu")
		(net "P5E_CPU0_P0_TX_DP<2>")
	)
	(arc
		(start 346.997528 -291.449506)
		(mid 346.770145 -291.905944)
		(end 346.997528 -292.362382)
		(width 0.1143)
		(layer "In6.Cu")
		(net "P5E_CPU0_P0_TX_DP<2>")
	)
	(arc
		(start 347.011752 -289.819588)
		(mid 347.003574 -289.825231)
		(end 346.995496 -289.831018)
		(width 0.1143)
		(layer "In6.Cu")
		(net "P5E_CPU0_P0_TX_DP<2>")
	)
	(arc
		(start 346.995496 -293.98087)
		(mid 347.003574 -293.986656)
		(end 347.011752 -293.9923)
		(width 0.1143)
		(layer "In6.Cu")
		(net "P5E_CPU0_P0_TX_DP<2>")
	)
	(arc
		(start 346.539058 -285.77159)
		(mid 346.295731 -286.236156)
		(end 346.539058 -286.700722)
		(width 0.1143)
		(layer "In6.Cu")
		(net "P5E_CPU0_P0_TX_DP<2>")
	)
	(arc
		(start 347.079824 -290.791646)
		(mid 347.235752 -291.095938)
		(end 347.079824 -291.40023)
		(width 0.1143)
		(layer "In6.Cu")
		(net "P5E_CPU0_P0_TX_DP<2>")
	)
	(arc
		(start 305.6509 -371.220492)
		(mid 303.369967 -371.674198)
		(end 301.436278 -372.966234)
		(width 0.14224)
		(layer "In6.Cu")
		(net "P5E_CPU0_P0_TX_DP<2>")
	)
	(arc
		(start 300.39691 -374.005602)
		(mid 299.589298 -375.214185)
		(end 299.305726 -376.639836)
		(width 0.14224)
		(layer "In6.Cu")
		(net "P5E_CPU0_P0_TX_DP<2>")
	)
	(arc
		(start 347.011752 -291.4396)
		(mid 347.004603 -291.4445)
		(end 346.997528 -291.449506)
		(width 0.1143)
		(layer "In6.Cu")
		(net "P5E_CPU0_P0_TX_DP<2>")
	)
	(arc
		(start 346.301822 -281.458924)
		(mid 346.30361 -281.470373)
		(end 346.305632 -281.481784)
		(width 0.1143)
		(layer "In6.Cu")
		(net "P5E_CPU0_P0_TX_DP<2>")
	)
	(arc
		(start 346.76588 -288.672524)
		(mid 346.830752 -288.922266)
		(end 346.995496 -289.120834)
		(width 0.1143)
		(layer "In6.Cu")
		(net "P5E_CPU0_P0_TX_DP<2>")
	)
	(arc
		(start 347.011752 -294.679624)
		(mid 347.003574 -294.685267)
		(end 346.995496 -294.691054)
		(width 0.1143)
		(layer "In6.Cu")
		(net "P5E_CPU0_P0_TX_DP<2>")
	)
	(arc
		(start 346.607892 -286.7406)
		(mid 346.723939 -286.874071)
		(end 346.76588 -287.045908)
		(width 0.1143)
		(layer "In6.Cu")
		(net "P5E_CPU0_P0_TX_DP<2>")
	)
	(arc
		(start 346.997528 -292.362382)
		(mid 347.004602 -292.367389)
		(end 347.011752 -292.372288)
		(width 0.1143)
		(layer "In6.Cu")
		(net "P5E_CPU0_P0_TX_DP<2>")
	)
	(arc
		(start 347.079824 -294.03167)
		(mid 347.235752 -294.335962)
		(end 347.079824 -294.640254)
		(width 0.1143)
		(layer "In6.Cu")
		(net "P5E_CPU0_P0_TX_DP<2>")
	)
	(arc
		(start 346.995496 -289.831018)
		(mid 346.772612 -290.285932)
		(end 346.995496 -290.740846)
		(width 0.1143)
		(layer "In6.Cu")
		(net "P5E_CPU0_P0_TX_DP<2>")
	)
	(arc
		(start 346.995496 -283.351224)
		(mid 346.772612 -283.806138)
		(end 346.995496 -284.261052)
		(width 0.1143)
		(layer "In6.Cu")
		(net "P5E_CPU0_P0_TX_DP<2>")
	)
	(arc
		(start 346.980256 -284.984444)
		(mid 346.847838 -285.157625)
		(end 346.773754 -285.36265)
		(width 0.1143)
		(layer "In6.Cu")
		(net "P5E_CPU0_P0_TX_DP<2>")
	)
	(arc
		(start 347.011752 -284.959806)
		(mid 346.995783 -284.971843)
		(end 346.980256 -284.984444)
		(width 0.1143)
		(layer "In6.Cu")
		(net "P5E_CPU0_P0_TX_DP<2>")
	)
	(arc
		(start 346.76588 -285.437326)
		(mid 346.721816 -285.602549)
		(end 346.608908 -285.73095)
		(width 0.1143)
		(layer "In6.Cu")
		(net "P5E_CPU0_P0_TX_DP<2>")
	)
	(arc
		(start 346.995496 -294.691054)
		(mid 346.830829 -294.889661)
		(end 346.76588 -295.139364)
		(width 0.1143)
		(layer "In6.Cu")
		(net "P5E_CPU0_P0_TX_DP<2>")
	)
	(arc
		(start 366.906048 -349.29445)
		(mid 365.483481 -356.446266)
		(end 361.432348 -362.509308)
		(width 0.14224)
		(layer "In6.Cu")
		(net "P5E_CPU0_P0_TX_DP<2>")
	)
	(arc
		(start 346.76588 -287.053528)
		(mid 346.826413 -287.304533)
		(end 346.994734 -287.500314)
		(width 0.1143)
		(layer "In6.Cu")
		(net "P5E_CPU0_P0_TX_DP<2>")
	)
	(arc
		(start 346.995496 -290.740846)
		(mid 347.003574 -290.746632)
		(end 347.011752 -290.752276)
		(width 0.1143)
		(layer "In6.Cu")
		(net "P5E_CPU0_P0_TX_DP<2>")
	)
	(arc
		(start 347.011752 -283.339794)
		(mid 347.003574 -283.345437)
		(end 346.995496 -283.351224)
		(width 0.1143)
		(layer "In6.Cu")
		(net "P5E_CPU0_P0_TX_DP<2>")
	)
	(arc
		(start 347.011752 -288.199576)
		(mid 346.829568 -288.405246)
		(end 346.76588 -288.672524)
		(width 0.1143)
		(layer "In6.Cu")
		(net "P5E_CPU0_P0_TX_DP<2>")
	)
	(arc
		(start 346.995496 -284.261052)
		(mid 347.003574 -284.266838)
		(end 347.011752 -284.272482)
		(width 0.1143)
		(layer "In6.Cu")
		(net "P5E_CPU0_P0_TX_DP<2>")
	)
	(arc
		(start 346.995496 -289.120834)
		(mid 347.003574 -289.12662)
		(end 347.011752 -289.132264)
		(width 0.1143)
		(layer "In6.Cu")
		(net "P5E_CPU0_P0_TX_DP<2>")
	)
	(arc
		(start 346.581222 -281.864816)
		(mid 346.717715 -282.002118)
		(end 346.767658 -282.189174)
		(width 0.1143)
		(layer "In6.Cu")
		(net "P5E_CPU0_P0_TX_DP<2>")
	)
	(arc
		(start 346.399104 -295.735248)
		(mid 346.322843 -295.849336)
		(end 346.29598 -295.983914)
		(width 0.1143)
		(layer "In6.Cu")
		(net "P5E_CPU0_P0_TX_DP<2>")
	)
	(arc
		(start 347.082618 -282.695904)
		(mid 347.162893 -282.774876)
		(end 347.21546 -282.874466)
		(width 0.1143)
		(layer "In6.Cu")
		(net "P5E_CPU0_P0_TX_DP<2>")
	)
	(arc
		(start 347.079824 -289.171634)
		(mid 347.235752 -289.475926)
		(end 347.079824 -289.780218)
		(width 0.1143)
		(layer "In6.Cu")
		(net "P5E_CPU0_P0_TX_DP<2>")
	)
	(arc
		(start 309.7784 -370.924582)
		(mid 309.049011 -371.145842)
		(end 308.290468 -371.220492)
		(width 0.14224)
		(layer "In6.Cu")
		(net "P5E_CPU0_P0_TX_DP<2>")
	)
	(arc
		(start 347.236034 -287.856168)
		(mid 347.195134 -288.026069)
		(end 347.081602 -288.158936)
		(width 0.1143)
		(layer "In6.Cu")
		(net "P5E_CPU0_P0_TX_DP<2>")
	)
	(arc
		(start 347.079824 -287.551876)
		(mid 347.194667 -287.685166)
		(end 347.236034 -287.856168)
		(width 0.1143)
		(layer "In6.Cu")
		(net "P5E_CPU0_P0_TX_DP<2>")
	)
	(arc
		(start 346.76588 -295.139364)
		(mid 346.76587 -295.142666)
		(end 346.76588 -295.145968)
		(width 0.1143)
		(layer "In6.Cu")
		(net "P5E_CPU0_P0_TX_DP<2>")
	)
	(arc
		(start 346.767658 -282.199588)
		(mid 346.84 -282.469786)
		(end 347.03766 -282.66771)
		(width 0.1143)
		(layer "In6.Cu")
		(net "P5E_CPU0_P0_TX_DP<2>")
	)
	(arc
		(start 346.305632 -281.481784)
		(mid 346.387065 -281.684182)
		(end 346.539058 -281.840686)
		(width 0.1143)
		(layer "In6.Cu")
		(net "P5E_CPU0_P0_TX_DP<2>")
	)
	(arc
		(start 346.76588 -295.30167)
		(mid 346.753618 -295.363407)
		(end 346.718636 -295.415716)
		(width 0.1143)
		(layer "In6.Cu")
		(net "P5E_CPU0_P0_TX_DP<2>")
	)
	(arc
		(start 357.973122 -365.968534)
		(mid 357.244785 -366.455256)
		(end 356.385622 -366.62614)
		(width 0.14224)
		(layer "In6.Cu")
		(net "P5E_CPU0_P0_TX_DP<2>")
	)
	(arc
		(start 346.995496 -293.071042)
		(mid 346.772612 -293.525956)
		(end 346.995496 -293.98087)
		(width 0.1143)
		(layer "In6.Cu")
		(net "P5E_CPU0_P0_TX_DP<2>")
	)
	(arc
		(start 347.21546 -282.874466)
		(mid 347.218081 -283.109875)
		(end 347.079824 -283.300424)
		(width 0.1143)
		(layer "In6.Cu")
		(net "P5E_CPU0_P0_TX_DP<2>")
	)
	(arc
		(start 347.011752 -293.059612)
		(mid 347.003574 -293.065255)
		(end 346.995496 -293.071042)
		(width 0.1143)
		(layer "In6.Cu")
		(net "P5E_CPU0_P0_TX_DP<2>")
	)
	(segment
		(start 297.700954 -384.62077)
		(end 298.404534 -384.62077)
		(width 0.12954)
		(layer "F.Cu")
		(net "P5E_CPU0_P0_TX_DP<1>")
	)
	(segment
		(start 297.430444 -384.35026)
		(end 297.700954 -384.62077)
		(width 0.12954)
		(layer "F.Cu")
		(net "P5E_CPU0_P0_TX_DP<1>")
	)
	(segment
		(start 298.404534 -384.62077)
		(end 298.700444 -384.32486)
		(width 0.12954)
		(layer "F.Cu")
		(net "P5E_CPU0_P0_TX_DP<1>")
	)
	(segment
		(start 346.387928 -284.350206)
		(end 345.921076 -284.616144)
		(width 0.12954)
		(layer "F.Cu")
		(net "P5E_CPU0_P0_TX_DP<1>")
	)
	(segment
		(start 298.532296 -384.500882)
		(end 298.432728 -384.60045)
		(width 0.14224)
		(layer "In6.Cu")
		(net "P5E_CPU0_P0_TX_DP<1>")
	)
	(segment
		(start 297.504866 -378.169678)
		(end 297.504866 -378.596398)
		(width 0.14224)
		(layer "In6.Cu")
		(net "P5E_CPU0_P0_TX_DP<1>")
	)
	(segment
		(start 297.367706 -379.861318)
		(end 297.367706 -380.288038)
		(width 0.14224)
		(layer "In6.Cu")
		(net "P5E_CPU0_P0_TX_DP<1>")
	)
	(segment
		(start 297.367706 -379.160278)
		(end 297.504866 -379.297438)
		(width 0.14224)
		(layer "In6.Cu")
		(net "P5E_CPU0_P0_TX_DP<1>")
	)
	(segment
		(start 297.367706 -377.605798)
		(end 297.367706 -378.032518)
		(width 0.14224)
		(layer "In6.Cu")
		(net "P5E_CPU0_P0_TX_DP<1>")
	)
	(segment
		(start 346.219018 -284.616144)
		(end 346.288868 -284.685994)
		(width 0.1143)
		(layer "In6.Cu")
		(net "P5E_CPU0_P0_TX_DP<1>")
	)
	(segment
		(start 361.799632 -326.521064)
		(end 363.915452 -330.568046)
		(width 0.14224)
		(layer "In6.Cu")
		(net "P5E_CPU0_P0_TX_DP<1>")
	)
	(segment
		(start 346.138754 -293.02075)
		(end 346.108274 -293.03853)
		(width 0.1143)
		(layer "In6.Cu")
		(net "P5E_CPU0_P0_TX_DP<1>")
	)
	(segment
		(start 346.140786 -288.159698)
		(end 346.108274 -288.178494)
		(width 0.1143)
		(layer "In6.Cu")
		(net "P5E_CPU0_P0_TX_DP<1>")
	)
	(segment
		(start 345.745054 -295.42232)
		(end 345.45905 -295.708324)
		(width 0.1143)
		(layer "In6.Cu")
		(net "P5E_CPU0_P0_TX_DP<1>")
	)
	(segment
		(start 364.67161 -334.773778)
		(end 365.947706 -341.872316)
		(width 0.14224)
		(layer "In6.Cu")
		(net "P5E_CPU0_P0_TX_DP<1>")
	)
	(segment
		(start 297.504866 -378.596398)
		(end 297.367706 -378.733558)
		(width 0.14224)
		(layer "In6.Cu")
		(net "P5E_CPU0_P0_TX_DP<1>")
	)
	(segment
		(start 298.569634 -383.79273)
		(end 298.569634 -384.410966)
		(width 0.14224)
		(layer "In6.Cu")
		(net "P5E_CPU0_P0_TX_DP<1>")
	)
	(segment
		(start 345.638882 -285.748222)
		(end 345.63812 -285.74873)
		(width 0.1143)
		(layer "In6.Cu")
		(net "P5E_CPU0_P0_TX_DP<1>")
	)
	(segment
		(start 345.612212 -285.763716)
		(end 345.599004 -285.77159)
		(width 0.1143)
		(layer "In6.Cu")
		(net "P5E_CPU0_P0_TX_DP<1>")
	)
	(segment
		(start 346.108274 -294.013382)
		(end 346.138754 -294.031162)
		(width 0.1143)
		(layer "In6.Cu")
		(net "P5E_CPU0_P0_TX_DP<1>")
	)
	(segment
		(start 345.625166 -285.756096)
		(end 345.624404 -285.756604)
		(width 0.1143)
		(layer "In6.Cu")
		(net "P5E_CPU0_P0_TX_DP<1>")
	)
	(segment
		(start 298.569634 -383.09169)
		(end 298.432474 -383.22885)
		(width 0.14224)
		(layer "In6.Cu")
		(net "P5E_CPU0_P0_TX_DP<1>")
	)
	(segment
		(start 345.634564 -285.750762)
		(end 345.633294 -285.751524)
		(width 0.1143)
		(layer "In6.Cu")
		(net "P5E_CPU0_P0_TX_DP<1>")
	)
	(segment
		(start 297.504866 -379.724158)
		(end 297.367706 -379.861318)
		(width 0.14224)
		(layer "In6.Cu")
		(net "P5E_CPU0_P0_TX_DP<1>")
	)
	(segment
		(start 297.504866 -379.297438)
		(end 297.504866 -379.724158)
		(width 0.14224)
		(layer "In6.Cu")
		(net "P5E_CPU0_P0_TX_DP<1>")
	)
	(segment
		(start 345.619324 -285.759652)
		(end 345.617038 -285.760922)
		(width 0.1143)
		(layer "In6.Cu")
		(net "P5E_CPU0_P0_TX_DP<1>")
	)
	(segment
		(start 346.069158 -293.990522)
		(end 346.108274 -294.013382)
		(width 0.1143)
		(layer "In6.Cu")
		(net "P5E_CPU0_P0_TX_DP<1>")
	)
	(segment
		(start 346.069158 -292.37051)
		(end 346.108274 -292.39337)
		(width 0.1143)
		(layer "In6.Cu")
		(net "P5E_CPU0_P0_TX_DP<1>")
	)
	(segment
		(start 345.626436 -285.755334)
		(end 345.625166 -285.756096)
		(width 0.1143)
		(layer "In6.Cu")
		(net "P5E_CPU0_P0_TX_DP<1>")
	)
	(segment
		(start 345.310206 -299.510704)
		(end 349.500698 -309.627778)
		(width 0.14224)
		(layer "In6.Cu")
		(net "P5E_CPU0_P0_TX_DP<1>")
	)
	(segment
		(start 365.947706 -341.872316)
		(end 365.947706 -349.276416)
		(width 0.14224)
		(layer "In6.Cu")
		(net "P5E_CPU0_P0_TX_DP<1>")
	)
	(segment
		(start 356.356158 -319.887854)
		(end 361.799632 -326.521064)
		(width 0.14224)
		(layer "In6.Cu")
		(net "P5E_CPU0_P0_TX_DP<1>")
	)
	(segment
		(start 297.744896 -381.714756)
		(end 298.532296 -382.502156)
		(width 0.14224)
		(layer "In6.Cu")
		(net "P5E_CPU0_P0_TX_DP<1>")
	)
	(segment
		(start 345.633294 -285.751524)
		(end 345.632278 -285.752032)
		(width 0.1143)
		(layer "In6.Cu")
		(net "P5E_CPU0_P0_TX_DP<1>")
	)
	(segment
		(start 297.367706 -378.733558)
		(end 297.367706 -379.160278)
		(width 0.14224)
		(layer "In6.Cu")
		(net "P5E_CPU0_P0_TX_DP<1>")
	)
	(segment
		(start 345.310206 -296.252646)
		(end 345.310206 -296.281094)
		(width 0.1143)
		(layer "In6.Cu")
		(net "P5E_CPU0_P0_TX_DP<1>")
	)
	(segment
		(start 297.504866 -377.468638)
		(end 297.367706 -377.605798)
		(width 0.14224)
		(layer "In6.Cu")
		(net "P5E_CPU0_P0_TX_DP<1>")
	)
	(segment
		(start 345.613736 -285.762954)
		(end 345.612212 -285.763716)
		(width 0.1143)
		(layer "In6.Cu")
		(net "P5E_CPU0_P0_TX_DP<1>")
	)
	(segment
		(start 298.432474 -383.22885)
		(end 298.432474 -383.65557)
		(width 0.14224)
		(layer "In6.Cu")
		(net "P5E_CPU0_P0_TX_DP<1>")
	)
	(segment
		(start 345.620086 -285.759144)
		(end 345.619324 -285.759652)
		(width 0.1143)
		(layer "In6.Cu")
		(net "P5E_CPU0_P0_TX_DP<1>")
	)
	(segment
		(start 346.138754 -291.400738)
		(end 346.108274 -291.418518)
		(width 0.1143)
		(layer "In6.Cu")
		(net "P5E_CPU0_P0_TX_DP<1>")
	)
	(segment
		(start 346.108274 -290.773358)
		(end 346.138754 -290.791138)
		(width 0.1143)
		(layer "In6.Cu")
		(net "P5E_CPU0_P0_TX_DP<1>")
	)
	(segment
		(start 345.355926 -295.95699)
		(end 345.355926 -296.206926)
		(width 0.1143)
		(layer "In6.Cu")
		(net "P5E_CPU0_P0_TX_DP<1>")
	)
	(segment
		(start 346.108274 -288.178494)
		(end 346.069158 -288.201354)
		(width 0.1143)
		(layer "In6.Cu")
		(net "P5E_CPU0_P0_TX_DP<1>")
	)
	(segment
		(start 297.504866 -377.041918)
		(end 297.504866 -377.468638)
		(width 0.14224)
		(layer "In6.Cu")
		(net "P5E_CPU0_P0_TX_DP<1>")
	)
	(segment
		(start 346.108274 -289.153346)
		(end 346.138754 -289.171126)
		(width 0.1143)
		(layer "In6.Cu")
		(net "P5E_CPU0_P0_TX_DP<1>")
	)
	(segment
		(start 346.071698 -287.512252)
		(end 346.138754 -287.551368)
		(width 0.1143)
		(layer "In6.Cu")
		(net "P5E_CPU0_P0_TX_DP<1>")
	)
	(segment
		(start 345.825826 -295.145968)
		(end 345.825826 -295.174924)
		(width 0.1143)
		(layer "In6.Cu")
		(net "P5E_CPU0_P0_TX_DP<1>")
	)
	(segment
		(start 345.6305 -285.753048)
		(end 345.628976 -285.754064)
		(width 0.1143)
		(layer "In6.Cu")
		(net "P5E_CPU0_P0_TX_DP<1>")
	)
	(segment
		(start 297.504866 -380.425198)
		(end 297.504866 -381.135636)
		(width 0.14224)
		(layer "In6.Cu")
		(net "P5E_CPU0_P0_TX_DP<1>")
	)
	(segment
		(start 356.280466 -365.691166)
		(end 321.838828 -365.691166)
		(width 0.14224)
		(layer "In6.Cu")
		(net "P5E_CPU0_P0_TX_DP<1>")
	)
	(segment
		(start 307.697886 -370.283486)
		(end 304.677318 -370.283486)
		(width 0.14224)
		(layer "In6.Cu")
		(net "P5E_CPU0_P0_TX_DP<1>")
	)
	(segment
		(start 345.921076 -284.616144)
		(end 346.219018 -284.616144)
		(width 0.1143)
		(layer "In6.Cu")
		(net "P5E_CPU0_P0_TX_DP<1>")
	)
	(segment
		(start 346.138754 -289.780726)
		(end 346.108274 -289.798506)
		(width 0.1143)
		(layer "In6.Cu")
		(net "P5E_CPU0_P0_TX_DP<1>")
	)
	(segment
		(start 297.367706 -380.288038)
		(end 297.504866 -380.425198)
		(width 0.14224)
		(layer "In6.Cu")
		(net "P5E_CPU0_P0_TX_DP<1>")
	)
	(segment
		(start 298.432474 -383.65557)
		(end 298.569634 -383.79273)
		(width 0.14224)
		(layer "In6.Cu")
		(net "P5E_CPU0_P0_TX_DP<1>")
	)
	(segment
		(start 345.628976 -285.754064)
		(end 345.626436 -285.755334)
		(width 0.1143)
		(layer "In6.Cu")
		(net "P5E_CPU0_P0_TX_DP<1>")
	)
	(segment
		(start 298.342812 -384.637788)
		(end 297.717972 -384.637788)
		(width 0.14224)
		(layer "In6.Cu")
		(net "P5E_CPU0_P0_TX_DP<1>")
	)
	(segment
		(start 363.915452 -330.568046)
		(end 364.67161 -334.77327)
		(width 0.14224)
		(layer "In6.Cu")
		(net "P5E_CPU0_P0_TX_DP<1>")
	)
	(segment
		(start 345.355926 -296.206926)
		(end 345.310206 -296.252646)
		(width 0.1143)
		(layer "In6.Cu")
		(net "P5E_CPU0_P0_TX_DP<1>")
	)
	(segment
		(start 346.069158 -290.750498)
		(end 346.108274 -290.773358)
		(width 0.1143)
		(layer "In6.Cu")
		(net "P5E_CPU0_P0_TX_DP<1>")
	)
	(segment
		(start 298.569634 -382.592072)
		(end 298.569634 -383.09169)
		(width 0.14224)
		(layer "In6.Cu")
		(net "P5E_CPU0_P0_TX_DP<1>")
	)
	(segment
		(start 349.500698 -309.627778)
		(end 356.356158 -319.887854)
		(width 0.14224)
		(layer "In6.Cu")
		(net "P5E_CPU0_P0_TX_DP<1>")
	)
	(segment
		(start 345.63812 -285.74873)
		(end 345.637104 -285.749238)
		(width 0.1143)
		(layer "In6.Cu")
		(net "P5E_CPU0_P0_TX_DP<1>")
	)
	(segment
		(start 346.108274 -292.39337)
		(end 346.138754 -292.41115)
		(width 0.1143)
		(layer "In6.Cu")
		(net "P5E_CPU0_P0_TX_DP<1>")
	)
	(segment
		(start 345.617038 -285.760922)
		(end 345.613736 -285.762954)
		(width 0.1143)
		(layer "In6.Cu")
		(net "P5E_CPU0_P0_TX_DP<1>")
	)
	(segment
		(start 346.138754 -294.640762)
		(end 346.069158 -294.681402)
		(width 0.1143)
		(layer "In6.Cu")
		(net "P5E_CPU0_P0_TX_DP<1>")
	)
	(segment
		(start 345.66987 -285.730442)
		(end 345.638882 -285.748222)
		(width 0.1143)
		(layer "In6.Cu")
		(net "P5E_CPU0_P0_TX_DP<1>")
	)
	(segment
		(start 345.637104 -285.749238)
		(end 345.63558 -285.750254)
		(width 0.1143)
		(layer "In6.Cu")
		(net "P5E_CPU0_P0_TX_DP<1>")
	)
	(segment
		(start 297.367706 -378.032518)
		(end 297.504866 -378.169678)
		(width 0.14224)
		(layer "In6.Cu")
		(net "P5E_CPU0_P0_TX_DP<1>")
	)
	(segment
		(start 345.599004 -286.700722)
		(end 345.63812 -286.723582)
		(width 0.1143)
		(layer "In6.Cu")
		(net "P5E_CPU0_P0_TX_DP<1>")
	)
	(segment
		(start 346.069158 -289.130486)
		(end 346.108274 -289.153346)
		(width 0.1143)
		(layer "In6.Cu")
		(net "P5E_CPU0_P0_TX_DP<1>")
	)
	(segment
		(start 345.624404 -285.756604)
		(end 345.620086 -285.759144)
		(width 0.1143)
		(layer "In6.Cu")
		(net "P5E_CPU0_P0_TX_DP<1>")
	)
	(segment
		(start 297.717972 -384.637788)
		(end 297.430444 -384.35026)
		(width 0.14224)
		(layer "In6.Cu")
		(net "P5E_CPU0_P0_TX_DP<1>")
	)
	(segment
		(start 346.138754 -284.920944)
		(end 346.069158 -284.961584)
		(width 0.1143)
		(layer "In6.Cu")
		(net "P5E_CPU0_P0_TX_DP<1>")
	)
	(segment
		(start 301.387256 -371.646196)
		(end 298.574968 -374.458484)
		(width 0.14224)
		(layer "In6.Cu")
		(net "P5E_CPU0_P0_TX_DP<1>")
	)
	(segment
		(start 360.717084 -361.904026)
		(end 357.389176 -365.231934)
		(width 0.14224)
		(layer "In6.Cu")
		(net "P5E_CPU0_P0_TX_DP<1>")
	)
	(segment
		(start 345.63812 -286.723582)
		(end 345.671648 -286.74314)
		(width 0.1143)
		(layer "In6.Cu")
		(net "P5E_CPU0_P0_TX_DP<1>")
	)
	(segment
		(start 318.213232 -366.412018)
		(end 309.945278 -369.836446)
		(width 0.14224)
		(layer "In6.Cu")
		(net "P5E_CPU0_P0_TX_DP<1>")
	)
	(segment
		(start 346.108274 -291.418518)
		(end 346.069158 -291.441378)
		(width 0.1143)
		(layer "In6.Cu")
		(net "P5E_CPU0_P0_TX_DP<1>")
	)
	(segment
		(start 346.108274 -293.03853)
		(end 346.069158 -293.06139)
		(width 0.1143)
		(layer "In6.Cu")
		(net "P5E_CPU0_P0_TX_DP<1>")
	)
	(segment
		(start 346.108274 -289.798506)
		(end 346.069158 -289.821366)
		(width 0.1143)
		(layer "In6.Cu")
		(net "P5E_CPU0_P0_TX_DP<1>")
	)
	(segment
		(start 364.67161 -334.77327)
		(end 364.67161 -334.773778)
		(width 0.14224)
		(layer "In6.Cu")
		(net "P5E_CPU0_P0_TX_DP<1>")
	)
	(segment
		(start 345.632278 -285.752032)
		(end 345.6305 -285.753048)
		(width 0.1143)
		(layer "In6.Cu")
		(net "P5E_CPU0_P0_TX_DP<1>")
	)
	(segment
		(start 345.63558 -285.750254)
		(end 345.634564 -285.750762)
		(width 0.1143)
		(layer "In6.Cu")
		(net "P5E_CPU0_P0_TX_DP<1>")
	)
	(segment
		(start 345.310206 -296.281094)
		(end 345.310206 -299.510704)
		(width 0.14224)
		(layer "In6.Cu")
		(net "P5E_CPU0_P0_TX_DP<1>")
	)
	(arc
		(start 346.138754 -294.031162)
		(mid 346.295731 -294.335962)
		(end 346.138754 -294.640762)
		(width 0.1143)
		(layer "In6.Cu")
		(net "P5E_CPU0_P0_TX_DP<1>")
	)
	(arc
		(start 345.825826 -287.045908)
		(mid 345.891062 -287.309499)
		(end 346.071698 -287.512252)
		(width 0.1143)
		(layer "In6.Cu")
		(net "P5E_CPU0_P0_TX_DP<1>")
	)
	(arc
		(start 309.945278 -369.836446)
		(mid 308.843593 -370.170608)
		(end 307.697886 -370.283486)
		(width 0.14224)
		(layer "In6.Cu")
		(net "P5E_CPU0_P0_TX_DP<1>")
	)
	(arc
		(start 345.671648 -286.74314)
		(mid 345.785055 -286.876029)
		(end 345.825826 -287.045908)
		(width 0.1143)
		(layer "In6.Cu")
		(net "P5E_CPU0_P0_TX_DP<1>")
	)
	(arc
		(start 346.288868 -284.685994)
		(mid 346.236451 -284.817925)
		(end 346.138754 -284.920944)
		(width 0.1143)
		(layer "In6.Cu")
		(net "P5E_CPU0_P0_TX_DP<1>")
	)
	(arc
		(start 365.947706 -349.276416)
		(mid 364.588314 -356.110451)
		(end 360.717084 -361.904026)
		(width 0.14224)
		(layer "In6.Cu")
		(net "P5E_CPU0_P0_TX_DP<1>")
	)
	(arc
		(start 345.808046 -295.312338)
		(mid 345.783905 -295.371546)
		(end 345.745054 -295.42232)
		(width 0.1143)
		(layer "In6.Cu")
		(net "P5E_CPU0_P0_TX_DP<1>")
	)
	(arc
		(start 346.138754 -290.791138)
		(mid 346.295731 -291.095938)
		(end 346.138754 -291.400738)
		(width 0.1143)
		(layer "In6.Cu")
		(net "P5E_CPU0_P0_TX_DP<1>")
	)
	(arc
		(start 345.825826 -285.42615)
		(mid 345.784571 -285.597121)
		(end 345.66987 -285.730442)
		(width 0.1143)
		(layer "In6.Cu")
		(net "P5E_CPU0_P0_TX_DP<1>")
	)
	(arc
		(start 345.599004 -285.77159)
		(mid 345.355677 -286.236156)
		(end 345.599004 -286.700722)
		(width 0.1143)
		(layer "In6.Cu")
		(net "P5E_CPU0_P0_TX_DP<1>")
	)
	(arc
		(start 346.069158 -288.201354)
		(mid 345.825831 -288.66592)
		(end 346.069158 -289.130486)
		(width 0.1143)
		(layer "In6.Cu")
		(net "P5E_CPU0_P0_TX_DP<1>")
	)
	(arc
		(start 346.069158 -291.441378)
		(mid 345.825831 -291.905944)
		(end 346.069158 -292.37051)
		(width 0.1143)
		(layer "In6.Cu")
		(net "P5E_CPU0_P0_TX_DP<1>")
	)
	(arc
		(start 346.138754 -287.551368)
		(mid 346.254181 -287.684744)
		(end 346.295726 -287.856168)
		(width 0.1143)
		(layer "In6.Cu")
		(net "P5E_CPU0_P0_TX_DP<1>")
	)
	(arc
		(start 345.825826 -295.174924)
		(mid 345.821326 -295.244198)
		(end 345.808046 -295.312338)
		(width 0.1143)
		(layer "In6.Cu")
		(net "P5E_CPU0_P0_TX_DP<1>")
	)
	(arc
		(start 357.389176 -365.231934)
		(mid 356.880496 -365.571823)
		(end 356.280466 -365.691166)
		(width 0.14224)
		(layer "In6.Cu")
		(net "P5E_CPU0_P0_TX_DP<1>")
	)
	(arc
		(start 298.532296 -382.502156)
		(mid 298.559915 -382.543396)
		(end 298.569634 -382.592072)
		(width 0.14224)
		(layer "In6.Cu")
		(net "P5E_CPU0_P0_TX_DP<1>")
	)
	(arc
		(start 346.069158 -293.06139)
		(mid 345.825831 -293.525956)
		(end 346.069158 -293.990522)
		(width 0.1143)
		(layer "In6.Cu")
		(net "P5E_CPU0_P0_TX_DP<1>")
	)
	(arc
		(start 321.838828 -365.691166)
		(mid 319.990529 -365.873044)
		(end 318.213232 -366.412018)
		(width 0.14224)
		(layer "In6.Cu")
		(net "P5E_CPU0_P0_TX_DP<1>")
	)
	(arc
		(start 298.432728 -384.60045)
		(mid 298.391488 -384.628069)
		(end 298.342812 -384.637788)
		(width 0.14224)
		(layer "In6.Cu")
		(net "P5E_CPU0_P0_TX_DP<1>")
	)
	(arc
		(start 298.569634 -384.410966)
		(mid 298.559932 -384.45965)
		(end 298.532296 -384.500882)
		(width 0.14224)
		(layer "In6.Cu")
		(net "P5E_CPU0_P0_TX_DP<1>")
	)
	(arc
		(start 298.574968 -374.458484)
		(mid 297.782983 -375.643774)
		(end 297.504866 -377.041918)
		(width 0.14224)
		(layer "In6.Cu")
		(net "P5E_CPU0_P0_TX_DP<1>")
	)
	(arc
		(start 346.069158 -284.961584)
		(mid 345.890345 -285.163934)
		(end 345.825826 -285.42615)
		(width 0.1143)
		(layer "In6.Cu")
		(net "P5E_CPU0_P0_TX_DP<1>")
	)
	(arc
		(start 346.138754 -292.41115)
		(mid 346.295731 -292.71595)
		(end 346.138754 -293.02075)
		(width 0.1143)
		(layer "In6.Cu")
		(net "P5E_CPU0_P0_TX_DP<1>")
	)
	(arc
		(start 345.45905 -295.708324)
		(mid 345.382789 -295.822412)
		(end 345.355926 -295.95699)
		(width 0.1143)
		(layer "In6.Cu")
		(net "P5E_CPU0_P0_TX_DP<1>")
	)
	(arc
		(start 346.069158 -294.681402)
		(mid 345.890345 -294.883752)
		(end 345.825826 -295.145968)
		(width 0.1143)
		(layer "In6.Cu")
		(net "P5E_CPU0_P0_TX_DP<1>")
	)
	(arc
		(start 346.295726 -287.856168)
		(mid 346.25476 -288.026574)
		(end 346.140786 -288.159698)
		(width 0.1143)
		(layer "In6.Cu")
		(net "P5E_CPU0_P0_TX_DP<1>")
	)
	(arc
		(start 346.069158 -289.821366)
		(mid 345.825831 -290.285932)
		(end 346.069158 -290.750498)
		(width 0.1143)
		(layer "In6.Cu")
		(net "P5E_CPU0_P0_TX_DP<1>")
	)
	(arc
		(start 297.504866 -381.135636)
		(mid 297.567303 -381.449057)
		(end 297.744896 -381.714756)
		(width 0.14224)
		(layer "In6.Cu")
		(net "P5E_CPU0_P0_TX_DP<1>")
	)
	(arc
		(start 304.677318 -370.283486)
		(mid 302.896765 -370.637642)
		(end 301.387256 -371.646196)
		(width 0.14224)
		(layer "In6.Cu")
		(net "P5E_CPU0_P0_TX_DP<1>")
	)
	(arc
		(start 346.138754 -289.171126)
		(mid 346.295731 -289.475926)
		(end 346.138754 -289.780726)
		(width 0.1143)
		(layer "In6.Cu")
		(net "P5E_CPU0_P0_TX_DP<1>")
	)
	(segment
		(start 357.197914 -281.920188)
		(end 356.731062 -282.186126)
		(width 0.12954)
		(layer "F.Cu")
		(net "P5E_CPU0_P0_TX_DP<15>")
	)
	(segment
		(start 326.303386 -388.149338)
		(end 327.006966 -388.149338)
		(width 0.12954)
		(layer "F.Cu")
		(net "P5E_CPU0_P0_TX_DP<15>")
	)
	(segment
		(start 327.006966 -388.149338)
		(end 327.277476 -387.878828)
		(width 0.12954)
		(layer "F.Cu")
		(net "P5E_CPU0_P0_TX_DP<15>")
	)
	(segment
		(start 326.007476 -387.853428)
		(end 326.303386 -388.149338)
		(width 0.12954)
		(layer "F.Cu")
		(net "P5E_CPU0_P0_TX_DP<15>")
	)
	(segment
		(start 363.670596 -381.244094)
		(end 363.552486 -381.56642)
		(width 0.14224)
		(layer "In6.Cu")
		(net "P5E_CPU0_P0_TX_DP<15>")
	)
	(segment
		(start 378.450348 -357.027734)
		(end 378.322332 -357.566468)
		(width 0.14224)
		(layer "In6.Cu")
		(net "P5E_CPU0_P0_TX_DP<15>")
	)
	(segment
		(start 364.509304 -379.359922)
		(end 364.333028 -379.441202)
		(width 0.14224)
		(layer "In6.Cu")
		(net "P5E_CPU0_P0_TX_DP<15>")
	)
	(segment
		(start 374.44807 -366.06099)
		(end 374.128792 -366.512094)
		(width 0.14224)
		(layer "In6.Cu")
		(net "P5E_CPU0_P0_TX_DP<15>")
	)
	(segment
		(start 365.428022 -376.85599)
		(end 364.840774 -378.458222)
		(width 0.14224)
		(layer "In6.Cu")
		(net "P5E_CPU0_P0_TX_DP<15>")
	)
	(segment
		(start 374.128792 -366.512094)
		(end 373.800116 -366.956594)
		(width 0.14224)
		(layer "In6.Cu")
		(net "P5E_CPU0_P0_TX_DP<15>")
	)
	(segment
		(start 379.057916 -352.650806)
		(end 379.022864 -353.203002)
		(width 0.14224)
		(layer "In6.Cu")
		(net "P5E_CPU0_P0_TX_DP<15>")
	)
	(segment
		(start 378.18314 -358.101392)
		(end 378.081032 -358.460548)
		(width 0.14224)
		(layer "In6.Cu")
		(net "P5E_CPU0_P0_TX_DP<15>")
	)
	(segment
		(start 364.178088 -380.261368)
		(end 364.001812 -380.342648)
		(width 0.14224)
		(layer "In6.Cu")
		(net "P5E_CPU0_P0_TX_DP<15>")
	)
	(segment
		(start 364.84052 -378.458476)
		(end 364.664244 -378.539756)
		(width 0.14224)
		(layer "In6.Cu")
		(net "P5E_CPU0_P0_TX_DP<15>")
	)
	(segment
		(start 364.333028 -379.441202)
		(end 364.214664 -379.763528)
		(width 0.14224)
		(layer "In6.Cu")
		(net "P5E_CPU0_P0_TX_DP<15>")
	)
	(segment
		(start 331.199236 -387.091936)
		(end 330.594208 -386.486908)
		(width 0.14224)
		(layer "In6.Cu")
		(net "P5E_CPU0_P0_TX_DP<15>")
	)
	(segment
		(start 378.97562 -353.753674)
		(end 378.9172 -354.303584)
		(width 0.14224)
		(layer "In6.Cu")
		(net "P5E_CPU0_P0_TX_DP<15>")
	)
	(segment
		(start 375.627646 -364.190026)
		(end 375.347738 -364.666784)
		(width 0.14224)
		(layer "In6.Cu")
		(net "P5E_CPU0_P0_TX_DP<15>")
	)
	(segment
		(start 360.276902 -389.853678)
		(end 359.996232 -389.969756)
		(width 0.14224)
		(layer "In6.Cu")
		(net "P5E_CPU0_P0_TX_DP<15>")
	)
	(segment
		(start 376.644154 -362.226098)
		(end 376.405648 -362.725208)
		(width 0.14224)
		(layer "In6.Cu")
		(net "P5E_CPU0_P0_TX_DP<15>")
	)
	(segment
		(start 379.095762 -339.023452)
		(end 379.095762 -351.419922)
		(width 0.14224)
		(layer "In6.Cu")
		(net "P5E_CPU0_P0_TX_DP<15>")
	)
	(segment
		(start 372.489984 -318.759332)
		(end 376.753628 -326.917812)
		(width 0.14224)
		(layer "In6.Cu")
		(net "P5E_CPU0_P0_TX_DP<15>")
	)
	(segment
		(start 328.519282 -387.273546)
		(end 328.519282 -387.754114)
		(width 0.14224)
		(layer "In6.Cu")
		(net "P5E_CPU0_P0_TX_DP<15>")
	)
	(segment
		(start 363.883448 -380.664974)
		(end 363.964982 -380.840996)
		(width 0.14224)
		(layer "In6.Cu")
		(net "P5E_CPU0_P0_TX_DP<15>")
	)
	(segment
		(start 377.799854 -359.307892)
		(end 377.490228 -360.182668)
		(width 0.14224)
		(layer "In6.Cu")
		(net "P5E_CPU0_P0_TX_DP<15>")
	)
	(segment
		(start 331.669136 -387.96976)
		(end 331.566012 -387.866382)
		(width 0.14224)
		(layer "In6.Cu")
		(net "P5E_CPU0_P0_TX_DP<15>")
	)
	(segment
		(start 372.099332 -369.032282)
		(end 367.467134 -373.66448)
		(width 0.14224)
		(layer "In6.Cu")
		(net "P5E_CPU0_P0_TX_DP<15>")
	)
	(segment
		(start 359.154476 -296.926254)
		(end 359.398824 -299.406056)
		(width 0.14224)
		(layer "In6.Cu")
		(net "P5E_CPU0_P0_TX_DP<15>")
	)
	(segment
		(start 364.001812 -380.342648)
		(end 363.883448 -380.664974)
		(width 0.14224)
		(layer "In6.Cu")
		(net "P5E_CPU0_P0_TX_DP<15>")
	)
	(segment
		(start 363.552486 -381.56642)
		(end 363.633766 -381.742442)
		(width 0.14224)
		(layer "In6.Cu")
		(net "P5E_CPU0_P0_TX_DP<15>")
	)
	(segment
		(start 328.8157 -386.592826)
		(end 328.791062 -386.617464)
		(width 0.14224)
		(layer "In6.Cu")
		(net "P5E_CPU0_P0_TX_DP<15>")
	)
	(segment
		(start 378.671582 -355.94417)
		(end 378.56668 -356.487222)
		(width 0.14224)
		(layer "In6.Cu")
		(net "P5E_CPU0_P0_TX_DP<15>")
	)
	(segment
		(start 358.909366 -389.753856)
		(end 358.896158 -389.740648)
		(width 0.14224)
		(layer "In6.Cu")
		(net "P5E_CPU0_P0_TX_DP<15>")
	)
	(segment
		(start 376.405648 -362.725208)
		(end 376.156474 -363.21873)
		(width 0.14224)
		(layer "In6.Cu")
		(net "P5E_CPU0_P0_TX_DP<15>")
	)
	(segment
		(start 364.54588 -378.862082)
		(end 364.627414 -379.038104)
		(width 0.14224)
		(layer "In6.Cu")
		(net "P5E_CPU0_P0_TX_DP<15>")
	)
	(segment
		(start 357.384604 -282.67152)
		(end 357.387144 -282.673044)
		(width 0.1143)
		(layer "In6.Cu")
		(net "P5E_CPU0_P0_TX_DP<15>")
	)
	(segment
		(start 359.154476 -285.308548)
		(end 359.154476 -296.926254)
		(width 0.14224)
		(layer "In6.Cu")
		(net "P5E_CPU0_P0_TX_DP<15>")
	)
	(segment
		(start 331.390244 -387.527038)
		(end 331.34173 -387.340348)
		(width 0.14224)
		(layer "In6.Cu")
		(net "P5E_CPU0_P0_TX_DP<15>")
	)
	(segment
		(start 376.753628 -326.917812)
		(end 377.106434 -327.948544)
		(width 0.14224)
		(layer "In6.Cu")
		(net "P5E_CPU0_P0_TX_DP<15>")
	)
	(segment
		(start 328.06259 -388.181088)
		(end 327.579736 -388.181088)
		(width 0.14224)
		(layer "In6.Cu")
		(net "P5E_CPU0_P0_TX_DP<15>")
	)
	(segment
		(start 375.347738 -364.666784)
		(end 375.057924 -365.137954)
		(width 0.14224)
		(layer "In6.Cu")
		(net "P5E_CPU0_P0_TX_DP<15>")
	)
	(segment
		(start 374.757696 -365.602774)
		(end 374.44807 -366.06099)
		(width 0.14224)
		(layer "In6.Cu")
		(net "P5E_CPU0_P0_TX_DP<15>")
	)
	(segment
		(start 331.566012 -387.866382)
		(end 331.390244 -387.527038)
		(width 0.14224)
		(layer "In6.Cu")
		(net "P5E_CPU0_P0_TX_DP<15>")
	)
	(segment
		(start 358.86644 -284.878272)
		(end 358.886506 -284.898338)
		(width 0.1143)
		(layer "In6.Cu")
		(net "P5E_CPU0_P0_TX_DP<15>")
	)
	(segment
		(start 379.095762 -351.419922)
		(end 379.088396 -351.759266)
		(width 0.14224)
		(layer "In6.Cu")
		(net "P5E_CPU0_P0_TX_DP<15>")
	)
	(segment
		(start 357.265478 -387.980682)
		(end 334.60944 -387.980682)
		(width 0.14224)
		(layer "In6.Cu")
		(net "P5E_CPU0_P0_TX_DP<15>")
	)
	(segment
		(start 379.022864 -353.203002)
		(end 378.97562 -353.753674)
		(width 0.14224)
		(layer "In6.Cu")
		(net "P5E_CPU0_P0_TX_DP<15>")
	)
	(segment
		(start 373.800116 -366.956594)
		(end 372.535196 -368.59591)
		(width 0.14224)
		(layer "In6.Cu")
		(net "P5E_CPU0_P0_TX_DP<15>")
	)
	(segment
		(start 378.846842 -354.852224)
		(end 378.765054 -355.399086)
		(width 0.14224)
		(layer "In6.Cu")
		(net "P5E_CPU0_P0_TX_DP<15>")
	)
	(segment
		(start 363.33938 -382.14554)
		(end 363.22127 -382.467866)
		(width 0.14224)
		(layer "In6.Cu")
		(net "P5E_CPU0_P0_TX_DP<15>")
	)
	(segment
		(start 376.872246 -361.722162)
		(end 376.644154 -362.226098)
		(width 0.14224)
		(layer "In6.Cu")
		(net "P5E_CPU0_P0_TX_DP<15>")
	)
	(segment
		(start 357.821738 -283.462476)
		(end 357.88981 -283.501846)
		(width 0.1143)
		(layer "In6.Cu")
		(net "P5E_CPU0_P0_TX_DP<15>")
	)
	(segment
		(start 361.354624 -389.018018)
		(end 360.792014 -389.52805)
		(width 0.14224)
		(layer "In6.Cu")
		(net "P5E_CPU0_P0_TX_DP<15>")
	)
	(segment
		(start 363.22127 -382.467866)
		(end 363.30255 -382.643888)
		(width 0.14224)
		(layer "In6.Cu")
		(net "P5E_CPU0_P0_TX_DP<15>")
	)
	(segment
		(start 327.579736 -388.181088)
		(end 327.277476 -387.878828)
		(width 0.14224)
		(layer "In6.Cu")
		(net "P5E_CPU0_P0_TX_DP<15>")
	)
	(segment
		(start 359.873042 -389.99414)
		(end 359.489248 -389.99414)
		(width 0.14224)
		(layer "In6.Cu")
		(net "P5E_CPU0_P0_TX_DP<15>")
	)
	(segment
		(start 375.897394 -363.706918)
		(end 375.627646 -364.190026)
		(width 0.14224)
		(layer "In6.Cu")
		(net "P5E_CPU0_P0_TX_DP<15>")
	)
	(segment
		(start 358.289098 -284.270704)
		(end 358.328214 -284.293564)
		(width 0.1143)
		(layer "In6.Cu")
		(net "P5E_CPU0_P0_TX_DP<15>")
	)
	(segment
		(start 379.088396 -351.759266)
		(end 379.088142 -351.759266)
		(width 0.14224)
		(layer "In6.Cu")
		(net "P5E_CPU0_P0_TX_DP<15>")
	)
	(segment
		(start 363.633766 -381.742442)
		(end 363.515656 -382.06426)
		(width 0.14224)
		(layer "In6.Cu")
		(net "P5E_CPU0_P0_TX_DP<15>")
	)
	(segment
		(start 379.081284 -352.098102)
		(end 379.057916 -352.650806)
		(width 0.14224)
		(layer "In6.Cu")
		(net "P5E_CPU0_P0_TX_DP<15>")
	)
	(segment
		(start 357.355902 -282.654756)
		(end 357.356664 -282.655264)
		(width 0.1143)
		(layer "In6.Cu")
		(net "P5E_CPU0_P0_TX_DP<15>")
	)
	(segment
		(start 356.731062 -282.186126)
		(end 357.029004 -282.186126)
		(width 0.1143)
		(layer "In6.Cu")
		(net "P5E_CPU0_P0_TX_DP<15>")
	)
	(segment
		(start 363.515656 -382.06426)
		(end 363.33938 -382.14554)
		(width 0.14224)
		(layer "In6.Cu")
		(net "P5E_CPU0_P0_TX_DP<15>")
	)
	(segment
		(start 358.404668 -284.352492)
		(end 358.86644 -284.814264)
		(width 0.1143)
		(layer "In6.Cu")
		(net "P5E_CPU0_P0_TX_DP<15>")
	)
	(segment
		(start 377.295156 -360.699812)
		(end 377.088908 -361.212892)
		(width 0.14224)
		(layer "In6.Cu")
		(net "P5E_CPU0_P0_TX_DP<15>")
	)
	(segment
		(start 357.383842 -282.671012)
		(end 357.384604 -282.67152)
		(width 0.1143)
		(layer "In6.Cu")
		(net "P5E_CPU0_P0_TX_DP<15>")
	)
	(segment
		(start 360.694224 -389.608314)
		(end 360.62412 -389.660384)
		(width 0.14224)
		(layer "In6.Cu")
		(net "P5E_CPU0_P0_TX_DP<15>")
	)
	(segment
		(start 363.30255 -382.643888)
		(end 362.209842 -385.619498)
		(width 0.14224)
		(layer "In6.Cu")
		(net "P5E_CPU0_P0_TX_DP<15>")
	)
	(segment
		(start 358.743758 -389.372856)
		(end 358.743758 -389.234426)
		(width 0.14224)
		(layer "In6.Cu")
		(net "P5E_CPU0_P0_TX_DP<15>")
	)
	(segment
		(start 378.081032 -358.460548)
		(end 377.799854 -359.307892)
		(width 0.14224)
		(layer "In6.Cu")
		(net "P5E_CPU0_P0_TX_DP<15>")
	)
	(segment
		(start 357.387144 -282.673044)
		(end 357.38816 -282.673552)
		(width 0.1143)
		(layer "In6.Cu")
		(net "P5E_CPU0_P0_TX_DP<15>")
	)
	(segment
		(start 376.156474 -363.21873)
		(end 375.897394 -363.706918)
		(width 0.14224)
		(layer "In6.Cu")
		(net "P5E_CPU0_P0_TX_DP<15>")
	)
	(segment
		(start 358.86644 -284.814264)
		(end 358.86644 -284.878272)
		(width 0.1143)
		(layer "In6.Cu")
		(net "P5E_CPU0_P0_TX_DP<15>")
	)
	(segment
		(start 377.490228 -360.182668)
		(end 377.295156 -360.699812)
		(width 0.14224)
		(layer "In6.Cu")
		(net "P5E_CPU0_P0_TX_DP<15>")
	)
	(segment
		(start 378.9172 -354.303584)
		(end 378.846842 -354.852224)
		(width 0.14224)
		(layer "In6.Cu")
		(net "P5E_CPU0_P0_TX_DP<15>")
	)
	(segment
		(start 358.613964 -388.920736)
		(end 357.946706 -388.253478)
		(width 0.14224)
		(layer "In6.Cu")
		(net "P5E_CPU0_P0_TX_DP<15>")
	)
	(segment
		(start 360.54792 -389.709914)
		(end 360.390694 -389.798306)
		(width 0.14224)
		(layer "In6.Cu")
		(net "P5E_CPU0_P0_TX_DP<15>")
	)
	(segment
		(start 363.846872 -381.162814)
		(end 363.670596 -381.244094)
		(width 0.14224)
		(layer "In6.Cu")
		(net "P5E_CPU0_P0_TX_DP<15>")
	)
	(segment
		(start 332.722474 -388.192518)
		(end 332.206854 -388.192518)
		(width 0.14224)
		(layer "In6.Cu")
		(net "P5E_CPU0_P0_TX_DP<15>")
	)
	(segment
		(start 361.036616 -303.360074)
		(end 366.228884 -311.130696)
		(width 0.14224)
		(layer "In6.Cu")
		(net "P5E_CPU0_P0_TX_DP<15>")
	)
	(segment
		(start 378.322332 -357.566468)
		(end 378.18314 -358.101392)
		(width 0.14224)
		(layer "In6.Cu")
		(net "P5E_CPU0_P0_TX_DP<15>")
	)
	(segment
		(start 357.38816 -282.673552)
		(end 357.388922 -282.67406)
		(width 0.1143)
		(layer "In6.Cu")
		(net "P5E_CPU0_P0_TX_DP<15>")
	)
	(segment
		(start 377.088908 -361.212892)
		(end 376.872246 -361.722162)
		(width 0.14224)
		(layer "In6.Cu")
		(net "P5E_CPU0_P0_TX_DP<15>")
	)
	(segment
		(start 378.765054 -355.399086)
		(end 378.671582 -355.94417)
		(width 0.14224)
		(layer "In6.Cu")
		(net "P5E_CPU0_P0_TX_DP<15>")
	)
	(segment
		(start 379.088142 -351.759266)
		(end 379.081284 -352.098102)
		(width 0.14224)
		(layer "In6.Cu")
		(net "P5E_CPU0_P0_TX_DP<15>")
	)
	(segment
		(start 357.388922 -282.67406)
		(end 357.41991 -282.69184)
		(width 0.1143)
		(layer "In6.Cu")
		(net "P5E_CPU0_P0_TX_DP<15>")
	)
	(segment
		(start 357.349044 -282.650692)
		(end 357.355902 -282.654756)
		(width 0.1143)
		(layer "In6.Cu")
		(net "P5E_CPU0_P0_TX_DP<15>")
	)
	(segment
		(start 364.62716 -379.038866)
		(end 364.509304 -379.359922)
		(width 0.14224)
		(layer "In6.Cu")
		(net "P5E_CPU0_P0_TX_DP<15>")
	)
	(segment
		(start 362.209842 -385.619498)
		(end 361.567476 -388.58825)
		(width 0.14224)
		(layer "In6.Cu")
		(net "P5E_CPU0_P0_TX_DP<15>")
	)
	(segment
		(start 364.296198 -379.93955)
		(end 364.178088 -380.261368)
		(width 0.14224)
		(layer "In6.Cu")
		(net "P5E_CPU0_P0_TX_DP<15>")
	)
	(segment
		(start 357.744268 -388.121144)
		(end 357.491538 -388.022846)
		(width 0.14224)
		(layer "In6.Cu")
		(net "P5E_CPU0_P0_TX_DP<15>")
	)
	(segment
		(start 358.886506 -284.898338)
		(end 359.053892 -285.065724)
		(width 0.14224)
		(layer "In6.Cu")
		(net "P5E_CPU0_P0_TX_DP<15>")
	)
	(segment
		(start 364.840774 -378.458222)
		(end 364.84052 -378.458476)
		(width 0.14224)
		(layer "In6.Cu")
		(net "P5E_CPU0_P0_TX_DP<15>")
	)
	(segment
		(start 357.356664 -282.655264)
		(end 357.383842 -282.671012)
		(width 0.1143)
		(layer "In6.Cu")
		(net "P5E_CPU0_P0_TX_DP<15>")
	)
	(segment
		(start 330.280518 -386.357114)
		(end 329.384914 -386.357114)
		(width 0.14224)
		(layer "In6.Cu")
		(net "P5E_CPU0_P0_TX_DP<15>")
	)
	(segment
		(start 363.964982 -380.840996)
		(end 363.846872 -381.162814)
		(width 0.14224)
		(layer "In6.Cu")
		(net "P5E_CPU0_P0_TX_DP<15>")
	)
	(segment
		(start 364.664244 -378.539756)
		(end 364.54588 -378.862082)
		(width 0.14224)
		(layer "In6.Cu")
		(net "P5E_CPU0_P0_TX_DP<15>")
	)
	(segment
		(start 366.228884 -311.130696)
		(end 372.489984 -318.759332)
		(width 0.14224)
		(layer "In6.Cu")
		(net "P5E_CPU0_P0_TX_DP<15>")
	)
	(segment
		(start 359.398824 -299.406056)
		(end 361.036616 -303.360074)
		(width 0.14224)
		(layer "In6.Cu")
		(net "P5E_CPU0_P0_TX_DP<15>")
	)
	(segment
		(start 375.057924 -365.137954)
		(end 374.757696 -365.602774)
		(width 0.14224)
		(layer "In6.Cu")
		(net "P5E_CPU0_P0_TX_DP<15>")
	)
	(segment
		(start 378.56668 -356.487222)
		(end 378.450348 -357.027734)
		(width 0.14224)
		(layer "In6.Cu")
		(net "P5E_CPU0_P0_TX_DP<15>")
	)
	(segment
		(start 357.029004 -282.186126)
		(end 357.111808 -282.26893)
		(width 0.1143)
		(layer "In6.Cu")
		(net "P5E_CPU0_P0_TX_DP<15>")
	)
	(segment
		(start 364.214664 -379.763528)
		(end 364.296198 -379.93955)
		(width 0.14224)
		(layer "In6.Cu")
		(net "P5E_CPU0_P0_TX_DP<15>")
	)
	(segment
		(start 364.627414 -379.038104)
		(end 364.62716 -379.038866)
		(width 0.14224)
		(layer "In6.Cu")
		(net "P5E_CPU0_P0_TX_DP<15>")
	)
	(segment
		(start 377.106434 -327.948544)
		(end 379.095762 -339.023452)
		(width 0.14224)
		(layer "In6.Cu")
		(net "P5E_CPU0_P0_TX_DP<15>")
	)
	(segment
		(start 372.535196 -368.59591)
		(end 372.099332 -369.032282)
		(width 0.14224)
		(layer "In6.Cu")
		(net "P5E_CPU0_P0_TX_DP<15>")
	)
	(arc
		(start 331.34173 -387.340348)
		(mid 331.28705 -387.206642)
		(end 331.199236 -387.091936)
		(width 0.14224)
		(layer "In6.Cu")
		(net "P5E_CPU0_P0_TX_DP<15>")
	)
	(arc
		(start 357.57612 -282.981146)
		(mid 357.577292 -283.006601)
		(end 357.57993 -283.031946)
		(width 0.1143)
		(layer "In6.Cu")
		(net "P5E_CPU0_P0_TX_DP<15>")
	)
	(arc
		(start 360.62412 -389.660384)
		(mid 360.586797 -389.686345)
		(end 360.54792 -389.709914)
		(width 0.14224)
		(layer "In6.Cu")
		(net "P5E_CPU0_P0_TX_DP<15>")
	)
	(arc
		(start 358.045766 -283.806138)
		(mid 358.110281 -284.068357)
		(end 358.289098 -284.270704)
		(width 0.1143)
		(layer "In6.Cu")
		(net "P5E_CPU0_P0_TX_DP<15>")
	)
	(arc
		(start 357.57993 -283.031946)
		(mid 357.660598 -283.269818)
		(end 357.821738 -283.462476)
		(width 0.1143)
		(layer "In6.Cu")
		(net "P5E_CPU0_P0_TX_DP<15>")
	)
	(arc
		(start 328.340466 -388.106412)
		(mid 328.20645 -388.162065)
		(end 328.06259 -388.181088)
		(width 0.14224)
		(layer "In6.Cu")
		(net "P5E_CPU0_P0_TX_DP<15>")
	)
	(arc
		(start 358.896158 -389.740648)
		(mid 358.783353 -389.571918)
		(end 358.743758 -389.372856)
		(width 0.14224)
		(layer "In6.Cu")
		(net "P5E_CPU0_P0_TX_DP<15>")
	)
	(arc
		(start 332.206854 -388.192518)
		(mid 331.915832 -388.13463)
		(end 331.669136 -387.96976)
		(width 0.14224)
		(layer "In6.Cu")
		(net "P5E_CPU0_P0_TX_DP<15>")
	)
	(arc
		(start 360.390694 -389.798306)
		(mid 360.33463 -389.827702)
		(end 360.276902 -389.853678)
		(width 0.14224)
		(layer "In6.Cu")
		(net "P5E_CPU0_P0_TX_DP<15>")
	)
	(arc
		(start 357.41991 -282.69184)
		(mid 357.531352 -282.818482)
		(end 357.57612 -282.981146)
		(width 0.1143)
		(layer "In6.Cu")
		(net "P5E_CPU0_P0_TX_DP<15>")
	)
	(arc
		(start 357.115618 -282.29179)
		(mid 357.197051 -282.494188)
		(end 357.349044 -282.650692)
		(width 0.1143)
		(layer "In6.Cu")
		(net "P5E_CPU0_P0_TX_DP<15>")
	)
	(arc
		(start 359.489248 -389.99414)
		(mid 359.175398 -389.931694)
		(end 358.909366 -389.753856)
		(width 0.14224)
		(layer "In6.Cu")
		(net "P5E_CPU0_P0_TX_DP<15>")
	)
	(arc
		(start 361.435396 -388.920482)
		(mid 361.398541 -388.972174)
		(end 361.354624 -389.018018)
		(width 0.14224)
		(layer "In6.Cu")
		(net "P5E_CPU0_P0_TX_DP<15>")
	)
	(arc
		(start 357.946706 -388.253478)
		(mid 357.852372 -388.176778)
		(end 357.744268 -388.121144)
		(width 0.14224)
		(layer "In6.Cu")
		(net "P5E_CPU0_P0_TX_DP<15>")
	)
	(arc
		(start 357.88981 -283.501846)
		(mid 358.004486 -283.63518)
		(end 358.045766 -283.806138)
		(width 0.1143)
		(layer "In6.Cu")
		(net "P5E_CPU0_P0_TX_DP<15>")
	)
	(arc
		(start 360.792014 -389.52805)
		(mid 360.74409 -389.569365)
		(end 360.694224 -389.608314)
		(width 0.14224)
		(layer "In6.Cu")
		(net "P5E_CPU0_P0_TX_DP<15>")
	)
	(arc
		(start 359.996232 -389.969756)
		(mid 359.935834 -389.988002)
		(end 359.873042 -389.99414)
		(width 0.14224)
		(layer "In6.Cu")
		(net "P5E_CPU0_P0_TX_DP<15>")
	)
	(arc
		(start 358.328214 -284.293564)
		(mid 358.368359 -284.32054)
		(end 358.404668 -284.352492)
		(width 0.1143)
		(layer "In6.Cu")
		(net "P5E_CPU0_P0_TX_DP<15>")
	)
	(arc
		(start 361.567476 -388.58825)
		(mid 361.51536 -388.759903)
		(end 361.435396 -388.920482)
		(width 0.14224)
		(layer "In6.Cu")
		(net "P5E_CPU0_P0_TX_DP<15>")
	)
	(arc
		(start 328.519282 -387.754114)
		(mid 328.514084 -387.817468)
		(end 328.498454 -387.879082)
		(width 0.14224)
		(layer "In6.Cu")
		(net "P5E_CPU0_P0_TX_DP<15>")
	)
	(arc
		(start 367.467134 -373.66448)
		(mid 366.273857 -375.149242)
		(end 365.428022 -376.85599)
		(width 0.14224)
		(layer "In6.Cu")
		(net "P5E_CPU0_P0_TX_DP<15>")
	)
	(arc
		(start 359.053892 -285.065724)
		(mid 359.128333 -285.177133)
		(end 359.154476 -285.308548)
		(width 0.14224)
		(layer "In6.Cu")
		(net "P5E_CPU0_P0_TX_DP<15>")
	)
	(arc
		(start 358.743758 -389.234426)
		(mid 358.710053 -389.064687)
		(end 358.613964 -388.920736)
		(width 0.14224)
		(layer "In6.Cu")
		(net "P5E_CPU0_P0_TX_DP<15>")
	)
	(arc
		(start 330.594208 -386.486908)
		(mid 330.450285 -386.390772)
		(end 330.280518 -386.357114)
		(width 0.14224)
		(layer "In6.Cu")
		(net "P5E_CPU0_P0_TX_DP<15>")
	)
	(arc
		(start 329.384914 -386.357114)
		(mid 329.076868 -386.41837)
		(end 328.8157 -386.592826)
		(width 0.14224)
		(layer "In6.Cu")
		(net "P5E_CPU0_P0_TX_DP<15>")
	)
	(arc
		(start 334.60944 -387.980682)
		(mid 334.134797 -388.007241)
		(end 333.666084 -388.0866)
		(width 0.14224)
		(layer "In6.Cu")
		(net "P5E_CPU0_P0_TX_DP<15>")
	)
	(arc
		(start 357.491538 -388.022846)
		(mid 357.380468 -387.991259)
		(end 357.265478 -387.980682)
		(width 0.14224)
		(layer "In6.Cu")
		(net "P5E_CPU0_P0_TX_DP<15>")
	)
	(arc
		(start 333.666084 -388.0866)
		(mid 333.197243 -388.165959)
		(end 332.722474 -388.192518)
		(width 0.14224)
		(layer "In6.Cu")
		(net "P5E_CPU0_P0_TX_DP<15>")
	)
	(arc
		(start 357.111808 -282.26893)
		(mid 357.113596 -282.280379)
		(end 357.115618 -282.29179)
		(width 0.1143)
		(layer "In6.Cu")
		(net "P5E_CPU0_P0_TX_DP<15>")
	)
	(arc
		(start 328.431652 -388.018528)
		(mid 328.391387 -388.067997)
		(end 328.340466 -388.106412)
		(width 0.14224)
		(layer "In6.Cu")
		(net "P5E_CPU0_P0_TX_DP<15>")
	)
	(arc
		(start 328.791062 -386.617464)
		(mid 328.589932 -386.918477)
		(end 328.519282 -387.273546)
		(width 0.14224)
		(layer "In6.Cu")
		(net "P5E_CPU0_P0_TX_DP<15>")
	)
	(arc
		(start 328.498454 -387.879082)
		(mid 328.469056 -387.950722)
		(end 328.431652 -388.018528)
		(width 0.14224)
		(layer "In6.Cu")
		(net "P5E_CPU0_P0_TX_DP<15>")
	)
	(segment
		(start 357.197914 -283.5402)
		(end 356.731062 -283.806138)
		(width 0.12954)
		(layer "F.Cu")
		(net "P5E_CPU0_P0_TX_DP<14>")
	)
	(segment
		(start 326.007476 -384.449828)
		(end 326.303386 -384.745738)
		(width 0.12954)
		(layer "F.Cu")
		(net "P5E_CPU0_P0_TX_DP<14>")
	)
	(segment
		(start 326.303386 -384.745738)
		(end 327.006966 -384.745738)
		(width 0.12954)
		(layer "F.Cu")
		(net "P5E_CPU0_P0_TX_DP<14>")
	)
	(segment
		(start 327.006966 -384.745738)
		(end 327.277476 -384.475228)
		(width 0.12954)
		(layer "F.Cu")
		(net "P5E_CPU0_P0_TX_DP<14>")
	)
	(segment
		(start 358.328214 -289.798506)
		(end 358.289098 -289.821366)
		(width 0.1143)
		(layer "In6.Cu")
		(net "P5E_CPU0_P0_TX_DP<14>")
	)
	(segment
		(start 358.359964 -294.031924)
		(end 358.393238 -294.055038)
		(width 0.1143)
		(layer "In6.Cu")
		(net "P5E_CPU0_P0_TX_DP<14>")
	)
	(segment
		(start 362.937044 -379.997716)
		(end 362.818934 -380.320042)
		(width 0.14224)
		(layer "In6.Cu")
		(net "P5E_CPU0_P0_TX_DP<14>")
	)
	(segment
		(start 358.32796 -294.013382)
		(end 358.328214 -294.013382)
		(width 0.1143)
		(layer "In6.Cu")
		(net "P5E_CPU0_P0_TX_DP<14>")
	)
	(segment
		(start 375.078498 -363.261148)
		(end 374.818402 -363.72673)
		(width 0.14224)
		(layer "In6.Cu")
		(net "P5E_CPU0_P0_TX_DP<14>")
	)
	(segment
		(start 376.22734 -360.856276)
		(end 376.018298 -361.347004)
		(width 0.14224)
		(layer "In6.Cu")
		(net "P5E_CPU0_P0_TX_DP<14>")
	)
	(segment
		(start 363.149896 -379.418596)
		(end 363.23143 -379.594618)
		(width 0.14224)
		(layer "In6.Cu")
		(net "P5E_CPU0_P0_TX_DP<14>")
	)
	(segment
		(start 375.798588 -361.832906)
		(end 375.568718 -362.313982)
		(width 0.14224)
		(layer "In6.Cu")
		(net "P5E_CPU0_P0_TX_DP<14>")
	)
	(segment
		(start 358.289098 -290.750498)
		(end 358.328214 -290.773358)
		(width 0.1143)
		(layer "In6.Cu")
		(net "P5E_CPU0_P0_TX_DP<14>")
	)
	(segment
		(start 362.568998 -381.39751)
		(end 360.873294 -386.014722)
		(width 0.14224)
		(layer "In6.Cu")
		(net "P5E_CPU0_P0_TX_DP<14>")
	)
	(segment
		(start 375.568718 -362.313982)
		(end 375.328434 -362.789978)
		(width 0.14224)
		(layer "In6.Cu")
		(net "P5E_CPU0_P0_TX_DP<14>")
	)
	(segment
		(start 378.150882 -339.13953)
		(end 378.150882 -351.536508)
		(width 0.14224)
		(layer "In6.Cu")
		(net "P5E_CPU0_P0_TX_DP<14>")
	)
	(segment
		(start 377.731782 -355.750876)
		(end 377.63069 -356.27437)
		(width 0.14224)
		(layer "In6.Cu")
		(net "P5E_CPU0_P0_TX_DP<14>")
	)
	(segment
		(start 373.373142 -365.96574)
		(end 373.05615 -366.394492)
		(width 0.14224)
		(layer "In6.Cu")
		(net "P5E_CPU0_P0_TX_DP<14>")
	)
	(segment
		(start 358.295956 -286.577532)
		(end 358.295956 -286.577278)
		(width 0.1143)
		(layer "In6.Cu")
		(net "P5E_CPU0_P0_TX_DP<14>")
	)
	(segment
		(start 378.025152 -353.638612)
		(end 377.968764 -354.168964)
		(width 0.14224)
		(layer "In6.Cu")
		(net "P5E_CPU0_P0_TX_DP<14>")
	)
	(segment
		(start 363.776006 -378.11329)
		(end 363.775752 -378.113544)
		(width 0.14224)
		(layer "In6.Cu")
		(net "P5E_CPU0_P0_TX_DP<14>")
	)
	(segment
		(start 376.426222 -360.361484)
		(end 376.22734 -360.856276)
		(width 0.14224)
		(layer "In6.Cu")
		(net "P5E_CPU0_P0_TX_DP<14>")
	)
	(segment
		(start 375.89079 -327.279762)
		(end 376.162316 -328.07148)
		(width 0.14224)
		(layer "In6.Cu")
		(net "P5E_CPU0_P0_TX_DP<14>")
	)
	(segment
		(start 377.394978 -357.3145)
		(end 377.260612 -357.830628)
		(width 0.14224)
		(layer "In6.Cu")
		(net "P5E_CPU0_P0_TX_DP<14>")
	)
	(segment
		(start 357.349044 -284.270704)
		(end 357.39705 -284.298644)
		(width 0.1143)
		(layer "In6.Cu")
		(net "P5E_CPU0_P0_TX_DP<14>")
	)
	(segment
		(start 357.584756 -284.62351)
		(end 357.584756 -284.628844)
		(width 0.1143)
		(layer "In6.Cu")
		(net "P5E_CPU0_P0_TX_DP<14>")
	)
	(segment
		(start 358.000046 -295.552876)
		(end 358.000046 -295.581324)
		(width 0.1143)
		(layer "In6.Cu")
		(net "P5E_CPU0_P0_TX_DP<14>")
	)
	(segment
		(start 363.481112 -378.51715)
		(end 363.562646 -378.693172)
		(width 0.14224)
		(layer "In6.Cu")
		(net "P5E_CPU0_P0_TX_DP<14>")
	)
	(segment
		(start 330.079604 -382.847342)
		(end 329.870816 -382.847342)
		(width 0.14224)
		(layer "In6.Cu")
		(net "P5E_CPU0_P0_TX_DP<14>")
	)
	(segment
		(start 353.988116 -384.668776)
		(end 333.698596 -384.668776)
		(width 0.14224)
		(layer "In6.Cu")
		(net "P5E_CPU0_P0_TX_DP<14>")
	)
	(segment
		(start 358.328214 -293.03853)
		(end 358.32796 -293.038784)
		(width 0.1143)
		(layer "In6.Cu")
		(net "P5E_CPU0_P0_TX_DP<14>")
	)
	(segment
		(start 358.328214 -294.013382)
		(end 358.359964 -294.031924)
		(width 0.1143)
		(layer "In6.Cu")
		(net "P5E_CPU0_P0_TX_DP<14>")
	)
	(segment
		(start 358.358694 -291.400738)
		(end 358.328214 -291.418518)
		(width 0.1143)
		(layer "In6.Cu")
		(net "P5E_CPU0_P0_TX_DP<14>")
	)
	(segment
		(start 373.05615 -366.394492)
		(end 372.730014 -366.816386)
		(width 0.14224)
		(layer "In6.Cu")
		(net "P5E_CPU0_P0_TX_DP<14>")
	)
	(segment
		(start 358.000046 -295.581324)
		(end 358.000046 -298.465748)
		(width 0.14224)
		(layer "In6.Cu")
		(net "P5E_CPU0_P0_TX_DP<14>")
	)
	(segment
		(start 357.85806 -285.10357)
		(end 357.88981 -285.121858)
		(width 0.1143)
		(layer "In6.Cu")
		(net "P5E_CPU0_P0_TX_DP<14>")
	)
	(segment
		(start 363.23143 -379.594618)
		(end 363.231176 -379.59538)
		(width 0.14224)
		(layer "In6.Cu")
		(net "P5E_CPU0_P0_TX_DP<14>")
	)
	(segment
		(start 376.614436 -359.862628)
		(end 376.426222 -360.361484)
		(width 0.14224)
		(layer "In6.Cu")
		(net "P5E_CPU0_P0_TX_DP<14>")
	)
	(segment
		(start 377.821952 -355.225096)
		(end 377.731782 -355.750876)
		(width 0.14224)
		(layer "In6.Cu")
		(net "P5E_CPU0_P0_TX_DP<14>")
	)
	(segment
		(start 358.515666 -287.856168)
		(end 358.515666 -287.90392)
		(width 0.1143)
		(layer "In6.Cu")
		(net "P5E_CPU0_P0_TX_DP<14>")
	)
	(segment
		(start 377.900946 -354.697792)
		(end 377.821952 -355.225096)
		(width 0.14224)
		(layer "In6.Cu")
		(net "P5E_CPU0_P0_TX_DP<14>")
	)
	(segment
		(start 356.731062 -283.806138)
		(end 357.029004 -283.806138)
		(width 0.1143)
		(layer "In6.Cu")
		(net "P5E_CPU0_P0_TX_DP<14>")
	)
	(segment
		(start 371.699028 -368.039396)
		(end 371.338348 -368.43208)
		(width 0.14224)
		(layer "In6.Cu")
		(net "P5E_CPU0_P0_TX_DP<14>")
	)
	(segment
		(start 363.775752 -378.113544)
		(end 363.599476 -378.194824)
		(width 0.14224)
		(layer "In6.Cu")
		(net "P5E_CPU0_P0_TX_DP<14>")
	)
	(segment
		(start 358.338882 -285.92145)
		(end 358.3432 -285.92145)
		(width 0.1143)
		(layer "In6.Cu")
		(net "P5E_CPU0_P0_TX_DP<14>")
	)
	(segment
		(start 362.605828 -380.899162)
		(end 362.487718 -381.221488)
		(width 0.14224)
		(layer "In6.Cu")
		(net "P5E_CPU0_P0_TX_DP<14>")
	)
	(segment
		(start 358.295956 -286.577278)
		(end 358.289098 -286.581342)
		(width 0.1143)
		(layer "In6.Cu")
		(net "P5E_CPU0_P0_TX_DP<14>")
	)
	(segment
		(start 358.358694 -289.780726)
		(end 358.328214 -289.798506)
		(width 0.1143)
		(layer "In6.Cu")
		(net "P5E_CPU0_P0_TX_DP<14>")
	)
	(segment
		(start 364.151164 -377.089924)
		(end 363.776006 -378.11329)
		(width 0.14224)
		(layer "In6.Cu")
		(net "P5E_CPU0_P0_TX_DP<14>")
	)
	(segment
		(start 377.518422 -356.795578)
		(end 377.394978 -357.3145)
		(width 0.14224)
		(layer "In6.Cu")
		(net "P5E_CPU0_P0_TX_DP<14>")
	)
	(segment
		(start 363.231176 -379.59538)
		(end 363.11332 -379.916436)
		(width 0.14224)
		(layer "In6.Cu")
		(net "P5E_CPU0_P0_TX_DP<14>")
	)
	(segment
		(start 378.150882 -351.536508)
		(end 378.135896 -351.621852)
		(width 0.14224)
		(layer "In6.Cu")
		(net "P5E_CPU0_P0_TX_DP<14>")
	)
	(segment
		(start 363.11332 -379.916436)
		(end 362.937044 -379.997716)
		(width 0.14224)
		(layer "In6.Cu")
		(net "P5E_CPU0_P0_TX_DP<14>")
	)
	(segment
		(start 378.1044 -352.575114)
		(end 378.070364 -353.107244)
		(width 0.14224)
		(layer "In6.Cu")
		(net "P5E_CPU0_P0_TX_DP<14>")
	)
	(segment
		(start 360.210608 -303.802796)
		(end 365.478314 -311.68594)
		(width 0.14224)
		(layer "In6.Cu")
		(net "P5E_CPU0_P0_TX_DP<14>")
	)
	(segment
		(start 363.562646 -378.693172)
		(end 363.444536 -379.01499)
		(width 0.14224)
		(layer "In6.Cu")
		(net "P5E_CPU0_P0_TX_DP<14>")
	)
	(segment
		(start 374.5484 -364.18647)
		(end 374.269 -364.640622)
		(width 0.14224)
		(layer "In6.Cu")
		(net "P5E_CPU0_P0_TX_DP<14>")
	)
	(segment
		(start 363.444536 -379.01499)
		(end 363.26826 -379.09627)
		(width 0.14224)
		(layer "In6.Cu")
		(net "P5E_CPU0_P0_TX_DP<14>")
	)
	(segment
		(start 376.959114 -358.853486)
		(end 376.792236 -359.359708)
		(width 0.14224)
		(layer "In6.Cu")
		(net "P5E_CPU0_P0_TX_DP<14>")
	)
	(segment
		(start 374.269 -364.640622)
		(end 373.979694 -365.088424)
		(width 0.14224)
		(layer "In6.Cu")
		(net "P5E_CPU0_P0_TX_DP<14>")
	)
	(segment
		(start 376.162316 -328.07148)
		(end 378.150882 -339.13953)
		(width 0.14224)
		(layer "In6.Cu")
		(net "P5E_CPU0_P0_TX_DP<14>")
	)
	(segment
		(start 377.115324 -358.343708)
		(end 376.959114 -358.853486)
		(width 0.14224)
		(layer "In6.Cu")
		(net "P5E_CPU0_P0_TX_DP<14>")
	)
	(segment
		(start 378.070364 -353.107244)
		(end 378.025152 -353.638612)
		(width 0.14224)
		(layer "In6.Cu")
		(net "P5E_CPU0_P0_TX_DP<14>")
	)
	(segment
		(start 363.26826 -379.09627)
		(end 363.149896 -379.418596)
		(width 0.14224)
		(layer "In6.Cu")
		(net "P5E_CPU0_P0_TX_DP<14>")
	)
	(segment
		(start 328.49947 -384.53822)
		(end 328.42581 -384.71602)
		(width 0.14224)
		(layer "In6.Cu")
		(net "P5E_CPU0_P0_TX_DP<14>")
	)
	(segment
		(start 328.323194 -384.766058)
		(end 327.568306 -384.766058)
		(width 0.14224)
		(layer "In6.Cu")
		(net "P5E_CPU0_P0_TX_DP<14>")
	)
	(segment
		(start 370.969286 -368.817144)
		(end 366.702086 -373.097298)
		(width 0.14224)
		(layer "In6.Cu")
		(net "P5E_CPU0_P0_TX_DP<14>")
	)
	(segment
		(start 358.396032 -294.615108)
		(end 358.324912 -294.660574)
		(width 0.1143)
		(layer "In6.Cu")
		(net "P5E_CPU0_P0_TX_DP<14>")
	)
	(segment
		(start 358.328214 -292.39337)
		(end 358.358694 -292.41115)
		(width 0.1143)
		(layer "In6.Cu")
		(net "P5E_CPU0_P0_TX_DP<14>")
	)
	(segment
		(start 358.328214 -290.773358)
		(end 358.358694 -290.791138)
		(width 0.1143)
		(layer "In6.Cu")
		(net "P5E_CPU0_P0_TX_DP<14>")
	)
	(segment
		(start 328.49947 -384.186684)
		(end 328.49947 -384.53822)
		(width 0.14224)
		(layer "In6.Cu")
		(net "P5E_CPU0_P0_TX_DP<14>")
	)
	(segment
		(start 371.70868 -319.277238)
		(end 375.89079 -327.279762)
		(width 0.14224)
		(layer "In6.Cu")
		(net "P5E_CPU0_P0_TX_DP<14>")
	)
	(segment
		(start 372.394988 -367.231422)
		(end 372.051326 -367.639092)
		(width 0.14224)
		(layer "In6.Cu")
		(net "P5E_CPU0_P0_TX_DP<14>")
	)
	(segment
		(start 378.135896 -351.621852)
		(end 378.127006 -352.042476)
		(width 0.14224)
		(layer "In6.Cu")
		(net "P5E_CPU0_P0_TX_DP<14>")
	)
	(segment
		(start 358.324912 -294.660574)
		(end 358.290622 -294.680132)
		(width 0.1143)
		(layer "In6.Cu")
		(net "P5E_CPU0_P0_TX_DP<14>")
	)
	(segment
		(start 328.923396 -383.239772)
		(end 328.869294 -383.293874)
		(width 0.14224)
		(layer "In6.Cu")
		(net "P5E_CPU0_P0_TX_DP<14>")
	)
	(segment
		(start 358.045766 -295.145968)
		(end 358.045766 -295.507156)
		(width 0.1143)
		(layer "In6.Cu")
		(net "P5E_CPU0_P0_TX_DP<14>")
	)
	(segment
		(start 358.289098 -289.130486)
		(end 358.328214 -289.153346)
		(width 0.1143)
		(layer "In6.Cu")
		(net "P5E_CPU0_P0_TX_DP<14>")
	)
	(segment
		(start 373.979694 -365.088424)
		(end 373.68099 -365.530384)
		(width 0.14224)
		(layer "In6.Cu")
		(net "P5E_CPU0_P0_TX_DP<14>")
	)
	(segment
		(start 360.218736 -386.471668)
		(end 359.702862 -386.471668)
		(width 0.14224)
		(layer "In6.Cu")
		(net "P5E_CPU0_P0_TX_DP<14>")
	)
	(segment
		(start 358.357678 -286.541464)
		(end 358.295956 -286.577532)
		(width 0.1143)
		(layer "In6.Cu")
		(net "P5E_CPU0_P0_TX_DP<14>")
	)
	(segment
		(start 357.029004 -283.806138)
		(end 357.111808 -283.888942)
		(width 0.1143)
		(layer "In6.Cu")
		(net "P5E_CPU0_P0_TX_DP<14>")
	)
	(segment
		(start 376.792236 -359.359708)
		(end 376.614436 -359.862628)
		(width 0.14224)
		(layer "In6.Cu")
		(net "P5E_CPU0_P0_TX_DP<14>")
	)
	(segment
		(start 362.487718 -381.221488)
		(end 362.568998 -381.39751)
		(width 0.14224)
		(layer "In6.Cu")
		(net "P5E_CPU0_P0_TX_DP<14>")
	)
	(segment
		(start 377.63069 -356.27437)
		(end 377.518422 -356.795578)
		(width 0.14224)
		(layer "In6.Cu")
		(net "P5E_CPU0_P0_TX_DP<14>")
	)
	(segment
		(start 378.127006 -352.042476)
		(end 378.1044 -352.575114)
		(width 0.14224)
		(layer "In6.Cu")
		(net "P5E_CPU0_P0_TX_DP<14>")
	)
	(segment
		(start 358.358694 -293.02075)
		(end 358.328214 -293.03853)
		(width 0.1143)
		(layer "In6.Cu")
		(net "P5E_CPU0_P0_TX_DP<14>")
	)
	(segment
		(start 358.000046 -298.465748)
		(end 360.210608 -303.802796)
		(width 0.14224)
		(layer "In6.Cu")
		(net "P5E_CPU0_P0_TX_DP<14>")
	)
	(segment
		(start 372.730014 -366.816386)
		(end 372.394988 -367.231422)
		(width 0.14224)
		(layer "In6.Cu")
		(net "P5E_CPU0_P0_TX_DP<14>")
	)
	(segment
		(start 375.328434 -362.789978)
		(end 375.078498 -363.261148)
		(width 0.14224)
		(layer "In6.Cu")
		(net "P5E_CPU0_P0_TX_DP<14>")
	)
	(segment
		(start 371.338348 -368.43208)
		(end 370.969286 -368.817144)
		(width 0.14224)
		(layer "In6.Cu")
		(net "P5E_CPU0_P0_TX_DP<14>")
	)
	(segment
		(start 362.782104 -380.817882)
		(end 362.605828 -380.899162)
		(width 0.14224)
		(layer "In6.Cu")
		(net "P5E_CPU0_P0_TX_DP<14>")
	)
	(segment
		(start 358.399334 -288.131758)
		(end 358.360726 -288.159698)
		(width 0.1143)
		(layer "In6.Cu")
		(net "P5E_CPU0_P0_TX_DP<14>")
	)
	(segment
		(start 331.90307 -383.925064)
		(end 331.352652 -383.374646)
		(width 0.14224)
		(layer "In6.Cu")
		(net "P5E_CPU0_P0_TX_DP<14>")
	)
	(segment
		(start 362.818934 -380.320042)
		(end 362.900214 -380.496064)
		(width 0.14224)
		(layer "In6.Cu")
		(net "P5E_CPU0_P0_TX_DP<14>")
	)
	(segment
		(start 328.42581 -384.71602)
		(end 328.41311 -384.72872)
		(width 0.14224)
		(layer "In6.Cu")
		(net "P5E_CPU0_P0_TX_DP<14>")
	)
	(segment
		(start 376.018298 -361.347004)
		(end 375.798588 -361.832906)
		(width 0.14224)
		(layer "In6.Cu")
		(net "P5E_CPU0_P0_TX_DP<14>")
	)
	(segment
		(start 327.568306 -384.766058)
		(end 327.277476 -384.475228)
		(width 0.14224)
		(layer "In6.Cu")
		(net "P5E_CPU0_P0_TX_DP<14>")
	)
	(segment
		(start 365.478314 -311.68594)
		(end 371.70868 -319.277238)
		(width 0.14224)
		(layer "In6.Cu")
		(net "P5E_CPU0_P0_TX_DP<14>")
	)
	(segment
		(start 358.291638 -287.512252)
		(end 358.358694 -287.551368)
		(width 0.1143)
		(layer "In6.Cu")
		(net "P5E_CPU0_P0_TX_DP<14>")
	)
	(segment
		(start 374.818402 -363.72673)
		(end 374.5484 -364.18647)
		(width 0.14224)
		(layer "In6.Cu")
		(net "P5E_CPU0_P0_TX_DP<14>")
	)
	(segment
		(start 358.360726 -288.159698)
		(end 358.289098 -288.201354)
		(width 0.1143)
		(layer "In6.Cu")
		(net "P5E_CPU0_P0_TX_DP<14>")
	)
	(segment
		(start 377.968764 -354.168964)
		(end 377.900946 -354.697792)
		(width 0.14224)
		(layer "In6.Cu")
		(net "P5E_CPU0_P0_TX_DP<14>")
	)
	(segment
		(start 358.045766 -295.507156)
		(end 358.000046 -295.552876)
		(width 0.1143)
		(layer "In6.Cu")
		(net "P5E_CPU0_P0_TX_DP<14>")
	)
	(segment
		(start 372.051326 -367.639092)
		(end 371.699028 -368.039396)
		(width 0.14224)
		(layer "In6.Cu")
		(net "P5E_CPU0_P0_TX_DP<14>")
	)
	(segment
		(start 363.599476 -378.194824)
		(end 363.481112 -378.51715)
		(width 0.14224)
		(layer "In6.Cu")
		(net "P5E_CPU0_P0_TX_DP<14>")
	)
	(segment
		(start 358.328214 -291.418518)
		(end 358.289098 -291.441378)
		(width 0.1143)
		(layer "In6.Cu")
		(net "P5E_CPU0_P0_TX_DP<14>")
	)
	(segment
		(start 362.900214 -380.496064)
		(end 362.782104 -380.817882)
		(width 0.14224)
		(layer "In6.Cu")
		(net "P5E_CPU0_P0_TX_DP<14>")
	)
	(segment
		(start 358.289098 -292.37051)
		(end 358.328214 -292.39337)
		(width 0.1143)
		(layer "In6.Cu")
		(net "P5E_CPU0_P0_TX_DP<14>")
	)
	(segment
		(start 358.328214 -289.153346)
		(end 358.358694 -289.171126)
		(width 0.1143)
		(layer "In6.Cu")
		(net "P5E_CPU0_P0_TX_DP<14>")
	)
	(segment
		(start 377.260612 -357.830628)
		(end 377.115324 -358.343708)
		(width 0.14224)
		(layer "In6.Cu")
		(net "P5E_CPU0_P0_TX_DP<14>")
	)
	(segment
		(start 373.68099 -365.530384)
		(end 373.373142 -365.96574)
		(width 0.14224)
		(layer "In6.Cu")
		(net "P5E_CPU0_P0_TX_DP<14>")
	)
	(arc
		(start 358.045766 -285.42615)
		(mid 358.108411 -285.684829)
		(end 358.282494 -285.886144)
		(width 0.1143)
		(layer "In6.Cu")
		(net "P5E_CPU0_P0_TX_DP<14>")
	)
	(arc
		(start 328.869294 -383.293874)
		(mid 328.595592 -383.703499)
		(end 328.49947 -384.186684)
		(width 0.14224)
		(layer "In6.Cu")
		(net "P5E_CPU0_P0_TX_DP<14>")
	)
	(arc
		(start 358.290622 -294.680132)
		(mid 358.110678 -294.882813)
		(end 358.045766 -295.145968)
		(width 0.1143)
		(layer "In6.Cu")
		(net "P5E_CPU0_P0_TX_DP<14>")
	)
	(arc
		(start 358.3432 -285.92145)
		(mid 358.515183 -286.227638)
		(end 358.357678 -286.541464)
		(width 0.1143)
		(layer "In6.Cu")
		(net "P5E_CPU0_P0_TX_DP<14>")
	)
	(arc
		(start 358.393238 -294.055038)
		(mid 358.540391 -294.334308)
		(end 358.396032 -294.615108)
		(width 0.1143)
		(layer "In6.Cu")
		(net "P5E_CPU0_P0_TX_DP<14>")
	)
	(arc
		(start 358.289098 -289.821366)
		(mid 358.045771 -290.285932)
		(end 358.289098 -290.750498)
		(width 0.1143)
		(layer "In6.Cu")
		(net "P5E_CPU0_P0_TX_DP<14>")
	)
	(arc
		(start 331.352652 -383.374646)
		(mid 330.768573 -382.984377)
		(end 330.079604 -382.847342)
		(width 0.14224)
		(layer "In6.Cu")
		(net "P5E_CPU0_P0_TX_DP<14>")
	)
	(arc
		(start 357.584756 -284.628844)
		(mid 357.657968 -284.902726)
		(end 357.85806 -285.10357)
		(width 0.1143)
		(layer "In6.Cu")
		(net "P5E_CPU0_P0_TX_DP<14>")
	)
	(arc
		(start 358.358694 -289.171126)
		(mid 358.515671 -289.475926)
		(end 358.358694 -289.780726)
		(width 0.1143)
		(layer "In6.Cu")
		(net "P5E_CPU0_P0_TX_DP<14>")
	)
	(arc
		(start 333.698596 -384.668776)
		(mid 332.726872 -384.475488)
		(end 331.90307 -383.925064)
		(width 0.14224)
		(layer "In6.Cu")
		(net "P5E_CPU0_P0_TX_DP<14>")
	)
	(arc
		(start 357.111808 -283.888942)
		(mid 357.113596 -283.900391)
		(end 357.115618 -283.911802)
		(width 0.1143)
		(layer "In6.Cu")
		(net "P5E_CPU0_P0_TX_DP<14>")
	)
	(arc
		(start 358.289098 -288.201354)
		(mid 358.045771 -288.66592)
		(end 358.289098 -289.130486)
		(width 0.1143)
		(layer "In6.Cu")
		(net "P5E_CPU0_P0_TX_DP<14>")
	)
	(arc
		(start 358.289098 -286.581342)
		(mid 358.110285 -286.783692)
		(end 358.045766 -287.045908)
		(width 0.1143)
		(layer "In6.Cu")
		(net "P5E_CPU0_P0_TX_DP<14>")
	)
	(arc
		(start 358.045766 -287.045908)
		(mid 358.111002 -287.309499)
		(end 358.291638 -287.512252)
		(width 0.1143)
		(layer "In6.Cu")
		(net "P5E_CPU0_P0_TX_DP<14>")
	)
	(arc
		(start 358.358694 -287.551368)
		(mid 358.474121 -287.684744)
		(end 358.515666 -287.856168)
		(width 0.1143)
		(layer "In6.Cu")
		(net "P5E_CPU0_P0_TX_DP<14>")
	)
	(arc
		(start 358.358694 -290.791138)
		(mid 358.515671 -291.095938)
		(end 358.358694 -291.400738)
		(width 0.1143)
		(layer "In6.Cu")
		(net "P5E_CPU0_P0_TX_DP<14>")
	)
	(arc
		(start 360.873294 -386.014722)
		(mid 360.617885 -386.346157)
		(end 360.218736 -386.471668)
		(width 0.14224)
		(layer "In6.Cu")
		(net "P5E_CPU0_P0_TX_DP<14>")
	)
	(arc
		(start 357.059738 -385.637786)
		(mid 355.598549 -384.916741)
		(end 353.988116 -384.668776)
		(width 0.14224)
		(layer "In6.Cu")
		(net "P5E_CPU0_P0_TX_DP<14>")
	)
	(arc
		(start 358.515666 -287.90392)
		(mid 358.484893 -288.03182)
		(end 358.399334 -288.131758)
		(width 0.1143)
		(layer "In6.Cu")
		(net "P5E_CPU0_P0_TX_DP<14>")
	)
	(arc
		(start 328.41311 -384.72872)
		(mid 328.37187 -384.756339)
		(end 328.323194 -384.766058)
		(width 0.14224)
		(layer "In6.Cu")
		(net "P5E_CPU0_P0_TX_DP<14>")
	)
	(arc
		(start 358.358694 -292.41115)
		(mid 358.515671 -292.71595)
		(end 358.358694 -293.02075)
		(width 0.1143)
		(layer "In6.Cu")
		(net "P5E_CPU0_P0_TX_DP<14>")
	)
	(arc
		(start 357.88981 -285.121858)
		(mid 358.004486 -285.255192)
		(end 358.045766 -285.42615)
		(width 0.1143)
		(layer "In6.Cu")
		(net "P5E_CPU0_P0_TX_DP<14>")
	)
	(arc
		(start 358.32796 -293.038784)
		(mid 358.048196 -293.526146)
		(end 358.32796 -294.013382)
		(width 0.1143)
		(layer "In6.Cu")
		(net "P5E_CPU0_P0_TX_DP<14>")
	)
	(arc
		(start 366.702086 -373.097298)
		(mid 365.209312 -374.954768)
		(end 364.151164 -377.089924)
		(width 0.14224)
		(layer "In6.Cu")
		(net "P5E_CPU0_P0_TX_DP<14>")
	)
	(arc
		(start 357.39705 -284.298644)
		(mid 357.534482 -284.435903)
		(end 357.584756 -284.62351)
		(width 0.1143)
		(layer "In6.Cu")
		(net "P5E_CPU0_P0_TX_DP<14>")
	)
	(arc
		(start 329.870816 -382.847342)
		(mid 329.358078 -382.949332)
		(end 328.923396 -383.239772)
		(width 0.14224)
		(layer "In6.Cu")
		(net "P5E_CPU0_P0_TX_DP<14>")
	)
	(arc
		(start 358.282494 -285.886144)
		(mid 358.310166 -285.904631)
		(end 358.338882 -285.92145)
		(width 0.1143)
		(layer "In6.Cu")
		(net "P5E_CPU0_P0_TX_DP<14>")
	)
	(arc
		(start 359.702862 -386.471668)
		(mid 358.317091 -386.258251)
		(end 357.059738 -385.637786)
		(width 0.14224)
		(layer "In6.Cu")
		(net "P5E_CPU0_P0_TX_DP<14>")
	)
	(arc
		(start 357.115618 -283.911802)
		(mid 357.197051 -284.1142)
		(end 357.349044 -284.270704)
		(width 0.1143)
		(layer "In6.Cu")
		(net "P5E_CPU0_P0_TX_DP<14>")
	)
	(arc
		(start 358.289098 -291.441378)
		(mid 358.045771 -291.905944)
		(end 358.289098 -292.37051)
		(width 0.1143)
		(layer "In6.Cu")
		(net "P5E_CPU0_P0_TX_DP<14>")
	)
	(segment
		(start 325.134986 -378.39142)
		(end 325.134986 -377.68784)
		(width 0.12954)
		(layer "F.Cu")
		(net "P5E_CPU0_P0_TX_DP<13>")
	)
	(segment
		(start 325.134986 -377.68784)
		(end 325.405496 -377.41733)
		(width 0.12954)
		(layer "F.Cu")
		(net "P5E_CPU0_P0_TX_DP<13>")
	)
	(segment
		(start 325.430896 -378.68733)
		(end 325.134986 -378.39142)
		(width 0.12954)
		(layer "F.Cu")
		(net "P5E_CPU0_P0_TX_DP<13>")
	)
	(segment
		(start 357.197914 -285.160212)
		(end 356.731062 -285.42615)
		(width 0.12954)
		(layer "F.Cu")
		(net "P5E_CPU0_P0_TX_DP<13>")
	)
	(segment
		(start 357.38816 -289.798506)
		(end 357.388922 -289.797998)
		(width 0.1143)
		(layer "In6.Cu")
		(net "P5E_CPU0_P0_TX_DP<13>")
	)
	(segment
		(start 357.388922 -292.393878)
		(end 357.38816 -292.39337)
		(width 0.1143)
		(layer "In6.Cu")
		(net "P5E_CPU0_P0_TX_DP<13>")
	)
	(segment
		(start 361.415838 -378.96165)
		(end 361.549188 -378.64034)
		(width 0.14224)
		(layer "In6.Cu")
		(net "P5E_CPU0_P0_TX_DP<13>")
	)
	(segment
		(start 334.532732 -383.476754)
		(end 334.959452 -383.476754)
		(width 0.14224)
		(layer "In6.Cu")
		(net "P5E_CPU0_P0_TX_DP<13>")
	)
	(segment
		(start 357.539544 -287.637982)
		(end 357.41991 -287.551876)
		(width 0.1143)
		(layer "In6.Cu")
		(net "P5E_CPU0_P0_TX_DP<13>")
	)
	(segment
		(start 357.373174 -294.004746)
		(end 357.35006 -293.991284)
		(width 0.1143)
		(layer "In6.Cu")
		(net "P5E_CPU0_P0_TX_DP<13>")
	)
	(segment
		(start 357.105712 -295.473882)
		(end 357.105458 -295.473628)
		(width 0.1143)
		(layer "In6.Cu")
		(net "P5E_CPU0_P0_TX_DP<13>")
	)
	(segment
		(start 338.079334 -383.613914)
		(end 338.216494 -383.476754)
		(width 0.14224)
		(layer "In6.Cu")
		(net "P5E_CPU0_P0_TX_DP<13>")
	)
	(segment
		(start 357.38816 -291.418518)
		(end 357.388922 -291.41801)
		(width 0.1143)
		(layer "In6.Cu")
		(net "P5E_CPU0_P0_TX_DP<13>")
	)
	(segment
		(start 357.375968 -294.006524)
		(end 357.373174 -294.004746)
		(width 0.1143)
		(layer "In6.Cu")
		(net "P5E_CPU0_P0_TX_DP<13>")
	)
	(segment
		(start 325.405496 -377.41733)
		(end 325.114666 -377.70816)
		(width 0.14224)
		(layer "In6.Cu")
		(net "P5E_CPU0_P0_TX_DP<13>")
	)
	(segment
		(start 357.409496 -294.646096)
		(end 357.410004 -294.646096)
		(width 0.1143)
		(layer "In6.Cu")
		(net "P5E_CPU0_P0_TX_DP<13>")
	)
	(segment
		(start 328.178414 -378.869448)
		(end 328.37247 -378.869448)
		(width 0.14224)
		(layer "In6.Cu")
		(net "P5E_CPU0_P0_TX_DP<13>")
	)
	(segment
		(start 357.40975 -285.926022)
		(end 357.409496 -285.926022)
		(width 0.1143)
		(layer "In6.Cu")
		(net "P5E_CPU0_P0_TX_DP<13>")
	)
	(segment
		(start 357.372666 -293.047166)
		(end 357.38816 -293.03853)
		(width 0.1143)
		(layer "In6.Cu")
		(net "P5E_CPU0_P0_TX_DP<13>")
	)
	(segment
		(start 325.114666 -377.70816)
		(end 325.114666 -378.31649)
		(width 0.14224)
		(layer "In6.Cu")
		(net "P5E_CPU0_P0_TX_DP<13>")
	)
	(segment
		(start 336.224372 -383.613914)
		(end 338.079334 -383.613914)
		(width 0.14224)
		(layer "In6.Cu")
		(net "P5E_CPU0_P0_TX_DP<13>")
	)
	(segment
		(start 357.347774 -293.062152)
		(end 357.372666 -293.047166)
		(width 0.1143)
		(layer "In6.Cu")
		(net "P5E_CPU0_P0_TX_DP<13>")
	)
	(segment
		(start 338.643214 -383.476754)
		(end 338.780374 -383.613914)
		(width 0.14224)
		(layer "In6.Cu")
		(net "P5E_CPU0_P0_TX_DP<13>")
	)
	(segment
		(start 329.773534 -380.464568)
		(end 329.96759 -380.464568)
		(width 0.14224)
		(layer "In6.Cu")
		(net "P5E_CPU0_P0_TX_DP<13>")
	)
	(segment
		(start 331.067156 -381.564134)
		(end 331.067156 -381.75819)
		(width 0.14224)
		(layer "In6.Cu")
		(net "P5E_CPU0_P0_TX_DP<13>")
	)
	(segment
		(start 365.017812 -373.44985)
		(end 370.121434 -368.346228)
		(width 0.14224)
		(layer "In6.Cu")
		(net "P5E_CPU0_P0_TX_DP<13>")
	)
	(segment
		(start 331.864716 -382.361694)
		(end 331.864716 -382.55575)
		(width 0.14224)
		(layer "In6.Cu")
		(net "P5E_CPU0_P0_TX_DP<13>")
	)
	(segment
		(start 357.38816 -293.03853)
		(end 357.388922 -293.038022)
		(width 0.1143)
		(layer "In6.Cu")
		(net "P5E_CPU0_P0_TX_DP<13>")
	)
	(segment
		(start 377.206002 -339.19287)
		(end 375.29135 -328.534014)
		(width 0.14224)
		(layer "In6.Cu")
		(net "P5E_CPU0_P0_TX_DP<13>")
	)
	(segment
		(start 357.409496 -286.54629)
		(end 357.410004 -286.54629)
		(width 0.1143)
		(layer "In6.Cu")
		(net "P5E_CPU0_P0_TX_DP<13>")
	)
	(segment
		(start 331.067156 -381.75819)
		(end 331.368654 -382.059688)
		(width 0.14224)
		(layer "In6.Cu")
		(net "P5E_CPU0_P0_TX_DP<13>")
	)
	(segment
		(start 328.674476 -379.36551)
		(end 328.975974 -379.667008)
		(width 0.14224)
		(layer "In6.Cu")
		(net "P5E_CPU0_P0_TX_DP<13>")
	)
	(segment
		(start 357.439722 -292.425882)
		(end 357.41991 -292.411658)
		(width 0.1143)
		(layer "In6.Cu")
		(net "P5E_CPU0_P0_TX_DP<13>")
	)
	(segment
		(start 357.349044 -288.201354)
		(end 357.421688 -288.158936)
		(width 0.1143)
		(layer "In6.Cu")
		(net "P5E_CPU0_P0_TX_DP<13>")
	)
	(segment
		(start 357.059992 -295.519602)
		(end 357.105712 -295.473882)
		(width 0.1143)
		(layer "In6.Cu")
		(net "P5E_CPU0_P0_TX_DP<13>")
	)
	(segment
		(start 357.356664 -289.135058)
		(end 357.355902 -289.13455)
		(width 0.1143)
		(layer "In6.Cu")
		(net "P5E_CPU0_P0_TX_DP<13>")
	)
	(segment
		(start 357.387144 -289.152838)
		(end 357.356664 -289.135058)
		(width 0.1143)
		(layer "In6.Cu")
		(net "P5E_CPU0_P0_TX_DP<13>")
	)
	(segment
		(start 377.206002 -351.24263)
		(end 377.206002 -339.19287)
		(width 0.14224)
		(layer "In6.Cu")
		(net "P5E_CPU0_P0_TX_DP<13>")
	)
	(segment
		(start 326.750934 -378.35205)
		(end 326.752712 -378.351542)
		(width 0.14224)
		(layer "In6.Cu")
		(net "P5E_CPU0_P0_TX_DP<13>")
	)
	(segment
		(start 357.349806 -294.680894)
		(end 357.409496 -294.646096)
		(width 0.1143)
		(layer "In6.Cu")
		(net "P5E_CPU0_P0_TX_DP<13>")
	)
	(segment
		(start 357.349044 -289.821366)
		(end 357.38562 -289.80003)
		(width 0.1143)
		(layer "In6.Cu")
		(net "P5E_CPU0_P0_TX_DP<13>")
	)
	(segment
		(start 357.387144 -292.392862)
		(end 357.349044 -292.37051)
		(width 0.1143)
		(layer "In6.Cu")
		(net "P5E_CPU0_P0_TX_DP<13>")
	)
	(segment
		(start 357.41991 -293.020242)
		(end 357.439722 -293.006018)
		(width 0.1143)
		(layer "In6.Cu")
		(net "P5E_CPU0_P0_TX_DP<13>")
	)
	(segment
		(start 327.876916 -378.56795)
		(end 328.178414 -378.869448)
		(width 0.14224)
		(layer "In6.Cu")
		(net "P5E_CPU0_P0_TX_DP<13>")
	)
	(segment
		(start 335.660492 -383.476754)
		(end 336.087212 -383.476754)
		(width 0.14224)
		(layer "In6.Cu")
		(net "P5E_CPU0_P0_TX_DP<13>")
	)
	(segment
		(start 360.581194 -381.233426)
		(end 361.41025 -378.977144)
		(width 0.14224)
		(layer "In6.Cu")
		(net "P5E_CPU0_P0_TX_DP<13>")
	)
	(segment
		(start 334.959452 -383.476754)
		(end 335.096612 -383.613914)
		(width 0.14224)
		(layer "In6.Cu")
		(net "P5E_CPU0_P0_TX_DP<13>")
	)
	(segment
		(start 375.29135 -328.534014)
		(end 374.906794 -327.410318)
		(width 0.14224)
		(layer "In6.Cu")
		(net "P5E_CPU0_P0_TX_DP<13>")
	)
	(segment
		(start 357.029004 -285.42615)
		(end 356.731062 -285.42615)
		(width 0.1143)
		(layer "In6.Cu")
		(net "P5E_CPU0_P0_TX_DP<13>")
	)
	(segment
		(start 338.216494 -383.476754)
		(end 338.643214 -383.476754)
		(width 0.14224)
		(layer "In6.Cu")
		(net "P5E_CPU0_P0_TX_DP<13>")
	)
	(segment
		(start 357.409496 -285.926022)
		(end 357.3907 -285.914846)
		(width 0.1143)
		(layer "In6.Cu")
		(net "P5E_CPU0_P0_TX_DP<13>")
	)
	(segment
		(start 357.41991 -289.171634)
		(end 357.388922 -289.153854)
		(width 0.1143)
		(layer "In6.Cu")
		(net "P5E_CPU0_P0_TX_DP<13>")
	)
	(segment
		(start 331.56271 -382.059688)
		(end 331.864716 -382.361694)
		(width 0.14224)
		(layer "In6.Cu")
		(net "P5E_CPU0_P0_TX_DP<13>")
	)
	(segment
		(start 329.472036 -380.16307)
		(end 329.773534 -380.464568)
		(width 0.14224)
		(layer "In6.Cu")
		(net "P5E_CPU0_P0_TX_DP<13>")
	)
	(segment
		(start 357.346758 -286.582866)
		(end 357.347012 -286.582866)
		(width 0.1143)
		(layer "In6.Cu")
		(net "P5E_CPU0_P0_TX_DP<13>")
	)
	(segment
		(start 357.38816 -290.773358)
		(end 357.387144 -290.77285)
		(width 0.1143)
		(layer "In6.Cu")
		(net "P5E_CPU0_P0_TX_DP<13>")
	)
	(segment
		(start 338.780374 -383.613914)
		(end 357.782622 -383.613914)
		(width 0.14224)
		(layer "In6.Cu")
		(net "P5E_CPU0_P0_TX_DP<13>")
	)
	(segment
		(start 357.388922 -291.41801)
		(end 357.41991 -291.40023)
		(width 0.1143)
		(layer "In6.Cu")
		(net "P5E_CPU0_P0_TX_DP<13>")
	)
	(segment
		(start 357.38816 -289.153346)
		(end 357.387144 -289.152838)
		(width 0.1143)
		(layer "In6.Cu")
		(net "P5E_CPU0_P0_TX_DP<13>")
	)
	(segment
		(start 357.355902 -285.89478)
		(end 357.349044 -285.890716)
		(width 0.1143)
		(layer "In6.Cu")
		(net "P5E_CPU0_P0_TX_DP<13>")
	)
	(segment
		(start 326.341994 -378.351288)
		(end 326.737218 -378.351288)
		(width 0.14224)
		(layer "In6.Cu")
		(net "P5E_CPU0_P0_TX_DP<13>")
	)
	(segment
		(start 330.76515 -381.262128)
		(end 331.067156 -381.564134)
		(width 0.14224)
		(layer "In6.Cu")
		(net "P5E_CPU0_P0_TX_DP<13>")
	)
	(segment
		(start 331.864716 -382.55575)
		(end 332.542642 -383.233676)
		(width 0.14224)
		(layer "In6.Cu")
		(net "P5E_CPU0_P0_TX_DP<13>")
	)
	(segment
		(start 331.368654 -382.059688)
		(end 331.56271 -382.059688)
		(width 0.14224)
		(layer "In6.Cu")
		(net "P5E_CPU0_P0_TX_DP<13>")
	)
	(segment
		(start 357.355902 -289.13455)
		(end 357.349044 -289.130486)
		(width 0.1143)
		(layer "In6.Cu")
		(net "P5E_CPU0_P0_TX_DP<13>")
	)
	(segment
		(start 364.948216 -312.578242)
		(end 359.38587 -304.254154)
		(width 0.14224)
		(layer "In6.Cu")
		(net "P5E_CPU0_P0_TX_DP<13>")
	)
	(segment
		(start 371.023896 -319.981072)
		(end 364.948216 -312.578242)
		(width 0.14224)
		(layer "In6.Cu")
		(net "P5E_CPU0_P0_TX_DP<13>")
	)
	(segment
		(start 329.472036 -379.969014)
		(end 329.472036 -380.16307)
		(width 0.14224)
		(layer "In6.Cu")
		(net "P5E_CPU0_P0_TX_DP<13>")
	)
	(segment
		(start 357.349044 -291.441378)
		(end 357.38562 -291.420042)
		(width 0.1143)
		(layer "In6.Cu")
		(net "P5E_CPU0_P0_TX_DP<13>")
	)
	(segment
		(start 361.416092 -378.96165)
		(end 361.415838 -378.96165)
		(width 0.14224)
		(layer "In6.Cu")
		(net "P5E_CPU0_P0_TX_DP<13>")
	)
	(segment
		(start 336.087212 -383.476754)
		(end 336.224372 -383.613914)
		(width 0.14224)
		(layer "In6.Cu")
		(net "P5E_CPU0_P0_TX_DP<13>")
	)
	(segment
		(start 357.40975 -294.025828)
		(end 357.409496 -294.025828)
		(width 0.1143)
		(layer "In6.Cu")
		(net "P5E_CPU0_P0_TX_DP<13>")
	)
	(segment
		(start 329.17003 -379.667008)
		(end 329.472036 -379.969014)
		(width 0.14224)
		(layer "In6.Cu")
		(net "P5E_CPU0_P0_TX_DP<13>")
	)
	(segment
		(start 357.388922 -289.153854)
		(end 357.38816 -289.153346)
		(width 0.1143)
		(layer "In6.Cu")
		(net "P5E_CPU0_P0_TX_DP<13>")
	)
	(segment
		(start 325.40448 -378.52985)
		(end 325.702422 -378.52985)
		(width 0.14224)
		(layer "In6.Cu")
		(net "P5E_CPU0_P0_TX_DP<13>")
	)
	(segment
		(start 326.758808 -378.35205)
		(end 327.355708 -378.35205)
		(width 0.14224)
		(layer "In6.Cu")
		(net "P5E_CPU0_P0_TX_DP<13>")
	)
	(segment
		(start 357.575866 -287.856168)
		(end 357.575866 -287.709102)
		(width 0.1143)
		(layer "In6.Cu")
		(net "P5E_CPU0_P0_TX_DP<13>")
	)
	(segment
		(start 357.387144 -290.77285)
		(end 357.349044 -290.750498)
		(width 0.1143)
		(layer "In6.Cu")
		(net "P5E_CPU0_P0_TX_DP<13>")
	)
	(segment
		(start 359.38587 -304.254154)
		(end 357.059992 -298.638722)
		(width 0.14224)
		(layer "In6.Cu")
		(net "P5E_CPU0_P0_TX_DP<13>")
	)
	(segment
		(start 357.41991 -289.780218)
		(end 357.439722 -289.765994)
		(width 0.1143)
		(layer "In6.Cu")
		(net "P5E_CPU0_P0_TX_DP<13>")
	)
	(segment
		(start 326.752712 -378.351542)
		(end 326.758808 -378.35205)
		(width 0.14224)
		(layer "In6.Cu")
		(net "P5E_CPU0_P0_TX_DP<13>")
	)
	(segment
		(start 357.059992 -298.638722)
		(end 357.059992 -295.54805)
		(width 0.14224)
		(layer "In6.Cu")
		(net "P5E_CPU0_P0_TX_DP<13>")
	)
	(segment
		(start 357.38816 -292.39337)
		(end 357.387144 -292.392862)
		(width 0.1143)
		(layer "In6.Cu")
		(net "P5E_CPU0_P0_TX_DP<13>")
	)
	(segment
		(start 328.975974 -379.667008)
		(end 329.17003 -379.667008)
		(width 0.14224)
		(layer "In6.Cu")
		(net "P5E_CPU0_P0_TX_DP<13>")
	)
	(segment
		(start 357.059992 -295.54805)
		(end 357.059992 -295.519602)
		(width 0.1143)
		(layer "In6.Cu")
		(net "P5E_CPU0_P0_TX_DP<13>")
	)
	(segment
		(start 357.38816 -287.533588)
		(end 357.351584 -287.512252)
		(width 0.1143)
		(layer "In6.Cu")
		(net "P5E_CPU0_P0_TX_DP<13>")
	)
	(segment
		(start 357.356664 -285.895288)
		(end 357.355902 -285.89478)
		(width 0.1143)
		(layer "In6.Cu")
		(net "P5E_CPU0_P0_TX_DP<13>")
	)
	(segment
		(start 357.408734 -294.02532)
		(end 357.375968 -294.006524)
		(width 0.1143)
		(layer "In6.Cu")
		(net "P5E_CPU0_P0_TX_DP<13>")
	)
	(segment
		(start 333.460598 -383.613914)
		(end 334.395572 -383.613914)
		(width 0.14224)
		(layer "In6.Cu")
		(net "P5E_CPU0_P0_TX_DP<13>")
	)
	(segment
		(start 357.387144 -289.799014)
		(end 357.38816 -289.798506)
		(width 0.1143)
		(layer "In6.Cu")
		(net "P5E_CPU0_P0_TX_DP<13>")
	)
	(segment
		(start 357.41991 -287.551876)
		(end 357.38816 -287.533588)
		(width 0.1143)
		(layer "In6.Cu")
		(net "P5E_CPU0_P0_TX_DP<13>")
	)
	(segment
		(start 328.37247 -378.869448)
		(end 328.674476 -379.171454)
		(width 0.14224)
		(layer "In6.Cu")
		(net "P5E_CPU0_P0_TX_DP<13>")
	)
	(segment
		(start 357.347012 -286.582866)
		(end 357.409496 -286.54629)
		(width 0.1143)
		(layer "In6.Cu")
		(net "P5E_CPU0_P0_TX_DP<13>")
	)
	(segment
		(start 357.41991 -292.411658)
		(end 357.388922 -292.393878)
		(width 0.1143)
		(layer "In6.Cu")
		(net "P5E_CPU0_P0_TX_DP<13>")
	)
	(segment
		(start 357.38562 -289.80003)
		(end 357.387144 -289.799014)
		(width 0.1143)
		(layer "In6.Cu")
		(net "P5E_CPU0_P0_TX_DP<13>")
	)
	(segment
		(start 329.96759 -380.464568)
		(end 330.269596 -380.766574)
		(width 0.14224)
		(layer "In6.Cu")
		(net "P5E_CPU0_P0_TX_DP<13>")
	)
	(segment
		(start 335.523332 -383.613914)
		(end 335.660492 -383.476754)
		(width 0.14224)
		(layer "In6.Cu")
		(net "P5E_CPU0_P0_TX_DP<13>")
	)
	(segment
		(start 357.3907 -285.914846)
		(end 357.387144 -285.913068)
		(width 0.1143)
		(layer "In6.Cu")
		(net "P5E_CPU0_P0_TX_DP<13>")
	)
	(segment
		(start 330.269596 -380.96063)
		(end 330.571094 -381.262128)
		(width 0.14224)
		(layer "In6.Cu")
		(net "P5E_CPU0_P0_TX_DP<13>")
	)
	(segment
		(start 357.387144 -285.913068)
		(end 357.356664 -285.895288)
		(width 0.1143)
		(layer "In6.Cu")
		(net "P5E_CPU0_P0_TX_DP<13>")
	)
	(segment
		(start 357.439722 -289.185858)
		(end 357.41991 -289.171634)
		(width 0.1143)
		(layer "In6.Cu")
		(net "P5E_CPU0_P0_TX_DP<13>")
	)
	(segment
		(start 334.395572 -383.613914)
		(end 334.532732 -383.476754)
		(width 0.14224)
		(layer "In6.Cu")
		(net "P5E_CPU0_P0_TX_DP<13>")
	)
	(segment
		(start 357.388922 -293.038022)
		(end 357.41991 -293.020242)
		(width 0.1143)
		(layer "In6.Cu")
		(net "P5E_CPU0_P0_TX_DP<13>")
	)
	(segment
		(start 330.269596 -380.766574)
		(end 330.269596 -380.96063)
		(width 0.14224)
		(layer "In6.Cu")
		(net "P5E_CPU0_P0_TX_DP<13>")
	)
	(segment
		(start 357.41991 -290.791646)
		(end 357.388922 -290.773866)
		(width 0.1143)
		(layer "In6.Cu")
		(net "P5E_CPU0_P0_TX_DP<13>")
	)
	(segment
		(start 357.409496 -294.025828)
		(end 357.408734 -294.02532)
		(width 0.1143)
		(layer "In6.Cu")
		(net "P5E_CPU0_P0_TX_DP<13>")
	)
	(segment
		(start 328.674476 -379.171454)
		(end 328.674476 -379.36551)
		(width 0.14224)
		(layer "In6.Cu")
		(net "P5E_CPU0_P0_TX_DP<13>")
	)
	(segment
		(start 357.105458 -295.394888)
		(end 357.105966 -295.39438)
		(width 0.1143)
		(layer "In6.Cu")
		(net "P5E_CPU0_P0_TX_DP<13>")
	)
	(segment
		(start 357.388922 -290.773866)
		(end 357.38816 -290.773358)
		(width 0.1143)
		(layer "In6.Cu")
		(net "P5E_CPU0_P0_TX_DP<13>")
	)
	(segment
		(start 335.096612 -383.613914)
		(end 335.523332 -383.613914)
		(width 0.14224)
		(layer "In6.Cu")
		(net "P5E_CPU0_P0_TX_DP<13>")
	)
	(segment
		(start 357.388922 -289.797998)
		(end 357.41991 -289.780218)
		(width 0.1143)
		(layer "In6.Cu")
		(net "P5E_CPU0_P0_TX_DP<13>")
	)
	(segment
		(start 357.38562 -291.420042)
		(end 357.387144 -291.419026)
		(width 0.1143)
		(layer "In6.Cu")
		(net "P5E_CPU0_P0_TX_DP<13>")
	)
	(segment
		(start 357.105966 -295.39438)
		(end 357.105966 -295.145968)
		(width 0.1143)
		(layer "In6.Cu")
		(net "P5E_CPU0_P0_TX_DP<13>")
	)
	(segment
		(start 374.906794 -327.410318)
		(end 371.023896 -319.981072)
		(width 0.14224)
		(layer "In6.Cu")
		(net "P5E_CPU0_P0_TX_DP<13>")
	)
	(segment
		(start 357.111808 -285.508954)
		(end 357.029004 -285.42615)
		(width 0.1143)
		(layer "In6.Cu")
		(net "P5E_CPU0_P0_TX_DP<13>")
	)
	(segment
		(start 330.571094 -381.262128)
		(end 330.76515 -381.262128)
		(width 0.14224)
		(layer "In6.Cu")
		(net "P5E_CPU0_P0_TX_DP<13>")
	)
	(segment
		(start 357.387144 -291.419026)
		(end 357.38816 -291.418518)
		(width 0.1143)
		(layer "In6.Cu")
		(net "P5E_CPU0_P0_TX_DP<13>")
	)
	(segment
		(start 357.105458 -295.473628)
		(end 357.105458 -295.394888)
		(width 0.1143)
		(layer "In6.Cu")
		(net "P5E_CPU0_P0_TX_DP<13>")
	)
	(arc
		(start 332.542642 -383.233676)
		(mid 332.963804 -383.515087)
		(end 333.460598 -383.613914)
		(width 0.14224)
		(layer "In6.Cu")
		(net "P5E_CPU0_P0_TX_DP<13>")
	)
	(arc
		(start 357.410004 -286.54629)
		(mid 357.58842 -286.236046)
		(end 357.40975 -285.926022)
		(width 0.1143)
		(layer "In6.Cu")
		(net "P5E_CPU0_P0_TX_DP<13>")
	)
	(arc
		(start 326.737218 -378.351288)
		(mid 326.744086 -378.351488)
		(end 326.750934 -378.35205)
		(width 0.14224)
		(layer "In6.Cu")
		(net "P5E_CPU0_P0_TX_DP<13>")
	)
	(arc
		(start 357.351584 -287.512252)
		(mid 357.105701 -287.048832)
		(end 357.346758 -286.582866)
		(width 0.1143)
		(layer "In6.Cu")
		(net "P5E_CPU0_P0_TX_DP<13>")
	)
	(arc
		(start 325.86041 -378.485908)
		(mid 326.091976 -378.385585)
		(end 326.341994 -378.351288)
		(width 0.14224)
		(layer "In6.Cu")
		(net "P5E_CPU0_P0_TX_DP<13>")
	)
	(arc
		(start 327.355708 -378.35205)
		(mid 327.637787 -378.408159)
		(end 327.876916 -378.56795)
		(width 0.14224)
		(layer "In6.Cu")
		(net "P5E_CPU0_P0_TX_DP<13>")
	)
	(arc
		(start 325.702422 -378.52985)
		(mid 325.784436 -378.518731)
		(end 325.86041 -378.485908)
		(width 0.14224)
		(layer "In6.Cu")
		(net "P5E_CPU0_P0_TX_DP<13>")
	)
	(arc
		(start 361.41025 -378.977144)
		(mid 361.413093 -378.969367)
		(end 361.416092 -378.96165)
		(width 0.14224)
		(layer "In6.Cu")
		(net "P5E_CPU0_P0_TX_DP<13>")
	)
	(arc
		(start 357.575866 -287.709102)
		(mid 357.566267 -287.669164)
		(end 357.539544 -287.637982)
		(width 0.1143)
		(layer "In6.Cu")
		(net "P5E_CPU0_P0_TX_DP<13>")
	)
	(arc
		(start 325.114666 -378.31649)
		(mid 325.126808 -378.377533)
		(end 325.161402 -378.429266)
		(width 0.14224)
		(layer "In6.Cu")
		(net "P5E_CPU0_P0_TX_DP<13>")
	)
	(arc
		(start 357.439722 -289.765994)
		(mid 357.588436 -289.475926)
		(end 357.439722 -289.185858)
		(width 0.1143)
		(layer "In6.Cu")
		(net "P5E_CPU0_P0_TX_DP<13>")
	)
	(arc
		(start 357.782622 -383.613914)
		(mid 358.723989 -383.427088)
		(end 359.522776 -382.895094)
		(width 0.14224)
		(layer "In6.Cu")
		(net "P5E_CPU0_P0_TX_DP<13>")
	)
	(arc
		(start 357.115618 -285.531814)
		(mid 357.113595 -285.520404)
		(end 357.111808 -285.508954)
		(width 0.1143)
		(layer "In6.Cu")
		(net "P5E_CPU0_P0_TX_DP<13>")
	)
	(arc
		(start 325.161402 -378.429266)
		(mid 325.272928 -378.503755)
		(end 325.40448 -378.52985)
		(width 0.14224)
		(layer "In6.Cu")
		(net "P5E_CPU0_P0_TX_DP<13>")
	)
	(arc
		(start 357.421688 -288.158936)
		(mid 357.535095 -288.026047)
		(end 357.575866 -287.856168)
		(width 0.1143)
		(layer "In6.Cu")
		(net "P5E_CPU0_P0_TX_DP<13>")
	)
	(arc
		(start 370.121434 -368.346228)
		(mid 375.364764 -360.499031)
		(end 377.206002 -351.24263)
		(width 0.14224)
		(layer "In6.Cu")
		(net "P5E_CPU0_P0_TX_DP<13>")
	)
	(arc
		(start 357.41991 -291.40023)
		(mid 357.570295 -291.095938)
		(end 357.41991 -290.791646)
		(width 0.1143)
		(layer "In6.Cu")
		(net "P5E_CPU0_P0_TX_DP<13>")
	)
	(arc
		(start 357.349044 -292.37051)
		(mid 357.105717 -291.905944)
		(end 357.349044 -291.441378)
		(width 0.1143)
		(layer "In6.Cu")
		(net "P5E_CPU0_P0_TX_DP<13>")
	)
	(arc
		(start 357.105966 -295.145968)
		(mid 357.170625 -294.883411)
		(end 357.349806 -294.680894)
		(width 0.1143)
		(layer "In6.Cu")
		(net "P5E_CPU0_P0_TX_DP<13>")
	)
	(arc
		(start 361.549188 -378.64034)
		(mid 363.027956 -375.874324)
		(end 365.017812 -373.44985)
		(width 0.14224)
		(layer "In6.Cu")
		(net "P5E_CPU0_P0_TX_DP<13>")
	)
	(arc
		(start 357.349044 -290.750498)
		(mid 357.105717 -290.285932)
		(end 357.349044 -289.821366)
		(width 0.1143)
		(layer "In6.Cu")
		(net "P5E_CPU0_P0_TX_DP<13>")
	)
	(arc
		(start 357.439722 -293.006018)
		(mid 357.588436 -292.71595)
		(end 357.439722 -292.425882)
		(width 0.1143)
		(layer "In6.Cu")
		(net "P5E_CPU0_P0_TX_DP<13>")
	)
	(arc
		(start 357.349044 -285.890716)
		(mid 357.197057 -285.734208)
		(end 357.115618 -285.531814)
		(width 0.1143)
		(layer "In6.Cu")
		(net "P5E_CPU0_P0_TX_DP<13>")
	)
	(arc
		(start 357.410004 -294.646096)
		(mid 357.58842 -294.335852)
		(end 357.40975 -294.025828)
		(width 0.1143)
		(layer "In6.Cu")
		(net "P5E_CPU0_P0_TX_DP<13>")
	)
	(arc
		(start 357.349044 -289.130486)
		(mid 357.105717 -288.66592)
		(end 357.349044 -288.201354)
		(width 0.1143)
		(layer "In6.Cu")
		(net "P5E_CPU0_P0_TX_DP<13>")
	)
	(arc
		(start 357.35006 -293.991284)
		(mid 357.10578 -293.527329)
		(end 357.347774 -293.062152)
		(width 0.1143)
		(layer "In6.Cu")
		(net "P5E_CPU0_P0_TX_DP<13>")
	)
	(arc
		(start 359.522776 -382.895094)
		(mid 360.126946 -382.112007)
		(end 360.581194 -381.233426)
		(width 0.14224)
		(layer "In6.Cu")
		(net "P5E_CPU0_P0_TX_DP<13>")
	)
	(segment
		(start 321.408806 -377.68784)
		(end 321.138296 -377.41733)
		(width 0.12954)
		(layer "F.Cu")
		(net "P5E_CPU0_P0_TX_DP<12>")
	)
	(segment
		(start 354.847906 -282.730194)
		(end 354.381054 -282.996132)
		(width 0.12954)
		(layer "F.Cu")
		(net "P5E_CPU0_P0_TX_DP<12>")
	)
	(segment
		(start 321.112896 -378.68733)
		(end 321.408806 -378.39142)
		(width 0.12954)
		(layer "F.Cu")
		(net "P5E_CPU0_P0_TX_DP<12>")
	)
	(segment
		(start 321.408806 -378.39142)
		(end 321.408806 -377.68784)
		(width 0.12954)
		(layer "F.Cu")
		(net "P5E_CPU0_P0_TX_DP<12>")
	)
	(segment
		(start 356.448106 -289.153346)
		(end 356.448868 -289.153854)
		(width 0.1143)
		(layer "In6.Cu")
		(net "P5E_CPU0_P0_TX_DP<12>")
	)
	(segment
		(start 356.448106 -290.773358)
		(end 356.448868 -290.773866)
		(width 0.1143)
		(layer "In6.Cu")
		(net "P5E_CPU0_P0_TX_DP<12>")
	)
	(segment
		(start 356.448106 -288.178494)
		(end 356.40899 -288.201354)
		(width 0.1143)
		(layer "In6.Cu")
		(net "P5E_CPU0_P0_TX_DP<12>")
	)
	(segment
		(start 356.415848 -290.754562)
		(end 356.41661 -290.75507)
		(width 0.1143)
		(layer "In6.Cu")
		(net "P5E_CPU0_P0_TX_DP<12>")
	)
	(segment
		(start 356.452424 -289.155886)
		(end 356.453948 -289.156648)
		(width 0.1143)
		(layer "In6.Cu")
		(net "P5E_CPU0_P0_TX_DP<12>")
	)
	(segment
		(start 356.445566 -289.80003)
		(end 356.44455 -289.800538)
		(width 0.1143)
		(layer "In6.Cu")
		(net "P5E_CPU0_P0_TX_DP<12>")
	)
	(segment
		(start 356.451662 -292.395402)
		(end 356.452424 -292.39591)
		(width 0.1143)
		(layer "In6.Cu")
		(net "P5E_CPU0_P0_TX_DP<12>")
	)
	(segment
		(start 356.481634 -286.538924)
		(end 356.448106 -286.558482)
		(width 0.1143)
		(layer "In6.Cu")
		(net "P5E_CPU0_P0_TX_DP<12>")
	)
	(segment
		(start 356.451662 -290.77539)
		(end 356.452424 -290.775898)
		(width 0.1143)
		(layer "In6.Cu")
		(net "P5E_CPU0_P0_TX_DP<12>")
	)
	(segment
		(start 356.45598 -289.157918)
		(end 356.45852 -289.159188)
		(width 0.1143)
		(layer "In6.Cu")
		(net "P5E_CPU0_P0_TX_DP<12>")
	)
	(segment
		(start 356.165912 -295.411144)
		(end 356.165404 -295.411652)
		(width 0.1143)
		(layer "In6.Cu")
		(net "P5E_CPU0_P0_TX_DP<12>")
	)
	(segment
		(start 356.40899 -285.890716)
		(end 356.415848 -285.89478)
		(width 0.1143)
		(layer "In6.Cu")
		(net "P5E_CPU0_P0_TX_DP<12>")
	)
	(segment
		(start 356.442264 -289.801808)
		(end 356.40899 -289.821366)
		(width 0.1143)
		(layer "In6.Cu")
		(net "P5E_CPU0_P0_TX_DP<12>")
	)
	(segment
		(start 356.44709 -293.039038)
		(end 356.445566 -293.040054)
		(width 0.1143)
		(layer "In6.Cu")
		(net "P5E_CPU0_P0_TX_DP<12>")
	)
	(segment
		(start 356.451662 -285.915608)
		(end 356.452424 -285.916116)
		(width 0.1143)
		(layer "In6.Cu")
		(net "P5E_CPU0_P0_TX_DP<12>")
	)
	(segment
		(start 356.44328 -293.041324)
		(end 356.442264 -293.041832)
		(width 0.1143)
		(layer "In6.Cu")
		(net "P5E_CPU0_P0_TX_DP<12>")
	)
	(segment
		(start 356.44201 -294.662098)
		(end 356.441248 -294.662606)
		(width 0.1143)
		(layer "In6.Cu")
		(net "P5E_CPU0_P0_TX_DP<12>")
	)
	(segment
		(start 356.441248 -294.662606)
		(end 356.409244 -294.681148)
		(width 0.1143)
		(layer "In6.Cu")
		(net "P5E_CPU0_P0_TX_DP<12>")
	)
	(segment
		(start 356.448106 -291.418518)
		(end 356.44709 -291.419026)
		(width 0.1143)
		(layer "In6.Cu")
		(net "P5E_CPU0_P0_TX_DP<12>")
	)
	(segment
		(start 355.508052 -284.293564)
		(end 355.539802 -284.311852)
		(width 0.1143)
		(layer "In6.Cu")
		(net "P5E_CPU0_P0_TX_DP<12>")
	)
	(segment
		(start 321.429126 -376.629422)
		(end 321.429126 -377.1265)
		(width 0.14224)
		(layer "In6.Cu")
		(net "P5E_CPU0_P0_TX_DP<12>")
	)
	(segment
		(start 356.415848 -289.13455)
		(end 356.41661 -289.135058)
		(width 0.1143)
		(layer "In6.Cu")
		(net "P5E_CPU0_P0_TX_DP<12>")
	)
	(segment
		(start 356.41661 -293.995094)
		(end 356.448106 -294.013382)
		(width 0.1143)
		(layer "In6.Cu")
		(net "P5E_CPU0_P0_TX_DP<12>")
	)
	(segment
		(start 356.41661 -290.75507)
		(end 356.448106 -290.773358)
		(width 0.1143)
		(layer "In6.Cu")
		(net "P5E_CPU0_P0_TX_DP<12>")
	)
	(segment
		(start 356.44455 -294.660574)
		(end 356.443788 -294.661082)
		(width 0.1143)
		(layer "In6.Cu")
		(net "P5E_CPU0_P0_TX_DP<12>")
	)
	(segment
		(start 356.41661 -292.375082)
		(end 356.448106 -292.39337)
		(width 0.1143)
		(layer "In6.Cu")
		(net "P5E_CPU0_P0_TX_DP<12>")
	)
	(segment
		(start 354.381054 -282.996132)
		(end 354.678996 -282.996132)
		(width 0.1143)
		(layer "In6.Cu")
		(net "P5E_CPU0_P0_TX_DP<12>")
	)
	(segment
		(start 356.45471 -289.157156)
		(end 356.45598 -289.157918)
		(width 0.1143)
		(layer "In6.Cu")
		(net "P5E_CPU0_P0_TX_DP<12>")
	)
	(segment
		(start 356.119938 -298.805854)
		(end 358.560116 -304.69713)
		(width 0.14224)
		(layer "In6.Cu")
		(net "P5E_CPU0_P0_TX_DP<12>")
	)
	(segment
		(start 356.453948 -290.77666)
		(end 356.45471 -290.777168)
		(width 0.1143)
		(layer "In6.Cu")
		(net "P5E_CPU0_P0_TX_DP<12>")
	)
	(segment
		(start 356.119938 -295.536366)
		(end 356.119938 -295.564814)
		(width 0.1143)
		(layer "In6.Cu")
		(net "P5E_CPU0_P0_TX_DP<12>")
	)
	(segment
		(start 356.119938 -295.564814)
		(end 356.119938 -298.805854)
		(width 0.14224)
		(layer "In6.Cu")
		(net "P5E_CPU0_P0_TX_DP<12>")
	)
	(segment
		(start 356.442264 -291.42182)
		(end 356.40899 -291.441378)
		(width 0.1143)
		(layer "In6.Cu")
		(net "P5E_CPU0_P0_TX_DP<12>")
	)
	(segment
		(start 354.678996 -282.996132)
		(end 354.7618 -283.078936)
		(width 0.1143)
		(layer "In6.Cu")
		(net "P5E_CPU0_P0_TX_DP<12>")
	)
	(segment
		(start 356.44455 -291.42055)
		(end 356.44328 -291.421312)
		(width 0.1143)
		(layer "In6.Cu")
		(net "P5E_CPU0_P0_TX_DP<12>")
	)
	(segment
		(start 356.165658 -295.490646)
		(end 356.119938 -295.536366)
		(width 0.1143)
		(layer "In6.Cu")
		(net "P5E_CPU0_P0_TX_DP<12>")
	)
	(segment
		(start 356.442264 -293.041832)
		(end 356.40899 -293.06139)
		(width 0.1143)
		(layer "In6.Cu")
		(net "P5E_CPU0_P0_TX_DP<12>")
	)
	(segment
		(start 356.452424 -285.916116)
		(end 356.453948 -285.916878)
		(width 0.1143)
		(layer "In6.Cu")
		(net "P5E_CPU0_P0_TX_DP<12>")
	)
	(segment
		(start 356.165404 -295.490392)
		(end 356.165658 -295.490646)
		(width 0.1143)
		(layer "In6.Cu")
		(net "P5E_CPU0_P0_TX_DP<12>")
	)
	(segment
		(start 356.40899 -293.990522)
		(end 356.415848 -293.994586)
		(width 0.1143)
		(layer "In6.Cu")
		(net "P5E_CPU0_P0_TX_DP<12>")
	)
	(segment
		(start 356.45598 -290.77793)
		(end 356.45852 -290.7792)
		(width 0.1143)
		(layer "In6.Cu")
		(net "P5E_CPU0_P0_TX_DP<12>")
	)
	(segment
		(start 356.452424 -290.775898)
		(end 356.453948 -290.77666)
		(width 0.1143)
		(layer "In6.Cu")
		(net "P5E_CPU0_P0_TX_DP<12>")
	)
	(segment
		(start 356.448106 -292.39337)
		(end 356.448868 -292.393878)
		(width 0.1143)
		(layer "In6.Cu")
		(net "P5E_CPU0_P0_TX_DP<12>")
	)
	(segment
		(start 356.453948 -285.916878)
		(end 356.45471 -285.917386)
		(width 0.1143)
		(layer "In6.Cu")
		(net "P5E_CPU0_P0_TX_DP<12>")
	)
	(segment
		(start 356.45852 -285.919418)
		(end 356.479856 -285.931864)
		(width 0.1143)
		(layer "In6.Cu")
		(net "P5E_CPU0_P0_TX_DP<12>")
	)
	(segment
		(start 356.415848 -292.374574)
		(end 356.41661 -292.375082)
		(width 0.1143)
		(layer "In6.Cu")
		(net "P5E_CPU0_P0_TX_DP<12>")
	)
	(segment
		(start 356.44455 -293.040562)
		(end 356.44328 -293.041324)
		(width 0.1143)
		(layer "In6.Cu")
		(net "P5E_CPU0_P0_TX_DP<12>")
	)
	(segment
		(start 356.41661 -285.895288)
		(end 356.448106 -285.913576)
		(width 0.1143)
		(layer "In6.Cu")
		(net "P5E_CPU0_P0_TX_DP<12>")
	)
	(segment
		(start 321.429126 -377.1265)
		(end 321.138296 -377.41733)
		(width 0.14224)
		(layer "In6.Cu")
		(net "P5E_CPU0_P0_TX_DP<12>")
	)
	(segment
		(start 356.40899 -290.750498)
		(end 356.415848 -290.754562)
		(width 0.1143)
		(layer "In6.Cu")
		(net "P5E_CPU0_P0_TX_DP<12>")
	)
	(segment
		(start 356.45852 -294.019224)
		(end 356.479856 -294.03167)
		(width 0.1143)
		(layer "In6.Cu")
		(net "P5E_CPU0_P0_TX_DP<12>")
	)
	(segment
		(start 356.448868 -292.393878)
		(end 356.451662 -292.395402)
		(width 0.1143)
		(layer "In6.Cu")
		(net "P5E_CPU0_P0_TX_DP<12>")
	)
	(segment
		(start 356.448106 -289.798506)
		(end 356.44709 -289.799014)
		(width 0.1143)
		(layer "In6.Cu")
		(net "P5E_CPU0_P0_TX_DP<12>")
	)
	(segment
		(start 356.445566 -293.040054)
		(end 356.44455 -293.040562)
		(width 0.1143)
		(layer "In6.Cu")
		(net "P5E_CPU0_P0_TX_DP<12>")
	)
	(segment
		(start 356.448868 -285.914084)
		(end 356.451662 -285.915608)
		(width 0.1143)
		(layer "In6.Cu")
		(net "P5E_CPU0_P0_TX_DP<12>")
	)
	(segment
		(start 356.453948 -289.156648)
		(end 356.45471 -289.157156)
		(width 0.1143)
		(layer "In6.Cu")
		(net "P5E_CPU0_P0_TX_DP<12>")
	)
	(segment
		(start 355.93909 -285.08071)
		(end 355.978206 -285.10357)
		(width 0.1143)
		(layer "In6.Cu")
		(net "P5E_CPU0_P0_TX_DP<12>")
	)
	(segment
		(start 370.24183 -320.498216)
		(end 373.9134 -327.52284)
		(width 0.14224)
		(layer "In6.Cu")
		(net "P5E_CPU0_P0_TX_DP<12>")
	)
	(segment
		(start 376.273822 -339.464142)
		(end 376.273822 -350.845628)
		(width 0.14224)
		(layer "In6.Cu")
		(net "P5E_CPU0_P0_TX_DP<12>")
	)
	(segment
		(start 374.366028 -328.845926)
		(end 376.273822 -339.464142)
		(width 0.14224)
		(layer "In6.Cu")
		(net "P5E_CPU0_P0_TX_DP<12>")
	)
	(segment
		(start 356.443788 -294.661082)
		(end 356.44201 -294.662098)
		(width 0.1143)
		(layer "In6.Cu")
		(net "P5E_CPU0_P0_TX_DP<12>")
	)
	(segment
		(start 356.479856 -289.780218)
		(end 356.448868 -289.797998)
		(width 0.1143)
		(layer "In6.Cu")
		(net "P5E_CPU0_P0_TX_DP<12>")
	)
	(segment
		(start 355.47173 -284.272482)
		(end 355.508052 -284.293564)
		(width 0.1143)
		(layer "In6.Cu")
		(net "P5E_CPU0_P0_TX_DP<12>")
	)
	(segment
		(start 356.41153 -287.512252)
		(end 356.448106 -287.533588)
		(width 0.1143)
		(layer "In6.Cu")
		(net "P5E_CPU0_P0_TX_DP<12>")
	)
	(segment
		(start 373.9134 -327.52284)
		(end 374.366028 -328.845926)
		(width 0.14224)
		(layer "In6.Cu")
		(net "P5E_CPU0_P0_TX_DP<12>")
	)
	(segment
		(start 356.45471 -292.39718)
		(end 356.45598 -292.397942)
		(width 0.1143)
		(layer "In6.Cu")
		(net "P5E_CPU0_P0_TX_DP<12>")
	)
	(segment
		(start 356.448868 -289.153854)
		(end 356.451662 -289.155378)
		(width 0.1143)
		(layer "In6.Cu")
		(net "P5E_CPU0_P0_TX_DP<12>")
	)
	(segment
		(start 355.978206 -285.10357)
		(end 356.008686 -285.12135)
		(width 0.1143)
		(layer "In6.Cu")
		(net "P5E_CPU0_P0_TX_DP<12>")
	)
	(segment
		(start 356.448106 -285.913576)
		(end 356.448868 -285.914084)
		(width 0.1143)
		(layer "In6.Cu")
		(net "P5E_CPU0_P0_TX_DP<12>")
	)
	(segment
		(start 356.448868 -289.797998)
		(end 356.448106 -289.798506)
		(width 0.1143)
		(layer "In6.Cu")
		(net "P5E_CPU0_P0_TX_DP<12>")
	)
	(segment
		(start 358.560116 -304.69713)
		(end 364.196122 -313.131454)
		(width 0.14224)
		(layer "In6.Cu")
		(net "P5E_CPU0_P0_TX_DP<12>")
	)
	(segment
		(start 356.479856 -291.40023)
		(end 356.448868 -291.41801)
		(width 0.1143)
		(layer "In6.Cu")
		(net "P5E_CPU0_P0_TX_DP<12>")
	)
	(segment
		(start 356.445566 -291.420042)
		(end 356.44455 -291.42055)
		(width 0.1143)
		(layer "In6.Cu")
		(net "P5E_CPU0_P0_TX_DP<12>")
	)
	(segment
		(start 356.165404 -295.411652)
		(end 356.165404 -295.490392)
		(width 0.1143)
		(layer "In6.Cu")
		(net "P5E_CPU0_P0_TX_DP<12>")
	)
	(segment
		(start 356.45471 -285.917386)
		(end 356.45598 -285.918148)
		(width 0.1143)
		(layer "In6.Cu")
		(net "P5E_CPU0_P0_TX_DP<12>")
	)
	(segment
		(start 356.44328 -289.8013)
		(end 356.442264 -289.801808)
		(width 0.1143)
		(layer "In6.Cu")
		(net "P5E_CPU0_P0_TX_DP<12>")
	)
	(segment
		(start 321.884294 -376.07621)
		(end 321.7672 -376.12447)
		(width 0.14224)
		(layer "In6.Cu")
		(net "P5E_CPU0_P0_TX_DP<12>")
	)
	(segment
		(start 356.44328 -291.421312)
		(end 356.442264 -291.42182)
		(width 0.1143)
		(layer "In6.Cu")
		(net "P5E_CPU0_P0_TX_DP<12>")
	)
	(segment
		(start 356.448106 -293.03853)
		(end 356.44709 -293.039038)
		(width 0.1143)
		(layer "In6.Cu")
		(net "P5E_CPU0_P0_TX_DP<12>")
	)
	(segment
		(start 356.445566 -294.660066)
		(end 356.44455 -294.660574)
		(width 0.1143)
		(layer "In6.Cu")
		(net "P5E_CPU0_P0_TX_DP<12>")
	)
	(segment
		(start 356.453948 -294.016684)
		(end 356.45471 -294.017192)
		(width 0.1143)
		(layer "In6.Cu")
		(net "P5E_CPU0_P0_TX_DP<12>")
	)
	(segment
		(start 356.415848 -285.89478)
		(end 356.41661 -285.895288)
		(width 0.1143)
		(layer "In6.Cu")
		(net "P5E_CPU0_P0_TX_DP<12>")
	)
	(segment
		(start 356.451662 -294.015414)
		(end 356.452424 -294.015922)
		(width 0.1143)
		(layer "In6.Cu")
		(net "P5E_CPU0_P0_TX_DP<12>")
	)
	(segment
		(start 364.196122 -313.131454)
		(end 370.24183 -320.498216)
		(width 0.14224)
		(layer "In6.Cu")
		(net "P5E_CPU0_P0_TX_DP<12>")
	)
	(segment
		(start 356.45852 -292.399212)
		(end 356.479856 -292.411658)
		(width 0.1143)
		(layer "In6.Cu")
		(net "P5E_CPU0_P0_TX_DP<12>")
	)
	(segment
		(start 356.448868 -290.773866)
		(end 356.451662 -290.77539)
		(width 0.1143)
		(layer "In6.Cu")
		(net "P5E_CPU0_P0_TX_DP<12>")
	)
	(segment
		(start 356.45471 -294.017192)
		(end 356.45598 -294.017954)
		(width 0.1143)
		(layer "In6.Cu")
		(net "P5E_CPU0_P0_TX_DP<12>")
	)
	(segment
		(start 354.999036 -283.460952)
		(end 355.061266 -283.49702)
		(width 0.1143)
		(layer "In6.Cu")
		(net "P5E_CPU0_P0_TX_DP<12>")
	)
	(segment
		(start 356.45852 -289.159188)
		(end 356.479856 -289.171634)
		(width 0.1143)
		(layer "In6.Cu")
		(net "P5E_CPU0_P0_TX_DP<12>")
	)
	(segment
		(start 356.448868 -293.038022)
		(end 356.448106 -293.03853)
		(width 0.1143)
		(layer "In6.Cu")
		(net "P5E_CPU0_P0_TX_DP<12>")
	)
	(segment
		(start 369.183158 -367.963958)
		(end 362.051854 -375.095262)
		(width 0.14224)
		(layer "In6.Cu")
		(net "P5E_CPU0_P0_TX_DP<12>")
	)
	(segment
		(start 356.451662 -289.155378)
		(end 356.452424 -289.155886)
		(width 0.1143)
		(layer "In6.Cu")
		(net "P5E_CPU0_P0_TX_DP<12>")
	)
	(segment
		(start 356.45598 -292.397942)
		(end 356.45852 -292.399212)
		(width 0.1143)
		(layer "In6.Cu")
		(net "P5E_CPU0_P0_TX_DP<12>")
	)
	(segment
		(start 356.448106 -294.658542)
		(end 356.44709 -294.65905)
		(width 0.1143)
		(layer "In6.Cu")
		(net "P5E_CPU0_P0_TX_DP<12>")
	)
	(segment
		(start 356.415848 -293.994586)
		(end 356.41661 -293.995094)
		(width 0.1143)
		(layer "In6.Cu")
		(net "P5E_CPU0_P0_TX_DP<12>")
	)
	(segment
		(start 356.448106 -294.013382)
		(end 356.448868 -294.01389)
		(width 0.1143)
		(layer "In6.Cu")
		(net "P5E_CPU0_P0_TX_DP<12>")
	)
	(segment
		(start 356.44709 -291.419026)
		(end 356.445566 -291.420042)
		(width 0.1143)
		(layer "In6.Cu")
		(net "P5E_CPU0_P0_TX_DP<12>")
	)
	(segment
		(start 356.453948 -292.396672)
		(end 356.45471 -292.39718)
		(width 0.1143)
		(layer "In6.Cu")
		(net "P5E_CPU0_P0_TX_DP<12>")
	)
	(segment
		(start 356.479856 -294.640254)
		(end 356.448106 -294.658542)
		(width 0.1143)
		(layer "In6.Cu")
		(net "P5E_CPU0_P0_TX_DP<12>")
	)
	(segment
		(start 356.40899 -292.37051)
		(end 356.415848 -292.374574)
		(width 0.1143)
		(layer "In6.Cu")
		(net "P5E_CPU0_P0_TX_DP<12>")
	)
	(segment
		(start 356.44709 -289.799014)
		(end 356.445566 -289.80003)
		(width 0.1143)
		(layer "In6.Cu")
		(net "P5E_CPU0_P0_TX_DP<12>")
	)
	(segment
		(start 356.448868 -291.41801)
		(end 356.448106 -291.418518)
		(width 0.1143)
		(layer "In6.Cu")
		(net "P5E_CPU0_P0_TX_DP<12>")
	)
	(segment
		(start 356.481634 -288.158936)
		(end 356.448106 -288.178494)
		(width 0.1143)
		(layer "In6.Cu")
		(net "P5E_CPU0_P0_TX_DP<12>")
	)
	(segment
		(start 359.926636 -375.975626)
		(end 322.392294 -375.975626)
		(width 0.14224)
		(layer "In6.Cu")
		(net "P5E_CPU0_P0_TX_DP<12>")
	)
	(segment
		(start 356.165912 -295.145968)
		(end 356.165912 -295.411144)
		(width 0.1143)
		(layer "In6.Cu")
		(net "P5E_CPU0_P0_TX_DP<12>")
	)
	(segment
		(start 356.45598 -294.017954)
		(end 356.45852 -294.019224)
		(width 0.1143)
		(layer "In6.Cu")
		(net "P5E_CPU0_P0_TX_DP<12>")
	)
	(segment
		(start 356.45852 -290.7792)
		(end 356.479856 -290.791646)
		(width 0.1143)
		(layer "In6.Cu")
		(net "P5E_CPU0_P0_TX_DP<12>")
	)
	(segment
		(start 356.448106 -287.533588)
		(end 356.479856 -287.551876)
		(width 0.1143)
		(layer "In6.Cu")
		(net "P5E_CPU0_P0_TX_DP<12>")
	)
	(segment
		(start 356.448106 -286.558482)
		(end 356.40899 -286.581342)
		(width 0.1143)
		(layer "In6.Cu")
		(net "P5E_CPU0_P0_TX_DP<12>")
	)
	(segment
		(start 356.41661 -289.135058)
		(end 356.448106 -289.153346)
		(width 0.1143)
		(layer "In6.Cu")
		(net "P5E_CPU0_P0_TX_DP<12>")
	)
	(segment
		(start 356.45471 -290.777168)
		(end 356.45598 -290.77793)
		(width 0.1143)
		(layer "In6.Cu")
		(net "P5E_CPU0_P0_TX_DP<12>")
	)
	(segment
		(start 356.479856 -293.020242)
		(end 356.448868 -293.038022)
		(width 0.1143)
		(layer "In6.Cu")
		(net "P5E_CPU0_P0_TX_DP<12>")
	)
	(segment
		(start 356.452424 -292.39591)
		(end 356.453948 -292.396672)
		(width 0.1143)
		(layer "In6.Cu")
		(net "P5E_CPU0_P0_TX_DP<12>")
	)
	(segment
		(start 356.44709 -294.65905)
		(end 356.445566 -294.660066)
		(width 0.1143)
		(layer "In6.Cu")
		(net "P5E_CPU0_P0_TX_DP<12>")
	)
	(segment
		(start 356.448868 -294.01389)
		(end 356.451662 -294.015414)
		(width 0.1143)
		(layer "In6.Cu")
		(net "P5E_CPU0_P0_TX_DP<12>")
	)
	(segment
		(start 356.40899 -289.130486)
		(end 356.415848 -289.13455)
		(width 0.1143)
		(layer "In6.Cu")
		(net "P5E_CPU0_P0_TX_DP<12>")
	)
	(segment
		(start 356.452424 -294.015922)
		(end 356.453948 -294.016684)
		(width 0.1143)
		(layer "In6.Cu")
		(net "P5E_CPU0_P0_TX_DP<12>")
	)
	(segment
		(start 356.45598 -285.918148)
		(end 356.45852 -285.919418)
		(width 0.1143)
		(layer "In6.Cu")
		(net "P5E_CPU0_P0_TX_DP<12>")
	)
	(segment
		(start 356.44455 -289.800538)
		(end 356.44328 -289.8013)
		(width 0.1143)
		(layer "In6.Cu")
		(net "P5E_CPU0_P0_TX_DP<12>")
	)
	(arc
		(start 354.766118 -283.101542)
		(mid 354.847245 -283.304138)
		(end 354.999036 -283.460952)
		(width 0.1143)
		(layer "In6.Cu")
		(net "P5E_CPU0_P0_TX_DP<12>")
	)
	(arc
		(start 356.165658 -287.045908)
		(mid 356.230894 -287.309499)
		(end 356.41153 -287.512252)
		(width 0.1143)
		(layer "In6.Cu")
		(net "P5E_CPU0_P0_TX_DP<12>")
	)
	(arc
		(start 354.7618 -283.078936)
		(mid 354.763845 -283.090261)
		(end 354.766118 -283.101542)
		(width 0.1143)
		(layer "In6.Cu")
		(net "P5E_CPU0_P0_TX_DP<12>")
	)
	(arc
		(start 322.392294 -375.975626)
		(mid 322.133366 -376.001021)
		(end 321.884294 -376.07621)
		(width 0.14224)
		(layer "In6.Cu")
		(net "P5E_CPU0_P0_TX_DP<12>")
	)
	(arc
		(start 356.479856 -289.171634)
		(mid 356.635784 -289.475926)
		(end 356.479856 -289.780218)
		(width 0.1143)
		(layer "In6.Cu")
		(net "P5E_CPU0_P0_TX_DP<12>")
	)
	(arc
		(start 356.40899 -288.201354)
		(mid 356.165663 -288.66592)
		(end 356.40899 -289.130486)
		(width 0.1143)
		(layer "In6.Cu")
		(net "P5E_CPU0_P0_TX_DP<12>")
	)
	(arc
		(start 356.635812 -286.236156)
		(mid 356.59505 -286.40604)
		(end 356.481634 -286.538924)
		(width 0.1143)
		(layer "In6.Cu")
		(net "P5E_CPU0_P0_TX_DP<12>")
	)
	(arc
		(start 356.635812 -287.856168)
		(mid 356.59505 -288.026052)
		(end 356.481634 -288.158936)
		(width 0.1143)
		(layer "In6.Cu")
		(net "P5E_CPU0_P0_TX_DP<12>")
	)
	(arc
		(start 356.008686 -285.12135)
		(mid 356.124113 -285.254726)
		(end 356.165658 -285.42615)
		(width 0.1143)
		(layer "In6.Cu")
		(net "P5E_CPU0_P0_TX_DP<12>")
	)
	(arc
		(start 362.051854 -375.095262)
		(mid 361.07681 -375.746829)
		(end 359.926636 -375.975626)
		(width 0.14224)
		(layer "In6.Cu")
		(net "P5E_CPU0_P0_TX_DP<12>")
	)
	(arc
		(start 356.165658 -285.42615)
		(mid 356.230173 -285.688369)
		(end 356.40899 -285.890716)
		(width 0.1143)
		(layer "In6.Cu")
		(net "P5E_CPU0_P0_TX_DP<12>")
	)
	(arc
		(start 356.40899 -286.581342)
		(mid 356.230177 -286.783692)
		(end 356.165658 -287.045908)
		(width 0.1143)
		(layer "In6.Cu")
		(net "P5E_CPU0_P0_TX_DP<12>")
	)
	(arc
		(start 356.40899 -293.06139)
		(mid 356.165663 -293.525956)
		(end 356.40899 -293.990522)
		(width 0.1143)
		(layer "In6.Cu")
		(net "P5E_CPU0_P0_TX_DP<12>")
	)
	(arc
		(start 356.479856 -285.931864)
		(mid 356.594532 -286.065198)
		(end 356.635812 -286.236156)
		(width 0.1143)
		(layer "In6.Cu")
		(net "P5E_CPU0_P0_TX_DP<12>")
	)
	(arc
		(start 356.479856 -287.551876)
		(mid 356.594532 -287.68521)
		(end 356.635812 -287.856168)
		(width 0.1143)
		(layer "In6.Cu")
		(net "P5E_CPU0_P0_TX_DP<12>")
	)
	(arc
		(start 356.479856 -292.411658)
		(mid 356.635784 -292.71595)
		(end 356.479856 -293.020242)
		(width 0.1143)
		(layer "In6.Cu")
		(net "P5E_CPU0_P0_TX_DP<12>")
	)
	(arc
		(start 356.40899 -289.821366)
		(mid 356.165663 -290.285932)
		(end 356.40899 -290.750498)
		(width 0.1143)
		(layer "In6.Cu")
		(net "P5E_CPU0_P0_TX_DP<12>")
	)
	(arc
		(start 355.695758 -284.616144)
		(mid 355.760273 -284.878363)
		(end 355.93909 -285.08071)
		(width 0.1143)
		(layer "In6.Cu")
		(net "P5E_CPU0_P0_TX_DP<12>")
	)
	(arc
		(start 356.409244 -294.681148)
		(mid 356.230435 -294.883642)
		(end 356.165912 -295.145968)
		(width 0.1143)
		(layer "In6.Cu")
		(net "P5E_CPU0_P0_TX_DP<12>")
	)
	(arc
		(start 355.461062 -284.265116)
		(mid 355.466376 -284.268828)
		(end 355.47173 -284.272482)
		(width 0.1143)
		(layer "In6.Cu")
		(net "P5E_CPU0_P0_TX_DP<12>")
	)
	(arc
		(start 356.479856 -290.791646)
		(mid 356.635784 -291.095938)
		(end 356.479856 -291.40023)
		(width 0.1143)
		(layer "In6.Cu")
		(net "P5E_CPU0_P0_TX_DP<12>")
	)
	(arc
		(start 355.539802 -284.311852)
		(mid 355.654478 -284.445186)
		(end 355.695758 -284.616144)
		(width 0.1143)
		(layer "In6.Cu")
		(net "P5E_CPU0_P0_TX_DP<12>")
	)
	(arc
		(start 376.273822 -350.845628)
		(mid 374.431022 -360.110009)
		(end 369.183158 -367.963958)
		(width 0.14224)
		(layer "In6.Cu")
		(net "P5E_CPU0_P0_TX_DP<12>")
	)
	(arc
		(start 356.479856 -294.03167)
		(mid 356.635784 -294.335962)
		(end 356.479856 -294.640254)
		(width 0.1143)
		(layer "In6.Cu")
		(net "P5E_CPU0_P0_TX_DP<12>")
	)
	(arc
		(start 321.7672 -376.12447)
		(mid 321.521431 -376.325577)
		(end 321.429126 -376.629422)
		(width 0.14224)
		(layer "In6.Cu")
		(net "P5E_CPU0_P0_TX_DP<12>")
	)
	(arc
		(start 355.225858 -283.821124)
		(mid 355.291478 -284.070642)
		(end 355.461062 -284.265116)
		(width 0.1143)
		(layer "In6.Cu")
		(net "P5E_CPU0_P0_TX_DP<12>")
	)
	(arc
		(start 355.223826 -283.796994)
		(mid 355.225135 -283.809034)
		(end 355.225858 -283.821124)
		(width 0.1143)
		(layer "In6.Cu")
		(net "P5E_CPU0_P0_TX_DP<12>")
	)
	(arc
		(start 356.40899 -291.441378)
		(mid 356.165663 -291.905944)
		(end 356.40899 -292.37051)
		(width 0.1143)
		(layer "In6.Cu")
		(net "P5E_CPU0_P0_TX_DP<12>")
	)
	(arc
		(start 355.061266 -283.49702)
		(mid 355.169466 -283.632422)
		(end 355.223826 -283.796994)
		(width 0.1143)
		(layer "In6.Cu")
		(net "P5E_CPU0_P0_TX_DP<12>")
	)
	(segment
		(start 354.847906 -285.970218)
		(end 354.381054 -286.236156)
		(width 0.12954)
		(layer "F.Cu")
		(net "P5E_CPU0_P0_TX_DP<11>")
	)
	(segment
		(start 319.707006 -380.85522)
		(end 319.707006 -380.15164)
		(width 0.12954)
		(layer "F.Cu")
		(net "P5E_CPU0_P0_TX_DP<11>")
	)
	(segment
		(start 319.411096 -381.15113)
		(end 319.707006 -380.85522)
		(width 0.12954)
		(layer "F.Cu")
		(net "P5E_CPU0_P0_TX_DP<11>")
	)
	(segment
		(start 319.707006 -380.15164)
		(end 319.436496 -379.88113)
		(width 0.12954)
		(layer "F.Cu")
		(net "P5E_CPU0_P0_TX_DP<11>")
	)
	(segment
		(start 354.887784 -296.583862)
		(end 354.887784 -296.61231)
		(width 0.1143)
		(layer "In6.Cu")
		(net "P5E_CPU0_P0_TX_DP<11>")
	)
	(segment
		(start 355.50983 -292.394386)
		(end 355.510592 -292.394894)
		(width 0.1143)
		(layer "In6.Cu")
		(net "P5E_CPU0_P0_TX_DP<11>")
	)
	(segment
		(start 354.755958 -295.955974)
		(end 354.755958 -296.04843)
		(width 0.1143)
		(layer "In6.Cu")
		(net "P5E_CPU0_P0_TX_DP<11>")
	)
	(segment
		(start 359.238296 -375.040652)
		(end 322.308982 -375.040652)
		(width 0.14224)
		(layer "In6.Cu")
		(net "P5E_CPU0_P0_TX_DP<11>")
	)
	(segment
		(start 355.539802 -294.640254)
		(end 355.49459 -294.666416)
		(width 0.1143)
		(layer "In6.Cu")
		(net "P5E_CPU0_P0_TX_DP<11>")
	)
	(segment
		(start 355.514148 -292.396926)
		(end 355.516688 -292.39845)
		(width 0.1143)
		(layer "In6.Cu")
		(net "P5E_CPU0_P0_TX_DP<11>")
	)
	(segment
		(start 355.529896 -291.405818)
		(end 355.529134 -291.406326)
		(width 0.1143)
		(layer "In6.Cu")
		(net "P5E_CPU0_P0_TX_DP<11>")
	)
	(segment
		(start 373.436134 -329.013058)
		(end 375.295668 -339.363304)
		(width 0.14224)
		(layer "In6.Cu")
		(net "P5E_CPU0_P0_TX_DP<11>")
	)
	(segment
		(start 355.51237 -292.39591)
		(end 355.513386 -292.396418)
		(width 0.1143)
		(layer "In6.Cu")
		(net "P5E_CPU0_P0_TX_DP<11>")
	)
	(segment
		(start 355.213158 -295.155366)
		(end 355.213158 -295.16578)
		(width 0.1143)
		(layer "In6.Cu")
		(net "P5E_CPU0_P0_TX_DP<11>")
	)
	(segment
		(start 355.508052 -293.03853)
		(end 355.47173 -293.059612)
		(width 0.1143)
		(layer "In6.Cu")
		(net "P5E_CPU0_P0_TX_DP<11>")
	)
	(segment
		(start 355.47173 -293.9923)
		(end 355.508052 -294.013382)
		(width 0.1143)
		(layer "In6.Cu")
		(net "P5E_CPU0_P0_TX_DP<11>")
	)
	(segment
		(start 354.381054 -286.236156)
		(end 354.678996 -286.236156)
		(width 0.1143)
		(layer "In6.Cu")
		(net "P5E_CPU0_P0_TX_DP<11>")
	)
	(segment
		(start 355.515418 -290.777676)
		(end 355.539802 -290.791646)
		(width 0.1143)
		(layer "In6.Cu")
		(net "P5E_CPU0_P0_TX_DP<11>")
	)
	(segment
		(start 355.51237 -290.775898)
		(end 355.513386 -290.776406)
		(width 0.1143)
		(layer "In6.Cu")
		(net "P5E_CPU0_P0_TX_DP<11>")
	)
	(segment
		(start 319.727326 -377.109736)
		(end 319.727326 -379.5903)
		(width 0.14224)
		(layer "In6.Cu")
		(net "P5E_CPU0_P0_TX_DP<11>")
	)
	(segment
		(start 354.849176 -296.27322)
		(end 354.896166 -296.32021)
		(width 0.1143)
		(layer "In6.Cu")
		(net "P5E_CPU0_P0_TX_DP<11>")
	)
	(segment
		(start 355.516688 -292.39845)
		(end 355.539802 -292.411658)
		(width 0.1143)
		(layer "In6.Cu")
		(net "P5E_CPU0_P0_TX_DP<11>")
	)
	(segment
		(start 319.727326 -379.5903)
		(end 319.436496 -379.88113)
		(width 0.14224)
		(layer "In6.Cu")
		(net "P5E_CPU0_P0_TX_DP<11>")
	)
	(segment
		(start 355.507798 -290.773358)
		(end 355.508052 -290.773358)
		(width 0.1143)
		(layer "In6.Cu")
		(net "P5E_CPU0_P0_TX_DP<11>")
	)
	(segment
		(start 355.004116 -286.703262)
		(end 355.070156 -286.742378)
		(width 0.1143)
		(layer "In6.Cu")
		(net "P5E_CPU0_P0_TX_DP<11>")
	)
	(segment
		(start 355.508052 -288.178494)
		(end 355.495098 -288.186114)
		(width 0.1143)
		(layer "In6.Cu")
		(net "P5E_CPU0_P0_TX_DP<11>")
	)
	(segment
		(start 355.510592 -292.394894)
		(end 355.511608 -292.395402)
		(width 0.1143)
		(layer "In6.Cu")
		(net "P5E_CPU0_P0_TX_DP<11>")
	)
	(segment
		(start 355.513386 -290.776406)
		(end 355.514148 -290.776914)
		(width 0.1143)
		(layer "In6.Cu")
		(net "P5E_CPU0_P0_TX_DP<11>")
	)
	(segment
		(start 355.529134 -291.406326)
		(end 355.508052 -291.418518)
		(width 0.1143)
		(layer "In6.Cu")
		(net "P5E_CPU0_P0_TX_DP<11>")
	)
	(segment
		(start 355.508814 -292.393878)
		(end 355.50983 -292.394386)
		(width 0.1143)
		(layer "In6.Cu")
		(net "P5E_CPU0_P0_TX_DP<11>")
	)
	(segment
		(start 355.539802 -293.020242)
		(end 355.508052 -293.03853)
		(width 0.1143)
		(layer "In6.Cu")
		(net "P5E_CPU0_P0_TX_DP<11>")
	)
	(segment
		(start 355.508052 -287.533588)
		(end 355.539802 -287.551876)
		(width 0.1143)
		(layer "In6.Cu")
		(net "P5E_CPU0_P0_TX_DP<11>")
	)
	(segment
		(start 363.443012 -313.683396)
		(end 369.45951 -321.014598)
		(width 0.14224)
		(layer "In6.Cu")
		(net "P5E_CPU0_P0_TX_DP<11>")
	)
	(segment
		(start 355.511608 -292.395402)
		(end 355.51237 -292.39591)
		(width 0.1143)
		(layer "In6.Cu")
		(net "P5E_CPU0_P0_TX_DP<11>")
	)
	(segment
		(start 355.508814 -290.773866)
		(end 355.50983 -290.774374)
		(width 0.1143)
		(layer "In6.Cu")
		(net "P5E_CPU0_P0_TX_DP<11>")
	)
	(segment
		(start 355.508052 -291.418518)
		(end 355.507798 -291.418772)
		(width 0.1143)
		(layer "In6.Cu")
		(net "P5E_CPU0_P0_TX_DP<11>")
	)
	(segment
		(start 355.495098 -289.145726)
		(end 355.539802 -289.171634)
		(width 0.1143)
		(layer "In6.Cu")
		(net "P5E_CPU0_P0_TX_DP<11>")
	)
	(segment
		(start 355.510592 -290.774882)
		(end 355.511608 -290.77539)
		(width 0.1143)
		(layer "In6.Cu")
		(net "P5E_CPU0_P0_TX_DP<11>")
	)
	(segment
		(start 354.933504 -296.538142)
		(end 354.887784 -296.583862)
		(width 0.1143)
		(layer "In6.Cu")
		(net "P5E_CPU0_P0_TX_DP<11>")
	)
	(segment
		(start 355.508052 -290.773358)
		(end 355.508814 -290.773866)
		(width 0.1143)
		(layer "In6.Cu")
		(net "P5E_CPU0_P0_TX_DP<11>")
	)
	(segment
		(start 375.295668 -339.363304)
		(end 375.295668 -350.963992)
		(width 0.14224)
		(layer "In6.Cu")
		(net "P5E_CPU0_P0_TX_DP<11>")
	)
	(segment
		(start 355.513386 -292.396418)
		(end 355.514148 -292.396926)
		(width 0.1143)
		(layer "In6.Cu")
		(net "P5E_CPU0_P0_TX_DP<11>")
	)
	(segment
		(start 355.508052 -294.013382)
		(end 355.539802 -294.03167)
		(width 0.1143)
		(layer "In6.Cu")
		(net "P5E_CPU0_P0_TX_DP<11>")
	)
	(segment
		(start 357.734616 -305.140614)
		(end 363.443012 -313.683396)
		(width 0.14224)
		(layer "In6.Cu")
		(net "P5E_CPU0_P0_TX_DP<11>")
	)
	(segment
		(start 354.887784 -296.61231)
		(end 354.887784 -298.26712)
		(width 0.14224)
		(layer "In6.Cu")
		(net "P5E_CPU0_P0_TX_DP<11>")
	)
	(segment
		(start 354.933504 -296.410126)
		(end 354.933504 -296.538142)
		(width 0.1143)
		(layer "In6.Cu")
		(net "P5E_CPU0_P0_TX_DP<11>")
	)
	(segment
		(start 355.54158 -288.158936)
		(end 355.508052 -288.178494)
		(width 0.1143)
		(layer "In6.Cu")
		(net "P5E_CPU0_P0_TX_DP<11>")
	)
	(segment
		(start 355.514148 -290.776914)
		(end 355.515418 -290.777676)
		(width 0.1143)
		(layer "In6.Cu")
		(net "P5E_CPU0_P0_TX_DP<11>")
	)
	(segment
		(start 355.529134 -289.786314)
		(end 355.508052 -289.798506)
		(width 0.1143)
		(layer "In6.Cu")
		(net "P5E_CPU0_P0_TX_DP<11>")
	)
	(segment
		(start 355.508052 -292.39337)
		(end 355.508814 -292.393878)
		(width 0.1143)
		(layer "In6.Cu")
		(net "P5E_CPU0_P0_TX_DP<11>")
	)
	(segment
		(start 355.507798 -292.39337)
		(end 355.508052 -292.39337)
		(width 0.1143)
		(layer "In6.Cu")
		(net "P5E_CPU0_P0_TX_DP<11>")
	)
	(segment
		(start 354.887784 -298.26712)
		(end 357.734616 -305.140614)
		(width 0.14224)
		(layer "In6.Cu")
		(net "P5E_CPU0_P0_TX_DP<11>")
	)
	(segment
		(start 355.539802 -291.40023)
		(end 355.529896 -291.405818)
		(width 0.1143)
		(layer "In6.Cu")
		(net "P5E_CPU0_P0_TX_DP<11>")
	)
	(segment
		(start 320.235326 -376.03938)
		(end 320.235326 -376.039634)
		(width 0.14224)
		(layer "In6.Cu")
		(net "P5E_CPU0_P0_TX_DP<11>")
	)
	(segment
		(start 355.070156 -286.742378)
		(end 355.070664 -286.742632)
		(width 0.1143)
		(layer "In6.Cu")
		(net "P5E_CPU0_P0_TX_DP<11>")
	)
	(segment
		(start 355.038152 -295.468548)
		(end 355.00183 -295.48963)
		(width 0.1143)
		(layer "In6.Cu")
		(net "P5E_CPU0_P0_TX_DP<11>")
	)
	(segment
		(start 355.511608 -290.77539)
		(end 355.51237 -290.775898)
		(width 0.1143)
		(layer "In6.Cu")
		(net "P5E_CPU0_P0_TX_DP<11>")
	)
	(segment
		(start 373.049292 -327.882758)
		(end 373.436134 -329.013058)
		(width 0.14224)
		(layer "In6.Cu")
		(net "P5E_CPU0_P0_TX_DP<11>")
	)
	(segment
		(start 355.508052 -289.798506)
		(end 355.507798 -289.79876)
		(width 0.1143)
		(layer "In6.Cu")
		(net "P5E_CPU0_P0_TX_DP<11>")
	)
	(segment
		(start 369.45951 -321.014598)
		(end 373.049292 -327.882758)
		(width 0.14224)
		(layer "In6.Cu")
		(net "P5E_CPU0_P0_TX_DP<11>")
	)
	(segment
		(start 368.530886 -367.295684)
		(end 361.880404 -373.946166)
		(width 0.14224)
		(layer "In6.Cu")
		(net "P5E_CPU0_P0_TX_DP<11>")
	)
	(segment
		(start 355.529896 -289.785806)
		(end 355.529134 -289.786314)
		(width 0.1143)
		(layer "In6.Cu")
		(net "P5E_CPU0_P0_TX_DP<11>")
	)
	(segment
		(start 355.50983 -290.774374)
		(end 355.510592 -290.774882)
		(width 0.1143)
		(layer "In6.Cu")
		(net "P5E_CPU0_P0_TX_DP<11>")
	)
	(segment
		(start 355.473254 -287.510728)
		(end 355.508052 -287.533588)
		(width 0.1143)
		(layer "In6.Cu")
		(net "P5E_CPU0_P0_TX_DP<11>")
	)
	(segment
		(start 354.678996 -286.236156)
		(end 354.703126 -286.260286)
		(width 0.1143)
		(layer "In6.Cu")
		(net "P5E_CPU0_P0_TX_DP<11>")
	)
	(segment
		(start 355.539802 -289.780218)
		(end 355.529896 -289.785806)
		(width 0.1143)
		(layer "In6.Cu")
		(net "P5E_CPU0_P0_TX_DP<11>")
	)
	(arc
		(start 355.45649 -293.07028)
		(mid 355.231319 -293.525956)
		(end 355.45649 -293.981632)
		(width 0.1143)
		(layer "In6.Cu")
		(net "P5E_CPU0_P0_TX_DP<11>")
	)
	(arc
		(start 355.070664 -286.742632)
		(mid 355.181919 -286.869811)
		(end 355.225858 -287.032954)
		(width 0.1143)
		(layer "In6.Cu")
		(net "P5E_CPU0_P0_TX_DP<11>")
	)
	(arc
		(start 355.47173 -293.059612)
		(mid 355.464066 -293.064883)
		(end 355.45649 -293.07028)
		(width 0.1143)
		(layer "In6.Cu")
		(net "P5E_CPU0_P0_TX_DP<11>")
	)
	(arc
		(start 355.45649 -293.981632)
		(mid 355.464066 -293.987028)
		(end 355.47173 -293.9923)
		(width 0.1143)
		(layer "In6.Cu")
		(net "P5E_CPU0_P0_TX_DP<11>")
	)
	(arc
		(start 354.703126 -286.260286)
		(mid 354.747579 -286.318043)
		(end 354.77577 -286.385254)
		(width 0.1143)
		(layer "In6.Cu")
		(net "P5E_CPU0_P0_TX_DP<11>")
	)
	(arc
		(start 355.539802 -292.411658)
		(mid 355.69573 -292.71595)
		(end 355.539802 -293.020242)
		(width 0.1143)
		(layer "In6.Cu")
		(net "P5E_CPU0_P0_TX_DP<11>")
	)
	(arc
		(start 355.495098 -288.186114)
		(mid 355.218765 -288.66592)
		(end 355.495098 -289.145726)
		(width 0.1143)
		(layer "In6.Cu")
		(net "P5E_CPU0_P0_TX_DP<11>")
	)
	(arc
		(start 355.539802 -294.03167)
		(mid 355.69573 -294.335962)
		(end 355.539802 -294.640254)
		(width 0.1143)
		(layer "In6.Cu")
		(net "P5E_CPU0_P0_TX_DP<11>")
	)
	(arc
		(start 355.225858 -287.032954)
		(mid 355.2269 -287.055858)
		(end 355.22916 -287.078674)
		(width 0.1143)
		(layer "In6.Cu")
		(net "P5E_CPU0_P0_TX_DP<11>")
	)
	(arc
		(start 375.295668 -350.963992)
		(mid 373.537554 -359.80263)
		(end 368.530886 -367.295684)
		(width 0.14224)
		(layer "In6.Cu")
		(net "P5E_CPU0_P0_TX_DP<11>")
	)
	(arc
		(start 355.22916 -287.078674)
		(mid 355.309849 -287.318061)
		(end 355.473254 -287.510728)
		(width 0.1143)
		(layer "In6.Cu")
		(net "P5E_CPU0_P0_TX_DP<11>")
	)
	(arc
		(start 354.755958 -296.04843)
		(mid 354.78018 -296.170112)
		(end 354.849176 -296.27322)
		(width 0.1143)
		(layer "In6.Cu")
		(net "P5E_CPU0_P0_TX_DP<11>")
	)
	(arc
		(start 355.507798 -289.79876)
		(mid 355.227151 -290.286122)
		(end 355.507798 -290.773358)
		(width 0.1143)
		(layer "In6.Cu")
		(net "P5E_CPU0_P0_TX_DP<11>")
	)
	(arc
		(start 354.77577 -286.385254)
		(mid 354.861501 -286.564688)
		(end 355.004116 -286.703262)
		(width 0.1143)
		(layer "In6.Cu")
		(net "P5E_CPU0_P0_TX_DP<11>")
	)
	(arc
		(start 355.507798 -291.418772)
		(mid 355.227151 -291.906134)
		(end 355.507798 -292.39337)
		(width 0.1143)
		(layer "In6.Cu")
		(net "P5E_CPU0_P0_TX_DP<11>")
	)
	(arc
		(start 355.213158 -295.16578)
		(mid 355.166267 -295.340646)
		(end 355.038152 -295.468548)
		(width 0.1143)
		(layer "In6.Cu")
		(net "P5E_CPU0_P0_TX_DP<11>")
	)
	(arc
		(start 355.00183 -295.48963)
		(mid 354.821178 -295.692375)
		(end 354.755958 -295.955974)
		(width 0.1143)
		(layer "In6.Cu")
		(net "P5E_CPU0_P0_TX_DP<11>")
	)
	(arc
		(start 322.308982 -375.040652)
		(mid 321.801274 -375.105842)
		(end 321.32651 -375.297192)
		(width 0.14224)
		(layer "In6.Cu")
		(net "P5E_CPU0_P0_TX_DP<11>")
	)
	(arc
		(start 320.235326 -376.039634)
		(mid 319.860661 -376.517404)
		(end 319.727326 -377.109736)
		(width 0.14224)
		(layer "In6.Cu")
		(net "P5E_CPU0_P0_TX_DP<11>")
	)
	(arc
		(start 355.695758 -287.856168)
		(mid 355.654996 -288.026052)
		(end 355.54158 -288.158936)
		(width 0.1143)
		(layer "In6.Cu")
		(net "P5E_CPU0_P0_TX_DP<11>")
	)
	(arc
		(start 355.539802 -287.551876)
		(mid 355.654478 -287.68521)
		(end 355.695758 -287.856168)
		(width 0.1143)
		(layer "In6.Cu")
		(net "P5E_CPU0_P0_TX_DP<11>")
	)
	(arc
		(start 361.880404 -373.946166)
		(mid 360.668209 -374.756192)
		(end 359.238296 -375.040652)
		(width 0.14224)
		(layer "In6.Cu")
		(net "P5E_CPU0_P0_TX_DP<11>")
	)
	(arc
		(start 355.49459 -294.666416)
		(mid 355.288522 -294.873279)
		(end 355.213158 -295.155366)
		(width 0.1143)
		(layer "In6.Cu")
		(net "P5E_CPU0_P0_TX_DP<11>")
	)
	(arc
		(start 321.32651 -375.297192)
		(mid 320.764849 -375.644662)
		(end 320.235326 -376.03938)
		(width 0.14224)
		(layer "In6.Cu")
		(net "P5E_CPU0_P0_TX_DP<11>")
	)
	(arc
		(start 354.896166 -296.32021)
		(mid 354.923785 -296.36145)
		(end 354.933504 -296.410126)
		(width 0.1143)
		(layer "In6.Cu")
		(net "P5E_CPU0_P0_TX_DP<11>")
	)
	(arc
		(start 355.539802 -290.791646)
		(mid 355.69573 -291.095938)
		(end 355.539802 -291.40023)
		(width 0.1143)
		(layer "In6.Cu")
		(net "P5E_CPU0_P0_TX_DP<11>")
	)
	(arc
		(start 355.539802 -289.171634)
		(mid 355.69573 -289.475926)
		(end 355.539802 -289.780218)
		(width 0.1143)
		(layer "In6.Cu")
		(net "P5E_CPU0_P0_TX_DP<11>")
	)
	(segment
		(start 318.005206 -383.31902)
		(end 318.005206 -382.61544)
		(width 0.12954)
		(layer "F.Cu")
		(net "P5E_CPU0_P0_TX_DP<10>")
	)
	(segment
		(start 317.709296 -383.61493)
		(end 318.005206 -383.31902)
		(width 0.12954)
		(layer "F.Cu")
		(net "P5E_CPU0_P0_TX_DP<10>")
	)
	(segment
		(start 354.847906 -284.350206)
		(end 354.381054 -284.616144)
		(width 0.12954)
		(layer "F.Cu")
		(net "P5E_CPU0_P0_TX_DP<10>")
	)
	(segment
		(start 318.005206 -382.61544)
		(end 317.734696 -382.34493)
		(width 0.12954)
		(layer "F.Cu")
		(net "P5E_CPU0_P0_TX_DP<10>")
	)
	(segment
		(start 359.03916 -374.105678)
		(end 322.339208 -374.105678)
		(width 0.14224)
		(layer "In6.Cu")
		(net "P5E_CPU0_P0_TX_DP<10>")
	)
	(segment
		(start 354.285804 -295.145968)
		(end 354.285804 -295.333928)
		(width 0.1143)
		(layer "In6.Cu")
		(net "P5E_CPU0_P0_TX_DP<10>")
	)
	(segment
		(start 354.598732 -294.640762)
		(end 354.568252 -294.658542)
		(width 0.1143)
		(layer "In6.Cu")
		(net "P5E_CPU0_P0_TX_DP<10>")
	)
	(segment
		(start 354.568252 -294.658542)
		(end 354.529136 -294.681402)
		(width 0.1143)
		(layer "In6.Cu")
		(net "P5E_CPU0_P0_TX_DP<10>")
	)
	(segment
		(start 353.902772 -295.945306)
		(end 353.902772 -296.206926)
		(width 0.1143)
		(layer "In6.Cu")
		(net "P5E_CPU0_P0_TX_DP<10>")
	)
	(segment
		(start 354.529136 -290.750498)
		(end 354.568252 -290.773358)
		(width 0.1143)
		(layer "In6.Cu")
		(net "P5E_CPU0_P0_TX_DP<10>")
	)
	(segment
		(start 354.568252 -289.798506)
		(end 354.529136 -289.821366)
		(width 0.1143)
		(layer "In6.Cu")
		(net "P5E_CPU0_P0_TX_DP<10>")
	)
	(segment
		(start 353.857052 -296.252646)
		(end 353.857052 -296.281094)
		(width 0.1143)
		(layer "In6.Cu")
		(net "P5E_CPU0_P0_TX_DP<10>")
	)
	(segment
		(start 367.845594 -366.66043)
		(end 361.362752 -373.143272)
		(width 0.14224)
		(layer "In6.Cu")
		(net "P5E_CPU0_P0_TX_DP<10>")
	)
	(segment
		(start 354.09886 -285.748222)
		(end 354.098098 -285.74873)
		(width 0.1143)
		(layer "In6.Cu")
		(net "P5E_CPU0_P0_TX_DP<10>")
	)
	(segment
		(start 354.568252 -293.03853)
		(end 354.529136 -293.06139)
		(width 0.1143)
		(layer "In6.Cu")
		(net "P5E_CPU0_P0_TX_DP<10>")
	)
	(segment
		(start 354.568252 -291.418518)
		(end 354.529136 -291.441378)
		(width 0.1143)
		(layer "In6.Cu")
		(net "P5E_CPU0_P0_TX_DP<10>")
	)
	(segment
		(start 354.568252 -288.178494)
		(end 354.529136 -288.201354)
		(width 0.1143)
		(layer "In6.Cu")
		(net "P5E_CPU0_P0_TX_DP<10>")
	)
	(segment
		(start 354.098098 -285.74873)
		(end 354.097082 -285.749238)
		(width 0.1143)
		(layer "In6.Cu")
		(net "P5E_CPU0_P0_TX_DP<10>")
	)
	(segment
		(start 354.568252 -294.013382)
		(end 354.598732 -294.031162)
		(width 0.1143)
		(layer "In6.Cu")
		(net "P5E_CPU0_P0_TX_DP<10>")
	)
	(segment
		(start 318.025526 -377.754134)
		(end 318.025526 -381.987298)
		(width 0.14224)
		(layer "In6.Cu")
		(net "P5E_CPU0_P0_TX_DP<10>")
	)
	(segment
		(start 368.67465 -321.527932)
		(end 372.181628 -328.23785)
		(width 0.14224)
		(layer "In6.Cu")
		(net "P5E_CPU0_P0_TX_DP<10>")
	)
	(segment
		(start 317.978282 -382.101344)
		(end 317.734696 -382.34493)
		(width 0.14224)
		(layer "In6.Cu")
		(net "P5E_CPU0_P0_TX_DP<10>")
	)
	(segment
		(start 354.529136 -289.130486)
		(end 354.568252 -289.153346)
		(width 0.1143)
		(layer "In6.Cu")
		(net "P5E_CPU0_P0_TX_DP<10>")
	)
	(segment
		(start 354.098098 -286.723582)
		(end 354.131626 -286.74314)
		(width 0.1143)
		(layer "In6.Cu")
		(net "P5E_CPU0_P0_TX_DP<10>")
	)
	(segment
		(start 354.381054 -284.616144)
		(end 354.678996 -284.616144)
		(width 0.1143)
		(layer "In6.Cu")
		(net "P5E_CPU0_P0_TX_DP<10>")
	)
	(segment
		(start 354.097082 -285.749238)
		(end 354.095558 -285.750254)
		(width 0.1143)
		(layer "In6.Cu")
		(net "P5E_CPU0_P0_TX_DP<10>")
	)
	(segment
		(start 354.568252 -289.153346)
		(end 354.598732 -289.171126)
		(width 0.1143)
		(layer "In6.Cu")
		(net "P5E_CPU0_P0_TX_DP<10>")
	)
	(segment
		(start 354.239068 -295.446704)
		(end 354.01758 -295.668192)
		(width 0.1143)
		(layer "In6.Cu")
		(net "P5E_CPU0_P0_TX_DP<10>")
	)
	(segment
		(start 354.129848 -285.730442)
		(end 354.09886 -285.748222)
		(width 0.1143)
		(layer "In6.Cu")
		(net "P5E_CPU0_P0_TX_DP<10>")
	)
	(segment
		(start 356.908608 -305.583082)
		(end 362.693458 -314.240418)
		(width 0.14224)
		(layer "In6.Cu")
		(net "P5E_CPU0_P0_TX_DP<10>")
	)
	(segment
		(start 353.857052 -298.216066)
		(end 356.908608 -305.583082)
		(width 0.14224)
		(layer "In6.Cu")
		(net "P5E_CPU0_P0_TX_DP<10>")
	)
	(segment
		(start 354.529136 -292.37051)
		(end 354.568252 -292.39337)
		(width 0.1143)
		(layer "In6.Cu")
		(net "P5E_CPU0_P0_TX_DP<10>")
	)
	(segment
		(start 353.902772 -296.206926)
		(end 353.857052 -296.252646)
		(width 0.1143)
		(layer "In6.Cu")
		(net "P5E_CPU0_P0_TX_DP<10>")
	)
	(segment
		(start 354.058982 -286.700722)
		(end 354.098098 -286.723582)
		(width 0.1143)
		(layer "In6.Cu")
		(net "P5E_CPU0_P0_TX_DP<10>")
	)
	(segment
		(start 354.529136 -293.990522)
		(end 354.568252 -294.013382)
		(width 0.1143)
		(layer "In6.Cu")
		(net "P5E_CPU0_P0_TX_DP<10>")
	)
	(segment
		(start 354.094542 -285.750762)
		(end 354.058982 -285.77159)
		(width 0.1143)
		(layer "In6.Cu")
		(net "P5E_CPU0_P0_TX_DP<10>")
	)
	(segment
		(start 354.531676 -287.512252)
		(end 354.598732 -287.551368)
		(width 0.1143)
		(layer "In6.Cu")
		(net "P5E_CPU0_P0_TX_DP<10>")
	)
	(segment
		(start 354.095558 -285.750254)
		(end 354.094542 -285.750762)
		(width 0.1143)
		(layer "In6.Cu")
		(net "P5E_CPU0_P0_TX_DP<10>")
	)
	(segment
		(start 321.146932 -374.34266)
		(end 319.982342 -374.825006)
		(width 0.14224)
		(layer "In6.Cu")
		(net "P5E_CPU0_P0_TX_DP<10>")
	)
	(segment
		(start 354.678996 -284.616144)
		(end 354.748846 -284.685994)
		(width 0.1143)
		(layer "In6.Cu")
		(net "P5E_CPU0_P0_TX_DP<10>")
	)
	(segment
		(start 362.693458 -314.240418)
		(end 368.67465 -321.527932)
		(width 0.14224)
		(layer "In6.Cu")
		(net "P5E_CPU0_P0_TX_DP<10>")
	)
	(segment
		(start 354.598732 -291.400738)
		(end 354.568252 -291.418518)
		(width 0.1143)
		(layer "In6.Cu")
		(net "P5E_CPU0_P0_TX_DP<10>")
	)
	(segment
		(start 374.363488 -340.38032)
		(end 374.363488 -350.92513)
		(width 0.14224)
		(layer "In6.Cu")
		(net "P5E_CPU0_P0_TX_DP<10>")
	)
	(segment
		(start 372.181628 -328.23785)
		(end 374.363488 -340.38032)
		(width 0.14224)
		(layer "In6.Cu")
		(net "P5E_CPU0_P0_TX_DP<10>")
	)
	(segment
		(start 354.598732 -293.02075)
		(end 354.568252 -293.03853)
		(width 0.1143)
		(layer "In6.Cu")
		(net "P5E_CPU0_P0_TX_DP<10>")
	)
	(segment
		(start 353.857052 -296.281094)
		(end 353.857052 -298.216066)
		(width 0.14224)
		(layer "In6.Cu")
		(net "P5E_CPU0_P0_TX_DP<10>")
	)
	(segment
		(start 354.598732 -289.780726)
		(end 354.568252 -289.798506)
		(width 0.1143)
		(layer "In6.Cu")
		(net "P5E_CPU0_P0_TX_DP<10>")
	)
	(segment
		(start 354.598732 -284.920944)
		(end 354.529136 -284.961584)
		(width 0.1143)
		(layer "In6.Cu")
		(net "P5E_CPU0_P0_TX_DP<10>")
	)
	(segment
		(start 354.600764 -288.159698)
		(end 354.568252 -288.178494)
		(width 0.1143)
		(layer "In6.Cu")
		(net "P5E_CPU0_P0_TX_DP<10>")
	)
	(segment
		(start 354.568252 -292.39337)
		(end 354.598732 -292.41115)
		(width 0.1143)
		(layer "In6.Cu")
		(net "P5E_CPU0_P0_TX_DP<10>")
	)
	(segment
		(start 354.568252 -290.773358)
		(end 354.598732 -290.791138)
		(width 0.1143)
		(layer "In6.Cu")
		(net "P5E_CPU0_P0_TX_DP<10>")
	)
	(arc
		(start 354.529136 -284.961584)
		(mid 354.350323 -285.163934)
		(end 354.285804 -285.42615)
		(width 0.1143)
		(layer "In6.Cu")
		(net "P5E_CPU0_P0_TX_DP<10>")
	)
	(arc
		(start 322.339208 -374.105678)
		(mid 321.731406 -374.165479)
		(end 321.146932 -374.34266)
		(width 0.14224)
		(layer "In6.Cu")
		(net "P5E_CPU0_P0_TX_DP<10>")
	)
	(arc
		(start 354.529136 -293.06139)
		(mid 354.285809 -293.525956)
		(end 354.529136 -293.990522)
		(width 0.1143)
		(layer "In6.Cu")
		(net "P5E_CPU0_P0_TX_DP<10>")
	)
	(arc
		(start 354.058982 -285.77159)
		(mid 353.815655 -286.236156)
		(end 354.058982 -286.700722)
		(width 0.1143)
		(layer "In6.Cu")
		(net "P5E_CPU0_P0_TX_DP<10>")
	)
	(arc
		(start 354.598732 -287.551368)
		(mid 354.714159 -287.684744)
		(end 354.755704 -287.856168)
		(width 0.1143)
		(layer "In6.Cu")
		(net "P5E_CPU0_P0_TX_DP<10>")
	)
	(arc
		(start 354.748846 -284.685994)
		(mid 354.696429 -284.817925)
		(end 354.598732 -284.920944)
		(width 0.1143)
		(layer "In6.Cu")
		(net "P5E_CPU0_P0_TX_DP<10>")
	)
	(arc
		(start 319.982342 -374.825006)
		(mid 318.559728 -375.992818)
		(end 318.025526 -377.754134)
		(width 0.14224)
		(layer "In6.Cu")
		(net "P5E_CPU0_P0_TX_DP<10>")
	)
	(arc
		(start 354.529136 -289.821366)
		(mid 354.285809 -290.285932)
		(end 354.529136 -290.750498)
		(width 0.1143)
		(layer "In6.Cu")
		(net "P5E_CPU0_P0_TX_DP<10>")
	)
	(arc
		(start 354.598732 -294.031162)
		(mid 354.755709 -294.335962)
		(end 354.598732 -294.640762)
		(width 0.1143)
		(layer "In6.Cu")
		(net "P5E_CPU0_P0_TX_DP<10>")
	)
	(arc
		(start 354.598732 -289.171126)
		(mid 354.755709 -289.475926)
		(end 354.598732 -289.780726)
		(width 0.1143)
		(layer "In6.Cu")
		(net "P5E_CPU0_P0_TX_DP<10>")
	)
	(arc
		(start 354.131626 -286.74314)
		(mid 354.245033 -286.876029)
		(end 354.285804 -287.045908)
		(width 0.1143)
		(layer "In6.Cu")
		(net "P5E_CPU0_P0_TX_DP<10>")
	)
	(arc
		(start 354.529136 -294.681402)
		(mid 354.350323 -294.883752)
		(end 354.285804 -295.145968)
		(width 0.1143)
		(layer "In6.Cu")
		(net "P5E_CPU0_P0_TX_DP<10>")
	)
	(arc
		(start 354.529136 -288.201354)
		(mid 354.285809 -288.66592)
		(end 354.529136 -289.130486)
		(width 0.1143)
		(layer "In6.Cu")
		(net "P5E_CPU0_P0_TX_DP<10>")
	)
	(arc
		(start 354.598732 -290.791138)
		(mid 354.755709 -291.095938)
		(end 354.598732 -291.400738)
		(width 0.1143)
		(layer "In6.Cu")
		(net "P5E_CPU0_P0_TX_DP<10>")
	)
	(arc
		(start 374.363488 -350.92513)
		(mid 372.669482 -359.441005)
		(end 367.845594 -366.66043)
		(width 0.14224)
		(layer "In6.Cu")
		(net "P5E_CPU0_P0_TX_DP<10>")
	)
	(arc
		(start 318.025526 -381.987298)
		(mid 318.013249 -382.049021)
		(end 317.978282 -382.101344)
		(width 0.14224)
		(layer "In6.Cu")
		(net "P5E_CPU0_P0_TX_DP<10>")
	)
	(arc
		(start 354.285804 -285.42615)
		(mid 354.244549 -285.597121)
		(end 354.129848 -285.730442)
		(width 0.1143)
		(layer "In6.Cu")
		(net "P5E_CPU0_P0_TX_DP<10>")
	)
	(arc
		(start 354.01758 -295.668192)
		(mid 353.932627 -295.795333)
		(end 353.902772 -295.945306)
		(width 0.1143)
		(layer "In6.Cu")
		(net "P5E_CPU0_P0_TX_DP<10>")
	)
	(arc
		(start 354.285804 -295.333928)
		(mid 354.273662 -295.394971)
		(end 354.239068 -295.446704)
		(width 0.1143)
		(layer "In6.Cu")
		(net "P5E_CPU0_P0_TX_DP<10>")
	)
	(arc
		(start 354.285804 -287.045908)
		(mid 354.35104 -287.309499)
		(end 354.531676 -287.512252)
		(width 0.1143)
		(layer "In6.Cu")
		(net "P5E_CPU0_P0_TX_DP<10>")
	)
	(arc
		(start 354.598732 -292.41115)
		(mid 354.755709 -292.71595)
		(end 354.598732 -293.02075)
		(width 0.1143)
		(layer "In6.Cu")
		(net "P5E_CPU0_P0_TX_DP<10>")
	)
	(arc
		(start 354.529136 -291.441378)
		(mid 354.285809 -291.905944)
		(end 354.529136 -292.37051)
		(width 0.1143)
		(layer "In6.Cu")
		(net "P5E_CPU0_P0_TX_DP<10>")
	)
	(arc
		(start 354.755704 -287.856168)
		(mid 354.714738 -288.026574)
		(end 354.600764 -288.159698)
		(width 0.1143)
		(layer "In6.Cu")
		(net "P5E_CPU0_P0_TX_DP<10>")
	)
	(arc
		(start 361.362752 -373.143272)
		(mid 360.296665 -373.855546)
		(end 359.03916 -374.105678)
		(width 0.14224)
		(layer "In6.Cu")
		(net "P5E_CPU0_P0_TX_DP<10>")
	)
	(segment
		(start 346.387928 -282.730194)
		(end 345.921076 -282.996132)
		(width 0.12954)
		(layer "F.Cu")
		(net "P5E_CPU0_P0_TX_DP<0>")
	)
	(segment
		(start 298.700444 -390.77646)
		(end 298.404534 -390.48055)
		(width 0.12954)
		(layer "F.Cu")
		(net "P5E_CPU0_P0_TX_DP<0>")
	)
	(segment
		(start 297.700954 -390.48055)
		(end 297.430444 -390.75106)
		(width 0.12954)
		(layer "F.Cu")
		(net "P5E_CPU0_P0_TX_DP<0>")
	)
	(segment
		(start 298.404534 -390.48055)
		(end 297.700954 -390.48055)
		(width 0.12954)
		(layer "F.Cu")
		(net "P5E_CPU0_P0_TX_DP<0>")
	)
	(segment
		(start 345.641676 -284.126686)
		(end 345.638882 -284.12821)
		(width 0.1143)
		(layer "In6.Cu")
		(net "P5E_CPU0_P0_TX_DP<0>")
	)
	(segment
		(start 346.108274 -283.318712)
		(end 346.069158 -283.341572)
		(width 0.1143)
		(layer "In6.Cu")
		(net "P5E_CPU0_P0_TX_DP<0>")
	)
	(segment
		(start 345.1987 -293.02075)
		(end 345.16822 -293.03853)
		(width 0.1143)
		(layer "In6.Cu")
		(net "P5E_CPU0_P0_TX_DP<0>")
	)
	(segment
		(start 348.674182 -310.068976)
		(end 355.608128 -320.446654)
		(width 0.14224)
		(layer "In6.Cu")
		(net "P5E_CPU0_P0_TX_DP<0>")
	)
	(segment
		(start 344.661744 -286.7025)
		(end 344.698066 -286.723582)
		(width 0.1143)
		(layer "In6.Cu")
		(net "P5E_CPU0_P0_TX_DP<0>")
	)
	(segment
		(start 345.16822 -294.013382)
		(end 345.1987 -294.031162)
		(width 0.1143)
		(layer "In6.Cu")
		(net "P5E_CPU0_P0_TX_DP<0>")
	)
	(segment
		(start 345.66987 -284.11043)
		(end 345.642438 -284.126178)
		(width 0.1143)
		(layer "In6.Cu")
		(net "P5E_CPU0_P0_TX_DP<0>")
	)
	(segment
		(start 345.1987 -294.640762)
		(end 345.129104 -294.681402)
		(width 0.1143)
		(layer "In6.Cu")
		(net "P5E_CPU0_P0_TX_DP<0>")
	)
	(segment
		(start 345.628214 -284.13456)
		(end 345.627198 -284.135068)
		(width 0.1143)
		(layer "In6.Cu")
		(net "P5E_CPU0_P0_TX_DP<0>")
	)
	(segment
		(start 344.370152 -296.252646)
		(end 344.370152 -296.281094)
		(width 0.1143)
		(layer "In6.Cu")
		(net "P5E_CPU0_P0_TX_DP<0>")
	)
	(segment
		(start 364.985046 -341.830152)
		(end 364.985046 -349.10014)
		(width 0.14224)
		(layer "In6.Cu")
		(net "P5E_CPU0_P0_TX_DP<0>")
	)
	(segment
		(start 345.16822 -293.03853)
		(end 345.129104 -293.06139)
		(width 0.1143)
		(layer "In6.Cu")
		(net "P5E_CPU0_P0_TX_DP<0>")
	)
	(segment
		(start 344.370152 -296.281094)
		(end 344.370152 -299.677582)
		(width 0.14224)
		(layer "In6.Cu")
		(net "P5E_CPU0_P0_TX_DP<0>")
	)
	(segment
		(start 345.16822 -288.178494)
		(end 345.129104 -288.201354)
		(width 0.1143)
		(layer "In6.Cu")
		(net "P5E_CPU0_P0_TX_DP<0>")
	)
	(segment
		(start 360.91241 -326.910192)
		(end 362.356146 -329.671426)
		(width 0.14224)
		(layer "In6.Cu")
		(net "P5E_CPU0_P0_TX_DP<0>")
	)
	(segment
		(start 345.16822 -290.773358)
		(end 345.1987 -290.791138)
		(width 0.1143)
		(layer "In6.Cu")
		(net "P5E_CPU0_P0_TX_DP<0>")
	)
	(segment
		(start 296.6212 -390.46023)
		(end 297.139614 -390.46023)
		(width 0.14224)
		(layer "In6.Cu")
		(net "P5E_CPU0_P0_TX_DP<0>")
	)
	(segment
		(start 363.288834 -332.395576)
		(end 364.985046 -341.830152)
		(width 0.14224)
		(layer "In6.Cu")
		(net "P5E_CPU0_P0_TX_DP<0>")
	)
	(segment
		(start 317.893446 -365.53521)
		(end 310.060594 -368.779044)
		(width 0.14224)
		(layer "In6.Cu")
		(net "P5E_CPU0_P0_TX_DP<0>")
	)
	(segment
		(start 307.211984 -369.345718)
		(end 304.271426 -369.345718)
		(width 0.14224)
		(layer "In6.Cu")
		(net "P5E_CPU0_P0_TX_DP<0>")
	)
	(segment
		(start 345.634564 -284.13075)
		(end 345.629738 -284.133544)
		(width 0.1143)
		(layer "In6.Cu")
		(net "P5E_CPU0_P0_TX_DP<0>")
	)
	(segment
		(start 296.173652 -390.235694)
		(end 296.240454 -390.302496)
		(width 0.14224)
		(layer "In6.Cu")
		(net "P5E_CPU0_P0_TX_DP<0>")
	)
	(segment
		(start 345.637104 -284.129226)
		(end 345.63558 -284.130242)
		(width 0.1143)
		(layer "In6.Cu")
		(net "P5E_CPU0_P0_TX_DP<0>")
	)
	(segment
		(start 345.131644 -287.512252)
		(end 345.1987 -287.551368)
		(width 0.1143)
		(layer "In6.Cu")
		(net "P5E_CPU0_P0_TX_DP<0>")
	)
	(segment
		(start 345.1987 -291.400738)
		(end 345.16822 -291.418518)
		(width 0.1143)
		(layer "In6.Cu")
		(net "P5E_CPU0_P0_TX_DP<0>")
	)
	(segment
		(start 345.16822 -292.39337)
		(end 345.1987 -292.41115)
		(width 0.1143)
		(layer "In6.Cu")
		(net "P5E_CPU0_P0_TX_DP<0>")
	)
	(segment
		(start 344.415872 -296.206926)
		(end 344.370152 -296.252646)
		(width 0.1143)
		(layer "In6.Cu")
		(net "P5E_CPU0_P0_TX_DP<0>")
	)
	(segment
		(start 345.642438 -284.126178)
		(end 345.641676 -284.126686)
		(width 0.1143)
		(layer "In6.Cu")
		(net "P5E_CPU0_P0_TX_DP<0>")
	)
	(segment
		(start 346.219018 -282.996132)
		(end 346.288868 -283.065982)
		(width 0.1143)
		(layer "In6.Cu")
		(net "P5E_CPU0_P0_TX_DP<0>")
	)
	(segment
		(start 345.16822 -291.418518)
		(end 345.129104 -291.441378)
		(width 0.1143)
		(layer "In6.Cu")
		(net "P5E_CPU0_P0_TX_DP<0>")
	)
	(segment
		(start 345.16822 -289.153346)
		(end 345.1987 -289.171126)
		(width 0.1143)
		(layer "In6.Cu")
		(net "P5E_CPU0_P0_TX_DP<0>")
	)
	(segment
		(start 345.921076 -282.996132)
		(end 346.219018 -282.996132)
		(width 0.1143)
		(layer "In6.Cu")
		(net "P5E_CPU0_P0_TX_DP<0>")
	)
	(segment
		(start 344.370152 -299.677582)
		(end 348.674182 -310.068976)
		(width 0.14224)
		(layer "In6.Cu")
		(net "P5E_CPU0_P0_TX_DP<0>")
	)
	(segment
		(start 345.16822 -284.938724)
		(end 345.129104 -284.961584)
		(width 0.1143)
		(layer "In6.Cu")
		(net "P5E_CPU0_P0_TX_DP<0>")
	)
	(segment
		(start 362.356146 -329.671426)
		(end 363.288834 -332.395576)
		(width 0.14224)
		(layer "In6.Cu")
		(net "P5E_CPU0_P0_TX_DP<0>")
	)
	(segment
		(start 300.874938 -370.752624)
		(end 298.32808 -373.299482)
		(width 0.14224)
		(layer "In6.Cu")
		(net "P5E_CPU0_P0_TX_DP<0>")
	)
	(segment
		(start 344.729816 -285.730442)
		(end 344.698828 -285.748222)
		(width 0.1143)
		(layer "In6.Cu")
		(net "P5E_CPU0_P0_TX_DP<0>")
	)
	(segment
		(start 344.698066 -285.74873)
		(end 344.697558 -285.749238)
		(width 0.1143)
		(layer "In6.Cu")
		(net "P5E_CPU0_P0_TX_DP<0>")
	)
	(segment
		(start 344.78468 -295.389808)
		(end 344.518996 -295.655492)
		(width 0.1143)
		(layer "In6.Cu")
		(net "P5E_CPU0_P0_TX_DP<0>")
	)
	(segment
		(start 345.63812 -284.128718)
		(end 345.637104 -284.129226)
		(width 0.1143)
		(layer "In6.Cu")
		(net "P5E_CPU0_P0_TX_DP<0>")
	)
	(segment
		(start 345.129104 -292.37051)
		(end 345.16822 -292.39337)
		(width 0.1143)
		(layer "In6.Cu")
		(net "P5E_CPU0_P0_TX_DP<0>")
	)
	(segment
		(start 345.627198 -284.135068)
		(end 345.599004 -284.151578)
		(width 0.1143)
		(layer "In6.Cu")
		(net "P5E_CPU0_P0_TX_DP<0>")
	)
	(segment
		(start 345.629738 -284.133544)
		(end 345.628214 -284.13456)
		(width 0.1143)
		(layer "In6.Cu")
		(net "P5E_CPU0_P0_TX_DP<0>")
	)
	(segment
		(start 295.952926 -379.033786)
		(end 295.952926 -389.702802)
		(width 0.14224)
		(layer "In6.Cu")
		(net "P5E_CPU0_P0_TX_DP<0>")
	)
	(segment
		(start 345.1987 -289.780726)
		(end 345.16822 -289.798506)
		(width 0.1143)
		(layer "In6.Cu")
		(net "P5E_CPU0_P0_TX_DP<0>")
	)
	(segment
		(start 345.63558 -284.130242)
		(end 345.634564 -284.13075)
		(width 0.1143)
		(layer "In6.Cu")
		(net "P5E_CPU0_P0_TX_DP<0>")
	)
	(segment
		(start 345.129104 -289.130486)
		(end 345.16822 -289.153346)
		(width 0.1143)
		(layer "In6.Cu")
		(net "P5E_CPU0_P0_TX_DP<0>")
	)
	(segment
		(start 345.129104 -290.750498)
		(end 345.16822 -290.773358)
		(width 0.1143)
		(layer "In6.Cu")
		(net "P5E_CPU0_P0_TX_DP<0>")
	)
	(segment
		(start 345.1987 -284.920944)
		(end 345.16822 -284.938724)
		(width 0.1143)
		(layer "In6.Cu")
		(net "P5E_CPU0_P0_TX_DP<0>")
	)
	(segment
		(start 344.415872 -295.904158)
		(end 344.415872 -296.206926)
		(width 0.1143)
		(layer "In6.Cu")
		(net "P5E_CPU0_P0_TX_DP<0>")
	)
	(segment
		(start 297.139614 -390.46023)
		(end 297.430444 -390.75106)
		(width 0.14224)
		(layer "In6.Cu")
		(net "P5E_CPU0_P0_TX_DP<0>")
	)
	(segment
		(start 344.698828 -285.748222)
		(end 344.698066 -285.74873)
		(width 0.1143)
		(layer "In6.Cu")
		(net "P5E_CPU0_P0_TX_DP<0>")
	)
	(segment
		(start 345.16822 -289.798506)
		(end 345.129104 -289.821366)
		(width 0.1143)
		(layer "In6.Cu")
		(net "P5E_CPU0_P0_TX_DP<0>")
	)
	(segment
		(start 359.882948 -361.417616)
		(end 356.942136 -364.358428)
		(width 0.14224)
		(layer "In6.Cu")
		(net "P5E_CPU0_P0_TX_DP<0>")
	)
	(segment
		(start 355.608128 -320.446654)
		(end 360.91241 -326.910192)
		(width 0.14224)
		(layer "In6.Cu")
		(net "P5E_CPU0_P0_TX_DP<0>")
	)
	(segment
		(start 345.129104 -293.990522)
		(end 345.16822 -294.013382)
		(width 0.1143)
		(layer "In6.Cu")
		(net "P5E_CPU0_P0_TX_DP<0>")
	)
	(segment
		(start 345.638882 -284.12821)
		(end 345.63812 -284.128718)
		(width 0.1143)
		(layer "In6.Cu")
		(net "P5E_CPU0_P0_TX_DP<0>")
	)
	(segment
		(start 355.982016 -364.756192)
		(end 321.819778 -364.756192)
		(width 0.14224)
		(layer "In6.Cu")
		(net "P5E_CPU0_P0_TX_DP<0>")
	)
	(segment
		(start 345.200732 -288.159698)
		(end 345.16822 -288.178494)
		(width 0.1143)
		(layer "In6.Cu")
		(net "P5E_CPU0_P0_TX_DP<0>")
	)
	(segment
		(start 344.698066 -286.723582)
		(end 344.731594 -286.74314)
		(width 0.1143)
		(layer "In6.Cu")
		(net "P5E_CPU0_P0_TX_DP<0>")
	)
	(segment
		(start 346.138754 -283.300932)
		(end 346.108274 -283.318712)
		(width 0.1143)
		(layer "In6.Cu")
		(net "P5E_CPU0_P0_TX_DP<0>")
	)
	(arc
		(start 345.1987 -289.171126)
		(mid 345.355677 -289.475926)
		(end 345.1987 -289.780726)
		(width 0.1143)
		(layer "In6.Cu")
		(net "P5E_CPU0_P0_TX_DP<0>")
	)
	(arc
		(start 310.060594 -368.779044)
		(mid 308.664196 -369.202677)
		(end 307.211984 -369.345718)
		(width 0.14224)
		(layer "In6.Cu")
		(net "P5E_CPU0_P0_TX_DP<0>")
	)
	(arc
		(start 345.129104 -289.821366)
		(mid 344.885777 -290.285932)
		(end 345.129104 -290.750498)
		(width 0.1143)
		(layer "In6.Cu")
		(net "P5E_CPU0_P0_TX_DP<0>")
	)
	(arc
		(start 345.355672 -287.856168)
		(mid 345.314706 -288.026574)
		(end 345.200732 -288.159698)
		(width 0.1143)
		(layer "In6.Cu")
		(net "P5E_CPU0_P0_TX_DP<0>")
	)
	(arc
		(start 345.825826 -283.806138)
		(mid 345.784571 -283.977109)
		(end 345.66987 -284.11043)
		(width 0.1143)
		(layer "In6.Cu")
		(net "P5E_CPU0_P0_TX_DP<0>")
	)
	(arc
		(start 344.697558 -285.749238)
		(mid 344.491336 -285.954882)
		(end 344.415872 -286.236156)
		(width 0.1143)
		(layer "In6.Cu")
		(net "P5E_CPU0_P0_TX_DP<0>")
	)
	(arc
		(start 321.819778 -364.756192)
		(mid 319.818349 -364.952838)
		(end 317.893446 -365.53521)
		(width 0.14224)
		(layer "In6.Cu")
		(net "P5E_CPU0_P0_TX_DP<0>")
	)
	(arc
		(start 345.1987 -290.791138)
		(mid 345.355677 -291.095938)
		(end 345.1987 -291.400738)
		(width 0.1143)
		(layer "In6.Cu")
		(net "P5E_CPU0_P0_TX_DP<0>")
	)
	(arc
		(start 345.599004 -284.151578)
		(mid 345.420191 -284.353928)
		(end 345.355672 -284.616144)
		(width 0.1143)
		(layer "In6.Cu")
		(net "P5E_CPU0_P0_TX_DP<0>")
	)
	(arc
		(start 345.129104 -294.681402)
		(mid 344.950291 -294.883752)
		(end 344.885772 -295.145968)
		(width 0.1143)
		(layer "In6.Cu")
		(net "P5E_CPU0_P0_TX_DP<0>")
	)
	(arc
		(start 344.885772 -287.045908)
		(mid 344.951008 -287.309499)
		(end 345.131644 -287.512252)
		(width 0.1143)
		(layer "In6.Cu")
		(net "P5E_CPU0_P0_TX_DP<0>")
	)
	(arc
		(start 345.355672 -284.616144)
		(mid 345.314123 -284.787566)
		(end 345.1987 -284.920944)
		(width 0.1143)
		(layer "In6.Cu")
		(net "P5E_CPU0_P0_TX_DP<0>")
	)
	(arc
		(start 345.129104 -284.961584)
		(mid 344.950291 -285.163934)
		(end 344.885772 -285.42615)
		(width 0.1143)
		(layer "In6.Cu")
		(net "P5E_CPU0_P0_TX_DP<0>")
	)
	(arc
		(start 295.952926 -389.702802)
		(mid 296.010292 -389.991199)
		(end 296.173652 -390.235694)
		(width 0.14224)
		(layer "In6.Cu")
		(net "P5E_CPU0_P0_TX_DP<0>")
	)
	(arc
		(start 298.32808 -373.299482)
		(mid 296.570208 -375.930417)
		(end 295.952926 -379.033786)
		(width 0.14224)
		(layer "In6.Cu")
		(net "P5E_CPU0_P0_TX_DP<0>")
	)
	(arc
		(start 344.885772 -285.42615)
		(mid 344.844517 -285.597121)
		(end 344.729816 -285.730442)
		(width 0.1143)
		(layer "In6.Cu")
		(net "P5E_CPU0_P0_TX_DP<0>")
	)
	(arc
		(start 356.942136 -364.358428)
		(mid 356.501643 -364.652819)
		(end 355.982016 -364.756192)
		(width 0.14224)
		(layer "In6.Cu")
		(net "P5E_CPU0_P0_TX_DP<0>")
	)
	(arc
		(start 346.288868 -283.065982)
		(mid 346.236451 -283.197913)
		(end 346.138754 -283.300932)
		(width 0.1143)
		(layer "In6.Cu")
		(net "P5E_CPU0_P0_TX_DP<0>")
	)
	(arc
		(start 345.129104 -288.201354)
		(mid 344.885777 -288.66592)
		(end 345.129104 -289.130486)
		(width 0.1143)
		(layer "In6.Cu")
		(net "P5E_CPU0_P0_TX_DP<0>")
	)
	(arc
		(start 364.985046 -349.10014)
		(mid 363.65906 -355.766322)
		(end 359.882948 -361.417616)
		(width 0.14224)
		(layer "In6.Cu")
		(net "P5E_CPU0_P0_TX_DP<0>")
	)
	(arc
		(start 344.648282 -286.692848)
		(mid 344.654977 -286.697724)
		(end 344.661744 -286.7025)
		(width 0.1143)
		(layer "In6.Cu")
		(net "P5E_CPU0_P0_TX_DP<0>")
	)
	(arc
		(start 344.731594 -286.74314)
		(mid 344.845001 -286.876029)
		(end 344.885772 -287.045908)
		(width 0.1143)
		(layer "In6.Cu")
		(net "P5E_CPU0_P0_TX_DP<0>")
	)
	(arc
		(start 344.518996 -295.655492)
		(mid 344.442735 -295.76958)
		(end 344.415872 -295.904158)
		(width 0.1143)
		(layer "In6.Cu")
		(net "P5E_CPU0_P0_TX_DP<0>")
	)
	(arc
		(start 304.271426 -369.345718)
		(mid 302.433247 -369.711355)
		(end 300.874938 -370.752624)
		(width 0.14224)
		(layer "In6.Cu")
		(net "P5E_CPU0_P0_TX_DP<0>")
	)
	(arc
		(start 344.885772 -295.145968)
		(mid 344.859501 -295.277954)
		(end 344.78468 -295.389808)
		(width 0.1143)
		(layer "In6.Cu")
		(net "P5E_CPU0_P0_TX_DP<0>")
	)
	(arc
		(start 345.1987 -294.031162)
		(mid 345.355677 -294.335962)
		(end 345.1987 -294.640762)
		(width 0.1143)
		(layer "In6.Cu")
		(net "P5E_CPU0_P0_TX_DP<0>")
	)
	(arc
		(start 346.069158 -283.341572)
		(mid 345.890345 -283.543922)
		(end 345.825826 -283.806138)
		(width 0.1143)
		(layer "In6.Cu")
		(net "P5E_CPU0_P0_TX_DP<0>")
	)
	(arc
		(start 345.129104 -291.441378)
		(mid 344.885777 -291.905944)
		(end 345.129104 -292.37051)
		(width 0.1143)
		(layer "In6.Cu")
		(net "P5E_CPU0_P0_TX_DP<0>")
	)
	(arc
		(start 345.129104 -293.06139)
		(mid 344.885777 -293.525956)
		(end 345.129104 -293.990522)
		(width 0.1143)
		(layer "In6.Cu")
		(net "P5E_CPU0_P0_TX_DP<0>")
	)
	(arc
		(start 296.240454 -390.302496)
		(mid 296.415142 -390.419219)
		(end 296.6212 -390.46023)
		(width 0.14224)
		(layer "In6.Cu")
		(net "P5E_CPU0_P0_TX_DP<0>")
	)
	(arc
		(start 344.415872 -286.236156)
		(mid 344.477317 -286.492368)
		(end 344.648282 -286.692848)
		(width 0.1143)
		(layer "In6.Cu")
		(net "P5E_CPU0_P0_TX_DP<0>")
	)
	(arc
		(start 345.1987 -287.551368)
		(mid 345.314127 -287.684744)
		(end 345.355672 -287.856168)
		(width 0.1143)
		(layer "In6.Cu")
		(net "P5E_CPU0_P0_TX_DP<0>")
	)
	(arc
		(start 345.1987 -292.41115)
		(mid 345.355677 -292.71595)
		(end 345.1987 -293.02075)
		(width 0.1143)
		(layer "In6.Cu")
		(net "P5E_CPU0_P0_TX_DP<0>")
	)
	(segment
		(start 352.968052 -282.730194)
		(end 352.5012 -282.996132)
		(width 0.12954)
		(layer "F.Cu")
		(net "P5E_CPU0_P0_TX_DN<9>")
	)
	(segment
		(start 314.924186 -377.68784)
		(end 315.194696 -377.41733)
		(width 0.12954)
		(layer "F.Cu")
		(net "P5E_CPU0_P0_TX_DN<9>")
	)
	(segment
		(start 315.220096 -378.68733)
		(end 314.924186 -378.39142)
		(width 0.12954)
		(layer "F.Cu")
		(net "P5E_CPU0_P0_TX_DN<9>")
	)
	(segment
		(start 314.924186 -378.39142)
		(end 314.924186 -377.68784)
		(width 0.12954)
		(layer "F.Cu")
		(net "P5E_CPU0_P0_TX_DN<9>")
	)
	(segment
		(start 353.763072 -288.320734)
		(end 353.723956 -288.343594)
		(width 0.1143)
		(layer "In6.Cu")
		(net "P5E_CPU0_P0_TX_DN<9>")
	)
	(segment
		(start 314.948062 -376.500898)
		(end 314.903866 -376.607578)
		(width 0.14224)
		(layer "In6.Cu")
		(net "P5E_CPU0_P0_TX_DN<9>")
	)
	(segment
		(start 353.193858 -296.281094)
		(end 353.193858 -298.314364)
		(width 0.14224)
		(layer "In6.Cu")
		(net "P5E_CPU0_P0_TX_DN<9>")
	)
	(segment
		(start 353.693476 -292.210744)
		(end 353.723956 -292.228524)
		(width 0.1143)
		(layer "In6.Cu")
		(net "P5E_CPU0_P0_TX_DN<9>")
	)
	(segment
		(start 353.693476 -293.830756)
		(end 353.723956 -293.848536)
		(width 0.1143)
		(layer "In6.Cu")
		(net "P5E_CPU0_P0_TX_DN<9>")
	)
	(segment
		(start 353.763072 -293.180516)
		(end 353.723956 -293.203376)
		(width 0.1143)
		(layer "In6.Cu")
		(net "P5E_CPU0_P0_TX_DN<9>")
	)
	(segment
		(start 352.5012 -282.996132)
		(end 352.203258 -282.996132)
		(width 0.1143)
		(layer "In6.Cu")
		(net "P5E_CPU0_P0_TX_DN<9>")
	)
	(segment
		(start 353.693476 -287.350708)
		(end 353.760532 -287.389824)
		(width 0.1143)
		(layer "In6.Cu")
		(net "P5E_CPU0_P0_TX_DN<9>")
	)
	(segment
		(start 353.723956 -293.848536)
		(end 353.763072 -293.871396)
		(width 0.1143)
		(layer "In6.Cu")
		(net "P5E_CPU0_P0_TX_DN<9>")
	)
	(segment
		(start 353.723956 -288.9885)
		(end 353.763072 -289.01136)
		(width 0.1143)
		(layer "In6.Cu")
		(net "P5E_CPU0_P0_TX_DN<9>")
	)
	(segment
		(start 353.723956 -290.608512)
		(end 353.763072 -290.631372)
		(width 0.1143)
		(layer "In6.Cu")
		(net "P5E_CPU0_P0_TX_DN<9>")
	)
	(segment
		(start 368.128042 -321.887342)
		(end 371.539262 -328.413364)
		(width 0.14224)
		(layer "In6.Cu")
		(net "P5E_CPU0_P0_TX_DN<9>")
	)
	(segment
		(start 353.193858 -298.314364)
		(end 356.33279 -305.892454)
		(width 0.14224)
		(layer "In6.Cu")
		(net "P5E_CPU0_P0_TX_DN<9>")
	)
	(segment
		(start 353.693476 -290.590732)
		(end 353.723956 -290.608512)
		(width 0.1143)
		(layer "In6.Cu")
		(net "P5E_CPU0_P0_TX_DN<9>")
	)
	(segment
		(start 353.723956 -289.963352)
		(end 353.693476 -289.981132)
		(width 0.1143)
		(layer "In6.Cu")
		(net "P5E_CPU0_P0_TX_DN<9>")
	)
	(segment
		(start 373.713248 -340.511384)
		(end 373.713248 -350.654874)
		(width 0.14224)
		(layer "In6.Cu")
		(net "P5E_CPU0_P0_TX_DN<9>")
	)
	(segment
		(start 352.314002 -283.318712)
		(end 352.353118 -283.341572)
		(width 0.1143)
		(layer "In6.Cu")
		(net "P5E_CPU0_P0_TX_DN<9>")
	)
	(segment
		(start 320.717164 -373.782082)
		(end 315.782706 -375.82602)
		(width 0.14224)
		(layer "In6.Cu")
		(net "P5E_CPU0_P0_TX_DN<9>")
	)
	(segment
		(start 353.23272 -286.54629)
		(end 353.295204 -286.582866)
		(width 0.1143)
		(layer "In6.Cu")
		(net "P5E_CPU0_P0_TX_DN<9>")
	)
	(segment
		(start 353.23272 -285.926022)
		(end 353.232466 -285.926022)
		(width 0.1143)
		(layer "In6.Cu")
		(net "P5E_CPU0_P0_TX_DN<9>")
	)
	(segment
		(start 353.763072 -291.560504)
		(end 353.723956 -291.583364)
		(width 0.1143)
		(layer "In6.Cu")
		(net "P5E_CPU0_P0_TX_DN<9>")
	)
	(segment
		(start 353.193858 -296.252646)
		(end 353.193858 -296.281094)
		(width 0.1143)
		(layer "In6.Cu")
		(net "P5E_CPU0_P0_TX_DN<9>")
	)
	(segment
		(start 353.723956 -288.343594)
		(end 353.691444 -288.36239)
		(width 0.1143)
		(layer "In6.Cu")
		(net "P5E_CPU0_P0_TX_DN<9>")
	)
	(segment
		(start 358.675178 -373.452898)
		(end 322.371974 -373.452898)
		(width 0.14224)
		(layer "In6.Cu")
		(net "P5E_CPU0_P0_TX_DN<9>")
	)
	(segment
		(start 353.763072 -294.800528)
		(end 353.693476 -294.841168)
		(width 0.1143)
		(layer "In6.Cu")
		(net "P5E_CPU0_P0_TX_DN<9>")
	)
	(segment
		(start 353.232212 -286.54629)
		(end 353.23272 -286.54629)
		(width 0.1143)
		(layer "In6.Cu")
		(net "P5E_CPU0_P0_TX_DN<9>")
	)
	(segment
		(start 314.903866 -377.1265)
		(end 315.194696 -377.41733)
		(width 0.14224)
		(layer "In6.Cu")
		(net "P5E_CPU0_P0_TX_DN<9>")
	)
	(segment
		(start 353.148138 -296.206926)
		(end 353.193858 -296.252646)
		(width 0.1143)
		(layer "In6.Cu")
		(net "P5E_CPU0_P0_TX_DN<9>")
	)
	(segment
		(start 353.693476 -288.97072)
		(end 353.723956 -288.9885)
		(width 0.1143)
		(layer "In6.Cu")
		(net "P5E_CPU0_P0_TX_DN<9>")
	)
	(segment
		(start 353.723956 -291.583364)
		(end 353.693476 -291.601144)
		(width 0.1143)
		(layer "In6.Cu")
		(net "P5E_CPU0_P0_TX_DN<9>")
	)
	(segment
		(start 356.33279 -305.892454)
		(end 362.16717 -314.624212)
		(width 0.14224)
		(layer "In6.Cu")
		(net "P5E_CPU0_P0_TX_DN<9>")
	)
	(segment
		(start 353.233482 -285.925514)
		(end 353.23272 -285.926022)
		(width 0.1143)
		(layer "In6.Cu")
		(net "P5E_CPU0_P0_TX_DN<9>")
	)
	(segment
		(start 353.723956 -292.228524)
		(end 353.763072 -292.251384)
		(width 0.1143)
		(layer "In6.Cu")
		(net "P5E_CPU0_P0_TX_DN<9>")
	)
	(segment
		(start 315.301122 -376.147838)
		(end 314.948062 -376.500898)
		(width 0.14224)
		(layer "In6.Cu")
		(net "P5E_CPU0_P0_TX_DN<9>")
	)
	(segment
		(start 353.763072 -289.940492)
		(end 353.723956 -289.963352)
		(width 0.1143)
		(layer "In6.Cu")
		(net "P5E_CPU0_P0_TX_DN<9>")
	)
	(segment
		(start 367.196116 -366.388142)
		(end 361.160822 -372.423436)
		(width 0.14224)
		(layer "In6.Cu")
		(net "P5E_CPU0_P0_TX_DN<9>")
	)
	(segment
		(start 353.723956 -293.203376)
		(end 353.693476 -293.221156)
		(width 0.1143)
		(layer "In6.Cu")
		(net "P5E_CPU0_P0_TX_DN<9>")
	)
	(segment
		(start 371.539262 -328.413364)
		(end 373.713248 -340.511384)
		(width 0.14224)
		(layer "In6.Cu")
		(net "P5E_CPU0_P0_TX_DN<9>")
	)
	(segment
		(start 362.16717 -314.624212)
		(end 368.128042 -321.887342)
		(width 0.14224)
		(layer "In6.Cu")
		(net "P5E_CPU0_P0_TX_DN<9>")
	)
	(segment
		(start 314.903866 -376.607578)
		(end 314.903866 -377.1265)
		(width 0.14224)
		(layer "In6.Cu")
		(net "P5E_CPU0_P0_TX_DN<9>")
	)
	(segment
		(start 353.222306 -284.920436)
		(end 353.293172 -284.961584)
		(width 0.1143)
		(layer "In6.Cu")
		(net "P5E_CPU0_P0_TX_DN<9>")
	)
	(segment
		(start 352.283522 -283.300932)
		(end 352.314002 -283.318712)
		(width 0.1143)
		(layer "In6.Cu")
		(net "P5E_CPU0_P0_TX_DN<9>")
	)
	(segment
		(start 353.148138 -295.910508)
		(end 353.148138 -296.206926)
		(width 0.1143)
		(layer "In6.Cu")
		(net "P5E_CPU0_P0_TX_DN<9>")
	)
	(segment
		(start 353.295204 -286.582866)
		(end 353.295204 -286.582612)
		(width 0.1143)
		(layer "In6.Cu")
		(net "P5E_CPU0_P0_TX_DN<9>")
	)
	(segment
		(start 353.315016 -295.677082)
		(end 353.195382 -295.796462)
		(width 0.1143)
		(layer "In6.Cu")
		(net "P5E_CPU0_P0_TX_DN<9>")
	)
	(segment
		(start 352.203258 -282.996132)
		(end 352.133408 -283.065982)
		(width 0.1143)
		(layer "In6.Cu")
		(net "P5E_CPU0_P0_TX_DN<9>")
	)
	(segment
		(start 352.752406 -284.11043)
		(end 352.82124 -284.150308)
		(width 0.1143)
		(layer "In6.Cu")
		(net "P5E_CPU0_P0_TX_DN<9>")
	)
	(segment
		(start 353.293172 -285.890716)
		(end 353.233482 -285.925514)
		(width 0.1143)
		(layer "In6.Cu")
		(net "P5E_CPU0_P0_TX_DN<9>")
	)
	(arc
		(start 353.293172 -284.961584)
		(mid 353.536499 -285.42615)
		(end 353.293172 -285.890716)
		(width 0.1143)
		(layer "In6.Cu")
		(net "P5E_CPU0_P0_TX_DN<9>")
	)
	(arc
		(start 373.713248 -350.654874)
		(mid 372.019469 -359.169694)
		(end 367.196116 -366.388142)
		(width 0.14224)
		(layer "In6.Cu")
		(net "P5E_CPU0_P0_TX_DN<9>")
	)
	(arc
		(start 352.82124 -284.150308)
		(mid 352.982454 -284.343166)
		(end 353.062794 -284.581346)
		(width 0.1143)
		(layer "In6.Cu")
		(net "P5E_CPU0_P0_TX_DN<9>")
	)
	(arc
		(start 353.763072 -289.01136)
		(mid 354.006399 -289.475926)
		(end 353.763072 -289.940492)
		(width 0.1143)
		(layer "In6.Cu")
		(net "P5E_CPU0_P0_TX_DN<9>")
	)
	(arc
		(start 353.295204 -286.582612)
		(mid 353.472567 -286.784723)
		(end 353.536504 -287.045908)
		(width 0.1143)
		(layer "In6.Cu")
		(net "P5E_CPU0_P0_TX_DN<9>")
	)
	(arc
		(start 354.006404 -287.856168)
		(mid 353.941889 -288.118387)
		(end 353.763072 -288.320734)
		(width 0.1143)
		(layer "In6.Cu")
		(net "P5E_CPU0_P0_TX_DN<9>")
	)
	(arc
		(start 352.133408 -283.065982)
		(mid 352.185825 -283.197913)
		(end 352.283522 -283.300932)
		(width 0.1143)
		(layer "In6.Cu")
		(net "P5E_CPU0_P0_TX_DN<9>")
	)
	(arc
		(start 353.06635 -284.625796)
		(mid 353.109743 -284.791428)
		(end 353.222306 -284.920436)
		(width 0.1143)
		(layer "In6.Cu")
		(net "P5E_CPU0_P0_TX_DN<9>")
	)
	(arc
		(start 353.232466 -285.926022)
		(mid 353.053924 -286.236046)
		(end 353.232212 -286.54629)
		(width 0.1143)
		(layer "In6.Cu")
		(net "P5E_CPU0_P0_TX_DN<9>")
	)
	(arc
		(start 353.195382 -295.796462)
		(mid 353.160473 -295.848801)
		(end 353.148138 -295.910508)
		(width 0.1143)
		(layer "In6.Cu")
		(net "P5E_CPU0_P0_TX_DN<9>")
	)
	(arc
		(start 353.691444 -288.36239)
		(mid 353.577515 -288.495537)
		(end 353.536504 -288.66592)
		(width 0.1143)
		(layer "In6.Cu")
		(net "P5E_CPU0_P0_TX_DN<9>")
	)
	(arc
		(start 353.536504 -288.66592)
		(mid 353.578053 -288.837342)
		(end 353.693476 -288.97072)
		(width 0.1143)
		(layer "In6.Cu")
		(net "P5E_CPU0_P0_TX_DN<9>")
	)
	(arc
		(start 315.782706 -375.82602)
		(mid 315.526049 -375.963193)
		(end 315.301122 -376.147838)
		(width 0.14224)
		(layer "In6.Cu")
		(net "P5E_CPU0_P0_TX_DN<9>")
	)
	(arc
		(start 353.693476 -293.221156)
		(mid 353.536499 -293.525956)
		(end 353.693476 -293.830756)
		(width 0.1143)
		(layer "In6.Cu")
		(net "P5E_CPU0_P0_TX_DN<9>")
	)
	(arc
		(start 353.536504 -287.045908)
		(mid 353.578053 -287.21733)
		(end 353.693476 -287.350708)
		(width 0.1143)
		(layer "In6.Cu")
		(net "P5E_CPU0_P0_TX_DN<9>")
	)
	(arc
		(start 361.160822 -372.423436)
		(mid 360.02037 -373.185335)
		(end 358.675178 -373.452898)
		(width 0.14224)
		(layer "In6.Cu")
		(net "P5E_CPU0_P0_TX_DN<9>")
	)
	(arc
		(start 353.763072 -292.251384)
		(mid 354.006399 -292.71595)
		(end 353.763072 -293.180516)
		(width 0.1143)
		(layer "In6.Cu")
		(net "P5E_CPU0_P0_TX_DN<9>")
	)
	(arc
		(start 353.693476 -294.841168)
		(mid 353.578282 -294.974092)
		(end 353.536504 -295.144952)
		(width 0.1143)
		(layer "In6.Cu")
		(net "P5E_CPU0_P0_TX_DN<9>")
	)
	(arc
		(start 353.760532 -287.389824)
		(mid 353.941184 -287.592569)
		(end 354.006404 -287.856168)
		(width 0.1143)
		(layer "In6.Cu")
		(net "P5E_CPU0_P0_TX_DN<9>")
	)
	(arc
		(start 353.763072 -290.631372)
		(mid 354.006399 -291.095938)
		(end 353.763072 -291.560504)
		(width 0.1143)
		(layer "In6.Cu")
		(net "P5E_CPU0_P0_TX_DN<9>")
	)
	(arc
		(start 353.763072 -293.871396)
		(mid 354.006399 -294.335962)
		(end 353.763072 -294.800528)
		(width 0.1143)
		(layer "In6.Cu")
		(net "P5E_CPU0_P0_TX_DN<9>")
	)
	(arc
		(start 353.062794 -284.581346)
		(mid 353.065138 -284.603526)
		(end 353.06635 -284.625796)
		(width 0.1143)
		(layer "In6.Cu")
		(net "P5E_CPU0_P0_TX_DN<9>")
	)
	(arc
		(start 322.371974 -373.452898)
		(mid 321.528363 -373.536019)
		(end 320.717164 -373.782082)
		(width 0.14224)
		(layer "In6.Cu")
		(net "P5E_CPU0_P0_TX_DN<9>")
	)
	(arc
		(start 352.353118 -283.341572)
		(mid 352.531931 -283.543922)
		(end 352.59645 -283.806138)
		(width 0.1143)
		(layer "In6.Cu")
		(net "P5E_CPU0_P0_TX_DN<9>")
	)
	(arc
		(start 353.536504 -295.144952)
		(mid 353.478447 -295.432941)
		(end 353.315016 -295.677082)
		(width 0.1143)
		(layer "In6.Cu")
		(net "P5E_CPU0_P0_TX_DN<9>")
	)
	(arc
		(start 353.693476 -289.981132)
		(mid 353.536499 -290.285932)
		(end 353.693476 -290.590732)
		(width 0.1143)
		(layer "In6.Cu")
		(net "P5E_CPU0_P0_TX_DN<9>")
	)
	(arc
		(start 352.59645 -283.806138)
		(mid 352.637705 -283.977109)
		(end 352.752406 -284.11043)
		(width 0.1143)
		(layer "In6.Cu")
		(net "P5E_CPU0_P0_TX_DN<9>")
	)
	(arc
		(start 353.693476 -291.601144)
		(mid 353.536499 -291.905944)
		(end 353.693476 -292.210744)
		(width 0.1143)
		(layer "In6.Cu")
		(net "P5E_CPU0_P0_TX_DN<9>")
	)
	(segment
		(start 313.222386 -380.15164)
		(end 313.492896 -379.88113)
		(width 0.12954)
		(layer "F.Cu")
		(net "P5E_CPU0_P0_TX_DN<8>")
	)
	(segment
		(start 313.518296 -381.15113)
		(end 313.222386 -380.85522)
		(width 0.12954)
		(layer "F.Cu")
		(net "P5E_CPU0_P0_TX_DN<8>")
	)
	(segment
		(start 352.968052 -285.970218)
		(end 352.5012 -286.236156)
		(width 0.12954)
		(layer "F.Cu")
		(net "P5E_CPU0_P0_TX_DN<8>")
	)
	(segment
		(start 313.222386 -380.85522)
		(end 313.222386 -380.15164)
		(width 0.12954)
		(layer "F.Cu")
		(net "P5E_CPU0_P0_TX_DN<8>")
	)
	(segment
		(start 370.627402 -328.682096)
		(end 372.781068 -340.667848)
		(width 0.14224)
		(layer "In6.Cu")
		(net "P5E_CPU0_P0_TX_DN<8>")
	)
	(segment
		(start 352.782124 -289.964622)
		(end 352.752406 -289.98164)
		(width 0.1143)
		(layer "In6.Cu")
		(net "P5E_CPU0_P0_TX_DN<8>")
	)
	(segment
		(start 352.783394 -289.96386)
		(end 352.782124 -289.964622)
		(width 0.1143)
		(layer "In6.Cu")
		(net "P5E_CPU0_P0_TX_DN<8>")
	)
	(segment
		(start 352.314002 -286.558482)
		(end 352.353118 -286.581342)
		(width 0.1143)
		(layer "In6.Cu")
		(net "P5E_CPU0_P0_TX_DN<8>")
	)
	(segment
		(start 352.783394 -293.203884)
		(end 352.782124 -293.204646)
		(width 0.1143)
		(layer "In6.Cu")
		(net "P5E_CPU0_P0_TX_DN<8>")
	)
	(segment
		(start 367.345214 -322.403216)
		(end 370.627402 -328.682096)
		(width 0.14224)
		(layer "In6.Cu")
		(net "P5E_CPU0_P0_TX_DN<8>")
	)
	(segment
		(start 352.823272 -294.800782)
		(end 352.752406 -294.84193)
		(width 0.1143)
		(layer "In6.Cu")
		(net "P5E_CPU0_P0_TX_DN<8>")
	)
	(segment
		(start 352.783394 -290.608004)
		(end 352.784156 -290.608512)
		(width 0.1143)
		(layer "In6.Cu")
		(net "P5E_CPU0_P0_TX_DN<8>")
	)
	(segment
		(start 352.752406 -290.590224)
		(end 352.783394 -290.608004)
		(width 0.1143)
		(layer "In6.Cu")
		(net "P5E_CPU0_P0_TX_DN<8>")
	)
	(segment
		(start 320.400172 -372.903496)
		(end 315.30671 -375.013728)
		(width 0.14224)
		(layer "In6.Cu")
		(net "P5E_CPU0_P0_TX_DN<8>")
	)
	(segment
		(start 352.783902 -287.368742)
		(end 352.784664 -287.36925)
		(width 0.1143)
		(layer "In6.Cu")
		(net "P5E_CPU0_P0_TX_DN<8>")
	)
	(segment
		(start 352.203004 -296.206926)
		(end 352.248724 -296.252646)
		(width 0.1143)
		(layer "In6.Cu")
		(net "P5E_CPU0_P0_TX_DN<8>")
	)
	(segment
		(start 361.418632 -315.181996)
		(end 367.345214 -322.403216)
		(width 0.14224)
		(layer "In6.Cu")
		(net "P5E_CPU0_P0_TX_DN<8>")
	)
	(segment
		(start 352.447098 -295.60393)
		(end 352.250248 -295.800526)
		(width 0.1143)
		(layer "In6.Cu")
		(net "P5E_CPU0_P0_TX_DN<8>")
	)
	(segment
		(start 352.783394 -292.228016)
		(end 352.784156 -292.228524)
		(width 0.1143)
		(layer "In6.Cu")
		(net "P5E_CPU0_P0_TX_DN<8>")
	)
	(segment
		(start 315.193426 -375.07037)
		(end 314.908946 -375.238772)
		(width 0.14224)
		(layer "In6.Cu")
		(net "P5E_CPU0_P0_TX_DN<8>")
	)
	(segment
		(start 352.784156 -291.583364)
		(end 352.783394 -291.583872)
		(width 0.1143)
		(layer "In6.Cu")
		(net "P5E_CPU0_P0_TX_DN<8>")
	)
	(segment
		(start 352.248724 -296.252646)
		(end 352.248724 -296.281094)
		(width 0.1143)
		(layer "In6.Cu")
		(net "P5E_CPU0_P0_TX_DN<8>")
	)
	(segment
		(start 352.248724 -296.281094)
		(end 352.248724 -298.46905)
		(width 0.14224)
		(layer "In6.Cu")
		(net "P5E_CPU0_P0_TX_DN<8>")
	)
	(segment
		(start 355.506528 -306.33416)
		(end 361.418632 -315.181996)
		(width 0.14224)
		(layer "In6.Cu")
		(net "P5E_CPU0_P0_TX_DN<8>")
	)
	(segment
		(start 352.783394 -291.583872)
		(end 352.782124 -291.584634)
		(width 0.1143)
		(layer "In6.Cu")
		(net "P5E_CPU0_P0_TX_DN<8>")
	)
	(segment
		(start 366.39881 -365.864902)
		(end 360.577892 -371.68582)
		(width 0.14224)
		(layer "In6.Cu")
		(net "P5E_CPU0_P0_TX_DN<8>")
	)
	(segment
		(start 352.784156 -290.608512)
		(end 352.820478 -290.629594)
		(width 0.1143)
		(layer "In6.Cu")
		(net "P5E_CPU0_P0_TX_DN<8>")
	)
	(segment
		(start 352.752406 -293.830248)
		(end 352.823272 -293.871142)
		(width 0.1143)
		(layer "In6.Cu")
		(net "P5E_CPU0_P0_TX_DN<8>")
	)
	(segment
		(start 372.781068 -340.667848)
		(end 372.781068 -350.456754)
		(width 0.14224)
		(layer "In6.Cu")
		(net "P5E_CPU0_P0_TX_DN<8>")
	)
	(segment
		(start 352.784156 -292.228524)
		(end 352.820478 -292.249606)
		(width 0.1143)
		(layer "In6.Cu")
		(net "P5E_CPU0_P0_TX_DN<8>")
	)
	(segment
		(start 352.28149 -286.539686)
		(end 352.314002 -286.558482)
		(width 0.1143)
		(layer "In6.Cu")
		(net "P5E_CPU0_P0_TX_DN<8>")
	)
	(segment
		(start 352.820478 -289.94227)
		(end 352.784156 -289.963352)
		(width 0.1143)
		(layer "In6.Cu")
		(net "P5E_CPU0_P0_TX_DN<8>")
	)
	(segment
		(start 358.569006 -372.517924)
		(end 322.338446 -372.517924)
		(width 0.14224)
		(layer "In6.Cu")
		(net "P5E_CPU0_P0_TX_DN<8>")
	)
	(segment
		(start 352.83267 -294.793924)
		(end 352.823272 -294.800782)
		(width 0.1143)
		(layer "In6.Cu")
		(net "P5E_CPU0_P0_TX_DN<8>")
	)
	(segment
		(start 352.784156 -287.368488)
		(end 352.783902 -287.368742)
		(width 0.1143)
		(layer "In6.Cu")
		(net "P5E_CPU0_P0_TX_DN<8>")
	)
	(segment
		(start 352.820478 -291.562282)
		(end 352.784156 -291.583364)
		(width 0.1143)
		(layer "In6.Cu")
		(net "P5E_CPU0_P0_TX_DN<8>")
	)
	(segment
		(start 352.784156 -288.9885)
		(end 352.820478 -289.009582)
		(width 0.1143)
		(layer "In6.Cu")
		(net "P5E_CPU0_P0_TX_DN<8>")
	)
	(segment
		(start 352.752406 -288.970212)
		(end 352.783394 -288.987992)
		(width 0.1143)
		(layer "In6.Cu")
		(net "P5E_CPU0_P0_TX_DN<8>")
	)
	(segment
		(start 352.782124 -293.204646)
		(end 352.752406 -293.221664)
		(width 0.1143)
		(layer "In6.Cu")
		(net "P5E_CPU0_P0_TX_DN<8>")
	)
	(segment
		(start 352.820478 -288.322512)
		(end 352.784156 -288.343594)
		(width 0.1143)
		(layer "In6.Cu")
		(net "P5E_CPU0_P0_TX_DN<8>")
	)
	(segment
		(start 352.752406 -292.210236)
		(end 352.783394 -292.228016)
		(width 0.1143)
		(layer "In6.Cu")
		(net "P5E_CPU0_P0_TX_DN<8>")
	)
	(segment
		(start 352.784156 -293.203376)
		(end 352.783394 -293.203884)
		(width 0.1143)
		(layer "In6.Cu")
		(net "P5E_CPU0_P0_TX_DN<8>")
	)
	(segment
		(start 352.784156 -289.963352)
		(end 352.783394 -289.96386)
		(width 0.1143)
		(layer "In6.Cu")
		(net "P5E_CPU0_P0_TX_DN<8>")
	)
	(segment
		(start 352.203258 -286.236156)
		(end 352.133408 -286.306006)
		(width 0.1143)
		(layer "In6.Cu")
		(net "P5E_CPU0_P0_TX_DN<8>")
	)
	(segment
		(start 313.202066 -379.5903)
		(end 313.492896 -379.88113)
		(width 0.14224)
		(layer "In6.Cu")
		(net "P5E_CPU0_P0_TX_DN<8>")
	)
	(segment
		(start 352.784156 -288.343594)
		(end 352.750628 -288.363152)
		(width 0.1143)
		(layer "In6.Cu")
		(net "P5E_CPU0_P0_TX_DN<8>")
	)
	(segment
		(start 352.820478 -293.182294)
		(end 352.784156 -293.203376)
		(width 0.1143)
		(layer "In6.Cu")
		(net "P5E_CPU0_P0_TX_DN<8>")
	)
	(segment
		(start 314.809124 -375.316242)
		(end 313.430666 -376.6947)
		(width 0.14224)
		(layer "In6.Cu")
		(net "P5E_CPU0_P0_TX_DN<8>")
	)
	(segment
		(start 313.202066 -377.246388)
		(end 313.202066 -379.5903)
		(width 0.14224)
		(layer "In6.Cu")
		(net "P5E_CPU0_P0_TX_DN<8>")
	)
	(segment
		(start 352.823272 -293.871142)
		(end 352.83267 -293.878)
		(width 0.1143)
		(layer "In6.Cu")
		(net "P5E_CPU0_P0_TX_DN<8>")
	)
	(segment
		(start 352.782124 -291.584634)
		(end 352.752406 -291.601652)
		(width 0.1143)
		(layer "In6.Cu")
		(net "P5E_CPU0_P0_TX_DN<8>")
	)
	(segment
		(start 352.783394 -287.36798)
		(end 352.784156 -287.368488)
		(width 0.1143)
		(layer "In6.Cu")
		(net "P5E_CPU0_P0_TX_DN<8>")
	)
	(segment
		(start 352.752406 -287.3502)
		(end 352.783394 -287.36798)
		(width 0.1143)
		(layer "In6.Cu")
		(net "P5E_CPU0_P0_TX_DN<8>")
	)
	(segment
		(start 352.203004 -295.914572)
		(end 352.203004 -296.206926)
		(width 0.1143)
		(layer "In6.Cu")
		(net "P5E_CPU0_P0_TX_DN<8>")
	)
	(segment
		(start 352.59645 -295.145968)
		(end 352.59645 -295.209468)
		(width 0.1143)
		(layer "In6.Cu")
		(net "P5E_CPU0_P0_TX_DN<8>")
	)
	(segment
		(start 352.5012 -286.236156)
		(end 352.203258 -286.236156)
		(width 0.1143)
		(layer "In6.Cu")
		(net "P5E_CPU0_P0_TX_DN<8>")
	)
	(segment
		(start 352.783394 -288.987992)
		(end 352.784156 -288.9885)
		(width 0.1143)
		(layer "In6.Cu")
		(net "P5E_CPU0_P0_TX_DN<8>")
	)
	(segment
		(start 352.248724 -298.46905)
		(end 355.506528 -306.33416)
		(width 0.14224)
		(layer "In6.Cu")
		(net "P5E_CPU0_P0_TX_DN<8>")
	)
	(arc
		(start 352.133408 -286.306006)
		(mid 352.185116 -286.436989)
		(end 352.28149 -286.539686)
		(width 0.1143)
		(layer "In6.Cu")
		(net "P5E_CPU0_P0_TX_DN<8>")
	)
	(arc
		(start 352.836734 -289.93084)
		(mid 352.828656 -289.936626)
		(end 352.820478 -289.94227)
		(width 0.1143)
		(layer "In6.Cu")
		(net "P5E_CPU0_P0_TX_DN<8>")
	)
	(arc
		(start 352.820478 -290.629594)
		(mid 352.827627 -290.634494)
		(end 352.834702 -290.6395)
		(width 0.1143)
		(layer "In6.Cu")
		(net "P5E_CPU0_P0_TX_DN<8>")
	)
	(arc
		(start 352.55962 -295.42486)
		(mid 352.513423 -295.520719)
		(end 352.447098 -295.60393)
		(width 0.1143)
		(layer "In6.Cu")
		(net "P5E_CPU0_P0_TX_DN<8>")
	)
	(arc
		(start 352.834702 -292.259512)
		(mid 353.062085 -292.71595)
		(end 352.834702 -293.172388)
		(width 0.1143)
		(layer "In6.Cu")
		(net "P5E_CPU0_P0_TX_DN<8>")
	)
	(arc
		(start 352.752406 -291.601652)
		(mid 352.596478 -291.905944)
		(end 352.752406 -292.210236)
		(width 0.1143)
		(layer "In6.Cu")
		(net "P5E_CPU0_P0_TX_DN<8>")
	)
	(arc
		(start 372.781068 -350.456754)
		(mid 371.122372 -358.795581)
		(end 366.39881 -365.864902)
		(width 0.14224)
		(layer "In6.Cu")
		(net "P5E_CPU0_P0_TX_DN<8>")
	)
	(arc
		(start 313.430666 -376.6947)
		(mid 313.261485 -376.947802)
		(end 313.202066 -377.246388)
		(width 0.14224)
		(layer "In6.Cu")
		(net "P5E_CPU0_P0_TX_DN<8>")
	)
	(arc
		(start 360.577892 -371.68582)
		(mid 359.656207 -372.30167)
		(end 358.569006 -372.517924)
		(width 0.14224)
		(layer "In6.Cu")
		(net "P5E_CPU0_P0_TX_DN<8>")
	)
	(arc
		(start 352.834702 -290.6395)
		(mid 353.062085 -291.095938)
		(end 352.834702 -291.552376)
		(width 0.1143)
		(layer "In6.Cu")
		(net "P5E_CPU0_P0_TX_DN<8>")
	)
	(arc
		(start 352.752406 -289.98164)
		(mid 352.596478 -290.285932)
		(end 352.752406 -290.590224)
		(width 0.1143)
		(layer "In6.Cu")
		(net "P5E_CPU0_P0_TX_DN<8>")
	)
	(arc
		(start 352.353118 -286.581342)
		(mid 352.531931 -286.783692)
		(end 352.59645 -287.045908)
		(width 0.1143)
		(layer "In6.Cu")
		(net "P5E_CPU0_P0_TX_DN<8>")
	)
	(arc
		(start 352.752406 -294.84193)
		(mid 352.703496 -294.883901)
		(end 352.66249 -294.933624)
		(width 0.1143)
		(layer "In6.Cu")
		(net "P5E_CPU0_P0_TX_DN<8>")
	)
	(arc
		(start 352.59645 -295.209468)
		(mid 352.587134 -295.31872)
		(end 352.55962 -295.42486)
		(width 0.1143)
		(layer "In6.Cu")
		(net "P5E_CPU0_P0_TX_DN<8>")
	)
	(arc
		(start 352.250248 -295.800526)
		(mid 352.215339 -295.852865)
		(end 352.203004 -295.914572)
		(width 0.1143)
		(layer "In6.Cu")
		(net "P5E_CPU0_P0_TX_DN<8>")
	)
	(arc
		(start 352.836734 -289.021012)
		(mid 353.059618 -289.475926)
		(end 352.836734 -289.93084)
		(width 0.1143)
		(layer "In6.Cu")
		(net "P5E_CPU0_P0_TX_DN<8>")
	)
	(arc
		(start 352.59645 -288.66592)
		(mid 352.637705 -288.836891)
		(end 352.752406 -288.970212)
		(width 0.1143)
		(layer "In6.Cu")
		(net "P5E_CPU0_P0_TX_DN<8>")
	)
	(arc
		(start 352.66249 -294.933624)
		(mid 352.613406 -295.034793)
		(end 352.59645 -295.145968)
		(width 0.1143)
		(layer "In6.Cu")
		(net "P5E_CPU0_P0_TX_DN<8>")
	)
	(arc
		(start 352.752406 -293.221664)
		(mid 352.596478 -293.525956)
		(end 352.752406 -293.830248)
		(width 0.1143)
		(layer "In6.Cu")
		(net "P5E_CPU0_P0_TX_DN<8>")
	)
	(arc
		(start 352.820478 -289.009582)
		(mid 352.828656 -289.015225)
		(end 352.836734 -289.021012)
		(width 0.1143)
		(layer "In6.Cu")
		(net "P5E_CPU0_P0_TX_DN<8>")
	)
	(arc
		(start 352.834702 -293.172388)
		(mid 352.827628 -293.177395)
		(end 352.820478 -293.182294)
		(width 0.1143)
		(layer "In6.Cu")
		(net "P5E_CPU0_P0_TX_DN<8>")
	)
	(arc
		(start 314.908946 -375.238772)
		(mid 314.856597 -375.274366)
		(end 314.809124 -375.316242)
		(width 0.14224)
		(layer "In6.Cu")
		(net "P5E_CPU0_P0_TX_DN<8>")
	)
	(arc
		(start 352.59645 -287.045908)
		(mid 352.637705 -287.216879)
		(end 352.752406 -287.3502)
		(width 0.1143)
		(layer "In6.Cu")
		(net "P5E_CPU0_P0_TX_DN<8>")
	)
	(arc
		(start 352.83267 -293.878)
		(mid 353.066323 -294.335962)
		(end 352.83267 -294.793924)
		(width 0.1143)
		(layer "In6.Cu")
		(net "P5E_CPU0_P0_TX_DN<8>")
	)
	(arc
		(start 315.30671 -375.013728)
		(mid 315.249065 -375.040043)
		(end 315.193426 -375.07037)
		(width 0.14224)
		(layer "In6.Cu")
		(net "P5E_CPU0_P0_TX_DN<8>")
	)
	(arc
		(start 352.750628 -288.363152)
		(mid 352.637221 -288.496041)
		(end 352.59645 -288.66592)
		(width 0.1143)
		(layer "In6.Cu")
		(net "P5E_CPU0_P0_TX_DN<8>")
	)
	(arc
		(start 353.06635 -287.856168)
		(mid 353.001114 -288.119759)
		(end 352.820478 -288.322512)
		(width 0.1143)
		(layer "In6.Cu")
		(net "P5E_CPU0_P0_TX_DN<8>")
	)
	(arc
		(start 352.834702 -291.552376)
		(mid 352.827628 -291.557383)
		(end 352.820478 -291.562282)
		(width 0.1143)
		(layer "In6.Cu")
		(net "P5E_CPU0_P0_TX_DN<8>")
	)
	(arc
		(start 322.338446 -372.517924)
		(mid 321.350318 -372.615235)
		(end 320.400172 -372.903496)
		(width 0.14224)
		(layer "In6.Cu")
		(net "P5E_CPU0_P0_TX_DN<8>")
	)
	(arc
		(start 352.820478 -292.249606)
		(mid 352.827627 -292.254506)
		(end 352.834702 -292.259512)
		(width 0.1143)
		(layer "In6.Cu")
		(net "P5E_CPU0_P0_TX_DN<8>")
	)
	(arc
		(start 352.784664 -287.36925)
		(mid 352.990886 -287.574894)
		(end 353.06635 -287.856168)
		(width 0.1143)
		(layer "In6.Cu")
		(net "P5E_CPU0_P0_TX_DN<8>")
	)
	(segment
		(start 311.520586 -383.31902)
		(end 311.520586 -382.61544)
		(width 0.12954)
		(layer "F.Cu")
		(net "P5E_CPU0_P0_TX_DN<7>")
	)
	(segment
		(start 311.816496 -383.61493)
		(end 311.520586 -383.31902)
		(width 0.12954)
		(layer "F.Cu")
		(net "P5E_CPU0_P0_TX_DN<7>")
	)
	(segment
		(start 311.520586 -382.61544)
		(end 311.791096 -382.34493)
		(width 0.12954)
		(layer "F.Cu")
		(net "P5E_CPU0_P0_TX_DN<7>")
	)
	(segment
		(start 352.968052 -284.350206)
		(end 352.5012 -284.616144)
		(width 0.12954)
		(layer "F.Cu")
		(net "P5E_CPU0_P0_TX_DN<7>")
	)
	(segment
		(start 351.656396 -285.421578)
		(end 351.656396 -285.42615)
		(width 0.1143)
		(layer "In6.Cu")
		(net "P5E_CPU0_P0_TX_DN<7>")
	)
	(segment
		(start 351.812352 -293.830248)
		(end 351.844102 -293.848536)
		(width 0.1143)
		(layer "In6.Cu")
		(net "P5E_CPU0_P0_TX_DN<7>")
	)
	(segment
		(start 320.290444 -371.937788)
		(end 313.726068 -374.657112)
		(width 0.14224)
		(layer "In6.Cu")
		(net "P5E_CPU0_P0_TX_DN<7>")
	)
	(segment
		(start 351.822258 -288.976054)
		(end 351.822766 -288.976054)
		(width 0.1143)
		(layer "In6.Cu")
		(net "P5E_CPU0_P0_TX_DN<7>")
	)
	(segment
		(start 351.812352 -290.590224)
		(end 351.844102 -290.608512)
		(width 0.1143)
		(layer "In6.Cu")
		(net "P5E_CPU0_P0_TX_DN<7>")
	)
	(segment
		(start 351.242122 -298.4754)
		(end 354.681028 -306.77739)
		(width 0.14224)
		(layer "In6.Cu")
		(net "P5E_CPU0_P0_TX_DN<7>")
	)
	(segment
		(start 351.812352 -292.210236)
		(end 351.844102 -292.228524)
		(width 0.1143)
		(layer "In6.Cu")
		(net "P5E_CPU0_P0_TX_DN<7>")
	)
	(segment
		(start 351.883218 -285.08071)
		(end 351.844102 -285.10357)
		(width 0.1143)
		(layer "In6.Cu")
		(net "P5E_CPU0_P0_TX_DN<7>")
	)
	(segment
		(start 311.500266 -377.988068)
		(end 311.500266 -381.987298)
		(width 0.14224)
		(layer "In6.Cu")
		(net "P5E_CPU0_P0_TX_DN<7>")
	)
	(segment
		(start 352.5012 -284.616144)
		(end 352.203258 -284.616144)
		(width 0.1143)
		(layer "In6.Cu")
		(net "P5E_CPU0_P0_TX_DN<7>")
	)
	(segment
		(start 351.844102 -290.608512)
		(end 351.883218 -290.631372)
		(width 0.1143)
		(layer "In6.Cu")
		(net "P5E_CPU0_P0_TX_DN<7>")
	)
	(segment
		(start 365.734346 -365.20882)
		(end 360.371898 -370.571268)
		(width 0.14224)
		(layer "In6.Cu")
		(net "P5E_CPU0_P0_TX_DN<7>")
	)
	(segment
		(start 351.812352 -285.121858)
		(end 351.808542 -285.124652)
		(width 0.1143)
		(layer "In6.Cu")
		(net "P5E_CPU0_P0_TX_DN<7>")
	)
	(segment
		(start 351.340674 -286.538924)
		(end 351.374202 -286.558482)
		(width 0.1143)
		(layer "In6.Cu")
		(net "P5E_CPU0_P0_TX_DN<7>")
	)
	(segment
		(start 351.844102 -294.823388)
		(end 351.84334 -294.823896)
		(width 0.1143)
		(layer "In6.Cu")
		(net "P5E_CPU0_P0_TX_DN<7>")
	)
	(segment
		(start 352.203258 -284.616144)
		(end 352.120454 -284.698948)
		(width 0.1143)
		(layer "In6.Cu")
		(net "P5E_CPU0_P0_TX_DN<7>")
	)
	(segment
		(start 351.844102 -287.368488)
		(end 351.880678 -287.389824)
		(width 0.1143)
		(layer "In6.Cu")
		(net "P5E_CPU0_P0_TX_DN<7>")
	)
	(segment
		(start 351.87763 -288.323528)
		(end 351.823528 -288.355278)
		(width 0.1143)
		(layer "In6.Cu")
		(net "P5E_CPU0_P0_TX_DN<7>")
	)
	(segment
		(start 351.883218 -293.180516)
		(end 351.844102 -293.203376)
		(width 0.1143)
		(layer "In6.Cu")
		(net "P5E_CPU0_P0_TX_DN<7>")
	)
	(segment
		(start 351.410524 -285.892494)
		(end 351.374202 -285.913576)
		(width 0.1143)
		(layer "In6.Cu")
		(net "P5E_CPU0_P0_TX_DN<7>")
	)
	(segment
		(start 351.374202 -286.558482)
		(end 351.410524 -286.579564)
		(width 0.1143)
		(layer "In6.Cu")
		(net "P5E_CPU0_P0_TX_DN<7>")
	)
	(segment
		(start 351.822766 -288.355786)
		(end 351.822512 -288.355786)
		(width 0.1143)
		(layer "In6.Cu")
		(net "P5E_CPU0_P0_TX_DN<7>")
	)
	(segment
		(start 351.242122 -296.252646)
		(end 351.242122 -296.281094)
		(width 0.1143)
		(layer "In6.Cu")
		(net "P5E_CPU0_P0_TX_DN<7>")
	)
	(segment
		(start 351.37217 -285.914846)
		(end 351.342452 -285.931864)
		(width 0.1143)
		(layer "In6.Cu")
		(net "P5E_CPU0_P0_TX_DN<7>")
	)
	(segment
		(start 351.823528 -288.355278)
		(end 351.822766 -288.355786)
		(width 0.1143)
		(layer "In6.Cu")
		(net "P5E_CPU0_P0_TX_DN<7>")
	)
	(segment
		(start 351.374202 -285.913576)
		(end 351.37344 -285.914084)
		(width 0.1143)
		(layer "In6.Cu")
		(net "P5E_CPU0_P0_TX_DN<7>")
	)
	(segment
		(start 351.883218 -288.320734)
		(end 351.87763 -288.323528)
		(width 0.1143)
		(layer "In6.Cu")
		(net "P5E_CPU0_P0_TX_DN<7>")
	)
	(segment
		(start 351.196402 -296.206926)
		(end 351.242122 -296.252646)
		(width 0.1143)
		(layer "In6.Cu")
		(net "P5E_CPU0_P0_TX_DN<7>")
	)
	(segment
		(start 357.92918 -371.58295)
		(end 322.074032 -371.58295)
		(width 0.14224)
		(layer "In6.Cu")
		(net "P5E_CPU0_P0_TX_DN<7>")
	)
	(segment
		(start 354.681028 -306.77739)
		(end 360.667046 -315.736224)
		(width 0.14224)
		(layer "In6.Cu")
		(net "P5E_CPU0_P0_TX_DN<7>")
	)
	(segment
		(start 351.822766 -288.976054)
		(end 351.882456 -289.010852)
		(width 0.1143)
		(layer "In6.Cu")
		(net "P5E_CPU0_P0_TX_DN<7>")
	)
	(segment
		(start 351.196402 -295.962324)
		(end 351.196402 -296.206926)
		(width 0.1143)
		(layer "In6.Cu")
		(net "P5E_CPU0_P0_TX_DN<7>")
	)
	(segment
		(start 351.844102 -293.203376)
		(end 351.812352 -293.221664)
		(width 0.1143)
		(layer "In6.Cu")
		(net "P5E_CPU0_P0_TX_DN<7>")
	)
	(segment
		(start 351.37344 -285.914084)
		(end 351.37217 -285.914846)
		(width 0.1143)
		(layer "In6.Cu")
		(net "P5E_CPU0_P0_TX_DN<7>")
	)
	(segment
		(start 351.430336 -295.661842)
		(end 351.243646 -295.848278)
		(width 0.1143)
		(layer "In6.Cu")
		(net "P5E_CPU0_P0_TX_DN<7>")
	)
	(segment
		(start 351.242122 -296.281094)
		(end 351.242122 -298.4754)
		(width 0.14224)
		(layer "In6.Cu")
		(net "P5E_CPU0_P0_TX_DN<7>")
	)
	(segment
		(start 351.844102 -289.963352)
		(end 351.812352 -289.98164)
		(width 0.1143)
		(layer "In6.Cu")
		(net "P5E_CPU0_P0_TX_DN<7>")
	)
	(segment
		(start 351.812352 -287.3502)
		(end 351.844102 -287.368488)
		(width 0.1143)
		(layer "In6.Cu")
		(net "P5E_CPU0_P0_TX_DN<7>")
	)
	(segment
		(start 369.620038 -328.769218)
		(end 371.848888 -341.17153)
		(width 0.14224)
		(layer "In6.Cu")
		(net "P5E_CPU0_P0_TX_DN<7>")
	)
	(segment
		(start 360.667046 -315.736224)
		(end 366.56391 -322.921122)
		(width 0.14224)
		(layer "In6.Cu")
		(net "P5E_CPU0_P0_TX_DN<7>")
	)
	(segment
		(start 351.844102 -291.583364)
		(end 351.812352 -291.601652)
		(width 0.1143)
		(layer "In6.Cu")
		(net "P5E_CPU0_P0_TX_DN<7>")
	)
	(segment
		(start 351.844102 -293.848536)
		(end 351.883218 -293.871396)
		(width 0.1143)
		(layer "In6.Cu")
		(net "P5E_CPU0_P0_TX_DN<7>")
	)
	(segment
		(start 351.844102 -292.228524)
		(end 351.883218 -292.251384)
		(width 0.1143)
		(layer "In6.Cu")
		(net "P5E_CPU0_P0_TX_DN<7>")
	)
	(segment
		(start 351.883218 -291.560504)
		(end 351.844102 -291.583364)
		(width 0.1143)
		(layer "In6.Cu")
		(net "P5E_CPU0_P0_TX_DN<7>")
	)
	(segment
		(start 351.883218 -289.940492)
		(end 351.844102 -289.963352)
		(width 0.1143)
		(layer "In6.Cu")
		(net "P5E_CPU0_P0_TX_DN<7>")
	)
	(segment
		(start 366.56391 -322.921122)
		(end 369.620038 -328.769218)
		(width 0.14224)
		(layer "In6.Cu")
		(net "P5E_CPU0_P0_TX_DN<7>")
	)
	(segment
		(start 351.883218 -294.800528)
		(end 351.845118 -294.82288)
		(width 0.1143)
		(layer "In6.Cu")
		(net "P5E_CPU0_P0_TX_DN<7>")
	)
	(segment
		(start 351.844102 -285.10357)
		(end 351.812352 -285.121858)
		(width 0.1143)
		(layer "In6.Cu")
		(net "P5E_CPU0_P0_TX_DN<7>")
	)
	(segment
		(start 311.54751 -382.101344)
		(end 311.791096 -382.34493)
		(width 0.14224)
		(layer "In6.Cu")
		(net "P5E_CPU0_P0_TX_DN<7>")
	)
	(segment
		(start 371.848888 -341.17153)
		(end 371.848888 -350.446848)
		(width 0.14224)
		(layer "In6.Cu")
		(net "P5E_CPU0_P0_TX_DN<7>")
	)
	(segment
		(start 351.845118 -294.82288)
		(end 351.844102 -294.823388)
		(width 0.1143)
		(layer "In6.Cu")
		(net "P5E_CPU0_P0_TX_DN<7>")
	)
	(segment
		(start 351.84334 -294.823896)
		(end 351.812352 -294.841676)
		(width 0.1143)
		(layer "In6.Cu")
		(net "P5E_CPU0_P0_TX_DN<7>")
	)
	(arc
		(start 351.812352 -294.841676)
		(mid 351.700494 -294.973772)
		(end 351.656396 -295.141142)
		(width 0.1143)
		(layer "In6.Cu")
		(net "P5E_CPU0_P0_TX_DN<7>")
	)
	(arc
		(start 351.883218 -292.251384)
		(mid 352.126545 -292.71595)
		(end 351.883218 -293.180516)
		(width 0.1143)
		(layer "In6.Cu")
		(net "P5E_CPU0_P0_TX_DN<7>")
	)
	(arc
		(start 351.822512 -288.355786)
		(mid 351.64397 -288.66581)
		(end 351.822258 -288.976054)
		(width 0.1143)
		(layer "In6.Cu")
		(net "P5E_CPU0_P0_TX_DN<7>")
	)
	(arc
		(start 351.812352 -293.221664)
		(mid 351.661967 -293.525956)
		(end 351.812352 -293.830248)
		(width 0.1143)
		(layer "In6.Cu")
		(net "P5E_CPU0_P0_TX_DN<7>")
	)
	(arc
		(start 360.371898 -370.571268)
		(mid 359.251141 -371.320007)
		(end 357.92918 -371.58295)
		(width 0.14224)
		(layer "In6.Cu")
		(net "P5E_CPU0_P0_TX_DN<7>")
	)
	(arc
		(start 351.42678 -285.881064)
		(mid 351.418702 -285.88685)
		(end 351.410524 -285.892494)
		(width 0.1143)
		(layer "In6.Cu")
		(net "P5E_CPU0_P0_TX_DN<7>")
	)
	(arc
		(start 351.186496 -286.236156)
		(mid 351.227258 -286.40604)
		(end 351.340674 -286.538924)
		(width 0.1143)
		(layer "In6.Cu")
		(net "P5E_CPU0_P0_TX_DN<7>")
	)
	(arc
		(start 351.808542 -285.124652)
		(mid 351.696632 -285.254755)
		(end 351.656396 -285.421578)
		(width 0.1143)
		(layer "In6.Cu")
		(net "P5E_CPU0_P0_TX_DN<7>")
	)
	(arc
		(start 351.812352 -289.98164)
		(mid 351.658411 -290.285932)
		(end 351.812352 -290.590224)
		(width 0.1143)
		(layer "In6.Cu")
		(net "P5E_CPU0_P0_TX_DN<7>")
	)
	(arc
		(start 322.074032 -371.58295)
		(mid 321.164758 -371.672513)
		(end 320.290444 -371.937788)
		(width 0.14224)
		(layer "In6.Cu")
		(net "P5E_CPU0_P0_TX_DN<7>")
	)
	(arc
		(start 351.880678 -287.389824)
		(mid 352.06133 -287.592569)
		(end 352.12655 -287.856168)
		(width 0.1143)
		(layer "In6.Cu")
		(net "P5E_CPU0_P0_TX_DN<7>")
	)
	(arc
		(start 351.410524 -286.579564)
		(mid 351.591176 -286.782309)
		(end 351.656396 -287.045908)
		(width 0.1143)
		(layer "In6.Cu")
		(net "P5E_CPU0_P0_TX_DN<7>")
	)
	(arc
		(start 351.883218 -290.631372)
		(mid 352.126545 -291.095938)
		(end 351.883218 -291.560504)
		(width 0.1143)
		(layer "In6.Cu")
		(net "P5E_CPU0_P0_TX_DN<7>")
	)
	(arc
		(start 351.882456 -289.010852)
		(mid 351.882837 -289.011106)
		(end 351.883218 -289.01136)
		(width 0.1143)
		(layer "In6.Cu")
		(net "P5E_CPU0_P0_TX_DN<7>")
	)
	(arc
		(start 313.726068 -374.657112)
		(mid 312.107906 -375.984971)
		(end 311.500266 -377.988068)
		(width 0.14224)
		(layer "In6.Cu")
		(net "P5E_CPU0_P0_TX_DN<7>")
	)
	(arc
		(start 352.116644 -284.721808)
		(mid 352.035211 -284.924206)
		(end 351.883218 -285.08071)
		(width 0.1143)
		(layer "In6.Cu")
		(net "P5E_CPU0_P0_TX_DN<7>")
	)
	(arc
		(start 351.243646 -295.848278)
		(mid 351.208737 -295.900617)
		(end 351.196402 -295.962324)
		(width 0.1143)
		(layer "In6.Cu")
		(net "P5E_CPU0_P0_TX_DN<7>")
	)
	(arc
		(start 311.500266 -381.987298)
		(mid 311.512543 -382.049021)
		(end 311.54751 -382.101344)
		(width 0.14224)
		(layer "In6.Cu")
		(net "P5E_CPU0_P0_TX_DN<7>")
	)
	(arc
		(start 352.12655 -287.856168)
		(mid 352.062035 -288.118387)
		(end 351.883218 -288.320734)
		(width 0.1143)
		(layer "In6.Cu")
		(net "P5E_CPU0_P0_TX_DN<7>")
	)
	(arc
		(start 351.656396 -287.045908)
		(mid 351.699456 -287.215963)
		(end 351.812352 -287.3502)
		(width 0.1143)
		(layer "In6.Cu")
		(net "P5E_CPU0_P0_TX_DN<7>")
	)
	(arc
		(start 351.656396 -285.432754)
		(mid 351.591524 -285.682496)
		(end 351.42678 -285.881064)
		(width 0.1143)
		(layer "In6.Cu")
		(net "P5E_CPU0_P0_TX_DN<7>")
	)
	(arc
		(start 351.656396 -295.141142)
		(mid 351.592877 -295.422993)
		(end 351.430336 -295.661842)
		(width 0.1143)
		(layer "In6.Cu")
		(net "P5E_CPU0_P0_TX_DN<7>")
	)
	(arc
		(start 351.812352 -291.601652)
		(mid 351.660763 -291.905944)
		(end 351.812352 -292.210236)
		(width 0.1143)
		(layer "In6.Cu")
		(net "P5E_CPU0_P0_TX_DN<7>")
	)
	(arc
		(start 351.342452 -285.931864)
		(mid 351.227776 -286.065198)
		(end 351.186496 -286.236156)
		(width 0.1143)
		(layer "In6.Cu")
		(net "P5E_CPU0_P0_TX_DN<7>")
	)
	(arc
		(start 371.848888 -350.446848)
		(mid 370.259773 -358.435958)
		(end 365.734346 -365.20882)
		(width 0.14224)
		(layer "In6.Cu")
		(net "P5E_CPU0_P0_TX_DN<7>")
	)
	(arc
		(start 351.883218 -293.871396)
		(mid 352.126545 -294.335962)
		(end 351.883218 -294.800528)
		(width 0.1143)
		(layer "In6.Cu")
		(net "P5E_CPU0_P0_TX_DN<7>")
	)
	(arc
		(start 351.656396 -285.42615)
		(mid 351.656406 -285.429452)
		(end 351.656396 -285.432754)
		(width 0.1143)
		(layer "In6.Cu")
		(net "P5E_CPU0_P0_TX_DN<7>")
	)
	(arc
		(start 352.120454 -284.698948)
		(mid 352.118666 -284.710397)
		(end 352.116644 -284.721808)
		(width 0.1143)
		(layer "In6.Cu")
		(net "P5E_CPU0_P0_TX_DN<7>")
	)
	(arc
		(start 351.883218 -289.01136)
		(mid 352.126545 -289.475926)
		(end 351.883218 -289.940492)
		(width 0.1143)
		(layer "In6.Cu")
		(net "P5E_CPU0_P0_TX_DN<7>")
	)
	(segment
		(start 308.116986 -377.68784)
		(end 308.387496 -377.41733)
		(width 0.12954)
		(layer "F.Cu")
		(net "P5E_CPU0_P0_TX_DN<6>")
	)
	(segment
		(start 308.116986 -378.39142)
		(end 308.116986 -377.68784)
		(width 0.12954)
		(layer "F.Cu")
		(net "P5E_CPU0_P0_TX_DN<6>")
	)
	(segment
		(start 350.14789 -281.110182)
		(end 349.681038 -281.37612)
		(width 0.12954)
		(layer "F.Cu")
		(net "P5E_CPU0_P0_TX_DN<6>")
	)
	(segment
		(start 308.412896 -378.68733)
		(end 308.116986 -378.39142)
		(width 0.12954)
		(layer "F.Cu")
		(net "P5E_CPU0_P0_TX_DN<6>")
	)
	(segment
		(start 350.40062 -286.538924)
		(end 350.434148 -286.558482)
		(width 0.1143)
		(layer "In6.Cu")
		(net "P5E_CPU0_P0_TX_DN<6>")
	)
	(segment
		(start 350.437704 -283.320744)
		(end 350.473264 -283.341572)
		(width 0.1143)
		(layer "In6.Cu")
		(net "P5E_CPU0_P0_TX_DN<6>")
	)
	(segment
		(start 350.297242 -296.281094)
		(end 350.297242 -298.630594)
		(width 0.14224)
		(layer "In6.Cu")
		(net "P5E_CPU0_P0_TX_DN<6>")
	)
	(segment
		(start 350.42729 -284.297628)
		(end 350.425258 -284.298898)
		(width 0.1143)
		(layer "In6.Cu")
		(net "P5E_CPU0_P0_TX_DN<6>")
	)
	(segment
		(start 350.433386 -285.914084)
		(end 350.432116 -285.914846)
		(width 0.1143)
		(layer "In6.Cu")
		(net "P5E_CPU0_P0_TX_DN<6>")
	)
	(segment
		(start 350.430592 -284.295596)
		(end 350.429322 -284.296358)
		(width 0.1143)
		(layer "In6.Cu")
		(net "P5E_CPU0_P0_TX_DN<6>")
	)
	(segment
		(start 308.096666 -377.1265)
		(end 308.387496 -377.41733)
		(width 0.14224)
		(layer "In6.Cu")
		(net "P5E_CPU0_P0_TX_DN<6>")
	)
	(segment
		(start 362.835698 -319.848484)
		(end 365.779558 -323.435472)
		(width 0.14224)
		(layer "In6.Cu")
		(net "P5E_CPU0_P0_TX_DN<6>")
	)
	(segment
		(start 350.559624 -295.605454)
		(end 350.298766 -295.866058)
		(width 0.1143)
		(layer "In6.Cu")
		(net "P5E_CPU0_P0_TX_DN<6>")
	)
	(segment
		(start 350.432116 -284.294834)
		(end 350.430592 -284.295596)
		(width 0.1143)
		(layer "In6.Cu")
		(net "P5E_CPU0_P0_TX_DN<6>")
	)
	(segment
		(start 350.434148 -284.293564)
		(end 350.433386 -284.294072)
		(width 0.1143)
		(layer "In6.Cu")
		(net "P5E_CPU0_P0_TX_DN<6>")
	)
	(segment
		(start 350.904048 -290.608512)
		(end 350.943164 -290.631372)
		(width 0.1143)
		(layer "In6.Cu")
		(net "P5E_CPU0_P0_TX_DN<6>")
	)
	(segment
		(start 350.434148 -284.938724)
		(end 350.435164 -284.939232)
		(width 0.1143)
		(layer "In6.Cu")
		(net "P5E_CPU0_P0_TX_DN<6>")
	)
	(segment
		(start 350.943164 -293.180516)
		(end 350.904048 -293.203376)
		(width 0.1143)
		(layer "In6.Cu")
		(net "P5E_CPU0_P0_TX_DN<6>")
	)
	(segment
		(start 350.402398 -284.920436)
		(end 350.434148 -284.938724)
		(width 0.1143)
		(layer "In6.Cu")
		(net "P5E_CPU0_P0_TX_DN<6>")
	)
	(segment
		(start 350.297242 -298.630594)
		(end 353.854766 -307.219096)
		(width 0.14224)
		(layer "In6.Cu")
		(net "P5E_CPU0_P0_TX_DN<6>")
	)
	(segment
		(start 308.51729 -375.717562)
		(end 308.185058 -376.049794)
		(width 0.14224)
		(layer "In6.Cu")
		(net "P5E_CPU0_P0_TX_DN<6>")
	)
	(segment
		(start 350.873568 -292.210744)
		(end 350.904048 -292.228524)
		(width 0.1143)
		(layer "In6.Cu")
		(net "P5E_CPU0_P0_TX_DN<6>")
	)
	(segment
		(start 357.78821 -370.647976)
		(end 321.966336 -370.647976)
		(width 0.14224)
		(layer "In6.Cu")
		(net "P5E_CPU0_P0_TX_DN<6>")
	)
	(segment
		(start 350.904048 -289.963352)
		(end 350.873568 -289.981132)
		(width 0.1143)
		(layer "In6.Cu")
		(net "P5E_CPU0_P0_TX_DN<6>")
	)
	(segment
		(start 350.42856 -285.916878)
		(end 350.42729 -285.91764)
		(width 0.1143)
		(layer "In6.Cu")
		(net "P5E_CPU0_P0_TX_DN<6>")
	)
	(segment
		(start 349.933514 -282.490926)
		(end 350.00311 -282.531566)
		(width 0.1143)
		(layer "In6.Cu")
		(net "P5E_CPU0_P0_TX_DN<6>")
	)
	(segment
		(start 350.42729 -285.91764)
		(end 350.425258 -285.91891)
		(width 0.1143)
		(layer "In6.Cu")
		(net "P5E_CPU0_P0_TX_DN<6>")
	)
	(segment
		(start 350.873568 -290.590732)
		(end 350.904048 -290.608512)
		(width 0.1143)
		(layer "In6.Cu")
		(net "P5E_CPU0_P0_TX_DN<6>")
	)
	(segment
		(start 308.096666 -376.33021)
		(end 308.096666 -377.1265)
		(width 0.14224)
		(layer "In6.Cu")
		(net "P5E_CPU0_P0_TX_DN<6>")
	)
	(segment
		(start 349.383096 -281.37612)
		(end 349.313246 -281.44597)
		(width 0.1143)
		(layer "In6.Cu")
		(net "P5E_CPU0_P0_TX_DN<6>")
	)
	(segment
		(start 350.873568 -293.830756)
		(end 350.904048 -293.848536)
		(width 0.1143)
		(layer "In6.Cu")
		(net "P5E_CPU0_P0_TX_DN<6>")
	)
	(segment
		(start 362.835698 -319.84823)
		(end 362.835698 -319.848484)
		(width 0.14224)
		(layer "In6.Cu")
		(net "P5E_CPU0_P0_TX_DN<6>")
	)
	(segment
		(start 359.919016 -316.29477)
		(end 362.835698 -319.84823)
		(width 0.14224)
		(layer "In6.Cu")
		(net "P5E_CPU0_P0_TX_DN<6>")
	)
	(segment
		(start 350.904048 -288.343594)
		(end 350.871536 -288.36239)
		(width 0.1143)
		(layer "In6.Cu")
		(net "P5E_CPU0_P0_TX_DN<6>")
	)
	(segment
		(start 350.425258 -285.91891)
		(end 350.422718 -285.920434)
		(width 0.1143)
		(layer "In6.Cu")
		(net "P5E_CPU0_P0_TX_DN<6>")
	)
	(segment
		(start 350.904048 -293.203376)
		(end 350.873568 -293.221156)
		(width 0.1143)
		(layer "In6.Cu")
		(net "P5E_CPU0_P0_TX_DN<6>")
	)
	(segment
		(start 350.943164 -294.800528)
		(end 350.872298 -294.84193)
		(width 0.1143)
		(layer "In6.Cu")
		(net "P5E_CPU0_P0_TX_DN<6>")
	)
	(segment
		(start 350.434148 -283.318712)
		(end 350.435164 -283.31922)
		(width 0.1143)
		(layer "In6.Cu")
		(net "P5E_CPU0_P0_TX_DN<6>")
	)
	(segment
		(start 350.425258 -284.298898)
		(end 350.422718 -284.300422)
		(width 0.1143)
		(layer "In6.Cu")
		(net "P5E_CPU0_P0_TX_DN<6>")
	)
	(segment
		(start 350.433386 -284.294072)
		(end 350.432116 -284.294834)
		(width 0.1143)
		(layer "In6.Cu")
		(net "P5E_CPU0_P0_TX_DN<6>")
	)
	(segment
		(start 350.429322 -284.296358)
		(end 350.42856 -284.296866)
		(width 0.1143)
		(layer "In6.Cu")
		(net "P5E_CPU0_P0_TX_DN<6>")
	)
	(segment
		(start 365.779558 -323.435472)
		(end 368.708178 -329.038458)
		(width 0.14224)
		(layer "In6.Cu")
		(net "P5E_CPU0_P0_TX_DN<6>")
	)
	(segment
		(start 350.904048 -292.228524)
		(end 350.943164 -292.251384)
		(width 0.1143)
		(layer "In6.Cu")
		(net "P5E_CPU0_P0_TX_DN<6>")
	)
	(segment
		(start 350.429322 -285.91637)
		(end 350.42856 -285.916878)
		(width 0.1143)
		(layer "In6.Cu")
		(net "P5E_CPU0_P0_TX_DN<6>")
	)
	(segment
		(start 350.716342 -295.145968)
		(end 350.716342 -295.180512)
		(width 0.1143)
		(layer "In6.Cu")
		(net "P5E_CPU0_P0_TX_DN<6>")
	)
	(segment
		(start 350.435164 -283.31922)
		(end 350.436688 -283.320236)
		(width 0.1143)
		(layer "In6.Cu")
		(net "P5E_CPU0_P0_TX_DN<6>")
	)
	(segment
		(start 350.422718 -284.300422)
		(end 350.402398 -284.311852)
		(width 0.1143)
		(layer "In6.Cu")
		(net "P5E_CPU0_P0_TX_DN<6>")
	)
	(segment
		(start 350.435164 -284.939232)
		(end 350.436688 -284.940248)
		(width 0.1143)
		(layer "In6.Cu")
		(net "P5E_CPU0_P0_TX_DN<6>")
	)
	(segment
		(start 350.430592 -285.915608)
		(end 350.429322 -285.91637)
		(width 0.1143)
		(layer "In6.Cu")
		(net "P5E_CPU0_P0_TX_DN<6>")
	)
	(segment
		(start 350.873568 -288.97072)
		(end 350.904048 -288.9885)
		(width 0.1143)
		(layer "In6.Cu")
		(net "P5E_CPU0_P0_TX_DN<6>")
	)
	(segment
		(start 350.904048 -293.848536)
		(end 350.943164 -293.871396)
		(width 0.1143)
		(layer "In6.Cu")
		(net "P5E_CPU0_P0_TX_DN<6>")
	)
	(segment
		(start 350.42856 -284.296866)
		(end 350.42729 -284.297628)
		(width 0.1143)
		(layer "In6.Cu")
		(net "P5E_CPU0_P0_TX_DN<6>")
	)
	(segment
		(start 350.251522 -296.206926)
		(end 350.297242 -296.252646)
		(width 0.1143)
		(layer "In6.Cu")
		(net "P5E_CPU0_P0_TX_DN<6>")
	)
	(segment
		(start 350.297242 -296.252646)
		(end 350.297242 -296.281094)
		(width 0.1143)
		(layer "In6.Cu")
		(net "P5E_CPU0_P0_TX_DN<6>")
	)
	(segment
		(start 350.433386 -283.318204)
		(end 350.434148 -283.318712)
		(width 0.1143)
		(layer "In6.Cu")
		(net "P5E_CPU0_P0_TX_DN<6>")
	)
	(segment
		(start 350.434148 -285.913576)
		(end 350.433386 -285.914084)
		(width 0.1143)
		(layer "In6.Cu")
		(net "P5E_CPU0_P0_TX_DN<6>")
	)
	(segment
		(start 320.045334 -371.02923)
		(end 309.945532 -375.203466)
		(width 0.14224)
		(layer "In6.Cu")
		(net "P5E_CPU0_P0_TX_DN<6>")
	)
	(segment
		(start 350.436688 -283.320236)
		(end 350.437704 -283.320744)
		(width 0.1143)
		(layer "In6.Cu")
		(net "P5E_CPU0_P0_TX_DN<6>")
	)
	(segment
		(start 368.708178 -329.038458)
		(end 370.916708 -341.32647)
		(width 0.14224)
		(layer "In6.Cu")
		(net "P5E_CPU0_P0_TX_DN<6>")
	)
	(segment
		(start 353.854766 -307.219096)
		(end 359.919016 -316.29477)
		(width 0.14224)
		(layer "In6.Cu")
		(net "P5E_CPU0_P0_TX_DN<6>")
	)
	(segment
		(start 370.916708 -341.32647)
		(end 370.916708 -350.229678)
		(width 0.14224)
		(layer "In6.Cu")
		(net "P5E_CPU0_P0_TX_DN<6>")
	)
	(segment
		(start 350.473264 -285.890716)
		(end 350.434148 -285.913576)
		(width 0.1143)
		(layer "In6.Cu")
		(net "P5E_CPU0_P0_TX_DN<6>")
	)
	(segment
		(start 350.473264 -284.270704)
		(end 350.434148 -284.293564)
		(width 0.1143)
		(layer "In6.Cu")
		(net "P5E_CPU0_P0_TX_DN<6>")
	)
	(segment
		(start 350.943164 -291.560504)
		(end 350.904048 -291.583364)
		(width 0.1143)
		(layer "In6.Cu")
		(net "P5E_CPU0_P0_TX_DN<6>")
	)
	(segment
		(start 349.681038 -281.37612)
		(end 349.383096 -281.37612)
		(width 0.1143)
		(layer "In6.Cu")
		(net "P5E_CPU0_P0_TX_DN<6>")
	)
	(segment
		(start 350.943164 -288.320734)
		(end 350.904048 -288.343594)
		(width 0.1143)
		(layer "In6.Cu")
		(net "P5E_CPU0_P0_TX_DN<6>")
	)
	(segment
		(start 350.251522 -295.980104)
		(end 350.251522 -296.206926)
		(width 0.1143)
		(layer "In6.Cu")
		(net "P5E_CPU0_P0_TX_DN<6>")
	)
	(segment
		(start 350.436688 -284.940248)
		(end 350.473264 -284.961584)
		(width 0.1143)
		(layer "In6.Cu")
		(net "P5E_CPU0_P0_TX_DN<6>")
	)
	(segment
		(start 364.92307 -364.69955)
		(end 359.813606 -369.809014)
		(width 0.14224)
		(layer "In6.Cu")
		(net "P5E_CPU0_P0_TX_DN<6>")
	)
	(segment
		(start 350.402398 -283.300424)
		(end 350.433386 -283.318204)
		(width 0.1143)
		(layer "In6.Cu")
		(net "P5E_CPU0_P0_TX_DN<6>")
	)
	(segment
		(start 350.432116 -285.914846)
		(end 350.430592 -285.915608)
		(width 0.1143)
		(layer "In6.Cu")
		(net "P5E_CPU0_P0_TX_DN<6>")
	)
	(segment
		(start 350.422718 -285.920434)
		(end 350.402398 -285.931864)
		(width 0.1143)
		(layer "In6.Cu")
		(net "P5E_CPU0_P0_TX_DN<6>")
	)
	(segment
		(start 308.09057 -376.277632)
		(end 308.09057 -376.324114)
		(width 0.14224)
		(layer "In6.Cu")
		(net "P5E_CPU0_P0_TX_DN<6>")
	)
	(segment
		(start 350.943164 -289.940492)
		(end 350.904048 -289.963352)
		(width 0.1143)
		(layer "In6.Cu")
		(net "P5E_CPU0_P0_TX_DN<6>")
	)
	(segment
		(start 350.434148 -286.558482)
		(end 350.473264 -286.581342)
		(width 0.1143)
		(layer "In6.Cu")
		(net "P5E_CPU0_P0_TX_DN<6>")
	)
	(segment
		(start 349.493586 -281.69997)
		(end 349.499682 -281.703526)
		(width 0.1143)
		(layer "In6.Cu")
		(net "P5E_CPU0_P0_TX_DN<6>")
	)
	(segment
		(start 308.09057 -376.324114)
		(end 308.096666 -376.33021)
		(width 0.14224)
		(layer "In6.Cu")
		(net "P5E_CPU0_P0_TX_DN<6>")
	)
	(segment
		(start 350.873568 -287.350708)
		(end 350.940624 -287.389824)
		(width 0.1143)
		(layer "In6.Cu")
		(net "P5E_CPU0_P0_TX_DN<6>")
	)
	(segment
		(start 350.904048 -288.9885)
		(end 350.943164 -289.01136)
		(width 0.1143)
		(layer "In6.Cu")
		(net "P5E_CPU0_P0_TX_DN<6>")
	)
	(segment
		(start 350.904048 -291.583364)
		(end 350.873568 -291.601144)
		(width 0.1143)
		(layer "In6.Cu")
		(net "P5E_CPU0_P0_TX_DN<6>")
	)
	(arc
		(start 350.943164 -289.01136)
		(mid 351.186491 -289.475926)
		(end 350.943164 -289.940492)
		(width 0.1143)
		(layer "In6.Cu")
		(net "P5E_CPU0_P0_TX_DN<6>")
	)
	(arc
		(start 350.246442 -282.996132)
		(mid 350.287697 -283.167103)
		(end 350.402398 -283.300424)
		(width 0.1143)
		(layer "In6.Cu")
		(net "P5E_CPU0_P0_TX_DN<6>")
	)
	(arc
		(start 350.872298 -294.84193)
		(mid 350.757622 -294.975121)
		(end 350.716342 -295.145968)
		(width 0.1143)
		(layer "In6.Cu")
		(net "P5E_CPU0_P0_TX_DN<6>")
	)
	(arc
		(start 350.473264 -283.341572)
		(mid 350.716591 -283.806138)
		(end 350.473264 -284.270704)
		(width 0.1143)
		(layer "In6.Cu")
		(net "P5E_CPU0_P0_TX_DN<6>")
	)
	(arc
		(start 350.873568 -289.981132)
		(mid 350.716591 -290.285932)
		(end 350.873568 -290.590732)
		(width 0.1143)
		(layer "In6.Cu")
		(net "P5E_CPU0_P0_TX_DN<6>")
	)
	(arc
		(start 349.313246 -281.44597)
		(mid 349.375597 -281.592733)
		(end 349.493586 -281.69997)
		(width 0.1143)
		(layer "In6.Cu")
		(net "P5E_CPU0_P0_TX_DN<6>")
	)
	(arc
		(start 350.402398 -285.931864)
		(mid 350.287722 -286.065198)
		(end 350.246442 -286.236156)
		(width 0.1143)
		(layer "In6.Cu")
		(net "P5E_CPU0_P0_TX_DN<6>")
	)
	(arc
		(start 370.916708 -350.229678)
		(mid 369.359016 -358.060724)
		(end 364.92307 -364.69955)
		(width 0.14224)
		(layer "In6.Cu")
		(net "P5E_CPU0_P0_TX_DN<6>")
	)
	(arc
		(start 350.943164 -293.871396)
		(mid 351.186491 -294.335962)
		(end 350.943164 -294.800528)
		(width 0.1143)
		(layer "In6.Cu")
		(net "P5E_CPU0_P0_TX_DN<6>")
	)
	(arc
		(start 309.524146 -375.290588)
		(mid 308.979149 -375.406063)
		(end 308.51729 -375.717562)
		(width 0.14224)
		(layer "In6.Cu")
		(net "P5E_CPU0_P0_TX_DN<6>")
	)
	(arc
		(start 350.473264 -286.581342)
		(mid 350.652077 -286.783692)
		(end 350.716596 -287.045908)
		(width 0.1143)
		(layer "In6.Cu")
		(net "P5E_CPU0_P0_TX_DN<6>")
	)
	(arc
		(start 350.298766 -295.866058)
		(mid 350.263857 -295.918397)
		(end 350.251522 -295.980104)
		(width 0.1143)
		(layer "In6.Cu")
		(net "P5E_CPU0_P0_TX_DN<6>")
	)
	(arc
		(start 349.776542 -282.186126)
		(mid 349.818091 -282.357548)
		(end 349.933514 -282.490926)
		(width 0.1143)
		(layer "In6.Cu")
		(net "P5E_CPU0_P0_TX_DN<6>")
	)
	(arc
		(start 350.716596 -288.66592)
		(mid 350.758145 -288.837342)
		(end 350.873568 -288.97072)
		(width 0.1143)
		(layer "In6.Cu")
		(net "P5E_CPU0_P0_TX_DN<6>")
	)
	(arc
		(start 321.966336 -370.647976)
		(mid 320.987095 -370.744181)
		(end 320.045334 -371.02923)
		(width 0.14224)
		(layer "In6.Cu")
		(net "P5E_CPU0_P0_TX_DN<6>")
	)
	(arc
		(start 350.716596 -287.045908)
		(mid 350.758145 -287.21733)
		(end 350.873568 -287.350708)
		(width 0.1143)
		(layer "In6.Cu")
		(net "P5E_CPU0_P0_TX_DN<6>")
	)
	(arc
		(start 309.945532 -375.203466)
		(mid 309.738943 -375.266873)
		(end 309.524146 -375.290588)
		(width 0.14224)
		(layer "In6.Cu")
		(net "P5E_CPU0_P0_TX_DN<6>")
	)
	(arc
		(start 349.499682 -281.703526)
		(mid 349.702409 -281.907939)
		(end 349.776542 -282.186126)
		(width 0.1143)
		(layer "In6.Cu")
		(net "P5E_CPU0_P0_TX_DN<6>")
	)
	(arc
		(start 350.943164 -292.251384)
		(mid 351.186491 -292.71595)
		(end 350.943164 -293.180516)
		(width 0.1143)
		(layer "In6.Cu")
		(net "P5E_CPU0_P0_TX_DN<6>")
	)
	(arc
		(start 350.246442 -286.236156)
		(mid 350.287204 -286.40604)
		(end 350.40062 -286.538924)
		(width 0.1143)
		(layer "In6.Cu")
		(net "P5E_CPU0_P0_TX_DN<6>")
	)
	(arc
		(start 350.716342 -295.180512)
		(mid 350.705157 -295.307192)
		(end 350.671892 -295.42994)
		(width 0.1143)
		(layer "In6.Cu")
		(net "P5E_CPU0_P0_TX_DN<6>")
	)
	(arc
		(start 350.873568 -293.221156)
		(mid 350.716591 -293.525956)
		(end 350.873568 -293.830756)
		(width 0.1143)
		(layer "In6.Cu")
		(net "P5E_CPU0_P0_TX_DN<6>")
	)
	(arc
		(start 350.473264 -284.961584)
		(mid 350.716591 -285.42615)
		(end 350.473264 -285.890716)
		(width 0.1143)
		(layer "In6.Cu")
		(net "P5E_CPU0_P0_TX_DN<6>")
	)
	(arc
		(start 359.813606 -369.809014)
		(mid 358.884346 -370.429925)
		(end 357.78821 -370.647976)
		(width 0.14224)
		(layer "In6.Cu")
		(net "P5E_CPU0_P0_TX_DN<6>")
	)
	(arc
		(start 350.940624 -287.389824)
		(mid 351.121276 -287.592569)
		(end 351.186496 -287.856168)
		(width 0.1143)
		(layer "In6.Cu")
		(net "P5E_CPU0_P0_TX_DN<6>")
	)
	(arc
		(start 350.671892 -295.42994)
		(mid 350.625269 -295.52378)
		(end 350.559624 -295.605454)
		(width 0.1143)
		(layer "In6.Cu")
		(net "P5E_CPU0_P0_TX_DN<6>")
	)
	(arc
		(start 308.185058 -376.049794)
		(mid 308.115104 -376.154298)
		(end 308.09057 -376.277632)
		(width 0.14224)
		(layer "In6.Cu")
		(net "P5E_CPU0_P0_TX_DN<6>")
	)
	(arc
		(start 350.943164 -290.631372)
		(mid 351.186491 -291.095938)
		(end 350.943164 -291.560504)
		(width 0.1143)
		(layer "In6.Cu")
		(net "P5E_CPU0_P0_TX_DN<6>")
	)
	(arc
		(start 350.873568 -291.601144)
		(mid 350.716591 -291.905944)
		(end 350.873568 -292.210744)
		(width 0.1143)
		(layer "In6.Cu")
		(net "P5E_CPU0_P0_TX_DN<6>")
	)
	(arc
		(start 350.402398 -284.311852)
		(mid 350.24647 -284.616144)
		(end 350.402398 -284.920436)
		(width 0.1143)
		(layer "In6.Cu")
		(net "P5E_CPU0_P0_TX_DN<6>")
	)
	(arc
		(start 351.186496 -287.856168)
		(mid 351.121981 -288.118387)
		(end 350.943164 -288.320734)
		(width 0.1143)
		(layer "In6.Cu")
		(net "P5E_CPU0_P0_TX_DN<6>")
	)
	(arc
		(start 350.871536 -288.36239)
		(mid 350.757607 -288.495537)
		(end 350.716596 -288.66592)
		(width 0.1143)
		(layer "In6.Cu")
		(net "P5E_CPU0_P0_TX_DN<6>")
	)
	(arc
		(start 350.00311 -282.531566)
		(mid 350.181923 -282.733916)
		(end 350.246442 -282.996132)
		(width 0.1143)
		(layer "In6.Cu")
		(net "P5E_CPU0_P0_TX_DN<6>")
	)
	(segment
		(start 306.415186 -380.85522)
		(end 306.415186 -380.15164)
		(width 0.12954)
		(layer "F.Cu")
		(net "P5E_CPU0_P0_TX_DN<5>")
	)
	(segment
		(start 306.711096 -381.15113)
		(end 306.415186 -380.85522)
		(width 0.12954)
		(layer "F.Cu")
		(net "P5E_CPU0_P0_TX_DN<5>")
	)
	(segment
		(start 350.14789 -285.970218)
		(end 349.681038 -286.236156)
		(width 0.12954)
		(layer "F.Cu")
		(net "P5E_CPU0_P0_TX_DN<5>")
	)
	(segment
		(start 306.415186 -380.15164)
		(end 306.685696 -379.88113)
		(width 0.12954)
		(layer "F.Cu")
		(net "P5E_CPU0_P0_TX_DN<5>")
	)
	(segment
		(start 349.681038 -286.236156)
		(end 349.383096 -286.236156)
		(width 0.1143)
		(layer "In6.Cu")
		(net "P5E_CPU0_P0_TX_DN<5>")
	)
	(segment
		(start 350.00311 -293.180516)
		(end 349.963994 -293.203376)
		(width 0.1143)
		(layer "In6.Cu")
		(net "P5E_CPU0_P0_TX_DN<5>")
	)
	(segment
		(start 349.494094 -286.558482)
		(end 349.53321 -286.581342)
		(width 0.1143)
		(layer "In6.Cu")
		(net "P5E_CPU0_P0_TX_DN<5>")
	)
	(segment
		(start 349.48876 -295.635934)
		(end 349.409004 -295.715944)
		(width 0.1143)
		(layer "In6.Cu")
		(net "P5E_CPU0_P0_TX_DN<5>")
	)
	(segment
		(start 349.933514 -293.830756)
		(end 349.963994 -293.848536)
		(width 0.1143)
		(layer "In6.Cu")
		(net "P5E_CPU0_P0_TX_DN<5>")
	)
	(segment
		(start 349.963994 -292.228524)
		(end 350.00311 -292.251384)
		(width 0.1143)
		(layer "In6.Cu")
		(net "P5E_CPU0_P0_TX_DN<5>")
	)
	(segment
		(start 367.796318 -329.30719)
		(end 369.984528 -341.48141)
		(width 0.14224)
		(layer "In6.Cu")
		(net "P5E_CPU0_P0_TX_DN<5>")
	)
	(segment
		(start 309.635652 -374.320816)
		(end 308.478428 -374.320816)
		(width 0.14224)
		(layer "In6.Cu")
		(net "P5E_CPU0_P0_TX_DN<5>")
	)
	(segment
		(start 319.647062 -370.173758)
		(end 309.635652 -374.320816)
		(width 0.14224)
		(layer "In6.Cu")
		(net "P5E_CPU0_P0_TX_DN<5>")
	)
	(segment
		(start 349.963994 -290.608512)
		(end 350.00311 -290.631372)
		(width 0.1143)
		(layer "In6.Cu")
		(net "P5E_CPU0_P0_TX_DN<5>")
	)
	(segment
		(start 349.352362 -296.281094)
		(end 349.352362 -298.786042)
		(width 0.14224)
		(layer "In6.Cu")
		(net "P5E_CPU0_P0_TX_DN<5>")
	)
	(segment
		(start 306.394866 -376.077988)
		(end 306.394866 -379.5903)
		(width 0.14224)
		(layer "In6.Cu")
		(net "P5E_CPU0_P0_TX_DN<5>")
	)
	(segment
		(start 349.933514 -292.210744)
		(end 349.963994 -292.228524)
		(width 0.1143)
		(layer "In6.Cu")
		(net "P5E_CPU0_P0_TX_DN<5>")
	)
	(segment
		(start 349.306642 -295.962578)
		(end 349.306642 -296.206926)
		(width 0.1143)
		(layer "In6.Cu")
		(net "P5E_CPU0_P0_TX_DN<5>")
	)
	(segment
		(start 350.00311 -291.560504)
		(end 349.963994 -291.583364)
		(width 0.1143)
		(layer "In6.Cu")
		(net "P5E_CPU0_P0_TX_DN<5>")
	)
	(segment
		(start 349.933514 -290.590732)
		(end 349.963994 -290.608512)
		(width 0.1143)
		(layer "In6.Cu")
		(net "P5E_CPU0_P0_TX_DN<5>")
	)
	(segment
		(start 350.00311 -289.940492)
		(end 349.963994 -289.963352)
		(width 0.1143)
		(layer "In6.Cu")
		(net "P5E_CPU0_P0_TX_DN<5>")
	)
	(segment
		(start 349.963994 -289.963352)
		(end 349.933514 -289.981132)
		(width 0.1143)
		(layer "In6.Cu")
		(net "P5E_CPU0_P0_TX_DN<5>")
	)
	(segment
		(start 349.352362 -298.786042)
		(end 353.029012 -307.661818)
		(width 0.14224)
		(layer "In6.Cu")
		(net "P5E_CPU0_P0_TX_DN<5>")
	)
	(segment
		(start 369.984528 -341.48141)
		(end 369.984528 -350.061784)
		(width 0.14224)
		(layer "In6.Cu")
		(net "P5E_CPU0_P0_TX_DN<5>")
	)
	(segment
		(start 349.460566 -286.538924)
		(end 349.494094 -286.558482)
		(width 0.1143)
		(layer "In6.Cu")
		(net "P5E_CPU0_P0_TX_DN<5>")
	)
	(segment
		(start 350.00311 -294.800528)
		(end 349.933514 -294.841168)
		(width 0.1143)
		(layer "In6.Cu")
		(net "P5E_CPU0_P0_TX_DN<5>")
	)
	(segment
		(start 306.394866 -379.5903)
		(end 306.685696 -379.88113)
		(width 0.14224)
		(layer "In6.Cu")
		(net "P5E_CPU0_P0_TX_DN<5>")
	)
	(segment
		(start 349.496126 -295.63187)
		(end 349.48876 -295.635934)
		(width 0.1143)
		(layer "In6.Cu")
		(net "P5E_CPU0_P0_TX_DN<5>")
	)
	(segment
		(start 349.963994 -288.9885)
		(end 350.00311 -289.01136)
		(width 0.1143)
		(layer "In6.Cu")
		(net "P5E_CPU0_P0_TX_DN<5>")
	)
	(segment
		(start 349.306642 -296.206926)
		(end 349.352362 -296.252646)
		(width 0.1143)
		(layer "In6.Cu")
		(net "P5E_CPU0_P0_TX_DN<5>")
	)
	(segment
		(start 349.963994 -288.343594)
		(end 349.931482 -288.36239)
		(width 0.1143)
		(layer "In6.Cu")
		(net "P5E_CPU0_P0_TX_DN<5>")
	)
	(segment
		(start 349.352362 -296.252646)
		(end 349.352362 -296.281094)
		(width 0.1143)
		(layer "In6.Cu")
		(net "P5E_CPU0_P0_TX_DN<5>")
	)
	(segment
		(start 349.963994 -291.583364)
		(end 349.933514 -291.601144)
		(width 0.1143)
		(layer "In6.Cu")
		(net "P5E_CPU0_P0_TX_DN<5>")
	)
	(segment
		(start 359.168446 -316.850014)
		(end 364.996984 -323.951854)
		(width 0.14224)
		(layer "In6.Cu")
		(net "P5E_CPU0_P0_TX_DN<5>")
	)
	(segment
		(start 353.029012 -307.661818)
		(end 359.168446 -316.850014)
		(width 0.14224)
		(layer "In6.Cu")
		(net "P5E_CPU0_P0_TX_DN<5>")
	)
	(segment
		(start 349.933514 -288.97072)
		(end 349.963994 -288.9885)
		(width 0.1143)
		(layer "In6.Cu")
		(net "P5E_CPU0_P0_TX_DN<5>")
	)
	(segment
		(start 364.996984 -323.951854)
		(end 367.796318 -329.30719)
		(width 0.14224)
		(layer "In6.Cu")
		(net "P5E_CPU0_P0_TX_DN<5>")
	)
	(segment
		(start 349.933514 -287.350708)
		(end 350.00057 -287.389824)
		(width 0.1143)
		(layer "In6.Cu")
		(net "P5E_CPU0_P0_TX_DN<5>")
	)
	(segment
		(start 349.963994 -293.203376)
		(end 349.933514 -293.221156)
		(width 0.1143)
		(layer "In6.Cu")
		(net "P5E_CPU0_P0_TX_DN<5>")
	)
	(segment
		(start 307.381402 -374.775222)
		(end 306.618386 -375.538238)
		(width 0.14224)
		(layer "In6.Cu")
		(net "P5E_CPU0_P0_TX_DN<5>")
	)
	(segment
		(start 349.963994 -293.848536)
		(end 350.00311 -293.871396)
		(width 0.1143)
		(layer "In6.Cu")
		(net "P5E_CPU0_P0_TX_DN<5>")
	)
	(segment
		(start 357.344726 -369.713002)
		(end 321.963288 -369.713002)
		(width 0.14224)
		(layer "In6.Cu")
		(net "P5E_CPU0_P0_TX_DN<5>")
	)
	(segment
		(start 350.00311 -288.320734)
		(end 349.963994 -288.343594)
		(width 0.1143)
		(layer "In6.Cu")
		(net "P5E_CPU0_P0_TX_DN<5>")
	)
	(segment
		(start 364.146846 -364.155228)
		(end 359.468928 -368.833146)
		(width 0.14224)
		(layer "In6.Cu")
		(net "P5E_CPU0_P0_TX_DN<5>")
	)
	(segment
		(start 349.383096 -286.236156)
		(end 349.313246 -286.306006)
		(width 0.1143)
		(layer "In6.Cu")
		(net "P5E_CPU0_P0_TX_DN<5>")
	)
	(arc
		(start 350.00311 -292.251384)
		(mid 350.246437 -292.71595)
		(end 350.00311 -293.180516)
		(width 0.1143)
		(layer "In6.Cu")
		(net "P5E_CPU0_P0_TX_DN<5>")
	)
	(arc
		(start 308.478428 -374.320816)
		(mid 307.884721 -374.438912)
		(end 307.381402 -374.775222)
		(width 0.14224)
		(layer "In6.Cu")
		(net "P5E_CPU0_P0_TX_DN<5>")
	)
	(arc
		(start 349.409004 -295.715944)
		(mid 349.333312 -295.829086)
		(end 349.306642 -295.962578)
		(width 0.1143)
		(layer "In6.Cu")
		(net "P5E_CPU0_P0_TX_DN<5>")
	)
	(arc
		(start 321.963288 -369.713002)
		(mid 320.782483 -369.829307)
		(end 319.647062 -370.173758)
		(width 0.14224)
		(layer "In6.Cu")
		(net "P5E_CPU0_P0_TX_DN<5>")
	)
	(arc
		(start 350.00311 -289.01136)
		(mid 350.246437 -289.475926)
		(end 350.00311 -289.940492)
		(width 0.1143)
		(layer "In6.Cu")
		(net "P5E_CPU0_P0_TX_DN<5>")
	)
	(arc
		(start 349.933514 -293.221156)
		(mid 349.776537 -293.525956)
		(end 349.933514 -293.830756)
		(width 0.1143)
		(layer "In6.Cu")
		(net "P5E_CPU0_P0_TX_DN<5>")
	)
	(arc
		(start 349.933514 -294.841168)
		(mid 349.808632 -294.985164)
		(end 349.763588 -295.170352)
		(width 0.1143)
		(layer "In6.Cu")
		(net "P5E_CPU0_P0_TX_DN<5>")
	)
	(arc
		(start 349.313246 -286.306006)
		(mid 349.364736 -286.436479)
		(end 349.460566 -286.538924)
		(width 0.1143)
		(layer "In6.Cu")
		(net "P5E_CPU0_P0_TX_DN<5>")
	)
	(arc
		(start 350.00311 -290.631372)
		(mid 350.246437 -291.095938)
		(end 350.00311 -291.560504)
		(width 0.1143)
		(layer "In6.Cu")
		(net "P5E_CPU0_P0_TX_DN<5>")
	)
	(arc
		(start 349.763588 -295.170352)
		(mid 349.691887 -295.437056)
		(end 349.496126 -295.63187)
		(width 0.1143)
		(layer "In6.Cu")
		(net "P5E_CPU0_P0_TX_DN<5>")
	)
	(arc
		(start 349.933514 -289.981132)
		(mid 349.776537 -290.285932)
		(end 349.933514 -290.590732)
		(width 0.1143)
		(layer "In6.Cu")
		(net "P5E_CPU0_P0_TX_DN<5>")
	)
	(arc
		(start 306.618386 -375.538238)
		(mid 306.452972 -375.785892)
		(end 306.394866 -376.077988)
		(width 0.14224)
		(layer "In6.Cu")
		(net "P5E_CPU0_P0_TX_DN<5>")
	)
	(arc
		(start 359.468928 -368.833146)
		(mid 358.494336 -369.484348)
		(end 357.344726 -369.713002)
		(width 0.14224)
		(layer "In6.Cu")
		(net "P5E_CPU0_P0_TX_DN<5>")
	)
	(arc
		(start 350.00311 -293.871396)
		(mid 350.246437 -294.335962)
		(end 350.00311 -294.800528)
		(width 0.1143)
		(layer "In6.Cu")
		(net "P5E_CPU0_P0_TX_DN<5>")
	)
	(arc
		(start 349.933514 -291.601144)
		(mid 349.776537 -291.905944)
		(end 349.933514 -292.210744)
		(width 0.1143)
		(layer "In6.Cu")
		(net "P5E_CPU0_P0_TX_DN<5>")
	)
	(arc
		(start 350.246442 -287.856168)
		(mid 350.181927 -288.118387)
		(end 350.00311 -288.320734)
		(width 0.1143)
		(layer "In6.Cu")
		(net "P5E_CPU0_P0_TX_DN<5>")
	)
	(arc
		(start 350.00057 -287.389824)
		(mid 350.181222 -287.592569)
		(end 350.246442 -287.856168)
		(width 0.1143)
		(layer "In6.Cu")
		(net "P5E_CPU0_P0_TX_DN<5>")
	)
	(arc
		(start 349.776542 -288.66592)
		(mid 349.818091 -288.837342)
		(end 349.933514 -288.97072)
		(width 0.1143)
		(layer "In6.Cu")
		(net "P5E_CPU0_P0_TX_DN<5>")
	)
	(arc
		(start 369.984528 -350.061784)
		(mid 368.467361 -357.689096)
		(end 364.146846 -364.155228)
		(width 0.14224)
		(layer "In6.Cu")
		(net "P5E_CPU0_P0_TX_DN<5>")
	)
	(arc
		(start 349.931482 -288.36239)
		(mid 349.817553 -288.495537)
		(end 349.776542 -288.66592)
		(width 0.1143)
		(layer "In6.Cu")
		(net "P5E_CPU0_P0_TX_DN<5>")
	)
	(arc
		(start 349.776542 -287.045908)
		(mid 349.818091 -287.21733)
		(end 349.933514 -287.350708)
		(width 0.1143)
		(layer "In6.Cu")
		(net "P5E_CPU0_P0_TX_DN<5>")
	)
	(arc
		(start 349.53321 -286.581342)
		(mid 349.712023 -286.783692)
		(end 349.776542 -287.045908)
		(width 0.1143)
		(layer "In6.Cu")
		(net "P5E_CPU0_P0_TX_DN<5>")
	)
	(segment
		(start 304.713386 -382.61544)
		(end 304.983896 -382.34493)
		(width 0.12954)
		(layer "F.Cu")
		(net "P5E_CPU0_P0_TX_DN<4>")
	)
	(segment
		(start 350.14789 -284.350206)
		(end 349.681038 -284.616144)
		(width 0.12954)
		(layer "F.Cu")
		(net "P5E_CPU0_P0_TX_DN<4>")
	)
	(segment
		(start 305.009296 -383.61493)
		(end 304.713386 -383.31902)
		(width 0.12954)
		(layer "F.Cu")
		(net "P5E_CPU0_P0_TX_DN<4>")
	)
	(segment
		(start 304.713386 -383.31902)
		(end 304.713386 -382.61544)
		(width 0.12954)
		(layer "F.Cu")
		(net "P5E_CPU0_P0_TX_DN<4>")
	)
	(segment
		(start 349.022162 -289.964622)
		(end 348.992444 -289.98164)
		(width 0.1143)
		(layer "In6.Cu")
		(net "P5E_CPU0_P0_TX_DN<4>")
	)
	(segment
		(start 348.992444 -288.970212)
		(end 349.023432 -288.987992)
		(width 0.1143)
		(layer "In6.Cu")
		(net "P5E_CPU0_P0_TX_DN<4>")
	)
	(segment
		(start 349.028004 -285.100776)
		(end 349.02394 -285.103062)
		(width 0.1143)
		(layer "In6.Cu")
		(net "P5E_CPU0_P0_TX_DN<4>")
	)
	(segment
		(start 348.521528 -286.539686)
		(end 348.55404 -286.558482)
		(width 0.1143)
		(layer "In6.Cu")
		(net "P5E_CPU0_P0_TX_DN<4>")
	)
	(segment
		(start 352.201988 -308.102762)
		(end 358.42067 -317.409322)
		(width 0.14224)
		(layer "In6.Cu")
		(net "P5E_CPU0_P0_TX_DN<4>")
	)
	(segment
		(start 361.304586 -320.922904)
		(end 361.304586 -320.923158)
		(width 0.14224)
		(layer "In6.Cu")
		(net "P5E_CPU0_P0_TX_DN<4>")
	)
	(segment
		(start 349.024194 -287.368488)
		(end 349.02394 -287.368742)
		(width 0.1143)
		(layer "In6.Cu")
		(net "P5E_CPU0_P0_TX_DN<4>")
	)
	(segment
		(start 349.024194 -289.963352)
		(end 349.023432 -289.96386)
		(width 0.1143)
		(layer "In6.Cu")
		(net "P5E_CPU0_P0_TX_DN<4>")
	)
	(segment
		(start 308.668928 -373.37873)
		(end 307.620924 -373.37873)
		(width 0.14224)
		(layer "In6.Cu")
		(net "P5E_CPU0_P0_TX_DN<4>")
	)
	(segment
		(start 348.407228 -298.941236)
		(end 352.201988 -308.102762)
		(width 0.14224)
		(layer "In6.Cu")
		(net "P5E_CPU0_P0_TX_DN<4>")
	)
	(segment
		(start 349.026988 -293.850314)
		(end 349.063056 -293.871142)
		(width 0.1143)
		(layer "In6.Cu")
		(net "P5E_CPU0_P0_TX_DN<4>")
	)
	(segment
		(start 348.679262 -295.525952)
		(end 348.408752 -295.796208)
		(width 0.1143)
		(layer "In6.Cu")
		(net "P5E_CPU0_P0_TX_DN<4>")
	)
	(segment
		(start 305.300634 -374.829578)
		(end 304.843688 -375.372884)
		(width 0.14224)
		(layer "In6.Cu")
		(net "P5E_CPU0_P0_TX_DN<4>")
	)
	(segment
		(start 348.407228 -296.281094)
		(end 348.407228 -298.941236)
		(width 0.14224)
		(layer "In6.Cu")
		(net "P5E_CPU0_P0_TX_DN<4>")
	)
	(segment
		(start 307.501036 -373.413528)
		(end 305.39563 -374.74652)
		(width 0.14224)
		(layer "In6.Cu")
		(net "P5E_CPU0_P0_TX_DN<4>")
	)
	(segment
		(start 361.304586 -320.923158)
		(end 364.215934 -324.470522)
		(width 0.14224)
		(layer "In6.Cu")
		(net "P5E_CPU0_P0_TX_DN<4>")
	)
	(segment
		(start 349.023432 -289.96386)
		(end 349.022162 -289.964622)
		(width 0.1143)
		(layer "In6.Cu")
		(net "P5E_CPU0_P0_TX_DN<4>")
	)
	(segment
		(start 349.024194 -293.203376)
		(end 349.023432 -293.203884)
		(width 0.1143)
		(layer "In6.Cu")
		(net "P5E_CPU0_P0_TX_DN<4>")
	)
	(segment
		(start 349.024194 -293.848536)
		(end 349.026988 -293.850314)
		(width 0.1143)
		(layer "In6.Cu")
		(net "P5E_CPU0_P0_TX_DN<4>")
	)
	(segment
		(start 349.02394 -287.368742)
		(end 349.024702 -287.36925)
		(width 0.1143)
		(layer "In6.Cu")
		(net "P5E_CPU0_P0_TX_DN<4>")
	)
	(segment
		(start 349.023432 -293.848028)
		(end 349.024194 -293.848536)
		(width 0.1143)
		(layer "In6.Cu")
		(net "P5E_CPU0_P0_TX_DN<4>")
	)
	(segment
		(start 348.55404 -286.558482)
		(end 348.593156 -286.581342)
		(width 0.1143)
		(layer "In6.Cu")
		(net "P5E_CPU0_P0_TX_DN<4>")
	)
	(segment
		(start 349.023432 -292.228016)
		(end 349.024194 -292.228524)
		(width 0.1143)
		(layer "In6.Cu")
		(net "P5E_CPU0_P0_TX_DN<4>")
	)
	(segment
		(start 304.693066 -375.750328)
		(end 304.693066 -381.987298)
		(width 0.14224)
		(layer "In6.Cu")
		(net "P5E_CPU0_P0_TX_DN<4>")
	)
	(segment
		(start 348.992444 -287.3502)
		(end 349.023432 -287.36798)
		(width 0.1143)
		(layer "In6.Cu")
		(net "P5E_CPU0_P0_TX_DN<4>")
	)
	(segment
		(start 348.992444 -293.830248)
		(end 349.023432 -293.848028)
		(width 0.1143)
		(layer "In6.Cu")
		(net "P5E_CPU0_P0_TX_DN<4>")
	)
	(segment
		(start 349.023432 -291.583872)
		(end 349.022162 -291.584634)
		(width 0.1143)
		(layer "In6.Cu")
		(net "P5E_CPU0_P0_TX_DN<4>")
	)
	(segment
		(start 349.063056 -293.871142)
		(end 349.06585 -293.873174)
		(width 0.1143)
		(layer "In6.Cu")
		(net "P5E_CPU0_P0_TX_DN<4>")
	)
	(segment
		(start 349.024194 -291.583364)
		(end 349.023432 -291.583872)
		(width 0.1143)
		(layer "In6.Cu")
		(net "P5E_CPU0_P0_TX_DN<4>")
	)
	(segment
		(start 348.361508 -296.206926)
		(end 348.407228 -296.252646)
		(width 0.1143)
		(layer "In6.Cu")
		(net "P5E_CPU0_P0_TX_DN<4>")
	)
	(segment
		(start 349.022162 -293.204646)
		(end 348.992444 -293.221664)
		(width 0.1143)
		(layer "In6.Cu")
		(net "P5E_CPU0_P0_TX_DN<4>")
	)
	(segment
		(start 349.023432 -287.36798)
		(end 349.024194 -287.368488)
		(width 0.1143)
		(layer "In6.Cu")
		(net "P5E_CPU0_P0_TX_DN<4>")
	)
	(segment
		(start 356.855522 -368.778028)
		(end 321.964304 -368.778028)
		(width 0.14224)
		(layer "In6.Cu")
		(net "P5E_CPU0_P0_TX_DN<4>")
	)
	(segment
		(start 348.992444 -292.210236)
		(end 349.023432 -292.228016)
		(width 0.1143)
		(layer "In6.Cu")
		(net "P5E_CPU0_P0_TX_DN<4>")
	)
	(segment
		(start 349.024194 -288.9885)
		(end 349.060516 -289.009582)
		(width 0.1143)
		(layer "In6.Cu")
		(net "P5E_CPU0_P0_TX_DN<4>")
	)
	(segment
		(start 358.42067 -317.409322)
		(end 361.304586 -320.922904)
		(width 0.14224)
		(layer "In6.Cu")
		(net "P5E_CPU0_P0_TX_DN<4>")
	)
	(segment
		(start 349.060516 -291.562282)
		(end 349.024194 -291.583364)
		(width 0.1143)
		(layer "In6.Cu")
		(net "P5E_CPU0_P0_TX_DN<4>")
	)
	(segment
		(start 348.992444 -290.590224)
		(end 349.023432 -290.608004)
		(width 0.1143)
		(layer "In6.Cu")
		(net "P5E_CPU0_P0_TX_DN<4>")
	)
	(segment
		(start 349.078042 -294.790114)
		(end 349.061786 -294.801798)
		(width 0.1143)
		(layer "In6.Cu")
		(net "P5E_CPU0_P0_TX_DN<4>")
	)
	(segment
		(start 349.06585 -293.873174)
		(end 349.072708 -293.877746)
		(width 0.1143)
		(layer "In6.Cu")
		(net "P5E_CPU0_P0_TX_DN<4>")
	)
	(segment
		(start 304.74031 -382.101344)
		(end 304.983896 -382.34493)
		(width 0.14224)
		(layer "In6.Cu")
		(net "P5E_CPU0_P0_TX_DN<4>")
	)
	(segment
		(start 349.061786 -294.801798)
		(end 348.992698 -294.841676)
		(width 0.1143)
		(layer "In6.Cu")
		(net "P5E_CPU0_P0_TX_DN<4>")
	)
	(segment
		(start 366.884204 -329.575668)
		(end 369.052348 -341.63762)
		(width 0.14224)
		(layer "In6.Cu")
		(net "P5E_CPU0_P0_TX_DN<4>")
	)
	(segment
		(start 349.023432 -293.203884)
		(end 349.022162 -293.204646)
		(width 0.1143)
		(layer "In6.Cu")
		(net "P5E_CPU0_P0_TX_DN<4>")
	)
	(segment
		(start 348.593156 -285.890716)
		(end 348.52356 -285.931356)
		(width 0.1143)
		(layer "In6.Cu")
		(net "P5E_CPU0_P0_TX_DN<4>")
	)
	(segment
		(start 349.060516 -289.94227)
		(end 349.024194 -289.963352)
		(width 0.1143)
		(layer "In6.Cu")
		(net "P5E_CPU0_P0_TX_DN<4>")
	)
	(segment
		(start 349.022162 -291.584634)
		(end 348.992444 -291.601652)
		(width 0.1143)
		(layer "In6.Cu")
		(net "P5E_CPU0_P0_TX_DN<4>")
	)
	(segment
		(start 349.02394 -285.103062)
		(end 349.022924 -285.10357)
		(width 0.1143)
		(layer "In6.Cu")
		(net "P5E_CPU0_P0_TX_DN<4>")
	)
	(segment
		(start 363.344206 -363.637322)
		(end 359.156508 -367.82502)
		(width 0.14224)
		(layer "In6.Cu")
		(net "P5E_CPU0_P0_TX_DN<4>")
	)
	(segment
		(start 349.024194 -292.228524)
		(end 349.060516 -292.249606)
		(width 0.1143)
		(layer "In6.Cu")
		(net "P5E_CPU0_P0_TX_DN<4>")
	)
	(segment
		(start 349.024194 -290.608512)
		(end 349.060516 -290.629594)
		(width 0.1143)
		(layer "In6.Cu")
		(net "P5E_CPU0_P0_TX_DN<4>")
	)
	(segment
		(start 349.383096 -284.616144)
		(end 349.300292 -284.698948)
		(width 0.1143)
		(layer "In6.Cu")
		(net "P5E_CPU0_P0_TX_DN<4>")
	)
	(segment
		(start 369.052348 -341.63762)
		(end 369.052348 -349.856552)
		(width 0.14224)
		(layer "In6.Cu")
		(net "P5E_CPU0_P0_TX_DN<4>")
	)
	(segment
		(start 348.407228 -296.252646)
		(end 348.407228 -296.281094)
		(width 0.1143)
		(layer "In6.Cu")
		(net "P5E_CPU0_P0_TX_DN<4>")
	)
	(segment
		(start 349.024194 -288.343594)
		(end 348.990666 -288.363152)
		(width 0.1143)
		(layer "In6.Cu")
		(net "P5E_CPU0_P0_TX_DN<4>")
	)
	(segment
		(start 319.292478 -369.309396)
		(end 310.204104 -373.073676)
		(width 0.14224)
		(layer "In6.Cu")
		(net "P5E_CPU0_P0_TX_DN<4>")
	)
	(segment
		(start 304.778156 -375.48058)
		(end 304.71745 -375.626884)
		(width 0.14224)
		(layer "In6.Cu")
		(net "P5E_CPU0_P0_TX_DN<4>")
	)
	(segment
		(start 349.060516 -288.322512)
		(end 349.024194 -288.343594)
		(width 0.1143)
		(layer "In6.Cu")
		(net "P5E_CPU0_P0_TX_DN<4>")
	)
	(segment
		(start 348.361508 -295.910254)
		(end 348.361508 -296.206926)
		(width 0.1143)
		(layer "In6.Cu")
		(net "P5E_CPU0_P0_TX_DN<4>")
	)
	(segment
		(start 349.023432 -290.608004)
		(end 349.024194 -290.608512)
		(width 0.1143)
		(layer "In6.Cu")
		(net "P5E_CPU0_P0_TX_DN<4>")
	)
	(segment
		(start 349.023432 -288.987992)
		(end 349.024194 -288.9885)
		(width 0.1143)
		(layer "In6.Cu")
		(net "P5E_CPU0_P0_TX_DN<4>")
	)
	(segment
		(start 349.681038 -284.616144)
		(end 349.383096 -284.616144)
		(width 0.1143)
		(layer "In6.Cu")
		(net "P5E_CPU0_P0_TX_DN<4>")
	)
	(segment
		(start 349.060516 -293.182294)
		(end 349.024194 -293.203376)
		(width 0.1143)
		(layer "In6.Cu")
		(net "P5E_CPU0_P0_TX_DN<4>")
	)
	(segment
		(start 364.215934 -324.470522)
		(end 366.884204 -329.575668)
		(width 0.14224)
		(layer "In6.Cu")
		(net "P5E_CPU0_P0_TX_DN<4>")
	)
	(arc
		(start 348.366588 -286.236156)
		(mid 348.407554 -286.406562)
		(end 348.521528 -286.539686)
		(width 0.1143)
		(layer "In6.Cu")
		(net "P5E_CPU0_P0_TX_DN<4>")
	)
	(arc
		(start 349.076772 -289.021012)
		(mid 349.299656 -289.475926)
		(end 349.076772 -289.93084)
		(width 0.1143)
		(layer "In6.Cu")
		(net "P5E_CPU0_P0_TX_DN<4>")
	)
	(arc
		(start 348.992444 -293.221664)
		(mid 348.836516 -293.525956)
		(end 348.992444 -293.830248)
		(width 0.1143)
		(layer "In6.Cu")
		(net "P5E_CPU0_P0_TX_DN<4>")
	)
	(arc
		(start 304.693066 -381.987298)
		(mid 304.705343 -382.049021)
		(end 304.74031 -382.101344)
		(width 0.14224)
		(layer "In6.Cu")
		(net "P5E_CPU0_P0_TX_DN<4>")
	)
	(arc
		(start 348.836488 -295.145968)
		(mid 348.795678 -295.351603)
		(end 348.679262 -295.525952)
		(width 0.1143)
		(layer "In6.Cu")
		(net "P5E_CPU0_P0_TX_DN<4>")
	)
	(arc
		(start 348.52356 -285.931356)
		(mid 348.408133 -286.064732)
		(end 348.366588 -286.236156)
		(width 0.1143)
		(layer "In6.Cu")
		(net "P5E_CPU0_P0_TX_DN<4>")
	)
	(arc
		(start 349.07474 -291.552376)
		(mid 349.067666 -291.557383)
		(end 349.060516 -291.562282)
		(width 0.1143)
		(layer "In6.Cu")
		(net "P5E_CPU0_P0_TX_DN<4>")
	)
	(arc
		(start 348.992444 -291.601652)
		(mid 348.836516 -291.905944)
		(end 348.992444 -292.210236)
		(width 0.1143)
		(layer "In6.Cu")
		(net "P5E_CPU0_P0_TX_DN<4>")
	)
	(arc
		(start 348.836488 -285.42615)
		(mid 348.771973 -285.688369)
		(end 348.593156 -285.890716)
		(width 0.1143)
		(layer "In6.Cu")
		(net "P5E_CPU0_P0_TX_DN<4>")
	)
	(arc
		(start 348.836488 -287.045908)
		(mid 348.877743 -287.216879)
		(end 348.992444 -287.3502)
		(width 0.1143)
		(layer "In6.Cu")
		(net "P5E_CPU0_P0_TX_DN<4>")
	)
	(arc
		(start 348.593156 -286.581342)
		(mid 348.771969 -286.783692)
		(end 348.836488 -287.045908)
		(width 0.1143)
		(layer "In6.Cu")
		(net "P5E_CPU0_P0_TX_DN<4>")
	)
	(arc
		(start 349.07474 -290.6395)
		(mid 349.302123 -291.095938)
		(end 349.07474 -291.552376)
		(width 0.1143)
		(layer "In6.Cu")
		(net "P5E_CPU0_P0_TX_DN<4>")
	)
	(arc
		(start 349.296482 -284.721554)
		(mid 349.203514 -284.940383)
		(end 349.028004 -285.100776)
		(width 0.1143)
		(layer "In6.Cu")
		(net "P5E_CPU0_P0_TX_DN<4>")
	)
	(arc
		(start 348.992444 -289.98164)
		(mid 348.836516 -290.285932)
		(end 348.992444 -290.590224)
		(width 0.1143)
		(layer "In6.Cu")
		(net "P5E_CPU0_P0_TX_DN<4>")
	)
	(arc
		(start 349.07474 -293.172388)
		(mid 349.067666 -293.177395)
		(end 349.060516 -293.182294)
		(width 0.1143)
		(layer "In6.Cu")
		(net "P5E_CPU0_P0_TX_DN<4>")
	)
	(arc
		(start 349.07474 -292.259512)
		(mid 349.302123 -292.71595)
		(end 349.07474 -293.172388)
		(width 0.1143)
		(layer "In6.Cu")
		(net "P5E_CPU0_P0_TX_DN<4>")
	)
	(arc
		(start 310.204104 -373.073676)
		(mid 309.451541 -373.301824)
		(end 308.668928 -373.37873)
		(width 0.14224)
		(layer "In6.Cu")
		(net "P5E_CPU0_P0_TX_DN<4>")
	)
	(arc
		(start 305.39563 -374.74652)
		(mid 305.344941 -374.784398)
		(end 305.300634 -374.829578)
		(width 0.14224)
		(layer "In6.Cu")
		(net "P5E_CPU0_P0_TX_DN<4>")
	)
	(arc
		(start 369.052348 -349.856552)
		(mid 367.568858 -357.31465)
		(end 363.344206 -363.637322)
		(width 0.14224)
		(layer "In6.Cu")
		(net "P5E_CPU0_P0_TX_DN<4>")
	)
	(arc
		(start 348.408752 -295.796208)
		(mid 348.373843 -295.848547)
		(end 348.361508 -295.910254)
		(width 0.1143)
		(layer "In6.Cu")
		(net "P5E_CPU0_P0_TX_DN<4>")
	)
	(arc
		(start 348.992698 -294.841676)
		(mid 348.877797 -294.974937)
		(end 348.836488 -295.145968)
		(width 0.1143)
		(layer "In6.Cu")
		(net "P5E_CPU0_P0_TX_DN<4>")
	)
	(arc
		(start 349.300292 -284.698948)
		(mid 349.298503 -284.71027)
		(end 349.296482 -284.721554)
		(width 0.1143)
		(layer "In6.Cu")
		(net "P5E_CPU0_P0_TX_DN<4>")
	)
	(arc
		(start 307.620924 -373.37873)
		(mid 307.558498 -373.387593)
		(end 307.501036 -373.413528)
		(width 0.14224)
		(layer "In6.Cu")
		(net "P5E_CPU0_P0_TX_DN<4>")
	)
	(arc
		(start 349.060516 -289.009582)
		(mid 349.068694 -289.015225)
		(end 349.076772 -289.021012)
		(width 0.1143)
		(layer "In6.Cu")
		(net "P5E_CPU0_P0_TX_DN<4>")
	)
	(arc
		(start 348.990666 -288.363152)
		(mid 348.877259 -288.496041)
		(end 348.836488 -288.66592)
		(width 0.1143)
		(layer "In6.Cu")
		(net "P5E_CPU0_P0_TX_DN<4>")
	)
	(arc
		(start 359.156508 -367.82502)
		(mid 358.100792 -368.530363)
		(end 356.855522 -368.778028)
		(width 0.14224)
		(layer "In6.Cu")
		(net "P5E_CPU0_P0_TX_DN<4>")
	)
	(arc
		(start 304.71745 -375.626884)
		(mid 304.699166 -375.687405)
		(end 304.693066 -375.750328)
		(width 0.14224)
		(layer "In6.Cu")
		(net "P5E_CPU0_P0_TX_DN<4>")
	)
	(arc
		(start 349.022924 -285.10357)
		(mid 348.886476 -285.239869)
		(end 348.836488 -285.42615)
		(width 0.1143)
		(layer "In6.Cu")
		(net "P5E_CPU0_P0_TX_DN<4>")
	)
	(arc
		(start 304.843688 -375.372884)
		(mid 304.806802 -375.424226)
		(end 304.778156 -375.48058)
		(width 0.14224)
		(layer "In6.Cu")
		(net "P5E_CPU0_P0_TX_DN<4>")
	)
	(arc
		(start 349.076772 -289.93084)
		(mid 349.068694 -289.936626)
		(end 349.060516 -289.94227)
		(width 0.1143)
		(layer "In6.Cu")
		(net "P5E_CPU0_P0_TX_DN<4>")
	)
	(arc
		(start 349.072708 -293.877746)
		(mid 349.302519 -294.332609)
		(end 349.078042 -294.790114)
		(width 0.1143)
		(layer "In6.Cu")
		(net "P5E_CPU0_P0_TX_DN<4>")
	)
	(arc
		(start 349.060516 -292.249606)
		(mid 349.067665 -292.254506)
		(end 349.07474 -292.259512)
		(width 0.1143)
		(layer "In6.Cu")
		(net "P5E_CPU0_P0_TX_DN<4>")
	)
	(arc
		(start 349.060516 -290.629594)
		(mid 349.067665 -290.634494)
		(end 349.07474 -290.6395)
		(width 0.1143)
		(layer "In6.Cu")
		(net "P5E_CPU0_P0_TX_DN<4>")
	)
	(arc
		(start 349.306388 -287.856168)
		(mid 349.241152 -288.119759)
		(end 349.060516 -288.322512)
		(width 0.1143)
		(layer "In6.Cu")
		(net "P5E_CPU0_P0_TX_DN<4>")
	)
	(arc
		(start 321.964304 -368.778028)
		(mid 320.602219 -368.912124)
		(end 319.292478 -369.309396)
		(width 0.14224)
		(layer "In6.Cu")
		(net "P5E_CPU0_P0_TX_DN<4>")
	)
	(arc
		(start 349.024702 -287.36925)
		(mid 349.230924 -287.574894)
		(end 349.306388 -287.856168)
		(width 0.1143)
		(layer "In6.Cu")
		(net "P5E_CPU0_P0_TX_DN<4>")
	)
	(arc
		(start 348.836488 -288.66592)
		(mid 348.877743 -288.836891)
		(end 348.992444 -288.970212)
		(width 0.1143)
		(layer "In6.Cu")
		(net "P5E_CPU0_P0_TX_DN<4>")
	)
	(segment
		(start 350.14789 -282.730194)
		(end 349.681038 -282.996132)
		(width 0.12954)
		(layer "F.Cu")
		(net "P5E_CPU0_P0_TX_DN<3>")
	)
	(segment
		(start 301.309786 -378.39142)
		(end 301.309786 -377.68784)
		(width 0.12954)
		(layer "F.Cu")
		(net "P5E_CPU0_P0_TX_DN<3>")
	)
	(segment
		(start 301.605696 -378.68733)
		(end 301.309786 -378.39142)
		(width 0.12954)
		(layer "F.Cu")
		(net "P5E_CPU0_P0_TX_DN<3>")
	)
	(segment
		(start 301.309786 -377.68784)
		(end 301.580296 -377.41733)
		(width 0.12954)
		(layer "F.Cu")
		(net "P5E_CPU0_P0_TX_DN<3>")
	)
	(segment
		(start 348.123256 -291.560504)
		(end 348.08414 -291.583364)
		(width 0.1143)
		(layer "In6.Cu")
		(net "P5E_CPU0_P0_TX_DN<3>")
	)
	(segment
		(start 368.120168 -341.736426)
		(end 368.120168 -349.515684)
		(width 0.14224)
		(layer "In6.Cu")
		(net "P5E_CPU0_P0_TX_DN<3>")
	)
	(segment
		(start 348.09176 -292.233096)
		(end 348.123256 -292.251384)
		(width 0.1143)
		(layer "In6.Cu")
		(net "P5E_CPU0_P0_TX_DN<3>")
	)
	(segment
		(start 349.028004 -283.480764)
		(end 349.02394 -283.48305)
		(width 0.1143)
		(layer "In6.Cu")
		(net "P5E_CPU0_P0_TX_DN<3>")
	)
	(segment
		(start 348.082108 -289.964622)
		(end 348.080584 -289.965384)
		(width 0.1143)
		(layer "In6.Cu")
		(net "P5E_CPU0_P0_TX_DN<3>")
	)
	(segment
		(start 348.07271 -289.97021)
		(end 348.05239 -289.98164)
		(width 0.1143)
		(layer "In6.Cu")
		(net "P5E_CPU0_P0_TX_DN<3>")
	)
	(segment
		(start 348.079822 -291.585904)
		(end 348.07525 -291.588698)
		(width 0.1143)
		(layer "In6.Cu")
		(net "P5E_CPU0_P0_TX_DN<3>")
	)
	(segment
		(start 365.994696 -329.912218)
		(end 368.120168 -341.736426)
		(width 0.14224)
		(layer "In6.Cu")
		(net "P5E_CPU0_P0_TX_DN<3>")
	)
	(segment
		(start 301.289466 -376.196352)
		(end 301.289466 -377.1265)
		(width 0.14224)
		(layer "In6.Cu")
		(net "P5E_CPU0_P0_TX_DN<3>")
	)
	(segment
		(start 349.681038 -282.996132)
		(end 349.383096 -282.996132)
		(width 0.1143)
		(layer "In6.Cu")
		(net "P5E_CPU0_P0_TX_DN<3>")
	)
	(segment
		(start 348.08414 -289.963352)
		(end 348.083378 -289.96386)
		(width 0.1143)
		(layer "In6.Cu")
		(net "P5E_CPU0_P0_TX_DN<3>")
	)
	(segment
		(start 348.079822 -285.10611)
		(end 348.07525 -285.108904)
		(width 0.1143)
		(layer "In6.Cu")
		(net "P5E_CPU0_P0_TX_DN<3>")
	)
	(segment
		(start 347.581474 -286.539686)
		(end 347.653102 -286.581342)
		(width 0.1143)
		(layer "In6.Cu")
		(net "P5E_CPU0_P0_TX_DN<3>")
	)
	(segment
		(start 348.090236 -290.612068)
		(end 348.09176 -290.613084)
		(width 0.1143)
		(layer "In6.Cu")
		(net "P5E_CPU0_P0_TX_DN<3>")
	)
	(segment
		(start 348.090236 -293.852092)
		(end 348.09176 -293.853108)
		(width 0.1143)
		(layer "In6.Cu")
		(net "P5E_CPU0_P0_TX_DN<3>")
	)
	(segment
		(start 348.05239 -290.590224)
		(end 348.090236 -290.612068)
		(width 0.1143)
		(layer "In6.Cu")
		(net "P5E_CPU0_P0_TX_DN<3>")
	)
	(segment
		(start 302.612552 -374.038876)
		(end 301.879508 -374.77192)
		(width 0.14224)
		(layer "In6.Cu")
		(net "P5E_CPU0_P0_TX_DN<3>")
	)
	(segment
		(start 348.123256 -285.08071)
		(end 348.08414 -285.10357)
		(width 0.1143)
		(layer "In6.Cu")
		(net "P5E_CPU0_P0_TX_DN<3>")
	)
	(segment
		(start 348.09176 -293.853108)
		(end 348.123256 -293.871396)
		(width 0.1143)
		(layer "In6.Cu")
		(net "P5E_CPU0_P0_TX_DN<3>")
	)
	(segment
		(start 347.653102 -285.890716)
		(end 347.583506 -285.931356)
		(width 0.1143)
		(layer "In6.Cu")
		(net "P5E_CPU0_P0_TX_DN<3>")
	)
	(segment
		(start 348.123256 -289.940492)
		(end 348.08414 -289.963352)
		(width 0.1143)
		(layer "In6.Cu")
		(net "P5E_CPU0_P0_TX_DN<3>")
	)
	(segment
		(start 348.09176 -290.613084)
		(end 348.123256 -290.631372)
		(width 0.1143)
		(layer "In6.Cu")
		(net "P5E_CPU0_P0_TX_DN<3>")
	)
	(segment
		(start 363.548168 -325.205598)
		(end 365.994696 -329.912218)
		(width 0.14224)
		(layer "In6.Cu")
		(net "P5E_CPU0_P0_TX_DN<3>")
	)
	(segment
		(start 348.05239 -293.830248)
		(end 348.090236 -293.852092)
		(width 0.1143)
		(layer "In6.Cu")
		(net "P5E_CPU0_P0_TX_DN<3>")
	)
	(segment
		(start 319.037462 -368.405156)
		(end 309.97271 -372.159784)
		(width 0.14224)
		(layer "In6.Cu")
		(net "P5E_CPU0_P0_TX_DN<3>")
	)
	(segment
		(start 348.07525 -289.968686)
		(end 348.07271 -289.97021)
		(width 0.1143)
		(layer "In6.Cu")
		(net "P5E_CPU0_P0_TX_DN<3>")
	)
	(segment
		(start 348.07779 -294.826944)
		(end 348.05239 -294.841676)
		(width 0.1143)
		(layer "In6.Cu")
		(net "P5E_CPU0_P0_TX_DN<3>")
	)
	(segment
		(start 348.07271 -291.590222)
		(end 348.05239 -291.601652)
		(width 0.1143)
		(layer "In6.Cu")
		(net "P5E_CPU0_P0_TX_DN<3>")
	)
	(segment
		(start 348.05239 -294.841676)
		(end 347.974158 -294.898064)
		(width 0.1143)
		(layer "In6.Cu")
		(net "P5E_CPU0_P0_TX_DN<3>")
	)
	(segment
		(start 348.090236 -292.23208)
		(end 348.09176 -292.233096)
		(width 0.1143)
		(layer "In6.Cu")
		(net "P5E_CPU0_P0_TX_DN<3>")
	)
	(segment
		(start 348.08414 -285.10357)
		(end 348.083378 -285.104078)
		(width 0.1143)
		(layer "In6.Cu")
		(net "P5E_CPU0_P0_TX_DN<3>")
	)
	(segment
		(start 301.289466 -377.1265)
		(end 301.580296 -377.41733)
		(width 0.14224)
		(layer "In6.Cu")
		(net "P5E_CPU0_P0_TX_DN<3>")
	)
	(segment
		(start 348.082108 -285.10484)
		(end 348.080584 -285.105602)
		(width 0.1143)
		(layer "In6.Cu")
		(net "P5E_CPU0_P0_TX_DN<3>")
	)
	(segment
		(start 348.08414 -293.203376)
		(end 348.083378 -293.203884)
		(width 0.1143)
		(layer "In6.Cu")
		(net "P5E_CPU0_P0_TX_DN<3>")
	)
	(segment
		(start 308.558946 -372.440962)
		(end 306.470304 -372.440962)
		(width 0.14224)
		(layer "In6.Cu")
		(net "P5E_CPU0_P0_TX_DN<3>")
	)
	(segment
		(start 348.079822 -294.825928)
		(end 348.07779 -294.826944)
		(width 0.1143)
		(layer "In6.Cu")
		(net "P5E_CPU0_P0_TX_DN<3>")
	)
	(segment
		(start 348.080584 -289.965384)
		(end 348.079822 -289.965892)
		(width 0.1143)
		(layer "In6.Cu")
		(net "P5E_CPU0_P0_TX_DN<3>")
	)
	(segment
		(start 348.082108 -291.584634)
		(end 348.080584 -291.585396)
		(width 0.1143)
		(layer "In6.Cu")
		(net "P5E_CPU0_P0_TX_DN<3>")
	)
	(segment
		(start 348.082108 -293.204646)
		(end 348.080584 -293.205408)
		(width 0.1143)
		(layer "In6.Cu")
		(net "P5E_CPU0_P0_TX_DN<3>")
	)
	(segment
		(start 348.083378 -293.203884)
		(end 348.082108 -293.204646)
		(width 0.1143)
		(layer "In6.Cu")
		(net "P5E_CPU0_P0_TX_DN<3>")
	)
	(segment
		(start 348.083378 -285.104078)
		(end 348.082108 -285.10484)
		(width 0.1143)
		(layer "In6.Cu")
		(net "P5E_CPU0_P0_TX_DN<3>")
	)
	(segment
		(start 348.080584 -291.585396)
		(end 348.079822 -291.585904)
		(width 0.1143)
		(layer "In6.Cu")
		(net "P5E_CPU0_P0_TX_DN<3>")
	)
	(segment
		(start 348.05239 -292.210236)
		(end 348.090236 -292.23208)
		(width 0.1143)
		(layer "In6.Cu")
		(net "P5E_CPU0_P0_TX_DN<3>")
	)
	(segment
		(start 348.083378 -291.583872)
		(end 348.082108 -291.584634)
		(width 0.1143)
		(layer "In6.Cu")
		(net "P5E_CPU0_P0_TX_DN<3>")
	)
	(segment
		(start 348.08414 -291.583364)
		(end 348.083378 -291.583872)
		(width 0.1143)
		(layer "In6.Cu")
		(net "P5E_CPU0_P0_TX_DN<3>")
	)
	(segment
		(start 348.123256 -294.800528)
		(end 348.079822 -294.825928)
		(width 0.1143)
		(layer "In6.Cu")
		(net "P5E_CPU0_P0_TX_DN<3>")
	)
	(segment
		(start 356.545642 -367.843054)
		(end 321.863466 -367.843054)
		(width 0.14224)
		(layer "In6.Cu")
		(net "P5E_CPU0_P0_TX_DN<3>")
	)
	(segment
		(start 347.472508 -296.252646)
		(end 347.472508 -296.281094)
		(width 0.1143)
		(layer "In6.Cu")
		(net "P5E_CPU0_P0_TX_DN<3>")
	)
	(segment
		(start 349.383096 -282.996132)
		(end 349.300292 -283.078936)
		(width 0.1143)
		(layer "In6.Cu")
		(net "P5E_CPU0_P0_TX_DN<3>")
	)
	(segment
		(start 348.079822 -293.205916)
		(end 348.07525 -293.20871)
		(width 0.1143)
		(layer "In6.Cu")
		(net "P5E_CPU0_P0_TX_DN<3>")
	)
	(segment
		(start 347.426788 -296.007028)
		(end 347.426788 -296.206926)
		(width 0.1143)
		(layer "In6.Cu")
		(net "P5E_CPU0_P0_TX_DN<3>")
	)
	(segment
		(start 348.123256 -288.320734)
		(end 348.050612 -288.363152)
		(width 0.1143)
		(layer "In6.Cu")
		(net "P5E_CPU0_P0_TX_DN<3>")
	)
	(segment
		(start 348.083378 -289.96386)
		(end 348.082108 -289.964622)
		(width 0.1143)
		(layer "In6.Cu")
		(net "P5E_CPU0_P0_TX_DN<3>")
	)
	(segment
		(start 347.472508 -296.281094)
		(end 347.472508 -299.120814)
		(width 0.14224)
		(layer "In6.Cu")
		(net "P5E_CPU0_P0_TX_DN<3>")
	)
	(segment
		(start 348.123256 -293.180516)
		(end 348.08414 -293.203376)
		(width 0.1143)
		(layer "In6.Cu")
		(net "P5E_CPU0_P0_TX_DN<3>")
	)
	(segment
		(start 348.07271 -293.210234)
		(end 348.05239 -293.221664)
		(width 0.1143)
		(layer "In6.Cu")
		(net "P5E_CPU0_P0_TX_DN<3>")
	)
	(segment
		(start 348.07525 -293.20871)
		(end 348.07271 -293.210234)
		(width 0.1143)
		(layer "In6.Cu")
		(net "P5E_CPU0_P0_TX_DN<3>")
	)
	(segment
		(start 347.472508 -299.120814)
		(end 351.37852 -308.551326)
		(width 0.14224)
		(layer "In6.Cu")
		(net "P5E_CPU0_P0_TX_DN<3>")
	)
	(segment
		(start 347.79331 -295.573958)
		(end 347.474032 -295.892982)
		(width 0.1143)
		(layer "In6.Cu")
		(net "P5E_CPU0_P0_TX_DN<3>")
	)
	(segment
		(start 348.07525 -285.108904)
		(end 348.07271 -285.110428)
		(width 0.1143)
		(layer "In6.Cu")
		(net "P5E_CPU0_P0_TX_DN<3>")
	)
	(segment
		(start 347.896434 -295.145968)
		(end 347.89618 -295.146222)
		(width 0.1143)
		(layer "In6.Cu")
		(net "P5E_CPU0_P0_TX_DN<3>")
	)
	(segment
		(start 348.593156 -284.270704)
		(end 348.52356 -284.311344)
		(width 0.1143)
		(layer "In6.Cu")
		(net "P5E_CPU0_P0_TX_DN<3>")
	)
	(segment
		(start 348.07271 -285.110428)
		(end 348.05239 -285.121858)
		(width 0.1143)
		(layer "In6.Cu")
		(net "P5E_CPU0_P0_TX_DN<3>")
	)
	(segment
		(start 348.07525 -291.588698)
		(end 348.07271 -291.590222)
		(width 0.1143)
		(layer "In6.Cu")
		(net "P5E_CPU0_P0_TX_DN<3>")
	)
	(segment
		(start 348.080584 -285.105602)
		(end 348.079822 -285.10611)
		(width 0.1143)
		(layer "In6.Cu")
		(net "P5E_CPU0_P0_TX_DN<3>")
	)
	(segment
		(start 351.37852 -308.551326)
		(end 357.944166 -318.377062)
		(width 0.14224)
		(layer "In6.Cu")
		(net "P5E_CPU0_P0_TX_DN<3>")
	)
	(segment
		(start 348.079822 -289.965892)
		(end 348.07525 -289.968686)
		(width 0.1143)
		(layer "In6.Cu")
		(net "P5E_CPU0_P0_TX_DN<3>")
	)
	(segment
		(start 357.944166 -318.377062)
		(end 363.548168 -325.205598)
		(width 0.14224)
		(layer "In6.Cu")
		(net "P5E_CPU0_P0_TX_DN<3>")
	)
	(segment
		(start 362.445554 -363.215428)
		(end 358.717596 -366.943386)
		(width 0.14224)
		(layer "In6.Cu")
		(net "P5E_CPU0_P0_TX_DN<3>")
	)
	(segment
		(start 347.89618 -295.146222)
		(end 347.89618 -295.325292)
		(width 0.1143)
		(layer "In6.Cu")
		(net "P5E_CPU0_P0_TX_DN<3>")
	)
	(segment
		(start 349.02394 -283.48305)
		(end 349.022924 -283.483558)
		(width 0.1143)
		(layer "In6.Cu")
		(net "P5E_CPU0_P0_TX_DN<3>")
	)
	(segment
		(start 348.080584 -293.205408)
		(end 348.079822 -293.205916)
		(width 0.1143)
		(layer "In6.Cu")
		(net "P5E_CPU0_P0_TX_DN<3>")
	)
	(segment
		(start 348.05239 -287.3502)
		(end 348.120716 -287.389824)
		(width 0.1143)
		(layer "In6.Cu")
		(net "P5E_CPU0_P0_TX_DN<3>")
	)
	(segment
		(start 348.05239 -288.970212)
		(end 348.123256 -289.01136)
		(width 0.1143)
		(layer "In6.Cu")
		(net "P5E_CPU0_P0_TX_DN<3>")
	)
	(segment
		(start 347.426788 -296.206926)
		(end 347.472508 -296.252646)
		(width 0.1143)
		(layer "In6.Cu")
		(net "P5E_CPU0_P0_TX_DN<3>")
	)
	(segment
		(start 347.896434 -295.049702)
		(end 347.896434 -295.145968)
		(width 0.1143)
		(layer "In6.Cu")
		(net "P5E_CPU0_P0_TX_DN<3>")
	)
	(arc
		(start 349.296482 -283.101542)
		(mid 349.203514 -283.320371)
		(end 349.028004 -283.480764)
		(width 0.1143)
		(layer "In6.Cu")
		(net "P5E_CPU0_P0_TX_DN<3>")
	)
	(arc
		(start 347.974158 -294.898064)
		(mid 347.916969 -294.964495)
		(end 347.896434 -295.049702)
		(width 0.1143)
		(layer "In6.Cu")
		(net "P5E_CPU0_P0_TX_DN<3>")
	)
	(arc
		(start 347.896434 -288.66592)
		(mid 347.937689 -288.836891)
		(end 348.05239 -288.970212)
		(width 0.1143)
		(layer "In6.Cu")
		(net "P5E_CPU0_P0_TX_DN<3>")
	)
	(arc
		(start 347.896434 -287.045908)
		(mid 347.937689 -287.216879)
		(end 348.05239 -287.3502)
		(width 0.1143)
		(layer "In6.Cu")
		(net "P5E_CPU0_P0_TX_DN<3>")
	)
	(arc
		(start 348.05239 -293.221664)
		(mid 347.896462 -293.525956)
		(end 348.05239 -293.830248)
		(width 0.1143)
		(layer "In6.Cu")
		(net "P5E_CPU0_P0_TX_DN<3>")
	)
	(arc
		(start 348.366588 -284.616144)
		(mid 348.302073 -284.878363)
		(end 348.123256 -285.08071)
		(width 0.1143)
		(layer "In6.Cu")
		(net "P5E_CPU0_P0_TX_DN<3>")
	)
	(arc
		(start 301.879508 -374.77192)
		(mid 301.44283 -375.425455)
		(end 301.289466 -376.196352)
		(width 0.14224)
		(layer "In6.Cu")
		(net "P5E_CPU0_P0_TX_DN<3>")
	)
	(arc
		(start 347.583506 -285.931356)
		(mid 347.468079 -286.064732)
		(end 347.426534 -286.236156)
		(width 0.1143)
		(layer "In6.Cu")
		(net "P5E_CPU0_P0_TX_DN<3>")
	)
	(arc
		(start 348.123256 -293.871396)
		(mid 348.366583 -294.335962)
		(end 348.123256 -294.800528)
		(width 0.1143)
		(layer "In6.Cu")
		(net "P5E_CPU0_P0_TX_DN<3>")
	)
	(arc
		(start 348.123256 -292.251384)
		(mid 348.366583 -292.71595)
		(end 348.123256 -293.180516)
		(width 0.1143)
		(layer "In6.Cu")
		(net "P5E_CPU0_P0_TX_DN<3>")
	)
	(arc
		(start 358.717596 -366.943386)
		(mid 357.721095 -367.609227)
		(end 356.545642 -367.843054)
		(width 0.14224)
		(layer "In6.Cu")
		(net "P5E_CPU0_P0_TX_DN<3>")
	)
	(arc
		(start 368.120168 -349.515684)
		(mid 366.645383 -356.92993)
		(end 362.445554 -363.215428)
		(width 0.14224)
		(layer "In6.Cu")
		(net "P5E_CPU0_P0_TX_DN<3>")
	)
	(arc
		(start 348.05239 -291.601652)
		(mid 347.896462 -291.905944)
		(end 348.05239 -292.210236)
		(width 0.1143)
		(layer "In6.Cu")
		(net "P5E_CPU0_P0_TX_DN<3>")
	)
	(arc
		(start 348.05239 -285.121858)
		(mid 347.937714 -285.255192)
		(end 347.896434 -285.42615)
		(width 0.1143)
		(layer "In6.Cu")
		(net "P5E_CPU0_P0_TX_DN<3>")
	)
	(arc
		(start 306.470304 -372.440962)
		(mid 304.382511 -372.85625)
		(end 302.612552 -374.038876)
		(width 0.14224)
		(layer "In6.Cu")
		(net "P5E_CPU0_P0_TX_DN<3>")
	)
	(arc
		(start 348.050612 -288.363152)
		(mid 347.937205 -288.496041)
		(end 347.896434 -288.66592)
		(width 0.1143)
		(layer "In6.Cu")
		(net "P5E_CPU0_P0_TX_DN<3>")
	)
	(arc
		(start 347.426534 -286.236156)
		(mid 347.4675 -286.406562)
		(end 347.581474 -286.539686)
		(width 0.1143)
		(layer "In6.Cu")
		(net "P5E_CPU0_P0_TX_DN<3>")
	)
	(arc
		(start 348.120716 -287.389824)
		(mid 348.366604 -287.854618)
		(end 348.123256 -288.320734)
		(width 0.1143)
		(layer "In6.Cu")
		(net "P5E_CPU0_P0_TX_DN<3>")
	)
	(arc
		(start 348.05239 -289.98164)
		(mid 347.896462 -290.285932)
		(end 348.05239 -290.590224)
		(width 0.1143)
		(layer "In6.Cu")
		(net "P5E_CPU0_P0_TX_DN<3>")
	)
	(arc
		(start 349.300292 -283.078936)
		(mid 349.298503 -283.090258)
		(end 349.296482 -283.101542)
		(width 0.1143)
		(layer "In6.Cu")
		(net "P5E_CPU0_P0_TX_DN<3>")
	)
	(arc
		(start 347.474032 -295.892982)
		(mid 347.439123 -295.945321)
		(end 347.426788 -296.007028)
		(width 0.1143)
		(layer "In6.Cu")
		(net "P5E_CPU0_P0_TX_DN<3>")
	)
	(arc
		(start 347.896434 -285.42615)
		(mid 347.831919 -285.688369)
		(end 347.653102 -285.890716)
		(width 0.1143)
		(layer "In6.Cu")
		(net "P5E_CPU0_P0_TX_DN<3>")
	)
	(arc
		(start 347.89618 -295.325292)
		(mid 347.869451 -295.459847)
		(end 347.79331 -295.573958)
		(width 0.1143)
		(layer "In6.Cu")
		(net "P5E_CPU0_P0_TX_DN<3>")
	)
	(arc
		(start 321.863466 -367.843054)
		(mid 320.422784 -367.984942)
		(end 319.037462 -368.405156)
		(width 0.14224)
		(layer "In6.Cu")
		(net "P5E_CPU0_P0_TX_DN<3>")
	)
	(arc
		(start 347.653102 -286.581342)
		(mid 347.831915 -286.783692)
		(end 347.896434 -287.045908)
		(width 0.1143)
		(layer "In6.Cu")
		(net "P5E_CPU0_P0_TX_DN<3>")
	)
	(arc
		(start 349.022924 -283.483558)
		(mid 348.886476 -283.619857)
		(end 348.836488 -283.806138)
		(width 0.1143)
		(layer "In6.Cu")
		(net "P5E_CPU0_P0_TX_DN<3>")
	)
	(arc
		(start 348.836488 -283.806138)
		(mid 348.771973 -284.068357)
		(end 348.593156 -284.270704)
		(width 0.1143)
		(layer "In6.Cu")
		(net "P5E_CPU0_P0_TX_DN<3>")
	)
	(arc
		(start 348.123256 -290.631372)
		(mid 348.366583 -291.095938)
		(end 348.123256 -291.560504)
		(width 0.1143)
		(layer "In6.Cu")
		(net "P5E_CPU0_P0_TX_DN<3>")
	)
	(arc
		(start 348.52356 -284.311344)
		(mid 348.408133 -284.44472)
		(end 348.366588 -284.616144)
		(width 0.1143)
		(layer "In6.Cu")
		(net "P5E_CPU0_P0_TX_DN<3>")
	)
	(arc
		(start 348.123256 -289.01136)
		(mid 348.366583 -289.475926)
		(end 348.123256 -289.940492)
		(width 0.1143)
		(layer "In6.Cu")
		(net "P5E_CPU0_P0_TX_DN<3>")
	)
	(arc
		(start 309.97271 -372.159784)
		(mid 309.279672 -372.369978)
		(end 308.558946 -372.440962)
		(width 0.14224)
		(layer "In6.Cu")
		(net "P5E_CPU0_P0_TX_DN<3>")
	)
	(segment
		(start 299.607986 -380.15164)
		(end 299.878496 -379.88113)
		(width 0.12954)
		(layer "F.Cu")
		(net "P5E_CPU0_P0_TX_DN<2>")
	)
	(segment
		(start 299.903896 -381.15113)
		(end 299.607986 -380.85522)
		(width 0.12954)
		(layer "F.Cu")
		(net "P5E_CPU0_P0_TX_DN<2>")
	)
	(segment
		(start 347.327982 -281.110182)
		(end 346.86113 -281.37612)
		(width 0.12954)
		(layer "F.Cu")
		(net "P5E_CPU0_P0_TX_DN<2>")
	)
	(segment
		(start 299.607986 -380.85522)
		(end 299.607986 -380.15164)
		(width 0.12954)
		(layer "F.Cu")
		(net "P5E_CPU0_P0_TX_DN<2>")
	)
	(segment
		(start 346.95638 -295.145968)
		(end 346.95638 -295.301924)
		(width 0.1143)
		(layer "In6.Cu")
		(net "P5E_CPU0_P0_TX_DN<2>")
	)
	(segment
		(start 347.144086 -289.963352)
		(end 347.112336 -289.98164)
		(width 0.1143)
		(layer "In6.Cu")
		(net "P5E_CPU0_P0_TX_DN<2>")
	)
	(segment
		(start 356.385622 -366.90808)
		(end 321.841114 -366.90808)
		(width 0.14224)
		(layer "In6.Cu")
		(net "P5E_CPU0_P0_TX_DN<2>")
	)
	(segment
		(start 347.183202 -288.320734)
		(end 347.113352 -288.36112)
		(width 0.1143)
		(layer "In6.Cu")
		(net "P5E_CPU0_P0_TX_DN<2>")
	)
	(segment
		(start 347.144086 -284.128718)
		(end 347.183202 -284.151578)
		(width 0.1143)
		(layer "In6.Cu")
		(net "P5E_CPU0_P0_TX_DN<2>")
	)
	(segment
		(start 347.156278 -283.4767)
		(end 347.154754 -283.477716)
		(width 0.1143)
		(layer "In6.Cu")
		(net "P5E_CPU0_P0_TX_DN<2>")
	)
	(segment
		(start 346.5322 -296.281094)
		(end 346.5322 -299.287692)
		(width 0.14224)
		(layer "In6.Cu")
		(net "P5E_CPU0_P0_TX_DN<2>")
	)
	(segment
		(start 299.587666 -379.5903)
		(end 299.878496 -379.88113)
		(width 0.14224)
		(layer "In6.Cu")
		(net "P5E_CPU0_P0_TX_DN<2>")
	)
	(segment
		(start 346.85351 -295.55059)
		(end 346.533724 -295.870122)
		(width 0.1143)
		(layer "In6.Cu")
		(net "P5E_CPU0_P0_TX_DN<2>")
	)
	(segment
		(start 346.958158 -282.189174)
		(end 346.958158 -282.199588)
		(width 0.1143)
		(layer "In6.Cu")
		(net "P5E_CPU0_P0_TX_DN<2>")
	)
	(segment
		(start 346.95638 -285.442152)
		(end 346.95638 -285.442406)
		(width 0.1143)
		(layer "In6.Cu")
		(net "P5E_CPU0_P0_TX_DN<2>")
	)
	(segment
		(start 350.552258 -308.993286)
		(end 357.321612 -319.123822)
		(width 0.14224)
		(layer "In6.Cu")
		(net "P5E_CPU0_P0_TX_DN<2>")
	)
	(segment
		(start 346.674186 -285.913576)
		(end 346.642436 -285.931864)
		(width 0.1143)
		(layer "In6.Cu")
		(net "P5E_CPU0_P0_TX_DN<2>")
	)
	(segment
		(start 347.11767 -285.11881)
		(end 347.116908 -285.119318)
		(width 0.1143)
		(layer "In6.Cu")
		(net "P5E_CPU0_P0_TX_DN<2>")
	)
	(segment
		(start 347.144086 -293.203376)
		(end 347.112336 -293.221664)
		(width 0.1143)
		(layer "In6.Cu")
		(net "P5E_CPU0_P0_TX_DN<2>")
	)
	(segment
		(start 347.144086 -291.583364)
		(end 347.112336 -291.601652)
		(width 0.1143)
		(layer "In6.Cu")
		(net "P5E_CPU0_P0_TX_DN<2>")
	)
	(segment
		(start 346.642436 -281.680412)
		(end 346.666566 -281.693874)
		(width 0.1143)
		(layer "In6.Cu")
		(net "P5E_CPU0_P0_TX_DN<2>")
	)
	(segment
		(start 347.112336 -287.3502)
		(end 347.180662 -287.389824)
		(width 0.1143)
		(layer "In6.Cu")
		(net "P5E_CPU0_P0_TX_DN<2>")
	)
	(segment
		(start 362.779564 -325.774304)
		(end 365.089948 -330.193142)
		(width 0.14224)
		(layer "In6.Cu")
		(net "P5E_CPU0_P0_TX_DN<2>")
	)
	(segment
		(start 347.143578 -285.10357)
		(end 347.11767 -285.11881)
		(width 0.1143)
		(layer "In6.Cu")
		(net "P5E_CPU0_P0_TX_DN<2>")
	)
	(segment
		(start 301.635668 -373.165624)
		(end 300.5963 -374.204992)
		(width 0.14224)
		(layer "In6.Cu")
		(net "P5E_CPU0_P0_TX_DN<2>")
	)
	(segment
		(start 367.187988 -341.864696)
		(end 367.187988 -349.29445)
		(width 0.14224)
		(layer "In6.Cu")
		(net "P5E_CPU0_P0_TX_DN<2>")
	)
	(segment
		(start 347.112336 -293.830248)
		(end 347.144086 -293.848536)
		(width 0.1143)
		(layer "In6.Cu")
		(net "P5E_CPU0_P0_TX_DN<2>")
	)
	(segment
		(start 347.112336 -284.11043)
		(end 347.144086 -284.128718)
		(width 0.1143)
		(layer "In6.Cu")
		(net "P5E_CPU0_P0_TX_DN<2>")
	)
	(segment
		(start 347.183202 -285.08071)
		(end 347.144086 -285.10357)
		(width 0.1143)
		(layer "In6.Cu")
		(net "P5E_CPU0_P0_TX_DN<2>")
	)
	(segment
		(start 346.640658 -286.538924)
		(end 346.64396 -286.540702)
		(width 0.1143)
		(layer "In6.Cu")
		(net "P5E_CPU0_P0_TX_DN<2>")
	)
	(segment
		(start 299.587666 -376.639836)
		(end 299.587666 -379.5903)
		(width 0.14224)
		(layer "In6.Cu")
		(net "P5E_CPU0_P0_TX_DN<2>")
	)
	(segment
		(start 347.105986 -287.345628)
		(end 347.112336 -287.3502)
		(width 0.1143)
		(layer "In6.Cu")
		(net "P5E_CPU0_P0_TX_DN<2>")
	)
	(segment
		(start 347.133164 -282.502864)
		(end 347.136212 -282.504388)
		(width 0.1143)
		(layer "In6.Cu")
		(net "P5E_CPU0_P0_TX_DN<2>")
	)
	(segment
		(start 347.144086 -290.608512)
		(end 347.183202 -290.631372)
		(width 0.1143)
		(layer "In6.Cu")
		(net "P5E_CPU0_P0_TX_DN<2>")
	)
	(segment
		(start 357.321612 -319.123822)
		(end 362.779564 -325.774304)
		(width 0.14224)
		(layer "In6.Cu")
		(net "P5E_CPU0_P0_TX_DN<2>")
	)
	(segment
		(start 347.154754 -283.477716)
		(end 347.153738 -283.478224)
		(width 0.1143)
		(layer "In6.Cu")
		(net "P5E_CPU0_P0_TX_DN<2>")
	)
	(segment
		(start 346.64396 -286.540702)
		(end 346.710508 -286.579564)
		(width 0.1143)
		(layer "In6.Cu")
		(net "P5E_CPU0_P0_TX_DN<2>")
	)
	(segment
		(start 346.5322 -299.287692)
		(end 350.552258 -308.993286)
		(width 0.14224)
		(layer "In6.Cu")
		(net "P5E_CPU0_P0_TX_DN<2>")
	)
	(segment
		(start 347.112336 -288.970212)
		(end 347.144086 -288.9885)
		(width 0.1143)
		(layer "In6.Cu")
		(net "P5E_CPU0_P0_TX_DN<2>")
	)
	(segment
		(start 347.113352 -288.36112)
		(end 347.110558 -288.363152)
		(width 0.1143)
		(layer "In6.Cu")
		(net "P5E_CPU0_P0_TX_DN<2>")
	)
	(segment
		(start 347.145102 -294.82288)
		(end 347.144086 -294.823388)
		(width 0.1143)
		(layer "In6.Cu")
		(net "P5E_CPU0_P0_TX_DN<2>")
	)
	(segment
		(start 347.183202 -294.800528)
		(end 347.145102 -294.82288)
		(width 0.1143)
		(layer "In6.Cu")
		(net "P5E_CPU0_P0_TX_DN<2>")
	)
	(segment
		(start 346.86113 -281.37612)
		(end 346.563188 -281.37612)
		(width 0.1143)
		(layer "In6.Cu")
		(net "P5E_CPU0_P0_TX_DN<2>")
	)
	(segment
		(start 347.144086 -292.228524)
		(end 347.183202 -292.251384)
		(width 0.1143)
		(layer "In6.Cu")
		(net "P5E_CPU0_P0_TX_DN<2>")
	)
	(segment
		(start 347.183202 -291.560504)
		(end 347.144086 -291.583364)
		(width 0.1143)
		(layer "In6.Cu")
		(net "P5E_CPU0_P0_TX_DN<2>")
	)
	(segment
		(start 346.563188 -281.37612)
		(end 346.493338 -281.44597)
		(width 0.1143)
		(layer "In6.Cu")
		(net "P5E_CPU0_P0_TX_DN<2>")
	)
	(segment
		(start 308.290214 -371.502432)
		(end 305.6509 -371.502432)
		(width 0.14224)
		(layer "In6.Cu")
		(net "P5E_CPU0_P0_TX_DN<2>")
	)
	(segment
		(start 347.153738 -283.478224)
		(end 347.112336 -283.501846)
		(width 0.1143)
		(layer "In6.Cu")
		(net "P5E_CPU0_P0_TX_DN<2>")
	)
	(segment
		(start 346.48648 -296.206926)
		(end 346.5322 -296.252646)
		(width 0.1143)
		(layer "In6.Cu")
		(net "P5E_CPU0_P0_TX_DN<2>")
	)
	(segment
		(start 347.183202 -293.180516)
		(end 347.144086 -293.203376)
		(width 0.1143)
		(layer "In6.Cu")
		(net "P5E_CPU0_P0_TX_DN<2>")
	)
	(segment
		(start 347.144086 -294.823388)
		(end 347.143324 -294.823896)
		(width 0.1143)
		(layer "In6.Cu")
		(net "P5E_CPU0_P0_TX_DN<2>")
	)
	(segment
		(start 347.112336 -292.210236)
		(end 347.144086 -292.228524)
		(width 0.1143)
		(layer "In6.Cu")
		(net "P5E_CPU0_P0_TX_DN<2>")
	)
	(segment
		(start 346.5322 -296.252646)
		(end 346.5322 -296.281094)
		(width 0.1143)
		(layer "In6.Cu")
		(net "P5E_CPU0_P0_TX_DN<2>")
	)
	(segment
		(start 318.701166 -367.532666)
		(end 309.88635 -371.185186)
		(width 0.14224)
		(layer "In6.Cu")
		(net "P5E_CPU0_P0_TX_DN<2>")
	)
	(segment
		(start 347.144086 -285.10357)
		(end 347.143578 -285.10357)
		(width 0.1143)
		(layer "In6.Cu")
		(net "P5E_CPU0_P0_TX_DN<2>")
	)
	(segment
		(start 347.143324 -294.823896)
		(end 347.112336 -294.841676)
		(width 0.1143)
		(layer "In6.Cu")
		(net "P5E_CPU0_P0_TX_DN<2>")
	)
	(segment
		(start 347.112336 -290.590224)
		(end 347.144086 -290.608512)
		(width 0.1143)
		(layer "In6.Cu")
		(net "P5E_CPU0_P0_TX_DN<2>")
	)
	(segment
		(start 347.136212 -282.504388)
		(end 347.188536 -282.537154)
		(width 0.1143)
		(layer "In6.Cu")
		(net "P5E_CPU0_P0_TX_DN<2>")
	)
	(segment
		(start 347.159072 -283.474922)
		(end 347.156278 -283.4767)
		(width 0.1143)
		(layer "In6.Cu")
		(net "P5E_CPU0_P0_TX_DN<2>")
	)
	(segment
		(start 346.48648 -295.984168)
		(end 346.48648 -296.206926)
		(width 0.1143)
		(layer "In6.Cu")
		(net "P5E_CPU0_P0_TX_DN<2>")
	)
	(segment
		(start 347.183202 -289.940492)
		(end 347.144086 -289.963352)
		(width 0.1143)
		(layer "In6.Cu")
		(net "P5E_CPU0_P0_TX_DN<2>")
	)
	(segment
		(start 365.089948 -330.193142)
		(end 367.187988 -341.864696)
		(width 0.14224)
		(layer "In6.Cu")
		(net "P5E_CPU0_P0_TX_DN<2>")
	)
	(segment
		(start 347.144086 -288.9885)
		(end 347.183202 -289.01136)
		(width 0.1143)
		(layer "In6.Cu")
		(net "P5E_CPU0_P0_TX_DN<2>")
	)
	(segment
		(start 347.182186 -283.46146)
		(end 347.159072 -283.474922)
		(width 0.1143)
		(layer "In6.Cu")
		(net "P5E_CPU0_P0_TX_DN<2>")
	)
	(segment
		(start 347.144086 -293.848536)
		(end 347.183202 -293.871396)
		(width 0.1143)
		(layer "In6.Cu")
		(net "P5E_CPU0_P0_TX_DN<2>")
	)
	(segment
		(start 346.710508 -285.892494)
		(end 346.674186 -285.913576)
		(width 0.1143)
		(layer "In6.Cu")
		(net "P5E_CPU0_P0_TX_DN<2>")
	)
	(segment
		(start 361.631738 -362.708698)
		(end 358.172512 -366.167924)
		(width 0.14224)
		(layer "In6.Cu")
		(net "P5E_CPU0_P0_TX_DN<2>")
	)
	(segment
		(start 346.95638 -287.045908)
		(end 346.95638 -287.053528)
		(width 0.1143)
		(layer "In6.Cu")
		(net "P5E_CPU0_P0_TX_DN<2>")
	)
	(arc
		(start 347.112336 -283.501846)
		(mid 346.963239 -283.806138)
		(end 347.112336 -284.11043)
		(width 0.1143)
		(layer "In6.Cu")
		(net "P5E_CPU0_P0_TX_DN<2>")
	)
	(arc
		(start 347.183202 -284.151578)
		(mid 347.426529 -284.616144)
		(end 347.183202 -285.08071)
		(width 0.1143)
		(layer "In6.Cu")
		(net "P5E_CPU0_P0_TX_DN<2>")
	)
	(arc
		(start 347.116908 -285.119318)
		(mid 347.112308 -285.122839)
		(end 347.107764 -285.12643)
		(width 0.1143)
		(layer "In6.Cu")
		(net "P5E_CPU0_P0_TX_DN<2>")
	)
	(arc
		(start 347.110558 -288.363152)
		(mid 346.997151 -288.496041)
		(end 346.95638 -288.66592)
		(width 0.1143)
		(layer "In6.Cu")
		(net "P5E_CPU0_P0_TX_DN<2>")
	)
	(arc
		(start 358.172512 -366.167924)
		(mid 357.35268 -366.715718)
		(end 356.385622 -366.90808)
		(width 0.14224)
		(layer "In6.Cu")
		(net "P5E_CPU0_P0_TX_DN<2>")
	)
	(arc
		(start 347.107764 -285.12643)
		(mid 347.013847 -285.251514)
		(end 346.960952 -285.398718)
		(width 0.1143)
		(layer "In6.Cu")
		(net "P5E_CPU0_P0_TX_DN<2>")
	)
	(arc
		(start 346.958158 -282.199588)
		(mid 347.005049 -282.37466)
		(end 347.133164 -282.502864)
		(width 0.1143)
		(layer "In6.Cu")
		(net "P5E_CPU0_P0_TX_DN<2>")
	)
	(arc
		(start 346.960952 -285.398718)
		(mid 346.957767 -285.42034)
		(end 346.95638 -285.442152)
		(width 0.1143)
		(layer "In6.Cu")
		(net "P5E_CPU0_P0_TX_DN<2>")
	)
	(arc
		(start 347.183202 -289.01136)
		(mid 347.426529 -289.475926)
		(end 347.183202 -289.940492)
		(width 0.1143)
		(layer "In6.Cu")
		(net "P5E_CPU0_P0_TX_DN<2>")
	)
	(arc
		(start 347.112336 -294.841676)
		(mid 347.000539 -294.976477)
		(end 346.95638 -295.145968)
		(width 0.1143)
		(layer "In6.Cu")
		(net "P5E_CPU0_P0_TX_DN<2>")
	)
	(arc
		(start 321.841114 -366.90808)
		(mid 320.240367 -367.065682)
		(end 318.701166 -367.532666)
		(width 0.14224)
		(layer "In6.Cu")
		(net "P5E_CPU0_P0_TX_DN<2>")
	)
	(arc
		(start 347.426534 -287.856168)
		(mid 347.362019 -288.118387)
		(end 347.183202 -288.320734)
		(width 0.1143)
		(layer "In6.Cu")
		(net "P5E_CPU0_P0_TX_DN<2>")
	)
	(arc
		(start 346.710508 -286.579564)
		(mid 346.89116 -286.782309)
		(end 346.95638 -287.045908)
		(width 0.1143)
		(layer "In6.Cu")
		(net "P5E_CPU0_P0_TX_DN<2>")
	)
	(arc
		(start 346.533724 -295.870122)
		(mid 346.498815 -295.922461)
		(end 346.48648 -295.984168)
		(width 0.1143)
		(layer "In6.Cu")
		(net "P5E_CPU0_P0_TX_DN<2>")
	)
	(arc
		(start 347.183202 -293.871396)
		(mid 347.426529 -294.335962)
		(end 347.183202 -294.800528)
		(width 0.1143)
		(layer "In6.Cu")
		(net "P5E_CPU0_P0_TX_DN<2>")
	)
	(arc
		(start 300.5963 -374.204992)
		(mid 299.849813 -375.322094)
		(end 299.587666 -376.639836)
		(width 0.14224)
		(layer "In6.Cu")
		(net "P5E_CPU0_P0_TX_DN<2>")
	)
	(arc
		(start 346.95638 -288.66592)
		(mid 347.000451 -288.835456)
		(end 347.112336 -288.970212)
		(width 0.1143)
		(layer "In6.Cu")
		(net "P5E_CPU0_P0_TX_DN<2>")
	)
	(arc
		(start 347.3958 -282.81249)
		(mid 347.398115 -283.172892)
		(end 347.182186 -283.46146)
		(width 0.1143)
		(layer "In6.Cu")
		(net "P5E_CPU0_P0_TX_DN<2>")
	)
	(arc
		(start 347.112336 -293.221664)
		(mid 346.963239 -293.525956)
		(end 347.112336 -293.830248)
		(width 0.1143)
		(layer "In6.Cu")
		(net "P5E_CPU0_P0_TX_DN<2>")
	)
	(arc
		(start 346.95638 -287.053528)
		(mid 346.99596 -287.217616)
		(end 347.105986 -287.345628)
		(width 0.1143)
		(layer "In6.Cu")
		(net "P5E_CPU0_P0_TX_DN<2>")
	)
	(arc
		(start 309.88635 -371.185186)
		(mid 309.10391 -371.422429)
		(end 308.290214 -371.502432)
		(width 0.14224)
		(layer "In6.Cu")
		(net "P5E_CPU0_P0_TX_DN<2>")
	)
	(arc
		(start 347.183202 -292.251384)
		(mid 347.426529 -292.71595)
		(end 347.183202 -293.180516)
		(width 0.1143)
		(layer "In6.Cu")
		(net "P5E_CPU0_P0_TX_DN<2>")
	)
	(arc
		(start 347.180662 -287.389824)
		(mid 347.361314 -287.592569)
		(end 347.426534 -287.856168)
		(width 0.1143)
		(layer "In6.Cu")
		(net "P5E_CPU0_P0_TX_DN<2>")
	)
	(arc
		(start 347.112336 -289.98164)
		(mid 346.963239 -290.285932)
		(end 347.112336 -290.590224)
		(width 0.1143)
		(layer "In6.Cu")
		(net "P5E_CPU0_P0_TX_DN<2>")
	)
	(arc
		(start 347.188536 -282.537154)
		(mid 347.313943 -282.658423)
		(end 347.3958 -282.81249)
		(width 0.1143)
		(layer "In6.Cu")
		(net "P5E_CPU0_P0_TX_DN<2>")
	)
	(arc
		(start 346.95638 -295.301924)
		(mid 346.929651 -295.436479)
		(end 346.85351 -295.55059)
		(width 0.1143)
		(layer "In6.Cu")
		(net "P5E_CPU0_P0_TX_DN<2>")
	)
	(arc
		(start 347.112336 -291.601652)
		(mid 346.960747 -291.905944)
		(end 347.112336 -292.210236)
		(width 0.1143)
		(layer "In6.Cu")
		(net "P5E_CPU0_P0_TX_DN<2>")
	)
	(arc
		(start 347.183202 -290.631372)
		(mid 347.426529 -291.095938)
		(end 347.183202 -291.560504)
		(width 0.1143)
		(layer "In6.Cu")
		(net "P5E_CPU0_P0_TX_DN<2>")
	)
	(arc
		(start 346.666566 -281.693874)
		(mid 346.87986 -281.90179)
		(end 346.958158 -282.189174)
		(width 0.1143)
		(layer "In6.Cu")
		(net "P5E_CPU0_P0_TX_DN<2>")
	)
	(arc
		(start 367.187988 -349.29445)
		(mid 365.743975 -356.554174)
		(end 361.631738 -362.708698)
		(width 0.14224)
		(layer "In6.Cu")
		(net "P5E_CPU0_P0_TX_DN<2>")
	)
	(arc
		(start 346.48648 -286.236156)
		(mid 346.527242 -286.40604)
		(end 346.640658 -286.538924)
		(width 0.1143)
		(layer "In6.Cu")
		(net "P5E_CPU0_P0_TX_DN<2>")
	)
	(arc
		(start 346.95638 -285.442406)
		(mid 346.887419 -285.696937)
		(end 346.710508 -285.892494)
		(width 0.1143)
		(layer "In6.Cu")
		(net "P5E_CPU0_P0_TX_DN<2>")
	)
	(arc
		(start 346.642436 -285.931864)
		(mid 346.52776 -286.065198)
		(end 346.48648 -286.236156)
		(width 0.1143)
		(layer "In6.Cu")
		(net "P5E_CPU0_P0_TX_DN<2>")
	)
	(arc
		(start 346.493338 -281.44597)
		(mid 346.545387 -281.577489)
		(end 346.642436 -281.680412)
		(width 0.1143)
		(layer "In6.Cu")
		(net "P5E_CPU0_P0_TX_DN<2>")
	)
	(arc
		(start 305.6509 -371.502432)
		(mid 303.477861 -371.934676)
		(end 301.635668 -373.165624)
		(width 0.14224)
		(layer "In6.Cu")
		(net "P5E_CPU0_P0_TX_DN<2>")
	)
	(segment
		(start 298.404534 -384.94335)
		(end 298.700444 -385.23926)
		(width 0.12954)
		(layer "F.Cu")
		(net "P5E_CPU0_P0_TX_DN<1>")
	)
	(segment
		(start 297.700954 -384.94335)
		(end 298.404534 -384.94335)
		(width 0.12954)
		(layer "F.Cu")
		(net "P5E_CPU0_P0_TX_DN<1>")
	)
	(segment
		(start 347.327982 -284.350206)
		(end 346.86113 -284.616144)
		(width 0.12954)
		(layer "F.Cu")
		(net "P5E_CPU0_P0_TX_DN<1>")
	)
	(segment
		(start 297.430444 -385.21386)
		(end 297.700954 -384.94335)
		(width 0.12954)
		(layer "F.Cu")
		(net "P5E_CPU0_P0_TX_DN<1>")
	)
	(segment
		(start 346.173552 -288.97072)
		(end 346.204032 -288.9885)
		(width 0.1143)
		(layer "In6.Cu")
		(net "P5E_CPU0_P0_TX_DN<1>")
	)
	(segment
		(start 345.709494 -285.928054)
		(end 345.702382 -285.931864)
		(width 0.1143)
		(layer "In6.Cu")
		(net "P5E_CPU0_P0_TX_DN<1>")
	)
	(segment
		(start 364.951264 -334.735424)
		(end 364.951518 -334.736186)
		(width 0.14224)
		(layer "In6.Cu")
		(net "P5E_CPU0_P0_TX_DN<1>")
	)
	(segment
		(start 345.700604 -286.538924)
		(end 345.734132 -286.558482)
		(width 0.1143)
		(layer "In6.Cu")
		(net "P5E_CPU0_P0_TX_DN<1>")
	)
	(segment
		(start 318.321182 -366.672622)
		(end 310.053228 -370.09705)
		(width 0.14224)
		(layer "In6.Cu")
		(net "P5E_CPU0_P0_TX_DN<1>")
	)
	(segment
		(start 345.592146 -299.45457)
		(end 349.750634 -309.494174)
		(width 0.14224)
		(layer "In6.Cu")
		(net "P5E_CPU0_P0_TX_DN<1>")
	)
	(segment
		(start 345.546426 -296.206926)
		(end 345.592146 -296.252646)
		(width 0.1143)
		(layer "In6.Cu")
		(net "P5E_CPU0_P0_TX_DN<1>")
	)
	(segment
		(start 345.592146 -296.281094)
		(end 345.592146 -299.45457)
		(width 0.14224)
		(layer "In6.Cu")
		(net "P5E_CPU0_P0_TX_DN<1>")
	)
	(segment
		(start 345.725242 -285.91891)
		(end 345.723464 -285.919926)
		(width 0.1143)
		(layer "In6.Cu")
		(net "P5E_CPU0_P0_TX_DN<1>")
	)
	(segment
		(start 346.204032 -288.343594)
		(end 346.17152 -288.36239)
		(width 0.1143)
		(layer "In6.Cu")
		(net "P5E_CPU0_P0_TX_DN<1>")
	)
	(segment
		(start 356.58298 -319.719706)
		(end 362.036106 -326.3646)
		(width 0.14224)
		(layer "In6.Cu")
		(net "P5E_CPU0_P0_TX_DN<1>")
	)
	(segment
		(start 298.851574 -382.592072)
		(end 298.851574 -384.410966)
		(width 0.14224)
		(layer "In6.Cu")
		(net "P5E_CPU0_P0_TX_DN<1>")
	)
	(segment
		(start 346.173552 -290.590732)
		(end 346.204032 -290.608512)
		(width 0.1143)
		(layer "In6.Cu")
		(net "P5E_CPU0_P0_TX_DN<1>")
	)
	(segment
		(start 297.786806 -377.041918)
		(end 297.786806 -381.135382)
		(width 0.14224)
		(layer "In6.Cu")
		(net "P5E_CPU0_P0_TX_DN<1>")
	)
	(segment
		(start 346.173552 -287.350708)
		(end 346.240608 -287.389824)
		(width 0.1143)
		(layer "In6.Cu")
		(net "P5E_CPU0_P0_TX_DN<1>")
	)
	(segment
		(start 345.713812 -285.925514)
		(end 345.709494 -285.928054)
		(width 0.1143)
		(layer "In6.Cu")
		(net "P5E_CPU0_P0_TX_DN<1>")
	)
	(segment
		(start 364.185454 -330.47559)
		(end 364.951264 -334.735424)
		(width 0.14224)
		(layer "In6.Cu")
		(net "P5E_CPU0_P0_TX_DN<1>")
	)
	(segment
		(start 346.243148 -288.320734)
		(end 346.204032 -288.343594)
		(width 0.1143)
		(layer "In6.Cu")
		(net "P5E_CPU0_P0_TX_DN<1>")
	)
	(segment
		(start 346.243148 -293.180516)
		(end 346.204032 -293.203376)
		(width 0.1143)
		(layer "In6.Cu")
		(net "P5E_CPU0_P0_TX_DN<1>")
	)
	(segment
		(start 345.879928 -295.557194)
		(end 345.59367 -295.843198)
		(width 0.1143)
		(layer "In6.Cu")
		(net "P5E_CPU0_P0_TX_DN<1>")
	)
	(segment
		(start 297.944286 -381.515366)
		(end 298.731686 -382.302766)
		(width 0.14224)
		(layer "In6.Cu")
		(net "P5E_CPU0_P0_TX_DN<1>")
	)
	(segment
		(start 345.730576 -285.915608)
		(end 345.729306 -285.91637)
		(width 0.1143)
		(layer "In6.Cu")
		(net "P5E_CPU0_P0_TX_DN<1>")
	)
	(segment
		(start 346.204032 -291.583364)
		(end 346.173552 -291.601144)
		(width 0.1143)
		(layer "In6.Cu")
		(net "P5E_CPU0_P0_TX_DN<1>")
	)
	(segment
		(start 346.204032 -293.203376)
		(end 346.173552 -293.221156)
		(width 0.1143)
		(layer "In6.Cu")
		(net "P5E_CPU0_P0_TX_DN<1>")
	)
	(segment
		(start 345.715336 -285.924498)
		(end 345.713812 -285.925514)
		(width 0.1143)
		(layer "In6.Cu")
		(net "P5E_CPU0_P0_TX_DN<1>")
	)
	(segment
		(start 345.722702 -285.920434)
		(end 345.7194 -285.922212)
		(width 0.1143)
		(layer "In6.Cu")
		(net "P5E_CPU0_P0_TX_DN<1>")
	)
	(segment
		(start 345.726766 -285.917894)
		(end 345.725242 -285.91891)
		(width 0.1143)
		(layer "In6.Cu")
		(net "P5E_CPU0_P0_TX_DN<1>")
	)
	(segment
		(start 346.204032 -292.228524)
		(end 346.243148 -292.251384)
		(width 0.1143)
		(layer "In6.Cu")
		(net "P5E_CPU0_P0_TX_DN<1>")
	)
	(segment
		(start 346.243148 -289.940492)
		(end 346.204032 -289.963352)
		(width 0.1143)
		(layer "In6.Cu")
		(net "P5E_CPU0_P0_TX_DN<1>")
	)
	(segment
		(start 345.727782 -285.917386)
		(end 345.726766 -285.917894)
		(width 0.1143)
		(layer "In6.Cu")
		(net "P5E_CPU0_P0_TX_DN<1>")
	)
	(segment
		(start 345.723464 -285.919926)
		(end 345.722702 -285.920434)
		(width 0.1143)
		(layer "In6.Cu")
		(net "P5E_CPU0_P0_TX_DN<1>")
	)
	(segment
		(start 356.280466 -365.973106)
		(end 321.838828 -365.973106)
		(width 0.14224)
		(layer "In6.Cu")
		(net "P5E_CPU0_P0_TX_DN<1>")
	)
	(segment
		(start 345.546426 -295.957244)
		(end 345.546426 -296.206926)
		(width 0.1143)
		(layer "In6.Cu")
		(net "P5E_CPU0_P0_TX_DN<1>")
	)
	(segment
		(start 345.734132 -286.558482)
		(end 345.773248 -286.581342)
		(width 0.1143)
		(layer "In6.Cu")
		(net "P5E_CPU0_P0_TX_DN<1>")
	)
	(segment
		(start 346.016326 -295.145968)
		(end 346.016326 -295.175178)
		(width 0.1143)
		(layer "In6.Cu")
		(net "P5E_CPU0_P0_TX_DN<1>")
	)
	(segment
		(start 346.243148 -294.800528)
		(end 346.172028 -294.842184)
		(width 0.1143)
		(layer "In6.Cu")
		(net "P5E_CPU0_P0_TX_DN<1>")
	)
	(segment
		(start 345.729306 -285.91637)
		(end 345.727782 -285.917386)
		(width 0.1143)
		(layer "In6.Cu")
		(net "P5E_CPU0_P0_TX_DN<1>")
	)
	(segment
		(start 298.731686 -384.700272)
		(end 298.632118 -384.79984)
		(width 0.14224)
		(layer "In6.Cu")
		(net "P5E_CPU0_P0_TX_DN<1>")
	)
	(segment
		(start 297.724576 -384.919728)
		(end 297.430444 -385.21386)
		(width 0.14224)
		(layer "In6.Cu")
		(net "P5E_CPU0_P0_TX_DN<1>")
	)
	(segment
		(start 366.229646 -341.84717)
		(end 366.229646 -349.276416)
		(width 0.14224)
		(layer "In6.Cu")
		(net "P5E_CPU0_P0_TX_DN<1>")
	)
	(segment
		(start 346.204032 -293.848536)
		(end 346.243148 -293.871396)
		(width 0.1143)
		(layer "In6.Cu")
		(net "P5E_CPU0_P0_TX_DN<1>")
	)
	(segment
		(start 362.036106 -326.3646)
		(end 364.185454 -330.47559)
		(width 0.14224)
		(layer "In6.Cu")
		(net "P5E_CPU0_P0_TX_DN<1>")
	)
	(segment
		(start 345.773248 -285.890716)
		(end 345.734132 -285.913576)
		(width 0.1143)
		(layer "In6.Cu")
		(net "P5E_CPU0_P0_TX_DN<1>")
	)
	(segment
		(start 346.173552 -293.830756)
		(end 346.204032 -293.848536)
		(width 0.1143)
		(layer "In6.Cu")
		(net "P5E_CPU0_P0_TX_DN<1>")
	)
	(segment
		(start 345.7321 -285.914846)
		(end 345.730576 -285.915608)
		(width 0.1143)
		(layer "In6.Cu")
		(net "P5E_CPU0_P0_TX_DN<1>")
	)
	(segment
		(start 345.592146 -296.252646)
		(end 345.592146 -296.281094)
		(width 0.1143)
		(layer "In6.Cu")
		(net "P5E_CPU0_P0_TX_DN<1>")
	)
	(segment
		(start 346.204032 -289.963352)
		(end 346.173552 -289.981132)
		(width 0.1143)
		(layer "In6.Cu")
		(net "P5E_CPU0_P0_TX_DN<1>")
	)
	(segment
		(start 298.342812 -384.919728)
		(end 297.724576 -384.919728)
		(width 0.14224)
		(layer "In6.Cu")
		(net "P5E_CPU0_P0_TX_DN<1>")
	)
	(segment
		(start 345.734132 -285.913576)
		(end 345.73337 -285.914084)
		(width 0.1143)
		(layer "In6.Cu")
		(net "P5E_CPU0_P0_TX_DN<1>")
	)
	(segment
		(start 301.586646 -371.845586)
		(end 298.774358 -374.657874)
		(width 0.14224)
		(layer "In6.Cu")
		(net "P5E_CPU0_P0_TX_DN<1>")
	)
	(segment
		(start 346.86113 -284.616144)
		(end 346.563188 -284.616144)
		(width 0.1143)
		(layer "In6.Cu")
		(net "P5E_CPU0_P0_TX_DN<1>")
	)
	(segment
		(start 346.243148 -285.08071)
		(end 346.173552 -285.12135)
		(width 0.1143)
		(layer "In6.Cu")
		(net "P5E_CPU0_P0_TX_DN<1>")
	)
	(segment
		(start 360.916474 -362.103416)
		(end 357.588566 -365.431324)
		(width 0.14224)
		(layer "In6.Cu")
		(net "P5E_CPU0_P0_TX_DN<1>")
	)
	(segment
		(start 346.204032 -288.9885)
		(end 346.243148 -289.01136)
		(width 0.1143)
		(layer "In6.Cu")
		(net "P5E_CPU0_P0_TX_DN<1>")
	)
	(segment
		(start 346.204032 -290.608512)
		(end 346.243148 -290.631372)
		(width 0.1143)
		(layer "In6.Cu")
		(net "P5E_CPU0_P0_TX_DN<1>")
	)
	(segment
		(start 364.951518 -334.736186)
		(end 366.229646 -341.84717)
		(width 0.14224)
		(layer "In6.Cu")
		(net "P5E_CPU0_P0_TX_DN<1>")
	)
	(segment
		(start 346.173552 -292.210744)
		(end 346.204032 -292.228524)
		(width 0.1143)
		(layer "In6.Cu")
		(net "P5E_CPU0_P0_TX_DN<1>")
	)
	(segment
		(start 346.563188 -284.616144)
		(end 346.480384 -284.698948)
		(width 0.1143)
		(layer "In6.Cu")
		(net "P5E_CPU0_P0_TX_DN<1>")
	)
	(segment
		(start 345.717368 -285.923482)
		(end 345.715336 -285.924498)
		(width 0.1143)
		(layer "In6.Cu")
		(net "P5E_CPU0_P0_TX_DN<1>")
	)
	(segment
		(start 345.7194 -285.922212)
		(end 345.717368 -285.923482)
		(width 0.1143)
		(layer "In6.Cu")
		(net "P5E_CPU0_P0_TX_DN<1>")
	)
	(segment
		(start 307.69814 -370.565426)
		(end 304.677318 -370.565426)
		(width 0.14224)
		(layer "In6.Cu")
		(net "P5E_CPU0_P0_TX_DN<1>")
	)
	(segment
		(start 349.750634 -309.494174)
		(end 356.58298 -319.719706)
		(width 0.14224)
		(layer "In6.Cu")
		(net "P5E_CPU0_P0_TX_DN<1>")
	)
	(segment
		(start 345.73337 -285.914084)
		(end 345.7321 -285.914846)
		(width 0.1143)
		(layer "In6.Cu")
		(net "P5E_CPU0_P0_TX_DN<1>")
	)
	(segment
		(start 346.243148 -291.560504)
		(end 346.204032 -291.583364)
		(width 0.1143)
		(layer "In6.Cu")
		(net "P5E_CPU0_P0_TX_DN<1>")
	)
	(arc
		(start 345.702382 -285.931864)
		(mid 345.587706 -286.065198)
		(end 345.546426 -286.236156)
		(width 0.1143)
		(layer "In6.Cu")
		(net "P5E_CPU0_P0_TX_DN<1>")
	)
	(arc
		(start 298.774358 -374.657874)
		(mid 298.043445 -375.751668)
		(end 297.786806 -377.041918)
		(width 0.14224)
		(layer "In6.Cu")
		(net "P5E_CPU0_P0_TX_DN<1>")
	)
	(arc
		(start 346.243148 -290.631372)
		(mid 346.486475 -291.095938)
		(end 346.243148 -291.560504)
		(width 0.1143)
		(layer "In6.Cu")
		(net "P5E_CPU0_P0_TX_DN<1>")
	)
	(arc
		(start 345.59367 -295.843198)
		(mid 345.558761 -295.895537)
		(end 345.546426 -295.957244)
		(width 0.1143)
		(layer "In6.Cu")
		(net "P5E_CPU0_P0_TX_DN<1>")
	)
	(arc
		(start 298.632118 -384.79984)
		(mid 298.499398 -384.888584)
		(end 298.342812 -384.919728)
		(width 0.14224)
		(layer "In6.Cu")
		(net "P5E_CPU0_P0_TX_DN<1>")
	)
	(arc
		(start 346.17152 -288.36239)
		(mid 346.057591 -288.495537)
		(end 346.01658 -288.66592)
		(width 0.1143)
		(layer "In6.Cu")
		(net "P5E_CPU0_P0_TX_DN<1>")
	)
	(arc
		(start 297.786806 -381.135382)
		(mid 297.827733 -381.341046)
		(end 297.944286 -381.515366)
		(width 0.14224)
		(layer "In6.Cu")
		(net "P5E_CPU0_P0_TX_DN<1>")
	)
	(arc
		(start 346.173552 -293.221156)
		(mid 346.016575 -293.525956)
		(end 346.173552 -293.830756)
		(width 0.1143)
		(layer "In6.Cu")
		(net "P5E_CPU0_P0_TX_DN<1>")
	)
	(arc
		(start 304.677318 -370.565426)
		(mid 303.004659 -370.898121)
		(end 301.586646 -371.845586)
		(width 0.14224)
		(layer "In6.Cu")
		(net "P5E_CPU0_P0_TX_DN<1>")
	)
	(arc
		(start 345.99245 -295.360598)
		(mid 345.949309 -295.466409)
		(end 345.879928 -295.557194)
		(width 0.1143)
		(layer "In6.Cu")
		(net "P5E_CPU0_P0_TX_DN<1>")
	)
	(arc
		(start 346.243148 -292.251384)
		(mid 346.486475 -292.71595)
		(end 346.243148 -293.180516)
		(width 0.1143)
		(layer "In6.Cu")
		(net "P5E_CPU0_P0_TX_DN<1>")
	)
	(arc
		(start 346.01658 -287.045908)
		(mid 346.058129 -287.21733)
		(end 346.173552 -287.350708)
		(width 0.1143)
		(layer "In6.Cu")
		(net "P5E_CPU0_P0_TX_DN<1>")
	)
	(arc
		(start 345.546426 -286.236156)
		(mid 345.587188 -286.40604)
		(end 345.700604 -286.538924)
		(width 0.1143)
		(layer "In6.Cu")
		(net "P5E_CPU0_P0_TX_DN<1>")
	)
	(arc
		(start 366.229646 -349.276416)
		(mid 364.848793 -356.218345)
		(end 360.916474 -362.103416)
		(width 0.14224)
		(layer "In6.Cu")
		(net "P5E_CPU0_P0_TX_DN<1>")
	)
	(arc
		(start 321.838828 -365.973106)
		(mid 320.045563 -366.149661)
		(end 318.321182 -366.672622)
		(width 0.14224)
		(layer "In6.Cu")
		(net "P5E_CPU0_P0_TX_DN<1>")
	)
	(arc
		(start 346.173552 -291.601144)
		(mid 346.016575 -291.905944)
		(end 346.173552 -292.210744)
		(width 0.1143)
		(layer "In6.Cu")
		(net "P5E_CPU0_P0_TX_DN<1>")
	)
	(arc
		(start 346.480384 -284.698948)
		(mid 346.401305 -284.914393)
		(end 346.243148 -285.08071)
		(width 0.1143)
		(layer "In6.Cu")
		(net "P5E_CPU0_P0_TX_DN<1>")
	)
	(arc
		(start 346.243148 -293.871396)
		(mid 346.486475 -294.335962)
		(end 346.243148 -294.800528)
		(width 0.1143)
		(layer "In6.Cu")
		(net "P5E_CPU0_P0_TX_DN<1>")
	)
	(arc
		(start 346.016326 -295.175178)
		(mid 346.010316 -295.268651)
		(end 345.99245 -295.360598)
		(width 0.1143)
		(layer "In6.Cu")
		(net "P5E_CPU0_P0_TX_DN<1>")
	)
	(arc
		(start 298.851574 -384.410966)
		(mid 298.820411 -384.567544)
		(end 298.731686 -384.700272)
		(width 0.14224)
		(layer "In6.Cu")
		(net "P5E_CPU0_P0_TX_DN<1>")
	)
	(arc
		(start 346.172028 -294.842184)
		(mid 346.057559 -294.975311)
		(end 346.016326 -295.145968)
		(width 0.1143)
		(layer "In6.Cu")
		(net "P5E_CPU0_P0_TX_DN<1>")
	)
	(arc
		(start 346.173552 -285.12135)
		(mid 346.058125 -285.254726)
		(end 346.01658 -285.42615)
		(width 0.1143)
		(layer "In6.Cu")
		(net "P5E_CPU0_P0_TX_DN<1>")
	)
	(arc
		(start 346.243148 -289.01136)
		(mid 346.486475 -289.475926)
		(end 346.243148 -289.940492)
		(width 0.1143)
		(layer "In6.Cu")
		(net "P5E_CPU0_P0_TX_DN<1>")
	)
	(arc
		(start 345.773248 -286.581342)
		(mid 345.952061 -286.783692)
		(end 346.01658 -287.045908)
		(width 0.1143)
		(layer "In6.Cu")
		(net "P5E_CPU0_P0_TX_DN<1>")
	)
	(arc
		(start 357.588566 -365.431324)
		(mid 356.98839 -365.832285)
		(end 356.280466 -365.973106)
		(width 0.14224)
		(layer "In6.Cu")
		(net "P5E_CPU0_P0_TX_DN<1>")
	)
	(arc
		(start 346.01658 -288.66592)
		(mid 346.058129 -288.837342)
		(end 346.173552 -288.97072)
		(width 0.1143)
		(layer "In6.Cu")
		(net "P5E_CPU0_P0_TX_DN<1>")
	)
	(arc
		(start 346.48648 -287.856168)
		(mid 346.421965 -288.118387)
		(end 346.243148 -288.320734)
		(width 0.1143)
		(layer "In6.Cu")
		(net "P5E_CPU0_P0_TX_DN<1>")
	)
	(arc
		(start 346.01658 -285.42615)
		(mid 345.952065 -285.688369)
		(end 345.773248 -285.890716)
		(width 0.1143)
		(layer "In6.Cu")
		(net "P5E_CPU0_P0_TX_DN<1>")
	)
	(arc
		(start 310.053228 -370.09705)
		(mid 308.898745 -370.447193)
		(end 307.69814 -370.565426)
		(width 0.14224)
		(layer "In6.Cu")
		(net "P5E_CPU0_P0_TX_DN<1>")
	)
	(arc
		(start 346.173552 -289.981132)
		(mid 346.016575 -290.285932)
		(end 346.173552 -290.590732)
		(width 0.1143)
		(layer "In6.Cu")
		(net "P5E_CPU0_P0_TX_DN<1>")
	)
	(arc
		(start 298.731686 -382.302766)
		(mid 298.82043 -382.435486)
		(end 298.851574 -382.592072)
		(width 0.14224)
		(layer "In6.Cu")
		(net "P5E_CPU0_P0_TX_DN<1>")
	)
	(arc
		(start 346.240608 -287.389824)
		(mid 346.42126 -287.592569)
		(end 346.48648 -287.856168)
		(width 0.1143)
		(layer "In6.Cu")
		(net "P5E_CPU0_P0_TX_DN<1>")
	)
	(segment
		(start 327.006966 -388.471918)
		(end 327.277476 -388.742428)
		(width 0.12954)
		(layer "F.Cu")
		(net "P5E_CPU0_P0_TX_DN<15>")
	)
	(segment
		(start 358.137968 -281.920188)
		(end 357.671116 -282.186126)
		(width 0.12954)
		(layer "F.Cu")
		(net "P5E_CPU0_P0_TX_DN<15>")
	)
	(segment
		(start 326.007476 -388.767828)
		(end 326.303386 -388.471918)
		(width 0.12954)
		(layer "F.Cu")
		(net "P5E_CPU0_P0_TX_DN<15>")
	)
	(segment
		(start 326.303386 -388.471918)
		(end 327.006966 -388.471918)
		(width 0.12954)
		(layer "F.Cu")
		(net "P5E_CPU0_P0_TX_DN<15>")
	)
	(segment
		(start 359.085896 -284.698948)
		(end 359.253282 -284.866334)
		(width 0.14224)
		(layer "In6.Cu")
		(net "P5E_CPU0_P0_TX_DN<15>")
	)
	(segment
		(start 357.931466 -283.305504)
		(end 357.993188 -283.341572)
		(width 0.1143)
		(layer "In6.Cu")
		(net "P5E_CPU0_P0_TX_DN<15>")
	)
	(segment
		(start 379.304042 -353.224084)
		(end 379.25629 -353.780598)
		(width 0.14224)
		(layer "In6.Cu")
		(net "P5E_CPU0_P0_TX_DN<15>")
	)
	(segment
		(start 358.393492 -284.110938)
		(end 358.423972 -284.128718)
		(width 0.1143)
		(layer "In6.Cu")
		(net "P5E_CPU0_P0_TX_DN<15>")
	)
	(segment
		(start 377.75515 -360.279442)
		(end 377.558046 -360.802174)
		(width 0.14224)
		(layer "In6.Cu")
		(net "P5E_CPU0_P0_TX_DN<15>")
	)
	(segment
		(start 361.286552 -303.22647)
		(end 366.455706 -310.962548)
		(width 0.14224)
		(layer "In6.Cu")
		(net "P5E_CPU0_P0_TX_DN<15>")
	)
	(segment
		(start 378.066808 -359.399586)
		(end 377.75515 -360.279442)
		(width 0.14224)
		(layer "In6.Cu")
		(net "P5E_CPU0_P0_TX_DN<15>")
	)
	(segment
		(start 357.373174 -282.186126)
		(end 357.303324 -282.255976)
		(width 0.1143)
		(layer "In6.Cu")
		(net "P5E_CPU0_P0_TX_DN<15>")
	)
	(segment
		(start 331.125068 -387.628638)
		(end 331.06868 -387.411468)
		(width 0.14224)
		(layer "In6.Cu")
		(net "P5E_CPU0_P0_TX_DN<15>")
	)
	(segment
		(start 379.377702 -351.42297)
		(end 379.363224 -352.106992)
		(width 0.14224)
		(layer "In6.Cu")
		(net "P5E_CPU0_P0_TX_DN<15>")
	)
	(segment
		(start 376.899932 -362.345224)
		(end 376.658886 -362.849668)
		(width 0.14224)
		(layer "In6.Cu")
		(net "P5E_CPU0_P0_TX_DN<15>")
	)
	(segment
		(start 372.74754 -368.7826)
		(end 372.298722 -369.231672)
		(width 0.14224)
		(layer "In6.Cu")
		(net "P5E_CPU0_P0_TX_DN<15>")
	)
	(segment
		(start 331.335634 -388.034784)
		(end 331.125068 -387.628638)
		(width 0.14224)
		(layer "In6.Cu")
		(net "P5E_CPU0_P0_TX_DN<15>")
	)
	(segment
		(start 359.000806 -284.678882)
		(end 359.06583 -284.678882)
		(width 0.1143)
		(layer "In6.Cu")
		(net "P5E_CPU0_P0_TX_DN<15>")
	)
	(segment
		(start 377.380246 -327.877678)
		(end 379.377702 -338.998306)
		(width 0.14224)
		(layer "In6.Cu")
		(net "P5E_CPU0_P0_TX_DN<15>")
	)
	(segment
		(start 359.67543 -299.336714)
		(end 361.286552 -303.22647)
		(width 0.14224)
		(layer "In6.Cu")
		(net "P5E_CPU0_P0_TX_DN<15>")
	)
	(segment
		(start 372.298722 -369.231672)
		(end 367.66627 -373.864124)
		(width 0.14224)
		(layer "In6.Cu")
		(net "P5E_CPU0_P0_TX_DN<15>")
	)
	(segment
		(start 359.872788 -390.27608)
		(end 359.489248 -390.27608)
		(width 0.14224)
		(layer "In6.Cu")
		(net "P5E_CPU0_P0_TX_DN<15>")
	)
	(segment
		(start 378.455174 -358.17556)
		(end 378.35078 -358.543606)
		(width 0.14224)
		(layer "In6.Cu")
		(net "P5E_CPU0_P0_TX_DN<15>")
	)
	(segment
		(start 379.126242 -354.891086)
		(end 379.043692 -355.44379)
		(width 0.14224)
		(layer "In6.Cu")
		(net "P5E_CPU0_P0_TX_DN<15>")
	)
	(segment
		(start 365.692944 -376.953272)
		(end 365.065056 -378.66574)
		(width 0.14224)
		(layer "In6.Cu")
		(net "P5E_CPU0_P0_TX_DN<15>")
	)
	(segment
		(start 357.484172 -282.508706)
		(end 357.522272 -282.530804)
		(width 0.1143)
		(layer "In6.Cu")
		(net "P5E_CPU0_P0_TX_DN<15>")
	)
	(segment
		(start 357.480616 -282.506674)
		(end 357.48214 -282.507436)
		(width 0.1143)
		(layer "In6.Cu")
		(net "P5E_CPU0_P0_TX_DN<15>")
	)
	(segment
		(start 358.414574 -389.120126)
		(end 357.747316 -388.452868)
		(width 0.14224)
		(layer "In6.Cu")
		(net "P5E_CPU0_P0_TX_DN<15>")
	)
	(segment
		(start 358.709976 -389.953246)
		(end 358.696768 -389.940038)
		(width 0.14224)
		(layer "In6.Cu")
		(net "P5E_CPU0_P0_TX_DN<15>")
	)
	(segment
		(start 377.558046 -360.802174)
		(end 377.349512 -361.320588)
		(width 0.14224)
		(layer "In6.Cu")
		(net "P5E_CPU0_P0_TX_DN<15>")
	)
	(segment
		(start 377.130564 -361.8357)
		(end 376.899932 -362.345224)
		(width 0.14224)
		(layer "In6.Cu")
		(net "P5E_CPU0_P0_TX_DN<15>")
	)
	(segment
		(start 361.543854 -389.22706)
		(end 360.981244 -389.737092)
		(width 0.14224)
		(layer "In6.Cu")
		(net "P5E_CPU0_P0_TX_DN<15>")
	)
	(segment
		(start 358.461818 -389.372856)
		(end 358.461818 -389.234172)
		(width 0.14224)
		(layer "In6.Cu")
		(net "P5E_CPU0_P0_TX_DN<15>")
	)
	(segment
		(start 365.064548 -378.665994)
		(end 364.892082 -379.13564)
		(width 0.14224)
		(layer "In6.Cu")
		(net "P5E_CPU0_P0_TX_DN<15>")
	)
	(segment
		(start 357.671116 -282.186126)
		(end 357.373174 -282.186126)
		(width 0.1143)
		(layer "In6.Cu")
		(net "P5E_CPU0_P0_TX_DN<15>")
	)
	(segment
		(start 379.339602 -352.665792)
		(end 379.304042 -353.224084)
		(width 0.14224)
		(layer "In6.Cu")
		(net "P5E_CPU0_P0_TX_DN<15>")
	)
	(segment
		(start 374.993154 -365.758222)
		(end 374.680226 -366.221518)
		(width 0.14224)
		(layer "In6.Cu")
		(net "P5E_CPU0_P0_TX_DN<15>")
	)
	(segment
		(start 375.296684 -365.288576)
		(end 374.993154 -365.758222)
		(width 0.14224)
		(layer "In6.Cu")
		(net "P5E_CPU0_P0_TX_DN<15>")
	)
	(segment
		(start 375.589546 -364.812072)
		(end 375.296684 -365.288576)
		(width 0.14224)
		(layer "In6.Cu")
		(net "P5E_CPU0_P0_TX_DN<15>")
	)
	(segment
		(start 357.48341 -282.508198)
		(end 357.484172 -282.508706)
		(width 0.1143)
		(layer "In6.Cu")
		(net "P5E_CPU0_P0_TX_DN<15>")
	)
	(segment
		(start 378.843032 -356.54361)
		(end 378.72543 -357.089964)
		(width 0.14224)
		(layer "In6.Cu")
		(net "P5E_CPU0_P0_TX_DN<15>")
	)
	(segment
		(start 378.35078 -358.543606)
		(end 378.066808 -359.399586)
		(width 0.14224)
		(layer "In6.Cu")
		(net "P5E_CPU0_P0_TX_DN<15>")
	)
	(segment
		(start 376.145044 -363.841792)
		(end 375.872502 -364.330234)
		(width 0.14224)
		(layer "In6.Cu")
		(net "P5E_CPU0_P0_TX_DN<15>")
	)
	(segment
		(start 359.06583 -284.678882)
		(end 359.085896 -284.698948)
		(width 0.1143)
		(layer "In6.Cu")
		(net "P5E_CPU0_P0_TX_DN<15>")
	)
	(segment
		(start 365.065056 -378.66574)
		(end 365.064548 -378.665994)
		(width 0.14224)
		(layer "In6.Cu")
		(net "P5E_CPU0_P0_TX_DN<15>")
	)
	(segment
		(start 360.862372 -389.834628)
		(end 360.792268 -389.886698)
		(width 0.14224)
		(layer "In6.Cu")
		(net "P5E_CPU0_P0_TX_DN<15>")
	)
	(segment
		(start 379.363224 -352.106992)
		(end 379.339602 -352.665792)
		(width 0.14224)
		(layer "In6.Cu")
		(net "P5E_CPU0_P0_TX_DN<15>")
	)
	(segment
		(start 362.481368 -385.698238)
		(end 361.84332 -388.647686)
		(width 0.14224)
		(layer "In6.Cu")
		(net "P5E_CPU0_P0_TX_DN<15>")
	)
	(segment
		(start 379.043692 -355.44379)
		(end 378.949204 -355.994716)
		(width 0.14224)
		(layer "In6.Cu")
		(net "P5E_CPU0_P0_TX_DN<15>")
	)
	(segment
		(start 360.68635 -389.955532)
		(end 360.529124 -390.044178)
		(width 0.14224)
		(layer "In6.Cu")
		(net "P5E_CPU0_P0_TX_DN<15>")
	)
	(segment
		(start 375.872502 -364.330234)
		(end 375.589546 -364.812072)
		(width 0.14224)
		(layer "In6.Cu")
		(net "P5E_CPU0_P0_TX_DN<15>")
	)
	(segment
		(start 330.280772 -386.639054)
		(end 329.384914 -386.639054)
		(width 0.14224)
		(layer "In6.Cu")
		(net "P5E_CPU0_P0_TX_DN<15>")
	)
	(segment
		(start 359.436416 -296.912284)
		(end 359.67543 -299.336714)
		(width 0.14224)
		(layer "In6.Cu")
		(net "P5E_CPU0_P0_TX_DN<15>")
	)
	(segment
		(start 374.357392 -366.677448)
		(end 374.02516 -367.12652)
		(width 0.14224)
		(layer "In6.Cu")
		(net "P5E_CPU0_P0_TX_DN<15>")
	)
	(segment
		(start 379.197362 -354.33635)
		(end 379.126242 -354.891086)
		(width 0.14224)
		(layer "In6.Cu")
		(net "P5E_CPU0_P0_TX_DN<15>")
	)
	(segment
		(start 357.641906 -388.384034)
		(end 357.38943 -388.285736)
		(width 0.14224)
		(layer "In6.Cu")
		(net "P5E_CPU0_P0_TX_DN<15>")
	)
	(segment
		(start 360.39933 -390.108186)
		(end 360.103928 -390.23036)
		(width 0.14224)
		(layer "In6.Cu")
		(net "P5E_CPU0_P0_TX_DN<15>")
	)
	(segment
		(start 357.479854 -282.506166)
		(end 357.480616 -282.506674)
		(width 0.1143)
		(layer "In6.Cu")
		(net "P5E_CPU0_P0_TX_DN<15>")
	)
	(segment
		(start 357.265732 -388.262622)
		(end 334.60944 -388.262622)
		(width 0.14224)
		(layer "In6.Cu")
		(net "P5E_CPU0_P0_TX_DN<15>")
	)
	(segment
		(start 364.892082 -379.13564)
		(end 364.891828 -379.136402)
		(width 0.14224)
		(layer "In6.Cu")
		(net "P5E_CPU0_P0_TX_DN<15>")
	)
	(segment
		(start 374.02516 -367.12652)
		(end 372.74754 -368.7826)
		(width 0.14224)
		(layer "In6.Cu")
		(net "P5E_CPU0_P0_TX_DN<15>")
	)
	(segment
		(start 377.349512 -361.320588)
		(end 377.130564 -361.8357)
		(width 0.14224)
		(layer "In6.Cu")
		(net "P5E_CPU0_P0_TX_DN<15>")
	)
	(segment
		(start 329.01509 -386.792216)
		(end 328.990452 -386.816854)
		(width 0.14224)
		(layer "In6.Cu")
		(net "P5E_CPU0_P0_TX_DN<15>")
	)
	(segment
		(start 374.680226 -366.221518)
		(end 374.357392 -366.677448)
		(width 0.14224)
		(layer "In6.Cu")
		(net "P5E_CPU0_P0_TX_DN<15>")
	)
	(segment
		(start 364.891828 -379.136402)
		(end 362.481368 -385.698238)
		(width 0.14224)
		(layer "In6.Cu")
		(net "P5E_CPU0_P0_TX_DN<15>")
	)
	(segment
		(start 376.658886 -362.849668)
		(end 376.406918 -363.34827)
		(width 0.14224)
		(layer "In6.Cu")
		(net "P5E_CPU0_P0_TX_DN<15>")
	)
	(segment
		(start 358.539542 -284.217618)
		(end 359.000806 -284.678882)
		(width 0.1143)
		(layer "In6.Cu")
		(net "P5E_CPU0_P0_TX_DN<15>")
	)
	(segment
		(start 327.556876 -388.463028)
		(end 327.277476 -388.742428)
		(width 0.14224)
		(layer "In6.Cu")
		(net "P5E_CPU0_P0_TX_DN<15>")
	)
	(segment
		(start 379.25629 -353.780598)
		(end 379.197362 -354.33635)
		(width 0.14224)
		(layer "In6.Cu")
		(net "P5E_CPU0_P0_TX_DN<15>")
	)
	(segment
		(start 328.062336 -388.463028)
		(end 327.556876 -388.463028)
		(width 0.14224)
		(layer "In6.Cu")
		(net "P5E_CPU0_P0_TX_DN<15>")
	)
	(segment
		(start 378.949204 -355.994716)
		(end 378.843032 -356.54361)
		(width 0.14224)
		(layer "In6.Cu")
		(net "P5E_CPU0_P0_TX_DN<15>")
	)
	(segment
		(start 366.455706 -310.962548)
		(end 372.726458 -318.602868)
		(width 0.14224)
		(layer "In6.Cu")
		(net "P5E_CPU0_P0_TX_DN<15>")
	)
	(segment
		(start 378.596144 -357.63454)
		(end 378.455174 -358.17556)
		(width 0.14224)
		(layer "In6.Cu")
		(net "P5E_CPU0_P0_TX_DN<15>")
	)
	(segment
		(start 377.013724 -326.806052)
		(end 377.380246 -327.877678)
		(width 0.14224)
		(layer "In6.Cu")
		(net "P5E_CPU0_P0_TX_DN<15>")
	)
	(segment
		(start 332.72222 -388.474458)
		(end 332.206854 -388.474458)
		(width 0.14224)
		(layer "In6.Cu")
		(net "P5E_CPU0_P0_TX_DN<15>")
	)
	(segment
		(start 372.726458 -318.602868)
		(end 377.013724 -326.806052)
		(width 0.14224)
		(layer "In6.Cu")
		(net "P5E_CPU0_P0_TX_DN<15>")
	)
	(segment
		(start 328.801222 -387.273546)
		(end 328.801222 -387.75386)
		(width 0.14224)
		(layer "In6.Cu")
		(net "P5E_CPU0_P0_TX_DN<15>")
	)
	(segment
		(start 331.469746 -388.16915)
		(end 331.335634 -388.034784)
		(width 0.14224)
		(layer "In6.Cu")
		(net "P5E_CPU0_P0_TX_DN<15>")
	)
	(segment
		(start 376.406918 -363.34827)
		(end 376.145044 -363.841792)
		(width 0.14224)
		(layer "In6.Cu")
		(net "P5E_CPU0_P0_TX_DN<15>")
	)
	(segment
		(start 357.48214 -282.507436)
		(end 357.48341 -282.508198)
		(width 0.1143)
		(layer "In6.Cu")
		(net "P5E_CPU0_P0_TX_DN<15>")
	)
	(segment
		(start 357.452422 -282.490418)
		(end 357.479854 -282.506166)
		(width 0.1143)
		(layer "In6.Cu")
		(net "P5E_CPU0_P0_TX_DN<15>")
	)
	(segment
		(start 330.999846 -387.291326)
		(end 330.394818 -386.686298)
		(width 0.14224)
		(layer "In6.Cu")
		(net "P5E_CPU0_P0_TX_DN<15>")
	)
	(segment
		(start 359.436416 -285.308548)
		(end 359.436416 -296.912284)
		(width 0.14224)
		(layer "In6.Cu")
		(net "P5E_CPU0_P0_TX_DN<15>")
	)
	(segment
		(start 378.72543 -357.089964)
		(end 378.596144 -357.63454)
		(width 0.14224)
		(layer "In6.Cu")
		(net "P5E_CPU0_P0_TX_DN<15>")
	)
	(segment
		(start 379.377702 -338.998306)
		(end 379.377702 -351.42297)
		(width 0.14224)
		(layer "In6.Cu")
		(net "P5E_CPU0_P0_TX_DN<15>")
	)
	(arc
		(start 360.981244 -389.737092)
		(mid 360.922991 -389.787301)
		(end 360.862372 -389.834628)
		(width 0.14224)
		(layer "In6.Cu")
		(net "P5E_CPU0_P0_TX_DN<15>")
	)
	(arc
		(start 328.484992 -388.348728)
		(mid 328.281268 -388.434003)
		(end 328.062336 -388.463028)
		(width 0.14224)
		(layer "In6.Cu")
		(net "P5E_CPU0_P0_TX_DN<15>")
	)
	(arc
		(start 328.801222 -387.75386)
		(mid 328.792234 -387.863823)
		(end 328.765154 -387.970776)
		(width 0.14224)
		(layer "In6.Cu")
		(net "P5E_CPU0_P0_TX_DN<15>")
	)
	(arc
		(start 359.489248 -390.27608)
		(mid 359.067505 -390.192172)
		(end 358.709976 -389.953246)
		(width 0.14224)
		(layer "In6.Cu")
		(net "P5E_CPU0_P0_TX_DN<15>")
	)
	(arc
		(start 358.23652 -283.806138)
		(mid 358.278069 -283.97756)
		(end 358.393492 -284.110938)
		(width 0.1143)
		(layer "In6.Cu")
		(net "P5E_CPU0_P0_TX_DN<15>")
	)
	(arc
		(start 357.993188 -283.341572)
		(mid 358.172001 -283.543922)
		(end 358.23652 -283.806138)
		(width 0.1143)
		(layer "In6.Cu")
		(net "P5E_CPU0_P0_TX_DN<15>")
	)
	(arc
		(start 367.66627 -373.864124)
		(mid 366.511428 -375.301265)
		(end 365.692944 -376.953272)
		(width 0.14224)
		(layer "In6.Cu")
		(net "P5E_CPU0_P0_TX_DN<15>")
	)
	(arc
		(start 328.670158 -388.168896)
		(mid 328.58833 -388.269884)
		(end 328.484992 -388.348728)
		(width 0.14224)
		(layer "In6.Cu")
		(net "P5E_CPU0_P0_TX_DN<15>")
	)
	(arc
		(start 329.384914 -386.639054)
		(mid 329.184776 -386.678864)
		(end 329.01509 -386.792216)
		(width 0.14224)
		(layer "In6.Cu")
		(net "P5E_CPU0_P0_TX_DN<15>")
	)
	(arc
		(start 330.394818 -386.686298)
		(mid 330.342493 -386.651336)
		(end 330.280772 -386.639054)
		(width 0.14224)
		(layer "In6.Cu")
		(net "P5E_CPU0_P0_TX_DN<15>")
	)
	(arc
		(start 328.990452 -386.816854)
		(mid 328.850393 -387.026372)
		(end 328.801222 -387.273546)
		(width 0.14224)
		(layer "In6.Cu")
		(net "P5E_CPU0_P0_TX_DN<15>")
	)
	(arc
		(start 358.423972 -284.128718)
		(mid 358.484645 -284.169414)
		(end 358.539542 -284.217618)
		(width 0.1143)
		(layer "In6.Cu")
		(net "P5E_CPU0_P0_TX_DN<15>")
	)
	(arc
		(start 361.84332 -388.647686)
		(mid 361.777436 -388.864348)
		(end 361.676442 -389.06704)
		(width 0.14224)
		(layer "In6.Cu")
		(net "P5E_CPU0_P0_TX_DN<15>")
	)
	(arc
		(start 358.461818 -389.234172)
		(mid 358.449525 -389.172463)
		(end 358.414574 -389.120126)
		(width 0.14224)
		(layer "In6.Cu")
		(net "P5E_CPU0_P0_TX_DN<15>")
	)
	(arc
		(start 361.676442 -389.06704)
		(mid 361.61595 -389.151859)
		(end 361.543854 -389.22706)
		(width 0.14224)
		(layer "In6.Cu")
		(net "P5E_CPU0_P0_TX_DN<15>")
	)
	(arc
		(start 359.253282 -284.866334)
		(mid 359.388848 -285.069224)
		(end 359.436416 -285.308548)
		(width 0.14224)
		(layer "In6.Cu")
		(net "P5E_CPU0_P0_TX_DN<15>")
	)
	(arc
		(start 357.522272 -282.530804)
		(mid 357.697208 -282.724478)
		(end 357.76662 -282.976066)
		(width 0.1143)
		(layer "In6.Cu")
		(net "P5E_CPU0_P0_TX_DN<15>")
	)
	(arc
		(start 334.60944 -388.262622)
		(mid 334.166233 -388.28751)
		(end 333.728568 -388.361682)
		(width 0.14224)
		(layer "In6.Cu")
		(net "P5E_CPU0_P0_TX_DN<15>")
	)
	(arc
		(start 360.792268 -389.886698)
		(mid 360.74039 -389.922778)
		(end 360.68635 -389.955532)
		(width 0.14224)
		(layer "In6.Cu")
		(net "P5E_CPU0_P0_TX_DN<15>")
	)
	(arc
		(start 333.728568 -388.361682)
		(mid 333.228551 -388.44625)
		(end 332.72222 -388.474458)
		(width 0.14224)
		(layer "In6.Cu")
		(net "P5E_CPU0_P0_TX_DN<15>")
	)
	(arc
		(start 360.103928 -390.23036)
		(mid 359.990603 -390.264563)
		(end 359.872788 -390.27608)
		(width 0.14224)
		(layer "In6.Cu")
		(net "P5E_CPU0_P0_TX_DN<15>")
	)
	(arc
		(start 328.765154 -387.970776)
		(mid 328.723356 -388.072568)
		(end 328.670158 -388.168896)
		(width 0.14224)
		(layer "In6.Cu")
		(net "P5E_CPU0_P0_TX_DN<15>")
	)
	(arc
		(start 331.06868 -387.411468)
		(mid 331.04227 -387.346812)
		(end 330.999846 -387.291326)
		(width 0.14224)
		(layer "In6.Cu")
		(net "P5E_CPU0_P0_TX_DN<15>")
	)
	(arc
		(start 358.696768 -389.940038)
		(mid 358.522891 -389.679813)
		(end 358.461818 -389.372856)
		(width 0.14224)
		(layer "In6.Cu")
		(net "P5E_CPU0_P0_TX_DN<15>")
	)
	(arc
		(start 360.529124 -390.044178)
		(mid 360.465097 -390.077946)
		(end 360.39933 -390.108186)
		(width 0.14224)
		(layer "In6.Cu")
		(net "P5E_CPU0_P0_TX_DN<15>")
	)
	(arc
		(start 357.303324 -282.255976)
		(mid 357.355373 -282.387495)
		(end 357.452422 -282.490418)
		(width 0.1143)
		(layer "In6.Cu")
		(net "P5E_CPU0_P0_TX_DN<15>")
	)
	(arc
		(start 332.206854 -388.474458)
		(mid 331.807939 -388.395109)
		(end 331.469746 -388.16915)
		(width 0.14224)
		(layer "In6.Cu")
		(net "P5E_CPU0_P0_TX_DN<15>")
	)
	(arc
		(start 357.768652 -283.005784)
		(mid 357.823335 -283.170161)
		(end 357.931466 -283.305504)
		(width 0.1143)
		(layer "In6.Cu")
		(net "P5E_CPU0_P0_TX_DN<15>")
	)
	(arc
		(start 357.76662 -282.976066)
		(mid 357.767193 -282.990955)
		(end 357.768652 -283.005784)
		(width 0.1143)
		(layer "In6.Cu")
		(net "P5E_CPU0_P0_TX_DN<15>")
	)
	(arc
		(start 357.747316 -388.452868)
		(mid 357.698194 -388.412964)
		(end 357.641906 -388.384034)
		(width 0.14224)
		(layer "In6.Cu")
		(net "P5E_CPU0_P0_TX_DN<15>")
	)
	(arc
		(start 357.38943 -388.285736)
		(mid 357.328655 -388.268436)
		(end 357.265732 -388.262622)
		(width 0.14224)
		(layer "In6.Cu")
		(net "P5E_CPU0_P0_TX_DN<15>")
	)
	(segment
		(start 326.303386 -385.068318)
		(end 327.006966 -385.068318)
		(width 0.12954)
		(layer "F.Cu")
		(net "P5E_CPU0_P0_TX_DN<14>")
	)
	(segment
		(start 358.137968 -283.5402)
		(end 357.671116 -283.806138)
		(width 0.12954)
		(layer "F.Cu")
		(net "P5E_CPU0_P0_TX_DN<14>")
	)
	(segment
		(start 326.007476 -385.364228)
		(end 326.303386 -385.068318)
		(width 0.12954)
		(layer "F.Cu")
		(net "P5E_CPU0_P0_TX_DN<14>")
	)
	(segment
		(start 327.006966 -385.068318)
		(end 327.277476 -385.338828)
		(width 0.12954)
		(layer "F.Cu")
		(net "P5E_CPU0_P0_TX_DN<14>")
	)
	(segment
		(start 364.040674 -378.210826)
		(end 364.000288 -378.320808)
		(width 0.14224)
		(layer "In6.Cu")
		(net "P5E_CPU0_P0_TX_DN<14>")
	)
	(segment
		(start 373.601742 -366.13084)
		(end 373.281194 -366.564672)
		(width 0.14224)
		(layer "In6.Cu")
		(net "P5E_CPU0_P0_TX_DN<14>")
	)
	(segment
		(start 378.248926 -354.20173)
		(end 378.180346 -354.736654)
		(width 0.14224)
		(layer "In6.Cu")
		(net "P5E_CPU0_P0_TX_DN<14>")
	)
	(segment
		(start 358.50195 -294.773604)
		(end 358.423972 -294.823388)
		(width 0.1143)
		(layer "In6.Cu")
		(net "P5E_CPU0_P0_TX_DN<14>")
	)
	(segment
		(start 358.393492 -287.350708)
		(end 358.395524 -287.351978)
		(width 0.1143)
		(layer "In6.Cu")
		(net "P5E_CPU0_P0_TX_DN<14>")
	)
	(segment
		(start 328.78141 -384.186684)
		(end 328.78141 -384.594354)
		(width 0.14224)
		(layer "In6.Cu")
		(net "P5E_CPU0_P0_TX_DN<14>")
	)
	(segment
		(start 378.408946 -352.051366)
		(end 378.386086 -352.5901)
		(width 0.14224)
		(layer "In6.Cu")
		(net "P5E_CPU0_P0_TX_DN<14>")
	)
	(segment
		(start 378.432822 -339.11413)
		(end 378.432822 -351.561146)
		(width 0.14224)
		(layer "In6.Cu")
		(net "P5E_CPU0_P0_TX_DN<14>")
	)
	(segment
		(start 364.000288 -378.320808)
		(end 363.99978 -378.321062)
		(width 0.14224)
		(layer "In6.Cu")
		(net "P5E_CPU0_P0_TX_DN<14>")
	)
	(segment
		(start 360.460544 -303.669192)
		(end 365.705136 -311.517792)
		(width 0.14224)
		(layer "In6.Cu")
		(net "P5E_CPU0_P0_TX_DN<14>")
	)
	(segment
		(start 357.452168 -284.110176)
		(end 357.491792 -284.13329)
		(width 0.1143)
		(layer "In6.Cu")
		(net "P5E_CPU0_P0_TX_DN<14>")
	)
	(segment
		(start 377.66879 -357.382826)
		(end 377.5329 -357.904542)
		(width 0.14224)
		(layer "In6.Cu")
		(net "P5E_CPU0_P0_TX_DN<14>")
	)
	(segment
		(start 378.417328 -351.649538)
		(end 378.417328 -351.649284)
		(width 0.14224)
		(layer "In6.Cu")
		(net "P5E_CPU0_P0_TX_DN<14>")
	)
	(segment
		(start 358.423972 -291.583364)
		(end 358.393492 -291.601144)
		(width 0.1143)
		(layer "In6.Cu")
		(net "P5E_CPU0_P0_TX_DN<14>")
	)
	(segment
		(start 375.063258 -363.866938)
		(end 374.790208 -364.331758)
		(width 0.14224)
		(layer "In6.Cu")
		(net "P5E_CPU0_P0_TX_DN<14>")
	)
	(segment
		(start 374.50776 -364.791244)
		(end 374.215152 -365.244126)
		(width 0.14224)
		(layer "In6.Cu")
		(net "P5E_CPU0_P0_TX_DN<14>")
	)
	(segment
		(start 358.423972 -294.823388)
		(end 358.393238 -294.841168)
		(width 0.1143)
		(layer "In6.Cu")
		(net "P5E_CPU0_P0_TX_DN<14>")
	)
	(segment
		(start 364.040928 -378.210064)
		(end 364.040674 -378.210826)
		(width 0.14224)
		(layer "In6.Cu")
		(net "P5E_CPU0_P0_TX_DN<14>")
	)
	(segment
		(start 378.009404 -355.801422)
		(end 377.907042 -356.330758)
		(width 0.14224)
		(layer "In6.Cu")
		(net "P5E_CPU0_P0_TX_DN<14>")
	)
	(segment
		(start 328.664824 -384.875786)
		(end 328.6125 -384.92811)
		(width 0.14224)
		(layer "In6.Cu")
		(net "P5E_CPU0_P0_TX_DN<14>")
	)
	(segment
		(start 358.511094 -288.28619)
		(end 358.464612 -288.319718)
		(width 0.1143)
		(layer "In6.Cu")
		(net "P5E_CPU0_P0_TX_DN<14>")
	)
	(segment
		(start 371.170708 -369.014502)
		(end 366.901476 -373.296688)
		(width 0.14224)
		(layer "In6.Cu")
		(net "P5E_CPU0_P0_TX_DN<14>")
	)
	(segment
		(start 358.395524 -287.351978)
		(end 358.461564 -287.390586)
		(width 0.1143)
		(layer "In6.Cu")
		(net "P5E_CPU0_P0_TX_DN<14>")
	)
	(segment
		(start 376.276616 -361.460542)
		(end 376.054366 -361.951778)
		(width 0.14224)
		(layer "In6.Cu")
		(net "P5E_CPU0_P0_TX_DN<14>")
	)
	(segment
		(start 378.305822 -353.665536)
		(end 378.248926 -354.20173)
		(width 0.14224)
		(layer "In6.Cu")
		(net "P5E_CPU0_P0_TX_DN<14>")
	)
	(segment
		(start 373.281194 -366.564672)
		(end 372.951502 -366.991392)
		(width 0.14224)
		(layer "In6.Cu")
		(net "P5E_CPU0_P0_TX_DN<14>")
	)
	(segment
		(start 358.423972 -292.228524)
		(end 358.460294 -292.249606)
		(width 0.1143)
		(layer "In6.Cu")
		(net "P5E_CPU0_P0_TX_DN<14>")
	)
	(segment
		(start 374.215152 -365.244126)
		(end 373.913146 -365.690912)
		(width 0.14224)
		(layer "In6.Cu")
		(net "P5E_CPU0_P0_TX_DN<14>")
	)
	(segment
		(start 376.689112 -360.463846)
		(end 376.487944 -360.964226)
		(width 0.14224)
		(layer "In6.Cu")
		(net "P5E_CPU0_P0_TX_DN<14>")
	)
	(segment
		(start 358.416098 -293.84371)
		(end 358.461564 -293.87038)
		(width 0.1143)
		(layer "In6.Cu")
		(net "P5E_CPU0_P0_TX_DN<14>")
	)
	(segment
		(start 376.150632 -327.168002)
		(end 376.436128 -328.00036)
		(width 0.14224)
		(layer "In6.Cu")
		(net "P5E_CPU0_P0_TX_DN<14>")
	)
	(segment
		(start 378.417582 -351.649284)
		(end 378.417328 -351.649538)
		(width 0.14224)
		(layer "In6.Cu")
		(net "P5E_CPU0_P0_TX_DN<14>")
	)
	(segment
		(start 358.706166 -287.856168)
		(end 358.706166 -287.90392)
		(width 0.1143)
		(layer "In6.Cu")
		(net "P5E_CPU0_P0_TX_DN<14>")
	)
	(segment
		(start 375.821956 -362.438442)
		(end 375.578878 -362.919518)
		(width 0.14224)
		(layer "In6.Cu")
		(net "P5E_CPU0_P0_TX_DN<14>")
	)
	(segment
		(start 358.394254 -290.59124)
		(end 358.423972 -290.608512)
		(width 0.1143)
		(layer "In6.Cu")
		(net "P5E_CPU0_P0_TX_DN<14>")
	)
	(segment
		(start 357.671116 -283.806138)
		(end 357.373174 -283.806138)
		(width 0.1143)
		(layer "In6.Cu")
		(net "P5E_CPU0_P0_TX_DN<14>")
	)
	(segment
		(start 358.393492 -292.210744)
		(end 358.423972 -292.228524)
		(width 0.1143)
		(layer "In6.Cu")
		(net "P5E_CPU0_P0_TX_DN<14>")
	)
	(segment
		(start 378.417328 -351.649284)
		(end 378.408946 -352.051366)
		(width 0.14224)
		(layer "In6.Cu")
		(net "P5E_CPU0_P0_TX_DN<14>")
	)
	(segment
		(start 358.395778 -285.73095)
		(end 358.42448 -285.747714)
		(width 0.1143)
		(layer "In6.Cu")
		(net "P5E_CPU0_P0_TX_DN<14>")
	)
	(segment
		(start 329.122786 -383.439162)
		(end 329.068684 -383.493264)
		(width 0.14224)
		(layer "In6.Cu")
		(net "P5E_CPU0_P0_TX_DN<14>")
	)
	(segment
		(start 330.079604 -383.129282)
		(end 329.870816 -383.129282)
		(width 0.14224)
		(layer "In6.Cu")
		(net "P5E_CPU0_P0_TX_DN<14>")
	)
	(segment
		(start 353.98837 -384.950716)
		(end 333.698596 -384.950716)
		(width 0.14224)
		(layer "In6.Cu")
		(net "P5E_CPU0_P0_TX_DN<14>")
	)
	(segment
		(start 375.578878 -362.919518)
		(end 375.326148 -363.396022)
		(width 0.14224)
		(layer "In6.Cu")
		(net "P5E_CPU0_P0_TX_DN<14>")
	)
	(segment
		(start 373.913146 -365.690912)
		(end 373.601742 -366.13084)
		(width 0.14224)
		(layer "In6.Cu")
		(net "P5E_CPU0_P0_TX_DN<14>")
	)
	(segment
		(start 363.99978 -378.321062)
		(end 363.496098 -379.692154)
		(width 0.14224)
		(layer "In6.Cu")
		(net "P5E_CPU0_P0_TX_DN<14>")
	)
	(segment
		(start 358.236266 -295.145968)
		(end 358.236266 -295.507156)
		(width 0.1143)
		(layer "In6.Cu")
		(net "P5E_CPU0_P0_TX_DN<14>")
	)
	(segment
		(start 328.78141 -384.594354)
		(end 328.664824 -384.875786)
		(width 0.14224)
		(layer "In6.Cu")
		(net "P5E_CPU0_P0_TX_DN<14>")
	)
	(segment
		(start 328.323194 -385.047998)
		(end 327.568306 -385.047998)
		(width 0.14224)
		(layer "In6.Cu")
		(net "P5E_CPU0_P0_TX_DN<14>")
	)
	(segment
		(start 377.793504 -356.857808)
		(end 377.66879 -357.382826)
		(width 0.14224)
		(layer "In6.Cu")
		(net "P5E_CPU0_P0_TX_DN<14>")
	)
	(segment
		(start 376.879358 -359.959402)
		(end 376.689112 -360.463846)
		(width 0.14224)
		(layer "In6.Cu")
		(net "P5E_CPU0_P0_TX_DN<14>")
	)
	(segment
		(start 376.487944 -360.964226)
		(end 376.276616 -361.460542)
		(width 0.14224)
		(layer "In6.Cu")
		(net "P5E_CPU0_P0_TX_DN<14>")
	)
	(segment
		(start 365.705136 -311.517792)
		(end 371.945154 -319.120774)
		(width 0.14224)
		(layer "In6.Cu")
		(net "P5E_CPU0_P0_TX_DN<14>")
	)
	(segment
		(start 358.460294 -291.562282)
		(end 358.423972 -291.583364)
		(width 0.1143)
		(layer "In6.Cu")
		(net "P5E_CPU0_P0_TX_DN<14>")
	)
	(segment
		(start 372.951502 -366.991392)
		(end 372.612666 -367.411)
		(width 0.14224)
		(layer "In6.Cu")
		(net "P5E_CPU0_P0_TX_DN<14>")
	)
	(segment
		(start 358.463088 -293.871396)
		(end 358.50195 -293.89832)
		(width 0.1143)
		(layer "In6.Cu")
		(net "P5E_CPU0_P0_TX_DN<14>")
	)
	(segment
		(start 371.945154 -319.120774)
		(end 376.150632 -327.168002)
		(width 0.14224)
		(layer "In6.Cu")
		(net "P5E_CPU0_P0_TX_DN<14>")
	)
	(segment
		(start 358.281986 -295.552876)
		(end 358.281986 -295.581324)
		(width 0.1143)
		(layer "In6.Cu")
		(net "P5E_CPU0_P0_TX_DN<14>")
	)
	(segment
		(start 358.423972 -289.963352)
		(end 358.393492 -289.981132)
		(width 0.1143)
		(layer "In6.Cu")
		(net "P5E_CPU0_P0_TX_DN<14>")
	)
	(segment
		(start 327.568306 -385.047998)
		(end 327.277476 -385.338828)
		(width 0.14224)
		(layer "In6.Cu")
		(net "P5E_CPU0_P0_TX_DN<14>")
	)
	(segment
		(start 358.423972 -288.9885)
		(end 358.460294 -289.009582)
		(width 0.1143)
		(layer "In6.Cu")
		(net "P5E_CPU0_P0_TX_DN<14>")
	)
	(segment
		(start 378.432822 -351.561146)
		(end 378.417582 -351.649284)
		(width 0.14224)
		(layer "In6.Cu")
		(net "P5E_CPU0_P0_TX_DN<14>")
	)
	(segment
		(start 358.393238 -285.73095)
		(end 358.395778 -285.73095)
		(width 0.1143)
		(layer "In6.Cu")
		(net "P5E_CPU0_P0_TX_DN<14>")
	)
	(segment
		(start 372.265194 -367.823242)
		(end 371.908832 -368.228118)
		(width 0.14224)
		(layer "In6.Cu")
		(net "P5E_CPU0_P0_TX_DN<14>")
	)
	(segment
		(start 358.281986 -298.409614)
		(end 360.460544 -303.669192)
		(width 0.14224)
		(layer "In6.Cu")
		(net "P5E_CPU0_P0_TX_DN<14>")
	)
	(segment
		(start 378.10059 -355.2698)
		(end 378.009404 -355.801422)
		(width 0.14224)
		(layer "In6.Cu")
		(net "P5E_CPU0_P0_TX_DN<14>")
	)
	(segment
		(start 358.236266 -295.507156)
		(end 358.281986 -295.552876)
		(width 0.1143)
		(layer "In6.Cu")
		(net "P5E_CPU0_P0_TX_DN<14>")
	)
	(segment
		(start 378.180346 -354.736654)
		(end 378.10059 -355.2698)
		(width 0.14224)
		(layer "In6.Cu")
		(net "P5E_CPU0_P0_TX_DN<14>")
	)
	(segment
		(start 363.496098 -379.692154)
		(end 363.495844 -379.692916)
		(width 0.14224)
		(layer "In6.Cu")
		(net "P5E_CPU0_P0_TX_DN<14>")
	)
	(segment
		(start 377.05919 -359.451148)
		(end 376.879358 -359.959402)
		(width 0.14224)
		(layer "In6.Cu")
		(net "P5E_CPU0_P0_TX_DN<14>")
	)
	(segment
		(start 377.907042 -356.330758)
		(end 377.793504 -356.857808)
		(width 0.14224)
		(layer "In6.Cu")
		(net "P5E_CPU0_P0_TX_DN<14>")
	)
	(segment
		(start 374.790208 -364.331758)
		(end 374.50776 -364.791244)
		(width 0.14224)
		(layer "In6.Cu")
		(net "P5E_CPU0_P0_TX_DN<14>")
	)
	(segment
		(start 358.460294 -286.7025)
		(end 358.39146 -286.742378)
		(width 0.1143)
		(layer "In6.Cu")
		(net "P5E_CPU0_P0_TX_DN<14>")
	)
	(segment
		(start 377.227846 -358.93883)
		(end 377.05919 -359.451148)
		(width 0.14224)
		(layer "In6.Cu")
		(net "P5E_CPU0_P0_TX_DN<14>")
	)
	(segment
		(start 358.460294 -289.94227)
		(end 358.423972 -289.963352)
		(width 0.1143)
		(layer "In6.Cu")
		(net "P5E_CPU0_P0_TX_DN<14>")
	)
	(segment
		(start 376.054366 -361.951778)
		(end 375.821956 -362.438442)
		(width 0.14224)
		(layer "In6.Cu")
		(net "P5E_CPU0_P0_TX_DN<14>")
	)
	(segment
		(start 358.464612 -288.319718)
		(end 358.39146 -288.36239)
		(width 0.1143)
		(layer "In6.Cu")
		(net "P5E_CPU0_P0_TX_DN<14>")
	)
	(segment
		(start 357.953564 -284.938724)
		(end 357.992426 -284.961076)
		(width 0.1143)
		(layer "In6.Cu")
		(net "P5E_CPU0_P0_TX_DN<14>")
	)
	(segment
		(start 364.416086 -377.187206)
		(end 364.040928 -378.210064)
		(width 0.14224)
		(layer "In6.Cu")
		(net "P5E_CPU0_P0_TX_DN<14>")
	)
	(segment
		(start 376.436128 -328.00036)
		(end 378.432822 -339.11413)
		(width 0.14224)
		(layer "In6.Cu")
		(net "P5E_CPU0_P0_TX_DN<14>")
	)
	(segment
		(start 358.281986 -295.581324)
		(end 358.281986 -298.409614)
		(width 0.14224)
		(layer "In6.Cu")
		(net "P5E_CPU0_P0_TX_DN<14>")
	)
	(segment
		(start 371.544088 -368.62512)
		(end 371.170708 -369.014502)
		(width 0.14224)
		(layer "In6.Cu")
		(net "P5E_CPU0_P0_TX_DN<14>")
	)
	(segment
		(start 358.393492 -288.97072)
		(end 358.423972 -288.9885)
		(width 0.1143)
		(layer "In6.Cu")
		(net "P5E_CPU0_P0_TX_DN<14>")
	)
	(segment
		(start 358.460294 -293.182294)
		(end 358.423972 -293.203376)
		(width 0.1143)
		(layer "In6.Cu")
		(net "P5E_CPU0_P0_TX_DN<14>")
	)
	(segment
		(start 357.373174 -283.806138)
		(end 357.303324 -283.875988)
		(width 0.1143)
		(layer "In6.Cu")
		(net "P5E_CPU0_P0_TX_DN<14>")
	)
	(segment
		(start 358.393492 -290.590732)
		(end 358.394254 -290.59124)
		(width 0.1143)
		(layer "In6.Cu")
		(net "P5E_CPU0_P0_TX_DN<14>")
	)
	(segment
		(start 378.351796 -353.128326)
		(end 378.305822 -353.665536)
		(width 0.14224)
		(layer "In6.Cu")
		(net "P5E_CPU0_P0_TX_DN<14>")
	)
	(segment
		(start 378.386086 -352.5901)
		(end 378.351796 -353.128326)
		(width 0.14224)
		(layer "In6.Cu")
		(net "P5E_CPU0_P0_TX_DN<14>")
	)
	(segment
		(start 358.423972 -293.203376)
		(end 358.424226 -293.203376)
		(width 0.1143)
		(layer "In6.Cu")
		(net "P5E_CPU0_P0_TX_DN<14>")
	)
	(segment
		(start 358.42448 -285.747714)
		(end 358.424734 -285.747968)
		(width 0.1143)
		(layer "In6.Cu")
		(net "P5E_CPU0_P0_TX_DN<14>")
	)
	(segment
		(start 371.908832 -368.228118)
		(end 371.544088 -368.62512)
		(width 0.14224)
		(layer "In6.Cu")
		(net "P5E_CPU0_P0_TX_DN<14>")
	)
	(segment
		(start 377.5329 -357.904542)
		(end 377.385834 -358.423464)
		(width 0.14224)
		(layer "In6.Cu")
		(net "P5E_CPU0_P0_TX_DN<14>")
	)
	(segment
		(start 372.612666 -367.411)
		(end 372.265194 -367.823242)
		(width 0.14224)
		(layer "In6.Cu")
		(net "P5E_CPU0_P0_TX_DN<14>")
	)
	(segment
		(start 360.218736 -386.753608)
		(end 359.702608 -386.753608)
		(width 0.14224)
		(layer "In6.Cu")
		(net "P5E_CPU0_P0_TX_DN<14>")
	)
	(segment
		(start 357.775256 -284.62351)
		(end 357.775256 -284.628844)
		(width 0.1143)
		(layer "In6.Cu")
		(net "P5E_CPU0_P0_TX_DN<14>")
	)
	(segment
		(start 363.495844 -379.692916)
		(end 361.137962 -386.112004)
		(width 0.14224)
		(layer "In6.Cu")
		(net "P5E_CPU0_P0_TX_DN<14>")
	)
	(segment
		(start 331.70368 -384.124454)
		(end 331.153262 -383.574036)
		(width 0.14224)
		(layer "In6.Cu")
		(net "P5E_CPU0_P0_TX_DN<14>")
	)
	(segment
		(start 377.385834 -358.423464)
		(end 377.227846 -358.93883)
		(width 0.14224)
		(layer "In6.Cu")
		(net "P5E_CPU0_P0_TX_DN<14>")
	)
	(segment
		(start 375.326148 -363.396022)
		(end 375.063258 -363.866938)
		(width 0.14224)
		(layer "In6.Cu")
		(net "P5E_CPU0_P0_TX_DN<14>")
	)
	(segment
		(start 358.423972 -290.608512)
		(end 358.460294 -290.629594)
		(width 0.1143)
		(layer "In6.Cu")
		(net "P5E_CPU0_P0_TX_DN<14>")
	)
	(arc
		(start 358.460294 -290.629594)
		(mid 358.706184 -291.095938)
		(end 358.460294 -291.562282)
		(width 0.1143)
		(layer "In6.Cu")
		(net "P5E_CPU0_P0_TX_DN<14>")
	)
	(arc
		(start 358.461564 -287.390586)
		(mid 358.641356 -287.593174)
		(end 358.706166 -287.856168)
		(width 0.1143)
		(layer "In6.Cu")
		(net "P5E_CPU0_P0_TX_DN<14>")
	)
	(arc
		(start 358.706166 -287.90392)
		(mid 358.654587 -288.118512)
		(end 358.511094 -288.28619)
		(width 0.1143)
		(layer "In6.Cu")
		(net "P5E_CPU0_P0_TX_DN<14>")
	)
	(arc
		(start 366.901476 -373.296688)
		(mid 365.447023 -375.106669)
		(end 364.416086 -377.187206)
		(width 0.14224)
		(layer "In6.Cu")
		(net "P5E_CPU0_P0_TX_DN<14>")
	)
	(arc
		(start 358.461564 -293.87038)
		(mid 358.462326 -293.870887)
		(end 358.463088 -293.871396)
		(width 0.1143)
		(layer "In6.Cu")
		(net "P5E_CPU0_P0_TX_DN<14>")
	)
	(arc
		(start 357.775256 -284.628844)
		(mid 357.823017 -284.8076)
		(end 357.953564 -284.938724)
		(width 0.1143)
		(layer "In6.Cu")
		(net "P5E_CPU0_P0_TX_DN<14>")
	)
	(arc
		(start 357.491792 -284.13329)
		(mid 357.699276 -284.340377)
		(end 357.775256 -284.62351)
		(width 0.1143)
		(layer "In6.Cu")
		(net "P5E_CPU0_P0_TX_DN<14>")
	)
	(arc
		(start 358.50195 -293.89832)
		(mid 358.731128 -294.335962)
		(end 358.50195 -294.773604)
		(width 0.1143)
		(layer "In6.Cu")
		(net "P5E_CPU0_P0_TX_DN<14>")
	)
	(arc
		(start 329.068684 -383.493264)
		(mid 328.856053 -383.811394)
		(end 328.78141 -384.186684)
		(width 0.14224)
		(layer "In6.Cu")
		(net "P5E_CPU0_P0_TX_DN<14>")
	)
	(arc
		(start 358.44607 -285.760922)
		(mid 358.705882 -286.227886)
		(end 358.460294 -286.7025)
		(width 0.1143)
		(layer "In6.Cu")
		(net "P5E_CPU0_P0_TX_DN<14>")
	)
	(arc
		(start 357.992426 -284.961076)
		(mid 358.171619 -285.163586)
		(end 358.236266 -285.42615)
		(width 0.1143)
		(layer "In6.Cu")
		(net "P5E_CPU0_P0_TX_DN<14>")
	)
	(arc
		(start 358.23652 -287.045908)
		(mid 358.278069 -287.21733)
		(end 358.393492 -287.350708)
		(width 0.1143)
		(layer "In6.Cu")
		(net "P5E_CPU0_P0_TX_DN<14>")
	)
	(arc
		(start 357.303324 -283.875988)
		(mid 357.355278 -284.007357)
		(end 357.452168 -284.110176)
		(width 0.1143)
		(layer "In6.Cu")
		(net "P5E_CPU0_P0_TX_DN<14>")
	)
	(arc
		(start 358.460294 -292.249606)
		(mid 358.706184 -292.71595)
		(end 358.460294 -293.182294)
		(width 0.1143)
		(layer "In6.Cu")
		(net "P5E_CPU0_P0_TX_DN<14>")
	)
	(arc
		(start 331.153262 -383.574036)
		(mid 330.660664 -383.244892)
		(end 330.079604 -383.129282)
		(width 0.14224)
		(layer "In6.Cu")
		(net "P5E_CPU0_P0_TX_DN<14>")
	)
	(arc
		(start 358.39146 -286.742378)
		(mid 358.277531 -286.875525)
		(end 358.23652 -287.045908)
		(width 0.1143)
		(layer "In6.Cu")
		(net "P5E_CPU0_P0_TX_DN<14>")
	)
	(arc
		(start 356.898194 -385.868926)
		(mid 355.51399 -385.185761)
		(end 353.98837 -384.950716)
		(width 0.14224)
		(layer "In6.Cu")
		(net "P5E_CPU0_P0_TX_DN<14>")
	)
	(arc
		(start 358.424226 -293.203376)
		(mid 358.239248 -293.52123)
		(end 358.416098 -293.84371)
		(width 0.1143)
		(layer "In6.Cu")
		(net "P5E_CPU0_P0_TX_DN<14>")
	)
	(arc
		(start 358.424734 -285.747968)
		(mid 358.435473 -285.754328)
		(end 358.44607 -285.760922)
		(width 0.1143)
		(layer "In6.Cu")
		(net "P5E_CPU0_P0_TX_DN<14>")
	)
	(arc
		(start 358.393492 -289.981132)
		(mid 358.236515 -290.285932)
		(end 358.393492 -290.590732)
		(width 0.1143)
		(layer "In6.Cu")
		(net "P5E_CPU0_P0_TX_DN<14>")
	)
	(arc
		(start 333.698596 -384.950716)
		(mid 332.618964 -384.735982)
		(end 331.70368 -384.124454)
		(width 0.14224)
		(layer "In6.Cu")
		(net "P5E_CPU0_P0_TX_DN<14>")
	)
	(arc
		(start 358.393492 -291.601144)
		(mid 358.236515 -291.905944)
		(end 358.393492 -292.210744)
		(width 0.1143)
		(layer "In6.Cu")
		(net "P5E_CPU0_P0_TX_DN<14>")
	)
	(arc
		(start 358.39146 -288.36239)
		(mid 358.277531 -288.495537)
		(end 358.23652 -288.66592)
		(width 0.1143)
		(layer "In6.Cu")
		(net "P5E_CPU0_P0_TX_DN<14>")
	)
	(arc
		(start 329.870816 -383.129282)
		(mid 329.465971 -383.209811)
		(end 329.122786 -383.439162)
		(width 0.14224)
		(layer "In6.Cu")
		(net "P5E_CPU0_P0_TX_DN<14>")
	)
	(arc
		(start 358.236266 -285.42615)
		(mid 358.277815 -285.597572)
		(end 358.393238 -285.73095)
		(width 0.1143)
		(layer "In6.Cu")
		(net "P5E_CPU0_P0_TX_DN<14>")
	)
	(arc
		(start 361.137962 -386.112004)
		(mid 360.779256 -386.577398)
		(end 360.218736 -386.753608)
		(width 0.14224)
		(layer "In6.Cu")
		(net "P5E_CPU0_P0_TX_DN<14>")
	)
	(arc
		(start 358.460294 -289.009582)
		(mid 358.706184 -289.475926)
		(end 358.460294 -289.94227)
		(width 0.1143)
		(layer "In6.Cu")
		(net "P5E_CPU0_P0_TX_DN<14>")
	)
	(arc
		(start 358.393238 -294.841168)
		(mid 358.277811 -294.974544)
		(end 358.236266 -295.145968)
		(width 0.1143)
		(layer "In6.Cu")
		(net "P5E_CPU0_P0_TX_DN<14>")
	)
	(arc
		(start 358.23652 -288.66592)
		(mid 358.278069 -288.837342)
		(end 358.393492 -288.97072)
		(width 0.1143)
		(layer "In6.Cu")
		(net "P5E_CPU0_P0_TX_DN<14>")
	)
	(arc
		(start 359.702608 -386.753608)
		(mid 358.232307 -386.527141)
		(end 356.898194 -385.868926)
		(width 0.14224)
		(layer "In6.Cu")
		(net "P5E_CPU0_P0_TX_DN<14>")
	)
	(arc
		(start 328.6125 -384.92811)
		(mid 328.47978 -385.016854)
		(end 328.323194 -385.047998)
		(width 0.14224)
		(layer "In6.Cu")
		(net "P5E_CPU0_P0_TX_DN<14>")
	)
	(segment
		(start 324.812406 -378.39142)
		(end 324.812406 -377.68784)
		(width 0.12954)
		(layer "F.Cu")
		(net "P5E_CPU0_P0_TX_DN<13>")
	)
	(segment
		(start 358.137968 -285.160212)
		(end 357.671116 -285.42615)
		(width 0.12954)
		(layer "F.Cu")
		(net "P5E_CPU0_P0_TX_DN<13>")
	)
	(segment
		(start 324.516496 -378.68733)
		(end 324.812406 -378.39142)
		(width 0.12954)
		(layer "F.Cu")
		(net "P5E_CPU0_P0_TX_DN<13>")
	)
	(segment
		(start 324.812406 -377.68784)
		(end 324.541896 -377.41733)
		(width 0.12954)
		(layer "F.Cu")
		(net "P5E_CPU0_P0_TX_DN<13>")
	)
	(segment
		(start 357.482648 -292.227762)
		(end 357.481886 -292.227254)
		(width 0.1143)
		(layer "In6.Cu")
		(net "P5E_CPU0_P0_TX_DN<13>")
	)
	(segment
		(start 357.766366 -287.856168)
		(end 357.766366 -287.709102)
		(width 0.1143)
		(layer "In6.Cu")
		(net "P5E_CPU0_P0_TX_DN<13>")
	)
	(segment
		(start 375.565162 -328.463148)
		(end 375.16689 -327.298558)
		(width 0.14224)
		(layer "In6.Cu")
		(net "P5E_CPU0_P0_TX_DN<13>")
	)
	(segment
		(start 327.677526 -378.76734)
		(end 332.343252 -383.433066)
		(width 0.14224)
		(layer "In6.Cu")
		(net "P5E_CPU0_P0_TX_DN<13>")
	)
	(segment
		(start 326.342248 -378.633228)
		(end 326.737218 -378.633228)
		(width 0.14224)
		(layer "In6.Cu")
		(net "P5E_CPU0_P0_TX_DN<13>")
	)
	(segment
		(start 357.341932 -295.54805)
		(end 357.341932 -295.519602)
		(width 0.1143)
		(layer "In6.Cu")
		(net "P5E_CPU0_P0_TX_DN<13>")
	)
	(segment
		(start 357.505508 -285.761176)
		(end 357.50373 -285.76016)
		(width 0.1143)
		(layer "In6.Cu")
		(net "P5E_CPU0_P0_TX_DN<13>")
	)
	(segment
		(start 325.40448 -378.81179)
		(end 325.702168 -378.81179)
		(width 0.14224)
		(layer "In6.Cu")
		(net "P5E_CPU0_P0_TX_DN<13>")
	)
	(segment
		(start 357.485696 -289.962336)
		(end 357.523034 -289.940746)
		(width 0.1143)
		(layer "In6.Cu")
		(net "P5E_CPU0_P0_TX_DN<13>")
	)
	(segment
		(start 357.48214 -291.584634)
		(end 357.48341 -291.583872)
		(width 0.1143)
		(layer "In6.Cu")
		(net "P5E_CPU0_P0_TX_DN<13>")
	)
	(segment
		(start 357.48087 -292.226746)
		(end 357.480108 -292.226238)
		(width 0.1143)
		(layer "In6.Cu")
		(net "P5E_CPU0_P0_TX_DN<13>")
	)
	(segment
		(start 357.452422 -294.841676)
		(end 357.505508 -294.810942)
		(width 0.1143)
		(layer "In6.Cu")
		(net "P5E_CPU0_P0_TX_DN<13>")
	)
	(segment
		(start 357.48341 -285.748222)
		(end 357.452422 -285.730442)
		(width 0.1143)
		(layer "In6.Cu")
		(net "P5E_CPU0_P0_TX_DN<13>")
	)
	(segment
		(start 357.484172 -290.608512)
		(end 357.452422 -290.590224)
		(width 0.1143)
		(layer "In6.Cu")
		(net "P5E_CPU0_P0_TX_DN<13>")
	)
	(segment
		(start 357.505508 -293.860982)
		(end 357.504746 -293.860474)
		(width 0.1143)
		(layer "In6.Cu")
		(net "P5E_CPU0_P0_TX_DN<13>")
	)
	(segment
		(start 359.635806 -304.12055)
		(end 357.341932 -298.582588)
		(width 0.14224)
		(layer "In6.Cu")
		(net "P5E_CPU0_P0_TX_DN<13>")
	)
	(segment
		(start 357.550974 -289.031172)
		(end 357.523034 -289.011106)
		(width 0.1143)
		(layer "In6.Cu")
		(net "P5E_CPU0_P0_TX_DN<13>")
	)
	(segment
		(start 357.484172 -285.74873)
		(end 357.48341 -285.748222)
		(width 0.1143)
		(layer "In6.Cu")
		(net "P5E_CPU0_P0_TX_DN<13>")
	)
	(segment
		(start 324.541896 -377.41733)
		(end 324.832726 -377.70816)
		(width 0.14224)
		(layer "In6.Cu")
		(net "P5E_CPU0_P0_TX_DN<13>")
	)
	(segment
		(start 326.750934 -378.63399)
		(end 327.355708 -378.63399)
		(width 0.14224)
		(layer "In6.Cu")
		(net "P5E_CPU0_P0_TX_DN<13>")
	)
	(segment
		(start 357.296466 -295.473628)
		(end 357.296466 -295.145968)
		(width 0.1143)
		(layer "In6.Cu")
		(net "P5E_CPU0_P0_TX_DN<13>")
	)
	(segment
		(start 361.67568 -379.072902)
		(end 361.676188 -379.071378)
		(width 0.14224)
		(layer "In6.Cu")
		(net "P5E_CPU0_P0_TX_DN<13>")
	)
	(segment
		(start 365.217202 -373.64924)
		(end 370.320824 -368.545618)
		(width 0.14224)
		(layer "In6.Cu")
		(net "P5E_CPU0_P0_TX_DN<13>")
	)
	(segment
		(start 357.341932 -295.519602)
		(end 357.296212 -295.473882)
		(width 0.1143)
		(layer "In6.Cu")
		(net "P5E_CPU0_P0_TX_DN<13>")
	)
	(segment
		(start 357.48341 -289.96386)
		(end 357.485696 -289.962336)
		(width 0.1143)
		(layer "In6.Cu")
		(net "P5E_CPU0_P0_TX_DN<13>")
	)
	(segment
		(start 357.467916 -293.212266)
		(end 357.485188 -293.202614)
		(width 0.1143)
		(layer "In6.Cu")
		(net "P5E_CPU0_P0_TX_DN<13>")
	)
	(segment
		(start 357.550974 -292.271196)
		(end 357.523034 -292.25113)
		(width 0.1143)
		(layer "In6.Cu")
		(net "P5E_CPU0_P0_TX_DN<13>")
	)
	(segment
		(start 357.48214 -289.964622)
		(end 357.48341 -289.96386)
		(width 0.1143)
		(layer "In6.Cu")
		(net "P5E_CPU0_P0_TX_DN<13>")
	)
	(segment
		(start 357.48341 -291.583872)
		(end 357.484172 -291.583364)
		(width 0.1143)
		(layer "In6.Cu")
		(net "P5E_CPU0_P0_TX_DN<13>")
	)
	(segment
		(start 357.481886 -292.227254)
		(end 357.48087 -292.226746)
		(width 0.1143)
		(layer "In6.Cu")
		(net "P5E_CPU0_P0_TX_DN<13>")
	)
	(segment
		(start 357.450644 -286.74314)
		(end 357.505508 -286.711136)
		(width 0.1143)
		(layer "In6.Cu")
		(net "P5E_CPU0_P0_TX_DN<13>")
	)
	(segment
		(start 357.484172 -291.583364)
		(end 357.520494 -291.562282)
		(width 0.1143)
		(layer "In6.Cu")
		(net "P5E_CPU0_P0_TX_DN<13>")
	)
	(segment
		(start 361.677458 -379.067568)
		(end 361.809792 -378.74829)
		(width 0.14224)
		(layer "In6.Cu")
		(net "P5E_CPU0_P0_TX_DN<13>")
	)
	(segment
		(start 365.175038 -312.410094)
		(end 359.635806 -304.12055)
		(width 0.14224)
		(layer "In6.Cu")
		(net "P5E_CPU0_P0_TX_DN<13>")
	)
	(segment
		(start 357.523034 -293.18077)
		(end 357.550974 -293.160704)
		(width 0.1143)
		(layer "In6.Cu")
		(net "P5E_CPU0_P0_TX_DN<13>")
	)
	(segment
		(start 357.373174 -285.42615)
		(end 357.671116 -285.42615)
		(width 0.1143)
		(layer "In6.Cu")
		(net "P5E_CPU0_P0_TX_DN<13>")
	)
	(segment
		(start 361.675172 -379.074172)
		(end 361.67568 -379.072902)
		(width 0.14224)
		(layer "In6.Cu")
		(net "P5E_CPU0_P0_TX_DN<13>")
	)
	(segment
		(start 357.341932 -298.582588)
		(end 357.341932 -295.54805)
		(width 0.14224)
		(layer "In6.Cu")
		(net "P5E_CPU0_P0_TX_DN<13>")
	)
	(segment
		(start 357.303324 -285.496)
		(end 357.373174 -285.42615)
		(width 0.1143)
		(layer "In6.Cu")
		(net "P5E_CPU0_P0_TX_DN<13>")
	)
	(segment
		(start 357.523542 -287.391348)
		(end 357.4542 -287.35147)
		(width 0.1143)
		(layer "In6.Cu")
		(net "P5E_CPU0_P0_TX_DN<13>")
	)
	(segment
		(start 360.844338 -381.33528)
		(end 361.675172 -379.074172)
		(width 0.14224)
		(layer "In6.Cu")
		(net "P5E_CPU0_P0_TX_DN<13>")
	)
	(segment
		(start 357.452422 -293.221664)
		(end 357.467916 -293.212266)
		(width 0.1143)
		(layer "In6.Cu")
		(net "P5E_CPU0_P0_TX_DN<13>")
	)
	(segment
		(start 357.489506 -293.200328)
		(end 357.523034 -293.18077)
		(width 0.1143)
		(layer "In6.Cu")
		(net "P5E_CPU0_P0_TX_DN<13>")
	)
	(segment
		(start 357.483918 -288.34334)
		(end 357.525828 -288.318956)
		(width 0.1143)
		(layer "In6.Cu")
		(net "P5E_CPU0_P0_TX_DN<13>")
	)
	(segment
		(start 357.296212 -295.473882)
		(end 357.296466 -295.473628)
		(width 0.1143)
		(layer "In6.Cu")
		(net "P5E_CPU0_P0_TX_DN<13>")
	)
	(segment
		(start 357.502968 -285.759652)
		(end 357.484172 -285.74873)
		(width 0.1143)
		(layer "In6.Cu")
		(net "P5E_CPU0_P0_TX_DN<13>")
	)
	(segment
		(start 326.737218 -378.633228)
		(end 326.750934 -378.63399)
		(width 0.14224)
		(layer "In6.Cu")
		(net "P5E_CPU0_P0_TX_DN<13>")
	)
	(segment
		(start 357.480108 -292.226238)
		(end 357.452422 -292.210236)
		(width 0.1143)
		(layer "In6.Cu")
		(net "P5E_CPU0_P0_TX_DN<13>")
	)
	(segment
		(start 357.452422 -291.601652)
		(end 357.48214 -291.584634)
		(width 0.1143)
		(layer "In6.Cu")
		(net "P5E_CPU0_P0_TX_DN<13>")
	)
	(segment
		(start 357.484172 -288.9885)
		(end 357.48341 -288.987992)
		(width 0.1143)
		(layer "In6.Cu")
		(net "P5E_CPU0_P0_TX_DN<13>")
	)
	(segment
		(start 371.26037 -319.824608)
		(end 365.175038 -312.410094)
		(width 0.14224)
		(layer "In6.Cu")
		(net "P5E_CPU0_P0_TX_DN<13>")
	)
	(segment
		(start 357.485188 -293.202614)
		(end 357.489506 -293.200328)
		(width 0.1143)
		(layer "In6.Cu")
		(net "P5E_CPU0_P0_TX_DN<13>")
	)
	(segment
		(start 357.520494 -290.629594)
		(end 357.484172 -290.608512)
		(width 0.1143)
		(layer "In6.Cu")
		(net "P5E_CPU0_P0_TX_DN<13>")
	)
	(segment
		(start 333.460598 -383.895854)
		(end 357.782876 -383.895854)
		(width 0.14224)
		(layer "In6.Cu")
		(net "P5E_CPU0_P0_TX_DN<13>")
	)
	(segment
		(start 375.16689 -327.298558)
		(end 371.26037 -319.824608)
		(width 0.14224)
		(layer "In6.Cu")
		(net "P5E_CPU0_P0_TX_DN<13>")
	)
	(segment
		(start 324.832726 -377.70816)
		(end 324.832726 -378.31649)
		(width 0.14224)
		(layer "In6.Cu")
		(net "P5E_CPU0_P0_TX_DN<13>")
	)
	(segment
		(start 357.450644 -288.363152)
		(end 357.484172 -288.343594)
		(width 0.1143)
		(layer "In6.Cu")
		(net "P5E_CPU0_P0_TX_DN<13>")
	)
	(segment
		(start 357.523034 -289.940746)
		(end 357.550974 -289.92068)
		(width 0.1143)
		(layer "In6.Cu")
		(net "P5E_CPU0_P0_TX_DN<13>")
	)
	(segment
		(start 357.486966 -288.990278)
		(end 357.484172 -288.9885)
		(width 0.1143)
		(layer "In6.Cu")
		(net "P5E_CPU0_P0_TX_DN<13>")
	)
	(segment
		(start 357.484172 -288.343594)
		(end 357.483918 -288.34334)
		(width 0.1143)
		(layer "In6.Cu")
		(net "P5E_CPU0_P0_TX_DN<13>")
	)
	(segment
		(start 357.50373 -285.76016)
		(end 357.502968 -285.759652)
		(width 0.1143)
		(layer "In6.Cu")
		(net "P5E_CPU0_P0_TX_DN<13>")
	)
	(segment
		(start 357.4542 -287.35147)
		(end 357.452422 -287.3502)
		(width 0.1143)
		(layer "In6.Cu")
		(net "P5E_CPU0_P0_TX_DN<13>")
	)
	(segment
		(start 357.452422 -289.98164)
		(end 357.48214 -289.964622)
		(width 0.1143)
		(layer "In6.Cu")
		(net "P5E_CPU0_P0_TX_DN<13>")
	)
	(segment
		(start 357.523034 -289.011106)
		(end 357.486966 -288.990278)
		(width 0.1143)
		(layer "In6.Cu")
		(net "P5E_CPU0_P0_TX_DN<13>")
	)
	(segment
		(start 377.487942 -339.167724)
		(end 375.565162 -328.463148)
		(width 0.14224)
		(layer "In6.Cu")
		(net "P5E_CPU0_P0_TX_DN<13>")
	)
	(segment
		(start 357.48341 -288.987992)
		(end 357.452422 -288.970212)
		(width 0.1143)
		(layer "In6.Cu")
		(net "P5E_CPU0_P0_TX_DN<13>")
	)
	(segment
		(start 377.487942 -351.24263)
		(end 377.487942 -339.167724)
		(width 0.14224)
		(layer "In6.Cu")
		(net "P5E_CPU0_P0_TX_DN<13>")
	)
	(segment
		(start 357.504746 -293.860474)
		(end 357.452422 -293.830248)
		(width 0.1143)
		(layer "In6.Cu")
		(net "P5E_CPU0_P0_TX_DN<13>")
	)
	(segment
		(start 357.523034 -292.25113)
		(end 357.482648 -292.227762)
		(width 0.1143)
		(layer "In6.Cu")
		(net "P5E_CPU0_P0_TX_DN<13>")
	)
	(segment
		(start 357.65105 -287.483296)
		(end 357.523542 -287.391348)
		(width 0.1143)
		(layer "In6.Cu")
		(net "P5E_CPU0_P0_TX_DN<13>")
	)
	(arc
		(start 357.296466 -295.145968)
		(mid 357.337721 -294.974997)
		(end 357.452422 -294.841676)
		(width 0.1143)
		(layer "In6.Cu")
		(net "P5E_CPU0_P0_TX_DN<13>")
	)
	(arc
		(start 361.676188 -379.071378)
		(mid 361.676808 -379.069468)
		(end 361.677458 -379.067568)
		(width 0.14224)
		(layer "In6.Cu")
		(net "P5E_CPU0_P0_TX_DN<13>")
	)
	(arc
		(start 357.452422 -292.210236)
		(mid 357.296494 -291.905944)
		(end 357.452422 -291.601652)
		(width 0.1143)
		(layer "In6.Cu")
		(net "P5E_CPU0_P0_TX_DN<13>")
	)
	(arc
		(start 357.766366 -287.709102)
		(mid 357.735934 -287.582287)
		(end 357.65105 -287.483296)
		(width 0.1143)
		(layer "In6.Cu")
		(net "P5E_CPU0_P0_TX_DN<13>")
	)
	(arc
		(start 357.535734 -291.551614)
		(mid 357.760905 -291.095938)
		(end 357.535734 -290.640262)
		(width 0.1143)
		(layer "In6.Cu")
		(net "P5E_CPU0_P0_TX_DN<13>")
	)
	(arc
		(start 325.702168 -378.81179)
		(mid 325.860124 -378.790393)
		(end 326.00646 -378.727208)
		(width 0.14224)
		(layer "In6.Cu")
		(net "P5E_CPU0_P0_TX_DN<13>")
	)
	(arc
		(start 326.00646 -378.727208)
		(mid 326.167908 -378.6572)
		(end 326.342248 -378.633228)
		(width 0.14224)
		(layer "In6.Cu")
		(net "P5E_CPU0_P0_TX_DN<13>")
	)
	(arc
		(start 357.296466 -288.66592)
		(mid 357.337228 -288.496036)
		(end 357.450644 -288.363152)
		(width 0.1143)
		(layer "In6.Cu")
		(net "P5E_CPU0_P0_TX_DN<13>")
	)
	(arc
		(start 357.520494 -291.562282)
		(mid 357.528158 -291.557011)
		(end 357.535734 -291.551614)
		(width 0.1143)
		(layer "In6.Cu")
		(net "P5E_CPU0_P0_TX_DN<13>")
	)
	(arc
		(start 357.525828 -288.318956)
		(mid 357.70272 -288.116988)
		(end 357.766366 -287.856168)
		(width 0.1143)
		(layer "In6.Cu")
		(net "P5E_CPU0_P0_TX_DN<13>")
	)
	(arc
		(start 361.809792 -378.74829)
		(mid 363.262459 -376.031012)
		(end 365.217202 -373.64924)
		(width 0.14224)
		(layer "In6.Cu")
		(net "P5E_CPU0_P0_TX_DN<13>")
	)
	(arc
		(start 357.452422 -290.590224)
		(mid 357.296494 -290.285932)
		(end 357.452422 -289.98164)
		(width 0.1143)
		(layer "In6.Cu")
		(net "P5E_CPU0_P0_TX_DN<13>")
	)
	(arc
		(start 324.962012 -378.628656)
		(mid 325.165019 -378.764271)
		(end 325.40448 -378.81179)
		(width 0.14224)
		(layer "In6.Cu")
		(net "P5E_CPU0_P0_TX_DN<13>")
	)
	(arc
		(start 370.320824 -368.545618)
		(mid 375.625279 -360.60694)
		(end 377.487942 -351.24263)
		(width 0.14224)
		(layer "In6.Cu")
		(net "P5E_CPU0_P0_TX_DN<13>")
	)
	(arc
		(start 324.832726 -378.31649)
		(mid 324.86633 -378.485426)
		(end 324.962012 -378.628656)
		(width 0.14224)
		(layer "In6.Cu")
		(net "P5E_CPU0_P0_TX_DN<13>")
	)
	(arc
		(start 357.535734 -290.640262)
		(mid 357.528158 -290.634866)
		(end 357.520494 -290.629594)
		(width 0.1143)
		(layer "In6.Cu")
		(net "P5E_CPU0_P0_TX_DN<13>")
	)
	(arc
		(start 357.452422 -288.970212)
		(mid 357.337746 -288.836878)
		(end 357.296466 -288.66592)
		(width 0.1143)
		(layer "In6.Cu")
		(net "P5E_CPU0_P0_TX_DN<13>")
	)
	(arc
		(start 327.355708 -378.63399)
		(mid 327.529879 -378.668653)
		(end 327.677526 -378.76734)
		(width 0.14224)
		(layer "In6.Cu")
		(net "P5E_CPU0_P0_TX_DN<13>")
	)
	(arc
		(start 357.452422 -287.3502)
		(mid 357.337746 -287.216866)
		(end 357.296466 -287.045908)
		(width 0.1143)
		(layer "In6.Cu")
		(net "P5E_CPU0_P0_TX_DN<13>")
	)
	(arc
		(start 357.550974 -293.160704)
		(mid 357.778974 -292.71595)
		(end 357.550974 -292.271196)
		(width 0.1143)
		(layer "In6.Cu")
		(net "P5E_CPU0_P0_TX_DN<13>")
	)
	(arc
		(start 357.782876 -383.895854)
		(mid 358.831835 -383.687586)
		(end 359.721912 -383.094738)
		(width 0.14224)
		(layer "In6.Cu")
		(net "P5E_CPU0_P0_TX_DN<13>")
	)
	(arc
		(start 357.550974 -289.92068)
		(mid 357.778974 -289.475926)
		(end 357.550974 -289.031172)
		(width 0.1143)
		(layer "In6.Cu")
		(net "P5E_CPU0_P0_TX_DN<13>")
	)
	(arc
		(start 357.452422 -285.730442)
		(mid 357.355287 -285.627573)
		(end 357.303324 -285.496)
		(width 0.1143)
		(layer "In6.Cu")
		(net "P5E_CPU0_P0_TX_DN<13>")
	)
	(arc
		(start 332.343252 -383.433066)
		(mid 332.855895 -383.775603)
		(end 333.460598 -383.895854)
		(width 0.14224)
		(layer "In6.Cu")
		(net "P5E_CPU0_P0_TX_DN<13>")
	)
	(arc
		(start 357.505508 -286.711136)
		(mid 357.779059 -286.236156)
		(end 357.505508 -285.761176)
		(width 0.1143)
		(layer "In6.Cu")
		(net "P5E_CPU0_P0_TX_DN<13>")
	)
	(arc
		(start 357.505508 -294.810942)
		(mid 357.779059 -294.335962)
		(end 357.505508 -293.860982)
		(width 0.1143)
		(layer "In6.Cu")
		(net "P5E_CPU0_P0_TX_DN<13>")
	)
	(arc
		(start 359.721912 -383.094738)
		(mid 359.723945 -383.092834)
		(end 359.725976 -383.090928)
		(width 0.14224)
		(layer "In6.Cu")
		(net "P5E_CPU0_P0_TX_DN<13>")
	)
	(arc
		(start 357.296466 -287.045908)
		(mid 357.337228 -286.876024)
		(end 357.450644 -286.74314)
		(width 0.1143)
		(layer "In6.Cu")
		(net "P5E_CPU0_P0_TX_DN<13>")
	)
	(arc
		(start 359.725976 -383.090928)
		(mid 360.364778 -382.263821)
		(end 360.844338 -381.33528)
		(width 0.14224)
		(layer "In6.Cu")
		(net "P5E_CPU0_P0_TX_DN<13>")
	)
	(arc
		(start 357.452422 -293.830248)
		(mid 357.296494 -293.525956)
		(end 357.452422 -293.221664)
		(width 0.1143)
		(layer "In6.Cu")
		(net "P5E_CPU0_P0_TX_DN<13>")
	)
	(segment
		(start 321.731386 -377.68784)
		(end 322.001896 -377.41733)
		(width 0.12954)
		(layer "F.Cu")
		(net "P5E_CPU0_P0_TX_DN<12>")
	)
	(segment
		(start 355.78796 -282.730194)
		(end 355.321108 -282.996132)
		(width 0.12954)
		(layer "F.Cu")
		(net "P5E_CPU0_P0_TX_DN<12>")
	)
	(segment
		(start 321.731386 -378.39142)
		(end 321.731386 -377.68784)
		(width 0.12954)
		(layer "F.Cu")
		(net "P5E_CPU0_P0_TX_DN<12>")
	)
	(segment
		(start 322.027296 -378.68733)
		(end 321.731386 -378.39142)
		(width 0.12954)
		(layer "F.Cu")
		(net "P5E_CPU0_P0_TX_DN<12>")
	)
	(segment
		(start 374.63984 -328.77506)
		(end 376.555762 -339.438996)
		(width 0.14224)
		(layer "In6.Cu")
		(net "P5E_CPU0_P0_TX_DN<12>")
	)
	(segment
		(start 356.356412 -295.490392)
		(end 356.356158 -295.490646)
		(width 0.1143)
		(layer "In6.Cu")
		(net "P5E_CPU0_P0_TX_DN<12>")
	)
	(segment
		(start 356.512368 -288.970212)
		(end 356.543356 -288.987992)
		(width 0.1143)
		(layer "In6.Cu")
		(net "P5E_CPU0_P0_TX_DN<12>")
	)
	(segment
		(start 356.544118 -286.723582)
		(end 356.51059 -286.74314)
		(width 0.1143)
		(layer "In6.Cu")
		(net "P5E_CPU0_P0_TX_DN<12>")
	)
	(segment
		(start 356.540562 -289.965384)
		(end 356.539292 -289.966146)
		(width 0.1143)
		(layer "In6.Cu")
		(net "P5E_CPU0_P0_TX_DN<12>")
	)
	(segment
		(start 356.544118 -293.203376)
		(end 356.543356 -293.203884)
		(width 0.1143)
		(layer "In6.Cu")
		(net "P5E_CPU0_P0_TX_DN<12>")
	)
	(segment
		(start 356.542086 -294.824658)
		(end 356.540562 -294.82542)
		(width 0.1143)
		(layer "In6.Cu")
		(net "P5E_CPU0_P0_TX_DN<12>")
	)
	(segment
		(start 356.545134 -288.989008)
		(end 356.546658 -288.990024)
		(width 0.1143)
		(layer "In6.Cu")
		(net "P5E_CPU0_P0_TX_DN<12>")
	)
	(segment
		(start 356.547674 -285.750762)
		(end 356.583234 -285.77159)
		(width 0.1143)
		(layer "In6.Cu")
		(net "P5E_CPU0_P0_TX_DN<12>")
	)
	(segment
		(start 374.173496 -327.41108)
		(end 374.63984 -328.77506)
		(width 0.14224)
		(layer "In6.Cu")
		(net "P5E_CPU0_P0_TX_DN<12>")
	)
	(segment
		(start 356.073964 -284.938724)
		(end 356.11308 -284.961584)
		(width 0.1143)
		(layer "In6.Cu")
		(net "P5E_CPU0_P0_TX_DN<12>")
	)
	(segment
		(start 321.711066 -376.629422)
		(end 321.711066 -377.1265)
		(width 0.14224)
		(layer "In6.Cu")
		(net "P5E_CPU0_P0_TX_DN<12>")
	)
	(segment
		(start 356.529386 -293.212012)
		(end 356.527354 -293.213282)
		(width 0.1143)
		(layer "In6.Cu")
		(net "P5E_CPU0_P0_TX_DN<12>")
	)
	(segment
		(start 364.422944 -312.963306)
		(end 370.478304 -320.341752)
		(width 0.14224)
		(layer "In6.Cu")
		(net "P5E_CPU0_P0_TX_DN<12>")
	)
	(segment
		(start 356.356158 -295.490646)
		(end 356.401878 -295.536366)
		(width 0.1143)
		(layer "In6.Cu")
		(net "P5E_CPU0_P0_TX_DN<12>")
	)
	(segment
		(start 356.532688 -293.210234)
		(end 356.529386 -293.212012)
		(width 0.1143)
		(layer "In6.Cu")
		(net "P5E_CPU0_P0_TX_DN<12>")
	)
	(segment
		(start 356.543356 -293.203884)
		(end 356.542086 -293.204646)
		(width 0.1143)
		(layer "In6.Cu")
		(net "P5E_CPU0_P0_TX_DN<12>")
	)
	(segment
		(start 356.535228 -289.968686)
		(end 356.532688 -289.97021)
		(width 0.1143)
		(layer "In6.Cu")
		(net "P5E_CPU0_P0_TX_DN<12>")
	)
	(segment
		(start 355.572314 -284.11043)
		(end 355.64318 -284.151578)
		(width 0.1143)
		(layer "In6.Cu")
		(net "P5E_CPU0_P0_TX_DN<12>")
	)
	(segment
		(start 356.543356 -291.583872)
		(end 356.542086 -291.584634)
		(width 0.1143)
		(layer "In6.Cu")
		(net "P5E_CPU0_P0_TX_DN<12>")
	)
	(segment
		(start 321.711066 -377.1265)
		(end 322.001896 -377.41733)
		(width 0.14224)
		(layer "In6.Cu")
		(net "P5E_CPU0_P0_TX_DN<12>")
	)
	(segment
		(start 356.546658 -292.230048)
		(end 356.547674 -292.230556)
		(width 0.1143)
		(layer "In6.Cu")
		(net "P5E_CPU0_P0_TX_DN<12>")
	)
	(segment
		(start 356.547674 -293.850568)
		(end 356.583234 -293.871396)
		(width 0.1143)
		(layer "In6.Cu")
		(net "P5E_CPU0_P0_TX_DN<12>")
	)
	(segment
		(start 356.545134 -285.749238)
		(end 356.546658 -285.750254)
		(width 0.1143)
		(layer "In6.Cu")
		(net "P5E_CPU0_P0_TX_DN<12>")
	)
	(segment
		(start 356.532688 -289.97021)
		(end 356.529386 -289.971988)
		(width 0.1143)
		(layer "In6.Cu")
		(net "P5E_CPU0_P0_TX_DN<12>")
	)
	(segment
		(start 356.535228 -291.588698)
		(end 356.532688 -291.590222)
		(width 0.1143)
		(layer "In6.Cu")
		(net "P5E_CPU0_P0_TX_DN<12>")
	)
	(segment
		(start 356.544118 -291.583364)
		(end 356.543356 -291.583872)
		(width 0.1143)
		(layer "In6.Cu")
		(net "P5E_CPU0_P0_TX_DN<12>")
	)
	(segment
		(start 356.535228 -293.20871)
		(end 356.532688 -293.210234)
		(width 0.1143)
		(layer "In6.Cu")
		(net "P5E_CPU0_P0_TX_DN<12>")
	)
	(segment
		(start 355.102414 -283.300424)
		(end 355.171248 -283.340302)
		(width 0.1143)
		(layer "In6.Cu")
		(net "P5E_CPU0_P0_TX_DN<12>")
	)
	(segment
		(start 356.583234 -291.560504)
		(end 356.544118 -291.583364)
		(width 0.1143)
		(layer "In6.Cu")
		(net "P5E_CPU0_P0_TX_DN<12>")
	)
	(segment
		(start 356.544118 -287.368488)
		(end 356.580694 -287.389824)
		(width 0.1143)
		(layer "In6.Cu")
		(net "P5E_CPU0_P0_TX_DN<12>")
	)
	(segment
		(start 376.555762 -339.438996)
		(end 376.555762 -350.845628)
		(width 0.14224)
		(layer "In6.Cu")
		(net "P5E_CPU0_P0_TX_DN<12>")
	)
	(segment
		(start 356.547674 -292.230556)
		(end 356.583234 -292.251384)
		(width 0.1143)
		(layer "In6.Cu")
		(net "P5E_CPU0_P0_TX_DN<12>")
	)
	(segment
		(start 356.539292 -291.586158)
		(end 356.53853 -291.586666)
		(width 0.1143)
		(layer "In6.Cu")
		(net "P5E_CPU0_P0_TX_DN<12>")
	)
	(segment
		(start 356.539292 -293.20617)
		(end 356.53853 -293.206678)
		(width 0.1143)
		(layer "In6.Cu")
		(net "P5E_CPU0_P0_TX_DN<12>")
	)
	(segment
		(start 356.53853 -293.206678)
		(end 356.535228 -293.20871)
		(width 0.1143)
		(layer "In6.Cu")
		(net "P5E_CPU0_P0_TX_DN<12>")
	)
	(segment
		(start 356.583234 -286.700722)
		(end 356.544118 -286.723582)
		(width 0.1143)
		(layer "In6.Cu")
		(net "P5E_CPU0_P0_TX_DN<12>")
	)
	(segment
		(start 356.544118 -288.9885)
		(end 356.545134 -288.989008)
		(width 0.1143)
		(layer "In6.Cu")
		(net "P5E_CPU0_P0_TX_DN<12>")
	)
	(segment
		(start 356.53853 -289.966654)
		(end 356.535228 -289.968686)
		(width 0.1143)
		(layer "In6.Cu")
		(net "P5E_CPU0_P0_TX_DN<12>")
	)
	(segment
		(start 356.544118 -288.343594)
		(end 356.51059 -288.363152)
		(width 0.1143)
		(layer "In6.Cu")
		(net "P5E_CPU0_P0_TX_DN<12>")
	)
	(segment
		(start 356.546658 -285.750254)
		(end 356.547674 -285.750762)
		(width 0.1143)
		(layer "In6.Cu")
		(net "P5E_CPU0_P0_TX_DN<12>")
	)
	(segment
		(start 356.532688 -291.590222)
		(end 356.529386 -291.592)
		(width 0.1143)
		(layer "In6.Cu")
		(net "P5E_CPU0_P0_TX_DN<12>")
	)
	(segment
		(start 356.545134 -293.849044)
		(end 356.546658 -293.85006)
		(width 0.1143)
		(layer "In6.Cu")
		(net "P5E_CPU0_P0_TX_DN<12>")
	)
	(segment
		(start 356.512368 -290.590224)
		(end 356.543356 -290.608004)
		(width 0.1143)
		(layer "In6.Cu")
		(net "P5E_CPU0_P0_TX_DN<12>")
	)
	(segment
		(start 356.545134 -292.229032)
		(end 356.546658 -292.230048)
		(width 0.1143)
		(layer "In6.Cu")
		(net "P5E_CPU0_P0_TX_DN<12>")
	)
	(segment
		(start 321.991736 -376.337068)
		(end 321.874896 -376.385328)
		(width 0.14224)
		(layer "In6.Cu")
		(net "P5E_CPU0_P0_TX_DN<12>")
	)
	(segment
		(start 356.543356 -285.748222)
		(end 356.544118 -285.74873)
		(width 0.1143)
		(layer "In6.Cu")
		(net "P5E_CPU0_P0_TX_DN<12>")
	)
	(segment
		(start 356.583234 -289.940492)
		(end 356.544118 -289.963352)
		(width 0.1143)
		(layer "In6.Cu")
		(net "P5E_CPU0_P0_TX_DN<12>")
	)
	(segment
		(start 356.527354 -289.973258)
		(end 356.512368 -289.98164)
		(width 0.1143)
		(layer "In6.Cu")
		(net "P5E_CPU0_P0_TX_DN<12>")
	)
	(segment
		(start 356.544118 -293.848536)
		(end 356.545134 -293.849044)
		(width 0.1143)
		(layer "In6.Cu")
		(net "P5E_CPU0_P0_TX_DN<12>")
	)
	(segment
		(start 356.543356 -294.823896)
		(end 356.542086 -294.824658)
		(width 0.1143)
		(layer "In6.Cu")
		(net "P5E_CPU0_P0_TX_DN<12>")
	)
	(segment
		(start 356.583234 -294.800528)
		(end 356.545134 -294.82288)
		(width 0.1143)
		(layer "In6.Cu")
		(net "P5E_CPU0_P0_TX_DN<12>")
	)
	(segment
		(start 356.544118 -292.228524)
		(end 356.545134 -292.229032)
		(width 0.1143)
		(layer "In6.Cu")
		(net "P5E_CPU0_P0_TX_DN<12>")
	)
	(segment
		(start 356.544118 -294.823388)
		(end 356.543356 -294.823896)
		(width 0.1143)
		(layer "In6.Cu")
		(net "P5E_CPU0_P0_TX_DN<12>")
	)
	(segment
		(start 356.546658 -293.85006)
		(end 356.547674 -293.850568)
		(width 0.1143)
		(layer "In6.Cu")
		(net "P5E_CPU0_P0_TX_DN<12>")
	)
	(segment
		(start 356.545134 -294.82288)
		(end 356.544118 -294.823388)
		(width 0.1143)
		(layer "In6.Cu")
		(net "P5E_CPU0_P0_TX_DN<12>")
	)
	(segment
		(start 356.043484 -284.920944)
		(end 356.073964 -284.938724)
		(width 0.1143)
		(layer "In6.Cu")
		(net "P5E_CPU0_P0_TX_DN<12>")
	)
	(segment
		(start 356.544118 -290.608512)
		(end 356.545134 -290.60902)
		(width 0.1143)
		(layer "In6.Cu")
		(net "P5E_CPU0_P0_TX_DN<12>")
	)
	(segment
		(start 356.539292 -289.966146)
		(end 356.53853 -289.966654)
		(width 0.1143)
		(layer "In6.Cu")
		(net "P5E_CPU0_P0_TX_DN<12>")
	)
	(segment
		(start 356.543356 -288.987992)
		(end 356.544118 -288.9885)
		(width 0.1143)
		(layer "In6.Cu")
		(net "P5E_CPU0_P0_TX_DN<12>")
	)
	(segment
		(start 356.527354 -293.213282)
		(end 356.512368 -293.221664)
		(width 0.1143)
		(layer "In6.Cu")
		(net "P5E_CPU0_P0_TX_DN<12>")
	)
	(segment
		(start 356.545134 -290.60902)
		(end 356.546658 -290.610036)
		(width 0.1143)
		(layer "In6.Cu")
		(net "P5E_CPU0_P0_TX_DN<12>")
	)
	(segment
		(start 356.543356 -290.608004)
		(end 356.544118 -290.608512)
		(width 0.1143)
		(layer "In6.Cu")
		(net "P5E_CPU0_P0_TX_DN<12>")
	)
	(segment
		(start 370.478304 -320.341752)
		(end 374.173496 -327.41108)
		(width 0.14224)
		(layer "In6.Cu")
		(net "P5E_CPU0_P0_TX_DN<12>")
	)
	(segment
		(start 356.512368 -287.3502)
		(end 356.544118 -287.368488)
		(width 0.1143)
		(layer "In6.Cu")
		(net "P5E_CPU0_P0_TX_DN<12>")
	)
	(segment
		(start 356.527354 -291.59327)
		(end 356.512368 -291.601652)
		(width 0.1143)
		(layer "In6.Cu")
		(net "P5E_CPU0_P0_TX_DN<12>")
	)
	(segment
		(start 359.926636 -376.257566)
		(end 322.392294 -376.257566)
		(width 0.14224)
		(layer "In6.Cu")
		(net "P5E_CPU0_P0_TX_DN<12>")
	)
	(segment
		(start 356.542086 -291.584634)
		(end 356.540562 -291.585396)
		(width 0.1143)
		(layer "In6.Cu")
		(net "P5E_CPU0_P0_TX_DN<12>")
	)
	(segment
		(start 356.540562 -293.205408)
		(end 356.539292 -293.20617)
		(width 0.1143)
		(layer "In6.Cu")
		(net "P5E_CPU0_P0_TX_DN<12>")
	)
	(segment
		(start 356.512368 -292.210236)
		(end 356.543356 -292.228016)
		(width 0.1143)
		(layer "In6.Cu")
		(net "P5E_CPU0_P0_TX_DN<12>")
	)
	(segment
		(start 356.540562 -294.82542)
		(end 356.538022 -294.826944)
		(width 0.1143)
		(layer "In6.Cu")
		(net "P5E_CPU0_P0_TX_DN<12>")
	)
	(segment
		(start 356.546658 -290.610036)
		(end 356.547674 -290.610544)
		(width 0.1143)
		(layer "In6.Cu")
		(net "P5E_CPU0_P0_TX_DN<12>")
	)
	(segment
		(start 356.401878 -295.536366)
		(end 356.401878 -295.564814)
		(width 0.1143)
		(layer "In6.Cu")
		(net "P5E_CPU0_P0_TX_DN<12>")
	)
	(segment
		(start 369.382548 -368.163348)
		(end 362.251244 -375.294652)
		(width 0.14224)
		(layer "In6.Cu")
		(net "P5E_CPU0_P0_TX_DN<12>")
	)
	(segment
		(start 356.512368 -293.830248)
		(end 356.543356 -293.848028)
		(width 0.1143)
		(layer "In6.Cu")
		(net "P5E_CPU0_P0_TX_DN<12>")
	)
	(segment
		(start 356.583234 -288.320734)
		(end 356.544118 -288.343594)
		(width 0.1143)
		(layer "In6.Cu")
		(net "P5E_CPU0_P0_TX_DN<12>")
	)
	(segment
		(start 356.583234 -293.180516)
		(end 356.544118 -293.203376)
		(width 0.1143)
		(layer "In6.Cu")
		(net "P5E_CPU0_P0_TX_DN<12>")
	)
	(segment
		(start 356.543356 -289.96386)
		(end 356.542086 -289.964622)
		(width 0.1143)
		(layer "In6.Cu")
		(net "P5E_CPU0_P0_TX_DN<12>")
	)
	(segment
		(start 356.529386 -291.592)
		(end 356.527354 -291.59327)
		(width 0.1143)
		(layer "In6.Cu")
		(net "P5E_CPU0_P0_TX_DN<12>")
	)
	(segment
		(start 355.321108 -282.996132)
		(end 355.023166 -282.996132)
		(width 0.1143)
		(layer "In6.Cu")
		(net "P5E_CPU0_P0_TX_DN<12>")
	)
	(segment
		(start 355.023166 -282.996132)
		(end 354.953316 -283.065982)
		(width 0.1143)
		(layer "In6.Cu")
		(net "P5E_CPU0_P0_TX_DN<12>")
	)
	(segment
		(start 356.546658 -288.990024)
		(end 356.547674 -288.990532)
		(width 0.1143)
		(layer "In6.Cu")
		(net "P5E_CPU0_P0_TX_DN<12>")
	)
	(segment
		(start 356.401878 -298.74972)
		(end 358.810052 -304.563526)
		(width 0.14224)
		(layer "In6.Cu")
		(net "P5E_CPU0_P0_TX_DN<12>")
	)
	(segment
		(start 356.401878 -295.564814)
		(end 356.401878 -298.74972)
		(width 0.14224)
		(layer "In6.Cu")
		(net "P5E_CPU0_P0_TX_DN<12>")
	)
	(segment
		(start 356.542086 -293.204646)
		(end 356.540562 -293.205408)
		(width 0.1143)
		(layer "In6.Cu")
		(net "P5E_CPU0_P0_TX_DN<12>")
	)
	(segment
		(start 356.542086 -289.964622)
		(end 356.540562 -289.965384)
		(width 0.1143)
		(layer "In6.Cu")
		(net "P5E_CPU0_P0_TX_DN<12>")
	)
	(segment
		(start 356.53853 -291.586666)
		(end 356.535228 -291.588698)
		(width 0.1143)
		(layer "In6.Cu")
		(net "P5E_CPU0_P0_TX_DN<12>")
	)
	(segment
		(start 356.544118 -289.963352)
		(end 356.543356 -289.96386)
		(width 0.1143)
		(layer "In6.Cu")
		(net "P5E_CPU0_P0_TX_DN<12>")
	)
	(segment
		(start 356.512368 -285.730442)
		(end 356.543356 -285.748222)
		(width 0.1143)
		(layer "In6.Cu")
		(net "P5E_CPU0_P0_TX_DN<12>")
	)
	(segment
		(start 356.543356 -293.848028)
		(end 356.544118 -293.848536)
		(width 0.1143)
		(layer "In6.Cu")
		(net "P5E_CPU0_P0_TX_DN<12>")
	)
	(segment
		(start 356.540562 -291.585396)
		(end 356.539292 -291.586158)
		(width 0.1143)
		(layer "In6.Cu")
		(net "P5E_CPU0_P0_TX_DN<12>")
	)
	(segment
		(start 356.538022 -294.826944)
		(end 356.537006 -294.827452)
		(width 0.1143)
		(layer "In6.Cu")
		(net "P5E_CPU0_P0_TX_DN<12>")
	)
	(segment
		(start 356.547674 -290.610544)
		(end 356.583234 -290.631372)
		(width 0.1143)
		(layer "In6.Cu")
		(net "P5E_CPU0_P0_TX_DN<12>")
	)
	(segment
		(start 356.529386 -289.971988)
		(end 356.527354 -289.973258)
		(width 0.1143)
		(layer "In6.Cu")
		(net "P5E_CPU0_P0_TX_DN<12>")
	)
	(segment
		(start 356.544118 -285.74873)
		(end 356.545134 -285.749238)
		(width 0.1143)
		(layer "In6.Cu")
		(net "P5E_CPU0_P0_TX_DN<12>")
	)
	(segment
		(start 358.810052 -304.563526)
		(end 364.422944 -312.963306)
		(width 0.14224)
		(layer "In6.Cu")
		(net "P5E_CPU0_P0_TX_DN<12>")
	)
	(segment
		(start 356.547674 -288.990532)
		(end 356.583234 -289.01136)
		(width 0.1143)
		(layer "In6.Cu")
		(net "P5E_CPU0_P0_TX_DN<12>")
	)
	(segment
		(start 356.356412 -295.145968)
		(end 356.356412 -295.490392)
		(width 0.1143)
		(layer "In6.Cu")
		(net "P5E_CPU0_P0_TX_DN<12>")
	)
	(segment
		(start 356.537006 -294.827452)
		(end 356.512368 -294.841676)
		(width 0.1143)
		(layer "In6.Cu")
		(net "P5E_CPU0_P0_TX_DN<12>")
	)
	(segment
		(start 356.543356 -292.228016)
		(end 356.544118 -292.228524)
		(width 0.1143)
		(layer "In6.Cu")
		(net "P5E_CPU0_P0_TX_DN<12>")
	)
	(arc
		(start 356.356412 -288.66592)
		(mid 356.397667 -288.836891)
		(end 356.512368 -288.970212)
		(width 0.1143)
		(layer "In6.Cu")
		(net "P5E_CPU0_P0_TX_DN<12>")
	)
	(arc
		(start 356.356412 -287.045908)
		(mid 356.397667 -287.216879)
		(end 356.512368 -287.3502)
		(width 0.1143)
		(layer "In6.Cu")
		(net "P5E_CPU0_P0_TX_DN<12>")
	)
	(arc
		(start 355.412802 -283.77134)
		(mid 355.415146 -283.79352)
		(end 355.416358 -283.81579)
		(width 0.1143)
		(layer "In6.Cu")
		(net "P5E_CPU0_P0_TX_DN<12>")
	)
	(arc
		(start 355.64318 -284.151578)
		(mid 355.821993 -284.353928)
		(end 355.886512 -284.616144)
		(width 0.1143)
		(layer "In6.Cu")
		(net "P5E_CPU0_P0_TX_DN<12>")
	)
	(arc
		(start 356.826566 -287.856168)
		(mid 356.762051 -288.118387)
		(end 356.583234 -288.320734)
		(width 0.1143)
		(layer "In6.Cu")
		(net "P5E_CPU0_P0_TX_DN<12>")
	)
	(arc
		(start 356.583234 -293.871396)
		(mid 356.826561 -294.335962)
		(end 356.583234 -294.800528)
		(width 0.1143)
		(layer "In6.Cu")
		(net "P5E_CPU0_P0_TX_DN<12>")
	)
	(arc
		(start 356.583234 -285.77159)
		(mid 356.826561 -286.236156)
		(end 356.583234 -286.700722)
		(width 0.1143)
		(layer "In6.Cu")
		(net "P5E_CPU0_P0_TX_DN<12>")
	)
	(arc
		(start 362.251244 -375.294652)
		(mid 361.184705 -376.007291)
		(end 359.926636 -376.257566)
		(width 0.14224)
		(layer "In6.Cu")
		(net "P5E_CPU0_P0_TX_DN<12>")
	)
	(arc
		(start 356.580694 -287.389824)
		(mid 356.761346 -287.592569)
		(end 356.826566 -287.856168)
		(width 0.1143)
		(layer "In6.Cu")
		(net "P5E_CPU0_P0_TX_DN<12>")
	)
	(arc
		(start 356.583234 -289.01136)
		(mid 356.826561 -289.475926)
		(end 356.583234 -289.940492)
		(width 0.1143)
		(layer "In6.Cu")
		(net "P5E_CPU0_P0_TX_DN<12>")
	)
	(arc
		(start 356.512368 -294.841676)
		(mid 356.397692 -294.97501)
		(end 356.356412 -295.145968)
		(width 0.1143)
		(layer "In6.Cu")
		(net "P5E_CPU0_P0_TX_DN<12>")
	)
	(arc
		(start 356.51059 -288.363152)
		(mid 356.397183 -288.496041)
		(end 356.356412 -288.66592)
		(width 0.1143)
		(layer "In6.Cu")
		(net "P5E_CPU0_P0_TX_DN<12>")
	)
	(arc
		(start 356.11308 -284.961584)
		(mid 356.291893 -285.163934)
		(end 356.356412 -285.42615)
		(width 0.1143)
		(layer "In6.Cu")
		(net "P5E_CPU0_P0_TX_DN<12>")
	)
	(arc
		(start 355.886512 -284.616144)
		(mid 355.928061 -284.787566)
		(end 356.043484 -284.920944)
		(width 0.1143)
		(layer "In6.Cu")
		(net "P5E_CPU0_P0_TX_DN<12>")
	)
	(arc
		(start 356.51059 -286.74314)
		(mid 356.397183 -286.876029)
		(end 356.356412 -287.045908)
		(width 0.1143)
		(layer "In6.Cu")
		(net "P5E_CPU0_P0_TX_DN<12>")
	)
	(arc
		(start 356.583234 -290.631372)
		(mid 356.826561 -291.095938)
		(end 356.583234 -291.560504)
		(width 0.1143)
		(layer "In6.Cu")
		(net "P5E_CPU0_P0_TX_DN<12>")
	)
	(arc
		(start 356.512368 -291.601652)
		(mid 356.35644 -291.905944)
		(end 356.512368 -292.210236)
		(width 0.1143)
		(layer "In6.Cu")
		(net "P5E_CPU0_P0_TX_DN<12>")
	)
	(arc
		(start 376.555762 -350.845628)
		(mid 374.691501 -360.217903)
		(end 369.382548 -368.163348)
		(width 0.14224)
		(layer "In6.Cu")
		(net "P5E_CPU0_P0_TX_DN<12>")
	)
	(arc
		(start 355.416358 -283.81579)
		(mid 355.459751 -283.981422)
		(end 355.572314 -284.11043)
		(width 0.1143)
		(layer "In6.Cu")
		(net "P5E_CPU0_P0_TX_DN<12>")
	)
	(arc
		(start 321.874896 -376.385328)
		(mid 321.755896 -376.482481)
		(end 321.711066 -376.629422)
		(width 0.14224)
		(layer "In6.Cu")
		(net "P5E_CPU0_P0_TX_DN<12>")
	)
	(arc
		(start 355.171248 -283.340302)
		(mid 355.332462 -283.53316)
		(end 355.412802 -283.77134)
		(width 0.1143)
		(layer "In6.Cu")
		(net "P5E_CPU0_P0_TX_DN<12>")
	)
	(arc
		(start 354.953316 -283.065982)
		(mid 355.005365 -283.197501)
		(end 355.102414 -283.300424)
		(width 0.1143)
		(layer "In6.Cu")
		(net "P5E_CPU0_P0_TX_DN<12>")
	)
	(arc
		(start 356.512368 -289.98164)
		(mid 356.35644 -290.285932)
		(end 356.512368 -290.590224)
		(width 0.1143)
		(layer "In6.Cu")
		(net "P5E_CPU0_P0_TX_DN<12>")
	)
	(arc
		(start 356.583234 -292.251384)
		(mid 356.826561 -292.71595)
		(end 356.583234 -293.180516)
		(width 0.1143)
		(layer "In6.Cu")
		(net "P5E_CPU0_P0_TX_DN<12>")
	)
	(arc
		(start 356.356412 -285.42615)
		(mid 356.397667 -285.597121)
		(end 356.512368 -285.730442)
		(width 0.1143)
		(layer "In6.Cu")
		(net "P5E_CPU0_P0_TX_DN<12>")
	)
	(arc
		(start 356.512368 -293.221664)
		(mid 356.35644 -293.525956)
		(end 356.512368 -293.830248)
		(width 0.1143)
		(layer "In6.Cu")
		(net "P5E_CPU0_P0_TX_DN<12>")
	)
	(arc
		(start 322.392294 -376.257566)
		(mid 322.188108 -376.277645)
		(end 321.991736 -376.337068)
		(width 0.14224)
		(layer "In6.Cu")
		(net "P5E_CPU0_P0_TX_DN<12>")
	)
	(segment
		(start 320.325496 -381.15113)
		(end 320.029586 -380.85522)
		(width 0.12954)
		(layer "F.Cu")
		(net "P5E_CPU0_P0_TX_DN<11>")
	)
	(segment
		(start 320.029586 -380.85522)
		(end 320.029586 -380.15164)
		(width 0.12954)
		(layer "F.Cu")
		(net "P5E_CPU0_P0_TX_DN<11>")
	)
	(segment
		(start 355.78796 -285.970218)
		(end 355.321108 -286.236156)
		(width 0.12954)
		(layer "F.Cu")
		(net "P5E_CPU0_P0_TX_DN<11>")
	)
	(segment
		(start 320.029586 -380.15164)
		(end 320.300096 -379.88113)
		(width 0.12954)
		(layer "F.Cu")
		(net "P5E_CPU0_P0_TX_DN<11>")
	)
	(segment
		(start 355.604572 -288.343086)
		(end 355.59111 -288.350706)
		(width 0.1143)
		(layer "In6.Cu")
		(net "P5E_CPU0_P0_TX_DN<11>")
	)
	(segment
		(start 355.64318 -293.180516)
		(end 355.640386 -293.182548)
		(width 0.1143)
		(layer "In6.Cu")
		(net "P5E_CPU0_P0_TX_DN<11>")
	)
	(segment
		(start 359.238296 -375.322592)
		(end 322.308982 -375.322592)
		(width 0.14224)
		(layer "In6.Cu")
		(net "P5E_CPU0_P0_TX_DN<11>")
	)
	(segment
		(start 355.625146 -291.571172)
		(end 355.624892 -291.571172)
		(width 0.1143)
		(layer "In6.Cu")
		(net "P5E_CPU0_P0_TX_DN<11>")
	)
	(segment
		(start 355.64318 -291.560504)
		(end 355.625146 -291.571172)
		(width 0.1143)
		(layer "In6.Cu")
		(net "P5E_CPU0_P0_TX_DN<11>")
	)
	(segment
		(start 355.608636 -292.231064)
		(end 355.609398 -292.231572)
		(width 0.1143)
		(layer "In6.Cu")
		(net "P5E_CPU0_P0_TX_DN<11>")
	)
	(segment
		(start 355.59111 -288.350706)
		(end 355.590856 -288.35096)
		(width 0.1143)
		(layer "In6.Cu")
		(net "P5E_CPU0_P0_TX_DN<11>")
	)
	(segment
		(start 355.640386 -293.182548)
		(end 355.604064 -293.203376)
		(width 0.1143)
		(layer "In6.Cu")
		(net "P5E_CPU0_P0_TX_DN<11>")
	)
	(segment
		(start 373.709946 -328.942192)
		(end 375.577608 -339.338158)
		(width 0.14224)
		(layer "In6.Cu")
		(net "P5E_CPU0_P0_TX_DN<11>")
	)
	(segment
		(start 363.669834 -313.515248)
		(end 369.695984 -320.858134)
		(width 0.14224)
		(layer "In6.Cu")
		(net "P5E_CPU0_P0_TX_DN<11>")
	)
	(segment
		(start 355.624892 -291.571172)
		(end 355.603556 -291.583618)
		(width 0.1143)
		(layer "In6.Cu")
		(net "P5E_CPU0_P0_TX_DN<11>")
	)
	(segment
		(start 355.610414 -292.23208)
		(end 355.642418 -292.250876)
		(width 0.1143)
		(layer "In6.Cu")
		(net "P5E_CPU0_P0_TX_DN<11>")
	)
	(segment
		(start 355.124004 -296.538142)
		(end 355.169724 -296.583862)
		(width 0.1143)
		(layer "In6.Cu")
		(net "P5E_CPU0_P0_TX_DN<11>")
	)
	(segment
		(start 355.169724 -296.61231)
		(end 355.169724 -298.210986)
		(width 0.14224)
		(layer "In6.Cu")
		(net "P5E_CPU0_P0_TX_DN<11>")
	)
	(segment
		(start 354.983796 -296.138346)
		(end 355.030786 -296.185336)
		(width 0.1143)
		(layer "In6.Cu")
		(net "P5E_CPU0_P0_TX_DN<11>")
	)
	(segment
		(start 355.590602 -288.98088)
		(end 355.59111 -288.981134)
		(width 0.1143)
		(layer "In6.Cu")
		(net "P5E_CPU0_P0_TX_DN<11>")
	)
	(segment
		(start 355.586284 -287.356804)
		(end 355.608382 -287.371282)
		(width 0.1143)
		(layer "In6.Cu")
		(net "P5E_CPU0_P0_TX_DN<11>")
	)
	(segment
		(start 355.604064 -293.848536)
		(end 355.64318 -293.871396)
		(width 0.1143)
		(layer "In6.Cu")
		(net "P5E_CPU0_P0_TX_DN<11>")
	)
	(segment
		(start 355.590602 -294.831008)
		(end 355.590348 -294.831262)
		(width 0.1143)
		(layer "In6.Cu")
		(net "P5E_CPU0_P0_TX_DN<11>")
	)
	(segment
		(start 355.610414 -290.612068)
		(end 355.642418 -290.630864)
		(width 0.1143)
		(layer "In6.Cu")
		(net "P5E_CPU0_P0_TX_DN<11>")
	)
	(segment
		(start 355.64318 -289.940492)
		(end 355.625146 -289.95116)
		(width 0.1143)
		(layer "In6.Cu")
		(net "P5E_CPU0_P0_TX_DN<11>")
	)
	(segment
		(start 320.009266 -377.109482)
		(end 320.009266 -379.5903)
		(width 0.14224)
		(layer "In6.Cu")
		(net "P5E_CPU0_P0_TX_DN<11>")
	)
	(segment
		(start 355.118924 -295.64203)
		(end 355.10724 -295.649142)
		(width 0.1143)
		(layer "In6.Cu")
		(net "P5E_CPU0_P0_TX_DN<11>")
	)
	(segment
		(start 355.604064 -293.203376)
		(end 355.572314 -293.221664)
		(width 0.1143)
		(layer "In6.Cu")
		(net "P5E_CPU0_P0_TX_DN<11>")
	)
	(segment
		(start 355.169724 -296.583862)
		(end 355.169724 -296.61231)
		(width 0.1143)
		(layer "In6.Cu")
		(net "P5E_CPU0_P0_TX_DN<11>")
	)
	(segment
		(start 355.169724 -298.210986)
		(end 357.984552 -305.00701)
		(width 0.14224)
		(layer "In6.Cu")
		(net "P5E_CPU0_P0_TX_DN<11>")
	)
	(segment
		(start 355.608636 -290.611052)
		(end 355.609398 -290.61156)
		(width 0.1143)
		(layer "In6.Cu")
		(net "P5E_CPU0_P0_TX_DN<11>")
	)
	(segment
		(start 355.59619 -290.60394)
		(end 355.608636 -290.611052)
		(width 0.1143)
		(layer "In6.Cu")
		(net "P5E_CPU0_P0_TX_DN<11>")
	)
	(segment
		(start 355.59111 -288.981134)
		(end 355.642418 -289.010852)
		(width 0.1143)
		(layer "In6.Cu")
		(net "P5E_CPU0_P0_TX_DN<11>")
	)
	(segment
		(start 355.64318 -288.320734)
		(end 355.637592 -288.323528)
		(width 0.1143)
		(layer "In6.Cu")
		(net "P5E_CPU0_P0_TX_DN<11>")
	)
	(segment
		(start 355.637592 -288.323528)
		(end 355.604572 -288.343086)
		(width 0.1143)
		(layer "In6.Cu")
		(net "P5E_CPU0_P0_TX_DN<11>")
	)
	(segment
		(start 355.59619 -292.223952)
		(end 355.608636 -292.231064)
		(width 0.1143)
		(layer "In6.Cu")
		(net "P5E_CPU0_P0_TX_DN<11>")
	)
	(segment
		(start 355.124004 -296.410126)
		(end 355.124004 -296.538142)
		(width 0.1143)
		(layer "In6.Cu")
		(net "P5E_CPU0_P0_TX_DN<11>")
	)
	(segment
		(start 368.730276 -367.495074)
		(end 362.079794 -374.145556)
		(width 0.14224)
		(layer "In6.Cu")
		(net "P5E_CPU0_P0_TX_DN<11>")
	)
	(segment
		(start 355.133656 -295.633394)
		(end 355.119686 -295.641522)
		(width 0.1143)
		(layer "In6.Cu")
		(net "P5E_CPU0_P0_TX_DN<11>")
	)
	(segment
		(start 373.309388 -327.770998)
		(end 373.709946 -328.942192)
		(width 0.14224)
		(layer "In6.Cu")
		(net "P5E_CPU0_P0_TX_DN<11>")
	)
	(segment
		(start 355.10724 -295.649142)
		(end 355.103938 -295.65092)
		(width 0.1143)
		(layer "In6.Cu")
		(net "P5E_CPU0_P0_TX_DN<11>")
	)
	(segment
		(start 355.106732 -286.542226)
		(end 355.161596 -286.574738)
		(width 0.1143)
		(layer "In6.Cu")
		(net "P5E_CPU0_P0_TX_DN<11>")
	)
	(segment
		(start 355.625146 -289.95116)
		(end 355.624892 -289.95116)
		(width 0.1143)
		(layer "In6.Cu")
		(net "P5E_CPU0_P0_TX_DN<11>")
	)
	(segment
		(start 355.572314 -293.830248)
		(end 355.604064 -293.848536)
		(width 0.1143)
		(layer "In6.Cu")
		(net "P5E_CPU0_P0_TX_DN<11>")
	)
	(segment
		(start 354.946458 -295.955974)
		(end 354.946458 -296.04843)
		(width 0.1143)
		(layer "In6.Cu")
		(net "P5E_CPU0_P0_TX_DN<11>")
	)
	(segment
		(start 369.695984 -320.858134)
		(end 373.309388 -327.770998)
		(width 0.14224)
		(layer "In6.Cu")
		(net "P5E_CPU0_P0_TX_DN<11>")
	)
	(segment
		(start 355.023166 -286.236156)
		(end 354.953316 -286.306006)
		(width 0.1143)
		(layer "In6.Cu")
		(net "P5E_CPU0_P0_TX_DN<11>")
	)
	(segment
		(start 357.984552 -305.00701)
		(end 363.669834 -313.515248)
		(width 0.14224)
		(layer "In6.Cu")
		(net "P5E_CPU0_P0_TX_DN<11>")
	)
	(segment
		(start 355.624892 -289.95116)
		(end 355.603556 -289.963606)
		(width 0.1143)
		(layer "In6.Cu")
		(net "P5E_CPU0_P0_TX_DN<11>")
	)
	(segment
		(start 355.608382 -287.371282)
		(end 355.642418 -287.391094)
		(width 0.1143)
		(layer "In6.Cu")
		(net "P5E_CPU0_P0_TX_DN<11>")
	)
	(segment
		(start 355.642418 -287.391094)
		(end 355.642418 -287.39084)
		(width 0.1143)
		(layer "In6.Cu")
		(net "P5E_CPU0_P0_TX_DN<11>")
	)
	(segment
		(start 355.609398 -292.231572)
		(end 355.610414 -292.23208)
		(width 0.1143)
		(layer "In6.Cu")
		(net "P5E_CPU0_P0_TX_DN<11>")
	)
	(segment
		(start 355.161596 -286.574738)
		(end 355.1682 -286.578294)
		(width 0.1143)
		(layer "In6.Cu")
		(net "P5E_CPU0_P0_TX_DN<11>")
	)
	(segment
		(start 355.609398 -290.61156)
		(end 355.610414 -290.612068)
		(width 0.1143)
		(layer "In6.Cu")
		(net "P5E_CPU0_P0_TX_DN<11>")
	)
	(segment
		(start 375.577608 -339.338158)
		(end 375.577608 -350.963992)
		(width 0.14224)
		(layer "In6.Cu")
		(net "P5E_CPU0_P0_TX_DN<11>")
	)
	(segment
		(start 320.009266 -379.5903)
		(end 320.300096 -379.88113)
		(width 0.14224)
		(layer "In6.Cu")
		(net "P5E_CPU0_P0_TX_DN<11>")
	)
	(segment
		(start 355.403658 -295.155366)
		(end 355.403658 -295.16578)
		(width 0.1143)
		(layer "In6.Cu")
		(net "P5E_CPU0_P0_TX_DN<11>")
	)
	(segment
		(start 355.119686 -295.641522)
		(end 355.118924 -295.64203)
		(width 0.1143)
		(layer "In6.Cu")
		(net "P5E_CPU0_P0_TX_DN<11>")
	)
	(segment
		(start 355.64318 -294.800528)
		(end 355.590602 -294.831008)
		(width 0.1143)
		(layer "In6.Cu")
		(net "P5E_CPU0_P0_TX_DN<11>")
	)
	(segment
		(start 355.321108 -286.236156)
		(end 355.023166 -286.236156)
		(width 0.1143)
		(layer "In6.Cu")
		(net "P5E_CPU0_P0_TX_DN<11>")
	)
	(arc
		(start 355.590348 -294.831262)
		(mid 355.453659 -294.968349)
		(end 355.403658 -295.155366)
		(width 0.1143)
		(layer "In6.Cu")
		(net "P5E_CPU0_P0_TX_DN<11>")
	)
	(arc
		(start 355.64318 -289.01136)
		(mid 355.886507 -289.475926)
		(end 355.64318 -289.940492)
		(width 0.1143)
		(layer "In6.Cu")
		(net "P5E_CPU0_P0_TX_DN<11>")
	)
	(arc
		(start 355.030786 -296.185336)
		(mid 355.099752 -296.288456)
		(end 355.124004 -296.410126)
		(width 0.1143)
		(layer "In6.Cu")
		(net "P5E_CPU0_P0_TX_DN<11>")
	)
	(arc
		(start 362.079794 -374.145556)
		(mid 360.776118 -375.016708)
		(end 359.238296 -375.322592)
		(width 0.14224)
		(layer "In6.Cu")
		(net "P5E_CPU0_P0_TX_DN<11>")
	)
	(arc
		(start 355.418136 -287.054036)
		(mid 355.453274 -287.179295)
		(end 355.520752 -287.29051)
		(width 0.1143)
		(layer "In6.Cu")
		(net "P5E_CPU0_P0_TX_DN<11>")
	)
	(arc
		(start 375.577608 -350.963992)
		(mid 373.798047 -359.910538)
		(end 368.730276 -367.495074)
		(width 0.14224)
		(layer "In6.Cu")
		(net "P5E_CPU0_P0_TX_DN<11>")
	)
	(arc
		(start 355.642418 -287.39084)
		(mid 355.88659 -287.855638)
		(end 355.64318 -288.320734)
		(width 0.1143)
		(layer "In6.Cu")
		(net "P5E_CPU0_P0_TX_DN<11>")
	)
	(arc
		(start 355.416358 -287.028128)
		(mid 355.416901 -287.041106)
		(end 355.418136 -287.054036)
		(width 0.1143)
		(layer "In6.Cu")
		(net "P5E_CPU0_P0_TX_DN<11>")
	)
	(arc
		(start 355.642418 -292.250876)
		(mid 355.642799 -292.25113)
		(end 355.64318 -292.251384)
		(width 0.1143)
		(layer "In6.Cu")
		(net "P5E_CPU0_P0_TX_DN<11>")
	)
	(arc
		(start 355.590856 -288.35096)
		(mid 355.409532 -288.66581)
		(end 355.590602 -288.98088)
		(width 0.1143)
		(layer "In6.Cu")
		(net "P5E_CPU0_P0_TX_DN<11>")
	)
	(arc
		(start 321.464432 -375.543318)
		(mid 320.923559 -375.877947)
		(end 320.413634 -376.258074)
		(width 0.14224)
		(layer "In6.Cu")
		(net "P5E_CPU0_P0_TX_DN<11>")
	)
	(arc
		(start 355.64318 -292.251384)
		(mid 355.886507 -292.71595)
		(end 355.64318 -293.180516)
		(width 0.1143)
		(layer "In6.Cu")
		(net "P5E_CPU0_P0_TX_DN<11>")
	)
	(arc
		(start 355.64318 -290.631372)
		(mid 355.886507 -291.095938)
		(end 355.64318 -291.560504)
		(width 0.1143)
		(layer "In6.Cu")
		(net "P5E_CPU0_P0_TX_DN<11>")
	)
	(arc
		(start 354.953316 -286.306006)
		(mid 354.952296 -286.306377)
		(end 354.951284 -286.306768)
		(width 0.1143)
		(layer "In6.Cu")
		(net "P5E_CPU0_P0_TX_DN<11>")
	)
	(arc
		(start 355.1682 -286.578294)
		(mid 355.346339 -286.773378)
		(end 355.416358 -287.028128)
		(width 0.1143)
		(layer "In6.Cu")
		(net "P5E_CPU0_P0_TX_DN<11>")
	)
	(arc
		(start 354.946458 -296.04843)
		(mid 354.95616 -296.097114)
		(end 354.983796 -296.138346)
		(width 0.1143)
		(layer "In6.Cu")
		(net "P5E_CPU0_P0_TX_DN<11>")
	)
	(arc
		(start 355.520752 -287.29051)
		(mid 355.551907 -287.32525)
		(end 355.586284 -287.356804)
		(width 0.1143)
		(layer "In6.Cu")
		(net "P5E_CPU0_P0_TX_DN<11>")
	)
	(arc
		(start 355.572314 -293.221664)
		(mid 355.421929 -293.525956)
		(end 355.572314 -293.830248)
		(width 0.1143)
		(layer "In6.Cu")
		(net "P5E_CPU0_P0_TX_DN<11>")
	)
	(arc
		(start 322.308982 -375.322592)
		(mid 321.872525 -375.378705)
		(end 321.464432 -375.543318)
		(width 0.14224)
		(layer "In6.Cu")
		(net "P5E_CPU0_P0_TX_DN<11>")
	)
	(arc
		(start 320.413634 -376.258074)
		(mid 320.115459 -376.638185)
		(end 320.009266 -377.109482)
		(width 0.14224)
		(layer "In6.Cu")
		(net "P5E_CPU0_P0_TX_DN<11>")
	)
	(arc
		(start 354.951284 -286.306768)
		(mid 354.95569 -286.320673)
		(end 354.959666 -286.334708)
		(width 0.1143)
		(layer "In6.Cu")
		(net "P5E_CPU0_P0_TX_DN<11>")
	)
	(arc
		(start 355.64318 -293.871396)
		(mid 355.886507 -294.335962)
		(end 355.64318 -294.800528)
		(width 0.1143)
		(layer "In6.Cu")
		(net "P5E_CPU0_P0_TX_DN<11>")
	)
	(arc
		(start 354.959666 -286.334708)
		(mid 355.015046 -286.451327)
		(end 355.106732 -286.542226)
		(width 0.1143)
		(layer "In6.Cu")
		(net "P5E_CPU0_P0_TX_DN<11>")
	)
	(arc
		(start 355.642418 -289.010852)
		(mid 355.642799 -289.011106)
		(end 355.64318 -289.01136)
		(width 0.1143)
		(layer "In6.Cu")
		(net "P5E_CPU0_P0_TX_DN<11>")
	)
	(arc
		(start 355.403658 -295.16578)
		(mid 355.331317 -295.435773)
		(end 355.133656 -295.633394)
		(width 0.1143)
		(layer "In6.Cu")
		(net "P5E_CPU0_P0_TX_DN<11>")
	)
	(arc
		(start 355.103938 -295.65092)
		(mid 354.988193 -295.784346)
		(end 354.946458 -295.955974)
		(width 0.1143)
		(layer "In6.Cu")
		(net "P5E_CPU0_P0_TX_DN<11>")
	)
	(arc
		(start 355.642418 -290.630864)
		(mid 355.642799 -290.631118)
		(end 355.64318 -290.631372)
		(width 0.1143)
		(layer "In6.Cu")
		(net "P5E_CPU0_P0_TX_DN<11>")
	)
	(arc
		(start 355.603556 -291.583618)
		(mid 355.418036 -291.901675)
		(end 355.59619 -292.223952)
		(width 0.1143)
		(layer "In6.Cu")
		(net "P5E_CPU0_P0_TX_DN<11>")
	)
	(arc
		(start 355.603556 -289.963606)
		(mid 355.418036 -290.281663)
		(end 355.59619 -290.60394)
		(width 0.1143)
		(layer "In6.Cu")
		(net "P5E_CPU0_P0_TX_DN<11>")
	)
	(segment
		(start 318.623696 -383.61493)
		(end 318.327786 -383.31902)
		(width 0.12954)
		(layer "F.Cu")
		(net "P5E_CPU0_P0_TX_DN<10>")
	)
	(segment
		(start 355.78796 -284.350206)
		(end 355.321108 -284.616144)
		(width 0.12954)
		(layer "F.Cu")
		(net "P5E_CPU0_P0_TX_DN<10>")
	)
	(segment
		(start 318.327786 -382.61544)
		(end 318.598296 -382.34493)
		(width 0.12954)
		(layer "F.Cu")
		(net "P5E_CPU0_P0_TX_DN<10>")
	)
	(segment
		(start 318.327786 -383.31902)
		(end 318.327786 -382.61544)
		(width 0.12954)
		(layer "F.Cu")
		(net "P5E_CPU0_P0_TX_DN<10>")
	)
	(segment
		(start 354.63353 -293.830756)
		(end 354.66401 -293.848536)
		(width 0.1143)
		(layer "In6.Cu")
		(net "P5E_CPU0_P0_TX_DN<10>")
	)
	(segment
		(start 357.158544 -305.449478)
		(end 362.92028 -314.07227)
		(width 0.14224)
		(layer "In6.Cu")
		(net "P5E_CPU0_P0_TX_DN<10>")
	)
	(segment
		(start 354.138992 -298.159932)
		(end 357.158544 -305.449478)
		(width 0.14224)
		(layer "In6.Cu")
		(net "P5E_CPU0_P0_TX_DN<10>")
	)
	(segment
		(start 354.63353 -292.210744)
		(end 354.66401 -292.228524)
		(width 0.1143)
		(layer "In6.Cu")
		(net "P5E_CPU0_P0_TX_DN<10>")
	)
	(segment
		(start 354.189538 -285.916116)
		(end 354.188014 -285.917132)
		(width 0.1143)
		(layer "In6.Cu")
		(net "P5E_CPU0_P0_TX_DN<10>")
	)
	(segment
		(start 354.703126 -293.180516)
		(end 354.66401 -293.203376)
		(width 0.1143)
		(layer "In6.Cu")
		(net "P5E_CPU0_P0_TX_DN<10>")
	)
	(segment
		(start 354.476558 -295.145968)
		(end 354.476304 -295.146222)
		(width 0.1143)
		(layer "In6.Cu")
		(net "P5E_CPU0_P0_TX_DN<10>")
	)
	(segment
		(start 354.138992 -296.252646)
		(end 354.138992 -296.281094)
		(width 0.1143)
		(layer "In6.Cu")
		(net "P5E_CPU0_P0_TX_DN<10>")
	)
	(segment
		(start 354.703126 -289.940492)
		(end 354.66401 -289.963352)
		(width 0.1143)
		(layer "In6.Cu")
		(net "P5E_CPU0_P0_TX_DN<10>")
	)
	(segment
		(start 359.03916 -374.387618)
		(end 322.339208 -374.387618)
		(width 0.14224)
		(layer "In6.Cu")
		(net "P5E_CPU0_P0_TX_DN<10>")
	)
	(segment
		(start 354.66401 -294.823388)
		(end 354.63353 -294.841168)
		(width 0.1143)
		(layer "In6.Cu")
		(net "P5E_CPU0_P0_TX_DN<10>")
	)
	(segment
		(start 354.66401 -292.228524)
		(end 354.703126 -292.251384)
		(width 0.1143)
		(layer "In6.Cu")
		(net "P5E_CPU0_P0_TX_DN<10>")
	)
	(segment
		(start 354.703126 -294.800528)
		(end 354.66401 -294.823388)
		(width 0.1143)
		(layer "In6.Cu")
		(net "P5E_CPU0_P0_TX_DN<10>")
	)
	(segment
		(start 354.182934 -285.919926)
		(end 354.182172 -285.920434)
		(width 0.1143)
		(layer "In6.Cu")
		(net "P5E_CPU0_P0_TX_DN<10>")
	)
	(segment
		(start 354.373942 -295.581578)
		(end 354.152454 -295.803066)
		(width 0.1143)
		(layer "In6.Cu")
		(net "P5E_CPU0_P0_TX_DN<10>")
	)
	(segment
		(start 368.044984 -366.85982)
		(end 361.562142 -373.342662)
		(width 0.14224)
		(layer "In6.Cu")
		(net "P5E_CPU0_P0_TX_DN<10>")
	)
	(segment
		(start 374.645428 -340.355174)
		(end 374.645428 -350.925384)
		(width 0.14224)
		(layer "In6.Cu")
		(net "P5E_CPU0_P0_TX_DN<10>")
	)
	(segment
		(start 362.92028 -314.07227)
		(end 368.911124 -321.371468)
		(width 0.14224)
		(layer "In6.Cu")
		(net "P5E_CPU0_P0_TX_DN<10>")
	)
	(segment
		(start 354.703126 -288.320734)
		(end 354.66401 -288.343594)
		(width 0.1143)
		(layer "In6.Cu")
		(net "P5E_CPU0_P0_TX_DN<10>")
	)
	(segment
		(start 354.093272 -295.945306)
		(end 354.093272 -296.206926)
		(width 0.1143)
		(layer "In6.Cu")
		(net "P5E_CPU0_P0_TX_DN<10>")
	)
	(segment
		(start 318.307466 -377.754134)
		(end 318.307466 -381.987298)
		(width 0.14224)
		(layer "In6.Cu")
		(net "P5E_CPU0_P0_TX_DN<10>")
	)
	(segment
		(start 354.476304 -295.146222)
		(end 354.476304 -295.333928)
		(width 0.1143)
		(layer "In6.Cu")
		(net "P5E_CPU0_P0_TX_DN<10>")
	)
	(segment
		(start 368.911124 -321.371468)
		(end 372.45163 -328.145394)
		(width 0.14224)
		(layer "In6.Cu")
		(net "P5E_CPU0_P0_TX_DN<10>")
	)
	(segment
		(start 354.093272 -296.206926)
		(end 354.138992 -296.252646)
		(width 0.1143)
		(layer "In6.Cu")
		(net "P5E_CPU0_P0_TX_DN<10>")
	)
	(segment
		(start 354.703126 -285.08071)
		(end 354.63353 -285.12135)
		(width 0.1143)
		(layer "In6.Cu")
		(net "P5E_CPU0_P0_TX_DN<10>")
	)
	(segment
		(start 318.35471 -382.101344)
		(end 318.598296 -382.34493)
		(width 0.14224)
		(layer "In6.Cu")
		(net "P5E_CPU0_P0_TX_DN<10>")
	)
	(segment
		(start 354.63353 -290.590732)
		(end 354.66401 -290.608512)
		(width 0.1143)
		(layer "In6.Cu")
		(net "P5E_CPU0_P0_TX_DN<10>")
	)
	(segment
		(start 354.193348 -285.914084)
		(end 354.192078 -285.914846)
		(width 0.1143)
		(layer "In6.Cu")
		(net "P5E_CPU0_P0_TX_DN<10>")
	)
	(segment
		(start 354.188014 -285.917132)
		(end 354.18649 -285.917894)
		(width 0.1143)
		(layer "In6.Cu")
		(net "P5E_CPU0_P0_TX_DN<10>")
	)
	(segment
		(start 354.66401 -293.203376)
		(end 354.63353 -293.221156)
		(width 0.1143)
		(layer "In6.Cu")
		(net "P5E_CPU0_P0_TX_DN<10>")
	)
	(segment
		(start 354.185728 -285.918402)
		(end 354.184458 -285.919164)
		(width 0.1143)
		(layer "In6.Cu")
		(net "P5E_CPU0_P0_TX_DN<10>")
	)
	(segment
		(start 354.63353 -288.97072)
		(end 354.66401 -288.9885)
		(width 0.1143)
		(layer "In6.Cu")
		(net "P5E_CPU0_P0_TX_DN<10>")
	)
	(segment
		(start 354.233226 -285.890716)
		(end 354.19411 -285.913576)
		(width 0.1143)
		(layer "In6.Cu")
		(net "P5E_CPU0_P0_TX_DN<10>")
	)
	(segment
		(start 354.63353 -287.350708)
		(end 354.700586 -287.389824)
		(width 0.1143)
		(layer "In6.Cu")
		(net "P5E_CPU0_P0_TX_DN<10>")
	)
	(segment
		(start 321.254882 -374.603264)
		(end 320.090292 -375.08561)
		(width 0.14224)
		(layer "In6.Cu")
		(net "P5E_CPU0_P0_TX_DN<10>")
	)
	(segment
		(start 354.66401 -288.9885)
		(end 354.703126 -289.01136)
		(width 0.1143)
		(layer "In6.Cu")
		(net "P5E_CPU0_P0_TX_DN<10>")
	)
	(segment
		(start 354.66401 -289.963352)
		(end 354.63353 -289.981132)
		(width 0.1143)
		(layer "In6.Cu")
		(net "P5E_CPU0_P0_TX_DN<10>")
	)
	(segment
		(start 354.66401 -293.848536)
		(end 354.703126 -293.871396)
		(width 0.1143)
		(layer "In6.Cu")
		(net "P5E_CPU0_P0_TX_DN<10>")
	)
	(segment
		(start 354.182172 -285.920434)
		(end 354.180902 -285.921196)
		(width 0.1143)
		(layer "In6.Cu")
		(net "P5E_CPU0_P0_TX_DN<10>")
	)
	(segment
		(start 354.192078 -285.914846)
		(end 354.189538 -285.916116)
		(width 0.1143)
		(layer "In6.Cu")
		(net "P5E_CPU0_P0_TX_DN<10>")
	)
	(segment
		(start 355.321108 -284.616144)
		(end 355.023166 -284.616144)
		(width 0.1143)
		(layer "In6.Cu")
		(net "P5E_CPU0_P0_TX_DN<10>")
	)
	(segment
		(start 354.703126 -291.560504)
		(end 354.66401 -291.583364)
		(width 0.1143)
		(layer "In6.Cu")
		(net "P5E_CPU0_P0_TX_DN<10>")
	)
	(segment
		(start 354.19411 -286.558482)
		(end 354.233226 -286.581342)
		(width 0.1143)
		(layer "In6.Cu")
		(net "P5E_CPU0_P0_TX_DN<10>")
	)
	(segment
		(start 355.023166 -284.616144)
		(end 354.940362 -284.698948)
		(width 0.1143)
		(layer "In6.Cu")
		(net "P5E_CPU0_P0_TX_DN<10>")
	)
	(segment
		(start 354.184458 -285.919164)
		(end 354.182934 -285.919926)
		(width 0.1143)
		(layer "In6.Cu")
		(net "P5E_CPU0_P0_TX_DN<10>")
	)
	(segment
		(start 354.19411 -285.913576)
		(end 354.193348 -285.914084)
		(width 0.1143)
		(layer "In6.Cu")
		(net "P5E_CPU0_P0_TX_DN<10>")
	)
	(segment
		(start 354.160582 -286.538924)
		(end 354.19411 -286.558482)
		(width 0.1143)
		(layer "In6.Cu")
		(net "P5E_CPU0_P0_TX_DN<10>")
	)
	(segment
		(start 354.66401 -290.608512)
		(end 354.703126 -290.631372)
		(width 0.1143)
		(layer "In6.Cu")
		(net "P5E_CPU0_P0_TX_DN<10>")
	)
	(segment
		(start 354.66401 -291.583364)
		(end 354.63353 -291.601144)
		(width 0.1143)
		(layer "In6.Cu")
		(net "P5E_CPU0_P0_TX_DN<10>")
	)
	(segment
		(start 354.180902 -285.921196)
		(end 354.16236 -285.931864)
		(width 0.1143)
		(layer "In6.Cu")
		(net "P5E_CPU0_P0_TX_DN<10>")
	)
	(segment
		(start 354.66401 -288.343594)
		(end 354.631498 -288.36239)
		(width 0.1143)
		(layer "In6.Cu")
		(net "P5E_CPU0_P0_TX_DN<10>")
	)
	(segment
		(start 354.18649 -285.917894)
		(end 354.185728 -285.918402)
		(width 0.1143)
		(layer "In6.Cu")
		(net "P5E_CPU0_P0_TX_DN<10>")
	)
	(segment
		(start 354.138992 -296.281094)
		(end 354.138992 -298.159932)
		(width 0.14224)
		(layer "In6.Cu")
		(net "P5E_CPU0_P0_TX_DN<10>")
	)
	(segment
		(start 372.45163 -328.145394)
		(end 374.645428 -340.355174)
		(width 0.14224)
		(layer "In6.Cu")
		(net "P5E_CPU0_P0_TX_DN<10>")
	)
	(arc
		(start 354.940362 -284.698948)
		(mid 354.938574 -284.710397)
		(end 354.936552 -284.721808)
		(width 0.1143)
		(layer "In6.Cu")
		(net "P5E_CPU0_P0_TX_DN<10>")
	)
	(arc
		(start 354.631498 -288.36239)
		(mid 354.517569 -288.495537)
		(end 354.476558 -288.66592)
		(width 0.1143)
		(layer "In6.Cu")
		(net "P5E_CPU0_P0_TX_DN<10>")
	)
	(arc
		(start 354.703126 -293.871396)
		(mid 354.946453 -294.335962)
		(end 354.703126 -294.800528)
		(width 0.1143)
		(layer "In6.Cu")
		(net "P5E_CPU0_P0_TX_DN<10>")
	)
	(arc
		(start 354.006404 -286.236156)
		(mid 354.047166 -286.40604)
		(end 354.160582 -286.538924)
		(width 0.1143)
		(layer "In6.Cu")
		(net "P5E_CPU0_P0_TX_DN<10>")
	)
	(arc
		(start 354.63353 -285.12135)
		(mid 354.518103 -285.254726)
		(end 354.476558 -285.42615)
		(width 0.1143)
		(layer "In6.Cu")
		(net "P5E_CPU0_P0_TX_DN<10>")
	)
	(arc
		(start 354.476304 -295.333928)
		(mid 354.449744 -295.467926)
		(end 354.373942 -295.581578)
		(width 0.1143)
		(layer "In6.Cu")
		(net "P5E_CPU0_P0_TX_DN<10>")
	)
	(arc
		(start 318.307466 -381.987298)
		(mid 318.319743 -382.049021)
		(end 318.35471 -382.101344)
		(width 0.14224)
		(layer "In6.Cu")
		(net "P5E_CPU0_P0_TX_DN<10>")
	)
	(arc
		(start 354.16236 -285.931864)
		(mid 354.047684 -286.065198)
		(end 354.006404 -286.236156)
		(width 0.1143)
		(layer "In6.Cu")
		(net "P5E_CPU0_P0_TX_DN<10>")
	)
	(arc
		(start 354.703126 -289.01136)
		(mid 354.946453 -289.475926)
		(end 354.703126 -289.940492)
		(width 0.1143)
		(layer "In6.Cu")
		(net "P5E_CPU0_P0_TX_DN<10>")
	)
	(arc
		(start 354.233226 -286.581342)
		(mid 354.412039 -286.783692)
		(end 354.476558 -287.045908)
		(width 0.1143)
		(layer "In6.Cu")
		(net "P5E_CPU0_P0_TX_DN<10>")
	)
	(arc
		(start 354.476558 -287.045908)
		(mid 354.518107 -287.21733)
		(end 354.63353 -287.350708)
		(width 0.1143)
		(layer "In6.Cu")
		(net "P5E_CPU0_P0_TX_DN<10>")
	)
	(arc
		(start 361.562142 -373.342662)
		(mid 360.404574 -374.116061)
		(end 359.03916 -374.387618)
		(width 0.14224)
		(layer "In6.Cu")
		(net "P5E_CPU0_P0_TX_DN<10>")
	)
	(arc
		(start 354.152454 -295.803066)
		(mid 354.108712 -295.868297)
		(end 354.093272 -295.945306)
		(width 0.1143)
		(layer "In6.Cu")
		(net "P5E_CPU0_P0_TX_DN<10>")
	)
	(arc
		(start 354.703126 -292.251384)
		(mid 354.946453 -292.71595)
		(end 354.703126 -293.180516)
		(width 0.1143)
		(layer "In6.Cu")
		(net "P5E_CPU0_P0_TX_DN<10>")
	)
	(arc
		(start 320.090292 -375.08561)
		(mid 318.79416 -376.149486)
		(end 318.307466 -377.754134)
		(width 0.14224)
		(layer "In6.Cu")
		(net "P5E_CPU0_P0_TX_DN<10>")
	)
	(arc
		(start 354.700586 -287.389824)
		(mid 354.881238 -287.592569)
		(end 354.946458 -287.856168)
		(width 0.1143)
		(layer "In6.Cu")
		(net "P5E_CPU0_P0_TX_DN<10>")
	)
	(arc
		(start 354.703126 -290.631372)
		(mid 354.946453 -291.095938)
		(end 354.703126 -291.560504)
		(width 0.1143)
		(layer "In6.Cu")
		(net "P5E_CPU0_P0_TX_DN<10>")
	)
	(arc
		(start 354.63353 -291.601144)
		(mid 354.476553 -291.905944)
		(end 354.63353 -292.210744)
		(width 0.1143)
		(layer "In6.Cu")
		(net "P5E_CPU0_P0_TX_DN<10>")
	)
	(arc
		(start 354.63353 -293.221156)
		(mid 354.476553 -293.525956)
		(end 354.63353 -293.830756)
		(width 0.1143)
		(layer "In6.Cu")
		(net "P5E_CPU0_P0_TX_DN<10>")
	)
	(arc
		(start 354.946458 -287.856168)
		(mid 354.881943 -288.118387)
		(end 354.703126 -288.320734)
		(width 0.1143)
		(layer "In6.Cu")
		(net "P5E_CPU0_P0_TX_DN<10>")
	)
	(arc
		(start 354.63353 -289.981132)
		(mid 354.476553 -290.285932)
		(end 354.63353 -290.590732)
		(width 0.1143)
		(layer "In6.Cu")
		(net "P5E_CPU0_P0_TX_DN<10>")
	)
	(arc
		(start 374.645428 -350.925384)
		(mid 372.929994 -359.54907)
		(end 368.044984 -366.85982)
		(width 0.14224)
		(layer "In6.Cu")
		(net "P5E_CPU0_P0_TX_DN<10>")
	)
	(arc
		(start 354.63353 -294.841168)
		(mid 354.518103 -294.974544)
		(end 354.476558 -295.145968)
		(width 0.1143)
		(layer "In6.Cu")
		(net "P5E_CPU0_P0_TX_DN<10>")
	)
	(arc
		(start 354.476558 -285.42615)
		(mid 354.412043 -285.688369)
		(end 354.233226 -285.890716)
		(width 0.1143)
		(layer "In6.Cu")
		(net "P5E_CPU0_P0_TX_DN<10>")
	)
	(arc
		(start 354.476558 -288.66592)
		(mid 354.518107 -288.837342)
		(end 354.63353 -288.97072)
		(width 0.1143)
		(layer "In6.Cu")
		(net "P5E_CPU0_P0_TX_DN<10>")
	)
	(arc
		(start 322.339208 -374.387618)
		(mid 321.786428 -374.442054)
		(end 321.254882 -374.603264)
		(width 0.14224)
		(layer "In6.Cu")
		(net "P5E_CPU0_P0_TX_DN<10>")
	)
	(arc
		(start 354.936552 -284.721808)
		(mid 354.855119 -284.924206)
		(end 354.703126 -285.08071)
		(width 0.1143)
		(layer "In6.Cu")
		(net "P5E_CPU0_P0_TX_DN<10>")
	)
	(segment
		(start 297.700954 -390.15797)
		(end 297.430444 -389.88746)
		(width 0.12954)
		(layer "F.Cu")
		(net "P5E_CPU0_P0_TX_DN<0>")
	)
	(segment
		(start 298.700444 -389.86206)
		(end 298.404534 -390.15797)
		(width 0.12954)
		(layer "F.Cu")
		(net "P5E_CPU0_P0_TX_DN<0>")
	)
	(segment
		(start 298.404534 -390.15797)
		(end 297.700954 -390.15797)
		(width 0.12954)
		(layer "F.Cu")
		(net "P5E_CPU0_P0_TX_DN<0>")
	)
	(segment
		(start 347.327982 -282.730194)
		(end 346.86113 -282.996132)
		(width 0.12954)
		(layer "F.Cu")
		(net "P5E_CPU0_P0_TX_DN<0>")
	)
	(segment
		(start 346.86113 -282.996132)
		(end 346.563188 -282.996132)
		(width 0.1143)
		(layer "In6.Cu")
		(net "P5E_CPU0_P0_TX_DN<0>")
	)
	(segment
		(start 345.263978 -290.608512)
		(end 345.303094 -290.631372)
		(width 0.1143)
		(layer "In6.Cu")
		(net "P5E_CPU0_P0_TX_DN<0>")
	)
	(segment
		(start 345.736672 -284.29204)
		(end 345.735148 -284.293056)
		(width 0.1143)
		(layer "In6.Cu")
		(net "P5E_CPU0_P0_TX_DN<0>")
	)
	(segment
		(start 297.139614 -390.17829)
		(end 297.430444 -389.88746)
		(width 0.14224)
		(layer "In6.Cu")
		(net "P5E_CPU0_P0_TX_DN<0>")
	)
	(segment
		(start 344.652092 -296.281094)
		(end 344.652092 -299.621448)
		(width 0.14224)
		(layer "In6.Cu")
		(net "P5E_CPU0_P0_TX_DN<0>")
	)
	(segment
		(start 345.773248 -284.270704)
		(end 345.736672 -284.29204)
		(width 0.1143)
		(layer "In6.Cu")
		(net "P5E_CPU0_P0_TX_DN<0>")
	)
	(segment
		(start 296.372026 -386.418074)
		(end 296.372026 -386.844794)
		(width 0.14224)
		(layer "In6.Cu")
		(net "P5E_CPU0_P0_TX_DN<0>")
	)
	(segment
		(start 365.266986 -341.805006)
		(end 365.266986 -349.10014)
		(width 0.14224)
		(layer "In6.Cu")
		(net "P5E_CPU0_P0_TX_DN<0>")
	)
	(segment
		(start 345.734132 -284.293564)
		(end 345.73337 -284.294072)
		(width 0.1143)
		(layer "In6.Cu")
		(net "P5E_CPU0_P0_TX_DN<0>")
	)
	(segment
		(start 345.263978 -291.583364)
		(end 345.233498 -291.601144)
		(width 0.1143)
		(layer "In6.Cu")
		(net "P5E_CPU0_P0_TX_DN<0>")
	)
	(segment
		(start 363.562646 -332.324456)
		(end 365.266986 -341.805006)
		(width 0.14224)
		(layer "In6.Cu")
		(net "P5E_CPU0_P0_TX_DN<0>")
	)
	(segment
		(start 296.372026 -386.844794)
		(end 296.234866 -386.981954)
		(width 0.14224)
		(layer "In6.Cu")
		(net "P5E_CPU0_P0_TX_DN<0>")
	)
	(segment
		(start 345.233498 -293.830756)
		(end 345.263978 -293.848536)
		(width 0.1143)
		(layer "In6.Cu")
		(net "P5E_CPU0_P0_TX_DN<0>")
	)
	(segment
		(start 345.727528 -284.297374)
		(end 345.726258 -284.298136)
		(width 0.1143)
		(layer "In6.Cu")
		(net "P5E_CPU0_P0_TX_DN<0>")
	)
	(segment
		(start 345.263978 -292.228524)
		(end 345.303094 -292.251384)
		(width 0.1143)
		(layer "In6.Cu")
		(net "P5E_CPU0_P0_TX_DN<0>")
	)
	(segment
		(start 296.372026 -380.651258)
		(end 296.372026 -381.077978)
		(width 0.14224)
		(layer "In6.Cu")
		(net "P5E_CPU0_P0_TX_DN<0>")
	)
	(segment
		(start 361.148884 -326.753728)
		(end 362.616242 -329.559666)
		(width 0.14224)
		(layer "In6.Cu")
		(net "P5E_CPU0_P0_TX_DN<0>")
	)
	(segment
		(start 345.73337 -284.294072)
		(end 345.7321 -284.294834)
		(width 0.1143)
		(layer "In6.Cu")
		(net "P5E_CPU0_P0_TX_DN<0>")
	)
	(segment
		(start 296.234866 -382.074166)
		(end 296.372026 -382.211326)
		(width 0.14224)
		(layer "In6.Cu")
		(net "P5E_CPU0_P0_TX_DN<0>")
	)
	(segment
		(start 346.204032 -283.483558)
		(end 346.173552 -283.501338)
		(width 0.1143)
		(layer "In6.Cu")
		(net "P5E_CPU0_P0_TX_DN<0>")
	)
	(segment
		(start 344.606372 -295.904412)
		(end 344.606372 -296.206926)
		(width 0.1143)
		(layer "In6.Cu")
		(net "P5E_CPU0_P0_TX_DN<0>")
	)
	(segment
		(start 345.72829 -284.296866)
		(end 345.727528 -284.297374)
		(width 0.1143)
		(layer "In6.Cu")
		(net "P5E_CPU0_P0_TX_DN<0>")
	)
	(segment
		(start 296.372026 -383.339086)
		(end 296.372026 -383.765806)
		(width 0.14224)
		(layer "In6.Cu")
		(net "P5E_CPU0_P0_TX_DN<0>")
	)
	(segment
		(start 296.234866 -382.775206)
		(end 296.234866 -383.201926)
		(width 0.14224)
		(layer "In6.Cu")
		(net "P5E_CPU0_P0_TX_DN<0>")
	)
	(segment
		(start 345.7321 -284.294834)
		(end 345.730576 -284.295596)
		(width 0.1143)
		(layer "In6.Cu")
		(net "P5E_CPU0_P0_TX_DN<0>")
	)
	(segment
		(start 344.833194 -285.890716)
		(end 344.795094 -285.913068)
		(width 0.1143)
		(layer "In6.Cu")
		(net "P5E_CPU0_P0_TX_DN<0>")
	)
	(segment
		(start 345.735148 -284.293056)
		(end 345.734132 -284.293564)
		(width 0.1143)
		(layer "In6.Cu")
		(net "P5E_CPU0_P0_TX_DN<0>")
	)
	(segment
		(start 345.263978 -293.203376)
		(end 345.233498 -293.221156)
		(width 0.1143)
		(layer "In6.Cu")
		(net "P5E_CPU0_P0_TX_DN<0>")
	)
	(segment
		(start 345.729814 -284.296104)
		(end 345.72829 -284.296866)
		(width 0.1143)
		(layer "In6.Cu")
		(net "P5E_CPU0_P0_TX_DN<0>")
	)
	(segment
		(start 345.233498 -290.590732)
		(end 345.263978 -290.608512)
		(width 0.1143)
		(layer "In6.Cu")
		(net "P5E_CPU0_P0_TX_DN<0>")
	)
	(segment
		(start 345.263978 -289.963352)
		(end 345.233498 -289.981132)
		(width 0.1143)
		(layer "In6.Cu")
		(net "P5E_CPU0_P0_TX_DN<0>")
	)
	(segment
		(start 296.234866 -379.033786)
		(end 296.234866 -380.514098)
		(width 0.14224)
		(layer "In6.Cu")
		(net "P5E_CPU0_P0_TX_DN<0>")
	)
	(segment
		(start 355.982016 -365.038132)
		(end 321.819778 -365.038132)
		(width 0.14224)
		(layer "In6.Cu")
		(net "P5E_CPU0_P0_TX_DN<0>")
	)
	(segment
		(start 296.372026 -383.765806)
		(end 296.234866 -383.902966)
		(width 0.14224)
		(layer "In6.Cu")
		(net "P5E_CPU0_P0_TX_DN<0>")
	)
	(segment
		(start 296.372026 -382.211326)
		(end 296.372026 -382.638046)
		(width 0.14224)
		(layer "In6.Cu")
		(net "P5E_CPU0_P0_TX_DN<0>")
	)
	(segment
		(start 318.001142 -365.795814)
		(end 310.168544 -369.039648)
		(width 0.14224)
		(layer "In6.Cu")
		(net "P5E_CPU0_P0_TX_DN<0>")
	)
	(segment
		(start 345.723718 -284.299406)
		(end 345.702382 -284.311852)
		(width 0.1143)
		(layer "In6.Cu")
		(net "P5E_CPU0_P0_TX_DN<0>")
	)
	(segment
		(start 301.074328 -370.952014)
		(end 298.52747 -373.498872)
		(width 0.14224)
		(layer "In6.Cu")
		(net "P5E_CPU0_P0_TX_DN<0>")
	)
	(segment
		(start 346.563188 -282.996132)
		(end 346.480384 -283.078936)
		(width 0.1143)
		(layer "In6.Cu")
		(net "P5E_CPU0_P0_TX_DN<0>")
	)
	(segment
		(start 296.234866 -386.981954)
		(end 296.234866 -389.702802)
		(width 0.14224)
		(layer "In6.Cu")
		(net "P5E_CPU0_P0_TX_DN<0>")
	)
	(segment
		(start 348.924118 -309.935372)
		(end 355.83495 -320.278506)
		(width 0.14224)
		(layer "In6.Cu")
		(net "P5E_CPU0_P0_TX_DN<0>")
	)
	(segment
		(start 355.83495 -320.278506)
		(end 361.148884 -326.753728)
		(width 0.14224)
		(layer "In6.Cu")
		(net "P5E_CPU0_P0_TX_DN<0>")
	)
	(segment
		(start 345.303094 -289.940492)
		(end 345.263978 -289.963352)
		(width 0.1143)
		(layer "In6.Cu")
		(net "P5E_CPU0_P0_TX_DN<0>")
	)
	(segment
		(start 296.373042 -390.036304)
		(end 296.439844 -390.103106)
		(width 0.14224)
		(layer "In6.Cu")
		(net "P5E_CPU0_P0_TX_DN<0>")
	)
	(segment
		(start 296.234866 -383.902966)
		(end 296.234866 -386.280914)
		(width 0.14224)
		(layer "In6.Cu")
		(net "P5E_CPU0_P0_TX_DN<0>")
	)
	(segment
		(start 307.212238 -369.627658)
		(end 304.271426 -369.627658)
		(width 0.14224)
		(layer "In6.Cu")
		(net "P5E_CPU0_P0_TX_DN<0>")
	)
	(segment
		(start 345.730576 -284.295596)
		(end 345.729814 -284.296104)
		(width 0.1143)
		(layer "In6.Cu")
		(net "P5E_CPU0_P0_TX_DN<0>")
	)
	(segment
		(start 345.263978 -288.343594)
		(end 345.231466 -288.36239)
		(width 0.1143)
		(layer "In6.Cu")
		(net "P5E_CPU0_P0_TX_DN<0>")
	)
	(segment
		(start 296.234866 -386.280914)
		(end 296.372026 -386.418074)
		(width 0.14224)
		(layer "In6.Cu")
		(net "P5E_CPU0_P0_TX_DN<0>")
	)
	(segment
		(start 345.263978 -285.10357)
		(end 345.233498 -285.12135)
		(width 0.1143)
		(layer "In6.Cu")
		(net "P5E_CPU0_P0_TX_DN<0>")
	)
	(segment
		(start 345.303094 -285.08071)
		(end 345.263978 -285.10357)
		(width 0.1143)
		(layer "In6.Cu")
		(net "P5E_CPU0_P0_TX_DN<0>")
	)
	(segment
		(start 296.234866 -383.201926)
		(end 296.372026 -383.339086)
		(width 0.14224)
		(layer "In6.Cu")
		(net "P5E_CPU0_P0_TX_DN<0>")
	)
	(segment
		(start 345.303094 -291.560504)
		(end 345.263978 -291.583364)
		(width 0.1143)
		(layer "In6.Cu")
		(net "P5E_CPU0_P0_TX_DN<0>")
	)
	(segment
		(start 344.795094 -285.913068)
		(end 344.7923 -285.914592)
		(width 0.1143)
		(layer "In6.Cu")
		(net "P5E_CPU0_P0_TX_DN<0>")
	)
	(segment
		(start 344.76055 -286.538924)
		(end 344.794078 -286.558482)
		(width 0.1143)
		(layer "In6.Cu")
		(net "P5E_CPU0_P0_TX_DN<0>")
	)
	(segment
		(start 345.303094 -294.800528)
		(end 345.232228 -294.84193)
		(width 0.1143)
		(layer "In6.Cu")
		(net "P5E_CPU0_P0_TX_DN<0>")
	)
	(segment
		(start 345.233498 -292.210744)
		(end 345.263978 -292.228524)
		(width 0.1143)
		(layer "In6.Cu")
		(net "P5E_CPU0_P0_TX_DN<0>")
	)
	(segment
		(start 344.794078 -286.558482)
		(end 344.833194 -286.581342)
		(width 0.1143)
		(layer "In6.Cu")
		(net "P5E_CPU0_P0_TX_DN<0>")
	)
	(segment
		(start 296.234866 -380.514098)
		(end 296.372026 -380.651258)
		(width 0.14224)
		(layer "In6.Cu")
		(net "P5E_CPU0_P0_TX_DN<0>")
	)
	(segment
		(start 296.6212 -390.17829)
		(end 297.139614 -390.17829)
		(width 0.14224)
		(layer "In6.Cu")
		(net "P5E_CPU0_P0_TX_DN<0>")
	)
	(segment
		(start 296.234866 -381.215138)
		(end 296.234866 -382.074166)
		(width 0.14224)
		(layer "In6.Cu")
		(net "P5E_CPU0_P0_TX_DN<0>")
	)
	(segment
		(start 296.372026 -382.638046)
		(end 296.234866 -382.775206)
		(width 0.14224)
		(layer "In6.Cu")
		(net "P5E_CPU0_P0_TX_DN<0>")
	)
	(segment
		(start 345.233498 -288.97072)
		(end 345.263978 -288.9885)
		(width 0.1143)
		(layer "In6.Cu")
		(net "P5E_CPU0_P0_TX_DN<0>")
	)
	(segment
		(start 345.726258 -284.298136)
		(end 345.723718 -284.299406)
		(width 0.1143)
		(layer "In6.Cu")
		(net "P5E_CPU0_P0_TX_DN<0>")
	)
	(segment
		(start 344.606372 -296.206926)
		(end 344.652092 -296.252646)
		(width 0.1143)
		(layer "In6.Cu")
		(net "P5E_CPU0_P0_TX_DN<0>")
	)
	(segment
		(start 345.303094 -293.180516)
		(end 345.263978 -293.203376)
		(width 0.1143)
		(layer "In6.Cu")
		(net "P5E_CPU0_P0_TX_DN<0>")
	)
	(segment
		(start 362.616242 -329.559666)
		(end 363.562646 -332.324456)
		(width 0.14224)
		(layer "In6.Cu")
		(net "P5E_CPU0_P0_TX_DN<0>")
	)
	(segment
		(start 345.263978 -293.848536)
		(end 345.303094 -293.871396)
		(width 0.1143)
		(layer "In6.Cu")
		(net "P5E_CPU0_P0_TX_DN<0>")
	)
	(segment
		(start 345.233498 -287.350708)
		(end 345.300554 -287.389824)
		(width 0.1143)
		(layer "In6.Cu")
		(net "P5E_CPU0_P0_TX_DN<0>")
	)
	(segment
		(start 345.303094 -288.320734)
		(end 345.263978 -288.343594)
		(width 0.1143)
		(layer "In6.Cu")
		(net "P5E_CPU0_P0_TX_DN<0>")
	)
	(segment
		(start 360.082338 -361.617006)
		(end 357.141526 -364.557818)
		(width 0.14224)
		(layer "In6.Cu")
		(net "P5E_CPU0_P0_TX_DN<0>")
	)
	(segment
		(start 345.263978 -288.9885)
		(end 345.303094 -289.01136)
		(width 0.1143)
		(layer "In6.Cu")
		(net "P5E_CPU0_P0_TX_DN<0>")
	)
	(segment
		(start 346.243148 -283.460698)
		(end 346.204032 -283.483558)
		(width 0.1143)
		(layer "In6.Cu")
		(net "P5E_CPU0_P0_TX_DN<0>")
	)
	(segment
		(start 344.652092 -296.252646)
		(end 344.652092 -296.281094)
		(width 0.1143)
		(layer "In6.Cu")
		(net "P5E_CPU0_P0_TX_DN<0>")
	)
	(segment
		(start 344.919554 -295.524682)
		(end 344.653616 -295.790366)
		(width 0.1143)
		(layer "In6.Cu")
		(net "P5E_CPU0_P0_TX_DN<0>")
	)
	(segment
		(start 296.372026 -381.077978)
		(end 296.234866 -381.215138)
		(width 0.14224)
		(layer "In6.Cu")
		(net "P5E_CPU0_P0_TX_DN<0>")
	)
	(segment
		(start 344.652092 -299.621448)
		(end 348.924118 -309.935372)
		(width 0.14224)
		(layer "In6.Cu")
		(net "P5E_CPU0_P0_TX_DN<0>")
	)
	(arc
		(start 357.141526 -364.557818)
		(mid 356.609538 -364.913281)
		(end 355.982016 -365.038132)
		(width 0.14224)
		(layer "In6.Cu")
		(net "P5E_CPU0_P0_TX_DN<0>")
	)
	(arc
		(start 345.076272 -295.145968)
		(mid 345.035583 -295.350908)
		(end 344.919554 -295.524682)
		(width 0.1143)
		(layer "In6.Cu")
		(net "P5E_CPU0_P0_TX_DN<0>")
	)
	(arc
		(start 345.231466 -288.36239)
		(mid 345.117537 -288.495537)
		(end 345.076526 -288.66592)
		(width 0.1143)
		(layer "In6.Cu")
		(net "P5E_CPU0_P0_TX_DN<0>")
	)
	(arc
		(start 345.546426 -287.856168)
		(mid 345.481911 -288.118387)
		(end 345.303094 -288.320734)
		(width 0.1143)
		(layer "In6.Cu")
		(net "P5E_CPU0_P0_TX_DN<0>")
	)
	(arc
		(start 346.476574 -283.101796)
		(mid 346.395141 -283.304194)
		(end 346.243148 -283.460698)
		(width 0.1143)
		(layer "In6.Cu")
		(net "P5E_CPU0_P0_TX_DN<0>")
	)
	(arc
		(start 345.300554 -287.389824)
		(mid 345.481206 -287.592569)
		(end 345.546426 -287.856168)
		(width 0.1143)
		(layer "In6.Cu")
		(net "P5E_CPU0_P0_TX_DN<0>")
	)
	(arc
		(start 346.01658 -283.806138)
		(mid 345.952065 -284.068357)
		(end 345.773248 -284.270704)
		(width 0.1143)
		(layer "In6.Cu")
		(net "P5E_CPU0_P0_TX_DN<0>")
	)
	(arc
		(start 345.303094 -289.01136)
		(mid 345.546421 -289.475926)
		(end 345.303094 -289.940492)
		(width 0.1143)
		(layer "In6.Cu")
		(net "P5E_CPU0_P0_TX_DN<0>")
	)
	(arc
		(start 345.076526 -288.66592)
		(mid 345.118075 -288.837342)
		(end 345.233498 -288.97072)
		(width 0.1143)
		(layer "In6.Cu")
		(net "P5E_CPU0_P0_TX_DN<0>")
	)
	(arc
		(start 296.234866 -389.702802)
		(mid 296.27077 -389.883305)
		(end 296.373042 -390.036304)
		(width 0.14224)
		(layer "In6.Cu")
		(net "P5E_CPU0_P0_TX_DN<0>")
	)
	(arc
		(start 344.7923 -285.914592)
		(mid 344.656219 -286.05044)
		(end 344.606372 -286.236156)
		(width 0.1143)
		(layer "In6.Cu")
		(net "P5E_CPU0_P0_TX_DN<0>")
	)
	(arc
		(start 344.833194 -286.581342)
		(mid 345.012007 -286.783692)
		(end 345.076526 -287.045908)
		(width 0.1143)
		(layer "In6.Cu")
		(net "P5E_CPU0_P0_TX_DN<0>")
	)
	(arc
		(start 346.173552 -283.501338)
		(mid 346.058125 -283.634714)
		(end 346.01658 -283.806138)
		(width 0.1143)
		(layer "In6.Cu")
		(net "P5E_CPU0_P0_TX_DN<0>")
	)
	(arc
		(start 298.52747 -373.498872)
		(mid 296.83067 -376.038312)
		(end 296.234866 -379.033786)
		(width 0.14224)
		(layer "In6.Cu")
		(net "P5E_CPU0_P0_TX_DN<0>")
	)
	(arc
		(start 304.271426 -369.627658)
		(mid 302.541155 -369.971848)
		(end 301.074328 -370.952014)
		(width 0.14224)
		(layer "In6.Cu")
		(net "P5E_CPU0_P0_TX_DN<0>")
	)
	(arc
		(start 310.168544 -369.039648)
		(mid 308.719342 -369.479199)
		(end 307.212238 -369.627658)
		(width 0.14224)
		(layer "In6.Cu")
		(net "P5E_CPU0_P0_TX_DN<0>")
	)
	(arc
		(start 345.233498 -289.981132)
		(mid 345.076521 -290.285932)
		(end 345.233498 -290.590732)
		(width 0.1143)
		(layer "In6.Cu")
		(net "P5E_CPU0_P0_TX_DN<0>")
	)
	(arc
		(start 345.303094 -292.251384)
		(mid 345.546421 -292.71595)
		(end 345.303094 -293.180516)
		(width 0.1143)
		(layer "In6.Cu")
		(net "P5E_CPU0_P0_TX_DN<0>")
	)
	(arc
		(start 345.076526 -285.42615)
		(mid 345.012011 -285.688369)
		(end 344.833194 -285.890716)
		(width 0.1143)
		(layer "In6.Cu")
		(net "P5E_CPU0_P0_TX_DN<0>")
	)
	(arc
		(start 345.232228 -294.84193)
		(mid 345.117552 -294.975121)
		(end 345.076272 -295.145968)
		(width 0.1143)
		(layer "In6.Cu")
		(net "P5E_CPU0_P0_TX_DN<0>")
	)
	(arc
		(start 344.653616 -295.790366)
		(mid 344.618707 -295.842705)
		(end 344.606372 -295.904412)
		(width 0.1143)
		(layer "In6.Cu")
		(net "P5E_CPU0_P0_TX_DN<0>")
	)
	(arc
		(start 296.439844 -390.103106)
		(mid 296.523037 -390.158757)
		(end 296.6212 -390.17829)
		(width 0.14224)
		(layer "In6.Cu")
		(net "P5E_CPU0_P0_TX_DN<0>")
	)
	(arc
		(start 321.819778 -365.038132)
		(mid 319.873239 -365.229383)
		(end 318.001142 -365.795814)
		(width 0.14224)
		(layer "In6.Cu")
		(net "P5E_CPU0_P0_TX_DN<0>")
	)
	(arc
		(start 345.546426 -284.616144)
		(mid 345.481911 -284.878363)
		(end 345.303094 -285.08071)
		(width 0.1143)
		(layer "In6.Cu")
		(net "P5E_CPU0_P0_TX_DN<0>")
	)
	(arc
		(start 345.303094 -293.871396)
		(mid 345.546421 -294.335962)
		(end 345.303094 -294.800528)
		(width 0.1143)
		(layer "In6.Cu")
		(net "P5E_CPU0_P0_TX_DN<0>")
	)
	(arc
		(start 345.233498 -293.221156)
		(mid 345.076521 -293.525956)
		(end 345.233498 -293.830756)
		(width 0.1143)
		(layer "In6.Cu")
		(net "P5E_CPU0_P0_TX_DN<0>")
	)
	(arc
		(start 365.266986 -349.10014)
		(mid 363.919538 -355.874216)
		(end 360.082338 -361.617006)
		(width 0.14224)
		(layer "In6.Cu")
		(net "P5E_CPU0_P0_TX_DN<0>")
	)
	(arc
		(start 345.233498 -291.601144)
		(mid 345.076521 -291.905944)
		(end 345.233498 -292.210744)
		(width 0.1143)
		(layer "In6.Cu")
		(net "P5E_CPU0_P0_TX_DN<0>")
	)
	(arc
		(start 345.702382 -284.311852)
		(mid 345.587706 -284.445186)
		(end 345.546426 -284.616144)
		(width 0.1143)
		(layer "In6.Cu")
		(net "P5E_CPU0_P0_TX_DN<0>")
	)
	(arc
		(start 344.606372 -286.236156)
		(mid 344.647134 -286.40604)
		(end 344.76055 -286.538924)
		(width 0.1143)
		(layer "In6.Cu")
		(net "P5E_CPU0_P0_TX_DN<0>")
	)
	(arc
		(start 346.480384 -283.078936)
		(mid 346.478596 -283.090385)
		(end 346.476574 -283.101796)
		(width 0.1143)
		(layer "In6.Cu")
		(net "P5E_CPU0_P0_TX_DN<0>")
	)
	(arc
		(start 345.233498 -285.12135)
		(mid 345.118071 -285.254726)
		(end 345.076526 -285.42615)
		(width 0.1143)
		(layer "In6.Cu")
		(net "P5E_CPU0_P0_TX_DN<0>")
	)
	(arc
		(start 345.076526 -287.045908)
		(mid 345.118075 -287.21733)
		(end 345.233498 -287.350708)
		(width 0.1143)
		(layer "In6.Cu")
		(net "P5E_CPU0_P0_TX_DN<0>")
	)
	(arc
		(start 345.303094 -290.631372)
		(mid 345.546421 -291.095938)
		(end 345.303094 -291.560504)
		(width 0.1143)
		(layer "In6.Cu")
		(net "P5E_CPU0_P0_TX_DN<0>")
	)
	(segment
		(start 355.78796 -271.39011)
		(end 355.321108 -271.656048)
		(width 0.12954)
		(layer "F.Cu")
		(net "P5E_CPU0_P0_RX_DP<9>")
	)
	(segment
		(start 314.470288 -394.385292)
		(end 314.990988 -394.385292)
		(width 0.127)
		(layer "F.Cu")
		(net "P5E_CPU0_P0_RX_DP<9>")
	)
	(segment
		(start 353.691444 -286.742378)
		(end 353.723956 -286.723582)
		(width 0.1143)
		(layer "In15.Cu")
		(net "P5E_CPU0_P0_RX_DP<9>")
	)
	(segment
		(start 347.26118 -367.19637)
		(end 347.11894 -367.05413)
		(width 0.14224)
		(layer "In15.Cu")
		(net "P5E_CPU0_P0_RX_DP<9>")
	)
	(segment
		(start 366.517936 -327.347072)
		(end 353.260914 -304.588418)
		(width 0.14224)
		(layer "In15.Cu")
		(net "P5E_CPU0_P0_RX_DP<9>")
	)
	(segment
		(start 353.693476 -283.501338)
		(end 353.763072 -283.460698)
		(width 0.1143)
		(layer "In15.Cu")
		(net "P5E_CPU0_P0_RX_DP<9>")
	)
	(segment
		(start 353.693476 -280.261314)
		(end 353.763072 -280.220674)
		(width 0.1143)
		(layer "In15.Cu")
		(net "P5E_CPU0_P0_RX_DP<9>")
	)
	(segment
		(start 317.751968 -375.65838)
		(end 318.368934 -375.246138)
		(width 0.14224)
		(layer "In15.Cu")
		(net "P5E_CPU0_P0_RX_DP<9>")
	)
	(segment
		(start 315.348366 -393.428982)
		(end 315.03239 -393.113006)
		(width 0.14224)
		(layer "In15.Cu")
		(net "P5E_CPU0_P0_RX_DP<9>")
	)
	(segment
		(start 359.72496 -367.19637)
		(end 347.26118 -367.19637)
		(width 0.14224)
		(layer "In15.Cu")
		(net "P5E_CPU0_P0_RX_DP<9>")
	)
	(segment
		(start 353.691444 -288.36239)
		(end 353.723956 -288.343594)
		(width 0.1143)
		(layer "In15.Cu")
		(net "P5E_CPU0_P0_RX_DP<9>")
	)
	(segment
		(start 353.693476 -294.841168)
		(end 353.763072 -294.800528)
		(width 0.1143)
		(layer "In15.Cu")
		(net "P5E_CPU0_P0_RX_DP<9>")
	)
	(segment
		(start 353.763072 -280.911554)
		(end 353.693476 -280.870914)
		(width 0.1143)
		(layer "In15.Cu")
		(net "P5E_CPU0_P0_RX_DP<9>")
	)
	(segment
		(start 315.035438 -392.7348)
		(end 315.340238 -392.430254)
		(width 0.14224)
		(layer "In15.Cu")
		(net "P5E_CPU0_P0_RX_DP<9>")
	)
	(segment
		(start 353.763072 -279.291542)
		(end 353.693476 -279.250902)
		(width 0.1143)
		(layer "In15.Cu")
		(net "P5E_CPU0_P0_RX_DP<9>")
	)
	(segment
		(start 314.990988 -394.385292)
		(end 315.085984 -394.031216)
		(width 0.14224)
		(layer "In15.Cu")
		(net "P5E_CPU0_P0_RX_DP<9>")
	)
	(segment
		(start 353.763072 -285.77159)
		(end 353.693476 -285.73095)
		(width 0.1143)
		(layer "In15.Cu")
		(net "P5E_CPU0_P0_RX_DP<9>")
	)
	(segment
		(start 353.18573 -295.829482)
		(end 353.419918 -295.59504)
		(width 0.1143)
		(layer "In15.Cu")
		(net "P5E_CPU0_P0_RX_DP<9>")
	)
	(segment
		(start 354.206048 -272.946876)
		(end 354.233226 -272.93062)
		(width 0.1143)
		(layer "In15.Cu")
		(net "P5E_CPU0_P0_RX_DP<9>")
	)
	(segment
		(start 353.693476 -281.881326)
		(end 353.763072 -281.840686)
		(width 0.1143)
		(layer "In15.Cu")
		(net "P5E_CPU0_P0_RX_DP<9>")
	)
	(segment
		(start 353.53625 -295.315132)
		(end 353.53625 -295.239694)
		(width 0.1143)
		(layer "In15.Cu")
		(net "P5E_CPU0_P0_RX_DP<9>")
	)
	(segment
		(start 315.085984 -394.031216)
		(end 315.260228 -393.930632)
		(width 0.14224)
		(layer "In15.Cu")
		(net "P5E_CPU0_P0_RX_DP<9>")
	)
	(segment
		(start 316.803024 -376.607324)
		(end 317.751968 -375.65838)
		(width 0.14224)
		(layer "In15.Cu")
		(net "P5E_CPU0_P0_RX_DP<9>")
	)
	(segment
		(start 353.53625 -295.239694)
		(end 353.536504 -295.23944)
		(width 0.1143)
		(layer "In15.Cu")
		(net "P5E_CPU0_P0_RX_DP<9>")
	)
	(segment
		(start 355.023166 -271.656048)
		(end 355.321108 -271.656048)
		(width 0.1143)
		(layer "In15.Cu")
		(net "P5E_CPU0_P0_RX_DP<9>")
	)
	(segment
		(start 353.763072 -277.67153)
		(end 353.693476 -277.63089)
		(width 0.1143)
		(layer "In15.Cu")
		(net "P5E_CPU0_P0_RX_DP<9>")
	)
	(segment
		(start 316.605666 -381.615442)
		(end 316.605666 -377.083574)
		(width 0.14224)
		(layer "In15.Cu")
		(net "P5E_CPU0_P0_RX_DP<9>")
	)
	(segment
		(start 353.763072 -293.871396)
		(end 353.693476 -293.830756)
		(width 0.1143)
		(layer "In15.Cu")
		(net "P5E_CPU0_P0_RX_DP<9>")
	)
	(segment
		(start 353.693476 -275.401278)
		(end 353.763072 -275.360638)
		(width 0.1143)
		(layer "In15.Cu")
		(net "P5E_CPU0_P0_RX_DP<9>")
	)
	(segment
		(start 353.193858 -296.374566)
		(end 353.193858 -296.346118)
		(width 0.1143)
		(layer "In15.Cu")
		(net "P5E_CPU0_P0_RX_DP<9>")
	)
	(segment
		(start 353.763072 -290.631372)
		(end 353.693476 -290.590732)
		(width 0.1143)
		(layer "In15.Cu")
		(net "P5E_CPU0_P0_RX_DP<9>")
	)
	(segment
		(start 353.763072 -282.531566)
		(end 353.693476 -282.490926)
		(width 0.1143)
		(layer "In15.Cu")
		(net "P5E_CPU0_P0_RX_DP<9>")
	)
	(segment
		(start 315.260228 -393.930632)
		(end 315.348366 -393.842494)
		(width 0.14224)
		(layer "In15.Cu")
		(net "P5E_CPU0_P0_RX_DP<9>")
	)
	(segment
		(start 360.0323 -367.50371)
		(end 359.72496 -367.19637)
		(width 0.14224)
		(layer "In15.Cu")
		(net "P5E_CPU0_P0_RX_DP<9>")
	)
	(segment
		(start 315.348366 -393.842494)
		(end 315.348366 -393.428982)
		(width 0.14224)
		(layer "In15.Cu")
		(net "P5E_CPU0_P0_RX_DP<9>")
	)
	(segment
		(start 353.723956 -288.343594)
		(end 353.763072 -288.320734)
		(width 0.1143)
		(layer "In15.Cu")
		(net "P5E_CPU0_P0_RX_DP<9>")
	)
	(segment
		(start 393.953238 -365.111792)
		(end 393.953238 -355.152198)
		(width 0.14224)
		(layer "In15.Cu")
		(net "P5E_CPU0_P0_RX_DP<9>")
	)
	(segment
		(start 353.693476 -277.02129)
		(end 353.763072 -276.98065)
		(width 0.1143)
		(layer "In15.Cu")
		(net "P5E_CPU0_P0_RX_DP<9>")
	)
	(segment
		(start 353.763072 -289.01136)
		(end 353.693476 -288.97072)
		(width 0.1143)
		(layer "In15.Cu")
		(net "P5E_CPU0_P0_RX_DP<9>")
	)
	(segment
		(start 353.760532 -287.389824)
		(end 353.693476 -287.350708)
		(width 0.1143)
		(layer "In15.Cu")
		(net "P5E_CPU0_P0_RX_DP<9>")
	)
	(segment
		(start 354.63353 -272.161254)
		(end 354.703126 -272.120614)
		(width 0.1143)
		(layer "In15.Cu")
		(net "P5E_CPU0_P0_RX_DP<9>")
	)
	(segment
		(start 393.42568 -353.897946)
		(end 367.120678 -328.121264)
		(width 0.14224)
		(layer "In15.Cu")
		(net "P5E_CPU0_P0_RX_DP<9>")
	)
	(segment
		(start 353.763072 -292.251384)
		(end 353.693476 -292.210744)
		(width 0.1143)
		(layer "In15.Cu")
		(net "P5E_CPU0_P0_RX_DP<9>")
	)
	(segment
		(start 354.16236 -272.971768)
		(end 354.162614 -272.972022)
		(width 0.1143)
		(layer "In15.Cu")
		(net "P5E_CPU0_P0_RX_DP<9>")
	)
	(segment
		(start 353.693476 -293.221156)
		(end 353.763072 -293.180516)
		(width 0.1143)
		(layer "In15.Cu")
		(net "P5E_CPU0_P0_RX_DP<9>")
	)
	(segment
		(start 393.143994 -366.161574)
		(end 393.783058 -365.52251)
		(width 0.14224)
		(layer "In15.Cu")
		(net "P5E_CPU0_P0_RX_DP<9>")
	)
	(segment
		(start 353.723956 -286.723582)
		(end 353.763072 -286.700722)
		(width 0.1143)
		(layer "In15.Cu")
		(net "P5E_CPU0_P0_RX_DP<9>")
	)
	(segment
		(start 353.693476 -278.641302)
		(end 353.763072 -278.600662)
		(width 0.1143)
		(layer "In15.Cu")
		(net "P5E_CPU0_P0_RX_DP<9>")
	)
	(segment
		(start 327.3679 -373.270272)
		(end 331.984604 -368.653568)
		(width 0.14224)
		(layer "In15.Cu")
		(net "P5E_CPU0_P0_RX_DP<9>")
	)
	(segment
		(start 353.693476 -285.12135)
		(end 353.763072 -285.08071)
		(width 0.1143)
		(layer "In15.Cu")
		(net "P5E_CPU0_P0_RX_DP<9>")
	)
	(segment
		(start 353.763072 -284.151578)
		(end 353.693476 -284.110938)
		(width 0.1143)
		(layer "In15.Cu")
		(net "P5E_CPU0_P0_RX_DP<9>")
	)
	(segment
		(start 315.03239 -393.113006)
		(end 315.035438 -392.7348)
		(width 0.14224)
		(layer "In15.Cu")
		(net "P5E_CPU0_P0_RX_DP<9>")
	)
	(segment
		(start 353.763072 -274.431506)
		(end 353.693476 -274.390866)
		(width 0.1143)
		(layer "In15.Cu")
		(net "P5E_CPU0_P0_RX_DP<9>")
	)
	(segment
		(start 323.012562 -373.400066)
		(end 327.054464 -373.400066)
		(width 0.14224)
		(layer "In15.Cu")
		(net "P5E_CPU0_P0_RX_DP<9>")
	)
	(segment
		(start 318.368934 -375.246138)
		(end 322.653152 -373.47144)
		(width 0.14224)
		(layer "In15.Cu")
		(net "P5E_CPU0_P0_RX_DP<9>")
	)
	(segment
		(start 353.193858 -304.340768)
		(end 353.193858 -296.374566)
		(width 0.14224)
		(layer "In15.Cu")
		(net "P5E_CPU0_P0_RX_DP<9>")
	)
	(segment
		(start 353.693476 -273.781266)
		(end 353.763072 -273.740626)
		(width 0.1143)
		(layer "In15.Cu")
		(net "P5E_CPU0_P0_RX_DP<9>")
	)
	(segment
		(start 332.074774 -368.61623)
		(end 359.72496 -368.61623)
		(width 0.14224)
		(layer "In15.Cu")
		(net "P5E_CPU0_P0_RX_DP<9>")
	)
	(segment
		(start 359.72496 -368.61623)
		(end 360.0323 -368.30889)
		(width 0.14224)
		(layer "In15.Cu")
		(net "P5E_CPU0_P0_RX_DP<9>")
	)
	(segment
		(start 354.940362 -271.738852)
		(end 355.023166 -271.656048)
		(width 0.1143)
		(layer "In15.Cu")
		(net "P5E_CPU0_P0_RX_DP<9>")
	)
	(segment
		(start 353.193858 -296.346118)
		(end 353.148138 -296.300398)
		(width 0.1143)
		(layer "In15.Cu")
		(net "P5E_CPU0_P0_RX_DP<9>")
	)
	(segment
		(start 360.0323 -368.30889)
		(end 360.0323 -367.50371)
		(width 0.14224)
		(layer "In15.Cu")
		(net "P5E_CPU0_P0_RX_DP<9>")
	)
	(segment
		(start 347.11894 -367.05413)
		(end 347.11894 -366.48263)
		(width 0.14224)
		(layer "In15.Cu")
		(net "P5E_CPU0_P0_RX_DP<9>")
	)
	(segment
		(start 347.11894 -366.48263)
		(end 347.26118 -366.34039)
		(width 0.14224)
		(layer "In15.Cu")
		(net "P5E_CPU0_P0_RX_DP<9>")
	)
	(segment
		(start 315.342778 -387.968236)
		(end 316.605666 -381.615442)
		(width 0.14224)
		(layer "In15.Cu")
		(net "P5E_CPU0_P0_RX_DP<9>")
	)
	(segment
		(start 353.148138 -296.300398)
		(end 353.148138 -295.919652)
		(width 0.1143)
		(layer "In15.Cu")
		(net "P5E_CPU0_P0_RX_DP<9>")
	)
	(segment
		(start 353.536504 -295.23944)
		(end 353.536504 -295.145968)
		(width 0.1143)
		(layer "In15.Cu")
		(net "P5E_CPU0_P0_RX_DP<9>")
	)
	(segment
		(start 354.162614 -272.972022)
		(end 354.206048 -272.946876)
		(width 0.1143)
		(layer "In15.Cu")
		(net "P5E_CPU0_P0_RX_DP<9>")
	)
	(segment
		(start 315.340238 -392.430254)
		(end 315.340238 -387.993128)
		(width 0.14224)
		(layer "In15.Cu")
		(net "P5E_CPU0_P0_RX_DP<9>")
	)
	(segment
		(start 353.763072 -276.051518)
		(end 353.693476 -276.010878)
		(width 0.1143)
		(layer "In15.Cu")
		(net "P5E_CPU0_P0_RX_DP<9>")
	)
	(segment
		(start 353.693476 -289.981132)
		(end 353.763072 -289.940492)
		(width 0.1143)
		(layer "In15.Cu")
		(net "P5E_CPU0_P0_RX_DP<9>")
	)
	(segment
		(start 347.26118 -366.34039)
		(end 392.712448 -366.34039)
		(width 0.14224)
		(layer "In15.Cu")
		(net "P5E_CPU0_P0_RX_DP<9>")
	)
	(segment
		(start 353.693476 -291.601144)
		(end 353.763072 -291.560504)
		(width 0.1143)
		(layer "In15.Cu")
		(net "P5E_CPU0_P0_RX_DP<9>")
	)
	(arc
		(start 353.763072 -293.180516)
		(mid 354.006399 -292.71595)
		(end 353.763072 -292.251384)
		(width 0.1143)
		(layer "In15.Cu")
		(net "P5E_CPU0_P0_RX_DP<9>")
	)
	(arc
		(start 354.476558 -272.466054)
		(mid 354.518107 -272.294632)
		(end 354.63353 -272.161254)
		(width 0.1143)
		(layer "In15.Cu")
		(net "P5E_CPU0_P0_RX_DP<9>")
	)
	(arc
		(start 353.693476 -288.97072)
		(mid 353.578049 -288.837344)
		(end 353.536504 -288.66592)
		(width 0.1143)
		(layer "In15.Cu")
		(net "P5E_CPU0_P0_RX_DP<9>")
	)
	(arc
		(start 353.763072 -273.740626)
		(mid 353.941885 -273.538276)
		(end 354.006404 -273.27606)
		(width 0.1143)
		(layer "In15.Cu")
		(net "P5E_CPU0_P0_RX_DP<9>")
	)
	(arc
		(start 353.693476 -280.870914)
		(mid 353.536499 -280.566114)
		(end 353.693476 -280.261314)
		(width 0.1143)
		(layer "In15.Cu")
		(net "P5E_CPU0_P0_RX_DP<9>")
	)
	(arc
		(start 353.763072 -286.700722)
		(mid 354.006399 -286.236156)
		(end 353.763072 -285.77159)
		(width 0.1143)
		(layer "In15.Cu")
		(net "P5E_CPU0_P0_RX_DP<9>")
	)
	(arc
		(start 353.763072 -280.220674)
		(mid 354.006399 -279.756108)
		(end 353.763072 -279.291542)
		(width 0.1143)
		(layer "In15.Cu")
		(net "P5E_CPU0_P0_RX_DP<9>")
	)
	(arc
		(start 353.763072 -283.460698)
		(mid 354.006399 -282.996132)
		(end 353.763072 -282.531566)
		(width 0.1143)
		(layer "In15.Cu")
		(net "P5E_CPU0_P0_RX_DP<9>")
	)
	(arc
		(start 367.120678 -328.121264)
		(mid 366.79334 -327.754386)
		(end 366.517936 -327.347072)
		(width 0.14224)
		(layer "In15.Cu")
		(net "P5E_CPU0_P0_RX_DP<9>")
	)
	(arc
		(start 392.712448 -366.34039)
		(mid 392.946009 -366.293914)
		(end 393.143994 -366.161574)
		(width 0.14224)
		(layer "In15.Cu")
		(net "P5E_CPU0_P0_RX_DP<9>")
	)
	(arc
		(start 353.763072 -291.560504)
		(mid 354.006399 -291.095938)
		(end 353.763072 -290.631372)
		(width 0.1143)
		(layer "In15.Cu")
		(net "P5E_CPU0_P0_RX_DP<9>")
	)
	(arc
		(start 353.763072 -281.840686)
		(mid 354.006399 -281.37612)
		(end 353.763072 -280.911554)
		(width 0.1143)
		(layer "In15.Cu")
		(net "P5E_CPU0_P0_RX_DP<9>")
	)
	(arc
		(start 353.763072 -294.800528)
		(mid 354.006399 -294.335962)
		(end 353.763072 -293.871396)
		(width 0.1143)
		(layer "In15.Cu")
		(net "P5E_CPU0_P0_RX_DP<9>")
	)
	(arc
		(start 353.693476 -285.73095)
		(mid 353.536499 -285.42615)
		(end 353.693476 -285.12135)
		(width 0.1143)
		(layer "In15.Cu")
		(net "P5E_CPU0_P0_RX_DP<9>")
	)
	(arc
		(start 331.984604 -368.653568)
		(mid 332.025974 -368.625925)
		(end 332.074774 -368.61623)
		(width 0.14224)
		(layer "In15.Cu")
		(net "P5E_CPU0_P0_RX_DP<9>")
	)
	(arc
		(start 353.536504 -295.145968)
		(mid 353.578053 -294.974546)
		(end 353.693476 -294.841168)
		(width 0.1143)
		(layer "In15.Cu")
		(net "P5E_CPU0_P0_RX_DP<9>")
	)
	(arc
		(start 353.260914 -304.588418)
		(mid 353.211014 -304.469029)
		(end 353.193858 -304.340768)
		(width 0.14224)
		(layer "In15.Cu")
		(net "P5E_CPU0_P0_RX_DP<9>")
	)
	(arc
		(start 353.693476 -287.350708)
		(mid 353.578049 -287.217332)
		(end 353.536504 -287.045908)
		(width 0.1143)
		(layer "In15.Cu")
		(net "P5E_CPU0_P0_RX_DP<9>")
	)
	(arc
		(start 353.763072 -278.600662)
		(mid 354.006399 -278.136096)
		(end 353.763072 -277.67153)
		(width 0.1143)
		(layer "In15.Cu")
		(net "P5E_CPU0_P0_RX_DP<9>")
	)
	(arc
		(start 353.693476 -290.590732)
		(mid 353.536499 -290.285932)
		(end 353.693476 -289.981132)
		(width 0.1143)
		(layer "In15.Cu")
		(net "P5E_CPU0_P0_RX_DP<9>")
	)
	(arc
		(start 353.763072 -285.08071)
		(mid 354.006399 -284.616144)
		(end 353.763072 -284.151578)
		(width 0.1143)
		(layer "In15.Cu")
		(net "P5E_CPU0_P0_RX_DP<9>")
	)
	(arc
		(start 353.763072 -275.360638)
		(mid 354.006399 -274.896072)
		(end 353.763072 -274.431506)
		(width 0.1143)
		(layer "In15.Cu")
		(net "P5E_CPU0_P0_RX_DP<9>")
	)
	(arc
		(start 354.703126 -272.120614)
		(mid 354.855113 -271.964106)
		(end 354.936552 -271.761712)
		(width 0.1143)
		(layer "In15.Cu")
		(net "P5E_CPU0_P0_RX_DP<9>")
	)
	(arc
		(start 316.605666 -377.083574)
		(mid 316.656956 -376.82581)
		(end 316.803024 -376.607324)
		(width 0.14224)
		(layer "In15.Cu")
		(net "P5E_CPU0_P0_RX_DP<9>")
	)
	(arc
		(start 353.148138 -295.919652)
		(mid 353.157977 -295.870842)
		(end 353.18573 -295.829482)
		(width 0.1143)
		(layer "In15.Cu")
		(net "P5E_CPU0_P0_RX_DP<9>")
	)
	(arc
		(start 353.693476 -284.110938)
		(mid 353.536499 -283.806138)
		(end 353.693476 -283.501338)
		(width 0.1143)
		(layer "In15.Cu")
		(net "P5E_CPU0_P0_RX_DP<9>")
	)
	(arc
		(start 353.693476 -279.250902)
		(mid 353.536499 -278.946102)
		(end 353.693476 -278.641302)
		(width 0.1143)
		(layer "In15.Cu")
		(net "P5E_CPU0_P0_RX_DP<9>")
	)
	(arc
		(start 353.693476 -292.210744)
		(mid 353.536499 -291.905944)
		(end 353.693476 -291.601144)
		(width 0.1143)
		(layer "In15.Cu")
		(net "P5E_CPU0_P0_RX_DP<9>")
	)
	(arc
		(start 353.536504 -288.66592)
		(mid 353.57747 -288.495514)
		(end 353.691444 -288.36239)
		(width 0.1143)
		(layer "In15.Cu")
		(net "P5E_CPU0_P0_RX_DP<9>")
	)
	(arc
		(start 353.763072 -276.98065)
		(mid 354.006399 -276.516084)
		(end 353.763072 -276.051518)
		(width 0.1143)
		(layer "In15.Cu")
		(net "P5E_CPU0_P0_RX_DP<9>")
	)
	(arc
		(start 353.693476 -274.390866)
		(mid 353.536499 -274.086066)
		(end 353.693476 -273.781266)
		(width 0.1143)
		(layer "In15.Cu")
		(net "P5E_CPU0_P0_RX_DP<9>")
	)
	(arc
		(start 354.006404 -273.27606)
		(mid 354.047659 -273.105089)
		(end 354.16236 -272.971768)
		(width 0.1143)
		(layer "In15.Cu")
		(net "P5E_CPU0_P0_RX_DP<9>")
	)
	(arc
		(start 354.233226 -272.93062)
		(mid 354.412039 -272.72827)
		(end 354.476558 -272.466054)
		(width 0.1143)
		(layer "In15.Cu")
		(net "P5E_CPU0_P0_RX_DP<9>")
	)
	(arc
		(start 354.936552 -271.761712)
		(mid 354.938575 -271.750302)
		(end 354.940362 -271.738852)
		(width 0.1143)
		(layer "In15.Cu")
		(net "P5E_CPU0_P0_RX_DP<9>")
	)
	(arc
		(start 393.783058 -365.52251)
		(mid 393.909023 -365.334085)
		(end 393.953238 -365.111792)
		(width 0.14224)
		(layer "In15.Cu")
		(net "P5E_CPU0_P0_RX_DP<9>")
	)
	(arc
		(start 322.653152 -373.47144)
		(mid 322.829341 -373.418041)
		(end 323.012562 -373.400066)
		(width 0.14224)
		(layer "In15.Cu")
		(net "P5E_CPU0_P0_RX_DP<9>")
	)
	(arc
		(start 353.693476 -277.63089)
		(mid 353.536499 -277.32609)
		(end 353.693476 -277.02129)
		(width 0.1143)
		(layer "In15.Cu")
		(net "P5E_CPU0_P0_RX_DP<9>")
	)
	(arc
		(start 353.419918 -295.59504)
		(mid 353.505947 -295.466661)
		(end 353.53625 -295.315132)
		(width 0.1143)
		(layer "In15.Cu")
		(net "P5E_CPU0_P0_RX_DP<9>")
	)
	(arc
		(start 353.536504 -287.045908)
		(mid 353.57747 -286.875502)
		(end 353.691444 -286.742378)
		(width 0.1143)
		(layer "In15.Cu")
		(net "P5E_CPU0_P0_RX_DP<9>")
	)
	(arc
		(start 353.763072 -289.940492)
		(mid 354.006399 -289.475926)
		(end 353.763072 -289.01136)
		(width 0.1143)
		(layer "In15.Cu")
		(net "P5E_CPU0_P0_RX_DP<9>")
	)
	(arc
		(start 353.693476 -276.010878)
		(mid 353.536499 -275.706078)
		(end 353.693476 -275.401278)
		(width 0.1143)
		(layer "In15.Cu")
		(net "P5E_CPU0_P0_RX_DP<9>")
	)
	(arc
		(start 353.693476 -282.490926)
		(mid 353.536499 -282.186126)
		(end 353.693476 -281.881326)
		(width 0.1143)
		(layer "In15.Cu")
		(net "P5E_CPU0_P0_RX_DP<9>")
	)
	(arc
		(start 327.054464 -373.400066)
		(mid 327.224081 -373.366327)
		(end 327.3679 -373.270272)
		(width 0.14224)
		(layer "In15.Cu")
		(net "P5E_CPU0_P0_RX_DP<9>")
	)
	(arc
		(start 353.693476 -293.830756)
		(mid 353.536499 -293.525956)
		(end 353.693476 -293.221156)
		(width 0.1143)
		(layer "In15.Cu")
		(net "P5E_CPU0_P0_RX_DP<9>")
	)
	(arc
		(start 393.953238 -355.152198)
		(mid 393.816026 -354.471837)
		(end 393.42568 -353.897946)
		(width 0.14224)
		(layer "In15.Cu")
		(net "P5E_CPU0_P0_RX_DP<9>")
	)
	(arc
		(start 353.763072 -288.320734)
		(mid 353.941885 -288.118384)
		(end 354.006404 -287.856168)
		(width 0.1143)
		(layer "In15.Cu")
		(net "P5E_CPU0_P0_RX_DP<9>")
	)
	(arc
		(start 315.340238 -387.993128)
		(mid 315.340902 -387.98062)
		(end 315.342778 -387.968236)
		(width 0.14224)
		(layer "In15.Cu")
		(net "P5E_CPU0_P0_RX_DP<9>")
	)
	(arc
		(start 354.006404 -287.856168)
		(mid 353.941168 -287.592577)
		(end 353.760532 -287.389824)
		(width 0.1143)
		(layer "In15.Cu")
		(net "P5E_CPU0_P0_RX_DP<9>")
	)
	(segment
		(start 352.968052 -269.770098)
		(end 352.5012 -270.036036)
		(width 0.12954)
		(layer "F.Cu")
		(net "P5E_CPU0_P0_RX_DP<8>")
	)
	(segment
		(start 313.270392 -394.385292)
		(end 313.791092 -394.385292)
		(width 0.127)
		(layer "F.Cu")
		(net "P5E_CPU0_P0_RX_DP<8>")
	)
	(segment
		(start 392.48842 -365.0234)
		(end 392.645646 -364.866174)
		(width 0.14224)
		(layer "In15.Cu")
		(net "P5E_CPU0_P0_RX_DP<8>")
	)
	(segment
		(start 352.771202 -288.981134)
		(end 352.770694 -288.98088)
		(width 0.1143)
		(layer "In15.Cu")
		(net "P5E_CPU0_P0_RX_DP<8>")
	)
	(segment
		(start 352.804984 -293.191184)
		(end 352.805238 -293.191184)
		(width 0.1143)
		(layer "In15.Cu")
		(net "P5E_CPU0_P0_RX_DP<8>")
	)
	(segment
		(start 352.752406 -284.11043)
		(end 352.732594 -284.096206)
		(width 0.1143)
		(layer "In15.Cu")
		(net "P5E_CPU0_P0_RX_DP<8>")
	)
	(segment
		(start 352.784156 -278.623522)
		(end 352.785172 -278.623014)
		(width 0.1143)
		(layer "In15.Cu")
		(net "P5E_CPU0_P0_RX_DP<8>")
	)
	(segment
		(start 352.783394 -275.384006)
		(end 352.784156 -275.383498)
		(width 0.1143)
		(layer "In15.Cu")
		(net "P5E_CPU0_P0_RX_DP<8>")
	)
	(segment
		(start 352.783394 -285.104078)
		(end 352.784156 -285.10357)
		(width 0.1143)
		(layer "In15.Cu")
		(net "P5E_CPU0_P0_RX_DP<8>")
	)
	(segment
		(start 352.133408 -270.105886)
		(end 352.203258 -270.036036)
		(width 0.1143)
		(layer "In15.Cu")
		(net "P5E_CPU0_P0_RX_DP<8>")
	)
	(segment
		(start 352.203258 -270.036036)
		(end 352.5012 -270.036036)
		(width 0.1143)
		(layer "In15.Cu")
		(net "P5E_CPU0_P0_RX_DP<8>")
	)
	(segment
		(start 352.785172 -273.762978)
		(end 352.823272 -273.740626)
		(width 0.1143)
		(layer "In15.Cu")
		(net "P5E_CPU0_P0_RX_DP<8>")
	)
	(segment
		(start 352.784156 -282.508706)
		(end 352.783394 -282.508198)
		(width 0.1143)
		(layer "In15.Cu")
		(net "P5E_CPU0_P0_RX_DP<8>")
	)
	(segment
		(start 352.783394 -281.864054)
		(end 352.784156 -281.863546)
		(width 0.1143)
		(layer "In15.Cu")
		(net "P5E_CPU0_P0_RX_DP<8>")
	)
	(segment
		(start 352.785172 -274.409154)
		(end 352.784156 -274.408646)
		(width 0.1143)
		(layer "In15.Cu")
		(net "P5E_CPU0_P0_RX_DP<8>")
	)
	(segment
		(start 352.783394 -279.268174)
		(end 352.752406 -279.250394)
		(width 0.1143)
		(layer "In15.Cu")
		(net "P5E_CPU0_P0_RX_DP<8>")
	)
	(segment
		(start 352.784156 -276.028658)
		(end 352.783394 -276.02815)
		(width 0.1143)
		(layer "In15.Cu")
		(net "P5E_CPU0_P0_RX_DP<8>")
	)
	(segment
		(start 352.731324 -272.17624)
		(end 352.747834 -272.164302)
		(width 0.1143)
		(layer "In15.Cu")
		(net "P5E_CPU0_P0_RX_DP<8>")
	)
	(segment
		(start 352.752406 -281.881834)
		(end 352.783394 -281.864054)
		(width 0.1143)
		(layer "In15.Cu")
		(net "P5E_CPU0_P0_RX_DP<8>")
	)
	(segment
		(start 352.783394 -277.648162)
		(end 352.752406 -277.630382)
		(width 0.1143)
		(layer "In15.Cu")
		(net "P5E_CPU0_P0_RX_DP<8>")
	)
	(segment
		(start 365.962692 -328.266552)
		(end 352.402648 -304.988214)
		(width 0.14224)
		(layer "In15.Cu")
		(net "P5E_CPU0_P0_RX_DP<8>")
	)
	(segment
		(start 352.784156 -272.788634)
		(end 352.783394 -272.788126)
		(width 0.1143)
		(layer "In15.Cu")
		(net "P5E_CPU0_P0_RX_DP<8>")
	)
	(segment
		(start 352.82251 -287.39084)
		(end 352.82251 -287.391094)
		(width 0.1143)
		(layer "In15.Cu")
		(net "P5E_CPU0_P0_RX_DP<8>")
	)
	(segment
		(start 352.823272 -272.811494)
		(end 352.816414 -272.80743)
		(width 0.1143)
		(layer "In15.Cu")
		(net "P5E_CPU0_P0_RX_DP<8>")
	)
	(segment
		(start 352.79584 -275.376894)
		(end 352.823272 -275.360638)
		(width 0.1143)
		(layer "In15.Cu")
		(net "P5E_CPU0_P0_RX_DP<8>")
	)
	(segment
		(start 316.98819 -375.002806)
		(end 317.112142 -374.878854)
		(width 0.14224)
		(layer "In15.Cu")
		(net "P5E_CPU0_P0_RX_DP<8>")
	)
	(segment
		(start 352.785172 -285.749238)
		(end 352.784156 -285.74873)
		(width 0.1143)
		(layer "In15.Cu")
		(net "P5E_CPU0_P0_RX_DP<8>")
	)
	(segment
		(start 338.8487 -365.414052)
		(end 338.99094 -365.271812)
		(width 0.14224)
		(layer "In15.Cu")
		(net "P5E_CPU0_P0_RX_DP<8>")
	)
	(segment
		(start 352.774504 -287.362138)
		(end 352.66757 -287.255204)
		(width 0.1143)
		(layer "In15.Cu")
		(net "P5E_CPU0_P0_RX_DP<8>")
	)
	(segment
		(start 352.815652 -282.526994)
		(end 352.785172 -282.509214)
		(width 0.1143)
		(layer "In15.Cu")
		(net "P5E_CPU0_P0_RX_DP<8>")
	)
	(segment
		(start 314.142882 -386.185156)
		(end 314.903866 -382.357884)
		(width 0.14224)
		(layer "In15.Cu")
		(net "P5E_CPU0_P0_RX_DP<8>")
	)
	(segment
		(start 352.783394 -278.62403)
		(end 352.784156 -278.623522)
		(width 0.1143)
		(layer "In15.Cu")
		(net "P5E_CPU0_P0_RX_DP<8>")
	)
	(segment
		(start 352.815652 -285.767018)
		(end 352.785172 -285.749238)
		(width 0.1143)
		(layer "In15.Cu")
		(net "P5E_CPU0_P0_RX_DP<8>")
	)
	(segment
		(start 313.886088 -394.031216)
		(end 314.060332 -393.930632)
		(width 0.14224)
		(layer "In15.Cu")
		(net "P5E_CPU0_P0_RX_DP<8>")
	)
	(segment
		(start 352.823272 -282.531566)
		(end 352.816414 -282.527502)
		(width 0.1143)
		(layer "In15.Cu")
		(net "P5E_CPU0_P0_RX_DP<8>")
	)
	(segment
		(start 352.784156 -277.00351)
		(end 352.785172 -277.003002)
		(width 0.1143)
		(layer "In15.Cu")
		(net "P5E_CPU0_P0_RX_DP<8>")
	)
	(segment
		(start 338.99094 -365.271812)
		(end 391.888726 -365.271812)
		(width 0.14224)
		(layer "In15.Cu")
		(net "P5E_CPU0_P0_RX_DP<8>")
	)
	(segment
		(start 352.82251 -293.870888)
		(end 352.792792 -293.853616)
		(width 0.1143)
		(layer "In15.Cu")
		(net "P5E_CPU0_P0_RX_DP<8>")
	)
	(segment
		(start 352.747072 -272.766282)
		(end 352.732594 -272.756122)
		(width 0.1143)
		(layer "In15.Cu")
		(net "P5E_CPU0_P0_RX_DP<8>")
	)
	(segment
		(start 352.783394 -277.004018)
		(end 352.784156 -277.00351)
		(width 0.1143)
		(layer "In15.Cu")
		(net "P5E_CPU0_P0_RX_DP<8>")
	)
	(segment
		(start 352.815652 -274.426934)
		(end 352.785172 -274.409154)
		(width 0.1143)
		(layer "In15.Cu")
		(net "P5E_CPU0_P0_RX_DP<8>")
	)
	(segment
		(start 352.787966 -275.381466)
		(end 352.79076 -275.379942)
		(width 0.1143)
		(layer "In15.Cu")
		(net "P5E_CPU0_P0_RX_DP<8>")
	)
	(segment
		(start 322.742052 -372.44147)
		(end 326.160384 -372.44147)
		(width 0.14224)
		(layer "In15.Cu")
		(net "P5E_CPU0_P0_RX_DP<8>")
	)
	(segment
		(start 352.784156 -275.383498)
		(end 352.785172 -275.38299)
		(width 0.1143)
		(layer "In15.Cu")
		(net "P5E_CPU0_P0_RX_DP<8>")
	)
	(segment
		(start 352.816414 -272.80743)
		(end 352.815652 -272.806922)
		(width 0.1143)
		(layer "In15.Cu")
		(net "P5E_CPU0_P0_RX_DP<8>")
	)
	(segment
		(start 314.400946 -376.1232)
		(end 316.791848 -375.13387)
		(width 0.14224)
		(layer "In15.Cu")
		(net "P5E_CPU0_P0_RX_DP<8>")
	)
	(segment
		(start 392.765534 -364.576868)
		(end 392.765534 -355.585522)
		(width 0.14224)
		(layer "In15.Cu")
		(net "P5E_CPU0_P0_RX_DP<8>")
	)
	(segment
		(start 352.790506 -293.852092)
		(end 352.776282 -293.843964)
		(width 0.1143)
		(layer "In15.Cu")
		(net "P5E_CPU0_P0_RX_DP<8>")
	)
	(segment
		(start 352.752914 -272.770346)
		(end 352.747834 -272.76679)
		(width 0.1143)
		(layer "In15.Cu")
		(net "P5E_CPU0_P0_RX_DP<8>")
	)
	(segment
		(start 352.785172 -285.103062)
		(end 352.823272 -285.08071)
		(width 0.1143)
		(layer "In15.Cu")
		(net "P5E_CPU0_P0_RX_DP<8>")
	)
	(segment
		(start 352.816414 -277.667466)
		(end 352.815652 -277.666958)
		(width 0.1143)
		(layer "In15.Cu")
		(net "P5E_CPU0_P0_RX_DP<8>")
	)
	(segment
		(start 392.058652 -353.903788)
		(end 366.220756 -328.597768)
		(width 0.14224)
		(layer "In15.Cu")
		(net "P5E_CPU0_P0_RX_DP<8>")
	)
	(segment
		(start 352.732594 -277.036022)
		(end 352.752406 -277.021798)
		(width 0.1143)
		(layer "In15.Cu")
		(net "P5E_CPU0_P0_RX_DP<8>")
	)
	(segment
		(start 313.388248 -378.248926)
		(end 313.264042 -378.12472)
		(width 0.14224)
		(layer "In15.Cu")
		(net "P5E_CPU0_P0_RX_DP<8>")
	)
	(segment
		(start 352.783648 -291.583618)
		(end 352.804984 -291.571172)
		(width 0.1143)
		(layer "In15.Cu")
		(net "P5E_CPU0_P0_RX_DP<8>")
	)
	(segment
		(start 352.804984 -289.95116)
		(end 352.805238 -289.95116)
		(width 0.1143)
		(layer "In15.Cu")
		(net "P5E_CPU0_P0_RX_DP<8>")
	)
	(segment
		(start 352.823272 -276.051518)
		(end 352.816414 -276.047454)
		(width 0.1143)
		(layer "In15.Cu")
		(net "P5E_CPU0_P0_RX_DP<8>")
	)
	(segment
		(start 352.783394 -284.12821)
		(end 352.752406 -284.11043)
		(width 0.1143)
		(layer "In15.Cu")
		(net "P5E_CPU0_P0_RX_DP<8>")
	)
	(segment
		(start 352.784156 -283.483558)
		(end 352.785172 -283.48305)
		(width 0.1143)
		(layer "In15.Cu")
		(net "P5E_CPU0_P0_RX_DP<8>")
	)
	(segment
		(start 326.47382 -372.311676)
		(end 331.200506 -367.58499)
		(width 0.14224)
		(layer "In15.Cu")
		(net "P5E_CPU0_P0_RX_DP<8>")
	)
	(segment
		(start 313.638946 -376.348244)
		(end 314.281312 -376.164856)
		(width 0.14224)
		(layer "In15.Cu")
		(net "P5E_CPU0_P0_RX_DP<8>")
	)
	(segment
		(start 352.747834 -272.76679)
		(end 352.747072 -272.766282)
		(width 0.1143)
		(layer "In15.Cu")
		(net "P5E_CPU0_P0_RX_DP<8>")
	)
	(segment
		(start 352.752406 -277.630382)
		(end 352.732594 -277.616158)
		(width 0.1143)
		(layer "In15.Cu")
		(net "P5E_CPU0_P0_RX_DP<8>")
	)
	(segment
		(start 352.823272 -274.431506)
		(end 352.816414 -274.427442)
		(width 0.1143)
		(layer "In15.Cu")
		(net "P5E_CPU0_P0_RX_DP<8>")
	)
	(segment
		(start 352.814636 -272.125948)
		(end 352.815398 -272.12544)
		(width 0.1143)
		(layer "In15.Cu")
		(net "P5E_CPU0_P0_RX_DP<8>")
	)
	(segment
		(start 314.745116 -379.189996)
		(end 314.145676 -378.590556)
		(width 0.14224)
		(layer "In15.Cu")
		(net "P5E_CPU0_P0_RX_DP<8>")
	)
	(segment
		(start 352.784156 -274.408646)
		(end 352.783394 -274.408138)
		(width 0.1143)
		(layer "In15.Cu")
		(net "P5E_CPU0_P0_RX_DP<8>")
	)
	(segment
		(start 352.783394 -272.788126)
		(end 352.755708 -272.772124)
		(width 0.1143)
		(layer "In15.Cu")
		(net "P5E_CPU0_P0_RX_DP<8>")
	)
	(segment
		(start 352.248724 -304.417984)
		(end 352.248724 -296.374566)
		(width 0.14224)
		(layer "In15.Cu")
		(net "P5E_CPU0_P0_RX_DP<8>")
	)
	(segment
		(start 352.804984 -291.571172)
		(end 352.805238 -291.571172)
		(width 0.1143)
		(layer "In15.Cu")
		(net "P5E_CPU0_P0_RX_DP<8>")
	)
	(segment
		(start 313.832494 -393.113006)
		(end 313.835542 -392.7348)
		(width 0.14224)
		(layer "In15.Cu")
		(net "P5E_CPU0_P0_RX_DP<8>")
	)
	(segment
		(start 352.591116 -295.331896)
		(end 352.591116 -295.151556)
		(width 0.1143)
		(layer "In15.Cu")
		(net "P5E_CPU0_P0_RX_DP<8>")
	)
	(segment
		(start 352.823272 -277.67153)
		(end 352.816414 -277.667466)
		(width 0.1143)
		(layer "In15.Cu")
		(net "P5E_CPU0_P0_RX_DP<8>")
	)
	(segment
		(start 352.732594 -278.656034)
		(end 352.752406 -278.64181)
		(width 0.1143)
		(layer "In15.Cu")
		(net "P5E_CPU0_P0_RX_DP<8>")
	)
	(segment
		(start 352.755708 -272.772124)
		(end 352.752914 -272.770346)
		(width 0.1143)
		(layer "In15.Cu")
		(net "P5E_CPU0_P0_RX_DP<8>")
	)
	(segment
		(start 352.732594 -283.51607)
		(end 352.752406 -283.501846)
		(width 0.1143)
		(layer "In15.Cu")
		(net "P5E_CPU0_P0_RX_DP<8>")
	)
	(segment
		(start 352.732594 -281.896058)
		(end 352.752406 -281.881834)
		(width 0.1143)
		(layer "In15.Cu")
		(net "P5E_CPU0_P0_RX_DP<8>")
	)
	(segment
		(start 352.752406 -273.781774)
		(end 352.783394 -273.763994)
		(width 0.1143)
		(layer "In15.Cu")
		(net "P5E_CPU0_P0_RX_DP<8>")
	)
	(segment
		(start 352.790506 -292.23208)
		(end 352.78949 -292.231572)
		(width 0.1143)
		(layer "In15.Cu")
		(net "P5E_CPU0_P0_RX_DP<8>")
	)
	(segment
		(start 352.785172 -276.029166)
		(end 352.784156 -276.028658)
		(width 0.1143)
		(layer "In15.Cu")
		(net "P5E_CPU0_P0_RX_DP<8>")
	)
	(segment
		(start 352.783394 -280.888186)
		(end 352.752406 -280.870406)
		(width 0.1143)
		(layer "In15.Cu")
		(net "P5E_CPU0_P0_RX_DP<8>")
	)
	(segment
		(start 352.248724 -296.346118)
		(end 352.203004 -296.300398)
		(width 0.1143)
		(layer "In15.Cu")
		(net "P5E_CPU0_P0_RX_DP<8>")
	)
	(segment
		(start 352.785172 -278.623014)
		(end 352.823272 -278.600662)
		(width 0.1143)
		(layer "In15.Cu")
		(net "P5E_CPU0_P0_RX_DP<8>")
	)
	(segment
		(start 313.791092 -394.385292)
		(end 313.886088 -394.031216)
		(width 0.14224)
		(layer "In15.Cu")
		(net "P5E_CPU0_P0_RX_DP<8>")
	)
	(segment
		(start 352.785172 -282.509214)
		(end 352.784156 -282.508706)
		(width 0.1143)
		(layer "In15.Cu")
		(net "P5E_CPU0_P0_RX_DP<8>")
	)
	(segment
		(start 352.240596 -295.834816)
		(end 352.482912 -295.592246)
		(width 0.1143)
		(layer "In15.Cu")
		(net "P5E_CPU0_P0_RX_DP<8>")
	)
	(segment
		(start 352.816414 -276.047454)
		(end 352.815652 -276.046946)
		(width 0.1143)
		(layer "In15.Cu")
		(net "P5E_CPU0_P0_RX_DP<8>")
	)
	(segment
		(start 352.785172 -279.26919)
		(end 352.784156 -279.268682)
		(width 0.1143)
		(layer "In15.Cu")
		(net "P5E_CPU0_P0_RX_DP<8>")
	)
	(segment
		(start 352.353118 -270.381476)
		(end 352.283522 -270.340836)
		(width 0.1143)
		(layer "In15.Cu")
		(net "P5E_CPU0_P0_RX_DP<8>")
	)
	(segment
		(start 352.752406 -283.501846)
		(end 352.783394 -283.484066)
		(width 0.1143)
		(layer "In15.Cu")
		(net "P5E_CPU0_P0_RX_DP<8>")
	)
	(segment
		(start 352.79457 -275.377656)
		(end 352.79584 -275.376894)
		(width 0.1143)
		(layer "In15.Cu")
		(net "P5E_CPU0_P0_RX_DP<8>")
	)
	(segment
		(start 352.785172 -283.48305)
		(end 352.823272 -283.460698)
		(width 0.1143)
		(layer "In15.Cu")
		(net "P5E_CPU0_P0_RX_DP<8>")
	)
	(segment
		(start 352.784156 -286.723582)
		(end 352.802444 -286.712914)
		(width 0.1143)
		(layer "In15.Cu")
		(net "P5E_CPU0_P0_RX_DP<8>")
	)
	(segment
		(start 314.145676 -378.590556)
		(end 313.492896 -378.31903)
		(width 0.14224)
		(layer "In15.Cu")
		(net "P5E_CPU0_P0_RX_DP<8>")
	)
	(segment
		(start 352.79076 -275.379942)
		(end 352.793046 -275.378672)
		(width 0.1143)
		(layer "In15.Cu")
		(net "P5E_CPU0_P0_RX_DP<8>")
	)
	(segment
		(start 352.599244 -287.090358)
		(end 352.599244 -287.000442)
		(width 0.1143)
		(layer "In15.Cu")
		(net "P5E_CPU0_P0_RX_DP<8>")
	)
	(segment
		(start 331.290422 -367.547652)
		(end 344.547444 -367.547652)
		(width 0.14224)
		(layer "In15.Cu")
		(net "P5E_CPU0_P0_RX_DP<8>")
	)
	(segment
		(start 352.784156 -277.64867)
		(end 352.783394 -277.648162)
		(width 0.1143)
		(layer "In15.Cu")
		(net "P5E_CPU0_P0_RX_DP<8>")
	)
	(segment
		(start 352.73361 -280.275538)
		(end 352.752406 -280.261822)
		(width 0.1143)
		(layer "In15.Cu")
		(net "P5E_CPU0_P0_RX_DP<8>")
	)
	(segment
		(start 352.203004 -296.300398)
		(end 352.203004 -295.924986)
		(width 0.1143)
		(layer "In15.Cu")
		(net "P5E_CPU0_P0_RX_DP<8>")
	)
	(segment
		(start 352.777552 -287.36417)
		(end 352.774504 -287.362138)
		(width 0.1143)
		(layer "In15.Cu")
		(net "P5E_CPU0_P0_RX_DP<8>")
	)
	(segment
		(start 352.788728 -292.231064)
		(end 352.776282 -292.223952)
		(width 0.1143)
		(layer "In15.Cu")
		(net "P5E_CPU0_P0_RX_DP<8>")
	)
	(segment
		(start 352.817684 -288.323528)
		(end 352.823272 -288.320734)
		(width 0.1143)
		(layer "In15.Cu")
		(net "P5E_CPU0_P0_RX_DP<8>")
	)
	(segment
		(start 352.815652 -284.147006)
		(end 352.785172 -284.129226)
		(width 0.1143)
		(layer "In15.Cu")
		(net "P5E_CPU0_P0_RX_DP<8>")
	)
	(segment
		(start 352.784156 -281.863546)
		(end 352.785172 -281.863038)
		(width 0.1143)
		(layer "In15.Cu")
		(net "P5E_CPU0_P0_RX_DP<8>")
	)
	(segment
		(start 352.784156 -280.888694)
		(end 352.783394 -280.888186)
		(width 0.1143)
		(layer "In15.Cu")
		(net "P5E_CPU0_P0_RX_DP<8>")
	)
	(segment
		(start 352.752406 -285.121858)
		(end 352.783394 -285.104078)
		(width 0.1143)
		(layer "In15.Cu")
		(net "P5E_CPU0_P0_RX_DP<8>")
	)
	(segment
		(start 352.752406 -280.261822)
		(end 352.783394 -280.244042)
		(width 0.1143)
		(layer "In15.Cu")
		(net "P5E_CPU0_P0_RX_DP<8>")
	)
	(segment
		(start 352.747834 -272.164302)
		(end 352.814636 -272.125948)
		(width 0.1143)
		(layer "In15.Cu")
		(net "P5E_CPU0_P0_RX_DP<8>")
	)
	(segment
		(start 352.820478 -271.189704)
		(end 352.784156 -271.168622)
		(width 0.1143)
		(layer "In15.Cu")
		(net "P5E_CPU0_P0_RX_DP<8>")
	)
	(segment
		(start 352.784156 -285.74873)
		(end 352.783394 -285.748222)
		(width 0.1143)
		(layer "In15.Cu")
		(net "P5E_CPU0_P0_RX_DP<8>")
	)
	(segment
		(start 352.82251 -287.391094)
		(end 352.818954 -287.389062)
		(width 0.1143)
		(layer "In15.Cu")
		(net "P5E_CPU0_P0_RX_DP<8>")
	)
	(segment
		(start 352.783648 -293.20363)
		(end 352.804984 -293.191184)
		(width 0.1143)
		(layer "In15.Cu")
		(net "P5E_CPU0_P0_RX_DP<8>")
	)
	(segment
		(start 352.815652 -276.046946)
		(end 352.785172 -276.029166)
		(width 0.1143)
		(layer "In15.Cu")
		(net "P5E_CPU0_P0_RX_DP<8>")
	)
	(segment
		(start 352.783394 -273.763994)
		(end 352.784156 -273.763486)
		(width 0.1143)
		(layer "In15.Cu")
		(net "P5E_CPU0_P0_RX_DP<8>")
	)
	(segment
		(start 352.805238 -289.95116)
		(end 352.823272 -289.940492)
		(width 0.1143)
		(layer "In15.Cu")
		(net "P5E_CPU0_P0_RX_DP<8>")
	)
	(segment
		(start 317.695326 -374.489472)
		(end 322.54444 -372.48084)
		(width 0.14224)
		(layer "In15.Cu")
		(net "P5E_CPU0_P0_RX_DP<8>")
	)
	(segment
		(start 352.785172 -280.889202)
		(end 352.784156 -280.888694)
		(width 0.1143)
		(layer "In15.Cu")
		(net "P5E_CPU0_P0_RX_DP<8>")
	)
	(segment
		(start 352.815398 -272.12544)
		(end 352.820478 -272.122392)
		(width 0.1143)
		(layer "In15.Cu")
		(net "P5E_CPU0_P0_RX_DP<8>")
	)
	(segment
		(start 352.785172 -275.38299)
		(end 352.78695 -275.381974)
		(width 0.1143)
		(layer "In15.Cu")
		(net "P5E_CPU0_P0_RX_DP<8>")
	)
	(segment
		(start 352.784664 -288.343086)
		(end 352.817684 -288.323528)
		(width 0.1143)
		(layer "In15.Cu")
		(net "P5E_CPU0_P0_RX_DP<8>")
	)
	(segment
		(start 352.785172 -294.82288)
		(end 352.79076 -294.819832)
		(width 0.1143)
		(layer "In15.Cu")
		(net "P5E_CPU0_P0_RX_DP<8>")
	)
	(segment
		(start 352.823272 -285.77159)
		(end 352.816414 -285.767526)
		(width 0.1143)
		(layer "In15.Cu")
		(net "P5E_CPU0_P0_RX_DP<8>")
	)
	(segment
		(start 352.805238 -291.571172)
		(end 352.823272 -291.560504)
		(width 0.1143)
		(layer "In15.Cu")
		(net "P5E_CPU0_P0_RX_DP<8>")
	)
	(segment
		(start 352.732594 -275.41601)
		(end 352.752406 -275.401786)
		(width 0.1143)
		(layer "In15.Cu")
		(net "P5E_CPU0_P0_RX_DP<8>")
	)
	(segment
		(start 352.78949 -292.231572)
		(end 352.788728 -292.231064)
		(width 0.1143)
		(layer "In15.Cu")
		(net "P5E_CPU0_P0_RX_DP<8>")
	)
	(segment
		(start 352.785172 -272.789142)
		(end 352.784156 -272.788634)
		(width 0.1143)
		(layer "In15.Cu")
		(net "P5E_CPU0_P0_RX_DP<8>")
	)
	(segment
		(start 352.752406 -279.250394)
		(end 352.732594 -279.23617)
		(width 0.1143)
		(layer "In15.Cu")
		(net "P5E_CPU0_P0_RX_DP<8>")
	)
	(segment
		(start 352.783648 -286.723328)
		(end 352.784156 -286.723582)
		(width 0.1143)
		(layer "In15.Cu")
		(net "P5E_CPU0_P0_RX_DP<8>")
	)
	(segment
		(start 352.783394 -294.823896)
		(end 352.784156 -294.823388)
		(width 0.1143)
		(layer "In15.Cu")
		(net "P5E_CPU0_P0_RX_DP<8>")
	)
	(segment
		(start 338.99094 -366.127792)
		(end 338.8487 -365.985552)
		(width 0.14224)
		(layer "In15.Cu")
		(net "P5E_CPU0_P0_RX_DP<8>")
	)
	(segment
		(start 338.8487 -365.985552)
		(end 338.8487 -365.414052)
		(width 0.14224)
		(layer "In15.Cu")
		(net "P5E_CPU0_P0_RX_DP<8>")
	)
	(segment
		(start 352.248724 -296.374566)
		(end 352.248724 -296.346118)
		(width 0.1143)
		(layer "In15.Cu")
		(net "P5E_CPU0_P0_RX_DP<8>")
	)
	(segment
		(start 352.816414 -282.527502)
		(end 352.815652 -282.526994)
		(width 0.1143)
		(layer "In15.Cu")
		(net "P5E_CPU0_P0_RX_DP<8>")
	)
	(segment
		(start 344.854784 -367.240312)
		(end 344.854784 -366.435132)
		(width 0.14224)
		(layer "In15.Cu")
		(net "P5E_CPU0_P0_RX_DP<8>")
	)
	(segment
		(start 352.816414 -285.767526)
		(end 352.815652 -285.767018)
		(width 0.1143)
		(layer "In15.Cu")
		(net "P5E_CPU0_P0_RX_DP<8>")
	)
	(segment
		(start 314.14847 -393.428982)
		(end 313.832494 -393.113006)
		(width 0.14224)
		(layer "In15.Cu")
		(net "P5E_CPU0_P0_RX_DP<8>")
	)
	(segment
		(start 352.802444 -286.712914)
		(end 352.823272 -286.700722)
		(width 0.1143)
		(layer "In15.Cu")
		(net "P5E_CPU0_P0_RX_DP<8>")
	)
	(segment
		(start 352.752406 -275.401786)
		(end 352.783394 -275.384006)
		(width 0.1143)
		(layer "In15.Cu")
		(net "P5E_CPU0_P0_RX_DP<8>")
	)
	(segment
		(start 352.783394 -276.02815)
		(end 352.752406 -276.01037)
		(width 0.1143)
		(layer "In15.Cu")
		(net "P5E_CPU0_P0_RX_DP<8>")
	)
	(segment
		(start 352.82251 -289.010852)
		(end 352.771202 -288.981134)
		(width 0.1143)
		(layer "In15.Cu")
		(net "P5E_CPU0_P0_RX_DP<8>")
	)
	(segment
		(start 352.784156 -284.128718)
		(end 352.783394 -284.12821)
		(width 0.1143)
		(layer "In15.Cu")
		(net "P5E_CPU0_P0_RX_DP<8>")
	)
	(segment
		(start 352.818954 -287.389062)
		(end 352.777552 -287.36417)
		(width 0.1143)
		(layer "In15.Cu")
		(net "P5E_CPU0_P0_RX_DP<8>")
	)
	(segment
		(start 352.783648 -289.963606)
		(end 352.804984 -289.95116)
		(width 0.1143)
		(layer "In15.Cu")
		(net "P5E_CPU0_P0_RX_DP<8>")
	)
	(segment
		(start 352.789744 -277.000208)
		(end 352.823272 -276.98065)
		(width 0.1143)
		(layer "In15.Cu")
		(net "P5E_CPU0_P0_RX_DP<8>")
	)
	(segment
		(start 352.785172 -281.863038)
		(end 352.823272 -281.840686)
		(width 0.1143)
		(layer "In15.Cu")
		(net "P5E_CPU0_P0_RX_DP<8>")
	)
	(segment
		(start 352.784156 -280.243534)
		(end 352.785172 -280.243026)
		(width 0.1143)
		(layer "In15.Cu")
		(net "P5E_CPU0_P0_RX_DP<8>")
	)
	(segment
		(start 352.785172 -280.243026)
		(end 352.823272 -280.220674)
		(width 0.1143)
		(layer "In15.Cu")
		(net "P5E_CPU0_P0_RX_DP<8>")
	)
	(segment
		(start 352.783394 -283.484066)
		(end 352.784156 -283.483558)
		(width 0.1143)
		(layer "In15.Cu")
		(net "P5E_CPU0_P0_RX_DP<8>")
	)
	(segment
		(start 352.784156 -279.268682)
		(end 352.783394 -279.268174)
		(width 0.1143)
		(layer "In15.Cu")
		(net "P5E_CPU0_P0_RX_DP<8>")
	)
	(segment
		(start 352.783394 -274.408138)
		(end 352.752406 -274.390358)
		(width 0.1143)
		(layer "In15.Cu")
		(net "P5E_CPU0_P0_RX_DP<8>")
	)
	(segment
		(start 314.903866 -382.357884)
		(end 314.903866 -379.573282)
		(width 0.14224)
		(layer "In15.Cu")
		(net "P5E_CPU0_P0_RX_DP<8>")
	)
	(segment
		(start 352.793046 -275.378672)
		(end 352.79457 -275.377656)
		(width 0.1143)
		(layer "In15.Cu")
		(net "P5E_CPU0_P0_RX_DP<8>")
	)
	(segment
		(start 352.815652 -272.806922)
		(end 352.785172 -272.789142)
		(width 0.1143)
		(layer "In15.Cu")
		(net "P5E_CPU0_P0_RX_DP<8>")
	)
	(segment
		(start 352.823272 -280.911554)
		(end 352.785172 -280.889202)
		(width 0.1143)
		(layer "In15.Cu")
		(net "P5E_CPU0_P0_RX_DP<8>")
	)
	(segment
		(start 352.77933 -294.826182)
		(end 352.783394 -294.823896)
		(width 0.1143)
		(layer "In15.Cu")
		(net "P5E_CPU0_P0_RX_DP<8>")
	)
	(segment
		(start 314.140342 -392.430254)
		(end 314.140342 -386.210048)
		(width 0.14224)
		(layer "In15.Cu")
		(net "P5E_CPU0_P0_RX_DP<8>")
	)
	(segment
		(start 352.784156 -294.823388)
		(end 352.785172 -294.82288)
		(width 0.1143)
		(layer "In15.Cu")
		(net "P5E_CPU0_P0_RX_DP<8>")
	)
	(segment
		(start 352.784156 -273.763486)
		(end 352.785172 -273.762978)
		(width 0.1143)
		(layer "In15.Cu")
		(net "P5E_CPU0_P0_RX_DP<8>")
	)
	(segment
		(start 352.784156 -285.10357)
		(end 352.785172 -285.103062)
		(width 0.1143)
		(layer "In15.Cu")
		(net "P5E_CPU0_P0_RX_DP<8>")
	)
	(segment
		(start 313.835542 -392.7348)
		(end 314.140342 -392.430254)
		(width 0.14224)
		(layer "In15.Cu")
		(net "P5E_CPU0_P0_RX_DP<8>")
	)
	(segment
		(start 352.783394 -282.508198)
		(end 352.752406 -282.490418)
		(width 0.1143)
		(layer "In15.Cu")
		(net "P5E_CPU0_P0_RX_DP<8>")
	)
	(segment
		(start 352.770948 -288.35096)
		(end 352.771202 -288.350706)
		(width 0.1143)
		(layer "In15.Cu")
		(net "P5E_CPU0_P0_RX_DP<8>")
	)
	(segment
		(start 352.79584 -294.816784)
		(end 352.823272 -294.800528)
		(width 0.1143)
		(layer "In15.Cu")
		(net "P5E_CPU0_P0_RX_DP<8>")
	)
	(segment
		(start 352.815652 -277.666958)
		(end 352.785172 -277.649178)
		(width 0.1143)
		(layer "In15.Cu")
		(net "P5E_CPU0_P0_RX_DP<8>")
	)
	(segment
		(start 352.823272 -279.291542)
		(end 352.816414 -279.287478)
		(width 0.1143)
		(layer "In15.Cu")
		(net "P5E_CPU0_P0_RX_DP<8>")
	)
	(segment
		(start 314.060332 -393.930632)
		(end 314.14847 -393.842494)
		(width 0.14224)
		(layer "In15.Cu")
		(net "P5E_CPU0_P0_RX_DP<8>")
	)
	(segment
		(start 352.805238 -293.191184)
		(end 352.823272 -293.180516)
		(width 0.1143)
		(layer "In15.Cu")
		(net "P5E_CPU0_P0_RX_DP<8>")
	)
	(segment
		(start 352.79076 -294.819832)
		(end 352.793046 -294.818562)
		(width 0.1143)
		(layer "In15.Cu")
		(net "P5E_CPU0_P0_RX_DP<8>")
	)
	(segment
		(start 352.79457 -294.817546)
		(end 352.79584 -294.816784)
		(width 0.1143)
		(layer "In15.Cu")
		(net "P5E_CPU0_P0_RX_DP<8>")
	)
	(segment
		(start 352.792792 -293.853616)
		(end 352.790506 -293.852092)
		(width 0.1143)
		(layer "In15.Cu")
		(net "P5E_CPU0_P0_RX_DP<8>")
	)
	(segment
		(start 352.752406 -280.870406)
		(end 352.73361 -280.85669)
		(width 0.1143)
		(layer "In15.Cu")
		(net "P5E_CPU0_P0_RX_DP<8>")
	)
	(segment
		(start 352.752406 -277.021798)
		(end 352.783394 -277.004018)
		(width 0.1143)
		(layer "In15.Cu")
		(net "P5E_CPU0_P0_RX_DP<8>")
	)
	(segment
		(start 352.816414 -274.427442)
		(end 352.815652 -274.426934)
		(width 0.1143)
		(layer "In15.Cu")
		(net "P5E_CPU0_P0_RX_DP<8>")
	)
	(segment
		(start 344.854784 -366.435132)
		(end 344.547444 -366.127792)
		(width 0.14224)
		(layer "In15.Cu")
		(net "P5E_CPU0_P0_RX_DP<8>")
	)
	(segment
		(start 313.216798 -378.010674)
		(end 313.216798 -376.792744)
		(width 0.14224)
		(layer "In15.Cu")
		(net "P5E_CPU0_P0_RX_DP<8>")
	)
	(segment
		(start 352.754438 -286.740346)
		(end 352.783648 -286.723328)
		(width 0.1143)
		(layer "In15.Cu")
		(net "P5E_CPU0_P0_RX_DP<8>")
	)
	(segment
		(start 352.78695 -275.381974)
		(end 352.787966 -275.381466)
		(width 0.1143)
		(layer "In15.Cu")
		(net "P5E_CPU0_P0_RX_DP<8>")
	)
	(segment
		(start 352.785172 -284.129226)
		(end 352.784156 -284.128718)
		(width 0.1143)
		(layer "In15.Cu")
		(net "P5E_CPU0_P0_RX_DP<8>")
	)
	(segment
		(start 352.816414 -284.147514)
		(end 352.815652 -284.147006)
		(width 0.1143)
		(layer "In15.Cu")
		(net "P5E_CPU0_P0_RX_DP<8>")
	)
	(segment
		(start 352.783394 -280.244042)
		(end 352.784156 -280.243534)
		(width 0.1143)
		(layer "In15.Cu")
		(net "P5E_CPU0_P0_RX_DP<8>")
	)
	(segment
		(start 352.815652 -279.28697)
		(end 352.785172 -279.26919)
		(width 0.1143)
		(layer "In15.Cu")
		(net "P5E_CPU0_P0_RX_DP<8>")
	)
	(segment
		(start 352.771202 -288.350706)
		(end 352.784664 -288.343086)
		(width 0.1143)
		(layer "In15.Cu")
		(net "P5E_CPU0_P0_RX_DP<8>")
	)
	(segment
		(start 352.784156 -271.168622)
		(end 352.752406 -271.150334)
		(width 0.1143)
		(layer "In15.Cu")
		(net "P5E_CPU0_P0_RX_DP<8>")
	)
	(segment
		(start 352.82251 -290.630864)
		(end 352.776282 -290.60394)
		(width 0.1143)
		(layer "In15.Cu")
		(net "P5E_CPU0_P0_RX_DP<8>")
	)
	(segment
		(start 352.783394 -285.748222)
		(end 352.752406 -285.730442)
		(width 0.1143)
		(layer "In15.Cu")
		(net "P5E_CPU0_P0_RX_DP<8>")
	)
	(segment
		(start 313.264042 -376.678698)
		(end 313.530996 -376.411744)
		(width 0.14224)
		(layer "In15.Cu")
		(net "P5E_CPU0_P0_RX_DP<8>")
	)
	(segment
		(start 352.752406 -276.01037)
		(end 352.732594 -275.996146)
		(width 0.1143)
		(layer "In15.Cu")
		(net "P5E_CPU0_P0_RX_DP<8>")
	)
	(segment
		(start 314.14847 -393.842494)
		(end 314.14847 -393.428982)
		(width 0.14224)
		(layer "In15.Cu")
		(net "P5E_CPU0_P0_RX_DP<8>")
	)
	(segment
		(start 352.816414 -279.287478)
		(end 352.815652 -279.28697)
		(width 0.1143)
		(layer "In15.Cu")
		(net "P5E_CPU0_P0_RX_DP<8>")
	)
	(segment
		(start 352.752406 -282.490418)
		(end 352.732594 -282.476194)
		(width 0.1143)
		(layer "In15.Cu")
		(net "P5E_CPU0_P0_RX_DP<8>")
	)
	(segment
		(start 352.82251 -292.250876)
		(end 352.790506 -292.23208)
		(width 0.1143)
		(layer "In15.Cu")
		(net "P5E_CPU0_P0_RX_DP<8>")
	)
	(segment
		(start 352.785172 -277.003002)
		(end 352.789744 -277.000208)
		(width 0.1143)
		(layer "In15.Cu")
		(net "P5E_CPU0_P0_RX_DP<8>")
	)
	(segment
		(start 352.823272 -284.151578)
		(end 352.816414 -284.147514)
		(width 0.1143)
		(layer "In15.Cu")
		(net "P5E_CPU0_P0_RX_DP<8>")
	)
	(segment
		(start 344.547444 -366.127792)
		(end 338.99094 -366.127792)
		(width 0.14224)
		(layer "In15.Cu")
		(net "P5E_CPU0_P0_RX_DP<8>")
	)
	(segment
		(start 352.793046 -294.818562)
		(end 352.79457 -294.817546)
		(width 0.1143)
		(layer "In15.Cu")
		(net "P5E_CPU0_P0_RX_DP<8>")
	)
	(segment
		(start 344.547444 -367.547652)
		(end 344.854784 -367.240312)
		(width 0.14224)
		(layer "In15.Cu")
		(net "P5E_CPU0_P0_RX_DP<8>")
	)
	(segment
		(start 352.752406 -278.64181)
		(end 352.783394 -278.62403)
		(width 0.1143)
		(layer "In15.Cu")
		(net "P5E_CPU0_P0_RX_DP<8>")
	)
	(segment
		(start 352.785172 -277.649178)
		(end 352.784156 -277.64867)
		(width 0.1143)
		(layer "In15.Cu")
		(net "P5E_CPU0_P0_RX_DP<8>")
	)
	(arc
		(start 352.776282 -292.223952)
		(mid 352.598065 -291.901675)
		(end 352.783648 -291.583618)
		(width 0.1143)
		(layer "In15.Cu")
		(net "P5E_CPU0_P0_RX_DP<8>")
	)
	(arc
		(start 352.732594 -277.616158)
		(mid 352.58388 -277.32609)
		(end 352.732594 -277.036022)
		(width 0.1143)
		(layer "In15.Cu")
		(net "P5E_CPU0_P0_RX_DP<8>")
	)
	(arc
		(start 352.823272 -275.360638)
		(mid 353.066599 -274.896072)
		(end 352.823272 -274.431506)
		(width 0.1143)
		(layer "In15.Cu")
		(net "P5E_CPU0_P0_RX_DP<8>")
	)
	(arc
		(start 313.216798 -376.792744)
		(mid 313.229075 -376.731021)
		(end 313.264042 -376.678698)
		(width 0.14224)
		(layer "In15.Cu")
		(net "P5E_CPU0_P0_RX_DP<8>")
	)
	(arc
		(start 352.823272 -293.871396)
		(mid 352.822891 -293.871142)
		(end 352.82251 -293.870888)
		(width 0.1143)
		(layer "In15.Cu")
		(net "P5E_CPU0_P0_RX_DP<8>")
	)
	(arc
		(start 352.823272 -280.220674)
		(mid 353.066599 -279.756108)
		(end 352.823272 -279.291542)
		(width 0.1143)
		(layer "In15.Cu")
		(net "P5E_CPU0_P0_RX_DP<8>")
	)
	(arc
		(start 352.823272 -291.560504)
		(mid 353.066599 -291.095938)
		(end 352.823272 -290.631372)
		(width 0.1143)
		(layer "In15.Cu")
		(net "P5E_CPU0_P0_RX_DP<8>")
	)
	(arc
		(start 352.732594 -275.996146)
		(mid 352.58388 -275.706078)
		(end 352.732594 -275.41601)
		(width 0.1143)
		(layer "In15.Cu")
		(net "P5E_CPU0_P0_RX_DP<8>")
	)
	(arc
		(start 352.599244 -287.000442)
		(mid 352.649365 -286.853994)
		(end 352.754438 -286.740346)
		(width 0.1143)
		(layer "In15.Cu")
		(net "P5E_CPU0_P0_RX_DP<8>")
	)
	(arc
		(start 352.776282 -290.60394)
		(mid 352.598065 -290.281663)
		(end 352.783648 -289.963606)
		(width 0.1143)
		(layer "In15.Cu")
		(net "P5E_CPU0_P0_RX_DP<8>")
	)
	(arc
		(start 352.752406 -274.390358)
		(mid 352.602021 -274.086066)
		(end 352.752406 -273.781774)
		(width 0.1143)
		(layer "In15.Cu")
		(net "P5E_CPU0_P0_RX_DP<8>")
	)
	(arc
		(start 352.823272 -288.320734)
		(mid 353.066489 -287.855638)
		(end 352.82251 -287.39084)
		(width 0.1143)
		(layer "In15.Cu")
		(net "P5E_CPU0_P0_RX_DP<8>")
	)
	(arc
		(start 366.220756 -328.597768)
		(mid 366.080583 -328.440839)
		(end 365.962692 -328.266552)
		(width 0.14224)
		(layer "In15.Cu")
		(net "P5E_CPU0_P0_RX_DP<8>")
	)
	(arc
		(start 317.112142 -374.878854)
		(mid 317.384536 -374.655412)
		(end 317.695326 -374.489472)
		(width 0.14224)
		(layer "In15.Cu")
		(net "P5E_CPU0_P0_RX_DP<8>")
	)
	(arc
		(start 392.645646 -364.866174)
		(mid 392.73439 -364.733454)
		(end 392.765534 -364.576868)
		(width 0.14224)
		(layer "In15.Cu")
		(net "P5E_CPU0_P0_RX_DP<8>")
	)
	(arc
		(start 352.732594 -282.476194)
		(mid 352.58388 -282.186126)
		(end 352.732594 -281.896058)
		(width 0.1143)
		(layer "In15.Cu")
		(net "P5E_CPU0_P0_RX_DP<8>")
	)
	(arc
		(start 313.530996 -376.411744)
		(mid 313.580921 -376.373107)
		(end 313.638946 -376.348244)
		(width 0.14224)
		(layer "In15.Cu")
		(net "P5E_CPU0_P0_RX_DP<8>")
	)
	(arc
		(start 352.591116 -295.151556)
		(mid 352.641501 -294.963578)
		(end 352.77933 -294.826182)
		(width 0.1143)
		(layer "In15.Cu")
		(net "P5E_CPU0_P0_RX_DP<8>")
	)
	(arc
		(start 352.770694 -288.98088)
		(mid 352.589496 -288.66581)
		(end 352.770948 -288.35096)
		(width 0.1143)
		(layer "In15.Cu")
		(net "P5E_CPU0_P0_RX_DP<8>")
	)
	(arc
		(start 352.823272 -286.700722)
		(mid 353.066599 -286.236156)
		(end 352.823272 -285.77159)
		(width 0.1143)
		(layer "In15.Cu")
		(net "P5E_CPU0_P0_RX_DP<8>")
	)
	(arc
		(start 352.823272 -289.01136)
		(mid 352.822891 -289.011106)
		(end 352.82251 -289.010852)
		(width 0.1143)
		(layer "In15.Cu")
		(net "P5E_CPU0_P0_RX_DP<8>")
	)
	(arc
		(start 352.732594 -272.756122)
		(mid 352.583886 -272.466538)
		(end 352.731324 -272.17624)
		(width 0.1143)
		(layer "In15.Cu")
		(net "P5E_CPU0_P0_RX_DP<8>")
	)
	(arc
		(start 352.203004 -295.924986)
		(mid 352.212843 -295.876176)
		(end 352.240596 -295.834816)
		(width 0.1143)
		(layer "In15.Cu")
		(net "P5E_CPU0_P0_RX_DP<8>")
	)
	(arc
		(start 314.140342 -386.210048)
		(mid 314.141006 -386.19754)
		(end 314.142882 -386.185156)
		(width 0.14224)
		(layer "In15.Cu")
		(net "P5E_CPU0_P0_RX_DP<8>")
	)
	(arc
		(start 352.732594 -279.23617)
		(mid 352.58388 -278.946102)
		(end 352.732594 -278.656034)
		(width 0.1143)
		(layer "In15.Cu")
		(net "P5E_CPU0_P0_RX_DP<8>")
	)
	(arc
		(start 352.823272 -281.840686)
		(mid 353.066599 -281.37612)
		(end 352.823272 -280.911554)
		(width 0.1143)
		(layer "In15.Cu")
		(net "P5E_CPU0_P0_RX_DP<8>")
	)
	(arc
		(start 352.823272 -283.460698)
		(mid 353.066599 -282.996132)
		(end 352.823272 -282.531566)
		(width 0.1143)
		(layer "In15.Cu")
		(net "P5E_CPU0_P0_RX_DP<8>")
	)
	(arc
		(start 314.903866 -379.573282)
		(mid 314.862606 -379.365854)
		(end 314.745116 -379.189996)
		(width 0.14224)
		(layer "In15.Cu")
		(net "P5E_CPU0_P0_RX_DP<8>")
	)
	(arc
		(start 352.73361 -280.85669)
		(mid 352.584695 -280.566114)
		(end 352.73361 -280.275538)
		(width 0.1143)
		(layer "In15.Cu")
		(net "P5E_CPU0_P0_RX_DP<8>")
	)
	(arc
		(start 352.59645 -270.846042)
		(mid 352.531935 -270.583823)
		(end 352.353118 -270.381476)
		(width 0.1143)
		(layer "In15.Cu")
		(net "P5E_CPU0_P0_RX_DP<8>")
	)
	(arc
		(start 352.752406 -285.730442)
		(mid 352.602021 -285.42615)
		(end 352.752406 -285.121858)
		(width 0.1143)
		(layer "In15.Cu")
		(net "P5E_CPU0_P0_RX_DP<8>")
	)
	(arc
		(start 352.823272 -293.180516)
		(mid 353.066599 -292.71595)
		(end 352.823272 -292.251384)
		(width 0.1143)
		(layer "In15.Cu")
		(net "P5E_CPU0_P0_RX_DP<8>")
	)
	(arc
		(start 322.54444 -372.48084)
		(mid 322.641309 -372.451432)
		(end 322.742052 -372.44147)
		(width 0.14224)
		(layer "In15.Cu")
		(net "P5E_CPU0_P0_RX_DP<8>")
	)
	(arc
		(start 352.732594 -284.096206)
		(mid 352.58388 -283.806138)
		(end 352.732594 -283.51607)
		(width 0.1143)
		(layer "In15.Cu")
		(net "P5E_CPU0_P0_RX_DP<8>")
	)
	(arc
		(start 352.402648 -304.988214)
		(mid 352.287845 -304.71331)
		(end 352.248724 -304.417984)
		(width 0.14224)
		(layer "In15.Cu")
		(net "P5E_CPU0_P0_RX_DP<8>")
	)
	(arc
		(start 352.820478 -272.122392)
		(mid 352.827627 -272.117492)
		(end 352.834702 -272.112486)
		(width 0.1143)
		(layer "In15.Cu")
		(net "P5E_CPU0_P0_RX_DP<8>")
	)
	(arc
		(start 314.281312 -376.164856)
		(mid 314.341721 -376.145728)
		(end 314.400946 -376.1232)
		(width 0.14224)
		(layer "In15.Cu")
		(net "P5E_CPU0_P0_RX_DP<8>")
	)
	(arc
		(start 352.776282 -293.843964)
		(mid 352.598065 -293.521687)
		(end 352.783648 -293.20363)
		(width 0.1143)
		(layer "In15.Cu")
		(net "P5E_CPU0_P0_RX_DP<8>")
	)
	(arc
		(start 352.823272 -285.08071)
		(mid 353.066599 -284.616144)
		(end 352.823272 -284.151578)
		(width 0.1143)
		(layer "In15.Cu")
		(net "P5E_CPU0_P0_RX_DP<8>")
	)
	(arc
		(start 391.888726 -365.271812)
		(mid 392.213268 -365.207239)
		(end 392.48842 -365.0234)
		(width 0.14224)
		(layer "In15.Cu")
		(net "P5E_CPU0_P0_RX_DP<8>")
	)
	(arc
		(start 352.834702 -271.19961)
		(mid 352.827628 -271.194603)
		(end 352.820478 -271.189704)
		(width 0.1143)
		(layer "In15.Cu")
		(net "P5E_CPU0_P0_RX_DP<8>")
	)
	(arc
		(start 313.492896 -378.31903)
		(mid 313.437145 -378.289098)
		(end 313.388248 -378.248926)
		(width 0.14224)
		(layer "In15.Cu")
		(net "P5E_CPU0_P0_RX_DP<8>")
	)
	(arc
		(start 352.823272 -278.600662)
		(mid 353.066599 -278.136096)
		(end 352.823272 -277.67153)
		(width 0.1143)
		(layer "In15.Cu")
		(net "P5E_CPU0_P0_RX_DP<8>")
	)
	(arc
		(start 352.823272 -294.800528)
		(mid 353.066599 -294.335962)
		(end 352.823272 -293.871396)
		(width 0.1143)
		(layer "In15.Cu")
		(net "P5E_CPU0_P0_RX_DP<8>")
	)
	(arc
		(start 313.264042 -378.12472)
		(mid 313.22908 -378.072395)
		(end 313.216798 -378.010674)
		(width 0.14224)
		(layer "In15.Cu")
		(net "P5E_CPU0_P0_RX_DP<8>")
	)
	(arc
		(start 352.823272 -290.631372)
		(mid 352.822891 -290.631118)
		(end 352.82251 -290.630864)
		(width 0.1143)
		(layer "In15.Cu")
		(net "P5E_CPU0_P0_RX_DP<8>")
	)
	(arc
		(start 331.200506 -367.58499)
		(mid 331.241746 -367.557371)
		(end 331.290422 -367.547652)
		(width 0.14224)
		(layer "In15.Cu")
		(net "P5E_CPU0_P0_RX_DP<8>")
	)
	(arc
		(start 392.765534 -355.585522)
		(mid 392.581622 -354.673401)
		(end 392.058652 -353.903788)
		(width 0.14224)
		(layer "In15.Cu")
		(net "P5E_CPU0_P0_RX_DP<8>")
	)
	(arc
		(start 316.791848 -375.13387)
		(mid 316.896497 -375.078039)
		(end 316.98819 -375.002806)
		(width 0.14224)
		(layer "In15.Cu")
		(net "P5E_CPU0_P0_RX_DP<8>")
	)
	(arc
		(start 352.823272 -276.98065)
		(mid 353.066599 -276.516084)
		(end 352.823272 -276.051518)
		(width 0.1143)
		(layer "In15.Cu")
		(net "P5E_CPU0_P0_RX_DP<8>")
	)
	(arc
		(start 352.482912 -295.592246)
		(mid 352.562892 -295.472826)
		(end 352.591116 -295.331896)
		(width 0.1143)
		(layer "In15.Cu")
		(net "P5E_CPU0_P0_RX_DP<8>")
	)
	(arc
		(start 352.834702 -272.112486)
		(mid 353.062085 -271.656048)
		(end 352.834702 -271.19961)
		(width 0.1143)
		(layer "In15.Cu")
		(net "P5E_CPU0_P0_RX_DP<8>")
	)
	(arc
		(start 352.752406 -271.150334)
		(mid 352.63773 -271.017)
		(end 352.59645 -270.846042)
		(width 0.1143)
		(layer "In15.Cu")
		(net "P5E_CPU0_P0_RX_DP<8>")
	)
	(arc
		(start 352.66757 -287.255204)
		(mid 352.616981 -287.179586)
		(end 352.599244 -287.090358)
		(width 0.1143)
		(layer "In15.Cu")
		(net "P5E_CPU0_P0_RX_DP<8>")
	)
	(arc
		(start 326.160384 -372.44147)
		(mid 326.330001 -372.407731)
		(end 326.47382 -372.311676)
		(width 0.14224)
		(layer "In15.Cu")
		(net "P5E_CPU0_P0_RX_DP<8>")
	)
	(arc
		(start 352.823272 -289.940492)
		(mid 353.066599 -289.475926)
		(end 352.823272 -289.01136)
		(width 0.1143)
		(layer "In15.Cu")
		(net "P5E_CPU0_P0_RX_DP<8>")
	)
	(arc
		(start 352.823272 -273.740626)
		(mid 353.066599 -273.27606)
		(end 352.823272 -272.811494)
		(width 0.1143)
		(layer "In15.Cu")
		(net "P5E_CPU0_P0_RX_DP<8>")
	)
	(arc
		(start 352.283522 -270.340836)
		(mid 352.185757 -270.23786)
		(end 352.133408 -270.105886)
		(width 0.1143)
		(layer "In15.Cu")
		(net "P5E_CPU0_P0_RX_DP<8>")
	)
	(arc
		(start 352.823272 -292.251384)
		(mid 352.822891 -292.25113)
		(end 352.82251 -292.250876)
		(width 0.1143)
		(layer "In15.Cu")
		(net "P5E_CPU0_P0_RX_DP<8>")
	)
	(segment
		(start 312.070242 -394.385292)
		(end 312.590942 -394.385292)
		(width 0.127)
		(layer "F.Cu")
		(net "P5E_CPU0_P0_RX_DP<7>")
	)
	(segment
		(start 352.968052 -273.010122)
		(end 352.5012 -273.27606)
		(width 0.12954)
		(layer "F.Cu")
		(net "P5E_CPU0_P0_RX_DP<7>")
	)
	(segment
		(start 351.844102 -279.268682)
		(end 351.813622 -279.250902)
		(width 0.1143)
		(layer "In13.Cu")
		(net "P5E_CPU0_P0_RX_DP<7>")
	)
	(segment
		(start 312.94832 -393.428982)
		(end 312.632344 -393.113006)
		(width 0.14224)
		(layer "In13.Cu")
		(net "P5E_CPU0_P0_RX_DP<7>")
	)
	(segment
		(start 312.632344 -393.113006)
		(end 312.635392 -392.7348)
		(width 0.14224)
		(layer "In13.Cu")
		(net "P5E_CPU0_P0_RX_DP<7>")
	)
	(segment
		(start 351.883218 -276.051518)
		(end 351.844102 -276.028658)
		(width 0.1143)
		(layer "In13.Cu")
		(net "P5E_CPU0_P0_RX_DP<7>")
	)
	(segment
		(start 351.844102 -285.74873)
		(end 351.813622 -285.73095)
		(width 0.1143)
		(layer "In13.Cu")
		(net "P5E_CPU0_P0_RX_DP<7>")
	)
	(segment
		(start 351.844102 -277.64867)
		(end 351.813622 -277.63089)
		(width 0.1143)
		(layer "In13.Cu")
		(net "P5E_CPU0_P0_RX_DP<7>")
	)
	(segment
		(start 351.844102 -289.963352)
		(end 351.883218 -289.940492)
		(width 0.1143)
		(layer "In13.Cu")
		(net "P5E_CPU0_P0_RX_DP<7>")
	)
	(segment
		(start 371.859048 -387.300724)
		(end 371.859048 -388.105904)
		(width 0.14224)
		(layer "In13.Cu")
		(net "P5E_CPU0_P0_RX_DP<7>")
	)
	(segment
		(start 390.527286 -377.744482)
		(end 390.527286 -376.377708)
		(width 0.14224)
		(layer "In13.Cu")
		(net "P5E_CPU0_P0_RX_DP<7>")
	)
	(segment
		(start 351.813622 -293.221156)
		(end 351.844102 -293.203376)
		(width 0.1143)
		(layer "In13.Cu")
		(net "P5E_CPU0_P0_RX_DP<7>")
	)
	(segment
		(start 351.844102 -281.863546)
		(end 351.883218 -281.840686)
		(width 0.1143)
		(layer "In13.Cu")
		(net "P5E_CPU0_P0_RX_DP<7>")
	)
	(segment
		(start 368.053874 -386.741416)
		(end 368.567716 -387.981952)
		(width 0.14224)
		(layer "In13.Cu")
		(net "P5E_CPU0_P0_RX_DP<7>")
	)
	(segment
		(start 351.844102 -280.243534)
		(end 351.883218 -280.220674)
		(width 0.1143)
		(layer "In13.Cu")
		(net "P5E_CPU0_P0_RX_DP<7>")
	)
	(segment
		(start 388.89686 -380.51867)
		(end 388.89686 -379.669802)
		(width 0.14224)
		(layer "In13.Cu")
		(net "P5E_CPU0_P0_RX_DP<7>")
	)
	(segment
		(start 390.407398 -376.088402)
		(end 389.93699 -375.617994)
		(width 0.14224)
		(layer "In13.Cu")
		(net "P5E_CPU0_P0_RX_DP<7>")
	)
	(segment
		(start 376.814588 -386.279644)
		(end 376.814588 -386.851144)
		(width 0.14224)
		(layer "In13.Cu")
		(net "P5E_CPU0_P0_RX_DP<7>")
	)
	(segment
		(start 352.387916 -296.502328)
		(end 352.387916 -296.47388)
		(width 0.1143)
		(layer "In13.Cu")
		(net "P5E_CPU0_P0_RX_DP<7>")
	)
	(segment
		(start 360.574082 -386.639054)
		(end 367.900712 -386.639054)
		(width 0.14224)
		(layer "In13.Cu")
		(net "P5E_CPU0_P0_RX_DP<7>")
	)
	(segment
		(start 312.685938 -394.031216)
		(end 312.860182 -393.930632)
		(width 0.14224)
		(layer "In13.Cu")
		(net "P5E_CPU0_P0_RX_DP<7>")
	)
	(segment
		(start 351.883218 -293.871396)
		(end 351.844102 -293.848536)
		(width 0.1143)
		(layer "In13.Cu")
		(net "P5E_CPU0_P0_RX_DP<7>")
	)
	(segment
		(start 351.844102 -290.608512)
		(end 351.813622 -290.590732)
		(width 0.1143)
		(layer "In13.Cu")
		(net "P5E_CPU0_P0_RX_DP<7>")
	)
	(segment
		(start 376.672348 -386.993384)
		(end 372.166388 -386.993384)
		(width 0.14224)
		(layer "In13.Cu")
		(net "P5E_CPU0_P0_RX_DP<7>")
	)
	(segment
		(start 371.003068 -386.279644)
		(end 371.145308 -386.137404)
		(width 0.14224)
		(layer "In13.Cu")
		(net "P5E_CPU0_P0_RX_DP<7>")
	)
	(segment
		(start 351.844102 -291.583364)
		(end 351.883218 -291.560504)
		(width 0.1143)
		(layer "In13.Cu")
		(net "P5E_CPU0_P0_RX_DP<7>")
	)
	(segment
		(start 389.873744 -375.46534)
		(end 389.873744 -373.322342)
		(width 0.14224)
		(layer "In13.Cu")
		(net "P5E_CPU0_P0_RX_DP<7>")
	)
	(segment
		(start 351.656396 -295.146222)
		(end 351.65665 -295.145968)
		(width 0.1143)
		(layer "In13.Cu")
		(net "P5E_CPU0_P0_RX_DP<7>")
	)
	(segment
		(start 316.99708 -386.745988)
		(end 327.366122 -386.745988)
		(width 0.14224)
		(layer "In13.Cu")
		(net "P5E_CPU0_P0_RX_DP<7>")
	)
	(segment
		(start 351.844102 -280.888694)
		(end 351.813622 -280.870914)
		(width 0.1143)
		(layer "In13.Cu")
		(net "P5E_CPU0_P0_RX_DP<7>")
	)
	(segment
		(start 351.813622 -294.841168)
		(end 351.844102 -294.823388)
		(width 0.1143)
		(layer "In13.Cu")
		(net "P5E_CPU0_P0_RX_DP<7>")
	)
	(segment
		(start 351.81159 -288.36239)
		(end 351.844102 -288.343594)
		(width 0.1143)
		(layer "In13.Cu")
		(net "P5E_CPU0_P0_RX_DP<7>")
	)
	(segment
		(start 351.883218 -280.911554)
		(end 351.844102 -280.888694)
		(width 0.1143)
		(layer "In13.Cu")
		(net "P5E_CPU0_P0_RX_DP<7>")
	)
	(segment
		(start 351.844102 -278.623522)
		(end 351.883218 -278.600662)
		(width 0.1143)
		(layer "In13.Cu")
		(net "P5E_CPU0_P0_RX_DP<7>")
	)
	(segment
		(start 387.161278 -381.70612)
		(end 387.393688 -381.47371)
		(width 0.14224)
		(layer "In13.Cu")
		(net "P5E_CPU0_P0_RX_DP<7>")
	)
	(segment
		(start 360.290618 -386.756402)
		(end 360.574082 -386.639054)
		(width 0.14224)
		(layer "In13.Cu")
		(net "P5E_CPU0_P0_RX_DP<7>")
	)
	(segment
		(start 351.883218 -285.77159)
		(end 351.844102 -285.74873)
		(width 0.1143)
		(layer "In13.Cu")
		(net "P5E_CPU0_P0_RX_DP<7>")
	)
	(segment
		(start 351.883218 -277.67153)
		(end 351.844102 -277.64867)
		(width 0.1143)
		(layer "In13.Cu")
		(net "P5E_CPU0_P0_RX_DP<7>")
	)
	(segment
		(start 376.672348 -386.137404)
		(end 376.814588 -386.279644)
		(width 0.14224)
		(layer "In13.Cu")
		(net "P5E_CPU0_P0_RX_DP<7>")
	)
	(segment
		(start 351.813622 -273.781266)
		(end 351.844102 -273.763486)
		(width 0.1143)
		(layer "In13.Cu")
		(net "P5E_CPU0_P0_RX_DP<7>")
	)
	(segment
		(start 351.813622 -291.601144)
		(end 351.844102 -291.583364)
		(width 0.1143)
		(layer "In13.Cu")
		(net "P5E_CPU0_P0_RX_DP<7>")
	)
	(segment
		(start 312.590942 -394.385292)
		(end 312.685938 -394.031216)
		(width 0.14224)
		(layer "In13.Cu")
		(net "P5E_CPU0_P0_RX_DP<7>")
	)
	(segment
		(start 351.883218 -284.151578)
		(end 351.844102 -284.128718)
		(width 0.1143)
		(layer "In13.Cu")
		(net "P5E_CPU0_P0_RX_DP<7>")
	)
	(segment
		(start 351.883218 -279.291542)
		(end 351.844102 -279.268682)
		(width 0.1143)
		(layer "In13.Cu")
		(net "P5E_CPU0_P0_RX_DP<7>")
	)
	(segment
		(start 351.813622 -285.12135)
		(end 351.844102 -285.10357)
		(width 0.1143)
		(layer "In13.Cu")
		(net "P5E_CPU0_P0_RX_DP<7>")
	)
	(segment
		(start 351.844102 -288.343594)
		(end 351.883218 -288.320734)
		(width 0.1143)
		(layer "In13.Cu")
		(net "P5E_CPU0_P0_RX_DP<7>")
	)
	(segment
		(start 351.656396 -295.34993)
		(end 351.656396 -295.146222)
		(width 0.1143)
		(layer "In13.Cu")
		(net "P5E_CPU0_P0_RX_DP<7>")
	)
	(segment
		(start 371.003068 -387.936486)
		(end 371.003068 -386.279644)
		(width 0.14224)
		(layer "In13.Cu")
		(net "P5E_CPU0_P0_RX_DP<7>")
	)
	(segment
		(start 351.813622 -280.261314)
		(end 351.844102 -280.243534)
		(width 0.1143)
		(layer "In13.Cu")
		(net "P5E_CPU0_P0_RX_DP<7>")
	)
	(segment
		(start 352.342196 -296.088308)
		(end 351.693734 -295.439846)
		(width 0.1143)
		(layer "In13.Cu")
		(net "P5E_CPU0_P0_RX_DP<7>")
	)
	(segment
		(start 351.844102 -285.10357)
		(end 351.883218 -285.08071)
		(width 0.1143)
		(layer "In13.Cu")
		(net "P5E_CPU0_P0_RX_DP<7>")
	)
	(segment
		(start 327.366122 -386.745988)
		(end 328.478388 -386.636514)
		(width 0.14224)
		(layer "In13.Cu")
		(net "P5E_CPU0_P0_RX_DP<7>")
	)
	(segment
		(start 312.635392 -392.7348)
		(end 312.940192 -392.43)
		(width 0.14224)
		(layer "In13.Cu")
		(net "P5E_CPU0_P0_RX_DP<7>")
	)
	(segment
		(start 386.941568 -388.293356)
		(end 386.994146 -388.240778)
		(width 0.14224)
		(layer "In13.Cu")
		(net "P5E_CPU0_P0_RX_DP<7>")
	)
	(segment
		(start 330.788772 -386.715)
		(end 331.419454 -388.237476)
		(width 0.14224)
		(layer "In13.Cu")
		(net "P5E_CPU0_P0_RX_DP<7>")
	)
	(segment
		(start 351.813622 -283.501338)
		(end 351.844102 -283.483558)
		(width 0.1143)
		(layer "In13.Cu")
		(net "P5E_CPU0_P0_RX_DP<7>")
	)
	(segment
		(start 351.883218 -292.251384)
		(end 351.844102 -292.228524)
		(width 0.1143)
		(layer "In13.Cu")
		(net "P5E_CPU0_P0_RX_DP<7>")
	)
	(segment
		(start 351.813622 -277.02129)
		(end 351.844102 -277.00351)
		(width 0.1143)
		(layer "In13.Cu")
		(net "P5E_CPU0_P0_RX_DP<7>")
	)
	(segment
		(start 387.114034 -387.951472)
		(end 387.114034 -381.820166)
		(width 0.14224)
		(layer "In13.Cu")
		(net "P5E_CPU0_P0_RX_DP<7>")
	)
	(segment
		(start 352.120454 -273.358864)
		(end 352.203258 -273.27606)
		(width 0.1143)
		(layer "In13.Cu")
		(net "P5E_CPU0_P0_RX_DP<7>")
	)
	(segment
		(start 357.763826 -386.756402)
		(end 360.290618 -386.756402)
		(width 0.14224)
		(layer "In13.Cu")
		(net "P5E_CPU0_P0_RX_DP<7>")
	)
	(segment
		(start 312.94832 -393.842494)
		(end 312.94832 -393.428982)
		(width 0.14224)
		(layer "In13.Cu")
		(net "P5E_CPU0_P0_RX_DP<7>")
	)
	(segment
		(start 372.166388 -386.993384)
		(end 371.859048 -387.300724)
		(width 0.14224)
		(layer "In13.Cu")
		(net "P5E_CPU0_P0_RX_DP<7>")
	)
	(segment
		(start 312.987436 -390.68883)
		(end 316.883034 -386.793232)
		(width 0.14224)
		(layer "In13.Cu")
		(net "P5E_CPU0_P0_RX_DP<7>")
	)
	(segment
		(start 351.81159 -286.742378)
		(end 351.844102 -286.723582)
		(width 0.1143)
		(layer "In13.Cu")
		(net "P5E_CPU0_P0_RX_DP<7>")
	)
	(segment
		(start 372.166388 -388.413244)
		(end 386.652262 -388.413244)
		(width 0.14224)
		(layer "In13.Cu")
		(net "P5E_CPU0_P0_RX_DP<7>")
	)
	(segment
		(start 352.342196 -296.42816)
		(end 352.342196 -296.088308)
		(width 0.1143)
		(layer "In13.Cu")
		(net "P5E_CPU0_P0_RX_DP<7>")
	)
	(segment
		(start 351.844102 -274.408646)
		(end 351.813622 -274.390866)
		(width 0.1143)
		(layer "In13.Cu")
		(net "P5E_CPU0_P0_RX_DP<7>")
	)
	(segment
		(start 389.873744 -373.322342)
		(end 364.63986 -312.403744)
		(width 0.14224)
		(layer "In13.Cu")
		(net "P5E_CPU0_P0_RX_DP<7>")
	)
	(segment
		(start 351.844102 -283.483558)
		(end 351.883218 -283.460698)
		(width 0.1143)
		(layer "In13.Cu")
		(net "P5E_CPU0_P0_RX_DP<7>")
	)
	(segment
		(start 351.844102 -288.9885)
		(end 351.813622 -288.97072)
		(width 0.1143)
		(layer "In13.Cu")
		(net "P5E_CPU0_P0_RX_DP<7>")
	)
	(segment
		(start 351.844102 -273.763486)
		(end 351.883218 -273.740626)
		(width 0.1143)
		(layer "In13.Cu")
		(net "P5E_CPU0_P0_RX_DP<7>")
	)
	(segment
		(start 352.203258 -273.27606)
		(end 352.5012 -273.27606)
		(width 0.1143)
		(layer "In13.Cu")
		(net "P5E_CPU0_P0_RX_DP<7>")
	)
	(segment
		(start 364.63986 -312.403744)
		(end 352.46056 -297.562524)
		(width 0.14224)
		(layer "In13.Cu")
		(net "P5E_CPU0_P0_RX_DP<7>")
	)
	(segment
		(start 351.883218 -290.631372)
		(end 351.844102 -290.608512)
		(width 0.1143)
		(layer "In13.Cu")
		(net "P5E_CPU0_P0_RX_DP<7>")
	)
	(segment
		(start 369.213892 -388.413244)
		(end 370.52631 -388.413244)
		(width 0.14224)
		(layer "In13.Cu")
		(net "P5E_CPU0_P0_RX_DP<7>")
	)
	(segment
		(start 351.883218 -282.531566)
		(end 351.844102 -282.508706)
		(width 0.1143)
		(layer "In13.Cu")
		(net "P5E_CPU0_P0_RX_DP<7>")
	)
	(segment
		(start 376.814588 -386.851144)
		(end 376.672348 -386.993384)
		(width 0.14224)
		(layer "In13.Cu")
		(net "P5E_CPU0_P0_RX_DP<7>")
	)
	(segment
		(start 370.815616 -388.293356)
		(end 370.88318 -388.225792)
		(width 0.14224)
		(layer "In13.Cu")
		(net "P5E_CPU0_P0_RX_DP<7>")
	)
	(segment
		(start 371.145308 -386.137404)
		(end 376.672348 -386.137404)
		(width 0.14224)
		(layer "In13.Cu")
		(net "P5E_CPU0_P0_RX_DP<7>")
	)
	(segment
		(start 388.216648 -381.156464)
		(end 388.567422 -381.011176)
		(width 0.14224)
		(layer "In13.Cu")
		(net "P5E_CPU0_P0_RX_DP<7>")
	)
	(segment
		(start 351.813622 -275.401278)
		(end 351.844102 -275.383498)
		(width 0.1143)
		(layer "In13.Cu")
		(net "P5E_CPU0_P0_RX_DP<7>")
	)
	(segment
		(start 352.387916 -297.36034)
		(end 352.387916 -296.502328)
		(width 0.14224)
		(layer "In13.Cu")
		(net "P5E_CPU0_P0_RX_DP<7>")
	)
	(segment
		(start 387.498082 -381.404114)
		(end 387.80339 -381.277876)
		(width 0.14224)
		(layer "In13.Cu")
		(net "P5E_CPU0_P0_RX_DP<7>")
	)
	(segment
		(start 351.844102 -282.508706)
		(end 351.813622 -282.490926)
		(width 0.1143)
		(layer "In13.Cu")
		(net "P5E_CPU0_P0_RX_DP<7>")
	)
	(segment
		(start 351.844102 -292.228524)
		(end 351.813622 -292.210744)
		(width 0.1143)
		(layer "In13.Cu")
		(net "P5E_CPU0_P0_RX_DP<7>")
	)
	(segment
		(start 351.883218 -274.431506)
		(end 351.844102 -274.408646)
		(width 0.1143)
		(layer "In13.Cu")
		(net "P5E_CPU0_P0_RX_DP<7>")
	)
	(segment
		(start 312.860182 -393.930632)
		(end 312.94832 -393.842494)
		(width 0.14224)
		(layer "In13.Cu")
		(net "P5E_CPU0_P0_RX_DP<7>")
	)
	(segment
		(start 312.940192 -392.43)
		(end 312.940192 -390.802876)
		(width 0.14224)
		(layer "In13.Cu")
		(net "P5E_CPU0_P0_RX_DP<7>")
	)
	(segment
		(start 371.859048 -388.105904)
		(end 372.166388 -388.413244)
		(width 0.14224)
		(layer "In13.Cu")
		(net "P5E_CPU0_P0_RX_DP<7>")
	)
	(segment
		(start 351.813622 -278.641302)
		(end 351.844102 -278.623522)
		(width 0.1143)
		(layer "In13.Cu")
		(net "P5E_CPU0_P0_RX_DP<7>")
	)
	(segment
		(start 351.813622 -289.981132)
		(end 351.844102 -289.963352)
		(width 0.1143)
		(layer "In13.Cu")
		(net "P5E_CPU0_P0_RX_DP<7>")
	)
	(segment
		(start 351.844102 -277.00351)
		(end 351.883218 -276.98065)
		(width 0.1143)
		(layer "In13.Cu")
		(net "P5E_CPU0_P0_RX_DP<7>")
	)
	(segment
		(start 351.844102 -294.823388)
		(end 351.883218 -294.800528)
		(width 0.1143)
		(layer "In13.Cu")
		(net "P5E_CPU0_P0_RX_DP<7>")
	)
	(segment
		(start 351.844102 -275.383498)
		(end 351.883218 -275.360638)
		(width 0.1143)
		(layer "In13.Cu")
		(net "P5E_CPU0_P0_RX_DP<7>")
	)
	(segment
		(start 351.813622 -281.881326)
		(end 351.844102 -281.863546)
		(width 0.1143)
		(layer "In13.Cu")
		(net "P5E_CPU0_P0_RX_DP<7>")
	)
	(segment
		(start 351.880678 -287.389824)
		(end 351.813622 -287.350708)
		(width 0.1143)
		(layer "In13.Cu")
		(net "P5E_CPU0_P0_RX_DP<7>")
	)
	(segment
		(start 351.844102 -293.203376)
		(end 351.883218 -293.180516)
		(width 0.1143)
		(layer "In13.Cu")
		(net "P5E_CPU0_P0_RX_DP<7>")
	)
	(segment
		(start 388.944104 -379.555756)
		(end 390.365996 -378.133864)
		(width 0.14224)
		(layer "In13.Cu")
		(net "P5E_CPU0_P0_RX_DP<7>")
	)
	(segment
		(start 351.844102 -284.128718)
		(end 351.813622 -284.110938)
		(width 0.1143)
		(layer "In13.Cu")
		(net "P5E_CPU0_P0_RX_DP<7>")
	)
	(segment
		(start 351.844102 -293.848536)
		(end 351.813622 -293.830756)
		(width 0.1143)
		(layer "In13.Cu")
		(net "P5E_CPU0_P0_RX_DP<7>")
	)
	(segment
		(start 355.937312 -388.360666)
		(end 357.38435 -386.913628)
		(width 0.14224)
		(layer "In13.Cu")
		(net "P5E_CPU0_P0_RX_DP<7>")
	)
	(segment
		(start 351.844102 -276.028658)
		(end 351.813622 -276.010878)
		(width 0.1143)
		(layer "In13.Cu")
		(net "P5E_CPU0_P0_RX_DP<7>")
	)
	(segment
		(start 331.797152 -388.49046)
		(end 355.623876 -388.49046)
		(width 0.14224)
		(layer "In13.Cu")
		(net "P5E_CPU0_P0_RX_DP<7>")
	)
	(segment
		(start 328.478388 -386.636514)
		(end 330.671424 -386.636514)
		(width 0.14224)
		(layer "In13.Cu")
		(net "P5E_CPU0_P0_RX_DP<7>")
	)
	(segment
		(start 352.387916 -296.47388)
		(end 352.342196 -296.42816)
		(width 0.1143)
		(layer "In13.Cu")
		(net "P5E_CPU0_P0_RX_DP<7>")
	)
	(segment
		(start 351.844102 -286.723582)
		(end 351.883218 -286.700722)
		(width 0.1143)
		(layer "In13.Cu")
		(net "P5E_CPU0_P0_RX_DP<7>")
	)
	(segment
		(start 351.883218 -289.01136)
		(end 351.844102 -288.9885)
		(width 0.1143)
		(layer "In13.Cu")
		(net "P5E_CPU0_P0_RX_DP<7>")
	)
	(arc
		(start 352.46056 -297.562524)
		(mid 352.406699 -297.467732)
		(end 352.387916 -297.36034)
		(width 0.14224)
		(layer "In13.Cu")
		(net "P5E_CPU0_P0_RX_DP<7>")
	)
	(arc
		(start 351.883218 -273.740626)
		(mid 352.035205 -273.584118)
		(end 352.116644 -273.381724)
		(width 0.1143)
		(layer "In13.Cu")
		(net "P5E_CPU0_P0_RX_DP<7>")
	)
	(arc
		(start 351.883218 -276.98065)
		(mid 352.126545 -276.516084)
		(end 351.883218 -276.051518)
		(width 0.1143)
		(layer "In13.Cu")
		(net "P5E_CPU0_P0_RX_DP<7>")
	)
	(arc
		(start 386.652262 -388.413244)
		(mid 386.80884 -388.382081)
		(end 386.941568 -388.293356)
		(width 0.14224)
		(layer "In13.Cu")
		(net "P5E_CPU0_P0_RX_DP<7>")
	)
	(arc
		(start 351.813622 -284.110938)
		(mid 351.656645 -283.806138)
		(end 351.813622 -283.501338)
		(width 0.1143)
		(layer "In13.Cu")
		(net "P5E_CPU0_P0_RX_DP<7>")
	)
	(arc
		(start 331.419454 -388.237476)
		(mid 331.569896 -388.421352)
		(end 331.797152 -388.49046)
		(width 0.14224)
		(layer "In13.Cu")
		(net "P5E_CPU0_P0_RX_DP<7>")
	)
	(arc
		(start 387.80339 -381.277876)
		(mid 387.904898 -381.242137)
		(end 388.009638 -381.217424)
		(width 0.14224)
		(layer "In13.Cu")
		(net "P5E_CPU0_P0_RX_DP<7>")
	)
	(arc
		(start 390.365996 -378.133864)
		(mid 390.485366 -377.955214)
		(end 390.527286 -377.744482)
		(width 0.14224)
		(layer "In13.Cu")
		(net "P5E_CPU0_P0_RX_DP<7>")
	)
	(arc
		(start 386.994146 -388.240778)
		(mid 387.08289 -388.108058)
		(end 387.114034 -387.951472)
		(width 0.14224)
		(layer "In13.Cu")
		(net "P5E_CPU0_P0_RX_DP<7>")
	)
	(arc
		(start 387.393688 -381.47371)
		(mid 387.44246 -381.433776)
		(end 387.498082 -381.404114)
		(width 0.14224)
		(layer "In13.Cu")
		(net "P5E_CPU0_P0_RX_DP<7>")
	)
	(arc
		(start 351.813622 -274.390866)
		(mid 351.656645 -274.086066)
		(end 351.813622 -273.781266)
		(width 0.1143)
		(layer "In13.Cu")
		(net "P5E_CPU0_P0_RX_DP<7>")
	)
	(arc
		(start 351.813622 -285.73095)
		(mid 351.656645 -285.42615)
		(end 351.813622 -285.12135)
		(width 0.1143)
		(layer "In13.Cu")
		(net "P5E_CPU0_P0_RX_DP<7>")
	)
	(arc
		(start 370.52631 -388.413244)
		(mid 370.682888 -388.382081)
		(end 370.815616 -388.293356)
		(width 0.14224)
		(layer "In13.Cu")
		(net "P5E_CPU0_P0_RX_DP<7>")
	)
	(arc
		(start 351.813622 -288.97072)
		(mid 351.698195 -288.837344)
		(end 351.65665 -288.66592)
		(width 0.1143)
		(layer "In13.Cu")
		(net "P5E_CPU0_P0_RX_DP<7>")
	)
	(arc
		(start 351.813622 -292.210744)
		(mid 351.656645 -291.905944)
		(end 351.813622 -291.601144)
		(width 0.1143)
		(layer "In13.Cu")
		(net "P5E_CPU0_P0_RX_DP<7>")
	)
	(arc
		(start 351.883218 -291.560504)
		(mid 352.126545 -291.095938)
		(end 351.883218 -290.631372)
		(width 0.1143)
		(layer "In13.Cu")
		(net "P5E_CPU0_P0_RX_DP<7>")
	)
	(arc
		(start 351.813622 -290.590732)
		(mid 351.656645 -290.285932)
		(end 351.813622 -289.981132)
		(width 0.1143)
		(layer "In13.Cu")
		(net "P5E_CPU0_P0_RX_DP<7>")
	)
	(arc
		(start 351.813622 -282.490926)
		(mid 351.656645 -282.186126)
		(end 351.813622 -281.881326)
		(width 0.1143)
		(layer "In13.Cu")
		(net "P5E_CPU0_P0_RX_DP<7>")
	)
	(arc
		(start 351.883218 -288.320734)
		(mid 352.062031 -288.118384)
		(end 352.12655 -287.856168)
		(width 0.1143)
		(layer "In13.Cu")
		(net "P5E_CPU0_P0_RX_DP<7>")
	)
	(arc
		(start 351.813622 -293.830756)
		(mid 351.656645 -293.525956)
		(end 351.813622 -293.221156)
		(width 0.1143)
		(layer "In13.Cu")
		(net "P5E_CPU0_P0_RX_DP<7>")
	)
	(arc
		(start 351.813622 -277.63089)
		(mid 351.656645 -277.32609)
		(end 351.813622 -277.02129)
		(width 0.1143)
		(layer "In13.Cu")
		(net "P5E_CPU0_P0_RX_DP<7>")
	)
	(arc
		(start 352.116644 -273.381724)
		(mid 352.118667 -273.370314)
		(end 352.120454 -273.358864)
		(width 0.1143)
		(layer "In13.Cu")
		(net "P5E_CPU0_P0_RX_DP<7>")
	)
	(arc
		(start 351.813622 -279.250902)
		(mid 351.656645 -278.946102)
		(end 351.813622 -278.641302)
		(width 0.1143)
		(layer "In13.Cu")
		(net "P5E_CPU0_P0_RX_DP<7>")
	)
	(arc
		(start 351.883218 -281.840686)
		(mid 352.126545 -281.37612)
		(end 351.883218 -280.911554)
		(width 0.1143)
		(layer "In13.Cu")
		(net "P5E_CPU0_P0_RX_DP<7>")
	)
	(arc
		(start 351.883218 -289.940492)
		(mid 352.126545 -289.475926)
		(end 351.883218 -289.01136)
		(width 0.1143)
		(layer "In13.Cu")
		(net "P5E_CPU0_P0_RX_DP<7>")
	)
	(arc
		(start 390.527286 -376.377708)
		(mid 390.496123 -376.22113)
		(end 390.407398 -376.088402)
		(width 0.14224)
		(layer "In13.Cu")
		(net "P5E_CPU0_P0_RX_DP<7>")
	)
	(arc
		(start 368.567716 -387.981952)
		(mid 368.825437 -388.295501)
		(end 369.213892 -388.413244)
		(width 0.14224)
		(layer "In13.Cu")
		(net "P5E_CPU0_P0_RX_DP<7>")
	)
	(arc
		(start 352.12655 -287.856168)
		(mid 352.061314 -287.592577)
		(end 351.880678 -287.389824)
		(width 0.1143)
		(layer "In13.Cu")
		(net "P5E_CPU0_P0_RX_DP<7>")
	)
	(arc
		(start 351.693734 -295.439846)
		(mid 351.666115 -295.398606)
		(end 351.656396 -295.34993)
		(width 0.1143)
		(layer "In13.Cu")
		(net "P5E_CPU0_P0_RX_DP<7>")
	)
	(arc
		(start 351.883218 -286.700722)
		(mid 352.126545 -286.236156)
		(end 351.883218 -285.77159)
		(width 0.1143)
		(layer "In13.Cu")
		(net "P5E_CPU0_P0_RX_DP<7>")
	)
	(arc
		(start 367.900712 -386.639054)
		(mid 367.992838 -386.666992)
		(end 368.053874 -386.741416)
		(width 0.14224)
		(layer "In13.Cu")
		(net "P5E_CPU0_P0_RX_DP<7>")
	)
	(arc
		(start 351.65665 -288.66592)
		(mid 351.697616 -288.495514)
		(end 351.81159 -288.36239)
		(width 0.1143)
		(layer "In13.Cu")
		(net "P5E_CPU0_P0_RX_DP<7>")
	)
	(arc
		(start 351.883218 -293.180516)
		(mid 352.126545 -292.71595)
		(end 351.883218 -292.251384)
		(width 0.1143)
		(layer "In13.Cu")
		(net "P5E_CPU0_P0_RX_DP<7>")
	)
	(arc
		(start 387.114034 -381.820166)
		(mid 387.126311 -381.758443)
		(end 387.161278 -381.70612)
		(width 0.14224)
		(layer "In13.Cu")
		(net "P5E_CPU0_P0_RX_DP<7>")
	)
	(arc
		(start 351.65665 -287.045908)
		(mid 351.697616 -286.875502)
		(end 351.81159 -286.742378)
		(width 0.1143)
		(layer "In13.Cu")
		(net "P5E_CPU0_P0_RX_DP<7>")
	)
	(arc
		(start 351.883218 -283.460698)
		(mid 352.126545 -282.996132)
		(end 351.883218 -282.531566)
		(width 0.1143)
		(layer "In13.Cu")
		(net "P5E_CPU0_P0_RX_DP<7>")
	)
	(arc
		(start 388.009638 -381.217424)
		(mid 388.114782 -381.192508)
		(end 388.216648 -381.156464)
		(width 0.14224)
		(layer "In13.Cu")
		(net "P5E_CPU0_P0_RX_DP<7>")
	)
	(arc
		(start 316.883034 -386.793232)
		(mid 316.935359 -386.75827)
		(end 316.99708 -386.745988)
		(width 0.14224)
		(layer "In13.Cu")
		(net "P5E_CPU0_P0_RX_DP<7>")
	)
	(arc
		(start 351.883218 -285.08071)
		(mid 352.126545 -284.616144)
		(end 351.883218 -284.151578)
		(width 0.1143)
		(layer "In13.Cu")
		(net "P5E_CPU0_P0_RX_DP<7>")
	)
	(arc
		(start 351.813622 -280.870914)
		(mid 351.656645 -280.566114)
		(end 351.813622 -280.261314)
		(width 0.1143)
		(layer "In13.Cu")
		(net "P5E_CPU0_P0_RX_DP<7>")
	)
	(arc
		(start 351.883218 -278.600662)
		(mid 352.126545 -278.136096)
		(end 351.883218 -277.67153)
		(width 0.1143)
		(layer "In13.Cu")
		(net "P5E_CPU0_P0_RX_DP<7>")
	)
	(arc
		(start 312.940192 -390.802876)
		(mid 312.952469 -390.741153)
		(end 312.987436 -390.68883)
		(width 0.14224)
		(layer "In13.Cu")
		(net "P5E_CPU0_P0_RX_DP<7>")
	)
	(arc
		(start 351.813622 -276.010878)
		(mid 351.656645 -275.706078)
		(end 351.813622 -275.401278)
		(width 0.1143)
		(layer "In13.Cu")
		(net "P5E_CPU0_P0_RX_DP<7>")
	)
	(arc
		(start 351.813622 -287.350708)
		(mid 351.698195 -287.217332)
		(end 351.65665 -287.045908)
		(width 0.1143)
		(layer "In13.Cu")
		(net "P5E_CPU0_P0_RX_DP<7>")
	)
	(arc
		(start 351.65665 -295.145968)
		(mid 351.698199 -294.974546)
		(end 351.813622 -294.841168)
		(width 0.1143)
		(layer "In13.Cu")
		(net "P5E_CPU0_P0_RX_DP<7>")
	)
	(arc
		(start 389.93699 -375.617994)
		(mid 389.890192 -375.547956)
		(end 389.873744 -375.46534)
		(width 0.14224)
		(layer "In13.Cu")
		(net "P5E_CPU0_P0_RX_DP<7>")
	)
	(arc
		(start 388.567422 -381.011176)
		(mid 388.806896 -380.81493)
		(end 388.89686 -380.51867)
		(width 0.14224)
		(layer "In13.Cu")
		(net "P5E_CPU0_P0_RX_DP<7>")
	)
	(arc
		(start 388.89686 -379.669802)
		(mid 388.909137 -379.608079)
		(end 388.944104 -379.555756)
		(width 0.14224)
		(layer "In13.Cu")
		(net "P5E_CPU0_P0_RX_DP<7>")
	)
	(arc
		(start 351.883218 -275.360638)
		(mid 352.126545 -274.896072)
		(end 351.883218 -274.431506)
		(width 0.1143)
		(layer "In13.Cu")
		(net "P5E_CPU0_P0_RX_DP<7>")
	)
	(arc
		(start 351.883218 -280.220674)
		(mid 352.126545 -279.756108)
		(end 351.883218 -279.291542)
		(width 0.1143)
		(layer "In13.Cu")
		(net "P5E_CPU0_P0_RX_DP<7>")
	)
	(arc
		(start 357.38435 -386.913628)
		(mid 357.558441 -386.797241)
		(end 357.763826 -386.756402)
		(width 0.14224)
		(layer "In13.Cu")
		(net "P5E_CPU0_P0_RX_DP<7>")
	)
	(arc
		(start 351.883218 -294.800528)
		(mid 352.126545 -294.335962)
		(end 351.883218 -293.871396)
		(width 0.1143)
		(layer "In13.Cu")
		(net "P5E_CPU0_P0_RX_DP<7>")
	)
	(arc
		(start 355.623876 -388.49046)
		(mid 355.793493 -388.456721)
		(end 355.937312 -388.360666)
		(width 0.14224)
		(layer "In13.Cu")
		(net "P5E_CPU0_P0_RX_DP<7>")
	)
	(arc
		(start 330.671424 -386.636514)
		(mid 330.742017 -386.657941)
		(end 330.788772 -386.715)
		(width 0.14224)
		(layer "In13.Cu")
		(net "P5E_CPU0_P0_RX_DP<7>")
	)
	(arc
		(start 370.88318 -388.225792)
		(mid 370.971924 -388.093072)
		(end 371.003068 -387.936486)
		(width 0.14224)
		(layer "In13.Cu")
		(net "P5E_CPU0_P0_RX_DP<7>")
	)
	(segment
		(start 310.870346 -394.385292)
		(end 311.391046 -394.385292)
		(width 0.127)
		(layer "F.Cu")
		(net "P5E_CPU0_P0_RX_DP<6>")
	)
	(segment
		(start 352.968052 -271.39011)
		(end 352.5012 -271.656048)
		(width 0.12954)
		(layer "F.Cu")
		(net "P5E_CPU0_P0_RX_DP<6>")
	)
	(segment
		(start 385.816856 -378.883672)
		(end 386.538724 -378.40031)
		(width 0.14224)
		(layer "In13.Cu")
		(net "P5E_CPU0_P0_RX_DP<6>")
	)
	(segment
		(start 350.904048 -285.74873)
		(end 350.873568 -285.73095)
		(width 0.1143)
		(layer "In13.Cu")
		(net "P5E_CPU0_P0_RX_DP<6>")
	)
	(segment
		(start 350.904048 -276.028658)
		(end 350.873568 -276.010878)
		(width 0.1143)
		(layer "In13.Cu")
		(net "P5E_CPU0_P0_RX_DP<6>")
	)
	(segment
		(start 363.903514 -313.137042)
		(end 351.460816 -297.97629)
		(width 0.14224)
		(layer "In13.Cu")
		(net "P5E_CPU0_P0_RX_DP<6>")
	)
	(segment
		(start 350.904048 -280.243534)
		(end 350.943164 -280.220674)
		(width 0.1143)
		(layer "In13.Cu")
		(net "P5E_CPU0_P0_RX_DP<6>")
	)
	(segment
		(start 385.57581 -379.107192)
		(end 385.71932 -378.963936)
		(width 0.14224)
		(layer "In13.Cu")
		(net "P5E_CPU0_P0_RX_DP<6>")
	)
	(segment
		(start 350.943164 -279.291542)
		(end 350.904048 -279.268682)
		(width 0.1143)
		(layer "In13.Cu")
		(net "P5E_CPU0_P0_RX_DP<6>")
	)
	(segment
		(start 350.904048 -285.10357)
		(end 350.943164 -285.08071)
		(width 0.1143)
		(layer "In13.Cu")
		(net "P5E_CPU0_P0_RX_DP<6>")
	)
	(segment
		(start 336.36077 -384.816096)
		(end 336.54873 -385.004056)
		(width 0.14224)
		(layer "In13.Cu")
		(net "P5E_CPU0_P0_RX_DP<6>")
	)
	(segment
		(start 357.97998 -384.508756)
		(end 359.933494 -382.554734)
		(width 0.14224)
		(layer "In13.Cu")
		(net "P5E_CPU0_P0_RX_DP<6>")
	)
	(segment
		(start 385.014216 -380.917196)
		(end 385.289298 -380.642114)
		(width 0.14224)
		(layer "In13.Cu")
		(net "P5E_CPU0_P0_RX_DP<6>")
	)
	(segment
		(start 351.253552 -296.552112)
		(end 351.253552 -296.113962)
		(width 0.1143)
		(layer "In13.Cu")
		(net "P5E_CPU0_P0_RX_DP<6>")
	)
	(segment
		(start 385.409186 -380.352808)
		(end 385.409186 -379.509274)
		(width 0.14224)
		(layer "In13.Cu")
		(net "P5E_CPU0_P0_RX_DP<6>")
	)
	(segment
		(start 387.097778 -377.674886)
		(end 387.097778 -376.814842)
		(width 0.14224)
		(layer "In13.Cu")
		(net "P5E_CPU0_P0_RX_DP<6>")
	)
	(segment
		(start 343.746328 -386.783326)
		(end 343.746328 -385.978146)
		(width 0.14224)
		(layer "In13.Cu")
		(net "P5E_CPU0_P0_RX_DP<6>")
	)
	(segment
		(start 350.873568 -277.02129)
		(end 350.943164 -276.98065)
		(width 0.1143)
		(layer "In13.Cu")
		(net "P5E_CPU0_P0_RX_DP<6>")
	)
	(segment
		(start 332.624938 -384.778758)
		(end 336.2706 -384.778758)
		(width 0.14224)
		(layer "In13.Cu")
		(net "P5E_CPU0_P0_RX_DP<6>")
	)
	(segment
		(start 343.746328 -385.978146)
		(end 343.438988 -385.670806)
		(width 0.14224)
		(layer "In13.Cu")
		(net "P5E_CPU0_P0_RX_DP<6>")
	)
	(segment
		(start 338.005928 -384.957066)
		(end 338.148168 -384.814826)
		(width 0.14224)
		(layer "In13.Cu")
		(net "P5E_CPU0_P0_RX_DP<6>")
	)
	(segment
		(start 311.432448 -393.113006)
		(end 311.435496 -392.7348)
		(width 0.14224)
		(layer "In13.Cu")
		(net "P5E_CPU0_P0_RX_DP<6>")
	)
	(segment
		(start 350.943164 -292.251384)
		(end 350.873568 -292.210744)
		(width 0.1143)
		(layer "In13.Cu")
		(net "P5E_CPU0_P0_RX_DP<6>")
	)
	(segment
		(start 350.873568 -278.641302)
		(end 350.904048 -278.623522)
		(width 0.1143)
		(layer "In13.Cu")
		(net "P5E_CPU0_P0_RX_DP<6>")
	)
	(segment
		(start 388.047738 -374.520968)
		(end 388.047738 -371.40515)
		(width 0.14224)
		(layer "In13.Cu")
		(net "P5E_CPU0_P0_RX_DP<6>")
	)
	(segment
		(start 336.586068 -385.093972)
		(end 336.586068 -386.783326)
		(width 0.14224)
		(layer "In13.Cu")
		(net "P5E_CPU0_P0_RX_DP<6>")
	)
	(segment
		(start 350.904048 -273.763486)
		(end 350.943164 -273.740626)
		(width 0.1143)
		(layer "In13.Cu")
		(net "P5E_CPU0_P0_RX_DP<6>")
	)
	(segment
		(start 350.904048 -278.623522)
		(end 350.943164 -278.600662)
		(width 0.1143)
		(layer "In13.Cu")
		(net "P5E_CPU0_P0_RX_DP<6>")
	)
	(segment
		(start 350.943164 -289.01136)
		(end 350.904048 -288.9885)
		(width 0.1143)
		(layer "In13.Cu")
		(net "P5E_CPU0_P0_RX_DP<6>")
	)
	(segment
		(start 350.716342 -295.524174)
		(end 350.716342 -295.053004)
		(width 0.1143)
		(layer "In13.Cu")
		(net "P5E_CPU0_P0_RX_DP<6>")
	)
	(segment
		(start 350.943164 -276.051518)
		(end 350.904048 -276.028658)
		(width 0.1143)
		(layer "In13.Cu")
		(net "P5E_CPU0_P0_RX_DP<6>")
	)
	(segment
		(start 351.299526 -297.52544)
		(end 351.299526 -296.612564)
		(width 0.14224)
		(layer "In13.Cu")
		(net "P5E_CPU0_P0_RX_DP<6>")
	)
	(segment
		(start 350.873568 -275.401278)
		(end 350.904048 -275.383498)
		(width 0.1143)
		(layer "In13.Cu")
		(net "P5E_CPU0_P0_RX_DP<6>")
	)
	(segment
		(start 350.716342 -295.053004)
		(end 350.716596 -295.053258)
		(width 0.1143)
		(layer "In13.Cu")
		(net "P5E_CPU0_P0_RX_DP<6>")
	)
	(segment
		(start 350.873568 -291.601144)
		(end 350.943164 -291.560504)
		(width 0.1143)
		(layer "In13.Cu")
		(net "P5E_CPU0_P0_RX_DP<6>")
	)
	(segment
		(start 336.586068 -386.783326)
		(end 336.893408 -387.090666)
		(width 0.14224)
		(layer "In13.Cu")
		(net "P5E_CPU0_P0_RX_DP<6>")
	)
	(segment
		(start 350.943164 -284.151578)
		(end 350.873568 -284.110938)
		(width 0.1143)
		(layer "In13.Cu")
		(net "P5E_CPU0_P0_RX_DP<6>")
	)
	(segment
		(start 350.871536 -286.742378)
		(end 350.904048 -286.723582)
		(width 0.1143)
		(layer "In13.Cu")
		(net "P5E_CPU0_P0_RX_DP<6>")
	)
	(segment
		(start 350.873568 -293.221156)
		(end 350.943164 -293.180516)
		(width 0.1143)
		(layer "In13.Cu")
		(net "P5E_CPU0_P0_RX_DP<6>")
	)
	(segment
		(start 350.873568 -281.881326)
		(end 350.904048 -281.863546)
		(width 0.1143)
		(layer "In13.Cu")
		(net "P5E_CPU0_P0_RX_DP<6>")
	)
	(segment
		(start 311.435496 -392.7348)
		(end 311.740296 -392.430254)
		(width 0.14224)
		(layer "In13.Cu")
		(net "P5E_CPU0_P0_RX_DP<6>")
	)
	(segment
		(start 350.943164 -277.67153)
		(end 350.904048 -277.64867)
		(width 0.1143)
		(layer "In13.Cu")
		(net "P5E_CPU0_P0_RX_DP<6>")
	)
	(segment
		(start 350.904048 -280.888694)
		(end 350.873568 -280.870914)
		(width 0.1143)
		(layer "In13.Cu")
		(net "P5E_CPU0_P0_RX_DP<6>")
	)
	(segment
		(start 386.636514 -378.320046)
		(end 386.967984 -377.988576)
		(width 0.14224)
		(layer "In13.Cu")
		(net "P5E_CPU0_P0_RX_DP<6>")
	)
	(segment
		(start 352.203258 -271.656048)
		(end 352.5012 -271.656048)
		(width 0.1143)
		(layer "In13.Cu")
		(net "P5E_CPU0_P0_RX_DP<6>")
	)
	(segment
		(start 351.299272 -296.597832)
		(end 351.253552 -296.552112)
		(width 0.1143)
		(layer "In13.Cu")
		(net "P5E_CPU0_P0_RX_DP<6>")
	)
	(segment
		(start 350.904048 -281.863546)
		(end 350.943164 -281.840686)
		(width 0.1143)
		(layer "In13.Cu")
		(net "P5E_CPU0_P0_RX_DP<6>")
	)
	(segment
		(start 350.904048 -286.723582)
		(end 350.943164 -286.700722)
		(width 0.1143)
		(layer "In13.Cu")
		(net "P5E_CPU0_P0_RX_DP<6>")
	)
	(segment
		(start 351.342452 -272.971768)
		(end 351.377758 -272.951448)
		(width 0.1143)
		(layer "In13.Cu")
		(net "P5E_CPU0_P0_RX_DP<6>")
	)
	(segment
		(start 351.299272 -296.61231)
		(end 351.299272 -296.597832)
		(width 0.1143)
		(layer "In13.Cu")
		(net "P5E_CPU0_P0_RX_DP<6>")
	)
	(segment
		(start 350.904048 -277.64867)
		(end 350.873568 -277.63089)
		(width 0.1143)
		(layer "In13.Cu")
		(net "P5E_CPU0_P0_RX_DP<6>")
	)
	(segment
		(start 319.411604 -376.283982)
		(end 327.514712 -376.283982)
		(width 0.14224)
		(layer "In13.Cu")
		(net "P5E_CPU0_P0_RX_DP<6>")
	)
	(segment
		(start 383.69367 -384.341878)
		(end 383.69367 -381.67691)
		(width 0.14224)
		(layer "In13.Cu")
		(net "P5E_CPU0_P0_RX_DP<6>")
	)
	(segment
		(start 367.821464 -384.894328)
		(end 383.14122 -384.894328)
		(width 0.14224)
		(layer "In13.Cu")
		(net "P5E_CPU0_P0_RX_DP<6>")
	)
	(segment
		(start 350.943164 -282.531566)
		(end 350.873568 -282.490926)
		(width 0.1143)
		(layer "In13.Cu")
		(net "P5E_CPU0_P0_RX_DP<6>")
	)
	(segment
		(start 350.90862 -294.820594)
		(end 350.94164 -294.801544)
		(width 0.1143)
		(layer "In13.Cu")
		(net "P5E_CPU0_P0_RX_DP<6>")
	)
	(segment
		(start 350.940624 -287.389824)
		(end 350.873568 -287.350708)
		(width 0.1143)
		(layer "In13.Cu")
		(net "P5E_CPU0_P0_RX_DP<6>")
	)
	(segment
		(start 343.438988 -387.090666)
		(end 343.746328 -386.783326)
		(width 0.14224)
		(layer "In13.Cu")
		(net "P5E_CPU0_P0_RX_DP<6>")
	)
	(segment
		(start 365.60633 -382.89738)
		(end 367.448846 -384.739896)
		(width 0.14224)
		(layer "In13.Cu")
		(net "P5E_CPU0_P0_RX_DP<6>")
	)
	(segment
		(start 351.844102 -272.143474)
		(end 351.883218 -272.120614)
		(width 0.1143)
		(layer "In13.Cu")
		(net "P5E_CPU0_P0_RX_DP<6>")
	)
	(segment
		(start 350.873568 -285.12135)
		(end 350.904048 -285.10357)
		(width 0.1143)
		(layer "In13.Cu")
		(net "P5E_CPU0_P0_RX_DP<6>")
	)
	(segment
		(start 311.740296 -392.430254)
		(end 311.740296 -390.552686)
		(width 0.14224)
		(layer "In13.Cu")
		(net "P5E_CPU0_P0_RX_DP<6>")
	)
	(segment
		(start 350.904048 -274.408646)
		(end 350.873568 -274.390866)
		(width 0.1143)
		(layer "In13.Cu")
		(net "P5E_CPU0_P0_RX_DP<6>")
	)
	(segment
		(start 350.94164 -293.87038)
		(end 350.873568 -293.830756)
		(width 0.1143)
		(layer "In13.Cu")
		(net "P5E_CPU0_P0_RX_DP<6>")
	)
	(segment
		(start 338.005928 -385.528566)
		(end 338.005928 -384.957066)
		(width 0.14224)
		(layer "In13.Cu")
		(net "P5E_CPU0_P0_RX_DP<6>")
	)
	(segment
		(start 338.148168 -384.814826)
		(end 357.457248 -384.814826)
		(width 0.14224)
		(layer "In13.Cu")
		(net "P5E_CPU0_P0_RX_DP<6>")
	)
	(segment
		(start 343.438988 -385.670806)
		(end 338.148168 -385.670806)
		(width 0.14224)
		(layer "In13.Cu")
		(net "P5E_CPU0_P0_RX_DP<6>")
	)
	(segment
		(start 352.120454 -271.738852)
		(end 352.203258 -271.656048)
		(width 0.1143)
		(layer "In13.Cu")
		(net "P5E_CPU0_P0_RX_DP<6>")
	)
	(segment
		(start 350.904048 -288.343594)
		(end 350.943164 -288.320734)
		(width 0.1143)
		(layer "In13.Cu")
		(net "P5E_CPU0_P0_RX_DP<6>")
	)
	(segment
		(start 338.148168 -385.670806)
		(end 338.005928 -385.528566)
		(width 0.14224)
		(layer "In13.Cu")
		(net "P5E_CPU0_P0_RX_DP<6>")
	)
	(segment
		(start 311.748424 -393.842494)
		(end 311.748424 -393.428982)
		(width 0.14224)
		(layer "In13.Cu")
		(net "P5E_CPU0_P0_RX_DP<6>")
	)
	(segment
		(start 350.873568 -280.261314)
		(end 350.904048 -280.243534)
		(width 0.1143)
		(layer "In13.Cu")
		(net "P5E_CPU0_P0_RX_DP<6>")
	)
	(segment
		(start 387.097778 -376.814842)
		(end 388.047738 -374.520968)
		(width 0.14224)
		(layer "In13.Cu")
		(net "P5E_CPU0_P0_RX_DP<6>")
	)
	(segment
		(start 350.873568 -273.781266)
		(end 350.904048 -273.763486)
		(width 0.1143)
		(layer "In13.Cu")
		(net "P5E_CPU0_P0_RX_DP<6>")
	)
	(segment
		(start 360.02341 -382.517396)
		(end 364.689136 -382.517396)
		(width 0.14224)
		(layer "In13.Cu")
		(net "P5E_CPU0_P0_RX_DP<6>")
	)
	(segment
		(start 311.660286 -393.930632)
		(end 311.748424 -393.842494)
		(width 0.14224)
		(layer "In13.Cu")
		(net "P5E_CPU0_P0_RX_DP<6>")
	)
	(segment
		(start 351.299526 -296.612564)
		(end 351.299272 -296.61231)
		(width 0.14224)
		(layer "In13.Cu")
		(net "P5E_CPU0_P0_RX_DP<6>")
	)
	(segment
		(start 350.904048 -279.268682)
		(end 350.873568 -279.250902)
		(width 0.1143)
		(layer "In13.Cu")
		(net "P5E_CPU0_P0_RX_DP<6>")
	)
	(segment
		(start 350.943164 -274.431506)
		(end 350.904048 -274.408646)
		(width 0.1143)
		(layer "In13.Cu")
		(net "P5E_CPU0_P0_RX_DP<6>")
	)
	(segment
		(start 350.799908 -294.891968)
		(end 350.90862 -294.820848)
		(width 0.1143)
		(layer "In13.Cu")
		(net "P5E_CPU0_P0_RX_DP<6>")
	)
	(segment
		(start 350.871536 -288.36239)
		(end 350.904048 -288.343594)
		(width 0.1143)
		(layer "In13.Cu")
		(net "P5E_CPU0_P0_RX_DP<6>")
	)
	(segment
		(start 350.873568 -283.501338)
		(end 350.904048 -283.483558)
		(width 0.1143)
		(layer "In13.Cu")
		(net "P5E_CPU0_P0_RX_DP<6>")
	)
	(segment
		(start 350.90862 -294.820848)
		(end 350.90862 -294.820594)
		(width 0.1143)
		(layer "In13.Cu")
		(net "P5E_CPU0_P0_RX_DP<6>")
	)
	(segment
		(start 350.904048 -283.483558)
		(end 350.943164 -283.460698)
		(width 0.1143)
		(layer "In13.Cu")
		(net "P5E_CPU0_P0_RX_DP<6>")
	)
	(segment
		(start 317.698882 -377.943872)
		(end 319.321434 -376.32132)
		(width 0.14224)
		(layer "In13.Cu")
		(net "P5E_CPU0_P0_RX_DP<6>")
	)
	(segment
		(start 311.748424 -393.428982)
		(end 311.432448 -393.113006)
		(width 0.14224)
		(layer "In13.Cu")
		(net "P5E_CPU0_P0_RX_DP<6>")
	)
	(segment
		(start 350.904048 -275.383498)
		(end 350.943164 -275.360638)
		(width 0.1143)
		(layer "In13.Cu")
		(net "P5E_CPU0_P0_RX_DP<6>")
	)
	(segment
		(start 336.893408 -387.090666)
		(end 343.438988 -387.090666)
		(width 0.14224)
		(layer "In13.Cu")
		(net "P5E_CPU0_P0_RX_DP<6>")
	)
	(segment
		(start 350.904048 -288.9885)
		(end 350.873568 -288.97072)
		(width 0.1143)
		(layer "In13.Cu")
		(net "P5E_CPU0_P0_RX_DP<6>")
	)
	(segment
		(start 328.584052 -376.998738)
		(end 331.493622 -384.022854)
		(width 0.14224)
		(layer "In13.Cu")
		(net "P5E_CPU0_P0_RX_DP<6>")
	)
	(segment
		(start 311.486042 -394.031216)
		(end 311.660286 -393.930632)
		(width 0.14224)
		(layer "In13.Cu")
		(net "P5E_CPU0_P0_RX_DP<6>")
	)
	(segment
		(start 350.943164 -290.631372)
		(end 350.873568 -290.590732)
		(width 0.1143)
		(layer "In13.Cu")
		(net "P5E_CPU0_P0_RX_DP<6>")
	)
	(segment
		(start 350.943164 -280.911554)
		(end 350.904048 -280.888694)
		(width 0.1143)
		(layer "In13.Cu")
		(net "P5E_CPU0_P0_RX_DP<6>")
	)
	(segment
		(start 351.84334 -272.143982)
		(end 351.844102 -272.143474)
		(width 0.1143)
		(layer "In13.Cu")
		(net "P5E_CPU0_P0_RX_DP<6>")
	)
	(segment
		(start 350.943164 -285.77159)
		(end 350.904048 -285.74873)
		(width 0.1143)
		(layer "In13.Cu")
		(net "P5E_CPU0_P0_RX_DP<6>")
	)
	(segment
		(start 388.047738 -371.40515)
		(end 363.903514 -313.137042)
		(width 0.14224)
		(layer "In13.Cu")
		(net "P5E_CPU0_P0_RX_DP<6>")
	)
	(segment
		(start 350.873568 -289.981132)
		(end 350.943164 -289.940492)
		(width 0.1143)
		(layer "In13.Cu")
		(net "P5E_CPU0_P0_RX_DP<6>")
	)
	(segment
		(start 311.391046 -394.385292)
		(end 311.486042 -394.031216)
		(width 0.14224)
		(layer "In13.Cu")
		(net "P5E_CPU0_P0_RX_DP<6>")
	)
	(segment
		(start 311.752488 -390.49833)
		(end 317.673736 -377.979686)
		(width 0.14224)
		(layer "In13.Cu")
		(net "P5E_CPU0_P0_RX_DP<6>")
	)
	(segment
		(start 351.253552 -296.113962)
		(end 350.75368 -295.61409)
		(width 0.1143)
		(layer "In13.Cu")
		(net "P5E_CPU0_P0_RX_DP<6>")
	)
	(arc
		(start 386.967984 -377.988576)
		(mid 387.06412 -377.844653)
		(end 387.097778 -377.674886)
		(width 0.14224)
		(layer "In13.Cu")
		(net "P5E_CPU0_P0_RX_DP<6>")
	)
	(arc
		(start 350.943164 -285.08071)
		(mid 351.186491 -284.616144)
		(end 350.943164 -284.151578)
		(width 0.1143)
		(layer "In13.Cu")
		(net "P5E_CPU0_P0_RX_DP<6>")
	)
	(arc
		(start 383.854706 -381.410464)
		(mid 383.980453 -381.359711)
		(end 384.113786 -381.335026)
		(width 0.14224)
		(layer "In13.Cu")
		(net "P5E_CPU0_P0_RX_DP<6>")
	)
	(arc
		(start 317.673736 -377.979686)
		(mid 317.68477 -377.960699)
		(end 317.698882 -377.943872)
		(width 0.14224)
		(layer "In13.Cu")
		(net "P5E_CPU0_P0_RX_DP<6>")
	)
	(arc
		(start 311.740296 -390.552686)
		(mid 311.743382 -390.524833)
		(end 311.752488 -390.49833)
		(width 0.14224)
		(layer "In13.Cu")
		(net "P5E_CPU0_P0_RX_DP<6>")
	)
	(arc
		(start 350.943164 -288.320734)
		(mid 351.121977 -288.118384)
		(end 351.186496 -287.856168)
		(width 0.1143)
		(layer "In13.Cu")
		(net "P5E_CPU0_P0_RX_DP<6>")
	)
	(arc
		(start 350.873568 -280.870914)
		(mid 350.716591 -280.566114)
		(end 350.873568 -280.261314)
		(width 0.1143)
		(layer "In13.Cu")
		(net "P5E_CPU0_P0_RX_DP<6>")
	)
	(arc
		(start 383.69367 -381.67691)
		(mid 383.737053 -381.521239)
		(end 383.854706 -381.410464)
		(width 0.14224)
		(layer "In13.Cu")
		(net "P5E_CPU0_P0_RX_DP<6>")
	)
	(arc
		(start 385.289298 -380.642114)
		(mid 385.378042 -380.509394)
		(end 385.409186 -380.352808)
		(width 0.14224)
		(layer "In13.Cu")
		(net "P5E_CPU0_P0_RX_DP<6>")
	)
	(arc
		(start 350.716596 -287.045908)
		(mid 350.757562 -286.875502)
		(end 350.871536 -286.742378)
		(width 0.1143)
		(layer "In13.Cu")
		(net "P5E_CPU0_P0_RX_DP<6>")
	)
	(arc
		(start 350.94164 -294.801544)
		(mid 351.186461 -294.335962)
		(end 350.94164 -293.87038)
		(width 0.1143)
		(layer "In13.Cu")
		(net "P5E_CPU0_P0_RX_DP<6>")
	)
	(arc
		(start 350.943164 -273.740626)
		(mid 351.121977 -273.538276)
		(end 351.186496 -273.27606)
		(width 0.1143)
		(layer "In13.Cu")
		(net "P5E_CPU0_P0_RX_DP<6>")
	)
	(arc
		(start 385.71932 -378.963936)
		(mid 385.766138 -378.921434)
		(end 385.816856 -378.883672)
		(width 0.14224)
		(layer "In13.Cu")
		(net "P5E_CPU0_P0_RX_DP<6>")
	)
	(arc
		(start 351.186496 -287.856168)
		(mid 351.12126 -287.592577)
		(end 350.940624 -287.389824)
		(width 0.1143)
		(layer "In13.Cu")
		(net "P5E_CPU0_P0_RX_DP<6>")
	)
	(arc
		(start 384.113786 -381.335026)
		(mid 384.601081 -381.205996)
		(end 385.014216 -380.917196)
		(width 0.14224)
		(layer "In13.Cu")
		(net "P5E_CPU0_P0_RX_DP<6>")
	)
	(arc
		(start 350.873568 -287.350708)
		(mid 350.758141 -287.217332)
		(end 350.716596 -287.045908)
		(width 0.1143)
		(layer "In13.Cu")
		(net "P5E_CPU0_P0_RX_DP<6>")
	)
	(arc
		(start 336.2706 -384.778758)
		(mid 336.319395 -384.788464)
		(end 336.36077 -384.816096)
		(width 0.14224)
		(layer "In13.Cu")
		(net "P5E_CPU0_P0_RX_DP<6>")
	)
	(arc
		(start 350.873568 -293.830756)
		(mid 350.716591 -293.525956)
		(end 350.873568 -293.221156)
		(width 0.1143)
		(layer "In13.Cu")
		(net "P5E_CPU0_P0_RX_DP<6>")
	)
	(arc
		(start 319.321434 -376.32132)
		(mid 319.362804 -376.293677)
		(end 319.411604 -376.283982)
		(width 0.14224)
		(layer "In13.Cu")
		(net "P5E_CPU0_P0_RX_DP<6>")
	)
	(arc
		(start 350.943164 -286.700722)
		(mid 351.186491 -286.236156)
		(end 350.943164 -285.77159)
		(width 0.1143)
		(layer "In13.Cu")
		(net "P5E_CPU0_P0_RX_DP<6>")
	)
	(arc
		(start 350.873568 -279.250902)
		(mid 350.716591 -278.946102)
		(end 350.873568 -278.641302)
		(width 0.1143)
		(layer "In13.Cu")
		(net "P5E_CPU0_P0_RX_DP<6>")
	)
	(arc
		(start 350.943164 -293.180516)
		(mid 351.186491 -292.71595)
		(end 350.943164 -292.251384)
		(width 0.1143)
		(layer "In13.Cu")
		(net "P5E_CPU0_P0_RX_DP<6>")
	)
	(arc
		(start 350.716596 -295.053258)
		(mid 350.738594 -294.962455)
		(end 350.799908 -294.891968)
		(width 0.1143)
		(layer "In13.Cu")
		(net "P5E_CPU0_P0_RX_DP<6>")
	)
	(arc
		(start 350.943164 -289.940492)
		(mid 351.186491 -289.475926)
		(end 350.943164 -289.01136)
		(width 0.1143)
		(layer "In13.Cu")
		(net "P5E_CPU0_P0_RX_DP<6>")
	)
	(arc
		(start 351.377758 -272.951448)
		(mid 351.583826 -272.744585)
		(end 351.65919 -272.462498)
		(width 0.1143)
		(layer "In13.Cu")
		(net "P5E_CPU0_P0_RX_DP<6>")
	)
	(arc
		(start 350.873568 -290.590732)
		(mid 350.716591 -290.285932)
		(end 350.873568 -289.981132)
		(width 0.1143)
		(layer "In13.Cu")
		(net "P5E_CPU0_P0_RX_DP<6>")
	)
	(arc
		(start 357.457248 -384.814826)
		(mid 357.613965 -384.788419)
		(end 357.753158 -384.711702)
		(width 0.14224)
		(layer "In13.Cu")
		(net "P5E_CPU0_P0_RX_DP<6>")
	)
	(arc
		(start 350.873568 -292.210744)
		(mid 350.716591 -291.905944)
		(end 350.873568 -291.601144)
		(width 0.1143)
		(layer "In13.Cu")
		(net "P5E_CPU0_P0_RX_DP<6>")
	)
	(arc
		(start 350.873568 -282.490926)
		(mid 350.716591 -282.186126)
		(end 350.873568 -281.881326)
		(width 0.1143)
		(layer "In13.Cu")
		(net "P5E_CPU0_P0_RX_DP<6>")
	)
	(arc
		(start 336.54873 -385.004056)
		(mid 336.576349 -385.045296)
		(end 336.586068 -385.093972)
		(width 0.14224)
		(layer "In13.Cu")
		(net "P5E_CPU0_P0_RX_DP<6>")
	)
	(arc
		(start 351.65919 -272.462498)
		(mid 351.708541 -272.278539)
		(end 351.84334 -272.143982)
		(width 0.1143)
		(layer "In13.Cu")
		(net "P5E_CPU0_P0_RX_DP<6>")
	)
	(arc
		(start 385.409186 -379.509274)
		(mid 385.452491 -379.291654)
		(end 385.57581 -379.107192)
		(width 0.14224)
		(layer "In13.Cu")
		(net "P5E_CPU0_P0_RX_DP<6>")
	)
	(arc
		(start 351.186496 -273.27606)
		(mid 351.227751 -273.105089)
		(end 351.342452 -272.971768)
		(width 0.1143)
		(layer "In13.Cu")
		(net "P5E_CPU0_P0_RX_DP<6>")
	)
	(arc
		(start 350.873568 -285.73095)
		(mid 350.716591 -285.42615)
		(end 350.873568 -285.12135)
		(width 0.1143)
		(layer "In13.Cu")
		(net "P5E_CPU0_P0_RX_DP<6>")
	)
	(arc
		(start 350.943164 -276.98065)
		(mid 351.186491 -276.516084)
		(end 350.943164 -276.051518)
		(width 0.1143)
		(layer "In13.Cu")
		(net "P5E_CPU0_P0_RX_DP<6>")
	)
	(arc
		(start 350.943164 -283.460698)
		(mid 351.186491 -282.996132)
		(end 350.943164 -282.531566)
		(width 0.1143)
		(layer "In13.Cu")
		(net "P5E_CPU0_P0_RX_DP<6>")
	)
	(arc
		(start 350.716596 -288.66592)
		(mid 350.757562 -288.495514)
		(end 350.871536 -288.36239)
		(width 0.1143)
		(layer "In13.Cu")
		(net "P5E_CPU0_P0_RX_DP<6>")
	)
	(arc
		(start 350.873568 -288.97072)
		(mid 350.758141 -288.837344)
		(end 350.716596 -288.66592)
		(width 0.1143)
		(layer "In13.Cu")
		(net "P5E_CPU0_P0_RX_DP<6>")
	)
	(arc
		(start 352.116644 -271.761712)
		(mid 352.118667 -271.750302)
		(end 352.120454 -271.738852)
		(width 0.1143)
		(layer "In13.Cu")
		(net "P5E_CPU0_P0_RX_DP<6>")
	)
	(arc
		(start 350.873568 -276.010878)
		(mid 350.716591 -275.706078)
		(end 350.873568 -275.401278)
		(width 0.1143)
		(layer "In13.Cu")
		(net "P5E_CPU0_P0_RX_DP<6>")
	)
	(arc
		(start 386.538724 -378.40031)
		(mid 386.589581 -378.362569)
		(end 386.636514 -378.320046)
		(width 0.14224)
		(layer "In13.Cu")
		(net "P5E_CPU0_P0_RX_DP<6>")
	)
	(arc
		(start 364.689136 -382.517396)
		(mid 365.18553 -382.616153)
		(end 365.60633 -382.89738)
		(width 0.14224)
		(layer "In13.Cu")
		(net "P5E_CPU0_P0_RX_DP<6>")
	)
	(arc
		(start 367.448846 -384.739896)
		(mid 367.61979 -384.854181)
		(end 367.821464 -384.894328)
		(width 0.14224)
		(layer "In13.Cu")
		(net "P5E_CPU0_P0_RX_DP<6>")
	)
	(arc
		(start 350.943164 -291.560504)
		(mid 351.186491 -291.095938)
		(end 350.943164 -290.631372)
		(width 0.1143)
		(layer "In13.Cu")
		(net "P5E_CPU0_P0_RX_DP<6>")
	)
	(arc
		(start 327.514712 -376.283982)
		(mid 328.157811 -376.479129)
		(end 328.584052 -376.998738)
		(width 0.14224)
		(layer "In13.Cu")
		(net "P5E_CPU0_P0_RX_DP<6>")
	)
	(arc
		(start 351.883218 -272.120614)
		(mid 352.035205 -271.964106)
		(end 352.116644 -271.761712)
		(width 0.1143)
		(layer "In13.Cu")
		(net "P5E_CPU0_P0_RX_DP<6>")
	)
	(arc
		(start 331.493622 -384.022854)
		(mid 331.944631 -384.572395)
		(end 332.624938 -384.778758)
		(width 0.14224)
		(layer "In13.Cu")
		(net "P5E_CPU0_P0_RX_DP<6>")
	)
	(arc
		(start 383.14122 -384.894328)
		(mid 383.531861 -384.732519)
		(end 383.69367 -384.341878)
		(width 0.14224)
		(layer "In13.Cu")
		(net "P5E_CPU0_P0_RX_DP<6>")
	)
	(arc
		(start 350.873568 -274.390866)
		(mid 350.716591 -274.086066)
		(end 350.873568 -273.781266)
		(width 0.1143)
		(layer "In13.Cu")
		(net "P5E_CPU0_P0_RX_DP<6>")
	)
	(arc
		(start 350.943164 -281.840686)
		(mid 351.186491 -281.37612)
		(end 350.943164 -280.911554)
		(width 0.1143)
		(layer "In13.Cu")
		(net "P5E_CPU0_P0_RX_DP<6>")
	)
	(arc
		(start 351.460816 -297.97629)
		(mid 351.341049 -297.764859)
		(end 351.299526 -297.52544)
		(width 0.14224)
		(layer "In13.Cu")
		(net "P5E_CPU0_P0_RX_DP<6>")
	)
	(arc
		(start 359.933494 -382.554734)
		(mid 359.974734 -382.527115)
		(end 360.02341 -382.517396)
		(width 0.14224)
		(layer "In13.Cu")
		(net "P5E_CPU0_P0_RX_DP<6>")
	)
	(arc
		(start 350.943164 -280.220674)
		(mid 351.186491 -279.756108)
		(end 350.943164 -279.291542)
		(width 0.1143)
		(layer "In13.Cu")
		(net "P5E_CPU0_P0_RX_DP<6>")
	)
	(arc
		(start 350.873568 -277.63089)
		(mid 350.716591 -277.32609)
		(end 350.873568 -277.02129)
		(width 0.1143)
		(layer "In13.Cu")
		(net "P5E_CPU0_P0_RX_DP<6>")
	)
	(arc
		(start 350.873568 -284.110938)
		(mid 350.716591 -283.806138)
		(end 350.873568 -283.501338)
		(width 0.1143)
		(layer "In13.Cu")
		(net "P5E_CPU0_P0_RX_DP<6>")
	)
	(arc
		(start 350.943164 -275.360638)
		(mid 351.186491 -274.896072)
		(end 350.943164 -274.431506)
		(width 0.1143)
		(layer "In13.Cu")
		(net "P5E_CPU0_P0_RX_DP<6>")
	)
	(arc
		(start 350.75368 -295.61409)
		(mid 350.726061 -295.57285)
		(end 350.716342 -295.524174)
		(width 0.1143)
		(layer "In13.Cu")
		(net "P5E_CPU0_P0_RX_DP<6>")
	)
	(arc
		(start 357.753158 -384.711702)
		(mid 357.869442 -384.61344)
		(end 357.97998 -384.508756)
		(width 0.14224)
		(layer "In13.Cu")
		(net "P5E_CPU0_P0_RX_DP<6>")
	)
	(arc
		(start 350.943164 -278.600662)
		(mid 351.186491 -278.136096)
		(end 350.943164 -277.67153)
		(width 0.1143)
		(layer "In13.Cu")
		(net "P5E_CPU0_P0_RX_DP<6>")
	)
	(segment
		(start 309.67045 -394.385292)
		(end 310.19115 -394.385292)
		(width 0.127)
		(layer "F.Cu")
		(net "P5E_CPU0_P0_RX_DP<5>")
	)
	(segment
		(start 350.14789 -269.770098)
		(end 349.681038 -270.036036)
		(width 0.12954)
		(layer "F.Cu")
		(net "P5E_CPU0_P0_RX_DP<5>")
	)
	(segment
		(start 309.52186 -384.588766)
		(end 309.52186 -382.249934)
		(width 0.14224)
		(layer "In13.Cu")
		(net "P5E_CPU0_P0_RX_DP<5>")
	)
	(segment
		(start 350.001586 -279.290526)
		(end 349.932244 -279.25014)
		(width 0.1143)
		(layer "In13.Cu")
		(net "P5E_CPU0_P0_RX_DP<5>")
	)
	(segment
		(start 349.49892 -270.362934)
		(end 349.498158 -270.362426)
		(width 0.1143)
		(layer "In13.Cu")
		(net "P5E_CPU0_P0_RX_DP<5>")
	)
	(segment
		(start 349.383096 -270.036036)
		(end 349.681038 -270.036036)
		(width 0.1143)
		(layer "In13.Cu")
		(net "P5E_CPU0_P0_RX_DP<5>")
	)
	(segment
		(start 310.232552 -393.113006)
		(end 310.2356 -392.7348)
		(width 0.14224)
		(layer "In13.Cu")
		(net "P5E_CPU0_P0_RX_DP<5>")
	)
	(segment
		(start 373.591836 -373.92483)
		(end 369.934744 -373.92483)
		(width 0.14224)
		(layer "In13.Cu")
		(net "P5E_CPU0_P0_RX_DP<5>")
	)
	(segment
		(start 360.99496 -376.20067)
		(end 360.85272 -376.05843)
		(width 0.14224)
		(layer "In13.Cu")
		(net "P5E_CPU0_P0_RX_DP<5>")
	)
	(segment
		(start 350.003364 -285.77159)
		(end 349.932498 -285.730188)
		(width 0.1143)
		(layer "In13.Cu")
		(net "P5E_CPU0_P0_RX_DP<5>")
	)
	(segment
		(start 369.627404 -374.23217)
		(end 369.627404 -375.03735)
		(width 0.14224)
		(layer "In13.Cu")
		(net "P5E_CPU0_P0_RX_DP<5>")
	)
	(segment
		(start 350.292162 -297.763438)
		(end 350.292162 -296.436034)
		(width 0.14224)
		(layer "In13.Cu")
		(net "P5E_CPU0_P0_RX_DP<5>")
	)
	(segment
		(start 359.43286 -375.48693)
		(end 359.43286 -377.31319)
		(width 0.14224)
		(layer "In13.Cu")
		(net "P5E_CPU0_P0_RX_DP<5>")
	)
	(segment
		(start 367.195608 -375.34469)
		(end 369.471448 -373.06885)
		(width 0.14224)
		(layer "In13.Cu")
		(net "P5E_CPU0_P0_RX_DP<5>")
	)
	(segment
		(start 350.006158 -294.798496)
		(end 350.012508 -294.793924)
		(width 0.1143)
		(layer "In13.Cu")
		(net "P5E_CPU0_P0_RX_DP<5>")
	)
	(segment
		(start 369.934744 -373.92483)
		(end 369.627404 -374.23217)
		(width 0.14224)
		(layer "In13.Cu")
		(net "P5E_CPU0_P0_RX_DP<5>")
	)
	(segment
		(start 309.543196 -382.179322)
		(end 313.95416 -375.578116)
		(width 0.14224)
		(layer "In13.Cu")
		(net "P5E_CPU0_P0_RX_DP<5>")
	)
	(segment
		(start 359.43286 -377.31319)
		(end 359.7402 -377.62053)
		(width 0.14224)
		(layer "In13.Cu")
		(net "P5E_CPU0_P0_RX_DP<5>")
	)
	(segment
		(start 310.286146 -394.031216)
		(end 310.46039 -393.930632)
		(width 0.14224)
		(layer "In13.Cu")
		(net "P5E_CPU0_P0_RX_DP<5>")
	)
	(segment
		(start 349.932244 -272.162016)
		(end 350.001586 -272.12163)
		(width 0.1143)
		(layer "In13.Cu")
		(net "P5E_CPU0_P0_RX_DP<5>")
	)
	(segment
		(start 310.509158 -386.99821)
		(end 309.531512 -384.637534)
		(width 0.14224)
		(layer "In13.Cu")
		(net "P5E_CPU0_P0_RX_DP<5>")
	)
	(segment
		(start 310.46039 -393.930632)
		(end 310.548528 -393.842494)
		(width 0.14224)
		(layer "In13.Cu")
		(net "P5E_CPU0_P0_RX_DP<5>")
	)
	(segment
		(start 366.473232 -376.50801)
		(end 366.165892 -376.20067)
		(width 0.14224)
		(layer "In13.Cu")
		(net "P5E_CPU0_P0_RX_DP<5>")
	)
	(segment
		(start 349.933514 -289.981132)
		(end 350.00311 -289.940492)
		(width 0.1143)
		(layer "In13.Cu")
		(net "P5E_CPU0_P0_RX_DP<5>")
	)
	(segment
		(start 350.001586 -277.670514)
		(end 349.932244 -277.630128)
		(width 0.1143)
		(layer "In13.Cu")
		(net "P5E_CPU0_P0_RX_DP<5>")
	)
	(segment
		(start 350.001586 -272.810478)
		(end 349.932244 -272.770092)
		(width 0.1143)
		(layer "In13.Cu")
		(net "P5E_CPU0_P0_RX_DP<5>")
	)
	(segment
		(start 350.00311 -289.011106)
		(end 349.933514 -288.97072)
		(width 0.1143)
		(layer "In13.Cu")
		(net "P5E_CPU0_P0_RX_DP<5>")
	)
	(segment
		(start 360.85272 -375.48693)
		(end 360.99496 -375.34469)
		(width 0.14224)
		(layer "In13.Cu")
		(net "P5E_CPU0_P0_RX_DP<5>")
	)
	(segment
		(start 350.001586 -282.53055)
		(end 349.932244 -282.490164)
		(width 0.1143)
		(layer "In13.Cu")
		(net "P5E_CPU0_P0_RX_DP<5>")
	)
	(segment
		(start 310.19115 -394.385292)
		(end 310.286146 -394.031216)
		(width 0.14224)
		(layer "In13.Cu")
		(net "P5E_CPU0_P0_RX_DP<5>")
	)
	(segment
		(start 360.99496 -375.34469)
		(end 367.195608 -375.34469)
		(width 0.14224)
		(layer "In13.Cu")
		(net "P5E_CPU0_P0_RX_DP<5>")
	)
	(segment
		(start 349.932244 -273.782028)
		(end 350.001586 -273.741642)
		(width 0.1143)
		(layer "In13.Cu")
		(net "P5E_CPU0_P0_RX_DP<5>")
	)
	(segment
		(start 373.591836 -373.06885)
		(end 373.734076 -373.21109)
		(width 0.14224)
		(layer "In13.Cu")
		(net "P5E_CPU0_P0_RX_DP<5>")
	)
	(segment
		(start 310.548528 -393.428982)
		(end 310.232552 -393.113006)
		(width 0.14224)
		(layer "In13.Cu")
		(net "P5E_CPU0_P0_RX_DP<5>")
	)
	(segment
		(start 369.934744 -375.34469)
		(end 380.562612 -375.34469)
		(width 0.14224)
		(layer "In13.Cu")
		(net "P5E_CPU0_P0_RX_DP<5>")
	)
	(segment
		(start 317.278004 -375.34469)
		(end 324.31609 -373.944896)
		(width 0.14224)
		(layer "In13.Cu")
		(net "P5E_CPU0_P0_RX_DP<5>")
	)
	(segment
		(start 349.933514 -293.221156)
		(end 350.00311 -293.180516)
		(width 0.1143)
		(layer "In13.Cu")
		(net "P5E_CPU0_P0_RX_DP<5>")
	)
	(segment
		(start 349.932244 -277.022052)
		(end 350.001586 -276.981666)
		(width 0.1143)
		(layer "In13.Cu")
		(net "P5E_CPU0_P0_RX_DP<5>")
	)
	(segment
		(start 385.86664 -368.690906)
		(end 363.117384 -313.767724)
		(width 0.14224)
		(layer "In13.Cu")
		(net "P5E_CPU0_P0_RX_DP<5>")
	)
	(segment
		(start 349.500698 -270.36395)
		(end 349.49892 -270.362934)
		(width 0.1143)
		(layer "In13.Cu")
		(net "P5E_CPU0_P0_RX_DP<5>")
	)
	(segment
		(start 369.627404 -375.03735)
		(end 369.934744 -375.34469)
		(width 0.14224)
		(layer "In13.Cu")
		(net "P5E_CPU0_P0_RX_DP<5>")
	)
	(segment
		(start 349.932244 -275.40204)
		(end 350.001586 -275.361654)
		(width 0.1143)
		(layer "In13.Cu")
		(net "P5E_CPU0_P0_RX_DP<5>")
	)
	(segment
		(start 350.00565 -294.799004)
		(end 350.006158 -294.798496)
		(width 0.1143)
		(layer "In13.Cu")
		(net "P5E_CPU0_P0_RX_DP<5>")
	)
	(segment
		(start 359.7402 -377.62053)
		(end 366.165892 -377.62053)
		(width 0.14224)
		(layer "In13.Cu")
		(net "P5E_CPU0_P0_RX_DP<5>")
	)
	(segment
		(start 345.368372 -374.276874)
		(end 356.209092 -375.34469)
		(width 0.14224)
		(layer "In13.Cu")
		(net "P5E_CPU0_P0_RX_DP<5>")
	)
	(segment
		(start 349.932244 -281.882088)
		(end 350.001586 -281.841702)
		(width 0.1143)
		(layer "In13.Cu")
		(net "P5E_CPU0_P0_RX_DP<5>")
	)
	(segment
		(start 350.292162 -296.436034)
		(end 350.292162 -296.421556)
		(width 0.1143)
		(layer "In13.Cu")
		(net "P5E_CPU0_P0_RX_DP<5>")
	)
	(segment
		(start 350.00311 -293.871142)
		(end 349.933514 -293.830756)
		(width 0.1143)
		(layer "In13.Cu")
		(net "P5E_CPU0_P0_RX_DP<5>")
	)
	(segment
		(start 349.931482 -288.362136)
		(end 350.002856 -288.320988)
		(width 0.1143)
		(layer "In13.Cu")
		(net "P5E_CPU0_P0_RX_DP<5>")
	)
	(segment
		(start 356.209092 -375.34469)
		(end 359.29062 -375.34469)
		(width 0.14224)
		(layer "In13.Cu")
		(net "P5E_CPU0_P0_RX_DP<5>")
	)
	(segment
		(start 349.312992 -270.105886)
		(end 349.313246 -270.105886)
		(width 0.1143)
		(layer "In13.Cu")
		(net "P5E_CPU0_P0_RX_DP<5>")
	)
	(segment
		(start 385.86664 -370.282216)
		(end 385.86664 -368.690906)
		(width 0.14224)
		(layer "In13.Cu")
		(net "P5E_CPU0_P0_RX_DP<5>")
	)
	(segment
		(start 310.2356 -392.7348)
		(end 310.5404 -392.43)
		(width 0.14224)
		(layer "In13.Cu")
		(net "P5E_CPU0_P0_RX_DP<5>")
	)
	(segment
		(start 350.001586 -284.150562)
		(end 349.932244 -284.110176)
		(width 0.1143)
		(layer "In13.Cu")
		(net "P5E_CPU0_P0_RX_DP<5>")
	)
	(segment
		(start 360.85272 -376.05843)
		(end 360.85272 -375.48693)
		(width 0.14224)
		(layer "In13.Cu")
		(net "P5E_CPU0_P0_RX_DP<5>")
	)
	(segment
		(start 310.5404 -392.43)
		(end 310.5404 -387.154928)
		(width 0.14224)
		(layer "In13.Cu")
		(net "P5E_CPU0_P0_RX_DP<5>")
	)
	(segment
		(start 366.165892 -377.62053)
		(end 366.473232 -377.31319)
		(width 0.14224)
		(layer "In13.Cu")
		(net "P5E_CPU0_P0_RX_DP<5>")
	)
	(segment
		(start 349.932244 -285.122112)
		(end 350.001586 -285.081726)
		(width 0.1143)
		(layer "In13.Cu")
		(net "P5E_CPU0_P0_RX_DP<5>")
	)
	(segment
		(start 350.001332 -271.190466)
		(end 349.933514 -271.150842)
		(width 0.1143)
		(layer "In13.Cu")
		(net "P5E_CPU0_P0_RX_DP<5>")
	)
	(segment
		(start 350.002856 -295.491154)
		(end 349.933006 -295.450768)
		(width 0.1143)
		(layer "In13.Cu")
		(net "P5E_CPU0_P0_RX_DP<5>")
	)
	(segment
		(start 350.001586 -274.43049)
		(end 349.932244 -274.390104)
		(width 0.1143)
		(layer "In13.Cu")
		(net "P5E_CPU0_P0_RX_DP<5>")
	)
	(segment
		(start 349.931482 -286.742124)
		(end 350.002856 -286.700976)
		(width 0.1143)
		(layer "In13.Cu")
		(net "P5E_CPU0_P0_RX_DP<5>")
	)
	(segment
		(start 350.246442 -296.375836)
		(end 350.246442 -295.955974)
		(width 0.1143)
		(layer "In13.Cu")
		(net "P5E_CPU0_P0_RX_DP<5>")
	)
	(segment
		(start 373.734076 -373.21109)
		(end 373.734076 -373.78259)
		(width 0.14224)
		(layer "In13.Cu")
		(net "P5E_CPU0_P0_RX_DP<5>")
	)
	(segment
		(start 327.37044 -373.64416)
		(end 332.488032 -373.64416)
		(width 0.14224)
		(layer "In13.Cu")
		(net "P5E_CPU0_P0_RX_DP<5>")
	)
	(segment
		(start 350.292162 -296.421556)
		(end 350.246442 -296.375836)
		(width 0.1143)
		(layer "In13.Cu")
		(net "P5E_CPU0_P0_RX_DP<5>")
	)
	(segment
		(start 350.001586 -276.050502)
		(end 349.932244 -276.010116)
		(width 0.1143)
		(layer "In13.Cu")
		(net "P5E_CPU0_P0_RX_DP<5>")
	)
	(segment
		(start 366.165892 -376.20067)
		(end 360.99496 -376.20067)
		(width 0.14224)
		(layer "In13.Cu")
		(net "P5E_CPU0_P0_RX_DP<5>")
	)
	(segment
		(start 349.932244 -278.642064)
		(end 350.001586 -278.601678)
		(width 0.1143)
		(layer "In13.Cu")
		(net "P5E_CPU0_P0_RX_DP<5>")
	)
	(segment
		(start 363.117384 -313.767724)
		(end 350.531684 -298.432728)
		(width 0.14224)
		(layer "In13.Cu")
		(net "P5E_CPU0_P0_RX_DP<5>")
	)
	(segment
		(start 350.001586 -280.910538)
		(end 349.932244 -280.870152)
		(width 0.1143)
		(layer "In13.Cu")
		(net "P5E_CPU0_P0_RX_DP<5>")
	)
	(segment
		(start 349.932244 -283.5021)
		(end 350.001586 -283.461714)
		(width 0.1143)
		(layer "In13.Cu")
		(net "P5E_CPU0_P0_RX_DP<5>")
	)
	(segment
		(start 373.734076 -373.78259)
		(end 373.591836 -373.92483)
		(width 0.14224)
		(layer "In13.Cu")
		(net "P5E_CPU0_P0_RX_DP<5>")
	)
	(segment
		(start 349.933514 -291.601144)
		(end 350.00311 -291.560504)
		(width 0.1143)
		(layer "In13.Cu")
		(net "P5E_CPU0_P0_RX_DP<5>")
	)
	(segment
		(start 314.39104 -375.34469)
		(end 317.278004 -375.34469)
		(width 0.14224)
		(layer "In13.Cu")
		(net "P5E_CPU0_P0_RX_DP<5>")
	)
	(segment
		(start 349.498158 -270.362426)
		(end 349.477584 -270.34998)
		(width 0.1143)
		(layer "In13.Cu")
		(net "P5E_CPU0_P0_RX_DP<5>")
	)
	(segment
		(start 350.00311 -292.25113)
		(end 349.933514 -292.210744)
		(width 0.1143)
		(layer "In13.Cu")
		(net "P5E_CPU0_P0_RX_DP<5>")
	)
	(segment
		(start 359.29062 -375.34469)
		(end 359.43286 -375.48693)
		(width 0.14224)
		(layer "In13.Cu")
		(net "P5E_CPU0_P0_RX_DP<5>")
	)
	(segment
		(start 381.626364 -374.904)
		(end 385.596892 -370.933472)
		(width 0.14224)
		(layer "In13.Cu")
		(net "P5E_CPU0_P0_RX_DP<5>")
	)
	(segment
		(start 349.93326 -294.841168)
		(end 350.00565 -294.799004)
		(width 0.1143)
		(layer "In13.Cu")
		(net "P5E_CPU0_P0_RX_DP<5>")
	)
	(segment
		(start 350.00057 -287.38957)
		(end 349.93326 -287.350708)
		(width 0.1143)
		(layer "In13.Cu")
		(net "P5E_CPU0_P0_RX_DP<5>")
	)
	(segment
		(start 350.00311 -290.631118)
		(end 349.933514 -290.590732)
		(width 0.1143)
		(layer "In13.Cu")
		(net "P5E_CPU0_P0_RX_DP<5>")
	)
	(segment
		(start 310.548528 -393.842494)
		(end 310.548528 -393.428982)
		(width 0.14224)
		(layer "In13.Cu")
		(net "P5E_CPU0_P0_RX_DP<5>")
	)
	(segment
		(start 369.471448 -373.06885)
		(end 373.591836 -373.06885)
		(width 0.14224)
		(layer "In13.Cu")
		(net "P5E_CPU0_P0_RX_DP<5>")
	)
	(segment
		(start 349.932244 -280.262076)
		(end 350.001586 -280.22169)
		(width 0.1143)
		(layer "In13.Cu")
		(net "P5E_CPU0_P0_RX_DP<5>")
	)
	(segment
		(start 349.313246 -270.105886)
		(end 349.383096 -270.036036)
		(width 0.1143)
		(layer "In13.Cu")
		(net "P5E_CPU0_P0_RX_DP<5>")
	)
	(segment
		(start 366.473232 -377.31319)
		(end 366.473232 -376.50801)
		(width 0.14224)
		(layer "In13.Cu")
		(net "P5E_CPU0_P0_RX_DP<5>")
	)
	(arc
		(start 350.246442 -295.955974)
		(mid 350.181919 -295.693547)
		(end 350.002856 -295.491154)
		(width 0.1143)
		(layer "In13.Cu")
		(net "P5E_CPU0_P0_RX_DP<5>")
	)
	(arc
		(start 350.002856 -286.700976)
		(mid 350.246501 -286.236437)
		(end 350.003364 -285.77159)
		(width 0.1143)
		(layer "In13.Cu")
		(net "P5E_CPU0_P0_RX_DP<5>")
	)
	(arc
		(start 385.596892 -370.933472)
		(mid 385.796543 -370.634673)
		(end 385.86664 -370.282216)
		(width 0.14224)
		(layer "In13.Cu")
		(net "P5E_CPU0_P0_RX_DP<5>")
	)
	(arc
		(start 350.001586 -280.22169)
		(mid 350.246407 -279.756108)
		(end 350.001586 -279.290526)
		(width 0.1143)
		(layer "In13.Cu")
		(net "P5E_CPU0_P0_RX_DP<5>")
	)
	(arc
		(start 349.776796 -287.045908)
		(mid 349.817565 -286.875378)
		(end 349.931482 -286.742124)
		(width 0.1143)
		(layer "In13.Cu")
		(net "P5E_CPU0_P0_RX_DP<5>")
	)
	(arc
		(start 350.00311 -293.180516)
		(mid 350.246546 -292.715878)
		(end 350.00311 -292.25113)
		(width 0.1143)
		(layer "In13.Cu")
		(net "P5E_CPU0_P0_RX_DP<5>")
	)
	(arc
		(start 332.488032 -373.64416)
		(mid 338.935968 -373.802416)
		(end 345.368372 -374.276874)
		(width 0.14224)
		(layer "In13.Cu")
		(net "P5E_CPU0_P0_RX_DP<5>")
	)
	(arc
		(start 349.933514 -293.830756)
		(mid 349.776537 -293.525956)
		(end 349.933514 -293.221156)
		(width 0.1143)
		(layer "In13.Cu")
		(net "P5E_CPU0_P0_RX_DP<5>")
	)
	(arc
		(start 350.012508 -294.793924)
		(mid 350.246446 -294.330146)
		(end 350.00311 -293.871142)
		(width 0.1143)
		(layer "In13.Cu")
		(net "P5E_CPU0_P0_RX_DP<5>")
	)
	(arc
		(start 349.776796 -288.66592)
		(mid 349.817565 -288.49539)
		(end 349.931482 -288.362136)
		(width 0.1143)
		(layer "In13.Cu")
		(net "P5E_CPU0_P0_RX_DP<5>")
	)
	(arc
		(start 350.001586 -276.981666)
		(mid 350.246407 -276.516084)
		(end 350.001586 -276.050502)
		(width 0.1143)
		(layer "In13.Cu")
		(net "P5E_CPU0_P0_RX_DP<5>")
	)
	(arc
		(start 349.932244 -282.490164)
		(mid 349.776417 -282.186126)
		(end 349.932244 -281.882088)
		(width 0.1143)
		(layer "In13.Cu")
		(net "P5E_CPU0_P0_RX_DP<5>")
	)
	(arc
		(start 349.933514 -288.97072)
		(mid 349.818254 -288.837301)
		(end 349.776796 -288.66592)
		(width 0.1143)
		(layer "In13.Cu")
		(net "P5E_CPU0_P0_RX_DP<5>")
	)
	(arc
		(start 350.001586 -285.081726)
		(mid 350.246407 -284.616144)
		(end 350.001586 -284.150562)
		(width 0.1143)
		(layer "In13.Cu")
		(net "P5E_CPU0_P0_RX_DP<5>")
	)
	(arc
		(start 350.00311 -289.940492)
		(mid 350.246546 -289.475854)
		(end 350.00311 -289.011106)
		(width 0.1143)
		(layer "In13.Cu")
		(net "P5E_CPU0_P0_RX_DP<5>")
	)
	(arc
		(start 349.932244 -277.630128)
		(mid 349.776417 -277.32609)
		(end 349.932244 -277.022052)
		(width 0.1143)
		(layer "In13.Cu")
		(net "P5E_CPU0_P0_RX_DP<5>")
	)
	(arc
		(start 350.002856 -288.320988)
		(mid 350.246499 -287.854723)
		(end 350.00057 -287.38957)
		(width 0.1143)
		(layer "In13.Cu")
		(net "P5E_CPU0_P0_RX_DP<5>")
	)
	(arc
		(start 349.932244 -279.25014)
		(mid 349.776417 -278.946102)
		(end 349.932244 -278.642064)
		(width 0.1143)
		(layer "In13.Cu")
		(net "P5E_CPU0_P0_RX_DP<5>")
	)
	(arc
		(start 324.31609 -373.944896)
		(mid 325.835879 -373.719515)
		(end 327.37044 -373.64416)
		(width 0.14224)
		(layer "In13.Cu")
		(net "P5E_CPU0_P0_RX_DP<5>")
	)
	(arc
		(start 380.562612 -375.34469)
		(mid 381.138323 -375.230156)
		(end 381.626364 -374.904)
		(width 0.14224)
		(layer "In13.Cu")
		(net "P5E_CPU0_P0_RX_DP<5>")
	)
	(arc
		(start 349.932244 -272.770092)
		(mid 349.776417 -272.466054)
		(end 349.932244 -272.162016)
		(width 0.1143)
		(layer "In13.Cu")
		(net "P5E_CPU0_P0_RX_DP<5>")
	)
	(arc
		(start 349.933514 -290.590732)
		(mid 349.776537 -290.285932)
		(end 349.933514 -289.981132)
		(width 0.1143)
		(layer "In13.Cu")
		(net "P5E_CPU0_P0_RX_DP<5>")
	)
	(arc
		(start 349.776796 -270.846042)
		(mid 349.702746 -270.568363)
		(end 349.500698 -270.36395)
		(width 0.1143)
		(layer "In13.Cu")
		(net "P5E_CPU0_P0_RX_DP<5>")
	)
	(arc
		(start 313.95416 -375.578116)
		(mid 314.143373 -375.406699)
		(end 314.39104 -375.34469)
		(width 0.14224)
		(layer "In13.Cu")
		(net "P5E_CPU0_P0_RX_DP<5>")
	)
	(arc
		(start 350.001586 -278.601678)
		(mid 350.246407 -278.136096)
		(end 350.001586 -277.670514)
		(width 0.1143)
		(layer "In13.Cu")
		(net "P5E_CPU0_P0_RX_DP<5>")
	)
	(arc
		(start 309.531512 -384.637534)
		(mid 309.524267 -384.613627)
		(end 309.52186 -384.588766)
		(width 0.14224)
		(layer "In13.Cu")
		(net "P5E_CPU0_P0_RX_DP<5>")
	)
	(arc
		(start 350.001586 -273.741642)
		(mid 350.246407 -273.27606)
		(end 350.001586 -272.810478)
		(width 0.1143)
		(layer "In13.Cu")
		(net "P5E_CPU0_P0_RX_DP<5>")
	)
	(arc
		(start 349.933514 -292.210744)
		(mid 349.776537 -291.905944)
		(end 349.933514 -291.601144)
		(width 0.1143)
		(layer "In13.Cu")
		(net "P5E_CPU0_P0_RX_DP<5>")
	)
	(arc
		(start 349.932244 -284.110176)
		(mid 349.776417 -283.806138)
		(end 349.932244 -283.5021)
		(width 0.1143)
		(layer "In13.Cu")
		(net "P5E_CPU0_P0_RX_DP<5>")
	)
	(arc
		(start 349.933514 -271.150842)
		(mid 349.818254 -271.017423)
		(end 349.776796 -270.846042)
		(width 0.1143)
		(layer "In13.Cu")
		(net "P5E_CPU0_P0_RX_DP<5>")
	)
	(arc
		(start 349.932498 -285.730188)
		(mid 349.776565 -285.426253)
		(end 349.932244 -285.122112)
		(width 0.1143)
		(layer "In13.Cu")
		(net "P5E_CPU0_P0_RX_DP<5>")
	)
	(arc
		(start 350.001586 -272.12163)
		(mid 350.246407 -271.655943)
		(end 350.001332 -271.190466)
		(width 0.1143)
		(layer "In13.Cu")
		(net "P5E_CPU0_P0_RX_DP<5>")
	)
	(arc
		(start 349.477584 -270.34998)
		(mid 349.370197 -270.244859)
		(end 349.312992 -270.105886)
		(width 0.1143)
		(layer "In13.Cu")
		(net "P5E_CPU0_P0_RX_DP<5>")
	)
	(arc
		(start 350.531684 -298.432728)
		(mid 350.353848 -298.118867)
		(end 350.292162 -297.763438)
		(width 0.14224)
		(layer "In13.Cu")
		(net "P5E_CPU0_P0_RX_DP<5>")
	)
	(arc
		(start 349.933006 -295.450768)
		(mid 349.776242 -295.145865)
		(end 349.93326 -294.841168)
		(width 0.1143)
		(layer "In13.Cu")
		(net "P5E_CPU0_P0_RX_DP<5>")
	)
	(arc
		(start 309.52186 -382.249934)
		(mid 309.527262 -382.213033)
		(end 309.543196 -382.179322)
		(width 0.14224)
		(layer "In13.Cu")
		(net "P5E_CPU0_P0_RX_DP<5>")
	)
	(arc
		(start 349.932244 -274.390104)
		(mid 349.776417 -274.086066)
		(end 349.932244 -273.782028)
		(width 0.1143)
		(layer "In13.Cu")
		(net "P5E_CPU0_P0_RX_DP<5>")
	)
	(arc
		(start 350.001586 -281.841702)
		(mid 350.246407 -281.37612)
		(end 350.001586 -280.910538)
		(width 0.1143)
		(layer "In13.Cu")
		(net "P5E_CPU0_P0_RX_DP<5>")
	)
	(arc
		(start 350.001586 -283.461714)
		(mid 350.246407 -282.996132)
		(end 350.001586 -282.53055)
		(width 0.1143)
		(layer "In13.Cu")
		(net "P5E_CPU0_P0_RX_DP<5>")
	)
	(arc
		(start 349.93326 -287.350708)
		(mid 349.818075 -287.217264)
		(end 349.776796 -287.045908)
		(width 0.1143)
		(layer "In13.Cu")
		(net "P5E_CPU0_P0_RX_DP<5>")
	)
	(arc
		(start 350.001586 -275.361654)
		(mid 350.246407 -274.896072)
		(end 350.001586 -274.43049)
		(width 0.1143)
		(layer "In13.Cu")
		(net "P5E_CPU0_P0_RX_DP<5>")
	)
	(arc
		(start 349.932244 -276.010116)
		(mid 349.776417 -275.706078)
		(end 349.932244 -275.40204)
		(width 0.1143)
		(layer "In13.Cu")
		(net "P5E_CPU0_P0_RX_DP<5>")
	)
	(arc
		(start 310.5404 -387.154928)
		(mid 310.532484 -387.075034)
		(end 310.509158 -386.99821)
		(width 0.14224)
		(layer "In13.Cu")
		(net "P5E_CPU0_P0_RX_DP<5>")
	)
	(arc
		(start 350.00311 -291.560504)
		(mid 350.246546 -291.095866)
		(end 350.00311 -290.631118)
		(width 0.1143)
		(layer "In13.Cu")
		(net "P5E_CPU0_P0_RX_DP<5>")
	)
	(arc
		(start 349.932244 -280.870152)
		(mid 349.776417 -280.566114)
		(end 349.932244 -280.262076)
		(width 0.1143)
		(layer "In13.Cu")
		(net "P5E_CPU0_P0_RX_DP<5>")
	)
	(segment
		(start 308.4703 -394.385292)
		(end 308.991 -394.385292)
		(width 0.127)
		(layer "F.Cu")
		(net "P5E_CPU0_P0_RX_DP<4>")
	)
	(segment
		(start 350.14789 -273.010122)
		(end 349.681038 -273.27606)
		(width 0.12954)
		(layer "F.Cu")
		(net "P5E_CPU0_P0_RX_DP<4>")
	)
	(segment
		(start 376.359928 -372.15699)
		(end 376.502168 -372.01475)
		(width 0.14224)
		(layer "In13.Cu")
		(net "P5E_CPU0_P0_RX_DP<4>")
	)
	(segment
		(start 307.56225 -378.66828)
		(end 306.673504 -378.300742)
		(width 0.14224)
		(layer "In13.Cu")
		(net "P5E_CPU0_P0_RX_DP<4>")
	)
	(segment
		(start 382.223518 -365.498126)
		(end 382.223518 -365.063278)
		(width 0.14224)
		(layer "In13.Cu")
		(net "P5E_CPU0_P0_RX_DP<4>")
	)
	(segment
		(start 349.06331 -282.531566)
		(end 349.024194 -282.508706)
		(width 0.1143)
		(layer "In13.Cu")
		(net "P5E_CPU0_P0_RX_DP<4>")
	)
	(segment
		(start 348.836488 -296.293794)
		(end 348.836488 -295.145968)
		(width 0.1143)
		(layer "In13.Cu")
		(net "P5E_CPU0_P0_RX_DP<4>")
	)
	(segment
		(start 349.024194 -282.508706)
		(end 348.993714 -282.490926)
		(width 0.1143)
		(layer "In13.Cu")
		(net "P5E_CPU0_P0_RX_DP<4>")
	)
	(segment
		(start 382.927352 -366.004856)
		(end 378.562616 -370.369592)
		(width 0.14224)
		(layer "In13.Cu")
		(net "P5E_CPU0_P0_RX_DP<4>")
	)
	(segment
		(start 349.300546 -273.358864)
		(end 349.38335 -273.27606)
		(width 0.1143)
		(layer "In13.Cu")
		(net "P5E_CPU0_P0_RX_DP<4>")
	)
	(segment
		(start 349.06331 -290.631372)
		(end 349.024194 -290.608512)
		(width 0.1143)
		(layer "In13.Cu")
		(net "P5E_CPU0_P0_RX_DP<4>")
	)
	(segment
		(start 383.931922 -367.009426)
		(end 383.931922 -366.574578)
		(width 0.14224)
		(layer "In13.Cu")
		(net "P5E_CPU0_P0_RX_DP<4>")
	)
	(segment
		(start 308.953916 -375.957846)
		(end 310.466994 -374.444768)
		(width 0.14224)
		(layer "In13.Cu")
		(net "P5E_CPU0_P0_RX_DP<4>")
	)
	(segment
		(start 349.024194 -283.483558)
		(end 349.06331 -283.460698)
		(width 0.1143)
		(layer "In13.Cu")
		(net "P5E_CPU0_P0_RX_DP<4>")
	)
	(segment
		(start 308.066186 -379.107192)
		(end 307.758338 -378.799344)
		(width 0.14224)
		(layer "In13.Cu")
		(net "P5E_CPU0_P0_RX_DP<4>")
	)
	(segment
		(start 382.223518 -365.063278)
		(end 381.653796 -364.493556)
		(width 0.14224)
		(layer "In13.Cu")
		(net "P5E_CPU0_P0_RX_DP<4>")
	)
	(segment
		(start 366.674654 -374.40743)
		(end 369.067334 -372.01475)
		(width 0.14224)
		(layer "In13.Cu")
		(net "P5E_CPU0_P0_RX_DP<4>")
	)
	(segment
		(start 308.19598 -385.099052)
		(end 308.19598 -379.420882)
		(width 0.14224)
		(layer "In13.Cu")
		(net "P5E_CPU0_P0_RX_DP<4>")
	)
	(segment
		(start 327.229978 -372.558056)
		(end 333.503524 -372.558056)
		(width 0.14224)
		(layer "In13.Cu")
		(net "P5E_CPU0_P0_RX_DP<4>")
	)
	(segment
		(start 348.993714 -283.501338)
		(end 349.024194 -283.483558)
		(width 0.1143)
		(layer "In13.Cu")
		(net "P5E_CPU0_P0_RX_DP<4>")
	)
	(segment
		(start 349.38335 -273.27606)
		(end 349.681038 -273.27606)
		(width 0.1143)
		(layer "In13.Cu")
		(net "P5E_CPU0_P0_RX_DP<4>")
	)
	(segment
		(start 309.34025 -392.43)
		(end 309.34025 -387.968998)
		(width 0.14224)
		(layer "In13.Cu")
		(net "P5E_CPU0_P0_RX_DP<4>")
	)
	(segment
		(start 378.562616 -370.369592)
		(end 378.361448 -370.369592)
		(width 0.14224)
		(layer "In13.Cu")
		(net "P5E_CPU0_P0_RX_DP<4>")
	)
	(segment
		(start 381.218948 -364.493556)
		(end 375.154698 -370.557806)
		(width 0.14224)
		(layer "In13.Cu")
		(net "P5E_CPU0_P0_RX_DP<4>")
	)
	(segment
		(start 349.024194 -274.408646)
		(end 348.993714 -274.390866)
		(width 0.1143)
		(layer "In13.Cu")
		(net "P5E_CPU0_P0_RX_DP<4>")
	)
	(segment
		(start 349.024194 -284.128718)
		(end 348.993714 -284.110938)
		(width 0.1143)
		(layer "In13.Cu")
		(net "P5E_CPU0_P0_RX_DP<4>")
	)
	(segment
		(start 374.54967 -370.153692)
		(end 374.54967 -369.95227)
		(width 0.14224)
		(layer "In13.Cu")
		(net "P5E_CPU0_P0_RX_DP<4>")
	)
	(segment
		(start 310.557164 -374.40743)
		(end 316.97168 -374.40743)
		(width 0.14224)
		(layer "In13.Cu")
		(net "P5E_CPU0_P0_RX_DP<4>")
	)
	(segment
		(start 349.06331 -274.431506)
		(end 349.024194 -274.408646)
		(width 0.1143)
		(layer "In13.Cu")
		(net "P5E_CPU0_P0_RX_DP<4>")
	)
	(segment
		(start 349.024194 -285.74873)
		(end 348.993714 -285.73095)
		(width 0.1143)
		(layer "In13.Cu")
		(net "P5E_CPU0_P0_RX_DP<4>")
	)
	(segment
		(start 349.024194 -288.343594)
		(end 349.06331 -288.320734)
		(width 0.1143)
		(layer "In13.Cu")
		(net "P5E_CPU0_P0_RX_DP<4>")
	)
	(segment
		(start 349.024194 -280.243534)
		(end 349.06331 -280.220674)
		(width 0.1143)
		(layer "In13.Cu")
		(net "P5E_CPU0_P0_RX_DP<4>")
	)
	(segment
		(start 348.993714 -280.261314)
		(end 349.024194 -280.243534)
		(width 0.1143)
		(layer "In13.Cu")
		(net "P5E_CPU0_P0_RX_DP<4>")
	)
	(segment
		(start 348.991682 -286.742378)
		(end 349.024194 -286.723582)
		(width 0.1143)
		(layer "In13.Cu")
		(net "P5E_CPU0_P0_RX_DP<4>")
	)
	(segment
		(start 383.3622 -366.004856)
		(end 382.927352 -366.004856)
		(width 0.14224)
		(layer "In13.Cu")
		(net "P5E_CPU0_P0_RX_DP<4>")
	)
	(segment
		(start 348.993714 -275.401278)
		(end 349.024194 -275.383498)
		(width 0.1143)
		(layer "In13.Cu")
		(net "P5E_CPU0_P0_RX_DP<4>")
	)
	(segment
		(start 309.348378 -393.428982)
		(end 309.032402 -393.113006)
		(width 0.14224)
		(layer "In13.Cu")
		(net "P5E_CPU0_P0_RX_DP<4>")
	)
	(segment
		(start 376.502168 -372.01475)
		(end 378.926598 -372.01475)
		(width 0.14224)
		(layer "In13.Cu")
		(net "P5E_CPU0_P0_RX_DP<4>")
	)
	(segment
		(start 369.067334 -372.01475)
		(end 374.797828 -372.01475)
		(width 0.14224)
		(layer "In13.Cu")
		(net "P5E_CPU0_P0_RX_DP<4>")
	)
	(segment
		(start 349.024194 -276.028658)
		(end 348.993714 -276.010878)
		(width 0.1143)
		(layer "In13.Cu")
		(net "P5E_CPU0_P0_RX_DP<4>")
	)
	(segment
		(start 309.085996 -394.031216)
		(end 309.26024 -393.930632)
		(width 0.14224)
		(layer "In13.Cu")
		(net "P5E_CPU0_P0_RX_DP<4>")
	)
	(segment
		(start 349.02394 -294.823388)
		(end 349.026734 -294.821864)
		(width 0.1143)
		(layer "In13.Cu")
		(net "P5E_CPU0_P0_RX_DP<4>")
	)
	(segment
		(start 349.06331 -277.67153)
		(end 349.024194 -277.64867)
		(width 0.1143)
		(layer "In13.Cu")
		(net "P5E_CPU0_P0_RX_DP<4>")
	)
	(segment
		(start 348.993714 -281.881326)
		(end 349.024194 -281.863546)
		(width 0.1143)
		(layer "In13.Cu")
		(net "P5E_CPU0_P0_RX_DP<4>")
	)
	(segment
		(start 309.348378 -393.842494)
		(end 309.348378 -393.428982)
		(width 0.14224)
		(layer "In13.Cu")
		(net "P5E_CPU0_P0_RX_DP<4>")
	)
	(segment
		(start 375.154698 -370.557806)
		(end 374.953784 -370.557806)
		(width 0.14224)
		(layer "In13.Cu")
		(net "P5E_CPU0_P0_RX_DP<4>")
	)
	(segment
		(start 348.993714 -289.981132)
		(end 349.024194 -289.963352)
		(width 0.1143)
		(layer "In13.Cu")
		(net "P5E_CPU0_P0_RX_DP<4>")
	)
	(segment
		(start 348.882208 -296.367962)
		(end 348.882208 -296.339514)
		(width 0.1143)
		(layer "In13.Cu")
		(net "P5E_CPU0_P0_RX_DP<4>")
	)
	(segment
		(start 379.0569 -373.98325)
		(end 379.0569 -373.17807)
		(width 0.14224)
		(layer "In13.Cu")
		(net "P5E_CPU0_P0_RX_DP<4>")
	)
	(segment
		(start 377.957334 -369.965478)
		(end 377.957334 -369.76431)
		(width 0.14224)
		(layer "In13.Cu")
		(net "P5E_CPU0_P0_RX_DP<4>")
	)
	(segment
		(start 349.024194 -286.723582)
		(end 349.06331 -286.700722)
		(width 0.1143)
		(layer "In13.Cu")
		(net "P5E_CPU0_P0_RX_DP<4>")
	)
	(segment
		(start 349.024194 -279.268682)
		(end 348.993714 -279.250902)
		(width 0.1143)
		(layer "In13.Cu")
		(net "P5E_CPU0_P0_RX_DP<4>")
	)
	(segment
		(start 307.347874 -376.08764)
		(end 308.64048 -376.08764)
		(width 0.14224)
		(layer "In13.Cu")
		(net "P5E_CPU0_P0_RX_DP<4>")
	)
	(segment
		(start 309.309008 -387.81228)
		(end 308.205632 -385.14782)
		(width 0.14224)
		(layer "In13.Cu")
		(net "P5E_CPU0_P0_RX_DP<4>")
	)
	(segment
		(start 308.991 -394.385292)
		(end 309.085996 -394.031216)
		(width 0.14224)
		(layer "In13.Cu")
		(net "P5E_CPU0_P0_RX_DP<4>")
	)
	(segment
		(start 383.931922 -366.574578)
		(end 383.3622 -366.004856)
		(width 0.14224)
		(layer "In13.Cu")
		(net "P5E_CPU0_P0_RX_DP<4>")
	)
	(segment
		(start 381.653796 -364.493556)
		(end 381.218948 -364.493556)
		(width 0.14224)
		(layer "In13.Cu")
		(net "P5E_CPU0_P0_RX_DP<4>")
	)
	(segment
		(start 348.993714 -278.641302)
		(end 349.024194 -278.623522)
		(width 0.1143)
		(layer "In13.Cu")
		(net "P5E_CPU0_P0_RX_DP<4>")
	)
	(segment
		(start 309.032402 -393.113006)
		(end 309.03545 -392.7348)
		(width 0.14224)
		(layer "In13.Cu")
		(net "P5E_CPU0_P0_RX_DP<4>")
	)
	(segment
		(start 309.26024 -393.930632)
		(end 309.348378 -393.842494)
		(width 0.14224)
		(layer "In13.Cu")
		(net "P5E_CPU0_P0_RX_DP<4>")
	)
	(segment
		(start 376.359928 -372.72849)
		(end 376.359928 -372.15699)
		(width 0.14224)
		(layer "In13.Cu")
		(net "P5E_CPU0_P0_RX_DP<4>")
	)
	(segment
		(start 349.06331 -293.871396)
		(end 348.993714 -293.830756)
		(width 0.1143)
		(layer "In13.Cu")
		(net "P5E_CPU0_P0_RX_DP<4>")
	)
	(segment
		(start 306.398676 -377.926092)
		(end 306.398676 -377.036838)
		(width 0.14224)
		(layer "In13.Cu")
		(net "P5E_CPU0_P0_RX_DP<4>")
	)
	(segment
		(start 349.024194 -293.203376)
		(end 349.06331 -293.180516)
		(width 0.1143)
		(layer "In13.Cu")
		(net "P5E_CPU0_P0_RX_DP<4>")
	)
	(segment
		(start 379.0569 -373.17807)
		(end 378.74956 -372.87073)
		(width 0.14224)
		(layer "In13.Cu")
		(net "P5E_CPU0_P0_RX_DP<4>")
	)
	(segment
		(start 374.940068 -373.98325)
		(end 375.247408 -374.29059)
		(width 0.14224)
		(layer "In13.Cu")
		(net "P5E_CPU0_P0_RX_DP<4>")
	)
	(segment
		(start 349.06331 -280.911554)
		(end 349.024194 -280.888694)
		(width 0.1143)
		(layer "In13.Cu")
		(net "P5E_CPU0_P0_RX_DP<4>")
	)
	(segment
		(start 378.74956 -372.87073)
		(end 376.502168 -372.87073)
		(width 0.14224)
		(layer "In13.Cu")
		(net "P5E_CPU0_P0_RX_DP<4>")
	)
	(segment
		(start 349.024194 -291.583364)
		(end 349.06331 -291.560504)
		(width 0.1143)
		(layer "In13.Cu")
		(net "P5E_CPU0_P0_RX_DP<4>")
	)
	(segment
		(start 349.06331 -279.291542)
		(end 349.024194 -279.268682)
		(width 0.1143)
		(layer "In13.Cu")
		(net "P5E_CPU0_P0_RX_DP<4>")
	)
	(segment
		(start 380.264416 -364.068106)
		(end 380.264416 -357.625142)
		(width 0.14224)
		(layer "In13.Cu")
		(net "P5E_CPU0_P0_RX_DP<4>")
	)
	(segment
		(start 374.54967 -369.95227)
		(end 380.144528 -364.357412)
		(width 0.14224)
		(layer "In13.Cu")
		(net "P5E_CPU0_P0_RX_DP<4>")
	)
	(segment
		(start 374.940068 -372.15699)
		(end 374.940068 -373.98325)
		(width 0.14224)
		(layer "In13.Cu")
		(net "P5E_CPU0_P0_RX_DP<4>")
	)
	(segment
		(start 349.06331 -285.77159)
		(end 349.024194 -285.74873)
		(width 0.1143)
		(layer "In13.Cu")
		(net "P5E_CPU0_P0_RX_DP<4>")
	)
	(segment
		(start 349.06331 -289.01136)
		(end 349.024194 -288.9885)
		(width 0.1143)
		(layer "In13.Cu")
		(net "P5E_CPU0_P0_RX_DP<4>")
	)
	(segment
		(start 349.024194 -289.963352)
		(end 349.06331 -289.940492)
		(width 0.1143)
		(layer "In13.Cu")
		(net "P5E_CPU0_P0_RX_DP<4>")
	)
	(segment
		(start 309.03545 -392.7348)
		(end 309.34025 -392.43)
		(width 0.14224)
		(layer "In13.Cu")
		(net "P5E_CPU0_P0_RX_DP<4>")
	)
	(segment
		(start 378.361448 -370.369592)
		(end 377.957334 -369.965478)
		(width 0.14224)
		(layer "In13.Cu")
		(net "P5E_CPU0_P0_RX_DP<4>")
	)
	(segment
		(start 349.024194 -281.863546)
		(end 349.06331 -281.840686)
		(width 0.1143)
		(layer "In13.Cu")
		(net "P5E_CPU0_P0_RX_DP<4>")
	)
	(segment
		(start 349.024194 -292.228524)
		(end 348.993714 -292.210744)
		(width 0.1143)
		(layer "In13.Cu")
		(net "P5E_CPU0_P0_RX_DP<4>")
	)
	(segment
		(start 349.024194 -277.64867)
		(end 348.993714 -277.63089)
		(width 0.1143)
		(layer "In13.Cu")
		(net "P5E_CPU0_P0_RX_DP<4>")
	)
	(segment
		(start 349.06331 -276.051518)
		(end 349.024194 -276.028658)
		(width 0.1143)
		(layer "In13.Cu")
		(net "P5E_CPU0_P0_RX_DP<4>")
	)
	(segment
		(start 346.446602 -373.192548)
		(end 358.770428 -374.40743)
		(width 0.14224)
		(layer "In13.Cu")
		(net "P5E_CPU0_P0_RX_DP<4>")
	)
	(segment
		(start 348.993714 -291.601144)
		(end 349.024194 -291.583364)
		(width 0.1143)
		(layer "In13.Cu")
		(net "P5E_CPU0_P0_RX_DP<4>")
	)
	(segment
		(start 306.569364 -378.231146)
		(end 306.493926 -378.155962)
		(width 0.14224)
		(layer "In13.Cu")
		(net "P5E_CPU0_P0_RX_DP<4>")
	)
	(segment
		(start 378.74956 -374.29059)
		(end 379.0569 -373.98325)
		(width 0.14224)
		(layer "In13.Cu")
		(net "P5E_CPU0_P0_RX_DP<4>")
	)
	(segment
		(start 348.99346 -294.841168)
		(end 349.02394 -294.823388)
		(width 0.1143)
		(layer "In13.Cu")
		(net "P5E_CPU0_P0_RX_DP<4>")
	)
	(segment
		(start 377.957334 -369.76431)
		(end 382.223518 -365.498126)
		(width 0.14224)
		(layer "In13.Cu")
		(net "P5E_CPU0_P0_RX_DP<4>")
	)
	(segment
		(start 306.436014 -376.946922)
		(end 307.257958 -376.124978)
		(width 0.14224)
		(layer "In13.Cu")
		(net "P5E_CPU0_P0_RX_DP<4>")
	)
	(segment
		(start 374.797828 -372.01475)
		(end 374.940068 -372.15699)
		(width 0.14224)
		(layer "In13.Cu")
		(net "P5E_CPU0_P0_RX_DP<4>")
	)
	(segment
		(start 349.024194 -280.888694)
		(end 348.993714 -280.870914)
		(width 0.1143)
		(layer "In13.Cu")
		(net "P5E_CPU0_P0_RX_DP<4>")
	)
	(segment
		(start 348.882208 -296.339514)
		(end 348.836488 -296.293794)
		(width 0.1143)
		(layer "In13.Cu")
		(net "P5E_CPU0_P0_RX_DP<4>")
	)
	(segment
		(start 349.024194 -285.10357)
		(end 349.06331 -285.08071)
		(width 0.1143)
		(layer "In13.Cu")
		(net "P5E_CPU0_P0_RX_DP<4>")
	)
	(segment
		(start 348.993714 -273.781266)
		(end 349.024194 -273.763486)
		(width 0.1143)
		(layer "In13.Cu")
		(net "P5E_CPU0_P0_RX_DP<4>")
	)
	(segment
		(start 348.882208 -297.818556)
		(end 348.882208 -296.367962)
		(width 0.14224)
		(layer "In13.Cu")
		(net "P5E_CPU0_P0_RX_DP<4>")
	)
	(segment
		(start 349.06331 -284.151578)
		(end 349.024194 -284.128718)
		(width 0.1143)
		(layer "In13.Cu")
		(net "P5E_CPU0_P0_RX_DP<4>")
	)
	(segment
		(start 348.993714 -293.221156)
		(end 349.024194 -293.203376)
		(width 0.1143)
		(layer "In13.Cu")
		(net "P5E_CPU0_P0_RX_DP<4>")
	)
	(segment
		(start 362.41736 -314.538106)
		(end 349.158306 -298.583096)
		(width 0.14224)
		(layer "In13.Cu")
		(net "P5E_CPU0_P0_RX_DP<4>")
	)
	(segment
		(start 380.264416 -357.625142)
		(end 362.41736 -314.538106)
		(width 0.14224)
		(layer "In13.Cu")
		(net "P5E_CPU0_P0_RX_DP<4>")
	)
	(segment
		(start 349.06331 -292.251384)
		(end 349.024194 -292.228524)
		(width 0.1143)
		(layer "In13.Cu")
		(net "P5E_CPU0_P0_RX_DP<4>")
	)
	(segment
		(start 348.993714 -277.02129)
		(end 349.024194 -277.00351)
		(width 0.1143)
		(layer "In13.Cu")
		(net "P5E_CPU0_P0_RX_DP<4>")
	)
	(segment
		(start 375.247408 -374.29059)
		(end 378.74956 -374.29059)
		(width 0.14224)
		(layer "In13.Cu")
		(net "P5E_CPU0_P0_RX_DP<4>")
	)
	(segment
		(start 349.024194 -273.763486)
		(end 349.06331 -273.740626)
		(width 0.1143)
		(layer "In13.Cu")
		(net "P5E_CPU0_P0_RX_DP<4>")
	)
	(segment
		(start 349.024194 -278.623522)
		(end 349.06331 -278.600662)
		(width 0.1143)
		(layer "In13.Cu")
		(net "P5E_CPU0_P0_RX_DP<4>")
	)
	(segment
		(start 316.97168 -374.40743)
		(end 325.328534 -372.745254)
		(width 0.14224)
		(layer "In13.Cu")
		(net "P5E_CPU0_P0_RX_DP<4>")
	)
	(segment
		(start 348.993714 -285.12135)
		(end 349.024194 -285.10357)
		(width 0.1143)
		(layer "In13.Cu")
		(net "P5E_CPU0_P0_RX_DP<4>")
	)
	(segment
		(start 349.06077 -287.389824)
		(end 348.993714 -287.350708)
		(width 0.1143)
		(layer "In13.Cu")
		(net "P5E_CPU0_P0_RX_DP<4>")
	)
	(segment
		(start 349.024194 -290.608512)
		(end 348.993714 -290.590732)
		(width 0.1143)
		(layer "In13.Cu")
		(net "P5E_CPU0_P0_RX_DP<4>")
	)
	(segment
		(start 378.926598 -372.01475)
		(end 383.931922 -367.009426)
		(width 0.14224)
		(layer "In13.Cu")
		(net "P5E_CPU0_P0_RX_DP<4>")
	)
	(segment
		(start 348.991682 -288.36239)
		(end 349.024194 -288.343594)
		(width 0.1143)
		(layer "In13.Cu")
		(net "P5E_CPU0_P0_RX_DP<4>")
	)
	(segment
		(start 349.024194 -275.383498)
		(end 349.06331 -275.360638)
		(width 0.1143)
		(layer "In13.Cu")
		(net "P5E_CPU0_P0_RX_DP<4>")
	)
	(segment
		(start 374.953784 -370.557806)
		(end 374.54967 -370.153692)
		(width 0.14224)
		(layer "In13.Cu")
		(net "P5E_CPU0_P0_RX_DP<4>")
	)
	(segment
		(start 349.024194 -277.00351)
		(end 349.06331 -276.98065)
		(width 0.1143)
		(layer "In13.Cu")
		(net "P5E_CPU0_P0_RX_DP<4>")
	)
	(segment
		(start 349.024194 -288.9885)
		(end 348.993714 -288.97072)
		(width 0.1143)
		(layer "In13.Cu")
		(net "P5E_CPU0_P0_RX_DP<4>")
	)
	(segment
		(start 358.770428 -374.40743)
		(end 366.674654 -374.40743)
		(width 0.14224)
		(layer "In13.Cu")
		(net "P5E_CPU0_P0_RX_DP<4>")
	)
	(segment
		(start 376.502168 -372.87073)
		(end 376.359928 -372.72849)
		(width 0.14224)
		(layer "In13.Cu")
		(net "P5E_CPU0_P0_RX_DP<4>")
	)
	(arc
		(start 348.836488 -295.145968)
		(mid 348.878037 -294.974546)
		(end 348.99346 -294.841168)
		(width 0.1143)
		(layer "In13.Cu")
		(net "P5E_CPU0_P0_RX_DP<4>")
	)
	(arc
		(start 308.205632 -385.14782)
		(mid 308.198387 -385.123913)
		(end 308.19598 -385.099052)
		(width 0.14224)
		(layer "In13.Cu")
		(net "P5E_CPU0_P0_RX_DP<4>")
	)
	(arc
		(start 349.296736 -273.381724)
		(mid 349.298759 -273.370314)
		(end 349.300546 -273.358864)
		(width 0.1143)
		(layer "In13.Cu")
		(net "P5E_CPU0_P0_RX_DP<4>")
	)
	(arc
		(start 348.993714 -284.110938)
		(mid 348.836737 -283.806138)
		(end 348.993714 -283.501338)
		(width 0.1143)
		(layer "In13.Cu")
		(net "P5E_CPU0_P0_RX_DP<4>")
	)
	(arc
		(start 349.306642 -287.856168)
		(mid 349.241406 -287.592577)
		(end 349.06077 -287.389824)
		(width 0.1143)
		(layer "In13.Cu")
		(net "P5E_CPU0_P0_RX_DP<4>")
	)
	(arc
		(start 349.06331 -281.840686)
		(mid 349.306637 -281.37612)
		(end 349.06331 -280.911554)
		(width 0.1143)
		(layer "In13.Cu")
		(net "P5E_CPU0_P0_RX_DP<4>")
	)
	(arc
		(start 348.993714 -290.590732)
		(mid 348.836737 -290.285932)
		(end 348.993714 -289.981132)
		(width 0.1143)
		(layer "In13.Cu")
		(net "P5E_CPU0_P0_RX_DP<4>")
	)
	(arc
		(start 348.993714 -292.210744)
		(mid 348.836737 -291.905944)
		(end 348.993714 -291.601144)
		(width 0.1143)
		(layer "In13.Cu")
		(net "P5E_CPU0_P0_RX_DP<4>")
	)
	(arc
		(start 309.34025 -387.968998)
		(mid 309.332334 -387.889104)
		(end 309.309008 -387.81228)
		(width 0.14224)
		(layer "In13.Cu")
		(net "P5E_CPU0_P0_RX_DP<4>")
	)
	(arc
		(start 348.993714 -277.63089)
		(mid 348.836737 -277.32609)
		(end 348.993714 -277.02129)
		(width 0.1143)
		(layer "In13.Cu")
		(net "P5E_CPU0_P0_RX_DP<4>")
	)
	(arc
		(start 310.466994 -374.444768)
		(mid 310.508364 -374.417125)
		(end 310.557164 -374.40743)
		(width 0.14224)
		(layer "In13.Cu")
		(net "P5E_CPU0_P0_RX_DP<4>")
	)
	(arc
		(start 349.158306 -298.583096)
		(mid 348.953339 -298.224996)
		(end 348.882208 -297.818556)
		(width 0.14224)
		(layer "In13.Cu")
		(net "P5E_CPU0_P0_RX_DP<4>")
	)
	(arc
		(start 348.993714 -279.250902)
		(mid 348.836737 -278.946102)
		(end 348.993714 -278.641302)
		(width 0.1143)
		(layer "In13.Cu")
		(net "P5E_CPU0_P0_RX_DP<4>")
	)
	(arc
		(start 349.06331 -289.940492)
		(mid 349.306637 -289.475926)
		(end 349.06331 -289.01136)
		(width 0.1143)
		(layer "In13.Cu")
		(net "P5E_CPU0_P0_RX_DP<4>")
	)
	(arc
		(start 349.06331 -273.740626)
		(mid 349.215297 -273.584118)
		(end 349.296736 -273.381724)
		(width 0.1143)
		(layer "In13.Cu")
		(net "P5E_CPU0_P0_RX_DP<4>")
	)
	(arc
		(start 306.398676 -377.036838)
		(mid 306.408378 -376.988154)
		(end 306.436014 -376.946922)
		(width 0.14224)
		(layer "In13.Cu")
		(net "P5E_CPU0_P0_RX_DP<4>")
	)
	(arc
		(start 349.06331 -280.220674)
		(mid 349.306637 -279.756108)
		(end 349.06331 -279.291542)
		(width 0.1143)
		(layer "In13.Cu")
		(net "P5E_CPU0_P0_RX_DP<4>")
	)
	(arc
		(start 306.673504 -378.300742)
		(mid 306.618005 -378.271073)
		(end 306.569364 -378.231146)
		(width 0.14224)
		(layer "In13.Cu")
		(net "P5E_CPU0_P0_RX_DP<4>")
	)
	(arc
		(start 325.328534 -372.745254)
		(mid 326.274658 -372.604947)
		(end 327.229978 -372.558056)
		(width 0.14224)
		(layer "In13.Cu")
		(net "P5E_CPU0_P0_RX_DP<4>")
	)
	(arc
		(start 348.993714 -293.830756)
		(mid 348.836737 -293.525956)
		(end 348.993714 -293.221156)
		(width 0.1143)
		(layer "In13.Cu")
		(net "P5E_CPU0_P0_RX_DP<4>")
	)
	(arc
		(start 349.026734 -294.821864)
		(mid 349.305767 -294.356649)
		(end 349.06331 -293.871396)
		(width 0.1143)
		(layer "In13.Cu")
		(net "P5E_CPU0_P0_RX_DP<4>")
	)
	(arc
		(start 349.06331 -285.08071)
		(mid 349.306637 -284.616144)
		(end 349.06331 -284.151578)
		(width 0.1143)
		(layer "In13.Cu")
		(net "P5E_CPU0_P0_RX_DP<4>")
	)
	(arc
		(start 308.19598 -379.420882)
		(mid 308.16229 -379.251129)
		(end 308.066186 -379.107192)
		(width 0.14224)
		(layer "In13.Cu")
		(net "P5E_CPU0_P0_RX_DP<4>")
	)
	(arc
		(start 349.06331 -275.360638)
		(mid 349.306637 -274.896072)
		(end 349.06331 -274.431506)
		(width 0.1143)
		(layer "In13.Cu")
		(net "P5E_CPU0_P0_RX_DP<4>")
	)
	(arc
		(start 349.06331 -286.700722)
		(mid 349.306637 -286.236156)
		(end 349.06331 -285.77159)
		(width 0.1143)
		(layer "In13.Cu")
		(net "P5E_CPU0_P0_RX_DP<4>")
	)
	(arc
		(start 348.993714 -282.490926)
		(mid 348.836737 -282.186126)
		(end 348.993714 -281.881326)
		(width 0.1143)
		(layer "In13.Cu")
		(net "P5E_CPU0_P0_RX_DP<4>")
	)
	(arc
		(start 349.06331 -288.320734)
		(mid 349.242123 -288.118384)
		(end 349.306642 -287.856168)
		(width 0.1143)
		(layer "In13.Cu")
		(net "P5E_CPU0_P0_RX_DP<4>")
	)
	(arc
		(start 306.493926 -378.155962)
		(mid 306.423456 -378.050497)
		(end 306.398676 -377.926092)
		(width 0.14224)
		(layer "In13.Cu")
		(net "P5E_CPU0_P0_RX_DP<4>")
	)
	(arc
		(start 349.06331 -293.180516)
		(mid 349.306637 -292.71595)
		(end 349.06331 -292.251384)
		(width 0.1143)
		(layer "In13.Cu")
		(net "P5E_CPU0_P0_RX_DP<4>")
	)
	(arc
		(start 349.06331 -283.460698)
		(mid 349.306637 -282.996132)
		(end 349.06331 -282.531566)
		(width 0.1143)
		(layer "In13.Cu")
		(net "P5E_CPU0_P0_RX_DP<4>")
	)
	(arc
		(start 348.993714 -280.870914)
		(mid 348.836737 -280.566114)
		(end 348.993714 -280.261314)
		(width 0.1143)
		(layer "In13.Cu")
		(net "P5E_CPU0_P0_RX_DP<4>")
	)
	(arc
		(start 333.503524 -372.558056)
		(mid 339.982849 -372.71647)
		(end 346.446602 -373.192548)
		(width 0.14224)
		(layer "In13.Cu")
		(net "P5E_CPU0_P0_RX_DP<4>")
	)
	(arc
		(start 348.993714 -287.350708)
		(mid 348.878287 -287.217332)
		(end 348.836742 -287.045908)
		(width 0.1143)
		(layer "In13.Cu")
		(net "P5E_CPU0_P0_RX_DP<4>")
	)
	(arc
		(start 349.06331 -276.98065)
		(mid 349.306637 -276.516084)
		(end 349.06331 -276.051518)
		(width 0.1143)
		(layer "In13.Cu")
		(net "P5E_CPU0_P0_RX_DP<4>")
	)
	(arc
		(start 307.257958 -376.124978)
		(mid 307.299198 -376.097359)
		(end 307.347874 -376.08764)
		(width 0.14224)
		(layer "In13.Cu")
		(net "P5E_CPU0_P0_RX_DP<4>")
	)
	(arc
		(start 348.993714 -285.73095)
		(mid 348.836737 -285.42615)
		(end 348.993714 -285.12135)
		(width 0.1143)
		(layer "In13.Cu")
		(net "P5E_CPU0_P0_RX_DP<4>")
	)
	(arc
		(start 348.993714 -288.97072)
		(mid 348.878287 -288.837344)
		(end 348.836742 -288.66592)
		(width 0.1143)
		(layer "In13.Cu")
		(net "P5E_CPU0_P0_RX_DP<4>")
	)
	(arc
		(start 349.06331 -278.600662)
		(mid 349.306637 -278.136096)
		(end 349.06331 -277.67153)
		(width 0.1143)
		(layer "In13.Cu")
		(net "P5E_CPU0_P0_RX_DP<4>")
	)
	(arc
		(start 349.06331 -291.560504)
		(mid 349.306637 -291.095938)
		(end 349.06331 -290.631372)
		(width 0.1143)
		(layer "In13.Cu")
		(net "P5E_CPU0_P0_RX_DP<4>")
	)
	(arc
		(start 348.993714 -276.010878)
		(mid 348.836737 -275.706078)
		(end 348.993714 -275.401278)
		(width 0.1143)
		(layer "In13.Cu")
		(net "P5E_CPU0_P0_RX_DP<4>")
	)
	(arc
		(start 380.144528 -364.357412)
		(mid 380.233272 -364.224692)
		(end 380.264416 -364.068106)
		(width 0.14224)
		(layer "In13.Cu")
		(net "P5E_CPU0_P0_RX_DP<4>")
	)
	(arc
		(start 348.836742 -288.66592)
		(mid 348.877708 -288.495514)
		(end 348.991682 -288.36239)
		(width 0.1143)
		(layer "In13.Cu")
		(net "P5E_CPU0_P0_RX_DP<4>")
	)
	(arc
		(start 308.64048 -376.08764)
		(mid 308.810097 -376.053901)
		(end 308.953916 -375.957846)
		(width 0.14224)
		(layer "In13.Cu")
		(net "P5E_CPU0_P0_RX_DP<4>")
	)
	(arc
		(start 307.758338 -378.799344)
		(mid 307.666753 -378.724148)
		(end 307.56225 -378.66828)
		(width 0.14224)
		(layer "In13.Cu")
		(net "P5E_CPU0_P0_RX_DP<4>")
	)
	(arc
		(start 348.993714 -274.390866)
		(mid 348.836737 -274.086066)
		(end 348.993714 -273.781266)
		(width 0.1143)
		(layer "In13.Cu")
		(net "P5E_CPU0_P0_RX_DP<4>")
	)
	(arc
		(start 348.836742 -287.045908)
		(mid 348.877708 -286.875502)
		(end 348.991682 -286.742378)
		(width 0.1143)
		(layer "In13.Cu")
		(net "P5E_CPU0_P0_RX_DP<4>")
	)
	(segment
		(start 350.14789 -271.39011)
		(end 349.681038 -271.656048)
		(width 0.12954)
		(layer "F.Cu")
		(net "P5E_CPU0_P0_RX_DP<3>")
	)
	(segment
		(start 307.270404 -394.385292)
		(end 307.791104 -394.385292)
		(width 0.127)
		(layer "F.Cu")
		(net "P5E_CPU0_P0_RX_DP<3>")
	)
	(segment
		(start 348.08414 -283.483558)
		(end 348.123256 -283.460698)
		(width 0.1143)
		(layer "In13.Cu")
		(net "P5E_CPU0_P0_RX_DP<3>")
	)
	(segment
		(start 308.109112 -388.398004)
		(end 306.674012 -384.932936)
		(width 0.14224)
		(layer "In13.Cu")
		(net "P5E_CPU0_P0_RX_DP<3>")
	)
	(segment
		(start 306.66436 -384.884168)
		(end 306.66436 -382.022604)
		(width 0.14224)
		(layer "In13.Cu")
		(net "P5E_CPU0_P0_RX_DP<3>")
	)
	(segment
		(start 348.08414 -279.268682)
		(end 348.05366 -279.250902)
		(width 0.1143)
		(layer "In13.Cu")
		(net "P5E_CPU0_P0_RX_DP<3>")
	)
	(segment
		(start 308.148482 -393.842494)
		(end 308.148482 -393.428982)
		(width 0.14224)
		(layer "In13.Cu")
		(net "P5E_CPU0_P0_RX_DP<3>")
	)
	(segment
		(start 348.123256 -290.631118)
		(end 348.05366 -290.590732)
		(width 0.1143)
		(layer "In13.Cu")
		(net "P5E_CPU0_P0_RX_DP<3>")
	)
	(segment
		(start 327.181718 -371.401594)
		(end 333.17815 -371.401594)
		(width 0.14224)
		(layer "In13.Cu")
		(net "P5E_CPU0_P0_RX_DP<3>")
	)
	(segment
		(start 348.05366 -278.641302)
		(end 348.08414 -278.623522)
		(width 0.1143)
		(layer "In13.Cu")
		(net "P5E_CPU0_P0_RX_DP<3>")
	)
	(segment
		(start 371.741954 -368.086386)
		(end 371.741954 -367.885472)
		(width 0.14224)
		(layer "In13.Cu")
		(net "P5E_CPU0_P0_RX_DP<3>")
	)
	(segment
		(start 348.123256 -276.051518)
		(end 348.08414 -276.028658)
		(width 0.1143)
		(layer "In13.Cu")
		(net "P5E_CPU0_P0_RX_DP<3>")
	)
	(segment
		(start 348.05366 -283.501338)
		(end 348.08414 -283.483558)
		(width 0.1143)
		(layer "In13.Cu")
		(net "P5E_CPU0_P0_RX_DP<3>")
	)
	(segment
		(start 365.440468 -372.613428)
		(end 366.009682 -373.182642)
		(width 0.14224)
		(layer "In13.Cu")
		(net "P5E_CPU0_P0_RX_DP<3>")
	)
	(segment
		(start 344.792808 -372.022878)
		(end 359.537508 -373.47525)
		(width 0.14224)
		(layer "In13.Cu")
		(net "P5E_CPU0_P0_RX_DP<3>")
	)
	(segment
		(start 348.08414 -285.74873)
		(end 348.05366 -285.73095)
		(width 0.1143)
		(layer "In13.Cu")
		(net "P5E_CPU0_P0_RX_DP<3>")
	)
	(segment
		(start 347.896434 -295.79316)
		(end 347.896434 -295.131236)
		(width 0.1143)
		(layer "In13.Cu")
		(net "P5E_CPU0_P0_RX_DP<3>")
	)
	(segment
		(start 378.667772 -363.745018)
		(end 378.09805 -363.175296)
		(width 0.14224)
		(layer "In13.Cu")
		(net "P5E_CPU0_P0_RX_DP<3>")
	)
	(segment
		(start 348.053406 -287.350708)
		(end 348.035626 -287.338008)
		(width 0.1143)
		(layer "In13.Cu")
		(net "P5E_CPU0_P0_RX_DP<3>")
	)
	(segment
		(start 348.033848 -286.755078)
		(end 348.051628 -286.742378)
		(width 0.1143)
		(layer "In13.Cu")
		(net "P5E_CPU0_P0_RX_DP<3>")
	)
	(segment
		(start 348.05366 -281.881326)
		(end 348.08414 -281.863546)
		(width 0.1143)
		(layer "In13.Cu")
		(net "P5E_CPU0_P0_RX_DP<3>")
	)
	(segment
		(start 369.625626 -370.0018)
		(end 372.841774 -370.005864)
		(width 0.14224)
		(layer "In13.Cu")
		(net "P5E_CPU0_P0_RX_DP<3>")
	)
	(segment
		(start 348.123256 -282.531566)
		(end 348.08414 -282.508706)
		(width 0.1143)
		(layer "In13.Cu")
		(net "P5E_CPU0_P0_RX_DP<3>")
	)
	(segment
		(start 304.32248 -380.167388)
		(end 304.32248 -375.282968)
		(width 0.14224)
		(layer "In13.Cu")
		(net "P5E_CPU0_P0_RX_DP<3>")
	)
	(segment
		(start 349.38335 -271.656048)
		(end 349.681038 -271.656048)
		(width 0.1143)
		(layer "In13.Cu")
		(net "P5E_CPU0_P0_RX_DP<3>")
	)
	(segment
		(start 359.537508 -373.47525)
		(end 362.932218 -373.47525)
		(width 0.14224)
		(layer "In13.Cu")
		(net "P5E_CPU0_P0_RX_DP<3>")
	)
	(segment
		(start 348.08414 -276.028658)
		(end 348.05366 -276.010878)
		(width 0.1143)
		(layer "In13.Cu")
		(net "P5E_CPU0_P0_RX_DP<3>")
	)
	(segment
		(start 348.05366 -273.781266)
		(end 348.123256 -273.740626)
		(width 0.1143)
		(layer "In13.Cu")
		(net "P5E_CPU0_P0_RX_DP<3>")
	)
	(segment
		(start 308.148482 -393.428982)
		(end 307.832506 -393.113006)
		(width 0.14224)
		(layer "In13.Cu")
		(net "P5E_CPU0_P0_RX_DP<3>")
	)
	(segment
		(start 348.123256 -293.871142)
		(end 348.05366 -293.830756)
		(width 0.1143)
		(layer "In13.Cu")
		(net "P5E_CPU0_P0_RX_DP<3>")
	)
	(segment
		(start 365.440468 -372.17858)
		(end 365.440468 -372.613428)
		(width 0.14224)
		(layer "In13.Cu")
		(net "P5E_CPU0_P0_RX_DP<3>")
	)
	(segment
		(start 348.051628 -288.362136)
		(end 348.123002 -288.320988)
		(width 0.1143)
		(layer "In13.Cu")
		(net "P5E_CPU0_P0_RX_DP<3>")
	)
	(segment
		(start 308.849522 -373.47525)
		(end 316.210696 -373.47525)
		(width 0.14224)
		(layer "In13.Cu")
		(net "P5E_CPU0_P0_RX_DP<3>")
	)
	(segment
		(start 348.08414 -282.508706)
		(end 348.05366 -282.490926)
		(width 0.1143)
		(layer "In13.Cu")
		(net "P5E_CPU0_P0_RX_DP<3>")
	)
	(segment
		(start 308.060344 -393.930632)
		(end 308.148482 -393.842494)
		(width 0.14224)
		(layer "In13.Cu")
		(net "P5E_CPU0_P0_RX_DP<3>")
	)
	(segment
		(start 348.05366 -285.12135)
		(end 348.08414 -285.10357)
		(width 0.1143)
		(layer "In13.Cu")
		(net "P5E_CPU0_P0_RX_DP<3>")
	)
	(segment
		(start 348.123256 -274.431506)
		(end 348.08414 -274.408646)
		(width 0.1143)
		(layer "In13.Cu")
		(net "P5E_CPU0_P0_RX_DP<3>")
	)
	(segment
		(start 305.386994 -374.290336)
		(end 307.772816 -374.290336)
		(width 0.14224)
		(layer "In13.Cu")
		(net "P5E_CPU0_P0_RX_DP<3>")
	)
	(segment
		(start 378.667772 -364.179866)
		(end 378.667772 -363.745018)
		(width 0.14224)
		(layer "In13.Cu")
		(net "P5E_CPU0_P0_RX_DP<3>")
	)
	(segment
		(start 347.942154 -298.075604)
		(end 347.942154 -295.853358)
		(width 0.14224)
		(layer "In13.Cu")
		(net "P5E_CPU0_P0_RX_DP<3>")
	)
	(segment
		(start 347.942154 -295.83888)
		(end 347.896434 -295.79316)
		(width 0.1143)
		(layer "In13.Cu")
		(net "P5E_CPU0_P0_RX_DP<3>")
	)
	(segment
		(start 348.08414 -281.863546)
		(end 348.123256 -281.840686)
		(width 0.1143)
		(layer "In13.Cu")
		(net "P5E_CPU0_P0_RX_DP<3>")
	)
	(segment
		(start 378.640086 -356.151688)
		(end 361.82427 -315.557154)
		(width 0.14224)
		(layer "In13.Cu")
		(net "P5E_CPU0_P0_RX_DP<3>")
	)
	(segment
		(start 368.6302 -368.78768)
		(end 368.6302 -368.988848)
		(width 0.14224)
		(layer "In13.Cu")
		(net "P5E_CPU0_P0_RX_DP<3>")
	)
	(segment
		(start 368.02441 -368.383058)
		(end 368.225578 -368.383058)
		(width 0.14224)
		(layer "In13.Cu")
		(net "P5E_CPU0_P0_RX_DP<3>")
	)
	(segment
		(start 348.08414 -277.00351)
		(end 348.123256 -276.98065)
		(width 0.1143)
		(layer "In13.Cu")
		(net "P5E_CPU0_P0_RX_DP<3>")
	)
	(segment
		(start 307.8861 -394.031216)
		(end 308.060344 -393.930632)
		(width 0.14224)
		(layer "In13.Cu")
		(net "P5E_CPU0_P0_RX_DP<3>")
	)
	(segment
		(start 348.123256 -280.911554)
		(end 348.08414 -280.888694)
		(width 0.1143)
		(layer "In13.Cu")
		(net "P5E_CPU0_P0_RX_DP<3>")
	)
	(segment
		(start 366.009682 -373.182642)
		(end 366.444784 -373.182642)
		(width 0.14224)
		(layer "In13.Cu")
		(net "P5E_CPU0_P0_RX_DP<3>")
	)
	(segment
		(start 361.82427 -315.557154)
		(end 348.30131 -299.07865)
		(width 0.14224)
		(layer "In13.Cu")
		(net "P5E_CPU0_P0_RX_DP<3>")
	)
	(segment
		(start 372.147338 -368.491516)
		(end 371.741954 -368.086386)
		(width 0.14224)
		(layer "In13.Cu")
		(net "P5E_CPU0_P0_RX_DP<3>")
	)
	(segment
		(start 348.05366 -294.841168)
		(end 348.123256 -294.800528)
		(width 0.1143)
		(layer "In13.Cu")
		(net "P5E_CPU0_P0_RX_DP<3>")
	)
	(segment
		(start 349.300546 -271.738852)
		(end 349.38335 -271.656048)
		(width 0.1143)
		(layer "In13.Cu")
		(net "P5E_CPU0_P0_RX_DP<3>")
	)
	(segment
		(start 348.05366 -275.401278)
		(end 348.08414 -275.383498)
		(width 0.1143)
		(layer "In13.Cu")
		(net "P5E_CPU0_P0_RX_DP<3>")
	)
	(segment
		(start 368.6302 -368.988848)
		(end 365.440468 -372.17858)
		(width 0.14224)
		(layer "In13.Cu")
		(net "P5E_CPU0_P0_RX_DP<3>")
	)
	(segment
		(start 308.140354 -392.43)
		(end 308.140354 -388.554722)
		(width 0.14224)
		(layer "In13.Cu")
		(net "P5E_CPU0_P0_RX_DP<3>")
	)
	(segment
		(start 378.640086 -360.817922)
		(end 378.640086 -356.151688)
		(width 0.14224)
		(layer "In13.Cu")
		(net "P5E_CPU0_P0_RX_DP<3>")
	)
	(segment
		(start 348.08414 -275.383498)
		(end 348.123256 -275.360638)
		(width 0.1143)
		(layer "In13.Cu")
		(net "P5E_CPU0_P0_RX_DP<3>")
	)
	(segment
		(start 372.841774 -370.005864)
		(end 378.667772 -364.179866)
		(width 0.14224)
		(layer "In13.Cu")
		(net "P5E_CPU0_P0_RX_DP<3>")
	)
	(segment
		(start 348.08414 -280.888694)
		(end 348.05366 -280.870914)
		(width 0.1143)
		(layer "In13.Cu")
		(net "P5E_CPU0_P0_RX_DP<3>")
	)
	(segment
		(start 348.123256 -284.151578)
		(end 348.08414 -284.128718)
		(width 0.1143)
		(layer "In13.Cu")
		(net "P5E_CPU0_P0_RX_DP<3>")
	)
	(segment
		(start 348.123256 -292.25113)
		(end 348.05366 -292.210744)
		(width 0.1143)
		(layer "In13.Cu")
		(net "P5E_CPU0_P0_RX_DP<3>")
	)
	(segment
		(start 348.120716 -287.38957)
		(end 348.053406 -287.350708)
		(width 0.1143)
		(layer "In13.Cu")
		(net "P5E_CPU0_P0_RX_DP<3>")
	)
	(segment
		(start 348.08414 -284.128718)
		(end 348.05366 -284.110938)
		(width 0.1143)
		(layer "In13.Cu")
		(net "P5E_CPU0_P0_RX_DP<3>")
	)
	(segment
		(start 348.123256 -279.291542)
		(end 348.08414 -279.268682)
		(width 0.1143)
		(layer "In13.Cu")
		(net "P5E_CPU0_P0_RX_DP<3>")
	)
	(segment
		(start 348.44863 -273.024854)
		(end 348.496382 -272.99031)
		(width 0.1143)
		(layer "In13.Cu")
		(net "P5E_CPU0_P0_RX_DP<3>")
	)
	(segment
		(start 362.932218 -373.47525)
		(end 368.02441 -368.383058)
		(width 0.14224)
		(layer "In13.Cu")
		(net "P5E_CPU0_P0_RX_DP<3>")
	)
	(segment
		(start 348.539308 -272.960338)
		(end 348.671134 -272.870422)
		(width 0.1143)
		(layer "In13.Cu")
		(net "P5E_CPU0_P0_RX_DP<3>")
	)
	(segment
		(start 366.444784 -373.182642)
		(end 369.625626 -370.0018)
		(width 0.14224)
		(layer "In13.Cu")
		(net "P5E_CPU0_P0_RX_DP<3>")
	)
	(segment
		(start 348.05366 -277.02129)
		(end 348.08414 -277.00351)
		(width 0.1143)
		(layer "In13.Cu")
		(net "P5E_CPU0_P0_RX_DP<3>")
	)
	(segment
		(start 348.834456 -272.556732)
		(end 348.834456 -272.466308)
		(width 0.1143)
		(layer "In13.Cu")
		(net "P5E_CPU0_P0_RX_DP<3>")
	)
	(segment
		(start 348.05366 -289.981132)
		(end 348.123256 -289.940492)
		(width 0.1143)
		(layer "In13.Cu")
		(net "P5E_CPU0_P0_RX_DP<3>")
	)
	(segment
		(start 348.123256 -285.77159)
		(end 348.08414 -285.74873)
		(width 0.1143)
		(layer "In13.Cu")
		(net "P5E_CPU0_P0_RX_DP<3>")
	)
	(segment
		(start 308.105302 -374.152668)
		(end 308.735476 -373.522494)
		(width 0.14224)
		(layer "In13.Cu")
		(net "P5E_CPU0_P0_RX_DP<3>")
	)
	(segment
		(start 348.08414 -277.64867)
		(end 348.05366 -277.63089)
		(width 0.1143)
		(layer "In13.Cu")
		(net "P5E_CPU0_P0_RX_DP<3>")
	)
	(segment
		(start 348.08414 -280.243534)
		(end 348.123256 -280.220674)
		(width 0.1143)
		(layer "In13.Cu")
		(net "P5E_CPU0_P0_RX_DP<3>")
	)
	(segment
		(start 348.08414 -274.408646)
		(end 348.05366 -274.390866)
		(width 0.1143)
		(layer "In13.Cu")
		(net "P5E_CPU0_P0_RX_DP<3>")
	)
	(segment
		(start 372.347236 -368.491516)
		(end 372.147338 -368.491516)
		(width 0.14224)
		(layer "In13.Cu")
		(net "P5E_CPU0_P0_RX_DP<3>")
	)
	(segment
		(start 348.08414 -285.10357)
		(end 348.123256 -285.08071)
		(width 0.1143)
		(layer "In13.Cu")
		(net "P5E_CPU0_P0_RX_DP<3>")
	)
	(segment
		(start 316.210696 -373.47525)
		(end 325.868284 -371.554248)
		(width 0.14224)
		(layer "In13.Cu")
		(net "P5E_CPU0_P0_RX_DP<3>")
	)
	(segment
		(start 348.051628 -286.742378)
		(end 348.123256 -286.700722)
		(width 0.1143)
		(layer "In13.Cu")
		(net "P5E_CPU0_P0_RX_DP<3>")
	)
	(segment
		(start 347.942154 -295.853358)
		(end 347.942154 -295.83888)
		(width 0.1143)
		(layer "In13.Cu")
		(net "P5E_CPU0_P0_RX_DP<3>")
	)
	(segment
		(start 348.05366 -291.601144)
		(end 348.123256 -291.560504)
		(width 0.1143)
		(layer "In13.Cu")
		(net "P5E_CPU0_P0_RX_DP<3>")
	)
	(segment
		(start 348.123256 -289.011106)
		(end 348.05366 -288.97072)
		(width 0.1143)
		(layer "In13.Cu")
		(net "P5E_CPU0_P0_RX_DP<3>")
	)
	(segment
		(start 348.366588 -273.27606)
		(end 348.366588 -273.185128)
		(width 0.1143)
		(layer "In13.Cu")
		(net "P5E_CPU0_P0_RX_DP<3>")
	)
	(segment
		(start 304.369724 -375.168922)
		(end 305.150266 -374.38838)
		(width 0.14224)
		(layer "In13.Cu")
		(net "P5E_CPU0_P0_RX_DP<3>")
	)
	(segment
		(start 378.09805 -363.175296)
		(end 377.662948 -363.175804)
		(width 0.14224)
		(layer "In13.Cu")
		(net "P5E_CPU0_P0_RX_DP<3>")
	)
	(segment
		(start 348.123256 -277.67153)
		(end 348.08414 -277.64867)
		(width 0.1143)
		(layer "In13.Cu")
		(net "P5E_CPU0_P0_RX_DP<3>")
	)
	(segment
		(start 348.05366 -280.261314)
		(end 348.08414 -280.243534)
		(width 0.1143)
		(layer "In13.Cu")
		(net "P5E_CPU0_P0_RX_DP<3>")
	)
	(segment
		(start 306.479956 -381.677418)
		(end 304.379122 -380.273306)
		(width 0.14224)
		(layer "In13.Cu")
		(net "P5E_CPU0_P0_RX_DP<3>")
	)
	(segment
		(start 307.791104 -394.385292)
		(end 307.8861 -394.031216)
		(width 0.14224)
		(layer "In13.Cu")
		(net "P5E_CPU0_P0_RX_DP<3>")
	)
	(segment
		(start 347.942408 -298.07535)
		(end 347.942154 -298.075604)
		(width 0.14224)
		(layer "In13.Cu")
		(net "P5E_CPU0_P0_RX_DP<3>")
	)
	(segment
		(start 368.225578 -368.383058)
		(end 368.6302 -368.78768)
		(width 0.14224)
		(layer "In13.Cu")
		(net "P5E_CPU0_P0_RX_DP<3>")
	)
	(segment
		(start 349.01632 -272.1483)
		(end 349.06331 -272.120614)
		(width 0.1143)
		(layer "In13.Cu")
		(net "P5E_CPU0_P0_RX_DP<3>")
	)
	(segment
		(start 347.896434 -295.131236)
		(end 347.898212 -295.113456)
		(width 0.1143)
		(layer "In13.Cu")
		(net "P5E_CPU0_P0_RX_DP<3>")
	)
	(segment
		(start 307.832506 -393.113006)
		(end 307.835554 -392.7348)
		(width 0.14224)
		(layer "In13.Cu")
		(net "P5E_CPU0_P0_RX_DP<3>")
	)
	(segment
		(start 371.741954 -367.885472)
		(end 378.520198 -361.107228)
		(width 0.14224)
		(layer "In13.Cu")
		(net "P5E_CPU0_P0_RX_DP<3>")
	)
	(segment
		(start 348.05366 -293.221156)
		(end 348.123256 -293.180516)
		(width 0.1143)
		(layer "In13.Cu")
		(net "P5E_CPU0_P0_RX_DP<3>")
	)
	(segment
		(start 307.835554 -392.7348)
		(end 308.140354 -392.43)
		(width 0.14224)
		(layer "In13.Cu")
		(net "P5E_CPU0_P0_RX_DP<3>")
	)
	(segment
		(start 377.662948 -363.175804)
		(end 372.347236 -368.491516)
		(width 0.14224)
		(layer "In13.Cu")
		(net "P5E_CPU0_P0_RX_DP<3>")
	)
	(segment
		(start 348.08414 -278.623522)
		(end 348.123256 -278.600662)
		(width 0.1143)
		(layer "In13.Cu")
		(net "P5E_CPU0_P0_RX_DP<3>")
	)
	(arc
		(start 348.123256 -276.98065)
		(mid 348.366583 -276.516084)
		(end 348.123256 -276.051518)
		(width 0.1143)
		(layer "In13.Cu")
		(net "P5E_CPU0_P0_RX_DP<3>")
	)
	(arc
		(start 349.296736 -271.761712)
		(mid 349.298759 -271.750302)
		(end 349.300546 -271.738852)
		(width 0.1143)
		(layer "In13.Cu")
		(net "P5E_CPU0_P0_RX_DP<3>")
	)
	(arc
		(start 348.05366 -285.73095)
		(mid 347.896683 -285.42615)
		(end 348.05366 -285.12135)
		(width 0.1143)
		(layer "In13.Cu")
		(net "P5E_CPU0_P0_RX_DP<3>")
	)
	(arc
		(start 348.123256 -286.700722)
		(mid 348.366583 -286.236156)
		(end 348.123256 -285.77159)
		(width 0.1143)
		(layer "In13.Cu")
		(net "P5E_CPU0_P0_RX_DP<3>")
	)
	(arc
		(start 348.05366 -280.870914)
		(mid 347.896683 -280.566114)
		(end 348.05366 -280.261314)
		(width 0.1143)
		(layer "In13.Cu")
		(net "P5E_CPU0_P0_RX_DP<3>")
	)
	(arc
		(start 348.30131 -299.07865)
		(mid 348.034852 -298.608126)
		(end 347.942408 -298.07535)
		(width 0.14224)
		(layer "In13.Cu")
		(net "P5E_CPU0_P0_RX_DP<3>")
	)
	(arc
		(start 333.17815 -371.401594)
		(mid 333.396338 -371.403697)
		(end 333.614522 -371.406166)
		(width 0.14224)
		(layer "In13.Cu")
		(net "P5E_CPU0_P0_RX_DP<3>")
	)
	(arc
		(start 305.150266 -374.38838)
		(mid 305.258878 -374.315808)
		(end 305.386994 -374.290336)
		(width 0.14224)
		(layer "In13.Cu")
		(net "P5E_CPU0_P0_RX_DP<3>")
	)
	(arc
		(start 348.123256 -289.940492)
		(mid 348.366692 -289.475854)
		(end 348.123256 -289.011106)
		(width 0.1143)
		(layer "In13.Cu")
		(net "P5E_CPU0_P0_RX_DP<3>")
	)
	(arc
		(start 348.05366 -292.210744)
		(mid 347.896683 -291.905944)
		(end 348.05366 -291.601144)
		(width 0.1143)
		(layer "In13.Cu")
		(net "P5E_CPU0_P0_RX_DP<3>")
	)
	(arc
		(start 306.66436 -382.022604)
		(mid 306.61537 -381.826926)
		(end 306.479956 -381.677418)
		(width 0.14224)
		(layer "In13.Cu")
		(net "P5E_CPU0_P0_RX_DP<3>")
	)
	(arc
		(start 347.898212 -295.113456)
		(mid 347.946099 -294.960293)
		(end 348.05366 -294.841168)
		(width 0.1143)
		(layer "In13.Cu")
		(net "P5E_CPU0_P0_RX_DP<3>")
	)
	(arc
		(start 304.379122 -380.273306)
		(mid 304.337499 -380.227454)
		(end 304.32248 -380.167388)
		(width 0.14224)
		(layer "In13.Cu")
		(net "P5E_CPU0_P0_RX_DP<3>")
	)
	(arc
		(start 348.123256 -294.800528)
		(mid 348.366692 -294.33589)
		(end 348.123256 -293.871142)
		(width 0.1143)
		(layer "In13.Cu")
		(net "P5E_CPU0_P0_RX_DP<3>")
	)
	(arc
		(start 348.123256 -285.08071)
		(mid 348.366583 -284.616144)
		(end 348.123256 -284.151578)
		(width 0.1143)
		(layer "In13.Cu")
		(net "P5E_CPU0_P0_RX_DP<3>")
	)
	(arc
		(start 348.123256 -293.180516)
		(mid 348.366692 -292.715878)
		(end 348.123256 -292.25113)
		(width 0.1143)
		(layer "In13.Cu")
		(net "P5E_CPU0_P0_RX_DP<3>")
	)
	(arc
		(start 348.05366 -277.63089)
		(mid 347.896683 -277.32609)
		(end 348.05366 -277.02129)
		(width 0.1143)
		(layer "In13.Cu")
		(net "P5E_CPU0_P0_RX_DP<3>")
	)
	(arc
		(start 304.32248 -375.282968)
		(mid 304.334757 -375.221245)
		(end 304.369724 -375.168922)
		(width 0.14224)
		(layer "In13.Cu")
		(net "P5E_CPU0_P0_RX_DP<3>")
	)
	(arc
		(start 306.674012 -384.932936)
		(mid 306.666767 -384.909029)
		(end 306.66436 -384.884168)
		(width 0.14224)
		(layer "In13.Cu")
		(net "P5E_CPU0_P0_RX_DP<3>")
	)
	(arc
		(start 348.05366 -276.010878)
		(mid 347.896683 -275.706078)
		(end 348.05366 -275.401278)
		(width 0.1143)
		(layer "In13.Cu")
		(net "P5E_CPU0_P0_RX_DP<3>")
	)
	(arc
		(start 348.496382 -272.99031)
		(mid 348.517748 -272.975185)
		(end 348.539308 -272.960338)
		(width 0.1143)
		(layer "In13.Cu")
		(net "P5E_CPU0_P0_RX_DP<3>")
	)
	(arc
		(start 348.671134 -272.870422)
		(mid 348.745524 -272.803279)
		(end 348.799404 -272.718784)
		(width 0.1143)
		(layer "In13.Cu")
		(net "P5E_CPU0_P0_RX_DP<3>")
	)
	(arc
		(start 348.123256 -278.600662)
		(mid 348.366583 -278.136096)
		(end 348.123256 -277.67153)
		(width 0.1143)
		(layer "In13.Cu")
		(net "P5E_CPU0_P0_RX_DP<3>")
	)
	(arc
		(start 348.123256 -280.220674)
		(mid 348.366583 -279.756108)
		(end 348.123256 -279.291542)
		(width 0.1143)
		(layer "In13.Cu")
		(net "P5E_CPU0_P0_RX_DP<3>")
	)
	(arc
		(start 349.06331 -272.120614)
		(mid 349.215355 -271.964138)
		(end 349.296736 -271.761712)
		(width 0.1143)
		(layer "In13.Cu")
		(net "P5E_CPU0_P0_RX_DP<3>")
	)
	(arc
		(start 348.05366 -282.490926)
		(mid 347.896683 -282.186126)
		(end 348.05366 -281.881326)
		(width 0.1143)
		(layer "In13.Cu")
		(net "P5E_CPU0_P0_RX_DP<3>")
	)
	(arc
		(start 348.123256 -281.840686)
		(mid 348.366583 -281.37612)
		(end 348.123256 -280.911554)
		(width 0.1143)
		(layer "In13.Cu")
		(net "P5E_CPU0_P0_RX_DP<3>")
	)
	(arc
		(start 308.140354 -388.554722)
		(mid 308.132438 -388.474828)
		(end 308.109112 -388.398004)
		(width 0.14224)
		(layer "In13.Cu")
		(net "P5E_CPU0_P0_RX_DP<3>")
	)
	(arc
		(start 348.123256 -291.560504)
		(mid 348.366692 -291.095866)
		(end 348.123256 -290.631118)
		(width 0.1143)
		(layer "In13.Cu")
		(net "P5E_CPU0_P0_RX_DP<3>")
	)
	(arc
		(start 348.366588 -273.185128)
		(mid 348.388288 -273.095098)
		(end 348.44863 -273.024854)
		(width 0.1143)
		(layer "In13.Cu")
		(net "P5E_CPU0_P0_RX_DP<3>")
	)
	(arc
		(start 348.05366 -274.390866)
		(mid 347.896683 -274.086066)
		(end 348.05366 -273.781266)
		(width 0.1143)
		(layer "In13.Cu")
		(net "P5E_CPU0_P0_RX_DP<3>")
	)
	(arc
		(start 348.05366 -279.250902)
		(mid 347.896683 -278.946102)
		(end 348.05366 -278.641302)
		(width 0.1143)
		(layer "In13.Cu")
		(net "P5E_CPU0_P0_RX_DP<3>")
	)
	(arc
		(start 348.05366 -290.590732)
		(mid 347.896683 -290.285932)
		(end 348.05366 -289.981132)
		(width 0.1143)
		(layer "In13.Cu")
		(net "P5E_CPU0_P0_RX_DP<3>")
	)
	(arc
		(start 348.123256 -275.360638)
		(mid 348.366583 -274.896072)
		(end 348.123256 -274.431506)
		(width 0.1143)
		(layer "In13.Cu")
		(net "P5E_CPU0_P0_RX_DP<3>")
	)
	(arc
		(start 348.123002 -288.320988)
		(mid 348.366645 -287.854723)
		(end 348.120716 -287.38957)
		(width 0.1143)
		(layer "In13.Cu")
		(net "P5E_CPU0_P0_RX_DP<3>")
	)
	(arc
		(start 348.05366 -288.97072)
		(mid 347.9384 -288.837301)
		(end 347.896942 -288.66592)
		(width 0.1143)
		(layer "In13.Cu")
		(net "P5E_CPU0_P0_RX_DP<3>")
	)
	(arc
		(start 348.123256 -283.460698)
		(mid 348.366583 -282.996132)
		(end 348.123256 -282.531566)
		(width 0.1143)
		(layer "In13.Cu")
		(net "P5E_CPU0_P0_RX_DP<3>")
	)
	(arc
		(start 307.772816 -374.290336)
		(mid 307.95275 -374.254563)
		(end 308.105302 -374.152668)
		(width 0.14224)
		(layer "In13.Cu")
		(net "P5E_CPU0_P0_RX_DP<3>")
	)
	(arc
		(start 378.520198 -361.107228)
		(mid 378.608942 -360.974508)
		(end 378.640086 -360.817922)
		(width 0.14224)
		(layer "In13.Cu")
		(net "P5E_CPU0_P0_RX_DP<3>")
	)
	(arc
		(start 348.123256 -273.740626)
		(mid 348.302069 -273.538276)
		(end 348.366588 -273.27606)
		(width 0.1143)
		(layer "In13.Cu")
		(net "P5E_CPU0_P0_RX_DP<3>")
	)
	(arc
		(start 348.799404 -272.718784)
		(mid 348.825706 -272.639656)
		(end 348.834456 -272.556732)
		(width 0.1143)
		(layer "In13.Cu")
		(net "P5E_CPU0_P0_RX_DP<3>")
	)
	(arc
		(start 347.896942 -288.66592)
		(mid 347.937711 -288.49539)
		(end 348.051628 -288.362136)
		(width 0.1143)
		(layer "In13.Cu")
		(net "P5E_CPU0_P0_RX_DP<3>")
	)
	(arc
		(start 333.614522 -371.406166)
		(mid 339.210299 -371.59428)
		(end 344.792808 -372.022878)
		(width 0.14224)
		(layer "In13.Cu")
		(net "P5E_CPU0_P0_RX_DP<3>")
	)
	(arc
		(start 325.868284 -371.554248)
		(mid 326.521926 -371.451464)
		(end 327.181718 -371.401594)
		(width 0.14224)
		(layer "In13.Cu")
		(net "P5E_CPU0_P0_RX_DP<3>")
	)
	(arc
		(start 308.735476 -373.522494)
		(mid 308.787801 -373.487532)
		(end 308.849522 -373.47525)
		(width 0.14224)
		(layer "In13.Cu")
		(net "P5E_CPU0_P0_RX_DP<3>")
	)
	(arc
		(start 348.834456 -272.466308)
		(mid 348.883125 -272.283127)
		(end 349.01632 -272.1483)
		(width 0.1143)
		(layer "In13.Cu")
		(net "P5E_CPU0_P0_RX_DP<3>")
	)
	(arc
		(start 348.035626 -287.338008)
		(mid 347.885262 -287.047)
		(end 348.033848 -286.755078)
		(width 0.1143)
		(layer "In13.Cu")
		(net "P5E_CPU0_P0_RX_DP<3>")
	)
	(arc
		(start 348.05366 -284.110938)
		(mid 347.896683 -283.806138)
		(end 348.05366 -283.501338)
		(width 0.1143)
		(layer "In13.Cu")
		(net "P5E_CPU0_P0_RX_DP<3>")
	)
	(arc
		(start 348.05366 -293.830756)
		(mid 347.896683 -293.525956)
		(end 348.05366 -293.221156)
		(width 0.1143)
		(layer "In13.Cu")
		(net "P5E_CPU0_P0_RX_DP<3>")
	)
	(segment
		(start 347.327982 -269.770098)
		(end 346.86113 -270.036036)
		(width 0.12954)
		(layer "F.Cu")
		(net "P5E_CPU0_P0_RX_DP<2>")
	)
	(segment
		(start 306.070254 -394.385292)
		(end 306.590954 -394.385292)
		(width 0.127)
		(layer "F.Cu")
		(net "P5E_CPU0_P0_RX_DP<2>")
	)
	(segment
		(start 347.144086 -281.863546)
		(end 347.156532 -281.85745)
		(width 0.1143)
		(layer "In13.Cu")
		(net "P5E_CPU0_P0_RX_DP<2>")
	)
	(segment
		(start 347.213936 -292.277038)
		(end 347.208856 -292.271958)
		(width 0.1143)
		(layer "In13.Cu")
		(net "P5E_CPU0_P0_RX_DP<2>")
	)
	(segment
		(start 347.144086 -273.763486)
		(end 347.181932 -273.744436)
		(width 0.1143)
		(layer "In13.Cu")
		(net "P5E_CPU0_P0_RX_DP<2>")
	)
	(segment
		(start 347.153992 -276.035008)
		(end 347.148404 -276.031452)
		(width 0.1143)
		(layer "In13.Cu")
		(net "P5E_CPU0_P0_RX_DP<2>")
	)
	(segment
		(start 347.144086 -276.028658)
		(end 347.143324 -276.02815)
		(width 0.1143)
		(layer "In13.Cu")
		(net "P5E_CPU0_P0_RX_DP<2>")
	)
	(segment
		(start 347.14561 -283.482796)
		(end 347.146372 -283.482288)
		(width 0.1143)
		(layer "In13.Cu")
		(net "P5E_CPU0_P0_RX_DP<2>")
	)
	(segment
		(start 347.144086 -288.343594)
		(end 347.148658 -288.341054)
		(width 0.1143)
		(layer "In13.Cu")
		(net "P5E_CPU0_P0_RX_DP<2>")
	)
	(segment
		(start 347.164914 -281.85237)
		(end 347.16847 -281.850338)
		(width 0.1143)
		(layer "In13.Cu")
		(net "P5E_CPU0_P0_RX_DP<2>")
	)
	(segment
		(start 347.145356 -284.131004)
		(end 347.142562 -284.129226)
		(width 0.1143)
		(layer "In13.Cu")
		(net "P5E_CPU0_P0_RX_DP<2>")
	)
	(segment
		(start 347.142562 -275.384514)
		(end 347.146626 -275.38172)
		(width 0.1143)
		(layer "In13.Cu")
		(net "P5E_CPU0_P0_RX_DP<2>")
	)
	(segment
		(start 347.185488 -289.01263)
		(end 347.114368 -288.971228)
		(width 0.1143)
		(layer "In13.Cu")
		(net "P5E_CPU0_P0_RX_DP<2>")
	)
	(segment
		(start 347.187774 -292.250622)
		(end 347.126814 -292.209728)
		(width 0.1143)
		(layer "In13.Cu")
		(net "P5E_CPU0_P0_RX_DP<2>")
	)
	(segment
		(start 347.146626 -275.38172)
		(end 347.180408 -275.361908)
		(width 0.1143)
		(layer "In13.Cu")
		(net "P5E_CPU0_P0_RX_DP<2>")
	)
	(segment
		(start 347.145356 -277.64867)
		(end 347.143578 -277.64867)
		(width 0.1143)
		(layer "In13.Cu")
		(net "P5E_CPU0_P0_RX_DP<2>")
	)
	(segment
		(start 347.115892 -273.781266)
		(end 347.126814 -273.774916)
		(width 0.1143)
		(layer "In13.Cu")
		(net "P5E_CPU0_P0_RX_DP<2>")
	)
	(segment
		(start 369.356894 -366.829594)
		(end 369.926616 -367.399316)
		(width 0.14224)
		(layer "In13.Cu")
		(net "P5E_CPU0_P0_RX_DP<2>")
	)
	(segment
		(start 308.45379 -372.54053)
		(end 315.468 -372.54053)
		(width 0.14224)
		(layer "In13.Cu")
		(net "P5E_CPU0_P0_RX_DP<2>")
	)
	(segment
		(start 347.180662 -282.53309)
		(end 347.148658 -282.511754)
		(width 0.1143)
		(layer "In13.Cu")
		(net "P5E_CPU0_P0_RX_DP<2>")
	)
	(segment
		(start 347.13799 -275.387308)
		(end 347.142562 -275.384514)
		(width 0.1143)
		(layer "In13.Cu")
		(net "P5E_CPU0_P0_RX_DP<2>")
	)
	(segment
		(start 306.632356 -393.113006)
		(end 306.635404 -392.734546)
		(width 0.14224)
		(layer "In13.Cu")
		(net "P5E_CPU0_P0_RX_DP<2>")
	)
	(segment
		(start 347.181678 -280.914094)
		(end 347.143832 -280.888694)
		(width 0.1143)
		(layer "In13.Cu")
		(net "P5E_CPU0_P0_RX_DP<2>")
	)
	(segment
		(start 347.157548 -278.614632)
		(end 347.158564 -278.614124)
		(width 0.1143)
		(layer "In13.Cu")
		(net "P5E_CPU0_P0_RX_DP<2>")
	)
	(segment
		(start 347.182948 -287.393634)
		(end 347.11132 -287.351978)
		(width 0.1143)
		(layer "In13.Cu")
		(net "P5E_CPU0_P0_RX_DP<2>")
	)
	(segment
		(start 347.107002 -277.026116)
		(end 347.10878 -277.024846)
		(width 0.1143)
		(layer "In13.Cu")
		(net "P5E_CPU0_P0_RX_DP<2>")
	)
	(segment
		(start 347.107002 -294.839898)
		(end 347.177868 -294.799004)
		(width 0.1143)
		(layer "In13.Cu")
		(net "P5E_CPU0_P0_RX_DP<2>")
	)
	(segment
		(start 347.143324 -276.02815)
		(end 347.112336 -276.01037)
		(width 0.1143)
		(layer "In13.Cu")
		(net "P5E_CPU0_P0_RX_DP<2>")
	)
	(segment
		(start 306.860194 -393.930632)
		(end 306.948332 -393.842494)
		(width 0.14224)
		(layer "In13.Cu")
		(net "P5E_CPU0_P0_RX_DP<2>")
	)
	(segment
		(start 347.208856 -292.271704)
		(end 347.187774 -292.250622)
		(width 0.1143)
		(layer "In13.Cu")
		(net "P5E_CPU0_P0_RX_DP<2>")
	)
	(segment
		(start 347.167962 -291.569394)
		(end 347.168724 -291.568886)
		(width 0.1143)
		(layer "In13.Cu")
		(net "P5E_CPU0_P0_RX_DP<2>")
	)
	(segment
		(start 347.179392 -274.432268)
		(end 347.115892 -274.38985)
		(width 0.1143)
		(layer "In13.Cu")
		(net "P5E_CPU0_P0_RX_DP<2>")
	)
	(segment
		(start 347.612462 -271.977866)
		(end 347.608398 -271.975326)
		(width 0.1143)
		(layer "In13.Cu")
		(net "P5E_CPU0_P0_RX_DP<2>")
	)
	(segment
		(start 347.183202 -293.871396)
		(end 347.11767 -293.833042)
		(width 0.1143)
		(layer "In13.Cu")
		(net "P5E_CPU0_P0_RX_DP<2>")
	)
	(segment
		(start 299.65015 -376.521726)
		(end 302.204882 -373.966994)
		(width 0.14224)
		(layer "In13.Cu")
		(net "P5E_CPU0_P0_RX_DP<2>")
	)
	(segment
		(start 362.344716 -372.19636)
		(end 374.942862 -359.598214)
		(width 0.14224)
		(layer "In13.Cu")
		(net "P5E_CPU0_P0_RX_DP<2>")
	)
	(segment
		(start 347.15196 -280.238962)
		(end 347.180154 -280.222706)
		(width 0.1143)
		(layer "In13.Cu")
		(net "P5E_CPU0_P0_RX_DP<2>")
	)
	(segment
		(start 347.219016 -293.163498)
		(end 347.25102 -293.133526)
		(width 0.1143)
		(layer "In13.Cu")
		(net "P5E_CPU0_P0_RX_DP<2>")
	)
	(segment
		(start 347.122496 -291.59581)
		(end 347.1418 -291.585142)
		(width 0.1143)
		(layer "In13.Cu")
		(net "P5E_CPU0_P0_RX_DP<2>")
	)
	(segment
		(start 347.425264 -273.27987)
		(end 347.425264 -273.278854)
		(width 0.1143)
		(layer "In13.Cu")
		(net "P5E_CPU0_P0_RX_DP<2>")
	)
	(segment
		(start 347.182948 -277.670514)
		(end 347.145356 -277.64867)
		(width 0.1143)
		(layer "In13.Cu")
		(net "P5E_CPU0_P0_RX_DP<2>")
	)
	(segment
		(start 346.563188 -270.036036)
		(end 346.86113 -270.036036)
		(width 0.1143)
		(layer "In13.Cu")
		(net "P5E_CPU0_P0_RX_DP<2>")
	)
	(segment
		(start 375.548144 -360.203496)
		(end 369.356894 -366.394746)
		(width 0.14224)
		(layer "In13.Cu")
		(net "P5E_CPU0_P0_RX_DP<2>")
	)
	(segment
		(start 347.146626 -276.030436)
		(end 347.146626 -276.030182)
		(width 0.1143)
		(layer "In13.Cu")
		(net "P5E_CPU0_P0_RX_DP<2>")
	)
	(segment
		(start 347.112336 -275.401786)
		(end 347.13799 -275.387308)
		(width 0.1143)
		(layer "In13.Cu")
		(net "P5E_CPU0_P0_RX_DP<2>")
	)
	(segment
		(start 347.11005 -289.986212)
		(end 347.110304 -289.986212)
		(width 0.1143)
		(layer "In13.Cu")
		(net "P5E_CPU0_P0_RX_DP<2>")
	)
	(segment
		(start 347.177868 -294.799004)
		(end 347.183202 -294.800528)
		(width 0.1143)
		(layer "In13.Cu")
		(net "P5E_CPU0_P0_RX_DP<2>")
	)
	(segment
		(start 375.548144 -360.023664)
		(end 375.548144 -360.203496)
		(width 0.14224)
		(layer "In13.Cu")
		(net "P5E_CPU0_P0_RX_DP<2>")
	)
	(segment
		(start 346.996766 -295.88968)
		(end 346.996766 -295.861232)
		(width 0.1143)
		(layer "In13.Cu")
		(net "P5E_CPU0_P0_RX_DP<2>")
	)
	(segment
		(start 347.182948 -285.77159)
		(end 347.112336 -285.730442)
		(width 0.1143)
		(layer "In13.Cu")
		(net "P5E_CPU0_P0_RX_DP<2>")
	)
	(segment
		(start 347.182186 -278.600154)
		(end 347.182948 -278.599646)
		(width 0.1143)
		(layer "In13.Cu")
		(net "P5E_CPU0_P0_RX_DP<2>")
	)
	(segment
		(start 326.839834 -370.452904)
		(end 331.659992 -370.452904)
		(width 0.14224)
		(layer "In13.Cu")
		(net "P5E_CPU0_P0_RX_DP<2>")
	)
	(segment
		(start 360.846878 -315.947806)
		(end 347.26499 -299.397674)
		(width 0.14224)
		(layer "In13.Cu")
		(net "P5E_CPU0_P0_RX_DP<2>")
	)
	(segment
		(start 347.184472 -284.154118)
		(end 347.145356 -284.131004)
		(width 0.1143)
		(layer "In13.Cu")
		(net "P5E_CPU0_P0_RX_DP<2>")
	)
	(segment
		(start 348.93504 -371.300756)
		(end 358.02189 -372.19636)
		(width 0.14224)
		(layer "In13.Cu")
		(net "P5E_CPU0_P0_RX_DP<2>")
	)
	(segment
		(start 346.996766 -298.647358)
		(end 346.996766 -295.88968)
		(width 0.14224)
		(layer "In13.Cu")
		(net "P5E_CPU0_P0_RX_DP<2>")
	)
	(segment
		(start 347.144086 -279.268682)
		(end 347.113352 -279.248108)
		(width 0.1143)
		(layer "In13.Cu")
		(net "P5E_CPU0_P0_RX_DP<2>")
	)
	(segment
		(start 347.147388 -283.48178)
		(end 347.14815 -283.481272)
		(width 0.1143)
		(layer "In13.Cu")
		(net "P5E_CPU0_P0_RX_DP<2>")
	)
	(segment
		(start 347.146626 -276.030182)
		(end 347.145102 -276.029166)
		(width 0.1143)
		(layer "In13.Cu")
		(net "P5E_CPU0_P0_RX_DP<2>")
	)
	(segment
		(start 347.187012 -276.056852)
		(end 347.153992 -276.035008)
		(width 0.1143)
		(layer "In13.Cu")
		(net "P5E_CPU0_P0_RX_DP<2>")
	)
	(segment
		(start 299.559218 -377.824238)
		(end 299.559218 -376.741182)
		(width 0.14224)
		(layer "In13.Cu")
		(net "P5E_CPU0_P0_RX_DP<2>")
	)
	(segment
		(start 306.68595 -394.031216)
		(end 306.860194 -393.930632)
		(width 0.14224)
		(layer "In13.Cu")
		(net "P5E_CPU0_P0_RX_DP<2>")
	)
	(segment
		(start 347.156532 -281.85745)
		(end 347.159834 -281.855418)
		(width 0.1143)
		(layer "In13.Cu")
		(net "P5E_CPU0_P0_RX_DP<2>")
	)
	(segment
		(start 307.782214 -373.145304)
		(end 308.339744 -372.587774)
		(width 0.14224)
		(layer "In13.Cu")
		(net "P5E_CPU0_P0_RX_DP<2>")
	)
	(segment
		(start 347.144086 -285.10357)
		(end 347.184472 -285.08325)
		(width 0.1143)
		(layer "In13.Cu")
		(net "P5E_CPU0_P0_RX_DP<2>")
	)
	(segment
		(start 347.183202 -279.291542)
		(end 347.144086 -279.268682)
		(width 0.1143)
		(layer "In13.Cu")
		(net "P5E_CPU0_P0_RX_DP<2>")
	)
	(segment
		(start 347.143578 -277.64867)
		(end 347.114368 -277.631398)
		(width 0.1143)
		(layer "In13.Cu")
		(net "P5E_CPU0_P0_RX_DP<2>")
	)
	(segment
		(start 347.424248 -271.653)
		(end 347.424248 -271.651984)
		(width 0.1143)
		(layer "In13.Cu")
		(net "P5E_CPU0_P0_RX_DP<2>")
	)
	(segment
		(start 358.02189 -372.19636)
		(end 362.344716 -372.19636)
		(width 0.14224)
		(layer "In13.Cu")
		(net "P5E_CPU0_P0_RX_DP<2>")
	)
	(segment
		(start 346.681552 -270.363188)
		(end 346.642436 -270.340074)
		(width 0.1143)
		(layer "In13.Cu")
		(net "P5E_CPU0_P0_RX_DP<2>")
	)
	(segment
		(start 347.161358 -278.612346)
		(end 347.182186 -278.600154)
		(width 0.1143)
		(layer "In13.Cu")
		(net "P5E_CPU0_P0_RX_DP<2>")
	)
	(segment
		(start 346.951046 -295.815512)
		(end 346.951046 -295.14419)
		(width 0.1143)
		(layer "In13.Cu")
		(net "P5E_CPU0_P0_RX_DP<2>")
	)
	(segment
		(start 315.468 -372.54053)
		(end 325.10476 -370.623846)
		(width 0.14224)
		(layer "In13.Cu")
		(net "P5E_CPU0_P0_RX_DP<2>")
	)
	(segment
		(start 347.159834 -281.855418)
		(end 347.16085 -281.85491)
		(width 0.1143)
		(layer "In13.Cu")
		(net "P5E_CPU0_P0_RX_DP<2>")
	)
	(segment
		(start 347.169232 -281.84983)
		(end 347.181424 -281.842718)
		(width 0.1143)
		(layer "In13.Cu")
		(net "P5E_CPU0_P0_RX_DP<2>")
	)
	(segment
		(start 375.122694 -359.598214)
		(end 375.548144 -360.023664)
		(width 0.14224)
		(layer "In13.Cu")
		(net "P5E_CPU0_P0_RX_DP<2>")
	)
	(segment
		(start 347.143324 -283.484066)
		(end 347.144086 -283.483558)
		(width 0.1143)
		(layer "In13.Cu")
		(net "P5E_CPU0_P0_RX_DP<2>")
	)
	(segment
		(start 377.404884 -360.355896)
		(end 377.404884 -355.933756)
		(width 0.14224)
		(layer "In13.Cu")
		(net "P5E_CPU0_P0_RX_DP<2>")
	)
	(segment
		(start 346.956634 -288.66592)
		(end 346.95638 -288.66592)
		(width 0.1143)
		(layer "In13.Cu")
		(net "P5E_CPU0_P0_RX_DP<2>")
	)
	(segment
		(start 347.143324 -285.104078)
		(end 347.144086 -285.10357)
		(width 0.1143)
		(layer "In13.Cu")
		(net "P5E_CPU0_P0_RX_DP<2>")
	)
	(segment
		(start 347.10878 -277.024846)
		(end 347.18117 -276.983444)
		(width 0.1143)
		(layer "In13.Cu")
		(net "P5E_CPU0_P0_RX_DP<2>")
	)
	(segment
		(start 347.15958 -291.57422)
		(end 347.167962 -291.569394)
		(width 0.1143)
		(layer "In13.Cu")
		(net "P5E_CPU0_P0_RX_DP<2>")
	)
	(segment
		(start 347.148658 -282.511754)
		(end 347.114114 -282.491942)
		(width 0.1143)
		(layer "In13.Cu")
		(net "P5E_CPU0_P0_RX_DP<2>")
	)
	(segment
		(start 303.77384 -373.317008)
		(end 307.367686 -373.317008)
		(width 0.14224)
		(layer "In13.Cu")
		(net "P5E_CPU0_P0_RX_DP<2>")
	)
	(segment
		(start 347.115892 -281.882342)
		(end 347.144086 -281.863546)
		(width 0.1143)
		(layer "In13.Cu")
		(net "P5E_CPU0_P0_RX_DP<2>")
	)
	(segment
		(start 346.493338 -270.105886)
		(end 346.563188 -270.036036)
		(width 0.1143)
		(layer "In13.Cu")
		(net "P5E_CPU0_P0_RX_DP<2>")
	)
	(segment
		(start 347.179646 -290.633404)
		(end 347.14434 -290.613084)
		(width 0.1143)
		(layer "In13.Cu")
		(net "P5E_CPU0_P0_RX_DP<2>")
	)
	(segment
		(start 347.117924 -293.22268)
		(end 347.219016 -293.163498)
		(width 0.1143)
		(layer "In13.Cu")
		(net "P5E_CPU0_P0_RX_DP<2>")
	)
	(segment
		(start 347.205808 -291.543994)
		(end 347.207332 -291.542978)
		(width 0.1143)
		(layer "In13.Cu")
		(net "P5E_CPU0_P0_RX_DP<2>")
	)
	(segment
		(start 347.110304 -289.986212)
		(end 347.185488 -289.942778)
		(width 0.1143)
		(layer "In13.Cu")
		(net "P5E_CPU0_P0_RX_DP<2>")
	)
	(segment
		(start 370.361464 -367.399316)
		(end 377.404884 -360.355896)
		(width 0.14224)
		(layer "In13.Cu")
		(net "P5E_CPU0_P0_RX_DP<2>")
	)
	(segment
		(start 377.404884 -355.933756)
		(end 360.846878 -315.947806)
		(width 0.14224)
		(layer "In13.Cu")
		(net "P5E_CPU0_P0_RX_DP<2>")
	)
	(segment
		(start 347.15577 -278.614124)
		(end 347.157548 -278.614632)
		(width 0.1143)
		(layer "In13.Cu")
		(net "P5E_CPU0_P0_RX_DP<2>")
	)
	(segment
		(start 306.590954 -394.385292)
		(end 306.68595 -394.031216)
		(width 0.14224)
		(layer "In13.Cu")
		(net "P5E_CPU0_P0_RX_DP<2>")
	)
	(segment
		(start 347.14815 -283.481272)
		(end 347.164406 -283.471874)
		(width 0.1143)
		(layer "In13.Cu")
		(net "P5E_CPU0_P0_RX_DP<2>")
	)
	(segment
		(start 347.1418 -291.585142)
		(end 347.145864 -291.583364)
		(width 0.1143)
		(layer "In13.Cu")
		(net "P5E_CPU0_P0_RX_DP<2>")
	)
	(segment
		(start 347.180408 -271.186656)
		(end 347.11894 -271.151604)
		(width 0.1143)
		(layer "In13.Cu")
		(net "P5E_CPU0_P0_RX_DP<2>")
	)
	(segment
		(start 347.16085 -281.85491)
		(end 347.164914 -281.85237)
		(width 0.1143)
		(layer "In13.Cu")
		(net "P5E_CPU0_P0_RX_DP<2>")
	)
	(segment
		(start 347.148404 -276.031452)
		(end 347.146626 -276.030436)
		(width 0.1143)
		(layer "In13.Cu")
		(net "P5E_CPU0_P0_RX_DP<2>")
	)
	(segment
		(start 347.146372 -283.482288)
		(end 347.147388 -283.48178)
		(width 0.1143)
		(layer "In13.Cu")
		(net "P5E_CPU0_P0_RX_DP<2>")
	)
	(segment
		(start 306.940204 -392.429746)
		(end 306.940204 -390.101074)
		(width 0.14224)
		(layer "In13.Cu")
		(net "P5E_CPU0_P0_RX_DP<2>")
	)
	(segment
		(start 369.356894 -366.394746)
		(end 369.356894 -366.829594)
		(width 0.14224)
		(layer "In13.Cu")
		(net "P5E_CPU0_P0_RX_DP<2>")
	)
	(segment
		(start 347.110558 -288.363152)
		(end 347.144086 -288.343594)
		(width 0.1143)
		(layer "In13.Cu")
		(net "P5E_CPU0_P0_RX_DP<2>")
	)
	(segment
		(start 347.208856 -292.271958)
		(end 347.208856 -292.271704)
		(width 0.1143)
		(layer "In13.Cu")
		(net "P5E_CPU0_P0_RX_DP<2>")
	)
	(segment
		(start 347.142562 -284.129226)
		(end 347.14053 -284.12821)
		(width 0.1143)
		(layer "In13.Cu")
		(net "P5E_CPU0_P0_RX_DP<2>")
	)
	(segment
		(start 347.613986 -271.978628)
		(end 347.612462 -271.977866)
		(width 0.1143)
		(layer "In13.Cu")
		(net "P5E_CPU0_P0_RX_DP<2>")
	)
	(segment
		(start 347.112336 -285.121858)
		(end 347.143324 -285.104078)
		(width 0.1143)
		(layer "In13.Cu")
		(net "P5E_CPU0_P0_RX_DP<2>")
	)
	(segment
		(start 347.164406 -283.471874)
		(end 347.165168 -283.471366)
		(width 0.1143)
		(layer "In13.Cu")
		(net "P5E_CPU0_P0_RX_DP<2>")
	)
	(segment
		(start 347.114114 -281.883358)
		(end 347.115892 -281.882342)
		(width 0.1143)
		(layer "In13.Cu")
		(net "P5E_CPU0_P0_RX_DP<2>")
	)
	(segment
		(start 347.126814 -273.774916)
		(end 347.144086 -273.763486)
		(width 0.1143)
		(layer "In13.Cu")
		(net "P5E_CPU0_P0_RX_DP<2>")
	)
	(segment
		(start 306.948332 -393.428982)
		(end 306.632356 -393.113006)
		(width 0.14224)
		(layer "In13.Cu")
		(net "P5E_CPU0_P0_RX_DP<2>")
	)
	(segment
		(start 346.95638 -287.049718)
		(end 346.95638 -287.045908)
		(width 0.1143)
		(layer "In13.Cu")
		(net "P5E_CPU0_P0_RX_DP<2>")
	)
	(segment
		(start 347.653102 -272.001488)
		(end 347.613986 -271.978628)
		(width 0.1143)
		(layer "In13.Cu")
		(net "P5E_CPU0_P0_RX_DP<2>")
	)
	(segment
		(start 347.112336 -278.639016)
		(end 347.15577 -278.614124)
		(width 0.1143)
		(layer "In13.Cu")
		(net "P5E_CPU0_P0_RX_DP<2>")
	)
	(segment
		(start 347.424502 -271.652746)
		(end 347.424248 -271.653)
		(width 0.1143)
		(layer "In13.Cu")
		(net "P5E_CPU0_P0_RX_DP<2>")
	)
	(segment
		(start 374.942862 -359.598214)
		(end 375.122694 -359.598214)
		(width 0.14224)
		(layer "In13.Cu")
		(net "P5E_CPU0_P0_RX_DP<2>")
	)
	(segment
		(start 306.948332 -393.842494)
		(end 306.948332 -393.428982)
		(width 0.14224)
		(layer "In13.Cu")
		(net "P5E_CPU0_P0_RX_DP<2>")
	)
	(segment
		(start 347.113352 -279.248108)
		(end 347.112336 -279.2476)
		(width 0.1143)
		(layer "In13.Cu")
		(net "P5E_CPU0_P0_RX_DP<2>")
	)
	(segment
		(start 306.635404 -392.734546)
		(end 306.940204 -392.429746)
		(width 0.14224)
		(layer "In13.Cu")
		(net "P5E_CPU0_P0_RX_DP<2>")
	)
	(segment
		(start 346.996766 -295.861232)
		(end 346.951046 -295.815512)
		(width 0.1143)
		(layer "In13.Cu")
		(net "P5E_CPU0_P0_RX_DP<2>")
	)
	(segment
		(start 347.14053 -284.12821)
		(end 347.111066 -284.111192)
		(width 0.1143)
		(layer "In13.Cu")
		(net "P5E_CPU0_P0_RX_DP<2>")
	)
	(segment
		(start 347.145102 -276.029166)
		(end 347.144086 -276.028658)
		(width 0.1143)
		(layer "In13.Cu")
		(net "P5E_CPU0_P0_RX_DP<2>")
	)
	(segment
		(start 347.144086 -283.483558)
		(end 347.14561 -283.482796)
		(width 0.1143)
		(layer "In13.Cu")
		(net "P5E_CPU0_P0_RX_DP<2>")
	)
	(segment
		(start 347.180408 -274.432776)
		(end 347.179392 -274.432268)
		(width 0.1143)
		(layer "In13.Cu")
		(net "P5E_CPU0_P0_RX_DP<2>")
	)
	(segment
		(start 306.871624 -389.873744)
		(end 302.27397 -382.993646)
		(width 0.14224)
		(layer "In13.Cu")
		(net "P5E_CPU0_P0_RX_DP<2>")
	)
	(segment
		(start 369.926616 -367.399316)
		(end 370.361464 -367.399316)
		(width 0.14224)
		(layer "In13.Cu")
		(net "P5E_CPU0_P0_RX_DP<2>")
	)
	(segment
		(start 301.924212 -381.840486)
		(end 301.924212 -379.972824)
		(width 0.14224)
		(layer "In13.Cu")
		(net "P5E_CPU0_P0_RX_DP<2>")
	)
	(segment
		(start 347.145864 -291.583364)
		(end 347.15958 -291.57422)
		(width 0.1143)
		(layer "In13.Cu")
		(net "P5E_CPU0_P0_RX_DP<2>")
	)
	(segment
		(start 347.16847 -281.850338)
		(end 347.169232 -281.84983)
		(width 0.1143)
		(layer "In13.Cu")
		(net "P5E_CPU0_P0_RX_DP<2>")
	)
	(segment
		(start 347.610938 -272.955258)
		(end 347.653102 -272.93062)
		(width 0.1143)
		(layer "In13.Cu")
		(net "P5E_CPU0_P0_RX_DP<2>")
	)
	(segment
		(start 347.140276 -286.725614)
		(end 347.182948 -286.700722)
		(width 0.1143)
		(layer "In13.Cu")
		(net "P5E_CPU0_P0_RX_DP<2>")
	)
	(segment
		(start 347.165168 -283.471366)
		(end 347.180662 -283.462222)
		(width 0.1143)
		(layer "In13.Cu")
		(net "P5E_CPU0_P0_RX_DP<2>")
	)
	(segment
		(start 347.118686 -280.26106)
		(end 347.15196 -280.238962)
		(width 0.1143)
		(layer "In13.Cu")
		(net "P5E_CPU0_P0_RX_DP<2>")
	)
	(segment
		(start 347.143832 -280.888694)
		(end 347.109796 -280.871422)
		(width 0.1143)
		(layer "In13.Cu")
		(net "P5E_CPU0_P0_RX_DP<2>")
	)
	(segment
		(start 347.158564 -278.614124)
		(end 347.161358 -278.612346)
		(width 0.1143)
		(layer "In13.Cu")
		(net "P5E_CPU0_P0_RX_DP<2>")
	)
	(segment
		(start 301.574708 -379.318774)
		(end 299.682154 -378.054108)
		(width 0.14224)
		(layer "In13.Cu")
		(net "P5E_CPU0_P0_RX_DP<2>")
	)
	(arc
		(start 347.183202 -294.800528)
		(mid 347.205056 -294.784657)
		(end 347.226128 -294.767762)
		(width 0.1143)
		(layer "In13.Cu")
		(net "P5E_CPU0_P0_RX_DP<2>")
	)
	(arc
		(start 347.425264 -273.278854)
		(mid 347.474899 -273.092246)
		(end 347.610938 -272.955258)
		(width 0.1143)
		(layer "In13.Cu")
		(net "P5E_CPU0_P0_RX_DP<2>")
	)
	(arc
		(start 347.11894 -271.151604)
		(mid 347.002079 -271.017839)
		(end 346.959936 -270.84528)
		(width 0.1143)
		(layer "In13.Cu")
		(net "P5E_CPU0_P0_RX_DP<2>")
	)
	(arc
		(start 347.109796 -280.871422)
		(mid 346.956805 -280.563954)
		(end 347.118686 -280.26106)
		(width 0.1143)
		(layer "In13.Cu")
		(net "P5E_CPU0_P0_RX_DP<2>")
	)
	(arc
		(start 347.115892 -274.38985)
		(mid 346.959964 -274.085558)
		(end 347.115892 -273.781266)
		(width 0.1143)
		(layer "In13.Cu")
		(net "P5E_CPU0_P0_RX_DP<2>")
	)
	(arc
		(start 347.25102 -293.133526)
		(mid 347.42897 -292.696794)
		(end 347.213936 -292.277038)
		(width 0.1143)
		(layer "In13.Cu")
		(net "P5E_CPU0_P0_RX_DP<2>")
	)
	(arc
		(start 306.940204 -390.101074)
		(mid 306.922751 -389.982332)
		(end 306.871624 -389.873744)
		(width 0.14224)
		(layer "In13.Cu")
		(net "P5E_CPU0_P0_RX_DP<2>")
	)
	(arc
		(start 346.642436 -270.340074)
		(mid 346.611589 -270.315335)
		(end 346.583508 -270.287496)
		(width 0.1143)
		(layer "In13.Cu")
		(net "P5E_CPU0_P0_RX_DP<2>")
	)
	(arc
		(start 347.112336 -285.730442)
		(mid 346.956408 -285.42615)
		(end 347.112336 -285.121858)
		(width 0.1143)
		(layer "In13.Cu")
		(net "P5E_CPU0_P0_RX_DP<2>")
	)
	(arc
		(start 347.111066 -284.111192)
		(mid 346.956136 -283.788781)
		(end 347.143324 -283.484066)
		(width 0.1143)
		(layer "In13.Cu")
		(net "P5E_CPU0_P0_RX_DP<2>")
	)
	(arc
		(start 347.114114 -282.491942)
		(mid 346.958186 -282.18765)
		(end 347.114114 -281.883358)
		(width 0.1143)
		(layer "In13.Cu")
		(net "P5E_CPU0_P0_RX_DP<2>")
	)
	(arc
		(start 347.182948 -278.599646)
		(mid 347.192416 -278.593012)
		(end 347.201744 -278.586184)
		(width 0.1143)
		(layer "In13.Cu")
		(net "P5E_CPU0_P0_RX_DP<2>")
	)
	(arc
		(start 347.201744 -278.586184)
		(mid 347.426266 -278.123519)
		(end 347.182948 -277.670514)
		(width 0.1143)
		(layer "In13.Cu")
		(net "P5E_CPU0_P0_RX_DP<2>")
	)
	(arc
		(start 302.27397 -382.993646)
		(mid 302.01352 -382.443014)
		(end 301.924212 -381.840486)
		(width 0.14224)
		(layer "In13.Cu")
		(net "P5E_CPU0_P0_RX_DP<2>")
	)
	(arc
		(start 347.168724 -291.568886)
		(mid 347.18769 -291.557072)
		(end 347.205808 -291.543994)
		(width 0.1143)
		(layer "In13.Cu")
		(net "P5E_CPU0_P0_RX_DP<2>")
	)
	(arc
		(start 347.148658 -288.341054)
		(mid 347.35228 -288.135649)
		(end 347.426788 -287.856168)
		(width 0.1143)
		(layer "In13.Cu")
		(net "P5E_CPU0_P0_RX_DP<2>")
	)
	(arc
		(start 347.608398 -271.975326)
		(mid 347.473723 -271.83841)
		(end 347.424502 -271.652746)
		(width 0.1143)
		(layer "In13.Cu")
		(net "P5E_CPU0_P0_RX_DP<2>")
	)
	(arc
		(start 347.18117 -276.983444)
		(mid 347.425331 -276.521674)
		(end 347.187012 -276.056852)
		(width 0.1143)
		(layer "In13.Cu")
		(net "P5E_CPU0_P0_RX_DP<2>")
	)
	(arc
		(start 325.10476 -370.623846)
		(mid 325.968099 -370.495769)
		(end 326.839834 -370.452904)
		(width 0.14224)
		(layer "In13.Cu")
		(net "P5E_CPU0_P0_RX_DP<2>")
	)
	(arc
		(start 347.180154 -280.222706)
		(mid 347.181678 -280.221691)
		(end 347.183202 -280.220674)
		(width 0.1143)
		(layer "In13.Cu")
		(net "P5E_CPU0_P0_RX_DP<2>")
	)
	(arc
		(start 347.181424 -281.842718)
		(mid 347.185246 -281.83994)
		(end 347.189044 -281.83713)
		(width 0.1143)
		(layer "In13.Cu")
		(net "P5E_CPU0_P0_RX_DP<2>")
	)
	(arc
		(start 347.180408 -275.361908)
		(mid 347.423735 -274.897342)
		(end 347.180408 -274.432776)
		(width 0.1143)
		(layer "In13.Cu")
		(net "P5E_CPU0_P0_RX_DP<2>")
	)
	(arc
		(start 346.583508 -270.287496)
		(mid 346.525889 -270.202912)
		(end 346.493338 -270.105886)
		(width 0.1143)
		(layer "In13.Cu")
		(net "P5E_CPU0_P0_RX_DP<2>")
	)
	(arc
		(start 331.659992 -370.452904)
		(mid 340.307922 -370.664811)
		(end 348.93504 -371.300756)
		(width 0.14224)
		(layer "In13.Cu")
		(net "P5E_CPU0_P0_RX_DP<2>")
	)
	(arc
		(start 347.11132 -287.351978)
		(mid 346.997391 -287.219541)
		(end 346.95638 -287.049718)
		(width 0.1143)
		(layer "In13.Cu")
		(net "P5E_CPU0_P0_RX_DP<2>")
	)
	(arc
		(start 347.11767 -293.833042)
		(mid 346.960379 -293.527811)
		(end 347.117924 -293.22268)
		(width 0.1143)
		(layer "In13.Cu")
		(net "P5E_CPU0_P0_RX_DP<2>")
	)
	(arc
		(start 346.959936 -270.84528)
		(mid 346.885333 -270.566946)
		(end 346.681552 -270.363188)
		(width 0.1143)
		(layer "In13.Cu")
		(net "P5E_CPU0_P0_RX_DP<2>")
	)
	(arc
		(start 307.367686 -373.317008)
		(mid 307.592027 -373.272384)
		(end 307.782214 -373.145304)
		(width 0.14224)
		(layer "In13.Cu")
		(net "P5E_CPU0_P0_RX_DP<2>")
	)
	(arc
		(start 347.26499 -299.397674)
		(mid 347.065793 -299.045788)
		(end 346.996766 -298.647358)
		(width 0.14224)
		(layer "In13.Cu")
		(net "P5E_CPU0_P0_RX_DP<2>")
	)
	(arc
		(start 347.181932 -273.744436)
		(mid 347.360745 -273.542086)
		(end 347.425264 -273.27987)
		(width 0.1143)
		(layer "In13.Cu")
		(net "P5E_CPU0_P0_RX_DP<2>")
	)
	(arc
		(start 347.226128 -294.767762)
		(mid 347.425973 -294.308959)
		(end 347.183202 -293.871396)
		(width 0.1143)
		(layer "In13.Cu")
		(net "P5E_CPU0_P0_RX_DP<2>")
	)
	(arc
		(start 347.14434 -290.613084)
		(mid 346.958553 -290.308828)
		(end 347.11005 -289.986212)
		(width 0.1143)
		(layer "In13.Cu")
		(net "P5E_CPU0_P0_RX_DP<2>")
	)
	(arc
		(start 347.112336 -279.2476)
		(mid 346.956408 -278.943308)
		(end 347.112336 -278.639016)
		(width 0.1143)
		(layer "In13.Cu")
		(net "P5E_CPU0_P0_RX_DP<2>")
	)
	(arc
		(start 347.182948 -286.700722)
		(mid 347.426275 -286.236156)
		(end 347.182948 -285.77159)
		(width 0.1143)
		(layer "In13.Cu")
		(net "P5E_CPU0_P0_RX_DP<2>")
	)
	(arc
		(start 346.95638 -287.045908)
		(mid 347.005626 -286.861247)
		(end 347.140276 -286.725614)
		(width 0.1143)
		(layer "In13.Cu")
		(net "P5E_CPU0_P0_RX_DP<2>")
	)
	(arc
		(start 347.112336 -276.01037)
		(mid 346.956408 -275.706078)
		(end 347.112336 -275.401786)
		(width 0.1143)
		(layer "In13.Cu")
		(net "P5E_CPU0_P0_RX_DP<2>")
	)
	(arc
		(start 346.95638 -288.66592)
		(mid 346.997142 -288.496036)
		(end 347.110558 -288.363152)
		(width 0.1143)
		(layer "In13.Cu")
		(net "P5E_CPU0_P0_RX_DP<2>")
	)
	(arc
		(start 299.559218 -376.741182)
		(mid 299.582845 -376.622402)
		(end 299.65015 -376.521726)
		(width 0.14224)
		(layer "In13.Cu")
		(net "P5E_CPU0_P0_RX_DP<2>")
	)
	(arc
		(start 347.184472 -285.08325)
		(mid 347.427799 -284.618684)
		(end 347.184472 -284.154118)
		(width 0.1143)
		(layer "In13.Cu")
		(net "P5E_CPU0_P0_RX_DP<2>")
	)
	(arc
		(start 347.180662 -283.462222)
		(mid 347.423989 -282.997656)
		(end 347.180662 -282.53309)
		(width 0.1143)
		(layer "In13.Cu")
		(net "P5E_CPU0_P0_RX_DP<2>")
	)
	(arc
		(start 347.114368 -288.971228)
		(mid 346.998489 -288.837714)
		(end 346.956634 -288.66592)
		(width 0.1143)
		(layer "In13.Cu")
		(net "P5E_CPU0_P0_RX_DP<2>")
	)
	(arc
		(start 347.183202 -280.220674)
		(mid 347.426529 -279.756108)
		(end 347.183202 -279.291542)
		(width 0.1143)
		(layer "In13.Cu")
		(net "P5E_CPU0_P0_RX_DP<2>")
	)
	(arc
		(start 308.339744 -372.587774)
		(mid 308.392069 -372.552812)
		(end 308.45379 -372.54053)
		(width 0.14224)
		(layer "In13.Cu")
		(net "P5E_CPU0_P0_RX_DP<2>")
	)
	(arc
		(start 347.424248 -271.651984)
		(mid 347.359648 -271.389285)
		(end 347.180408 -271.186656)
		(width 0.1143)
		(layer "In13.Cu")
		(net "P5E_CPU0_P0_RX_DP<2>")
	)
	(arc
		(start 302.204882 -373.966994)
		(mid 302.924712 -373.485956)
		(end 303.77384 -373.317008)
		(width 0.14224)
		(layer "In13.Cu")
		(net "P5E_CPU0_P0_RX_DP<2>")
	)
	(arc
		(start 347.653102 -272.93062)
		(mid 347.896429 -272.466054)
		(end 347.653102 -272.001488)
		(width 0.1143)
		(layer "In13.Cu")
		(net "P5E_CPU0_P0_RX_DP<2>")
	)
	(arc
		(start 347.189044 -281.83713)
		(mid 347.424557 -281.373678)
		(end 347.181678 -280.914094)
		(width 0.1143)
		(layer "In13.Cu")
		(net "P5E_CPU0_P0_RX_DP<2>")
	)
	(arc
		(start 347.207332 -291.542978)
		(mid 347.423112 -291.081233)
		(end 347.179646 -290.633404)
		(width 0.1143)
		(layer "In13.Cu")
		(net "P5E_CPU0_P0_RX_DP<2>")
	)
	(arc
		(start 301.924212 -379.972824)
		(mid 301.831349 -379.602046)
		(end 301.574708 -379.318774)
		(width 0.14224)
		(layer "In13.Cu")
		(net "P5E_CPU0_P0_RX_DP<2>")
	)
	(arc
		(start 347.185488 -289.942778)
		(mid 347.429342 -289.477704)
		(end 347.185488 -289.01263)
		(width 0.1143)
		(layer "In13.Cu")
		(net "P5E_CPU0_P0_RX_DP<2>")
	)
	(arc
		(start 347.114368 -277.631398)
		(mid 346.956791 -277.330637)
		(end 347.107002 -277.026116)
		(width 0.1143)
		(layer "In13.Cu")
		(net "P5E_CPU0_P0_RX_DP<2>")
	)
	(arc
		(start 346.951046 -295.14419)
		(mid 346.992301 -294.973219)
		(end 347.107002 -294.839898)
		(width 0.1143)
		(layer "In13.Cu")
		(net "P5E_CPU0_P0_RX_DP<2>")
	)
	(arc
		(start 347.126814 -292.209728)
		(mid 346.964879 -291.903941)
		(end 347.122496 -291.59581)
		(width 0.1143)
		(layer "In13.Cu")
		(net "P5E_CPU0_P0_RX_DP<2>")
	)
	(arc
		(start 347.426788 -287.856168)
		(mid 347.362093 -287.594734)
		(end 347.182948 -287.393634)
		(width 0.1143)
		(layer "In13.Cu")
		(net "P5E_CPU0_P0_RX_DP<2>")
	)
	(arc
		(start 299.682154 -378.054108)
		(mid 299.591874 -377.95458)
		(end 299.559218 -377.824238)
		(width 0.14224)
		(layer "In13.Cu")
		(net "P5E_CPU0_P0_RX_DP<2>")
	)
	(segment
		(start 347.327982 -273.010122)
		(end 346.86113 -273.27606)
		(width 0.12954)
		(layer "F.Cu")
		(net "P5E_CPU0_P0_RX_DP<1>")
	)
	(segment
		(start 304.870358 -394.385292)
		(end 305.391058 -394.385292)
		(width 0.127)
		(layer "F.Cu")
		(net "P5E_CPU0_P0_RX_DP<1>")
	)
	(segment
		(start 346.243148 -293.871142)
		(end 346.173552 -293.830756)
		(width 0.1143)
		(layer "In13.Cu")
		(net "P5E_CPU0_P0_RX_DP<1>")
	)
	(segment
		(start 346.171266 -288.36239)
		(end 346.243148 -288.320988)
		(width 0.1143)
		(layer "In13.Cu")
		(net "P5E_CPU0_P0_RX_DP<1>")
	)
	(segment
		(start 298.376594 -376.168412)
		(end 299.372528 -375.172478)
		(width 0.14224)
		(layer "In13.Cu")
		(net "P5E_CPU0_P0_RX_DP<1>")
	)
	(segment
		(start 346.563188 -273.27606)
		(end 346.86113 -273.27606)
		(width 0.1143)
		(layer "In13.Cu")
		(net "P5E_CPU0_P0_RX_DP<1>")
	)
	(segment
		(start 305.660298 -393.930632)
		(end 305.748436 -393.842494)
		(width 0.14224)
		(layer "In13.Cu")
		(net "P5E_CPU0_P0_RX_DP<1>")
	)
	(segment
		(start 346.243148 -284.151578)
		(end 346.173552 -284.110938)
		(width 0.1143)
		(layer "In13.Cu")
		(net "P5E_CPU0_P0_RX_DP<1>")
	)
	(segment
		(start 297.777154 -379.368304)
		(end 297.914314 -379.231144)
		(width 0.14224)
		(layer "In13.Cu")
		(net "P5E_CPU0_P0_RX_DP<1>")
	)
	(segment
		(start 346.173552 -278.641302)
		(end 346.243148 -278.600662)
		(width 0.1143)
		(layer "In13.Cu")
		(net "P5E_CPU0_P0_RX_DP<1>")
	)
	(segment
		(start 346.173552 -294.841168)
		(end 346.243148 -294.800528)
		(width 0.1143)
		(layer "In13.Cu")
		(net "P5E_CPU0_P0_RX_DP<1>")
	)
	(segment
		(start 346.243148 -285.77159)
		(end 346.173552 -285.73095)
		(width 0.1143)
		(layer "In13.Cu")
		(net "P5E_CPU0_P0_RX_DP<1>")
	)
	(segment
		(start 346.173806 -286.740854)
		(end 346.243148 -286.700722)
		(width 0.1143)
		(layer "In13.Cu")
		(net "P5E_CPU0_P0_RX_DP<1>")
	)
	(segment
		(start 315.359542 -371.60581)
		(end 324.886574 -369.71097)
		(width 0.14224)
		(layer "In13.Cu")
		(net "P5E_CPU0_P0_RX_DP<1>")
	)
	(segment
		(start 305.435508 -392.7348)
		(end 305.740308 -392.43)
		(width 0.14224)
		(layer "In13.Cu")
		(net "P5E_CPU0_P0_RX_DP<1>")
	)
	(segment
		(start 299.372528 -375.172478)
		(end 299.566584 -375.172478)
		(width 0.14224)
		(layer "In13.Cu")
		(net "P5E_CPU0_P0_RX_DP<1>")
	)
	(segment
		(start 300.524926 -374.019826)
		(end 300.718982 -374.019826)
		(width 0.14224)
		(layer "In13.Cu")
		(net "P5E_CPU0_P0_RX_DP<1>")
	)
	(segment
		(start 305.43246 -393.113006)
		(end 305.435508 -392.7348)
		(width 0.14224)
		(layer "In13.Cu")
		(net "P5E_CPU0_P0_RX_DP<1>")
	)
	(segment
		(start 362.945934 -367.995454)
		(end 362.54182 -367.59134)
		(width 0.14224)
		(layer "In13.Cu")
		(net "P5E_CPU0_P0_RX_DP<1>")
	)
	(segment
		(start 297.914314 -378.103384)
		(end 297.914314 -377.676664)
		(width 0.14224)
		(layer "In13.Cu")
		(net "P5E_CPU0_P0_RX_DP<1>")
	)
	(segment
		(start 308.014116 -371.60581)
		(end 315.359542 -371.60581)
		(width 0.14224)
		(layer "In13.Cu")
		(net "P5E_CPU0_P0_RX_DP<1>")
	)
	(segment
		(start 346.243148 -274.431506)
		(end 346.173552 -274.390866)
		(width 0.1143)
		(layer "In13.Cu")
		(net "P5E_CPU0_P0_RX_DP<1>")
	)
	(segment
		(start 297.777154 -382.048512)
		(end 297.777154 -379.368304)
		(width 0.14224)
		(layer "In13.Cu")
		(net "P5E_CPU0_P0_RX_DP<1>")
	)
	(segment
		(start 299.86859 -374.870472)
		(end 299.86859 -374.676162)
		(width 0.14224)
		(layer "In13.Cu")
		(net "P5E_CPU0_P0_RX_DP<1>")
	)
	(segment
		(start 302.843184 -372.340124)
		(end 307.213 -372.340124)
		(width 0.14224)
		(layer "In13.Cu")
		(net "P5E_CPU0_P0_RX_DP<1>")
	)
	(segment
		(start 359.992168 -316.562486)
		(end 346.450666 -300.062138)
		(width 0.14224)
		(layer "In13.Cu")
		(net "P5E_CPU0_P0_RX_DP<1>")
	)
	(segment
		(start 346.243148 -277.67153)
		(end 346.173552 -277.63089)
		(width 0.1143)
		(layer "In13.Cu")
		(net "P5E_CPU0_P0_RX_DP<1>")
	)
	(segment
		(start 346.243148 -290.631118)
		(end 346.173552 -290.590732)
		(width 0.1143)
		(layer "In13.Cu")
		(net "P5E_CPU0_P0_RX_DP<1>")
	)
	(segment
		(start 374.75541 -355.176582)
		(end 374.81256 -355.038914)
		(width 0.14224)
		(layer "In13.Cu")
		(net "P5E_CPU0_P0_RX_DP<1>")
	)
	(segment
		(start 358.444546 -370.944394)
		(end 362.207302 -370.944394)
		(width 0.14224)
		(layer "In13.Cu")
		(net "P5E_CPU0_P0_RX_DP<1>")
	)
	(segment
		(start 305.748436 -393.428982)
		(end 305.43246 -393.113006)
		(width 0.14224)
		(layer "In13.Cu")
		(net "P5E_CPU0_P0_RX_DP<1>")
	)
	(segment
		(start 346.243148 -279.291542)
		(end 346.173552 -279.250902)
		(width 0.1143)
		(layer "In13.Cu")
		(net "P5E_CPU0_P0_RX_DP<1>")
	)
	(segment
		(start 346.243148 -276.051518)
		(end 346.173552 -276.010878)
		(width 0.1143)
		(layer "In13.Cu")
		(net "P5E_CPU0_P0_RX_DP<1>")
	)
	(segment
		(start 346.173552 -291.601144)
		(end 346.243148 -291.560504)
		(width 0.1143)
		(layer "In13.Cu")
		(net "P5E_CPU0_P0_RX_DP<1>")
	)
	(segment
		(start 297.777154 -377.539504)
		(end 297.777154 -377.09475)
		(width 0.14224)
		(layer "In13.Cu")
		(net "P5E_CPU0_P0_RX_DP<1>")
	)
	(segment
		(start 298.37634 -376.168412)
		(end 298.376594 -376.168412)
		(width 0.14224)
		(layer "In13.Cu")
		(net "P5E_CPU0_P0_RX_DP<1>")
	)
	(segment
		(start 346.062046 -295.689528)
		(end 346.062046 -295.67505)
		(width 0.1143)
		(layer "In13.Cu")
		(net "P5E_CPU0_P0_RX_DP<1>")
	)
	(segment
		(start 346.173552 -293.221156)
		(end 346.243148 -293.180516)
		(width 0.1143)
		(layer "In13.Cu")
		(net "P5E_CPU0_P0_RX_DP<1>")
	)
	(segment
		(start 346.243148 -289.011106)
		(end 346.173552 -288.97072)
		(width 0.1143)
		(layer "In13.Cu")
		(net "P5E_CPU0_P0_RX_DP<1>")
	)
	(segment
		(start 372.79453 -359.922064)
		(end 372.224808 -359.352342)
		(width 0.14224)
		(layer "In13.Cu")
		(net "P5E_CPU0_P0_RX_DP<1>")
	)
	(segment
		(start 307.213 -372.340124)
		(end 307.90007 -371.653054)
		(width 0.14224)
		(layer "In13.Cu")
		(net "P5E_CPU0_P0_RX_DP<1>")
	)
	(segment
		(start 305.748436 -393.842494)
		(end 305.748436 -393.428982)
		(width 0.14224)
		(layer "In13.Cu")
		(net "P5E_CPU0_P0_RX_DP<1>")
	)
	(segment
		(start 346.17279 -286.74187)
		(end 346.173806 -286.741108)
		(width 0.1143)
		(layer "In13.Cu")
		(net "P5E_CPU0_P0_RX_DP<1>")
	)
	(segment
		(start 299.566584 -375.172478)
		(end 299.86859 -374.870472)
		(width 0.14224)
		(layer "In13.Cu")
		(net "P5E_CPU0_P0_RX_DP<1>")
	)
	(segment
		(start 346.173552 -289.981132)
		(end 346.243148 -289.940492)
		(width 0.1143)
		(layer "In13.Cu")
		(net "P5E_CPU0_P0_RX_DP<1>")
	)
	(segment
		(start 301.020988 -373.523764)
		(end 301.753016 -372.791736)
		(width 0.14224)
		(layer "In13.Cu")
		(net "P5E_CPU0_P0_RX_DP<1>")
	)
	(segment
		(start 352.384106 -370.383308)
		(end 358.444546 -370.944394)
		(width 0.14224)
		(layer "In13.Cu")
		(net "P5E_CPU0_P0_RX_DP<1>")
	)
	(segment
		(start 297.777154 -378.667264)
		(end 297.777154 -378.240544)
		(width 0.14224)
		(layer "In13.Cu")
		(net "P5E_CPU0_P0_RX_DP<1>")
	)
	(segment
		(start 305.610514 -390.045448)
		(end 297.893232 -382.328166)
		(width 0.14224)
		(layer "In13.Cu")
		(net "P5E_CPU0_P0_RX_DP<1>")
	)
	(segment
		(start 346.173552 -285.12135)
		(end 346.243148 -285.08071)
		(width 0.1143)
		(layer "In13.Cu")
		(net "P5E_CPU0_P0_RX_DP<1>")
	)
	(segment
		(start 298.008802 -376.53595)
		(end 298.37634 -376.168412)
		(width 0.14224)
		(layer "In13.Cu")
		(net "P5E_CPU0_P0_RX_DP<1>")
	)
	(segment
		(start 362.207302 -370.944394)
		(end 372.79453 -360.357166)
		(width 0.14224)
		(layer "In13.Cu")
		(net "P5E_CPU0_P0_RX_DP<1>")
	)
	(segment
		(start 346.062046 -298.975526)
		(end 346.062046 -295.689528)
		(width 0.14224)
		(layer "In13.Cu")
		(net "P5E_CPU0_P0_RX_DP<1>")
	)
	(segment
		(start 346.243148 -282.531566)
		(end 346.173552 -282.490926)
		(width 0.1143)
		(layer "In13.Cu")
		(net "P5E_CPU0_P0_RX_DP<1>")
	)
	(segment
		(start 346.173552 -283.501338)
		(end 346.243148 -283.460698)
		(width 0.1143)
		(layer "In13.Cu")
		(net "P5E_CPU0_P0_RX_DP<1>")
	)
	(segment
		(start 297.914314 -379.231144)
		(end 297.914314 -378.804424)
		(width 0.14224)
		(layer "In13.Cu")
		(net "P5E_CPU0_P0_RX_DP<1>")
	)
	(segment
		(start 346.480384 -273.358864)
		(end 346.563188 -273.27606)
		(width 0.1143)
		(layer "In13.Cu")
		(net "P5E_CPU0_P0_RX_DP<1>")
	)
	(segment
		(start 346.173552 -277.02129)
		(end 346.243148 -276.98065)
		(width 0.1143)
		(layer "In13.Cu")
		(net "P5E_CPU0_P0_RX_DP<1>")
	)
	(segment
		(start 346.173552 -273.781266)
		(end 346.243148 -273.740626)
		(width 0.1143)
		(layer "In13.Cu")
		(net "P5E_CPU0_P0_RX_DP<1>")
	)
	(segment
		(start 297.914314 -377.676664)
		(end 297.777154 -377.539504)
		(width 0.14224)
		(layer "In13.Cu")
		(net "P5E_CPU0_P0_RX_DP<1>")
	)
	(segment
		(start 297.777154 -378.240544)
		(end 297.914314 -378.103384)
		(width 0.14224)
		(layer "In13.Cu")
		(net "P5E_CPU0_P0_RX_DP<1>")
	)
	(segment
		(start 305.486054 -394.031216)
		(end 305.660298 -393.930632)
		(width 0.14224)
		(layer "In13.Cu")
		(net "P5E_CPU0_P0_RX_DP<1>")
	)
	(segment
		(start 346.168726 -286.74441)
		(end 346.17279 -286.74187)
		(width 0.1143)
		(layer "In13.Cu")
		(net "P5E_CPU0_P0_RX_DP<1>")
	)
	(segment
		(start 305.740308 -392.43)
		(end 305.740308 -390.358884)
		(width 0.14224)
		(layer "In13.Cu")
		(net "P5E_CPU0_P0_RX_DP<1>")
	)
	(segment
		(start 346.243148 -292.25113)
		(end 346.173552 -292.210744)
		(width 0.1143)
		(layer "In13.Cu")
		(net "P5E_CPU0_P0_RX_DP<1>")
	)
	(segment
		(start 346.173552 -275.401278)
		(end 346.243148 -275.360638)
		(width 0.1143)
		(layer "In13.Cu")
		(net "P5E_CPU0_P0_RX_DP<1>")
	)
	(segment
		(start 362.54182 -367.59134)
		(end 362.54182 -367.390172)
		(width 0.14224)
		(layer "In13.Cu")
		(net "P5E_CPU0_P0_RX_DP<1>")
	)
	(segment
		(start 346.173806 -286.741108)
		(end 346.173806 -286.740854)
		(width 0.1143)
		(layer "In13.Cu")
		(net "P5E_CPU0_P0_RX_DP<1>")
	)
	(segment
		(start 346.062046 -295.67505)
		(end 346.016326 -295.62933)
		(width 0.1143)
		(layer "In13.Cu")
		(net "P5E_CPU0_P0_RX_DP<1>")
	)
	(segment
		(start 346.243148 -280.911554)
		(end 346.173552 -280.870914)
		(width 0.1143)
		(layer "In13.Cu")
		(net "P5E_CPU0_P0_RX_DP<1>")
	)
	(segment
		(start 374.81256 -355.038914)
		(end 374.81256 -352.267774)
		(width 0.14224)
		(layer "In13.Cu")
		(net "P5E_CPU0_P0_RX_DP<1>")
	)
	(segment
		(start 346.016326 -295.62933)
		(end 346.016326 -295.145714)
		(width 0.1143)
		(layer "In13.Cu")
		(net "P5E_CPU0_P0_RX_DP<1>")
	)
	(segment
		(start 362.54182 -367.390172)
		(end 374.75541 -355.176582)
		(width 0.14224)
		(layer "In13.Cu")
		(net "P5E_CPU0_P0_RX_DP<1>")
	)
	(segment
		(start 327.365106 -369.466876)
		(end 332.545436 -369.466876)
		(width 0.14224)
		(layer "In13.Cu")
		(net "P5E_CPU0_P0_RX_DP<1>")
	)
	(segment
		(start 346.173552 -281.881326)
		(end 346.243148 -281.840686)
		(width 0.1143)
		(layer "In13.Cu")
		(net "P5E_CPU0_P0_RX_DP<1>")
	)
	(segment
		(start 374.81256 -352.267774)
		(end 360.094022 -316.735206)
		(width 0.14224)
		(layer "In13.Cu")
		(net "P5E_CPU0_P0_RX_DP<1>")
	)
	(segment
		(start 299.86859 -374.676162)
		(end 300.524926 -374.019826)
		(width 0.14224)
		(layer "In13.Cu")
		(net "P5E_CPU0_P0_RX_DP<1>")
	)
	(segment
		(start 300.718982 -374.019826)
		(end 301.020988 -373.71782)
		(width 0.14224)
		(layer "In13.Cu")
		(net "P5E_CPU0_P0_RX_DP<1>")
	)
	(segment
		(start 363.147102 -367.995454)
		(end 362.945934 -367.995454)
		(width 0.14224)
		(layer "In13.Cu")
		(net "P5E_CPU0_P0_RX_DP<1>")
	)
	(segment
		(start 372.79453 -360.357166)
		(end 372.79453 -359.922064)
		(width 0.14224)
		(layer "In13.Cu")
		(net "P5E_CPU0_P0_RX_DP<1>")
	)
	(segment
		(start 297.914314 -378.804424)
		(end 297.777154 -378.667264)
		(width 0.14224)
		(layer "In13.Cu")
		(net "P5E_CPU0_P0_RX_DP<1>")
	)
	(segment
		(start 372.224808 -359.352342)
		(end 371.790214 -359.352342)
		(width 0.14224)
		(layer "In13.Cu")
		(net "P5E_CPU0_P0_RX_DP<1>")
	)
	(segment
		(start 346.240608 -287.38957)
		(end 346.173298 -287.350708)
		(width 0.1143)
		(layer "In13.Cu")
		(net "P5E_CPU0_P0_RX_DP<1>")
	)
	(segment
		(start 346.173552 -280.261314)
		(end 346.243148 -280.220674)
		(width 0.1143)
		(layer "In13.Cu")
		(net "P5E_CPU0_P0_RX_DP<1>")
	)
	(segment
		(start 371.790214 -359.352342)
		(end 363.147102 -367.995454)
		(width 0.14224)
		(layer "In13.Cu")
		(net "P5E_CPU0_P0_RX_DP<1>")
	)
	(segment
		(start 305.391058 -394.385292)
		(end 305.486054 -394.031216)
		(width 0.14224)
		(layer "In13.Cu")
		(net "P5E_CPU0_P0_RX_DP<1>")
	)
	(segment
		(start 301.020988 -373.71782)
		(end 301.020988 -373.523764)
		(width 0.14224)
		(layer "In13.Cu")
		(net "P5E_CPU0_P0_RX_DP<1>")
	)
	(segment
		(start 359.993692 -316.564264)
		(end 359.992168 -316.562486)
		(width 0.14224)
		(layer "In13.Cu")
		(net "P5E_CPU0_P0_RX_DP<1>")
	)
	(arc
		(start 346.173552 -288.97072)
		(mid 346.058292 -288.837301)
		(end 346.016834 -288.66592)
		(width 0.1143)
		(layer "In13.Cu")
		(net "P5E_CPU0_P0_RX_DP<1>")
	)
	(arc
		(start 346.173298 -287.350708)
		(mid 346.058113 -287.217264)
		(end 346.016834 -287.045908)
		(width 0.1143)
		(layer "In13.Cu")
		(net "P5E_CPU0_P0_RX_DP<1>")
	)
	(arc
		(start 332.545436 -369.466876)
		(mid 342.475351 -369.696065)
		(end 352.384106 -370.383308)
		(width 0.14224)
		(layer "In13.Cu")
		(net "P5E_CPU0_P0_RX_DP<1>")
	)
	(arc
		(start 346.450666 -300.062138)
		(mid 346.162081 -299.552549)
		(end 346.062046 -298.975526)
		(width 0.14224)
		(layer "In13.Cu")
		(net "P5E_CPU0_P0_RX_DP<1>")
	)
	(arc
		(start 346.173552 -284.110938)
		(mid 346.016575 -283.806138)
		(end 346.173552 -283.501338)
		(width 0.1143)
		(layer "In13.Cu")
		(net "P5E_CPU0_P0_RX_DP<1>")
	)
	(arc
		(start 346.016326 -295.145714)
		(mid 346.058073 -294.974417)
		(end 346.173552 -294.841168)
		(width 0.1143)
		(layer "In13.Cu")
		(net "P5E_CPU0_P0_RX_DP<1>")
	)
	(arc
		(start 346.243148 -286.700722)
		(mid 346.486475 -286.236156)
		(end 346.243148 -285.77159)
		(width 0.1143)
		(layer "In13.Cu")
		(net "P5E_CPU0_P0_RX_DP<1>")
	)
	(arc
		(start 297.777154 -377.09475)
		(mid 297.837368 -376.792301)
		(end 298.008802 -376.53595)
		(width 0.14224)
		(layer "In13.Cu")
		(net "P5E_CPU0_P0_RX_DP<1>")
	)
	(arc
		(start 346.243148 -291.560504)
		(mid 346.486584 -291.095866)
		(end 346.243148 -290.631118)
		(width 0.1143)
		(layer "In13.Cu")
		(net "P5E_CPU0_P0_RX_DP<1>")
	)
	(arc
		(start 346.243148 -276.98065)
		(mid 346.486475 -276.516084)
		(end 346.243148 -276.051518)
		(width 0.1143)
		(layer "In13.Cu")
		(net "P5E_CPU0_P0_RX_DP<1>")
	)
	(arc
		(start 346.016834 -287.045908)
		(mid 346.056881 -286.877061)
		(end 346.168726 -286.74441)
		(width 0.1143)
		(layer "In13.Cu")
		(net "P5E_CPU0_P0_RX_DP<1>")
	)
	(arc
		(start 346.173552 -277.63089)
		(mid 346.016575 -277.32609)
		(end 346.173552 -277.02129)
		(width 0.1143)
		(layer "In13.Cu")
		(net "P5E_CPU0_P0_RX_DP<1>")
	)
	(arc
		(start 346.243148 -289.940492)
		(mid 346.486584 -289.475854)
		(end 346.243148 -289.011106)
		(width 0.1143)
		(layer "In13.Cu")
		(net "P5E_CPU0_P0_RX_DP<1>")
	)
	(arc
		(start 307.90007 -371.653054)
		(mid 307.952395 -371.618092)
		(end 308.014116 -371.60581)
		(width 0.14224)
		(layer "In13.Cu")
		(net "P5E_CPU0_P0_RX_DP<1>")
	)
	(arc
		(start 346.243148 -273.740626)
		(mid 346.395135 -273.584118)
		(end 346.476574 -273.381724)
		(width 0.1143)
		(layer "In13.Cu")
		(net "P5E_CPU0_P0_RX_DP<1>")
	)
	(arc
		(start 346.173552 -274.390866)
		(mid 346.016575 -274.086066)
		(end 346.173552 -273.781266)
		(width 0.1143)
		(layer "In13.Cu")
		(net "P5E_CPU0_P0_RX_DP<1>")
	)
	(arc
		(start 346.243148 -280.220674)
		(mid 346.486475 -279.756108)
		(end 346.243148 -279.291542)
		(width 0.1143)
		(layer "In13.Cu")
		(net "P5E_CPU0_P0_RX_DP<1>")
	)
	(arc
		(start 346.173552 -293.830756)
		(mid 346.016575 -293.525956)
		(end 346.173552 -293.221156)
		(width 0.1143)
		(layer "In13.Cu")
		(net "P5E_CPU0_P0_RX_DP<1>")
	)
	(arc
		(start 346.173552 -279.250902)
		(mid 346.016575 -278.946102)
		(end 346.173552 -278.641302)
		(width 0.1143)
		(layer "In13.Cu")
		(net "P5E_CPU0_P0_RX_DP<1>")
	)
	(arc
		(start 346.173552 -280.870914)
		(mid 346.016575 -280.566114)
		(end 346.173552 -280.261314)
		(width 0.1143)
		(layer "In13.Cu")
		(net "P5E_CPU0_P0_RX_DP<1>")
	)
	(arc
		(start 324.886574 -369.71097)
		(mid 326.119845 -369.528047)
		(end 327.365106 -369.466876)
		(width 0.14224)
		(layer "In13.Cu")
		(net "P5E_CPU0_P0_RX_DP<1>")
	)
	(arc
		(start 346.173552 -282.490926)
		(mid 346.016575 -282.186126)
		(end 346.173552 -281.881326)
		(width 0.1143)
		(layer "In13.Cu")
		(net "P5E_CPU0_P0_RX_DP<1>")
	)
	(arc
		(start 305.740308 -390.358884)
		(mid 305.706569 -390.189267)
		(end 305.610514 -390.045448)
		(width 0.14224)
		(layer "In13.Cu")
		(net "P5E_CPU0_P0_RX_DP<1>")
	)
	(arc
		(start 360.030268 -316.614556)
		(mid 360.012531 -316.589009)
		(end 359.993692 -316.564264)
		(width 0.14224)
		(layer "In13.Cu")
		(net "P5E_CPU0_P0_RX_DP<1>")
	)
	(arc
		(start 346.173552 -285.73095)
		(mid 346.016575 -285.42615)
		(end 346.173552 -285.12135)
		(width 0.1143)
		(layer "In13.Cu")
		(net "P5E_CPU0_P0_RX_DP<1>")
	)
	(arc
		(start 346.243148 -285.08071)
		(mid 346.486475 -284.616144)
		(end 346.243148 -284.151578)
		(width 0.1143)
		(layer "In13.Cu")
		(net "P5E_CPU0_P0_RX_DP<1>")
	)
	(arc
		(start 346.173552 -292.210744)
		(mid 346.016575 -291.905944)
		(end 346.173552 -291.601144)
		(width 0.1143)
		(layer "In13.Cu")
		(net "P5E_CPU0_P0_RX_DP<1>")
	)
	(arc
		(start 297.893232 -382.328166)
		(mid 297.807285 -382.199917)
		(end 297.777154 -382.048512)
		(width 0.14224)
		(layer "In13.Cu")
		(net "P5E_CPU0_P0_RX_DP<1>")
	)
	(arc
		(start 360.094022 -316.735206)
		(mid 360.065049 -316.673346)
		(end 360.030268 -316.614556)
		(width 0.14224)
		(layer "In13.Cu")
		(net "P5E_CPU0_P0_RX_DP<1>")
	)
	(arc
		(start 346.243148 -275.360638)
		(mid 346.486475 -274.896072)
		(end 346.243148 -274.431506)
		(width 0.1143)
		(layer "In13.Cu")
		(net "P5E_CPU0_P0_RX_DP<1>")
	)
	(arc
		(start 346.243148 -294.800528)
		(mid 346.486584 -294.33589)
		(end 346.243148 -293.871142)
		(width 0.1143)
		(layer "In13.Cu")
		(net "P5E_CPU0_P0_RX_DP<1>")
	)
	(arc
		(start 346.016834 -288.66592)
		(mid 346.057615 -288.495623)
		(end 346.171266 -288.36239)
		(width 0.1143)
		(layer "In13.Cu")
		(net "P5E_CPU0_P0_RX_DP<1>")
	)
	(arc
		(start 346.243148 -293.180516)
		(mid 346.486584 -292.715878)
		(end 346.243148 -292.25113)
		(width 0.1143)
		(layer "In13.Cu")
		(net "P5E_CPU0_P0_RX_DP<1>")
	)
	(arc
		(start 346.243148 -283.460698)
		(mid 346.486475 -282.996132)
		(end 346.243148 -282.531566)
		(width 0.1143)
		(layer "In13.Cu")
		(net "P5E_CPU0_P0_RX_DP<1>")
	)
	(arc
		(start 346.243148 -281.840686)
		(mid 346.486475 -281.37612)
		(end 346.243148 -280.911554)
		(width 0.1143)
		(layer "In13.Cu")
		(net "P5E_CPU0_P0_RX_DP<1>")
	)
	(arc
		(start 346.476574 -273.381724)
		(mid 346.478597 -273.370314)
		(end 346.480384 -273.358864)
		(width 0.1143)
		(layer "In13.Cu")
		(net "P5E_CPU0_P0_RX_DP<1>")
	)
	(arc
		(start 346.243148 -288.320988)
		(mid 346.486681 -287.854618)
		(end 346.240608 -287.38957)
		(width 0.1143)
		(layer "In13.Cu")
		(net "P5E_CPU0_P0_RX_DP<1>")
	)
	(arc
		(start 346.243148 -278.600662)
		(mid 346.486475 -278.136096)
		(end 346.243148 -277.67153)
		(width 0.1143)
		(layer "In13.Cu")
		(net "P5E_CPU0_P0_RX_DP<1>")
	)
	(arc
		(start 346.173552 -290.590732)
		(mid 346.016575 -290.285932)
		(end 346.173552 -289.981132)
		(width 0.1143)
		(layer "In13.Cu")
		(net "P5E_CPU0_P0_RX_DP<1>")
	)
	(arc
		(start 346.173552 -276.010878)
		(mid 346.016575 -275.706078)
		(end 346.173552 -275.401278)
		(width 0.1143)
		(layer "In13.Cu")
		(net "P5E_CPU0_P0_RX_DP<1>")
	)
	(arc
		(start 301.753016 -372.791736)
		(mid 302.253175 -372.457477)
		(end 302.843184 -372.340124)
		(width 0.14224)
		(layer "In13.Cu")
		(net "P5E_CPU0_P0_RX_DP<1>")
	)
	(segment
		(start 321.670426 -394.385292)
		(end 322.191126 -394.385292)
		(width 0.127)
		(layer "F.Cu")
		(net "P5E_CPU0_P0_RX_DP<15>")
	)
	(segment
		(start 358.137968 -268.960092)
		(end 357.671116 -269.22603)
		(width 0.12954)
		(layer "F.Cu")
		(net "P5E_CPU0_P0_RX_DP<15>")
	)
	(segment
		(start 379.375924 -387.283198)
		(end 379.683264 -386.975858)
		(width 0.14224)
		(layer "In15.Cu")
		(net "P5E_CPU0_P0_RX_DP<15>")
	)
	(segment
		(start 388.042658 -381.157226)
		(end 388.671054 -380.52883)
		(width 0.14224)
		(layer "In15.Cu")
		(net "P5E_CPU0_P0_RX_DP<15>")
	)
	(segment
		(start 357.491284 -269.55242)
		(end 357.487728 -269.550388)
		(width 0.1143)
		(layer "In15.Cu")
		(net "P5E_CPU0_P0_RX_DP<15>")
	)
	(segment
		(start 379.683264 -386.170678)
		(end 379.375924 -385.863338)
		(width 0.14224)
		(layer "In15.Cu")
		(net "P5E_CPU0_P0_RX_DP<15>")
	)
	(segment
		(start 328.722228 -389.47852)
		(end 328.722228 -387.128004)
		(width 0.14224)
		(layer "In15.Cu")
		(net "P5E_CPU0_P0_RX_DP<15>")
	)
	(segment
		(start 322.460366 -393.930632)
		(end 322.548504 -393.842494)
		(width 0.14224)
		(layer "In15.Cu")
		(net "P5E_CPU0_P0_RX_DP<15>")
	)
	(segment
		(start 370.877084 -387.283198)
		(end 379.375924 -387.283198)
		(width 0.14224)
		(layer "In15.Cu")
		(net "P5E_CPU0_P0_RX_DP<15>")
	)
	(segment
		(start 363.695742 -382.928114)
		(end 364.410244 -382.928114)
		(width 0.14224)
		(layer "In15.Cu")
		(net "P5E_CPU0_P0_RX_DP<15>")
	)
	(segment
		(start 370.569744 -386.975858)
		(end 370.877084 -387.283198)
		(width 0.14224)
		(layer "In15.Cu")
		(net "P5E_CPU0_P0_RX_DP<15>")
	)
	(segment
		(start 357.98633 -270.377412)
		(end 357.985568 -270.376904)
		(width 0.1143)
		(layer "In15.Cu")
		(net "P5E_CPU0_P0_RX_DP<15>")
	)
	(segment
		(start 400.537934 -352.605086)
		(end 373.8626 -325.930006)
		(width 0.14224)
		(layer "In15.Cu")
		(net "P5E_CPU0_P0_RX_DP<15>")
	)
	(segment
		(start 371.989604 -385.721098)
		(end 371.989604 -385.149598)
		(width 0.14224)
		(layer "In15.Cu")
		(net "P5E_CPU0_P0_RX_DP<15>")
	)
	(segment
		(start 357.477822 -269.544546)
		(end 357.474774 -269.543022)
		(width 0.1143)
		(layer "In15.Cu")
		(net "P5E_CPU0_P0_RX_DP<15>")
	)
	(segment
		(start 372.711218 -324.492366)
		(end 359.78211 -304.076608)
		(width 0.14224)
		(layer "In15.Cu")
		(net "P5E_CPU0_P0_RX_DP<15>")
	)
	(segment
		(start 379.375924 -385.863338)
		(end 372.131844 -385.863338)
		(width 0.14224)
		(layer "In15.Cu")
		(net "P5E_CPU0_P0_RX_DP<15>")
	)
	(segment
		(start 357.474012 -269.542514)
		(end 357.471472 -269.541244)
		(width 0.1143)
		(layer "In15.Cu")
		(net "P5E_CPU0_P0_RX_DP<15>")
	)
	(segment
		(start 379.683264 -386.975858)
		(end 379.683264 -386.170678)
		(width 0.14224)
		(layer "In15.Cu")
		(net "P5E_CPU0_P0_RX_DP<15>")
	)
	(segment
		(start 390.801606 -376.137424)
		(end 392.544046 -374.394984)
		(width 0.14224)
		(layer "In15.Cu")
		(net "P5E_CPU0_P0_RX_DP<15>")
	)
	(segment
		(start 400.959574 -370.445792)
		(end 400.959574 -353.641406)
		(width 0.14224)
		(layer "In15.Cu")
		(net "P5E_CPU0_P0_RX_DP<15>")
	)
	(segment
		(start 359.747312 -295.347644)
		(end 359.414826 -274.806918)
		(width 0.14224)
		(layer "In15.Cu")
		(net "P5E_CPU0_P0_RX_DP<15>")
	)
	(segment
		(start 357.487728 -269.550388)
		(end 357.477822 -269.544546)
		(width 0.1143)
		(layer "In15.Cu")
		(net "P5E_CPU0_P0_RX_DP<15>")
	)
	(segment
		(start 322.191126 -394.385292)
		(end 322.286122 -394.031216)
		(width 0.14224)
		(layer "In15.Cu")
		(net "P5E_CPU0_P0_RX_DP<15>")
	)
	(segment
		(start 358.476042 -271.199102)
		(end 358.393492 -271.150842)
		(width 0.1143)
		(layer "In15.Cu")
		(net "P5E_CPU0_P0_RX_DP<15>")
	)
	(segment
		(start 359.747312 -303.95672)
		(end 359.747312 -295.347644)
		(width 0.14224)
		(layer "In15.Cu")
		(net "P5E_CPU0_P0_RX_DP<15>")
	)
	(segment
		(start 368.629184 -385.007358)
		(end 370.427504 -385.007358)
		(width 0.14224)
		(layer "In15.Cu")
		(net "P5E_CPU0_P0_RX_DP<15>")
	)
	(segment
		(start 371.989604 -385.149598)
		(end 372.131844 -385.007358)
		(width 0.14224)
		(layer "In15.Cu")
		(net "P5E_CPU0_P0_RX_DP<15>")
	)
	(segment
		(start 388.800848 -380.21514)
		(end 388.800848 -379.63221)
		(width 0.14224)
		(layer "In15.Cu")
		(net "P5E_CPU0_P0_RX_DP<15>")
	)
	(segment
		(start 387.1468 -381.410972)
		(end 387.233414 -381.324358)
		(width 0.14224)
		(layer "In15.Cu")
		(net "P5E_CPU0_P0_RX_DP<15>")
	)
	(segment
		(start 357.303324 -269.29588)
		(end 357.373174 -269.22603)
		(width 0.1143)
		(layer "In15.Cu")
		(net "P5E_CPU0_P0_RX_DP<15>")
	)
	(segment
		(start 387.109462 -382.910334)
		(end 387.109462 -381.501142)
		(width 0.14224)
		(layer "In15.Cu")
		(net "P5E_CPU0_P0_RX_DP<15>")
	)
	(segment
		(start 366.019334 -383.593594)
		(end 366.587532 -384.161792)
		(width 0.14224)
		(layer "In15.Cu")
		(net "P5E_CPU0_P0_RX_DP<15>")
	)
	(segment
		(start 357.77678 -270.053308)
		(end 357.77678 -270.04391)
		(width 0.1143)
		(layer "In15.Cu")
		(net "P5E_CPU0_P0_RX_DP<15>")
	)
	(segment
		(start 357.985568 -270.376904)
		(end 357.955088 -270.359124)
		(width 0.1143)
		(layer "In15.Cu")
		(net "P5E_CPU0_P0_RX_DP<15>")
	)
	(segment
		(start 357.474774 -269.543022)
		(end 357.474012 -269.542514)
		(width 0.1143)
		(layer "In15.Cu")
		(net "P5E_CPU0_P0_RX_DP<15>")
	)
	(segment
		(start 359.414826 -272.073624)
		(end 359.100374 -271.759172)
		(width 0.14224)
		(layer "In15.Cu")
		(net "P5E_CPU0_P0_RX_DP<15>")
	)
	(segment
		(start 322.286122 -394.031216)
		(end 322.460366 -393.930632)
		(width 0.14224)
		(layer "In15.Cu")
		(net "P5E_CPU0_P0_RX_DP<15>")
	)
	(segment
		(start 392.805412 -374.28678)
		(end 397.264128 -374.28678)
		(width 0.14224)
		(layer "In15.Cu")
		(net "P5E_CPU0_P0_RX_DP<15>")
	)
	(segment
		(start 357.993188 -270.381476)
		(end 357.98633 -270.377412)
		(width 0.1143)
		(layer "In15.Cu")
		(net "P5E_CPU0_P0_RX_DP<15>")
	)
	(segment
		(start 357.471472 -269.541244)
		(end 357.452422 -269.530322)
		(width 0.1143)
		(layer "In15.Cu")
		(net "P5E_CPU0_P0_RX_DP<15>")
	)
	(segment
		(start 357.373174 -269.22603)
		(end 357.671116 -269.22603)
		(width 0.1143)
		(layer "In15.Cu")
		(net "P5E_CPU0_P0_RX_DP<15>")
	)
	(segment
		(start 359.414826 -274.806918)
		(end 359.414826 -272.073624)
		(width 0.14224)
		(layer "In15.Cu")
		(net "P5E_CPU0_P0_RX_DP<15>")
	)
	(segment
		(start 400.915378 -353.412298)
		(end 400.66976 -352.803714)
		(width 0.14224)
		(layer "In15.Cu")
		(net "P5E_CPU0_P0_RX_DP<15>")
	)
	(segment
		(start 386.940298 -383.478532)
		(end 387.06933 -383.133092)
		(width 0.14224)
		(layer "In15.Cu")
		(net "P5E_CPU0_P0_RX_DP<15>")
	)
	(segment
		(start 357.954072 -270.358616)
		(end 357.95331 -270.358108)
		(width 0.1143)
		(layer "In15.Cu")
		(net "P5E_CPU0_P0_RX_DP<15>")
	)
	(segment
		(start 370.569744 -385.149598)
		(end 370.569744 -386.975858)
		(width 0.14224)
		(layer "In15.Cu")
		(net "P5E_CPU0_P0_RX_DP<15>")
	)
	(segment
		(start 390.51611 -377.726956)
		(end 390.51611 -376.82678)
		(width 0.14224)
		(layer "In15.Cu")
		(net "P5E_CPU0_P0_RX_DP<15>")
	)
	(segment
		(start 327.864978 -390.107424)
		(end 328.470514 -389.856472)
		(width 0.14224)
		(layer "In15.Cu")
		(net "P5E_CPU0_P0_RX_DP<15>")
	)
	(segment
		(start 359.016046 -271.739106)
		(end 358.476042 -271.199102)
		(width 0.1143)
		(layer "In15.Cu")
		(net "P5E_CPU0_P0_RX_DP<15>")
	)
	(segment
		(start 362.034328 -385.501134)
		(end 362.266484 -384.939286)
		(width 0.14224)
		(layer "In15.Cu")
		(net "P5E_CPU0_P0_RX_DP<15>")
	)
	(segment
		(start 370.427504 -385.007358)
		(end 370.569744 -385.149598)
		(width 0.14224)
		(layer "In15.Cu")
		(net "P5E_CPU0_P0_RX_DP<15>")
	)
	(segment
		(start 322.548504 -393.842494)
		(end 322.548504 -393.234418)
		(width 0.14224)
		(layer "In15.Cu")
		(net "P5E_CPU0_P0_RX_DP<15>")
	)
	(segment
		(start 362.737908 -383.819146)
		(end 363.581696 -382.975358)
		(width 0.14224)
		(layer "In15.Cu")
		(net "P5E_CPU0_P0_RX_DP<15>")
	)
	(segment
		(start 357.495348 -269.55496)
		(end 357.491284 -269.55242)
		(width 0.1143)
		(layer "In15.Cu")
		(net "P5E_CPU0_P0_RX_DP<15>")
	)
	(segment
		(start 361.300522 -386.29971)
		(end 361.90301 -385.697476)
		(width 0.14224)
		(layer "In15.Cu")
		(net "P5E_CPU0_P0_RX_DP<15>")
	)
	(segment
		(start 359.080308 -271.739106)
		(end 359.016046 -271.739106)
		(width 0.1143)
		(layer "In15.Cu")
		(net "P5E_CPU0_P0_RX_DP<15>")
	)
	(segment
		(start 328.769472 -387.013958)
		(end 328.978768 -386.804662)
		(width 0.14224)
		(layer "In15.Cu")
		(net "P5E_CPU0_P0_RX_DP<15>")
	)
	(segment
		(start 322.548504 -393.234418)
		(end 325.381112 -390.40181)
		(width 0.14224)
		(layer "In15.Cu")
		(net "P5E_CPU0_P0_RX_DP<15>")
	)
	(segment
		(start 325.980552 -390.153398)
		(end 327.633838 -390.153398)
		(width 0.14224)
		(layer "In15.Cu")
		(net "P5E_CPU0_P0_RX_DP<15>")
	)
	(segment
		(start 359.100374 -271.759172)
		(end 359.080308 -271.739106)
		(width 0.1143)
		(layer "In15.Cu")
		(net "P5E_CPU0_P0_RX_DP<15>")
	)
	(segment
		(start 397.678656 -374.115076)
		(end 400.685 -371.108732)
		(width 0.14224)
		(layer "In15.Cu")
		(net "P5E_CPU0_P0_RX_DP<15>")
	)
	(segment
		(start 357.955088 -270.359124)
		(end 357.954072 -270.358616)
		(width 0.1143)
		(layer "In15.Cu")
		(net "P5E_CPU0_P0_RX_DP<15>")
	)
	(segment
		(start 372.131844 -385.863338)
		(end 371.989604 -385.721098)
		(width 0.14224)
		(layer "In15.Cu")
		(net "P5E_CPU0_P0_RX_DP<15>")
	)
	(segment
		(start 372.131844 -385.007358)
		(end 382.154176 -385.007358)
		(width 0.14224)
		(layer "In15.Cu")
		(net "P5E_CPU0_P0_RX_DP<15>")
	)
	(segment
		(start 389.485378 -378.832618)
		(end 389.780018 -378.715524)
		(width 0.14224)
		(layer "In15.Cu")
		(net "P5E_CPU0_P0_RX_DP<15>")
	)
	(segment
		(start 387.34746 -381.277114)
		(end 387.753098 -381.277114)
		(width 0.14224)
		(layer "In15.Cu")
		(net "P5E_CPU0_P0_RX_DP<15>")
	)
	(segment
		(start 388.941818 -379.291342)
		(end 389.22452 -379.00864)
		(width 0.14224)
		(layer "In15.Cu")
		(net "P5E_CPU0_P0_RX_DP<15>")
	)
	(segment
		(start 329.092814 -386.757418)
		(end 360.195622 -386.757418)
		(width 0.14224)
		(layer "In15.Cu")
		(net "P5E_CPU0_P0_RX_DP<15>")
	)
	(arc
		(start 388.671054 -380.52883)
		(mid 388.76719 -380.384907)
		(end 388.800848 -380.21514)
		(width 0.14224)
		(layer "In15.Cu")
		(net "P5E_CPU0_P0_RX_DP<15>")
	)
	(arc
		(start 328.978768 -386.804662)
		(mid 329.031093 -386.7697)
		(end 329.092814 -386.757418)
		(width 0.14224)
		(layer "In15.Cu")
		(net "P5E_CPU0_P0_RX_DP<15>")
	)
	(arc
		(start 388.800848 -379.63221)
		(mid 388.837428 -379.447751)
		(end 388.941818 -379.291342)
		(width 0.14224)
		(layer "In15.Cu")
		(net "P5E_CPU0_P0_RX_DP<15>")
	)
	(arc
		(start 387.233414 -381.324358)
		(mid 387.285739 -381.289396)
		(end 387.34746 -381.277114)
		(width 0.14224)
		(layer "In15.Cu")
		(net "P5E_CPU0_P0_RX_DP<15>")
	)
	(arc
		(start 389.372602 -378.890276)
		(mid 389.427648 -378.858822)
		(end 389.485378 -378.832618)
		(width 0.14224)
		(layer "In15.Cu")
		(net "P5E_CPU0_P0_RX_DP<15>")
	)
	(arc
		(start 390.284716 -378.354336)
		(mid 390.456516 -378.061331)
		(end 390.51611 -377.726956)
		(width 0.14224)
		(layer "In15.Cu")
		(net "P5E_CPU0_P0_RX_DP<15>")
	)
	(arc
		(start 392.544046 -374.394984)
		(mid 392.663976 -374.314913)
		(end 392.805412 -374.28678)
		(width 0.14224)
		(layer "In15.Cu")
		(net "P5E_CPU0_P0_RX_DP<15>")
	)
	(arc
		(start 397.264128 -374.28678)
		(mid 397.488469 -374.242156)
		(end 397.678656 -374.115076)
		(width 0.14224)
		(layer "In15.Cu")
		(net "P5E_CPU0_P0_RX_DP<15>")
	)
	(arc
		(start 328.470514 -389.856472)
		(mid 328.653736 -389.705683)
		(end 328.722228 -389.47852)
		(width 0.14224)
		(layer "In15.Cu")
		(net "P5E_CPU0_P0_RX_DP<15>")
	)
	(arc
		(start 357.95331 -270.358108)
		(mid 357.824056 -270.229438)
		(end 357.77678 -270.053308)
		(width 0.1143)
		(layer "In15.Cu")
		(net "P5E_CPU0_P0_RX_DP<15>")
	)
	(arc
		(start 382.154176 -385.007358)
		(mid 383.9926 -384.88497)
		(end 385.798568 -384.519932)
		(width 0.14224)
		(layer "In15.Cu")
		(net "P5E_CPU0_P0_RX_DP<15>")
	)
	(arc
		(start 357.452422 -269.530322)
		(mid 357.355287 -269.427453)
		(end 357.303324 -269.29588)
		(width 0.1143)
		(layer "In15.Cu")
		(net "P5E_CPU0_P0_RX_DP<15>")
	)
	(arc
		(start 373.8626 -325.930006)
		(mid 373.247299 -325.242909)
		(end 372.711218 -324.492366)
		(width 0.14224)
		(layer "In15.Cu")
		(net "P5E_CPU0_P0_RX_DP<15>")
	)
	(arc
		(start 360.195622 -386.757418)
		(mid 360.793592 -386.638457)
		(end 361.300522 -386.29971)
		(width 0.14224)
		(layer "In15.Cu")
		(net "P5E_CPU0_P0_RX_DP<15>")
	)
	(arc
		(start 361.90301 -385.697476)
		(mid 361.97836 -385.605787)
		(end 362.034328 -385.501134)
		(width 0.14224)
		(layer "In15.Cu")
		(net "P5E_CPU0_P0_RX_DP<15>")
	)
	(arc
		(start 400.685 -371.108732)
		(mid 400.888233 -370.804573)
		(end 400.959574 -370.445792)
		(width 0.14224)
		(layer "In15.Cu")
		(net "P5E_CPU0_P0_RX_DP<15>")
	)
	(arc
		(start 362.357416 -384.595624)
		(mid 362.482991 -384.175688)
		(end 362.737908 -383.819146)
		(width 0.14224)
		(layer "In15.Cu")
		(net "P5E_CPU0_P0_RX_DP<15>")
	)
	(arc
		(start 387.753098 -381.277114)
		(mid 387.909801 -381.245962)
		(end 388.042658 -381.157226)
		(width 0.14224)
		(layer "In15.Cu")
		(net "P5E_CPU0_P0_RX_DP<15>")
	)
	(arc
		(start 362.266484 -384.939286)
		(mid 362.32344 -384.770496)
		(end 362.357416 -384.595624)
		(width 0.14224)
		(layer "In15.Cu")
		(net "P5E_CPU0_P0_RX_DP<15>")
	)
	(arc
		(start 387.109462 -381.501142)
		(mid 387.119168 -381.452347)
		(end 387.1468 -381.410972)
		(width 0.14224)
		(layer "In15.Cu")
		(net "P5E_CPU0_P0_RX_DP<15>")
	)
	(arc
		(start 364.410244 -382.928114)
		(mid 365.280567 -383.101798)
		(end 366.019334 -383.593594)
		(width 0.14224)
		(layer "In15.Cu")
		(net "P5E_CPU0_P0_RX_DP<15>")
	)
	(arc
		(start 328.722228 -387.128004)
		(mid 328.734505 -387.066281)
		(end 328.769472 -387.013958)
		(width 0.14224)
		(layer "In15.Cu")
		(net "P5E_CPU0_P0_RX_DP<15>")
	)
	(arc
		(start 389.780018 -378.715524)
		(mid 390.054357 -378.565662)
		(end 390.284716 -378.354336)
		(width 0.14224)
		(layer "In15.Cu")
		(net "P5E_CPU0_P0_RX_DP<15>")
	)
	(arc
		(start 366.587532 -384.161792)
		(mid 367.524264 -384.787633)
		(end 368.629184 -385.007358)
		(width 0.14224)
		(layer "In15.Cu")
		(net "P5E_CPU0_P0_RX_DP<15>")
	)
	(arc
		(start 385.798568 -384.519932)
		(mid 386.495115 -384.137018)
		(end 386.940298 -383.478532)
		(width 0.14224)
		(layer "In15.Cu")
		(net "P5E_CPU0_P0_RX_DP<15>")
	)
	(arc
		(start 400.66976 -352.803714)
		(mid 400.61384 -352.69777)
		(end 400.537934 -352.605086)
		(width 0.14224)
		(layer "In15.Cu")
		(net "P5E_CPU0_P0_RX_DP<15>")
	)
	(arc
		(start 390.51611 -376.82678)
		(mid 390.590301 -376.453706)
		(end 390.801606 -376.137424)
		(width 0.14224)
		(layer "In15.Cu")
		(net "P5E_CPU0_P0_RX_DP<15>")
	)
	(arc
		(start 359.78211 -304.076608)
		(mid 359.756229 -304.01913)
		(end 359.747312 -303.95672)
		(width 0.14224)
		(layer "In15.Cu")
		(net "P5E_CPU0_P0_RX_DP<15>")
	)
	(arc
		(start 357.77678 -270.04391)
		(mid 357.701393 -269.761837)
		(end 357.495348 -269.55496)
		(width 0.1143)
		(layer "In15.Cu")
		(net "P5E_CPU0_P0_RX_DP<15>")
	)
	(arc
		(start 327.633838 -390.153398)
		(mid 327.751672 -390.141793)
		(end 327.864978 -390.107424)
		(width 0.14224)
		(layer "In15.Cu")
		(net "P5E_CPU0_P0_RX_DP<15>")
	)
	(arc
		(start 358.23652 -270.846042)
		(mid 358.172005 -270.583823)
		(end 357.993188 -270.381476)
		(width 0.1143)
		(layer "In15.Cu")
		(net "P5E_CPU0_P0_RX_DP<15>")
	)
	(arc
		(start 358.393492 -271.150842)
		(mid 358.278065 -271.017466)
		(end 358.23652 -270.846042)
		(width 0.1143)
		(layer "In15.Cu")
		(net "P5E_CPU0_P0_RX_DP<15>")
	)
	(arc
		(start 363.581696 -382.975358)
		(mid 363.634021 -382.940396)
		(end 363.695742 -382.928114)
		(width 0.14224)
		(layer "In15.Cu")
		(net "P5E_CPU0_P0_RX_DP<15>")
	)
	(arc
		(start 400.959574 -353.641406)
		(mid 400.948494 -353.524727)
		(end 400.915378 -353.412298)
		(width 0.14224)
		(layer "In15.Cu")
		(net "P5E_CPU0_P0_RX_DP<15>")
	)
	(arc
		(start 325.381112 -390.40181)
		(mid 325.656122 -390.217961)
		(end 325.980552 -390.153398)
		(width 0.14224)
		(layer "In15.Cu")
		(net "P5E_CPU0_P0_RX_DP<15>")
	)
	(arc
		(start 387.06933 -383.133092)
		(mid 387.099368 -383.023511)
		(end 387.109462 -382.910334)
		(width 0.14224)
		(layer "In15.Cu")
		(net "P5E_CPU0_P0_RX_DP<15>")
	)
	(arc
		(start 389.22452 -379.00864)
		(mid 389.295291 -378.945368)
		(end 389.372602 -378.890276)
		(width 0.14224)
		(layer "In15.Cu")
		(net "P5E_CPU0_P0_RX_DP<15>")
	)
	(segment
		(start 320.470276 -394.385292)
		(end 320.990976 -394.385292)
		(width 0.127)
		(layer "F.Cu")
		(net "P5E_CPU0_P0_RX_DP<14>")
	)
	(segment
		(start 358.137968 -270.580104)
		(end 357.671116 -270.846042)
		(width 0.12954)
		(layer "F.Cu")
		(net "P5E_CPU0_P0_RX_DP<14>")
	)
	(segment
		(start 358.423972 -288.343594)
		(end 358.424226 -288.343086)
		(width 0.1143)
		(layer "In15.Cu")
		(net "P5E_CPU0_P0_RX_DP<14>")
	)
	(segment
		(start 358.461564 -285.770574)
		(end 358.424226 -285.748984)
		(width 0.1143)
		(layer "In15.Cu")
		(net "P5E_CPU0_P0_RX_DP<14>")
	)
	(segment
		(start 358.423972 -288.9885)
		(end 358.393492 -288.97072)
		(width 0.1143)
		(layer "In15.Cu")
		(net "P5E_CPU0_P0_RX_DP<14>")
	)
	(segment
		(start 321.032378 -393.113006)
		(end 321.035426 -392.7348)
		(width 0.14224)
		(layer "In15.Cu")
		(net "P5E_CPU0_P0_RX_DP<14>")
	)
	(segment
		(start 358.463088 -280.911554)
		(end 358.393492 -280.870914)
		(width 0.1143)
		(layer "In15.Cu")
		(net "P5E_CPU0_P0_RX_DP<14>")
	)
	(segment
		(start 358.423972 -294.823388)
		(end 358.50195 -294.773604)
		(width 0.1143)
		(layer "In15.Cu")
		(net "P5E_CPU0_P0_RX_DP<14>")
	)
	(segment
		(start 358.423972 -279.268682)
		(end 358.393492 -279.250902)
		(width 0.1143)
		(layer "In15.Cu")
		(net "P5E_CPU0_P0_RX_DP<14>")
	)
	(segment
		(start 358.281986 -303.332642)
		(end 358.281986 -295.841928)
		(width 0.14224)
		(layer "In15.Cu")
		(net "P5E_CPU0_P0_RX_DP<14>")
	)
	(segment
		(start 357.993188 -272.001234)
		(end 357.930958 -271.965166)
		(width 0.1143)
		(layer "In15.Cu")
		(net "P5E_CPU0_P0_RX_DP<14>")
	)
	(segment
		(start 359.883964 -378.31903)
		(end 362.9533 -378.31903)
		(width 0.14224)
		(layer "In15.Cu")
		(net "P5E_CPU0_P0_RX_DP<14>")
	)
	(segment
		(start 358.422448 -277.004526)
		(end 358.423972 -277.00351)
		(width 0.1143)
		(layer "In15.Cu")
		(net "P5E_CPU0_P0_RX_DP<14>")
	)
	(segment
		(start 358.463088 -277.67153)
		(end 358.393492 -277.63089)
		(width 0.1143)
		(layer "In15.Cu")
		(net "P5E_CPU0_P0_RX_DP<14>")
	)
	(segment
		(start 358.464358 -274.432522)
		(end 358.393492 -274.390866)
		(width 0.1143)
		(layer "In15.Cu")
		(net "P5E_CPU0_P0_RX_DP<14>")
	)
	(segment
		(start 358.423972 -277.00351)
		(end 358.42448 -277.003002)
		(width 0.1143)
		(layer "In15.Cu")
		(net "P5E_CPU0_P0_RX_DP<14>")
	)
	(segment
		(start 360.996484 -376.75693)
		(end 360.996484 -376.18543)
		(width 0.14224)
		(layer "In15.Cu")
		(net "P5E_CPU0_P0_RX_DP<14>")
	)
	(segment
		(start 358.706166 -286.236664)
		(end 358.706166 -286.236156)
		(width 0.1143)
		(layer "In15.Cu")
		(net "P5E_CPU0_P0_RX_DP<14>")
	)
	(segment
		(start 381.920242 -374.62333)
		(end 381.612902 -374.93067)
		(width 0.14224)
		(layer "In15.Cu")
		(net "P5E_CPU0_P0_RX_DP<14>")
	)
	(segment
		(start 380.756922 -373.90959)
		(end 380.899162 -373.76735)
		(width 0.14224)
		(layer "In15.Cu")
		(net "P5E_CPU0_P0_RX_DP<14>")
	)
	(segment
		(start 358.706166 -284.62859)
		(end 358.706166 -284.616144)
		(width 0.1143)
		(layer "In15.Cu")
		(net "P5E_CPU0_P0_RX_DP<14>")
	)
	(segment
		(start 329.530964 -379.282452)
		(end 329.530964 -379.282706)
		(width 0.14224)
		(layer "In15.Cu")
		(net "P5E_CPU0_P0_RX_DP<14>")
	)
	(segment
		(start 358.393492 -283.501338)
		(end 358.394254 -283.50083)
		(width 0.1143)
		(layer "In15.Cu")
		(net "P5E_CPU0_P0_RX_DP<14>")
	)
	(segment
		(start 363.26064 -378.01169)
		(end 363.26064 -377.20651)
		(width 0.14224)
		(layer "In15.Cu")
		(net "P5E_CPU0_P0_RX_DP<14>")
	)
	(segment
		(start 358.445562 -293.19093)
		(end 358.456484 -293.184326)
		(width 0.1143)
		(layer "In15.Cu")
		(net "P5E_CPU0_P0_RX_DP<14>")
	)
	(segment
		(start 380.449582 -376.04319)
		(end 380.756922 -375.73585)
		(width 0.14224)
		(layer "In15.Cu")
		(net "P5E_CPU0_P0_RX_DP<14>")
	)
	(segment
		(start 370.84762 -324.250812)
		(end 358.359456 -303.61001)
		(width 0.14224)
		(layer "In15.Cu")
		(net "P5E_CPU0_P0_RX_DP<14>")
	)
	(segment
		(start 358.420416 -288.345626)
		(end 358.421432 -288.345118)
		(width 0.1143)
		(layer "In15.Cu")
		(net "P5E_CPU0_P0_RX_DP<14>")
	)
	(segment
		(start 321.085972 -394.031216)
		(end 321.260216 -393.930632)
		(width 0.14224)
		(layer "In15.Cu")
		(net "P5E_CPU0_P0_RX_DP<14>")
	)
	(segment
		(start 360.996484 -376.18543)
		(end 361.138724 -376.04319)
		(width 0.14224)
		(layer "In15.Cu")
		(net "P5E_CPU0_P0_RX_DP<14>")
	)
	(segment
		(start 358.395778 -276.012148)
		(end 358.393492 -276.010878)
		(width 0.1143)
		(layer "In15.Cu")
		(net "P5E_CPU0_P0_RX_DP<14>")
	)
	(segment
		(start 358.236266 -295.76776)
		(end 358.236266 -295.145968)
		(width 0.1143)
		(layer "In15.Cu")
		(net "P5E_CPU0_P0_RX_DP<14>")
	)
	(segment
		(start 387.38429 -373.76735)
		(end 387.51129 -373.89435)
		(width 0.14224)
		(layer "In15.Cu")
		(net "P5E_CPU0_P0_RX_DP<14>")
	)
	(segment
		(start 358.460294 -289.009582)
		(end 358.423972 -288.9885)
		(width 0.1143)
		(layer "In15.Cu")
		(net "P5E_CPU0_P0_RX_DP<14>")
	)
	(segment
		(start 358.464358 -272.812002)
		(end 358.393492 -272.7706)
		(width 0.1143)
		(layer "In15.Cu")
		(net "P5E_CPU0_P0_RX_DP<14>")
	)
	(segment
		(start 358.706166 -292.71595)
		(end 358.706166 -292.702742)
		(width 0.1143)
		(layer "In15.Cu")
		(net "P5E_CPU0_P0_RX_DP<14>")
	)
	(segment
		(start 362.9533 -378.31903)
		(end 363.26064 -378.01169)
		(width 0.14224)
		(layer "In15.Cu")
		(net "P5E_CPU0_P0_RX_DP<14>")
	)
	(segment
		(start 361.138724 -376.89917)
		(end 360.996484 -376.75693)
		(width 0.14224)
		(layer "In15.Cu")
		(net "P5E_CPU0_P0_RX_DP<14>")
	)
	(segment
		(start 321.340226 -392.43)
		(end 321.340226 -391.091928)
		(width 0.14224)
		(layer "In15.Cu")
		(net "P5E_CPU0_P0_RX_DP<14>")
	)
	(segment
		(start 358.50195 -293.89832)
		(end 358.463088 -293.871396)
		(width 0.1143)
		(layer "In15.Cu")
		(net "P5E_CPU0_P0_RX_DP<14>")
	)
	(segment
		(start 358.42448 -279.26919)
		(end 358.423972 -279.268682)
		(width 0.1143)
		(layer "In15.Cu")
		(net "P5E_CPU0_P0_RX_DP<14>")
	)
	(segment
		(start 321.446398 -390.835642)
		(end 325.444866 -386.837174)
		(width 0.14224)
		(layer "In15.Cu")
		(net "P5E_CPU0_P0_RX_DP<14>")
	)
	(segment
		(start 358.392222 -281.882342)
		(end 358.463088 -281.840686)
		(width 0.1143)
		(layer "In15.Cu")
		(net "P5E_CPU0_P0_RX_DP<14>")
	)
	(segment
		(start 381.612902 -375.73585)
		(end 381.920242 -376.04319)
		(width 0.14224)
		(layer "In15.Cu")
		(net "P5E_CPU0_P0_RX_DP<14>")
	)
	(segment
		(start 358.417876 -277.007066)
		(end 358.422448 -277.004526)
		(width 0.1143)
		(layer "In15.Cu")
		(net "P5E_CPU0_P0_RX_DP<14>")
	)
	(segment
		(start 358.393492 -280.261314)
		(end 358.417876 -280.24709)
		(width 0.1143)
		(layer "In15.Cu")
		(net "P5E_CPU0_P0_RX_DP<14>")
	)
	(segment
		(start 380.756922 -375.73585)
		(end 380.756922 -373.90959)
		(width 0.14224)
		(layer "In15.Cu")
		(net "P5E_CPU0_P0_RX_DP<14>")
	)
	(segment
		(start 387.51129 -373.89435)
		(end 387.51129 -374.49633)
		(width 0.14224)
		(layer "In15.Cu")
		(net "P5E_CPU0_P0_RX_DP<14>")
	)
	(segment
		(start 358.393492 -275.401278)
		(end 358.463088 -275.360638)
		(width 0.1143)
		(layer "In15.Cu")
		(net "P5E_CPU0_P0_RX_DP<14>")
	)
	(segment
		(start 358.281986 -295.81348)
		(end 358.236266 -295.76776)
		(width 0.1143)
		(layer "In15.Cu")
		(net "P5E_CPU0_P0_RX_DP<14>")
	)
	(segment
		(start 357.373174 -270.846042)
		(end 357.671116 -270.846042)
		(width 0.1143)
		(layer "In15.Cu")
		(net "P5E_CPU0_P0_RX_DP<14>")
	)
	(segment
		(start 358.460548 -287.389824)
		(end 358.393492 -287.350708)
		(width 0.1143)
		(layer "In15.Cu")
		(net "P5E_CPU0_P0_RX_DP<14>")
	)
	(segment
		(start 380.899162 -373.76735)
		(end 387.38429 -373.76735)
		(width 0.14224)
		(layer "In15.Cu")
		(net "P5E_CPU0_P0_RX_DP<14>")
	)
	(segment
		(start 358.423972 -289.963352)
		(end 358.460294 -289.94227)
		(width 0.1143)
		(layer "In15.Cu")
		(net "P5E_CPU0_P0_RX_DP<14>")
	)
	(segment
		(start 358.393492 -289.981132)
		(end 358.423972 -289.963352)
		(width 0.1143)
		(layer "In15.Cu")
		(net "P5E_CPU0_P0_RX_DP<14>")
	)
	(segment
		(start 362.9533 -376.89917)
		(end 361.138724 -376.89917)
		(width 0.14224)
		(layer "In15.Cu")
		(net "P5E_CPU0_P0_RX_DP<14>")
	)
	(segment
		(start 358.393492 -277.02129)
		(end 358.417876 -277.007066)
		(width 0.1143)
		(layer "In15.Cu")
		(net "P5E_CPU0_P0_RX_DP<14>")
	)
	(segment
		(start 358.394254 -290.59124)
		(end 358.393492 -290.590732)
		(width 0.1143)
		(layer "In15.Cu")
		(net "P5E_CPU0_P0_RX_DP<14>")
	)
	(segment
		(start 358.417876 -280.24709)
		(end 358.422448 -280.24455)
		(width 0.1143)
		(layer "In15.Cu")
		(net "P5E_CPU0_P0_RX_DP<14>")
	)
	(segment
		(start 358.39146 -286.742378)
		(end 358.47782 -286.692086)
		(width 0.1143)
		(layer "In15.Cu")
		(net "P5E_CPU0_P0_RX_DP<14>")
	)
	(segment
		(start 358.42194 -278.630634)
		(end 358.426258 -278.628094)
		(width 0.1143)
		(layer "In15.Cu")
		(net "P5E_CPU0_P0_RX_DP<14>")
	)
	(segment
		(start 358.393492 -294.841168)
		(end 358.423972 -294.823388)
		(width 0.1143)
		(layer "In15.Cu")
		(net "P5E_CPU0_P0_RX_DP<14>")
	)
	(segment
		(start 358.423972 -280.243534)
		(end 358.42448 -280.243026)
		(width 0.1143)
		(layer "In15.Cu")
		(net "P5E_CPU0_P0_RX_DP<14>")
	)
	(segment
		(start 358.392222 -285.122366)
		(end 358.464358 -285.079948)
		(width 0.1143)
		(layer "In15.Cu")
		(net "P5E_CPU0_P0_RX_DP<14>")
	)
	(segment
		(start 358.42321 -288.344102)
		(end 358.423972 -288.343594)
		(width 0.1143)
		(layer "In15.Cu")
		(net "P5E_CPU0_P0_RX_DP<14>")
	)
	(segment
		(start 358.393492 -273.781266)
		(end 358.464104 -273.740372)
		(width 0.1143)
		(layer "In15.Cu")
		(net "P5E_CPU0_P0_RX_DP<14>")
	)
	(segment
		(start 358.42448 -276.029166)
		(end 358.423972 -276.028658)
		(width 0.1143)
		(layer "In15.Cu")
		(net "P5E_CPU0_P0_RX_DP<14>")
	)
	(segment
		(start 333.079852 -376.04319)
		(end 359.434384 -376.04319)
		(width 0.14224)
		(layer "In15.Cu")
		(net "P5E_CPU0_P0_RX_DP<14>")
	)
	(segment
		(start 358.423972 -285.74873)
		(end 358.393492 -285.73095)
		(width 0.1143)
		(layer "In15.Cu")
		(net "P5E_CPU0_P0_RX_DP<14>")
	)
	(segment
		(start 321.348354 -393.842494)
		(end 321.348354 -393.428982)
		(width 0.14224)
		(layer "In15.Cu")
		(net "P5E_CPU0_P0_RX_DP<14>")
	)
	(segment
		(start 358.394254 -283.50083)
		(end 358.460294 -283.462476)
		(width 0.1143)
		(layer "In15.Cu")
		(net "P5E_CPU0_P0_RX_DP<14>")
	)
	(segment
		(start 358.70642 -274.896072)
		(end 358.706166 -274.896072)
		(width 0.1143)
		(layer "In15.Cu")
		(net "P5E_CPU0_P0_RX_DP<14>")
	)
	(segment
		(start 325.76516 -386.063744)
		(end 325.76516 -383.347976)
		(width 0.14224)
		(layer "In15.Cu")
		(net "P5E_CPU0_P0_RX_DP<14>")
	)
	(segment
		(start 387.51129 -374.49633)
		(end 387.38429 -374.62333)
		(width 0.14224)
		(layer "In15.Cu")
		(net "P5E_CPU0_P0_RX_DP<14>")
	)
	(segment
		(start 359.434384 -376.04319)
		(end 359.576624 -376.18543)
		(width 0.14224)
		(layer "In15.Cu")
		(net "P5E_CPU0_P0_RX_DP<14>")
	)
	(segment
		(start 358.424226 -293.203376)
		(end 358.425242 -293.202868)
		(width 0.1143)
		(layer "In15.Cu")
		(net "P5E_CPU0_P0_RX_DP<14>")
	)
	(segment
		(start 358.393492 -272.7706)
		(end 358.393492 -272.770854)
		(width 0.1143)
		(layer "In15.Cu")
		(net "P5E_CPU0_P0_RX_DP<14>")
	)
	(segment
		(start 387.38429 -374.62333)
		(end 381.920242 -374.62333)
		(width 0.14224)
		(layer "In15.Cu")
		(net "P5E_CPU0_P0_RX_DP<14>")
	)
	(segment
		(start 358.460294 -284.1498)
		(end 358.393492 -284.110938)
		(width 0.1143)
		(layer "In15.Cu")
		(net "P5E_CPU0_P0_RX_DP<14>")
	)
	(segment
		(start 358.393492 -291.601144)
		(end 358.423972 -291.583364)
		(width 0.1143)
		(layer "In15.Cu")
		(net "P5E_CPU0_P0_RX_DP<14>")
	)
	(segment
		(start 392.665458 -373.062246)
		(end 396.426182 -373.062246)
		(width 0.14224)
		(layer "In15.Cu")
		(net "P5E_CPU0_P0_RX_DP<14>")
	)
	(segment
		(start 358.445308 -293.19093)
		(end 358.445562 -293.19093)
		(width 0.1143)
		(layer "In15.Cu")
		(net "P5E_CPU0_P0_RX_DP<14>")
	)
	(segment
		(start 358.424226 -285.74873)
		(end 358.423972 -285.74873)
		(width 0.1143)
		(layer "In15.Cu")
		(net "P5E_CPU0_P0_RX_DP<14>")
	)
	(segment
		(start 358.421432 -288.345118)
		(end 358.422194 -288.34461)
		(width 0.1143)
		(layer "In15.Cu")
		(net "P5E_CPU0_P0_RX_DP<14>")
	)
	(segment
		(start 357.484172 -271.168622)
		(end 357.452422 -271.150334)
		(width 0.1143)
		(layer "In15.Cu")
		(net "P5E_CPU0_P0_RX_DP<14>")
	)
	(segment
		(start 358.424226 -288.343086)
		(end 358.46385 -288.319972)
		(width 0.1143)
		(layer "In15.Cu")
		(net "P5E_CPU0_P0_RX_DP<14>")
	)
	(segment
		(start 358.423972 -291.583364)
		(end 358.460294 -291.562282)
		(width 0.1143)
		(layer "In15.Cu")
		(net "P5E_CPU0_P0_RX_DP<14>")
	)
	(segment
		(start 359.576624 -378.01169)
		(end 359.883964 -378.31903)
		(width 0.14224)
		(layer "In15.Cu")
		(net "P5E_CPU0_P0_RX_DP<14>")
	)
	(segment
		(start 358.70642 -292.71595)
		(end 358.706166 -292.71595)
		(width 0.1143)
		(layer "In15.Cu")
		(net "P5E_CPU0_P0_RX_DP<14>")
	)
	(segment
		(start 321.260216 -393.930632)
		(end 321.348354 -393.842494)
		(width 0.14224)
		(layer "In15.Cu")
		(net "P5E_CPU0_P0_RX_DP<14>")
	)
	(segment
		(start 357.520494 -271.189704)
		(end 357.484172 -271.168622)
		(width 0.1143)
		(layer "In15.Cu")
		(net "P5E_CPU0_P0_RX_DP<14>")
	)
	(segment
		(start 399.767298 -369.529614)
		(end 399.767298 -354.707952)
		(width 0.14224)
		(layer "In15.Cu")
		(net "P5E_CPU0_P0_RX_DP<14>")
	)
	(segment
		(start 357.303324 -270.915892)
		(end 357.373174 -270.846042)
		(width 0.1143)
		(layer "In15.Cu")
		(net "P5E_CPU0_P0_RX_DP<14>")
	)
	(segment
		(start 358.422194 -288.34461)
		(end 358.42321 -288.344102)
		(width 0.1143)
		(layer "In15.Cu")
		(net "P5E_CPU0_P0_RX_DP<14>")
	)
	(segment
		(start 358.39146 -288.36239)
		(end 358.420416 -288.345626)
		(width 0.1143)
		(layer "In15.Cu")
		(net "P5E_CPU0_P0_RX_DP<14>")
	)
	(segment
		(start 363.26064 -377.20651)
		(end 362.9533 -376.89917)
		(width 0.14224)
		(layer "In15.Cu")
		(net "P5E_CPU0_P0_RX_DP<14>")
	)
	(segment
		(start 329.530964 -379.282706)
		(end 332.632558 -376.181112)
		(width 0.14224)
		(layer "In15.Cu")
		(net "P5E_CPU0_P0_RX_DP<14>")
	)
	(segment
		(start 358.424226 -285.748984)
		(end 358.424226 -285.74873)
		(width 0.1143)
		(layer "In15.Cu")
		(net "P5E_CPU0_P0_RX_DP<14>")
	)
	(segment
		(start 358.456484 -293.184326)
		(end 358.463088 -293.180516)
		(width 0.1143)
		(layer "In15.Cu")
		(net "P5E_CPU0_P0_RX_DP<14>")
	)
	(segment
		(start 359.576624 -376.18543)
		(end 359.576624 -378.01169)
		(width 0.14224)
		(layer "In15.Cu")
		(net "P5E_CPU0_P0_RX_DP<14>")
	)
	(segment
		(start 321.035426 -392.7348)
		(end 321.340226 -392.43)
		(width 0.14224)
		(layer "In15.Cu")
		(net "P5E_CPU0_P0_RX_DP<14>")
	)
	(segment
		(start 396.715488 -372.942358)
		(end 399.512028 -370.145818)
		(width 0.14224)
		(layer "In15.Cu")
		(net "P5E_CPU0_P0_RX_DP<14>")
	)
	(segment
		(start 358.473502 -272.81886)
		(end 358.464358 -272.812002)
		(width 0.1143)
		(layer "In15.Cu")
		(net "P5E_CPU0_P0_RX_DP<14>")
	)
	(segment
		(start 381.920242 -376.04319)
		(end 388.30377 -376.04319)
		(width 0.14224)
		(layer "In15.Cu")
		(net "P5E_CPU0_P0_RX_DP<14>")
	)
	(segment
		(start 358.461564 -293.87038)
		(end 358.416098 -293.84371)
		(width 0.1143)
		(layer "In15.Cu")
		(net "P5E_CPU0_P0_RX_DP<14>")
	)
	(segment
		(start 358.423972 -292.228524)
		(end 358.393492 -292.210744)
		(width 0.1143)
		(layer "In15.Cu")
		(net "P5E_CPU0_P0_RX_DP<14>")
	)
	(segment
		(start 358.47147 -292.257226)
		(end 358.423972 -292.228524)
		(width 0.1143)
		(layer "In15.Cu")
		(net "P5E_CPU0_P0_RX_DP<14>")
	)
	(segment
		(start 358.281986 -295.841928)
		(end 358.281986 -295.81348)
		(width 0.1143)
		(layer "In15.Cu")
		(net "P5E_CPU0_P0_RX_DP<14>")
	)
	(segment
		(start 358.423972 -276.028658)
		(end 358.395778 -276.012148)
		(width 0.1143)
		(layer "In15.Cu")
		(net "P5E_CPU0_P0_RX_DP<14>")
	)
	(segment
		(start 358.425242 -293.202868)
		(end 358.445308 -293.19093)
		(width 0.1143)
		(layer "In15.Cu")
		(net "P5E_CPU0_P0_RX_DP<14>")
	)
	(segment
		(start 361.138724 -376.04319)
		(end 380.449582 -376.04319)
		(width 0.14224)
		(layer "In15.Cu")
		(net "P5E_CPU0_P0_RX_DP<14>")
	)
	(segment
		(start 321.348354 -393.428982)
		(end 321.032378 -393.113006)
		(width 0.14224)
		(layer "In15.Cu")
		(net "P5E_CPU0_P0_RX_DP<14>")
	)
	(segment
		(start 358.706166 -274.896072)
		(end 358.706166 -274.8915)
		(width 0.1143)
		(layer "In15.Cu")
		(net "P5E_CPU0_P0_RX_DP<14>")
	)
	(segment
		(start 389.859012 -375.399046)
		(end 391.86358 -373.394478)
		(width 0.14224)
		(layer "In15.Cu")
		(net "P5E_CPU0_P0_RX_DP<14>")
	)
	(segment
		(start 358.393238 -294.841168)
		(end 358.393492 -294.841168)
		(width 0.1143)
		(layer "In15.Cu")
		(net "P5E_CPU0_P0_RX_DP<14>")
	)
	(segment
		(start 358.422448 -280.24455)
		(end 358.423972 -280.243534)
		(width 0.1143)
		(layer "In15.Cu")
		(net "P5E_CPU0_P0_RX_DP<14>")
	)
	(segment
		(start 398.709388 -352.153982)
		(end 370.996718 -324.441058)
		(width 0.14224)
		(layer "In15.Cu")
		(net "P5E_CPU0_P0_RX_DP<14>")
	)
	(segment
		(start 358.47782 -286.692086)
		(end 358.486456 -286.68345)
		(width 0.1143)
		(layer "In15.Cu")
		(net "P5E_CPU0_P0_RX_DP<14>")
	)
	(segment
		(start 381.612902 -374.93067)
		(end 381.612902 -375.73585)
		(width 0.14224)
		(layer "In15.Cu")
		(net "P5E_CPU0_P0_RX_DP<14>")
	)
	(segment
		(start 325.976996 -382.83642)
		(end 329.530964 -379.282452)
		(width 0.14224)
		(layer "In15.Cu")
		(net "P5E_CPU0_P0_RX_DP<14>")
	)
	(segment
		(start 358.460294 -290.629594)
		(end 358.394254 -290.59124)
		(width 0.1143)
		(layer "In15.Cu")
		(net "P5E_CPU0_P0_RX_DP<14>")
	)
	(segment
		(start 358.460294 -282.529788)
		(end 358.393492 -282.490926)
		(width 0.1143)
		(layer "In15.Cu")
		(net "P5E_CPU0_P0_RX_DP<14>")
	)
	(segment
		(start 320.990976 -394.385292)
		(end 321.085972 -394.031216)
		(width 0.14224)
		(layer "In15.Cu")
		(net "P5E_CPU0_P0_RX_DP<14>")
	)
	(arc
		(start 332.887066 -376.055636)
		(mid 332.983258 -376.046308)
		(end 333.079852 -376.04319)
		(width 0.14224)
		(layer "In15.Cu")
		(net "P5E_CPU0_P0_RX_DP<14>")
	)
	(arc
		(start 358.393492 -287.350708)
		(mid 358.278065 -287.217332)
		(end 358.23652 -287.045908)
		(width 0.1143)
		(layer "In15.Cu")
		(net "P5E_CPU0_P0_RX_DP<14>")
	)
	(arc
		(start 358.236266 -272.466054)
		(mid 358.171878 -272.203761)
		(end 357.993188 -272.001234)
		(width 0.1143)
		(layer "In15.Cu")
		(net "P5E_CPU0_P0_RX_DP<14>")
	)
	(arc
		(start 358.706166 -292.702742)
		(mid 358.643962 -292.450933)
		(end 358.47147 -292.257226)
		(width 0.1143)
		(layer "In15.Cu")
		(net "P5E_CPU0_P0_RX_DP<14>")
	)
	(arc
		(start 358.393492 -292.210744)
		(mid 358.236515 -291.905944)
		(end 358.393492 -291.601144)
		(width 0.1143)
		(layer "In15.Cu")
		(net "P5E_CPU0_P0_RX_DP<14>")
	)
	(arc
		(start 357.452422 -271.150334)
		(mid 357.355287 -271.047465)
		(end 357.303324 -270.915892)
		(width 0.1143)
		(layer "In15.Cu")
		(net "P5E_CPU0_P0_RX_DP<14>")
	)
	(arc
		(start 358.460294 -289.94227)
		(mid 358.706184 -289.475926)
		(end 358.460294 -289.009582)
		(width 0.1143)
		(layer "In15.Cu")
		(net "P5E_CPU0_P0_RX_DP<14>")
	)
	(arc
		(start 358.426258 -278.628094)
		(mid 358.70704 -278.159935)
		(end 358.463088 -277.67153)
		(width 0.1143)
		(layer "In15.Cu")
		(net "P5E_CPU0_P0_RX_DP<14>")
	)
	(arc
		(start 396.426182 -373.062246)
		(mid 396.58276 -373.031083)
		(end 396.715488 -372.942358)
		(width 0.14224)
		(layer "In15.Cu")
		(net "P5E_CPU0_P0_RX_DP<14>")
	)
	(arc
		(start 358.464104 -273.740372)
		(mid 358.642456 -273.538014)
		(end 358.706674 -273.27606)
		(width 0.1143)
		(layer "In15.Cu")
		(net "P5E_CPU0_P0_RX_DP<14>")
	)
	(arc
		(start 332.632558 -376.181112)
		(mid 332.749439 -376.097339)
		(end 332.887066 -376.055636)
		(width 0.14224)
		(layer "In15.Cu")
		(net "P5E_CPU0_P0_RX_DP<14>")
	)
	(arc
		(start 358.393492 -288.97072)
		(mid 358.278065 -288.837344)
		(end 358.23652 -288.66592)
		(width 0.1143)
		(layer "In15.Cu")
		(net "P5E_CPU0_P0_RX_DP<14>")
	)
	(arc
		(start 358.393492 -280.870914)
		(mid 358.236515 -280.566114)
		(end 358.393492 -280.261314)
		(width 0.1143)
		(layer "In15.Cu")
		(net "P5E_CPU0_P0_RX_DP<14>")
	)
	(arc
		(start 357.766366 -271.641062)
		(mid 357.700746 -271.391544)
		(end 357.531162 -271.19707)
		(width 0.1143)
		(layer "In15.Cu")
		(net "P5E_CPU0_P0_RX_DP<14>")
	)
	(arc
		(start 325.444866 -386.837174)
		(mid 325.681917 -386.482307)
		(end 325.76516 -386.063744)
		(width 0.14224)
		(layer "In15.Cu")
		(net "P5E_CPU0_P0_RX_DP<14>")
	)
	(arc
		(start 370.996718 -324.441058)
		(mid 370.916423 -324.350438)
		(end 370.84762 -324.250812)
		(width 0.14224)
		(layer "In15.Cu")
		(net "P5E_CPU0_P0_RX_DP<14>")
	)
	(arc
		(start 321.340226 -391.091928)
		(mid 321.367816 -390.953221)
		(end 321.446398 -390.835642)
		(width 0.14224)
		(layer "In15.Cu")
		(net "P5E_CPU0_P0_RX_DP<14>")
	)
	(arc
		(start 358.393492 -290.590732)
		(mid 358.236515 -290.285932)
		(end 358.393492 -289.981132)
		(width 0.1143)
		(layer "In15.Cu")
		(net "P5E_CPU0_P0_RX_DP<14>")
	)
	(arc
		(start 358.23652 -288.66592)
		(mid 358.277486 -288.495514)
		(end 358.39146 -288.36239)
		(width 0.1143)
		(layer "In15.Cu")
		(net "P5E_CPU0_P0_RX_DP<14>")
	)
	(arc
		(start 358.46385 -288.319972)
		(mid 358.630416 -288.113064)
		(end 358.706166 -287.858454)
		(width 0.1143)
		(layer "In15.Cu")
		(net "P5E_CPU0_P0_RX_DP<14>")
	)
	(arc
		(start 358.706166 -284.616144)
		(mid 358.64093 -284.352553)
		(end 358.460294 -284.1498)
		(width 0.1143)
		(layer "In15.Cu")
		(net "P5E_CPU0_P0_RX_DP<14>")
	)
	(arc
		(start 358.705912 -292.737032)
		(mid 358.706264 -292.726493)
		(end 358.70642 -292.71595)
		(width 0.1143)
		(layer "In15.Cu")
		(net "P5E_CPU0_P0_RX_DP<14>")
	)
	(arc
		(start 358.393492 -285.73095)
		(mid 358.236622 -285.426962)
		(end 358.392222 -285.122366)
		(width 0.1143)
		(layer "In15.Cu")
		(net "P5E_CPU0_P0_RX_DP<14>")
	)
	(arc
		(start 358.359456 -303.61001)
		(mid 358.301725 -303.476629)
		(end 358.281986 -303.332642)
		(width 0.14224)
		(layer "In15.Cu")
		(net "P5E_CPU0_P0_RX_DP<14>")
	)
	(arc
		(start 358.48417 -285.065216)
		(mid 358.638729 -284.87179)
		(end 358.705658 -284.633416)
		(width 0.1143)
		(layer "In15.Cu")
		(net "P5E_CPU0_P0_RX_DP<14>")
	)
	(arc
		(start 358.706166 -274.8915)
		(mid 358.642091 -274.632056)
		(end 358.464358 -274.432522)
		(width 0.1143)
		(layer "In15.Cu")
		(net "P5E_CPU0_P0_RX_DP<14>")
	)
	(arc
		(start 391.86358 -373.394478)
		(mid 392.231471 -373.148598)
		(end 392.665458 -373.062246)
		(width 0.14224)
		(layer "In15.Cu")
		(net "P5E_CPU0_P0_RX_DP<14>")
	)
	(arc
		(start 358.393492 -284.110938)
		(mid 358.236515 -283.806138)
		(end 358.393492 -283.501338)
		(width 0.1143)
		(layer "In15.Cu")
		(net "P5E_CPU0_P0_RX_DP<14>")
	)
	(arc
		(start 358.463088 -293.180516)
		(mid 358.636921 -292.987462)
		(end 358.705912 -292.737032)
		(width 0.1143)
		(layer "In15.Cu")
		(net "P5E_CPU0_P0_RX_DP<14>")
	)
	(arc
		(start 358.23652 -287.045908)
		(mid 358.277486 -286.875502)
		(end 358.39146 -286.742378)
		(width 0.1143)
		(layer "In15.Cu")
		(net "P5E_CPU0_P0_RX_DP<14>")
	)
	(arc
		(start 358.705912 -274.917154)
		(mid 358.706264 -274.906615)
		(end 358.70642 -274.896072)
		(width 0.1143)
		(layer "In15.Cu")
		(net "P5E_CPU0_P0_RX_DP<14>")
	)
	(arc
		(start 358.50195 -294.773604)
		(mid 358.731128 -294.335962)
		(end 358.50195 -293.89832)
		(width 0.1143)
		(layer "In15.Cu")
		(net "P5E_CPU0_P0_RX_DP<14>")
	)
	(arc
		(start 357.531162 -271.19707)
		(mid 357.525848 -271.193358)
		(end 357.520494 -271.189704)
		(width 0.1143)
		(layer "In15.Cu")
		(net "P5E_CPU0_P0_RX_DP<14>")
	)
	(arc
		(start 358.393492 -272.770854)
		(mid 358.277973 -272.637497)
		(end 358.236266 -272.466054)
		(width 0.1143)
		(layer "In15.Cu")
		(net "P5E_CPU0_P0_RX_DP<14>")
	)
	(arc
		(start 399.512028 -370.145818)
		(mid 399.700933 -369.863101)
		(end 399.767298 -369.529614)
		(width 0.14224)
		(layer "In15.Cu")
		(net "P5E_CPU0_P0_RX_DP<14>")
	)
	(arc
		(start 358.42448 -277.003002)
		(mid 358.703931 -276.516084)
		(end 358.42448 -276.029166)
		(width 0.1143)
		(layer "In15.Cu")
		(net "P5E_CPU0_P0_RX_DP<14>")
	)
	(arc
		(start 358.460294 -283.462476)
		(mid 358.706184 -282.996132)
		(end 358.460294 -282.529788)
		(width 0.1143)
		(layer "In15.Cu")
		(net "P5E_CPU0_P0_RX_DP<14>")
	)
	(arc
		(start 399.767298 -354.707952)
		(mid 399.49236 -353.325745)
		(end 398.709388 -352.153982)
		(width 0.14224)
		(layer "In15.Cu")
		(net "P5E_CPU0_P0_RX_DP<14>")
	)
	(arc
		(start 358.705658 -284.633416)
		(mid 358.705917 -284.631004)
		(end 358.706166 -284.62859)
		(width 0.1143)
		(layer "In15.Cu")
		(net "P5E_CPU0_P0_RX_DP<14>")
	)
	(arc
		(start 358.706674 -273.27606)
		(mid 358.705706 -273.243493)
		(end 358.702864 -273.211036)
		(width 0.1143)
		(layer "In15.Cu")
		(net "P5E_CPU0_P0_RX_DP<14>")
	)
	(arc
		(start 358.463088 -281.840686)
		(mid 358.469084 -281.836533)
		(end 358.475026 -281.832304)
		(width 0.1143)
		(layer "In15.Cu")
		(net "P5E_CPU0_P0_RX_DP<14>")
	)
	(arc
		(start 358.236266 -295.145968)
		(mid 358.277815 -294.974546)
		(end 358.393238 -294.841168)
		(width 0.1143)
		(layer "In15.Cu")
		(net "P5E_CPU0_P0_RX_DP<14>")
	)
	(arc
		(start 358.706166 -287.858454)
		(mid 358.705306 -287.824106)
		(end 358.702356 -287.789874)
		(width 0.1143)
		(layer "In15.Cu")
		(net "P5E_CPU0_P0_RX_DP<14>")
	)
	(arc
		(start 325.76516 -383.347976)
		(mid 325.82021 -383.071132)
		(end 325.976996 -382.83642)
		(width 0.14224)
		(layer "In15.Cu")
		(net "P5E_CPU0_P0_RX_DP<14>")
	)
	(arc
		(start 357.930958 -271.965166)
		(mid 357.822758 -271.829764)
		(end 357.768398 -271.665192)
		(width 0.1143)
		(layer "In15.Cu")
		(net "P5E_CPU0_P0_RX_DP<14>")
	)
	(arc
		(start 358.393492 -279.250902)
		(mid 358.238832 -278.933001)
		(end 358.42194 -278.630634)
		(width 0.1143)
		(layer "In15.Cu")
		(net "P5E_CPU0_P0_RX_DP<14>")
	)
	(arc
		(start 358.393492 -276.010878)
		(mid 358.236515 -275.706078)
		(end 358.393492 -275.401278)
		(width 0.1143)
		(layer "In15.Cu")
		(net "P5E_CPU0_P0_RX_DP<14>")
	)
	(arc
		(start 358.486456 -286.68345)
		(mid 358.648266 -286.485607)
		(end 358.706166 -286.236664)
		(width 0.1143)
		(layer "In15.Cu")
		(net "P5E_CPU0_P0_RX_DP<14>")
	)
	(arc
		(start 358.702864 -273.211036)
		(mid 358.629767 -272.990621)
		(end 358.473502 -272.81886)
		(width 0.1143)
		(layer "In15.Cu")
		(net "P5E_CPU0_P0_RX_DP<14>")
	)
	(arc
		(start 358.393492 -282.490926)
		(mid 358.236622 -282.186938)
		(end 358.392222 -281.882342)
		(width 0.1143)
		(layer "In15.Cu")
		(net "P5E_CPU0_P0_RX_DP<14>")
	)
	(arc
		(start 358.460294 -291.562282)
		(mid 358.706184 -291.095938)
		(end 358.460294 -290.629594)
		(width 0.1143)
		(layer "In15.Cu")
		(net "P5E_CPU0_P0_RX_DP<14>")
	)
	(arc
		(start 358.702356 -287.789874)
		(mid 358.624792 -287.563639)
		(end 358.460548 -287.389824)
		(width 0.1143)
		(layer "In15.Cu")
		(net "P5E_CPU0_P0_RX_DP<14>")
	)
	(arc
		(start 358.463088 -275.360638)
		(mid 358.636921 -275.167584)
		(end 358.705912 -274.917154)
		(width 0.1143)
		(layer "In15.Cu")
		(net "P5E_CPU0_P0_RX_DP<14>")
	)
	(arc
		(start 358.393492 -274.390866)
		(mid 358.236515 -274.086066)
		(end 358.393492 -273.781266)
		(width 0.1143)
		(layer "In15.Cu")
		(net "P5E_CPU0_P0_RX_DP<14>")
	)
	(arc
		(start 388.30377 -376.04319)
		(mid 389.145453 -375.875787)
		(end 389.859012 -375.399046)
		(width 0.14224)
		(layer "In15.Cu")
		(net "P5E_CPU0_P0_RX_DP<14>")
	)
	(arc
		(start 358.42448 -280.243026)
		(mid 358.703931 -279.756108)
		(end 358.42448 -279.26919)
		(width 0.1143)
		(layer "In15.Cu")
		(net "P5E_CPU0_P0_RX_DP<14>")
	)
	(arc
		(start 358.463088 -293.871396)
		(mid 358.462326 -293.870887)
		(end 358.461564 -293.87038)
		(width 0.1143)
		(layer "In15.Cu")
		(net "P5E_CPU0_P0_RX_DP<14>")
	)
	(arc
		(start 358.393492 -277.63089)
		(mid 358.236515 -277.32609)
		(end 358.393492 -277.02129)
		(width 0.1143)
		(layer "In15.Cu")
		(net "P5E_CPU0_P0_RX_DP<14>")
	)
	(arc
		(start 357.768398 -271.665192)
		(mid 357.767089 -271.653152)
		(end 357.766366 -271.641062)
		(width 0.1143)
		(layer "In15.Cu")
		(net "P5E_CPU0_P0_RX_DP<14>")
	)
	(arc
		(start 358.706166 -286.236156)
		(mid 358.641348 -285.973167)
		(end 358.461564 -285.770574)
		(width 0.1143)
		(layer "In15.Cu")
		(net "P5E_CPU0_P0_RX_DP<14>")
	)
	(arc
		(start 358.475026 -280.919936)
		(mid 358.469084 -280.915706)
		(end 358.463088 -280.911554)
		(width 0.1143)
		(layer "In15.Cu")
		(net "P5E_CPU0_P0_RX_DP<14>")
	)
	(arc
		(start 358.464358 -285.079948)
		(mid 358.474345 -285.072691)
		(end 358.48417 -285.065216)
		(width 0.1143)
		(layer "In15.Cu")
		(net "P5E_CPU0_P0_RX_DP<14>")
	)
	(arc
		(start 358.416098 -293.84371)
		(mid 358.23919 -293.521229)
		(end 358.424226 -293.203376)
		(width 0.1143)
		(layer "In15.Cu")
		(net "P5E_CPU0_P0_RX_DP<14>")
	)
	(arc
		(start 358.475026 -281.832304)
		(mid 358.703423 -281.37612)
		(end 358.475026 -280.919936)
		(width 0.1143)
		(layer "In15.Cu")
		(net "P5E_CPU0_P0_RX_DP<14>")
	)
	(segment
		(start 358.137968 -273.820128)
		(end 357.671116 -274.086066)
		(width 0.12954)
		(layer "F.Cu")
		(net "P5E_CPU0_P0_RX_DP<13>")
	)
	(segment
		(start 319.27038 -394.385292)
		(end 319.79108 -394.385292)
		(width 0.127)
		(layer "F.Cu")
		(net "P5E_CPU0_P0_RX_DP<13>")
	)
	(segment
		(start 398.149318 -367.812066)
		(end 398.149318 -353.520502)
		(width 0.14224)
		(layer "In15.Cu")
		(net "P5E_CPU0_P0_RX_DP<13>")
	)
	(segment
		(start 357.453946 -288.970974)
		(end 357.452676 -288.970212)
		(width 0.1143)
		(layer "In15.Cu")
		(net "P5E_CPU0_P0_RX_DP<13>")
	)
	(segment
		(start 357.47579 -292.223698)
		(end 357.47198 -292.221412)
		(width 0.1143)
		(layer "In15.Cu")
		(net "P5E_CPU0_P0_RX_DP<13>")
	)
	(segment
		(start 357.471472 -280.881328)
		(end 357.469694 -280.880312)
		(width 0.1143)
		(layer "In15.Cu")
		(net "P5E_CPU0_P0_RX_DP<13>")
	)
	(segment
		(start 324.69328 -382.489964)
		(end 332.116684 -375.06656)
		(width 0.14224)
		(layer "In15.Cu")
		(net "P5E_CPU0_P0_RX_DP<13>")
	)
	(segment
		(start 357.505508 -279.281128)
		(end 357.452422 -279.250394)
		(width 0.1143)
		(layer "In15.Cu")
		(net "P5E_CPU0_P0_RX_DP<13>")
	)
	(segment
		(start 357.493062 -293.198296)
		(end 357.494332 -293.197534)
		(width 0.1143)
		(layer "In15.Cu")
		(net "P5E_CPU0_P0_RX_DP<13>")
	)
	(segment
		(start 319.79108 -394.385292)
		(end 319.886076 -394.031216)
		(width 0.14224)
		(layer "In15.Cu")
		(net "P5E_CPU0_P0_RX_DP<13>")
	)
	(segment
		(start 357.537766 -289.930332)
		(end 357.556308 -289.916362)
		(width 0.1143)
		(layer "In15.Cu")
		(net "P5E_CPU0_P0_RX_DP<13>")
	)
	(segment
		(start 332.634844 -374.85193)
		(end 379.487684 -374.85193)
		(width 0.14224)
		(layer "In15.Cu")
		(net "P5E_CPU0_P0_RX_DP<13>")
	)
	(segment
		(start 320.14033 -392.43)
		(end 320.14033 -390.293352)
		(width 0.14224)
		(layer "In15.Cu")
		(net "P5E_CPU0_P0_RX_DP<13>")
	)
	(segment
		(start 357.464106 -288.97707)
		(end 357.457502 -288.973006)
		(width 0.1143)
		(layer "In15.Cu")
		(net "P5E_CPU0_P0_RX_DP<13>")
	)
	(segment
		(start 357.472996 -280.88209)
		(end 357.471472 -280.881328)
		(width 0.1143)
		(layer "In15.Cu")
		(net "P5E_CPU0_P0_RX_DP<13>")
	)
	(segment
		(start 357.452422 -283.501846)
		(end 357.484172 -283.483558)
		(width 0.1143)
		(layer "In15.Cu")
		(net "P5E_CPU0_P0_RX_DP<13>")
	)
	(segment
		(start 320.06032 -393.930632)
		(end 320.148458 -393.842494)
		(width 0.14224)
		(layer "In15.Cu")
		(net "P5E_CPU0_P0_RX_DP<13>")
	)
	(segment
		(start 369.003326 -323.86651)
		(end 368.024918 -322.142358)
		(width 0.14224)
		(layer "In15.Cu")
		(net "P5E_CPU0_P0_RX_DP<13>")
	)
	(segment
		(start 357.484172 -284.128718)
		(end 357.452422 -284.11043)
		(width 0.1143)
		(layer "In15.Cu")
		(net "P5E_CPU0_P0_RX_DP<13>")
	)
	(segment
		(start 357.555546 -292.277546)
		(end 357.487728 -292.230302)
		(width 0.1143)
		(layer "In15.Cu")
		(net "P5E_CPU0_P0_RX_DP<13>")
	)
	(segment
		(start 357.468932 -292.219634)
		(end 357.452676 -292.210236)
		(width 0.1143)
		(layer "In15.Cu")
		(net "P5E_CPU0_P0_RX_DP<13>")
	)
	(segment
		(start 357.520494 -277.669752)
		(end 357.484172 -277.64867)
		(width 0.1143)
		(layer "In15.Cu")
		(net "P5E_CPU0_P0_RX_DP<13>")
	)
	(segment
		(start 357.452422 -285.121858)
		(end 357.484172 -285.10357)
		(width 0.1143)
		(layer "In15.Cu")
		(net "P5E_CPU0_P0_RX_DP<13>")
	)
	(segment
		(start 379.70333 -372.57609)
		(end 381.765302 -370.514118)
		(width 0.14224)
		(layer "In15.Cu")
		(net "P5E_CPU0_P0_RX_DP<13>")
	)
	(segment
		(start 357.484172 -285.10357)
		(end 357.520494 -285.082488)
		(width 0.1143)
		(layer "In15.Cu")
		(net "P5E_CPU0_P0_RX_DP<13>")
	)
	(segment
		(start 357.303324 -274.155916)
		(end 357.373174 -274.086066)
		(width 0.1143)
		(layer "In15.Cu")
		(net "P5E_CPU0_P0_RX_DP<13>")
	)
	(segment
		(start 357.457502 -288.973006)
		(end 357.453946 -288.970974)
		(width 0.1143)
		(layer "In15.Cu")
		(net "P5E_CPU0_P0_RX_DP<13>")
	)
	(segment
		(start 357.486458 -293.201852)
		(end 357.487982 -293.20109)
		(width 0.1143)
		(layer "In15.Cu")
		(net "P5E_CPU0_P0_RX_DP<13>")
	)
	(segment
		(start 357.341932 -295.896538)
		(end 357.296212 -295.850818)
		(width 0.1143)
		(layer "In15.Cu")
		(net "P5E_CPU0_P0_RX_DP<13>")
	)
	(segment
		(start 381.765302 -370.514118)
		(end 395.21384 -370.514118)
		(width 0.14224)
		(layer "In15.Cu")
		(net "P5E_CPU0_P0_RX_DP<13>")
	)
	(segment
		(start 357.341932 -303.598072)
		(end 357.341932 -295.911016)
		(width 0.14224)
		(layer "In15.Cu")
		(net "P5E_CPU0_P0_RX_DP<13>")
	)
	(segment
		(start 357.484172 -277.64867)
		(end 357.452422 -277.630382)
		(width 0.1143)
		(layer "In15.Cu")
		(net "P5E_CPU0_P0_RX_DP<13>")
	)
	(segment
		(start 379.487684 -374.85193)
		(end 379.795024 -374.54459)
		(width 0.14224)
		(layer "In15.Cu")
		(net "P5E_CPU0_P0_RX_DP<13>")
	)
	(segment
		(start 357.467408 -293.213028)
		(end 357.486458 -293.201852)
		(width 0.1143)
		(layer "In15.Cu")
		(net "P5E_CPU0_P0_RX_DP<13>")
	)
	(segment
		(start 357.452422 -278.64181)
		(end 357.484172 -278.623522)
		(width 0.1143)
		(layer "In15.Cu")
		(net "P5E_CPU0_P0_RX_DP<13>")
	)
	(segment
		(start 379.795024 -373.73941)
		(end 379.487684 -373.43207)
		(width 0.14224)
		(layer "In15.Cu")
		(net "P5E_CPU0_P0_RX_DP<13>")
	)
	(segment
		(start 357.52278 -289.941)
		(end 357.532178 -289.934396)
		(width 0.1143)
		(layer "In15.Cu")
		(net "P5E_CPU0_P0_RX_DP<13>")
	)
	(segment
		(start 379.795024 -374.54459)
		(end 379.795024 -373.73941)
		(width 0.14224)
		(layer "In15.Cu")
		(net "P5E_CPU0_P0_RX_DP<13>")
	)
	(segment
		(start 357.434134 -293.234618)
		(end 357.452168 -293.221664)
		(width 0.1143)
		(layer "In15.Cu")
		(net "P5E_CPU0_P0_RX_DP<13>")
	)
	(segment
		(start 357.484172 -289.96386)
		(end 357.489506 -289.960304)
		(width 0.1143)
		(layer "In15.Cu")
		(net "P5E_CPU0_P0_RX_DP<13>")
	)
	(segment
		(start 357.47579 -291.58819)
		(end 357.484172 -291.583872)
		(width 0.1143)
		(layer "In15.Cu")
		(net "P5E_CPU0_P0_RX_DP<13>")
	)
	(segment
		(start 357.452422 -275.401786)
		(end 357.484172 -275.383498)
		(width 0.1143)
		(layer "In15.Cu")
		(net "P5E_CPU0_P0_RX_DP<13>")
	)
	(segment
		(start 319.83553 -392.7348)
		(end 320.14033 -392.43)
		(width 0.14224)
		(layer "In15.Cu")
		(net "P5E_CPU0_P0_RX_DP<13>")
	)
	(segment
		(start 357.52278 -293.181024)
		(end 357.550974 -293.160958)
		(width 0.1143)
		(layer "In15.Cu")
		(net "P5E_CPU0_P0_RX_DP<13>")
	)
	(segment
		(start 366.5982 -373.28983)
		(end 366.5982 -372.71833)
		(width 0.14224)
		(layer "In15.Cu")
		(net "P5E_CPU0_P0_RX_DP<13>")
	)
	(segment
		(start 357.448866 -286.744156)
		(end 357.451406 -286.742632)
		(width 0.1143)
		(layer "In15.Cu")
		(net "P5E_CPU0_P0_RX_DP<13>")
	)
	(segment
		(start 379.487684 -373.43207)
		(end 366.74044 -373.43207)
		(width 0.14224)
		(layer "In15.Cu")
		(net "P5E_CPU0_P0_RX_DP<13>")
	)
	(segment
		(start 357.490776 -290.612576)
		(end 357.484172 -290.608004)
		(width 0.1143)
		(layer "In15.Cu")
		(net "P5E_CPU0_P0_RX_DP<13>")
	)
	(segment
		(start 357.484172 -276.028658)
		(end 357.452422 -276.01037)
		(width 0.1143)
		(layer "In15.Cu")
		(net "P5E_CPU0_P0_RX_DP<13>")
	)
	(segment
		(start 366.74044 -373.43207)
		(end 366.5982 -373.28983)
		(width 0.14224)
		(layer "In15.Cu")
		(net "P5E_CPU0_P0_RX_DP<13>")
	)
	(segment
		(start 357.296466 -287.046162)
		(end 357.296212 -287.045908)
		(width 0.1143)
		(layer "In15.Cu")
		(net "P5E_CPU0_P0_RX_DP<13>")
	)
	(segment
		(start 357.473758 -288.982658)
		(end 357.464868 -288.977578)
		(width 0.1143)
		(layer "In15.Cu")
		(net "P5E_CPU0_P0_RX_DP<13>")
	)
	(segment
		(start 357.537004 -289.93084)
		(end 357.537766 -289.930332)
		(width 0.1143)
		(layer "In15.Cu")
		(net "P5E_CPU0_P0_RX_DP<13>")
	)
	(segment
		(start 357.494332 -293.197534)
		(end 357.523034 -293.18077)
		(width 0.1143)
		(layer "In15.Cu")
		(net "P5E_CPU0_P0_RX_DP<13>")
	)
	(segment
		(start 357.341932 -295.911016)
		(end 357.341932 -295.896538)
		(width 0.1143)
		(layer "In15.Cu")
		(net "P5E_CPU0_P0_RX_DP<13>")
	)
	(segment
		(start 366.5982 -372.71833)
		(end 366.74044 -372.57609)
		(width 0.14224)
		(layer "In15.Cu")
		(net "P5E_CPU0_P0_RX_DP<13>")
	)
	(segment
		(start 357.484172 -291.583872)
		(end 357.490776 -291.579554)
		(width 0.1143)
		(layer "In15.Cu")
		(net "P5E_CPU0_P0_RX_DP<13>")
	)
	(segment
		(start 357.492554 -291.578284)
		(end 357.524558 -291.559996)
		(width 0.1143)
		(layer "In15.Cu")
		(net "P5E_CPU0_P0_RX_DP<13>")
	)
	(segment
		(start 357.51897 -282.528772)
		(end 357.51516 -282.526486)
		(width 0.1143)
		(layer "In15.Cu")
		(net "P5E_CPU0_P0_RX_DP<13>")
	)
	(segment
		(start 357.452422 -277.021798)
		(end 357.484172 -277.00351)
		(width 0.1143)
		(layer "In15.Cu")
		(net "P5E_CPU0_P0_RX_DP<13>")
	)
	(segment
		(start 357.596948 -287.459674)
		(end 357.459026 -287.361376)
		(width 0.1143)
		(layer "In15.Cu")
		(net "P5E_CPU0_P0_RX_DP<13>")
	)
	(segment
		(start 357.47579 -289.968178)
		(end 357.484172 -289.96386)
		(width 0.1143)
		(layer "In15.Cu")
		(net "P5E_CPU0_P0_RX_DP<13>")
	)
	(segment
		(start 357.451406 -286.742632)
		(end 357.520494 -286.7025)
		(width 0.1143)
		(layer "In15.Cu")
		(net "P5E_CPU0_P0_RX_DP<13>")
	)
	(segment
		(start 357.484172 -285.74873)
		(end 357.452422 -285.730442)
		(width 0.1143)
		(layer "In15.Cu")
		(net "P5E_CPU0_P0_RX_DP<13>")
	)
	(segment
		(start 357.484172 -280.888694)
		(end 357.474266 -280.882852)
		(width 0.1143)
		(layer "In15.Cu")
		(net "P5E_CPU0_P0_RX_DP<13>")
	)
	(segment
		(start 357.484172 -283.483558)
		(end 357.520494 -283.462476)
		(width 0.1143)
		(layer "In15.Cu")
		(net "P5E_CPU0_P0_RX_DP<13>")
	)
	(segment
		(start 357.296212 -295.850818)
		(end 357.296212 -295.145968)
		(width 0.1143)
		(layer "In15.Cu")
		(net "P5E_CPU0_P0_RX_DP<13>")
	)
	(segment
		(start 357.484172 -290.608004)
		(end 357.475536 -290.603686)
		(width 0.1143)
		(layer "In15.Cu")
		(net "P5E_CPU0_P0_RX_DP<13>")
	)
	(segment
		(start 357.452168 -291.601906)
		(end 357.47579 -291.58819)
		(width 0.1143)
		(layer "In15.Cu")
		(net "P5E_CPU0_P0_RX_DP<13>")
	)
	(segment
		(start 357.5431 -289.028886)
		(end 357.473758 -288.982658)
		(width 0.1143)
		(layer "In15.Cu")
		(net "P5E_CPU0_P0_RX_DP<13>")
	)
	(segment
		(start 357.484172 -278.623522)
		(end 357.520494 -278.60244)
		(width 0.1143)
		(layer "In15.Cu")
		(net "P5E_CPU0_P0_RX_DP<13>")
	)
	(segment
		(start 357.476552 -292.224206)
		(end 357.47579 -292.223698)
		(width 0.1143)
		(layer "In15.Cu")
		(net "P5E_CPU0_P0_RX_DP<13>")
	)
	(segment
		(start 357.520494 -282.529788)
		(end 357.51897 -282.528772)
		(width 0.1143)
		(layer "In15.Cu")
		(net "P5E_CPU0_P0_RX_DP<13>")
	)
	(segment
		(start 319.886076 -394.031216)
		(end 320.06032 -393.930632)
		(width 0.14224)
		(layer "In15.Cu")
		(net "P5E_CPU0_P0_RX_DP<13>")
	)
	(segment
		(start 357.523034 -289.940746)
		(end 357.52278 -289.941)
		(width 0.1143)
		(layer "In15.Cu")
		(net "P5E_CPU0_P0_RX_DP<13>")
	)
	(segment
		(start 357.504746 -280.231596)
		(end 357.505508 -280.231088)
		(width 0.1143)
		(layer "In15.Cu")
		(net "P5E_CPU0_P0_RX_DP<13>")
	)
	(segment
		(start 397.846804 -352.800158)
		(end 369.289076 -324.241668)
		(width 0.14224)
		(layer "In15.Cu")
		(net "P5E_CPU0_P0_RX_DP<13>")
	)
	(segment
		(start 357.520494 -284.1498)
		(end 357.484172 -284.128718)
		(width 0.1143)
		(layer "In15.Cu")
		(net "P5E_CPU0_P0_RX_DP<13>")
	)
	(segment
		(start 357.464868 -288.977578)
		(end 357.464106 -288.97707)
		(width 0.1143)
		(layer "In15.Cu")
		(net "P5E_CPU0_P0_RX_DP<13>")
	)
	(segment
		(start 357.484172 -275.383498)
		(end 357.504746 -275.37156)
		(width 0.1143)
		(layer "In15.Cu")
		(net "P5E_CPU0_P0_RX_DP<13>")
	)
	(segment
		(start 320.187574 -390.179306)
		(end 324.483222 -385.883658)
		(width 0.14224)
		(layer "In15.Cu")
		(net "P5E_CPU0_P0_RX_DP<13>")
	)
	(segment
		(start 357.484172 -292.228016)
		(end 357.476552 -292.224206)
		(width 0.1143)
		(layer "In15.Cu")
		(net "P5E_CPU0_P0_RX_DP<13>")
	)
	(segment
		(start 357.470964 -292.220904)
		(end 357.469694 -292.220142)
		(width 0.1143)
		(layer "In15.Cu")
		(net "P5E_CPU0_P0_RX_DP<13>")
	)
	(segment
		(start 357.523034 -293.18077)
		(end 357.52278 -293.181024)
		(width 0.1143)
		(layer "In15.Cu")
		(net "P5E_CPU0_P0_RX_DP<13>")
	)
	(segment
		(start 357.487728 -292.230302)
		(end 357.486966 -292.229794)
		(width 0.1143)
		(layer "In15.Cu")
		(net "P5E_CPU0_P0_RX_DP<13>")
	)
	(segment
		(start 357.490776 -291.579554)
		(end 357.492554 -291.578284)
		(width 0.1143)
		(layer "In15.Cu")
		(net "P5E_CPU0_P0_RX_DP<13>")
	)
	(segment
		(start 357.520494 -276.04974)
		(end 357.484172 -276.028658)
		(width 0.1143)
		(layer "In15.Cu")
		(net "P5E_CPU0_P0_RX_DP<13>")
	)
	(segment
		(start 357.47198 -292.221412)
		(end 357.470964 -292.220904)
		(width 0.1143)
		(layer "In15.Cu")
		(net "P5E_CPU0_P0_RX_DP<13>")
	)
	(segment
		(start 357.452422 -294.841676)
		(end 357.471726 -294.8305)
		(width 0.1143)
		(layer "In15.Cu")
		(net "P5E_CPU0_P0_RX_DP<13>")
	)
	(segment
		(start 357.524558 -290.63188)
		(end 357.490776 -290.612576)
		(width 0.1143)
		(layer "In15.Cu")
		(net "P5E_CPU0_P0_RX_DP<13>")
	)
	(segment
		(start 357.486966 -292.229794)
		(end 357.484172 -292.228016)
		(width 0.1143)
		(layer "In15.Cu")
		(net "P5E_CPU0_P0_RX_DP<13>")
	)
	(segment
		(start 357.51516 -282.526486)
		(end 357.452422 -282.490418)
		(width 0.1143)
		(layer "In15.Cu")
		(net "P5E_CPU0_P0_RX_DP<13>")
	)
	(segment
		(start 357.468678 -293.839646)
		(end 357.452676 -293.830502)
		(width 0.1143)
		(layer "In15.Cu")
		(net "P5E_CPU0_P0_RX_DP<13>")
	)
	(segment
		(start 357.532178 -289.934396)
		(end 357.537004 -289.93084)
		(width 0.1143)
		(layer "In15.Cu")
		(net "P5E_CPU0_P0_RX_DP<13>")
	)
	(segment
		(start 357.373174 -274.086066)
		(end 357.671116 -274.086066)
		(width 0.1143)
		(layer "In15.Cu")
		(net "P5E_CPU0_P0_RX_DP<13>")
	)
	(segment
		(start 319.832482 -393.113006)
		(end 319.83553 -392.7348)
		(width 0.14224)
		(layer "In15.Cu")
		(net "P5E_CPU0_P0_RX_DP<13>")
	)
	(segment
		(start 364.53953 -315.698124)
		(end 364.538514 -315.696346)
		(width 0.14224)
		(layer "In15.Cu")
		(net "P5E_CPU0_P0_RX_DP<13>")
	)
	(segment
		(start 357.452676 -293.830502)
		(end 357.434642 -293.817548)
		(width 0.1143)
		(layer "In15.Cu")
		(net "P5E_CPU0_P0_RX_DP<13>")
	)
	(segment
		(start 357.553768 -289.03422)
		(end 357.5431 -289.028886)
		(width 0.1143)
		(layer "In15.Cu")
		(net "P5E_CPU0_P0_RX_DP<13>")
	)
	(segment
		(start 320.148458 -393.428982)
		(end 319.832482 -393.113006)
		(width 0.14224)
		(layer "In15.Cu")
		(net "P5E_CPU0_P0_RX_DP<13>")
	)
	(segment
		(start 357.452422 -281.881834)
		(end 357.484172 -281.863546)
		(width 0.1143)
		(layer "In15.Cu")
		(net "P5E_CPU0_P0_RX_DP<13>")
	)
	(segment
		(start 364.538514 -315.696346)
		(end 357.445056 -303.96688)
		(width 0.14224)
		(layer "In15.Cu")
		(net "P5E_CPU0_P0_RX_DP<13>")
	)
	(segment
		(start 357.766366 -287.856168)
		(end 357.766366 -287.854136)
		(width 0.1143)
		(layer "In15.Cu")
		(net "P5E_CPU0_P0_RX_DP<13>")
	)
	(segment
		(start 357.484172 -277.00351)
		(end 357.520494 -276.982428)
		(width 0.1143)
		(layer "In15.Cu")
		(net "P5E_CPU0_P0_RX_DP<13>")
	)
	(segment
		(start 324.69328 -385.376674)
		(end 324.69328 -382.489964)
		(width 0.14224)
		(layer "In15.Cu")
		(net "P5E_CPU0_P0_RX_DP<13>")
	)
	(segment
		(start 366.697514 -319.73266)
		(end 364.550706 -315.71819)
		(width 0.14224)
		(layer "In15.Cu")
		(net "P5E_CPU0_P0_RX_DP<13>")
	)
	(segment
		(start 357.505508 -274.421092)
		(end 357.452422 -274.390358)
		(width 0.1143)
		(layer "In15.Cu")
		(net "P5E_CPU0_P0_RX_DP<13>")
	)
	(segment
		(start 357.452168 -293.221664)
		(end 357.467408 -293.213028)
		(width 0.1143)
		(layer "In15.Cu")
		(net "P5E_CPU0_P0_RX_DP<13>")
	)
	(segment
		(start 320.148458 -393.842494)
		(end 320.148458 -393.428982)
		(width 0.14224)
		(layer "In15.Cu")
		(net "P5E_CPU0_P0_RX_DP<13>")
	)
	(segment
		(start 357.489506 -289.960304)
		(end 357.523034 -289.940746)
		(width 0.1143)
		(layer "In15.Cu")
		(net "P5E_CPU0_P0_RX_DP<13>")
	)
	(segment
		(start 366.74044 -372.57609)
		(end 379.70333 -372.57609)
		(width 0.14224)
		(layer "In15.Cu")
		(net "P5E_CPU0_P0_RX_DP<13>")
	)
	(segment
		(start 357.452168 -289.981894)
		(end 357.47579 -289.968178)
		(width 0.1143)
		(layer "In15.Cu")
		(net "P5E_CPU0_P0_RX_DP<13>")
	)
	(segment
		(start 397.306546 -369.647216)
		(end 397.447516 -369.506246)
		(width 0.14224)
		(layer "In15.Cu")
		(net "P5E_CPU0_P0_RX_DP<13>")
	)
	(segment
		(start 357.474266 -280.882852)
		(end 357.472996 -280.88209)
		(width 0.1143)
		(layer "In15.Cu")
		(net "P5E_CPU0_P0_RX_DP<13>")
	)
	(segment
		(start 357.520494 -285.769812)
		(end 357.484172 -285.74873)
		(width 0.1143)
		(layer "In15.Cu")
		(net "P5E_CPU0_P0_RX_DP<13>")
	)
	(segment
		(start 357.469694 -292.220142)
		(end 357.468932 -292.219634)
		(width 0.1143)
		(layer "In15.Cu")
		(net "P5E_CPU0_P0_RX_DP<13>")
	)
	(segment
		(start 357.470202 -280.251662)
		(end 357.504746 -280.231596)
		(width 0.1143)
		(layer "In15.Cu")
		(net "P5E_CPU0_P0_RX_DP<13>")
	)
	(segment
		(start 357.475536 -290.603686)
		(end 357.452422 -290.58997)
		(width 0.1143)
		(layer "In15.Cu")
		(net "P5E_CPU0_P0_RX_DP<13>")
	)
	(segment
		(start 357.452168 -288.361882)
		(end 357.525828 -288.318956)
		(width 0.1143)
		(layer "In15.Cu")
		(net "P5E_CPU0_P0_RX_DP<13>")
	)
	(segment
		(start 357.487982 -293.20109)
		(end 357.493062 -293.198296)
		(width 0.1143)
		(layer "In15.Cu")
		(net "P5E_CPU0_P0_RX_DP<13>")
	)
	(segment
		(start 357.504746 -275.37156)
		(end 357.505508 -275.371052)
		(width 0.1143)
		(layer "In15.Cu")
		(net "P5E_CPU0_P0_RX_DP<13>")
	)
	(arc
		(start 357.452422 -290.58997)
		(mid 357.296489 -290.286035)
		(end 357.452168 -289.981894)
		(width 0.1143)
		(layer "In15.Cu")
		(net "P5E_CPU0_P0_RX_DP<13>")
	)
	(arc
		(start 395.21384 -370.514118)
		(mid 396.346419 -370.288816)
		(end 397.306546 -369.647216)
		(width 0.14224)
		(layer "In15.Cu")
		(net "P5E_CPU0_P0_RX_DP<13>")
	)
	(arc
		(start 357.520494 -285.082488)
		(mid 357.528158 -285.077217)
		(end 357.535734 -285.07182)
		(width 0.1143)
		(layer "In15.Cu")
		(net "P5E_CPU0_P0_RX_DP<13>")
	)
	(arc
		(start 357.452676 -292.210236)
		(mid 357.302391 -291.906223)
		(end 357.452168 -291.601906)
		(width 0.1143)
		(layer "In15.Cu")
		(net "P5E_CPU0_P0_RX_DP<13>")
	)
	(arc
		(start 357.296212 -295.145968)
		(mid 357.337552 -294.974953)
		(end 357.452422 -294.841676)
		(width 0.1143)
		(layer "In15.Cu")
		(net "P5E_CPU0_P0_RX_DP<13>")
	)
	(arc
		(start 357.505508 -275.371052)
		(mid 357.779059 -274.896072)
		(end 357.505508 -274.421092)
		(width 0.1143)
		(layer "In15.Cu")
		(net "P5E_CPU0_P0_RX_DP<13>")
	)
	(arc
		(start 357.535734 -278.591772)
		(mid 357.760905 -278.136096)
		(end 357.535734 -277.68042)
		(width 0.1143)
		(layer "In15.Cu")
		(net "P5E_CPU0_P0_RX_DP<13>")
	)
	(arc
		(start 357.556308 -289.916362)
		(mid 357.775966 -289.47463)
		(end 357.553768 -289.03422)
		(width 0.1143)
		(layer "In15.Cu")
		(net "P5E_CPU0_P0_RX_DP<13>")
	)
	(arc
		(start 398.12595 -353.309174)
		(mid 398.022717 -353.034742)
		(end 397.846804 -352.800158)
		(width 0.14224)
		(layer "In15.Cu")
		(net "P5E_CPU0_P0_RX_DP<13>")
	)
	(arc
		(start 357.520494 -283.462476)
		(mid 357.527643 -283.457576)
		(end 357.534718 -283.45257)
		(width 0.1143)
		(layer "In15.Cu")
		(net "P5E_CPU0_P0_RX_DP<13>")
	)
	(arc
		(start 357.535734 -277.68042)
		(mid 357.528158 -277.675024)
		(end 357.520494 -277.669752)
		(width 0.1143)
		(layer "In15.Cu")
		(net "P5E_CPU0_P0_RX_DP<13>")
	)
	(arc
		(start 357.296212 -287.045908)
		(mid 357.336541 -286.876816)
		(end 357.448866 -286.744156)
		(width 0.1143)
		(layer "In15.Cu")
		(net "P5E_CPU0_P0_RX_DP<13>")
	)
	(arc
		(start 357.53675 -285.781242)
		(mid 357.528672 -285.775456)
		(end 357.520494 -285.769812)
		(width 0.1143)
		(layer "In15.Cu")
		(net "P5E_CPU0_P0_RX_DP<13>")
	)
	(arc
		(start 357.452422 -285.730442)
		(mid 357.296494 -285.42615)
		(end 357.452422 -285.121858)
		(width 0.1143)
		(layer "In15.Cu")
		(net "P5E_CPU0_P0_RX_DP<13>")
	)
	(arc
		(start 357.434642 -293.817548)
		(mid 357.285008 -293.526236)
		(end 357.434134 -293.234618)
		(width 0.1143)
		(layer "In15.Cu")
		(net "P5E_CPU0_P0_RX_DP<13>")
	)
	(arc
		(start 357.452422 -279.250394)
		(mid 357.296494 -278.946102)
		(end 357.452422 -278.64181)
		(width 0.1143)
		(layer "In15.Cu")
		(net "P5E_CPU0_P0_RX_DP<13>")
	)
	(arc
		(start 357.469694 -280.880312)
		(mid 357.289658 -280.565831)
		(end 357.470202 -280.251662)
		(width 0.1143)
		(layer "In15.Cu")
		(net "P5E_CPU0_P0_RX_DP<13>")
	)
	(arc
		(start 364.550706 -315.71819)
		(mid 364.551087 -315.718062)
		(end 364.551468 -315.717936)
		(width 0.14224)
		(layer "In15.Cu")
		(net "P5E_CPU0_P0_RX_DP<13>")
	)
	(arc
		(start 357.520494 -278.60244)
		(mid 357.528158 -278.597169)
		(end 357.535734 -278.591772)
		(width 0.1143)
		(layer "In15.Cu")
		(net "P5E_CPU0_P0_RX_DP<13>")
	)
	(arc
		(start 357.520494 -276.982428)
		(mid 357.528158 -276.977157)
		(end 357.535734 -276.97176)
		(width 0.1143)
		(layer "In15.Cu")
		(net "P5E_CPU0_P0_RX_DP<13>")
	)
	(arc
		(start 357.766366 -286.229552)
		(mid 357.701494 -285.97981)
		(end 357.53675 -285.781242)
		(width 0.1143)
		(layer "In15.Cu")
		(net "P5E_CPU0_P0_RX_DP<13>")
	)
	(arc
		(start 357.535734 -276.060408)
		(mid 357.528158 -276.055012)
		(end 357.520494 -276.04974)
		(width 0.1143)
		(layer "In15.Cu")
		(net "P5E_CPU0_P0_RX_DP<13>")
	)
	(arc
		(start 357.452422 -276.01037)
		(mid 357.296494 -275.706078)
		(end 357.452422 -275.401786)
		(width 0.1143)
		(layer "In15.Cu")
		(net "P5E_CPU0_P0_RX_DP<13>")
	)
	(arc
		(start 357.525828 -288.318956)
		(mid 357.70272 -288.116988)
		(end 357.766366 -287.856168)
		(width 0.1143)
		(layer "In15.Cu")
		(net "P5E_CPU0_P0_RX_DP<13>")
	)
	(arc
		(start 368.024918 -322.142358)
		(mid 367.353628 -320.941689)
		(end 366.697514 -319.73266)
		(width 0.14224)
		(layer "In15.Cu")
		(net "P5E_CPU0_P0_RX_DP<13>")
	)
	(arc
		(start 357.471726 -294.8305)
		(mid 357.755866 -294.334198)
		(end 357.468678 -293.839646)
		(width 0.1143)
		(layer "In15.Cu")
		(net "P5E_CPU0_P0_RX_DP<13>")
	)
	(arc
		(start 369.289076 -324.241668)
		(mid 369.133578 -324.063705)
		(end 369.003326 -323.86651)
		(width 0.14224)
		(layer "In15.Cu")
		(net "P5E_CPU0_P0_RX_DP<13>")
	)
	(arc
		(start 364.551468 -315.717936)
		(mid 364.54639 -315.709553)
		(end 364.541308 -315.701172)
		(width 0.14224)
		(layer "In15.Cu")
		(net "P5E_CPU0_P0_RX_DP<13>")
	)
	(arc
		(start 357.452422 -282.490418)
		(mid 357.296494 -282.186126)
		(end 357.452422 -281.881834)
		(width 0.1143)
		(layer "In15.Cu")
		(net "P5E_CPU0_P0_RX_DP<13>")
	)
	(arc
		(start 357.445056 -303.96688)
		(mid 357.368276 -303.789528)
		(end 357.341932 -303.598072)
		(width 0.14224)
		(layer "In15.Cu")
		(net "P5E_CPU0_P0_RX_DP<13>")
	)
	(arc
		(start 357.452422 -277.630382)
		(mid 357.296494 -277.32609)
		(end 357.452422 -277.021798)
		(width 0.1143)
		(layer "In15.Cu")
		(net "P5E_CPU0_P0_RX_DP<13>")
	)
	(arc
		(start 324.483222 -385.883658)
		(mid 324.638698 -385.651066)
		(end 324.69328 -385.376674)
		(width 0.14224)
		(layer "In15.Cu")
		(net "P5E_CPU0_P0_RX_DP<13>")
	)
	(arc
		(start 397.447516 -369.506246)
		(mid 397.966943 -368.728964)
		(end 398.149318 -367.812066)
		(width 0.14224)
		(layer "In15.Cu")
		(net "P5E_CPU0_P0_RX_DP<13>")
	)
	(arc
		(start 357.766366 -287.854136)
		(mid 357.722213 -287.639491)
		(end 357.596948 -287.459674)
		(width 0.1143)
		(layer "In15.Cu")
		(net "P5E_CPU0_P0_RX_DP<13>")
	)
	(arc
		(start 332.116684 -375.06656)
		(mid 332.354418 -374.907711)
		(end 332.634844 -374.85193)
		(width 0.14224)
		(layer "In15.Cu")
		(net "P5E_CPU0_P0_RX_DP<13>")
	)
	(arc
		(start 320.14033 -390.293352)
		(mid 320.152607 -390.231629)
		(end 320.187574 -390.179306)
		(width 0.14224)
		(layer "In15.Cu")
		(net "P5E_CPU0_P0_RX_DP<13>")
	)
	(arc
		(start 357.520494 -286.7025)
		(mid 357.702678 -286.49683)
		(end 357.766366 -286.229552)
		(width 0.1143)
		(layer "In15.Cu")
		(net "P5E_CPU0_P0_RX_DP<13>")
	)
	(arc
		(start 357.535734 -276.97176)
		(mid 357.760905 -276.516084)
		(end 357.535734 -276.060408)
		(width 0.1143)
		(layer "In15.Cu")
		(net "P5E_CPU0_P0_RX_DP<13>")
	)
	(arc
		(start 398.149318 -353.520502)
		(mid 398.143419 -353.414198)
		(end 398.12595 -353.309174)
		(width 0.14224)
		(layer "In15.Cu")
		(net "P5E_CPU0_P0_RX_DP<13>")
	)
	(arc
		(start 357.459026 -287.361376)
		(mid 357.339544 -287.223468)
		(end 357.296466 -287.046162)
		(width 0.1143)
		(layer "In15.Cu")
		(net "P5E_CPU0_P0_RX_DP<13>")
	)
	(arc
		(start 357.534718 -283.45257)
		(mid 357.762101 -282.996132)
		(end 357.534718 -282.539694)
		(width 0.1143)
		(layer "In15.Cu")
		(net "P5E_CPU0_P0_RX_DP<13>")
	)
	(arc
		(start 357.535734 -284.160468)
		(mid 357.528158 -284.155072)
		(end 357.520494 -284.1498)
		(width 0.1143)
		(layer "In15.Cu")
		(net "P5E_CPU0_P0_RX_DP<13>")
	)
	(arc
		(start 357.484172 -281.863546)
		(mid 357.764819 -281.37612)
		(end 357.484172 -280.888694)
		(width 0.1143)
		(layer "In15.Cu")
		(net "P5E_CPU0_P0_RX_DP<13>")
	)
	(arc
		(start 357.550974 -293.160958)
		(mid 357.770703 -292.811032)
		(end 357.683562 -292.407086)
		(width 0.1143)
		(layer "In15.Cu")
		(net "P5E_CPU0_P0_RX_DP<13>")
	)
	(arc
		(start 357.524558 -291.559996)
		(mid 357.760944 -291.095938)
		(end 357.524558 -290.63188)
		(width 0.1143)
		(layer "In15.Cu")
		(net "P5E_CPU0_P0_RX_DP<13>")
	)
	(arc
		(start 357.452422 -284.11043)
		(mid 357.296494 -283.806138)
		(end 357.452422 -283.501846)
		(width 0.1143)
		(layer "In15.Cu")
		(net "P5E_CPU0_P0_RX_DP<13>")
	)
	(arc
		(start 357.535734 -285.07182)
		(mid 357.760905 -284.616144)
		(end 357.535734 -284.160468)
		(width 0.1143)
		(layer "In15.Cu")
		(net "P5E_CPU0_P0_RX_DP<13>")
	)
	(arc
		(start 357.452422 -274.390358)
		(mid 357.355287 -274.287489)
		(end 357.303324 -274.155916)
		(width 0.1143)
		(layer "In15.Cu")
		(net "P5E_CPU0_P0_RX_DP<13>")
	)
	(arc
		(start 364.541308 -315.701172)
		(mid 364.540422 -315.699646)
		(end 364.53953 -315.698124)
		(width 0.14224)
		(layer "In15.Cu")
		(net "P5E_CPU0_P0_RX_DP<13>")
	)
	(arc
		(start 357.452676 -288.970212)
		(mid 357.296431 -288.6662)
		(end 357.452168 -288.361882)
		(width 0.1143)
		(layer "In15.Cu")
		(net "P5E_CPU0_P0_RX_DP<13>")
	)
	(arc
		(start 357.505508 -280.231088)
		(mid 357.779059 -279.756108)
		(end 357.505508 -279.281128)
		(width 0.1143)
		(layer "In15.Cu")
		(net "P5E_CPU0_P0_RX_DP<13>")
	)
	(arc
		(start 357.683562 -292.407086)
		(mid 357.625421 -292.336516)
		(end 357.555546 -292.277546)
		(width 0.1143)
		(layer "In15.Cu")
		(net "P5E_CPU0_P0_RX_DP<13>")
	)
	(arc
		(start 357.534718 -282.539694)
		(mid 357.527644 -282.534687)
		(end 357.520494 -282.529788)
		(width 0.1143)
		(layer "In15.Cu")
		(net "P5E_CPU0_P0_RX_DP<13>")
	)
	(segment
		(start 358.137968 -272.200116)
		(end 357.671116 -272.466054)
		(width 0.12954)
		(layer "F.Cu")
		(net "P5E_CPU0_P0_RX_DP<12>")
	)
	(segment
		(start 318.07023 -394.385292)
		(end 318.59093 -394.385292)
		(width 0.127)
		(layer "F.Cu")
		(net "P5E_CPU0_P0_RX_DP<12>")
	)
	(segment
		(start 356.562406 -274.418552)
		(end 356.53472 -274.403312)
		(width 0.1143)
		(layer "In15.Cu")
		(net "P5E_CPU0_P0_RX_DP<12>")
	)
	(segment
		(start 356.540562 -278.625554)
		(end 356.543356 -278.62403)
		(width 0.1143)
		(layer "In15.Cu")
		(net "P5E_CPU0_P0_RX_DP<12>")
	)
	(segment
		(start 356.583234 -290.631372)
		(end 356.576376 -290.627308)
		(width 0.1143)
		(layer "In15.Cu")
		(net "P5E_CPU0_P0_RX_DP<12>")
	)
	(segment
		(start 318.685926 -394.031216)
		(end 318.86017 -393.930632)
		(width 0.14224)
		(layer "In15.Cu")
		(net "P5E_CPU0_P0_RX_DP<12>")
	)
	(segment
		(start 356.540562 -277.005542)
		(end 356.543356 -277.004018)
		(width 0.1143)
		(layer "In15.Cu")
		(net "P5E_CPU0_P0_RX_DP<12>")
	)
	(segment
		(start 356.583234 -293.871396)
		(end 356.576376 -293.867332)
		(width 0.1143)
		(layer "In15.Cu")
		(net "P5E_CPU0_P0_RX_DP<12>")
	)
	(segment
		(start 356.512368 -273.781774)
		(end 356.536244 -273.768058)
		(width 0.1143)
		(layer "In15.Cu")
		(net "P5E_CPU0_P0_RX_DP<12>")
	)
	(segment
		(start 318.632332 -393.113006)
		(end 318.63538 -392.7348)
		(width 0.14224)
		(layer "In15.Cu")
		(net "P5E_CPU0_P0_RX_DP<12>")
	)
	(segment
		(start 356.543356 -280.888186)
		(end 356.542086 -280.887424)
		(width 0.1143)
		(layer "In15.Cu")
		(net "P5E_CPU0_P0_RX_DP<12>")
	)
	(segment
		(start 356.543356 -275.384006)
		(end 356.544118 -275.383498)
		(width 0.1143)
		(layer "In15.Cu")
		(net "P5E_CPU0_P0_RX_DP<12>")
	)
	(segment
		(start 380.833376 -369.579906)
		(end 394.275818 -369.579906)
		(width 0.14224)
		(layer "In15.Cu")
		(net "P5E_CPU0_P0_RX_DP<12>")
	)
	(segment
		(start 356.512368 -294.841676)
		(end 356.537006 -294.827452)
		(width 0.1143)
		(layer "In15.Cu")
		(net "P5E_CPU0_P0_RX_DP<12>")
	)
	(segment
		(start 324.221602 -376.266456)
		(end 329.414632 -376.266456)
		(width 0.14224)
		(layer "In15.Cu")
		(net "P5E_CPU0_P0_RX_DP<12>")
	)
	(segment
		(start 356.545134 -284.129226)
		(end 356.544118 -284.128718)
		(width 0.1143)
		(layer "In15.Cu")
		(net "P5E_CPU0_P0_RX_DP<12>")
	)
	(segment
		(start 356.583234 -282.531566)
		(end 356.546658 -282.51023)
		(width 0.1143)
		(layer "In15.Cu")
		(net "P5E_CPU0_P0_RX_DP<12>")
	)
	(segment
		(start 356.583234 -276.050248)
		(end 356.563168 -276.039072)
		(width 0.1143)
		(layer "In15.Cu")
		(net "P5E_CPU0_P0_RX_DP<12>")
	)
	(segment
		(start 356.545896 -280.88971)
		(end 356.545134 -280.889202)
		(width 0.1143)
		(layer "In15.Cu")
		(net "P5E_CPU0_P0_RX_DP<12>")
	)
	(segment
		(start 363.38764 -372.327424)
		(end 352.56216 -372.327424)
		(width 0.14224)
		(layer "In15.Cu")
		(net "P5E_CPU0_P0_RX_DP<12>")
	)
	(segment
		(start 356.575614 -290.6268)
		(end 356.544118 -290.608512)
		(width 0.1143)
		(layer "In15.Cu")
		(net "P5E_CPU0_P0_RX_DP<12>")
	)
	(segment
		(start 379.00483 -371.34165)
		(end 380.71933 -369.62715)
		(width 0.14224)
		(layer "In15.Cu")
		(net "P5E_CPU0_P0_RX_DP<12>")
	)
	(segment
		(start 352.56216 -371.471444)
		(end 378.691394 -371.471444)
		(width 0.14224)
		(layer "In15.Cu")
		(net "P5E_CPU0_P0_RX_DP<12>")
	)
	(segment
		(start 356.53472 -274.403312)
		(end 356.512368 -274.390358)
		(width 0.1143)
		(layer "In15.Cu")
		(net "P5E_CPU0_P0_RX_DP<12>")
	)
	(segment
		(start 357.29037 -272.548858)
		(end 357.373174 -272.466054)
		(width 0.1143)
		(layer "In15.Cu")
		(net "P5E_CPU0_P0_RX_DP<12>")
	)
	(segment
		(start 356.538276 -278.626824)
		(end 356.5398 -278.626062)
		(width 0.1143)
		(layer "In15.Cu")
		(net "P5E_CPU0_P0_RX_DP<12>")
	)
	(segment
		(start 356.544118 -282.508706)
		(end 356.512368 -282.490418)
		(width 0.1143)
		(layer "In15.Cu")
		(net "P5E_CPU0_P0_RX_DP<12>")
	)
	(segment
		(start 356.575614 -285.767018)
		(end 356.544118 -285.74873)
		(width 0.1143)
		(layer "In15.Cu")
		(net "P5E_CPU0_P0_RX_DP<12>")
	)
	(segment
		(start 356.583234 -284.151578)
		(end 356.546658 -284.130242)
		(width 0.1143)
		(layer "In15.Cu")
		(net "P5E_CPU0_P0_RX_DP<12>")
	)
	(segment
		(start 356.582726 -291.561012)
		(end 356.583234 -291.560758)
		(width 0.1143)
		(layer "In15.Cu")
		(net "P5E_CPU0_P0_RX_DP<12>")
	)
	(segment
		(start 356.562406 -276.038564)
		(end 356.53472 -276.023324)
		(width 0.1143)
		(layer "In15.Cu")
		(net "P5E_CPU0_P0_RX_DP<12>")
	)
	(segment
		(start 356.545134 -279.26919)
		(end 356.544118 -279.268682)
		(width 0.1143)
		(layer "In15.Cu")
		(net "P5E_CPU0_P0_RX_DP<12>")
	)
	(segment
		(start 356.546658 -275.381974)
		(end 356.583234 -275.360638)
		(width 0.1143)
		(layer "In15.Cu")
		(net "P5E_CPU0_P0_RX_DP<12>")
	)
	(segment
		(start 356.544118 -294.823388)
		(end 356.545134 -294.82288)
		(width 0.1143)
		(layer "In15.Cu")
		(net "P5E_CPU0_P0_RX_DP<12>")
	)
	(segment
		(start 363.67974 -372.619524)
		(end 363.38764 -372.327424)
		(width 0.14224)
		(layer "In15.Cu")
		(net "P5E_CPU0_P0_RX_DP<12>")
	)
	(segment
		(start 356.514146 -291.600636)
		(end 356.582726 -291.561012)
		(width 0.1143)
		(layer "In15.Cu")
		(net "P5E_CPU0_P0_RX_DP<12>")
	)
	(segment
		(start 356.583234 -289.01136)
		(end 356.576376 -289.007296)
		(width 0.1143)
		(layer "In15.Cu")
		(net "P5E_CPU0_P0_RX_DP<12>")
	)
	(segment
		(start 356.58298 -289.941)
		(end 356.583488 -289.940746)
		(width 0.1143)
		(layer "In15.Cu")
		(net "P5E_CPU0_P0_RX_DP<12>")
	)
	(segment
		(start 356.512368 -281.881834)
		(end 356.544118 -281.863546)
		(width 0.1143)
		(layer "In15.Cu")
		(net "P5E_CPU0_P0_RX_DP<12>")
	)
	(segment
		(start 356.537514 -277.00732)
		(end 356.538276 -277.006812)
		(width 0.1143)
		(layer "In15.Cu")
		(net "P5E_CPU0_P0_RX_DP<12>")
	)
	(segment
		(start 356.583234 -279.291542)
		(end 356.546658 -279.270206)
		(width 0.1143)
		(layer "In15.Cu")
		(net "P5E_CPU0_P0_RX_DP<12>")
	)
	(segment
		(start 356.512368 -285.121858)
		(end 356.544118 -285.10357)
		(width 0.1143)
		(layer "In15.Cu")
		(net "P5E_CPU0_P0_RX_DP<12>")
	)
	(segment
		(start 356.575614 -289.006788)
		(end 356.544118 -288.9885)
		(width 0.1143)
		(layer "In15.Cu")
		(net "P5E_CPU0_P0_RX_DP<12>")
	)
	(segment
		(start 356.545134 -275.38299)
		(end 356.546658 -275.381974)
		(width 0.1143)
		(layer "In15.Cu")
		(net "P5E_CPU0_P0_RX_DP<12>")
	)
	(segment
		(start 356.356412 -295.423082)
		(end 356.356412 -295.145968)
		(width 0.1143)
		(layer "In15.Cu")
		(net "P5E_CPU0_P0_RX_DP<12>")
	)
	(segment
		(start 356.512622 -289.981894)
		(end 356.58298 -289.941)
		(width 0.1143)
		(layer "In15.Cu")
		(net "P5E_CPU0_P0_RX_DP<12>")
	)
	(segment
		(start 356.563168 -276.039072)
		(end 356.562406 -276.038564)
		(width 0.1143)
		(layer "In15.Cu")
		(net "P5E_CPU0_P0_RX_DP<12>")
	)
	(segment
		(start 356.5398 -277.00605)
		(end 356.540562 -277.005542)
		(width 0.1143)
		(layer "In15.Cu")
		(net "P5E_CPU0_P0_RX_DP<12>")
	)
	(segment
		(start 356.542086 -292.227254)
		(end 356.512368 -292.210236)
		(width 0.1143)
		(layer "In15.Cu")
		(net "P5E_CPU0_P0_RX_DP<12>")
	)
	(segment
		(start 356.543356 -293.848028)
		(end 356.542086 -293.847266)
		(width 0.1143)
		(layer "In15.Cu")
		(net "P5E_CPU0_P0_RX_DP<12>")
	)
	(segment
		(start 356.544118 -279.268682)
		(end 356.512368 -279.250394)
		(width 0.1143)
		(layer "In15.Cu")
		(net "P5E_CPU0_P0_RX_DP<12>")
	)
	(segment
		(start 332.16977 -373.747284)
		(end 363.38764 -373.747284)
		(width 0.14224)
		(layer "In15.Cu")
		(net "P5E_CPU0_P0_RX_DP<12>")
	)
	(segment
		(start 356.546658 -282.51023)
		(end 356.545134 -282.509214)
		(width 0.1143)
		(layer "In15.Cu")
		(net "P5E_CPU0_P0_RX_DP<12>")
	)
	(segment
		(start 363.38764 -373.747284)
		(end 363.67974 -373.455184)
		(width 0.14224)
		(layer "In15.Cu")
		(net "P5E_CPU0_P0_RX_DP<12>")
	)
	(segment
		(start 323.412866 -384.467354)
		(end 323.412866 -377.130056)
		(width 0.14224)
		(layer "In15.Cu")
		(net "P5E_CPU0_P0_RX_DP<12>")
	)
	(segment
		(start 356.544118 -280.243534)
		(end 356.545134 -280.243026)
		(width 0.1143)
		(layer "In15.Cu")
		(net "P5E_CPU0_P0_RX_DP<12>")
	)
	(segment
		(start 356.583234 -293.18077)
		(end 356.583234 -293.180516)
		(width 0.1143)
		(layer "In15.Cu")
		(net "P5E_CPU0_P0_RX_DP<12>")
	)
	(segment
		(start 356.544118 -288.9885)
		(end 356.543356 -288.987992)
		(width 0.1143)
		(layer "In15.Cu")
		(net "P5E_CPU0_P0_RX_DP<12>")
	)
	(segment
		(start 356.546658 -279.270206)
		(end 356.545134 -279.26919)
		(width 0.1143)
		(layer "In15.Cu")
		(net "P5E_CPU0_P0_RX_DP<12>")
	)
	(segment
		(start 356.512368 -291.601652)
		(end 356.512368 -291.601906)
		(width 0.1143)
		(layer "In15.Cu")
		(net "P5E_CPU0_P0_RX_DP<12>")
	)
	(segment
		(start 356.582726 -293.181024)
		(end 356.583234 -293.18077)
		(width 0.1143)
		(layer "In15.Cu")
		(net "P5E_CPU0_P0_RX_DP<12>")
	)
	(segment
		(start 356.5398 -273.766026)
		(end 356.540562 -273.765518)
		(width 0.1143)
		(layer "In15.Cu")
		(net "P5E_CPU0_P0_RX_DP<12>")
	)
	(segment
		(start 356.5398 -275.386038)
		(end 356.540562 -275.38553)
		(width 0.1143)
		(layer "In15.Cu")
		(net "P5E_CPU0_P0_RX_DP<12>")
	)
	(segment
		(start 356.583234 -291.560758)
		(end 356.583234 -291.560504)
		(width 0.1143)
		(layer "In15.Cu")
		(net "P5E_CPU0_P0_RX_DP<12>")
	)
	(segment
		(start 318.63538 -392.7348)
		(end 318.94018 -392.43)
		(width 0.14224)
		(layer "In15.Cu")
		(net "P5E_CPU0_P0_RX_DP<12>")
	)
	(segment
		(start 356.537514 -278.627332)
		(end 356.538276 -278.626824)
		(width 0.1143)
		(layer "In15.Cu")
		(net "P5E_CPU0_P0_RX_DP<12>")
	)
	(segment
		(start 356.545134 -273.762978)
		(end 356.546658 -273.761962)
		(width 0.1143)
		(layer "In15.Cu")
		(net "P5E_CPU0_P0_RX_DP<12>")
	)
	(segment
		(start 356.536244 -278.628094)
		(end 356.537514 -278.627332)
		(width 0.1143)
		(layer "In15.Cu")
		(net "P5E_CPU0_P0_RX_DP<12>")
	)
	(segment
		(start 356.543356 -283.484066)
		(end 356.544118 -283.483558)
		(width 0.1143)
		(layer "In15.Cu")
		(net "P5E_CPU0_P0_RX_DP<12>")
	)
	(segment
		(start 356.544118 -275.383498)
		(end 356.545134 -275.38299)
		(width 0.1143)
		(layer "In15.Cu")
		(net "P5E_CPU0_P0_RX_DP<12>")
	)
	(segment
		(start 356.553262 -280.894028)
		(end 356.552246 -280.893266)
		(width 0.1143)
		(layer "In15.Cu")
		(net "P5E_CPU0_P0_RX_DP<12>")
	)
	(segment
		(start 356.546658 -280.24201)
		(end 356.583234 -280.220674)
		(width 0.1143)
		(layer "In15.Cu")
		(net "P5E_CPU0_P0_RX_DP<12>")
	)
	(segment
		(start 356.537514 -275.387308)
		(end 356.538276 -275.3868)
		(width 0.1143)
		(layer "In15.Cu")
		(net "P5E_CPU0_P0_RX_DP<12>")
	)
	(segment
		(start 356.537006 -294.827452)
		(end 356.538022 -294.826944)
		(width 0.1143)
		(layer "In15.Cu")
		(net "P5E_CPU0_P0_RX_DP<12>")
	)
	(segment
		(start 356.401878 -296.04208)
		(end 356.356158 -295.99636)
		(width 0.1143)
		(layer "In15.Cu")
		(net "P5E_CPU0_P0_RX_DP<12>")
	)
	(segment
		(start 356.544118 -293.848536)
		(end 356.543356 -293.848028)
		(width 0.1143)
		(layer "In15.Cu")
		(net "P5E_CPU0_P0_RX_DP<12>")
	)
	(segment
		(start 356.583234 -285.77159)
		(end 356.576376 -285.767526)
		(width 0.1143)
		(layer "In15.Cu")
		(net "P5E_CPU0_P0_RX_DP<12>")
	)
	(segment
		(start 357.373174 -272.466054)
		(end 357.671116 -272.466054)
		(width 0.1143)
		(layer "In15.Cu")
		(net "P5E_CPU0_P0_RX_DP<12>")
	)
	(segment
		(start 356.552246 -280.893266)
		(end 356.545896 -280.88971)
		(width 0.1143)
		(layer "In15.Cu")
		(net "P5E_CPU0_P0_RX_DP<12>")
	)
	(segment
		(start 356.512368 -277.021798)
		(end 356.536244 -277.008082)
		(width 0.1143)
		(layer "In15.Cu")
		(net "P5E_CPU0_P0_RX_DP<12>")
	)
	(segment
		(start 356.542086 -290.607242)
		(end 356.512368 -290.590224)
		(width 0.1143)
		(layer "In15.Cu")
		(net "P5E_CPU0_P0_RX_DP<12>")
	)
	(segment
		(start 356.542086 -283.484828)
		(end 356.543356 -283.484066)
		(width 0.1143)
		(layer "In15.Cu")
		(net "P5E_CPU0_P0_RX_DP<12>")
	)
	(segment
		(start 352.56216 -372.327424)
		(end 352.41992 -372.185184)
		(width 0.14224)
		(layer "In15.Cu")
		(net "P5E_CPU0_P0_RX_DP<12>")
	)
	(segment
		(start 356.401878 -296.070528)
		(end 356.401878 -296.04208)
		(width 0.1143)
		(layer "In15.Cu")
		(net "P5E_CPU0_P0_RX_DP<12>")
	)
	(segment
		(start 356.544118 -277.00351)
		(end 356.545134 -277.003002)
		(width 0.1143)
		(layer "In15.Cu")
		(net "P5E_CPU0_P0_RX_DP<12>")
	)
	(segment
		(start 356.543356 -294.823896)
		(end 356.544118 -294.823388)
		(width 0.1143)
		(layer "In15.Cu")
		(net "P5E_CPU0_P0_RX_DP<12>")
	)
	(segment
		(start 356.543356 -290.608004)
		(end 356.542086 -290.607242)
		(width 0.1143)
		(layer "In15.Cu")
		(net "P5E_CPU0_P0_RX_DP<12>")
	)
	(segment
		(start 356.576376 -289.007296)
		(end 356.575614 -289.006788)
		(width 0.1143)
		(layer "In15.Cu")
		(net "P5E_CPU0_P0_RX_DP<12>")
	)
	(segment
		(start 396.18412 -368.789458)
		(end 396.440406 -368.533172)
		(width 0.14224)
		(layer "In15.Cu")
		(net "P5E_CPU0_P0_RX_DP<12>")
	)
	(segment
		(start 356.540562 -275.38553)
		(end 356.543356 -275.384006)
		(width 0.1143)
		(layer "In15.Cu")
		(net "P5E_CPU0_P0_RX_DP<12>")
	)
	(segment
		(start 356.554532 -280.89479)
		(end 356.553262 -280.894028)
		(width 0.1143)
		(layer "In15.Cu")
		(net "P5E_CPU0_P0_RX_DP<12>")
	)
	(segment
		(start 356.58044 -285.082742)
		(end 356.583234 -285.08071)
		(width 0.1143)
		(layer "In15.Cu")
		(net "P5E_CPU0_P0_RX_DP<12>")
	)
	(segment
		(start 356.545134 -294.82288)
		(end 356.583234 -294.800528)
		(width 0.1143)
		(layer "In15.Cu")
		(net "P5E_CPU0_P0_RX_DP<12>")
	)
	(segment
		(start 356.536244 -280.248106)
		(end 356.537514 -280.247344)
		(width 0.1143)
		(layer "In15.Cu")
		(net "P5E_CPU0_P0_RX_DP<12>")
	)
	(segment
		(start 356.580694 -287.389824)
		(end 356.544118 -287.368488)
		(width 0.1143)
		(layer "In15.Cu")
		(net "P5E_CPU0_P0_RX_DP<12>")
	)
	(segment
		(start 356.545134 -280.243026)
		(end 356.546658 -280.24201)
		(width 0.1143)
		(layer "In15.Cu")
		(net "P5E_CPU0_P0_RX_DP<12>")
	)
	(segment
		(start 356.536244 -275.38807)
		(end 356.537514 -275.387308)
		(width 0.1143)
		(layer "In15.Cu")
		(net "P5E_CPU0_P0_RX_DP<12>")
	)
	(segment
		(start 352.41992 -371.613684)
		(end 352.56216 -371.471444)
		(width 0.14224)
		(layer "In15.Cu")
		(net "P5E_CPU0_P0_RX_DP<12>")
	)
	(segment
		(start 356.5398 -280.246074)
		(end 356.540562 -280.245566)
		(width 0.1143)
		(layer "In15.Cu")
		(net "P5E_CPU0_P0_RX_DP<12>")
	)
	(segment
		(start 356.576376 -293.867332)
		(end 356.575614 -293.866824)
		(width 0.1143)
		(layer "In15.Cu")
		(net "P5E_CPU0_P0_RX_DP<12>")
	)
	(segment
		(start 356.540562 -294.82542)
		(end 356.542086 -294.824658)
		(width 0.1143)
		(layer "In15.Cu")
		(net "P5E_CPU0_P0_RX_DP<12>")
	)
	(segment
		(start 318.86017 -393.930632)
		(end 318.948308 -393.842494)
		(width 0.14224)
		(layer "In15.Cu")
		(net "P5E_CPU0_P0_RX_DP<12>")
	)
	(segment
		(start 356.512368 -280.261822)
		(end 356.536244 -280.248106)
		(width 0.1143)
		(layer "In15.Cu")
		(net "P5E_CPU0_P0_RX_DP<12>")
	)
	(segment
		(start 356.545134 -280.889202)
		(end 356.544118 -280.888694)
		(width 0.1143)
		(layer "In15.Cu")
		(net "P5E_CPU0_P0_RX_DP<12>")
	)
	(segment
		(start 356.537514 -273.767296)
		(end 356.538276 -273.766788)
		(width 0.1143)
		(layer "In15.Cu")
		(net "P5E_CPU0_P0_RX_DP<12>")
	)
	(segment
		(start 356.544118 -273.763486)
		(end 356.545134 -273.762978)
		(width 0.1143)
		(layer "In15.Cu")
		(net "P5E_CPU0_P0_RX_DP<12>")
	)
	(segment
		(start 356.545134 -277.003002)
		(end 356.546658 -277.001986)
		(width 0.1143)
		(layer "In15.Cu")
		(net "P5E_CPU0_P0_RX_DP<12>")
	)
	(segment
		(start 356.546658 -277.650194)
		(end 356.545134 -277.649178)
		(width 0.1143)
		(layer "In15.Cu")
		(net "P5E_CPU0_P0_RX_DP<12>")
	)
	(segment
		(start 356.58044 -281.842718)
		(end 356.583234 -281.840686)
		(width 0.1143)
		(layer "In15.Cu")
		(net "P5E_CPU0_P0_RX_DP<12>")
	)
	(segment
		(start 356.356158 -295.423336)
		(end 356.356412 -295.423082)
		(width 0.1143)
		(layer "In15.Cu")
		(net "P5E_CPU0_P0_RX_DP<12>")
	)
	(segment
		(start 356.576376 -290.627308)
		(end 356.575614 -290.6268)
		(width 0.1143)
		(layer "In15.Cu")
		(net "P5E_CPU0_P0_RX_DP<12>")
	)
	(segment
		(start 319.03797 -389.83285)
		(end 322.712334 -386.158486)
		(width 0.14224)
		(layer "In15.Cu")
		(net "P5E_CPU0_P0_RX_DP<12>")
	)
	(segment
		(start 356.544118 -278.623522)
		(end 356.545134 -278.623014)
		(width 0.1143)
		(layer "In15.Cu")
		(net "P5E_CPU0_P0_RX_DP<12>")
	)
	(segment
		(start 356.543356 -277.004018)
		(end 356.544118 -277.00351)
		(width 0.1143)
		(layer "In15.Cu")
		(net "P5E_CPU0_P0_RX_DP<12>")
	)
	(segment
		(start 356.543356 -288.987992)
		(end 356.542086 -288.98723)
		(width 0.1143)
		(layer "In15.Cu")
		(net "P5E_CPU0_P0_RX_DP<12>")
	)
	(segment
		(start 356.545134 -277.649178)
		(end 356.544118 -277.64867)
		(width 0.1143)
		(layer "In15.Cu")
		(net "P5E_CPU0_P0_RX_DP<12>")
	)
	(segment
		(start 356.538276 -277.006812)
		(end 356.5398 -277.00605)
		(width 0.1143)
		(layer "In15.Cu")
		(net "P5E_CPU0_P0_RX_DP<12>")
	)
	(segment
		(start 356.583234 -280.911554)
		(end 356.554532 -280.89479)
		(width 0.1143)
		(layer "In15.Cu")
		(net "P5E_CPU0_P0_RX_DP<12>")
	)
	(segment
		(start 356.512368 -283.501846)
		(end 356.542086 -283.484828)
		(width 0.1143)
		(layer "In15.Cu")
		(net "P5E_CPU0_P0_RX_DP<12>")
	)
	(segment
		(start 356.543356 -280.244042)
		(end 356.544118 -280.243534)
		(width 0.1143)
		(layer "In15.Cu")
		(net "P5E_CPU0_P0_RX_DP<12>")
	)
	(segment
		(start 356.540562 -273.765518)
		(end 356.543356 -273.763994)
		(width 0.1143)
		(layer "In15.Cu")
		(net "P5E_CPU0_P0_RX_DP<12>")
	)
	(segment
		(start 356.983538 -272.97126)
		(end 357.053134 -272.93062)
		(width 0.1143)
		(layer "In15.Cu")
		(net "P5E_CPU0_P0_RX_DP<12>")
	)
	(segment
		(start 356.542086 -294.824658)
		(end 356.543356 -294.823896)
		(width 0.1143)
		(layer "In15.Cu")
		(net "P5E_CPU0_P0_RX_DP<12>")
	)
	(segment
		(start 356.583234 -277.67153)
		(end 356.546658 -277.650194)
		(width 0.1143)
		(layer "In15.Cu")
		(net "P5E_CPU0_P0_RX_DP<12>")
	)
	(segment
		(start 356.540562 -280.245566)
		(end 356.543356 -280.244042)
		(width 0.1143)
		(layer "In15.Cu")
		(net "P5E_CPU0_P0_RX_DP<12>")
	)
	(segment
		(start 356.544118 -285.74873)
		(end 356.512368 -285.730442)
		(width 0.1143)
		(layer "In15.Cu")
		(net "P5E_CPU0_P0_RX_DP<12>")
	)
	(segment
		(start 356.538022 -294.826944)
		(end 356.540562 -294.82542)
		(width 0.1143)
		(layer "In15.Cu")
		(net "P5E_CPU0_P0_RX_DP<12>")
	)
	(segment
		(start 356.546658 -277.001986)
		(end 356.583234 -276.98065)
		(width 0.1143)
		(layer "In15.Cu")
		(net "P5E_CPU0_P0_RX_DP<12>")
	)
	(segment
		(start 356.545134 -282.509214)
		(end 356.544118 -282.508706)
		(width 0.1143)
		(layer "In15.Cu")
		(net "P5E_CPU0_P0_RX_DP<12>")
	)
	(segment
		(start 356.544118 -280.888694)
		(end 356.543356 -280.888186)
		(width 0.1143)
		(layer "In15.Cu")
		(net "P5E_CPU0_P0_RX_DP<12>")
	)
	(segment
		(start 356.51059 -286.74314)
		(end 356.583234 -286.700722)
		(width 0.1143)
		(layer "In15.Cu")
		(net "P5E_CPU0_P0_RX_DP<12>")
	)
	(segment
		(start 356.512368 -293.221664)
		(end 356.52329 -293.221664)
		(width 0.1143)
		(layer "In15.Cu")
		(net "P5E_CPU0_P0_RX_DP<12>")
	)
	(segment
		(start 352.41992 -372.185184)
		(end 352.41992 -371.613684)
		(width 0.14224)
		(layer "In15.Cu")
		(net "P5E_CPU0_P0_RX_DP<12>")
	)
	(segment
		(start 356.583234 -274.430236)
		(end 356.563168 -274.41906)
		(width 0.1143)
		(layer "In15.Cu")
		(net "P5E_CPU0_P0_RX_DP<12>")
	)
	(segment
		(start 323.489066 -376.94616)
		(end 324.131432 -376.303794)
		(width 0.14224)
		(layer "In15.Cu")
		(net "P5E_CPU0_P0_RX_DP<12>")
	)
	(segment
		(start 397.100044 -366.940846)
		(end 397.100044 -354.06838)
		(width 0.14224)
		(layer "In15.Cu")
		(net "P5E_CPU0_P0_RX_DP<12>")
	)
	(segment
		(start 356.356158 -295.99636)
		(end 356.356158 -295.423336)
		(width 0.1143)
		(layer "In15.Cu")
		(net "P5E_CPU0_P0_RX_DP<12>")
	)
	(segment
		(start 356.544118 -292.228524)
		(end 356.543356 -292.228016)
		(width 0.1143)
		(layer "In15.Cu")
		(net "P5E_CPU0_P0_RX_DP<12>")
	)
	(segment
		(start 356.583234 -274.431506)
		(end 356.583234 -274.430236)
		(width 0.1143)
		(layer "In15.Cu")
		(net "P5E_CPU0_P0_RX_DP<12>")
	)
	(segment
		(start 356.575614 -293.866824)
		(end 356.544118 -293.848536)
		(width 0.1143)
		(layer "In15.Cu")
		(net "P5E_CPU0_P0_RX_DP<12>")
	)
	(segment
		(start 363.67974 -373.455184)
		(end 363.67974 -372.619524)
		(width 0.14224)
		(layer "In15.Cu")
		(net "P5E_CPU0_P0_RX_DP<12>")
	)
	(segment
		(start 356.401878 -303.91989)
		(end 356.401878 -296.070528)
		(width 0.14224)
		(layer "In15.Cu")
		(net "P5E_CPU0_P0_RX_DP<12>")
	)
	(segment
		(start 356.538276 -280.246836)
		(end 356.5398 -280.246074)
		(width 0.1143)
		(layer "In15.Cu")
		(net "P5E_CPU0_P0_RX_DP<12>")
	)
	(segment
		(start 356.543356 -292.228016)
		(end 356.542086 -292.227254)
		(width 0.1143)
		(layer "In15.Cu")
		(net "P5E_CPU0_P0_RX_DP<12>")
	)
	(segment
		(start 356.542086 -280.887424)
		(end 356.512368 -280.870406)
		(width 0.1143)
		(layer "In15.Cu")
		(net "P5E_CPU0_P0_RX_DP<12>")
	)
	(segment
		(start 356.583488 -289.940746)
		(end 356.583234 -289.940492)
		(width 0.1143)
		(layer "In15.Cu")
		(net "P5E_CPU0_P0_RX_DP<12>")
	)
	(segment
		(start 356.546658 -284.130242)
		(end 356.545134 -284.129226)
		(width 0.1143)
		(layer "In15.Cu")
		(net "P5E_CPU0_P0_RX_DP<12>")
	)
	(segment
		(start 356.542086 -293.847266)
		(end 356.512368 -293.830248)
		(width 0.1143)
		(layer "In15.Cu")
		(net "P5E_CPU0_P0_RX_DP<12>")
	)
	(segment
		(start 356.544118 -283.483558)
		(end 356.545134 -283.48305)
		(width 0.1143)
		(layer "In15.Cu")
		(net "P5E_CPU0_P0_RX_DP<12>")
	)
	(segment
		(start 356.53472 -276.023324)
		(end 356.512368 -276.01037)
		(width 0.1143)
		(layer "In15.Cu")
		(net "P5E_CPU0_P0_RX_DP<12>")
	)
	(segment
		(start 318.94018 -392.43)
		(end 318.94018 -390.068816)
		(width 0.14224)
		(layer "In15.Cu")
		(net "P5E_CPU0_P0_RX_DP<12>")
	)
	(segment
		(start 356.544118 -277.64867)
		(end 356.512368 -277.630382)
		(width 0.1143)
		(layer "In15.Cu")
		(net "P5E_CPU0_P0_RX_DP<12>")
	)
	(segment
		(start 356.52329 -293.221664)
		(end 356.52329 -293.215314)
		(width 0.1143)
		(layer "In15.Cu")
		(net "P5E_CPU0_P0_RX_DP<12>")
	)
	(segment
		(start 318.59093 -394.385292)
		(end 318.685926 -394.031216)
		(width 0.14224)
		(layer "In15.Cu")
		(net "P5E_CPU0_P0_RX_DP<12>")
	)
	(segment
		(start 356.544118 -284.128718)
		(end 356.512368 -284.11043)
		(width 0.1143)
		(layer "In15.Cu")
		(net "P5E_CPU0_P0_RX_DP<12>")
	)
	(segment
		(start 356.543356 -273.763994)
		(end 356.544118 -273.763486)
		(width 0.1143)
		(layer "In15.Cu")
		(net "P5E_CPU0_P0_RX_DP<12>")
	)
	(segment
		(start 356.512368 -278.64181)
		(end 356.536244 -278.628094)
		(width 0.1143)
		(layer "In15.Cu")
		(net "P5E_CPU0_P0_RX_DP<12>")
	)
	(segment
		(start 356.544118 -281.863546)
		(end 356.58044 -281.842718)
		(width 0.1143)
		(layer "In15.Cu")
		(net "P5E_CPU0_P0_RX_DP<12>")
	)
	(segment
		(start 318.948308 -393.842494)
		(end 318.948308 -393.428982)
		(width 0.14224)
		(layer "In15.Cu")
		(net "P5E_CPU0_P0_RX_DP<12>")
	)
	(segment
		(start 356.536244 -277.008082)
		(end 356.537514 -277.00732)
		(width 0.1143)
		(layer "In15.Cu")
		(net "P5E_CPU0_P0_RX_DP<12>")
	)
	(segment
		(start 396.596616 -352.8695)
		(end 369.325906 -326.126856)
		(width 0.14224)
		(layer "In15.Cu")
		(net "P5E_CPU0_P0_RX_DP<12>")
	)
	(segment
		(start 356.583234 -276.051518)
		(end 356.583234 -276.050248)
		(width 0.1143)
		(layer "In15.Cu")
		(net "P5E_CPU0_P0_RX_DP<12>")
	)
	(segment
		(start 318.948308 -393.428982)
		(end 318.632332 -393.113006)
		(width 0.14224)
		(layer "In15.Cu")
		(net "P5E_CPU0_P0_RX_DP<12>")
	)
	(segment
		(start 356.545134 -278.623014)
		(end 356.546658 -278.621998)
		(width 0.1143)
		(layer "In15.Cu")
		(net "P5E_CPU0_P0_RX_DP<12>")
	)
	(segment
		(start 356.512368 -275.401786)
		(end 356.536244 -275.38807)
		(width 0.1143)
		(layer "In15.Cu")
		(net "P5E_CPU0_P0_RX_DP<12>")
	)
	(segment
		(start 356.538276 -275.3868)
		(end 356.5398 -275.386038)
		(width 0.1143)
		(layer "In15.Cu")
		(net "P5E_CPU0_P0_RX_DP<12>")
	)
	(segment
		(start 356.546658 -273.761962)
		(end 356.583234 -273.740626)
		(width 0.1143)
		(layer "In15.Cu")
		(net "P5E_CPU0_P0_RX_DP<12>")
	)
	(segment
		(start 356.575614 -292.246812)
		(end 356.544118 -292.228524)
		(width 0.1143)
		(layer "In15.Cu")
		(net "P5E_CPU0_P0_RX_DP<12>")
	)
	(segment
		(start 356.51059 -288.363152)
		(end 356.583234 -288.320734)
		(width 0.1143)
		(layer "In15.Cu")
		(net "P5E_CPU0_P0_RX_DP<12>")
	)
	(segment
		(start 356.546658 -278.621998)
		(end 356.583234 -278.600662)
		(width 0.1143)
		(layer "In15.Cu")
		(net "P5E_CPU0_P0_RX_DP<12>")
	)
	(segment
		(start 356.512368 -289.98164)
		(end 356.512622 -289.981894)
		(width 0.1143)
		(layer "In15.Cu")
		(net "P5E_CPU0_P0_RX_DP<12>")
	)
	(segment
		(start 368.743992 -325.376794)
		(end 356.458012 -304.129694)
		(width 0.14224)
		(layer "In15.Cu")
		(net "P5E_CPU0_P0_RX_DP<12>")
	)
	(segment
		(start 356.576376 -292.24732)
		(end 356.575614 -292.246812)
		(width 0.1143)
		(layer "In15.Cu")
		(net "P5E_CPU0_P0_RX_DP<12>")
	)
	(segment
		(start 356.52329 -293.215314)
		(end 356.582726 -293.181024)
		(width 0.1143)
		(layer "In15.Cu")
		(net "P5E_CPU0_P0_RX_DP<12>")
	)
	(segment
		(start 356.544118 -287.368488)
		(end 356.512368 -287.3502)
		(width 0.1143)
		(layer "In15.Cu")
		(net "P5E_CPU0_P0_RX_DP<12>")
	)
	(segment
		(start 356.5398 -278.626062)
		(end 356.540562 -278.625554)
		(width 0.1143)
		(layer "In15.Cu")
		(net "P5E_CPU0_P0_RX_DP<12>")
	)
	(segment
		(start 356.542086 -288.98723)
		(end 356.512368 -288.970212)
		(width 0.1143)
		(layer "In15.Cu")
		(net "P5E_CPU0_P0_RX_DP<12>")
	)
	(segment
		(start 356.512368 -291.601906)
		(end 356.514146 -291.600636)
		(width 0.1143)
		(layer "In15.Cu")
		(net "P5E_CPU0_P0_RX_DP<12>")
	)
	(segment
		(start 356.563168 -274.41906)
		(end 356.562406 -274.418552)
		(width 0.1143)
		(layer "In15.Cu")
		(net "P5E_CPU0_P0_RX_DP<12>")
	)
	(segment
		(start 356.583234 -292.251384)
		(end 356.576376 -292.24732)
		(width 0.1143)
		(layer "In15.Cu")
		(net "P5E_CPU0_P0_RX_DP<12>")
	)
	(segment
		(start 329.728068 -376.136662)
		(end 332.079854 -373.784622)
		(width 0.14224)
		(layer "In15.Cu")
		(net "P5E_CPU0_P0_RX_DP<12>")
	)
	(segment
		(start 356.537514 -280.247344)
		(end 356.538276 -280.246836)
		(width 0.1143)
		(layer "In15.Cu")
		(net "P5E_CPU0_P0_RX_DP<12>")
	)
	(segment
		(start 356.543356 -278.62403)
		(end 356.544118 -278.623522)
		(width 0.1143)
		(layer "In15.Cu")
		(net "P5E_CPU0_P0_RX_DP<12>")
	)
	(segment
		(start 356.545134 -283.48305)
		(end 356.583234 -283.460698)
		(width 0.1143)
		(layer "In15.Cu")
		(net "P5E_CPU0_P0_RX_DP<12>")
	)
	(segment
		(start 356.538276 -273.766788)
		(end 356.5398 -273.766026)
		(width 0.1143)
		(layer "In15.Cu")
		(net "P5E_CPU0_P0_RX_DP<12>")
	)
	(segment
		(start 356.576376 -285.767526)
		(end 356.575614 -285.767018)
		(width 0.1143)
		(layer "In15.Cu")
		(net "P5E_CPU0_P0_RX_DP<12>")
	)
	(segment
		(start 356.544118 -290.608512)
		(end 356.543356 -290.608004)
		(width 0.1143)
		(layer "In15.Cu")
		(net "P5E_CPU0_P0_RX_DP<12>")
	)
	(segment
		(start 356.536244 -273.768058)
		(end 356.537514 -273.767296)
		(width 0.1143)
		(layer "In15.Cu")
		(net "P5E_CPU0_P0_RX_DP<12>")
	)
	(segment
		(start 356.544118 -285.10357)
		(end 356.58044 -285.082742)
		(width 0.1143)
		(layer "In15.Cu")
		(net "P5E_CPU0_P0_RX_DP<12>")
	)
	(arc
		(start 356.458012 -304.129694)
		(mid 356.416124 -304.028493)
		(end 356.401878 -303.91989)
		(width 0.14224)
		(layer "In15.Cu")
		(net "P5E_CPU0_P0_RX_DP<12>")
	)
	(arc
		(start 356.583234 -273.740626)
		(mid 356.762047 -273.538276)
		(end 356.826566 -273.27606)
		(width 0.1143)
		(layer "In15.Cu")
		(net "P5E_CPU0_P0_RX_DP<12>")
	)
	(arc
		(start 356.512368 -282.490418)
		(mid 356.35644 -282.186126)
		(end 356.512368 -281.881834)
		(width 0.1143)
		(layer "In15.Cu")
		(net "P5E_CPU0_P0_RX_DP<12>")
	)
	(arc
		(start 356.356412 -287.045908)
		(mid 356.397174 -286.876024)
		(end 356.51059 -286.74314)
		(width 0.1143)
		(layer "In15.Cu")
		(net "P5E_CPU0_P0_RX_DP<12>")
	)
	(arc
		(start 329.414632 -376.266456)
		(mid 329.584249 -376.232717)
		(end 329.728068 -376.136662)
		(width 0.14224)
		(layer "In15.Cu")
		(net "P5E_CPU0_P0_RX_DP<12>")
	)
	(arc
		(start 356.583234 -278.600662)
		(mid 356.826561 -278.136096)
		(end 356.583234 -277.67153)
		(width 0.1143)
		(layer "In15.Cu")
		(net "P5E_CPU0_P0_RX_DP<12>")
	)
	(arc
		(start 356.583234 -289.940492)
		(mid 356.826561 -289.475926)
		(end 356.583234 -289.01136)
		(width 0.1143)
		(layer "In15.Cu")
		(net "P5E_CPU0_P0_RX_DP<12>")
	)
	(arc
		(start 356.583234 -280.220674)
		(mid 356.826561 -279.756108)
		(end 356.583234 -279.291542)
		(width 0.1143)
		(layer "In15.Cu")
		(net "P5E_CPU0_P0_RX_DP<12>")
	)
	(arc
		(start 356.826566 -273.27606)
		(mid 356.868115 -273.104638)
		(end 356.983538 -272.97126)
		(width 0.1143)
		(layer "In15.Cu")
		(net "P5E_CPU0_P0_RX_DP<12>")
	)
	(arc
		(start 357.053134 -272.93062)
		(mid 357.205121 -272.774112)
		(end 357.28656 -272.571718)
		(width 0.1143)
		(layer "In15.Cu")
		(net "P5E_CPU0_P0_RX_DP<12>")
	)
	(arc
		(start 356.583234 -294.800528)
		(mid 356.826561 -294.335962)
		(end 356.583234 -293.871396)
		(width 0.1143)
		(layer "In15.Cu")
		(net "P5E_CPU0_P0_RX_DP<12>")
	)
	(arc
		(start 356.512368 -276.01037)
		(mid 356.35644 -275.706078)
		(end 356.512368 -275.401786)
		(width 0.1143)
		(layer "In15.Cu")
		(net "P5E_CPU0_P0_RX_DP<12>")
	)
	(arc
		(start 356.583234 -293.180516)
		(mid 356.826561 -292.71595)
		(end 356.583234 -292.251384)
		(width 0.1143)
		(layer "In15.Cu")
		(net "P5E_CPU0_P0_RX_DP<12>")
	)
	(arc
		(start 357.28656 -272.571718)
		(mid 357.288583 -272.560308)
		(end 357.29037 -272.548858)
		(width 0.1143)
		(layer "In15.Cu")
		(net "P5E_CPU0_P0_RX_DP<12>")
	)
	(arc
		(start 318.94018 -390.068816)
		(mid 318.965601 -389.941107)
		(end 319.03797 -389.83285)
		(width 0.14224)
		(layer "In15.Cu")
		(net "P5E_CPU0_P0_RX_DP<12>")
	)
	(arc
		(start 394.275818 -369.579906)
		(mid 395.308585 -369.374476)
		(end 396.18412 -368.789458)
		(width 0.14224)
		(layer "In15.Cu")
		(net "P5E_CPU0_P0_RX_DP<12>")
	)
	(arc
		(start 356.583234 -281.840686)
		(mid 356.826561 -281.37612)
		(end 356.583234 -280.911554)
		(width 0.1143)
		(layer "In15.Cu")
		(net "P5E_CPU0_P0_RX_DP<12>")
	)
	(arc
		(start 332.079854 -373.784622)
		(mid 332.121094 -373.757003)
		(end 332.16977 -373.747284)
		(width 0.14224)
		(layer "In15.Cu")
		(net "P5E_CPU0_P0_RX_DP<12>")
	)
	(arc
		(start 356.826566 -287.856168)
		(mid 356.76133 -287.592577)
		(end 356.580694 -287.389824)
		(width 0.1143)
		(layer "In15.Cu")
		(net "P5E_CPU0_P0_RX_DP<12>")
	)
	(arc
		(start 323.412866 -377.130056)
		(mid 323.432665 -377.030522)
		(end 323.489066 -376.94616)
		(width 0.14224)
		(layer "In15.Cu")
		(net "P5E_CPU0_P0_RX_DP<12>")
	)
	(arc
		(start 378.691394 -371.471444)
		(mid 378.861011 -371.437705)
		(end 379.00483 -371.34165)
		(width 0.14224)
		(layer "In15.Cu")
		(net "P5E_CPU0_P0_RX_DP<12>")
	)
	(arc
		(start 356.512368 -292.210236)
		(mid 356.35644 -291.905944)
		(end 356.512368 -291.601652)
		(width 0.1143)
		(layer "In15.Cu")
		(net "P5E_CPU0_P0_RX_DP<12>")
	)
	(arc
		(start 356.512368 -288.970212)
		(mid 356.397692 -288.836878)
		(end 356.356412 -288.66592)
		(width 0.1143)
		(layer "In15.Cu")
		(net "P5E_CPU0_P0_RX_DP<12>")
	)
	(arc
		(start 324.131432 -376.303794)
		(mid 324.172802 -376.276151)
		(end 324.221602 -376.266456)
		(width 0.14224)
		(layer "In15.Cu")
		(net "P5E_CPU0_P0_RX_DP<12>")
	)
	(arc
		(start 356.583234 -288.320734)
		(mid 356.762047 -288.118384)
		(end 356.826566 -287.856168)
		(width 0.1143)
		(layer "In15.Cu")
		(net "P5E_CPU0_P0_RX_DP<12>")
	)
	(arc
		(start 356.512368 -285.730442)
		(mid 356.35644 -285.42615)
		(end 356.512368 -285.121858)
		(width 0.1143)
		(layer "In15.Cu")
		(net "P5E_CPU0_P0_RX_DP<12>")
	)
	(arc
		(start 356.512368 -290.590224)
		(mid 356.35644 -290.285932)
		(end 356.512368 -289.98164)
		(width 0.1143)
		(layer "In15.Cu")
		(net "P5E_CPU0_P0_RX_DP<12>")
	)
	(arc
		(start 356.512368 -293.830248)
		(mid 356.35644 -293.525956)
		(end 356.512368 -293.221664)
		(width 0.1143)
		(layer "In15.Cu")
		(net "P5E_CPU0_P0_RX_DP<12>")
	)
	(arc
		(start 356.512368 -274.390358)
		(mid 356.35644 -274.086066)
		(end 356.512368 -273.781774)
		(width 0.1143)
		(layer "In15.Cu")
		(net "P5E_CPU0_P0_RX_DP<12>")
	)
	(arc
		(start 356.512368 -287.3502)
		(mid 356.397692 -287.216866)
		(end 356.356412 -287.045908)
		(width 0.1143)
		(layer "In15.Cu")
		(net "P5E_CPU0_P0_RX_DP<12>")
	)
	(arc
		(start 356.583234 -286.700722)
		(mid 356.826561 -286.236156)
		(end 356.583234 -285.77159)
		(width 0.1143)
		(layer "In15.Cu")
		(net "P5E_CPU0_P0_RX_DP<12>")
	)
	(arc
		(start 356.512368 -284.11043)
		(mid 356.35644 -283.806138)
		(end 356.512368 -283.501846)
		(width 0.1143)
		(layer "In15.Cu")
		(net "P5E_CPU0_P0_RX_DP<12>")
	)
	(arc
		(start 356.356412 -295.145968)
		(mid 356.397667 -294.974997)
		(end 356.512368 -294.841676)
		(width 0.1143)
		(layer "In15.Cu")
		(net "P5E_CPU0_P0_RX_DP<12>")
	)
	(arc
		(start 322.712334 -386.158486)
		(mid 323.230826 -385.382602)
		(end 323.412866 -384.467354)
		(width 0.14224)
		(layer "In15.Cu")
		(net "P5E_CPU0_P0_RX_DP<12>")
	)
	(arc
		(start 356.583234 -283.460698)
		(mid 356.826561 -282.996132)
		(end 356.583234 -282.531566)
		(width 0.1143)
		(layer "In15.Cu")
		(net "P5E_CPU0_P0_RX_DP<12>")
	)
	(arc
		(start 356.583234 -291.560504)
		(mid 356.826561 -291.095938)
		(end 356.583234 -290.631372)
		(width 0.1143)
		(layer "In15.Cu")
		(net "P5E_CPU0_P0_RX_DP<12>")
	)
	(arc
		(start 356.356412 -288.66592)
		(mid 356.397174 -288.496036)
		(end 356.51059 -288.363152)
		(width 0.1143)
		(layer "In15.Cu")
		(net "P5E_CPU0_P0_RX_DP<12>")
	)
	(arc
		(start 369.325906 -326.126856)
		(mid 369.00952 -325.771555)
		(end 368.743992 -325.376794)
		(width 0.14224)
		(layer "In15.Cu")
		(net "P5E_CPU0_P0_RX_DP<12>")
	)
	(arc
		(start 356.583234 -275.360638)
		(mid 356.826561 -274.896072)
		(end 356.583234 -274.431506)
		(width 0.1143)
		(layer "In15.Cu")
		(net "P5E_CPU0_P0_RX_DP<12>")
	)
	(arc
		(start 356.512368 -277.630382)
		(mid 356.35644 -277.32609)
		(end 356.512368 -277.021798)
		(width 0.1143)
		(layer "In15.Cu")
		(net "P5E_CPU0_P0_RX_DP<12>")
	)
	(arc
		(start 396.440406 -368.533172)
		(mid 396.928608 -367.802621)
		(end 397.100044 -366.940846)
		(width 0.14224)
		(layer "In15.Cu")
		(net "P5E_CPU0_P0_RX_DP<12>")
	)
	(arc
		(start 356.512368 -280.870406)
		(mid 356.35644 -280.566114)
		(end 356.512368 -280.261822)
		(width 0.1143)
		(layer "In15.Cu")
		(net "P5E_CPU0_P0_RX_DP<12>")
	)
	(arc
		(start 397.100044 -354.06838)
		(mid 396.969077 -353.418238)
		(end 396.596616 -352.8695)
		(width 0.14224)
		(layer "In15.Cu")
		(net "P5E_CPU0_P0_RX_DP<12>")
	)
	(arc
		(start 356.583234 -276.98065)
		(mid 356.826561 -276.516084)
		(end 356.583234 -276.051518)
		(width 0.1143)
		(layer "In15.Cu")
		(net "P5E_CPU0_P0_RX_DP<12>")
	)
	(arc
		(start 380.71933 -369.62715)
		(mid 380.771655 -369.592188)
		(end 380.833376 -369.579906)
		(width 0.14224)
		(layer "In15.Cu")
		(net "P5E_CPU0_P0_RX_DP<12>")
	)
	(arc
		(start 356.583234 -285.08071)
		(mid 356.826561 -284.616144)
		(end 356.583234 -284.151578)
		(width 0.1143)
		(layer "In15.Cu")
		(net "P5E_CPU0_P0_RX_DP<12>")
	)
	(arc
		(start 356.512368 -279.250394)
		(mid 356.35644 -278.946102)
		(end 356.512368 -278.64181)
		(width 0.1143)
		(layer "In15.Cu")
		(net "P5E_CPU0_P0_RX_DP<12>")
	)
	(segment
		(start 355.78796 -269.770098)
		(end 355.321108 -270.036036)
		(width 0.12954)
		(layer "F.Cu")
		(net "P5E_CPU0_P0_RX_DP<11>")
	)
	(segment
		(start 316.870334 -394.385292)
		(end 317.391034 -394.385292)
		(width 0.127)
		(layer "F.Cu")
		(net "P5E_CPU0_P0_RX_DP<11>")
	)
	(segment
		(start 320.339466 -378.406152)
		(end 320.291206 -378.357892)
		(width 0.14224)
		(layer "In15.Cu")
		(net "P5E_CPU0_P0_RX_DP<11>")
	)
	(segment
		(start 355.625146 -291.571172)
		(end 355.64318 -291.560504)
		(width 0.1143)
		(layer "In15.Cu")
		(net "P5E_CPU0_P0_RX_DP<11>")
	)
	(segment
		(start 346.52712 -371.675406)
		(end 346.23502 -371.383306)
		(width 0.14224)
		(layer "In15.Cu")
		(net "P5E_CPU0_P0_RX_DP<11>")
	)
	(segment
		(start 355.604064 -274.408646)
		(end 355.603302 -274.408138)
		(width 0.1143)
		(layer "In15.Cu")
		(net "P5E_CPU0_P0_RX_DP<11>")
	)
	(segment
		(start 355.552502 -277.036022)
		(end 355.572314 -277.021798)
		(width 0.1143)
		(layer "In15.Cu")
		(net "P5E_CPU0_P0_RX_DP<11>")
	)
	(segment
		(start 355.603302 -276.02815)
		(end 355.572314 -276.01037)
		(width 0.1143)
		(layer "In15.Cu")
		(net "P5E_CPU0_P0_RX_DP<11>")
	)
	(segment
		(start 355.190552 -296.340276)
		(end 355.12883 -296.283634)
		(width 0.1143)
		(layer "In15.Cu")
		(net "P5E_CPU0_P0_RX_DP<11>")
	)
	(segment
		(start 355.64318 -282.531566)
		(end 355.606604 -282.51023)
		(width 0.1143)
		(layer "In15.Cu")
		(net "P5E_CPU0_P0_RX_DP<11>")
	)
	(segment
		(start 355.625146 -289.95116)
		(end 355.64318 -289.940492)
		(width 0.1143)
		(layer "In15.Cu")
		(net "P5E_CPU0_P0_RX_DP<11>")
	)
	(segment
		(start 338.93252 -370.527326)
		(end 377.550172 -370.527326)
		(width 0.14224)
		(layer "In15.Cu")
		(net "P5E_CPU0_P0_RX_DP<11>")
	)
	(segment
		(start 355.604572 -288.343086)
		(end 355.637592 -288.323528)
		(width 0.1143)
		(layer "In15.Cu")
		(net "P5E_CPU0_P0_RX_DP<11>")
	)
	(segment
		(start 317.911988 -389.490712)
		(end 321.126612 -386.276088)
		(width 0.14224)
		(layer "In15.Cu")
		(net "P5E_CPU0_P0_RX_DP<11>")
	)
	(segment
		(start 354.946458 -296.04843)
		(end 354.946458 -295.93921)
		(width 0.1143)
		(layer "In15.Cu")
		(net "P5E_CPU0_P0_RX_DP<11>")
	)
	(segment
		(start 355.60508 -294.82288)
		(end 355.64318 -294.800528)
		(width 0.1143)
		(layer "In15.Cu")
		(net "P5E_CPU0_P0_RX_DP<11>")
	)
	(segment
		(start 355.63556 -293.866824)
		(end 355.60508 -293.849044)
		(width 0.1143)
		(layer "In15.Cu")
		(net "P5E_CPU0_P0_RX_DP<11>")
	)
	(segment
		(start 355.603302 -275.384006)
		(end 355.604064 -275.383498)
		(width 0.1143)
		(layer "In15.Cu")
		(net "P5E_CPU0_P0_RX_DP<11>")
	)
	(segment
		(start 355.603302 -273.763994)
		(end 355.604064 -273.763486)
		(width 0.1143)
		(layer "In15.Cu")
		(net "P5E_CPU0_P0_RX_DP<11>")
	)
	(segment
		(start 355.603302 -294.823896)
		(end 355.604064 -294.823388)
		(width 0.1143)
		(layer "In15.Cu")
		(net "P5E_CPU0_P0_RX_DP<11>")
	)
	(segment
		(start 320.952876 -378.590556)
		(end 320.72961 -378.497592)
		(width 0.14224)
		(layer "In15.Cu")
		(net "P5E_CPU0_P0_RX_DP<11>")
	)
	(segment
		(start 355.572314 -277.021798)
		(end 355.603302 -277.004018)
		(width 0.1143)
		(layer "In15.Cu")
		(net "P5E_CPU0_P0_RX_DP<11>")
	)
	(segment
		(start 355.622352 -286.712914)
		(end 355.64318 -286.700722)
		(width 0.1143)
		(layer "In15.Cu")
		(net "P5E_CPU0_P0_RX_DP<11>")
	)
	(segment
		(start 355.603302 -272.143982)
		(end 355.604064 -272.143474)
		(width 0.1143)
		(layer "In15.Cu")
		(net "P5E_CPU0_P0_RX_DP<11>")
	)
	(segment
		(start 317.432436 -393.113006)
		(end 317.435484 -392.7348)
		(width 0.14224)
		(layer "In15.Cu")
		(net "P5E_CPU0_P0_RX_DP<11>")
	)
	(segment
		(start 355.572314 -285.121858)
		(end 355.603302 -285.104078)
		(width 0.1143)
		(layer "In15.Cu")
		(net "P5E_CPU0_P0_RX_DP<11>")
	)
	(segment
		(start 367.9444 -326.01535)
		(end 355.334316 -304.368708)
		(width 0.14224)
		(layer "In15.Cu")
		(net "P5E_CPU0_P0_RX_DP<11>")
	)
	(segment
		(start 355.603302 -293.848028)
		(end 355.572314 -293.830248)
		(width 0.1143)
		(layer "In15.Cu")
		(net "P5E_CPU0_P0_RX_DP<11>")
	)
	(segment
		(start 355.642418 -287.391094)
		(end 355.638862 -287.389062)
		(width 0.1143)
		(layer "In15.Cu")
		(net "P5E_CPU0_P0_RX_DP<11>")
	)
	(segment
		(start 355.64318 -285.77159)
		(end 355.606604 -285.750254)
		(width 0.1143)
		(layer "In15.Cu")
		(net "P5E_CPU0_P0_RX_DP<11>")
	)
	(segment
		(start 355.572314 -279.250394)
		(end 355.552502 -279.23617)
		(width 0.1143)
		(layer "In15.Cu")
		(net "P5E_CPU0_P0_RX_DP<11>")
	)
	(segment
		(start 355.604064 -294.823388)
		(end 355.60508 -294.82288)
		(width 0.1143)
		(layer "In15.Cu")
		(net "P5E_CPU0_P0_RX_DP<11>")
	)
	(segment
		(start 317.48603 -394.031216)
		(end 317.660274 -393.930632)
		(width 0.14224)
		(layer "In15.Cu")
		(net "P5E_CPU0_P0_RX_DP<11>")
	)
	(segment
		(start 355.603302 -282.508198)
		(end 355.572314 -282.490418)
		(width 0.1143)
		(layer "In15.Cu")
		(net "P5E_CPU0_P0_RX_DP<11>")
	)
	(segment
		(start 355.572314 -293.221664)
		(end 355.604064 -293.203376)
		(width 0.1143)
		(layer "In15.Cu")
		(net "P5E_CPU0_P0_RX_DP<11>")
	)
	(segment
		(start 355.64318 -272.811494)
		(end 355.636322 -272.80743)
		(width 0.1143)
		(layer "In15.Cu")
		(net "P5E_CPU0_P0_RX_DP<11>")
	)
	(segment
		(start 355.60508 -277.649178)
		(end 355.604064 -277.64867)
		(width 0.1143)
		(layer "In15.Cu")
		(net "P5E_CPU0_P0_RX_DP<11>")
	)
	(segment
		(start 355.604064 -272.143474)
		(end 355.60508 -272.142966)
		(width 0.1143)
		(layer "In15.Cu")
		(net "P5E_CPU0_P0_RX_DP<11>")
	)
	(segment
		(start 355.594412 -287.362138)
		(end 355.487478 -287.255204)
		(width 0.1143)
		(layer "In15.Cu")
		(net "P5E_CPU0_P0_RX_DP<11>")
	)
	(segment
		(start 355.604064 -284.128718)
		(end 355.603302 -284.12821)
		(width 0.1143)
		(layer "In15.Cu")
		(net "P5E_CPU0_P0_RX_DP<11>")
	)
	(segment
		(start 355.642418 -290.630864)
		(end 355.6127 -290.613592)
		(width 0.1143)
		(layer "In15.Cu")
		(net "P5E_CPU0_P0_RX_DP<11>")
	)
	(segment
		(start 355.604064 -279.268682)
		(end 355.603302 -279.268174)
		(width 0.1143)
		(layer "In15.Cu")
		(net "P5E_CPU0_P0_RX_DP<11>")
	)
	(segment
		(start 355.606604 -282.51023)
		(end 355.60508 -282.509214)
		(width 0.1143)
		(layer "In15.Cu")
		(net "P5E_CPU0_P0_RX_DP<11>")
	)
	(segment
		(start 395.22019 -367.965482)
		(end 395.46784 -367.717832)
		(width 0.14224)
		(layer "In15.Cu")
		(net "P5E_CPU0_P0_RX_DP<11>")
	)
	(segment
		(start 355.64318 -284.151578)
		(end 355.606604 -284.130242)
		(width 0.1143)
		(layer "In15.Cu")
		(net "P5E_CPU0_P0_RX_DP<11>")
	)
	(segment
		(start 355.604064 -283.483558)
		(end 355.60508 -283.48305)
		(width 0.1143)
		(layer "In15.Cu")
		(net "P5E_CPU0_P0_RX_DP<11>")
	)
	(segment
		(start 355.572314 -278.64181)
		(end 355.603302 -278.62403)
		(width 0.1143)
		(layer "In15.Cu")
		(net "P5E_CPU0_P0_RX_DP<11>")
	)
	(segment
		(start 355.624892 -291.571172)
		(end 355.625146 -291.571172)
		(width 0.1143)
		(layer "In15.Cu")
		(net "P5E_CPU0_P0_RX_DP<11>")
	)
	(segment
		(start 355.642418 -289.010852)
		(end 355.59111 -288.981134)
		(width 0.1143)
		(layer "In15.Cu")
		(net "P5E_CPU0_P0_RX_DP<11>")
	)
	(segment
		(start 355.64318 -274.431506)
		(end 355.606604 -274.41017)
		(width 0.1143)
		(layer "In15.Cu")
		(net "P5E_CPU0_P0_RX_DP<11>")
	)
	(segment
		(start 355.590856 -288.35096)
		(end 355.59111 -288.350706)
		(width 0.1143)
		(layer "In15.Cu")
		(net "P5E_CPU0_P0_RX_DP<11>")
	)
	(segment
		(start 355.64318 -279.291542)
		(end 355.606604 -279.270206)
		(width 0.1143)
		(layer "In15.Cu")
		(net "P5E_CPU0_P0_RX_DP<11>")
	)
	(segment
		(start 355.553518 -280.275538)
		(end 355.572314 -280.261822)
		(width 0.1143)
		(layer "In15.Cu")
		(net "P5E_CPU0_P0_RX_DP<11>")
	)
	(segment
		(start 355.572314 -272.161762)
		(end 355.603302 -272.143982)
		(width 0.1143)
		(layer "In15.Cu")
		(net "P5E_CPU0_P0_RX_DP<11>")
	)
	(segment
		(start 355.572314 -281.881834)
		(end 355.603302 -281.864054)
		(width 0.1143)
		(layer "In15.Cu")
		(net "P5E_CPU0_P0_RX_DP<11>")
	)
	(segment
		(start 355.60508 -278.623014)
		(end 355.64318 -278.600662)
		(width 0.1143)
		(layer "In15.Cu")
		(net "P5E_CPU0_P0_RX_DP<11>")
	)
	(segment
		(start 320.54927 -376.403616)
		(end 323.149468 -375.326656)
		(width 0.14224)
		(layer "In15.Cu")
		(net "P5E_CPU0_P0_RX_DP<11>")
	)
	(segment
		(start 355.610668 -275.379942)
		(end 355.612954 -275.378672)
		(width 0.1143)
		(layer "In15.Cu")
		(net "P5E_CPU0_P0_RX_DP<11>")
	)
	(segment
		(start 355.612954 -275.378672)
		(end 355.614478 -275.377656)
		(width 0.1143)
		(layer "In15.Cu")
		(net "P5E_CPU0_P0_RX_DP<11>")
	)
	(segment
		(start 317.740284 -392.43)
		(end 317.740284 -389.90524)
		(width 0.14224)
		(layer "In15.Cu")
		(net "P5E_CPU0_P0_RX_DP<11>")
	)
	(segment
		(start 355.604064 -273.763486)
		(end 355.60508 -273.762978)
		(width 0.1143)
		(layer "In15.Cu")
		(net "P5E_CPU0_P0_RX_DP<11>")
	)
	(segment
		(start 355.60508 -285.749238)
		(end 355.604064 -285.74873)
		(width 0.1143)
		(layer "In15.Cu")
		(net "P5E_CPU0_P0_RX_DP<11>")
	)
	(segment
		(start 355.6127 -290.613592)
		(end 355.610414 -290.612068)
		(width 0.1143)
		(layer "In15.Cu")
		(net "P5E_CPU0_P0_RX_DP<11>")
	)
	(segment
		(start 355.603302 -271.168114)
		(end 355.572314 -271.150334)
		(width 0.1143)
		(layer "In15.Cu")
		(net "P5E_CPU0_P0_RX_DP<11>")
	)
	(segment
		(start 355.236272 -296.61231)
		(end 355.236272 -296.583862)
		(width 0.1143)
		(layer "In15.Cu")
		(net "P5E_CPU0_P0_RX_DP<11>")
	)
	(segment
		(start 355.59746 -287.36417)
		(end 355.594412 -287.362138)
		(width 0.1143)
		(layer "In15.Cu")
		(net "P5E_CPU0_P0_RX_DP<11>")
	)
	(segment
		(start 355.636068 -292.247066)
		(end 355.612192 -292.23335)
		(width 0.1143)
		(layer "In15.Cu")
		(net "P5E_CPU0_P0_RX_DP<11>")
	)
	(segment
		(start 355.603302 -277.004018)
		(end 355.604064 -277.00351)
		(width 0.1143)
		(layer "In15.Cu")
		(net "P5E_CPU0_P0_RX_DP<11>")
	)
	(segment
		(start 355.604064 -282.508706)
		(end 355.603302 -282.508198)
		(width 0.1143)
		(layer "In15.Cu")
		(net "P5E_CPU0_P0_RX_DP<11>")
	)
	(segment
		(start 355.59111 -288.350706)
		(end 355.604572 -288.343086)
		(width 0.1143)
		(layer "In15.Cu")
		(net "P5E_CPU0_P0_RX_DP<11>")
	)
	(segment
		(start 355.60508 -284.129226)
		(end 355.604064 -284.128718)
		(width 0.1143)
		(layer "In15.Cu")
		(net "P5E_CPU0_P0_RX_DP<11>")
	)
	(segment
		(start 355.58857 -294.832024)
		(end 355.603302 -294.823896)
		(width 0.1143)
		(layer "In15.Cu")
		(net "P5E_CPU0_P0_RX_DP<11>")
	)
	(segment
		(start 355.572314 -277.630382)
		(end 355.552502 -277.616158)
		(width 0.1143)
		(layer "In15.Cu")
		(net "P5E_CPU0_P0_RX_DP<11>")
	)
	(segment
		(start 355.572314 -275.401786)
		(end 355.603302 -275.384006)
		(width 0.1143)
		(layer "In15.Cu")
		(net "P5E_CPU0_P0_RX_DP<11>")
	)
	(segment
		(start 355.12883 -296.283634)
		(end 354.98405 -296.1386)
		(width 0.1143)
		(layer "In15.Cu")
		(net "P5E_CPU0_P0_RX_DP<11>")
	)
	(segment
		(start 346.23502 -371.383306)
		(end 338.93252 -371.383306)
		(width 0.14224)
		(layer "In15.Cu")
		(net "P5E_CPU0_P0_RX_DP<11>")
	)
	(segment
		(start 355.552502 -275.41601)
		(end 355.572314 -275.401786)
		(width 0.1143)
		(layer "In15.Cu")
		(net "P5E_CPU0_P0_RX_DP<11>")
	)
	(segment
		(start 355.170486 -270.379698)
		(end 355.156262 -270.371316)
		(width 0.1143)
		(layer "In15.Cu")
		(net "P5E_CPU0_P0_RX_DP<11>")
	)
	(segment
		(start 355.606604 -274.41017)
		(end 355.60508 -274.409154)
		(width 0.1143)
		(layer "In15.Cu")
		(net "P5E_CPU0_P0_RX_DP<11>")
	)
	(segment
		(start 320.008758 -377.676156)
		(end 320.008758 -376.983244)
		(width 0.14224)
		(layer "In15.Cu")
		(net "P5E_CPU0_P0_RX_DP<11>")
	)
	(segment
		(start 329.019408 -375.197116)
		(end 331.366114 -372.85041)
		(width 0.14224)
		(layer "In15.Cu")
		(net "P5E_CPU0_P0_RX_DP<11>")
	)
	(segment
		(start 396.051278 -366.309148)
		(end 396.051278 -354.647754)
		(width 0.14224)
		(layer "In15.Cu")
		(net "P5E_CPU0_P0_RX_DP<11>")
	)
	(segment
		(start 355.606604 -279.270206)
		(end 355.60508 -279.26919)
		(width 0.1143)
		(layer "In15.Cu")
		(net "P5E_CPU0_P0_RX_DP<11>")
	)
	(segment
		(start 355.023166 -270.036036)
		(end 355.321108 -270.036036)
		(width 0.1143)
		(layer "In15.Cu")
		(net "P5E_CPU0_P0_RX_DP<11>")
	)
	(segment
		(start 355.572314 -273.781774)
		(end 355.603302 -273.763994)
		(width 0.1143)
		(layer "In15.Cu")
		(net "P5E_CPU0_P0_RX_DP<11>")
	)
	(segment
		(start 355.604064 -277.64867)
		(end 355.603302 -277.648162)
		(width 0.1143)
		(layer "In15.Cu")
		(net "P5E_CPU0_P0_RX_DP<11>")
	)
	(segment
		(start 355.64318 -277.67153)
		(end 355.606604 -277.650194)
		(width 0.1143)
		(layer "In15.Cu")
		(net "P5E_CPU0_P0_RX_DP<11>")
	)
	(segment
		(start 355.60508 -276.029166)
		(end 355.604064 -276.028658)
		(width 0.1143)
		(layer "In15.Cu")
		(net "P5E_CPU0_P0_RX_DP<11>")
	)
	(segment
		(start 355.603302 -285.748222)
		(end 355.572314 -285.730442)
		(width 0.1143)
		(layer "In15.Cu")
		(net "P5E_CPU0_P0_RX_DP<11>")
	)
	(segment
		(start 355.607874 -275.381466)
		(end 355.610668 -275.379942)
		(width 0.1143)
		(layer "In15.Cu")
		(net "P5E_CPU0_P0_RX_DP<11>")
	)
	(segment
		(start 355.604064 -278.623522)
		(end 355.60508 -278.623014)
		(width 0.1143)
		(layer "In15.Cu")
		(net "P5E_CPU0_P0_RX_DP<11>")
	)
	(segment
		(start 321.552316 -379.189996)
		(end 320.952876 -378.590556)
		(width 0.14224)
		(layer "In15.Cu")
		(net "P5E_CPU0_P0_RX_DP<11>")
	)
	(segment
		(start 355.614478 -275.377656)
		(end 355.615748 -275.376894)
		(width 0.1143)
		(layer "In15.Cu")
		(net "P5E_CPU0_P0_RX_DP<11>")
	)
	(segment
		(start 355.419152 -287.090358)
		(end 355.419152 -287.000442)
		(width 0.1143)
		(layer "In15.Cu")
		(net "P5E_CPU0_P0_RX_DP<11>")
	)
	(segment
		(start 355.190552 -296.538142)
		(end 355.190552 -296.340276)
		(width 0.1143)
		(layer "In15.Cu")
		(net "P5E_CPU0_P0_RX_DP<11>")
	)
	(segment
		(start 317.435484 -392.7348)
		(end 317.740284 -392.43)
		(width 0.14224)
		(layer "In15.Cu")
		(net "P5E_CPU0_P0_RX_DP<11>")
	)
	(segment
		(start 355.604064 -280.243534)
		(end 355.60508 -280.243026)
		(width 0.1143)
		(layer "In15.Cu")
		(net "P5E_CPU0_P0_RX_DP<11>")
	)
	(segment
		(start 331.48016 -372.803166)
		(end 346.23502 -372.803166)
		(width 0.14224)
		(layer "In15.Cu")
		(net "P5E_CPU0_P0_RX_DP<11>")
	)
	(segment
		(start 396.051278 -354.647754)
		(end 396.049754 -354.52558)
		(width 0.14224)
		(layer "In15.Cu")
		(net "P5E_CPU0_P0_RX_DP<11>")
	)
	(segment
		(start 355.636322 -271.187418)
		(end 355.63556 -271.18691)
		(width 0.1143)
		(layer "In15.Cu")
		(net "P5E_CPU0_P0_RX_DP<11>")
	)
	(segment
		(start 355.603302 -283.484066)
		(end 355.604064 -283.483558)
		(width 0.1143)
		(layer "In15.Cu")
		(net "P5E_CPU0_P0_RX_DP<11>")
	)
	(segment
		(start 355.606604 -285.750254)
		(end 355.60508 -285.749238)
		(width 0.1143)
		(layer "In15.Cu")
		(net "P5E_CPU0_P0_RX_DP<11>")
	)
	(segment
		(start 355.604064 -293.203376)
		(end 355.640386 -293.182548)
		(width 0.1143)
		(layer "In15.Cu")
		(net "P5E_CPU0_P0_RX_DP<11>")
	)
	(segment
		(start 355.603302 -274.408138)
		(end 355.572314 -274.390358)
		(width 0.1143)
		(layer "In15.Cu")
		(net "P5E_CPU0_P0_RX_DP<11>")
	)
	(segment
		(start 355.604064 -277.00351)
		(end 355.60508 -277.003002)
		(width 0.1143)
		(layer "In15.Cu")
		(net "P5E_CPU0_P0_RX_DP<11>")
	)
	(segment
		(start 355.60508 -281.863038)
		(end 355.64318 -281.840686)
		(width 0.1143)
		(layer "In15.Cu")
		(net "P5E_CPU0_P0_RX_DP<11>")
	)
	(segment
		(start 355.64318 -276.051518)
		(end 355.606604 -276.030182)
		(width 0.1143)
		(layer "In15.Cu")
		(net "P5E_CPU0_P0_RX_DP<11>")
	)
	(segment
		(start 355.603302 -284.12821)
		(end 355.572314 -284.11043)
		(width 0.1143)
		(layer "In15.Cu")
		(net "P5E_CPU0_P0_RX_DP<11>")
	)
	(segment
		(start 355.606604 -273.761962)
		(end 355.64318 -273.740626)
		(width 0.1143)
		(layer "In15.Cu")
		(net "P5E_CPU0_P0_RX_DP<11>")
	)
	(segment
		(start 355.64318 -280.911554)
		(end 355.60508 -280.889202)
		(width 0.1143)
		(layer "In15.Cu")
		(net "P5E_CPU0_P0_RX_DP<11>")
	)
	(segment
		(start 320.404744 -378.433076)
		(end 320.339466 -378.406152)
		(width 0.14224)
		(layer "In15.Cu")
		(net "P5E_CPU0_P0_RX_DP<11>")
	)
	(segment
		(start 355.640386 -293.182548)
		(end 355.64318 -293.180516)
		(width 0.1143)
		(layer "In15.Cu")
		(net "P5E_CPU0_P0_RX_DP<11>")
	)
	(segment
		(start 317.391034 -394.385292)
		(end 317.48603 -394.031216)
		(width 0.14224)
		(layer "In15.Cu")
		(net "P5E_CPU0_P0_RX_DP<11>")
	)
	(segment
		(start 355.603556 -291.583618)
		(end 355.624892 -291.571172)
		(width 0.1143)
		(layer "In15.Cu")
		(net "P5E_CPU0_P0_RX_DP<11>")
	)
	(segment
		(start 377.863608 -370.397532)
		(end 379.612144 -368.648996)
		(width 0.14224)
		(layer "In15.Cu")
		(net "P5E_CPU0_P0_RX_DP<11>")
	)
	(segment
		(start 355.609398 -292.231572)
		(end 355.608636 -292.231064)
		(width 0.1143)
		(layer "In15.Cu")
		(net "P5E_CPU0_P0_RX_DP<11>")
	)
	(segment
		(start 355.572314 -283.501846)
		(end 355.603302 -283.484066)
		(width 0.1143)
		(layer "In15.Cu")
		(net "P5E_CPU0_P0_RX_DP<11>")
	)
	(segment
		(start 355.574346 -286.740346)
		(end 355.603556 -286.723328)
		(width 0.1143)
		(layer "In15.Cu")
		(net "P5E_CPU0_P0_RX_DP<11>")
	)
	(segment
		(start 355.572314 -276.01037)
		(end 355.552502 -275.996146)
		(width 0.1143)
		(layer "In15.Cu")
		(net "P5E_CPU0_P0_RX_DP<11>")
	)
	(segment
		(start 346.52712 -372.511066)
		(end 346.52712 -371.675406)
		(width 0.14224)
		(layer "In15.Cu")
		(net "P5E_CPU0_P0_RX_DP<11>")
	)
	(segment
		(start 355.603302 -278.62403)
		(end 355.604064 -278.623522)
		(width 0.1143)
		(layer "In15.Cu")
		(net "P5E_CPU0_P0_RX_DP<11>")
	)
	(segment
		(start 355.552502 -283.51607)
		(end 355.572314 -283.501846)
		(width 0.1143)
		(layer "In15.Cu")
		(net "P5E_CPU0_P0_RX_DP<11>")
	)
	(segment
		(start 355.615748 -275.376894)
		(end 355.64318 -275.360638)
		(width 0.1143)
		(layer "In15.Cu")
		(net "P5E_CPU0_P0_RX_DP<11>")
	)
	(segment
		(start 395.43228 -353.08413)
		(end 368.405918 -326.608186)
		(width 0.14224)
		(layer "In15.Cu")
		(net "P5E_CPU0_P0_RX_DP<11>")
	)
	(segment
		(start 355.60508 -273.762978)
		(end 355.606604 -273.761962)
		(width 0.1143)
		(layer "In15.Cu")
		(net "P5E_CPU0_P0_RX_DP<11>")
	)
	(segment
		(start 355.60508 -274.409154)
		(end 355.604064 -274.408646)
		(width 0.1143)
		(layer "In15.Cu")
		(net "P5E_CPU0_P0_RX_DP<11>")
	)
	(segment
		(start 355.60508 -280.243026)
		(end 355.64318 -280.220674)
		(width 0.1143)
		(layer "In15.Cu")
		(net "P5E_CPU0_P0_RX_DP<11>")
	)
	(segment
		(start 355.604064 -293.848536)
		(end 355.603302 -293.848028)
		(width 0.1143)
		(layer "In15.Cu")
		(net "P5E_CPU0_P0_RX_DP<11>")
	)
	(segment
		(start 355.64318 -271.191482)
		(end 355.636322 -271.187418)
		(width 0.1143)
		(layer "In15.Cu")
		(net "P5E_CPU0_P0_RX_DP<11>")
	)
	(segment
		(start 355.572314 -282.490418)
		(end 355.552502 -282.476194)
		(width 0.1143)
		(layer "In15.Cu")
		(net "P5E_CPU0_P0_RX_DP<11>")
	)
	(segment
		(start 355.603302 -280.888186)
		(end 355.572314 -280.870406)
		(width 0.1143)
		(layer "In15.Cu")
		(net "P5E_CPU0_P0_RX_DP<11>")
	)
	(segment
		(start 355.60508 -277.003002)
		(end 355.609652 -277.000208)
		(width 0.1143)
		(layer "In15.Cu")
		(net "P5E_CPU0_P0_RX_DP<11>")
	)
	(segment
		(start 338.79028 -371.241066)
		(end 338.79028 -370.669566)
		(width 0.14224)
		(layer "In15.Cu")
		(net "P5E_CPU0_P0_RX_DP<11>")
	)
	(segment
		(start 355.603302 -280.244042)
		(end 355.604064 -280.243534)
		(width 0.1143)
		(layer "In15.Cu")
		(net "P5E_CPU0_P0_RX_DP<11>")
	)
	(segment
		(start 355.638862 -287.389062)
		(end 355.59746 -287.36417)
		(width 0.1143)
		(layer "In15.Cu")
		(net "P5E_CPU0_P0_RX_DP<11>")
	)
	(segment
		(start 355.606858 -275.381974)
		(end 355.607874 -275.381466)
		(width 0.1143)
		(layer "In15.Cu")
		(net "P5E_CPU0_P0_RX_DP<11>")
	)
	(segment
		(start 321.711066 -384.865372)
		(end 321.711066 -379.573282)
		(width 0.14224)
		(layer "In15.Cu")
		(net "P5E_CPU0_P0_RX_DP<11>")
	)
	(segment
		(start 355.134164 -270.358616)
		(end 355.102414 -270.340328)
		(width 0.1143)
		(layer "In15.Cu")
		(net "P5E_CPU0_P0_RX_DP<11>")
	)
	(segment
		(start 355.603556 -289.963606)
		(end 355.624892 -289.95116)
		(width 0.1143)
		(layer "In15.Cu")
		(net "P5E_CPU0_P0_RX_DP<11>")
	)
	(segment
		(start 379.72619 -368.601752)
		(end 393.684252 -368.601752)
		(width 0.14224)
		(layer "In15.Cu")
		(net "P5E_CPU0_P0_RX_DP<11>")
	)
	(segment
		(start 355.552502 -281.896058)
		(end 355.572314 -281.881834)
		(width 0.1143)
		(layer "In15.Cu")
		(net "P5E_CPU0_P0_RX_DP<11>")
	)
	(segment
		(start 355.606604 -284.130242)
		(end 355.60508 -284.129226)
		(width 0.1143)
		(layer "In15.Cu")
		(net "P5E_CPU0_P0_RX_DP<11>")
	)
	(segment
		(start 323.198236 -375.317004)
		(end 328.730102 -375.317004)
		(width 0.14224)
		(layer "In15.Cu")
		(net "P5E_CPU0_P0_RX_DP<11>")
	)
	(segment
		(start 355.636322 -293.867332)
		(end 355.63556 -293.866824)
		(width 0.1143)
		(layer "In15.Cu")
		(net "P5E_CPU0_P0_RX_DP<11>")
	)
	(segment
		(start 355.603556 -286.723328)
		(end 355.604064 -286.723582)
		(width 0.1143)
		(layer "In15.Cu")
		(net "P5E_CPU0_P0_RX_DP<11>")
	)
	(segment
		(start 355.60508 -285.103062)
		(end 355.64318 -285.08071)
		(width 0.1143)
		(layer "In15.Cu")
		(net "P5E_CPU0_P0_RX_DP<11>")
	)
	(segment
		(start 355.604064 -286.723582)
		(end 355.622352 -286.712914)
		(width 0.1143)
		(layer "In15.Cu")
		(net "P5E_CPU0_P0_RX_DP<11>")
	)
	(segment
		(start 338.79028 -370.669566)
		(end 338.93252 -370.527326)
		(width 0.14224)
		(layer "In15.Cu")
		(net "P5E_CPU0_P0_RX_DP<11>")
	)
	(segment
		(start 355.604064 -272.788634)
		(end 355.603302 -272.788126)
		(width 0.1143)
		(layer "In15.Cu")
		(net "P5E_CPU0_P0_RX_DP<11>")
	)
	(segment
		(start 355.572314 -280.870406)
		(end 355.553518 -280.85669)
		(width 0.1143)
		(layer "In15.Cu")
		(net "P5E_CPU0_P0_RX_DP<11>")
	)
	(segment
		(start 355.63556 -272.806922)
		(end 355.604064 -272.788634)
		(width 0.1143)
		(layer "In15.Cu")
		(net "P5E_CPU0_P0_RX_DP<11>")
	)
	(segment
		(start 355.60508 -283.48305)
		(end 355.64318 -283.460698)
		(width 0.1143)
		(layer "In15.Cu")
		(net "P5E_CPU0_P0_RX_DP<11>")
	)
	(segment
		(start 355.604064 -281.863546)
		(end 355.60508 -281.863038)
		(width 0.1143)
		(layer "In15.Cu")
		(net "P5E_CPU0_P0_RX_DP<11>")
	)
	(segment
		(start 355.236272 -304.005742)
		(end 355.236272 -296.61231)
		(width 0.14224)
		(layer "In15.Cu")
		(net "P5E_CPU0_P0_RX_DP<11>")
	)
	(segment
		(start 355.603302 -281.864054)
		(end 355.604064 -281.863546)
		(width 0.1143)
		(layer "In15.Cu")
		(net "P5E_CPU0_P0_RX_DP<11>")
	)
	(segment
		(start 355.637592 -288.323528)
		(end 355.64318 -288.320734)
		(width 0.1143)
		(layer "In15.Cu")
		(net "P5E_CPU0_P0_RX_DP<11>")
	)
	(segment
		(start 355.609652 -277.000208)
		(end 355.64318 -276.98065)
		(width 0.1143)
		(layer "In15.Cu")
		(net "P5E_CPU0_P0_RX_DP<11>")
	)
	(segment
		(start 355.603302 -285.104078)
		(end 355.604064 -285.10357)
		(width 0.1143)
		(layer "In15.Cu")
		(net "P5E_CPU0_P0_RX_DP<11>")
	)
	(segment
		(start 355.603302 -277.648162)
		(end 355.572314 -277.630382)
		(width 0.1143)
		(layer "In15.Cu")
		(net "P5E_CPU0_P0_RX_DP<11>")
	)
	(segment
		(start 355.64318 -293.871396)
		(end 355.636322 -293.867332)
		(width 0.1143)
		(layer "In15.Cu")
		(net "P5E_CPU0_P0_RX_DP<11>")
	)
	(segment
		(start 355.60508 -280.889202)
		(end 355.604064 -280.888694)
		(width 0.1143)
		(layer "In15.Cu")
		(net "P5E_CPU0_P0_RX_DP<11>")
	)
	(segment
		(start 355.604064 -285.10357)
		(end 355.60508 -285.103062)
		(width 0.1143)
		(layer "In15.Cu")
		(net "P5E_CPU0_P0_RX_DP<11>")
	)
	(segment
		(start 355.612192 -292.23335)
		(end 355.609398 -292.231572)
		(width 0.1143)
		(layer "In15.Cu")
		(net "P5E_CPU0_P0_RX_DP<11>")
	)
	(segment
		(start 355.606604 -276.030182)
		(end 355.60508 -276.029166)
		(width 0.1143)
		(layer "In15.Cu")
		(net "P5E_CPU0_P0_RX_DP<11>")
	)
	(segment
		(start 355.60508 -272.142966)
		(end 355.606604 -272.14195)
		(width 0.1143)
		(layer "In15.Cu")
		(net "P5E_CPU0_P0_RX_DP<11>")
	)
	(segment
		(start 355.236272 -296.583862)
		(end 355.190552 -296.538142)
		(width 0.1143)
		(layer "In15.Cu")
		(net "P5E_CPU0_P0_RX_DP<11>")
	)
	(segment
		(start 355.60508 -293.849044)
		(end 355.604064 -293.848536)
		(width 0.1143)
		(layer "In15.Cu")
		(net "P5E_CPU0_P0_RX_DP<11>")
	)
	(segment
		(start 355.606604 -272.14195)
		(end 355.64318 -272.120614)
		(width 0.1143)
		(layer "In15.Cu")
		(net "P5E_CPU0_P0_RX_DP<11>")
	)
	(segment
		(start 355.59111 -288.981134)
		(end 355.590602 -288.98088)
		(width 0.1143)
		(layer "In15.Cu")
		(net "P5E_CPU0_P0_RX_DP<11>")
	)
	(segment
		(start 355.572314 -284.11043)
		(end 355.552502 -284.096206)
		(width 0.1143)
		(layer "In15.Cu")
		(net "P5E_CPU0_P0_RX_DP<11>")
	)
	(segment
		(start 355.606604 -277.650194)
		(end 355.60508 -277.649178)
		(width 0.1143)
		(layer "In15.Cu")
		(net "P5E_CPU0_P0_RX_DP<11>")
	)
	(segment
		(start 355.624892 -289.95116)
		(end 355.625146 -289.95116)
		(width 0.1143)
		(layer "In15.Cu")
		(net "P5E_CPU0_P0_RX_DP<11>")
	)
	(segment
		(start 355.604064 -271.168622)
		(end 355.603302 -271.168114)
		(width 0.1143)
		(layer "In15.Cu")
		(net "P5E_CPU0_P0_RX_DP<11>")
	)
	(segment
		(start 355.60508 -279.26919)
		(end 355.604064 -279.268682)
		(width 0.1143)
		(layer "In15.Cu")
		(net "P5E_CPU0_P0_RX_DP<11>")
	)
	(segment
		(start 355.636322 -272.80743)
		(end 355.63556 -272.806922)
		(width 0.1143)
		(layer "In15.Cu")
		(net "P5E_CPU0_P0_RX_DP<11>")
	)
	(segment
		(start 355.610414 -290.612068)
		(end 355.59619 -290.60394)
		(width 0.1143)
		(layer "In15.Cu")
		(net "P5E_CPU0_P0_RX_DP<11>")
	)
	(segment
		(start 346.23502 -372.803166)
		(end 346.52712 -372.511066)
		(width 0.14224)
		(layer "In15.Cu")
		(net "P5E_CPU0_P0_RX_DP<11>")
	)
	(segment
		(start 317.748412 -393.842494)
		(end 317.748412 -393.428982)
		(width 0.14224)
		(layer "In15.Cu")
		(net "P5E_CPU0_P0_RX_DP<11>")
	)
	(segment
		(start 355.089968 -295.659048)
		(end 355.160072 -295.618408)
		(width 0.1143)
		(layer "In15.Cu")
		(net "P5E_CPU0_P0_RX_DP<11>")
	)
	(segment
		(start 355.608636 -292.231064)
		(end 355.59619 -292.223952)
		(width 0.1143)
		(layer "In15.Cu")
		(net "P5E_CPU0_P0_RX_DP<11>")
	)
	(segment
		(start 355.603302 -279.268174)
		(end 355.572314 -279.250394)
		(width 0.1143)
		(layer "In15.Cu")
		(net "P5E_CPU0_P0_RX_DP<11>")
	)
	(segment
		(start 317.748412 -393.428982)
		(end 317.432436 -393.113006)
		(width 0.14224)
		(layer "In15.Cu")
		(net "P5E_CPU0_P0_RX_DP<11>")
	)
	(segment
		(start 355.604064 -280.888694)
		(end 355.603302 -280.888186)
		(width 0.1143)
		(layer "In15.Cu")
		(net "P5E_CPU0_P0_RX_DP<11>")
	)
	(segment
		(start 354.953316 -270.105886)
		(end 355.023166 -270.036036)
		(width 0.1143)
		(layer "In15.Cu")
		(net "P5E_CPU0_P0_RX_DP<11>")
	)
	(segment
		(start 355.60508 -275.38299)
		(end 355.606858 -275.381974)
		(width 0.1143)
		(layer "In15.Cu")
		(net "P5E_CPU0_P0_RX_DP<11>")
	)
	(segment
		(start 355.156262 -270.371316)
		(end 355.1555 -270.370808)
		(width 0.1143)
		(layer "In15.Cu")
		(net "P5E_CPU0_P0_RX_DP<11>")
	)
	(segment
		(start 338.93252 -371.383306)
		(end 338.79028 -371.241066)
		(width 0.14224)
		(layer "In15.Cu")
		(net "P5E_CPU0_P0_RX_DP<11>")
	)
	(segment
		(start 355.642418 -287.39084)
		(end 355.642418 -287.391094)
		(width 0.1143)
		(layer "In15.Cu")
		(net "P5E_CPU0_P0_RX_DP<11>")
	)
	(segment
		(start 320.046096 -376.893074)
		(end 320.507868 -376.431302)
		(width 0.14224)
		(layer "In15.Cu")
		(net "P5E_CPU0_P0_RX_DP<11>")
	)
	(segment
		(start 317.660274 -393.930632)
		(end 317.748412 -393.842494)
		(width 0.14224)
		(layer "In15.Cu")
		(net "P5E_CPU0_P0_RX_DP<11>")
	)
	(segment
		(start 355.552502 -278.656034)
		(end 355.572314 -278.64181)
		(width 0.1143)
		(layer "In15.Cu")
		(net "P5E_CPU0_P0_RX_DP<11>")
	)
	(segment
		(start 320.72961 -378.497592)
		(end 320.404744 -378.433076)
		(width 0.14224)
		(layer "In15.Cu")
		(net "P5E_CPU0_P0_RX_DP<11>")
	)
	(segment
		(start 355.63556 -271.18691)
		(end 355.604064 -271.168622)
		(width 0.1143)
		(layer "In15.Cu")
		(net "P5E_CPU0_P0_RX_DP<11>")
	)
	(segment
		(start 355.60508 -282.509214)
		(end 355.604064 -282.508706)
		(width 0.1143)
		(layer "In15.Cu")
		(net "P5E_CPU0_P0_RX_DP<11>")
	)
	(segment
		(start 355.603302 -272.788126)
		(end 355.572314 -272.770346)
		(width 0.1143)
		(layer "In15.Cu")
		(net "P5E_CPU0_P0_RX_DP<11>")
	)
	(segment
		(start 355.642418 -292.250876)
		(end 355.636068 -292.247066)
		(width 0.1143)
		(layer "In15.Cu")
		(net "P5E_CPU0_P0_RX_DP<11>")
	)
	(segment
		(start 355.604064 -276.028658)
		(end 355.603302 -276.02815)
		(width 0.1143)
		(layer "In15.Cu")
		(net "P5E_CPU0_P0_RX_DP<11>")
	)
	(segment
		(start 355.604064 -275.383498)
		(end 355.60508 -275.38299)
		(width 0.1143)
		(layer "In15.Cu")
		(net "P5E_CPU0_P0_RX_DP<11>")
	)
	(segment
		(start 355.572314 -280.261822)
		(end 355.603302 -280.244042)
		(width 0.1143)
		(layer "In15.Cu")
		(net "P5E_CPU0_P0_RX_DP<11>")
	)
	(segment
		(start 355.1555 -270.370808)
		(end 355.134164 -270.358616)
		(width 0.1143)
		(layer "In15.Cu")
		(net "P5E_CPU0_P0_RX_DP<11>")
	)
	(segment
		(start 355.604064 -285.74873)
		(end 355.603302 -285.748222)
		(width 0.1143)
		(layer "In15.Cu")
		(net "P5E_CPU0_P0_RX_DP<11>")
	)
	(arc
		(start 355.403658 -295.153334)
		(mid 355.453188 -294.967976)
		(end 355.58857 -294.832024)
		(width 0.1143)
		(layer "In15.Cu")
		(net "P5E_CPU0_P0_RX_DP<11>")
	)
	(arc
		(start 355.64318 -286.700722)
		(mid 355.886507 -286.236156)
		(end 355.64318 -285.77159)
		(width 0.1143)
		(layer "In15.Cu")
		(net "P5E_CPU0_P0_RX_DP<11>")
	)
	(arc
		(start 355.572314 -274.390358)
		(mid 355.421929 -274.086066)
		(end 355.572314 -273.781774)
		(width 0.1143)
		(layer "In15.Cu")
		(net "P5E_CPU0_P0_RX_DP<11>")
	)
	(arc
		(start 355.64318 -283.460698)
		(mid 355.886507 -282.996132)
		(end 355.64318 -282.531566)
		(width 0.1143)
		(layer "In15.Cu")
		(net "P5E_CPU0_P0_RX_DP<11>")
	)
	(arc
		(start 317.740284 -389.90524)
		(mid 317.784908 -389.680899)
		(end 317.911988 -389.490712)
		(width 0.14224)
		(layer "In15.Cu")
		(net "P5E_CPU0_P0_RX_DP<11>")
	)
	(arc
		(start 321.711066 -379.573282)
		(mid 321.669806 -379.365854)
		(end 321.552316 -379.189996)
		(width 0.14224)
		(layer "In15.Cu")
		(net "P5E_CPU0_P0_RX_DP<11>")
	)
	(arc
		(start 355.572314 -272.770346)
		(mid 355.421929 -272.466054)
		(end 355.572314 -272.161762)
		(width 0.1143)
		(layer "In15.Cu")
		(net "P5E_CPU0_P0_RX_DP<11>")
	)
	(arc
		(start 379.612144 -368.648996)
		(mid 379.664469 -368.614034)
		(end 379.72619 -368.601752)
		(width 0.14224)
		(layer "In15.Cu")
		(net "P5E_CPU0_P0_RX_DP<11>")
	)
	(arc
		(start 355.572314 -285.730442)
		(mid 355.421929 -285.42615)
		(end 355.572314 -285.121858)
		(width 0.1143)
		(layer "In15.Cu")
		(net "P5E_CPU0_P0_RX_DP<11>")
	)
	(arc
		(start 355.64318 -281.840686)
		(mid 355.886507 -281.37612)
		(end 355.64318 -280.911554)
		(width 0.1143)
		(layer "In15.Cu")
		(net "P5E_CPU0_P0_RX_DP<11>")
	)
	(arc
		(start 355.64318 -275.360638)
		(mid 355.886507 -274.896072)
		(end 355.64318 -274.431506)
		(width 0.1143)
		(layer "In15.Cu")
		(net "P5E_CPU0_P0_RX_DP<11>")
	)
	(arc
		(start 355.64318 -280.220674)
		(mid 355.886507 -279.756108)
		(end 355.64318 -279.291542)
		(width 0.1143)
		(layer "In15.Cu")
		(net "P5E_CPU0_P0_RX_DP<11>")
	)
	(arc
		(start 355.59619 -290.60394)
		(mid 355.417973 -290.281663)
		(end 355.603556 -289.963606)
		(width 0.1143)
		(layer "In15.Cu")
		(net "P5E_CPU0_P0_RX_DP<11>")
	)
	(arc
		(start 395.46784 -367.717832)
		(mid 395.899637 -367.071508)
		(end 396.051278 -366.309148)
		(width 0.14224)
		(layer "In15.Cu")
		(net "P5E_CPU0_P0_RX_DP<11>")
	)
	(arc
		(start 355.416104 -270.860266)
		(mid 355.414832 -270.834425)
		(end 355.41204 -270.808704)
		(width 0.1143)
		(layer "In15.Cu")
		(net "P5E_CPU0_P0_RX_DP<11>")
	)
	(arc
		(start 355.334316 -304.368708)
		(mid 355.261251 -304.19372)
		(end 355.236272 -304.005742)
		(width 0.14224)
		(layer "In15.Cu")
		(net "P5E_CPU0_P0_RX_DP<11>")
	)
	(arc
		(start 331.366114 -372.85041)
		(mid 331.418439 -372.815448)
		(end 331.48016 -372.803166)
		(width 0.14224)
		(layer "In15.Cu")
		(net "P5E_CPU0_P0_RX_DP<11>")
	)
	(arc
		(start 355.59619 -292.223952)
		(mid 355.417973 -291.901675)
		(end 355.603556 -291.583618)
		(width 0.1143)
		(layer "In15.Cu")
		(net "P5E_CPU0_P0_RX_DP<11>")
	)
	(arc
		(start 355.186488 -270.393414)
		(mid 355.178539 -270.386495)
		(end 355.170486 -270.379698)
		(width 0.1143)
		(layer "In15.Cu")
		(net "P5E_CPU0_P0_RX_DP<11>")
	)
	(arc
		(start 355.64318 -285.08071)
		(mid 355.886507 -284.616144)
		(end 355.64318 -284.151578)
		(width 0.1143)
		(layer "In15.Cu")
		(net "P5E_CPU0_P0_RX_DP<11>")
	)
	(arc
		(start 320.291206 -378.357892)
		(mid 320.082157 -378.045123)
		(end 320.008758 -377.676156)
		(width 0.14224)
		(layer "In15.Cu")
		(net "P5E_CPU0_P0_RX_DP<11>")
	)
	(arc
		(start 355.64318 -288.320734)
		(mid 355.886397 -287.855638)
		(end 355.642418 -287.39084)
		(width 0.1143)
		(layer "In15.Cu")
		(net "P5E_CPU0_P0_RX_DP<11>")
	)
	(arc
		(start 355.64318 -292.251384)
		(mid 355.642799 -292.25113)
		(end 355.642418 -292.250876)
		(width 0.1143)
		(layer "In15.Cu")
		(net "P5E_CPU0_P0_RX_DP<11>")
	)
	(arc
		(start 377.550172 -370.527326)
		(mid 377.719789 -370.493587)
		(end 377.863608 -370.397532)
		(width 0.14224)
		(layer "In15.Cu")
		(net "P5E_CPU0_P0_RX_DP<11>")
	)
	(arc
		(start 355.552502 -277.616158)
		(mid 355.403788 -277.32609)
		(end 355.552502 -277.036022)
		(width 0.1143)
		(layer "In15.Cu")
		(net "P5E_CPU0_P0_RX_DP<11>")
	)
	(arc
		(start 355.160072 -295.618408)
		(mid 355.339095 -295.415853)
		(end 355.403658 -295.153334)
		(width 0.1143)
		(layer "In15.Cu")
		(net "P5E_CPU0_P0_RX_DP<11>")
	)
	(arc
		(start 354.946458 -295.93921)
		(mid 354.984479 -295.781851)
		(end 355.089968 -295.659048)
		(width 0.1143)
		(layer "In15.Cu")
		(net "P5E_CPU0_P0_RX_DP<11>")
	)
	(arc
		(start 355.553518 -280.85669)
		(mid 355.404603 -280.566114)
		(end 355.553518 -280.275538)
		(width 0.1143)
		(layer "In15.Cu")
		(net "P5E_CPU0_P0_RX_DP<11>")
	)
	(arc
		(start 355.64318 -278.600662)
		(mid 355.886507 -278.136096)
		(end 355.64318 -277.67153)
		(width 0.1143)
		(layer "In15.Cu")
		(net "P5E_CPU0_P0_RX_DP<11>")
	)
	(arc
		(start 355.552502 -279.23617)
		(mid 355.403788 -278.946102)
		(end 355.552502 -278.656034)
		(width 0.1143)
		(layer "In15.Cu")
		(net "P5E_CPU0_P0_RX_DP<11>")
	)
	(arc
		(start 354.98405 -296.1386)
		(mid 354.956216 -296.097273)
		(end 354.946458 -296.04843)
		(width 0.1143)
		(layer "In15.Cu")
		(net "P5E_CPU0_P0_RX_DP<11>")
	)
	(arc
		(start 355.64318 -272.120614)
		(mid 355.886507 -271.656048)
		(end 355.64318 -271.191482)
		(width 0.1143)
		(layer "In15.Cu")
		(net "P5E_CPU0_P0_RX_DP<11>")
	)
	(arc
		(start 396.049754 -354.52558)
		(mid 395.884344 -353.743451)
		(end 395.43228 -353.08413)
		(width 0.14224)
		(layer "In15.Cu")
		(net "P5E_CPU0_P0_RX_DP<11>")
	)
	(arc
		(start 355.64318 -273.740626)
		(mid 355.886507 -273.27606)
		(end 355.64318 -272.811494)
		(width 0.1143)
		(layer "In15.Cu")
		(net "P5E_CPU0_P0_RX_DP<11>")
	)
	(arc
		(start 323.149468 -375.326656)
		(mid 323.173375 -375.319411)
		(end 323.198236 -375.317004)
		(width 0.14224)
		(layer "In15.Cu")
		(net "P5E_CPU0_P0_RX_DP<11>")
	)
	(arc
		(start 355.487478 -287.255204)
		(mid 355.436889 -287.179586)
		(end 355.419152 -287.090358)
		(width 0.1143)
		(layer "In15.Cu")
		(net "P5E_CPU0_P0_RX_DP<11>")
	)
	(arc
		(start 355.552502 -275.996146)
		(mid 355.403788 -275.706078)
		(end 355.552502 -275.41601)
		(width 0.1143)
		(layer "In15.Cu")
		(net "P5E_CPU0_P0_RX_DP<11>")
	)
	(arc
		(start 355.590602 -288.98088)
		(mid 355.409404 -288.66581)
		(end 355.590856 -288.35096)
		(width 0.1143)
		(layer "In15.Cu")
		(net "P5E_CPU0_P0_RX_DP<11>")
	)
	(arc
		(start 355.102414 -270.340328)
		(mid 355.005279 -270.237459)
		(end 354.953316 -270.105886)
		(width 0.1143)
		(layer "In15.Cu")
		(net "P5E_CPU0_P0_RX_DP<11>")
	)
	(arc
		(start 355.41204 -270.808704)
		(mid 355.336123 -270.581037)
		(end 355.186488 -270.393414)
		(width 0.1143)
		(layer "In15.Cu")
		(net "P5E_CPU0_P0_RX_DP<11>")
	)
	(arc
		(start 355.552502 -282.476194)
		(mid 355.403788 -282.186126)
		(end 355.552502 -281.896058)
		(width 0.1143)
		(layer "In15.Cu")
		(net "P5E_CPU0_P0_RX_DP<11>")
	)
	(arc
		(start 368.405918 -326.608186)
		(mid 368.155243 -326.327271)
		(end 367.9444 -326.01535)
		(width 0.14224)
		(layer "In15.Cu")
		(net "P5E_CPU0_P0_RX_DP<11>")
	)
	(arc
		(start 355.64318 -294.800528)
		(mid 355.886507 -294.335962)
		(end 355.64318 -293.871396)
		(width 0.1143)
		(layer "In15.Cu")
		(net "P5E_CPU0_P0_RX_DP<11>")
	)
	(arc
		(start 355.572314 -293.830248)
		(mid 355.421929 -293.525956)
		(end 355.572314 -293.221664)
		(width 0.1143)
		(layer "In15.Cu")
		(net "P5E_CPU0_P0_RX_DP<11>")
	)
	(arc
		(start 393.684252 -368.601752)
		(mid 394.515506 -368.436387)
		(end 395.22019 -367.965482)
		(width 0.14224)
		(layer "In15.Cu")
		(net "P5E_CPU0_P0_RX_DP<11>")
	)
	(arc
		(start 355.64318 -289.01136)
		(mid 355.642799 -289.011106)
		(end 355.642418 -289.010852)
		(width 0.1143)
		(layer "In15.Cu")
		(net "P5E_CPU0_P0_RX_DP<11>")
	)
	(arc
		(start 355.419152 -287.000442)
		(mid 355.469273 -286.853994)
		(end 355.574346 -286.740346)
		(width 0.1143)
		(layer "In15.Cu")
		(net "P5E_CPU0_P0_RX_DP<11>")
	)
	(arc
		(start 355.64318 -293.180516)
		(mid 355.886507 -292.71595)
		(end 355.64318 -292.251384)
		(width 0.1143)
		(layer "In15.Cu")
		(net "P5E_CPU0_P0_RX_DP<11>")
	)
	(arc
		(start 321.126612 -386.276088)
		(mid 321.559168 -385.628861)
		(end 321.711066 -384.865372)
		(width 0.14224)
		(layer "In15.Cu")
		(net "P5E_CPU0_P0_RX_DP<11>")
	)
	(arc
		(start 355.64318 -276.98065)
		(mid 355.886507 -276.516084)
		(end 355.64318 -276.051518)
		(width 0.1143)
		(layer "In15.Cu")
		(net "P5E_CPU0_P0_RX_DP<11>")
	)
	(arc
		(start 355.64318 -291.560504)
		(mid 355.886507 -291.095938)
		(end 355.64318 -290.631372)
		(width 0.1143)
		(layer "In15.Cu")
		(net "P5E_CPU0_P0_RX_DP<11>")
	)
	(arc
		(start 355.64318 -289.940492)
		(mid 355.886507 -289.475926)
		(end 355.64318 -289.01136)
		(width 0.1143)
		(layer "In15.Cu")
		(net "P5E_CPU0_P0_RX_DP<11>")
	)
	(arc
		(start 355.572314 -271.150334)
		(mid 355.460691 -271.023357)
		(end 355.416104 -270.860266)
		(width 0.1143)
		(layer "In15.Cu")
		(net "P5E_CPU0_P0_RX_DP<11>")
	)
	(arc
		(start 355.64318 -290.631372)
		(mid 355.642799 -290.631118)
		(end 355.642418 -290.630864)
		(width 0.1143)
		(layer "In15.Cu")
		(net "P5E_CPU0_P0_RX_DP<11>")
	)
	(arc
		(start 355.552502 -284.096206)
		(mid 355.403788 -283.806138)
		(end 355.552502 -283.51607)
		(width 0.1143)
		(layer "In15.Cu")
		(net "P5E_CPU0_P0_RX_DP<11>")
	)
	(arc
		(start 320.507868 -376.431302)
		(mid 320.527211 -376.415431)
		(end 320.54927 -376.403616)
		(width 0.14224)
		(layer "In15.Cu")
		(net "P5E_CPU0_P0_RX_DP<11>")
	)
	(arc
		(start 320.008758 -376.983244)
		(mid 320.018464 -376.934449)
		(end 320.046096 -376.893074)
		(width 0.14224)
		(layer "In15.Cu")
		(net "P5E_CPU0_P0_RX_DP<11>")
	)
	(arc
		(start 328.730102 -375.317004)
		(mid 328.88668 -375.285841)
		(end 329.019408 -375.197116)
		(width 0.14224)
		(layer "In15.Cu")
		(net "P5E_CPU0_P0_RX_DP<11>")
	)
	(segment
		(start 355.78796 -273.010122)
		(end 355.321108 -273.27606)
		(width 0.12954)
		(layer "F.Cu")
		(net "P5E_CPU0_P0_RX_DP<10>")
	)
	(segment
		(start 315.670438 -394.385292)
		(end 316.191138 -394.385292)
		(width 0.127)
		(layer "F.Cu")
		(net "P5E_CPU0_P0_RX_DP<10>")
	)
	(segment
		(start 354.138992 -296.346118)
		(end 354.093272 -296.300398)
		(width 0.1143)
		(layer "In15.Cu")
		(net "P5E_CPU0_P0_RX_DP<10>")
	)
	(segment
		(start 316.548516 -393.842494)
		(end 316.548516 -393.428982)
		(width 0.14224)
		(layer "In15.Cu")
		(net "P5E_CPU0_P0_RX_DP<10>")
	)
	(segment
		(start 354.703126 -289.01136)
		(end 354.63353 -288.97072)
		(width 0.1143)
		(layer "In15.Cu")
		(net "P5E_CPU0_P0_RX_DP<10>")
	)
	(segment
		(start 363.937296 -368.024156)
		(end 363.937296 -367.452656)
		(width 0.14224)
		(layer "In15.Cu")
		(net "P5E_CPU0_P0_RX_DP<10>")
	)
	(segment
		(start 316.191138 -394.385292)
		(end 316.286134 -394.031216)
		(width 0.14224)
		(layer "In15.Cu")
		(net "P5E_CPU0_P0_RX_DP<10>")
	)
	(segment
		(start 354.66401 -286.723582)
		(end 354.703126 -286.700722)
		(width 0.1143)
		(layer "In15.Cu")
		(net "P5E_CPU0_P0_RX_DP<10>")
	)
	(segment
		(start 395.114018 -365.426244)
		(end 395.114018 -355.181154)
		(width 0.14224)
		(layer "In15.Cu")
		(net "P5E_CPU0_P0_RX_DP<10>")
	)
	(segment
		(start 394.337032 -353.332542)
		(end 367.617248 -327.147682)
		(width 0.14224)
		(layer "In15.Cu")
		(net "P5E_CPU0_P0_RX_DP<10>")
	)
	(segment
		(start 354.63353 -278.641302)
		(end 354.703126 -278.600662)
		(width 0.1143)
		(layer "In15.Cu")
		(net "P5E_CPU0_P0_RX_DP<10>")
	)
	(segment
		(start 354.703126 -282.531566)
		(end 354.63353 -282.490926)
		(width 0.1143)
		(layer "In15.Cu")
		(net "P5E_CPU0_P0_RX_DP<10>")
	)
	(segment
		(start 375.6533 -368.473736)
		(end 375.34596 -368.166396)
		(width 0.14224)
		(layer "In15.Cu")
		(net "P5E_CPU0_P0_RX_DP<10>")
	)
	(segment
		(start 354.63353 -280.261314)
		(end 354.703126 -280.220674)
		(width 0.1143)
		(layer "In15.Cu")
		(net "P5E_CPU0_P0_RX_DP<10>")
	)
	(segment
		(start 354.703126 -285.77159)
		(end 354.63353 -285.73095)
		(width 0.1143)
		(layer "In15.Cu")
		(net "P5E_CPU0_P0_RX_DP<10>")
	)
	(segment
		(start 319.798954 -381.29083)
		(end 318.386206 -380.70536)
		(width 0.14224)
		(layer "In15.Cu")
		(net "P5E_CPU0_P0_RX_DP<10>")
	)
	(segment
		(start 354.63353 -294.841168)
		(end 354.703126 -294.800528)
		(width 0.1143)
		(layer "In15.Cu")
		(net "P5E_CPU0_P0_RX_DP<10>")
	)
	(segment
		(start 375.6533 -369.278916)
		(end 375.6533 -368.473736)
		(width 0.14224)
		(layer "In15.Cu")
		(net "P5E_CPU0_P0_RX_DP<10>")
	)
	(segment
		(start 375.34596 -368.166396)
		(end 364.079536 -368.166396)
		(width 0.14224)
		(layer "In15.Cu")
		(net "P5E_CPU0_P0_RX_DP<10>")
	)
	(segment
		(start 316.235588 -392.7348)
		(end 316.540388 -392.430254)
		(width 0.14224)
		(layer "In15.Cu")
		(net "P5E_CPU0_P0_RX_DP<10>")
	)
	(segment
		(start 354.700586 -287.389824)
		(end 354.63353 -287.350708)
		(width 0.1143)
		(layer "In15.Cu")
		(net "P5E_CPU0_P0_RX_DP<10>")
	)
	(segment
		(start 318.307466 -380.588012)
		(end 318.307466 -376.576336)
		(width 0.14224)
		(layer "In15.Cu")
		(net "P5E_CPU0_P0_RX_DP<10>")
	)
	(segment
		(start 354.703126 -274.431506)
		(end 354.63353 -274.390866)
		(width 0.1143)
		(layer "In15.Cu")
		(net "P5E_CPU0_P0_RX_DP<10>")
	)
	(segment
		(start 316.763908 -388.830312)
		(end 319.873122 -385.721098)
		(width 0.14224)
		(layer "In15.Cu")
		(net "P5E_CPU0_P0_RX_DP<10>")
	)
	(segment
		(start 354.703126 -276.051518)
		(end 354.63353 -276.010878)
		(width 0.1143)
		(layer "In15.Cu")
		(net "P5E_CPU0_P0_RX_DP<10>")
	)
	(segment
		(start 354.63353 -275.401278)
		(end 354.703126 -275.360638)
		(width 0.1143)
		(layer "In15.Cu")
		(net "P5E_CPU0_P0_RX_DP<10>")
	)
	(segment
		(start 367.09223 -326.473566)
		(end 354.217986 -304.37328)
		(width 0.14224)
		(layer "In15.Cu")
		(net "P5E_CPU0_P0_RX_DP<10>")
	)
	(segment
		(start 316.23254 -393.113006)
		(end 316.235588 -392.7348)
		(width 0.14224)
		(layer "In15.Cu")
		(net "P5E_CPU0_P0_RX_DP<10>")
	)
	(segment
		(start 354.63353 -273.781266)
		(end 354.703126 -273.740626)
		(width 0.1143)
		(layer "In15.Cu")
		(net "P5E_CPU0_P0_RX_DP<10>")
	)
	(segment
		(start 332.804008 -369.586256)
		(end 375.34596 -369.586256)
		(width 0.14224)
		(layer "In15.Cu")
		(net "P5E_CPU0_P0_RX_DP<10>")
	)
	(segment
		(start 364.079536 -367.310416)
		(end 393.289282 -367.310416)
		(width 0.14224)
		(layer "In15.Cu")
		(net "P5E_CPU0_P0_RX_DP<10>")
	)
	(segment
		(start 316.286134 -394.031216)
		(end 316.460378 -393.930632)
		(width 0.14224)
		(layer "In15.Cu")
		(net "P5E_CPU0_P0_RX_DP<10>")
	)
	(segment
		(start 354.66401 -288.343594)
		(end 354.703126 -288.320734)
		(width 0.1143)
		(layer "In15.Cu")
		(net "P5E_CPU0_P0_RX_DP<10>")
	)
	(segment
		(start 318.74841 -376.138948)
		(end 322.937632 -374.403874)
		(width 0.14224)
		(layer "In15.Cu")
		(net "P5E_CPU0_P0_RX_DP<10>")
	)
	(segment
		(start 354.63353 -277.02129)
		(end 354.703126 -276.98065)
		(width 0.1143)
		(layer "In15.Cu")
		(net "P5E_CPU0_P0_RX_DP<10>")
	)
	(segment
		(start 354.63353 -281.881326)
		(end 354.703126 -281.840686)
		(width 0.1143)
		(layer "In15.Cu")
		(net "P5E_CPU0_P0_RX_DP<10>")
	)
	(segment
		(start 354.940362 -273.358864)
		(end 355.023166 -273.27606)
		(width 0.1143)
		(layer "In15.Cu")
		(net "P5E_CPU0_P0_RX_DP<10>")
	)
	(segment
		(start 354.63353 -291.601144)
		(end 354.703126 -291.560504)
		(width 0.1143)
		(layer "In15.Cu")
		(net "P5E_CPU0_P0_RX_DP<10>")
	)
	(segment
		(start 354.63353 -283.501338)
		(end 354.703126 -283.460698)
		(width 0.1143)
		(layer "In15.Cu")
		(net "P5E_CPU0_P0_RX_DP<10>")
	)
	(segment
		(start 354.130864 -295.824402)
		(end 354.33254 -295.622472)
		(width 0.1143)
		(layer "In15.Cu")
		(net "P5E_CPU0_P0_RX_DP<10>")
	)
	(segment
		(start 364.079536 -368.166396)
		(end 363.937296 -368.024156)
		(width 0.14224)
		(layer "In15.Cu")
		(net "P5E_CPU0_P0_RX_DP<10>")
	)
	(segment
		(start 354.703126 -292.251384)
		(end 354.63353 -292.210744)
		(width 0.1143)
		(layer "In15.Cu")
		(net "P5E_CPU0_P0_RX_DP<10>")
	)
	(segment
		(start 354.703126 -284.151578)
		(end 354.63353 -284.110938)
		(width 0.1143)
		(layer "In15.Cu")
		(net "P5E_CPU0_P0_RX_DP<10>")
	)
	(segment
		(start 354.703126 -280.911554)
		(end 354.63353 -280.870914)
		(width 0.1143)
		(layer "In15.Cu")
		(net "P5E_CPU0_P0_RX_DP<10>")
	)
	(segment
		(start 328.108818 -374.228614)
		(end 332.713838 -369.623594)
		(width 0.14224)
		(layer "In15.Cu")
		(net "P5E_CPU0_P0_RX_DP<10>")
	)
	(segment
		(start 323.16547 -374.358408)
		(end 327.795382 -374.358408)
		(width 0.14224)
		(layer "In15.Cu")
		(net "P5E_CPU0_P0_RX_DP<10>")
	)
	(segment
		(start 354.703126 -290.631372)
		(end 354.63353 -290.590732)
		(width 0.1143)
		(layer "In15.Cu")
		(net "P5E_CPU0_P0_RX_DP<10>")
	)
	(segment
		(start 354.138992 -296.374566)
		(end 354.138992 -296.346118)
		(width 0.1143)
		(layer "In15.Cu")
		(net "P5E_CPU0_P0_RX_DP<10>")
	)
	(segment
		(start 354.631498 -286.742378)
		(end 354.66401 -286.723582)
		(width 0.1143)
		(layer "In15.Cu")
		(net "P5E_CPU0_P0_RX_DP<10>")
	)
	(segment
		(start 316.460378 -393.930632)
		(end 316.548516 -393.842494)
		(width 0.14224)
		(layer "In15.Cu")
		(net "P5E_CPU0_P0_RX_DP<10>")
	)
	(segment
		(start 354.63353 -285.12135)
		(end 354.703126 -285.08071)
		(width 0.1143)
		(layer "In15.Cu")
		(net "P5E_CPU0_P0_RX_DP<10>")
	)
	(segment
		(start 316.540388 -392.430254)
		(end 316.540388 -389.370062)
		(width 0.14224)
		(layer "In15.Cu")
		(net "P5E_CPU0_P0_RX_DP<10>")
	)
	(segment
		(start 355.023166 -273.27606)
		(end 355.321108 -273.27606)
		(width 0.1143)
		(layer "In15.Cu")
		(net "P5E_CPU0_P0_RX_DP<10>")
	)
	(segment
		(start 354.476304 -295.192958)
		(end 354.476558 -295.145968)
		(width 0.1143)
		(layer "In15.Cu")
		(net "P5E_CPU0_P0_RX_DP<10>")
	)
	(segment
		(start 363.937296 -367.452656)
		(end 364.079536 -367.310416)
		(width 0.14224)
		(layer "In15.Cu")
		(net "P5E_CPU0_P0_RX_DP<10>")
	)
	(segment
		(start 354.703126 -293.871396)
		(end 354.63353 -293.830756)
		(width 0.1143)
		(layer "In15.Cu")
		(net "P5E_CPU0_P0_RX_DP<10>")
	)
	(segment
		(start 354.703126 -277.67153)
		(end 354.63353 -277.63089)
		(width 0.1143)
		(layer "In15.Cu")
		(net "P5E_CPU0_P0_RX_DP<10>")
	)
	(segment
		(start 316.548516 -393.428982)
		(end 316.23254 -393.113006)
		(width 0.14224)
		(layer "In15.Cu")
		(net "P5E_CPU0_P0_RX_DP<10>")
	)
	(segment
		(start 394.37945 -366.858804)
		(end 394.620496 -366.617758)
		(width 0.14224)
		(layer "In15.Cu")
		(net "P5E_CPU0_P0_RX_DP<10>")
	)
	(segment
		(start 354.476304 -295.27627)
		(end 354.476304 -295.192958)
		(width 0.1143)
		(layer "In15.Cu")
		(net "P5E_CPU0_P0_RX_DP<10>")
	)
	(segment
		(start 354.63353 -289.981132)
		(end 354.703126 -289.940492)
		(width 0.1143)
		(layer "In15.Cu")
		(net "P5E_CPU0_P0_RX_DP<10>")
	)
	(segment
		(start 320.21018 -384.907536)
		(end 320.21018 -381.906526)
		(width 0.14224)
		(layer "In15.Cu")
		(net "P5E_CPU0_P0_RX_DP<10>")
	)
	(segment
		(start 375.34596 -369.586256)
		(end 375.6533 -369.278916)
		(width 0.14224)
		(layer "In15.Cu")
		(net "P5E_CPU0_P0_RX_DP<10>")
	)
	(segment
		(start 354.631498 -288.36239)
		(end 354.66401 -288.343594)
		(width 0.1143)
		(layer "In15.Cu")
		(net "P5E_CPU0_P0_RX_DP<10>")
	)
	(segment
		(start 318.344804 -376.486166)
		(end 318.57823 -376.25274)
		(width 0.14224)
		(layer "In15.Cu")
		(net "P5E_CPU0_P0_RX_DP<10>")
	)
	(segment
		(start 354.093272 -296.300398)
		(end 354.093272 -295.914572)
		(width 0.1143)
		(layer "In15.Cu")
		(net "P5E_CPU0_P0_RX_DP<10>")
	)
	(segment
		(start 354.138992 -304.080164)
		(end 354.138992 -296.374566)
		(width 0.14224)
		(layer "In15.Cu")
		(net "P5E_CPU0_P0_RX_DP<10>")
	)
	(segment
		(start 354.703126 -279.291542)
		(end 354.63353 -279.250902)
		(width 0.1143)
		(layer "In15.Cu")
		(net "P5E_CPU0_P0_RX_DP<10>")
	)
	(segment
		(start 354.63353 -293.221156)
		(end 354.703126 -293.180516)
		(width 0.1143)
		(layer "In15.Cu")
		(net "P5E_CPU0_P0_RX_DP<10>")
	)
	(arc
		(start 327.795382 -374.358408)
		(mid 327.964999 -374.324669)
		(end 328.108818 -374.228614)
		(width 0.14224)
		(layer "In15.Cu")
		(net "P5E_CPU0_P0_RX_DP<10>")
	)
	(arc
		(start 354.936552 -273.381724)
		(mid 354.938575 -273.370314)
		(end 354.940362 -273.358864)
		(width 0.1143)
		(layer "In15.Cu")
		(net "P5E_CPU0_P0_RX_DP<10>")
	)
	(arc
		(start 395.114018 -355.181154)
		(mid 395.111577 -355.100228)
		(end 395.104112 -355.01961)
		(width 0.14224)
		(layer "In15.Cu")
		(net "P5E_CPU0_P0_RX_DP<10>")
	)
	(arc
		(start 332.713838 -369.623594)
		(mid 332.755208 -369.595951)
		(end 332.804008 -369.586256)
		(width 0.14224)
		(layer "In15.Cu")
		(net "P5E_CPU0_P0_RX_DP<10>")
	)
	(arc
		(start 318.57823 -376.25274)
		(mid 318.657716 -376.187463)
		(end 318.74841 -376.138948)
		(width 0.14224)
		(layer "In15.Cu")
		(net "P5E_CPU0_P0_RX_DP<10>")
	)
	(arc
		(start 354.476558 -287.045908)
		(mid 354.517524 -286.875502)
		(end 354.631498 -286.742378)
		(width 0.1143)
		(layer "In15.Cu")
		(net "P5E_CPU0_P0_RX_DP<10>")
	)
	(arc
		(start 354.63353 -284.110938)
		(mid 354.476553 -283.806138)
		(end 354.63353 -283.501338)
		(width 0.1143)
		(layer "In15.Cu")
		(net "P5E_CPU0_P0_RX_DP<10>")
	)
	(arc
		(start 354.703126 -289.940492)
		(mid 354.946453 -289.475926)
		(end 354.703126 -289.01136)
		(width 0.1143)
		(layer "In15.Cu")
		(net "P5E_CPU0_P0_RX_DP<10>")
	)
	(arc
		(start 316.540388 -389.370062)
		(mid 316.598473 -389.077957)
		(end 316.763908 -388.830312)
		(width 0.14224)
		(layer "In15.Cu")
		(net "P5E_CPU0_P0_RX_DP<10>")
	)
	(arc
		(start 354.093272 -295.914572)
		(mid 354.10308 -295.865733)
		(end 354.130864 -295.824402)
		(width 0.1143)
		(layer "In15.Cu")
		(net "P5E_CPU0_P0_RX_DP<10>")
	)
	(arc
		(start 354.476558 -295.145968)
		(mid 354.518107 -294.974546)
		(end 354.63353 -294.841168)
		(width 0.1143)
		(layer "In15.Cu")
		(net "P5E_CPU0_P0_RX_DP<10>")
	)
	(arc
		(start 367.617248 -327.147682)
		(mid 367.332132 -326.828232)
		(end 367.09223 -326.473566)
		(width 0.14224)
		(layer "In15.Cu")
		(net "P5E_CPU0_P0_RX_DP<10>")
	)
	(arc
		(start 354.703126 -294.800528)
		(mid 354.946453 -294.335962)
		(end 354.703126 -293.871396)
		(width 0.1143)
		(layer "In15.Cu")
		(net "P5E_CPU0_P0_RX_DP<10>")
	)
	(arc
		(start 394.445236 -353.452176)
		(mid 394.392985 -353.390685)
		(end 394.337032 -353.332542)
		(width 0.14224)
		(layer "In15.Cu")
		(net "P5E_CPU0_P0_RX_DP<10>")
	)
	(arc
		(start 354.703126 -288.320734)
		(mid 354.881939 -288.118384)
		(end 354.946458 -287.856168)
		(width 0.1143)
		(layer "In15.Cu")
		(net "P5E_CPU0_P0_RX_DP<10>")
	)
	(arc
		(start 395.104112 -355.01961)
		(mid 394.882628 -354.190515)
		(end 394.445236 -353.452176)
		(width 0.14224)
		(layer "In15.Cu")
		(net "P5E_CPU0_P0_RX_DP<10>")
	)
	(arc
		(start 354.63353 -274.390866)
		(mid 354.476553 -274.086066)
		(end 354.63353 -273.781266)
		(width 0.1143)
		(layer "In15.Cu")
		(net "P5E_CPU0_P0_RX_DP<10>")
	)
	(arc
		(start 354.33254 -295.622472)
		(mid 354.438839 -295.463663)
		(end 354.476304 -295.27627)
		(width 0.1143)
		(layer "In15.Cu")
		(net "P5E_CPU0_P0_RX_DP<10>")
	)
	(arc
		(start 318.307466 -376.576336)
		(mid 318.317172 -376.527541)
		(end 318.344804 -376.486166)
		(width 0.14224)
		(layer "In15.Cu")
		(net "P5E_CPU0_P0_RX_DP<10>")
	)
	(arc
		(start 354.63353 -293.830756)
		(mid 354.476553 -293.525956)
		(end 354.63353 -293.221156)
		(width 0.1143)
		(layer "In15.Cu")
		(net "P5E_CPU0_P0_RX_DP<10>")
	)
	(arc
		(start 354.703126 -280.220674)
		(mid 354.946453 -279.756108)
		(end 354.703126 -279.291542)
		(width 0.1143)
		(layer "In15.Cu")
		(net "P5E_CPU0_P0_RX_DP<10>")
	)
	(arc
		(start 393.289282 -367.310416)
		(mid 393.879281 -367.19304)
		(end 394.37945 -366.858804)
		(width 0.14224)
		(layer "In15.Cu")
		(net "P5E_CPU0_P0_RX_DP<10>")
	)
	(arc
		(start 354.63353 -287.350708)
		(mid 354.518103 -287.217332)
		(end 354.476558 -287.045908)
		(width 0.1143)
		(layer "In15.Cu")
		(net "P5E_CPU0_P0_RX_DP<10>")
	)
	(arc
		(start 354.476558 -288.66592)
		(mid 354.517524 -288.495514)
		(end 354.631498 -288.36239)
		(width 0.1143)
		(layer "In15.Cu")
		(net "P5E_CPU0_P0_RX_DP<10>")
	)
	(arc
		(start 354.63353 -285.73095)
		(mid 354.476553 -285.42615)
		(end 354.63353 -285.12135)
		(width 0.1143)
		(layer "In15.Cu")
		(net "P5E_CPU0_P0_RX_DP<10>")
	)
	(arc
		(start 354.63353 -276.010878)
		(mid 354.476553 -275.706078)
		(end 354.63353 -275.401278)
		(width 0.1143)
		(layer "In15.Cu")
		(net "P5E_CPU0_P0_RX_DP<10>")
	)
	(arc
		(start 354.703126 -278.600662)
		(mid 354.946453 -278.136096)
		(end 354.703126 -277.67153)
		(width 0.1143)
		(layer "In15.Cu")
		(net "P5E_CPU0_P0_RX_DP<10>")
	)
	(arc
		(start 354.63353 -292.210744)
		(mid 354.476553 -291.905944)
		(end 354.63353 -291.601144)
		(width 0.1143)
		(layer "In15.Cu")
		(net "P5E_CPU0_P0_RX_DP<10>")
	)
	(arc
		(start 354.703126 -293.180516)
		(mid 354.946453 -292.71595)
		(end 354.703126 -292.251384)
		(width 0.1143)
		(layer "In15.Cu")
		(net "P5E_CPU0_P0_RX_DP<10>")
	)
	(arc
		(start 319.873122 -385.721098)
		(mid 320.122584 -385.347847)
		(end 320.21018 -384.907536)
		(width 0.14224)
		(layer "In15.Cu")
		(net "P5E_CPU0_P0_RX_DP<10>")
	)
	(arc
		(start 354.703126 -276.98065)
		(mid 354.946453 -276.516084)
		(end 354.703126 -276.051518)
		(width 0.1143)
		(layer "In15.Cu")
		(net "P5E_CPU0_P0_RX_DP<10>")
	)
	(arc
		(start 354.703126 -281.840686)
		(mid 354.946453 -281.37612)
		(end 354.703126 -280.911554)
		(width 0.1143)
		(layer "In15.Cu")
		(net "P5E_CPU0_P0_RX_DP<10>")
	)
	(arc
		(start 354.703126 -286.700722)
		(mid 354.946453 -286.236156)
		(end 354.703126 -285.77159)
		(width 0.1143)
		(layer "In15.Cu")
		(net "P5E_CPU0_P0_RX_DP<10>")
	)
	(arc
		(start 354.63353 -280.870914)
		(mid 354.476553 -280.566114)
		(end 354.63353 -280.261314)
		(width 0.1143)
		(layer "In15.Cu")
		(net "P5E_CPU0_P0_RX_DP<10>")
	)
	(arc
		(start 354.703126 -273.740626)
		(mid 354.855113 -273.584118)
		(end 354.936552 -273.381724)
		(width 0.1143)
		(layer "In15.Cu")
		(net "P5E_CPU0_P0_RX_DP<10>")
	)
	(arc
		(start 394.620496 -366.617758)
		(mid 394.98577 -366.071087)
		(end 395.114018 -365.426244)
		(width 0.14224)
		(layer "In15.Cu")
		(net "P5E_CPU0_P0_RX_DP<10>")
	)
	(arc
		(start 322.937632 -374.403874)
		(mid 323.049315 -374.369934)
		(end 323.16547 -374.358408)
		(width 0.14224)
		(layer "In15.Cu")
		(net "P5E_CPU0_P0_RX_DP<10>")
	)
	(arc
		(start 354.63353 -288.97072)
		(mid 354.518103 -288.837344)
		(end 354.476558 -288.66592)
		(width 0.1143)
		(layer "In15.Cu")
		(net "P5E_CPU0_P0_RX_DP<10>")
	)
	(arc
		(start 354.703126 -275.360638)
		(mid 354.946453 -274.896072)
		(end 354.703126 -274.431506)
		(width 0.1143)
		(layer "In15.Cu")
		(net "P5E_CPU0_P0_RX_DP<10>")
	)
	(arc
		(start 354.703126 -285.08071)
		(mid 354.946453 -284.616144)
		(end 354.703126 -284.151578)
		(width 0.1143)
		(layer "In15.Cu")
		(net "P5E_CPU0_P0_RX_DP<10>")
	)
	(arc
		(start 354.63353 -279.250902)
		(mid 354.476553 -278.946102)
		(end 354.63353 -278.641302)
		(width 0.1143)
		(layer "In15.Cu")
		(net "P5E_CPU0_P0_RX_DP<10>")
	)
	(arc
		(start 354.703126 -291.560504)
		(mid 354.946453 -291.095938)
		(end 354.703126 -290.631372)
		(width 0.1143)
		(layer "In15.Cu")
		(net "P5E_CPU0_P0_RX_DP<10>")
	)
	(arc
		(start 354.703126 -283.460698)
		(mid 354.946453 -282.996132)
		(end 354.703126 -282.531566)
		(width 0.1143)
		(layer "In15.Cu")
		(net "P5E_CPU0_P0_RX_DP<10>")
	)
	(arc
		(start 320.21018 -381.906526)
		(mid 320.097917 -381.536333)
		(end 319.798954 -381.29083)
		(width 0.14224)
		(layer "In15.Cu")
		(net "P5E_CPU0_P0_RX_DP<10>")
	)
	(arc
		(start 354.63353 -282.490926)
		(mid 354.476553 -282.186126)
		(end 354.63353 -281.881326)
		(width 0.1143)
		(layer "In15.Cu")
		(net "P5E_CPU0_P0_RX_DP<10>")
	)
	(arc
		(start 318.386206 -380.70536)
		(mid 318.328957 -380.658661)
		(end 318.307466 -380.588012)
		(width 0.14224)
		(layer "In15.Cu")
		(net "P5E_CPU0_P0_RX_DP<10>")
	)
	(arc
		(start 354.63353 -277.63089)
		(mid 354.476553 -277.32609)
		(end 354.63353 -277.02129)
		(width 0.1143)
		(layer "In15.Cu")
		(net "P5E_CPU0_P0_RX_DP<10>")
	)
	(arc
		(start 354.63353 -290.590732)
		(mid 354.476553 -290.285932)
		(end 354.63353 -289.981132)
		(width 0.1143)
		(layer "In15.Cu")
		(net "P5E_CPU0_P0_RX_DP<10>")
	)
	(arc
		(start 354.217986 -304.37328)
		(mid 354.159033 -304.231963)
		(end 354.138992 -304.080164)
		(width 0.14224)
		(layer "In15.Cu")
		(net "P5E_CPU0_P0_RX_DP<10>")
	)
	(arc
		(start 354.946458 -287.856168)
		(mid 354.881222 -287.592577)
		(end 354.700586 -287.389824)
		(width 0.1143)
		(layer "In15.Cu")
		(net "P5E_CPU0_P0_RX_DP<10>")
	)
	(segment
		(start 347.327982 -271.39011)
		(end 346.86113 -271.656048)
		(width 0.12954)
		(layer "F.Cu")
		(net "P5E_CPU0_P0_RX_DP<0>")
	)
	(segment
		(start 303.670462 -394.385292)
		(end 304.191162 -394.385292)
		(width 0.127)
		(layer "F.Cu")
		(net "P5E_CPU0_P0_RX_DP<0>")
	)
	(segment
		(start 358.766364 -316.626748)
		(end 345.571064 -300.546008)
		(width 0.14224)
		(layer "In13.Cu")
		(net "P5E_CPU0_P0_RX_DP<0>")
	)
	(segment
		(start 352.640138 -369.205002)
		(end 356.16769 -369.205002)
		(width 0.14224)
		(layer "In13.Cu")
		(net "P5E_CPU0_P0_RX_DP<0>")
	)
	(segment
		(start 345.303094 -284.151578)
		(end 345.263978 -284.128718)
		(width 0.1143)
		(layer "In13.Cu")
		(net "P5E_CPU0_P0_RX_DP<0>")
	)
	(segment
		(start 304.540412 -392.430254)
		(end 304.540412 -390.731756)
		(width 0.14224)
		(layer "In13.Cu")
		(net "P5E_CPU0_P0_RX_DP<0>")
	)
	(segment
		(start 304.287682 -390.353804)
		(end 303.598834 -390.068562)
		(width 0.14224)
		(layer "In13.Cu")
		(net "P5E_CPU0_P0_RX_DP<0>")
	)
	(segment
		(start 346.234512 -272.125694)
		(end 346.235274 -272.125186)
		(width 0.1143)
		(layer "In13.Cu")
		(net "P5E_CPU0_P0_RX_DP<0>")
	)
	(segment
		(start 327.051924 -368.36604)
		(end 327.052178 -368.36604)
		(width 0.14224)
		(layer "In13.Cu")
		(net "P5E_CPU0_P0_RX_DP<0>")
	)
	(segment
		(start 373.56796 -355.024436)
		(end 373.56796 -352.373438)
		(width 0.14224)
		(layer "In13.Cu")
		(net "P5E_CPU0_P0_RX_DP<0>")
	)
	(segment
		(start 364.556802 -362.02747)
		(end 364.556802 -362.462318)
		(width 0.14224)
		(layer "In13.Cu")
		(net "P5E_CPU0_P0_RX_DP<0>")
	)
	(segment
		(start 345.300554 -287.389824)
		(end 345.233498 -287.350708)
		(width 0.1143)
		(layer "In13.Cu")
		(net "P5E_CPU0_P0_RX_DP<0>")
	)
	(segment
		(start 304.287936 -390.353804)
		(end 304.287682 -390.353804)
		(width 0.14224)
		(layer "In13.Cu")
		(net "P5E_CPU0_P0_RX_DP<0>")
	)
	(segment
		(start 345.233498 -283.501338)
		(end 345.263978 -283.483558)
		(width 0.1143)
		(layer "In13.Cu")
		(net "P5E_CPU0_P0_RX_DP<0>")
	)
	(segment
		(start 345.233498 -277.02129)
		(end 345.263978 -277.00351)
		(width 0.1143)
		(layer "In13.Cu")
		(net "P5E_CPU0_P0_RX_DP<0>")
	)
	(segment
		(start 364.556802 -362.462318)
		(end 365.126016 -363.031532)
		(width 0.14224)
		(layer "In13.Cu")
		(net "P5E_CPU0_P0_RX_DP<0>")
	)
	(segment
		(start 345.303094 -285.77159)
		(end 345.263978 -285.74873)
		(width 0.1143)
		(layer "In13.Cu")
		(net "P5E_CPU0_P0_RX_DP<0>")
	)
	(segment
		(start 345.263978 -277.64867)
		(end 345.233498 -277.63089)
		(width 0.1143)
		(layer "In13.Cu")
		(net "P5E_CPU0_P0_RX_DP<0>")
	)
	(segment
		(start 345.30157 -290.630356)
		(end 345.232228 -290.58997)
		(width 0.1143)
		(layer "In13.Cu")
		(net "P5E_CPU0_P0_RX_DP<0>")
	)
	(segment
		(start 356.16769 -369.205002)
		(end 361.529122 -363.84357)
		(width 0.14224)
		(layer "In13.Cu")
		(net "P5E_CPU0_P0_RX_DP<0>")
	)
	(segment
		(start 345.727782 -272.957036)
		(end 345.729814 -272.95602)
		(width 0.1143)
		(layer "In13.Cu")
		(net "P5E_CPU0_P0_RX_DP<0>")
	)
	(segment
		(start 369.34902 -356.22484)
		(end 369.753642 -356.629462)
		(width 0.14224)
		(layer "In13.Cu")
		(net "P5E_CPU0_P0_RX_DP<0>")
	)
	(segment
		(start 345.233498 -273.781266)
		(end 345.263978 -273.763486)
		(width 0.1143)
		(layer "In13.Cu")
		(net "P5E_CPU0_P0_RX_DP<0>")
	)
	(segment
		(start 369.147852 -356.22484)
		(end 369.34902 -356.22484)
		(width 0.14224)
		(layer "In13.Cu")
		(net "P5E_CPU0_P0_RX_DP<0>")
	)
	(segment
		(start 345.303094 -279.291542)
		(end 345.263978 -279.268682)
		(width 0.1143)
		(layer "In13.Cu")
		(net "P5E_CPU0_P0_RX_DP<0>")
	)
	(segment
		(start 361.529122 -363.84357)
		(end 361.73029 -363.84357)
		(width 0.14224)
		(layer "In13.Cu")
		(net "P5E_CPU0_P0_RX_DP<0>")
	)
	(segment
		(start 345.730576 -272.955512)
		(end 345.773248 -272.930112)
		(width 0.1143)
		(layer "In13.Cu")
		(net "P5E_CPU0_P0_RX_DP<0>")
	)
	(segment
		(start 345.303094 -282.531566)
		(end 345.263978 -282.508706)
		(width 0.1143)
		(layer "In13.Cu")
		(net "P5E_CPU0_P0_RX_DP<0>")
	)
	(segment
		(start 345.263978 -279.268682)
		(end 345.233498 -279.250902)
		(width 0.1143)
		(layer "In13.Cu")
		(net "P5E_CPU0_P0_RX_DP<0>")
	)
	(segment
		(start 373.56796 -352.373438)
		(end 358.766364 -316.626748)
		(width 0.14224)
		(layer "In13.Cu")
		(net "P5E_CPU0_P0_RX_DP<0>")
	)
	(segment
		(start 345.30157 -289.010344)
		(end 345.232228 -288.969958)
		(width 0.1143)
		(layer "In13.Cu")
		(net "P5E_CPU0_P0_RX_DP<0>")
	)
	(segment
		(start 345.263978 -277.00351)
		(end 345.303094 -276.98065)
		(width 0.1143)
		(layer "In13.Cu")
		(net "P5E_CPU0_P0_RX_DP<0>")
	)
	(segment
		(start 304.460402 -393.930632)
		(end 304.54854 -393.842494)
		(width 0.14224)
		(layer "In13.Cu")
		(net "P5E_CPU0_P0_RX_DP<0>")
	)
	(segment
		(start 369.753642 -356.629462)
		(end 369.753642 -356.83063)
		(width 0.14224)
		(layer "In13.Cu")
		(net "P5E_CPU0_P0_RX_DP<0>")
	)
	(segment
		(start 345.30157 -293.87038)
		(end 345.232228 -293.829994)
		(width 0.1143)
		(layer "In13.Cu")
		(net "P5E_CPU0_P0_RX_DP<0>")
	)
	(segment
		(start 345.233498 -285.12135)
		(end 345.263978 -285.10357)
		(width 0.1143)
		(layer "In13.Cu")
		(net "P5E_CPU0_P0_RX_DP<0>")
	)
	(segment
		(start 345.233498 -275.401278)
		(end 345.263978 -275.383498)
		(width 0.1143)
		(layer "In13.Cu")
		(net "P5E_CPU0_P0_RX_DP<0>")
	)
	(segment
		(start 346.235274 -272.125186)
		(end 346.243148 -272.120614)
		(width 0.1143)
		(layer "In13.Cu")
		(net "P5E_CPU0_P0_RX_DP<0>")
	)
	(segment
		(start 346.563188 -271.656048)
		(end 346.86113 -271.656048)
		(width 0.1143)
		(layer "In13.Cu")
		(net "P5E_CPU0_P0_RX_DP<0>")
	)
	(segment
		(start 345.263978 -283.483558)
		(end 345.303094 -283.460698)
		(width 0.1143)
		(layer "In13.Cu")
		(net "P5E_CPU0_P0_RX_DP<0>")
	)
	(segment
		(start 346.480384 -271.738852)
		(end 346.563188 -271.656048)
		(width 0.1143)
		(layer "In13.Cu")
		(net "P5E_CPU0_P0_RX_DP<0>")
	)
	(segment
		(start 365.560864 -363.031532)
		(end 373.56796 -355.024436)
		(width 0.14224)
		(layer "In13.Cu")
		(net "P5E_CPU0_P0_RX_DP<0>")
	)
	(segment
		(start 304.191162 -394.385292)
		(end 304.286158 -394.031216)
		(width 0.14224)
		(layer "In13.Cu")
		(net "P5E_CPU0_P0_RX_DP<0>")
	)
	(segment
		(start 303.598834 -390.068562)
		(end 296.584624 -386.537708)
		(width 0.14224)
		(layer "In13.Cu")
		(net "P5E_CPU0_P0_RX_DP<0>")
	)
	(segment
		(start 345.263978 -285.10357)
		(end 345.303094 -285.08071)
		(width 0.1143)
		(layer "In13.Cu")
		(net "P5E_CPU0_P0_RX_DP<0>")
	)
	(segment
		(start 304.286158 -394.031216)
		(end 304.460402 -393.930632)
		(width 0.14224)
		(layer "In13.Cu")
		(net "P5E_CPU0_P0_RX_DP<0>")
	)
	(segment
		(start 346.204032 -272.143474)
		(end 346.234512 -272.125694)
		(width 0.1143)
		(layer "In13.Cu")
		(net "P5E_CPU0_P0_RX_DP<0>")
	)
	(segment
		(start 345.233498 -280.261314)
		(end 345.263978 -280.243534)
		(width 0.1143)
		(layer "In13.Cu")
		(net "P5E_CPU0_P0_RX_DP<0>")
	)
	(segment
		(start 345.303094 -277.67153)
		(end 345.263978 -277.64867)
		(width 0.1143)
		(layer "In13.Cu")
		(net "P5E_CPU0_P0_RX_DP<0>")
	)
	(segment
		(start 345.263978 -280.888694)
		(end 345.233498 -280.870914)
		(width 0.1143)
		(layer "In13.Cu")
		(net "P5E_CPU0_P0_RX_DP<0>")
	)
	(segment
		(start 365.126016 -363.031532)
		(end 365.560864 -363.031532)
		(width 0.14224)
		(layer "In13.Cu")
		(net "P5E_CPU0_P0_RX_DP<0>")
	)
	(segment
		(start 345.263978 -281.863546)
		(end 345.303094 -281.840686)
		(width 0.1143)
		(layer "In13.Cu")
		(net "P5E_CPU0_P0_RX_DP<0>")
	)
	(segment
		(start 345.77401 -272.929604)
		(end 345.777058 -272.92808)
		(width 0.1143)
		(layer "In13.Cu")
		(net "P5E_CPU0_P0_RX_DP<0>")
	)
	(segment
		(start 357.98633 -369.03279)
		(end 358.555544 -369.602004)
		(width 0.14224)
		(layer "In13.Cu")
		(net "P5E_CPU0_P0_RX_DP<0>")
	)
	(segment
		(start 302.73625 -371.352064)
		(end 306.65547 -371.352064)
		(width 0.14224)
		(layer "In13.Cu")
		(net "P5E_CPU0_P0_RX_DP<0>")
	)
	(segment
		(start 314.744608 -370.552472)
		(end 324.450456 -368.622072)
		(width 0.14224)
		(layer "In13.Cu")
		(net "P5E_CPU0_P0_RX_DP<0>")
	)
	(segment
		(start 304.232564 -393.113006)
		(end 304.235612 -392.7348)
		(width 0.14224)
		(layer "In13.Cu")
		(net "P5E_CPU0_P0_RX_DP<0>")
	)
	(segment
		(start 345.263978 -284.128718)
		(end 345.233498 -284.110938)
		(width 0.1143)
		(layer "In13.Cu")
		(net "P5E_CPU0_P0_RX_DP<0>")
	)
	(segment
		(start 345.232228 -291.601906)
		(end 345.30157 -291.56152)
		(width 0.1143)
		(layer "In13.Cu")
		(net "P5E_CPU0_P0_RX_DP<0>")
	)
	(segment
		(start 363.62005 -361.752642)
		(end 369.147852 -356.22484)
		(width 0.14224)
		(layer "In13.Cu")
		(net "P5E_CPU0_P0_RX_DP<0>")
	)
	(segment
		(start 304.54854 -393.842494)
		(end 304.54854 -393.428982)
		(width 0.14224)
		(layer "In13.Cu")
		(net "P5E_CPU0_P0_RX_DP<0>")
	)
	(segment
		(start 363.62005 -364.972346)
		(end 363.62005 -361.752642)
		(width 0.14224)
		(layer "In13.Cu")
		(net "P5E_CPU0_P0_RX_DP<0>")
	)
	(segment
		(start 345.30157 -292.250368)
		(end 345.232228 -292.209982)
		(width 0.1143)
		(layer "In13.Cu")
		(net "P5E_CPU0_P0_RX_DP<0>")
	)
	(segment
		(start 345.129104 -296.079164)
		(end 345.129104 -296.064686)
		(width 0.1143)
		(layer "In13.Cu")
		(net "P5E_CPU0_P0_RX_DP<0>")
	)
	(segment
		(start 358.990392 -369.602004)
		(end 363.62005 -364.972346)
		(width 0.14224)
		(layer "In13.Cu")
		(net "P5E_CPU0_P0_RX_DP<0>")
	)
	(segment
		(start 345.129104 -299.31106)
		(end 345.129104 -296.079164)
		(width 0.14224)
		(layer "In13.Cu")
		(net "P5E_CPU0_P0_RX_DP<0>")
	)
	(segment
		(start 345.263978 -285.74873)
		(end 345.233498 -285.73095)
		(width 0.1143)
		(layer "In13.Cu")
		(net "P5E_CPU0_P0_RX_DP<0>")
	)
	(segment
		(start 345.233498 -281.881326)
		(end 345.263978 -281.863546)
		(width 0.1143)
		(layer "In13.Cu")
		(net "P5E_CPU0_P0_RX_DP<0>")
	)
	(segment
		(start 296.149522 -385.832096)
		(end 296.149522 -377.038362)
		(width 0.14224)
		(layer "In13.Cu")
		(net "P5E_CPU0_P0_RX_DP<0>")
	)
	(segment
		(start 352.628454 -369.20424)
		(end 352.640138 -369.205002)
		(width 0.14224)
		(layer "In13.Cu")
		(net "P5E_CPU0_P0_RX_DP<0>")
	)
	(segment
		(start 362.134912 -364.248192)
		(end 362.134912 -364.44936)
		(width 0.14224)
		(layer "In13.Cu")
		(net "P5E_CPU0_P0_RX_DP<0>")
	)
	(segment
		(start 345.232228 -293.221918)
		(end 345.30157 -293.181532)
		(width 0.1143)
		(layer "In13.Cu")
		(net "P5E_CPU0_P0_RX_DP<0>")
	)
	(segment
		(start 345.303094 -276.051518)
		(end 345.263978 -276.028658)
		(width 0.1143)
		(layer "In13.Cu")
		(net "P5E_CPU0_P0_RX_DP<0>")
	)
	(segment
		(start 345.263978 -286.723582)
		(end 345.303094 -286.700722)
		(width 0.1143)
		(layer "In13.Cu")
		(net "P5E_CPU0_P0_RX_DP<0>")
	)
	(segment
		(start 345.773248 -272.930112)
		(end 345.77401 -272.929604)
		(width 0.1143)
		(layer "In13.Cu")
		(net "P5E_CPU0_P0_RX_DP<0>")
	)
	(segment
		(start 361.73029 -363.84357)
		(end 362.134912 -364.248192)
		(width 0.14224)
		(layer "In13.Cu")
		(net "P5E_CPU0_P0_RX_DP<0>")
	)
	(segment
		(start 345.303094 -280.911554)
		(end 345.263978 -280.888694)
		(width 0.1143)
		(layer "In13.Cu")
		(net "P5E_CPU0_P0_RX_DP<0>")
	)
	(segment
		(start 369.753642 -356.83063)
		(end 364.556802 -362.02747)
		(width 0.14224)
		(layer "In13.Cu")
		(net "P5E_CPU0_P0_RX_DP<0>")
	)
	(segment
		(start 304.54854 -393.428982)
		(end 304.232564 -393.113006)
		(width 0.14224)
		(layer "In13.Cu")
		(net "P5E_CPU0_P0_RX_DP<0>")
	)
	(segment
		(start 304.235612 -392.7348)
		(end 304.540412 -392.430254)
		(width 0.14224)
		(layer "In13.Cu")
		(net "P5E_CPU0_P0_RX_DP<0>")
	)
	(segment
		(start 345.263978 -276.028658)
		(end 345.233498 -276.010878)
		(width 0.1143)
		(layer "In13.Cu")
		(net "P5E_CPU0_P0_RX_DP<0>")
	)
	(segment
		(start 357.98633 -368.597942)
		(end 357.98633 -369.03279)
		(width 0.14224)
		(layer "In13.Cu")
		(net "P5E_CPU0_P0_RX_DP<0>")
	)
	(segment
		(start 345.263978 -282.508706)
		(end 345.233498 -282.490926)
		(width 0.1143)
		(layer "In13.Cu")
		(net "P5E_CPU0_P0_RX_DP<0>")
	)
	(segment
		(start 307.72735 -370.552472)
		(end 314.744608 -370.552472)
		(width 0.14224)
		(layer "In13.Cu")
		(net "P5E_CPU0_P0_RX_DP<0>")
	)
	(segment
		(start 345.083384 -296.018966)
		(end 345.083384 -295.13276)
		(width 0.1143)
		(layer "In13.Cu")
		(net "P5E_CPU0_P0_RX_DP<0>")
	)
	(segment
		(start 345.303094 -274.431506)
		(end 345.263978 -274.408646)
		(width 0.1143)
		(layer "In13.Cu")
		(net "P5E_CPU0_P0_RX_DP<0>")
	)
	(segment
		(start 345.233498 -278.641302)
		(end 345.263978 -278.623522)
		(width 0.1143)
		(layer "In13.Cu")
		(net "P5E_CPU0_P0_RX_DP<0>")
	)
	(segment
		(start 358.555544 -369.602004)
		(end 358.990392 -369.602004)
		(width 0.14224)
		(layer "In13.Cu")
		(net "P5E_CPU0_P0_RX_DP<0>")
	)
	(segment
		(start 345.263978 -273.763486)
		(end 345.303094 -273.740626)
		(width 0.1143)
		(layer "In13.Cu")
		(net "P5E_CPU0_P0_RX_DP<0>")
	)
	(segment
		(start 345.263978 -280.243534)
		(end 345.303094 -280.220674)
		(width 0.1143)
		(layer "In13.Cu")
		(net "P5E_CPU0_P0_RX_DP<0>")
	)
	(segment
		(start 345.232228 -288.361882)
		(end 345.303094 -288.320734)
		(width 0.1143)
		(layer "In13.Cu")
		(net "P5E_CPU0_P0_RX_DP<0>")
	)
	(segment
		(start 345.129104 -296.064686)
		(end 345.083384 -296.018966)
		(width 0.1143)
		(layer "In13.Cu")
		(net "P5E_CPU0_P0_RX_DP<0>")
	)
	(segment
		(start 345.263978 -274.408646)
		(end 345.233498 -274.390866)
		(width 0.1143)
		(layer "In13.Cu")
		(net "P5E_CPU0_P0_RX_DP<0>")
	)
	(segment
		(start 296.204386 -376.906028)
		(end 301.066962 -372.043452)
		(width 0.14224)
		(layer "In13.Cu")
		(net "P5E_CPU0_P0_RX_DP<0>")
	)
	(segment
		(start 345.232228 -289.981894)
		(end 345.30157 -289.941508)
		(width 0.1143)
		(layer "In13.Cu")
		(net "P5E_CPU0_P0_RX_DP<0>")
	)
	(segment
		(start 345.263978 -278.623522)
		(end 345.303094 -278.600662)
		(width 0.1143)
		(layer "In13.Cu")
		(net "P5E_CPU0_P0_RX_DP<0>")
	)
	(segment
		(start 345.129358 -299.310806)
		(end 345.129104 -299.31106)
		(width 0.14224)
		(layer "In13.Cu")
		(net "P5E_CPU0_P0_RX_DP<0>")
	)
	(segment
		(start 345.231466 -286.742378)
		(end 345.263978 -286.723582)
		(width 0.1143)
		(layer "In13.Cu")
		(net "P5E_CPU0_P0_RX_DP<0>")
	)
	(segment
		(start 345.729814 -272.95602)
		(end 345.730576 -272.955512)
		(width 0.1143)
		(layer "In13.Cu")
		(net "P5E_CPU0_P0_RX_DP<0>")
	)
	(segment
		(start 345.702382 -272.971768)
		(end 345.727782 -272.957036)
		(width 0.1143)
		(layer "In13.Cu")
		(net "P5E_CPU0_P0_RX_DP<0>")
	)
	(segment
		(start 345.232482 -294.84193)
		(end 345.301824 -294.801544)
		(width 0.1143)
		(layer "In13.Cu")
		(net "P5E_CPU0_P0_RX_DP<0>")
	)
	(segment
		(start 307.03012 -371.19687)
		(end 307.63718 -370.58981)
		(width 0.14224)
		(layer "In13.Cu")
		(net "P5E_CPU0_P0_RX_DP<0>")
	)
	(segment
		(start 327.052178 -368.36604)
		(end 332.66761 -368.35588)
		(width 0.14224)
		(layer "In13.Cu")
		(net "P5E_CPU0_P0_RX_DP<0>")
	)
	(segment
		(start 345.263978 -275.383498)
		(end 345.303094 -275.360638)
		(width 0.1143)
		(layer "In13.Cu")
		(net "P5E_CPU0_P0_RX_DP<0>")
	)
	(segment
		(start 362.134912 -364.44936)
		(end 357.98633 -368.597942)
		(width 0.14224)
		(layer "In13.Cu")
		(net "P5E_CPU0_P0_RX_DP<0>")
	)
	(arc
		(start 345.233498 -285.73095)
		(mid 345.076521 -285.42615)
		(end 345.233498 -285.12135)
		(width 0.1143)
		(layer "In13.Cu")
		(net "P5E_CPU0_P0_RX_DP<0>")
	)
	(arc
		(start 345.777058 -272.92808)
		(mid 345.955867 -272.725586)
		(end 346.02039 -272.46326)
		(width 0.1143)
		(layer "In13.Cu")
		(net "P5E_CPU0_P0_RX_DP<0>")
	)
	(arc
		(start 345.546426 -273.27606)
		(mid 345.587681 -273.105089)
		(end 345.702382 -272.971768)
		(width 0.1143)
		(layer "In13.Cu")
		(net "P5E_CPU0_P0_RX_DP<0>")
	)
	(arc
		(start 346.02039 -272.46326)
		(mid 346.06956 -272.278868)
		(end 346.204032 -272.143474)
		(width 0.1143)
		(layer "In13.Cu")
		(net "P5E_CPU0_P0_RX_DP<0>")
	)
	(arc
		(start 345.232228 -292.209982)
		(mid 345.076401 -291.905944)
		(end 345.232228 -291.601906)
		(width 0.1143)
		(layer "In13.Cu")
		(net "P5E_CPU0_P0_RX_DP<0>")
	)
	(arc
		(start 345.233498 -276.010878)
		(mid 345.076521 -275.706078)
		(end 345.233498 -275.401278)
		(width 0.1143)
		(layer "In13.Cu")
		(net "P5E_CPU0_P0_RX_DP<0>")
	)
	(arc
		(start 345.233498 -282.490926)
		(mid 345.076521 -282.186126)
		(end 345.233498 -281.881326)
		(width 0.1143)
		(layer "In13.Cu")
		(net "P5E_CPU0_P0_RX_DP<0>")
	)
	(arc
		(start 345.233498 -280.870914)
		(mid 345.076521 -280.566114)
		(end 345.233498 -280.261314)
		(width 0.1143)
		(layer "In13.Cu")
		(net "P5E_CPU0_P0_RX_DP<0>")
	)
	(arc
		(start 345.303094 -285.08071)
		(mid 345.546421 -284.616144)
		(end 345.303094 -284.151578)
		(width 0.1143)
		(layer "In13.Cu")
		(net "P5E_CPU0_P0_RX_DP<0>")
	)
	(arc
		(start 345.30157 -289.941508)
		(mid 345.546391 -289.475926)
		(end 345.30157 -289.010344)
		(width 0.1143)
		(layer "In13.Cu")
		(net "P5E_CPU0_P0_RX_DP<0>")
	)
	(arc
		(start 345.303094 -280.220674)
		(mid 345.546421 -279.756108)
		(end 345.303094 -279.291542)
		(width 0.1143)
		(layer "In13.Cu")
		(net "P5E_CPU0_P0_RX_DP<0>")
	)
	(arc
		(start 345.232228 -290.58997)
		(mid 345.076401 -290.285932)
		(end 345.232228 -289.981894)
		(width 0.1143)
		(layer "In13.Cu")
		(net "P5E_CPU0_P0_RX_DP<0>")
	)
	(arc
		(start 307.63718 -370.58981)
		(mid 307.67855 -370.562167)
		(end 307.72735 -370.552472)
		(width 0.14224)
		(layer "In13.Cu")
		(net "P5E_CPU0_P0_RX_DP<0>")
	)
	(arc
		(start 345.303094 -288.320734)
		(mid 345.481907 -288.118384)
		(end 345.546426 -287.856168)
		(width 0.1143)
		(layer "In13.Cu")
		(net "P5E_CPU0_P0_RX_DP<0>")
	)
	(arc
		(start 296.584624 -386.537708)
		(mid 296.267036 -386.246572)
		(end 296.149522 -385.832096)
		(width 0.14224)
		(layer "In13.Cu")
		(net "P5E_CPU0_P0_RX_DP<0>")
	)
	(arc
		(start 345.233498 -277.63089)
		(mid 345.076521 -277.32609)
		(end 345.233498 -277.02129)
		(width 0.1143)
		(layer "In13.Cu")
		(net "P5E_CPU0_P0_RX_DP<0>")
	)
	(arc
		(start 345.233498 -287.350708)
		(mid 345.118071 -287.217332)
		(end 345.076526 -287.045908)
		(width 0.1143)
		(layer "In13.Cu")
		(net "P5E_CPU0_P0_RX_DP<0>")
	)
	(arc
		(start 346.476574 -271.761712)
		(mid 346.478597 -271.750302)
		(end 346.480384 -271.738852)
		(width 0.1143)
		(layer "In13.Cu")
		(net "P5E_CPU0_P0_RX_DP<0>")
	)
	(arc
		(start 345.233498 -274.390866)
		(mid 345.076521 -274.086066)
		(end 345.233498 -273.781266)
		(width 0.1143)
		(layer "In13.Cu")
		(net "P5E_CPU0_P0_RX_DP<0>")
	)
	(arc
		(start 301.066962 -372.043452)
		(mid 301.832852 -371.531764)
		(end 302.73625 -371.352064)
		(width 0.14224)
		(layer "In13.Cu")
		(net "P5E_CPU0_P0_RX_DP<0>")
	)
	(arc
		(start 345.546426 -287.856168)
		(mid 345.48119 -287.592577)
		(end 345.300554 -287.389824)
		(width 0.1143)
		(layer "In13.Cu")
		(net "P5E_CPU0_P0_RX_DP<0>")
	)
	(arc
		(start 345.083384 -295.13276)
		(mid 345.122888 -294.969381)
		(end 345.232482 -294.84193)
		(width 0.1143)
		(layer "In13.Cu")
		(net "P5E_CPU0_P0_RX_DP<0>")
	)
	(arc
		(start 345.30157 -293.181532)
		(mid 345.546391 -292.71595)
		(end 345.30157 -292.250368)
		(width 0.1143)
		(layer "In13.Cu")
		(net "P5E_CPU0_P0_RX_DP<0>")
	)
	(arc
		(start 346.243148 -272.120614)
		(mid 346.395193 -271.964138)
		(end 346.476574 -271.761712)
		(width 0.1143)
		(layer "In13.Cu")
		(net "P5E_CPU0_P0_RX_DP<0>")
	)
	(arc
		(start 345.232228 -288.969958)
		(mid 345.076401 -288.66592)
		(end 345.232228 -288.361882)
		(width 0.1143)
		(layer "In13.Cu")
		(net "P5E_CPU0_P0_RX_DP<0>")
	)
	(arc
		(start 345.303094 -286.700722)
		(mid 345.546421 -286.236156)
		(end 345.303094 -285.77159)
		(width 0.1143)
		(layer "In13.Cu")
		(net "P5E_CPU0_P0_RX_DP<0>")
	)
	(arc
		(start 345.303094 -273.740626)
		(mid 345.481907 -273.538276)
		(end 345.546426 -273.27606)
		(width 0.1143)
		(layer "In13.Cu")
		(net "P5E_CPU0_P0_RX_DP<0>")
	)
	(arc
		(start 345.303094 -278.600662)
		(mid 345.546421 -278.136096)
		(end 345.303094 -277.67153)
		(width 0.1143)
		(layer "In13.Cu")
		(net "P5E_CPU0_P0_RX_DP<0>")
	)
	(arc
		(start 345.303094 -283.460698)
		(mid 345.546421 -282.996132)
		(end 345.303094 -282.531566)
		(width 0.1143)
		(layer "In13.Cu")
		(net "P5E_CPU0_P0_RX_DP<0>")
	)
	(arc
		(start 324.450456 -368.622072)
		(mid 325.744902 -368.430167)
		(end 327.051924 -368.36604)
		(width 0.14224)
		(layer "In13.Cu")
		(net "P5E_CPU0_P0_RX_DP<0>")
	)
	(arc
		(start 345.301824 -294.801544)
		(mid 345.546645 -294.335857)
		(end 345.30157 -293.87038)
		(width 0.1143)
		(layer "In13.Cu")
		(net "P5E_CPU0_P0_RX_DP<0>")
	)
	(arc
		(start 345.303094 -275.360638)
		(mid 345.546421 -274.896072)
		(end 345.303094 -274.431506)
		(width 0.1143)
		(layer "In13.Cu")
		(net "P5E_CPU0_P0_RX_DP<0>")
	)
	(arc
		(start 345.233498 -279.250902)
		(mid 345.076521 -278.946102)
		(end 345.233498 -278.641302)
		(width 0.1143)
		(layer "In13.Cu")
		(net "P5E_CPU0_P0_RX_DP<0>")
	)
	(arc
		(start 345.303094 -281.840686)
		(mid 345.546421 -281.37612)
		(end 345.303094 -280.911554)
		(width 0.1143)
		(layer "In13.Cu")
		(net "P5E_CPU0_P0_RX_DP<0>")
	)
	(arc
		(start 296.149522 -377.038362)
		(mid 296.163787 -376.966739)
		(end 296.204386 -376.906028)
		(width 0.14224)
		(layer "In13.Cu")
		(net "P5E_CPU0_P0_RX_DP<0>")
	)
	(arc
		(start 332.66761 -368.35588)
		(mid 342.656804 -368.573666)
		(end 352.628454 -369.20424)
		(width 0.14224)
		(layer "In13.Cu")
		(net "P5E_CPU0_P0_RX_DP<0>")
	)
	(arc
		(start 345.30157 -291.56152)
		(mid 345.546391 -291.095938)
		(end 345.30157 -290.630356)
		(width 0.1143)
		(layer "In13.Cu")
		(net "P5E_CPU0_P0_RX_DP<0>")
	)
	(arc
		(start 345.232228 -293.829994)
		(mid 345.076401 -293.525956)
		(end 345.232228 -293.221918)
		(width 0.1143)
		(layer "In13.Cu")
		(net "P5E_CPU0_P0_RX_DP<0>")
	)
	(arc
		(start 345.303094 -276.98065)
		(mid 345.546421 -276.516084)
		(end 345.303094 -276.051518)
		(width 0.1143)
		(layer "In13.Cu")
		(net "P5E_CPU0_P0_RX_DP<0>")
	)
	(arc
		(start 345.233498 -284.110938)
		(mid 345.076521 -283.806138)
		(end 345.233498 -283.501338)
		(width 0.1143)
		(layer "In13.Cu")
		(net "P5E_CPU0_P0_RX_DP<0>")
	)
	(arc
		(start 345.076526 -287.045908)
		(mid 345.117492 -286.875502)
		(end 345.231466 -286.742378)
		(width 0.1143)
		(layer "In13.Cu")
		(net "P5E_CPU0_P0_RX_DP<0>")
	)
	(arc
		(start 306.65547 -371.352064)
		(mid 306.858233 -371.311732)
		(end 307.03012 -371.19687)
		(width 0.14224)
		(layer "In13.Cu")
		(net "P5E_CPU0_P0_RX_DP<0>")
	)
	(arc
		(start 304.540412 -390.731756)
		(mid 304.471493 -390.504483)
		(end 304.287936 -390.353804)
		(width 0.14224)
		(layer "In13.Cu")
		(net "P5E_CPU0_P0_RX_DP<0>")
	)
	(arc
		(start 345.571064 -300.546008)
		(mid 345.243054 -299.966725)
		(end 345.129358 -299.310806)
		(width 0.14224)
		(layer "In13.Cu")
		(net "P5E_CPU0_P0_RX_DP<0>")
	)
	(segment
		(start 314.070238 -393.69238)
		(end 314.590938 -393.69238)
		(width 0.127)
		(layer "F.Cu")
		(net "P5E_CPU0_P0_RX_DN<9>")
	)
	(segment
		(start 354.847906 -271.39011)
		(end 354.381054 -271.656048)
		(width 0.12954)
		(layer "F.Cu")
		(net "P5E_CPU0_P0_RX_DN<9>")
	)
	(segment
		(start 353.591114 -286.579818)
		(end 353.628198 -286.558482)
		(width 0.1143)
		(layer "In15.Cu")
		(net "P5E_CPU0_P0_RX_DN<9>")
	)
	(segment
		(start 359.60812 -368.33429)
		(end 359.75036 -368.19205)
		(width 0.14224)
		(layer "In15.Cu")
		(net "P5E_CPU0_P0_RX_DN<9>")
	)
	(segment
		(start 323.012816 -373.118126)
		(end 327.054464 -373.118126)
		(width 0.14224)
		(layer "In15.Cu")
		(net "P5E_CPU0_P0_RX_DN<9>")
	)
	(segment
		(start 353.589082 -293.06139)
		(end 353.658678 -293.02075)
		(width 0.1143)
		(layer "In15.Cu")
		(net "P5E_CPU0_P0_RX_DN<9>")
	)
	(segment
		(start 354.058982 -272.811494)
		(end 354.129848 -272.770346)
		(width 0.1143)
		(layer "In15.Cu")
		(net "P5E_CPU0_P0_RX_DN<9>")
	)
	(segment
		(start 314.749434 -393.22883)
		(end 314.75426 -392.616944)
		(width 0.14224)
		(layer "In15.Cu")
		(net "P5E_CPU0_P0_RX_DN<9>")
	)
	(segment
		(start 353.589082 -273.6215)
		(end 353.658678 -273.58086)
		(width 0.1143)
		(layer "In15.Cu")
		(net "P5E_CPU0_P0_RX_DN<9>")
	)
	(segment
		(start 332.074774 -368.33429)
		(end 359.60812 -368.33429)
		(width 0.14224)
		(layer "In15.Cu")
		(net "P5E_CPU0_P0_RX_DN<9>")
	)
	(segment
		(start 392.944604 -365.962184)
		(end 393.583668 -365.32312)
		(width 0.14224)
		(layer "In15.Cu")
		(net "P5E_CPU0_P0_RX_DN<9>")
	)
	(segment
		(start 353.658678 -287.551368)
		(end 353.591622 -287.512252)
		(width 0.1143)
		(layer "In15.Cu")
		(net "P5E_CPU0_P0_RX_DN<9>")
	)
	(segment
		(start 353.658678 -294.031162)
		(end 353.589082 -293.990522)
		(width 0.1143)
		(layer "In15.Cu")
		(net "P5E_CPU0_P0_RX_DN<9>")
	)
	(segment
		(start 327.570592 -372.6688)
		(end 327.570592 -372.474998)
		(width 0.14224)
		(layer "In15.Cu")
		(net "P5E_CPU0_P0_RX_DN<9>")
	)
	(segment
		(start 327.872598 -372.172992)
		(end 328.0664 -372.172992)
		(width 0.14224)
		(layer "In15.Cu")
		(net "P5E_CPU0_P0_RX_DN<9>")
	)
	(segment
		(start 353.628198 -288.178494)
		(end 353.66071 -288.159698)
		(width 0.1143)
		(layer "In15.Cu")
		(net "P5E_CPU0_P0_RX_DN<9>")
	)
	(segment
		(start 353.589082 -281.72156)
		(end 353.658678 -281.68092)
		(width 0.1143)
		(layer "In15.Cu")
		(net "P5E_CPU0_P0_RX_DN<9>")
	)
	(segment
		(start 353.658678 -277.831296)
		(end 353.589082 -277.790656)
		(width 0.1143)
		(layer "In15.Cu")
		(net "P5E_CPU0_P0_RX_DN<9>")
	)
	(segment
		(start 328.367898 -371.677438)
		(end 328.669904 -371.375432)
		(width 0.14224)
		(layer "In15.Cu")
		(net "P5E_CPU0_P0_RX_DN<9>")
	)
	(segment
		(start 328.0664 -372.172992)
		(end 328.367898 -371.871494)
		(width 0.14224)
		(layer "In15.Cu")
		(net "P5E_CPU0_P0_RX_DN<9>")
	)
	(segment
		(start 353.628198 -286.558482)
		(end 353.66071 -286.539686)
		(width 0.1143)
		(layer "In15.Cu")
		(net "P5E_CPU0_P0_RX_DN<9>")
	)
	(segment
		(start 353.589082 -284.961584)
		(end 353.658678 -284.920944)
		(width 0.1143)
		(layer "In15.Cu")
		(net "P5E_CPU0_P0_RX_DN<9>")
	)
	(segment
		(start 353.589082 -291.441378)
		(end 353.658678 -291.400738)
		(width 0.1143)
		(layer "In15.Cu")
		(net "P5E_CPU0_P0_RX_DN<9>")
	)
	(segment
		(start 329.467464 -370.577872)
		(end 329.66152 -370.577872)
		(width 0.14224)
		(layer "In15.Cu")
		(net "P5E_CPU0_P0_RX_DN<9>")
	)
	(segment
		(start 353.658678 -279.451308)
		(end 353.589082 -279.410668)
		(width 0.1143)
		(layer "In15.Cu")
		(net "P5E_CPU0_P0_RX_DN<9>")
	)
	(segment
		(start 314.75426 -392.616944)
		(end 315.058298 -392.31316)
		(width 0.14224)
		(layer "In15.Cu")
		(net "P5E_CPU0_P0_RX_DN<9>")
	)
	(segment
		(start 353.658678 -284.311344)
		(end 353.589082 -284.270704)
		(width 0.1143)
		(layer "In15.Cu")
		(net "P5E_CPU0_P0_RX_DN<9>")
	)
	(segment
		(start 328.669904 -371.375432)
		(end 328.86396 -371.375432)
		(width 0.14224)
		(layer "In15.Cu")
		(net "P5E_CPU0_P0_RX_DN<9>")
	)
	(segment
		(start 353.589082 -294.681402)
		(end 353.658678 -294.640762)
		(width 0.1143)
		(layer "In15.Cu")
		(net "P5E_CPU0_P0_RX_DN<9>")
	)
	(segment
		(start 359.75036 -368.19205)
		(end 359.75036 -367.62055)
		(width 0.14224)
		(layer "In15.Cu")
		(net "P5E_CPU0_P0_RX_DN<9>")
	)
	(segment
		(start 346.837 -367.17097)
		(end 346.837 -366.36579)
		(width 0.14224)
		(layer "In15.Cu")
		(net "P5E_CPU0_P0_RX_DN<9>")
	)
	(segment
		(start 353.589082 -280.101548)
		(end 353.658678 -280.060908)
		(width 0.1143)
		(layer "In15.Cu")
		(net "P5E_CPU0_P0_RX_DN<9>")
	)
	(segment
		(start 354.678996 -271.656048)
		(end 354.381054 -271.656048)
		(width 0.1143)
		(layer "In15.Cu")
		(net "P5E_CPU0_P0_RX_DN<9>")
	)
	(segment
		(start 352.957638 -296.300398)
		(end 352.957638 -295.919398)
		(width 0.1143)
		(layer "In15.Cu")
		(net "P5E_CPU0_P0_RX_DN<9>")
	)
	(segment
		(start 318.23533 -374.996202)
		(end 322.545202 -373.210836)
		(width 0.14224)
		(layer "In15.Cu")
		(net "P5E_CPU0_P0_RX_DN<9>")
	)
	(segment
		(start 393.228322 -354.099622)
		(end 366.92332 -328.322686)
		(width 0.14224)
		(layer "In15.Cu")
		(net "P5E_CPU0_P0_RX_DN<9>")
	)
	(segment
		(start 366.27435 -327.489058)
		(end 353.017074 -304.730404)
		(width 0.14224)
		(layer "In15.Cu")
		(net "P5E_CPU0_P0_RX_DN<9>")
	)
	(segment
		(start 314.94476 -393.786868)
		(end 315.066426 -393.716764)
		(width 0.14224)
		(layer "In15.Cu")
		(net "P5E_CPU0_P0_RX_DN<9>")
	)
	(segment
		(start 353.34575 -295.314878)
		(end 353.34575 -295.145968)
		(width 0.1143)
		(layer "In15.Cu")
		(net "P5E_CPU0_P0_RX_DN<9>")
	)
	(segment
		(start 354.748846 -271.725898)
		(end 354.678996 -271.656048)
		(width 0.1143)
		(layer "In15.Cu")
		(net "P5E_CPU0_P0_RX_DN<9>")
	)
	(segment
		(start 353.658678 -290.791138)
		(end 353.589082 -290.750498)
		(width 0.1143)
		(layer "In15.Cu")
		(net "P5E_CPU0_P0_RX_DN<9>")
	)
	(segment
		(start 346.837 -366.36579)
		(end 347.14434 -366.05845)
		(width 0.14224)
		(layer "In15.Cu")
		(net "P5E_CPU0_P0_RX_DN<9>")
	)
	(segment
		(start 354.529136 -272.001488)
		(end 354.598732 -271.960848)
		(width 0.1143)
		(layer "In15.Cu")
		(net "P5E_CPU0_P0_RX_DN<9>")
	)
	(segment
		(start 328.86396 -371.375432)
		(end 329.165458 -371.073934)
		(width 0.14224)
		(layer "In15.Cu")
		(net "P5E_CPU0_P0_RX_DN<9>")
	)
	(segment
		(start 393.671298 -365.111792)
		(end 393.671298 -355.152198)
		(width 0.14224)
		(layer "In15.Cu")
		(net "P5E_CPU0_P0_RX_DN<9>")
	)
	(segment
		(start 352.911918 -296.346118)
		(end 352.957638 -296.300398)
		(width 0.1143)
		(layer "In15.Cu")
		(net "P5E_CPU0_P0_RX_DN<9>")
	)
	(segment
		(start 327.570592 -372.474998)
		(end 327.872598 -372.172992)
		(width 0.14224)
		(layer "In15.Cu")
		(net "P5E_CPU0_P0_RX_DN<9>")
	)
	(segment
		(start 347.14434 -367.47831)
		(end 346.837 -367.17097)
		(width 0.14224)
		(layer "In15.Cu")
		(net "P5E_CPU0_P0_RX_DN<9>")
	)
	(segment
		(start 329.165458 -370.879878)
		(end 329.467464 -370.577872)
		(width 0.14224)
		(layer "In15.Cu")
		(net "P5E_CPU0_P0_RX_DN<9>")
	)
	(segment
		(start 329.165458 -371.073934)
		(end 329.165458 -370.879878)
		(width 0.14224)
		(layer "In15.Cu")
		(net "P5E_CPU0_P0_RX_DN<9>")
	)
	(segment
		(start 315.066172 -387.912864)
		(end 316.323726 -381.587502)
		(width 0.14224)
		(layer "In15.Cu")
		(net "P5E_CPU0_P0_RX_DN<9>")
	)
	(segment
		(start 314.944252 -393.787376)
		(end 314.94476 -393.786868)
		(width 0.14224)
		(layer "In15.Cu")
		(net "P5E_CPU0_P0_RX_DN<9>")
	)
	(segment
		(start 353.658678 -292.41115)
		(end 353.589082 -292.37051)
		(width 0.1143)
		(layer "In15.Cu")
		(net "P5E_CPU0_P0_RX_DN<9>")
	)
	(segment
		(start 353.658678 -276.211284)
		(end 353.589082 -276.170644)
		(width 0.1143)
		(layer "In15.Cu")
		(net "P5E_CPU0_P0_RX_DN<9>")
	)
	(segment
		(start 328.367898 -371.871494)
		(end 328.367898 -371.677438)
		(width 0.14224)
		(layer "In15.Cu")
		(net "P5E_CPU0_P0_RX_DN<9>")
	)
	(segment
		(start 347.14434 -366.05845)
		(end 392.712448 -366.05845)
		(width 0.14224)
		(layer "In15.Cu")
		(net "P5E_CPU0_P0_RX_DN<9>")
	)
	(segment
		(start 359.75036 -367.62055)
		(end 359.60812 -367.47831)
		(width 0.14224)
		(layer "In15.Cu")
		(net "P5E_CPU0_P0_RX_DN<9>")
	)
	(segment
		(start 353.589082 -278.481536)
		(end 353.658678 -278.440896)
		(width 0.1143)
		(layer "In15.Cu")
		(net "P5E_CPU0_P0_RX_DN<9>")
	)
	(segment
		(start 315.066426 -393.716764)
		(end 315.066426 -393.545822)
		(width 0.14224)
		(layer "In15.Cu")
		(net "P5E_CPU0_P0_RX_DN<9>")
	)
	(segment
		(start 359.60812 -367.47831)
		(end 347.14434 -367.47831)
		(width 0.14224)
		(layer "In15.Cu")
		(net "P5E_CPU0_P0_RX_DN<9>")
	)
	(segment
		(start 353.658678 -289.171126)
		(end 353.589082 -289.130486)
		(width 0.1143)
		(layer "In15.Cu")
		(net "P5E_CPU0_P0_RX_DN<9>")
	)
	(segment
		(start 327.16851 -373.070882)
		(end 327.570592 -372.6688)
		(width 0.14224)
		(layer "In15.Cu")
		(net "P5E_CPU0_P0_RX_DN<9>")
	)
	(segment
		(start 316.603634 -376.407934)
		(end 317.572136 -375.439432)
		(width 0.14224)
		(layer "In15.Cu")
		(net "P5E_CPU0_P0_RX_DN<9>")
	)
	(segment
		(start 352.911918 -304.340514)
		(end 352.911918 -296.374566)
		(width 0.14224)
		(layer "In15.Cu")
		(net "P5E_CPU0_P0_RX_DN<9>")
	)
	(segment
		(start 353.658678 -274.591272)
		(end 353.589082 -274.550632)
		(width 0.1143)
		(layer "In15.Cu")
		(net "P5E_CPU0_P0_RX_DN<9>")
	)
	(segment
		(start 317.572136 -375.439432)
		(end 318.23533 -374.996202)
		(width 0.14224)
		(layer "In15.Cu")
		(net "P5E_CPU0_P0_RX_DN<9>")
	)
	(segment
		(start 353.050856 -295.694608)
		(end 353.285298 -295.460166)
		(width 0.1143)
		(layer "In15.Cu")
		(net "P5E_CPU0_P0_RX_DN<9>")
	)
	(segment
		(start 353.589082 -288.201354)
		(end 353.628198 -288.178494)
		(width 0.1143)
		(layer "In15.Cu")
		(net "P5E_CPU0_P0_RX_DN<9>")
	)
	(segment
		(start 315.066426 -393.545822)
		(end 314.749434 -393.22883)
		(width 0.14224)
		(layer "In15.Cu")
		(net "P5E_CPU0_P0_RX_DN<9>")
	)
	(segment
		(start 329.66152 -370.577872)
		(end 331.785214 -368.454178)
		(width 0.14224)
		(layer "In15.Cu")
		(net "P5E_CPU0_P0_RX_DN<9>")
	)
	(segment
		(start 353.589082 -275.241512)
		(end 353.658678 -275.200872)
		(width 0.1143)
		(layer "In15.Cu")
		(net "P5E_CPU0_P0_RX_DN<9>")
	)
	(segment
		(start 316.323726 -381.587502)
		(end 316.323726 -377.083574)
		(width 0.14224)
		(layer "In15.Cu")
		(net "P5E_CPU0_P0_RX_DN<9>")
	)
	(segment
		(start 315.058298 -392.31316)
		(end 315.058298 -387.99262)
		(width 0.14224)
		(layer "In15.Cu")
		(net "P5E_CPU0_P0_RX_DN<9>")
	)
	(segment
		(start 353.589082 -289.821366)
		(end 353.658678 -289.780726)
		(width 0.1143)
		(layer "In15.Cu")
		(net "P5E_CPU0_P0_RX_DN<9>")
	)
	(segment
		(start 353.658678 -282.691332)
		(end 353.589082 -282.650692)
		(width 0.1143)
		(layer "In15.Cu")
		(net "P5E_CPU0_P0_RX_DN<9>")
	)
	(segment
		(start 314.590938 -393.69238)
		(end 314.944252 -393.787376)
		(width 0.14224)
		(layer "In15.Cu")
		(net "P5E_CPU0_P0_RX_DN<9>")
	)
	(segment
		(start 353.589082 -286.581342)
		(end 353.591114 -286.579818)
		(width 0.1143)
		(layer "In15.Cu")
		(net "P5E_CPU0_P0_RX_DN<9>")
	)
	(segment
		(start 353.658678 -285.931356)
		(end 353.589082 -285.890716)
		(width 0.1143)
		(layer "In15.Cu")
		(net "P5E_CPU0_P0_RX_DN<9>")
	)
	(segment
		(start 353.589082 -276.861524)
		(end 353.658678 -276.820884)
		(width 0.1143)
		(layer "In15.Cu")
		(net "P5E_CPU0_P0_RX_DN<9>")
	)
	(segment
		(start 353.589082 -283.341572)
		(end 353.658678 -283.300932)
		(width 0.1143)
		(layer "In15.Cu")
		(net "P5E_CPU0_P0_RX_DN<9>")
	)
	(segment
		(start 353.658678 -281.07132)
		(end 353.589082 -281.03068)
		(width 0.1143)
		(layer "In15.Cu")
		(net "P5E_CPU0_P0_RX_DN<9>")
	)
	(segment
		(start 352.911918 -296.374566)
		(end 352.911918 -296.346118)
		(width 0.1143)
		(layer "In15.Cu")
		(net "P5E_CPU0_P0_RX_DN<9>")
	)
	(arc
		(start 353.658678 -276.820884)
		(mid 353.815655 -276.516084)
		(end 353.658678 -276.211284)
		(width 0.1143)
		(layer "In15.Cu")
		(net "P5E_CPU0_P0_RX_DN<9>")
	)
	(arc
		(start 353.34575 -287.045908)
		(mid 353.410265 -286.783689)
		(end 353.589082 -286.581342)
		(width 0.1143)
		(layer "In15.Cu")
		(net "P5E_CPU0_P0_RX_DN<9>")
	)
	(arc
		(start 354.598732 -271.960848)
		(mid 354.696497 -271.857872)
		(end 354.748846 -271.725898)
		(width 0.1143)
		(layer "In15.Cu")
		(net "P5E_CPU0_P0_RX_DN<9>")
	)
	(arc
		(start 366.92332 -328.322686)
		(mid 366.570855 -327.927654)
		(end 366.27435 -327.489058)
		(width 0.14224)
		(layer "In15.Cu")
		(net "P5E_CPU0_P0_RX_DN<9>")
	)
	(arc
		(start 393.583668 -365.32312)
		(mid 393.648507 -365.226176)
		(end 393.671298 -365.111792)
		(width 0.14224)
		(layer "In15.Cu")
		(net "P5E_CPU0_P0_RX_DN<9>")
	)
	(arc
		(start 353.81565 -287.856168)
		(mid 353.774101 -287.684746)
		(end 353.658678 -287.551368)
		(width 0.1143)
		(layer "In15.Cu")
		(net "P5E_CPU0_P0_RX_DN<9>")
	)
	(arc
		(start 353.017074 -304.730404)
		(mid 352.938651 -304.542428)
		(end 352.911918 -304.340514)
		(width 0.14224)
		(layer "In15.Cu")
		(net "P5E_CPU0_P0_RX_DN<9>")
	)
	(arc
		(start 353.658678 -280.060908)
		(mid 353.815655 -279.756108)
		(end 353.658678 -279.451308)
		(width 0.1143)
		(layer "In15.Cu")
		(net "P5E_CPU0_P0_RX_DN<9>")
	)
	(arc
		(start 353.589082 -285.890716)
		(mid 353.345755 -285.42615)
		(end 353.589082 -284.961584)
		(width 0.1143)
		(layer "In15.Cu")
		(net "P5E_CPU0_P0_RX_DN<9>")
	)
	(arc
		(start 331.785214 -368.454178)
		(mid 331.918079 -368.365463)
		(end 332.074774 -368.33429)
		(width 0.14224)
		(layer "In15.Cu")
		(net "P5E_CPU0_P0_RX_DN<9>")
	)
	(arc
		(start 353.658678 -291.400738)
		(mid 353.815655 -291.095938)
		(end 353.658678 -290.791138)
		(width 0.1143)
		(layer "In15.Cu")
		(net "P5E_CPU0_P0_RX_DN<9>")
	)
	(arc
		(start 353.589082 -282.650692)
		(mid 353.345755 -282.186126)
		(end 353.589082 -281.72156)
		(width 0.1143)
		(layer "In15.Cu")
		(net "P5E_CPU0_P0_RX_DN<9>")
	)
	(arc
		(start 392.712448 -366.05845)
		(mid 392.838115 -366.033435)
		(end 392.944604 -365.962184)
		(width 0.14224)
		(layer "In15.Cu")
		(net "P5E_CPU0_P0_RX_DN<9>")
	)
	(arc
		(start 353.81565 -286.236156)
		(mid 353.774101 -286.064734)
		(end 353.658678 -285.931356)
		(width 0.1143)
		(layer "In15.Cu")
		(net "P5E_CPU0_P0_RX_DN<9>")
	)
	(arc
		(start 353.658678 -278.440896)
		(mid 353.815655 -278.136096)
		(end 353.658678 -277.831296)
		(width 0.1143)
		(layer "In15.Cu")
		(net "P5E_CPU0_P0_RX_DN<9>")
	)
	(arc
		(start 322.545202 -373.210836)
		(mid 322.774442 -373.141455)
		(end 323.012816 -373.118126)
		(width 0.14224)
		(layer "In15.Cu")
		(net "P5E_CPU0_P0_RX_DN<9>")
	)
	(arc
		(start 353.589082 -293.990522)
		(mid 353.345755 -293.525956)
		(end 353.589082 -293.06139)
		(width 0.1143)
		(layer "In15.Cu")
		(net "P5E_CPU0_P0_RX_DN<9>")
	)
	(arc
		(start 354.129848 -272.770346)
		(mid 354.244524 -272.637012)
		(end 354.285804 -272.466054)
		(width 0.1143)
		(layer "In15.Cu")
		(net "P5E_CPU0_P0_RX_DN<9>")
	)
	(arc
		(start 353.589082 -292.37051)
		(mid 353.345755 -291.905944)
		(end 353.589082 -291.441378)
		(width 0.1143)
		(layer "In15.Cu")
		(net "P5E_CPU0_P0_RX_DN<9>")
	)
	(arc
		(start 315.058298 -387.99262)
		(mid 315.060287 -387.95255)
		(end 315.066172 -387.912864)
		(width 0.14224)
		(layer "In15.Cu")
		(net "P5E_CPU0_P0_RX_DN<9>")
	)
	(arc
		(start 327.054464 -373.118126)
		(mid 327.116187 -373.105849)
		(end 327.16851 -373.070882)
		(width 0.14224)
		(layer "In15.Cu")
		(net "P5E_CPU0_P0_RX_DN<9>")
	)
	(arc
		(start 353.66071 -286.539686)
		(mid 353.774639 -286.406539)
		(end 353.81565 -286.236156)
		(width 0.1143)
		(layer "In15.Cu")
		(net "P5E_CPU0_P0_RX_DN<9>")
	)
	(arc
		(start 353.658678 -283.300932)
		(mid 353.815655 -282.996132)
		(end 353.658678 -282.691332)
		(width 0.1143)
		(layer "In15.Cu")
		(net "P5E_CPU0_P0_RX_DN<9>")
	)
	(arc
		(start 393.671298 -355.152198)
		(mid 393.556036 -354.581208)
		(end 393.228322 -354.099622)
		(width 0.14224)
		(layer "In15.Cu")
		(net "P5E_CPU0_P0_RX_DN<9>")
	)
	(arc
		(start 353.658678 -284.920944)
		(mid 353.815655 -284.616144)
		(end 353.658678 -284.311344)
		(width 0.1143)
		(layer "In15.Cu")
		(net "P5E_CPU0_P0_RX_DN<9>")
	)
	(arc
		(start 353.658678 -273.58086)
		(mid 353.774105 -273.447484)
		(end 353.81565 -273.27606)
		(width 0.1143)
		(layer "In15.Cu")
		(net "P5E_CPU0_P0_RX_DN<9>")
	)
	(arc
		(start 353.285298 -295.460166)
		(mid 353.329975 -295.393537)
		(end 353.34575 -295.314878)
		(width 0.1143)
		(layer "In15.Cu")
		(net "P5E_CPU0_P0_RX_DN<9>")
	)
	(arc
		(start 353.66071 -288.159698)
		(mid 353.774639 -288.026551)
		(end 353.81565 -287.856168)
		(width 0.1143)
		(layer "In15.Cu")
		(net "P5E_CPU0_P0_RX_DN<9>")
	)
	(arc
		(start 353.34575 -295.145968)
		(mid 353.410265 -294.883749)
		(end 353.589082 -294.681402)
		(width 0.1143)
		(layer "In15.Cu")
		(net "P5E_CPU0_P0_RX_DN<9>")
	)
	(arc
		(start 353.589082 -276.170644)
		(mid 353.345755 -275.706078)
		(end 353.589082 -275.241512)
		(width 0.1143)
		(layer "In15.Cu")
		(net "P5E_CPU0_P0_RX_DN<9>")
	)
	(arc
		(start 316.323726 -377.083574)
		(mid 316.396478 -376.717916)
		(end 316.603634 -376.407934)
		(width 0.14224)
		(layer "In15.Cu")
		(net "P5E_CPU0_P0_RX_DN<9>")
	)
	(arc
		(start 353.81565 -273.27606)
		(mid 353.880165 -273.013841)
		(end 354.058982 -272.811494)
		(width 0.1143)
		(layer "In15.Cu")
		(net "P5E_CPU0_P0_RX_DN<9>")
	)
	(arc
		(start 353.589082 -284.270704)
		(mid 353.345755 -283.806138)
		(end 353.589082 -283.341572)
		(width 0.1143)
		(layer "In15.Cu")
		(net "P5E_CPU0_P0_RX_DN<9>")
	)
	(arc
		(start 353.658678 -281.68092)
		(mid 353.815655 -281.37612)
		(end 353.658678 -281.07132)
		(width 0.1143)
		(layer "In15.Cu")
		(net "P5E_CPU0_P0_RX_DN<9>")
	)
	(arc
		(start 353.591622 -287.512252)
		(mid 353.41097 -287.309507)
		(end 353.34575 -287.045908)
		(width 0.1143)
		(layer "In15.Cu")
		(net "P5E_CPU0_P0_RX_DN<9>")
	)
	(arc
		(start 352.957638 -295.919398)
		(mid 352.981928 -295.797755)
		(end 353.050856 -295.694608)
		(width 0.1143)
		(layer "In15.Cu")
		(net "P5E_CPU0_P0_RX_DN<9>")
	)
	(arc
		(start 353.589082 -274.550632)
		(mid 353.345755 -274.086066)
		(end 353.589082 -273.6215)
		(width 0.1143)
		(layer "In15.Cu")
		(net "P5E_CPU0_P0_RX_DN<9>")
	)
	(arc
		(start 353.658678 -275.200872)
		(mid 353.815655 -274.896072)
		(end 353.658678 -274.591272)
		(width 0.1143)
		(layer "In15.Cu")
		(net "P5E_CPU0_P0_RX_DN<9>")
	)
	(arc
		(start 353.658678 -294.640762)
		(mid 353.815655 -294.335962)
		(end 353.658678 -294.031162)
		(width 0.1143)
		(layer "In15.Cu")
		(net "P5E_CPU0_P0_RX_DN<9>")
	)
	(arc
		(start 353.589082 -279.410668)
		(mid 353.345755 -278.946102)
		(end 353.589082 -278.481536)
		(width 0.1143)
		(layer "In15.Cu")
		(net "P5E_CPU0_P0_RX_DN<9>")
	)
	(arc
		(start 353.658678 -293.02075)
		(mid 353.815655 -292.71595)
		(end 353.658678 -292.41115)
		(width 0.1143)
		(layer "In15.Cu")
		(net "P5E_CPU0_P0_RX_DN<9>")
	)
	(arc
		(start 354.285804 -272.466054)
		(mid 354.350319 -272.203835)
		(end 354.529136 -272.001488)
		(width 0.1143)
		(layer "In15.Cu")
		(net "P5E_CPU0_P0_RX_DN<9>")
	)
	(arc
		(start 353.589082 -281.03068)
		(mid 353.345755 -280.566114)
		(end 353.589082 -280.101548)
		(width 0.1143)
		(layer "In15.Cu")
		(net "P5E_CPU0_P0_RX_DN<9>")
	)
	(arc
		(start 353.589082 -290.750498)
		(mid 353.345755 -290.285932)
		(end 353.589082 -289.821366)
		(width 0.1143)
		(layer "In15.Cu")
		(net "P5E_CPU0_P0_RX_DN<9>")
	)
	(arc
		(start 353.658678 -289.780726)
		(mid 353.815655 -289.475926)
		(end 353.658678 -289.171126)
		(width 0.1143)
		(layer "In15.Cu")
		(net "P5E_CPU0_P0_RX_DN<9>")
	)
	(arc
		(start 353.589082 -277.790656)
		(mid 353.345755 -277.32609)
		(end 353.589082 -276.861524)
		(width 0.1143)
		(layer "In15.Cu")
		(net "P5E_CPU0_P0_RX_DN<9>")
	)
	(arc
		(start 353.589082 -289.130486)
		(mid 353.345755 -288.66592)
		(end 353.589082 -288.201354)
		(width 0.1143)
		(layer "In15.Cu")
		(net "P5E_CPU0_P0_RX_DN<9>")
	)
	(segment
		(start 352.027998 -269.770098)
		(end 351.561146 -270.036036)
		(width 0.12954)
		(layer "F.Cu")
		(net "P5E_CPU0_P0_RX_DN<8>")
	)
	(segment
		(start 312.870342 -393.69238)
		(end 313.391042 -393.69238)
		(width 0.127)
		(layer "F.Cu")
		(net "P5E_CPU0_P0_RX_DN<8>")
	)
	(segment
		(start 352.693478 -294.01643)
		(end 352.692462 -294.015922)
		(width 0.1143)
		(layer "In15.Cu")
		(net "P5E_CPU0_P0_RX_DN<8>")
	)
	(segment
		(start 352.695002 -271.974818)
		(end 352.695764 -271.97431)
		(width 0.1143)
		(layer "In15.Cu")
		(net "P5E_CPU0_P0_RX_DN<8>")
	)
	(segment
		(start 352.408744 -287.090358)
		(end 352.408744 -286.989774)
		(width 0.1143)
		(layer "In15.Cu")
		(net "P5E_CPU0_P0_RX_DN<8>")
	)
	(segment
		(start 352.692208 -276.836378)
		(end 352.693224 -276.83587)
		(width 0.1143)
		(layer "In15.Cu")
		(net "P5E_CPU0_P0_RX_DN<8>")
	)
	(segment
		(start 352.719894 -279.451816)
		(end 352.69424 -279.437084)
		(width 0.1143)
		(layer "In15.Cu")
		(net "P5E_CPU0_P0_RX_DN<8>")
	)
	(segment
		(start 352.69424 -294.016938)
		(end 352.693478 -294.01643)
		(width 0.1143)
		(layer "In15.Cu")
		(net "P5E_CPU0_P0_RX_DN<8>")
	)
	(segment
		(start 352.621342 -283.361384)
		(end 352.649282 -283.341318)
		(width 0.1143)
		(layer "In15.Cu")
		(net "P5E_CPU0_P0_RX_DN<8>")
	)
	(segment
		(start 352.690176 -272.95475)
		(end 352.688906 -272.953988)
		(width 0.1143)
		(layer "In15.Cu")
		(net "P5E_CPU0_P0_RX_DN<8>")
	)
	(segment
		(start 314.29325 -375.862596)
		(end 316.684152 -374.873266)
		(width 0.14224)
		(layer "In15.Cu")
		(net "P5E_CPU0_P0_RX_DN<8>")
	)
	(segment
		(start 352.649282 -277.79091)
		(end 352.621342 -277.770844)
		(width 0.1143)
		(layer "In15.Cu")
		(net "P5E_CPU0_P0_RX_DN<8>")
	)
	(segment
		(start 352.69424 -279.437084)
		(end 352.692716 -279.436068)
		(width 0.1143)
		(layer "In15.Cu")
		(net "P5E_CPU0_P0_RX_DN<8>")
	)
	(segment
		(start 352.649282 -279.410922)
		(end 352.621342 -279.390856)
		(width 0.1143)
		(layer "In15.Cu")
		(net "P5E_CPU0_P0_RX_DN<8>")
	)
	(segment
		(start 352.719894 -287.551876)
		(end 352.688144 -287.533588)
		(width 0.1143)
		(layer "In15.Cu")
		(net "P5E_CPU0_P0_RX_DN<8>")
	)
	(segment
		(start 351.966784 -296.346118)
		(end 352.012504 -296.300398)
		(width 0.1143)
		(layer "In15.Cu")
		(net "P5E_CPU0_P0_RX_DN<8>")
	)
	(segment
		(start 352.688906 -279.434036)
		(end 352.688144 -279.433528)
		(width 0.1143)
		(layer "In15.Cu")
		(net "P5E_CPU0_P0_RX_DN<8>")
	)
	(segment
		(start 326.27443 -372.112286)
		(end 331.000862 -367.3856)
		(width 0.14224)
		(layer "In15.Cu")
		(net "P5E_CPU0_P0_RX_DN<8>")
	)
	(segment
		(start 352.69678 -278.45385)
		(end 352.719894 -278.440388)
		(width 0.1143)
		(layer "In15.Cu")
		(net "P5E_CPU0_P0_RX_DN<8>")
	)
	(segment
		(start 352.688144 -291.418518)
		(end 352.709226 -291.406326)
		(width 0.1143)
		(layer "In15.Cu")
		(net "P5E_CPU0_P0_RX_DN<8>")
	)
	(segment
		(start 352.69678 -283.313886)
		(end 352.719894 -283.300424)
		(width 0.1143)
		(layer "In15.Cu")
		(net "P5E_CPU0_P0_RX_DN<8>")
	)
	(segment
		(start 352.68535 -279.43175)
		(end 352.649282 -279.410922)
		(width 0.1143)
		(layer "In15.Cu")
		(net "P5E_CPU0_P0_RX_DN<8>")
	)
	(segment
		(start 333.71028 -367.128552)
		(end 334.137 -367.128552)
		(width 0.14224)
		(layer "In15.Cu")
		(net "P5E_CPU0_P0_RX_DN<8>")
	)
	(segment
		(start 344.430604 -367.265712)
		(end 344.572844 -367.123472)
		(width 0.14224)
		(layer "In15.Cu")
		(net "P5E_CPU0_P0_RX_DN<8>")
	)
	(segment
		(start 334.137 -367.128552)
		(end 334.27416 -367.265712)
		(width 0.14224)
		(layer "In15.Cu")
		(net "P5E_CPU0_P0_RX_DN<8>")
	)
	(segment
		(start 352.69043 -283.317442)
		(end 352.691446 -283.316934)
		(width 0.1143)
		(layer "In15.Cu")
		(net "P5E_CPU0_P0_RX_DN<8>")
	)
	(segment
		(start 352.69424 -290.776914)
		(end 352.693478 -290.776406)
		(width 0.1143)
		(layer "In15.Cu")
		(net "P5E_CPU0_P0_RX_DN<8>")
	)
	(segment
		(start 352.688144 -284.938724)
		(end 352.719894 -284.920436)
		(width 0.1143)
		(layer "In15.Cu")
		(net "P5E_CPU0_P0_RX_DN<8>")
	)
	(segment
		(start 392.28903 -364.82401)
		(end 392.446256 -364.666784)
		(width 0.14224)
		(layer "In15.Cu")
		(net "P5E_CPU0_P0_RX_DN<8>")
	)
	(segment
		(start 352.719894 -277.831804)
		(end 352.69424 -277.817072)
		(width 0.1143)
		(layer "In15.Cu")
		(net "P5E_CPU0_P0_RX_DN<8>")
	)
	(segment
		(start 352.693986 -271.975326)
		(end 352.695002 -271.974818)
		(width 0.1143)
		(layer "In15.Cu")
		(net "P5E_CPU0_P0_RX_DN<8>")
	)
	(segment
		(start 312.934858 -378.01042)
		(end 312.934858 -376.792744)
		(width 0.14224)
		(layer "In15.Cu")
		(net "P5E_CPU0_P0_RX_DN<8>")
	)
	(segment
		(start 352.621342 -278.501348)
		(end 352.649282 -278.481282)
		(width 0.1143)
		(layer "In15.Cu")
		(net "P5E_CPU0_P0_RX_DN<8>")
	)
	(segment
		(start 352.688144 -282.673552)
		(end 352.68535 -282.671774)
		(width 0.1143)
		(layer "In15.Cu")
		(net "P5E_CPU0_P0_RX_DN<8>")
	)
	(segment
		(start 352.6917 -294.015414)
		(end 352.690684 -294.014906)
		(width 0.1143)
		(layer "In15.Cu")
		(net "P5E_CPU0_P0_RX_DN<8>")
	)
	(segment
		(start 352.719894 -271.351756)
		(end 352.688906 -271.333976)
		(width 0.1143)
		(layer "In15.Cu")
		(net "P5E_CPU0_P0_RX_DN<8>")
	)
	(segment
		(start 338.8741 -364.989872)
		(end 391.888726 -364.989872)
		(width 0.14224)
		(layer "In15.Cu")
		(net "P5E_CPU0_P0_RX_DN<8>")
	)
	(segment
		(start 352.688906 -284.294072)
		(end 352.688144 -284.293564)
		(width 0.1143)
		(layer "In15.Cu")
		(net "P5E_CPU0_P0_RX_DN<8>")
	)
	(segment
		(start 352.649282 -276.86127)
		(end 352.689668 -276.837902)
		(width 0.1143)
		(layer "In15.Cu")
		(net "P5E_CPU0_P0_RX_DN<8>")
	)
	(segment
		(start 352.68535 -276.191726)
		(end 352.649282 -276.170898)
		(width 0.1143)
		(layer "In15.Cu")
		(net "P5E_CPU0_P0_RX_DN<8>")
	)
	(segment
		(start 352.694748 -275.215096)
		(end 352.69551 -275.214588)
		(width 0.1143)
		(layer "In15.Cu")
		(net "P5E_CPU0_P0_RX_DN<8>")
	)
	(segment
		(start 352.69678 -292.39845)
		(end 352.69424 -292.396926)
		(width 0.1143)
		(layer "In15.Cu")
		(net "P5E_CPU0_P0_RX_DN<8>")
	)
	(segment
		(start 352.688144 -284.293564)
		(end 352.68535 -284.291786)
		(width 0.1143)
		(layer "In15.Cu")
		(net "P5E_CPU0_P0_RX_DN<8>")
	)
	(segment
		(start 352.709226 -289.786314)
		(end 352.709988 -289.785806)
		(width 0.1143)
		(layer "In15.Cu")
		(net "P5E_CPU0_P0_RX_DN<8>")
	)
	(segment
		(start 352.688144 -281.053286)
		(end 352.64852 -281.03068)
		(width 0.1143)
		(layer "In15.Cu")
		(net "P5E_CPU0_P0_RX_DN<8>")
	)
	(segment
		(start 352.68789 -293.038784)
		(end 352.688144 -293.03853)
		(width 0.1143)
		(layer "In15.Cu")
		(net "P5E_CPU0_P0_RX_DN<8>")
	)
	(segment
		(start 352.709226 -293.026338)
		(end 352.709988 -293.02583)
		(width 0.1143)
		(layer "In15.Cu")
		(net "P5E_CPU0_P0_RX_DN<8>")
	)
	(segment
		(start 352.691446 -281.696922)
		(end 352.692208 -281.696414)
		(width 0.1143)
		(layer "In15.Cu")
		(net "P5E_CPU0_P0_RX_DN<8>")
	)
	(segment
		(start 352.693224 -278.455882)
		(end 352.693986 -278.455374)
		(width 0.1143)
		(layer "In15.Cu")
		(net "P5E_CPU0_P0_RX_DN<8>")
	)
	(segment
		(start 352.692462 -294.015922)
		(end 352.6917 -294.015414)
		(width 0.1143)
		(layer "In15.Cu")
		(net "P5E_CPU0_P0_RX_DN<8>")
	)
	(segment
		(start 352.688144 -276.193504)
		(end 352.68535 -276.191726)
		(width 0.1143)
		(layer "In15.Cu")
		(net "P5E_CPU0_P0_RX_DN<8>")
	)
	(segment
		(start 352.649282 -281.721306)
		(end 352.689668 -281.697938)
		(width 0.1143)
		(layer "In15.Cu")
		(net "P5E_CPU0_P0_RX_DN<8>")
	)
	(segment
		(start 352.621342 -276.881336)
		(end 352.649282 -276.86127)
		(width 0.1143)
		(layer "In15.Cu")
		(net "P5E_CPU0_P0_RX_DN<8>")
	)
	(segment
		(start 344.572844 -367.123472)
		(end 344.572844 -366.551972)
		(width 0.14224)
		(layer "In15.Cu")
		(net "P5E_CPU0_P0_RX_DN<8>")
	)
	(segment
		(start 352.692716 -284.296104)
		(end 352.690176 -284.294834)
		(width 0.1143)
		(layer "In15.Cu")
		(net "P5E_CPU0_P0_RX_DN<8>")
	)
	(segment
		(start 352.68789 -294.658796)
		(end 352.688652 -294.658288)
		(width 0.1143)
		(layer "In15.Cu")
		(net "P5E_CPU0_P0_RX_DN<8>")
	)
	(segment
		(start 352.690176 -285.914846)
		(end 352.688906 -285.914084)
		(width 0.1143)
		(layer "In15.Cu")
		(net "P5E_CPU0_P0_RX_DN<8>")
	)
	(segment
		(start 352.690176 -279.434798)
		(end 352.688906 -279.434036)
		(width 0.1143)
		(layer "In15.Cu")
		(net "P5E_CPU0_P0_RX_DN<8>")
	)
	(segment
		(start 352.692716 -285.916116)
		(end 352.690176 -285.914846)
		(width 0.1143)
		(layer "In15.Cu")
		(net "P5E_CPU0_P0_RX_DN<8>")
	)
	(segment
		(start 352.68789 -289.79876)
		(end 352.688144 -289.798506)
		(width 0.1143)
		(layer "In15.Cu")
		(net "P5E_CPU0_P0_RX_DN<8>")
	)
	(segment
		(start 352.69424 -282.677108)
		(end 352.692716 -282.676092)
		(width 0.1143)
		(layer "In15.Cu")
		(net "P5E_CPU0_P0_RX_DN<8>")
	)
	(segment
		(start 352.719894 -294.03167)
		(end 352.697542 -294.018716)
		(width 0.1143)
		(layer "In15.Cu")
		(net "P5E_CPU0_P0_RX_DN<8>")
	)
	(segment
		(start 352.694748 -294.654986)
		(end 352.69551 -294.654478)
		(width 0.1143)
		(layer "In15.Cu")
		(net "P5E_CPU0_P0_RX_DN<8>")
	)
	(segment
		(start 352.690176 -282.674822)
		(end 352.688906 -282.67406)
		(width 0.1143)
		(layer "In15.Cu")
		(net "P5E_CPU0_P0_RX_DN<8>")
	)
	(segment
		(start 352.688906 -276.194012)
		(end 352.688144 -276.193504)
		(width 0.1143)
		(layer "In15.Cu")
		(net "P5E_CPU0_P0_RX_DN<8>")
	)
	(segment
		(start 313.866276 -386.129784)
		(end 314.621926 -382.329944)
		(width 0.14224)
		(layer "In15.Cu")
		(net "P5E_CPU0_P0_RX_DN<8>")
	)
	(segment
		(start 352.689922 -292.394386)
		(end 352.688906 -292.393878)
		(width 0.1143)
		(layer "In15.Cu")
		(net "P5E_CPU0_P0_RX_DN<8>")
	)
	(segment
		(start 352.709988 -293.02583)
		(end 352.719894 -293.020242)
		(width 0.1143)
		(layer "In15.Cu")
		(net "P5E_CPU0_P0_RX_DN<8>")
	)
	(segment
		(start 331.290422 -367.265712)
		(end 332.37932 -367.265712)
		(width 0.14224)
		(layer "In15.Cu")
		(net "P5E_CPU0_P0_RX_DN<8>")
	)
	(segment
		(start 352.6917 -292.395402)
		(end 352.690684 -292.394894)
		(width 0.1143)
		(layer "In15.Cu")
		(net "P5E_CPU0_P0_RX_DN<8>")
	)
	(segment
		(start 352.63709 -272.921984)
		(end 352.621342 -272.910808)
		(width 0.1143)
		(layer "In15.Cu")
		(net "P5E_CPU0_P0_RX_DN<8>")
	)
	(segment
		(start 352.68535 -284.291786)
		(end 352.649282 -284.270958)
		(width 0.1143)
		(layer "In15.Cu")
		(net "P5E_CPU0_P0_RX_DN<8>")
	)
	(segment
		(start 352.709226 -291.406326)
		(end 352.709988 -291.405818)
		(width 0.1143)
		(layer "In15.Cu")
		(net "P5E_CPU0_P0_RX_DN<8>")
	)
	(segment
		(start 352.695764 -281.694382)
		(end 352.69678 -281.693874)
		(width 0.1143)
		(layer "In15.Cu")
		(net "P5E_CPU0_P0_RX_DN<8>")
	)
	(segment
		(start 313.064652 -376.479308)
		(end 313.331606 -376.212354)
		(width 0.14224)
		(layer "In15.Cu")
		(net "P5E_CPU0_P0_RX_DN<8>")
	)
	(segment
		(start 352.696272 -290.77793)
		(end 352.69424 -290.776914)
		(width 0.1143)
		(layer "In15.Cu")
		(net "P5E_CPU0_P0_RX_DN<8>")
	)
	(segment
		(start 351.966784 -304.41773)
		(end 351.966784 -296.374566)
		(width 0.14224)
		(layer "In15.Cu")
		(net "P5E_CPU0_P0_RX_DN<8>")
	)
	(segment
		(start 313.858402 -392.31316)
		(end 313.858402 -386.20954)
		(width 0.14224)
		(layer "In15.Cu")
		(net "P5E_CPU0_P0_RX_DN<8>")
	)
	(segment
		(start 352.692716 -277.816056)
		(end 352.690176 -277.814786)
		(width 0.1143)
		(layer "In15.Cu")
		(net "P5E_CPU0_P0_RX_DN<8>")
	)
	(segment
		(start 335.46542 -367.265712)
		(end 344.430604 -367.265712)
		(width 0.14224)
		(layer "In15.Cu")
		(net "P5E_CPU0_P0_RX_DN<8>")
	)
	(segment
		(start 352.709988 -291.405818)
		(end 352.719894 -291.40023)
		(width 0.1143)
		(layer "In15.Cu")
		(net "P5E_CPU0_P0_RX_DN<8>")
	)
	(segment
		(start 352.688652 -294.658288)
		(end 352.689668 -294.65778)
		(width 0.1143)
		(layer "In15.Cu")
		(net "P5E_CPU0_P0_RX_DN<8>")
	)
	(segment
		(start 352.64852 -281.03068)
		(end 352.621596 -281.011122)
		(width 0.1143)
		(layer "In15.Cu")
		(net "P5E_CPU0_P0_RX_DN<8>")
	)
	(segment
		(start 352.688906 -290.773866)
		(end 352.688144 -290.773358)
		(width 0.1143)
		(layer "In15.Cu")
		(net "P5E_CPU0_P0_RX_DN<8>")
	)
	(segment
		(start 351.859088 -270.036036)
		(end 351.561146 -270.036036)
		(width 0.1143)
		(layer "In15.Cu")
		(net "P5E_CPU0_P0_RX_DN<8>")
	)
	(segment
		(start 352.69424 -276.19706)
		(end 352.692716 -276.196044)
		(width 0.1143)
		(layer "In15.Cu")
		(net "P5E_CPU0_P0_RX_DN<8>")
	)
	(segment
		(start 352.69424 -292.396926)
		(end 352.693478 -292.396418)
		(width 0.1143)
		(layer "In15.Cu")
		(net "P5E_CPU0_P0_RX_DN<8>")
	)
	(segment
		(start 352.688906 -274.574)
		(end 352.688144 -274.573492)
		(width 0.1143)
		(layer "In15.Cu")
		(net "P5E_CPU0_P0_RX_DN<8>")
	)
	(segment
		(start 352.692208 -278.45639)
		(end 352.693224 -278.455882)
		(width 0.1143)
		(layer "In15.Cu")
		(net "P5E_CPU0_P0_RX_DN<8>")
	)
	(segment
		(start 352.621342 -275.261324)
		(end 352.649282 -275.241258)
		(width 0.1143)
		(layer "In15.Cu")
		(net "P5E_CPU0_P0_RX_DN<8>")
	)
	(segment
		(start 352.69043 -294.657272)
		(end 352.691446 -294.656764)
		(width 0.1143)
		(layer "In15.Cu")
		(net "P5E_CPU0_P0_RX_DN<8>")
	)
	(segment
		(start 352.691446 -283.316934)
		(end 352.692208 -283.316426)
		(width 0.1143)
		(layer "In15.Cu")
		(net "P5E_CPU0_P0_RX_DN<8>")
	)
	(segment
		(start 352.688144 -271.333468)
		(end 352.687128 -271.33296)
		(width 0.1143)
		(layer "In15.Cu")
		(net "P5E_CPU0_P0_RX_DN<8>")
	)
	(segment
		(start 352.691446 -278.456898)
		(end 352.692208 -278.45639)
		(width 0.1143)
		(layer "In15.Cu")
		(net "P5E_CPU0_P0_RX_DN<8>")
	)
	(segment
		(start 352.69043 -271.977358)
		(end 352.691446 -271.97685)
		(width 0.1143)
		(layer "In15.Cu")
		(net "P5E_CPU0_P0_RX_DN<8>")
	)
	(segment
		(start 352.63963 -272.923762)
		(end 352.638614 -272.923)
		(width 0.1143)
		(layer "In15.Cu")
		(net "P5E_CPU0_P0_RX_DN<8>")
	)
	(segment
		(start 352.695764 -271.97431)
		(end 352.69678 -271.973802)
		(width 0.1143)
		(layer "In15.Cu")
		(net "P5E_CPU0_P0_RX_DN<8>")
	)
	(segment
		(start 352.690684 -290.774882)
		(end 352.689922 -290.774374)
		(width 0.1143)
		(layer "In15.Cu")
		(net "P5E_CPU0_P0_RX_DN<8>")
	)
	(segment
		(start 352.649282 -272.930874)
		(end 352.641662 -272.925286)
		(width 0.1143)
		(layer "In15.Cu")
		(net "P5E_CPU0_P0_RX_DN<8>")
	)
	(segment
		(start 352.719894 -274.59178)
		(end 352.69424 -274.577048)
		(width 0.1143)
		(layer "In15.Cu")
		(net "P5E_CPU0_P0_RX_DN<8>")
	)
	(segment
		(start 352.688906 -292.393878)
		(end 352.688144 -292.39337)
		(width 0.1143)
		(layer "In15.Cu")
		(net "P5E_CPU0_P0_RX_DN<8>")
	)
	(segment
		(start 352.691446 -276.836886)
		(end 352.692208 -276.836378)
		(width 0.1143)
		(layer "In15.Cu")
		(net "P5E_CPU0_P0_RX_DN<8>")
	)
	(segment
		(start 352.651822 -286.579564)
		(end 352.721672 -286.538924)
		(width 0.1143)
		(layer "In15.Cu")
		(net "P5E_CPU0_P0_RX_DN<8>")
	)
	(segment
		(start 352.693478 -290.776406)
		(end 352.692462 -290.775898)
		(width 0.1143)
		(layer "In15.Cu")
		(net "P5E_CPU0_P0_RX_DN<8>")
	)
	(segment
		(start 352.719894 -285.931864)
		(end 352.69424 -285.917132)
		(width 0.1143)
		(layer "In15.Cu")
		(net "P5E_CPU0_P0_RX_DN<8>")
	)
	(segment
		(start 352.689668 -276.837902)
		(end 352.69043 -276.837394)
		(width 0.1143)
		(layer "In15.Cu")
		(net "P5E_CPU0_P0_RX_DN<8>")
	)
	(segment
		(start 352.719894 -282.69184)
		(end 352.69424 -282.677108)
		(width 0.1143)
		(layer "In15.Cu")
		(net "P5E_CPU0_P0_RX_DN<8>")
	)
	(segment
		(start 338.56676 -366.102392)
		(end 338.56676 -365.297212)
		(width 0.14224)
		(layer "In15.Cu")
		(net "P5E_CPU0_P0_RX_DN<8>")
	)
	(segment
		(start 313.86653 -393.716764)
		(end 313.86653 -393.545822)
		(width 0.14224)
		(layer "In15.Cu")
		(net "P5E_CPU0_P0_RX_DN<8>")
	)
	(segment
		(start 352.69424 -285.917132)
		(end 352.692716 -285.916116)
		(width 0.1143)
		(layer "In15.Cu")
		(net "P5E_CPU0_P0_RX_DN<8>")
	)
	(segment
		(start 352.649282 -276.170898)
		(end 352.621342 -276.150832)
		(width 0.1143)
		(layer "In15.Cu")
		(net "P5E_CPU0_P0_RX_DN<8>")
	)
	(segment
		(start 338.8741 -366.409732)
		(end 338.56676 -366.102392)
		(width 0.14224)
		(layer "In15.Cu")
		(net "P5E_CPU0_P0_RX_DN<8>")
	)
	(segment
		(start 352.691446 -294.656764)
		(end 352.692208 -294.656256)
		(width 0.1143)
		(layer "In15.Cu")
		(net "P5E_CPU0_P0_RX_DN<8>")
	)
	(segment
		(start 352.649282 -275.241258)
		(end 352.689668 -275.21789)
		(width 0.1143)
		(layer "In15.Cu")
		(net "P5E_CPU0_P0_RX_DN<8>")
	)
	(segment
		(start 352.709988 -289.785806)
		(end 352.719894 -289.780218)
		(width 0.1143)
		(layer "In15.Cu")
		(net "P5E_CPU0_P0_RX_DN<8>")
	)
	(segment
		(start 352.719894 -290.791646)
		(end 352.696272 -290.77793)
		(width 0.1143)
		(layer "In15.Cu")
		(net "P5E_CPU0_P0_RX_DN<8>")
	)
	(segment
		(start 352.248724 -270.541242)
		(end 352.179128 -270.500602)
		(width 0.1143)
		(layer "In15.Cu")
		(net "P5E_CPU0_P0_RX_DN<8>")
	)
	(segment
		(start 334.27416 -367.265712)
		(end 334.76438 -367.265712)
		(width 0.14224)
		(layer "In15.Cu")
		(net "P5E_CPU0_P0_RX_DN<8>")
	)
	(segment
		(start 352.105722 -295.699942)
		(end 352.348292 -295.457372)
		(width 0.1143)
		(layer "In15.Cu")
		(net "P5E_CPU0_P0_RX_DN<8>")
	)
	(segment
		(start 352.688144 -294.013382)
		(end 352.68789 -294.013382)
		(width 0.1143)
		(layer "In15.Cu")
		(net "P5E_CPU0_P0_RX_DN<8>")
	)
	(segment
		(start 313.188858 -378.448316)
		(end 313.064652 -378.32411)
		(width 0.14224)
		(layer "In15.Cu")
		(net "P5E_CPU0_P0_RX_DN<8>")
	)
	(segment
		(start 335.32826 -367.128552)
		(end 335.46542 -367.265712)
		(width 0.14224)
		(layer "In15.Cu")
		(net "P5E_CPU0_P0_RX_DN<8>")
	)
	(segment
		(start 352.688144 -285.913576)
		(end 352.651822 -285.892494)
		(width 0.1143)
		(layer "In15.Cu")
		(net "P5E_CPU0_P0_RX_DN<8>")
	)
	(segment
		(start 313.744356 -393.787376)
		(end 313.744864 -393.786868)
		(width 0.14224)
		(layer "In15.Cu")
		(net "P5E_CPU0_P0_RX_DN<8>")
	)
	(segment
		(start 352.688144 -288.178494)
		(end 352.721672 -288.158936)
		(width 0.1143)
		(layer "In15.Cu")
		(net "P5E_CPU0_P0_RX_DN<8>")
	)
	(segment
		(start 352.692716 -276.196044)
		(end 352.690176 -276.194774)
		(width 0.1143)
		(layer "In15.Cu")
		(net "P5E_CPU0_P0_RX_DN<8>")
	)
	(segment
		(start 352.688144 -290.773358)
		(end 352.68789 -290.773358)
		(width 0.1143)
		(layer "In15.Cu")
		(net "P5E_CPU0_P0_RX_DN<8>")
	)
	(segment
		(start 352.688906 -285.914084)
		(end 352.688144 -285.913576)
		(width 0.1143)
		(layer "In15.Cu")
		(net "P5E_CPU0_P0_RX_DN<8>")
	)
	(segment
		(start 352.719894 -276.211792)
		(end 352.69424 -276.19706)
		(width 0.1143)
		(layer "In15.Cu")
		(net "P5E_CPU0_P0_RX_DN<8>")
	)
	(segment
		(start 338.56676 -365.297212)
		(end 338.8741 -364.989872)
		(width 0.14224)
		(layer "In15.Cu")
		(net "P5E_CPU0_P0_RX_DN<8>")
	)
	(segment
		(start 352.688144 -273.59864)
		(end 352.719894 -273.580352)
		(width 0.1143)
		(layer "In15.Cu")
		(net "P5E_CPU0_P0_RX_DN<8>")
	)
	(segment
		(start 352.69678 -281.693874)
		(end 352.719894 -281.680412)
		(width 0.1143)
		(layer "In15.Cu")
		(net "P5E_CPU0_P0_RX_DN<8>")
	)
	(segment
		(start 352.69043 -275.217382)
		(end 352.691446 -275.216874)
		(width 0.1143)
		(layer "In15.Cu")
		(net "P5E_CPU0_P0_RX_DN<8>")
	)
	(segment
		(start 352.687128 -271.33296)
		(end 352.649028 -271.310608)
		(width 0.1143)
		(layer "In15.Cu")
		(net "P5E_CPU0_P0_RX_DN<8>")
	)
	(segment
		(start 352.644202 -272.004028)
		(end 352.689668 -271.977866)
		(width 0.1143)
		(layer "In15.Cu")
		(net "P5E_CPU0_P0_RX_DN<8>")
	)
	(segment
		(start 352.688144 -274.573492)
		(end 352.651822 -274.55241)
		(width 0.1143)
		(layer "In15.Cu")
		(net "P5E_CPU0_P0_RX_DN<8>")
	)
	(segment
		(start 352.695002 -278.454866)
		(end 352.695764 -278.454358)
		(width 0.1143)
		(layer "In15.Cu")
		(net "P5E_CPU0_P0_RX_DN<8>")
	)
	(segment
		(start 352.621596 -280.121106)
		(end 352.64852 -280.101548)
		(width 0.1143)
		(layer "In15.Cu")
		(net "P5E_CPU0_P0_RX_DN<8>")
	)
	(segment
		(start 352.695256 -294.017446)
		(end 352.69424 -294.016938)
		(width 0.1143)
		(layer "In15.Cu")
		(net "P5E_CPU0_P0_RX_DN<8>")
	)
	(segment
		(start 352.688906 -271.333976)
		(end 352.688144 -271.333468)
		(width 0.1143)
		(layer "In15.Cu")
		(net "P5E_CPU0_P0_RX_DN<8>")
	)
	(segment
		(start 352.69678 -271.973802)
		(end 352.719894 -271.96034)
		(width 0.1143)
		(layer "In15.Cu")
		(net "P5E_CPU0_P0_RX_DN<8>")
	)
	(segment
		(start 316.7888 -374.803416)
		(end 316.912752 -374.679464)
		(width 0.14224)
		(layer "In15.Cu")
		(net "P5E_CPU0_P0_RX_DN<8>")
	)
	(segment
		(start 352.688144 -289.798506)
		(end 352.709226 -289.786314)
		(width 0.1143)
		(layer "In15.Cu")
		(net "P5E_CPU0_P0_RX_DN<8>")
	)
	(segment
		(start 352.692208 -275.216366)
		(end 352.694748 -275.215096)
		(width 0.1143)
		(layer "In15.Cu")
		(net "P5E_CPU0_P0_RX_DN<8>")
	)
	(segment
		(start 352.689668 -275.21789)
		(end 352.69043 -275.217382)
		(width 0.1143)
		(layer "In15.Cu")
		(net "P5E_CPU0_P0_RX_DN<8>")
	)
	(segment
		(start 352.719894 -292.411658)
		(end 352.69678 -292.39845)
		(width 0.1143)
		(layer "In15.Cu")
		(net "P5E_CPU0_P0_RX_DN<8>")
	)
	(segment
		(start 352.719894 -289.171634)
		(end 352.67519 -289.145726)
		(width 0.1143)
		(layer "In15.Cu")
		(net "P5E_CPU0_P0_RX_DN<8>")
	)
	(segment
		(start 352.653346 -287.510728)
		(end 352.532696 -287.389824)
		(width 0.1143)
		(layer "In15.Cu")
		(net "P5E_CPU0_P0_RX_DN<8>")
	)
	(segment
		(start 392.483594 -364.576868)
		(end 392.483594 -355.585522)
		(width 0.14224)
		(layer "In15.Cu")
		(net "P5E_CPU0_P0_RX_DN<8>")
	)
	(segment
		(start 352.638614 -272.923)
		(end 352.63709 -272.921984)
		(width 0.1143)
		(layer "In15.Cu")
		(net "P5E_CPU0_P0_RX_DN<8>")
	)
	(segment
		(start 352.649282 -284.270958)
		(end 352.621342 -284.250892)
		(width 0.1143)
		(layer "In15.Cu")
		(net "P5E_CPU0_P0_RX_DN<8>")
	)
	(segment
		(start 352.693224 -281.695906)
		(end 352.693986 -281.695398)
		(width 0.1143)
		(layer "In15.Cu")
		(net "P5E_CPU0_P0_RX_DN<8>")
	)
	(segment
		(start 352.641662 -272.925286)
		(end 352.640392 -272.92427)
		(width 0.1143)
		(layer "In15.Cu")
		(net "P5E_CPU0_P0_RX_DN<8>")
	)
	(segment
		(start 352.688144 -287.533588)
		(end 352.653346 -287.510728)
		(width 0.1143)
		(layer "In15.Cu")
		(net "P5E_CPU0_P0_RX_DN<8>")
	)
	(segment
		(start 352.719894 -281.071828)
		(end 352.688144 -281.05354)
		(width 0.1143)
		(layer "In15.Cu")
		(net "P5E_CPU0_P0_RX_DN<8>")
	)
	(segment
		(start 352.692716 -282.676092)
		(end 352.690176 -282.674822)
		(width 0.1143)
		(layer "In15.Cu")
		(net "P5E_CPU0_P0_RX_DN<8>")
	)
	(segment
		(start 352.6917 -290.77539)
		(end 352.690684 -290.774882)
		(width 0.1143)
		(layer "In15.Cu")
		(net "P5E_CPU0_P0_RX_DN<8>")
	)
	(segment
		(start 352.649282 -283.341318)
		(end 352.689668 -283.31795)
		(width 0.1143)
		(layer "In15.Cu")
		(net "P5E_CPU0_P0_RX_DN<8>")
	)
	(segment
		(start 352.693986 -276.835362)
		(end 352.719894 -276.820376)
		(width 0.1143)
		(layer "In15.Cu")
		(net "P5E_CPU0_P0_RX_DN<8>")
	)
	(segment
		(start 314.621926 -382.329944)
		(end 314.621926 -379.573282)
		(width 0.14224)
		(layer "In15.Cu")
		(net "P5E_CPU0_P0_RX_DN<8>")
	)
	(segment
		(start 352.690684 -292.394894)
		(end 352.689922 -292.394386)
		(width 0.1143)
		(layer "In15.Cu")
		(net "P5E_CPU0_P0_RX_DN<8>")
	)
	(segment
		(start 352.621342 -281.741372)
		(end 352.649282 -281.721306)
		(width 0.1143)
		(layer "In15.Cu")
		(net "P5E_CPU0_P0_RX_DN<8>")
	)
	(segment
		(start 365.719106 -328.408538)
		(end 352.158808 -305.1302)
		(width 0.14224)
		(layer "In15.Cu")
		(net "P5E_CPU0_P0_RX_DN<8>")
	)
	(segment
		(start 352.69043 -276.837394)
		(end 352.691446 -276.836886)
		(width 0.1143)
		(layer "In15.Cu")
		(net "P5E_CPU0_P0_RX_DN<8>")
	)
	(segment
		(start 352.691446 -275.216874)
		(end 352.692208 -275.216366)
		(width 0.1143)
		(layer "In15.Cu")
		(net "P5E_CPU0_P0_RX_DN<8>")
	)
	(segment
		(start 352.692716 -279.436068)
		(end 352.690176 -279.434798)
		(width 0.1143)
		(layer "In15.Cu")
		(net "P5E_CPU0_P0_RX_DN<8>")
	)
	(segment
		(start 352.693478 -292.396418)
		(end 352.692462 -292.39591)
		(width 0.1143)
		(layer "In15.Cu")
		(net "P5E_CPU0_P0_RX_DN<8>")
	)
	(segment
		(start 352.690176 -284.294834)
		(end 352.688906 -284.294072)
		(width 0.1143)
		(layer "In15.Cu")
		(net "P5E_CPU0_P0_RX_DN<8>")
	)
	(segment
		(start 351.966784 -296.374566)
		(end 351.966784 -296.346118)
		(width 0.1143)
		(layer "In15.Cu")
		(net "P5E_CPU0_P0_RX_DN<8>")
	)
	(segment
		(start 352.619564 -272.021808)
		(end 352.644202 -272.004028)
		(width 0.1143)
		(layer "In15.Cu")
		(net "P5E_CPU0_P0_RX_DN<8>")
	)
	(segment
		(start 313.744864 -393.786868)
		(end 313.86653 -393.716764)
		(width 0.14224)
		(layer "In15.Cu")
		(net "P5E_CPU0_P0_RX_DN<8>")
	)
	(segment
		(start 332.9432 -367.128552)
		(end 333.08036 -367.265712)
		(width 0.14224)
		(layer "In15.Cu")
		(net "P5E_CPU0_P0_RX_DN<8>")
	)
	(segment
		(start 352.688144 -292.39337)
		(end 352.68789 -292.39337)
		(width 0.1143)
		(layer "In15.Cu")
		(net "P5E_CPU0_P0_RX_DN<8>")
	)
	(segment
		(start 352.688144 -272.95348)
		(end 352.68535 -272.951702)
		(width 0.1143)
		(layer "In15.Cu")
		(net "P5E_CPU0_P0_RX_DN<8>")
	)
	(segment
		(start 352.688144 -293.03853)
		(end 352.709226 -293.026338)
		(width 0.1143)
		(layer "In15.Cu")
		(net "P5E_CPU0_P0_RX_DN<8>")
	)
	(segment
		(start 352.69424 -272.957036)
		(end 352.692716 -272.95602)
		(width 0.1143)
		(layer "In15.Cu")
		(net "P5E_CPU0_P0_RX_DN<8>")
	)
	(segment
		(start 317.587376 -374.228868)
		(end 322.43649 -372.220236)
		(width 0.14224)
		(layer "In15.Cu")
		(net "P5E_CPU0_P0_RX_DN<8>")
	)
	(segment
		(start 352.690176 -274.574762)
		(end 352.688906 -274.574)
		(width 0.1143)
		(layer "In15.Cu")
		(net "P5E_CPU0_P0_RX_DN<8>")
	)
	(segment
		(start 352.695002 -281.69489)
		(end 352.695764 -281.694382)
		(width 0.1143)
		(layer "In15.Cu")
		(net "P5E_CPU0_P0_RX_DN<8>")
	)
	(segment
		(start 352.693986 -278.455374)
		(end 352.695002 -278.454866)
		(width 0.1143)
		(layer "In15.Cu")
		(net "P5E_CPU0_P0_RX_DN<8>")
	)
	(segment
		(start 352.012504 -296.300398)
		(end 352.012504 -295.924732)
		(width 0.1143)
		(layer "In15.Cu")
		(net "P5E_CPU0_P0_RX_DN<8>")
	)
	(segment
		(start 352.690176 -276.194774)
		(end 352.688906 -276.194012)
		(width 0.1143)
		(layer "In15.Cu")
		(net "P5E_CPU0_P0_RX_DN<8>")
	)
	(segment
		(start 314.545726 -379.389386)
		(end 313.98591 -378.82957)
		(width 0.14224)
		(layer "In15.Cu")
		(net "P5E_CPU0_P0_RX_DN<8>")
	)
	(segment
		(start 352.689668 -271.977866)
		(end 352.69043 -271.977358)
		(width 0.1143)
		(layer "In15.Cu")
		(net "P5E_CPU0_P0_RX_DN<8>")
	)
	(segment
		(start 352.689922 -290.774374)
		(end 352.688906 -290.773866)
		(width 0.1143)
		(layer "In15.Cu")
		(net "P5E_CPU0_P0_RX_DN<8>")
	)
	(segment
		(start 352.689922 -294.014398)
		(end 352.688906 -294.01389)
		(width 0.1143)
		(layer "In15.Cu")
		(net "P5E_CPU0_P0_RX_DN<8>")
	)
	(segment
		(start 332.51648 -367.128552)
		(end 332.9432 -367.128552)
		(width 0.14224)
		(layer "In15.Cu")
		(net "P5E_CPU0_P0_RX_DN<8>")
	)
	(segment
		(start 352.67519 -288.186114)
		(end 352.688144 -288.178494)
		(width 0.1143)
		(layer "In15.Cu")
		(net "P5E_CPU0_P0_RX_DN<8>")
	)
	(segment
		(start 352.640392 -272.92427)
		(end 352.63963 -272.923762)
		(width 0.1143)
		(layer "In15.Cu")
		(net "P5E_CPU0_P0_RX_DN<8>")
	)
	(segment
		(start 352.692208 -271.976342)
		(end 352.693224 -271.975834)
		(width 0.1143)
		(layer "In15.Cu")
		(net "P5E_CPU0_P0_RX_DN<8>")
	)
	(segment
		(start 352.689668 -281.697938)
		(end 352.69043 -281.69743)
		(width 0.1143)
		(layer "In15.Cu")
		(net "P5E_CPU0_P0_RX_DN<8>")
	)
	(segment
		(start 352.649282 -278.481282)
		(end 352.689668 -278.457914)
		(width 0.1143)
		(layer "In15.Cu")
		(net "P5E_CPU0_P0_RX_DN<8>")
	)
	(segment
		(start 352.693986 -283.31541)
		(end 352.695002 -283.314902)
		(width 0.1143)
		(layer "In15.Cu")
		(net "P5E_CPU0_P0_RX_DN<8>")
	)
	(segment
		(start 391.861294 -354.10521)
		(end 366.023398 -328.79919)
		(width 0.14224)
		(layer "In15.Cu")
		(net "P5E_CPU0_P0_RX_DN<8>")
	)
	(segment
		(start 352.692208 -283.316426)
		(end 352.693224 -283.315918)
		(width 0.1143)
		(layer "In15.Cu")
		(net "P5E_CPU0_P0_RX_DN<8>")
	)
	(segment
		(start 352.64852 -280.101548)
		(end 352.719894 -280.0604)
		(width 0.1143)
		(layer "In15.Cu")
		(net "P5E_CPU0_P0_RX_DN<8>")
	)
	(segment
		(start 352.688144 -281.05354)
		(end 352.688144 -281.053286)
		(width 0.1143)
		(layer "In15.Cu")
		(net "P5E_CPU0_P0_RX_DN<8>")
	)
	(segment
		(start 352.690684 -294.014906)
		(end 352.689922 -294.014398)
		(width 0.1143)
		(layer "In15.Cu")
		(net "P5E_CPU0_P0_RX_DN<8>")
	)
	(segment
		(start 352.69043 -278.457406)
		(end 352.691446 -278.456898)
		(width 0.1143)
		(layer "In15.Cu")
		(net "P5E_CPU0_P0_RX_DN<8>")
	)
	(segment
		(start 313.554364 -392.616944)
		(end 313.858402 -392.31316)
		(width 0.14224)
		(layer "In15.Cu")
		(net "P5E_CPU0_P0_RX_DN<8>")
	)
	(segment
		(start 352.689668 -294.65778)
		(end 352.69043 -294.657272)
		(width 0.1143)
		(layer "In15.Cu")
		(net "P5E_CPU0_P0_RX_DN<8>")
	)
	(segment
		(start 352.688906 -294.01389)
		(end 352.688144 -294.013382)
		(width 0.1143)
		(layer "In15.Cu")
		(net "P5E_CPU0_P0_RX_DN<8>")
	)
	(segment
		(start 352.649282 -282.650946)
		(end 352.621342 -282.63088)
		(width 0.1143)
		(layer "In15.Cu")
		(net "P5E_CPU0_P0_RX_DN<8>")
	)
	(segment
		(start 334.76438 -367.265712)
		(end 334.90154 -367.128552)
		(width 0.14224)
		(layer "In15.Cu")
		(net "P5E_CPU0_P0_RX_DN<8>")
	)
	(segment
		(start 352.68535 -282.671774)
		(end 352.649282 -282.650946)
		(width 0.1143)
		(layer "In15.Cu")
		(net "P5E_CPU0_P0_RX_DN<8>")
	)
	(segment
		(start 352.693224 -271.975834)
		(end 352.693986 -271.975326)
		(width 0.1143)
		(layer "In15.Cu")
		(net "P5E_CPU0_P0_RX_DN<8>")
	)
	(segment
		(start 352.695002 -283.314902)
		(end 352.695764 -283.314394)
		(width 0.1143)
		(layer "In15.Cu")
		(net "P5E_CPU0_P0_RX_DN<8>")
	)
	(segment
		(start 352.693986 -281.695398)
		(end 352.695002 -281.69489)
		(width 0.1143)
		(layer "In15.Cu")
		(net "P5E_CPU0_P0_RX_DN<8>")
	)
	(segment
		(start 352.695764 -278.454358)
		(end 352.69678 -278.45385)
		(width 0.1143)
		(layer "In15.Cu")
		(net "P5E_CPU0_P0_RX_DN<8>")
	)
	(segment
		(start 352.692462 -290.775898)
		(end 352.6917 -290.77539)
		(width 0.1143)
		(layer "In15.Cu")
		(net "P5E_CPU0_P0_RX_DN<8>")
	)
	(segment
		(start 352.688906 -272.953988)
		(end 352.688144 -272.95348)
		(width 0.1143)
		(layer "In15.Cu")
		(net "P5E_CPU0_P0_RX_DN<8>")
	)
	(segment
		(start 333.57312 -367.265712)
		(end 333.71028 -367.128552)
		(width 0.14224)
		(layer "In15.Cu")
		(net "P5E_CPU0_P0_RX_DN<8>")
	)
	(segment
		(start 351.941892 -270.11884)
		(end 351.859088 -270.036036)
		(width 0.1143)
		(layer "In15.Cu")
		(net "P5E_CPU0_P0_RX_DN<8>")
	)
	(segment
		(start 352.688144 -277.813516)
		(end 352.68535 -277.811738)
		(width 0.1143)
		(layer "In15.Cu")
		(net "P5E_CPU0_P0_RX_DN<8>")
	)
	(segment
		(start 352.692716 -272.95602)
		(end 352.690176 -272.95475)
		(width 0.1143)
		(layer "In15.Cu")
		(net "P5E_CPU0_P0_RX_DN<8>")
	)
	(segment
		(start 352.692208 -294.656256)
		(end 352.694748 -294.654986)
		(width 0.1143)
		(layer "In15.Cu")
		(net "P5E_CPU0_P0_RX_DN<8>")
	)
	(segment
		(start 352.719894 -272.971768)
		(end 352.69424 -272.957036)
		(width 0.1143)
		(layer "In15.Cu")
		(net "P5E_CPU0_P0_RX_DN<8>")
	)
	(segment
		(start 322.742052 -372.15953)
		(end 326.160384 -372.15953)
		(width 0.14224)
		(layer "In15.Cu")
		(net "P5E_CPU0_P0_RX_DN<8>")
	)
	(segment
		(start 352.695764 -283.314394)
		(end 352.69678 -283.313886)
		(width 0.1143)
		(layer "In15.Cu")
		(net "P5E_CPU0_P0_RX_DN<8>")
	)
	(segment
		(start 352.68535 -272.951702)
		(end 352.649282 -272.930874)
		(width 0.1143)
		(layer "In15.Cu")
		(net "P5E_CPU0_P0_RX_DN<8>")
	)
	(segment
		(start 352.688144 -279.433528)
		(end 352.68535 -279.43175)
		(width 0.1143)
		(layer "In15.Cu")
		(net "P5E_CPU0_P0_RX_DN<8>")
	)
	(segment
		(start 352.689668 -283.31795)
		(end 352.69043 -283.317442)
		(width 0.1143)
		(layer "In15.Cu")
		(net "P5E_CPU0_P0_RX_DN<8>")
	)
	(segment
		(start 352.69043 -281.69743)
		(end 352.691446 -281.696922)
		(width 0.1143)
		(layer "In15.Cu")
		(net "P5E_CPU0_P0_RX_DN<8>")
	)
	(segment
		(start 352.688906 -277.814024)
		(end 352.688144 -277.813516)
		(width 0.1143)
		(layer "In15.Cu")
		(net "P5E_CPU0_P0_RX_DN<8>")
	)
	(segment
		(start 352.68789 -291.418772)
		(end 352.688144 -291.418518)
		(width 0.1143)
		(layer "In15.Cu")
		(net "P5E_CPU0_P0_RX_DN<8>")
	)
	(segment
		(start 352.69424 -277.817072)
		(end 352.692716 -277.816056)
		(width 0.1143)
		(layer "In15.Cu")
		(net "P5E_CPU0_P0_RX_DN<8>")
	)
	(segment
		(start 352.697542 -294.018716)
		(end 352.695256 -294.017446)
		(width 0.1143)
		(layer "In15.Cu")
		(net "P5E_CPU0_P0_RX_DN<8>")
	)
	(segment
		(start 352.693224 -276.83587)
		(end 352.693986 -276.835362)
		(width 0.1143)
		(layer "In15.Cu")
		(net "P5E_CPU0_P0_RX_DN<8>")
	)
	(segment
		(start 352.719894 -284.311852)
		(end 352.69424 -284.29712)
		(width 0.1143)
		(layer "In15.Cu")
		(net "P5E_CPU0_P0_RX_DN<8>")
	)
	(segment
		(start 344.430604 -366.409732)
		(end 338.8741 -366.409732)
		(width 0.14224)
		(layer "In15.Cu")
		(net "P5E_CPU0_P0_RX_DN<8>")
	)
	(segment
		(start 352.693224 -283.315918)
		(end 352.693986 -283.31541)
		(width 0.1143)
		(layer "In15.Cu")
		(net "P5E_CPU0_P0_RX_DN<8>")
	)
	(segment
		(start 352.692462 -292.39591)
		(end 352.6917 -292.395402)
		(width 0.1143)
		(layer "In15.Cu")
		(net "P5E_CPU0_P0_RX_DN<8>")
	)
	(segment
		(start 352.651822 -284.959806)
		(end 352.688144 -284.938724)
		(width 0.1143)
		(layer "In15.Cu")
		(net "P5E_CPU0_P0_RX_DN<8>")
	)
	(segment
		(start 334.90154 -367.128552)
		(end 335.32826 -367.128552)
		(width 0.14224)
		(layer "In15.Cu")
		(net "P5E_CPU0_P0_RX_DN<8>")
	)
	(segment
		(start 352.689668 -278.457914)
		(end 352.69043 -278.457406)
		(width 0.1143)
		(layer "In15.Cu")
		(net "P5E_CPU0_P0_RX_DN<8>")
	)
	(segment
		(start 352.68535 -277.811738)
		(end 352.649282 -277.79091)
		(width 0.1143)
		(layer "In15.Cu")
		(net "P5E_CPU0_P0_RX_DN<8>")
	)
	(segment
		(start 313.98591 -378.82957)
		(end 313.384438 -378.579634)
		(width 0.14224)
		(layer "In15.Cu")
		(net "P5E_CPU0_P0_RX_DN<8>")
	)
	(segment
		(start 352.692208 -281.696414)
		(end 352.693224 -281.695906)
		(width 0.1143)
		(layer "In15.Cu")
		(net "P5E_CPU0_P0_RX_DN<8>")
	)
	(segment
		(start 352.688906 -282.67406)
		(end 352.688144 -282.673552)
		(width 0.1143)
		(layer "In15.Cu")
		(net "P5E_CPU0_P0_RX_DN<8>")
	)
	(segment
		(start 313.86653 -393.545822)
		(end 313.549538 -393.22883)
		(width 0.14224)
		(layer "In15.Cu")
		(net "P5E_CPU0_P0_RX_DN<8>")
	)
	(segment
		(start 344.572844 -366.551972)
		(end 344.430604 -366.409732)
		(width 0.14224)
		(layer "In15.Cu")
		(net "P5E_CPU0_P0_RX_DN<8>")
	)
	(segment
		(start 313.391042 -393.69238)
		(end 313.744356 -393.787376)
		(width 0.14224)
		(layer "In15.Cu")
		(net "P5E_CPU0_P0_RX_DN<8>")
	)
	(segment
		(start 352.69424 -284.29712)
		(end 352.692716 -284.296104)
		(width 0.1143)
		(layer "In15.Cu")
		(net "P5E_CPU0_P0_RX_DN<8>")
	)
	(segment
		(start 352.685096 -294.66032)
		(end 352.68789 -294.658796)
		(width 0.1143)
		(layer "In15.Cu")
		(net "P5E_CPU0_P0_RX_DN<8>")
	)
	(segment
		(start 333.08036 -367.265712)
		(end 333.57312 -367.265712)
		(width 0.14224)
		(layer "In15.Cu")
		(net "P5E_CPU0_P0_RX_DN<8>")
	)
	(segment
		(start 352.651822 -273.619722)
		(end 352.688144 -273.59864)
		(width 0.1143)
		(layer "In15.Cu")
		(net "P5E_CPU0_P0_RX_DN<8>")
	)
	(segment
		(start 352.69424 -274.577048)
		(end 352.692716 -274.576032)
		(width 0.1143)
		(layer "In15.Cu")
		(net "P5E_CPU0_P0_RX_DN<8>")
	)
	(segment
		(start 352.69551 -275.214588)
		(end 352.719894 -275.200364)
		(width 0.1143)
		(layer "In15.Cu")
		(net "P5E_CPU0_P0_RX_DN<8>")
	)
	(segment
		(start 352.691446 -271.97685)
		(end 352.692208 -271.976342)
		(width 0.1143)
		(layer "In15.Cu")
		(net "P5E_CPU0_P0_RX_DN<8>")
	)
	(segment
		(start 313.561476 -376.076972)
		(end 314.203842 -375.893584)
		(width 0.14224)
		(layer "In15.Cu")
		(net "P5E_CPU0_P0_RX_DN<8>")
	)
	(segment
		(start 352.692716 -274.576032)
		(end 352.690176 -274.574762)
		(width 0.1143)
		(layer "In15.Cu")
		(net "P5E_CPU0_P0_RX_DN<8>")
	)
	(segment
		(start 352.400616 -295.331642)
		(end 352.400616 -295.151556)
		(width 0.1143)
		(layer "In15.Cu")
		(net "P5E_CPU0_P0_RX_DN<8>")
	)
	(segment
		(start 332.37932 -367.265712)
		(end 332.51648 -367.128552)
		(width 0.14224)
		(layer "In15.Cu")
		(net "P5E_CPU0_P0_RX_DN<8>")
	)
	(segment
		(start 352.69551 -294.654478)
		(end 352.719894 -294.640254)
		(width 0.1143)
		(layer "In15.Cu")
		(net "P5E_CPU0_P0_RX_DN<8>")
	)
	(segment
		(start 313.549538 -393.22883)
		(end 313.554364 -392.616944)
		(width 0.14224)
		(layer "In15.Cu")
		(net "P5E_CPU0_P0_RX_DN<8>")
	)
	(segment
		(start 352.690176 -277.814786)
		(end 352.688906 -277.814024)
		(width 0.1143)
		(layer "In15.Cu")
		(net "P5E_CPU0_P0_RX_DN<8>")
	)
	(arc
		(start 313.331606 -376.212354)
		(mid 313.4379 -376.129984)
		(end 313.561476 -376.076972)
		(width 0.14224)
		(layer "In15.Cu")
		(net "P5E_CPU0_P0_RX_DN<8>")
	)
	(arc
		(start 352.719894 -294.640254)
		(mid 352.875822 -294.335962)
		(end 352.719894 -294.03167)
		(width 0.1143)
		(layer "In15.Cu")
		(net "P5E_CPU0_P0_RX_DN<8>")
	)
	(arc
		(start 352.719894 -283.300424)
		(mid 352.875822 -282.996132)
		(end 352.719894 -282.69184)
		(width 0.1143)
		(layer "In15.Cu")
		(net "P5E_CPU0_P0_RX_DN<8>")
	)
	(arc
		(start 352.651822 -274.55241)
		(mid 352.644158 -274.547139)
		(end 352.636582 -274.541742)
		(width 0.1143)
		(layer "In15.Cu")
		(net "P5E_CPU0_P0_RX_DN<8>")
	)
	(arc
		(start 352.721672 -288.158936)
		(mid 352.835079 -288.026047)
		(end 352.87585 -287.856168)
		(width 0.1143)
		(layer "In15.Cu")
		(net "P5E_CPU0_P0_RX_DN<8>")
	)
	(arc
		(start 352.408744 -286.989774)
		(mid 352.48491 -286.757785)
		(end 352.651822 -286.579564)
		(width 0.1143)
		(layer "In15.Cu")
		(net "P5E_CPU0_P0_RX_DN<8>")
	)
	(arc
		(start 352.651822 -285.892494)
		(mid 352.644158 -285.887223)
		(end 352.636582 -285.881826)
		(width 0.1143)
		(layer "In15.Cu")
		(net "P5E_CPU0_P0_RX_DN<8>")
	)
	(arc
		(start 366.023398 -328.79919)
		(mid 365.858139 -328.614079)
		(end 365.719106 -328.408538)
		(width 0.14224)
		(layer "In15.Cu")
		(net "P5E_CPU0_P0_RX_DN<8>")
	)
	(arc
		(start 313.384438 -378.579634)
		(mid 313.280197 -378.523581)
		(end 313.188858 -378.448316)
		(width 0.14224)
		(layer "In15.Cu")
		(net "P5E_CPU0_P0_RX_DN<8>")
	)
	(arc
		(start 352.719894 -276.820376)
		(mid 352.875822 -276.516084)
		(end 352.719894 -276.211792)
		(width 0.1143)
		(layer "In15.Cu")
		(net "P5E_CPU0_P0_RX_DN<8>")
	)
	(arc
		(start 312.934858 -376.792744)
		(mid 312.968597 -376.623127)
		(end 313.064652 -376.479308)
		(width 0.14224)
		(layer "In15.Cu")
		(net "P5E_CPU0_P0_RX_DN<8>")
	)
	(arc
		(start 316.684152 -374.873266)
		(mid 316.739934 -374.843517)
		(end 316.7888 -374.803416)
		(width 0.14224)
		(layer "In15.Cu")
		(net "P5E_CPU0_P0_RX_DN<8>")
	)
	(arc
		(start 352.719894 -291.40023)
		(mid 352.875822 -291.095938)
		(end 352.719894 -290.791646)
		(width 0.1143)
		(layer "In15.Cu")
		(net "P5E_CPU0_P0_RX_DN<8>")
	)
	(arc
		(start 331.000862 -367.3856)
		(mid 331.1337 -367.296807)
		(end 331.290422 -367.265712)
		(width 0.14224)
		(layer "In15.Cu")
		(net "P5E_CPU0_P0_RX_DN<8>")
	)
	(arc
		(start 352.636582 -284.970474)
		(mid 352.644158 -284.965078)
		(end 352.651822 -284.959806)
		(width 0.1143)
		(layer "In15.Cu")
		(net "P5E_CPU0_P0_RX_DN<8>")
	)
	(arc
		(start 352.621342 -272.910808)
		(mid 352.393037 -272.466713)
		(end 352.619564 -272.021808)
		(width 0.1143)
		(layer "In15.Cu")
		(net "P5E_CPU0_P0_RX_DN<8>")
	)
	(arc
		(start 352.719894 -273.580352)
		(mid 352.875822 -273.27606)
		(end 352.719894 -272.971768)
		(width 0.1143)
		(layer "In15.Cu")
		(net "P5E_CPU0_P0_RX_DN<8>")
	)
	(arc
		(start 352.348292 -295.457372)
		(mid 352.386973 -295.399716)
		(end 352.400616 -295.331642)
		(width 0.1143)
		(layer "In15.Cu")
		(net "P5E_CPU0_P0_RX_DN<8>")
	)
	(arc
		(start 352.719894 -289.780218)
		(mid 352.875822 -289.475926)
		(end 352.719894 -289.171634)
		(width 0.1143)
		(layer "In15.Cu")
		(net "P5E_CPU0_P0_RX_DN<8>")
	)
	(arc
		(start 352.721672 -286.538924)
		(mid 352.835079 -286.406035)
		(end 352.87585 -286.236156)
		(width 0.1143)
		(layer "In15.Cu")
		(net "P5E_CPU0_P0_RX_DN<8>")
	)
	(arc
		(start 352.87585 -286.236156)
		(mid 352.834595 -286.065185)
		(end 352.719894 -285.931864)
		(width 0.1143)
		(layer "In15.Cu")
		(net "P5E_CPU0_P0_RX_DN<8>")
	)
	(arc
		(start 352.158808 -305.1302)
		(mid 352.015544 -304.786701)
		(end 351.966784 -304.41773)
		(width 0.14224)
		(layer "In15.Cu")
		(net "P5E_CPU0_P0_RX_DN<8>")
	)
	(arc
		(start 313.064652 -378.32411)
		(mid 312.968516 -378.180187)
		(end 312.934858 -378.01042)
		(width 0.14224)
		(layer "In15.Cu")
		(net "P5E_CPU0_P0_RX_DN<8>")
	)
	(arc
		(start 352.636582 -285.881826)
		(mid 352.411411 -285.42615)
		(end 352.636582 -284.970474)
		(width 0.1143)
		(layer "In15.Cu")
		(net "P5E_CPU0_P0_RX_DN<8>")
	)
	(arc
		(start 352.649028 -271.310608)
		(mid 352.470215 -271.108258)
		(end 352.405696 -270.846042)
		(width 0.1143)
		(layer "In15.Cu")
		(net "P5E_CPU0_P0_RX_DN<8>")
	)
	(arc
		(start 352.636582 -273.63039)
		(mid 352.644158 -273.624994)
		(end 352.651822 -273.619722)
		(width 0.1143)
		(layer "In15.Cu")
		(net "P5E_CPU0_P0_RX_DN<8>")
	)
	(arc
		(start 352.532696 -287.389824)
		(mid 352.440944 -287.252414)
		(end 352.408744 -287.090358)
		(width 0.1143)
		(layer "In15.Cu")
		(net "P5E_CPU0_P0_RX_DN<8>")
	)
	(arc
		(start 314.621926 -379.573282)
		(mid 314.602127 -379.473748)
		(end 314.545726 -379.389386)
		(width 0.14224)
		(layer "In15.Cu")
		(net "P5E_CPU0_P0_RX_DN<8>")
	)
	(arc
		(start 352.621342 -277.770844)
		(mid 352.393342 -277.32609)
		(end 352.621342 -276.881336)
		(width 0.1143)
		(layer "In15.Cu")
		(net "P5E_CPU0_P0_RX_DN<8>")
	)
	(arc
		(start 352.67519 -289.145726)
		(mid 352.398857 -288.66592)
		(end 352.67519 -288.186114)
		(width 0.1143)
		(layer "In15.Cu")
		(net "P5E_CPU0_P0_RX_DN<8>")
	)
	(arc
		(start 352.012504 -295.924732)
		(mid 352.036794 -295.803089)
		(end 352.105722 -295.699942)
		(width 0.1143)
		(layer "In15.Cu")
		(net "P5E_CPU0_P0_RX_DN<8>")
	)
	(arc
		(start 352.400616 -295.151556)
		(mid 352.476737 -294.867635)
		(end 352.685096 -294.66032)
		(width 0.1143)
		(layer "In15.Cu")
		(net "P5E_CPU0_P0_RX_DN<8>")
	)
	(arc
		(start 352.179128 -270.500602)
		(mid 352.027141 -270.344094)
		(end 351.945702 -270.1417)
		(width 0.1143)
		(layer "In15.Cu")
		(net "P5E_CPU0_P0_RX_DN<8>")
	)
	(arc
		(start 352.68789 -294.013382)
		(mid 352.407463 -293.526146)
		(end 352.68789 -293.038784)
		(width 0.1143)
		(layer "In15.Cu")
		(net "P5E_CPU0_P0_RX_DN<8>")
	)
	(arc
		(start 352.87585 -287.856168)
		(mid 352.834595 -287.685197)
		(end 352.719894 -287.551876)
		(width 0.1143)
		(layer "In15.Cu")
		(net "P5E_CPU0_P0_RX_DN<8>")
	)
	(arc
		(start 326.160384 -372.15953)
		(mid 326.222107 -372.147253)
		(end 326.27443 -372.112286)
		(width 0.14224)
		(layer "In15.Cu")
		(net "P5E_CPU0_P0_RX_DN<8>")
	)
	(arc
		(start 352.636582 -274.541742)
		(mid 352.411411 -274.086066)
		(end 352.636582 -273.63039)
		(width 0.1143)
		(layer "In15.Cu")
		(net "P5E_CPU0_P0_RX_DN<8>")
	)
	(arc
		(start 316.912752 -374.679464)
		(mid 317.227857 -374.420921)
		(end 317.587376 -374.228868)
		(width 0.14224)
		(layer "In15.Cu")
		(net "P5E_CPU0_P0_RX_DN<8>")
	)
	(arc
		(start 391.888726 -364.989872)
		(mid 392.105374 -364.94676)
		(end 392.28903 -364.82401)
		(width 0.14224)
		(layer "In15.Cu")
		(net "P5E_CPU0_P0_RX_DN<8>")
	)
	(arc
		(start 313.858402 -386.20954)
		(mid 313.860391 -386.16947)
		(end 313.866276 -386.129784)
		(width 0.14224)
		(layer "In15.Cu")
		(net "P5E_CPU0_P0_RX_DN<8>")
	)
	(arc
		(start 322.43649 -372.220236)
		(mid 322.586281 -372.174823)
		(end 322.742052 -372.15953)
		(width 0.14224)
		(layer "In15.Cu")
		(net "P5E_CPU0_P0_RX_DN<8>")
	)
	(arc
		(start 352.68789 -290.773358)
		(mid 352.407463 -290.286122)
		(end 352.68789 -289.79876)
		(width 0.1143)
		(layer "In15.Cu")
		(net "P5E_CPU0_P0_RX_DN<8>")
	)
	(arc
		(start 352.621596 -281.011122)
		(mid 352.393918 -280.566114)
		(end 352.621596 -280.121106)
		(width 0.1143)
		(layer "In15.Cu")
		(net "P5E_CPU0_P0_RX_DN<8>")
	)
	(arc
		(start 392.446256 -364.666784)
		(mid 392.473875 -364.625544)
		(end 392.483594 -364.576868)
		(width 0.14224)
		(layer "In15.Cu")
		(net "P5E_CPU0_P0_RX_DN<8>")
	)
	(arc
		(start 352.405696 -270.846042)
		(mid 352.364147 -270.67462)
		(end 352.248724 -270.541242)
		(width 0.1143)
		(layer "In15.Cu")
		(net "P5E_CPU0_P0_RX_DN<8>")
	)
	(arc
		(start 352.719894 -278.440388)
		(mid 352.875822 -278.136096)
		(end 352.719894 -277.831804)
		(width 0.1143)
		(layer "In15.Cu")
		(net "P5E_CPU0_P0_RX_DN<8>")
	)
	(arc
		(start 352.719894 -284.920436)
		(mid 352.875822 -284.616144)
		(end 352.719894 -284.311852)
		(width 0.1143)
		(layer "In15.Cu")
		(net "P5E_CPU0_P0_RX_DN<8>")
	)
	(arc
		(start 352.719894 -271.96034)
		(mid 352.871483 -271.656048)
		(end 352.719894 -271.351756)
		(width 0.1143)
		(layer "In15.Cu")
		(net "P5E_CPU0_P0_RX_DN<8>")
	)
	(arc
		(start 351.945702 -270.1417)
		(mid 351.943679 -270.13029)
		(end 351.941892 -270.11884)
		(width 0.1143)
		(layer "In15.Cu")
		(net "P5E_CPU0_P0_RX_DN<8>")
	)
	(arc
		(start 314.203842 -375.893584)
		(mid 314.248989 -375.879369)
		(end 314.29325 -375.862596)
		(width 0.14224)
		(layer "In15.Cu")
		(net "P5E_CPU0_P0_RX_DN<8>")
	)
	(arc
		(start 352.621342 -282.63088)
		(mid 352.393342 -282.186126)
		(end 352.621342 -281.741372)
		(width 0.1143)
		(layer "In15.Cu")
		(net "P5E_CPU0_P0_RX_DN<8>")
	)
	(arc
		(start 392.483594 -355.585522)
		(mid 392.321697 -354.78262)
		(end 391.861294 -354.10521)
		(width 0.14224)
		(layer "In15.Cu")
		(net "P5E_CPU0_P0_RX_DN<8>")
	)
	(arc
		(start 352.719894 -275.200364)
		(mid 352.875822 -274.896072)
		(end 352.719894 -274.59178)
		(width 0.1143)
		(layer "In15.Cu")
		(net "P5E_CPU0_P0_RX_DN<8>")
	)
	(arc
		(start 352.719894 -293.020242)
		(mid 352.875822 -292.71595)
		(end 352.719894 -292.411658)
		(width 0.1143)
		(layer "In15.Cu")
		(net "P5E_CPU0_P0_RX_DN<8>")
	)
	(arc
		(start 352.621342 -276.150832)
		(mid 352.393342 -275.706078)
		(end 352.621342 -275.261324)
		(width 0.1143)
		(layer "In15.Cu")
		(net "P5E_CPU0_P0_RX_DN<8>")
	)
	(arc
		(start 352.621342 -279.390856)
		(mid 352.393342 -278.946102)
		(end 352.621342 -278.501348)
		(width 0.1143)
		(layer "In15.Cu")
		(net "P5E_CPU0_P0_RX_DN<8>")
	)
	(arc
		(start 352.719894 -281.680412)
		(mid 352.875822 -281.37612)
		(end 352.719894 -281.071828)
		(width 0.1143)
		(layer "In15.Cu")
		(net "P5E_CPU0_P0_RX_DN<8>")
	)
	(arc
		(start 352.621342 -284.250892)
		(mid 352.393342 -283.806138)
		(end 352.621342 -283.361384)
		(width 0.1143)
		(layer "In15.Cu")
		(net "P5E_CPU0_P0_RX_DN<8>")
	)
	(arc
		(start 352.68789 -292.39337)
		(mid 352.407463 -291.906134)
		(end 352.68789 -291.418772)
		(width 0.1143)
		(layer "In15.Cu")
		(net "P5E_CPU0_P0_RX_DN<8>")
	)
	(arc
		(start 352.719894 -280.0604)
		(mid 352.875822 -279.756108)
		(end 352.719894 -279.451816)
		(width 0.1143)
		(layer "In15.Cu")
		(net "P5E_CPU0_P0_RX_DN<8>")
	)
	(segment
		(start 352.027998 -273.010122)
		(end 351.561146 -273.27606)
		(width 0.12954)
		(layer "F.Cu")
		(net "P5E_CPU0_P0_RX_DN<7>")
	)
	(segment
		(start 311.670446 -393.69238)
		(end 312.191146 -393.69238)
		(width 0.127)
		(layer "F.Cu")
		(net "P5E_CPU0_P0_RX_DN<7>")
	)
	(segment
		(start 351.748344 -281.05354)
		(end 351.709228 -281.03068)
		(width 0.1143)
		(layer "In13.Cu")
		(net "P5E_CPU0_P0_RX_DN<7>")
	)
	(segment
		(start 389.591804 -373.378476)
		(end 364.395258 -312.550302)
		(width 0.14224)
		(layer "In13.Cu")
		(net "P5E_CPU0_P0_RX_DN<7>")
	)
	(segment
		(start 351.709228 -284.961584)
		(end 351.748344 -284.938724)
		(width 0.1143)
		(layer "In13.Cu")
		(net "P5E_CPU0_P0_RX_DN<7>")
	)
	(segment
		(start 312.191146 -393.69238)
		(end 312.544206 -393.787376)
		(width 0.14224)
		(layer "In13.Cu")
		(net "P5E_CPU0_P0_RX_DN<7>")
	)
	(segment
		(start 331.049376 -386.60705)
		(end 331.680058 -388.12978)
		(width 0.14224)
		(layer "In13.Cu")
		(net "P5E_CPU0_P0_RX_DN<7>")
	)
	(segment
		(start 351.709228 -286.581342)
		(end 351.71126 -286.579818)
		(width 0.1143)
		(layer "In13.Cu")
		(net "P5E_CPU0_P0_RX_DN<7>")
	)
	(segment
		(start 312.354214 -392.616944)
		(end 312.658252 -392.31316)
		(width 0.14224)
		(layer "In13.Cu")
		(net "P5E_CPU0_P0_RX_DN<7>")
	)
	(segment
		(start 357.763826 -386.474462)
		(end 360.234484 -386.474462)
		(width 0.14224)
		(layer "In13.Cu")
		(net "P5E_CPU0_P0_RX_DN<7>")
	)
	(segment
		(start 389.454644 -374.602502)
		(end 389.454644 -374.175782)
		(width 0.14224)
		(layer "In13.Cu")
		(net "P5E_CPU0_P0_RX_DN<7>")
	)
	(segment
		(start 360.234484 -386.474462)
		(end 360.517948 -386.357114)
		(width 0.14224)
		(layer "In13.Cu")
		(net "P5E_CPU0_P0_RX_DN<7>")
	)
	(segment
		(start 352.151696 -296.167302)
		(end 351.559114 -295.57472)
		(width 0.1143)
		(layer "In13.Cu")
		(net "P5E_CPU0_P0_RX_DN<7>")
	)
	(segment
		(start 312.544206 -393.787376)
		(end 312.544714 -393.786868)
		(width 0.14224)
		(layer "In13.Cu")
		(net "P5E_CPU0_P0_RX_DN<7>")
	)
	(segment
		(start 351.748344 -281.6987)
		(end 351.778824 -281.68092)
		(width 0.1143)
		(layer "In13.Cu")
		(net "P5E_CPU0_P0_RX_DN<7>")
	)
	(segment
		(start 390.208008 -376.287792)
		(end 389.7376 -375.817384)
		(width 0.14224)
		(layer "In13.Cu")
		(net "P5E_CPU0_P0_RX_DN<7>")
	)
	(segment
		(start 386.832094 -385.338828)
		(end 386.832094 -384.912108)
		(width 0.14224)
		(layer "In13.Cu")
		(net "P5E_CPU0_P0_RX_DN<7>")
	)
	(segment
		(start 351.709228 -291.441378)
		(end 351.748344 -291.418518)
		(width 0.1143)
		(layer "In13.Cu")
		(net "P5E_CPU0_P0_RX_DN<7>")
	)
	(segment
		(start 386.832094 -387.951472)
		(end 386.832094 -386.039868)
		(width 0.14224)
		(layer "In13.Cu")
		(net "P5E_CPU0_P0_RX_DN<7>")
	)
	(segment
		(start 351.709228 -275.241512)
		(end 351.748344 -275.218652)
		(width 0.1143)
		(layer "In13.Cu")
		(net "P5E_CPU0_P0_RX_DN<7>")
	)
	(segment
		(start 312.658252 -392.31316)
		(end 312.658252 -390.802876)
		(width 0.14224)
		(layer "In13.Cu")
		(net "P5E_CPU0_P0_RX_DN<7>")
	)
	(segment
		(start 351.748344 -289.153346)
		(end 351.709228 -289.130486)
		(width 0.1143)
		(layer "In13.Cu")
		(net "P5E_CPU0_P0_RX_DN<7>")
	)
	(segment
		(start 312.544714 -393.786868)
		(end 312.66638 -393.716764)
		(width 0.14224)
		(layer "In13.Cu")
		(net "P5E_CPU0_P0_RX_DN<7>")
	)
	(segment
		(start 386.961888 -381.50673)
		(end 387.194298 -381.27432)
		(width 0.14224)
		(layer "In13.Cu")
		(net "P5E_CPU0_P0_RX_DN<7>")
	)
	(segment
		(start 351.748344 -283.318712)
		(end 351.778824 -283.300932)
		(width 0.1143)
		(layer "In13.Cu")
		(net "P5E_CPU0_P0_RX_DN<7>")
	)
	(segment
		(start 327.352152 -386.464048)
		(end 328.464418 -386.354574)
		(width 0.14224)
		(layer "In13.Cu")
		(net "P5E_CPU0_P0_RX_DN<7>")
	)
	(segment
		(start 351.748344 -294.658542)
		(end 351.778824 -294.640762)
		(width 0.1143)
		(layer "In13.Cu")
		(net "P5E_CPU0_P0_RX_DN<7>")
	)
	(segment
		(start 390.245346 -377.744482)
		(end 390.245346 -376.377708)
		(width 0.14224)
		(layer "In13.Cu")
		(net "P5E_CPU0_P0_RX_DN<7>")
	)
	(segment
		(start 351.928938 -273.34591)
		(end 351.859088 -273.27606)
		(width 0.1143)
		(layer "In13.Cu")
		(net "P5E_CPU0_P0_RX_DN<7>")
	)
	(segment
		(start 351.859088 -273.27606)
		(end 351.561146 -273.27606)
		(width 0.1143)
		(layer "In13.Cu")
		(net "P5E_CPU0_P0_RX_DN<7>")
	)
	(segment
		(start 372.283228 -387.275324)
		(end 372.140988 -387.417564)
		(width 0.14224)
		(layer "In13.Cu")
		(net "P5E_CPU0_P0_RX_DN<7>")
	)
	(segment
		(start 351.709228 -293.06139)
		(end 351.748344 -293.03853)
		(width 0.1143)
		(layer "In13.Cu")
		(net "P5E_CPU0_P0_RX_DN<7>")
	)
	(segment
		(start 386.832094 -386.039868)
		(end 386.694934 -385.902708)
		(width 0.14224)
		(layer "In13.Cu")
		(net "P5E_CPU0_P0_RX_DN<7>")
	)
	(segment
		(start 377.096528 -386.162804)
		(end 377.096528 -386.967984)
		(width 0.14224)
		(layer "In13.Cu")
		(net "P5E_CPU0_P0_RX_DN<7>")
	)
	(segment
		(start 368.314478 -386.633466)
		(end 368.82832 -387.873748)
		(width 0.14224)
		(layer "In13.Cu")
		(net "P5E_CPU0_P0_RX_DN<7>")
	)
	(segment
		(start 351.778824 -282.691332)
		(end 351.748344 -282.673552)
		(width 0.1143)
		(layer "In13.Cu")
		(net "P5E_CPU0_P0_RX_DN<7>")
	)
	(segment
		(start 351.748344 -273.59864)
		(end 351.778824 -273.58086)
		(width 0.1143)
		(layer "In13.Cu")
		(net "P5E_CPU0_P0_RX_DN<7>")
	)
	(segment
		(start 351.709228 -294.681402)
		(end 351.748344 -294.658542)
		(width 0.1143)
		(layer "In13.Cu")
		(net "P5E_CPU0_P0_RX_DN<7>")
	)
	(segment
		(start 351.778824 -287.551368)
		(end 351.711768 -287.512252)
		(width 0.1143)
		(layer "In13.Cu")
		(net "P5E_CPU0_P0_RX_DN<7>")
	)
	(segment
		(start 355.737922 -388.161276)
		(end 357.18496 -386.714238)
		(width 0.14224)
		(layer "In13.Cu")
		(net "P5E_CPU0_P0_RX_DN<7>")
	)
	(segment
		(start 386.832094 -384.144266)
		(end 386.832094 -381.82042)
		(width 0.14224)
		(layer "In13.Cu")
		(net "P5E_CPU0_P0_RX_DN<7>")
	)
	(segment
		(start 370.721128 -386.162804)
		(end 371.028468 -385.855464)
		(width 0.14224)
		(layer "In13.Cu")
		(net "P5E_CPU0_P0_RX_DN<7>")
	)
	(segment
		(start 351.709228 -273.6215)
		(end 351.748344 -273.59864)
		(width 0.1143)
		(layer "In13.Cu")
		(net "P5E_CPU0_P0_RX_DN<7>")
	)
	(segment
		(start 386.694934 -385.902708)
		(end 386.694934 -385.475988)
		(width 0.14224)
		(layer "In13.Cu")
		(net "P5E_CPU0_P0_RX_DN<7>")
	)
	(segment
		(start 331.797406 -388.20852)
		(end 355.623876 -388.20852)
		(width 0.14224)
		(layer "In13.Cu")
		(net "P5E_CPU0_P0_RX_DN<7>")
	)
	(segment
		(start 369.213892 -388.131304)
		(end 370.52631 -388.131304)
		(width 0.14224)
		(layer "In13.Cu")
		(net "P5E_CPU0_P0_RX_DN<7>")
	)
	(segment
		(start 351.748344 -289.798506)
		(end 351.778824 -289.780726)
		(width 0.1143)
		(layer "In13.Cu")
		(net "P5E_CPU0_P0_RX_DN<7>")
	)
	(segment
		(start 376.789188 -385.855464)
		(end 377.096528 -386.162804)
		(width 0.14224)
		(layer "In13.Cu")
		(net "P5E_CPU0_P0_RX_DN<7>")
	)
	(segment
		(start 351.748344 -288.178494)
		(end 351.780856 -288.159698)
		(width 0.1143)
		(layer "In13.Cu")
		(net "P5E_CPU0_P0_RX_DN<7>")
	)
	(segment
		(start 389.591804 -374.038622)
		(end 389.591804 -373.378476)
		(width 0.14224)
		(layer "In13.Cu")
		(net "P5E_CPU0_P0_RX_DN<7>")
	)
	(segment
		(start 351.465896 -295.34993)
		(end 351.465896 -295.14546)
		(width 0.1143)
		(layer "In13.Cu")
		(net "P5E_CPU0_P0_RX_DN<7>")
	)
	(segment
		(start 351.778824 -284.311344)
		(end 351.748344 -284.293564)
		(width 0.1143)
		(layer "In13.Cu")
		(net "P5E_CPU0_P0_RX_DN<7>")
	)
	(segment
		(start 351.778824 -292.41115)
		(end 351.748344 -292.39337)
		(width 0.1143)
		(layer "In13.Cu")
		(net "P5E_CPU0_P0_RX_DN<7>")
	)
	(segment
		(start 351.778824 -277.831296)
		(end 351.748344 -277.813516)
		(width 0.1143)
		(layer "In13.Cu")
		(net "P5E_CPU0_P0_RX_DN<7>")
	)
	(segment
		(start 352.151696 -296.42816)
		(end 352.151696 -296.167302)
		(width 0.1143)
		(layer "In13.Cu")
		(net "P5E_CPU0_P0_RX_DN<7>")
	)
	(segment
		(start 377.096528 -386.967984)
		(end 376.789188 -387.275324)
		(width 0.14224)
		(layer "In13.Cu")
		(net "P5E_CPU0_P0_RX_DN<7>")
	)
	(segment
		(start 312.349388 -393.22883)
		(end 312.354214 -392.616944)
		(width 0.14224)
		(layer "In13.Cu")
		(net "P5E_CPU0_P0_RX_DN<7>")
	)
	(segment
		(start 386.742178 -388.093966)
		(end 386.794756 -388.041388)
		(width 0.14224)
		(layer "In13.Cu")
		(net "P5E_CPU0_P0_RX_DN<7>")
	)
	(segment
		(start 370.721128 -387.936486)
		(end 370.721128 -386.162804)
		(width 0.14224)
		(layer "In13.Cu")
		(net "P5E_CPU0_P0_RX_DN<7>")
	)
	(segment
		(start 351.709228 -276.861524)
		(end 351.748344 -276.838664)
		(width 0.1143)
		(layer "In13.Cu")
		(net "P5E_CPU0_P0_RX_DN<7>")
	)
	(segment
		(start 312.66638 -393.545822)
		(end 312.349388 -393.22883)
		(width 0.14224)
		(layer "In13.Cu")
		(net "P5E_CPU0_P0_RX_DN<7>")
	)
	(segment
		(start 351.709228 -280.101548)
		(end 351.748344 -280.078688)
		(width 0.1143)
		(layer "In13.Cu")
		(net "P5E_CPU0_P0_RX_DN<7>")
	)
	(segment
		(start 351.778824 -274.591272)
		(end 351.748344 -274.573492)
		(width 0.1143)
		(layer "In13.Cu")
		(net "P5E_CPU0_P0_RX_DN<7>")
	)
	(segment
		(start 351.748344 -277.813516)
		(end 351.709228 -277.790656)
		(width 0.1143)
		(layer "In13.Cu")
		(net "P5E_CPU0_P0_RX_DN<7>")
	)
	(segment
		(start 389.454644 -374.175782)
		(end 389.591804 -374.038622)
		(width 0.14224)
		(layer "In13.Cu")
		(net "P5E_CPU0_P0_RX_DN<7>")
	)
	(segment
		(start 360.517948 -386.357114)
		(end 367.900712 -386.357114)
		(width 0.14224)
		(layer "In13.Cu")
		(net "P5E_CPU0_P0_RX_DN<7>")
	)
	(segment
		(start 312.66638 -393.716764)
		(end 312.66638 -393.545822)
		(width 0.14224)
		(layer "In13.Cu")
		(net "P5E_CPU0_P0_RX_DN<7>")
	)
	(segment
		(start 388.108698 -380.89586)
		(end 388.459726 -380.750572)
		(width 0.14224)
		(layer "In13.Cu")
		(net "P5E_CPU0_P0_RX_DN<7>")
	)
	(segment
		(start 351.709228 -278.481536)
		(end 351.748344 -278.458676)
		(width 0.1143)
		(layer "In13.Cu")
		(net "P5E_CPU0_P0_RX_DN<7>")
	)
	(segment
		(start 316.997334 -386.464048)
		(end 327.352152 -386.464048)
		(width 0.14224)
		(layer "In13.Cu")
		(net "P5E_CPU0_P0_RX_DN<7>")
	)
	(segment
		(start 351.748344 -293.03853)
		(end 351.778824 -293.02075)
		(width 0.1143)
		(layer "In13.Cu")
		(net "P5E_CPU0_P0_RX_DN<7>")
	)
	(segment
		(start 351.778824 -290.791138)
		(end 351.748344 -290.773358)
		(width 0.1143)
		(layer "In13.Cu")
		(net "P5E_CPU0_P0_RX_DN<7>")
	)
	(segment
		(start 351.709228 -281.72156)
		(end 351.748344 -281.6987)
		(width 0.1143)
		(layer "In13.Cu")
		(net "P5E_CPU0_P0_RX_DN<7>")
	)
	(segment
		(start 351.748344 -276.838664)
		(end 351.778824 -276.820884)
		(width 0.1143)
		(layer "In13.Cu")
		(net "P5E_CPU0_P0_RX_DN<7>")
	)
	(segment
		(start 351.748344 -290.773358)
		(end 351.709228 -290.750498)
		(width 0.1143)
		(layer "In13.Cu")
		(net "P5E_CPU0_P0_RX_DN<7>")
	)
	(segment
		(start 351.709228 -289.821366)
		(end 351.748344 -289.798506)
		(width 0.1143)
		(layer "In13.Cu")
		(net "P5E_CPU0_P0_RX_DN<7>")
	)
	(segment
		(start 370.616226 -388.093966)
		(end 370.68379 -388.026402)
		(width 0.14224)
		(layer "In13.Cu")
		(net "P5E_CPU0_P0_RX_DN<7>")
	)
	(segment
		(start 351.748344 -274.573492)
		(end 351.709228 -274.550632)
		(width 0.1143)
		(layer "In13.Cu")
		(net "P5E_CPU0_P0_RX_DN<7>")
	)
	(segment
		(start 351.709228 -283.341572)
		(end 351.748344 -283.318712)
		(width 0.1143)
		(layer "In13.Cu")
		(net "P5E_CPU0_P0_RX_DN<7>")
	)
	(segment
		(start 351.778824 -294.031162)
		(end 351.748344 -294.013382)
		(width 0.1143)
		(layer "In13.Cu")
		(net "P5E_CPU0_P0_RX_DN<7>")
	)
	(segment
		(start 364.395258 -312.550302)
		(end 352.242628 -297.741594)
		(width 0.14224)
		(layer "In13.Cu")
		(net "P5E_CPU0_P0_RX_DN<7>")
	)
	(segment
		(start 312.788046 -390.48944)
		(end 316.683644 -386.593842)
		(width 0.14224)
		(layer "In13.Cu")
		(net "P5E_CPU0_P0_RX_DN<7>")
	)
	(segment
		(start 351.748344 -291.418518)
		(end 351.778824 -291.400738)
		(width 0.1143)
		(layer "In13.Cu")
		(net "P5E_CPU0_P0_RX_DN<7>")
	)
	(segment
		(start 351.748344 -282.673552)
		(end 351.709228 -282.650692)
		(width 0.1143)
		(layer "In13.Cu")
		(net "P5E_CPU0_P0_RX_DN<7>")
	)
	(segment
		(start 352.105976 -296.502328)
		(end 352.105976 -296.47388)
		(width 0.1143)
		(layer "In13.Cu")
		(net "P5E_CPU0_P0_RX_DN<7>")
	)
	(segment
		(start 389.591804 -375.46534)
		(end 389.591804 -374.739662)
		(width 0.14224)
		(layer "In13.Cu")
		(net "P5E_CPU0_P0_RX_DN<7>")
	)
	(segment
		(start 371.028468 -385.855464)
		(end 376.789188 -385.855464)
		(width 0.14224)
		(layer "In13.Cu")
		(net "P5E_CPU0_P0_RX_DN<7>")
	)
	(segment
		(start 351.71126 -286.579818)
		(end 351.748344 -286.558482)
		(width 0.1143)
		(layer "In13.Cu")
		(net "P5E_CPU0_P0_RX_DN<7>")
	)
	(segment
		(start 351.748344 -280.078688)
		(end 351.778824 -280.060908)
		(width 0.1143)
		(layer "In13.Cu")
		(net "P5E_CPU0_P0_RX_DN<7>")
	)
	(segment
		(start 351.748344 -276.193504)
		(end 351.709228 -276.170644)
		(width 0.1143)
		(layer "In13.Cu")
		(net "P5E_CPU0_P0_RX_DN<7>")
	)
	(segment
		(start 388.61492 -380.51867)
		(end 388.61492 -379.669802)
		(width 0.14224)
		(layer "In13.Cu")
		(net "P5E_CPU0_P0_RX_DN<7>")
	)
	(segment
		(start 351.748344 -286.558482)
		(end 351.780856 -286.539686)
		(width 0.1143)
		(layer "In13.Cu")
		(net "P5E_CPU0_P0_RX_DN<7>")
	)
	(segment
		(start 351.778824 -276.211284)
		(end 351.748344 -276.193504)
		(width 0.1143)
		(layer "In13.Cu")
		(net "P5E_CPU0_P0_RX_DN<7>")
	)
	(segment
		(start 388.744714 -379.356366)
		(end 390.166606 -377.934474)
		(width 0.14224)
		(layer "In13.Cu")
		(net "P5E_CPU0_P0_RX_DN<7>")
	)
	(segment
		(start 372.283228 -388.131304)
		(end 386.652262 -388.131304)
		(width 0.14224)
		(layer "In13.Cu")
		(net "P5E_CPU0_P0_RX_DN<7>")
	)
	(segment
		(start 351.748344 -275.218652)
		(end 351.778824 -275.200872)
		(width 0.1143)
		(layer "In13.Cu")
		(net "P5E_CPU0_P0_RX_DN<7>")
	)
	(segment
		(start 386.694934 -385.475988)
		(end 386.832094 -385.338828)
		(width 0.14224)
		(layer "In13.Cu")
		(net "P5E_CPU0_P0_RX_DN<7>")
	)
	(segment
		(start 351.748344 -284.293564)
		(end 351.709228 -284.270704)
		(width 0.1143)
		(layer "In13.Cu")
		(net "P5E_CPU0_P0_RX_DN<7>")
	)
	(segment
		(start 351.748344 -294.013382)
		(end 351.709228 -293.990522)
		(width 0.1143)
		(layer "In13.Cu")
		(net "P5E_CPU0_P0_RX_DN<7>")
	)
	(segment
		(start 351.778824 -285.931356)
		(end 351.748344 -285.913576)
		(width 0.1143)
		(layer "In13.Cu")
		(net "P5E_CPU0_P0_RX_DN<7>")
	)
	(segment
		(start 328.464418 -386.354574)
		(end 330.671424 -386.354574)
		(width 0.14224)
		(layer "In13.Cu")
		(net "P5E_CPU0_P0_RX_DN<7>")
	)
	(segment
		(start 351.748344 -292.39337)
		(end 351.709228 -292.37051)
		(width 0.1143)
		(layer "In13.Cu")
		(net "P5E_CPU0_P0_RX_DN<7>")
	)
	(segment
		(start 389.591804 -374.739662)
		(end 389.454644 -374.602502)
		(width 0.14224)
		(layer "In13.Cu")
		(net "P5E_CPU0_P0_RX_DN<7>")
	)
	(segment
		(start 352.105976 -296.47388)
		(end 352.151696 -296.42816)
		(width 0.1143)
		(layer "In13.Cu")
		(net "P5E_CPU0_P0_RX_DN<7>")
	)
	(segment
		(start 386.832094 -384.912108)
		(end 386.694934 -384.774948)
		(width 0.14224)
		(layer "In13.Cu")
		(net "P5E_CPU0_P0_RX_DN<7>")
	)
	(segment
		(start 351.748344 -279.433528)
		(end 351.709228 -279.410668)
		(width 0.1143)
		(layer "In13.Cu")
		(net "P5E_CPU0_P0_RX_DN<7>")
	)
	(segment
		(start 351.778824 -281.07132)
		(end 351.748344 -281.05354)
		(width 0.1143)
		(layer "In13.Cu")
		(net "P5E_CPU0_P0_RX_DN<7>")
	)
	(segment
		(start 351.778824 -289.171126)
		(end 351.748344 -289.153346)
		(width 0.1143)
		(layer "In13.Cu")
		(net "P5E_CPU0_P0_RX_DN<7>")
	)
	(segment
		(start 387.390386 -381.14351)
		(end 387.695694 -381.017272)
		(width 0.14224)
		(layer "In13.Cu")
		(net "P5E_CPU0_P0_RX_DN<7>")
	)
	(segment
		(start 386.694934 -384.774948)
		(end 386.694934 -384.348228)
		(width 0.14224)
		(layer "In13.Cu")
		(net "P5E_CPU0_P0_RX_DN<7>")
	)
	(segment
		(start 386.694934 -384.348228)
		(end 386.78485 -384.258312)
		(width 0.14224)
		(layer "In13.Cu")
		(net "P5E_CPU0_P0_RX_DN<7>")
	)
	(segment
		(start 351.709228 -288.201354)
		(end 351.748344 -288.178494)
		(width 0.1143)
		(layer "In13.Cu")
		(net "P5E_CPU0_P0_RX_DN<7>")
	)
	(segment
		(start 352.105976 -297.360594)
		(end 352.105976 -296.502328)
		(width 0.14224)
		(layer "In13.Cu")
		(net "P5E_CPU0_P0_RX_DN<7>")
	)
	(segment
		(start 351.778824 -279.451308)
		(end 351.748344 -279.433528)
		(width 0.1143)
		(layer "In13.Cu")
		(net "P5E_CPU0_P0_RX_DN<7>")
	)
	(segment
		(start 376.789188 -387.275324)
		(end 372.283228 -387.275324)
		(width 0.14224)
		(layer "In13.Cu")
		(net "P5E_CPU0_P0_RX_DN<7>")
	)
	(segment
		(start 351.748344 -284.938724)
		(end 351.778824 -284.920944)
		(width 0.1143)
		(layer "In13.Cu")
		(net "P5E_CPU0_P0_RX_DN<7>")
	)
	(segment
		(start 351.748344 -285.913576)
		(end 351.709228 -285.890716)
		(width 0.1143)
		(layer "In13.Cu")
		(net "P5E_CPU0_P0_RX_DN<7>")
	)
	(segment
		(start 351.748344 -278.458676)
		(end 351.778824 -278.440896)
		(width 0.1143)
		(layer "In13.Cu")
		(net "P5E_CPU0_P0_RX_DN<7>")
	)
	(segment
		(start 372.140988 -387.989064)
		(end 372.283228 -388.131304)
		(width 0.14224)
		(layer "In13.Cu")
		(net "P5E_CPU0_P0_RX_DN<7>")
	)
	(segment
		(start 372.140988 -387.417564)
		(end 372.140988 -387.989064)
		(width 0.14224)
		(layer "In13.Cu")
		(net "P5E_CPU0_P0_RX_DN<7>")
	)
	(arc
		(start 351.778824 -281.68092)
		(mid 351.935801 -281.37612)
		(end 351.778824 -281.07132)
		(width 0.1143)
		(layer "In13.Cu")
		(net "P5E_CPU0_P0_RX_DN<7>")
	)
	(arc
		(start 351.778824 -294.640762)
		(mid 351.935801 -294.335962)
		(end 351.778824 -294.031162)
		(width 0.1143)
		(layer "In13.Cu")
		(net "P5E_CPU0_P0_RX_DN<7>")
	)
	(arc
		(start 386.652262 -388.131304)
		(mid 386.700946 -388.121602)
		(end 386.742178 -388.093966)
		(width 0.14224)
		(layer "In13.Cu")
		(net "P5E_CPU0_P0_RX_DN<7>")
	)
	(arc
		(start 387.695694 -381.017272)
		(mid 387.825578 -380.97149)
		(end 387.9596 -380.939802)
		(width 0.14224)
		(layer "In13.Cu")
		(net "P5E_CPU0_P0_RX_DN<7>")
	)
	(arc
		(start 351.778824 -291.400738)
		(mid 351.935801 -291.095938)
		(end 351.778824 -290.791138)
		(width 0.1143)
		(layer "In13.Cu")
		(net "P5E_CPU0_P0_RX_DN<7>")
	)
	(arc
		(start 351.709228 -289.130486)
		(mid 351.465901 -288.66592)
		(end 351.709228 -288.201354)
		(width 0.1143)
		(layer "In13.Cu")
		(net "P5E_CPU0_P0_RX_DN<7>")
	)
	(arc
		(start 330.671424 -386.354574)
		(mid 330.898697 -386.423493)
		(end 331.049376 -386.60705)
		(width 0.14224)
		(layer "In13.Cu")
		(net "P5E_CPU0_P0_RX_DN<7>")
	)
	(arc
		(start 386.832094 -381.82042)
		(mid 386.865784 -381.650667)
		(end 386.961888 -381.50673)
		(width 0.14224)
		(layer "In13.Cu")
		(net "P5E_CPU0_P0_RX_DN<7>")
	)
	(arc
		(start 355.623876 -388.20852)
		(mid 355.685599 -388.196243)
		(end 355.737922 -388.161276)
		(width 0.14224)
		(layer "In13.Cu")
		(net "P5E_CPU0_P0_RX_DN<7>")
	)
	(arc
		(start 370.52631 -388.131304)
		(mid 370.574994 -388.121602)
		(end 370.616226 -388.093966)
		(width 0.14224)
		(layer "In13.Cu")
		(net "P5E_CPU0_P0_RX_DN<7>")
	)
	(arc
		(start 387.194298 -381.27432)
		(mid 387.285897 -381.199254)
		(end 387.390386 -381.14351)
		(width 0.14224)
		(layer "In13.Cu")
		(net "P5E_CPU0_P0_RX_DN<7>")
	)
	(arc
		(start 351.778824 -289.780726)
		(mid 351.935801 -289.475926)
		(end 351.778824 -289.171126)
		(width 0.1143)
		(layer "In13.Cu")
		(net "P5E_CPU0_P0_RX_DN<7>")
	)
	(arc
		(start 351.709228 -274.550632)
		(mid 351.465901 -274.086066)
		(end 351.709228 -273.6215)
		(width 0.1143)
		(layer "In13.Cu")
		(net "P5E_CPU0_P0_RX_DN<7>")
	)
	(arc
		(start 351.709228 -285.890716)
		(mid 351.465901 -285.42615)
		(end 351.709228 -284.961584)
		(width 0.1143)
		(layer "In13.Cu")
		(net "P5E_CPU0_P0_RX_DN<7>")
	)
	(arc
		(start 351.709228 -292.37051)
		(mid 351.465901 -291.905944)
		(end 351.709228 -291.441378)
		(width 0.1143)
		(layer "In13.Cu")
		(net "P5E_CPU0_P0_RX_DN<7>")
	)
	(arc
		(start 351.778824 -284.920944)
		(mid 351.935801 -284.616144)
		(end 351.778824 -284.311344)
		(width 0.1143)
		(layer "In13.Cu")
		(net "P5E_CPU0_P0_RX_DN<7>")
	)
	(arc
		(start 351.778824 -278.440896)
		(mid 351.935801 -278.136096)
		(end 351.778824 -277.831296)
		(width 0.1143)
		(layer "In13.Cu")
		(net "P5E_CPU0_P0_RX_DN<7>")
	)
	(arc
		(start 351.711768 -287.512252)
		(mid 351.531116 -287.309507)
		(end 351.465896 -287.045908)
		(width 0.1143)
		(layer "In13.Cu")
		(net "P5E_CPU0_P0_RX_DN<7>")
	)
	(arc
		(start 351.780856 -286.539686)
		(mid 351.894785 -286.406539)
		(end 351.935796 -286.236156)
		(width 0.1143)
		(layer "In13.Cu")
		(net "P5E_CPU0_P0_RX_DN<7>")
	)
	(arc
		(start 351.559114 -295.57472)
		(mid 351.490148 -295.4716)
		(end 351.465896 -295.34993)
		(width 0.1143)
		(layer "In13.Cu")
		(net "P5E_CPU0_P0_RX_DN<7>")
	)
	(arc
		(start 351.465896 -295.14546)
		(mid 351.465896 -295.145206)
		(end 351.465896 -295.144952)
		(width 0.1143)
		(layer "In13.Cu")
		(net "P5E_CPU0_P0_RX_DN<7>")
	)
	(arc
		(start 351.709228 -279.410668)
		(mid 351.465901 -278.946102)
		(end 351.709228 -278.481536)
		(width 0.1143)
		(layer "In13.Cu")
		(net "P5E_CPU0_P0_RX_DN<7>")
	)
	(arc
		(start 367.900712 -386.357114)
		(mid 368.149517 -386.432544)
		(end 368.314478 -386.633466)
		(width 0.14224)
		(layer "In13.Cu")
		(net "P5E_CPU0_P0_RX_DN<7>")
	)
	(arc
		(start 351.709228 -277.790656)
		(mid 351.465901 -277.32609)
		(end 351.709228 -276.861524)
		(width 0.1143)
		(layer "In13.Cu")
		(net "P5E_CPU0_P0_RX_DN<7>")
	)
	(arc
		(start 351.780856 -288.159698)
		(mid 351.894785 -288.026551)
		(end 351.935796 -287.856168)
		(width 0.1143)
		(layer "In13.Cu")
		(net "P5E_CPU0_P0_RX_DN<7>")
	)
	(arc
		(start 351.778824 -273.58086)
		(mid 351.876589 -273.477884)
		(end 351.928938 -273.34591)
		(width 0.1143)
		(layer "In13.Cu")
		(net "P5E_CPU0_P0_RX_DN<7>")
	)
	(arc
		(start 351.935796 -287.856168)
		(mid 351.894247 -287.684746)
		(end 351.778824 -287.551368)
		(width 0.1143)
		(layer "In13.Cu")
		(net "P5E_CPU0_P0_RX_DN<7>")
	)
	(arc
		(start 390.245346 -376.377708)
		(mid 390.235644 -376.329024)
		(end 390.208008 -376.287792)
		(width 0.14224)
		(layer "In13.Cu")
		(net "P5E_CPU0_P0_RX_DN<7>")
	)
	(arc
		(start 368.82832 -387.873748)
		(mid 368.98204 -388.06102)
		(end 369.213892 -388.131304)
		(width 0.14224)
		(layer "In13.Cu")
		(net "P5E_CPU0_P0_RX_DN<7>")
	)
	(arc
		(start 351.709228 -290.750498)
		(mid 351.465901 -290.285932)
		(end 351.709228 -289.821366)
		(width 0.1143)
		(layer "In13.Cu")
		(net "P5E_CPU0_P0_RX_DN<7>")
	)
	(arc
		(start 351.709228 -281.03068)
		(mid 351.465901 -280.566114)
		(end 351.709228 -280.101548)
		(width 0.1143)
		(layer "In13.Cu")
		(net "P5E_CPU0_P0_RX_DN<7>")
	)
	(arc
		(start 388.459726 -380.750572)
		(mid 388.572503 -380.658174)
		(end 388.61492 -380.51867)
		(width 0.14224)
		(layer "In13.Cu")
		(net "P5E_CPU0_P0_RX_DN<7>")
	)
	(arc
		(start 357.18496 -386.714238)
		(mid 357.450546 -386.536779)
		(end 357.763826 -386.474462)
		(width 0.14224)
		(layer "In13.Cu")
		(net "P5E_CPU0_P0_RX_DN<7>")
	)
	(arc
		(start 351.465896 -287.045908)
		(mid 351.530411 -286.783689)
		(end 351.709228 -286.581342)
		(width 0.1143)
		(layer "In13.Cu")
		(net "P5E_CPU0_P0_RX_DN<7>")
	)
	(arc
		(start 387.9596 -380.939802)
		(mid 388.035331 -380.921839)
		(end 388.108698 -380.89586)
		(width 0.14224)
		(layer "In13.Cu")
		(net "P5E_CPU0_P0_RX_DN<7>")
	)
	(arc
		(start 390.166606 -377.934474)
		(mid 390.224904 -377.847319)
		(end 390.245346 -377.744482)
		(width 0.14224)
		(layer "In13.Cu")
		(net "P5E_CPU0_P0_RX_DN<7>")
	)
	(arc
		(start 351.778824 -293.02075)
		(mid 351.935801 -292.71595)
		(end 351.778824 -292.41115)
		(width 0.1143)
		(layer "In13.Cu")
		(net "P5E_CPU0_P0_RX_DN<7>")
	)
	(arc
		(start 351.778824 -283.300932)
		(mid 351.935801 -282.996132)
		(end 351.778824 -282.691332)
		(width 0.1143)
		(layer "In13.Cu")
		(net "P5E_CPU0_P0_RX_DN<7>")
	)
	(arc
		(start 351.709228 -276.170644)
		(mid 351.465901 -275.706078)
		(end 351.709228 -275.241512)
		(width 0.1143)
		(layer "In13.Cu")
		(net "P5E_CPU0_P0_RX_DN<7>")
	)
	(arc
		(start 351.465896 -295.144952)
		(mid 351.530646 -294.883299)
		(end 351.709228 -294.681402)
		(width 0.1143)
		(layer "In13.Cu")
		(net "P5E_CPU0_P0_RX_DN<7>")
	)
	(arc
		(start 351.709228 -282.650692)
		(mid 351.465901 -282.186126)
		(end 351.709228 -281.72156)
		(width 0.1143)
		(layer "In13.Cu")
		(net "P5E_CPU0_P0_RX_DN<7>")
	)
	(arc
		(start 351.935796 -286.236156)
		(mid 351.894247 -286.064734)
		(end 351.778824 -285.931356)
		(width 0.1143)
		(layer "In13.Cu")
		(net "P5E_CPU0_P0_RX_DN<7>")
	)
	(arc
		(start 352.242628 -297.741594)
		(mid 352.14127 -297.562943)
		(end 352.105976 -297.360594)
		(width 0.14224)
		(layer "In13.Cu")
		(net "P5E_CPU0_P0_RX_DN<7>")
	)
	(arc
		(start 331.680058 -388.12978)
		(mid 331.726757 -388.187029)
		(end 331.797406 -388.20852)
		(width 0.14224)
		(layer "In13.Cu")
		(net "P5E_CPU0_P0_RX_DN<7>")
	)
	(arc
		(start 386.794756 -388.041388)
		(mid 386.822375 -388.000148)
		(end 386.832094 -387.951472)
		(width 0.14224)
		(layer "In13.Cu")
		(net "P5E_CPU0_P0_RX_DN<7>")
	)
	(arc
		(start 351.709228 -293.990522)
		(mid 351.465901 -293.525956)
		(end 351.709228 -293.06139)
		(width 0.1143)
		(layer "In13.Cu")
		(net "P5E_CPU0_P0_RX_DN<7>")
	)
	(arc
		(start 388.61492 -379.669802)
		(mid 388.648659 -379.500185)
		(end 388.744714 -379.356366)
		(width 0.14224)
		(layer "In13.Cu")
		(net "P5E_CPU0_P0_RX_DN<7>")
	)
	(arc
		(start 351.709228 -284.270704)
		(mid 351.465901 -283.806138)
		(end 351.709228 -283.341572)
		(width 0.1143)
		(layer "In13.Cu")
		(net "P5E_CPU0_P0_RX_DN<7>")
	)
	(arc
		(start 351.778824 -275.200872)
		(mid 351.935801 -274.896072)
		(end 351.778824 -274.591272)
		(width 0.1143)
		(layer "In13.Cu")
		(net "P5E_CPU0_P0_RX_DN<7>")
	)
	(arc
		(start 312.658252 -390.802876)
		(mid 312.691991 -390.633259)
		(end 312.788046 -390.48944)
		(width 0.14224)
		(layer "In13.Cu")
		(net "P5E_CPU0_P0_RX_DN<7>")
	)
	(arc
		(start 389.7376 -375.817384)
		(mid 389.629676 -375.655865)
		(end 389.591804 -375.46534)
		(width 0.14224)
		(layer "In13.Cu")
		(net "P5E_CPU0_P0_RX_DN<7>")
	)
	(arc
		(start 386.78485 -384.258312)
		(mid 386.819812 -384.205987)
		(end 386.832094 -384.144266)
		(width 0.14224)
		(layer "In13.Cu")
		(net "P5E_CPU0_P0_RX_DN<7>")
	)
	(arc
		(start 351.778824 -280.060908)
		(mid 351.935801 -279.756108)
		(end 351.778824 -279.451308)
		(width 0.1143)
		(layer "In13.Cu")
		(net "P5E_CPU0_P0_RX_DN<7>")
	)
	(arc
		(start 351.778824 -276.820884)
		(mid 351.935801 -276.516084)
		(end 351.778824 -276.211284)
		(width 0.1143)
		(layer "In13.Cu")
		(net "P5E_CPU0_P0_RX_DN<7>")
	)
	(arc
		(start 316.683644 -386.593842)
		(mid 316.827567 -386.497706)
		(end 316.997334 -386.464048)
		(width 0.14224)
		(layer "In13.Cu")
		(net "P5E_CPU0_P0_RX_DN<7>")
	)
	(arc
		(start 370.68379 -388.026402)
		(mid 370.711409 -387.985162)
		(end 370.721128 -387.936486)
		(width 0.14224)
		(layer "In13.Cu")
		(net "P5E_CPU0_P0_RX_DN<7>")
	)
	(segment
		(start 310.470296 -393.69238)
		(end 310.990996 -393.69238)
		(width 0.127)
		(layer "F.Cu")
		(net "P5E_CPU0_P0_RX_DN<6>")
	)
	(segment
		(start 352.027998 -271.39011)
		(end 351.561146 -271.656048)
		(width 0.12954)
		(layer "F.Cu")
		(net "P5E_CPU0_P0_RX_DN<6>")
	)
	(segment
		(start 375.62282 -384.612388)
		(end 376.04954 -384.612388)
		(width 0.14224)
		(layer "In13.Cu")
		(net "P5E_CPU0_P0_RX_DN<6>")
	)
	(segment
		(start 343.464388 -386.094986)
		(end 343.322148 -385.952746)
		(width 0.14224)
		(layer "In13.Cu")
		(net "P5E_CPU0_P0_RX_DN<6>")
	)
	(segment
		(start 386.815838 -377.67514)
		(end 386.815838 -376.758708)
		(width 0.14224)
		(layer "In13.Cu")
		(net "P5E_CPU0_P0_RX_DN<6>")
	)
	(segment
		(start 350.83877 -285.931356)
		(end 350.80829 -285.913576)
		(width 0.1143)
		(layer "In13.Cu")
		(net "P5E_CPU0_P0_RX_DN<6>")
	)
	(segment
		(start 337.723988 -385.645406)
		(end 337.723988 -384.840226)
		(width 0.14224)
		(layer "In13.Cu")
		(net "P5E_CPU0_P0_RX_DN<6>")
	)
	(segment
		(start 374.49506 -384.612388)
		(end 374.92178 -384.612388)
		(width 0.14224)
		(layer "In13.Cu")
		(net "P5E_CPU0_P0_RX_DN<6>")
	)
	(segment
		(start 351.747582 -271.978882)
		(end 351.77984 -271.960086)
		(width 0.1143)
		(layer "In13.Cu")
		(net "P5E_CPU0_P0_RX_DN<6>")
	)
	(segment
		(start 317.499238 -377.744482)
		(end 319.122044 -376.12193)
		(width 0.14224)
		(layer "In13.Cu")
		(net "P5E_CPU0_P0_RX_DN<6>")
	)
	(segment
		(start 350.83877 -294.031162)
		(end 350.769174 -293.990522)
		(width 0.1143)
		(layer "In13.Cu")
		(net "P5E_CPU0_P0_RX_DN<6>")
	)
	(segment
		(start 350.83877 -287.551368)
		(end 350.771714 -287.512252)
		(width 0.1143)
		(layer "In13.Cu")
		(net "P5E_CPU0_P0_RX_DN<6>")
	)
	(segment
		(start 350.83877 -290.791138)
		(end 350.769174 -290.750498)
		(width 0.1143)
		(layer "In13.Cu")
		(net "P5E_CPU0_P0_RX_DN<6>")
	)
	(segment
		(start 376.04954 -384.612388)
		(end 376.1867 -384.475228)
		(width 0.14224)
		(layer "In13.Cu")
		(net "P5E_CPU0_P0_RX_DN<6>")
	)
	(segment
		(start 373.79402 -384.612388)
		(end 373.93118 -384.475228)
		(width 0.14224)
		(layer "In13.Cu")
		(net "P5E_CPU0_P0_RX_DN<6>")
	)
	(segment
		(start 350.769174 -284.961584)
		(end 350.80829 -284.938724)
		(width 0.1143)
		(layer "In13.Cu")
		(net "P5E_CPU0_P0_RX_DN<6>")
	)
	(segment
		(start 350.769174 -281.72156)
		(end 350.80829 -281.6987)
		(width 0.1143)
		(layer "In13.Cu")
		(net "P5E_CPU0_P0_RX_DN<6>")
	)
	(segment
		(start 332.624938 -384.496818)
		(end 336.2706 -384.496818)
		(width 0.14224)
		(layer "In13.Cu")
		(net "P5E_CPU0_P0_RX_DN<6>")
	)
	(segment
		(start 385.127246 -380.352808)
		(end 385.127246 -379.509274)
		(width 0.14224)
		(layer "In13.Cu")
		(net "P5E_CPU0_P0_RX_DN<6>")
	)
	(segment
		(start 338.031328 -384.532886)
		(end 357.457502 -384.532886)
		(width 0.14224)
		(layer "In13.Cu")
		(net "P5E_CPU0_P0_RX_DN<6>")
	)
	(segment
		(start 350.80829 -275.218652)
		(end 350.83877 -275.200872)
		(width 0.1143)
		(layer "In13.Cu")
		(net "P5E_CPU0_P0_RX_DN<6>")
	)
	(segment
		(start 350.80829 -281.6987)
		(end 350.83877 -281.68092)
		(width 0.1143)
		(layer "In13.Cu")
		(net "P5E_CPU0_P0_RX_DN<6>")
	)
	(segment
		(start 350.80829 -273.59864)
		(end 350.83877 -273.58086)
		(width 0.1143)
		(layer "In13.Cu")
		(net "P5E_CPU0_P0_RX_DN<6>")
	)
	(segment
		(start 360.023156 -382.235456)
		(end 364.689136 -382.235456)
		(width 0.14224)
		(layer "In13.Cu")
		(net "P5E_CPU0_P0_RX_DN<6>")
	)
	(segment
		(start 385.65963 -378.64923)
		(end 386.382006 -378.165868)
		(width 0.14224)
		(layer "In13.Cu")
		(net "P5E_CPU0_P0_RX_DN<6>")
	)
	(segment
		(start 350.769174 -288.201354)
		(end 350.80829 -288.178494)
		(width 0.1143)
		(layer "In13.Cu")
		(net "P5E_CPU0_P0_RX_DN<6>")
	)
	(segment
		(start 374.92178 -384.612388)
		(end 375.05894 -384.475228)
		(width 0.14224)
		(layer "In13.Cu")
		(net "P5E_CPU0_P0_RX_DN<6>")
	)
	(segment
		(start 375.48566 -384.475228)
		(end 375.62282 -384.612388)
		(width 0.14224)
		(layer "In13.Cu")
		(net "P5E_CPU0_P0_RX_DN<6>")
	)
	(segment
		(start 376.1867 -384.475228)
		(end 376.61342 -384.475228)
		(width 0.14224)
		(layer "In13.Cu")
		(net "P5E_CPU0_P0_RX_DN<6>")
	)
	(segment
		(start 350.83877 -289.171126)
		(end 350.80829 -289.153346)
		(width 0.1143)
		(layer "In13.Cu")
		(net "P5E_CPU0_P0_RX_DN<6>")
	)
	(segment
		(start 350.83877 -279.451308)
		(end 350.80829 -279.433528)
		(width 0.1143)
		(layer "In13.Cu")
		(net "P5E_CPU0_P0_RX_DN<6>")
	)
	(segment
		(start 386.815838 -376.758708)
		(end 387.765798 -374.464834)
		(width 0.14224)
		(layer "In13.Cu")
		(net "P5E_CPU0_P0_RX_DN<6>")
	)
	(segment
		(start 328.844656 -376.890788)
		(end 331.754226 -383.914904)
		(width 0.14224)
		(layer "In13.Cu")
		(net "P5E_CPU0_P0_RX_DN<6>")
	)
	(segment
		(start 367.821464 -384.612388)
		(end 373.79402 -384.612388)
		(width 0.14224)
		(layer "In13.Cu")
		(net "P5E_CPU0_P0_RX_DN<6>")
	)
	(segment
		(start 351.859088 -271.656048)
		(end 351.561146 -271.656048)
		(width 0.1143)
		(layer "In13.Cu")
		(net "P5E_CPU0_P0_RX_DN<6>")
	)
	(segment
		(start 350.80829 -283.318712)
		(end 350.83877 -283.300932)
		(width 0.1143)
		(layer "In13.Cu")
		(net "P5E_CPU0_P0_RX_DN<6>")
	)
	(segment
		(start 350.80829 -286.558482)
		(end 350.840802 -286.539686)
		(width 0.1143)
		(layer "In13.Cu")
		(net "P5E_CPU0_P0_RX_DN<6>")
	)
	(segment
		(start 384.814826 -380.717806)
		(end 385.089908 -380.442724)
		(width 0.14224)
		(layer "In13.Cu")
		(net "P5E_CPU0_P0_RX_DN<6>")
	)
	(segment
		(start 350.769174 -291.441378)
		(end 350.83877 -291.400738)
		(width 0.1143)
		(layer "In13.Cu")
		(net "P5E_CPU0_P0_RX_DN<6>")
	)
	(segment
		(start 350.83877 -274.591272)
		(end 350.80829 -274.573492)
		(width 0.1143)
		(layer "In13.Cu")
		(net "P5E_CPU0_P0_RX_DN<6>")
	)
	(segment
		(start 350.769174 -276.861524)
		(end 350.83877 -276.820884)
		(width 0.1143)
		(layer "In13.Cu")
		(net "P5E_CPU0_P0_RX_DN<6>")
	)
	(segment
		(start 311.466484 -393.545822)
		(end 311.149492 -393.22883)
		(width 0.14224)
		(layer "In13.Cu")
		(net "P5E_CPU0_P0_RX_DN<6>")
	)
	(segment
		(start 374.3579 -384.475228)
		(end 374.49506 -384.612388)
		(width 0.14224)
		(layer "In13.Cu")
		(net "P5E_CPU0_P0_RX_DN<6>")
	)
	(segment
		(start 351.063052 -296.192956)
		(end 350.61906 -295.748964)
		(width 0.1143)
		(layer "In13.Cu")
		(net "P5E_CPU0_P0_RX_DN<6>")
	)
	(segment
		(start 350.83877 -281.07132)
		(end 350.80829 -281.05354)
		(width 0.1143)
		(layer "In13.Cu")
		(net "P5E_CPU0_P0_RX_DN<6>")
	)
	(segment
		(start 311.466484 -393.716764)
		(end 311.466484 -393.545822)
		(width 0.14224)
		(layer "In13.Cu")
		(net "P5E_CPU0_P0_RX_DN<6>")
	)
	(segment
		(start 337.723988 -384.840226)
		(end 338.031328 -384.532886)
		(width 0.14224)
		(layer "In13.Cu")
		(net "P5E_CPU0_P0_RX_DN<6>")
	)
	(segment
		(start 336.56016 -384.616706)
		(end 336.74812 -384.804666)
		(width 0.14224)
		(layer "In13.Cu")
		(net "P5E_CPU0_P0_RX_DN<6>")
	)
	(segment
		(start 373.93118 -384.475228)
		(end 374.3579 -384.475228)
		(width 0.14224)
		(layer "In13.Cu")
		(net "P5E_CPU0_P0_RX_DN<6>")
	)
	(segment
		(start 319.411604 -376.002042)
		(end 327.514966 -376.002042)
		(width 0.14224)
		(layer "In13.Cu")
		(net "P5E_CPU0_P0_RX_DN<6>")
	)
	(segment
		(start 375.05894 -384.475228)
		(end 375.48566 -384.475228)
		(width 0.14224)
		(layer "In13.Cu")
		(net "P5E_CPU0_P0_RX_DN<6>")
	)
	(segment
		(start 350.80829 -277.813516)
		(end 350.769174 -277.790656)
		(width 0.1143)
		(layer "In13.Cu")
		(net "P5E_CPU0_P0_RX_DN<6>")
	)
	(segment
		(start 310.990996 -393.69238)
		(end 311.34431 -393.787376)
		(width 0.14224)
		(layer "In13.Cu")
		(net "P5E_CPU0_P0_RX_DN<6>")
	)
	(segment
		(start 350.83877 -277.831296)
		(end 350.80829 -277.813516)
		(width 0.1143)
		(layer "In13.Cu")
		(net "P5E_CPU0_P0_RX_DN<6>")
	)
	(segment
		(start 350.769174 -286.581342)
		(end 350.80829 -286.558482)
		(width 0.1143)
		(layer "In13.Cu")
		(net "P5E_CPU0_P0_RX_DN<6>")
	)
	(segment
		(start 343.464388 -386.666486)
		(end 343.464388 -386.094986)
		(width 0.14224)
		(layer "In13.Cu")
		(net "P5E_CPU0_P0_RX_DN<6>")
	)
	(segment
		(start 350.83877 -292.41115)
		(end 350.769174 -292.37051)
		(width 0.1143)
		(layer "In13.Cu")
		(net "P5E_CPU0_P0_RX_DN<6>")
	)
	(segment
		(start 350.692974 -294.734234)
		(end 350.80829 -294.658542)
		(width 0.1143)
		(layer "In13.Cu")
		(net "P5E_CPU0_P0_RX_DN<6>")
	)
	(segment
		(start 350.80829 -284.938724)
		(end 350.83877 -284.920944)
		(width 0.1143)
		(layer "In13.Cu")
		(net "P5E_CPU0_P0_RX_DN<6>")
	)
	(segment
		(start 350.769174 -275.241512)
		(end 350.80829 -275.218652)
		(width 0.1143)
		(layer "In13.Cu")
		(net "P5E_CPU0_P0_RX_DN<6>")
	)
	(segment
		(start 350.83877 -282.691332)
		(end 350.769174 -282.650692)
		(width 0.1143)
		(layer "In13.Cu")
		(net "P5E_CPU0_P0_RX_DN<6>")
	)
	(segment
		(start 350.769174 -280.101548)
		(end 350.80829 -280.078688)
		(width 0.1143)
		(layer "In13.Cu")
		(net "P5E_CPU0_P0_RX_DN<6>")
	)
	(segment
		(start 338.031328 -385.952746)
		(end 337.723988 -385.645406)
		(width 0.14224)
		(layer "In13.Cu")
		(net "P5E_CPU0_P0_RX_DN<6>")
	)
	(segment
		(start 350.83877 -276.211284)
		(end 350.80829 -276.193504)
		(width 0.1143)
		(layer "In13.Cu")
		(net "P5E_CPU0_P0_RX_DN<6>")
	)
	(segment
		(start 376.75058 -384.612388)
		(end 383.14122 -384.612388)
		(width 0.14224)
		(layer "In13.Cu")
		(net "P5E_CPU0_P0_RX_DN<6>")
	)
	(segment
		(start 350.83877 -284.311344)
		(end 350.769174 -284.270704)
		(width 0.1143)
		(layer "In13.Cu")
		(net "P5E_CPU0_P0_RX_DN<6>")
	)
	(segment
		(start 311.154318 -392.616944)
		(end 311.458356 -392.31316)
		(width 0.14224)
		(layer "In13.Cu")
		(net "P5E_CPU0_P0_RX_DN<6>")
	)
	(segment
		(start 350.80829 -280.078688)
		(end 350.83877 -280.060908)
		(width 0.1143)
		(layer "In13.Cu")
		(net "P5E_CPU0_P0_RX_DN<6>")
	)
	(segment
		(start 386.437124 -378.120656)
		(end 386.768594 -377.789186)
		(width 0.14224)
		(layer "In13.Cu")
		(net "P5E_CPU0_P0_RX_DN<6>")
	)
	(segment
		(start 336.868008 -385.093972)
		(end 336.868008 -386.666486)
		(width 0.14224)
		(layer "In13.Cu")
		(net "P5E_CPU0_P0_RX_DN<6>")
	)
	(segment
		(start 387.765798 -371.461284)
		(end 363.658912 -313.2836)
		(width 0.14224)
		(layer "In13.Cu")
		(net "P5E_CPU0_P0_RX_DN<6>")
	)
	(segment
		(start 357.780336 -384.30962)
		(end 359.73385 -382.355344)
		(width 0.14224)
		(layer "In13.Cu")
		(net "P5E_CPU0_P0_RX_DN<6>")
	)
	(segment
		(start 311.458356 -392.31316)
		(end 311.458356 -390.552686)
		(width 0.14224)
		(layer "In13.Cu")
		(net "P5E_CPU0_P0_RX_DN<6>")
	)
	(segment
		(start 350.80829 -279.433528)
		(end 350.769174 -279.410668)
		(width 0.1143)
		(layer "In13.Cu")
		(net "P5E_CPU0_P0_RX_DN<6>")
	)
	(segment
		(start 351.017586 -297.52544)
		(end 351.017586 -296.612564)
		(width 0.14224)
		(layer "In13.Cu")
		(net "P5E_CPU0_P0_RX_DN<6>")
	)
	(segment
		(start 376.61342 -384.475228)
		(end 376.75058 -384.612388)
		(width 0.14224)
		(layer "In13.Cu")
		(net "P5E_CPU0_P0_RX_DN<6>")
	)
	(segment
		(start 350.769174 -278.481536)
		(end 350.80829 -278.458676)
		(width 0.1143)
		(layer "In13.Cu")
		(net "P5E_CPU0_P0_RX_DN<6>")
	)
	(segment
		(start 350.80829 -281.05354)
		(end 350.769174 -281.03068)
		(width 0.1143)
		(layer "In13.Cu")
		(net "P5E_CPU0_P0_RX_DN<6>")
	)
	(segment
		(start 311.149492 -393.22883)
		(end 311.154318 -392.616944)
		(width 0.14224)
		(layer "In13.Cu")
		(net "P5E_CPU0_P0_RX_DN<6>")
	)
	(segment
		(start 351.017332 -296.61231)
		(end 351.017332 -296.583862)
		(width 0.1143)
		(layer "In13.Cu")
		(net "P5E_CPU0_P0_RX_DN<6>")
	)
	(segment
		(start 351.74301 -271.981676)
		(end 351.747582 -271.978882)
		(width 0.1143)
		(layer "In13.Cu")
		(net "P5E_CPU0_P0_RX_DN<6>")
	)
	(segment
		(start 351.742248 -271.982184)
		(end 351.74301 -271.981676)
		(width 0.1143)
		(layer "In13.Cu")
		(net "P5E_CPU0_P0_RX_DN<6>")
	)
	(segment
		(start 343.322148 -386.808726)
		(end 343.464388 -386.666486)
		(width 0.14224)
		(layer "In13.Cu")
		(net "P5E_CPU0_P0_RX_DN<6>")
	)
	(segment
		(start 387.765798 -374.464834)
		(end 387.765798 -371.461284)
		(width 0.14224)
		(layer "In13.Cu")
		(net "P5E_CPU0_P0_RX_DN<6>")
	)
	(segment
		(start 351.017332 -296.583862)
		(end 351.063052 -296.538142)
		(width 0.1143)
		(layer "In13.Cu")
		(net "P5E_CPU0_P0_RX_DN<6>")
	)
	(segment
		(start 350.769174 -293.06139)
		(end 350.83877 -293.02075)
		(width 0.1143)
		(layer "In13.Cu")
		(net "P5E_CPU0_P0_RX_DN<6>")
	)
	(segment
		(start 311.34431 -393.787376)
		(end 311.344818 -393.786868)
		(width 0.14224)
		(layer "In13.Cu")
		(net "P5E_CPU0_P0_RX_DN<6>")
	)
	(segment
		(start 350.80829 -274.573492)
		(end 350.769174 -274.550632)
		(width 0.1143)
		(layer "In13.Cu")
		(net "P5E_CPU0_P0_RX_DN<6>")
	)
	(segment
		(start 351.063052 -296.538142)
		(end 351.063052 -296.192956)
		(width 0.1143)
		(layer "In13.Cu")
		(net "P5E_CPU0_P0_RX_DN<6>")
	)
	(segment
		(start 383.41173 -384.341878)
		(end 383.41173 -381.67691)
		(width 0.14224)
		(layer "In13.Cu")
		(net "P5E_CPU0_P0_RX_DN<6>")
	)
	(segment
		(start 350.80829 -276.193504)
		(end 350.769174 -276.170644)
		(width 0.1143)
		(layer "In13.Cu")
		(net "P5E_CPU0_P0_RX_DN<6>")
	)
	(segment
		(start 350.769174 -283.341572)
		(end 350.80829 -283.318712)
		(width 0.1143)
		(layer "In13.Cu")
		(net "P5E_CPU0_P0_RX_DN<6>")
	)
	(segment
		(start 350.80829 -285.913576)
		(end 350.769174 -285.890716)
		(width 0.1143)
		(layer "In13.Cu")
		(net "P5E_CPU0_P0_RX_DN<6>")
	)
	(segment
		(start 336.868008 -386.666486)
		(end 337.010248 -386.808726)
		(width 0.14224)
		(layer "In13.Cu")
		(net "P5E_CPU0_P0_RX_DN<6>")
	)
	(segment
		(start 350.80829 -288.178494)
		(end 350.840802 -288.159698)
		(width 0.1143)
		(layer "In13.Cu")
		(net "P5E_CPU0_P0_RX_DN<6>")
	)
	(segment
		(start 350.769174 -289.821366)
		(end 350.83877 -289.780726)
		(width 0.1143)
		(layer "In13.Cu")
		(net "P5E_CPU0_P0_RX_DN<6>")
	)
	(segment
		(start 350.80829 -289.153346)
		(end 350.769174 -289.130486)
		(width 0.1143)
		(layer "In13.Cu")
		(net "P5E_CPU0_P0_RX_DN<6>")
	)
	(segment
		(start 365.80572 -382.69799)
		(end 367.648236 -384.540506)
		(width 0.14224)
		(layer "In13.Cu")
		(net "P5E_CPU0_P0_RX_DN<6>")
	)
	(segment
		(start 311.344818 -393.786868)
		(end 311.466484 -393.716764)
		(width 0.14224)
		(layer "In13.Cu")
		(net "P5E_CPU0_P0_RX_DN<6>")
	)
	(segment
		(start 311.497472 -390.377934)
		(end 317.41872 -377.85929)
		(width 0.14224)
		(layer "In13.Cu")
		(net "P5E_CPU0_P0_RX_DN<6>")
	)
	(segment
		(start 351.239074 -272.811494)
		(end 351.282508 -272.786348)
		(width 0.1143)
		(layer "In13.Cu")
		(net "P5E_CPU0_P0_RX_DN<6>")
	)
	(segment
		(start 363.658912 -313.2836)
		(end 351.24263 -298.15536)
		(width 0.14224)
		(layer "In13.Cu")
		(net "P5E_CPU0_P0_RX_DN<6>")
	)
	(segment
		(start 351.017586 -296.612564)
		(end 351.017332 -296.61231)
		(width 0.1143)
		(layer "In13.Cu")
		(net "P5E_CPU0_P0_RX_DN<6>")
	)
	(segment
		(start 351.929192 -271.726152)
		(end 351.859088 -271.656048)
		(width 0.1143)
		(layer "In13.Cu")
		(net "P5E_CPU0_P0_RX_DN<6>")
	)
	(segment
		(start 337.010248 -386.808726)
		(end 343.322148 -386.808726)
		(width 0.14224)
		(layer "In13.Cu")
		(net "P5E_CPU0_P0_RX_DN<6>")
	)
	(segment
		(start 343.322148 -385.952746)
		(end 338.031328 -385.952746)
		(width 0.14224)
		(layer "In13.Cu")
		(net "P5E_CPU0_P0_RX_DN<6>")
	)
	(segment
		(start 350.525842 -295.524174)
		(end 350.525842 -295.053258)
		(width 0.1143)
		(layer "In13.Cu")
		(net "P5E_CPU0_P0_RX_DN<6>")
	)
	(segment
		(start 350.80829 -294.658542)
		(end 350.83877 -294.640762)
		(width 0.1143)
		(layer "In13.Cu")
		(net "P5E_CPU0_P0_RX_DN<6>")
	)
	(segment
		(start 350.80829 -278.458676)
		(end 350.83877 -278.440896)
		(width 0.1143)
		(layer "In13.Cu")
		(net "P5E_CPU0_P0_RX_DN<6>")
	)
	(segment
		(start 385.37642 -378.907802)
		(end 385.51993 -378.764546)
		(width 0.14224)
		(layer "In13.Cu")
		(net "P5E_CPU0_P0_RX_DN<6>")
	)
	(segment
		(start 350.769174 -273.6215)
		(end 350.80829 -273.59864)
		(width 0.1143)
		(layer "In13.Cu")
		(net "P5E_CPU0_P0_RX_DN<6>")
	)
	(arc
		(start 351.77984 -271.960086)
		(mid 351.876981 -271.85746)
		(end 351.929192 -271.726152)
		(width 0.1143)
		(layer "In13.Cu")
		(net "P5E_CPU0_P0_RX_DN<6>")
	)
	(arc
		(start 351.24263 -298.15536)
		(mid 351.075483 -297.859919)
		(end 351.017586 -297.52544)
		(width 0.14224)
		(layer "In13.Cu")
		(net "P5E_CPU0_P0_RX_DN<6>")
	)
	(arc
		(start 350.525842 -295.053258)
		(mid 350.57017 -294.873201)
		(end 350.692974 -294.734234)
		(width 0.1143)
		(layer "In13.Cu")
		(net "P5E_CPU0_P0_RX_DN<6>")
	)
	(arc
		(start 350.995742 -287.856168)
		(mid 350.954193 -287.684746)
		(end 350.83877 -287.551368)
		(width 0.1143)
		(layer "In13.Cu")
		(net "P5E_CPU0_P0_RX_DN<6>")
	)
	(arc
		(start 350.83877 -275.200872)
		(mid 350.995747 -274.896072)
		(end 350.83877 -274.591272)
		(width 0.1143)
		(layer "In13.Cu")
		(net "P5E_CPU0_P0_RX_DN<6>")
	)
	(arc
		(start 350.83877 -283.300932)
		(mid 350.995747 -282.996132)
		(end 350.83877 -282.691332)
		(width 0.1143)
		(layer "In13.Cu")
		(net "P5E_CPU0_P0_RX_DN<6>")
	)
	(arc
		(start 331.754226 -383.914904)
		(mid 332.1013 -384.337963)
		(end 332.624938 -384.496818)
		(width 0.14224)
		(layer "In13.Cu")
		(net "P5E_CPU0_P0_RX_DN<6>")
	)
	(arc
		(start 350.769174 -281.03068)
		(mid 350.525847 -280.566114)
		(end 350.769174 -280.101548)
		(width 0.1143)
		(layer "In13.Cu")
		(net "P5E_CPU0_P0_RX_DN<6>")
	)
	(arc
		(start 350.769174 -292.37051)
		(mid 350.525847 -291.905944)
		(end 350.769174 -291.441378)
		(width 0.1143)
		(layer "In13.Cu")
		(net "P5E_CPU0_P0_RX_DN<6>")
	)
	(arc
		(start 350.83877 -276.820884)
		(mid 350.995747 -276.516084)
		(end 350.83877 -276.211284)
		(width 0.1143)
		(layer "In13.Cu")
		(net "P5E_CPU0_P0_RX_DN<6>")
	)
	(arc
		(start 336.74812 -384.804666)
		(mid 336.836864 -384.937386)
		(end 336.868008 -385.093972)
		(width 0.14224)
		(layer "In13.Cu")
		(net "P5E_CPU0_P0_RX_DN<6>")
	)
	(arc
		(start 367.648236 -384.540506)
		(mid 367.727685 -384.593719)
		(end 367.821464 -384.612388)
		(width 0.14224)
		(layer "In13.Cu")
		(net "P5E_CPU0_P0_RX_DN<6>")
	)
	(arc
		(start 350.769174 -289.130486)
		(mid 350.525847 -288.66592)
		(end 350.769174 -288.201354)
		(width 0.1143)
		(layer "In13.Cu")
		(net "P5E_CPU0_P0_RX_DN<6>")
	)
	(arc
		(start 383.723642 -381.160782)
		(mid 383.901657 -381.088884)
		(end 384.090418 -381.053848)
		(width 0.14224)
		(layer "In13.Cu")
		(net "P5E_CPU0_P0_RX_DN<6>")
	)
	(arc
		(start 350.83877 -273.58086)
		(mid 350.954197 -273.447484)
		(end 350.995742 -273.27606)
		(width 0.1143)
		(layer "In13.Cu")
		(net "P5E_CPU0_P0_RX_DN<6>")
	)
	(arc
		(start 350.83877 -278.440896)
		(mid 350.995747 -278.136096)
		(end 350.83877 -277.831296)
		(width 0.1143)
		(layer "In13.Cu")
		(net "P5E_CPU0_P0_RX_DN<6>")
	)
	(arc
		(start 350.771714 -287.512252)
		(mid 350.591062 -287.309507)
		(end 350.525842 -287.045908)
		(width 0.1143)
		(layer "In13.Cu")
		(net "P5E_CPU0_P0_RX_DN<6>")
	)
	(arc
		(start 357.457502 -384.532886)
		(mid 357.520986 -384.522252)
		(end 357.57739 -384.49123)
		(width 0.14224)
		(layer "In13.Cu")
		(net "P5E_CPU0_P0_RX_DN<6>")
	)
	(arc
		(start 357.57739 -384.49123)
		(mid 357.681433 -384.403297)
		(end 357.780336 -384.30962)
		(width 0.14224)
		(layer "In13.Cu")
		(net "P5E_CPU0_P0_RX_DN<6>")
	)
	(arc
		(start 350.83877 -284.920944)
		(mid 350.995747 -284.616144)
		(end 350.83877 -284.311344)
		(width 0.1143)
		(layer "In13.Cu")
		(net "P5E_CPU0_P0_RX_DN<6>")
	)
	(arc
		(start 327.514966 -376.002042)
		(mid 328.314552 -376.244774)
		(end 328.844656 -376.890788)
		(width 0.14224)
		(layer "In13.Cu")
		(net "P5E_CPU0_P0_RX_DN<6>")
	)
	(arc
		(start 350.769174 -277.790656)
		(mid 350.525847 -277.32609)
		(end 350.769174 -276.861524)
		(width 0.1143)
		(layer "In13.Cu")
		(net "P5E_CPU0_P0_RX_DN<6>")
	)
	(arc
		(start 350.769174 -293.990522)
		(mid 350.525847 -293.525956)
		(end 350.769174 -293.06139)
		(width 0.1143)
		(layer "In13.Cu")
		(net "P5E_CPU0_P0_RX_DN<6>")
	)
	(arc
		(start 386.768594 -377.789186)
		(mid 386.803556 -377.736861)
		(end 386.815838 -377.67514)
		(width 0.14224)
		(layer "In13.Cu")
		(net "P5E_CPU0_P0_RX_DN<6>")
	)
	(arc
		(start 350.769174 -290.750498)
		(mid 350.525847 -290.285932)
		(end 350.769174 -289.821366)
		(width 0.1143)
		(layer "In13.Cu")
		(net "P5E_CPU0_P0_RX_DN<6>")
	)
	(arc
		(start 350.769174 -282.650692)
		(mid 350.525847 -282.186126)
		(end 350.769174 -281.72156)
		(width 0.1143)
		(layer "In13.Cu")
		(net "P5E_CPU0_P0_RX_DN<6>")
	)
	(arc
		(start 311.458356 -390.552686)
		(mid 311.468218 -390.463137)
		(end 311.497472 -390.377934)
		(width 0.14224)
		(layer "In13.Cu")
		(net "P5E_CPU0_P0_RX_DN<6>")
	)
	(arc
		(start 350.83877 -294.640762)
		(mid 350.995747 -294.335962)
		(end 350.83877 -294.031162)
		(width 0.1143)
		(layer "In13.Cu")
		(net "P5E_CPU0_P0_RX_DN<6>")
	)
	(arc
		(start 383.14122 -384.612388)
		(mid 383.332499 -384.533157)
		(end 383.41173 -384.341878)
		(width 0.14224)
		(layer "In13.Cu")
		(net "P5E_CPU0_P0_RX_DN<6>")
	)
	(arc
		(start 384.090418 -381.053848)
		(mid 384.482396 -380.950025)
		(end 384.814826 -380.717806)
		(width 0.14224)
		(layer "In13.Cu")
		(net "P5E_CPU0_P0_RX_DN<6>")
	)
	(arc
		(start 386.382006 -378.165868)
		(mid 386.410674 -378.144614)
		(end 386.437124 -378.120656)
		(width 0.14224)
		(layer "In13.Cu")
		(net "P5E_CPU0_P0_RX_DN<6>")
	)
	(arc
		(start 385.127246 -379.509274)
		(mid 385.191998 -379.183746)
		(end 385.37642 -378.907802)
		(width 0.14224)
		(layer "In13.Cu")
		(net "P5E_CPU0_P0_RX_DN<6>")
	)
	(arc
		(start 350.995742 -273.27606)
		(mid 351.060257 -273.013841)
		(end 351.239074 -272.811494)
		(width 0.1143)
		(layer "In13.Cu")
		(net "P5E_CPU0_P0_RX_DN<6>")
	)
	(arc
		(start 350.840802 -286.539686)
		(mid 350.954731 -286.406539)
		(end 350.995742 -286.236156)
		(width 0.1143)
		(layer "In13.Cu")
		(net "P5E_CPU0_P0_RX_DN<6>")
	)
	(arc
		(start 364.689136 -382.235456)
		(mid 365.293438 -382.355659)
		(end 365.80572 -382.69799)
		(width 0.14224)
		(layer "In13.Cu")
		(net "P5E_CPU0_P0_RX_DN<6>")
	)
	(arc
		(start 351.46869 -272.462498)
		(mid 351.541813 -272.186084)
		(end 351.742248 -271.982184)
		(width 0.1143)
		(layer "In13.Cu")
		(net "P5E_CPU0_P0_RX_DN<6>")
	)
	(arc
		(start 350.769174 -274.550632)
		(mid 350.525847 -274.086066)
		(end 350.769174 -273.6215)
		(width 0.1143)
		(layer "In13.Cu")
		(net "P5E_CPU0_P0_RX_DN<6>")
	)
	(arc
		(start 350.83877 -289.780726)
		(mid 350.995747 -289.475926)
		(end 350.83877 -289.171126)
		(width 0.1143)
		(layer "In13.Cu")
		(net "P5E_CPU0_P0_RX_DN<6>")
	)
	(arc
		(start 350.769174 -284.270704)
		(mid 350.525847 -283.806138)
		(end 350.769174 -283.341572)
		(width 0.1143)
		(layer "In13.Cu")
		(net "P5E_CPU0_P0_RX_DN<6>")
	)
	(arc
		(start 385.51993 -378.764546)
		(mid 385.586972 -378.703486)
		(end 385.65963 -378.64923)
		(width 0.14224)
		(layer "In13.Cu")
		(net "P5E_CPU0_P0_RX_DN<6>")
	)
	(arc
		(start 350.83877 -281.68092)
		(mid 350.995747 -281.37612)
		(end 350.83877 -281.07132)
		(width 0.1143)
		(layer "In13.Cu")
		(net "P5E_CPU0_P0_RX_DN<6>")
	)
	(arc
		(start 350.769174 -276.170644)
		(mid 350.525847 -275.706078)
		(end 350.769174 -275.241512)
		(width 0.1143)
		(layer "In13.Cu")
		(net "P5E_CPU0_P0_RX_DN<6>")
	)
	(arc
		(start 350.83877 -280.060908)
		(mid 350.995747 -279.756108)
		(end 350.83877 -279.451308)
		(width 0.1143)
		(layer "In13.Cu")
		(net "P5E_CPU0_P0_RX_DN<6>")
	)
	(arc
		(start 350.769174 -285.890716)
		(mid 350.525847 -285.42615)
		(end 350.769174 -284.961584)
		(width 0.1143)
		(layer "In13.Cu")
		(net "P5E_CPU0_P0_RX_DN<6>")
	)
	(arc
		(start 351.282508 -272.786348)
		(mid 351.418861 -272.649287)
		(end 351.46869 -272.462498)
		(width 0.1143)
		(layer "In13.Cu")
		(net "P5E_CPU0_P0_RX_DN<6>")
	)
	(arc
		(start 350.525842 -287.045908)
		(mid 350.590357 -286.783689)
		(end 350.769174 -286.581342)
		(width 0.1143)
		(layer "In13.Cu")
		(net "P5E_CPU0_P0_RX_DN<6>")
	)
	(arc
		(start 350.83877 -291.400738)
		(mid 350.995747 -291.095938)
		(end 350.83877 -290.791138)
		(width 0.1143)
		(layer "In13.Cu")
		(net "P5E_CPU0_P0_RX_DN<6>")
	)
	(arc
		(start 319.122044 -376.12193)
		(mid 319.254909 -376.033215)
		(end 319.411604 -376.002042)
		(width 0.14224)
		(layer "In13.Cu")
		(net "P5E_CPU0_P0_RX_DN<6>")
	)
	(arc
		(start 350.995742 -286.236156)
		(mid 350.954193 -286.064734)
		(end 350.83877 -285.931356)
		(width 0.1143)
		(layer "In13.Cu")
		(net "P5E_CPU0_P0_RX_DN<6>")
	)
	(arc
		(start 359.73385 -382.355344)
		(mid 359.86657 -382.2666)
		(end 360.023156 -382.235456)
		(width 0.14224)
		(layer "In13.Cu")
		(net "P5E_CPU0_P0_RX_DN<6>")
	)
	(arc
		(start 383.41173 -381.67691)
		(mid 383.495769 -381.375389)
		(end 383.723642 -381.160782)
		(width 0.14224)
		(layer "In13.Cu")
		(net "P5E_CPU0_P0_RX_DN<6>")
	)
	(arc
		(start 350.61906 -295.748964)
		(mid 350.550094 -295.645844)
		(end 350.525842 -295.524174)
		(width 0.1143)
		(layer "In13.Cu")
		(net "P5E_CPU0_P0_RX_DN<6>")
	)
	(arc
		(start 350.83877 -293.02075)
		(mid 350.995747 -292.71595)
		(end 350.83877 -292.41115)
		(width 0.1143)
		(layer "In13.Cu")
		(net "P5E_CPU0_P0_RX_DN<6>")
	)
	(arc
		(start 336.2706 -384.496818)
		(mid 336.427303 -384.52797)
		(end 336.56016 -384.616706)
		(width 0.14224)
		(layer "In13.Cu")
		(net "P5E_CPU0_P0_RX_DN<6>")
	)
	(arc
		(start 350.840802 -288.159698)
		(mid 350.954731 -288.026551)
		(end 350.995742 -287.856168)
		(width 0.1143)
		(layer "In13.Cu")
		(net "P5E_CPU0_P0_RX_DN<6>")
	)
	(arc
		(start 385.089908 -380.442724)
		(mid 385.117527 -380.401484)
		(end 385.127246 -380.352808)
		(width 0.14224)
		(layer "In13.Cu")
		(net "P5E_CPU0_P0_RX_DN<6>")
	)
	(arc
		(start 350.769174 -279.410668)
		(mid 350.525847 -278.946102)
		(end 350.769174 -278.481536)
		(width 0.1143)
		(layer "In13.Cu")
		(net "P5E_CPU0_P0_RX_DN<6>")
	)
	(arc
		(start 317.41872 -377.85929)
		(mid 317.454022 -377.798408)
		(end 317.499238 -377.744482)
		(width 0.14224)
		(layer "In13.Cu")
		(net "P5E_CPU0_P0_RX_DN<6>")
	)
	(segment
		(start 349.20809 -269.770098)
		(end 348.741238 -270.036036)
		(width 0.12954)
		(layer "F.Cu")
		(net "P5E_CPU0_P0_RX_DN<5>")
	)
	(segment
		(start 309.2704 -393.69238)
		(end 309.7911 -393.69238)
		(width 0.127)
		(layer "F.Cu")
		(net "P5E_CPU0_P0_RX_DN<5>")
	)
	(segment
		(start 373.708676 -374.20677)
		(end 370.051584 -374.20677)
		(width 0.14224)
		(layer "In13.Cu")
		(net "P5E_CPU0_P0_RX_DN<5>")
	)
	(segment
		(start 382.693164 -373.43842)
		(end 382.693164 -373.244364)
		(width 0.14224)
		(layer "In13.Cu")
		(net "P5E_CPU0_P0_RX_DN<5>")
	)
	(segment
		(start 360.57078 -375.37009)
		(end 360.87812 -375.06275)
		(width 0.14224)
		(layer "In13.Cu")
		(net "P5E_CPU0_P0_RX_DN<5>")
	)
	(segment
		(start 369.354608 -372.78691)
		(end 373.708676 -372.78691)
		(width 0.14224)
		(layer "In13.Cu")
		(net "P5E_CPU0_P0_RX_DN<5>")
	)
	(segment
		(start 349.899986 -292.411912)
		(end 349.830644 -292.371526)
		(width 0.1143)
		(layer "In13.Cu")
		(net "P5E_CPU0_P0_RX_DN<5>")
	)
	(segment
		(start 374.016016 -373.89943)
		(end 373.708676 -374.20677)
		(width 0.14224)
		(layer "In13.Cu")
		(net "P5E_CPU0_P0_RX_DN<5>")
	)
	(segment
		(start 373.708676 -372.78691)
		(end 374.016016 -373.09425)
		(width 0.14224)
		(layer "In13.Cu")
		(net "P5E_CPU0_P0_RX_DN<5>")
	)
	(segment
		(start 366.191292 -377.19635)
		(end 366.191292 -376.62485)
		(width 0.14224)
		(layer "In13.Cu")
		(net "P5E_CPU0_P0_RX_DN<5>")
	)
	(segment
		(start 366.049052 -376.48261)
		(end 360.87812 -376.48261)
		(width 0.14224)
		(layer "In13.Cu")
		(net "P5E_CPU0_P0_RX_DN<5>")
	)
	(segment
		(start 383.189226 -372.942358)
		(end 383.494788 -372.636796)
		(width 0.14224)
		(layer "In13.Cu")
		(net "P5E_CPU0_P0_RX_DN<5>")
	)
	(segment
		(start 349.82912 -283.341572)
		(end 349.868236 -283.318712)
		(width 0.1143)
		(layer "In13.Cu")
		(net "P5E_CPU0_P0_RX_DN<5>")
	)
	(segment
		(start 359.85704 -377.33859)
		(end 366.049052 -377.33859)
		(width 0.14224)
		(layer "In13.Cu")
		(net "P5E_CPU0_P0_RX_DN<5>")
	)
	(segment
		(start 349.868236 -275.218652)
		(end 349.898716 -275.200872)
		(width 0.1143)
		(layer "In13.Cu")
		(net "P5E_CPU0_P0_RX_DN<5>")
	)
	(segment
		(start 367.078768 -375.06275)
		(end 369.354608 -372.78691)
		(width 0.14224)
		(layer "In13.Cu")
		(net "P5E_CPU0_P0_RX_DN<5>")
	)
	(segment
		(start 309.3085 -382.022604)
		(end 313.719718 -375.421398)
		(width 0.14224)
		(layer "In13.Cu")
		(net "P5E_CPU0_P0_RX_DN<5>")
	)
	(segment
		(start 349.82912 -281.72156)
		(end 349.868236 -281.6987)
		(width 0.1143)
		(layer "In13.Cu")
		(net "P5E_CPU0_P0_RX_DN<5>")
	)
	(segment
		(start 349.868236 -279.433528)
		(end 349.82912 -279.410668)
		(width 0.1143)
		(layer "In13.Cu")
		(net "P5E_CPU0_P0_RX_DN<5>")
	)
	(segment
		(start 349.899986 -289.171888)
		(end 349.830644 -289.131502)
		(width 0.1143)
		(layer "In13.Cu")
		(net "P5E_CPU0_P0_RX_DN<5>")
	)
	(segment
		(start 349.898716 -276.211284)
		(end 349.868236 -276.193504)
		(width 0.1143)
		(layer "In13.Cu")
		(net "P5E_CPU0_P0_RX_DN<5>")
	)
	(segment
		(start 359.7148 -377.19635)
		(end 359.85704 -377.33859)
		(width 0.14224)
		(layer "In13.Cu")
		(net "P5E_CPU0_P0_RX_DN<5>")
	)
	(segment
		(start 349.377254 -270.512794)
		(end 349.37446 -270.510254)
		(width 0.1143)
		(layer "In13.Cu")
		(net "P5E_CPU0_P0_RX_DN<5>")
	)
	(segment
		(start 349.868236 -283.318712)
		(end 349.898716 -283.300932)
		(width 0.1143)
		(layer "In13.Cu")
		(net "P5E_CPU0_P0_RX_DN<5>")
	)
	(segment
		(start 309.23992 -384.588512)
		(end 309.23992 -382.249934)
		(width 0.14224)
		(layer "In13.Cu")
		(net "P5E_CPU0_P0_RX_DN<5>")
	)
	(segment
		(start 310.144922 -393.786868)
		(end 310.266588 -393.716764)
		(width 0.14224)
		(layer "In13.Cu")
		(net "P5E_CPU0_P0_RX_DN<5>")
	)
	(segment
		(start 349.03918 -270.036036)
		(end 348.741238 -270.036036)
		(width 0.1143)
		(layer "In13.Cu")
		(net "P5E_CPU0_P0_RX_DN<5>")
	)
	(segment
		(start 349.868236 -273.59864)
		(end 349.898716 -273.58086)
		(width 0.1143)
		(layer "In13.Cu")
		(net "P5E_CPU0_P0_RX_DN<5>")
	)
	(segment
		(start 309.7911 -393.69238)
		(end 310.144414 -393.787376)
		(width 0.14224)
		(layer "In13.Cu")
		(net "P5E_CPU0_P0_RX_DN<5>")
	)
	(segment
		(start 349.899986 -295.651936)
		(end 349.83039 -295.61155)
		(width 0.1143)
		(layer "In13.Cu")
		(net "P5E_CPU0_P0_RX_DN<5>")
	)
	(segment
		(start 349.868236 -278.458676)
		(end 349.898716 -278.440896)
		(width 0.1143)
		(layer "In13.Cu")
		(net "P5E_CPU0_P0_RX_DN<5>")
	)
	(segment
		(start 349.82912 -280.101548)
		(end 349.868236 -280.078688)
		(width 0.1143)
		(layer "In13.Cu")
		(net "P5E_CPU0_P0_RX_DN<5>")
	)
	(segment
		(start 349.830644 -293.060374)
		(end 349.899986 -293.019988)
		(width 0.1143)
		(layer "In13.Cu")
		(net "P5E_CPU0_P0_RX_DN<5>")
	)
	(segment
		(start 369.909344 -374.92051)
		(end 370.051584 -375.06275)
		(width 0.14224)
		(layer "In13.Cu")
		(net "P5E_CPU0_P0_RX_DN<5>")
	)
	(segment
		(start 349.897954 -287.550606)
		(end 349.830644 -287.51149)
		(width 0.1143)
		(layer "In13.Cu")
		(net "P5E_CPU0_P0_RX_DN<5>")
	)
	(segment
		(start 349.82912 -278.481536)
		(end 349.868236 -278.458676)
		(width 0.1143)
		(layer "In13.Cu")
		(net "P5E_CPU0_P0_RX_DN<5>")
	)
	(segment
		(start 385.5847 -368.74704)
		(end 362.872782 -313.914282)
		(width 0.14224)
		(layer "In13.Cu")
		(net "P5E_CPU0_P0_RX_DN<5>")
	)
	(segment
		(start 349.404178 -270.528288)
		(end 349.400876 -270.52651)
		(width 0.1143)
		(layer "In13.Cu")
		(net "P5E_CPU0_P0_RX_DN<5>")
	)
	(segment
		(start 349.828358 -286.581596)
		(end 349.899732 -286.540194)
		(width 0.1143)
		(layer "In13.Cu")
		(net "P5E_CPU0_P0_RX_DN<5>")
	)
	(segment
		(start 349.82912 -284.961584)
		(end 349.868236 -284.938724)
		(width 0.1143)
		(layer "In13.Cu")
		(net "P5E_CPU0_P0_RX_DN<5>")
	)
	(segment
		(start 356.223062 -375.06275)
		(end 359.40746 -375.06275)
		(width 0.14224)
		(layer "In13.Cu")
		(net "P5E_CPU0_P0_RX_DN<5>")
	)
	(segment
		(start 366.049052 -377.33859)
		(end 366.191292 -377.19635)
		(width 0.14224)
		(layer "In13.Cu")
		(net "P5E_CPU0_P0_RX_DN<5>")
	)
	(segment
		(start 349.868236 -277.813516)
		(end 349.82912 -277.790656)
		(width 0.1143)
		(layer "In13.Cu")
		(net "P5E_CPU0_P0_RX_DN<5>")
	)
	(segment
		(start 383.494788 -372.636796)
		(end 383.494788 -372.442994)
		(width 0.14224)
		(layer "In13.Cu")
		(net "P5E_CPU0_P0_RX_DN<5>")
	)
	(segment
		(start 349.868236 -271.978628)
		(end 349.898716 -271.960848)
		(width 0.1143)
		(layer "In13.Cu")
		(net "P5E_CPU0_P0_RX_DN<5>")
	)
	(segment
		(start 349.399606 -270.525748)
		(end 349.377254 -270.512794)
		(width 0.1143)
		(layer "In13.Cu")
		(net "P5E_CPU0_P0_RX_DN<5>")
	)
	(segment
		(start 349.868236 -274.573492)
		(end 349.82912 -274.550632)
		(width 0.1143)
		(layer "In13.Cu")
		(net "P5E_CPU0_P0_RX_DN<5>")
	)
	(segment
		(start 374.016016 -373.09425)
		(end 374.016016 -373.89943)
		(width 0.14224)
		(layer "In13.Cu")
		(net "P5E_CPU0_P0_RX_DN<5>")
	)
	(segment
		(start 349.898716 -272.97126)
		(end 349.868236 -272.95348)
		(width 0.1143)
		(layer "In13.Cu")
		(net "P5E_CPU0_P0_RX_DN<5>")
	)
	(segment
		(start 360.87812 -376.48261)
		(end 360.57078 -376.17527)
		(width 0.14224)
		(layer "In13.Cu")
		(net "P5E_CPU0_P0_RX_DN<5>")
	)
	(segment
		(start 349.899986 -285.932118)
		(end 349.82912 -285.890716)
		(width 0.1143)
		(layer "In13.Cu")
		(net "P5E_CPU0_P0_RX_DN<5>")
	)
	(segment
		(start 349.82912 -272.001488)
		(end 349.868236 -271.978628)
		(width 0.1143)
		(layer "In13.Cu")
		(net "P5E_CPU0_P0_RX_DN<5>")
	)
	(segment
		(start 350.010222 -296.436034)
		(end 350.010222 -296.421556)
		(width 0.1143)
		(layer "In13.Cu")
		(net "P5E_CPU0_P0_RX_DN<5>")
	)
	(segment
		(start 349.899986 -290.7919)
		(end 349.830644 -290.751514)
		(width 0.1143)
		(layer "In13.Cu")
		(net "P5E_CPU0_P0_RX_DN<5>")
	)
	(segment
		(start 382.693164 -373.244364)
		(end 382.99517 -372.942358)
		(width 0.14224)
		(layer "In13.Cu")
		(net "P5E_CPU0_P0_RX_DN<5>")
	)
	(segment
		(start 382.197864 -373.739918)
		(end 382.391666 -373.739918)
		(width 0.14224)
		(layer "In13.Cu")
		(net "P5E_CPU0_P0_RX_DN<5>")
	)
	(segment
		(start 349.82912 -273.6215)
		(end 349.868236 -273.59864)
		(width 0.1143)
		(layer "In13.Cu")
		(net "P5E_CPU0_P0_RX_DN<5>")
	)
	(segment
		(start 349.898716 -271.351248)
		(end 349.830644 -271.311624)
		(width 0.1143)
		(layer "In13.Cu")
		(net "P5E_CPU0_P0_RX_DN<5>")
	)
	(segment
		(start 381.895858 -374.041924)
		(end 382.197864 -373.739918)
		(width 0.14224)
		(layer "In13.Cu")
		(net "P5E_CPU0_P0_RX_DN<5>")
	)
	(segment
		(start 360.57078 -376.17527)
		(end 360.57078 -375.37009)
		(width 0.14224)
		(layer "In13.Cu")
		(net "P5E_CPU0_P0_RX_DN<5>")
	)
	(segment
		(start 349.898716 -274.591272)
		(end 349.868236 -274.573492)
		(width 0.1143)
		(layer "In13.Cu")
		(net "P5E_CPU0_P0_RX_DN<5>")
	)
	(segment
		(start 349.830644 -289.82035)
		(end 349.899986 -289.779964)
		(width 0.1143)
		(layer "In13.Cu")
		(net "P5E_CPU0_P0_RX_DN<5>")
	)
	(segment
		(start 310.248554 -387.10616)
		(end 309.270908 -384.74523)
		(width 0.14224)
		(layer "In13.Cu")
		(net "P5E_CPU0_P0_RX_DN<5>")
	)
	(segment
		(start 362.872782 -313.914282)
		(end 350.313498 -298.611798)
		(width 0.14224)
		(layer "In13.Cu")
		(net "P5E_CPU0_P0_RX_DN<5>")
	)
	(segment
		(start 309.954422 -392.616944)
		(end 310.25846 -392.31316)
		(width 0.14224)
		(layer "In13.Cu")
		(net "P5E_CPU0_P0_RX_DN<5>")
	)
	(segment
		(start 345.396058 -373.996204)
		(end 356.223062 -375.06275)
		(width 0.14224)
		(layer "In13.Cu")
		(net "P5E_CPU0_P0_RX_DN<5>")
	)
	(segment
		(start 310.266588 -393.545822)
		(end 309.949596 -393.22883)
		(width 0.14224)
		(layer "In13.Cu")
		(net "P5E_CPU0_P0_RX_DN<5>")
	)
	(segment
		(start 383.796794 -372.140988)
		(end 383.990596 -372.140988)
		(width 0.14224)
		(layer "In13.Cu")
		(net "P5E_CPU0_P0_RX_DN<5>")
	)
	(segment
		(start 359.40746 -375.06275)
		(end 359.7148 -375.37009)
		(width 0.14224)
		(layer "In13.Cu")
		(net "P5E_CPU0_P0_RX_DN<5>")
	)
	(segment
		(start 349.830644 -294.680386)
		(end 349.899986 -294.64)
		(width 0.1143)
		(layer "In13.Cu")
		(net "P5E_CPU0_P0_RX_DN<5>")
	)
	(segment
		(start 349.82912 -275.241512)
		(end 349.868236 -275.218652)
		(width 0.1143)
		(layer "In13.Cu")
		(net "P5E_CPU0_P0_RX_DN<5>")
	)
	(segment
		(start 349.121984 -270.11884)
		(end 349.03918 -270.036036)
		(width 0.1143)
		(layer "In13.Cu")
		(net "P5E_CPU0_P0_RX_DN<5>")
	)
	(segment
		(start 349.868236 -284.938724)
		(end 349.898716 -284.920944)
		(width 0.1143)
		(layer "In13.Cu")
		(net "P5E_CPU0_P0_RX_DN<5>")
	)
	(segment
		(start 382.99517 -372.942358)
		(end 383.189226 -372.942358)
		(width 0.14224)
		(layer "In13.Cu")
		(net "P5E_CPU0_P0_RX_DN<5>")
	)
	(segment
		(start 314.39104 -375.06275)
		(end 317.250064 -375.06275)
		(width 0.14224)
		(layer "In13.Cu")
		(net "P5E_CPU0_P0_RX_DN<5>")
	)
	(segment
		(start 309.949596 -393.22883)
		(end 309.954422 -392.616944)
		(width 0.14224)
		(layer "In13.Cu")
		(net "P5E_CPU0_P0_RX_DN<5>")
	)
	(segment
		(start 349.898716 -284.311344)
		(end 349.868236 -284.293564)
		(width 0.1143)
		(layer "In13.Cu")
		(net "P5E_CPU0_P0_RX_DN<5>")
	)
	(segment
		(start 349.82912 -276.861524)
		(end 349.868236 -276.838664)
		(width 0.1143)
		(layer "In13.Cu")
		(net "P5E_CPU0_P0_RX_DN<5>")
	)
	(segment
		(start 369.909344 -374.34901)
		(end 369.909344 -374.92051)
		(width 0.14224)
		(layer "In13.Cu")
		(net "P5E_CPU0_P0_RX_DN<5>")
	)
	(segment
		(start 349.868236 -281.05354)
		(end 349.82912 -281.03068)
		(width 0.1143)
		(layer "In13.Cu")
		(net "P5E_CPU0_P0_RX_DN<5>")
	)
	(segment
		(start 310.248554 -387.106414)
		(end 310.248554 -387.10616)
		(width 0.14224)
		(layer "In13.Cu")
		(net "P5E_CPU0_P0_RX_DN<5>")
	)
	(segment
		(start 349.828358 -288.201608)
		(end 349.899732 -288.160206)
		(width 0.1143)
		(layer "In13.Cu")
		(net "P5E_CPU0_P0_RX_DN<5>")
	)
	(segment
		(start 381.895858 -374.235726)
		(end 381.895858 -374.041924)
		(width 0.14224)
		(layer "In13.Cu")
		(net "P5E_CPU0_P0_RX_DN<5>")
	)
	(segment
		(start 327.370694 -373.36222)
		(end 332.488032 -373.36222)
		(width 0.14224)
		(layer "In13.Cu")
		(net "P5E_CPU0_P0_RX_DN<5>")
	)
	(segment
		(start 349.868236 -281.6987)
		(end 349.898716 -281.68092)
		(width 0.1143)
		(layer "In13.Cu")
		(net "P5E_CPU0_P0_RX_DN<5>")
	)
	(segment
		(start 349.898716 -279.451308)
		(end 349.868236 -279.433528)
		(width 0.1143)
		(layer "In13.Cu")
		(net "P5E_CPU0_P0_RX_DN<5>")
	)
	(segment
		(start 317.250064 -375.06275)
		(end 324.260972 -373.66829)
		(width 0.14224)
		(layer "In13.Cu")
		(net "P5E_CPU0_P0_RX_DN<5>")
	)
	(segment
		(start 349.898716 -277.831296)
		(end 349.868236 -277.813516)
		(width 0.1143)
		(layer "In13.Cu")
		(net "P5E_CPU0_P0_RX_DN<5>")
	)
	(segment
		(start 349.868236 -280.078688)
		(end 349.898716 -280.060908)
		(width 0.1143)
		(layer "In13.Cu")
		(net "P5E_CPU0_P0_RX_DN<5>")
	)
	(segment
		(start 349.898716 -282.691332)
		(end 349.868236 -282.673552)
		(width 0.1143)
		(layer "In13.Cu")
		(net "P5E_CPU0_P0_RX_DN<5>")
	)
	(segment
		(start 385.5847 -370.282216)
		(end 385.5847 -368.74704)
		(width 0.14224)
		(layer "In13.Cu")
		(net "P5E_CPU0_P0_RX_DN<5>")
	)
	(segment
		(start 359.7148 -375.37009)
		(end 359.7148 -377.19635)
		(width 0.14224)
		(layer "In13.Cu")
		(net "P5E_CPU0_P0_RX_DN<5>")
	)
	(segment
		(start 349.830644 -291.440362)
		(end 349.899986 -291.399976)
		(width 0.1143)
		(layer "In13.Cu")
		(net "P5E_CPU0_P0_RX_DN<5>")
	)
	(segment
		(start 349.400876 -270.52651)
		(end 349.399606 -270.525748)
		(width 0.1143)
		(layer "In13.Cu")
		(net "P5E_CPU0_P0_RX_DN<5>")
	)
	(segment
		(start 349.868236 -276.193504)
		(end 349.82912 -276.170644)
		(width 0.1143)
		(layer "In13.Cu")
		(net "P5E_CPU0_P0_RX_DN<5>")
	)
	(segment
		(start 382.391666 -373.739918)
		(end 382.693164 -373.43842)
		(width 0.14224)
		(layer "In13.Cu")
		(net "P5E_CPU0_P0_RX_DN<5>")
	)
	(segment
		(start 310.25846 -392.31316)
		(end 310.25846 -387.155182)
		(width 0.14224)
		(layer "In13.Cu")
		(net "P5E_CPU0_P0_RX_DN<5>")
	)
	(segment
		(start 350.010222 -296.421556)
		(end 350.055942 -296.375836)
		(width 0.1143)
		(layer "In13.Cu")
		(net "P5E_CPU0_P0_RX_DN<5>")
	)
	(segment
		(start 310.144414 -393.787376)
		(end 310.144922 -393.786868)
		(width 0.14224)
		(layer "In13.Cu")
		(net "P5E_CPU0_P0_RX_DN<5>")
	)
	(segment
		(start 370.051584 -374.20677)
		(end 369.909344 -374.34901)
		(width 0.14224)
		(layer "In13.Cu")
		(net "P5E_CPU0_P0_RX_DN<5>")
	)
	(segment
		(start 383.494788 -372.442994)
		(end 383.796794 -372.140988)
		(width 0.14224)
		(layer "In13.Cu")
		(net "P5E_CPU0_P0_RX_DN<5>")
	)
	(segment
		(start 349.868236 -272.95348)
		(end 349.82912 -272.93062)
		(width 0.1143)
		(layer "In13.Cu")
		(net "P5E_CPU0_P0_RX_DN<5>")
	)
	(segment
		(start 349.868236 -282.673552)
		(end 349.82912 -282.650692)
		(width 0.1143)
		(layer "In13.Cu")
		(net "P5E_CPU0_P0_RX_DN<5>")
	)
	(segment
		(start 383.990596 -372.140988)
		(end 385.397502 -370.734082)
		(width 0.14224)
		(layer "In13.Cu")
		(net "P5E_CPU0_P0_RX_DN<5>")
	)
	(segment
		(start 349.868236 -284.293564)
		(end 349.82912 -284.270704)
		(width 0.1143)
		(layer "In13.Cu")
		(net "P5E_CPU0_P0_RX_DN<5>")
	)
	(segment
		(start 350.055942 -296.375836)
		(end 350.055942 -295.955974)
		(width 0.1143)
		(layer "In13.Cu")
		(net "P5E_CPU0_P0_RX_DN<5>")
	)
	(segment
		(start 366.191292 -376.62485)
		(end 366.049052 -376.48261)
		(width 0.14224)
		(layer "In13.Cu")
		(net "P5E_CPU0_P0_RX_DN<5>")
	)
	(segment
		(start 381.426974 -374.70461)
		(end 381.895858 -374.235726)
		(width 0.14224)
		(layer "In13.Cu")
		(net "P5E_CPU0_P0_RX_DN<5>")
	)
	(segment
		(start 349.868236 -276.838664)
		(end 349.898716 -276.820884)
		(width 0.1143)
		(layer "In13.Cu")
		(net "P5E_CPU0_P0_RX_DN<5>")
	)
	(segment
		(start 370.051584 -375.06275)
		(end 380.562612 -375.06275)
		(width 0.14224)
		(layer "In13.Cu")
		(net "P5E_CPU0_P0_RX_DN<5>")
	)
	(segment
		(start 349.899986 -294.031924)
		(end 349.830644 -293.991538)
		(width 0.1143)
		(layer "In13.Cu")
		(net "P5E_CPU0_P0_RX_DN<5>")
	)
	(segment
		(start 350.010222 -297.763438)
		(end 350.010222 -296.436034)
		(width 0.14224)
		(layer "In13.Cu")
		(net "P5E_CPU0_P0_RX_DN<5>")
	)
	(segment
		(start 349.898716 -281.07132)
		(end 349.868236 -281.05354)
		(width 0.1143)
		(layer "In13.Cu")
		(net "P5E_CPU0_P0_RX_DN<5>")
	)
	(segment
		(start 360.87812 -375.06275)
		(end 367.078768 -375.06275)
		(width 0.14224)
		(layer "In13.Cu")
		(net "P5E_CPU0_P0_RX_DN<5>")
	)
	(segment
		(start 310.266588 -393.716764)
		(end 310.266588 -393.545822)
		(width 0.14224)
		(layer "In13.Cu")
		(net "P5E_CPU0_P0_RX_DN<5>")
	)
	(segment
		(start 349.899986 -294.64)
		(end 349.900748 -294.639492)
		(width 0.1143)
		(layer "In13.Cu")
		(net "P5E_CPU0_P0_RX_DN<5>")
	)
	(arc
		(start 349.82912 -277.790656)
		(mid 349.585793 -277.32609)
		(end 349.82912 -276.861524)
		(width 0.1143)
		(layer "In13.Cu")
		(net "P5E_CPU0_P0_RX_DN<5>")
	)
	(arc
		(start 349.898716 -284.920944)
		(mid 350.055693 -284.616144)
		(end 349.898716 -284.311344)
		(width 0.1143)
		(layer "In13.Cu")
		(net "P5E_CPU0_P0_RX_DN<5>")
	)
	(arc
		(start 349.899986 -293.019988)
		(mid 350.055813 -292.71595)
		(end 349.899986 -292.411912)
		(width 0.1143)
		(layer "In13.Cu")
		(net "P5E_CPU0_P0_RX_DN<5>")
	)
	(arc
		(start 349.899986 -291.399976)
		(mid 350.055813 -291.095938)
		(end 349.899986 -290.7919)
		(width 0.1143)
		(layer "In13.Cu")
		(net "P5E_CPU0_P0_RX_DN<5>")
	)
	(arc
		(start 349.898716 -271.960848)
		(mid 350.055693 -271.656048)
		(end 349.898716 -271.351248)
		(width 0.1143)
		(layer "In13.Cu")
		(net "P5E_CPU0_P0_RX_DN<5>")
	)
	(arc
		(start 349.898716 -281.68092)
		(mid 350.055693 -281.37612)
		(end 349.898716 -281.07132)
		(width 0.1143)
		(layer "In13.Cu")
		(net "P5E_CPU0_P0_RX_DN<5>")
	)
	(arc
		(start 349.82912 -284.270704)
		(mid 349.585793 -283.806138)
		(end 349.82912 -283.341572)
		(width 0.1143)
		(layer "In13.Cu")
		(net "P5E_CPU0_P0_RX_DN<5>")
	)
	(arc
		(start 309.23992 -382.249934)
		(mid 309.257373 -382.131192)
		(end 309.3085 -382.022604)
		(width 0.14224)
		(layer "In13.Cu")
		(net "P5E_CPU0_P0_RX_DN<5>")
	)
	(arc
		(start 349.899986 -289.779964)
		(mid 350.055813 -289.475926)
		(end 349.899986 -289.171888)
		(width 0.1143)
		(layer "In13.Cu")
		(net "P5E_CPU0_P0_RX_DN<5>")
	)
	(arc
		(start 349.37446 -270.510254)
		(mid 349.205883 -270.34186)
		(end 349.121984 -270.11884)
		(width 0.1143)
		(layer "In13.Cu")
		(net "P5E_CPU0_P0_RX_DN<5>")
	)
	(arc
		(start 349.586042 -288.66592)
		(mid 349.650218 -288.404033)
		(end 349.828358 -288.201608)
		(width 0.1143)
		(layer "In13.Cu")
		(net "P5E_CPU0_P0_RX_DN<5>")
	)
	(arc
		(start 349.830644 -290.751514)
		(mid 349.585823 -290.285932)
		(end 349.830644 -289.82035)
		(width 0.1143)
		(layer "In13.Cu")
		(net "P5E_CPU0_P0_RX_DN<5>")
	)
	(arc
		(start 309.270908 -384.74523)
		(mid 309.247705 -384.668396)
		(end 309.23992 -384.588512)
		(width 0.14224)
		(layer "In13.Cu")
		(net "P5E_CPU0_P0_RX_DN<5>")
	)
	(arc
		(start 349.898716 -278.440896)
		(mid 350.055693 -278.136096)
		(end 349.898716 -277.831296)
		(width 0.1143)
		(layer "In13.Cu")
		(net "P5E_CPU0_P0_RX_DN<5>")
	)
	(arc
		(start 349.830644 -292.371526)
		(mid 349.585823 -291.905944)
		(end 349.830644 -291.440362)
		(width 0.1143)
		(layer "In13.Cu")
		(net "P5E_CPU0_P0_RX_DN<5>")
	)
	(arc
		(start 350.313498 -298.611798)
		(mid 350.088282 -298.213927)
		(end 350.010222 -297.763438)
		(width 0.14224)
		(layer "In13.Cu")
		(net "P5E_CPU0_P0_RX_DN<5>")
	)
	(arc
		(start 349.82912 -281.03068)
		(mid 349.585793 -280.566114)
		(end 349.82912 -280.101548)
		(width 0.1143)
		(layer "In13.Cu")
		(net "P5E_CPU0_P0_RX_DN<5>")
	)
	(arc
		(start 349.898716 -283.300932)
		(mid 350.055693 -282.996132)
		(end 349.898716 -282.691332)
		(width 0.1143)
		(layer "In13.Cu")
		(net "P5E_CPU0_P0_RX_DN<5>")
	)
	(arc
		(start 349.899732 -286.540194)
		(mid 350.055665 -286.236259)
		(end 349.899986 -285.932118)
		(width 0.1143)
		(layer "In13.Cu")
		(net "P5E_CPU0_P0_RX_DN<5>")
	)
	(arc
		(start 310.25846 -387.155182)
		(mid 310.25591 -387.13031)
		(end 310.248554 -387.106414)
		(width 0.14224)
		(layer "In13.Cu")
		(net "P5E_CPU0_P0_RX_DN<5>")
	)
	(arc
		(start 324.260972 -373.66829)
		(mid 325.808315 -373.438871)
		(end 327.370694 -373.36222)
		(width 0.14224)
		(layer "In13.Cu")
		(net "P5E_CPU0_P0_RX_DN<5>")
	)
	(arc
		(start 349.899732 -288.160206)
		(mid 350.055764 -287.854895)
		(end 349.897954 -287.550606)
		(width 0.1143)
		(layer "In13.Cu")
		(net "P5E_CPU0_P0_RX_DN<5>")
	)
	(arc
		(start 350.055942 -295.955974)
		(mid 350.014683 -295.785117)
		(end 349.899986 -295.651936)
		(width 0.1143)
		(layer "In13.Cu")
		(net "P5E_CPU0_P0_RX_DN<5>")
	)
	(arc
		(start 349.830644 -289.131502)
		(mid 349.650852 -288.928914)
		(end 349.586042 -288.66592)
		(width 0.1143)
		(layer "In13.Cu")
		(net "P5E_CPU0_P0_RX_DN<5>")
	)
	(arc
		(start 349.830644 -271.311624)
		(mid 349.650852 -271.109036)
		(end 349.586042 -270.846042)
		(width 0.1143)
		(layer "In13.Cu")
		(net "P5E_CPU0_P0_RX_DN<5>")
	)
	(arc
		(start 349.586042 -270.846042)
		(mid 349.53731 -270.663005)
		(end 349.404178 -270.528288)
		(width 0.1143)
		(layer "In13.Cu")
		(net "P5E_CPU0_P0_RX_DN<5>")
	)
	(arc
		(start 349.898716 -280.060908)
		(mid 350.055693 -279.756108)
		(end 349.898716 -279.451308)
		(width 0.1143)
		(layer "In13.Cu")
		(net "P5E_CPU0_P0_RX_DN<5>")
	)
	(arc
		(start 349.82912 -272.93062)
		(mid 349.585793 -272.466054)
		(end 349.82912 -272.001488)
		(width 0.1143)
		(layer "In13.Cu")
		(net "P5E_CPU0_P0_RX_DN<5>")
	)
	(arc
		(start 380.562612 -375.06275)
		(mid 381.030429 -374.969678)
		(end 381.426974 -374.70461)
		(width 0.14224)
		(layer "In13.Cu")
		(net "P5E_CPU0_P0_RX_DN<5>")
	)
	(arc
		(start 349.82912 -279.410668)
		(mid 349.585793 -278.946102)
		(end 349.82912 -278.481536)
		(width 0.1143)
		(layer "In13.Cu")
		(net "P5E_CPU0_P0_RX_DN<5>")
	)
	(arc
		(start 349.82912 -285.890716)
		(mid 349.585793 -285.42615)
		(end 349.82912 -284.961584)
		(width 0.1143)
		(layer "In13.Cu")
		(net "P5E_CPU0_P0_RX_DN<5>")
	)
	(arc
		(start 313.719718 -375.421398)
		(mid 314.010491 -375.158065)
		(end 314.39104 -375.06275)
		(width 0.14224)
		(layer "In13.Cu")
		(net "P5E_CPU0_P0_RX_DN<5>")
	)
	(arc
		(start 349.898716 -276.820884)
		(mid 350.055693 -276.516084)
		(end 349.898716 -276.211284)
		(width 0.1143)
		(layer "In13.Cu")
		(net "P5E_CPU0_P0_RX_DN<5>")
	)
	(arc
		(start 349.898716 -275.200872)
		(mid 350.055693 -274.896072)
		(end 349.898716 -274.591272)
		(width 0.1143)
		(layer "In13.Cu")
		(net "P5E_CPU0_P0_RX_DN<5>")
	)
	(arc
		(start 349.82912 -276.170644)
		(mid 349.585793 -275.706078)
		(end 349.82912 -275.241512)
		(width 0.1143)
		(layer "In13.Cu")
		(net "P5E_CPU0_P0_RX_DN<5>")
	)
	(arc
		(start 332.488032 -373.36222)
		(mid 338.949827 -373.520766)
		(end 345.396058 -373.996204)
		(width 0.14224)
		(layer "In13.Cu")
		(net "P5E_CPU0_P0_RX_DN<5>")
	)
	(arc
		(start 349.830644 -287.51149)
		(mid 349.650852 -287.308902)
		(end 349.586042 -287.045908)
		(width 0.1143)
		(layer "In13.Cu")
		(net "P5E_CPU0_P0_RX_DN<5>")
	)
	(arc
		(start 349.83039 -295.61155)
		(mid 349.585569 -295.145863)
		(end 349.830644 -294.680386)
		(width 0.1143)
		(layer "In13.Cu")
		(net "P5E_CPU0_P0_RX_DN<5>")
	)
	(arc
		(start 349.586042 -287.045908)
		(mid 349.650218 -286.784021)
		(end 349.828358 -286.581596)
		(width 0.1143)
		(layer "In13.Cu")
		(net "P5E_CPU0_P0_RX_DN<5>")
	)
	(arc
		(start 349.898716 -273.58086)
		(mid 350.055693 -273.27606)
		(end 349.898716 -272.97126)
		(width 0.1143)
		(layer "In13.Cu")
		(net "P5E_CPU0_P0_RX_DN<5>")
	)
	(arc
		(start 385.397502 -370.734082)
		(mid 385.536027 -370.526764)
		(end 385.5847 -370.282216)
		(width 0.14224)
		(layer "In13.Cu")
		(net "P5E_CPU0_P0_RX_DN<5>")
	)
	(arc
		(start 349.82912 -282.650692)
		(mid 349.585793 -282.186126)
		(end 349.82912 -281.72156)
		(width 0.1143)
		(layer "In13.Cu")
		(net "P5E_CPU0_P0_RX_DN<5>")
	)
	(arc
		(start 349.900748 -294.639492)
		(mid 350.055847 -294.335504)
		(end 349.899986 -294.031924)
		(width 0.1143)
		(layer "In13.Cu")
		(net "P5E_CPU0_P0_RX_DN<5>")
	)
	(arc
		(start 349.82912 -274.550632)
		(mid 349.585793 -274.086066)
		(end 349.82912 -273.6215)
		(width 0.1143)
		(layer "In13.Cu")
		(net "P5E_CPU0_P0_RX_DN<5>")
	)
	(arc
		(start 349.830644 -293.991538)
		(mid 349.585823 -293.525956)
		(end 349.830644 -293.060374)
		(width 0.1143)
		(layer "In13.Cu")
		(net "P5E_CPU0_P0_RX_DN<5>")
	)
	(segment
		(start 349.20809 -273.010122)
		(end 348.741238 -273.27606)
		(width 0.12954)
		(layer "F.Cu")
		(net "P5E_CPU0_P0_RX_DN<4>")
	)
	(segment
		(start 308.07025 -393.69238)
		(end 308.59095 -393.69238)
		(width 0.127)
		(layer "F.Cu")
		(net "P5E_CPU0_P0_RX_DN<4>")
	)
	(segment
		(start 362.173012 -314.68568)
		(end 348.941136 -298.763436)
		(width 0.14224)
		(layer "In13.Cu")
		(net "P5E_CPU0_P0_RX_DN<4>")
	)
	(segment
		(start 375.222008 -372.04015)
		(end 375.222008 -373.86641)
		(width 0.14224)
		(layer "In13.Cu")
		(net "P5E_CPU0_P0_RX_DN<4>")
	)
	(segment
		(start 348.88932 -278.481536)
		(end 348.928436 -278.458676)
		(width 0.1143)
		(layer "In13.Cu")
		(net "P5E_CPU0_P0_RX_DN<4>")
	)
	(segment
		(start 306.236624 -376.747532)
		(end 307.058568 -375.925588)
		(width 0.14224)
		(layer "In13.Cu")
		(net "P5E_CPU0_P0_RX_DN<4>")
	)
	(segment
		(start 372.73484 -371.59565)
		(end 372.872 -371.73281)
		(width 0.14224)
		(layer "In13.Cu")
		(net "P5E_CPU0_P0_RX_DN<4>")
	)
	(segment
		(start 348.958916 -285.931356)
		(end 348.928436 -285.913576)
		(width 0.1143)
		(layer "In13.Cu")
		(net "P5E_CPU0_P0_RX_DN<4>")
	)
	(segment
		(start 348.88932 -273.6215)
		(end 348.928436 -273.59864)
		(width 0.1143)
		(layer "In13.Cu")
		(net "P5E_CPU0_P0_RX_DN<4>")
	)
	(segment
		(start 348.928436 -288.178494)
		(end 348.960948 -288.159698)
		(width 0.1143)
		(layer "In13.Cu")
		(net "P5E_CPU0_P0_RX_DN<4>")
	)
	(segment
		(start 372.872 -371.73281)
		(end 374.914668 -371.73281)
		(width 0.14224)
		(layer "In13.Cu")
		(net "P5E_CPU0_P0_RX_DN<4>")
	)
	(segment
		(start 378.809758 -371.73281)
		(end 383.649982 -366.892586)
		(width 0.14224)
		(layer "In13.Cu")
		(net "P5E_CPU0_P0_RX_DN<4>")
	)
	(segment
		(start 348.928436 -286.558482)
		(end 348.960948 -286.539686)
		(width 0.1143)
		(layer "In13.Cu")
		(net "P5E_CPU0_P0_RX_DN<4>")
	)
	(segment
		(start 348.88932 -293.06139)
		(end 348.928436 -293.03853)
		(width 0.1143)
		(layer "In13.Cu")
		(net "P5E_CPU0_P0_RX_DN<4>")
	)
	(segment
		(start 348.958916 -287.551368)
		(end 348.89186 -287.512252)
		(width 0.1143)
		(layer "In13.Cu")
		(net "P5E_CPU0_P0_RX_DN<4>")
	)
	(segment
		(start 308.59095 -393.69238)
		(end 308.944264 -393.787376)
		(width 0.14224)
		(layer "In13.Cu")
		(net "P5E_CPU0_P0_RX_DN<4>")
	)
	(segment
		(start 375.222008 -373.86641)
		(end 375.364248 -374.00865)
		(width 0.14224)
		(layer "In13.Cu")
		(net "P5E_CPU0_P0_RX_DN<4>")
	)
	(segment
		(start 381.941578 -365.180118)
		(end 381.536956 -364.775496)
		(width 0.14224)
		(layer "In13.Cu")
		(net "P5E_CPU0_P0_RX_DN<4>")
	)
	(segment
		(start 376.385328 -371.73281)
		(end 378.809758 -371.73281)
		(width 0.14224)
		(layer "In13.Cu")
		(net "P5E_CPU0_P0_RX_DN<4>")
	)
	(segment
		(start 377.675394 -369.64747)
		(end 381.941578 -365.381286)
		(width 0.14224)
		(layer "In13.Cu")
		(net "P5E_CPU0_P0_RX_DN<4>")
	)
	(segment
		(start 378.63272 -374.00865)
		(end 378.77496 -373.86641)
		(width 0.14224)
		(layer "In13.Cu")
		(net "P5E_CPU0_P0_RX_DN<4>")
	)
	(segment
		(start 374.26773 -369.83543)
		(end 379.945138 -364.158022)
		(width 0.14224)
		(layer "In13.Cu")
		(net "P5E_CPU0_P0_RX_DN<4>")
	)
	(segment
		(start 348.88932 -280.101548)
		(end 348.928436 -280.078688)
		(width 0.1143)
		(layer "In13.Cu")
		(net "P5E_CPU0_P0_RX_DN<4>")
	)
	(segment
		(start 369.7859 -371.73281)
		(end 369.92306 -371.59565)
		(width 0.14224)
		(layer "In13.Cu")
		(net "P5E_CPU0_P0_RX_DN<4>")
	)
	(segment
		(start 383.044192 -366.286796)
		(end 378.679456 -370.651532)
		(width 0.14224)
		(layer "In13.Cu")
		(net "P5E_CPU0_P0_RX_DN<4>")
	)
	(segment
		(start 348.928436 -285.913576)
		(end 348.88932 -285.890716)
		(width 0.1143)
		(layer "In13.Cu")
		(net "P5E_CPU0_P0_RX_DN<4>")
	)
	(segment
		(start 348.928436 -276.838664)
		(end 348.958916 -276.820884)
		(width 0.1143)
		(layer "In13.Cu")
		(net "P5E_CPU0_P0_RX_DN<4>")
	)
	(segment
		(start 348.88932 -288.201354)
		(end 348.928436 -288.178494)
		(width 0.1143)
		(layer "In13.Cu")
		(net "P5E_CPU0_P0_RX_DN<4>")
	)
	(segment
		(start 348.928436 -281.6987)
		(end 348.958916 -281.68092)
		(width 0.1143)
		(layer "In13.Cu")
		(net "P5E_CPU0_P0_RX_DN<4>")
	)
	(segment
		(start 348.928436 -273.59864)
		(end 348.958916 -273.58086)
		(width 0.1143)
		(layer "In13.Cu")
		(net "P5E_CPU0_P0_RX_DN<4>")
	)
	(segment
		(start 348.958916 -279.451308)
		(end 348.928436 -279.433528)
		(width 0.1143)
		(layer "In13.Cu")
		(net "P5E_CPU0_P0_RX_DN<4>")
	)
	(segment
		(start 348.645988 -296.293794)
		(end 348.645988 -295.145968)
		(width 0.1143)
		(layer "In13.Cu")
		(net "P5E_CPU0_P0_RX_DN<4>")
	)
	(segment
		(start 376.077988 -372.04015)
		(end 376.385328 -371.73281)
		(width 0.14224)
		(layer "In13.Cu")
		(net "P5E_CPU0_P0_RX_DN<4>")
	)
	(segment
		(start 383.649982 -366.892586)
		(end 383.649982 -366.691418)
		(width 0.14224)
		(layer "In13.Cu")
		(net "P5E_CPU0_P0_RX_DN<4>")
	)
	(segment
		(start 374.836944 -370.839746)
		(end 374.26773 -370.270532)
		(width 0.14224)
		(layer "In13.Cu")
		(net "P5E_CPU0_P0_RX_DN<4>")
	)
	(segment
		(start 376.385328 -373.15267)
		(end 376.077988 -372.84533)
		(width 0.14224)
		(layer "In13.Cu")
		(net "P5E_CPU0_P0_RX_DN<4>")
	)
	(segment
		(start 348.958916 -292.41115)
		(end 348.928436 -292.39337)
		(width 0.1143)
		(layer "In13.Cu")
		(net "P5E_CPU0_P0_RX_DN<4>")
	)
	(segment
		(start 348.927928 -294.658542)
		(end 348.930214 -294.657272)
		(width 0.1143)
		(layer "In13.Cu")
		(net "P5E_CPU0_P0_RX_DN<4>")
	)
	(segment
		(start 316.94374 -374.12549)
		(end 325.273416 -372.468648)
		(width 0.14224)
		(layer "In13.Cu")
		(net "P5E_CPU0_P0_RX_DN<4>")
	)
	(segment
		(start 378.77496 -373.29491)
		(end 378.63272 -373.15267)
		(width 0.14224)
		(layer "In13.Cu")
		(net "P5E_CPU0_P0_RX_DN<4>")
	)
	(segment
		(start 348.928436 -275.218652)
		(end 348.958916 -275.200872)
		(width 0.1143)
		(layer "In13.Cu")
		(net "P5E_CPU0_P0_RX_DN<4>")
	)
	(segment
		(start 348.88932 -276.861524)
		(end 348.928436 -276.838664)
		(width 0.1143)
		(layer "In13.Cu")
		(net "P5E_CPU0_P0_RX_DN<4>")
	)
	(segment
		(start 348.600268 -296.367962)
		(end 348.600268 -296.339514)
		(width 0.1143)
		(layer "In13.Cu")
		(net "P5E_CPU0_P0_RX_DN<4>")
	)
	(segment
		(start 379.982476 -357.681276)
		(end 362.173012 -314.68568)
		(width 0.14224)
		(layer "In13.Cu")
		(net "P5E_CPU0_P0_RX_DN<4>")
	)
	(segment
		(start 308.944264 -393.787376)
		(end 308.944772 -393.786868)
		(width 0.14224)
		(layer "In13.Cu")
		(net "P5E_CPU0_P0_RX_DN<4>")
	)
	(segment
		(start 349.10903 -273.34591)
		(end 349.03918 -273.27606)
		(width 0.1143)
		(layer "In13.Cu")
		(net "P5E_CPU0_P0_RX_DN<4>")
	)
	(segment
		(start 372.30812 -371.59565)
		(end 372.73484 -371.59565)
		(width 0.14224)
		(layer "In13.Cu")
		(net "P5E_CPU0_P0_RX_DN<4>")
	)
	(segment
		(start 378.63272 -373.15267)
		(end 376.385328 -373.15267)
		(width 0.14224)
		(layer "In13.Cu")
		(net "P5E_CPU0_P0_RX_DN<4>")
	)
	(segment
		(start 383.24536 -366.286796)
		(end 383.044192 -366.286796)
		(width 0.14224)
		(layer "In13.Cu")
		(net "P5E_CPU0_P0_RX_DN<4>")
	)
	(segment
		(start 348.88932 -291.441378)
		(end 348.928436 -291.418518)
		(width 0.1143)
		(layer "In13.Cu")
		(net "P5E_CPU0_P0_RX_DN<4>")
	)
	(segment
		(start 348.928436 -291.418518)
		(end 348.958916 -291.400738)
		(width 0.1143)
		(layer "In13.Cu")
		(net "P5E_CPU0_P0_RX_DN<4>")
	)
	(segment
		(start 368.950494 -371.73281)
		(end 369.7859 -371.73281)
		(width 0.14224)
		(layer "In13.Cu")
		(net "P5E_CPU0_P0_RX_DN<4>")
	)
	(segment
		(start 348.928436 -278.458676)
		(end 348.958916 -278.440896)
		(width 0.1143)
		(layer "In13.Cu")
		(net "P5E_CPU0_P0_RX_DN<4>")
	)
	(segment
		(start 348.600268 -297.818302)
		(end 348.600268 -296.367962)
		(width 0.14224)
		(layer "In13.Cu")
		(net "P5E_CPU0_P0_RX_DN<4>")
	)
	(segment
		(start 348.928436 -292.39337)
		(end 348.88932 -292.37051)
		(width 0.1143)
		(layer "In13.Cu")
		(net "P5E_CPU0_P0_RX_DN<4>")
	)
	(segment
		(start 348.958916 -290.791138)
		(end 348.928436 -290.773358)
		(width 0.1143)
		(layer "In13.Cu")
		(net "P5E_CPU0_P0_RX_DN<4>")
	)
	(segment
		(start 348.928436 -289.153346)
		(end 348.88932 -289.130486)
		(width 0.1143)
		(layer "In13.Cu")
		(net "P5E_CPU0_P0_RX_DN<4>")
	)
	(segment
		(start 306.369974 -378.43079)
		(end 306.294536 -378.355352)
		(width 0.14224)
		(layer "In13.Cu")
		(net "P5E_CPU0_P0_RX_DN<4>")
	)
	(segment
		(start 348.928436 -283.318712)
		(end 348.958916 -283.300932)
		(width 0.1143)
		(layer "In13.Cu")
		(net "P5E_CPU0_P0_RX_DN<4>")
	)
	(segment
		(start 376.077988 -372.84533)
		(end 376.077988 -372.04015)
		(width 0.14224)
		(layer "In13.Cu")
		(net "P5E_CPU0_P0_RX_DN<4>")
	)
	(segment
		(start 349.03918 -273.27606)
		(end 348.741238 -273.27606)
		(width 0.1143)
		(layer "In13.Cu")
		(net "P5E_CPU0_P0_RX_DN<4>")
	)
	(segment
		(start 378.244608 -370.651532)
		(end 377.675394 -370.082318)
		(width 0.14224)
		(layer "In13.Cu")
		(net "P5E_CPU0_P0_RX_DN<4>")
	)
	(segment
		(start 379.982476 -364.068106)
		(end 379.982476 -357.681276)
		(width 0.14224)
		(layer "In13.Cu")
		(net "P5E_CPU0_P0_RX_DN<4>")
	)
	(segment
		(start 348.958916 -284.311344)
		(end 348.928436 -284.293564)
		(width 0.1143)
		(layer "In13.Cu")
		(net "P5E_CPU0_P0_RX_DN<4>")
	)
	(segment
		(start 309.048404 -387.920484)
		(end 309.048404 -387.92023)
		(width 0.14224)
		(layer "In13.Cu")
		(net "P5E_CPU0_P0_RX_DN<4>")
	)
	(segment
		(start 371.05082 -371.59565)
		(end 371.47754 -371.59565)
		(width 0.14224)
		(layer "In13.Cu")
		(net "P5E_CPU0_P0_RX_DN<4>")
	)
	(segment
		(start 309.066438 -393.545822)
		(end 308.749446 -393.22883)
		(width 0.14224)
		(layer "In13.Cu")
		(net "P5E_CPU0_P0_RX_DN<4>")
	)
	(segment
		(start 375.271538 -370.839746)
		(end 374.836944 -370.839746)
		(width 0.14224)
		(layer "In13.Cu")
		(net "P5E_CPU0_P0_RX_DN<4>")
	)
	(segment
		(start 370.91366 -371.73281)
		(end 371.05082 -371.59565)
		(width 0.14224)
		(layer "In13.Cu")
		(net "P5E_CPU0_P0_RX_DN<4>")
	)
	(segment
		(start 307.347874 -375.8057)
		(end 308.64048 -375.8057)
		(width 0.14224)
		(layer "In13.Cu")
		(net "P5E_CPU0_P0_RX_DN<4>")
	)
	(segment
		(start 348.88932 -281.72156)
		(end 348.928436 -281.6987)
		(width 0.1143)
		(layer "In13.Cu")
		(net "P5E_CPU0_P0_RX_DN<4>")
	)
	(segment
		(start 348.928436 -284.293564)
		(end 348.88932 -284.270704)
		(width 0.1143)
		(layer "In13.Cu")
		(net "P5E_CPU0_P0_RX_DN<4>")
	)
	(segment
		(start 348.928436 -279.433528)
		(end 348.88932 -279.410668)
		(width 0.1143)
		(layer "In13.Cu")
		(net "P5E_CPU0_P0_RX_DN<4>")
	)
	(segment
		(start 348.930214 -294.657272)
		(end 348.932754 -294.656002)
		(width 0.1143)
		(layer "In13.Cu")
		(net "P5E_CPU0_P0_RX_DN<4>")
	)
	(segment
		(start 348.891352 -286.579818)
		(end 348.928436 -286.558482)
		(width 0.1143)
		(layer "In13.Cu")
		(net "P5E_CPU0_P0_RX_DN<4>")
	)
	(segment
		(start 348.928436 -281.05354)
		(end 348.88932 -281.03068)
		(width 0.1143)
		(layer "In13.Cu")
		(net "P5E_CPU0_P0_RX_DN<4>")
	)
	(segment
		(start 308.754272 -392.616944)
		(end 309.05831 -392.31316)
		(width 0.14224)
		(layer "In13.Cu")
		(net "P5E_CPU0_P0_RX_DN<4>")
	)
	(segment
		(start 374.914668 -371.73281)
		(end 375.222008 -372.04015)
		(width 0.14224)
		(layer "In13.Cu")
		(net "P5E_CPU0_P0_RX_DN<4>")
	)
	(segment
		(start 371.47754 -371.59565)
		(end 371.6147 -371.73281)
		(width 0.14224)
		(layer "In13.Cu")
		(net "P5E_CPU0_P0_RX_DN<4>")
	)
	(segment
		(start 370.48694 -371.73281)
		(end 370.91366 -371.73281)
		(width 0.14224)
		(layer "In13.Cu")
		(net "P5E_CPU0_P0_RX_DN<4>")
	)
	(segment
		(start 307.91404 -385.098798)
		(end 307.91404 -379.420628)
		(width 0.14224)
		(layer "In13.Cu")
		(net "P5E_CPU0_P0_RX_DN<4>")
	)
	(segment
		(start 348.958916 -276.211284)
		(end 348.928436 -276.193504)
		(width 0.1143)
		(layer "In13.Cu")
		(net "P5E_CPU0_P0_RX_DN<4>")
	)
	(segment
		(start 308.944772 -393.786868)
		(end 309.066438 -393.716764)
		(width 0.14224)
		(layer "In13.Cu")
		(net "P5E_CPU0_P0_RX_DN<4>")
	)
	(segment
		(start 307.4543 -378.928884)
		(end 306.565808 -378.561346)
		(width 0.14224)
		(layer "In13.Cu")
		(net "P5E_CPU0_P0_RX_DN<4>")
	)
	(segment
		(start 348.88932 -286.581342)
		(end 348.891352 -286.579818)
		(width 0.1143)
		(layer "In13.Cu")
		(net "P5E_CPU0_P0_RX_DN<4>")
	)
	(segment
		(start 348.928436 -274.573492)
		(end 348.88932 -274.550632)
		(width 0.1143)
		(layer "In13.Cu")
		(net "P5E_CPU0_P0_RX_DN<4>")
	)
	(segment
		(start 348.928436 -280.078688)
		(end 348.958916 -280.060908)
		(width 0.1143)
		(layer "In13.Cu")
		(net "P5E_CPU0_P0_RX_DN<4>")
	)
	(segment
		(start 348.928436 -277.813516)
		(end 348.88932 -277.790656)
		(width 0.1143)
		(layer "In13.Cu")
		(net "P5E_CPU0_P0_RX_DN<4>")
	)
	(segment
		(start 374.26773 -370.270532)
		(end 374.26773 -369.83543)
		(width 0.14224)
		(layer "In13.Cu")
		(net "P5E_CPU0_P0_RX_DN<4>")
	)
	(segment
		(start 358.784398 -374.12549)
		(end 366.557814 -374.12549)
		(width 0.14224)
		(layer "In13.Cu")
		(net "P5E_CPU0_P0_RX_DN<4>")
	)
	(segment
		(start 375.364248 -374.00865)
		(end 378.63272 -374.00865)
		(width 0.14224)
		(layer "In13.Cu")
		(net "P5E_CPU0_P0_RX_DN<4>")
	)
	(segment
		(start 327.230232 -372.276116)
		(end 333.503524 -372.276116)
		(width 0.14224)
		(layer "In13.Cu")
		(net "P5E_CPU0_P0_RX_DN<4>")
	)
	(segment
		(start 346.474034 -372.911878)
		(end 358.784398 -374.12549)
		(width 0.14224)
		(layer "In13.Cu")
		(net "P5E_CPU0_P0_RX_DN<4>")
	)
	(segment
		(start 309.05831 -392.31316)
		(end 309.05831 -387.969252)
		(width 0.14224)
		(layer "In13.Cu")
		(net "P5E_CPU0_P0_RX_DN<4>")
	)
	(segment
		(start 308.754526 -375.758456)
		(end 310.267604 -374.245378)
		(width 0.14224)
		(layer "In13.Cu")
		(net "P5E_CPU0_P0_RX_DN<4>")
	)
	(segment
		(start 369.92306 -371.59565)
		(end 370.34978 -371.59565)
		(width 0.14224)
		(layer "In13.Cu")
		(net "P5E_CPU0_P0_RX_DN<4>")
	)
	(segment
		(start 308.749446 -393.22883)
		(end 308.754272 -392.616944)
		(width 0.14224)
		(layer "In13.Cu")
		(net "P5E_CPU0_P0_RX_DN<4>")
	)
	(segment
		(start 348.928436 -293.03853)
		(end 348.958916 -293.02075)
		(width 0.1143)
		(layer "In13.Cu")
		(net "P5E_CPU0_P0_RX_DN<4>")
	)
	(segment
		(start 348.928436 -276.193504)
		(end 348.88932 -276.170644)
		(width 0.1143)
		(layer "In13.Cu")
		(net "P5E_CPU0_P0_RX_DN<4>")
	)
	(segment
		(start 306.116736 -377.926092)
		(end 306.116736 -377.036838)
		(width 0.14224)
		(layer "In13.Cu")
		(net "P5E_CPU0_P0_RX_DN<4>")
	)
	(segment
		(start 383.649982 -366.691418)
		(end 383.24536 -366.286796)
		(width 0.14224)
		(layer "In13.Cu")
		(net "P5E_CPU0_P0_RX_DN<4>")
	)
	(segment
		(start 310.557164 -374.12549)
		(end 316.94374 -374.12549)
		(width 0.14224)
		(layer "In13.Cu")
		(net "P5E_CPU0_P0_RX_DN<4>")
	)
	(segment
		(start 348.958916 -289.171126)
		(end 348.928436 -289.153346)
		(width 0.1143)
		(layer "In13.Cu")
		(net "P5E_CPU0_P0_RX_DN<4>")
	)
	(segment
		(start 348.928436 -289.798506)
		(end 348.958916 -289.780726)
		(width 0.1143)
		(layer "In13.Cu")
		(net "P5E_CPU0_P0_RX_DN<4>")
	)
	(segment
		(start 348.958916 -281.07132)
		(end 348.928436 -281.05354)
		(width 0.1143)
		(layer "In13.Cu")
		(net "P5E_CPU0_P0_RX_DN<4>")
	)
	(segment
		(start 378.77496 -373.86641)
		(end 378.77496 -373.29491)
		(width 0.14224)
		(layer "In13.Cu")
		(net "P5E_CPU0_P0_RX_DN<4>")
	)
	(segment
		(start 348.960186 -294.031924)
		(end 348.88932 -293.990522)
		(width 0.1143)
		(layer "In13.Cu")
		(net "P5E_CPU0_P0_RX_DN<4>")
	)
	(segment
		(start 381.941578 -365.381286)
		(end 381.941578 -365.180118)
		(width 0.14224)
		(layer "In13.Cu")
		(net "P5E_CPU0_P0_RX_DN<4>")
	)
	(segment
		(start 348.88932 -289.821366)
		(end 348.928436 -289.798506)
		(width 0.1143)
		(layer "In13.Cu")
		(net "P5E_CPU0_P0_RX_DN<4>")
	)
	(segment
		(start 307.91404 -379.420628)
		(end 307.913786 -379.420628)
		(width 0.14224)
		(layer "In13.Cu")
		(net "P5E_CPU0_P0_RX_DN<4>")
	)
	(segment
		(start 348.958916 -274.591272)
		(end 348.928436 -274.573492)
		(width 0.1143)
		(layer "In13.Cu")
		(net "P5E_CPU0_P0_RX_DN<4>")
	)
	(segment
		(start 307.866796 -379.306582)
		(end 307.558948 -378.998734)
		(width 0.14224)
		(layer "In13.Cu")
		(net "P5E_CPU0_P0_RX_DN<4>")
	)
	(segment
		(start 348.958916 -282.691332)
		(end 348.928436 -282.673552)
		(width 0.1143)
		(layer "In13.Cu")
		(net "P5E_CPU0_P0_RX_DN<4>")
	)
	(segment
		(start 366.557814 -374.12549)
		(end 368.950494 -371.73281)
		(width 0.14224)
		(layer "In13.Cu")
		(net "P5E_CPU0_P0_RX_DN<4>")
	)
	(segment
		(start 370.34978 -371.59565)
		(end 370.48694 -371.73281)
		(width 0.14224)
		(layer "In13.Cu")
		(net "P5E_CPU0_P0_RX_DN<4>")
	)
	(segment
		(start 348.88932 -284.961584)
		(end 348.928436 -284.938724)
		(width 0.1143)
		(layer "In13.Cu")
		(net "P5E_CPU0_P0_RX_DN<4>")
	)
	(segment
		(start 348.928436 -284.938724)
		(end 348.958916 -284.920944)
		(width 0.1143)
		(layer "In13.Cu")
		(net "P5E_CPU0_P0_RX_DN<4>")
	)
	(segment
		(start 346.474034 -372.911624)
		(end 346.474034 -372.911878)
		(width 0.14224)
		(layer "In13.Cu")
		(net "P5E_CPU0_P0_RX_DN<4>")
	)
	(segment
		(start 372.17096 -371.73281)
		(end 372.30812 -371.59565)
		(width 0.14224)
		(layer "In13.Cu")
		(net "P5E_CPU0_P0_RX_DN<4>")
	)
	(segment
		(start 348.928436 -290.773358)
		(end 348.88932 -290.750498)
		(width 0.1143)
		(layer "In13.Cu")
		(net "P5E_CPU0_P0_RX_DN<4>")
	)
	(segment
		(start 381.536956 -364.775496)
		(end 381.335788 -364.775496)
		(width 0.14224)
		(layer "In13.Cu")
		(net "P5E_CPU0_P0_RX_DN<4>")
	)
	(segment
		(start 377.675394 -370.082318)
		(end 377.675394 -369.64747)
		(width 0.14224)
		(layer "In13.Cu")
		(net "P5E_CPU0_P0_RX_DN<4>")
	)
	(segment
		(start 309.048404 -387.92023)
		(end 307.945028 -385.255516)
		(width 0.14224)
		(layer "In13.Cu")
		(net "P5E_CPU0_P0_RX_DN<4>")
	)
	(segment
		(start 371.6147 -371.73281)
		(end 372.17096 -371.73281)
		(width 0.14224)
		(layer "In13.Cu")
		(net "P5E_CPU0_P0_RX_DN<4>")
	)
	(segment
		(start 378.679456 -370.651532)
		(end 378.244608 -370.651532)
		(width 0.14224)
		(layer "In13.Cu")
		(net "P5E_CPU0_P0_RX_DN<4>")
	)
	(segment
		(start 348.928436 -282.673552)
		(end 348.88932 -282.650692)
		(width 0.1143)
		(layer "In13.Cu")
		(net "P5E_CPU0_P0_RX_DN<4>")
	)
	(segment
		(start 309.066438 -393.716764)
		(end 309.066438 -393.545822)
		(width 0.14224)
		(layer "In13.Cu")
		(net "P5E_CPU0_P0_RX_DN<4>")
	)
	(segment
		(start 381.335788 -364.775496)
		(end 375.271538 -370.839746)
		(width 0.14224)
		(layer "In13.Cu")
		(net "P5E_CPU0_P0_RX_DN<4>")
	)
	(segment
		(start 348.88932 -283.341572)
		(end 348.928436 -283.318712)
		(width 0.1143)
		(layer "In13.Cu")
		(net "P5E_CPU0_P0_RX_DN<4>")
	)
	(segment
		(start 348.89059 -294.680386)
		(end 348.927928 -294.658542)
		(width 0.1143)
		(layer "In13.Cu")
		(net "P5E_CPU0_P0_RX_DN<4>")
	)
	(segment
		(start 348.88932 -275.241512)
		(end 348.928436 -275.218652)
		(width 0.1143)
		(layer "In13.Cu")
		(net "P5E_CPU0_P0_RX_DN<4>")
	)
	(segment
		(start 348.958916 -277.831296)
		(end 348.928436 -277.813516)
		(width 0.1143)
		(layer "In13.Cu")
		(net "P5E_CPU0_P0_RX_DN<4>")
	)
	(segment
		(start 348.600268 -296.339514)
		(end 348.645988 -296.293794)
		(width 0.1143)
		(layer "In13.Cu")
		(net "P5E_CPU0_P0_RX_DN<4>")
	)
	(arc
		(start 309.05831 -387.969252)
		(mid 309.05576 -387.94438)
		(end 309.048404 -387.920484)
		(width 0.14224)
		(layer "In13.Cu")
		(net "P5E_CPU0_P0_RX_DN<4>")
	)
	(arc
		(start 349.115888 -287.856168)
		(mid 349.074339 -287.684746)
		(end 348.958916 -287.551368)
		(width 0.1143)
		(layer "In13.Cu")
		(net "P5E_CPU0_P0_RX_DN<4>")
	)
	(arc
		(start 348.88932 -281.03068)
		(mid 348.645993 -280.566114)
		(end 348.88932 -280.101548)
		(width 0.1143)
		(layer "In13.Cu")
		(net "P5E_CPU0_P0_RX_DN<4>")
	)
	(arc
		(start 348.958916 -276.820884)
		(mid 349.115893 -276.516084)
		(end 348.958916 -276.211284)
		(width 0.1143)
		(layer "In13.Cu")
		(net "P5E_CPU0_P0_RX_DN<4>")
	)
	(arc
		(start 348.958916 -293.02075)
		(mid 349.115893 -292.71595)
		(end 348.958916 -292.41115)
		(width 0.1143)
		(layer "In13.Cu")
		(net "P5E_CPU0_P0_RX_DN<4>")
	)
	(arc
		(start 348.88932 -279.410668)
		(mid 348.645993 -278.946102)
		(end 348.88932 -278.481536)
		(width 0.1143)
		(layer "In13.Cu")
		(net "P5E_CPU0_P0_RX_DN<4>")
	)
	(arc
		(start 348.645988 -295.145968)
		(mid 348.710806 -294.882979)
		(end 348.89059 -294.680386)
		(width 0.1143)
		(layer "In13.Cu")
		(net "P5E_CPU0_P0_RX_DN<4>")
	)
	(arc
		(start 348.958916 -278.440896)
		(mid 349.115893 -278.136096)
		(end 348.958916 -277.831296)
		(width 0.1143)
		(layer "In13.Cu")
		(net "P5E_CPU0_P0_RX_DN<4>")
	)
	(arc
		(start 348.958916 -275.200872)
		(mid 349.115893 -274.896072)
		(end 348.958916 -274.591272)
		(width 0.1143)
		(layer "In13.Cu")
		(net "P5E_CPU0_P0_RX_DN<4>")
	)
	(arc
		(start 379.945138 -364.158022)
		(mid 379.972757 -364.116782)
		(end 379.982476 -364.068106)
		(width 0.14224)
		(layer "In13.Cu")
		(net "P5E_CPU0_P0_RX_DN<4>")
	)
	(arc
		(start 306.294536 -378.355352)
		(mid 306.162941 -378.158406)
		(end 306.116736 -377.926092)
		(width 0.14224)
		(layer "In13.Cu")
		(net "P5E_CPU0_P0_RX_DN<4>")
	)
	(arc
		(start 348.932754 -294.656002)
		(mid 349.115212 -294.351362)
		(end 348.960186 -294.031924)
		(width 0.1143)
		(layer "In13.Cu")
		(net "P5E_CPU0_P0_RX_DN<4>")
	)
	(arc
		(start 348.958916 -283.300932)
		(mid 349.115893 -282.996132)
		(end 348.958916 -282.691332)
		(width 0.1143)
		(layer "In13.Cu")
		(net "P5E_CPU0_P0_RX_DN<4>")
	)
	(arc
		(start 348.958916 -289.780726)
		(mid 349.115893 -289.475926)
		(end 348.958916 -289.171126)
		(width 0.1143)
		(layer "In13.Cu")
		(net "P5E_CPU0_P0_RX_DN<4>")
	)
	(arc
		(start 348.958916 -273.58086)
		(mid 349.056681 -273.477884)
		(end 349.10903 -273.34591)
		(width 0.1143)
		(layer "In13.Cu")
		(net "P5E_CPU0_P0_RX_DN<4>")
	)
	(arc
		(start 348.645988 -287.045908)
		(mid 348.710503 -286.783689)
		(end 348.88932 -286.581342)
		(width 0.1143)
		(layer "In13.Cu")
		(net "P5E_CPU0_P0_RX_DN<4>")
	)
	(arc
		(start 333.503524 -372.276116)
		(mid 339.996578 -372.434701)
		(end 346.474034 -372.911624)
		(width 0.14224)
		(layer "In13.Cu")
		(net "P5E_CPU0_P0_RX_DN<4>")
	)
	(arc
		(start 348.88932 -289.130486)
		(mid 348.645993 -288.66592)
		(end 348.88932 -288.201354)
		(width 0.1143)
		(layer "In13.Cu")
		(net "P5E_CPU0_P0_RX_DN<4>")
	)
	(arc
		(start 348.88932 -274.550632)
		(mid 348.645993 -274.086066)
		(end 348.88932 -273.6215)
		(width 0.1143)
		(layer "In13.Cu")
		(net "P5E_CPU0_P0_RX_DN<4>")
	)
	(arc
		(start 348.960948 -286.539686)
		(mid 349.074877 -286.406539)
		(end 349.115888 -286.236156)
		(width 0.1143)
		(layer "In13.Cu")
		(net "P5E_CPU0_P0_RX_DN<4>")
	)
	(arc
		(start 306.116736 -377.036838)
		(mid 306.147899 -376.88026)
		(end 306.236624 -376.747532)
		(width 0.14224)
		(layer "In13.Cu")
		(net "P5E_CPU0_P0_RX_DN<4>")
	)
	(arc
		(start 307.945028 -385.255516)
		(mid 307.921825 -385.178682)
		(end 307.91404 -385.098798)
		(width 0.14224)
		(layer "In13.Cu")
		(net "P5E_CPU0_P0_RX_DN<4>")
	)
	(arc
		(start 348.958916 -291.400738)
		(mid 349.115893 -291.095938)
		(end 348.958916 -290.791138)
		(width 0.1143)
		(layer "In13.Cu")
		(net "P5E_CPU0_P0_RX_DN<4>")
	)
	(arc
		(start 307.058568 -375.925588)
		(mid 307.191288 -375.836844)
		(end 307.347874 -375.8057)
		(width 0.14224)
		(layer "In13.Cu")
		(net "P5E_CPU0_P0_RX_DN<4>")
	)
	(arc
		(start 307.913786 -379.420628)
		(mid 307.901611 -379.358948)
		(end 307.866796 -379.306582)
		(width 0.14224)
		(layer "In13.Cu")
		(net "P5E_CPU0_P0_RX_DN<4>")
	)
	(arc
		(start 348.88932 -285.890716)
		(mid 348.645993 -285.42615)
		(end 348.88932 -284.961584)
		(width 0.1143)
		(layer "In13.Cu")
		(net "P5E_CPU0_P0_RX_DN<4>")
	)
	(arc
		(start 307.558948 -378.998734)
		(mid 307.510074 -378.958639)
		(end 307.4543 -378.928884)
		(width 0.14224)
		(layer "In13.Cu")
		(net "P5E_CPU0_P0_RX_DN<4>")
	)
	(arc
		(start 349.115888 -286.236156)
		(mid 349.074339 -286.064734)
		(end 348.958916 -285.931356)
		(width 0.1143)
		(layer "In13.Cu")
		(net "P5E_CPU0_P0_RX_DN<4>")
	)
	(arc
		(start 348.88932 -292.37051)
		(mid 348.645993 -291.905944)
		(end 348.88932 -291.441378)
		(width 0.1143)
		(layer "In13.Cu")
		(net "P5E_CPU0_P0_RX_DN<4>")
	)
	(arc
		(start 310.267604 -374.245378)
		(mid 310.400469 -374.156663)
		(end 310.557164 -374.12549)
		(width 0.14224)
		(layer "In13.Cu")
		(net "P5E_CPU0_P0_RX_DN<4>")
	)
	(arc
		(start 348.88932 -276.170644)
		(mid 348.645993 -275.706078)
		(end 348.88932 -275.241512)
		(width 0.1143)
		(layer "In13.Cu")
		(net "P5E_CPU0_P0_RX_DN<4>")
	)
	(arc
		(start 348.88932 -282.650692)
		(mid 348.645993 -282.186126)
		(end 348.88932 -281.72156)
		(width 0.1143)
		(layer "In13.Cu")
		(net "P5E_CPU0_P0_RX_DN<4>")
	)
	(arc
		(start 348.941136 -298.763436)
		(mid 348.687983 -298.32071)
		(end 348.600268 -297.818302)
		(width 0.14224)
		(layer "In13.Cu")
		(net "P5E_CPU0_P0_RX_DN<4>")
	)
	(arc
		(start 325.273416 -372.468648)
		(mid 326.247094 -372.324303)
		(end 327.230232 -372.276116)
		(width 0.14224)
		(layer "In13.Cu")
		(net "P5E_CPU0_P0_RX_DN<4>")
	)
	(arc
		(start 348.88932 -277.790656)
		(mid 348.645993 -277.32609)
		(end 348.88932 -276.861524)
		(width 0.1143)
		(layer "In13.Cu")
		(net "P5E_CPU0_P0_RX_DN<4>")
	)
	(arc
		(start 348.88932 -293.990522)
		(mid 348.645993 -293.525956)
		(end 348.88932 -293.06139)
		(width 0.1143)
		(layer "In13.Cu")
		(net "P5E_CPU0_P0_RX_DN<4>")
	)
	(arc
		(start 348.958916 -284.920944)
		(mid 349.115893 -284.616144)
		(end 348.958916 -284.311344)
		(width 0.1143)
		(layer "In13.Cu")
		(net "P5E_CPU0_P0_RX_DN<4>")
	)
	(arc
		(start 308.64048 -375.8057)
		(mid 308.702203 -375.793423)
		(end 308.754526 -375.758456)
		(width 0.14224)
		(layer "In13.Cu")
		(net "P5E_CPU0_P0_RX_DN<4>")
	)
	(arc
		(start 348.958916 -280.060908)
		(mid 349.115893 -279.756108)
		(end 348.958916 -279.451308)
		(width 0.1143)
		(layer "In13.Cu")
		(net "P5E_CPU0_P0_RX_DN<4>")
	)
	(arc
		(start 306.565808 -378.561346)
		(mid 306.461473 -378.505697)
		(end 306.369974 -378.43079)
		(width 0.14224)
		(layer "In13.Cu")
		(net "P5E_CPU0_P0_RX_DN<4>")
	)
	(arc
		(start 348.88932 -284.270704)
		(mid 348.645993 -283.806138)
		(end 348.88932 -283.341572)
		(width 0.1143)
		(layer "In13.Cu")
		(net "P5E_CPU0_P0_RX_DN<4>")
	)
	(arc
		(start 348.960948 -288.159698)
		(mid 349.074877 -288.026551)
		(end 349.115888 -287.856168)
		(width 0.1143)
		(layer "In13.Cu")
		(net "P5E_CPU0_P0_RX_DN<4>")
	)
	(arc
		(start 348.89186 -287.512252)
		(mid 348.711208 -287.309507)
		(end 348.645988 -287.045908)
		(width 0.1143)
		(layer "In13.Cu")
		(net "P5E_CPU0_P0_RX_DN<4>")
	)
	(arc
		(start 348.88932 -290.750498)
		(mid 348.645993 -290.285932)
		(end 348.88932 -289.821366)
		(width 0.1143)
		(layer "In13.Cu")
		(net "P5E_CPU0_P0_RX_DN<4>")
	)
	(arc
		(start 348.958916 -281.68092)
		(mid 349.115893 -281.37612)
		(end 348.958916 -281.07132)
		(width 0.1143)
		(layer "In13.Cu")
		(net "P5E_CPU0_P0_RX_DN<4>")
	)
	(segment
		(start 306.870354 -393.69238)
		(end 307.391054 -393.69238)
		(width 0.127)
		(layer "F.Cu")
		(net "P5E_CPU0_P0_RX_DN<3>")
	)
	(segment
		(start 349.20809 -271.39011)
		(end 348.741238 -271.656048)
		(width 0.12954)
		(layer "F.Cu")
		(net "P5E_CPU0_P0_RX_DN<3>")
	)
	(segment
		(start 304.04054 -379.740668)
		(end 303.90338 -379.603508)
		(width 0.14224)
		(layer "In13.Cu")
		(net "P5E_CPU0_P0_RX_DN<3>")
	)
	(segment
		(start 348.431866 -272.802604)
		(end 348.563438 -272.712942)
		(width 0.1143)
		(layer "In13.Cu")
		(net "P5E_CPU0_P0_RX_DN<3>")
	)
	(segment
		(start 347.95079 -284.960568)
		(end 348.020132 -284.920182)
		(width 0.1143)
		(layer "In13.Cu")
		(net "P5E_CPU0_P0_RX_DN<3>")
	)
	(segment
		(start 347.660214 -295.853358)
		(end 347.660214 -295.83888)
		(width 0.1143)
		(layer "In13.Cu")
		(net "P5E_CPU0_P0_RX_DN<3>")
	)
	(segment
		(start 349.10903 -271.725898)
		(end 349.03918 -271.656048)
		(width 0.1143)
		(layer "In13.Cu")
		(net "P5E_CPU0_P0_RX_DN<3>")
	)
	(segment
		(start 306.323238 -381.91186)
		(end 304.222404 -380.507748)
		(width 0.14224)
		(layer "In13.Cu")
		(net "P5E_CPU0_P0_RX_DN<3>")
	)
	(segment
		(start 303.90338 -377.33224)
		(end 303.90338 -376.90552)
		(width 0.14224)
		(layer "In13.Cu")
		(net "P5E_CPU0_P0_RX_DN<3>")
	)
	(segment
		(start 307.848508 -388.506208)
		(end 307.848508 -388.505954)
		(width 0.14224)
		(layer "In13.Cu")
		(net "P5E_CPU0_P0_RX_DN<3>")
	)
	(segment
		(start 348.020132 -294.031924)
		(end 347.95079 -293.991538)
		(width 0.1143)
		(layer "In13.Cu")
		(net "P5E_CPU0_P0_RX_DN<3>")
	)
	(segment
		(start 316.182756 -373.19331)
		(end 325.81342 -371.277642)
		(width 0.14224)
		(layer "In13.Cu")
		(net "P5E_CPU0_P0_RX_DN<3>")
	)
	(segment
		(start 308.849522 -373.19331)
		(end 316.182756 -373.19331)
		(width 0.14224)
		(layer "In13.Cu")
		(net "P5E_CPU0_P0_RX_DN<3>")
	)
	(segment
		(start 369.50904 -369.719606)
		(end 372.725188 -369.72367)
		(width 0.14224)
		(layer "In13.Cu")
		(net "P5E_CPU0_P0_RX_DN<3>")
	)
	(segment
		(start 368.91214 -369.105688)
		(end 365.722408 -372.29542)
		(width 0.14224)
		(layer "In13.Cu")
		(net "P5E_CPU0_P0_RX_DN<3>")
	)
	(segment
		(start 366.327944 -372.900702)
		(end 369.50904 -369.719606)
		(width 0.14224)
		(layer "In13.Cu")
		(net "P5E_CPU0_P0_RX_DN<3>")
	)
	(segment
		(start 307.866542 -393.545822)
		(end 307.54955 -393.22883)
		(width 0.14224)
		(layer "In13.Cu")
		(net "P5E_CPU0_P0_RX_DN<3>")
	)
	(segment
		(start 348.020132 -282.692094)
		(end 347.95079 -282.651708)
		(width 0.1143)
		(layer "In13.Cu")
		(net "P5E_CPU0_P0_RX_DN<3>")
	)
	(segment
		(start 362.815378 -373.19331)
		(end 367.90757 -368.101118)
		(width 0.14224)
		(layer "In13.Cu")
		(net "P5E_CPU0_P0_RX_DN<3>")
	)
	(segment
		(start 378.358146 -360.817922)
		(end 378.358146 -356.207822)
		(width 0.14224)
		(layer "In13.Cu")
		(net "P5E_CPU0_P0_RX_DN<3>")
	)
	(segment
		(start 348.020132 -277.832058)
		(end 347.95079 -277.791672)
		(width 0.1143)
		(layer "In13.Cu")
		(net "P5E_CPU0_P0_RX_DN<3>")
	)
	(segment
		(start 347.95079 -278.48052)
		(end 348.020132 -278.440134)
		(width 0.1143)
		(layer "In13.Cu")
		(net "P5E_CPU0_P0_RX_DN<3>")
	)
	(segment
		(start 307.744368 -393.787376)
		(end 307.744876 -393.786868)
		(width 0.14224)
		(layer "In13.Cu")
		(net "P5E_CPU0_P0_RX_DN<3>")
	)
	(segment
		(start 307.554376 -392.616944)
		(end 307.858414 -392.31316)
		(width 0.14224)
		(layer "In13.Cu")
		(net "P5E_CPU0_P0_RX_DN<3>")
	)
	(segment
		(start 305.386994 -374.008396)
		(end 307.772816 -374.008396)
		(width 0.14224)
		(layer "In13.Cu")
		(net "P5E_CPU0_P0_RX_DN<3>")
	)
	(segment
		(start 347.95079 -280.100532)
		(end 348.020132 -280.060146)
		(width 0.1143)
		(layer "In13.Cu")
		(net "P5E_CPU0_P0_RX_DN<3>")
	)
	(segment
		(start 303.90338 -379.176788)
		(end 304.04054 -379.039628)
		(width 0.14224)
		(layer "In13.Cu")
		(net "P5E_CPU0_P0_RX_DN<3>")
	)
	(segment
		(start 347.95079 -275.240496)
		(end 348.020132 -275.20011)
		(width 0.1143)
		(layer "In13.Cu")
		(net "P5E_CPU0_P0_RX_DN<3>")
	)
	(segment
		(start 372.725188 -369.72367)
		(end 378.385832 -364.063026)
		(width 0.14224)
		(layer "In13.Cu")
		(net "P5E_CPU0_P0_RX_DN<3>")
	)
	(segment
		(start 354.831142 -307.480716)
		(end 354.831396 -307.480716)
		(width 0.14224)
		(layer "In13.Cu")
		(net "P5E_CPU0_P0_RX_DN<3>")
	)
	(segment
		(start 356.51821 -309.536592)
		(end 354.831142 -307.480716)
		(width 0.14224)
		(layer "In13.Cu")
		(net "P5E_CPU0_P0_RX_DN<3>")
	)
	(segment
		(start 348.919546 -271.983962)
		(end 348.95917 -271.960594)
		(width 0.1143)
		(layer "In13.Cu")
		(net "P5E_CPU0_P0_RX_DN<3>")
	)
	(segment
		(start 347.95079 -281.720544)
		(end 348.020132 -281.680158)
		(width 0.1143)
		(layer "In13.Cu")
		(net "P5E_CPU0_P0_RX_DN<3>")
	)
	(segment
		(start 347.950028 -287.511236)
		(end 347.924628 -287.493202)
		(width 0.1143)
		(layer "In13.Cu")
		(net "P5E_CPU0_P0_RX_DN<3>")
	)
	(segment
		(start 347.94825 -286.58185)
		(end 348.019878 -286.540194)
		(width 0.1143)
		(layer "In13.Cu")
		(net "P5E_CPU0_P0_RX_DN<3>")
	)
	(segment
		(start 347.95079 -289.82035)
		(end 348.020132 -289.779964)
		(width 0.1143)
		(layer "In13.Cu")
		(net "P5E_CPU0_P0_RX_DN<3>")
	)
	(segment
		(start 348.020132 -281.072082)
		(end 347.95079 -281.031696)
		(width 0.1143)
		(layer "In13.Cu")
		(net "P5E_CPU0_P0_RX_DN<3>")
	)
	(segment
		(start 348.020132 -289.171888)
		(end 347.95079 -289.131502)
		(width 0.1143)
		(layer "In13.Cu")
		(net "P5E_CPU0_P0_RX_DN<3>")
	)
	(segment
		(start 307.858414 -392.31316)
		(end 307.858414 -388.554976)
		(width 0.14224)
		(layer "In13.Cu")
		(net "P5E_CPU0_P0_RX_DN<3>")
	)
	(segment
		(start 353.144328 -305.42484)
		(end 348.083124 -299.25772)
		(width 0.14224)
		(layer "In13.Cu")
		(net "P5E_CPU0_P0_RX_DN<3>")
	)
	(segment
		(start 347.95079 -283.340556)
		(end 348.020132 -283.30017)
		(width 0.1143)
		(layer "In13.Cu")
		(net "P5E_CPU0_P0_RX_DN<3>")
	)
	(segment
		(start 304.04054 -377.89612)
		(end 304.04054 -377.4694)
		(width 0.14224)
		(layer "In13.Cu")
		(net "P5E_CPU0_P0_RX_DN<3>")
	)
	(segment
		(start 347.95079 -293.060374)
		(end 348.020132 -293.019988)
		(width 0.1143)
		(layer "In13.Cu")
		(net "P5E_CPU0_P0_RX_DN<3>")
	)
	(segment
		(start 377.981464 -363.45749)
		(end 377.780042 -363.457744)
		(width 0.14224)
		(layer "In13.Cu")
		(net "P5E_CPU0_P0_RX_DN<3>")
	)
	(segment
		(start 365.722408 -372.496588)
		(end 366.126522 -372.900702)
		(width 0.14224)
		(layer "In13.Cu")
		(net "P5E_CPU0_P0_RX_DN<3>")
	)
	(segment
		(start 348.020132 -279.45207)
		(end 347.95079 -279.411684)
		(width 0.1143)
		(layer "In13.Cu")
		(net "P5E_CPU0_P0_RX_DN<3>")
	)
	(segment
		(start 361.579668 -315.703712)
		(end 356.51821 -309.536338)
		(width 0.14224)
		(layer "In13.Cu")
		(net "P5E_CPU0_P0_RX_DN<3>")
	)
	(segment
		(start 307.391054 -393.69238)
		(end 307.744368 -393.787376)
		(width 0.14224)
		(layer "In13.Cu")
		(net "P5E_CPU0_P0_RX_DN<3>")
	)
	(segment
		(start 365.722408 -372.29542)
		(end 365.722408 -372.496588)
		(width 0.14224)
		(layer "In13.Cu")
		(net "P5E_CPU0_P0_RX_DN<3>")
	)
	(segment
		(start 348.020132 -276.212046)
		(end 347.95079 -276.17166)
		(width 0.1143)
		(layer "In13.Cu")
		(net "P5E_CPU0_P0_RX_DN<3>")
	)
	(segment
		(start 307.744876 -393.786868)
		(end 307.866542 -393.716764)
		(width 0.14224)
		(layer "In13.Cu")
		(net "P5E_CPU0_P0_RX_DN<3>")
	)
	(segment
		(start 303.90338 -376.90552)
		(end 304.04054 -376.76836)
		(width 0.14224)
		(layer "In13.Cu")
		(net "P5E_CPU0_P0_RX_DN<3>")
	)
	(segment
		(start 304.04054 -379.039628)
		(end 304.04054 -378.59716)
		(width 0.14224)
		(layer "In13.Cu")
		(net "P5E_CPU0_P0_RX_DN<3>")
	)
	(segment
		(start 368.91214 -368.67084)
		(end 368.91214 -369.105688)
		(width 0.14224)
		(layer "In13.Cu")
		(net "P5E_CPU0_P0_RX_DN<3>")
	)
	(segment
		(start 348.020132 -284.312106)
		(end 347.95079 -284.27172)
		(width 0.1143)
		(layer "In13.Cu")
		(net "P5E_CPU0_P0_RX_DN<3>")
	)
	(segment
		(start 372.030498 -368.773456)
		(end 371.460014 -368.20348)
		(width 0.14224)
		(layer "In13.Cu")
		(net "P5E_CPU0_P0_RX_DN<3>")
	)
	(segment
		(start 349.03918 -271.656048)
		(end 348.741238 -271.656048)
		(width 0.1143)
		(layer "In13.Cu")
		(net "P5E_CPU0_P0_RX_DN<3>")
	)
	(segment
		(start 367.90757 -368.101118)
		(end 368.342418 -368.101118)
		(width 0.14224)
		(layer "In13.Cu")
		(net "P5E_CPU0_P0_RX_DN<3>")
	)
	(segment
		(start 303.90338 -379.603508)
		(end 303.90338 -379.176788)
		(width 0.14224)
		(layer "In13.Cu")
		(net "P5E_CPU0_P0_RX_DN<3>")
	)
	(segment
		(start 303.90338 -378.03328)
		(end 304.04054 -377.89612)
		(width 0.14224)
		(layer "In13.Cu")
		(net "P5E_CPU0_P0_RX_DN<3>")
	)
	(segment
		(start 347.95079 -291.440362)
		(end 348.020132 -291.399976)
		(width 0.1143)
		(layer "In13.Cu")
		(net "P5E_CPU0_P0_RX_DN<3>")
	)
	(segment
		(start 348.020132 -290.7919)
		(end 347.95079 -290.751514)
		(width 0.1143)
		(layer "In13.Cu")
		(net "P5E_CPU0_P0_RX_DN<3>")
	)
	(segment
		(start 327.176638 -371.119654)
		(end 333.17942 -371.119654)
		(width 0.14224)
		(layer "In13.Cu")
		(net "P5E_CPU0_P0_RX_DN<3>")
	)
	(segment
		(start 347.705934 -295.79316)
		(end 347.705934 -295.101264)
		(width 0.1143)
		(layer "In13.Cu")
		(net "P5E_CPU0_P0_RX_DN<3>")
	)
	(segment
		(start 368.342418 -368.101118)
		(end 368.91214 -368.67084)
		(width 0.14224)
		(layer "In13.Cu")
		(net "P5E_CPU0_P0_RX_DN<3>")
	)
	(segment
		(start 348.020132 -285.932118)
		(end 347.95079 -285.891732)
		(width 0.1143)
		(layer "In13.Cu")
		(net "P5E_CPU0_P0_RX_DN<3>")
	)
	(segment
		(start 347.660214 -295.83888)
		(end 347.705934 -295.79316)
		(width 0.1143)
		(layer "In13.Cu")
		(net "P5E_CPU0_P0_RX_DN<3>")
	)
	(segment
		(start 347.948504 -288.201608)
		(end 348.020132 -288.160206)
		(width 0.1143)
		(layer "In13.Cu")
		(net "P5E_CPU0_P0_RX_DN<3>")
	)
	(segment
		(start 347.660214 -298.07535)
		(end 347.660214 -295.853358)
		(width 0.14224)
		(layer "In13.Cu")
		(net "P5E_CPU0_P0_RX_DN<3>")
	)
	(segment
		(start 307.848508 -388.505954)
		(end 306.413408 -385.040632)
		(width 0.14224)
		(layer "In13.Cu")
		(net "P5E_CPU0_P0_RX_DN<3>")
	)
	(segment
		(start 378.358146 -356.207822)
		(end 361.579668 -315.703712)
		(width 0.14224)
		(layer "In13.Cu")
		(net "P5E_CPU0_P0_RX_DN<3>")
	)
	(segment
		(start 344.820494 -371.742208)
		(end 359.551478 -373.19331)
		(width 0.14224)
		(layer "In13.Cu")
		(net "P5E_CPU0_P0_RX_DN<3>")
	)
	(segment
		(start 307.866542 -393.716764)
		(end 307.866542 -393.545822)
		(width 0.14224)
		(layer "In13.Cu")
		(net "P5E_CPU0_P0_RX_DN<3>")
	)
	(segment
		(start 347.95079 -273.620484)
		(end 348.020132 -273.580098)
		(width 0.1143)
		(layer "In13.Cu")
		(net "P5E_CPU0_P0_RX_DN<3>")
	)
	(segment
		(start 377.780042 -363.457744)
		(end 372.464076 -368.773456)
		(width 0.14224)
		(layer "In13.Cu")
		(net "P5E_CPU0_P0_RX_DN<3>")
	)
	(segment
		(start 348.020132 -292.411912)
		(end 347.95079 -292.371526)
		(width 0.1143)
		(layer "In13.Cu")
		(net "P5E_CPU0_P0_RX_DN<3>")
	)
	(segment
		(start 356.51821 -309.536338)
		(end 356.51821 -309.536592)
		(width 0.14224)
		(layer "In13.Cu")
		(net "P5E_CPU0_P0_RX_DN<3>")
	)
	(segment
		(start 348.95917 -271.960594)
		(end 348.959932 -271.960086)
		(width 0.1143)
		(layer "In13.Cu")
		(net "P5E_CPU0_P0_RX_DN<3>")
	)
	(segment
		(start 348.018608 -287.550606)
		(end 347.950028 -287.511236)
		(width 0.1143)
		(layer "In13.Cu")
		(net "P5E_CPU0_P0_RX_DN<3>")
	)
	(segment
		(start 347.705934 -295.101264)
		(end 347.70822 -295.096692)
		(width 0.1143)
		(layer "In13.Cu")
		(net "P5E_CPU0_P0_RX_DN<3>")
	)
	(segment
		(start 304.04054 -378.59716)
		(end 303.90338 -378.46)
		(width 0.14224)
		(layer "In13.Cu")
		(net "P5E_CPU0_P0_RX_DN<3>")
	)
	(segment
		(start 304.170334 -374.969532)
		(end 304.950876 -374.18899)
		(width 0.14224)
		(layer "In13.Cu")
		(net "P5E_CPU0_P0_RX_DN<3>")
	)
	(segment
		(start 304.04054 -376.76836)
		(end 304.04054 -375.282968)
		(width 0.14224)
		(layer "In13.Cu")
		(net "P5E_CPU0_P0_RX_DN<3>")
	)
	(segment
		(start 378.385832 -363.861858)
		(end 377.981464 -363.45749)
		(width 0.14224)
		(layer "In13.Cu")
		(net "P5E_CPU0_P0_RX_DN<3>")
	)
	(segment
		(start 371.460014 -367.768632)
		(end 378.320808 -360.907838)
		(width 0.14224)
		(layer "In13.Cu")
		(net "P5E_CPU0_P0_RX_DN<3>")
	)
	(segment
		(start 347.922596 -286.600392)
		(end 347.94825 -286.58185)
		(width 0.1143)
		(layer "In13.Cu")
		(net "P5E_CPU0_P0_RX_DN<3>")
	)
	(segment
		(start 304.04054 -380.167388)
		(end 304.04054 -379.740668)
		(width 0.14224)
		(layer "In13.Cu")
		(net "P5E_CPU0_P0_RX_DN<3>")
	)
	(segment
		(start 347.95079 -276.860508)
		(end 348.020132 -276.820122)
		(width 0.1143)
		(layer "In13.Cu")
		(net "P5E_CPU0_P0_RX_DN<3>")
	)
	(segment
		(start 378.385832 -364.063026)
		(end 378.385832 -363.861858)
		(width 0.14224)
		(layer "In13.Cu")
		(net "P5E_CPU0_P0_RX_DN<3>")
	)
	(segment
		(start 304.04054 -377.4694)
		(end 303.90338 -377.33224)
		(width 0.14224)
		(layer "In13.Cu")
		(net "P5E_CPU0_P0_RX_DN<3>")
	)
	(segment
		(start 348.643956 -272.55724)
		(end 348.643956 -272.466308)
		(width 0.1143)
		(layer "In13.Cu")
		(net "P5E_CPU0_P0_RX_DN<3>")
	)
	(segment
		(start 348.020132 -274.592034)
		(end 347.95079 -274.551648)
		(width 0.1143)
		(layer "In13.Cu")
		(net "P5E_CPU0_P0_RX_DN<3>")
	)
	(segment
		(start 347.95079 -294.680386)
		(end 348.020132 -294.64)
		(width 0.1143)
		(layer "In13.Cu")
		(net "P5E_CPU0_P0_RX_DN<3>")
	)
	(segment
		(start 303.90338 -378.46)
		(end 303.90338 -378.03328)
		(width 0.14224)
		(layer "In13.Cu")
		(net "P5E_CPU0_P0_RX_DN<3>")
	)
	(segment
		(start 354.831396 -307.480716)
		(end 353.144328 -305.42484)
		(width 0.14224)
		(layer "In13.Cu")
		(net "P5E_CPU0_P0_RX_DN<3>")
	)
	(segment
		(start 372.464076 -368.773456)
		(end 372.030498 -368.773456)
		(width 0.14224)
		(layer "In13.Cu")
		(net "P5E_CPU0_P0_RX_DN<3>")
	)
	(segment
		(start 371.460014 -368.20348)
		(end 371.460014 -367.768632)
		(width 0.14224)
		(layer "In13.Cu")
		(net "P5E_CPU0_P0_RX_DN<3>")
	)
	(segment
		(start 307.905912 -373.953278)
		(end 308.536086 -373.323104)
		(width 0.14224)
		(layer "In13.Cu")
		(net "P5E_CPU0_P0_RX_DN<3>")
	)
	(segment
		(start 359.551478 -373.19331)
		(end 362.815378 -373.19331)
		(width 0.14224)
		(layer "In13.Cu")
		(net "P5E_CPU0_P0_RX_DN<3>")
	)
	(segment
		(start 348.176088 -273.27606)
		(end 348.176088 -273.185128)
		(width 0.1143)
		(layer "In13.Cu")
		(net "P5E_CPU0_P0_RX_DN<3>")
	)
	(segment
		(start 306.38242 -384.883914)
		(end 306.38242 -382.022604)
		(width 0.14224)
		(layer "In13.Cu")
		(net "P5E_CPU0_P0_RX_DN<3>")
	)
	(segment
		(start 307.54955 -393.22883)
		(end 307.554376 -392.616944)
		(width 0.14224)
		(layer "In13.Cu")
		(net "P5E_CPU0_P0_RX_DN<3>")
	)
	(segment
		(start 348.33687 -272.870168)
		(end 348.384876 -272.835624)
		(width 0.1143)
		(layer "In13.Cu")
		(net "P5E_CPU0_P0_RX_DN<3>")
	)
	(segment
		(start 366.126522 -372.900702)
		(end 366.327944 -372.900702)
		(width 0.14224)
		(layer "In13.Cu")
		(net "P5E_CPU0_P0_RX_DN<3>")
	)
	(arc
		(start 348.083124 -299.25772)
		(mid 347.769093 -298.703221)
		(end 347.660214 -298.07535)
		(width 0.14224)
		(layer "In13.Cu")
		(net "P5E_CPU0_P0_RX_DN<3>")
	)
	(arc
		(start 308.536086 -373.323104)
		(mid 308.679892 -373.227016)
		(end 308.849522 -373.19331)
		(width 0.14224)
		(layer "In13.Cu")
		(net "P5E_CPU0_P0_RX_DN<3>")
	)
	(arc
		(start 304.950876 -374.18899)
		(mid 305.150983 -374.055346)
		(end 305.386994 -374.008396)
		(width 0.14224)
		(layer "In13.Cu")
		(net "P5E_CPU0_P0_RX_DN<3>")
	)
	(arc
		(start 304.04054 -375.282968)
		(mid 304.074279 -375.113351)
		(end 304.170334 -374.969532)
		(width 0.14224)
		(layer "In13.Cu")
		(net "P5E_CPU0_P0_RX_DN<3>")
	)
	(arc
		(start 347.706188 -288.66592)
		(mid 347.770364 -288.404033)
		(end 347.948504 -288.201608)
		(width 0.1143)
		(layer "In13.Cu")
		(net "P5E_CPU0_P0_RX_DN<3>")
	)
	(arc
		(start 348.020132 -281.680158)
		(mid 348.175959 -281.37612)
		(end 348.020132 -281.072082)
		(width 0.1143)
		(layer "In13.Cu")
		(net "P5E_CPU0_P0_RX_DN<3>")
	)
	(arc
		(start 307.858414 -388.554976)
		(mid 307.855864 -388.530104)
		(end 307.848508 -388.506208)
		(width 0.14224)
		(layer "In13.Cu")
		(net "P5E_CPU0_P0_RX_DN<3>")
	)
	(arc
		(start 348.020132 -288.160206)
		(mid 348.176164 -287.854999)
		(end 348.018608 -287.550606)
		(width 0.1143)
		(layer "In13.Cu")
		(net "P5E_CPU0_P0_RX_DN<3>")
	)
	(arc
		(start 306.38242 -382.022604)
		(mid 306.366688 -381.959833)
		(end 306.323238 -381.91186)
		(width 0.14224)
		(layer "In13.Cu")
		(net "P5E_CPU0_P0_RX_DN<3>")
	)
	(arc
		(start 347.95079 -277.791672)
		(mid 347.705969 -277.32609)
		(end 347.95079 -276.860508)
		(width 0.1143)
		(layer "In13.Cu")
		(net "P5E_CPU0_P0_RX_DN<3>")
	)
	(arc
		(start 348.020132 -283.30017)
		(mid 348.175959 -282.996132)
		(end 348.020132 -282.692094)
		(width 0.1143)
		(layer "In13.Cu")
		(net "P5E_CPU0_P0_RX_DN<3>")
	)
	(arc
		(start 348.020132 -293.019988)
		(mid 348.175959 -292.71595)
		(end 348.020132 -292.411912)
		(width 0.1143)
		(layer "In13.Cu")
		(net "P5E_CPU0_P0_RX_DN<3>")
	)
	(arc
		(start 348.020132 -278.440134)
		(mid 348.175959 -278.136096)
		(end 348.020132 -277.832058)
		(width 0.1143)
		(layer "In13.Cu")
		(net "P5E_CPU0_P0_RX_DN<3>")
	)
	(arc
		(start 333.17942 -371.119654)
		(mid 333.398624 -371.121756)
		(end 333.617824 -371.124226)
		(width 0.14224)
		(layer "In13.Cu")
		(net "P5E_CPU0_P0_RX_DN<3>")
	)
	(arc
		(start 348.020132 -294.64)
		(mid 348.175959 -294.335962)
		(end 348.020132 -294.031924)
		(width 0.1143)
		(layer "In13.Cu")
		(net "P5E_CPU0_P0_RX_DN<3>")
	)
	(arc
		(start 325.81342 -371.277642)
		(mid 326.491835 -371.171089)
		(end 327.176638 -371.119654)
		(width 0.14224)
		(layer "In13.Cu")
		(net "P5E_CPU0_P0_RX_DN<3>")
	)
	(arc
		(start 347.95079 -285.891732)
		(mid 347.705969 -285.42615)
		(end 347.95079 -284.960568)
		(width 0.1143)
		(layer "In13.Cu")
		(net "P5E_CPU0_P0_RX_DN<3>")
	)
	(arc
		(start 347.70822 -295.096692)
		(mid 347.782946 -294.861423)
		(end 347.95079 -294.680386)
		(width 0.1143)
		(layer "In13.Cu")
		(net "P5E_CPU0_P0_RX_DN<3>")
	)
	(arc
		(start 347.95079 -290.751514)
		(mid 347.705969 -290.285932)
		(end 347.95079 -289.82035)
		(width 0.1143)
		(layer "In13.Cu")
		(net "P5E_CPU0_P0_RX_DN<3>")
	)
	(arc
		(start 347.95079 -289.131502)
		(mid 347.770998 -288.928914)
		(end 347.706188 -288.66592)
		(width 0.1143)
		(layer "In13.Cu")
		(net "P5E_CPU0_P0_RX_DN<3>")
	)
	(arc
		(start 348.019878 -286.540194)
		(mid 348.175811 -286.236259)
		(end 348.020132 -285.932118)
		(width 0.1143)
		(layer "In13.Cu")
		(net "P5E_CPU0_P0_RX_DN<3>")
	)
	(arc
		(start 348.643956 -272.466308)
		(mid 348.717644 -272.1885)
		(end 348.919546 -271.983962)
		(width 0.1143)
		(layer "In13.Cu")
		(net "P5E_CPU0_P0_RX_DN<3>")
	)
	(arc
		(start 348.020132 -284.920182)
		(mid 348.175959 -284.616144)
		(end 348.020132 -284.312106)
		(width 0.1143)
		(layer "In13.Cu")
		(net "P5E_CPU0_P0_RX_DN<3>")
	)
	(arc
		(start 347.95079 -293.991538)
		(mid 347.705969 -293.525956)
		(end 347.95079 -293.060374)
		(width 0.1143)
		(layer "In13.Cu")
		(net "P5E_CPU0_P0_RX_DN<3>")
	)
	(arc
		(start 347.95079 -292.371526)
		(mid 347.705969 -291.905944)
		(end 347.95079 -291.440362)
		(width 0.1143)
		(layer "In13.Cu")
		(net "P5E_CPU0_P0_RX_DN<3>")
	)
	(arc
		(start 347.95079 -279.411684)
		(mid 347.705969 -278.946102)
		(end 347.95079 -278.48052)
		(width 0.1143)
		(layer "In13.Cu")
		(net "P5E_CPU0_P0_RX_DN<3>")
	)
	(arc
		(start 348.384876 -272.835624)
		(mid 348.408265 -272.818963)
		(end 348.431866 -272.802604)
		(width 0.1143)
		(layer "In13.Cu")
		(net "P5E_CPU0_P0_RX_DN<3>")
	)
	(arc
		(start 348.626176 -272.639028)
		(mid 348.63947 -272.599091)
		(end 348.643956 -272.55724)
		(width 0.1143)
		(layer "In13.Cu")
		(net "P5E_CPU0_P0_RX_DN<3>")
	)
	(arc
		(start 348.020132 -276.820122)
		(mid 348.175959 -276.516084)
		(end 348.020132 -276.212046)
		(width 0.1143)
		(layer "In13.Cu")
		(net "P5E_CPU0_P0_RX_DN<3>")
	)
	(arc
		(start 306.413408 -385.040632)
		(mid 306.390205 -384.963798)
		(end 306.38242 -384.883914)
		(width 0.14224)
		(layer "In13.Cu")
		(net "P5E_CPU0_P0_RX_DN<3>")
	)
	(arc
		(start 378.320808 -360.907838)
		(mid 378.348427 -360.866598)
		(end 378.358146 -360.817922)
		(width 0.14224)
		(layer "In13.Cu")
		(net "P5E_CPU0_P0_RX_DN<3>")
	)
	(arc
		(start 348.020132 -291.399976)
		(mid 348.175959 -291.095938)
		(end 348.020132 -290.7919)
		(width 0.1143)
		(layer "In13.Cu")
		(net "P5E_CPU0_P0_RX_DN<3>")
	)
	(arc
		(start 347.924628 -287.493202)
		(mid 347.694666 -287.047357)
		(end 347.922596 -286.600392)
		(width 0.1143)
		(layer "In13.Cu")
		(net "P5E_CPU0_P0_RX_DN<3>")
	)
	(arc
		(start 347.95079 -274.551648)
		(mid 347.705969 -274.086066)
		(end 347.95079 -273.620484)
		(width 0.1143)
		(layer "In13.Cu")
		(net "P5E_CPU0_P0_RX_DN<3>")
	)
	(arc
		(start 304.222404 -380.507748)
		(mid 304.088864 -380.360336)
		(end 304.04054 -380.167388)
		(width 0.14224)
		(layer "In13.Cu")
		(net "P5E_CPU0_P0_RX_DN<3>")
	)
	(arc
		(start 347.95079 -281.031696)
		(mid 347.705969 -280.566114)
		(end 347.95079 -280.100532)
		(width 0.1143)
		(layer "In13.Cu")
		(net "P5E_CPU0_P0_RX_DN<3>")
	)
	(arc
		(start 348.020132 -289.779964)
		(mid 348.175959 -289.475926)
		(end 348.020132 -289.171888)
		(width 0.1143)
		(layer "In13.Cu")
		(net "P5E_CPU0_P0_RX_DN<3>")
	)
	(arc
		(start 347.95079 -276.17166)
		(mid 347.705969 -275.706078)
		(end 347.95079 -275.240496)
		(width 0.1143)
		(layer "In13.Cu")
		(net "P5E_CPU0_P0_RX_DN<3>")
	)
	(arc
		(start 348.020132 -275.20011)
		(mid 348.175959 -274.896072)
		(end 348.020132 -274.592034)
		(width 0.1143)
		(layer "In13.Cu")
		(net "P5E_CPU0_P0_RX_DN<3>")
	)
	(arc
		(start 348.970346 -271.952212)
		(mid 349.060394 -271.851746)
		(end 349.10903 -271.725898)
		(width 0.1143)
		(layer "In13.Cu")
		(net "P5E_CPU0_P0_RX_DN<3>")
	)
	(arc
		(start 348.020132 -273.580098)
		(mid 348.134808 -273.446907)
		(end 348.176088 -273.27606)
		(width 0.1143)
		(layer "In13.Cu")
		(net "P5E_CPU0_P0_RX_DN<3>")
	)
	(arc
		(start 348.959932 -271.960086)
		(mid 348.965173 -271.956194)
		(end 348.970346 -271.952212)
		(width 0.1143)
		(layer "In13.Cu")
		(net "P5E_CPU0_P0_RX_DN<3>")
	)
	(arc
		(start 307.772816 -374.008396)
		(mid 307.844842 -373.994069)
		(end 307.905912 -373.953278)
		(width 0.14224)
		(layer "In13.Cu")
		(net "P5E_CPU0_P0_RX_DN<3>")
	)
	(arc
		(start 347.95079 -282.651708)
		(mid 347.705969 -282.186126)
		(end 347.95079 -281.720544)
		(width 0.1143)
		(layer "In13.Cu")
		(net "P5E_CPU0_P0_RX_DN<3>")
	)
	(arc
		(start 348.176088 -273.185128)
		(mid 348.218555 -273.008289)
		(end 348.33687 -272.870168)
		(width 0.1143)
		(layer "In13.Cu")
		(net "P5E_CPU0_P0_RX_DN<3>")
	)
	(arc
		(start 348.563438 -272.712942)
		(mid 348.599795 -272.680218)
		(end 348.626176 -272.639028)
		(width 0.1143)
		(layer "In13.Cu")
		(net "P5E_CPU0_P0_RX_DN<3>")
	)
	(arc
		(start 347.95079 -284.27172)
		(mid 347.705969 -283.806138)
		(end 347.95079 -283.340556)
		(width 0.1143)
		(layer "In13.Cu")
		(net "P5E_CPU0_P0_RX_DN<3>")
	)
	(arc
		(start 348.020132 -280.060146)
		(mid 348.175959 -279.756108)
		(end 348.020132 -279.45207)
		(width 0.1143)
		(layer "In13.Cu")
		(net "P5E_CPU0_P0_RX_DN<3>")
	)
	(arc
		(start 333.617824 -371.124226)
		(mid 339.225806 -371.312715)
		(end 344.820494 -371.742208)
		(width 0.14224)
		(layer "In13.Cu")
		(net "P5E_CPU0_P0_RX_DN<3>")
	)
	(segment
		(start 305.670458 -393.69238)
		(end 306.191158 -393.69238)
		(width 0.127)
		(layer "F.Cu")
		(net "P5E_CPU0_P0_RX_DN<2>")
	)
	(segment
		(start 346.387928 -269.770098)
		(end 345.921076 -270.036036)
		(width 0.12954)
		(layer "F.Cu")
		(net "P5E_CPU0_P0_RX_DN<2>")
	)
	(segment
		(start 305.69662 -388.623048)
		(end 305.506374 -388.585202)
		(width 0.14224)
		(layer "In13.Cu")
		(net "P5E_CPU0_P0_RX_DN<2>")
	)
	(segment
		(start 347.042486 -279.429972)
		(end 347.04274 -279.430226)
		(width 0.1143)
		(layer "In13.Cu")
		(net "P5E_CPU0_P0_RX_DN<2>")
	)
	(segment
		(start 315.44006 -372.25859)
		(end 325.049642 -370.34724)
		(width 0.14224)
		(layer "In13.Cu")
		(net "P5E_CPU0_P0_RX_DN<2>")
	)
	(segment
		(start 377.122944 -360.239056)
		(end 377.122944 -355.98989)
		(width 0.14224)
		(layer "In13.Cu")
		(net "P5E_CPU0_P0_RX_DN<2>")
	)
	(segment
		(start 375.830084 -360.320336)
		(end 369.638834 -366.511586)
		(width 0.14224)
		(layer "In13.Cu")
		(net "P5E_CPU0_P0_RX_DN<2>")
	)
	(segment
		(start 347.055948 -289.79749)
		(end 347.082872 -289.781996)
		(width 0.1143)
		(layer "In13.Cu")
		(net "P5E_CPU0_P0_RX_DN<2>")
	)
	(segment
		(start 347.07322 -282.690824)
		(end 347.048074 -282.67406)
		(width 0.1143)
		(layer "In13.Cu")
		(net "P5E_CPU0_P0_RX_DN<2>")
	)
	(segment
		(start 347.049598 -273.597624)
		(end 347.08338 -273.580606)
		(width 0.1143)
		(layer "In13.Cu")
		(net "P5E_CPU0_P0_RX_DN<2>")
	)
	(segment
		(start 347.04274 -279.430226)
		(end 347.019372 -279.414478)
		(width 0.1143)
		(layer "In13.Cu")
		(net "P5E_CPU0_P0_RX_DN<2>")
	)
	(segment
		(start 346.76588 -287.049718)
		(end 346.76588 -287.045908)
		(width 0.1143)
		(layer "In13.Cu")
		(net "P5E_CPU0_P0_RX_DN<2>")
	)
	(segment
		(start 347.052138 -284.297374)
		(end 347.050106 -284.296358)
		(width 0.1143)
		(layer "In13.Cu")
		(net "P5E_CPU0_P0_RX_DN<2>")
	)
	(segment
		(start 308.45379 -372.25859)
		(end 315.44006 -372.25859)
		(width 0.14224)
		(layer "In13.Cu")
		(net "P5E_CPU0_P0_RX_DN<2>")
	)
	(segment
		(start 306.636928 -390.030462)
		(end 305.69662 -388.623048)
		(width 0.14224)
		(layer "In13.Cu")
		(net "P5E_CPU0_P0_RX_DN<2>")
	)
	(segment
		(start 347.07957 -285.931864)
		(end 347.00972 -285.891478)
		(width 0.1143)
		(layer "In13.Cu")
		(net "P5E_CPU0_P0_RX_DN<2>")
	)
	(segment
		(start 375.239534 -359.316274)
		(end 375.830084 -359.906824)
		(width 0.14224)
		(layer "In13.Cu")
		(net "P5E_CPU0_P0_RX_DN<2>")
	)
	(segment
		(start 347.079824 -294.03167)
		(end 347.015308 -293.994332)
		(width 0.1143)
		(layer "In13.Cu")
		(net "P5E_CPU0_P0_RX_DN<2>")
	)
	(segment
		(start 348.962726 -371.020086)
		(end 358.03586 -371.91442)
		(width 0.14224)
		(layer "In13.Cu")
		(net "P5E_CPU0_P0_RX_DN<2>")
	)
	(segment
		(start 347.017086 -289.818572)
		(end 347.019626 -289.817302)
		(width 0.1143)
		(layer "In13.Cu")
		(net "P5E_CPU0_P0_RX_DN<2>")
	)
	(segment
		(start 347.048074 -284.938724)
		(end 347.051122 -284.936946)
		(width 0.1143)
		(layer "In13.Cu")
		(net "P5E_CPU0_P0_RX_DN<2>")
	)
	(segment
		(start 347.07322 -281.684984)
		(end 347.077792 -281.682444)
		(width 0.1143)
		(layer "In13.Cu")
		(net "P5E_CPU0_P0_RX_DN<2>")
	)
	(segment
		(start 346.714826 -298.647358)
		(end 346.714826 -295.88968)
		(width 0.14224)
		(layer "In13.Cu")
		(net "P5E_CPU0_P0_RX_DN<2>")
	)
	(segment
		(start 304.879502 -387.647434)
		(end 304.642266 -387.292342)
		(width 0.14224)
		(layer "In13.Cu")
		(net "P5E_CPU0_P0_RX_DN<2>")
	)
	(segment
		(start 347.08592 -284.91942)
		(end 347.086682 -284.918912)
		(width 0.1143)
		(layer "In13.Cu")
		(net "P5E_CPU0_P0_RX_DN<2>")
	)
	(segment
		(start 299.277278 -377.824238)
		(end 299.277278 -376.741182)
		(width 0.14224)
		(layer "In13.Cu")
		(net "P5E_CPU0_P0_RX_DN<2>")
	)
	(segment
		(start 347.049598 -289.79749)
		(end 347.055948 -289.79749)
		(width 0.1143)
		(layer "In13.Cu")
		(net "P5E_CPU0_P0_RX_DN<2>")
	)
	(segment
		(start 301.642272 -381.840232)
		(end 301.642272 -379.972824)
		(width 0.14224)
		(layer "In13.Cu")
		(net "P5E_CPU0_P0_RX_DN<2>")
	)
	(segment
		(start 299.45076 -376.322336)
		(end 302.005492 -373.767604)
		(width 0.14224)
		(layer "In13.Cu")
		(net "P5E_CPU0_P0_RX_DN<2>")
	)
	(segment
		(start 347.044772 -284.29331)
		(end 347.008704 -284.272228)
		(width 0.1143)
		(layer "In13.Cu")
		(net "P5E_CPU0_P0_RX_DN<2>")
	)
	(segment
		(start 369.638834 -366.712754)
		(end 370.043456 -367.117376)
		(width 0.14224)
		(layer "In13.Cu")
		(net "P5E_CPU0_P0_RX_DN<2>")
	)
	(segment
		(start 347.011752 -288.199576)
		(end 347.014546 -288.19856)
		(width 0.1143)
		(layer "In13.Cu")
		(net "P5E_CPU0_P0_RX_DN<2>")
	)
	(segment
		(start 347.049852 -283.317696)
		(end 347.051122 -283.316934)
		(width 0.1143)
		(layer "In13.Cu")
		(net "P5E_CPU0_P0_RX_DN<2>")
	)
	(segment
		(start 347.077284 -274.593304)
		(end 347.00972 -274.548346)
		(width 0.1143)
		(layer "In13.Cu")
		(net "P5E_CPU0_P0_RX_DN<2>")
	)
	(segment
		(start 346.586048 -270.528034)
		(end 346.539058 -270.500602)
		(width 0.1143)
		(layer "In13.Cu")
		(net "P5E_CPU0_P0_RX_DN<2>")
	)
	(segment
		(start 347.02623 -273.612864)
		(end 347.048328 -273.598386)
		(width 0.1143)
		(layer "In13.Cu")
		(net "P5E_CPU0_P0_RX_DN<2>")
	)
	(segment
		(start 347.013022 -276.86)
		(end 347.014038 -276.859492)
		(width 0.1143)
		(layer "In13.Cu")
		(net "P5E_CPU0_P0_RX_DN<2>")
	)
	(segment
		(start 347.047566 -281.05354)
		(end 347.011752 -281.03576)
		(width 0.1143)
		(layer "In13.Cu")
		(net "P5E_CPU0_P0_RX_DN<2>")
	)
	(segment
		(start 347.049344 -284.29585)
		(end 347.044772 -284.29331)
		(width 0.1143)
		(layer "In13.Cu")
		(net "P5E_CPU0_P0_RX_DN<2>")
	)
	(segment
		(start 304.053494 -386.164328)
		(end 302.039528 -383.150364)
		(width 0.14224)
		(layer "In13.Cu")
		(net "P5E_CPU0_P0_RX_DN<2>")
	)
	(segment
		(start 347.015308 -293.061644)
		(end 347.103954 -293.010082)
		(width 0.1143)
		(layer "In13.Cu")
		(net "P5E_CPU0_P0_RX_DN<2>")
	)
	(segment
		(start 347.049852 -288.177986)
		(end 347.052646 -288.176208)
		(width 0.1143)
		(layer "In13.Cu")
		(net "P5E_CPU0_P0_RX_DN<2>")
	)
	(segment
		(start 306.544218 -393.787376)
		(end 306.544726 -393.786868)
		(width 0.14224)
		(layer "In13.Cu")
		(net "P5E_CPU0_P0_RX_DN<2>")
	)
	(segment
		(start 347.011752 -281.722322)
		(end 347.0148 -281.720544)
		(width 0.1143)
		(layer "In13.Cu")
		(net "P5E_CPU0_P0_RX_DN<2>")
	)
	(segment
		(start 347.064584 -281.688286)
		(end 347.067886 -281.688286)
		(width 0.1143)
		(layer "In13.Cu")
		(net "P5E_CPU0_P0_RX_DN<2>")
	)
	(segment
		(start 347.00972 -274.548346)
		(end 347.009974 -274.548346)
		(width 0.1143)
		(layer "In13.Cu")
		(net "P5E_CPU0_P0_RX_DN<2>")
	)
	(segment
		(start 347.011752 -284.959806)
		(end 347.048074 -284.938724)
		(width 0.1143)
		(layer "In13.Cu")
		(net "P5E_CPU0_P0_RX_DN<2>")
	)
	(segment
		(start 347.518228 -272.143474)
		(end 347.513656 -272.140934)
		(width 0.1143)
		(layer "In13.Cu")
		(net "P5E_CPU0_P0_RX_DN<2>")
	)
	(segment
		(start 347.004386 -294.679116)
		(end 347.102938 -294.621966)
		(width 0.1143)
		(layer "In13.Cu")
		(net "P5E_CPU0_P0_RX_DN<2>")
	)
	(segment
		(start 347.044264 -286.560768)
		(end 347.079824 -286.540194)
		(width 0.1143)
		(layer "In13.Cu")
		(net "P5E_CPU0_P0_RX_DN<2>")
	)
	(segment
		(start 347.00972 -278.47798)
		(end 347.084904 -278.435054)
		(width 0.1143)
		(layer "In13.Cu")
		(net "P5E_CPU0_P0_RX_DN<2>")
	)
	(segment
		(start 346.714826 -295.861232)
		(end 346.760546 -295.815512)
		(width 0.1143)
		(layer "In13.Cu")
		(net "P5E_CPU0_P0_RX_DN<2>")
	)
	(segment
		(start 346.714826 -295.88968)
		(end 346.714826 -295.861232)
		(width 0.1143)
		(layer "In13.Cu")
		(net "P5E_CPU0_P0_RX_DN<2>")
	)
	(segment
		(start 306.354226 -392.616944)
		(end 306.658264 -392.312906)
		(width 0.14224)
		(layer "In13.Cu")
		(net "P5E_CPU0_P0_RX_DN<2>")
	)
	(segment
		(start 304.252884 -386.709666)
		(end 304.015648 -386.354574)
		(width 0.14224)
		(layer "In13.Cu")
		(net "P5E_CPU0_P0_RX_DN<2>")
	)
	(segment
		(start 374.826022 -359.316274)
		(end 375.239534 -359.316274)
		(width 0.14224)
		(layer "In13.Cu")
		(net "P5E_CPU0_P0_RX_DN<2>")
	)
	(segment
		(start 305.506374 -388.585202)
		(end 305.268884 -388.23011)
		(width 0.14224)
		(layer "In13.Cu")
		(net "P5E_CPU0_P0_RX_DN<2>")
	)
	(segment
		(start 347.058488 -283.31287)
		(end 347.067632 -283.307282)
		(width 0.1143)
		(layer "In13.Cu")
		(net "P5E_CPU0_P0_RX_DN<2>")
	)
	(segment
		(start 347.009974 -274.548346)
		(end 347.00464 -274.544536)
		(width 0.1143)
		(layer "In13.Cu")
		(net "P5E_CPU0_P0_RX_DN<2>")
	)
	(segment
		(start 347.548962 -272.7706)
		(end 347.549724 -272.770092)
		(width 0.1143)
		(layer "In13.Cu")
		(net "P5E_CPU0_P0_RX_DN<2>")
	)
	(segment
		(start 347.019626 -289.817302)
		(end 347.048074 -289.798252)
		(width 0.1143)
		(layer "In13.Cu")
		(net "P5E_CPU0_P0_RX_DN<2>")
	)
	(segment
		(start 347.514926 -272.790666)
		(end 347.548962 -272.7706)
		(width 0.1143)
		(layer "In13.Cu")
		(net "P5E_CPU0_P0_RX_DN<2>")
	)
	(segment
		(start 347.019372 -279.414478)
		(end 347.0148 -279.411938)
		(width 0.1143)
		(layer "In13.Cu")
		(net "P5E_CPU0_P0_RX_DN<2>")
	)
	(segment
		(start 347.049852 -291.417502)
		(end 347.050868 -291.416994)
		(width 0.1143)
		(layer "In13.Cu")
		(net "P5E_CPU0_P0_RX_DN<2>")
	)
	(segment
		(start 347.234764 -273.27987)
		(end 347.234764 -273.278854)
		(width 0.1143)
		(layer "In13.Cu")
		(net "P5E_CPU0_P0_RX_DN<2>")
	)
	(segment
		(start 347.048328 -283.318458)
		(end 347.049852 -283.317696)
		(width 0.1143)
		(layer "In13.Cu")
		(net "P5E_CPU0_P0_RX_DN<2>")
	)
	(segment
		(start 347.048074 -289.798252)
		(end 347.049598 -289.79749)
		(width 0.1143)
		(layer "In13.Cu")
		(net "P5E_CPU0_P0_RX_DN<2>")
	)
	(segment
		(start 347.014546 -288.19856)
		(end 347.049852 -288.177986)
		(width 0.1143)
		(layer "In13.Cu")
		(net "P5E_CPU0_P0_RX_DN<2>")
	)
	(segment
		(start 347.0148 -281.720544)
		(end 347.015308 -281.72029)
		(width 0.1143)
		(layer "In13.Cu")
		(net "P5E_CPU0_P0_RX_DN<2>")
	)
	(segment
		(start 347.052646 -288.176208)
		(end 347.052646 -288.176462)
		(width 0.1143)
		(layer "In13.Cu")
		(net "P5E_CPU0_P0_RX_DN<2>")
	)
	(segment
		(start 362.227876 -371.91442)
		(end 374.826022 -359.316274)
		(width 0.14224)
		(layer "In13.Cu")
		(net "P5E_CPU0_P0_RX_DN<2>")
	)
	(segment
		(start 347.075506 -280.062686)
		(end 347.079824 -280.0604)
		(width 0.1143)
		(layer "In13.Cu")
		(net "P5E_CPU0_P0_RX_DN<2>")
	)
	(segment
		(start 347.548708 -272.161254)
		(end 347.518228 -272.143474)
		(width 0.1143)
		(layer "In13.Cu")
		(net "P5E_CPU0_P0_RX_DN<2>")
	)
	(segment
		(start 347.103954 -293.010082)
		(end 347.120464 -292.994588)
		(width 0.1143)
		(layer "In13.Cu")
		(net "P5E_CPU0_P0_RX_DN<2>")
	)
	(segment
		(start 375.830084 -359.906824)
		(end 375.830084 -360.320336)
		(width 0.14224)
		(layer "In13.Cu")
		(net "P5E_CPU0_P0_RX_DN<2>")
	)
	(segment
		(start 347.048074 -281.698192)
		(end 347.053154 -281.695652)
		(width 0.1143)
		(layer "In13.Cu")
		(net "P5E_CPU0_P0_RX_DN<2>")
	)
	(segment
		(start 347.082872 -289.173412)
		(end 347.011752 -289.132264)
		(width 0.1143)
		(layer "In13.Cu")
		(net "P5E_CPU0_P0_RX_DN<2>")
	)
	(segment
		(start 347.06179 -281.690826)
		(end 347.062552 -281.690318)
		(width 0.1143)
		(layer "In13.Cu")
		(net "P5E_CPU0_P0_RX_DN<2>")
	)
	(segment
		(start 347.048328 -273.598386)
		(end 347.049598 -273.597624)
		(width 0.1143)
		(layer "In13.Cu")
		(net "P5E_CPU0_P0_RX_DN<2>")
	)
	(segment
		(start 346.301822 -270.11884)
		(end 346.219018 -270.036036)
		(width 0.1143)
		(layer "In13.Cu")
		(net "P5E_CPU0_P0_RX_DN<2>")
	)
	(segment
		(start 370.244624 -367.117376)
		(end 377.122944 -360.239056)
		(width 0.14224)
		(layer "In13.Cu")
		(net "P5E_CPU0_P0_RX_DN<2>")
	)
	(segment
		(start 347.048582 -283.318712)
		(end 347.048328 -283.318458)
		(width 0.1143)
		(layer "In13.Cu")
		(net "P5E_CPU0_P0_RX_DN<2>")
	)
	(segment
		(start 306.666392 -393.545822)
		(end 306.3494 -393.22883)
		(width 0.14224)
		(layer "In13.Cu")
		(net "P5E_CPU0_P0_RX_DN<2>")
	)
	(segment
		(start 370.043456 -367.117376)
		(end 370.244624 -367.117376)
		(width 0.14224)
		(layer "In13.Cu")
		(net "P5E_CPU0_P0_RX_DN<2>")
	)
	(segment
		(start 347.08338 -273.580606)
		(end 347.084142 -273.580098)
		(width 0.1143)
		(layer "In13.Cu")
		(net "P5E_CPU0_P0_RX_DN<2>")
	)
	(segment
		(start 303.77384 -373.035068)
		(end 307.367686 -373.035068)
		(width 0.14224)
		(layer "In13.Cu")
		(net "P5E_CPU0_P0_RX_DN<2>")
	)
	(segment
		(start 306.3494 -393.22883)
		(end 306.354226 -392.616944)
		(width 0.14224)
		(layer "In13.Cu")
		(net "P5E_CPU0_P0_RX_DN<2>")
	)
	(segment
		(start 369.638834 -366.511586)
		(end 369.638834 -366.712754)
		(width 0.14224)
		(layer "In13.Cu")
		(net "P5E_CPU0_P0_RX_DN<2>")
	)
	(segment
		(start 347.009974 -275.24075)
		(end 347.07703 -275.20138)
		(width 0.1143)
		(layer "In13.Cu")
		(net "P5E_CPU0_P0_RX_DN<2>")
	)
	(segment
		(start 358.03586 -371.91442)
		(end 362.227876 -371.91442)
		(width 0.14224)
		(layer "In13.Cu")
		(net "P5E_CPU0_P0_RX_DN<2>")
	)
	(segment
		(start 304.44313 -386.747512)
		(end 304.252884 -386.709666)
		(width 0.14224)
		(layer "In13.Cu")
		(net "P5E_CPU0_P0_RX_DN<2>")
	)
	(segment
		(start 346.219018 -270.036036)
		(end 345.921076 -270.036036)
		(width 0.1143)
		(layer "In13.Cu")
		(net "P5E_CPU0_P0_RX_DN<2>")
	)
	(segment
		(start 347.080332 -287.55467)
		(end 347.008196 -287.51276)
		(width 0.1143)
		(layer "In13.Cu")
		(net "P5E_CPU0_P0_RX_DN<2>")
	)
	(segment
		(start 306.544726 -393.786868)
		(end 306.666392 -393.716764)
		(width 0.14224)
		(layer "In13.Cu")
		(net "P5E_CPU0_P0_RX_DN<2>")
	)
	(segment
		(start 347.051122 -284.936946)
		(end 347.08592 -284.91942)
		(width 0.1143)
		(layer "In13.Cu")
		(net "P5E_CPU0_P0_RX_DN<2>")
	)
	(segment
		(start 347.051122 -283.316934)
		(end 347.058488 -283.31287)
		(width 0.1143)
		(layer "In13.Cu")
		(net "P5E_CPU0_P0_RX_DN<2>")
	)
	(segment
		(start 326.839834 -370.170964)
		(end 331.659992 -370.170964)
		(width 0.14224)
		(layer "In13.Cu")
		(net "P5E_CPU0_P0_RX_DN<2>")
	)
	(segment
		(start 307.582824 -372.945914)
		(end 308.140354 -372.388384)
		(width 0.14224)
		(layer "In13.Cu")
		(net "P5E_CPU0_P0_RX_DN<2>")
	)
	(segment
		(start 347.014038 -276.859492)
		(end 347.078554 -276.822408)
		(width 0.1143)
		(layer "In13.Cu")
		(net "P5E_CPU0_P0_RX_DN<2>")
	)
	(segment
		(start 347.068648 -283.306774)
		(end 347.077284 -283.301694)
		(width 0.1143)
		(layer "In13.Cu")
		(net "P5E_CPU0_P0_RX_DN<2>")
	)
	(segment
		(start 347.011752 -276.859746)
		(end 347.013022 -276.86)
		(width 0.1143)
		(layer "In13.Cu")
		(net "P5E_CPU0_P0_RX_DN<2>")
	)
	(segment
		(start 305.268884 -388.23011)
		(end 305.30673 -388.039864)
		(width 0.14224)
		(layer "In13.Cu")
		(net "P5E_CPU0_P0_RX_DN<2>")
	)
	(segment
		(start 304.015648 -386.354574)
		(end 304.053494 -386.164328)
		(width 0.14224)
		(layer "In13.Cu")
		(net "P5E_CPU0_P0_RX_DN<2>")
	)
	(segment
		(start 347.233748 -271.652746)
		(end 347.233748 -271.651984)
		(width 0.1143)
		(layer "In13.Cu")
		(net "P5E_CPU0_P0_RX_DN<2>")
	)
	(segment
		(start 347.084904 -278.435054)
		(end 347.086682 -278.433784)
		(width 0.1143)
		(layer "In13.Cu")
		(net "P5E_CPU0_P0_RX_DN<2>")
	)
	(segment
		(start 306.658264 -392.312906)
		(end 306.658264 -390.101074)
		(width 0.14224)
		(layer "In13.Cu")
		(net "P5E_CPU0_P0_RX_DN<2>")
	)
	(segment
		(start 347.017594 -271.313148)
		(end 347.015308 -271.311624)
		(width 0.1143)
		(layer "In13.Cu")
		(net "P5E_CPU0_P0_RX_DN<2>")
	)
	(segment
		(start 347.050614 -280.077164)
		(end 347.05036 -280.077164)
		(width 0.1143)
		(layer "In13.Cu")
		(net "P5E_CPU0_P0_RX_DN<2>")
	)
	(segment
		(start 304.642266 -387.292342)
		(end 304.680112 -387.102096)
		(width 0.14224)
		(layer "In13.Cu")
		(net "P5E_CPU0_P0_RX_DN<2>")
	)
	(segment
		(start 347.015308 -281.72029)
		(end 347.015054 -281.720544)
		(width 0.1143)
		(layer "In13.Cu")
		(net "P5E_CPU0_P0_RX_DN<2>")
	)
	(segment
		(start 347.07195 -291.404548)
		(end 347.072966 -291.40404)
		(width 0.1143)
		(layer "In13.Cu")
		(net "P5E_CPU0_P0_RX_DN<2>")
	)
	(segment
		(start 347.050106 -284.296358)
		(end 347.049344 -284.29585)
		(width 0.1143)
		(layer "In13.Cu")
		(net "P5E_CPU0_P0_RX_DN<2>")
	)
	(segment
		(start 346.760546 -295.815512)
		(end 346.760546 -295.14419)
		(width 0.1143)
		(layer "In13.Cu")
		(net "P5E_CPU0_P0_RX_DN<2>")
	)
	(segment
		(start 347.073982 -281.07132)
		(end 347.047566 -281.05354)
		(width 0.1143)
		(layer "In13.Cu")
		(net "P5E_CPU0_P0_RX_DN<2>")
	)
	(segment
		(start 347.015054 -281.720544)
		(end 347.020134 -281.716988)
		(width 0.1143)
		(layer "In13.Cu")
		(net "P5E_CPU0_P0_RX_DN<2>")
	)
	(segment
		(start 347.048074 -276.193504)
		(end 347.00972 -276.171406)
		(width 0.1143)
		(layer "In13.Cu")
		(net "P5E_CPU0_P0_RX_DN<2>")
	)
	(segment
		(start 347.048074 -282.67406)
		(end 347.011498 -282.652978)
		(width 0.1143)
		(layer "In13.Cu")
		(net "P5E_CPU0_P0_RX_DN<2>")
	)
	(segment
		(start 347.0656 -292.398196)
		(end 347.01988 -292.367716)
		(width 0.1143)
		(layer "In13.Cu")
		(net "P5E_CPU0_P0_RX_DN<2>")
	)
	(segment
		(start 306.191158 -393.69238)
		(end 306.544218 -393.787376)
		(width 0.14224)
		(layer "In13.Cu")
		(net "P5E_CPU0_P0_RX_DN<2>")
	)
	(segment
		(start 360.602276 -316.094364)
		(end 347.046804 -299.576744)
		(width 0.14224)
		(layer "In13.Cu")
		(net "P5E_CPU0_P0_RX_DN<2>")
	)
	(segment
		(start 347.053154 -281.695652)
		(end 347.06179 -281.690826)
		(width 0.1143)
		(layer "In13.Cu")
		(net "P5E_CPU0_P0_RX_DN<2>")
	)
	(segment
		(start 305.30673 -388.039864)
		(end 305.069748 -387.68528)
		(width 0.14224)
		(layer "In13.Cu")
		(net "P5E_CPU0_P0_RX_DN<2>")
	)
	(segment
		(start 347.05036 -280.077164)
		(end 347.075506 -280.062686)
		(width 0.1143)
		(layer "In13.Cu")
		(net "P5E_CPU0_P0_RX_DN<2>")
	)
	(segment
		(start 301.41799 -379.553216)
		(end 299.525436 -378.28855)
		(width 0.14224)
		(layer "In13.Cu")
		(net "P5E_CPU0_P0_RX_DN<2>")
	)
	(segment
		(start 347.080078 -279.45207)
		(end 347.042486 -279.429972)
		(width 0.1143)
		(layer "In13.Cu")
		(net "P5E_CPU0_P0_RX_DN<2>")
	)
	(segment
		(start 347.011752 -280.103072)
		(end 347.050614 -280.077164)
		(width 0.1143)
		(layer "In13.Cu")
		(net "P5E_CPU0_P0_RX_DN<2>")
	)
	(segment
		(start 347.087952 -292.420548)
		(end 347.0656 -292.398196)
		(width 0.1143)
		(layer "In13.Cu")
		(net "P5E_CPU0_P0_RX_DN<2>")
	)
	(segment
		(start 347.076776 -290.794186)
		(end 347.048328 -290.777676)
		(width 0.1143)
		(layer "In13.Cu")
		(net "P5E_CPU0_P0_RX_DN<2>")
	)
	(segment
		(start 306.666392 -393.716764)
		(end 306.666392 -393.545822)
		(width 0.14224)
		(layer "In13.Cu")
		(net "P5E_CPU0_P0_RX_DN<2>")
	)
	(segment
		(start 347.020134 -281.716988)
		(end 347.048074 -281.698192)
		(width 0.1143)
		(layer "In13.Cu")
		(net "P5E_CPU0_P0_RX_DN<2>")
	)
	(segment
		(start 347.081094 -284.314392)
		(end 347.052138 -284.297374)
		(width 0.1143)
		(layer "In13.Cu")
		(net "P5E_CPU0_P0_RX_DN<2>")
	)
	(segment
		(start 347.077792 -271.347692)
		(end 347.017594 -271.313148)
		(width 0.1143)
		(layer "In13.Cu")
		(net "P5E_CPU0_P0_RX_DN<2>")
	)
	(segment
		(start 377.122944 -355.98989)
		(end 360.602276 -316.094364)
		(width 0.14224)
		(layer "In13.Cu")
		(net "P5E_CPU0_P0_RX_DN<2>")
	)
	(segment
		(start 347.050868 -291.416994)
		(end 347.07195 -291.404548)
		(width 0.1143)
		(layer "In13.Cu")
		(net "P5E_CPU0_P0_RX_DN<2>")
	)
	(segment
		(start 347.067632 -283.307282)
		(end 347.068648 -283.306774)
		(width 0.1143)
		(layer "In13.Cu")
		(net "P5E_CPU0_P0_RX_DN<2>")
	)
	(segment
		(start 347.01988 -291.435028)
		(end 347.049852 -291.417502)
		(width 0.1143)
		(layer "In13.Cu")
		(net "P5E_CPU0_P0_RX_DN<2>")
	)
	(segment
		(start 305.069748 -387.68528)
		(end 304.879502 -387.647434)
		(width 0.14224)
		(layer "In13.Cu")
		(net "P5E_CPU0_P0_RX_DN<2>")
	)
	(segment
		(start 347.078554 -276.213824)
		(end 347.048074 -276.193504)
		(width 0.1143)
		(layer "In13.Cu")
		(net "P5E_CPU0_P0_RX_DN<2>")
	)
	(segment
		(start 347.067886 -281.688286)
		(end 347.07322 -281.684984)
		(width 0.1143)
		(layer "In13.Cu")
		(net "P5E_CPU0_P0_RX_DN<2>")
	)
	(segment
		(start 347.012768 -273.620484)
		(end 347.02623 -273.612864)
		(width 0.1143)
		(layer "In13.Cu")
		(net "P5E_CPU0_P0_RX_DN<2>")
	)
	(segment
		(start 304.680112 -387.102096)
		(end 304.44313 -386.747512)
		(width 0.14224)
		(layer "In13.Cu")
		(net "P5E_CPU0_P0_RX_DN<2>")
	)
	(segment
		(start 347.062552 -281.690318)
		(end 347.064584 -281.688286)
		(width 0.1143)
		(layer "In13.Cu")
		(net "P5E_CPU0_P0_RX_DN<2>")
	)
	(arc
		(start 347.046804 -299.576744)
		(mid 346.800151 -299.14086)
		(end 346.714826 -298.647358)
		(width 0.14224)
		(layer "In13.Cu")
		(net "P5E_CPU0_P0_RX_DN<2>")
	)
	(arc
		(start 302.039528 -383.150364)
		(mid 301.743703 -382.524771)
		(end 301.642272 -381.840232)
		(width 0.14224)
		(layer "In13.Cu")
		(net "P5E_CPU0_P0_RX_DN<2>")
	)
	(arc
		(start 301.642272 -379.972824)
		(mid 301.582686 -379.734927)
		(end 301.41799 -379.553216)
		(width 0.14224)
		(layer "In13.Cu")
		(net "P5E_CPU0_P0_RX_DN<2>")
	)
	(arc
		(start 347.008196 -287.51276)
		(mid 346.829997 -287.311076)
		(end 346.76588 -287.049718)
		(width 0.1143)
		(layer "In13.Cu")
		(net "P5E_CPU0_P0_RX_DN<2>")
	)
	(arc
		(start 331.659992 -370.170964)
		(mid 340.32178 -370.383175)
		(end 348.962726 -371.020086)
		(width 0.14224)
		(layer "In13.Cu")
		(net "P5E_CPU0_P0_RX_DN<2>")
	)
	(arc
		(start 347.078554 -276.822408)
		(mid 347.234482 -276.518116)
		(end 347.078554 -276.213824)
		(width 0.1143)
		(layer "In13.Cu")
		(net "P5E_CPU0_P0_RX_DN<2>")
	)
	(arc
		(start 347.07703 -275.20138)
		(mid 347.232963 -274.897445)
		(end 347.077284 -274.593304)
		(width 0.1143)
		(layer "In13.Cu")
		(net "P5E_CPU0_P0_RX_DN<2>")
	)
	(arc
		(start 346.539058 -270.500602)
		(mid 346.488246 -270.460816)
		(end 346.442284 -270.415512)
		(width 0.1143)
		(layer "In13.Cu")
		(net "P5E_CPU0_P0_RX_DN<2>")
	)
	(arc
		(start 346.76588 -287.045908)
		(mid 346.840352 -286.766191)
		(end 347.044264 -286.560768)
		(width 0.1143)
		(layer "In13.Cu")
		(net "P5E_CPU0_P0_RX_DN<2>")
	)
	(arc
		(start 347.011498 -282.652978)
		(mid 346.767326 -282.187545)
		(end 347.011752 -281.722322)
		(width 0.1143)
		(layer "In13.Cu")
		(net "P5E_CPU0_P0_RX_DN<2>")
	)
	(arc
		(start 347.513656 -272.140934)
		(mid 347.308689 -271.934129)
		(end 347.233748 -271.652746)
		(width 0.1143)
		(layer "In13.Cu")
		(net "P5E_CPU0_P0_RX_DN<2>")
	)
	(arc
		(start 299.525436 -378.28855)
		(mid 299.343239 -378.087462)
		(end 299.277278 -377.824238)
		(width 0.14224)
		(layer "In13.Cu")
		(net "P5E_CPU0_P0_RX_DN<2>")
	)
	(arc
		(start 347.011752 -289.132264)
		(mid 346.765862 -288.66592)
		(end 347.011752 -288.199576)
		(width 0.1143)
		(layer "In13.Cu")
		(net "P5E_CPU0_P0_RX_DN<2>")
	)
	(arc
		(start 347.234764 -273.278854)
		(mid 347.309708 -272.997366)
		(end 347.514926 -272.790666)
		(width 0.1143)
		(layer "In13.Cu")
		(net "P5E_CPU0_P0_RX_DN<2>")
	)
	(arc
		(start 347.077284 -283.301694)
		(mid 347.233103 -282.99519)
		(end 347.07322 -282.690824)
		(width 0.1143)
		(layer "In13.Cu")
		(net "P5E_CPU0_P0_RX_DN<2>")
	)
	(arc
		(start 347.082872 -289.781996)
		(mid 347.2388 -289.477704)
		(end 347.082872 -289.173412)
		(width 0.1143)
		(layer "In13.Cu")
		(net "P5E_CPU0_P0_RX_DN<2>")
	)
	(arc
		(start 347.00972 -276.171406)
		(mid 346.765548 -275.705973)
		(end 347.009974 -275.24075)
		(width 0.1143)
		(layer "In13.Cu")
		(net "P5E_CPU0_P0_RX_DN<2>")
	)
	(arc
		(start 347.0148 -279.411938)
		(mid 346.765693 -278.946336)
		(end 347.00972 -278.47798)
		(width 0.1143)
		(layer "In13.Cu")
		(net "P5E_CPU0_P0_RX_DN<2>")
	)
	(arc
		(start 347.00464 -274.544536)
		(mid 346.769136 -274.080372)
		(end 347.012768 -273.620484)
		(width 0.1143)
		(layer "In13.Cu")
		(net "P5E_CPU0_P0_RX_DN<2>")
	)
	(arc
		(start 347.084396 -277.834598)
		(mid 347.043154 -277.812516)
		(end 347.003878 -277.7871)
		(width 0.1143)
		(layer "In13.Cu")
		(net "P5E_CPU0_P0_RX_DN<2>")
	)
	(arc
		(start 347.077792 -281.682444)
		(mid 347.233924 -281.375863)
		(end 347.073982 -281.07132)
		(width 0.1143)
		(layer "In13.Cu")
		(net "P5E_CPU0_P0_RX_DN<2>")
	)
	(arc
		(start 346.996766 -289.83305)
		(mid 347.006847 -289.8257)
		(end 347.017086 -289.818572)
		(width 0.1143)
		(layer "In13.Cu")
		(net "P5E_CPU0_P0_RX_DN<2>")
	)
	(arc
		(start 347.086682 -278.433784)
		(mid 347.235323 -278.133632)
		(end 347.084396 -277.834598)
		(width 0.1143)
		(layer "In13.Cu")
		(net "P5E_CPU0_P0_RX_DN<2>")
	)
	(arc
		(start 347.00972 -285.891478)
		(mid 346.765781 -285.431615)
		(end 347.001084 -284.967172)
		(width 0.1143)
		(layer "In13.Cu")
		(net "P5E_CPU0_P0_RX_DN<2>")
	)
	(arc
		(start 347.015308 -271.311624)
		(mid 346.834656 -271.108879)
		(end 346.769436 -270.84528)
		(width 0.1143)
		(layer "In13.Cu")
		(net "P5E_CPU0_P0_RX_DN<2>")
	)
	(arc
		(start 346.992956 -276.873208)
		(mid 347.002286 -276.866382)
		(end 347.011752 -276.859746)
		(width 0.1143)
		(layer "In13.Cu")
		(net "P5E_CPU0_P0_RX_DN<2>")
	)
	(arc
		(start 347.01988 -292.367716)
		(mid 346.77399 -291.901372)
		(end 347.01988 -291.435028)
		(width 0.1143)
		(layer "In13.Cu")
		(net "P5E_CPU0_P0_RX_DN<2>")
	)
	(arc
		(start 307.367686 -373.035068)
		(mid 307.484119 -373.01189)
		(end 307.582824 -372.945914)
		(width 0.14224)
		(layer "In13.Cu")
		(net "P5E_CPU0_P0_RX_DN<2>")
	)
	(arc
		(start 347.003878 -277.7871)
		(mid 346.765776 -277.332898)
		(end 346.992956 -276.873208)
		(width 0.1143)
		(layer "In13.Cu")
		(net "P5E_CPU0_P0_RX_DN<2>")
	)
	(arc
		(start 347.120464 -292.994588)
		(mid 347.238244 -292.70002)
		(end 347.087952 -292.420548)
		(width 0.1143)
		(layer "In13.Cu")
		(net "P5E_CPU0_P0_RX_DN<2>")
	)
	(arc
		(start 347.102938 -294.621966)
		(mid 347.235566 -294.321124)
		(end 347.079824 -294.03167)
		(width 0.1143)
		(layer "In13.Cu")
		(net "P5E_CPU0_P0_RX_DN<2>")
	)
	(arc
		(start 306.658264 -390.101074)
		(mid 306.652862 -390.064173)
		(end 306.636928 -390.030462)
		(width 0.14224)
		(layer "In13.Cu")
		(net "P5E_CPU0_P0_RX_DN<2>")
	)
	(arc
		(start 346.305632 -270.1417)
		(mid 346.303609 -270.13029)
		(end 346.301822 -270.11884)
		(width 0.1143)
		(layer "In13.Cu")
		(net "P5E_CPU0_P0_RX_DN<2>")
	)
	(arc
		(start 347.089476 -291.393118)
		(mid 347.232638 -291.090503)
		(end 347.076776 -290.794186)
		(width 0.1143)
		(layer "In13.Cu")
		(net "P5E_CPU0_P0_RX_DN<2>")
	)
	(arc
		(start 346.760546 -295.14419)
		(mid 346.825205 -294.881633)
		(end 347.004386 -294.679116)
		(width 0.1143)
		(layer "In13.Cu")
		(net "P5E_CPU0_P0_RX_DN<2>")
	)
	(arc
		(start 299.277278 -376.741182)
		(mid 299.322366 -376.514508)
		(end 299.45076 -376.322336)
		(width 0.14224)
		(layer "In13.Cu")
		(net "P5E_CPU0_P0_RX_DN<2>")
	)
	(arc
		(start 347.65234 -272.658332)
		(mid 347.697618 -272.389585)
		(end 347.548708 -272.161254)
		(width 0.1143)
		(layer "In13.Cu")
		(net "P5E_CPU0_P0_RX_DN<2>")
	)
	(arc
		(start 347.008704 -284.272228)
		(mid 346.765529 -283.784407)
		(end 347.048582 -283.318712)
		(width 0.1143)
		(layer "In13.Cu")
		(net "P5E_CPU0_P0_RX_DN<2>")
	)
	(arc
		(start 347.015308 -293.994332)
		(mid 346.769418 -293.527988)
		(end 347.015308 -293.061644)
		(width 0.1143)
		(layer "In13.Cu")
		(net "P5E_CPU0_P0_RX_DN<2>")
	)
	(arc
		(start 347.052646 -288.176462)
		(mid 347.187136 -288.040776)
		(end 347.236288 -287.856168)
		(width 0.1143)
		(layer "In13.Cu")
		(net "P5E_CPU0_P0_RX_DN<2>")
	)
	(arc
		(start 347.079824 -286.540194)
		(mid 347.235651 -286.235979)
		(end 347.07957 -285.931864)
		(width 0.1143)
		(layer "In13.Cu")
		(net "P5E_CPU0_P0_RX_DN<2>")
	)
	(arc
		(start 347.001084 -284.967172)
		(mid 347.006398 -284.96346)
		(end 347.011752 -284.959806)
		(width 0.1143)
		(layer "In13.Cu")
		(net "P5E_CPU0_P0_RX_DN<2>")
	)
	(arc
		(start 347.086682 -284.918912)
		(mid 347.237238 -284.615229)
		(end 347.081094 -284.314392)
		(width 0.1143)
		(layer "In13.Cu")
		(net "P5E_CPU0_P0_RX_DN<2>")
	)
	(arc
		(start 347.079824 -280.0604)
		(mid 347.235963 -279.756285)
		(end 347.080078 -279.45207)
		(width 0.1143)
		(layer "In13.Cu")
		(net "P5E_CPU0_P0_RX_DN<2>")
	)
	(arc
		(start 325.049642 -370.34724)
		(mid 325.940409 -370.215137)
		(end 326.839834 -370.170964)
		(width 0.14224)
		(layer "In13.Cu")
		(net "P5E_CPU0_P0_RX_DN<2>")
	)
	(arc
		(start 347.048328 -290.777676)
		(mid 346.768497 -290.319288)
		(end 346.996766 -289.83305)
		(width 0.1143)
		(layer "In13.Cu")
		(net "P5E_CPU0_P0_RX_DN<2>")
	)
	(arc
		(start 302.005492 -373.767604)
		(mid 302.816803 -373.22544)
		(end 303.77384 -373.035068)
		(width 0.14224)
		(layer "In13.Cu")
		(net "P5E_CPU0_P0_RX_DN<2>")
	)
	(arc
		(start 308.140354 -372.388384)
		(mid 308.28416 -372.292296)
		(end 308.45379 -372.25859)
		(width 0.14224)
		(layer "In13.Cu")
		(net "P5E_CPU0_P0_RX_DN<2>")
	)
	(arc
		(start 347.236288 -287.856168)
		(mid 347.194949 -287.686456)
		(end 347.080332 -287.55467)
		(width 0.1143)
		(layer "In13.Cu")
		(net "P5E_CPU0_P0_RX_DN<2>")
	)
	(arc
		(start 347.072966 -291.40404)
		(mid 347.081421 -291.398882)
		(end 347.089476 -291.393118)
		(width 0.1143)
		(layer "In13.Cu")
		(net "P5E_CPU0_P0_RX_DN<2>")
	)
	(arc
		(start 347.084142 -273.580098)
		(mid 347.194962 -273.447805)
		(end 347.234764 -273.27987)
		(width 0.1143)
		(layer "In13.Cu")
		(net "P5E_CPU0_P0_RX_DN<2>")
	)
	(arc
		(start 347.549724 -272.770092)
		(mid 347.606753 -272.719465)
		(end 347.65234 -272.658332)
		(width 0.1143)
		(layer "In13.Cu")
		(net "P5E_CPU0_P0_RX_DN<2>")
	)
	(arc
		(start 346.442284 -270.415512)
		(mid 346.355062 -270.288034)
		(end 346.305632 -270.1417)
		(width 0.1143)
		(layer "In13.Cu")
		(net "P5E_CPU0_P0_RX_DN<2>")
	)
	(arc
		(start 346.769436 -270.84528)
		(mid 346.720283 -270.662072)
		(end 346.586048 -270.528034)
		(width 0.1143)
		(layer "In13.Cu")
		(net "P5E_CPU0_P0_RX_DN<2>")
	)
	(arc
		(start 347.011752 -281.03576)
		(mid 346.765862 -280.569416)
		(end 347.011752 -280.103072)
		(width 0.1143)
		(layer "In13.Cu")
		(net "P5E_CPU0_P0_RX_DN<2>")
	)
	(arc
		(start 347.233748 -271.651984)
		(mid 347.192493 -271.481013)
		(end 347.077792 -271.347692)
		(width 0.1143)
		(layer "In13.Cu")
		(net "P5E_CPU0_P0_RX_DN<2>")
	)
	(segment
		(start 304.470308 -393.69238)
		(end 304.991008 -393.69238)
		(width 0.127)
		(layer "F.Cu")
		(net "P5E_CPU0_P0_RX_DN<1>")
	)
	(segment
		(start 346.387928 -273.010122)
		(end 345.921076 -273.27606)
		(width 0.12954)
		(layer "F.Cu")
		(net "P5E_CPU0_P0_RX_DN<1>")
	)
	(segment
		(start 362.090462 -370.662454)
		(end 362.792264 -369.960652)
		(width 0.14224)
		(layer "In13.Cu")
		(net "P5E_CPU0_P0_RX_DN<1>")
	)
	(segment
		(start 305.466496 -393.716764)
		(end 305.466496 -393.545822)
		(width 0.14224)
		(layer "In13.Cu")
		(net "P5E_CPU0_P0_RX_DN<1>")
	)
	(segment
		(start 345.825826 -295.62933)
		(end 345.825826 -295.14546)
		(width 0.1143)
		(layer "In13.Cu")
		(net "P5E_CPU0_P0_RX_DN<1>")
	)
	(segment
		(start 346.066872 -286.58312)
		(end 346.067888 -286.582358)
		(width 0.1143)
		(layer "In13.Cu")
		(net "P5E_CPU0_P0_RX_DN<1>")
	)
	(segment
		(start 346.138754 -276.211284)
		(end 346.069158 -276.170644)
		(width 0.1143)
		(layer "In13.Cu")
		(net "P5E_CPU0_P0_RX_DN<1>")
	)
	(segment
		(start 346.219018 -273.27606)
		(end 345.921076 -273.27606)
		(width 0.1143)
		(layer "In13.Cu")
		(net "P5E_CPU0_P0_RX_DN<1>")
	)
	(segment
		(start 299.173138 -374.973088)
		(end 299.172884 -374.973088)
		(width 0.14224)
		(layer "In13.Cu")
		(net "P5E_CPU0_P0_RX_DN<1>")
	)
	(segment
		(start 346.069158 -278.481536)
		(end 346.138754 -278.440896)
		(width 0.1143)
		(layer "In13.Cu")
		(net "P5E_CPU0_P0_RX_DN<1>")
	)
	(segment
		(start 362.25988 -367.70818)
		(end 362.25988 -367.273332)
		(width 0.14224)
		(layer "In13.Cu")
		(net "P5E_CPU0_P0_RX_DN<1>")
	)
	(segment
		(start 359.53954 -370.662454)
		(end 359.6767 -370.525294)
		(width 0.14224)
		(layer "In13.Cu")
		(net "P5E_CPU0_P0_RX_DN<1>")
	)
	(segment
		(start 305.15433 -392.616944)
		(end 305.458368 -392.31316)
		(width 0.14224)
		(layer "In13.Cu")
		(net "P5E_CPU0_P0_RX_DN<1>")
	)
	(segment
		(start 371.907054 -359.634282)
		(end 363.263942 -368.277394)
		(width 0.14224)
		(layer "In13.Cu")
		(net "P5E_CPU0_P0_RX_DN<1>")
	)
	(segment
		(start 305.458368 -392.31316)
		(end 305.458368 -390.358884)
		(width 0.14224)
		(layer "In13.Cu")
		(net "P5E_CPU0_P0_RX_DN<1>")
	)
	(segment
		(start 304.991008 -393.69238)
		(end 305.344322 -393.787376)
		(width 0.14224)
		(layer "In13.Cu")
		(net "P5E_CPU0_P0_RX_DN<1>")
	)
	(segment
		(start 302.741584 -387.575298)
		(end 302.547528 -387.575298)
		(width 0.14224)
		(layer "In13.Cu")
		(net "P5E_CPU0_P0_RX_DN<1>")
	)
	(segment
		(start 346.069158 -276.861524)
		(end 346.138754 -276.820884)
		(width 0.1143)
		(layer "In13.Cu")
		(net "P5E_CPU0_P0_RX_DN<1>")
	)
	(segment
		(start 346.137992 -287.550606)
		(end 346.070682 -287.51149)
		(width 0.1143)
		(layer "In13.Cu")
		(net "P5E_CPU0_P0_RX_DN<1>")
	)
	(segment
		(start 346.067888 -286.582358)
		(end 346.070428 -286.58058)
		(width 0.1143)
		(layer "In13.Cu")
		(net "P5E_CPU0_P0_RX_DN<1>")
	)
	(segment
		(start 297.809412 -376.33656)
		(end 298.2595 -375.886472)
		(width 0.14224)
		(layer "In13.Cu")
		(net "P5E_CPU0_P0_RX_DN<1>")
	)
	(segment
		(start 307.09616 -372.058184)
		(end 307.70068 -371.453664)
		(width 0.14224)
		(layer "In13.Cu")
		(net "P5E_CPU0_P0_RX_DN<1>")
	)
	(segment
		(start 346.070682 -291.440362)
		(end 346.140024 -291.399976)
		(width 0.1143)
		(layer "In13.Cu")
		(net "P5E_CPU0_P0_RX_DN<1>")
	)
	(segment
		(start 298.259754 -375.886472)
		(end 299.173138 -374.973088)
		(width 0.14224)
		(layer "In13.Cu")
		(net "P5E_CPU0_P0_RX_DN<1>")
	)
	(segment
		(start 346.069158 -275.241512)
		(end 346.138754 -275.200872)
		(width 0.1143)
		(layer "In13.Cu")
		(net "P5E_CPU0_P0_RX_DN<1>")
	)
	(segment
		(start 298.2595 -375.886472)
		(end 298.259754 -375.886472)
		(width 0.14224)
		(layer "In13.Cu")
		(net "P5E_CPU0_P0_RX_DN<1>")
	)
	(segment
		(start 304.336704 -389.170418)
		(end 304.142648 -389.170418)
		(width 0.14224)
		(layer "In13.Cu")
		(net "P5E_CPU0_P0_RX_DN<1>")
	)
	(segment
		(start 346.069158 -284.961584)
		(end 346.138754 -284.920944)
		(width 0.1143)
		(layer "In13.Cu")
		(net "P5E_CPU0_P0_RX_DN<1>")
	)
	(segment
		(start 305.344322 -393.787376)
		(end 305.34483 -393.786868)
		(width 0.14224)
		(layer "In13.Cu")
		(net "P5E_CPU0_P0_RX_DN<1>")
	)
	(segment
		(start 302.245522 -387.079236)
		(end 301.944024 -386.777738)
		(width 0.14224)
		(layer "In13.Cu")
		(net "P5E_CPU0_P0_RX_DN<1>")
	)
	(segment
		(start 346.060014 -286.587692)
		(end 346.066872 -286.58312)
		(width 0.1143)
		(layer "In13.Cu")
		(net "P5E_CPU0_P0_RX_DN<1>")
	)
	(segment
		(start 346.05976 -286.587946)
		(end 346.060014 -286.587692)
		(width 0.1143)
		(layer "In13.Cu")
		(net "P5E_CPU0_P0_RX_DN<1>")
	)
	(segment
		(start 361.23118 -370.525294)
		(end 361.36834 -370.662454)
		(width 0.14224)
		(layer "In13.Cu")
		(net "P5E_CPU0_P0_RX_DN<1>")
	)
	(segment
		(start 360.6673 -370.662454)
		(end 360.80446 -370.525294)
		(width 0.14224)
		(layer "In13.Cu")
		(net "P5E_CPU0_P0_RX_DN<1>")
	)
	(segment
		(start 303.043082 -388.070852)
		(end 303.043082 -387.876796)
		(width 0.14224)
		(layer "In13.Cu")
		(net "P5E_CPU0_P0_RX_DN<1>")
	)
	(segment
		(start 303.840642 -388.868412)
		(end 303.840642 -388.674356)
		(width 0.14224)
		(layer "In13.Cu")
		(net "P5E_CPU0_P0_RX_DN<1>")
	)
	(segment
		(start 305.34483 -393.786868)
		(end 305.466496 -393.716764)
		(width 0.14224)
		(layer "In13.Cu")
		(net "P5E_CPU0_P0_RX_DN<1>")
	)
	(segment
		(start 346.069158 -281.72156)
		(end 346.138754 -281.68092)
		(width 0.1143)
		(layer "In13.Cu")
		(net "P5E_CPU0_P0_RX_DN<1>")
	)
	(segment
		(start 346.138754 -282.691332)
		(end 346.069158 -282.650692)
		(width 0.1143)
		(layer "In13.Cu")
		(net "P5E_CPU0_P0_RX_DN<1>")
	)
	(segment
		(start 345.780106 -298.975272)
		(end 345.780106 -295.689528)
		(width 0.14224)
		(layer "In13.Cu")
		(net "P5E_CPU0_P0_RX_DN<1>")
	)
	(segment
		(start 346.070682 -294.680386)
		(end 346.140024 -294.64)
		(width 0.1143)
		(layer "In13.Cu")
		(net "P5E_CPU0_P0_RX_DN<1>")
	)
	(segment
		(start 301.447962 -386.475732)
		(end 301.447962 -386.281676)
		(width 0.14224)
		(layer "In13.Cu")
		(net "P5E_CPU0_P0_RX_DN<1>")
	)
	(segment
		(start 346.070682 -293.060374)
		(end 346.140024 -293.019988)
		(width 0.1143)
		(layer "In13.Cu")
		(net "P5E_CPU0_P0_RX_DN<1>")
	)
	(segment
		(start 360.10342 -370.525294)
		(end 360.24058 -370.662454)
		(width 0.14224)
		(layer "In13.Cu")
		(net "P5E_CPU0_P0_RX_DN<1>")
	)
	(segment
		(start 372.51259 -360.038904)
		(end 372.107968 -359.634282)
		(width 0.14224)
		(layer "In13.Cu")
		(net "P5E_CPU0_P0_RX_DN<1>")
	)
	(segment
		(start 303.840642 -388.674356)
		(end 303.539144 -388.372858)
		(width 0.14224)
		(layer "In13.Cu")
		(net "P5E_CPU0_P0_RX_DN<1>")
	)
	(segment
		(start 346.140024 -292.411912)
		(end 346.070682 -292.371526)
		(width 0.1143)
		(layer "In13.Cu")
		(net "P5E_CPU0_P0_RX_DN<1>")
	)
	(segment
		(start 346.138754 -277.831296)
		(end 346.069158 -277.790656)
		(width 0.1143)
		(layer "In13.Cu")
		(net "P5E_CPU0_P0_RX_DN<1>")
	)
	(segment
		(start 352.410014 -370.102384)
		(end 358.457754 -370.662454)
		(width 0.14224)
		(layer "In13.Cu")
		(net "P5E_CPU0_P0_RX_DN<1>")
	)
	(segment
		(start 346.069158 -273.6215)
		(end 346.138754 -273.58086)
		(width 0.1143)
		(layer "In13.Cu")
		(net "P5E_CPU0_P0_RX_DN<1>")
	)
	(segment
		(start 297.495214 -382.048258)
		(end 297.495214 -377.09475)
		(width 0.14224)
		(layer "In13.Cu")
		(net "P5E_CPU0_P0_RX_DN<1>")
	)
	(segment
		(start 303.043082 -387.876796)
		(end 302.741584 -387.575298)
		(width 0.14224)
		(layer "In13.Cu")
		(net "P5E_CPU0_P0_RX_DN<1>")
	)
	(segment
		(start 299.172884 -374.973088)
		(end 301.553626 -372.592346)
		(width 0.14224)
		(layer "In13.Cu")
		(net "P5E_CPU0_P0_RX_DN<1>")
	)
	(segment
		(start 303.539144 -388.372858)
		(end 303.345088 -388.372858)
		(width 0.14224)
		(layer "In13.Cu")
		(net "P5E_CPU0_P0_RX_DN<1>")
	)
	(segment
		(start 346.138754 -284.311344)
		(end 346.069158 -284.270704)
		(width 0.1143)
		(layer "In13.Cu")
		(net "P5E_CPU0_P0_RX_DN<1>")
	)
	(segment
		(start 305.466496 -393.545822)
		(end 305.149504 -393.22883)
		(width 0.14224)
		(layer "In13.Cu")
		(net "P5E_CPU0_P0_RX_DN<1>")
	)
	(segment
		(start 346.069158 -280.101548)
		(end 346.138754 -280.060908)
		(width 0.1143)
		(layer "In13.Cu")
		(net "P5E_CPU0_P0_RX_DN<1>")
	)
	(segment
		(start 315.331602 -371.32387)
		(end 324.831456 -369.434364)
		(width 0.14224)
		(layer "In13.Cu")
		(net "P5E_CPU0_P0_RX_DN<1>")
	)
	(segment
		(start 360.80446 -370.525294)
		(end 361.23118 -370.525294)
		(width 0.14224)
		(layer "In13.Cu")
		(net "P5E_CPU0_P0_RX_DN<1>")
	)
	(segment
		(start 304.142648 -389.170418)
		(end 303.840642 -388.868412)
		(width 0.14224)
		(layer "In13.Cu")
		(net "P5E_CPU0_P0_RX_DN<1>")
	)
	(segment
		(start 346.070428 -286.58058)
		(end 346.140024 -286.53994)
		(width 0.1143)
		(layer "In13.Cu")
		(net "P5E_CPU0_P0_RX_DN<1>")
	)
	(segment
		(start 358.457754 -370.662454)
		(end 359.53954 -370.662454)
		(width 0.14224)
		(layer "In13.Cu")
		(net "P5E_CPU0_P0_RX_DN<1>")
	)
	(segment
		(start 346.288868 -273.34591)
		(end 346.219018 -273.27606)
		(width 0.1143)
		(layer "In13.Cu")
		(net "P5E_CPU0_P0_RX_DN<1>")
	)
	(segment
		(start 372.51259 -360.240326)
		(end 372.51259 -360.038904)
		(width 0.14224)
		(layer "In13.Cu")
		(net "P5E_CPU0_P0_RX_DN<1>")
	)
	(segment
		(start 301.749968 -386.777738)
		(end 301.447962 -386.475732)
		(width 0.14224)
		(layer "In13.Cu")
		(net "P5E_CPU0_P0_RX_DN<1>")
	)
	(segment
		(start 308.014116 -371.32387)
		(end 315.331602 -371.32387)
		(width 0.14224)
		(layer "In13.Cu")
		(net "P5E_CPU0_P0_RX_DN<1>")
	)
	(segment
		(start 346.140024 -289.171888)
		(end 346.070682 -289.131502)
		(width 0.1143)
		(layer "In13.Cu")
		(net "P5E_CPU0_P0_RX_DN<1>")
	)
	(segment
		(start 301.447962 -386.281676)
		(end 297.693842 -382.52781)
		(width 0.14224)
		(layer "In13.Cu")
		(net "P5E_CPU0_P0_RX_DN<1>")
	)
	(segment
		(start 302.843184 -372.058184)
		(end 307.09616 -372.058184)
		(width 0.14224)
		(layer "In13.Cu")
		(net "P5E_CPU0_P0_RX_DN<1>")
	)
	(segment
		(start 359.773982 -316.741302)
		(end 346.23248 -300.241208)
		(width 0.14224)
		(layer "In13.Cu")
		(net "P5E_CPU0_P0_RX_DN<1>")
	)
	(segment
		(start 345.780106 -295.67505)
		(end 345.825826 -295.62933)
		(width 0.1143)
		(layer "In13.Cu")
		(net "P5E_CPU0_P0_RX_DN<1>")
	)
	(segment
		(start 346.069158 -283.341572)
		(end 346.138754 -283.300932)
		(width 0.1143)
		(layer "In13.Cu")
		(net "P5E_CPU0_P0_RX_DN<1>")
	)
	(segment
		(start 346.138754 -281.07132)
		(end 346.069158 -281.03068)
		(width 0.1143)
		(layer "In13.Cu")
		(net "P5E_CPU0_P0_RX_DN<1>")
	)
	(segment
		(start 346.140024 -294.031924)
		(end 346.070682 -293.991538)
		(width 0.1143)
		(layer "In13.Cu")
		(net "P5E_CPU0_P0_RX_DN<1>")
	)
	(segment
		(start 346.068142 -288.201862)
		(end 346.140024 -288.160206)
		(width 0.1143)
		(layer "In13.Cu")
		(net "P5E_CPU0_P0_RX_DN<1>")
	)
	(segment
		(start 361.36834 -370.662454)
		(end 362.090462 -370.662454)
		(width 0.14224)
		(layer "In13.Cu")
		(net "P5E_CPU0_P0_RX_DN<1>")
	)
	(segment
		(start 374.516396 -355.016816)
		(end 374.53062 -354.982526)
		(width 0.14224)
		(layer "In13.Cu")
		(net "P5E_CPU0_P0_RX_DN<1>")
	)
	(segment
		(start 302.245522 -387.273292)
		(end 302.245522 -387.079236)
		(width 0.14224)
		(layer "In13.Cu")
		(net "P5E_CPU0_P0_RX_DN<1>")
	)
	(segment
		(start 362.25988 -367.273332)
		(end 374.516396 -355.016816)
		(width 0.14224)
		(layer "In13.Cu")
		(net "P5E_CPU0_P0_RX_DN<1>")
	)
	(segment
		(start 346.138754 -274.591272)
		(end 346.069158 -274.550632)
		(width 0.1143)
		(layer "In13.Cu")
		(net "P5E_CPU0_P0_RX_DN<1>")
	)
	(segment
		(start 301.944024 -386.777738)
		(end 301.749968 -386.777738)
		(width 0.14224)
		(layer "In13.Cu")
		(net "P5E_CPU0_P0_RX_DN<1>")
	)
	(segment
		(start 374.53062 -354.982526)
		(end 374.53062 -352.323908)
		(width 0.14224)
		(layer "In13.Cu")
		(net "P5E_CPU0_P0_RX_DN<1>")
	)
	(segment
		(start 346.070682 -289.82035)
		(end 346.140024 -289.779964)
		(width 0.1143)
		(layer "In13.Cu")
		(net "P5E_CPU0_P0_RX_DN<1>")
	)
	(segment
		(start 345.780106 -295.689528)
		(end 345.780106 -295.67505)
		(width 0.1143)
		(layer "In13.Cu")
		(net "P5E_CPU0_P0_RX_DN<1>")
	)
	(segment
		(start 359.6767 -370.525294)
		(end 360.10342 -370.525294)
		(width 0.14224)
		(layer "In13.Cu")
		(net "P5E_CPU0_P0_RX_DN<1>")
	)
	(segment
		(start 363.288072 -369.464844)
		(end 372.51259 -360.240326)
		(width 0.14224)
		(layer "In13.Cu")
		(net "P5E_CPU0_P0_RX_DN<1>")
	)
	(segment
		(start 305.411124 -390.244838)
		(end 304.336704 -389.170418)
		(width 0.14224)
		(layer "In13.Cu")
		(net "P5E_CPU0_P0_RX_DN<1>")
	)
	(segment
		(start 362.829094 -368.277394)
		(end 362.25988 -367.70818)
		(width 0.14224)
		(layer "In13.Cu")
		(net "P5E_CPU0_P0_RX_DN<1>")
	)
	(segment
		(start 305.149504 -393.22883)
		(end 305.15433 -392.616944)
		(width 0.14224)
		(layer "In13.Cu")
		(net "P5E_CPU0_P0_RX_DN<1>")
	)
	(segment
		(start 346.140024 -290.7919)
		(end 346.070682 -290.751514)
		(width 0.1143)
		(layer "In13.Cu")
		(net "P5E_CPU0_P0_RX_DN<1>")
	)
	(segment
		(start 346.138754 -279.451308)
		(end 346.069158 -279.410668)
		(width 0.1143)
		(layer "In13.Cu")
		(net "P5E_CPU0_P0_RX_DN<1>")
	)
	(segment
		(start 363.09427 -369.464844)
		(end 363.288072 -369.464844)
		(width 0.14224)
		(layer "In13.Cu")
		(net "P5E_CPU0_P0_RX_DN<1>")
	)
	(segment
		(start 374.53062 -352.323908)
		(end 359.833164 -316.842902)
		(width 0.14224)
		(layer "In13.Cu")
		(net "P5E_CPU0_P0_RX_DN<1>")
	)
	(segment
		(start 303.345088 -388.372858)
		(end 303.043082 -388.070852)
		(width 0.14224)
		(layer "In13.Cu")
		(net "P5E_CPU0_P0_RX_DN<1>")
	)
	(segment
		(start 362.792264 -369.960652)
		(end 362.792264 -369.76685)
		(width 0.14224)
		(layer "In13.Cu")
		(net "P5E_CPU0_P0_RX_DN<1>")
	)
	(segment
		(start 327.365106 -369.184936)
		(end 332.545436 -369.184936)
		(width 0.14224)
		(layer "In13.Cu")
		(net "P5E_CPU0_P0_RX_DN<1>")
	)
	(segment
		(start 302.547528 -387.575298)
		(end 302.245522 -387.273292)
		(width 0.14224)
		(layer "In13.Cu")
		(net "P5E_CPU0_P0_RX_DN<1>")
	)
	(segment
		(start 363.263942 -368.277394)
		(end 362.829094 -368.277394)
		(width 0.14224)
		(layer "In13.Cu")
		(net "P5E_CPU0_P0_RX_DN<1>")
	)
	(segment
		(start 372.107968 -359.634282)
		(end 371.907054 -359.634282)
		(width 0.14224)
		(layer "In13.Cu")
		(net "P5E_CPU0_P0_RX_DN<1>")
	)
	(segment
		(start 360.24058 -370.662454)
		(end 360.6673 -370.662454)
		(width 0.14224)
		(layer "In13.Cu")
		(net "P5E_CPU0_P0_RX_DN<1>")
	)
	(segment
		(start 346.140024 -285.932118)
		(end 346.070428 -285.891732)
		(width 0.1143)
		(layer "In13.Cu")
		(net "P5E_CPU0_P0_RX_DN<1>")
	)
	(segment
		(start 362.792264 -369.76685)
		(end 363.09427 -369.464844)
		(width 0.14224)
		(layer "In13.Cu")
		(net "P5E_CPU0_P0_RX_DN<1>")
	)
	(arc
		(start 346.140024 -286.53994)
		(mid 346.295645 -286.236082)
		(end 346.140024 -285.932118)
		(width 0.1143)
		(layer "In13.Cu")
		(net "P5E_CPU0_P0_RX_DN<1>")
	)
	(arc
		(start 346.069158 -281.03068)
		(mid 345.825831 -280.566114)
		(end 346.069158 -280.101548)
		(width 0.1143)
		(layer "In13.Cu")
		(net "P5E_CPU0_P0_RX_DN<1>")
	)
	(arc
		(start 346.070428 -285.891732)
		(mid 345.825608 -285.426961)
		(end 346.069158 -284.961584)
		(width 0.1143)
		(layer "In13.Cu")
		(net "P5E_CPU0_P0_RX_DN<1>")
	)
	(arc
		(start 346.069158 -284.270704)
		(mid 345.825831 -283.806138)
		(end 346.069158 -283.341572)
		(width 0.1143)
		(layer "In13.Cu")
		(net "P5E_CPU0_P0_RX_DN<1>")
	)
	(arc
		(start 346.23248 -300.241208)
		(mid 345.896473 -299.647489)
		(end 345.780106 -298.975272)
		(width 0.14224)
		(layer "In13.Cu")
		(net "P5E_CPU0_P0_RX_DN<1>")
	)
	(arc
		(start 301.553626 -372.592346)
		(mid 302.14528 -372.197015)
		(end 302.843184 -372.058184)
		(width 0.14224)
		(layer "In13.Cu")
		(net "P5E_CPU0_P0_RX_DN<1>")
	)
	(arc
		(start 345.82608 -287.045908)
		(mid 345.887871 -286.788834)
		(end 346.05976 -286.587946)
		(width 0.1143)
		(layer "In13.Cu")
		(net "P5E_CPU0_P0_RX_DN<1>")
	)
	(arc
		(start 346.070682 -289.131502)
		(mid 345.89089 -288.928914)
		(end 345.82608 -288.66592)
		(width 0.1143)
		(layer "In13.Cu")
		(net "P5E_CPU0_P0_RX_DN<1>")
	)
	(arc
		(start 345.82608 -288.66592)
		(mid 345.890174 -288.404189)
		(end 346.068142 -288.201862)
		(width 0.1143)
		(layer "In13.Cu")
		(net "P5E_CPU0_P0_RX_DN<1>")
	)
	(arc
		(start 346.140024 -294.64)
		(mid 346.295851 -294.335962)
		(end 346.140024 -294.031924)
		(width 0.1143)
		(layer "In13.Cu")
		(net "P5E_CPU0_P0_RX_DN<1>")
	)
	(arc
		(start 346.138754 -281.68092)
		(mid 346.295731 -281.37612)
		(end 346.138754 -281.07132)
		(width 0.1143)
		(layer "In13.Cu")
		(net "P5E_CPU0_P0_RX_DN<1>")
	)
	(arc
		(start 307.70068 -371.453664)
		(mid 307.844486 -371.357576)
		(end 308.014116 -371.32387)
		(width 0.14224)
		(layer "In13.Cu")
		(net "P5E_CPU0_P0_RX_DN<1>")
	)
	(arc
		(start 346.069158 -274.550632)
		(mid 345.825831 -274.086066)
		(end 346.069158 -273.6215)
		(width 0.1143)
		(layer "In13.Cu")
		(net "P5E_CPU0_P0_RX_DN<1>")
	)
	(arc
		(start 346.070682 -293.991538)
		(mid 345.825861 -293.525956)
		(end 346.070682 -293.060374)
		(width 0.1143)
		(layer "In13.Cu")
		(net "P5E_CPU0_P0_RX_DN<1>")
	)
	(arc
		(start 346.070682 -287.51149)
		(mid 345.89089 -287.308902)
		(end 345.82608 -287.045908)
		(width 0.1143)
		(layer "In13.Cu")
		(net "P5E_CPU0_P0_RX_DN<1>")
	)
	(arc
		(start 346.138754 -284.920944)
		(mid 346.295731 -284.616144)
		(end 346.138754 -284.311344)
		(width 0.1143)
		(layer "In13.Cu")
		(net "P5E_CPU0_P0_RX_DN<1>")
	)
	(arc
		(start 297.693842 -382.52781)
		(mid 297.546756 -382.30783)
		(end 297.495214 -382.048258)
		(width 0.14224)
		(layer "In13.Cu")
		(net "P5E_CPU0_P0_RX_DN<1>")
	)
	(arc
		(start 346.140024 -291.399976)
		(mid 346.295851 -291.095938)
		(end 346.140024 -290.7919)
		(width 0.1143)
		(layer "In13.Cu")
		(net "P5E_CPU0_P0_RX_DN<1>")
	)
	(arc
		(start 346.138754 -273.58086)
		(mid 346.236519 -273.477884)
		(end 346.288868 -273.34591)
		(width 0.1143)
		(layer "In13.Cu")
		(net "P5E_CPU0_P0_RX_DN<1>")
	)
	(arc
		(start 346.070682 -290.751514)
		(mid 345.825861 -290.285932)
		(end 346.070682 -289.82035)
		(width 0.1143)
		(layer "In13.Cu")
		(net "P5E_CPU0_P0_RX_DN<1>")
	)
	(arc
		(start 359.833164 -316.842902)
		(mid 359.815614 -316.805524)
		(end 359.794556 -316.770004)
		(width 0.14224)
		(layer "In13.Cu")
		(net "P5E_CPU0_P0_RX_DN<1>")
	)
	(arc
		(start 324.831456 -369.434364)
		(mid 326.092154 -369.247415)
		(end 327.365106 -369.184936)
		(width 0.14224)
		(layer "In13.Cu")
		(net "P5E_CPU0_P0_RX_DN<1>")
	)
	(arc
		(start 346.140024 -288.160206)
		(mid 346.295849 -287.854898)
		(end 346.137992 -287.550606)
		(width 0.1143)
		(layer "In13.Cu")
		(net "P5E_CPU0_P0_RX_DN<1>")
	)
	(arc
		(start 346.140024 -293.019988)
		(mid 346.295851 -292.71595)
		(end 346.140024 -292.411912)
		(width 0.1143)
		(layer "In13.Cu")
		(net "P5E_CPU0_P0_RX_DN<1>")
	)
	(arc
		(start 359.794556 -316.770004)
		(mid 359.784562 -316.755443)
		(end 359.773982 -316.741302)
		(width 0.14224)
		(layer "In13.Cu")
		(net "P5E_CPU0_P0_RX_DN<1>")
	)
	(arc
		(start 297.495214 -377.09475)
		(mid 297.57689 -376.684408)
		(end 297.809412 -376.33656)
		(width 0.14224)
		(layer "In13.Cu")
		(net "P5E_CPU0_P0_RX_DN<1>")
	)
	(arc
		(start 332.545436 -369.184936)
		(mid 342.488316 -369.414341)
		(end 352.410014 -370.102384)
		(width 0.14224)
		(layer "In13.Cu")
		(net "P5E_CPU0_P0_RX_DN<1>")
	)
	(arc
		(start 346.140024 -289.779964)
		(mid 346.295851 -289.475926)
		(end 346.140024 -289.171888)
		(width 0.1143)
		(layer "In13.Cu")
		(net "P5E_CPU0_P0_RX_DN<1>")
	)
	(arc
		(start 346.070682 -292.371526)
		(mid 345.825861 -291.905944)
		(end 346.070682 -291.440362)
		(width 0.1143)
		(layer "In13.Cu")
		(net "P5E_CPU0_P0_RX_DN<1>")
	)
	(arc
		(start 346.138754 -280.060908)
		(mid 346.295731 -279.756108)
		(end 346.138754 -279.451308)
		(width 0.1143)
		(layer "In13.Cu")
		(net "P5E_CPU0_P0_RX_DN<1>")
	)
	(arc
		(start 346.069158 -277.790656)
		(mid 345.825831 -277.32609)
		(end 346.069158 -276.861524)
		(width 0.1143)
		(layer "In13.Cu")
		(net "P5E_CPU0_P0_RX_DN<1>")
	)
	(arc
		(start 305.458368 -390.358884)
		(mid 305.446091 -390.297161)
		(end 305.411124 -390.244838)
		(width 0.14224)
		(layer "In13.Cu")
		(net "P5E_CPU0_P0_RX_DN<1>")
	)
	(arc
		(start 346.069158 -282.650692)
		(mid 345.825831 -282.186126)
		(end 346.069158 -281.72156)
		(width 0.1143)
		(layer "In13.Cu")
		(net "P5E_CPU0_P0_RX_DN<1>")
	)
	(arc
		(start 346.138754 -283.300932)
		(mid 346.295731 -282.996132)
		(end 346.138754 -282.691332)
		(width 0.1143)
		(layer "In13.Cu")
		(net "P5E_CPU0_P0_RX_DN<1>")
	)
	(arc
		(start 345.825826 -295.14546)
		(mid 345.890884 -294.882714)
		(end 346.070682 -294.680386)
		(width 0.1143)
		(layer "In13.Cu")
		(net "P5E_CPU0_P0_RX_DN<1>")
	)
	(arc
		(start 346.138754 -278.440896)
		(mid 346.295731 -278.136096)
		(end 346.138754 -277.831296)
		(width 0.1143)
		(layer "In13.Cu")
		(net "P5E_CPU0_P0_RX_DN<1>")
	)
	(arc
		(start 346.138754 -275.200872)
		(mid 346.295731 -274.896072)
		(end 346.138754 -274.591272)
		(width 0.1143)
		(layer "In13.Cu")
		(net "P5E_CPU0_P0_RX_DN<1>")
	)
	(arc
		(start 346.069158 -279.410668)
		(mid 345.825831 -278.946102)
		(end 346.069158 -278.481536)
		(width 0.1143)
		(layer "In13.Cu")
		(net "P5E_CPU0_P0_RX_DN<1>")
	)
	(arc
		(start 346.069158 -276.170644)
		(mid 345.825831 -275.706078)
		(end 346.069158 -275.241512)
		(width 0.1143)
		(layer "In13.Cu")
		(net "P5E_CPU0_P0_RX_DN<1>")
	)
	(arc
		(start 346.138754 -276.820884)
		(mid 346.295731 -276.516084)
		(end 346.138754 -276.211284)
		(width 0.1143)
		(layer "In13.Cu")
		(net "P5E_CPU0_P0_RX_DN<1>")
	)
	(segment
		(start 357.197914 -268.960092)
		(end 356.731062 -269.22603)
		(width 0.12954)
		(layer "F.Cu")
		(net "P5E_CPU0_P0_RX_DN<15>")
	)
	(segment
		(start 321.270376 -393.69238)
		(end 321.791076 -393.69238)
		(width 0.127)
		(layer "F.Cu")
		(net "P5E_CPU0_P0_RX_DN<15>")
	)
	(segment
		(start 400.338544 -352.80473)
		(end 373.66321 -326.129396)
		(width 0.14224)
		(layer "In15.Cu")
		(net "P5E_CPU0_P0_RX_DN<15>")
	)
	(segment
		(start 400.677634 -370.445792)
		(end 400.677634 -353.641406)
		(width 0.14224)
		(layer "In15.Cu")
		(net "P5E_CPU0_P0_RX_DN<15>")
	)
	(segment
		(start 361.773724 -385.393184)
		(end 362.00588 -384.83159)
		(width 0.14224)
		(layer "In15.Cu")
		(net "P5E_CPU0_P0_RX_DN<15>")
	)
	(segment
		(start 357.400352 -269.720314)
		(end 357.398574 -269.719298)
		(width 0.1143)
		(layer "In15.Cu")
		(net "P5E_CPU0_P0_RX_DN<15>")
	)
	(segment
		(start 325.980298 -389.871458)
		(end 327.633838 -389.871458)
		(width 0.14224)
		(layer "In15.Cu")
		(net "P5E_CPU0_P0_RX_DN<15>")
	)
	(segment
		(start 390.23417 -377.72721)
		(end 390.23417 -376.82678)
		(width 0.14224)
		(layer "In15.Cu")
		(net "P5E_CPU0_P0_RX_DN<15>")
	)
	(segment
		(start 363.695742 -382.646174)
		(end 364.410498 -382.646174)
		(width 0.14224)
		(layer "In15.Cu")
		(net "P5E_CPU0_P0_RX_DN<15>")
	)
	(segment
		(start 357.394764 -269.717266)
		(end 357.38943 -269.714218)
		(width 0.1143)
		(layer "In15.Cu")
		(net "P5E_CPU0_P0_RX_DN<15>")
	)
	(segment
		(start 321.791076 -393.69238)
		(end 322.14439 -393.787376)
		(width 0.14224)
		(layer "In15.Cu")
		(net "P5E_CPU0_P0_RX_DN<15>")
	)
	(segment
		(start 379.259084 -387.001258)
		(end 379.401324 -386.859018)
		(width 0.14224)
		(layer "In15.Cu")
		(net "P5E_CPU0_P0_RX_DN<15>")
	)
	(segment
		(start 392.805412 -374.00484)
		(end 397.264128 -374.00484)
		(width 0.14224)
		(layer "In15.Cu")
		(net "P5E_CPU0_P0_RX_DN<15>")
	)
	(segment
		(start 342.8873 -386.475478)
		(end 343.02446 -386.338318)
		(width 0.14224)
		(layer "In15.Cu")
		(net "P5E_CPU0_P0_RX_DN<15>")
	)
	(segment
		(start 357.85806 -270.523462)
		(end 357.85806 -270.523208)
		(width 0.1143)
		(layer "In15.Cu")
		(net "P5E_CPU0_P0_RX_DN<15>")
	)
	(segment
		(start 386.827522 -382.910588)
		(end 386.827522 -381.501142)
		(width 0.14224)
		(layer "In15.Cu")
		(net "P5E_CPU0_P0_RX_DN<15>")
	)
	(segment
		(start 362.538518 -383.619756)
		(end 363.382306 -382.775968)
		(width 0.14224)
		(layer "In15.Cu")
		(net "P5E_CPU0_P0_RX_DN<15>")
	)
	(segment
		(start 357.029004 -269.22603)
		(end 356.731062 -269.22603)
		(width 0.1143)
		(layer "In15.Cu")
		(net "P5E_CPU0_P0_RX_DN<15>")
	)
	(segment
		(start 387.843268 -380.957836)
		(end 388.471664 -380.32944)
		(width 0.14224)
		(layer "In15.Cu")
		(net "P5E_CPU0_P0_RX_DN<15>")
	)
	(segment
		(start 358.900984 -271.958562)
		(end 358.880918 -271.938496)
		(width 0.1143)
		(layer "In15.Cu")
		(net "P5E_CPU0_P0_RX_DN<15>")
	)
	(segment
		(start 357.111808 -269.308834)
		(end 357.029004 -269.22603)
		(width 0.1143)
		(layer "In15.Cu")
		(net "P5E_CPU0_P0_RX_DN<15>")
	)
	(segment
		(start 379.259084 -386.145278)
		(end 372.015004 -386.145278)
		(width 0.14224)
		(layer "In15.Cu")
		(net "P5E_CPU0_P0_RX_DN<15>")
	)
	(segment
		(start 357.357172 -269.695422)
		(end 357.35641 -269.694914)
		(width 0.1143)
		(layer "In15.Cu")
		(net "P5E_CPU0_P0_RX_DN<15>")
	)
	(segment
		(start 359.465372 -295.34993)
		(end 359.132886 -274.811236)
		(width 0.14224)
		(layer "In15.Cu")
		(net "P5E_CPU0_P0_RX_DN<15>")
	)
	(segment
		(start 329.093068 -386.475478)
		(end 341.75954 -386.475478)
		(width 0.14224)
		(layer "In15.Cu")
		(net "P5E_CPU0_P0_RX_DN<15>")
	)
	(segment
		(start 370.544344 -384.725418)
		(end 370.851684 -385.032758)
		(width 0.14224)
		(layer "In15.Cu")
		(net "P5E_CPU0_P0_RX_DN<15>")
	)
	(segment
		(start 370.851684 -386.859018)
		(end 370.993924 -387.001258)
		(width 0.14224)
		(layer "In15.Cu")
		(net "P5E_CPU0_P0_RX_DN<15>")
	)
	(segment
		(start 357.382572 -269.710154)
		(end 357.380794 -269.709138)
		(width 0.1143)
		(layer "In15.Cu")
		(net "P5E_CPU0_P0_RX_DN<15>")
	)
	(segment
		(start 322.144898 -393.786868)
		(end 322.266564 -393.716764)
		(width 0.14224)
		(layer "In15.Cu")
		(net "P5E_CPU0_P0_RX_DN<15>")
	)
	(segment
		(start 379.401324 -386.287518)
		(end 379.259084 -386.145278)
		(width 0.14224)
		(layer "In15.Cu")
		(net "P5E_CPU0_P0_RX_DN<15>")
	)
	(segment
		(start 400.653758 -353.517962)
		(end 400.40814 -352.909632)
		(width 0.14224)
		(layer "In15.Cu")
		(net "P5E_CPU0_P0_RX_DN<15>")
	)
	(segment
		(start 368.62893 -384.725418)
		(end 370.544344 -384.725418)
		(width 0.14224)
		(layer "In15.Cu")
		(net "P5E_CPU0_P0_RX_DN<15>")
	)
	(segment
		(start 371.707664 -385.837938)
		(end 371.707664 -385.032758)
		(width 0.14224)
		(layer "In15.Cu")
		(net "P5E_CPU0_P0_RX_DN<15>")
	)
	(segment
		(start 358.358694 -271.351248)
		(end 358.289098 -271.310608)
		(width 0.1143)
		(layer "In15.Cu")
		(net "P5E_CPU0_P0_RX_DN<15>")
	)
	(segment
		(start 322.266564 -393.716764)
		(end 322.266564 -393.117578)
		(width 0.14224)
		(layer "In15.Cu")
		(net "P5E_CPU0_P0_RX_DN<15>")
	)
	(segment
		(start 357.862632 -270.526002)
		(end 357.860092 -270.524732)
		(width 0.1143)
		(layer "In15.Cu")
		(net "P5E_CPU0_P0_RX_DN<15>")
	)
	(segment
		(start 359.132886 -274.811236)
		(end 359.132886 -272.190464)
		(width 0.14224)
		(layer "In15.Cu")
		(net "P5E_CPU0_P0_RX_DN<15>")
	)
	(segment
		(start 357.58628 -270.053308)
		(end 357.58628 -270.04391)
		(width 0.1143)
		(layer "In15.Cu")
		(net "P5E_CPU0_P0_RX_DN<15>")
	)
	(segment
		(start 343.02446 -386.338318)
		(end 343.45118 -386.338318)
		(width 0.14224)
		(layer "In15.Cu")
		(net "P5E_CPU0_P0_RX_DN<15>")
	)
	(segment
		(start 342.32342 -386.338318)
		(end 342.46058 -386.475478)
		(width 0.14224)
		(layer "In15.Cu")
		(net "P5E_CPU0_P0_RX_DN<15>")
	)
	(segment
		(start 379.401324 -386.859018)
		(end 379.401324 -386.287518)
		(width 0.14224)
		(layer "In15.Cu")
		(net "P5E_CPU0_P0_RX_DN<15>")
	)
	(segment
		(start 370.993924 -387.001258)
		(end 379.259084 -387.001258)
		(width 0.14224)
		(layer "In15.Cu")
		(net "P5E_CPU0_P0_RX_DN<15>")
	)
	(segment
		(start 341.8967 -386.338318)
		(end 342.32342 -386.338318)
		(width 0.14224)
		(layer "In15.Cu")
		(net "P5E_CPU0_P0_RX_DN<15>")
	)
	(segment
		(start 386.676138 -383.379726)
		(end 386.80517 -383.03454)
		(width 0.14224)
		(layer "In15.Cu")
		(net "P5E_CPU0_P0_RX_DN<15>")
	)
	(segment
		(start 372.015004 -384.725418)
		(end 382.153922 -384.725418)
		(width 0.14224)
		(layer "In15.Cu")
		(net "P5E_CPU0_P0_RX_DN<15>")
	)
	(segment
		(start 359.132886 -272.190464)
		(end 358.900984 -271.958562)
		(width 0.14224)
		(layer "In15.Cu")
		(net "P5E_CPU0_P0_RX_DN<15>")
	)
	(segment
		(start 343.58834 -386.475478)
		(end 344.01506 -386.475478)
		(width 0.14224)
		(layer "In15.Cu")
		(net "P5E_CPU0_P0_RX_DN<15>")
	)
	(segment
		(start 342.46058 -386.475478)
		(end 342.8873 -386.475478)
		(width 0.14224)
		(layer "In15.Cu")
		(net "P5E_CPU0_P0_RX_DN<15>")
	)
	(segment
		(start 341.75954 -386.475478)
		(end 341.8967 -386.338318)
		(width 0.14224)
		(layer "In15.Cu")
		(net "P5E_CPU0_P0_RX_DN<15>")
	)
	(segment
		(start 357.860092 -270.524732)
		(end 357.858822 -270.52397)
		(width 0.1143)
		(layer "In15.Cu")
		(net "P5E_CPU0_P0_RX_DN<15>")
	)
	(segment
		(start 357.864156 -270.527018)
		(end 357.862632 -270.526002)
		(width 0.1143)
		(layer "In15.Cu")
		(net "P5E_CPU0_P0_RX_DN<15>")
	)
	(segment
		(start 357.38816 -269.713456)
		(end 357.385874 -269.711932)
		(width 0.1143)
		(layer "In15.Cu")
		(net "P5E_CPU0_P0_RX_DN<15>")
	)
	(segment
		(start 371.707664 -385.032758)
		(end 372.015004 -384.725418)
		(width 0.14224)
		(layer "In15.Cu")
		(net "P5E_CPU0_P0_RX_DN<15>")
	)
	(segment
		(start 344.15222 -386.338318)
		(end 344.57894 -386.338318)
		(width 0.14224)
		(layer "In15.Cu")
		(net "P5E_CPU0_P0_RX_DN<15>")
	)
	(segment
		(start 344.01506 -386.475478)
		(end 344.15222 -386.338318)
		(width 0.14224)
		(layer "In15.Cu")
		(net "P5E_CPU0_P0_RX_DN<15>")
	)
	(segment
		(start 372.472966 -324.643242)
		(end 359.543858 -304.227484)
		(width 0.14224)
		(layer "In15.Cu")
		(net "P5E_CPU0_P0_RX_DN<15>")
	)
	(segment
		(start 358.880918 -271.873472)
		(end 358.358694 -271.351248)
		(width 0.1143)
		(layer "In15.Cu")
		(net "P5E_CPU0_P0_RX_DN<15>")
	)
	(segment
		(start 327.757028 -389.84682)
		(end 328.36231 -389.595868)
		(width 0.14224)
		(layer "In15.Cu")
		(net "P5E_CPU0_P0_RX_DN<15>")
	)
	(segment
		(start 357.380032 -269.70863)
		(end 357.376984 -269.706852)
		(width 0.1143)
		(layer "In15.Cu")
		(net "P5E_CPU0_P0_RX_DN<15>")
	)
	(segment
		(start 389.380984 -378.57049)
		(end 389.675624 -378.453396)
		(width 0.14224)
		(layer "In15.Cu")
		(net "P5E_CPU0_P0_RX_DN<15>")
	)
	(segment
		(start 357.858822 -270.52397)
		(end 357.85806 -270.523462)
		(width 0.1143)
		(layer "In15.Cu")
		(net "P5E_CPU0_P0_RX_DN<15>")
	)
	(segment
		(start 357.398574 -269.719298)
		(end 357.394764 -269.717266)
		(width 0.1143)
		(layer "In15.Cu")
		(net "P5E_CPU0_P0_RX_DN<15>")
	)
	(segment
		(start 343.45118 -386.338318)
		(end 343.58834 -386.475478)
		(width 0.14224)
		(layer "In15.Cu")
		(net "P5E_CPU0_P0_RX_DN<15>")
	)
	(segment
		(start 357.38943 -269.714218)
		(end 357.38816 -269.713456)
		(width 0.1143)
		(layer "In15.Cu")
		(net "P5E_CPU0_P0_RX_DN<15>")
	)
	(segment
		(start 358.880918 -271.938496)
		(end 358.880918 -271.873472)
		(width 0.1143)
		(layer "In15.Cu")
		(net "P5E_CPU0_P0_RX_DN<15>")
	)
	(segment
		(start 390.602216 -375.938034)
		(end 392.344656 -374.195594)
		(width 0.14224)
		(layer "In15.Cu")
		(net "P5E_CPU0_P0_RX_DN<15>")
	)
	(segment
		(start 357.35641 -269.694914)
		(end 357.349806 -269.691104)
		(width 0.1143)
		(layer "In15.Cu")
		(net "P5E_CPU0_P0_RX_DN<15>")
	)
	(segment
		(start 357.376222 -269.706344)
		(end 357.357172 -269.695422)
		(width 0.1143)
		(layer "In15.Cu")
		(net "P5E_CPU0_P0_RX_DN<15>")
	)
	(segment
		(start 322.14439 -393.787376)
		(end 322.144898 -393.786868)
		(width 0.14224)
		(layer "In15.Cu")
		(net "P5E_CPU0_P0_RX_DN<15>")
	)
	(segment
		(start 361.101132 -386.10032)
		(end 361.70362 -385.497832)
		(width 0.14224)
		(layer "In15.Cu")
		(net "P5E_CPU0_P0_RX_DN<15>")
	)
	(segment
		(start 344.7161 -386.475478)
		(end 360.195622 -386.475478)
		(width 0.14224)
		(layer "In15.Cu")
		(net "P5E_CPU0_P0_RX_DN<15>")
	)
	(segment
		(start 388.742428 -379.091952)
		(end 389.02513 -378.80925)
		(width 0.14224)
		(layer "In15.Cu")
		(net "P5E_CPU0_P0_RX_DN<15>")
	)
	(segment
		(start 386.94741 -381.211582)
		(end 387.034024 -381.124968)
		(width 0.14224)
		(layer "In15.Cu")
		(net "P5E_CPU0_P0_RX_DN<15>")
	)
	(segment
		(start 366.21847 -383.39395)
		(end 366.786922 -383.962402)
		(width 0.14224)
		(layer "In15.Cu")
		(net "P5E_CPU0_P0_RX_DN<15>")
	)
	(segment
		(start 328.440288 -389.478774)
		(end 328.440288 -387.128258)
		(width 0.14224)
		(layer "In15.Cu")
		(net "P5E_CPU0_P0_RX_DN<15>")
	)
	(segment
		(start 387.347714 -380.995174)
		(end 387.753098 -380.995174)
		(width 0.14224)
		(layer "In15.Cu")
		(net "P5E_CPU0_P0_RX_DN<15>")
	)
	(segment
		(start 370.851684 -385.032758)
		(end 370.851684 -386.859018)
		(width 0.14224)
		(layer "In15.Cu")
		(net "P5E_CPU0_P0_RX_DN<15>")
	)
	(segment
		(start 357.380794 -269.709138)
		(end 357.380032 -269.70863)
		(width 0.1143)
		(layer "In15.Cu")
		(net "P5E_CPU0_P0_RX_DN<15>")
	)
	(segment
		(start 328.570082 -386.814568)
		(end 328.779378 -386.605272)
		(width 0.14224)
		(layer "In15.Cu")
		(net "P5E_CPU0_P0_RX_DN<15>")
	)
	(segment
		(start 357.385874 -269.711932)
		(end 357.382572 -269.710154)
		(width 0.1143)
		(layer "In15.Cu")
		(net "P5E_CPU0_P0_RX_DN<15>")
	)
	(segment
		(start 359.465372 -303.956974)
		(end 359.465372 -295.34993)
		(width 0.14224)
		(layer "In15.Cu")
		(net "P5E_CPU0_P0_RX_DN<15>")
	)
	(segment
		(start 372.015004 -386.145278)
		(end 371.707664 -385.837938)
		(width 0.14224)
		(layer "In15.Cu")
		(net "P5E_CPU0_P0_RX_DN<15>")
	)
	(segment
		(start 357.376984 -269.706852)
		(end 357.376222 -269.706344)
		(width 0.1143)
		(layer "In15.Cu")
		(net "P5E_CPU0_P0_RX_DN<15>")
	)
	(segment
		(start 344.57894 -386.338318)
		(end 344.7161 -386.475478)
		(width 0.14224)
		(layer "In15.Cu")
		(net "P5E_CPU0_P0_RX_DN<15>")
	)
	(segment
		(start 388.518908 -380.215394)
		(end 388.518908 -379.63221)
		(width 0.14224)
		(layer "In15.Cu")
		(net "P5E_CPU0_P0_RX_DN<15>")
	)
	(segment
		(start 397.479266 -373.915686)
		(end 400.48561 -370.909342)
		(width 0.14224)
		(layer "In15.Cu")
		(net "P5E_CPU0_P0_RX_DN<15>")
	)
	(segment
		(start 322.266564 -393.117578)
		(end 325.181722 -390.20242)
		(width 0.14224)
		(layer "In15.Cu")
		(net "P5E_CPU0_P0_RX_DN<15>")
	)
	(segment
		(start 357.88981 -270.54175)
		(end 357.864156 -270.527018)
		(width 0.1143)
		(layer "In15.Cu")
		(net "P5E_CPU0_P0_RX_DN<15>")
	)
	(arc
		(start 358.045766 -270.846042)
		(mid 358.004511 -270.675071)
		(end 357.88981 -270.54175)
		(width 0.1143)
		(layer "In15.Cu")
		(net "P5E_CPU0_P0_RX_DN<15>")
	)
	(arc
		(start 389.675624 -378.453396)
		(mid 389.890186 -378.33636)
		(end 390.07034 -378.171202)
		(width 0.14224)
		(layer "In15.Cu")
		(net "P5E_CPU0_P0_RX_DN<15>")
	)
	(arc
		(start 328.36231 -389.595868)
		(mid 328.418979 -389.54912)
		(end 328.440288 -389.478774)
		(width 0.14224)
		(layer "In15.Cu")
		(net "P5E_CPU0_P0_RX_DN<15>")
	)
	(arc
		(start 360.195622 -386.475478)
		(mid 360.685698 -386.377978)
		(end 361.101132 -386.10032)
		(width 0.14224)
		(layer "In15.Cu")
		(net "P5E_CPU0_P0_RX_DN<15>")
	)
	(arc
		(start 388.471664 -380.32944)
		(mid 388.506626 -380.277115)
		(end 388.518908 -380.215394)
		(width 0.14224)
		(layer "In15.Cu")
		(net "P5E_CPU0_P0_RX_DN<15>")
	)
	(arc
		(start 400.677634 -353.641406)
		(mid 400.671638 -353.578534)
		(end 400.653758 -353.517962)
		(width 0.14224)
		(layer "In15.Cu")
		(net "P5E_CPU0_P0_RX_DN<15>")
	)
	(arc
		(start 388.518908 -379.63221)
		(mid 388.576949 -379.339857)
		(end 388.742428 -379.091952)
		(width 0.14224)
		(layer "In15.Cu")
		(net "P5E_CPU0_P0_RX_DN<15>")
	)
	(arc
		(start 397.264128 -374.00484)
		(mid 397.380561 -373.981662)
		(end 397.479266 -373.915686)
		(width 0.14224)
		(layer "In15.Cu")
		(net "P5E_CPU0_P0_RX_DN<15>")
	)
	(arc
		(start 357.85806 -270.523208)
		(mid 357.659092 -270.324735)
		(end 357.58628 -270.053308)
		(width 0.1143)
		(layer "In15.Cu")
		(net "P5E_CPU0_P0_RX_DN<15>")
	)
	(arc
		(start 361.70362 -385.497832)
		(mid 361.743838 -385.448969)
		(end 361.773724 -385.393184)
		(width 0.14224)
		(layer "In15.Cu")
		(net "P5E_CPU0_P0_RX_DN<15>")
	)
	(arc
		(start 387.753098 -380.995174)
		(mid 387.801893 -380.985468)
		(end 387.843268 -380.957836)
		(width 0.14224)
		(layer "In15.Cu")
		(net "P5E_CPU0_P0_RX_DN<15>")
	)
	(arc
		(start 373.66321 -326.129396)
		(mid 373.027148 -325.419108)
		(end 372.472966 -324.643242)
		(width 0.14224)
		(layer "In15.Cu")
		(net "P5E_CPU0_P0_RX_DN<15>")
	)
	(arc
		(start 328.779378 -386.605272)
		(mid 328.923301 -386.509136)
		(end 329.093068 -386.475478)
		(width 0.14224)
		(layer "In15.Cu")
		(net "P5E_CPU0_P0_RX_DN<15>")
	)
	(arc
		(start 357.58628 -270.04391)
		(mid 357.536496 -269.857296)
		(end 357.400352 -269.720314)
		(width 0.1143)
		(layer "In15.Cu")
		(net "P5E_CPU0_P0_RX_DN<15>")
	)
	(arc
		(start 363.382306 -382.775968)
		(mid 363.526112 -382.67988)
		(end 363.695742 -382.646174)
		(width 0.14224)
		(layer "In15.Cu")
		(net "P5E_CPU0_P0_RX_DN<15>")
	)
	(arc
		(start 392.344656 -374.195594)
		(mid 392.556067 -374.054397)
		(end 392.805412 -374.00484)
		(width 0.14224)
		(layer "In15.Cu")
		(net "P5E_CPU0_P0_RX_DN<15>")
	)
	(arc
		(start 327.633838 -389.871458)
		(mid 327.69665 -389.865218)
		(end 327.757028 -389.84682)
		(width 0.14224)
		(layer "In15.Cu")
		(net "P5E_CPU0_P0_RX_DN<15>")
	)
	(arc
		(start 328.440288 -387.128258)
		(mid 328.473978 -386.958505)
		(end 328.570082 -386.814568)
		(width 0.14224)
		(layer "In15.Cu")
		(net "P5E_CPU0_P0_RX_DN<15>")
	)
	(arc
		(start 357.349044 -269.690596)
		(mid 357.197057 -269.534088)
		(end 357.115618 -269.331694)
		(width 0.1143)
		(layer "In15.Cu")
		(net "P5E_CPU0_P0_RX_DN<15>")
	)
	(arc
		(start 362.077508 -384.560318)
		(mid 362.229707 -384.051657)
		(end 362.538518 -383.619756)
		(width 0.14224)
		(layer "In15.Cu")
		(net "P5E_CPU0_P0_RX_DN<15>")
	)
	(arc
		(start 359.543858 -304.227484)
		(mid 359.485417 -304.097798)
		(end 359.465372 -303.956974)
		(width 0.14224)
		(layer "In15.Cu")
		(net "P5E_CPU0_P0_RX_DN<15>")
	)
	(arc
		(start 400.40814 -352.909632)
		(mid 400.378637 -352.853667)
		(end 400.338544 -352.80473)
		(width 0.14224)
		(layer "In15.Cu")
		(net "P5E_CPU0_P0_RX_DN<15>")
	)
	(arc
		(start 386.827522 -381.501142)
		(mid 386.858674 -381.344439)
		(end 386.94741 -381.211582)
		(width 0.14224)
		(layer "In15.Cu")
		(net "P5E_CPU0_P0_RX_DN<15>")
	)
	(arc
		(start 358.289098 -271.310608)
		(mid 358.110285 -271.108258)
		(end 358.045766 -270.846042)
		(width 0.1143)
		(layer "In15.Cu")
		(net "P5E_CPU0_P0_RX_DN<15>")
	)
	(arc
		(start 386.80517 -383.03454)
		(mid 386.821882 -382.973564)
		(end 386.827522 -382.910588)
		(width 0.14224)
		(layer "In15.Cu")
		(net "P5E_CPU0_P0_RX_DN<15>")
	)
	(arc
		(start 357.349806 -269.691104)
		(mid 357.349425 -269.69085)
		(end 357.349044 -269.690596)
		(width 0.1143)
		(layer "In15.Cu")
		(net "P5E_CPU0_P0_RX_DN<15>")
	)
	(arc
		(start 400.48561 -370.909342)
		(mid 400.627717 -370.696663)
		(end 400.677634 -370.445792)
		(width 0.14224)
		(layer "In15.Cu")
		(net "P5E_CPU0_P0_RX_DN<15>")
	)
	(arc
		(start 390.23417 -376.82678)
		(mid 390.329823 -376.345812)
		(end 390.602216 -375.938034)
		(width 0.14224)
		(layer "In15.Cu")
		(net "P5E_CPU0_P0_RX_DN<15>")
	)
	(arc
		(start 389.02513 -378.80925)
		(mid 389.119081 -378.725201)
		(end 389.221726 -378.652024)
		(width 0.14224)
		(layer "In15.Cu")
		(net "P5E_CPU0_P0_RX_DN<15>")
	)
	(arc
		(start 389.221726 -378.652024)
		(mid 389.299459 -378.607552)
		(end 389.380984 -378.57049)
		(width 0.14224)
		(layer "In15.Cu")
		(net "P5E_CPU0_P0_RX_DN<15>")
	)
	(arc
		(start 362.00588 -384.83159)
		(mid 362.050767 -384.69835)
		(end 362.077508 -384.560318)
		(width 0.14224)
		(layer "In15.Cu")
		(net "P5E_CPU0_P0_RX_DN<15>")
	)
	(arc
		(start 357.115618 -269.331694)
		(mid 357.113595 -269.320284)
		(end 357.111808 -269.308834)
		(width 0.1143)
		(layer "In15.Cu")
		(net "P5E_CPU0_P0_RX_DN<15>")
	)
	(arc
		(start 364.410498 -382.646174)
		(mid 365.388412 -382.841299)
		(end 366.21847 -383.39395)
		(width 0.14224)
		(layer "In15.Cu")
		(net "P5E_CPU0_P0_RX_DN<15>")
	)
	(arc
		(start 325.181722 -390.20242)
		(mid 325.548111 -389.957577)
		(end 325.980298 -389.871458)
		(width 0.14224)
		(layer "In15.Cu")
		(net "P5E_CPU0_P0_RX_DN<15>")
	)
	(arc
		(start 382.153922 -384.725418)
		(mid 383.955056 -384.605507)
		(end 385.7244 -384.247898)
		(width 0.14224)
		(layer "In15.Cu")
		(net "P5E_CPU0_P0_RX_DN<15>")
	)
	(arc
		(start 385.7244 -384.247898)
		(mid 386.305005 -383.928642)
		(end 386.676138 -383.379726)
		(width 0.14224)
		(layer "In15.Cu")
		(net "P5E_CPU0_P0_RX_DN<15>")
	)
	(arc
		(start 390.07034 -378.171202)
		(mid 390.191955 -377.963849)
		(end 390.23417 -377.72721)
		(width 0.14224)
		(layer "In15.Cu")
		(net "P5E_CPU0_P0_RX_DN<15>")
	)
	(arc
		(start 387.034024 -381.124968)
		(mid 387.177947 -381.028832)
		(end 387.347714 -380.995174)
		(width 0.14224)
		(layer "In15.Cu")
		(net "P5E_CPU0_P0_RX_DN<15>")
	)
	(arc
		(start 366.786922 -383.962402)
		(mid 367.632056 -384.527069)
		(end 368.62893 -384.725418)
		(width 0.14224)
		(layer "In15.Cu")
		(net "P5E_CPU0_P0_RX_DN<15>")
	)
	(segment
		(start 357.197914 -270.580104)
		(end 356.731062 -270.846042)
		(width 0.12954)
		(layer "F.Cu")
		(net "P5E_CPU0_P0_RX_DN<14>")
	)
	(segment
		(start 320.07048 -393.69238)
		(end 320.59118 -393.69238)
		(width 0.127)
		(layer "F.Cu")
		(net "P5E_CPU0_P0_RX_DN<14>")
	)
	(segment
		(start 358.307132 -279.421336)
		(end 358.306624 -279.420828)
		(width 0.1143)
		(layer "In15.Cu")
		(net "P5E_CPU0_P0_RX_DN<14>")
	)
	(segment
		(start 358.359964 -277.832058)
		(end 358.289098 -277.790656)
		(width 0.1143)
		(layer "In15.Cu")
		(net "P5E_CPU0_P0_RX_DN<14>")
	)
	(segment
		(start 358.289098 -281.72156)
		(end 358.36098 -281.67965)
		(width 0.1143)
		(layer "In15.Cu")
		(net "P5E_CPU0_P0_RX_DN<14>")
	)
	(segment
		(start 358.307132 -276.850856)
		(end 358.322118 -276.84222)
		(width 0.1143)
		(layer "In15.Cu")
		(net "P5E_CPU0_P0_RX_DN<14>")
	)
	(segment
		(start 358.32542 -278.466042)
		(end 358.329738 -278.463502)
		(width 0.1143)
		(layer "In15.Cu")
		(net "P5E_CPU0_P0_RX_DN<14>")
	)
	(segment
		(start 389.659622 -375.199656)
		(end 391.66419 -373.195088)
		(width 0.14224)
		(layer "In15.Cu")
		(net "P5E_CPU0_P0_RX_DN<14>")
	)
	(segment
		(start 359.551224 -375.76125)
		(end 359.858564 -376.06859)
		(width 0.14224)
		(layer "In15.Cu")
		(net "P5E_CPU0_P0_RX_DN<14>")
	)
	(segment
		(start 325.777606 -382.63703)
		(end 329.331574 -379.083062)
		(width 0.14224)
		(layer "In15.Cu")
		(net "P5E_CPU0_P0_RX_DN<14>")
	)
	(segment
		(start 320.59118 -393.69238)
		(end 320.94424 -393.787376)
		(width 0.14224)
		(layer "In15.Cu")
		(net "P5E_CPU0_P0_RX_DN<14>")
	)
	(segment
		(start 387.50113 -373.48541)
		(end 387.79323 -373.77751)
		(width 0.14224)
		(layer "In15.Cu")
		(net "P5E_CPU0_P0_RX_DN<14>")
	)
	(segment
		(start 358.323642 -276.841204)
		(end 358.326182 -276.83968)
		(width 0.1143)
		(layer "In15.Cu")
		(net "P5E_CPU0_P0_RX_DN<14>")
	)
	(segment
		(start 387.79323 -373.77751)
		(end 387.79323 -374.61317)
		(width 0.14224)
		(layer "In15.Cu")
		(net "P5E_CPU0_P0_RX_DN<14>")
	)
	(segment
		(start 382.037082 -374.90527)
		(end 381.894842 -375.04751)
		(width 0.14224)
		(layer "In15.Cu")
		(net "P5E_CPU0_P0_RX_DN<14>")
	)
	(segment
		(start 358.289098 -275.241512)
		(end 358.35971 -275.20011)
		(width 0.1143)
		(layer "In15.Cu")
		(net "P5E_CPU0_P0_RX_DN<14>")
	)
	(segment
		(start 358.328214 -281.05354)
		(end 358.289098 -281.03068)
		(width 0.1143)
		(layer "In15.Cu")
		(net "P5E_CPU0_P0_RX_DN<14>")
	)
	(segment
		(start 382.037082 -375.76125)
		(end 388.30377 -375.76125)
		(width 0.14224)
		(layer "In15.Cu")
		(net "P5E_CPU0_P0_RX_DN<14>")
	)
	(segment
		(start 361.021884 -377.18111)
		(end 360.714544 -376.87377)
		(width 0.14224)
		(layer "In15.Cu")
		(net "P5E_CPU0_P0_RX_DN<14>")
	)
	(segment
		(start 357.029004 -270.846042)
		(end 356.731062 -270.846042)
		(width 0.1143)
		(layer "In15.Cu")
		(net "P5E_CPU0_P0_RX_DN<14>")
	)
	(segment
		(start 358.289098 -288.201354)
		(end 358.352598 -288.16427)
		(width 0.1143)
		(layer "In15.Cu")
		(net "P5E_CPU0_P0_RX_DN<14>")
	)
	(segment
		(start 358.32796 -293.038784)
		(end 358.328214 -293.03853)
		(width 0.1143)
		(layer "In15.Cu")
		(net "P5E_CPU0_P0_RX_DN<14>")
	)
	(segment
		(start 360.714544 -376.06859)
		(end 361.021884 -375.76125)
		(width 0.14224)
		(layer "In15.Cu")
		(net "P5E_CPU0_P0_RX_DN<14>")
	)
	(segment
		(start 359.858564 -377.89485)
		(end 360.000804 -378.03709)
		(width 0.14224)
		(layer "In15.Cu")
		(net "P5E_CPU0_P0_RX_DN<14>")
	)
	(segment
		(start 330.129134 -378.0917)
		(end 330.43114 -377.789694)
		(width 0.14224)
		(layer "In15.Cu")
		(net "P5E_CPU0_P0_RX_DN<14>")
	)
	(segment
		(start 381.894842 -375.04751)
		(end 381.894842 -375.61901)
		(width 0.14224)
		(layer "In15.Cu")
		(net "P5E_CPU0_P0_RX_DN<14>")
	)
	(segment
		(start 358.51592 -273.27606)
		(end 358.515666 -273.27606)
		(width 0.1143)
		(layer "In15.Cu")
		(net "P5E_CPU0_P0_RX_DN<14>")
	)
	(segment
		(start 358.367584 -292.417246)
		(end 358.32669 -292.392354)
		(width 0.1143)
		(layer "In15.Cu")
		(net "P5E_CPU0_P0_RX_DN<14>")
	)
	(segment
		(start 360.000804 -378.03709)
		(end 362.83646 -378.03709)
		(width 0.14224)
		(layer "In15.Cu")
		(net "P5E_CPU0_P0_RX_DN<14>")
	)
	(segment
		(start 358.307132 -280.09088)
		(end 358.322118 -280.082244)
		(width 0.1143)
		(layer "In15.Cu")
		(net "P5E_CPU0_P0_RX_DN<14>")
	)
	(segment
		(start 320.944748 -393.786868)
		(end 321.066414 -393.716764)
		(width 0.14224)
		(layer "In15.Cu")
		(net "P5E_CPU0_P0_RX_DN<14>")
	)
	(segment
		(start 330.926694 -377.488196)
		(end 330.926694 -377.29414)
		(width 0.14224)
		(layer "In15.Cu")
		(net "P5E_CPU0_P0_RX_DN<14>")
	)
	(segment
		(start 358.306624 -280.091388)
		(end 358.307132 -280.09088)
		(width 0.1143)
		(layer "In15.Cu")
		(net "P5E_CPU0_P0_RX_DN<14>")
	)
	(segment
		(start 358.515412 -274.910042)
		(end 358.515412 -274.8915)
		(width 0.1143)
		(layer "In15.Cu")
		(net "P5E_CPU0_P0_RX_DN<14>")
	)
	(segment
		(start 370.60632 -324.396862)
		(end 358.118156 -303.75606)
		(width 0.14224)
		(layer "In15.Cu")
		(net "P5E_CPU0_P0_RX_DN<14>")
	)
	(segment
		(start 398.509998 -352.353372)
		(end 370.797328 -324.640448)
		(width 0.14224)
		(layer "In15.Cu")
		(net "P5E_CPU0_P0_RX_DN<14>")
	)
	(segment
		(start 321.066414 -393.545822)
		(end 320.749422 -393.22883)
		(width 0.14224)
		(layer "In15.Cu")
		(net "P5E_CPU0_P0_RX_DN<14>")
	)
	(segment
		(start 358.36098 -281.07259)
		(end 358.328214 -281.05354)
		(width 0.1143)
		(layer "In15.Cu")
		(net "P5E_CPU0_P0_RX_DN<14>")
	)
	(segment
		(start 358.515666 -284.619446)
		(end 358.515666 -284.616144)
		(width 0.1143)
		(layer "In15.Cu")
		(net "P5E_CPU0_P0_RX_DN<14>")
	)
	(segment
		(start 362.9787 -377.32335)
		(end 362.83646 -377.18111)
		(width 0.14224)
		(layer "In15.Cu")
		(net "P5E_CPU0_P0_RX_DN<14>")
	)
	(segment
		(start 358.289098 -276.861524)
		(end 358.306624 -276.851364)
		(width 0.1143)
		(layer "In15.Cu")
		(net "P5E_CPU0_P0_RX_DN<14>")
	)
	(segment
		(start 358.289098 -291.441378)
		(end 358.358694 -291.400738)
		(width 0.1143)
		(layer "In15.Cu")
		(net "P5E_CPU0_P0_RX_DN<14>")
	)
	(segment
		(start 358.358694 -289.171126)
		(end 358.289098 -289.130486)
		(width 0.1143)
		(layer "In15.Cu")
		(net "P5E_CPU0_P0_RX_DN<14>")
	)
	(segment
		(start 358.289098 -284.961584)
		(end 358.35971 -284.920436)
		(width 0.1143)
		(layer "In15.Cu")
		(net "P5E_CPU0_P0_RX_DN<14>")
	)
	(segment
		(start 331.2287 -376.992134)
		(end 331.422756 -376.992134)
		(width 0.14224)
		(layer "In15.Cu")
		(net "P5E_CPU0_P0_RX_DN<14>")
	)
	(segment
		(start 358.324658 -294.660574)
		(end 358.396032 -294.615108)
		(width 0.1143)
		(layer "In15.Cu")
		(net "P5E_CPU0_P0_RX_DN<14>")
	)
	(segment
		(start 362.83646 -377.18111)
		(end 361.021884 -377.18111)
		(width 0.14224)
		(layer "In15.Cu")
		(net "P5E_CPU0_P0_RX_DN<14>")
	)
	(segment
		(start 358.328214 -294.013382)
		(end 358.32796 -294.013382)
		(width 0.1143)
		(layer "In15.Cu")
		(net "P5E_CPU0_P0_RX_DN<14>")
	)
	(segment
		(start 358.359964 -294.031924)
		(end 358.328214 -294.013382)
		(width 0.1143)
		(layer "In15.Cu")
		(net "P5E_CPU0_P0_RX_DN<14>")
	)
	(segment
		(start 329.827636 -378.587254)
		(end 330.129134 -378.285756)
		(width 0.14224)
		(layer "In15.Cu")
		(net "P5E_CPU0_P0_RX_DN<14>")
	)
	(segment
		(start 358.306624 -276.180804)
		(end 358.290622 -276.17166)
		(width 0.1143)
		(layer "In15.Cu")
		(net "P5E_CPU0_P0_RX_DN<14>")
	)
	(segment
		(start 358.515666 -286.236664)
		(end 358.515666 -286.236156)
		(width 0.1143)
		(layer "In15.Cu")
		(net "P5E_CPU0_P0_RX_DN<14>")
	)
	(segment
		(start 387.79323 -374.61317)
		(end 387.50113 -374.90527)
		(width 0.14224)
		(layer "In15.Cu")
		(net "P5E_CPU0_P0_RX_DN<14>")
	)
	(segment
		(start 358.360726 -286.539686)
		(end 358.361234 -286.539178)
		(width 0.1143)
		(layer "In15.Cu")
		(net "P5E_CPU0_P0_RX_DN<14>")
	)
	(segment
		(start 358.290622 -294.680386)
		(end 358.324658 -294.660574)
		(width 0.1143)
		(layer "In15.Cu")
		(net "P5E_CPU0_P0_RX_DN<14>")
	)
	(segment
		(start 381.894842 -375.61901)
		(end 382.037082 -375.76125)
		(width 0.14224)
		(layer "In15.Cu")
		(net "P5E_CPU0_P0_RX_DN<14>")
	)
	(segment
		(start 358.361234 -274.59305)
		(end 358.290622 -274.551648)
		(width 0.1143)
		(layer "In15.Cu")
		(net "P5E_CPU0_P0_RX_DN<14>")
	)
	(segment
		(start 330.926694 -377.29414)
		(end 331.2287 -376.992134)
		(width 0.14224)
		(layer "In15.Cu")
		(net "P5E_CPU0_P0_RX_DN<14>")
	)
	(segment
		(start 358.289098 -289.821366)
		(end 358.358694 -289.780726)
		(width 0.1143)
		(layer "In15.Cu")
		(net "P5E_CPU0_P0_RX_DN<14>")
	)
	(segment
		(start 396.516098 -372.742968)
		(end 399.312638 -369.946428)
		(width 0.14224)
		(layer "In15.Cu")
		(net "P5E_CPU0_P0_RX_DN<14>")
	)
	(segment
		(start 358.328214 -293.03853)
		(end 358.359456 -293.020242)
		(width 0.1143)
		(layer "In15.Cu")
		(net "P5E_CPU0_P0_RX_DN<14>")
	)
	(segment
		(start 358.358694 -272.97126)
		(end 358.289098 -272.93062)
		(width 0.1143)
		(layer "In15.Cu")
		(net "P5E_CPU0_P0_RX_DN<14>")
	)
	(segment
		(start 358.306624 -276.851364)
		(end 358.307132 -276.850856)
		(width 0.1143)
		(layer "In15.Cu")
		(net "P5E_CPU0_P0_RX_DN<14>")
	)
	(segment
		(start 358.32669 -292.392354)
		(end 358.289098 -292.37051)
		(width 0.1143)
		(layer "In15.Cu")
		(net "P5E_CPU0_P0_RX_DN<14>")
	)
	(segment
		(start 325.48322 -386.063744)
		(end 325.48322 -383.347976)
		(width 0.14224)
		(layer "In15.Cu")
		(net "P5E_CPU0_P0_RX_DN<14>")
	)
	(segment
		(start 358.359456 -293.020242)
		(end 358.360218 -293.019734)
		(width 0.1143)
		(layer "In15.Cu")
		(net "P5E_CPU0_P0_RX_DN<14>")
	)
	(segment
		(start 358.358694 -290.791138)
		(end 358.289098 -290.750498)
		(width 0.1143)
		(layer "In15.Cu")
		(net "P5E_CPU0_P0_RX_DN<14>")
	)
	(segment
		(start 358.289098 -273.6215)
		(end 358.36098 -273.57959)
		(width 0.1143)
		(layer "In15.Cu")
		(net "P5E_CPU0_P0_RX_DN<14>")
	)
	(segment
		(start 358.358694 -282.691332)
		(end 358.289098 -282.650692)
		(width 0.1143)
		(layer "In15.Cu")
		(net "P5E_CPU0_P0_RX_DN<14>")
	)
	(segment
		(start 357.88981 -272.161762)
		(end 357.820976 -272.121884)
		(width 0.1143)
		(layer "In15.Cu")
		(net "P5E_CPU0_P0_RX_DN<14>")
	)
	(segment
		(start 358.307132 -276.181312)
		(end 358.306624 -276.180804)
		(width 0.1143)
		(layer "In15.Cu")
		(net "P5E_CPU0_P0_RX_DN<14>")
	)
	(segment
		(start 380.474982 -375.61901)
		(end 380.474982 -373.79275)
		(width 0.14224)
		(layer "In15.Cu")
		(net "P5E_CPU0_P0_RX_DN<14>")
	)
	(segment
		(start 320.754248 -392.616944)
		(end 321.058286 -392.31316)
		(width 0.14224)
		(layer "In15.Cu")
		(net "P5E_CPU0_P0_RX_DN<14>")
	)
	(segment
		(start 360.714544 -376.87377)
		(end 360.714544 -376.06859)
		(width 0.14224)
		(layer "In15.Cu")
		(net "P5E_CPU0_P0_RX_DN<14>")
	)
	(segment
		(start 380.474982 -373.79275)
		(end 380.782322 -373.48541)
		(width 0.14224)
		(layer "In15.Cu")
		(net "P5E_CPU0_P0_RX_DN<14>")
	)
	(segment
		(start 329.63358 -378.587254)
		(end 329.827636 -378.587254)
		(width 0.14224)
		(layer "In15.Cu")
		(net "P5E_CPU0_P0_RX_DN<14>")
	)
	(segment
		(start 380.782322 -373.48541)
		(end 387.50113 -373.48541)
		(width 0.14224)
		(layer "In15.Cu")
		(net "P5E_CPU0_P0_RX_DN<14>")
	)
	(segment
		(start 362.83646 -378.03709)
		(end 362.9787 -377.89485)
		(width 0.14224)
		(layer "In15.Cu")
		(net "P5E_CPU0_P0_RX_DN<14>")
	)
	(segment
		(start 358.358694 -285.931356)
		(end 358.289098 -285.890716)
		(width 0.1143)
		(layer "In15.Cu")
		(net "P5E_CPU0_P0_RX_DN<14>")
	)
	(segment
		(start 358.326182 -276.83968)
		(end 358.326944 -276.839172)
		(width 0.1143)
		(layer "In15.Cu")
		(net "P5E_CPU0_P0_RX_DN<14>")
	)
	(segment
		(start 330.129134 -378.285756)
		(end 330.129134 -378.0917)
		(width 0.14224)
		(layer "In15.Cu")
		(net "P5E_CPU0_P0_RX_DN<14>")
	)
	(segment
		(start 358.328214 -283.318712)
		(end 358.358694 -283.300932)
		(width 0.1143)
		(layer "In15.Cu")
		(net "P5E_CPU0_P0_RX_DN<14>")
	)
	(segment
		(start 387.50113 -374.90527)
		(end 382.037082 -374.90527)
		(width 0.14224)
		(layer "In15.Cu")
		(net "P5E_CPU0_P0_RX_DN<14>")
	)
	(segment
		(start 321.058286 -392.31316)
		(end 321.058286 -391.091928)
		(width 0.14224)
		(layer "In15.Cu")
		(net "P5E_CPU0_P0_RX_DN<14>")
	)
	(segment
		(start 380.332742 -375.76125)
		(end 380.474982 -375.61901)
		(width 0.14224)
		(layer "In15.Cu")
		(net "P5E_CPU0_P0_RX_DN<14>")
	)
	(segment
		(start 358.393238 -294.055038)
		(end 358.359964 -294.031924)
		(width 0.1143)
		(layer "In15.Cu")
		(net "P5E_CPU0_P0_RX_DN<14>")
	)
	(segment
		(start 357.111808 -270.928846)
		(end 357.029004 -270.846042)
		(width 0.1143)
		(layer "In15.Cu")
		(net "P5E_CPU0_P0_RX_DN<14>")
	)
	(segment
		(start 358.358694 -284.311344)
		(end 358.289098 -284.270704)
		(width 0.1143)
		(layer "In15.Cu")
		(net "P5E_CPU0_P0_RX_DN<14>")
	)
	(segment
		(start 321.066414 -393.716764)
		(end 321.066414 -393.545822)
		(width 0.14224)
		(layer "In15.Cu")
		(net "P5E_CPU0_P0_RX_DN<14>")
	)
	(segment
		(start 357.41991 -271.351756)
		(end 357.349044 -271.310608)
		(width 0.1143)
		(layer "In15.Cu")
		(net "P5E_CPU0_P0_RX_DN<14>")
	)
	(segment
		(start 358.306624 -279.420828)
		(end 358.290622 -279.411684)
		(width 0.1143)
		(layer "In15.Cu")
		(net "P5E_CPU0_P0_RX_DN<14>")
	)
	(segment
		(start 358.322118 -276.84222)
		(end 358.323642 -276.841204)
		(width 0.1143)
		(layer "In15.Cu")
		(net "P5E_CPU0_P0_RX_DN<14>")
	)
	(segment
		(start 358.515666 -273.27606)
		(end 358.515666 -273.27352)
		(width 0.1143)
		(layer "In15.Cu")
		(net "P5E_CPU0_P0_RX_DN<14>")
	)
	(segment
		(start 358.289098 -286.581342)
		(end 358.328214 -286.558482)
		(width 0.1143)
		(layer "In15.Cu")
		(net "P5E_CPU0_P0_RX_DN<14>")
	)
	(segment
		(start 320.94424 -393.787376)
		(end 320.944748 -393.786868)
		(width 0.14224)
		(layer "In15.Cu")
		(net "P5E_CPU0_P0_RX_DN<14>")
	)
	(segment
		(start 358.328214 -286.558482)
		(end 358.360726 -286.539686)
		(width 0.1143)
		(layer "In15.Cu")
		(net "P5E_CPU0_P0_RX_DN<14>")
	)
	(segment
		(start 358.323642 -280.081228)
		(end 358.326182 -280.079704)
		(width 0.1143)
		(layer "In15.Cu")
		(net "P5E_CPU0_P0_RX_DN<14>")
	)
	(segment
		(start 329.331574 -378.88926)
		(end 329.63358 -378.587254)
		(width 0.14224)
		(layer "In15.Cu")
		(net "P5E_CPU0_P0_RX_DN<14>")
	)
	(segment
		(start 361.021884 -375.76125)
		(end 380.332742 -375.76125)
		(width 0.14224)
		(layer "In15.Cu")
		(net "P5E_CPU0_P0_RX_DN<14>")
	)
	(segment
		(start 359.858564 -376.06859)
		(end 359.858564 -377.89485)
		(width 0.14224)
		(layer "In15.Cu")
		(net "P5E_CPU0_P0_RX_DN<14>")
	)
	(segment
		(start 358.045766 -295.76776)
		(end 358.045766 -295.145968)
		(width 0.1143)
		(layer "In15.Cu")
		(net "P5E_CPU0_P0_RX_DN<14>")
	)
	(segment
		(start 358.000046 -295.81348)
		(end 358.045766 -295.76776)
		(width 0.1143)
		(layer "In15.Cu")
		(net "P5E_CPU0_P0_RX_DN<14>")
	)
	(segment
		(start 358.326944 -280.079196)
		(end 358.328214 -280.078434)
		(width 0.1143)
		(layer "In15.Cu")
		(net "P5E_CPU0_P0_RX_DN<14>")
	)
	(segment
		(start 331.422756 -376.992134)
		(end 332.433168 -375.981722)
		(width 0.14224)
		(layer "In15.Cu")
		(net "P5E_CPU0_P0_RX_DN<14>")
	)
	(segment
		(start 358.322118 -280.082244)
		(end 358.323642 -280.081228)
		(width 0.1143)
		(layer "In15.Cu")
		(net "P5E_CPU0_P0_RX_DN<14>")
	)
	(segment
		(start 358.515412 -292.72992)
		(end 358.515412 -292.702742)
		(width 0.1143)
		(layer "In15.Cu")
		(net "P5E_CPU0_P0_RX_DN<14>")
	)
	(segment
		(start 333.080106 -375.76125)
		(end 359.551224 -375.76125)
		(width 0.14224)
		(layer "In15.Cu")
		(net "P5E_CPU0_P0_RX_DN<14>")
	)
	(segment
		(start 358.289098 -283.341572)
		(end 358.289606 -283.341318)
		(width 0.1143)
		(layer "In15.Cu")
		(net "P5E_CPU0_P0_RX_DN<14>")
	)
	(segment
		(start 358.328468 -276.193758)
		(end 358.307132 -276.181312)
		(width 0.1143)
		(layer "In15.Cu")
		(net "P5E_CPU0_P0_RX_DN<14>")
	)
	(segment
		(start 329.331574 -379.083062)
		(end 329.331574 -378.88926)
		(width 0.14224)
		(layer "In15.Cu")
		(net "P5E_CPU0_P0_RX_DN<14>")
	)
	(segment
		(start 330.43114 -377.789694)
		(end 330.625196 -377.789694)
		(width 0.14224)
		(layer "In15.Cu")
		(net "P5E_CPU0_P0_RX_DN<14>")
	)
	(segment
		(start 358.000046 -303.332642)
		(end 358.000046 -295.841928)
		(width 0.14224)
		(layer "In15.Cu")
		(net "P5E_CPU0_P0_RX_DN<14>")
	)
	(segment
		(start 358.328468 -279.433782)
		(end 358.307132 -279.421336)
		(width 0.1143)
		(layer "In15.Cu")
		(net "P5E_CPU0_P0_RX_DN<14>")
	)
	(segment
		(start 358.000046 -295.841928)
		(end 358.000046 -295.81348)
		(width 0.1143)
		(layer "In15.Cu")
		(net "P5E_CPU0_P0_RX_DN<14>")
	)
	(segment
		(start 320.749422 -393.22883)
		(end 320.754248 -392.616944)
		(width 0.14224)
		(layer "In15.Cu")
		(net "P5E_CPU0_P0_RX_DN<14>")
	)
	(segment
		(start 358.326944 -276.839172)
		(end 358.328214 -276.83841)
		(width 0.1143)
		(layer "In15.Cu")
		(net "P5E_CPU0_P0_RX_DN<14>")
	)
	(segment
		(start 392.665458 -372.780306)
		(end 396.426182 -372.780306)
		(width 0.14224)
		(layer "In15.Cu")
		(net "P5E_CPU0_P0_RX_DN<14>")
	)
	(segment
		(start 330.625196 -377.789694)
		(end 330.926694 -377.488196)
		(width 0.14224)
		(layer "In15.Cu")
		(net "P5E_CPU0_P0_RX_DN<14>")
	)
	(segment
		(start 358.329738 -278.463502)
		(end 358.329992 -278.463502)
		(width 0.1143)
		(layer "In15.Cu")
		(net "P5E_CPU0_P0_RX_DN<14>")
	)
	(segment
		(start 321.247008 -390.636252)
		(end 325.245476 -386.637784)
		(width 0.14224)
		(layer "In15.Cu")
		(net "P5E_CPU0_P0_RX_DN<14>")
	)
	(segment
		(start 358.358694 -287.551368)
		(end 358.291638 -287.512252)
		(width 0.1143)
		(layer "In15.Cu")
		(net "P5E_CPU0_P0_RX_DN<14>")
	)
	(segment
		(start 358.289098 -280.101548)
		(end 358.306624 -280.091388)
		(width 0.1143)
		(layer "In15.Cu")
		(net "P5E_CPU0_P0_RX_DN<14>")
	)
	(segment
		(start 358.289606 -283.341318)
		(end 358.328214 -283.318712)
		(width 0.1143)
		(layer "In15.Cu")
		(net "P5E_CPU0_P0_RX_DN<14>")
	)
	(segment
		(start 399.485358 -369.529614)
		(end 399.485358 -354.707952)
		(width 0.14224)
		(layer "In15.Cu")
		(net "P5E_CPU0_P0_RX_DN<14>")
	)
	(segment
		(start 358.326182 -280.079704)
		(end 358.326944 -280.079196)
		(width 0.1143)
		(layer "In15.Cu")
		(net "P5E_CPU0_P0_RX_DN<14>")
	)
	(segment
		(start 358.360726 -272.972784)
		(end 358.358694 -272.97126)
		(width 0.1143)
		(layer "In15.Cu")
		(net "P5E_CPU0_P0_RX_DN<14>")
	)
	(segment
		(start 362.9787 -377.89485)
		(end 362.9787 -377.32335)
		(width 0.14224)
		(layer "In15.Cu")
		(net "P5E_CPU0_P0_RX_DN<14>")
	)
	(arc
		(start 399.312638 -369.946428)
		(mid 399.440471 -369.755206)
		(end 399.485358 -369.529614)
		(width 0.14224)
		(layer "In15.Cu")
		(net "P5E_CPU0_P0_RX_DN<14>")
	)
	(arc
		(start 358.512872 -287.812226)
		(mid 358.463381 -287.665477)
		(end 358.358694 -287.551368)
		(width 0.1143)
		(layer "In15.Cu")
		(net "P5E_CPU0_P0_RX_DN<14>")
	)
	(arc
		(start 358.358694 -283.300932)
		(mid 358.515671 -282.996132)
		(end 358.358694 -282.691332)
		(width 0.1143)
		(layer "In15.Cu")
		(net "P5E_CPU0_P0_RX_DN<14>")
	)
	(arc
		(start 358.289098 -276.170644)
		(mid 358.045771 -275.706078)
		(end 358.289098 -275.241512)
		(width 0.1143)
		(layer "In15.Cu")
		(net "P5E_CPU0_P0_RX_DN<14>")
	)
	(arc
		(start 325.245476 -386.637784)
		(mid 325.421455 -386.374412)
		(end 325.48322 -386.063744)
		(width 0.14224)
		(layer "In15.Cu")
		(net "P5E_CPU0_P0_RX_DN<14>")
	)
	(arc
		(start 358.515666 -286.236156)
		(mid 358.474117 -286.064734)
		(end 358.358694 -285.931356)
		(width 0.1143)
		(layer "In15.Cu")
		(net "P5E_CPU0_P0_RX_DN<14>")
	)
	(arc
		(start 358.289098 -294.681402)
		(mid 358.28986 -294.680893)
		(end 358.290622 -294.680386)
		(width 0.1143)
		(layer "In15.Cu")
		(net "P5E_CPU0_P0_RX_DN<14>")
	)
	(arc
		(start 358.36098 -281.67965)
		(mid 358.512872 -281.37612)
		(end 358.36098 -281.07259)
		(width 0.1143)
		(layer "In15.Cu")
		(net "P5E_CPU0_P0_RX_DN<14>")
	)
	(arc
		(start 358.118156 -303.75606)
		(mid 358.030139 -303.552431)
		(end 358.000046 -303.332642)
		(width 0.14224)
		(layer "In15.Cu")
		(net "P5E_CPU0_P0_RX_DN<14>")
	)
	(arc
		(start 358.328214 -276.83841)
		(mid 358.513128 -276.516194)
		(end 358.328468 -276.193758)
		(width 0.1143)
		(layer "In15.Cu")
		(net "P5E_CPU0_P0_RX_DN<14>")
	)
	(arc
		(start 358.515412 -274.8915)
		(mid 358.474649 -274.723506)
		(end 358.361234 -274.59305)
		(width 0.1143)
		(layer "In15.Cu")
		(net "P5E_CPU0_P0_RX_DN<14>")
	)
	(arc
		(start 358.289098 -274.550632)
		(mid 358.045771 -274.086066)
		(end 358.289098 -273.6215)
		(width 0.1143)
		(layer "In15.Cu")
		(net "P5E_CPU0_P0_RX_DN<14>")
	)
	(arc
		(start 358.289098 -292.37051)
		(mid 358.045771 -291.905944)
		(end 358.289098 -291.441378)
		(width 0.1143)
		(layer "In15.Cu")
		(net "P5E_CPU0_P0_RX_DN<14>")
	)
	(arc
		(start 358.289098 -290.750498)
		(mid 358.045771 -290.285932)
		(end 358.289098 -289.821366)
		(width 0.1143)
		(layer "In15.Cu")
		(net "P5E_CPU0_P0_RX_DN<14>")
	)
	(arc
		(start 325.48322 -383.347976)
		(mid 325.559731 -382.963238)
		(end 325.777606 -382.63703)
		(width 0.14224)
		(layer "In15.Cu")
		(net "P5E_CPU0_P0_RX_DN<14>")
	)
	(arc
		(start 332.85049 -375.775982)
		(mid 332.96506 -375.764909)
		(end 333.080106 -375.76125)
		(width 0.14224)
		(layer "In15.Cu")
		(net "P5E_CPU0_P0_RX_DN<14>")
	)
	(arc
		(start 358.289098 -284.270704)
		(mid 358.045771 -283.806138)
		(end 358.289098 -283.341572)
		(width 0.1143)
		(layer "In15.Cu")
		(net "P5E_CPU0_P0_RX_DN<14>")
	)
	(arc
		(start 358.289098 -272.93062)
		(mid 358.110285 -272.72827)
		(end 358.045766 -272.466054)
		(width 0.1143)
		(layer "In15.Cu")
		(net "P5E_CPU0_P0_RX_DN<14>")
	)
	(arc
		(start 358.290622 -276.17166)
		(mid 358.28986 -276.171153)
		(end 358.289098 -276.170644)
		(width 0.1143)
		(layer "In15.Cu")
		(net "P5E_CPU0_P0_RX_DN<14>")
	)
	(arc
		(start 358.32796 -294.013382)
		(mid 358.048416 -293.526146)
		(end 358.32796 -293.038784)
		(width 0.1143)
		(layer "In15.Cu")
		(net "P5E_CPU0_P0_RX_DN<14>")
	)
	(arc
		(start 358.361234 -286.539178)
		(mid 358.474789 -286.406479)
		(end 358.515666 -286.236664)
		(width 0.1143)
		(layer "In15.Cu")
		(net "P5E_CPU0_P0_RX_DN<14>")
	)
	(arc
		(start 358.045766 -287.045908)
		(mid 358.110281 -286.783689)
		(end 358.289098 -286.581342)
		(width 0.1143)
		(layer "In15.Cu")
		(net "P5E_CPU0_P0_RX_DN<14>")
	)
	(arc
		(start 358.290622 -279.411684)
		(mid 358.048109 -278.929301)
		(end 358.32542 -278.466042)
		(width 0.1143)
		(layer "In15.Cu")
		(net "P5E_CPU0_P0_RX_DN<14>")
	)
	(arc
		(start 357.349044 -271.310608)
		(mid 357.197057 -271.1541)
		(end 357.115618 -270.951706)
		(width 0.1143)
		(layer "In15.Cu")
		(net "P5E_CPU0_P0_RX_DN<14>")
	)
	(arc
		(start 358.045766 -295.145968)
		(mid 358.110281 -294.883749)
		(end 358.289098 -294.681402)
		(width 0.1143)
		(layer "In15.Cu")
		(net "P5E_CPU0_P0_RX_DN<14>")
	)
	(arc
		(start 358.396032 -294.615108)
		(mid 358.540536 -294.334307)
		(end 358.393238 -294.055038)
		(width 0.1143)
		(layer "In15.Cu")
		(net "P5E_CPU0_P0_RX_DN<14>")
	)
	(arc
		(start 357.115618 -270.951706)
		(mid 357.113595 -270.940296)
		(end 357.111808 -270.928846)
		(width 0.1143)
		(layer "In15.Cu")
		(net "P5E_CPU0_P0_RX_DN<14>")
	)
	(arc
		(start 321.058286 -391.091928)
		(mid 321.107338 -390.845328)
		(end 321.247008 -390.636252)
		(width 0.14224)
		(layer "In15.Cu")
		(net "P5E_CPU0_P0_RX_DN<14>")
	)
	(arc
		(start 388.30377 -375.76125)
		(mid 389.037545 -375.615293)
		(end 389.659622 -375.199656)
		(width 0.14224)
		(layer "In15.Cu")
		(net "P5E_CPU0_P0_RX_DN<14>")
	)
	(arc
		(start 391.66419 -373.195088)
		(mid 392.123561 -372.888083)
		(end 392.665458 -372.780306)
		(width 0.14224)
		(layer "In15.Cu")
		(net "P5E_CPU0_P0_RX_DN<14>")
	)
	(arc
		(start 358.35971 -284.920436)
		(mid 358.361875 -284.918793)
		(end 358.364028 -284.917134)
		(width 0.1143)
		(layer "In15.Cu")
		(net "P5E_CPU0_P0_RX_DN<14>")
	)
	(arc
		(start 357.579422 -271.690846)
		(mid 357.577078 -271.668666)
		(end 357.575866 -271.646396)
		(width 0.1143)
		(layer "In15.Cu")
		(net "P5E_CPU0_P0_RX_DN<14>")
	)
	(arc
		(start 358.352598 -288.16427)
		(mid 358.463146 -288.021707)
		(end 358.515412 -287.849056)
		(width 0.1143)
		(layer "In15.Cu")
		(net "P5E_CPU0_P0_RX_DN<14>")
	)
	(arc
		(start 358.515666 -284.616144)
		(mid 358.474117 -284.444722)
		(end 358.358694 -284.311344)
		(width 0.1143)
		(layer "In15.Cu")
		(net "P5E_CPU0_P0_RX_DN<14>")
	)
	(arc
		(start 358.289098 -285.890716)
		(mid 358.045771 -285.42615)
		(end 358.289098 -284.961584)
		(width 0.1143)
		(layer "In15.Cu")
		(net "P5E_CPU0_P0_RX_DN<14>")
	)
	(arc
		(start 358.364028 -284.917134)
		(mid 358.469783 -284.783546)
		(end 358.515666 -284.619446)
		(width 0.1143)
		(layer "In15.Cu")
		(net "P5E_CPU0_P0_RX_DN<14>")
	)
	(arc
		(start 358.360218 -293.019734)
		(mid 358.471353 -292.892778)
		(end 358.515412 -292.72992)
		(width 0.1143)
		(layer "In15.Cu")
		(net "P5E_CPU0_P0_RX_DN<14>")
	)
	(arc
		(start 358.329992 -278.463502)
		(mid 358.516235 -278.15595)
		(end 358.359964 -277.832058)
		(width 0.1143)
		(layer "In15.Cu")
		(net "P5E_CPU0_P0_RX_DN<14>")
	)
	(arc
		(start 399.485358 -354.707952)
		(mid 399.231866 -353.433653)
		(end 398.509998 -352.353372)
		(width 0.14224)
		(layer "In15.Cu")
		(net "P5E_CPU0_P0_RX_DN<14>")
	)
	(arc
		(start 357.820976 -272.121884)
		(mid 357.659762 -271.929026)
		(end 357.579422 -271.690846)
		(width 0.1143)
		(layer "In15.Cu")
		(net "P5E_CPU0_P0_RX_DN<14>")
	)
	(arc
		(start 358.515412 -287.849056)
		(mid 358.514593 -287.83061)
		(end 358.512872 -287.812226)
		(width 0.1143)
		(layer "In15.Cu")
		(net "P5E_CPU0_P0_RX_DN<14>")
	)
	(arc
		(start 357.575866 -271.646396)
		(mid 357.532473 -271.480764)
		(end 357.41991 -271.351756)
		(width 0.1143)
		(layer "In15.Cu")
		(net "P5E_CPU0_P0_RX_DN<14>")
	)
	(arc
		(start 358.36098 -273.57959)
		(mid 358.474909 -273.446443)
		(end 358.51592 -273.27606)
		(width 0.1143)
		(layer "In15.Cu")
		(net "P5E_CPU0_P0_RX_DN<14>")
	)
	(arc
		(start 358.045766 -272.466054)
		(mid 358.004511 -272.295083)
		(end 357.88981 -272.161762)
		(width 0.1143)
		(layer "In15.Cu")
		(net "P5E_CPU0_P0_RX_DN<14>")
	)
	(arc
		(start 358.290622 -274.551648)
		(mid 358.28986 -274.551141)
		(end 358.289098 -274.550632)
		(width 0.1143)
		(layer "In15.Cu")
		(net "P5E_CPU0_P0_RX_DN<14>")
	)
	(arc
		(start 358.289098 -289.130486)
		(mid 358.045771 -288.66592)
		(end 358.289098 -288.201354)
		(width 0.1143)
		(layer "In15.Cu")
		(net "P5E_CPU0_P0_RX_DN<14>")
	)
	(arc
		(start 358.291638 -287.512252)
		(mid 358.110986 -287.309507)
		(end 358.045766 -287.045908)
		(width 0.1143)
		(layer "In15.Cu")
		(net "P5E_CPU0_P0_RX_DN<14>")
	)
	(arc
		(start 358.289098 -281.03068)
		(mid 358.045771 -280.566114)
		(end 358.289098 -280.101548)
		(width 0.1143)
		(layer "In15.Cu")
		(net "P5E_CPU0_P0_RX_DN<14>")
	)
	(arc
		(start 358.358694 -289.780726)
		(mid 358.515671 -289.475926)
		(end 358.358694 -289.171126)
		(width 0.1143)
		(layer "In15.Cu")
		(net "P5E_CPU0_P0_RX_DN<14>")
	)
	(arc
		(start 358.35971 -275.20011)
		(mid 358.471141 -275.073105)
		(end 358.515412 -274.910042)
		(width 0.1143)
		(layer "In15.Cu")
		(net "P5E_CPU0_P0_RX_DN<14>")
	)
	(arc
		(start 396.426182 -372.780306)
		(mid 396.474866 -372.770604)
		(end 396.516098 -372.742968)
		(width 0.14224)
		(layer "In15.Cu")
		(net "P5E_CPU0_P0_RX_DN<14>")
	)
	(arc
		(start 358.515412 -292.702742)
		(mid 358.476329 -292.541951)
		(end 358.367584 -292.417246)
		(width 0.1143)
		(layer "In15.Cu")
		(net "P5E_CPU0_P0_RX_DN<14>")
	)
	(arc
		(start 370.797328 -324.640448)
		(mid 370.694464 -324.524426)
		(end 370.60632 -324.396862)
		(width 0.14224)
		(layer "In15.Cu")
		(net "P5E_CPU0_P0_RX_DN<14>")
	)
	(arc
		(start 358.358694 -291.400738)
		(mid 358.515671 -291.095938)
		(end 358.358694 -290.791138)
		(width 0.1143)
		(layer "In15.Cu")
		(net "P5E_CPU0_P0_RX_DN<14>")
	)
	(arc
		(start 358.515666 -273.27352)
		(mid 358.474726 -273.104319)
		(end 358.360726 -272.972784)
		(width 0.1143)
		(layer "In15.Cu")
		(net "P5E_CPU0_P0_RX_DN<14>")
	)
	(arc
		(start 358.289098 -282.650692)
		(mid 358.045771 -282.186126)
		(end 358.289098 -281.72156)
		(width 0.1143)
		(layer "In15.Cu")
		(net "P5E_CPU0_P0_RX_DN<14>")
	)
	(arc
		(start 358.328214 -280.078434)
		(mid 358.513128 -279.756218)
		(end 358.328468 -279.433782)
		(width 0.1143)
		(layer "In15.Cu")
		(net "P5E_CPU0_P0_RX_DN<14>")
	)
	(arc
		(start 358.289098 -277.790656)
		(mid 358.045771 -277.32609)
		(end 358.289098 -276.861524)
		(width 0.1143)
		(layer "In15.Cu")
		(net "P5E_CPU0_P0_RX_DN<14>")
	)
	(arc
		(start 332.433168 -375.981722)
		(mid 332.62481 -375.84432)
		(end 332.85049 -375.775982)
		(width 0.14224)
		(layer "In15.Cu")
		(net "P5E_CPU0_P0_RX_DN<14>")
	)
	(segment
		(start 357.197914 -273.820128)
		(end 356.731062 -274.086066)
		(width 0.12954)
		(layer "F.Cu")
		(net "P5E_CPU0_P0_RX_DN<13>")
	)
	(segment
		(start 318.87033 -393.69238)
		(end 319.39103 -393.69238)
		(width 0.127)
		(layer "F.Cu")
		(net "P5E_CPU0_P0_RX_DN<13>")
	)
	(segment
		(start 379.370844 -373.71401)
		(end 366.6236 -373.71401)
		(width 0.14224)
		(layer "In15.Cu")
		(net "P5E_CPU0_P0_RX_DN<13>")
	)
	(segment
		(start 357.387144 -292.392862)
		(end 357.381556 -292.389814)
		(width 0.1143)
		(layer "In15.Cu")
		(net "P5E_CPU0_P0_RX_DN<13>")
	)
	(segment
		(start 357.391462 -293.036498)
		(end 357.394764 -293.03472)
		(width 0.1143)
		(layer "In15.Cu")
		(net "P5E_CPU0_P0_RX_DN<13>")
	)
	(segment
		(start 357.421688 -289.778948)
		(end 357.422196 -289.778694)
		(width 0.1143)
		(layer "In15.Cu")
		(net "P5E_CPU0_P0_RX_DN<13>")
	)
	(segment
		(start 357.38816 -276.838664)
		(end 357.41991 -276.820376)
		(width 0.1143)
		(layer "In15.Cu")
		(net "P5E_CPU0_P0_RX_DN<13>")
	)
	(segment
		(start 357.38816 -291.418518)
		(end 357.388922 -291.41801)
		(width 0.1143)
		(layer "In15.Cu")
		(net "P5E_CPU0_P0_RX_DN<13>")
	)
	(segment
		(start 357.41991 -282.69184)
		(end 357.38816 -282.673552)
		(width 0.1143)
		(layer "In15.Cu")
		(net "P5E_CPU0_P0_RX_DN<13>")
	)
	(segment
		(start 324.41134 -382.373124)
		(end 325.580248 -381.204216)
		(width 0.14224)
		(layer "In15.Cu")
		(net "P5E_CPU0_P0_RX_DN<13>")
	)
	(segment
		(start 357.388668 -281.05354)
		(end 357.387906 -281.053286)
		(width 0.1143)
		(layer "In15.Cu")
		(net "P5E_CPU0_P0_RX_DN<13>")
	)
	(segment
		(start 397.867378 -367.812066)
		(end 397.867378 -353.520756)
		(width 0.14224)
		(layer "In15.Cu")
		(net "P5E_CPU0_P0_RX_DN<13>")
	)
	(segment
		(start 357.41991 -276.211792)
		(end 357.38816 -276.193504)
		(width 0.1143)
		(layer "In15.Cu")
		(net "P5E_CPU0_P0_RX_DN<13>")
	)
	(segment
		(start 327.47712 -379.113288)
		(end 327.671176 -379.113288)
		(width 0.14224)
		(layer "In15.Cu")
		(net "P5E_CPU0_P0_RX_DN<13>")
	)
	(segment
		(start 357.349044 -291.441378)
		(end 357.38562 -291.420042)
		(width 0.1143)
		(layer "In15.Cu")
		(net "P5E_CPU0_P0_RX_DN<13>")
	)
	(segment
		(start 381.648462 -370.232178)
		(end 395.21384 -370.232178)
		(width 0.14224)
		(layer "In15.Cu")
		(net "P5E_CPU0_P0_RX_DN<13>")
	)
	(segment
		(start 357.41991 -293.020242)
		(end 357.439722 -293.006018)
		(width 0.1143)
		(layer "In15.Cu")
		(net "P5E_CPU0_P0_RX_DN<13>")
	)
	(segment
		(start 357.349044 -288.201354)
		(end 357.407972 -288.167064)
		(width 0.1143)
		(layer "In15.Cu")
		(net "P5E_CPU0_P0_RX_DN<13>")
	)
	(segment
		(start 357.388922 -293.038022)
		(end 357.391462 -293.036498)
		(width 0.1143)
		(layer "In15.Cu")
		(net "P5E_CPU0_P0_RX_DN<13>")
	)
	(segment
		(start 357.37419 -280.086816)
		(end 357.408734 -280.06675)
		(width 0.1143)
		(layer "In15.Cu")
		(net "P5E_CPU0_P0_RX_DN<13>")
	)
	(segment
		(start 357.375968 -281.046428)
		(end 357.373682 -281.045158)
		(width 0.1143)
		(layer "In15.Cu")
		(net "P5E_CPU0_P0_RX_DN<13>")
	)
	(segment
		(start 357.381556 -292.389814)
		(end 357.380286 -292.389052)
		(width 0.1143)
		(layer "In15.Cu")
		(net "P5E_CPU0_P0_RX_DN<13>")
	)
	(segment
		(start 357.349552 -293.99103)
		(end 357.32339 -293.972488)
		(width 0.1143)
		(layer "In15.Cu")
		(net "P5E_CPU0_P0_RX_DN<13>")
	)
	(segment
		(start 357.387906 -281.053286)
		(end 357.378762 -281.048206)
		(width 0.1143)
		(layer "In15.Cu")
		(net "P5E_CPU0_P0_RX_DN<13>")
	)
	(segment
		(start 357.378762 -281.048206)
		(end 357.375968 -281.046428)
		(width 0.1143)
		(layer "In15.Cu")
		(net "P5E_CPU0_P0_RX_DN<13>")
	)
	(segment
		(start 357.38562 -291.420042)
		(end 357.387144 -291.419026)
		(width 0.1143)
		(layer "In15.Cu")
		(net "P5E_CPU0_P0_RX_DN<13>")
	)
	(segment
		(start 357.059992 -295.911016)
		(end 357.059992 -295.882568)
		(width 0.1143)
		(layer "In15.Cu")
		(net "P5E_CPU0_P0_RX_DN<13>")
	)
	(segment
		(start 357.409496 -279.445974)
		(end 357.349806 -279.411176)
		(width 0.1143)
		(layer "In15.Cu")
		(net "P5E_CPU0_P0_RX_DN<13>")
	)
	(segment
		(start 325.882254 -380.708408)
		(end 326.076056 -380.708408)
		(width 0.14224)
		(layer "In15.Cu")
		(net "P5E_CPU0_P0_RX_DN<13>")
	)
	(segment
		(start 357.408734 -275.206714)
		(end 357.409496 -275.206206)
		(width 0.1143)
		(layer "In15.Cu")
		(net "P5E_CPU0_P0_RX_DN<13>")
	)
	(segment
		(start 357.38816 -283.318712)
		(end 357.41991 -283.300424)
		(width 0.1143)
		(layer "In15.Cu")
		(net "P5E_CPU0_P0_RX_DN<13>")
	)
	(segment
		(start 364.297214 -315.84265)
		(end 357.203502 -304.11293)
		(width 0.14224)
		(layer "In15.Cu")
		(net "P5E_CPU0_P0_RX_DN<13>")
	)
	(segment
		(start 357.41991 -284.311852)
		(end 357.38816 -284.293564)
		(width 0.1143)
		(layer "In15.Cu")
		(net "P5E_CPU0_P0_RX_DN<13>")
	)
	(segment
		(start 357.394764 -293.03472)
		(end 357.395526 -293.034212)
		(width 0.1143)
		(layer "In15.Cu")
		(net "P5E_CPU0_P0_RX_DN<13>")
	)
	(segment
		(start 357.41991 -277.831804)
		(end 357.38816 -277.813516)
		(width 0.1143)
		(layer "In15.Cu")
		(net "P5E_CPU0_P0_RX_DN<13>")
	)
	(segment
		(start 357.456486 -289.20059)
		(end 357.454962 -289.19932)
		(width 0.1143)
		(layer "In15.Cu")
		(net "P5E_CPU0_P0_RX_DN<13>")
	)
	(segment
		(start 357.422196 -289.778694)
		(end 357.422958 -289.778186)
		(width 0.1143)
		(layer "In15.Cu")
		(net "P5E_CPU0_P0_RX_DN<13>")
	)
	(segment
		(start 357.39959 -293.031926)
		(end 357.41991 -293.020242)
		(width 0.1143)
		(layer "In15.Cu")
		(net "P5E_CPU0_P0_RX_DN<13>")
	)
	(segment
		(start 357.408734 -280.06675)
		(end 357.409496 -280.066242)
		(width 0.1143)
		(layer "In15.Cu")
		(net "P5E_CPU0_P0_RX_DN<13>")
	)
	(segment
		(start 357.380286 -292.389052)
		(end 357.379524 -292.388544)
		(width 0.1143)
		(layer "In15.Cu")
		(net "P5E_CPU0_P0_RX_DN<13>")
	)
	(segment
		(start 357.41991 -289.780218)
		(end 357.420418 -289.77971)
		(width 0.1143)
		(layer "In15.Cu")
		(net "P5E_CPU0_P0_RX_DN<13>")
	)
	(segment
		(start 357.375206 -292.386004)
		(end 357.37292 -292.38448)
		(width 0.1143)
		(layer "In15.Cu")
		(net "P5E_CPU0_P0_RX_DN<13>")
	)
	(segment
		(start 319.988184 -389.979916)
		(end 324.283832 -385.684268)
		(width 0.14224)
		(layer "In15.Cu")
		(net "P5E_CPU0_P0_RX_DN<13>")
	)
	(segment
		(start 357.38816 -284.938724)
		(end 357.41991 -284.920436)
		(width 0.1143)
		(layer "In15.Cu")
		(net "P5E_CPU0_P0_RX_DN<13>")
	)
	(segment
		(start 327.175114 -379.415294)
		(end 327.47712 -379.113288)
		(width 0.14224)
		(layer "In15.Cu")
		(net "P5E_CPU0_P0_RX_DN<13>")
	)
	(segment
		(start 379.58649 -372.29415)
		(end 381.648462 -370.232178)
		(width 0.14224)
		(layer "In15.Cu")
		(net "P5E_CPU0_P0_RX_DN<13>")
	)
	(segment
		(start 357.387144 -290.77285)
		(end 357.349044 -290.750498)
		(width 0.1143)
		(layer "In15.Cu")
		(net "P5E_CPU0_P0_RX_DN<13>")
	)
	(segment
		(start 357.41991 -285.931864)
		(end 357.38816 -285.913576)
		(width 0.1143)
		(layer "In15.Cu")
		(net "P5E_CPU0_P0_RX_DN<13>")
	)
	(segment
		(start 357.38816 -293.03853)
		(end 357.388922 -293.038022)
		(width 0.1143)
		(layer "In15.Cu")
		(net "P5E_CPU0_P0_RX_DN<13>")
	)
	(segment
		(start 357.059992 -303.598326)
		(end 357.059992 -295.911016)
		(width 0.14224)
		(layer "In15.Cu")
		(net "P5E_CPU0_P0_RX_DN<13>")
	)
	(segment
		(start 357.387144 -291.419026)
		(end 357.38816 -291.418518)
		(width 0.1143)
		(layer "In15.Cu")
		(net "P5E_CPU0_P0_RX_DN<13>")
	)
	(segment
		(start 357.388922 -289.797998)
		(end 357.41991 -289.780218)
		(width 0.1143)
		(layer "In15.Cu")
		(net "P5E_CPU0_P0_RX_DN<13>")
	)
	(segment
		(start 326.67956 -379.910848)
		(end 326.873616 -379.910848)
		(width 0.14224)
		(layer "In15.Cu")
		(net "P5E_CPU0_P0_RX_DN<13>")
	)
	(segment
		(start 357.059992 -295.882568)
		(end 357.105712 -295.836848)
		(width 0.1143)
		(layer "In15.Cu")
		(net "P5E_CPU0_P0_RX_DN<13>")
	)
	(segment
		(start 357.395526 -293.034212)
		(end 357.398066 -293.032688)
		(width 0.1143)
		(layer "In15.Cu")
		(net "P5E_CPU0_P0_RX_DN<13>")
	)
	(segment
		(start 357.322882 -293.079932)
		(end 357.349298 -293.060882)
		(width 0.1143)
		(layer "In15.Cu")
		(net "P5E_CPU0_P0_RX_DN<13>")
	)
	(segment
		(start 357.410004 -279.445974)
		(end 357.409496 -279.445974)
		(width 0.1143)
		(layer "In15.Cu")
		(net "P5E_CPU0_P0_RX_DN<13>")
	)
	(segment
		(start 357.349044 -289.821366)
		(end 357.38562 -289.80003)
		(width 0.1143)
		(layer "In15.Cu")
		(net "P5E_CPU0_P0_RX_DN<13>")
	)
	(segment
		(start 319.866518 -393.545822)
		(end 319.549526 -393.22883)
		(width 0.14224)
		(layer "In15.Cu")
		(net "P5E_CPU0_P0_RX_DN<13>")
	)
	(segment
		(start 357.575866 -287.856422)
		(end 357.575866 -287.854136)
		(width 0.1143)
		(layer "In15.Cu")
		(net "P5E_CPU0_P0_RX_DN<13>")
	)
	(segment
		(start 366.451388 -319.870836)
		(end 364.30204 -315.85154)
		(width 0.14224)
		(layer "In15.Cu")
		(net "P5E_CPU0_P0_RX_DN<13>")
	)
	(segment
		(start 327.671176 -379.113288)
		(end 331.917294 -374.86717)
		(width 0.14224)
		(layer "In15.Cu")
		(net "P5E_CPU0_P0_RX_DN<13>")
	)
	(segment
		(start 326.377554 -380.40691)
		(end 326.377554 -380.212854)
		(width 0.14224)
		(layer "In15.Cu")
		(net "P5E_CPU0_P0_RX_DN<13>")
	)
	(segment
		(start 326.873616 -379.910848)
		(end 327.175114 -379.60935)
		(width 0.14224)
		(layer "In15.Cu")
		(net "P5E_CPU0_P0_RX_DN<13>")
	)
	(segment
		(start 397.107156 -369.447826)
		(end 397.248126 -369.306856)
		(width 0.14224)
		(layer "In15.Cu")
		(net "P5E_CPU0_P0_RX_DN<13>")
	)
	(segment
		(start 357.398066 -293.032688)
		(end 357.39959 -293.031926)
		(width 0.1143)
		(layer "In15.Cu")
		(net "P5E_CPU0_P0_RX_DN<13>")
	)
	(segment
		(start 379.513084 -374.42775)
		(end 379.513084 -373.85625)
		(width 0.14224)
		(layer "In15.Cu")
		(net "P5E_CPU0_P0_RX_DN<13>")
	)
	(segment
		(start 357.349044 -284.961584)
		(end 357.38816 -284.938724)
		(width 0.1143)
		(layer "In15.Cu")
		(net "P5E_CPU0_P0_RX_DN<13>")
	)
	(segment
		(start 357.41991 -290.791646)
		(end 357.388922 -290.773866)
		(width 0.1143)
		(layer "In15.Cu")
		(net "P5E_CPU0_P0_RX_DN<13>")
	)
	(segment
		(start 324.41134 -385.376674)
		(end 324.41134 -382.373124)
		(width 0.14224)
		(layer "In15.Cu")
		(net "P5E_CPU0_P0_RX_DN<13>")
	)
	(segment
		(start 357.575612 -287.856168)
		(end 357.575866 -287.856422)
		(width 0.1143)
		(layer "In15.Cu")
		(net "P5E_CPU0_P0_RX_DN<13>")
	)
	(segment
		(start 357.349044 -275.241512)
		(end 357.408734 -275.206714)
		(width 0.1143)
		(layer "In15.Cu")
		(net "P5E_CPU0_P0_RX_DN<13>")
	)
	(segment
		(start 357.420418 -289.77971)
		(end 357.421688 -289.778948)
		(width 0.1143)
		(layer "In15.Cu")
		(net "P5E_CPU0_P0_RX_DN<13>")
	)
	(segment
		(start 357.445818 -292.433502)
		(end 357.389684 -292.394386)
		(width 0.1143)
		(layer "In15.Cu")
		(net "P5E_CPU0_P0_RX_DN<13>")
	)
	(segment
		(start 319.554352 -392.616944)
		(end 319.811146 -392.360404)
		(width 0.14224)
		(layer "In15.Cu")
		(net "P5E_CPU0_P0_RX_DN<13>")
	)
	(segment
		(start 319.744852 -393.786868)
		(end 319.866518 -393.716764)
		(width 0.14224)
		(layer "In15.Cu")
		(net "P5E_CPU0_P0_RX_DN<13>")
	)
	(segment
		(start 357.105712 -295.836848)
		(end 357.105712 -295.145968)
		(width 0.1143)
		(layer "In15.Cu")
		(net "P5E_CPU0_P0_RX_DN<13>")
	)
	(segment
		(start 357.349298 -293.060882)
		(end 357.38816 -293.03853)
		(width 0.1143)
		(layer "In15.Cu")
		(net "P5E_CPU0_P0_RX_DN<13>")
	)
	(segment
		(start 325.580248 -381.010414)
		(end 325.882254 -380.708408)
		(width 0.14224)
		(layer "In15.Cu")
		(net "P5E_CPU0_P0_RX_DN<13>")
	)
	(segment
		(start 357.349044 -278.481536)
		(end 357.38816 -278.458676)
		(width 0.1143)
		(layer "In15.Cu")
		(net "P5E_CPU0_P0_RX_DN<13>")
	)
	(segment
		(start 357.38816 -285.913576)
		(end 357.349044 -285.890716)
		(width 0.1143)
		(layer "In15.Cu")
		(net "P5E_CPU0_P0_RX_DN<13>")
	)
	(segment
		(start 357.474266 -287.606232)
		(end 357.348282 -287.51657)
		(width 0.1143)
		(layer "In15.Cu")
		(net "P5E_CPU0_P0_RX_DN<13>")
	)
	(segment
		(start 357.407972 -288.167064)
		(end 357.422196 -288.158428)
		(width 0.1143)
		(layer "In15.Cu")
		(net "P5E_CPU0_P0_RX_DN<13>")
	)
	(segment
		(start 366.6236 -373.71401)
		(end 366.31626 -373.40667)
		(width 0.14224)
		(layer "In15.Cu")
		(net "P5E_CPU0_P0_RX_DN<13>")
	)
	(segment
		(start 357.38816 -282.673552)
		(end 357.349044 -282.650692)
		(width 0.1143)
		(layer "In15.Cu")
		(net "P5E_CPU0_P0_RX_DN<13>")
	)
	(segment
		(start 357.388922 -290.773866)
		(end 357.38816 -290.773358)
		(width 0.1143)
		(layer "In15.Cu")
		(net "P5E_CPU0_P0_RX_DN<13>")
	)
	(segment
		(start 366.31626 -373.40667)
		(end 366.31626 -372.60149)
		(width 0.14224)
		(layer "In15.Cu")
		(net "P5E_CPU0_P0_RX_DN<13>")
	)
	(segment
		(start 325.580248 -381.204216)
		(end 325.580248 -381.010414)
		(width 0.14224)
		(layer "In15.Cu")
		(net "P5E_CPU0_P0_RX_DN<13>")
	)
	(segment
		(start 379.370844 -374.56999)
		(end 379.513084 -374.42775)
		(width 0.14224)
		(layer "In15.Cu")
		(net "P5E_CPU0_P0_RX_DN<13>")
	)
	(segment
		(start 326.377554 -380.212854)
		(end 326.67956 -379.910848)
		(width 0.14224)
		(layer "In15.Cu")
		(net "P5E_CPU0_P0_RX_DN<13>")
	)
	(segment
		(start 357.38816 -290.773358)
		(end 357.387144 -290.77285)
		(width 0.1143)
		(layer "In15.Cu")
		(net "P5E_CPU0_P0_RX_DN<13>")
	)
	(segment
		(start 326.076056 -380.708408)
		(end 326.377554 -380.40691)
		(width 0.14224)
		(layer "In15.Cu")
		(net "P5E_CPU0_P0_RX_DN<13>")
	)
	(segment
		(start 319.85839 -392.246358)
		(end 319.85839 -390.293352)
		(width 0.14224)
		(layer "In15.Cu")
		(net "P5E_CPU0_P0_RX_DN<13>")
	)
	(segment
		(start 357.349044 -276.861524)
		(end 357.38816 -276.838664)
		(width 0.1143)
		(layer "In15.Cu")
		(net "P5E_CPU0_P0_RX_DN<13>")
	)
	(segment
		(start 357.378508 -292.388036)
		(end 357.376222 -292.386512)
		(width 0.1143)
		(layer "In15.Cu")
		(net "P5E_CPU0_P0_RX_DN<13>")
	)
	(segment
		(start 397.647414 -352.999548)
		(end 369.089686 -324.441058)
		(width 0.14224)
		(layer "In15.Cu")
		(net "P5E_CPU0_P0_RX_DN<13>")
	)
	(segment
		(start 332.634844 -374.56999)
		(end 379.370844 -374.56999)
		(width 0.14224)
		(layer "In15.Cu")
		(net "P5E_CPU0_P0_RX_DN<13>")
	)
	(segment
		(start 319.866518 -393.716764)
		(end 319.866518 -393.545822)
		(width 0.14224)
		(layer "In15.Cu")
		(net "P5E_CPU0_P0_RX_DN<13>")
	)
	(segment
		(start 357.422958 -289.778186)
		(end 357.4415 -289.763962)
		(width 0.1143)
		(layer "In15.Cu")
		(net "P5E_CPU0_P0_RX_DN<13>")
	)
	(segment
		(start 357.356664 -289.135058)
		(end 357.355902 -289.13455)
		(width 0.1143)
		(layer "In15.Cu")
		(net "P5E_CPU0_P0_RX_DN<13>")
	)
	(segment
		(start 357.111808 -274.16887)
		(end 357.029004 -274.086066)
		(width 0.1143)
		(layer "In15.Cu")
		(net "P5E_CPU0_P0_RX_DN<13>")
	)
	(segment
		(start 357.387144 -289.799014)
		(end 357.38816 -289.798506)
		(width 0.1143)
		(layer "In15.Cu")
		(net "P5E_CPU0_P0_RX_DN<13>")
	)
	(segment
		(start 357.409496 -275.206206)
		(end 357.40975 -275.206206)
		(width 0.1143)
		(layer "In15.Cu")
		(net "P5E_CPU0_P0_RX_DN<13>")
	)
	(segment
		(start 357.38816 -277.813516)
		(end 357.349044 -277.790656)
		(width 0.1143)
		(layer "In15.Cu")
		(net "P5E_CPU0_P0_RX_DN<13>")
	)
	(segment
		(start 357.38816 -276.193504)
		(end 357.349044 -276.170644)
		(width 0.1143)
		(layer "In15.Cu")
		(net "P5E_CPU0_P0_RX_DN<13>")
	)
	(segment
		(start 357.358442 -289.136074)
		(end 357.356664 -289.135058)
		(width 0.1143)
		(layer "In15.Cu")
		(net "P5E_CPU0_P0_RX_DN<13>")
	)
	(segment
		(start 366.31626 -372.60149)
		(end 366.6236 -372.29415)
		(width 0.14224)
		(layer "In15.Cu")
		(net "P5E_CPU0_P0_RX_DN<13>")
	)
	(segment
		(start 357.389684 -292.394386)
		(end 357.38816 -292.39337)
		(width 0.1143)
		(layer "In15.Cu")
		(net "P5E_CPU0_P0_RX_DN<13>")
	)
	(segment
		(start 319.549526 -393.22883)
		(end 319.554352 -392.616944)
		(width 0.14224)
		(layer "In15.Cu")
		(net "P5E_CPU0_P0_RX_DN<13>")
	)
	(segment
		(start 364.30204 -315.85154)
		(end 364.301278 -315.850016)
		(width 0.14224)
		(layer "In15.Cu")
		(net "P5E_CPU0_P0_RX_DN<13>")
	)
	(segment
		(start 366.6236 -372.29415)
		(end 379.58649 -372.29415)
		(width 0.14224)
		(layer "In15.Cu")
		(net "P5E_CPU0_P0_RX_DN<13>")
	)
	(segment
		(start 327.175114 -379.60935)
		(end 327.175114 -379.415294)
		(width 0.14224)
		(layer "In15.Cu")
		(net "P5E_CPU0_P0_RX_DN<13>")
	)
	(segment
		(start 357.37292 -292.38448)
		(end 357.349044 -292.37051)
		(width 0.1143)
		(layer "In15.Cu")
		(net "P5E_CPU0_P0_RX_DN<13>")
	)
	(segment
		(start 357.349044 -283.341572)
		(end 357.38816 -283.318712)
		(width 0.1143)
		(layer "In15.Cu")
		(net "P5E_CPU0_P0_RX_DN<13>")
	)
	(segment
		(start 357.370126 -289.142932)
		(end 357.359204 -289.136582)
		(width 0.1143)
		(layer "In15.Cu")
		(net "P5E_CPU0_P0_RX_DN<13>")
	)
	(segment
		(start 357.38816 -289.798506)
		(end 357.388922 -289.797998)
		(width 0.1143)
		(layer "In15.Cu")
		(net "P5E_CPU0_P0_RX_DN<13>")
	)
	(segment
		(start 357.409496 -274.585938)
		(end 357.349806 -274.55114)
		(width 0.1143)
		(layer "In15.Cu")
		(net "P5E_CPU0_P0_RX_DN<13>")
	)
	(segment
		(start 357.349806 -294.680894)
		(end 357.375714 -294.665654)
		(width 0.1143)
		(layer "In15.Cu")
		(net "P5E_CPU0_P0_RX_DN<13>")
	)
	(segment
		(start 368.757962 -324.005448)
		(end 367.779554 -322.28155)
		(width 0.14224)
		(layer "In15.Cu")
		(net "P5E_CPU0_P0_RX_DN<13>")
	)
	(segment
		(start 357.418894 -286.540956)
		(end 357.421688 -286.538924)
		(width 0.1143)
		(layer "In15.Cu")
		(net "P5E_CPU0_P0_RX_DN<13>")
	)
	(segment
		(start 357.355902 -289.13455)
		(end 357.349044 -289.130486)
		(width 0.1143)
		(layer "In15.Cu")
		(net "P5E_CPU0_P0_RX_DN<13>")
	)
	(segment
		(start 379.513084 -373.85625)
		(end 379.370844 -373.71401)
		(width 0.14224)
		(layer "In15.Cu")
		(net "P5E_CPU0_P0_RX_DN<13>")
	)
	(segment
		(start 357.349044 -286.581342)
		(end 357.418894 -286.540956)
		(width 0.1143)
		(layer "In15.Cu")
		(net "P5E_CPU0_P0_RX_DN<13>")
	)
	(segment
		(start 357.454962 -289.19932)
		(end 357.373428 -289.144964)
		(width 0.1143)
		(layer "In15.Cu")
		(net "P5E_CPU0_P0_RX_DN<13>")
	)
	(segment
		(start 357.410004 -274.585938)
		(end 357.409496 -274.585938)
		(width 0.1143)
		(layer "In15.Cu")
		(net "P5E_CPU0_P0_RX_DN<13>")
	)
	(segment
		(start 357.38816 -278.458676)
		(end 357.41991 -278.440388)
		(width 0.1143)
		(layer "In15.Cu")
		(net "P5E_CPU0_P0_RX_DN<13>")
	)
	(segment
		(start 357.373428 -289.144964)
		(end 357.370126 -289.142932)
		(width 0.1143)
		(layer "In15.Cu")
		(net "P5E_CPU0_P0_RX_DN<13>")
	)
	(segment
		(start 357.38816 -292.39337)
		(end 357.387144 -292.392862)
		(width 0.1143)
		(layer "In15.Cu")
		(net "P5E_CPU0_P0_RX_DN<13>")
	)
	(segment
		(start 357.388922 -291.41801)
		(end 357.41991 -291.40023)
		(width 0.1143)
		(layer "In15.Cu")
		(net "P5E_CPU0_P0_RX_DN<13>")
	)
	(segment
		(start 357.029004 -274.086066)
		(end 356.731062 -274.086066)
		(width 0.1143)
		(layer "In15.Cu")
		(net "P5E_CPU0_P0_RX_DN<13>")
	)
	(segment
		(start 319.39103 -393.69238)
		(end 319.744344 -393.787376)
		(width 0.14224)
		(layer "In15.Cu")
		(net "P5E_CPU0_P0_RX_DN<13>")
	)
	(segment
		(start 357.373936 -294.005)
		(end 357.349552 -293.99103)
		(width 0.1143)
		(layer "In15.Cu")
		(net "P5E_CPU0_P0_RX_DN<13>")
	)
	(segment
		(start 357.38562 -289.80003)
		(end 357.387144 -289.799014)
		(width 0.1143)
		(layer "In15.Cu")
		(net "P5E_CPU0_P0_RX_DN<13>")
	)
	(segment
		(start 357.359204 -289.136582)
		(end 357.358442 -289.136074)
		(width 0.1143)
		(layer "In15.Cu")
		(net "P5E_CPU0_P0_RX_DN<13>")
	)
	(segment
		(start 357.38816 -284.293564)
		(end 357.349044 -284.270704)
		(width 0.1143)
		(layer "In15.Cu")
		(net "P5E_CPU0_P0_RX_DN<13>")
	)
	(segment
		(start 357.349044 -281.72156)
		(end 357.388668 -281.698446)
		(width 0.1143)
		(layer "In15.Cu")
		(net "P5E_CPU0_P0_RX_DN<13>")
	)
	(segment
		(start 357.379524 -292.388544)
		(end 357.378508 -292.388036)
		(width 0.1143)
		(layer "In15.Cu")
		(net "P5E_CPU0_P0_RX_DN<13>")
	)
	(segment
		(start 357.376222 -292.386512)
		(end 357.375206 -292.386004)
		(width 0.1143)
		(layer "In15.Cu")
		(net "P5E_CPU0_P0_RX_DN<13>")
	)
	(segment
		(start 319.744344 -393.787376)
		(end 319.744852 -393.786868)
		(width 0.14224)
		(layer "In15.Cu")
		(net "P5E_CPU0_P0_RX_DN<13>")
	)
	(segment
		(start 357.409496 -280.066242)
		(end 357.40975 -280.066242)
		(width 0.1143)
		(layer "In15.Cu")
		(net "P5E_CPU0_P0_RX_DN<13>")
	)
	(arc
		(start 319.85839 -390.293352)
		(mid 319.892129 -390.123735)
		(end 319.988184 -389.979916)
		(width 0.14224)
		(layer "In15.Cu")
		(net "P5E_CPU0_P0_RX_DN<13>")
	)
	(arc
		(start 357.349044 -289.130486)
		(mid 357.105717 -288.66592)
		(end 357.349044 -288.201354)
		(width 0.1143)
		(layer "In15.Cu")
		(net "P5E_CPU0_P0_RX_DN<13>")
	)
	(arc
		(start 397.248126 -369.306856)
		(mid 397.706427 -368.621055)
		(end 397.867378 -367.812066)
		(width 0.14224)
		(layer "In15.Cu")
		(net "P5E_CPU0_P0_RX_DN<13>")
	)
	(arc
		(start 367.779554 -322.28155)
		(mid 367.107893 -321.080368)
		(end 366.451388 -319.870836)
		(width 0.14224)
		(layer "In15.Cu")
		(net "P5E_CPU0_P0_RX_DN<13>")
	)
	(arc
		(start 357.336852 -291.450268)
		(mid 357.337613 -291.449632)
		(end 357.338376 -291.448998)
		(width 0.1143)
		(layer "In15.Cu")
		(net "P5E_CPU0_P0_RX_DN<13>")
	)
	(arc
		(start 357.339392 -292.363398)
		(mid 357.338502 -292.362764)
		(end 357.337614 -292.362128)
		(width 0.1143)
		(layer "In15.Cu")
		(net "P5E_CPU0_P0_RX_DN<13>")
	)
	(arc
		(start 357.40975 -275.206206)
		(mid 357.588292 -274.896182)
		(end 357.410004 -274.585938)
		(width 0.1143)
		(layer "In15.Cu")
		(net "P5E_CPU0_P0_RX_DN<13>")
	)
	(arc
		(start 357.373682 -281.045158)
		(mid 357.098764 -280.565831)
		(end 357.37419 -280.086816)
		(width 0.1143)
		(layer "In15.Cu")
		(net "P5E_CPU0_P0_RX_DN<13>")
	)
	(arc
		(start 357.375714 -294.665654)
		(mid 357.564973 -294.334875)
		(end 357.373936 -294.005)
		(width 0.1143)
		(layer "In15.Cu")
		(net "P5E_CPU0_P0_RX_DN<13>")
	)
	(arc
		(start 357.337614 -292.362128)
		(mid 357.337233 -292.361874)
		(end 357.336852 -292.36162)
		(width 0.1143)
		(layer "In15.Cu")
		(net "P5E_CPU0_P0_RX_DN<13>")
	)
	(arc
		(start 357.349044 -277.790656)
		(mid 357.105717 -277.32609)
		(end 357.349044 -276.861524)
		(width 0.1143)
		(layer "In15.Cu")
		(net "P5E_CPU0_P0_RX_DN<13>")
	)
	(arc
		(start 357.349044 -279.410668)
		(mid 357.105717 -278.946102)
		(end 357.349044 -278.481536)
		(width 0.1143)
		(layer "In15.Cu")
		(net "P5E_CPU0_P0_RX_DN<13>")
	)
	(arc
		(start 397.867378 -353.520756)
		(mid 397.863123 -353.445111)
		(end 397.850614 -353.370388)
		(width 0.14224)
		(layer "In15.Cu")
		(net "P5E_CPU0_P0_RX_DN<13>")
	)
	(arc
		(start 357.421688 -286.538924)
		(mid 357.535095 -286.406035)
		(end 357.575866 -286.236156)
		(width 0.1143)
		(layer "In15.Cu")
		(net "P5E_CPU0_P0_RX_DN<13>")
	)
	(arc
		(start 357.349044 -276.170644)
		(mid 357.105717 -275.706078)
		(end 357.349044 -275.241512)
		(width 0.1143)
		(layer "In15.Cu")
		(net "P5E_CPU0_P0_RX_DN<13>")
	)
	(arc
		(start 319.811146 -392.360404)
		(mid 319.846162 -392.308094)
		(end 319.85839 -392.246358)
		(width 0.14224)
		(layer "In15.Cu")
		(net "P5E_CPU0_P0_RX_DN<13>")
	)
	(arc
		(start 357.40975 -280.066242)
		(mid 357.588292 -279.756218)
		(end 357.410004 -279.445974)
		(width 0.1143)
		(layer "In15.Cu")
		(net "P5E_CPU0_P0_RX_DN<13>")
	)
	(arc
		(start 357.575866 -286.236156)
		(mid 357.531795 -286.06662)
		(end 357.41991 -285.931864)
		(width 0.1143)
		(layer "In15.Cu")
		(net "P5E_CPU0_P0_RX_DN<13>")
	)
	(arc
		(start 357.422196 -288.158428)
		(mid 357.535082 -288.025657)
		(end 357.575612 -287.856168)
		(width 0.1143)
		(layer "In15.Cu")
		(net "P5E_CPU0_P0_RX_DN<13>")
	)
	(arc
		(start 357.4415 -289.763962)
		(mid 357.584733 -289.485932)
		(end 357.456486 -289.20059)
		(width 0.1143)
		(layer "In15.Cu")
		(net "P5E_CPU0_P0_RX_DN<13>")
	)
	(arc
		(start 357.349044 -274.550632)
		(mid 357.197057 -274.394124)
		(end 357.115618 -274.19173)
		(width 0.1143)
		(layer "In15.Cu")
		(net "P5E_CPU0_P0_RX_DN<13>")
	)
	(arc
		(start 357.41991 -278.440388)
		(mid 357.570295 -278.136096)
		(end 357.41991 -277.831804)
		(width 0.1143)
		(layer "In15.Cu")
		(net "P5E_CPU0_P0_RX_DN<13>")
	)
	(arc
		(start 357.349806 -274.55114)
		(mid 357.349425 -274.550886)
		(end 357.349044 -274.550632)
		(width 0.1143)
		(layer "In15.Cu")
		(net "P5E_CPU0_P0_RX_DN<13>")
	)
	(arc
		(start 357.575866 -287.854136)
		(mid 357.549485 -287.720174)
		(end 357.474266 -287.606232)
		(width 0.1143)
		(layer "In15.Cu")
		(net "P5E_CPU0_P0_RX_DN<13>")
	)
	(arc
		(start 364.301278 -315.850016)
		(mid 364.299289 -315.846309)
		(end 364.297214 -315.84265)
		(width 0.14224)
		(layer "In15.Cu")
		(net "P5E_CPU0_P0_RX_DN<13>")
	)
	(arc
		(start 357.349044 -284.270704)
		(mid 357.105717 -283.806138)
		(end 357.349044 -283.341572)
		(width 0.1143)
		(layer "In15.Cu")
		(net "P5E_CPU0_P0_RX_DN<13>")
	)
	(arc
		(start 395.21384 -370.232178)
		(mid 396.238511 -370.028323)
		(end 397.107156 -369.447826)
		(width 0.14224)
		(layer "In15.Cu")
		(net "P5E_CPU0_P0_RX_DN<13>")
	)
	(arc
		(start 357.33609 -291.450776)
		(mid 357.336471 -291.450522)
		(end 357.336852 -291.450268)
		(width 0.1143)
		(layer "In15.Cu")
		(net "P5E_CPU0_P0_RX_DN<13>")
	)
	(arc
		(start 357.41991 -276.820376)
		(mid 357.570295 -276.516084)
		(end 357.41991 -276.211792)
		(width 0.1143)
		(layer "In15.Cu")
		(net "P5E_CPU0_P0_RX_DN<13>")
	)
	(arc
		(start 357.349044 -282.650692)
		(mid 357.105717 -282.186126)
		(end 357.349044 -281.72156)
		(width 0.1143)
		(layer "In15.Cu")
		(net "P5E_CPU0_P0_RX_DN<13>")
	)
	(arc
		(start 331.917294 -374.86717)
		(mid 332.246523 -374.647249)
		(end 332.634844 -374.56999)
		(width 0.14224)
		(layer "In15.Cu")
		(net "P5E_CPU0_P0_RX_DN<13>")
	)
	(arc
		(start 357.349044 -285.890716)
		(mid 357.105717 -285.42615)
		(end 357.349044 -284.961584)
		(width 0.1143)
		(layer "In15.Cu")
		(net "P5E_CPU0_P0_RX_DN<13>")
	)
	(arc
		(start 357.105712 -287.045908)
		(mid 357.170227 -286.783689)
		(end 357.349044 -286.581342)
		(width 0.1143)
		(layer "In15.Cu")
		(net "P5E_CPU0_P0_RX_DN<13>")
	)
	(arc
		(start 357.349806 -279.411176)
		(mid 357.349425 -279.410922)
		(end 357.349044 -279.410668)
		(width 0.1143)
		(layer "In15.Cu")
		(net "P5E_CPU0_P0_RX_DN<13>")
	)
	(arc
		(start 357.115618 -274.19173)
		(mid 357.113595 -274.18032)
		(end 357.111808 -274.16887)
		(width 0.1143)
		(layer "In15.Cu")
		(net "P5E_CPU0_P0_RX_DN<13>")
	)
	(arc
		(start 357.388668 -281.698446)
		(mid 357.574086 -281.376056)
		(end 357.388668 -281.05354)
		(width 0.1143)
		(layer "In15.Cu")
		(net "P5E_CPU0_P0_RX_DN<13>")
	)
	(arc
		(start 357.348282 -287.51657)
		(mid 357.169982 -287.310635)
		(end 357.105712 -287.045908)
		(width 0.1143)
		(layer "In15.Cu")
		(net "P5E_CPU0_P0_RX_DN<13>")
	)
	(arc
		(start 357.349044 -290.750498)
		(mid 357.105717 -290.285932)
		(end 357.349044 -289.821366)
		(width 0.1143)
		(layer "In15.Cu")
		(net "P5E_CPU0_P0_RX_DN<13>")
	)
	(arc
		(start 357.340408 -292.36416)
		(mid 357.3399 -292.363779)
		(end 357.339392 -292.363398)
		(width 0.1143)
		(layer "In15.Cu")
		(net "P5E_CPU0_P0_RX_DN<13>")
	)
	(arc
		(start 357.41991 -284.920436)
		(mid 357.570295 -284.616144)
		(end 357.41991 -284.311852)
		(width 0.1143)
		(layer "In15.Cu")
		(net "P5E_CPU0_P0_RX_DN<13>")
	)
	(arc
		(start 357.336852 -292.36162)
		(mid 357.111781 -291.906401)
		(end 357.33609 -291.450776)
		(width 0.1143)
		(layer "In15.Cu")
		(net "P5E_CPU0_P0_RX_DN<13>")
	)
	(arc
		(start 357.41991 -283.300424)
		(mid 357.571499 -282.996132)
		(end 357.41991 -282.69184)
		(width 0.1143)
		(layer "In15.Cu")
		(net "P5E_CPU0_P0_RX_DN<13>")
	)
	(arc
		(start 357.338376 -291.448998)
		(mid 357.339138 -291.448489)
		(end 357.3399 -291.447982)
		(width 0.1143)
		(layer "In15.Cu")
		(net "P5E_CPU0_P0_RX_DN<13>")
	)
	(arc
		(start 357.526336 -292.514782)
		(mid 357.48978 -292.470472)
		(end 357.445818 -292.433502)
		(width 0.1143)
		(layer "In15.Cu")
		(net "P5E_CPU0_P0_RX_DN<13>")
	)
	(arc
		(start 357.41991 -291.40023)
		(mid 357.570295 -291.095938)
		(end 357.41991 -290.791646)
		(width 0.1143)
		(layer "In15.Cu")
		(net "P5E_CPU0_P0_RX_DN<13>")
	)
	(arc
		(start 397.850614 -353.370388)
		(mid 397.775544 -353.170427)
		(end 397.647414 -352.999548)
		(width 0.14224)
		(layer "In15.Cu")
		(net "P5E_CPU0_P0_RX_DN<13>")
	)
	(arc
		(start 357.203502 -304.11293)
		(mid 357.09656 -303.865439)
		(end 357.059992 -303.598326)
		(width 0.14224)
		(layer "In15.Cu")
		(net "P5E_CPU0_P0_RX_DN<13>")
	)
	(arc
		(start 357.32339 -293.972488)
		(mid 357.094264 -293.526311)
		(end 357.322882 -293.079932)
		(width 0.1143)
		(layer "In15.Cu")
		(net "P5E_CPU0_P0_RX_DN<13>")
	)
	(arc
		(start 324.283832 -385.684268)
		(mid 324.378183 -385.543157)
		(end 324.41134 -385.376674)
		(width 0.14224)
		(layer "In15.Cu")
		(net "P5E_CPU0_P0_RX_DN<13>")
	)
	(arc
		(start 357.349044 -292.37051)
		(mid 357.344712 -292.367354)
		(end 357.340408 -292.36416)
		(width 0.1143)
		(layer "In15.Cu")
		(net "P5E_CPU0_P0_RX_DN<13>")
	)
	(arc
		(start 357.105712 -295.145968)
		(mid 357.170439 -294.883344)
		(end 357.349806 -294.680894)
		(width 0.1143)
		(layer "In15.Cu")
		(net "P5E_CPU0_P0_RX_DN<13>")
	)
	(arc
		(start 357.3399 -291.447982)
		(mid 357.344456 -291.444657)
		(end 357.349044 -291.441378)
		(width 0.1143)
		(layer "In15.Cu")
		(net "P5E_CPU0_P0_RX_DN<13>")
	)
	(arc
		(start 369.089686 -324.441058)
		(mid 368.909152 -324.234427)
		(end 368.757962 -324.005448)
		(width 0.14224)
		(layer "In15.Cu")
		(net "P5E_CPU0_P0_RX_DN<13>")
	)
	(arc
		(start 357.439722 -293.006018)
		(mid 357.583003 -292.778014)
		(end 357.526336 -292.514782)
		(width 0.1143)
		(layer "In15.Cu")
		(net "P5E_CPU0_P0_RX_DN<13>")
	)
	(segment
		(start 357.197914 -272.200116)
		(end 356.731062 -272.466054)
		(width 0.12954)
		(layer "F.Cu")
		(net "P5E_CPU0_P0_RX_DN<12>")
	)
	(segment
		(start 317.670434 -393.69238)
		(end 318.191134 -393.69238)
		(width 0.127)
		(layer "F.Cu")
		(net "P5E_CPU0_P0_RX_DN<12>")
	)
	(segment
		(start 348.23654 -373.328184)
		(end 348.66326 -373.328184)
		(width 0.14224)
		(layer "In15.Cu")
		(net "P5E_CPU0_P0_RX_DN<12>")
	)
	(segment
		(start 356.44455 -275.220684)
		(end 356.445566 -275.220176)
		(width 0.1143)
		(layer "In15.Cu")
		(net "P5E_CPU0_P0_RX_DN<12>")
	)
	(segment
		(start 368.499898 -325.518018)
		(end 356.213664 -304.270664)
		(width 0.14224)
		(layer "In15.Cu")
		(net "P5E_CPU0_P0_RX_DN<12>")
	)
	(segment
		(start 356.448106 -277.813516)
		(end 356.44709 -277.813008)
		(width 0.1143)
		(layer "In15.Cu")
		(net "P5E_CPU0_P0_RX_DN<12>")
	)
	(segment
		(start 347.53296 -373.465344)
		(end 348.09938 -373.465344)
		(width 0.14224)
		(layer "In15.Cu")
		(net "P5E_CPU0_P0_RX_DN<12>")
	)
	(segment
		(start 356.448868 -277.814024)
		(end 356.448106 -277.813516)
		(width 0.1143)
		(layer "In15.Cu")
		(net "P5E_CPU0_P0_RX_DN<12>")
	)
	(segment
		(start 356.442264 -276.189948)
		(end 356.40899 -276.170644)
		(width 0.1143)
		(layer "In15.Cu")
		(net "P5E_CPU0_P0_RX_DN<12>")
	)
	(segment
		(start 356.40899 -291.441378)
		(end 356.417626 -291.436298)
		(width 0.1143)
		(layer "In15.Cu")
		(net "P5E_CPU0_P0_RX_DN<12>")
	)
	(segment
		(start 356.450138 -277.814786)
		(end 356.448868 -277.814024)
		(width 0.1143)
		(layer "In15.Cu")
		(net "P5E_CPU0_P0_RX_DN<12>")
	)
	(segment
		(start 356.471728 -274.586446)
		(end 356.470204 -274.58543)
		(width 0.1143)
		(layer "In15.Cu")
		(net "P5E_CPU0_P0_RX_DN<12>")
	)
	(segment
		(start 356.479856 -284.311852)
		(end 356.450138 -284.294834)
		(width 0.1143)
		(layer "In15.Cu")
		(net "P5E_CPU0_P0_RX_DN<12>")
	)
	(segment
		(start 347.3958 -373.328184)
		(end 347.53296 -373.465344)
		(width 0.14224)
		(layer "In15.Cu")
		(net "P5E_CPU0_P0_RX_DN<12>")
	)
	(segment
		(start 356.448868 -276.838156)
		(end 356.450138 -276.837394)
		(width 0.1143)
		(layer "In15.Cu")
		(net "P5E_CPU0_P0_RX_DN<12>")
	)
	(segment
		(start 356.44455 -273.600672)
		(end 356.445566 -273.600164)
		(width 0.1143)
		(layer "In15.Cu")
		(net "P5E_CPU0_P0_RX_DN<12>")
	)
	(segment
		(start 356.44709 -275.21916)
		(end 356.448106 -275.218652)
		(width 0.1143)
		(layer "In15.Cu")
		(net "P5E_CPU0_P0_RX_DN<12>")
	)
	(segment
		(start 356.445566 -278.4602)
		(end 356.44709 -278.459184)
		(width 0.1143)
		(layer "In15.Cu")
		(net "P5E_CPU0_P0_RX_DN<12>")
	)
	(segment
		(start 356.479856 -276.820376)
		(end 356.479602 -276.820376)
		(width 0.1143)
		(layer "In15.Cu")
		(net "P5E_CPU0_P0_RX_DN<12>")
	)
	(segment
		(start 356.448868 -292.393878)
		(end 356.448106 -292.39337)
		(width 0.1143)
		(layer "In15.Cu")
		(net "P5E_CPU0_P0_RX_DN<12>")
	)
	(segment
		(start 329.528678 -375.937272)
		(end 331.880464 -373.585232)
		(width 0.14224)
		(layer "In15.Cu")
		(net "P5E_CPU0_P0_RX_DN<12>")
	)
	(segment
		(start 356.445566 -294.011858)
		(end 356.40899 -293.990522)
		(width 0.1143)
		(layer "In15.Cu")
		(net "P5E_CPU0_P0_RX_DN<12>")
	)
	(segment
		(start 356.448106 -279.433528)
		(end 356.44709 -279.43302)
		(width 0.1143)
		(layer "In15.Cu")
		(net "P5E_CPU0_P0_RX_DN<12>")
	)
	(segment
		(start 346.96908 -373.328184)
		(end 347.3958 -373.328184)
		(width 0.14224)
		(layer "In15.Cu")
		(net "P5E_CPU0_P0_RX_DN<12>")
	)
	(segment
		(start 356.448106 -276.838664)
		(end 356.448868 -276.838156)
		(width 0.1143)
		(layer "In15.Cu")
		(net "P5E_CPU0_P0_RX_DN<12>")
	)
	(segment
		(start 395.98473 -368.590068)
		(end 396.241016 -368.333782)
		(width 0.14224)
		(layer "In15.Cu")
		(net "P5E_CPU0_P0_RX_DN<12>")
	)
	(segment
		(start 356.448868 -284.294072)
		(end 356.448106 -284.293564)
		(width 0.1143)
		(layer "In15.Cu")
		(net "P5E_CPU0_P0_RX_DN<12>")
	)
	(segment
		(start 356.42677 -293.050976)
		(end 356.427786 -293.050468)
		(width 0.1143)
		(layer "In15.Cu")
		(net "P5E_CPU0_P0_RX_DN<12>")
	)
	(segment
		(start 318.544702 -393.786868)
		(end 318.666368 -393.716764)
		(width 0.14224)
		(layer "In15.Cu")
		(net "P5E_CPU0_P0_RX_DN<12>")
	)
	(segment
		(start 356.479856 -294.03167)
		(end 356.448868 -294.01389)
		(width 0.1143)
		(layer "In15.Cu")
		(net "P5E_CPU0_P0_RX_DN<12>")
	)
	(segment
		(start 356.479856 -282.69184)
		(end 356.450138 -282.674822)
		(width 0.1143)
		(layer "In15.Cu")
		(net "P5E_CPU0_P0_RX_DN<12>")
	)
	(segment
		(start 356.448106 -282.673552)
		(end 356.44709 -282.673044)
		(width 0.1143)
		(layer "In15.Cu")
		(net "P5E_CPU0_P0_RX_DN<12>")
	)
	(segment
		(start 396.399258 -353.070922)
		(end 369.128294 -326.328278)
		(width 0.14224)
		(layer "In15.Cu")
		(net "P5E_CPU0_P0_RX_DN<12>")
	)
	(segment
		(start 332.170024 -373.465344)
		(end 346.83192 -373.465344)
		(width 0.14224)
		(layer "In15.Cu")
		(net "P5E_CPU0_P0_RX_DN<12>")
	)
	(segment
		(start 356.448106 -284.293564)
		(end 356.44709 -284.293056)
		(width 0.1143)
		(layer "In15.Cu")
		(net "P5E_CPU0_P0_RX_DN<12>")
	)
	(segment
		(start 356.448106 -281.05354)
		(end 356.44709 -281.053032)
		(width 0.1143)
		(layer "In15.Cu")
		(net "P5E_CPU0_P0_RX_DN<12>")
	)
	(segment
		(start 356.448106 -275.218652)
		(end 356.448868 -275.218144)
		(width 0.1143)
		(layer "In15.Cu")
		(net "P5E_CPU0_P0_RX_DN<12>")
	)
	(segment
		(start 356.472744 -274.586954)
		(end 356.471728 -274.586446)
		(width 0.1143)
		(layer "In15.Cu")
		(net "P5E_CPU0_P0_RX_DN<12>")
	)
	(segment
		(start 356.454964 -281.057858)
		(end 356.454202 -281.05735)
		(width 0.1143)
		(layer "In15.Cu")
		(net "P5E_CPU0_P0_RX_DN<12>")
	)
	(segment
		(start 356.471728 -276.206458)
		(end 356.470204 -276.205442)
		(width 0.1143)
		(layer "In15.Cu")
		(net "P5E_CPU0_P0_RX_DN<12>")
	)
	(segment
		(start 356.119938 -303.919636)
		(end 356.119938 -296.070528)
		(width 0.14224)
		(layer "In15.Cu")
		(net "P5E_CPU0_P0_RX_DN<12>")
	)
	(segment
		(start 356.40899 -289.821366)
		(end 356.479856 -289.780218)
		(width 0.1143)
		(layer "In15.Cu")
		(net "P5E_CPU0_P0_RX_DN<12>")
	)
	(segment
		(start 356.472744 -276.206966)
		(end 356.471728 -276.206458)
		(width 0.1143)
		(layer "In15.Cu")
		(net "P5E_CPU0_P0_RX_DN<12>")
	)
	(segment
		(start 356.44709 -289.152838)
		(end 356.445566 -289.151822)
		(width 0.1143)
		(layer "In15.Cu")
		(net "P5E_CPU0_P0_RX_DN<12>")
	)
	(segment
		(start 318.349376 -393.22883)
		(end 318.354202 -392.616944)
		(width 0.14224)
		(layer "In15.Cu")
		(net "P5E_CPU0_P0_RX_DN<12>")
	)
	(segment
		(start 356.119938 -296.070528)
		(end 356.119938 -296.04208)
		(width 0.1143)
		(layer "In15.Cu")
		(net "P5E_CPU0_P0_RX_DN<12>")
	)
	(segment
		(start 356.450138 -279.434798)
		(end 356.448868 -279.434036)
		(width 0.1143)
		(layer "In15.Cu")
		(net "P5E_CPU0_P0_RX_DN<12>")
	)
	(segment
		(start 356.479602 -275.200364)
		(end 356.48011 -275.20011)
		(width 0.1143)
		(layer "In15.Cu")
		(net "P5E_CPU0_P0_RX_DN<12>")
	)
	(segment
		(start 318.666368 -393.545822)
		(end 318.349376 -393.22883)
		(width 0.14224)
		(layer "In15.Cu")
		(net "P5E_CPU0_P0_RX_DN<12>")
	)
	(segment
		(start 356.44709 -277.813008)
		(end 356.40899 -277.790656)
		(width 0.1143)
		(layer "In15.Cu")
		(net "P5E_CPU0_P0_RX_DN<12>")
	)
	(segment
		(start 356.44455 -276.840696)
		(end 356.445566 -276.840188)
		(width 0.1143)
		(layer "In15.Cu")
		(net "P5E_CPU0_P0_RX_DN<12>")
	)
	(segment
		(start 356.40899 -293.06139)
		(end 356.42677 -293.050976)
		(width 0.1143)
		(layer "In15.Cu")
		(net "P5E_CPU0_P0_RX_DN<12>")
	)
	(segment
		(start 378.80544 -371.14226)
		(end 380.51994 -369.42776)
		(width 0.14224)
		(layer "In15.Cu")
		(net "P5E_CPU0_P0_RX_DN<12>")
	)
	(segment
		(start 363.2708 -373.465344)
		(end 363.3978 -373.338344)
		(width 0.14224)
		(layer "In15.Cu")
		(net "P5E_CPU0_P0_RX_DN<12>")
	)
	(segment
		(start 356.450138 -282.674822)
		(end 356.448868 -282.67406)
		(width 0.1143)
		(layer "In15.Cu")
		(net "P5E_CPU0_P0_RX_DN<12>")
	)
	(segment
		(start 356.448106 -273.59864)
		(end 356.448868 -273.598132)
		(width 0.1143)
		(layer "In15.Cu")
		(net "P5E_CPU0_P0_RX_DN<12>")
	)
	(segment
		(start 350.09582 -373.465344)
		(end 350.23298 -373.328184)
		(width 0.14224)
		(layer "In15.Cu")
		(net "P5E_CPU0_P0_RX_DN<12>")
	)
	(segment
		(start 350.6597 -373.328184)
		(end 350.79686 -373.465344)
		(width 0.14224)
		(layer "In15.Cu")
		(net "P5E_CPU0_P0_RX_DN<12>")
	)
	(segment
		(start 318.354202 -392.616944)
		(end 318.65824 -392.31316)
		(width 0.14224)
		(layer "In15.Cu")
		(net "P5E_CPU0_P0_RX_DN<12>")
	)
	(segment
		(start 356.40899 -275.241512)
		(end 356.44455 -275.220684)
		(width 0.1143)
		(layer "In15.Cu")
		(net "P5E_CPU0_P0_RX_DN<12>")
	)
	(segment
		(start 356.441248 -294.662606)
		(end 356.44201 -294.662098)
		(width 0.1143)
		(layer "In15.Cu")
		(net "P5E_CPU0_P0_RX_DN<12>")
	)
	(segment
		(start 356.40899 -283.341572)
		(end 356.445566 -283.320236)
		(width 0.1143)
		(layer "In15.Cu")
		(net "P5E_CPU0_P0_RX_DN<12>")
	)
	(segment
		(start 356.445566 -281.052016)
		(end 356.40899 -281.03068)
		(width 0.1143)
		(layer "In15.Cu")
		(net "P5E_CPU0_P0_RX_DN<12>")
	)
	(segment
		(start 356.474522 -274.58797)
		(end 356.472744 -274.586954)
		(width 0.1143)
		(layer "In15.Cu")
		(net "P5E_CPU0_P0_RX_DN<12>")
	)
	(segment
		(start 356.442264 -274.569936)
		(end 356.40899 -274.550632)
		(width 0.1143)
		(layer "In15.Cu")
		(net "P5E_CPU0_P0_RX_DN<12>")
	)
	(segment
		(start 356.448106 -290.773358)
		(end 356.44709 -290.77285)
		(width 0.1143)
		(layer "In15.Cu")
		(net "P5E_CPU0_P0_RX_DN<12>")
	)
	(segment
		(start 356.40899 -294.681402)
		(end 356.441248 -294.662606)
		(width 0.1143)
		(layer "In15.Cu")
		(net "P5E_CPU0_P0_RX_DN<12>")
	)
	(segment
		(start 356.445566 -276.840188)
		(end 356.44709 -276.839172)
		(width 0.1143)
		(layer "In15.Cu")
		(net "P5E_CPU0_P0_RX_DN<12>")
	)
	(segment
		(start 363.2708 -372.609364)
		(end 352.44532 -372.609364)
		(width 0.14224)
		(layer "In15.Cu")
		(net "P5E_CPU0_P0_RX_DN<12>")
	)
	(segment
		(start 356.445566 -273.600164)
		(end 356.44709 -273.599148)
		(width 0.1143)
		(layer "In15.Cu")
		(net "P5E_CPU0_P0_RX_DN<12>")
	)
	(segment
		(start 356.445566 -289.151822)
		(end 356.40899 -289.130486)
		(width 0.1143)
		(layer "In15.Cu")
		(net "P5E_CPU0_P0_RX_DN<12>")
	)
	(segment
		(start 356.448106 -289.153346)
		(end 356.44709 -289.152838)
		(width 0.1143)
		(layer "In15.Cu")
		(net "P5E_CPU0_P0_RX_DN<12>")
	)
	(segment
		(start 356.448106 -281.6987)
		(end 356.479856 -281.680412)
		(width 0.1143)
		(layer "In15.Cu")
		(net "P5E_CPU0_P0_RX_DN<12>")
	)
	(segment
		(start 348.09938 -373.465344)
		(end 348.23654 -373.328184)
		(width 0.14224)
		(layer "In15.Cu")
		(net "P5E_CPU0_P0_RX_DN<12>")
	)
	(segment
		(start 356.479856 -285.931864)
		(end 356.448868 -285.914084)
		(width 0.1143)
		(layer "In15.Cu")
		(net "P5E_CPU0_P0_RX_DN<12>")
	)
	(segment
		(start 356.44709 -281.053032)
		(end 356.445566 -281.052016)
		(width 0.1143)
		(layer "In15.Cu")
		(net "P5E_CPU0_P0_RX_DN<12>")
	)
	(segment
		(start 356.479856 -281.071828)
		(end 356.45852 -281.05989)
		(width 0.1143)
		(layer "In15.Cu")
		(net "P5E_CPU0_P0_RX_DN<12>")
	)
	(segment
		(start 356.448106 -278.458676)
		(end 356.448868 -278.458168)
		(width 0.1143)
		(layer "In15.Cu")
		(net "P5E_CPU0_P0_RX_DN<12>")
	)
	(segment
		(start 356.40899 -284.961584)
		(end 356.448106 -284.938724)
		(width 0.1143)
		(layer "In15.Cu")
		(net "P5E_CPU0_P0_RX_DN<12>")
	)
	(segment
		(start 356.448868 -289.153854)
		(end 356.448106 -289.153346)
		(width 0.1143)
		(layer "In15.Cu")
		(net "P5E_CPU0_P0_RX_DN<12>")
	)
	(segment
		(start 352.44532 -371.189504)
		(end 378.691394 -371.189504)
		(width 0.14224)
		(layer "In15.Cu")
		(net "P5E_CPU0_P0_RX_DN<12>")
	)
	(segment
		(start 356.448868 -278.458168)
		(end 356.450138 -278.457406)
		(width 0.1143)
		(layer "In15.Cu")
		(net "P5E_CPU0_P0_RX_DN<12>")
	)
	(segment
		(start 356.445566 -280.080212)
		(end 356.44709 -280.079196)
		(width 0.1143)
		(layer "In15.Cu")
		(net "P5E_CPU0_P0_RX_DN<12>")
	)
	(segment
		(start 356.470204 -274.58543)
		(end 356.442264 -274.569936)
		(width 0.1143)
		(layer "In15.Cu")
		(net "P5E_CPU0_P0_RX_DN<12>")
	)
	(segment
		(start 356.44455 -278.460708)
		(end 356.445566 -278.4602)
		(width 0.1143)
		(layer "In15.Cu")
		(net "P5E_CPU0_P0_RX_DN<12>")
	)
	(segment
		(start 356.450138 -273.59737)
		(end 356.479856 -273.580352)
		(width 0.1143)
		(layer "In15.Cu")
		(net "P5E_CPU0_P0_RX_DN<12>")
	)
	(segment
		(start 318.544194 -393.787376)
		(end 318.544702 -393.786868)
		(width 0.14224)
		(layer "In15.Cu")
		(net "P5E_CPU0_P0_RX_DN<12>")
	)
	(segment
		(start 318.191134 -393.69238)
		(end 318.544194 -393.787376)
		(width 0.14224)
		(layer "In15.Cu")
		(net "P5E_CPU0_P0_RX_DN<12>")
	)
	(segment
		(start 356.448868 -279.434036)
		(end 356.448106 -279.433528)
		(width 0.1143)
		(layer "In15.Cu")
		(net "P5E_CPU0_P0_RX_DN<12>")
	)
	(segment
		(start 356.448868 -280.07818)
		(end 356.450138 -280.077418)
		(width 0.1143)
		(layer "In15.Cu")
		(net "P5E_CPU0_P0_RX_DN<12>")
	)
	(segment
		(start 352.13798 -371.496844)
		(end 352.44532 -371.189504)
		(width 0.14224)
		(layer "In15.Cu")
		(net "P5E_CPU0_P0_RX_DN<12>")
	)
	(segment
		(start 357.098854 -272.535904)
		(end 357.029004 -272.466054)
		(width 0.1143)
		(layer "In15.Cu")
		(net "P5E_CPU0_P0_RX_DN<12>")
	)
	(segment
		(start 356.44709 -283.31922)
		(end 356.448106 -283.318712)
		(width 0.1143)
		(layer "In15.Cu")
		(net "P5E_CPU0_P0_RX_DN<12>")
	)
	(segment
		(start 356.44709 -294.012874)
		(end 356.445566 -294.011858)
		(width 0.1143)
		(layer "In15.Cu")
		(net "P5E_CPU0_P0_RX_DN<12>")
	)
	(segment
		(start 356.450138 -278.457406)
		(end 356.479856 -278.440388)
		(width 0.1143)
		(layer "In15.Cu")
		(net "P5E_CPU0_P0_RX_DN<12>")
	)
	(segment
		(start 356.448106 -285.913576)
		(end 356.44709 -285.913068)
		(width 0.1143)
		(layer "In15.Cu")
		(net "P5E_CPU0_P0_RX_DN<12>")
	)
	(segment
		(start 356.448106 -286.558482)
		(end 356.481634 -286.538924)
		(width 0.1143)
		(layer "In15.Cu")
		(net "P5E_CPU0_P0_RX_DN<12>")
	)
	(segment
		(start 356.40899 -288.201354)
		(end 356.481634 -288.158936)
		(width 0.1143)
		(layer "In15.Cu")
		(net "P5E_CPU0_P0_RX_DN<12>")
	)
	(segment
		(start 356.119938 -296.04208)
		(end 356.165658 -295.99636)
		(width 0.1143)
		(layer "In15.Cu")
		(net "P5E_CPU0_P0_RX_DN<12>")
	)
	(segment
		(start 356.40899 -278.481536)
		(end 356.44455 -278.460708)
		(width 0.1143)
		(layer "In15.Cu")
		(net "P5E_CPU0_P0_RX_DN<12>")
	)
	(segment
		(start 356.40899 -280.101548)
		(end 356.44455 -280.08072)
		(width 0.1143)
		(layer "In15.Cu")
		(net "P5E_CPU0_P0_RX_DN<12>")
	)
	(segment
		(start 356.427786 -293.050468)
		(end 356.479856 -293.020242)
		(width 0.1143)
		(layer "In15.Cu")
		(net "P5E_CPU0_P0_RX_DN<12>")
	)
	(segment
		(start 356.44709 -284.293056)
		(end 356.40899 -284.270704)
		(width 0.1143)
		(layer "In15.Cu")
		(net "P5E_CPU0_P0_RX_DN<12>")
	)
	(segment
		(start 356.450138 -280.077418)
		(end 356.479856 -280.0604)
		(width 0.1143)
		(layer "In15.Cu")
		(net "P5E_CPU0_P0_RX_DN<12>")
	)
	(segment
		(start 356.448106 -283.318712)
		(end 356.479856 -283.300424)
		(width 0.1143)
		(layer "In15.Cu")
		(net "P5E_CPU0_P0_RX_DN<12>")
	)
	(segment
		(start 348.80042 -373.465344)
		(end 350.09582 -373.465344)
		(width 0.14224)
		(layer "In15.Cu")
		(net "P5E_CPU0_P0_RX_DN<12>")
	)
	(segment
		(start 356.479856 -287.551876)
		(end 356.448106 -287.533588)
		(width 0.1143)
		(layer "In15.Cu")
		(net "P5E_CPU0_P0_RX_DN<12>")
	)
	(segment
		(start 356.450138 -284.294834)
		(end 356.448868 -284.294072)
		(width 0.1143)
		(layer "In15.Cu")
		(net "P5E_CPU0_P0_RX_DN<12>")
	)
	(segment
		(start 356.448106 -292.39337)
		(end 356.44709 -292.392862)
		(width 0.1143)
		(layer "In15.Cu")
		(net "P5E_CPU0_P0_RX_DN<12>")
	)
	(segment
		(start 356.479602 -276.820376)
		(end 356.48011 -276.820122)
		(width 0.1143)
		(layer "In15.Cu")
		(net "P5E_CPU0_P0_RX_DN<12>")
	)
	(segment
		(start 356.44709 -280.079196)
		(end 356.448106 -280.078688)
		(width 0.1143)
		(layer "In15.Cu")
		(net "P5E_CPU0_P0_RX_DN<12>")
	)
	(segment
		(start 356.44709 -278.459184)
		(end 356.448106 -278.458676)
		(width 0.1143)
		(layer "In15.Cu")
		(net "P5E_CPU0_P0_RX_DN<12>")
	)
	(segment
		(start 356.44709 -273.599148)
		(end 356.448106 -273.59864)
		(width 0.1143)
		(layer "In15.Cu")
		(net "P5E_CPU0_P0_RX_DN<12>")
	)
	(segment
		(start 356.40899 -286.581342)
		(end 356.409498 -286.581088)
		(width 0.1143)
		(layer "In15.Cu")
		(net "P5E_CPU0_P0_RX_DN<12>")
	)
	(segment
		(start 356.448106 -287.533588)
		(end 356.41153 -287.512252)
		(width 0.1143)
		(layer "In15.Cu")
		(net "P5E_CPU0_P0_RX_DN<12>")
	)
	(segment
		(start 356.448868 -282.67406)
		(end 356.448106 -282.673552)
		(width 0.1143)
		(layer "In15.Cu")
		(net "P5E_CPU0_P0_RX_DN<12>")
	)
	(segment
		(start 352.44532 -372.609364)
		(end 352.13798 -372.302024)
		(width 0.14224)
		(layer "In15.Cu")
		(net "P5E_CPU0_P0_RX_DN<12>")
	)
	(segment
		(start 356.44709 -290.77285)
		(end 356.445566 -290.771834)
		(width 0.1143)
		(layer "In15.Cu")
		(net "P5E_CPU0_P0_RX_DN<12>")
	)
	(segment
		(start 356.448106 -294.013382)
		(end 356.44709 -294.012874)
		(width 0.1143)
		(layer "In15.Cu")
		(net "P5E_CPU0_P0_RX_DN<12>")
	)
	(segment
		(start 356.443788 -294.661082)
		(end 356.44455 -294.660574)
		(width 0.1143)
		(layer "In15.Cu")
		(net "P5E_CPU0_P0_RX_DN<12>")
	)
	(segment
		(start 380.83363 -369.297966)
		(end 394.275818 -369.297966)
		(width 0.14224)
		(layer "In15.Cu")
		(net "P5E_CPU0_P0_RX_DN<12>")
	)
	(segment
		(start 357.029004 -272.466054)
		(end 356.731062 -272.466054)
		(width 0.1143)
		(layer "In15.Cu")
		(net "P5E_CPU0_P0_RX_DN<12>")
	)
	(segment
		(start 356.44709 -285.913068)
		(end 356.40899 -285.890716)
		(width 0.1143)
		(layer "In15.Cu")
		(net "P5E_CPU0_P0_RX_DN<12>")
	)
	(segment
		(start 356.470204 -276.205442)
		(end 356.442264 -276.189948)
		(width 0.1143)
		(layer "In15.Cu")
		(net "P5E_CPU0_P0_RX_DN<12>")
	)
	(segment
		(start 356.479856 -290.791646)
		(end 356.448868 -290.773866)
		(width 0.1143)
		(layer "In15.Cu")
		(net "P5E_CPU0_P0_RX_DN<12>")
	)
	(segment
		(start 356.45852 -281.05989)
		(end 356.457504 -281.059382)
		(width 0.1143)
		(layer "In15.Cu")
		(net "P5E_CPU0_P0_RX_DN<12>")
	)
	(segment
		(start 356.165658 -295.99636)
		(end 356.165658 -295.145968)
		(width 0.1143)
		(layer "In15.Cu")
		(net "P5E_CPU0_P0_RX_DN<12>")
	)
	(segment
		(start 350.79686 -373.465344)
		(end 363.2708 -373.465344)
		(width 0.14224)
		(layer "In15.Cu")
		(net "P5E_CPU0_P0_RX_DN<12>")
	)
	(segment
		(start 356.44709 -279.43302)
		(end 356.40899 -279.410668)
		(width 0.1143)
		(layer "In15.Cu")
		(net "P5E_CPU0_P0_RX_DN<12>")
	)
	(segment
		(start 356.445566 -292.391846)
		(end 356.40899 -292.37051)
		(width 0.1143)
		(layer "In15.Cu")
		(net "P5E_CPU0_P0_RX_DN<12>")
	)
	(segment
		(start 323.130926 -384.467354)
		(end 323.130926 -377.130056)
		(width 0.14224)
		(layer "In15.Cu")
		(net "P5E_CPU0_P0_RX_DN<12>")
	)
	(segment
		(start 356.448868 -285.914084)
		(end 356.448106 -285.913576)
		(width 0.1143)
		(layer "In15.Cu")
		(net "P5E_CPU0_P0_RX_DN<12>")
	)
	(segment
		(start 324.221602 -375.984516)
		(end 329.414632 -375.984516)
		(width 0.14224)
		(layer "In15.Cu")
		(net "P5E_CPU0_P0_RX_DN<12>")
	)
	(segment
		(start 356.445566 -275.220176)
		(end 356.44709 -275.21916)
		(width 0.1143)
		(layer "In15.Cu")
		(net "P5E_CPU0_P0_RX_DN<12>")
	)
	(segment
		(start 356.44455 -280.08072)
		(end 356.445566 -280.080212)
		(width 0.1143)
		(layer "In15.Cu")
		(net "P5E_CPU0_P0_RX_DN<12>")
	)
	(segment
		(start 356.450138 -275.217382)
		(end 356.479856 -275.200364)
		(width 0.1143)
		(layer "In15.Cu")
		(net "P5E_CPU0_P0_RX_DN<12>")
	)
	(segment
		(start 356.448868 -275.218144)
		(end 356.450138 -275.217382)
		(width 0.1143)
		(layer "In15.Cu")
		(net "P5E_CPU0_P0_RX_DN<12>")
	)
	(segment
		(start 356.40899 -273.6215)
		(end 356.44455 -273.600672)
		(width 0.1143)
		(layer "In15.Cu")
		(net "P5E_CPU0_P0_RX_DN<12>")
	)
	(segment
		(start 356.479856 -289.171634)
		(end 356.448868 -289.153854)
		(width 0.1143)
		(layer "In15.Cu")
		(net "P5E_CPU0_P0_RX_DN<12>")
	)
	(segment
		(start 356.450138 -276.837394)
		(end 356.479856 -276.820376)
		(width 0.1143)
		(layer "In15.Cu")
		(net "P5E_CPU0_P0_RX_DN<12>")
	)
	(segment
		(start 356.448868 -281.054048)
		(end 356.448106 -281.05354)
		(width 0.1143)
		(layer "In15.Cu")
		(net "P5E_CPU0_P0_RX_DN<12>")
	)
	(segment
		(start 356.445566 -283.320236)
		(end 356.44709 -283.31922)
		(width 0.1143)
		(layer "In15.Cu")
		(net "P5E_CPU0_P0_RX_DN<12>")
	)
	(segment
		(start 356.448106 -294.658542)
		(end 356.479856 -294.640254)
		(width 0.1143)
		(layer "In15.Cu")
		(net "P5E_CPU0_P0_RX_DN<12>")
	)
	(segment
		(start 356.445566 -290.771834)
		(end 356.40899 -290.750498)
		(width 0.1143)
		(layer "In15.Cu")
		(net "P5E_CPU0_P0_RX_DN<12>")
	)
	(segment
		(start 356.454202 -281.05735)
		(end 356.452932 -281.056588)
		(width 0.1143)
		(layer "In15.Cu")
		(net "P5E_CPU0_P0_RX_DN<12>")
	)
	(segment
		(start 356.44201 -294.662098)
		(end 356.443788 -294.661082)
		(width 0.1143)
		(layer "In15.Cu")
		(net "P5E_CPU0_P0_RX_DN<12>")
	)
	(segment
		(start 363.3978 -372.736364)
		(end 363.2708 -372.609364)
		(width 0.14224)
		(layer "In15.Cu")
		(net "P5E_CPU0_P0_RX_DN<12>")
	)
	(segment
		(start 348.66326 -373.328184)
		(end 348.80042 -373.465344)
		(width 0.14224)
		(layer "In15.Cu")
		(net "P5E_CPU0_P0_RX_DN<12>")
	)
	(segment
		(start 356.479856 -279.451816)
		(end 356.450138 -279.434798)
		(width 0.1143)
		(layer "In15.Cu")
		(net "P5E_CPU0_P0_RX_DN<12>")
	)
	(segment
		(start 356.448106 -284.938724)
		(end 356.479856 -284.920436)
		(width 0.1143)
		(layer "In15.Cu")
		(net "P5E_CPU0_P0_RX_DN<12>")
	)
	(segment
		(start 396.818104 -366.940846)
		(end 396.818104 -354.06838)
		(width 0.14224)
		(layer "In15.Cu")
		(net "P5E_CPU0_P0_RX_DN<12>")
	)
	(segment
		(start 356.40899 -276.861524)
		(end 356.44455 -276.840696)
		(width 0.1143)
		(layer "In15.Cu")
		(net "P5E_CPU0_P0_RX_DN<12>")
	)
	(segment
		(start 363.3978 -373.338344)
		(end 363.3978 -372.736364)
		(width 0.14224)
		(layer "In15.Cu")
		(net "P5E_CPU0_P0_RX_DN<12>")
	)
	(segment
		(start 356.418642 -291.43579)
		(end 356.479856 -291.40023)
		(width 0.1143)
		(layer "In15.Cu")
		(net "P5E_CPU0_P0_RX_DN<12>")
	)
	(segment
		(start 346.83192 -373.465344)
		(end 346.96908 -373.328184)
		(width 0.14224)
		(layer "In15.Cu")
		(net "P5E_CPU0_P0_RX_DN<12>")
	)
	(segment
		(start 356.879144 -272.811494)
		(end 356.94874 -272.770854)
		(width 0.1143)
		(layer "In15.Cu")
		(net "P5E_CPU0_P0_RX_DN<12>")
	)
	(segment
		(start 352.13798 -372.302024)
		(end 352.13798 -371.496844)
		(width 0.14224)
		(layer "In15.Cu")
		(net "P5E_CPU0_P0_RX_DN<12>")
	)
	(segment
		(start 356.44709 -276.839172)
		(end 356.448106 -276.838664)
		(width 0.1143)
		(layer "In15.Cu")
		(net "P5E_CPU0_P0_RX_DN<12>")
	)
	(segment
		(start 318.83858 -389.63346)
		(end 322.512944 -385.959096)
		(width 0.14224)
		(layer "In15.Cu")
		(net "P5E_CPU0_P0_RX_DN<12>")
	)
	(segment
		(start 323.289676 -376.74677)
		(end 323.932042 -376.104404)
		(width 0.14224)
		(layer "In15.Cu")
		(net "P5E_CPU0_P0_RX_DN<12>")
	)
	(segment
		(start 356.479856 -275.200364)
		(end 356.479602 -275.200364)
		(width 0.1143)
		(layer "In15.Cu")
		(net "P5E_CPU0_P0_RX_DN<12>")
	)
	(segment
		(start 356.44709 -294.65905)
		(end 356.448106 -294.658542)
		(width 0.1143)
		(layer "In15.Cu")
		(net "P5E_CPU0_P0_RX_DN<12>")
	)
	(segment
		(start 318.666368 -393.716764)
		(end 318.666368 -393.545822)
		(width 0.14224)
		(layer "In15.Cu")
		(net "P5E_CPU0_P0_RX_DN<12>")
	)
	(segment
		(start 356.40899 -281.72156)
		(end 356.448106 -281.6987)
		(width 0.1143)
		(layer "In15.Cu")
		(net "P5E_CPU0_P0_RX_DN<12>")
	)
	(segment
		(start 356.448106 -280.078688)
		(end 356.448868 -280.07818)
		(width 0.1143)
		(layer "In15.Cu")
		(net "P5E_CPU0_P0_RX_DN<12>")
	)
	(segment
		(start 356.479856 -277.831804)
		(end 356.450138 -277.814786)
		(width 0.1143)
		(layer "In15.Cu")
		(net "P5E_CPU0_P0_RX_DN<12>")
	)
	(segment
		(start 318.65824 -392.31316)
		(end 318.65824 -390.068816)
		(width 0.14224)
		(layer "In15.Cu")
		(net "P5E_CPU0_P0_RX_DN<12>")
	)
	(segment
		(start 356.44709 -292.392862)
		(end 356.445566 -292.391846)
		(width 0.1143)
		(layer "In15.Cu")
		(net "P5E_CPU0_P0_RX_DN<12>")
	)
	(segment
		(start 356.448868 -290.773866)
		(end 356.448106 -290.773358)
		(width 0.1143)
		(layer "In15.Cu")
		(net "P5E_CPU0_P0_RX_DN<12>")
	)
	(segment
		(start 356.44455 -294.660574)
		(end 356.445566 -294.660066)
		(width 0.1143)
		(layer "In15.Cu")
		(net "P5E_CPU0_P0_RX_DN<12>")
	)
	(segment
		(start 356.448868 -294.01389)
		(end 356.448106 -294.013382)
		(width 0.1143)
		(layer "In15.Cu")
		(net "P5E_CPU0_P0_RX_DN<12>")
	)
	(segment
		(start 356.474522 -276.207982)
		(end 356.472744 -276.206966)
		(width 0.1143)
		(layer "In15.Cu")
		(net "P5E_CPU0_P0_RX_DN<12>")
	)
	(segment
		(start 356.479856 -292.411658)
		(end 356.448868 -292.393878)
		(width 0.1143)
		(layer "In15.Cu")
		(net "P5E_CPU0_P0_RX_DN<12>")
	)
	(segment
		(start 356.445566 -294.660066)
		(end 356.44709 -294.65905)
		(width 0.1143)
		(layer "In15.Cu")
		(net "P5E_CPU0_P0_RX_DN<12>")
	)
	(segment
		(start 356.448868 -273.598132)
		(end 356.450138 -273.59737)
		(width 0.1143)
		(layer "In15.Cu")
		(net "P5E_CPU0_P0_RX_DN<12>")
	)
	(segment
		(start 356.457504 -281.059382)
		(end 356.454964 -281.057858)
		(width 0.1143)
		(layer "In15.Cu")
		(net "P5E_CPU0_P0_RX_DN<12>")
	)
	(segment
		(start 350.23298 -373.328184)
		(end 350.6597 -373.328184)
		(width 0.14224)
		(layer "In15.Cu")
		(net "P5E_CPU0_P0_RX_DN<12>")
	)
	(segment
		(start 356.409498 -286.581088)
		(end 356.448106 -286.558482)
		(width 0.1143)
		(layer "In15.Cu")
		(net "P5E_CPU0_P0_RX_DN<12>")
	)
	(segment
		(start 356.44709 -282.673044)
		(end 356.40899 -282.650692)
		(width 0.1143)
		(layer "In15.Cu")
		(net "P5E_CPU0_P0_RX_DN<12>")
	)
	(segment
		(start 356.452932 -281.056588)
		(end 356.448868 -281.054048)
		(width 0.1143)
		(layer "In15.Cu")
		(net "P5E_CPU0_P0_RX_DN<12>")
	)
	(segment
		(start 356.417626 -291.436298)
		(end 356.418642 -291.43579)
		(width 0.1143)
		(layer "In15.Cu")
		(net "P5E_CPU0_P0_RX_DN<12>")
	)
	(arc
		(start 356.635812 -287.856168)
		(mid 356.594557 -287.685197)
		(end 356.479856 -287.551876)
		(width 0.1143)
		(layer "In15.Cu")
		(net "P5E_CPU0_P0_RX_DN<12>")
	)
	(arc
		(start 356.481634 -288.158936)
		(mid 356.595041 -288.026047)
		(end 356.635812 -287.856168)
		(width 0.1143)
		(layer "In15.Cu")
		(net "P5E_CPU0_P0_RX_DN<12>")
	)
	(arc
		(start 356.479856 -283.300424)
		(mid 356.635784 -282.996132)
		(end 356.479856 -282.69184)
		(width 0.1143)
		(layer "In15.Cu")
		(net "P5E_CPU0_P0_RX_DN<12>")
	)
	(arc
		(start 356.165658 -295.145968)
		(mid 356.230173 -294.883749)
		(end 356.40899 -294.681402)
		(width 0.1143)
		(layer "In15.Cu")
		(net "P5E_CPU0_P0_RX_DN<12>")
	)
	(arc
		(start 356.479856 -289.780218)
		(mid 356.635784 -289.475926)
		(end 356.479856 -289.171634)
		(width 0.1143)
		(layer "In15.Cu")
		(net "P5E_CPU0_P0_RX_DN<12>")
	)
	(arc
		(start 356.479856 -273.580352)
		(mid 356.594532 -273.447018)
		(end 356.635812 -273.27606)
		(width 0.1143)
		(layer "In15.Cu")
		(net "P5E_CPU0_P0_RX_DN<12>")
	)
	(arc
		(start 396.818104 -354.06838)
		(mid 396.709137 -353.527472)
		(end 396.399258 -353.070922)
		(width 0.14224)
		(layer "In15.Cu")
		(net "P5E_CPU0_P0_RX_DN<12>")
	)
	(arc
		(start 396.241016 -368.333782)
		(mid 396.668146 -367.694726)
		(end 396.818104 -366.940846)
		(width 0.14224)
		(layer "In15.Cu")
		(net "P5E_CPU0_P0_RX_DN<12>")
	)
	(arc
		(start 380.51994 -369.42776)
		(mid 380.663863 -369.331624)
		(end 380.83363 -369.297966)
		(width 0.14224)
		(layer "In15.Cu")
		(net "P5E_CPU0_P0_RX_DN<12>")
	)
	(arc
		(start 394.275818 -369.297966)
		(mid 395.200677 -369.113982)
		(end 395.98473 -368.590068)
		(width 0.14224)
		(layer "In15.Cu")
		(net "P5E_CPU0_P0_RX_DN<12>")
	)
	(arc
		(start 356.479856 -280.0604)
		(mid 356.635784 -279.756108)
		(end 356.479856 -279.451816)
		(width 0.1143)
		(layer "In15.Cu")
		(net "P5E_CPU0_P0_RX_DN<12>")
	)
	(arc
		(start 356.479856 -294.640254)
		(mid 356.635784 -294.335962)
		(end 356.479856 -294.03167)
		(width 0.1143)
		(layer "In15.Cu")
		(net "P5E_CPU0_P0_RX_DN<12>")
	)
	(arc
		(start 356.635812 -286.236156)
		(mid 356.594557 -286.065185)
		(end 356.479856 -285.931864)
		(width 0.1143)
		(layer "In15.Cu")
		(net "P5E_CPU0_P0_RX_DN<12>")
	)
	(arc
		(start 356.48011 -275.20011)
		(mid 356.635921 -274.892618)
		(end 356.474522 -274.58797)
		(width 0.1143)
		(layer "In15.Cu")
		(net "P5E_CPU0_P0_RX_DN<12>")
	)
	(arc
		(start 322.512944 -385.959096)
		(mid 322.970311 -385.274693)
		(end 323.130926 -384.467354)
		(width 0.14224)
		(layer "In15.Cu")
		(net "P5E_CPU0_P0_RX_DN<12>")
	)
	(arc
		(start 356.165658 -287.045908)
		(mid 356.230173 -286.783689)
		(end 356.40899 -286.581342)
		(width 0.1143)
		(layer "In15.Cu")
		(net "P5E_CPU0_P0_RX_DN<12>")
	)
	(arc
		(start 329.414632 -375.984516)
		(mid 329.476355 -375.972239)
		(end 329.528678 -375.937272)
		(width 0.14224)
		(layer "In15.Cu")
		(net "P5E_CPU0_P0_RX_DN<12>")
	)
	(arc
		(start 356.479856 -278.440388)
		(mid 356.635784 -278.136096)
		(end 356.479856 -277.831804)
		(width 0.1143)
		(layer "In15.Cu")
		(net "P5E_CPU0_P0_RX_DN<12>")
	)
	(arc
		(start 356.94874 -272.770854)
		(mid 357.046505 -272.667878)
		(end 357.098854 -272.535904)
		(width 0.1143)
		(layer "In15.Cu")
		(net "P5E_CPU0_P0_RX_DN<12>")
	)
	(arc
		(start 323.932042 -376.104404)
		(mid 324.064907 -376.015689)
		(end 324.221602 -375.984516)
		(width 0.14224)
		(layer "In15.Cu")
		(net "P5E_CPU0_P0_RX_DN<12>")
	)
	(arc
		(start 356.40899 -290.750498)
		(mid 356.165663 -290.285932)
		(end 356.40899 -289.821366)
		(width 0.1143)
		(layer "In15.Cu")
		(net "P5E_CPU0_P0_RX_DN<12>")
	)
	(arc
		(start 356.213664 -304.270664)
		(mid 356.143656 -304.101331)
		(end 356.119938 -303.919636)
		(width 0.14224)
		(layer "In15.Cu")
		(net "P5E_CPU0_P0_RX_DN<12>")
	)
	(arc
		(start 356.40899 -289.130486)
		(mid 356.165663 -288.66592)
		(end 356.40899 -288.201354)
		(width 0.1143)
		(layer "In15.Cu")
		(net "P5E_CPU0_P0_RX_DN<12>")
	)
	(arc
		(start 356.40899 -281.03068)
		(mid 356.165663 -280.566114)
		(end 356.40899 -280.101548)
		(width 0.1143)
		(layer "In15.Cu")
		(net "P5E_CPU0_P0_RX_DN<12>")
	)
	(arc
		(start 356.40899 -284.270704)
		(mid 356.165663 -283.806138)
		(end 356.40899 -283.341572)
		(width 0.1143)
		(layer "In15.Cu")
		(net "P5E_CPU0_P0_RX_DN<12>")
	)
	(arc
		(start 356.41153 -287.512252)
		(mid 356.230878 -287.309507)
		(end 356.165658 -287.045908)
		(width 0.1143)
		(layer "In15.Cu")
		(net "P5E_CPU0_P0_RX_DN<12>")
	)
	(arc
		(start 356.40899 -293.990522)
		(mid 356.165663 -293.525956)
		(end 356.40899 -293.06139)
		(width 0.1143)
		(layer "In15.Cu")
		(net "P5E_CPU0_P0_RX_DN<12>")
	)
	(arc
		(start 356.40899 -282.650692)
		(mid 356.165663 -282.186126)
		(end 356.40899 -281.72156)
		(width 0.1143)
		(layer "In15.Cu")
		(net "P5E_CPU0_P0_RX_DN<12>")
	)
	(arc
		(start 318.65824 -390.068816)
		(mid 318.705107 -389.833199)
		(end 318.83858 -389.63346)
		(width 0.14224)
		(layer "In15.Cu")
		(net "P5E_CPU0_P0_RX_DN<12>")
	)
	(arc
		(start 356.48011 -276.820122)
		(mid 356.635921 -276.51263)
		(end 356.474522 -276.207982)
		(width 0.1143)
		(layer "In15.Cu")
		(net "P5E_CPU0_P0_RX_DN<12>")
	)
	(arc
		(start 356.479856 -291.40023)
		(mid 356.635784 -291.095938)
		(end 356.479856 -290.791646)
		(width 0.1143)
		(layer "In15.Cu")
		(net "P5E_CPU0_P0_RX_DN<12>")
	)
	(arc
		(start 323.130926 -377.130056)
		(mid 323.172186 -376.922628)
		(end 323.289676 -376.74677)
		(width 0.14224)
		(layer "In15.Cu")
		(net "P5E_CPU0_P0_RX_DN<12>")
	)
	(arc
		(start 356.635812 -273.27606)
		(mid 356.700327 -273.013841)
		(end 356.879144 -272.811494)
		(width 0.1143)
		(layer "In15.Cu")
		(net "P5E_CPU0_P0_RX_DN<12>")
	)
	(arc
		(start 356.481634 -286.538924)
		(mid 356.595041 -286.406035)
		(end 356.635812 -286.236156)
		(width 0.1143)
		(layer "In15.Cu")
		(net "P5E_CPU0_P0_RX_DN<12>")
	)
	(arc
		(start 356.40899 -279.410668)
		(mid 356.165663 -278.946102)
		(end 356.40899 -278.481536)
		(width 0.1143)
		(layer "In15.Cu")
		(net "P5E_CPU0_P0_RX_DN<12>")
	)
	(arc
		(start 356.40899 -276.170644)
		(mid 356.165663 -275.706078)
		(end 356.40899 -275.241512)
		(width 0.1143)
		(layer "In15.Cu")
		(net "P5E_CPU0_P0_RX_DN<12>")
	)
	(arc
		(start 369.128294 -326.328278)
		(mid 368.786599 -325.944471)
		(end 368.499898 -325.518018)
		(width 0.14224)
		(layer "In15.Cu")
		(net "P5E_CPU0_P0_RX_DN<12>")
	)
	(arc
		(start 331.880464 -373.585232)
		(mid 332.013302 -373.496439)
		(end 332.170024 -373.465344)
		(width 0.14224)
		(layer "In15.Cu")
		(net "P5E_CPU0_P0_RX_DN<12>")
	)
	(arc
		(start 356.479856 -284.920436)
		(mid 356.635784 -284.616144)
		(end 356.479856 -284.311852)
		(width 0.1143)
		(layer "In15.Cu")
		(net "P5E_CPU0_P0_RX_DN<12>")
	)
	(arc
		(start 356.40899 -292.37051)
		(mid 356.165663 -291.905944)
		(end 356.40899 -291.441378)
		(width 0.1143)
		(layer "In15.Cu")
		(net "P5E_CPU0_P0_RX_DN<12>")
	)
	(arc
		(start 356.40899 -277.790656)
		(mid 356.165663 -277.32609)
		(end 356.40899 -276.861524)
		(width 0.1143)
		(layer "In15.Cu")
		(net "P5E_CPU0_P0_RX_DN<12>")
	)
	(arc
		(start 356.40899 -274.550632)
		(mid 356.165663 -274.086066)
		(end 356.40899 -273.6215)
		(width 0.1143)
		(layer "In15.Cu")
		(net "P5E_CPU0_P0_RX_DN<12>")
	)
	(arc
		(start 378.691394 -371.189504)
		(mid 378.753117 -371.177227)
		(end 378.80544 -371.14226)
		(width 0.14224)
		(layer "In15.Cu")
		(net "P5E_CPU0_P0_RX_DN<12>")
	)
	(arc
		(start 356.479856 -293.020242)
		(mid 356.635784 -292.71595)
		(end 356.479856 -292.411658)
		(width 0.1143)
		(layer "In15.Cu")
		(net "P5E_CPU0_P0_RX_DN<12>")
	)
	(arc
		(start 356.40899 -285.890716)
		(mid 356.165663 -285.42615)
		(end 356.40899 -284.961584)
		(width 0.1143)
		(layer "In15.Cu")
		(net "P5E_CPU0_P0_RX_DN<12>")
	)
	(arc
		(start 356.479856 -281.680412)
		(mid 356.635784 -281.37612)
		(end 356.479856 -281.071828)
		(width 0.1143)
		(layer "In15.Cu")
		(net "P5E_CPU0_P0_RX_DN<12>")
	)
	(segment
		(start 354.847906 -269.770098)
		(end 354.381054 -270.036036)
		(width 0.12954)
		(layer "F.Cu")
		(net "P5E_CPU0_P0_RX_DN<11>")
	)
	(segment
		(start 316.470284 -393.69238)
		(end 316.990984 -393.69238)
		(width 0.127)
		(layer "F.Cu")
		(net "P5E_CPU0_P0_RX_DN<11>")
	)
	(segment
		(start 355.510084 -277.814786)
		(end 355.508814 -277.814024)
		(width 0.1143)
		(layer "In15.Cu")
		(net "P5E_CPU0_P0_RX_DN<11>")
	)
	(segment
		(start 333.502 -372.521226)
		(end 333.9338 -372.521226)
		(width 0.14224)
		(layer "In15.Cu")
		(net "P5E_CPU0_P0_RX_DN<11>")
	)
	(segment
		(start 355.513386 -292.396418)
		(end 355.51237 -292.39591)
		(width 0.1143)
		(layer "In15.Cu")
		(net "P5E_CPU0_P0_RX_DN<11>")
	)
	(segment
		(start 355.46919 -276.86127)
		(end 355.509576 -276.837902)
		(width 0.1143)
		(layer "In15.Cu")
		(net "P5E_CPU0_P0_RX_DN<11>")
	)
	(segment
		(start 355.44125 -276.881336)
		(end 355.46919 -276.86127)
		(width 0.1143)
		(layer "In15.Cu")
		(net "P5E_CPU0_P0_RX_DN<11>")
	)
	(segment
		(start 316.990984 -393.69238)
		(end 317.344298 -393.787376)
		(width 0.14224)
		(layer "In15.Cu")
		(net "P5E_CPU0_P0_RX_DN<11>")
	)
	(segment
		(start 355.508052 -292.39337)
		(end 355.507798 -292.39337)
		(width 0.1143)
		(layer "In15.Cu")
		(net "P5E_CPU0_P0_RX_DN<11>")
	)
	(segment
		(start 319.726818 -377.676156)
		(end 319.726818 -376.983244)
		(width 0.14224)
		(layer "In15.Cu")
		(net "P5E_CPU0_P0_RX_DN<11>")
	)
	(segment
		(start 355.539802 -294.03167)
		(end 355.51491 -294.017446)
		(width 0.1143)
		(layer "In15.Cu")
		(net "P5E_CPU0_P0_RX_DN<11>")
	)
	(segment
		(start 355.473254 -273.618706)
		(end 355.508052 -273.59864)
		(width 0.1143)
		(layer "In15.Cu")
		(net "P5E_CPU0_P0_RX_DN<11>")
	)
	(segment
		(start 355.51745 -290.778692)
		(end 355.515164 -290.777422)
		(width 0.1143)
		(layer "In15.Cu")
		(net "P5E_CPU0_P0_RX_DN<11>")
	)
	(segment
		(start 319.846706 -376.693684)
		(end 320.308478 -376.231912)
		(width 0.14224)
		(layer "In15.Cu")
		(net "P5E_CPU0_P0_RX_DN<11>")
	)
	(segment
		(start 321.429126 -384.865118)
		(end 321.429126 -379.573282)
		(width 0.14224)
		(layer "In15.Cu")
		(net "P5E_CPU0_P0_RX_DN<11>")
	)
	(segment
		(start 355.493066 -294.667178)
		(end 355.539802 -294.640254)
		(width 0.1143)
		(layer "In15.Cu")
		(net "P5E_CPU0_P0_RX_DN<11>")
	)
	(segment
		(start 331.480414 -372.521226)
		(end 332.80096 -372.521226)
		(width 0.14224)
		(layer "In15.Cu")
		(net "P5E_CPU0_P0_RX_DN<11>")
	)
	(segment
		(start 332.80096 -372.521226)
		(end 332.93812 -372.384066)
		(width 0.14224)
		(layer "In15.Cu")
		(net "P5E_CPU0_P0_RX_DN<11>")
	)
	(segment
		(start 355.539802 -271.351756)
		(end 355.508814 -271.333976)
		(width 0.1143)
		(layer "In15.Cu")
		(net "P5E_CPU0_P0_RX_DN<11>")
	)
	(segment
		(start 355.508052 -282.673552)
		(end 355.505258 -282.671774)
		(width 0.1143)
		(layer "In15.Cu")
		(net "P5E_CPU0_P0_RX_DN<11>")
	)
	(segment
		(start 355.513894 -278.455374)
		(end 355.51491 -278.454866)
		(width 0.1143)
		(layer "In15.Cu")
		(net "P5E_CPU0_P0_RX_DN<11>")
	)
	(segment
		(start 346.11818 -371.665246)
		(end 338.81568 -371.665246)
		(width 0.14224)
		(layer "In15.Cu")
		(net "P5E_CPU0_P0_RX_DN<11>")
	)
	(segment
		(start 355.513894 -283.31541)
		(end 355.51491 -283.314902)
		(width 0.1143)
		(layer "In15.Cu")
		(net "P5E_CPU0_P0_RX_DN<11>")
	)
	(segment
		(start 355.509576 -275.21789)
		(end 355.510338 -275.217382)
		(width 0.1143)
		(layer "In15.Cu")
		(net "P5E_CPU0_P0_RX_DN<11>")
	)
	(segment
		(start 355.510338 -281.69743)
		(end 355.511354 -281.696922)
		(width 0.1143)
		(layer "In15.Cu")
		(net "P5E_CPU0_P0_RX_DN<11>")
	)
	(segment
		(start 334.07096 -372.384066)
		(end 334.49768 -372.384066)
		(width 0.14224)
		(layer "In15.Cu")
		(net "P5E_CPU0_P0_RX_DN<11>")
	)
	(segment
		(start 355.515672 -278.454358)
		(end 355.516688 -278.45385)
		(width 0.1143)
		(layer "In15.Cu")
		(net "P5E_CPU0_P0_RX_DN<11>")
	)
	(segment
		(start 355.508052 -284.938724)
		(end 355.539802 -284.920436)
		(width 0.1143)
		(layer "In15.Cu")
		(net "P5E_CPU0_P0_RX_DN<11>")
	)
	(segment
		(start 355.508052 -281.053286)
		(end 355.468428 -281.03068)
		(width 0.1143)
		(layer "In15.Cu")
		(net "P5E_CPU0_P0_RX_DN<11>")
	)
	(segment
		(start 355.510084 -273.59737)
		(end 355.539802 -273.580352)
		(width 0.1143)
		(layer "In15.Cu")
		(net "P5E_CPU0_P0_RX_DN<11>")
	)
	(segment
		(start 355.53904 -292.41115)
		(end 355.519228 -292.39972)
		(width 0.1143)
		(layer "In15.Cu")
		(net "P5E_CPU0_P0_RX_DN<11>")
	)
	(segment
		(start 336.0166 -372.384066)
		(end 336.15376 -372.521226)
		(width 0.14224)
		(layer "In15.Cu")
		(net "P5E_CPU0_P0_RX_DN<11>")
	)
	(segment
		(start 355.46919 -278.481282)
		(end 355.509576 -278.457914)
		(width 0.1143)
		(layer "In15.Cu")
		(net "P5E_CPU0_P0_RX_DN<11>")
	)
	(segment
		(start 355.505258 -279.43175)
		(end 355.46919 -279.410922)
		(width 0.1143)
		(layer "In15.Cu")
		(net "P5E_CPU0_P0_RX_DN<11>")
	)
	(segment
		(start 355.510084 -285.914846)
		(end 355.508814 -285.914084)
		(width 0.1143)
		(layer "In15.Cu")
		(net "P5E_CPU0_P0_RX_DN<11>")
	)
	(segment
		(start 354.997004 -296.421302)
		(end 354.849176 -296.273474)
		(width 0.1143)
		(layer "In15.Cu")
		(net "P5E_CPU0_P0_RX_DN<11>")
	)
	(segment
		(start 355.515672 -283.314394)
		(end 355.516688 -283.313886)
		(width 0.1143)
		(layer "In15.Cu")
		(net "P5E_CPU0_P0_RX_DN<11>")
	)
	(segment
		(start 355.513132 -276.83587)
		(end 355.513894 -276.835362)
		(width 0.1143)
		(layer "In15.Cu")
		(net "P5E_CPU0_P0_RX_DN<11>")
	)
	(segment
		(start 355.509576 -281.697938)
		(end 355.510338 -281.69743)
		(width 0.1143)
		(layer "In15.Cu")
		(net "P5E_CPU0_P0_RX_DN<11>")
	)
	(segment
		(start 355.511608 -290.77539)
		(end 355.510592 -290.774882)
		(width 0.1143)
		(layer "In15.Cu")
		(net "P5E_CPU0_P0_RX_DN<11>")
	)
	(segment
		(start 355.515164 -290.777422)
		(end 355.514148 -290.776914)
		(width 0.1143)
		(layer "In15.Cu")
		(net "P5E_CPU0_P0_RX_DN<11>")
	)
	(segment
		(start 355.539802 -276.211792)
		(end 355.510084 -276.194774)
		(width 0.1143)
		(layer "In15.Cu")
		(net "P5E_CPU0_P0_RX_DN<11>")
	)
	(segment
		(start 355.510084 -271.977358)
		(end 355.539802 -271.96034)
		(width 0.1143)
		(layer "In15.Cu")
		(net "P5E_CPU0_P0_RX_DN<11>")
	)
	(segment
		(start 355.508052 -291.418518)
		(end 355.529134 -291.406326)
		(width 0.1143)
		(layer "In15.Cu")
		(net "P5E_CPU0_P0_RX_DN<11>")
	)
	(segment
		(start 355.514148 -290.776914)
		(end 355.513386 -290.776406)
		(width 0.1143)
		(layer "In15.Cu")
		(net "P5E_CPU0_P0_RX_DN<11>")
	)
	(segment
		(start 355.508052 -281.05354)
		(end 355.508052 -281.053286)
		(width 0.1143)
		(layer "In15.Cu")
		(net "P5E_CPU0_P0_RX_DN<11>")
	)
	(segment
		(start 355.508052 -287.533588)
		(end 355.473254 -287.510728)
		(width 0.1143)
		(layer "In15.Cu")
		(net "P5E_CPU0_P0_RX_DN<11>")
	)
	(segment
		(start 395.769338 -354.649532)
		(end 395.767814 -354.528882)
		(width 0.14224)
		(layer "In15.Cu")
		(net "P5E_CPU0_P0_RX_DN<11>")
	)
	(segment
		(start 355.508814 -279.434036)
		(end 355.508052 -279.433528)
		(width 0.1143)
		(layer "In15.Cu")
		(net "P5E_CPU0_P0_RX_DN<11>")
	)
	(segment
		(start 355.539802 -284.311852)
		(end 355.510084 -284.294834)
		(width 0.1143)
		(layer "In15.Cu")
		(net "P5E_CPU0_P0_RX_DN<11>")
	)
	(segment
		(start 355.51237 -292.39591)
		(end 355.511608 -292.395402)
		(width 0.1143)
		(layer "In15.Cu")
		(net "P5E_CPU0_P0_RX_DN<11>")
	)
	(segment
		(start 355.539802 -282.69184)
		(end 355.510084 -282.674822)
		(width 0.1143)
		(layer "In15.Cu")
		(net "P5E_CPU0_P0_RX_DN<11>")
	)
	(segment
		(start 355.46919 -283.341318)
		(end 355.509576 -283.31795)
		(width 0.1143)
		(layer "In15.Cu")
		(net "P5E_CPU0_P0_RX_DN<11>")
	)
	(segment
		(start 336.15376 -372.521226)
		(end 346.11818 -372.521226)
		(width 0.14224)
		(layer "In15.Cu")
		(net "P5E_CPU0_P0_RX_DN<11>")
	)
	(segment
		(start 355.510338 -278.457406)
		(end 355.511354 -278.456898)
		(width 0.1143)
		(layer "In15.Cu")
		(net "P5E_CPU0_P0_RX_DN<11>")
	)
	(segment
		(start 354.755958 -296.048684)
		(end 354.755958 -295.93921)
		(width 0.1143)
		(layer "In15.Cu")
		(net "P5E_CPU0_P0_RX_DN<11>")
	)
	(segment
		(start 355.508052 -276.193504)
		(end 355.505258 -276.191726)
		(width 0.1143)
		(layer "In15.Cu")
		(net "P5E_CPU0_P0_RX_DN<11>")
	)
	(segment
		(start 355.510084 -294.014652)
		(end 355.508814 -294.01389)
		(width 0.1143)
		(layer "In15.Cu")
		(net "P5E_CPU0_P0_RX_DN<11>")
	)
	(segment
		(start 355.508814 -290.773866)
		(end 355.508052 -290.773358)
		(width 0.1143)
		(layer "In15.Cu")
		(net "P5E_CPU0_P0_RX_DN<11>")
	)
	(segment
		(start 338.50834 -370.552726)
		(end 338.81568 -370.245386)
		(width 0.14224)
		(layer "In15.Cu")
		(net "P5E_CPU0_P0_RX_DN<11>")
	)
	(segment
		(start 333.9338 -372.521226)
		(end 334.07096 -372.384066)
		(width 0.14224)
		(layer "In15.Cu")
		(net "P5E_CPU0_P0_RX_DN<11>")
	)
	(segment
		(start 354.7618 -270.11884)
		(end 354.678996 -270.036036)
		(width 0.1143)
		(layer "In15.Cu")
		(net "P5E_CPU0_P0_RX_DN<11>")
	)
	(segment
		(start 355.519228 -292.39972)
		(end 355.516688 -292.39845)
		(width 0.1143)
		(layer "In15.Cu")
		(net "P5E_CPU0_P0_RX_DN<11>")
	)
	(segment
		(start 355.509576 -283.31795)
		(end 355.510338 -283.317442)
		(width 0.1143)
		(layer "In15.Cu")
		(net "P5E_CPU0_P0_RX_DN<11>")
	)
	(segment
		(start 355.44125 -275.261324)
		(end 355.46919 -275.241258)
		(width 0.1143)
		(layer "In15.Cu")
		(net "P5E_CPU0_P0_RX_DN<11>")
	)
	(segment
		(start 355.508814 -271.333976)
		(end 355.508052 -271.333468)
		(width 0.1143)
		(layer "In15.Cu")
		(net "P5E_CPU0_P0_RX_DN<11>")
	)
	(segment
		(start 354.954332 -304.005488)
		(end 354.954332 -296.61231)
		(width 0.14224)
		(layer "In15.Cu")
		(net "P5E_CPU0_P0_RX_DN<11>")
	)
	(segment
		(start 355.508052 -271.333468)
		(end 355.47173 -271.312386)
		(width 0.1143)
		(layer "In15.Cu")
		(net "P5E_CPU0_P0_RX_DN<11>")
	)
	(segment
		(start 355.508052 -290.773358)
		(end 355.507798 -290.773358)
		(width 0.1143)
		(layer "In15.Cu")
		(net "P5E_CPU0_P0_RX_DN<11>")
	)
	(segment
		(start 355.539802 -290.791646)
		(end 355.51745 -290.778692)
		(width 0.1143)
		(layer "In15.Cu")
		(net "P5E_CPU0_P0_RX_DN<11>")
	)
	(segment
		(start 355.508052 -271.978628)
		(end 355.508814 -271.97812)
		(width 0.1143)
		(layer "In15.Cu")
		(net "P5E_CPU0_P0_RX_DN<11>")
	)
	(segment
		(start 355.47173 -286.579564)
		(end 355.54158 -286.538924)
		(width 0.1143)
		(layer "In15.Cu")
		(net "P5E_CPU0_P0_RX_DN<11>")
	)
	(segment
		(start 334.49768 -372.384066)
		(end 334.63484 -372.521226)
		(width 0.14224)
		(layer "In15.Cu")
		(net "P5E_CPU0_P0_RX_DN<11>")
	)
	(segment
		(start 355.50983 -292.394386)
		(end 355.508814 -292.393878)
		(width 0.1143)
		(layer "In15.Cu")
		(net "P5E_CPU0_P0_RX_DN<11>")
	)
	(segment
		(start 355.512116 -278.45639)
		(end 355.513132 -278.455882)
		(width 0.1143)
		(layer "In15.Cu")
		(net "P5E_CPU0_P0_RX_DN<11>")
	)
	(segment
		(start 355.513894 -281.695398)
		(end 355.51491 -281.69489)
		(width 0.1143)
		(layer "In15.Cu")
		(net "P5E_CPU0_P0_RX_DN<11>")
	)
	(segment
		(start 355.507798 -289.79876)
		(end 355.508052 -289.798506)
		(width 0.1143)
		(layer "In15.Cu")
		(net "P5E_CPU0_P0_RX_DN<11>")
	)
	(segment
		(start 355.508052 -289.798506)
		(end 355.529134 -289.786314)
		(width 0.1143)
		(layer "In15.Cu")
		(net "P5E_CPU0_P0_RX_DN<11>")
	)
	(segment
		(start 355.000052 -296.424096)
		(end 354.997004 -296.421302)
		(width 0.1143)
		(layer "In15.Cu")
		(net "P5E_CPU0_P0_RX_DN<11>")
	)
	(segment
		(start 355.510338 -275.217382)
		(end 355.511354 -275.216874)
		(width 0.1143)
		(layer "In15.Cu")
		(net "P5E_CPU0_P0_RX_DN<11>")
	)
	(segment
		(start 355.468428 -280.101548)
		(end 355.539802 -280.0604)
		(width 0.1143)
		(layer "In15.Cu")
		(net "P5E_CPU0_P0_RX_DN<11>")
	)
	(segment
		(start 355.513132 -281.695906)
		(end 355.513894 -281.695398)
		(width 0.1143)
		(layer "In15.Cu")
		(net "P5E_CPU0_P0_RX_DN<11>")
	)
	(segment
		(start 355.529896 -291.405818)
		(end 355.539802 -291.40023)
		(width 0.1143)
		(layer "In15.Cu")
		(net "P5E_CPU0_P0_RX_DN<11>")
	)
	(segment
		(start 355.508052 -277.813516)
		(end 355.505258 -277.811738)
		(width 0.1143)
		(layer "In15.Cu")
		(net "P5E_CPU0_P0_RX_DN<11>")
	)
	(segment
		(start 355.539802 -285.931864)
		(end 355.510084 -285.914846)
		(width 0.1143)
		(layer "In15.Cu")
		(net "P5E_CPU0_P0_RX_DN<11>")
	)
	(segment
		(start 355.539802 -287.551876)
		(end 355.508052 -287.533588)
		(width 0.1143)
		(layer "In15.Cu")
		(net "P5E_CPU0_P0_RX_DN<11>")
	)
	(segment
		(start 355.508052 -285.913576)
		(end 355.47173 -285.892494)
		(width 0.1143)
		(layer "In15.Cu")
		(net "P5E_CPU0_P0_RX_DN<11>")
	)
	(segment
		(start 355.000052 -296.538142)
		(end 355.000052 -296.424096)
		(width 0.1143)
		(layer "In15.Cu")
		(net "P5E_CPU0_P0_RX_DN<11>")
	)
	(segment
		(start 338.81568 -371.665246)
		(end 338.50834 -371.357906)
		(width 0.14224)
		(layer "In15.Cu")
		(net "P5E_CPU0_P0_RX_DN<11>")
	)
	(segment
		(start 355.513894 -276.835362)
		(end 355.539802 -276.820376)
		(width 0.1143)
		(layer "In15.Cu")
		(net "P5E_CPU0_P0_RX_DN<11>")
	)
	(segment
		(start 355.516688 -292.39845)
		(end 355.514148 -292.396926)
		(width 0.1143)
		(layer "In15.Cu")
		(net "P5E_CPU0_P0_RX_DN<11>")
	)
	(segment
		(start 395.769338 -366.309148)
		(end 395.769338 -354.649532)
		(width 0.14224)
		(layer "In15.Cu")
		(net "P5E_CPU0_P0_RX_DN<11>")
	)
	(segment
		(start 355.508814 -272.953988)
		(end 355.508052 -272.95348)
		(width 0.1143)
		(layer "In15.Cu")
		(net "P5E_CPU0_P0_RX_DN<11>")
	)
	(segment
		(start 355.511608 -292.395402)
		(end 355.510592 -292.394894)
		(width 0.1143)
		(layer "In15.Cu")
		(net "P5E_CPU0_P0_RX_DN<11>")
	)
	(segment
		(start 355.510338 -276.837394)
		(end 355.511354 -276.836886)
		(width 0.1143)
		(layer "In15.Cu")
		(net "P5E_CPU0_P0_RX_DN<11>")
	)
	(segment
		(start 355.508052 -293.03853)
		(end 355.539802 -293.020242)
		(width 0.1143)
		(layer "In15.Cu")
		(net "P5E_CPU0_P0_RX_DN<11>")
	)
	(segment
		(start 355.508814 -274.574)
		(end 355.508052 -274.573492)
		(width 0.1143)
		(layer "In15.Cu")
		(net "P5E_CPU0_P0_RX_DN<11>")
	)
	(segment
		(start 355.508052 -274.573492)
		(end 355.47173 -274.55241)
		(width 0.1143)
		(layer "In15.Cu")
		(net "P5E_CPU0_P0_RX_DN<11>")
	)
	(segment
		(start 355.507798 -291.418772)
		(end 355.508052 -291.418518)
		(width 0.1143)
		(layer "In15.Cu")
		(net "P5E_CPU0_P0_RX_DN<11>")
	)
	(segment
		(start 355.51491 -281.69489)
		(end 355.515672 -281.694382)
		(width 0.1143)
		(layer "In15.Cu")
		(net "P5E_CPU0_P0_RX_DN<11>")
	)
	(segment
		(start 355.473254 -293.993316)
		(end 355.47173 -293.9923)
		(width 0.1143)
		(layer "In15.Cu")
		(net "P5E_CPU0_P0_RX_DN<11>")
	)
	(segment
		(start 317.458344 -392.31316)
		(end 317.458344 -389.90524)
		(width 0.14224)
		(layer "In15.Cu")
		(net "P5E_CPU0_P0_RX_DN<11>")
	)
	(segment
		(start 355.00183 -270.502634)
		(end 354.999036 -270.500602)
		(width 0.1143)
		(layer "In15.Cu")
		(net "P5E_CPU0_P0_RX_DN<11>")
	)
	(segment
		(start 355.495098 -288.186114)
		(end 355.508052 -288.178494)
		(width 0.1143)
		(layer "In15.Cu")
		(net "P5E_CPU0_P0_RX_DN<11>")
	)
	(segment
		(start 355.510592 -290.774882)
		(end 355.50983 -290.774374)
		(width 0.1143)
		(layer "In15.Cu")
		(net "P5E_CPU0_P0_RX_DN<11>")
	)
	(segment
		(start 355.46919 -282.650946)
		(end 355.44125 -282.63088)
		(width 0.1143)
		(layer "In15.Cu")
		(net "P5E_CPU0_P0_RX_DN<11>")
	)
	(segment
		(start 355.539802 -277.831804)
		(end 355.510084 -277.814786)
		(width 0.1143)
		(layer "In15.Cu")
		(net "P5E_CPU0_P0_RX_DN<11>")
	)
	(segment
		(start 355.505258 -276.191726)
		(end 355.46919 -276.170898)
		(width 0.1143)
		(layer "In15.Cu")
		(net "P5E_CPU0_P0_RX_DN<11>")
	)
	(segment
		(start 321.352926 -379.389386)
		(end 320.79311 -378.82957)
		(width 0.14224)
		(layer "In15.Cu")
		(net "P5E_CPU0_P0_RX_DN<11>")
	)
	(segment
		(start 355.47173 -271.99971)
		(end 355.508052 -271.978628)
		(width 0.1143)
		(layer "In15.Cu")
		(net "P5E_CPU0_P0_RX_DN<11>")
	)
	(segment
		(start 355.510084 -276.194774)
		(end 355.508814 -276.194012)
		(width 0.1143)
		(layer "In15.Cu")
		(net "P5E_CPU0_P0_RX_DN<11>")
	)
	(segment
		(start 355.510084 -284.294834)
		(end 355.508814 -284.294072)
		(width 0.1143)
		(layer "In15.Cu")
		(net "P5E_CPU0_P0_RX_DN<11>")
	)
	(segment
		(start 355.508052 -284.293564)
		(end 355.505258 -284.291786)
		(width 0.1143)
		(layer "In15.Cu")
		(net "P5E_CPU0_P0_RX_DN<11>")
	)
	(segment
		(start 355.511354 -281.696922)
		(end 355.512116 -281.696414)
		(width 0.1143)
		(layer "In15.Cu")
		(net "P5E_CPU0_P0_RX_DN<11>")
	)
	(segment
		(start 355.511608 -294.015414)
		(end 355.510084 -294.014652)
		(width 0.1143)
		(layer "In15.Cu")
		(net "P5E_CPU0_P0_RX_DN<11>")
	)
	(segment
		(start 317.466472 -393.545822)
		(end 317.14948 -393.22883)
		(width 0.14224)
		(layer "In15.Cu")
		(net "P5E_CPU0_P0_RX_DN<11>")
	)
	(segment
		(start 395.235176 -353.285806)
		(end 368.20856 -326.809608)
		(width 0.14224)
		(layer "In15.Cu")
		(net "P5E_CPU0_P0_RX_DN<11>")
	)
	(segment
		(start 355.539802 -274.59178)
		(end 355.510084 -274.574762)
		(width 0.1143)
		(layer "In15.Cu")
		(net "P5E_CPU0_P0_RX_DN<11>")
	)
	(segment
		(start 355.47173 -284.959806)
		(end 355.508052 -284.938724)
		(width 0.1143)
		(layer "In15.Cu")
		(net "P5E_CPU0_P0_RX_DN<11>")
	)
	(segment
		(start 317.344806 -393.786868)
		(end 317.466472 -393.716764)
		(width 0.14224)
		(layer "In15.Cu")
		(net "P5E_CPU0_P0_RX_DN<11>")
	)
	(segment
		(start 377.664218 -370.198142)
		(end 379.412754 -368.449606)
		(width 0.14224)
		(layer "In15.Cu")
		(net "P5E_CPU0_P0_RX_DN<11>")
	)
	(segment
		(start 346.24518 -371.792246)
		(end 346.11818 -371.665246)
		(width 0.14224)
		(layer "In15.Cu")
		(net "P5E_CPU0_P0_RX_DN<11>")
	)
	(segment
		(start 320.179954 -378.64542)
		(end 320.091816 -378.557282)
		(width 0.14224)
		(layer "In15.Cu")
		(net "P5E_CPU0_P0_RX_DN<11>")
	)
	(segment
		(start 334.63484 -372.521226)
		(end 335.45272 -372.521226)
		(width 0.14224)
		(layer "In15.Cu")
		(net "P5E_CPU0_P0_RX_DN<11>")
	)
	(segment
		(start 355.44125 -281.741372)
		(end 355.46919 -281.721306)
		(width 0.1143)
		(layer "In15.Cu")
		(net "P5E_CPU0_P0_RX_DN<11>")
	)
	(segment
		(start 355.513132 -283.315918)
		(end 355.513894 -283.31541)
		(width 0.1143)
		(layer "In15.Cu")
		(net "P5E_CPU0_P0_RX_DN<11>")
	)
	(segment
		(start 355.508814 -282.67406)
		(end 355.508052 -282.673552)
		(width 0.1143)
		(layer "In15.Cu")
		(net "P5E_CPU0_P0_RX_DN<11>")
	)
	(segment
		(start 355.508814 -271.97812)
		(end 355.510084 -271.977358)
		(width 0.1143)
		(layer "In15.Cu")
		(net "P5E_CPU0_P0_RX_DN<11>")
	)
	(segment
		(start 355.441504 -280.121106)
		(end 355.468428 -280.101548)
		(width 0.1143)
		(layer "In15.Cu")
		(net "P5E_CPU0_P0_RX_DN<11>")
	)
	(segment
		(start 355.46919 -284.270958)
		(end 355.44125 -284.250892)
		(width 0.1143)
		(layer "In15.Cu")
		(net "P5E_CPU0_P0_RX_DN<11>")
	)
	(segment
		(start 355.46919 -275.241258)
		(end 355.509576 -275.21789)
		(width 0.1143)
		(layer "In15.Cu")
		(net "P5E_CPU0_P0_RX_DN<11>")
	)
	(segment
		(start 355.50983 -290.774374)
		(end 355.508814 -290.773866)
		(width 0.1143)
		(layer "In15.Cu")
		(net "P5E_CPU0_P0_RX_DN<11>")
	)
	(segment
		(start 317.712598 -389.291322)
		(end 320.927222 -386.076698)
		(width 0.14224)
		(layer "In15.Cu")
		(net "P5E_CPU0_P0_RX_DN<11>")
	)
	(segment
		(start 355.508814 -273.598132)
		(end 355.510084 -273.59737)
		(width 0.1143)
		(layer "In15.Cu")
		(net "P5E_CPU0_P0_RX_DN<11>")
	)
	(segment
		(start 355.539802 -281.071828)
		(end 355.508052 -281.05354)
		(width 0.1143)
		(layer "In15.Cu")
		(net "P5E_CPU0_P0_RX_DN<11>")
	)
	(segment
		(start 355.539802 -289.171634)
		(end 355.495098 -289.145726)
		(width 0.1143)
		(layer "In15.Cu")
		(net "P5E_CPU0_P0_RX_DN<11>")
	)
	(segment
		(start 355.46919 -281.721306)
		(end 355.509576 -281.697938)
		(width 0.1143)
		(layer "In15.Cu")
		(net "P5E_CPU0_P0_RX_DN<11>")
	)
	(segment
		(start 355.512116 -281.696414)
		(end 355.513132 -281.695906)
		(width 0.1143)
		(layer "In15.Cu")
		(net "P5E_CPU0_P0_RX_DN<11>")
	)
	(segment
		(start 338.50834 -371.357906)
		(end 338.50834 -370.552726)
		(width 0.14224)
		(layer "In15.Cu")
		(net "P5E_CPU0_P0_RX_DN<11>")
	)
	(segment
		(start 355.529896 -289.785806)
		(end 355.539802 -289.780218)
		(width 0.1143)
		(layer "In15.Cu")
		(net "P5E_CPU0_P0_RX_DN<11>")
	)
	(segment
		(start 355.512116 -276.836378)
		(end 355.513132 -276.83587)
		(width 0.1143)
		(layer "In15.Cu")
		(net "P5E_CPU0_P0_RX_DN<11>")
	)
	(segment
		(start 328.820018 -374.997726)
		(end 331.166724 -372.65102)
		(width 0.14224)
		(layer "In15.Cu")
		(net "P5E_CPU0_P0_RX_DN<11>")
	)
	(segment
		(start 355.508052 -272.95348)
		(end 355.47173 -272.932398)
		(width 0.1143)
		(layer "In15.Cu")
		(net "P5E_CPU0_P0_RX_DN<11>")
	)
	(segment
		(start 317.466472 -393.716764)
		(end 317.466472 -393.545822)
		(width 0.14224)
		(layer "In15.Cu")
		(net "P5E_CPU0_P0_RX_DN<11>")
	)
	(segment
		(start 355.508814 -285.914084)
		(end 355.508052 -285.913576)
		(width 0.1143)
		(layer "In15.Cu")
		(net "P5E_CPU0_P0_RX_DN<11>")
	)
	(segment
		(start 355.508052 -288.178494)
		(end 355.54158 -288.158936)
		(width 0.1143)
		(layer "In15.Cu")
		(net "P5E_CPU0_P0_RX_DN<11>")
	)
	(segment
		(start 355.508052 -279.433528)
		(end 355.505258 -279.43175)
		(width 0.1143)
		(layer "In15.Cu")
		(net "P5E_CPU0_P0_RX_DN<11>")
	)
	(segment
		(start 355.44125 -283.361384)
		(end 355.46919 -283.341318)
		(width 0.1143)
		(layer "In15.Cu")
		(net "P5E_CPU0_P0_RX_DN<11>")
	)
	(segment
		(start 355.511354 -283.316934)
		(end 355.512116 -283.316426)
		(width 0.1143)
		(layer "In15.Cu")
		(net "P5E_CPU0_P0_RX_DN<11>")
	)
	(segment
		(start 354.678996 -270.036036)
		(end 354.381054 -270.036036)
		(width 0.1143)
		(layer "In15.Cu")
		(net "P5E_CPU0_P0_RX_DN<11>")
	)
	(segment
		(start 354.954332 -296.61231)
		(end 354.954332 -296.583862)
		(width 0.1143)
		(layer "In15.Cu")
		(net "P5E_CPU0_P0_RX_DN<11>")
	)
	(segment
		(start 355.473254 -287.510728)
		(end 355.352604 -287.389824)
		(width 0.1143)
		(layer "In15.Cu")
		(net "P5E_CPU0_P0_RX_DN<11>")
	)
	(segment
		(start 317.14948 -393.22883)
		(end 317.154306 -392.616944)
		(width 0.14224)
		(layer "In15.Cu")
		(net "P5E_CPU0_P0_RX_DN<11>")
	)
	(segment
		(start 355.51491 -294.017446)
		(end 355.51237 -294.015922)
		(width 0.1143)
		(layer "In15.Cu")
		(net "P5E_CPU0_P0_RX_DN<11>")
	)
	(segment
		(start 355.510338 -283.317442)
		(end 355.511354 -283.316934)
		(width 0.1143)
		(layer "In15.Cu")
		(net "P5E_CPU0_P0_RX_DN<11>")
	)
	(segment
		(start 355.511354 -275.216874)
		(end 355.512116 -275.216366)
		(width 0.1143)
		(layer "In15.Cu")
		(net "P5E_CPU0_P0_RX_DN<11>")
	)
	(segment
		(start 333.36484 -372.384066)
		(end 333.502 -372.521226)
		(width 0.14224)
		(layer "In15.Cu")
		(net "P5E_CPU0_P0_RX_DN<11>")
	)
	(segment
		(start 355.46919 -277.79091)
		(end 355.44125 -277.770844)
		(width 0.1143)
		(layer "In15.Cu")
		(net "P5E_CPU0_P0_RX_DN<11>")
	)
	(segment
		(start 355.510084 -279.434798)
		(end 355.508814 -279.434036)
		(width 0.1143)
		(layer "In15.Cu")
		(net "P5E_CPU0_P0_RX_DN<11>")
	)
	(segment
		(start 355.468428 -281.03068)
		(end 355.441504 -281.011122)
		(width 0.1143)
		(layer "In15.Cu")
		(net "P5E_CPU0_P0_RX_DN<11>")
	)
	(segment
		(start 355.508052 -294.013382)
		(end 355.473254 -293.993316)
		(width 0.1143)
		(layer "In15.Cu")
		(net "P5E_CPU0_P0_RX_DN<11>")
	)
	(segment
		(start 355.509576 -276.837902)
		(end 355.510338 -276.837394)
		(width 0.1143)
		(layer "In15.Cu")
		(net "P5E_CPU0_P0_RX_DN<11>")
	)
	(segment
		(start 355.51237 -290.775898)
		(end 355.511608 -290.77539)
		(width 0.1143)
		(layer "In15.Cu")
		(net "P5E_CPU0_P0_RX_DN<11>")
	)
	(segment
		(start 355.060504 -270.536416)
		(end 355.00183 -270.502634)
		(width 0.1143)
		(layer "In15.Cu")
		(net "P5E_CPU0_P0_RX_DN<11>")
	)
	(segment
		(start 323.19849 -375.035064)
		(end 328.730102 -375.035064)
		(width 0.14224)
		(layer "In15.Cu")
		(net "P5E_CPU0_P0_RX_DN<11>")
	)
	(segment
		(start 355.514148 -292.396926)
		(end 355.513386 -292.396418)
		(width 0.1143)
		(layer "In15.Cu")
		(net "P5E_CPU0_P0_RX_DN<11>")
	)
	(segment
		(start 335.58988 -372.384066)
		(end 336.0166 -372.384066)
		(width 0.14224)
		(layer "In15.Cu")
		(net "P5E_CPU0_P0_RX_DN<11>")
	)
	(segment
		(start 355.508814 -294.01389)
		(end 355.508052 -294.013382)
		(width 0.1143)
		(layer "In15.Cu")
		(net "P5E_CPU0_P0_RX_DN<11>")
	)
	(segment
		(start 338.81568 -370.245386)
		(end 377.550172 -370.245386)
		(width 0.14224)
		(layer "In15.Cu")
		(net "P5E_CPU0_P0_RX_DN<11>")
	)
	(segment
		(start 355.513386 -290.776406)
		(end 355.51237 -290.775898)
		(width 0.1143)
		(layer "In15.Cu")
		(net "P5E_CPU0_P0_RX_DN<11>")
	)
	(segment
		(start 355.509576 -278.457914)
		(end 355.510338 -278.457406)
		(width 0.1143)
		(layer "In15.Cu")
		(net "P5E_CPU0_P0_RX_DN<11>")
	)
	(segment
		(start 355.51491 -278.454866)
		(end 355.515672 -278.454358)
		(width 0.1143)
		(layer "In15.Cu")
		(net "P5E_CPU0_P0_RX_DN<11>")
	)
	(segment
		(start 346.24518 -372.394226)
		(end 346.24518 -371.792246)
		(width 0.14224)
		(layer "In15.Cu")
		(net "P5E_CPU0_P0_RX_DN<11>")
	)
	(segment
		(start 355.505258 -284.291786)
		(end 355.46919 -284.270958)
		(width 0.1143)
		(layer "In15.Cu")
		(net "P5E_CPU0_P0_RX_DN<11>")
	)
	(segment
		(start 355.508052 -273.59864)
		(end 355.508814 -273.598132)
		(width 0.1143)
		(layer "In15.Cu")
		(net "P5E_CPU0_P0_RX_DN<11>")
	)
	(segment
		(start 354.987098 -295.498266)
		(end 355.057202 -295.457626)
		(width 0.1143)
		(layer "In15.Cu")
		(net "P5E_CPU0_P0_RX_DN<11>")
	)
	(segment
		(start 355.513132 -278.455882)
		(end 355.513894 -278.455374)
		(width 0.1143)
		(layer "In15.Cu")
		(net "P5E_CPU0_P0_RX_DN<11>")
	)
	(segment
		(start 355.512116 -275.216366)
		(end 355.514656 -275.215096)
		(width 0.1143)
		(layer "In15.Cu")
		(net "P5E_CPU0_P0_RX_DN<11>")
	)
	(segment
		(start 355.539802 -292.411658)
		(end 355.53904 -292.41115)
		(width 0.1143)
		(layer "In15.Cu")
		(net "P5E_CPU0_P0_RX_DN<11>")
	)
	(segment
		(start 355.515418 -275.214588)
		(end 355.539802 -275.200364)
		(width 0.1143)
		(layer "In15.Cu")
		(net "P5E_CPU0_P0_RX_DN<11>")
	)
	(segment
		(start 355.508814 -276.194012)
		(end 355.508052 -276.193504)
		(width 0.1143)
		(layer "In15.Cu")
		(net "P5E_CPU0_P0_RX_DN<11>")
	)
	(segment
		(start 320.44132 -376.143012)
		(end 323.041772 -375.066052)
		(width 0.14224)
		(layer "In15.Cu")
		(net "P5E_CPU0_P0_RX_DN<11>")
	)
	(segment
		(start 355.46919 -276.170898)
		(end 355.44125 -276.150832)
		(width 0.1143)
		(layer "In15.Cu")
		(net "P5E_CPU0_P0_RX_DN<11>")
	)
	(segment
		(start 395.0208 -367.766092)
		(end 395.26845 -367.518442)
		(width 0.14224)
		(layer "In15.Cu")
		(net "P5E_CPU0_P0_RX_DN<11>")
	)
	(segment
		(start 355.508814 -284.294072)
		(end 355.508052 -284.293564)
		(width 0.1143)
		(layer "In15.Cu")
		(net "P5E_CPU0_P0_RX_DN<11>")
	)
	(segment
		(start 355.508814 -277.814024)
		(end 355.508052 -277.813516)
		(width 0.1143)
		(layer "In15.Cu")
		(net "P5E_CPU0_P0_RX_DN<11>")
	)
	(segment
		(start 354.954332 -296.583862)
		(end 355.000052 -296.538142)
		(width 0.1143)
		(layer "In15.Cu")
		(net "P5E_CPU0_P0_RX_DN<11>")
	)
	(segment
		(start 355.515672 -281.694382)
		(end 355.516688 -281.693874)
		(width 0.1143)
		(layer "In15.Cu")
		(net "P5E_CPU0_P0_RX_DN<11>")
	)
	(segment
		(start 346.11818 -372.521226)
		(end 346.24518 -372.394226)
		(width 0.14224)
		(layer "In15.Cu")
		(net "P5E_CPU0_P0_RX_DN<11>")
	)
	(segment
		(start 355.51491 -283.314902)
		(end 355.515672 -283.314394)
		(width 0.1143)
		(layer "In15.Cu")
		(net "P5E_CPU0_P0_RX_DN<11>")
	)
	(segment
		(start 355.505258 -282.671774)
		(end 355.46919 -282.650946)
		(width 0.1143)
		(layer "In15.Cu")
		(net "P5E_CPU0_P0_RX_DN<11>")
	)
	(segment
		(start 332.93812 -372.384066)
		(end 333.36484 -372.384066)
		(width 0.14224)
		(layer "In15.Cu")
		(net "P5E_CPU0_P0_RX_DN<11>")
	)
	(segment
		(start 320.64706 -378.768864)
		(end 320.322956 -378.704348)
		(width 0.14224)
		(layer "In15.Cu")
		(net "P5E_CPU0_P0_RX_DN<11>")
	)
	(segment
		(start 355.539802 -279.451816)
		(end 355.510084 -279.434798)
		(width 0.1143)
		(layer "In15.Cu")
		(net "P5E_CPU0_P0_RX_DN<11>")
	)
	(segment
		(start 317.344298 -393.787376)
		(end 317.344806 -393.786868)
		(width 0.14224)
		(layer "In15.Cu")
		(net "P5E_CPU0_P0_RX_DN<11>")
	)
	(segment
		(start 355.47173 -293.059612)
		(end 355.508052 -293.03853)
		(width 0.1143)
		(layer "In15.Cu")
		(net "P5E_CPU0_P0_RX_DN<11>")
	)
	(segment
		(start 317.154306 -392.616944)
		(end 317.458344 -392.31316)
		(width 0.14224)
		(layer "In15.Cu")
		(net "P5E_CPU0_P0_RX_DN<11>")
	)
	(segment
		(start 355.505258 -277.811738)
		(end 355.46919 -277.79091)
		(width 0.1143)
		(layer "In15.Cu")
		(net "P5E_CPU0_P0_RX_DN<11>")
	)
	(segment
		(start 355.511354 -276.836886)
		(end 355.512116 -276.836378)
		(width 0.1143)
		(layer "In15.Cu")
		(net "P5E_CPU0_P0_RX_DN<11>")
	)
	(segment
		(start 355.51237 -294.015922)
		(end 355.511608 -294.015414)
		(width 0.1143)
		(layer "In15.Cu")
		(net "P5E_CPU0_P0_RX_DN<11>")
	)
	(segment
		(start 355.46919 -279.410922)
		(end 355.44125 -279.390856)
		(width 0.1143)
		(layer "In15.Cu")
		(net "P5E_CPU0_P0_RX_DN<11>")
	)
	(segment
		(start 355.511354 -278.456898)
		(end 355.512116 -278.45639)
		(width 0.1143)
		(layer "In15.Cu")
		(net "P5E_CPU0_P0_RX_DN<11>")
	)
	(segment
		(start 355.508814 -292.393878)
		(end 355.508052 -292.39337)
		(width 0.1143)
		(layer "In15.Cu")
		(net "P5E_CPU0_P0_RX_DN<11>")
	)
	(segment
		(start 355.516688 -281.693874)
		(end 355.539802 -281.680412)
		(width 0.1143)
		(layer "In15.Cu")
		(net "P5E_CPU0_P0_RX_DN<11>")
	)
	(segment
		(start 355.510592 -292.394894)
		(end 355.50983 -292.394386)
		(width 0.1143)
		(layer "In15.Cu")
		(net "P5E_CPU0_P0_RX_DN<11>")
	)
	(segment
		(start 355.539802 -272.971768)
		(end 355.508814 -272.953988)
		(width 0.1143)
		(layer "In15.Cu")
		(net "P5E_CPU0_P0_RX_DN<11>")
	)
	(segment
		(start 355.529134 -289.786314)
		(end 355.529896 -289.785806)
		(width 0.1143)
		(layer "In15.Cu")
		(net "P5E_CPU0_P0_RX_DN<11>")
	)
	(segment
		(start 355.516688 -278.45385)
		(end 355.539802 -278.440388)
		(width 0.1143)
		(layer "In15.Cu")
		(net "P5E_CPU0_P0_RX_DN<11>")
	)
	(segment
		(start 367.700814 -326.157336)
		(end 355.090476 -304.510694)
		(width 0.14224)
		(layer "In15.Cu")
		(net "P5E_CPU0_P0_RX_DN<11>")
	)
	(segment
		(start 335.45272 -372.521226)
		(end 335.58988 -372.384066)
		(width 0.14224)
		(layer "In15.Cu")
		(net "P5E_CPU0_P0_RX_DN<11>")
	)
	(segment
		(start 355.514656 -275.215096)
		(end 355.515418 -275.214588)
		(width 0.1143)
		(layer "In15.Cu")
		(net "P5E_CPU0_P0_RX_DN<11>")
	)
	(segment
		(start 355.516688 -283.313886)
		(end 355.539802 -283.300424)
		(width 0.1143)
		(layer "In15.Cu")
		(net "P5E_CPU0_P0_RX_DN<11>")
	)
	(segment
		(start 320.322956 -378.704348)
		(end 320.179954 -378.64542)
		(width 0.14224)
		(layer "In15.Cu")
		(net "P5E_CPU0_P0_RX_DN<11>")
	)
	(segment
		(start 355.510084 -274.574762)
		(end 355.508814 -274.574)
		(width 0.1143)
		(layer "In15.Cu")
		(net "P5E_CPU0_P0_RX_DN<11>")
	)
	(segment
		(start 355.228652 -287.090358)
		(end 355.228652 -286.989774)
		(width 0.1143)
		(layer "In15.Cu")
		(net "P5E_CPU0_P0_RX_DN<11>")
	)
	(segment
		(start 379.726444 -368.319812)
		(end 393.684252 -368.319812)
		(width 0.14224)
		(layer "In15.Cu")
		(net "P5E_CPU0_P0_RX_DN<11>")
	)
	(segment
		(start 355.510084 -282.674822)
		(end 355.508814 -282.67406)
		(width 0.1143)
		(layer "In15.Cu")
		(net "P5E_CPU0_P0_RX_DN<11>")
	)
	(segment
		(start 320.79311 -378.82957)
		(end 320.64706 -378.768864)
		(width 0.14224)
		(layer "In15.Cu")
		(net "P5E_CPU0_P0_RX_DN<11>")
	)
	(segment
		(start 355.47173 -273.619722)
		(end 355.473254 -273.618706)
		(width 0.1143)
		(layer "In15.Cu")
		(net "P5E_CPU0_P0_RX_DN<11>")
	)
	(segment
		(start 355.529134 -291.406326)
		(end 355.529896 -291.405818)
		(width 0.1143)
		(layer "In15.Cu")
		(net "P5E_CPU0_P0_RX_DN<11>")
	)
	(segment
		(start 355.44125 -278.501348)
		(end 355.46919 -278.481282)
		(width 0.1143)
		(layer "In15.Cu")
		(net "P5E_CPU0_P0_RX_DN<11>")
	)
	(segment
		(start 355.512116 -283.316426)
		(end 355.513132 -283.315918)
		(width 0.1143)
		(layer "In15.Cu")
		(net "P5E_CPU0_P0_RX_DN<11>")
	)
	(arc
		(start 395.26845 -367.518442)
		(mid 395.639175 -366.963613)
		(end 395.769338 -366.309148)
		(width 0.14224)
		(layer "In15.Cu")
		(net "P5E_CPU0_P0_RX_DN<11>")
	)
	(arc
		(start 323.041772 -375.066052)
		(mid 323.118606 -375.042849)
		(end 323.19849 -375.035064)
		(width 0.14224)
		(layer "In15.Cu")
		(net "P5E_CPU0_P0_RX_DN<11>")
	)
	(arc
		(start 355.695758 -287.856168)
		(mid 355.654503 -287.685197)
		(end 355.539802 -287.551876)
		(width 0.1143)
		(layer "In15.Cu")
		(net "P5E_CPU0_P0_RX_DN<11>")
	)
	(arc
		(start 355.44125 -277.770844)
		(mid 355.21325 -277.32609)
		(end 355.44125 -276.881336)
		(width 0.1143)
		(layer "In15.Cu")
		(net "P5E_CPU0_P0_RX_DN<11>")
	)
	(arc
		(start 355.47173 -285.892494)
		(mid 355.464066 -285.887223)
		(end 355.45649 -285.881826)
		(width 0.1143)
		(layer "In15.Cu")
		(net "P5E_CPU0_P0_RX_DN<11>")
	)
	(arc
		(start 355.539802 -294.640254)
		(mid 355.69573 -294.335962)
		(end 355.539802 -294.03167)
		(width 0.1143)
		(layer "In15.Cu")
		(net "P5E_CPU0_P0_RX_DN<11>")
	)
	(arc
		(start 355.539802 -293.020242)
		(mid 355.69573 -292.71595)
		(end 355.539802 -292.411658)
		(width 0.1143)
		(layer "In15.Cu")
		(net "P5E_CPU0_P0_RX_DN<11>")
	)
	(arc
		(start 320.308478 -376.231912)
		(mid 320.370532 -376.18094)
		(end 320.44132 -376.143012)
		(width 0.14224)
		(layer "In15.Cu")
		(net "P5E_CPU0_P0_RX_DN<11>")
	)
	(arc
		(start 355.441504 -281.011122)
		(mid 355.213826 -280.566114)
		(end 355.441504 -280.121106)
		(width 0.1143)
		(layer "In15.Cu")
		(net "P5E_CPU0_P0_RX_DN<11>")
	)
	(arc
		(start 320.091816 -378.557282)
		(mid 319.821695 -378.153018)
		(end 319.726818 -377.676156)
		(width 0.14224)
		(layer "In15.Cu")
		(net "P5E_CPU0_P0_RX_DN<11>")
	)
	(arc
		(start 355.213158 -295.153334)
		(mid 355.288138 -294.87285)
		(end 355.493066 -294.667178)
		(width 0.1143)
		(layer "In15.Cu")
		(net "P5E_CPU0_P0_RX_DN<11>")
	)
	(arc
		(start 354.76561 -270.1417)
		(mid 354.763587 -270.13029)
		(end 354.7618 -270.11884)
		(width 0.1143)
		(layer "In15.Cu")
		(net "P5E_CPU0_P0_RX_DN<11>")
	)
	(arc
		(start 355.539802 -284.920436)
		(mid 355.69573 -284.616144)
		(end 355.539802 -284.311852)
		(width 0.1143)
		(layer "In15.Cu")
		(net "P5E_CPU0_P0_RX_DN<11>")
	)
	(arc
		(start 355.539802 -283.300424)
		(mid 355.69573 -282.996132)
		(end 355.539802 -282.69184)
		(width 0.1143)
		(layer "In15.Cu")
		(net "P5E_CPU0_P0_RX_DN<11>")
	)
	(arc
		(start 355.44125 -282.63088)
		(mid 355.21325 -282.186126)
		(end 355.44125 -281.741372)
		(width 0.1143)
		(layer "In15.Cu")
		(net "P5E_CPU0_P0_RX_DN<11>")
	)
	(arc
		(start 355.47173 -293.9923)
		(mid 355.464066 -293.987029)
		(end 355.45649 -293.981632)
		(width 0.1143)
		(layer "In15.Cu")
		(net "P5E_CPU0_P0_RX_DN<11>")
	)
	(arc
		(start 355.507798 -290.773358)
		(mid 355.227371 -290.286122)
		(end 355.507798 -289.79876)
		(width 0.1143)
		(layer "In15.Cu")
		(net "P5E_CPU0_P0_RX_DN<11>")
	)
	(arc
		(start 379.412754 -368.449606)
		(mid 379.556677 -368.35347)
		(end 379.726444 -368.319812)
		(width 0.14224)
		(layer "In15.Cu")
		(net "P5E_CPU0_P0_RX_DN<11>")
	)
	(arc
		(start 355.223318 -270.835882)
		(mid 355.168414 -270.671745)
		(end 355.060504 -270.536416)
		(width 0.1143)
		(layer "In15.Cu")
		(net "P5E_CPU0_P0_RX_DN<11>")
	)
	(arc
		(start 355.47173 -272.932398)
		(mid 355.464066 -272.927127)
		(end 355.45649 -272.92173)
		(width 0.1143)
		(layer "In15.Cu")
		(net "P5E_CPU0_P0_RX_DN<11>")
	)
	(arc
		(start 355.45649 -293.07028)
		(mid 355.464066 -293.064884)
		(end 355.47173 -293.059612)
		(width 0.1143)
		(layer "In15.Cu")
		(net "P5E_CPU0_P0_RX_DN<11>")
	)
	(arc
		(start 317.458344 -389.90524)
		(mid 317.524415 -389.572991)
		(end 317.712598 -389.291322)
		(width 0.14224)
		(layer "In15.Cu")
		(net "P5E_CPU0_P0_RX_DN<11>")
	)
	(arc
		(start 355.495098 -289.145726)
		(mid 355.218765 -288.66592)
		(end 355.495098 -288.186114)
		(width 0.1143)
		(layer "In15.Cu")
		(net "P5E_CPU0_P0_RX_DN<11>")
	)
	(arc
		(start 355.44125 -279.390856)
		(mid 355.21325 -278.946102)
		(end 355.44125 -278.501348)
		(width 0.1143)
		(layer "In15.Cu")
		(net "P5E_CPU0_P0_RX_DN<11>")
	)
	(arc
		(start 355.225604 -270.86433)
		(mid 355.224872 -270.850073)
		(end 355.223318 -270.835882)
		(width 0.1143)
		(layer "In15.Cu")
		(net "P5E_CPU0_P0_RX_DN<11>")
	)
	(arc
		(start 355.45649 -284.970474)
		(mid 355.464066 -284.965078)
		(end 355.47173 -284.959806)
		(width 0.1143)
		(layer "In15.Cu")
		(net "P5E_CPU0_P0_RX_DN<11>")
	)
	(arc
		(start 355.45649 -273.63039)
		(mid 355.464066 -273.624994)
		(end 355.47173 -273.619722)
		(width 0.1143)
		(layer "In15.Cu")
		(net "P5E_CPU0_P0_RX_DN<11>")
	)
	(arc
		(start 354.755958 -295.93921)
		(mid 354.817243 -295.690281)
		(end 354.987098 -295.498266)
		(width 0.1143)
		(layer "In15.Cu")
		(net "P5E_CPU0_P0_RX_DN<11>")
	)
	(arc
		(start 355.539802 -276.820376)
		(mid 355.69573 -276.516084)
		(end 355.539802 -276.211792)
		(width 0.1143)
		(layer "In15.Cu")
		(net "P5E_CPU0_P0_RX_DN<11>")
	)
	(arc
		(start 355.352604 -287.389824)
		(mid 355.260852 -287.252414)
		(end 355.228652 -287.090358)
		(width 0.1143)
		(layer "In15.Cu")
		(net "P5E_CPU0_P0_RX_DN<11>")
	)
	(arc
		(start 355.47173 -271.312386)
		(mid 355.466374 -271.308735)
		(end 355.461062 -271.30502)
		(width 0.1143)
		(layer "In15.Cu")
		(net "P5E_CPU0_P0_RX_DN<11>")
	)
	(arc
		(start 354.999036 -270.500602)
		(mid 354.847049 -270.344094)
		(end 354.76561 -270.1417)
		(width 0.1143)
		(layer "In15.Cu")
		(net "P5E_CPU0_P0_RX_DN<11>")
	)
	(arc
		(start 319.726818 -376.983244)
		(mid 319.75797 -376.826541)
		(end 319.846706 -376.693684)
		(width 0.14224)
		(layer "In15.Cu")
		(net "P5E_CPU0_P0_RX_DN<11>")
	)
	(arc
		(start 355.539802 -271.96034)
		(mid 355.69573 -271.656048)
		(end 355.539802 -271.351756)
		(width 0.1143)
		(layer "In15.Cu")
		(net "P5E_CPU0_P0_RX_DN<11>")
	)
	(arc
		(start 355.47173 -274.55241)
		(mid 355.464066 -274.547139)
		(end 355.45649 -274.541742)
		(width 0.1143)
		(layer "In15.Cu")
		(net "P5E_CPU0_P0_RX_DN<11>")
	)
	(arc
		(start 355.539802 -281.680412)
		(mid 355.69573 -281.37612)
		(end 355.539802 -281.071828)
		(width 0.1143)
		(layer "In15.Cu")
		(net "P5E_CPU0_P0_RX_DN<11>")
	)
	(arc
		(start 355.45649 -285.881826)
		(mid 355.231319 -285.42615)
		(end 355.45649 -284.970474)
		(width 0.1143)
		(layer "In15.Cu")
		(net "P5E_CPU0_P0_RX_DN<11>")
	)
	(arc
		(start 355.057202 -295.457626)
		(mid 355.171878 -295.324292)
		(end 355.213158 -295.153334)
		(width 0.1143)
		(layer "In15.Cu")
		(net "P5E_CPU0_P0_RX_DN<11>")
	)
	(arc
		(start 355.539802 -291.40023)
		(mid 355.69573 -291.095938)
		(end 355.539802 -290.791646)
		(width 0.1143)
		(layer "In15.Cu")
		(net "P5E_CPU0_P0_RX_DN<11>")
	)
	(arc
		(start 355.695758 -286.236156)
		(mid 355.654503 -286.065185)
		(end 355.539802 -285.931864)
		(width 0.1143)
		(layer "In15.Cu")
		(net "P5E_CPU0_P0_RX_DN<11>")
	)
	(arc
		(start 355.228652 -286.989774)
		(mid 355.304818 -286.757785)
		(end 355.47173 -286.579564)
		(width 0.1143)
		(layer "In15.Cu")
		(net "P5E_CPU0_P0_RX_DN<11>")
	)
	(arc
		(start 368.20856 -326.809608)
		(mid 367.93278 -326.500524)
		(end 367.700814 -326.157336)
		(width 0.14224)
		(layer "In15.Cu")
		(net "P5E_CPU0_P0_RX_DN<11>")
	)
	(arc
		(start 328.730102 -375.035064)
		(mid 328.778786 -375.025362)
		(end 328.820018 -374.997726)
		(width 0.14224)
		(layer "In15.Cu")
		(net "P5E_CPU0_P0_RX_DN<11>")
	)
	(arc
		(start 395.767814 -354.528882)
		(mid 395.625034 -353.854418)
		(end 395.235176 -353.285806)
		(width 0.14224)
		(layer "In15.Cu")
		(net "P5E_CPU0_P0_RX_DN<11>")
	)
	(arc
		(start 355.45649 -272.92173)
		(mid 355.231319 -272.466054)
		(end 355.45649 -272.010378)
		(width 0.1143)
		(layer "In15.Cu")
		(net "P5E_CPU0_P0_RX_DN<11>")
	)
	(arc
		(start 355.539802 -289.780218)
		(mid 355.69573 -289.475926)
		(end 355.539802 -289.171634)
		(width 0.1143)
		(layer "In15.Cu")
		(net "P5E_CPU0_P0_RX_DN<11>")
	)
	(arc
		(start 355.54158 -288.158936)
		(mid 355.654987 -288.026047)
		(end 355.695758 -287.856168)
		(width 0.1143)
		(layer "In15.Cu")
		(net "P5E_CPU0_P0_RX_DN<11>")
	)
	(arc
		(start 355.44125 -284.250892)
		(mid 355.21325 -283.806138)
		(end 355.44125 -283.361384)
		(width 0.1143)
		(layer "In15.Cu")
		(net "P5E_CPU0_P0_RX_DN<11>")
	)
	(arc
		(start 355.090476 -304.510694)
		(mid 354.988925 -304.267115)
		(end 354.954332 -304.005488)
		(width 0.14224)
		(layer "In15.Cu")
		(net "P5E_CPU0_P0_RX_DN<11>")
	)
	(arc
		(start 377.550172 -370.245386)
		(mid 377.611895 -370.233109)
		(end 377.664218 -370.198142)
		(width 0.14224)
		(layer "In15.Cu")
		(net "P5E_CPU0_P0_RX_DN<11>")
	)
	(arc
		(start 355.461062 -271.30502)
		(mid 355.291988 -271.112099)
		(end 355.225604 -270.86433)
		(width 0.1143)
		(layer "In15.Cu")
		(net "P5E_CPU0_P0_RX_DN<11>")
	)
	(arc
		(start 331.166724 -372.65102)
		(mid 331.310647 -372.554884)
		(end 331.480414 -372.521226)
		(width 0.14224)
		(layer "In15.Cu")
		(net "P5E_CPU0_P0_RX_DN<11>")
	)
	(arc
		(start 355.45649 -272.010378)
		(mid 355.464066 -272.004982)
		(end 355.47173 -271.99971)
		(width 0.1143)
		(layer "In15.Cu")
		(net "P5E_CPU0_P0_RX_DN<11>")
	)
	(arc
		(start 393.684252 -368.319812)
		(mid 394.407612 -368.175909)
		(end 395.0208 -367.766092)
		(width 0.14224)
		(layer "In15.Cu")
		(net "P5E_CPU0_P0_RX_DN<11>")
	)
	(arc
		(start 321.429126 -379.573282)
		(mid 321.409327 -379.473748)
		(end 321.352926 -379.389386)
		(width 0.14224)
		(layer "In15.Cu")
		(net "P5E_CPU0_P0_RX_DN<11>")
	)
	(arc
		(start 355.45649 -293.981632)
		(mid 355.231319 -293.525956)
		(end 355.45649 -293.07028)
		(width 0.1143)
		(layer "In15.Cu")
		(net "P5E_CPU0_P0_RX_DN<11>")
	)
	(arc
		(start 355.44125 -276.150832)
		(mid 355.21325 -275.706078)
		(end 355.44125 -275.261324)
		(width 0.1143)
		(layer "In15.Cu")
		(net "P5E_CPU0_P0_RX_DN<11>")
	)
	(arc
		(start 320.927222 -386.076698)
		(mid 321.298701 -385.520835)
		(end 321.429126 -384.865118)
		(width 0.14224)
		(layer "In15.Cu")
		(net "P5E_CPU0_P0_RX_DN<11>")
	)
	(arc
		(start 354.849176 -296.273474)
		(mid 354.780181 -296.170355)
		(end 354.755958 -296.048684)
		(width 0.1143)
		(layer "In15.Cu")
		(net "P5E_CPU0_P0_RX_DN<11>")
	)
	(arc
		(start 355.45649 -274.541742)
		(mid 355.231319 -274.086066)
		(end 355.45649 -273.63039)
		(width 0.1143)
		(layer "In15.Cu")
		(net "P5E_CPU0_P0_RX_DN<11>")
	)
	(arc
		(start 355.539802 -278.440388)
		(mid 355.69573 -278.136096)
		(end 355.539802 -277.831804)
		(width 0.1143)
		(layer "In15.Cu")
		(net "P5E_CPU0_P0_RX_DN<11>")
	)
	(arc
		(start 355.539802 -273.580352)
		(mid 355.69573 -273.27606)
		(end 355.539802 -272.971768)
		(width 0.1143)
		(layer "In15.Cu")
		(net "P5E_CPU0_P0_RX_DN<11>")
	)
	(arc
		(start 355.539802 -275.200364)
		(mid 355.69573 -274.896072)
		(end 355.539802 -274.59178)
		(width 0.1143)
		(layer "In15.Cu")
		(net "P5E_CPU0_P0_RX_DN<11>")
	)
	(arc
		(start 355.507798 -292.39337)
		(mid 355.227371 -291.906134)
		(end 355.507798 -291.418772)
		(width 0.1143)
		(layer "In15.Cu")
		(net "P5E_CPU0_P0_RX_DN<11>")
	)
	(arc
		(start 355.539802 -280.0604)
		(mid 355.69573 -279.756108)
		(end 355.539802 -279.451816)
		(width 0.1143)
		(layer "In15.Cu")
		(net "P5E_CPU0_P0_RX_DN<11>")
	)
	(arc
		(start 355.54158 -286.538924)
		(mid 355.654987 -286.406035)
		(end 355.695758 -286.236156)
		(width 0.1143)
		(layer "In15.Cu")
		(net "P5E_CPU0_P0_RX_DN<11>")
	)
	(segment
		(start 315.270388 -393.69238)
		(end 315.791088 -393.69238)
		(width 0.127)
		(layer "F.Cu")
		(net "P5E_CPU0_P0_RX_DN<10>")
	)
	(segment
		(start 354.847906 -273.010122)
		(end 354.381054 -273.27606)
		(width 0.12954)
		(layer "F.Cu")
		(net "P5E_CPU0_P0_RX_DN<10>")
	)
	(segment
		(start 353.902772 -296.300398)
		(end 353.902772 -295.914572)
		(width 0.1143)
		(layer "In15.Cu")
		(net "P5E_CPU0_P0_RX_DN<10>")
	)
	(segment
		(start 354.598732 -282.691332)
		(end 354.529136 -282.650692)
		(width 0.1143)
		(layer "In15.Cu")
		(net "P5E_CPU0_P0_RX_DN<10>")
	)
	(segment
		(start 354.529136 -281.72156)
		(end 354.598732 -281.68092)
		(width 0.1143)
		(layer "In15.Cu")
		(net "P5E_CPU0_P0_RX_DN<10>")
	)
	(segment
		(start 354.678996 -273.27606)
		(end 354.381054 -273.27606)
		(width 0.1143)
		(layer "In15.Cu")
		(net "P5E_CPU0_P0_RX_DN<10>")
	)
	(segment
		(start 354.529136 -284.961584)
		(end 354.598732 -284.920944)
		(width 0.1143)
		(layer "In15.Cu")
		(net "P5E_CPU0_P0_RX_DN<10>")
	)
	(segment
		(start 316.266576 -393.716764)
		(end 316.266576 -393.545822)
		(width 0.14224)
		(layer "In15.Cu")
		(net "P5E_CPU0_P0_RX_DN<10>")
	)
	(segment
		(start 353.99599 -295.689528)
		(end 354.19792 -295.487598)
		(width 0.1143)
		(layer "In15.Cu")
		(net "P5E_CPU0_P0_RX_DN<10>")
	)
	(segment
		(start 354.598732 -277.831296)
		(end 354.529136 -277.790656)
		(width 0.1143)
		(layer "In15.Cu")
		(net "P5E_CPU0_P0_RX_DN<10>")
	)
	(segment
		(start 318.145414 -376.286776)
		(end 318.37884 -376.05335)
		(width 0.14224)
		(layer "In15.Cu")
		(net "P5E_CPU0_P0_RX_DN<10>")
	)
	(segment
		(start 329.34656 -372.592092)
		(end 329.648058 -372.290594)
		(width 0.14224)
		(layer "In15.Cu")
		(net "P5E_CPU0_P0_RX_DN<10>")
	)
	(segment
		(start 319.691004 -381.551434)
		(end 318.278002 -380.965964)
		(width 0.14224)
		(layer "In15.Cu")
		(net "P5E_CPU0_P0_RX_DN<10>")
	)
	(segment
		(start 354.598732 -287.551368)
		(end 354.531676 -287.512252)
		(width 0.1143)
		(layer "In15.Cu")
		(net "P5E_CPU0_P0_RX_DN<10>")
	)
	(segment
		(start 329.648058 -372.096538)
		(end 329.950064 -371.794532)
		(width 0.14224)
		(layer "In15.Cu")
		(net "P5E_CPU0_P0_RX_DN<10>")
	)
	(segment
		(start 354.598732 -285.931356)
		(end 354.529136 -285.890716)
		(width 0.1143)
		(layer "In15.Cu")
		(net "P5E_CPU0_P0_RX_DN<10>")
	)
	(segment
		(start 363.655356 -367.335816)
		(end 363.962696 -367.028476)
		(width 0.14224)
		(layer "In15.Cu")
		(net "P5E_CPU0_P0_RX_DN<10>")
	)
	(segment
		(start 315.95441 -392.616944)
		(end 316.258448 -392.31316)
		(width 0.14224)
		(layer "In15.Cu")
		(net "P5E_CPU0_P0_RX_DN<10>")
	)
	(segment
		(start 315.791088 -393.69238)
		(end 316.144402 -393.787376)
		(width 0.14224)
		(layer "In15.Cu")
		(net "P5E_CPU0_P0_RX_DN<10>")
	)
	(segment
		(start 354.285804 -295.276016)
		(end 354.285804 -295.14546)
		(width 0.1143)
		(layer "In15.Cu")
		(net "P5E_CPU0_P0_RX_DN<10>")
	)
	(segment
		(start 354.529136 -280.101548)
		(end 354.598732 -280.060908)
		(width 0.1143)
		(layer "In15.Cu")
		(net "P5E_CPU0_P0_RX_DN<10>")
	)
	(segment
		(start 353.857052 -304.07991)
		(end 353.857052 -296.374566)
		(width 0.14224)
		(layer "In15.Cu")
		(net "P5E_CPU0_P0_RX_DN<10>")
	)
	(segment
		(start 330.747624 -370.996972)
		(end 330.94168 -370.996972)
		(width 0.14224)
		(layer "In15.Cu")
		(net "P5E_CPU0_P0_RX_DN<10>")
	)
	(segment
		(start 354.529136 -293.06139)
		(end 354.598732 -293.02075)
		(width 0.1143)
		(layer "In15.Cu")
		(net "P5E_CPU0_P0_RX_DN<10>")
	)
	(segment
		(start 354.531168 -286.579818)
		(end 354.568252 -286.558482)
		(width 0.1143)
		(layer "In15.Cu")
		(net "P5E_CPU0_P0_RX_DN<10>")
	)
	(segment
		(start 354.598732 -276.211284)
		(end 354.529136 -276.170644)
		(width 0.1143)
		(layer "In15.Cu")
		(net "P5E_CPU0_P0_RX_DN<10>")
	)
	(segment
		(start 354.598732 -279.451308)
		(end 354.529136 -279.410668)
		(width 0.1143)
		(layer "In15.Cu")
		(net "P5E_CPU0_P0_RX_DN<10>")
	)
	(segment
		(start 354.529136 -283.341572)
		(end 354.598732 -283.300932)
		(width 0.1143)
		(layer "In15.Cu")
		(net "P5E_CPU0_P0_RX_DN<10>")
	)
	(segment
		(start 353.857052 -296.374566)
		(end 353.857052 -296.346118)
		(width 0.1143)
		(layer "In15.Cu")
		(net "P5E_CPU0_P0_RX_DN<10>")
	)
	(segment
		(start 394.139928 -353.534218)
		(end 367.41989 -327.349104)
		(width 0.14224)
		(layer "In15.Cu")
		(net "P5E_CPU0_P0_RX_DN<10>")
	)
	(segment
		(start 330.14412 -371.794532)
		(end 330.445618 -371.493034)
		(width 0.14224)
		(layer "In15.Cu")
		(net "P5E_CPU0_P0_RX_DN<10>")
	)
	(segment
		(start 354.529136 -276.861524)
		(end 354.598732 -276.820884)
		(width 0.1143)
		(layer "In15.Cu")
		(net "P5E_CPU0_P0_RX_DN<10>")
	)
	(segment
		(start 354.598732 -294.031162)
		(end 354.529136 -293.990522)
		(width 0.1143)
		(layer "In15.Cu")
		(net "P5E_CPU0_P0_RX_DN<10>")
	)
	(segment
		(start 363.962696 -368.448336)
		(end 363.655356 -368.140996)
		(width 0.14224)
		(layer "In15.Cu")
		(net "P5E_CPU0_P0_RX_DN<10>")
	)
	(segment
		(start 354.529136 -278.481536)
		(end 354.598732 -278.440896)
		(width 0.1143)
		(layer "In15.Cu")
		(net "P5E_CPU0_P0_RX_DN<10>")
	)
	(segment
		(start 329.950064 -371.794532)
		(end 330.14412 -371.794532)
		(width 0.14224)
		(layer "In15.Cu")
		(net "P5E_CPU0_P0_RX_DN<10>")
	)
	(segment
		(start 354.598732 -290.791138)
		(end 354.529136 -290.750498)
		(width 0.1143)
		(layer "In15.Cu")
		(net "P5E_CPU0_P0_RX_DN<10>")
	)
	(segment
		(start 363.962696 -367.028476)
		(end 393.289282 -367.028476)
		(width 0.14224)
		(layer "In15.Cu")
		(net "P5E_CPU0_P0_RX_DN<10>")
	)
	(segment
		(start 332.804008 -369.304316)
		(end 375.22912 -369.304316)
		(width 0.14224)
		(layer "In15.Cu")
		(net "P5E_CPU0_P0_RX_DN<10>")
	)
	(segment
		(start 316.14491 -393.786868)
		(end 316.266576 -393.716764)
		(width 0.14224)
		(layer "In15.Cu")
		(net "P5E_CPU0_P0_RX_DN<10>")
	)
	(segment
		(start 354.529136 -286.581342)
		(end 354.531168 -286.579818)
		(width 0.1143)
		(layer "In15.Cu")
		(net "P5E_CPU0_P0_RX_DN<10>")
	)
	(segment
		(start 354.598732 -274.591272)
		(end 354.529136 -274.550632)
		(width 0.1143)
		(layer "In15.Cu")
		(net "P5E_CPU0_P0_RX_DN<10>")
	)
	(segment
		(start 354.529136 -294.681402)
		(end 354.598732 -294.640762)
		(width 0.1143)
		(layer "In15.Cu")
		(net "P5E_CPU0_P0_RX_DN<10>")
	)
	(segment
		(start 375.37136 -368.590576)
		(end 375.22912 -368.448336)
		(width 0.14224)
		(layer "In15.Cu")
		(net "P5E_CPU0_P0_RX_DN<10>")
	)
	(segment
		(start 366.848644 -326.615552)
		(end 353.974146 -304.515266)
		(width 0.14224)
		(layer "In15.Cu")
		(net "P5E_CPU0_P0_RX_DN<10>")
	)
	(segment
		(start 330.94168 -370.996972)
		(end 332.514448 -369.424204)
		(width 0.14224)
		(layer "In15.Cu")
		(net "P5E_CPU0_P0_RX_DN<10>")
	)
	(segment
		(start 327.909428 -374.029224)
		(end 328.850752 -373.0879)
		(width 0.14224)
		(layer "In15.Cu")
		(net "P5E_CPU0_P0_RX_DN<10>")
	)
	(segment
		(start 330.445618 -371.493034)
		(end 330.445618 -371.298978)
		(width 0.14224)
		(layer "In15.Cu")
		(net "P5E_CPU0_P0_RX_DN<10>")
	)
	(segment
		(start 323.165216 -374.076468)
		(end 327.795382 -374.076468)
		(width 0.14224)
		(layer "In15.Cu")
		(net "P5E_CPU0_P0_RX_DN<10>")
	)
	(segment
		(start 316.258448 -392.31316)
		(end 316.258448 -389.370062)
		(width 0.14224)
		(layer "In15.Cu")
		(net "P5E_CPU0_P0_RX_DN<10>")
	)
	(segment
		(start 354.598732 -284.311344)
		(end 354.529136 -284.270704)
		(width 0.1143)
		(layer "In15.Cu")
		(net "P5E_CPU0_P0_RX_DN<10>")
	)
	(segment
		(start 315.949584 -393.22883)
		(end 315.95441 -392.616944)
		(width 0.14224)
		(layer "In15.Cu")
		(net "P5E_CPU0_P0_RX_DN<10>")
	)
	(segment
		(start 354.598732 -292.41115)
		(end 354.529136 -292.37051)
		(width 0.1143)
		(layer "In15.Cu")
		(net "P5E_CPU0_P0_RX_DN<10>")
	)
	(segment
		(start 318.64046 -375.878344)
		(end 322.829682 -374.14327)
		(width 0.14224)
		(layer "In15.Cu")
		(net "P5E_CPU0_P0_RX_DN<10>")
	)
	(segment
		(start 330.445618 -371.298978)
		(end 330.747624 -370.996972)
		(width 0.14224)
		(layer "In15.Cu")
		(net "P5E_CPU0_P0_RX_DN<10>")
	)
	(segment
		(start 316.564518 -388.630922)
		(end 319.673732 -385.521708)
		(width 0.14224)
		(layer "In15.Cu")
		(net "P5E_CPU0_P0_RX_DN<10>")
	)
	(segment
		(start 375.22912 -368.448336)
		(end 363.962696 -368.448336)
		(width 0.14224)
		(layer "In15.Cu")
		(net "P5E_CPU0_P0_RX_DN<10>")
	)
	(segment
		(start 394.832078 -365.426244)
		(end 394.832078 -355.181154)
		(width 0.14224)
		(layer "In15.Cu")
		(net "P5E_CPU0_P0_RX_DN<10>")
	)
	(segment
		(start 319.92824 -384.907536)
		(end 319.92824 -381.906526)
		(width 0.14224)
		(layer "In15.Cu")
		(net "P5E_CPU0_P0_RX_DN<10>")
	)
	(segment
		(start 328.850752 -372.894098)
		(end 329.152758 -372.592092)
		(width 0.14224)
		(layer "In15.Cu")
		(net "P5E_CPU0_P0_RX_DN<10>")
	)
	(segment
		(start 354.529136 -273.6215)
		(end 354.598732 -273.58086)
		(width 0.1143)
		(layer "In15.Cu")
		(net "P5E_CPU0_P0_RX_DN<10>")
	)
	(segment
		(start 354.748846 -273.34591)
		(end 354.678996 -273.27606)
		(width 0.1143)
		(layer "In15.Cu")
		(net "P5E_CPU0_P0_RX_DN<10>")
	)
	(segment
		(start 354.568252 -288.178494)
		(end 354.600764 -288.159698)
		(width 0.1143)
		(layer "In15.Cu")
		(net "P5E_CPU0_P0_RX_DN<10>")
	)
	(segment
		(start 329.648058 -372.290594)
		(end 329.648058 -372.096538)
		(width 0.14224)
		(layer "In15.Cu")
		(net "P5E_CPU0_P0_RX_DN<10>")
	)
	(segment
		(start 354.529136 -291.441378)
		(end 354.598732 -291.400738)
		(width 0.1143)
		(layer "In15.Cu")
		(net "P5E_CPU0_P0_RX_DN<10>")
	)
	(segment
		(start 375.22912 -369.304316)
		(end 375.37136 -369.162076)
		(width 0.14224)
		(layer "In15.Cu")
		(net "P5E_CPU0_P0_RX_DN<10>")
	)
	(segment
		(start 318.025526 -380.588012)
		(end 318.025526 -376.576336)
		(width 0.14224)
		(layer "In15.Cu")
		(net "P5E_CPU0_P0_RX_DN<10>")
	)
	(segment
		(start 354.529136 -289.821366)
		(end 354.598732 -289.780726)
		(width 0.1143)
		(layer "In15.Cu")
		(net "P5E_CPU0_P0_RX_DN<10>")
	)
	(segment
		(start 353.857052 -296.346118)
		(end 353.902772 -296.300398)
		(width 0.1143)
		(layer "In15.Cu")
		(net "P5E_CPU0_P0_RX_DN<10>")
	)
	(segment
		(start 354.598732 -289.171126)
		(end 354.529136 -289.130486)
		(width 0.1143)
		(layer "In15.Cu")
		(net "P5E_CPU0_P0_RX_DN<10>")
	)
	(segment
		(start 354.529136 -275.241512)
		(end 354.598732 -275.200872)
		(width 0.1143)
		(layer "In15.Cu")
		(net "P5E_CPU0_P0_RX_DN<10>")
	)
	(segment
		(start 354.568252 -286.558482)
		(end 354.600764 -286.539686)
		(width 0.1143)
		(layer "In15.Cu")
		(net "P5E_CPU0_P0_RX_DN<10>")
	)
	(segment
		(start 394.18006 -366.659414)
		(end 394.421106 -366.418368)
		(width 0.14224)
		(layer "In15.Cu")
		(net "P5E_CPU0_P0_RX_DN<10>")
	)
	(segment
		(start 363.655356 -368.140996)
		(end 363.655356 -367.335816)
		(width 0.14224)
		(layer "In15.Cu")
		(net "P5E_CPU0_P0_RX_DN<10>")
	)
	(segment
		(start 329.152758 -372.592092)
		(end 329.34656 -372.592092)
		(width 0.14224)
		(layer "In15.Cu")
		(net "P5E_CPU0_P0_RX_DN<10>")
	)
	(segment
		(start 375.37136 -369.162076)
		(end 375.37136 -368.590576)
		(width 0.14224)
		(layer "In15.Cu")
		(net "P5E_CPU0_P0_RX_DN<10>")
	)
	(segment
		(start 316.266576 -393.545822)
		(end 315.949584 -393.22883)
		(width 0.14224)
		(layer "In15.Cu")
		(net "P5E_CPU0_P0_RX_DN<10>")
	)
	(segment
		(start 354.529136 -288.201354)
		(end 354.568252 -288.178494)
		(width 0.1143)
		(layer "In15.Cu")
		(net "P5E_CPU0_P0_RX_DN<10>")
	)
	(segment
		(start 328.850752 -373.0879)
		(end 328.850752 -372.894098)
		(width 0.14224)
		(layer "In15.Cu")
		(net "P5E_CPU0_P0_RX_DN<10>")
	)
	(segment
		(start 316.144402 -393.787376)
		(end 316.14491 -393.786868)
		(width 0.14224)
		(layer "In15.Cu")
		(net "P5E_CPU0_P0_RX_DN<10>")
	)
	(segment
		(start 354.598732 -281.07132)
		(end 354.529136 -281.03068)
		(width 0.1143)
		(layer "In15.Cu")
		(net "P5E_CPU0_P0_RX_DN<10>")
	)
	(arc
		(start 354.529136 -285.890716)
		(mid 354.285809 -285.42615)
		(end 354.529136 -284.961584)
		(width 0.1143)
		(layer "In15.Cu")
		(net "P5E_CPU0_P0_RX_DN<10>")
	)
	(arc
		(start 394.224764 -353.627944)
		(mid 394.183793 -353.579771)
		(end 394.139928 -353.534218)
		(width 0.14224)
		(layer "In15.Cu")
		(net "P5E_CPU0_P0_RX_DN<10>")
	)
	(arc
		(start 354.529136 -293.990522)
		(mid 354.285809 -293.525956)
		(end 354.529136 -293.06139)
		(width 0.1143)
		(layer "In15.Cu")
		(net "P5E_CPU0_P0_RX_DN<10>")
	)
	(arc
		(start 354.531676 -287.512252)
		(mid 354.351024 -287.309507)
		(end 354.285804 -287.045908)
		(width 0.1143)
		(layer "In15.Cu")
		(net "P5E_CPU0_P0_RX_DN<10>")
	)
	(arc
		(start 354.529136 -276.170644)
		(mid 354.285809 -275.706078)
		(end 354.529136 -275.241512)
		(width 0.1143)
		(layer "In15.Cu")
		(net "P5E_CPU0_P0_RX_DN<10>")
	)
	(arc
		(start 354.598732 -278.440896)
		(mid 354.755709 -278.136096)
		(end 354.598732 -277.831296)
		(width 0.1143)
		(layer "In15.Cu")
		(net "P5E_CPU0_P0_RX_DN<10>")
	)
	(arc
		(start 354.529136 -277.790656)
		(mid 354.285809 -277.32609)
		(end 354.529136 -276.861524)
		(width 0.1143)
		(layer "In15.Cu")
		(net "P5E_CPU0_P0_RX_DN<10>")
	)
	(arc
		(start 354.529136 -274.550632)
		(mid 354.285809 -274.086066)
		(end 354.529136 -273.6215)
		(width 0.1143)
		(layer "In15.Cu")
		(net "P5E_CPU0_P0_RX_DN<10>")
	)
	(arc
		(start 354.600764 -286.539686)
		(mid 354.714693 -286.406539)
		(end 354.755704 -286.236156)
		(width 0.1143)
		(layer "In15.Cu")
		(net "P5E_CPU0_P0_RX_DN<10>")
	)
	(arc
		(start 394.824204 -355.054662)
		(mid 394.622745 -354.300016)
		(end 394.224764 -353.627944)
		(width 0.14224)
		(layer "In15.Cu")
		(net "P5E_CPU0_P0_RX_DN<10>")
	)
	(arc
		(start 354.598732 -273.58086)
		(mid 354.696497 -273.477884)
		(end 354.748846 -273.34591)
		(width 0.1143)
		(layer "In15.Cu")
		(net "P5E_CPU0_P0_RX_DN<10>")
	)
	(arc
		(start 354.598732 -293.02075)
		(mid 354.755709 -292.71595)
		(end 354.598732 -292.41115)
		(width 0.1143)
		(layer "In15.Cu")
		(net "P5E_CPU0_P0_RX_DN<10>")
	)
	(arc
		(start 354.529136 -290.750498)
		(mid 354.285809 -290.285932)
		(end 354.529136 -289.821366)
		(width 0.1143)
		(layer "In15.Cu")
		(net "P5E_CPU0_P0_RX_DN<10>")
	)
	(arc
		(start 354.598732 -281.68092)
		(mid 354.755709 -281.37612)
		(end 354.598732 -281.07132)
		(width 0.1143)
		(layer "In15.Cu")
		(net "P5E_CPU0_P0_RX_DN<10>")
	)
	(arc
		(start 354.529136 -282.650692)
		(mid 354.285809 -282.186126)
		(end 354.529136 -281.72156)
		(width 0.1143)
		(layer "In15.Cu")
		(net "P5E_CPU0_P0_RX_DN<10>")
	)
	(arc
		(start 354.598732 -291.400738)
		(mid 354.755709 -291.095938)
		(end 354.598732 -290.791138)
		(width 0.1143)
		(layer "In15.Cu")
		(net "P5E_CPU0_P0_RX_DN<10>")
	)
	(arc
		(start 354.755704 -287.856168)
		(mid 354.714155 -287.684746)
		(end 354.598732 -287.551368)
		(width 0.1143)
		(layer "In15.Cu")
		(net "P5E_CPU0_P0_RX_DN<10>")
	)
	(arc
		(start 353.974146 -304.515266)
		(mid 353.886733 -304.305354)
		(end 353.857052 -304.07991)
		(width 0.14224)
		(layer "In15.Cu")
		(net "P5E_CPU0_P0_RX_DN<10>")
	)
	(arc
		(start 319.92824 -381.906526)
		(mid 319.863469 -381.693012)
		(end 319.691004 -381.551434)
		(width 0.14224)
		(layer "In15.Cu")
		(net "P5E_CPU0_P0_RX_DN<10>")
	)
	(arc
		(start 354.529136 -292.37051)
		(mid 354.285809 -291.905944)
		(end 354.529136 -291.441378)
		(width 0.1143)
		(layer "In15.Cu")
		(net "P5E_CPU0_P0_RX_DN<10>")
	)
	(arc
		(start 322.829682 -374.14327)
		(mid 322.994162 -374.093349)
		(end 323.165216 -374.076468)
		(width 0.14224)
		(layer "In15.Cu")
		(net "P5E_CPU0_P0_RX_DN<10>")
	)
	(arc
		(start 354.598732 -275.200872)
		(mid 354.755709 -274.896072)
		(end 354.598732 -274.591272)
		(width 0.1143)
		(layer "In15.Cu")
		(net "P5E_CPU0_P0_RX_DN<10>")
	)
	(arc
		(start 318.025526 -376.576336)
		(mid 318.056678 -376.419633)
		(end 318.145414 -376.286776)
		(width 0.14224)
		(layer "In15.Cu")
		(net "P5E_CPU0_P0_RX_DN<10>")
	)
	(arc
		(start 354.529136 -279.410668)
		(mid 354.285809 -278.946102)
		(end 354.529136 -278.481536)
		(width 0.1143)
		(layer "In15.Cu")
		(net "P5E_CPU0_P0_RX_DN<10>")
	)
	(arc
		(start 354.755704 -286.236156)
		(mid 354.714155 -286.064734)
		(end 354.598732 -285.931356)
		(width 0.1143)
		(layer "In15.Cu")
		(net "P5E_CPU0_P0_RX_DN<10>")
	)
	(arc
		(start 354.285804 -287.045908)
		(mid 354.350319 -286.783689)
		(end 354.529136 -286.581342)
		(width 0.1143)
		(layer "In15.Cu")
		(net "P5E_CPU0_P0_RX_DN<10>")
	)
	(arc
		(start 354.598732 -289.780726)
		(mid 354.755709 -289.475926)
		(end 354.598732 -289.171126)
		(width 0.1143)
		(layer "In15.Cu")
		(net "P5E_CPU0_P0_RX_DN<10>")
	)
	(arc
		(start 354.529136 -281.03068)
		(mid 354.285809 -280.566114)
		(end 354.529136 -280.101548)
		(width 0.1143)
		(layer "In15.Cu")
		(net "P5E_CPU0_P0_RX_DN<10>")
	)
	(arc
		(start 393.289282 -367.028476)
		(mid 393.771388 -366.932561)
		(end 394.18006 -366.659414)
		(width 0.14224)
		(layer "In15.Cu")
		(net "P5E_CPU0_P0_RX_DN<10>")
	)
	(arc
		(start 394.421106 -366.418368)
		(mid 394.725254 -365.963178)
		(end 394.832078 -365.426244)
		(width 0.14224)
		(layer "In15.Cu")
		(net "P5E_CPU0_P0_RX_DN<10>")
	)
	(arc
		(start 354.598732 -284.920944)
		(mid 354.755709 -284.616144)
		(end 354.598732 -284.311344)
		(width 0.1143)
		(layer "In15.Cu")
		(net "P5E_CPU0_P0_RX_DN<10>")
	)
	(arc
		(start 318.37884 -376.05335)
		(mid 318.501037 -375.952972)
		(end 318.64046 -375.878344)
		(width 0.14224)
		(layer "In15.Cu")
		(net "P5E_CPU0_P0_RX_DN<10>")
	)
	(arc
		(start 394.832078 -355.181154)
		(mid 394.830105 -355.117786)
		(end 394.824204 -355.054662)
		(width 0.14224)
		(layer "In15.Cu")
		(net "P5E_CPU0_P0_RX_DN<10>")
	)
	(arc
		(start 316.258448 -389.370062)
		(mid 316.337995 -388.970063)
		(end 316.564518 -388.630922)
		(width 0.14224)
		(layer "In15.Cu")
		(net "P5E_CPU0_P0_RX_DN<10>")
	)
	(arc
		(start 332.514448 -369.424204)
		(mid 332.647313 -369.335489)
		(end 332.804008 -369.304316)
		(width 0.14224)
		(layer "In15.Cu")
		(net "P5E_CPU0_P0_RX_DN<10>")
	)
	(arc
		(start 354.598732 -276.820884)
		(mid 354.755709 -276.516084)
		(end 354.598732 -276.211284)
		(width 0.1143)
		(layer "In15.Cu")
		(net "P5E_CPU0_P0_RX_DN<10>")
	)
	(arc
		(start 327.795382 -374.076468)
		(mid 327.857105 -374.064191)
		(end 327.909428 -374.029224)
		(width 0.14224)
		(layer "In15.Cu")
		(net "P5E_CPU0_P0_RX_DN<10>")
	)
	(arc
		(start 353.902772 -295.914572)
		(mid 353.926998 -295.792778)
		(end 353.99599 -295.689528)
		(width 0.1143)
		(layer "In15.Cu")
		(net "P5E_CPU0_P0_RX_DN<10>")
	)
	(arc
		(start 354.19792 -295.487598)
		(mid 354.26292 -295.390553)
		(end 354.285804 -295.276016)
		(width 0.1143)
		(layer "In15.Cu")
		(net "P5E_CPU0_P0_RX_DN<10>")
	)
	(arc
		(start 319.673732 -385.521708)
		(mid 319.862068 -385.239938)
		(end 319.92824 -384.907536)
		(width 0.14224)
		(layer "In15.Cu")
		(net "P5E_CPU0_P0_RX_DN<10>")
	)
	(arc
		(start 354.598732 -280.060908)
		(mid 354.755709 -279.756108)
		(end 354.598732 -279.451308)
		(width 0.1143)
		(layer "In15.Cu")
		(net "P5E_CPU0_P0_RX_DN<10>")
	)
	(arc
		(start 354.598732 -294.640762)
		(mid 354.755709 -294.335962)
		(end 354.598732 -294.031162)
		(width 0.1143)
		(layer "In15.Cu")
		(net "P5E_CPU0_P0_RX_DN<10>")
	)
	(arc
		(start 318.278002 -380.965964)
		(mid 318.094477 -380.815263)
		(end 318.025526 -380.588012)
		(width 0.14224)
		(layer "In15.Cu")
		(net "P5E_CPU0_P0_RX_DN<10>")
	)
	(arc
		(start 354.529136 -289.130486)
		(mid 354.285809 -288.66592)
		(end 354.529136 -288.201354)
		(width 0.1143)
		(layer "In15.Cu")
		(net "P5E_CPU0_P0_RX_DN<10>")
	)
	(arc
		(start 354.598732 -283.300932)
		(mid 354.755709 -282.996132)
		(end 354.598732 -282.691332)
		(width 0.1143)
		(layer "In15.Cu")
		(net "P5E_CPU0_P0_RX_DN<10>")
	)
	(arc
		(start 354.529136 -284.270704)
		(mid 354.285809 -283.806138)
		(end 354.529136 -283.341572)
		(width 0.1143)
		(layer "In15.Cu")
		(net "P5E_CPU0_P0_RX_DN<10>")
	)
	(arc
		(start 354.285804 -295.14546)
		(mid 354.285804 -295.145206)
		(end 354.285804 -295.144952)
		(width 0.1143)
		(layer "In15.Cu")
		(net "P5E_CPU0_P0_RX_DN<10>")
	)
	(arc
		(start 354.600764 -288.159698)
		(mid 354.714693 -288.026551)
		(end 354.755704 -287.856168)
		(width 0.1143)
		(layer "In15.Cu")
		(net "P5E_CPU0_P0_RX_DN<10>")
	)
	(arc
		(start 367.41989 -327.349104)
		(mid 367.109647 -327.0015)
		(end 366.848644 -326.615552)
		(width 0.14224)
		(layer "In15.Cu")
		(net "P5E_CPU0_P0_RX_DN<10>")
	)
	(arc
		(start 354.285804 -295.144952)
		(mid 354.350554 -294.883299)
		(end 354.529136 -294.681402)
		(width 0.1143)
		(layer "In15.Cu")
		(net "P5E_CPU0_P0_RX_DN<10>")
	)
	(segment
		(start 303.270412 -393.69238)
		(end 303.791112 -393.69238)
		(width 0.127)
		(layer "F.Cu")
		(net "P5E_CPU0_P0_RX_DN<0>")
	)
	(segment
		(start 346.387928 -271.39011)
		(end 345.921076 -271.656048)
		(width 0.12954)
		(layer "F.Cu")
		(net "P5E_CPU0_P0_RX_DN<0>")
	)
	(segment
		(start 369.031012 -355.9429)
		(end 369.46586 -355.9429)
		(width 0.14224)
		(layer "In13.Cu")
		(net "P5E_CPU0_P0_RX_DN<0>")
	)
	(segment
		(start 346.138246 -271.961102)
		(end 346.13977 -271.960086)
		(width 0.1143)
		(layer "In13.Cu")
		(net "P5E_CPU0_P0_RX_DN<0>")
	)
	(segment
		(start 372.206774 -355.79304)
		(end 372.50878 -355.491034)
		(width 0.14224)
		(layer "In13.Cu")
		(net "P5E_CPU0_P0_RX_DN<0>")
	)
	(segment
		(start 345.129104 -280.101548)
		(end 345.16822 -280.078688)
		(width 0.1143)
		(layer "In13.Cu")
		(net "P5E_CPU0_P0_RX_DN<0>")
	)
	(segment
		(start 363.33811 -364.855506)
		(end 363.33811 -361.635802)
		(width 0.14224)
		(layer "In13.Cu")
		(net "P5E_CPU0_P0_RX_DN<0>")
	)
	(segment
		(start 373.14886 -354.0125)
		(end 373.14886 -353.58578)
		(width 0.14224)
		(layer "In13.Cu")
		(net "P5E_CPU0_P0_RX_DN<0>")
	)
	(segment
		(start 371.341904 -356.65791)
		(end 371.64391 -356.355904)
		(width 0.14224)
		(layer "In13.Cu")
		(net "P5E_CPU0_P0_RX_DN<0>")
	)
	(segment
		(start 345.1987 -290.791138)
		(end 345.16822 -290.773358)
		(width 0.1143)
		(layer "In13.Cu")
		(net "P5E_CPU0_P0_RX_DN<0>")
	)
	(segment
		(start 362.416852 -364.5662)
		(end 358.26827 -368.714782)
		(width 0.14224)
		(layer "In13.Cu")
		(net "P5E_CPU0_P0_RX_DN<0>")
	)
	(segment
		(start 358.672384 -369.320064)
		(end 358.873552 -369.320064)
		(width 0.14224)
		(layer "In13.Cu")
		(net "P5E_CPU0_P0_RX_DN<0>")
	)
	(segment
		(start 361.84713 -363.56163)
		(end 362.416852 -364.131352)
		(width 0.14224)
		(layer "In13.Cu")
		(net "P5E_CPU0_P0_RX_DN<0>")
	)
	(segment
		(start 345.16822 -273.59864)
		(end 345.1987 -273.58086)
		(width 0.1143)
		(layer "In13.Cu")
		(net "P5E_CPU0_P0_RX_DN<0>")
	)
	(segment
		(start 370.035582 -356.94747)
		(end 364.838742 -362.14431)
		(width 0.14224)
		(layer "In13.Cu")
		(net "P5E_CPU0_P0_RX_DN<0>")
	)
	(segment
		(start 372.702582 -355.491034)
		(end 373.28602 -354.907596)
		(width 0.14224)
		(layer "In13.Cu")
		(net "P5E_CPU0_P0_RX_DN<0>")
	)
	(segment
		(start 345.129104 -289.821366)
		(end 345.16822 -289.798506)
		(width 0.1143)
		(layer "In13.Cu")
		(net "P5E_CPU0_P0_RX_DN<0>")
	)
	(segment
		(start 307.72735 -370.270532)
		(end 314.716668 -370.270532)
		(width 0.14224)
		(layer "In13.Cu")
		(net "P5E_CPU0_P0_RX_DN<0>")
	)
	(segment
		(start 345.129104 -278.481536)
		(end 345.16822 -278.458676)
		(width 0.1143)
		(layer "In13.Cu")
		(net "P5E_CPU0_P0_RX_DN<0>")
	)
	(segment
		(start 370.035582 -356.512622)
		(end 370.035582 -356.94747)
		(width 0.14224)
		(layer "In13.Cu")
		(net "P5E_CPU0_P0_RX_DN<0>")
	)
	(segment
		(start 345.1987 -281.07132)
		(end 345.16822 -281.05354)
		(width 0.1143)
		(layer "In13.Cu")
		(net "P5E_CPU0_P0_RX_DN<0>")
	)
	(segment
		(start 346.10802 -271.978882)
		(end 346.138246 -271.961102)
		(width 0.1143)
		(layer "In13.Cu")
		(net "P5E_CPU0_P0_RX_DN<0>")
	)
	(segment
		(start 345.129104 -283.341572)
		(end 345.16822 -283.318712)
		(width 0.1143)
		(layer "In13.Cu")
		(net "P5E_CPU0_P0_RX_DN<0>")
	)
	(segment
		(start 303.949608 -393.22883)
		(end 303.954434 -392.616944)
		(width 0.14224)
		(layer "In13.Cu")
		(net "P5E_CPU0_P0_RX_DN<0>")
	)
	(segment
		(start 345.675712 -272.766282)
		(end 345.67622 -272.765774)
		(width 0.1143)
		(layer "In13.Cu")
		(net "P5E_CPU0_P0_RX_DN<0>")
	)
	(segment
		(start 345.599004 -272.811494)
		(end 345.630246 -272.793206)
		(width 0.1143)
		(layer "In13.Cu")
		(net "P5E_CPU0_P0_RX_DN<0>")
	)
	(segment
		(start 345.16822 -274.573492)
		(end 345.129104 -274.550632)
		(width 0.1143)
		(layer "In13.Cu")
		(net "P5E_CPU0_P0_RX_DN<0>")
	)
	(segment
		(start 345.1987 -282.691332)
		(end 345.16822 -282.673552)
		(width 0.1143)
		(layer "In13.Cu")
		(net "P5E_CPU0_P0_RX_DN<0>")
	)
	(segment
		(start 345.1987 -289.171126)
		(end 345.16822 -289.153346)
		(width 0.1143)
		(layer "In13.Cu")
		(net "P5E_CPU0_P0_RX_DN<0>")
	)
	(segment
		(start 344.847164 -296.079164)
		(end 344.847164 -296.050716)
		(width 0.1143)
		(layer "In13.Cu")
		(net "P5E_CPU0_P0_RX_DN<0>")
	)
	(segment
		(start 365.444024 -362.749592)
		(end 371.341904 -356.851712)
		(width 0.14224)
		(layer "In13.Cu")
		(net "P5E_CPU0_P0_RX_DN<0>")
	)
	(segment
		(start 373.28602 -352.429572)
		(end 358.521762 -316.773306)
		(width 0.14224)
		(layer "In13.Cu")
		(net "P5E_CPU0_P0_RX_DN<0>")
	)
	(segment
		(start 345.16822 -280.078688)
		(end 345.1987 -280.060908)
		(width 0.1143)
		(layer "In13.Cu")
		(net "P5E_CPU0_P0_RX_DN<0>")
	)
	(segment
		(start 345.16822 -277.813516)
		(end 345.129104 -277.790656)
		(width 0.1143)
		(layer "In13.Cu")
		(net "P5E_CPU0_P0_RX_DN<0>")
	)
	(segment
		(start 303.481232 -390.325356)
		(end 296.457624 -386.789676)
		(width 0.14224)
		(layer "In13.Cu")
		(net "P5E_CPU0_P0_RX_DN<0>")
	)
	(segment
		(start 345.16822 -284.938724)
		(end 345.1987 -284.920944)
		(width 0.1143)
		(layer "In13.Cu")
		(net "P5E_CPU0_P0_RX_DN<0>")
	)
	(segment
		(start 345.1987 -276.211284)
		(end 345.16822 -276.193504)
		(width 0.1143)
		(layer "In13.Cu")
		(net "P5E_CPU0_P0_RX_DN<0>")
	)
	(segment
		(start 345.67622 -272.765774)
		(end 345.67749 -272.765012)
		(width 0.1143)
		(layer "In13.Cu")
		(net "P5E_CPU0_P0_RX_DN<0>")
	)
	(segment
		(start 304.2666 -393.716764)
		(end 304.2666 -393.545822)
		(width 0.14224)
		(layer "In13.Cu")
		(net "P5E_CPU0_P0_RX_DN<0>")
	)
	(segment
		(start 327.051924 -368.083846)
		(end 332.66761 -368.073686)
		(width 0.14224)
		(layer "In13.Cu")
		(net "P5E_CPU0_P0_RX_DN<0>")
	)
	(segment
		(start 296.004996 -376.706638)
		(end 300.867572 -371.844062)
		(width 0.14224)
		(layer "In13.Cu")
		(net "P5E_CPU0_P0_RX_DN<0>")
	)
	(segment
		(start 364.838742 -362.14431)
		(end 364.838742 -362.345478)
		(width 0.14224)
		(layer "In13.Cu")
		(net "P5E_CPU0_P0_RX_DN<0>")
	)
	(segment
		(start 345.129104 -273.6215)
		(end 345.16822 -273.59864)
		(width 0.1143)
		(layer "In13.Cu")
		(net "P5E_CPU0_P0_RX_DN<0>")
	)
	(segment
		(start 345.16822 -275.218652)
		(end 345.1987 -275.200872)
		(width 0.1143)
		(layer "In13.Cu")
		(net "P5E_CPU0_P0_RX_DN<0>")
	)
	(segment
		(start 303.954434 -392.616944)
		(end 304.258472 -392.312906)
		(width 0.14224)
		(layer "In13.Cu")
		(net "P5E_CPU0_P0_RX_DN<0>")
	)
	(segment
		(start 345.16822 -289.153346)
		(end 345.129104 -289.130486)
		(width 0.1143)
		(layer "In13.Cu")
		(net "P5E_CPU0_P0_RX_DN<0>")
	)
	(segment
		(start 345.1987 -287.551368)
		(end 345.131644 -287.512252)
		(width 0.1143)
		(layer "In13.Cu")
		(net "P5E_CPU0_P0_RX_DN<0>")
	)
	(segment
		(start 345.630246 -272.793206)
		(end 345.631008 -272.792698)
		(width 0.1143)
		(layer "In13.Cu")
		(net "P5E_CPU0_P0_RX_DN<0>")
	)
	(segment
		(start 345.16822 -281.6987)
		(end 345.1987 -281.68092)
		(width 0.1143)
		(layer "In13.Cu")
		(net "P5E_CPU0_P0_RX_DN<0>")
	)
	(segment
		(start 373.28602 -354.907596)
		(end 373.28602 -354.14966)
		(width 0.14224)
		(layer "In13.Cu")
		(net "P5E_CPU0_P0_RX_DN<0>")
	)
	(segment
		(start 345.16822 -279.433528)
		(end 345.129104 -279.410668)
		(width 0.1143)
		(layer "In13.Cu")
		(net "P5E_CPU0_P0_RX_DN<0>")
	)
	(segment
		(start 371.341904 -356.851712)
		(end 371.341904 -356.65791)
		(width 0.14224)
		(layer "In13.Cu")
		(net "P5E_CPU0_P0_RX_DN<0>")
	)
	(segment
		(start 345.1987 -294.031162)
		(end 345.16822 -294.013382)
		(width 0.1143)
		(layer "In13.Cu")
		(net "P5E_CPU0_P0_RX_DN<0>")
	)
	(segment
		(start 372.50878 -355.491034)
		(end 372.702582 -355.491034)
		(width 0.14224)
		(layer "In13.Cu")
		(net "P5E_CPU0_P0_RX_DN<0>")
	)
	(segment
		(start 361.412282 -363.56163)
		(end 361.84713 -363.56163)
		(width 0.14224)
		(layer "In13.Cu")
		(net "P5E_CPU0_P0_RX_DN<0>")
	)
	(segment
		(start 346.219018 -271.656048)
		(end 345.921076 -271.656048)
		(width 0.1143)
		(layer "In13.Cu")
		(net "P5E_CPU0_P0_RX_DN<0>")
	)
	(segment
		(start 345.16822 -293.03853)
		(end 345.1987 -293.02075)
		(width 0.1143)
		(layer "In13.Cu")
		(net "P5E_CPU0_P0_RX_DN<0>")
	)
	(segment
		(start 358.26827 -368.714782)
		(end 358.26827 -368.91595)
		(width 0.14224)
		(layer "In13.Cu")
		(net "P5E_CPU0_P0_RX_DN<0>")
	)
	(segment
		(start 314.716668 -370.270532)
		(end 324.395338 -368.345466)
		(width 0.14224)
		(layer "In13.Cu")
		(net "P5E_CPU0_P0_RX_DN<0>")
	)
	(segment
		(start 363.33811 -361.635802)
		(end 369.031012 -355.9429)
		(width 0.14224)
		(layer "In13.Cu")
		(net "P5E_CPU0_P0_RX_DN<0>")
	)
	(segment
		(start 346.288868 -271.725898)
		(end 346.219018 -271.656048)
		(width 0.1143)
		(layer "In13.Cu")
		(net "P5E_CPU0_P0_RX_DN<0>")
	)
	(segment
		(start 345.16822 -285.913576)
		(end 345.129104 -285.890716)
		(width 0.1143)
		(layer "In13.Cu")
		(net "P5E_CPU0_P0_RX_DN<0>")
	)
	(segment
		(start 345.129104 -288.201354)
		(end 345.200732 -288.159698)
		(width 0.1143)
		(layer "In13.Cu")
		(net "P5E_CPU0_P0_RX_DN<0>")
	)
	(segment
		(start 345.1987 -284.311344)
		(end 345.16822 -284.293564)
		(width 0.1143)
		(layer "In13.Cu")
		(net "P5E_CPU0_P0_RX_DN<0>")
	)
	(segment
		(start 304.144934 -393.786868)
		(end 304.2666 -393.716764)
		(width 0.14224)
		(layer "In13.Cu")
		(net "P5E_CPU0_P0_RX_DN<0>")
	)
	(segment
		(start 306.83073 -370.99748)
		(end 307.43779 -370.39042)
		(width 0.14224)
		(layer "In13.Cu")
		(net "P5E_CPU0_P0_RX_DN<0>")
	)
	(segment
		(start 371.837712 -356.355904)
		(end 372.206774 -355.986842)
		(width 0.14224)
		(layer "In13.Cu")
		(net "P5E_CPU0_P0_RX_DN<0>")
	)
	(segment
		(start 345.16822 -290.773358)
		(end 345.129104 -290.750498)
		(width 0.1143)
		(layer "In13.Cu")
		(net "P5E_CPU0_P0_RX_DN<0>")
	)
	(segment
		(start 372.206774 -355.986842)
		(end 372.206774 -355.79304)
		(width 0.14224)
		(layer "In13.Cu")
		(net "P5E_CPU0_P0_RX_DN<0>")
	)
	(segment
		(start 302.73625 -371.070124)
		(end 306.65547 -371.070124)
		(width 0.14224)
		(layer "In13.Cu")
		(net "P5E_CPU0_P0_RX_DN<0>")
	)
	(segment
		(start 352.652076 -368.923062)
		(end 356.05085 -368.923062)
		(width 0.14224)
		(layer "In13.Cu")
		(net "P5E_CPU0_P0_RX_DN<0>")
	)
	(segment
		(start 345.16822 -278.458676)
		(end 345.1987 -278.440896)
		(width 0.1143)
		(layer "In13.Cu")
		(net "P5E_CPU0_P0_RX_DN<0>")
	)
	(segment
		(start 345.129104 -294.681402)
		(end 345.1987 -294.640762)
		(width 0.1143)
		(layer "In13.Cu")
		(net "P5E_CPU0_P0_RX_DN<0>")
	)
	(segment
		(start 373.28602 -354.14966)
		(end 373.14886 -354.0125)
		(width 0.14224)
		(layer "In13.Cu")
		(net "P5E_CPU0_P0_RX_DN<0>")
	)
	(segment
		(start 344.892884 -296.004996)
		(end 344.892884 -295.132506)
		(width 0.1143)
		(layer "In13.Cu")
		(net "P5E_CPU0_P0_RX_DN<0>")
	)
	(segment
		(start 345.1987 -285.931356)
		(end 345.16822 -285.913576)
		(width 0.1143)
		(layer "In13.Cu")
		(net "P5E_CPU0_P0_RX_DN<0>")
	)
	(segment
		(start 304.144426 -393.787376)
		(end 304.144934 -393.786868)
		(width 0.14224)
		(layer "In13.Cu")
		(net "P5E_CPU0_P0_RX_DN<0>")
	)
	(segment
		(start 345.16822 -291.418518)
		(end 345.1987 -291.400738)
		(width 0.1143)
		(layer "In13.Cu")
		(net "P5E_CPU0_P0_RX_DN<0>")
	)
	(segment
		(start 345.129104 -284.961584)
		(end 345.16822 -284.938724)
		(width 0.1143)
		(layer "In13.Cu")
		(net "P5E_CPU0_P0_RX_DN<0>")
	)
	(segment
		(start 373.28602 -353.44862)
		(end 373.28602 -352.429572)
		(width 0.14224)
		(layer "In13.Cu")
		(net "P5E_CPU0_P0_RX_DN<0>")
	)
	(segment
		(start 344.847164 -296.050716)
		(end 344.892884 -296.004996)
		(width 0.1143)
		(layer "In13.Cu")
		(net "P5E_CPU0_P0_RX_DN<0>")
	)
	(segment
		(start 345.16822 -294.013382)
		(end 345.129104 -293.990522)
		(width 0.1143)
		(layer "In13.Cu")
		(net "P5E_CPU0_P0_RX_DN<0>")
	)
	(segment
		(start 345.129104 -281.72156)
		(end 345.16822 -281.6987)
		(width 0.1143)
		(layer "In13.Cu")
		(net "P5E_CPU0_P0_RX_DN<0>")
	)
	(segment
		(start 345.1987 -277.831296)
		(end 345.16822 -277.813516)
		(width 0.1143)
		(layer "In13.Cu")
		(net "P5E_CPU0_P0_RX_DN<0>")
	)
	(segment
		(start 345.16822 -286.558482)
		(end 345.200732 -286.539686)
		(width 0.1143)
		(layer "In13.Cu")
		(net "P5E_CPU0_P0_RX_DN<0>")
	)
	(segment
		(start 356.05085 -368.923062)
		(end 361.412282 -363.56163)
		(width 0.14224)
		(layer "In13.Cu")
		(net "P5E_CPU0_P0_RX_DN<0>")
	)
	(segment
		(start 358.26827 -368.91595)
		(end 358.672384 -369.320064)
		(width 0.14224)
		(layer "In13.Cu")
		(net "P5E_CPU0_P0_RX_DN<0>")
	)
	(segment
		(start 358.873552 -369.320064)
		(end 363.33811 -364.855506)
		(width 0.14224)
		(layer "In13.Cu")
		(net "P5E_CPU0_P0_RX_DN<0>")
	)
	(segment
		(start 345.131136 -286.579818)
		(end 345.16822 -286.558482)
		(width 0.1143)
		(layer "In13.Cu")
		(net "P5E_CPU0_P0_RX_DN<0>")
	)
	(segment
		(start 365.242856 -362.749592)
		(end 365.444024 -362.749592)
		(width 0.14224)
		(layer "In13.Cu")
		(net "P5E_CPU0_P0_RX_DN<0>")
	)
	(segment
		(start 304.179986 -390.614408)
		(end 303.481232 -390.325356)
		(width 0.14224)
		(layer "In13.Cu")
		(net "P5E_CPU0_P0_RX_DN<0>")
	)
	(segment
		(start 303.791112 -393.69238)
		(end 304.144426 -393.787376)
		(width 0.14224)
		(layer "In13.Cu")
		(net "P5E_CPU0_P0_RX_DN<0>")
	)
	(segment
		(start 345.1987 -279.451308)
		(end 345.16822 -279.433528)
		(width 0.1143)
		(layer "In13.Cu")
		(net "P5E_CPU0_P0_RX_DN<0>")
	)
	(segment
		(start 345.631008 -272.792698)
		(end 345.675712 -272.766282)
		(width 0.1143)
		(layer "In13.Cu")
		(net "P5E_CPU0_P0_RX_DN<0>")
	)
	(segment
		(start 295.867582 -385.832096)
		(end 295.867582 -377.038362)
		(width 0.14224)
		(layer "In13.Cu")
		(net "P5E_CPU0_P0_RX_DN<0>")
	)
	(segment
		(start 364.838742 -362.345478)
		(end 365.242856 -362.749592)
		(width 0.14224)
		(layer "In13.Cu")
		(net "P5E_CPU0_P0_RX_DN<0>")
	)
	(segment
		(start 304.2666 -393.545822)
		(end 303.949608 -393.22883)
		(width 0.14224)
		(layer "In13.Cu")
		(net "P5E_CPU0_P0_RX_DN<0>")
	)
	(segment
		(start 345.16822 -281.05354)
		(end 345.129104 -281.03068)
		(width 0.1143)
		(layer "In13.Cu")
		(net "P5E_CPU0_P0_RX_DN<0>")
	)
	(segment
		(start 345.129104 -276.861524)
		(end 345.16822 -276.838664)
		(width 0.1143)
		(layer "In13.Cu")
		(net "P5E_CPU0_P0_RX_DN<0>")
	)
	(segment
		(start 345.16822 -292.39337)
		(end 345.129104 -292.37051)
		(width 0.1143)
		(layer "In13.Cu")
		(net "P5E_CPU0_P0_RX_DN<0>")
	)
	(segment
		(start 345.1987 -292.41115)
		(end 345.16822 -292.39337)
		(width 0.1143)
		(layer "In13.Cu")
		(net "P5E_CPU0_P0_RX_DN<0>")
	)
	(segment
		(start 304.258472 -392.312906)
		(end 304.258472 -390.731756)
		(width 0.14224)
		(layer "In13.Cu")
		(net "P5E_CPU0_P0_RX_DN<0>")
	)
	(segment
		(start 345.16822 -276.193504)
		(end 345.129104 -276.170644)
		(width 0.1143)
		(layer "In13.Cu")
		(net "P5E_CPU0_P0_RX_DN<0>")
	)
	(segment
		(start 362.416852 -364.131352)
		(end 362.416852 -364.5662)
		(width 0.14224)
		(layer "In13.Cu")
		(net "P5E_CPU0_P0_RX_DN<0>")
	)
	(segment
		(start 369.46586 -355.9429)
		(end 370.035582 -356.512622)
		(width 0.14224)
		(layer "In13.Cu")
		(net "P5E_CPU0_P0_RX_DN<0>")
	)
	(segment
		(start 345.1987 -274.591272)
		(end 345.16822 -274.573492)
		(width 0.1143)
		(layer "In13.Cu")
		(net "P5E_CPU0_P0_RX_DN<0>")
	)
	(segment
		(start 345.129104 -291.441378)
		(end 345.16822 -291.418518)
		(width 0.1143)
		(layer "In13.Cu")
		(net "P5E_CPU0_P0_RX_DN<0>")
	)
	(segment
		(start 345.129104 -275.241512)
		(end 345.16822 -275.218652)
		(width 0.1143)
		(layer "In13.Cu")
		(net "P5E_CPU0_P0_RX_DN<0>")
	)
	(segment
		(start 345.16822 -289.798506)
		(end 345.1987 -289.780726)
		(width 0.1143)
		(layer "In13.Cu")
		(net "P5E_CPU0_P0_RX_DN<0>")
	)
	(segment
		(start 345.129104 -286.581342)
		(end 345.131136 -286.579818)
		(width 0.1143)
		(layer "In13.Cu")
		(net "P5E_CPU0_P0_RX_DN<0>")
	)
	(segment
		(start 345.16822 -283.318712)
		(end 345.1987 -283.300932)
		(width 0.1143)
		(layer "In13.Cu")
		(net "P5E_CPU0_P0_RX_DN<0>")
	)
	(segment
		(start 358.521762 -316.773306)
		(end 345.352878 -300.725078)
		(width 0.14224)
		(layer "In13.Cu")
		(net "P5E_CPU0_P0_RX_DN<0>")
	)
	(segment
		(start 373.14886 -353.58578)
		(end 373.28602 -353.44862)
		(width 0.14224)
		(layer "In13.Cu")
		(net "P5E_CPU0_P0_RX_DN<0>")
	)
	(segment
		(start 345.129104 -293.06139)
		(end 345.16822 -293.03853)
		(width 0.1143)
		(layer "In13.Cu")
		(net "P5E_CPU0_P0_RX_DN<0>")
	)
	(segment
		(start 345.16822 -284.293564)
		(end 345.129104 -284.270704)
		(width 0.1143)
		(layer "In13.Cu")
		(net "P5E_CPU0_P0_RX_DN<0>")
	)
	(segment
		(start 344.847164 -299.310806)
		(end 344.847164 -296.079164)
		(width 0.14224)
		(layer "In13.Cu")
		(net "P5E_CPU0_P0_RX_DN<0>")
	)
	(segment
		(start 345.16822 -276.838664)
		(end 345.1987 -276.820884)
		(width 0.1143)
		(layer "In13.Cu")
		(net "P5E_CPU0_P0_RX_DN<0>")
	)
	(segment
		(start 371.64391 -356.355904)
		(end 371.837712 -356.355904)
		(width 0.14224)
		(layer "In13.Cu")
		(net "P5E_CPU0_P0_RX_DN<0>")
	)
	(segment
		(start 345.16822 -282.673552)
		(end 345.129104 -282.650692)
		(width 0.1143)
		(layer "In13.Cu")
		(net "P5E_CPU0_P0_RX_DN<0>")
	)
	(arc
		(start 344.892884 -295.132506)
		(mid 344.955562 -294.877922)
		(end 345.129104 -294.681402)
		(width 0.1143)
		(layer "In13.Cu")
		(net "P5E_CPU0_P0_RX_DN<0>")
	)
	(arc
		(start 345.129104 -290.750498)
		(mid 344.885777 -290.285932)
		(end 345.129104 -289.821366)
		(width 0.1143)
		(layer "In13.Cu")
		(net "P5E_CPU0_P0_RX_DN<0>")
	)
	(arc
		(start 345.1987 -294.640762)
		(mid 345.355677 -294.335962)
		(end 345.1987 -294.031162)
		(width 0.1143)
		(layer "In13.Cu")
		(net "P5E_CPU0_P0_RX_DN<0>")
	)
	(arc
		(start 344.885772 -287.045908)
		(mid 344.950287 -286.783689)
		(end 345.129104 -286.581342)
		(width 0.1143)
		(layer "In13.Cu")
		(net "P5E_CPU0_P0_RX_DN<0>")
	)
	(arc
		(start 345.129104 -293.990522)
		(mid 344.885777 -293.525956)
		(end 345.129104 -293.06139)
		(width 0.1143)
		(layer "In13.Cu")
		(net "P5E_CPU0_P0_RX_DN<0>")
	)
	(arc
		(start 345.200732 -286.539686)
		(mid 345.314661 -286.406539)
		(end 345.355672 -286.236156)
		(width 0.1143)
		(layer "In13.Cu")
		(net "P5E_CPU0_P0_RX_DN<0>")
	)
	(arc
		(start 345.129104 -289.130486)
		(mid 344.885777 -288.66592)
		(end 345.129104 -288.201354)
		(width 0.1143)
		(layer "In13.Cu")
		(net "P5E_CPU0_P0_RX_DN<0>")
	)
	(arc
		(start 345.129104 -284.270704)
		(mid 344.885777 -283.806138)
		(end 345.129104 -283.341572)
		(width 0.1143)
		(layer "In13.Cu")
		(net "P5E_CPU0_P0_RX_DN<0>")
	)
	(arc
		(start 295.867582 -377.038362)
		(mid 295.903293 -376.858831)
		(end 296.004996 -376.706638)
		(width 0.14224)
		(layer "In13.Cu")
		(net "P5E_CPU0_P0_RX_DN<0>")
	)
	(arc
		(start 345.129104 -277.790656)
		(mid 344.885777 -277.32609)
		(end 345.129104 -276.861524)
		(width 0.1143)
		(layer "In13.Cu")
		(net "P5E_CPU0_P0_RX_DN<0>")
	)
	(arc
		(start 345.129104 -274.550632)
		(mid 344.885777 -274.086066)
		(end 345.129104 -273.6215)
		(width 0.1143)
		(layer "In13.Cu")
		(net "P5E_CPU0_P0_RX_DN<0>")
	)
	(arc
		(start 345.82989 -272.46326)
		(mid 345.904369 -272.183987)
		(end 346.10802 -271.978882)
		(width 0.1143)
		(layer "In13.Cu")
		(net "P5E_CPU0_P0_RX_DN<0>")
	)
	(arc
		(start 296.457624 -386.789676)
		(mid 296.026968 -386.394469)
		(end 295.867582 -385.832096)
		(width 0.14224)
		(layer "In13.Cu")
		(net "P5E_CPU0_P0_RX_DN<0>")
	)
	(arc
		(start 346.150184 -271.952212)
		(mid 346.240232 -271.851746)
		(end 346.288868 -271.725898)
		(width 0.1143)
		(layer "In13.Cu")
		(net "P5E_CPU0_P0_RX_DN<0>")
	)
	(arc
		(start 345.1987 -280.060908)
		(mid 345.355677 -279.756108)
		(end 345.1987 -279.451308)
		(width 0.1143)
		(layer "In13.Cu")
		(net "P5E_CPU0_P0_RX_DN<0>")
	)
	(arc
		(start 345.1987 -284.920944)
		(mid 345.355677 -284.616144)
		(end 345.1987 -284.311344)
		(width 0.1143)
		(layer "In13.Cu")
		(net "P5E_CPU0_P0_RX_DN<0>")
	)
	(arc
		(start 345.200732 -288.159698)
		(mid 345.314661 -288.026551)
		(end 345.355672 -287.856168)
		(width 0.1143)
		(layer "In13.Cu")
		(net "P5E_CPU0_P0_RX_DN<0>")
	)
	(arc
		(start 324.395338 -368.345466)
		(mid 325.717206 -368.149411)
		(end 327.051924 -368.083846)
		(width 0.14224)
		(layer "In13.Cu")
		(net "P5E_CPU0_P0_RX_DN<0>")
	)
	(arc
		(start 345.1987 -273.58086)
		(mid 345.314127 -273.447484)
		(end 345.355672 -273.27606)
		(width 0.1143)
		(layer "In13.Cu")
		(net "P5E_CPU0_P0_RX_DN<0>")
	)
	(arc
		(start 345.131644 -287.512252)
		(mid 344.950992 -287.309507)
		(end 344.885772 -287.045908)
		(width 0.1143)
		(layer "In13.Cu")
		(net "P5E_CPU0_P0_RX_DN<0>")
	)
	(arc
		(start 345.1987 -276.820884)
		(mid 345.355677 -276.516084)
		(end 345.1987 -276.211284)
		(width 0.1143)
		(layer "In13.Cu")
		(net "P5E_CPU0_P0_RX_DN<0>")
	)
	(arc
		(start 306.65547 -371.070124)
		(mid 306.750325 -371.051238)
		(end 306.83073 -370.99748)
		(width 0.14224)
		(layer "In13.Cu")
		(net "P5E_CPU0_P0_RX_DN<0>")
	)
	(arc
		(start 332.66761 -368.073686)
		(mid 342.668626 -368.29173)
		(end 352.652076 -368.923062)
		(width 0.14224)
		(layer "In13.Cu")
		(net "P5E_CPU0_P0_RX_DN<0>")
	)
	(arc
		(start 300.867572 -371.844062)
		(mid 301.724943 -371.271248)
		(end 302.73625 -371.070124)
		(width 0.14224)
		(layer "In13.Cu")
		(net "P5E_CPU0_P0_RX_DN<0>")
	)
	(arc
		(start 345.352878 -300.725078)
		(mid 344.977328 -300.061816)
		(end 344.847164 -299.310806)
		(width 0.14224)
		(layer "In13.Cu")
		(net "P5E_CPU0_P0_RX_DN<0>")
	)
	(arc
		(start 345.1987 -278.440896)
		(mid 345.355677 -278.136096)
		(end 345.1987 -277.831296)
		(width 0.1143)
		(layer "In13.Cu")
		(net "P5E_CPU0_P0_RX_DN<0>")
	)
	(arc
		(start 345.355672 -273.27606)
		(mid 345.420187 -273.013841)
		(end 345.599004 -272.811494)
		(width 0.1143)
		(layer "In13.Cu")
		(net "P5E_CPU0_P0_RX_DN<0>")
	)
	(arc
		(start 345.1987 -275.200872)
		(mid 345.355677 -274.896072)
		(end 345.1987 -274.591272)
		(width 0.1143)
		(layer "In13.Cu")
		(net "P5E_CPU0_P0_RX_DN<0>")
	)
	(arc
		(start 345.129104 -282.650692)
		(mid 344.885777 -282.186126)
		(end 345.129104 -281.72156)
		(width 0.1143)
		(layer "In13.Cu")
		(net "P5E_CPU0_P0_RX_DN<0>")
	)
	(arc
		(start 345.129104 -285.890716)
		(mid 344.885777 -285.42615)
		(end 345.129104 -284.961584)
		(width 0.1143)
		(layer "In13.Cu")
		(net "P5E_CPU0_P0_RX_DN<0>")
	)
	(arc
		(start 345.1987 -291.400738)
		(mid 345.355677 -291.095938)
		(end 345.1987 -290.791138)
		(width 0.1143)
		(layer "In13.Cu")
		(net "P5E_CPU0_P0_RX_DN<0>")
	)
	(arc
		(start 345.129104 -279.410668)
		(mid 344.885777 -278.946102)
		(end 345.129104 -278.481536)
		(width 0.1143)
		(layer "In13.Cu")
		(net "P5E_CPU0_P0_RX_DN<0>")
	)
	(arc
		(start 307.43779 -370.39042)
		(mid 307.570655 -370.301705)
		(end 307.72735 -370.270532)
		(width 0.14224)
		(layer "In13.Cu")
		(net "P5E_CPU0_P0_RX_DN<0>")
	)
	(arc
		(start 345.355672 -286.236156)
		(mid 345.314123 -286.064734)
		(end 345.1987 -285.931356)
		(width 0.1143)
		(layer "In13.Cu")
		(net "P5E_CPU0_P0_RX_DN<0>")
	)
	(arc
		(start 345.1987 -281.68092)
		(mid 345.355677 -281.37612)
		(end 345.1987 -281.07132)
		(width 0.1143)
		(layer "In13.Cu")
		(net "P5E_CPU0_P0_RX_DN<0>")
	)
	(arc
		(start 345.1987 -283.300932)
		(mid 345.355677 -282.996132)
		(end 345.1987 -282.691332)
		(width 0.1143)
		(layer "In13.Cu")
		(net "P5E_CPU0_P0_RX_DN<0>")
	)
	(arc
		(start 345.129104 -276.170644)
		(mid 344.885777 -275.706078)
		(end 345.129104 -275.241512)
		(width 0.1143)
		(layer "In13.Cu")
		(net "P5E_CPU0_P0_RX_DN<0>")
	)
	(arc
		(start 345.129104 -292.37051)
		(mid 344.885777 -291.905944)
		(end 345.129104 -291.441378)
		(width 0.1143)
		(layer "In13.Cu")
		(net "P5E_CPU0_P0_RX_DN<0>")
	)
	(arc
		(start 345.129104 -281.03068)
		(mid 344.885777 -280.566114)
		(end 345.129104 -280.101548)
		(width 0.1143)
		(layer "In13.Cu")
		(net "P5E_CPU0_P0_RX_DN<0>")
	)
	(arc
		(start 345.67749 -272.765012)
		(mid 345.789637 -272.632289)
		(end 345.82989 -272.46326)
		(width 0.1143)
		(layer "In13.Cu")
		(net "P5E_CPU0_P0_RX_DN<0>")
	)
	(arc
		(start 345.1987 -289.780726)
		(mid 345.355677 -289.475926)
		(end 345.1987 -289.171126)
		(width 0.1143)
		(layer "In13.Cu")
		(net "P5E_CPU0_P0_RX_DN<0>")
	)
	(arc
		(start 346.13977 -271.960086)
		(mid 346.145011 -271.956194)
		(end 346.150184 -271.952212)
		(width 0.1143)
		(layer "In13.Cu")
		(net "P5E_CPU0_P0_RX_DN<0>")
	)
	(arc
		(start 345.355672 -287.856168)
		(mid 345.314123 -287.684746)
		(end 345.1987 -287.551368)
		(width 0.1143)
		(layer "In13.Cu")
		(net "P5E_CPU0_P0_RX_DN<0>")
	)
	(arc
		(start 345.1987 -293.02075)
		(mid 345.355677 -292.71595)
		(end 345.1987 -292.41115)
		(width 0.1143)
		(layer "In13.Cu")
		(net "P5E_CPU0_P0_RX_DN<0>")
	)
	(arc
		(start 304.258472 -390.731756)
		(mid 304.237045 -390.661163)
		(end 304.179986 -390.614408)
		(width 0.14224)
		(layer "In13.Cu")
		(net "P5E_CPU0_P0_RX_DN<0>")
	)
	(segment
		(start 367.707926 -235.03001)
		(end 368.174778 -234.764072)
		(width 0.12954)
		(layer "F.Cu")
		(net "P5E_CPU0_G3_TX_DP<9>")
	)
	(segment
		(start 407.389838 -17.342612)
		(end 407.660348 -17.613122)
		(width 0.12954)
		(layer "F.Cu")
		(net "P5E_CPU0_G3_TX_DP<9>")
	)
	(segment
		(start 407.685748 -16.366998)
		(end 407.389838 -16.662908)
		(width 0.12954)
		(layer "F.Cu")
		(net "P5E_CPU0_G3_TX_DP<9>")
	)
	(segment
		(start 407.389838 -16.662908)
		(end 407.389838 -17.342612)
		(width 0.12954)
		(layer "F.Cu")
		(net "P5E_CPU0_G3_TX_DP<9>")
	)
	(segment
		(start 407.369518 -20.548346)
		(end 323.895212 -125.220476)
		(width 0.14224)
		(layer "In4.Cu")
		(net "P5E_CPU0_G3_TX_DP<9>")
	)
	(segment
		(start 311.89549 -157.174184)
		(end 311.73801 -157.965902)
		(width 0.14224)
		(layer "In4.Cu")
		(net "P5E_CPU0_G3_TX_DP<9>")
	)
	(segment
		(start 367.086896 -223.078802)
		(end 367.05032 -223.100138)
		(width 0.1143)
		(layer "In4.Cu")
		(net "P5E_CPU0_G3_TX_DP<9>")
	)
	(segment
		(start 366.146842 -229.55885)
		(end 366.107726 -229.58171)
		(width 0.1143)
		(layer "In4.Cu")
		(net "P5E_CPU0_G3_TX_DP<9>")
	)
	(segment
		(start 367.05032 -223.748346)
		(end 367.054892 -223.750886)
		(width 0.1143)
		(layer "In4.Cu")
		(net "P5E_CPU0_G3_TX_DP<9>")
	)
	(segment
		(start 367.04778 -233.46664)
		(end 367.086896 -233.4895)
		(width 0.1143)
		(layer "In4.Cu")
		(net "P5E_CPU0_G3_TX_DP<9>")
	)
	(segment
		(start 366.544352 -231.017064)
		(end 366.614202 -231.057704)
		(width 0.1143)
		(layer "In4.Cu")
		(net "P5E_CPU0_G3_TX_DP<9>")
	)
	(segment
		(start 367.086134 -224.699322)
		(end 367.047272 -224.721928)
		(width 0.1143)
		(layer "In4.Cu")
		(net "P5E_CPU0_G3_TX_DP<9>")
	)
	(segment
		(start 366.990884 -222.090488)
		(end 367.01603 -222.108522)
		(width 0.1143)
		(layer "In4.Cu")
		(net "P5E_CPU0_G3_TX_DP<9>")
	)
	(segment
		(start 367.05032 -223.100138)
		(end 367.048796 -223.101154)
		(width 0.1143)
		(layer "In4.Cu")
		(net "P5E_CPU0_G3_TX_DP<9>")
	)
	(segment
		(start 367.044224 -223.103694)
		(end 367.043462 -223.104202)
		(width 0.1143)
		(layer "In4.Cu")
		(net "P5E_CPU0_G3_TX_DP<9>")
	)
	(segment
		(start 407.369518 -17.903952)
		(end 407.369518 -20.548346)
		(width 0.14224)
		(layer "In4.Cu")
		(net "P5E_CPU0_G3_TX_DP<9>")
	)
	(segment
		(start 367.047018 -223.746314)
		(end 367.04778 -223.746822)
		(width 0.1143)
		(layer "In4.Cu")
		(net "P5E_CPU0_G3_TX_DP<9>")
	)
	(segment
		(start 323.4944 -174.512478)
		(end 361.733846 -205.849474)
		(width 0.14224)
		(layer "In4.Cu")
		(net "P5E_CPU0_G3_TX_DP<9>")
	)
	(segment
		(start 367.04143 -223.105218)
		(end 367.01603 -223.11995)
		(width 0.1143)
		(layer "In4.Cu")
		(net "P5E_CPU0_G3_TX_DP<9>")
	)
	(segment
		(start 366.851184 -225.051366)
		(end 366.851184 -225.058986)
		(width 0.1143)
		(layer "In4.Cu")
		(net "P5E_CPU0_G3_TX_DP<9>")
	)
	(segment
		(start 366.87252 -233.153204)
		(end 366.87252 -233.163364)
		(width 0.1143)
		(layer "In4.Cu")
		(net "P5E_CPU0_G3_TX_DP<9>")
	)
	(segment
		(start 367.048796 -223.74733)
		(end 367.05032 -223.748346)
		(width 0.1143)
		(layer "In4.Cu")
		(net "P5E_CPU0_G3_TX_DP<9>")
	)
	(segment
		(start 366.583468 -232.659682)
		(end 366.58423 -232.66019)
		(width 0.1143)
		(layer "In4.Cu")
		(net "P5E_CPU0_G3_TX_DP<9>")
	)
	(segment
		(start 323.017388 -174.124112)
		(end 323.421502 -174.43958)
		(width 0.14224)
		(layer "In4.Cu")
		(net "P5E_CPU0_G3_TX_DP<9>")
	)
	(segment
		(start 311.73801 -157.965902)
		(end 311.73801 -162.313874)
		(width 0.14224)
		(layer "In4.Cu")
		(net "P5E_CPU0_G3_TX_DP<9>")
	)
	(segment
		(start 366.107726 -229.58171)
		(end 366.075214 -229.600506)
		(width 0.1143)
		(layer "In4.Cu")
		(net "P5E_CPU0_G3_TX_DP<9>")
	)
	(segment
		(start 367.4872 -234.258866)
		(end 367.556796 -234.299506)
		(width 0.1143)
		(layer "In4.Cu")
		(net "P5E_CPU0_G3_TX_DP<9>")
	)
	(segment
		(start 366.860074 -221.412054)
		(end 366.860074 -221.834964)
		(width 0.1143)
		(layer "In4.Cu")
		(net "P5E_CPU0_G3_TX_DP<9>")
	)
	(segment
		(start 367.01603 -223.728534)
		(end 367.045748 -223.745552)
		(width 0.1143)
		(layer "In4.Cu")
		(net "P5E_CPU0_G3_TX_DP<9>")
	)
	(segment
		(start 367.01603 -222.108522)
		(end 367.086896 -222.14967)
		(width 0.1143)
		(layer "In4.Cu")
		(net "P5E_CPU0_G3_TX_DP<9>")
	)
	(segment
		(start 366.57788 -232.656634)
		(end 366.578896 -232.657142)
		(width 0.1143)
		(layer "In4.Cu")
		(net "P5E_CPU0_G3_TX_DP<9>")
	)
	(segment
		(start 367.047018 -223.10217)
		(end 367.044224 -223.103694)
		(width 0.1143)
		(layer "In4.Cu")
		(net "P5E_CPU0_G3_TX_DP<9>")
	)
	(segment
		(start 316.14999 -142.4686)
		(end 311.89549 -157.174184)
		(width 0.14224)
		(layer "In4.Cu")
		(net "P5E_CPU0_G3_TX_DP<9>")
	)
	(segment
		(start 366.58423 -232.66019)
		(end 366.591088 -232.664254)
		(width 0.1143)
		(layer "In4.Cu")
		(net "P5E_CPU0_G3_TX_DP<9>")
	)
	(segment
		(start 366.146842 -227.938838)
		(end 366.077246 -227.979478)
		(width 0.1143)
		(layer "In4.Cu")
		(net "P5E_CPU0_G3_TX_DP<9>")
	)
	(segment
		(start 367.04778 -223.746822)
		(end 367.048796 -223.74733)
		(width 0.1143)
		(layer "In4.Cu")
		(net "P5E_CPU0_G3_TX_DP<9>")
	)
	(segment
		(start 366.57153 -225.535236)
		(end 366.54613 -225.549968)
		(width 0.1143)
		(layer "In4.Cu")
		(net "P5E_CPU0_G3_TX_DP<9>")
	)
	(segment
		(start 366.930178 -221.083124)
		(end 366.884458 -221.128844)
		(width 0.1143)
		(layer "In4.Cu")
		(net "P5E_CPU0_G3_TX_DP<9>")
	)
	(segment
		(start 311.73801 -162.313874)
		(end 313.639962 -166.906448)
		(width 0.14224)
		(layer "In4.Cu")
		(net "P5E_CPU0_G3_TX_DP<9>")
	)
	(segment
		(start 317.62573 -170.892724)
		(end 323.017388 -174.124112)
		(width 0.14224)
		(layer "In4.Cu")
		(net "P5E_CPU0_G3_TX_DP<9>")
	)
	(segment
		(start 313.639962 -166.906448)
		(end 317.62573 -170.892724)
		(width 0.14224)
		(layer "In4.Cu")
		(net "P5E_CPU0_G3_TX_DP<9>")
	)
	(segment
		(start 367.794032 -234.681268)
		(end 367.876836 -234.764072)
		(width 0.1143)
		(layer "In4.Cu")
		(net "P5E_CPU0_G3_TX_DP<9>")
	)
	(segment
		(start 366.574324 -225.533712)
		(end 366.573562 -225.53422)
		(width 0.1143)
		(layer "In4.Cu")
		(net "P5E_CPU0_G3_TX_DP<9>")
	)
	(segment
		(start 366.560862 -232.646728)
		(end 366.569498 -232.651808)
		(width 0.1143)
		(layer "In4.Cu")
		(net "P5E_CPU0_G3_TX_DP<9>")
	)
	(segment
		(start 366.573562 -225.53422)
		(end 366.57153 -225.535236)
		(width 0.1143)
		(layer "In4.Cu")
		(net "P5E_CPU0_G3_TX_DP<9>")
	)
	(segment
		(start 323.421502 -174.43958)
		(end 323.4944 -174.512478)
		(width 0.14224)
		(layer "In4.Cu")
		(net "P5E_CPU0_G3_TX_DP<9>")
	)
	(segment
		(start 367.047272 -224.721928)
		(end 367.03762 -224.727262)
		(width 0.1143)
		(layer "In4.Cu")
		(net "P5E_CPU0_G3_TX_DP<9>")
	)
	(segment
		(start 366.077246 -226.969066)
		(end 366.146842 -227.009706)
		(width 0.1143)
		(layer "In4.Cu")
		(net "P5E_CPU0_G3_TX_DP<9>")
	)
	(segment
		(start 361.733846 -205.849474)
		(end 366.930178 -214.602822)
		(width 0.14224)
		(layer "In4.Cu")
		(net "P5E_CPU0_G3_TX_DP<9>")
	)
	(segment
		(start 367.048796 -223.101154)
		(end 367.04778 -223.101662)
		(width 0.1143)
		(layer "In4.Cu")
		(net "P5E_CPU0_G3_TX_DP<9>")
	)
	(segment
		(start 366.577118 -232.011982)
		(end 366.535208 -232.037128)
		(width 0.1143)
		(layer "In4.Cu")
		(net "P5E_CPU0_G3_TX_DP<9>")
	)
	(segment
		(start 320.499232 -131.150868)
		(end 316.14999 -142.4686)
		(width 0.14224)
		(layer "In4.Cu")
		(net "P5E_CPU0_G3_TX_DP<9>")
	)
	(segment
		(start 366.587786 -225.525584)
		(end 366.57788 -225.53168)
		(width 0.1143)
		(layer "In4.Cu")
		(net "P5E_CPU0_G3_TX_DP<9>")
	)
	(segment
		(start 366.077246 -230.208836)
		(end 366.144302 -230.247952)
		(width 0.1143)
		(layer "In4.Cu")
		(net "P5E_CPU0_G3_TX_DP<9>")
	)
	(segment
		(start 323.895212 -125.220476)
		(end 320.499232 -131.150868)
		(width 0.14224)
		(layer "In4.Cu")
		(net "P5E_CPU0_G3_TX_DP<9>")
	)
	(segment
		(start 366.884458 -221.128844)
		(end 366.884458 -221.38767)
		(width 0.1143)
		(layer "In4.Cu")
		(net "P5E_CPU0_G3_TX_DP<9>")
	)
	(segment
		(start 366.077246 -228.589078)
		(end 366.146842 -228.629718)
		(width 0.1143)
		(layer "In4.Cu")
		(net "P5E_CPU0_G3_TX_DP<9>")
	)
	(segment
		(start 366.577118 -225.532188)
		(end 366.574324 -225.533712)
		(width 0.1143)
		(layer "In4.Cu")
		(net "P5E_CPU0_G3_TX_DP<9>")
	)
	(segment
		(start 367.043462 -223.104202)
		(end 367.04143 -223.105218)
		(width 0.1143)
		(layer "In4.Cu")
		(net "P5E_CPU0_G3_TX_DP<9>")
	)
	(segment
		(start 366.575848 -232.655364)
		(end 366.577118 -232.656126)
		(width 0.1143)
		(layer "In4.Cu")
		(net "P5E_CPU0_G3_TX_DP<9>")
	)
	(segment
		(start 366.578642 -232.010966)
		(end 366.577118 -232.011982)
		(width 0.1143)
		(layer "In4.Cu")
		(net "P5E_CPU0_G3_TX_DP<9>")
	)
	(segment
		(start 366.58169 -232.658666)
		(end 366.583468 -232.659682)
		(width 0.1143)
		(layer "In4.Cu")
		(net "P5E_CPU0_G3_TX_DP<9>")
	)
	(segment
		(start 407.660348 -17.613122)
		(end 407.369518 -17.903952)
		(width 0.14224)
		(layer "In4.Cu")
		(net "P5E_CPU0_G3_TX_DP<9>")
	)
	(segment
		(start 366.578896 -232.657142)
		(end 366.579658 -232.65765)
		(width 0.1143)
		(layer "In4.Cu")
		(net "P5E_CPU0_G3_TX_DP<9>")
	)
	(segment
		(start 366.579658 -232.65765)
		(end 366.58169 -232.658666)
		(width 0.1143)
		(layer "In4.Cu")
		(net "P5E_CPU0_G3_TX_DP<9>")
	)
	(segment
		(start 366.930178 -214.602822)
		(end 366.930178 -221.083124)
		(width 0.14224)
		(layer "In4.Cu")
		(net "P5E_CPU0_G3_TX_DP<9>")
	)
	(segment
		(start 367.045748 -223.745552)
		(end 367.047018 -223.746314)
		(width 0.1143)
		(layer "In4.Cu")
		(net "P5E_CPU0_G3_TX_DP<9>")
	)
	(segment
		(start 366.569498 -232.651808)
		(end 366.575848 -232.655364)
		(width 0.1143)
		(layer "In4.Cu")
		(net "P5E_CPU0_G3_TX_DP<9>")
	)
	(segment
		(start 366.57788 -225.53168)
		(end 366.577118 -225.532188)
		(width 0.1143)
		(layer "In4.Cu")
		(net "P5E_CPU0_G3_TX_DP<9>")
	)
	(segment
		(start 366.146842 -226.318826)
		(end 366.077246 -226.359466)
		(width 0.1143)
		(layer "In4.Cu")
		(net "P5E_CPU0_G3_TX_DP<9>")
	)
	(segment
		(start 366.577118 -232.656126)
		(end 366.57788 -232.656634)
		(width 0.1143)
		(layer "In4.Cu")
		(net "P5E_CPU0_G3_TX_DP<9>")
	)
	(segment
		(start 367.04778 -223.101662)
		(end 367.047018 -223.10217)
		(width 0.1143)
		(layer "In4.Cu")
		(net "P5E_CPU0_G3_TX_DP<9>")
	)
	(segment
		(start 366.884458 -221.38767)
		(end 366.860074 -221.412054)
		(width 0.1143)
		(layer "In4.Cu")
		(net "P5E_CPU0_G3_TX_DP<9>")
	)
	(segment
		(start 367.876836 -234.764072)
		(end 368.174778 -234.764072)
		(width 0.1143)
		(layer "In4.Cu")
		(net "P5E_CPU0_G3_TX_DP<9>")
	)
	(segment
		(start 367.054892 -223.750886)
		(end 367.086896 -223.769682)
		(width 0.1143)
		(layer "In4.Cu")
		(net "P5E_CPU0_G3_TX_DP<9>")
	)
	(arc
		(start 366.146842 -228.629718)
		(mid 366.390169 -229.094284)
		(end 366.146842 -229.55885)
		(width 0.1143)
		(layer "In4.Cu")
		(net "P5E_CPU0_G3_TX_DP<9>")
	)
	(arc
		(start 367.086896 -223.769682)
		(mid 367.330223 -224.234248)
		(end 367.086896 -224.698814)
		(width 0.1143)
		(layer "In4.Cu")
		(net "P5E_CPU0_G3_TX_DP<9>")
	)
	(arc
		(start 366.860074 -221.834964)
		(mid 366.894606 -221.978544)
		(end 366.990884 -222.090488)
		(width 0.1143)
		(layer "In4.Cu")
		(net "P5E_CPU0_G3_TX_DP<9>")
	)
	(arc
		(start 367.330228 -233.954066)
		(mid 367.371777 -234.125488)
		(end 367.4872 -234.258866)
		(width 0.1143)
		(layer "In4.Cu")
		(net "P5E_CPU0_G3_TX_DP<9>")
	)
	(arc
		(start 367.03762 -224.727262)
		(mid 366.901108 -224.864412)
		(end 366.851184 -225.051366)
		(width 0.1143)
		(layer "In4.Cu")
		(net "P5E_CPU0_G3_TX_DP<9>")
	)
	(arc
		(start 366.390174 -230.714296)
		(mid 366.430936 -230.88418)
		(end 366.544352 -231.017064)
		(width 0.1143)
		(layer "In4.Cu")
		(net "P5E_CPU0_G3_TX_DP<9>")
	)
	(arc
		(start 366.851184 -225.058986)
		(mid 366.780797 -225.326904)
		(end 366.587786 -225.525584)
		(width 0.1143)
		(layer "In4.Cu")
		(net "P5E_CPU0_G3_TX_DP<9>")
	)
	(arc
		(start 366.535208 -232.037128)
		(mid 366.381538 -232.348989)
		(end 366.560862 -232.646728)
		(width 0.1143)
		(layer "In4.Cu")
		(net "P5E_CPU0_G3_TX_DP<9>")
	)
	(arc
		(start 366.390174 -225.85426)
		(mid 366.325659 -226.116479)
		(end 366.146842 -226.318826)
		(width 0.1143)
		(layer "In4.Cu")
		(net "P5E_CPU0_G3_TX_DP<9>")
	)
	(arc
		(start 366.146842 -227.009706)
		(mid 366.390169 -227.474272)
		(end 366.146842 -227.938838)
		(width 0.1143)
		(layer "In4.Cu")
		(net "P5E_CPU0_G3_TX_DP<9>")
	)
	(arc
		(start 366.87252 -233.163364)
		(mid 366.919487 -233.338499)
		(end 367.04778 -233.46664)
		(width 0.1143)
		(layer "In4.Cu")
		(net "P5E_CPU0_G3_TX_DP<9>")
	)
	(arc
		(start 367.086896 -233.4895)
		(mid 367.265709 -233.69185)
		(end 367.330228 -233.954066)
		(width 0.1143)
		(layer "In4.Cu")
		(net "P5E_CPU0_G3_TX_DP<9>")
	)
	(arc
		(start 367.01603 -223.11995)
		(mid 366.860102 -223.424242)
		(end 367.01603 -223.728534)
		(width 0.1143)
		(layer "In4.Cu")
		(net "P5E_CPU0_G3_TX_DP<9>")
	)
	(arc
		(start 365.920274 -229.904036)
		(mid 365.961823 -230.075458)
		(end 366.077246 -230.208836)
		(width 0.1143)
		(layer "In4.Cu")
		(net "P5E_CPU0_G3_TX_DP<9>")
	)
	(arc
		(start 366.075214 -229.600506)
		(mid 365.961285 -229.733653)
		(end 365.920274 -229.904036)
		(width 0.1143)
		(layer "In4.Cu")
		(net "P5E_CPU0_G3_TX_DP<9>")
	)
	(arc
		(start 367.086896 -224.698814)
		(mid 367.086515 -224.699068)
		(end 367.086134 -224.699322)
		(width 0.1143)
		(layer "In4.Cu")
		(net "P5E_CPU0_G3_TX_DP<9>")
	)
	(arc
		(start 366.077246 -226.359466)
		(mid 365.920269 -226.664266)
		(end 366.077246 -226.969066)
		(width 0.1143)
		(layer "In4.Cu")
		(net "P5E_CPU0_G3_TX_DP<9>")
	)
	(arc
		(start 367.556796 -234.299506)
		(mid 367.708783 -234.456014)
		(end 367.790222 -234.658408)
		(width 0.1143)
		(layer "In4.Cu")
		(net "P5E_CPU0_G3_TX_DP<9>")
	)
	(arc
		(start 366.54613 -225.549968)
		(mid 366.431454 -225.683302)
		(end 366.390174 -225.85426)
		(width 0.1143)
		(layer "In4.Cu")
		(net "P5E_CPU0_G3_TX_DP<9>")
	)
	(arc
		(start 367.790222 -234.658408)
		(mid 367.792245 -234.669818)
		(end 367.794032 -234.681268)
		(width 0.1143)
		(layer "In4.Cu")
		(net "P5E_CPU0_G3_TX_DP<9>")
	)
	(arc
		(start 366.614202 -231.057704)
		(mid 366.859081 -231.544098)
		(end 366.578642 -232.010966)
		(width 0.1143)
		(layer "In4.Cu")
		(net "P5E_CPU0_G3_TX_DP<9>")
	)
	(arc
		(start 366.077246 -227.979478)
		(mid 365.920269 -228.284278)
		(end 366.077246 -228.589078)
		(width 0.1143)
		(layer "In4.Cu")
		(net "P5E_CPU0_G3_TX_DP<9>")
	)
	(arc
		(start 366.591088 -232.664254)
		(mid 366.797156 -232.871117)
		(end 366.87252 -233.153204)
		(width 0.1143)
		(layer "In4.Cu")
		(net "P5E_CPU0_G3_TX_DP<9>")
	)
	(arc
		(start 367.086896 -222.14967)
		(mid 367.330223 -222.614236)
		(end 367.086896 -223.078802)
		(width 0.1143)
		(layer "In4.Cu")
		(net "P5E_CPU0_G3_TX_DP<9>")
	)
	(arc
		(start 366.144302 -230.247952)
		(mid 366.324954 -230.450697)
		(end 366.390174 -230.714296)
		(width 0.1143)
		(layer "In4.Cu")
		(net "P5E_CPU0_G3_TX_DP<9>")
	)
	(segment
		(start 410.184854 -18.86585)
		(end 410.455364 -19.13636)
		(width 0.12954)
		(layer "F.Cu")
		(net "P5E_CPU0_G3_TX_DP<8>")
	)
	(segment
		(start 410.184854 -18.185892)
		(end 410.184854 -18.86585)
		(width 0.12954)
		(layer "F.Cu")
		(net "P5E_CPU0_G3_TX_DP<8>")
	)
	(segment
		(start 367.707926 -231.789986)
		(end 368.174778 -231.524048)
		(width 0.12954)
		(layer "F.Cu")
		(net "P5E_CPU0_G3_TX_DP<8>")
	)
	(segment
		(start 410.479748 -17.890998)
		(end 410.184854 -18.185892)
		(width 0.12954)
		(layer "F.Cu")
		(net "P5E_CPU0_G3_TX_DP<8>")
	)
	(segment
		(start 367.799874 -221.422468)
		(end 367.799874 -221.804484)
		(width 0.1143)
		(layer "In4.Cu")
		(net "P5E_CPU0_G3_TX_DP<8>")
	)
	(segment
		(start 367.017046 -226.969066)
		(end 367.086642 -227.009706)
		(width 0.1143)
		(layer "In4.Cu")
		(net "P5E_CPU0_G3_TX_DP<8>")
	)
	(segment
		(start 367.52022 -225.530156)
		(end 367.518696 -225.531172)
		(width 0.1143)
		(layer "In4.Cu")
		(net "P5E_CPU0_G3_TX_DP<8>")
	)
	(segment
		(start 367.987072 -222.126302)
		(end 367.987834 -222.12681)
		(width 0.1143)
		(layer "In4.Cu")
		(net "P5E_CPU0_G3_TX_DP<8>")
	)
	(segment
		(start 367.975896 -222.119952)
		(end 367.977928 -222.120968)
		(width 0.1143)
		(layer "In4.Cu")
		(net "P5E_CPU0_G3_TX_DP<8>")
	)
	(segment
		(start 367.9571 -223.729042)
		(end 368.026696 -223.769682)
		(width 0.1143)
		(layer "In4.Cu")
		(net "P5E_CPU0_G3_TX_DP<8>")
	)
	(segment
		(start 367.98123 -222.123)
		(end 367.981992 -222.123508)
		(width 0.1143)
		(layer "In4.Cu")
		(net "P5E_CPU0_G3_TX_DP<8>")
	)
	(segment
		(start 312.67019 -158.058866)
		(end 312.67019 -162.1282)
		(width 0.14224)
		(layer "In4.Cu")
		(net "P5E_CPU0_G3_TX_DP<8>")
	)
	(segment
		(start 367.979198 -222.12173)
		(end 367.98123 -222.123)
		(width 0.1143)
		(layer "In4.Cu")
		(net "P5E_CPU0_G3_TX_DP<8>")
	)
	(segment
		(start 367.51768 -225.53168)
		(end 367.516918 -225.532188)
		(width 0.1143)
		(layer "In4.Cu")
		(net "P5E_CPU0_G3_TX_DP<8>")
	)
	(segment
		(start 410.164534 -20.547584)
		(end 324.283832 -126.466346)
		(width 0.14224)
		(layer "In4.Cu")
		(net "P5E_CPU0_G3_TX_DP<8>")
	)
	(segment
		(start 367.017046 -228.589078)
		(end 367.086642 -228.629718)
		(width 0.1143)
		(layer "In4.Cu")
		(net "P5E_CPU0_G3_TX_DP<8>")
	)
	(segment
		(start 367.876836 -231.524048)
		(end 368.174778 -231.524048)
		(width 0.1143)
		(layer "In4.Cu")
		(net "P5E_CPU0_G3_TX_DP<8>")
	)
	(segment
		(start 367.047526 -229.58171)
		(end 367.015014 -229.600506)
		(width 0.1143)
		(layer "In4.Cu")
		(net "P5E_CPU0_G3_TX_DP<8>")
	)
	(segment
		(start 367.086642 -227.938838)
		(end 367.017046 -227.979478)
		(width 0.1143)
		(layer "In4.Cu")
		(net "P5E_CPU0_G3_TX_DP<8>")
	)
	(segment
		(start 367.017046 -230.208836)
		(end 367.084102 -230.247952)
		(width 0.1143)
		(layer "In4.Cu")
		(net "P5E_CPU0_G3_TX_DP<8>")
	)
	(segment
		(start 367.981992 -222.123508)
		(end 367.983516 -222.12427)
		(width 0.1143)
		(layer "In4.Cu")
		(net "P5E_CPU0_G3_TX_DP<8>")
	)
	(segment
		(start 367.834672 -221.128844)
		(end 367.834672 -221.38767)
		(width 0.1143)
		(layer "In4.Cu")
		(net "P5E_CPU0_G3_TX_DP<8>")
	)
	(segment
		(start 367.983516 -222.12427)
		(end 367.984278 -222.124778)
		(width 0.1143)
		(layer "In4.Cu")
		(net "P5E_CPU0_G3_TX_DP<8>")
	)
	(segment
		(start 368.026696 -223.078802)
		(end 367.9571 -223.119442)
		(width 0.1143)
		(layer "In4.Cu")
		(net "P5E_CPU0_G3_TX_DP<8>")
	)
	(segment
		(start 367.516918 -225.532188)
		(end 367.48593 -225.549968)
		(width 0.1143)
		(layer "In4.Cu")
		(net "P5E_CPU0_G3_TX_DP<8>")
	)
	(segment
		(start 368.026696 -224.698814)
		(end 367.9571 -224.739454)
		(width 0.1143)
		(layer "In4.Cu")
		(net "P5E_CPU0_G3_TX_DP<8>")
	)
	(segment
		(start 318.19977 -170.147996)
		(end 324.060566 -173.662086)
		(width 0.14224)
		(layer "In4.Cu")
		(net "P5E_CPU0_G3_TX_DP<8>")
	)
	(segment
		(start 367.834672 -221.38767)
		(end 367.799874 -221.422468)
		(width 0.1143)
		(layer "In4.Cu")
		(net "P5E_CPU0_G3_TX_DP<8>")
	)
	(segment
		(start 367.880392 -214.375492)
		(end 367.880392 -221.083124)
		(width 0.14224)
		(layer "In4.Cu")
		(net "P5E_CPU0_G3_TX_DP<8>")
	)
	(segment
		(start 367.987834 -222.12681)
		(end 367.98885 -222.127318)
		(width 0.1143)
		(layer "In4.Cu")
		(net "P5E_CPU0_G3_TX_DP<8>")
	)
	(segment
		(start 324.060566 -173.662086)
		(end 324.5358 -174.03318)
		(width 0.14224)
		(layer "In4.Cu")
		(net "P5E_CPU0_G3_TX_DP<8>")
	)
	(segment
		(start 367.98885 -222.127318)
		(end 368.02695 -222.14967)
		(width 0.1143)
		(layer "In4.Cu")
		(net "P5E_CPU0_G3_TX_DP<8>")
	)
	(segment
		(start 321.343274 -131.553712)
		(end 317.034418 -142.76705)
		(width 0.14224)
		(layer "In4.Cu")
		(net "P5E_CPU0_G3_TX_DP<8>")
	)
	(segment
		(start 367.799874 -221.804484)
		(end 367.800128 -221.80423)
		(width 0.1143)
		(layer "In4.Cu")
		(net "P5E_CPU0_G3_TX_DP<8>")
	)
	(segment
		(start 367.956084 -222.108522)
		(end 367.975896 -222.119952)
		(width 0.1143)
		(layer "In4.Cu")
		(net "P5E_CPU0_G3_TX_DP<8>")
	)
	(segment
		(start 410.164534 -19.42719)
		(end 410.164534 -20.547584)
		(width 0.14224)
		(layer "In4.Cu")
		(net "P5E_CPU0_G3_TX_DP<8>")
	)
	(segment
		(start 410.455364 -19.13636)
		(end 410.164534 -19.42719)
		(width 0.14224)
		(layer "In4.Cu")
		(net "P5E_CPU0_G3_TX_DP<8>")
	)
	(segment
		(start 368.270282 -222.614236)
		(end 368.270028 -222.614236)
		(width 0.1143)
		(layer "In4.Cu")
		(net "P5E_CPU0_G3_TX_DP<8>")
	)
	(segment
		(start 367.880392 -221.083124)
		(end 367.834672 -221.128844)
		(width 0.1143)
		(layer "In4.Cu")
		(net "P5E_CPU0_G3_TX_DP<8>")
	)
	(segment
		(start 314.429902 -166.377366)
		(end 318.19977 -170.147996)
		(width 0.14224)
		(layer "In4.Cu")
		(net "P5E_CPU0_G3_TX_DP<8>")
	)
	(segment
		(start 324.283832 -126.466346)
		(end 321.343274 -131.553712)
		(width 0.14224)
		(layer "In4.Cu")
		(net "P5E_CPU0_G3_TX_DP<8>")
	)
	(segment
		(start 367.984278 -222.124778)
		(end 367.987072 -222.126302)
		(width 0.1143)
		(layer "In4.Cu")
		(net "P5E_CPU0_G3_TX_DP<8>")
	)
	(segment
		(start 362.305092 -204.985366)
		(end 367.880392 -214.375492)
		(width 0.14224)
		(layer "In4.Cu")
		(net "P5E_CPU0_G3_TX_DP<8>")
	)
	(segment
		(start 317.034418 -142.76705)
		(end 312.801762 -157.39745)
		(width 0.14224)
		(layer "In4.Cu")
		(net "P5E_CPU0_G3_TX_DP<8>")
	)
	(segment
		(start 367.086642 -229.55885)
		(end 367.047526 -229.58171)
		(width 0.1143)
		(layer "In4.Cu")
		(net "P5E_CPU0_G3_TX_DP<8>")
	)
	(segment
		(start 367.556796 -225.50882)
		(end 367.52022 -225.530156)
		(width 0.1143)
		(layer "In4.Cu")
		(net "P5E_CPU0_G3_TX_DP<8>")
	)
	(segment
		(start 367.518696 -225.531172)
		(end 367.51768 -225.53168)
		(width 0.1143)
		(layer "In4.Cu")
		(net "P5E_CPU0_G3_TX_DP<8>")
	)
	(segment
		(start 367.794032 -231.441244)
		(end 367.876836 -231.524048)
		(width 0.1143)
		(layer "In4.Cu")
		(net "P5E_CPU0_G3_TX_DP<8>")
	)
	(segment
		(start 324.5358 -174.03318)
		(end 362.305092 -204.985366)
		(width 0.14224)
		(layer "In4.Cu")
		(net "P5E_CPU0_G3_TX_DP<8>")
	)
	(segment
		(start 367.977928 -222.120968)
		(end 367.979198 -222.12173)
		(width 0.1143)
		(layer "In4.Cu")
		(net "P5E_CPU0_G3_TX_DP<8>")
	)
	(segment
		(start 367.086642 -226.318826)
		(end 367.017046 -226.359466)
		(width 0.1143)
		(layer "In4.Cu")
		(net "P5E_CPU0_G3_TX_DP<8>")
	)
	(segment
		(start 312.801762 -157.39745)
		(end 312.67019 -158.058866)
		(width 0.14224)
		(layer "In4.Cu")
		(net "P5E_CPU0_G3_TX_DP<8>")
	)
	(segment
		(start 312.67019 -162.1282)
		(end 314.429902 -166.377366)
		(width 0.14224)
		(layer "In4.Cu")
		(net "P5E_CPU0_G3_TX_DP<8>")
	)
	(segment
		(start 367.484152 -231.017064)
		(end 367.556796 -231.059482)
		(width 0.1143)
		(layer "In4.Cu")
		(net "P5E_CPU0_G3_TX_DP<8>")
	)
	(arc
		(start 367.329974 -225.85426)
		(mid 367.265459 -226.116479)
		(end 367.086642 -226.318826)
		(width 0.1143)
		(layer "In4.Cu")
		(net "P5E_CPU0_G3_TX_DP<8>")
	)
	(arc
		(start 367.084102 -230.247952)
		(mid 367.264754 -230.450697)
		(end 367.329974 -230.714296)
		(width 0.1143)
		(layer "In4.Cu")
		(net "P5E_CPU0_G3_TX_DP<8>")
	)
	(arc
		(start 367.086642 -228.629718)
		(mid 367.329969 -229.094284)
		(end 367.086642 -229.55885)
		(width 0.1143)
		(layer "In4.Cu")
		(net "P5E_CPU0_G3_TX_DP<8>")
	)
	(arc
		(start 367.329974 -230.714296)
		(mid 367.370736 -230.88418)
		(end 367.484152 -231.017064)
		(width 0.1143)
		(layer "In4.Cu")
		(net "P5E_CPU0_G3_TX_DP<8>")
	)
	(arc
		(start 368.026696 -223.769682)
		(mid 368.270023 -224.234248)
		(end 368.026696 -224.698814)
		(width 0.1143)
		(layer "In4.Cu")
		(net "P5E_CPU0_G3_TX_DP<8>")
	)
	(arc
		(start 367.866168 -222.016574)
		(mid 367.907151 -222.066436)
		(end 367.956084 -222.108522)
		(width 0.1143)
		(layer "In4.Cu")
		(net "P5E_CPU0_G3_TX_DP<8>")
	)
	(arc
		(start 367.017046 -227.979478)
		(mid 366.860069 -228.284278)
		(end 367.017046 -228.589078)
		(width 0.1143)
		(layer "In4.Cu")
		(net "P5E_CPU0_G3_TX_DP<8>")
	)
	(arc
		(start 367.812066 -221.898464)
		(mid 367.833944 -221.95989)
		(end 367.866168 -222.016574)
		(width 0.1143)
		(layer "In4.Cu")
		(net "P5E_CPU0_G3_TX_DP<8>")
	)
	(arc
		(start 367.017046 -226.359466)
		(mid 366.860069 -226.664266)
		(end 367.017046 -226.969066)
		(width 0.1143)
		(layer "In4.Cu")
		(net "P5E_CPU0_G3_TX_DP<8>")
	)
	(arc
		(start 367.48593 -225.549968)
		(mid 367.371254 -225.683302)
		(end 367.329974 -225.85426)
		(width 0.1143)
		(layer "In4.Cu")
		(net "P5E_CPU0_G3_TX_DP<8>")
	)
	(arc
		(start 367.9571 -223.119442)
		(mid 367.800123 -223.424242)
		(end 367.9571 -223.729042)
		(width 0.1143)
		(layer "In4.Cu")
		(net "P5E_CPU0_G3_TX_DP<8>")
	)
	(arc
		(start 367.9571 -224.739454)
		(mid 367.841673 -224.87283)
		(end 367.800128 -225.044254)
		(width 0.1143)
		(layer "In4.Cu")
		(net "P5E_CPU0_G3_TX_DP<8>")
	)
	(arc
		(start 367.800128 -221.80423)
		(mid 367.803086 -221.851729)
		(end 367.812066 -221.898464)
		(width 0.1143)
		(layer "In4.Cu")
		(net "P5E_CPU0_G3_TX_DP<8>")
	)
	(arc
		(start 367.790222 -231.418384)
		(mid 367.792245 -231.429794)
		(end 367.794032 -231.441244)
		(width 0.1143)
		(layer "In4.Cu")
		(net "P5E_CPU0_G3_TX_DP<8>")
	)
	(arc
		(start 367.800128 -225.044254)
		(mid 367.735613 -225.306473)
		(end 367.556796 -225.50882)
		(width 0.1143)
		(layer "In4.Cu")
		(net "P5E_CPU0_G3_TX_DP<8>")
	)
	(arc
		(start 367.086642 -227.009706)
		(mid 367.329969 -227.474272)
		(end 367.086642 -227.938838)
		(width 0.1143)
		(layer "In4.Cu")
		(net "P5E_CPU0_G3_TX_DP<8>")
	)
	(arc
		(start 368.02695 -222.14967)
		(mid 368.205763 -222.35202)
		(end 368.270282 -222.614236)
		(width 0.1143)
		(layer "In4.Cu")
		(net "P5E_CPU0_G3_TX_DP<8>")
	)
	(arc
		(start 367.556796 -231.059482)
		(mid 367.708783 -231.21599)
		(end 367.790222 -231.418384)
		(width 0.1143)
		(layer "In4.Cu")
		(net "P5E_CPU0_G3_TX_DP<8>")
	)
	(arc
		(start 368.270028 -222.614236)
		(mid 368.205513 -222.876455)
		(end 368.026696 -223.078802)
		(width 0.1143)
		(layer "In4.Cu")
		(net "P5E_CPU0_G3_TX_DP<8>")
	)
	(arc
		(start 367.015014 -229.600506)
		(mid 366.901085 -229.733653)
		(end 366.860074 -229.904036)
		(width 0.1143)
		(layer "In4.Cu")
		(net "P5E_CPU0_G3_TX_DP<8>")
	)
	(arc
		(start 366.860074 -229.904036)
		(mid 366.901623 -230.075458)
		(end 367.017046 -230.208836)
		(width 0.1143)
		(layer "In4.Cu")
		(net "P5E_CPU0_G3_TX_DP<8>")
	)
	(segment
		(start 367.707926 -233.409998)
		(end 368.174778 -233.14406)
		(width 0.12954)
		(layer "F.Cu")
		(net "P5E_CPU0_G3_TX_DP<7>")
	)
	(segment
		(start 412.978854 -16.661892)
		(end 412.978854 -17.343628)
		(width 0.12954)
		(layer "F.Cu")
		(net "P5E_CPU0_G3_TX_DP<7>")
	)
	(segment
		(start 413.273748 -16.366998)
		(end 412.978854 -16.661892)
		(width 0.12954)
		(layer "F.Cu")
		(net "P5E_CPU0_G3_TX_DP<7>")
	)
	(segment
		(start 412.978854 -17.343628)
		(end 413.248348 -17.613122)
		(width 0.12954)
		(layer "F.Cu")
		(net "P5E_CPU0_G3_TX_DP<7>")
	)
	(segment
		(start 368.452146 -225.534982)
		(end 368.42827 -225.548698)
		(width 0.1143)
		(layer "In4.Cu")
		(net "P5E_CPU0_G3_TX_DP<7>")
	)
	(segment
		(start 368.496088 -231.989122)
		(end 368.457226 -232.011728)
		(width 0.1143)
		(layer "In4.Cu")
		(net "P5E_CPU0_G3_TX_DP<7>")
	)
	(segment
		(start 367.985802 -232.82275)
		(end 367.956084 -232.839768)
		(width 0.1143)
		(layer "In4.Cu")
		(net "P5E_CPU0_G3_TX_DP<7>")
	)
	(segment
		(start 368.428016 -231.019604)
		(end 368.49685 -231.059482)
		(width 0.1143)
		(layer "In4.Cu")
		(net "P5E_CPU0_G3_TX_DP<7>")
	)
	(segment
		(start 367.985802 -228.605588)
		(end 367.987072 -228.60635)
		(width 0.1143)
		(layer "In4.Cu")
		(net "P5E_CPU0_G3_TX_DP<7>")
	)
	(segment
		(start 324.687692 -127.670052)
		(end 322.188332 -131.955032)
		(width 0.14224)
		(layer "In4.Cu")
		(net "P5E_CPU0_G3_TX_DP<7>")
	)
	(segment
		(start 368.024156 -227.940616)
		(end 367.987834 -227.961698)
		(width 0.1143)
		(layer "In4.Cu")
		(net "P5E_CPU0_G3_TX_DP<7>")
	)
	(segment
		(start 367.987072 -226.342194)
		(end 367.985802 -226.342956)
		(width 0.1143)
		(layer "In4.Cu")
		(net "P5E_CPU0_G3_TX_DP<7>")
	)
	(segment
		(start 315.220096 -165.848792)
		(end 318.364362 -168.99382)
		(width 0.14224)
		(layer "In4.Cu")
		(net "P5E_CPU0_G3_TX_DP<7>")
	)
	(segment
		(start 412.957518 -20.548346)
		(end 324.687692 -127.670052)
		(width 0.14224)
		(layer "In4.Cu")
		(net "P5E_CPU0_G3_TX_DP<7>")
	)
	(segment
		(start 369.397788 -222.291656)
		(end 369.366038 -222.309944)
		(width 0.1143)
		(layer "In4.Cu")
		(net "P5E_CPU0_G3_TX_DP<7>")
	)
	(segment
		(start 369.401344 -222.289624)
		(end 369.400328 -222.290132)
		(width 0.1143)
		(layer "In4.Cu")
		(net "P5E_CPU0_G3_TX_DP<7>")
	)
	(segment
		(start 367.987834 -226.341686)
		(end 367.987072 -226.342194)
		(width 0.1143)
		(layer "In4.Cu")
		(net "P5E_CPU0_G3_TX_DP<7>")
	)
	(segment
		(start 321.457066 -171.013628)
		(end 322.346574 -171.502578)
		(width 0.14224)
		(layer "In4.Cu")
		(net "P5E_CPU0_G3_TX_DP<7>")
	)
	(segment
		(start 369.398804 -222.291148)
		(end 369.397788 -222.291656)
		(width 0.1143)
		(layer "In4.Cu")
		(net "P5E_CPU0_G3_TX_DP<7>")
	)
	(segment
		(start 368.024156 -229.560628)
		(end 367.956338 -229.599744)
		(width 0.1143)
		(layer "In4.Cu")
		(net "P5E_CPU0_G3_TX_DP<7>")
	)
	(segment
		(start 368.96675 -224.698814)
		(end 368.897154 -224.739454)
		(width 0.1143)
		(layer "In4.Cu")
		(net "P5E_CPU0_G3_TX_DP<7>")
	)
	(segment
		(start 367.987834 -228.606858)
		(end 368.024156 -228.62794)
		(width 0.1143)
		(layer "In4.Cu")
		(net "P5E_CPU0_G3_TX_DP<7>")
	)
	(segment
		(start 318.364362 -168.99382)
		(end 321.457066 -171.013628)
		(width 0.14224)
		(layer "In4.Cu")
		(net "P5E_CPU0_G3_TX_DP<7>")
	)
	(segment
		(start 367.956338 -229.599744)
		(end 367.956084 -229.599998)
		(width 0.1143)
		(layer "In4.Cu")
		(net "P5E_CPU0_G3_TX_DP<7>")
	)
	(segment
		(start 367.985802 -226.342956)
		(end 367.956084 -226.359974)
		(width 0.1143)
		(layer "In4.Cu")
		(net "P5E_CPU0_G3_TX_DP<7>")
	)
	(segment
		(start 368.45621 -225.532696)
		(end 368.454178 -225.533712)
		(width 0.1143)
		(layer "In4.Cu")
		(net "P5E_CPU0_G3_TX_DP<7>")
	)
	(segment
		(start 313.60237 -158.1531)
		(end 313.60237 -161.942272)
		(width 0.14224)
		(layer "In4.Cu")
		(net "P5E_CPU0_G3_TX_DP<7>")
	)
	(segment
		(start 313.60237 -161.942272)
		(end 315.220096 -165.848792)
		(width 0.14224)
		(layer "In4.Cu")
		(net "P5E_CPU0_G3_TX_DP<7>")
	)
	(segment
		(start 369.725702 -221.083124)
		(end 369.679982 -221.128844)
		(width 0.1143)
		(layer "In4.Cu")
		(net "P5E_CPU0_G3_TX_DP<7>")
	)
	(segment
		(start 412.957518 -17.903952)
		(end 412.957518 -20.548346)
		(width 0.14224)
		(layer "In4.Cu")
		(net "P5E_CPU0_G3_TX_DP<7>")
	)
	(segment
		(start 367.956084 -228.58857)
		(end 367.985802 -228.605588)
		(width 0.1143)
		(layer "In4.Cu")
		(net "P5E_CPU0_G3_TX_DP<7>")
	)
	(segment
		(start 368.454178 -225.533712)
		(end 368.453416 -225.53422)
		(width 0.1143)
		(layer "In4.Cu")
		(net "P5E_CPU0_G3_TX_DP<7>")
	)
	(segment
		(start 367.987072 -226.986338)
		(end 367.987834 -226.986846)
		(width 0.1143)
		(layer "In4.Cu")
		(net "P5E_CPU0_G3_TX_DP<7>")
	)
	(segment
		(start 367.98631 -230.228902)
		(end 367.990882 -230.231696)
		(width 0.1143)
		(layer "In4.Cu")
		(net "P5E_CPU0_G3_TX_DP<7>")
	)
	(segment
		(start 367.806986 -233.07421)
		(end 367.876836 -233.14406)
		(width 0.1143)
		(layer "In4.Cu")
		(net "P5E_CPU0_G3_TX_DP<7>")
	)
	(segment
		(start 368.897154 -223.729042)
		(end 368.96675 -223.769682)
		(width 0.1143)
		(layer "In4.Cu")
		(net "P5E_CPU0_G3_TX_DP<7>")
	)
	(segment
		(start 367.985802 -226.985576)
		(end 367.987072 -226.986338)
		(width 0.1143)
		(layer "In4.Cu")
		(net "P5E_CPU0_G3_TX_DP<7>")
	)
	(segment
		(start 367.987072 -228.60635)
		(end 367.987834 -228.606858)
		(width 0.1143)
		(layer "In4.Cu")
		(net "P5E_CPU0_G3_TX_DP<7>")
	)
	(segment
		(start 368.457734 -225.53168)
		(end 368.45621 -225.532696)
		(width 0.1143)
		(layer "In4.Cu")
		(net "P5E_CPU0_G3_TX_DP<7>")
	)
	(segment
		(start 367.991136 -232.819702)
		(end 367.988596 -232.820972)
		(width 0.1143)
		(layer "In4.Cu")
		(net "P5E_CPU0_G3_TX_DP<7>")
	)
	(segment
		(start 368.96675 -223.078802)
		(end 368.897154 -223.119442)
		(width 0.1143)
		(layer "In4.Cu")
		(net "P5E_CPU0_G3_TX_DP<7>")
	)
	(segment
		(start 367.988596 -232.820972)
		(end 367.987072 -232.821988)
		(width 0.1143)
		(layer "In4.Cu")
		(net "P5E_CPU0_G3_TX_DP<7>")
	)
	(segment
		(start 367.987072 -227.962206)
		(end 367.985802 -227.962968)
		(width 0.1143)
		(layer "In4.Cu")
		(net "P5E_CPU0_G3_TX_DP<7>")
	)
	(segment
		(start 367.985802 -227.962968)
		(end 367.956084 -227.979986)
		(width 0.1143)
		(layer "In4.Cu")
		(net "P5E_CPU0_G3_TX_DP<7>")
	)
	(segment
		(start 367.876836 -233.14406)
		(end 368.174778 -233.14406)
		(width 0.1143)
		(layer "In4.Cu")
		(net "P5E_CPU0_G3_TX_DP<7>")
	)
	(segment
		(start 322.188332 -131.955032)
		(end 317.919354 -143.063976)
		(width 0.14224)
		(layer "In4.Cu")
		(net "P5E_CPU0_G3_TX_DP<7>")
	)
	(segment
		(start 413.248348 -17.613122)
		(end 412.957518 -17.903952)
		(width 0.14224)
		(layer "In4.Cu")
		(net "P5E_CPU0_G3_TX_DP<7>")
	)
	(segment
		(start 368.026696 -226.31908)
		(end 367.990628 -226.339908)
		(width 0.1143)
		(layer "In4.Cu")
		(net "P5E_CPU0_G3_TX_DP<7>")
	)
	(segment
		(start 367.987072 -232.821988)
		(end 367.985802 -232.82275)
		(width 0.1143)
		(layer "In4.Cu")
		(net "P5E_CPU0_G3_TX_DP<7>")
	)
	(segment
		(start 368.458242 -225.531172)
		(end 368.457734 -225.53168)
		(width 0.1143)
		(layer "In4.Cu")
		(net "P5E_CPU0_G3_TX_DP<7>")
	)
	(segment
		(start 368.270028 -225.85426)
		(end 368.270028 -225.861372)
		(width 0.1143)
		(layer "In4.Cu")
		(net "P5E_CPU0_G3_TX_DP<7>")
	)
	(segment
		(start 367.990628 -226.339908)
		(end 367.987834 -226.341686)
		(width 0.1143)
		(layer "In4.Cu")
		(net "P5E_CPU0_G3_TX_DP<7>")
	)
	(segment
		(start 317.919354 -143.063976)
		(end 313.708542 -157.618938)
		(width 0.14224)
		(layer "In4.Cu")
		(net "P5E_CPU0_G3_TX_DP<7>")
	)
	(segment
		(start 313.708542 -157.618938)
		(end 313.60237 -158.1531)
		(width 0.14224)
		(layer "In4.Cu")
		(net "P5E_CPU0_G3_TX_DP<7>")
	)
	(segment
		(start 369.436904 -222.268796)
		(end 369.40617 -222.28683)
		(width 0.1143)
		(layer "In4.Cu")
		(net "P5E_CPU0_G3_TX_DP<7>")
	)
	(segment
		(start 369.725702 -220.853508)
		(end 369.725702 -221.083124)
		(width 0.14224)
		(layer "In4.Cu")
		(net "P5E_CPU0_G3_TX_DP<7>")
	)
	(segment
		(start 324.799198 -173.023022)
		(end 362.973112 -204.28331)
		(width 0.14224)
		(layer "In4.Cu")
		(net "P5E_CPU0_G3_TX_DP<7>")
	)
	(segment
		(start 368.453416 -225.53422)
		(end 368.452146 -225.534982)
		(width 0.1143)
		(layer "In4.Cu")
		(net "P5E_CPU0_G3_TX_DP<7>")
	)
	(segment
		(start 369.400328 -222.290132)
		(end 369.398804 -222.291148)
		(width 0.1143)
		(layer "In4.Cu")
		(net "P5E_CPU0_G3_TX_DP<7>")
	)
	(segment
		(start 367.956084 -226.968558)
		(end 367.985802 -226.985576)
		(width 0.1143)
		(layer "In4.Cu")
		(net "P5E_CPU0_G3_TX_DP<7>")
	)
	(segment
		(start 362.973112 -204.28331)
		(end 368.878866 -214.230966)
		(width 0.14224)
		(layer "In4.Cu")
		(net "P5E_CPU0_G3_TX_DP<7>")
	)
	(segment
		(start 369.403884 -222.2881)
		(end 369.402868 -222.288608)
		(width 0.1143)
		(layer "In4.Cu")
		(net "P5E_CPU0_G3_TX_DP<7>")
	)
	(segment
		(start 368.740182 -225.044254)
		(end 368.739928 -225.044254)
		(width 0.1143)
		(layer "In4.Cu")
		(net "P5E_CPU0_G3_TX_DP<7>")
	)
	(segment
		(start 369.679982 -221.128844)
		(end 369.679982 -221.80423)
		(width 0.1143)
		(layer "In4.Cu")
		(net "P5E_CPU0_G3_TX_DP<7>")
	)
	(segment
		(start 368.878866 -214.230966)
		(end 369.725702 -220.853508)
		(width 0.14224)
		(layer "In4.Cu")
		(net "P5E_CPU0_G3_TX_DP<7>")
	)
	(segment
		(start 367.987834 -226.986846)
		(end 368.024156 -227.007928)
		(width 0.1143)
		(layer "In4.Cu")
		(net "P5E_CPU0_G3_TX_DP<7>")
	)
	(segment
		(start 368.03711 -226.311206)
		(end 368.026696 -226.31908)
		(width 0.1143)
		(layer "In4.Cu")
		(net "P5E_CPU0_G3_TX_DP<7>")
	)
	(segment
		(start 369.402868 -222.288608)
		(end 369.401344 -222.289624)
		(width 0.1143)
		(layer "In4.Cu")
		(net "P5E_CPU0_G3_TX_DP<7>")
	)
	(segment
		(start 368.275616 -232.326942)
		(end 368.275616 -232.329482)
		(width 0.1143)
		(layer "In4.Cu")
		(net "P5E_CPU0_G3_TX_DP<7>")
	)
	(segment
		(start 322.346574 -171.502578)
		(end 324.799198 -173.023022)
		(width 0.14224)
		(layer "In4.Cu")
		(net "P5E_CPU0_G3_TX_DP<7>")
	)
	(segment
		(start 369.40617 -222.28683)
		(end 369.403884 -222.2881)
		(width 0.1143)
		(layer "In4.Cu")
		(net "P5E_CPU0_G3_TX_DP<7>")
	)
	(segment
		(start 367.987834 -227.961698)
		(end 367.987072 -227.962206)
		(width 0.1143)
		(layer "In4.Cu")
		(net "P5E_CPU0_G3_TX_DP<7>")
	)
	(arc
		(start 369.366038 -222.309944)
		(mid 369.251362 -222.443278)
		(end 369.210082 -222.614236)
		(width 0.1143)
		(layer "In4.Cu")
		(net "P5E_CPU0_G3_TX_DP<7>")
	)
	(arc
		(start 368.03838 -227.017834)
		(mid 368.265763 -227.474272)
		(end 368.03838 -227.93071)
		(width 0.1143)
		(layer "In4.Cu")
		(net "P5E_CPU0_G3_TX_DP<7>")
	)
	(arc
		(start 367.990882 -230.231696)
		(mid 368.195206 -230.435541)
		(end 368.270028 -230.714296)
		(width 0.1143)
		(layer "In4.Cu")
		(net "P5E_CPU0_G3_TX_DP<7>")
	)
	(arc
		(start 368.897154 -223.119442)
		(mid 368.740177 -223.424242)
		(end 368.897154 -223.729042)
		(width 0.1143)
		(layer "In4.Cu")
		(net "P5E_CPU0_G3_TX_DP<7>")
	)
	(arc
		(start 368.270028 -229.08768)
		(mid 368.270038 -229.090982)
		(end 368.270028 -229.094284)
		(width 0.1143)
		(layer "In4.Cu")
		(net "P5E_CPU0_G3_TX_DP<7>")
	)
	(arc
		(start 368.270028 -230.714296)
		(mid 368.311907 -230.886165)
		(end 368.428016 -231.019604)
		(width 0.1143)
		(layer "In4.Cu")
		(net "P5E_CPU0_G3_TX_DP<7>")
	)
	(arc
		(start 368.49685 -231.059482)
		(mid 368.740177 -231.524048)
		(end 368.49685 -231.988614)
		(width 0.1143)
		(layer "In4.Cu")
		(net "P5E_CPU0_G3_TX_DP<7>")
	)
	(arc
		(start 367.956084 -229.599998)
		(mid 367.841241 -229.733146)
		(end 367.799874 -229.904036)
		(width 0.1143)
		(layer "In4.Cu")
		(net "P5E_CPU0_G3_TX_DP<7>")
	)
	(arc
		(start 368.040412 -228.63937)
		(mid 368.205079 -228.837977)
		(end 368.270028 -229.08768)
		(width 0.1143)
		(layer "In4.Cu")
		(net "P5E_CPU0_G3_TX_DP<7>")
	)
	(arc
		(start 369.679982 -221.80423)
		(mid 369.652066 -221.980206)
		(end 369.570762 -222.138748)
		(width 0.1143)
		(layer "In4.Cu")
		(net "P5E_CPU0_G3_TX_DP<7>")
	)
	(arc
		(start 368.270028 -229.094284)
		(mid 368.204792 -229.357875)
		(end 368.024156 -229.560628)
		(width 0.1143)
		(layer "In4.Cu")
		(net "P5E_CPU0_G3_TX_DP<7>")
	)
	(arc
		(start 368.270028 -225.861372)
		(mid 368.203826 -226.112305)
		(end 368.03711 -226.311206)
		(width 0.1143)
		(layer "In4.Cu")
		(net "P5E_CPU0_G3_TX_DP<7>")
	)
	(arc
		(start 369.210082 -222.614236)
		(mid 369.145567 -222.876455)
		(end 368.96675 -223.078802)
		(width 0.1143)
		(layer "In4.Cu")
		(net "P5E_CPU0_G3_TX_DP<7>")
	)
	(arc
		(start 368.457226 -232.011728)
		(mid 368.324306 -232.145075)
		(end 368.275616 -232.326942)
		(width 0.1143)
		(layer "In4.Cu")
		(net "P5E_CPU0_G3_TX_DP<7>")
	)
	(arc
		(start 368.897154 -224.739454)
		(mid 368.781727 -224.87283)
		(end 368.740182 -225.044254)
		(width 0.1143)
		(layer "In4.Cu")
		(net "P5E_CPU0_G3_TX_DP<7>")
	)
	(arc
		(start 368.42827 -225.548698)
		(mid 368.311997 -225.682238)
		(end 368.270028 -225.85426)
		(width 0.1143)
		(layer "In4.Cu")
		(net "P5E_CPU0_G3_TX_DP<7>")
	)
	(arc
		(start 368.96675 -223.769682)
		(mid 369.210077 -224.234248)
		(end 368.96675 -224.698814)
		(width 0.1143)
		(layer "In4.Cu")
		(net "P5E_CPU0_G3_TX_DP<7>")
	)
	(arc
		(start 369.570762 -222.138748)
		(mid 369.509243 -222.209342)
		(end 369.436904 -222.268796)
		(width 0.1143)
		(layer "In4.Cu")
		(net "P5E_CPU0_G3_TX_DP<7>")
	)
	(arc
		(start 368.024156 -228.62794)
		(mid 368.032334 -228.633583)
		(end 368.040412 -228.63937)
		(width 0.1143)
		(layer "In4.Cu")
		(net "P5E_CPU0_G3_TX_DP<7>")
	)
	(arc
		(start 367.799874 -229.904036)
		(mid 367.849802 -230.091306)
		(end 367.98631 -230.228902)
		(width 0.1143)
		(layer "In4.Cu")
		(net "P5E_CPU0_G3_TX_DP<7>")
	)
	(arc
		(start 367.956084 -227.979986)
		(mid 367.800156 -228.284278)
		(end 367.956084 -228.58857)
		(width 0.1143)
		(layer "In4.Cu")
		(net "P5E_CPU0_G3_TX_DP<7>")
	)
	(arc
		(start 368.739928 -225.044254)
		(mid 368.664426 -225.325506)
		(end 368.458242 -225.531172)
		(width 0.1143)
		(layer "In4.Cu")
		(net "P5E_CPU0_G3_TX_DP<7>")
	)
	(arc
		(start 368.024156 -227.007928)
		(mid 368.031306 -227.012826)
		(end 368.03838 -227.017834)
		(width 0.1143)
		(layer "In4.Cu")
		(net "P5E_CPU0_G3_TX_DP<7>")
	)
	(arc
		(start 368.03838 -227.93071)
		(mid 368.031307 -227.935719)
		(end 368.024156 -227.940616)
		(width 0.1143)
		(layer "In4.Cu")
		(net "P5E_CPU0_G3_TX_DP<7>")
	)
	(arc
		(start 367.956084 -226.359974)
		(mid 367.800156 -226.664266)
		(end 367.956084 -226.968558)
		(width 0.1143)
		(layer "In4.Cu")
		(net "P5E_CPU0_G3_TX_DP<7>")
	)
	(arc
		(start 367.956084 -232.839768)
		(mid 367.858949 -232.942637)
		(end 367.806986 -233.07421)
		(width 0.1143)
		(layer "In4.Cu")
		(net "P5E_CPU0_G3_TX_DP<7>")
	)
	(arc
		(start 368.49685 -231.988614)
		(mid 368.496469 -231.988868)
		(end 368.496088 -231.989122)
		(width 0.1143)
		(layer "In4.Cu")
		(net "P5E_CPU0_G3_TX_DP<7>")
	)
	(arc
		(start 368.275616 -232.329482)
		(mid 368.1994 -232.612903)
		(end 367.991136 -232.819702)
		(width 0.1143)
		(layer "In4.Cu")
		(net "P5E_CPU0_G3_TX_DP<7>")
	)
	(segment
		(start 370.527834 -236.650022)
		(end 370.994686 -236.384084)
		(width 0.12954)
		(layer "F.Cu")
		(net "P5E_CPU0_G3_TX_DP<6>")
	)
	(segment
		(start 416.373564 -17.890998)
		(end 416.07867 -18.185892)
		(width 0.12954)
		(layer "F.Cu")
		(net "P5E_CPU0_G3_TX_DP<6>")
	)
	(segment
		(start 416.07867 -18.185892)
		(end 416.07867 -18.86585)
		(width 0.12954)
		(layer "F.Cu")
		(net "P5E_CPU0_G3_TX_DP<6>")
	)
	(segment
		(start 416.07867 -18.86585)
		(end 416.34918 -19.13636)
		(width 0.12954)
		(layer "F.Cu")
		(net "P5E_CPU0_G3_TX_DP<6>")
	)
	(segment
		(start 368.943128 -226.33305)
		(end 368.941858 -226.333812)
		(width 0.1143)
		(layer "In4.Cu")
		(net "P5E_CPU0_G3_TX_DP<6>")
	)
	(segment
		(start 368.939064 -226.335336)
		(end 368.938302 -226.335844)
		(width 0.1143)
		(layer "In4.Cu")
		(net "P5E_CPU0_G3_TX_DP<6>")
	)
	(segment
		(start 369.416076 -231.04729)
		(end 369.436904 -231.059482)
		(width 0.1143)
		(layer "In4.Cu")
		(net "P5E_CPU0_G3_TX_DP<6>")
	)
	(segment
		(start 368.896138 -228.58857)
		(end 368.927126 -228.60635)
		(width 0.1143)
		(layer "In4.Cu")
		(net "P5E_CPU0_G3_TX_DP<6>")
	)
	(segment
		(start 318.803274 -143.364204)
		(end 314.615576 -157.839156)
		(width 0.14224)
		(layer "In4.Cu")
		(net "P5E_CPU0_G3_TX_DP<6>")
	)
	(segment
		(start 368.967258 -230.249476)
		(end 369.111276 -230.353616)
		(width 0.1143)
		(layer "In4.Cu")
		(net "P5E_CPU0_G3_TX_DP<6>")
	)
	(segment
		(start 370.344192 -235.900468)
		(end 370.376958 -235.919518)
		(width 0.1143)
		(layer "In4.Cu")
		(net "P5E_CPU0_G3_TX_DP<6>")
	)
	(segment
		(start 369.398804 -234.277154)
		(end 369.436904 -234.299506)
		(width 0.1143)
		(layer "In4.Cu")
		(net "P5E_CPU0_G3_TX_DP<6>")
	)
	(segment
		(start 369.430046 -231.992678)
		(end 369.429284 -231.993186)
		(width 0.1143)
		(layer "In4.Cu")
		(net "P5E_CPU0_G3_TX_DP<6>")
	)
	(segment
		(start 370.331238 -235.892848)
		(end 370.332 -235.893356)
		(width 0.1143)
		(layer "In4.Cu")
		(net "P5E_CPU0_G3_TX_DP<6>")
	)
	(segment
		(start 325.18223 -128.750822)
		(end 323.032374 -132.358638)
		(width 0.14224)
		(layer "In4.Cu")
		(net "P5E_CPU0_G3_TX_DP<6>")
	)
	(segment
		(start 368.927126 -228.60635)
		(end 368.927888 -228.606858)
		(width 0.1143)
		(layer "In4.Cu")
		(net "P5E_CPU0_G3_TX_DP<6>")
	)
	(segment
		(start 316.010544 -165.320472)
		(end 318.95161 -168.262554)
		(width 0.14224)
		(layer "In4.Cu")
		(net "P5E_CPU0_G3_TX_DP<6>")
	)
	(segment
		(start 370.306092 -235.87837)
		(end 370.327428 -235.890816)
		(width 0.1143)
		(layer "In4.Cu")
		(net "P5E_CPU0_G3_TX_DP<6>")
	)
	(segment
		(start 370.376958 -222.268796)
		(end 370.306092 -222.309944)
		(width 0.1143)
		(layer "In4.Cu")
		(net "P5E_CPU0_G3_TX_DP<6>")
	)
	(segment
		(start 368.968782 -232.797858)
		(end 368.928142 -232.821226)
		(width 0.1143)
		(layer "In4.Cu")
		(net "P5E_CPU0_G3_TX_DP<6>")
	)
	(segment
		(start 322.858638 -170.60418)
		(end 326.12711 -172.788834)
		(width 0.14224)
		(layer "In4.Cu")
		(net "P5E_CPU0_G3_TX_DP<6>")
	)
	(segment
		(start 368.897916 -230.209598)
		(end 368.967258 -230.249476)
		(width 0.1143)
		(layer "In4.Cu")
		(net "P5E_CPU0_G3_TX_DP<6>")
	)
	(segment
		(start 370.620036 -221.418658)
		(end 370.620036 -221.80423)
		(width 0.1143)
		(layer "In4.Cu")
		(net "P5E_CPU0_G3_TX_DP<6>")
	)
	(segment
		(start 369.429284 -231.993186)
		(end 369.398804 -232.010966)
		(width 0.1143)
		(layer "In4.Cu")
		(net "P5E_CPU0_G3_TX_DP<6>")
	)
	(segment
		(start 369.397026 -232.011982)
		(end 369.394232 -232.013252)
		(width 0.1143)
		(layer "In4.Cu")
		(net "P5E_CPU0_G3_TX_DP<6>")
	)
	(segment
		(start 368.896138 -226.968558)
		(end 368.927888 -226.986846)
		(width 0.1143)
		(layer "In4.Cu")
		(net "P5E_CPU0_G3_TX_DP<6>")
	)
	(segment
		(start 368.965988 -226.319588)
		(end 368.942874 -226.33305)
		(width 0.1143)
		(layer "In4.Cu")
		(net "P5E_CPU0_G3_TX_DP<6>")
	)
	(segment
		(start 416.05835 -19.42719)
		(end 416.05835 -20.547584)
		(width 0.14224)
		(layer "In4.Cu")
		(net "P5E_CPU0_G3_TX_DP<6>")
	)
	(segment
		(start 369.394486 -234.274614)
		(end 369.397026 -234.276138)
		(width 0.1143)
		(layer "In4.Cu")
		(net "P5E_CPU0_G3_TX_DP<6>")
	)
	(segment
		(start 370.651024 -221.38767)
		(end 370.620036 -221.418658)
		(width 0.1143)
		(layer "In4.Cu")
		(net "P5E_CPU0_G3_TX_DP<6>")
	)
	(segment
		(start 369.39728 -231.036876)
		(end 369.397788 -231.036622)
		(width 0.1143)
		(layer "In4.Cu")
		(net "P5E_CPU0_G3_TX_DP<6>")
	)
	(segment
		(start 368.925348 -232.823004)
		(end 368.896138 -232.839768)
		(width 0.1143)
		(layer "In4.Cu")
		(net "P5E_CPU0_G3_TX_DP<6>")
	)
	(segment
		(start 369.397026 -225.532188)
		(end 369.394232 -225.533458)
		(width 0.1143)
		(layer "In4.Cu")
		(net "P5E_CPU0_G3_TX_DP<6>")
	)
	(segment
		(start 369.429284 -225.513392)
		(end 369.398804 -225.531172)
		(width 0.1143)
		(layer "In4.Cu")
		(net "P5E_CPU0_G3_TX_DP<6>")
	)
	(segment
		(start 368.929412 -228.60762)
		(end 368.96421 -228.62794)
		(width 0.1143)
		(layer "In4.Cu")
		(net "P5E_CPU0_G3_TX_DP<6>")
	)
	(segment
		(start 370.340382 -235.898182)
		(end 370.34216 -235.899198)
		(width 0.1143)
		(layer "In4.Cu")
		(net "P5E_CPU0_G3_TX_DP<6>")
	)
	(segment
		(start 368.92865 -227.963476)
		(end 368.927634 -227.963984)
		(width 0.1143)
		(layer "In4.Cu")
		(net "P5E_CPU0_G3_TX_DP<6>")
	)
	(segment
		(start 368.935508 -226.337368)
		(end 368.92865 -226.341432)
		(width 0.1143)
		(layer "In4.Cu")
		(net "P5E_CPU0_G3_TX_DP<6>")
	)
	(segment
		(start 368.942874 -226.33305)
		(end 368.943128 -226.33305)
		(width 0.1143)
		(layer "In4.Cu")
		(net "P5E_CPU0_G3_TX_DP<6>")
	)
	(segment
		(start 368.896138 -230.208328)
		(end 368.897916 -230.209598)
		(width 0.1143)
		(layer "In4.Cu")
		(net "P5E_CPU0_G3_TX_DP<6>")
	)
	(segment
		(start 369.837208 -223.729042)
		(end 369.906804 -223.769682)
		(width 0.1143)
		(layer "In4.Cu")
		(net "P5E_CPU0_G3_TX_DP<6>")
	)
	(segment
		(start 369.436904 -231.988614)
		(end 369.430046 -231.992678)
		(width 0.1143)
		(layer "In4.Cu")
		(net "P5E_CPU0_G3_TX_DP<6>")
	)
	(segment
		(start 370.696998 -236.384084)
		(end 370.994686 -236.384084)
		(width 0.1143)
		(layer "In4.Cu")
		(net "P5E_CPU0_G3_TX_DP<6>")
	)
	(segment
		(start 369.397788 -225.53168)
		(end 369.397026 -225.532188)
		(width 0.1143)
		(layer "In4.Cu")
		(net "P5E_CPU0_G3_TX_DP<6>")
	)
	(segment
		(start 368.927126 -233.466132)
		(end 368.927888 -233.46664)
		(width 0.1143)
		(layer "In4.Cu")
		(net "P5E_CPU0_G3_TX_DP<6>")
	)
	(segment
		(start 370.338858 -235.897166)
		(end 370.340382 -235.898182)
		(width 0.1143)
		(layer "In4.Cu")
		(net "P5E_CPU0_G3_TX_DP<6>")
	)
	(segment
		(start 370.34216 -235.899198)
		(end 370.34343 -235.89996)
		(width 0.1143)
		(layer "In4.Cu")
		(net "P5E_CPU0_G3_TX_DP<6>")
	)
	(segment
		(start 370.337842 -235.896658)
		(end 370.338858 -235.897166)
		(width 0.1143)
		(layer "In4.Cu")
		(net "P5E_CPU0_G3_TX_DP<6>")
	)
	(segment
		(start 314.53455 -161.756344)
		(end 316.010544 -165.320472)
		(width 0.14224)
		(layer "In4.Cu")
		(net "P5E_CPU0_G3_TX_DP<6>")
	)
	(segment
		(start 369.394232 -225.533458)
		(end 369.393724 -225.533712)
		(width 0.1143)
		(layer "In4.Cu")
		(net "P5E_CPU0_G3_TX_DP<6>")
	)
	(segment
		(start 370.614194 -236.30128)
		(end 370.696998 -236.384084)
		(width 0.1143)
		(layer "In4.Cu")
		(net "P5E_CPU0_G3_TX_DP<6>")
	)
	(segment
		(start 369.210082 -230.546402)
		(end 369.210082 -230.714296)
		(width 0.1143)
		(layer "In4.Cu")
		(net "P5E_CPU0_G3_TX_DP<6>")
	)
	(segment
		(start 369.430046 -225.512884)
		(end 369.429284 -225.513392)
		(width 0.1143)
		(layer "In4.Cu")
		(net "P5E_CPU0_G3_TX_DP<6>")
	)
	(segment
		(start 370.696744 -220.85427)
		(end 370.696744 -221.083124)
		(width 0.14224)
		(layer "In4.Cu")
		(net "P5E_CPU0_G3_TX_DP<6>")
	)
	(segment
		(start 368.927888 -228.606858)
		(end 368.929412 -228.60762)
		(width 0.1143)
		(layer "In4.Cu")
		(net "P5E_CPU0_G3_TX_DP<6>")
	)
	(segment
		(start 370.651024 -221.128844)
		(end 370.651024 -221.38767)
		(width 0.1143)
		(layer "In4.Cu")
		(net "P5E_CPU0_G3_TX_DP<6>")
	)
	(segment
		(start 370.332 -235.893356)
		(end 370.333524 -235.894118)
		(width 0.1143)
		(layer "In4.Cu")
		(net "P5E_CPU0_G3_TX_DP<6>")
	)
	(segment
		(start 368.961416 -229.562152)
		(end 368.89436 -229.601268)
		(width 0.1143)
		(layer "In4.Cu")
		(net "P5E_CPU0_G3_TX_DP<6>")
	)
	(segment
		(start 369.36807 -231.019858)
		(end 369.39728 -231.036876)
		(width 0.1143)
		(layer "In4.Cu")
		(net "P5E_CPU0_G3_TX_DP<6>")
	)
	(segment
		(start 369.436904 -225.50882)
		(end 369.430046 -225.512884)
		(width 0.1143)
		(layer "In4.Cu")
		(net "P5E_CPU0_G3_TX_DP<6>")
	)
	(segment
		(start 369.397788 -231.036622)
		(end 369.416076 -231.04729)
		(width 0.1143)
		(layer "In4.Cu")
		(net "P5E_CPU0_G3_TX_DP<6>")
	)
	(segment
		(start 370.333524 -235.894118)
		(end 370.334286 -235.894626)
		(width 0.1143)
		(layer "In4.Cu")
		(net "P5E_CPU0_G3_TX_DP<6>")
	)
	(segment
		(start 368.896138 -232.839768)
		(end 368.880898 -232.85069)
		(width 0.1143)
		(layer "In4.Cu")
		(net "P5E_CPU0_G3_TX_DP<6>")
	)
	(segment
		(start 368.925602 -233.46537)
		(end 368.927126 -233.466132)
		(width 0.1143)
		(layer "In4.Cu")
		(net "P5E_CPU0_G3_TX_DP<6>")
	)
	(segment
		(start 314.53455 -158.246572)
		(end 314.53455 -161.756344)
		(width 0.14224)
		(layer "In4.Cu")
		(net "P5E_CPU0_G3_TX_DP<6>")
	)
	(segment
		(start 368.93627 -226.33686)
		(end 368.935508 -226.337368)
		(width 0.1143)
		(layer "In4.Cu")
		(net "P5E_CPU0_G3_TX_DP<6>")
	)
	(segment
		(start 369.870228 -214.038688)
		(end 370.696744 -220.85427)
		(width 0.14224)
		(layer "In4.Cu")
		(net "P5E_CPU0_G3_TX_DP<6>")
	)
	(segment
		(start 369.394232 -232.013252)
		(end 369.393724 -232.013506)
		(width 0.1143)
		(layer "In4.Cu")
		(net "P5E_CPU0_G3_TX_DP<6>")
	)
	(segment
		(start 368.927888 -226.986846)
		(end 368.96421 -227.007928)
		(width 0.1143)
		(layer "In4.Cu")
		(net "P5E_CPU0_G3_TX_DP<6>")
	)
	(segment
		(start 368.880898 -233.43743)
		(end 368.896138 -233.448352)
		(width 0.1143)
		(layer "In4.Cu")
		(net "P5E_CPU0_G3_TX_DP<6>")
	)
	(segment
		(start 370.34343 -235.89996)
		(end 370.344192 -235.900468)
		(width 0.1143)
		(layer "In4.Cu")
		(net "P5E_CPU0_G3_TX_DP<6>")
	)
	(segment
		(start 370.327428 -235.890816)
		(end 370.329968 -235.892086)
		(width 0.1143)
		(layer "In4.Cu")
		(net "P5E_CPU0_G3_TX_DP<6>")
	)
	(segment
		(start 369.906804 -224.698814)
		(end 369.837208 -224.739454)
		(width 0.1143)
		(layer "In4.Cu")
		(net "P5E_CPU0_G3_TX_DP<6>")
	)
	(segment
		(start 368.94008 -226.334828)
		(end 368.939064 -226.335336)
		(width 0.1143)
		(layer "In4.Cu")
		(net "P5E_CPU0_G3_TX_DP<6>")
	)
	(segment
		(start 368.938302 -226.335844)
		(end 368.93627 -226.33686)
		(width 0.1143)
		(layer "In4.Cu")
		(net "P5E_CPU0_G3_TX_DP<6>")
	)
	(segment
		(start 323.032374 -132.358638)
		(end 318.803274 -143.364204)
		(width 0.14224)
		(layer "In4.Cu")
		(net "P5E_CPU0_G3_TX_DP<6>")
	)
	(segment
		(start 368.927888 -233.46664)
		(end 368.928396 -233.466894)
		(width 0.1143)
		(layer "In4.Cu")
		(net "P5E_CPU0_G3_TX_DP<6>")
	)
	(segment
		(start 368.940842 -226.33432)
		(end 368.94008 -226.334828)
		(width 0.1143)
		(layer "In4.Cu")
		(net "P5E_CPU0_G3_TX_DP<6>")
	)
	(segment
		(start 369.906804 -223.078802)
		(end 369.837208 -223.119442)
		(width 0.1143)
		(layer "In4.Cu")
		(net "P5E_CPU0_G3_TX_DP<6>")
	)
	(segment
		(start 369.398804 -225.531172)
		(end 369.397788 -225.53168)
		(width 0.1143)
		(layer "In4.Cu")
		(net "P5E_CPU0_G3_TX_DP<6>")
	)
	(segment
		(start 370.33708 -235.89615)
		(end 370.337842 -235.896658)
		(width 0.1143)
		(layer "In4.Cu")
		(net "P5E_CPU0_G3_TX_DP<6>")
	)
	(segment
		(start 369.837208 -235.068872)
		(end 369.906804 -235.109512)
		(width 0.1143)
		(layer "In4.Cu")
		(net "P5E_CPU0_G3_TX_DP<6>")
	)
	(segment
		(start 416.34918 -19.13636)
		(end 416.05835 -19.42719)
		(width 0.14224)
		(layer "In4.Cu")
		(net "P5E_CPU0_G3_TX_DP<6>")
	)
	(segment
		(start 369.398804 -232.010966)
		(end 369.397788 -232.011474)
		(width 0.1143)
		(layer "In4.Cu")
		(net "P5E_CPU0_G3_TX_DP<6>")
	)
	(segment
		(start 326.12711 -172.788834)
		(end 327.176638 -173.739302)
		(width 0.14224)
		(layer "In4.Cu")
		(net "P5E_CPU0_G3_TX_DP<6>")
	)
	(segment
		(start 363.799882 -203.754228)
		(end 369.870228 -214.038688)
		(width 0.14224)
		(layer "In4.Cu")
		(net "P5E_CPU0_G3_TX_DP<6>")
	)
	(segment
		(start 369.397026 -234.276138)
		(end 369.397788 -234.276646)
		(width 0.1143)
		(layer "In4.Cu")
		(net "P5E_CPU0_G3_TX_DP<6>")
	)
	(segment
		(start 368.92611 -232.822496)
		(end 368.925348 -232.823004)
		(width 0.1143)
		(layer "In4.Cu")
		(net "P5E_CPU0_G3_TX_DP<6>")
	)
	(segment
		(start 370.334286 -235.894626)
		(end 370.33708 -235.89615)
		(width 0.1143)
		(layer "In4.Cu")
		(net "P5E_CPU0_G3_TX_DP<6>")
	)
	(segment
		(start 368.941858 -226.333812)
		(end 368.940842 -226.33432)
		(width 0.1143)
		(layer "In4.Cu")
		(net "P5E_CPU0_G3_TX_DP<6>")
	)
	(segment
		(start 370.329968 -235.892086)
		(end 370.331238 -235.892848)
		(width 0.1143)
		(layer "In4.Cu")
		(net "P5E_CPU0_G3_TX_DP<6>")
	)
	(segment
		(start 314.615576 -157.839156)
		(end 314.53455 -158.246572)
		(width 0.14224)
		(layer "In4.Cu")
		(net "P5E_CPU0_G3_TX_DP<6>")
	)
	(segment
		(start 368.896138 -233.448352)
		(end 368.925602 -233.46537)
		(width 0.1143)
		(layer "In4.Cu")
		(net "P5E_CPU0_G3_TX_DP<6>")
	)
	(segment
		(start 416.05835 -20.547584)
		(end 325.18223 -128.750822)
		(width 0.14224)
		(layer "In4.Cu")
		(net "P5E_CPU0_G3_TX_DP<6>")
	)
	(segment
		(start 369.397788 -234.276646)
		(end 369.398804 -234.277154)
		(width 0.1143)
		(layer "In4.Cu")
		(net "P5E_CPU0_G3_TX_DP<6>")
	)
	(segment
		(start 369.397788 -232.011474)
		(end 369.397026 -232.011982)
		(width 0.1143)
		(layer "In4.Cu")
		(net "P5E_CPU0_G3_TX_DP<6>")
	)
	(segment
		(start 370.696744 -221.083124)
		(end 370.651024 -221.128844)
		(width 0.1143)
		(layer "In4.Cu")
		(net "P5E_CPU0_G3_TX_DP<6>")
	)
	(segment
		(start 327.176638 -173.739302)
		(end 363.799882 -203.754228)
		(width 0.14224)
		(layer "In4.Cu")
		(net "P5E_CPU0_G3_TX_DP<6>")
	)
	(segment
		(start 368.96421 -229.560628)
		(end 368.961416 -229.562152)
		(width 0.1143)
		(layer "In4.Cu")
		(net "P5E_CPU0_G3_TX_DP<6>")
	)
	(segment
		(start 368.928142 -232.821226)
		(end 368.92611 -232.822496)
		(width 0.1143)
		(layer "In4.Cu")
		(net "P5E_CPU0_G3_TX_DP<6>")
	)
	(segment
		(start 318.95161 -168.262554)
		(end 322.858638 -170.60418)
		(width 0.14224)
		(layer "In4.Cu")
		(net "P5E_CPU0_G3_TX_DP<6>")
	)
	(arc
		(start 369.393724 -232.013506)
		(mid 369.258745 -232.150609)
		(end 369.210336 -232.336848)
		(width 0.1143)
		(layer "In4.Cu")
		(net "P5E_CPU0_G3_TX_DP<6>")
	)
	(arc
		(start 368.880898 -232.85069)
		(mid 368.730561 -233.14406)
		(end 368.880898 -233.43743)
		(width 0.1143)
		(layer "In4.Cu")
		(net "P5E_CPU0_G3_TX_DP<6>")
	)
	(arc
		(start 369.210082 -225.85426)
		(mid 369.14536 -226.116999)
		(end 368.965988 -226.319588)
		(width 0.1143)
		(layer "In4.Cu")
		(net "P5E_CPU0_G3_TX_DP<6>")
	)
	(arc
		(start 369.210336 -232.336848)
		(mid 369.142722 -232.595191)
		(end 368.968782 -232.797858)
		(width 0.1143)
		(layer "In4.Cu")
		(net "P5E_CPU0_G3_TX_DP<6>")
	)
	(arc
		(start 368.89436 -229.601268)
		(mid 368.780953 -229.734157)
		(end 368.740182 -229.904036)
		(width 0.1143)
		(layer "In4.Cu")
		(net "P5E_CPU0_G3_TX_DP<6>")
	)
	(arc
		(start 370.376958 -235.919518)
		(mid 370.528945 -236.076026)
		(end 370.610384 -236.27842)
		(width 0.1143)
		(layer "In4.Cu")
		(net "P5E_CPU0_G3_TX_DP<6>")
	)
	(arc
		(start 368.96421 -227.007928)
		(mid 369.209809 -227.495528)
		(end 368.92865 -227.963476)
		(width 0.1143)
		(layer "In4.Cu")
		(net "P5E_CPU0_G3_TX_DP<6>")
	)
	(arc
		(start 368.977672 -229.550976)
		(mid 368.970977 -229.555852)
		(end 368.96421 -229.560628)
		(width 0.1143)
		(layer "In4.Cu")
		(net "P5E_CPU0_G3_TX_DP<6>")
	)
	(arc
		(start 369.111276 -230.353616)
		(mid 369.183939 -230.438087)
		(end 369.210082 -230.546402)
		(width 0.1143)
		(layer "In4.Cu")
		(net "P5E_CPU0_G3_TX_DP<6>")
	)
	(arc
		(start 370.306092 -222.309944)
		(mid 370.191416 -222.443278)
		(end 370.150136 -222.614236)
		(width 0.1143)
		(layer "In4.Cu")
		(net "P5E_CPU0_G3_TX_DP<6>")
	)
	(arc
		(start 369.680236 -225.044254)
		(mid 369.615721 -225.306473)
		(end 369.436904 -225.50882)
		(width 0.1143)
		(layer "In4.Cu")
		(net "P5E_CPU0_G3_TX_DP<6>")
	)
	(arc
		(start 369.436904 -234.299506)
		(mid 369.615717 -234.501856)
		(end 369.680236 -234.764072)
		(width 0.1143)
		(layer "In4.Cu")
		(net "P5E_CPU0_G3_TX_DP<6>")
	)
	(arc
		(start 370.610384 -236.27842)
		(mid 370.612407 -236.28983)
		(end 370.614194 -236.30128)
		(width 0.1143)
		(layer "In4.Cu")
		(net "P5E_CPU0_G3_TX_DP<6>")
	)
	(arc
		(start 369.393724 -225.533712)
		(mid 369.259252 -225.66955)
		(end 369.210082 -225.85426)
		(width 0.1143)
		(layer "In4.Cu")
		(net "P5E_CPU0_G3_TX_DP<6>")
	)
	(arc
		(start 369.906804 -223.769682)
		(mid 370.150131 -224.234248)
		(end 369.906804 -224.698814)
		(width 0.1143)
		(layer "In4.Cu")
		(net "P5E_CPU0_G3_TX_DP<6>")
	)
	(arc
		(start 368.927634 -227.963984)
		(mid 368.741584 -228.267749)
		(end 368.896138 -228.58857)
		(width 0.1143)
		(layer "In4.Cu")
		(net "P5E_CPU0_G3_TX_DP<6>")
	)
	(arc
		(start 368.928396 -233.466894)
		(mid 369.132814 -233.672016)
		(end 369.207542 -233.95178)
		(width 0.1143)
		(layer "In4.Cu")
		(net "P5E_CPU0_G3_TX_DP<6>")
	)
	(arc
		(start 369.210082 -230.714296)
		(mid 369.251922 -230.886282)
		(end 369.36807 -231.019858)
		(width 0.1143)
		(layer "In4.Cu")
		(net "P5E_CPU0_G3_TX_DP<6>")
	)
	(arc
		(start 369.906804 -235.109512)
		(mid 370.085617 -235.311862)
		(end 370.150136 -235.574078)
		(width 0.1143)
		(layer "In4.Cu")
		(net "P5E_CPU0_G3_TX_DP<6>")
	)
	(arc
		(start 368.96421 -228.62794)
		(mid 368.980175 -228.639981)
		(end 368.995706 -228.652578)
		(width 0.1143)
		(layer "In4.Cu")
		(net "P5E_CPU0_G3_TX_DP<6>")
	)
	(arc
		(start 369.207542 -233.95178)
		(mid 369.25766 -234.138293)
		(end 369.394486 -234.274614)
		(width 0.1143)
		(layer "In4.Cu")
		(net "P5E_CPU0_G3_TX_DP<6>")
	)
	(arc
		(start 368.740182 -229.904036)
		(mid 368.781437 -230.075007)
		(end 368.896138 -230.208328)
		(width 0.1143)
		(layer "In4.Cu")
		(net "P5E_CPU0_G3_TX_DP<6>")
	)
	(arc
		(start 368.92865 -226.341432)
		(mid 368.741306 -226.646158)
		(end 368.896138 -226.968558)
		(width 0.1143)
		(layer "In4.Cu")
		(net "P5E_CPU0_G3_TX_DP<6>")
	)
	(arc
		(start 369.837208 -223.119442)
		(mid 369.680231 -223.424242)
		(end 369.837208 -223.729042)
		(width 0.1143)
		(layer "In4.Cu")
		(net "P5E_CPU0_G3_TX_DP<6>")
	)
	(arc
		(start 370.620036 -221.80423)
		(mid 370.555589 -222.066382)
		(end 370.376958 -222.268796)
		(width 0.1143)
		(layer "In4.Cu")
		(net "P5E_CPU0_G3_TX_DP<6>")
	)
	(arc
		(start 368.995706 -228.652578)
		(mid 369.139747 -228.848112)
		(end 369.210082 -229.080568)
		(width 0.1143)
		(layer "In4.Cu")
		(net "P5E_CPU0_G3_TX_DP<6>")
	)
	(arc
		(start 370.150136 -222.614236)
		(mid 370.085621 -222.876455)
		(end 369.906804 -223.078802)
		(width 0.1143)
		(layer "In4.Cu")
		(net "P5E_CPU0_G3_TX_DP<6>")
	)
	(arc
		(start 369.436904 -231.059482)
		(mid 369.680231 -231.524048)
		(end 369.436904 -231.988614)
		(width 0.1143)
		(layer "In4.Cu")
		(net "P5E_CPU0_G3_TX_DP<6>")
	)
	(arc
		(start 369.680236 -234.764072)
		(mid 369.721785 -234.935494)
		(end 369.837208 -235.068872)
		(width 0.1143)
		(layer "In4.Cu")
		(net "P5E_CPU0_G3_TX_DP<6>")
	)
	(arc
		(start 369.837208 -224.739454)
		(mid 369.721781 -224.87283)
		(end 369.680236 -225.044254)
		(width 0.1143)
		(layer "In4.Cu")
		(net "P5E_CPU0_G3_TX_DP<6>")
	)
	(arc
		(start 370.150136 -235.574078)
		(mid 370.191391 -235.745049)
		(end 370.306092 -235.87837)
		(width 0.1143)
		(layer "In4.Cu")
		(net "P5E_CPU0_G3_TX_DP<6>")
	)
	(arc
		(start 369.210082 -229.080568)
		(mid 369.151746 -229.344341)
		(end 368.977672 -229.550976)
		(width 0.1143)
		(layer "In4.Cu")
		(net "P5E_CPU0_G3_TX_DP<6>")
	)
	(segment
		(start 418.87267 -17.34185)
		(end 419.14318 -17.61236)
		(width 0.12954)
		(layer "F.Cu")
		(net "P5E_CPU0_G3_TX_DP<5>")
	)
	(segment
		(start 418.87267 -16.661892)
		(end 418.87267 -17.34185)
		(width 0.12954)
		(layer "F.Cu")
		(net "P5E_CPU0_G3_TX_DP<5>")
	)
	(segment
		(start 419.167564 -16.366998)
		(end 418.87267 -16.661892)
		(width 0.12954)
		(layer "F.Cu")
		(net "P5E_CPU0_G3_TX_DP<5>")
	)
	(segment
		(start 370.527834 -231.789986)
		(end 370.994686 -231.524048)
		(width 0.12954)
		(layer "F.Cu")
		(net "P5E_CPU0_G3_TX_DP<5>")
	)
	(segment
		(start 371.748812 -223.101154)
		(end 371.747796 -223.101662)
		(width 0.1143)
		(layer "In4.Cu")
		(net "P5E_CPU0_G3_TX_DP<5>")
	)
	(segment
		(start 370.334286 -225.533712)
		(end 370.333524 -225.53422)
		(width 0.1143)
		(layer "In4.Cu")
		(net "P5E_CPU0_G3_TX_DP<5>")
	)
	(segment
		(start 370.778786 -224.738438)
		(end 370.777262 -224.739454)
		(width 0.1143)
		(layer "In4.Cu")
		(net "P5E_CPU0_G3_TX_DP<5>")
	)
	(segment
		(start 370.614194 -231.441244)
		(end 370.696998 -231.524048)
		(width 0.1143)
		(layer "In4.Cu")
		(net "P5E_CPU0_G3_TX_DP<5>")
	)
	(segment
		(start 315.521848 -158.062168)
		(end 315.46673 -158.33979)
		(width 0.14224)
		(layer "In4.Cu")
		(net "P5E_CPU0_G3_TX_DP<5>")
	)
	(segment
		(start 326.746362 -172.080936)
		(end 326.761602 -172.094906)
		(width 0.14224)
		(layer "In4.Cu")
		(net "P5E_CPU0_G3_TX_DP<5>")
	)
	(segment
		(start 315.46673 -158.33979)
		(end 315.46673 -161.570416)
		(width 0.14224)
		(layer "In4.Cu")
		(net "P5E_CPU0_G3_TX_DP<5>")
	)
	(segment
		(start 370.369338 -225.513392)
		(end 370.34216 -225.52914)
		(width 0.1143)
		(layer "In4.Cu")
		(net "P5E_CPU0_G3_TX_DP<5>")
	)
	(segment
		(start 370.341398 -225.529648)
		(end 370.338858 -225.531172)
		(width 0.1143)
		(layer "In4.Cu")
		(net "P5E_CPU0_G3_TX_DP<5>")
	)
	(segment
		(start 370.3701 -225.512884)
		(end 370.369338 -225.513392)
		(width 0.1143)
		(layer "In4.Cu")
		(net "P5E_CPU0_G3_TX_DP<5>")
	)
	(segment
		(start 326.761602 -172.09516)
		(end 327.652888 -172.902372)
		(width 0.14224)
		(layer "In4.Cu")
		(net "P5E_CPU0_G3_TX_DP<5>")
	)
	(segment
		(start 372.49989 -221.248478)
		(end 372.49989 -221.80423)
		(width 0.1143)
		(layer "In4.Cu")
		(net "P5E_CPU0_G3_TX_DP<5>")
	)
	(segment
		(start 315.46673 -161.570416)
		(end 316.751716 -164.673026)
		(width 0.14224)
		(layer "In4.Cu")
		(net "P5E_CPU0_G3_TX_DP<5>")
	)
	(segment
		(start 372.54561 -221.202758)
		(end 372.49989 -221.248478)
		(width 0.1143)
		(layer "In4.Cu")
		(net "P5E_CPU0_G3_TX_DP<5>")
	)
	(segment
		(start 327.652888 -172.902372)
		(end 364.613444 -203.191364)
		(width 0.14224)
		(layer "In4.Cu")
		(net "P5E_CPU0_G3_TX_DP<5>")
	)
	(segment
		(start 372.54561 -221.17431)
		(end 372.54561 -221.202758)
		(width 0.1143)
		(layer "In4.Cu")
		(net "P5E_CPU0_G3_TX_DP<5>")
	)
	(segment
		(start 370.331238 -225.53549)
		(end 370.329968 -225.536252)
		(width 0.1143)
		(layer "In4.Cu")
		(net "P5E_CPU0_G3_TX_DP<5>")
	)
	(segment
		(start 371.316758 -223.888808)
		(end 371.277642 -223.911668)
		(width 0.1143)
		(layer "In4.Cu")
		(net "P5E_CPU0_G3_TX_DP<5>")
	)
	(segment
		(start 418.85235 -20.547584)
		(end 325.577454 -129.923286)
		(width 0.14224)
		(layer "In4.Cu")
		(net "P5E_CPU0_G3_TX_DP<5>")
	)
	(segment
		(start 372.54561 -220.865954)
		(end 372.54561 -221.17431)
		(width 0.14224)
		(layer "In4.Cu")
		(net "P5E_CPU0_G3_TX_DP<5>")
	)
	(segment
		(start 371.747034 -223.10217)
		(end 371.716046 -223.11995)
		(width 0.1143)
		(layer "In4.Cu")
		(net "P5E_CPU0_G3_TX_DP<5>")
	)
	(segment
		(start 371.277642 -223.911668)
		(end 371.247162 -223.929448)
		(width 0.1143)
		(layer "In4.Cu")
		(net "P5E_CPU0_G3_TX_DP<5>")
	)
	(segment
		(start 319.019682 -166.941754)
		(end 319.819782 -167.667178)
		(width 0.14224)
		(layer "In4.Cu")
		(net "P5E_CPU0_G3_TX_DP<5>")
	)
	(segment
		(start 370.376958 -225.50882)
		(end 370.3701 -225.512884)
		(width 0.1143)
		(layer "In4.Cu")
		(net "P5E_CPU0_G3_TX_DP<5>")
	)
	(segment
		(start 370.327428 -225.537522)
		(end 370.306092 -225.549968)
		(width 0.1143)
		(layer "In4.Cu")
		(net "P5E_CPU0_G3_TX_DP<5>")
	)
	(segment
		(start 371.750336 -223.100138)
		(end 371.748812 -223.101154)
		(width 0.1143)
		(layer "In4.Cu")
		(net "P5E_CPU0_G3_TX_DP<5>")
	)
	(segment
		(start 369.906804 -227.938838)
		(end 369.837208 -227.979478)
		(width 0.1143)
		(layer "In4.Cu")
		(net "P5E_CPU0_G3_TX_DP<5>")
	)
	(segment
		(start 369.837208 -226.969066)
		(end 369.906804 -227.009706)
		(width 0.1143)
		(layer "In4.Cu")
		(net "P5E_CPU0_G3_TX_DP<5>")
	)
	(segment
		(start 320.29527 -167.976042)
		(end 323.41439 -169.850054)
		(width 0.14224)
		(layer "In4.Cu")
		(net "P5E_CPU0_G3_TX_DP<5>")
	)
	(segment
		(start 370.332 -225.534982)
		(end 370.331238 -225.53549)
		(width 0.1143)
		(layer "In4.Cu")
		(net "P5E_CPU0_G3_TX_DP<5>")
	)
	(segment
		(start 370.981986 -213.919054)
		(end 372.54561 -220.865954)
		(width 0.14224)
		(layer "In4.Cu")
		(net "P5E_CPU0_G3_TX_DP<5>")
	)
	(segment
		(start 316.751716 -164.673026)
		(end 319.01511 -166.936928)
		(width 0.14224)
		(layer "In4.Cu")
		(net "P5E_CPU0_G3_TX_DP<5>")
	)
	(segment
		(start 372.256812 -222.268796)
		(end 372.187216 -222.309436)
		(width 0.1143)
		(layer "In4.Cu")
		(net "P5E_CPU0_G3_TX_DP<5>")
	)
	(segment
		(start 369.906804 -226.318826)
		(end 369.837208 -226.359466)
		(width 0.1143)
		(layer "In4.Cu")
		(net "P5E_CPU0_G3_TX_DP<5>")
	)
	(segment
		(start 319.686686 -143.665956)
		(end 315.521848 -158.062168)
		(width 0.14224)
		(layer "In4.Cu")
		(net "P5E_CPU0_G3_TX_DP<5>")
	)
	(segment
		(start 371.786912 -223.078802)
		(end 371.750336 -223.100138)
		(width 0.1143)
		(layer "In4.Cu")
		(net "P5E_CPU0_G3_TX_DP<5>")
	)
	(segment
		(start 370.338858 -225.531172)
		(end 370.337842 -225.53168)
		(width 0.1143)
		(layer "In4.Cu")
		(net "P5E_CPU0_G3_TX_DP<5>")
	)
	(segment
		(start 323.414898 -169.850308)
		(end 326.746362 -172.080936)
		(width 0.14224)
		(layer "In4.Cu")
		(net "P5E_CPU0_G3_TX_DP<5>")
	)
	(segment
		(start 369.906804 -229.55885)
		(end 369.867688 -229.58171)
		(width 0.1143)
		(layer "In4.Cu")
		(net "P5E_CPU0_G3_TX_DP<5>")
	)
	(segment
		(start 325.577454 -129.923286)
		(end 323.860922 -132.802884)
		(width 0.14224)
		(layer "In4.Cu")
		(net "P5E_CPU0_G3_TX_DP<5>")
	)
	(segment
		(start 370.34216 -225.52914)
		(end 370.341398 -225.529648)
		(width 0.1143)
		(layer "In4.Cu")
		(net "P5E_CPU0_G3_TX_DP<5>")
	)
	(segment
		(start 419.14318 -17.61236)
		(end 418.85235 -17.90319)
		(width 0.14224)
		(layer "In4.Cu")
		(net "P5E_CPU0_G3_TX_DP<5>")
	)
	(segment
		(start 320.22542 -167.938704)
		(end 320.29527 -167.976042)
		(width 0.14224)
		(layer "In4.Cu")
		(net "P5E_CPU0_G3_TX_DP<5>")
	)
	(segment
		(start 369.837208 -228.589078)
		(end 369.906804 -228.629718)
		(width 0.1143)
		(layer "In4.Cu")
		(net "P5E_CPU0_G3_TX_DP<5>")
	)
	(segment
		(start 370.696998 -231.524048)
		(end 370.994686 -231.524048)
		(width 0.1143)
		(layer "In4.Cu")
		(net "P5E_CPU0_G3_TX_DP<5>")
	)
	(segment
		(start 371.747796 -223.101662)
		(end 371.747034 -223.10217)
		(width 0.1143)
		(layer "In4.Cu")
		(net "P5E_CPU0_G3_TX_DP<5>")
	)
	(segment
		(start 369.837208 -230.208836)
		(end 369.904264 -230.247952)
		(width 0.1143)
		(layer "In4.Cu")
		(net "P5E_CPU0_G3_TX_DP<5>")
	)
	(segment
		(start 369.867688 -229.58171)
		(end 369.835176 -229.600506)
		(width 0.1143)
		(layer "In4.Cu")
		(net "P5E_CPU0_G3_TX_DP<5>")
	)
	(segment
		(start 370.33708 -225.532188)
		(end 370.334286 -225.533712)
		(width 0.1143)
		(layer "In4.Cu")
		(net "P5E_CPU0_G3_TX_DP<5>")
	)
	(segment
		(start 326.761602 -172.094906)
		(end 326.761602 -172.09516)
		(width 0.14224)
		(layer "In4.Cu")
		(net "P5E_CPU0_G3_TX_DP<5>")
	)
	(segment
		(start 370.807742 -224.721674)
		(end 370.778786 -224.738438)
		(width 0.1143)
		(layer "In4.Cu")
		(net "P5E_CPU0_G3_TX_DP<5>")
	)
	(segment
		(start 370.846858 -224.698814)
		(end 370.807742 -224.721674)
		(width 0.1143)
		(layer "In4.Cu")
		(net "P5E_CPU0_G3_TX_DP<5>")
	)
	(segment
		(start 418.85235 -17.90319)
		(end 418.85235 -20.547584)
		(width 0.14224)
		(layer "In4.Cu")
		(net "P5E_CPU0_G3_TX_DP<5>")
	)
	(segment
		(start 364.613444 -203.191364)
		(end 370.981986 -213.919054)
		(width 0.14224)
		(layer "In4.Cu")
		(net "P5E_CPU0_G3_TX_DP<5>")
	)
	(segment
		(start 319.819782 -167.667178)
		(end 320.22542 -167.938704)
		(width 0.14224)
		(layer "In4.Cu")
		(net "P5E_CPU0_G3_TX_DP<5>")
	)
	(segment
		(start 323.860922 -132.802884)
		(end 319.686686 -143.665956)
		(width 0.14224)
		(layer "In4.Cu")
		(net "P5E_CPU0_G3_TX_DP<5>")
	)
	(segment
		(start 370.337842 -225.53168)
		(end 370.33708 -225.532188)
		(width 0.1143)
		(layer "In4.Cu")
		(net "P5E_CPU0_G3_TX_DP<5>")
	)
	(segment
		(start 319.01511 -166.936928)
		(end 319.019682 -166.941754)
		(width 0.14224)
		(layer "In4.Cu")
		(net "P5E_CPU0_G3_TX_DP<5>")
	)
	(segment
		(start 370.304314 -231.017064)
		(end 370.376958 -231.059482)
		(width 0.1143)
		(layer "In4.Cu")
		(net "P5E_CPU0_G3_TX_DP<5>")
	)
	(segment
		(start 370.329968 -225.536252)
		(end 370.327428 -225.537522)
		(width 0.1143)
		(layer "In4.Cu")
		(net "P5E_CPU0_G3_TX_DP<5>")
	)
	(segment
		(start 323.41439 -169.850054)
		(end 323.414898 -169.850308)
		(width 0.14224)
		(layer "In4.Cu")
		(net "P5E_CPU0_G3_TX_DP<5>")
	)
	(segment
		(start 370.333524 -225.53422)
		(end 370.332 -225.534982)
		(width 0.1143)
		(layer "In4.Cu")
		(net "P5E_CPU0_G3_TX_DP<5>")
	)
	(arc
		(start 370.62029 -225.044254)
		(mid 370.555775 -225.306473)
		(end 370.376958 -225.50882)
		(width 0.1143)
		(layer "In4.Cu")
		(net "P5E_CPU0_G3_TX_DP<5>")
	)
	(arc
		(start 369.906804 -228.629718)
		(mid 370.150131 -229.094284)
		(end 369.906804 -229.55885)
		(width 0.1143)
		(layer "In4.Cu")
		(net "P5E_CPU0_G3_TX_DP<5>")
	)
	(arc
		(start 371.716046 -223.11995)
		(mid 371.60137 -223.253284)
		(end 371.56009 -223.424242)
		(width 0.1143)
		(layer "In4.Cu")
		(net "P5E_CPU0_G3_TX_DP<5>")
	)
	(arc
		(start 369.837208 -227.979478)
		(mid 369.680231 -228.284278)
		(end 369.837208 -228.589078)
		(width 0.1143)
		(layer "In4.Cu")
		(net "P5E_CPU0_G3_TX_DP<5>")
	)
	(arc
		(start 369.906804 -227.009706)
		(mid 370.150131 -227.474272)
		(end 369.906804 -227.938838)
		(width 0.1143)
		(layer "In4.Cu")
		(net "P5E_CPU0_G3_TX_DP<5>")
	)
	(arc
		(start 372.030244 -222.614236)
		(mid 371.965729 -222.876455)
		(end 371.786912 -223.078802)
		(width 0.1143)
		(layer "In4.Cu")
		(net "P5E_CPU0_G3_TX_DP<5>")
	)
	(arc
		(start 370.610384 -231.418384)
		(mid 370.612407 -231.429794)
		(end 370.614194 -231.441244)
		(width 0.1143)
		(layer "In4.Cu")
		(net "P5E_CPU0_G3_TX_DP<5>")
	)
	(arc
		(start 370.150136 -225.85426)
		(mid 370.085621 -226.116479)
		(end 369.906804 -226.318826)
		(width 0.1143)
		(layer "In4.Cu")
		(net "P5E_CPU0_G3_TX_DP<5>")
	)
	(arc
		(start 371.247162 -223.929448)
		(mid 371.131735 -224.062824)
		(end 371.09019 -224.234248)
		(width 0.1143)
		(layer "In4.Cu")
		(net "P5E_CPU0_G3_TX_DP<5>")
	)
	(arc
		(start 371.09019 -224.234248)
		(mid 371.025675 -224.496467)
		(end 370.846858 -224.698814)
		(width 0.1143)
		(layer "In4.Cu")
		(net "P5E_CPU0_G3_TX_DP<5>")
	)
	(arc
		(start 369.837208 -226.359466)
		(mid 369.680231 -226.664266)
		(end 369.837208 -226.969066)
		(width 0.1143)
		(layer "In4.Cu")
		(net "P5E_CPU0_G3_TX_DP<5>")
	)
	(arc
		(start 369.680236 -229.904036)
		(mid 369.721785 -230.075458)
		(end 369.837208 -230.208836)
		(width 0.1143)
		(layer "In4.Cu")
		(net "P5E_CPU0_G3_TX_DP<5>")
	)
	(arc
		(start 370.376958 -231.059482)
		(mid 370.528945 -231.21599)
		(end 370.610384 -231.418384)
		(width 0.1143)
		(layer "In4.Cu")
		(net "P5E_CPU0_G3_TX_DP<5>")
	)
	(arc
		(start 370.306092 -225.549968)
		(mid 370.191416 -225.683302)
		(end 370.150136 -225.85426)
		(width 0.1143)
		(layer "In4.Cu")
		(net "P5E_CPU0_G3_TX_DP<5>")
	)
	(arc
		(start 369.904264 -230.247952)
		(mid 370.084916 -230.450697)
		(end 370.150136 -230.714296)
		(width 0.1143)
		(layer "In4.Cu")
		(net "P5E_CPU0_G3_TX_DP<5>")
	)
	(arc
		(start 369.835176 -229.600506)
		(mid 369.721247 -229.733653)
		(end 369.680236 -229.904036)
		(width 0.1143)
		(layer "In4.Cu")
		(net "P5E_CPU0_G3_TX_DP<5>")
	)
	(arc
		(start 371.56009 -223.424242)
		(mid 371.495575 -223.686461)
		(end 371.316758 -223.888808)
		(width 0.1143)
		(layer "In4.Cu")
		(net "P5E_CPU0_G3_TX_DP<5>")
	)
	(arc
		(start 372.49989 -221.80423)
		(mid 372.435516 -222.066434)
		(end 372.256812 -222.268796)
		(width 0.1143)
		(layer "In4.Cu")
		(net "P5E_CPU0_G3_TX_DP<5>")
	)
	(arc
		(start 372.187216 -222.309436)
		(mid 372.071789 -222.442812)
		(end 372.030244 -222.614236)
		(width 0.1143)
		(layer "In4.Cu")
		(net "P5E_CPU0_G3_TX_DP<5>")
	)
	(arc
		(start 370.777262 -224.739454)
		(mid 370.661835 -224.87283)
		(end 370.62029 -225.044254)
		(width 0.1143)
		(layer "In4.Cu")
		(net "P5E_CPU0_G3_TX_DP<5>")
	)
	(arc
		(start 370.150136 -230.714296)
		(mid 370.190898 -230.88418)
		(end 370.304314 -231.017064)
		(width 0.1143)
		(layer "In4.Cu")
		(net "P5E_CPU0_G3_TX_DP<5>")
	)
	(segment
		(start 421.96131 -17.890998)
		(end 421.665654 -18.186654)
		(width 0.12954)
		(layer "F.Cu")
		(net "P5E_CPU0_G3_TX_DP<4>")
	)
	(segment
		(start 421.961564 -17.890998)
		(end 421.96131 -17.890998)
		(width 0.12954)
		(layer "F.Cu")
		(net "P5E_CPU0_G3_TX_DP<4>")
	)
	(segment
		(start 421.665654 -18.866612)
		(end 421.936164 -19.137122)
		(width 0.12954)
		(layer "F.Cu")
		(net "P5E_CPU0_G3_TX_DP<4>")
	)
	(segment
		(start 370.527834 -233.409998)
		(end 370.994686 -233.14406)
		(width 0.12954)
		(layer "F.Cu")
		(net "P5E_CPU0_G3_TX_DP<4>")
	)
	(segment
		(start 421.665654 -18.186654)
		(end 421.665654 -18.866612)
		(width 0.12954)
		(layer "F.Cu")
		(net "P5E_CPU0_G3_TX_DP<4>")
	)
	(segment
		(start 320.570606 -143.966184)
		(end 316.42939 -158.280354)
		(width 0.14224)
		(layer "In4.Cu")
		(net "P5E_CPU0_G3_TX_DP<4>")
	)
	(segment
		(start 370.81079 -226.339908)
		(end 370.807996 -226.341686)
		(width 0.1143)
		(layer "In4.Cu")
		(net "P5E_CPU0_G3_TX_DP<4>")
	)
	(segment
		(start 371.31625 -231.989122)
		(end 371.277388 -232.011728)
		(width 0.1143)
		(layer "In4.Cu")
		(net "P5E_CPU0_G3_TX_DP<4>")
	)
	(segment
		(start 370.846858 -226.31908)
		(end 370.81079 -226.339908)
		(width 0.1143)
		(layer "In4.Cu")
		(net "P5E_CPU0_G3_TX_DP<4>")
	)
	(segment
		(start 372.217696 -223.911668)
		(end 372.187216 -223.929448)
		(width 0.1143)
		(layer "In4.Cu")
		(net "P5E_CPU0_G3_TX_DP<4>")
	)
	(segment
		(start 316.399164 -161.374074)
		(end 316.399418 -161.374582)
		(width 0.14224)
		(layer "In4.Cu")
		(net "P5E_CPU0_G3_TX_DP<4>")
	)
	(segment
		(start 370.857272 -226.311206)
		(end 370.846858 -226.31908)
		(width 0.1143)
		(layer "In4.Cu")
		(net "P5E_CPU0_G3_TX_DP<4>")
	)
	(segment
		(start 316.42939 -158.280354)
		(end 316.399164 -158.4325)
		(width 0.14224)
		(layer "In4.Cu")
		(net "P5E_CPU0_G3_TX_DP<4>")
	)
	(segment
		(start 371.786912 -224.698814)
		(end 371.747796 -224.721674)
		(width 0.1143)
		(layer "In4.Cu")
		(net "P5E_CPU0_G3_TX_DP<4>")
	)
	(segment
		(start 371.71884 -224.738438)
		(end 371.717316 -224.739454)
		(width 0.1143)
		(layer "In4.Cu")
		(net "P5E_CPU0_G3_TX_DP<4>")
	)
	(segment
		(start 370.807234 -232.821988)
		(end 370.805964 -232.82275)
		(width 0.1143)
		(layer "In4.Cu")
		(net "P5E_CPU0_G3_TX_DP<4>")
	)
	(segment
		(start 372.256812 -223.888808)
		(end 372.217696 -223.911668)
		(width 0.1143)
		(layer "In4.Cu")
		(net "P5E_CPU0_G3_TX_DP<4>")
	)
	(segment
		(start 370.805964 -226.342956)
		(end 370.776246 -226.359974)
		(width 0.1143)
		(layer "In4.Cu")
		(net "P5E_CPU0_G3_TX_DP<4>")
	)
	(segment
		(start 317.560198 -164.157914)
		(end 319.880742 -166.443406)
		(width 0.14224)
		(layer "In4.Cu")
		(net "P5E_CPU0_G3_TX_DP<4>")
	)
	(segment
		(start 371.272308 -225.534982)
		(end 371.248432 -225.548698)
		(width 0.1143)
		(layer "In4.Cu")
		(net "P5E_CPU0_G3_TX_DP<4>")
	)
	(segment
		(start 371.277896 -225.53168)
		(end 371.276372 -225.532696)
		(width 0.1143)
		(layer "In4.Cu")
		(net "P5E_CPU0_G3_TX_DP<4>")
	)
	(segment
		(start 328.956162 -172.621956)
		(end 330.615036 -174.12462)
		(width 0.14224)
		(layer "In4.Cu")
		(net "P5E_CPU0_G3_TX_DP<4>")
	)
	(segment
		(start 373.485664 -221.202758)
		(end 373.439944 -221.248478)
		(width 0.1143)
		(layer "In4.Cu")
		(net "P5E_CPU0_G3_TX_DP<4>")
	)
	(segment
		(start 370.807996 -228.606858)
		(end 370.844318 -228.62794)
		(width 0.1143)
		(layer "In4.Cu")
		(net "P5E_CPU0_G3_TX_DP<4>")
	)
	(segment
		(start 370.807234 -226.342194)
		(end 370.805964 -226.342956)
		(width 0.1143)
		(layer "In4.Cu")
		(net "P5E_CPU0_G3_TX_DP<4>")
	)
	(segment
		(start 421.645334 -19.427952)
		(end 421.645334 -20.548346)
		(width 0.14224)
		(layer "In4.Cu")
		(net "P5E_CPU0_G3_TX_DP<4>")
	)
	(segment
		(start 330.615036 -174.12462)
		(end 365.32439 -202.561698)
		(width 0.14224)
		(layer "In4.Cu")
		(net "P5E_CPU0_G3_TX_DP<4>")
	)
	(segment
		(start 319.880742 -166.443406)
		(end 323.26453 -168.597072)
		(width 0.14224)
		(layer "In4.Cu")
		(net "P5E_CPU0_G3_TX_DP<4>")
	)
	(segment
		(start 421.936164 -19.137122)
		(end 421.645334 -19.427952)
		(width 0.14224)
		(layer "In4.Cu")
		(net "P5E_CPU0_G3_TX_DP<4>")
	)
	(segment
		(start 372.15953 -214.075264)
		(end 373.485664 -220.786198)
		(width 0.14224)
		(layer "In4.Cu")
		(net "P5E_CPU0_G3_TX_DP<4>")
	)
	(segment
		(start 370.627148 -233.07421)
		(end 370.696998 -233.14406)
		(width 0.1143)
		(layer "In4.Cu")
		(net "P5E_CPU0_G3_TX_DP<4>")
	)
	(segment
		(start 370.844318 -229.560628)
		(end 370.7765 -229.599744)
		(width 0.1143)
		(layer "In4.Cu")
		(net "P5E_CPU0_G3_TX_DP<4>")
	)
	(segment
		(start 371.273578 -225.53422)
		(end 371.272308 -225.534982)
		(width 0.1143)
		(layer "In4.Cu")
		(net "P5E_CPU0_G3_TX_DP<4>")
	)
	(segment
		(start 365.32439 -202.561698)
		(end 372.15953 -214.075264)
		(width 0.14224)
		(layer "In4.Cu")
		(net "P5E_CPU0_G3_TX_DP<4>")
	)
	(segment
		(start 371.09019 -225.85426)
		(end 371.09019 -225.861372)
		(width 0.1143)
		(layer "In4.Cu")
		(net "P5E_CPU0_G3_TX_DP<4>")
	)
	(segment
		(start 370.807234 -226.986338)
		(end 370.807996 -226.986846)
		(width 0.1143)
		(layer "In4.Cu")
		(net "P5E_CPU0_G3_TX_DP<4>")
	)
	(segment
		(start 323.26453 -168.597072)
		(end 327.078594 -171.157646)
		(width 0.14224)
		(layer "In4.Cu")
		(net "P5E_CPU0_G3_TX_DP<4>")
	)
	(segment
		(start 370.776246 -228.58857)
		(end 370.805964 -228.605588)
		(width 0.1143)
		(layer "In4.Cu")
		(net "P5E_CPU0_G3_TX_DP<4>")
	)
	(segment
		(start 371.276372 -225.532696)
		(end 371.27434 -225.533712)
		(width 0.1143)
		(layer "In4.Cu")
		(net "P5E_CPU0_G3_TX_DP<4>")
	)
	(segment
		(start 316.399418 -161.385504)
		(end 317.560198 -164.157914)
		(width 0.14224)
		(layer "In4.Cu")
		(net "P5E_CPU0_G3_TX_DP<4>")
	)
	(segment
		(start 370.806472 -230.228902)
		(end 370.811044 -230.231696)
		(width 0.1143)
		(layer "In4.Cu")
		(net "P5E_CPU0_G3_TX_DP<4>")
	)
	(segment
		(start 370.807996 -226.986846)
		(end 370.844318 -227.007928)
		(width 0.1143)
		(layer "In4.Cu")
		(net "P5E_CPU0_G3_TX_DP<4>")
	)
	(segment
		(start 371.095778 -232.326942)
		(end 371.095778 -232.329482)
		(width 0.1143)
		(layer "In4.Cu")
		(net "P5E_CPU0_G3_TX_DP<4>")
	)
	(segment
		(start 371.278404 -225.531172)
		(end 371.277896 -225.53168)
		(width 0.1143)
		(layer "In4.Cu")
		(net "P5E_CPU0_G3_TX_DP<4>")
	)
	(segment
		(start 327.078594 -171.157646)
		(end 328.956162 -172.621956)
		(width 0.14224)
		(layer "In4.Cu")
		(net "P5E_CPU0_G3_TX_DP<4>")
	)
	(segment
		(start 325.981314 -131.067556)
		(end 324.70217 -133.21411)
		(width 0.14224)
		(layer "In4.Cu")
		(net "P5E_CPU0_G3_TX_DP<4>")
	)
	(segment
		(start 421.645334 -20.548346)
		(end 325.981314 -131.067556)
		(width 0.14224)
		(layer "In4.Cu")
		(net "P5E_CPU0_G3_TX_DP<4>")
	)
	(segment
		(start 370.7765 -229.599744)
		(end 370.776246 -229.599998)
		(width 0.1143)
		(layer "In4.Cu")
		(net "P5E_CPU0_G3_TX_DP<4>")
	)
	(segment
		(start 370.808758 -232.820972)
		(end 370.807234 -232.821988)
		(width 0.1143)
		(layer "In4.Cu")
		(net "P5E_CPU0_G3_TX_DP<4>")
	)
	(segment
		(start 370.805964 -228.605588)
		(end 370.807234 -228.60635)
		(width 0.1143)
		(layer "In4.Cu")
		(net "P5E_CPU0_G3_TX_DP<4>")
	)
	(segment
		(start 372.761002 -223.054672)
		(end 372.72722 -223.078802)
		(width 0.1143)
		(layer "In4.Cu")
		(net "P5E_CPU0_G3_TX_DP<4>")
	)
	(segment
		(start 372.72722 -223.078802)
		(end 372.6561 -223.11995)
		(width 0.1143)
		(layer "In4.Cu")
		(net "P5E_CPU0_G3_TX_DP<4>")
	)
	(segment
		(start 370.805964 -227.962968)
		(end 370.776246 -227.979986)
		(width 0.1143)
		(layer "In4.Cu")
		(net "P5E_CPU0_G3_TX_DP<4>")
	)
	(segment
		(start 370.811298 -232.819702)
		(end 370.808758 -232.820972)
		(width 0.1143)
		(layer "In4.Cu")
		(net "P5E_CPU0_G3_TX_DP<4>")
	)
	(segment
		(start 370.805964 -226.985576)
		(end 370.807234 -226.986338)
		(width 0.1143)
		(layer "In4.Cu")
		(net "P5E_CPU0_G3_TX_DP<4>")
	)
	(segment
		(start 371.248178 -231.019604)
		(end 371.317012 -231.059482)
		(width 0.1143)
		(layer "In4.Cu")
		(net "P5E_CPU0_G3_TX_DP<4>")
	)
	(segment
		(start 373.439944 -221.248478)
		(end 373.439944 -221.80423)
		(width 0.1143)
		(layer "In4.Cu")
		(net "P5E_CPU0_G3_TX_DP<4>")
	)
	(segment
		(start 370.807234 -228.60635)
		(end 370.807996 -228.606858)
		(width 0.1143)
		(layer "In4.Cu")
		(net "P5E_CPU0_G3_TX_DP<4>")
	)
	(segment
		(start 370.844318 -227.940616)
		(end 370.807996 -227.961698)
		(width 0.1143)
		(layer "In4.Cu")
		(net "P5E_CPU0_G3_TX_DP<4>")
	)
	(segment
		(start 370.807234 -227.962206)
		(end 370.805964 -227.962968)
		(width 0.1143)
		(layer "In4.Cu")
		(net "P5E_CPU0_G3_TX_DP<4>")
	)
	(segment
		(start 372.970044 -222.614236)
		(end 372.970044 -222.645732)
		(width 0.1143)
		(layer "In4.Cu")
		(net "P5E_CPU0_G3_TX_DP<4>")
	)
	(segment
		(start 371.560344 -225.044254)
		(end 371.56009 -225.044254)
		(width 0.1143)
		(layer "In4.Cu")
		(net "P5E_CPU0_G3_TX_DP<4>")
	)
	(segment
		(start 316.399418 -161.374582)
		(end 316.399418 -161.385504)
		(width 0.14224)
		(layer "In4.Cu")
		(net "P5E_CPU0_G3_TX_DP<4>")
	)
	(segment
		(start 324.70217 -133.21411)
		(end 320.570606 -143.966184)
		(width 0.14224)
		(layer "In4.Cu")
		(net "P5E_CPU0_G3_TX_DP<4>")
	)
	(segment
		(start 370.696998 -233.14406)
		(end 370.994686 -233.14406)
		(width 0.1143)
		(layer "In4.Cu")
		(net "P5E_CPU0_G3_TX_DP<4>")
	)
	(segment
		(start 316.399164 -158.4325)
		(end 316.399164 -161.374074)
		(width 0.14224)
		(layer "In4.Cu")
		(net "P5E_CPU0_G3_TX_DP<4>")
	)
	(segment
		(start 373.485664 -221.17431)
		(end 373.485664 -221.202758)
		(width 0.1143)
		(layer "In4.Cu")
		(net "P5E_CPU0_G3_TX_DP<4>")
	)
	(segment
		(start 370.807996 -227.961698)
		(end 370.807234 -227.962206)
		(width 0.1143)
		(layer "In4.Cu")
		(net "P5E_CPU0_G3_TX_DP<4>")
	)
	(segment
		(start 370.805964 -232.82275)
		(end 370.776246 -232.839768)
		(width 0.1143)
		(layer "In4.Cu")
		(net "P5E_CPU0_G3_TX_DP<4>")
	)
	(segment
		(start 370.807996 -226.341686)
		(end 370.807234 -226.342194)
		(width 0.1143)
		(layer "In4.Cu")
		(net "P5E_CPU0_G3_TX_DP<4>")
	)
	(segment
		(start 371.27434 -225.533712)
		(end 371.273578 -225.53422)
		(width 0.1143)
		(layer "In4.Cu")
		(net "P5E_CPU0_G3_TX_DP<4>")
	)
	(segment
		(start 370.776246 -226.968558)
		(end 370.805964 -226.985576)
		(width 0.1143)
		(layer "In4.Cu")
		(net "P5E_CPU0_G3_TX_DP<4>")
	)
	(segment
		(start 373.485664 -220.786198)
		(end 373.485664 -221.17431)
		(width 0.14224)
		(layer "In4.Cu")
		(net "P5E_CPU0_G3_TX_DP<4>")
	)
	(segment
		(start 373.196866 -222.268796)
		(end 373.128032 -222.308928)
		(width 0.1143)
		(layer "In4.Cu")
		(net "P5E_CPU0_G3_TX_DP<4>")
	)
	(segment
		(start 371.747796 -224.721674)
		(end 371.71884 -224.738438)
		(width 0.1143)
		(layer "In4.Cu")
		(net "P5E_CPU0_G3_TX_DP<4>")
	)
	(arc
		(start 373.439944 -221.80423)
		(mid 373.375497 -222.066382)
		(end 373.196866 -222.268796)
		(width 0.1143)
		(layer "In4.Cu")
		(net "P5E_CPU0_G3_TX_DP<4>")
	)
	(arc
		(start 372.030244 -224.234248)
		(mid 371.965729 -224.496467)
		(end 371.786912 -224.698814)
		(width 0.1143)
		(layer "In4.Cu")
		(net "P5E_CPU0_G3_TX_DP<4>")
	)
	(arc
		(start 370.776246 -226.359974)
		(mid 370.620318 -226.664266)
		(end 370.776246 -226.968558)
		(width 0.1143)
		(layer "In4.Cu")
		(net "P5E_CPU0_G3_TX_DP<4>")
	)
	(arc
		(start 370.844318 -227.007928)
		(mid 370.851468 -227.012826)
		(end 370.858542 -227.017834)
		(width 0.1143)
		(layer "In4.Cu")
		(net "P5E_CPU0_G3_TX_DP<4>")
	)
	(arc
		(start 371.277388 -232.011728)
		(mid 371.144468 -232.145075)
		(end 371.095778 -232.326942)
		(width 0.1143)
		(layer "In4.Cu")
		(net "P5E_CPU0_G3_TX_DP<4>")
	)
	(arc
		(start 371.317012 -231.059482)
		(mid 371.560339 -231.524048)
		(end 371.317012 -231.988614)
		(width 0.1143)
		(layer "In4.Cu")
		(net "P5E_CPU0_G3_TX_DP<4>")
	)
	(arc
		(start 373.128032 -222.308928)
		(mid 373.011985 -222.442399)
		(end 372.970044 -222.614236)
		(width 0.1143)
		(layer "In4.Cu")
		(net "P5E_CPU0_G3_TX_DP<4>")
	)
	(arc
		(start 371.717316 -224.739454)
		(mid 371.601889 -224.87283)
		(end 371.560344 -225.044254)
		(width 0.1143)
		(layer "In4.Cu")
		(net "P5E_CPU0_G3_TX_DP<4>")
	)
	(arc
		(start 371.56009 -225.044254)
		(mid 371.484588 -225.325506)
		(end 371.278404 -225.531172)
		(width 0.1143)
		(layer "In4.Cu")
		(net "P5E_CPU0_G3_TX_DP<4>")
	)
	(arc
		(start 372.6561 -223.11995)
		(mid 372.541424 -223.253284)
		(end 372.500144 -223.424242)
		(width 0.1143)
		(layer "In4.Cu")
		(net "P5E_CPU0_G3_TX_DP<4>")
	)
	(arc
		(start 370.858542 -227.93071)
		(mid 370.851469 -227.935719)
		(end 370.844318 -227.940616)
		(width 0.1143)
		(layer "In4.Cu")
		(net "P5E_CPU0_G3_TX_DP<4>")
	)
	(arc
		(start 371.095778 -232.329482)
		(mid 371.019562 -232.612903)
		(end 370.811298 -232.819702)
		(width 0.1143)
		(layer "In4.Cu")
		(net "P5E_CPU0_G3_TX_DP<4>")
	)
	(arc
		(start 371.09019 -225.861372)
		(mid 371.023988 -226.112305)
		(end 370.857272 -226.311206)
		(width 0.1143)
		(layer "In4.Cu")
		(net "P5E_CPU0_G3_TX_DP<4>")
	)
	(arc
		(start 370.620036 -229.904036)
		(mid 370.669964 -230.091306)
		(end 370.806472 -230.228902)
		(width 0.1143)
		(layer "In4.Cu")
		(net "P5E_CPU0_G3_TX_DP<4>")
	)
	(arc
		(start 372.500144 -223.424242)
		(mid 372.435629 -223.686461)
		(end 372.256812 -223.888808)
		(width 0.1143)
		(layer "In4.Cu")
		(net "P5E_CPU0_G3_TX_DP<4>")
	)
	(arc
		(start 371.248432 -225.548698)
		(mid 371.132159 -225.682238)
		(end 371.09019 -225.85426)
		(width 0.1143)
		(layer "In4.Cu")
		(net "P5E_CPU0_G3_TX_DP<4>")
	)
	(arc
		(start 371.09019 -230.714296)
		(mid 371.132069 -230.886165)
		(end 371.248178 -231.019604)
		(width 0.1143)
		(layer "In4.Cu")
		(net "P5E_CPU0_G3_TX_DP<4>")
	)
	(arc
		(start 370.858542 -227.017834)
		(mid 371.085925 -227.474272)
		(end 370.858542 -227.93071)
		(width 0.1143)
		(layer "In4.Cu")
		(net "P5E_CPU0_G3_TX_DP<4>")
	)
	(arc
		(start 370.776246 -229.599998)
		(mid 370.661403 -229.733146)
		(end 370.620036 -229.904036)
		(width 0.1143)
		(layer "In4.Cu")
		(net "P5E_CPU0_G3_TX_DP<4>")
	)
	(arc
		(start 370.860574 -228.63937)
		(mid 371.025241 -228.837977)
		(end 371.09019 -229.08768)
		(width 0.1143)
		(layer "In4.Cu")
		(net "P5E_CPU0_G3_TX_DP<4>")
	)
	(arc
		(start 371.09019 -229.08768)
		(mid 371.0902 -229.090982)
		(end 371.09019 -229.094284)
		(width 0.1143)
		(layer "In4.Cu")
		(net "P5E_CPU0_G3_TX_DP<4>")
	)
	(arc
		(start 372.187216 -223.929448)
		(mid 372.071789 -224.062824)
		(end 372.030244 -224.234248)
		(width 0.1143)
		(layer "In4.Cu")
		(net "P5E_CPU0_G3_TX_DP<4>")
	)
	(arc
		(start 370.844318 -228.62794)
		(mid 370.852496 -228.633583)
		(end 370.860574 -228.63937)
		(width 0.1143)
		(layer "In4.Cu")
		(net "P5E_CPU0_G3_TX_DP<4>")
	)
	(arc
		(start 370.776246 -227.979986)
		(mid 370.620318 -228.284278)
		(end 370.776246 -228.58857)
		(width 0.1143)
		(layer "In4.Cu")
		(net "P5E_CPU0_G3_TX_DP<4>")
	)
	(arc
		(start 371.317012 -231.988614)
		(mid 371.316631 -231.988868)
		(end 371.31625 -231.989122)
		(width 0.1143)
		(layer "In4.Cu")
		(net "P5E_CPU0_G3_TX_DP<4>")
	)
	(arc
		(start 372.970044 -222.645732)
		(mid 372.914802 -222.875388)
		(end 372.761002 -223.054672)
		(width 0.1143)
		(layer "In4.Cu")
		(net "P5E_CPU0_G3_TX_DP<4>")
	)
	(arc
		(start 371.09019 -229.094284)
		(mid 371.024954 -229.357875)
		(end 370.844318 -229.560628)
		(width 0.1143)
		(layer "In4.Cu")
		(net "P5E_CPU0_G3_TX_DP<4>")
	)
	(arc
		(start 370.776246 -232.839768)
		(mid 370.679111 -232.942637)
		(end 370.627148 -233.07421)
		(width 0.1143)
		(layer "In4.Cu")
		(net "P5E_CPU0_G3_TX_DP<4>")
	)
	(arc
		(start 370.811044 -230.231696)
		(mid 371.015368 -230.435541)
		(end 371.09019 -230.714296)
		(width 0.1143)
		(layer "In4.Cu")
		(net "P5E_CPU0_G3_TX_DP<4>")
	)
	(segment
		(start 424.46067 -17.34185)
		(end 424.73118 -17.61236)
		(width 0.12954)
		(layer "F.Cu")
		(net "P5E_CPU0_G3_TX_DP<3>")
	)
	(segment
		(start 424.46067 -16.661892)
		(end 424.46067 -17.34185)
		(width 0.12954)
		(layer "F.Cu")
		(net "P5E_CPU0_G3_TX_DP<3>")
	)
	(segment
		(start 424.755564 -16.366998)
		(end 424.46067 -16.661892)
		(width 0.12954)
		(layer "F.Cu")
		(net "P5E_CPU0_G3_TX_DP<3>")
	)
	(segment
		(start 370.527834 -235.03001)
		(end 370.994686 -234.764072)
		(width 0.12954)
		(layer "F.Cu")
		(net "P5E_CPU0_G3_TX_DP<3>")
	)
	(segment
		(start 317.335662 -158.50362)
		(end 317.331598 -158.52394)
		(width 0.14224)
		(layer "In4.Cu")
		(net "P5E_CPU0_G3_TX_DP<3>")
	)
	(segment
		(start 370.807996 -234.441492)
		(end 370.807234 -234.442)
		(width 0.1143)
		(layer "In4.Cu")
		(net "P5E_CPU0_G3_TX_DP<3>")
	)
	(segment
		(start 321.455542 -144.262856)
		(end 317.335662 -158.50362)
		(width 0.14224)
		(layer "In4.Cu")
		(net "P5E_CPU0_G3_TX_DP<3>")
	)
	(segment
		(start 319.970658 -165.209728)
		(end 325.194676 -168.690798)
		(width 0.14224)
		(layer "In4.Cu")
		(net "P5E_CPU0_G3_TX_DP<3>")
	)
	(segment
		(start 371.786912 -227.938838)
		(end 371.717316 -227.979478)
		(width 0.1143)
		(layer "In4.Cu")
		(net "P5E_CPU0_G3_TX_DP<3>")
	)
	(segment
		(start 333.009494 -174.878238)
		(end 366.213898 -202.071224)
		(width 0.14224)
		(layer "In4.Cu")
		(net "P5E_CPU0_G3_TX_DP<3>")
	)
	(segment
		(start 372.218966 -225.531172)
		(end 372.21795 -225.53168)
		(width 0.1143)
		(layer "In4.Cu")
		(net "P5E_CPU0_G3_TX_DP<3>")
	)
	(segment
		(start 372.218966 -232.010966)
		(end 372.21795 -232.011474)
		(width 0.1143)
		(layer "In4.Cu")
		(net "P5E_CPU0_G3_TX_DP<3>")
	)
	(segment
		(start 372.68785 -224.721674)
		(end 372.658894 -224.738438)
		(width 0.1143)
		(layer "In4.Cu")
		(net "P5E_CPU0_G3_TX_DP<3>")
	)
	(segment
		(start 373.631206 -223.09963)
		(end 373.63019 -223.100138)
		(width 0.1143)
		(layer "In4.Cu")
		(net "P5E_CPU0_G3_TX_DP<3>")
	)
	(segment
		(start 372.249446 -225.513392)
		(end 372.224808 -225.527616)
		(width 0.1143)
		(layer "In4.Cu")
		(net "P5E_CPU0_G3_TX_DP<3>")
	)
	(segment
		(start 370.696998 -234.764072)
		(end 370.994686 -234.764072)
		(width 0.1143)
		(layer "In4.Cu")
		(net "P5E_CPU0_G3_TX_DP<3>")
	)
	(segment
		(start 371.317012 -233.608626)
		(end 371.265196 -233.638852)
		(width 0.1143)
		(layer "In4.Cu")
		(net "P5E_CPU0_G3_TX_DP<3>")
	)
	(segment
		(start 317.331598 -158.52394)
		(end 317.331598 -161.172144)
		(width 0.14224)
		(layer "In4.Cu")
		(net "P5E_CPU0_G3_TX_DP<3>")
	)
	(segment
		(start 373.63019 -223.100138)
		(end 373.628666 -223.101154)
		(width 0.1143)
		(layer "In4.Cu")
		(net "P5E_CPU0_G3_TX_DP<3>")
	)
	(segment
		(start 424.73118 -17.61236)
		(end 424.44035 -17.90319)
		(width 0.14224)
		(layer "In4.Cu")
		(net "P5E_CPU0_G3_TX_DP<3>")
	)
	(segment
		(start 371.717316 -228.589078)
		(end 371.786912 -228.629718)
		(width 0.1143)
		(layer "In4.Cu")
		(net "P5E_CPU0_G3_TX_DP<3>")
	)
	(segment
		(start 371.717316 -226.969066)
		(end 371.786912 -227.009706)
		(width 0.1143)
		(layer "In4.Cu")
		(net "P5E_CPU0_G3_TX_DP<3>")
	)
	(segment
		(start 372.184422 -231.017064)
		(end 372.257066 -231.059482)
		(width 0.1143)
		(layer "In4.Cu")
		(net "P5E_CPU0_G3_TX_DP<3>")
	)
	(segment
		(start 374.13692 -222.268796)
		(end 374.066054 -222.309944)
		(width 0.1143)
		(layer "In4.Cu")
		(net "P5E_CPU0_G3_TX_DP<3>")
	)
	(segment
		(start 373.15775 -223.911668)
		(end 373.126 -223.929956)
		(width 0.1143)
		(layer "In4.Cu")
		(net "P5E_CPU0_G3_TX_DP<3>")
	)
	(segment
		(start 371.786912 -232.79862)
		(end 371.717316 -232.83926)
		(width 0.1143)
		(layer "In4.Cu")
		(net "P5E_CPU0_G3_TX_DP<3>")
	)
	(segment
		(start 373.666766 -223.078802)
		(end 373.633492 -223.09836)
		(width 0.1143)
		(layer "In4.Cu")
		(net "P5E_CPU0_G3_TX_DP<3>")
	)
	(segment
		(start 372.220744 -232.00995)
		(end 372.218966 -232.010966)
		(width 0.1143)
		(layer "In4.Cu")
		(net "P5E_CPU0_G3_TX_DP<3>")
	)
	(segment
		(start 366.213898 -202.071224)
		(end 373.177562 -213.858856)
		(width 0.14224)
		(layer "In4.Cu")
		(net "P5E_CPU0_G3_TX_DP<3>")
	)
	(segment
		(start 372.249446 -231.993186)
		(end 372.224808 -232.00741)
		(width 0.1143)
		(layer "In4.Cu")
		(net "P5E_CPU0_G3_TX_DP<3>")
	)
	(segment
		(start 371.07749 -233.963718)
		(end 371.07749 -233.97337)
		(width 0.1143)
		(layer "In4.Cu")
		(net "P5E_CPU0_G3_TX_DP<3>")
	)
	(segment
		(start 371.786912 -226.318826)
		(end 371.717316 -226.359466)
		(width 0.1143)
		(layer "In4.Cu")
		(net "P5E_CPU0_G3_TX_DP<3>")
	)
	(segment
		(start 424.44035 -17.90319)
		(end 424.44035 -20.547584)
		(width 0.14224)
		(layer "In4.Cu")
		(net "P5E_CPU0_G3_TX_DP<3>")
	)
	(segment
		(start 373.632476 -223.098868)
		(end 373.631206 -223.09963)
		(width 0.1143)
		(layer "In4.Cu")
		(net "P5E_CPU0_G3_TX_DP<3>")
	)
	(segment
		(start 372.250208 -225.512884)
		(end 372.249446 -225.513392)
		(width 0.1143)
		(layer "In4.Cu")
		(net "P5E_CPU0_G3_TX_DP<3>")
	)
	(segment
		(start 424.44035 -20.547584)
		(end 326.418702 -132.155438)
		(width 0.14224)
		(layer "In4.Cu")
		(net "P5E_CPU0_G3_TX_DP<3>")
	)
	(segment
		(start 317.331598 -161.172144)
		(end 318.320166 -163.558728)
		(width 0.14224)
		(layer "In4.Cu")
		(net "P5E_CPU0_G3_TX_DP<3>")
	)
	(segment
		(start 372.21795 -225.53168)
		(end 372.217188 -225.532188)
		(width 0.1143)
		(layer "In4.Cu")
		(net "P5E_CPU0_G3_TX_DP<3>")
	)
	(segment
		(start 374.379998 -221.248478)
		(end 374.379998 -221.80423)
		(width 0.1143)
		(layer "In4.Cu")
		(net "P5E_CPU0_G3_TX_DP<3>")
	)
	(segment
		(start 374.425718 -221.202758)
		(end 374.379998 -221.248478)
		(width 0.1143)
		(layer "In4.Cu")
		(net "P5E_CPU0_G3_TX_DP<3>")
	)
	(segment
		(start 372.224808 -232.00741)
		(end 372.223284 -232.008426)
		(width 0.1143)
		(layer "In4.Cu")
		(net "P5E_CPU0_G3_TX_DP<3>")
	)
	(segment
		(start 373.628666 -223.101154)
		(end 373.62765 -223.101662)
		(width 0.1143)
		(layer "In4.Cu")
		(net "P5E_CPU0_G3_TX_DP<3>")
	)
	(segment
		(start 370.807234 -234.442)
		(end 370.805964 -234.442762)
		(width 0.1143)
		(layer "In4.Cu")
		(net "P5E_CPU0_G3_TX_DP<3>")
	)
	(segment
		(start 372.222268 -232.008934)
		(end 372.220744 -232.00995)
		(width 0.1143)
		(layer "In4.Cu")
		(net "P5E_CPU0_G3_TX_DP<3>")
	)
	(segment
		(start 371.717316 -230.208836)
		(end 371.784372 -230.247952)
		(width 0.1143)
		(layer "In4.Cu")
		(net "P5E_CPU0_G3_TX_DP<3>")
	)
	(segment
		(start 325.194676 -168.690798)
		(end 329.603862 -171.794678)
		(width 0.14224)
		(layer "In4.Cu")
		(net "P5E_CPU0_G3_TX_DP<3>")
	)
	(segment
		(start 372.220744 -225.530156)
		(end 372.218966 -225.531172)
		(width 0.1143)
		(layer "In4.Cu")
		(net "P5E_CPU0_G3_TX_DP<3>")
	)
	(segment
		(start 325.543418 -133.624574)
		(end 321.455542 -144.262856)
		(width 0.14224)
		(layer "In4.Cu")
		(net "P5E_CPU0_G3_TX_DP<3>")
	)
	(segment
		(start 372.215918 -232.012744)
		(end 372.1862 -232.029762)
		(width 0.1143)
		(layer "In4.Cu")
		(net "P5E_CPU0_G3_TX_DP<3>")
	)
	(segment
		(start 326.418702 -132.155438)
		(end 325.543418 -133.624574)
		(width 0.14224)
		(layer "In4.Cu")
		(net "P5E_CPU0_G3_TX_DP<3>")
	)
	(segment
		(start 372.217188 -225.532188)
		(end 372.215918 -225.53295)
		(width 0.1143)
		(layer "In4.Cu")
		(net "P5E_CPU0_G3_TX_DP<3>")
	)
	(segment
		(start 373.203216 -213.902036)
		(end 374.425718 -220.556582)
		(width 0.14224)
		(layer "In4.Cu")
		(net "P5E_CPU0_G3_TX_DP<3>")
	)
	(segment
		(start 373.633492 -223.09836)
		(end 373.632476 -223.098868)
		(width 0.1143)
		(layer "In4.Cu")
		(net "P5E_CPU0_G3_TX_DP<3>")
	)
	(segment
		(start 372.217188 -232.011982)
		(end 372.215918 -232.012744)
		(width 0.1143)
		(layer "In4.Cu")
		(net "P5E_CPU0_G3_TX_DP<3>")
	)
	(segment
		(start 372.257066 -225.50882)
		(end 372.250208 -225.512884)
		(width 0.1143)
		(layer "In4.Cu")
		(net "P5E_CPU0_G3_TX_DP<3>")
	)
	(segment
		(start 372.224808 -225.527616)
		(end 372.223284 -225.528632)
		(width 0.1143)
		(layer "In4.Cu")
		(net "P5E_CPU0_G3_TX_DP<3>")
	)
	(segment
		(start 370.805964 -234.442762)
		(end 370.776246 -234.45978)
		(width 0.1143)
		(layer "In4.Cu")
		(net "P5E_CPU0_G3_TX_DP<3>")
	)
	(segment
		(start 372.223284 -232.008426)
		(end 372.222268 -232.008934)
		(width 0.1143)
		(layer "In4.Cu")
		(net "P5E_CPU0_G3_TX_DP<3>")
	)
	(segment
		(start 372.223284 -225.528632)
		(end 372.222268 -225.52914)
		(width 0.1143)
		(layer "In4.Cu")
		(net "P5E_CPU0_G3_TX_DP<3>")
	)
	(segment
		(start 372.658894 -224.738438)
		(end 372.65737 -224.739454)
		(width 0.1143)
		(layer "In4.Cu")
		(net "P5E_CPU0_G3_TX_DP<3>")
	)
	(segment
		(start 373.626888 -223.10217)
		(end 373.5959 -223.11995)
		(width 0.1143)
		(layer "In4.Cu")
		(net "P5E_CPU0_G3_TX_DP<3>")
	)
	(segment
		(start 372.724172 -224.700592)
		(end 372.68785 -224.721674)
		(width 0.1143)
		(layer "In4.Cu")
		(net "P5E_CPU0_G3_TX_DP<3>")
	)
	(segment
		(start 373.62765 -223.101662)
		(end 373.626888 -223.10217)
		(width 0.1143)
		(layer "In4.Cu")
		(net "P5E_CPU0_G3_TX_DP<3>")
	)
	(segment
		(start 373.194072 -223.890586)
		(end 373.15775 -223.911668)
		(width 0.1143)
		(layer "In4.Cu")
		(net "P5E_CPU0_G3_TX_DP<3>")
	)
	(segment
		(start 372.21795 -232.011474)
		(end 372.217188 -232.011982)
		(width 0.1143)
		(layer "In4.Cu")
		(net "P5E_CPU0_G3_TX_DP<3>")
	)
	(segment
		(start 372.215918 -225.53295)
		(end 372.1862 -225.549968)
		(width 0.1143)
		(layer "In4.Cu")
		(net "P5E_CPU0_G3_TX_DP<3>")
	)
	(segment
		(start 318.320166 -163.558728)
		(end 319.970658 -165.209728)
		(width 0.14224)
		(layer "In4.Cu")
		(net "P5E_CPU0_G3_TX_DP<3>")
	)
	(segment
		(start 370.627148 -234.694222)
		(end 370.696998 -234.764072)
		(width 0.1143)
		(layer "In4.Cu")
		(net "P5E_CPU0_G3_TX_DP<3>")
	)
	(segment
		(start 374.425718 -221.17431)
		(end 374.425718 -221.202758)
		(width 0.1143)
		(layer "In4.Cu")
		(net "P5E_CPU0_G3_TX_DP<3>")
	)
	(segment
		(start 374.425718 -220.556582)
		(end 374.425718 -221.17431)
		(width 0.14224)
		(layer "In4.Cu")
		(net "P5E_CPU0_G3_TX_DP<3>")
	)
	(segment
		(start 371.747796 -229.58171)
		(end 371.715284 -229.600506)
		(width 0.1143)
		(layer "In4.Cu")
		(net "P5E_CPU0_G3_TX_DP<3>")
	)
	(segment
		(start 372.250208 -231.992678)
		(end 372.249446 -231.993186)
		(width 0.1143)
		(layer "In4.Cu")
		(net "P5E_CPU0_G3_TX_DP<3>")
	)
	(segment
		(start 329.603862 -171.794678)
		(end 333.009494 -174.878238)
		(width 0.14224)
		(layer "In4.Cu")
		(net "P5E_CPU0_G3_TX_DP<3>")
	)
	(segment
		(start 371.786912 -229.55885)
		(end 371.747796 -229.58171)
		(width 0.1143)
		(layer "In4.Cu")
		(net "P5E_CPU0_G3_TX_DP<3>")
	)
	(segment
		(start 373.177562 -213.858856)
		(end 373.203216 -213.902036)
		(width 0.14224)
		(layer "In4.Cu")
		(net "P5E_CPU0_G3_TX_DP<3>")
	)
	(segment
		(start 372.222268 -225.52914)
		(end 372.220744 -225.530156)
		(width 0.1143)
		(layer "In4.Cu")
		(net "P5E_CPU0_G3_TX_DP<3>")
	)
	(segment
		(start 372.257066 -231.988614)
		(end 372.250208 -231.992678)
		(width 0.1143)
		(layer "In4.Cu")
		(net "P5E_CPU0_G3_TX_DP<3>")
	)
	(arc
		(start 371.717316 -227.979478)
		(mid 371.560339 -228.284278)
		(end 371.717316 -228.589078)
		(width 0.1143)
		(layer "In4.Cu")
		(net "P5E_CPU0_G3_TX_DP<3>")
	)
	(arc
		(start 372.030244 -225.85426)
		(mid 371.965729 -226.116479)
		(end 371.786912 -226.318826)
		(width 0.1143)
		(layer "In4.Cu")
		(net "P5E_CPU0_G3_TX_DP<3>")
	)
	(arc
		(start 371.265196 -233.638852)
		(mid 371.127764 -233.776111)
		(end 371.07749 -233.963718)
		(width 0.1143)
		(layer "In4.Cu")
		(net "P5E_CPU0_G3_TX_DP<3>")
	)
	(arc
		(start 373.439944 -223.424242)
		(mid 373.439954 -223.427544)
		(end 373.439944 -223.430846)
		(width 0.1143)
		(layer "In4.Cu")
		(net "P5E_CPU0_G3_TX_DP<3>")
	)
	(arc
		(start 372.1862 -225.549968)
		(mid 372.071524 -225.683302)
		(end 372.030244 -225.85426)
		(width 0.1143)
		(layer "In4.Cu")
		(net "P5E_CPU0_G3_TX_DP<3>")
	)
	(arc
		(start 374.379998 -221.80423)
		(mid 374.315551 -222.066382)
		(end 374.13692 -222.268796)
		(width 0.1143)
		(layer "In4.Cu")
		(net "P5E_CPU0_G3_TX_DP<3>")
	)
	(arc
		(start 371.717316 -226.359466)
		(mid 371.560339 -226.664266)
		(end 371.717316 -226.969066)
		(width 0.1143)
		(layer "In4.Cu")
		(net "P5E_CPU0_G3_TX_DP<3>")
	)
	(arc
		(start 372.740428 -224.689162)
		(mid 372.73235 -224.694948)
		(end 372.724172 -224.700592)
		(width 0.1143)
		(layer "In4.Cu")
		(net "P5E_CPU0_G3_TX_DP<3>")
	)
	(arc
		(start 371.715284 -229.600506)
		(mid 371.601355 -229.733653)
		(end 371.560344 -229.904036)
		(width 0.1143)
		(layer "In4.Cu")
		(net "P5E_CPU0_G3_TX_DP<3>")
	)
	(arc
		(start 372.1862 -232.029762)
		(mid 372.071524 -232.163096)
		(end 372.030244 -232.334054)
		(width 0.1143)
		(layer "In4.Cu")
		(net "P5E_CPU0_G3_TX_DP<3>")
	)
	(arc
		(start 370.776246 -234.45978)
		(mid 370.679111 -234.562649)
		(end 370.627148 -234.694222)
		(width 0.1143)
		(layer "In4.Cu")
		(net "P5E_CPU0_G3_TX_DP<3>")
	)
	(arc
		(start 373.5959 -223.11995)
		(mid 373.484103 -223.254751)
		(end 373.439944 -223.424242)
		(width 0.1143)
		(layer "In4.Cu")
		(net "P5E_CPU0_G3_TX_DP<3>")
	)
	(arc
		(start 373.439944 -223.430846)
		(mid 373.375072 -223.680588)
		(end 373.210328 -223.879156)
		(width 0.1143)
		(layer "In4.Cu")
		(net "P5E_CPU0_G3_TX_DP<3>")
	)
	(arc
		(start 371.784372 -230.247952)
		(mid 371.965024 -230.450697)
		(end 372.030244 -230.714296)
		(width 0.1143)
		(layer "In4.Cu")
		(net "P5E_CPU0_G3_TX_DP<3>")
	)
	(arc
		(start 371.717316 -232.83926)
		(mid 371.601889 -232.972636)
		(end 371.560344 -233.14406)
		(width 0.1143)
		(layer "In4.Cu")
		(net "P5E_CPU0_G3_TX_DP<3>")
	)
	(arc
		(start 372.030244 -230.714296)
		(mid 372.071006 -230.88418)
		(end 372.184422 -231.017064)
		(width 0.1143)
		(layer "In4.Cu")
		(net "P5E_CPU0_G3_TX_DP<3>")
	)
	(arc
		(start 371.786912 -227.009706)
		(mid 372.030239 -227.474272)
		(end 371.786912 -227.938838)
		(width 0.1143)
		(layer "In4.Cu")
		(net "P5E_CPU0_G3_TX_DP<3>")
	)
	(arc
		(start 373.126 -223.929956)
		(mid 373.014203 -224.064757)
		(end 372.970044 -224.234248)
		(width 0.1143)
		(layer "In4.Cu")
		(net "P5E_CPU0_G3_TX_DP<3>")
	)
	(arc
		(start 372.65737 -224.739454)
		(mid 372.541943 -224.87283)
		(end 372.500398 -225.044254)
		(width 0.1143)
		(layer "In4.Cu")
		(net "P5E_CPU0_G3_TX_DP<3>")
	)
	(arc
		(start 374.066054 -222.309944)
		(mid 373.951378 -222.443278)
		(end 373.910098 -222.614236)
		(width 0.1143)
		(layer "In4.Cu")
		(net "P5E_CPU0_G3_TX_DP<3>")
	)
	(arc
		(start 371.786912 -228.629718)
		(mid 372.030239 -229.094284)
		(end 371.786912 -229.55885)
		(width 0.1143)
		(layer "In4.Cu")
		(net "P5E_CPU0_G3_TX_DP<3>")
	)
	(arc
		(start 371.560344 -233.14406)
		(mid 371.495829 -233.406279)
		(end 371.317012 -233.608626)
		(width 0.1143)
		(layer "In4.Cu")
		(net "P5E_CPU0_G3_TX_DP<3>")
	)
	(arc
		(start 371.07749 -233.97337)
		(mid 371.0053 -234.243441)
		(end 370.807996 -234.441492)
		(width 0.1143)
		(layer "In4.Cu")
		(net "P5E_CPU0_G3_TX_DP<3>")
	)
	(arc
		(start 372.970044 -224.234248)
		(mid 372.970054 -224.23755)
		(end 372.970044 -224.240852)
		(width 0.1143)
		(layer "In4.Cu")
		(net "P5E_CPU0_G3_TX_DP<3>")
	)
	(arc
		(start 372.030244 -232.334054)
		(mid 371.965729 -232.596273)
		(end 371.786912 -232.79862)
		(width 0.1143)
		(layer "In4.Cu")
		(net "P5E_CPU0_G3_TX_DP<3>")
	)
	(arc
		(start 372.970044 -224.240852)
		(mid 372.905172 -224.490594)
		(end 372.740428 -224.689162)
		(width 0.1143)
		(layer "In4.Cu")
		(net "P5E_CPU0_G3_TX_DP<3>")
	)
	(arc
		(start 372.257066 -231.059482)
		(mid 372.500393 -231.524048)
		(end 372.257066 -231.988614)
		(width 0.1143)
		(layer "In4.Cu")
		(net "P5E_CPU0_G3_TX_DP<3>")
	)
	(arc
		(start 373.910098 -222.614236)
		(mid 373.845583 -222.876455)
		(end 373.666766 -223.078802)
		(width 0.1143)
		(layer "In4.Cu")
		(net "P5E_CPU0_G3_TX_DP<3>")
	)
	(arc
		(start 372.500398 -225.044254)
		(mid 372.435883 -225.306473)
		(end 372.257066 -225.50882)
		(width 0.1143)
		(layer "In4.Cu")
		(net "P5E_CPU0_G3_TX_DP<3>")
	)
	(arc
		(start 371.560344 -229.904036)
		(mid 371.601893 -230.075458)
		(end 371.717316 -230.208836)
		(width 0.1143)
		(layer "In4.Cu")
		(net "P5E_CPU0_G3_TX_DP<3>")
	)
	(arc
		(start 373.210328 -223.879156)
		(mid 373.20225 -223.884942)
		(end 373.194072 -223.890586)
		(width 0.1143)
		(layer "In4.Cu")
		(net "P5E_CPU0_G3_TX_DP<3>")
	)
	(segment
		(start 427.288706 -18.185892)
		(end 427.288706 -18.86585)
		(width 0.12954)
		(layer "F.Cu")
		(net "P5E_CPU0_G3_TX_DP<2>")
	)
	(segment
		(start 373.347996 -236.650022)
		(end 373.814848 -236.384084)
		(width 0.12954)
		(layer "F.Cu")
		(net "P5E_CPU0_G3_TX_DP<2>")
	)
	(segment
		(start 427.288706 -18.86585)
		(end 427.559216 -19.13636)
		(width 0.12954)
		(layer "F.Cu")
		(net "P5E_CPU0_G3_TX_DP<2>")
	)
	(segment
		(start 427.5836 -17.890998)
		(end 427.288706 -18.185892)
		(width 0.12954)
		(layer "F.Cu")
		(net "P5E_CPU0_G3_TX_DP<2>")
	)
	(segment
		(start 373.434102 -236.30128)
		(end 373.516906 -236.384084)
		(width 0.1143)
		(layer "In4.Cu")
		(net "P5E_CPU0_G3_TX_DP<2>")
	)
	(segment
		(start 375.320052 -221.248478)
		(end 375.320052 -221.80423)
		(width 0.1143)
		(layer "In4.Cu")
		(net "P5E_CPU0_G3_TX_DP<2>")
	)
	(segment
		(start 372.69039 -233.468164)
		(end 372.694454 -233.47045)
		(width 0.1143)
		(layer "In4.Cu")
		(net "P5E_CPU0_G3_TX_DP<2>")
	)
	(segment
		(start 372.68785 -234.441492)
		(end 372.687088 -234.442)
		(width 0.1143)
		(layer "In4.Cu")
		(net "P5E_CPU0_G3_TX_DP<2>")
	)
	(segment
		(start 328.033888 -156.588206)
		(end 335.853786 -172.598334)
		(width 0.14224)
		(layer "In4.Cu")
		(net "P5E_CPU0_G3_TX_DP<2>")
	)
	(segment
		(start 372.69039 -226.98837)
		(end 372.694454 -226.990656)
		(width 0.1143)
		(layer "In4.Cu")
		(net "P5E_CPU0_G3_TX_DP<2>")
	)
	(segment
		(start 372.683024 -233.463846)
		(end 372.684294 -233.464608)
		(width 0.1143)
		(layer "In4.Cu")
		(net "P5E_CPU0_G3_TX_DP<2>")
	)
	(segment
		(start 373.516906 -236.384084)
		(end 373.814848 -236.384084)
		(width 0.1143)
		(layer "In4.Cu")
		(net "P5E_CPU0_G3_TX_DP<2>")
	)
	(segment
		(start 372.673372 -226.97821)
		(end 372.674388 -226.978718)
		(width 0.1143)
		(layer "In4.Cu")
		(net "P5E_CPU0_G3_TX_DP<2>")
	)
	(segment
		(start 372.674388 -228.59873)
		(end 372.675912 -228.599746)
		(width 0.1143)
		(layer "In4.Cu")
		(net "P5E_CPU0_G3_TX_DP<2>")
	)
	(segment
		(start 375.365772 -221.17431)
		(end 375.365772 -221.202758)
		(width 0.1143)
		(layer "In4.Cu")
		(net "P5E_CPU0_G3_TX_DP<2>")
	)
	(segment
		(start 372.693946 -226.33813)
		(end 372.69293 -226.338638)
		(width 0.1143)
		(layer "In4.Cu")
		(net "P5E_CPU0_G3_TX_DP<2>")
	)
	(segment
		(start 372.726966 -226.318826)
		(end 372.696232 -226.33686)
		(width 0.1143)
		(layer "In4.Cu")
		(net "P5E_CPU0_G3_TX_DP<2>")
	)
	(segment
		(start 372.679722 -226.98202)
		(end 372.682262 -226.983544)
		(width 0.1143)
		(layer "In4.Cu")
		(net "P5E_CPU0_G3_TX_DP<2>")
	)
	(segment
		(start 372.673372 -233.458004)
		(end 372.674388 -233.458512)
		(width 0.1143)
		(layer "In4.Cu")
		(net "P5E_CPU0_G3_TX_DP<2>")
	)
	(segment
		(start 372.688866 -226.341178)
		(end 372.68785 -226.341686)
		(width 0.1143)
		(layer "In4.Cu")
		(net "P5E_CPU0_G3_TX_DP<2>")
	)
	(segment
		(start 372.688866 -228.607366)
		(end 372.69039 -228.608382)
		(width 0.1143)
		(layer "In4.Cu")
		(net "P5E_CPU0_G3_TX_DP<2>")
	)
	(segment
		(start 375.076212 -222.269304)
		(end 375.075196 -222.270066)
		(width 0.1143)
		(layer "In4.Cu")
		(net "P5E_CPU0_G3_TX_DP<2>")
	)
	(segment
		(start 372.693946 -232.817924)
		(end 372.69293 -232.818432)
		(width 0.1143)
		(layer "In4.Cu")
		(net "P5E_CPU0_G3_TX_DP<2>")
	)
	(segment
		(start 372.688866 -235.08716)
		(end 372.69039 -235.088176)
		(width 0.1143)
		(layer "In4.Cu")
		(net "P5E_CPU0_G3_TX_DP<2>")
	)
	(segment
		(start 366.944148 -201.464164)
		(end 374.335802 -213.976712)
		(width 0.14224)
		(layer "In4.Cu")
		(net "P5E_CPU0_G3_TX_DP<2>")
	)
	(segment
		(start 372.694454 -235.090462)
		(end 372.695978 -235.091478)
		(width 0.1143)
		(layer "In4.Cu")
		(net "P5E_CPU0_G3_TX_DP<2>")
	)
	(segment
		(start 372.694454 -233.47045)
		(end 372.695978 -233.471466)
		(width 0.1143)
		(layer "In4.Cu")
		(net "P5E_CPU0_G3_TX_DP<2>")
	)
	(segment
		(start 372.679722 -235.081826)
		(end 372.682262 -235.08335)
		(width 0.1143)
		(layer "In4.Cu")
		(net "P5E_CPU0_G3_TX_DP<2>")
	)
	(segment
		(start 374.567704 -223.101662)
		(end 374.537224 -223.119442)
		(width 0.1143)
		(layer "In4.Cu")
		(net "P5E_CPU0_G3_TX_DP<2>")
	)
	(segment
		(start 372.688866 -232.820972)
		(end 372.68785 -232.82148)
		(width 0.1143)
		(layer "In4.Cu")
		(net "P5E_CPU0_G3_TX_DP<2>")
	)
	(segment
		(start 372.674388 -226.978718)
		(end 372.675912 -226.979734)
		(width 0.1143)
		(layer "In4.Cu")
		(net "P5E_CPU0_G3_TX_DP<2>")
	)
	(segment
		(start 373.666766 -224.698814)
		(end 373.62765 -224.721674)
		(width 0.1143)
		(layer "In4.Cu")
		(net "P5E_CPU0_G3_TX_DP<2>")
	)
	(segment
		(start 372.694454 -228.610668)
		(end 372.695978 -228.611684)
		(width 0.1143)
		(layer "In4.Cu")
		(net "P5E_CPU0_G3_TX_DP<2>")
	)
	(segment
		(start 372.684294 -228.604826)
		(end 372.685818 -228.605588)
		(width 0.1143)
		(layer "In4.Cu")
		(net "P5E_CPU0_G3_TX_DP<2>")
	)
	(segment
		(start 373.196866 -231.988614)
		(end 373.12727 -232.029254)
		(width 0.1143)
		(layer "In4.Cu")
		(net "P5E_CPU0_G3_TX_DP<2>")
	)
	(segment
		(start 372.69039 -234.439968)
		(end 372.688866 -234.440984)
		(width 0.1143)
		(layer "In4.Cu")
		(net "P5E_CPU0_G3_TX_DP<2>")
	)
	(segment
		(start 372.677944 -226.981004)
		(end 372.679722 -226.98202)
		(width 0.1143)
		(layer "In4.Cu")
		(net "P5E_CPU0_G3_TX_DP<2>")
	)
	(segment
		(start 372.695978 -228.611684)
		(end 372.726966 -228.629718)
		(width 0.1143)
		(layer "In4.Cu")
		(net "P5E_CPU0_G3_TX_DP<2>")
	)
	(segment
		(start 372.69039 -226.340162)
		(end 372.688866 -226.341178)
		(width 0.1143)
		(layer "In4.Cu")
		(net "P5E_CPU0_G3_TX_DP<2>")
	)
	(segment
		(start 372.6561 -230.208328)
		(end 372.68785 -230.226616)
		(width 0.1143)
		(layer "In4.Cu")
		(net "P5E_CPU0_G3_TX_DP<2>")
	)
	(segment
		(start 372.687088 -232.821988)
		(end 372.6561 -232.839768)
		(width 0.1143)
		(layer "In4.Cu")
		(net "P5E_CPU0_G3_TX_DP<2>")
	)
	(segment
		(start 372.68785 -235.086652)
		(end 372.688866 -235.08716)
		(width 0.1143)
		(layer "In4.Cu")
		(net "P5E_CPU0_G3_TX_DP<2>")
	)
	(segment
		(start 372.687088 -233.466132)
		(end 372.68785 -233.46664)
		(width 0.1143)
		(layer "In4.Cu")
		(net "P5E_CPU0_G3_TX_DP<2>")
	)
	(segment
		(start 372.675912 -228.599746)
		(end 372.677944 -228.601016)
		(width 0.1143)
		(layer "In4.Cu")
		(net "P5E_CPU0_G3_TX_DP<2>")
	)
	(segment
		(start 372.683024 -235.083858)
		(end 372.684294 -235.08462)
		(width 0.1143)
		(layer "In4.Cu")
		(net "P5E_CPU0_G3_TX_DP<2>")
	)
	(segment
		(start 374.335802 -213.976712)
		(end 375.365772 -220.270578)
		(width 0.14224)
		(layer "In4.Cu")
		(net "P5E_CPU0_G3_TX_DP<2>")
	)
	(segment
		(start 375.07418 -222.270574)
		(end 375.032016 -222.294704)
		(width 0.1143)
		(layer "In4.Cu")
		(net "P5E_CPU0_G3_TX_DP<2>")
	)
	(segment
		(start 372.68785 -227.961698)
		(end 372.687088 -227.962206)
		(width 0.1143)
		(layer "In4.Cu")
		(net "P5E_CPU0_G3_TX_DP<2>")
	)
	(segment
		(start 372.685818 -228.605588)
		(end 372.687088 -228.60635)
		(width 0.1143)
		(layer "In4.Cu")
		(net "P5E_CPU0_G3_TX_DP<2>")
	)
	(segment
		(start 372.682262 -226.983544)
		(end 372.683024 -226.984052)
		(width 0.1143)
		(layer "In4.Cu")
		(net "P5E_CPU0_G3_TX_DP<2>")
	)
	(segment
		(start 372.675912 -233.459528)
		(end 372.677944 -233.460798)
		(width 0.1143)
		(layer "In4.Cu")
		(net "P5E_CPU0_G3_TX_DP<2>")
	)
	(segment
		(start 372.6561 -233.448352)
		(end 372.673372 -233.458004)
		(width 0.1143)
		(layer "In4.Cu")
		(net "P5E_CPU0_G3_TX_DP<2>")
	)
	(segment
		(start 372.68785 -228.606858)
		(end 372.688866 -228.607366)
		(width 0.1143)
		(layer "In4.Cu")
		(net "P5E_CPU0_G3_TX_DP<2>")
	)
	(segment
		(start 372.68785 -232.82148)
		(end 372.687088 -232.821988)
		(width 0.1143)
		(layer "In4.Cu")
		(net "P5E_CPU0_G3_TX_DP<2>")
	)
	(segment
		(start 427.268386 -20.547584)
		(end 327.328784 -132.697474)
		(width 0.14224)
		(layer "In4.Cu")
		(net "P5E_CPU0_G3_TX_DP<2>")
	)
	(segment
		(start 372.684294 -233.464608)
		(end 372.685818 -233.46537)
		(width 0.1143)
		(layer "In4.Cu")
		(net "P5E_CPU0_G3_TX_DP<2>")
	)
	(segment
		(start 335.853786 -172.598334)
		(end 338.299806 -176.202848)
		(width 0.14224)
		(layer "In4.Cu")
		(net "P5E_CPU0_G3_TX_DP<2>")
	)
	(segment
		(start 325.616316 -137.67816)
		(end 325.545196 -138.204194)
		(width 0.14224)
		(layer "In4.Cu")
		(net "P5E_CPU0_G3_TX_DP<2>")
	)
	(segment
		(start 326.682862 -151.559768)
		(end 327.492614 -155.062428)
		(width 0.14224)
		(layer "In4.Cu")
		(net "P5E_CPU0_G3_TX_DP<2>")
	)
	(segment
		(start 372.726966 -232.79862)
		(end 372.696232 -232.816654)
		(width 0.1143)
		(layer "In4.Cu")
		(net "P5E_CPU0_G3_TX_DP<2>")
	)
	(segment
		(start 372.685818 -235.085382)
		(end 372.687088 -235.086144)
		(width 0.1143)
		(layer "In4.Cu")
		(net "P5E_CPU0_G3_TX_DP<2>")
	)
	(segment
		(start 372.687088 -227.962206)
		(end 372.6561 -227.979986)
		(width 0.1143)
		(layer "In4.Cu")
		(net "P5E_CPU0_G3_TX_DP<2>")
	)
	(segment
		(start 372.673372 -228.598222)
		(end 372.674388 -228.59873)
		(width 0.1143)
		(layer "In4.Cu")
		(net "P5E_CPU0_G3_TX_DP<2>")
	)
	(segment
		(start 374.572784 -223.098614)
		(end 374.570498 -223.100138)
		(width 0.1143)
		(layer "In4.Cu")
		(net "P5E_CPU0_G3_TX_DP<2>")
	)
	(segment
		(start 372.682262 -235.08335)
		(end 372.683024 -235.083858)
		(width 0.1143)
		(layer "In4.Cu")
		(net "P5E_CPU0_G3_TX_DP<2>")
	)
	(segment
		(start 372.696232 -234.436666)
		(end 372.693946 -234.437936)
		(width 0.1143)
		(layer "In4.Cu")
		(net "P5E_CPU0_G3_TX_DP<2>")
	)
	(segment
		(start 372.683024 -226.984052)
		(end 372.684294 -226.984814)
		(width 0.1143)
		(layer "In4.Cu")
		(net "P5E_CPU0_G3_TX_DP<2>")
	)
	(segment
		(start 373.196866 -225.50882)
		(end 373.12727 -225.54946)
		(width 0.1143)
		(layer "In4.Cu")
		(net "P5E_CPU0_G3_TX_DP<2>")
	)
	(segment
		(start 375.365772 -221.202758)
		(end 375.320052 -221.248478)
		(width 0.1143)
		(layer "In4.Cu")
		(net "P5E_CPU0_G3_TX_DP<2>")
	)
	(segment
		(start 427.268386 -19.42719)
		(end 427.268386 -20.547584)
		(width 0.14224)
		(layer "In4.Cu")
		(net "P5E_CPU0_G3_TX_DP<2>")
	)
	(segment
		(start 372.687088 -228.60635)
		(end 372.68785 -228.606858)
		(width 0.1143)
		(layer "In4.Cu")
		(net "P5E_CPU0_G3_TX_DP<2>")
	)
	(segment
		(start 372.684294 -235.08462)
		(end 372.685818 -235.085382)
		(width 0.1143)
		(layer "In4.Cu")
		(net "P5E_CPU0_G3_TX_DP<2>")
	)
	(segment
		(start 374.570498 -223.100138)
		(end 374.567704 -223.101662)
		(width 0.1143)
		(layer "In4.Cu")
		(net "P5E_CPU0_G3_TX_DP<2>")
	)
	(segment
		(start 372.6561 -228.58857)
		(end 372.673372 -228.598222)
		(width 0.1143)
		(layer "In4.Cu")
		(net "P5E_CPU0_G3_TX_DP<2>")
	)
	(segment
		(start 372.687088 -235.086144)
		(end 372.68785 -235.086652)
		(width 0.1143)
		(layer "In4.Cu")
		(net "P5E_CPU0_G3_TX_DP<2>")
	)
	(segment
		(start 372.69039 -227.960174)
		(end 372.688866 -227.96119)
		(width 0.1143)
		(layer "In4.Cu")
		(net "P5E_CPU0_G3_TX_DP<2>")
	)
	(segment
		(start 327.18629 -132.936742)
		(end 326.442578 -134.680452)
		(width 0.14224)
		(layer "In4.Cu")
		(net "P5E_CPU0_G3_TX_DP<2>")
	)
	(segment
		(start 325.545196 -138.204194)
		(end 325.545196 -141.589506)
		(width 0.14224)
		(layer "In4.Cu")
		(net "P5E_CPU0_G3_TX_DP<2>")
	)
	(segment
		(start 338.299806 -176.202848)
		(end 338.299806 -176.202594)
		(width 0.14224)
		(layer "In4.Cu")
		(net "P5E_CPU0_G3_TX_DP<2>")
	)
	(segment
		(start 375.075196 -222.270066)
		(end 375.07418 -222.270574)
		(width 0.1143)
		(layer "In4.Cu")
		(net "P5E_CPU0_G3_TX_DP<2>")
	)
	(segment
		(start 327.328784 -132.697474)
		(end 327.18629 -132.936742)
		(width 0.14224)
		(layer "In4.Cu")
		(net "P5E_CPU0_G3_TX_DP<2>")
	)
	(segment
		(start 372.682262 -228.603556)
		(end 372.683024 -228.604064)
		(width 0.1143)
		(layer "In4.Cu")
		(net "P5E_CPU0_G3_TX_DP<2>")
	)
	(segment
		(start 372.69293 -234.438444)
		(end 372.691406 -234.43946)
		(width 0.1143)
		(layer "In4.Cu")
		(net "P5E_CPU0_G3_TX_DP<2>")
	)
	(segment
		(start 372.69293 -226.338638)
		(end 372.691406 -226.339654)
		(width 0.1143)
		(layer "In4.Cu")
		(net "P5E_CPU0_G3_TX_DP<2>")
	)
	(segment
		(start 372.691406 -227.959666)
		(end 372.69039 -227.960174)
		(width 0.1143)
		(layer "In4.Cu")
		(net "P5E_CPU0_G3_TX_DP<2>")
	)
	(segment
		(start 326.442578 -134.680452)
		(end 325.616316 -137.67816)
		(width 0.14224)
		(layer "In4.Cu")
		(net "P5E_CPU0_G3_TX_DP<2>")
	)
	(segment
		(start 372.694454 -226.990656)
		(end 372.695978 -226.991672)
		(width 0.1143)
		(layer "In4.Cu")
		(net "P5E_CPU0_G3_TX_DP<2>")
	)
	(segment
		(start 372.68785 -226.986846)
		(end 372.688866 -226.987354)
		(width 0.1143)
		(layer "In4.Cu")
		(net "P5E_CPU0_G3_TX_DP<2>")
	)
	(segment
		(start 327.492614 -155.062428)
		(end 328.033888 -156.588206)
		(width 0.14224)
		(layer "In4.Cu")
		(net "P5E_CPU0_G3_TX_DP<2>")
	)
	(segment
		(start 372.675912 -226.979734)
		(end 372.677944 -226.981004)
		(width 0.1143)
		(layer "In4.Cu")
		(net "P5E_CPU0_G3_TX_DP<2>")
	)
	(segment
		(start 372.674388 -235.078524)
		(end 372.675912 -235.07954)
		(width 0.1143)
		(layer "In4.Cu")
		(net "P5E_CPU0_G3_TX_DP<2>")
	)
	(segment
		(start 372.695978 -233.471466)
		(end 372.726966 -233.4895)
		(width 0.1143)
		(layer "In4.Cu")
		(net "P5E_CPU0_G3_TX_DP<2>")
	)
	(segment
		(start 372.693946 -234.437936)
		(end 372.69293 -234.438444)
		(width 0.1143)
		(layer "In4.Cu")
		(net "P5E_CPU0_G3_TX_DP<2>")
	)
	(segment
		(start 373.12727 -235.878878)
		(end 373.196866 -235.919518)
		(width 0.1143)
		(layer "In4.Cu")
		(net "P5E_CPU0_G3_TX_DP<2>")
	)
	(segment
		(start 372.688866 -234.440984)
		(end 372.68785 -234.441492)
		(width 0.1143)
		(layer "In4.Cu")
		(net "P5E_CPU0_G3_TX_DP<2>")
	)
	(segment
		(start 372.695978 -226.991672)
		(end 372.726966 -227.009706)
		(width 0.1143)
		(layer "In4.Cu")
		(net "P5E_CPU0_G3_TX_DP<2>")
	)
	(segment
		(start 372.684294 -226.984814)
		(end 372.685818 -226.985576)
		(width 0.1143)
		(layer "In4.Cu")
		(net "P5E_CPU0_G3_TX_DP<2>")
	)
	(segment
		(start 372.674388 -233.458512)
		(end 372.675912 -233.459528)
		(width 0.1143)
		(layer "In4.Cu")
		(net "P5E_CPU0_G3_TX_DP<2>")
	)
	(segment
		(start 372.726966 -229.55885)
		(end 372.654322 -229.601268)
		(width 0.1143)
		(layer "In4.Cu")
		(net "P5E_CPU0_G3_TX_DP<2>")
	)
	(segment
		(start 372.691406 -226.339654)
		(end 372.69039 -226.340162)
		(width 0.1143)
		(layer "In4.Cu")
		(net "P5E_CPU0_G3_TX_DP<2>")
	)
	(segment
		(start 372.687088 -226.986338)
		(end 372.68785 -226.986846)
		(width 0.1143)
		(layer "In4.Cu")
		(net "P5E_CPU0_G3_TX_DP<2>")
	)
	(segment
		(start 338.299806 -176.202594)
		(end 340.74608 -179.807362)
		(width 0.14224)
		(layer "In4.Cu")
		(net "P5E_CPU0_G3_TX_DP<2>")
	)
	(segment
		(start 372.683024 -228.604064)
		(end 372.684294 -228.604826)
		(width 0.1143)
		(layer "In4.Cu")
		(net "P5E_CPU0_G3_TX_DP<2>")
	)
	(segment
		(start 372.673372 -235.078016)
		(end 372.674388 -235.078524)
		(width 0.1143)
		(layer "In4.Cu")
		(net "P5E_CPU0_G3_TX_DP<2>")
	)
	(segment
		(start 372.691406 -234.43946)
		(end 372.69039 -234.439968)
		(width 0.1143)
		(layer "In4.Cu")
		(net "P5E_CPU0_G3_TX_DP<2>")
	)
	(segment
		(start 372.688866 -226.987354)
		(end 372.69039 -226.98837)
		(width 0.1143)
		(layer "In4.Cu")
		(net "P5E_CPU0_G3_TX_DP<2>")
	)
	(segment
		(start 373.125238 -231.017826)
		(end 373.15775 -231.036622)
		(width 0.1143)
		(layer "In4.Cu")
		(net "P5E_CPU0_G3_TX_DP<2>")
	)
	(segment
		(start 372.6561 -226.968558)
		(end 372.673372 -226.97821)
		(width 0.1143)
		(layer "In4.Cu")
		(net "P5E_CPU0_G3_TX_DP<2>")
	)
	(segment
		(start 372.688866 -233.467148)
		(end 372.69039 -233.468164)
		(width 0.1143)
		(layer "In4.Cu")
		(net "P5E_CPU0_G3_TX_DP<2>")
	)
	(segment
		(start 372.68785 -230.226616)
		(end 372.724426 -230.247952)
		(width 0.1143)
		(layer "In4.Cu")
		(net "P5E_CPU0_G3_TX_DP<2>")
	)
	(segment
		(start 372.685818 -233.46537)
		(end 372.687088 -233.466132)
		(width 0.1143)
		(layer "In4.Cu")
		(net "P5E_CPU0_G3_TX_DP<2>")
	)
	(segment
		(start 372.691406 -232.819448)
		(end 372.69039 -232.819956)
		(width 0.1143)
		(layer "In4.Cu")
		(net "P5E_CPU0_G3_TX_DP<2>")
	)
	(segment
		(start 372.677944 -235.08081)
		(end 372.679722 -235.081826)
		(width 0.1143)
		(layer "In4.Cu")
		(net "P5E_CPU0_G3_TX_DP<2>")
	)
	(segment
		(start 372.696232 -226.33686)
		(end 372.693946 -226.33813)
		(width 0.1143)
		(layer "In4.Cu")
		(net "P5E_CPU0_G3_TX_DP<2>")
	)
	(segment
		(start 372.69039 -235.088176)
		(end 372.694454 -235.090462)
		(width 0.1143)
		(layer "In4.Cu")
		(net "P5E_CPU0_G3_TX_DP<2>")
	)
	(segment
		(start 325.545196 -141.589506)
		(end 326.682862 -151.559768)
		(width 0.14224)
		(layer "In4.Cu")
		(net "P5E_CPU0_G3_TX_DP<2>")
	)
	(segment
		(start 373.15775 -231.036622)
		(end 373.196866 -231.059482)
		(width 0.1143)
		(layer "In4.Cu")
		(net "P5E_CPU0_G3_TX_DP<2>")
	)
	(segment
		(start 372.6561 -235.068364)
		(end 372.673372 -235.078016)
		(width 0.1143)
		(layer "In4.Cu")
		(net "P5E_CPU0_G3_TX_DP<2>")
	)
	(segment
		(start 372.687088 -226.342194)
		(end 372.6561 -226.359974)
		(width 0.1143)
		(layer "In4.Cu")
		(net "P5E_CPU0_G3_TX_DP<2>")
	)
	(segment
		(start 372.679722 -233.461814)
		(end 372.682262 -233.463338)
		(width 0.1143)
		(layer "In4.Cu")
		(net "P5E_CPU0_G3_TX_DP<2>")
	)
	(segment
		(start 372.696232 -232.816654)
		(end 372.693946 -232.817924)
		(width 0.1143)
		(layer "In4.Cu")
		(net "P5E_CPU0_G3_TX_DP<2>")
	)
	(segment
		(start 372.69293 -227.95865)
		(end 372.691406 -227.959666)
		(width 0.1143)
		(layer "In4.Cu")
		(net "P5E_CPU0_G3_TX_DP<2>")
	)
	(segment
		(start 427.559216 -19.13636)
		(end 427.268386 -19.42719)
		(width 0.14224)
		(layer "In4.Cu")
		(net "P5E_CPU0_G3_TX_DP<2>")
	)
	(segment
		(start 372.682262 -233.463338)
		(end 372.683024 -233.463846)
		(width 0.1143)
		(layer "In4.Cu")
		(net "P5E_CPU0_G3_TX_DP<2>")
	)
	(segment
		(start 341.851234 -180.912516)
		(end 366.944148 -201.464164)
		(width 0.14224)
		(layer "In4.Cu")
		(net "P5E_CPU0_G3_TX_DP<2>")
	)
	(segment
		(start 372.695978 -235.091478)
		(end 372.726966 -235.109512)
		(width 0.1143)
		(layer "In4.Cu")
		(net "P5E_CPU0_G3_TX_DP<2>")
	)
	(segment
		(start 372.726966 -234.418632)
		(end 372.696232 -234.436666)
		(width 0.1143)
		(layer "In4.Cu")
		(net "P5E_CPU0_G3_TX_DP<2>")
	)
	(segment
		(start 372.69039 -232.819956)
		(end 372.688866 -232.820972)
		(width 0.1143)
		(layer "In4.Cu")
		(net "P5E_CPU0_G3_TX_DP<2>")
	)
	(segment
		(start 372.68785 -226.341686)
		(end 372.687088 -226.342194)
		(width 0.1143)
		(layer "In4.Cu")
		(net "P5E_CPU0_G3_TX_DP<2>")
	)
	(segment
		(start 372.693946 -227.958142)
		(end 372.69293 -227.95865)
		(width 0.1143)
		(layer "In4.Cu")
		(net "P5E_CPU0_G3_TX_DP<2>")
	)
	(segment
		(start 372.726966 -227.938838)
		(end 372.696232 -227.956872)
		(width 0.1143)
		(layer "In4.Cu")
		(net "P5E_CPU0_G3_TX_DP<2>")
	)
	(segment
		(start 372.685818 -226.985576)
		(end 372.687088 -226.986338)
		(width 0.1143)
		(layer "In4.Cu")
		(net "P5E_CPU0_G3_TX_DP<2>")
	)
	(segment
		(start 372.69293 -232.818432)
		(end 372.691406 -232.819448)
		(width 0.1143)
		(layer "In4.Cu")
		(net "P5E_CPU0_G3_TX_DP<2>")
	)
	(segment
		(start 372.677944 -228.601016)
		(end 372.679722 -228.602032)
		(width 0.1143)
		(layer "In4.Cu")
		(net "P5E_CPU0_G3_TX_DP<2>")
	)
	(segment
		(start 372.69039 -228.608382)
		(end 372.694454 -228.610668)
		(width 0.1143)
		(layer "In4.Cu")
		(net "P5E_CPU0_G3_TX_DP<2>")
	)
	(segment
		(start 372.696232 -227.956872)
		(end 372.693946 -227.958142)
		(width 0.1143)
		(layer "In4.Cu")
		(net "P5E_CPU0_G3_TX_DP<2>")
	)
	(segment
		(start 340.74608 -179.807362)
		(end 341.851234 -180.912516)
		(width 0.14224)
		(layer "In4.Cu")
		(net "P5E_CPU0_G3_TX_DP<2>")
	)
	(segment
		(start 372.677944 -233.460798)
		(end 372.679722 -233.461814)
		(width 0.1143)
		(layer "In4.Cu")
		(net "P5E_CPU0_G3_TX_DP<2>")
	)
	(segment
		(start 375.365772 -220.270578)
		(end 375.365772 -221.17431)
		(width 0.14224)
		(layer "In4.Cu")
		(net "P5E_CPU0_G3_TX_DP<2>")
	)
	(segment
		(start 373.62765 -224.721674)
		(end 373.596154 -224.739962)
		(width 0.1143)
		(layer "In4.Cu")
		(net "P5E_CPU0_G3_TX_DP<2>")
	)
	(segment
		(start 372.675912 -235.07954)
		(end 372.677944 -235.08081)
		(width 0.1143)
		(layer "In4.Cu")
		(net "P5E_CPU0_G3_TX_DP<2>")
	)
	(segment
		(start 372.687088 -234.442)
		(end 372.6561 -234.45978)
		(width 0.1143)
		(layer "In4.Cu")
		(net "P5E_CPU0_G3_TX_DP<2>")
	)
	(segment
		(start 372.679722 -228.602032)
		(end 372.682262 -228.603556)
		(width 0.1143)
		(layer "In4.Cu")
		(net "P5E_CPU0_G3_TX_DP<2>")
	)
	(segment
		(start 372.688866 -227.96119)
		(end 372.68785 -227.961698)
		(width 0.1143)
		(layer "In4.Cu")
		(net "P5E_CPU0_G3_TX_DP<2>")
	)
	(segment
		(start 372.68785 -233.46664)
		(end 372.688866 -233.467148)
		(width 0.1143)
		(layer "In4.Cu")
		(net "P5E_CPU0_G3_TX_DP<2>")
	)
	(arc
		(start 373.196866 -235.919518)
		(mid 373.348853 -236.076026)
		(end 373.430292 -236.27842)
		(width 0.1143)
		(layer "In4.Cu")
		(net "P5E_CPU0_G3_TX_DP<2>")
	)
	(arc
		(start 372.970298 -230.714296)
		(mid 373.011264 -230.884702)
		(end 373.125238 -231.017826)
		(width 0.1143)
		(layer "In4.Cu")
		(net "P5E_CPU0_G3_TX_DP<2>")
	)
	(arc
		(start 372.724426 -230.247952)
		(mid 372.905078 -230.450697)
		(end 372.970298 -230.714296)
		(width 0.1143)
		(layer "In4.Cu")
		(net "P5E_CPU0_G3_TX_DP<2>")
	)
	(arc
		(start 372.726966 -233.4895)
		(mid 372.970293 -233.954066)
		(end 372.726966 -234.418632)
		(width 0.1143)
		(layer "In4.Cu")
		(net "P5E_CPU0_G3_TX_DP<2>")
	)
	(arc
		(start 372.6561 -226.359974)
		(mid 372.500172 -226.664266)
		(end 372.6561 -226.968558)
		(width 0.1143)
		(layer "In4.Cu")
		(net "P5E_CPU0_G3_TX_DP<2>")
	)
	(arc
		(start 372.500144 -229.904036)
		(mid 372.541399 -230.075007)
		(end 372.6561 -230.208328)
		(width 0.1143)
		(layer "In4.Cu")
		(net "P5E_CPU0_G3_TX_DP<2>")
	)
	(arc
		(start 372.726966 -235.109512)
		(mid 372.905779 -235.311862)
		(end 372.970298 -235.574078)
		(width 0.1143)
		(layer "In4.Cu")
		(net "P5E_CPU0_G3_TX_DP<2>")
	)
	(arc
		(start 373.12727 -232.029254)
		(mid 373.011843 -232.16263)
		(end 372.970298 -232.334054)
		(width 0.1143)
		(layer "In4.Cu")
		(net "P5E_CPU0_G3_TX_DP<2>")
	)
	(arc
		(start 373.596154 -224.739962)
		(mid 373.481478 -224.873296)
		(end 373.440198 -225.044254)
		(width 0.1143)
		(layer "In4.Cu")
		(net "P5E_CPU0_G3_TX_DP<2>")
	)
	(arc
		(start 373.430292 -236.27842)
		(mid 373.432315 -236.28983)
		(end 373.434102 -236.30128)
		(width 0.1143)
		(layer "In4.Cu")
		(net "P5E_CPU0_G3_TX_DP<2>")
	)
	(arc
		(start 374.537224 -223.119442)
		(mid 374.421797 -223.252818)
		(end 374.380252 -223.424242)
		(width 0.1143)
		(layer "In4.Cu")
		(net "P5E_CPU0_G3_TX_DP<2>")
	)
	(arc
		(start 373.440198 -225.044254)
		(mid 373.375683 -225.306473)
		(end 373.196866 -225.50882)
		(width 0.1143)
		(layer "In4.Cu")
		(net "P5E_CPU0_G3_TX_DP<2>")
	)
	(arc
		(start 372.6561 -232.839768)
		(mid 372.500172 -233.14406)
		(end 372.6561 -233.448352)
		(width 0.1143)
		(layer "In4.Cu")
		(net "P5E_CPU0_G3_TX_DP<2>")
	)
	(arc
		(start 372.6561 -234.45978)
		(mid 372.500172 -234.764072)
		(end 372.6561 -235.068364)
		(width 0.1143)
		(layer "In4.Cu")
		(net "P5E_CPU0_G3_TX_DP<2>")
	)
	(arc
		(start 372.726966 -227.009706)
		(mid 372.970293 -227.474272)
		(end 372.726966 -227.938838)
		(width 0.1143)
		(layer "In4.Cu")
		(net "P5E_CPU0_G3_TX_DP<2>")
	)
	(arc
		(start 373.12727 -225.54946)
		(mid 373.011843 -225.682836)
		(end 372.970298 -225.85426)
		(width 0.1143)
		(layer "In4.Cu")
		(net "P5E_CPU0_G3_TX_DP<2>")
	)
	(arc
		(start 372.970298 -235.574078)
		(mid 373.011847 -235.7455)
		(end 373.12727 -235.878878)
		(width 0.1143)
		(layer "In4.Cu")
		(net "P5E_CPU0_G3_TX_DP<2>")
	)
	(arc
		(start 372.970298 -225.85426)
		(mid 372.905783 -226.116479)
		(end 372.726966 -226.318826)
		(width 0.1143)
		(layer "In4.Cu")
		(net "P5E_CPU0_G3_TX_DP<2>")
	)
	(arc
		(start 375.320052 -221.80423)
		(mid 375.255393 -222.066787)
		(end 375.076212 -222.269304)
		(width 0.1143)
		(layer "In4.Cu")
		(net "P5E_CPU0_G3_TX_DP<2>")
	)
	(arc
		(start 372.970298 -232.334054)
		(mid 372.905783 -232.596273)
		(end 372.726966 -232.79862)
		(width 0.1143)
		(layer "In4.Cu")
		(net "P5E_CPU0_G3_TX_DP<2>")
	)
	(arc
		(start 374.848628 -222.614998)
		(mid 374.774818 -222.893373)
		(end 374.572784 -223.098614)
		(width 0.1143)
		(layer "In4.Cu")
		(net "P5E_CPU0_G3_TX_DP<2>")
	)
	(arc
		(start 374.380252 -223.424242)
		(mid 374.317316 -223.683485)
		(end 374.142508 -223.884998)
		(width 0.1143)
		(layer "In4.Cu")
		(net "P5E_CPU0_G3_TX_DP<2>")
	)
	(arc
		(start 373.907558 -224.290128)
		(mid 373.83209 -224.520935)
		(end 373.666766 -224.698814)
		(width 0.1143)
		(layer "In4.Cu")
		(net "P5E_CPU0_G3_TX_DP<2>")
	)
	(arc
		(start 374.142508 -223.884998)
		(mid 373.981108 -224.062083)
		(end 373.907558 -224.290128)
		(width 0.1143)
		(layer "In4.Cu")
		(net "P5E_CPU0_G3_TX_DP<2>")
	)
	(arc
		(start 372.726966 -228.629718)
		(mid 372.970293 -229.094284)
		(end 372.726966 -229.55885)
		(width 0.1143)
		(layer "In4.Cu")
		(net "P5E_CPU0_G3_TX_DP<2>")
	)
	(arc
		(start 372.6561 -227.979986)
		(mid 372.500172 -228.284278)
		(end 372.6561 -228.58857)
		(width 0.1143)
		(layer "In4.Cu")
		(net "P5E_CPU0_G3_TX_DP<2>")
	)
	(arc
		(start 372.654322 -229.601268)
		(mid 372.540915 -229.734157)
		(end 372.500144 -229.904036)
		(width 0.1143)
		(layer "In4.Cu")
		(net "P5E_CPU0_G3_TX_DP<2>")
	)
	(arc
		(start 373.196866 -231.059482)
		(mid 373.440193 -231.524048)
		(end 373.196866 -231.988614)
		(width 0.1143)
		(layer "In4.Cu")
		(net "P5E_CPU0_G3_TX_DP<2>")
	)
	(arc
		(start 375.032016 -222.294704)
		(mid 374.897703 -222.430452)
		(end 374.848628 -222.614998)
		(width 0.1143)
		(layer "In4.Cu")
		(net "P5E_CPU0_G3_TX_DP<2>")
	)
	(segment
		(start 373.347996 -233.409998)
		(end 373.814848 -233.14406)
		(width 0.12954)
		(layer "F.Cu")
		(net "P5E_CPU0_G3_TX_DP<1>")
	)
	(segment
		(start 430.3776 -16.366998)
		(end 430.08169 -16.662908)
		(width 0.12954)
		(layer "F.Cu")
		(net "P5E_CPU0_G3_TX_DP<1>")
	)
	(segment
		(start 430.08169 -16.662908)
		(end 430.08169 -17.342612)
		(width 0.12954)
		(layer "F.Cu")
		(net "P5E_CPU0_G3_TX_DP<1>")
	)
	(segment
		(start 430.08169 -17.342612)
		(end 430.3522 -17.613122)
		(width 0.12954)
		(layer "F.Cu")
		(net "P5E_CPU0_G3_TX_DP<1>")
	)
	(segment
		(start 326.477376 -141.532102)
		(end 327.603358 -151.402288)
		(width 0.14224)
		(layer "In4.Cu")
		(net "P5E_CPU0_G3_TX_DP<1>")
	)
	(segment
		(start 375.510298 -223.100138)
		(end 375.508774 -223.101154)
		(width 0.1143)
		(layer "In4.Cu")
		(net "P5E_CPU0_G3_TX_DP<1>")
	)
	(segment
		(start 373.627142 -227.962206)
		(end 373.624348 -227.96373)
		(width 0.1143)
		(layer "In4.Cu")
		(net "P5E_CPU0_G3_TX_DP<1>")
	)
	(segment
		(start 373.516906 -233.14406)
		(end 373.814848 -233.14406)
		(width 0.1143)
		(layer "In4.Cu")
		(net "P5E_CPU0_G3_TX_DP<1>")
	)
	(segment
		(start 374.094248 -225.533712)
		(end 374.093486 -225.53422)
		(width 0.1143)
		(layer "In4.Cu")
		(net "P5E_CPU0_G3_TX_DP<1>")
	)
	(segment
		(start 376.305826 -219.984066)
		(end 376.305826 -221.17431)
		(width 0.14224)
		(layer "In4.Cu")
		(net "P5E_CPU0_G3_TX_DP<1>")
	)
	(segment
		(start 373.627142 -226.342194)
		(end 373.624348 -226.343718)
		(width 0.1143)
		(layer "In4.Cu")
		(net "P5E_CPU0_G3_TX_DP<1>")
	)
	(segment
		(start 373.624348 -227.96373)
		(end 373.623586 -227.964238)
		(width 0.1143)
		(layer "In4.Cu")
		(net "P5E_CPU0_G3_TX_DP<1>")
	)
	(segment
		(start 373.624348 -226.343718)
		(end 373.623586 -226.344226)
		(width 0.1143)
		(layer "In4.Cu")
		(net "P5E_CPU0_G3_TX_DP<1>")
	)
	(segment
		(start 430.06137 -20.547584)
		(end 328.238866 -133.23951)
		(width 0.14224)
		(layer "In4.Cu")
		(net "P5E_CPU0_G3_TX_DP<1>")
	)
	(segment
		(start 373.664226 -229.560628)
		(end 373.596408 -229.599744)
		(width 0.1143)
		(layer "In4.Cu")
		(net "P5E_CPU0_G3_TX_DP<1>")
	)
	(segment
		(start 375.511314 -223.09963)
		(end 375.510298 -223.100138)
		(width 0.1143)
		(layer "In4.Cu")
		(net "P5E_CPU0_G3_TX_DP<1>")
	)
	(segment
		(start 373.596154 -226.968558)
		(end 373.625872 -226.985576)
		(width 0.1143)
		(layer "In4.Cu")
		(net "P5E_CPU0_G3_TX_DP<1>")
	)
	(segment
		(start 342.427814 -180.153818)
		(end 367.676938 -200.832974)
		(width 0.14224)
		(layer "In4.Cu")
		(net "P5E_CPU0_G3_TX_DP<1>")
	)
	(segment
		(start 373.620284 -226.346004)
		(end 373.596154 -226.359974)
		(width 0.1143)
		(layer "In4.Cu")
		(net "P5E_CPU0_G3_TX_DP<1>")
	)
	(segment
		(start 373.447056 -233.07421)
		(end 373.516906 -233.14406)
		(width 0.1143)
		(layer "In4.Cu")
		(net "P5E_CPU0_G3_TX_DP<1>")
	)
	(segment
		(start 373.627142 -226.986338)
		(end 373.627904 -226.986846)
		(width 0.1143)
		(layer "In4.Cu")
		(net "P5E_CPU0_G3_TX_DP<1>")
	)
	(segment
		(start 375.08688 -223.883474)
		(end 375.009156 -223.928178)
		(width 0.1143)
		(layer "In4.Cu")
		(net "P5E_CPU0_G3_TX_DP<1>")
	)
	(segment
		(start 327.603358 -151.402288)
		(end 328.365104 -154.696922)
		(width 0.14224)
		(layer "In4.Cu")
		(net "P5E_CPU0_G3_TX_DP<1>")
	)
	(segment
		(start 328.238866 -133.23951)
		(end 327.650602 -134.226808)
		(width 0.14224)
		(layer "In4.Cu")
		(net "P5E_CPU0_G3_TX_DP<1>")
	)
	(segment
		(start 430.06137 -17.903952)
		(end 430.06137 -20.547584)
		(width 0.14224)
		(layer "In4.Cu")
		(net "P5E_CPU0_G3_TX_DP<1>")
	)
	(segment
		(start 373.625872 -228.605588)
		(end 373.627142 -228.60635)
		(width 0.1143)
		(layer "In4.Cu")
		(net "P5E_CPU0_G3_TX_DP<1>")
	)
	(segment
		(start 374.136158 -231.989122)
		(end 374.097296 -232.011728)
		(width 0.1143)
		(layer "In4.Cu")
		(net "P5E_CPU0_G3_TX_DP<1>")
	)
	(segment
		(start 336.663792 -172.13072)
		(end 341.432896 -179.159154)
		(width 0.14224)
		(layer "In4.Cu")
		(net "P5E_CPU0_G3_TX_DP<1>")
	)
	(segment
		(start 374.097804 -225.53168)
		(end 374.09628 -225.532696)
		(width 0.1143)
		(layer "In4.Cu")
		(net "P5E_CPU0_G3_TX_DP<1>")
	)
	(segment
		(start 373.62257 -232.824528)
		(end 373.621808 -232.825036)
		(width 0.1143)
		(layer "In4.Cu")
		(net "P5E_CPU0_G3_TX_DP<1>")
	)
	(segment
		(start 375.009156 -223.928178)
		(end 375.007378 -223.929448)
		(width 0.1143)
		(layer "In4.Cu")
		(net "P5E_CPU0_G3_TX_DP<1>")
	)
	(segment
		(start 376.305826 -221.202758)
		(end 376.260106 -221.248478)
		(width 0.1143)
		(layer "In4.Cu")
		(net "P5E_CPU0_G3_TX_DP<1>")
	)
	(segment
		(start 374.09628 -225.532696)
		(end 374.094248 -225.533712)
		(width 0.1143)
		(layer "In4.Cu")
		(net "P5E_CPU0_G3_TX_DP<1>")
	)
	(segment
		(start 373.627904 -228.606858)
		(end 373.664226 -228.62794)
		(width 0.1143)
		(layer "In4.Cu")
		(net "P5E_CPU0_G3_TX_DP<1>")
	)
	(segment
		(start 373.624348 -232.823512)
		(end 373.623586 -232.82402)
		(width 0.1143)
		(layer "In4.Cu")
		(net "P5E_CPU0_G3_TX_DP<1>")
	)
	(segment
		(start 375.519696 -223.094804)
		(end 375.51741 -223.096074)
		(width 0.1143)
		(layer "In4.Cu")
		(net "P5E_CPU0_G3_TX_DP<1>")
	)
	(segment
		(start 326.606662 -137.594848)
		(end 326.492362 -138.159236)
		(width 0.14224)
		(layer "In4.Cu")
		(net "P5E_CPU0_G3_TX_DP<1>")
	)
	(segment
		(start 373.625872 -226.985576)
		(end 373.627142 -226.986338)
		(width 0.1143)
		(layer "In4.Cu")
		(net "P5E_CPU0_G3_TX_DP<1>")
	)
	(segment
		(start 374.093486 -225.53422)
		(end 374.09247 -225.534728)
		(width 0.1143)
		(layer "In4.Cu")
		(net "P5E_CPU0_G3_TX_DP<1>")
	)
	(segment
		(start 373.630698 -226.339908)
		(end 373.627904 -226.341686)
		(width 0.1143)
		(layer "In4.Cu")
		(net "P5E_CPU0_G3_TX_DP<1>")
	)
	(segment
		(start 367.676938 -200.832974)
		(end 375.420382 -213.902798)
		(width 0.14224)
		(layer "In4.Cu")
		(net "P5E_CPU0_G3_TX_DP<1>")
	)
	(segment
		(start 376.040142 -222.252032)
		(end 376.032014 -222.26016)
		(width 0.1143)
		(layer "In4.Cu")
		(net "P5E_CPU0_G3_TX_DP<1>")
	)
	(segment
		(start 375.507758 -223.101662)
		(end 375.506996 -223.10217)
		(width 0.1143)
		(layer "In4.Cu")
		(net "P5E_CPU0_G3_TX_DP<1>")
	)
	(segment
		(start 373.627904 -226.341686)
		(end 373.627142 -226.342194)
		(width 0.1143)
		(layer "In4.Cu")
		(net "P5E_CPU0_G3_TX_DP<1>")
	)
	(segment
		(start 373.915686 -232.326942)
		(end 373.915686 -232.329482)
		(width 0.1143)
		(layer "In4.Cu")
		(net "P5E_CPU0_G3_TX_DP<1>")
	)
	(segment
		(start 373.620284 -232.825798)
		(end 373.596154 -232.839768)
		(width 0.1143)
		(layer "In4.Cu")
		(net "P5E_CPU0_G3_TX_DP<1>")
	)
	(segment
		(start 374.068086 -231.019604)
		(end 374.13692 -231.059482)
		(width 0.1143)
		(layer "In4.Cu")
		(net "P5E_CPU0_G3_TX_DP<1>")
	)
	(segment
		(start 430.3522 -17.613122)
		(end 430.06137 -17.903952)
		(width 0.14224)
		(layer "In4.Cu")
		(net "P5E_CPU0_G3_TX_DP<1>")
	)
	(segment
		(start 373.631206 -232.819702)
		(end 373.628666 -232.820972)
		(width 0.1143)
		(layer "In4.Cu")
		(net "P5E_CPU0_G3_TX_DP<1>")
	)
	(segment
		(start 376.305826 -221.17431)
		(end 376.305826 -221.202758)
		(width 0.1143)
		(layer "In4.Cu")
		(net "P5E_CPU0_G3_TX_DP<1>")
	)
	(segment
		(start 373.620284 -227.966016)
		(end 373.596154 -227.979986)
		(width 0.1143)
		(layer "In4.Cu")
		(net "P5E_CPU0_G3_TX_DP<1>")
	)
	(segment
		(start 326.477376 -138.26998)
		(end 326.477376 -141.532102)
		(width 0.14224)
		(layer "In4.Cu")
		(net "P5E_CPU0_G3_TX_DP<1>")
	)
	(segment
		(start 374.09247 -225.534728)
		(end 374.06834 -225.548698)
		(width 0.1143)
		(layer "In4.Cu")
		(net "P5E_CPU0_G3_TX_DP<1>")
	)
	(segment
		(start 373.627142 -232.821988)
		(end 373.624348 -232.823512)
		(width 0.1143)
		(layer "In4.Cu")
		(net "P5E_CPU0_G3_TX_DP<1>")
	)
	(segment
		(start 373.596154 -228.58857)
		(end 373.625872 -228.605588)
		(width 0.1143)
		(layer "In4.Cu")
		(net "P5E_CPU0_G3_TX_DP<1>")
	)
	(segment
		(start 373.621808 -232.825036)
		(end 373.620284 -232.825798)
		(width 0.1143)
		(layer "In4.Cu")
		(net "P5E_CPU0_G3_TX_DP<1>")
	)
	(segment
		(start 327.650602 -134.226808)
		(end 327.413874 -134.838186)
		(width 0.14224)
		(layer "In4.Cu")
		(net "P5E_CPU0_G3_TX_DP<1>")
	)
	(segment
		(start 375.515378 -223.097344)
		(end 375.5136 -223.09836)
		(width 0.1143)
		(layer "In4.Cu")
		(net "P5E_CPU0_G3_TX_DP<1>")
	)
	(segment
		(start 375.506996 -223.10217)
		(end 375.477278 -223.119442)
		(width 0.1143)
		(layer "In4.Cu")
		(net "P5E_CPU0_G3_TX_DP<1>")
	)
	(segment
		(start 373.910098 -225.85426)
		(end 373.910098 -225.861372)
		(width 0.1143)
		(layer "In4.Cu")
		(net "P5E_CPU0_G3_TX_DP<1>")
	)
	(segment
		(start 373.62257 -227.964746)
		(end 373.621808 -227.965254)
		(width 0.1143)
		(layer "In4.Cu")
		(net "P5E_CPU0_G3_TX_DP<1>")
	)
	(segment
		(start 327.413874 -134.838186)
		(end 326.606662 -137.594848)
		(width 0.14224)
		(layer "In4.Cu")
		(net "P5E_CPU0_G3_TX_DP<1>")
	)
	(segment
		(start 373.623586 -226.344226)
		(end 373.62257 -226.344734)
		(width 0.1143)
		(layer "In4.Cu")
		(net "P5E_CPU0_G3_TX_DP<1>")
	)
	(segment
		(start 373.627904 -226.986846)
		(end 373.664226 -227.007928)
		(width 0.1143)
		(layer "In4.Cu")
		(net "P5E_CPU0_G3_TX_DP<1>")
	)
	(segment
		(start 373.621808 -226.345242)
		(end 373.620284 -226.346004)
		(width 0.1143)
		(layer "In4.Cu")
		(net "P5E_CPU0_G3_TX_DP<1>")
	)
	(segment
		(start 375.5136 -223.09836)
		(end 375.512584 -223.098868)
		(width 0.1143)
		(layer "In4.Cu")
		(net "P5E_CPU0_G3_TX_DP<1>")
	)
	(segment
		(start 373.67718 -226.311206)
		(end 373.666766 -226.31908)
		(width 0.1143)
		(layer "In4.Cu")
		(net "P5E_CPU0_G3_TX_DP<1>")
	)
	(segment
		(start 328.939906 -156.31795)
		(end 336.663792 -172.13072)
		(width 0.14224)
		(layer "In4.Cu")
		(net "P5E_CPU0_G3_TX_DP<1>")
	)
	(segment
		(start 373.666766 -226.31908)
		(end 373.630698 -226.339908)
		(width 0.1143)
		(layer "In4.Cu")
		(net "P5E_CPU0_G3_TX_DP<1>")
	)
	(segment
		(start 373.623586 -232.82402)
		(end 373.62257 -232.824528)
		(width 0.1143)
		(layer "In4.Cu")
		(net "P5E_CPU0_G3_TX_DP<1>")
	)
	(segment
		(start 326.492362 -138.159236)
		(end 326.477376 -138.26998)
		(width 0.14224)
		(layer "In4.Cu")
		(net "P5E_CPU0_G3_TX_DP<1>")
	)
	(segment
		(start 376.260106 -221.248478)
		(end 376.260106 -221.804738)
		(width 0.1143)
		(layer "In4.Cu")
		(net "P5E_CPU0_G3_TX_DP<1>")
	)
	(segment
		(start 373.623586 -227.964238)
		(end 373.62257 -227.964746)
		(width 0.1143)
		(layer "In4.Cu")
		(net "P5E_CPU0_G3_TX_DP<1>")
	)
	(segment
		(start 341.432896 -179.159154)
		(end 342.427814 -180.153818)
		(width 0.14224)
		(layer "In4.Cu")
		(net "P5E_CPU0_G3_TX_DP<1>")
	)
	(segment
		(start 373.596408 -229.599744)
		(end 373.596154 -229.599998)
		(width 0.1143)
		(layer "In4.Cu")
		(net "P5E_CPU0_G3_TX_DP<1>")
	)
	(segment
		(start 373.621808 -227.965254)
		(end 373.620284 -227.966016)
		(width 0.1143)
		(layer "In4.Cu")
		(net "P5E_CPU0_G3_TX_DP<1>")
	)
	(segment
		(start 375.512584 -223.098868)
		(end 375.511314 -223.09963)
		(width 0.1143)
		(layer "In4.Cu")
		(net "P5E_CPU0_G3_TX_DP<1>")
	)
	(segment
		(start 375.420382 -213.902798)
		(end 376.305826 -219.984066)
		(width 0.14224)
		(layer "In4.Cu")
		(net "P5E_CPU0_G3_TX_DP<1>")
	)
	(segment
		(start 373.62638 -230.228902)
		(end 373.630952 -230.231696)
		(width 0.1143)
		(layer "In4.Cu")
		(net "P5E_CPU0_G3_TX_DP<1>")
	)
	(segment
		(start 373.627904 -227.961698)
		(end 373.627142 -227.962206)
		(width 0.1143)
		(layer "In4.Cu")
		(net "P5E_CPU0_G3_TX_DP<1>")
	)
	(segment
		(start 373.62257 -226.344734)
		(end 373.621808 -226.345242)
		(width 0.1143)
		(layer "In4.Cu")
		(net "P5E_CPU0_G3_TX_DP<1>")
	)
	(segment
		(start 374.098312 -225.531172)
		(end 374.097804 -225.53168)
		(width 0.1143)
		(layer "In4.Cu")
		(net "P5E_CPU0_G3_TX_DP<1>")
	)
	(segment
		(start 373.664226 -227.940616)
		(end 373.627904 -227.961698)
		(width 0.1143)
		(layer "In4.Cu")
		(net "P5E_CPU0_G3_TX_DP<1>")
	)
	(segment
		(start 375.51741 -223.096074)
		(end 375.515378 -223.097344)
		(width 0.1143)
		(layer "In4.Cu")
		(net "P5E_CPU0_G3_TX_DP<1>")
	)
	(segment
		(start 328.365104 -154.696922)
		(end 328.939906 -156.31795)
		(width 0.14224)
		(layer "In4.Cu")
		(net "P5E_CPU0_G3_TX_DP<1>")
	)
	(segment
		(start 373.627142 -228.60635)
		(end 373.627904 -228.606858)
		(width 0.1143)
		(layer "In4.Cu")
		(net "P5E_CPU0_G3_TX_DP<1>")
	)
	(segment
		(start 373.628666 -232.820972)
		(end 373.627142 -232.821988)
		(width 0.1143)
		(layer "In4.Cu")
		(net "P5E_CPU0_G3_TX_DP<1>")
	)
	(segment
		(start 376.032014 -222.26016)
		(end 375.947178 -222.309436)
		(width 0.1143)
		(layer "In4.Cu")
		(net "P5E_CPU0_G3_TX_DP<1>")
	)
	(segment
		(start 375.508774 -223.101154)
		(end 375.507758 -223.101662)
		(width 0.1143)
		(layer "In4.Cu")
		(net "P5E_CPU0_G3_TX_DP<1>")
	)
	(segment
		(start 375.546874 -223.078802)
		(end 375.519696 -223.094804)
		(width 0.1143)
		(layer "In4.Cu")
		(net "P5E_CPU0_G3_TX_DP<1>")
	)
	(arc
		(start 373.596154 -226.359974)
		(mid 373.440226 -226.664266)
		(end 373.596154 -226.968558)
		(width 0.1143)
		(layer "In4.Cu")
		(net "P5E_CPU0_G3_TX_DP<1>")
	)
	(arc
		(start 373.680482 -228.63937)
		(mid 373.845149 -228.837977)
		(end 373.910098 -229.08768)
		(width 0.1143)
		(layer "In4.Cu")
		(net "P5E_CPU0_G3_TX_DP<1>")
	)
	(arc
		(start 373.664226 -227.007928)
		(mid 373.671376 -227.012826)
		(end 373.67845 -227.017834)
		(width 0.1143)
		(layer "In4.Cu")
		(net "P5E_CPU0_G3_TX_DP<1>")
	)
	(arc
		(start 373.630952 -230.231696)
		(mid 373.835276 -230.435541)
		(end 373.910098 -230.714296)
		(width 0.1143)
		(layer "In4.Cu")
		(net "P5E_CPU0_G3_TX_DP<1>")
	)
	(arc
		(start 375.291858 -223.568768)
		(mid 375.210705 -223.740022)
		(end 375.08688 -223.883474)
		(width 0.1143)
		(layer "In4.Cu")
		(net "P5E_CPU0_G3_TX_DP<1>")
	)
	(arc
		(start 373.596154 -227.979986)
		(mid 373.440226 -228.284278)
		(end 373.596154 -228.58857)
		(width 0.1143)
		(layer "In4.Cu")
		(net "P5E_CPU0_G3_TX_DP<1>")
	)
	(arc
		(start 375.477278 -223.119442)
		(mid 375.365807 -223.245166)
		(end 375.32056 -223.40697)
		(width 0.1143)
		(layer "In4.Cu")
		(net "P5E_CPU0_G3_TX_DP<1>")
	)
	(arc
		(start 373.915686 -232.329482)
		(mid 373.83947 -232.612903)
		(end 373.631206 -232.819702)
		(width 0.1143)
		(layer "In4.Cu")
		(net "P5E_CPU0_G3_TX_DP<1>")
	)
	(arc
		(start 374.85193 -224.197164)
		(mid 374.75353 -224.501975)
		(end 374.537732 -224.738692)
		(width 0.1143)
		(layer "In4.Cu")
		(net "P5E_CPU0_G3_TX_DP<1>")
	)
	(arc
		(start 375.947178 -222.309436)
		(mid 375.831751 -222.442812)
		(end 375.790206 -222.614236)
		(width 0.1143)
		(layer "In4.Cu")
		(net "P5E_CPU0_G3_TX_DP<1>")
	)
	(arc
		(start 376.260106 -221.804738)
		(mid 376.202203 -222.054003)
		(end 376.040142 -222.252032)
		(width 0.1143)
		(layer "In4.Cu")
		(net "P5E_CPU0_G3_TX_DP<1>")
	)
	(arc
		(start 373.596154 -229.599998)
		(mid 373.481311 -229.733146)
		(end 373.439944 -229.904036)
		(width 0.1143)
		(layer "In4.Cu")
		(net "P5E_CPU0_G3_TX_DP<1>")
	)
	(arc
		(start 374.13692 -231.059482)
		(mid 374.380247 -231.524048)
		(end 374.13692 -231.988614)
		(width 0.1143)
		(layer "In4.Cu")
		(net "P5E_CPU0_G3_TX_DP<1>")
	)
	(arc
		(start 374.379998 -225.044254)
		(mid 374.304496 -225.325506)
		(end 374.098312 -225.531172)
		(width 0.1143)
		(layer "In4.Cu")
		(net "P5E_CPU0_G3_TX_DP<1>")
	)
	(arc
		(start 373.910098 -230.714296)
		(mid 373.951977 -230.886165)
		(end 374.068086 -231.019604)
		(width 0.1143)
		(layer "In4.Cu")
		(net "P5E_CPU0_G3_TX_DP<1>")
	)
	(arc
		(start 373.664226 -228.62794)
		(mid 373.672404 -228.633583)
		(end 373.680482 -228.63937)
		(width 0.1143)
		(layer "In4.Cu")
		(net "P5E_CPU0_G3_TX_DP<1>")
	)
	(arc
		(start 373.67845 -227.017834)
		(mid 373.905833 -227.474272)
		(end 373.67845 -227.93071)
		(width 0.1143)
		(layer "In4.Cu")
		(net "P5E_CPU0_G3_TX_DP<1>")
	)
	(arc
		(start 375.790206 -222.614236)
		(mid 375.725691 -222.876455)
		(end 375.546874 -223.078802)
		(width 0.1143)
		(layer "In4.Cu")
		(net "P5E_CPU0_G3_TX_DP<1>")
	)
	(arc
		(start 373.439944 -229.904036)
		(mid 373.489872 -230.091306)
		(end 373.62638 -230.228902)
		(width 0.1143)
		(layer "In4.Cu")
		(net "P5E_CPU0_G3_TX_DP<1>")
	)
	(arc
		(start 375.32056 -223.40697)
		(mid 375.311516 -223.48881)
		(end 375.291858 -223.568768)
		(width 0.1143)
		(layer "In4.Cu")
		(net "P5E_CPU0_G3_TX_DP<1>")
	)
	(arc
		(start 374.537732 -224.738692)
		(mid 374.421779 -224.872325)
		(end 374.379998 -225.044254)
		(width 0.1143)
		(layer "In4.Cu")
		(net "P5E_CPU0_G3_TX_DP<1>")
	)
	(arc
		(start 373.910098 -229.08768)
		(mid 373.910108 -229.090982)
		(end 373.910098 -229.094284)
		(width 0.1143)
		(layer "In4.Cu")
		(net "P5E_CPU0_G3_TX_DP<1>")
	)
	(arc
		(start 374.097296 -232.011728)
		(mid 373.964376 -232.145075)
		(end 373.915686 -232.326942)
		(width 0.1143)
		(layer "In4.Cu")
		(net "P5E_CPU0_G3_TX_DP<1>")
	)
	(arc
		(start 373.596154 -232.839768)
		(mid 373.499019 -232.942637)
		(end 373.447056 -233.07421)
		(width 0.1143)
		(layer "In4.Cu")
		(net "P5E_CPU0_G3_TX_DP<1>")
	)
	(arc
		(start 375.007378 -223.929448)
		(mid 374.900774 -224.046521)
		(end 374.85193 -224.197164)
		(width 0.1143)
		(layer "In4.Cu")
		(net "P5E_CPU0_G3_TX_DP<1>")
	)
	(arc
		(start 373.67845 -227.93071)
		(mid 373.671377 -227.935719)
		(end 373.664226 -227.940616)
		(width 0.1143)
		(layer "In4.Cu")
		(net "P5E_CPU0_G3_TX_DP<1>")
	)
	(arc
		(start 374.06834 -225.548698)
		(mid 373.952067 -225.682238)
		(end 373.910098 -225.85426)
		(width 0.1143)
		(layer "In4.Cu")
		(net "P5E_CPU0_G3_TX_DP<1>")
	)
	(arc
		(start 374.13692 -231.988614)
		(mid 374.136539 -231.988868)
		(end 374.136158 -231.989122)
		(width 0.1143)
		(layer "In4.Cu")
		(net "P5E_CPU0_G3_TX_DP<1>")
	)
	(arc
		(start 373.910098 -225.861372)
		(mid 373.843896 -226.112305)
		(end 373.67718 -226.311206)
		(width 0.1143)
		(layer "In4.Cu")
		(net "P5E_CPU0_G3_TX_DP<1>")
	)
	(arc
		(start 373.910098 -229.094284)
		(mid 373.844862 -229.357875)
		(end 373.664226 -229.560628)
		(width 0.1143)
		(layer "In4.Cu")
		(net "P5E_CPU0_G3_TX_DP<1>")
	)
	(segment
		(start 390.626854 -16.661892)
		(end 390.626854 -17.34185)
		(width 0.12954)
		(layer "F.Cu")
		(net "P5E_CPU0_G3_TX_DP<15>")
	)
	(segment
		(start 362.53801 -235.840016)
		(end 363.004862 -235.574078)
		(width 0.12954)
		(layer "F.Cu")
		(net "P5E_CPU0_G3_TX_DP<15>")
	)
	(segment
		(start 390.626854 -17.34185)
		(end 390.897364 -17.61236)
		(width 0.12954)
		(layer "F.Cu")
		(net "P5E_CPU0_G3_TX_DP<15>")
	)
	(segment
		(start 390.921748 -16.366998)
		(end 390.626854 -16.661892)
		(width 0.12954)
		(layer "F.Cu")
		(net "P5E_CPU0_G3_TX_DP<15>")
	)
	(segment
		(start 320.196972 -179.046886)
		(end 357.281734 -209.455004)
		(width 0.14224)
		(layer "In4.Cu")
		(net "P5E_CPU0_G3_TX_DP<15>")
	)
	(segment
		(start 360.990134 -233.06659)
		(end 361.331256 -233.407712)
		(width 0.1143)
		(layer "In4.Cu")
		(net "P5E_CPU0_G3_TX_DP<15>")
	)
	(segment
		(start 361.40771 -233.46664)
		(end 361.446826 -233.4895)
		(width 0.1143)
		(layer "In4.Cu")
		(net "P5E_CPU0_G3_TX_DP<15>")
	)
	(segment
		(start 361.873292 -234.274106)
		(end 361.875832 -234.275376)
		(width 0.1143)
		(layer "In4.Cu")
		(net "P5E_CPU0_G3_TX_DP<15>")
	)
	(segment
		(start 362.34878 -235.08716)
		(end 362.350304 -235.088176)
		(width 0.1143)
		(layer "In4.Cu")
		(net "P5E_CPU0_G3_TX_DP<15>")
	)
	(segment
		(start 390.897364 -17.61236)
		(end 390.606534 -17.90319)
		(width 0.14224)
		(layer "In4.Cu")
		(net "P5E_CPU0_G3_TX_DP<15>")
	)
	(segment
		(start 357.281734 -209.455004)
		(end 359.228898 -212.734398)
		(width 0.14224)
		(layer "In4.Cu")
		(net "P5E_CPU0_G3_TX_DP<15>")
	)
	(segment
		(start 361.877102 -234.276138)
		(end 361.877864 -234.276646)
		(width 0.1143)
		(layer "In4.Cu")
		(net "P5E_CPU0_G3_TX_DP<15>")
	)
	(segment
		(start 362.316014 -235.068364)
		(end 362.347002 -235.086144)
		(width 0.1143)
		(layer "In4.Cu")
		(net "P5E_CPU0_G3_TX_DP<15>")
	)
	(segment
		(start 361.189778 -216.03716)
		(end 361.189778 -220.359224)
		(width 0.14224)
		(layer "In4.Cu")
		(net "P5E_CPU0_G3_TX_DP<15>")
	)
	(segment
		(start 361.846114 -234.258358)
		(end 361.871768 -234.27309)
		(width 0.1143)
		(layer "In4.Cu")
		(net "P5E_CPU0_G3_TX_DP<15>")
	)
	(segment
		(start 361.189778 -220.359224)
		(end 360.596434 -223.3422)
		(width 0.14224)
		(layer "In4.Cu")
		(net "P5E_CPU0_G3_TX_DP<15>")
	)
	(segment
		(start 319.340992 -178.474624)
		(end 320.185542 -179.039266)
		(width 0.14224)
		(layer "In4.Cu")
		(net "P5E_CPU0_G3_TX_DP<15>")
	)
	(segment
		(start 361.877864 -234.276646)
		(end 361.914186 -234.297728)
		(width 0.1143)
		(layer "In4.Cu")
		(net "P5E_CPU0_G3_TX_DP<15>")
	)
	(segment
		(start 390.606534 -20.547584)
		(end 321.983862 -116.574316)
		(width 0.14224)
		(layer "In4.Cu")
		(net "P5E_CPU0_G3_TX_DP<15>")
	)
	(segment
		(start 362.355892 -235.091478)
		(end 362.38688 -235.109512)
		(width 0.1143)
		(layer "In4.Cu")
		(net "P5E_CPU0_G3_TX_DP<15>")
	)
	(segment
		(start 360.596434 -223.3422)
		(end 360.596434 -232.607866)
		(width 0.14224)
		(layer "In4.Cu")
		(net "P5E_CPU0_G3_TX_DP<15>")
	)
	(segment
		(start 390.606534 -17.90319)
		(end 390.606534 -20.547584)
		(width 0.14224)
		(layer "In4.Cu")
		(net "P5E_CPU0_G3_TX_DP<15>")
	)
	(segment
		(start 320.185542 -179.039266)
		(end 320.185542 -179.039012)
		(width 0.14224)
		(layer "In4.Cu")
		(net "P5E_CPU0_G3_TX_DP<15>")
	)
	(segment
		(start 362.353098 -235.0897)
		(end 362.354368 -235.090462)
		(width 0.1143)
		(layer "In4.Cu")
		(net "P5E_CPU0_G3_TX_DP<15>")
	)
	(segment
		(start 362.347002 -235.086144)
		(end 362.347764 -235.086652)
		(width 0.1143)
		(layer "In4.Cu")
		(net "P5E_CPU0_G3_TX_DP<15>")
	)
	(segment
		(start 362.302552 -235.058712)
		(end 362.316014 -235.068364)
		(width 0.1143)
		(layer "In4.Cu")
		(net "P5E_CPU0_G3_TX_DP<15>")
	)
	(segment
		(start 359.228898 -212.734398)
		(end 359.229152 -212.734398)
		(width 0.14224)
		(layer "In4.Cu")
		(net "P5E_CPU0_G3_TX_DP<15>")
	)
	(segment
		(start 361.871768 -234.27309)
		(end 361.873292 -234.274106)
		(width 0.1143)
		(layer "In4.Cu")
		(net "P5E_CPU0_G3_TX_DP<15>")
	)
	(segment
		(start 362.350304 -235.088176)
		(end 362.353098 -235.0897)
		(width 0.1143)
		(layer "In4.Cu")
		(net "P5E_CPU0_G3_TX_DP<15>")
	)
	(segment
		(start 315.410596 -128.789938)
		(end 310.846978 -140.666216)
		(width 0.14224)
		(layer "In4.Cu")
		(net "P5E_CPU0_G3_TX_DP<15>")
	)
	(segment
		(start 362.354368 -235.090462)
		(end 362.355892 -235.091478)
		(width 0.1143)
		(layer "In4.Cu")
		(net "P5E_CPU0_G3_TX_DP<15>")
	)
	(segment
		(start 361.875832 -234.275376)
		(end 361.877102 -234.276138)
		(width 0.1143)
		(layer "In4.Cu")
		(net "P5E_CPU0_G3_TX_DP<15>")
	)
	(segment
		(start 305.990752 -163.286694)
		(end 308.888892 -170.284648)
		(width 0.14224)
		(layer "In4.Cu")
		(net "P5E_CPU0_G3_TX_DP<15>")
	)
	(segment
		(start 362.160058 -234.764072)
		(end 362.160058 -234.780582)
		(width 0.1143)
		(layer "In4.Cu")
		(net "P5E_CPU0_G3_TX_DP<15>")
	)
	(segment
		(start 310.846978 -140.666216)
		(end 306.453794 -155.851606)
		(width 0.14224)
		(layer "In4.Cu")
		(net "P5E_CPU0_G3_TX_DP<15>")
	)
	(segment
		(start 362.70692 -235.574078)
		(end 363.004862 -235.574078)
		(width 0.1143)
		(layer "In4.Cu")
		(net "P5E_CPU0_G3_TX_DP<15>")
	)
	(segment
		(start 360.990134 -233.001566)
		(end 360.990134 -233.06659)
		(width 0.1143)
		(layer "In4.Cu")
		(net "P5E_CPU0_G3_TX_DP<15>")
	)
	(segment
		(start 362.347764 -235.086652)
		(end 362.34878 -235.08716)
		(width 0.1143)
		(layer "In4.Cu")
		(net "P5E_CPU0_G3_TX_DP<15>")
	)
	(segment
		(start 306.453794 -155.851606)
		(end 305.990752 -158.1785)
		(width 0.14224)
		(layer "In4.Cu")
		(net "P5E_CPU0_G3_TX_DP<15>")
	)
	(segment
		(start 360.970068 -232.9815)
		(end 360.990134 -233.001566)
		(width 0.1143)
		(layer "In4.Cu")
		(net "P5E_CPU0_G3_TX_DP<15>")
	)
	(segment
		(start 362.624116 -235.491274)
		(end 362.70692 -235.574078)
		(width 0.1143)
		(layer "In4.Cu")
		(net "P5E_CPU0_G3_TX_DP<15>")
	)
	(segment
		(start 320.185542 -179.039012)
		(end 320.196972 -179.046886)
		(width 0.14224)
		(layer "In4.Cu")
		(net "P5E_CPU0_G3_TX_DP<15>")
	)
	(segment
		(start 305.990752 -158.1785)
		(end 305.990752 -163.286694)
		(width 0.14224)
		(layer "In4.Cu")
		(net "P5E_CPU0_G3_TX_DP<15>")
	)
	(segment
		(start 313.692286 -175.089312)
		(end 319.340992 -178.474624)
		(width 0.14224)
		(layer "In4.Cu")
		(net "P5E_CPU0_G3_TX_DP<15>")
	)
	(segment
		(start 360.596434 -232.607866)
		(end 360.970068 -232.9815)
		(width 0.14224)
		(layer "In4.Cu")
		(net "P5E_CPU0_G3_TX_DP<15>")
	)
	(segment
		(start 308.888892 -170.284648)
		(end 313.692286 -175.089312)
		(width 0.14224)
		(layer "In4.Cu")
		(net "P5E_CPU0_G3_TX_DP<15>")
	)
	(segment
		(start 321.983862 -116.574316)
		(end 315.410596 -128.789938)
		(width 0.14224)
		(layer "In4.Cu")
		(net "P5E_CPU0_G3_TX_DP<15>")
	)
	(segment
		(start 359.229152 -212.734398)
		(end 361.189778 -216.03716)
		(width 0.14224)
		(layer "In4.Cu")
		(net "P5E_CPU0_G3_TX_DP<15>")
	)
	(arc
		(start 362.160058 -234.780582)
		(mid 362.197758 -234.936832)
		(end 362.302552 -235.058712)
		(width 0.1143)
		(layer "In4.Cu")
		(net "P5E_CPU0_G3_TX_DP<15>")
	)
	(arc
		(start 361.914186 -234.297728)
		(mid 361.922364 -234.303371)
		(end 361.930442 -234.309158)
		(width 0.1143)
		(layer "In4.Cu")
		(net "P5E_CPU0_G3_TX_DP<15>")
	)
	(arc
		(start 362.160058 -234.757468)
		(mid 362.160068 -234.76077)
		(end 362.160058 -234.764072)
		(width 0.1143)
		(layer "In4.Cu")
		(net "P5E_CPU0_G3_TX_DP<15>")
	)
	(arc
		(start 361.446826 -233.4895)
		(mid 361.625639 -233.69185)
		(end 361.690158 -233.954066)
		(width 0.1143)
		(layer "In4.Cu")
		(net "P5E_CPU0_G3_TX_DP<15>")
	)
	(arc
		(start 362.620306 -235.468414)
		(mid 362.622329 -235.479824)
		(end 362.624116 -235.491274)
		(width 0.1143)
		(layer "In4.Cu")
		(net "P5E_CPU0_G3_TX_DP<15>")
	)
	(arc
		(start 361.690158 -233.954066)
		(mid 361.731413 -234.125037)
		(end 361.846114 -234.258358)
		(width 0.1143)
		(layer "In4.Cu")
		(net "P5E_CPU0_G3_TX_DP<15>")
	)
	(arc
		(start 362.38688 -235.109512)
		(mid 362.538867 -235.26602)
		(end 362.620306 -235.468414)
		(width 0.1143)
		(layer "In4.Cu")
		(net "P5E_CPU0_G3_TX_DP<15>")
	)
	(arc
		(start 361.930442 -234.309158)
		(mid 362.095109 -234.507765)
		(end 362.160058 -234.757468)
		(width 0.1143)
		(layer "In4.Cu")
		(net "P5E_CPU0_G3_TX_DP<15>")
	)
	(arc
		(start 361.331256 -233.407712)
		(mid 361.367571 -233.439656)
		(end 361.40771 -233.46664)
		(width 0.1143)
		(layer "In4.Cu")
		(net "P5E_CPU0_G3_TX_DP<15>")
	)
	(segment
		(start 393.715748 -17.890998)
		(end 393.420854 -18.185892)
		(width 0.12954)
		(layer "F.Cu")
		(net "P5E_CPU0_G3_TX_DP<14>")
	)
	(segment
		(start 362.53801 -234.220004)
		(end 363.004862 -233.954066)
		(width 0.12954)
		(layer "F.Cu")
		(net "P5E_CPU0_G3_TX_DP<14>")
	)
	(segment
		(start 393.420854 -18.185892)
		(end 393.420854 -18.867628)
		(width 0.12954)
		(layer "F.Cu")
		(net "P5E_CPU0_G3_TX_DP<14>")
	)
	(segment
		(start 393.420854 -18.867628)
		(end 393.690348 -19.137122)
		(width 0.12954)
		(layer "F.Cu")
		(net "P5E_CPU0_G3_TX_DP<14>")
	)
	(segment
		(start 322.239386 -118.191026)
		(end 316.260226 -129.17932)
		(width 0.14224)
		(layer "In4.Cu")
		(net "P5E_CPU0_G3_TX_DP<14>")
	)
	(segment
		(start 362.70692 -233.954066)
		(end 363.004862 -233.954066)
		(width 0.1143)
		(layer "In4.Cu")
		(net "P5E_CPU0_G3_TX_DP<14>")
	)
	(segment
		(start 306.922932 -162.871658)
		(end 309.841392 -169.91838)
		(width 0.14224)
		(layer "In4.Cu")
		(net "P5E_CPU0_G3_TX_DP<14>")
	)
	(segment
		(start 362.160058 -221.128844)
		(end 362.160058 -221.38767)
		(width 0.1143)
		(layer "In4.Cu")
		(net "P5E_CPU0_G3_TX_DP<14>")
	)
	(segment
		(start 393.399518 -19.427952)
		(end 393.399518 -20.548346)
		(width 0.14224)
		(layer "In4.Cu")
		(net "P5E_CPU0_G3_TX_DP<14>")
	)
	(segment
		(start 393.399518 -20.548346)
		(end 322.239386 -118.191026)
		(width 0.14224)
		(layer "In4.Cu")
		(net "P5E_CPU0_G3_TX_DP<14>")
	)
	(segment
		(start 362.159804 -221.387924)
		(end 362.159804 -223.631252)
		(width 0.1143)
		(layer "In4.Cu")
		(net "P5E_CPU0_G3_TX_DP<14>")
	)
	(segment
		(start 362.205778 -221.083124)
		(end 362.160058 -221.128844)
		(width 0.1143)
		(layer "In4.Cu")
		(net "P5E_CPU0_G3_TX_DP<14>")
	)
	(segment
		(start 362.619798 -233.848656)
		(end 362.62056 -233.848656)
		(width 0.1143)
		(layer "In4.Cu")
		(net "P5E_CPU0_G3_TX_DP<14>")
	)
	(segment
		(start 361.907328 -232.676192)
		(end 361.94111 -232.698544)
		(width 0.1143)
		(layer "In4.Cu")
		(net "P5E_CPU0_G3_TX_DP<14>")
	)
	(segment
		(start 361.879134 -232.659174)
		(end 361.906566 -232.67543)
		(width 0.1143)
		(layer "In4.Cu")
		(net "P5E_CPU0_G3_TX_DP<14>")
	)
	(segment
		(start 362.270548 -233.421682)
		(end 362.379006 -233.484928)
		(width 0.1143)
		(layer "In4.Cu")
		(net "P5E_CPU0_G3_TX_DP<14>")
	)
	(segment
		(start 362.159804 -223.631252)
		(end 361.69092 -225.749358)
		(width 0.1143)
		(layer "In4.Cu")
		(net "P5E_CPU0_G3_TX_DP<14>")
	)
	(segment
		(start 362.624116 -233.871262)
		(end 362.70692 -233.954066)
		(width 0.1143)
		(layer "In4.Cu")
		(net "P5E_CPU0_G3_TX_DP<14>")
	)
	(segment
		(start 361.406694 -231.849422)
		(end 361.41279 -231.852978)
		(width 0.1143)
		(layer "In4.Cu")
		(net "P5E_CPU0_G3_TX_DP<14>")
	)
	(segment
		(start 314.27039 -174.348394)
		(end 319.848992 -177.691796)
		(width 0.14224)
		(layer "In4.Cu")
		(net "P5E_CPU0_G3_TX_DP<14>")
	)
	(segment
		(start 361.220258 -231.524048)
		(end 361.220512 -231.524048)
		(width 0.1143)
		(layer "In4.Cu")
		(net "P5E_CPU0_G3_TX_DP<14>")
	)
	(segment
		(start 361.37723 -230.208836)
		(end 361.444286 -230.247952)
		(width 0.1143)
		(layer "In4.Cu")
		(net "P5E_CPU0_G3_TX_DP<14>")
	)
	(segment
		(start 319.848992 -177.691796)
		(end 320.747136 -178.292252)
		(width 0.14224)
		(layer "In4.Cu")
		(net "P5E_CPU0_G3_TX_DP<14>")
	)
	(segment
		(start 362.160058 -221.38767)
		(end 362.159804 -221.387924)
		(width 0.1143)
		(layer "In4.Cu")
		(net "P5E_CPU0_G3_TX_DP<14>")
	)
	(segment
		(start 320.747136 -178.292252)
		(end 358.041448 -208.87182)
		(width 0.14224)
		(layer "In4.Cu")
		(net "P5E_CPU0_G3_TX_DP<14>")
	)
	(segment
		(start 362.205778 -215.88603)
		(end 362.205778 -221.083124)
		(width 0.14224)
		(layer "In4.Cu")
		(net "P5E_CPU0_G3_TX_DP<14>")
	)
	(segment
		(start 358.041448 -208.87182)
		(end 362.205778 -215.88603)
		(width 0.14224)
		(layer "In4.Cu")
		(net "P5E_CPU0_G3_TX_DP<14>")
	)
	(segment
		(start 311.730898 -140.966444)
		(end 307.360574 -156.072332)
		(width 0.14224)
		(layer "In4.Cu")
		(net "P5E_CPU0_G3_TX_DP<14>")
	)
	(segment
		(start 361.272328 -231.714548)
		(end 361.27182 -231.714548)
		(width 0.1143)
		(layer "In4.Cu")
		(net "P5E_CPU0_G3_TX_DP<14>")
	)
	(segment
		(start 309.841392 -169.91838)
		(end 314.27039 -174.34814)
		(width 0.14224)
		(layer "In4.Cu")
		(net "P5E_CPU0_G3_TX_DP<14>")
	)
	(segment
		(start 314.27039 -174.34814)
		(end 314.27039 -174.348394)
		(width 0.14224)
		(layer "In4.Cu")
		(net "P5E_CPU0_G3_TX_DP<14>")
	)
	(segment
		(start 362.379006 -233.484928)
		(end 362.386372 -233.488992)
		(width 0.1143)
		(layer "In4.Cu")
		(net "P5E_CPU0_G3_TX_DP<14>")
	)
	(segment
		(start 361.446826 -226.318826)
		(end 361.37723 -226.359466)
		(width 0.1143)
		(layer "In4.Cu")
		(net "P5E_CPU0_G3_TX_DP<14>")
	)
	(segment
		(start 361.37723 -228.589078)
		(end 361.446826 -228.629718)
		(width 0.1143)
		(layer "In4.Cu")
		(net "P5E_CPU0_G3_TX_DP<14>")
	)
	(segment
		(start 361.409488 -231.2035)
		(end 361.40898 -231.203754)
		(width 0.1143)
		(layer "In4.Cu")
		(net "P5E_CPU0_G3_TX_DP<14>")
	)
	(segment
		(start 361.37723 -226.969066)
		(end 361.446826 -227.009706)
		(width 0.1143)
		(layer "In4.Cu")
		(net "P5E_CPU0_G3_TX_DP<14>")
	)
	(segment
		(start 361.906566 -232.67543)
		(end 361.907328 -232.676192)
		(width 0.1143)
		(layer "In4.Cu")
		(net "P5E_CPU0_G3_TX_DP<14>")
	)
	(segment
		(start 393.690348 -19.137122)
		(end 393.399518 -19.427952)
		(width 0.14224)
		(layer "In4.Cu")
		(net "P5E_CPU0_G3_TX_DP<14>")
	)
	(segment
		(start 361.69092 -225.749358)
		(end 361.689904 -225.859848)
		(width 0.1143)
		(layer "In4.Cu")
		(net "P5E_CPU0_G3_TX_DP<14>")
	)
	(segment
		(start 316.260226 -129.17932)
		(end 311.730898 -140.966444)
		(width 0.14224)
		(layer "In4.Cu")
		(net "P5E_CPU0_G3_TX_DP<14>")
	)
	(segment
		(start 361.40898 -231.203754)
		(end 361.403138 -231.207056)
		(width 0.1143)
		(layer "In4.Cu")
		(net "P5E_CPU0_G3_TX_DP<14>")
	)
	(segment
		(start 361.446826 -229.55885)
		(end 361.40771 -229.58171)
		(width 0.1143)
		(layer "In4.Cu")
		(net "P5E_CPU0_G3_TX_DP<14>")
	)
	(segment
		(start 361.40771 -229.58171)
		(end 361.39501 -229.588822)
		(width 0.1143)
		(layer "In4.Cu")
		(net "P5E_CPU0_G3_TX_DP<14>")
	)
	(segment
		(start 362.16463 -233.131614)
		(end 362.16463 -233.238548)
		(width 0.1143)
		(layer "In4.Cu")
		(net "P5E_CPU0_G3_TX_DP<14>")
	)
	(segment
		(start 361.446826 -227.938838)
		(end 361.37723 -227.979478)
		(width 0.1143)
		(layer "In4.Cu")
		(net "P5E_CPU0_G3_TX_DP<14>")
	)
	(segment
		(start 306.922932 -158.272734)
		(end 306.922932 -162.871658)
		(width 0.14224)
		(layer "In4.Cu")
		(net "P5E_CPU0_G3_TX_DP<14>")
	)
	(segment
		(start 307.360574 -156.072332)
		(end 306.922932 -158.272734)
		(width 0.14224)
		(layer "In4.Cu")
		(net "P5E_CPU0_G3_TX_DP<14>")
	)
	(arc
		(start 361.446826 -228.629718)
		(mid 361.690153 -229.094284)
		(end 361.446826 -229.55885)
		(width 0.1143)
		(layer "In4.Cu")
		(net "P5E_CPU0_G3_TX_DP<14>")
	)
	(arc
		(start 361.690158 -230.714296)
		(mid 361.615007 -230.996296)
		(end 361.409488 -231.2035)
		(width 0.1143)
		(layer "In4.Cu")
		(net "P5E_CPU0_G3_TX_DP<14>")
	)
	(arc
		(start 361.27182 -231.714548)
		(mid 361.330587 -231.790655)
		(end 361.406694 -231.849422)
		(width 0.1143)
		(layer "In4.Cu")
		(net "P5E_CPU0_G3_TX_DP<14>")
	)
	(arc
		(start 361.403138 -231.207056)
		(mid 361.269292 -231.341079)
		(end 361.220258 -231.524048)
		(width 0.1143)
		(layer "In4.Cu")
		(net "P5E_CPU0_G3_TX_DP<14>")
	)
	(arc
		(start 361.689904 -232.332784)
		(mid 361.741142 -232.521142)
		(end 361.879134 -232.659174)
		(width 0.1143)
		(layer "In4.Cu")
		(net "P5E_CPU0_G3_TX_DP<14>")
	)
	(arc
		(start 361.41279 -231.852978)
		(mid 361.614834 -232.056202)
		(end 361.689904 -232.332784)
		(width 0.1143)
		(layer "In4.Cu")
		(net "P5E_CPU0_G3_TX_DP<14>")
	)
	(arc
		(start 361.446826 -227.009706)
		(mid 361.690153 -227.474272)
		(end 361.446826 -227.938838)
		(width 0.1143)
		(layer "In4.Cu")
		(net "P5E_CPU0_G3_TX_DP<14>")
	)
	(arc
		(start 362.62056 -233.848656)
		(mid 362.62245 -233.859941)
		(end 362.624116 -233.871262)
		(width 0.1143)
		(layer "In4.Cu")
		(net "P5E_CPU0_G3_TX_DP<14>")
	)
	(arc
		(start 361.37723 -227.979478)
		(mid 361.220253 -228.284278)
		(end 361.37723 -228.589078)
		(width 0.1143)
		(layer "In4.Cu")
		(net "P5E_CPU0_G3_TX_DP<14>")
	)
	(arc
		(start 361.220258 -229.904036)
		(mid 361.264505 -230.074069)
		(end 361.37723 -230.208836)
		(width 0.1143)
		(layer "In4.Cu")
		(net "P5E_CPU0_G3_TX_DP<14>")
	)
	(arc
		(start 361.37723 -226.359466)
		(mid 361.220253 -226.664266)
		(end 361.37723 -226.969066)
		(width 0.1143)
		(layer "In4.Cu")
		(net "P5E_CPU0_G3_TX_DP<14>")
	)
	(arc
		(start 362.386372 -233.488992)
		(mid 362.538495 -233.645839)
		(end 362.619798 -233.848656)
		(width 0.1143)
		(layer "In4.Cu")
		(net "P5E_CPU0_G3_TX_DP<14>")
	)
	(arc
		(start 361.39501 -229.588822)
		(mid 361.263947 -229.722219)
		(end 361.220258 -229.904036)
		(width 0.1143)
		(layer "In4.Cu")
		(net "P5E_CPU0_G3_TX_DP<14>")
	)
	(arc
		(start 361.94111 -232.698544)
		(mid 362.105493 -232.887916)
		(end 362.16463 -233.131614)
		(width 0.1143)
		(layer "In4.Cu")
		(net "P5E_CPU0_G3_TX_DP<14>")
	)
	(arc
		(start 361.220512 -231.524048)
		(mid 361.233618 -231.622784)
		(end 361.272328 -231.714548)
		(width 0.1143)
		(layer "In4.Cu")
		(net "P5E_CPU0_G3_TX_DP<14>")
	)
	(arc
		(start 362.16463 -233.238548)
		(mid 362.193066 -233.344307)
		(end 362.270548 -233.421682)
		(width 0.1143)
		(layer "In4.Cu")
		(net "P5E_CPU0_G3_TX_DP<14>")
	)
	(arc
		(start 361.444286 -230.247952)
		(mid 361.624938 -230.450697)
		(end 361.690158 -230.714296)
		(width 0.1143)
		(layer "In4.Cu")
		(net "P5E_CPU0_G3_TX_DP<14>")
	)
	(arc
		(start 361.689904 -225.859848)
		(mid 361.624232 -226.118922)
		(end 361.446826 -226.318826)
		(width 0.1143)
		(layer "In4.Cu")
		(net "P5E_CPU0_G3_TX_DP<14>")
	)
	(segment
		(start 396.214854 -17.34185)
		(end 396.485364 -17.61236)
		(width 0.12954)
		(layer "F.Cu")
		(net "P5E_CPU0_G3_TX_DP<13>")
	)
	(segment
		(start 362.53801 -232.599992)
		(end 363.004862 -232.334054)
		(width 0.12954)
		(layer "F.Cu")
		(net "P5E_CPU0_G3_TX_DP<13>")
	)
	(segment
		(start 396.509748 -16.366998)
		(end 396.214854 -16.661892)
		(width 0.12954)
		(layer "F.Cu")
		(net "P5E_CPU0_G3_TX_DP<13>")
	)
	(segment
		(start 396.214854 -16.661892)
		(end 396.214854 -17.34185)
		(width 0.12954)
		(layer "F.Cu")
		(net "P5E_CPU0_G3_TX_DP<13>")
	)
	(segment
		(start 307.909976 -162.818064)
		(end 310.57723 -169.258234)
		(width 0.14224)
		(layer "In4.Cu")
		(net "P5E_CPU0_G3_TX_DP<13>")
	)
	(segment
		(start 362.352082 -227.959158)
		(end 362.350558 -227.960174)
		(width 0.1143)
		(layer "In4.Cu")
		(net "P5E_CPU0_G3_TX_DP<13>")
	)
	(segment
		(start 362.34878 -226.987354)
		(end 362.38688 -227.009706)
		(width 0.1143)
		(layer "In4.Cu")
		(net "P5E_CPU0_G3_TX_DP<13>")
	)
	(segment
		(start 362.34878 -227.96119)
		(end 362.336334 -227.968302)
		(width 0.1143)
		(layer "In4.Cu")
		(net "P5E_CPU0_G3_TX_DP<13>")
	)
	(segment
		(start 321.30238 -177.541428)
		(end 358.866948 -208.342992)
		(width 0.14224)
		(layer "In4.Cu")
		(net "P5E_CPU0_G3_TX_DP<13>")
	)
	(segment
		(start 317.108586 -129.571242)
		(end 312.61558 -141.263878)
		(width 0.14224)
		(layer "In4.Cu")
		(net "P5E_CPU0_G3_TX_DP<13>")
	)
	(segment
		(start 362.351066 -226.339654)
		(end 362.346494 -226.342194)
		(width 0.1143)
		(layer "In4.Cu")
		(net "P5E_CPU0_G3_TX_DP<13>")
	)
	(segment
		(start 363.287056 -224.722182)
		(end 363.256068 -224.739962)
		(width 0.1143)
		(layer "In4.Cu")
		(net "P5E_CPU0_G3_TX_DP<13>")
	)
	(segment
		(start 362.38688 -229.55885)
		(end 362.314236 -229.601268)
		(width 0.1143)
		(layer "In4.Cu")
		(net "P5E_CPU0_G3_TX_DP<13>")
	)
	(segment
		(start 362.353098 -226.338384)
		(end 362.352336 -226.338892)
		(width 0.1143)
		(layer "In4.Cu")
		(net "P5E_CPU0_G3_TX_DP<13>")
	)
	(segment
		(start 363.290104 -224.720404)
		(end 363.287818 -224.721674)
		(width 0.1143)
		(layer "In4.Cu")
		(net "P5E_CPU0_G3_TX_DP<13>")
	)
	(segment
		(start 362.353352 -230.229918)
		(end 362.37926 -230.244904)
		(width 0.1143)
		(layer "In4.Cu")
		(net "P5E_CPU0_G3_TX_DP<13>")
	)
	(segment
		(start 363.256068 -222.108522)
		(end 363.285786 -222.12554)
		(width 0.1143)
		(layer "In4.Cu")
		(net "P5E_CPU0_G3_TX_DP<13>")
	)
	(segment
		(start 362.378498 -227.943918)
		(end 362.362242 -227.953316)
		(width 0.1143)
		(layer "In4.Cu")
		(net "P5E_CPU0_G3_TX_DP<13>")
	)
	(segment
		(start 362.346748 -226.986338)
		(end 362.34878 -226.987354)
		(width 0.1143)
		(layer "In4.Cu")
		(net "P5E_CPU0_G3_TX_DP<13>")
	)
	(segment
		(start 362.348526 -231.20096)
		(end 362.347764 -231.201468)
		(width 0.1143)
		(layer "In4.Cu")
		(net "P5E_CPU0_G3_TX_DP<13>")
	)
	(segment
		(start 362.619798 -232.228644)
		(end 362.62056 -232.228644)
		(width 0.1143)
		(layer "In4.Cu")
		(net "P5E_CPU0_G3_TX_DP<13>")
	)
	(segment
		(start 363.100112 -225.042222)
		(end 363.100112 -225.044254)
		(width 0.1143)
		(layer "In4.Cu")
		(net "P5E_CPU0_G3_TX_DP<13>")
	)
	(segment
		(start 362.380022 -230.245412)
		(end 362.38434 -230.247952)
		(width 0.1143)
		(layer "In4.Cu")
		(net "P5E_CPU0_G3_TX_DP<13>")
	)
	(segment
		(start 362.360718 -227.954332)
		(end 362.352082 -227.959158)
		(width 0.1143)
		(layer "In4.Cu")
		(net "P5E_CPU0_G3_TX_DP<13>")
	)
	(segment
		(start 363.256068 -224.739962)
		(end 363.25429 -224.741232)
		(width 0.1143)
		(layer "In4.Cu")
		(net "P5E_CPU0_G3_TX_DP<13>")
	)
	(segment
		(start 362.347764 -231.201468)
		(end 362.347256 -231.201468)
		(width 0.1143)
		(layer "In4.Cu")
		(net "P5E_CPU0_G3_TX_DP<13>")
	)
	(segment
		(start 362.386118 -226.319334)
		(end 362.353098 -226.338384)
		(width 0.1143)
		(layer "In4.Cu")
		(net "P5E_CPU0_G3_TX_DP<13>")
	)
	(segment
		(start 362.35259 -230.22941)
		(end 362.353352 -230.229918)
		(width 0.1143)
		(layer "In4.Cu")
		(net "P5E_CPU0_G3_TX_DP<13>")
	)
	(segment
		(start 362.70692 -232.334054)
		(end 363.004862 -232.334054)
		(width 0.1143)
		(layer "In4.Cu")
		(net "P5E_CPU0_G3_TX_DP<13>")
	)
	(segment
		(start 362.355892 -228.61143)
		(end 362.357416 -228.612446)
		(width 0.1143)
		(layer "In4.Cu")
		(net "P5E_CPU0_G3_TX_DP<13>")
	)
	(segment
		(start 362.351828 -226.339146)
		(end 362.351066 -226.339654)
		(width 0.1143)
		(layer "In4.Cu")
		(net "P5E_CPU0_G3_TX_DP<13>")
	)
	(segment
		(start 358.866948 -208.342992)
		(end 363.150658 -215.557862)
		(width 0.14224)
		(layer "In4.Cu")
		(net "P5E_CPU0_G3_TX_DP<13>")
	)
	(segment
		(start 363.255814 -223.728534)
		(end 363.329474 -223.770698)
		(width 0.1143)
		(layer "In4.Cu")
		(net "P5E_CPU0_G3_TX_DP<13>")
	)
	(segment
		(start 363.150658 -221.083124)
		(end 363.104938 -221.128844)
		(width 0.1143)
		(layer "In4.Cu")
		(net "P5E_CPU0_G3_TX_DP<13>")
	)
	(segment
		(start 363.104938 -221.128844)
		(end 363.104938 -221.38767)
		(width 0.1143)
		(layer "In4.Cu")
		(net "P5E_CPU0_G3_TX_DP<13>")
	)
	(segment
		(start 363.285786 -222.12554)
		(end 363.287056 -222.126302)
		(width 0.1143)
		(layer "In4.Cu")
		(net "P5E_CPU0_G3_TX_DP<13>")
	)
	(segment
		(start 362.353098 -228.609906)
		(end 362.355892 -228.61143)
		(width 0.1143)
		(layer "In4.Cu")
		(net "P5E_CPU0_G3_TX_DP<13>")
	)
	(segment
		(start 362.388912 -231.177338)
		(end 362.348526 -231.20096)
		(width 0.1143)
		(layer "In4.Cu")
		(net "P5E_CPU0_G3_TX_DP<13>")
	)
	(segment
		(start 362.362242 -227.953316)
		(end 362.360718 -227.954332)
		(width 0.1143)
		(layer "In4.Cu")
		(net "P5E_CPU0_G3_TX_DP<13>")
	)
	(segment
		(start 363.099858 -221.804484)
		(end 363.100112 -221.80423)
		(width 0.1143)
		(layer "In4.Cu")
		(net "P5E_CPU0_G3_TX_DP<13>")
	)
	(segment
		(start 396.194534 -17.90319)
		(end 396.194534 -20.547584)
		(width 0.14224)
		(layer "In4.Cu")
		(net "P5E_CPU0_G3_TX_DP<13>")
	)
	(segment
		(start 362.386118 -227.939346)
		(end 362.37926 -227.94341)
		(width 0.1143)
		(layer "In4.Cu")
		(net "P5E_CPU0_G3_TX_DP<13>")
	)
	(segment
		(start 362.357416 -228.612446)
		(end 362.38688 -228.629718)
		(width 0.1143)
		(layer "In4.Cu")
		(net "P5E_CPU0_G3_TX_DP<13>")
	)
	(segment
		(start 363.339634 -223.069658)
		(end 363.328712 -223.07804)
		(width 0.1143)
		(layer "In4.Cu")
		(net "P5E_CPU0_G3_TX_DP<13>")
	)
	(segment
		(start 363.099858 -221.39275)
		(end 363.099858 -221.804484)
		(width 0.1143)
		(layer "In4.Cu")
		(net "P5E_CPU0_G3_TX_DP<13>")
	)
	(segment
		(start 363.287818 -224.721674)
		(end 363.287056 -224.722182)
		(width 0.1143)
		(layer "In4.Cu")
		(net "P5E_CPU0_G3_TX_DP<13>")
	)
	(segment
		(start 315.04001 -173.722284)
		(end 320.34861 -176.903888)
		(width 0.14224)
		(layer "In4.Cu")
		(net "P5E_CPU0_G3_TX_DP<13>")
	)
	(segment
		(start 362.345986 -230.2256)
		(end 362.34878 -230.227124)
		(width 0.1143)
		(layer "In4.Cu")
		(net "P5E_CPU0_G3_TX_DP<13>")
	)
	(segment
		(start 363.288834 -222.127318)
		(end 363.328712 -222.150432)
		(width 0.1143)
		(layer "In4.Cu")
		(net "P5E_CPU0_G3_TX_DP<13>")
	)
	(segment
		(start 396.194534 -20.547584)
		(end 322.523104 -119.727472)
		(width 0.14224)
		(layer "In4.Cu")
		(net "P5E_CPU0_G3_TX_DP<13>")
	)
	(segment
		(start 312.61558 -141.263878)
		(end 308.267354 -156.294074)
		(width 0.14224)
		(layer "In4.Cu")
		(net "P5E_CPU0_G3_TX_DP<13>")
	)
	(segment
		(start 362.336334 -228.600254)
		(end 362.352336 -228.609398)
		(width 0.1143)
		(layer "In4.Cu")
		(net "P5E_CPU0_G3_TX_DP<13>")
	)
	(segment
		(start 362.352336 -228.609398)
		(end 362.353098 -228.609906)
		(width 0.1143)
		(layer "In4.Cu")
		(net "P5E_CPU0_G3_TX_DP<13>")
	)
	(segment
		(start 322.523104 -119.727472)
		(end 317.108586 -129.571242)
		(width 0.14224)
		(layer "In4.Cu")
		(net "P5E_CPU0_G3_TX_DP<13>")
	)
	(segment
		(start 363.287818 -222.12681)
		(end 363.288834 -222.127318)
		(width 0.1143)
		(layer "In4.Cu")
		(net "P5E_CPU0_G3_TX_DP<13>")
	)
	(segment
		(start 362.350558 -227.960174)
		(end 362.349542 -227.960682)
		(width 0.1143)
		(layer "In4.Cu")
		(net "P5E_CPU0_G3_TX_DP<13>")
	)
	(segment
		(start 307.909976 -158.090616)
		(end 307.909976 -162.818064)
		(width 0.14224)
		(layer "In4.Cu")
		(net "P5E_CPU0_G3_TX_DP<13>")
	)
	(segment
		(start 362.347256 -231.846628)
		(end 362.386118 -231.86898)
		(width 0.1143)
		(layer "In4.Cu")
		(net "P5E_CPU0_G3_TX_DP<13>")
	)
	(segment
		(start 310.57723 -169.258234)
		(end 315.04001 -173.722284)
		(width 0.14224)
		(layer "In4.Cu")
		(net "P5E_CPU0_G3_TX_DP<13>")
	)
	(segment
		(start 362.352336 -226.338892)
		(end 362.351828 -226.339146)
		(width 0.1143)
		(layer "In4.Cu")
		(net "P5E_CPU0_G3_TX_DP<13>")
	)
	(segment
		(start 363.150658 -215.557862)
		(end 363.150658 -221.083124)
		(width 0.14224)
		(layer "In4.Cu")
		(net "P5E_CPU0_G3_TX_DP<13>")
	)
	(segment
		(start 396.485364 -17.61236)
		(end 396.194534 -17.90319)
		(width 0.14224)
		(layer "In4.Cu")
		(net "P5E_CPU0_G3_TX_DP<13>")
	)
	(segment
		(start 362.389166 -231.177338)
		(end 362.388912 -231.177338)
		(width 0.1143)
		(layer "In4.Cu")
		(net "P5E_CPU0_G3_TX_DP<13>")
	)
	(segment
		(start 363.104938 -221.38767)
		(end 363.099858 -221.39275)
		(width 0.1143)
		(layer "In4.Cu")
		(net "P5E_CPU0_G3_TX_DP<13>")
	)
	(segment
		(start 363.329474 -223.770698)
		(end 363.341412 -223.780096)
		(width 0.1143)
		(layer "In4.Cu")
		(net "P5E_CPU0_G3_TX_DP<13>")
	)
	(segment
		(start 362.624116 -232.25125)
		(end 362.70692 -232.334054)
		(width 0.1143)
		(layer "In4.Cu")
		(net "P5E_CPU0_G3_TX_DP<13>")
	)
	(segment
		(start 362.37926 -227.94341)
		(end 362.378498 -227.943918)
		(width 0.1143)
		(layer "In4.Cu")
		(net "P5E_CPU0_G3_TX_DP<13>")
	)
	(segment
		(start 363.328712 -223.07804)
		(end 363.254544 -223.120966)
		(width 0.1143)
		(layer "In4.Cu")
		(net "P5E_CPU0_G3_TX_DP<13>")
	)
	(segment
		(start 363.328712 -222.150432)
		(end 363.339634 -222.158814)
		(width 0.1143)
		(layer "In4.Cu")
		(net "P5E_CPU0_G3_TX_DP<13>")
	)
	(segment
		(start 362.349542 -227.960682)
		(end 362.34878 -227.96119)
		(width 0.1143)
		(layer "In4.Cu")
		(net "P5E_CPU0_G3_TX_DP<13>")
	)
	(segment
		(start 363.287056 -222.126302)
		(end 363.287818 -222.12681)
		(width 0.1143)
		(layer "In4.Cu")
		(net "P5E_CPU0_G3_TX_DP<13>")
	)
	(segment
		(start 320.34861 -176.903888)
		(end 321.30238 -177.541428)
		(width 0.14224)
		(layer "In4.Cu")
		(net "P5E_CPU0_G3_TX_DP<13>")
	)
	(segment
		(start 362.37926 -230.244904)
		(end 362.380022 -230.245412)
		(width 0.1143)
		(layer "In4.Cu")
		(net "P5E_CPU0_G3_TX_DP<13>")
	)
	(segment
		(start 362.85678 -225.50882)
		(end 362.787184 -225.54946)
		(width 0.1143)
		(layer "In4.Cu")
		(net "P5E_CPU0_G3_TX_DP<13>")
	)
	(segment
		(start 362.34878 -230.227124)
		(end 362.35259 -230.22941)
		(width 0.1143)
		(layer "In4.Cu")
		(net "P5E_CPU0_G3_TX_DP<13>")
	)
	(segment
		(start 308.267354 -156.294074)
		(end 307.909976 -158.090616)
		(width 0.14224)
		(layer "In4.Cu")
		(net "P5E_CPU0_G3_TX_DP<13>")
	)
	(arc
		(start 363.100112 -221.80423)
		(mid 363.10307 -221.851729)
		(end 363.11205 -221.898464)
		(width 0.1143)
		(layer "In4.Cu")
		(net "P5E_CPU0_G3_TX_DP<13>")
	)
	(arc
		(start 362.346494 -226.342194)
		(mid 362.161169 -226.664376)
		(end 362.346748 -226.986338)
		(width 0.1143)
		(layer "In4.Cu")
		(net "P5E_CPU0_G3_TX_DP<13>")
	)
	(arc
		(start 363.254544 -223.120966)
		(mid 363.099967 -223.425054)
		(end 363.255814 -223.728534)
		(width 0.1143)
		(layer "In4.Cu")
		(net "P5E_CPU0_G3_TX_DP<13>")
	)
	(arc
		(start 363.166152 -222.016574)
		(mid 363.207135 -222.066436)
		(end 363.256068 -222.108522)
		(width 0.1143)
		(layer "In4.Cu")
		(net "P5E_CPU0_G3_TX_DP<13>")
	)
	(arc
		(start 362.630212 -225.85426)
		(mid 362.565697 -226.116479)
		(end 362.38688 -226.318826)
		(width 0.1143)
		(layer "In4.Cu")
		(net "P5E_CPU0_G3_TX_DP<13>")
	)
	(arc
		(start 363.341412 -223.780096)
		(mid 363.50461 -223.97818)
		(end 363.570012 -224.226374)
		(width 0.1143)
		(layer "In4.Cu")
		(net "P5E_CPU0_G3_TX_DP<13>")
	)
	(arc
		(start 362.787184 -225.54946)
		(mid 362.671757 -225.682836)
		(end 362.630212 -225.85426)
		(width 0.1143)
		(layer "In4.Cu")
		(net "P5E_CPU0_G3_TX_DP<13>")
	)
	(arc
		(start 362.386118 -231.86898)
		(mid 362.538448 -232.025765)
		(end 362.619798 -232.228644)
		(width 0.1143)
		(layer "In4.Cu")
		(net "P5E_CPU0_G3_TX_DP<13>")
	)
	(arc
		(start 362.38688 -227.009706)
		(mid 362.630207 -227.474272)
		(end 362.38688 -227.938838)
		(width 0.1143)
		(layer "In4.Cu")
		(net "P5E_CPU0_G3_TX_DP<13>")
	)
	(arc
		(start 363.100112 -225.044254)
		(mid 363.035597 -225.306473)
		(end 362.85678 -225.50882)
		(width 0.1143)
		(layer "In4.Cu")
		(net "P5E_CPU0_G3_TX_DP<13>")
	)
	(arc
		(start 363.339634 -222.158814)
		(mid 363.571965 -222.614236)
		(end 363.339634 -223.069658)
		(width 0.1143)
		(layer "In4.Cu")
		(net "P5E_CPU0_G3_TX_DP<13>")
	)
	(arc
		(start 363.570012 -224.226374)
		(mid 363.570027 -224.230311)
		(end 363.570012 -224.234248)
		(width 0.1143)
		(layer "In4.Cu")
		(net "P5E_CPU0_G3_TX_DP<13>")
	)
	(arc
		(start 362.314236 -229.601268)
		(mid 362.200829 -229.734157)
		(end 362.160058 -229.904036)
		(width 0.1143)
		(layer "In4.Cu")
		(net "P5E_CPU0_G3_TX_DP<13>")
	)
	(arc
		(start 362.160058 -229.904036)
		(mid 362.209881 -230.089766)
		(end 362.345986 -230.2256)
		(width 0.1143)
		(layer "In4.Cu")
		(net "P5E_CPU0_G3_TX_DP<13>")
	)
	(arc
		(start 362.38688 -226.318826)
		(mid 362.386499 -226.31908)
		(end 362.386118 -226.319334)
		(width 0.1143)
		(layer "In4.Cu")
		(net "P5E_CPU0_G3_TX_DP<13>")
	)
	(arc
		(start 362.38434 -230.247952)
		(mid 362.630223 -230.711372)
		(end 362.389166 -231.177338)
		(width 0.1143)
		(layer "In4.Cu")
		(net "P5E_CPU0_G3_TX_DP<13>")
	)
	(arc
		(start 362.38688 -228.629718)
		(mid 362.630207 -229.094284)
		(end 362.38688 -229.55885)
		(width 0.1143)
		(layer "In4.Cu")
		(net "P5E_CPU0_G3_TX_DP<13>")
	)
	(arc
		(start 363.11205 -221.898464)
		(mid 363.133928 -221.95989)
		(end 363.166152 -222.016574)
		(width 0.1143)
		(layer "In4.Cu")
		(net "P5E_CPU0_G3_TX_DP<13>")
	)
	(arc
		(start 363.570012 -224.234248)
		(mid 363.495032 -224.514732)
		(end 363.290104 -224.720404)
		(width 0.1143)
		(layer "In4.Cu")
		(net "P5E_CPU0_G3_TX_DP<13>")
	)
	(arc
		(start 362.336334 -227.968302)
		(mid 362.161384 -228.284278)
		(end 362.336334 -228.600254)
		(width 0.1143)
		(layer "In4.Cu")
		(net "P5E_CPU0_G3_TX_DP<13>")
	)
	(arc
		(start 362.347256 -231.201468)
		(mid 362.161618 -231.524048)
		(end 362.347256 -231.846628)
		(width 0.1143)
		(layer "In4.Cu")
		(net "P5E_CPU0_G3_TX_DP<13>")
	)
	(arc
		(start 362.62056 -232.228644)
		(mid 362.62245 -232.239929)
		(end 362.624116 -232.25125)
		(width 0.1143)
		(layer "In4.Cu")
		(net "P5E_CPU0_G3_TX_DP<13>")
	)
	(arc
		(start 362.38688 -227.938838)
		(mid 362.386499 -227.939092)
		(end 362.386118 -227.939346)
		(width 0.1143)
		(layer "In4.Cu")
		(net "P5E_CPU0_G3_TX_DP<13>")
	)
	(arc
		(start 363.25429 -224.741232)
		(mid 363.140885 -224.873127)
		(end 363.100112 -225.042222)
		(width 0.1143)
		(layer "In4.Cu")
		(net "P5E_CPU0_G3_TX_DP<13>")
	)
	(segment
		(start 399.008854 -18.185892)
		(end 399.008854 -18.86585)
		(width 0.12954)
		(layer "F.Cu")
		(net "P5E_CPU0_G3_TX_DP<12>")
	)
	(segment
		(start 399.008854 -18.86585)
		(end 399.279364 -19.13636)
		(width 0.12954)
		(layer "F.Cu")
		(net "P5E_CPU0_G3_TX_DP<12>")
	)
	(segment
		(start 364.888018 -235.03001)
		(end 365.35487 -234.764072)
		(width 0.12954)
		(layer "F.Cu")
		(net "P5E_CPU0_G3_TX_DP<12>")
	)
	(segment
		(start 399.303748 -17.890998)
		(end 399.008854 -18.185892)
		(width 0.12954)
		(layer "F.Cu")
		(net "P5E_CPU0_G3_TX_DP<12>")
	)
	(segment
		(start 363.287818 -228.606858)
		(end 363.319314 -228.625146)
		(width 0.1143)
		(layer "In4.Cu")
		(net "P5E_CPU0_G3_TX_DP<12>")
	)
	(segment
		(start 315.615828 -172.979334)
		(end 320.839338 -176.110138)
		(width 0.14224)
		(layer "In4.Cu")
		(net "P5E_CPU0_G3_TX_DP<12>")
	)
	(segment
		(start 364.228634 -223.74733)
		(end 364.266734 -223.769682)
		(width 0.1143)
		(layer "In4.Cu")
		(net "P5E_CPU0_G3_TX_DP<12>")
	)
	(segment
		(start 363.326934 -227.938838)
		(end 363.297724 -227.955856)
		(width 0.1143)
		(layer "In4.Cu")
		(net "P5E_CPU0_G3_TX_DP<12>")
	)
	(segment
		(start 311.367678 -168.730168)
		(end 315.615828 -172.979334)
		(width 0.14224)
		(layer "In4.Cu")
		(net "P5E_CPU0_G3_TX_DP<12>")
	)
	(segment
		(start 364.22711 -233.466132)
		(end 364.234222 -233.470704)
		(width 0.1143)
		(layer "In4.Cu")
		(net "P5E_CPU0_G3_TX_DP<12>")
	)
	(segment
		(start 363.256068 -228.58857)
		(end 363.285786 -228.605588)
		(width 0.1143)
		(layer "In4.Cu")
		(net "P5E_CPU0_G3_TX_DP<12>")
	)
	(segment
		(start 364.175802 -223.714056)
		(end 364.195868 -223.728534)
		(width 0.1143)
		(layer "In4.Cu")
		(net "P5E_CPU0_G3_TX_DP<12>")
	)
	(segment
		(start 363.293152 -230.229664)
		(end 363.293914 -230.230172)
		(width 0.1143)
		(layer "In4.Cu")
		(net "P5E_CPU0_G3_TX_DP<12>")
	)
	(segment
		(start 363.280706 -226.34575)
		(end 363.256068 -226.359974)
		(width 0.1143)
		(layer "In4.Cu")
		(net "P5E_CPU0_G3_TX_DP<12>")
	)
	(segment
		(start 363.287818 -226.986846)
		(end 363.319314 -227.005134)
		(width 0.1143)
		(layer "In4.Cu")
		(net "P5E_CPU0_G3_TX_DP<12>")
	)
	(segment
		(start 364.22584 -233.46537)
		(end 364.22711 -233.466132)
		(width 0.1143)
		(layer "In4.Cu")
		(net "P5E_CPU0_G3_TX_DP<12>")
	)
	(segment
		(start 363.293914 -230.230172)
		(end 363.29493 -230.23068)
		(width 0.1143)
		(layer "In4.Cu")
		(net "P5E_CPU0_G3_TX_DP<12>")
	)
	(segment
		(start 363.319314 -230.244904)
		(end 363.324394 -230.247952)
		(width 0.1143)
		(layer "In4.Cu")
		(net "P5E_CPU0_G3_TX_DP<12>")
	)
	(segment
		(start 363.287818 -230.226616)
		(end 363.288834 -230.227124)
		(width 0.1143)
		(layer "In4.Cu")
		(net "P5E_CPU0_G3_TX_DP<12>")
	)
	(segment
		(start 363.79404 -225.510598)
		(end 363.757718 -225.53168)
		(width 0.1143)
		(layer "In4.Cu")
		(net "P5E_CPU0_G3_TX_DP<12>")
	)
	(segment
		(start 363.287056 -231.84612)
		(end 363.287818 -231.846628)
		(width 0.1143)
		(layer "In4.Cu")
		(net "P5E_CPU0_G3_TX_DP<12>")
	)
	(segment
		(start 363.2835 -226.344226)
		(end 363.282484 -226.344734)
		(width 0.1143)
		(layer "In4.Cu")
		(net "P5E_CPU0_G3_TX_DP<12>")
	)
	(segment
		(start 363.284262 -230.224584)
		(end 363.285786 -230.225346)
		(width 0.1143)
		(layer "In4.Cu")
		(net "P5E_CPU0_G3_TX_DP<12>")
	)
	(segment
		(start 363.297724 -226.335844)
		(end 363.2962 -226.33686)
		(width 0.1143)
		(layer "In4.Cu")
		(net "P5E_CPU0_G3_TX_DP<12>")
	)
	(segment
		(start 363.288834 -227.96119)
		(end 363.287818 -227.961698)
		(width 0.1143)
		(layer "In4.Cu")
		(net "P5E_CPU0_G3_TX_DP<12>")
	)
	(segment
		(start 363.2962 -226.33686)
		(end 363.291374 -226.339654)
		(width 0.1143)
		(layer "In4.Cu")
		(net "P5E_CPU0_G3_TX_DP<12>")
	)
	(segment
		(start 363.285786 -230.225346)
		(end 363.287056 -230.226108)
		(width 0.1143)
		(layer "In4.Cu")
		(net "P5E_CPU0_G3_TX_DP<12>")
	)
	(segment
		(start 364.195868 -223.11995)
		(end 364.175802 -223.134428)
		(width 0.1143)
		(layer "In4.Cu")
		(net "P5E_CPU0_G3_TX_DP<12>")
	)
	(segment
		(start 364.223046 -223.744028)
		(end 364.223808 -223.744536)
		(width 0.1143)
		(layer "In4.Cu")
		(net "P5E_CPU0_G3_TX_DP<12>")
	)
	(segment
		(start 363.282484 -227.964746)
		(end 363.281722 -227.965254)
		(width 0.1143)
		(layer "In4.Cu")
		(net "P5E_CPU0_G3_TX_DP<12>")
	)
	(segment
		(start 363.290358 -226.340162)
		(end 363.288834 -226.341178)
		(width 0.1143)
		(layer "In4.Cu")
		(net "P5E_CPU0_G3_TX_DP<12>")
	)
	(segment
		(start 363.287056 -227.962206)
		(end 363.284262 -227.96373)
		(width 0.1143)
		(layer "In4.Cu")
		(net "P5E_CPU0_G3_TX_DP<12>")
	)
	(segment
		(start 363.300518 -230.233982)
		(end 363.302042 -230.234998)
		(width 0.1143)
		(layer "In4.Cu")
		(net "P5E_CPU0_G3_TX_DP<12>")
	)
	(segment
		(start 364.095284 -221.083124)
		(end 364.049564 -221.128844)
		(width 0.1143)
		(layer "In4.Cu")
		(net "P5E_CPU0_G3_TX_DP<12>")
	)
	(segment
		(start 364.049564 -221.128844)
		(end 364.049564 -221.38767)
		(width 0.1143)
		(layer "In4.Cu")
		(net "P5E_CPU0_G3_TX_DP<12>")
	)
	(segment
		(start 364.049564 -221.38767)
		(end 364.040166 -221.397068)
		(width 0.1143)
		(layer "In4.Cu")
		(net "P5E_CPU0_G3_TX_DP<12>")
	)
	(segment
		(start 363.256068 -231.82834)
		(end 363.285786 -231.845358)
		(width 0.1143)
		(layer "In4.Cu")
		(net "P5E_CPU0_G3_TX_DP<12>")
	)
	(segment
		(start 363.256068 -226.968558)
		(end 363.285786 -226.985576)
		(width 0.1143)
		(layer "In4.Cu")
		(net "P5E_CPU0_G3_TX_DP<12>")
	)
	(segment
		(start 363.297978 -230.232458)
		(end 363.299502 -230.233474)
		(width 0.1143)
		(layer "In4.Cu")
		(net "P5E_CPU0_G3_TX_DP<12>")
	)
	(segment
		(start 320.839338 -176.110138)
		(end 321.864736 -176.795684)
		(width 0.14224)
		(layer "In4.Cu")
		(net "P5E_CPU0_G3_TX_DP<12>")
	)
	(segment
		(start 363.290866 -230.228394)
		(end 363.291882 -230.228902)
		(width 0.1143)
		(layer "In4.Cu")
		(net "P5E_CPU0_G3_TX_DP<12>")
	)
	(segment
		(start 364.510066 -224.234248)
		(end 364.509812 -224.234248)
		(width 0.1143)
		(layer "In4.Cu")
		(net "P5E_CPU0_G3_TX_DP<12>")
	)
	(segment
		(start 363.319314 -227.005134)
		(end 363.320076 -227.005642)
		(width 0.1143)
		(layer "In4.Cu")
		(net "P5E_CPU0_G3_TX_DP<12>")
	)
	(segment
		(start 364.265464 -223.079818)
		(end 364.25886 -223.083628)
		(width 0.1143)
		(layer "In4.Cu")
		(net "P5E_CPU0_G3_TX_DP<12>")
	)
	(segment
		(start 363.326934 -229.55885)
		(end 363.25429 -229.601268)
		(width 0.1143)
		(layer "In4.Cu")
		(net "P5E_CPU0_G3_TX_DP<12>")
	)
	(segment
		(start 363.320076 -227.005642)
		(end 363.326934 -227.009706)
		(width 0.1143)
		(layer "In4.Cu")
		(net "P5E_CPU0_G3_TX_DP<12>")
	)
	(segment
		(start 364.040166 -221.397068)
		(end 364.040166 -221.804484)
		(width 0.1143)
		(layer "In4.Cu")
		(net "P5E_CPU0_G3_TX_DP<12>")
	)
	(segment
		(start 364.258098 -223.084136)
		(end 364.195868 -223.11995)
		(width 0.1143)
		(layer "In4.Cu")
		(net "P5E_CPU0_G3_TX_DP<12>")
	)
	(segment
		(start 317.957454 -129.963418)
		(end 313.4995 -141.563852)
		(width 0.14224)
		(layer "In4.Cu")
		(net "P5E_CPU0_G3_TX_DP<12>")
	)
	(segment
		(start 321.864736 -176.795684)
		(end 359.57129 -207.700372)
		(width 0.14224)
		(layer "In4.Cu")
		(net "P5E_CPU0_G3_TX_DP<12>")
	)
	(segment
		(start 313.4995 -141.563852)
		(end 309.174896 -156.512006)
		(width 0.14224)
		(layer "In4.Cu")
		(net "P5E_CPU0_G3_TX_DP<12>")
	)
	(segment
		(start 364.227618 -223.746822)
		(end 364.228634 -223.74733)
		(width 0.1143)
		(layer "In4.Cu")
		(net "P5E_CPU0_G3_TX_DP<12>")
	)
	(segment
		(start 364.195868 -223.728534)
		(end 364.223046 -223.744028)
		(width 0.1143)
		(layer "In4.Cu")
		(net "P5E_CPU0_G3_TX_DP<12>")
	)
	(segment
		(start 359.57129 -207.700372)
		(end 364.095284 -215.31961)
		(width 0.14224)
		(layer "In4.Cu")
		(net "P5E_CPU0_G3_TX_DP<12>")
	)
	(segment
		(start 364.095284 -221.054676)
		(end 364.095284 -221.083124)
		(width 0.1143)
		(layer "In4.Cu")
		(net "P5E_CPU0_G3_TX_DP<12>")
	)
	(segment
		(start 363.285786 -226.985576)
		(end 363.287056 -226.986338)
		(width 0.1143)
		(layer "In4.Cu")
		(net "P5E_CPU0_G3_TX_DP<12>")
	)
	(segment
		(start 398.988534 -20.43811)
		(end 322.836794 -121.180098)
		(width 0.14224)
		(layer "In4.Cu")
		(net "P5E_CPU0_G3_TX_DP<12>")
	)
	(segment
		(start 363.297724 -227.955856)
		(end 363.2962 -227.956872)
		(width 0.1143)
		(layer "In4.Cu")
		(net "P5E_CPU0_G3_TX_DP<12>")
	)
	(segment
		(start 363.2962 -227.956872)
		(end 363.291374 -227.959666)
		(width 0.1143)
		(layer "In4.Cu")
		(net "P5E_CPU0_G3_TX_DP<12>")
	)
	(segment
		(start 363.285786 -231.845358)
		(end 363.287056 -231.84612)
		(width 0.1143)
		(layer "In4.Cu")
		(net "P5E_CPU0_G3_TX_DP<12>")
	)
	(segment
		(start 308.842156 -158.184342)
		(end 308.842156 -162.631882)
		(width 0.14224)
		(layer "In4.Cu")
		(net "P5E_CPU0_G3_TX_DP<12>")
	)
	(segment
		(start 363.288834 -226.341178)
		(end 363.287818 -226.341686)
		(width 0.1143)
		(layer "In4.Cu")
		(net "P5E_CPU0_G3_TX_DP<12>")
	)
	(segment
		(start 398.988534 -19.42719)
		(end 398.988534 -20.43811)
		(width 0.14224)
		(layer "In4.Cu")
		(net "P5E_CPU0_G3_TX_DP<12>")
	)
	(segment
		(start 364.226856 -223.746314)
		(end 364.227618 -223.746822)
		(width 0.1143)
		(layer "In4.Cu")
		(net "P5E_CPU0_G3_TX_DP<12>")
	)
	(segment
		(start 309.174896 -156.512006)
		(end 308.842156 -158.184342)
		(width 0.14224)
		(layer "In4.Cu")
		(net "P5E_CPU0_G3_TX_DP<12>")
	)
	(segment
		(start 363.319314 -228.625146)
		(end 363.320076 -228.625654)
		(width 0.1143)
		(layer "In4.Cu")
		(net "P5E_CPU0_G3_TX_DP<12>")
	)
	(segment
		(start 363.318552 -230.244396)
		(end 363.319314 -230.244904)
		(width 0.1143)
		(layer "In4.Cu")
		(net "P5E_CPU0_G3_TX_DP<12>")
	)
	(segment
		(start 363.320076 -228.625654)
		(end 363.326934 -228.629718)
		(width 0.1143)
		(layer "In4.Cu")
		(net "P5E_CPU0_G3_TX_DP<12>")
	)
	(segment
		(start 363.285786 -228.605588)
		(end 363.287056 -228.60635)
		(width 0.1143)
		(layer "In4.Cu")
		(net "P5E_CPU0_G3_TX_DP<12>")
	)
	(segment
		(start 364.040166 -221.804484)
		(end 364.04042 -221.80423)
		(width 0.1143)
		(layer "In4.Cu")
		(net "P5E_CPU0_G3_TX_DP<12>")
	)
	(segment
		(start 363.287818 -226.341686)
		(end 363.287056 -226.342194)
		(width 0.1143)
		(layer "In4.Cu")
		(net "P5E_CPU0_G3_TX_DP<12>")
	)
	(segment
		(start 363.256068 -230.208328)
		(end 363.284262 -230.224584)
		(width 0.1143)
		(layer "In4.Cu")
		(net "P5E_CPU0_G3_TX_DP<12>")
	)
	(segment
		(start 363.280706 -227.965762)
		(end 363.256068 -227.979986)
		(width 0.1143)
		(layer "In4.Cu")
		(net "P5E_CPU0_G3_TX_DP<12>")
	)
	(segment
		(start 363.757718 -225.53168)
		(end 363.727238 -225.54946)
		(width 0.1143)
		(layer "In4.Cu")
		(net "P5E_CPU0_G3_TX_DP<12>")
	)
	(segment
		(start 363.284262 -226.343718)
		(end 363.2835 -226.344226)
		(width 0.1143)
		(layer "In4.Cu")
		(net "P5E_CPU0_G3_TX_DP<12>")
	)
	(segment
		(start 363.281722 -227.965254)
		(end 363.280706 -227.965762)
		(width 0.1143)
		(layer "In4.Cu")
		(net "P5E_CPU0_G3_TX_DP<12>")
	)
	(segment
		(start 363.291882 -230.228902)
		(end 363.293152 -230.229664)
		(width 0.1143)
		(layer "In4.Cu")
		(net "P5E_CPU0_G3_TX_DP<12>")
	)
	(segment
		(start 363.282484 -226.344734)
		(end 363.281722 -226.345242)
		(width 0.1143)
		(layer "In4.Cu")
		(net "P5E_CPU0_G3_TX_DP<12>")
	)
	(segment
		(start 364.25886 -223.083628)
		(end 364.258098 -223.084136)
		(width 0.1143)
		(layer "In4.Cu")
		(net "P5E_CPU0_G3_TX_DP<12>")
	)
	(segment
		(start 364.236762 -233.472228)
		(end 364.23854 -233.473498)
		(width 0.1143)
		(layer "In4.Cu")
		(net "P5E_CPU0_G3_TX_DP<12>")
	)
	(segment
		(start 363.287056 -228.60635)
		(end 363.287818 -228.606858)
		(width 0.1143)
		(layer "In4.Cu")
		(net "P5E_CPU0_G3_TX_DP<12>")
	)
	(segment
		(start 364.234222 -233.470704)
		(end 364.236762 -233.472228)
		(width 0.1143)
		(layer "In4.Cu")
		(net "P5E_CPU0_G3_TX_DP<12>")
	)
	(segment
		(start 364.26648 -224.698814)
		(end 364.196884 -224.739454)
		(width 0.1143)
		(layer "In4.Cu")
		(net "P5E_CPU0_G3_TX_DP<12>")
	)
	(segment
		(start 364.671102 -234.261152)
		(end 364.736888 -234.299252)
		(width 0.1143)
		(layer "In4.Cu")
		(net "P5E_CPU0_G3_TX_DP<12>")
	)
	(segment
		(start 363.291374 -226.339654)
		(end 363.290358 -226.340162)
		(width 0.1143)
		(layer "In4.Cu")
		(net "P5E_CPU0_G3_TX_DP<12>")
	)
	(segment
		(start 363.326934 -231.178862)
		(end 363.25429 -231.22128)
		(width 0.1143)
		(layer "In4.Cu")
		(net "P5E_CPU0_G3_TX_DP<12>")
	)
	(segment
		(start 363.281722 -226.345242)
		(end 363.280706 -226.34575)
		(width 0.1143)
		(layer "In4.Cu")
		(net "P5E_CPU0_G3_TX_DP<12>")
	)
	(segment
		(start 363.290104 -230.227886)
		(end 363.290866 -230.228394)
		(width 0.1143)
		(layer "In4.Cu")
		(net "P5E_CPU0_G3_TX_DP<12>")
	)
	(segment
		(start 363.287056 -230.226108)
		(end 363.287818 -230.226616)
		(width 0.1143)
		(layer "In4.Cu")
		(net "P5E_CPU0_G3_TX_DP<12>")
	)
	(segment
		(start 363.299502 -230.233474)
		(end 363.300518 -230.233982)
		(width 0.1143)
		(layer "In4.Cu")
		(net "P5E_CPU0_G3_TX_DP<12>")
	)
	(segment
		(start 363.284262 -227.96373)
		(end 363.2835 -227.964238)
		(width 0.1143)
		(layer "In4.Cu")
		(net "P5E_CPU0_G3_TX_DP<12>")
	)
	(segment
		(start 365.056928 -234.764072)
		(end 365.35487 -234.764072)
		(width 0.1143)
		(layer "In4.Cu")
		(net "P5E_CPU0_G3_TX_DP<12>")
	)
	(segment
		(start 364.095284 -215.31961)
		(end 364.095284 -221.054676)
		(width 0.14224)
		(layer "In4.Cu")
		(net "P5E_CPU0_G3_TX_DP<12>")
	)
	(segment
		(start 363.287818 -231.846628)
		(end 363.319314 -231.864916)
		(width 0.1143)
		(layer "In4.Cu")
		(net "P5E_CPU0_G3_TX_DP<12>")
	)
	(segment
		(start 399.279364 -19.13636)
		(end 398.988534 -19.42719)
		(width 0.14224)
		(layer "In4.Cu")
		(net "P5E_CPU0_G3_TX_DP<12>")
	)
	(segment
		(start 363.287056 -226.342194)
		(end 363.284262 -226.343718)
		(width 0.1143)
		(layer "In4.Cu")
		(net "P5E_CPU0_G3_TX_DP<12>")
	)
	(segment
		(start 363.29493 -230.23068)
		(end 363.297978 -230.232458)
		(width 0.1143)
		(layer "In4.Cu")
		(net "P5E_CPU0_G3_TX_DP<12>")
	)
	(segment
		(start 364.236254 -222.144336)
		(end 364.31982 -222.192596)
		(width 0.1143)
		(layer "In4.Cu")
		(net "P5E_CPU0_G3_TX_DP<12>")
	)
	(segment
		(start 363.287056 -226.986338)
		(end 363.287818 -226.986846)
		(width 0.1143)
		(layer "In4.Cu")
		(net "P5E_CPU0_G3_TX_DP<12>")
	)
	(segment
		(start 322.836794 -121.180098)
		(end 317.957454 -129.963418)
		(width 0.14224)
		(layer "In4.Cu")
		(net "P5E_CPU0_G3_TX_DP<12>")
	)
	(segment
		(start 363.727238 -232.638854)
		(end 363.796834 -232.679494)
		(width 0.1143)
		(layer "In4.Cu")
		(net "P5E_CPU0_G3_TX_DP<12>")
	)
	(segment
		(start 364.196122 -233.448352)
		(end 364.22584 -233.46537)
		(width 0.1143)
		(layer "In4.Cu")
		(net "P5E_CPU0_G3_TX_DP<12>")
	)
	(segment
		(start 364.974124 -234.681268)
		(end 365.056928 -234.764072)
		(width 0.1143)
		(layer "In4.Cu")
		(net "P5E_CPU0_G3_TX_DP<12>")
	)
	(segment
		(start 308.842156 -162.631882)
		(end 311.367678 -168.730168)
		(width 0.14224)
		(layer "In4.Cu")
		(net "P5E_CPU0_G3_TX_DP<12>")
	)
	(segment
		(start 363.291374 -227.959666)
		(end 363.290358 -227.960174)
		(width 0.1143)
		(layer "In4.Cu")
		(net "P5E_CPU0_G3_TX_DP<12>")
	)
	(segment
		(start 363.302042 -230.234998)
		(end 363.318552 -230.244396)
		(width 0.1143)
		(layer "In4.Cu")
		(net "P5E_CPU0_G3_TX_DP<12>")
	)
	(segment
		(start 364.223808 -223.744536)
		(end 364.225586 -223.745552)
		(width 0.1143)
		(layer "In4.Cu")
		(net "P5E_CPU0_G3_TX_DP<12>")
	)
	(segment
		(start 364.225586 -223.745552)
		(end 364.226856 -223.746314)
		(width 0.1143)
		(layer "In4.Cu")
		(net "P5E_CPU0_G3_TX_DP<12>")
	)
	(segment
		(start 364.509812 -224.234248)
		(end 364.508288 -224.258886)
		(width 0.1143)
		(layer "In4.Cu")
		(net "P5E_CPU0_G3_TX_DP<12>")
	)
	(segment
		(start 363.290358 -227.960174)
		(end 363.288834 -227.96119)
		(width 0.1143)
		(layer "In4.Cu")
		(net "P5E_CPU0_G3_TX_DP<12>")
	)
	(segment
		(start 363.319314 -231.864916)
		(end 363.320076 -231.865424)
		(width 0.1143)
		(layer "In4.Cu")
		(net "P5E_CPU0_G3_TX_DP<12>")
	)
	(segment
		(start 363.288834 -230.227124)
		(end 363.290104 -230.227886)
		(width 0.1143)
		(layer "In4.Cu")
		(net "P5E_CPU0_G3_TX_DP<12>")
	)
	(segment
		(start 363.326934 -226.318826)
		(end 363.297724 -226.335844)
		(width 0.1143)
		(layer "In4.Cu")
		(net "P5E_CPU0_G3_TX_DP<12>")
	)
	(segment
		(start 363.287818 -227.961698)
		(end 363.287056 -227.962206)
		(width 0.1143)
		(layer "In4.Cu")
		(net "P5E_CPU0_G3_TX_DP<12>")
	)
	(segment
		(start 363.320076 -231.865424)
		(end 363.326934 -231.869488)
		(width 0.1143)
		(layer "In4.Cu")
		(net "P5E_CPU0_G3_TX_DP<12>")
	)
	(segment
		(start 363.2835 -227.964238)
		(end 363.282484 -227.964746)
		(width 0.1143)
		(layer "In4.Cu")
		(net "P5E_CPU0_G3_TX_DP<12>")
	)
	(arc
		(start 364.51032 -233.950764)
		(mid 364.557211 -234.123312)
		(end 364.671102 -234.261152)
		(width 0.1143)
		(layer "In4.Cu")
		(net "P5E_CPU0_G3_TX_DP<12>")
	)
	(arc
		(start 364.278164 -224.689924)
		(mid 364.272352 -224.694408)
		(end 364.26648 -224.698814)
		(width 0.1143)
		(layer "In4.Cu")
		(net "P5E_CPU0_G3_TX_DP<12>")
	)
	(arc
		(start 364.295944 -224.6757)
		(mid 364.287126 -224.682902)
		(end 364.278164 -224.689924)
		(width 0.1143)
		(layer "In4.Cu")
		(net "P5E_CPU0_G3_TX_DP<12>")
	)
	(arc
		(start 364.507018 -224.26803)
		(mid 364.435857 -224.489661)
		(end 364.295944 -224.6757)
		(width 0.1143)
		(layer "In4.Cu")
		(net "P5E_CPU0_G3_TX_DP<12>")
	)
	(arc
		(start 363.570266 -225.85426)
		(mid 363.505751 -226.116479)
		(end 363.326934 -226.318826)
		(width 0.1143)
		(layer "In4.Cu")
		(net "P5E_CPU0_G3_TX_DP<12>")
	)
	(arc
		(start 364.039912 -225.044254)
		(mid 363.974676 -225.307845)
		(end 363.79404 -225.510598)
		(width 0.1143)
		(layer "In4.Cu")
		(net "P5E_CPU0_G3_TX_DP<12>")
	)
	(arc
		(start 364.279434 -223.069912)
		(mid 364.272487 -223.074918)
		(end 364.265464 -223.079818)
		(width 0.1143)
		(layer "In4.Cu")
		(net "P5E_CPU0_G3_TX_DP<12>")
	)
	(arc
		(start 364.969806 -234.658662)
		(mid 364.972081 -234.669943)
		(end 364.974124 -234.681268)
		(width 0.1143)
		(layer "In4.Cu")
		(net "P5E_CPU0_G3_TX_DP<12>")
	)
	(arc
		(start 364.04042 -221.80423)
		(mid 364.092808 -222.000509)
		(end 364.236254 -222.144336)
		(width 0.1143)
		(layer "In4.Cu")
		(net "P5E_CPU0_G3_TX_DP<12>")
	)
	(arc
		(start 363.256068 -226.359974)
		(mid 363.10014 -226.664266)
		(end 363.256068 -226.968558)
		(width 0.1143)
		(layer "In4.Cu")
		(net "P5E_CPU0_G3_TX_DP<12>")
	)
	(arc
		(start 363.326934 -231.869488)
		(mid 363.505747 -232.071838)
		(end 363.570266 -232.334054)
		(width 0.1143)
		(layer "In4.Cu")
		(net "P5E_CPU0_G3_TX_DP<12>")
	)
	(arc
		(start 364.23854 -233.473498)
		(mid 364.430918 -233.679962)
		(end 364.51032 -233.950764)
		(width 0.1143)
		(layer "In4.Cu")
		(net "P5E_CPU0_G3_TX_DP<12>")
	)
	(arc
		(start 363.100112 -229.904036)
		(mid 363.141367 -230.075007)
		(end 363.256068 -230.208328)
		(width 0.1143)
		(layer "In4.Cu")
		(net "P5E_CPU0_G3_TX_DP<12>")
	)
	(arc
		(start 363.570266 -230.714296)
		(mid 363.505751 -230.976515)
		(end 363.326934 -231.178862)
		(width 0.1143)
		(layer "In4.Cu")
		(net "P5E_CPU0_G3_TX_DP<12>")
	)
	(arc
		(start 363.326934 -227.009706)
		(mid 363.570261 -227.474272)
		(end 363.326934 -227.938838)
		(width 0.1143)
		(layer "In4.Cu")
		(net "P5E_CPU0_G3_TX_DP<12>")
	)
	(arc
		(start 363.256068 -227.979986)
		(mid 363.10014 -228.284278)
		(end 363.256068 -228.58857)
		(width 0.1143)
		(layer "In4.Cu")
		(net "P5E_CPU0_G3_TX_DP<12>")
	)
	(arc
		(start 364.175802 -223.134428)
		(mid 364.027295 -223.424242)
		(end 364.175802 -223.714056)
		(width 0.1143)
		(layer "In4.Cu")
		(net "P5E_CPU0_G3_TX_DP<12>")
	)
	(arc
		(start 363.324394 -230.247952)
		(mid 363.505046 -230.450697)
		(end 363.570266 -230.714296)
		(width 0.1143)
		(layer "In4.Cu")
		(net "P5E_CPU0_G3_TX_DP<12>")
	)
	(arc
		(start 363.570266 -232.334054)
		(mid 363.611815 -232.505476)
		(end 363.727238 -232.638854)
		(width 0.1143)
		(layer "In4.Cu")
		(net "P5E_CPU0_G3_TX_DP<12>")
	)
	(arc
		(start 363.25429 -229.601268)
		(mid 363.140883 -229.734157)
		(end 363.100112 -229.904036)
		(width 0.1143)
		(layer "In4.Cu")
		(net "P5E_CPU0_G3_TX_DP<12>")
	)
	(arc
		(start 363.25429 -231.22128)
		(mid 363.140883 -231.354169)
		(end 363.100112 -231.524048)
		(width 0.1143)
		(layer "In4.Cu")
		(net "P5E_CPU0_G3_TX_DP<12>")
	)
	(arc
		(start 364.266734 -223.769682)
		(mid 364.445547 -223.972032)
		(end 364.510066 -224.234248)
		(width 0.1143)
		(layer "In4.Cu")
		(net "P5E_CPU0_G3_TX_DP<12>")
	)
	(arc
		(start 363.326934 -228.629718)
		(mid 363.570261 -229.094284)
		(end 363.326934 -229.55885)
		(width 0.1143)
		(layer "In4.Cu")
		(net "P5E_CPU0_G3_TX_DP<12>")
	)
	(arc
		(start 364.040166 -233.14406)
		(mid 364.081421 -233.315031)
		(end 364.196122 -233.448352)
		(width 0.1143)
		(layer "In4.Cu")
		(net "P5E_CPU0_G3_TX_DP<12>")
	)
	(arc
		(start 364.34014 -222.212408)
		(mid 364.503012 -222.654804)
		(end 364.279434 -223.069912)
		(width 0.1143)
		(layer "In4.Cu")
		(net "P5E_CPU0_G3_TX_DP<12>")
	)
	(arc
		(start 364.508288 -224.258886)
		(mid 364.507668 -224.26346)
		(end 364.507018 -224.26803)
		(width 0.1143)
		(layer "In4.Cu")
		(net "P5E_CPU0_G3_TX_DP<12>")
	)
	(arc
		(start 364.736888 -234.299252)
		(mid 364.888724 -234.456037)
		(end 364.969806 -234.658662)
		(width 0.1143)
		(layer "In4.Cu")
		(net "P5E_CPU0_G3_TX_DP<12>")
	)
	(arc
		(start 363.727238 -225.54946)
		(mid 363.611811 -225.682836)
		(end 363.570266 -225.85426)
		(width 0.1143)
		(layer "In4.Cu")
		(net "P5E_CPU0_G3_TX_DP<12>")
	)
	(arc
		(start 364.31982 -222.192596)
		(mid 364.330101 -222.202378)
		(end 364.34014 -222.212408)
		(width 0.1143)
		(layer "In4.Cu")
		(net "P5E_CPU0_G3_TX_DP<12>")
	)
	(arc
		(start 363.100112 -231.524048)
		(mid 363.141367 -231.695019)
		(end 363.256068 -231.82834)
		(width 0.1143)
		(layer "In4.Cu")
		(net "P5E_CPU0_G3_TX_DP<12>")
	)
	(arc
		(start 363.796834 -232.679494)
		(mid 363.975647 -232.881844)
		(end 364.040166 -233.14406)
		(width 0.1143)
		(layer "In4.Cu")
		(net "P5E_CPU0_G3_TX_DP<12>")
	)
	(arc
		(start 364.196884 -224.739454)
		(mid 364.081457 -224.87283)
		(end 364.039912 -225.044254)
		(width 0.1143)
		(layer "In4.Cu")
		(net "P5E_CPU0_G3_TX_DP<12>")
	)
	(segment
		(start 364.888018 -231.789986)
		(end 365.35487 -231.524048)
		(width 0.12954)
		(layer "F.Cu")
		(net "P5E_CPU0_G3_TX_DP<11>")
	)
	(segment
		(start 402.097748 -16.366998)
		(end 401.802854 -16.661892)
		(width 0.12954)
		(layer "F.Cu")
		(net "P5E_CPU0_G3_TX_DP<11>")
	)
	(segment
		(start 401.802854 -17.34185)
		(end 402.073364 -17.61236)
		(width 0.12954)
		(layer "F.Cu")
		(net "P5E_CPU0_G3_TX_DP<11>")
	)
	(segment
		(start 401.802854 -16.661892)
		(end 401.802854 -17.34185)
		(width 0.12954)
		(layer "F.Cu")
		(net "P5E_CPU0_G3_TX_DP<11>")
	)
	(segment
		(start 310.082438 -156.730192)
		(end 309.87365 -157.779212)
		(width 0.14224)
		(layer "In4.Cu")
		(net "P5E_CPU0_G3_TX_DP<11>")
	)
	(segment
		(start 365.137192 -223.729042)
		(end 365.206788 -223.769682)
		(width 0.1143)
		(layer "In4.Cu")
		(net "P5E_CPU0_G3_TX_DP<11>")
	)
	(segment
		(start 365.136176 -222.108522)
		(end 365.160306 -222.122492)
		(width 0.1143)
		(layer "In4.Cu")
		(net "P5E_CPU0_G3_TX_DP<11>")
	)
	(segment
		(start 364.700312 -225.530156)
		(end 364.698788 -225.531172)
		(width 0.1143)
		(layer "In4.Cu")
		(net "P5E_CPU0_G3_TX_DP<11>")
	)
	(segment
		(start 365.161322 -222.123)
		(end 365.162084 -222.123508)
		(width 0.1143)
		(layer "In4.Cu")
		(net "P5E_CPU0_G3_TX_DP<11>")
	)
	(segment
		(start 364.979966 -221.804484)
		(end 364.98022 -221.80423)
		(width 0.1143)
		(layer "In4.Cu")
		(net "P5E_CPU0_G3_TX_DP<11>")
	)
	(segment
		(start 312.058812 -167.962326)
		(end 316.54369 -172.448474)
		(width 0.14224)
		(layer "In4.Cu")
		(net "P5E_CPU0_G3_TX_DP<11>")
	)
	(segment
		(start 309.87365 -157.779212)
		(end 309.87365 -162.685984)
		(width 0.14224)
		(layer "In4.Cu")
		(net "P5E_CPU0_G3_TX_DP<11>")
	)
	(segment
		(start 364.664244 -231.017064)
		(end 364.736888 -231.059482)
		(width 0.1143)
		(layer "In4.Cu")
		(net "P5E_CPU0_G3_TX_DP<11>")
	)
	(segment
		(start 365.163608 -222.12427)
		(end 365.16437 -222.124778)
		(width 0.1143)
		(layer "In4.Cu")
		(net "P5E_CPU0_G3_TX_DP<11>")
	)
	(segment
		(start 365.168942 -222.127318)
		(end 365.207042 -222.14967)
		(width 0.1143)
		(layer "In4.Cu")
		(net "P5E_CPU0_G3_TX_DP<11>")
	)
	(segment
		(start 365.206788 -224.698814)
		(end 365.137192 -224.739454)
		(width 0.1143)
		(layer "In4.Cu")
		(net "P5E_CPU0_G3_TX_DP<11>")
	)
	(segment
		(start 365.162084 -222.123508)
		(end 365.163608 -222.12427)
		(width 0.1143)
		(layer "In4.Cu")
		(net "P5E_CPU0_G3_TX_DP<11>")
	)
	(segment
		(start 401.782534 -17.90319)
		(end 401.782534 -20.547584)
		(width 0.14224)
		(layer "In4.Cu")
		(net "P5E_CPU0_G3_TX_DP<11>")
	)
	(segment
		(start 365.056928 -231.524048)
		(end 365.35487 -231.524048)
		(width 0.1143)
		(layer "In4.Cu")
		(net "P5E_CPU0_G3_TX_DP<11>")
	)
	(segment
		(start 364.266734 -226.318826)
		(end 364.197138 -226.359466)
		(width 0.1143)
		(layer "In4.Cu")
		(net "P5E_CPU0_G3_TX_DP<11>")
	)
	(segment
		(start 364.197138 -226.969066)
		(end 364.266734 -227.009706)
		(width 0.1143)
		(layer "In4.Cu")
		(net "P5E_CPU0_G3_TX_DP<11>")
	)
	(segment
		(start 365.450374 -222.614236)
		(end 365.45012 -222.614236)
		(width 0.1143)
		(layer "In4.Cu")
		(net "P5E_CPU0_G3_TX_DP<11>")
	)
	(segment
		(start 318.804036 -130.359912)
		(end 314.382404 -141.867128)
		(width 0.14224)
		(layer "In4.Cu")
		(net "P5E_CPU0_G3_TX_DP<11>")
	)
	(segment
		(start 364.979966 -221.401894)
		(end 364.979966 -221.804484)
		(width 0.1143)
		(layer "In4.Cu")
		(net "P5E_CPU0_G3_TX_DP<11>")
	)
	(segment
		(start 314.382404 -141.867128)
		(end 310.082438 -156.730192)
		(width 0.14224)
		(layer "In4.Cu")
		(net "P5E_CPU0_G3_TX_DP<11>")
	)
	(segment
		(start 365.03991 -221.054676)
		(end 365.03991 -221.083124)
		(width 0.1143)
		(layer "In4.Cu")
		(net "P5E_CPU0_G3_TX_DP<11>")
	)
	(segment
		(start 309.87365 -162.685984)
		(end 312.058812 -167.962326)
		(width 0.14224)
		(layer "In4.Cu")
		(net "P5E_CPU0_G3_TX_DP<11>")
	)
	(segment
		(start 364.736888 -225.50882)
		(end 364.700312 -225.530156)
		(width 0.1143)
		(layer "In4.Cu")
		(net "P5E_CPU0_G3_TX_DP<11>")
	)
	(segment
		(start 364.698788 -225.531172)
		(end 364.697772 -225.53168)
		(width 0.1143)
		(layer "In4.Cu")
		(net "P5E_CPU0_G3_TX_DP<11>")
	)
	(segment
		(start 365.03991 -221.083124)
		(end 364.99419 -221.128844)
		(width 0.1143)
		(layer "In4.Cu")
		(net "P5E_CPU0_G3_TX_DP<11>")
	)
	(segment
		(start 364.197138 -230.208836)
		(end 364.264194 -230.247952)
		(width 0.1143)
		(layer "In4.Cu")
		(net "P5E_CPU0_G3_TX_DP<11>")
	)
	(segment
		(start 364.974124 -231.441244)
		(end 365.056928 -231.524048)
		(width 0.1143)
		(layer "In4.Cu")
		(net "P5E_CPU0_G3_TX_DP<11>")
	)
	(segment
		(start 316.54369 -172.448474)
		(end 322.080636 -175.765714)
		(width 0.14224)
		(layer "In4.Cu")
		(net "P5E_CPU0_G3_TX_DP<11>")
	)
	(segment
		(start 322.080636 -175.765714)
		(end 360.28249 -207.071976)
		(width 0.14224)
		(layer "In4.Cu")
		(net "P5E_CPU0_G3_TX_DP<11>")
	)
	(segment
		(start 364.69701 -225.532188)
		(end 364.666022 -225.549968)
		(width 0.1143)
		(layer "In4.Cu")
		(net "P5E_CPU0_G3_TX_DP<11>")
	)
	(segment
		(start 365.160306 -222.122492)
		(end 365.161322 -222.123)
		(width 0.1143)
		(layer "In4.Cu")
		(net "P5E_CPU0_G3_TX_DP<11>")
	)
	(segment
		(start 365.167164 -222.126302)
		(end 365.167926 -222.12681)
		(width 0.1143)
		(layer "In4.Cu")
		(net "P5E_CPU0_G3_TX_DP<11>")
	)
	(segment
		(start 364.227618 -229.58171)
		(end 364.195106 -229.600506)
		(width 0.1143)
		(layer "In4.Cu")
		(net "P5E_CPU0_G3_TX_DP<11>")
	)
	(segment
		(start 365.206788 -223.078802)
		(end 365.137192 -223.119442)
		(width 0.1143)
		(layer "In4.Cu")
		(net "P5E_CPU0_G3_TX_DP<11>")
	)
	(segment
		(start 401.782534 -20.547584)
		(end 323.168772 -122.587258)
		(width 0.14224)
		(layer "In4.Cu")
		(net "P5E_CPU0_G3_TX_DP<11>")
	)
	(segment
		(start 364.99419 -221.128844)
		(end 364.99419 -221.38767)
		(width 0.1143)
		(layer "In4.Cu")
		(net "P5E_CPU0_G3_TX_DP<11>")
	)
	(segment
		(start 365.03991 -215.084152)
		(end 365.03991 -221.054676)
		(width 0.14224)
		(layer "In4.Cu")
		(net "P5E_CPU0_G3_TX_DP<11>")
	)
	(segment
		(start 364.197138 -228.589078)
		(end 364.266734 -228.629718)
		(width 0.1143)
		(layer "In4.Cu")
		(net "P5E_CPU0_G3_TX_DP<11>")
	)
	(segment
		(start 323.168772 -122.587258)
		(end 318.804036 -130.359912)
		(width 0.14224)
		(layer "In4.Cu")
		(net "P5E_CPU0_G3_TX_DP<11>")
	)
	(segment
		(start 365.167926 -222.12681)
		(end 365.168942 -222.127318)
		(width 0.1143)
		(layer "In4.Cu")
		(net "P5E_CPU0_G3_TX_DP<11>")
	)
	(segment
		(start 364.266734 -229.55885)
		(end 364.227618 -229.58171)
		(width 0.1143)
		(layer "In4.Cu")
		(net "P5E_CPU0_G3_TX_DP<11>")
	)
	(segment
		(start 364.99419 -221.38767)
		(end 364.979966 -221.401894)
		(width 0.1143)
		(layer "In4.Cu")
		(net "P5E_CPU0_G3_TX_DP<11>")
	)
	(segment
		(start 364.266734 -227.938838)
		(end 364.197138 -227.979478)
		(width 0.1143)
		(layer "In4.Cu")
		(net "P5E_CPU0_G3_TX_DP<11>")
	)
	(segment
		(start 360.28249 -207.071976)
		(end 365.03991 -215.084152)
		(width 0.14224)
		(layer "In4.Cu")
		(net "P5E_CPU0_G3_TX_DP<11>")
	)
	(segment
		(start 364.697772 -225.53168)
		(end 364.69701 -225.532188)
		(width 0.1143)
		(layer "In4.Cu")
		(net "P5E_CPU0_G3_TX_DP<11>")
	)
	(segment
		(start 365.16437 -222.124778)
		(end 365.167164 -222.126302)
		(width 0.1143)
		(layer "In4.Cu")
		(net "P5E_CPU0_G3_TX_DP<11>")
	)
	(segment
		(start 402.073364 -17.61236)
		(end 401.782534 -17.90319)
		(width 0.14224)
		(layer "In4.Cu")
		(net "P5E_CPU0_G3_TX_DP<11>")
	)
	(arc
		(start 365.137192 -224.739454)
		(mid 365.021765 -224.87283)
		(end 364.98022 -225.044254)
		(width 0.1143)
		(layer "In4.Cu")
		(net "P5E_CPU0_G3_TX_DP<11>")
	)
	(arc
		(start 365.206788 -223.769682)
		(mid 365.450115 -224.234248)
		(end 365.206788 -224.698814)
		(width 0.1143)
		(layer "In4.Cu")
		(net "P5E_CPU0_G3_TX_DP<11>")
	)
	(arc
		(start 364.98022 -221.80423)
		(mid 364.983178 -221.851729)
		(end 364.992158 -221.898464)
		(width 0.1143)
		(layer "In4.Cu")
		(net "P5E_CPU0_G3_TX_DP<11>")
	)
	(arc
		(start 364.264194 -230.247952)
		(mid 364.444846 -230.450697)
		(end 364.510066 -230.714296)
		(width 0.1143)
		(layer "In4.Cu")
		(net "P5E_CPU0_G3_TX_DP<11>")
	)
	(arc
		(start 364.197138 -227.979478)
		(mid 364.040161 -228.284278)
		(end 364.197138 -228.589078)
		(width 0.1143)
		(layer "In4.Cu")
		(net "P5E_CPU0_G3_TX_DP<11>")
	)
	(arc
		(start 364.666022 -225.549968)
		(mid 364.551346 -225.683302)
		(end 364.510066 -225.85426)
		(width 0.1143)
		(layer "In4.Cu")
		(net "P5E_CPU0_G3_TX_DP<11>")
	)
	(arc
		(start 365.207042 -222.14967)
		(mid 365.385855 -222.35202)
		(end 365.450374 -222.614236)
		(width 0.1143)
		(layer "In4.Cu")
		(net "P5E_CPU0_G3_TX_DP<11>")
	)
	(arc
		(start 364.736888 -231.059482)
		(mid 364.888875 -231.21599)
		(end 364.970314 -231.418384)
		(width 0.1143)
		(layer "In4.Cu")
		(net "P5E_CPU0_G3_TX_DP<11>")
	)
	(arc
		(start 365.137192 -223.119442)
		(mid 364.980215 -223.424242)
		(end 365.137192 -223.729042)
		(width 0.1143)
		(layer "In4.Cu")
		(net "P5E_CPU0_G3_TX_DP<11>")
	)
	(arc
		(start 364.992158 -221.898464)
		(mid 365.014036 -221.95989)
		(end 365.04626 -222.016574)
		(width 0.1143)
		(layer "In4.Cu")
		(net "P5E_CPU0_G3_TX_DP<11>")
	)
	(arc
		(start 364.510066 -225.85426)
		(mid 364.445551 -226.116479)
		(end 364.266734 -226.318826)
		(width 0.1143)
		(layer "In4.Cu")
		(net "P5E_CPU0_G3_TX_DP<11>")
	)
	(arc
		(start 364.970314 -231.418384)
		(mid 364.972337 -231.429794)
		(end 364.974124 -231.441244)
		(width 0.1143)
		(layer "In4.Cu")
		(net "P5E_CPU0_G3_TX_DP<11>")
	)
	(arc
		(start 364.98022 -225.044254)
		(mid 364.915705 -225.306473)
		(end 364.736888 -225.50882)
		(width 0.1143)
		(layer "In4.Cu")
		(net "P5E_CPU0_G3_TX_DP<11>")
	)
	(arc
		(start 365.04626 -222.016574)
		(mid 365.087243 -222.066436)
		(end 365.136176 -222.108522)
		(width 0.1143)
		(layer "In4.Cu")
		(net "P5E_CPU0_G3_TX_DP<11>")
	)
	(arc
		(start 364.195106 -229.600506)
		(mid 364.081177 -229.733653)
		(end 364.040166 -229.904036)
		(width 0.1143)
		(layer "In4.Cu")
		(net "P5E_CPU0_G3_TX_DP<11>")
	)
	(arc
		(start 364.266734 -228.629718)
		(mid 364.510061 -229.094284)
		(end 364.266734 -229.55885)
		(width 0.1143)
		(layer "In4.Cu")
		(net "P5E_CPU0_G3_TX_DP<11>")
	)
	(arc
		(start 364.197138 -226.359466)
		(mid 364.040161 -226.664266)
		(end 364.197138 -226.969066)
		(width 0.1143)
		(layer "In4.Cu")
		(net "P5E_CPU0_G3_TX_DP<11>")
	)
	(arc
		(start 364.266734 -227.009706)
		(mid 364.510061 -227.474272)
		(end 364.266734 -227.938838)
		(width 0.1143)
		(layer "In4.Cu")
		(net "P5E_CPU0_G3_TX_DP<11>")
	)
	(arc
		(start 365.45012 -222.614236)
		(mid 365.385605 -222.876455)
		(end 365.206788 -223.078802)
		(width 0.1143)
		(layer "In4.Cu")
		(net "P5E_CPU0_G3_TX_DP<11>")
	)
	(arc
		(start 364.040166 -229.904036)
		(mid 364.081715 -230.075458)
		(end 364.197138 -230.208836)
		(width 0.1143)
		(layer "In4.Cu")
		(net "P5E_CPU0_G3_TX_DP<11>")
	)
	(arc
		(start 364.510066 -230.714296)
		(mid 364.550828 -230.88418)
		(end 364.664244 -231.017064)
		(width 0.1143)
		(layer "In4.Cu")
		(net "P5E_CPU0_G3_TX_DP<11>")
	)
	(segment
		(start 364.888018 -233.409998)
		(end 365.35487 -233.14406)
		(width 0.12954)
		(layer "F.Cu")
		(net "P5E_CPU0_G3_TX_DP<10>")
	)
	(segment
		(start 404.596854 -18.185892)
		(end 404.596854 -18.86585)
		(width 0.12954)
		(layer "F.Cu")
		(net "P5E_CPU0_G3_TX_DP<10>")
	)
	(segment
		(start 404.891748 -17.890998)
		(end 404.596854 -18.185892)
		(width 0.12954)
		(layer "F.Cu")
		(net "P5E_CPU0_G3_TX_DP<10>")
	)
	(segment
		(start 404.596854 -18.86585)
		(end 404.867364 -19.13636)
		(width 0.12954)
		(layer "F.Cu")
		(net "P5E_CPU0_G3_TX_DP<10>")
	)
	(segment
		(start 404.867364 -19.13636)
		(end 404.576534 -19.42719)
		(width 0.14224)
		(layer "In4.Cu")
		(net "P5E_CPU0_G3_TX_DP<10>")
	)
	(segment
		(start 365.171228 -232.819702)
		(end 365.168688 -232.820972)
		(width 0.1143)
		(layer "In4.Cu")
		(net "P5E_CPU0_G3_TX_DP<10>")
	)
	(segment
		(start 323.522086 -123.93041)
		(end 319.652142 -130.754374)
		(width 0.14224)
		(layer "In4.Cu")
		(net "P5E_CPU0_G3_TX_DP<10>")
	)
	(segment
		(start 365.632238 -225.534982)
		(end 365.608362 -225.548698)
		(width 0.1143)
		(layer "In4.Cu")
		(net "P5E_CPU0_G3_TX_DP<10>")
	)
	(segment
		(start 361.015788 -206.466948)
		(end 365.985298 -214.837518)
		(width 0.14224)
		(layer "In4.Cu")
		(net "P5E_CPU0_G3_TX_DP<10>")
	)
	(segment
		(start 365.168688 -232.820972)
		(end 365.167164 -232.821988)
		(width 0.1143)
		(layer "In4.Cu")
		(net "P5E_CPU0_G3_TX_DP<10>")
	)
	(segment
		(start 365.167926 -226.986846)
		(end 365.204248 -227.007928)
		(width 0.1143)
		(layer "In4.Cu")
		(net "P5E_CPU0_G3_TX_DP<10>")
	)
	(segment
		(start 310.988964 -156.952442)
		(end 310.80583 -157.87243)
		(width 0.14224)
		(layer "In4.Cu")
		(net "P5E_CPU0_G3_TX_DP<10>")
	)
	(segment
		(start 365.136176 -226.968558)
		(end 365.165894 -226.985576)
		(width 0.1143)
		(layer "In4.Cu")
		(net "P5E_CPU0_G3_TX_DP<10>")
	)
	(segment
		(start 312.894726 -167.479726)
		(end 317.046864 -171.632626)
		(width 0.14224)
		(layer "In4.Cu")
		(net "P5E_CPU0_G3_TX_DP<10>")
	)
	(segment
		(start 366.145318 -223.079818)
		(end 366.077246 -223.119442)
		(width 0.1143)
		(layer "In4.Cu")
		(net "P5E_CPU0_G3_TX_DP<10>")
	)
	(segment
		(start 365.165894 -232.82275)
		(end 365.136176 -232.839768)
		(width 0.1143)
		(layer "In4.Cu")
		(net "P5E_CPU0_G3_TX_DP<10>")
	)
	(segment
		(start 365.637826 -225.53168)
		(end 365.636302 -225.532696)
		(width 0.1143)
		(layer "In4.Cu")
		(net "P5E_CPU0_G3_TX_DP<10>")
	)
	(segment
		(start 365.939578 -221.128844)
		(end 365.939578 -221.38767)
		(width 0.1143)
		(layer "In4.Cu")
		(net "P5E_CPU0_G3_TX_DP<10>")
	)
	(segment
		(start 310.80583 -162.500056)
		(end 312.824876 -167.374824)
		(width 0.14224)
		(layer "In4.Cu")
		(net "P5E_CPU0_G3_TX_DP<10>")
	)
	(segment
		(start 365.165894 -228.605588)
		(end 365.167164 -228.60635)
		(width 0.1143)
		(layer "In4.Cu")
		(net "P5E_CPU0_G3_TX_DP<10>")
	)
	(segment
		(start 317.046864 -171.632626)
		(end 322.490084 -174.89551)
		(width 0.14224)
		(layer "In4.Cu")
		(net "P5E_CPU0_G3_TX_DP<10>")
	)
	(segment
		(start 365.204248 -227.940616)
		(end 365.167926 -227.961698)
		(width 0.1143)
		(layer "In4.Cu")
		(net "P5E_CPU0_G3_TX_DP<10>")
	)
	(segment
		(start 365.167164 -226.342194)
		(end 365.165894 -226.342956)
		(width 0.1143)
		(layer "In4.Cu")
		(net "P5E_CPU0_G3_TX_DP<10>")
	)
	(segment
		(start 365.166402 -230.228902)
		(end 365.170974 -230.231696)
		(width 0.1143)
		(layer "In4.Cu")
		(net "P5E_CPU0_G3_TX_DP<10>")
	)
	(segment
		(start 365.204248 -229.560628)
		(end 365.13643 -229.599744)
		(width 0.1143)
		(layer "In4.Cu")
		(net "P5E_CPU0_G3_TX_DP<10>")
	)
	(segment
		(start 404.576534 -19.42719)
		(end 404.576534 -20.547584)
		(width 0.14224)
		(layer "In4.Cu")
		(net "P5E_CPU0_G3_TX_DP<10>")
	)
	(segment
		(start 365.63427 -225.533712)
		(end 365.633508 -225.53422)
		(width 0.1143)
		(layer "In4.Cu")
		(net "P5E_CPU0_G3_TX_DP<10>")
	)
	(segment
		(start 366.146842 -224.698814)
		(end 366.077246 -224.739454)
		(width 0.1143)
		(layer "In4.Cu")
		(net "P5E_CPU0_G3_TX_DP<10>")
	)
	(segment
		(start 312.824876 -167.374824)
		(end 312.894726 -167.479726)
		(width 0.14224)
		(layer "In4.Cu")
		(net "P5E_CPU0_G3_TX_DP<10>")
	)
	(segment
		(start 365.920274 -225.044254)
		(end 365.92002 -225.044254)
		(width 0.1143)
		(layer "In4.Cu")
		(net "P5E_CPU0_G3_TX_DP<10>")
	)
	(segment
		(start 365.167926 -226.341686)
		(end 365.167164 -226.342194)
		(width 0.1143)
		(layer "In4.Cu")
		(net "P5E_CPU0_G3_TX_DP<10>")
	)
	(segment
		(start 365.217202 -226.311206)
		(end 365.206788 -226.31908)
		(width 0.1143)
		(layer "In4.Cu")
		(net "P5E_CPU0_G3_TX_DP<10>")
	)
	(segment
		(start 366.077246 -223.729042)
		(end 366.146842 -223.769682)
		(width 0.1143)
		(layer "In4.Cu")
		(net "P5E_CPU0_G3_TX_DP<10>")
	)
	(segment
		(start 365.165894 -227.962968)
		(end 365.136176 -227.979986)
		(width 0.1143)
		(layer "In4.Cu")
		(net "P5E_CPU0_G3_TX_DP<10>")
	)
	(segment
		(start 322.490084 -174.89551)
		(end 361.015788 -206.466948)
		(width 0.14224)
		(layer "In4.Cu")
		(net "P5E_CPU0_G3_TX_DP<10>")
	)
	(segment
		(start 365.136176 -228.58857)
		(end 365.165894 -228.605588)
		(width 0.1143)
		(layer "In4.Cu")
		(net "P5E_CPU0_G3_TX_DP<10>")
	)
	(segment
		(start 365.985298 -214.837518)
		(end 365.985298 -221.083124)
		(width 0.14224)
		(layer "In4.Cu")
		(net "P5E_CPU0_G3_TX_DP<10>")
	)
	(segment
		(start 365.608108 -231.019604)
		(end 365.676942 -231.059482)
		(width 0.1143)
		(layer "In4.Cu")
		(net "P5E_CPU0_G3_TX_DP<10>")
	)
	(segment
		(start 365.45012 -225.85426)
		(end 365.45012 -225.861372)
		(width 0.1143)
		(layer "In4.Cu")
		(net "P5E_CPU0_G3_TX_DP<10>")
	)
	(segment
		(start 365.167164 -227.962206)
		(end 365.165894 -227.962968)
		(width 0.1143)
		(layer "In4.Cu")
		(net "P5E_CPU0_G3_TX_DP<10>")
	)
	(segment
		(start 365.67618 -231.989122)
		(end 365.637318 -232.011728)
		(width 0.1143)
		(layer "In4.Cu")
		(net "P5E_CPU0_G3_TX_DP<10>")
	)
	(segment
		(start 365.636302 -225.532696)
		(end 365.63427 -225.533712)
		(width 0.1143)
		(layer "In4.Cu")
		(net "P5E_CPU0_G3_TX_DP<10>")
	)
	(segment
		(start 365.206788 -226.31908)
		(end 365.17072 -226.339908)
		(width 0.1143)
		(layer "In4.Cu")
		(net "P5E_CPU0_G3_TX_DP<10>")
	)
	(segment
		(start 365.13643 -229.599744)
		(end 365.136176 -229.599998)
		(width 0.1143)
		(layer "In4.Cu")
		(net "P5E_CPU0_G3_TX_DP<10>")
	)
	(segment
		(start 364.987078 -233.07421)
		(end 365.056928 -233.14406)
		(width 0.1143)
		(layer "In4.Cu")
		(net "P5E_CPU0_G3_TX_DP<10>")
	)
	(segment
		(start 365.17072 -226.339908)
		(end 365.167926 -226.341686)
		(width 0.1143)
		(layer "In4.Cu")
		(net "P5E_CPU0_G3_TX_DP<10>")
	)
	(segment
		(start 365.167164 -228.60635)
		(end 365.167926 -228.606858)
		(width 0.1143)
		(layer "In4.Cu")
		(net "P5E_CPU0_G3_TX_DP<10>")
	)
	(segment
		(start 315.2648 -142.172182)
		(end 310.988964 -156.952442)
		(width 0.14224)
		(layer "In4.Cu")
		(net "P5E_CPU0_G3_TX_DP<10>")
	)
	(segment
		(start 310.80583 -157.87243)
		(end 310.80583 -162.500056)
		(width 0.14224)
		(layer "In4.Cu")
		(net "P5E_CPU0_G3_TX_DP<10>")
	)
	(segment
		(start 365.167164 -232.821988)
		(end 365.165894 -232.82275)
		(width 0.1143)
		(layer "In4.Cu")
		(net "P5E_CPU0_G3_TX_DP<10>")
	)
	(segment
		(start 365.92002 -221.407228)
		(end 365.92002 -221.80423)
		(width 0.1143)
		(layer "In4.Cu")
		(net "P5E_CPU0_G3_TX_DP<10>")
	)
	(segment
		(start 365.167926 -228.606858)
		(end 365.204248 -228.62794)
		(width 0.1143)
		(layer "In4.Cu")
		(net "P5E_CPU0_G3_TX_DP<10>")
	)
	(segment
		(start 319.652142 -130.754374)
		(end 315.2648 -142.172182)
		(width 0.14224)
		(layer "In4.Cu")
		(net "P5E_CPU0_G3_TX_DP<10>")
	)
	(segment
		(start 365.939578 -221.38767)
		(end 365.92002 -221.407228)
		(width 0.1143)
		(layer "In4.Cu")
		(net "P5E_CPU0_G3_TX_DP<10>")
	)
	(segment
		(start 365.056928 -233.14406)
		(end 365.35487 -233.14406)
		(width 0.1143)
		(layer "In4.Cu")
		(net "P5E_CPU0_G3_TX_DP<10>")
	)
	(segment
		(start 404.576534 -20.547584)
		(end 323.522086 -123.93041)
		(width 0.14224)
		(layer "In4.Cu")
		(net "P5E_CPU0_G3_TX_DP<10>")
	)
	(segment
		(start 365.985298 -221.083124)
		(end 365.939578 -221.128844)
		(width 0.1143)
		(layer "In4.Cu")
		(net "P5E_CPU0_G3_TX_DP<10>")
	)
	(segment
		(start 365.633508 -225.53422)
		(end 365.632238 -225.534982)
		(width 0.1143)
		(layer "In4.Cu")
		(net "P5E_CPU0_G3_TX_DP<10>")
	)
	(segment
		(start 365.455708 -232.326942)
		(end 365.455708 -232.329482)
		(width 0.1143)
		(layer "In4.Cu")
		(net "P5E_CPU0_G3_TX_DP<10>")
	)
	(segment
		(start 366.10417 -222.12808)
		(end 366.106964 -222.129604)
		(width 0.1143)
		(layer "In4.Cu")
		(net "P5E_CPU0_G3_TX_DP<10>")
	)
	(segment
		(start 365.165894 -226.342956)
		(end 365.136176 -226.359974)
		(width 0.1143)
		(layer "In4.Cu")
		(net "P5E_CPU0_G3_TX_DP<10>")
	)
	(segment
		(start 365.638334 -225.531172)
		(end 365.637826 -225.53168)
		(width 0.1143)
		(layer "In4.Cu")
		(net "P5E_CPU0_G3_TX_DP<10>")
	)
	(segment
		(start 365.167164 -226.986338)
		(end 365.167926 -226.986846)
		(width 0.1143)
		(layer "In4.Cu")
		(net "P5E_CPU0_G3_TX_DP<10>")
	)
	(segment
		(start 365.165894 -226.985576)
		(end 365.167164 -226.986338)
		(width 0.1143)
		(layer "In4.Cu")
		(net "P5E_CPU0_G3_TX_DP<10>")
	)
	(segment
		(start 365.167926 -227.961698)
		(end 365.167164 -227.962206)
		(width 0.1143)
		(layer "In4.Cu")
		(net "P5E_CPU0_G3_TX_DP<10>")
	)
	(arc
		(start 365.637318 -232.011728)
		(mid 365.504398 -232.145075)
		(end 365.455708 -232.326942)
		(width 0.1143)
		(layer "In4.Cu")
		(net "P5E_CPU0_G3_TX_DP<10>")
	)
	(arc
		(start 365.45012 -229.08768)
		(mid 365.45013 -229.090982)
		(end 365.45012 -229.094284)
		(width 0.1143)
		(layer "In4.Cu")
		(net "P5E_CPU0_G3_TX_DP<10>")
	)
	(arc
		(start 365.676942 -231.988614)
		(mid 365.676561 -231.988868)
		(end 365.67618 -231.989122)
		(width 0.1143)
		(layer "In4.Cu")
		(net "P5E_CPU0_G3_TX_DP<10>")
	)
	(arc
		(start 365.218472 -227.93071)
		(mid 365.211399 -227.935719)
		(end 365.204248 -227.940616)
		(width 0.1143)
		(layer "In4.Cu")
		(net "P5E_CPU0_G3_TX_DP<10>")
	)
	(arc
		(start 366.146842 -223.769682)
		(mid 366.390169 -224.234248)
		(end 366.146842 -224.698814)
		(width 0.1143)
		(layer "In4.Cu")
		(net "P5E_CPU0_G3_TX_DP<10>")
	)
	(arc
		(start 365.204248 -227.007928)
		(mid 365.211398 -227.012826)
		(end 365.218472 -227.017834)
		(width 0.1143)
		(layer "In4.Cu")
		(net "P5E_CPU0_G3_TX_DP<10>")
	)
	(arc
		(start 364.979966 -229.904036)
		(mid 365.029894 -230.091306)
		(end 365.166402 -230.228902)
		(width 0.1143)
		(layer "In4.Cu")
		(net "P5E_CPU0_G3_TX_DP<10>")
	)
	(arc
		(start 366.106964 -222.129604)
		(mid 366.388458 -222.59412)
		(end 366.145318 -223.079818)
		(width 0.1143)
		(layer "In4.Cu")
		(net "P5E_CPU0_G3_TX_DP<10>")
	)
	(arc
		(start 366.077246 -224.739454)
		(mid 365.961819 -224.87283)
		(end 365.920274 -225.044254)
		(width 0.1143)
		(layer "In4.Cu")
		(net "P5E_CPU0_G3_TX_DP<10>")
	)
	(arc
		(start 365.136176 -232.839768)
		(mid 365.039041 -232.942637)
		(end 364.987078 -233.07421)
		(width 0.1143)
		(layer "In4.Cu")
		(net "P5E_CPU0_G3_TX_DP<10>")
	)
	(arc
		(start 365.136176 -227.979986)
		(mid 364.980248 -228.284278)
		(end 365.136176 -228.58857)
		(width 0.1143)
		(layer "In4.Cu")
		(net "P5E_CPU0_G3_TX_DP<10>")
	)
	(arc
		(start 365.136176 -226.359974)
		(mid 364.980248 -226.664266)
		(end 365.136176 -226.968558)
		(width 0.1143)
		(layer "In4.Cu")
		(net "P5E_CPU0_G3_TX_DP<10>")
	)
	(arc
		(start 365.92002 -221.80423)
		(mid 365.969269 -221.990514)
		(end 366.10417 -222.12808)
		(width 0.1143)
		(layer "In4.Cu")
		(net "P5E_CPU0_G3_TX_DP<10>")
	)
	(arc
		(start 366.077246 -223.119442)
		(mid 365.920269 -223.424242)
		(end 366.077246 -223.729042)
		(width 0.1143)
		(layer "In4.Cu")
		(net "P5E_CPU0_G3_TX_DP<10>")
	)
	(arc
		(start 365.170974 -230.231696)
		(mid 365.375298 -230.435541)
		(end 365.45012 -230.714296)
		(width 0.1143)
		(layer "In4.Cu")
		(net "P5E_CPU0_G3_TX_DP<10>")
	)
	(arc
		(start 365.45012 -225.861372)
		(mid 365.383918 -226.112305)
		(end 365.217202 -226.311206)
		(width 0.1143)
		(layer "In4.Cu")
		(net "P5E_CPU0_G3_TX_DP<10>")
	)
	(arc
		(start 365.204248 -228.62794)
		(mid 365.212426 -228.633583)
		(end 365.220504 -228.63937)
		(width 0.1143)
		(layer "In4.Cu")
		(net "P5E_CPU0_G3_TX_DP<10>")
	)
	(arc
		(start 365.608362 -225.548698)
		(mid 365.492089 -225.682238)
		(end 365.45012 -225.85426)
		(width 0.1143)
		(layer "In4.Cu")
		(net "P5E_CPU0_G3_TX_DP<10>")
	)
	(arc
		(start 365.45012 -230.714296)
		(mid 365.491999 -230.886165)
		(end 365.608108 -231.019604)
		(width 0.1143)
		(layer "In4.Cu")
		(net "P5E_CPU0_G3_TX_DP<10>")
	)
	(arc
		(start 365.45012 -229.094284)
		(mid 365.384884 -229.357875)
		(end 365.204248 -229.560628)
		(width 0.1143)
		(layer "In4.Cu")
		(net "P5E_CPU0_G3_TX_DP<10>")
	)
	(arc
		(start 365.218472 -227.017834)
		(mid 365.445855 -227.474272)
		(end 365.218472 -227.93071)
		(width 0.1143)
		(layer "In4.Cu")
		(net "P5E_CPU0_G3_TX_DP<10>")
	)
	(arc
		(start 365.92002 -225.044254)
		(mid 365.844518 -225.325506)
		(end 365.638334 -225.531172)
		(width 0.1143)
		(layer "In4.Cu")
		(net "P5E_CPU0_G3_TX_DP<10>")
	)
	(arc
		(start 365.676942 -231.059482)
		(mid 365.920269 -231.524048)
		(end 365.676942 -231.988614)
		(width 0.1143)
		(layer "In4.Cu")
		(net "P5E_CPU0_G3_TX_DP<10>")
	)
	(arc
		(start 365.136176 -229.599998)
		(mid 365.021333 -229.733146)
		(end 364.979966 -229.904036)
		(width 0.1143)
		(layer "In4.Cu")
		(net "P5E_CPU0_G3_TX_DP<10>")
	)
	(arc
		(start 365.455708 -232.329482)
		(mid 365.379492 -232.612903)
		(end 365.171228 -232.819702)
		(width 0.1143)
		(layer "In4.Cu")
		(net "P5E_CPU0_G3_TX_DP<10>")
	)
	(arc
		(start 365.220504 -228.63937)
		(mid 365.385171 -228.837977)
		(end 365.45012 -229.08768)
		(width 0.1143)
		(layer "In4.Cu")
		(net "P5E_CPU0_G3_TX_DP<10>")
	)
	(segment
		(start 373.347996 -235.03001)
		(end 373.814848 -234.764072)
		(width 0.12954)
		(layer "F.Cu")
		(net "P5E_CPU0_G3_TX_DP<0>")
	)
	(segment
		(start 432.876706 -18.86585)
		(end 433.147216 -19.13636)
		(width 0.12954)
		(layer "F.Cu")
		(net "P5E_CPU0_G3_TX_DP<0>")
	)
	(segment
		(start 432.876706 -18.185892)
		(end 432.876706 -18.86585)
		(width 0.12954)
		(layer "F.Cu")
		(net "P5E_CPU0_G3_TX_DP<0>")
	)
	(segment
		(start 433.1716 -17.890998)
		(end 432.876706 -18.185892)
		(width 0.12954)
		(layer "F.Cu")
		(net "P5E_CPU0_G3_TX_DP<0>")
	)
	(segment
		(start 375.977658 -223.911668)
		(end 375.944892 -223.930718)
		(width 0.1143)
		(layer "In4.Cu")
		(net "P5E_CPU0_G3_TX_DP<0>")
	)
	(segment
		(start 373.897398 -233.963718)
		(end 373.897398 -233.97337)
		(width 0.1143)
		(layer "In4.Cu")
		(net "P5E_CPU0_G3_TX_DP<0>")
	)
	(segment
		(start 432.856386 -19.42719)
		(end 432.856386 -20.13712)
		(width 0.14224)
		(layer "In4.Cu")
		(net "P5E_CPU0_G3_TX_DP<0>")
	)
	(segment
		(start 375.041414 -232.009442)
		(end 375.038874 -232.010966)
		(width 0.1143)
		(layer "In4.Cu")
		(net "P5E_CPU0_G3_TX_DP<0>")
	)
	(segment
		(start 376.016774 -223.888808)
		(end 375.977658 -223.911668)
		(width 0.1143)
		(layer "In4.Cu")
		(net "P5E_CPU0_G3_TX_DP<0>")
	)
	(segment
		(start 342.132412 -178.529234)
		(end 343.113614 -179.510182)
		(width 0.14224)
		(layer "In4.Cu")
		(net "P5E_CPU0_G3_TX_DP<0>")
	)
	(segment
		(start 375.035826 -225.53295)
		(end 375.006108 -225.549968)
		(width 0.1143)
		(layer "In4.Cu")
		(net "P5E_CPU0_G3_TX_DP<0>")
	)
	(segment
		(start 375.037858 -232.011474)
		(end 375.037096 -232.011982)
		(width 0.1143)
		(layer "In4.Cu")
		(net "P5E_CPU0_G3_TX_DP<0>")
	)
	(segment
		(start 375.821702 -212.743542)
		(end 376.52579 -213.882732)
		(width 0.14224)
		(layer "In4.Cu")
		(net "P5E_CPU0_G3_TX_DP<0>")
	)
	(segment
		(start 327.410826 -138.324082)
		(end 327.409556 -138.33348)
		(width 0.14224)
		(layer "In4.Cu")
		(net "P5E_CPU0_G3_TX_DP<0>")
	)
	(segment
		(start 373.516906 -234.764072)
		(end 373.814848 -234.764072)
		(width 0.1143)
		(layer "In4.Cu")
		(net "P5E_CPU0_G3_TX_DP<0>")
	)
	(segment
		(start 375.076974 -225.50882)
		(end 375.070116 -225.512884)
		(width 0.1143)
		(layer "In4.Cu")
		(net "P5E_CPU0_G3_TX_DP<0>")
	)
	(segment
		(start 433.147216 -19.13636)
		(end 432.856386 -19.42719)
		(width 0.14224)
		(layer "In4.Cu")
		(net "P5E_CPU0_G3_TX_DP<0>")
	)
	(segment
		(start 328.14006 -135.677402)
		(end 327.410826 -138.324082)
		(width 0.14224)
		(layer "In4.Cu")
		(net "P5E_CPU0_G3_TX_DP<0>")
	)
	(segment
		(start 375.479056 -224.738184)
		(end 375.478294 -224.738692)
		(width 0.1143)
		(layer "In4.Cu")
		(net "P5E_CPU0_G3_TX_DP<0>")
	)
	(segment
		(start 373.447056 -234.694222)
		(end 373.516906 -234.764072)
		(width 0.1143)
		(layer "In4.Cu")
		(net "P5E_CPU0_G3_TX_DP<0>")
	)
	(segment
		(start 375.038874 -225.531172)
		(end 375.037858 -225.53168)
		(width 0.1143)
		(layer "In4.Cu")
		(net "P5E_CPU0_G3_TX_DP<0>")
	)
	(segment
		(start 328.524108 -151.244554)
		(end 329.261216 -154.43327)
		(width 0.14224)
		(layer "In4.Cu")
		(net "P5E_CPU0_G3_TX_DP<0>")
	)
	(segment
		(start 375.00433 -231.017064)
		(end 375.076974 -231.059482)
		(width 0.1143)
		(layer "In4.Cu")
		(net "P5E_CPU0_G3_TX_DP<0>")
	)
	(segment
		(start 375.035826 -232.012744)
		(end 375.006108 -232.029762)
		(width 0.1143)
		(layer "In4.Cu")
		(net "P5E_CPU0_G3_TX_DP<0>")
	)
	(segment
		(start 375.070116 -225.512884)
		(end 375.069354 -225.513392)
		(width 0.1143)
		(layer "In4.Cu")
		(net "P5E_CPU0_G3_TX_DP<0>")
	)
	(segment
		(start 376.52579 -213.882732)
		(end 377.246134 -219.285058)
		(width 0.14224)
		(layer "In4.Cu")
		(net "P5E_CPU0_G3_TX_DP<0>")
	)
	(segment
		(start 432.856386 -20.13712)
		(end 328.749406 -134.248906)
		(width 0.14224)
		(layer "In4.Cu")
		(net "P5E_CPU0_G3_TX_DP<0>")
	)
	(segment
		(start 377.246134 -221.57563)
		(end 377.200414 -221.62135)
		(width 0.1143)
		(layer "In4.Cu")
		(net "P5E_CPU0_G3_TX_DP<0>")
	)
	(segment
		(start 368.444018 -200.25614)
		(end 375.821702 -212.743542)
		(width 0.14224)
		(layer "In4.Cu")
		(net "P5E_CPU0_G3_TX_DP<0>")
	)
	(segment
		(start 337.472528 -171.66209)
		(end 342.132412 -178.529234)
		(width 0.14224)
		(layer "In4.Cu")
		(net "P5E_CPU0_G3_TX_DP<0>")
	)
	(segment
		(start 328.749406 -134.248906)
		(end 328.14006 -135.677402)
		(width 0.14224)
		(layer "In4.Cu")
		(net "P5E_CPU0_G3_TX_DP<0>")
	)
	(segment
		(start 373.625872 -234.442762)
		(end 373.596154 -234.45978)
		(width 0.1143)
		(layer "In4.Cu")
		(net "P5E_CPU0_G3_TX_DP<0>")
	)
	(segment
		(start 375.038874 -232.010966)
		(end 375.037858 -232.011474)
		(width 0.1143)
		(layer "In4.Cu")
		(net "P5E_CPU0_G3_TX_DP<0>")
	)
	(segment
		(start 373.627142 -234.442)
		(end 373.625872 -234.442762)
		(width 0.1143)
		(layer "In4.Cu")
		(net "P5E_CPU0_G3_TX_DP<0>")
	)
	(segment
		(start 327.409556 -141.477746)
		(end 328.524108 -151.244554)
		(width 0.14224)
		(layer "In4.Cu")
		(net "P5E_CPU0_G3_TX_DP<0>")
	)
	(segment
		(start 375.069354 -225.513392)
		(end 375.042176 -225.52914)
		(width 0.1143)
		(layer "In4.Cu")
		(net "P5E_CPU0_G3_TX_DP<0>")
	)
	(segment
		(start 327.409556 -138.33348)
		(end 327.409556 -141.477746)
		(width 0.14224)
		(layer "In4.Cu")
		(net "P5E_CPU0_G3_TX_DP<0>")
	)
	(segment
		(start 374.537224 -230.208836)
		(end 374.60428 -230.247952)
		(width 0.1143)
		(layer "In4.Cu")
		(net "P5E_CPU0_G3_TX_DP<0>")
	)
	(segment
		(start 343.113614 -179.510182)
		(end 368.444018 -200.25614)
		(width 0.14224)
		(layer "In4.Cu")
		(net "P5E_CPU0_G3_TX_DP<0>")
	)
	(segment
		(start 375.076974 -231.988614)
		(end 375.070116 -231.992678)
		(width 0.1143)
		(layer "In4.Cu")
		(net "P5E_CPU0_G3_TX_DP<0>")
	)
	(segment
		(start 373.627904 -234.441492)
		(end 373.627142 -234.442)
		(width 0.1143)
		(layer "In4.Cu")
		(net "P5E_CPU0_G3_TX_DP<0>")
	)
	(segment
		(start 375.041414 -225.529648)
		(end 375.038874 -225.531172)
		(width 0.1143)
		(layer "In4.Cu")
		(net "P5E_CPU0_G3_TX_DP<0>")
	)
	(segment
		(start 376.917204 -222.292164)
		(end 376.915934 -222.292926)
		(width 0.1143)
		(layer "In4.Cu")
		(net "P5E_CPU0_G3_TX_DP<0>")
	)
	(segment
		(start 376.44578 -223.102932)
		(end 376.416062 -223.11995)
		(width 0.1143)
		(layer "In4.Cu")
		(net "P5E_CPU0_G3_TX_DP<0>")
	)
	(segment
		(start 374.537224 -228.589078)
		(end 374.60682 -228.629718)
		(width 0.1143)
		(layer "In4.Cu")
		(net "P5E_CPU0_G3_TX_DP<0>")
	)
	(segment
		(start 375.54662 -224.698814)
		(end 375.507504 -224.721674)
		(width 0.1143)
		(layer "In4.Cu")
		(net "P5E_CPU0_G3_TX_DP<0>")
	)
	(segment
		(start 375.042176 -232.008934)
		(end 375.041414 -232.009442)
		(width 0.1143)
		(layer "In4.Cu")
		(net "P5E_CPU0_G3_TX_DP<0>")
	)
	(segment
		(start 375.507504 -224.721674)
		(end 375.479056 -224.738184)
		(width 0.1143)
		(layer "In4.Cu")
		(net "P5E_CPU0_G3_TX_DP<0>")
	)
	(segment
		(start 375.478294 -224.738692)
		(end 375.477278 -224.739454)
		(width 0.1143)
		(layer "In4.Cu")
		(net "P5E_CPU0_G3_TX_DP<0>")
	)
	(segment
		(start 376.917966 -222.291656)
		(end 376.917204 -222.292164)
		(width 0.1143)
		(layer "In4.Cu")
		(net "P5E_CPU0_G3_TX_DP<0>")
	)
	(segment
		(start 375.042176 -225.52914)
		(end 375.041414 -225.529648)
		(width 0.1143)
		(layer "In4.Cu")
		(net "P5E_CPU0_G3_TX_DP<0>")
	)
	(segment
		(start 376.447812 -223.101662)
		(end 376.44705 -223.10217)
		(width 0.1143)
		(layer "In4.Cu")
		(net "P5E_CPU0_G3_TX_DP<0>")
	)
	(segment
		(start 375.037096 -232.011982)
		(end 375.035826 -232.012744)
		(width 0.1143)
		(layer "In4.Cu")
		(net "P5E_CPU0_G3_TX_DP<0>")
	)
	(segment
		(start 376.915934 -222.292926)
		(end 376.886216 -222.309944)
		(width 0.1143)
		(layer "In4.Cu")
		(net "P5E_CPU0_G3_TX_DP<0>")
	)
	(segment
		(start 374.60682 -229.55885)
		(end 374.567704 -229.58171)
		(width 0.1143)
		(layer "In4.Cu")
		(net "P5E_CPU0_G3_TX_DP<0>")
	)
	(segment
		(start 329.261216 -154.43327)
		(end 329.800712 -155.954984)
		(width 0.14224)
		(layer "In4.Cu")
		(net "P5E_CPU0_G3_TX_DP<0>")
	)
	(segment
		(start 377.200414 -221.62135)
		(end 377.200414 -221.80423)
		(width 0.1143)
		(layer "In4.Cu")
		(net "P5E_CPU0_G3_TX_DP<0>")
	)
	(segment
		(start 374.60682 -232.79862)
		(end 374.537224 -232.83926)
		(width 0.1143)
		(layer "In4.Cu")
		(net "P5E_CPU0_G3_TX_DP<0>")
	)
	(segment
		(start 377.246134 -219.285058)
		(end 377.246134 -221.547182)
		(width 0.14224)
		(layer "In4.Cu")
		(net "P5E_CPU0_G3_TX_DP<0>")
	)
	(segment
		(start 374.567704 -229.58171)
		(end 374.535192 -229.600506)
		(width 0.1143)
		(layer "In4.Cu")
		(net "P5E_CPU0_G3_TX_DP<0>")
	)
	(segment
		(start 374.537224 -226.969066)
		(end 374.60682 -227.009706)
		(width 0.1143)
		(layer "In4.Cu")
		(net "P5E_CPU0_G3_TX_DP<0>")
	)
	(segment
		(start 376.450098 -223.100392)
		(end 376.447812 -223.101662)
		(width 0.1143)
		(layer "In4.Cu")
		(net "P5E_CPU0_G3_TX_DP<0>")
	)
	(segment
		(start 374.60682 -226.318826)
		(end 374.537224 -226.359466)
		(width 0.1143)
		(layer "In4.Cu")
		(net "P5E_CPU0_G3_TX_DP<0>")
	)
	(segment
		(start 375.037096 -225.532188)
		(end 375.035826 -225.53295)
		(width 0.1143)
		(layer "In4.Cu")
		(net "P5E_CPU0_G3_TX_DP<0>")
	)
	(segment
		(start 377.246134 -221.547182)
		(end 377.246134 -221.57563)
		(width 0.1143)
		(layer "In4.Cu")
		(net "P5E_CPU0_G3_TX_DP<0>")
	)
	(segment
		(start 375.069354 -231.993186)
		(end 375.042176 -232.008934)
		(width 0.1143)
		(layer "In4.Cu")
		(net "P5E_CPU0_G3_TX_DP<0>")
	)
	(segment
		(start 375.037858 -225.53168)
		(end 375.037096 -225.532188)
		(width 0.1143)
		(layer "In4.Cu")
		(net "P5E_CPU0_G3_TX_DP<0>")
	)
	(segment
		(start 375.070116 -231.992678)
		(end 375.069354 -231.993186)
		(width 0.1143)
		(layer "In4.Cu")
		(net "P5E_CPU0_G3_TX_DP<0>")
	)
	(segment
		(start 329.800712 -155.954984)
		(end 337.472528 -171.66209)
		(width 0.14224)
		(layer "In4.Cu")
		(net "P5E_CPU0_G3_TX_DP<0>")
	)
	(segment
		(start 376.957082 -222.268796)
		(end 376.917966 -222.291656)
		(width 0.1143)
		(layer "In4.Cu")
		(net "P5E_CPU0_G3_TX_DP<0>")
	)
	(segment
		(start 374.60682 -227.938838)
		(end 374.537224 -227.979478)
		(width 0.1143)
		(layer "In4.Cu")
		(net "P5E_CPU0_G3_TX_DP<0>")
	)
	(segment
		(start 376.44705 -223.10217)
		(end 376.44578 -223.102932)
		(width 0.1143)
		(layer "In4.Cu")
		(net "P5E_CPU0_G3_TX_DP<0>")
	)
	(segment
		(start 374.13692 -233.608626)
		(end 374.085104 -233.638852)
		(width 0.1143)
		(layer "In4.Cu")
		(net "P5E_CPU0_G3_TX_DP<0>")
	)
	(segment
		(start 376.486928 -223.078802)
		(end 376.450098 -223.100392)
		(width 0.1143)
		(layer "In4.Cu")
		(net "P5E_CPU0_G3_TX_DP<0>")
	)
	(arc
		(start 374.850152 -232.334054)
		(mid 374.785637 -232.596273)
		(end 374.60682 -232.79862)
		(width 0.1143)
		(layer "In4.Cu")
		(net "P5E_CPU0_G3_TX_DP<0>")
	)
	(arc
		(start 374.850152 -230.714296)
		(mid 374.890914 -230.88418)
		(end 375.00433 -231.017064)
		(width 0.1143)
		(layer "In4.Cu")
		(net "P5E_CPU0_G3_TX_DP<0>")
	)
	(arc
		(start 373.596154 -234.45978)
		(mid 373.499019 -234.562649)
		(end 373.447056 -234.694222)
		(width 0.1143)
		(layer "In4.Cu")
		(net "P5E_CPU0_G3_TX_DP<0>")
	)
	(arc
		(start 374.60682 -227.009706)
		(mid 374.850147 -227.474272)
		(end 374.60682 -227.938838)
		(width 0.1143)
		(layer "In4.Cu")
		(net "P5E_CPU0_G3_TX_DP<0>")
	)
	(arc
		(start 375.320306 -225.044254)
		(mid 375.255791 -225.306473)
		(end 375.076974 -225.50882)
		(width 0.1143)
		(layer "In4.Cu")
		(net "P5E_CPU0_G3_TX_DP<0>")
	)
	(arc
		(start 374.537224 -226.359466)
		(mid 374.380247 -226.664266)
		(end 374.537224 -226.969066)
		(width 0.1143)
		(layer "In4.Cu")
		(net "P5E_CPU0_G3_TX_DP<0>")
	)
	(arc
		(start 375.808748 -224.14357)
		(mid 375.795498 -224.199328)
		(end 375.789698 -224.256346)
		(width 0.1143)
		(layer "In4.Cu")
		(net "P5E_CPU0_G3_TX_DP<0>")
	)
	(arc
		(start 374.380252 -233.14406)
		(mid 374.315737 -233.406279)
		(end 374.13692 -233.608626)
		(width 0.1143)
		(layer "In4.Cu")
		(net "P5E_CPU0_G3_TX_DP<0>")
	)
	(arc
		(start 376.416062 -223.11995)
		(mid 376.301386 -223.253284)
		(end 376.260106 -223.424242)
		(width 0.1143)
		(layer "In4.Cu")
		(net "P5E_CPU0_G3_TX_DP<0>")
	)
	(arc
		(start 374.535192 -229.600506)
		(mid 374.421263 -229.733653)
		(end 374.380252 -229.904036)
		(width 0.1143)
		(layer "In4.Cu")
		(net "P5E_CPU0_G3_TX_DP<0>")
	)
	(arc
		(start 374.537224 -232.83926)
		(mid 374.421797 -232.972636)
		(end 374.380252 -233.14406)
		(width 0.1143)
		(layer "In4.Cu")
		(net "P5E_CPU0_G3_TX_DP<0>")
	)
	(arc
		(start 376.260106 -223.424242)
		(mid 376.195591 -223.686461)
		(end 376.016774 -223.888808)
		(width 0.1143)
		(layer "In4.Cu")
		(net "P5E_CPU0_G3_TX_DP<0>")
	)
	(arc
		(start 377.200414 -221.80423)
		(mid 377.135899 -222.066449)
		(end 376.957082 -222.268796)
		(width 0.1143)
		(layer "In4.Cu")
		(net "P5E_CPU0_G3_TX_DP<0>")
	)
	(arc
		(start 375.006108 -225.549968)
		(mid 374.891432 -225.683302)
		(end 374.850152 -225.85426)
		(width 0.1143)
		(layer "In4.Cu")
		(net "P5E_CPU0_G3_TX_DP<0>")
	)
	(arc
		(start 375.076974 -231.059482)
		(mid 375.320301 -231.524048)
		(end 375.076974 -231.988614)
		(width 0.1143)
		(layer "In4.Cu")
		(net "P5E_CPU0_G3_TX_DP<0>")
	)
	(arc
		(start 375.789698 -224.256346)
		(mid 375.720264 -224.506188)
		(end 375.54662 -224.698814)
		(width 0.1143)
		(layer "In4.Cu")
		(net "P5E_CPU0_G3_TX_DP<0>")
	)
	(arc
		(start 374.60428 -230.247952)
		(mid 374.784932 -230.450697)
		(end 374.850152 -230.714296)
		(width 0.1143)
		(layer "In4.Cu")
		(net "P5E_CPU0_G3_TX_DP<0>")
	)
	(arc
		(start 374.537224 -227.979478)
		(mid 374.380247 -228.284278)
		(end 374.537224 -228.589078)
		(width 0.1143)
		(layer "In4.Cu")
		(net "P5E_CPU0_G3_TX_DP<0>")
	)
	(arc
		(start 374.60682 -228.629718)
		(mid 374.850147 -229.094284)
		(end 374.60682 -229.55885)
		(width 0.1143)
		(layer "In4.Cu")
		(net "P5E_CPU0_G3_TX_DP<0>")
	)
	(arc
		(start 373.897398 -233.97337)
		(mid 373.825208 -234.243441)
		(end 373.627904 -234.441492)
		(width 0.1143)
		(layer "In4.Cu")
		(net "P5E_CPU0_G3_TX_DP<0>")
	)
	(arc
		(start 374.085104 -233.638852)
		(mid 373.947761 -233.776143)
		(end 373.897398 -233.963718)
		(width 0.1143)
		(layer "In4.Cu")
		(net "P5E_CPU0_G3_TX_DP<0>")
	)
	(arc
		(start 376.886216 -222.309944)
		(mid 376.77154 -222.443278)
		(end 376.73026 -222.614236)
		(width 0.1143)
		(layer "In4.Cu")
		(net "P5E_CPU0_G3_TX_DP<0>")
	)
	(arc
		(start 376.73026 -222.614236)
		(mid 376.665745 -222.876455)
		(end 376.486928 -223.078802)
		(width 0.1143)
		(layer "In4.Cu")
		(net "P5E_CPU0_G3_TX_DP<0>")
	)
	(arc
		(start 375.006108 -232.029762)
		(mid 374.891432 -232.163096)
		(end 374.850152 -232.334054)
		(width 0.1143)
		(layer "In4.Cu")
		(net "P5E_CPU0_G3_TX_DP<0>")
	)
	(arc
		(start 375.477278 -224.739454)
		(mid 375.361851 -224.87283)
		(end 375.320306 -225.044254)
		(width 0.1143)
		(layer "In4.Cu")
		(net "P5E_CPU0_G3_TX_DP<0>")
	)
	(arc
		(start 375.944892 -223.930718)
		(mid 375.862608 -224.02806)
		(end 375.808748 -224.14357)
		(width 0.1143)
		(layer "In4.Cu")
		(net "P5E_CPU0_G3_TX_DP<0>")
	)
	(arc
		(start 374.380252 -229.904036)
		(mid 374.421801 -230.075458)
		(end 374.537224 -230.208836)
		(width 0.1143)
		(layer "In4.Cu")
		(net "P5E_CPU0_G3_TX_DP<0>")
	)
	(arc
		(start 374.850152 -225.85426)
		(mid 374.785637 -226.116479)
		(end 374.60682 -226.318826)
		(width 0.1143)
		(layer "In4.Cu")
		(net "P5E_CPU0_G3_TX_DP<0>")
	)
	(segment
		(start 407.067258 -17.342612)
		(end 406.796748 -17.613122)
		(width 0.12954)
		(layer "F.Cu")
		(net "P5E_CPU0_G3_TX_DN<9>")
	)
	(segment
		(start 407.067258 -16.662908)
		(end 407.067258 -17.342612)
		(width 0.12954)
		(layer "F.Cu")
		(net "P5E_CPU0_G3_TX_DN<9>")
	)
	(segment
		(start 406.771348 -16.366998)
		(end 407.067258 -16.662908)
		(width 0.12954)
		(layer "F.Cu")
		(net "P5E_CPU0_G3_TX_DN<9>")
	)
	(segment
		(start 366.767872 -235.03001)
		(end 367.234724 -234.764072)
		(width 0.12954)
		(layer "F.Cu")
		(net "P5E_CPU0_G3_TX_DN<9>")
	)
	(segment
		(start 366.94618 -222.940118)
		(end 366.945418 -222.940626)
		(width 0.1143)
		(layer "In4.Cu")
		(net "P5E_CPU0_G3_TX_DN<9>")
	)
	(segment
		(start 366.481868 -231.846628)
		(end 366.481614 -231.846628)
		(width 0.1143)
		(layer "In4.Cu")
		(net "P5E_CPU0_G3_TX_DN<9>")
	)
	(segment
		(start 366.949228 -223.910144)
		(end 366.950752 -223.91116)
		(width 0.1143)
		(layer "In4.Cu")
		(net "P5E_CPU0_G3_TX_DN<9>")
	)
	(segment
		(start 366.693958 -221.128844)
		(end 366.693958 -221.308676)
		(width 0.1143)
		(layer "In4.Cu")
		(net "P5E_CPU0_G3_TX_DN<9>")
	)
	(segment
		(start 366.042448 -226.15906)
		(end 365.972852 -226.1997)
		(width 0.1143)
		(layer "In4.Cu")
		(net "P5E_CPU0_G3_TX_DN<9>")
	)
	(segment
		(start 361.516676 -206.036164)
		(end 366.648238 -214.680292)
		(width 0.14224)
		(layer "In4.Cu")
		(net "P5E_CPU0_G3_TX_DN<9>")
	)
	(segment
		(start 366.95253 -222.936308)
		(end 366.951768 -222.936816)
		(width 0.1143)
		(layer "In4.Cu")
		(net "P5E_CPU0_G3_TX_DN<9>")
	)
	(segment
		(start 366.983518 -224.53854)
		(end 366.942116 -224.562416)
		(width 0.1143)
		(layer "In4.Cu")
		(net "P5E_CPU0_G3_TX_DN<9>")
	)
	(segment
		(start 366.951768 -222.936816)
		(end 366.950752 -222.937324)
		(width 0.1143)
		(layer "In4.Cu")
		(net "P5E_CPU0_G3_TX_DN<9>")
	)
	(segment
		(start 366.46485 -232.811574)
		(end 366.47374 -232.816654)
		(width 0.1143)
		(layer "In4.Cu")
		(net "P5E_CPU0_G3_TX_DN<9>")
	)
	(segment
		(start 366.9538 -223.912938)
		(end 366.955324 -223.9137)
		(width 0.1143)
		(layer "In4.Cu")
		(net "P5E_CPU0_G3_TX_DN<9>")
	)
	(segment
		(start 366.478312 -232.819448)
		(end 366.479328 -232.819956)
		(width 0.1143)
		(layer "In4.Cu")
		(net "P5E_CPU0_G3_TX_DN<9>")
	)
	(segment
		(start 366.48898 -232.82529)
		(end 366.489742 -232.825798)
		(width 0.1143)
		(layer "In4.Cu")
		(net "P5E_CPU0_G3_TX_DN<9>")
	)
	(segment
		(start 366.48263 -225.366326)
		(end 366.481868 -225.366834)
		(width 0.1143)
		(layer "In4.Cu")
		(net "P5E_CPU0_G3_TX_DN<9>")
	)
	(segment
		(start 366.481868 -225.366834)
		(end 366.480852 -225.367342)
		(width 0.1143)
		(layer "In4.Cu")
		(net "P5E_CPU0_G3_TX_DN<9>")
	)
	(segment
		(start 366.47374 -232.816654)
		(end 366.47755 -232.81894)
		(width 0.1143)
		(layer "In4.Cu")
		(net "P5E_CPU0_G3_TX_DN<9>")
	)
	(segment
		(start 407.087578 -20.44954)
		(end 323.661024 -125.061472)
		(width 0.14224)
		(layer "In4.Cu")
		(net "P5E_CPU0_G3_TX_DN<9>")
	)
	(segment
		(start 366.442752 -231.178862)
		(end 366.511586 -231.21874)
		(width 0.1143)
		(layer "In4.Cu")
		(net "P5E_CPU0_G3_TX_DN<9>")
	)
	(segment
		(start 320.243708 -131.029456)
		(end 315.882274 -142.378684)
		(width 0.14224)
		(layer "In4.Cu")
		(net "P5E_CPU0_G3_TX_DN<9>")
	)
	(segment
		(start 367.139728 -233.954066)
		(end 367.139474 -233.954066)
		(width 0.1143)
		(layer "In4.Cu")
		(net "P5E_CPU0_G3_TX_DN<9>")
	)
	(segment
		(start 366.648238 -221.083124)
		(end 366.693958 -221.128844)
		(width 0.1143)
		(layer "In4.Cu")
		(net "P5E_CPU0_G3_TX_DN<9>")
	)
	(segment
		(start 366.950752 -222.937324)
		(end 366.949228 -222.93834)
		(width 0.1143)
		(layer "In4.Cu")
		(net "P5E_CPU0_G3_TX_DN<9>")
	)
	(segment
		(start 365.972852 -228.748844)
		(end 366.042448 -228.789484)
		(width 0.1143)
		(layer "In4.Cu")
		(net "P5E_CPU0_G3_TX_DN<9>")
	)
	(segment
		(start 366.479328 -225.368358)
		(end 366.47755 -225.369374)
		(width 0.1143)
		(layer "In4.Cu")
		(net "P5E_CPU0_G3_TX_DN<9>")
	)
	(segment
		(start 366.952022 -233.631486)
		(end 366.983772 -233.650028)
		(width 0.1143)
		(layer "In4.Cu")
		(net "P5E_CPU0_G3_TX_DN<9>")
	)
	(segment
		(start 366.011968 -229.41661)
		(end 365.972852 -229.43947)
		(width 0.1143)
		(layer "In4.Cu")
		(net "P5E_CPU0_G3_TX_DN<9>")
	)
	(segment
		(start 311.45607 -157.937962)
		(end 311.45607 -162.370008)
		(width 0.14224)
		(layer "In4.Cu")
		(net "P5E_CPU0_G3_TX_DN<9>")
	)
	(segment
		(start 323.234304 -174.651162)
		(end 323.304916 -174.721774)
		(width 0.14224)
		(layer "In4.Cu")
		(net "P5E_CPU0_G3_TX_DN<9>")
	)
	(segment
		(start 366.47755 -225.369374)
		(end 366.47628 -225.370136)
		(width 0.1143)
		(layer "In4.Cu")
		(net "P5E_CPU0_G3_TX_DN<9>")
	)
	(segment
		(start 311.45607 -162.370008)
		(end 313.400948 -167.066214)
		(width 0.14224)
		(layer "In4.Cu")
		(net "P5E_CPU0_G3_TX_DN<9>")
	)
	(segment
		(start 366.487456 -232.824528)
		(end 366.48898 -232.82529)
		(width 0.1143)
		(layer "In4.Cu")
		(net "P5E_CPU0_G3_TX_DN<9>")
	)
	(segment
		(start 315.882274 -142.378684)
		(end 311.62117 -157.107382)
		(width 0.14224)
		(layer "In4.Cu")
		(net "P5E_CPU0_G3_TX_DN<9>")
	)
	(segment
		(start 366.956086 -223.914208)
		(end 366.957102 -223.914716)
		(width 0.1143)
		(layer "In4.Cu")
		(net "P5E_CPU0_G3_TX_DN<9>")
	)
	(segment
		(start 311.62117 -157.107382)
		(end 311.45607 -157.937962)
		(width 0.14224)
		(layer "In4.Cu")
		(net "P5E_CPU0_G3_TX_DN<9>")
	)
	(segment
		(start 366.955324 -223.9137)
		(end 366.956086 -223.914208)
		(width 0.1143)
		(layer "In4.Cu")
		(net "P5E_CPU0_G3_TX_DN<9>")
	)
	(segment
		(start 366.94745 -222.939356)
		(end 366.94618 -222.940118)
		(width 0.1143)
		(layer "In4.Cu")
		(net "P5E_CPU0_G3_TX_DN<9>")
	)
	(segment
		(start 322.857368 -174.357284)
		(end 323.234304 -174.651162)
		(width 0.14224)
		(layer "In4.Cu")
		(net "P5E_CPU0_G3_TX_DN<9>")
	)
	(segment
		(start 366.950752 -223.91116)
		(end 366.951768 -223.911668)
		(width 0.1143)
		(layer "In4.Cu")
		(net "P5E_CPU0_G3_TX_DN<9>")
	)
	(segment
		(start 366.48263 -232.821734)
		(end 366.485424 -232.823258)
		(width 0.1143)
		(layer "In4.Cu")
		(net "P5E_CPU0_G3_TX_DN<9>")
	)
	(segment
		(start 366.879632 -222.245174)
		(end 366.912398 -222.268796)
		(width 0.1143)
		(layer "In4.Cu")
		(net "P5E_CPU0_G3_TX_DN<9>")
	)
	(segment
		(start 366.489742 -232.825798)
		(end 366.495584 -232.8291)
		(width 0.1143)
		(layer "In4.Cu")
		(net "P5E_CPU0_G3_TX_DN<9>")
	)
	(segment
		(start 366.47628 -225.370136)
		(end 366.475518 -225.370644)
		(width 0.1143)
		(layer "In4.Cu")
		(net "P5E_CPU0_G3_TX_DN<9>")
	)
	(segment
		(start 366.68202 -233.153204)
		(end 366.68202 -233.163364)
		(width 0.1143)
		(layer "In4.Cu")
		(net "P5E_CPU0_G3_TX_DN<9>")
	)
	(segment
		(start 366.945418 -222.940626)
		(end 366.912652 -222.959676)
		(width 0.1143)
		(layer "In4.Cu")
		(net "P5E_CPU0_G3_TX_DN<9>")
	)
	(segment
		(start 366.951768 -223.911668)
		(end 366.95253 -223.912176)
		(width 0.1143)
		(layer "In4.Cu")
		(net "P5E_CPU0_G3_TX_DN<9>")
	)
	(segment
		(start 366.042448 -227.779072)
		(end 365.972852 -227.819712)
		(width 0.1143)
		(layer "In4.Cu")
		(net "P5E_CPU0_G3_TX_DN<9>")
	)
	(segment
		(start 366.693958 -221.308676)
		(end 366.669574 -221.33306)
		(width 0.1143)
		(layer "In4.Cu")
		(net "P5E_CPU0_G3_TX_DN<9>")
	)
	(segment
		(start 366.949228 -222.93834)
		(end 366.94745 -222.939356)
		(width 0.1143)
		(layer "In4.Cu")
		(net "P5E_CPU0_G3_TX_DN<9>")
	)
	(segment
		(start 366.983518 -222.918528)
		(end 366.9538 -222.935546)
		(width 0.1143)
		(layer "In4.Cu")
		(net "P5E_CPU0_G3_TX_DN<9>")
	)
	(segment
		(start 366.480852 -225.367342)
		(end 366.479328 -225.368358)
		(width 0.1143)
		(layer "In4.Cu")
		(net "P5E_CPU0_G3_TX_DN<9>")
	)
	(segment
		(start 366.912652 -223.888808)
		(end 366.949228 -223.910144)
		(width 0.1143)
		(layer "In4.Cu")
		(net "P5E_CPU0_G3_TX_DN<9>")
	)
	(segment
		(start 366.481868 -232.82148)
		(end 366.48263 -232.821734)
		(width 0.1143)
		(layer "In4.Cu")
		(net "P5E_CPU0_G3_TX_DN<9>")
	)
	(segment
		(start 367.602516 -234.694222)
		(end 367.532666 -234.764072)
		(width 0.1143)
		(layer "In4.Cu")
		(net "P5E_CPU0_G3_TX_DN<9>")
	)
	(segment
		(start 366.47755 -232.81894)
		(end 366.478312 -232.819448)
		(width 0.1143)
		(layer "In4.Cu")
		(net "P5E_CPU0_G3_TX_DN<9>")
	)
	(segment
		(start 366.648238 -214.680292)
		(end 366.648238 -221.083124)
		(width 0.14224)
		(layer "In4.Cu")
		(net "P5E_CPU0_G3_TX_DN<9>")
	)
	(segment
		(start 366.660684 -225.051366)
		(end 366.660684 -225.058986)
		(width 0.1143)
		(layer "In4.Cu")
		(net "P5E_CPU0_G3_TX_DN<9>")
	)
	(segment
		(start 366.482884 -231.84612)
		(end 366.481868 -231.846628)
		(width 0.1143)
		(layer "In4.Cu")
		(net "P5E_CPU0_G3_TX_DN<9>")
	)
	(segment
		(start 317.450978 -171.116752)
		(end 322.857368 -174.357284)
		(width 0.14224)
		(layer "In4.Cu")
		(net "P5E_CPU0_G3_TX_DN<9>")
	)
	(segment
		(start 366.486694 -232.82402)
		(end 366.487456 -232.824528)
		(width 0.1143)
		(layer "In4.Cu")
		(net "P5E_CPU0_G3_TX_DN<9>")
	)
	(segment
		(start 323.304916 -174.721774)
		(end 361.516676 -206.036164)
		(width 0.14224)
		(layer "In4.Cu")
		(net "P5E_CPU0_G3_TX_DN<9>")
	)
	(segment
		(start 366.485424 -232.823258)
		(end 366.486694 -232.82402)
		(width 0.1143)
		(layer "In4.Cu")
		(net "P5E_CPU0_G3_TX_DN<9>")
	)
	(segment
		(start 313.400948 -167.066214)
		(end 317.450978 -171.116752)
		(width 0.14224)
		(layer "In4.Cu")
		(net "P5E_CPU0_G3_TX_DN<9>")
	)
	(segment
		(start 366.957864 -223.915224)
		(end 366.95888 -223.915732)
		(width 0.1143)
		(layer "In4.Cu")
		(net "P5E_CPU0_G3_TX_DN<9>")
	)
	(segment
		(start 365.972852 -227.128832)
		(end 366.042448 -227.169472)
		(width 0.1143)
		(layer "In4.Cu")
		(net "P5E_CPU0_G3_TX_DN<9>")
	)
	(segment
		(start 366.9538 -222.935546)
		(end 366.95253 -222.936308)
		(width 0.1143)
		(layer "In4.Cu")
		(net "P5E_CPU0_G3_TX_DN<9>")
	)
	(segment
		(start 366.957102 -223.914716)
		(end 366.957864 -223.915224)
		(width 0.1143)
		(layer "In4.Cu")
		(net "P5E_CPU0_G3_TX_DN<9>")
	)
	(segment
		(start 366.669574 -221.33306)
		(end 366.669574 -221.83471)
		(width 0.1143)
		(layer "In4.Cu")
		(net "P5E_CPU0_G3_TX_DN<9>")
	)
	(segment
		(start 366.95888 -223.915732)
		(end 366.983518 -223.929956)
		(width 0.1143)
		(layer "In4.Cu")
		(net "P5E_CPU0_G3_TX_DN<9>")
	)
	(segment
		(start 366.475518 -225.370644)
		(end 366.442752 -225.389694)
		(width 0.1143)
		(layer "In4.Cu")
		(net "P5E_CPU0_G3_TX_DN<9>")
	)
	(segment
		(start 366.479328 -232.819956)
		(end 366.480852 -232.820972)
		(width 0.1143)
		(layer "In4.Cu")
		(net "P5E_CPU0_G3_TX_DN<9>")
	)
	(segment
		(start 407.087578 -17.903952)
		(end 407.087578 -20.44954)
		(width 0.14224)
		(layer "In4.Cu")
		(net "P5E_CPU0_G3_TX_DN<9>")
	)
	(segment
		(start 366.04448 -229.397814)
		(end 366.011968 -229.41661)
		(width 0.1143)
		(layer "In4.Cu")
		(net "P5E_CPU0_G3_TX_DN<9>")
	)
	(segment
		(start 406.796748 -17.613122)
		(end 407.087578 -17.903952)
		(width 0.14224)
		(layer "In4.Cu")
		(net "P5E_CPU0_G3_TX_DN<9>")
	)
	(segment
		(start 365.975392 -230.37038)
		(end 366.042448 -230.409496)
		(width 0.1143)
		(layer "In4.Cu")
		(net "P5E_CPU0_G3_TX_DN<9>")
	)
	(segment
		(start 366.480852 -232.820972)
		(end 366.481868 -232.82148)
		(width 0.1143)
		(layer "In4.Cu")
		(net "P5E_CPU0_G3_TX_DN<9>")
	)
	(segment
		(start 366.912398 -222.268796)
		(end 366.983518 -222.309944)
		(width 0.1143)
		(layer "In4.Cu")
		(net "P5E_CPU0_G3_TX_DN<9>")
	)
	(segment
		(start 366.95253 -223.912176)
		(end 366.9538 -223.912938)
		(width 0.1143)
		(layer "In4.Cu")
		(net "P5E_CPU0_G3_TX_DN<9>")
	)
	(segment
		(start 323.661024 -125.061472)
		(end 320.243708 -131.029456)
		(width 0.14224)
		(layer "In4.Cu")
		(net "P5E_CPU0_G3_TX_DN<9>")
	)
	(segment
		(start 367.532666 -234.764072)
		(end 367.234724 -234.764072)
		(width 0.1143)
		(layer "In4.Cu")
		(net "P5E_CPU0_G3_TX_DN<9>")
	)
	(segment
		(start 367.382806 -234.418632)
		(end 367.452402 -234.459272)
		(width 0.1143)
		(layer "In4.Cu")
		(net "P5E_CPU0_G3_TX_DN<9>")
	)
	(arc
		(start 366.19942 -230.714296)
		(mid 366.263935 -230.976515)
		(end 366.442752 -231.178862)
		(width 0.1143)
		(layer "In4.Cu")
		(net "P5E_CPU0_G3_TX_DN<9>")
	)
	(arc
		(start 366.983518 -223.929956)
		(mid 367.139446 -224.234248)
		(end 366.983518 -224.53854)
		(width 0.1143)
		(layer "In4.Cu")
		(net "P5E_CPU0_G3_TX_DN<9>")
	)
	(arc
		(start 366.19942 -225.85426)
		(mid 366.157871 -226.025682)
		(end 366.042448 -226.15906)
		(width 0.1143)
		(layer "In4.Cu")
		(net "P5E_CPU0_G3_TX_DN<9>")
	)
	(arc
		(start 366.042448 -228.789484)
		(mid 366.157875 -228.92286)
		(end 366.19942 -229.094284)
		(width 0.1143)
		(layer "In4.Cu")
		(net "P5E_CPU0_G3_TX_DN<9>")
	)
	(arc
		(start 365.972852 -226.1997)
		(mid 365.729525 -226.664266)
		(end 365.972852 -227.128832)
		(width 0.1143)
		(layer "In4.Cu")
		(net "P5E_CPU0_G3_TX_DN<9>")
	)
	(arc
		(start 366.983772 -233.650028)
		(mid 367.098448 -233.783219)
		(end 367.139728 -233.954066)
		(width 0.1143)
		(layer "In4.Cu")
		(net "P5E_CPU0_G3_TX_DN<9>")
	)
	(arc
		(start 366.511586 -231.21874)
		(mid 366.668502 -231.540306)
		(end 366.482884 -231.84612)
		(width 0.1143)
		(layer "In4.Cu")
		(net "P5E_CPU0_G3_TX_DN<9>")
	)
	(arc
		(start 365.972852 -227.819712)
		(mid 365.729525 -228.284278)
		(end 365.972852 -228.748844)
		(width 0.1143)
		(layer "In4.Cu")
		(net "P5E_CPU0_G3_TX_DN<9>")
	)
	(arc
		(start 366.481614 -231.846628)
		(mid 366.453031 -231.863061)
		(end 366.42548 -231.881172)
		(width 0.1143)
		(layer "In4.Cu")
		(net "P5E_CPU0_G3_TX_DN<9>")
	)
	(arc
		(start 366.669574 -221.83471)
		(mid 366.72502 -222.065324)
		(end 366.879632 -222.245174)
		(width 0.1143)
		(layer "In4.Cu")
		(net "P5E_CPU0_G3_TX_DN<9>")
	)
	(arc
		(start 366.912652 -222.959676)
		(mid 366.669325 -223.424242)
		(end 366.912652 -223.888808)
		(width 0.1143)
		(layer "In4.Cu")
		(net "P5E_CPU0_G3_TX_DN<9>")
	)
	(arc
		(start 366.042448 -227.169472)
		(mid 366.199425 -227.474272)
		(end 366.042448 -227.779072)
		(width 0.1143)
		(layer "In4.Cu")
		(net "P5E_CPU0_G3_TX_DN<9>")
	)
	(arc
		(start 367.139474 -233.954066)
		(mid 367.203989 -234.216285)
		(end 367.382806 -234.418632)
		(width 0.1143)
		(layer "In4.Cu")
		(net "P5E_CPU0_G3_TX_DN<9>")
	)
	(arc
		(start 366.42548 -231.881172)
		(mid 366.190916 -232.35716)
		(end 366.46485 -232.811574)
		(width 0.1143)
		(layer "In4.Cu")
		(net "P5E_CPU0_G3_TX_DN<9>")
	)
	(arc
		(start 367.452402 -234.459272)
		(mid 367.550167 -234.562248)
		(end 367.602516 -234.694222)
		(width 0.1143)
		(layer "In4.Cu")
		(net "P5E_CPU0_G3_TX_DN<9>")
	)
	(arc
		(start 366.495584 -232.8291)
		(mid 366.632096 -232.96625)
		(end 366.68202 -233.153204)
		(width 0.1143)
		(layer "In4.Cu")
		(net "P5E_CPU0_G3_TX_DN<9>")
	)
	(arc
		(start 366.442752 -225.389694)
		(mid 366.263939 -225.592044)
		(end 366.19942 -225.85426)
		(width 0.1143)
		(layer "In4.Cu")
		(net "P5E_CPU0_G3_TX_DN<9>")
	)
	(arc
		(start 365.972852 -229.43947)
		(mid 365.794039 -229.64182)
		(end 365.72952 -229.904036)
		(width 0.1143)
		(layer "In4.Cu")
		(net "P5E_CPU0_G3_TX_DN<9>")
	)
	(arc
		(start 366.68202 -233.163364)
		(mid 366.754362 -233.433562)
		(end 366.952022 -233.631486)
		(width 0.1143)
		(layer "In4.Cu")
		(net "P5E_CPU0_G3_TX_DN<9>")
	)
	(arc
		(start 366.042448 -230.409496)
		(mid 366.157875 -230.542872)
		(end 366.19942 -230.714296)
		(width 0.1143)
		(layer "In4.Cu")
		(net "P5E_CPU0_G3_TX_DN<9>")
	)
	(arc
		(start 366.19942 -229.094284)
		(mid 366.158454 -229.26469)
		(end 366.04448 -229.397814)
		(width 0.1143)
		(layer "In4.Cu")
		(net "P5E_CPU0_G3_TX_DN<9>")
	)
	(arc
		(start 366.660684 -225.058986)
		(mid 366.61296 -225.236588)
		(end 366.48263 -225.366326)
		(width 0.1143)
		(layer "In4.Cu")
		(net "P5E_CPU0_G3_TX_DN<9>")
	)
	(arc
		(start 366.942116 -224.562416)
		(mid 366.736048 -224.769279)
		(end 366.660684 -225.051366)
		(width 0.1143)
		(layer "In4.Cu")
		(net "P5E_CPU0_G3_TX_DN<9>")
	)
	(arc
		(start 365.72952 -229.904036)
		(mid 365.794756 -230.167627)
		(end 365.975392 -230.37038)
		(width 0.1143)
		(layer "In4.Cu")
		(net "P5E_CPU0_G3_TX_DN<9>")
	)
	(arc
		(start 366.983518 -222.309944)
		(mid 367.139446 -222.614236)
		(end 366.983518 -222.918528)
		(width 0.1143)
		(layer "In4.Cu")
		(net "P5E_CPU0_G3_TX_DN<9>")
	)
	(segment
		(start 409.862274 -18.187924)
		(end 409.862274 -18.86585)
		(width 0.12954)
		(layer "F.Cu")
		(net "P5E_CPU0_G3_TX_DN<8>")
	)
	(segment
		(start 409.862274 -18.86585)
		(end 409.591764 -19.13636)
		(width 0.12954)
		(layer "F.Cu")
		(net "P5E_CPU0_G3_TX_DN<8>")
	)
	(segment
		(start 409.565348 -17.890998)
		(end 409.862274 -18.187924)
		(width 0.12954)
		(layer "F.Cu")
		(net "P5E_CPU0_G3_TX_DN<8>")
	)
	(segment
		(start 366.767872 -231.789986)
		(end 367.234724 -231.524048)
		(width 0.12954)
		(layer "F.Cu")
		(net "P5E_CPU0_G3_TX_DN<8>")
	)
	(segment
		(start 367.888266 -222.289624)
		(end 367.889282 -222.290132)
		(width 0.1143)
		(layer "In4.Cu")
		(net "P5E_CPU0_G3_TX_DN<8>")
	)
	(segment
		(start 367.532666 -231.524048)
		(end 367.234724 -231.524048)
		(width 0.1143)
		(layer "In4.Cu")
		(net "P5E_CPU0_G3_TX_DN<8>")
	)
	(segment
		(start 367.852706 -222.268796)
		(end 367.880138 -222.284798)
		(width 0.1143)
		(layer "In4.Cu")
		(net "P5E_CPU0_G3_TX_DN<8>")
	)
	(segment
		(start 367.598452 -221.083124)
		(end 367.644172 -221.128844)
		(width 0.1143)
		(layer "In4.Cu")
		(net "P5E_CPU0_G3_TX_DN<8>")
	)
	(segment
		(start 324.359524 -174.253652)
		(end 362.087922 -205.172056)
		(width 0.14224)
		(layer "In4.Cu")
		(net "P5E_CPU0_G3_TX_DN<8>")
	)
	(segment
		(start 366.912652 -227.128832)
		(end 366.982248 -227.169472)
		(width 0.1143)
		(layer "In4.Cu")
		(net "P5E_CPU0_G3_TX_DN<8>")
	)
	(segment
		(start 324.05066 -126.305818)
		(end 321.088004 -131.431792)
		(width 0.14224)
		(layer "In4.Cu")
		(net "P5E_CPU0_G3_TX_DN<8>")
	)
	(segment
		(start 314.190888 -166.537132)
		(end 318.025018 -170.372024)
		(width 0.14224)
		(layer "In4.Cu")
		(net "P5E_CPU0_G3_TX_DN<8>")
	)
	(segment
		(start 312.38825 -158.030926)
		(end 312.38825 -162.184334)
		(width 0.14224)
		(layer "In4.Cu")
		(net "P5E_CPU0_G3_TX_DN<8>")
	)
	(segment
		(start 366.912652 -228.748844)
		(end 366.982248 -228.789484)
		(width 0.1143)
		(layer "In4.Cu")
		(net "P5E_CPU0_G3_TX_DN<8>")
	)
	(segment
		(start 367.453418 -225.348546)
		(end 367.4237 -225.365564)
		(width 0.1143)
		(layer "In4.Cu")
		(net "P5E_CPU0_G3_TX_DN<8>")
	)
	(segment
		(start 367.602516 -231.454198)
		(end 367.532666 -231.524048)
		(width 0.1143)
		(layer "In4.Cu")
		(net "P5E_CPU0_G3_TX_DN<8>")
	)
	(segment
		(start 366.982248 -226.15906)
		(end 366.912652 -226.1997)
		(width 0.1143)
		(layer "In4.Cu")
		(net "P5E_CPU0_G3_TX_DN<8>")
	)
	(segment
		(start 367.4237 -225.365564)
		(end 367.42243 -225.366326)
		(width 0.1143)
		(layer "In4.Cu")
		(net "P5E_CPU0_G3_TX_DN<8>")
	)
	(segment
		(start 318.025018 -170.372024)
		(end 323.900546 -173.895004)
		(width 0.14224)
		(layer "In4.Cu")
		(net "P5E_CPU0_G3_TX_DN<8>")
	)
	(segment
		(start 316.766702 -142.677134)
		(end 312.527442 -157.330648)
		(width 0.14224)
		(layer "In4.Cu")
		(net "P5E_CPU0_G3_TX_DN<8>")
	)
	(segment
		(start 367.852706 -223.888808)
		(end 367.922302 -223.929448)
		(width 0.1143)
		(layer "In4.Cu")
		(net "P5E_CPU0_G3_TX_DN<8>")
	)
	(segment
		(start 366.982248 -227.779072)
		(end 366.912652 -227.819712)
		(width 0.1143)
		(layer "In4.Cu")
		(net "P5E_CPU0_G3_TX_DN<8>")
	)
	(segment
		(start 366.951768 -229.41661)
		(end 366.912652 -229.43947)
		(width 0.1143)
		(layer "In4.Cu")
		(net "P5E_CPU0_G3_TX_DN<8>")
	)
	(segment
		(start 409.591764 -19.13636)
		(end 409.882594 -19.42719)
		(width 0.14224)
		(layer "In4.Cu")
		(net "P5E_CPU0_G3_TX_DN<8>")
	)
	(segment
		(start 367.644172 -221.128844)
		(end 367.644172 -221.308676)
		(width 0.1143)
		(layer "In4.Cu")
		(net "P5E_CPU0_G3_TX_DN<8>")
	)
	(segment
		(start 367.890806 -222.291148)
		(end 367.891822 -222.291656)
		(width 0.1143)
		(layer "In4.Cu")
		(net "P5E_CPU0_G3_TX_DN<8>")
	)
	(segment
		(start 312.38825 -162.184334)
		(end 314.190888 -166.537132)
		(width 0.14224)
		(layer "In4.Cu")
		(net "P5E_CPU0_G3_TX_DN<8>")
	)
	(segment
		(start 367.644172 -221.308676)
		(end 367.609374 -221.343474)
		(width 0.1143)
		(layer "In4.Cu")
		(net "P5E_CPU0_G3_TX_DN<8>")
	)
	(segment
		(start 367.42243 -225.366326)
		(end 367.421668 -225.366834)
		(width 0.1143)
		(layer "In4.Cu")
		(net "P5E_CPU0_G3_TX_DN<8>")
	)
	(segment
		(start 323.900546 -173.895004)
		(end 324.130416 -174.074582)
		(width 0.14224)
		(layer "In4.Cu")
		(net "P5E_CPU0_G3_TX_DN<8>")
	)
	(segment
		(start 367.885726 -222.2881)
		(end 367.888266 -222.289624)
		(width 0.1143)
		(layer "In4.Cu")
		(net "P5E_CPU0_G3_TX_DN<8>")
	)
	(segment
		(start 367.880138 -222.284798)
		(end 367.881154 -222.285306)
		(width 0.1143)
		(layer "In4.Cu")
		(net "P5E_CPU0_G3_TX_DN<8>")
	)
	(segment
		(start 366.98428 -229.397814)
		(end 366.951768 -229.41661)
		(width 0.1143)
		(layer "In4.Cu")
		(net "P5E_CPU0_G3_TX_DN<8>")
	)
	(segment
		(start 324.130416 -174.074836)
		(end 324.359524 -174.253652)
		(width 0.14224)
		(layer "In4.Cu")
		(net "P5E_CPU0_G3_TX_DN<8>")
	)
	(segment
		(start 366.915192 -230.37038)
		(end 366.982248 -230.409496)
		(width 0.1143)
		(layer "In4.Cu")
		(net "P5E_CPU0_G3_TX_DN<8>")
	)
	(segment
		(start 367.421668 -225.366834)
		(end 367.390172 -225.385122)
		(width 0.1143)
		(layer "In4.Cu")
		(net "P5E_CPU0_G3_TX_DN<8>")
	)
	(segment
		(start 362.087922 -205.172056)
		(end 367.598452 -214.452962)
		(width 0.14224)
		(layer "In4.Cu")
		(net "P5E_CPU0_G3_TX_DN<8>")
	)
	(segment
		(start 367.891822 -222.291656)
		(end 367.923572 -222.309944)
		(width 0.1143)
		(layer "In4.Cu")
		(net "P5E_CPU0_G3_TX_DN<8>")
	)
	(segment
		(start 321.088004 -131.431792)
		(end 316.766702 -142.677134)
		(width 0.14224)
		(layer "In4.Cu")
		(net "P5E_CPU0_G3_TX_DN<8>")
	)
	(segment
		(start 367.88344 -222.286576)
		(end 367.885726 -222.2881)
		(width 0.1143)
		(layer "In4.Cu")
		(net "P5E_CPU0_G3_TX_DN<8>")
	)
	(segment
		(start 367.922302 -222.919036)
		(end 367.852706 -222.959676)
		(width 0.1143)
		(layer "In4.Cu")
		(net "P5E_CPU0_G3_TX_DN<8>")
	)
	(segment
		(start 367.38941 -225.38563)
		(end 367.382552 -225.389694)
		(width 0.1143)
		(layer "In4.Cu")
		(net "P5E_CPU0_G3_TX_DN<8>")
	)
	(segment
		(start 368.079528 -222.614236)
		(end 368.079274 -222.614236)
		(width 0.1143)
		(layer "In4.Cu")
		(net "P5E_CPU0_G3_TX_DN<8>")
	)
	(segment
		(start 367.922302 -224.539048)
		(end 367.852706 -224.579688)
		(width 0.1143)
		(layer "In4.Cu")
		(net "P5E_CPU0_G3_TX_DN<8>")
	)
	(segment
		(start 367.390172 -225.385122)
		(end 367.38941 -225.38563)
		(width 0.1143)
		(layer "In4.Cu")
		(net "P5E_CPU0_G3_TX_DN<8>")
	)
	(segment
		(start 367.609374 -221.343474)
		(end 367.609374 -221.80423)
		(width 0.1143)
		(layer "In4.Cu")
		(net "P5E_CPU0_G3_TX_DN<8>")
	)
	(segment
		(start 367.881154 -222.285306)
		(end 367.882424 -222.286068)
		(width 0.1143)
		(layer "In4.Cu")
		(net "P5E_CPU0_G3_TX_DN<8>")
	)
	(segment
		(start 409.882594 -20.447508)
		(end 324.05066 -126.305818)
		(width 0.14224)
		(layer "In4.Cu")
		(net "P5E_CPU0_G3_TX_DN<8>")
	)
	(segment
		(start 367.382552 -231.178862)
		(end 367.455196 -231.22128)
		(width 0.1143)
		(layer "In4.Cu")
		(net "P5E_CPU0_G3_TX_DN<8>")
	)
	(segment
		(start 367.598452 -214.452962)
		(end 367.598452 -221.083124)
		(width 0.14224)
		(layer "In4.Cu")
		(net "P5E_CPU0_G3_TX_DN<8>")
	)
	(segment
		(start 324.130416 -174.074582)
		(end 324.130416 -174.074836)
		(width 0.14224)
		(layer "In4.Cu")
		(net "P5E_CPU0_G3_TX_DN<8>")
	)
	(segment
		(start 367.882424 -222.286068)
		(end 367.88344 -222.286576)
		(width 0.1143)
		(layer "In4.Cu")
		(net "P5E_CPU0_G3_TX_DN<8>")
	)
	(segment
		(start 312.527442 -157.330648)
		(end 312.38825 -158.030926)
		(width 0.14224)
		(layer "In4.Cu")
		(net "P5E_CPU0_G3_TX_DN<8>")
	)
	(segment
		(start 367.889282 -222.290132)
		(end 367.890806 -222.291148)
		(width 0.1143)
		(layer "In4.Cu")
		(net "P5E_CPU0_G3_TX_DN<8>")
	)
	(segment
		(start 409.882594 -19.42719)
		(end 409.882594 -20.447508)
		(width 0.14224)
		(layer "In4.Cu")
		(net "P5E_CPU0_G3_TX_DN<8>")
	)
	(arc
		(start 367.382552 -225.389694)
		(mid 367.203739 -225.592044)
		(end 367.13922 -225.85426)
		(width 0.1143)
		(layer "In4.Cu")
		(net "P5E_CPU0_G3_TX_DN<8>")
	)
	(arc
		(start 367.852706 -222.959676)
		(mid 367.609379 -223.424242)
		(end 367.852706 -223.888808)
		(width 0.1143)
		(layer "In4.Cu")
		(net "P5E_CPU0_G3_TX_DN<8>")
	)
	(arc
		(start 367.455196 -231.22128)
		(mid 367.551084 -231.323688)
		(end 367.602516 -231.454198)
		(width 0.1143)
		(layer "In4.Cu")
		(net "P5E_CPU0_G3_TX_DN<8>")
	)
	(arc
		(start 367.609374 -221.80423)
		(mid 367.613875 -221.875922)
		(end 367.627408 -221.94647)
		(width 0.1143)
		(layer "In4.Cu")
		(net "P5E_CPU0_G3_TX_DN<8>")
	)
	(arc
		(start 367.13922 -225.85426)
		(mid 367.097671 -226.025682)
		(end 366.982248 -226.15906)
		(width 0.1143)
		(layer "In4.Cu")
		(net "P5E_CPU0_G3_TX_DN<8>")
	)
	(arc
		(start 367.13922 -230.714296)
		(mid 367.203735 -230.976515)
		(end 367.382552 -231.178862)
		(width 0.1143)
		(layer "In4.Cu")
		(net "P5E_CPU0_G3_TX_DN<8>")
	)
	(arc
		(start 367.13922 -229.094284)
		(mid 367.098254 -229.26469)
		(end 366.98428 -229.397814)
		(width 0.1143)
		(layer "In4.Cu")
		(net "P5E_CPU0_G3_TX_DN<8>")
	)
	(arc
		(start 367.923572 -222.309944)
		(mid 368.038248 -222.443278)
		(end 368.079528 -222.614236)
		(width 0.1143)
		(layer "In4.Cu")
		(net "P5E_CPU0_G3_TX_DN<8>")
	)
	(arc
		(start 366.912652 -227.819712)
		(mid 366.669325 -228.284278)
		(end 366.912652 -228.748844)
		(width 0.1143)
		(layer "In4.Cu")
		(net "P5E_CPU0_G3_TX_DN<8>")
	)
	(arc
		(start 367.609374 -225.044254)
		(mid 367.568119 -225.215225)
		(end 367.453418 -225.348546)
		(width 0.1143)
		(layer "In4.Cu")
		(net "P5E_CPU0_G3_TX_DN<8>")
	)
	(arc
		(start 367.627408 -221.94647)
		(mid 367.711149 -222.12783)
		(end 367.852706 -222.268796)
		(width 0.1143)
		(layer "In4.Cu")
		(net "P5E_CPU0_G3_TX_DN<8>")
	)
	(arc
		(start 366.912652 -226.1997)
		(mid 366.669325 -226.664266)
		(end 366.912652 -227.128832)
		(width 0.1143)
		(layer "In4.Cu")
		(net "P5E_CPU0_G3_TX_DN<8>")
	)
	(arc
		(start 366.982248 -227.169472)
		(mid 367.139225 -227.474272)
		(end 366.982248 -227.779072)
		(width 0.1143)
		(layer "In4.Cu")
		(net "P5E_CPU0_G3_TX_DN<8>")
	)
	(arc
		(start 366.66932 -229.904036)
		(mid 366.734556 -230.167627)
		(end 366.915192 -230.37038)
		(width 0.1143)
		(layer "In4.Cu")
		(net "P5E_CPU0_G3_TX_DN<8>")
	)
	(arc
		(start 367.922302 -223.929448)
		(mid 368.079279 -224.234248)
		(end 367.922302 -224.539048)
		(width 0.1143)
		(layer "In4.Cu")
		(net "P5E_CPU0_G3_TX_DN<8>")
	)
	(arc
		(start 368.079274 -222.614236)
		(mid 368.037725 -222.785658)
		(end 367.922302 -222.919036)
		(width 0.1143)
		(layer "In4.Cu")
		(net "P5E_CPU0_G3_TX_DN<8>")
	)
	(arc
		(start 366.982248 -228.789484)
		(mid 367.097675 -228.92286)
		(end 367.13922 -229.094284)
		(width 0.1143)
		(layer "In4.Cu")
		(net "P5E_CPU0_G3_TX_DN<8>")
	)
	(arc
		(start 366.912652 -229.43947)
		(mid 366.733839 -229.64182)
		(end 366.66932 -229.904036)
		(width 0.1143)
		(layer "In4.Cu")
		(net "P5E_CPU0_G3_TX_DN<8>")
	)
	(arc
		(start 367.852706 -224.579688)
		(mid 367.673893 -224.782038)
		(end 367.609374 -225.044254)
		(width 0.1143)
		(layer "In4.Cu")
		(net "P5E_CPU0_G3_TX_DN<8>")
	)
	(arc
		(start 366.982248 -230.409496)
		(mid 367.097675 -230.542872)
		(end 367.13922 -230.714296)
		(width 0.1143)
		(layer "In4.Cu")
		(net "P5E_CPU0_G3_TX_DN<8>")
	)
	(segment
		(start 412.656274 -17.341596)
		(end 412.384748 -17.613122)
		(width 0.12954)
		(layer "F.Cu")
		(net "P5E_CPU0_G3_TX_DN<7>")
	)
	(segment
		(start 412.656274 -16.663924)
		(end 412.656274 -17.341596)
		(width 0.12954)
		(layer "F.Cu")
		(net "P5E_CPU0_G3_TX_DN<7>")
	)
	(segment
		(start 412.359348 -16.366998)
		(end 412.656274 -16.663924)
		(width 0.12954)
		(layer "F.Cu")
		(net "P5E_CPU0_G3_TX_DN<7>")
	)
	(segment
		(start 366.767872 -233.409998)
		(end 367.234724 -233.14406)
		(width 0.12954)
		(layer "F.Cu")
		(net "P5E_CPU0_G3_TX_DN<7>")
	)
	(segment
		(start 367.892584 -228.772212)
		(end 367.923572 -228.789992)
		(width 0.1143)
		(layer "In4.Cu")
		(net "P5E_CPU0_G3_TX_DN<7>")
	)
	(segment
		(start 369.443762 -221.083124)
		(end 369.489482 -221.128844)
		(width 0.1143)
		(layer "In4.Cu")
		(net "P5E_CPU0_G3_TX_DN<7>")
	)
	(segment
		(start 368.393472 -231.82834)
		(end 368.361722 -231.846628)
		(width 0.1143)
		(layer "In4.Cu")
		(net "P5E_CPU0_G3_TX_DN<7>")
	)
	(segment
		(start 313.32043 -161.998406)
		(end 314.981082 -166.008558)
		(width 0.14224)
		(layer "In4.Cu")
		(net "P5E_CPU0_G3_TX_DN<7>")
	)
	(segment
		(start 362.755942 -204.47)
		(end 368.606578 -214.324692)
		(width 0.14224)
		(layer "In4.Cu")
		(net "P5E_CPU0_G3_TX_DN<7>")
	)
	(segment
		(start 369.309904 -222.122238)
		(end 369.302538 -222.126302)
		(width 0.1143)
		(layer "In4.Cu")
		(net "P5E_CPU0_G3_TX_DN<7>")
	)
	(segment
		(start 368.357912 -225.368866)
		(end 368.356896 -225.369374)
		(width 0.1143)
		(layer "In4.Cu")
		(net "P5E_CPU0_G3_TX_DN<7>")
	)
	(segment
		(start 367.892584 -227.796344)
		(end 367.891822 -227.796852)
		(width 0.1143)
		(layer "In4.Cu")
		(net "P5E_CPU0_G3_TX_DN<7>")
	)
	(segment
		(start 367.897664 -232.653332)
		(end 367.892584 -232.656126)
		(width 0.1143)
		(layer "In4.Cu")
		(net "P5E_CPU0_G3_TX_DN<7>")
	)
	(segment
		(start 367.923572 -227.778564)
		(end 367.892584 -227.796344)
		(width 0.1143)
		(layer "In4.Cu")
		(net "P5E_CPU0_G3_TX_DN<7>")
	)
	(segment
		(start 367.61547 -233.061256)
		(end 367.532666 -233.14406)
		(width 0.1143)
		(layer "In4.Cu")
		(net "P5E_CPU0_G3_TX_DN<7>")
	)
	(segment
		(start 367.889282 -232.658158)
		(end 367.852706 -232.679494)
		(width 0.1143)
		(layer "In4.Cu")
		(net "P5E_CPU0_G3_TX_DN<7>")
	)
	(segment
		(start 369.333526 -222.108522)
		(end 369.309904 -222.122238)
		(width 0.1143)
		(layer "In4.Cu")
		(net "P5E_CPU0_G3_TX_DN<7>")
	)
	(segment
		(start 321.933316 -131.832604)
		(end 317.651638 -142.97406)
		(width 0.14224)
		(layer "In4.Cu")
		(net "P5E_CPU0_G3_TX_DN<7>")
	)
	(segment
		(start 367.890806 -227.79736)
		(end 367.889282 -227.798376)
		(width 0.1143)
		(layer "In4.Cu")
		(net "P5E_CPU0_G3_TX_DN<7>")
	)
	(segment
		(start 367.890806 -226.177348)
		(end 367.889282 -226.178364)
		(width 0.1143)
		(layer "In4.Cu")
		(net "P5E_CPU0_G3_TX_DN<7>")
	)
	(segment
		(start 368.360198 -225.367596)
		(end 368.357912 -225.368866)
		(width 0.1143)
		(layer "In4.Cu")
		(net "P5E_CPU0_G3_TX_DN<7>")
	)
	(segment
		(start 367.892584 -226.176332)
		(end 367.891822 -226.17684)
		(width 0.1143)
		(layer "In4.Cu")
		(net "P5E_CPU0_G3_TX_DN<7>")
	)
	(segment
		(start 412.675578 -17.903952)
		(end 412.675578 -20.447)
		(width 0.14224)
		(layer "In4.Cu")
		(net "P5E_CPU0_G3_TX_DN<7>")
	)
	(segment
		(start 368.085116 -232.326942)
		(end 368.085116 -232.329482)
		(width 0.1143)
		(layer "In4.Cu")
		(net "P5E_CPU0_G3_TX_DN<7>")
	)
	(segment
		(start 367.92535 -229.397052)
		(end 367.852706 -229.43947)
		(width 0.1143)
		(layer "In4.Cu")
		(net "P5E_CPU0_G3_TX_DN<7>")
	)
	(segment
		(start 322.204334 -171.746164)
		(end 324.63486 -173.252892)
		(width 0.14224)
		(layer "In4.Cu")
		(net "P5E_CPU0_G3_TX_DN<7>")
	)
	(segment
		(start 317.651638 -142.97406)
		(end 313.434222 -157.552136)
		(width 0.14224)
		(layer "In4.Cu")
		(net "P5E_CPU0_G3_TX_DN<7>")
	)
	(segment
		(start 367.889282 -227.798376)
		(end 367.852706 -227.819712)
		(width 0.1143)
		(layer "In4.Cu")
		(net "P5E_CPU0_G3_TX_DN<7>")
	)
	(segment
		(start 367.890806 -232.657142)
		(end 367.889282 -232.658158)
		(width 0.1143)
		(layer "In4.Cu")
		(net "P5E_CPU0_G3_TX_DN<7>")
	)
	(segment
		(start 367.852706 -227.128832)
		(end 367.889282 -227.150168)
		(width 0.1143)
		(layer "In4.Cu")
		(net "P5E_CPU0_G3_TX_DN<7>")
	)
	(segment
		(start 368.356896 -225.369374)
		(end 368.3254 -225.387916)
		(width 0.1143)
		(layer "In4.Cu")
		(net "P5E_CPU0_G3_TX_DN<7>")
	)
	(segment
		(start 367.892584 -227.1522)
		(end 367.923572 -227.16998)
		(width 0.1143)
		(layer "In4.Cu")
		(net "P5E_CPU0_G3_TX_DN<7>")
	)
	(segment
		(start 367.891822 -226.17684)
		(end 367.890806 -226.177348)
		(width 0.1143)
		(layer "In4.Cu")
		(net "P5E_CPU0_G3_TX_DN<7>")
	)
	(segment
		(start 321.311778 -171.25569)
		(end 322.204334 -171.746164)
		(width 0.14224)
		(layer "In4.Cu")
		(net "P5E_CPU0_G3_TX_DN<7>")
	)
	(segment
		(start 367.889282 -227.150168)
		(end 367.890806 -227.151184)
		(width 0.1143)
		(layer "In4.Cu")
		(net "P5E_CPU0_G3_TX_DN<7>")
	)
	(segment
		(start 368.79276 -223.888808)
		(end 368.862356 -223.929448)
		(width 0.1143)
		(layer "In4.Cu")
		(net "P5E_CPU0_G3_TX_DN<7>")
	)
	(segment
		(start 367.892584 -232.656126)
		(end 367.891822 -232.656634)
		(width 0.1143)
		(layer "In4.Cu")
		(net "P5E_CPU0_G3_TX_DN<7>")
	)
	(segment
		(start 314.981082 -166.008558)
		(end 318.185546 -169.214038)
		(width 0.14224)
		(layer "In4.Cu")
		(net "P5E_CPU0_G3_TX_DN<7>")
	)
	(segment
		(start 367.890806 -230.394002)
		(end 367.89614 -230.39705)
		(width 0.1143)
		(layer "In4.Cu")
		(net "P5E_CPU0_G3_TX_DN<7>")
	)
	(segment
		(start 367.891822 -227.151692)
		(end 367.892584 -227.1522)
		(width 0.1143)
		(layer "In4.Cu")
		(net "P5E_CPU0_G3_TX_DN<7>")
	)
	(segment
		(start 367.889282 -228.77018)
		(end 367.890806 -228.771196)
		(width 0.1143)
		(layer "In4.Cu")
		(net "P5E_CPU0_G3_TX_DN<7>")
	)
	(segment
		(start 313.32043 -158.12516)
		(end 313.32043 -161.998406)
		(width 0.14224)
		(layer "In4.Cu")
		(net "P5E_CPU0_G3_TX_DN<7>")
	)
	(segment
		(start 369.301776 -222.12681)
		(end 369.30076 -222.127318)
		(width 0.1143)
		(layer "In4.Cu")
		(net "P5E_CPU0_G3_TX_DN<7>")
	)
	(segment
		(start 367.532666 -233.14406)
		(end 367.234724 -233.14406)
		(width 0.1143)
		(layer "In4.Cu")
		(net "P5E_CPU0_G3_TX_DN<7>")
	)
	(segment
		(start 367.889282 -226.178364)
		(end 367.852706 -226.1997)
		(width 0.1143)
		(layer "In4.Cu")
		(net "P5E_CPU0_G3_TX_DN<7>")
	)
	(segment
		(start 313.434222 -157.552136)
		(end 313.32043 -158.12516)
		(width 0.14224)
		(layer "In4.Cu")
		(net "P5E_CPU0_G3_TX_DN<7>")
	)
	(segment
		(start 367.921286 -226.159822)
		(end 367.892584 -226.176332)
		(width 0.1143)
		(layer "In4.Cu")
		(net "P5E_CPU0_G3_TX_DN<7>")
	)
	(segment
		(start 369.443762 -220.871542)
		(end 369.443762 -221.083124)
		(width 0.14224)
		(layer "In4.Cu")
		(net "P5E_CPU0_G3_TX_DN<7>")
	)
	(segment
		(start 368.862356 -222.919036)
		(end 368.79276 -222.959676)
		(width 0.1143)
		(layer "In4.Cu")
		(net "P5E_CPU0_G3_TX_DN<7>")
	)
	(segment
		(start 367.891822 -232.656634)
		(end 367.890806 -232.657142)
		(width 0.1143)
		(layer "In4.Cu")
		(net "P5E_CPU0_G3_TX_DN<7>")
	)
	(segment
		(start 412.675578 -20.447)
		(end 324.455536 -127.508254)
		(width 0.14224)
		(layer "In4.Cu")
		(net "P5E_CPU0_G3_TX_DN<7>")
	)
	(segment
		(start 324.63486 -173.252892)
		(end 362.755942 -204.47)
		(width 0.14224)
		(layer "In4.Cu")
		(net "P5E_CPU0_G3_TX_DN<7>")
	)
	(segment
		(start 412.384748 -17.613122)
		(end 412.675578 -17.903952)
		(width 0.14224)
		(layer "In4.Cu")
		(net "P5E_CPU0_G3_TX_DN<7>")
	)
	(segment
		(start 318.185546 -169.214038)
		(end 321.311778 -171.25569)
		(width 0.14224)
		(layer "In4.Cu")
		(net "P5E_CPU0_G3_TX_DN<7>")
	)
	(segment
		(start 369.302538 -222.126302)
		(end 369.301776 -222.12681)
		(width 0.1143)
		(layer "In4.Cu")
		(net "P5E_CPU0_G3_TX_DN<7>")
	)
	(segment
		(start 367.852706 -228.748844)
		(end 367.889282 -228.77018)
		(width 0.1143)
		(layer "In4.Cu")
		(net "P5E_CPU0_G3_TX_DN<7>")
	)
	(segment
		(start 368.862356 -224.539048)
		(end 368.79276 -224.579688)
		(width 0.1143)
		(layer "In4.Cu")
		(net "P5E_CPU0_G3_TX_DN<7>")
	)
	(segment
		(start 369.489482 -221.128844)
		(end 369.489482 -221.804484)
		(width 0.1143)
		(layer "In4.Cu")
		(net "P5E_CPU0_G3_TX_DN<7>")
	)
	(segment
		(start 368.606578 -214.324692)
		(end 369.443762 -220.871542)
		(width 0.14224)
		(layer "In4.Cu")
		(net "P5E_CPU0_G3_TX_DN<7>")
	)
	(segment
		(start 324.455536 -127.508254)
		(end 321.933316 -131.832604)
		(width 0.14224)
		(layer "In4.Cu")
		(net "P5E_CPU0_G3_TX_DN<7>")
	)
	(segment
		(start 367.891822 -227.796852)
		(end 367.890806 -227.79736)
		(width 0.1143)
		(layer "In4.Cu")
		(net "P5E_CPU0_G3_TX_DN<7>")
	)
	(segment
		(start 368.3254 -231.18064)
		(end 368.39525 -231.22128)
		(width 0.1143)
		(layer "In4.Cu")
		(net "P5E_CPU0_G3_TX_DN<7>")
	)
	(segment
		(start 368.3635 -225.365818)
		(end 368.361214 -225.367088)
		(width 0.1143)
		(layer "In4.Cu")
		(net "P5E_CPU0_G3_TX_DN<7>")
	)
	(segment
		(start 367.890806 -228.771196)
		(end 367.891822 -228.771704)
		(width 0.1143)
		(layer "In4.Cu")
		(net "P5E_CPU0_G3_TX_DN<7>")
	)
	(segment
		(start 369.30076 -222.127318)
		(end 369.26266 -222.14967)
		(width 0.1143)
		(layer "In4.Cu")
		(net "P5E_CPU0_G3_TX_DN<7>")
	)
	(segment
		(start 368.361214 -225.367088)
		(end 368.360198 -225.367596)
		(width 0.1143)
		(layer "In4.Cu")
		(net "P5E_CPU0_G3_TX_DN<7>")
	)
	(segment
		(start 367.891822 -228.771704)
		(end 367.892584 -228.772212)
		(width 0.1143)
		(layer "In4.Cu")
		(net "P5E_CPU0_G3_TX_DN<7>")
	)
	(segment
		(start 367.890806 -227.151184)
		(end 367.891822 -227.151692)
		(width 0.1143)
		(layer "In4.Cu")
		(net "P5E_CPU0_G3_TX_DN<7>")
	)
	(arc
		(start 369.26266 -222.14967)
		(mid 369.083847 -222.35202)
		(end 369.019328 -222.614236)
		(width 0.1143)
		(layer "In4.Cu")
		(net "P5E_CPU0_G3_TX_DN<7>")
	)
	(arc
		(start 368.361722 -231.846628)
		(mid 368.159182 -232.049798)
		(end 368.085116 -232.326942)
		(width 0.1143)
		(layer "In4.Cu")
		(net "P5E_CPU0_G3_TX_DN<7>")
	)
	(arc
		(start 368.39525 -231.22128)
		(mid 368.508657 -231.354169)
		(end 368.549428 -231.524048)
		(width 0.1143)
		(layer "In4.Cu")
		(net "P5E_CPU0_G3_TX_DN<7>")
	)
	(arc
		(start 367.89614 -230.39705)
		(mid 368.030412 -230.531067)
		(end 368.079528 -230.714296)
		(width 0.1143)
		(layer "In4.Cu")
		(net "P5E_CPU0_G3_TX_DN<7>")
	)
	(arc
		(start 368.3254 -225.387916)
		(mid 368.144748 -225.590661)
		(end 368.079528 -225.85426)
		(width 0.1143)
		(layer "In4.Cu")
		(net "P5E_CPU0_G3_TX_DN<7>")
	)
	(arc
		(start 367.923572 -227.16998)
		(mid 368.075161 -227.474272)
		(end 367.923572 -227.778564)
		(width 0.1143)
		(layer "In4.Cu")
		(net "P5E_CPU0_G3_TX_DN<7>")
	)
	(arc
		(start 368.085116 -232.329482)
		(mid 368.034866 -232.516564)
		(end 367.897664 -232.653332)
		(width 0.1143)
		(layer "In4.Cu")
		(net "P5E_CPU0_G3_TX_DN<7>")
	)
	(arc
		(start 367.61928 -233.038396)
		(mid 367.617257 -233.049806)
		(end 367.61547 -233.061256)
		(width 0.1143)
		(layer "In4.Cu")
		(net "P5E_CPU0_G3_TX_DN<7>")
	)
	(arc
		(start 367.852706 -229.43947)
		(mid 367.673893 -229.64182)
		(end 367.609374 -229.904036)
		(width 0.1143)
		(layer "In4.Cu")
		(net "P5E_CPU0_G3_TX_DN<7>")
	)
	(arc
		(start 368.079528 -229.094284)
		(mid 368.038766 -229.264168)
		(end 367.92535 -229.397052)
		(width 0.1143)
		(layer "In4.Cu")
		(net "P5E_CPU0_G3_TX_DN<7>")
	)
	(arc
		(start 369.019328 -222.614236)
		(mid 368.977779 -222.785658)
		(end 368.862356 -222.919036)
		(width 0.1143)
		(layer "In4.Cu")
		(net "P5E_CPU0_G3_TX_DN<7>")
	)
	(arc
		(start 367.852706 -227.819712)
		(mid 367.609379 -228.284278)
		(end 367.852706 -228.748844)
		(width 0.1143)
		(layer "In4.Cu")
		(net "P5E_CPU0_G3_TX_DN<7>")
	)
	(arc
		(start 367.852706 -226.1997)
		(mid 367.609379 -226.664266)
		(end 367.852706 -227.128832)
		(width 0.1143)
		(layer "In4.Cu")
		(net "P5E_CPU0_G3_TX_DN<7>")
	)
	(arc
		(start 368.79276 -224.579688)
		(mid 368.613947 -224.782038)
		(end 368.549428 -225.044254)
		(width 0.1143)
		(layer "In4.Cu")
		(net "P5E_CPU0_G3_TX_DN<7>")
	)
	(arc
		(start 368.549428 -225.044254)
		(mid 368.499605 -225.229984)
		(end 368.3635 -225.365818)
		(width 0.1143)
		(layer "In4.Cu")
		(net "P5E_CPU0_G3_TX_DN<7>")
	)
	(arc
		(start 367.923572 -228.789992)
		(mid 368.035369 -228.924793)
		(end 368.079528 -229.094284)
		(width 0.1143)
		(layer "In4.Cu")
		(net "P5E_CPU0_G3_TX_DN<7>")
	)
	(arc
		(start 368.79276 -222.959676)
		(mid 368.549433 -223.424242)
		(end 368.79276 -223.888808)
		(width 0.1143)
		(layer "In4.Cu")
		(net "P5E_CPU0_G3_TX_DN<7>")
	)
	(arc
		(start 367.852706 -232.679494)
		(mid 367.700719 -232.836002)
		(end 367.61928 -233.038396)
		(width 0.1143)
		(layer "In4.Cu")
		(net "P5E_CPU0_G3_TX_DN<7>")
	)
	(arc
		(start 369.489482 -221.804484)
		(mid 369.448169 -221.975314)
		(end 369.333526 -222.108522)
		(width 0.1143)
		(layer "In4.Cu")
		(net "P5E_CPU0_G3_TX_DN<7>")
	)
	(arc
		(start 368.862356 -223.929448)
		(mid 369.019333 -224.234248)
		(end 368.862356 -224.539048)
		(width 0.1143)
		(layer "In4.Cu")
		(net "P5E_CPU0_G3_TX_DN<7>")
	)
	(arc
		(start 368.079528 -225.85426)
		(mid 368.034517 -226.024696)
		(end 367.921286 -226.159822)
		(width 0.1143)
		(layer "In4.Cu")
		(net "P5E_CPU0_G3_TX_DN<7>")
	)
	(arc
		(start 367.609374 -229.904036)
		(mid 367.684742 -230.186551)
		(end 367.890806 -230.394002)
		(width 0.1143)
		(layer "In4.Cu")
		(net "P5E_CPU0_G3_TX_DN<7>")
	)
	(arc
		(start 368.079528 -230.714296)
		(mid 368.144764 -230.977887)
		(end 368.3254 -231.18064)
		(width 0.1143)
		(layer "In4.Cu")
		(net "P5E_CPU0_G3_TX_DN<7>")
	)
	(arc
		(start 368.549428 -231.524048)
		(mid 368.508173 -231.695019)
		(end 368.393472 -231.82834)
		(width 0.1143)
		(layer "In4.Cu")
		(net "P5E_CPU0_G3_TX_DN<7>")
	)
	(segment
		(start 415.460942 -17.890998)
		(end 415.75609 -18.186146)
		(width 0.12954)
		(layer "F.Cu")
		(net "P5E_CPU0_G3_TX_DN<6>")
	)
	(segment
		(start 369.588034 -236.650022)
		(end 370.054886 -236.384084)
		(width 0.12954)
		(layer "F.Cu")
		(net "P5E_CPU0_G3_TX_DN<6>")
	)
	(segment
		(start 415.75609 -18.186146)
		(end 415.75609 -18.86585)
		(width 0.12954)
		(layer "F.Cu")
		(net "P5E_CPU0_G3_TX_DN<6>")
	)
	(segment
		(start 415.75609 -18.86585)
		(end 415.48558 -19.13636)
		(width 0.12954)
		(layer "F.Cu")
		(net "P5E_CPU0_G3_TX_DN<6>")
	)
	(segment
		(start 415.459164 -17.890998)
		(end 415.460942 -17.890998)
		(width 0.12954)
		(layer "F.Cu")
		(net "P5E_CPU0_G3_TX_DN<6>")
	)
	(segment
		(start 369.301776 -231.846628)
		(end 369.29949 -231.847898)
		(width 0.1143)
		(layer "In4.Cu")
		(net "P5E_CPU0_G3_TX_DN<6>")
	)
	(segment
		(start 368.863626 -230.410004)
		(end 369.000024 -230.508302)
		(width 0.1143)
		(layer "In4.Cu")
		(net "P5E_CPU0_G3_TX_DN<6>")
	)
	(segment
		(start 369.303808 -225.365564)
		(end 369.302538 -225.366326)
		(width 0.1143)
		(layer "In4.Cu")
		(net "P5E_CPU0_G3_TX_DN<6>")
	)
	(segment
		(start 369.301776 -234.441492)
		(end 369.333526 -234.45978)
		(width 0.1143)
		(layer "In4.Cu")
		(net "P5E_CPU0_G3_TX_DN<6>")
	)
	(segment
		(start 369.306348 -225.364294)
		(end 369.303808 -225.365564)
		(width 0.1143)
		(layer "In4.Cu")
		(net "P5E_CPU0_G3_TX_DN<6>")
	)
	(segment
		(start 318.776858 -168.486582)
		(end 322.707508 -170.842686)
		(width 0.14224)
		(layer "In4.Cu")
		(net "P5E_CPU0_G3_TX_DN<6>")
	)
	(segment
		(start 369.732814 -223.888808)
		(end 369.80241 -223.929448)
		(width 0.1143)
		(layer "In4.Cu")
		(net "P5E_CPU0_G3_TX_DN<6>")
	)
	(segment
		(start 368.793522 -227.12934)
		(end 368.832384 -227.151946)
		(width 0.1143)
		(layer "In4.Cu")
		(net "P5E_CPU0_G3_TX_DN<6>")
	)
	(segment
		(start 368.832384 -228.771704)
		(end 368.858292 -228.786944)
		(width 0.1143)
		(layer "In4.Cu")
		(net "P5E_CPU0_G3_TX_DN<6>")
	)
	(segment
		(start 324.951598 -128.586992)
		(end 322.777866 -132.23494)
		(width 0.14224)
		(layer "In4.Cu")
		(net "P5E_CPU0_G3_TX_DN<6>")
	)
	(segment
		(start 369.29949 -234.439968)
		(end 369.301776 -234.441492)
		(width 0.1143)
		(layer "In4.Cu")
		(net "P5E_CPU0_G3_TX_DN<6>")
	)
	(segment
		(start 368.830098 -232.65765)
		(end 368.793776 -232.678732)
		(width 0.1143)
		(layer "In4.Cu")
		(net "P5E_CPU0_G3_TX_DN<6>")
	)
	(segment
		(start 415.77641 -20.444714)
		(end 324.951598 -128.586992)
		(width 0.14224)
		(layer "In4.Cu")
		(net "P5E_CPU0_G3_TX_DN<6>")
	)
	(segment
		(start 314.25261 -158.218632)
		(end 314.25261 -161.812478)
		(width 0.14224)
		(layer "In4.Cu")
		(net "P5E_CPU0_G3_TX_DN<6>")
	)
	(segment
		(start 322.777866 -132.23494)
		(end 318.535558 -143.274288)
		(width 0.14224)
		(layer "In4.Cu")
		(net "P5E_CPU0_G3_TX_DN<6>")
	)
	(segment
		(start 368.840258 -226.172014)
		(end 368.836448 -226.174554)
		(width 0.1143)
		(layer "In4.Cu")
		(net "P5E_CPU0_G3_TX_DN<6>")
	)
	(segment
		(start 370.24183 -222.12681)
		(end 370.202714 -222.14967)
		(width 0.1143)
		(layer "In4.Cu")
		(net "P5E_CPU0_G3_TX_DN<6>")
	)
	(segment
		(start 318.535558 -143.274288)
		(end 314.341256 -157.772354)
		(width 0.14224)
		(layer "In4.Cu")
		(net "P5E_CPU0_G3_TX_DN<6>")
	)
	(segment
		(start 368.815366 -233.621834)
		(end 368.830352 -233.630724)
		(width 0.1143)
		(layer "In4.Cu")
		(net "P5E_CPU0_G3_TX_DN<6>")
	)
	(segment
		(start 415.77641 -19.42719)
		(end 415.77641 -20.444714)
		(width 0.14224)
		(layer "In4.Cu")
		(net "P5E_CPU0_G3_TX_DN<6>")
	)
	(segment
		(start 369.80241 -222.919036)
		(end 369.732814 -222.959676)
		(width 0.1143)
		(layer "In4.Cu")
		(net "P5E_CPU0_G3_TX_DN<6>")
	)
	(segment
		(start 369.597178 -214.131398)
		(end 370.414804 -220.871542)
		(width 0.14224)
		(layer "In4.Cu")
		(net "P5E_CPU0_G3_TX_DN<6>")
	)
	(segment
		(start 368.769646 -233.59237)
		(end 368.79276 -233.60888)
		(width 0.1143)
		(layer "In4.Cu")
		(net "P5E_CPU0_G3_TX_DN<6>")
	)
	(segment
		(start 369.732814 -235.228638)
		(end 369.80241 -235.269278)
		(width 0.1143)
		(layer "In4.Cu")
		(net "P5E_CPU0_G3_TX_DN<6>")
	)
	(segment
		(start 368.858292 -228.786944)
		(end 368.859054 -228.787452)
		(width 0.1143)
		(layer "In4.Cu")
		(net "P5E_CPU0_G3_TX_DN<6>")
	)
	(segment
		(start 368.832638 -232.656126)
		(end 368.831876 -232.656634)
		(width 0.1143)
		(layer "In4.Cu")
		(net "P5E_CPU0_G3_TX_DN<6>")
	)
	(segment
		(start 370.238274 -236.059472)
		(end 370.23929 -236.05998)
		(width 0.1143)
		(layer "In4.Cu")
		(net "P5E_CPU0_G3_TX_DN<6>")
	)
	(segment
		(start 370.23929 -236.05998)
		(end 370.240814 -236.060996)
		(width 0.1143)
		(layer "In4.Cu")
		(net "P5E_CPU0_G3_TX_DN<6>")
	)
	(segment
		(start 370.422678 -236.314234)
		(end 370.352828 -236.384084)
		(width 0.1143)
		(layer "In4.Cu")
		(net "P5E_CPU0_G3_TX_DN<6>")
	)
	(segment
		(start 314.25261 -161.812478)
		(end 315.77153 -165.480238)
		(width 0.14224)
		(layer "In4.Cu")
		(net "P5E_CPU0_G3_TX_DN<6>")
	)
	(segment
		(start 370.243862 -236.062774)
		(end 370.245386 -236.063536)
		(width 0.1143)
		(layer "In4.Cu")
		(net "P5E_CPU0_G3_TX_DN<6>")
	)
	(segment
		(start 368.831876 -232.656634)
		(end 368.83086 -232.657142)
		(width 0.1143)
		(layer "In4.Cu")
		(net "P5E_CPU0_G3_TX_DN<6>")
	)
	(segment
		(start 368.847116 -226.168204)
		(end 368.8461 -226.168712)
		(width 0.1143)
		(layer "In4.Cu")
		(net "P5E_CPU0_G3_TX_DN<6>")
	)
	(segment
		(start 368.845338 -226.16922)
		(end 368.842544 -226.170744)
		(width 0.1143)
		(layer "In4.Cu")
		(net "P5E_CPU0_G3_TX_DN<6>")
	)
	(segment
		(start 368.863626 -226.158552)
		(end 368.847116 -226.168204)
		(width 0.1143)
		(layer "In4.Cu")
		(net "P5E_CPU0_G3_TX_DN<6>")
	)
	(segment
		(start 368.83213 -227.151946)
		(end 368.861594 -227.168964)
		(width 0.1143)
		(layer "In4.Cu")
		(net "P5E_CPU0_G3_TX_DN<6>")
	)
	(segment
		(start 369.303808 -231.845358)
		(end 369.302538 -231.84612)
		(width 0.1143)
		(layer "In4.Cu")
		(net "P5E_CPU0_G3_TX_DN<6>")
	)
	(segment
		(start 370.414804 -221.083124)
		(end 370.460524 -221.128844)
		(width 0.1143)
		(layer "In4.Cu")
		(net "P5E_CPU0_G3_TX_DN<6>")
	)
	(segment
		(start 317.281306 -166.990522)
		(end 318.776858 -168.486582)
		(width 0.14224)
		(layer "In4.Cu")
		(net "P5E_CPU0_G3_TX_DN<6>")
	)
	(segment
		(start 368.842544 -226.170744)
		(end 368.840258 -226.172014)
		(width 0.1143)
		(layer "In4.Cu")
		(net "P5E_CPU0_G3_TX_DN<6>")
	)
	(segment
		(start 326.992488 -173.952916)
		(end 363.582458 -203.940664)
		(width 0.14224)
		(layer "In4.Cu")
		(net "P5E_CPU0_G3_TX_DN<6>")
	)
	(segment
		(start 368.865404 -229.397052)
		(end 368.79276 -229.43947)
		(width 0.1143)
		(layer "In4.Cu")
		(net "P5E_CPU0_G3_TX_DN<6>")
	)
	(segment
		(start 322.707508 -170.842686)
		(end 325.95312 -173.011846)
		(width 0.14224)
		(layer "In4.Cu")
		(net "P5E_CPU0_G3_TX_DN<6>")
	)
	(segment
		(start 368.831876 -230.391716)
		(end 368.863626 -230.410004)
		(width 0.1143)
		(layer "In4.Cu")
		(net "P5E_CPU0_G3_TX_DN<6>")
	)
	(segment
		(start 368.793522 -228.749352)
		(end 368.830352 -228.770688)
		(width 0.1143)
		(layer "In4.Cu")
		(net "P5E_CPU0_G3_TX_DN<6>")
	)
	(segment
		(start 369.80241 -224.539048)
		(end 369.732814 -224.579688)
		(width 0.1143)
		(layer "In4.Cu")
		(net "P5E_CPU0_G3_TX_DN<6>")
	)
	(segment
		(start 368.831876 -228.771704)
		(end 368.832384 -228.771704)
		(width 0.1143)
		(layer "In4.Cu")
		(net "P5E_CPU0_G3_TX_DN<6>")
	)
	(segment
		(start 370.240814 -236.060996)
		(end 370.24183 -236.061504)
		(width 0.1143)
		(layer "In4.Cu")
		(net "P5E_CPU0_G3_TX_DN<6>")
	)
	(segment
		(start 315.77153 -165.480238)
		(end 317.281052 -166.990522)
		(width 0.14224)
		(layer "In4.Cu")
		(net "P5E_CPU0_G3_TX_DN<6>")
	)
	(segment
		(start 369.265454 -231.18064)
		(end 369.335304 -231.22128)
		(width 0.1143)
		(layer "In4.Cu")
		(net "P5E_CPU0_G3_TX_DN<6>")
	)
	(segment
		(start 368.832384 -227.151946)
		(end 368.83213 -227.151946)
		(width 0.1143)
		(layer "In4.Cu")
		(net "P5E_CPU0_G3_TX_DN<6>")
	)
	(segment
		(start 369.333526 -225.348546)
		(end 369.306348 -225.364294)
		(width 0.1143)
		(layer "In4.Cu")
		(net "P5E_CPU0_G3_TX_DN<6>")
	)
	(segment
		(start 369.291616 -234.435396)
		(end 369.29949 -234.439968)
		(width 0.1143)
		(layer "In4.Cu")
		(net "P5E_CPU0_G3_TX_DN<6>")
	)
	(segment
		(start 368.7953 -230.37038)
		(end 368.831876 -230.391716)
		(width 0.1143)
		(layer "In4.Cu")
		(net "P5E_CPU0_G3_TX_DN<6>")
	)
	(segment
		(start 325.95312 -173.011846)
		(end 326.992488 -173.952916)
		(width 0.14224)
		(layer "In4.Cu")
		(net "P5E_CPU0_G3_TX_DN<6>")
	)
	(segment
		(start 370.245386 -236.063536)
		(end 370.246148 -236.064044)
		(width 0.1143)
		(layer "In4.Cu")
		(net "P5E_CPU0_G3_TX_DN<6>")
	)
	(segment
		(start 368.79276 -233.60888)
		(end 368.815366 -233.621834)
		(width 0.1143)
		(layer "In4.Cu")
		(net "P5E_CPU0_G3_TX_DN<6>")
	)
	(segment
		(start 368.831368 -233.631232)
		(end 368.83594 -233.633772)
		(width 0.1143)
		(layer "In4.Cu")
		(net "P5E_CPU0_G3_TX_DN<6>")
	)
	(segment
		(start 368.830352 -228.770688)
		(end 368.831876 -228.771704)
		(width 0.1143)
		(layer "In4.Cu")
		(net "P5E_CPU0_G3_TX_DN<6>")
	)
	(segment
		(start 369.301776 -225.366834)
		(end 369.29949 -225.368104)
		(width 0.1143)
		(layer "In4.Cu")
		(net "P5E_CPU0_G3_TX_DN<6>")
	)
	(segment
		(start 370.202714 -236.038644)
		(end 370.238274 -236.059472)
		(width 0.1143)
		(layer "In4.Cu")
		(net "P5E_CPU0_G3_TX_DN<6>")
	)
	(segment
		(start 363.582458 -203.940664)
		(end 369.597178 -214.131398)
		(width 0.14224)
		(layer "In4.Cu")
		(net "P5E_CPU0_G3_TX_DN<6>")
	)
	(segment
		(start 369.306348 -231.844088)
		(end 369.303808 -231.845358)
		(width 0.1143)
		(layer "In4.Cu")
		(net "P5E_CPU0_G3_TX_DN<6>")
	)
	(segment
		(start 370.27358 -222.108522)
		(end 370.24183 -222.12681)
		(width 0.1143)
		(layer "In4.Cu")
		(net "P5E_CPU0_G3_TX_DN<6>")
	)
	(segment
		(start 370.242592 -236.062012)
		(end 370.243862 -236.062774)
		(width 0.1143)
		(layer "In4.Cu")
		(net "P5E_CPU0_G3_TX_DN<6>")
	)
	(segment
		(start 370.460524 -221.128844)
		(end 370.460524 -221.308676)
		(width 0.1143)
		(layer "In4.Cu")
		(net "P5E_CPU0_G3_TX_DN<6>")
	)
	(segment
		(start 370.24818 -236.06506)
		(end 370.27358 -236.079792)
		(width 0.1143)
		(layer "In4.Cu")
		(net "P5E_CPU0_G3_TX_DN<6>")
	)
	(segment
		(start 369.302538 -225.366326)
		(end 369.301776 -225.366834)
		(width 0.1143)
		(layer "In4.Cu")
		(net "P5E_CPU0_G3_TX_DN<6>")
	)
	(segment
		(start 415.48558 -19.13636)
		(end 415.77641 -19.42719)
		(width 0.14224)
		(layer "In4.Cu")
		(net "P5E_CPU0_G3_TX_DN<6>")
	)
	(segment
		(start 369.019582 -230.546402)
		(end 369.019582 -230.714296)
		(width 0.1143)
		(layer "In4.Cu")
		(net "P5E_CPU0_G3_TX_DN<6>")
	)
	(segment
		(start 369.302538 -231.84612)
		(end 369.301776 -231.846628)
		(width 0.1143)
		(layer "In4.Cu")
		(net "P5E_CPU0_G3_TX_DN<6>")
	)
	(segment
		(start 370.460524 -221.308676)
		(end 370.429536 -221.339664)
		(width 0.1143)
		(layer "In4.Cu")
		(net "P5E_CPU0_G3_TX_DN<6>")
	)
	(segment
		(start 368.83086 -232.657142)
		(end 368.830098 -232.65765)
		(width 0.1143)
		(layer "In4.Cu")
		(net "P5E_CPU0_G3_TX_DN<6>")
	)
	(segment
		(start 368.8461 -226.168712)
		(end 368.845338 -226.16922)
		(width 0.1143)
		(layer "In4.Cu")
		(net "P5E_CPU0_G3_TX_DN<6>")
	)
	(segment
		(start 370.414804 -220.871542)
		(end 370.414804 -221.083124)
		(width 0.14224)
		(layer "In4.Cu")
		(net "P5E_CPU0_G3_TX_DN<6>")
	)
	(segment
		(start 368.836448 -226.174554)
		(end 368.832638 -226.176586)
		(width 0.1143)
		(layer "In4.Cu")
		(net "P5E_CPU0_G3_TX_DN<6>")
	)
	(segment
		(start 370.429536 -221.339664)
		(end 370.429536 -221.80423)
		(width 0.1143)
		(layer "In4.Cu")
		(net "P5E_CPU0_G3_TX_DN<6>")
	)
	(segment
		(start 368.863626 -232.638346)
		(end 368.832638 -232.656126)
		(width 0.1143)
		(layer "In4.Cu")
		(net "P5E_CPU0_G3_TX_DN<6>")
	)
	(segment
		(start 368.793776 -232.678732)
		(end 368.769646 -232.69575)
		(width 0.1143)
		(layer "In4.Cu")
		(net "P5E_CPU0_G3_TX_DN<6>")
	)
	(segment
		(start 370.352828 -236.384084)
		(end 370.054886 -236.384084)
		(width 0.1143)
		(layer "In4.Cu")
		(net "P5E_CPU0_G3_TX_DN<6>")
	)
	(segment
		(start 317.281052 -166.990522)
		(end 317.281306 -166.990522)
		(width 0.14224)
		(layer "In4.Cu")
		(net "P5E_CPU0_G3_TX_DN<6>")
	)
	(segment
		(start 369.333526 -231.82834)
		(end 369.306348 -231.844088)
		(width 0.1143)
		(layer "In4.Cu")
		(net "P5E_CPU0_G3_TX_DN<6>")
	)
	(segment
		(start 314.341256 -157.772354)
		(end 314.25261 -158.218632)
		(width 0.14224)
		(layer "In4.Cu")
		(net "P5E_CPU0_G3_TX_DN<6>")
	)
	(segment
		(start 370.24183 -236.061504)
		(end 370.242592 -236.062012)
		(width 0.1143)
		(layer "In4.Cu")
		(net "P5E_CPU0_G3_TX_DN<6>")
	)
	(segment
		(start 368.830352 -233.630724)
		(end 368.831368 -233.631232)
		(width 0.1143)
		(layer "In4.Cu")
		(net "P5E_CPU0_G3_TX_DN<6>")
	)
	(segment
		(start 370.246148 -236.064044)
		(end 370.24818 -236.06506)
		(width 0.1143)
		(layer "In4.Cu")
		(net "P5E_CPU0_G3_TX_DN<6>")
	)
	(arc
		(start 369.489482 -225.044254)
		(mid 369.448227 -225.215225)
		(end 369.333526 -225.348546)
		(width 0.1143)
		(layer "In4.Cu")
		(net "P5E_CPU0_G3_TX_DN<6>")
	)
	(arc
		(start 368.832638 -226.176586)
		(mid 368.550604 -226.642169)
		(end 368.793522 -227.12934)
		(width 0.1143)
		(layer "In4.Cu")
		(net "P5E_CPU0_G3_TX_DN<6>")
	)
	(arc
		(start 369.959382 -222.614236)
		(mid 369.917833 -222.785658)
		(end 369.80241 -222.919036)
		(width 0.1143)
		(layer "In4.Cu")
		(net "P5E_CPU0_G3_TX_DN<6>")
	)
	(arc
		(start 369.732814 -224.579688)
		(mid 369.554001 -224.782038)
		(end 369.489482 -225.044254)
		(width 0.1143)
		(layer "In4.Cu")
		(net "P5E_CPU0_G3_TX_DN<6>")
	)
	(arc
		(start 368.549428 -229.904036)
		(mid 368.614664 -230.167627)
		(end 368.7953 -230.37038)
		(width 0.1143)
		(layer "In4.Cu")
		(net "P5E_CPU0_G3_TX_DN<6>")
	)
	(arc
		(start 369.80241 -223.929448)
		(mid 369.959387 -224.234248)
		(end 369.80241 -224.539048)
		(width 0.1143)
		(layer "In4.Cu")
		(net "P5E_CPU0_G3_TX_DN<6>")
	)
	(arc
		(start 370.429536 -221.80423)
		(mid 370.388281 -221.975201)
		(end 370.27358 -222.108522)
		(width 0.1143)
		(layer "In4.Cu")
		(net "P5E_CPU0_G3_TX_DN<6>")
	)
	(arc
		(start 368.83594 -233.633772)
		(mid 368.968576 -233.768818)
		(end 369.017042 -233.95178)
		(width 0.1143)
		(layer "In4.Cu")
		(net "P5E_CPU0_G3_TX_DN<6>")
	)
	(arc
		(start 368.79276 -229.43947)
		(mid 368.613947 -229.64182)
		(end 368.549428 -229.904036)
		(width 0.1143)
		(layer "In4.Cu")
		(net "P5E_CPU0_G3_TX_DN<6>")
	)
	(arc
		(start 369.489482 -234.764072)
		(mid 369.553997 -235.026291)
		(end 369.732814 -235.228638)
		(width 0.1143)
		(layer "In4.Cu")
		(net "P5E_CPU0_G3_TX_DN<6>")
	)
	(arc
		(start 369.019582 -225.85426)
		(mid 368.978327 -226.025231)
		(end 368.863626 -226.158552)
		(width 0.1143)
		(layer "In4.Cu")
		(net "P5E_CPU0_G3_TX_DN<6>")
	)
	(arc
		(start 369.019582 -230.714296)
		(mid 369.084818 -230.977887)
		(end 369.265454 -231.18064)
		(width 0.1143)
		(layer "In4.Cu")
		(net "P5E_CPU0_G3_TX_DN<6>")
	)
	(arc
		(start 370.27358 -236.079792)
		(mid 370.370715 -236.182661)
		(end 370.422678 -236.314234)
		(width 0.1143)
		(layer "In4.Cu")
		(net "P5E_CPU0_G3_TX_DN<6>")
	)
	(arc
		(start 369.335304 -231.22128)
		(mid 369.448711 -231.354169)
		(end 369.489482 -231.524048)
		(width 0.1143)
		(layer "In4.Cu")
		(net "P5E_CPU0_G3_TX_DN<6>")
	)
	(arc
		(start 368.861594 -227.168964)
		(mid 369.019115 -227.489282)
		(end 368.836956 -227.796344)
		(width 0.1143)
		(layer "In4.Cu")
		(net "P5E_CPU0_G3_TX_DN<6>")
	)
	(arc
		(start 369.29949 -231.847898)
		(mid 369.094545 -232.05356)
		(end 369.019582 -232.334054)
		(width 0.1143)
		(layer "In4.Cu")
		(net "P5E_CPU0_G3_TX_DN<6>")
	)
	(arc
		(start 369.017042 -233.95178)
		(mid 369.090404 -234.22989)
		(end 369.291616 -234.435396)
		(width 0.1143)
		(layer "In4.Cu")
		(net "P5E_CPU0_G3_TX_DN<6>")
	)
	(arc
		(start 369.29949 -225.368104)
		(mid 369.094545 -225.573766)
		(end 369.019582 -225.85426)
		(width 0.1143)
		(layer "In4.Cu")
		(net "P5E_CPU0_G3_TX_DN<6>")
	)
	(arc
		(start 369.80241 -235.269278)
		(mid 369.917837 -235.402654)
		(end 369.959382 -235.574078)
		(width 0.1143)
		(layer "In4.Cu")
		(net "P5E_CPU0_G3_TX_DN<6>")
	)
	(arc
		(start 368.859054 -228.787452)
		(mid 368.863654 -228.790973)
		(end 368.868198 -228.794564)
		(width 0.1143)
		(layer "In4.Cu")
		(net "P5E_CPU0_G3_TX_DN<6>")
	)
	(arc
		(start 369.489482 -231.524048)
		(mid 369.448227 -231.695019)
		(end 369.333526 -231.82834)
		(width 0.1143)
		(layer "In4.Cu")
		(net "P5E_CPU0_G3_TX_DN<6>")
	)
	(arc
		(start 369.019582 -229.094284)
		(mid 368.97882 -229.264168)
		(end 368.865404 -229.397052)
		(width 0.1143)
		(layer "In4.Cu")
		(net "P5E_CPU0_G3_TX_DN<6>")
	)
	(arc
		(start 369.333526 -234.45978)
		(mid 369.448202 -234.593114)
		(end 369.489482 -234.764072)
		(width 0.1143)
		(layer "In4.Cu")
		(net "P5E_CPU0_G3_TX_DN<6>")
	)
	(arc
		(start 370.202714 -222.14967)
		(mid 370.023901 -222.35202)
		(end 369.959382 -222.614236)
		(width 0.1143)
		(layer "In4.Cu")
		(net "P5E_CPU0_G3_TX_DN<6>")
	)
	(arc
		(start 368.868198 -228.794564)
		(mid 368.968552 -228.931976)
		(end 369.019582 -229.094284)
		(width 0.1143)
		(layer "In4.Cu")
		(net "P5E_CPU0_G3_TX_DN<6>")
	)
	(arc
		(start 368.769646 -232.69575)
		(mid 368.539816 -233.14406)
		(end 368.769646 -233.59237)
		(width 0.1143)
		(layer "In4.Cu")
		(net "P5E_CPU0_G3_TX_DN<6>")
	)
	(arc
		(start 369.959382 -235.574078)
		(mid 370.023897 -235.836297)
		(end 370.202714 -236.038644)
		(width 0.1143)
		(layer "In4.Cu")
		(net "P5E_CPU0_G3_TX_DN<6>")
	)
	(arc
		(start 369.000024 -230.508302)
		(mid 369.014377 -230.524998)
		(end 369.019582 -230.546402)
		(width 0.1143)
		(layer "In4.Cu")
		(net "P5E_CPU0_G3_TX_DN<6>")
	)
	(arc
		(start 369.732814 -222.959676)
		(mid 369.489487 -223.424242)
		(end 369.732814 -223.888808)
		(width 0.1143)
		(layer "In4.Cu")
		(net "P5E_CPU0_G3_TX_DN<6>")
	)
	(arc
		(start 369.019582 -232.334054)
		(mid 368.975511 -232.50359)
		(end 368.863626 -232.638346)
		(width 0.1143)
		(layer "In4.Cu")
		(net "P5E_CPU0_G3_TX_DN<6>")
	)
	(arc
		(start 368.836956 -227.796344)
		(mid 368.551361 -228.260764)
		(end 368.793522 -228.749352)
		(width 0.1143)
		(layer "In4.Cu")
		(net "P5E_CPU0_G3_TX_DN<6>")
	)
	(segment
		(start 418.254942 -16.366998)
		(end 418.55009 -16.662146)
		(width 0.12954)
		(layer "F.Cu")
		(net "P5E_CPU0_G3_TX_DN<5>")
	)
	(segment
		(start 418.55009 -16.662146)
		(end 418.55009 -17.34185)
		(width 0.12954)
		(layer "F.Cu")
		(net "P5E_CPU0_G3_TX_DN<5>")
	)
	(segment
		(start 418.253164 -16.366998)
		(end 418.254942 -16.366998)
		(width 0.12954)
		(layer "F.Cu")
		(net "P5E_CPU0_G3_TX_DN<5>")
	)
	(segment
		(start 369.588034 -231.789986)
		(end 370.054886 -231.524048)
		(width 0.12954)
		(layer "F.Cu")
		(net "P5E_CPU0_G3_TX_DN<5>")
	)
	(segment
		(start 418.55009 -17.34185)
		(end 418.27958 -17.61236)
		(width 0.12954)
		(layer "F.Cu")
		(net "P5E_CPU0_G3_TX_DN<5>")
	)
	(segment
		(start 369.804442 -229.397814)
		(end 369.77193 -229.41661)
		(width 0.1143)
		(layer "In4.Cu")
		(net "P5E_CPU0_G3_TX_DN<5>")
	)
	(segment
		(start 370.352828 -231.524048)
		(end 370.054886 -231.524048)
		(width 0.1143)
		(layer "In4.Cu")
		(net "P5E_CPU0_G3_TX_DN<5>")
	)
	(segment
		(start 371.615462 -222.957644)
		(end 371.612668 -222.959676)
		(width 0.1143)
		(layer "In4.Cu")
		(net "P5E_CPU0_G3_TX_DN<5>")
	)
	(segment
		(start 325.34733 -129.75844)
		(end 323.606414 -132.679186)
		(width 0.14224)
		(layer "In4.Cu")
		(net "P5E_CPU0_G3_TX_DN<5>")
	)
	(segment
		(start 369.735354 -230.37038)
		(end 369.80241 -230.409496)
		(width 0.1143)
		(layer "In4.Cu")
		(net "P5E_CPU0_G3_TX_DN<5>")
	)
	(segment
		(start 371.652546 -222.936308)
		(end 371.651784 -222.936816)
		(width 0.1143)
		(layer "In4.Cu")
		(net "P5E_CPU0_G3_TX_DN<5>")
	)
	(segment
		(start 418.57041 -17.90319)
		(end 418.57041 -20.443444)
		(width 0.14224)
		(layer "In4.Cu")
		(net "P5E_CPU0_G3_TX_DN<5>")
	)
	(segment
		(start 371.181884 -223.746822)
		(end 371.142768 -223.769682)
		(width 0.1143)
		(layer "In4.Cu")
		(net "P5E_CPU0_G3_TX_DN<5>")
	)
	(segment
		(start 318.825118 -167.14597)
		(end 319.645538 -167.89019)
		(width 0.14224)
		(layer "In4.Cu")
		(net "P5E_CPU0_G3_TX_DN<5>")
	)
	(segment
		(start 371.653816 -222.935546)
		(end 371.652546 -222.936308)
		(width 0.1143)
		(layer "In4.Cu")
		(net "P5E_CPU0_G3_TX_DN<5>")
	)
	(segment
		(start 315.18479 -158.31185)
		(end 315.18479 -161.62655)
		(width 0.14224)
		(layer "In4.Cu")
		(net "P5E_CPU0_G3_TX_DN<5>")
	)
	(segment
		(start 369.732814 -227.128832)
		(end 369.80241 -227.169472)
		(width 0.1143)
		(layer "In4.Cu")
		(net "P5E_CPU0_G3_TX_DN<5>")
	)
	(segment
		(start 364.396274 -203.378054)
		(end 370.716556 -214.024718)
		(width 0.14224)
		(layer "In4.Cu")
		(net "P5E_CPU0_G3_TX_DN<5>")
	)
	(segment
		(start 370.24183 -225.366834)
		(end 370.240814 -225.367342)
		(width 0.1143)
		(layer "In4.Cu")
		(net "P5E_CPU0_G3_TX_DN<5>")
	)
	(segment
		(start 370.676932 -224.576894)
		(end 370.672868 -224.579688)
		(width 0.1143)
		(layer "In4.Cu")
		(net "P5E_CPU0_G3_TX_DN<5>")
	)
	(segment
		(start 370.27358 -225.348546)
		(end 370.247164 -225.363786)
		(width 0.1143)
		(layer "In4.Cu")
		(net "P5E_CPU0_G3_TX_DN<5>")
	)
	(segment
		(start 370.238274 -225.368866)
		(end 370.202714 -225.389694)
		(width 0.1143)
		(layer "In4.Cu")
		(net "P5E_CPU0_G3_TX_DN<5>")
	)
	(segment
		(start 323.606414 -132.679186)
		(end 319.41897 -143.57604)
		(width 0.14224)
		(layer "In4.Cu")
		(net "P5E_CPU0_G3_TX_DN<5>")
	)
	(segment
		(start 370.422678 -231.454198)
		(end 370.352828 -231.524048)
		(width 0.1143)
		(layer "In4.Cu")
		(net "P5E_CPU0_G3_TX_DN<5>")
	)
	(segment
		(start 370.242592 -225.366326)
		(end 370.24183 -225.366834)
		(width 0.1143)
		(layer "In4.Cu")
		(net "P5E_CPU0_G3_TX_DN<5>")
	)
	(segment
		(start 369.80241 -227.779072)
		(end 369.732814 -227.819712)
		(width 0.1143)
		(layer "In4.Cu")
		(net "P5E_CPU0_G3_TX_DN<5>")
	)
	(segment
		(start 371.651784 -222.936816)
		(end 371.615462 -222.957644)
		(width 0.1143)
		(layer "In4.Cu")
		(net "P5E_CPU0_G3_TX_DN<5>")
	)
	(segment
		(start 369.80241 -226.15906)
		(end 369.732814 -226.1997)
		(width 0.1143)
		(layer "In4.Cu")
		(net "P5E_CPU0_G3_TX_DN<5>")
	)
	(segment
		(start 370.247164 -225.363786)
		(end 370.246148 -225.364294)
		(width 0.1143)
		(layer "In4.Cu")
		(net "P5E_CPU0_G3_TX_DN<5>")
	)
	(segment
		(start 369.732814 -228.748844)
		(end 369.80241 -228.789484)
		(width 0.1143)
		(layer "In4.Cu")
		(net "P5E_CPU0_G3_TX_DN<5>")
	)
	(segment
		(start 372.26367 -221.202758)
		(end 372.30939 -221.248478)
		(width 0.1143)
		(layer "In4.Cu")
		(net "P5E_CPU0_G3_TX_DN<5>")
	)
	(segment
		(start 371.212364 -223.729042)
		(end 371.181884 -223.746822)
		(width 0.1143)
		(layer "In4.Cu")
		(net "P5E_CPU0_G3_TX_DN<5>")
	)
	(segment
		(start 323.263514 -170.08856)
		(end 326.572118 -172.303948)
		(width 0.14224)
		(layer "In4.Cu")
		(net "P5E_CPU0_G3_TX_DN<5>")
	)
	(segment
		(start 370.245386 -225.364802)
		(end 370.243862 -225.365564)
		(width 0.1143)
		(layer "In4.Cu")
		(net "P5E_CPU0_G3_TX_DN<5>")
	)
	(segment
		(start 372.152418 -222.10903)
		(end 372.121938 -222.12681)
		(width 0.1143)
		(layer "In4.Cu")
		(net "P5E_CPU0_G3_TX_DN<5>")
	)
	(segment
		(start 372.26367 -220.89745)
		(end 372.26367 -221.17431)
		(width 0.14224)
		(layer "In4.Cu")
		(net "P5E_CPU0_G3_TX_DN<5>")
	)
	(segment
		(start 315.247528 -157.995366)
		(end 315.18479 -158.31185)
		(width 0.14224)
		(layer "In4.Cu")
		(net "P5E_CPU0_G3_TX_DN<5>")
	)
	(segment
		(start 370.243862 -225.365564)
		(end 370.242592 -225.366326)
		(width 0.1143)
		(layer "In4.Cu")
		(net "P5E_CPU0_G3_TX_DN<5>")
	)
	(segment
		(start 370.23929 -225.368358)
		(end 370.238274 -225.368866)
		(width 0.1143)
		(layer "In4.Cu")
		(net "P5E_CPU0_G3_TX_DN<5>")
	)
	(segment
		(start 370.246148 -225.364294)
		(end 370.245386 -225.364802)
		(width 0.1143)
		(layer "In4.Cu")
		(net "P5E_CPU0_G3_TX_DN<5>")
	)
	(segment
		(start 319.645538 -167.89019)
		(end 320.080132 -168.180766)
		(width 0.14224)
		(layer "In4.Cu")
		(net "P5E_CPU0_G3_TX_DN<5>")
	)
	(segment
		(start 320.080132 -168.180766)
		(end 320.155824 -168.221406)
		(width 0.14224)
		(layer "In4.Cu")
		(net "P5E_CPU0_G3_TX_DN<5>")
	)
	(segment
		(start 372.121938 -222.12681)
		(end 372.082822 -222.14967)
		(width 0.1143)
		(layer "In4.Cu")
		(net "P5E_CPU0_G3_TX_DN<5>")
	)
	(segment
		(start 326.572118 -172.303948)
		(end 327.468738 -173.115986)
		(width 0.14224)
		(layer "In4.Cu")
		(net "P5E_CPU0_G3_TX_DN<5>")
	)
	(segment
		(start 370.716556 -214.024718)
		(end 372.26367 -220.89745)
		(width 0.14224)
		(layer "In4.Cu")
		(net "P5E_CPU0_G3_TX_DN<5>")
	)
	(segment
		(start 418.27958 -17.61236)
		(end 418.57041 -17.90319)
		(width 0.14224)
		(layer "In4.Cu")
		(net "P5E_CPU0_G3_TX_DN<5>")
	)
	(segment
		(start 327.468738 -173.115986)
		(end 364.396274 -203.378054)
		(width 0.14224)
		(layer "In4.Cu")
		(net "P5E_CPU0_G3_TX_DN<5>")
	)
	(segment
		(start 320.156078 -168.221406)
		(end 323.26326 -170.08856)
		(width 0.14224)
		(layer "In4.Cu")
		(net "P5E_CPU0_G3_TX_DN<5>")
	)
	(segment
		(start 319.41897 -143.57604)
		(end 315.247528 -157.995366)
		(width 0.14224)
		(layer "In4.Cu")
		(net "P5E_CPU0_G3_TX_DN<5>")
	)
	(segment
		(start 315.18479 -161.62655)
		(end 316.512702 -164.832792)
		(width 0.14224)
		(layer "In4.Cu")
		(net "P5E_CPU0_G3_TX_DN<5>")
	)
	(segment
		(start 372.30939 -221.248478)
		(end 372.30939 -221.80423)
		(width 0.1143)
		(layer "In4.Cu")
		(net "P5E_CPU0_G3_TX_DN<5>")
	)
	(segment
		(start 371.683534 -222.918528)
		(end 371.653816 -222.935546)
		(width 0.1143)
		(layer "In4.Cu")
		(net "P5E_CPU0_G3_TX_DN<5>")
	)
	(segment
		(start 372.26367 -221.17431)
		(end 372.26367 -221.202758)
		(width 0.1143)
		(layer "In4.Cu")
		(net "P5E_CPU0_G3_TX_DN<5>")
	)
	(segment
		(start 320.155824 -168.221406)
		(end 320.156078 -168.221406)
		(width 0.14224)
		(layer "In4.Cu")
		(net "P5E_CPU0_G3_TX_DN<5>")
	)
	(segment
		(start 370.71173 -224.556828)
		(end 370.676932 -224.576894)
		(width 0.1143)
		(layer "In4.Cu")
		(net "P5E_CPU0_G3_TX_DN<5>")
	)
	(segment
		(start 316.512702 -164.832792)
		(end 318.825118 -167.14597)
		(width 0.14224)
		(layer "In4.Cu")
		(net "P5E_CPU0_G3_TX_DN<5>")
	)
	(segment
		(start 370.74348 -224.53854)
		(end 370.71173 -224.556828)
		(width 0.1143)
		(layer "In4.Cu")
		(net "P5E_CPU0_G3_TX_DN<5>")
	)
	(segment
		(start 370.240814 -225.367342)
		(end 370.23929 -225.368358)
		(width 0.1143)
		(layer "In4.Cu")
		(net "P5E_CPU0_G3_TX_DN<5>")
	)
	(segment
		(start 370.202714 -231.178862)
		(end 370.275358 -231.22128)
		(width 0.1143)
		(layer "In4.Cu")
		(net "P5E_CPU0_G3_TX_DN<5>")
	)
	(segment
		(start 323.26326 -170.08856)
		(end 323.263514 -170.08856)
		(width 0.14224)
		(layer "In4.Cu")
		(net "P5E_CPU0_G3_TX_DN<5>")
	)
	(segment
		(start 418.57041 -20.443444)
		(end 325.34733 -129.75844)
		(width 0.14224)
		(layer "In4.Cu")
		(net "P5E_CPU0_G3_TX_DN<5>")
	)
	(segment
		(start 369.77193 -229.41661)
		(end 369.732814 -229.43947)
		(width 0.1143)
		(layer "In4.Cu")
		(net "P5E_CPU0_G3_TX_DN<5>")
	)
	(arc
		(start 372.30939 -221.80423)
		(mid 372.267841 -221.975652)
		(end 372.152418 -222.10903)
		(width 0.1143)
		(layer "In4.Cu")
		(net "P5E_CPU0_G3_TX_DN<5>")
	)
	(arc
		(start 369.732814 -229.43947)
		(mid 369.554001 -229.64182)
		(end 369.489482 -229.904036)
		(width 0.1143)
		(layer "In4.Cu")
		(net "P5E_CPU0_G3_TX_DN<5>")
	)
	(arc
		(start 369.959382 -230.714296)
		(mid 370.023897 -230.976515)
		(end 370.202714 -231.178862)
		(width 0.1143)
		(layer "In4.Cu")
		(net "P5E_CPU0_G3_TX_DN<5>")
	)
	(arc
		(start 371.83949 -222.614236)
		(mid 371.798235 -222.785207)
		(end 371.683534 -222.918528)
		(width 0.1143)
		(layer "In4.Cu")
		(net "P5E_CPU0_G3_TX_DN<5>")
	)
	(arc
		(start 370.672868 -224.579688)
		(mid 370.494055 -224.782038)
		(end 370.429536 -225.044254)
		(width 0.1143)
		(layer "In4.Cu")
		(net "P5E_CPU0_G3_TX_DN<5>")
	)
	(arc
		(start 370.429536 -225.044254)
		(mid 370.388281 -225.215225)
		(end 370.27358 -225.348546)
		(width 0.1143)
		(layer "In4.Cu")
		(net "P5E_CPU0_G3_TX_DN<5>")
	)
	(arc
		(start 371.612668 -222.959676)
		(mid 371.433855 -223.162026)
		(end 371.369336 -223.424242)
		(width 0.1143)
		(layer "In4.Cu")
		(net "P5E_CPU0_G3_TX_DN<5>")
	)
	(arc
		(start 369.80241 -230.409496)
		(mid 369.917837 -230.542872)
		(end 369.959382 -230.714296)
		(width 0.1143)
		(layer "In4.Cu")
		(net "P5E_CPU0_G3_TX_DN<5>")
	)
	(arc
		(start 369.732814 -226.1997)
		(mid 369.489487 -226.664266)
		(end 369.732814 -227.128832)
		(width 0.1143)
		(layer "In4.Cu")
		(net "P5E_CPU0_G3_TX_DN<5>")
	)
	(arc
		(start 372.082822 -222.14967)
		(mid 371.904009 -222.35202)
		(end 371.83949 -222.614236)
		(width 0.1143)
		(layer "In4.Cu")
		(net "P5E_CPU0_G3_TX_DN<5>")
	)
	(arc
		(start 369.489482 -229.904036)
		(mid 369.554718 -230.167627)
		(end 369.735354 -230.37038)
		(width 0.1143)
		(layer "In4.Cu")
		(net "P5E_CPU0_G3_TX_DN<5>")
	)
	(arc
		(start 369.959382 -225.85426)
		(mid 369.917833 -226.025682)
		(end 369.80241 -226.15906)
		(width 0.1143)
		(layer "In4.Cu")
		(net "P5E_CPU0_G3_TX_DN<5>")
	)
	(arc
		(start 370.899436 -224.234248)
		(mid 370.858181 -224.405219)
		(end 370.74348 -224.53854)
		(width 0.1143)
		(layer "In4.Cu")
		(net "P5E_CPU0_G3_TX_DN<5>")
	)
	(arc
		(start 369.80241 -227.169472)
		(mid 369.959387 -227.474272)
		(end 369.80241 -227.779072)
		(width 0.1143)
		(layer "In4.Cu")
		(net "P5E_CPU0_G3_TX_DN<5>")
	)
	(arc
		(start 370.275358 -231.22128)
		(mid 370.371246 -231.323688)
		(end 370.422678 -231.454198)
		(width 0.1143)
		(layer "In4.Cu")
		(net "P5E_CPU0_G3_TX_DN<5>")
	)
	(arc
		(start 371.142768 -223.769682)
		(mid 370.963955 -223.972032)
		(end 370.899436 -224.234248)
		(width 0.1143)
		(layer "In4.Cu")
		(net "P5E_CPU0_G3_TX_DN<5>")
	)
	(arc
		(start 369.959382 -229.094284)
		(mid 369.918416 -229.26469)
		(end 369.804442 -229.397814)
		(width 0.1143)
		(layer "In4.Cu")
		(net "P5E_CPU0_G3_TX_DN<5>")
	)
	(arc
		(start 369.80241 -228.789484)
		(mid 369.917837 -228.92286)
		(end 369.959382 -229.094284)
		(width 0.1143)
		(layer "In4.Cu")
		(net "P5E_CPU0_G3_TX_DN<5>")
	)
	(arc
		(start 370.202714 -225.389694)
		(mid 370.023901 -225.592044)
		(end 369.959382 -225.85426)
		(width 0.1143)
		(layer "In4.Cu")
		(net "P5E_CPU0_G3_TX_DN<5>")
	)
	(arc
		(start 371.369336 -223.424242)
		(mid 371.327787 -223.595664)
		(end 371.212364 -223.729042)
		(width 0.1143)
		(layer "In4.Cu")
		(net "P5E_CPU0_G3_TX_DN<5>")
	)
	(arc
		(start 369.732814 -227.819712)
		(mid 369.489487 -228.284278)
		(end 369.732814 -228.748844)
		(width 0.1143)
		(layer "In4.Cu")
		(net "P5E_CPU0_G3_TX_DN<5>")
	)
	(segment
		(start 421.343074 -18.186908)
		(end 421.343074 -18.866612)
		(width 0.12954)
		(layer "F.Cu")
		(net "P5E_CPU0_G3_TX_DN<4>")
	)
	(segment
		(start 421.343074 -18.866612)
		(end 421.072564 -19.137122)
		(width 0.12954)
		(layer "F.Cu")
		(net "P5E_CPU0_G3_TX_DN<4>")
	)
	(segment
		(start 369.588034 -233.409998)
		(end 370.054886 -233.14406)
		(width 0.12954)
		(layer "F.Cu")
		(net "P5E_CPU0_G3_TX_DN<4>")
	)
	(segment
		(start 421.047164 -17.890998)
		(end 421.343074 -18.186908)
		(width 0.12954)
		(layer "F.Cu")
		(net "P5E_CPU0_G3_TX_DN<4>")
	)
	(segment
		(start 373.203724 -221.17431)
		(end 373.203724 -221.202758)
		(width 0.1143)
		(layer "In4.Cu")
		(net "P5E_CPU0_G3_TX_DN<4>")
	)
	(segment
		(start 370.712746 -227.1522)
		(end 370.743734 -227.16998)
		(width 0.1143)
		(layer "In4.Cu")
		(net "P5E_CPU0_G3_TX_DN<4>")
	)
	(segment
		(start 421.072564 -19.137122)
		(end 421.363394 -19.427952)
		(width 0.14224)
		(layer "In4.Cu")
		(net "P5E_CPU0_G3_TX_DN<4>")
	)
	(segment
		(start 421.363394 -19.427952)
		(end 421.363394 -20.44319)
		(width 0.14224)
		(layer "In4.Cu")
		(net "P5E_CPU0_G3_TX_DN<4>")
	)
	(segment
		(start 370.709444 -232.658158)
		(end 370.672868 -232.679494)
		(width 0.1143)
		(layer "In4.Cu")
		(net "P5E_CPU0_G3_TX_DN<4>")
	)
	(segment
		(start 371.683534 -224.53854)
		(end 371.651784 -224.556828)
		(width 0.1143)
		(layer "In4.Cu")
		(net "P5E_CPU0_G3_TX_DN<4>")
	)
	(segment
		(start 370.710968 -227.151184)
		(end 370.711984 -227.151692)
		(width 0.1143)
		(layer "In4.Cu")
		(net "P5E_CPU0_G3_TX_DN<4>")
	)
	(segment
		(start 370.712746 -227.796344)
		(end 370.711984 -227.796852)
		(width 0.1143)
		(layer "In4.Cu")
		(net "P5E_CPU0_G3_TX_DN<4>")
	)
	(segment
		(start 370.709444 -227.798376)
		(end 370.672868 -227.819712)
		(width 0.1143)
		(layer "In4.Cu")
		(net "P5E_CPU0_G3_TX_DN<4>")
	)
	(segment
		(start 371.616986 -224.576894)
		(end 371.612922 -224.579688)
		(width 0.1143)
		(layer "In4.Cu")
		(net "P5E_CPU0_G3_TX_DN<4>")
	)
	(segment
		(start 370.710968 -227.79736)
		(end 370.709444 -227.798376)
		(width 0.1143)
		(layer "In4.Cu")
		(net "P5E_CPU0_G3_TX_DN<4>")
	)
	(segment
		(start 317.321692 -164.319204)
		(end 319.703958 -166.665402)
		(width 0.14224)
		(layer "In4.Cu")
		(net "P5E_CPU0_G3_TX_DN<4>")
	)
	(segment
		(start 323.109336 -168.83253)
		(end 323.503544 -169.10177)
		(width 0.14224)
		(layer "In4.Cu")
		(net "P5E_CPU0_G3_TX_DN<4>")
	)
	(segment
		(start 371.183662 -225.365818)
		(end 371.181376 -225.367088)
		(width 0.1143)
		(layer "In4.Cu")
		(net "P5E_CPU0_G3_TX_DN<4>")
	)
	(segment
		(start 316.117478 -161.441384)
		(end 316.117478 -161.442146)
		(width 0.14224)
		(layer "In4.Cu")
		(net "P5E_CPU0_G3_TX_DN<4>")
	)
	(segment
		(start 323.507354 -169.099738)
		(end 323.707506 -169.234104)
		(width 0.14224)
		(layer "In4.Cu")
		(net "P5E_CPU0_G3_TX_DN<4>")
	)
	(segment
		(start 370.709444 -228.77018)
		(end 370.710968 -228.771196)
		(width 0.1143)
		(layer "In4.Cu")
		(net "P5E_CPU0_G3_TX_DN<4>")
	)
	(segment
		(start 372.623588 -222.918528)
		(end 372.552722 -222.959676)
		(width 0.1143)
		(layer "In4.Cu")
		(net "P5E_CPU0_G3_TX_DN<4>")
	)
	(segment
		(start 316.117478 -161.442146)
		(end 317.321692 -164.319204)
		(width 0.14224)
		(layer "In4.Cu")
		(net "P5E_CPU0_G3_TX_DN<4>")
	)
	(segment
		(start 373.203724 -221.202758)
		(end 373.249444 -221.248478)
		(width 0.1143)
		(layer "In4.Cu")
		(net "P5E_CPU0_G3_TX_DN<4>")
	)
	(segment
		(start 370.435632 -233.061256)
		(end 370.352828 -233.14406)
		(width 0.1143)
		(layer "In4.Cu")
		(net "P5E_CPU0_G3_TX_DN<4>")
	)
	(segment
		(start 371.651784 -224.556828)
		(end 371.616986 -224.576894)
		(width 0.1143)
		(layer "In4.Cu")
		(net "P5E_CPU0_G3_TX_DN<4>")
	)
	(segment
		(start 371.178074 -225.368866)
		(end 371.177058 -225.369374)
		(width 0.1143)
		(layer "In4.Cu")
		(net "P5E_CPU0_G3_TX_DN<4>")
	)
	(segment
		(start 370.672868 -228.748844)
		(end 370.709444 -228.77018)
		(width 0.1143)
		(layer "In4.Cu")
		(net "P5E_CPU0_G3_TX_DN<4>")
	)
	(segment
		(start 316.15507 -158.213552)
		(end 316.117224 -158.40456)
		(width 0.14224)
		(layer "In4.Cu")
		(net "P5E_CPU0_G3_TX_DN<4>")
	)
	(segment
		(start 370.672868 -227.128832)
		(end 370.709444 -227.150168)
		(width 0.1143)
		(layer "In4.Cu")
		(net "P5E_CPU0_G3_TX_DN<4>")
	)
	(segment
		(start 365.10722 -202.748388)
		(end 371.892068 -214.177626)
		(width 0.14224)
		(layer "In4.Cu")
		(net "P5E_CPU0_G3_TX_DN<4>")
	)
	(segment
		(start 371.145562 -231.18064)
		(end 371.215412 -231.22128)
		(width 0.1143)
		(layer "In4.Cu")
		(net "P5E_CPU0_G3_TX_DN<4>")
	)
	(segment
		(start 370.712746 -228.772212)
		(end 370.743734 -228.789992)
		(width 0.1143)
		(layer "In4.Cu")
		(net "P5E_CPU0_G3_TX_DN<4>")
	)
	(segment
		(start 323.503544 -169.10177)
		(end 323.507354 -169.099738)
		(width 0.14224)
		(layer "In4.Cu")
		(net "P5E_CPU0_G3_TX_DN<4>")
	)
	(segment
		(start 370.710968 -228.771196)
		(end 370.711984 -228.771704)
		(width 0.1143)
		(layer "In4.Cu")
		(net "P5E_CPU0_G3_TX_DN<4>")
	)
	(segment
		(start 319.703958 -166.665402)
		(end 323.109336 -168.83253)
		(width 0.14224)
		(layer "In4.Cu")
		(net "P5E_CPU0_G3_TX_DN<4>")
	)
	(segment
		(start 370.745512 -229.397052)
		(end 370.672868 -229.43947)
		(width 0.1143)
		(layer "In4.Cu")
		(net "P5E_CPU0_G3_TX_DN<4>")
	)
	(segment
		(start 316.117224 -158.40456)
		(end 316.117224 -161.440876)
		(width 0.14224)
		(layer "In4.Cu")
		(net "P5E_CPU0_G3_TX_DN<4>")
	)
	(segment
		(start 371.18036 -225.367596)
		(end 371.178074 -225.368866)
		(width 0.1143)
		(layer "In4.Cu")
		(net "P5E_CPU0_G3_TX_DN<4>")
	)
	(segment
		(start 372.649242 -222.899986)
		(end 372.623588 -222.918528)
		(width 0.1143)
		(layer "In4.Cu")
		(net "P5E_CPU0_G3_TX_DN<4>")
	)
	(segment
		(start 328.774298 -172.83811)
		(end 330.430886 -174.338234)
		(width 0.14224)
		(layer "In4.Cu")
		(net "P5E_CPU0_G3_TX_DN<4>")
	)
	(segment
		(start 373.093488 -222.108522)
		(end 373.025416 -222.147892)
		(width 0.1143)
		(layer "In4.Cu")
		(net "P5E_CPU0_G3_TX_DN<4>")
	)
	(segment
		(start 370.743734 -227.778564)
		(end 370.712746 -227.796344)
		(width 0.1143)
		(layer "In4.Cu")
		(net "P5E_CPU0_G3_TX_DN<4>")
	)
	(segment
		(start 370.710968 -230.394002)
		(end 370.716302 -230.39705)
		(width 0.1143)
		(layer "In4.Cu")
		(net "P5E_CPU0_G3_TX_DN<4>")
	)
	(segment
		(start 370.712746 -226.176332)
		(end 370.711984 -226.17684)
		(width 0.1143)
		(layer "In4.Cu")
		(net "P5E_CPU0_G3_TX_DN<4>")
	)
	(segment
		(start 373.203724 -220.813884)
		(end 373.203724 -221.17431)
		(width 0.14224)
		(layer "In4.Cu")
		(net "P5E_CPU0_G3_TX_DN<4>")
	)
	(segment
		(start 370.711984 -226.17684)
		(end 370.710968 -226.177348)
		(width 0.1143)
		(layer "In4.Cu")
		(net "P5E_CPU0_G3_TX_DN<4>")
	)
	(segment
		(start 373.249444 -221.248478)
		(end 373.249444 -221.80423)
		(width 0.1143)
		(layer "In4.Cu")
		(net "P5E_CPU0_G3_TX_DN<4>")
	)
	(segment
		(start 370.711984 -228.771704)
		(end 370.712746 -228.772212)
		(width 0.1143)
		(layer "In4.Cu")
		(net "P5E_CPU0_G3_TX_DN<4>")
	)
	(segment
		(start 370.905278 -232.326942)
		(end 370.905278 -232.329482)
		(width 0.1143)
		(layer "In4.Cu")
		(net "P5E_CPU0_G3_TX_DN<4>")
	)
	(segment
		(start 371.892068 -214.177626)
		(end 373.203724 -220.813884)
		(width 0.14224)
		(layer "In4.Cu")
		(net "P5E_CPU0_G3_TX_DN<4>")
	)
	(segment
		(start 371.181376 -225.367088)
		(end 371.18036 -225.367596)
		(width 0.1143)
		(layer "In4.Cu")
		(net "P5E_CPU0_G3_TX_DN<4>")
	)
	(segment
		(start 320.30289 -143.876268)
		(end 316.15507 -158.213552)
		(width 0.14224)
		(layer "In4.Cu")
		(net "P5E_CPU0_G3_TX_DN<4>")
	)
	(segment
		(start 370.717826 -232.653332)
		(end 370.712746 -232.656126)
		(width 0.1143)
		(layer "In4.Cu")
		(net "P5E_CPU0_G3_TX_DN<4>")
	)
	(segment
		(start 370.352828 -233.14406)
		(end 370.054886 -233.14406)
		(width 0.1143)
		(layer "In4.Cu")
		(net "P5E_CPU0_G3_TX_DN<4>")
	)
	(segment
		(start 370.741448 -226.159822)
		(end 370.712746 -226.176332)
		(width 0.1143)
		(layer "In4.Cu")
		(net "P5E_CPU0_G3_TX_DN<4>")
	)
	(segment
		(start 372.121938 -223.746822)
		(end 372.082822 -223.769682)
		(width 0.1143)
		(layer "In4.Cu")
		(net "P5E_CPU0_G3_TX_DN<4>")
	)
	(segment
		(start 370.709444 -227.150168)
		(end 370.710968 -227.151184)
		(width 0.1143)
		(layer "In4.Cu")
		(net "P5E_CPU0_G3_TX_DN<4>")
	)
	(segment
		(start 370.710968 -232.657142)
		(end 370.709444 -232.658158)
		(width 0.1143)
		(layer "In4.Cu")
		(net "P5E_CPU0_G3_TX_DN<4>")
	)
	(segment
		(start 372.779544 -222.614236)
		(end 372.779544 -222.645732)
		(width 0.1143)
		(layer "In4.Cu")
		(net "P5E_CPU0_G3_TX_DN<4>")
	)
	(segment
		(start 371.177058 -225.369374)
		(end 371.145562 -225.387916)
		(width 0.1143)
		(layer "In4.Cu")
		(net "P5E_CPU0_G3_TX_DN<4>")
	)
	(segment
		(start 316.117224 -161.440876)
		(end 316.117478 -161.441384)
		(width 0.14224)
		(layer "In4.Cu")
		(net "P5E_CPU0_G3_TX_DN<4>")
	)
	(segment
		(start 370.711984 -227.151692)
		(end 370.712746 -227.1522)
		(width 0.1143)
		(layer "In4.Cu")
		(net "P5E_CPU0_G3_TX_DN<4>")
	)
	(segment
		(start 326.91324 -171.386246)
		(end 328.774298 -172.83811)
		(width 0.14224)
		(layer "In4.Cu")
		(net "P5E_CPU0_G3_TX_DN<4>")
	)
	(segment
		(start 324.447662 -133.090412)
		(end 320.30289 -143.876268)
		(width 0.14224)
		(layer "In4.Cu")
		(net "P5E_CPU0_G3_TX_DN<4>")
	)
	(segment
		(start 421.363394 -20.44319)
		(end 325.751698 -130.901694)
		(width 0.14224)
		(layer "In4.Cu")
		(net "P5E_CPU0_G3_TX_DN<4>")
	)
	(segment
		(start 370.712746 -232.656126)
		(end 370.711984 -232.656634)
		(width 0.1143)
		(layer "In4.Cu")
		(net "P5E_CPU0_G3_TX_DN<4>")
	)
	(segment
		(start 323.707506 -169.234104)
		(end 326.91324 -171.386246)
		(width 0.14224)
		(layer "In4.Cu")
		(net "P5E_CPU0_G3_TX_DN<4>")
	)
	(segment
		(start 325.751698 -130.901694)
		(end 324.447662 -133.090412)
		(width 0.14224)
		(layer "In4.Cu")
		(net "P5E_CPU0_G3_TX_DN<4>")
	)
	(segment
		(start 370.709444 -226.178364)
		(end 370.672868 -226.1997)
		(width 0.1143)
		(layer "In4.Cu")
		(net "P5E_CPU0_G3_TX_DN<4>")
	)
	(segment
		(start 330.430886 -174.338234)
		(end 365.10722 -202.748388)
		(width 0.14224)
		(layer "In4.Cu")
		(net "P5E_CPU0_G3_TX_DN<4>")
	)
	(segment
		(start 370.710968 -226.177348)
		(end 370.709444 -226.178364)
		(width 0.1143)
		(layer "In4.Cu")
		(net "P5E_CPU0_G3_TX_DN<4>")
	)
	(segment
		(start 371.213634 -231.82834)
		(end 371.181884 -231.846628)
		(width 0.1143)
		(layer "In4.Cu")
		(net "P5E_CPU0_G3_TX_DN<4>")
	)
	(segment
		(start 370.711984 -232.656634)
		(end 370.710968 -232.657142)
		(width 0.1143)
		(layer "In4.Cu")
		(net "P5E_CPU0_G3_TX_DN<4>")
	)
	(segment
		(start 370.711984 -227.796852)
		(end 370.710968 -227.79736)
		(width 0.1143)
		(layer "In4.Cu")
		(net "P5E_CPU0_G3_TX_DN<4>")
	)
	(segment
		(start 372.152418 -223.729042)
		(end 372.121938 -223.746822)
		(width 0.1143)
		(layer "In4.Cu")
		(net "P5E_CPU0_G3_TX_DN<4>")
	)
	(arc
		(start 371.36959 -225.044254)
		(mid 371.319767 -225.229984)
		(end 371.183662 -225.365818)
		(width 0.1143)
		(layer "In4.Cu")
		(net "P5E_CPU0_G3_TX_DN<4>")
	)
	(arc
		(start 370.429536 -229.904036)
		(mid 370.504904 -230.186551)
		(end 370.710968 -230.394002)
		(width 0.1143)
		(layer "In4.Cu")
		(net "P5E_CPU0_G3_TX_DN<4>")
	)
	(arc
		(start 370.439442 -233.038396)
		(mid 370.437419 -233.049806)
		(end 370.435632 -233.061256)
		(width 0.1143)
		(layer "In4.Cu")
		(net "P5E_CPU0_G3_TX_DN<4>")
	)
	(arc
		(start 373.025416 -222.147892)
		(mid 372.844764 -222.350637)
		(end 372.779544 -222.614236)
		(width 0.1143)
		(layer "In4.Cu")
		(net "P5E_CPU0_G3_TX_DN<4>")
	)
	(arc
		(start 371.145562 -225.387916)
		(mid 370.96491 -225.590661)
		(end 370.89969 -225.85426)
		(width 0.1143)
		(layer "In4.Cu")
		(net "P5E_CPU0_G3_TX_DN<4>")
	)
	(arc
		(start 370.89969 -225.85426)
		(mid 370.854679 -226.024696)
		(end 370.741448 -226.159822)
		(width 0.1143)
		(layer "In4.Cu")
		(net "P5E_CPU0_G3_TX_DN<4>")
	)
	(arc
		(start 371.215412 -231.22128)
		(mid 371.328819 -231.354169)
		(end 371.36959 -231.524048)
		(width 0.1143)
		(layer "In4.Cu")
		(net "P5E_CPU0_G3_TX_DN<4>")
	)
	(arc
		(start 371.83949 -224.234248)
		(mid 371.798235 -224.405219)
		(end 371.683534 -224.53854)
		(width 0.1143)
		(layer "In4.Cu")
		(net "P5E_CPU0_G3_TX_DN<4>")
	)
	(arc
		(start 371.181884 -231.846628)
		(mid 370.979344 -232.049798)
		(end 370.905278 -232.326942)
		(width 0.1143)
		(layer "In4.Cu")
		(net "P5E_CPU0_G3_TX_DN<4>")
	)
	(arc
		(start 370.743734 -228.789992)
		(mid 370.855531 -228.924793)
		(end 370.89969 -229.094284)
		(width 0.1143)
		(layer "In4.Cu")
		(net "P5E_CPU0_G3_TX_DN<4>")
	)
	(arc
		(start 372.552722 -222.959676)
		(mid 372.373909 -223.162026)
		(end 372.30939 -223.424242)
		(width 0.1143)
		(layer "In4.Cu")
		(net "P5E_CPU0_G3_TX_DN<4>")
	)
	(arc
		(start 370.672868 -227.819712)
		(mid 370.429541 -228.284278)
		(end 370.672868 -228.748844)
		(width 0.1143)
		(layer "In4.Cu")
		(net "P5E_CPU0_G3_TX_DN<4>")
	)
	(arc
		(start 371.36959 -231.524048)
		(mid 371.328335 -231.695019)
		(end 371.213634 -231.82834)
		(width 0.1143)
		(layer "In4.Cu")
		(net "P5E_CPU0_G3_TX_DN<4>")
	)
	(arc
		(start 370.716302 -230.39705)
		(mid 370.850574 -230.531067)
		(end 370.89969 -230.714296)
		(width 0.1143)
		(layer "In4.Cu")
		(net "P5E_CPU0_G3_TX_DN<4>")
	)
	(arc
		(start 373.249444 -221.80423)
		(mid 373.208189 -221.975201)
		(end 373.093488 -222.108522)
		(width 0.1143)
		(layer "In4.Cu")
		(net "P5E_CPU0_G3_TX_DN<4>")
	)
	(arc
		(start 370.672868 -229.43947)
		(mid 370.494055 -229.64182)
		(end 370.429536 -229.904036)
		(width 0.1143)
		(layer "In4.Cu")
		(net "P5E_CPU0_G3_TX_DN<4>")
	)
	(arc
		(start 372.082822 -223.769682)
		(mid 371.904009 -223.972032)
		(end 371.83949 -224.234248)
		(width 0.1143)
		(layer "In4.Cu")
		(net "P5E_CPU0_G3_TX_DN<4>")
	)
	(arc
		(start 372.779544 -222.645732)
		(mid 372.745069 -222.788579)
		(end 372.649242 -222.899986)
		(width 0.1143)
		(layer "In4.Cu")
		(net "P5E_CPU0_G3_TX_DN<4>")
	)
	(arc
		(start 372.30939 -223.424242)
		(mid 372.267841 -223.595664)
		(end 372.152418 -223.729042)
		(width 0.1143)
		(layer "In4.Cu")
		(net "P5E_CPU0_G3_TX_DN<4>")
	)
	(arc
		(start 370.905278 -232.329482)
		(mid 370.855028 -232.516564)
		(end 370.717826 -232.653332)
		(width 0.1143)
		(layer "In4.Cu")
		(net "P5E_CPU0_G3_TX_DN<4>")
	)
	(arc
		(start 370.89969 -229.094284)
		(mid 370.858928 -229.264168)
		(end 370.745512 -229.397052)
		(width 0.1143)
		(layer "In4.Cu")
		(net "P5E_CPU0_G3_TX_DN<4>")
	)
	(arc
		(start 370.89969 -230.714296)
		(mid 370.964926 -230.977887)
		(end 371.145562 -231.18064)
		(width 0.1143)
		(layer "In4.Cu")
		(net "P5E_CPU0_G3_TX_DN<4>")
	)
	(arc
		(start 370.672868 -226.1997)
		(mid 370.429541 -226.664266)
		(end 370.672868 -227.128832)
		(width 0.1143)
		(layer "In4.Cu")
		(net "P5E_CPU0_G3_TX_DN<4>")
	)
	(arc
		(start 370.672868 -232.679494)
		(mid 370.520881 -232.836002)
		(end 370.439442 -233.038396)
		(width 0.1143)
		(layer "In4.Cu")
		(net "P5E_CPU0_G3_TX_DN<4>")
	)
	(arc
		(start 370.743734 -227.16998)
		(mid 370.895323 -227.474272)
		(end 370.743734 -227.778564)
		(width 0.1143)
		(layer "In4.Cu")
		(net "P5E_CPU0_G3_TX_DN<4>")
	)
	(arc
		(start 371.612922 -224.579688)
		(mid 371.434109 -224.782038)
		(end 371.36959 -225.044254)
		(width 0.1143)
		(layer "In4.Cu")
		(net "P5E_CPU0_G3_TX_DN<4>")
	)
	(segment
		(start 369.588034 -235.03001)
		(end 370.054886 -234.764072)
		(width 0.12954)
		(layer "F.Cu")
		(net "P5E_CPU0_G3_TX_DN<3>")
	)
	(segment
		(start 423.841164 -16.366998)
		(end 424.13809 -16.663924)
		(width 0.12954)
		(layer "F.Cu")
		(net "P5E_CPU0_G3_TX_DN<3>")
	)
	(segment
		(start 424.13809 -17.34185)
		(end 423.86758 -17.61236)
		(width 0.12954)
		(layer "F.Cu")
		(net "P5E_CPU0_G3_TX_DN<3>")
	)
	(segment
		(start 424.13809 -16.663924)
		(end 424.13809 -17.34185)
		(width 0.12954)
		(layer "F.Cu")
		(net "P5E_CPU0_G3_TX_DN<3>")
	)
	(segment
		(start 423.86758 -17.61236)
		(end 424.15841 -17.90319)
		(width 0.14224)
		(layer "In4.Cu")
		(net "P5E_CPU0_G3_TX_DN<3>")
	)
	(segment
		(start 372.128034 -231.843072)
		(end 372.12651 -231.844088)
		(width 0.1143)
		(layer "In4.Cu")
		(net "P5E_CPU0_G3_TX_DN<3>")
	)
	(segment
		(start 372.1227 -225.366326)
		(end 372.121938 -225.366834)
		(width 0.1143)
		(layer "In4.Cu")
		(net "P5E_CPU0_G3_TX_DN<3>")
	)
	(segment
		(start 373.53367 -222.935546)
		(end 373.5324 -222.936308)
		(width 0.1143)
		(layer "In4.Cu")
		(net "P5E_CPU0_G3_TX_DN<3>")
	)
	(segment
		(start 371.181376 -233.465116)
		(end 371.181122 -233.465116)
		(width 0.1143)
		(layer "In4.Cu")
		(net "P5E_CPU0_G3_TX_DN<3>")
	)
	(segment
		(start 373.535194 -222.934784)
		(end 373.53367 -222.935546)
		(width 0.1143)
		(layer "In4.Cu")
		(net "P5E_CPU0_G3_TX_DN<3>")
	)
	(segment
		(start 372.121938 -231.846628)
		(end 372.120922 -231.847136)
		(width 0.1143)
		(layer "In4.Cu")
		(net "P5E_CPU0_G3_TX_DN<3>")
	)
	(segment
		(start 371.615462 -230.37038)
		(end 371.682518 -230.409496)
		(width 0.1143)
		(layer "In4.Cu")
		(net "P5E_CPU0_G3_TX_DN<3>")
	)
	(segment
		(start 424.15841 -17.90319)
		(end 424.15841 -20.441158)
		(width 0.14224)
		(layer "In4.Cu")
		(net "P5E_CPU0_G3_TX_DN<3>")
	)
	(segment
		(start 372.153688 -225.348546)
		(end 372.128034 -225.363278)
		(width 0.1143)
		(layer "In4.Cu")
		(net "P5E_CPU0_G3_TX_DN<3>")
	)
	(segment
		(start 373.5324 -222.936308)
		(end 373.531638 -222.936816)
		(width 0.1143)
		(layer "In4.Cu")
		(net "P5E_CPU0_G3_TX_DN<3>")
	)
	(segment
		(start 373.536464 -222.934022)
		(end 373.535194 -222.934784)
		(width 0.1143)
		(layer "In4.Cu")
		(net "P5E_CPU0_G3_TX_DN<3>")
	)
	(segment
		(start 365.996474 -202.25766)
		(end 372.934738 -214.002366)
		(width 0.14224)
		(layer "In4.Cu")
		(net "P5E_CPU0_G3_TX_DN<3>")
	)
	(segment
		(start 372.120922 -225.367342)
		(end 372.119398 -225.368358)
		(width 0.1143)
		(layer "In4.Cu")
		(net "P5E_CPU0_G3_TX_DN<3>")
	)
	(segment
		(start 371.682518 -226.15906)
		(end 371.612922 -226.1997)
		(width 0.1143)
		(layer "In4.Cu")
		(net "P5E_CPU0_G3_TX_DN<3>")
	)
	(segment
		(start 374.143778 -221.202758)
		(end 374.189498 -221.248478)
		(width 0.1143)
		(layer "In4.Cu")
		(net "P5E_CPU0_G3_TX_DN<3>")
	)
	(segment
		(start 371.612922 -227.128832)
		(end 371.682518 -227.169472)
		(width 0.1143)
		(layer "In4.Cu")
		(net "P5E_CPU0_G3_TX_DN<3>")
	)
	(segment
		(start 374.033542 -222.108522)
		(end 374.001792 -222.12681)
		(width 0.1143)
		(layer "In4.Cu")
		(net "P5E_CPU0_G3_TX_DN<3>")
	)
	(segment
		(start 332.825344 -175.091852)
		(end 365.996474 -202.25766)
		(width 0.14224)
		(layer "In4.Cu")
		(net "P5E_CPU0_G3_TX_DN<3>")
	)
	(segment
		(start 372.623588 -224.53854)
		(end 372.591838 -224.556828)
		(width 0.1143)
		(layer "In4.Cu")
		(net "P5E_CPU0_G3_TX_DN<3>")
	)
	(segment
		(start 321.187826 -144.17294)
		(end 317.061342 -158.436564)
		(width 0.14224)
		(layer "In4.Cu")
		(net "P5E_CPU0_G3_TX_DN<3>")
	)
	(segment
		(start 317.061342 -158.436564)
		(end 317.049658 -158.496)
		(width 0.14224)
		(layer "In4.Cu")
		(net "P5E_CPU0_G3_TX_DN<3>")
	)
	(segment
		(start 374.143778 -221.17431)
		(end 374.143778 -221.202758)
		(width 0.1143)
		(layer "In4.Cu")
		(net "P5E_CPU0_G3_TX_DN<3>")
	)
	(segment
		(start 370.712492 -234.276646)
		(end 370.711984 -234.276646)
		(width 0.1143)
		(layer "In4.Cu")
		(net "P5E_CPU0_G3_TX_DN<3>")
	)
	(segment
		(start 374.189498 -221.248478)
		(end 374.189498 -221.80423)
		(width 0.1143)
		(layer "In4.Cu")
		(net "P5E_CPU0_G3_TX_DN<3>")
	)
	(segment
		(start 373.540528 -222.931482)
		(end 373.537226 -222.933514)
		(width 0.1143)
		(layer "In4.Cu")
		(net "P5E_CPU0_G3_TX_DN<3>")
	)
	(segment
		(start 325.28891 -133.500876)
		(end 321.187826 -144.17294)
		(width 0.14224)
		(layer "In4.Cu")
		(net "P5E_CPU0_G3_TX_DN<3>")
	)
	(segment
		(start 373.563388 -222.918528)
		(end 373.543068 -222.929958)
		(width 0.1143)
		(layer "In4.Cu")
		(net "P5E_CPU0_G3_TX_DN<3>")
	)
	(segment
		(start 372.12651 -225.364294)
		(end 372.12397 -225.365564)
		(width 0.1143)
		(layer "In4.Cu")
		(net "P5E_CPU0_G3_TX_DN<3>")
	)
	(segment
		(start 326.189594 -131.988814)
		(end 325.28891 -133.500876)
		(width 0.14224)
		(layer "In4.Cu")
		(net "P5E_CPU0_G3_TX_DN<3>")
	)
	(segment
		(start 371.682518 -232.638854)
		(end 371.612922 -232.679494)
		(width 0.1143)
		(layer "In4.Cu")
		(net "P5E_CPU0_G3_TX_DN<3>")
	)
	(segment
		(start 372.128034 -225.363278)
		(end 372.12651 -225.364294)
		(width 0.1143)
		(layer "In4.Cu")
		(net "P5E_CPU0_G3_TX_DN<3>")
	)
	(segment
		(start 371.682518 -227.779072)
		(end 371.612922 -227.819712)
		(width 0.1143)
		(layer "In4.Cu")
		(net "P5E_CPU0_G3_TX_DN<3>")
	)
	(segment
		(start 372.119398 -225.368358)
		(end 372.082822 -225.389694)
		(width 0.1143)
		(layer "In4.Cu")
		(net "P5E_CPU0_G3_TX_DN<3>")
	)
	(segment
		(start 370.711984 -234.276646)
		(end 370.710968 -234.277154)
		(width 0.1143)
		(layer "In4.Cu")
		(net "P5E_CPU0_G3_TX_DN<3>")
	)
	(segment
		(start 317.049658 -161.228278)
		(end 318.081152 -163.718494)
		(width 0.14224)
		(layer "In4.Cu")
		(net "P5E_CPU0_G3_TX_DN<3>")
	)
	(segment
		(start 373.531638 -222.936816)
		(end 373.495316 -222.957898)
		(width 0.1143)
		(layer "In4.Cu")
		(net "P5E_CPU0_G3_TX_DN<3>")
	)
	(segment
		(start 372.55704 -224.576894)
		(end 372.552976 -224.579688)
		(width 0.1143)
		(layer "In4.Cu")
		(net "P5E_CPU0_G3_TX_DN<3>")
	)
	(segment
		(start 373.537226 -222.933514)
		(end 373.536464 -222.934022)
		(width 0.1143)
		(layer "In4.Cu")
		(net "P5E_CPU0_G3_TX_DN<3>")
	)
	(segment
		(start 371.68455 -229.397814)
		(end 371.652038 -229.41661)
		(width 0.1143)
		(layer "In4.Cu")
		(net "P5E_CPU0_G3_TX_DN<3>")
	)
	(segment
		(start 371.652038 -229.41661)
		(end 371.612922 -229.43947)
		(width 0.1143)
		(layer "In4.Cu")
		(net "P5E_CPU0_G3_TX_DN<3>")
	)
	(segment
		(start 372.12397 -225.365564)
		(end 372.1227 -225.366326)
		(width 0.1143)
		(layer "In4.Cu")
		(net "P5E_CPU0_G3_TX_DN<3>")
	)
	(segment
		(start 372.153688 -231.82834)
		(end 372.128034 -231.843072)
		(width 0.1143)
		(layer "In4.Cu")
		(net "P5E_CPU0_G3_TX_DN<3>")
	)
	(segment
		(start 370.352828 -234.764072)
		(end 370.054886 -234.764072)
		(width 0.1143)
		(layer "In4.Cu")
		(net "P5E_CPU0_G3_TX_DN<3>")
	)
	(segment
		(start 372.119398 -231.848152)
		(end 372.082822 -231.869488)
		(width 0.1143)
		(layer "In4.Cu")
		(net "P5E_CPU0_G3_TX_DN<3>")
	)
	(segment
		(start 424.15841 -20.441158)
		(end 326.189594 -131.988814)
		(width 0.14224)
		(layer "In4.Cu")
		(net "P5E_CPU0_G3_TX_DN<3>")
	)
	(segment
		(start 370.88699 -233.963718)
		(end 370.88699 -233.97337)
		(width 0.1143)
		(layer "In4.Cu")
		(net "P5E_CPU0_G3_TX_DN<3>")
	)
	(segment
		(start 371.134894 -233.495088)
		(end 371.135148 -233.495342)
		(width 0.1143)
		(layer "In4.Cu")
		(net "P5E_CPU0_G3_TX_DN<3>")
	)
	(segment
		(start 372.1227 -231.84612)
		(end 372.121938 -231.846628)
		(width 0.1143)
		(layer "In4.Cu")
		(net "P5E_CPU0_G3_TX_DN<3>")
	)
	(segment
		(start 371.18544 -233.46283)
		(end 371.183916 -233.463592)
		(width 0.1143)
		(layer "In4.Cu")
		(net "P5E_CPU0_G3_TX_DN<3>")
	)
	(segment
		(start 318.081152 -163.718494)
		(end 319.79108 -165.42893)
		(width 0.14224)
		(layer "In4.Cu")
		(net "P5E_CPU0_G3_TX_DN<3>")
	)
	(segment
		(start 371.183916 -233.463592)
		(end 371.181376 -233.465116)
		(width 0.1143)
		(layer "In4.Cu")
		(net "P5E_CPU0_G3_TX_DN<3>")
	)
	(segment
		(start 372.934738 -214.002366)
		(end 374.143778 -220.58249)
		(width 0.14224)
		(layer "In4.Cu")
		(net "P5E_CPU0_G3_TX_DN<3>")
	)
	(segment
		(start 372.121938 -225.366834)
		(end 372.120922 -225.367342)
		(width 0.1143)
		(layer "In4.Cu")
		(net "P5E_CPU0_G3_TX_DN<3>")
	)
	(segment
		(start 372.591838 -224.556828)
		(end 372.55704 -224.576894)
		(width 0.1143)
		(layer "In4.Cu")
		(net "P5E_CPU0_G3_TX_DN<3>")
	)
	(segment
		(start 372.082822 -231.178862)
		(end 372.155466 -231.22128)
		(width 0.1143)
		(layer "In4.Cu")
		(net "P5E_CPU0_G3_TX_DN<3>")
	)
	(segment
		(start 372.12397 -231.845358)
		(end 372.1227 -231.84612)
		(width 0.1143)
		(layer "In4.Cu")
		(net "P5E_CPU0_G3_TX_DN<3>")
	)
	(segment
		(start 373.093488 -223.728534)
		(end 373.061738 -223.746822)
		(width 0.1143)
		(layer "In4.Cu")
		(net "P5E_CPU0_G3_TX_DN<3>")
	)
	(segment
		(start 372.120922 -231.847136)
		(end 372.119398 -231.848152)
		(width 0.1143)
		(layer "In4.Cu")
		(net "P5E_CPU0_G3_TX_DN<3>")
	)
	(segment
		(start 370.710968 -234.277154)
		(end 370.709444 -234.27817)
		(width 0.1143)
		(layer "In4.Cu")
		(net "P5E_CPU0_G3_TX_DN<3>")
	)
	(segment
		(start 374.143778 -220.58249)
		(end 374.143778 -221.17431)
		(width 0.14224)
		(layer "In4.Cu")
		(net "P5E_CPU0_G3_TX_DN<3>")
	)
	(segment
		(start 370.435632 -234.681268)
		(end 370.352828 -234.764072)
		(width 0.1143)
		(layer "In4.Cu")
		(net "P5E_CPU0_G3_TX_DN<3>")
	)
	(segment
		(start 373.543068 -222.929958)
		(end 373.540528 -222.931482)
		(width 0.1143)
		(layer "In4.Cu")
		(net "P5E_CPU0_G3_TX_DN<3>")
	)
	(segment
		(start 325.035164 -168.923716)
		(end 329.427332 -172.015404)
		(width 0.14224)
		(layer "In4.Cu")
		(net "P5E_CPU0_G3_TX_DN<3>")
	)
	(segment
		(start 374.001792 -222.12681)
		(end 373.962676 -222.14967)
		(width 0.1143)
		(layer "In4.Cu")
		(net "P5E_CPU0_G3_TX_DN<3>")
	)
	(segment
		(start 370.709444 -234.27817)
		(end 370.672868 -234.299506)
		(width 0.1143)
		(layer "In4.Cu")
		(net "P5E_CPU0_G3_TX_DN<3>")
	)
	(segment
		(start 372.12651 -231.844088)
		(end 372.12397 -231.845358)
		(width 0.1143)
		(layer "In4.Cu")
		(net "P5E_CPU0_G3_TX_DN<3>")
	)
	(segment
		(start 373.061738 -223.746822)
		(end 373.025416 -223.767904)
		(width 0.1143)
		(layer "In4.Cu")
		(net "P5E_CPU0_G3_TX_DN<3>")
	)
	(segment
		(start 329.427332 -172.015404)
		(end 332.825344 -175.091852)
		(width 0.14224)
		(layer "In4.Cu")
		(net "P5E_CPU0_G3_TX_DN<3>")
	)
	(segment
		(start 371.612922 -228.748844)
		(end 371.682518 -228.789484)
		(width 0.1143)
		(layer "In4.Cu")
		(net "P5E_CPU0_G3_TX_DN<3>")
	)
	(segment
		(start 319.79108 -165.42893)
		(end 325.035164 -168.923716)
		(width 0.14224)
		(layer "In4.Cu")
		(net "P5E_CPU0_G3_TX_DN<3>")
	)
	(segment
		(start 317.049658 -158.496)
		(end 317.049658 -161.228278)
		(width 0.14224)
		(layer "In4.Cu")
		(net "P5E_CPU0_G3_TX_DN<3>")
	)
	(arc
		(start 371.682518 -227.169472)
		(mid 371.839495 -227.474272)
		(end 371.682518 -227.779072)
		(width 0.1143)
		(layer "In4.Cu")
		(net "P5E_CPU0_G3_TX_DN<3>")
	)
	(arc
		(start 371.83949 -232.334054)
		(mid 371.797941 -232.505476)
		(end 371.682518 -232.638854)
		(width 0.1143)
		(layer "In4.Cu")
		(net "P5E_CPU0_G3_TX_DN<3>")
	)
	(arc
		(start 373.719344 -222.614236)
		(mid 373.678089 -222.785207)
		(end 373.563388 -222.918528)
		(width 0.1143)
		(layer "In4.Cu")
		(net "P5E_CPU0_G3_TX_DN<3>")
	)
	(arc
		(start 371.83949 -230.714296)
		(mid 371.904005 -230.976515)
		(end 372.082822 -231.178862)
		(width 0.1143)
		(layer "In4.Cu")
		(net "P5E_CPU0_G3_TX_DN<3>")
	)
	(arc
		(start 371.181122 -233.465116)
		(mid 371.157644 -233.47954)
		(end 371.134894 -233.495088)
		(width 0.1143)
		(layer "In4.Cu")
		(net "P5E_CPU0_G3_TX_DN<3>")
	)
	(arc
		(start 373.249444 -223.417638)
		(mid 373.249434 -223.42094)
		(end 373.249444 -223.424242)
		(width 0.1143)
		(layer "In4.Cu")
		(net "P5E_CPU0_G3_TX_DN<3>")
	)
	(arc
		(start 371.36959 -229.904036)
		(mid 371.434826 -230.167627)
		(end 371.615462 -230.37038)
		(width 0.1143)
		(layer "In4.Cu")
		(net "P5E_CPU0_G3_TX_DN<3>")
	)
	(arc
		(start 373.47906 -222.969328)
		(mid 373.314393 -223.167935)
		(end 373.249444 -223.417638)
		(width 0.1143)
		(layer "In4.Cu")
		(net "P5E_CPU0_G3_TX_DN<3>")
	)
	(arc
		(start 372.082822 -225.389694)
		(mid 371.904009 -225.592044)
		(end 371.83949 -225.85426)
		(width 0.1143)
		(layer "In4.Cu")
		(net "P5E_CPU0_G3_TX_DN<3>")
	)
	(arc
		(start 371.612922 -227.819712)
		(mid 371.369595 -228.284278)
		(end 371.612922 -228.748844)
		(width 0.1143)
		(layer "In4.Cu")
		(net "P5E_CPU0_G3_TX_DN<3>")
	)
	(arc
		(start 370.439442 -234.658408)
		(mid 370.437419 -234.669818)
		(end 370.435632 -234.681268)
		(width 0.1143)
		(layer "In4.Cu")
		(net "P5E_CPU0_G3_TX_DN<3>")
	)
	(arc
		(start 371.612922 -226.1997)
		(mid 371.369595 -226.664266)
		(end 371.612922 -227.128832)
		(width 0.1143)
		(layer "In4.Cu")
		(net "P5E_CPU0_G3_TX_DN<3>")
	)
	(arc
		(start 373.495316 -222.957898)
		(mid 373.487138 -222.963541)
		(end 373.47906 -222.969328)
		(width 0.1143)
		(layer "In4.Cu")
		(net "P5E_CPU0_G3_TX_DN<3>")
	)
	(arc
		(start 373.249444 -223.424242)
		(mid 373.205373 -223.593778)
		(end 373.093488 -223.728534)
		(width 0.1143)
		(layer "In4.Cu")
		(net "P5E_CPU0_G3_TX_DN<3>")
	)
	(arc
		(start 371.612922 -232.679494)
		(mid 371.434109 -232.881844)
		(end 371.36959 -233.14406)
		(width 0.1143)
		(layer "In4.Cu")
		(net "P5E_CPU0_G3_TX_DN<3>")
	)
	(arc
		(start 372.309644 -231.524048)
		(mid 372.268389 -231.695019)
		(end 372.153688 -231.82834)
		(width 0.1143)
		(layer "In4.Cu")
		(net "P5E_CPU0_G3_TX_DN<3>")
	)
	(arc
		(start 370.88699 -233.97337)
		(mid 370.84025 -234.148315)
		(end 370.712492 -234.276646)
		(width 0.1143)
		(layer "In4.Cu")
		(net "P5E_CPU0_G3_TX_DN<3>")
	)
	(arc
		(start 373.00916 -223.779334)
		(mid 372.844493 -223.977941)
		(end 372.779544 -224.227644)
		(width 0.1143)
		(layer "In4.Cu")
		(net "P5E_CPU0_G3_TX_DN<3>")
	)
	(arc
		(start 371.682518 -228.789484)
		(mid 371.797945 -228.92286)
		(end 371.83949 -229.094284)
		(width 0.1143)
		(layer "In4.Cu")
		(net "P5E_CPU0_G3_TX_DN<3>")
	)
	(arc
		(start 371.135148 -233.495342)
		(mid 370.952822 -233.698666)
		(end 370.88699 -233.963718)
		(width 0.1143)
		(layer "In4.Cu")
		(net "P5E_CPU0_G3_TX_DN<3>")
	)
	(arc
		(start 373.962676 -222.14967)
		(mid 373.783863 -222.35202)
		(end 373.719344 -222.614236)
		(width 0.1143)
		(layer "In4.Cu")
		(net "P5E_CPU0_G3_TX_DN<3>")
	)
	(arc
		(start 372.779544 -224.234248)
		(mid 372.735473 -224.403784)
		(end 372.623588 -224.53854)
		(width 0.1143)
		(layer "In4.Cu")
		(net "P5E_CPU0_G3_TX_DN<3>")
	)
	(arc
		(start 372.779544 -224.227644)
		(mid 372.779534 -224.230946)
		(end 372.779544 -224.234248)
		(width 0.1143)
		(layer "In4.Cu")
		(net "P5E_CPU0_G3_TX_DN<3>")
	)
	(arc
		(start 370.672868 -234.299506)
		(mid 370.520881 -234.456014)
		(end 370.439442 -234.658408)
		(width 0.1143)
		(layer "In4.Cu")
		(net "P5E_CPU0_G3_TX_DN<3>")
	)
	(arc
		(start 372.155466 -231.22128)
		(mid 372.268873 -231.354169)
		(end 372.309644 -231.524048)
		(width 0.1143)
		(layer "In4.Cu")
		(net "P5E_CPU0_G3_TX_DN<3>")
	)
	(arc
		(start 372.082822 -231.869488)
		(mid 371.904009 -232.071838)
		(end 371.83949 -232.334054)
		(width 0.1143)
		(layer "In4.Cu")
		(net "P5E_CPU0_G3_TX_DN<3>")
	)
	(arc
		(start 371.36959 -233.14406)
		(mid 371.32025 -233.328138)
		(end 371.18544 -233.46283)
		(width 0.1143)
		(layer "In4.Cu")
		(net "P5E_CPU0_G3_TX_DN<3>")
	)
	(arc
		(start 371.83949 -225.85426)
		(mid 371.797941 -226.025682)
		(end 371.682518 -226.15906)
		(width 0.1143)
		(layer "In4.Cu")
		(net "P5E_CPU0_G3_TX_DN<3>")
	)
	(arc
		(start 372.552976 -224.579688)
		(mid 372.374163 -224.782038)
		(end 372.309644 -225.044254)
		(width 0.1143)
		(layer "In4.Cu")
		(net "P5E_CPU0_G3_TX_DN<3>")
	)
	(arc
		(start 372.309644 -225.044254)
		(mid 372.268389 -225.215225)
		(end 372.153688 -225.348546)
		(width 0.1143)
		(layer "In4.Cu")
		(net "P5E_CPU0_G3_TX_DN<3>")
	)
	(arc
		(start 373.025416 -223.767904)
		(mid 373.017238 -223.773547)
		(end 373.00916 -223.779334)
		(width 0.1143)
		(layer "In4.Cu")
		(net "P5E_CPU0_G3_TX_DN<3>")
	)
	(arc
		(start 371.682518 -230.409496)
		(mid 371.797945 -230.542872)
		(end 371.83949 -230.714296)
		(width 0.1143)
		(layer "In4.Cu")
		(net "P5E_CPU0_G3_TX_DN<3>")
	)
	(arc
		(start 371.612922 -229.43947)
		(mid 371.434109 -229.64182)
		(end 371.36959 -229.904036)
		(width 0.1143)
		(layer "In4.Cu")
		(net "P5E_CPU0_G3_TX_DN<3>")
	)
	(arc
		(start 374.189498 -221.80423)
		(mid 374.148243 -221.975201)
		(end 374.033542 -222.108522)
		(width 0.1143)
		(layer "In4.Cu")
		(net "P5E_CPU0_G3_TX_DN<3>")
	)
	(arc
		(start 371.83949 -229.094284)
		(mid 371.798524 -229.26469)
		(end 371.68455 -229.397814)
		(width 0.1143)
		(layer "In4.Cu")
		(net "P5E_CPU0_G3_TX_DN<3>")
	)
	(segment
		(start 372.407942 -236.650022)
		(end 372.874794 -236.384084)
		(width 0.12954)
		(layer "F.Cu")
		(net "P5E_CPU0_G3_TX_DN<2>")
	)
	(segment
		(start 426.6692 -17.890998)
		(end 426.966126 -18.187924)
		(width 0.12954)
		(layer "F.Cu")
		(net "P5E_CPU0_G3_TX_DN<2>")
	)
	(segment
		(start 426.966126 -18.187924)
		(end 426.966126 -18.86585)
		(width 0.12954)
		(layer "F.Cu")
		(net "P5E_CPU0_G3_TX_DN<2>")
	)
	(segment
		(start 426.966126 -18.86585)
		(end 426.695616 -19.13636)
		(width 0.12954)
		(layer "F.Cu")
		(net "P5E_CPU0_G3_TX_DN<2>")
	)
	(segment
		(start 372.596156 -228.774244)
		(end 372.597172 -228.774752)
		(width 0.1143)
		(layer "In4.Cu")
		(net "P5E_CPU0_G3_TX_DN<2>")
	)
	(segment
		(start 327.773538 -156.69768)
		(end 335.609184 -172.740066)
		(width 0.14224)
		(layer "In4.Cu")
		(net "P5E_CPU0_G3_TX_DN<2>")
	)
	(segment
		(start 372.578884 -235.243878)
		(end 372.579646 -235.244386)
		(width 0.1143)
		(layer "In4.Cu")
		(net "P5E_CPU0_G3_TX_DN<2>")
	)
	(segment
		(start 372.583456 -227.146866)
		(end 372.58625 -227.14839)
		(width 0.1143)
		(layer "In4.Cu")
		(net "P5E_CPU0_G3_TX_DN<2>")
	)
	(segment
		(start 372.560342 -226.195128)
		(end 372.55958 -226.195636)
		(width 0.1143)
		(layer "In4.Cu")
		(net "P5E_CPU0_G3_TX_DN<2>")
	)
	(segment
		(start 372.591838 -232.656634)
		(end 372.560342 -232.674922)
		(width 0.1143)
		(layer "In4.Cu")
		(net "P5E_CPU0_G3_TX_DN<2>")
	)
	(segment
		(start 372.59387 -228.772974)
		(end 372.595394 -228.773736)
		(width 0.1143)
		(layer "In4.Cu")
		(net "P5E_CPU0_G3_TX_DN<2>")
	)
	(segment
		(start 372.587012 -235.248704)
		(end 372.588282 -235.249466)
		(width 0.1143)
		(layer "In4.Cu")
		(net "P5E_CPU0_G3_TX_DN<2>")
	)
	(segment
		(start 327.100184 -132.529834)
		(end 326.934322 -132.808726)
		(width 0.14224)
		(layer "In4.Cu")
		(net "P5E_CPU0_G3_TX_DN<2>")
	)
	(segment
		(start 372.599966 -226.172268)
		(end 372.5926 -226.176332)
		(width 0.1143)
		(layer "In4.Cu")
		(net "P5E_CPU0_G3_TX_DN<2>")
	)
	(segment
		(start 373.493792 -224.578926)
		(end 373.492776 -224.579688)
		(width 0.1143)
		(layer "In4.Cu")
		(net "P5E_CPU0_G3_TX_DN<2>")
	)
	(segment
		(start 372.597172 -233.634534)
		(end 372.597934 -233.635042)
		(width 0.1143)
		(layer "In4.Cu")
		(net "P5E_CPU0_G3_TX_DN<2>")
	)
	(segment
		(start 326.934322 -132.808726)
		(end 326.175624 -134.587234)
		(width 0.14224)
		(layer "In4.Cu")
		(net "P5E_CPU0_G3_TX_DN<2>")
	)
	(segment
		(start 374.973596 -222.108522)
		(end 374.936512 -222.129858)
		(width 0.1143)
		(layer "In4.Cu")
		(net "P5E_CPU0_G3_TX_DN<2>")
	)
	(segment
		(start 374.473978 -222.935546)
		(end 374.471946 -222.936816)
		(width 0.1143)
		(layer "In4.Cu")
		(net "P5E_CPU0_G3_TX_DN<2>")
	)
	(segment
		(start 372.623588 -232.638346)
		(end 372.599966 -232.652062)
		(width 0.1143)
		(layer "In4.Cu")
		(net "P5E_CPU0_G3_TX_DN<2>")
	)
	(segment
		(start 373.242586 -236.314234)
		(end 373.172736 -236.384084)
		(width 0.1143)
		(layer "In4.Cu")
		(net "P5E_CPU0_G3_TX_DN<2>")
	)
	(segment
		(start 372.58625 -227.14839)
		(end 372.587012 -227.148898)
		(width 0.1143)
		(layer "In4.Cu")
		(net "P5E_CPU0_G3_TX_DN<2>")
	)
	(segment
		(start 372.589298 -227.150168)
		(end 372.590822 -227.151184)
		(width 0.1143)
		(layer "In4.Cu")
		(net "P5E_CPU0_G3_TX_DN<2>")
	)
	(segment
		(start 372.591838 -234.276646)
		(end 372.560342 -234.294934)
		(width 0.1143)
		(layer "In4.Cu")
		(net "P5E_CPU0_G3_TX_DN<2>")
	)
	(segment
		(start 372.581424 -233.62539)
		(end 372.583456 -233.62666)
		(width 0.1143)
		(layer "In4.Cu")
		(net "P5E_CPU0_G3_TX_DN<2>")
	)
	(segment
		(start 372.560342 -234.294934)
		(end 372.55958 -234.295442)
		(width 0.1143)
		(layer "In4.Cu")
		(net "P5E_CPU0_G3_TX_DN<2>")
	)
	(segment
		(start 372.589298 -228.77018)
		(end 372.590822 -228.771196)
		(width 0.1143)
		(layer "In4.Cu")
		(net "P5E_CPU0_G3_TX_DN<2>")
	)
	(segment
		(start 372.587012 -233.628692)
		(end 372.588282 -233.629454)
		(width 0.1143)
		(layer "In4.Cu")
		(net "P5E_CPU0_G3_TX_DN<2>")
	)
	(segment
		(start 372.595394 -227.153724)
		(end 372.596156 -227.154232)
		(width 0.1143)
		(layer "In4.Cu")
		(net "P5E_CPU0_G3_TX_DN<2>")
	)
	(segment
		(start 372.599966 -234.272074)
		(end 372.5926 -234.276138)
		(width 0.1143)
		(layer "In4.Cu")
		(net "P5E_CPU0_G3_TX_DN<2>")
	)
	(segment
		(start 372.597172 -227.15474)
		(end 372.597934 -227.155248)
		(width 0.1143)
		(layer "In4.Cu")
		(net "P5E_CPU0_G3_TX_DN<2>")
	)
	(segment
		(start 373.061992 -231.201722)
		(end 373.094504 -231.220518)
		(width 0.1143)
		(layer "In4.Cu")
		(net "P5E_CPU0_G3_TX_DN<2>")
	)
	(segment
		(start 374.471946 -222.936816)
		(end 374.435624 -222.957898)
		(width 0.1143)
		(layer "In4.Cu")
		(net "P5E_CPU0_G3_TX_DN<2>")
	)
	(segment
		(start 341.66175 -181.121812)
		(end 366.726724 -201.6506)
		(width 0.14224)
		(layer "In4.Cu")
		(net "P5E_CPU0_G3_TX_DN<2>")
	)
	(segment
		(start 372.58625 -233.628184)
		(end 372.587012 -233.628692)
		(width 0.1143)
		(layer "In4.Cu")
		(net "P5E_CPU0_G3_TX_DN<2>")
	)
	(segment
		(start 372.599966 -232.652062)
		(end 372.5926 -232.656126)
		(width 0.1143)
		(layer "In4.Cu")
		(net "P5E_CPU0_G3_TX_DN<2>")
	)
	(segment
		(start 372.600474 -235.256324)
		(end 372.623588 -235.269786)
		(width 0.1143)
		(layer "In4.Cu")
		(net "P5E_CPU0_G3_TX_DN<2>")
	)
	(segment
		(start 375.083832 -220.293692)
		(end 375.083832 -221.17431)
		(width 0.14224)
		(layer "In4.Cu")
		(net "P5E_CPU0_G3_TX_DN<2>")
	)
	(segment
		(start 372.59387 -227.152962)
		(end 372.595394 -227.153724)
		(width 0.1143)
		(layer "In4.Cu")
		(net "P5E_CPU0_G3_TX_DN<2>")
	)
	(segment
		(start 335.609184 -172.740066)
		(end 340.52764 -179.987956)
		(width 0.14224)
		(layer "In4.Cu")
		(net "P5E_CPU0_G3_TX_DN<2>")
	)
	(segment
		(start 372.587012 -227.148898)
		(end 372.588282 -227.14966)
		(width 0.1143)
		(layer "In4.Cu")
		(net "P5E_CPU0_G3_TX_DN<2>")
	)
	(segment
		(start 372.596156 -235.254038)
		(end 372.597172 -235.254546)
		(width 0.1143)
		(layer "In4.Cu")
		(net "P5E_CPU0_G3_TX_DN<2>")
	)
	(segment
		(start 375.083832 -221.17431)
		(end 375.083832 -221.202758)
		(width 0.1143)
		(layer "In4.Cu")
		(net "P5E_CPU0_G3_TX_DN<2>")
	)
	(segment
		(start 372.583456 -228.766878)
		(end 372.58625 -228.768402)
		(width 0.1143)
		(layer "In4.Cu")
		(net "P5E_CPU0_G3_TX_DN<2>")
	)
	(segment
		(start 372.589298 -235.249974)
		(end 372.590822 -235.25099)
		(width 0.1143)
		(layer "In4.Cu")
		(net "P5E_CPU0_G3_TX_DN<2>")
	)
	(segment
		(start 340.52764 -179.987956)
		(end 341.66175 -181.121812)
		(width 0.14224)
		(layer "In4.Cu")
		(net "P5E_CPU0_G3_TX_DN<2>")
	)
	(segment
		(start 426.986446 -20.440142)
		(end 327.100184 -132.529834)
		(width 0.14224)
		(layer "In4.Cu")
		(net "P5E_CPU0_G3_TX_DN<2>")
	)
	(segment
		(start 372.579646 -228.764592)
		(end 372.581424 -228.765608)
		(width 0.1143)
		(layer "In4.Cu")
		(net "P5E_CPU0_G3_TX_DN<2>")
	)
	(segment
		(start 372.5926 -228.772212)
		(end 372.59387 -228.772974)
		(width 0.1143)
		(layer "In4.Cu")
		(net "P5E_CPU0_G3_TX_DN<2>")
	)
	(segment
		(start 373.092472 -231.828848)
		(end 373.022876 -231.869488)
		(width 0.1143)
		(layer "In4.Cu")
		(net "P5E_CPU0_G3_TX_DN<2>")
	)
	(segment
		(start 372.552722 -227.128832)
		(end 372.578884 -227.144072)
		(width 0.1143)
		(layer "In4.Cu")
		(net "P5E_CPU0_G3_TX_DN<2>")
	)
	(segment
		(start 372.595394 -228.773736)
		(end 372.596156 -228.774244)
		(width 0.1143)
		(layer "In4.Cu")
		(net "P5E_CPU0_G3_TX_DN<2>")
	)
	(segment
		(start 372.600474 -228.77653)
		(end 372.623588 -228.789992)
		(width 0.1143)
		(layer "In4.Cu")
		(net "P5E_CPU0_G3_TX_DN<2>")
	)
	(segment
		(start 372.579646 -233.624374)
		(end 372.581424 -233.62539)
		(width 0.1143)
		(layer "In4.Cu")
		(net "P5E_CPU0_G3_TX_DN<2>")
	)
	(segment
		(start 372.588282 -233.629454)
		(end 372.589298 -233.629962)
		(width 0.1143)
		(layer "In4.Cu")
		(net "P5E_CPU0_G3_TX_DN<2>")
	)
	(segment
		(start 366.726724 -201.6506)
		(end 374.066054 -214.074502)
		(width 0.14224)
		(layer "In4.Cu")
		(net "P5E_CPU0_G3_TX_DN<2>")
	)
	(segment
		(start 372.591838 -227.796852)
		(end 372.560342 -227.81514)
		(width 0.1143)
		(layer "In4.Cu")
		(net "P5E_CPU0_G3_TX_DN<2>")
	)
	(segment
		(start 372.587012 -228.76891)
		(end 372.588282 -228.769672)
		(width 0.1143)
		(layer "In4.Cu")
		(net "P5E_CPU0_G3_TX_DN<2>")
	)
	(segment
		(start 373.022876 -236.038644)
		(end 373.092472 -236.079284)
		(width 0.1143)
		(layer "In4.Cu")
		(net "P5E_CPU0_G3_TX_DN<2>")
	)
	(segment
		(start 372.552722 -235.228638)
		(end 372.578884 -235.243878)
		(width 0.1143)
		(layer "In4.Cu")
		(net "P5E_CPU0_G3_TX_DN<2>")
	)
	(segment
		(start 372.588282 -235.249466)
		(end 372.589298 -235.249974)
		(width 0.1143)
		(layer "In4.Cu")
		(net "P5E_CPU0_G3_TX_DN<2>")
	)
	(segment
		(start 372.583456 -235.246672)
		(end 372.58625 -235.248196)
		(width 0.1143)
		(layer "In4.Cu")
		(net "P5E_CPU0_G3_TX_DN<2>")
	)
	(segment
		(start 372.599966 -227.79228)
		(end 372.5926 -227.796344)
		(width 0.1143)
		(layer "In4.Cu")
		(net "P5E_CPU0_G3_TX_DN<2>")
	)
	(segment
		(start 372.578884 -233.623866)
		(end 372.579646 -233.624374)
		(width 0.1143)
		(layer "In4.Cu")
		(net "P5E_CPU0_G3_TX_DN<2>")
	)
	(segment
		(start 372.55958 -227.815648)
		(end 372.552722 -227.819712)
		(width 0.1143)
		(layer "In4.Cu")
		(net "P5E_CPU0_G3_TX_DN<2>")
	)
	(segment
		(start 372.58625 -235.248196)
		(end 372.587012 -235.248704)
		(width 0.1143)
		(layer "In4.Cu")
		(net "P5E_CPU0_G3_TX_DN<2>")
	)
	(segment
		(start 372.595394 -235.25353)
		(end 372.596156 -235.254038)
		(width 0.1143)
		(layer "In4.Cu")
		(net "P5E_CPU0_G3_TX_DN<2>")
	)
	(segment
		(start 372.600474 -233.636312)
		(end 372.623588 -233.649774)
		(width 0.1143)
		(layer "In4.Cu")
		(net "P5E_CPU0_G3_TX_DN<2>")
	)
	(segment
		(start 372.590822 -227.151184)
		(end 372.591838 -227.151692)
		(width 0.1143)
		(layer "In4.Cu")
		(net "P5E_CPU0_G3_TX_DN<2>")
	)
	(segment
		(start 372.5926 -226.176332)
		(end 372.591838 -226.17684)
		(width 0.1143)
		(layer "In4.Cu")
		(net "P5E_CPU0_G3_TX_DN<2>")
	)
	(segment
		(start 372.591838 -230.391716)
		(end 372.623588 -230.410004)
		(width 0.1143)
		(layer "In4.Cu")
		(net "P5E_CPU0_G3_TX_DN<2>")
	)
	(segment
		(start 372.55958 -226.195636)
		(end 372.552722 -226.1997)
		(width 0.1143)
		(layer "In4.Cu")
		(net "P5E_CPU0_G3_TX_DN<2>")
	)
	(segment
		(start 372.590822 -233.630978)
		(end 372.591838 -233.631486)
		(width 0.1143)
		(layer "In4.Cu")
		(net "P5E_CPU0_G3_TX_DN<2>")
	)
	(segment
		(start 372.5926 -235.252006)
		(end 372.59387 -235.252768)
		(width 0.1143)
		(layer "In4.Cu")
		(net "P5E_CPU0_G3_TX_DN<2>")
	)
	(segment
		(start 325.263256 -141.605762)
		(end 326.404478 -151.607774)
		(width 0.14224)
		(layer "In4.Cu")
		(net "P5E_CPU0_G3_TX_DN<2>")
	)
	(segment
		(start 372.581424 -235.245402)
		(end 372.583456 -235.246672)
		(width 0.1143)
		(layer "In4.Cu")
		(net "P5E_CPU0_G3_TX_DN<2>")
	)
	(segment
		(start 326.175624 -134.587234)
		(end 325.339456 -137.621518)
		(width 0.14224)
		(layer "In4.Cu")
		(net "P5E_CPU0_G3_TX_DN<2>")
	)
	(segment
		(start 372.5926 -227.1522)
		(end 372.59387 -227.152962)
		(width 0.1143)
		(layer "In4.Cu")
		(net "P5E_CPU0_G3_TX_DN<2>")
	)
	(segment
		(start 372.59387 -235.252768)
		(end 372.595394 -235.25353)
		(width 0.1143)
		(layer "In4.Cu")
		(net "P5E_CPU0_G3_TX_DN<2>")
	)
	(segment
		(start 372.597934 -233.635042)
		(end 372.600474 -233.636312)
		(width 0.1143)
		(layer "In4.Cu")
		(net "P5E_CPU0_G3_TX_DN<2>")
	)
	(segment
		(start 372.597934 -228.77526)
		(end 372.600474 -228.77653)
		(width 0.1143)
		(layer "In4.Cu")
		(net "P5E_CPU0_G3_TX_DN<2>")
	)
	(segment
		(start 372.590822 -235.25099)
		(end 372.591838 -235.251498)
		(width 0.1143)
		(layer "In4.Cu")
		(net "P5E_CPU0_G3_TX_DN<2>")
	)
	(segment
		(start 372.597172 -228.774752)
		(end 372.597934 -228.77526)
		(width 0.1143)
		(layer "In4.Cu")
		(net "P5E_CPU0_G3_TX_DN<2>")
	)
	(segment
		(start 372.5926 -233.631994)
		(end 372.59387 -233.632756)
		(width 0.1143)
		(layer "In4.Cu")
		(net "P5E_CPU0_G3_TX_DN<2>")
	)
	(segment
		(start 426.695616 -19.13636)
		(end 426.986446 -19.42719)
		(width 0.14224)
		(layer "In4.Cu")
		(net "P5E_CPU0_G3_TX_DN<2>")
	)
	(segment
		(start 372.597172 -235.254546)
		(end 372.597934 -235.255054)
		(width 0.1143)
		(layer "In4.Cu")
		(net "P5E_CPU0_G3_TX_DN<2>")
	)
	(segment
		(start 372.5926 -227.796344)
		(end 372.591838 -227.796852)
		(width 0.1143)
		(layer "In4.Cu")
		(net "P5E_CPU0_G3_TX_DN<2>")
	)
	(segment
		(start 372.600474 -227.156518)
		(end 372.623588 -227.16998)
		(width 0.1143)
		(layer "In4.Cu")
		(net "P5E_CPU0_G3_TX_DN<2>")
	)
	(segment
		(start 372.623588 -226.158552)
		(end 372.599966 -226.172268)
		(width 0.1143)
		(layer "In4.Cu")
		(net "P5E_CPU0_G3_TX_DN<2>")
	)
	(segment
		(start 372.591838 -228.771704)
		(end 372.5926 -228.772212)
		(width 0.1143)
		(layer "In4.Cu")
		(net "P5E_CPU0_G3_TX_DN<2>")
	)
	(segment
		(start 372.590822 -228.771196)
		(end 372.591838 -228.771704)
		(width 0.1143)
		(layer "In4.Cu")
		(net "P5E_CPU0_G3_TX_DN<2>")
	)
	(segment
		(start 372.581424 -227.145596)
		(end 372.583456 -227.146866)
		(width 0.1143)
		(layer "In4.Cu")
		(net "P5E_CPU0_G3_TX_DN<2>")
	)
	(segment
		(start 325.339456 -137.621518)
		(end 325.263256 -138.185144)
		(width 0.14224)
		(layer "In4.Cu")
		(net "P5E_CPU0_G3_TX_DN<2>")
	)
	(segment
		(start 372.596156 -233.634026)
		(end 372.597172 -233.634534)
		(width 0.1143)
		(layer "In4.Cu")
		(net "P5E_CPU0_G3_TX_DN<2>")
	)
	(segment
		(start 372.55958 -234.295442)
		(end 372.552722 -234.299506)
		(width 0.1143)
		(layer "In4.Cu")
		(net "P5E_CPU0_G3_TX_DN<2>")
	)
	(segment
		(start 372.591838 -235.251498)
		(end 372.5926 -235.252006)
		(width 0.1143)
		(layer "In4.Cu")
		(net "P5E_CPU0_G3_TX_DN<2>")
	)
	(segment
		(start 372.578884 -227.144072)
		(end 372.579646 -227.14458)
		(width 0.1143)
		(layer "In4.Cu")
		(net "P5E_CPU0_G3_TX_DN<2>")
	)
	(segment
		(start 372.552722 -233.608626)
		(end 372.578884 -233.623866)
		(width 0.1143)
		(layer "In4.Cu")
		(net "P5E_CPU0_G3_TX_DN<2>")
	)
	(segment
		(start 372.55958 -232.67543)
		(end 372.552722 -232.679494)
		(width 0.1143)
		(layer "In4.Cu")
		(net "P5E_CPU0_G3_TX_DN<2>")
	)
	(segment
		(start 372.589298 -233.629962)
		(end 372.590822 -233.630978)
		(width 0.1143)
		(layer "In4.Cu")
		(net "P5E_CPU0_G3_TX_DN<2>")
	)
	(segment
		(start 372.560342 -232.674922)
		(end 372.55958 -232.67543)
		(width 0.1143)
		(layer "In4.Cu")
		(net "P5E_CPU0_G3_TX_DN<2>")
	)
	(segment
		(start 372.583456 -233.62666)
		(end 372.58625 -233.628184)
		(width 0.1143)
		(layer "In4.Cu")
		(net "P5E_CPU0_G3_TX_DN<2>")
	)
	(segment
		(start 372.5926 -232.656126)
		(end 372.591838 -232.656634)
		(width 0.1143)
		(layer "In4.Cu")
		(net "P5E_CPU0_G3_TX_DN<2>")
	)
	(segment
		(start 373.172736 -236.384084)
		(end 372.874794 -236.384084)
		(width 0.1143)
		(layer "In4.Cu")
		(net "P5E_CPU0_G3_TX_DN<2>")
	)
	(segment
		(start 372.597934 -227.155248)
		(end 372.600474 -227.156518)
		(width 0.1143)
		(layer "In4.Cu")
		(net "P5E_CPU0_G3_TX_DN<2>")
	)
	(segment
		(start 372.59387 -233.632756)
		(end 372.595394 -233.633518)
		(width 0.1143)
		(layer "In4.Cu")
		(net "P5E_CPU0_G3_TX_DN<2>")
	)
	(segment
		(start 373.563134 -224.53854)
		(end 373.493792 -224.578926)
		(width 0.1143)
		(layer "In4.Cu")
		(net "P5E_CPU0_G3_TX_DN<2>")
	)
	(segment
		(start 372.623588 -234.258358)
		(end 372.599966 -234.272074)
		(width 0.1143)
		(layer "In4.Cu")
		(net "P5E_CPU0_G3_TX_DN<2>")
	)
	(segment
		(start 372.58625 -228.768402)
		(end 372.587012 -228.76891)
		(width 0.1143)
		(layer "In4.Cu")
		(net "P5E_CPU0_G3_TX_DN<2>")
	)
	(segment
		(start 372.579646 -235.244386)
		(end 372.581424 -235.245402)
		(width 0.1143)
		(layer "In4.Cu")
		(net "P5E_CPU0_G3_TX_DN<2>")
	)
	(segment
		(start 372.588282 -227.14966)
		(end 372.589298 -227.150168)
		(width 0.1143)
		(layer "In4.Cu")
		(net "P5E_CPU0_G3_TX_DN<2>")
	)
	(segment
		(start 372.597934 -235.255054)
		(end 372.600474 -235.256324)
		(width 0.1143)
		(layer "In4.Cu")
		(net "P5E_CPU0_G3_TX_DN<2>")
	)
	(segment
		(start 372.591838 -226.17684)
		(end 372.560342 -226.195128)
		(width 0.1143)
		(layer "In4.Cu")
		(net "P5E_CPU0_G3_TX_DN<2>")
	)
	(segment
		(start 373.022876 -231.178862)
		(end 373.061992 -231.201722)
		(width 0.1143)
		(layer "In4.Cu")
		(net "P5E_CPU0_G3_TX_DN<2>")
	)
	(segment
		(start 426.986446 -19.42719)
		(end 426.986446 -20.440142)
		(width 0.14224)
		(layer "In4.Cu")
		(net "P5E_CPU0_G3_TX_DN<2>")
	)
	(segment
		(start 372.560342 -227.81514)
		(end 372.55958 -227.815648)
		(width 0.1143)
		(layer "In4.Cu")
		(net "P5E_CPU0_G3_TX_DN<2>")
	)
	(segment
		(start 325.263256 -138.185144)
		(end 325.263256 -141.605762)
		(width 0.14224)
		(layer "In4.Cu")
		(net "P5E_CPU0_G3_TX_DN<2>")
	)
	(segment
		(start 372.596156 -227.154232)
		(end 372.597172 -227.15474)
		(width 0.1143)
		(layer "In4.Cu")
		(net "P5E_CPU0_G3_TX_DN<2>")
	)
	(segment
		(start 374.066054 -214.074502)
		(end 375.083832 -220.293692)
		(width 0.14224)
		(layer "In4.Cu")
		(net "P5E_CPU0_G3_TX_DN<2>")
	)
	(segment
		(start 372.5926 -234.276138)
		(end 372.591838 -234.276646)
		(width 0.1143)
		(layer "In4.Cu")
		(net "P5E_CPU0_G3_TX_DN<2>")
	)
	(segment
		(start 372.623588 -227.778564)
		(end 372.599966 -227.79228)
		(width 0.1143)
		(layer "In4.Cu")
		(net "P5E_CPU0_G3_TX_DN<2>")
	)
	(segment
		(start 372.555262 -230.37038)
		(end 372.591838 -230.391716)
		(width 0.1143)
		(layer "In4.Cu")
		(net "P5E_CPU0_G3_TX_DN<2>")
	)
	(segment
		(start 326.404478 -151.607774)
		(end 327.221342 -155.141676)
		(width 0.14224)
		(layer "In4.Cu")
		(net "P5E_CPU0_G3_TX_DN<2>")
	)
	(segment
		(start 372.578884 -228.764084)
		(end 372.579646 -228.764592)
		(width 0.1143)
		(layer "In4.Cu")
		(net "P5E_CPU0_G3_TX_DN<2>")
	)
	(segment
		(start 372.581424 -228.765608)
		(end 372.583456 -228.766878)
		(width 0.1143)
		(layer "In4.Cu")
		(net "P5E_CPU0_G3_TX_DN<2>")
	)
	(segment
		(start 375.129552 -221.248478)
		(end 375.129552 -221.80423)
		(width 0.1143)
		(layer "In4.Cu")
		(net "P5E_CPU0_G3_TX_DN<2>")
	)
	(segment
		(start 372.595394 -233.633518)
		(end 372.596156 -233.634026)
		(width 0.1143)
		(layer "In4.Cu")
		(net "P5E_CPU0_G3_TX_DN<2>")
	)
	(segment
		(start 372.625366 -229.397052)
		(end 372.552722 -229.43947)
		(width 0.1143)
		(layer "In4.Cu")
		(net "P5E_CPU0_G3_TX_DN<2>")
	)
	(segment
		(start 375.083832 -221.202758)
		(end 375.129552 -221.248478)
		(width 0.1143)
		(layer "In4.Cu")
		(net "P5E_CPU0_G3_TX_DN<2>")
	)
	(segment
		(start 327.221342 -155.141676)
		(end 327.773538 -156.69768)
		(width 0.14224)
		(layer "In4.Cu")
		(net "P5E_CPU0_G3_TX_DN<2>")
	)
	(segment
		(start 372.552722 -228.748844)
		(end 372.578884 -228.764084)
		(width 0.1143)
		(layer "In4.Cu")
		(net "P5E_CPU0_G3_TX_DN<2>")
	)
	(segment
		(start 372.591838 -233.631486)
		(end 372.5926 -233.631994)
		(width 0.1143)
		(layer "In4.Cu")
		(net "P5E_CPU0_G3_TX_DN<2>")
	)
	(segment
		(start 373.092472 -225.349054)
		(end 373.022876 -225.389694)
		(width 0.1143)
		(layer "In4.Cu")
		(net "P5E_CPU0_G3_TX_DN<2>")
	)
	(segment
		(start 372.579646 -227.14458)
		(end 372.581424 -227.145596)
		(width 0.1143)
		(layer "In4.Cu")
		(net "P5E_CPU0_G3_TX_DN<2>")
	)
	(segment
		(start 372.588282 -228.769672)
		(end 372.589298 -228.77018)
		(width 0.1143)
		(layer "In4.Cu")
		(net "P5E_CPU0_G3_TX_DN<2>")
	)
	(segment
		(start 372.591838 -227.151692)
		(end 372.5926 -227.1522)
		(width 0.1143)
		(layer "In4.Cu")
		(net "P5E_CPU0_G3_TX_DN<2>")
	)
	(arc
		(start 372.552722 -232.679494)
		(mid 372.309395 -233.14406)
		(end 372.552722 -233.608626)
		(width 0.1143)
		(layer "In4.Cu")
		(net "P5E_CPU0_G3_TX_DN<2>")
	)
	(arc
		(start 372.779544 -232.334054)
		(mid 372.738289 -232.505025)
		(end 372.623588 -232.638346)
		(width 0.1143)
		(layer "In4.Cu")
		(net "P5E_CPU0_G3_TX_DN<2>")
	)
	(arc
		(start 374.936512 -222.129858)
		(mid 374.732643 -222.33532)
		(end 374.658128 -222.614998)
		(width 0.1143)
		(layer "In4.Cu")
		(net "P5E_CPU0_G3_TX_DN<2>")
	)
	(arc
		(start 374.189752 -223.424242)
		(mid 374.147998 -223.596185)
		(end 374.032018 -223.729804)
		(width 0.1143)
		(layer "In4.Cu")
		(net "P5E_CPU0_G3_TX_DN<2>")
	)
	(arc
		(start 372.779544 -225.85426)
		(mid 372.738289 -226.025231)
		(end 372.623588 -226.158552)
		(width 0.1143)
		(layer "In4.Cu")
		(net "P5E_CPU0_G3_TX_DN<2>")
	)
	(arc
		(start 372.552722 -227.819712)
		(mid 372.309395 -228.284278)
		(end 372.552722 -228.748844)
		(width 0.1143)
		(layer "In4.Cu")
		(net "P5E_CPU0_G3_TX_DN<2>")
	)
	(arc
		(start 372.623588 -235.269786)
		(mid 372.738264 -235.40312)
		(end 372.779544 -235.574078)
		(width 0.1143)
		(layer "In4.Cu")
		(net "P5E_CPU0_G3_TX_DN<2>")
	)
	(arc
		(start 373.71782 -224.271332)
		(mid 373.669294 -224.421617)
		(end 373.563134 -224.53854)
		(width 0.1143)
		(layer "In4.Cu")
		(net "P5E_CPU0_G3_TX_DN<2>")
	)
	(arc
		(start 374.435624 -222.957898)
		(mid 374.254972 -223.160643)
		(end 374.189752 -223.424242)
		(width 0.1143)
		(layer "In4.Cu")
		(net "P5E_CPU0_G3_TX_DN<2>")
	)
	(arc
		(start 372.552722 -226.1997)
		(mid 372.309395 -226.664266)
		(end 372.552722 -227.128832)
		(width 0.1143)
		(layer "In4.Cu")
		(net "P5E_CPU0_G3_TX_DN<2>")
	)
	(arc
		(start 372.779544 -230.714296)
		(mid 372.844059 -230.976515)
		(end 373.022876 -231.178862)
		(width 0.1143)
		(layer "In4.Cu")
		(net "P5E_CPU0_G3_TX_DN<2>")
	)
	(arc
		(start 374.658128 -222.614998)
		(mid 374.608816 -222.799841)
		(end 374.473978 -222.935546)
		(width 0.1143)
		(layer "In4.Cu")
		(net "P5E_CPU0_G3_TX_DN<2>")
	)
	(arc
		(start 372.623588 -230.410004)
		(mid 372.738264 -230.543338)
		(end 372.779544 -230.714296)
		(width 0.1143)
		(layer "In4.Cu")
		(net "P5E_CPU0_G3_TX_DN<2>")
	)
	(arc
		(start 373.022876 -231.869488)
		(mid 372.844063 -232.071838)
		(end 372.779544 -232.334054)
		(width 0.1143)
		(layer "In4.Cu")
		(net "P5E_CPU0_G3_TX_DN<2>")
	)
	(arc
		(start 373.092472 -236.079284)
		(mid 373.190237 -236.18226)
		(end 373.242586 -236.314234)
		(width 0.1143)
		(layer "In4.Cu")
		(net "P5E_CPU0_G3_TX_DN<2>")
	)
	(arc
		(start 372.623588 -227.16998)
		(mid 372.779516 -227.474272)
		(end 372.623588 -227.778564)
		(width 0.1143)
		(layer "In4.Cu")
		(net "P5E_CPU0_G3_TX_DN<2>")
	)
	(arc
		(start 375.129552 -221.80423)
		(mid 375.088297 -221.975201)
		(end 374.973596 -222.108522)
		(width 0.1143)
		(layer "In4.Cu")
		(net "P5E_CPU0_G3_TX_DN<2>")
	)
	(arc
		(start 373.094504 -231.220518)
		(mid 373.208433 -231.353665)
		(end 373.249444 -231.524048)
		(width 0.1143)
		(layer "In4.Cu")
		(net "P5E_CPU0_G3_TX_DN<2>")
	)
	(arc
		(start 373.492776 -224.579688)
		(mid 373.313963 -224.782038)
		(end 373.249444 -225.044254)
		(width 0.1143)
		(layer "In4.Cu")
		(net "P5E_CPU0_G3_TX_DN<2>")
	)
	(arc
		(start 372.623588 -228.789992)
		(mid 372.738264 -228.923326)
		(end 372.779544 -229.094284)
		(width 0.1143)
		(layer "In4.Cu")
		(net "P5E_CPU0_G3_TX_DN<2>")
	)
	(arc
		(start 372.30939 -229.904036)
		(mid 372.374626 -230.167627)
		(end 372.555262 -230.37038)
		(width 0.1143)
		(layer "In4.Cu")
		(net "P5E_CPU0_G3_TX_DN<2>")
	)
	(arc
		(start 372.779544 -229.094284)
		(mid 372.738782 -229.264168)
		(end 372.625366 -229.397052)
		(width 0.1143)
		(layer "In4.Cu")
		(net "P5E_CPU0_G3_TX_DN<2>")
	)
	(arc
		(start 374.032018 -223.729804)
		(mid 373.81615 -223.96648)
		(end 373.71782 -224.271332)
		(width 0.1143)
		(layer "In4.Cu")
		(net "P5E_CPU0_G3_TX_DN<2>")
	)
	(arc
		(start 372.623588 -233.649774)
		(mid 372.779516 -233.954066)
		(end 372.623588 -234.258358)
		(width 0.1143)
		(layer "In4.Cu")
		(net "P5E_CPU0_G3_TX_DN<2>")
	)
	(arc
		(start 373.022876 -225.389694)
		(mid 372.844063 -225.592044)
		(end 372.779544 -225.85426)
		(width 0.1143)
		(layer "In4.Cu")
		(net "P5E_CPU0_G3_TX_DN<2>")
	)
	(arc
		(start 372.779544 -235.574078)
		(mid 372.844059 -235.836297)
		(end 373.022876 -236.038644)
		(width 0.1143)
		(layer "In4.Cu")
		(net "P5E_CPU0_G3_TX_DN<2>")
	)
	(arc
		(start 373.249444 -231.524048)
		(mid 373.207895 -231.69547)
		(end 373.092472 -231.828848)
		(width 0.1143)
		(layer "In4.Cu")
		(net "P5E_CPU0_G3_TX_DN<2>")
	)
	(arc
		(start 372.552722 -234.299506)
		(mid 372.309395 -234.764072)
		(end 372.552722 -235.228638)
		(width 0.1143)
		(layer "In4.Cu")
		(net "P5E_CPU0_G3_TX_DN<2>")
	)
	(arc
		(start 373.249444 -225.044254)
		(mid 373.207895 -225.215676)
		(end 373.092472 -225.349054)
		(width 0.1143)
		(layer "In4.Cu")
		(net "P5E_CPU0_G3_TX_DN<2>")
	)
	(arc
		(start 372.552722 -229.43947)
		(mid 372.373909 -229.64182)
		(end 372.30939 -229.904036)
		(width 0.1143)
		(layer "In4.Cu")
		(net "P5E_CPU0_G3_TX_DN<2>")
	)
	(segment
		(start 429.75911 -16.662908)
		(end 429.75911 -17.342612)
		(width 0.12954)
		(layer "F.Cu")
		(net "P5E_CPU0_G3_TX_DN<1>")
	)
	(segment
		(start 429.75911 -17.342612)
		(end 429.4886 -17.613122)
		(width 0.12954)
		(layer "F.Cu")
		(net "P5E_CPU0_G3_TX_DN<1>")
	)
	(segment
		(start 429.4632 -16.366998)
		(end 429.75911 -16.662908)
		(width 0.12954)
		(layer "F.Cu")
		(net "P5E_CPU0_G3_TX_DN<1>")
	)
	(segment
		(start 372.407942 -233.409998)
		(end 372.874794 -233.14406)
		(width 0.12954)
		(layer "F.Cu")
		(net "P5E_CPU0_G3_TX_DN<1>")
	)
	(segment
		(start 374.001284 -225.367088)
		(end 374.000268 -225.367596)
		(width 0.1143)
		(layer "In4.Cu")
		(net "P5E_CPU0_G3_TX_DN<1>")
	)
	(segment
		(start 376.023886 -221.17431)
		(end 376.023886 -221.202758)
		(width 0.1143)
		(layer "In4.Cu")
		(net "P5E_CPU0_G3_TX_DN<1>")
	)
	(segment
		(start 373.537734 -232.653332)
		(end 373.535194 -232.654856)
		(width 0.1143)
		(layer "In4.Cu")
		(net "P5E_CPU0_G3_TX_DN<1>")
	)
	(segment
		(start 374.941846 -223.746822)
		(end 374.905524 -223.767904)
		(width 0.1143)
		(layer "In4.Cu")
		(net "P5E_CPU0_G3_TX_DN<1>")
	)
	(segment
		(start 374.00357 -225.365818)
		(end 374.001284 -225.367088)
		(width 0.1143)
		(layer "In4.Cu")
		(net "P5E_CPU0_G3_TX_DN<1>")
	)
	(segment
		(start 376.023886 -220.00464)
		(end 376.023886 -221.17431)
		(width 0.14224)
		(layer "In4.Cu")
		(net "P5E_CPU0_G3_TX_DN<1>")
	)
	(segment
		(start 375.417334 -222.933514)
		(end 375.416572 -222.934022)
		(width 0.1143)
		(layer "In4.Cu")
		(net "P5E_CPU0_G3_TX_DN<1>")
	)
	(segment
		(start 373.96547 -231.18064)
		(end 374.03532 -231.22128)
		(width 0.1143)
		(layer "In4.Cu")
		(net "P5E_CPU0_G3_TX_DN<1>")
	)
	(segment
		(start 342.23833 -180.363114)
		(end 367.459514 -201.019664)
		(width 0.14224)
		(layer "In4.Cu")
		(net "P5E_CPU0_G3_TX_DN<1>")
	)
	(segment
		(start 336.41919 -172.272452)
		(end 341.21471 -179.339748)
		(width 0.14224)
		(layer "In4.Cu")
		(net "P5E_CPU0_G3_TX_DN<1>")
	)
	(segment
		(start 375.413778 -222.935546)
		(end 375.412508 -222.936308)
		(width 0.1143)
		(layer "In4.Cu")
		(net "P5E_CPU0_G3_TX_DN<1>")
	)
	(segment
		(start 375.8819 -222.12681)
		(end 375.842784 -222.14967)
		(width 0.1143)
		(layer "In4.Cu")
		(net "P5E_CPU0_G3_TX_DN<1>")
	)
	(segment
		(start 376.069606 -221.248478)
		(end 376.069606 -221.804738)
		(width 0.1143)
		(layer "In4.Cu")
		(net "P5E_CPU0_G3_TX_DN<1>")
	)
	(segment
		(start 373.492776 -227.128832)
		(end 373.529352 -227.150168)
		(width 0.1143)
		(layer "In4.Cu")
		(net "P5E_CPU0_G3_TX_DN<1>")
	)
	(segment
		(start 326.213978 -138.112246)
		(end 326.195436 -138.25093)
		(width 0.14224)
		(layer "In4.Cu")
		(net "P5E_CPU0_G3_TX_DN<1>")
	)
	(segment
		(start 326.195436 -141.548358)
		(end 327.324974 -151.450294)
		(width 0.14224)
		(layer "In4.Cu")
		(net "P5E_CPU0_G3_TX_DN<1>")
	)
	(segment
		(start 375.411746 -222.936816)
		(end 375.375424 -222.957898)
		(width 0.1143)
		(layer "In4.Cu")
		(net "P5E_CPU0_G3_TX_DN<1>")
	)
	(segment
		(start 373.532654 -228.772212)
		(end 373.563642 -228.789992)
		(width 0.1143)
		(layer "In4.Cu")
		(net "P5E_CPU0_G3_TX_DN<1>")
	)
	(segment
		(start 375.443496 -222.918528)
		(end 375.423176 -222.929958)
		(width 0.1143)
		(layer "In4.Cu")
		(net "P5E_CPU0_G3_TX_DN<1>")
	)
	(segment
		(start 373.996204 -225.369882)
		(end 373.96547 -225.387916)
		(width 0.1143)
		(layer "In4.Cu")
		(net "P5E_CPU0_G3_TX_DN<1>")
	)
	(segment
		(start 375.415302 -222.934784)
		(end 375.413778 -222.935546)
		(width 0.1143)
		(layer "In4.Cu")
		(net "P5E_CPU0_G3_TX_DN<1>")
	)
	(segment
		(start 373.530876 -227.79736)
		(end 373.529352 -227.798376)
		(width 0.1143)
		(layer "In4.Cu")
		(net "P5E_CPU0_G3_TX_DN<1>")
	)
	(segment
		(start 375.149364 -213.998556)
		(end 376.023886 -220.00464)
		(width 0.14224)
		(layer "In4.Cu")
		(net "P5E_CPU0_G3_TX_DN<1>")
	)
	(segment
		(start 375.418604 -222.932752)
		(end 375.417334 -222.933514)
		(width 0.1143)
		(layer "In4.Cu")
		(net "P5E_CPU0_G3_TX_DN<1>")
	)
	(segment
		(start 373.529352 -228.77018)
		(end 373.530876 -228.771196)
		(width 0.1143)
		(layer "In4.Cu")
		(net "P5E_CPU0_G3_TX_DN<1>")
	)
	(segment
		(start 375.423176 -222.929958)
		(end 375.420636 -222.931482)
		(width 0.1143)
		(layer "In4.Cu")
		(net "P5E_CPU0_G3_TX_DN<1>")
	)
	(segment
		(start 373.532654 -227.796344)
		(end 373.531892 -227.796852)
		(width 0.1143)
		(layer "In4.Cu")
		(net "P5E_CPU0_G3_TX_DN<1>")
	)
	(segment
		(start 373.531892 -227.151692)
		(end 373.532654 -227.1522)
		(width 0.1143)
		(layer "In4.Cu")
		(net "P5E_CPU0_G3_TX_DN<1>")
	)
	(segment
		(start 373.529352 -226.178364)
		(end 373.492776 -226.1997)
		(width 0.1143)
		(layer "In4.Cu")
		(net "P5E_CPU0_G3_TX_DN<1>")
	)
	(segment
		(start 373.531892 -227.796852)
		(end 373.530876 -227.79736)
		(width 0.1143)
		(layer "In4.Cu")
		(net "P5E_CPU0_G3_TX_DN<1>")
	)
	(segment
		(start 375.412508 -222.936308)
		(end 375.411746 -222.936816)
		(width 0.1143)
		(layer "In4.Cu")
		(net "P5E_CPU0_G3_TX_DN<1>")
	)
	(segment
		(start 373.532654 -226.176332)
		(end 373.531892 -226.17684)
		(width 0.1143)
		(layer "In4.Cu")
		(net "P5E_CPU0_G3_TX_DN<1>")
	)
	(segment
		(start 341.21471 -179.339748)
		(end 342.23833 -180.363114)
		(width 0.14224)
		(layer "In4.Cu")
		(net "P5E_CPU0_G3_TX_DN<1>")
	)
	(segment
		(start 327.146412 -134.747508)
		(end 326.332596 -137.52703)
		(width 0.14224)
		(layer "In4.Cu")
		(net "P5E_CPU0_G3_TX_DN<1>")
	)
	(segment
		(start 375.91492 -222.107506)
		(end 375.914666 -222.10776)
		(width 0.1143)
		(layer "In4.Cu")
		(net "P5E_CPU0_G3_TX_DN<1>")
	)
	(segment
		(start 373.561356 -226.159822)
		(end 373.532654 -226.176332)
		(width 0.1143)
		(layer "In4.Cu")
		(net "P5E_CPU0_G3_TX_DN<1>")
	)
	(segment
		(start 373.530876 -227.151184)
		(end 373.531892 -227.151692)
		(width 0.1143)
		(layer "In4.Cu")
		(net "P5E_CPU0_G3_TX_DN<1>")
	)
	(segment
		(start 328.010774 -133.071108)
		(end 327.396094 -134.102856)
		(width 0.14224)
		(layer "In4.Cu")
		(net "P5E_CPU0_G3_TX_DN<1>")
	)
	(segment
		(start 374.033542 -231.82834)
		(end 374.001792 -231.846628)
		(width 0.1143)
		(layer "In4.Cu")
		(net "P5E_CPU0_G3_TX_DN<1>")
	)
	(segment
		(start 373.725186 -232.326942)
		(end 373.725186 -232.329482)
		(width 0.1143)
		(layer "In4.Cu")
		(net "P5E_CPU0_G3_TX_DN<1>")
	)
	(segment
		(start 373.25554 -233.061256)
		(end 373.172736 -233.14406)
		(width 0.1143)
		(layer "In4.Cu")
		(net "P5E_CPU0_G3_TX_DN<1>")
	)
	(segment
		(start 374.000268 -225.367596)
		(end 373.996204 -225.369882)
		(width 0.1143)
		(layer "In4.Cu")
		(net "P5E_CPU0_G3_TX_DN<1>")
	)
	(segment
		(start 373.532654 -232.656126)
		(end 373.531892 -232.656634)
		(width 0.1143)
		(layer "In4.Cu")
		(net "P5E_CPU0_G3_TX_DN<1>")
	)
	(segment
		(start 367.459514 -201.019664)
		(end 375.149364 -213.998556)
		(width 0.14224)
		(layer "In4.Cu")
		(net "P5E_CPU0_G3_TX_DN<1>")
	)
	(segment
		(start 326.332596 -137.52703)
		(end 326.213978 -138.112246)
		(width 0.14224)
		(layer "In4.Cu")
		(net "P5E_CPU0_G3_TX_DN<1>")
	)
	(segment
		(start 327.396094 -134.102856)
		(end 327.146412 -134.747508)
		(width 0.14224)
		(layer "In4.Cu")
		(net "P5E_CPU0_G3_TX_DN<1>")
	)
	(segment
		(start 376.023886 -221.202758)
		(end 376.069606 -221.248478)
		(width 0.1143)
		(layer "In4.Cu")
		(net "P5E_CPU0_G3_TX_DN<1>")
	)
	(segment
		(start 373.535194 -232.654856)
		(end 373.532654 -232.656126)
		(width 0.1143)
		(layer "In4.Cu")
		(net "P5E_CPU0_G3_TX_DN<1>")
	)
	(segment
		(start 373.532654 -227.1522)
		(end 373.563642 -227.16998)
		(width 0.1143)
		(layer "In4.Cu")
		(net "P5E_CPU0_G3_TX_DN<1>")
	)
	(segment
		(start 327.324974 -151.450294)
		(end 328.093832 -154.77617)
		(width 0.14224)
		(layer "In4.Cu")
		(net "P5E_CPU0_G3_TX_DN<1>")
	)
	(segment
		(start 375.914666 -222.10776)
		(end 375.8819 -222.12681)
		(width 0.1143)
		(layer "In4.Cu")
		(net "P5E_CPU0_G3_TX_DN<1>")
	)
	(segment
		(start 373.530876 -232.657142)
		(end 373.529352 -232.658158)
		(width 0.1143)
		(layer "In4.Cu")
		(net "P5E_CPU0_G3_TX_DN<1>")
	)
	(segment
		(start 373.531892 -228.771704)
		(end 373.532654 -228.772212)
		(width 0.1143)
		(layer "In4.Cu")
		(net "P5E_CPU0_G3_TX_DN<1>")
	)
	(segment
		(start 429.77943 -17.903952)
		(end 429.77943 -20.438872)
		(width 0.14224)
		(layer "In4.Cu")
		(net "P5E_CPU0_G3_TX_DN<1>")
	)
	(segment
		(start 373.531892 -226.17684)
		(end 373.530876 -226.177348)
		(width 0.1143)
		(layer "In4.Cu")
		(net "P5E_CPU0_G3_TX_DN<1>")
	)
	(segment
		(start 326.195436 -138.25093)
		(end 326.195436 -141.548358)
		(width 0.14224)
		(layer "In4.Cu")
		(net "P5E_CPU0_G3_TX_DN<1>")
	)
	(segment
		(start 375.420636 -222.931482)
		(end 375.418604 -222.932752)
		(width 0.1143)
		(layer "In4.Cu")
		(net "P5E_CPU0_G3_TX_DN<1>")
	)
	(segment
		(start 373.56542 -229.397052)
		(end 373.492776 -229.43947)
		(width 0.1143)
		(layer "In4.Cu")
		(net "P5E_CPU0_G3_TX_DN<1>")
	)
	(segment
		(start 373.563642 -227.778564)
		(end 373.532654 -227.796344)
		(width 0.1143)
		(layer "In4.Cu")
		(net "P5E_CPU0_G3_TX_DN<1>")
	)
	(segment
		(start 373.529352 -232.658158)
		(end 373.492776 -232.679494)
		(width 0.1143)
		(layer "In4.Cu")
		(net "P5E_CPU0_G3_TX_DN<1>")
	)
	(segment
		(start 429.4886 -17.613122)
		(end 429.77943 -17.903952)
		(width 0.14224)
		(layer "In4.Cu")
		(net "P5E_CPU0_G3_TX_DN<1>")
	)
	(segment
		(start 373.530876 -230.394002)
		(end 373.53621 -230.39705)
		(width 0.1143)
		(layer "In4.Cu")
		(net "P5E_CPU0_G3_TX_DN<1>")
	)
	(segment
		(start 374.973596 -223.728534)
		(end 374.941846 -223.746822)
		(width 0.1143)
		(layer "In4.Cu")
		(net "P5E_CPU0_G3_TX_DN<1>")
	)
	(segment
		(start 373.530876 -226.177348)
		(end 373.529352 -226.178364)
		(width 0.1143)
		(layer "In4.Cu")
		(net "P5E_CPU0_G3_TX_DN<1>")
	)
	(segment
		(start 373.529352 -227.798376)
		(end 373.492776 -227.819712)
		(width 0.1143)
		(layer "In4.Cu")
		(net "P5E_CPU0_G3_TX_DN<1>")
	)
	(segment
		(start 375.416572 -222.934022)
		(end 375.415302 -222.934784)
		(width 0.1143)
		(layer "In4.Cu")
		(net "P5E_CPU0_G3_TX_DN<1>")
	)
	(segment
		(start 373.530876 -228.771196)
		(end 373.531892 -228.771704)
		(width 0.1143)
		(layer "In4.Cu")
		(net "P5E_CPU0_G3_TX_DN<1>")
	)
	(segment
		(start 373.529352 -227.150168)
		(end 373.530876 -227.151184)
		(width 0.1143)
		(layer "In4.Cu")
		(net "P5E_CPU0_G3_TX_DN<1>")
	)
	(segment
		(start 429.77943 -20.438872)
		(end 328.010774 -133.071108)
		(width 0.14224)
		(layer "In4.Cu")
		(net "P5E_CPU0_G3_TX_DN<1>")
	)
	(segment
		(start 328.679302 -156.427424)
		(end 336.41919 -172.272452)
		(width 0.14224)
		(layer "In4.Cu")
		(net "P5E_CPU0_G3_TX_DN<1>")
	)
	(segment
		(start 328.093832 -154.77617)
		(end 328.679302 -156.427424)
		(width 0.14224)
		(layer "In4.Cu")
		(net "P5E_CPU0_G3_TX_DN<1>")
	)
	(segment
		(start 373.172736 -233.14406)
		(end 372.874794 -233.14406)
		(width 0.1143)
		(layer "In4.Cu")
		(net "P5E_CPU0_G3_TX_DN<1>")
	)
	(segment
		(start 373.531892 -232.656634)
		(end 373.530876 -232.657142)
		(width 0.1143)
		(layer "In4.Cu")
		(net "P5E_CPU0_G3_TX_DN<1>")
	)
	(segment
		(start 373.492776 -228.748844)
		(end 373.529352 -228.77018)
		(width 0.1143)
		(layer "In4.Cu")
		(net "P5E_CPU0_G3_TX_DN<1>")
	)
	(arc
		(start 373.725186 -232.329482)
		(mid 373.674936 -232.516564)
		(end 373.537734 -232.653332)
		(width 0.1143)
		(layer "In4.Cu")
		(net "P5E_CPU0_G3_TX_DN<1>")
	)
	(arc
		(start 373.53621 -230.39705)
		(mid 373.670482 -230.531067)
		(end 373.719598 -230.714296)
		(width 0.1143)
		(layer "In4.Cu")
		(net "P5E_CPU0_G3_TX_DN<1>")
	)
	(arc
		(start 374.03532 -231.22128)
		(mid 374.148727 -231.354169)
		(end 374.189498 -231.524048)
		(width 0.1143)
		(layer "In4.Cu")
		(net "P5E_CPU0_G3_TX_DN<1>")
	)
	(arc
		(start 375.842784 -222.14967)
		(mid 375.663971 -222.35202)
		(end 375.599452 -222.614236)
		(width 0.1143)
		(layer "In4.Cu")
		(net "P5E_CPU0_G3_TX_DN<1>")
	)
	(arc
		(start 373.719598 -225.85426)
		(mid 373.674587 -226.024696)
		(end 373.561356 -226.159822)
		(width 0.1143)
		(layer "In4.Cu")
		(net "P5E_CPU0_G3_TX_DN<1>")
	)
	(arc
		(start 374.662192 -224.178368)
		(mid 374.588683 -224.406437)
		(end 374.427242 -224.583498)
		(width 0.1143)
		(layer "In4.Cu")
		(net "P5E_CPU0_G3_TX_DN<1>")
	)
	(arc
		(start 373.563642 -228.789992)
		(mid 373.675439 -228.924793)
		(end 373.719598 -229.094284)
		(width 0.1143)
		(layer "In4.Cu")
		(net "P5E_CPU0_G3_TX_DN<1>")
	)
	(arc
		(start 373.249444 -229.904036)
		(mid 373.324812 -230.186551)
		(end 373.530876 -230.394002)
		(width 0.1143)
		(layer "In4.Cu")
		(net "P5E_CPU0_G3_TX_DN<1>")
	)
	(arc
		(start 373.492776 -227.819712)
		(mid 373.249449 -228.284278)
		(end 373.492776 -228.748844)
		(width 0.1143)
		(layer "In4.Cu")
		(net "P5E_CPU0_G3_TX_DN<1>")
	)
	(arc
		(start 373.563642 -227.16998)
		(mid 373.715231 -227.474272)
		(end 373.563642 -227.778564)
		(width 0.1143)
		(layer "In4.Cu")
		(net "P5E_CPU0_G3_TX_DN<1>")
	)
	(arc
		(start 374.189498 -225.044254)
		(mid 374.139675 -225.229984)
		(end 374.00357 -225.365818)
		(width 0.1143)
		(layer "In4.Cu")
		(net "P5E_CPU0_G3_TX_DN<1>")
	)
	(arc
		(start 373.719598 -229.094284)
		(mid 373.678836 -229.264168)
		(end 373.56542 -229.397052)
		(width 0.1143)
		(layer "In4.Cu")
		(net "P5E_CPU0_G3_TX_DN<1>")
	)
	(arc
		(start 373.492776 -232.679494)
		(mid 373.340789 -232.836002)
		(end 373.25935 -233.038396)
		(width 0.1143)
		(layer "In4.Cu")
		(net "P5E_CPU0_G3_TX_DN<1>")
	)
	(arc
		(start 375.599452 -222.614236)
		(mid 375.558197 -222.785207)
		(end 375.443496 -222.918528)
		(width 0.1143)
		(layer "In4.Cu")
		(net "P5E_CPU0_G3_TX_DN<1>")
	)
	(arc
		(start 375.375424 -222.957898)
		(mid 375.200946 -223.149251)
		(end 375.13006 -223.398334)
		(width 0.1143)
		(layer "In4.Cu")
		(net "P5E_CPU0_G3_TX_DN<1>")
	)
	(arc
		(start 375.13006 -223.398334)
		(mid 375.123875 -223.455377)
		(end 375.110248 -223.51111)
		(width 0.1143)
		(layer "In4.Cu")
		(net "P5E_CPU0_G3_TX_DN<1>")
	)
	(arc
		(start 374.427242 -224.583498)
		(mid 374.252453 -224.785021)
		(end 374.189498 -225.044254)
		(width 0.1143)
		(layer "In4.Cu")
		(net "P5E_CPU0_G3_TX_DN<1>")
	)
	(arc
		(start 374.905524 -223.767904)
		(mid 374.738376 -223.946184)
		(end 374.662192 -224.178368)
		(width 0.1143)
		(layer "In4.Cu")
		(net "P5E_CPU0_G3_TX_DN<1>")
	)
	(arc
		(start 373.719598 -230.714296)
		(mid 373.784834 -230.977887)
		(end 373.96547 -231.18064)
		(width 0.1143)
		(layer "In4.Cu")
		(net "P5E_CPU0_G3_TX_DN<1>")
	)
	(arc
		(start 373.492776 -229.43947)
		(mid 373.313963 -229.64182)
		(end 373.249444 -229.904036)
		(width 0.1143)
		(layer "In4.Cu")
		(net "P5E_CPU0_G3_TX_DN<1>")
	)
	(arc
		(start 373.25935 -233.038396)
		(mid 373.257327 -233.049806)
		(end 373.25554 -233.061256)
		(width 0.1143)
		(layer "In4.Cu")
		(net "P5E_CPU0_G3_TX_DN<1>")
	)
	(arc
		(start 375.110248 -223.51111)
		(mid 375.055696 -223.628481)
		(end 374.973596 -223.728534)
		(width 0.1143)
		(layer "In4.Cu")
		(net "P5E_CPU0_G3_TX_DN<1>")
	)
	(arc
		(start 373.96547 -225.387916)
		(mid 373.784818 -225.590661)
		(end 373.719598 -225.85426)
		(width 0.1143)
		(layer "In4.Cu")
		(net "P5E_CPU0_G3_TX_DN<1>")
	)
	(arc
		(start 374.001792 -231.846628)
		(mid 373.799252 -232.049798)
		(end 373.725186 -232.326942)
		(width 0.1143)
		(layer "In4.Cu")
		(net "P5E_CPU0_G3_TX_DN<1>")
	)
	(arc
		(start 373.492776 -226.1997)
		(mid 373.249449 -226.664266)
		(end 373.492776 -227.128832)
		(width 0.1143)
		(layer "In4.Cu")
		(net "P5E_CPU0_G3_TX_DN<1>")
	)
	(arc
		(start 374.189498 -231.524048)
		(mid 374.148243 -231.695019)
		(end 374.033542 -231.82834)
		(width 0.1143)
		(layer "In4.Cu")
		(net "P5E_CPU0_G3_TX_DN<1>")
	)
	(arc
		(start 376.069606 -221.804738)
		(mid 376.028694 -221.974734)
		(end 375.91492 -222.107506)
		(width 0.1143)
		(layer "In4.Cu")
		(net "P5E_CPU0_G3_TX_DN<1>")
	)
	(segment
		(start 390.302496 -16.662146)
		(end 390.304274 -16.662146)
		(width 0.12954)
		(layer "F.Cu")
		(net "P5E_CPU0_G3_TX_DN<15>")
	)
	(segment
		(start 390.304274 -16.662146)
		(end 390.304274 -17.34185)
		(width 0.12954)
		(layer "F.Cu")
		(net "P5E_CPU0_G3_TX_DN<15>")
	)
	(segment
		(start 390.304274 -17.34185)
		(end 390.033764 -17.61236)
		(width 0.12954)
		(layer "F.Cu")
		(net "P5E_CPU0_G3_TX_DN<15>")
	)
	(segment
		(start 361.597956 -235.840016)
		(end 362.064808 -235.574078)
		(width 0.12954)
		(layer "F.Cu")
		(net "P5E_CPU0_G3_TX_DN<15>")
	)
	(segment
		(start 390.007348 -16.366998)
		(end 390.302496 -16.662146)
		(width 0.12954)
		(layer "F.Cu")
		(net "P5E_CPU0_G3_TX_DN<15>")
	)
	(segment
		(start 362.253784 -235.252768)
		(end 362.255308 -235.25353)
		(width 0.1143)
		(layer "In4.Cu")
		(net "P5E_CPU0_G3_TX_DN<15>")
	)
	(segment
		(start 361.311698 -233.631232)
		(end 361.311952 -233.631486)
		(width 0.1143)
		(layer "In4.Cu")
		(net "P5E_CPU0_G3_TX_DN<15>")
	)
	(segment
		(start 362.249974 -235.250228)
		(end 362.252514 -235.252006)
		(width 0.1143)
		(layer "In4.Cu")
		(net "P5E_CPU0_G3_TX_DN<15>")
	)
	(segment
		(start 360.314494 -223.31426)
		(end 360.314494 -232.724706)
		(width 0.14224)
		(layer "In4.Cu")
		(net "P5E_CPU0_G3_TX_DN<15>")
	)
	(segment
		(start 362.260388 -235.256324)
		(end 362.283502 -235.269786)
		(width 0.1143)
		(layer "In4.Cu")
		(net "P5E_CPU0_G3_TX_DN<15>")
	)
	(segment
		(start 362.247942 -235.248958)
		(end 362.249974 -235.250228)
		(width 0.1143)
		(layer "In4.Cu")
		(net "P5E_CPU0_G3_TX_DN<15>")
	)
	(segment
		(start 361.781852 -234.441492)
		(end 361.782614 -234.442)
		(width 0.1143)
		(layer "In4.Cu")
		(net "P5E_CPU0_G3_TX_DN<15>")
	)
	(segment
		(start 308.649878 -170.444414)
		(end 313.517534 -175.31334)
		(width 0.14224)
		(layer "In4.Cu")
		(net "P5E_CPU0_G3_TX_DN<15>")
	)
	(segment
		(start 361.780836 -234.440984)
		(end 361.781852 -234.441492)
		(width 0.1143)
		(layer "In4.Cu")
		(net "P5E_CPU0_G3_TX_DN<15>")
	)
	(segment
		(start 362.21289 -235.228892)
		(end 362.247942 -235.248958)
		(width 0.1143)
		(layer "In4.Cu")
		(net "P5E_CPU0_G3_TX_DN<15>")
	)
	(segment
		(start 361.782614 -234.442)
		(end 361.813602 -234.45978)
		(width 0.1143)
		(layer "In4.Cu")
		(net "P5E_CPU0_G3_TX_DN<15>")
	)
	(segment
		(start 321.743832 -116.42471)
		(end 315.153802 -128.672082)
		(width 0.14224)
		(layer "In4.Cu")
		(net "P5E_CPU0_G3_TX_DN<15>")
	)
	(segment
		(start 362.4326 -235.504228)
		(end 362.36275 -235.574078)
		(width 0.1143)
		(layer "In4.Cu")
		(net "P5E_CPU0_G3_TX_DN<15>")
	)
	(segment
		(start 361.969558 -234.764072)
		(end 361.969558 -234.780582)
		(width 0.1143)
		(layer "In4.Cu")
		(net "P5E_CPU0_G3_TX_DN<15>")
	)
	(segment
		(start 361.779058 -234.439968)
		(end 361.780836 -234.440984)
		(width 0.1143)
		(layer "In4.Cu")
		(net "P5E_CPU0_G3_TX_DN<15>")
	)
	(segment
		(start 360.907838 -216.11463)
		(end 360.907838 -220.331284)
		(width 0.14224)
		(layer "In4.Cu")
		(net "P5E_CPU0_G3_TX_DN<15>")
	)
	(segment
		(start 361.749594 -234.422696)
		(end 361.750356 -234.423204)
		(width 0.1143)
		(layer "In4.Cu")
		(net "P5E_CPU0_G3_TX_DN<15>")
	)
	(segment
		(start 361.776518 -234.438444)
		(end 361.777534 -234.438952)
		(width 0.1143)
		(layer "In4.Cu")
		(net "P5E_CPU0_G3_TX_DN<15>")
	)
	(segment
		(start 313.517534 -175.31334)
		(end 319.189862 -178.71313)
		(width 0.14224)
		(layer "In4.Cu")
		(net "P5E_CPU0_G3_TX_DN<15>")
	)
	(segment
		(start 390.324594 -20.45716)
		(end 321.743832 -116.42471)
		(width 0.14224)
		(layer "In4.Cu")
		(net "P5E_CPU0_G3_TX_DN<15>")
	)
	(segment
		(start 305.708812 -163.342828)
		(end 308.649878 -170.444414)
		(width 0.14224)
		(layer "In4.Cu")
		(net "P5E_CPU0_G3_TX_DN<15>")
	)
	(segment
		(start 362.257848 -235.255054)
		(end 362.260388 -235.256324)
		(width 0.1143)
		(layer "In4.Cu")
		(net "P5E_CPU0_G3_TX_DN<15>")
	)
	(segment
		(start 360.854752 -233.200702)
		(end 361.196382 -233.542332)
		(width 0.1143)
		(layer "In4.Cu")
		(net "P5E_CPU0_G3_TX_DN<15>")
	)
	(segment
		(start 362.36275 -235.574078)
		(end 362.064808 -235.574078)
		(width 0.1143)
		(layer "In4.Cu")
		(net "P5E_CPU0_G3_TX_DN<15>")
	)
	(segment
		(start 320.028062 -179.2732)
		(end 357.064564 -209.641694)
		(width 0.14224)
		(layer "In4.Cu")
		(net "P5E_CPU0_G3_TX_DN<15>")
	)
	(segment
		(start 362.1913 -235.213398)
		(end 362.21289 -235.228892)
		(width 0.1143)
		(layer "In4.Cu")
		(net "P5E_CPU0_G3_TX_DN<15>")
	)
	(segment
		(start 357.064564 -209.641694)
		(end 360.907838 -216.11463)
		(width 0.14224)
		(layer "In4.Cu")
		(net "P5E_CPU0_G3_TX_DN<15>")
	)
	(segment
		(start 360.907838 -220.331284)
		(end 360.314494 -223.31426)
		(width 0.14224)
		(layer "In4.Cu")
		(net "P5E_CPU0_G3_TX_DN<15>")
	)
	(segment
		(start 390.324594 -17.90319)
		(end 390.324594 -20.45716)
		(width 0.14224)
		(layer "In4.Cu")
		(net "P5E_CPU0_G3_TX_DN<15>")
	)
	(segment
		(start 362.255308 -235.25353)
		(end 362.25607 -235.254038)
		(width 0.1143)
		(layer "In4.Cu")
		(net "P5E_CPU0_G3_TX_DN<15>")
	)
	(segment
		(start 315.153802 -128.672082)
		(end 310.579262 -140.5763)
		(width 0.14224)
		(layer "In4.Cu")
		(net "P5E_CPU0_G3_TX_DN<15>")
	)
	(segment
		(start 319.189862 -178.71313)
		(end 320.028062 -179.2732)
		(width 0.14224)
		(layer "In4.Cu")
		(net "P5E_CPU0_G3_TX_DN<15>")
	)
	(segment
		(start 360.314494 -232.724706)
		(end 360.770678 -233.18089)
		(width 0.14224)
		(layer "In4.Cu")
		(net "P5E_CPU0_G3_TX_DN<15>")
	)
	(segment
		(start 361.742736 -234.418632)
		(end 361.749594 -234.422696)
		(width 0.1143)
		(layer "In4.Cu")
		(net "P5E_CPU0_G3_TX_DN<15>")
	)
	(segment
		(start 362.257086 -235.254546)
		(end 362.257848 -235.255054)
		(width 0.1143)
		(layer "In4.Cu")
		(net "P5E_CPU0_G3_TX_DN<15>")
	)
	(segment
		(start 390.033764 -17.61236)
		(end 390.324594 -17.90319)
		(width 0.14224)
		(layer "In4.Cu")
		(net "P5E_CPU0_G3_TX_DN<15>")
	)
	(segment
		(start 360.790744 -233.200956)
		(end 360.854752 -233.200702)
		(width 0.1143)
		(layer "In4.Cu")
		(net "P5E_CPU0_G3_TX_DN<15>")
	)
	(segment
		(start 360.770678 -233.18089)
		(end 360.790744 -233.200956)
		(width 0.1143)
		(layer "In4.Cu")
		(net "P5E_CPU0_G3_TX_DN<15>")
	)
	(segment
		(start 361.774994 -234.437428)
		(end 361.776518 -234.438444)
		(width 0.1143)
		(layer "In4.Cu")
		(net "P5E_CPU0_G3_TX_DN<15>")
	)
	(segment
		(start 362.25607 -235.254038)
		(end 362.257086 -235.254546)
		(width 0.1143)
		(layer "In4.Cu")
		(net "P5E_CPU0_G3_TX_DN<15>")
	)
	(segment
		(start 361.777534 -234.438952)
		(end 361.779058 -234.439968)
		(width 0.1143)
		(layer "In4.Cu")
		(net "P5E_CPU0_G3_TX_DN<15>")
	)
	(segment
		(start 362.252514 -235.252006)
		(end 362.253784 -235.252768)
		(width 0.1143)
		(layer "In4.Cu")
		(net "P5E_CPU0_G3_TX_DN<15>")
	)
	(segment
		(start 310.579262 -140.5763)
		(end 306.179474 -155.784804)
		(width 0.14224)
		(layer "In4.Cu")
		(net "P5E_CPU0_G3_TX_DN<15>")
	)
	(segment
		(start 306.179474 -155.784804)
		(end 305.708812 -158.15056)
		(width 0.14224)
		(layer "In4.Cu")
		(net "P5E_CPU0_G3_TX_DN<15>")
	)
	(segment
		(start 361.311952 -233.631486)
		(end 361.342432 -233.649266)
		(width 0.1143)
		(layer "In4.Cu")
		(net "P5E_CPU0_G3_TX_DN<15>")
	)
	(segment
		(start 305.708812 -158.15056)
		(end 305.708812 -163.342828)
		(width 0.14224)
		(layer "In4.Cu")
		(net "P5E_CPU0_G3_TX_DN<15>")
	)
	(segment
		(start 361.750356 -234.423204)
		(end 361.774994 -234.437428)
		(width 0.1143)
		(layer "In4.Cu")
		(net "P5E_CPU0_G3_TX_DN<15>")
	)
	(arc
		(start 362.283502 -235.269786)
		(mid 362.380637 -235.372655)
		(end 362.4326 -235.504228)
		(width 0.1143)
		(layer "In4.Cu")
		(net "P5E_CPU0_G3_TX_DN<15>")
	)
	(arc
		(start 361.196382 -233.542332)
		(mid 361.251155 -233.590524)
		(end 361.311698 -233.631232)
		(width 0.1143)
		(layer "In4.Cu")
		(net "P5E_CPU0_G3_TX_DN<15>")
	)
	(arc
		(start 361.342432 -233.649266)
		(mid 361.457859 -233.782642)
		(end 361.499404 -233.954066)
		(width 0.1143)
		(layer "In4.Cu")
		(net "P5E_CPU0_G3_TX_DN<15>")
	)
	(arc
		(start 361.499404 -233.954066)
		(mid 361.563919 -234.216285)
		(end 361.742736 -234.418632)
		(width 0.1143)
		(layer "In4.Cu")
		(net "P5E_CPU0_G3_TX_DN<15>")
	)
	(arc
		(start 361.813602 -234.45978)
		(mid 361.925399 -234.594581)
		(end 361.969558 -234.764072)
		(width 0.1143)
		(layer "In4.Cu")
		(net "P5E_CPU0_G3_TX_DN<15>")
	)
	(arc
		(start 361.969558 -234.780582)
		(mid 362.028211 -235.02375)
		(end 362.1913 -235.213398)
		(width 0.1143)
		(layer "In4.Cu")
		(net "P5E_CPU0_G3_TX_DN<15>")
	)
	(segment
		(start 392.801348 -17.890998)
		(end 393.098274 -18.187924)
		(width 0.12954)
		(layer "F.Cu")
		(net "P5E_CPU0_G3_TX_DN<14>")
	)
	(segment
		(start 393.098274 -18.865596)
		(end 392.826748 -19.137122)
		(width 0.12954)
		(layer "F.Cu")
		(net "P5E_CPU0_G3_TX_DN<14>")
	)
	(segment
		(start 393.098274 -18.187924)
		(end 393.098274 -18.865596)
		(width 0.12954)
		(layer "F.Cu")
		(net "P5E_CPU0_G3_TX_DN<14>")
	)
	(segment
		(start 361.597956 -234.220004)
		(end 362.064808 -233.954066)
		(width 0.12954)
		(layer "F.Cu")
		(net "P5E_CPU0_G3_TX_DN<14>")
	)
	(segment
		(start 361.27563 -228.750622)
		(end 361.311952 -228.771704)
		(width 0.1143)
		(layer "In4.Cu")
		(net "P5E_CPU0_G3_TX_DN<14>")
	)
	(segment
		(start 393.117578 -20.456398)
		(end 322.000626 -118.039896)
		(width 0.14224)
		(layer "In4.Cu")
		(net "P5E_CPU0_G3_TX_DN<14>")
	)
	(segment
		(start 361.923838 -215.9635)
		(end 361.923838 -221.083124)
		(width 0.14224)
		(layer "In4.Cu")
		(net "P5E_CPU0_G3_TX_DN<14>")
	)
	(segment
		(start 361.315508 -231.037384)
		(end 361.30865 -231.041448)
		(width 0.1143)
		(layer "In4.Cu")
		(net "P5E_CPU0_G3_TX_DN<14>")
	)
	(segment
		(start 361.029758 -231.524048)
		(end 361.029504 -231.524048)
		(width 0.1143)
		(layer "In4.Cu")
		(net "P5E_CPU0_G3_TX_DN<14>")
	)
	(segment
		(start 361.969304 -221.30893)
		(end 361.969304 -223.61017)
		(width 0.1143)
		(layer "In4.Cu")
		(net "P5E_CPU0_G3_TX_DN<14>")
	)
	(segment
		(start 392.826748 -19.137122)
		(end 393.117578 -19.427952)
		(width 0.14224)
		(layer "In4.Cu")
		(net "P5E_CPU0_G3_TX_DN<14>")
	)
	(segment
		(start 361.969558 -221.128844)
		(end 361.969558 -221.308676)
		(width 0.1143)
		(layer "In4.Cu")
		(net "P5E_CPU0_G3_TX_DN<14>")
	)
	(segment
		(start 357.824278 -209.05851)
		(end 361.923838 -215.9635)
		(width 0.14224)
		(layer "In4.Cu")
		(net "P5E_CPU0_G3_TX_DN<14>")
	)
	(segment
		(start 361.311698 -230.391462)
		(end 361.34167 -230.408734)
		(width 0.1143)
		(layer "In4.Cu")
		(net "P5E_CPU0_G3_TX_DN<14>")
	)
	(segment
		(start 316.003432 -129.060702)
		(end 311.463182 -140.876528)
		(width 0.14224)
		(layer "In4.Cu")
		(net "P5E_CPU0_G3_TX_DN<14>")
	)
	(segment
		(start 322.000626 -118.039896)
		(end 316.003432 -129.060702)
		(width 0.14224)
		(layer "In4.Cu")
		(net "P5E_CPU0_G3_TX_DN<14>")
	)
	(segment
		(start 361.342432 -227.779072)
		(end 361.311952 -227.796852)
		(width 0.1143)
		(layer "In4.Cu")
		(net "P5E_CPU0_G3_TX_DN<14>")
	)
	(segment
		(start 319.697862 -177.930302)
		(end 320.578988 -178.519074)
		(width 0.14224)
		(layer "In4.Cu")
		(net "P5E_CPU0_G3_TX_DN<14>")
	)
	(segment
		(start 361.311952 -227.151692)
		(end 361.342432 -227.169472)
		(width 0.1143)
		(layer "In4.Cu")
		(net "P5E_CPU0_G3_TX_DN<14>")
	)
	(segment
		(start 361.50042 -225.727514)
		(end 361.50042 -225.747834)
		(width 0.1143)
		(layer "In4.Cu")
		(net "P5E_CPU0_G3_TX_DN<14>")
	)
	(segment
		(start 361.344464 -229.397814)
		(end 361.300776 -229.42296)
		(width 0.1143)
		(layer "In4.Cu")
		(net "P5E_CPU0_G3_TX_DN<14>")
	)
	(segment
		(start 361.311952 -227.796852)
		(end 361.27563 -227.817934)
		(width 0.1143)
		(layer "In4.Cu")
		(net "P5E_CPU0_G3_TX_DN<14>")
	)
	(segment
		(start 361.310682 -232.014014)
		(end 361.316778 -232.01757)
		(width 0.1143)
		(layer "In4.Cu")
		(net "P5E_CPU0_G3_TX_DN<14>")
	)
	(segment
		(start 362.4326 -233.884216)
		(end 362.36275 -233.954066)
		(width 0.1143)
		(layer "In4.Cu")
		(net "P5E_CPU0_G3_TX_DN<14>")
	)
	(segment
		(start 361.311952 -228.771704)
		(end 361.342432 -228.789484)
		(width 0.1143)
		(layer "In4.Cu")
		(net "P5E_CPU0_G3_TX_DN<14>")
	)
	(segment
		(start 361.97413 -233.131614)
		(end 361.97413 -233.238548)
		(width 0.1143)
		(layer "In4.Cu")
		(net "P5E_CPU0_G3_TX_DN<14>")
	)
	(segment
		(start 362.36275 -233.954066)
		(end 362.064808 -233.954066)
		(width 0.1143)
		(layer "In4.Cu")
		(net "P5E_CPU0_G3_TX_DN<14>")
	)
	(segment
		(start 361.278424 -230.372158)
		(end 361.311698 -230.391462)
		(width 0.1143)
		(layer "In4.Cu")
		(net "P5E_CPU0_G3_TX_DN<14>")
	)
	(segment
		(start 361.969304 -223.61017)
		(end 361.50042 -225.727514)
		(width 0.1143)
		(layer "In4.Cu")
		(net "P5E_CPU0_G3_TX_DN<14>")
	)
	(segment
		(start 362.17479 -233.586782)
		(end 362.283502 -233.649774)
		(width 0.1143)
		(layer "In4.Cu")
		(net "P5E_CPU0_G3_TX_DN<14>")
	)
	(segment
		(start 306.640992 -158.244794)
		(end 306.640992 -162.927792)
		(width 0.14224)
		(layer "In4.Cu")
		(net "P5E_CPU0_G3_TX_DN<14>")
	)
	(segment
		(start 393.117578 -19.427952)
		(end 393.117578 -20.456398)
		(width 0.14224)
		(layer "In4.Cu")
		(net "P5E_CPU0_G3_TX_DN<14>")
	)
	(segment
		(start 309.602378 -170.078146)
		(end 314.095638 -174.572422)
		(width 0.14224)
		(layer "In4.Cu")
		(net "P5E_CPU0_G3_TX_DN<14>")
	)
	(segment
		(start 361.923838 -221.083124)
		(end 361.969558 -221.128844)
		(width 0.1143)
		(layer "In4.Cu")
		(net "P5E_CPU0_G3_TX_DN<14>")
	)
	(segment
		(start 361.783376 -232.824274)
		(end 361.80141 -232.834688)
		(width 0.1143)
		(layer "In4.Cu")
		(net "P5E_CPU0_G3_TX_DN<14>")
	)
	(segment
		(start 307.086254 -156.00553)
		(end 306.640992 -158.244794)
		(width 0.14224)
		(layer "In4.Cu")
		(net "P5E_CPU0_G3_TX_DN<14>")
	)
	(segment
		(start 361.343702 -226.158298)
		(end 361.27563 -226.197922)
		(width 0.1143)
		(layer "In4.Cu")
		(net "P5E_CPU0_G3_TX_DN<14>")
	)
	(segment
		(start 311.463182 -140.876528)
		(end 307.086254 -156.00553)
		(width 0.14224)
		(layer "In4.Cu")
		(net "P5E_CPU0_G3_TX_DN<14>")
	)
	(segment
		(start 361.50042 -225.747834)
		(end 361.499404 -225.85807)
		(width 0.1143)
		(layer "In4.Cu")
		(net "P5E_CPU0_G3_TX_DN<14>")
	)
	(segment
		(start 314.095638 -174.572422)
		(end 319.697862 -177.930302)
		(width 0.14224)
		(layer "In4.Cu")
		(net "P5E_CPU0_G3_TX_DN<14>")
	)
	(segment
		(start 361.27563 -227.13061)
		(end 361.311952 -227.151692)
		(width 0.1143)
		(layer "In4.Cu")
		(net "P5E_CPU0_G3_TX_DN<14>")
	)
	(segment
		(start 306.640992 -162.927792)
		(end 309.602378 -170.078146)
		(width 0.14224)
		(layer "In4.Cu")
		(net "P5E_CPU0_G3_TX_DN<14>")
	)
	(segment
		(start 320.578988 -178.519074)
		(end 357.824278 -209.05851)
		(width 0.14224)
		(layer "In4.Cu")
		(net "P5E_CPU0_G3_TX_DN<14>")
	)
	(segment
		(start 361.80141 -232.834688)
		(end 361.832652 -232.855516)
		(width 0.1143)
		(layer "In4.Cu")
		(net "P5E_CPU0_G3_TX_DN<14>")
	)
	(segment
		(start 361.969558 -221.308676)
		(end 361.969304 -221.30893)
		(width 0.1143)
		(layer "In4.Cu")
		(net "P5E_CPU0_G3_TX_DN<14>")
	)
	(arc
		(start 361.499404 -225.85807)
		(mid 361.457336 -226.026727)
		(end 361.343702 -226.158298)
		(width 0.1143)
		(layer "In4.Cu")
		(net "P5E_CPU0_G3_TX_DN<14>")
	)
	(arc
		(start 362.283502 -233.649774)
		(mid 362.380637 -233.752643)
		(end 362.4326 -233.884216)
		(width 0.1143)
		(layer "In4.Cu")
		(net "P5E_CPU0_G3_TX_DN<14>")
	)
	(arc
		(start 361.316778 -232.01757)
		(mid 361.450012 -232.151635)
		(end 361.499404 -232.334054)
		(width 0.1143)
		(layer "In4.Cu")
		(net "P5E_CPU0_G3_TX_DN<14>")
	)
	(arc
		(start 361.27563 -227.817934)
		(mid 361.02974 -228.284278)
		(end 361.27563 -228.750622)
		(width 0.1143)
		(layer "In4.Cu")
		(net "P5E_CPU0_G3_TX_DN<14>")
	)
	(arc
		(start 361.029504 -231.524048)
		(mid 361.04926 -231.672728)
		(end 361.107228 -231.811068)
		(width 0.1143)
		(layer "In4.Cu")
		(net "P5E_CPU0_G3_TX_DN<14>")
	)
	(arc
		(start 361.34167 -230.408734)
		(mid 361.457851 -230.542293)
		(end 361.499658 -230.714296)
		(width 0.1143)
		(layer "In4.Cu")
		(net "P5E_CPU0_G3_TX_DN<14>")
	)
	(arc
		(start 361.342432 -227.169472)
		(mid 361.499409 -227.474272)
		(end 361.342432 -227.779072)
		(width 0.1143)
		(layer "In4.Cu")
		(net "P5E_CPU0_G3_TX_DN<14>")
	)
	(arc
		(start 361.029758 -229.910386)
		(mid 361.095045 -230.161327)
		(end 361.261406 -230.36022)
		(width 0.1143)
		(layer "In4.Cu")
		(net "P5E_CPU0_G3_TX_DN<14>")
	)
	(arc
		(start 361.342432 -228.789484)
		(mid 361.457859 -228.92286)
		(end 361.499404 -229.094284)
		(width 0.1143)
		(layer "In4.Cu")
		(net "P5E_CPU0_G3_TX_DN<14>")
	)
	(arc
		(start 361.27563 -226.197922)
		(mid 361.02974 -226.664266)
		(end 361.27563 -227.13061)
		(width 0.1143)
		(layer "In4.Cu")
		(net "P5E_CPU0_G3_TX_DN<14>")
	)
	(arc
		(start 361.499404 -232.334054)
		(mid 361.576269 -232.6169)
		(end 361.783376 -232.824274)
		(width 0.1143)
		(layer "In4.Cu")
		(net "P5E_CPU0_G3_TX_DN<14>")
	)
	(arc
		(start 361.97413 -233.238548)
		(mid 362.027877 -233.439514)
		(end 362.17479 -233.586782)
		(width 0.1143)
		(layer "In4.Cu")
		(net "P5E_CPU0_G3_TX_DN<14>")
	)
	(arc
		(start 361.832652 -232.855516)
		(mid 361.936713 -232.976492)
		(end 361.97413 -233.131614)
		(width 0.1143)
		(layer "In4.Cu")
		(net "P5E_CPU0_G3_TX_DN<14>")
	)
	(arc
		(start 361.499658 -230.714296)
		(mid 361.450328 -230.900201)
		(end 361.315508 -231.037384)
		(width 0.1143)
		(layer "In4.Cu")
		(net "P5E_CPU0_G3_TX_DN<14>")
	)
	(arc
		(start 361.261406 -230.36022)
		(mid 361.269859 -230.366269)
		(end 361.278424 -230.372158)
		(width 0.1143)
		(layer "In4.Cu")
		(net "P5E_CPU0_G3_TX_DN<14>")
	)
	(arc
		(start 361.30865 -231.041448)
		(mid 361.104504 -231.245356)
		(end 361.029758 -231.524048)
		(width 0.1143)
		(layer "In4.Cu")
		(net "P5E_CPU0_G3_TX_DN<14>")
	)
	(arc
		(start 361.107228 -231.811068)
		(mid 361.195902 -231.925625)
		(end 361.310682 -232.014014)
		(width 0.1143)
		(layer "In4.Cu")
		(net "P5E_CPU0_G3_TX_DN<14>")
	)
	(arc
		(start 361.499404 -229.094284)
		(mid 361.458438 -229.26469)
		(end 361.344464 -229.397814)
		(width 0.1143)
		(layer "In4.Cu")
		(net "P5E_CPU0_G3_TX_DN<14>")
	)
	(arc
		(start 361.300776 -229.42296)
		(mid 361.0976 -229.629046)
		(end 361.029758 -229.910386)
		(width 0.1143)
		(layer "In4.Cu")
		(net "P5E_CPU0_G3_TX_DN<14>")
	)
	(segment
		(start 361.597956 -232.599992)
		(end 362.064808 -232.334054)
		(width 0.12954)
		(layer "F.Cu")
		(net "P5E_CPU0_G3_TX_DN<13>")
	)
	(segment
		(start 395.892274 -17.34185)
		(end 395.621764 -17.61236)
		(width 0.12954)
		(layer "F.Cu")
		(net "P5E_CPU0_G3_TX_DN<13>")
	)
	(segment
		(start 395.892274 -16.662146)
		(end 395.892274 -17.34185)
		(width 0.12954)
		(layer "F.Cu")
		(net "P5E_CPU0_G3_TX_DN<13>")
	)
	(segment
		(start 395.597126 -16.366998)
		(end 395.892274 -16.662146)
		(width 0.12954)
		(layer "F.Cu")
		(net "P5E_CPU0_G3_TX_DN<13>")
	)
	(segment
		(start 395.595348 -16.366998)
		(end 395.597126 -16.366998)
		(width 0.12954)
		(layer "F.Cu")
		(net "P5E_CPU0_G3_TX_DN<13>")
	)
	(segment
		(start 362.909358 -221.313756)
		(end 362.909358 -221.80423)
		(width 0.1143)
		(layer "In4.Cu")
		(net "P5E_CPU0_G3_TX_DN<13>")
	)
	(segment
		(start 362.252514 -231.036114)
		(end 362.251752 -231.036622)
		(width 0.1143)
		(layer "In4.Cu")
		(net "P5E_CPU0_G3_TX_DN<13>")
	)
	(segment
		(start 362.258356 -226.17303)
		(end 362.25734 -226.173538)
		(width 0.1143)
		(layer "In4.Cu")
		(net "P5E_CPU0_G3_TX_DN<13>")
	)
	(segment
		(start 362.251752 -227.151692)
		(end 362.283502 -227.16998)
		(width 0.1143)
		(layer "In4.Cu")
		(net "P5E_CPU0_G3_TX_DN<13>")
	)
	(segment
		(start 362.256578 -226.174046)
		(end 362.251752 -226.17684)
		(width 0.1143)
		(layer "In4.Cu")
		(net "P5E_CPU0_G3_TX_DN<13>")
	)
	(segment
		(start 363.226604 -222.916242)
		(end 363.223556 -222.918528)
		(width 0.1143)
		(layer "In4.Cu")
		(net "P5E_CPU0_G3_TX_DN<13>")
	)
	(segment
		(start 321.134232 -177.76825)
		(end 358.649778 -208.529682)
		(width 0.14224)
		(layer "In4.Cu")
		(net "P5E_CPU0_G3_TX_DN<13>")
	)
	(segment
		(start 362.26623 -227.78847)
		(end 362.26496 -227.789232)
		(width 0.1143)
		(layer "In4.Cu")
		(net "P5E_CPU0_G3_TX_DN<13>")
	)
	(segment
		(start 307.993034 -156.227272)
		(end 307.628036 -158.062676)
		(width 0.14224)
		(layer "In4.Cu")
		(net "P5E_CPU0_G3_TX_DN<13>")
	)
	(segment
		(start 322.285106 -119.574564)
		(end 316.8523 -129.452116)
		(width 0.14224)
		(layer "In4.Cu")
		(net "P5E_CPU0_G3_TX_DN<13>")
	)
	(segment
		(start 362.255562 -227.794566)
		(end 362.254292 -227.795328)
		(width 0.1143)
		(layer "In4.Cu")
		(net "P5E_CPU0_G3_TX_DN<13>")
	)
	(segment
		(start 358.649778 -208.529682)
		(end 362.868718 -215.635332)
		(width 0.14224)
		(layer "In4.Cu")
		(net "P5E_CPU0_G3_TX_DN<13>")
	)
	(segment
		(start 362.259118 -227.792534)
		(end 362.258356 -227.793042)
		(width 0.1143)
		(layer "In4.Cu")
		(net "P5E_CPU0_G3_TX_DN<13>")
	)
	(segment
		(start 362.251752 -226.17684)
		(end 362.25099 -226.177348)
		(width 0.1143)
		(layer "In4.Cu")
		(net "P5E_CPU0_G3_TX_DN<13>")
	)
	(segment
		(start 363.190282 -224.557844)
		(end 363.152944 -224.579434)
		(width 0.1143)
		(layer "In4.Cu")
		(net "P5E_CPU0_G3_TX_DN<13>")
	)
	(segment
		(start 362.251244 -230.390954)
		(end 362.252006 -230.391462)
		(width 0.1143)
		(layer "In4.Cu")
		(net "P5E_CPU0_G3_TX_DN<13>")
	)
	(segment
		(start 362.868718 -221.083124)
		(end 362.914438 -221.128844)
		(width 0.1143)
		(layer "In4.Cu")
		(net "P5E_CPU0_G3_TX_DN<13>")
	)
	(segment
		(start 362.257086 -228.774752)
		(end 362.257848 -228.77526)
		(width 0.1143)
		(layer "In4.Cu")
		(net "P5E_CPU0_G3_TX_DN<13>")
	)
	(segment
		(start 362.283502 -227.778564)
		(end 362.267246 -227.787962)
		(width 0.1143)
		(layer "In4.Cu")
		(net "P5E_CPU0_G3_TX_DN<13>")
	)
	(segment
		(start 362.263944 -227.78974)
		(end 362.263182 -227.790248)
		(width 0.1143)
		(layer "In4.Cu")
		(net "P5E_CPU0_G3_TX_DN<13>")
	)
	(segment
		(start 362.251752 -232.011474)
		(end 362.283502 -232.029762)
		(width 0.1143)
		(layer "In4.Cu")
		(net "P5E_CPU0_G3_TX_DN<13>")
	)
	(segment
		(start 362.261658 -227.79101)
		(end 362.260896 -227.791518)
		(width 0.1143)
		(layer "In4.Cu")
		(net "P5E_CPU0_G3_TX_DN<13>")
	)
	(segment
		(start 316.8523 -129.452116)
		(end 312.347864 -141.173962)
		(width 0.14224)
		(layer "In4.Cu")
		(net "P5E_CPU0_G3_TX_DN<13>")
	)
	(segment
		(start 362.25099 -227.151184)
		(end 362.251752 -227.151692)
		(width 0.1143)
		(layer "In4.Cu")
		(net "P5E_CPU0_G3_TX_DN<13>")
	)
	(segment
		(start 363.189266 -222.290132)
		(end 363.19079 -222.291148)
		(width 0.1143)
		(layer "In4.Cu")
		(net "P5E_CPU0_G3_TX_DN<13>")
	)
	(segment
		(start 362.252514 -230.392224)
		(end 362.254292 -230.39324)
		(width 0.1143)
		(layer "In4.Cu")
		(net "P5E_CPU0_G3_TX_DN<13>")
	)
	(segment
		(start 314.865258 -173.946312)
		(end 320.19748 -177.142394)
		(width 0.14224)
		(layer "In4.Cu")
		(net "P5E_CPU0_G3_TX_DN<13>")
	)
	(segment
		(start 363.192568 -224.55632)
		(end 363.190282 -224.557844)
		(width 0.1143)
		(layer "In4.Cu")
		(net "P5E_CPU0_G3_TX_DN<13>")
	)
	(segment
		(start 310.338216 -169.418)
		(end 314.865258 -173.946312)
		(width 0.14224)
		(layer "In4.Cu")
		(net "P5E_CPU0_G3_TX_DN<13>")
	)
	(segment
		(start 363.191806 -222.291656)
		(end 363.223556 -222.309944)
		(width 0.1143)
		(layer "In4.Cu")
		(net "P5E_CPU0_G3_TX_DN<13>")
	)
	(segment
		(start 362.25734 -226.173538)
		(end 362.256578 -226.174046)
		(width 0.1143)
		(layer "In4.Cu")
		(net "P5E_CPU0_G3_TX_DN<13>")
	)
	(segment
		(start 363.221778 -223.92894)
		(end 363.223556 -223.93021)
		(width 0.1143)
		(layer "In4.Cu")
		(net "P5E_CPU0_G3_TX_DN<13>")
	)
	(segment
		(start 362.256578 -230.39451)
		(end 362.25734 -230.395018)
		(width 0.1143)
		(layer "In4.Cu")
		(net "P5E_CPU0_G3_TX_DN<13>")
	)
	(segment
		(start 362.868718 -215.635332)
		(end 362.868718 -221.083124)
		(width 0.14224)
		(layer "In4.Cu")
		(net "P5E_CPU0_G3_TX_DN<13>")
	)
	(segment
		(start 307.628036 -158.062676)
		(end 307.628036 -162.874198)
		(width 0.14224)
		(layer "In4.Cu")
		(net "P5E_CPU0_G3_TX_DN<13>")
	)
	(segment
		(start 362.25353 -227.795836)
		(end 362.252514 -227.796344)
		(width 0.1143)
		(layer "In4.Cu")
		(net "P5E_CPU0_G3_TX_DN<13>")
	)
	(segment
		(start 363.223556 -222.309944)
		(end 363.226604 -222.31223)
		(width 0.1143)
		(layer "In4.Cu")
		(net "P5E_CPU0_G3_TX_DN<13>")
	)
	(segment
		(start 362.753402 -225.348292)
		(end 362.68279 -225.389694)
		(width 0.1143)
		(layer "In4.Cu")
		(net "P5E_CPU0_G3_TX_DN<13>")
	)
	(segment
		(start 362.254292 -228.773228)
		(end 362.255308 -228.773736)
		(width 0.1143)
		(layer "In4.Cu")
		(net "P5E_CPU0_G3_TX_DN<13>")
	)
	(segment
		(start 363.379512 -224.232978)
		(end 363.379512 -224.234248)
		(width 0.1143)
		(layer "In4.Cu")
		(net "P5E_CPU0_G3_TX_DN<13>")
	)
	(segment
		(start 363.19079 -222.291148)
		(end 363.191806 -222.291656)
		(width 0.1143)
		(layer "In4.Cu")
		(net "P5E_CPU0_G3_TX_DN<13>")
	)
	(segment
		(start 363.15142 -223.888046)
		(end 363.15142 -223.8883)
		(width 0.1143)
		(layer "In4.Cu")
		(net "P5E_CPU0_G3_TX_DN<13>")
	)
	(segment
		(start 362.251752 -228.771704)
		(end 362.252514 -228.772212)
		(width 0.1143)
		(layer "In4.Cu")
		(net "P5E_CPU0_G3_TX_DN<13>")
	)
	(segment
		(start 362.28528 -229.397052)
		(end 362.251752 -229.41661)
		(width 0.1143)
		(layer "In4.Cu")
		(net "P5E_CPU0_G3_TX_DN<13>")
	)
	(segment
		(start 362.258356 -230.395526)
		(end 362.283502 -230.410004)
		(width 0.1143)
		(layer "In4.Cu")
		(net "P5E_CPU0_G3_TX_DN<13>")
	)
	(segment
		(start 362.257848 -228.77526)
		(end 362.261404 -228.777038)
		(width 0.1143)
		(layer "In4.Cu")
		(net "P5E_CPU0_G3_TX_DN<13>")
	)
	(segment
		(start 363.15269 -222.268796)
		(end 363.189266 -222.290132)
		(width 0.1143)
		(layer "In4.Cu")
		(net "P5E_CPU0_G3_TX_DN<13>")
	)
	(segment
		(start 312.347864 -141.173962)
		(end 307.993034 -156.227272)
		(width 0.14224)
		(layer "In4.Cu")
		(net "P5E_CPU0_G3_TX_DN<13>")
	)
	(segment
		(start 362.914438 -221.128844)
		(end 362.914438 -221.308676)
		(width 0.1143)
		(layer "In4.Cu")
		(net "P5E_CPU0_G3_TX_DN<13>")
	)
	(segment
		(start 362.267246 -227.787962)
		(end 362.26623 -227.78847)
		(width 0.1143)
		(layer "In4.Cu")
		(net "P5E_CPU0_G3_TX_DN<13>")
	)
	(segment
		(start 362.25734 -227.79355)
		(end 362.255562 -227.794566)
		(width 0.1143)
		(layer "In4.Cu")
		(net "P5E_CPU0_G3_TX_DN<13>")
	)
	(segment
		(start 362.252514 -228.772212)
		(end 362.25353 -228.77272)
		(width 0.1143)
		(layer "In4.Cu")
		(net "P5E_CPU0_G3_TX_DN<13>")
	)
	(segment
		(start 362.252006 -230.391462)
		(end 362.251752 -230.391716)
		(width 0.1143)
		(layer "In4.Cu")
		(net "P5E_CPU0_G3_TX_DN<13>")
	)
	(segment
		(start 362.251752 -227.796852)
		(end 362.251244 -227.796852)
		(width 0.1143)
		(layer "In4.Cu")
		(net "P5E_CPU0_G3_TX_DN<13>")
	)
	(segment
		(start 363.153452 -223.88957)
		(end 363.221778 -223.92894)
		(width 0.1143)
		(layer "In4.Cu")
		(net "P5E_CPU0_G3_TX_DN<13>")
	)
	(segment
		(start 362.255308 -228.773736)
		(end 362.25607 -228.774244)
		(width 0.1143)
		(layer "In4.Cu")
		(net "P5E_CPU0_G3_TX_DN<13>")
	)
	(segment
		(start 362.261404 -228.777038)
		(end 362.283502 -228.789992)
		(width 0.1143)
		(layer "In4.Cu")
		(net "P5E_CPU0_G3_TX_DN<13>")
	)
	(segment
		(start 362.283502 -226.158552)
		(end 362.258356 -226.17303)
		(width 0.1143)
		(layer "In4.Cu")
		(net "P5E_CPU0_G3_TX_DN<13>")
	)
	(segment
		(start 395.621764 -17.61236)
		(end 395.912594 -17.90319)
		(width 0.14224)
		(layer "In4.Cu")
		(net "P5E_CPU0_G3_TX_DN<13>")
	)
	(segment
		(start 362.252514 -227.796344)
		(end 362.251752 -227.796852)
		(width 0.1143)
		(layer "In4.Cu")
		(net "P5E_CPU0_G3_TX_DN<13>")
	)
	(segment
		(start 362.26496 -227.789232)
		(end 362.263944 -227.78974)
		(width 0.1143)
		(layer "In4.Cu")
		(net "P5E_CPU0_G3_TX_DN<13>")
	)
	(segment
		(start 362.260896 -227.791518)
		(end 362.259118 -227.792534)
		(width 0.1143)
		(layer "In4.Cu")
		(net "P5E_CPU0_G3_TX_DN<13>")
	)
	(segment
		(start 307.628036 -162.874198)
		(end 310.338216 -169.418)
		(width 0.14224)
		(layer "In4.Cu")
		(net "P5E_CPU0_G3_TX_DN<13>")
	)
	(segment
		(start 363.379258 -224.230946)
		(end 363.379512 -224.232978)
		(width 0.1143)
		(layer "In4.Cu")
		(net "P5E_CPU0_G3_TX_DN<13>")
	)
	(segment
		(start 363.191806 -222.936816)
		(end 363.15142 -222.960438)
		(width 0.1143)
		(layer "In4.Cu")
		(net "P5E_CPU0_G3_TX_DN<13>")
	)
	(segment
		(start 362.25734 -230.395018)
		(end 362.258356 -230.395526)
		(width 0.1143)
		(layer "In4.Cu")
		(net "P5E_CPU0_G3_TX_DN<13>")
	)
	(segment
		(start 395.912594 -17.90319)
		(end 395.912594 -20.454112)
		(width 0.14224)
		(layer "In4.Cu")
		(net "P5E_CPU0_G3_TX_DN<13>")
	)
	(segment
		(start 362.254292 -230.39324)
		(end 362.255054 -230.393748)
		(width 0.1143)
		(layer "In4.Cu")
		(net "P5E_CPU0_G3_TX_DN<13>")
	)
	(segment
		(start 362.255054 -230.393748)
		(end 362.256578 -230.39451)
		(width 0.1143)
		(layer "In4.Cu")
		(net "P5E_CPU0_G3_TX_DN<13>")
	)
	(segment
		(start 363.195362 -224.55505)
		(end 363.192568 -224.55632)
		(width 0.1143)
		(layer "In4.Cu")
		(net "P5E_CPU0_G3_TX_DN<13>")
	)
	(segment
		(start 362.254292 -227.795328)
		(end 362.25353 -227.795836)
		(width 0.1143)
		(layer "In4.Cu")
		(net "P5E_CPU0_G3_TX_DN<13>")
	)
	(segment
		(start 363.19587 -224.554796)
		(end 363.195362 -224.55505)
		(width 0.1143)
		(layer "In4.Cu")
		(net "P5E_CPU0_G3_TX_DN<13>")
	)
	(segment
		(start 362.251752 -229.41661)
		(end 362.21543 -229.437692)
		(width 0.1143)
		(layer "In4.Cu")
		(net "P5E_CPU0_G3_TX_DN<13>")
	)
	(segment
		(start 362.263182 -227.790248)
		(end 362.261658 -227.79101)
		(width 0.1143)
		(layer "In4.Cu")
		(net "P5E_CPU0_G3_TX_DN<13>")
	)
	(segment
		(start 362.251244 -228.771704)
		(end 362.251752 -228.771704)
		(width 0.1143)
		(layer "In4.Cu")
		(net "P5E_CPU0_G3_TX_DN<13>")
	)
	(segment
		(start 362.914438 -221.308676)
		(end 362.909358 -221.313756)
		(width 0.1143)
		(layer "In4.Cu")
		(net "P5E_CPU0_G3_TX_DN<13>")
	)
	(segment
		(start 362.4326 -232.264204)
		(end 362.36275 -232.334054)
		(width 0.1143)
		(layer "In4.Cu")
		(net "P5E_CPU0_G3_TX_DN<13>")
	)
	(segment
		(start 362.36275 -232.334054)
		(end 362.064808 -232.334054)
		(width 0.1143)
		(layer "In4.Cu")
		(net "P5E_CPU0_G3_TX_DN<13>")
	)
	(segment
		(start 362.258356 -227.793042)
		(end 362.25734 -227.79355)
		(width 0.1143)
		(layer "In4.Cu")
		(net "P5E_CPU0_G3_TX_DN<13>")
	)
	(segment
		(start 362.28528 -231.017064)
		(end 362.252514 -231.036114)
		(width 0.1143)
		(layer "In4.Cu")
		(net "P5E_CPU0_G3_TX_DN<13>")
	)
	(segment
		(start 362.251752 -230.391716)
		(end 362.252514 -230.392224)
		(width 0.1143)
		(layer "In4.Cu")
		(net "P5E_CPU0_G3_TX_DN<13>")
	)
	(segment
		(start 363.152944 -224.579434)
		(end 363.143292 -224.586292)
		(width 0.1143)
		(layer "In4.Cu")
		(net "P5E_CPU0_G3_TX_DN<13>")
	)
	(segment
		(start 362.25353 -228.77272)
		(end 362.254292 -228.773228)
		(width 0.1143)
		(layer "In4.Cu")
		(net "P5E_CPU0_G3_TX_DN<13>")
	)
	(segment
		(start 363.223556 -222.918528)
		(end 363.191806 -222.936816)
		(width 0.1143)
		(layer "In4.Cu")
		(net "P5E_CPU0_G3_TX_DN<13>")
	)
	(segment
		(start 320.19748 -177.142394)
		(end 321.134232 -177.76825)
		(width 0.14224)
		(layer "In4.Cu")
		(net "P5E_CPU0_G3_TX_DN<13>")
	)
	(segment
		(start 395.912594 -20.454112)
		(end 322.285106 -119.574564)
		(width 0.14224)
		(layer "In4.Cu")
		(net "P5E_CPU0_G3_TX_DN<13>")
	)
	(segment
		(start 362.25607 -228.774244)
		(end 362.257086 -228.774752)
		(width 0.1143)
		(layer "In4.Cu")
		(net "P5E_CPU0_G3_TX_DN<13>")
	)
	(segment
		(start 362.909612 -225.042222)
		(end 362.909612 -225.044254)
		(width 0.1143)
		(layer "In4.Cu")
		(net "P5E_CPU0_G3_TX_DN<13>")
	)
	(arc
		(start 362.68279 -225.389694)
		(mid 362.503977 -225.592044)
		(end 362.439458 -225.85426)
		(width 0.1143)
		(layer "In4.Cu")
		(net "P5E_CPU0_G3_TX_DN<13>")
	)
	(arc
		(start 362.909104 -223.424242)
		(mid 362.973397 -223.685847)
		(end 363.15142 -223.888046)
		(width 0.1143)
		(layer "In4.Cu")
		(net "P5E_CPU0_G3_TX_DN<13>")
	)
	(arc
		(start 363.15142 -222.960438)
		(mid 362.973355 -223.162615)
		(end 362.909104 -223.424242)
		(width 0.1143)
		(layer "In4.Cu")
		(net "P5E_CPU0_G3_TX_DN<13>")
	)
	(arc
		(start 362.251752 -231.036622)
		(mid 361.971105 -231.524048)
		(end 362.251752 -232.011474)
		(width 0.1143)
		(layer "In4.Cu")
		(net "P5E_CPU0_G3_TX_DN<13>")
	)
	(arc
		(start 363.223556 -223.93021)
		(mid 363.334061 -224.063676)
		(end 363.379258 -224.230946)
		(width 0.1143)
		(layer "In4.Cu")
		(net "P5E_CPU0_G3_TX_DN<13>")
	)
	(arc
		(start 362.439458 -229.094284)
		(mid 362.398696 -229.264168)
		(end 362.28528 -229.397052)
		(width 0.1143)
		(layer "In4.Cu")
		(net "P5E_CPU0_G3_TX_DN<13>")
	)
	(arc
		(start 362.909612 -225.044254)
		(mid 362.868214 -225.215128)
		(end 362.753402 -225.348292)
		(width 0.1143)
		(layer "In4.Cu")
		(net "P5E_CPU0_G3_TX_DN<13>")
	)
	(arc
		(start 362.283502 -227.16998)
		(mid 362.43943 -227.474272)
		(end 362.283502 -227.778564)
		(width 0.1143)
		(layer "In4.Cu")
		(net "P5E_CPU0_G3_TX_DN<13>")
	)
	(arc
		(start 362.25099 -226.177348)
		(mid 361.970656 -226.664266)
		(end 362.25099 -227.151184)
		(width 0.1143)
		(layer "In4.Cu")
		(net "P5E_CPU0_G3_TX_DN<13>")
	)
	(arc
		(start 363.15142 -223.8883)
		(mid 363.152435 -223.888936)
		(end 363.153452 -223.88957)
		(width 0.1143)
		(layer "In4.Cu")
		(net "P5E_CPU0_G3_TX_DN<13>")
	)
	(arc
		(start 362.251244 -227.796852)
		(mid 361.970597 -228.284278)
		(end 362.251244 -228.771704)
		(width 0.1143)
		(layer "In4.Cu")
		(net "P5E_CPU0_G3_TX_DN<13>")
	)
	(arc
		(start 363.379512 -224.234248)
		(mid 363.330351 -224.418964)
		(end 363.19587 -224.554796)
		(width 0.1143)
		(layer "In4.Cu")
		(net "P5E_CPU0_G3_TX_DN<13>")
	)
	(arc
		(start 362.439458 -230.714296)
		(mid 362.398696 -230.88418)
		(end 362.28528 -231.017064)
		(width 0.1143)
		(layer "In4.Cu")
		(net "P5E_CPU0_G3_TX_DN<13>")
	)
	(arc
		(start 362.283502 -228.789992)
		(mid 362.398178 -228.923326)
		(end 362.439458 -229.094284)
		(width 0.1143)
		(layer "In4.Cu")
		(net "P5E_CPU0_G3_TX_DN<13>")
	)
	(arc
		(start 363.143292 -224.586292)
		(mid 362.971427 -224.786056)
		(end 362.909612 -225.042222)
		(width 0.1143)
		(layer "In4.Cu")
		(net "P5E_CPU0_G3_TX_DN<13>")
	)
	(arc
		(start 362.439458 -225.85426)
		(mid 362.398203 -226.025231)
		(end 362.283502 -226.158552)
		(width 0.1143)
		(layer "In4.Cu")
		(net "P5E_CPU0_G3_TX_DN<13>")
	)
	(arc
		(start 363.226604 -222.31223)
		(mid 363.381416 -222.614236)
		(end 363.226604 -222.916242)
		(width 0.1143)
		(layer "In4.Cu")
		(net "P5E_CPU0_G3_TX_DN<13>")
	)
	(arc
		(start 362.283502 -230.410004)
		(mid 362.398178 -230.543338)
		(end 362.439458 -230.714296)
		(width 0.1143)
		(layer "In4.Cu")
		(net "P5E_CPU0_G3_TX_DN<13>")
	)
	(arc
		(start 362.21543 -229.437692)
		(mid 362.034778 -229.640437)
		(end 361.969558 -229.904036)
		(width 0.1143)
		(layer "In4.Cu")
		(net "P5E_CPU0_G3_TX_DN<13>")
	)
	(arc
		(start 362.283502 -232.029762)
		(mid 362.380637 -232.132631)
		(end 362.4326 -232.264204)
		(width 0.1143)
		(layer "In4.Cu")
		(net "P5E_CPU0_G3_TX_DN<13>")
	)
	(arc
		(start 362.927392 -221.94647)
		(mid 363.011133 -222.12783)
		(end 363.15269 -222.268796)
		(width 0.1143)
		(layer "In4.Cu")
		(net "P5E_CPU0_G3_TX_DN<13>")
	)
	(arc
		(start 362.909358 -221.80423)
		(mid 362.913859 -221.875922)
		(end 362.927392 -221.94647)
		(width 0.1143)
		(layer "In4.Cu")
		(net "P5E_CPU0_G3_TX_DN<13>")
	)
	(arc
		(start 361.969558 -229.904036)
		(mid 362.04506 -230.185288)
		(end 362.251244 -230.390954)
		(width 0.1143)
		(layer "In4.Cu")
		(net "P5E_CPU0_G3_TX_DN<13>")
	)
	(segment
		(start 398.686274 -18.86585)
		(end 398.415764 -19.13636)
		(width 0.12954)
		(layer "F.Cu")
		(net "P5E_CPU0_G3_TX_DN<12>")
	)
	(segment
		(start 398.389348 -17.890998)
		(end 398.391126 -17.890998)
		(width 0.12954)
		(layer "F.Cu")
		(net "P5E_CPU0_G3_TX_DN<12>")
	)
	(segment
		(start 398.686274 -18.186146)
		(end 398.686274 -18.86585)
		(width 0.12954)
		(layer "F.Cu")
		(net "P5E_CPU0_G3_TX_DN<12>")
	)
	(segment
		(start 363.947964 -235.03001)
		(end 364.414816 -234.764072)
		(width 0.12954)
		(layer "F.Cu")
		(net "P5E_CPU0_G3_TX_DN<12>")
	)
	(segment
		(start 398.391126 -17.890998)
		(end 398.686274 -18.186146)
		(width 0.12954)
		(layer "F.Cu")
		(net "P5E_CPU0_G3_TX_DN<12>")
	)
	(segment
		(start 364.16107 -224.539556)
		(end 364.095284 -224.57791)
		(width 0.1143)
		(layer "In4.Cu")
		(net "P5E_CPU0_G3_TX_DN<12>")
	)
	(segment
		(start 363.191806 -228.771704)
		(end 363.192568 -228.772212)
		(width 0.1143)
		(layer "In4.Cu")
		(net "P5E_CPU0_G3_TX_DN<12>")
	)
	(segment
		(start 313.231784 -141.473936)
		(end 308.900576 -156.445204)
		(width 0.14224)
		(layer "In4.Cu")
		(net "P5E_CPU0_G3_TX_DN<12>")
	)
	(segment
		(start 364.14075 -222.309436)
		(end 364.20425 -222.346012)
		(width 0.1143)
		(layer "In4.Cu")
		(net "P5E_CPU0_G3_TX_DN<12>")
	)
	(segment
		(start 363.192568 -228.772212)
		(end 363.223556 -228.789992)
		(width 0.1143)
		(layer "In4.Cu")
		(net "P5E_CPU0_G3_TX_DN<12>")
	)
	(segment
		(start 363.15269 -228.748844)
		(end 363.189266 -228.77018)
		(width 0.1143)
		(layer "In4.Cu")
		(net "P5E_CPU0_G3_TX_DN<12>")
	)
	(segment
		(start 363.193584 -230.392732)
		(end 363.194346 -230.39324)
		(width 0.1143)
		(layer "In4.Cu")
		(net "P5E_CPU0_G3_TX_DN<12>")
	)
	(segment
		(start 363.195362 -227.79482)
		(end 363.192568 -227.796344)
		(width 0.1143)
		(layer "In4.Cu")
		(net "P5E_CPU0_G3_TX_DN<12>")
	)
	(segment
		(start 364.319058 -224.225866)
		(end 364.318296 -224.240852)
		(width 0.1143)
		(layer "In4.Cu")
		(net "P5E_CPU0_G3_TX_DN<12>")
	)
	(segment
		(start 311.128664 -168.889934)
		(end 315.441076 -173.203362)
		(width 0.14224)
		(layer "In4.Cu")
		(net "P5E_CPU0_G3_TX_DN<12>")
	)
	(segment
		(start 363.196124 -226.1743)
		(end 363.195362 -226.174808)
		(width 0.1143)
		(layer "In4.Cu")
		(net "P5E_CPU0_G3_TX_DN<12>")
	)
	(segment
		(start 364.092744 -233.608626)
		(end 364.12932 -233.629962)
		(width 0.1143)
		(layer "In4.Cu")
		(net "P5E_CPU0_G3_TX_DN<12>")
	)
	(segment
		(start 315.441076 -173.203362)
		(end 320.688208 -176.348644)
		(width 0.14224)
		(layer "In4.Cu")
		(net "P5E_CPU0_G3_TX_DN<12>")
	)
	(segment
		(start 363.184694 -227.800916)
		(end 363.15269 -227.819712)
		(width 0.1143)
		(layer "In4.Cu")
		(net "P5E_CPU0_G3_TX_DN<12>")
	)
	(segment
		(start 398.706594 -19.42719)
		(end 398.706594 -20.343368)
		(width 0.14224)
		(layer "In4.Cu")
		(net "P5E_CPU0_G3_TX_DN<12>")
	)
	(segment
		(start 363.204506 -230.399082)
		(end 363.205268 -230.39959)
		(width 0.1143)
		(layer "In4.Cu")
		(net "P5E_CPU0_G3_TX_DN<12>")
	)
	(segment
		(start 363.192568 -227.796344)
		(end 363.191806 -227.796852)
		(width 0.1143)
		(layer "In4.Cu")
		(net "P5E_CPU0_G3_TX_DN<12>")
	)
	(segment
		(start 363.189266 -228.77018)
		(end 363.19079 -228.771196)
		(width 0.1143)
		(layer "In4.Cu")
		(net "P5E_CPU0_G3_TX_DN<12>")
	)
	(segment
		(start 363.191806 -227.796852)
		(end 363.19079 -227.79736)
		(width 0.1143)
		(layer "In4.Cu")
		(net "P5E_CPU0_G3_TX_DN<12>")
	)
	(segment
		(start 359.35412 -207.887062)
		(end 361.583732 -211.641944)
		(width 0.14224)
		(layer "In4.Cu")
		(net "P5E_CPU0_G3_TX_DN<12>")
	)
	(segment
		(start 363.19841 -226.17303)
		(end 363.197648 -226.173538)
		(width 0.1143)
		(layer "In4.Cu")
		(net "P5E_CPU0_G3_TX_DN<12>")
	)
	(segment
		(start 363.19079 -226.177348)
		(end 363.189266 -226.178364)
		(width 0.1143)
		(layer "In4.Cu")
		(net "P5E_CPU0_G3_TX_DN<12>")
	)
	(segment
		(start 363.202728 -230.398066)
		(end 363.204506 -230.399082)
		(width 0.1143)
		(layer "In4.Cu")
		(net "P5E_CPU0_G3_TX_DN<12>")
	)
	(segment
		(start 363.191806 -227.151692)
		(end 363.192568 -227.1522)
		(width 0.1143)
		(layer "In4.Cu")
		(net "P5E_CPU0_G3_TX_DN<12>")
	)
	(segment
		(start 363.191806 -226.17684)
		(end 363.19079 -226.177348)
		(width 0.1143)
		(layer "In4.Cu")
		(net "P5E_CPU0_G3_TX_DN<12>")
	)
	(segment
		(start 308.560216 -162.688016)
		(end 311.128664 -168.889934)
		(width 0.14224)
		(layer "In4.Cu")
		(net "P5E_CPU0_G3_TX_DN<12>")
	)
	(segment
		(start 363.205268 -230.39959)
		(end 363.206538 -230.400098)
		(width 0.1143)
		(layer "In4.Cu")
		(net "P5E_CPU0_G3_TX_DN<12>")
	)
	(segment
		(start 308.900576 -156.445204)
		(end 308.560216 -158.156402)
		(width 0.14224)
		(layer "In4.Cu")
		(net "P5E_CPU0_G3_TX_DN<12>")
	)
	(segment
		(start 364.131606 -223.911668)
		(end 364.163356 -223.929956)
		(width 0.1143)
		(layer "In4.Cu")
		(net "P5E_CPU0_G3_TX_DN<12>")
	)
	(segment
		(start 363.19968 -226.172268)
		(end 363.19841 -226.17303)
		(width 0.1143)
		(layer "In4.Cu")
		(net "P5E_CPU0_G3_TX_DN<12>")
	)
	(segment
		(start 363.813344 -221.083124)
		(end 363.859064 -221.128844)
		(width 0.1143)
		(layer "In4.Cu")
		(net "P5E_CPU0_G3_TX_DN<12>")
	)
	(segment
		(start 363.189266 -230.390192)
		(end 363.19079 -230.391208)
		(width 0.1143)
		(layer "In4.Cu")
		(net "P5E_CPU0_G3_TX_DN<12>")
	)
	(segment
		(start 364.712758 -234.764072)
		(end 364.414816 -234.764072)
		(width 0.1143)
		(layer "In4.Cu")
		(net "P5E_CPU0_G3_TX_DN<12>")
	)
	(segment
		(start 364.12932 -233.629962)
		(end 364.130844 -233.630978)
		(width 0.1143)
		(layer "In4.Cu")
		(net "P5E_CPU0_G3_TX_DN<12>")
	)
	(segment
		(start 363.18825 -230.389684)
		(end 363.189266 -230.390192)
		(width 0.1143)
		(layer "In4.Cu")
		(net "P5E_CPU0_G3_TX_DN<12>")
	)
	(segment
		(start 364.565438 -234.42041)
		(end 364.575598 -234.425998)
		(width 0.1143)
		(layer "In4.Cu")
		(net "P5E_CPU0_G3_TX_DN<12>")
	)
	(segment
		(start 363.189266 -227.150168)
		(end 363.19079 -227.151184)
		(width 0.1143)
		(layer "In4.Cu")
		(net "P5E_CPU0_G3_TX_DN<12>")
	)
	(segment
		(start 364.093506 -223.88957)
		(end 364.128304 -223.909636)
		(width 0.1143)
		(layer "In4.Cu")
		(net "P5E_CPU0_G3_TX_DN<12>")
	)
	(segment
		(start 363.15269 -227.128832)
		(end 363.189266 -227.150168)
		(width 0.1143)
		(layer "In4.Cu")
		(net "P5E_CPU0_G3_TX_DN<12>")
	)
	(segment
		(start 363.192568 -227.1522)
		(end 363.223556 -227.16998)
		(width 0.1143)
		(layer "In4.Cu")
		(net "P5E_CPU0_G3_TX_DN<12>")
	)
	(segment
		(start 363.206538 -230.400098)
		(end 363.22254 -230.409496)
		(width 0.1143)
		(layer "In4.Cu")
		(net "P5E_CPU0_G3_TX_DN<12>")
	)
	(segment
		(start 363.196124 -227.794312)
		(end 363.195362 -227.79482)
		(width 0.1143)
		(layer "In4.Cu")
		(net "P5E_CPU0_G3_TX_DN<12>")
	)
	(segment
		(start 363.19079 -227.151184)
		(end 363.191806 -227.151692)
		(width 0.1143)
		(layer "In4.Cu")
		(net "P5E_CPU0_G3_TX_DN<12>")
	)
	(segment
		(start 398.706594 -20.343368)
		(end 322.599812 -121.025666)
		(width 0.14224)
		(layer "In4.Cu")
		(net "P5E_CPU0_G3_TX_DN<12>")
	)
	(segment
		(start 364.128304 -223.909636)
		(end 364.13059 -223.91116)
		(width 0.1143)
		(layer "In4.Cu")
		(net "P5E_CPU0_G3_TX_DN<12>")
	)
	(segment
		(start 317.701168 -129.843784)
		(end 313.231784 -141.473936)
		(width 0.14224)
		(layer "In4.Cu")
		(net "P5E_CPU0_G3_TX_DN<12>")
	)
	(segment
		(start 363.223556 -227.778564)
		(end 363.20222 -227.79101)
		(width 0.1143)
		(layer "In4.Cu")
		(net "P5E_CPU0_G3_TX_DN<12>")
	)
	(segment
		(start 363.15523 -230.37038)
		(end 363.159802 -230.373174)
		(width 0.1143)
		(layer "In4.Cu")
		(net "P5E_CPU0_G3_TX_DN<12>")
	)
	(segment
		(start 363.69244 -225.349054)
		(end 363.622844 -225.389694)
		(width 0.1143)
		(layer "In4.Cu")
		(net "P5E_CPU0_G3_TX_DN<12>")
	)
	(segment
		(start 363.813344 -215.39708)
		(end 363.813344 -221.054676)
		(width 0.14224)
		(layer "In4.Cu")
		(net "P5E_CPU0_G3_TX_DN<12>")
	)
	(segment
		(start 363.195362 -226.174808)
		(end 363.192568 -226.176332)
		(width 0.1143)
		(layer "In4.Cu")
		(net "P5E_CPU0_G3_TX_DN<12>")
	)
	(segment
		(start 364.16361 -222.918528)
		(end 364.16361 -222.918274)
		(width 0.1143)
		(layer "In4.Cu")
		(net "P5E_CPU0_G3_TX_DN<12>")
	)
	(segment
		(start 320.688208 -176.348644)
		(end 321.696588 -177.022506)
		(width 0.14224)
		(layer "In4.Cu")
		(net "P5E_CPU0_G3_TX_DN<12>")
	)
	(segment
		(start 363.191806 -232.011474)
		(end 363.192568 -232.011982)
		(width 0.1143)
		(layer "In4.Cu")
		(net "P5E_CPU0_G3_TX_DN<12>")
	)
	(segment
		(start 361.583732 -211.641944)
		(end 363.813344 -215.39708)
		(width 0.14224)
		(layer "In4.Cu")
		(net "P5E_CPU0_G3_TX_DN<12>")
	)
	(segment
		(start 321.696588 -177.022506)
		(end 359.35412 -207.887062)
		(width 0.14224)
		(layer "In4.Cu")
		(net "P5E_CPU0_G3_TX_DN<12>")
	)
	(segment
		(start 364.091982 -222.95993)
		(end 364.064296 -222.979742)
		(width 0.1143)
		(layer "In4.Cu")
		(net "P5E_CPU0_G3_TX_DN<12>")
	)
	(segment
		(start 363.192568 -226.176332)
		(end 363.191806 -226.17684)
		(width 0.1143)
		(layer "In4.Cu")
		(net "P5E_CPU0_G3_TX_DN<12>")
	)
	(segment
		(start 363.200188 -230.396542)
		(end 363.202728 -230.398066)
		(width 0.1143)
		(layer "In4.Cu")
		(net "P5E_CPU0_G3_TX_DN<12>")
	)
	(segment
		(start 363.859064 -221.308676)
		(end 363.849666 -221.318074)
		(width 0.1143)
		(layer "In4.Cu")
		(net "P5E_CPU0_G3_TX_DN<12>")
	)
	(segment
		(start 363.19968 -227.79228)
		(end 363.19841 -227.793042)
		(width 0.1143)
		(layer "In4.Cu")
		(net "P5E_CPU0_G3_TX_DN<12>")
	)
	(segment
		(start 364.162848 -222.918782)
		(end 364.091982 -222.95993)
		(width 0.1143)
		(layer "In4.Cu")
		(net "P5E_CPU0_G3_TX_DN<12>")
	)
	(segment
		(start 363.192568 -232.011982)
		(end 363.223556 -232.029762)
		(width 0.1143)
		(layer "In4.Cu")
		(net "P5E_CPU0_G3_TX_DN<12>")
	)
	(segment
		(start 363.197648 -226.173538)
		(end 363.196124 -226.1743)
		(width 0.1143)
		(layer "In4.Cu")
		(net "P5E_CPU0_G3_TX_DN<12>")
	)
	(segment
		(start 363.223556 -226.158552)
		(end 363.20222 -226.170998)
		(width 0.1143)
		(layer "In4.Cu")
		(net "P5E_CPU0_G3_TX_DN<12>")
	)
	(segment
		(start 364.16361 -222.918274)
		(end 364.162848 -222.918782)
		(width 0.1143)
		(layer "In4.Cu")
		(net "P5E_CPU0_G3_TX_DN<12>")
	)
	(segment
		(start 363.225334 -231.017064)
		(end 363.15269 -231.059482)
		(width 0.1143)
		(layer "In4.Cu")
		(net "P5E_CPU0_G3_TX_DN<12>")
	)
	(segment
		(start 363.813344 -221.054676)
		(end 363.813344 -221.083124)
		(width 0.1143)
		(layer "In4.Cu")
		(net "P5E_CPU0_G3_TX_DN<12>")
	)
	(segment
		(start 363.19079 -227.79736)
		(end 363.189266 -227.798376)
		(width 0.1143)
		(layer "In4.Cu")
		(net "P5E_CPU0_G3_TX_DN<12>")
	)
	(segment
		(start 363.859064 -221.128844)
		(end 363.859064 -221.308676)
		(width 0.1143)
		(layer "In4.Cu")
		(net "P5E_CPU0_G3_TX_DN<12>")
	)
	(segment
		(start 364.064296 -223.868742)
		(end 364.093506 -223.88957)
		(width 0.1143)
		(layer "In4.Cu")
		(net "P5E_CPU0_G3_TX_DN<12>")
	)
	(segment
		(start 363.19079 -230.391208)
		(end 363.191806 -230.391716)
		(width 0.1143)
		(layer "In4.Cu")
		(net "P5E_CPU0_G3_TX_DN<12>")
	)
	(segment
		(start 363.189266 -227.798376)
		(end 363.184694 -227.800916)
		(width 0.1143)
		(layer "In4.Cu")
		(net "P5E_CPU0_G3_TX_DN<12>")
	)
	(segment
		(start 363.159802 -230.373174)
		(end 363.18825 -230.389684)
		(width 0.1143)
		(layer "In4.Cu")
		(net "P5E_CPU0_G3_TX_DN<12>")
	)
	(segment
		(start 363.20222 -226.170998)
		(end 363.19968 -226.172268)
		(width 0.1143)
		(layer "In4.Cu")
		(net "P5E_CPU0_G3_TX_DN<12>")
	)
	(segment
		(start 322.599812 -121.025666)
		(end 317.701168 -129.843784)
		(width 0.14224)
		(layer "In4.Cu")
		(net "P5E_CPU0_G3_TX_DN<12>")
	)
	(segment
		(start 364.782608 -234.694222)
		(end 364.712758 -234.764072)
		(width 0.1143)
		(layer "In4.Cu")
		(net "P5E_CPU0_G3_TX_DN<12>")
	)
	(segment
		(start 363.225334 -229.397052)
		(end 363.15269 -229.43947)
		(width 0.1143)
		(layer "In4.Cu")
		(net "P5E_CPU0_G3_TX_DN<12>")
	)
	(segment
		(start 364.13186 -233.631486)
		(end 364.132622 -233.631994)
		(width 0.1143)
		(layer "In4.Cu")
		(net "P5E_CPU0_G3_TX_DN<12>")
	)
	(segment
		(start 363.19079 -232.010966)
		(end 363.191806 -232.011474)
		(width 0.1143)
		(layer "In4.Cu")
		(net "P5E_CPU0_G3_TX_DN<12>")
	)
	(segment
		(start 364.575598 -234.425998)
		(end 364.63351 -234.45978)
		(width 0.1143)
		(layer "In4.Cu")
		(net "P5E_CPU0_G3_TX_DN<12>")
	)
	(segment
		(start 363.19841 -227.793042)
		(end 363.197648 -227.79355)
		(width 0.1143)
		(layer "In4.Cu")
		(net "P5E_CPU0_G3_TX_DN<12>")
	)
	(segment
		(start 363.20222 -227.79101)
		(end 363.19968 -227.79228)
		(width 0.1143)
		(layer "In4.Cu")
		(net "P5E_CPU0_G3_TX_DN<12>")
	)
	(segment
		(start 363.19079 -228.771196)
		(end 363.191806 -228.771704)
		(width 0.1143)
		(layer "In4.Cu")
		(net "P5E_CPU0_G3_TX_DN<12>")
	)
	(segment
		(start 363.191806 -230.391716)
		(end 363.193584 -230.392732)
		(width 0.1143)
		(layer "In4.Cu")
		(net "P5E_CPU0_G3_TX_DN<12>")
	)
	(segment
		(start 363.197648 -230.395272)
		(end 363.200188 -230.396542)
		(width 0.1143)
		(layer "In4.Cu")
		(net "P5E_CPU0_G3_TX_DN<12>")
	)
	(segment
		(start 398.415764 -19.13636)
		(end 398.706594 -19.42719)
		(width 0.14224)
		(layer "In4.Cu")
		(net "P5E_CPU0_G3_TX_DN<12>")
	)
	(segment
		(start 363.15269 -231.988614)
		(end 363.189266 -232.00995)
		(width 0.1143)
		(layer "In4.Cu")
		(net "P5E_CPU0_G3_TX_DN<12>")
	)
	(segment
		(start 308.560216 -158.156402)
		(end 308.560216 -162.688016)
		(width 0.14224)
		(layer "In4.Cu")
		(net "P5E_CPU0_G3_TX_DN<12>")
	)
	(segment
		(start 363.189266 -232.00995)
		(end 363.19079 -232.010966)
		(width 0.1143)
		(layer "In4.Cu")
		(net "P5E_CPU0_G3_TX_DN<12>")
	)
	(segment
		(start 363.849666 -221.318074)
		(end 363.849666 -221.80423)
		(width 0.1143)
		(layer "In4.Cu")
		(net "P5E_CPU0_G3_TX_DN<12>")
	)
	(segment
		(start 363.184694 -226.180904)
		(end 363.15269 -226.1997)
		(width 0.1143)
		(layer "In4.Cu")
		(net "P5E_CPU0_G3_TX_DN<12>")
	)
	(segment
		(start 364.130844 -233.630978)
		(end 364.13186 -233.631486)
		(width 0.1143)
		(layer "In4.Cu")
		(net "P5E_CPU0_G3_TX_DN<12>")
	)
	(segment
		(start 363.22254 -230.409496)
		(end 363.223556 -230.410004)
		(width 0.1143)
		(layer "In4.Cu")
		(net "P5E_CPU0_G3_TX_DN<12>")
	)
	(segment
		(start 363.622844 -232.79862)
		(end 363.69244 -232.83926)
		(width 0.1143)
		(layer "In4.Cu")
		(net "P5E_CPU0_G3_TX_DN<12>")
	)
	(segment
		(start 363.189266 -226.178364)
		(end 363.184694 -226.180904)
		(width 0.1143)
		(layer "In4.Cu")
		(net "P5E_CPU0_G3_TX_DN<12>")
	)
	(segment
		(start 364.13059 -223.91116)
		(end 364.131606 -223.911668)
		(width 0.1143)
		(layer "In4.Cu")
		(net "P5E_CPU0_G3_TX_DN<12>")
	)
	(segment
		(start 363.197648 -227.79355)
		(end 363.196124 -227.794312)
		(width 0.1143)
		(layer "In4.Cu")
		(net "P5E_CPU0_G3_TX_DN<12>")
	)
	(segment
		(start 363.194346 -230.39324)
		(end 363.197648 -230.395272)
		(width 0.1143)
		(layer "In4.Cu")
		(net "P5E_CPU0_G3_TX_DN<12>")
	)
	(arc
		(start 363.15269 -226.1997)
		(mid 362.909363 -226.664266)
		(end 363.15269 -227.128832)
		(width 0.1143)
		(layer "In4.Cu")
		(net "P5E_CPU0_G3_TX_DN<12>")
	)
	(arc
		(start 363.379512 -225.85426)
		(mid 363.338257 -226.025231)
		(end 363.223556 -226.158552)
		(width 0.1143)
		(layer "In4.Cu")
		(net "P5E_CPU0_G3_TX_DN<12>")
	)
	(arc
		(start 363.379512 -230.714296)
		(mid 363.33875 -230.88418)
		(end 363.225334 -231.017064)
		(width 0.1143)
		(layer "In4.Cu")
		(net "P5E_CPU0_G3_TX_DN<12>")
	)
	(arc
		(start 363.223556 -232.029762)
		(mid 363.338232 -232.163096)
		(end 363.379512 -232.334054)
		(width 0.1143)
		(layer "In4.Cu")
		(net "P5E_CPU0_G3_TX_DN<12>")
	)
	(arc
		(start 363.379512 -229.094284)
		(mid 363.33875 -229.264168)
		(end 363.225334 -229.397052)
		(width 0.1143)
		(layer "In4.Cu")
		(net "P5E_CPU0_G3_TX_DN<12>")
	)
	(arc
		(start 364.132622 -233.631994)
		(mid 364.265248 -233.774265)
		(end 364.31982 -233.960924)
		(width 0.1143)
		(layer "In4.Cu")
		(net "P5E_CPU0_G3_TX_DN<12>")
	)
	(arc
		(start 363.223556 -230.410004)
		(mid 363.338232 -230.543338)
		(end 363.379512 -230.714296)
		(width 0.1143)
		(layer "In4.Cu")
		(net "P5E_CPU0_G3_TX_DN<12>")
	)
	(arc
		(start 363.223556 -227.16998)
		(mid 363.379484 -227.474272)
		(end 363.223556 -227.778564)
		(width 0.1143)
		(layer "In4.Cu")
		(net "P5E_CPU0_G3_TX_DN<12>")
	)
	(arc
		(start 364.095284 -224.57791)
		(mid 363.914632 -224.780655)
		(end 363.849412 -225.044254)
		(width 0.1143)
		(layer "In4.Cu")
		(net "P5E_CPU0_G3_TX_DN<12>")
	)
	(arc
		(start 363.15269 -229.43947)
		(mid 362.973877 -229.64182)
		(end 362.909358 -229.904036)
		(width 0.1143)
		(layer "In4.Cu")
		(net "P5E_CPU0_G3_TX_DN<12>")
	)
	(arc
		(start 363.849666 -221.80423)
		(mid 363.92757 -222.095817)
		(end 364.14075 -222.309436)
		(width 0.1143)
		(layer "In4.Cu")
		(net "P5E_CPU0_G3_TX_DN<12>")
	)
	(arc
		(start 363.15269 -231.059482)
		(mid 362.909363 -231.524048)
		(end 363.15269 -231.988614)
		(width 0.1143)
		(layer "In4.Cu")
		(net "P5E_CPU0_G3_TX_DN<12>")
	)
	(arc
		(start 364.16869 -224.53346)
		(mid 364.1649 -224.536532)
		(end 364.16107 -224.539556)
		(width 0.1143)
		(layer "In4.Cu")
		(net "P5E_CPU0_G3_TX_DN<12>")
	)
	(arc
		(start 363.223556 -228.789992)
		(mid 363.338232 -228.923326)
		(end 363.379512 -229.094284)
		(width 0.1143)
		(layer "In4.Cu")
		(net "P5E_CPU0_G3_TX_DN<12>")
	)
	(arc
		(start 363.15269 -227.819712)
		(mid 362.909363 -228.284278)
		(end 363.15269 -228.748844)
		(width 0.1143)
		(layer "In4.Cu")
		(net "P5E_CPU0_G3_TX_DN<12>")
	)
	(arc
		(start 364.064296 -222.979742)
		(mid 363.836608 -223.424242)
		(end 364.064296 -223.868742)
		(width 0.1143)
		(layer "In4.Cu")
		(net "P5E_CPU0_G3_TX_DN<12>")
	)
	(arc
		(start 363.379512 -232.334054)
		(mid 363.444027 -232.596273)
		(end 363.622844 -232.79862)
		(width 0.1143)
		(layer "In4.Cu")
		(net "P5E_CPU0_G3_TX_DN<12>")
	)
	(arc
		(start 363.849412 -225.044254)
		(mid 363.807863 -225.215676)
		(end 363.69244 -225.349054)
		(width 0.1143)
		(layer "In4.Cu")
		(net "P5E_CPU0_G3_TX_DN<12>")
	)
	(arc
		(start 364.318296 -224.240852)
		(mid 364.267781 -224.399578)
		(end 364.16869 -224.53346)
		(width 0.1143)
		(layer "In4.Cu")
		(net "P5E_CPU0_G3_TX_DN<12>")
	)
	(arc
		(start 364.63351 -234.45978)
		(mid 364.730645 -234.562649)
		(end 364.782608 -234.694222)
		(width 0.1143)
		(layer "In4.Cu")
		(net "P5E_CPU0_G3_TX_DN<12>")
	)
	(arc
		(start 364.31982 -233.960924)
		(mid 364.391481 -234.218021)
		(end 364.565438 -234.42041)
		(width 0.1143)
		(layer "In4.Cu")
		(net "P5E_CPU0_G3_TX_DN<12>")
	)
	(arc
		(start 362.909358 -229.904036)
		(mid 362.974594 -230.167627)
		(end 363.15523 -230.37038)
		(width 0.1143)
		(layer "In4.Cu")
		(net "P5E_CPU0_G3_TX_DN<12>")
	)
	(arc
		(start 363.622844 -225.389694)
		(mid 363.444031 -225.592044)
		(end 363.379512 -225.85426)
		(width 0.1143)
		(layer "In4.Cu")
		(net "P5E_CPU0_G3_TX_DN<12>")
	)
	(arc
		(start 364.163356 -223.929956)
		(mid 364.27601 -224.059589)
		(end 364.319058 -224.225866)
		(width 0.1143)
		(layer "In4.Cu")
		(net "P5E_CPU0_G3_TX_DN<12>")
	)
	(arc
		(start 363.849412 -233.14406)
		(mid 363.913927 -233.406279)
		(end 364.092744 -233.608626)
		(width 0.1143)
		(layer "In4.Cu")
		(net "P5E_CPU0_G3_TX_DN<12>")
	)
	(arc
		(start 363.69244 -232.83926)
		(mid 363.807867 -232.972636)
		(end 363.849412 -233.14406)
		(width 0.1143)
		(layer "In4.Cu")
		(net "P5E_CPU0_G3_TX_DN<12>")
	)
	(arc
		(start 364.20425 -222.346012)
		(mid 364.312844 -222.641401)
		(end 364.16361 -222.918528)
		(width 0.1143)
		(layer "In4.Cu")
		(net "P5E_CPU0_G3_TX_DN<12>")
	)
	(segment
		(start 401.183348 -16.366998)
		(end 401.185126 -16.366998)
		(width 0.12954)
		(layer "F.Cu")
		(net "P5E_CPU0_G3_TX_DN<11>")
	)
	(segment
		(start 363.947964 -231.789986)
		(end 364.414816 -231.524048)
		(width 0.12954)
		(layer "F.Cu")
		(net "P5E_CPU0_G3_TX_DN<11>")
	)
	(segment
		(start 401.480274 -17.34185)
		(end 401.209764 -17.61236)
		(width 0.12954)
		(layer "F.Cu")
		(net "P5E_CPU0_G3_TX_DN<11>")
	)
	(segment
		(start 401.480274 -16.662146)
		(end 401.480274 -17.34185)
		(width 0.12954)
		(layer "F.Cu")
		(net "P5E_CPU0_G3_TX_DN<11>")
	)
	(segment
		(start 401.185126 -16.366998)
		(end 401.480274 -16.662146)
		(width 0.12954)
		(layer "F.Cu")
		(net "P5E_CPU0_G3_TX_DN<11>")
	)
	(segment
		(start 364.092744 -228.748844)
		(end 364.16234 -228.789484)
		(width 0.1143)
		(layer "In4.Cu")
		(net "P5E_CPU0_G3_TX_DN<11>")
	)
	(segment
		(start 322.932806 -122.431302)
		(end 318.548004 -130.239516)
		(width 0.14224)
		(layer "In4.Cu")
		(net "P5E_CPU0_G3_TX_DN<11>")
	)
	(segment
		(start 365.25962 -222.614236)
		(end 365.259366 -222.614236)
		(width 0.1143)
		(layer "In4.Cu")
		(net "P5E_CPU0_G3_TX_DN<11>")
	)
	(segment
		(start 365.065818 -222.2881)
		(end 365.068358 -222.289624)
		(width 0.1143)
		(layer "In4.Cu")
		(net "P5E_CPU0_G3_TX_DN<11>")
	)
	(segment
		(start 364.164372 -229.397814)
		(end 364.13186 -229.41661)
		(width 0.1143)
		(layer "In4.Cu")
		(net "P5E_CPU0_G3_TX_DN<11>")
	)
	(segment
		(start 364.782608 -231.454198)
		(end 364.712758 -231.524048)
		(width 0.1143)
		(layer "In4.Cu")
		(net "P5E_CPU0_G3_TX_DN<11>")
	)
	(segment
		(start 311.819798 -168.122092)
		(end 316.368938 -172.672502)
		(width 0.14224)
		(layer "In4.Cu")
		(net "P5E_CPU0_G3_TX_DN<11>")
	)
	(segment
		(start 401.500594 -20.451572)
		(end 322.932806 -122.431302)
		(width 0.14224)
		(layer "In4.Cu")
		(net "P5E_CPU0_G3_TX_DN<11>")
	)
	(segment
		(start 401.500594 -17.90319)
		(end 401.500594 -20.451572)
		(width 0.14224)
		(layer "In4.Cu")
		(net "P5E_CPU0_G3_TX_DN<11>")
	)
	(segment
		(start 364.63351 -225.348546)
		(end 364.603792 -225.365564)
		(width 0.1143)
		(layer "In4.Cu")
		(net "P5E_CPU0_G3_TX_DN<11>")
	)
	(segment
		(start 364.092744 -227.128832)
		(end 364.16234 -227.169472)
		(width 0.1143)
		(layer "In4.Cu")
		(net "P5E_CPU0_G3_TX_DN<11>")
	)
	(segment
		(start 364.75797 -215.161622)
		(end 364.75797 -221.054676)
		(width 0.14224)
		(layer "In4.Cu")
		(net "P5E_CPU0_G3_TX_DN<11>")
	)
	(segment
		(start 365.070898 -222.291148)
		(end 365.071914 -222.291656)
		(width 0.1143)
		(layer "In4.Cu")
		(net "P5E_CPU0_G3_TX_DN<11>")
	)
	(segment
		(start 364.095284 -230.37038)
		(end 364.16234 -230.409496)
		(width 0.1143)
		(layer "In4.Cu")
		(net "P5E_CPU0_G3_TX_DN<11>")
	)
	(segment
		(start 364.60176 -225.366834)
		(end 364.570264 -225.385122)
		(width 0.1143)
		(layer "In4.Cu")
		(net "P5E_CPU0_G3_TX_DN<11>")
	)
	(segment
		(start 364.712758 -231.524048)
		(end 364.414816 -231.524048)
		(width 0.1143)
		(layer "In4.Cu")
		(net "P5E_CPU0_G3_TX_DN<11>")
	)
	(segment
		(start 365.102394 -224.539048)
		(end 365.032798 -224.579688)
		(width 0.1143)
		(layer "In4.Cu")
		(net "P5E_CPU0_G3_TX_DN<11>")
	)
	(segment
		(start 364.80369 -221.128844)
		(end 364.80369 -221.308676)
		(width 0.1143)
		(layer "In4.Cu")
		(net "P5E_CPU0_G3_TX_DN<11>")
	)
	(segment
		(start 309.808118 -156.66339)
		(end 309.59171 -157.751272)
		(width 0.14224)
		(layer "In4.Cu")
		(net "P5E_CPU0_G3_TX_DN<11>")
	)
	(segment
		(start 365.102394 -222.919036)
		(end 365.032798 -222.959676)
		(width 0.1143)
		(layer "In4.Cu")
		(net "P5E_CPU0_G3_TX_DN<11>")
	)
	(segment
		(start 318.548004 -130.239516)
		(end 314.114688 -141.777212)
		(width 0.14224)
		(layer "In4.Cu")
		(net "P5E_CPU0_G3_TX_DN<11>")
	)
	(segment
		(start 401.209764 -17.61236)
		(end 401.500594 -17.90319)
		(width 0.14224)
		(layer "In4.Cu")
		(net "P5E_CPU0_G3_TX_DN<11>")
	)
	(segment
		(start 364.75797 -221.083124)
		(end 364.80369 -221.128844)
		(width 0.1143)
		(layer "In4.Cu")
		(net "P5E_CPU0_G3_TX_DN<11>")
	)
	(segment
		(start 316.368938 -172.672502)
		(end 321.917822 -175.997108)
		(width 0.14224)
		(layer "In4.Cu")
		(net "P5E_CPU0_G3_TX_DN<11>")
	)
	(segment
		(start 364.789466 -221.3229)
		(end 364.789466 -221.80423)
		(width 0.1143)
		(layer "In4.Cu")
		(net "P5E_CPU0_G3_TX_DN<11>")
	)
	(segment
		(start 364.13186 -229.41661)
		(end 364.092744 -229.43947)
		(width 0.1143)
		(layer "In4.Cu")
		(net "P5E_CPU0_G3_TX_DN<11>")
	)
	(segment
		(start 365.032798 -222.268796)
		(end 365.064294 -222.287084)
		(width 0.1143)
		(layer "In4.Cu")
		(net "P5E_CPU0_G3_TX_DN<11>")
	)
	(segment
		(start 364.562644 -231.178862)
		(end 364.635288 -231.22128)
		(width 0.1143)
		(layer "In4.Cu")
		(net "P5E_CPU0_G3_TX_DN<11>")
	)
	(segment
		(start 364.75797 -221.054676)
		(end 364.75797 -221.083124)
		(width 0.1143)
		(layer "In4.Cu")
		(net "P5E_CPU0_G3_TX_DN<11>")
	)
	(segment
		(start 364.80369 -221.308676)
		(end 364.789466 -221.3229)
		(width 0.1143)
		(layer "In4.Cu")
		(net "P5E_CPU0_G3_TX_DN<11>")
	)
	(segment
		(start 365.071914 -222.291656)
		(end 365.103664 -222.309944)
		(width 0.1143)
		(layer "In4.Cu")
		(net "P5E_CPU0_G3_TX_DN<11>")
	)
	(segment
		(start 309.59171 -157.751272)
		(end 309.59171 -162.742118)
		(width 0.14224)
		(layer "In4.Cu")
		(net "P5E_CPU0_G3_TX_DN<11>")
	)
	(segment
		(start 364.16234 -227.779072)
		(end 364.092744 -227.819712)
		(width 0.1143)
		(layer "In4.Cu")
		(net "P5E_CPU0_G3_TX_DN<11>")
	)
	(segment
		(start 364.602522 -225.366326)
		(end 364.60176 -225.366834)
		(width 0.1143)
		(layer "In4.Cu")
		(net "P5E_CPU0_G3_TX_DN<11>")
	)
	(segment
		(start 309.59171 -162.742118)
		(end 311.819798 -168.122092)
		(width 0.14224)
		(layer "In4.Cu")
		(net "P5E_CPU0_G3_TX_DN<11>")
	)
	(segment
		(start 360.06532 -207.258666)
		(end 364.75797 -215.161622)
		(width 0.14224)
		(layer "In4.Cu")
		(net "P5E_CPU0_G3_TX_DN<11>")
	)
	(segment
		(start 365.032798 -223.888808)
		(end 365.102394 -223.929448)
		(width 0.1143)
		(layer "In4.Cu")
		(net "P5E_CPU0_G3_TX_DN<11>")
	)
	(segment
		(start 365.069374 -222.290132)
		(end 365.070898 -222.291148)
		(width 0.1143)
		(layer "In4.Cu")
		(net "P5E_CPU0_G3_TX_DN<11>")
	)
	(segment
		(start 365.068358 -222.289624)
		(end 365.069374 -222.290132)
		(width 0.1143)
		(layer "In4.Cu")
		(net "P5E_CPU0_G3_TX_DN<11>")
	)
	(segment
		(start 364.569502 -225.38563)
		(end 364.562644 -225.389694)
		(width 0.1143)
		(layer "In4.Cu")
		(net "P5E_CPU0_G3_TX_DN<11>")
	)
	(segment
		(start 364.570264 -225.385122)
		(end 364.569502 -225.38563)
		(width 0.1143)
		(layer "In4.Cu")
		(net "P5E_CPU0_G3_TX_DN<11>")
	)
	(segment
		(start 314.114688 -141.777212)
		(end 309.808118 -156.66339)
		(width 0.14224)
		(layer "In4.Cu")
		(net "P5E_CPU0_G3_TX_DN<11>")
	)
	(segment
		(start 364.603792 -225.365564)
		(end 364.602522 -225.366326)
		(width 0.1143)
		(layer "In4.Cu")
		(net "P5E_CPU0_G3_TX_DN<11>")
	)
	(segment
		(start 321.917822 -175.997108)
		(end 360.06532 -207.258666)
		(width 0.14224)
		(layer "In4.Cu")
		(net "P5E_CPU0_G3_TX_DN<11>")
	)
	(segment
		(start 365.064294 -222.287084)
		(end 365.065818 -222.2881)
		(width 0.1143)
		(layer "In4.Cu")
		(net "P5E_CPU0_G3_TX_DN<11>")
	)
	(segment
		(start 364.16234 -226.15906)
		(end 364.092744 -226.1997)
		(width 0.1143)
		(layer "In4.Cu")
		(net "P5E_CPU0_G3_TX_DN<11>")
	)
	(arc
		(start 365.032798 -222.959676)
		(mid 364.789471 -223.424242)
		(end 365.032798 -223.888808)
		(width 0.1143)
		(layer "In4.Cu")
		(net "P5E_CPU0_G3_TX_DN<11>")
	)
	(arc
		(start 364.319312 -229.094284)
		(mid 364.278346 -229.26469)
		(end 364.164372 -229.397814)
		(width 0.1143)
		(layer "In4.Cu")
		(net "P5E_CPU0_G3_TX_DN<11>")
	)
	(arc
		(start 365.103664 -222.309944)
		(mid 365.21834 -222.443278)
		(end 365.25962 -222.614236)
		(width 0.1143)
		(layer "In4.Cu")
		(net "P5E_CPU0_G3_TX_DN<11>")
	)
	(arc
		(start 364.319312 -225.85426)
		(mid 364.277763 -226.025682)
		(end 364.16234 -226.15906)
		(width 0.1143)
		(layer "In4.Cu")
		(net "P5E_CPU0_G3_TX_DN<11>")
	)
	(arc
		(start 364.319312 -230.714296)
		(mid 364.383827 -230.976515)
		(end 364.562644 -231.178862)
		(width 0.1143)
		(layer "In4.Cu")
		(net "P5E_CPU0_G3_TX_DN<11>")
	)
	(arc
		(start 364.789466 -221.80423)
		(mid 364.793967 -221.875922)
		(end 364.8075 -221.94647)
		(width 0.1143)
		(layer "In4.Cu")
		(net "P5E_CPU0_G3_TX_DN<11>")
	)
	(arc
		(start 364.789466 -225.044254)
		(mid 364.748211 -225.215225)
		(end 364.63351 -225.348546)
		(width 0.1143)
		(layer "In4.Cu")
		(net "P5E_CPU0_G3_TX_DN<11>")
	)
	(arc
		(start 364.16234 -227.169472)
		(mid 364.319317 -227.474272)
		(end 364.16234 -227.779072)
		(width 0.1143)
		(layer "In4.Cu")
		(net "P5E_CPU0_G3_TX_DN<11>")
	)
	(arc
		(start 364.092744 -226.1997)
		(mid 363.849417 -226.664266)
		(end 364.092744 -227.128832)
		(width 0.1143)
		(layer "In4.Cu")
		(net "P5E_CPU0_G3_TX_DN<11>")
	)
	(arc
		(start 364.16234 -230.409496)
		(mid 364.277767 -230.542872)
		(end 364.319312 -230.714296)
		(width 0.1143)
		(layer "In4.Cu")
		(net "P5E_CPU0_G3_TX_DN<11>")
	)
	(arc
		(start 365.032798 -224.579688)
		(mid 364.853985 -224.782038)
		(end 364.789466 -225.044254)
		(width 0.1143)
		(layer "In4.Cu")
		(net "P5E_CPU0_G3_TX_DN<11>")
	)
	(arc
		(start 364.092744 -229.43947)
		(mid 363.913931 -229.64182)
		(end 363.849412 -229.904036)
		(width 0.1143)
		(layer "In4.Cu")
		(net "P5E_CPU0_G3_TX_DN<11>")
	)
	(arc
		(start 363.849412 -229.904036)
		(mid 363.914648 -230.167627)
		(end 364.095284 -230.37038)
		(width 0.1143)
		(layer "In4.Cu")
		(net "P5E_CPU0_G3_TX_DN<11>")
	)
	(arc
		(start 364.562644 -225.389694)
		(mid 364.383831 -225.592044)
		(end 364.319312 -225.85426)
		(width 0.1143)
		(layer "In4.Cu")
		(net "P5E_CPU0_G3_TX_DN<11>")
	)
	(arc
		(start 365.259366 -222.614236)
		(mid 365.217817 -222.785658)
		(end 365.102394 -222.919036)
		(width 0.1143)
		(layer "In4.Cu")
		(net "P5E_CPU0_G3_TX_DN<11>")
	)
	(arc
		(start 364.092744 -227.819712)
		(mid 363.849417 -228.284278)
		(end 364.092744 -228.748844)
		(width 0.1143)
		(layer "In4.Cu")
		(net "P5E_CPU0_G3_TX_DN<11>")
	)
	(arc
		(start 364.8075 -221.94647)
		(mid 364.891241 -222.12783)
		(end 365.032798 -222.268796)
		(width 0.1143)
		(layer "In4.Cu")
		(net "P5E_CPU0_G3_TX_DN<11>")
	)
	(arc
		(start 364.16234 -228.789484)
		(mid 364.277767 -228.92286)
		(end 364.319312 -229.094284)
		(width 0.1143)
		(layer "In4.Cu")
		(net "P5E_CPU0_G3_TX_DN<11>")
	)
	(arc
		(start 365.102394 -223.929448)
		(mid 365.259371 -224.234248)
		(end 365.102394 -224.539048)
		(width 0.1143)
		(layer "In4.Cu")
		(net "P5E_CPU0_G3_TX_DN<11>")
	)
	(arc
		(start 364.635288 -231.22128)
		(mid 364.731176 -231.323688)
		(end 364.782608 -231.454198)
		(width 0.1143)
		(layer "In4.Cu")
		(net "P5E_CPU0_G3_TX_DN<11>")
	)
	(segment
		(start 363.947964 -233.409998)
		(end 364.414816 -233.14406)
		(width 0.12954)
		(layer "F.Cu")
		(net "P5E_CPU0_G3_TX_DN<10>")
	)
	(segment
		(start 403.977348 -17.890998)
		(end 403.979126 -17.890998)
		(width 0.12954)
		(layer "F.Cu")
		(net "P5E_CPU0_G3_TX_DN<10>")
	)
	(segment
		(start 403.979126 -17.890998)
		(end 404.274274 -18.186146)
		(width 0.12954)
		(layer "F.Cu")
		(net "P5E_CPU0_G3_TX_DN<10>")
	)
	(segment
		(start 404.274274 -18.186146)
		(end 404.274274 -18.86585)
		(width 0.12954)
		(layer "F.Cu")
		(net "P5E_CPU0_G3_TX_DN<10>")
	)
	(segment
		(start 404.274274 -18.86585)
		(end 404.003764 -19.13636)
		(width 0.12954)
		(layer "F.Cu")
		(net "P5E_CPU0_G3_TX_DN<10>")
	)
	(segment
		(start 364.795562 -233.061256)
		(end 364.712758 -233.14406)
		(width 0.1143)
		(layer "In4.Cu")
		(net "P5E_CPU0_G3_TX_DN<10>")
	)
	(segment
		(start 365.538004 -225.368866)
		(end 365.536988 -225.369374)
		(width 0.1143)
		(layer "In4.Cu")
		(net "P5E_CPU0_G3_TX_DN<10>")
	)
	(segment
		(start 365.749078 -221.308676)
		(end 365.72952 -221.328234)
		(width 0.1143)
		(layer "In4.Cu")
		(net "P5E_CPU0_G3_TX_DN<10>")
	)
	(segment
		(start 365.071914 -227.796852)
		(end 365.070898 -227.79736)
		(width 0.1143)
		(layer "In4.Cu")
		(net "P5E_CPU0_G3_TX_DN<10>")
	)
	(segment
		(start 365.069374 -232.658158)
		(end 365.032798 -232.679494)
		(width 0.1143)
		(layer "In4.Cu")
		(net "P5E_CPU0_G3_TX_DN<10>")
	)
	(segment
		(start 365.070898 -227.79736)
		(end 365.069374 -227.798376)
		(width 0.1143)
		(layer "In4.Cu")
		(net "P5E_CPU0_G3_TX_DN<10>")
	)
	(segment
		(start 365.072676 -227.1522)
		(end 365.103664 -227.16998)
		(width 0.1143)
		(layer "In4.Cu")
		(net "P5E_CPU0_G3_TX_DN<10>")
	)
	(segment
		(start 365.072676 -232.656126)
		(end 365.071914 -232.656634)
		(width 0.1143)
		(layer "In4.Cu")
		(net "P5E_CPU0_G3_TX_DN<10>")
	)
	(segment
		(start 365.072676 -227.796344)
		(end 365.071914 -227.796852)
		(width 0.1143)
		(layer "In4.Cu")
		(net "P5E_CPU0_G3_TX_DN<10>")
	)
	(segment
		(start 310.714644 -156.88564)
		(end 310.52389 -157.84449)
		(width 0.14224)
		(layer "In4.Cu")
		(net "P5E_CPU0_G3_TX_DN<10>")
	)
	(segment
		(start 365.069374 -227.150168)
		(end 365.070898 -227.151184)
		(width 0.1143)
		(layer "In4.Cu")
		(net "P5E_CPU0_G3_TX_DN<10>")
	)
	(segment
		(start 365.070898 -226.177348)
		(end 365.069374 -226.178364)
		(width 0.1143)
		(layer "In4.Cu")
		(net "P5E_CPU0_G3_TX_DN<10>")
	)
	(segment
		(start 365.071914 -228.771704)
		(end 365.072676 -228.772212)
		(width 0.1143)
		(layer "In4.Cu")
		(net "P5E_CPU0_G3_TX_DN<10>")
	)
	(segment
		(start 365.105442 -229.397052)
		(end 365.032798 -229.43947)
		(width 0.1143)
		(layer "In4.Cu")
		(net "P5E_CPU0_G3_TX_DN<10>")
	)
	(segment
		(start 366.010698 -222.294196)
		(end 366.014 -222.295974)
		(width 0.1143)
		(layer "In4.Cu")
		(net "P5E_CPU0_G3_TX_DN<10>")
	)
	(segment
		(start 365.070898 -232.657142)
		(end 365.069374 -232.658158)
		(width 0.1143)
		(layer "In4.Cu")
		(net "P5E_CPU0_G3_TX_DN<10>")
	)
	(segment
		(start 404.003764 -19.13636)
		(end 404.294594 -19.42719)
		(width 0.14224)
		(layer "In4.Cu")
		(net "P5E_CPU0_G3_TX_DN<10>")
	)
	(segment
		(start 364.712758 -233.14406)
		(end 364.414816 -233.14406)
		(width 0.1143)
		(layer "In4.Cu")
		(net "P5E_CPU0_G3_TX_DN<10>")
	)
	(segment
		(start 365.573564 -231.82834)
		(end 365.541814 -231.846628)
		(width 0.1143)
		(layer "In4.Cu")
		(net "P5E_CPU0_G3_TX_DN<10>")
	)
	(segment
		(start 365.72952 -221.328234)
		(end 365.72952 -221.80423)
		(width 0.1143)
		(layer "In4.Cu")
		(net "P5E_CPU0_G3_TX_DN<10>")
	)
	(segment
		(start 310.52389 -157.84449)
		(end 310.52389 -162.55619)
		(width 0.14224)
		(layer "In4.Cu")
		(net "P5E_CPU0_G3_TX_DN<10>")
	)
	(segment
		(start 404.294594 -19.42719)
		(end 404.294594 -20.450048)
		(width 0.14224)
		(layer "In4.Cu")
		(net "P5E_CPU0_G3_TX_DN<10>")
	)
	(segment
		(start 365.077756 -232.653332)
		(end 365.072676 -232.656126)
		(width 0.1143)
		(layer "In4.Cu")
		(net "P5E_CPU0_G3_TX_DN<10>")
	)
	(segment
		(start 365.070898 -228.771196)
		(end 365.071914 -228.771704)
		(width 0.1143)
		(layer "In4.Cu")
		(net "P5E_CPU0_G3_TX_DN<10>")
	)
	(segment
		(start 365.070898 -230.394002)
		(end 365.076232 -230.39705)
		(width 0.1143)
		(layer "In4.Cu")
		(net "P5E_CPU0_G3_TX_DN<10>")
	)
	(segment
		(start 365.072676 -228.772212)
		(end 365.103664 -228.789992)
		(width 0.1143)
		(layer "In4.Cu")
		(net "P5E_CPU0_G3_TX_DN<10>")
	)
	(segment
		(start 365.071914 -227.151692)
		(end 365.072676 -227.1522)
		(width 0.1143)
		(layer "In4.Cu")
		(net "P5E_CPU0_G3_TX_DN<10>")
	)
	(segment
		(start 365.703358 -221.083124)
		(end 365.749078 -221.128844)
		(width 0.1143)
		(layer "In4.Cu")
		(net "P5E_CPU0_G3_TX_DN<10>")
	)
	(segment
		(start 365.54029 -225.367596)
		(end 365.538004 -225.368866)
		(width 0.1143)
		(layer "In4.Cu")
		(net "P5E_CPU0_G3_TX_DN<10>")
	)
	(segment
		(start 365.069374 -228.77018)
		(end 365.070898 -228.771196)
		(width 0.1143)
		(layer "In4.Cu")
		(net "P5E_CPU0_G3_TX_DN<10>")
	)
	(segment
		(start 312.675778 -167.659558)
		(end 316.872112 -171.856654)
		(width 0.14224)
		(layer "In4.Cu")
		(net "P5E_CPU0_G3_TX_DN<10>")
	)
	(segment
		(start 365.101378 -226.159822)
		(end 365.072676 -226.176332)
		(width 0.1143)
		(layer "In4.Cu")
		(net "P5E_CPU0_G3_TX_DN<10>")
	)
	(segment
		(start 319.396364 -130.63347)
		(end 314.997084 -142.082266)
		(width 0.14224)
		(layer "In4.Cu")
		(net "P5E_CPU0_G3_TX_DN<10>")
	)
	(segment
		(start 314.997084 -142.082266)
		(end 310.714644 -156.88564)
		(width 0.14224)
		(layer "In4.Cu")
		(net "P5E_CPU0_G3_TX_DN<10>")
	)
	(segment
		(start 365.541306 -225.367088)
		(end 365.54029 -225.367596)
		(width 0.1143)
		(layer "In4.Cu")
		(net "P5E_CPU0_G3_TX_DN<10>")
	)
	(segment
		(start 366.042448 -224.539048)
		(end 365.972852 -224.579688)
		(width 0.1143)
		(layer "In4.Cu")
		(net "P5E_CPU0_G3_TX_DN<10>")
	)
	(segment
		(start 360.798364 -206.653638)
		(end 360.798618 -206.653638)
		(width 0.14224)
		(layer "In4.Cu")
		(net "P5E_CPU0_G3_TX_DN<10>")
	)
	(segment
		(start 365.069374 -226.178364)
		(end 365.032798 -226.1997)
		(width 0.1143)
		(layer "In4.Cu")
		(net "P5E_CPU0_G3_TX_DN<10>")
	)
	(segment
		(start 365.505492 -231.18064)
		(end 365.575342 -231.22128)
		(width 0.1143)
		(layer "In4.Cu")
		(net "P5E_CPU0_G3_TX_DN<10>")
	)
	(segment
		(start 365.536988 -225.369374)
		(end 365.505492 -225.387916)
		(width 0.1143)
		(layer "In4.Cu")
		(net "P5E_CPU0_G3_TX_DN<10>")
	)
	(segment
		(start 365.069374 -227.798376)
		(end 365.032798 -227.819712)
		(width 0.1143)
		(layer "In4.Cu")
		(net "P5E_CPU0_G3_TX_DN<10>")
	)
	(segment
		(start 312.574686 -167.508428)
		(end 312.675778 -167.659558)
		(width 0.14224)
		(layer "In4.Cu")
		(net "P5E_CPU0_G3_TX_DN<10>")
	)
	(segment
		(start 316.872112 -171.856654)
		(end 322.32727 -175.12665)
		(width 0.14224)
		(layer "In4.Cu")
		(net "P5E_CPU0_G3_TX_DN<10>")
	)
	(segment
		(start 365.070898 -227.151184)
		(end 365.071914 -227.151692)
		(width 0.1143)
		(layer "In4.Cu")
		(net "P5E_CPU0_G3_TX_DN<10>")
	)
	(segment
		(start 323.287136 -123.77293)
		(end 319.396364 -130.63347)
		(width 0.14224)
		(layer "In4.Cu")
		(net "P5E_CPU0_G3_TX_DN<10>")
	)
	(segment
		(start 365.543592 -225.365818)
		(end 365.541306 -225.367088)
		(width 0.1143)
		(layer "In4.Cu")
		(net "P5E_CPU0_G3_TX_DN<10>")
	)
	(segment
		(start 322.32727 -175.12665)
		(end 360.798364 -206.653638)
		(width 0.14224)
		(layer "In4.Cu")
		(net "P5E_CPU0_G3_TX_DN<10>")
	)
	(segment
		(start 365.032798 -228.748844)
		(end 365.069374 -228.77018)
		(width 0.1143)
		(layer "In4.Cu")
		(net "P5E_CPU0_G3_TX_DN<10>")
	)
	(segment
		(start 365.072676 -226.176332)
		(end 365.071914 -226.17684)
		(width 0.1143)
		(layer "In4.Cu")
		(net "P5E_CPU0_G3_TX_DN<10>")
	)
	(segment
		(start 365.972852 -223.888808)
		(end 366.042448 -223.929448)
		(width 0.1143)
		(layer "In4.Cu")
		(net "P5E_CPU0_G3_TX_DN<10>")
	)
	(segment
		(start 404.294594 -20.450048)
		(end 323.287136 -123.77293)
		(width 0.14224)
		(layer "In4.Cu")
		(net "P5E_CPU0_G3_TX_DN<10>")
	)
	(segment
		(start 365.703358 -214.914988)
		(end 365.703358 -221.083124)
		(width 0.14224)
		(layer "In4.Cu")
		(net "P5E_CPU0_G3_TX_DN<10>")
	)
	(segment
		(start 360.798618 -206.653638)
		(end 365.703358 -214.914988)
		(width 0.14224)
		(layer "In4.Cu")
		(net "P5E_CPU0_G3_TX_DN<10>")
	)
	(segment
		(start 365.749078 -221.128844)
		(end 365.749078 -221.308676)
		(width 0.1143)
		(layer "In4.Cu")
		(net "P5E_CPU0_G3_TX_DN<10>")
	)
	(segment
		(start 310.52389 -162.55619)
		(end 312.574686 -167.508428)
		(width 0.14224)
		(layer "In4.Cu")
		(net "P5E_CPU0_G3_TX_DN<10>")
	)
	(segment
		(start 366.042448 -222.919036)
		(end 365.972852 -222.959676)
		(width 0.1143)
		(layer "In4.Cu")
		(net "P5E_CPU0_G3_TX_DN<10>")
	)
	(segment
		(start 365.032798 -227.128832)
		(end 365.069374 -227.150168)
		(width 0.1143)
		(layer "In4.Cu")
		(net "P5E_CPU0_G3_TX_DN<10>")
	)
	(segment
		(start 365.265208 -232.326942)
		(end 365.265208 -232.329482)
		(width 0.1143)
		(layer "In4.Cu")
		(net "P5E_CPU0_G3_TX_DN<10>")
	)
	(segment
		(start 365.071914 -232.656634)
		(end 365.070898 -232.657142)
		(width 0.1143)
		(layer "In4.Cu")
		(net "P5E_CPU0_G3_TX_DN<10>")
	)
	(segment
		(start 365.071914 -226.17684)
		(end 365.070898 -226.177348)
		(width 0.1143)
		(layer "In4.Cu")
		(net "P5E_CPU0_G3_TX_DN<10>")
	)
	(segment
		(start 365.103664 -227.778564)
		(end 365.072676 -227.796344)
		(width 0.1143)
		(layer "In4.Cu")
		(net "P5E_CPU0_G3_TX_DN<10>")
	)
	(arc
		(start 365.72952 -231.524048)
		(mid 365.688265 -231.695019)
		(end 365.573564 -231.82834)
		(width 0.1143)
		(layer "In4.Cu")
		(net "P5E_CPU0_G3_TX_DN<10>")
	)
	(arc
		(start 365.076232 -230.39705)
		(mid 365.210504 -230.531067)
		(end 365.25962 -230.714296)
		(width 0.1143)
		(layer "In4.Cu")
		(net "P5E_CPU0_G3_TX_DN<10>")
	)
	(arc
		(start 365.972852 -224.579688)
		(mid 365.794039 -224.782038)
		(end 365.72952 -225.044254)
		(width 0.1143)
		(layer "In4.Cu")
		(net "P5E_CPU0_G3_TX_DN<10>")
	)
	(arc
		(start 364.789466 -229.904036)
		(mid 364.864834 -230.186551)
		(end 365.070898 -230.394002)
		(width 0.1143)
		(layer "In4.Cu")
		(net "P5E_CPU0_G3_TX_DN<10>")
	)
	(arc
		(start 365.72952 -225.044254)
		(mid 365.679697 -225.229984)
		(end 365.543592 -225.365818)
		(width 0.1143)
		(layer "In4.Cu")
		(net "P5E_CPU0_G3_TX_DN<10>")
	)
	(arc
		(start 365.103664 -228.789992)
		(mid 365.215461 -228.924793)
		(end 365.25962 -229.094284)
		(width 0.1143)
		(layer "In4.Cu")
		(net "P5E_CPU0_G3_TX_DN<10>")
	)
	(arc
		(start 365.72952 -221.80423)
		(mid 365.804813 -222.086681)
		(end 366.010698 -222.294196)
		(width 0.1143)
		(layer "In4.Cu")
		(net "P5E_CPU0_G3_TX_DN<10>")
	)
	(arc
		(start 365.032798 -227.819712)
		(mid 364.789471 -228.284278)
		(end 365.032798 -228.748844)
		(width 0.1143)
		(layer "In4.Cu")
		(net "P5E_CPU0_G3_TX_DN<10>")
	)
	(arc
		(start 365.25962 -229.094284)
		(mid 365.218858 -229.264168)
		(end 365.105442 -229.397052)
		(width 0.1143)
		(layer "In4.Cu")
		(net "P5E_CPU0_G3_TX_DN<10>")
	)
	(arc
		(start 365.541814 -231.846628)
		(mid 365.339274 -232.049798)
		(end 365.265208 -232.326942)
		(width 0.1143)
		(layer "In4.Cu")
		(net "P5E_CPU0_G3_TX_DN<10>")
	)
	(arc
		(start 365.032798 -226.1997)
		(mid 364.789471 -226.664266)
		(end 365.032798 -227.128832)
		(width 0.1143)
		(layer "In4.Cu")
		(net "P5E_CPU0_G3_TX_DN<10>")
	)
	(arc
		(start 365.25962 -225.85426)
		(mid 365.214609 -226.024696)
		(end 365.101378 -226.159822)
		(width 0.1143)
		(layer "In4.Cu")
		(net "P5E_CPU0_G3_TX_DN<10>")
	)
	(arc
		(start 365.575342 -231.22128)
		(mid 365.688749 -231.354169)
		(end 365.72952 -231.524048)
		(width 0.1143)
		(layer "In4.Cu")
		(net "P5E_CPU0_G3_TX_DN<10>")
	)
	(arc
		(start 365.265208 -232.329482)
		(mid 365.214958 -232.516564)
		(end 365.077756 -232.653332)
		(width 0.1143)
		(layer "In4.Cu")
		(net "P5E_CPU0_G3_TX_DN<10>")
	)
	(arc
		(start 365.032798 -229.43947)
		(mid 364.853985 -229.64182)
		(end 364.789466 -229.904036)
		(width 0.1143)
		(layer "In4.Cu")
		(net "P5E_CPU0_G3_TX_DN<10>")
	)
	(arc
		(start 365.25962 -230.714296)
		(mid 365.324856 -230.977887)
		(end 365.505492 -231.18064)
		(width 0.1143)
		(layer "In4.Cu")
		(net "P5E_CPU0_G3_TX_DN<10>")
	)
	(arc
		(start 365.505492 -225.387916)
		(mid 365.32484 -225.590661)
		(end 365.25962 -225.85426)
		(width 0.1143)
		(layer "In4.Cu")
		(net "P5E_CPU0_G3_TX_DN<10>")
	)
	(arc
		(start 366.014 -222.295974)
		(mid 366.197839 -222.599795)
		(end 366.042448 -222.919036)
		(width 0.1143)
		(layer "In4.Cu")
		(net "P5E_CPU0_G3_TX_DN<10>")
	)
	(arc
		(start 365.972852 -222.959676)
		(mid 365.729525 -223.424242)
		(end 365.972852 -223.888808)
		(width 0.1143)
		(layer "In4.Cu")
		(net "P5E_CPU0_G3_TX_DN<10>")
	)
	(arc
		(start 365.032798 -232.679494)
		(mid 364.880811 -232.836002)
		(end 364.799372 -233.038396)
		(width 0.1143)
		(layer "In4.Cu")
		(net "P5E_CPU0_G3_TX_DN<10>")
	)
	(arc
		(start 364.799372 -233.038396)
		(mid 364.797349 -233.049806)
		(end 364.795562 -233.061256)
		(width 0.1143)
		(layer "In4.Cu")
		(net "P5E_CPU0_G3_TX_DN<10>")
	)
	(arc
		(start 365.103664 -227.16998)
		(mid 365.255253 -227.474272)
		(end 365.103664 -227.778564)
		(width 0.1143)
		(layer "In4.Cu")
		(net "P5E_CPU0_G3_TX_DN<10>")
	)
	(arc
		(start 366.042448 -223.929448)
		(mid 366.199425 -224.234248)
		(end 366.042448 -224.539048)
		(width 0.1143)
		(layer "In4.Cu")
		(net "P5E_CPU0_G3_TX_DN<10>")
	)
	(segment
		(start 372.407942 -235.03001)
		(end 372.874794 -234.764072)
		(width 0.12954)
		(layer "F.Cu")
		(net "P5E_CPU0_G3_TX_DN<0>")
	)
	(segment
		(start 432.554126 -18.86585)
		(end 432.283616 -19.13636)
		(width 0.12954)
		(layer "F.Cu")
		(net "P5E_CPU0_G3_TX_DN<0>")
	)
	(segment
		(start 432.554126 -18.187924)
		(end 432.554126 -18.86585)
		(width 0.12954)
		(layer "F.Cu")
		(net "P5E_CPU0_G3_TX_DN<0>")
	)
	(segment
		(start 432.2572 -17.890998)
		(end 432.554126 -18.187924)
		(width 0.12954)
		(layer "F.Cu")
		(net "P5E_CPU0_G3_TX_DN<0>")
	)
	(segment
		(start 374.945402 -231.844596)
		(end 374.943878 -231.845358)
		(width 0.1143)
		(layer "In4.Cu")
		(net "P5E_CPU0_G3_TX_DN<0>")
	)
	(segment
		(start 375.37517 -224.57791)
		(end 375.372884 -224.579688)
		(width 0.1143)
		(layer "In4.Cu")
		(net "P5E_CPU0_G3_TX_DN<0>")
	)
	(segment
		(start 374.939306 -231.848152)
		(end 374.90273 -231.869488)
		(width 0.1143)
		(layer "In4.Cu")
		(net "P5E_CPU0_G3_TX_DN<0>")
	)
	(segment
		(start 374.005348 -233.46283)
		(end 374.003824 -233.463592)
		(width 0.1143)
		(layer "In4.Cu")
		(net "P5E_CPU0_G3_TX_DN<0>")
	)
	(segment
		(start 373.172736 -234.764072)
		(end 372.874794 -234.764072)
		(width 0.1143)
		(layer "In4.Cu")
		(net "P5E_CPU0_G3_TX_DN<0>")
	)
	(segment
		(start 374.943878 -231.845358)
		(end 374.942608 -231.84612)
		(width 0.1143)
		(layer "In4.Cu")
		(net "P5E_CPU0_G3_TX_DN<0>")
	)
	(segment
		(start 374.94718 -225.363786)
		(end 374.946164 -225.364294)
		(width 0.1143)
		(layer "In4.Cu")
		(net "P5E_CPU0_G3_TX_DN<0>")
	)
	(segment
		(start 376.34926 -222.93834)
		(end 376.312684 -222.959676)
		(width 0.1143)
		(layer "In4.Cu")
		(net "P5E_CPU0_G3_TX_DN<0>")
	)
	(segment
		(start 327.127616 -138.31443)
		(end 327.127616 -141.494002)
		(width 0.14224)
		(layer "In4.Cu")
		(net "P5E_CPU0_G3_TX_DN<0>")
	)
	(segment
		(start 373.531892 -234.276646)
		(end 373.530876 -234.277154)
		(width 0.1143)
		(layer "In4.Cu")
		(net "P5E_CPU0_G3_TX_DN<0>")
	)
	(segment
		(start 376.964194 -219.303854)
		(end 376.964194 -221.547182)
		(width 0.14224)
		(layer "In4.Cu")
		(net "P5E_CPU0_G3_TX_DN<0>")
	)
	(segment
		(start 374.973596 -231.82834)
		(end 374.94718 -231.84358)
		(width 0.1143)
		(layer "In4.Cu")
		(net "P5E_CPU0_G3_TX_DN<0>")
	)
	(segment
		(start 368.226594 -200.442576)
		(end 375.57837 -212.88629)
		(width 0.14224)
		(layer "In4.Cu")
		(net "P5E_CPU0_G3_TX_DN<0>")
	)
	(segment
		(start 376.3518 -222.936816)
		(end 376.350784 -222.937324)
		(width 0.1143)
		(layer "In4.Cu")
		(net "P5E_CPU0_G3_TX_DN<0>")
	)
	(segment
		(start 375.442988 -224.53854)
		(end 375.37517 -224.57791)
		(width 0.1143)
		(layer "In4.Cu")
		(net "P5E_CPU0_G3_TX_DN<0>")
	)
	(segment
		(start 376.352562 -222.936308)
		(end 376.3518 -222.936816)
		(width 0.1143)
		(layer "In4.Cu")
		(net "P5E_CPU0_G3_TX_DN<0>")
	)
	(segment
		(start 374.471946 -229.41661)
		(end 374.43283 -229.43947)
		(width 0.1143)
		(layer "In4.Cu")
		(net "P5E_CPU0_G3_TX_DN<0>")
	)
	(segment
		(start 374.946164 -225.364294)
		(end 374.945402 -225.364802)
		(width 0.1143)
		(layer "In4.Cu")
		(net "P5E_CPU0_G3_TX_DN<0>")
	)
	(segment
		(start 374.946164 -231.844088)
		(end 374.945402 -231.844596)
		(width 0.1143)
		(layer "In4.Cu")
		(net "P5E_CPU0_G3_TX_DN<0>")
	)
	(segment
		(start 374.945402 -225.364802)
		(end 374.943878 -225.365564)
		(width 0.1143)
		(layer "In4.Cu")
		(net "P5E_CPU0_G3_TX_DN<0>")
	)
	(segment
		(start 376.820938 -222.127318)
		(end 376.819414 -222.128334)
		(width 0.1143)
		(layer "In4.Cu")
		(net "P5E_CPU0_G3_TX_DN<0>")
	)
	(segment
		(start 374.43283 -228.748844)
		(end 374.502426 -228.789484)
		(width 0.1143)
		(layer "In4.Cu")
		(net "P5E_CPU0_G3_TX_DN<0>")
	)
	(segment
		(start 341.914226 -178.709828)
		(end 342.92413 -179.719478)
		(width 0.14224)
		(layer "In4.Cu")
		(net "P5E_CPU0_G3_TX_DN<0>")
	)
	(segment
		(start 328.989944 -154.512518)
		(end 329.540108 -156.064458)
		(width 0.14224)
		(layer "In4.Cu")
		(net "P5E_CPU0_G3_TX_DN<0>")
	)
	(segment
		(start 374.504458 -229.397814)
		(end 374.471946 -229.41661)
		(width 0.1143)
		(layer "In4.Cu")
		(net "P5E_CPU0_G3_TX_DN<0>")
	)
	(segment
		(start 374.94718 -231.84358)
		(end 374.946164 -231.844088)
		(width 0.1143)
		(layer "In4.Cu")
		(net "P5E_CPU0_G3_TX_DN<0>")
	)
	(segment
		(start 374.502426 -226.15906)
		(end 374.43283 -226.1997)
		(width 0.1143)
		(layer "In4.Cu")
		(net "P5E_CPU0_G3_TX_DN<0>")
	)
	(segment
		(start 376.964194 -221.57563)
		(end 377.009914 -221.62135)
		(width 0.1143)
		(layer "In4.Cu")
		(net "P5E_CPU0_G3_TX_DN<0>")
	)
	(segment
		(start 375.57837 -212.88629)
		(end 376.254264 -213.97976)
		(width 0.14224)
		(layer "In4.Cu")
		(net "P5E_CPU0_G3_TX_DN<0>")
	)
	(segment
		(start 373.529352 -234.27817)
		(end 373.492776 -234.299506)
		(width 0.1143)
		(layer "In4.Cu")
		(net "P5E_CPU0_G3_TX_DN<0>")
	)
	(segment
		(start 373.25554 -234.681268)
		(end 373.172736 -234.764072)
		(width 0.1143)
		(layer "In4.Cu")
		(net "P5E_CPU0_G3_TX_DN<0>")
	)
	(segment
		(start 328.508868 -134.09422)
		(end 327.873106 -135.584184)
		(width 0.14224)
		(layer "In4.Cu")
		(net "P5E_CPU0_G3_TX_DN<0>")
	)
	(segment
		(start 376.38355 -222.918528)
		(end 376.353832 -222.935546)
		(width 0.1143)
		(layer "In4.Cu")
		(net "P5E_CPU0_G3_TX_DN<0>")
	)
	(segment
		(start 374.001284 -233.465116)
		(end 374.00103 -233.465116)
		(width 0.1143)
		(layer "In4.Cu")
		(net "P5E_CPU0_G3_TX_DN<0>")
	)
	(segment
		(start 373.5324 -234.276646)
		(end 373.531892 -234.276646)
		(width 0.1143)
		(layer "In4.Cu")
		(net "P5E_CPU0_G3_TX_DN<0>")
	)
	(segment
		(start 376.819414 -222.128334)
		(end 376.782838 -222.14967)
		(width 0.1143)
		(layer "In4.Cu")
		(net "P5E_CPU0_G3_TX_DN<0>")
	)
	(segment
		(start 374.942608 -225.366326)
		(end 374.941846 -225.366834)
		(width 0.1143)
		(layer "In4.Cu")
		(net "P5E_CPU0_G3_TX_DN<0>")
	)
	(segment
		(start 374.942608 -231.84612)
		(end 374.941846 -231.846628)
		(width 0.1143)
		(layer "In4.Cu")
		(net "P5E_CPU0_G3_TX_DN<0>")
	)
	(segment
		(start 376.964194 -221.547182)
		(end 376.964194 -221.57563)
		(width 0.1143)
		(layer "In4.Cu")
		(net "P5E_CPU0_G3_TX_DN<0>")
	)
	(segment
		(start 374.43537 -230.37038)
		(end 374.502426 -230.409496)
		(width 0.1143)
		(layer "In4.Cu")
		(net "P5E_CPU0_G3_TX_DN<0>")
	)
	(segment
		(start 376.350784 -222.937324)
		(end 376.34926 -222.93834)
		(width 0.1143)
		(layer "In4.Cu")
		(net "P5E_CPU0_G3_TX_DN<0>")
	)
	(segment
		(start 374.003824 -233.463592)
		(end 374.001284 -233.465116)
		(width 0.1143)
		(layer "In4.Cu")
		(net "P5E_CPU0_G3_TX_DN<0>")
	)
	(segment
		(start 374.502426 -227.779072)
		(end 374.43283 -227.819712)
		(width 0.1143)
		(layer "In4.Cu")
		(net "P5E_CPU0_G3_TX_DN<0>")
	)
	(segment
		(start 376.254264 -213.97976)
		(end 376.964194 -219.303854)
		(width 0.14224)
		(layer "In4.Cu")
		(net "P5E_CPU0_G3_TX_DN<0>")
	)
	(segment
		(start 375.91238 -223.729042)
		(end 375.833132 -223.77527)
		(width 0.1143)
		(layer "In4.Cu")
		(net "P5E_CPU0_G3_TX_DN<0>")
	)
	(segment
		(start 376.353832 -222.935546)
		(end 376.352562 -222.936308)
		(width 0.1143)
		(layer "In4.Cu")
		(net "P5E_CPU0_G3_TX_DN<0>")
	)
	(segment
		(start 374.941846 -231.846628)
		(end 374.94083 -231.847136)
		(width 0.1143)
		(layer "In4.Cu")
		(net "P5E_CPU0_G3_TX_DN<0>")
	)
	(segment
		(start 374.943878 -225.365564)
		(end 374.942608 -225.366326)
		(width 0.1143)
		(layer "In4.Cu")
		(net "P5E_CPU0_G3_TX_DN<0>")
	)
	(segment
		(start 327.873106 -135.584184)
		(end 327.133966 -138.26744)
		(width 0.14224)
		(layer "In4.Cu")
		(net "P5E_CPU0_G3_TX_DN<0>")
	)
	(segment
		(start 327.127616 -141.494002)
		(end 328.245724 -151.29256)
		(width 0.14224)
		(layer "In4.Cu")
		(net "P5E_CPU0_G3_TX_DN<0>")
	)
	(segment
		(start 374.90273 -231.178862)
		(end 374.975374 -231.22128)
		(width 0.1143)
		(layer "In4.Cu")
		(net "P5E_CPU0_G3_TX_DN<0>")
	)
	(segment
		(start 374.43283 -227.128832)
		(end 374.502426 -227.169472)
		(width 0.1143)
		(layer "In4.Cu")
		(net "P5E_CPU0_G3_TX_DN<0>")
	)
	(segment
		(start 328.245724 -151.29256)
		(end 328.989944 -154.512518)
		(width 0.14224)
		(layer "In4.Cu")
		(net "P5E_CPU0_G3_TX_DN<0>")
	)
	(segment
		(start 373.706898 -233.963718)
		(end 373.706898 -233.97337)
		(width 0.1143)
		(layer "In4.Cu")
		(net "P5E_CPU0_G3_TX_DN<0>")
	)
	(segment
		(start 327.133966 -138.26744)
		(end 327.127616 -138.31443)
		(width 0.14224)
		(layer "In4.Cu")
		(net "P5E_CPU0_G3_TX_DN<0>")
	)
	(segment
		(start 432.283616 -19.13636)
		(end 432.574446 -19.42719)
		(width 0.14224)
		(layer "In4.Cu")
		(net "P5E_CPU0_G3_TX_DN<0>")
	)
	(segment
		(start 374.939306 -225.368358)
		(end 374.90273 -225.389694)
		(width 0.1143)
		(layer "In4.Cu")
		(net "P5E_CPU0_G3_TX_DN<0>")
	)
	(segment
		(start 374.94083 -225.367342)
		(end 374.939306 -225.368358)
		(width 0.1143)
		(layer "In4.Cu")
		(net "P5E_CPU0_G3_TX_DN<0>")
	)
	(segment
		(start 373.530876 -234.277154)
		(end 373.529352 -234.27817)
		(width 0.1143)
		(layer "In4.Cu")
		(net "P5E_CPU0_G3_TX_DN<0>")
	)
	(segment
		(start 374.94083 -231.847136)
		(end 374.939306 -231.848152)
		(width 0.1143)
		(layer "In4.Cu")
		(net "P5E_CPU0_G3_TX_DN<0>")
	)
	(segment
		(start 377.009914 -221.62135)
		(end 377.009914 -221.80423)
		(width 0.1143)
		(layer "In4.Cu")
		(net "P5E_CPU0_G3_TX_DN<0>")
	)
	(segment
		(start 342.92413 -179.719478)
		(end 368.226594 -200.442576)
		(width 0.14224)
		(layer "In4.Cu")
		(net "P5E_CPU0_G3_TX_DN<0>")
	)
	(segment
		(start 432.574446 -20.027646)
		(end 328.508868 -134.09422)
		(width 0.14224)
		(layer "In4.Cu")
		(net "P5E_CPU0_G3_TX_DN<0>")
	)
	(segment
		(start 329.540108 -156.064458)
		(end 337.227926 -171.803822)
		(width 0.14224)
		(layer "In4.Cu")
		(net "P5E_CPU0_G3_TX_DN<0>")
	)
	(segment
		(start 374.941846 -225.366834)
		(end 374.94083 -225.367342)
		(width 0.1143)
		(layer "In4.Cu")
		(net "P5E_CPU0_G3_TX_DN<0>")
	)
	(segment
		(start 374.502426 -232.638854)
		(end 374.43283 -232.679494)
		(width 0.1143)
		(layer "In4.Cu")
		(net "P5E_CPU0_G3_TX_DN<0>")
	)
	(segment
		(start 376.857768 -222.103442)
		(end 376.821954 -222.12681)
		(width 0.1143)
		(layer "In4.Cu")
		(net "P5E_CPU0_G3_TX_DN<0>")
	)
	(segment
		(start 337.227926 -171.803822)
		(end 341.914226 -178.709828)
		(width 0.14224)
		(layer "In4.Cu")
		(net "P5E_CPU0_G3_TX_DN<0>")
	)
	(segment
		(start 376.821954 -222.12681)
		(end 376.820938 -222.127318)
		(width 0.1143)
		(layer "In4.Cu")
		(net "P5E_CPU0_G3_TX_DN<0>")
	)
	(segment
		(start 373.954802 -233.495088)
		(end 373.955056 -233.495342)
		(width 0.1143)
		(layer "In4.Cu")
		(net "P5E_CPU0_G3_TX_DN<0>")
	)
	(segment
		(start 432.574446 -19.42719)
		(end 432.574446 -20.027646)
		(width 0.14224)
		(layer "In4.Cu")
		(net "P5E_CPU0_G3_TX_DN<0>")
	)
	(segment
		(start 374.973596 -225.348546)
		(end 374.94718 -225.363786)
		(width 0.1143)
		(layer "In4.Cu")
		(net "P5E_CPU0_G3_TX_DN<0>")
	)
	(arc
		(start 375.372884 -224.579688)
		(mid 375.194071 -224.782038)
		(end 375.129552 -225.044254)
		(width 0.1143)
		(layer "In4.Cu")
		(net "P5E_CPU0_G3_TX_DN<0>")
	)
	(arc
		(start 373.492776 -234.299506)
		(mid 373.340789 -234.456014)
		(end 373.25935 -234.658408)
		(width 0.1143)
		(layer "In4.Cu")
		(net "P5E_CPU0_G3_TX_DN<0>")
	)
	(arc
		(start 374.502426 -227.169472)
		(mid 374.659403 -227.474272)
		(end 374.502426 -227.779072)
		(width 0.1143)
		(layer "In4.Cu")
		(net "P5E_CPU0_G3_TX_DN<0>")
	)
	(arc
		(start 375.129552 -231.524048)
		(mid 375.088297 -231.695019)
		(end 374.973596 -231.82834)
		(width 0.1143)
		(layer "In4.Cu")
		(net "P5E_CPU0_G3_TX_DN<0>")
	)
	(arc
		(start 373.706898 -233.97337)
		(mid 373.660158 -234.148315)
		(end 373.5324 -234.276646)
		(width 0.1143)
		(layer "In4.Cu")
		(net "P5E_CPU0_G3_TX_DN<0>")
	)
	(arc
		(start 374.00103 -233.465116)
		(mid 373.977552 -233.47954)
		(end 373.954802 -233.495088)
		(width 0.1143)
		(layer "In4.Cu")
		(net "P5E_CPU0_G3_TX_DN<0>")
	)
	(arc
		(start 374.975374 -231.22128)
		(mid 375.088781 -231.354169)
		(end 375.129552 -231.524048)
		(width 0.1143)
		(layer "In4.Cu")
		(net "P5E_CPU0_G3_TX_DN<0>")
	)
	(arc
		(start 374.43283 -229.43947)
		(mid 374.254017 -229.64182)
		(end 374.189498 -229.904036)
		(width 0.1143)
		(layer "In4.Cu")
		(net "P5E_CPU0_G3_TX_DN<0>")
	)
	(arc
		(start 376.069352 -223.424242)
		(mid 376.027803 -223.595664)
		(end 375.91238 -223.729042)
		(width 0.1143)
		(layer "In4.Cu")
		(net "P5E_CPU0_G3_TX_DN<0>")
	)
	(arc
		(start 374.43283 -227.819712)
		(mid 374.189503 -228.284278)
		(end 374.43283 -228.748844)
		(width 0.1143)
		(layer "In4.Cu")
		(net "P5E_CPU0_G3_TX_DN<0>")
	)
	(arc
		(start 374.502426 -230.409496)
		(mid 374.617853 -230.542872)
		(end 374.659398 -230.714296)
		(width 0.1143)
		(layer "In4.Cu")
		(net "P5E_CPU0_G3_TX_DN<0>")
	)
	(arc
		(start 375.129552 -225.044254)
		(mid 375.088297 -225.215225)
		(end 374.973596 -225.348546)
		(width 0.1143)
		(layer "In4.Cu")
		(net "P5E_CPU0_G3_TX_DN<0>")
	)
	(arc
		(start 374.502426 -228.789484)
		(mid 374.617853 -228.92286)
		(end 374.659398 -229.094284)
		(width 0.1143)
		(layer "In4.Cu")
		(net "P5E_CPU0_G3_TX_DN<0>")
	)
	(arc
		(start 376.539506 -222.614236)
		(mid 376.498251 -222.785207)
		(end 376.38355 -222.918528)
		(width 0.1143)
		(layer "In4.Cu")
		(net "P5E_CPU0_G3_TX_DN<0>")
	)
	(arc
		(start 373.25935 -234.658408)
		(mid 373.257327 -234.669818)
		(end 373.25554 -234.681268)
		(width 0.1143)
		(layer "In4.Cu")
		(net "P5E_CPU0_G3_TX_DN<0>")
	)
	(arc
		(start 375.62663 -224.086928)
		(mid 375.60756 -224.167048)
		(end 375.599198 -224.24898)
		(width 0.1143)
		(layer "In4.Cu")
		(net "P5E_CPU0_G3_TX_DN<0>")
	)
	(arc
		(start 374.43283 -232.679494)
		(mid 374.254017 -232.881844)
		(end 374.189498 -233.14406)
		(width 0.1143)
		(layer "In4.Cu")
		(net "P5E_CPU0_G3_TX_DN<0>")
	)
	(arc
		(start 374.659398 -229.094284)
		(mid 374.618432 -229.26469)
		(end 374.504458 -229.397814)
		(width 0.1143)
		(layer "In4.Cu")
		(net "P5E_CPU0_G3_TX_DN<0>")
	)
	(arc
		(start 374.90273 -231.869488)
		(mid 374.723917 -232.071838)
		(end 374.659398 -232.334054)
		(width 0.1143)
		(layer "In4.Cu")
		(net "P5E_CPU0_G3_TX_DN<0>")
	)
	(arc
		(start 375.833132 -223.77527)
		(mid 375.707847 -223.916494)
		(end 375.62663 -224.086928)
		(width 0.1143)
		(layer "In4.Cu")
		(net "P5E_CPU0_G3_TX_DN<0>")
	)
	(arc
		(start 374.43283 -226.1997)
		(mid 374.189503 -226.664266)
		(end 374.43283 -227.128832)
		(width 0.1143)
		(layer "In4.Cu")
		(net "P5E_CPU0_G3_TX_DN<0>")
	)
	(arc
		(start 374.659398 -230.714296)
		(mid 374.723913 -230.976515)
		(end 374.90273 -231.178862)
		(width 0.1143)
		(layer "In4.Cu")
		(net "P5E_CPU0_G3_TX_DN<0>")
	)
	(arc
		(start 374.659398 -232.334054)
		(mid 374.617849 -232.505476)
		(end 374.502426 -232.638854)
		(width 0.1143)
		(layer "In4.Cu")
		(net "P5E_CPU0_G3_TX_DN<0>")
	)
	(arc
		(start 374.189498 -233.14406)
		(mid 374.140158 -233.328138)
		(end 374.005348 -233.46283)
		(width 0.1143)
		(layer "In4.Cu")
		(net "P5E_CPU0_G3_TX_DN<0>")
	)
	(arc
		(start 374.189498 -229.904036)
		(mid 374.254734 -230.167627)
		(end 374.43537 -230.37038)
		(width 0.1143)
		(layer "In4.Cu")
		(net "P5E_CPU0_G3_TX_DN<0>")
	)
	(arc
		(start 373.955056 -233.495342)
		(mid 373.77273 -233.698666)
		(end 373.706898 -233.963718)
		(width 0.1143)
		(layer "In4.Cu")
		(net "P5E_CPU0_G3_TX_DN<0>")
	)
	(arc
		(start 374.659398 -225.85426)
		(mid 374.617849 -226.025682)
		(end 374.502426 -226.15906)
		(width 0.1143)
		(layer "In4.Cu")
		(net "P5E_CPU0_G3_TX_DN<0>")
	)
	(arc
		(start 376.312684 -222.959676)
		(mid 376.133871 -223.162026)
		(end 376.069352 -223.424242)
		(width 0.1143)
		(layer "In4.Cu")
		(net "P5E_CPU0_G3_TX_DN<0>")
	)
	(arc
		(start 375.599198 -224.24898)
		(mid 375.5546 -224.411844)
		(end 375.442988 -224.53854)
		(width 0.1143)
		(layer "In4.Cu")
		(net "P5E_CPU0_G3_TX_DN<0>")
	)
	(arc
		(start 374.90273 -225.389694)
		(mid 374.723917 -225.592044)
		(end 374.659398 -225.85426)
		(width 0.1143)
		(layer "In4.Cu")
		(net "P5E_CPU0_G3_TX_DN<0>")
	)
	(arc
		(start 377.009914 -221.80423)
		(mid 376.969325 -221.971885)
		(end 376.857768 -222.103442)
		(width 0.1143)
		(layer "In4.Cu")
		(net "P5E_CPU0_G3_TX_DN<0>")
	)
	(arc
		(start 376.782838 -222.14967)
		(mid 376.604025 -222.35202)
		(end 376.539506 -222.614236)
		(width 0.1143)
		(layer "In4.Cu")
		(net "P5E_CPU0_G3_TX_DN<0>")
	)
	(segment
		(start 404.446994 -7.709154)
		(end 404.585678 -7.57047)
		(width 0.12954)
		(layer "F.Cu")
		(net "P5E_CPU0_G3_RX_DP<9>")
	)
	(segment
		(start 363.947964 -246.370094)
		(end 364.414816 -246.104156)
		(width 0.12954)
		(layer "F.Cu")
		(net "P5E_CPU0_G3_RX_DP<9>")
	)
	(segment
		(start 404.585678 -6.99516)
		(end 404.315676 -6.725158)
		(width 0.12954)
		(layer "F.Cu")
		(net "P5E_CPU0_G3_RX_DP<9>")
	)
	(segment
		(start 404.446994 -8.320024)
		(end 404.446994 -7.709154)
		(width 0.12954)
		(layer "F.Cu")
		(net "P5E_CPU0_G3_RX_DP<9>")
	)
	(segment
		(start 404.585678 -7.57047)
		(end 404.585678 -6.99516)
		(width 0.12954)
		(layer "F.Cu")
		(net "P5E_CPU0_G3_RX_DP<9>")
	)
	(segment
		(start 366.48644 -225.364294)
		(end 366.4839 -225.365564)
		(width 0.1143)
		(layer "In11.Cu")
		(net "P5E_CPU0_G3_RX_DP<9>")
	)
	(segment
		(start 366.648238 -221.054676)
		(end 366.648238 -221.083124)
		(width 0.1143)
		(layer "In11.Cu")
		(net "P5E_CPU0_G3_RX_DP<9>")
	)
	(segment
		(start 365.072422 -245.616476)
		(end 365.03356 -245.639082)
		(width 0.1143)
		(layer "In11.Cu")
		(net "P5E_CPU0_G3_RX_DP<9>")
	)
	(segment
		(start 366.669574 -221.658942)
		(end 366.669574 -221.80423)
		(width 0.1143)
		(layer "In11.Cu")
		(net "P5E_CPU0_G3_RX_DP<9>")
	)
	(segment
		(start 365.972852 -227.128832)
		(end 366.042448 -227.169472)
		(width 0.1143)
		(layer "In11.Cu")
		(net "P5E_CPU0_G3_RX_DP<9>")
	)
	(segment
		(start 366.912652 -223.888808)
		(end 366.951768 -223.911668)
		(width 0.1143)
		(layer "In11.Cu")
		(net "P5E_CPU0_G3_RX_DP<9>")
	)
	(segment
		(start 365.972852 -228.748844)
		(end 365.97336 -228.749098)
		(width 0.1143)
		(layer "In11.Cu")
		(net "P5E_CPU0_G3_RX_DP<9>")
	)
	(segment
		(start 323.234304 -174.651162)
		(end 323.304916 -174.721774)
		(width 0.14224)
		(layer "In11.Cu")
		(net "P5E_CPU0_G3_RX_DP<9>")
	)
	(segment
		(start 365.97336 -228.749098)
		(end 366.011968 -228.771704)
		(width 0.1143)
		(layer "In11.Cu")
		(net "P5E_CPU0_G3_RX_DP<9>")
	)
	(segment
		(start 366.693958 -221.308676)
		(end 366.66932 -221.333314)
		(width 0.1143)
		(layer "In11.Cu")
		(net "P5E_CPU0_G3_RX_DP<9>")
	)
	(segment
		(start 365.573818 -244.788182)
		(end 365.530638 -244.813328)
		(width 0.1143)
		(layer "In11.Cu")
		(net "P5E_CPU0_G3_RX_DP<9>")
	)
	(segment
		(start 366.951768 -223.911668)
		(end 366.982502 -223.929448)
		(width 0.1143)
		(layer "In11.Cu")
		(net "P5E_CPU0_G3_RX_DP<9>")
	)
	(segment
		(start 366.011968 -231.036622)
		(end 365.972852 -231.059482)
		(width 0.1143)
		(layer "In11.Cu")
		(net "P5E_CPU0_G3_RX_DP<9>")
	)
	(segment
		(start 366.935766 -222.94596)
		(end 366.912652 -222.959676)
		(width 0.1143)
		(layer "In11.Cu")
		(net "P5E_CPU0_G3_RX_DP<9>")
	)
	(segment
		(start 366.042448 -237.49889)
		(end 365.972852 -237.53953)
		(width 0.1143)
		(layer "In11.Cu")
		(net "P5E_CPU0_G3_RX_DP<9>")
	)
	(segment
		(start 366.66932 -221.333314)
		(end 366.66932 -221.658688)
		(width 0.1143)
		(layer "In11.Cu")
		(net "P5E_CPU0_G3_RX_DP<9>")
	)
	(segment
		(start 406.030684 -19.272758)
		(end 405.953468 -19.397726)
		(width 0.14224)
		(layer "In11.Cu")
		(net "P5E_CPU0_G3_RX_DP<9>")
	)
	(segment
		(start 404.315676 -6.725158)
		(end 404.606506 -7.015988)
		(width 0.14224)
		(layer "In11.Cu")
		(net "P5E_CPU0_G3_RX_DP<9>")
	)
	(segment
		(start 366.042448 -234.258866)
		(end 365.972852 -234.299506)
		(width 0.1143)
		(layer "In11.Cu")
		(net "P5E_CPU0_G3_RX_DP<9>")
	)
	(segment
		(start 404.606506 -11.796776)
		(end 405.34209 -17.750028)
		(width 0.14224)
		(layer "In11.Cu")
		(net "P5E_CPU0_G3_RX_DP<9>")
	)
	(segment
		(start 366.4839 -225.365564)
		(end 366.48263 -225.366326)
		(width 0.1143)
		(layer "In11.Cu")
		(net "P5E_CPU0_G3_RX_DP<9>")
	)
	(segment
		(start 365.972852 -231.988614)
		(end 366.042448 -232.029254)
		(width 0.1143)
		(layer "In11.Cu")
		(net "P5E_CPU0_G3_RX_DP<9>")
	)
	(segment
		(start 366.489742 -225.362262)
		(end 366.488726 -225.36277)
		(width 0.1143)
		(layer "In11.Cu")
		(net "P5E_CPU0_G3_RX_DP<9>")
	)
	(segment
		(start 313.400948 -167.066214)
		(end 317.450978 -171.116752)
		(width 0.14224)
		(layer "In11.Cu")
		(net "P5E_CPU0_G3_RX_DP<9>")
	)
	(segment
		(start 311.45607 -160.632902)
		(end 311.45607 -162.370008)
		(width 0.14224)
		(layer "In11.Cu")
		(net "P5E_CPU0_G3_RX_DP<9>")
	)
	(segment
		(start 366.513618 -225.348546)
		(end 366.489742 -225.362262)
		(width 0.1143)
		(layer "In11.Cu")
		(net "P5E_CPU0_G3_RX_DP<9>")
	)
	(segment
		(start 365.972852 -241.708686)
		(end 366.042448 -241.749326)
		(width 0.1143)
		(layer "In11.Cu")
		(net "P5E_CPU0_G3_RX_DP<9>")
	)
	(segment
		(start 405.34209 -17.750028)
		(end 405.37765 -17.890236)
		(width 0.14224)
		(layer "In11.Cu")
		(net "P5E_CPU0_G3_RX_DP<9>")
	)
	(segment
		(start 405.637492 -18.375122)
		(end 406.030684 -18.962624)
		(width 0.14224)
		(layer "In11.Cu")
		(net "P5E_CPU0_G3_RX_DP<9>")
	)
	(segment
		(start 366.66932 -221.658688)
		(end 366.669574 -221.658942)
		(width 0.1143)
		(layer "In11.Cu")
		(net "P5E_CPU0_G3_RX_DP<9>")
	)
	(segment
		(start 366.042448 -232.638854)
		(end 365.972852 -232.679494)
		(width 0.1143)
		(layer "In11.Cu")
		(net "P5E_CPU0_G3_RX_DP<9>")
	)
	(segment
		(start 361.516676 -206.036164)
		(end 366.648238 -214.680292)
		(width 0.14224)
		(layer "In11.Cu")
		(net "P5E_CPU0_G3_RX_DP<9>")
	)
	(segment
		(start 366.042448 -242.358926)
		(end 365.972852 -242.399566)
		(width 0.1143)
		(layer "In11.Cu")
		(net "P5E_CPU0_G3_RX_DP<9>")
	)
	(segment
		(start 366.48263 -225.366326)
		(end 366.481868 -225.366834)
		(width 0.1143)
		(layer "In11.Cu")
		(net "P5E_CPU0_G3_RX_DP<9>")
	)
	(segment
		(start 365.975392 -230.37038)
		(end 366.042448 -230.409496)
		(width 0.1143)
		(layer "In11.Cu")
		(net "P5E_CPU0_G3_RX_DP<9>")
	)
	(segment
		(start 365.972852 -233.608626)
		(end 366.042448 -233.649266)
		(width 0.1143)
		(layer "In11.Cu")
		(net "P5E_CPU0_G3_RX_DP<9>")
	)
	(segment
		(start 323.304916 -174.721774)
		(end 361.516676 -206.036164)
		(width 0.14224)
		(layer "In11.Cu")
		(net "P5E_CPU0_G3_RX_DP<9>")
	)
	(segment
		(start 319.913 -131.129024)
		(end 313.562238 -148.643848)
		(width 0.14224)
		(layer "In11.Cu")
		(net "P5E_CPU0_G3_RX_DP<9>")
	)
	(segment
		(start 366.952276 -222.936562)
		(end 366.935766 -222.94596)
		(width 0.1143)
		(layer "In11.Cu")
		(net "P5E_CPU0_G3_RX_DP<9>")
	)
	(segment
		(start 322.857368 -174.357284)
		(end 323.234304 -174.651162)
		(width 0.14224)
		(layer "In11.Cu")
		(net "P5E_CPU0_G3_RX_DP<9>")
	)
	(segment
		(start 405.953468 -19.397726)
		(end 402.476716 -24.378158)
		(width 0.14224)
		(layer "In11.Cu")
		(net "P5E_CPU0_G3_RX_DP<9>")
	)
	(segment
		(start 365.972852 -240.088674)
		(end 366.042448 -240.129314)
		(width 0.1143)
		(layer "In11.Cu")
		(net "P5E_CPU0_G3_RX_DP<9>")
	)
	(segment
		(start 366.648238 -214.680292)
		(end 366.648238 -221.054676)
		(width 0.14224)
		(layer "In11.Cu")
		(net "P5E_CPU0_G3_RX_DP<9>")
	)
	(segment
		(start 366.042448 -240.738914)
		(end 365.972852 -240.779554)
		(width 0.1143)
		(layer "In11.Cu")
		(net "P5E_CPU0_G3_RX_DP<9>")
	)
	(segment
		(start 313.562238 -148.643848)
		(end 311.45607 -160.632902)
		(width 0.14224)
		(layer "In11.Cu")
		(net "P5E_CPU0_G3_RX_DP<9>")
	)
	(segment
		(start 311.45607 -162.370008)
		(end 313.400948 -167.066214)
		(width 0.14224)
		(layer "In11.Cu")
		(net "P5E_CPU0_G3_RX_DP<9>")
	)
	(segment
		(start 366.042448 -235.878878)
		(end 365.972852 -235.919518)
		(width 0.1143)
		(layer "In11.Cu")
		(net "P5E_CPU0_G3_RX_DP<9>")
	)
	(segment
		(start 365.972852 -236.84865)
		(end 366.042448 -236.88929)
		(width 0.1143)
		(layer "In11.Cu")
		(net "P5E_CPU0_G3_RX_DP<9>")
	)
	(segment
		(start 366.011968 -229.41661)
		(end 365.972852 -229.43947)
		(width 0.1143)
		(layer "In11.Cu")
		(net "P5E_CPU0_G3_RX_DP<9>")
	)
	(segment
		(start 322.615814 -126.255018)
		(end 319.913 -131.129024)
		(width 0.14224)
		(layer "In11.Cu")
		(net "P5E_CPU0_G3_RX_DP<9>")
	)
	(segment
		(start 366.648238 -221.083124)
		(end 366.693958 -221.128844)
		(width 0.1143)
		(layer "In11.Cu")
		(net "P5E_CPU0_G3_RX_DP<9>")
	)
	(segment
		(start 366.04448 -231.017826)
		(end 366.011968 -231.036622)
		(width 0.1143)
		(layer "In11.Cu")
		(net "P5E_CPU0_G3_RX_DP<9>")
	)
	(segment
		(start 366.480852 -225.367342)
		(end 366.479328 -225.368358)
		(width 0.1143)
		(layer "In11.Cu")
		(net "P5E_CPU0_G3_RX_DP<9>")
	)
	(segment
		(start 366.042448 -226.15906)
		(end 365.972852 -226.1997)
		(width 0.1143)
		(layer "In11.Cu")
		(net "P5E_CPU0_G3_RX_DP<9>")
	)
	(segment
		(start 402.476716 -24.378158)
		(end 322.615814 -126.255018)
		(width 0.14224)
		(layer "In11.Cu")
		(net "P5E_CPU0_G3_RX_DP<9>")
	)
	(segment
		(start 366.04448 -229.397814)
		(end 366.011968 -229.41661)
		(width 0.1143)
		(layer "In11.Cu")
		(net "P5E_CPU0_G3_RX_DP<9>")
	)
	(segment
		(start 366.042448 -227.779072)
		(end 365.972852 -227.819712)
		(width 0.1143)
		(layer "In11.Cu")
		(net "P5E_CPU0_G3_RX_DP<9>")
	)
	(segment
		(start 366.481868 -225.366834)
		(end 366.480852 -225.367342)
		(width 0.1143)
		(layer "In11.Cu")
		(net "P5E_CPU0_G3_RX_DP<9>")
	)
	(segment
		(start 365.972852 -238.468662)
		(end 366.042448 -238.509302)
		(width 0.1143)
		(layer "In11.Cu")
		(net "P5E_CPU0_G3_RX_DP<9>")
	)
	(segment
		(start 406.030684 -18.962624)
		(end 406.030684 -19.272758)
		(width 0.14224)
		(layer "In11.Cu")
		(net "P5E_CPU0_G3_RX_DP<9>")
	)
	(segment
		(start 364.712758 -246.104156)
		(end 364.414816 -246.104156)
		(width 0.1143)
		(layer "In11.Cu")
		(net "P5E_CPU0_G3_RX_DP<9>")
	)
	(segment
		(start 366.488726 -225.36277)
		(end 366.48644 -225.364294)
		(width 0.1143)
		(layer "In11.Cu")
		(net "P5E_CPU0_G3_RX_DP<9>")
	)
	(segment
		(start 365.247174 -245.303548)
		(end 365.247174 -245.3132)
		(width 0.1143)
		(layer "In11.Cu")
		(net "P5E_CPU0_G3_RX_DP<9>")
	)
	(segment
		(start 366.915446 -222.270574)
		(end 366.952276 -222.291656)
		(width 0.1143)
		(layer "In11.Cu")
		(net "P5E_CPU0_G3_RX_DP<9>")
	)
	(segment
		(start 366.479328 -225.368358)
		(end 366.442752 -225.389694)
		(width 0.1143)
		(layer "In11.Cu")
		(net "P5E_CPU0_G3_RX_DP<9>")
	)
	(segment
		(start 366.042448 -239.118902)
		(end 365.972852 -239.159542)
		(width 0.1143)
		(layer "In11.Cu")
		(net "P5E_CPU0_G3_RX_DP<9>")
	)
	(segment
		(start 364.795562 -246.021352)
		(end 364.712758 -246.104156)
		(width 0.1143)
		(layer "In11.Cu")
		(net "P5E_CPU0_G3_RX_DP<9>")
	)
	(segment
		(start 365.972852 -235.228638)
		(end 366.042448 -235.269278)
		(width 0.1143)
		(layer "In11.Cu")
		(net "P5E_CPU0_G3_RX_DP<9>")
	)
	(segment
		(start 404.606506 -7.015988)
		(end 404.606506 -11.796776)
		(width 0.14224)
		(layer "In11.Cu")
		(net "P5E_CPU0_G3_RX_DP<9>")
	)
	(segment
		(start 317.450978 -171.116752)
		(end 322.857368 -174.357284)
		(width 0.14224)
		(layer "In11.Cu")
		(net "P5E_CPU0_G3_RX_DP<9>")
	)
	(segment
		(start 366.011968 -228.771704)
		(end 366.042448 -228.789484)
		(width 0.1143)
		(layer "In11.Cu")
		(net "P5E_CPU0_G3_RX_DP<9>")
	)
	(segment
		(start 365.972852 -243.328698)
		(end 366.042448 -243.369338)
		(width 0.1143)
		(layer "In11.Cu")
		(net "P5E_CPU0_G3_RX_DP<9>")
	)
	(segment
		(start 405.37765 -17.890236)
		(end 405.637492 -18.375122)
		(width 0.14224)
		(layer "In11.Cu")
		(net "P5E_CPU0_G3_RX_DP<9>")
	)
	(segment
		(start 366.042448 -243.978938)
		(end 365.972852 -244.019578)
		(width 0.1143)
		(layer "In11.Cu")
		(net "P5E_CPU0_G3_RX_DP<9>")
	)
	(segment
		(start 366.693958 -221.128844)
		(end 366.693958 -221.308676)
		(width 0.1143)
		(layer "In11.Cu")
		(net "P5E_CPU0_G3_RX_DP<9>")
	)
	(segment
		(start 366.982502 -224.539048)
		(end 366.912906 -224.579688)
		(width 0.1143)
		(layer "In11.Cu")
		(net "P5E_CPU0_G3_RX_DP<9>")
	)
	(arc
		(start 365.972852 -239.159542)
		(mid 365.729525 -239.624108)
		(end 365.972852 -240.088674)
		(width 0.1143)
		(layer "In11.Cu")
		(net "P5E_CPU0_G3_RX_DP<9>")
	)
	(arc
		(start 366.912906 -224.579688)
		(mid 366.734093 -224.782038)
		(end 366.669574 -225.044254)
		(width 0.1143)
		(layer "In11.Cu")
		(net "P5E_CPU0_G3_RX_DP<9>")
	)
	(arc
		(start 365.530638 -244.813328)
		(mid 365.323154 -245.020415)
		(end 365.247174 -245.303548)
		(width 0.1143)
		(layer "In11.Cu")
		(net "P5E_CPU0_G3_RX_DP<9>")
	)
	(arc
		(start 365.972852 -235.919518)
		(mid 365.729525 -236.384084)
		(end 365.972852 -236.84865)
		(width 0.1143)
		(layer "In11.Cu")
		(net "P5E_CPU0_G3_RX_DP<9>")
	)
	(arc
		(start 365.972852 -240.779554)
		(mid 365.729525 -241.24412)
		(end 365.972852 -241.708686)
		(width 0.1143)
		(layer "In11.Cu")
		(net "P5E_CPU0_G3_RX_DP<9>")
	)
	(arc
		(start 366.442752 -225.389694)
		(mid 366.263939 -225.592044)
		(end 366.19942 -225.85426)
		(width 0.1143)
		(layer "In11.Cu")
		(net "P5E_CPU0_G3_RX_DP<9>")
	)
	(arc
		(start 365.72952 -244.484144)
		(mid 365.688327 -244.654933)
		(end 365.573818 -244.788182)
		(width 0.1143)
		(layer "In11.Cu")
		(net "P5E_CPU0_G3_RX_DP<9>")
	)
	(arc
		(start 365.972852 -231.059482)
		(mid 365.729525 -231.524048)
		(end 365.972852 -231.988614)
		(width 0.1143)
		(layer "In11.Cu")
		(net "P5E_CPU0_G3_RX_DP<9>")
	)
	(arc
		(start 366.042448 -238.509302)
		(mid 366.199425 -238.814102)
		(end 366.042448 -239.118902)
		(width 0.1143)
		(layer "In11.Cu")
		(net "P5E_CPU0_G3_RX_DP<9>")
	)
	(arc
		(start 365.972852 -232.679494)
		(mid 365.729525 -233.14406)
		(end 365.972852 -233.608626)
		(width 0.1143)
		(layer "In11.Cu")
		(net "P5E_CPU0_G3_RX_DP<9>")
	)
	(arc
		(start 365.972852 -242.399566)
		(mid 365.729525 -242.864132)
		(end 365.972852 -243.328698)
		(width 0.1143)
		(layer "In11.Cu")
		(net "P5E_CPU0_G3_RX_DP<9>")
	)
	(arc
		(start 365.032798 -245.63959)
		(mid 364.880811 -245.796098)
		(end 364.799372 -245.998492)
		(width 0.1143)
		(layer "In11.Cu")
		(net "P5E_CPU0_G3_RX_DP<9>")
	)
	(arc
		(start 365.72952 -229.904036)
		(mid 365.794756 -230.167627)
		(end 365.975392 -230.37038)
		(width 0.1143)
		(layer "In11.Cu")
		(net "P5E_CPU0_G3_RX_DP<9>")
	)
	(arc
		(start 365.972852 -234.299506)
		(mid 365.729525 -234.764072)
		(end 365.972852 -235.228638)
		(width 0.1143)
		(layer "In11.Cu")
		(net "P5E_CPU0_G3_RX_DP<9>")
	)
	(arc
		(start 366.952276 -222.291656)
		(mid 367.137914 -222.614172)
		(end 366.952276 -222.936562)
		(width 0.1143)
		(layer "In11.Cu")
		(net "P5E_CPU0_G3_RX_DP<9>")
	)
	(arc
		(start 365.972852 -226.1997)
		(mid 365.729525 -226.664266)
		(end 365.972852 -227.128832)
		(width 0.1143)
		(layer "In11.Cu")
		(net "P5E_CPU0_G3_RX_DP<9>")
	)
	(arc
		(start 366.042448 -233.649266)
		(mid 366.199425 -233.954066)
		(end 366.042448 -234.258866)
		(width 0.1143)
		(layer "In11.Cu")
		(net "P5E_CPU0_G3_RX_DP<9>")
	)
	(arc
		(start 366.042448 -241.749326)
		(mid 366.199425 -242.054126)
		(end 366.042448 -242.358926)
		(width 0.1143)
		(layer "In11.Cu")
		(net "P5E_CPU0_G3_RX_DP<9>")
	)
	(arc
		(start 365.247174 -245.3132)
		(mid 365.200284 -245.488151)
		(end 365.072422 -245.616476)
		(width 0.1143)
		(layer "In11.Cu")
		(net "P5E_CPU0_G3_RX_DP<9>")
	)
	(arc
		(start 366.89919 -222.259144)
		(mid 366.907268 -222.26493)
		(end 366.915446 -222.270574)
		(width 0.1143)
		(layer "In11.Cu")
		(net "P5E_CPU0_G3_RX_DP<9>")
	)
	(arc
		(start 366.19942 -225.85426)
		(mid 366.157871 -226.025682)
		(end 366.042448 -226.15906)
		(width 0.1143)
		(layer "In11.Cu")
		(net "P5E_CPU0_G3_RX_DP<9>")
	)
	(arc
		(start 365.972852 -237.53953)
		(mid 365.729525 -238.004096)
		(end 365.972852 -238.468662)
		(width 0.1143)
		(layer "In11.Cu")
		(net "P5E_CPU0_G3_RX_DP<9>")
	)
	(arc
		(start 366.19942 -229.094284)
		(mid 366.158454 -229.26469)
		(end 366.04448 -229.397814)
		(width 0.1143)
		(layer "In11.Cu")
		(net "P5E_CPU0_G3_RX_DP<9>")
	)
	(arc
		(start 366.042448 -227.169472)
		(mid 366.199425 -227.474272)
		(end 366.042448 -227.779072)
		(width 0.1143)
		(layer "In11.Cu")
		(net "P5E_CPU0_G3_RX_DP<9>")
	)
	(arc
		(start 366.042448 -240.129314)
		(mid 366.199425 -240.434114)
		(end 366.042448 -240.738914)
		(width 0.1143)
		(layer "In11.Cu")
		(net "P5E_CPU0_G3_RX_DP<9>")
	)
	(arc
		(start 366.669574 -221.80423)
		(mid 366.669564 -221.807532)
		(end 366.669574 -221.810834)
		(width 0.1143)
		(layer "In11.Cu")
		(net "P5E_CPU0_G3_RX_DP<9>")
	)
	(arc
		(start 366.042448 -228.789484)
		(mid 366.157875 -228.92286)
		(end 366.19942 -229.094284)
		(width 0.1143)
		(layer "In11.Cu")
		(net "P5E_CPU0_G3_RX_DP<9>")
	)
	(arc
		(start 366.042448 -243.369338)
		(mid 366.199425 -243.674138)
		(end 366.042448 -243.978938)
		(width 0.1143)
		(layer "In11.Cu")
		(net "P5E_CPU0_G3_RX_DP<9>")
	)
	(arc
		(start 366.042448 -230.409496)
		(mid 366.157875 -230.542872)
		(end 366.19942 -230.714296)
		(width 0.1143)
		(layer "In11.Cu")
		(net "P5E_CPU0_G3_RX_DP<9>")
	)
	(arc
		(start 365.972852 -244.019578)
		(mid 365.794039 -244.221928)
		(end 365.72952 -244.484144)
		(width 0.1143)
		(layer "In11.Cu")
		(net "P5E_CPU0_G3_RX_DP<9>")
	)
	(arc
		(start 364.799372 -245.998492)
		(mid 364.797349 -246.009902)
		(end 364.795562 -246.021352)
		(width 0.1143)
		(layer "In11.Cu")
		(net "P5E_CPU0_G3_RX_DP<9>")
	)
	(arc
		(start 366.669574 -221.810834)
		(mid 366.734446 -222.060576)
		(end 366.89919 -222.259144)
		(width 0.1143)
		(layer "In11.Cu")
		(net "P5E_CPU0_G3_RX_DP<9>")
	)
	(arc
		(start 366.042448 -236.88929)
		(mid 366.199425 -237.19409)
		(end 366.042448 -237.49889)
		(width 0.1143)
		(layer "In11.Cu")
		(net "P5E_CPU0_G3_RX_DP<9>")
	)
	(arc
		(start 366.912652 -222.959676)
		(mid 366.669325 -223.424242)
		(end 366.912652 -223.888808)
		(width 0.1143)
		(layer "In11.Cu")
		(net "P5E_CPU0_G3_RX_DP<9>")
	)
	(arc
		(start 365.03356 -245.639082)
		(mid 365.033179 -245.639336)
		(end 365.032798 -245.63959)
		(width 0.1143)
		(layer "In11.Cu")
		(net "P5E_CPU0_G3_RX_DP<9>")
	)
	(arc
		(start 366.982502 -223.929448)
		(mid 367.139479 -224.234248)
		(end 366.982502 -224.539048)
		(width 0.1143)
		(layer "In11.Cu")
		(net "P5E_CPU0_G3_RX_DP<9>")
	)
	(arc
		(start 365.972852 -227.819712)
		(mid 365.729525 -228.284278)
		(end 365.972852 -228.748844)
		(width 0.1143)
		(layer "In11.Cu")
		(net "P5E_CPU0_G3_RX_DP<9>")
	)
	(arc
		(start 365.972852 -229.43947)
		(mid 365.794039 -229.64182)
		(end 365.72952 -229.904036)
		(width 0.1143)
		(layer "In11.Cu")
		(net "P5E_CPU0_G3_RX_DP<9>")
	)
	(arc
		(start 366.669574 -225.044254)
		(mid 366.628319 -225.215225)
		(end 366.513618 -225.348546)
		(width 0.1143)
		(layer "In11.Cu")
		(net "P5E_CPU0_G3_RX_DP<9>")
	)
	(arc
		(start 366.042448 -232.029254)
		(mid 366.199425 -232.334054)
		(end 366.042448 -232.638854)
		(width 0.1143)
		(layer "In11.Cu")
		(net "P5E_CPU0_G3_RX_DP<9>")
	)
	(arc
		(start 366.19942 -230.714296)
		(mid 366.158454 -230.884702)
		(end 366.04448 -231.017826)
		(width 0.1143)
		(layer "In11.Cu")
		(net "P5E_CPU0_G3_RX_DP<9>")
	)
	(arc
		(start 366.042448 -235.269278)
		(mid 366.199425 -235.574078)
		(end 366.042448 -235.878878)
		(width 0.1143)
		(layer "In11.Cu")
		(net "P5E_CPU0_G3_RX_DP<9>")
	)
	(segment
		(start 406.386538 -5.229606)
		(end 406.386538 -7.569454)
		(width 0.12954)
		(layer "F.Cu")
		(net "P5E_CPU0_G3_RX_DP<8>")
	)
	(segment
		(start 366.767872 -247.990106)
		(end 367.234724 -247.724168)
		(width 0.12954)
		(layer "F.Cu")
		(net "P5E_CPU0_G3_RX_DP<8>")
	)
	(segment
		(start 406.386538 -7.569454)
		(end 406.246838 -7.709154)
		(width 0.12954)
		(layer "F.Cu")
		(net "P5E_CPU0_G3_RX_DP<8>")
	)
	(segment
		(start 406.246838 -7.709154)
		(end 406.246838 -8.320024)
		(width 0.12954)
		(layer "F.Cu")
		(net "P5E_CPU0_G3_RX_DP<8>")
	)
	(segment
		(start 406.120346 -4.963414)
		(end 406.386538 -5.229606)
		(width 0.12954)
		(layer "F.Cu")
		(net "P5E_CPU0_G3_RX_DP<8>")
	)
	(segment
		(start 366.947704 -239.138968)
		(end 366.94618 -239.139984)
		(width 0.1143)
		(layer "In11.Cu")
		(net "P5E_CPU0_G3_RX_DP<8>")
	)
	(segment
		(start 366.949228 -232.00995)
		(end 366.950752 -232.010966)
		(width 0.1143)
		(layer "In11.Cu")
		(net "P5E_CPU0_G3_RX_DP<8>")
	)
	(segment
		(start 366.947704 -235.898944)
		(end 366.94618 -235.89996)
		(width 0.1143)
		(layer "In11.Cu")
		(net "P5E_CPU0_G3_RX_DP<8>")
	)
	(segment
		(start 312.38825 -162.184334)
		(end 314.190888 -166.537132)
		(width 0.14224)
		(layer "In11.Cu")
		(net "P5E_CPU0_G3_RX_DP<8>")
	)
	(segment
		(start 366.947704 -234.278932)
		(end 366.94618 -234.279948)
		(width 0.1143)
		(layer "In11.Cu")
		(net "P5E_CPU0_G3_RX_DP<8>")
	)
	(segment
		(start 367.923572 -224.53854)
		(end 367.891822 -224.556828)
		(width 0.1143)
		(layer "In11.Cu")
		(net "P5E_CPU0_G3_RX_DP<8>")
	)
	(segment
		(start 366.951768 -236.87151)
		(end 366.95253 -236.872018)
		(width 0.1143)
		(layer "In11.Cu")
		(net "P5E_CPU0_G3_RX_DP<8>")
	)
	(segment
		(start 367.382806 -247.378728)
		(end 367.452402 -247.419368)
		(width 0.1143)
		(layer "In11.Cu")
		(net "P5E_CPU0_G3_RX_DP<8>")
	)
	(segment
		(start 366.95253 -243.352066)
		(end 366.983518 -243.369846)
		(width 0.1143)
		(layer "In11.Cu")
		(net "P5E_CPU0_G3_RX_DP<8>")
	)
	(segment
		(start 408.84348 -17.708626)
		(end 408.799538 -17.815052)
		(width 0.14224)
		(layer "In11.Cu")
		(net "P5E_CPU0_G3_RX_DP<8>")
	)
	(segment
		(start 366.94618 -239.139984)
		(end 366.945164 -239.140492)
		(width 0.1143)
		(layer "In11.Cu")
		(net "P5E_CPU0_G3_RX_DP<8>")
	)
	(segment
		(start 366.950752 -243.997226)
		(end 366.947704 -243.999004)
		(width 0.1143)
		(layer "In11.Cu")
		(net "P5E_CPU0_G3_RX_DP<8>")
	)
	(segment
		(start 402.92528 -26.748232)
		(end 323.482208 -126.729744)
		(width 0.14224)
		(layer "In11.Cu")
		(net "P5E_CPU0_G3_RX_DP<8>")
	)
	(segment
		(start 366.949228 -240.11001)
		(end 366.950752 -240.111026)
		(width 0.1143)
		(layer "In11.Cu")
		(net "P5E_CPU0_G3_RX_DP<8>")
	)
	(segment
		(start 367.453418 -225.348546)
		(end 367.4237 -225.365564)
		(width 0.1143)
		(layer "In11.Cu")
		(net "P5E_CPU0_G3_RX_DP<8>")
	)
	(segment
		(start 366.95253 -244.972078)
		(end 366.983518 -244.989858)
		(width 0.1143)
		(layer "In11.Cu")
		(net "P5E_CPU0_G3_RX_DP<8>")
	)
	(segment
		(start 366.985296 -229.397052)
		(end 366.951768 -229.41661)
		(width 0.1143)
		(layer "In11.Cu")
		(net "P5E_CPU0_G3_RX_DP<8>")
	)
	(segment
		(start 366.669574 -229.904036)
		(end 366.66932 -229.904036)
		(width 0.1143)
		(layer "In11.Cu")
		(net "P5E_CPU0_G3_RX_DP<8>")
	)
	(segment
		(start 367.598452 -214.452962)
		(end 367.598452 -221.054676)
		(width 0.14224)
		(layer "In11.Cu")
		(net "P5E_CPU0_G3_RX_DP<8>")
	)
	(segment
		(start 366.95253 -234.276138)
		(end 366.951768 -234.276646)
		(width 0.1143)
		(layer "In11.Cu")
		(net "P5E_CPU0_G3_RX_DP<8>")
	)
	(segment
		(start 366.983518 -240.738406)
		(end 366.95253 -240.756186)
		(width 0.1143)
		(layer "In11.Cu")
		(net "P5E_CPU0_G3_RX_DP<8>")
	)
	(segment
		(start 366.945164 -239.140492)
		(end 366.94364 -239.141508)
		(width 0.1143)
		(layer "In11.Cu")
		(net "P5E_CPU0_G3_RX_DP<8>")
	)
	(segment
		(start 324.359524 -174.253652)
		(end 362.087922 -205.172056)
		(width 0.14224)
		(layer "In11.Cu")
		(net "P5E_CPU0_G3_RX_DP<8>")
	)
	(segment
		(start 366.951768 -240.111534)
		(end 366.95253 -240.112042)
		(width 0.1143)
		(layer "In11.Cu")
		(net "P5E_CPU0_G3_RX_DP<8>")
	)
	(segment
		(start 366.95253 -243.99621)
		(end 366.951768 -243.996718)
		(width 0.1143)
		(layer "In11.Cu")
		(net "P5E_CPU0_G3_RX_DP<8>")
	)
	(segment
		(start 366.951768 -244.97157)
		(end 366.95253 -244.972078)
		(width 0.1143)
		(layer "In11.Cu")
		(net "P5E_CPU0_G3_RX_DP<8>")
	)
	(segment
		(start 366.950752 -233.630978)
		(end 366.951768 -233.631486)
		(width 0.1143)
		(layer "In11.Cu")
		(net "P5E_CPU0_G3_RX_DP<8>")
	)
	(segment
		(start 366.951768 -240.756694)
		(end 366.950752 -240.757202)
		(width 0.1143)
		(layer "In11.Cu")
		(net "P5E_CPU0_G3_RX_DP<8>")
	)
	(segment
		(start 406.411176 -5.254244)
		(end 406.411176 -11.572748)
		(width 0.14224)
		(layer "In11.Cu")
		(net "P5E_CPU0_G3_RX_DP<8>")
	)
	(segment
		(start 366.951768 -232.011474)
		(end 366.95253 -232.011982)
		(width 0.1143)
		(layer "In11.Cu")
		(net "P5E_CPU0_G3_RX_DP<8>")
	)
	(segment
		(start 366.912652 -243.328698)
		(end 366.949228 -243.350034)
		(width 0.1143)
		(layer "In11.Cu")
		(net "P5E_CPU0_G3_RX_DP<8>")
	)
	(segment
		(start 366.94618 -244.00002)
		(end 366.945164 -244.000528)
		(width 0.1143)
		(layer "In11.Cu")
		(net "P5E_CPU0_G3_RX_DP<8>")
	)
	(segment
		(start 362.087922 -205.172056)
		(end 367.598452 -214.452962)
		(width 0.14224)
		(layer "In11.Cu")
		(net "P5E_CPU0_G3_RX_DP<8>")
	)
	(segment
		(start 366.949228 -243.350034)
		(end 366.950752 -243.35105)
		(width 0.1143)
		(layer "In11.Cu")
		(net "P5E_CPU0_G3_RX_DP<8>")
	)
	(segment
		(start 366.950752 -234.277154)
		(end 366.947704 -234.278932)
		(width 0.1143)
		(layer "In11.Cu")
		(net "P5E_CPU0_G3_RX_DP<8>")
	)
	(segment
		(start 367.892584 -223.912176)
		(end 367.893854 -223.912938)
		(width 0.1143)
		(layer "In11.Cu")
		(net "P5E_CPU0_G3_RX_DP<8>")
	)
	(segment
		(start 366.95253 -235.89615)
		(end 366.951768 -235.896658)
		(width 0.1143)
		(layer "In11.Cu")
		(net "P5E_CPU0_G3_RX_DP<8>")
	)
	(segment
		(start 407.46807 -14.193012)
		(end 408.84348 -17.517364)
		(width 0.14224)
		(layer "In11.Cu")
		(net "P5E_CPU0_G3_RX_DP<8>")
	)
	(segment
		(start 366.983518 -243.97843)
		(end 366.95253 -243.99621)
		(width 0.1143)
		(layer "In11.Cu")
		(net "P5E_CPU0_G3_RX_DP<8>")
	)
	(segment
		(start 318.025018 -170.372024)
		(end 323.900546 -173.895004)
		(width 0.14224)
		(layer "In11.Cu")
		(net "P5E_CPU0_G3_RX_DP<8>")
	)
	(segment
		(start 366.950752 -235.25099)
		(end 366.951768 -235.251498)
		(width 0.1143)
		(layer "In11.Cu")
		(net "P5E_CPU0_G3_RX_DP<8>")
	)
	(segment
		(start 366.950752 -236.871002)
		(end 366.951768 -236.87151)
		(width 0.1143)
		(layer "In11.Cu")
		(net "P5E_CPU0_G3_RX_DP<8>")
	)
	(segment
		(start 366.94364 -240.76152)
		(end 366.912652 -240.779554)
		(width 0.1143)
		(layer "In11.Cu")
		(net "P5E_CPU0_G3_RX_DP<8>")
	)
	(segment
		(start 366.912652 -241.708686)
		(end 366.949228 -241.730022)
		(width 0.1143)
		(layer "In11.Cu")
		(net "P5E_CPU0_G3_RX_DP<8>")
	)
	(segment
		(start 366.912652 -233.608626)
		(end 366.949228 -233.629962)
		(width 0.1143)
		(layer "In11.Cu")
		(net "P5E_CPU0_G3_RX_DP<8>")
	)
	(segment
		(start 367.891822 -224.556828)
		(end 367.8555 -224.577656)
		(width 0.1143)
		(layer "In11.Cu")
		(net "P5E_CPU0_G3_RX_DP<8>")
	)
	(segment
		(start 366.950752 -240.757202)
		(end 366.947704 -240.75898)
		(width 0.1143)
		(layer "In11.Cu")
		(net "P5E_CPU0_G3_RX_DP<8>")
	)
	(segment
		(start 366.950752 -244.971062)
		(end 366.951768 -244.97157)
		(width 0.1143)
		(layer "In11.Cu")
		(net "P5E_CPU0_G3_RX_DP<8>")
	)
	(segment
		(start 367.890806 -223.91116)
		(end 367.891822 -223.911668)
		(width 0.1143)
		(layer "In11.Cu")
		(net "P5E_CPU0_G3_RX_DP<8>")
	)
	(segment
		(start 366.947704 -243.999004)
		(end 366.94618 -244.00002)
		(width 0.1143)
		(layer "In11.Cu")
		(net "P5E_CPU0_G3_RX_DP<8>")
	)
	(segment
		(start 367.609374 -221.658942)
		(end 367.609374 -221.80423)
		(width 0.1143)
		(layer "In11.Cu")
		(net "P5E_CPU0_G3_RX_DP<8>")
	)
	(segment
		(start 367.60912 -221.343474)
		(end 367.60912 -221.658688)
		(width 0.1143)
		(layer "In11.Cu")
		(net "P5E_CPU0_G3_RX_DP<8>")
	)
	(segment
		(start 366.945164 -232.660444)
		(end 366.94364 -232.66146)
		(width 0.1143)
		(layer "In11.Cu")
		(net "P5E_CPU0_G3_RX_DP<8>")
	)
	(segment
		(start 408.799538 -17.815052)
		(end 408.497786 -18.378678)
		(width 0.14224)
		(layer "In11.Cu")
		(net "P5E_CPU0_G3_RX_DP<8>")
	)
	(segment
		(start 366.95253 -232.011982)
		(end 366.983518 -232.029762)
		(width 0.1143)
		(layer "In11.Cu")
		(net "P5E_CPU0_G3_RX_DP<8>")
	)
	(segment
		(start 366.951768 -242.376706)
		(end 366.950752 -242.377214)
		(width 0.1143)
		(layer "In11.Cu")
		(net "P5E_CPU0_G3_RX_DP<8>")
	)
	(segment
		(start 366.951768 -230.391716)
		(end 366.983518 -230.410004)
		(width 0.1143)
		(layer "In11.Cu")
		(net "P5E_CPU0_G3_RX_DP<8>")
	)
	(segment
		(start 366.94618 -235.89996)
		(end 366.945164 -235.900468)
		(width 0.1143)
		(layer "In11.Cu")
		(net "P5E_CPU0_G3_RX_DP<8>")
	)
	(segment
		(start 366.9538 -245.61546)
		(end 366.95253 -245.616222)
		(width 0.1143)
		(layer "In11.Cu")
		(net "P5E_CPU0_G3_RX_DP<8>")
	)
	(segment
		(start 366.947704 -232.65892)
		(end 366.94618 -232.659936)
		(width 0.1143)
		(layer "In11.Cu")
		(net "P5E_CPU0_G3_RX_DP<8>")
	)
	(segment
		(start 366.983518 -245.598442)
		(end 366.9538 -245.61546)
		(width 0.1143)
		(layer "In11.Cu")
		(net "P5E_CPU0_G3_RX_DP<8>")
	)
	(segment
		(start 366.951768 -239.136682)
		(end 366.950752 -239.13719)
		(width 0.1143)
		(layer "In11.Cu")
		(net "P5E_CPU0_G3_RX_DP<8>")
	)
	(segment
		(start 366.912652 -231.988614)
		(end 366.949228 -232.00995)
		(width 0.1143)
		(layer "In11.Cu")
		(net "P5E_CPU0_G3_RX_DP<8>")
	)
	(segment
		(start 366.94364 -244.001544)
		(end 366.912652 -244.019578)
		(width 0.1143)
		(layer "In11.Cu")
		(net "P5E_CPU0_G3_RX_DP<8>")
	)
	(segment
		(start 366.95253 -237.516162)
		(end 366.951768 -237.51667)
		(width 0.1143)
		(layer "In11.Cu")
		(net "P5E_CPU0_G3_RX_DP<8>")
	)
	(segment
		(start 314.465462 -148.892514)
		(end 312.38825 -160.716214)
		(width 0.14224)
		(layer "In11.Cu")
		(net "P5E_CPU0_G3_RX_DP<8>")
	)
	(segment
		(start 367.8555 -224.577656)
		(end 367.852706 -224.579688)
		(width 0.1143)
		(layer "In11.Cu")
		(net "P5E_CPU0_G3_RX_DP<8>")
	)
	(segment
		(start 366.912652 -246.568722)
		(end 366.949228 -246.590058)
		(width 0.1143)
		(layer "In11.Cu")
		(net "P5E_CPU0_G3_RX_DP<8>")
	)
	(segment
		(start 367.855246 -222.270574)
		(end 367.891568 -222.291656)
		(width 0.1143)
		(layer "In11.Cu")
		(net "P5E_CPU0_G3_RX_DP<8>")
	)
	(segment
		(start 367.598452 -221.054676)
		(end 367.598452 -221.083124)
		(width 0.1143)
		(layer "In11.Cu")
		(net "P5E_CPU0_G3_RX_DP<8>")
	)
	(segment
		(start 366.983518 -234.258358)
		(end 366.95253 -234.276138)
		(width 0.1143)
		(layer "In11.Cu")
		(net "P5E_CPU0_G3_RX_DP<8>")
	)
	(segment
		(start 366.983518 -232.638346)
		(end 366.95253 -232.656126)
		(width 0.1143)
		(layer "In11.Cu")
		(net "P5E_CPU0_G3_RX_DP<8>")
	)
	(segment
		(start 366.951768 -234.276646)
		(end 366.950752 -234.277154)
		(width 0.1143)
		(layer "In11.Cu")
		(net "P5E_CPU0_G3_RX_DP<8>")
	)
	(segment
		(start 366.982248 -226.15906)
		(end 366.912652 -226.1997)
		(width 0.1143)
		(layer "In11.Cu")
		(net "P5E_CPU0_G3_RX_DP<8>")
	)
	(segment
		(start 366.95253 -232.656126)
		(end 366.951768 -232.656634)
		(width 0.1143)
		(layer "In11.Cu")
		(net "P5E_CPU0_G3_RX_DP<8>")
	)
	(segment
		(start 366.951768 -246.591582)
		(end 366.95253 -246.59209)
		(width 0.1143)
		(layer "In11.Cu")
		(net "P5E_CPU0_G3_RX_DP<8>")
	)
	(segment
		(start 367.38941 -225.38563)
		(end 367.382552 -225.389694)
		(width 0.1143)
		(layer "In11.Cu")
		(net "P5E_CPU0_G3_RX_DP<8>")
	)
	(segment
		(start 366.912652 -238.468662)
		(end 366.949228 -238.489998)
		(width 0.1143)
		(layer "In11.Cu")
		(net "P5E_CPU0_G3_RX_DP<8>")
	)
	(segment
		(start 366.94364 -239.141508)
		(end 366.912652 -239.159542)
		(width 0.1143)
		(layer "In11.Cu")
		(net "P5E_CPU0_G3_RX_DP<8>")
	)
	(segment
		(start 366.95253 -239.136174)
		(end 366.951768 -239.136682)
		(width 0.1143)
		(layer "In11.Cu")
		(net "P5E_CPU0_G3_RX_DP<8>")
	)
	(segment
		(start 366.945164 -234.280456)
		(end 366.94364 -234.281472)
		(width 0.1143)
		(layer "In11.Cu")
		(net "P5E_CPU0_G3_RX_DP<8>")
	)
	(segment
		(start 366.945164 -240.760504)
		(end 366.94364 -240.76152)
		(width 0.1143)
		(layer "In11.Cu")
		(net "P5E_CPU0_G3_RX_DP<8>")
	)
	(segment
		(start 367.893854 -223.912938)
		(end 367.923572 -223.929956)
		(width 0.1143)
		(layer "In11.Cu")
		(net "P5E_CPU0_G3_RX_DP<8>")
	)
	(segment
		(start 366.94364 -235.901484)
		(end 366.912652 -235.919518)
		(width 0.1143)
		(layer "In11.Cu")
		(net "P5E_CPU0_G3_RX_DP<8>")
	)
	(segment
		(start 366.951768 -229.41661)
		(end 366.915446 -229.437692)
		(width 0.1143)
		(layer "In11.Cu")
		(net "P5E_CPU0_G3_RX_DP<8>")
	)
	(segment
		(start 367.899696 -222.93199)
		(end 367.85423 -222.95866)
		(width 0.1143)
		(layer "In11.Cu")
		(net "P5E_CPU0_G3_RX_DP<8>")
	)
	(segment
		(start 366.950752 -243.35105)
		(end 366.951768 -243.351558)
		(width 0.1143)
		(layer "In11.Cu")
		(net "P5E_CPU0_G3_RX_DP<8>")
	)
	(segment
		(start 367.891822 -223.911668)
		(end 367.892584 -223.912176)
		(width 0.1143)
		(layer "In11.Cu")
		(net "P5E_CPU0_G3_RX_DP<8>")
	)
	(segment
		(start 366.94618 -240.759996)
		(end 366.945164 -240.760504)
		(width 0.1143)
		(layer "In11.Cu")
		(net "P5E_CPU0_G3_RX_DP<8>")
	)
	(segment
		(start 366.912652 -235.228638)
		(end 366.949228 -235.249974)
		(width 0.1143)
		(layer "In11.Cu")
		(net "P5E_CPU0_G3_RX_DP<8>")
	)
	(segment
		(start 366.951768 -238.491522)
		(end 366.983518 -238.50981)
		(width 0.1143)
		(layer "In11.Cu")
		(net "P5E_CPU0_G3_RX_DP<8>")
	)
	(segment
		(start 367.852706 -223.888808)
		(end 367.890806 -223.91116)
		(width 0.1143)
		(layer "In11.Cu")
		(net "P5E_CPU0_G3_RX_DP<8>")
	)
	(segment
		(start 366.912652 -227.128832)
		(end 366.982248 -227.169472)
		(width 0.1143)
		(layer "In11.Cu")
		(net "P5E_CPU0_G3_RX_DP<8>")
	)
	(segment
		(start 366.915192 -230.37038)
		(end 366.951768 -230.391716)
		(width 0.1143)
		(layer "In11.Cu")
		(net "P5E_CPU0_G3_RX_DP<8>")
	)
	(segment
		(start 408.84348 -17.517364)
		(end 408.84348 -17.708626)
		(width 0.14224)
		(layer "In11.Cu")
		(net "P5E_CPU0_G3_RX_DP<8>")
	)
	(segment
		(start 366.94618 -232.659936)
		(end 366.945164 -232.660444)
		(width 0.1143)
		(layer "In11.Cu")
		(net "P5E_CPU0_G3_RX_DP<8>")
	)
	(segment
		(start 324.130416 -174.074582)
		(end 324.130416 -174.074836)
		(width 0.14224)
		(layer "In11.Cu")
		(net "P5E_CPU0_G3_RX_DP<8>")
	)
	(segment
		(start 366.983518 -235.87837)
		(end 366.95253 -235.89615)
		(width 0.1143)
		(layer "In11.Cu")
		(net "P5E_CPU0_G3_RX_DP<8>")
	)
	(segment
		(start 366.95253 -233.631994)
		(end 366.983518 -233.649774)
		(width 0.1143)
		(layer "In11.Cu")
		(net "P5E_CPU0_G3_RX_DP<8>")
	)
	(segment
		(start 324.130416 -174.074836)
		(end 324.359524 -174.253652)
		(width 0.14224)
		(layer "In11.Cu")
		(net "P5E_CPU0_G3_RX_DP<8>")
	)
	(segment
		(start 367.532666 -247.724168)
		(end 367.234724 -247.724168)
		(width 0.1143)
		(layer "In11.Cu")
		(net "P5E_CPU0_G3_RX_DP<8>")
	)
	(segment
		(start 320.68516 -131.734814)
		(end 314.465462 -148.892514)
		(width 0.14224)
		(layer "In11.Cu")
		(net "P5E_CPU0_G3_RX_DP<8>")
	)
	(segment
		(start 366.951768 -243.351558)
		(end 366.95253 -243.352066)
		(width 0.1143)
		(layer "In11.Cu")
		(net "P5E_CPU0_G3_RX_DP<8>")
	)
	(segment
		(start 366.95253 -240.112042)
		(end 366.983518 -240.129822)
		(width 0.1143)
		(layer "In11.Cu")
		(net "P5E_CPU0_G3_RX_DP<8>")
	)
	(segment
		(start 367.60912 -221.658688)
		(end 367.609374 -221.658942)
		(width 0.1143)
		(layer "In11.Cu")
		(net "P5E_CPU0_G3_RX_DP<8>")
	)
	(segment
		(start 366.951768 -241.731546)
		(end 366.95253 -241.732054)
		(width 0.1143)
		(layer "In11.Cu")
		(net "P5E_CPU0_G3_RX_DP<8>")
	)
	(segment
		(start 366.983518 -239.118394)
		(end 366.95253 -239.136174)
		(width 0.1143)
		(layer "In11.Cu")
		(net "P5E_CPU0_G3_RX_DP<8>")
	)
	(segment
		(start 366.94618 -234.279948)
		(end 366.945164 -234.280456)
		(width 0.1143)
		(layer "In11.Cu")
		(net "P5E_CPU0_G3_RX_DP<8>")
	)
	(segment
		(start 366.950752 -242.377214)
		(end 366.912652 -242.399566)
		(width 0.1143)
		(layer "In11.Cu")
		(net "P5E_CPU0_G3_RX_DP<8>")
	)
	(segment
		(start 366.950752 -232.010966)
		(end 366.951768 -232.011474)
		(width 0.1143)
		(layer "In11.Cu")
		(net "P5E_CPU0_G3_RX_DP<8>")
	)
	(segment
		(start 323.482208 -126.729744)
		(end 320.68516 -131.734814)
		(width 0.14224)
		(layer "In11.Cu")
		(net "P5E_CPU0_G3_RX_DP<8>")
	)
	(segment
		(start 366.94364 -234.281472)
		(end 366.912652 -234.299506)
		(width 0.1143)
		(layer "In11.Cu")
		(net "P5E_CPU0_G3_RX_DP<8>")
	)
	(segment
		(start 366.949228 -244.970046)
		(end 366.950752 -244.971062)
		(width 0.1143)
		(layer "In11.Cu")
		(net "P5E_CPU0_G3_RX_DP<8>")
	)
	(segment
		(start 366.949228 -246.590058)
		(end 366.950752 -246.591074)
		(width 0.1143)
		(layer "In11.Cu")
		(net "P5E_CPU0_G3_RX_DP<8>")
	)
	(segment
		(start 366.950752 -232.657142)
		(end 366.947704 -232.65892)
		(width 0.1143)
		(layer "In11.Cu")
		(net "P5E_CPU0_G3_RX_DP<8>")
	)
	(segment
		(start 366.912652 -244.94871)
		(end 366.949228 -244.970046)
		(width 0.1143)
		(layer "In11.Cu")
		(net "P5E_CPU0_G3_RX_DP<8>")
	)
	(segment
		(start 367.390172 -225.385122)
		(end 367.38941 -225.38563)
		(width 0.1143)
		(layer "In11.Cu")
		(net "P5E_CPU0_G3_RX_DP<8>")
	)
	(segment
		(start 366.945164 -244.000528)
		(end 366.94364 -244.001544)
		(width 0.1143)
		(layer "In11.Cu")
		(net "P5E_CPU0_G3_RX_DP<8>")
	)
	(segment
		(start 408.497786 -18.378678)
		(end 402.92528 -26.748232)
		(width 0.14224)
		(layer "In11.Cu")
		(net "P5E_CPU0_G3_RX_DP<8>")
	)
	(segment
		(start 366.951768 -233.631486)
		(end 366.95253 -233.631994)
		(width 0.1143)
		(layer "In11.Cu")
		(net "P5E_CPU0_G3_RX_DP<8>")
	)
	(segment
		(start 366.95253 -241.732054)
		(end 366.983518 -241.749834)
		(width 0.1143)
		(layer "In11.Cu")
		(net "P5E_CPU0_G3_RX_DP<8>")
	)
	(segment
		(start 367.598452 -221.083124)
		(end 367.644172 -221.128844)
		(width 0.1143)
		(layer "In11.Cu")
		(net "P5E_CPU0_G3_RX_DP<8>")
	)
	(segment
		(start 366.915446 -228.750876)
		(end 366.951768 -228.771704)
		(width 0.1143)
		(layer "In11.Cu")
		(net "P5E_CPU0_G3_RX_DP<8>")
	)
	(segment
		(start 323.900546 -173.895004)
		(end 324.130416 -174.074582)
		(width 0.14224)
		(layer "In11.Cu")
		(net "P5E_CPU0_G3_RX_DP<8>")
	)
	(segment
		(start 366.94364 -232.66146)
		(end 366.912652 -232.679494)
		(width 0.1143)
		(layer "In11.Cu")
		(net "P5E_CPU0_G3_RX_DP<8>")
	)
	(segment
		(start 366.947704 -240.75898)
		(end 366.94618 -240.759996)
		(width 0.1143)
		(layer "In11.Cu")
		(net "P5E_CPU0_G3_RX_DP<8>")
	)
	(segment
		(start 367.42243 -225.366326)
		(end 367.421668 -225.366834)
		(width 0.1143)
		(layer "In11.Cu")
		(net "P5E_CPU0_G3_RX_DP<8>")
	)
	(segment
		(start 366.95253 -240.756186)
		(end 366.951768 -240.756694)
		(width 0.1143)
		(layer "In11.Cu")
		(net "P5E_CPU0_G3_RX_DP<8>")
	)
	(segment
		(start 366.951768 -228.771704)
		(end 366.983518 -228.789992)
		(width 0.1143)
		(layer "In11.Cu")
		(net "P5E_CPU0_G3_RX_DP<8>")
	)
	(segment
		(start 366.951768 -235.896658)
		(end 366.950752 -235.897166)
		(width 0.1143)
		(layer "In11.Cu")
		(net "P5E_CPU0_G3_RX_DP<8>")
	)
	(segment
		(start 366.9538 -242.375436)
		(end 366.95253 -242.376198)
		(width 0.1143)
		(layer "In11.Cu")
		(net "P5E_CPU0_G3_RX_DP<8>")
	)
	(segment
		(start 366.95253 -235.252006)
		(end 366.983518 -235.269786)
		(width 0.1143)
		(layer "In11.Cu")
		(net "P5E_CPU0_G3_RX_DP<8>")
	)
	(segment
		(start 366.950752 -237.517178)
		(end 366.912652 -237.53953)
		(width 0.1143)
		(layer "In11.Cu")
		(net "P5E_CPU0_G3_RX_DP<8>")
	)
	(segment
		(start 366.950752 -245.617238)
		(end 366.912652 -245.63959)
		(width 0.1143)
		(layer "In11.Cu")
		(net "P5E_CPU0_G3_RX_DP<8>")
	)
	(segment
		(start 366.950752 -246.591074)
		(end 366.951768 -246.591582)
		(width 0.1143)
		(layer "In11.Cu")
		(net "P5E_CPU0_G3_RX_DP<8>")
	)
	(segment
		(start 366.912652 -228.748844)
		(end 366.915446 -228.750876)
		(width 0.1143)
		(layer "In11.Cu")
		(net "P5E_CPU0_G3_RX_DP<8>")
	)
	(segment
		(start 366.949228 -241.730022)
		(end 366.950752 -241.731038)
		(width 0.1143)
		(layer "In11.Cu")
		(net "P5E_CPU0_G3_RX_DP<8>")
	)
	(segment
		(start 366.950752 -238.491014)
		(end 366.951768 -238.491522)
		(width 0.1143)
		(layer "In11.Cu")
		(net "P5E_CPU0_G3_RX_DP<8>")
	)
	(segment
		(start 366.945164 -235.900468)
		(end 366.94364 -235.901484)
		(width 0.1143)
		(layer "In11.Cu")
		(net "P5E_CPU0_G3_RX_DP<8>")
	)
	(segment
		(start 314.190888 -166.537132)
		(end 318.025018 -170.372024)
		(width 0.14224)
		(layer "In11.Cu")
		(net "P5E_CPU0_G3_RX_DP<8>")
	)
	(segment
		(start 366.9538 -237.5154)
		(end 366.95253 -237.516162)
		(width 0.1143)
		(layer "In11.Cu")
		(net "P5E_CPU0_G3_RX_DP<8>")
	)
	(segment
		(start 366.985296 -231.017064)
		(end 366.912652 -231.059482)
		(width 0.1143)
		(layer "In11.Cu")
		(net "P5E_CPU0_G3_RX_DP<8>")
	)
	(segment
		(start 366.95253 -245.616222)
		(end 366.951768 -245.61673)
		(width 0.1143)
		(layer "In11.Cu")
		(net "P5E_CPU0_G3_RX_DP<8>")
	)
	(segment
		(start 406.411176 -11.572748)
		(end 406.737312 -12.648438)
		(width 0.14224)
		(layer "In11.Cu")
		(net "P5E_CPU0_G3_RX_DP<8>")
	)
	(segment
		(start 367.602516 -247.654318)
		(end 367.532666 -247.724168)
		(width 0.1143)
		(layer "In11.Cu")
		(net "P5E_CPU0_G3_RX_DP<8>")
	)
	(segment
		(start 366.912652 -240.088674)
		(end 366.949228 -240.11001)
		(width 0.1143)
		(layer "In11.Cu")
		(net "P5E_CPU0_G3_RX_DP<8>")
	)
	(segment
		(start 406.120346 -4.963414)
		(end 406.411176 -5.254244)
		(width 0.14224)
		(layer "In11.Cu")
		(net "P5E_CPU0_G3_RX_DP<8>")
	)
	(segment
		(start 366.950752 -241.731038)
		(end 366.951768 -241.731546)
		(width 0.1143)
		(layer "In11.Cu")
		(net "P5E_CPU0_G3_RX_DP<8>")
	)
	(segment
		(start 366.949228 -235.249974)
		(end 366.950752 -235.25099)
		(width 0.1143)
		(layer "In11.Cu")
		(net "P5E_CPU0_G3_RX_DP<8>")
	)
	(segment
		(start 366.951768 -232.656634)
		(end 366.950752 -232.657142)
		(width 0.1143)
		(layer "In11.Cu")
		(net "P5E_CPU0_G3_RX_DP<8>")
	)
	(segment
		(start 406.737312 -12.648438)
		(end 407.46807 -14.193012)
		(width 0.14224)
		(layer "In11.Cu")
		(net "P5E_CPU0_G3_RX_DP<8>")
	)
	(segment
		(start 366.951768 -235.251498)
		(end 366.95253 -235.252006)
		(width 0.1143)
		(layer "In11.Cu")
		(net "P5E_CPU0_G3_RX_DP<8>")
	)
	(segment
		(start 366.950752 -240.111026)
		(end 366.951768 -240.111534)
		(width 0.1143)
		(layer "In11.Cu")
		(net "P5E_CPU0_G3_RX_DP<8>")
	)
	(segment
		(start 366.950752 -235.897166)
		(end 366.947704 -235.898944)
		(width 0.1143)
		(layer "In11.Cu")
		(net "P5E_CPU0_G3_RX_DP<8>")
	)
	(segment
		(start 366.95253 -236.872018)
		(end 366.983518 -236.889798)
		(width 0.1143)
		(layer "In11.Cu")
		(net "P5E_CPU0_G3_RX_DP<8>")
	)
	(segment
		(start 366.95253 -242.376198)
		(end 366.951768 -242.376706)
		(width 0.1143)
		(layer "In11.Cu")
		(net "P5E_CPU0_G3_RX_DP<8>")
	)
	(segment
		(start 366.982248 -227.779072)
		(end 366.912652 -227.819712)
		(width 0.1143)
		(layer "In11.Cu")
		(net "P5E_CPU0_G3_RX_DP<8>")
	)
	(segment
		(start 312.38825 -160.716214)
		(end 312.38825 -162.184334)
		(width 0.14224)
		(layer "In11.Cu")
		(net "P5E_CPU0_G3_RX_DP<8>")
	)
	(segment
		(start 366.950752 -239.13719)
		(end 366.947704 -239.138968)
		(width 0.1143)
		(layer "In11.Cu")
		(net "P5E_CPU0_G3_RX_DP<8>")
	)
	(segment
		(start 367.644172 -221.308422)
		(end 367.60912 -221.343474)
		(width 0.1143)
		(layer "In11.Cu")
		(net "P5E_CPU0_G3_RX_DP<8>")
	)
	(segment
		(start 366.949228 -233.629962)
		(end 366.950752 -233.630978)
		(width 0.1143)
		(layer "In11.Cu")
		(net "P5E_CPU0_G3_RX_DP<8>")
	)
	(segment
		(start 366.949228 -236.869986)
		(end 366.950752 -236.871002)
		(width 0.1143)
		(layer "In11.Cu")
		(net "P5E_CPU0_G3_RX_DP<8>")
	)
	(segment
		(start 366.951768 -243.996718)
		(end 366.950752 -243.997226)
		(width 0.1143)
		(layer "In11.Cu")
		(net "P5E_CPU0_G3_RX_DP<8>")
	)
	(segment
		(start 367.421668 -225.366834)
		(end 367.390172 -225.385122)
		(width 0.1143)
		(layer "In11.Cu")
		(net "P5E_CPU0_G3_RX_DP<8>")
	)
	(segment
		(start 367.4237 -225.365564)
		(end 367.42243 -225.366326)
		(width 0.1143)
		(layer "In11.Cu")
		(net "P5E_CPU0_G3_RX_DP<8>")
	)
	(segment
		(start 366.95253 -246.59209)
		(end 366.983518 -246.60987)
		(width 0.1143)
		(layer "In11.Cu")
		(net "P5E_CPU0_G3_RX_DP<8>")
	)
	(segment
		(start 366.983518 -237.498382)
		(end 366.9538 -237.5154)
		(width 0.1143)
		(layer "In11.Cu")
		(net "P5E_CPU0_G3_RX_DP<8>")
	)
	(segment
		(start 366.912652 -236.84865)
		(end 366.949228 -236.869986)
		(width 0.1143)
		(layer "In11.Cu")
		(net "P5E_CPU0_G3_RX_DP<8>")
	)
	(segment
		(start 366.983518 -242.358418)
		(end 366.9538 -242.375436)
		(width 0.1143)
		(layer "In11.Cu")
		(net "P5E_CPU0_G3_RX_DP<8>")
	)
	(segment
		(start 366.951768 -237.51667)
		(end 366.950752 -237.517178)
		(width 0.1143)
		(layer "In11.Cu")
		(net "P5E_CPU0_G3_RX_DP<8>")
	)
	(segment
		(start 367.644172 -221.128844)
		(end 367.644172 -221.308422)
		(width 0.1143)
		(layer "In11.Cu")
		(net "P5E_CPU0_G3_RX_DP<8>")
	)
	(segment
		(start 366.949228 -238.489998)
		(end 366.950752 -238.491014)
		(width 0.1143)
		(layer "In11.Cu")
		(net "P5E_CPU0_G3_RX_DP<8>")
	)
	(segment
		(start 366.951768 -245.61673)
		(end 366.950752 -245.617238)
		(width 0.1143)
		(layer "In11.Cu")
		(net "P5E_CPU0_G3_RX_DP<8>")
	)
	(arc
		(start 366.912652 -239.159542)
		(mid 366.669325 -239.624108)
		(end 366.912652 -240.088674)
		(width 0.1143)
		(layer "In11.Cu")
		(net "P5E_CPU0_G3_RX_DP<8>")
	)
	(arc
		(start 366.912652 -240.779554)
		(mid 366.669325 -241.24412)
		(end 366.912652 -241.708686)
		(width 0.1143)
		(layer "In11.Cu")
		(net "P5E_CPU0_G3_RX_DP<8>")
	)
	(arc
		(start 367.609374 -221.808548)
		(mid 367.673351 -222.061178)
		(end 367.841022 -222.260668)
		(width 0.1143)
		(layer "In11.Cu")
		(net "P5E_CPU0_G3_RX_DP<8>")
	)
	(arc
		(start 366.982248 -227.169472)
		(mid 367.139225 -227.474272)
		(end 366.982248 -227.779072)
		(width 0.1143)
		(layer "In11.Cu")
		(net "P5E_CPU0_G3_RX_DP<8>")
	)
	(arc
		(start 366.983518 -240.129822)
		(mid 367.139446 -240.434114)
		(end 366.983518 -240.738406)
		(width 0.1143)
		(layer "In11.Cu")
		(net "P5E_CPU0_G3_RX_DP<8>")
	)
	(arc
		(start 367.382552 -225.389694)
		(mid 367.203739 -225.592044)
		(end 367.13922 -225.85426)
		(width 0.1143)
		(layer "In11.Cu")
		(net "P5E_CPU0_G3_RX_DP<8>")
	)
	(arc
		(start 367.609374 -221.80423)
		(mid 367.609369 -221.806389)
		(end 367.609374 -221.808548)
		(width 0.1143)
		(layer "In11.Cu")
		(net "P5E_CPU0_G3_RX_DP<8>")
	)
	(arc
		(start 366.983518 -241.749834)
		(mid 367.139446 -242.054126)
		(end 366.983518 -242.358418)
		(width 0.1143)
		(layer "In11.Cu")
		(net "P5E_CPU0_G3_RX_DP<8>")
	)
	(arc
		(start 367.852706 -224.579688)
		(mid 367.673893 -224.782038)
		(end 367.609374 -225.044254)
		(width 0.1143)
		(layer "In11.Cu")
		(net "P5E_CPU0_G3_RX_DP<8>")
	)
	(arc
		(start 366.912652 -231.059482)
		(mid 366.669325 -231.524048)
		(end 366.912652 -231.988614)
		(width 0.1143)
		(layer "In11.Cu")
		(net "P5E_CPU0_G3_RX_DP<8>")
	)
	(arc
		(start 366.983518 -244.989858)
		(mid 367.139446 -245.29415)
		(end 366.983518 -245.598442)
		(width 0.1143)
		(layer "In11.Cu")
		(net "P5E_CPU0_G3_RX_DP<8>")
	)
	(arc
		(start 366.912652 -242.399566)
		(mid 366.669325 -242.864132)
		(end 366.912652 -243.328698)
		(width 0.1143)
		(layer "In11.Cu")
		(net "P5E_CPU0_G3_RX_DP<8>")
	)
	(arc
		(start 366.983518 -232.029762)
		(mid 367.139446 -232.334054)
		(end 366.983518 -232.638346)
		(width 0.1143)
		(layer "In11.Cu")
		(net "P5E_CPU0_G3_RX_DP<8>")
	)
	(arc
		(start 367.139474 -229.094284)
		(mid 367.098712 -229.264168)
		(end 366.985296 -229.397052)
		(width 0.1143)
		(layer "In11.Cu")
		(net "P5E_CPU0_G3_RX_DP<8>")
	)
	(arc
		(start 367.13922 -225.85426)
		(mid 367.097671 -226.025682)
		(end 366.982248 -226.15906)
		(width 0.1143)
		(layer "In11.Cu")
		(net "P5E_CPU0_G3_RX_DP<8>")
	)
	(arc
		(start 366.912652 -235.919518)
		(mid 366.669325 -236.384084)
		(end 366.912652 -236.84865)
		(width 0.1143)
		(layer "In11.Cu")
		(net "P5E_CPU0_G3_RX_DP<8>")
	)
	(arc
		(start 366.912652 -237.53953)
		(mid 366.669325 -238.004096)
		(end 366.912652 -238.468662)
		(width 0.1143)
		(layer "In11.Cu")
		(net "P5E_CPU0_G3_RX_DP<8>")
	)
	(arc
		(start 366.983518 -238.50981)
		(mid 367.139446 -238.814102)
		(end 366.983518 -239.118394)
		(width 0.1143)
		(layer "In11.Cu")
		(net "P5E_CPU0_G3_RX_DP<8>")
	)
	(arc
		(start 367.452402 -247.419368)
		(mid 367.550167 -247.522344)
		(end 367.602516 -247.654318)
		(width 0.1143)
		(layer "In11.Cu")
		(net "P5E_CPU0_G3_RX_DP<8>")
	)
	(arc
		(start 366.983518 -243.369846)
		(mid 367.139446 -243.674138)
		(end 366.983518 -243.97843)
		(width 0.1143)
		(layer "In11.Cu")
		(net "P5E_CPU0_G3_RX_DP<8>")
	)
	(arc
		(start 366.983518 -230.410004)
		(mid 367.098194 -230.543338)
		(end 367.139474 -230.714296)
		(width 0.1143)
		(layer "In11.Cu")
		(net "P5E_CPU0_G3_RX_DP<8>")
	)
	(arc
		(start 367.841022 -222.260668)
		(mid 367.848095 -222.265677)
		(end 367.855246 -222.270574)
		(width 0.1143)
		(layer "In11.Cu")
		(net "P5E_CPU0_G3_RX_DP<8>")
	)
	(arc
		(start 367.891568 -222.291656)
		(mid 368.076546 -222.60951)
		(end 367.899696 -222.93199)
		(width 0.1143)
		(layer "In11.Cu")
		(net "P5E_CPU0_G3_RX_DP<8>")
	)
	(arc
		(start 367.923572 -223.929956)
		(mid 368.0795 -224.234248)
		(end 367.923572 -224.53854)
		(width 0.1143)
		(layer "In11.Cu")
		(net "P5E_CPU0_G3_RX_DP<8>")
	)
	(arc
		(start 366.983518 -236.889798)
		(mid 367.139446 -237.19409)
		(end 366.983518 -237.498382)
		(width 0.1143)
		(layer "In11.Cu")
		(net "P5E_CPU0_G3_RX_DP<8>")
	)
	(arc
		(start 366.983518 -246.60987)
		(mid 367.098194 -246.743204)
		(end 367.139474 -246.914162)
		(width 0.1143)
		(layer "In11.Cu")
		(net "P5E_CPU0_G3_RX_DP<8>")
	)
	(arc
		(start 366.983518 -228.789992)
		(mid 367.098194 -228.923326)
		(end 367.139474 -229.094284)
		(width 0.1143)
		(layer "In11.Cu")
		(net "P5E_CPU0_G3_RX_DP<8>")
	)
	(arc
		(start 367.139474 -246.914162)
		(mid 367.203989 -247.176381)
		(end 367.382806 -247.378728)
		(width 0.1143)
		(layer "In11.Cu")
		(net "P5E_CPU0_G3_RX_DP<8>")
	)
	(arc
		(start 367.852706 -222.959676)
		(mid 367.609379 -223.424242)
		(end 367.852706 -223.888808)
		(width 0.1143)
		(layer "In11.Cu")
		(net "P5E_CPU0_G3_RX_DP<8>")
	)
	(arc
		(start 367.609374 -225.044254)
		(mid 367.568119 -225.215225)
		(end 367.453418 -225.348546)
		(width 0.1143)
		(layer "In11.Cu")
		(net "P5E_CPU0_G3_RX_DP<8>")
	)
	(arc
		(start 366.912652 -226.1997)
		(mid 366.669325 -226.664266)
		(end 366.912652 -227.128832)
		(width 0.1143)
		(layer "In11.Cu")
		(net "P5E_CPU0_G3_RX_DP<8>")
	)
	(arc
		(start 366.912652 -227.819712)
		(mid 366.669325 -228.284278)
		(end 366.912652 -228.748844)
		(width 0.1143)
		(layer "In11.Cu")
		(net "P5E_CPU0_G3_RX_DP<8>")
	)
	(arc
		(start 366.912652 -245.63959)
		(mid 366.669325 -246.104156)
		(end 366.912652 -246.568722)
		(width 0.1143)
		(layer "In11.Cu")
		(net "P5E_CPU0_G3_RX_DP<8>")
	)
	(arc
		(start 366.912652 -244.019578)
		(mid 366.669325 -244.484144)
		(end 366.912652 -244.94871)
		(width 0.1143)
		(layer "In11.Cu")
		(net "P5E_CPU0_G3_RX_DP<8>")
	)
	(arc
		(start 366.912652 -234.299506)
		(mid 366.669325 -234.764072)
		(end 366.912652 -235.228638)
		(width 0.1143)
		(layer "In11.Cu")
		(net "P5E_CPU0_G3_RX_DP<8>")
	)
	(arc
		(start 366.915446 -229.437692)
		(mid 366.734794 -229.640437)
		(end 366.669574 -229.904036)
		(width 0.1143)
		(layer "In11.Cu")
		(net "P5E_CPU0_G3_RX_DP<8>")
	)
	(arc
		(start 367.139474 -230.714296)
		(mid 367.098712 -230.88418)
		(end 366.985296 -231.017064)
		(width 0.1143)
		(layer "In11.Cu")
		(net "P5E_CPU0_G3_RX_DP<8>")
	)
	(arc
		(start 366.912652 -232.679494)
		(mid 366.669325 -233.14406)
		(end 366.912652 -233.608626)
		(width 0.1143)
		(layer "In11.Cu")
		(net "P5E_CPU0_G3_RX_DP<8>")
	)
	(arc
		(start 366.983518 -235.269786)
		(mid 367.139446 -235.574078)
		(end 366.983518 -235.87837)
		(width 0.1143)
		(layer "In11.Cu")
		(net "P5E_CPU0_G3_RX_DP<8>")
	)
	(arc
		(start 367.85423 -222.95866)
		(mid 367.853468 -222.959167)
		(end 367.852706 -222.959676)
		(width 0.1143)
		(layer "In11.Cu")
		(net "P5E_CPU0_G3_RX_DP<8>")
	)
	(arc
		(start 366.983518 -233.649774)
		(mid 367.139446 -233.954066)
		(end 366.983518 -234.258358)
		(width 0.1143)
		(layer "In11.Cu")
		(net "P5E_CPU0_G3_RX_DP<8>")
	)
	(arc
		(start 366.66932 -229.904036)
		(mid 366.734556 -230.167627)
		(end 366.915192 -230.37038)
		(width 0.1143)
		(layer "In11.Cu")
		(net "P5E_CPU0_G3_RX_DP<8>")
	)
	(segment
		(start 413.695642 -6.99516)
		(end 413.42564 -6.725158)
		(width 0.12954)
		(layer "F.Cu")
		(net "P5E_CPU0_G3_RX_DP<7>")
	)
	(segment
		(start 413.556958 -7.709154)
		(end 413.695642 -7.57047)
		(width 0.12954)
		(layer "F.Cu")
		(net "P5E_CPU0_G3_RX_DP<7>")
	)
	(segment
		(start 413.695642 -7.57047)
		(end 413.695642 -6.99516)
		(width 0.12954)
		(layer "F.Cu")
		(net "P5E_CPU0_G3_RX_DP<7>")
	)
	(segment
		(start 413.556958 -8.320024)
		(end 413.556958 -7.709154)
		(width 0.12954)
		(layer "F.Cu")
		(net "P5E_CPU0_G3_RX_DP<7>")
	)
	(segment
		(start 366.767872 -244.750082)
		(end 367.234724 -244.484144)
		(width 0.12954)
		(layer "F.Cu")
		(net "P5E_CPU0_G3_RX_DP<7>")
	)
	(segment
		(start 367.889282 -232.00995)
		(end 367.890806 -232.010966)
		(width 0.1143)
		(layer "In11.Cu")
		(net "P5E_CPU0_G3_RX_DP<7>")
	)
	(segment
		(start 367.890806 -243.35105)
		(end 367.891822 -243.351558)
		(width 0.1143)
		(layer "In11.Cu")
		(net "P5E_CPU0_G3_RX_DP<7>")
	)
	(segment
		(start 367.87074 -240.099342)
		(end 367.870994 -240.099342)
		(width 0.1143)
		(layer "In11.Cu")
		(net "P5E_CPU0_G3_RX_DP<7>")
	)
	(segment
		(start 367.892584 -232.011982)
		(end 367.923572 -232.029762)
		(width 0.1143)
		(layer "In11.Cu")
		(net "P5E_CPU0_G3_RX_DP<7>")
	)
	(segment
		(start 367.86058 -235.914692)
		(end 367.859818 -235.9152)
		(width 0.1143)
		(layer "In11.Cu")
		(net "P5E_CPU0_G3_RX_DP<7>")
	)
	(segment
		(start 367.891822 -232.656634)
		(end 367.890806 -232.657142)
		(width 0.1143)
		(layer "In11.Cu")
		(net "P5E_CPU0_G3_RX_DP<7>")
	)
	(segment
		(start 411.618684 -19.286474)
		(end 409.71216 -22.02307)
		(width 0.14224)
		(layer "In11.Cu")
		(net "P5E_CPU0_G3_RX_DP<7>")
	)
	(segment
		(start 410.919676 -17.500346)
		(end 410.919676 -17.765014)
		(width 0.14224)
		(layer "In11.Cu")
		(net "P5E_CPU0_G3_RX_DP<7>")
	)
	(segment
		(start 411.618684 -18.963132)
		(end 411.618684 -19.286474)
		(width 0.14224)
		(layer "In11.Cu")
		(net "P5E_CPU0_G3_RX_DP<7>")
	)
	(segment
		(start 367.87074 -238.47933)
		(end 367.870994 -238.47933)
		(width 0.1143)
		(layer "In11.Cu")
		(net "P5E_CPU0_G3_RX_DP<7>")
	)
	(segment
		(start 367.899696 -242.372134)
		(end 367.88725 -242.379246)
		(width 0.1143)
		(layer "In11.Cu")
		(net "P5E_CPU0_G3_RX_DP<7>")
	)
	(segment
		(start 369.309904 -222.122238)
		(end 369.302538 -222.126302)
		(width 0.1143)
		(layer "In11.Cu")
		(net "P5E_CPU0_G3_RX_DP<7>")
	)
	(segment
		(start 369.333526 -222.108522)
		(end 369.309904 -222.122238)
		(width 0.1143)
		(layer "In11.Cu")
		(net "P5E_CPU0_G3_RX_DP<7>")
	)
	(segment
		(start 367.88217 -228.766116)
		(end 367.883694 -228.767132)
		(width 0.1143)
		(layer "In11.Cu")
		(net "P5E_CPU0_G3_RX_DP<7>")
	)
	(segment
		(start 367.890806 -232.657142)
		(end 367.852706 -232.679494)
		(width 0.1143)
		(layer "In11.Cu")
		(net "P5E_CPU0_G3_RX_DP<7>")
	)
	(segment
		(start 313.32043 -161.998406)
		(end 314.981082 -166.008558)
		(width 0.14224)
		(layer "In11.Cu")
		(net "P5E_CPU0_G3_RX_DP<7>")
	)
	(segment
		(start 367.886488 -237.519718)
		(end 367.885472 -237.520226)
		(width 0.1143)
		(layer "In11.Cu")
		(net "P5E_CPU0_G3_RX_DP<7>")
	)
	(segment
		(start 367.88725 -239.139222)
		(end 367.886488 -239.13973)
		(width 0.1143)
		(layer "In11.Cu")
		(net "P5E_CPU0_G3_RX_DP<7>")
	)
	(segment
		(start 367.886488 -242.379754)
		(end 367.885472 -242.380262)
		(width 0.1143)
		(layer "In11.Cu")
		(net "P5E_CPU0_G3_RX_DP<7>")
	)
	(segment
		(start 368.621818 -214.323676)
		(end 369.443762 -220.881956)
		(width 0.14224)
		(layer "In11.Cu")
		(net "P5E_CPU0_G3_RX_DP<7>")
	)
	(segment
		(start 367.870994 -235.239306)
		(end 367.89233 -235.251752)
		(width 0.1143)
		(layer "In11.Cu")
		(net "P5E_CPU0_G3_RX_DP<7>")
	)
	(segment
		(start 368.79276 -223.888808)
		(end 368.862356 -223.929448)
		(width 0.1143)
		(layer "In11.Cu")
		(net "P5E_CPU0_G3_RX_DP<7>")
	)
	(segment
		(start 369.489482 -221.128844)
		(end 369.489482 -221.80423)
		(width 0.1143)
		(layer "In11.Cu")
		(net "P5E_CPU0_G3_RX_DP<7>")
	)
	(segment
		(start 413.236664 -13.4112)
		(end 411.264862 -16.362426)
		(width 0.14224)
		(layer "In11.Cu")
		(net "P5E_CPU0_G3_RX_DP<7>")
	)
	(segment
		(start 367.890806 -230.391208)
		(end 367.891822 -230.391716)
		(width 0.1143)
		(layer "In11.Cu")
		(net "P5E_CPU0_G3_RX_DP<7>")
	)
	(segment
		(start 321.311778 -171.25569)
		(end 322.204334 -171.746164)
		(width 0.14224)
		(layer "In11.Cu")
		(net "P5E_CPU0_G3_RX_DP<7>")
	)
	(segment
		(start 367.895378 -230.393748)
		(end 367.923572 -230.410004)
		(width 0.1143)
		(layer "In11.Cu")
		(net "P5E_CPU0_G3_RX_DP<7>")
	)
	(segment
		(start 367.888774 -235.898436)
		(end 367.88725 -235.899198)
		(width 0.1143)
		(layer "In11.Cu")
		(net "P5E_CPU0_G3_RX_DP<7>")
	)
	(segment
		(start 367.923572 -227.778564)
		(end 367.892584 -227.796344)
		(width 0.1143)
		(layer "In11.Cu")
		(net "P5E_CPU0_G3_RX_DP<7>")
	)
	(segment
		(start 367.889282 -243.350034)
		(end 367.890806 -243.35105)
		(width 0.1143)
		(layer "In11.Cu")
		(net "P5E_CPU0_G3_RX_DP<7>")
	)
	(segment
		(start 411.264862 -16.362426)
		(end 410.919676 -17.500346)
		(width 0.14224)
		(layer "In11.Cu")
		(net "P5E_CPU0_G3_RX_DP<7>")
	)
	(segment
		(start 367.888266 -232.009442)
		(end 367.889282 -232.00995)
		(width 0.1143)
		(layer "In11.Cu")
		(net "P5E_CPU0_G3_RX_DP<7>")
	)
	(segment
		(start 368.361722 -225.366834)
		(end 368.359944 -225.36785)
		(width 0.1143)
		(layer "In11.Cu")
		(net "P5E_CPU0_G3_RX_DP<7>")
	)
	(segment
		(start 367.852706 -238.468662)
		(end 367.87074 -238.47933)
		(width 0.1143)
		(layer "In11.Cu")
		(net "P5E_CPU0_G3_RX_DP<7>")
	)
	(segment
		(start 367.892584 -230.392224)
		(end 367.893854 -230.392986)
		(width 0.1143)
		(layer "In11.Cu")
		(net "P5E_CPU0_G3_RX_DP<7>")
	)
	(segment
		(start 367.899696 -237.512098)
		(end 367.88725 -237.51921)
		(width 0.1143)
		(layer "In11.Cu")
		(net "P5E_CPU0_G3_RX_DP<7>")
	)
	(segment
		(start 367.8555 -227.130864)
		(end 367.891822 -227.151692)
		(width 0.1143)
		(layer "In11.Cu")
		(net "P5E_CPU0_G3_RX_DP<7>")
	)
	(segment
		(start 367.885472 -240.76025)
		(end 367.853468 -240.779046)
		(width 0.1143)
		(layer "In11.Cu")
		(net "P5E_CPU0_G3_RX_DP<7>")
	)
	(segment
		(start 367.886488 -235.899706)
		(end 367.86058 -235.914692)
		(width 0.1143)
		(layer "In11.Cu")
		(net "P5E_CPU0_G3_RX_DP<7>")
	)
	(segment
		(start 369.30076 -222.127318)
		(end 369.26266 -222.14967)
		(width 0.1143)
		(layer "In11.Cu")
		(net "P5E_CPU0_G3_RX_DP<7>")
	)
	(segment
		(start 367.852706 -236.84865)
		(end 367.87074 -236.859318)
		(width 0.1143)
		(layer "In11.Cu")
		(net "P5E_CPU0_G3_RX_DP<7>")
	)
	(segment
		(start 367.852706 -228.748844)
		(end 367.88217 -228.766116)
		(width 0.1143)
		(layer "In11.Cu")
		(net "P5E_CPU0_G3_RX_DP<7>")
	)
	(segment
		(start 367.889282 -227.798376)
		(end 367.852706 -227.819712)
		(width 0.1143)
		(layer "In11.Cu")
		(net "P5E_CPU0_G3_RX_DP<7>")
	)
	(segment
		(start 367.891822 -232.011474)
		(end 367.892584 -232.011982)
		(width 0.1143)
		(layer "In11.Cu")
		(net "P5E_CPU0_G3_RX_DP<7>")
	)
	(segment
		(start 367.852706 -240.088674)
		(end 367.87074 -240.099342)
		(width 0.1143)
		(layer "In11.Cu")
		(net "P5E_CPU0_G3_RX_DP<7>")
	)
	(segment
		(start 367.899696 -239.13211)
		(end 367.88725 -239.139222)
		(width 0.1143)
		(layer "In11.Cu")
		(net "P5E_CPU0_G3_RX_DP<7>")
	)
	(segment
		(start 367.856262 -234.296966)
		(end 367.853468 -234.298998)
		(width 0.1143)
		(layer "In11.Cu")
		(net "P5E_CPU0_G3_RX_DP<7>")
	)
	(segment
		(start 367.890806 -228.771196)
		(end 367.891822 -228.771704)
		(width 0.1143)
		(layer "In11.Cu")
		(net "P5E_CPU0_G3_RX_DP<7>")
	)
	(segment
		(start 367.87074 -236.859318)
		(end 367.870994 -236.859318)
		(width 0.1143)
		(layer "In11.Cu")
		(net "P5E_CPU0_G3_RX_DP<7>")
	)
	(segment
		(start 410.990288 -17.935702)
		(end 411.225492 -18.375122)
		(width 0.14224)
		(layer "In11.Cu")
		(net "P5E_CPU0_G3_RX_DP<7>")
	)
	(segment
		(start 367.859818 -235.9152)
		(end 367.853468 -235.91901)
		(width 0.1143)
		(layer "In11.Cu")
		(net "P5E_CPU0_G3_RX_DP<7>")
	)
	(segment
		(start 367.885472 -239.140238)
		(end 367.853468 -239.159034)
		(width 0.1143)
		(layer "In11.Cu")
		(net "P5E_CPU0_G3_RX_DP<7>")
	)
	(segment
		(start 324.63486 -173.252892)
		(end 362.755942 -204.47)
		(width 0.14224)
		(layer "In11.Cu")
		(net "P5E_CPU0_G3_RX_DP<7>")
	)
	(segment
		(start 313.32043 -160.79851)
		(end 313.32043 -161.998406)
		(width 0.14224)
		(layer "In11.Cu")
		(net "P5E_CPU0_G3_RX_DP<7>")
	)
	(segment
		(start 411.225492 -18.375122)
		(end 411.618684 -18.963132)
		(width 0.14224)
		(layer "In11.Cu")
		(net "P5E_CPU0_G3_RX_DP<7>")
	)
	(segment
		(start 413.71647 -11.564874)
		(end 413.716216 -11.565128)
		(width 0.14224)
		(layer "In11.Cu")
		(net "P5E_CPU0_G3_RX_DP<7>")
	)
	(segment
		(start 367.88725 -240.759234)
		(end 367.886488 -240.759742)
		(width 0.1143)
		(layer "In11.Cu")
		(net "P5E_CPU0_G3_RX_DP<7>")
	)
	(segment
		(start 367.923572 -234.258358)
		(end 367.891822 -234.276646)
		(width 0.1143)
		(layer "In11.Cu")
		(net "P5E_CPU0_G3_RX_DP<7>")
	)
	(segment
		(start 367.88725 -235.899198)
		(end 367.886488 -235.899706)
		(width 0.1143)
		(layer "In11.Cu")
		(net "P5E_CPU0_G3_RX_DP<7>")
	)
	(segment
		(start 367.870994 -240.099342)
		(end 367.89233 -240.111788)
		(width 0.1143)
		(layer "In11.Cu")
		(net "P5E_CPU0_G3_RX_DP<7>")
	)
	(segment
		(start 367.893854 -230.392986)
		(end 367.895378 -230.393748)
		(width 0.1143)
		(layer "In11.Cu")
		(net "P5E_CPU0_G3_RX_DP<7>")
	)
	(segment
		(start 369.302538 -222.126302)
		(end 369.301776 -222.12681)
		(width 0.1143)
		(layer "In11.Cu")
		(net "P5E_CPU0_G3_RX_DP<7>")
	)
	(segment
		(start 367.923572 -232.638346)
		(end 367.892584 -232.656126)
		(width 0.1143)
		(layer "In11.Cu")
		(net "P5E_CPU0_G3_RX_DP<7>")
	)
	(segment
		(start 369.443762 -221.083124)
		(end 369.489482 -221.128844)
		(width 0.1143)
		(layer "In11.Cu")
		(net "P5E_CPU0_G3_RX_DP<7>")
	)
	(segment
		(start 367.891822 -227.151692)
		(end 367.923572 -227.16998)
		(width 0.1143)
		(layer "In11.Cu")
		(net "P5E_CPU0_G3_RX_DP<7>")
	)
	(segment
		(start 367.892584 -228.772212)
		(end 367.893092 -228.772466)
		(width 0.1143)
		(layer "In11.Cu")
		(net "P5E_CPU0_G3_RX_DP<7>")
	)
	(segment
		(start 367.88725 -237.51921)
		(end 367.886488 -237.519718)
		(width 0.1143)
		(layer "In11.Cu")
		(net "P5E_CPU0_G3_RX_DP<7>")
	)
	(segment
		(start 367.883694 -228.767132)
		(end 367.889282 -228.77018)
		(width 0.1143)
		(layer "In11.Cu")
		(net "P5E_CPU0_G3_RX_DP<7>")
	)
	(segment
		(start 367.889282 -233.629962)
		(end 367.890806 -233.630978)
		(width 0.1143)
		(layer "In11.Cu")
		(net "P5E_CPU0_G3_RX_DP<7>")
	)
	(segment
		(start 368.862356 -224.539048)
		(end 368.79276 -224.579688)
		(width 0.1143)
		(layer "In11.Cu")
		(net "P5E_CPU0_G3_RX_DP<7>")
	)
	(segment
		(start 367.899696 -240.752122)
		(end 367.88725 -240.759234)
		(width 0.1143)
		(layer "In11.Cu")
		(net "P5E_CPU0_G3_RX_DP<7>")
	)
	(segment
		(start 413.716216 -11.565128)
		(end 413.453072 -12.888214)
		(width 0.14224)
		(layer "In11.Cu")
		(net "P5E_CPU0_G3_RX_DP<7>")
	)
	(segment
		(start 367.852706 -231.988614)
		(end 367.888266 -232.009442)
		(width 0.1143)
		(layer "In11.Cu")
		(net "P5E_CPU0_G3_RX_DP<7>")
	)
	(segment
		(start 362.755942 -204.47)
		(end 368.621818 -214.323676)
		(width 0.14224)
		(layer "In11.Cu")
		(net "P5E_CPU0_G3_RX_DP<7>")
	)
	(segment
		(start 368.862356 -222.919036)
		(end 368.79276 -222.959676)
		(width 0.1143)
		(layer "In11.Cu")
		(net "P5E_CPU0_G3_RX_DP<7>")
	)
	(segment
		(start 410.919676 -17.765014)
		(end 410.990288 -17.935702)
		(width 0.14224)
		(layer "In11.Cu")
		(net "P5E_CPU0_G3_RX_DP<7>")
	)
	(segment
		(start 367.855246 -230.37038)
		(end 367.890806 -230.391208)
		(width 0.1143)
		(layer "In11.Cu")
		(net "P5E_CPU0_G3_RX_DP<7>")
	)
	(segment
		(start 367.889282 -243.998242)
		(end 367.852706 -244.019578)
		(width 0.1143)
		(layer "In11.Cu")
		(net "P5E_CPU0_G3_RX_DP<7>")
	)
	(segment
		(start 367.87074 -241.719354)
		(end 367.870994 -241.719354)
		(width 0.1143)
		(layer "In11.Cu")
		(net "P5E_CPU0_G3_RX_DP<7>")
	)
	(segment
		(start 367.891822 -243.996718)
		(end 367.890806 -243.997226)
		(width 0.1143)
		(layer "In11.Cu")
		(net "P5E_CPU0_G3_RX_DP<7>")
	)
	(segment
		(start 367.886488 -239.13973)
		(end 367.885472 -239.140238)
		(width 0.1143)
		(layer "In11.Cu")
		(net "P5E_CPU0_G3_RX_DP<7>")
	)
	(segment
		(start 367.892584 -233.631994)
		(end 367.923572 -233.649774)
		(width 0.1143)
		(layer "In11.Cu")
		(net "P5E_CPU0_G3_RX_DP<7>")
	)
	(segment
		(start 367.532666 -244.484144)
		(end 367.234724 -244.484144)
		(width 0.1143)
		(layer "In11.Cu")
		(net "P5E_CPU0_G3_RX_DP<7>")
	)
	(segment
		(start 367.852706 -235.228638)
		(end 367.87074 -235.239306)
		(width 0.1143)
		(layer "In11.Cu")
		(net "P5E_CPU0_G3_RX_DP<7>")
	)
	(segment
		(start 367.852706 -243.328698)
		(end 367.888266 -243.349526)
		(width 0.1143)
		(layer "In11.Cu")
		(net "P5E_CPU0_G3_RX_DP<7>")
	)
	(segment
		(start 367.87074 -235.239306)
		(end 367.870994 -235.239306)
		(width 0.1143)
		(layer "In11.Cu")
		(net "P5E_CPU0_G3_RX_DP<7>")
	)
	(segment
		(start 369.443762 -220.881956)
		(end 369.443762 -221.054676)
		(width 0.14224)
		(layer "In11.Cu")
		(net "P5E_CPU0_G3_RX_DP<7>")
	)
	(segment
		(start 367.92535 -229.397052)
		(end 367.852706 -229.43947)
		(width 0.1143)
		(layer "In11.Cu")
		(net "P5E_CPU0_G3_RX_DP<7>")
	)
	(segment
		(start 367.891822 -226.17684)
		(end 367.852706 -226.1997)
		(width 0.1143)
		(layer "In11.Cu")
		(net "P5E_CPU0_G3_RX_DP<7>")
	)
	(segment
		(start 367.890806 -227.79736)
		(end 367.889282 -227.798376)
		(width 0.1143)
		(layer "In11.Cu")
		(net "P5E_CPU0_G3_RX_DP<7>")
	)
	(segment
		(start 413.71647 -7.015988)
		(end 413.71647 -11.564874)
		(width 0.14224)
		(layer "In11.Cu")
		(net "P5E_CPU0_G3_RX_DP<7>")
	)
	(segment
		(start 318.185546 -169.214038)
		(end 321.311778 -171.25569)
		(width 0.14224)
		(layer "In11.Cu")
		(net "P5E_CPU0_G3_RX_DP<7>")
	)
	(segment
		(start 368.359944 -225.36785)
		(end 368.35842 -225.368866)
		(width 0.1143)
		(layer "In11.Cu")
		(net "P5E_CPU0_G3_RX_DP<7>")
	)
	(segment
		(start 413.453072 -12.888214)
		(end 413.236664 -13.4112)
		(width 0.14224)
		(layer "In11.Cu")
		(net "P5E_CPU0_G3_RX_DP<7>")
	)
	(segment
		(start 367.891822 -228.771704)
		(end 367.892584 -228.772212)
		(width 0.1143)
		(layer "In11.Cu")
		(net "P5E_CPU0_G3_RX_DP<7>")
	)
	(segment
		(start 367.890806 -232.010966)
		(end 367.891822 -232.011474)
		(width 0.1143)
		(layer "In11.Cu")
		(net "P5E_CPU0_G3_RX_DP<7>")
	)
	(segment
		(start 322.204334 -171.746164)
		(end 324.63486 -173.252892)
		(width 0.14224)
		(layer "In11.Cu")
		(net "P5E_CPU0_G3_RX_DP<7>")
	)
	(segment
		(start 367.922556 -226.15906)
		(end 367.891822 -226.17684)
		(width 0.1143)
		(layer "In11.Cu")
		(net "P5E_CPU0_G3_RX_DP<7>")
	)
	(segment
		(start 367.870994 -241.719354)
		(end 367.89233 -241.7318)
		(width 0.1143)
		(layer "In11.Cu")
		(net "P5E_CPU0_G3_RX_DP<7>")
	)
	(segment
		(start 367.870994 -238.47933)
		(end 367.89233 -238.491776)
		(width 0.1143)
		(layer "In11.Cu")
		(net "P5E_CPU0_G3_RX_DP<7>")
	)
	(segment
		(start 367.891822 -243.351558)
		(end 367.892584 -243.352066)
		(width 0.1143)
		(layer "In11.Cu")
		(net "P5E_CPU0_G3_RX_DP<7>")
	)
	(segment
		(start 367.852706 -233.608626)
		(end 367.888266 -233.629454)
		(width 0.1143)
		(layer "In11.Cu")
		(net "P5E_CPU0_G3_RX_DP<7>")
	)
	(segment
		(start 409.71216 -22.02307)
		(end 324.219824 -127.457708)
		(width 0.14224)
		(layer "In11.Cu")
		(net "P5E_CPU0_G3_RX_DP<7>")
	)
	(segment
		(start 369.443762 -221.054676)
		(end 369.443762 -221.083124)
		(width 0.1143)
		(layer "In11.Cu")
		(net "P5E_CPU0_G3_RX_DP<7>")
	)
	(segment
		(start 369.301776 -222.12681)
		(end 369.30076 -222.127318)
		(width 0.1143)
		(layer "In11.Cu")
		(net "P5E_CPU0_G3_RX_DP<7>")
	)
	(segment
		(start 367.885472 -237.520226)
		(end 367.853468 -237.539022)
		(width 0.1143)
		(layer "In11.Cu")
		(net "P5E_CPU0_G3_RX_DP<7>")
	)
	(segment
		(start 367.892584 -227.796344)
		(end 367.891822 -227.796852)
		(width 0.1143)
		(layer "In11.Cu")
		(net "P5E_CPU0_G3_RX_DP<7>")
	)
	(segment
		(start 367.88725 -242.379246)
		(end 367.886488 -242.379754)
		(width 0.1143)
		(layer "In11.Cu")
		(net "P5E_CPU0_G3_RX_DP<7>")
	)
	(segment
		(start 324.219824 -127.457708)
		(end 321.466972 -132.316982)
		(width 0.14224)
		(layer "In11.Cu")
		(net "P5E_CPU0_G3_RX_DP<7>")
	)
	(segment
		(start 367.891822 -227.796852)
		(end 367.890806 -227.79736)
		(width 0.1143)
		(layer "In11.Cu")
		(net "P5E_CPU0_G3_RX_DP<7>")
	)
	(segment
		(start 315.369956 -149.133052)
		(end 313.32043 -160.79851)
		(width 0.14224)
		(layer "In11.Cu")
		(net "P5E_CPU0_G3_RX_DP<7>")
	)
	(segment
		(start 367.889282 -228.77018)
		(end 367.890806 -228.771196)
		(width 0.1143)
		(layer "In11.Cu")
		(net "P5E_CPU0_G3_RX_DP<7>")
	)
	(segment
		(start 367.890806 -233.630978)
		(end 367.891822 -233.631486)
		(width 0.1143)
		(layer "In11.Cu")
		(net "P5E_CPU0_G3_RX_DP<7>")
	)
	(segment
		(start 321.466972 -132.316982)
		(end 315.369956 -149.133052)
		(width 0.14224)
		(layer "In11.Cu")
		(net "P5E_CPU0_G3_RX_DP<7>")
	)
	(segment
		(start 368.35842 -225.368866)
		(end 368.3254 -225.387916)
		(width 0.1143)
		(layer "In11.Cu")
		(net "P5E_CPU0_G3_RX_DP<7>")
	)
	(segment
		(start 367.886488 -240.759742)
		(end 367.885472 -240.76025)
		(width 0.1143)
		(layer "In11.Cu")
		(net "P5E_CPU0_G3_RX_DP<7>")
	)
	(segment
		(start 367.852706 -241.708686)
		(end 367.87074 -241.719354)
		(width 0.1143)
		(layer "In11.Cu")
		(net "P5E_CPU0_G3_RX_DP<7>")
	)
	(segment
		(start 367.885472 -242.380262)
		(end 367.853468 -242.399058)
		(width 0.1143)
		(layer "In11.Cu")
		(net "P5E_CPU0_G3_RX_DP<7>")
	)
	(segment
		(start 367.892584 -232.656126)
		(end 367.891822 -232.656634)
		(width 0.1143)
		(layer "In11.Cu")
		(net "P5E_CPU0_G3_RX_DP<7>")
	)
	(segment
		(start 367.901982 -231.03078)
		(end 367.852706 -231.059482)
		(width 0.1143)
		(layer "In11.Cu")
		(net "P5E_CPU0_G3_RX_DP<7>")
	)
	(segment
		(start 314.981082 -166.008558)
		(end 318.185546 -169.214038)
		(width 0.14224)
		(layer "In11.Cu")
		(net "P5E_CPU0_G3_RX_DP<7>")
	)
	(segment
		(start 367.892584 -243.99621)
		(end 367.891822 -243.996718)
		(width 0.1143)
		(layer "In11.Cu")
		(net "P5E_CPU0_G3_RX_DP<7>")
	)
	(segment
		(start 367.891822 -234.276646)
		(end 367.856262 -234.296966)
		(width 0.1143)
		(layer "In11.Cu")
		(net "P5E_CPU0_G3_RX_DP<7>")
	)
	(segment
		(start 367.890806 -243.997226)
		(end 367.889282 -243.998242)
		(width 0.1143)
		(layer "In11.Cu")
		(net "P5E_CPU0_G3_RX_DP<7>")
	)
	(segment
		(start 367.892584 -243.352066)
		(end 367.923572 -243.369846)
		(width 0.1143)
		(layer "In11.Cu")
		(net "P5E_CPU0_G3_RX_DP<7>")
	)
	(segment
		(start 367.852706 -227.128832)
		(end 367.8555 -227.130864)
		(width 0.1143)
		(layer "In11.Cu")
		(net "P5E_CPU0_G3_RX_DP<7>")
	)
	(segment
		(start 367.888266 -233.629454)
		(end 367.889282 -233.629962)
		(width 0.1143)
		(layer "In11.Cu")
		(net "P5E_CPU0_G3_RX_DP<7>")
	)
	(segment
		(start 367.61547 -244.40134)
		(end 367.532666 -244.484144)
		(width 0.1143)
		(layer "In11.Cu")
		(net "P5E_CPU0_G3_RX_DP<7>")
	)
	(segment
		(start 368.393472 -225.348546)
		(end 368.361722 -225.366834)
		(width 0.1143)
		(layer "In11.Cu")
		(net "P5E_CPU0_G3_RX_DP<7>")
	)
	(segment
		(start 367.888266 -243.349526)
		(end 367.889282 -243.350034)
		(width 0.1143)
		(layer "In11.Cu")
		(net "P5E_CPU0_G3_RX_DP<7>")
	)
	(segment
		(start 413.42564 -6.725158)
		(end 413.71647 -7.015988)
		(width 0.14224)
		(layer "In11.Cu")
		(net "P5E_CPU0_G3_RX_DP<7>")
	)
	(segment
		(start 367.891822 -233.631486)
		(end 367.892584 -233.631994)
		(width 0.1143)
		(layer "In11.Cu")
		(net "P5E_CPU0_G3_RX_DP<7>")
	)
	(segment
		(start 367.899696 -235.892086)
		(end 367.888774 -235.898436)
		(width 0.1143)
		(layer "In11.Cu")
		(net "P5E_CPU0_G3_RX_DP<7>")
	)
	(segment
		(start 367.870994 -236.859318)
		(end 367.89233 -236.871764)
		(width 0.1143)
		(layer "In11.Cu")
		(net "P5E_CPU0_G3_RX_DP<7>")
	)
	(segment
		(start 367.891822 -230.391716)
		(end 367.892584 -230.392224)
		(width 0.1143)
		(layer "In11.Cu")
		(net "P5E_CPU0_G3_RX_DP<7>")
	)
	(segment
		(start 367.923572 -243.97843)
		(end 367.892584 -243.99621)
		(width 0.1143)
		(layer "In11.Cu")
		(net "P5E_CPU0_G3_RX_DP<7>")
	)
	(arc
		(start 367.89233 -236.871764)
		(mid 368.07785 -237.189821)
		(end 367.899696 -237.512098)
		(width 0.1143)
		(layer "In11.Cu")
		(net "P5E_CPU0_G3_RX_DP<7>")
	)
	(arc
		(start 367.89233 -240.111788)
		(mid 368.07785 -240.429845)
		(end 367.899696 -240.752122)
		(width 0.1143)
		(layer "In11.Cu")
		(net "P5E_CPU0_G3_RX_DP<7>")
	)
	(arc
		(start 368.293904 -225.412554)
		(mid 368.161486 -225.585735)
		(end 368.087402 -225.79076)
		(width 0.1143)
		(layer "In11.Cu")
		(net "P5E_CPU0_G3_RX_DP<7>")
	)
	(arc
		(start 367.852706 -232.679494)
		(mid 367.609379 -233.14406)
		(end 367.852706 -233.608626)
		(width 0.1143)
		(layer "In11.Cu")
		(net "P5E_CPU0_G3_RX_DP<7>")
	)
	(arc
		(start 368.79276 -224.579688)
		(mid 368.613947 -224.782038)
		(end 368.549428 -225.044254)
		(width 0.1143)
		(layer "In11.Cu")
		(net "P5E_CPU0_G3_RX_DP<7>")
	)
	(arc
		(start 367.923572 -233.649774)
		(mid 368.075161 -233.954066)
		(end 367.923572 -234.258358)
		(width 0.1143)
		(layer "In11.Cu")
		(net "P5E_CPU0_G3_RX_DP<7>")
	)
	(arc
		(start 367.852706 -231.059482)
		(mid 367.609379 -231.524048)
		(end 367.852706 -231.988614)
		(width 0.1143)
		(layer "In11.Cu")
		(net "P5E_CPU0_G3_RX_DP<7>")
	)
	(arc
		(start 367.61928 -244.37848)
		(mid 367.617257 -244.38989)
		(end 367.61547 -244.40134)
		(width 0.1143)
		(layer "In11.Cu")
		(net "P5E_CPU0_G3_RX_DP<7>")
	)
	(arc
		(start 367.923572 -227.16998)
		(mid 368.072669 -227.474272)
		(end 367.923572 -227.778564)
		(width 0.1143)
		(layer "In11.Cu")
		(net "P5E_CPU0_G3_RX_DP<7>")
	)
	(arc
		(start 367.853468 -234.298998)
		(mid 367.853087 -234.299252)
		(end 367.852706 -234.299506)
		(width 0.1143)
		(layer "In11.Cu")
		(net "P5E_CPU0_G3_RX_DP<7>")
	)
	(arc
		(start 367.893092 -228.772466)
		(mid 368.02951 -228.908339)
		(end 368.079528 -229.094284)
		(width 0.1143)
		(layer "In11.Cu")
		(net "P5E_CPU0_G3_RX_DP<7>")
	)
	(arc
		(start 367.852706 -227.819712)
		(mid 367.609379 -228.284278)
		(end 367.852706 -228.748844)
		(width 0.1143)
		(layer "In11.Cu")
		(net "P5E_CPU0_G3_RX_DP<7>")
	)
	(arc
		(start 367.852706 -235.919518)
		(mid 367.609379 -236.384084)
		(end 367.852706 -236.84865)
		(width 0.1143)
		(layer "In11.Cu")
		(net "P5E_CPU0_G3_RX_DP<7>")
	)
	(arc
		(start 369.019328 -222.614236)
		(mid 368.977779 -222.785658)
		(end 368.862356 -222.919036)
		(width 0.1143)
		(layer "In11.Cu")
		(net "P5E_CPU0_G3_RX_DP<7>")
	)
	(arc
		(start 368.862356 -223.929448)
		(mid 369.019333 -224.234248)
		(end 368.862356 -224.539048)
		(width 0.1143)
		(layer "In11.Cu")
		(net "P5E_CPU0_G3_RX_DP<7>")
	)
	(arc
		(start 369.489482 -221.80423)
		(mid 369.448227 -221.975201)
		(end 369.333526 -222.108522)
		(width 0.1143)
		(layer "In11.Cu")
		(net "P5E_CPU0_G3_RX_DP<7>")
	)
	(arc
		(start 367.852706 -239.159542)
		(mid 367.609379 -239.624108)
		(end 367.852706 -240.088674)
		(width 0.1143)
		(layer "In11.Cu")
		(net "P5E_CPU0_G3_RX_DP<7>")
	)
	(arc
		(start 368.079528 -230.714296)
		(mid 368.033848 -230.896707)
		(end 367.901982 -231.03078)
		(width 0.1143)
		(layer "In11.Cu")
		(net "P5E_CPU0_G3_RX_DP<7>")
	)
	(arc
		(start 368.079528 -225.865436)
		(mid 368.035464 -226.030659)
		(end 367.922556 -226.15906)
		(width 0.1143)
		(layer "In11.Cu")
		(net "P5E_CPU0_G3_RX_DP<7>")
	)
	(arc
		(start 367.852706 -226.1997)
		(mid 367.609379 -226.664266)
		(end 367.852706 -227.128832)
		(width 0.1143)
		(layer "In11.Cu")
		(net "P5E_CPU0_G3_RX_DP<7>")
	)
	(arc
		(start 367.852706 -242.399566)
		(mid 367.609379 -242.864132)
		(end 367.852706 -243.328698)
		(width 0.1143)
		(layer "In11.Cu")
		(net "P5E_CPU0_G3_RX_DP<7>")
	)
	(arc
		(start 367.89233 -241.7318)
		(mid 368.07785 -242.049857)
		(end 367.899696 -242.372134)
		(width 0.1143)
		(layer "In11.Cu")
		(net "P5E_CPU0_G3_RX_DP<7>")
	)
	(arc
		(start 367.89233 -235.251752)
		(mid 368.07785 -235.569809)
		(end 367.899696 -235.892086)
		(width 0.1143)
		(layer "In11.Cu")
		(net "P5E_CPU0_G3_RX_DP<7>")
	)
	(arc
		(start 368.087402 -225.79076)
		(mid 368.081923 -225.827935)
		(end 368.079528 -225.865436)
		(width 0.1143)
		(layer "In11.Cu")
		(net "P5E_CPU0_G3_RX_DP<7>")
	)
	(arc
		(start 367.853468 -240.779046)
		(mid 367.853087 -240.7793)
		(end 367.852706 -240.779554)
		(width 0.1143)
		(layer "In11.Cu")
		(net "P5E_CPU0_G3_RX_DP<7>")
	)
	(arc
		(start 367.923572 -243.369846)
		(mid 368.072669 -243.674138)
		(end 367.923572 -243.97843)
		(width 0.1143)
		(layer "In11.Cu")
		(net "P5E_CPU0_G3_RX_DP<7>")
	)
	(arc
		(start 367.89233 -238.491776)
		(mid 368.07785 -238.809833)
		(end 367.899696 -239.13211)
		(width 0.1143)
		(layer "In11.Cu")
		(net "P5E_CPU0_G3_RX_DP<7>")
	)
	(arc
		(start 367.852706 -240.779554)
		(mid 367.609379 -241.24412)
		(end 367.852706 -241.708686)
		(width 0.1143)
		(layer "In11.Cu")
		(net "P5E_CPU0_G3_RX_DP<7>")
	)
	(arc
		(start 367.923572 -230.410004)
		(mid 368.036592 -230.54418)
		(end 368.079528 -230.714296)
		(width 0.1143)
		(layer "In11.Cu")
		(net "P5E_CPU0_G3_RX_DP<7>")
	)
	(arc
		(start 367.852706 -234.299506)
		(mid 367.609379 -234.764072)
		(end 367.852706 -235.228638)
		(width 0.1143)
		(layer "In11.Cu")
		(net "P5E_CPU0_G3_RX_DP<7>")
	)
	(arc
		(start 367.609374 -229.904036)
		(mid 367.67461 -230.167627)
		(end 367.855246 -230.37038)
		(width 0.1143)
		(layer "In11.Cu")
		(net "P5E_CPU0_G3_RX_DP<7>")
	)
	(arc
		(start 367.853468 -239.159034)
		(mid 367.853087 -239.159288)
		(end 367.852706 -239.159542)
		(width 0.1143)
		(layer "In11.Cu")
		(net "P5E_CPU0_G3_RX_DP<7>")
	)
	(arc
		(start 367.923572 -232.029762)
		(mid 368.072669 -232.334054)
		(end 367.923572 -232.638346)
		(width 0.1143)
		(layer "In11.Cu")
		(net "P5E_CPU0_G3_RX_DP<7>")
	)
	(arc
		(start 368.549428 -225.044254)
		(mid 368.508173 -225.215225)
		(end 368.393472 -225.348546)
		(width 0.1143)
		(layer "In11.Cu")
		(net "P5E_CPU0_G3_RX_DP<7>")
	)
	(arc
		(start 368.79276 -222.959676)
		(mid 368.549433 -223.424242)
		(end 368.79276 -223.888808)
		(width 0.1143)
		(layer "In11.Cu")
		(net "P5E_CPU0_G3_RX_DP<7>")
	)
	(arc
		(start 368.3254 -225.387916)
		(mid 368.309431 -225.399953)
		(end 368.293904 -225.412554)
		(width 0.1143)
		(layer "In11.Cu")
		(net "P5E_CPU0_G3_RX_DP<7>")
	)
	(arc
		(start 367.853468 -242.399058)
		(mid 367.853087 -242.399312)
		(end 367.852706 -242.399566)
		(width 0.1143)
		(layer "In11.Cu")
		(net "P5E_CPU0_G3_RX_DP<7>")
	)
	(arc
		(start 367.852706 -244.019578)
		(mid 367.700719 -244.176086)
		(end 367.61928 -244.37848)
		(width 0.1143)
		(layer "In11.Cu")
		(net "P5E_CPU0_G3_RX_DP<7>")
	)
	(arc
		(start 367.853468 -235.91901)
		(mid 367.853087 -235.919264)
		(end 367.852706 -235.919518)
		(width 0.1143)
		(layer "In11.Cu")
		(net "P5E_CPU0_G3_RX_DP<7>")
	)
	(arc
		(start 367.852706 -229.43947)
		(mid 367.673893 -229.64182)
		(end 367.609374 -229.904036)
		(width 0.1143)
		(layer "In11.Cu")
		(net "P5E_CPU0_G3_RX_DP<7>")
	)
	(arc
		(start 369.26266 -222.14967)
		(mid 369.083847 -222.35202)
		(end 369.019328 -222.614236)
		(width 0.1143)
		(layer "In11.Cu")
		(net "P5E_CPU0_G3_RX_DP<7>")
	)
	(arc
		(start 368.079528 -229.094284)
		(mid 368.038766 -229.264168)
		(end 367.92535 -229.397052)
		(width 0.1143)
		(layer "In11.Cu")
		(net "P5E_CPU0_G3_RX_DP<7>")
	)
	(arc
		(start 367.852706 -237.53953)
		(mid 367.609379 -238.004096)
		(end 367.852706 -238.468662)
		(width 0.1143)
		(layer "In11.Cu")
		(net "P5E_CPU0_G3_RX_DP<7>")
	)
	(arc
		(start 367.853468 -237.539022)
		(mid 367.853087 -237.539276)
		(end 367.852706 -237.53953)
		(width 0.1143)
		(layer "In11.Cu")
		(net "P5E_CPU0_G3_RX_DP<7>")
	)
	(segment
		(start 366.767872 -246.370094)
		(end 367.234724 -246.104156)
		(width 0.12954)
		(layer "F.Cu")
		(net "P5E_CPU0_G3_RX_DP<6>")
	)
	(segment
		(start 415.356802 -7.709154)
		(end 415.356802 -8.320024)
		(width 0.12954)
		(layer "F.Cu")
		(net "P5E_CPU0_G3_RX_DP<6>")
	)
	(segment
		(start 415.495486 -5.22859)
		(end 415.495486 -7.57047)
		(width 0.12954)
		(layer "F.Cu")
		(net "P5E_CPU0_G3_RX_DP<6>")
	)
	(segment
		(start 415.23031 -4.963414)
		(end 415.495486 -5.22859)
		(width 0.12954)
		(layer "F.Cu")
		(net "P5E_CPU0_G3_RX_DP<6>")
	)
	(segment
		(start 415.495486 -7.57047)
		(end 415.356802 -7.709154)
		(width 0.12954)
		(layer "F.Cu")
		(net "P5E_CPU0_G3_RX_DP<6>")
	)
	(segment
		(start 368.831876 -228.771704)
		(end 368.862356 -228.789484)
		(width 0.1143)
		(layer "In11.Cu")
		(net "P5E_CPU0_G3_RX_DP<6>")
	)
	(segment
		(start 368.862356 -237.49889)
		(end 368.79276 -237.53953)
		(width 0.1143)
		(layer "In11.Cu")
		(net "P5E_CPU0_G3_RX_DP<6>")
	)
	(segment
		(start 369.732814 -223.888808)
		(end 369.80241 -223.929448)
		(width 0.1143)
		(layer "In11.Cu")
		(net "P5E_CPU0_G3_RX_DP<6>")
	)
	(segment
		(start 370.272818 -222.108776)
		(end 370.202714 -222.14967)
		(width 0.1143)
		(layer "In11.Cu")
		(net "P5E_CPU0_G3_RX_DP<6>")
	)
	(segment
		(start 368.79276 -228.748844)
		(end 368.793268 -228.749098)
		(width 0.1143)
		(layer "In11.Cu")
		(net "P5E_CPU0_G3_RX_DP<6>")
	)
	(segment
		(start 368.79276 -235.228638)
		(end 368.862356 -235.269278)
		(width 0.1143)
		(layer "In11.Cu")
		(net "P5E_CPU0_G3_RX_DP<6>")
	)
	(segment
		(start 324.463918 -129.097024)
		(end 322.195952 -133.04266)
		(width 0.14224)
		(layer "In11.Cu")
		(net "P5E_CPU0_G3_RX_DP<6>")
	)
	(segment
		(start 368.79276 -240.088674)
		(end 368.862356 -240.129314)
		(width 0.1143)
		(layer "In11.Cu")
		(net "P5E_CPU0_G3_RX_DP<6>")
	)
	(segment
		(start 367.89233 -245.616476)
		(end 367.853468 -245.639082)
		(width 0.1143)
		(layer "In11.Cu")
		(net "P5E_CPU0_G3_RX_DP<6>")
	)
	(segment
		(start 368.864388 -229.397814)
		(end 368.831876 -229.41661)
		(width 0.1143)
		(layer "In11.Cu")
		(net "P5E_CPU0_G3_RX_DP<6>")
	)
	(segment
		(start 368.864388 -231.017826)
		(end 368.831876 -231.036622)
		(width 0.1143)
		(layer "In11.Cu")
		(net "P5E_CPU0_G3_RX_DP<6>")
	)
	(segment
		(start 369.302538 -225.366326)
		(end 369.301776 -225.366834)
		(width 0.1143)
		(layer "In11.Cu")
		(net "P5E_CPU0_G3_RX_DP<6>")
	)
	(segment
		(start 369.80241 -222.919036)
		(end 369.732814 -222.959676)
		(width 0.1143)
		(layer "In11.Cu")
		(net "P5E_CPU0_G3_RX_DP<6>")
	)
	(segment
		(start 369.631214 -214.153242)
		(end 370.414804 -220.602048)
		(width 0.14224)
		(layer "In11.Cu")
		(net "P5E_CPU0_G3_RX_DP<6>")
	)
	(segment
		(start 414.414716 -17.747742)
		(end 413.431228 -19.294348)
		(width 0.14224)
		(layer "In11.Cu")
		(net "P5E_CPU0_G3_RX_DP<6>")
	)
	(segment
		(start 368.862356 -232.638854)
		(end 368.79276 -232.679494)
		(width 0.1143)
		(layer "In11.Cu")
		(net "P5E_CPU0_G3_RX_DP<6>")
	)
	(segment
		(start 370.273072 -222.108776)
		(end 370.272818 -222.108776)
		(width 0.1143)
		(layer "In11.Cu")
		(net "P5E_CPU0_G3_RX_DP<6>")
	)
	(segment
		(start 316.273688 -149.377146)
		(end 314.25261 -160.880806)
		(width 0.14224)
		(layer "In11.Cu")
		(net "P5E_CPU0_G3_RX_DP<6>")
	)
	(segment
		(start 368.79276 -227.128832)
		(end 368.862356 -227.169472)
		(width 0.1143)
		(layer "In11.Cu")
		(net "P5E_CPU0_G3_RX_DP<6>")
	)
	(segment
		(start 369.305332 -225.364802)
		(end 369.303808 -225.365564)
		(width 0.1143)
		(layer "In11.Cu")
		(net "P5E_CPU0_G3_RX_DP<6>")
	)
	(segment
		(start 368.79276 -243.328698)
		(end 368.862356 -243.369338)
		(width 0.1143)
		(layer "In11.Cu")
		(net "P5E_CPU0_G3_RX_DP<6>")
	)
	(segment
		(start 368.793268 -228.749098)
		(end 368.831876 -228.771704)
		(width 0.1143)
		(layer "In11.Cu")
		(net "P5E_CPU0_G3_RX_DP<6>")
	)
	(segment
		(start 368.79276 -233.608626)
		(end 368.862356 -233.649266)
		(width 0.1143)
		(layer "In11.Cu")
		(net "P5E_CPU0_G3_RX_DP<6>")
	)
	(segment
		(start 415.23031 -4.963414)
		(end 415.52114 -5.254244)
		(width 0.14224)
		(layer "In11.Cu")
		(net "P5E_CPU0_G3_RX_DP<6>")
	)
	(segment
		(start 369.30711 -225.363786)
		(end 369.306094 -225.364294)
		(width 0.1143)
		(layer "In11.Cu")
		(net "P5E_CPU0_G3_RX_DP<6>")
	)
	(segment
		(start 386.740146 -54.504844)
		(end 324.463918 -129.097024)
		(width 0.14224)
		(layer "In11.Cu")
		(net "P5E_CPU0_G3_RX_DP<6>")
	)
	(segment
		(start 368.862356 -227.779072)
		(end 368.79276 -227.819712)
		(width 0.1143)
		(layer "In11.Cu")
		(net "P5E_CPU0_G3_RX_DP<6>")
	)
	(segment
		(start 369.30076 -225.367342)
		(end 369.299236 -225.368358)
		(width 0.1143)
		(layer "In11.Cu")
		(net "P5E_CPU0_G3_RX_DP<6>")
	)
	(segment
		(start 367.61547 -246.021352)
		(end 367.532666 -246.104156)
		(width 0.1143)
		(layer "In11.Cu")
		(net "P5E_CPU0_G3_RX_DP<6>")
	)
	(segment
		(start 368.79276 -238.468662)
		(end 368.862356 -238.509302)
		(width 0.1143)
		(layer "In11.Cu")
		(net "P5E_CPU0_G3_RX_DP<6>")
	)
	(segment
		(start 322.195952 -133.04266)
		(end 316.273688 -149.377146)
		(width 0.14224)
		(layer "In11.Cu")
		(net "P5E_CPU0_G3_RX_DP<6>")
	)
	(segment
		(start 317.281306 -166.990522)
		(end 318.776858 -168.486582)
		(width 0.14224)
		(layer "In11.Cu")
		(net "P5E_CPU0_G3_RX_DP<6>")
	)
	(segment
		(start 368.7953 -230.37038)
		(end 368.862356 -230.409496)
		(width 0.1143)
		(layer "In11.Cu")
		(net "P5E_CPU0_G3_RX_DP<6>")
	)
	(segment
		(start 368.831876 -231.036622)
		(end 368.79276 -231.059482)
		(width 0.1143)
		(layer "In11.Cu")
		(net "P5E_CPU0_G3_RX_DP<6>")
	)
	(segment
		(start 368.862356 -243.978938)
		(end 368.79276 -244.019578)
		(width 0.1143)
		(layer "In11.Cu")
		(net "P5E_CPU0_G3_RX_DP<6>")
	)
	(segment
		(start 369.301776 -225.366834)
		(end 369.30076 -225.367342)
		(width 0.1143)
		(layer "In11.Cu")
		(net "P5E_CPU0_G3_RX_DP<6>")
	)
	(segment
		(start 363.681264 -204.021944)
		(end 369.631214 -214.153242)
		(width 0.14224)
		(layer "In11.Cu")
		(net "P5E_CPU0_G3_RX_DP<6>")
	)
	(segment
		(start 324.330314 -171.927012)
		(end 325.95312 -173.011846)
		(width 0.14224)
		(layer "In11.Cu")
		(net "P5E_CPU0_G3_RX_DP<6>")
	)
	(segment
		(start 325.95312 -173.011846)
		(end 326.992488 -173.952916)
		(width 0.14224)
		(layer "In11.Cu")
		(net "P5E_CPU0_G3_RX_DP<6>")
	)
	(segment
		(start 368.393726 -244.788182)
		(end 368.350546 -244.813328)
		(width 0.1143)
		(layer "In11.Cu")
		(net "P5E_CPU0_G3_RX_DP<6>")
	)
	(segment
		(start 318.776858 -168.486582)
		(end 322.707508 -170.842686)
		(width 0.14224)
		(layer "In11.Cu")
		(net "P5E_CPU0_G3_RX_DP<6>")
	)
	(segment
		(start 368.862356 -226.15906)
		(end 368.79276 -226.1997)
		(width 0.1143)
		(layer "In11.Cu")
		(net "P5E_CPU0_G3_RX_DP<6>")
	)
	(segment
		(start 326.992488 -173.952916)
		(end 363.681264 -204.021944)
		(width 0.14224)
		(layer "In11.Cu")
		(net "P5E_CPU0_G3_RX_DP<6>")
	)
	(segment
		(start 314.25261 -160.880806)
		(end 314.25261 -161.812478)
		(width 0.14224)
		(layer "In11.Cu")
		(net "P5E_CPU0_G3_RX_DP<6>")
	)
	(segment
		(start 369.303808 -225.365564)
		(end 369.302538 -225.366326)
		(width 0.1143)
		(layer "In11.Cu")
		(net "P5E_CPU0_G3_RX_DP<6>")
	)
	(segment
		(start 413.431228 -19.294348)
		(end 386.740146 -54.504844)
		(width 0.14224)
		(layer "In11.Cu")
		(net "P5E_CPU0_G3_RX_DP<6>")
	)
	(segment
		(start 368.862356 -240.738914)
		(end 368.79276 -240.779554)
		(width 0.1143)
		(layer "In11.Cu")
		(net "P5E_CPU0_G3_RX_DP<6>")
	)
	(segment
		(start 415.52114 -12.295886)
		(end 414.457134 -17.648174)
		(width 0.14224)
		(layer "In11.Cu")
		(net "P5E_CPU0_G3_RX_DP<6>")
	)
	(segment
		(start 370.414804 -220.602048)
		(end 370.414804 -221.054676)
		(width 0.14224)
		(layer "In11.Cu")
		(net "P5E_CPU0_G3_RX_DP<6>")
	)
	(segment
		(start 315.77153 -165.480238)
		(end 317.281052 -166.990522)
		(width 0.14224)
		(layer "In11.Cu")
		(net "P5E_CPU0_G3_RX_DP<6>")
	)
	(segment
		(start 369.306094 -225.364294)
		(end 369.305332 -225.364802)
		(width 0.1143)
		(layer "In11.Cu")
		(net "P5E_CPU0_G3_RX_DP<6>")
	)
	(segment
		(start 369.333526 -225.348546)
		(end 369.308888 -225.36277)
		(width 0.1143)
		(layer "In11.Cu")
		(net "P5E_CPU0_G3_RX_DP<6>")
	)
	(segment
		(start 368.79276 -241.708686)
		(end 368.862356 -241.749326)
		(width 0.1143)
		(layer "In11.Cu")
		(net "P5E_CPU0_G3_RX_DP<6>")
	)
	(segment
		(start 367.532666 -246.104156)
		(end 367.234724 -246.104156)
		(width 0.1143)
		(layer "In11.Cu")
		(net "P5E_CPU0_G3_RX_DP<6>")
	)
	(segment
		(start 368.862356 -242.358926)
		(end 368.79276 -242.399566)
		(width 0.1143)
		(layer "In11.Cu")
		(net "P5E_CPU0_G3_RX_DP<6>")
	)
	(segment
		(start 368.862356 -234.258866)
		(end 368.79276 -234.299506)
		(width 0.1143)
		(layer "In11.Cu")
		(net "P5E_CPU0_G3_RX_DP<6>")
	)
	(segment
		(start 368.79276 -236.84865)
		(end 368.862356 -236.88929)
		(width 0.1143)
		(layer "In11.Cu")
		(net "P5E_CPU0_G3_RX_DP<6>")
	)
	(segment
		(start 370.414804 -221.083124)
		(end 370.460524 -221.128844)
		(width 0.1143)
		(layer "In11.Cu")
		(net "P5E_CPU0_G3_RX_DP<6>")
	)
	(segment
		(start 370.414804 -221.054676)
		(end 370.414804 -221.083124)
		(width 0.1143)
		(layer "In11.Cu")
		(net "P5E_CPU0_G3_RX_DP<6>")
	)
	(segment
		(start 415.52114 -5.254244)
		(end 415.52114 -12.295886)
		(width 0.14224)
		(layer "In11.Cu")
		(net "P5E_CPU0_G3_RX_DP<6>")
	)
	(segment
		(start 370.460524 -221.128844)
		(end 370.460524 -221.308676)
		(width 0.1143)
		(layer "In11.Cu")
		(net "P5E_CPU0_G3_RX_DP<6>")
	)
	(segment
		(start 370.460524 -221.308676)
		(end 370.429536 -221.339664)
		(width 0.1143)
		(layer "In11.Cu")
		(net "P5E_CPU0_G3_RX_DP<6>")
	)
	(segment
		(start 324.330314 -171.927266)
		(end 324.330314 -171.927012)
		(width 0.14224)
		(layer "In11.Cu")
		(net "P5E_CPU0_G3_RX_DP<6>")
	)
	(segment
		(start 369.308888 -225.36277)
		(end 369.307872 -225.363278)
		(width 0.1143)
		(layer "In11.Cu")
		(net "P5E_CPU0_G3_RX_DP<6>")
	)
	(segment
		(start 322.707508 -170.842686)
		(end 324.330314 -171.927266)
		(width 0.14224)
		(layer "In11.Cu")
		(net "P5E_CPU0_G3_RX_DP<6>")
	)
	(segment
		(start 368.067082 -245.303548)
		(end 368.067082 -245.3132)
		(width 0.1143)
		(layer "In11.Cu")
		(net "P5E_CPU0_G3_RX_DP<6>")
	)
	(segment
		(start 369.299236 -225.368358)
		(end 369.26266 -225.389694)
		(width 0.1143)
		(layer "In11.Cu")
		(net "P5E_CPU0_G3_RX_DP<6>")
	)
	(segment
		(start 314.25261 -161.812478)
		(end 315.77153 -165.480238)
		(width 0.14224)
		(layer "In11.Cu")
		(net "P5E_CPU0_G3_RX_DP<6>")
	)
	(segment
		(start 317.281052 -166.990522)
		(end 317.281306 -166.990522)
		(width 0.14224)
		(layer "In11.Cu")
		(net "P5E_CPU0_G3_RX_DP<6>")
	)
	(segment
		(start 369.80241 -224.539048)
		(end 369.732814 -224.579688)
		(width 0.1143)
		(layer "In11.Cu")
		(net "P5E_CPU0_G3_RX_DP<6>")
	)
	(segment
		(start 370.429536 -221.339664)
		(end 370.429536 -221.80423)
		(width 0.1143)
		(layer "In11.Cu")
		(net "P5E_CPU0_G3_RX_DP<6>")
	)
	(segment
		(start 368.862356 -239.118902)
		(end 368.79276 -239.159542)
		(width 0.1143)
		(layer "In11.Cu")
		(net "P5E_CPU0_G3_RX_DP<6>")
	)
	(segment
		(start 368.831876 -229.41661)
		(end 368.79276 -229.43947)
		(width 0.1143)
		(layer "In11.Cu")
		(net "P5E_CPU0_G3_RX_DP<6>")
	)
	(segment
		(start 368.79276 -231.988614)
		(end 368.862356 -232.029254)
		(width 0.1143)
		(layer "In11.Cu")
		(net "P5E_CPU0_G3_RX_DP<6>")
	)
	(segment
		(start 369.307872 -225.363278)
		(end 369.30711 -225.363786)
		(width 0.1143)
		(layer "In11.Cu")
		(net "P5E_CPU0_G3_RX_DP<6>")
	)
	(segment
		(start 414.457134 -17.648174)
		(end 414.414716 -17.747742)
		(width 0.14224)
		(layer "In11.Cu")
		(net "P5E_CPU0_G3_RX_DP<6>")
	)
	(segment
		(start 368.862356 -235.878878)
		(end 368.79276 -235.919518)
		(width 0.1143)
		(layer "In11.Cu")
		(net "P5E_CPU0_G3_RX_DP<6>")
	)
	(arc
		(start 368.79276 -244.019578)
		(mid 368.613947 -244.221928)
		(end 368.549428 -244.484144)
		(width 0.1143)
		(layer "In11.Cu")
		(net "P5E_CPU0_G3_RX_DP<6>")
	)
	(arc
		(start 368.79276 -227.819712)
		(mid 368.549433 -228.284278)
		(end 368.79276 -228.748844)
		(width 0.1143)
		(layer "In11.Cu")
		(net "P5E_CPU0_G3_RX_DP<6>")
	)
	(arc
		(start 369.019328 -229.094284)
		(mid 368.978362 -229.26469)
		(end 368.864388 -229.397814)
		(width 0.1143)
		(layer "In11.Cu")
		(net "P5E_CPU0_G3_RX_DP<6>")
	)
	(arc
		(start 368.79276 -234.299506)
		(mid 368.549433 -234.764072)
		(end 368.79276 -235.228638)
		(width 0.1143)
		(layer "In11.Cu")
		(net "P5E_CPU0_G3_RX_DP<6>")
	)
	(arc
		(start 368.862356 -233.649266)
		(mid 369.019333 -233.954066)
		(end 368.862356 -234.258866)
		(width 0.1143)
		(layer "In11.Cu")
		(net "P5E_CPU0_G3_RX_DP<6>")
	)
	(arc
		(start 369.019328 -230.714296)
		(mid 368.978362 -230.884702)
		(end 368.864388 -231.017826)
		(width 0.1143)
		(layer "In11.Cu")
		(net "P5E_CPU0_G3_RX_DP<6>")
	)
	(arc
		(start 368.862356 -238.509302)
		(mid 369.019333 -238.814102)
		(end 368.862356 -239.118902)
		(width 0.1143)
		(layer "In11.Cu")
		(net "P5E_CPU0_G3_RX_DP<6>")
	)
	(arc
		(start 368.862356 -232.029254)
		(mid 369.019333 -232.334054)
		(end 368.862356 -232.638854)
		(width 0.1143)
		(layer "In11.Cu")
		(net "P5E_CPU0_G3_RX_DP<6>")
	)
	(arc
		(start 369.019328 -225.85426)
		(mid 368.977779 -226.025682)
		(end 368.862356 -226.15906)
		(width 0.1143)
		(layer "In11.Cu")
		(net "P5E_CPU0_G3_RX_DP<6>")
	)
	(arc
		(start 368.067082 -245.3132)
		(mid 368.020192 -245.488151)
		(end 367.89233 -245.616476)
		(width 0.1143)
		(layer "In11.Cu")
		(net "P5E_CPU0_G3_RX_DP<6>")
	)
	(arc
		(start 368.862356 -243.369338)
		(mid 369.019333 -243.674138)
		(end 368.862356 -243.978938)
		(width 0.1143)
		(layer "In11.Cu")
		(net "P5E_CPU0_G3_RX_DP<6>")
	)
	(arc
		(start 368.862356 -235.269278)
		(mid 369.019333 -235.574078)
		(end 368.862356 -235.878878)
		(width 0.1143)
		(layer "In11.Cu")
		(net "P5E_CPU0_G3_RX_DP<6>")
	)
	(arc
		(start 368.862356 -236.88929)
		(mid 369.019333 -237.19409)
		(end 368.862356 -237.49889)
		(width 0.1143)
		(layer "In11.Cu")
		(net "P5E_CPU0_G3_RX_DP<6>")
	)
	(arc
		(start 369.489482 -225.044254)
		(mid 369.448227 -225.215225)
		(end 369.333526 -225.348546)
		(width 0.1143)
		(layer "In11.Cu")
		(net "P5E_CPU0_G3_RX_DP<6>")
	)
	(arc
		(start 368.862356 -230.409496)
		(mid 368.977783 -230.542872)
		(end 369.019328 -230.714296)
		(width 0.1143)
		(layer "In11.Cu")
		(net "P5E_CPU0_G3_RX_DP<6>")
	)
	(arc
		(start 369.732814 -222.959676)
		(mid 369.489487 -223.424242)
		(end 369.732814 -223.888808)
		(width 0.1143)
		(layer "In11.Cu")
		(net "P5E_CPU0_G3_RX_DP<6>")
	)
	(arc
		(start 368.79276 -239.159542)
		(mid 368.549433 -239.624108)
		(end 368.79276 -240.088674)
		(width 0.1143)
		(layer "In11.Cu")
		(net "P5E_CPU0_G3_RX_DP<6>")
	)
	(arc
		(start 368.79276 -237.53953)
		(mid 368.549433 -238.004096)
		(end 368.79276 -238.468662)
		(width 0.1143)
		(layer "In11.Cu")
		(net "P5E_CPU0_G3_RX_DP<6>")
	)
	(arc
		(start 368.79276 -242.399566)
		(mid 368.549433 -242.864132)
		(end 368.79276 -243.328698)
		(width 0.1143)
		(layer "In11.Cu")
		(net "P5E_CPU0_G3_RX_DP<6>")
	)
	(arc
		(start 369.80241 -223.929448)
		(mid 369.959387 -224.234248)
		(end 369.80241 -224.539048)
		(width 0.1143)
		(layer "In11.Cu")
		(net "P5E_CPU0_G3_RX_DP<6>")
	)
	(arc
		(start 368.79276 -226.1997)
		(mid 368.549433 -226.664266)
		(end 368.79276 -227.128832)
		(width 0.1143)
		(layer "In11.Cu")
		(net "P5E_CPU0_G3_RX_DP<6>")
	)
	(arc
		(start 368.79276 -240.779554)
		(mid 368.549433 -241.24412)
		(end 368.79276 -241.708686)
		(width 0.1143)
		(layer "In11.Cu")
		(net "P5E_CPU0_G3_RX_DP<6>")
	)
	(arc
		(start 367.852706 -245.63959)
		(mid 367.700719 -245.796098)
		(end 367.61928 -245.998492)
		(width 0.1143)
		(layer "In11.Cu")
		(net "P5E_CPU0_G3_RX_DP<6>")
	)
	(arc
		(start 369.959382 -222.614236)
		(mid 369.917833 -222.785658)
		(end 369.80241 -222.919036)
		(width 0.1143)
		(layer "In11.Cu")
		(net "P5E_CPU0_G3_RX_DP<6>")
	)
	(arc
		(start 368.350546 -244.813328)
		(mid 368.143062 -245.020415)
		(end 368.067082 -245.303548)
		(width 0.1143)
		(layer "In11.Cu")
		(net "P5E_CPU0_G3_RX_DP<6>")
	)
	(arc
		(start 368.549428 -229.904036)
		(mid 368.614664 -230.167627)
		(end 368.7953 -230.37038)
		(width 0.1143)
		(layer "In11.Cu")
		(net "P5E_CPU0_G3_RX_DP<6>")
	)
	(arc
		(start 369.732814 -224.579688)
		(mid 369.554001 -224.782038)
		(end 369.489482 -225.044254)
		(width 0.1143)
		(layer "In11.Cu")
		(net "P5E_CPU0_G3_RX_DP<6>")
	)
	(arc
		(start 368.549428 -244.484144)
		(mid 368.508235 -244.654933)
		(end 368.393726 -244.788182)
		(width 0.1143)
		(layer "In11.Cu")
		(net "P5E_CPU0_G3_RX_DP<6>")
	)
	(arc
		(start 369.26266 -225.389694)
		(mid 369.083847 -225.592044)
		(end 369.019328 -225.85426)
		(width 0.1143)
		(layer "In11.Cu")
		(net "P5E_CPU0_G3_RX_DP<6>")
	)
	(arc
		(start 368.79276 -231.059482)
		(mid 368.549433 -231.524048)
		(end 368.79276 -231.988614)
		(width 0.1143)
		(layer "In11.Cu")
		(net "P5E_CPU0_G3_RX_DP<6>")
	)
	(arc
		(start 370.202714 -222.14967)
		(mid 370.023901 -222.35202)
		(end 369.959382 -222.614236)
		(width 0.1143)
		(layer "In11.Cu")
		(net "P5E_CPU0_G3_RX_DP<6>")
	)
	(arc
		(start 368.79276 -232.679494)
		(mid 368.549433 -233.14406)
		(end 368.79276 -233.608626)
		(width 0.1143)
		(layer "In11.Cu")
		(net "P5E_CPU0_G3_RX_DP<6>")
	)
	(arc
		(start 368.862356 -240.129314)
		(mid 369.019333 -240.434114)
		(end 368.862356 -240.738914)
		(width 0.1143)
		(layer "In11.Cu")
		(net "P5E_CPU0_G3_RX_DP<6>")
	)
	(arc
		(start 367.853468 -245.639082)
		(mid 367.853087 -245.639336)
		(end 367.852706 -245.63959)
		(width 0.1143)
		(layer "In11.Cu")
		(net "P5E_CPU0_G3_RX_DP<6>")
	)
	(arc
		(start 367.61928 -245.998492)
		(mid 367.617257 -246.009902)
		(end 367.61547 -246.021352)
		(width 0.1143)
		(layer "In11.Cu")
		(net "P5E_CPU0_G3_RX_DP<6>")
	)
	(arc
		(start 368.862356 -241.749326)
		(mid 369.019333 -242.054126)
		(end 368.862356 -242.358926)
		(width 0.1143)
		(layer "In11.Cu")
		(net "P5E_CPU0_G3_RX_DP<6>")
	)
	(arc
		(start 368.79276 -229.43947)
		(mid 368.613947 -229.64182)
		(end 368.549428 -229.904036)
		(width 0.1143)
		(layer "In11.Cu")
		(net "P5E_CPU0_G3_RX_DP<6>")
	)
	(arc
		(start 368.862356 -228.789484)
		(mid 368.977783 -228.92286)
		(end 369.019328 -229.094284)
		(width 0.1143)
		(layer "In11.Cu")
		(net "P5E_CPU0_G3_RX_DP<6>")
	)
	(arc
		(start 368.79276 -235.919518)
		(mid 368.549433 -236.384084)
		(end 368.79276 -236.84865)
		(width 0.1143)
		(layer "In11.Cu")
		(net "P5E_CPU0_G3_RX_DP<6>")
	)
	(arc
		(start 370.429536 -221.80423)
		(mid 370.388134 -221.975427)
		(end 370.273072 -222.108776)
		(width 0.1143)
		(layer "In11.Cu")
		(net "P5E_CPU0_G3_RX_DP<6>")
	)
	(arc
		(start 368.862356 -227.169472)
		(mid 369.019333 -227.474272)
		(end 368.862356 -227.779072)
		(width 0.1143)
		(layer "In11.Cu")
		(net "P5E_CPU0_G3_RX_DP<6>")
	)
	(segment
		(start 417.295584 -7.57047)
		(end 417.295584 -6.99516)
		(width 0.12954)
		(layer "F.Cu")
		(net "P5E_CPU0_G3_RX_DP<5>")
	)
	(segment
		(start 369.588034 -247.990106)
		(end 370.054886 -247.724168)
		(width 0.12954)
		(layer "F.Cu")
		(net "P5E_CPU0_G3_RX_DP<5>")
	)
	(segment
		(start 417.1569 -8.320024)
		(end 417.1569 -7.709154)
		(width 0.12954)
		(layer "F.Cu")
		(net "P5E_CPU0_G3_RX_DP<5>")
	)
	(segment
		(start 417.295584 -6.99516)
		(end 417.025582 -6.725158)
		(width 0.12954)
		(layer "F.Cu")
		(net "P5E_CPU0_G3_RX_DP<5>")
	)
	(segment
		(start 417.1569 -7.709154)
		(end 417.295584 -7.57047)
		(width 0.12954)
		(layer "F.Cu")
		(net "P5E_CPU0_G3_RX_DP<5>")
	)
	(segment
		(start 417.5125 -18.963386)
		(end 417.5125 -19.495262)
		(width 0.14224)
		(layer "In11.Cu")
		(net "P5E_CPU0_G3_RX_DP<5>")
	)
	(segment
		(start 369.76939 -240.758218)
		(end 369.732814 -240.779554)
		(width 0.1143)
		(layer "In11.Cu")
		(net "P5E_CPU0_G3_RX_DP<5>")
	)
	(segment
		(start 370.74348 -224.53854)
		(end 370.71173 -224.556828)
		(width 0.1143)
		(layer "In11.Cu")
		(net "P5E_CPU0_G3_RX_DP<5>")
	)
	(segment
		(start 364.382304 -203.366624)
		(end 370.72824 -214.050372)
		(width 0.14224)
		(layer "In11.Cu")
		(net "P5E_CPU0_G3_RX_DP<5>")
	)
	(segment
		(start 316.512702 -164.832792)
		(end 318.825118 -167.14597)
		(width 0.14224)
		(layer "In11.Cu")
		(net "P5E_CPU0_G3_RX_DP<5>")
	)
	(segment
		(start 369.772692 -236.872018)
		(end 369.773962 -236.87278)
		(width 0.1143)
		(layer "In11.Cu")
		(net "P5E_CPU0_G3_RX_DP<5>")
	)
	(segment
		(start 327.468738 -173.115986)
		(end 364.382304 -203.366624)
		(width 0.14224)
		(layer "In11.Cu")
		(net "P5E_CPU0_G3_RX_DP<5>")
	)
	(segment
		(start 416.884104 -17.935702)
		(end 417.119308 -18.375122)
		(width 0.14224)
		(layer "In11.Cu")
		(net "P5E_CPU0_G3_RX_DP<5>")
	)
	(segment
		(start 370.242592 -225.366326)
		(end 370.24183 -225.366834)
		(width 0.1143)
		(layer "In11.Cu")
		(net "P5E_CPU0_G3_RX_DP<5>")
	)
	(segment
		(start 369.770914 -239.13719)
		(end 369.76939 -239.138206)
		(width 0.1143)
		(layer "In11.Cu")
		(net "P5E_CPU0_G3_RX_DP<5>")
	)
	(segment
		(start 369.77193 -239.136682)
		(end 369.770914 -239.13719)
		(width 0.1143)
		(layer "In11.Cu")
		(net "P5E_CPU0_G3_RX_DP<5>")
	)
	(segment
		(start 372.121938 -222.12681)
		(end 372.082822 -222.14967)
		(width 0.1143)
		(layer "In11.Cu")
		(net "P5E_CPU0_G3_RX_DP<5>")
	)
	(segment
		(start 369.80368 -232.638346)
		(end 369.773962 -232.655364)
		(width 0.1143)
		(layer "In11.Cu")
		(net "P5E_CPU0_G3_RX_DP<5>")
	)
	(segment
		(start 369.772692 -240.756186)
		(end 369.77193 -240.756694)
		(width 0.1143)
		(layer "In11.Cu")
		(net "P5E_CPU0_G3_RX_DP<5>")
	)
	(segment
		(start 369.770914 -243.35105)
		(end 369.77193 -243.351558)
		(width 0.1143)
		(layer "In11.Cu")
		(net "P5E_CPU0_G3_RX_DP<5>")
	)
	(segment
		(start 369.732814 -243.328698)
		(end 369.76939 -243.350034)
		(width 0.1143)
		(layer "In11.Cu")
		(net "P5E_CPU0_G3_RX_DP<5>")
	)
	(segment
		(start 369.773962 -243.352828)
		(end 369.80368 -243.369846)
		(width 0.1143)
		(layer "In11.Cu")
		(net "P5E_CPU0_G3_RX_DP<5>")
	)
	(segment
		(start 319.645538 -167.89019)
		(end 320.080132 -168.180766)
		(width 0.14224)
		(layer "In11.Cu")
		(net "P5E_CPU0_G3_RX_DP<5>")
	)
	(segment
		(start 369.770914 -242.377214)
		(end 369.732814 -242.399566)
		(width 0.1143)
		(layer "In11.Cu")
		(net "P5E_CPU0_G3_RX_DP<5>")
	)
	(segment
		(start 369.77193 -245.61673)
		(end 369.770914 -245.617238)
		(width 0.1143)
		(layer "In11.Cu")
		(net "P5E_CPU0_G3_RX_DP<5>")
	)
	(segment
		(start 369.772692 -241.732054)
		(end 369.773962 -241.732816)
		(width 0.1143)
		(layer "In11.Cu")
		(net "P5E_CPU0_G3_RX_DP<5>")
	)
	(segment
		(start 369.770914 -244.971062)
		(end 369.77193 -244.97157)
		(width 0.1143)
		(layer "In11.Cu")
		(net "P5E_CPU0_G3_RX_DP<5>")
	)
	(segment
		(start 370.240814 -225.367342)
		(end 370.23929 -225.368358)
		(width 0.1143)
		(layer "In11.Cu")
		(net "P5E_CPU0_G3_RX_DP<5>")
	)
	(segment
		(start 369.804442 -229.397814)
		(end 369.77193 -229.41661)
		(width 0.1143)
		(layer "In11.Cu")
		(net "P5E_CPU0_G3_RX_DP<5>")
	)
	(segment
		(start 369.77193 -237.51667)
		(end 369.770914 -237.517178)
		(width 0.1143)
		(layer "In11.Cu")
		(net "P5E_CPU0_G3_RX_DP<5>")
	)
	(segment
		(start 369.80368 -237.498382)
		(end 369.773962 -237.5154)
		(width 0.1143)
		(layer "In11.Cu")
		(net "P5E_CPU0_G3_RX_DP<5>")
	)
	(segment
		(start 417.316412 -12.468352)
		(end 416.813492 -17.57553)
		(width 0.14224)
		(layer "In11.Cu")
		(net "P5E_CPU0_G3_RX_DP<5>")
	)
	(segment
		(start 369.773962 -240.755424)
		(end 369.772692 -240.756186)
		(width 0.1143)
		(layer "In11.Cu")
		(net "P5E_CPU0_G3_RX_DP<5>")
	)
	(segment
		(start 369.77193 -243.996718)
		(end 369.770914 -243.997226)
		(width 0.1143)
		(layer "In11.Cu")
		(net "P5E_CPU0_G3_RX_DP<5>")
	)
	(segment
		(start 369.772692 -242.376198)
		(end 369.77193 -242.376706)
		(width 0.1143)
		(layer "In11.Cu")
		(net "P5E_CPU0_G3_RX_DP<5>")
	)
	(segment
		(start 369.732814 -233.608626)
		(end 369.76939 -233.629962)
		(width 0.1143)
		(layer "In11.Cu")
		(net "P5E_CPU0_G3_RX_DP<5>")
	)
	(segment
		(start 369.77193 -238.491522)
		(end 369.80368 -238.50981)
		(width 0.1143)
		(layer "In11.Cu")
		(net "P5E_CPU0_G3_RX_DP<5>")
	)
	(segment
		(start 369.773962 -240.112804)
		(end 369.80368 -240.129822)
		(width 0.1143)
		(layer "In11.Cu")
		(net "P5E_CPU0_G3_RX_DP<5>")
	)
	(segment
		(start 372.26367 -220.678756)
		(end 372.26367 -221.17431)
		(width 0.14224)
		(layer "In11.Cu")
		(net "P5E_CPU0_G3_RX_DP<5>")
	)
	(segment
		(start 369.732814 -236.84865)
		(end 369.76939 -236.869986)
		(width 0.1143)
		(layer "In11.Cu")
		(net "P5E_CPU0_G3_RX_DP<5>")
	)
	(segment
		(start 369.772692 -235.89615)
		(end 369.77193 -235.896658)
		(width 0.1143)
		(layer "In11.Cu")
		(net "P5E_CPU0_G3_RX_DP<5>")
	)
	(segment
		(start 369.772692 -233.631994)
		(end 369.773962 -233.632756)
		(width 0.1143)
		(layer "In11.Cu")
		(net "P5E_CPU0_G3_RX_DP<5>")
	)
	(segment
		(start 417.316412 -7.015988)
		(end 417.316412 -12.468352)
		(width 0.14224)
		(layer "In11.Cu")
		(net "P5E_CPU0_G3_RX_DP<5>")
	)
	(segment
		(start 369.770914 -232.657142)
		(end 369.76939 -232.658158)
		(width 0.1143)
		(layer "In11.Cu")
		(net "P5E_CPU0_G3_RX_DP<5>")
	)
	(segment
		(start 369.80368 -242.358418)
		(end 369.773962 -242.375436)
		(width 0.1143)
		(layer "In11.Cu")
		(net "P5E_CPU0_G3_RX_DP<5>")
	)
	(segment
		(start 369.770914 -234.277154)
		(end 369.76939 -234.27817)
		(width 0.1143)
		(layer "In11.Cu")
		(net "P5E_CPU0_G3_RX_DP<5>")
	)
	(segment
		(start 369.770914 -245.617238)
		(end 369.732814 -245.63959)
		(width 0.1143)
		(layer "In11.Cu")
		(net "P5E_CPU0_G3_RX_DP<5>")
	)
	(segment
		(start 369.773962 -245.61546)
		(end 369.772692 -245.616222)
		(width 0.1143)
		(layer "In11.Cu")
		(net "P5E_CPU0_G3_RX_DP<5>")
	)
	(segment
		(start 369.732814 -231.988614)
		(end 369.76939 -232.00995)
		(width 0.1143)
		(layer "In11.Cu")
		(net "P5E_CPU0_G3_RX_DP<5>")
	)
	(segment
		(start 371.651784 -222.936816)
		(end 371.650768 -222.937324)
		(width 0.1143)
		(layer "In11.Cu")
		(net "P5E_CPU0_G3_RX_DP<5>")
	)
	(segment
		(start 371.212364 -223.729042)
		(end 371.181884 -223.746822)
		(width 0.1143)
		(layer "In11.Cu")
		(net "P5E_CPU0_G3_RX_DP<5>")
	)
	(segment
		(start 323.001386 -133.56463)
		(end 317.175134 -149.634194)
		(width 0.14224)
		(layer "In11.Cu")
		(net "P5E_CPU0_G3_RX_DP<5>")
	)
	(segment
		(start 369.77193 -234.276646)
		(end 369.770914 -234.277154)
		(width 0.1143)
		(layer "In11.Cu")
		(net "P5E_CPU0_G3_RX_DP<5>")
	)
	(segment
		(start 369.732814 -238.468662)
		(end 369.76939 -238.489998)
		(width 0.1143)
		(layer "In11.Cu")
		(net "P5E_CPU0_G3_RX_DP<5>")
	)
	(segment
		(start 369.80368 -235.87837)
		(end 369.773962 -235.895388)
		(width 0.1143)
		(layer "In11.Cu")
		(net "P5E_CPU0_G3_RX_DP<5>")
	)
	(segment
		(start 369.770914 -237.517178)
		(end 369.732814 -237.53953)
		(width 0.1143)
		(layer "In11.Cu")
		(net "P5E_CPU0_G3_RX_DP<5>")
	)
	(segment
		(start 325.327264 -129.51841)
		(end 323.001386 -133.56463)
		(width 0.14224)
		(layer "In11.Cu")
		(net "P5E_CPU0_G3_RX_DP<5>")
	)
	(segment
		(start 369.80368 -245.598442)
		(end 369.773962 -245.61546)
		(width 0.1143)
		(layer "In11.Cu")
		(net "P5E_CPU0_G3_RX_DP<5>")
	)
	(segment
		(start 369.733322 -228.749098)
		(end 369.77193 -228.771704)
		(width 0.1143)
		(layer "In11.Cu")
		(net "P5E_CPU0_G3_RX_DP<5>")
	)
	(segment
		(start 369.77193 -241.731546)
		(end 369.772692 -241.732054)
		(width 0.1143)
		(layer "In11.Cu")
		(net "P5E_CPU0_G3_RX_DP<5>")
	)
	(segment
		(start 369.772692 -245.616222)
		(end 369.77193 -245.61673)
		(width 0.1143)
		(layer "In11.Cu")
		(net "P5E_CPU0_G3_RX_DP<5>")
	)
	(segment
		(start 370.676932 -224.576894)
		(end 370.672868 -224.579688)
		(width 0.1143)
		(layer "In11.Cu")
		(net "P5E_CPU0_G3_RX_DP<5>")
	)
	(segment
		(start 369.732814 -240.088674)
		(end 369.76939 -240.11001)
		(width 0.1143)
		(layer "In11.Cu")
		(net "P5E_CPU0_G3_RX_DP<5>")
	)
	(segment
		(start 369.770914 -236.871002)
		(end 369.77193 -236.87151)
		(width 0.1143)
		(layer "In11.Cu")
		(net "P5E_CPU0_G3_RX_DP<5>")
	)
	(segment
		(start 369.76939 -235.898182)
		(end 369.732814 -235.919518)
		(width 0.1143)
		(layer "In11.Cu")
		(net "P5E_CPU0_G3_RX_DP<5>")
	)
	(segment
		(start 369.770914 -232.010966)
		(end 369.77193 -232.011474)
		(width 0.1143)
		(layer "In11.Cu")
		(net "P5E_CPU0_G3_RX_DP<5>")
	)
	(segment
		(start 372.152418 -222.10903)
		(end 372.121938 -222.12681)
		(width 0.1143)
		(layer "In11.Cu")
		(net "P5E_CPU0_G3_RX_DP<5>")
	)
	(segment
		(start 369.773962 -234.275376)
		(end 369.772692 -234.276138)
		(width 0.1143)
		(layer "In11.Cu")
		(net "P5E_CPU0_G3_RX_DP<5>")
	)
	(segment
		(start 320.080132 -168.180766)
		(end 320.155824 -168.221406)
		(width 0.14224)
		(layer "In11.Cu")
		(net "P5E_CPU0_G3_RX_DP<5>")
	)
	(segment
		(start 369.77193 -236.87151)
		(end 369.772692 -236.872018)
		(width 0.1143)
		(layer "In11.Cu")
		(net "P5E_CPU0_G3_RX_DP<5>")
	)
	(segment
		(start 369.76939 -241.730022)
		(end 369.770914 -241.731038)
		(width 0.1143)
		(layer "In11.Cu")
		(net "P5E_CPU0_G3_RX_DP<5>")
	)
	(segment
		(start 369.732814 -244.94871)
		(end 369.76939 -244.970046)
		(width 0.1143)
		(layer "In11.Cu")
		(net "P5E_CPU0_G3_RX_DP<5>")
	)
	(segment
		(start 369.772692 -234.276138)
		(end 369.77193 -234.276646)
		(width 0.1143)
		(layer "In11.Cu")
		(net "P5E_CPU0_G3_RX_DP<5>")
	)
	(segment
		(start 369.77193 -246.591582)
		(end 369.772692 -246.59209)
		(width 0.1143)
		(layer "In11.Cu")
		(net "P5E_CPU0_G3_RX_DP<5>")
	)
	(segment
		(start 369.76939 -243.350034)
		(end 369.770914 -243.35105)
		(width 0.1143)
		(layer "In11.Cu")
		(net "P5E_CPU0_G3_RX_DP<5>")
	)
	(segment
		(start 369.77193 -244.97157)
		(end 369.772692 -244.972078)
		(width 0.1143)
		(layer "In11.Cu")
		(net "P5E_CPU0_G3_RX_DP<5>")
	)
	(segment
		(start 369.772692 -240.112042)
		(end 369.773962 -240.112804)
		(width 0.1143)
		(layer "In11.Cu")
		(net "P5E_CPU0_G3_RX_DP<5>")
	)
	(segment
		(start 417.119308 -18.375122)
		(end 417.5125 -18.963386)
		(width 0.14224)
		(layer "In11.Cu")
		(net "P5E_CPU0_G3_RX_DP<5>")
	)
	(segment
		(start 320.155824 -168.221406)
		(end 320.156078 -168.221406)
		(width 0.14224)
		(layer "In11.Cu")
		(net "P5E_CPU0_G3_RX_DP<5>")
	)
	(segment
		(start 371.656102 -222.934276)
		(end 371.65534 -222.934784)
		(width 0.1143)
		(layer "In11.Cu")
		(net "P5E_CPU0_G3_RX_DP<5>")
	)
	(segment
		(start 369.772692 -246.59209)
		(end 369.773962 -246.592852)
		(width 0.1143)
		(layer "In11.Cu")
		(net "P5E_CPU0_G3_RX_DP<5>")
	)
	(segment
		(start 369.732814 -246.568722)
		(end 369.76939 -246.590058)
		(width 0.1143)
		(layer "In11.Cu")
		(net "P5E_CPU0_G3_RX_DP<5>")
	)
	(segment
		(start 369.773962 -235.895388)
		(end 369.772692 -235.89615)
		(width 0.1143)
		(layer "In11.Cu")
		(net "P5E_CPU0_G3_RX_DP<5>")
	)
	(segment
		(start 370.23929 -225.368358)
		(end 370.202714 -225.389694)
		(width 0.1143)
		(layer "In11.Cu")
		(net "P5E_CPU0_G3_RX_DP<5>")
	)
	(segment
		(start 369.773962 -242.375436)
		(end 369.772692 -242.376198)
		(width 0.1143)
		(layer "In11.Cu")
		(net "P5E_CPU0_G3_RX_DP<5>")
	)
	(segment
		(start 370.202968 -247.378728)
		(end 370.272564 -247.419368)
		(width 0.1143)
		(layer "In11.Cu")
		(net "P5E_CPU0_G3_RX_DP<5>")
	)
	(segment
		(start 369.76939 -244.970046)
		(end 369.770914 -244.971062)
		(width 0.1143)
		(layer "In11.Cu")
		(net "P5E_CPU0_G3_RX_DP<5>")
	)
	(segment
		(start 369.76939 -232.658158)
		(end 369.732814 -232.679494)
		(width 0.1143)
		(layer "In11.Cu")
		(net "P5E_CPU0_G3_RX_DP<5>")
	)
	(segment
		(start 369.77193 -235.251498)
		(end 369.772692 -235.252006)
		(width 0.1143)
		(layer "In11.Cu")
		(net "P5E_CPU0_G3_RX_DP<5>")
	)
	(segment
		(start 369.773962 -232.012744)
		(end 369.80368 -232.029762)
		(width 0.1143)
		(layer "In11.Cu")
		(net "P5E_CPU0_G3_RX_DP<5>")
	)
	(segment
		(start 369.770914 -235.897166)
		(end 369.76939 -235.898182)
		(width 0.1143)
		(layer "In11.Cu")
		(net "P5E_CPU0_G3_RX_DP<5>")
	)
	(segment
		(start 371.181884 -223.746822)
		(end 371.142768 -223.769682)
		(width 0.1143)
		(layer "In11.Cu")
		(net "P5E_CPU0_G3_RX_DP<5>")
	)
	(segment
		(start 318.825118 -167.14597)
		(end 319.645538 -167.89019)
		(width 0.14224)
		(layer "In11.Cu")
		(net "P5E_CPU0_G3_RX_DP<5>")
	)
	(segment
		(start 369.80368 -240.738406)
		(end 369.773962 -240.755424)
		(width 0.1143)
		(layer "In11.Cu")
		(net "P5E_CPU0_G3_RX_DP<5>")
	)
	(segment
		(start 372.26367 -221.202758)
		(end 372.30939 -221.248478)
		(width 0.1143)
		(layer "In11.Cu")
		(net "P5E_CPU0_G3_RX_DP<5>")
	)
	(segment
		(start 369.805458 -231.017064)
		(end 369.732814 -231.059482)
		(width 0.1143)
		(layer "In11.Cu")
		(net "P5E_CPU0_G3_RX_DP<5>")
	)
	(segment
		(start 369.773962 -246.592852)
		(end 369.80368 -246.60987)
		(width 0.1143)
		(layer "In11.Cu")
		(net "P5E_CPU0_G3_RX_DP<5>")
	)
	(segment
		(start 369.773962 -233.632756)
		(end 369.80368 -233.649774)
		(width 0.1143)
		(layer "In11.Cu")
		(net "P5E_CPU0_G3_RX_DP<5>")
	)
	(segment
		(start 369.770914 -235.25099)
		(end 369.77193 -235.251498)
		(width 0.1143)
		(layer "In11.Cu")
		(net "P5E_CPU0_G3_RX_DP<5>")
	)
	(segment
		(start 323.26326 -170.08856)
		(end 326.572118 -172.303948)
		(width 0.14224)
		(layer "In11.Cu")
		(net "P5E_CPU0_G3_RX_DP<5>")
	)
	(segment
		(start 369.773962 -237.5154)
		(end 369.772692 -237.516162)
		(width 0.1143)
		(layer "In11.Cu")
		(net "P5E_CPU0_G3_RX_DP<5>")
	)
	(segment
		(start 369.80241 -227.779072)
		(end 369.732814 -227.819712)
		(width 0.1143)
		(layer "In11.Cu")
		(net "P5E_CPU0_G3_RX_DP<5>")
	)
	(segment
		(start 369.80368 -239.118394)
		(end 369.773962 -239.135412)
		(width 0.1143)
		(layer "In11.Cu")
		(net "P5E_CPU0_G3_RX_DP<5>")
	)
	(segment
		(start 369.77193 -232.011474)
		(end 369.772692 -232.011982)
		(width 0.1143)
		(layer "In11.Cu")
		(net "P5E_CPU0_G3_RX_DP<5>")
	)
	(segment
		(start 417.279328 -20.071334)
		(end 388.194804 -54.21757)
		(width 0.14224)
		(layer "In11.Cu")
		(net "P5E_CPU0_G3_RX_DP<5>")
	)
	(segment
		(start 371.652546 -222.936308)
		(end 371.651784 -222.936816)
		(width 0.1143)
		(layer "In11.Cu")
		(net "P5E_CPU0_G3_RX_DP<5>")
	)
	(segment
		(start 388.194804 -54.21757)
		(end 325.327264 -129.51841)
		(width 0.14224)
		(layer "In11.Cu")
		(net "P5E_CPU0_G3_RX_DP<5>")
	)
	(segment
		(start 369.773962 -235.252768)
		(end 369.80368 -235.269786)
		(width 0.1143)
		(layer "In11.Cu")
		(net "P5E_CPU0_G3_RX_DP<5>")
	)
	(segment
		(start 369.77193 -240.756694)
		(end 369.770914 -240.757202)
		(width 0.1143)
		(layer "In11.Cu")
		(net "P5E_CPU0_G3_RX_DP<5>")
	)
	(segment
		(start 369.80241 -226.15906)
		(end 369.732814 -226.1997)
		(width 0.1143)
		(layer "In11.Cu")
		(net "P5E_CPU0_G3_RX_DP<5>")
	)
	(segment
		(start 369.772692 -237.516162)
		(end 369.77193 -237.51667)
		(width 0.1143)
		(layer "In11.Cu")
		(net "P5E_CPU0_G3_RX_DP<5>")
	)
	(segment
		(start 369.735354 -230.37038)
		(end 369.77193 -230.391716)
		(width 0.1143)
		(layer "In11.Cu")
		(net "P5E_CPU0_G3_RX_DP<5>")
	)
	(segment
		(start 369.76939 -235.249974)
		(end 369.770914 -235.25099)
		(width 0.1143)
		(layer "In11.Cu")
		(net "P5E_CPU0_G3_RX_DP<5>")
	)
	(segment
		(start 416.813492 -17.57553)
		(end 416.813492 -17.765014)
		(width 0.14224)
		(layer "In11.Cu")
		(net "P5E_CPU0_G3_RX_DP<5>")
	)
	(segment
		(start 369.770914 -240.757202)
		(end 369.76939 -240.758218)
		(width 0.1143)
		(layer "In11.Cu")
		(net "P5E_CPU0_G3_RX_DP<5>")
	)
	(segment
		(start 369.773962 -243.995448)
		(end 369.772692 -243.99621)
		(width 0.1143)
		(layer "In11.Cu")
		(net "P5E_CPU0_G3_RX_DP<5>")
	)
	(segment
		(start 369.76939 -232.00995)
		(end 369.770914 -232.010966)
		(width 0.1143)
		(layer "In11.Cu")
		(net "P5E_CPU0_G3_RX_DP<5>")
	)
	(segment
		(start 369.770914 -241.731038)
		(end 369.77193 -241.731546)
		(width 0.1143)
		(layer "In11.Cu")
		(net "P5E_CPU0_G3_RX_DP<5>")
	)
	(segment
		(start 371.649244 -222.93834)
		(end 371.612668 -222.959676)
		(width 0.1143)
		(layer "In11.Cu")
		(net "P5E_CPU0_G3_RX_DP<5>")
	)
	(segment
		(start 320.156078 -168.221406)
		(end 323.26326 -170.08856)
		(width 0.14224)
		(layer "In11.Cu")
		(net "P5E_CPU0_G3_RX_DP<5>")
	)
	(segment
		(start 370.24183 -225.366834)
		(end 370.240814 -225.367342)
		(width 0.1143)
		(layer "In11.Cu")
		(net "P5E_CPU0_G3_RX_DP<5>")
	)
	(segment
		(start 370.246402 -225.364294)
		(end 370.243862 -225.365564)
		(width 0.1143)
		(layer "In11.Cu")
		(net "P5E_CPU0_G3_RX_DP<5>")
	)
	(segment
		(start 369.772692 -232.656126)
		(end 369.77193 -232.656634)
		(width 0.1143)
		(layer "In11.Cu")
		(net "P5E_CPU0_G3_RX_DP<5>")
	)
	(segment
		(start 369.76939 -234.27817)
		(end 369.732814 -234.299506)
		(width 0.1143)
		(layer "In11.Cu")
		(net "P5E_CPU0_G3_RX_DP<5>")
	)
	(segment
		(start 369.77193 -243.351558)
		(end 369.772692 -243.352066)
		(width 0.1143)
		(layer "In11.Cu")
		(net "P5E_CPU0_G3_RX_DP<5>")
	)
	(segment
		(start 369.772692 -235.252006)
		(end 369.773962 -235.252768)
		(width 0.1143)
		(layer "In11.Cu")
		(net "P5E_CPU0_G3_RX_DP<5>")
	)
	(segment
		(start 315.18479 -161.62655)
		(end 316.512702 -164.832792)
		(width 0.14224)
		(layer "In11.Cu")
		(net "P5E_CPU0_G3_RX_DP<5>")
	)
	(segment
		(start 369.76939 -236.869986)
		(end 369.770914 -236.871002)
		(width 0.1143)
		(layer "In11.Cu")
		(net "P5E_CPU0_G3_RX_DP<5>")
	)
	(segment
		(start 371.683534 -222.918528)
		(end 371.656102 -222.934276)
		(width 0.1143)
		(layer "In11.Cu")
		(net "P5E_CPU0_G3_RX_DP<5>")
	)
	(segment
		(start 372.30939 -221.248478)
		(end 372.30939 -221.80423)
		(width 0.1143)
		(layer "In11.Cu")
		(net "P5E_CPU0_G3_RX_DP<5>")
	)
	(segment
		(start 369.732814 -235.228638)
		(end 369.76939 -235.249974)
		(width 0.1143)
		(layer "In11.Cu")
		(net "P5E_CPU0_G3_RX_DP<5>")
	)
	(segment
		(start 416.813492 -17.765014)
		(end 416.884104 -17.935702)
		(width 0.14224)
		(layer "In11.Cu")
		(net "P5E_CPU0_G3_RX_DP<5>")
	)
	(segment
		(start 369.76939 -233.629962)
		(end 369.770914 -233.630978)
		(width 0.1143)
		(layer "In11.Cu")
		(net "P5E_CPU0_G3_RX_DP<5>")
	)
	(segment
		(start 326.572118 -172.303948)
		(end 327.468738 -173.115986)
		(width 0.14224)
		(layer "In11.Cu")
		(net "P5E_CPU0_G3_RX_DP<5>")
	)
	(segment
		(start 369.772692 -232.011982)
		(end 369.773962 -232.012744)
		(width 0.1143)
		(layer "In11.Cu")
		(net "P5E_CPU0_G3_RX_DP<5>")
	)
	(segment
		(start 369.773962 -236.87278)
		(end 369.80368 -236.889798)
		(width 0.1143)
		(layer "In11.Cu")
		(net "P5E_CPU0_G3_RX_DP<5>")
	)
	(segment
		(start 369.76939 -243.998242)
		(end 369.732814 -244.019578)
		(width 0.1143)
		(layer "In11.Cu")
		(net "P5E_CPU0_G3_RX_DP<5>")
	)
	(segment
		(start 417.025582 -6.725158)
		(end 417.316412 -7.015988)
		(width 0.14224)
		(layer "In11.Cu")
		(net "P5E_CPU0_G3_RX_DP<5>")
	)
	(segment
		(start 369.76939 -238.489998)
		(end 369.770914 -238.491014)
		(width 0.1143)
		(layer "In11.Cu")
		(net "P5E_CPU0_G3_RX_DP<5>")
	)
	(segment
		(start 369.77193 -230.391716)
		(end 369.80368 -230.410004)
		(width 0.1143)
		(layer "In11.Cu")
		(net "P5E_CPU0_G3_RX_DP<5>")
	)
	(segment
		(start 369.770914 -243.997226)
		(end 369.76939 -243.998242)
		(width 0.1143)
		(layer "In11.Cu")
		(net "P5E_CPU0_G3_RX_DP<5>")
	)
	(segment
		(start 370.243862 -225.365564)
		(end 370.242592 -225.366326)
		(width 0.1143)
		(layer "In11.Cu")
		(net "P5E_CPU0_G3_RX_DP<5>")
	)
	(segment
		(start 369.76939 -240.11001)
		(end 369.770914 -240.111026)
		(width 0.1143)
		(layer "In11.Cu")
		(net "P5E_CPU0_G3_RX_DP<5>")
	)
	(segment
		(start 369.80368 -234.258358)
		(end 369.773962 -234.275376)
		(width 0.1143)
		(layer "In11.Cu")
		(net "P5E_CPU0_G3_RX_DP<5>")
	)
	(segment
		(start 369.773962 -241.732816)
		(end 369.80368 -241.749834)
		(width 0.1143)
		(layer "In11.Cu")
		(net "P5E_CPU0_G3_RX_DP<5>")
	)
	(segment
		(start 317.175134 -149.634194)
		(end 315.18479 -160.963356)
		(width 0.14224)
		(layer "In11.Cu")
		(net "P5E_CPU0_G3_RX_DP<5>")
	)
	(segment
		(start 369.76939 -239.138206)
		(end 369.732814 -239.159542)
		(width 0.1143)
		(layer "In11.Cu")
		(net "P5E_CPU0_G3_RX_DP<5>")
	)
	(segment
		(start 369.772692 -243.99621)
		(end 369.77193 -243.996718)
		(width 0.1143)
		(layer "In11.Cu")
		(net "P5E_CPU0_G3_RX_DP<5>")
	)
	(segment
		(start 369.76939 -246.590058)
		(end 369.770914 -246.591074)
		(width 0.1143)
		(layer "In11.Cu")
		(net "P5E_CPU0_G3_RX_DP<5>")
	)
	(segment
		(start 371.65534 -222.934784)
		(end 371.652546 -222.936308)
		(width 0.1143)
		(layer "In11.Cu")
		(net "P5E_CPU0_G3_RX_DP<5>")
	)
	(segment
		(start 369.773962 -232.655364)
		(end 369.772692 -232.656126)
		(width 0.1143)
		(layer "In11.Cu")
		(net "P5E_CPU0_G3_RX_DP<5>")
	)
	(segment
		(start 370.72824 -214.050372)
		(end 372.26367 -220.678756)
		(width 0.14224)
		(layer "In11.Cu")
		(net "P5E_CPU0_G3_RX_DP<5>")
	)
	(segment
		(start 371.650768 -222.937324)
		(end 371.649244 -222.93834)
		(width 0.1143)
		(layer "In11.Cu")
		(net "P5E_CPU0_G3_RX_DP<5>")
	)
	(segment
		(start 315.18479 -160.963356)
		(end 315.18479 -161.62655)
		(width 0.14224)
		(layer "In11.Cu")
		(net "P5E_CPU0_G3_RX_DP<5>")
	)
	(segment
		(start 369.772692 -243.352066)
		(end 369.773962 -243.352828)
		(width 0.1143)
		(layer "In11.Cu")
		(net "P5E_CPU0_G3_RX_DP<5>")
	)
	(segment
		(start 369.732814 -241.708686)
		(end 369.76939 -241.730022)
		(width 0.1143)
		(layer "In11.Cu")
		(net "P5E_CPU0_G3_RX_DP<5>")
	)
	(segment
		(start 369.770914 -233.630978)
		(end 369.77193 -233.631486)
		(width 0.1143)
		(layer "In11.Cu")
		(net "P5E_CPU0_G3_RX_DP<5>")
	)
	(segment
		(start 370.422678 -247.654318)
		(end 370.352828 -247.724168)
		(width 0.1143)
		(layer "In11.Cu")
		(net "P5E_CPU0_G3_RX_DP<5>")
	)
	(segment
		(start 370.27358 -225.348546)
		(end 370.246402 -225.364294)
		(width 0.1143)
		(layer "In11.Cu")
		(net "P5E_CPU0_G3_RX_DP<5>")
	)
	(segment
		(start 369.77193 -229.41661)
		(end 369.732814 -229.43947)
		(width 0.1143)
		(layer "In11.Cu")
		(net "P5E_CPU0_G3_RX_DP<5>")
	)
	(segment
		(start 372.26367 -221.17431)
		(end 372.26367 -221.202758)
		(width 0.1143)
		(layer "In11.Cu")
		(net "P5E_CPU0_G3_RX_DP<5>")
	)
	(segment
		(start 369.77193 -240.111534)
		(end 369.772692 -240.112042)
		(width 0.1143)
		(layer "In11.Cu")
		(net "P5E_CPU0_G3_RX_DP<5>")
	)
	(segment
		(start 369.77193 -235.896658)
		(end 369.770914 -235.897166)
		(width 0.1143)
		(layer "In11.Cu")
		(net "P5E_CPU0_G3_RX_DP<5>")
	)
	(segment
		(start 370.352828 -247.724168)
		(end 370.054886 -247.724168)
		(width 0.1143)
		(layer "In11.Cu")
		(net "P5E_CPU0_G3_RX_DP<5>")
	)
	(segment
		(start 369.77193 -233.631486)
		(end 369.772692 -233.631994)
		(width 0.1143)
		(layer "In11.Cu")
		(net "P5E_CPU0_G3_RX_DP<5>")
	)
	(segment
		(start 369.772692 -244.972078)
		(end 369.773962 -244.97284)
		(width 0.1143)
		(layer "In11.Cu")
		(net "P5E_CPU0_G3_RX_DP<5>")
	)
	(segment
		(start 369.77193 -242.376706)
		(end 369.770914 -242.377214)
		(width 0.1143)
		(layer "In11.Cu")
		(net "P5E_CPU0_G3_RX_DP<5>")
	)
	(segment
		(start 369.772692 -239.136174)
		(end 369.77193 -239.136682)
		(width 0.1143)
		(layer "In11.Cu")
		(net "P5E_CPU0_G3_RX_DP<5>")
	)
	(segment
		(start 369.80368 -243.97843)
		(end 369.773962 -243.995448)
		(width 0.1143)
		(layer "In11.Cu")
		(net "P5E_CPU0_G3_RX_DP<5>")
	)
	(segment
		(start 369.773962 -239.135412)
		(end 369.772692 -239.136174)
		(width 0.1143)
		(layer "In11.Cu")
		(net "P5E_CPU0_G3_RX_DP<5>")
	)
	(segment
		(start 417.5125 -19.495262)
		(end 417.279328 -20.071334)
		(width 0.14224)
		(layer "In11.Cu")
		(net "P5E_CPU0_G3_RX_DP<5>")
	)
	(segment
		(start 369.77193 -232.656634)
		(end 369.770914 -232.657142)
		(width 0.1143)
		(layer "In11.Cu")
		(net "P5E_CPU0_G3_RX_DP<5>")
	)
	(segment
		(start 369.770914 -240.111026)
		(end 369.77193 -240.111534)
		(width 0.1143)
		(layer "In11.Cu")
		(net "P5E_CPU0_G3_RX_DP<5>")
	)
	(segment
		(start 369.732814 -228.748844)
		(end 369.733322 -228.749098)
		(width 0.1143)
		(layer "In11.Cu")
		(net "P5E_CPU0_G3_RX_DP<5>")
	)
	(segment
		(start 369.732814 -227.128832)
		(end 369.80241 -227.169472)
		(width 0.1143)
		(layer "In11.Cu")
		(net "P5E_CPU0_G3_RX_DP<5>")
	)
	(segment
		(start 369.770914 -238.491014)
		(end 369.77193 -238.491522)
		(width 0.1143)
		(layer "In11.Cu")
		(net "P5E_CPU0_G3_RX_DP<5>")
	)
	(segment
		(start 369.77193 -228.771704)
		(end 369.80241 -228.789484)
		(width 0.1143)
		(layer "In11.Cu")
		(net "P5E_CPU0_G3_RX_DP<5>")
	)
	(segment
		(start 369.770914 -246.591074)
		(end 369.77193 -246.591582)
		(width 0.1143)
		(layer "In11.Cu")
		(net "P5E_CPU0_G3_RX_DP<5>")
	)
	(segment
		(start 370.71173 -224.556828)
		(end 370.676932 -224.576894)
		(width 0.1143)
		(layer "In11.Cu")
		(net "P5E_CPU0_G3_RX_DP<5>")
	)
	(segment
		(start 369.773962 -244.97284)
		(end 369.80368 -244.989858)
		(width 0.1143)
		(layer "In11.Cu")
		(net "P5E_CPU0_G3_RX_DP<5>")
	)
	(arc
		(start 372.30939 -221.80423)
		(mid 372.267841 -221.975652)
		(end 372.152418 -222.10903)
		(width 0.1143)
		(layer "In11.Cu")
		(net "P5E_CPU0_G3_RX_DP<5>")
	)
	(arc
		(start 369.80368 -238.50981)
		(mid 369.959608 -238.814102)
		(end 369.80368 -239.118394)
		(width 0.1143)
		(layer "In11.Cu")
		(net "P5E_CPU0_G3_RX_DP<5>")
	)
	(arc
		(start 369.80241 -228.789484)
		(mid 369.917837 -228.92286)
		(end 369.959382 -229.094284)
		(width 0.1143)
		(layer "In11.Cu")
		(net "P5E_CPU0_G3_RX_DP<5>")
	)
	(arc
		(start 369.959382 -225.85426)
		(mid 369.917833 -226.025682)
		(end 369.80241 -226.15906)
		(width 0.1143)
		(layer "In11.Cu")
		(net "P5E_CPU0_G3_RX_DP<5>")
	)
	(arc
		(start 370.429536 -225.044254)
		(mid 370.388281 -225.215225)
		(end 370.27358 -225.348546)
		(width 0.1143)
		(layer "In11.Cu")
		(net "P5E_CPU0_G3_RX_DP<5>")
	)
	(arc
		(start 369.732814 -237.53953)
		(mid 369.489487 -238.004096)
		(end 369.732814 -238.468662)
		(width 0.1143)
		(layer "In11.Cu")
		(net "P5E_CPU0_G3_RX_DP<5>")
	)
	(arc
		(start 369.732814 -235.919518)
		(mid 369.489487 -236.384084)
		(end 369.732814 -236.84865)
		(width 0.1143)
		(layer "In11.Cu")
		(net "P5E_CPU0_G3_RX_DP<5>")
	)
	(arc
		(start 369.732814 -226.1997)
		(mid 369.489487 -226.664266)
		(end 369.732814 -227.128832)
		(width 0.1143)
		(layer "In11.Cu")
		(net "P5E_CPU0_G3_RX_DP<5>")
	)
	(arc
		(start 372.082822 -222.14967)
		(mid 371.904009 -222.35202)
		(end 371.83949 -222.614236)
		(width 0.1143)
		(layer "In11.Cu")
		(net "P5E_CPU0_G3_RX_DP<5>")
	)
	(arc
		(start 369.80368 -243.369846)
		(mid 369.959608 -243.674138)
		(end 369.80368 -243.97843)
		(width 0.1143)
		(layer "In11.Cu")
		(net "P5E_CPU0_G3_RX_DP<5>")
	)
	(arc
		(start 369.80368 -240.129822)
		(mid 369.959608 -240.434114)
		(end 369.80368 -240.738406)
		(width 0.1143)
		(layer "In11.Cu")
		(net "P5E_CPU0_G3_RX_DP<5>")
	)
	(arc
		(start 369.80368 -236.889798)
		(mid 369.959608 -237.19409)
		(end 369.80368 -237.498382)
		(width 0.1143)
		(layer "In11.Cu")
		(net "P5E_CPU0_G3_RX_DP<5>")
	)
	(arc
		(start 369.732814 -244.019578)
		(mid 369.489487 -244.484144)
		(end 369.732814 -244.94871)
		(width 0.1143)
		(layer "In11.Cu")
		(net "P5E_CPU0_G3_RX_DP<5>")
	)
	(arc
		(start 369.959636 -230.714296)
		(mid 369.918874 -230.88418)
		(end 369.805458 -231.017064)
		(width 0.1143)
		(layer "In11.Cu")
		(net "P5E_CPU0_G3_RX_DP<5>")
	)
	(arc
		(start 370.202714 -225.389694)
		(mid 370.023901 -225.592044)
		(end 369.959382 -225.85426)
		(width 0.1143)
		(layer "In11.Cu")
		(net "P5E_CPU0_G3_RX_DP<5>")
	)
	(arc
		(start 370.899436 -224.234248)
		(mid 370.858181 -224.405219)
		(end 370.74348 -224.53854)
		(width 0.1143)
		(layer "In11.Cu")
		(net "P5E_CPU0_G3_RX_DP<5>")
	)
	(arc
		(start 371.369336 -223.424242)
		(mid 371.327787 -223.595664)
		(end 371.212364 -223.729042)
		(width 0.1143)
		(layer "In11.Cu")
		(net "P5E_CPU0_G3_RX_DP<5>")
	)
	(arc
		(start 369.732814 -229.43947)
		(mid 369.554001 -229.64182)
		(end 369.489482 -229.904036)
		(width 0.1143)
		(layer "In11.Cu")
		(net "P5E_CPU0_G3_RX_DP<5>")
	)
	(arc
		(start 369.80368 -244.989858)
		(mid 369.959608 -245.29415)
		(end 369.80368 -245.598442)
		(width 0.1143)
		(layer "In11.Cu")
		(net "P5E_CPU0_G3_RX_DP<5>")
	)
	(arc
		(start 369.732814 -232.679494)
		(mid 369.489487 -233.14406)
		(end 369.732814 -233.608626)
		(width 0.1143)
		(layer "In11.Cu")
		(net "P5E_CPU0_G3_RX_DP<5>")
	)
	(arc
		(start 369.959636 -246.914162)
		(mid 370.024151 -247.176381)
		(end 370.202968 -247.378728)
		(width 0.1143)
		(layer "In11.Cu")
		(net "P5E_CPU0_G3_RX_DP<5>")
	)
	(arc
		(start 369.80368 -235.269786)
		(mid 369.959608 -235.574078)
		(end 369.80368 -235.87837)
		(width 0.1143)
		(layer "In11.Cu")
		(net "P5E_CPU0_G3_RX_DP<5>")
	)
	(arc
		(start 369.489482 -229.904036)
		(mid 369.554718 -230.167627)
		(end 369.735354 -230.37038)
		(width 0.1143)
		(layer "In11.Cu")
		(net "P5E_CPU0_G3_RX_DP<5>")
	)
	(arc
		(start 369.732814 -245.63959)
		(mid 369.489487 -246.104156)
		(end 369.732814 -246.568722)
		(width 0.1143)
		(layer "In11.Cu")
		(net "P5E_CPU0_G3_RX_DP<5>")
	)
	(arc
		(start 370.672868 -224.579688)
		(mid 370.494055 -224.782038)
		(end 370.429536 -225.044254)
		(width 0.1143)
		(layer "In11.Cu")
		(net "P5E_CPU0_G3_RX_DP<5>")
	)
	(arc
		(start 369.80368 -230.410004)
		(mid 369.918356 -230.543338)
		(end 369.959636 -230.714296)
		(width 0.1143)
		(layer "In11.Cu")
		(net "P5E_CPU0_G3_RX_DP<5>")
	)
	(arc
		(start 371.83949 -222.614236)
		(mid 371.798235 -222.785207)
		(end 371.683534 -222.918528)
		(width 0.1143)
		(layer "In11.Cu")
		(net "P5E_CPU0_G3_RX_DP<5>")
	)
	(arc
		(start 370.272564 -247.419368)
		(mid 370.370329 -247.522344)
		(end 370.422678 -247.654318)
		(width 0.1143)
		(layer "In11.Cu")
		(net "P5E_CPU0_G3_RX_DP<5>")
	)
	(arc
		(start 369.732814 -231.059482)
		(mid 369.489487 -231.524048)
		(end 369.732814 -231.988614)
		(width 0.1143)
		(layer "In11.Cu")
		(net "P5E_CPU0_G3_RX_DP<5>")
	)
	(arc
		(start 369.732814 -242.399566)
		(mid 369.489487 -242.864132)
		(end 369.732814 -243.328698)
		(width 0.1143)
		(layer "In11.Cu")
		(net "P5E_CPU0_G3_RX_DP<5>")
	)
	(arc
		(start 369.80368 -233.649774)
		(mid 369.959608 -233.954066)
		(end 369.80368 -234.258358)
		(width 0.1143)
		(layer "In11.Cu")
		(net "P5E_CPU0_G3_RX_DP<5>")
	)
	(arc
		(start 369.732814 -227.819712)
		(mid 369.489487 -228.284278)
		(end 369.732814 -228.748844)
		(width 0.1143)
		(layer "In11.Cu")
		(net "P5E_CPU0_G3_RX_DP<5>")
	)
	(arc
		(start 369.80368 -232.029762)
		(mid 369.959608 -232.334054)
		(end 369.80368 -232.638346)
		(width 0.1143)
		(layer "In11.Cu")
		(net "P5E_CPU0_G3_RX_DP<5>")
	)
	(arc
		(start 371.612668 -222.959676)
		(mid 371.433855 -223.162026)
		(end 371.369336 -223.424242)
		(width 0.1143)
		(layer "In11.Cu")
		(net "P5E_CPU0_G3_RX_DP<5>")
	)
	(arc
		(start 369.80368 -241.749834)
		(mid 369.959608 -242.054126)
		(end 369.80368 -242.358418)
		(width 0.1143)
		(layer "In11.Cu")
		(net "P5E_CPU0_G3_RX_DP<5>")
	)
	(arc
		(start 371.142768 -223.769682)
		(mid 370.963955 -223.972032)
		(end 370.899436 -224.234248)
		(width 0.1143)
		(layer "In11.Cu")
		(net "P5E_CPU0_G3_RX_DP<5>")
	)
	(arc
		(start 369.732814 -240.779554)
		(mid 369.489487 -241.24412)
		(end 369.732814 -241.708686)
		(width 0.1143)
		(layer "In11.Cu")
		(net "P5E_CPU0_G3_RX_DP<5>")
	)
	(arc
		(start 369.80241 -227.169472)
		(mid 369.959387 -227.474272)
		(end 369.80241 -227.779072)
		(width 0.1143)
		(layer "In11.Cu")
		(net "P5E_CPU0_G3_RX_DP<5>")
	)
	(arc
		(start 369.732814 -239.159542)
		(mid 369.489487 -239.624108)
		(end 369.732814 -240.088674)
		(width 0.1143)
		(layer "In11.Cu")
		(net "P5E_CPU0_G3_RX_DP<5>")
	)
	(arc
		(start 369.732814 -234.299506)
		(mid 369.489487 -234.764072)
		(end 369.732814 -235.228638)
		(width 0.1143)
		(layer "In11.Cu")
		(net "P5E_CPU0_G3_RX_DP<5>")
	)
	(arc
		(start 369.959382 -229.094284)
		(mid 369.918416 -229.26469)
		(end 369.804442 -229.397814)
		(width 0.1143)
		(layer "In11.Cu")
		(net "P5E_CPU0_G3_RX_DP<5>")
	)
	(arc
		(start 369.80368 -246.60987)
		(mid 369.918356 -246.743204)
		(end 369.959636 -246.914162)
		(width 0.1143)
		(layer "In11.Cu")
		(net "P5E_CPU0_G3_RX_DP<5>")
	)
	(segment
		(start 418.956998 -7.709154)
		(end 418.956998 -8.320024)
		(width 0.12954)
		(layer "F.Cu")
		(net "P5E_CPU0_G3_RX_DP<4>")
	)
	(segment
		(start 419.095682 -7.57047)
		(end 418.956998 -7.709154)
		(width 0.12954)
		(layer "F.Cu")
		(net "P5E_CPU0_G3_RX_DP<4>")
	)
	(segment
		(start 369.588034 -244.750082)
		(end 370.054886 -244.484144)
		(width 0.12954)
		(layer "F.Cu")
		(net "P5E_CPU0_G3_RX_DP<4>")
	)
	(segment
		(start 419.095682 -5.228844)
		(end 419.095682 -7.57047)
		(width 0.12954)
		(layer "F.Cu")
		(net "P5E_CPU0_G3_RX_DP<4>")
	)
	(segment
		(start 418.830252 -4.963414)
		(end 419.095682 -5.228844)
		(width 0.12954)
		(layer "F.Cu")
		(net "P5E_CPU0_G3_RX_DP<4>")
	)
	(segment
		(start 370.712746 -228.772212)
		(end 370.713254 -228.772466)
		(width 0.1143)
		(layer "In11.Cu")
		(net "P5E_CPU0_G3_RX_DP<4>")
	)
	(segment
		(start 419.121082 -5.254244)
		(end 419.121082 -11.435588)
		(width 0.14224)
		(layer "In11.Cu")
		(net "P5E_CPU0_G3_RX_DP<4>")
	)
	(segment
		(start 370.745512 -229.397052)
		(end 370.672868 -229.43947)
		(width 0.1143)
		(layer "In11.Cu")
		(net "P5E_CPU0_G3_RX_DP<4>")
	)
	(segment
		(start 370.710968 -228.771196)
		(end 370.711984 -228.771704)
		(width 0.1143)
		(layer "In11.Cu")
		(net "P5E_CPU0_G3_RX_DP<4>")
	)
	(segment
		(start 372.591838 -222.936816)
		(end 372.555516 -222.957644)
		(width 0.1143)
		(layer "In11.Cu")
		(net "P5E_CPU0_G3_RX_DP<4>")
	)
	(segment
		(start 370.711984 -243.996718)
		(end 370.710968 -243.997226)
		(width 0.1143)
		(layer "In11.Cu")
		(net "P5E_CPU0_G3_RX_DP<4>")
	)
	(segment
		(start 371.180106 -225.36785)
		(end 371.178582 -225.368866)
		(width 0.1143)
		(layer "In11.Cu")
		(net "P5E_CPU0_G3_RX_DP<4>")
	)
	(segment
		(start 370.690902 -238.47933)
		(end 370.691156 -238.47933)
		(width 0.1143)
		(layer "In11.Cu")
		(net "P5E_CPU0_G3_RX_DP<4>")
	)
	(segment
		(start 370.719858 -235.892086)
		(end 370.708936 -235.898436)
		(width 0.1143)
		(layer "In11.Cu")
		(net "P5E_CPU0_G3_RX_DP<4>")
	)
	(segment
		(start 420.323518 -17.71269)
		(end 420.281354 -17.814798)
		(width 0.14224)
		(layer "In11.Cu")
		(net "P5E_CPU0_G3_RX_DP<4>")
	)
	(segment
		(start 370.711984 -227.796852)
		(end 370.710968 -227.79736)
		(width 0.1143)
		(layer "In11.Cu")
		(net "P5E_CPU0_G3_RX_DP<4>")
	)
	(segment
		(start 370.690902 -240.099342)
		(end 370.691156 -240.099342)
		(width 0.1143)
		(layer "In11.Cu")
		(net "P5E_CPU0_G3_RX_DP<4>")
	)
	(segment
		(start 370.690902 -235.239306)
		(end 370.691156 -235.239306)
		(width 0.1143)
		(layer "In11.Cu")
		(net "P5E_CPU0_G3_RX_DP<4>")
	)
	(segment
		(start 419.121082 -11.435588)
		(end 420.325296 -17.489932)
		(width 0.14224)
		(layer "In11.Cu")
		(net "P5E_CPU0_G3_RX_DP<4>")
	)
	(segment
		(start 316.117224 -161.044128)
		(end 316.117224 -161.440876)
		(width 0.14224)
		(layer "In11.Cu")
		(net "P5E_CPU0_G3_RX_DP<4>")
	)
	(segment
		(start 370.719858 -239.13211)
		(end 370.707412 -239.139222)
		(width 0.1143)
		(layer "In11.Cu")
		(net "P5E_CPU0_G3_RX_DP<4>")
	)
	(segment
		(start 370.435632 -244.40134)
		(end 370.352828 -244.484144)
		(width 0.1143)
		(layer "In11.Cu")
		(net "P5E_CPU0_G3_RX_DP<4>")
	)
	(segment
		(start 370.707412 -235.899198)
		(end 370.70665 -235.899706)
		(width 0.1143)
		(layer "In11.Cu")
		(net "P5E_CPU0_G3_RX_DP<4>")
	)
	(segment
		(start 370.672868 -243.328698)
		(end 370.709444 -243.350034)
		(width 0.1143)
		(layer "In11.Cu")
		(net "P5E_CPU0_G3_RX_DP<4>")
	)
	(segment
		(start 372.121938 -223.746822)
		(end 372.082822 -223.769682)
		(width 0.1143)
		(layer "In11.Cu")
		(net "P5E_CPU0_G3_RX_DP<4>")
	)
	(segment
		(start 373.093488 -222.108522)
		(end 373.061738 -222.12681)
		(width 0.1143)
		(layer "In11.Cu")
		(net "P5E_CPU0_G3_RX_DP<4>")
	)
	(segment
		(start 370.712746 -230.392224)
		(end 370.714016 -230.392986)
		(width 0.1143)
		(layer "In11.Cu")
		(net "P5E_CPU0_G3_RX_DP<4>")
	)
	(segment
		(start 370.711984 -234.276646)
		(end 370.676424 -234.296966)
		(width 0.1143)
		(layer "In11.Cu")
		(net "P5E_CPU0_G3_RX_DP<4>")
	)
	(segment
		(start 370.672868 -233.608626)
		(end 370.709444 -233.629962)
		(width 0.1143)
		(layer "In11.Cu")
		(net "P5E_CPU0_G3_RX_DP<4>")
	)
	(segment
		(start 370.708936 -235.898436)
		(end 370.707412 -235.899198)
		(width 0.1143)
		(layer "In11.Cu")
		(net "P5E_CPU0_G3_RX_DP<4>")
	)
	(segment
		(start 317.321692 -164.319204)
		(end 319.790318 -166.750746)
		(width 0.14224)
		(layer "In11.Cu")
		(net "P5E_CPU0_G3_RX_DP<4>")
	)
	(segment
		(start 370.709444 -243.998242)
		(end 370.672868 -244.019578)
		(width 0.1143)
		(layer "In11.Cu")
		(net "P5E_CPU0_G3_RX_DP<4>")
	)
	(segment
		(start 370.742718 -226.15906)
		(end 370.711984 -226.17684)
		(width 0.1143)
		(layer "In11.Cu")
		(net "P5E_CPU0_G3_RX_DP<4>")
	)
	(segment
		(start 370.672868 -227.128832)
		(end 370.675662 -227.130864)
		(width 0.1143)
		(layer "In11.Cu")
		(net "P5E_CPU0_G3_RX_DP<4>")
	)
	(segment
		(start 370.67998 -235.9152)
		(end 370.67363 -235.91901)
		(width 0.1143)
		(layer "In11.Cu")
		(net "P5E_CPU0_G3_RX_DP<4>")
	)
	(segment
		(start 370.710968 -227.79736)
		(end 370.709444 -227.798376)
		(width 0.1143)
		(layer "In11.Cu")
		(net "P5E_CPU0_G3_RX_DP<4>")
	)
	(segment
		(start 420.325296 -17.489932)
		(end 420.325296 -17.708626)
		(width 0.14224)
		(layer "In11.Cu")
		(net "P5E_CPU0_G3_RX_DP<4>")
	)
	(segment
		(start 370.714016 -230.392986)
		(end 370.71554 -230.393748)
		(width 0.1143)
		(layer "In11.Cu")
		(net "P5E_CPU0_G3_RX_DP<4>")
	)
	(segment
		(start 418.830252 -4.963414)
		(end 419.121082 -5.254244)
		(width 0.14224)
		(layer "In11.Cu")
		(net "P5E_CPU0_G3_RX_DP<4>")
	)
	(segment
		(start 419.977316 -18.382742)
		(end 419.977062 -18.382742)
		(width 0.14224)
		(layer "In11.Cu")
		(net "P5E_CPU0_G3_RX_DP<4>")
	)
	(segment
		(start 370.690902 -236.859318)
		(end 370.691156 -236.859318)
		(width 0.1143)
		(layer "In11.Cu")
		(net "P5E_CPU0_G3_RX_DP<4>")
	)
	(segment
		(start 370.691156 -241.719354)
		(end 370.712492 -241.7318)
		(width 0.1143)
		(layer "In11.Cu")
		(net "P5E_CPU0_G3_RX_DP<4>")
	)
	(segment
		(start 370.709698 -230.390446)
		(end 370.710968 -230.391208)
		(width 0.1143)
		(layer "In11.Cu")
		(net "P5E_CPU0_G3_RX_DP<4>")
	)
	(segment
		(start 370.672868 -238.468662)
		(end 370.690902 -238.47933)
		(width 0.1143)
		(layer "In11.Cu")
		(net "P5E_CPU0_G3_RX_DP<4>")
	)
	(segment
		(start 323.776848 -169.304208)
		(end 327.130156 -171.55541)
		(width 0.14224)
		(layer "In11.Cu")
		(net "P5E_CPU0_G3_RX_DP<4>")
	)
	(segment
		(start 370.712746 -227.796344)
		(end 370.711984 -227.796852)
		(width 0.1143)
		(layer "In11.Cu")
		(net "P5E_CPU0_G3_RX_DP<4>")
	)
	(segment
		(start 370.712746 -243.352066)
		(end 370.743734 -243.369846)
		(width 0.1143)
		(layer "In11.Cu")
		(net "P5E_CPU0_G3_RX_DP<4>")
	)
	(segment
		(start 370.719858 -242.372134)
		(end 370.707412 -242.379246)
		(width 0.1143)
		(layer "In11.Cu")
		(net "P5E_CPU0_G3_RX_DP<4>")
	)
	(segment
		(start 372.623588 -222.918528)
		(end 372.591838 -222.936816)
		(width 0.1143)
		(layer "In11.Cu")
		(net "P5E_CPU0_G3_RX_DP<4>")
	)
	(segment
		(start 370.710968 -232.657142)
		(end 370.672868 -232.679494)
		(width 0.1143)
		(layer "In11.Cu")
		(net "P5E_CPU0_G3_RX_DP<4>")
	)
	(segment
		(start 370.743734 -232.638346)
		(end 370.712746 -232.656126)
		(width 0.1143)
		(layer "In11.Cu")
		(net "P5E_CPU0_G3_RX_DP<4>")
	)
	(segment
		(start 370.352828 -244.484144)
		(end 370.054886 -244.484144)
		(width 0.1143)
		(layer "In11.Cu")
		(net "P5E_CPU0_G3_RX_DP<4>")
	)
	(segment
		(start 370.70665 -239.13973)
		(end 370.705634 -239.140238)
		(width 0.1143)
		(layer "In11.Cu")
		(net "P5E_CPU0_G3_RX_DP<4>")
	)
	(segment
		(start 370.705634 -242.380262)
		(end 370.67363 -242.399058)
		(width 0.1143)
		(layer "In11.Cu")
		(net "P5E_CPU0_G3_RX_DP<4>")
	)
	(segment
		(start 323.771006 -169.305478)
		(end 323.776848 -169.304208)
		(width 0.14224)
		(layer "In11.Cu")
		(net "P5E_CPU0_G3_RX_DP<4>")
	)
	(segment
		(start 370.708936 -230.389938)
		(end 370.709698 -230.390446)
		(width 0.1143)
		(layer "In11.Cu")
		(net "P5E_CPU0_G3_RX_DP<4>")
	)
	(segment
		(start 371.181884 -225.366834)
		(end 371.180106 -225.36785)
		(width 0.1143)
		(layer "In11.Cu")
		(net "P5E_CPU0_G3_RX_DP<4>")
	)
	(segment
		(start 370.70665 -235.899706)
		(end 370.680742 -235.914692)
		(width 0.1143)
		(layer "In11.Cu")
		(net "P5E_CPU0_G3_RX_DP<4>")
	)
	(segment
		(start 370.712746 -233.631994)
		(end 370.743734 -233.649774)
		(width 0.1143)
		(layer "In11.Cu")
		(net "P5E_CPU0_G3_RX_DP<4>")
	)
	(segment
		(start 370.675408 -230.37038)
		(end 370.67998 -230.373174)
		(width 0.1143)
		(layer "In11.Cu")
		(net "P5E_CPU0_G3_RX_DP<4>")
	)
	(segment
		(start 371.748558 -213.932262)
		(end 373.203724 -220.389704)
		(width 0.14224)
		(layer "In11.Cu")
		(net "P5E_CPU0_G3_RX_DP<4>")
	)
	(segment
		(start 370.70665 -240.759742)
		(end 370.705634 -240.76025)
		(width 0.1143)
		(layer "In11.Cu")
		(net "P5E_CPU0_G3_RX_DP<4>")
	)
	(segment
		(start 370.743734 -243.97843)
		(end 370.712746 -243.99621)
		(width 0.1143)
		(layer "In11.Cu")
		(net "P5E_CPU0_G3_RX_DP<4>")
	)
	(segment
		(start 328.774298 -172.83811)
		(end 330.430886 -174.338234)
		(width 0.14224)
		(layer "In11.Cu")
		(net "P5E_CPU0_G3_RX_DP<4>")
	)
	(segment
		(start 419.977062 -18.382742)
		(end 418.98062 -19.87423)
		(width 0.14224)
		(layer "In11.Cu")
		(net "P5E_CPU0_G3_RX_DP<4>")
	)
	(segment
		(start 370.709444 -232.00995)
		(end 370.710968 -232.010966)
		(width 0.1143)
		(layer "In11.Cu")
		(net "P5E_CPU0_G3_RX_DP<4>")
	)
	(segment
		(start 370.691156 -236.859318)
		(end 370.712492 -236.871764)
		(width 0.1143)
		(layer "In11.Cu")
		(net "P5E_CPU0_G3_RX_DP<4>")
	)
	(segment
		(start 370.691156 -235.239306)
		(end 370.712492 -235.251752)
		(width 0.1143)
		(layer "In11.Cu")
		(net "P5E_CPU0_G3_RX_DP<4>")
	)
	(segment
		(start 373.249444 -221.248478)
		(end 373.249444 -221.80423)
		(width 0.1143)
		(layer "In11.Cu")
		(net "P5E_CPU0_G3_RX_DP<4>")
	)
	(segment
		(start 370.675662 -227.130864)
		(end 370.711984 -227.151692)
		(width 0.1143)
		(layer "In11.Cu")
		(net "P5E_CPU0_G3_RX_DP<4>")
	)
	(segment
		(start 370.67998 -230.373174)
		(end 370.708936 -230.389938)
		(width 0.1143)
		(layer "In11.Cu")
		(net "P5E_CPU0_G3_RX_DP<4>")
	)
	(segment
		(start 373.203724 -221.202758)
		(end 373.249444 -221.248478)
		(width 0.1143)
		(layer "In11.Cu")
		(net "P5E_CPU0_G3_RX_DP<4>")
	)
	(segment
		(start 372.555516 -222.957644)
		(end 372.552722 -222.959676)
		(width 0.1143)
		(layer "In11.Cu")
		(net "P5E_CPU0_G3_RX_DP<4>")
	)
	(segment
		(start 370.691156 -238.47933)
		(end 370.712492 -238.491776)
		(width 0.1143)
		(layer "In11.Cu")
		(net "P5E_CPU0_G3_RX_DP<4>")
	)
	(segment
		(start 370.710968 -232.010966)
		(end 370.711984 -232.011474)
		(width 0.1143)
		(layer "In11.Cu")
		(net "P5E_CPU0_G3_RX_DP<4>")
	)
	(segment
		(start 370.710968 -243.997226)
		(end 370.709444 -243.998242)
		(width 0.1143)
		(layer "In11.Cu")
		(net "P5E_CPU0_G3_RX_DP<4>")
	)
	(segment
		(start 370.710968 -233.630978)
		(end 370.711984 -233.631486)
		(width 0.1143)
		(layer "In11.Cu")
		(net "P5E_CPU0_G3_RX_DP<4>")
	)
	(segment
		(start 370.707412 -237.51921)
		(end 370.70665 -237.519718)
		(width 0.1143)
		(layer "In11.Cu")
		(net "P5E_CPU0_G3_RX_DP<4>")
	)
	(segment
		(start 371.683534 -224.53854)
		(end 371.651784 -224.556828)
		(width 0.1143)
		(layer "In11.Cu")
		(net "P5E_CPU0_G3_RX_DP<4>")
	)
	(segment
		(start 370.712746 -243.99621)
		(end 370.711984 -243.996718)
		(width 0.1143)
		(layer "In11.Cu")
		(net "P5E_CPU0_G3_RX_DP<4>")
	)
	(segment
		(start 370.711984 -233.631486)
		(end 370.712746 -233.631994)
		(width 0.1143)
		(layer "In11.Cu")
		(net "P5E_CPU0_G3_RX_DP<4>")
	)
	(segment
		(start 370.690902 -241.719354)
		(end 370.691156 -241.719354)
		(width 0.1143)
		(layer "In11.Cu")
		(net "P5E_CPU0_G3_RX_DP<4>")
	)
	(segment
		(start 372.152418 -223.729042)
		(end 372.121938 -223.746822)
		(width 0.1143)
		(layer "In11.Cu")
		(net "P5E_CPU0_G3_RX_DP<4>")
	)
	(segment
		(start 418.878766 -20.018756)
		(end 387.697726 -56.268112)
		(width 0.14224)
		(layer "In11.Cu")
		(net "P5E_CPU0_G3_RX_DP<4>")
	)
	(segment
		(start 370.710968 -230.391208)
		(end 370.711984 -230.391716)
		(width 0.1143)
		(layer "In11.Cu")
		(net "P5E_CPU0_G3_RX_DP<4>")
	)
	(segment
		(start 371.651784 -224.556828)
		(end 371.616986 -224.576894)
		(width 0.1143)
		(layer "In11.Cu")
		(net "P5E_CPU0_G3_RX_DP<4>")
	)
	(segment
		(start 327.130156 -171.55541)
		(end 328.774298 -172.83811)
		(width 0.14224)
		(layer "In11.Cu")
		(net "P5E_CPU0_G3_RX_DP<4>")
	)
	(segment
		(start 365.10722 -202.748388)
		(end 371.748558 -213.932262)
		(width 0.14224)
		(layer "In11.Cu")
		(net "P5E_CPU0_G3_RX_DP<4>")
	)
	(segment
		(start 323.75475 -134.221982)
		(end 318.079628 -149.874732)
		(width 0.14224)
		(layer "In11.Cu")
		(net "P5E_CPU0_G3_RX_DP<4>")
	)
	(segment
		(start 370.711984 -230.391716)
		(end 370.712746 -230.392224)
		(width 0.1143)
		(layer "In11.Cu")
		(net "P5E_CPU0_G3_RX_DP<4>")
	)
	(segment
		(start 370.70665 -242.379754)
		(end 370.705634 -242.380262)
		(width 0.1143)
		(layer "In11.Cu")
		(net "P5E_CPU0_G3_RX_DP<4>")
	)
	(segment
		(start 370.722144 -231.03078)
		(end 370.672868 -231.059482)
		(width 0.1143)
		(layer "In11.Cu")
		(net "P5E_CPU0_G3_RX_DP<4>")
	)
	(segment
		(start 370.707412 -242.379246)
		(end 370.70665 -242.379754)
		(width 0.1143)
		(layer "In11.Cu")
		(net "P5E_CPU0_G3_RX_DP<4>")
	)
	(segment
		(start 370.691156 -240.099342)
		(end 370.712492 -240.111788)
		(width 0.1143)
		(layer "In11.Cu")
		(net "P5E_CPU0_G3_RX_DP<4>")
	)
	(segment
		(start 373.061738 -222.12681)
		(end 373.025416 -222.147892)
		(width 0.1143)
		(layer "In11.Cu")
		(net "P5E_CPU0_G3_RX_DP<4>")
	)
	(segment
		(start 370.743734 -234.258358)
		(end 370.711984 -234.276646)
		(width 0.1143)
		(layer "In11.Cu")
		(net "P5E_CPU0_G3_RX_DP<4>")
	)
	(segment
		(start 370.712746 -232.656126)
		(end 370.711984 -232.656634)
		(width 0.1143)
		(layer "In11.Cu")
		(net "P5E_CPU0_G3_RX_DP<4>")
	)
	(segment
		(start 370.711984 -232.656634)
		(end 370.710968 -232.657142)
		(width 0.1143)
		(layer "In11.Cu")
		(net "P5E_CPU0_G3_RX_DP<4>")
	)
	(segment
		(start 370.709444 -233.629962)
		(end 370.710968 -233.630978)
		(width 0.1143)
		(layer "In11.Cu")
		(net "P5E_CPU0_G3_RX_DP<4>")
	)
	(segment
		(start 370.672868 -241.708686)
		(end 370.690902 -241.719354)
		(width 0.1143)
		(layer "In11.Cu")
		(net "P5E_CPU0_G3_RX_DP<4>")
	)
	(segment
		(start 370.672868 -231.988614)
		(end 370.709444 -232.00995)
		(width 0.1143)
		(layer "In11.Cu")
		(net "P5E_CPU0_G3_RX_DP<4>")
	)
	(segment
		(start 370.707412 -239.139222)
		(end 370.70665 -239.13973)
		(width 0.1143)
		(layer "In11.Cu")
		(net "P5E_CPU0_G3_RX_DP<4>")
	)
	(segment
		(start 370.719858 -237.512098)
		(end 370.707412 -237.51921)
		(width 0.1143)
		(layer "In11.Cu")
		(net "P5E_CPU0_G3_RX_DP<4>")
	)
	(segment
		(start 370.672868 -236.84865)
		(end 370.690902 -236.859318)
		(width 0.1143)
		(layer "In11.Cu")
		(net "P5E_CPU0_G3_RX_DP<4>")
	)
	(segment
		(start 370.743734 -227.778564)
		(end 370.712746 -227.796344)
		(width 0.1143)
		(layer "In11.Cu")
		(net "P5E_CPU0_G3_RX_DP<4>")
	)
	(segment
		(start 418.98062 -19.87423)
		(end 418.878766 -20.018756)
		(width 0.14224)
		(layer "In11.Cu")
		(net "P5E_CPU0_G3_RX_DP<4>")
	)
	(segment
		(start 370.711984 -232.011474)
		(end 370.712746 -232.011982)
		(width 0.1143)
		(layer "In11.Cu")
		(net "P5E_CPU0_G3_RX_DP<4>")
	)
	(segment
		(start 330.430886 -174.338234)
		(end 365.10722 -202.748388)
		(width 0.14224)
		(layer "In11.Cu")
		(net "P5E_CPU0_G3_RX_DP<4>")
	)
	(segment
		(start 370.71554 -230.393748)
		(end 370.743734 -230.410004)
		(width 0.1143)
		(layer "In11.Cu")
		(net "P5E_CPU0_G3_RX_DP<4>")
	)
	(segment
		(start 370.719858 -240.752122)
		(end 370.707412 -240.759234)
		(width 0.1143)
		(layer "In11.Cu")
		(net "P5E_CPU0_G3_RX_DP<4>")
	)
	(segment
		(start 370.711984 -228.771704)
		(end 370.712746 -228.772212)
		(width 0.1143)
		(layer "In11.Cu")
		(net "P5E_CPU0_G3_RX_DP<4>")
	)
	(segment
		(start 371.178582 -225.368866)
		(end 371.145562 -225.387916)
		(width 0.1143)
		(layer "In11.Cu")
		(net "P5E_CPU0_G3_RX_DP<4>")
	)
	(segment
		(start 371.213634 -225.348546)
		(end 371.181884 -225.366834)
		(width 0.1143)
		(layer "In11.Cu")
		(net "P5E_CPU0_G3_RX_DP<4>")
	)
	(segment
		(start 387.697726 -56.268112)
		(end 326.27316 -129.840482)
		(width 0.14224)
		(layer "In11.Cu")
		(net "P5E_CPU0_G3_RX_DP<4>")
	)
	(segment
		(start 370.705634 -240.76025)
		(end 370.67363 -240.779046)
		(width 0.1143)
		(layer "In11.Cu")
		(net "P5E_CPU0_G3_RX_DP<4>")
	)
	(segment
		(start 370.709444 -243.350034)
		(end 370.710968 -243.35105)
		(width 0.1143)
		(layer "In11.Cu")
		(net "P5E_CPU0_G3_RX_DP<4>")
	)
	(segment
		(start 316.117224 -161.440876)
		(end 316.117478 -161.441384)
		(width 0.14224)
		(layer "In11.Cu")
		(net "P5E_CPU0_G3_RX_DP<4>")
	)
	(segment
		(start 370.672868 -240.088674)
		(end 370.690902 -240.099342)
		(width 0.1143)
		(layer "In11.Cu")
		(net "P5E_CPU0_G3_RX_DP<4>")
	)
	(segment
		(start 370.710968 -243.35105)
		(end 370.711984 -243.351558)
		(width 0.1143)
		(layer "In11.Cu")
		(net "P5E_CPU0_G3_RX_DP<4>")
	)
	(segment
		(start 370.672868 -235.228638)
		(end 370.690902 -235.239306)
		(width 0.1143)
		(layer "In11.Cu")
		(net "P5E_CPU0_G3_RX_DP<4>")
	)
	(segment
		(start 370.712746 -232.011982)
		(end 370.743734 -232.029762)
		(width 0.1143)
		(layer "In11.Cu")
		(net "P5E_CPU0_G3_RX_DP<4>")
	)
	(segment
		(start 370.705634 -239.140238)
		(end 370.67363 -239.159034)
		(width 0.1143)
		(layer "In11.Cu")
		(net "P5E_CPU0_G3_RX_DP<4>")
	)
	(segment
		(start 373.203724 -220.389704)
		(end 373.203724 -221.17431)
		(width 0.14224)
		(layer "In11.Cu")
		(net "P5E_CPU0_G3_RX_DP<4>")
	)
	(segment
		(start 370.676424 -234.296966)
		(end 370.67363 -234.298998)
		(width 0.1143)
		(layer "In11.Cu")
		(net "P5E_CPU0_G3_RX_DP<4>")
	)
	(segment
		(start 370.680742 -235.914692)
		(end 370.67998 -235.9152)
		(width 0.1143)
		(layer "In11.Cu")
		(net "P5E_CPU0_G3_RX_DP<4>")
	)
	(segment
		(start 420.281354 -17.814798)
		(end 419.977316 -18.382742)
		(width 0.14224)
		(layer "In11.Cu")
		(net "P5E_CPU0_G3_RX_DP<4>")
	)
	(segment
		(start 373.203724 -221.17431)
		(end 373.203724 -221.202758)
		(width 0.1143)
		(layer "In11.Cu")
		(net "P5E_CPU0_G3_RX_DP<4>")
	)
	(segment
		(start 370.709444 -228.77018)
		(end 370.710968 -228.771196)
		(width 0.1143)
		(layer "In11.Cu")
		(net "P5E_CPU0_G3_RX_DP<4>")
	)
	(segment
		(start 370.711984 -226.17684)
		(end 370.672868 -226.1997)
		(width 0.1143)
		(layer "In11.Cu")
		(net "P5E_CPU0_G3_RX_DP<4>")
	)
	(segment
		(start 319.790318 -166.750746)
		(end 323.771006 -169.305478)
		(width 0.14224)
		(layer "In11.Cu")
		(net "P5E_CPU0_G3_RX_DP<4>")
	)
	(segment
		(start 370.705634 -237.520226)
		(end 370.67363 -237.539022)
		(width 0.1143)
		(layer "In11.Cu")
		(net "P5E_CPU0_G3_RX_DP<4>")
	)
	(segment
		(start 316.117478 -161.442146)
		(end 317.321692 -164.319204)
		(width 0.14224)
		(layer "In11.Cu")
		(net "P5E_CPU0_G3_RX_DP<4>")
	)
	(segment
		(start 316.117478 -161.441384)
		(end 316.117478 -161.442146)
		(width 0.14224)
		(layer "In11.Cu")
		(net "P5E_CPU0_G3_RX_DP<4>")
	)
	(segment
		(start 326.27316 -129.840482)
		(end 323.75475 -134.221982)
		(width 0.14224)
		(layer "In11.Cu")
		(net "P5E_CPU0_G3_RX_DP<4>")
	)
	(segment
		(start 420.325296 -17.708626)
		(end 420.323518 -17.71269)
		(width 0.14224)
		(layer "In11.Cu")
		(net "P5E_CPU0_G3_RX_DP<4>")
	)
	(segment
		(start 370.711984 -227.151692)
		(end 370.743734 -227.16998)
		(width 0.1143)
		(layer "In11.Cu")
		(net "P5E_CPU0_G3_RX_DP<4>")
	)
	(segment
		(start 371.616986 -224.576894)
		(end 371.612922 -224.579688)
		(width 0.1143)
		(layer "In11.Cu")
		(net "P5E_CPU0_G3_RX_DP<4>")
	)
	(segment
		(start 370.711984 -243.351558)
		(end 370.712746 -243.352066)
		(width 0.1143)
		(layer "In11.Cu")
		(net "P5E_CPU0_G3_RX_DP<4>")
	)
	(segment
		(start 318.079628 -149.874732)
		(end 316.117224 -161.044128)
		(width 0.14224)
		(layer "In11.Cu")
		(net "P5E_CPU0_G3_RX_DP<4>")
	)
	(segment
		(start 370.709444 -227.798376)
		(end 370.672868 -227.819712)
		(width 0.1143)
		(layer "In11.Cu")
		(net "P5E_CPU0_G3_RX_DP<4>")
	)
	(segment
		(start 370.672868 -228.748844)
		(end 370.709444 -228.77018)
		(width 0.1143)
		(layer "In11.Cu")
		(net "P5E_CPU0_G3_RX_DP<4>")
	)
	(segment
		(start 370.70665 -237.519718)
		(end 370.705634 -237.520226)
		(width 0.1143)
		(layer "In11.Cu")
		(net "P5E_CPU0_G3_RX_DP<4>")
	)
	(segment
		(start 370.707412 -240.759234)
		(end 370.70665 -240.759742)
		(width 0.1143)
		(layer "In11.Cu")
		(net "P5E_CPU0_G3_RX_DP<4>")
	)
	(arc
		(start 373.025416 -222.147892)
		(mid 373.017238 -222.153535)
		(end 373.00916 -222.159322)
		(width 0.1143)
		(layer "In11.Cu")
		(net "P5E_CPU0_G3_RX_DP<4>")
	)
	(arc
		(start 370.672868 -237.53953)
		(mid 370.429541 -238.004096)
		(end 370.672868 -238.468662)
		(width 0.1143)
		(layer "In11.Cu")
		(net "P5E_CPU0_G3_RX_DP<4>")
	)
	(arc
		(start 370.713254 -228.772466)
		(mid 370.849672 -228.908339)
		(end 370.89969 -229.094284)
		(width 0.1143)
		(layer "In11.Cu")
		(net "P5E_CPU0_G3_RX_DP<4>")
	)
	(arc
		(start 370.67363 -237.539022)
		(mid 370.673249 -237.539276)
		(end 370.672868 -237.53953)
		(width 0.1143)
		(layer "In11.Cu")
		(net "P5E_CPU0_G3_RX_DP<4>")
	)
	(arc
		(start 370.429536 -229.904036)
		(mid 370.494772 -230.167627)
		(end 370.675408 -230.37038)
		(width 0.1143)
		(layer "In11.Cu")
		(net "P5E_CPU0_G3_RX_DP<4>")
	)
	(arc
		(start 370.743734 -243.369846)
		(mid 370.892831 -243.674138)
		(end 370.743734 -243.97843)
		(width 0.1143)
		(layer "In11.Cu")
		(net "P5E_CPU0_G3_RX_DP<4>")
	)
	(arc
		(start 373.00916 -222.159322)
		(mid 372.844493 -222.357929)
		(end 372.779544 -222.607632)
		(width 0.1143)
		(layer "In11.Cu")
		(net "P5E_CPU0_G3_RX_DP<4>")
	)
	(arc
		(start 371.114066 -225.412554)
		(mid 370.981648 -225.585735)
		(end 370.907564 -225.79076)
		(width 0.1143)
		(layer "In11.Cu")
		(net "P5E_CPU0_G3_RX_DP<4>")
	)
	(arc
		(start 370.743734 -230.410004)
		(mid 370.856754 -230.54418)
		(end 370.89969 -230.714296)
		(width 0.1143)
		(layer "In11.Cu")
		(net "P5E_CPU0_G3_RX_DP<4>")
	)
	(arc
		(start 371.83949 -224.234248)
		(mid 371.798235 -224.405219)
		(end 371.683534 -224.53854)
		(width 0.1143)
		(layer "In11.Cu")
		(net "P5E_CPU0_G3_RX_DP<4>")
	)
	(arc
		(start 370.672868 -227.819712)
		(mid 370.429541 -228.284278)
		(end 370.672868 -228.748844)
		(width 0.1143)
		(layer "In11.Cu")
		(net "P5E_CPU0_G3_RX_DP<4>")
	)
	(arc
		(start 371.36959 -225.044254)
		(mid 371.328335 -225.215225)
		(end 371.213634 -225.348546)
		(width 0.1143)
		(layer "In11.Cu")
		(net "P5E_CPU0_G3_RX_DP<4>")
	)
	(arc
		(start 370.672868 -234.299506)
		(mid 370.429541 -234.764072)
		(end 370.672868 -235.228638)
		(width 0.1143)
		(layer "In11.Cu")
		(net "P5E_CPU0_G3_RX_DP<4>")
	)
	(arc
		(start 370.712492 -235.251752)
		(mid 370.898012 -235.569809)
		(end 370.719858 -235.892086)
		(width 0.1143)
		(layer "In11.Cu")
		(net "P5E_CPU0_G3_RX_DP<4>")
	)
	(arc
		(start 370.672868 -239.159542)
		(mid 370.429541 -239.624108)
		(end 370.672868 -240.088674)
		(width 0.1143)
		(layer "In11.Cu")
		(net "P5E_CPU0_G3_RX_DP<4>")
	)
	(arc
		(start 370.672868 -235.919518)
		(mid 370.429541 -236.384084)
		(end 370.672868 -236.84865)
		(width 0.1143)
		(layer "In11.Cu")
		(net "P5E_CPU0_G3_RX_DP<4>")
	)
	(arc
		(start 372.082822 -223.769682)
		(mid 371.904009 -223.972032)
		(end 371.83949 -224.234248)
		(width 0.1143)
		(layer "In11.Cu")
		(net "P5E_CPU0_G3_RX_DP<4>")
	)
	(arc
		(start 370.89969 -230.714296)
		(mid 370.85401 -230.896707)
		(end 370.722144 -231.03078)
		(width 0.1143)
		(layer "In11.Cu")
		(net "P5E_CPU0_G3_RX_DP<4>")
	)
	(arc
		(start 370.67363 -240.779046)
		(mid 370.673249 -240.7793)
		(end 370.672868 -240.779554)
		(width 0.1143)
		(layer "In11.Cu")
		(net "P5E_CPU0_G3_RX_DP<4>")
	)
	(arc
		(start 370.672868 -232.679494)
		(mid 370.429541 -233.14406)
		(end 370.672868 -233.608626)
		(width 0.1143)
		(layer "In11.Cu")
		(net "P5E_CPU0_G3_RX_DP<4>")
	)
	(arc
		(start 370.672868 -244.019578)
		(mid 370.520881 -244.176086)
		(end 370.439442 -244.37848)
		(width 0.1143)
		(layer "In11.Cu")
		(net "P5E_CPU0_G3_RX_DP<4>")
	)
	(arc
		(start 370.672868 -226.1997)
		(mid 370.429541 -226.664266)
		(end 370.672868 -227.128832)
		(width 0.1143)
		(layer "In11.Cu")
		(net "P5E_CPU0_G3_RX_DP<4>")
	)
	(arc
		(start 370.439442 -244.37848)
		(mid 370.437419 -244.38989)
		(end 370.435632 -244.40134)
		(width 0.1143)
		(layer "In11.Cu")
		(net "P5E_CPU0_G3_RX_DP<4>")
	)
	(arc
		(start 370.672868 -242.399566)
		(mid 370.429541 -242.864132)
		(end 370.672868 -243.328698)
		(width 0.1143)
		(layer "In11.Cu")
		(net "P5E_CPU0_G3_RX_DP<4>")
	)
	(arc
		(start 370.712492 -238.491776)
		(mid 370.898012 -238.809833)
		(end 370.719858 -239.13211)
		(width 0.1143)
		(layer "In11.Cu")
		(net "P5E_CPU0_G3_RX_DP<4>")
	)
	(arc
		(start 372.779544 -222.614236)
		(mid 372.735473 -222.783772)
		(end 372.623588 -222.918528)
		(width 0.1143)
		(layer "In11.Cu")
		(net "P5E_CPU0_G3_RX_DP<4>")
	)
	(arc
		(start 370.743734 -227.16998)
		(mid 370.892831 -227.474272)
		(end 370.743734 -227.778564)
		(width 0.1143)
		(layer "In11.Cu")
		(net "P5E_CPU0_G3_RX_DP<4>")
	)
	(arc
		(start 370.67363 -235.91901)
		(mid 370.673249 -235.919264)
		(end 370.672868 -235.919518)
		(width 0.1143)
		(layer "In11.Cu")
		(net "P5E_CPU0_G3_RX_DP<4>")
	)
	(arc
		(start 370.743734 -232.029762)
		(mid 370.892831 -232.334054)
		(end 370.743734 -232.638346)
		(width 0.1143)
		(layer "In11.Cu")
		(net "P5E_CPU0_G3_RX_DP<4>")
	)
	(arc
		(start 370.907564 -225.79076)
		(mid 370.902085 -225.827935)
		(end 370.89969 -225.865436)
		(width 0.1143)
		(layer "In11.Cu")
		(net "P5E_CPU0_G3_RX_DP<4>")
	)
	(arc
		(start 370.712492 -241.7318)
		(mid 370.898012 -242.049857)
		(end 370.719858 -242.372134)
		(width 0.1143)
		(layer "In11.Cu")
		(net "P5E_CPU0_G3_RX_DP<4>")
	)
	(arc
		(start 371.612922 -224.579688)
		(mid 371.434109 -224.782038)
		(end 371.36959 -225.044254)
		(width 0.1143)
		(layer "In11.Cu")
		(net "P5E_CPU0_G3_RX_DP<4>")
	)
	(arc
		(start 371.145562 -225.387916)
		(mid 371.129593 -225.399953)
		(end 371.114066 -225.412554)
		(width 0.1143)
		(layer "In11.Cu")
		(net "P5E_CPU0_G3_RX_DP<4>")
	)
	(arc
		(start 372.779544 -222.607632)
		(mid 372.779534 -222.610934)
		(end 372.779544 -222.614236)
		(width 0.1143)
		(layer "In11.Cu")
		(net "P5E_CPU0_G3_RX_DP<4>")
	)
	(arc
		(start 370.712492 -236.871764)
		(mid 370.898012 -237.189821)
		(end 370.719858 -237.512098)
		(width 0.1143)
		(layer "In11.Cu")
		(net "P5E_CPU0_G3_RX_DP<4>")
	)
	(arc
		(start 370.743734 -233.649774)
		(mid 370.895323 -233.954066)
		(end 370.743734 -234.258358)
		(width 0.1143)
		(layer "In11.Cu")
		(net "P5E_CPU0_G3_RX_DP<4>")
	)
	(arc
		(start 370.67363 -239.159034)
		(mid 370.673249 -239.159288)
		(end 370.672868 -239.159542)
		(width 0.1143)
		(layer "In11.Cu")
		(net "P5E_CPU0_G3_RX_DP<4>")
	)
	(arc
		(start 370.672868 -240.779554)
		(mid 370.429541 -241.24412)
		(end 370.672868 -241.708686)
		(width 0.1143)
		(layer "In11.Cu")
		(net "P5E_CPU0_G3_RX_DP<4>")
	)
	(arc
		(start 372.30939 -223.424242)
		(mid 372.267841 -223.595664)
		(end 372.152418 -223.729042)
		(width 0.1143)
		(layer "In11.Cu")
		(net "P5E_CPU0_G3_RX_DP<4>")
	)
	(arc
		(start 372.552722 -222.959676)
		(mid 372.373909 -223.162026)
		(end 372.30939 -223.424242)
		(width 0.1143)
		(layer "In11.Cu")
		(net "P5E_CPU0_G3_RX_DP<4>")
	)
	(arc
		(start 370.712492 -240.111788)
		(mid 370.898012 -240.429845)
		(end 370.719858 -240.752122)
		(width 0.1143)
		(layer "In11.Cu")
		(net "P5E_CPU0_G3_RX_DP<4>")
	)
	(arc
		(start 370.89969 -225.865436)
		(mid 370.855626 -226.030659)
		(end 370.742718 -226.15906)
		(width 0.1143)
		(layer "In11.Cu")
		(net "P5E_CPU0_G3_RX_DP<4>")
	)
	(arc
		(start 370.672868 -229.43947)
		(mid 370.494055 -229.64182)
		(end 370.429536 -229.904036)
		(width 0.1143)
		(layer "In11.Cu")
		(net "P5E_CPU0_G3_RX_DP<4>")
	)
	(arc
		(start 370.67363 -234.298998)
		(mid 370.673249 -234.299252)
		(end 370.672868 -234.299506)
		(width 0.1143)
		(layer "In11.Cu")
		(net "P5E_CPU0_G3_RX_DP<4>")
	)
	(arc
		(start 373.249444 -221.80423)
		(mid 373.208189 -221.975201)
		(end 373.093488 -222.108522)
		(width 0.1143)
		(layer "In11.Cu")
		(net "P5E_CPU0_G3_RX_DP<4>")
	)
	(arc
		(start 370.89969 -229.094284)
		(mid 370.858928 -229.264168)
		(end 370.745512 -229.397052)
		(width 0.1143)
		(layer "In11.Cu")
		(net "P5E_CPU0_G3_RX_DP<4>")
	)
	(arc
		(start 370.67363 -242.399058)
		(mid 370.673249 -242.399312)
		(end 370.672868 -242.399566)
		(width 0.1143)
		(layer "In11.Cu")
		(net "P5E_CPU0_G3_RX_DP<4>")
	)
	(arc
		(start 370.672868 -231.059482)
		(mid 370.429541 -231.524048)
		(end 370.672868 -231.988614)
		(width 0.1143)
		(layer "In11.Cu")
		(net "P5E_CPU0_G3_RX_DP<4>")
	)
	(segment
		(start 424.766994 -8.320024)
		(end 424.766994 -7.709154)
		(width 0.12954)
		(layer "F.Cu")
		(net "P5E_CPU0_G3_RX_DP<3>")
	)
	(segment
		(start 369.588034 -246.370094)
		(end 370.054886 -246.104156)
		(width 0.12954)
		(layer "F.Cu")
		(net "P5E_CPU0_G3_RX_DP<3>")
	)
	(segment
		(start 424.905678 -6.99516)
		(end 424.635676 -6.725158)
		(width 0.12954)
		(layer "F.Cu")
		(net "P5E_CPU0_G3_RX_DP<3>")
	)
	(segment
		(start 424.766994 -7.709154)
		(end 424.905678 -7.57047)
		(width 0.12954)
		(layer "F.Cu")
		(net "P5E_CPU0_G3_RX_DP<3>")
	)
	(segment
		(start 424.905678 -7.57047)
		(end 424.905678 -6.99516)
		(width 0.12954)
		(layer "F.Cu")
		(net "P5E_CPU0_G3_RX_DP<3>")
	)
	(segment
		(start 371.612922 -240.088674)
		(end 371.682518 -240.129314)
		(width 0.1143)
		(layer "In11.Cu")
		(net "P5E_CPU0_G3_RX_DP<3>")
	)
	(segment
		(start 374.033542 -222.108522)
		(end 374.001792 -222.12681)
		(width 0.1143)
		(layer "In11.Cu")
		(net "P5E_CPU0_G3_RX_DP<3>")
	)
	(segment
		(start 370.887244 -245.303548)
		(end 370.887244 -245.3132)
		(width 0.1143)
		(layer "In11.Cu")
		(net "P5E_CPU0_G3_RX_DP<3>")
	)
	(segment
		(start 423.131742 -19.612102)
		(end 422.75887 -20.512532)
		(width 0.14224)
		(layer "In11.Cu")
		(net "P5E_CPU0_G3_RX_DP<3>")
	)
	(segment
		(start 422.75887 -20.512532)
		(end 401.820888 -43.613324)
		(width 0.14224)
		(layer "In11.Cu")
		(net "P5E_CPU0_G3_RX_DP<3>")
	)
	(segment
		(start 371.68455 -229.397814)
		(end 371.652038 -229.41661)
		(width 0.1143)
		(layer "In11.Cu")
		(net "P5E_CPU0_G3_RX_DP<3>")
	)
	(segment
		(start 371.612922 -231.988614)
		(end 371.682518 -232.029254)
		(width 0.1143)
		(layer "In11.Cu")
		(net "P5E_CPU0_G3_RX_DP<3>")
	)
	(segment
		(start 371.682518 -226.15906)
		(end 371.612922 -226.1997)
		(width 0.1143)
		(layer "In11.Cu")
		(net "P5E_CPU0_G3_RX_DP<3>")
	)
	(segment
		(start 424.926506 -7.015988)
		(end 424.926506 -12.346178)
		(width 0.14224)
		(layer "In11.Cu")
		(net "P5E_CPU0_G3_RX_DP<3>")
	)
	(segment
		(start 422.472104 -17.935702)
		(end 422.707562 -18.375122)
		(width 0.14224)
		(layer "In11.Cu")
		(net "P5E_CPU0_G3_RX_DP<3>")
	)
	(segment
		(start 422.401492 -17.31772)
		(end 422.401492 -17.765014)
		(width 0.14224)
		(layer "In11.Cu")
		(net "P5E_CPU0_G3_RX_DP<3>")
	)
	(segment
		(start 317.185802 -160.49117)
		(end 317.34506 -161.941764)
		(width 0.14224)
		(layer "In11.Cu")
		(net "P5E_CPU0_G3_RX_DP<3>")
	)
	(segment
		(start 371.615462 -230.37038)
		(end 371.682518 -230.409496)
		(width 0.1143)
		(layer "In11.Cu")
		(net "P5E_CPU0_G3_RX_DP<3>")
	)
	(segment
		(start 423.131742 -19.071336)
		(end 423.131742 -19.612102)
		(width 0.14224)
		(layer "In11.Cu")
		(net "P5E_CPU0_G3_RX_DP<3>")
	)
	(segment
		(start 373.061738 -223.746822)
		(end 373.025416 -223.767904)
		(width 0.1143)
		(layer "In11.Cu")
		(net "P5E_CPU0_G3_RX_DP<3>")
	)
	(segment
		(start 327.052432 -130.362198)
		(end 324.598538 -134.631684)
		(width 0.14224)
		(layer "In11.Cu")
		(net "P5E_CPU0_G3_RX_DP<3>")
	)
	(segment
		(start 372.591838 -224.556828)
		(end 372.55704 -224.576894)
		(width 0.1143)
		(layer "In11.Cu")
		(net "P5E_CPU0_G3_RX_DP<3>")
	)
	(segment
		(start 317.34506 -161.941764)
		(end 318.081152 -163.718494)
		(width 0.14224)
		(layer "In11.Cu")
		(net "P5E_CPU0_G3_RX_DP<3>")
	)
	(segment
		(start 371.682518 -227.779072)
		(end 371.612922 -227.819712)
		(width 0.1143)
		(layer "In11.Cu")
		(net "P5E_CPU0_G3_RX_DP<3>")
	)
	(segment
		(start 371.213888 -244.788182)
		(end 371.170708 -244.813328)
		(width 0.1143)
		(layer "In11.Cu")
		(net "P5E_CPU0_G3_RX_DP<3>")
	)
	(segment
		(start 325.035164 -168.923716)
		(end 329.427332 -172.015404)
		(width 0.14224)
		(layer "In11.Cu")
		(net "P5E_CPU0_G3_RX_DP<3>")
	)
	(segment
		(start 332.825344 -175.091852)
		(end 365.996474 -202.25766)
		(width 0.14224)
		(layer "In11.Cu")
		(net "P5E_CPU0_G3_RX_DP<3>")
	)
	(segment
		(start 401.738592 -43.704256)
		(end 401.738846 -43.706796)
		(width 0.14224)
		(layer "In11.Cu")
		(net "P5E_CPU0_G3_RX_DP<3>")
	)
	(segment
		(start 373.093488 -223.728534)
		(end 373.061738 -223.746822)
		(width 0.1143)
		(layer "In11.Cu")
		(net "P5E_CPU0_G3_RX_DP<3>")
	)
	(segment
		(start 423.064432 -18.909284)
		(end 423.131742 -19.071336)
		(width 0.14224)
		(layer "In11.Cu")
		(net "P5E_CPU0_G3_RX_DP<3>")
	)
	(segment
		(start 422.401492 -17.765014)
		(end 422.472104 -17.935702)
		(width 0.14224)
		(layer "In11.Cu")
		(net "P5E_CPU0_G3_RX_DP<3>")
	)
	(segment
		(start 374.189498 -221.248478)
		(end 374.189498 -221.80423)
		(width 0.1143)
		(layer "In11.Cu")
		(net "P5E_CPU0_G3_RX_DP<3>")
	)
	(segment
		(start 371.61343 -228.749098)
		(end 371.652038 -228.771704)
		(width 0.1143)
		(layer "In11.Cu")
		(net "P5E_CPU0_G3_RX_DP<3>")
	)
	(segment
		(start 370.712492 -245.616476)
		(end 370.67363 -245.639082)
		(width 0.1143)
		(layer "In11.Cu")
		(net "P5E_CPU0_G3_RX_DP<3>")
	)
	(segment
		(start 422.707562 -18.375122)
		(end 423.064432 -18.909284)
		(width 0.14224)
		(layer "In11.Cu")
		(net "P5E_CPU0_G3_RX_DP<3>")
	)
	(segment
		(start 371.682518 -234.258866)
		(end 371.612922 -234.299506)
		(width 0.1143)
		(layer "In11.Cu")
		(net "P5E_CPU0_G3_RX_DP<3>")
	)
	(segment
		(start 374.001792 -222.12681)
		(end 373.962676 -222.14967)
		(width 0.1143)
		(layer "In11.Cu")
		(net "P5E_CPU0_G3_RX_DP<3>")
	)
	(segment
		(start 371.682518 -242.358926)
		(end 371.612922 -242.399566)
		(width 0.1143)
		(layer "In11.Cu")
		(net "P5E_CPU0_G3_RX_DP<3>")
	)
	(segment
		(start 422.996614 -16.426942)
		(end 422.401492 -17.31772)
		(width 0.14224)
		(layer "In11.Cu")
		(net "P5E_CPU0_G3_RX_DP<3>")
	)
	(segment
		(start 371.652038 -231.036622)
		(end 371.612922 -231.059482)
		(width 0.1143)
		(layer "In11.Cu")
		(net "P5E_CPU0_G3_RX_DP<3>")
	)
	(segment
		(start 424.926506 -12.346178)
		(end 422.996614 -16.426942)
		(width 0.14224)
		(layer "In11.Cu")
		(net "P5E_CPU0_G3_RX_DP<3>")
	)
	(segment
		(start 372.125494 -225.364802)
		(end 372.12397 -225.365564)
		(width 0.1143)
		(layer "In11.Cu")
		(net "P5E_CPU0_G3_RX_DP<3>")
	)
	(segment
		(start 372.12397 -225.365564)
		(end 372.1227 -225.366326)
		(width 0.1143)
		(layer "In11.Cu")
		(net "P5E_CPU0_G3_RX_DP<3>")
	)
	(segment
		(start 371.652038 -228.771704)
		(end 371.682518 -228.789484)
		(width 0.1143)
		(layer "In11.Cu")
		(net "P5E_CPU0_G3_RX_DP<3>")
	)
	(segment
		(start 329.427332 -172.015404)
		(end 332.825344 -175.091852)
		(width 0.14224)
		(layer "In11.Cu")
		(net "P5E_CPU0_G3_RX_DP<3>")
	)
	(segment
		(start 318.081152 -163.718494)
		(end 319.79108 -165.42893)
		(width 0.14224)
		(layer "In11.Cu")
		(net "P5E_CPU0_G3_RX_DP<3>")
	)
	(segment
		(start 372.127272 -225.363786)
		(end 372.126256 -225.364294)
		(width 0.1143)
		(layer "In11.Cu")
		(net "P5E_CPU0_G3_RX_DP<3>")
	)
	(segment
		(start 373.531638 -222.936816)
		(end 373.495316 -222.957898)
		(width 0.1143)
		(layer "In11.Cu")
		(net "P5E_CPU0_G3_RX_DP<3>")
	)
	(segment
		(start 371.612922 -227.128832)
		(end 371.682518 -227.169472)
		(width 0.1143)
		(layer "In11.Cu")
		(net "P5E_CPU0_G3_RX_DP<3>")
	)
	(segment
		(start 372.701566 -224.482406)
		(end 372.623588 -224.53854)
		(width 0.1143)
		(layer "In11.Cu")
		(net "P5E_CPU0_G3_RX_DP<3>")
	)
	(segment
		(start 424.635676 -6.725158)
		(end 424.926506 -7.015988)
		(width 0.14224)
		(layer "In11.Cu")
		(net "P5E_CPU0_G3_RX_DP<3>")
	)
	(segment
		(start 372.623588 -224.53854)
		(end 372.591838 -224.556828)
		(width 0.1143)
		(layer "In11.Cu")
		(net "P5E_CPU0_G3_RX_DP<3>")
	)
	(segment
		(start 371.682518 -240.738914)
		(end 371.612922 -240.779554)
		(width 0.1143)
		(layer "In11.Cu")
		(net "P5E_CPU0_G3_RX_DP<3>")
	)
	(segment
		(start 401.819364 -43.615102)
		(end 401.738592 -43.704256)
		(width 0.14224)
		(layer "In11.Cu")
		(net "P5E_CPU0_G3_RX_DP<3>")
	)
	(segment
		(start 372.12905 -225.36277)
		(end 372.128034 -225.363278)
		(width 0.1143)
		(layer "In11.Cu")
		(net "P5E_CPU0_G3_RX_DP<3>")
	)
	(segment
		(start 372.119398 -225.368358)
		(end 372.082822 -225.389694)
		(width 0.1143)
		(layer "In11.Cu")
		(net "P5E_CPU0_G3_RX_DP<3>")
	)
	(segment
		(start 371.612922 -233.608626)
		(end 371.682518 -233.649266)
		(width 0.1143)
		(layer "In11.Cu")
		(net "P5E_CPU0_G3_RX_DP<3>")
	)
	(segment
		(start 371.612922 -228.748844)
		(end 371.61343 -228.749098)
		(width 0.1143)
		(layer "In11.Cu")
		(net "P5E_CPU0_G3_RX_DP<3>")
	)
	(segment
		(start 371.612922 -236.84865)
		(end 371.682518 -236.88929)
		(width 0.1143)
		(layer "In11.Cu")
		(net "P5E_CPU0_G3_RX_DP<3>")
	)
	(segment
		(start 374.143778 -220.28658)
		(end 374.143778 -221.17431)
		(width 0.14224)
		(layer "In11.Cu")
		(net "P5E_CPU0_G3_RX_DP<3>")
	)
	(segment
		(start 371.612922 -241.708686)
		(end 371.682518 -241.749326)
		(width 0.1143)
		(layer "In11.Cu")
		(net "P5E_CPU0_G3_RX_DP<3>")
	)
	(segment
		(start 372.55704 -224.576894)
		(end 372.552976 -224.579688)
		(width 0.1143)
		(layer "In11.Cu")
		(net "P5E_CPU0_G3_RX_DP<3>")
	)
	(segment
		(start 371.682518 -243.978938)
		(end 371.612922 -244.019578)
		(width 0.1143)
		(layer "In11.Cu")
		(net "P5E_CPU0_G3_RX_DP<3>")
	)
	(segment
		(start 319.031366 -149.986238)
		(end 317.185802 -160.49117)
		(width 0.14224)
		(layer "In11.Cu")
		(net "P5E_CPU0_G3_RX_DP<3>")
	)
	(segment
		(start 401.820888 -43.613324)
		(end 401.819364 -43.615102)
		(width 0.14224)
		(layer "In11.Cu")
		(net "P5E_CPU0_G3_RX_DP<3>")
	)
	(segment
		(start 371.652038 -229.41661)
		(end 371.612922 -229.43947)
		(width 0.1143)
		(layer "In11.Cu")
		(net "P5E_CPU0_G3_RX_DP<3>")
	)
	(segment
		(start 365.996474 -202.25766)
		(end 372.781322 -213.746334)
		(width 0.14224)
		(layer "In11.Cu")
		(net "P5E_CPU0_G3_RX_DP<3>")
	)
	(segment
		(start 373.563388 -222.918528)
		(end 373.531638 -222.936816)
		(width 0.1143)
		(layer "In11.Cu")
		(net "P5E_CPU0_G3_RX_DP<3>")
	)
	(segment
		(start 374.143778 -221.202758)
		(end 374.189498 -221.248478)
		(width 0.1143)
		(layer "In11.Cu")
		(net "P5E_CPU0_G3_RX_DP<3>")
	)
	(segment
		(start 371.68455 -231.017826)
		(end 371.652038 -231.036622)
		(width 0.1143)
		(layer "In11.Cu")
		(net "P5E_CPU0_G3_RX_DP<3>")
	)
	(segment
		(start 319.79108 -165.42893)
		(end 325.035164 -168.923716)
		(width 0.14224)
		(layer "In11.Cu")
		(net "P5E_CPU0_G3_RX_DP<3>")
	)
	(segment
		(start 372.120922 -225.367342)
		(end 372.119398 -225.368358)
		(width 0.1143)
		(layer "In11.Cu")
		(net "P5E_CPU0_G3_RX_DP<3>")
	)
	(segment
		(start 372.1227 -225.366326)
		(end 372.121938 -225.366834)
		(width 0.1143)
		(layer "In11.Cu")
		(net "P5E_CPU0_G3_RX_DP<3>")
	)
	(segment
		(start 401.738846 -43.706796)
		(end 374.738646 -73.245472)
		(width 0.14224)
		(layer "In11.Cu")
		(net "P5E_CPU0_G3_RX_DP<3>")
	)
	(segment
		(start 374.143778 -221.17431)
		(end 374.143778 -221.202758)
		(width 0.1143)
		(layer "In11.Cu")
		(net "P5E_CPU0_G3_RX_DP<3>")
	)
	(segment
		(start 372.153688 -225.348546)
		(end 372.12905 -225.36277)
		(width 0.1143)
		(layer "In11.Cu")
		(net "P5E_CPU0_G3_RX_DP<3>")
	)
	(segment
		(start 371.682518 -235.878878)
		(end 371.612922 -235.919518)
		(width 0.1143)
		(layer "In11.Cu")
		(net "P5E_CPU0_G3_RX_DP<3>")
	)
	(segment
		(start 371.612922 -238.468662)
		(end 371.682518 -238.509302)
		(width 0.1143)
		(layer "In11.Cu")
		(net "P5E_CPU0_G3_RX_DP<3>")
	)
	(segment
		(start 371.682518 -239.118902)
		(end 371.612922 -239.159542)
		(width 0.1143)
		(layer "In11.Cu")
		(net "P5E_CPU0_G3_RX_DP<3>")
	)
	(segment
		(start 372.781322 -213.746334)
		(end 374.143778 -220.28658)
		(width 0.14224)
		(layer "In11.Cu")
		(net "P5E_CPU0_G3_RX_DP<3>")
	)
	(segment
		(start 372.128034 -225.363278)
		(end 372.127272 -225.363786)
		(width 0.1143)
		(layer "In11.Cu")
		(net "P5E_CPU0_G3_RX_DP<3>")
	)
	(segment
		(start 371.682518 -232.638854)
		(end 371.612922 -232.679494)
		(width 0.1143)
		(layer "In11.Cu")
		(net "P5E_CPU0_G3_RX_DP<3>")
	)
	(segment
		(start 372.779544 -224.234248)
		(end 372.779544 -224.33026)
		(width 0.1143)
		(layer "In11.Cu")
		(net "P5E_CPU0_G3_RX_DP<3>")
	)
	(segment
		(start 371.612922 -235.228638)
		(end 371.682518 -235.269278)
		(width 0.1143)
		(layer "In11.Cu")
		(net "P5E_CPU0_G3_RX_DP<3>")
	)
	(segment
		(start 370.435632 -246.021352)
		(end 370.352828 -246.104156)
		(width 0.1143)
		(layer "In11.Cu")
		(net "P5E_CPU0_G3_RX_DP<3>")
	)
	(segment
		(start 371.682518 -237.49889)
		(end 371.612922 -237.53953)
		(width 0.1143)
		(layer "In11.Cu")
		(net "P5E_CPU0_G3_RX_DP<3>")
	)
	(segment
		(start 374.738646 -73.245472)
		(end 327.052432 -130.362198)
		(width 0.14224)
		(layer "In11.Cu")
		(net "P5E_CPU0_G3_RX_DP<3>")
	)
	(segment
		(start 324.598538 -134.631684)
		(end 319.031366 -149.986238)
		(width 0.14224)
		(layer "In11.Cu")
		(net "P5E_CPU0_G3_RX_DP<3>")
	)
	(segment
		(start 370.352828 -246.104156)
		(end 370.054886 -246.104156)
		(width 0.1143)
		(layer "In11.Cu")
		(net "P5E_CPU0_G3_RX_DP<3>")
	)
	(segment
		(start 372.121938 -225.366834)
		(end 372.120922 -225.367342)
		(width 0.1143)
		(layer "In11.Cu")
		(net "P5E_CPU0_G3_RX_DP<3>")
	)
	(segment
		(start 371.612922 -243.328698)
		(end 371.682518 -243.369338)
		(width 0.1143)
		(layer "In11.Cu")
		(net "P5E_CPU0_G3_RX_DP<3>")
	)
	(segment
		(start 372.126256 -225.364294)
		(end 372.125494 -225.364802)
		(width 0.1143)
		(layer "In11.Cu")
		(net "P5E_CPU0_G3_RX_DP<3>")
	)
	(arc
		(start 371.36959 -244.484144)
		(mid 371.328397 -244.654933)
		(end 371.213888 -244.788182)
		(width 0.1143)
		(layer "In11.Cu")
		(net "P5E_CPU0_G3_RX_DP<3>")
	)
	(arc
		(start 373.249444 -223.417638)
		(mid 373.249434 -223.42094)
		(end 373.249444 -223.424242)
		(width 0.1143)
		(layer "In11.Cu")
		(net "P5E_CPU0_G3_RX_DP<3>")
	)
	(arc
		(start 372.309644 -225.044254)
		(mid 372.268389 -225.215225)
		(end 372.153688 -225.348546)
		(width 0.1143)
		(layer "In11.Cu")
		(net "P5E_CPU0_G3_RX_DP<3>")
	)
	(arc
		(start 371.83949 -230.714296)
		(mid 371.798524 -230.884702)
		(end 371.68455 -231.017826)
		(width 0.1143)
		(layer "In11.Cu")
		(net "P5E_CPU0_G3_RX_DP<3>")
	)
	(arc
		(start 371.612922 -232.679494)
		(mid 371.369595 -233.14406)
		(end 371.612922 -233.608626)
		(width 0.1143)
		(layer "In11.Cu")
		(net "P5E_CPU0_G3_RX_DP<3>")
	)
	(arc
		(start 372.779544 -224.227644)
		(mid 372.779534 -224.230946)
		(end 372.779544 -224.234248)
		(width 0.1143)
		(layer "In11.Cu")
		(net "P5E_CPU0_G3_RX_DP<3>")
	)
	(arc
		(start 371.612922 -227.819712)
		(mid 371.369595 -228.284278)
		(end 371.612922 -228.748844)
		(width 0.1143)
		(layer "In11.Cu")
		(net "P5E_CPU0_G3_RX_DP<3>")
	)
	(arc
		(start 374.189498 -221.80423)
		(mid 374.148243 -221.975201)
		(end 374.033542 -222.108522)
		(width 0.1143)
		(layer "In11.Cu")
		(net "P5E_CPU0_G3_RX_DP<3>")
	)
	(arc
		(start 371.170708 -244.813328)
		(mid 370.963224 -245.020415)
		(end 370.887244 -245.303548)
		(width 0.1143)
		(layer "In11.Cu")
		(net "P5E_CPU0_G3_RX_DP<3>")
	)
	(arc
		(start 372.779544 -224.33026)
		(mid 372.758917 -224.415746)
		(end 372.701566 -224.482406)
		(width 0.1143)
		(layer "In11.Cu")
		(net "P5E_CPU0_G3_RX_DP<3>")
	)
	(arc
		(start 371.682518 -228.789484)
		(mid 371.797945 -228.92286)
		(end 371.83949 -229.094284)
		(width 0.1143)
		(layer "In11.Cu")
		(net "P5E_CPU0_G3_RX_DP<3>")
	)
	(arc
		(start 371.682518 -227.169472)
		(mid 371.839495 -227.474272)
		(end 371.682518 -227.779072)
		(width 0.1143)
		(layer "In11.Cu")
		(net "P5E_CPU0_G3_RX_DP<3>")
	)
	(arc
		(start 371.612922 -229.43947)
		(mid 371.434109 -229.64182)
		(end 371.36959 -229.904036)
		(width 0.1143)
		(layer "In11.Cu")
		(net "P5E_CPU0_G3_RX_DP<3>")
	)
	(arc
		(start 371.612922 -234.299506)
		(mid 371.369595 -234.764072)
		(end 371.612922 -235.228638)
		(width 0.1143)
		(layer "In11.Cu")
		(net "P5E_CPU0_G3_RX_DP<3>")
	)
	(arc
		(start 371.612922 -235.919518)
		(mid 371.369595 -236.384084)
		(end 371.612922 -236.84865)
		(width 0.1143)
		(layer "In11.Cu")
		(net "P5E_CPU0_G3_RX_DP<3>")
	)
	(arc
		(start 371.682518 -240.129314)
		(mid 371.839495 -240.434114)
		(end 371.682518 -240.738914)
		(width 0.1143)
		(layer "In11.Cu")
		(net "P5E_CPU0_G3_RX_DP<3>")
	)
	(arc
		(start 370.67363 -245.639082)
		(mid 370.673249 -245.639336)
		(end 370.672868 -245.63959)
		(width 0.1143)
		(layer "In11.Cu")
		(net "P5E_CPU0_G3_RX_DP<3>")
	)
	(arc
		(start 371.612922 -242.399566)
		(mid 371.369595 -242.864132)
		(end 371.612922 -243.328698)
		(width 0.1143)
		(layer "In11.Cu")
		(net "P5E_CPU0_G3_RX_DP<3>")
	)
	(arc
		(start 373.47906 -222.969328)
		(mid 373.314393 -223.167935)
		(end 373.249444 -223.417638)
		(width 0.1143)
		(layer "In11.Cu")
		(net "P5E_CPU0_G3_RX_DP<3>")
	)
	(arc
		(start 371.612922 -239.159542)
		(mid 371.369595 -239.624108)
		(end 371.612922 -240.088674)
		(width 0.1143)
		(layer "In11.Cu")
		(net "P5E_CPU0_G3_RX_DP<3>")
	)
	(arc
		(start 371.682518 -232.029254)
		(mid 371.839495 -232.334054)
		(end 371.682518 -232.638854)
		(width 0.1143)
		(layer "In11.Cu")
		(net "P5E_CPU0_G3_RX_DP<3>")
	)
	(arc
		(start 371.36959 -229.904036)
		(mid 371.434826 -230.167627)
		(end 371.615462 -230.37038)
		(width 0.1143)
		(layer "In11.Cu")
		(net "P5E_CPU0_G3_RX_DP<3>")
	)
	(arc
		(start 371.682518 -230.409496)
		(mid 371.797945 -230.542872)
		(end 371.83949 -230.714296)
		(width 0.1143)
		(layer "In11.Cu")
		(net "P5E_CPU0_G3_RX_DP<3>")
	)
	(arc
		(start 371.612922 -231.059482)
		(mid 371.369595 -231.524048)
		(end 371.612922 -231.988614)
		(width 0.1143)
		(layer "In11.Cu")
		(net "P5E_CPU0_G3_RX_DP<3>")
	)
	(arc
		(start 373.962676 -222.14967)
		(mid 373.783863 -222.35202)
		(end 373.719344 -222.614236)
		(width 0.1143)
		(layer "In11.Cu")
		(net "P5E_CPU0_G3_RX_DP<3>")
	)
	(arc
		(start 371.682518 -238.509302)
		(mid 371.839495 -238.814102)
		(end 371.682518 -239.118902)
		(width 0.1143)
		(layer "In11.Cu")
		(net "P5E_CPU0_G3_RX_DP<3>")
	)
	(arc
		(start 371.83949 -229.094284)
		(mid 371.798524 -229.26469)
		(end 371.68455 -229.397814)
		(width 0.1143)
		(layer "In11.Cu")
		(net "P5E_CPU0_G3_RX_DP<3>")
	)
	(arc
		(start 371.612922 -226.1997)
		(mid 371.369595 -226.664266)
		(end 371.612922 -227.128832)
		(width 0.1143)
		(layer "In11.Cu")
		(net "P5E_CPU0_G3_RX_DP<3>")
	)
	(arc
		(start 370.439442 -245.998492)
		(mid 370.437419 -246.009902)
		(end 370.435632 -246.021352)
		(width 0.1143)
		(layer "In11.Cu")
		(net "P5E_CPU0_G3_RX_DP<3>")
	)
	(arc
		(start 372.082822 -225.389694)
		(mid 371.904009 -225.592044)
		(end 371.83949 -225.85426)
		(width 0.1143)
		(layer "In11.Cu")
		(net "P5E_CPU0_G3_RX_DP<3>")
	)
	(arc
		(start 371.682518 -235.269278)
		(mid 371.839495 -235.574078)
		(end 371.682518 -235.878878)
		(width 0.1143)
		(layer "In11.Cu")
		(net "P5E_CPU0_G3_RX_DP<3>")
	)
	(arc
		(start 371.83949 -225.85426)
		(mid 371.797941 -226.025682)
		(end 371.682518 -226.15906)
		(width 0.1143)
		(layer "In11.Cu")
		(net "P5E_CPU0_G3_RX_DP<3>")
	)
	(arc
		(start 371.682518 -243.369338)
		(mid 371.839495 -243.674138)
		(end 371.682518 -243.978938)
		(width 0.1143)
		(layer "In11.Cu")
		(net "P5E_CPU0_G3_RX_DP<3>")
	)
	(arc
		(start 371.612922 -240.779554)
		(mid 371.369595 -241.24412)
		(end 371.612922 -241.708686)
		(width 0.1143)
		(layer "In11.Cu")
		(net "P5E_CPU0_G3_RX_DP<3>")
	)
	(arc
		(start 370.887244 -245.3132)
		(mid 370.840354 -245.488151)
		(end 370.712492 -245.616476)
		(width 0.1143)
		(layer "In11.Cu")
		(net "P5E_CPU0_G3_RX_DP<3>")
	)
	(arc
		(start 371.682518 -241.749326)
		(mid 371.839495 -242.054126)
		(end 371.682518 -242.358926)
		(width 0.1143)
		(layer "In11.Cu")
		(net "P5E_CPU0_G3_RX_DP<3>")
	)
	(arc
		(start 373.00916 -223.779334)
		(mid 372.844493 -223.977941)
		(end 372.779544 -224.227644)
		(width 0.1143)
		(layer "In11.Cu")
		(net "P5E_CPU0_G3_RX_DP<3>")
	)
	(arc
		(start 372.552976 -224.579688)
		(mid 372.374163 -224.782038)
		(end 372.309644 -225.044254)
		(width 0.1143)
		(layer "In11.Cu")
		(net "P5E_CPU0_G3_RX_DP<3>")
	)
	(arc
		(start 373.249444 -223.424242)
		(mid 373.205373 -223.593778)
		(end 373.093488 -223.728534)
		(width 0.1143)
		(layer "In11.Cu")
		(net "P5E_CPU0_G3_RX_DP<3>")
	)
	(arc
		(start 373.025416 -223.767904)
		(mid 373.017238 -223.773547)
		(end 373.00916 -223.779334)
		(width 0.1143)
		(layer "In11.Cu")
		(net "P5E_CPU0_G3_RX_DP<3>")
	)
	(arc
		(start 371.682518 -233.649266)
		(mid 371.839495 -233.954066)
		(end 371.682518 -234.258866)
		(width 0.1143)
		(layer "In11.Cu")
		(net "P5E_CPU0_G3_RX_DP<3>")
	)
	(arc
		(start 370.672868 -245.63959)
		(mid 370.520881 -245.796098)
		(end 370.439442 -245.998492)
		(width 0.1143)
		(layer "In11.Cu")
		(net "P5E_CPU0_G3_RX_DP<3>")
	)
	(arc
		(start 371.682518 -236.88929)
		(mid 371.839495 -237.19409)
		(end 371.682518 -237.49889)
		(width 0.1143)
		(layer "In11.Cu")
		(net "P5E_CPU0_G3_RX_DP<3>")
	)
	(arc
		(start 373.719344 -222.614236)
		(mid 373.678089 -222.785207)
		(end 373.563388 -222.918528)
		(width 0.1143)
		(layer "In11.Cu")
		(net "P5E_CPU0_G3_RX_DP<3>")
	)
	(arc
		(start 371.612922 -237.53953)
		(mid 371.369595 -238.004096)
		(end 371.612922 -238.468662)
		(width 0.1143)
		(layer "In11.Cu")
		(net "P5E_CPU0_G3_RX_DP<3>")
	)
	(arc
		(start 373.495316 -222.957898)
		(mid 373.487138 -222.963541)
		(end 373.47906 -222.969328)
		(width 0.1143)
		(layer "In11.Cu")
		(net "P5E_CPU0_G3_RX_DP<3>")
	)
	(arc
		(start 371.612922 -244.019578)
		(mid 371.434109 -244.221928)
		(end 371.36959 -244.484144)
		(width 0.1143)
		(layer "In11.Cu")
		(net "P5E_CPU0_G3_RX_DP<3>")
	)
	(segment
		(start 372.407942 -247.990106)
		(end 372.874794 -247.724168)
		(width 0.12954)
		(layer "F.Cu")
		(net "P5E_CPU0_G3_RX_DP<2>")
	)
	(segment
		(start 426.440346 -4.963414)
		(end 426.705522 -5.22859)
		(width 0.12954)
		(layer "F.Cu")
		(net "P5E_CPU0_G3_RX_DP<2>")
	)
	(segment
		(start 426.705522 -7.57047)
		(end 426.566838 -7.709154)
		(width 0.12954)
		(layer "F.Cu")
		(net "P5E_CPU0_G3_RX_DP<2>")
	)
	(segment
		(start 426.566838 -7.709154)
		(end 426.566838 -8.320024)
		(width 0.12954)
		(layer "F.Cu")
		(net "P5E_CPU0_G3_RX_DP<2>")
	)
	(segment
		(start 426.705522 -5.22859)
		(end 426.705522 -7.57047)
		(width 0.12954)
		(layer "F.Cu")
		(net "P5E_CPU0_G3_RX_DP<2>")
	)
	(segment
		(start 372.589298 -236.869986)
		(end 372.590822 -236.871002)
		(width 0.1143)
		(layer "In11.Cu")
		(net "P5E_CPU0_G3_RX_DP<2>")
	)
	(segment
		(start 372.552722 -233.608626)
		(end 372.589298 -233.629962)
		(width 0.1143)
		(layer "In11.Cu")
		(net "P5E_CPU0_G3_RX_DP<2>")
	)
	(segment
		(start 425.323508 -18.769076)
		(end 424.363642 -20.648422)
		(width 0.14224)
		(layer "In11.Cu")
		(net "P5E_CPU0_G3_RX_DP<2>")
	)
	(segment
		(start 372.589552 -243.997988)
		(end 372.587266 -243.999512)
		(width 0.1143)
		(layer "In11.Cu")
		(net "P5E_CPU0_G3_RX_DP<2>")
	)
	(segment
		(start 372.552722 -231.988614)
		(end 372.589298 -232.00995)
		(width 0.1143)
		(layer "In11.Cu")
		(net "P5E_CPU0_G3_RX_DP<2>")
	)
	(segment
		(start 372.584218 -228.767132)
		(end 372.585742 -228.768148)
		(width 0.1143)
		(layer "In11.Cu")
		(net "P5E_CPU0_G3_RX_DP<2>")
	)
	(segment
		(start 372.55323 -229.439216)
		(end 372.552722 -229.43947)
		(width 0.1143)
		(layer "In11.Cu")
		(net "P5E_CPU0_G3_RX_DP<2>")
	)
	(segment
		(start 372.5926 -240.112042)
		(end 372.623588 -240.129822)
		(width 0.1143)
		(layer "In11.Cu")
		(net "P5E_CPU0_G3_RX_DP<2>")
	)
	(segment
		(start 372.589298 -232.00995)
		(end 372.590822 -232.010966)
		(width 0.1143)
		(layer "In11.Cu")
		(net "P5E_CPU0_G3_RX_DP<2>")
	)
	(segment
		(start 372.596156 -227.154232)
		(end 372.59768 -227.154994)
		(width 0.1143)
		(layer "In11.Cu")
		(net "P5E_CPU0_G3_RX_DP<2>")
	)
	(segment
		(start 372.590822 -240.111026)
		(end 372.591838 -240.111534)
		(width 0.1143)
		(layer "In11.Cu")
		(net "P5E_CPU0_G3_RX_DP<2>")
	)
	(segment
		(start 372.587266 -240.759488)
		(end 372.552722 -240.779554)
		(width 0.1143)
		(layer "In11.Cu")
		(net "P5E_CPU0_G3_RX_DP<2>")
	)
	(segment
		(start 372.590822 -246.591074)
		(end 372.591838 -246.591582)
		(width 0.1143)
		(layer "In11.Cu")
		(net "P5E_CPU0_G3_RX_DP<2>")
	)
	(segment
		(start 373.535194 -224.55505)
		(end 373.531892 -224.556828)
		(width 0.1143)
		(layer "In11.Cu")
		(net "P5E_CPU0_G3_RX_DP<2>")
	)
	(segment
		(start 372.55958 -226.195636)
		(end 372.552722 -226.1997)
		(width 0.1143)
		(layer "In11.Cu")
		(net "P5E_CPU0_G3_RX_DP<2>")
	)
	(segment
		(start 372.552722 -228.748844)
		(end 372.584218 -228.767132)
		(width 0.1143)
		(layer "In11.Cu")
		(net "P5E_CPU0_G3_RX_DP<2>")
	)
	(segment
		(start 373.092472 -225.349054)
		(end 373.022876 -225.389694)
		(width 0.1143)
		(layer "In11.Cu")
		(net "P5E_CPU0_G3_RX_DP<2>")
	)
	(segment
		(start 372.552722 -240.088674)
		(end 372.589298 -240.11001)
		(width 0.1143)
		(layer "In11.Cu")
		(net "P5E_CPU0_G3_RX_DP<2>")
	)
	(segment
		(start 426.440346 -4.963414)
		(end 426.731176 -5.254244)
		(width 0.14224)
		(layer "In11.Cu")
		(net "P5E_CPU0_G3_RX_DP<2>")
	)
	(segment
		(start 372.591838 -230.391716)
		(end 372.623588 -230.410004)
		(width 0.1143)
		(layer "In11.Cu")
		(net "P5E_CPU0_G3_RX_DP<2>")
	)
	(segment
		(start 426.731176 -5.254244)
		(end 426.731176 -13.624306)
		(width 0.14224)
		(layer "In11.Cu")
		(net "P5E_CPU0_G3_RX_DP<2>")
	)
	(segment
		(start 372.590822 -243.997226)
		(end 372.589552 -243.997988)
		(width 0.1143)
		(layer "In11.Cu")
		(net "P5E_CPU0_G3_RX_DP<2>")
	)
	(segment
		(start 336.0801 -175.11522)
		(end 338.262214 -178.337718)
		(width 0.14224)
		(layer "In11.Cu")
		(net "P5E_CPU0_G3_RX_DP<2>")
	)
	(segment
		(start 372.591838 -232.011474)
		(end 372.5926 -232.011982)
		(width 0.1143)
		(layer "In11.Cu")
		(net "P5E_CPU0_G3_RX_DP<2>")
	)
	(segment
		(start 372.5926 -239.136174)
		(end 372.591838 -239.136682)
		(width 0.1143)
		(layer "In11.Cu")
		(net "P5E_CPU0_G3_RX_DP<2>")
	)
	(segment
		(start 338.262214 -178.337718)
		(end 366.73155 -201.65441)
		(width 0.14224)
		(layer "In11.Cu")
		(net "P5E_CPU0_G3_RX_DP<2>")
	)
	(segment
		(start 372.552722 -238.468662)
		(end 372.589298 -238.489998)
		(width 0.1143)
		(layer "In11.Cu")
		(net "P5E_CPU0_G3_RX_DP<2>")
	)
	(segment
		(start 372.59768 -227.154994)
		(end 372.598442 -227.155502)
		(width 0.1143)
		(layer "In11.Cu")
		(net "P5E_CPU0_G3_RX_DP<2>")
	)
	(segment
		(start 372.590822 -242.377214)
		(end 372.552722 -242.399566)
		(width 0.1143)
		(layer "In11.Cu")
		(net "P5E_CPU0_G3_RX_DP<2>")
	)
	(segment
		(start 372.591838 -240.756694)
		(end 372.590822 -240.757202)
		(width 0.1143)
		(layer "In11.Cu")
		(net "P5E_CPU0_G3_RX_DP<2>")
	)
	(segment
		(start 373.022876 -247.378728)
		(end 373.092472 -247.419368)
		(width 0.1143)
		(layer "In11.Cu")
		(net "P5E_CPU0_G3_RX_DP<2>")
	)
	(segment
		(start 372.599966 -226.172268)
		(end 372.5926 -226.176332)
		(width 0.1143)
		(layer "In11.Cu")
		(net "P5E_CPU0_G3_RX_DP<2>")
	)
	(segment
		(start 372.5926 -244.972078)
		(end 372.623588 -244.989858)
		(width 0.1143)
		(layer "In11.Cu")
		(net "P5E_CPU0_G3_RX_DP<2>")
	)
	(segment
		(start 372.552722 -243.328698)
		(end 372.589298 -243.350034)
		(width 0.1143)
		(layer "In11.Cu")
		(net "P5E_CPU0_G3_RX_DP<2>")
	)
	(segment
		(start 373.531892 -224.556828)
		(end 373.493792 -224.578926)
		(width 0.1143)
		(layer "In11.Cu")
		(net "P5E_CPU0_G3_RX_DP<2>")
	)
	(segment
		(start 372.59387 -234.275376)
		(end 372.5926 -234.276138)
		(width 0.1143)
		(layer "In11.Cu")
		(net "P5E_CPU0_G3_RX_DP<2>")
	)
	(segment
		(start 372.589552 -227.798122)
		(end 372.587266 -227.799646)
		(width 0.1143)
		(layer "In11.Cu")
		(net "P5E_CPU0_G3_RX_DP<2>")
	)
	(segment
		(start 372.590822 -232.010966)
		(end 372.591838 -232.011474)
		(width 0.1143)
		(layer "In11.Cu")
		(net "P5E_CPU0_G3_RX_DP<2>")
	)
	(segment
		(start 372.590822 -227.79736)
		(end 372.589552 -227.798122)
		(width 0.1143)
		(layer "In11.Cu")
		(net "P5E_CPU0_G3_RX_DP<2>")
	)
	(segment
		(start 375.083832 -220.033596)
		(end 375.083832 -221.17431)
		(width 0.14224)
		(layer "In11.Cu")
		(net "P5E_CPU0_G3_RX_DP<2>")
	)
	(segment
		(start 372.5926 -227.1522)
		(end 372.595394 -227.153724)
		(width 0.1143)
		(layer "In11.Cu")
		(net "P5E_CPU0_G3_RX_DP<2>")
	)
	(segment
		(start 372.590822 -228.771196)
		(end 372.591838 -228.771704)
		(width 0.1143)
		(layer "In11.Cu")
		(net "P5E_CPU0_G3_RX_DP<2>")
	)
	(segment
		(start 372.589298 -233.629962)
		(end 372.590822 -233.630978)
		(width 0.1143)
		(layer "In11.Cu")
		(net "P5E_CPU0_G3_RX_DP<2>")
	)
	(segment
		(start 372.5926 -232.656126)
		(end 372.591838 -232.656634)
		(width 0.1143)
		(layer "In11.Cu")
		(net "P5E_CPU0_G3_RX_DP<2>")
	)
	(segment
		(start 372.5926 -235.89615)
		(end 372.591838 -235.896658)
		(width 0.1143)
		(layer "In11.Cu")
		(net "P5E_CPU0_G3_RX_DP<2>")
	)
	(segment
		(start 372.590822 -232.657142)
		(end 372.589552 -232.657904)
		(width 0.1143)
		(layer "In11.Cu")
		(net "P5E_CPU0_G3_RX_DP<2>")
	)
	(segment
		(start 372.590822 -235.25099)
		(end 372.591838 -235.251498)
		(width 0.1143)
		(layer "In11.Cu")
		(net "P5E_CPU0_G3_RX_DP<2>")
	)
	(segment
		(start 372.5926 -243.352066)
		(end 372.623588 -243.369846)
		(width 0.1143)
		(layer "In11.Cu")
		(net "P5E_CPU0_G3_RX_DP<2>")
	)
	(segment
		(start 375.083832 -221.202758)
		(end 375.129552 -221.248478)
		(width 0.1143)
		(layer "In11.Cu")
		(net "P5E_CPU0_G3_RX_DP<2>")
	)
	(segment
		(start 372.590822 -243.35105)
		(end 372.591838 -243.351558)
		(width 0.1143)
		(layer "In11.Cu")
		(net "P5E_CPU0_G3_RX_DP<2>")
	)
	(segment
		(start 372.595394 -227.153724)
		(end 372.596156 -227.154232)
		(width 0.1143)
		(layer "In11.Cu")
		(net "P5E_CPU0_G3_RX_DP<2>")
	)
	(segment
		(start 372.591838 -235.896658)
		(end 372.590822 -235.897166)
		(width 0.1143)
		(layer "In11.Cu")
		(net "P5E_CPU0_G3_RX_DP<2>")
	)
	(segment
		(start 372.590822 -244.971062)
		(end 372.591838 -244.97157)
		(width 0.1143)
		(layer "In11.Cu")
		(net "P5E_CPU0_G3_RX_DP<2>")
	)
	(segment
		(start 372.552722 -236.84865)
		(end 372.589298 -236.869986)
		(width 0.1143)
		(layer "In11.Cu")
		(net "P5E_CPU0_G3_RX_DP<2>")
	)
	(segment
		(start 372.587266 -227.799646)
		(end 372.552722 -227.819712)
		(width 0.1143)
		(layer "In11.Cu")
		(net "P5E_CPU0_G3_RX_DP<2>")
	)
	(segment
		(start 372.5926 -235.252006)
		(end 372.623588 -235.269786)
		(width 0.1143)
		(layer "In11.Cu")
		(net "P5E_CPU0_G3_RX_DP<2>")
	)
	(segment
		(start 372.591838 -236.87151)
		(end 372.5926 -236.872018)
		(width 0.1143)
		(layer "In11.Cu")
		(net "P5E_CPU0_G3_RX_DP<2>")
	)
	(segment
		(start 372.589552 -232.657904)
		(end 372.587266 -232.659428)
		(width 0.1143)
		(layer "In11.Cu")
		(net "P5E_CPU0_G3_RX_DP<2>")
	)
	(segment
		(start 372.623588 -239.118394)
		(end 372.59387 -239.135412)
		(width 0.1143)
		(layer "In11.Cu")
		(net "P5E_CPU0_G3_RX_DP<2>")
	)
	(segment
		(start 372.591838 -233.631486)
		(end 372.5926 -233.631994)
		(width 0.1143)
		(layer "In11.Cu")
		(net "P5E_CPU0_G3_RX_DP<2>")
	)
	(segment
		(start 372.59387 -243.995448)
		(end 372.5926 -243.99621)
		(width 0.1143)
		(layer "In11.Cu")
		(net "P5E_CPU0_G3_RX_DP<2>")
	)
	(segment
		(start 372.552722 -244.94871)
		(end 372.589298 -244.970046)
		(width 0.1143)
		(layer "In11.Cu")
		(net "P5E_CPU0_G3_RX_DP<2>")
	)
	(segment
		(start 373.493792 -224.578926)
		(end 373.492776 -224.579688)
		(width 0.1143)
		(layer "In11.Cu")
		(net "P5E_CPU0_G3_RX_DP<2>")
	)
	(segment
		(start 372.5926 -246.59209)
		(end 372.623588 -246.60987)
		(width 0.1143)
		(layer "In11.Cu")
		(net "P5E_CPU0_G3_RX_DP<2>")
	)
	(segment
		(start 374.973596 -222.108522)
		(end 374.941846 -222.12681)
		(width 0.1143)
		(layer "In11.Cu")
		(net "P5E_CPU0_G3_RX_DP<2>")
	)
	(segment
		(start 372.602252 -227.157534)
		(end 372.623588 -227.16998)
		(width 0.1143)
		(layer "In11.Cu")
		(net "P5E_CPU0_G3_RX_DP<2>")
	)
	(segment
		(start 372.5926 -236.872018)
		(end 372.623588 -236.889798)
		(width 0.1143)
		(layer "In11.Cu")
		(net "P5E_CPU0_G3_RX_DP<2>")
	)
	(segment
		(start 372.623588 -234.258358)
		(end 372.59387 -234.275376)
		(width 0.1143)
		(layer "In11.Cu")
		(net "P5E_CPU0_G3_RX_DP<2>")
	)
	(segment
		(start 372.5926 -245.616222)
		(end 372.591838 -245.61673)
		(width 0.1143)
		(layer "In11.Cu")
		(net "P5E_CPU0_G3_RX_DP<2>")
	)
	(segment
		(start 372.623588 -243.97843)
		(end 372.59387 -243.995448)
		(width 0.1143)
		(layer "In11.Cu")
		(net "P5E_CPU0_G3_RX_DP<2>")
	)
	(segment
		(start 372.59387 -232.655364)
		(end 372.5926 -232.656126)
		(width 0.1143)
		(layer "In11.Cu")
		(net "P5E_CPU0_G3_RX_DP<2>")
	)
	(segment
		(start 372.590822 -235.897166)
		(end 372.589552 -235.897928)
		(width 0.1143)
		(layer "In11.Cu")
		(net "P5E_CPU0_G3_RX_DP<2>")
	)
	(segment
		(start 373.860314 -213.72195)
		(end 375.083832 -220.033596)
		(width 0.14224)
		(layer "In11.Cu")
		(net "P5E_CPU0_G3_RX_DP<2>")
	)
	(segment
		(start 372.585742 -228.768148)
		(end 372.588282 -228.769672)
		(width 0.1143)
		(layer "In11.Cu")
		(net "P5E_CPU0_G3_RX_DP<2>")
	)
	(segment
		(start 372.587266 -239.139476)
		(end 372.552722 -239.159542)
		(width 0.1143)
		(layer "In11.Cu")
		(net "P5E_CPU0_G3_RX_DP<2>")
	)
	(segment
		(start 372.589552 -239.137952)
		(end 372.587266 -239.139476)
		(width 0.1143)
		(layer "In11.Cu")
		(net "P5E_CPU0_G3_RX_DP<2>")
	)
	(segment
		(start 372.587266 -234.27944)
		(end 372.552722 -234.299506)
		(width 0.1143)
		(layer "In11.Cu")
		(net "P5E_CPU0_G3_RX_DP<2>")
	)
	(segment
		(start 372.591838 -228.771704)
		(end 372.623588 -228.789992)
		(width 0.1143)
		(layer "In11.Cu")
		(net "P5E_CPU0_G3_RX_DP<2>")
	)
	(segment
		(start 372.590822 -241.731038)
		(end 372.591838 -241.731546)
		(width 0.1143)
		(layer "In11.Cu")
		(net "P5E_CPU0_G3_RX_DP<2>")
	)
	(segment
		(start 325.427848 -135.391144)
		(end 325.09587 -136.91489)
		(width 0.14224)
		(layer "In11.Cu")
		(net "P5E_CPU0_G3_RX_DP<2>")
	)
	(segment
		(start 425.869354 -17.815052)
		(end 425.64304 -18.237708)
		(width 0.14224)
		(layer "In11.Cu")
		(net "P5E_CPU0_G3_RX_DP<2>")
	)
	(segment
		(start 372.589298 -243.350034)
		(end 372.590822 -243.35105)
		(width 0.1143)
		(layer "In11.Cu")
		(net "P5E_CPU0_G3_RX_DP<2>")
	)
	(segment
		(start 372.588282 -228.769672)
		(end 372.589298 -228.77018)
		(width 0.1143)
		(layer "In11.Cu")
		(net "P5E_CPU0_G3_RX_DP<2>")
	)
	(segment
		(start 372.589552 -234.277916)
		(end 372.587266 -234.27944)
		(width 0.1143)
		(layer "In11.Cu")
		(net "P5E_CPU0_G3_RX_DP<2>")
	)
	(segment
		(start 372.587266 -243.999512)
		(end 372.552722 -244.019578)
		(width 0.1143)
		(layer "In11.Cu")
		(net "P5E_CPU0_G3_RX_DP<2>")
	)
	(segment
		(start 372.589298 -240.11001)
		(end 372.590822 -240.111026)
		(width 0.1143)
		(layer "In11.Cu")
		(net "P5E_CPU0_G3_RX_DP<2>")
	)
	(segment
		(start 425.92371 -17.682972)
		(end 425.869354 -17.815052)
		(width 0.14224)
		(layer "In11.Cu")
		(net "P5E_CPU0_G3_RX_DP<2>")
	)
	(segment
		(start 372.590822 -245.617238)
		(end 372.552722 -245.63959)
		(width 0.1143)
		(layer "In11.Cu")
		(net "P5E_CPU0_G3_RX_DP<2>")
	)
	(segment
		(start 372.5926 -243.99621)
		(end 372.591838 -243.996718)
		(width 0.1143)
		(layer "In11.Cu")
		(net "P5E_CPU0_G3_RX_DP<2>")
	)
	(segment
		(start 372.591838 -245.61673)
		(end 372.590822 -245.617238)
		(width 0.1143)
		(layer "In11.Cu")
		(net "P5E_CPU0_G3_RX_DP<2>")
	)
	(segment
		(start 372.591838 -232.656634)
		(end 372.590822 -232.657142)
		(width 0.1143)
		(layer "In11.Cu")
		(net "P5E_CPU0_G3_RX_DP<2>")
	)
	(segment
		(start 425.64304 -18.237708)
		(end 425.323508 -18.769076)
		(width 0.14224)
		(layer "In11.Cu")
		(net "P5E_CPU0_G3_RX_DP<2>")
	)
	(segment
		(start 372.589298 -244.970046)
		(end 372.590822 -244.971062)
		(width 0.1143)
		(layer "In11.Cu")
		(net "P5E_CPU0_G3_RX_DP<2>")
	)
	(segment
		(start 372.552722 -241.708686)
		(end 372.589298 -241.730022)
		(width 0.1143)
		(layer "In11.Cu")
		(net "P5E_CPU0_G3_RX_DP<2>")
	)
	(segment
		(start 372.591838 -226.17684)
		(end 372.560342 -226.195128)
		(width 0.1143)
		(layer "In11.Cu")
		(net "P5E_CPU0_G3_RX_DP<2>")
	)
	(segment
		(start 372.623588 -232.638346)
		(end 372.59387 -232.655364)
		(width 0.1143)
		(layer "In11.Cu")
		(net "P5E_CPU0_G3_RX_DP<2>")
	)
	(segment
		(start 372.591838 -242.376706)
		(end 372.590822 -242.377214)
		(width 0.1143)
		(layer "In11.Cu")
		(net "P5E_CPU0_G3_RX_DP<2>")
	)
	(segment
		(start 372.590822 -238.491014)
		(end 372.591838 -238.491522)
		(width 0.1143)
		(layer "In11.Cu")
		(net "P5E_CPU0_G3_RX_DP<2>")
	)
	(segment
		(start 372.5926 -226.176332)
		(end 372.591838 -226.17684)
		(width 0.1143)
		(layer "In11.Cu")
		(net "P5E_CPU0_G3_RX_DP<2>")
	)
	(segment
		(start 372.589298 -228.77018)
		(end 372.590822 -228.771196)
		(width 0.1143)
		(layer "In11.Cu")
		(net "P5E_CPU0_G3_RX_DP<2>")
	)
	(segment
		(start 372.625366 -229.397052)
		(end 372.591838 -229.41661)
		(width 0.1143)
		(layer "In11.Cu")
		(net "P5E_CPU0_G3_RX_DP<2>")
	)
	(segment
		(start 372.5926 -240.756186)
		(end 372.591838 -240.756694)
		(width 0.1143)
		(layer "In11.Cu")
		(net "P5E_CPU0_G3_RX_DP<2>")
	)
	(segment
		(start 372.590822 -233.630978)
		(end 372.591838 -233.631486)
		(width 0.1143)
		(layer "In11.Cu")
		(net "P5E_CPU0_G3_RX_DP<2>")
	)
	(segment
		(start 372.589552 -240.757964)
		(end 372.587266 -240.759488)
		(width 0.1143)
		(layer "In11.Cu")
		(net "P5E_CPU0_G3_RX_DP<2>")
	)
	(segment
		(start 374.502426 -222.919036)
		(end 374.471946 -222.936816)
		(width 0.1143)
		(layer "In11.Cu")
		(net "P5E_CPU0_G3_RX_DP<2>")
	)
	(segment
		(start 372.591838 -244.97157)
		(end 372.5926 -244.972078)
		(width 0.1143)
		(layer "In11.Cu")
		(net "P5E_CPU0_G3_RX_DP<2>")
	)
	(segment
		(start 372.552722 -227.128832)
		(end 372.555516 -227.130864)
		(width 0.1143)
		(layer "In11.Cu")
		(net "P5E_CPU0_G3_RX_DP<2>")
	)
	(segment
		(start 372.59387 -242.375436)
		(end 372.5926 -242.376198)
		(width 0.1143)
		(layer "In11.Cu")
		(net "P5E_CPU0_G3_RX_DP<2>")
	)
	(segment
		(start 373.172736 -247.724168)
		(end 372.874794 -247.724168)
		(width 0.1143)
		(layer "In11.Cu")
		(net "P5E_CPU0_G3_RX_DP<2>")
	)
	(segment
		(start 372.623588 -245.598442)
		(end 372.59387 -245.61546)
		(width 0.1143)
		(layer "In11.Cu")
		(net "P5E_CPU0_G3_RX_DP<2>")
	)
	(segment
		(start 372.552722 -235.228638)
		(end 372.589298 -235.249974)
		(width 0.1143)
		(layer "In11.Cu")
		(net "P5E_CPU0_G3_RX_DP<2>")
	)
	(segment
		(start 372.590822 -239.13719)
		(end 372.589552 -239.137952)
		(width 0.1143)
		(layer "In11.Cu")
		(net "P5E_CPU0_G3_RX_DP<2>")
	)
	(segment
		(start 372.589298 -238.489998)
		(end 372.590822 -238.491014)
		(width 0.1143)
		(layer "In11.Cu")
		(net "P5E_CPU0_G3_RX_DP<2>")
	)
	(segment
		(start 424.363642 -20.648422)
		(end 328.876152 -129.633218)
		(width 0.14224)
		(layer "In11.Cu")
		(net "P5E_CPU0_G3_RX_DP<2>")
	)
	(segment
		(start 372.591838 -238.491522)
		(end 372.623588 -238.50981)
		(width 0.1143)
		(layer "In11.Cu")
		(net "P5E_CPU0_G3_RX_DP<2>")
	)
	(segment
		(start 372.560342 -226.195128)
		(end 372.55958 -226.195636)
		(width 0.1143)
		(layer "In11.Cu")
		(net "P5E_CPU0_G3_RX_DP<2>")
	)
	(segment
		(start 372.5926 -237.516162)
		(end 372.591838 -237.51667)
		(width 0.1143)
		(layer "In11.Cu")
		(net "P5E_CPU0_G3_RX_DP<2>")
	)
	(segment
		(start 372.552722 -246.568722)
		(end 372.589298 -246.590058)
		(width 0.1143)
		(layer "In11.Cu")
		(net "P5E_CPU0_G3_RX_DP<2>")
	)
	(segment
		(start 372.587266 -232.659428)
		(end 372.552722 -232.679494)
		(width 0.1143)
		(layer "In11.Cu")
		(net "P5E_CPU0_G3_RX_DP<2>")
	)
	(segment
		(start 372.590822 -237.517178)
		(end 372.552722 -237.53953)
		(width 0.1143)
		(layer "In11.Cu")
		(net "P5E_CPU0_G3_RX_DP<2>")
	)
	(segment
		(start 372.555262 -230.37038)
		(end 372.591838 -230.391716)
		(width 0.1143)
		(layer "In11.Cu")
		(net "P5E_CPU0_G3_RX_DP<2>")
	)
	(segment
		(start 372.591838 -246.591582)
		(end 372.5926 -246.59209)
		(width 0.1143)
		(layer "In11.Cu")
		(net "P5E_CPU0_G3_RX_DP<2>")
	)
	(segment
		(start 372.587266 -235.899452)
		(end 372.552722 -235.919518)
		(width 0.1143)
		(layer "In11.Cu")
		(net "P5E_CPU0_G3_RX_DP<2>")
	)
	(segment
		(start 372.591838 -243.351558)
		(end 372.5926 -243.352066)
		(width 0.1143)
		(layer "In11.Cu")
		(net "P5E_CPU0_G3_RX_DP<2>")
	)
	(segment
		(start 372.59387 -239.135412)
		(end 372.5926 -239.136174)
		(width 0.1143)
		(layer "In11.Cu")
		(net "P5E_CPU0_G3_RX_DP<2>")
	)
	(segment
		(start 375.083832 -221.17431)
		(end 375.083832 -221.202758)
		(width 0.1143)
		(layer "In11.Cu")
		(net "P5E_CPU0_G3_RX_DP<2>")
	)
	(segment
		(start 372.589298 -235.249974)
		(end 372.590822 -235.25099)
		(width 0.1143)
		(layer "In11.Cu")
		(net "P5E_CPU0_G3_RX_DP<2>")
	)
	(segment
		(start 372.5926 -232.011982)
		(end 372.623588 -232.029762)
		(width 0.1143)
		(layer "In11.Cu")
		(net "P5E_CPU0_G3_RX_DP<2>")
	)
	(segment
		(start 372.59387 -237.5154)
		(end 372.5926 -237.516162)
		(width 0.1143)
		(layer "In11.Cu")
		(net "P5E_CPU0_G3_RX_DP<2>")
	)
	(segment
		(start 372.5926 -234.276138)
		(end 372.591838 -234.276646)
		(width 0.1143)
		(layer "In11.Cu")
		(net "P5E_CPU0_G3_RX_DP<2>")
	)
	(segment
		(start 375.129552 -221.248478)
		(end 375.129552 -221.80423)
		(width 0.1143)
		(layer "In11.Cu")
		(net "P5E_CPU0_G3_RX_DP<2>")
	)
	(segment
		(start 372.598442 -227.155502)
		(end 372.599712 -227.156264)
		(width 0.1143)
		(layer "In11.Cu")
		(net "P5E_CPU0_G3_RX_DP<2>")
	)
	(segment
		(start 372.590822 -234.277154)
		(end 372.589552 -234.277916)
		(width 0.1143)
		(layer "In11.Cu")
		(net "P5E_CPU0_G3_RX_DP<2>")
	)
	(segment
		(start 374.941846 -222.12681)
		(end 374.90273 -222.14967)
		(width 0.1143)
		(layer "In11.Cu")
		(net "P5E_CPU0_G3_RX_DP<2>")
	)
	(segment
		(start 372.591838 -243.996718)
		(end 372.590822 -243.997226)
		(width 0.1143)
		(layer "In11.Cu")
		(net "P5E_CPU0_G3_RX_DP<2>")
	)
	(segment
		(start 374.471946 -222.936816)
		(end 374.435624 -222.957898)
		(width 0.1143)
		(layer "In11.Cu")
		(net "P5E_CPU0_G3_RX_DP<2>")
	)
	(segment
		(start 372.623588 -235.87837)
		(end 372.59387 -235.895388)
		(width 0.1143)
		(layer "In11.Cu")
		(net "P5E_CPU0_G3_RX_DP<2>")
	)
	(segment
		(start 372.591838 -227.151692)
		(end 372.5926 -227.1522)
		(width 0.1143)
		(layer "In11.Cu")
		(net "P5E_CPU0_G3_RX_DP<2>")
	)
	(segment
		(start 372.59387 -240.755424)
		(end 372.5926 -240.756186)
		(width 0.1143)
		(layer "In11.Cu")
		(net "P5E_CPU0_G3_RX_DP<2>")
	)
	(segment
		(start 372.589298 -246.590058)
		(end 372.590822 -246.591074)
		(width 0.1143)
		(layer "In11.Cu")
		(net "P5E_CPU0_G3_RX_DP<2>")
	)
	(segment
		(start 372.590822 -240.757202)
		(end 372.589552 -240.757964)
		(width 0.1143)
		(layer "In11.Cu")
		(net "P5E_CPU0_G3_RX_DP<2>")
	)
	(segment
		(start 372.5926 -242.376198)
		(end 372.591838 -242.376706)
		(width 0.1143)
		(layer "In11.Cu")
		(net "P5E_CPU0_G3_RX_DP<2>")
	)
	(segment
		(start 372.555516 -227.130864)
		(end 372.591838 -227.151692)
		(width 0.1143)
		(layer "In11.Cu")
		(net "P5E_CPU0_G3_RX_DP<2>")
	)
	(segment
		(start 372.623588 -226.158552)
		(end 372.599966 -226.172268)
		(width 0.1143)
		(layer "In11.Cu")
		(net "P5E_CPU0_G3_RX_DP<2>")
	)
	(segment
		(start 372.591838 -239.136682)
		(end 372.590822 -239.13719)
		(width 0.1143)
		(layer "In11.Cu")
		(net "P5E_CPU0_G3_RX_DP<2>")
	)
	(segment
		(start 372.591838 -235.251498)
		(end 372.5926 -235.252006)
		(width 0.1143)
		(layer "In11.Cu")
		(net "P5E_CPU0_G3_RX_DP<2>")
	)
	(segment
		(start 373.242586 -247.654318)
		(end 373.172736 -247.724168)
		(width 0.1143)
		(layer "In11.Cu")
		(net "P5E_CPU0_G3_RX_DP<2>")
	)
	(segment
		(start 372.589298 -241.730022)
		(end 372.590822 -241.731038)
		(width 0.1143)
		(layer "In11.Cu")
		(net "P5E_CPU0_G3_RX_DP<2>")
	)
	(segment
		(start 426.731176 -13.624306)
		(end 425.92371 -17.682972)
		(width 0.14224)
		(layer "In11.Cu")
		(net "P5E_CPU0_G3_RX_DP<2>")
	)
	(segment
		(start 366.73155 -201.65441)
		(end 373.860314 -213.72195)
		(width 0.14224)
		(layer "In11.Cu")
		(net "P5E_CPU0_G3_RX_DP<2>")
	)
	(segment
		(start 372.589552 -235.897928)
		(end 372.587266 -235.899452)
		(width 0.1143)
		(layer "In11.Cu")
		(net "P5E_CPU0_G3_RX_DP<2>")
	)
	(segment
		(start 332.76286 -167.657272)
		(end 336.0801 -175.11522)
		(width 0.14224)
		(layer "In11.Cu")
		(net "P5E_CPU0_G3_RX_DP<2>")
	)
	(segment
		(start 372.59387 -245.61546)
		(end 372.5926 -245.616222)
		(width 0.1143)
		(layer "In11.Cu")
		(net "P5E_CPU0_G3_RX_DP<2>")
	)
	(segment
		(start 328.876152 -129.633218)
		(end 325.427848 -135.391144)
		(width 0.14224)
		(layer "In11.Cu")
		(net "P5E_CPU0_G3_RX_DP<2>")
	)
	(segment
		(start 372.591838 -240.111534)
		(end 372.5926 -240.112042)
		(width 0.1143)
		(layer "In11.Cu")
		(net "P5E_CPU0_G3_RX_DP<2>")
	)
	(segment
		(start 372.591838 -227.796852)
		(end 372.590822 -227.79736)
		(width 0.1143)
		(layer "In11.Cu")
		(net "P5E_CPU0_G3_RX_DP<2>")
	)
	(segment
		(start 372.590822 -236.871002)
		(end 372.591838 -236.87151)
		(width 0.1143)
		(layer "In11.Cu")
		(net "P5E_CPU0_G3_RX_DP<2>")
	)
	(segment
		(start 372.623588 -237.498382)
		(end 372.59387 -237.5154)
		(width 0.1143)
		(layer "In11.Cu")
		(net "P5E_CPU0_G3_RX_DP<2>")
	)
	(segment
		(start 325.930006 -154.65298)
		(end 332.76286 -167.657272)
		(width 0.14224)
		(layer "In11.Cu")
		(net "P5E_CPU0_G3_RX_DP<2>")
	)
	(segment
		(start 372.625366 -231.017064)
		(end 372.552722 -231.059482)
		(width 0.1143)
		(layer "In11.Cu")
		(net "P5E_CPU0_G3_RX_DP<2>")
	)
	(segment
		(start 372.591838 -229.41661)
		(end 372.55323 -229.439216)
		(width 0.1143)
		(layer "In11.Cu")
		(net "P5E_CPU0_G3_RX_DP<2>")
	)
	(segment
		(start 372.623588 -242.358418)
		(end 372.59387 -242.375436)
		(width 0.1143)
		(layer "In11.Cu")
		(net "P5E_CPU0_G3_RX_DP<2>")
	)
	(segment
		(start 372.623588 -240.738406)
		(end 372.59387 -240.755424)
		(width 0.1143)
		(layer "In11.Cu")
		(net "P5E_CPU0_G3_RX_DP<2>")
	)
	(segment
		(start 372.591838 -237.51667)
		(end 372.590822 -237.517178)
		(width 0.1143)
		(layer "In11.Cu")
		(net "P5E_CPU0_G3_RX_DP<2>")
	)
	(segment
		(start 372.5926 -233.631994)
		(end 372.623588 -233.649774)
		(width 0.1143)
		(layer "In11.Cu")
		(net "P5E_CPU0_G3_RX_DP<2>")
	)
	(segment
		(start 372.591838 -241.731546)
		(end 372.5926 -241.732054)
		(width 0.1143)
		(layer "In11.Cu")
		(net "P5E_CPU0_G3_RX_DP<2>")
	)
	(segment
		(start 372.599712 -227.156264)
		(end 372.602252 -227.157534)
		(width 0.1143)
		(layer "In11.Cu")
		(net "P5E_CPU0_G3_RX_DP<2>")
	)
	(segment
		(start 372.5926 -241.732054)
		(end 372.623588 -241.749834)
		(width 0.1143)
		(layer "In11.Cu")
		(net "P5E_CPU0_G3_RX_DP<2>")
	)
	(segment
		(start 325.09587 -136.91489)
		(end 325.930006 -154.65298)
		(width 0.14224)
		(layer "In11.Cu")
		(net "P5E_CPU0_G3_RX_DP<2>")
	)
	(segment
		(start 372.59387 -235.895388)
		(end 372.5926 -235.89615)
		(width 0.1143)
		(layer "In11.Cu")
		(net "P5E_CPU0_G3_RX_DP<2>")
	)
	(segment
		(start 372.591838 -234.276646)
		(end 372.590822 -234.277154)
		(width 0.1143)
		(layer "In11.Cu")
		(net "P5E_CPU0_G3_RX_DP<2>")
	)
	(segment
		(start 372.623588 -227.778564)
		(end 372.591838 -227.796852)
		(width 0.1143)
		(layer "In11.Cu")
		(net "P5E_CPU0_G3_RX_DP<2>")
	)
	(arc
		(start 372.552722 -234.299506)
		(mid 372.309395 -234.764072)
		(end 372.552722 -235.228638)
		(width 0.1143)
		(layer "In11.Cu")
		(net "P5E_CPU0_G3_RX_DP<2>")
	)
	(arc
		(start 372.623588 -243.369846)
		(mid 372.779516 -243.674138)
		(end 372.623588 -243.97843)
		(width 0.1143)
		(layer "In11.Cu")
		(net "P5E_CPU0_G3_RX_DP<2>")
	)
	(arc
		(start 373.965978 -223.769174)
		(mid 373.784923 -223.97106)
		(end 373.719598 -224.234248)
		(width 0.1143)
		(layer "In11.Cu")
		(net "P5E_CPU0_G3_RX_DP<2>")
	)
	(arc
		(start 372.623588 -228.789992)
		(mid 372.738264 -228.923326)
		(end 372.779544 -229.094284)
		(width 0.1143)
		(layer "In11.Cu")
		(net "P5E_CPU0_G3_RX_DP<2>")
	)
	(arc
		(start 372.623588 -238.50981)
		(mid 372.779516 -238.814102)
		(end 372.623588 -239.118394)
		(width 0.1143)
		(layer "In11.Cu")
		(net "P5E_CPU0_G3_RX_DP<2>")
	)
	(arc
		(start 374.426734 -222.964248)
		(mid 374.270031 -223.13353)
		(end 374.19407 -223.351344)
		(width 0.1143)
		(layer "In11.Cu")
		(net "P5E_CPU0_G3_RX_DP<2>")
	)
	(arc
		(start 372.779544 -229.094284)
		(mid 372.738782 -229.264168)
		(end 372.625366 -229.397052)
		(width 0.1143)
		(layer "In11.Cu")
		(net "P5E_CPU0_G3_RX_DP<2>")
	)
	(arc
		(start 372.552722 -244.019578)
		(mid 372.309395 -244.484144)
		(end 372.552722 -244.94871)
		(width 0.1143)
		(layer "In11.Cu")
		(net "P5E_CPU0_G3_RX_DP<2>")
	)
	(arc
		(start 373.719598 -224.234248)
		(mid 373.670221 -224.419273)
		(end 373.535194 -224.55505)
		(width 0.1143)
		(layer "In11.Cu")
		(net "P5E_CPU0_G3_RX_DP<2>")
	)
	(arc
		(start 375.129552 -221.80423)
		(mid 375.088297 -221.975201)
		(end 374.973596 -222.108522)
		(width 0.1143)
		(layer "In11.Cu")
		(net "P5E_CPU0_G3_RX_DP<2>")
	)
	(arc
		(start 372.623588 -227.16998)
		(mid 372.779516 -227.474272)
		(end 372.623588 -227.778564)
		(width 0.1143)
		(layer "In11.Cu")
		(net "P5E_CPU0_G3_RX_DP<2>")
	)
	(arc
		(start 372.623588 -235.269786)
		(mid 372.779516 -235.574078)
		(end 372.623588 -235.87837)
		(width 0.1143)
		(layer "In11.Cu")
		(net "P5E_CPU0_G3_RX_DP<2>")
	)
	(arc
		(start 374.047258 -223.688656)
		(mid 374.010462 -223.732797)
		(end 373.965978 -223.769174)
		(width 0.1143)
		(layer "In11.Cu")
		(net "P5E_CPU0_G3_RX_DP<2>")
	)
	(arc
		(start 372.623588 -241.749834)
		(mid 372.779516 -242.054126)
		(end 372.623588 -242.358418)
		(width 0.1143)
		(layer "In11.Cu")
		(net "P5E_CPU0_G3_RX_DP<2>")
	)
	(arc
		(start 374.19407 -223.351344)
		(mid 374.183471 -223.407691)
		(end 374.16613 -223.462342)
		(width 0.1143)
		(layer "In11.Cu")
		(net "P5E_CPU0_G3_RX_DP<2>")
	)
	(arc
		(start 372.30939 -229.904036)
		(mid 372.374626 -230.167627)
		(end 372.555262 -230.37038)
		(width 0.1143)
		(layer "In11.Cu")
		(net "P5E_CPU0_G3_RX_DP<2>")
	)
	(arc
		(start 374.16613 -223.462342)
		(mid 374.112997 -223.57881)
		(end 374.047258 -223.688656)
		(width 0.1143)
		(layer "In11.Cu")
		(net "P5E_CPU0_G3_RX_DP<2>")
	)
	(arc
		(start 374.659398 -222.614236)
		(mid 374.617849 -222.785658)
		(end 374.502426 -222.919036)
		(width 0.1143)
		(layer "In11.Cu")
		(net "P5E_CPU0_G3_RX_DP<2>")
	)
	(arc
		(start 372.623588 -230.410004)
		(mid 372.738264 -230.543338)
		(end 372.779544 -230.714296)
		(width 0.1143)
		(layer "In11.Cu")
		(net "P5E_CPU0_G3_RX_DP<2>")
	)
	(arc
		(start 373.492776 -224.579688)
		(mid 373.313963 -224.782038)
		(end 373.249444 -225.044254)
		(width 0.1143)
		(layer "In11.Cu")
		(net "P5E_CPU0_G3_RX_DP<2>")
	)
	(arc
		(start 372.552722 -240.779554)
		(mid 372.309395 -241.24412)
		(end 372.552722 -241.708686)
		(width 0.1143)
		(layer "In11.Cu")
		(net "P5E_CPU0_G3_RX_DP<2>")
	)
	(arc
		(start 373.249444 -225.044254)
		(mid 373.207895 -225.215676)
		(end 373.092472 -225.349054)
		(width 0.1143)
		(layer "In11.Cu")
		(net "P5E_CPU0_G3_RX_DP<2>")
	)
	(arc
		(start 373.022876 -225.389694)
		(mid 372.844063 -225.592044)
		(end 372.779544 -225.85426)
		(width 0.1143)
		(layer "In11.Cu")
		(net "P5E_CPU0_G3_RX_DP<2>")
	)
	(arc
		(start 373.092472 -247.419368)
		(mid 373.190237 -247.522344)
		(end 373.242586 -247.654318)
		(width 0.1143)
		(layer "In11.Cu")
		(net "P5E_CPU0_G3_RX_DP<2>")
	)
	(arc
		(start 372.623588 -240.129822)
		(mid 372.779516 -240.434114)
		(end 372.623588 -240.738406)
		(width 0.1143)
		(layer "In11.Cu")
		(net "P5E_CPU0_G3_RX_DP<2>")
	)
	(arc
		(start 372.779544 -246.914162)
		(mid 372.844059 -247.176381)
		(end 373.022876 -247.378728)
		(width 0.1143)
		(layer "In11.Cu")
		(net "P5E_CPU0_G3_RX_DP<2>")
	)
	(arc
		(start 372.623588 -236.889798)
		(mid 372.779516 -237.19409)
		(end 372.623588 -237.498382)
		(width 0.1143)
		(layer "In11.Cu")
		(net "P5E_CPU0_G3_RX_DP<2>")
	)
	(arc
		(start 372.552722 -232.679494)
		(mid 372.309395 -233.14406)
		(end 372.552722 -233.608626)
		(width 0.1143)
		(layer "In11.Cu")
		(net "P5E_CPU0_G3_RX_DP<2>")
	)
	(arc
		(start 372.779544 -225.85426)
		(mid 372.738289 -226.025231)
		(end 372.623588 -226.158552)
		(width 0.1143)
		(layer "In11.Cu")
		(net "P5E_CPU0_G3_RX_DP<2>")
	)
	(arc
		(start 372.552722 -226.1997)
		(mid 372.309395 -226.664266)
		(end 372.552722 -227.128832)
		(width 0.1143)
		(layer "In11.Cu")
		(net "P5E_CPU0_G3_RX_DP<2>")
	)
	(arc
		(start 372.623588 -244.989858)
		(mid 372.779516 -245.29415)
		(end 372.623588 -245.598442)
		(width 0.1143)
		(layer "In11.Cu")
		(net "P5E_CPU0_G3_RX_DP<2>")
	)
	(arc
		(start 372.552722 -235.919518)
		(mid 372.309395 -236.384084)
		(end 372.552722 -236.84865)
		(width 0.1143)
		(layer "In11.Cu")
		(net "P5E_CPU0_G3_RX_DP<2>")
	)
	(arc
		(start 372.552722 -237.53953)
		(mid 372.309395 -238.004096)
		(end 372.552722 -238.468662)
		(width 0.1143)
		(layer "In11.Cu")
		(net "P5E_CPU0_G3_RX_DP<2>")
	)
	(arc
		(start 374.435624 -222.957898)
		(mid 374.431164 -222.961052)
		(end 374.426734 -222.964248)
		(width 0.1143)
		(layer "In11.Cu")
		(net "P5E_CPU0_G3_RX_DP<2>")
	)
	(arc
		(start 374.90273 -222.14967)
		(mid 374.723917 -222.35202)
		(end 374.659398 -222.614236)
		(width 0.1143)
		(layer "In11.Cu")
		(net "P5E_CPU0_G3_RX_DP<2>")
	)
	(arc
		(start 372.552722 -239.159542)
		(mid 372.309395 -239.624108)
		(end 372.552722 -240.088674)
		(width 0.1143)
		(layer "In11.Cu")
		(net "P5E_CPU0_G3_RX_DP<2>")
	)
	(arc
		(start 372.552722 -229.43947)
		(mid 372.373909 -229.64182)
		(end 372.30939 -229.904036)
		(width 0.1143)
		(layer "In11.Cu")
		(net "P5E_CPU0_G3_RX_DP<2>")
	)
	(arc
		(start 372.623588 -246.60987)
		(mid 372.738264 -246.743204)
		(end 372.779544 -246.914162)
		(width 0.1143)
		(layer "In11.Cu")
		(net "P5E_CPU0_G3_RX_DP<2>")
	)
	(arc
		(start 372.623588 -232.029762)
		(mid 372.779516 -232.334054)
		(end 372.623588 -232.638346)
		(width 0.1143)
		(layer "In11.Cu")
		(net "P5E_CPU0_G3_RX_DP<2>")
	)
	(arc
		(start 372.552722 -245.63959)
		(mid 372.309395 -246.104156)
		(end 372.552722 -246.568722)
		(width 0.1143)
		(layer "In11.Cu")
		(net "P5E_CPU0_G3_RX_DP<2>")
	)
	(arc
		(start 372.552722 -242.399566)
		(mid 372.309395 -242.864132)
		(end 372.552722 -243.328698)
		(width 0.1143)
		(layer "In11.Cu")
		(net "P5E_CPU0_G3_RX_DP<2>")
	)
	(arc
		(start 372.552722 -227.819712)
		(mid 372.309395 -228.284278)
		(end 372.552722 -228.748844)
		(width 0.1143)
		(layer "In11.Cu")
		(net "P5E_CPU0_G3_RX_DP<2>")
	)
	(arc
		(start 372.779544 -230.714296)
		(mid 372.738782 -230.88418)
		(end 372.625366 -231.017064)
		(width 0.1143)
		(layer "In11.Cu")
		(net "P5E_CPU0_G3_RX_DP<2>")
	)
	(arc
		(start 372.623588 -233.649774)
		(mid 372.779516 -233.954066)
		(end 372.623588 -234.258358)
		(width 0.1143)
		(layer "In11.Cu")
		(net "P5E_CPU0_G3_RX_DP<2>")
	)
	(arc
		(start 372.552722 -231.059482)
		(mid 372.309395 -231.524048)
		(end 372.552722 -231.988614)
		(width 0.1143)
		(layer "In11.Cu")
		(net "P5E_CPU0_G3_RX_DP<2>")
	)
	(segment
		(start 428.50562 -6.99516)
		(end 428.235618 -6.725158)
		(width 0.12954)
		(layer "F.Cu")
		(net "P5E_CPU0_G3_RX_DP<1>")
	)
	(segment
		(start 428.366936 -7.709154)
		(end 428.50562 -7.57047)
		(width 0.12954)
		(layer "F.Cu")
		(net "P5E_CPU0_G3_RX_DP<1>")
	)
	(segment
		(start 428.366936 -8.320024)
		(end 428.366936 -7.709154)
		(width 0.12954)
		(layer "F.Cu")
		(net "P5E_CPU0_G3_RX_DP<1>")
	)
	(segment
		(start 428.50562 -7.57047)
		(end 428.50562 -6.99516)
		(width 0.12954)
		(layer "F.Cu")
		(net "P5E_CPU0_G3_RX_DP<1>")
	)
	(segment
		(start 372.407942 -244.750082)
		(end 372.874794 -244.484144)
		(width 0.12954)
		(layer "F.Cu")
		(net "P5E_CPU0_G3_RX_DP<1>")
	)
	(segment
		(start 373.563642 -234.258358)
		(end 373.531892 -234.276646)
		(width 0.1143)
		(layer "In11.Cu")
		(net "P5E_CPU0_G3_RX_DP<1>")
	)
	(segment
		(start 373.539766 -237.512098)
		(end 373.52732 -237.51921)
		(width 0.1143)
		(layer "In11.Cu")
		(net "P5E_CPU0_G3_RX_DP<1>")
	)
	(segment
		(start 373.51081 -240.099342)
		(end 373.511064 -240.099342)
		(width 0.1143)
		(layer "In11.Cu")
		(net "P5E_CPU0_G3_RX_DP<1>")
	)
	(segment
		(start 375.129552 -223.34601)
		(end 375.129552 -223.425258)
		(width 0.1143)
		(layer "In11.Cu")
		(net "P5E_CPU0_G3_RX_DP<1>")
	)
	(segment
		(start 428.520352 -12.52855)
		(end 428.023528 -17.57553)
		(width 0.14224)
		(layer "In11.Cu")
		(net "P5E_CPU0_G3_RX_DP<1>")
	)
	(segment
		(start 373.492776 -228.748844)
		(end 373.524272 -228.767132)
		(width 0.1143)
		(layer "In11.Cu")
		(net "P5E_CPU0_G3_RX_DP<1>")
	)
	(segment
		(start 373.511064 -241.719354)
		(end 373.5324 -241.7318)
		(width 0.1143)
		(layer "In11.Cu")
		(net "P5E_CPU0_G3_RX_DP<1>")
	)
	(segment
		(start 373.532654 -233.631994)
		(end 373.563642 -233.649774)
		(width 0.1143)
		(layer "In11.Cu")
		(net "P5E_CPU0_G3_RX_DP<1>")
	)
	(segment
		(start 374.973596 -223.728534)
		(end 374.941846 -223.746822)
		(width 0.1143)
		(layer "In11.Cu")
		(net "P5E_CPU0_G3_RX_DP<1>")
	)
	(segment
		(start 373.529606 -230.390446)
		(end 373.530876 -230.391208)
		(width 0.1143)
		(layer "In11.Cu")
		(net "P5E_CPU0_G3_RX_DP<1>")
	)
	(segment
		(start 428.023528 -17.57553)
		(end 428.023528 -17.765014)
		(width 0.14224)
		(layer "In11.Cu")
		(net "P5E_CPU0_G3_RX_DP<1>")
	)
	(segment
		(start 373.563642 -243.97843)
		(end 373.532654 -243.99621)
		(width 0.1143)
		(layer "In11.Cu")
		(net "P5E_CPU0_G3_RX_DP<1>")
	)
	(segment
		(start 373.530876 -243.35105)
		(end 373.531892 -243.351558)
		(width 0.1143)
		(layer "In11.Cu")
		(net "P5E_CPU0_G3_RX_DP<1>")
	)
	(segment
		(start 373.56542 -229.397052)
		(end 373.492776 -229.43947)
		(width 0.1143)
		(layer "In11.Cu")
		(net "P5E_CPU0_G3_RX_DP<1>")
	)
	(segment
		(start 374.659652 -224.221802)
		(end 374.659652 -224.234248)
		(width 0.1143)
		(layer "In11.Cu")
		(net "P5E_CPU0_G3_RX_DP<1>")
	)
	(segment
		(start 373.492776 -236.84865)
		(end 373.51081 -236.859318)
		(width 0.1143)
		(layer "In11.Cu")
		(net "P5E_CPU0_G3_RX_DP<1>")
	)
	(segment
		(start 376.023632 -221.17431)
		(end 376.023632 -221.202758)
		(width 0.1143)
		(layer "In11.Cu")
		(net "P5E_CPU0_G3_RX_DP<1>")
	)
	(segment
		(start 375.8819 -222.12681)
		(end 375.842784 -222.14967)
		(width 0.1143)
		(layer "In11.Cu")
		(net "P5E_CPU0_G3_RX_DP<1>")
	)
	(segment
		(start 373.563642 -227.778564)
		(end 373.532654 -227.796344)
		(width 0.1143)
		(layer "In11.Cu")
		(net "P5E_CPU0_G3_RX_DP<1>")
	)
	(segment
		(start 426.11675 -23.11019)
		(end 329.625452 -130.235452)
		(width 0.14224)
		(layer "In11.Cu")
		(net "P5E_CPU0_G3_RX_DP<1>")
	)
	(segment
		(start 373.563642 -232.638346)
		(end 373.532654 -232.656126)
		(width 0.1143)
		(layer "In11.Cu")
		(net "P5E_CPU0_G3_RX_DP<1>")
	)
	(segment
		(start 329.625452 -130.235452)
		(end 326.399144 -135.610854)
		(width 0.14224)
		(layer "In11.Cu")
		(net "P5E_CPU0_G3_RX_DP<1>")
	)
	(segment
		(start 373.25554 -244.40134)
		(end 373.172736 -244.484144)
		(width 0.1143)
		(layer "In11.Cu")
		(net "P5E_CPU0_G3_RX_DP<1>")
	)
	(segment
		(start 326.996806 -154.606752)
		(end 333.411322 -166.826438)
		(width 0.14224)
		(layer "In11.Cu")
		(net "P5E_CPU0_G3_RX_DP<1>")
	)
	(segment
		(start 373.530876 -228.771196)
		(end 373.531892 -228.771704)
		(width 0.1143)
		(layer "In11.Cu")
		(net "P5E_CPU0_G3_RX_DP<1>")
	)
	(segment
		(start 373.528844 -230.389938)
		(end 373.529606 -230.390446)
		(width 0.1143)
		(layer "In11.Cu")
		(net "P5E_CPU0_G3_RX_DP<1>")
	)
	(segment
		(start 373.529352 -233.629962)
		(end 373.530876 -233.630978)
		(width 0.1143)
		(layer "In11.Cu")
		(net "P5E_CPU0_G3_RX_DP<1>")
	)
	(segment
		(start 373.539766 -240.752122)
		(end 373.52732 -240.759234)
		(width 0.1143)
		(layer "In11.Cu")
		(net "P5E_CPU0_G3_RX_DP<1>")
	)
	(segment
		(start 373.531892 -233.631486)
		(end 373.532654 -233.631994)
		(width 0.1143)
		(layer "In11.Cu")
		(net "P5E_CPU0_G3_RX_DP<1>")
	)
	(segment
		(start 373.492776 -240.088674)
		(end 373.51081 -240.099342)
		(width 0.1143)
		(layer "In11.Cu")
		(net "P5E_CPU0_G3_RX_DP<1>")
	)
	(segment
		(start 373.524272 -228.767132)
		(end 373.525796 -228.768148)
		(width 0.1143)
		(layer "In11.Cu")
		(net "P5E_CPU0_G3_RX_DP<1>")
	)
	(segment
		(start 373.51081 -241.719354)
		(end 373.511064 -241.719354)
		(width 0.1143)
		(layer "In11.Cu")
		(net "P5E_CPU0_G3_RX_DP<1>")
	)
	(segment
		(start 373.532654 -232.656126)
		(end 373.531892 -232.656634)
		(width 0.1143)
		(layer "In11.Cu")
		(net "P5E_CPU0_G3_RX_DP<1>")
	)
	(segment
		(start 373.172736 -244.484144)
		(end 372.874794 -244.484144)
		(width 0.1143)
		(layer "In11.Cu")
		(net "P5E_CPU0_G3_RX_DP<1>")
	)
	(segment
		(start 373.531892 -230.391716)
		(end 373.532654 -230.392224)
		(width 0.1143)
		(layer "In11.Cu")
		(net "P5E_CPU0_G3_RX_DP<1>")
	)
	(segment
		(start 374.503696 -224.53854)
		(end 374.435624 -224.577656)
		(width 0.1143)
		(layer "In11.Cu")
		(net "P5E_CPU0_G3_RX_DP<1>")
	)
	(segment
		(start 428.023528 -17.765014)
		(end 428.09414 -17.935702)
		(width 0.14224)
		(layer "In11.Cu")
		(net "P5E_CPU0_G3_RX_DP<1>")
	)
	(segment
		(start 373.492776 -241.708686)
		(end 373.51081 -241.719354)
		(width 0.1143)
		(layer "In11.Cu")
		(net "P5E_CPU0_G3_RX_DP<1>")
	)
	(segment
		(start 428.39386 -20.23364)
		(end 426.11675 -23.11019)
		(width 0.14224)
		(layer "In11.Cu")
		(net "P5E_CPU0_G3_RX_DP<1>")
	)
	(segment
		(start 374.001792 -225.366834)
		(end 374.000014 -225.36785)
		(width 0.1143)
		(layer "In11.Cu")
		(net "P5E_CPU0_G3_RX_DP<1>")
	)
	(segment
		(start 373.492776 -243.328698)
		(end 373.529352 -243.350034)
		(width 0.1143)
		(layer "In11.Cu")
		(net "P5E_CPU0_G3_RX_DP<1>")
	)
	(segment
		(start 373.496332 -234.296966)
		(end 373.493538 -234.298998)
		(width 0.1143)
		(layer "In11.Cu")
		(net "P5E_CPU0_G3_RX_DP<1>")
	)
	(segment
		(start 375.37263 -222.959422)
		(end 375.300748 -223.011238)
		(width 0.1143)
		(layer "In11.Cu")
		(net "P5E_CPU0_G3_RX_DP<1>")
	)
	(segment
		(start 373.526558 -242.379754)
		(end 373.525542 -242.380262)
		(width 0.1143)
		(layer "In11.Cu")
		(net "P5E_CPU0_G3_RX_DP<1>")
	)
	(segment
		(start 326.399144 -135.610854)
		(end 326.036686 -137.073386)
		(width 0.14224)
		(layer "In11.Cu")
		(net "P5E_CPU0_G3_RX_DP<1>")
	)
	(segment
		(start 326.036686 -137.073386)
		(end 326.996806 -154.606752)
		(width 0.14224)
		(layer "In11.Cu")
		(net "P5E_CPU0_G3_RX_DP<1>")
	)
	(segment
		(start 373.529352 -243.998242)
		(end 373.492776 -244.019578)
		(width 0.1143)
		(layer "In11.Cu")
		(net "P5E_CPU0_G3_RX_DP<1>")
	)
	(segment
		(start 373.530876 -232.010966)
		(end 373.531892 -232.011474)
		(width 0.1143)
		(layer "In11.Cu")
		(net "P5E_CPU0_G3_RX_DP<1>")
	)
	(segment
		(start 367.459514 -201.019664)
		(end 374.957086 -213.674198)
		(width 0.14224)
		(layer "In11.Cu")
		(net "P5E_CPU0_G3_RX_DP<1>")
	)
	(segment
		(start 373.530876 -230.391208)
		(end 373.531892 -230.391716)
		(width 0.1143)
		(layer "In11.Cu")
		(net "P5E_CPU0_G3_RX_DP<1>")
	)
	(segment
		(start 373.531892 -243.351558)
		(end 373.532654 -243.352066)
		(width 0.1143)
		(layer "In11.Cu")
		(net "P5E_CPU0_G3_RX_DP<1>")
	)
	(segment
		(start 373.511064 -236.859318)
		(end 373.5324 -236.871764)
		(width 0.1143)
		(layer "In11.Cu")
		(net "P5E_CPU0_G3_RX_DP<1>")
	)
	(segment
		(start 373.492776 -227.128832)
		(end 373.49557 -227.130864)
		(width 0.1143)
		(layer "In11.Cu")
		(net "P5E_CPU0_G3_RX_DP<1>")
	)
	(segment
		(start 373.495316 -230.37038)
		(end 373.499888 -230.373174)
		(width 0.1143)
		(layer "In11.Cu")
		(net "P5E_CPU0_G3_RX_DP<1>")
	)
	(segment
		(start 374.957086 -213.674198)
		(end 376.023632 -219.72524)
		(width 0.14224)
		(layer "In11.Cu")
		(net "P5E_CPU0_G3_RX_DP<1>")
	)
	(segment
		(start 373.532654 -232.011982)
		(end 373.563642 -232.029762)
		(width 0.1143)
		(layer "In11.Cu")
		(net "P5E_CPU0_G3_RX_DP<1>")
	)
	(segment
		(start 373.492776 -235.228638)
		(end 373.51081 -235.239306)
		(width 0.1143)
		(layer "In11.Cu")
		(net "P5E_CPU0_G3_RX_DP<1>")
	)
	(segment
		(start 375.443496 -222.918528)
		(end 375.37263 -222.959422)
		(width 0.1143)
		(layer "In11.Cu")
		(net "P5E_CPU0_G3_RX_DP<1>")
	)
	(segment
		(start 373.530876 -233.630978)
		(end 373.531892 -233.631486)
		(width 0.1143)
		(layer "In11.Cu")
		(net "P5E_CPU0_G3_RX_DP<1>")
	)
	(segment
		(start 374.941846 -223.746822)
		(end 374.89511 -223.775016)
		(width 0.1143)
		(layer "In11.Cu")
		(net "P5E_CPU0_G3_RX_DP<1>")
	)
	(segment
		(start 428.526448 -7.015988)
		(end 428.526448 -12.498578)
		(width 0.14224)
		(layer "In11.Cu")
		(net "P5E_CPU0_G3_RX_DP<1>")
	)
	(segment
		(start 338.085176 -176.17694)
		(end 339.357716 -178.003962)
		(width 0.14224)
		(layer "In11.Cu")
		(net "P5E_CPU0_G3_RX_DP<1>")
	)
	(segment
		(start 373.529352 -243.350034)
		(end 373.530876 -243.35105)
		(width 0.1143)
		(layer "In11.Cu")
		(net "P5E_CPU0_G3_RX_DP<1>")
	)
	(segment
		(start 338.08543 -176.17694)
		(end 338.085176 -176.17694)
		(width 0.14224)
		(layer "In11.Cu")
		(net "P5E_CPU0_G3_RX_DP<1>")
	)
	(segment
		(start 373.526558 -235.899706)
		(end 373.50065 -235.914692)
		(width 0.1143)
		(layer "In11.Cu")
		(net "P5E_CPU0_G3_RX_DP<1>")
	)
	(segment
		(start 375.91238 -222.10903)
		(end 375.8819 -222.12681)
		(width 0.1143)
		(layer "In11.Cu")
		(net "P5E_CPU0_G3_RX_DP<1>")
	)
	(segment
		(start 373.525542 -239.140238)
		(end 373.493538 -239.159034)
		(width 0.1143)
		(layer "In11.Cu")
		(net "P5E_CPU0_G3_RX_DP<1>")
	)
	(segment
		(start 428.235618 -6.725158)
		(end 428.526448 -7.015988)
		(width 0.14224)
		(layer "In11.Cu")
		(net "P5E_CPU0_G3_RX_DP<1>")
	)
	(segment
		(start 373.52732 -240.759234)
		(end 373.526558 -240.759742)
		(width 0.1143)
		(layer "In11.Cu")
		(net "P5E_CPU0_G3_RX_DP<1>")
	)
	(segment
		(start 373.499888 -230.373174)
		(end 373.528844 -230.389938)
		(width 0.1143)
		(layer "In11.Cu")
		(net "P5E_CPU0_G3_RX_DP<1>")
	)
	(segment
		(start 373.532654 -230.392224)
		(end 373.533924 -230.392986)
		(width 0.1143)
		(layer "In11.Cu")
		(net "P5E_CPU0_G3_RX_DP<1>")
	)
	(segment
		(start 373.49557 -227.130864)
		(end 373.531892 -227.151692)
		(width 0.1143)
		(layer "In11.Cu")
		(net "P5E_CPU0_G3_RX_DP<1>")
	)
	(segment
		(start 373.535448 -230.393748)
		(end 373.563642 -230.410004)
		(width 0.1143)
		(layer "In11.Cu")
		(net "P5E_CPU0_G3_RX_DP<1>")
	)
	(segment
		(start 374.000014 -225.36785)
		(end 373.99849 -225.368866)
		(width 0.1143)
		(layer "In11.Cu")
		(net "P5E_CPU0_G3_RX_DP<1>")
	)
	(segment
		(start 373.542052 -231.03078)
		(end 373.492776 -231.059482)
		(width 0.1143)
		(layer "In11.Cu")
		(net "P5E_CPU0_G3_RX_DP<1>")
	)
	(segment
		(start 373.531892 -226.17684)
		(end 373.492776 -226.1997)
		(width 0.1143)
		(layer "In11.Cu")
		(net "P5E_CPU0_G3_RX_DP<1>")
	)
	(segment
		(start 428.526448 -12.498578)
		(end 428.520352 -12.52855)
		(width 0.14224)
		(layer "In11.Cu")
		(net "P5E_CPU0_G3_RX_DP<1>")
	)
	(segment
		(start 428.744634 -19.183096)
		(end 428.74438 -19.18335)
		(width 0.14224)
		(layer "In11.Cu")
		(net "P5E_CPU0_G3_RX_DP<1>")
	)
	(segment
		(start 373.532654 -243.99621)
		(end 373.531892 -243.996718)
		(width 0.1143)
		(layer "In11.Cu")
		(net "P5E_CPU0_G3_RX_DP<1>")
	)
	(segment
		(start 373.531892 -234.276646)
		(end 373.496332 -234.296966)
		(width 0.1143)
		(layer "In11.Cu")
		(net "P5E_CPU0_G3_RX_DP<1>")
	)
	(segment
		(start 373.51081 -235.239306)
		(end 373.511064 -235.239306)
		(width 0.1143)
		(layer "In11.Cu")
		(net "P5E_CPU0_G3_RX_DP<1>")
	)
	(segment
		(start 373.492776 -233.608626)
		(end 373.529352 -233.629962)
		(width 0.1143)
		(layer "In11.Cu")
		(net "P5E_CPU0_G3_RX_DP<1>")
	)
	(segment
		(start 374.033542 -225.348546)
		(end 374.001792 -225.366834)
		(width 0.1143)
		(layer "In11.Cu")
		(net "P5E_CPU0_G3_RX_DP<1>")
	)
	(segment
		(start 373.52732 -242.379246)
		(end 373.526558 -242.379754)
		(width 0.1143)
		(layer "In11.Cu")
		(net "P5E_CPU0_G3_RX_DP<1>")
	)
	(segment
		(start 373.52732 -237.51921)
		(end 373.526558 -237.519718)
		(width 0.1143)
		(layer "In11.Cu")
		(net "P5E_CPU0_G3_RX_DP<1>")
	)
	(segment
		(start 428.744634 -19.104864)
		(end 428.744634 -19.183096)
		(width 0.14224)
		(layer "In11.Cu")
		(net "P5E_CPU0_G3_RX_DP<1>")
	)
	(segment
		(start 373.539766 -239.13211)
		(end 373.52732 -239.139222)
		(width 0.1143)
		(layer "In11.Cu")
		(net "P5E_CPU0_G3_RX_DP<1>")
	)
	(segment
		(start 373.511064 -240.099342)
		(end 373.5324 -240.111788)
		(width 0.1143)
		(layer "In11.Cu")
		(net "P5E_CPU0_G3_RX_DP<1>")
	)
	(segment
		(start 373.532654 -243.352066)
		(end 373.563642 -243.369846)
		(width 0.1143)
		(layer "In11.Cu")
		(net "P5E_CPU0_G3_RX_DP<1>")
	)
	(segment
		(start 373.539766 -242.372134)
		(end 373.52732 -242.379246)
		(width 0.1143)
		(layer "In11.Cu")
		(net "P5E_CPU0_G3_RX_DP<1>")
	)
	(segment
		(start 373.51081 -238.47933)
		(end 373.511064 -238.47933)
		(width 0.1143)
		(layer "In11.Cu")
		(net "P5E_CPU0_G3_RX_DP<1>")
	)
	(segment
		(start 373.531892 -232.656634)
		(end 373.530876 -232.657142)
		(width 0.1143)
		(layer "In11.Cu")
		(net "P5E_CPU0_G3_RX_DP<1>")
	)
	(segment
		(start 376.023632 -221.202758)
		(end 376.069352 -221.248478)
		(width 0.1143)
		(layer "In11.Cu")
		(net "P5E_CPU0_G3_RX_DP<1>")
	)
	(segment
		(start 373.525542 -240.76025)
		(end 373.493538 -240.779046)
		(width 0.1143)
		(layer "In11.Cu")
		(net "P5E_CPU0_G3_RX_DP<1>")
	)
	(segment
		(start 373.52732 -235.899198)
		(end 373.526558 -235.899706)
		(width 0.1143)
		(layer "In11.Cu")
		(net "P5E_CPU0_G3_RX_DP<1>")
	)
	(segment
		(start 373.511064 -238.47933)
		(end 373.5324 -238.491776)
		(width 0.1143)
		(layer "In11.Cu")
		(net "P5E_CPU0_G3_RX_DP<1>")
	)
	(segment
		(start 373.530876 -232.657142)
		(end 373.492776 -232.679494)
		(width 0.1143)
		(layer "In11.Cu")
		(net "P5E_CPU0_G3_RX_DP<1>")
	)
	(segment
		(start 339.357716 -178.003962)
		(end 367.459514 -201.019664)
		(width 0.14224)
		(layer "In11.Cu")
		(net "P5E_CPU0_G3_RX_DP<1>")
	)
	(segment
		(start 373.492776 -238.468662)
		(end 373.51081 -238.47933)
		(width 0.1143)
		(layer "In11.Cu")
		(net "P5E_CPU0_G3_RX_DP<1>")
	)
	(segment
		(start 373.50065 -235.914692)
		(end 373.499888 -235.9152)
		(width 0.1143)
		(layer "In11.Cu")
		(net "P5E_CPU0_G3_RX_DP<1>")
	)
	(segment
		(start 373.525796 -228.768148)
		(end 373.528336 -228.769672)
		(width 0.1143)
		(layer "In11.Cu")
		(net "P5E_CPU0_G3_RX_DP<1>")
	)
	(segment
		(start 373.511064 -235.239306)
		(end 373.5324 -235.251752)
		(width 0.1143)
		(layer "In11.Cu")
		(net "P5E_CPU0_G3_RX_DP<1>")
	)
	(segment
		(start 373.533924 -230.392986)
		(end 373.535448 -230.393748)
		(width 0.1143)
		(layer "In11.Cu")
		(net "P5E_CPU0_G3_RX_DP<1>")
	)
	(segment
		(start 373.530876 -227.79736)
		(end 373.529352 -227.798376)
		(width 0.1143)
		(layer "In11.Cu")
		(net "P5E_CPU0_G3_RX_DP<1>")
	)
	(segment
		(start 373.529352 -228.77018)
		(end 373.530876 -228.771196)
		(width 0.1143)
		(layer "In11.Cu")
		(net "P5E_CPU0_G3_RX_DP<1>")
	)
	(segment
		(start 373.526558 -239.13973)
		(end 373.525542 -239.140238)
		(width 0.1143)
		(layer "In11.Cu")
		(net "P5E_CPU0_G3_RX_DP<1>")
	)
	(segment
		(start 428.723552 -18.9992)
		(end 428.744634 -19.104864)
		(width 0.14224)
		(layer "In11.Cu")
		(net "P5E_CPU0_G3_RX_DP<1>")
	)
	(segment
		(start 373.539766 -235.892086)
		(end 373.528844 -235.898436)
		(width 0.1143)
		(layer "In11.Cu")
		(net "P5E_CPU0_G3_RX_DP<1>")
	)
	(segment
		(start 373.531892 -243.996718)
		(end 373.530876 -243.997226)
		(width 0.1143)
		(layer "In11.Cu")
		(net "P5E_CPU0_G3_RX_DP<1>")
	)
	(segment
		(start 373.526558 -240.759742)
		(end 373.525542 -240.76025)
		(width 0.1143)
		(layer "In11.Cu")
		(net "P5E_CPU0_G3_RX_DP<1>")
	)
	(segment
		(start 373.532654 -227.796344)
		(end 373.531892 -227.796852)
		(width 0.1143)
		(layer "In11.Cu")
		(net "P5E_CPU0_G3_RX_DP<1>")
	)
	(segment
		(start 373.528844 -235.898436)
		(end 373.52732 -235.899198)
		(width 0.1143)
		(layer "In11.Cu")
		(net "P5E_CPU0_G3_RX_DP<1>")
	)
	(segment
		(start 373.531892 -232.011474)
		(end 373.532654 -232.011982)
		(width 0.1143)
		(layer "In11.Cu")
		(net "P5E_CPU0_G3_RX_DP<1>")
	)
	(segment
		(start 373.99849 -225.368866)
		(end 373.96547 -225.387916)
		(width 0.1143)
		(layer "In11.Cu")
		(net "P5E_CPU0_G3_RX_DP<1>")
	)
	(segment
		(start 428.723552 -18.998692)
		(end 428.723552 -18.9992)
		(width 0.14224)
		(layer "In11.Cu")
		(net "P5E_CPU0_G3_RX_DP<1>")
	)
	(segment
		(start 376.023632 -219.72524)
		(end 376.023632 -221.17431)
		(width 0.14224)
		(layer "In11.Cu")
		(net "P5E_CPU0_G3_RX_DP<1>")
	)
	(segment
		(start 373.525542 -242.380262)
		(end 373.493538 -242.399058)
		(width 0.1143)
		(layer "In11.Cu")
		(net "P5E_CPU0_G3_RX_DP<1>")
	)
	(segment
		(start 374.435624 -224.577656)
		(end 374.43283 -224.579688)
		(width 0.1143)
		(layer "In11.Cu")
		(net "P5E_CPU0_G3_RX_DP<1>")
	)
	(segment
		(start 376.069352 -221.248478)
		(end 376.069352 -221.80423)
		(width 0.1143)
		(layer "In11.Cu")
		(net "P5E_CPU0_G3_RX_DP<1>")
	)
	(segment
		(start 373.531892 -227.796852)
		(end 373.530876 -227.79736)
		(width 0.1143)
		(layer "In11.Cu")
		(net "P5E_CPU0_G3_RX_DP<1>")
	)
	(segment
		(start 373.531892 -227.151692)
		(end 373.563642 -227.16998)
		(width 0.1143)
		(layer "In11.Cu")
		(net "P5E_CPU0_G3_RX_DP<1>")
	)
	(segment
		(start 336.820764 -174.36084)
		(end 338.08543 -176.17694)
		(width 0.14224)
		(layer "In11.Cu")
		(net "P5E_CPU0_G3_RX_DP<1>")
	)
	(segment
		(start 428.329344 -18.375122)
		(end 428.686468 -18.909284)
		(width 0.14224)
		(layer "In11.Cu")
		(net "P5E_CPU0_G3_RX_DP<1>")
	)
	(segment
		(start 373.562626 -226.15906)
		(end 373.531892 -226.17684)
		(width 0.1143)
		(layer "In11.Cu")
		(net "P5E_CPU0_G3_RX_DP<1>")
	)
	(segment
		(start 373.525542 -237.520226)
		(end 373.493538 -237.539022)
		(width 0.1143)
		(layer "In11.Cu")
		(net "P5E_CPU0_G3_RX_DP<1>")
	)
	(segment
		(start 428.686468 -18.909284)
		(end 428.723552 -18.998692)
		(width 0.14224)
		(layer "In11.Cu")
		(net "P5E_CPU0_G3_RX_DP<1>")
	)
	(segment
		(start 428.09414 -17.935702)
		(end 428.329344 -18.375122)
		(width 0.14224)
		(layer "In11.Cu")
		(net "P5E_CPU0_G3_RX_DP<1>")
	)
	(segment
		(start 373.529352 -227.798376)
		(end 373.492776 -227.819712)
		(width 0.1143)
		(layer "In11.Cu")
		(net "P5E_CPU0_G3_RX_DP<1>")
	)
	(segment
		(start 373.530876 -243.997226)
		(end 373.529352 -243.998242)
		(width 0.1143)
		(layer "In11.Cu")
		(net "P5E_CPU0_G3_RX_DP<1>")
	)
	(segment
		(start 333.411322 -166.826438)
		(end 336.820764 -174.36084)
		(width 0.14224)
		(layer "In11.Cu")
		(net "P5E_CPU0_G3_RX_DP<1>")
	)
	(segment
		(start 373.51081 -236.859318)
		(end 373.511064 -236.859318)
		(width 0.1143)
		(layer "In11.Cu")
		(net "P5E_CPU0_G3_RX_DP<1>")
	)
	(segment
		(start 373.499888 -235.9152)
		(end 373.493538 -235.91901)
		(width 0.1143)
		(layer "In11.Cu")
		(net "P5E_CPU0_G3_RX_DP<1>")
	)
	(segment
		(start 375.129552 -223.425258)
		(end 375.129298 -223.426782)
		(width 0.1143)
		(layer "In11.Cu")
		(net "P5E_CPU0_G3_RX_DP<1>")
	)
	(segment
		(start 373.532654 -228.772212)
		(end 373.533162 -228.772466)
		(width 0.1143)
		(layer "In11.Cu")
		(net "P5E_CPU0_G3_RX_DP<1>")
	)
	(segment
		(start 373.528336 -228.769672)
		(end 373.529352 -228.77018)
		(width 0.1143)
		(layer "In11.Cu")
		(net "P5E_CPU0_G3_RX_DP<1>")
	)
	(segment
		(start 373.531892 -228.771704)
		(end 373.532654 -228.772212)
		(width 0.1143)
		(layer "In11.Cu")
		(net "P5E_CPU0_G3_RX_DP<1>")
	)
	(segment
		(start 373.492776 -231.988614)
		(end 373.529352 -232.00995)
		(width 0.1143)
		(layer "In11.Cu")
		(net "P5E_CPU0_G3_RX_DP<1>")
	)
	(segment
		(start 373.529352 -232.00995)
		(end 373.530876 -232.010966)
		(width 0.1143)
		(layer "In11.Cu")
		(net "P5E_CPU0_G3_RX_DP<1>")
	)
	(segment
		(start 428.74438 -19.18335)
		(end 428.39386 -20.23364)
		(width 0.14224)
		(layer "In11.Cu")
		(net "P5E_CPU0_G3_RX_DP<1>")
	)
	(segment
		(start 373.52732 -239.139222)
		(end 373.526558 -239.13973)
		(width 0.1143)
		(layer "In11.Cu")
		(net "P5E_CPU0_G3_RX_DP<1>")
	)
	(segment
		(start 373.526558 -237.519718)
		(end 373.525542 -237.520226)
		(width 0.1143)
		(layer "In11.Cu")
		(net "P5E_CPU0_G3_RX_DP<1>")
	)
	(arc
		(start 373.563642 -232.029762)
		(mid 373.712739 -232.334054)
		(end 373.563642 -232.638346)
		(width 0.1143)
		(layer "In11.Cu")
		(net "P5E_CPU0_G3_RX_DP<1>")
	)
	(arc
		(start 374.659652 -224.234248)
		(mid 374.618397 -224.405219)
		(end 374.503696 -224.53854)
		(width 0.1143)
		(layer "In11.Cu")
		(net "P5E_CPU0_G3_RX_DP<1>")
	)
	(arc
		(start 373.492776 -229.43947)
		(mid 373.313963 -229.64182)
		(end 373.249444 -229.904036)
		(width 0.1143)
		(layer "In11.Cu")
		(net "P5E_CPU0_G3_RX_DP<1>")
	)
	(arc
		(start 375.129298 -223.426782)
		(mid 375.084759 -223.59484)
		(end 374.973596 -223.728534)
		(width 0.1143)
		(layer "In11.Cu")
		(net "P5E_CPU0_G3_RX_DP<1>")
	)
	(arc
		(start 373.492776 -240.779554)
		(mid 373.249449 -241.24412)
		(end 373.492776 -241.708686)
		(width 0.1143)
		(layer "In11.Cu")
		(net "P5E_CPU0_G3_RX_DP<1>")
	)
	(arc
		(start 375.300748 -223.011238)
		(mid 375.174743 -223.157957)
		(end 375.129552 -223.34601)
		(width 0.1143)
		(layer "In11.Cu")
		(net "P5E_CPU0_G3_RX_DP<1>")
	)
	(arc
		(start 373.5324 -236.871764)
		(mid 373.71792 -237.189821)
		(end 373.539766 -237.512098)
		(width 0.1143)
		(layer "In11.Cu")
		(net "P5E_CPU0_G3_RX_DP<1>")
	)
	(arc
		(start 373.719598 -225.865436)
		(mid 373.675534 -226.030659)
		(end 373.562626 -226.15906)
		(width 0.1143)
		(layer "In11.Cu")
		(net "P5E_CPU0_G3_RX_DP<1>")
	)
	(arc
		(start 373.492776 -227.819712)
		(mid 373.249449 -228.284278)
		(end 373.492776 -228.748844)
		(width 0.1143)
		(layer "In11.Cu")
		(net "P5E_CPU0_G3_RX_DP<1>")
	)
	(arc
		(start 373.492776 -232.679494)
		(mid 373.249449 -233.14406)
		(end 373.492776 -233.608626)
		(width 0.1143)
		(layer "In11.Cu")
		(net "P5E_CPU0_G3_RX_DP<1>")
	)
	(arc
		(start 373.5324 -240.111788)
		(mid 373.71792 -240.429845)
		(end 373.539766 -240.752122)
		(width 0.1143)
		(layer "In11.Cu")
		(net "P5E_CPU0_G3_RX_DP<1>")
	)
	(arc
		(start 375.599452 -222.614236)
		(mid 375.558197 -222.785207)
		(end 375.443496 -222.918528)
		(width 0.1143)
		(layer "In11.Cu")
		(net "P5E_CPU0_G3_RX_DP<1>")
	)
	(arc
		(start 373.493538 -237.539022)
		(mid 373.493157 -237.539276)
		(end 373.492776 -237.53953)
		(width 0.1143)
		(layer "In11.Cu")
		(net "P5E_CPU0_G3_RX_DP<1>")
	)
	(arc
		(start 373.492776 -231.059482)
		(mid 373.249449 -231.524048)
		(end 373.492776 -231.988614)
		(width 0.1143)
		(layer "In11.Cu")
		(net "P5E_CPU0_G3_RX_DP<1>")
	)
	(arc
		(start 373.5324 -238.491776)
		(mid 373.71792 -238.809833)
		(end 373.539766 -239.13211)
		(width 0.1143)
		(layer "In11.Cu")
		(net "P5E_CPU0_G3_RX_DP<1>")
	)
	(arc
		(start 373.563642 -227.16998)
		(mid 373.712739 -227.474272)
		(end 373.563642 -227.778564)
		(width 0.1143)
		(layer "In11.Cu")
		(net "P5E_CPU0_G3_RX_DP<1>")
	)
	(arc
		(start 373.493538 -234.298998)
		(mid 373.493157 -234.299252)
		(end 373.492776 -234.299506)
		(width 0.1143)
		(layer "In11.Cu")
		(net "P5E_CPU0_G3_RX_DP<1>")
	)
	(arc
		(start 373.492776 -244.019578)
		(mid 373.340789 -244.176086)
		(end 373.25935 -244.37848)
		(width 0.1143)
		(layer "In11.Cu")
		(net "P5E_CPU0_G3_RX_DP<1>")
	)
	(arc
		(start 376.069352 -221.80423)
		(mid 376.027803 -221.975652)
		(end 375.91238 -222.10903)
		(width 0.1143)
		(layer "In11.Cu")
		(net "P5E_CPU0_G3_RX_DP<1>")
	)
	(arc
		(start 373.563642 -230.410004)
		(mid 373.676662 -230.54418)
		(end 373.719598 -230.714296)
		(width 0.1143)
		(layer "In11.Cu")
		(net "P5E_CPU0_G3_RX_DP<1>")
	)
	(arc
		(start 373.492776 -234.299506)
		(mid 373.249449 -234.764072)
		(end 373.492776 -235.228638)
		(width 0.1143)
		(layer "In11.Cu")
		(net "P5E_CPU0_G3_RX_DP<1>")
	)
	(arc
		(start 373.719598 -230.714296)
		(mid 373.673918 -230.896707)
		(end 373.542052 -231.03078)
		(width 0.1143)
		(layer "In11.Cu")
		(net "P5E_CPU0_G3_RX_DP<1>")
	)
	(arc
		(start 373.5324 -235.251752)
		(mid 373.71792 -235.569809)
		(end 373.539766 -235.892086)
		(width 0.1143)
		(layer "In11.Cu")
		(net "P5E_CPU0_G3_RX_DP<1>")
	)
	(arc
		(start 373.249444 -229.904036)
		(mid 373.31468 -230.167627)
		(end 373.495316 -230.37038)
		(width 0.1143)
		(layer "In11.Cu")
		(net "P5E_CPU0_G3_RX_DP<1>")
	)
	(arc
		(start 373.493538 -239.159034)
		(mid 373.493157 -239.159288)
		(end 373.492776 -239.159542)
		(width 0.1143)
		(layer "In11.Cu")
		(net "P5E_CPU0_G3_RX_DP<1>")
	)
	(arc
		(start 373.727472 -225.79076)
		(mid 373.721993 -225.827935)
		(end 373.719598 -225.865436)
		(width 0.1143)
		(layer "In11.Cu")
		(net "P5E_CPU0_G3_RX_DP<1>")
	)
	(arc
		(start 373.563642 -243.369846)
		(mid 373.712739 -243.674138)
		(end 373.563642 -243.97843)
		(width 0.1143)
		(layer "In11.Cu")
		(net "P5E_CPU0_G3_RX_DP<1>")
	)
	(arc
		(start 373.533162 -228.772466)
		(mid 373.66958 -228.908339)
		(end 373.719598 -229.094284)
		(width 0.1143)
		(layer "In11.Cu")
		(net "P5E_CPU0_G3_RX_DP<1>")
	)
	(arc
		(start 374.43283 -224.579688)
		(mid 374.254017 -224.782038)
		(end 374.189498 -225.044254)
		(width 0.1143)
		(layer "In11.Cu")
		(net "P5E_CPU0_G3_RX_DP<1>")
	)
	(arc
		(start 373.492776 -226.1997)
		(mid 373.249449 -226.664266)
		(end 373.492776 -227.128832)
		(width 0.1143)
		(layer "In11.Cu")
		(net "P5E_CPU0_G3_RX_DP<1>")
	)
	(arc
		(start 373.25935 -244.37848)
		(mid 373.257327 -244.38989)
		(end 373.25554 -244.40134)
		(width 0.1143)
		(layer "In11.Cu")
		(net "P5E_CPU0_G3_RX_DP<1>")
	)
	(arc
		(start 373.493538 -235.91901)
		(mid 373.493157 -235.919264)
		(end 373.492776 -235.919518)
		(width 0.1143)
		(layer "In11.Cu")
		(net "P5E_CPU0_G3_RX_DP<1>")
	)
	(arc
		(start 374.89511 -223.775016)
		(mid 374.72209 -223.969276)
		(end 374.659652 -224.221802)
		(width 0.1143)
		(layer "In11.Cu")
		(net "P5E_CPU0_G3_RX_DP<1>")
	)
	(arc
		(start 373.5324 -241.7318)
		(mid 373.71792 -242.049857)
		(end 373.539766 -242.372134)
		(width 0.1143)
		(layer "In11.Cu")
		(net "P5E_CPU0_G3_RX_DP<1>")
	)
	(arc
		(start 373.493538 -240.779046)
		(mid 373.493157 -240.7793)
		(end 373.492776 -240.779554)
		(width 0.1143)
		(layer "In11.Cu")
		(net "P5E_CPU0_G3_RX_DP<1>")
	)
	(arc
		(start 373.719598 -229.094284)
		(mid 373.678836 -229.264168)
		(end 373.56542 -229.397052)
		(width 0.1143)
		(layer "In11.Cu")
		(net "P5E_CPU0_G3_RX_DP<1>")
	)
	(arc
		(start 373.492776 -235.919518)
		(mid 373.249449 -236.384084)
		(end 373.492776 -236.84865)
		(width 0.1143)
		(layer "In11.Cu")
		(net "P5E_CPU0_G3_RX_DP<1>")
	)
	(arc
		(start 374.189498 -225.044254)
		(mid 374.148243 -225.215225)
		(end 374.033542 -225.348546)
		(width 0.1143)
		(layer "In11.Cu")
		(net "P5E_CPU0_G3_RX_DP<1>")
	)
	(arc
		(start 373.563642 -233.649774)
		(mid 373.715231 -233.954066)
		(end 373.563642 -234.258358)
		(width 0.1143)
		(layer "In11.Cu")
		(net "P5E_CPU0_G3_RX_DP<1>")
	)
	(arc
		(start 373.492776 -237.53953)
		(mid 373.249449 -238.004096)
		(end 373.492776 -238.468662)
		(width 0.1143)
		(layer "In11.Cu")
		(net "P5E_CPU0_G3_RX_DP<1>")
	)
	(arc
		(start 373.493538 -242.399058)
		(mid 373.493157 -242.399312)
		(end 373.492776 -242.399566)
		(width 0.1143)
		(layer "In11.Cu")
		(net "P5E_CPU0_G3_RX_DP<1>")
	)
	(arc
		(start 373.96547 -225.387916)
		(mid 373.949501 -225.399953)
		(end 373.933974 -225.412554)
		(width 0.1143)
		(layer "In11.Cu")
		(net "P5E_CPU0_G3_RX_DP<1>")
	)
	(arc
		(start 373.492776 -239.159542)
		(mid 373.249449 -239.624108)
		(end 373.492776 -240.088674)
		(width 0.1143)
		(layer "In11.Cu")
		(net "P5E_CPU0_G3_RX_DP<1>")
	)
	(arc
		(start 373.933974 -225.412554)
		(mid 373.801556 -225.585735)
		(end 373.727472 -225.79076)
		(width 0.1143)
		(layer "In11.Cu")
		(net "P5E_CPU0_G3_RX_DP<1>")
	)
	(arc
		(start 373.492776 -242.399566)
		(mid 373.249449 -242.864132)
		(end 373.492776 -243.328698)
		(width 0.1143)
		(layer "In11.Cu")
		(net "P5E_CPU0_G3_RX_DP<1>")
	)
	(arc
		(start 375.842784 -222.14967)
		(mid 375.663971 -222.35202)
		(end 375.599452 -222.614236)
		(width 0.1143)
		(layer "In11.Cu")
		(net "P5E_CPU0_G3_RX_DP<1>")
	)
	(segment
		(start 393.785598 -6.99516)
		(end 393.515596 -6.725158)
		(width 0.12954)
		(layer "F.Cu")
		(net "P5E_CPU0_G3_RX_DP<15>")
	)
	(segment
		(start 393.646914 -7.709154)
		(end 393.785598 -7.57047)
		(width 0.12954)
		(layer "F.Cu")
		(net "P5E_CPU0_G3_RX_DP<15>")
	)
	(segment
		(start 361.597956 -248.800112)
		(end 362.064808 -248.534174)
		(width 0.12954)
		(layer "F.Cu")
		(net "P5E_CPU0_G3_RX_DP<15>")
	)
	(segment
		(start 393.646914 -8.320024)
		(end 393.646914 -7.709154)
		(width 0.12954)
		(layer "F.Cu")
		(net "P5E_CPU0_G3_RX_DP<15>")
	)
	(segment
		(start 393.785598 -7.57047)
		(end 393.785598 -6.99516)
		(width 0.12954)
		(layer "F.Cu")
		(net "P5E_CPU0_G3_RX_DP<15>")
	)
	(segment
		(start 360.353356 -222.756984)
		(end 360.353356 -245.723664)
		(width 0.14224)
		(layer "In11.Cu")
		(net "P5E_CPU0_G3_RX_DP<15>")
	)
	(segment
		(start 362.36275 -248.534174)
		(end 362.064808 -248.534174)
		(width 0.1143)
		(layer "In11.Cu")
		(net "P5E_CPU0_G3_RX_DP<15>")
	)
	(segment
		(start 362.251752 -248.211594)
		(end 362.283502 -248.229882)
		(width 0.1143)
		(layer "In11.Cu")
		(net "P5E_CPU0_G3_RX_DP<15>")
	)
	(segment
		(start 360.907838 -216.11463)
		(end 360.907838 -221.41815)
		(width 0.14224)
		(layer "In11.Cu")
		(net "P5E_CPU0_G3_RX_DP<15>")
	)
	(segment
		(start 308.649878 -170.444414)
		(end 313.517534 -175.31334)
		(width 0.14224)
		(layer "In11.Cu")
		(net "P5E_CPU0_G3_RX_DP<15>")
	)
	(segment
		(start 317.932816 -122.411998)
		(end 314.796678 -128.350518)
		(width 0.14224)
		(layer "In11.Cu")
		(net "P5E_CPU0_G3_RX_DP<15>")
	)
	(segment
		(start 361.78236 -247.401588)
		(end 361.8103 -247.417844)
		(width 0.1143)
		(layer "In11.Cu")
		(net "P5E_CPU0_G3_RX_DP<15>")
	)
	(segment
		(start 393.806426 -11.85545)
		(end 393.431776 -12.759944)
		(width 0.14224)
		(layer "In11.Cu")
		(net "P5E_CPU0_G3_RX_DP<15>")
	)
	(segment
		(start 386.611368 -23.570946)
		(end 385.865878 -25.162002)
		(width 0.14224)
		(layer "In11.Cu")
		(net "P5E_CPU0_G3_RX_DP<15>")
	)
	(segment
		(start 361.775756 -247.398032)
		(end 361.778804 -247.39981)
		(width 0.1143)
		(layer "In11.Cu")
		(net "P5E_CPU0_G3_RX_DP<15>")
	)
	(segment
		(start 361.780836 -247.40108)
		(end 361.781852 -247.401588)
		(width 0.1143)
		(layer "In11.Cu")
		(net "P5E_CPU0_G3_RX_DP<15>")
	)
	(segment
		(start 361.311952 -246.591582)
		(end 361.342432 -246.609362)
		(width 0.1143)
		(layer "In11.Cu")
		(net "P5E_CPU0_G3_RX_DP<15>")
	)
	(segment
		(start 368.797586 -51.741578)
		(end 317.932816 -122.411998)
		(width 0.14224)
		(layer "In11.Cu")
		(net "P5E_CPU0_G3_RX_DP<15>")
	)
	(segment
		(start 393.431776 -12.759944)
		(end 389.29691 -16.15313)
		(width 0.14224)
		(layer "In11.Cu")
		(net "P5E_CPU0_G3_RX_DP<15>")
	)
	(segment
		(start 314.796678 -128.350518)
		(end 308.26456 -146.367754)
		(width 0.14224)
		(layer "In11.Cu")
		(net "P5E_CPU0_G3_RX_DP<15>")
	)
	(segment
		(start 361.311698 -246.591328)
		(end 361.311952 -246.591582)
		(width 0.1143)
		(layer "In11.Cu")
		(net "P5E_CPU0_G3_RX_DP<15>")
	)
	(segment
		(start 319.189862 -178.71313)
		(end 320.028824 -179.273708)
		(width 0.14224)
		(layer "In11.Cu")
		(net "P5E_CPU0_G3_RX_DP<15>")
	)
	(segment
		(start 361.779566 -247.400318)
		(end 361.780836 -247.40108)
		(width 0.1143)
		(layer "In11.Cu")
		(net "P5E_CPU0_G3_RX_DP<15>")
	)
	(segment
		(start 313.517534 -175.31334)
		(end 319.189862 -178.71313)
		(width 0.14224)
		(layer "In11.Cu")
		(net "P5E_CPU0_G3_RX_DP<15>")
	)
	(segment
		(start 320.028824 -179.273708)
		(end 357.064564 -209.641694)
		(width 0.14224)
		(layer "In11.Cu")
		(net "P5E_CPU0_G3_RX_DP<15>")
	)
	(segment
		(start 361.749594 -247.382792)
		(end 361.750356 -247.3833)
		(width 0.1143)
		(layer "In11.Cu")
		(net "P5E_CPU0_G3_RX_DP<15>")
	)
	(segment
		(start 388.78764 -16.839946)
		(end 388.567422 -17.371822)
		(width 0.14224)
		(layer "In11.Cu")
		(net "P5E_CPU0_G3_RX_DP<15>")
	)
	(segment
		(start 360.353356 -245.723664)
		(end 360.673142 -246.04345)
		(width 0.14224)
		(layer "In11.Cu")
		(net "P5E_CPU0_G3_RX_DP<15>")
	)
	(segment
		(start 361.778804 -247.39981)
		(end 361.779566 -247.400318)
		(width 0.1143)
		(layer "In11.Cu")
		(net "P5E_CPU0_G3_RX_DP<15>")
	)
	(segment
		(start 393.515596 -6.725158)
		(end 393.806426 -7.015988)
		(width 0.14224)
		(layer "In11.Cu")
		(net "P5E_CPU0_G3_RX_DP<15>")
	)
	(segment
		(start 389.29691 -16.15313)
		(end 388.78764 -16.839946)
		(width 0.14224)
		(layer "In11.Cu")
		(net "P5E_CPU0_G3_RX_DP<15>")
	)
	(segment
		(start 357.064564 -209.641694)
		(end 360.907838 -216.11463)
		(width 0.14224)
		(layer "In11.Cu")
		(net "P5E_CPU0_G3_RX_DP<15>")
	)
	(segment
		(start 360.75747 -246.063516)
		(end 361.196382 -246.502428)
		(width 0.1143)
		(layer "In11.Cu")
		(net "P5E_CPU0_G3_RX_DP<15>")
	)
	(segment
		(start 360.693208 -246.063516)
		(end 360.75747 -246.063516)
		(width 0.1143)
		(layer "In11.Cu")
		(net "P5E_CPU0_G3_RX_DP<15>")
	)
	(segment
		(start 361.774994 -247.397524)
		(end 361.775756 -247.398032)
		(width 0.1143)
		(layer "In11.Cu")
		(net "P5E_CPU0_G3_RX_DP<15>")
	)
	(segment
		(start 360.907838 -221.41815)
		(end 360.353356 -222.756984)
		(width 0.14224)
		(layer "In11.Cu")
		(net "P5E_CPU0_G3_RX_DP<15>")
	)
	(segment
		(start 361.750356 -247.3833)
		(end 361.774994 -247.397524)
		(width 0.1143)
		(layer "In11.Cu")
		(net "P5E_CPU0_G3_RX_DP<15>")
	)
	(segment
		(start 360.673142 -246.04345)
		(end 360.693208 -246.063516)
		(width 0.1143)
		(layer "In11.Cu")
		(net "P5E_CPU0_G3_RX_DP<15>")
	)
	(segment
		(start 385.865878 -25.162002)
		(end 368.797586 -51.741578)
		(width 0.14224)
		(layer "In11.Cu")
		(net "P5E_CPU0_G3_RX_DP<15>")
	)
	(segment
		(start 305.708812 -163.342828)
		(end 308.649878 -170.444414)
		(width 0.14224)
		(layer "In11.Cu")
		(net "P5E_CPU0_G3_RX_DP<15>")
	)
	(segment
		(start 361.742736 -247.378728)
		(end 361.749594 -247.382792)
		(width 0.1143)
		(layer "In11.Cu")
		(net "P5E_CPU0_G3_RX_DP<15>")
	)
	(segment
		(start 305.708812 -160.915096)
		(end 305.708812 -163.342828)
		(width 0.14224)
		(layer "In11.Cu")
		(net "P5E_CPU0_G3_RX_DP<15>")
	)
	(segment
		(start 308.26456 -146.367754)
		(end 305.708812 -160.915096)
		(width 0.14224)
		(layer "In11.Cu")
		(net "P5E_CPU0_G3_RX_DP<15>")
	)
	(segment
		(start 361.781852 -247.401588)
		(end 361.78236 -247.401588)
		(width 0.1143)
		(layer "In11.Cu")
		(net "P5E_CPU0_G3_RX_DP<15>")
	)
	(segment
		(start 393.806426 -7.015988)
		(end 393.806426 -11.85545)
		(width 0.14224)
		(layer "In11.Cu")
		(net "P5E_CPU0_G3_RX_DP<15>")
	)
	(segment
		(start 388.567422 -17.371822)
		(end 386.611368 -23.570946)
		(width 0.14224)
		(layer "In11.Cu")
		(net "P5E_CPU0_G3_RX_DP<15>")
	)
	(segment
		(start 362.21543 -248.190512)
		(end 362.251752 -248.211594)
		(width 0.1143)
		(layer "In11.Cu")
		(net "P5E_CPU0_G3_RX_DP<15>")
	)
	(segment
		(start 362.4326 -248.464324)
		(end 362.36275 -248.534174)
		(width 0.1143)
		(layer "In11.Cu")
		(net "P5E_CPU0_G3_RX_DP<15>")
	)
	(arc
		(start 361.196382 -246.502428)
		(mid 361.251155 -246.55062)
		(end 361.311698 -246.591328)
		(width 0.1143)
		(layer "In11.Cu")
		(net "P5E_CPU0_G3_RX_DP<15>")
	)
	(arc
		(start 361.8103 -247.417844)
		(mid 361.814 -247.420615)
		(end 361.817666 -247.423432)
		(width 0.1143)
		(layer "In11.Cu")
		(net "P5E_CPU0_G3_RX_DP<15>")
	)
	(arc
		(start 361.969812 -247.733566)
		(mid 362.035203 -247.981692)
		(end 362.199174 -248.179082)
		(width 0.1143)
		(layer "In11.Cu")
		(net "P5E_CPU0_G3_RX_DP<15>")
	)
	(arc
		(start 361.342432 -246.609362)
		(mid 361.457859 -246.742738)
		(end 361.499404 -246.914162)
		(width 0.1143)
		(layer "In11.Cu")
		(net "P5E_CPU0_G3_RX_DP<15>")
	)
	(arc
		(start 361.817666 -247.423432)
		(mid 361.917411 -247.5532)
		(end 361.96778 -247.708928)
		(width 0.1143)
		(layer "In11.Cu")
		(net "P5E_CPU0_G3_RX_DP<15>")
	)
	(arc
		(start 361.96778 -247.708928)
		(mid 361.969112 -247.721221)
		(end 361.969812 -247.733566)
		(width 0.1143)
		(layer "In11.Cu")
		(net "P5E_CPU0_G3_RX_DP<15>")
	)
	(arc
		(start 361.499404 -246.914162)
		(mid 361.563919 -247.176381)
		(end 361.742736 -247.378728)
		(width 0.1143)
		(layer "In11.Cu")
		(net "P5E_CPU0_G3_RX_DP<15>")
	)
	(arc
		(start 362.199174 -248.179082)
		(mid 362.207252 -248.184868)
		(end 362.21543 -248.190512)
		(width 0.1143)
		(layer "In11.Cu")
		(net "P5E_CPU0_G3_RX_DP<15>")
	)
	(arc
		(start 362.283502 -248.229882)
		(mid 362.380637 -248.332751)
		(end 362.4326 -248.464324)
		(width 0.1143)
		(layer "In11.Cu")
		(net "P5E_CPU0_G3_RX_DP<15>")
	)
	(segment
		(start 395.446758 -8.320024)
		(end 395.446758 -7.709154)
		(width 0.12954)
		(layer "F.Cu")
		(net "P5E_CPU0_G3_RX_DP<14>")
	)
	(segment
		(start 395.585442 -5.22859)
		(end 395.320266 -4.963414)
		(width 0.12954)
		(layer "F.Cu")
		(net "P5E_CPU0_G3_RX_DP<14>")
	)
	(segment
		(start 361.597956 -247.1801)
		(end 362.064808 -246.914162)
		(width 0.12954)
		(layer "F.Cu")
		(net "P5E_CPU0_G3_RX_DP<14>")
	)
	(segment
		(start 395.446758 -7.709154)
		(end 395.585442 -7.57047)
		(width 0.12954)
		(layer "F.Cu")
		(net "P5E_CPU0_G3_RX_DP<14>")
	)
	(segment
		(start 395.585442 -7.57047)
		(end 395.585442 -5.22859)
		(width 0.12954)
		(layer "F.Cu")
		(net "P5E_CPU0_G3_RX_DP<14>")
	)
	(segment
		(start 361.269534 -239.16132)
		(end 361.259628 -239.168686)
		(width 0.1143)
		(layer "In11.Cu")
		(net "P5E_CPU0_G3_RX_DP<14>")
	)
	(segment
		(start 361.923838 -221.083124)
		(end 361.969558 -221.128844)
		(width 0.1143)
		(layer "In11.Cu")
		(net "P5E_CPU0_G3_RX_DP<14>")
	)
	(segment
		(start 362.268516 -222.301308)
		(end 362.283502 -222.310198)
		(width 0.1143)
		(layer "In11.Cu")
		(net "P5E_CPU0_G3_RX_DP<14>")
	)
	(segment
		(start 361.269534 -238.466884)
		(end 361.342432 -238.509556)
		(width 0.1143)
		(layer "In11.Cu")
		(net "P5E_CPU0_G3_RX_DP<14>")
	)
	(segment
		(start 361.269534 -233.606848)
		(end 361.342432 -233.64952)
		(width 0.1143)
		(layer "In11.Cu")
		(net "P5E_CPU0_G3_RX_DP<14>")
	)
	(segment
		(start 361.272836 -243.328698)
		(end 361.342432 -243.369592)
		(width 0.1143)
		(layer "In11.Cu")
		(net "P5E_CPU0_G3_RX_DP<14>")
	)
	(segment
		(start 361.030266 -229.89667)
		(end 361.029758 -229.904036)
		(width 0.1143)
		(layer "In11.Cu")
		(net "P5E_CPU0_G3_RX_DP<14>")
	)
	(segment
		(start 361.342432 -226.15906)
		(end 361.311952 -226.17684)
		(width 0.1143)
		(layer "In11.Cu")
		(net "P5E_CPU0_G3_RX_DP<14>")
	)
	(segment
		(start 361.342432 -238.509556)
		(end 361.342432 -238.509302)
		(width 0.1143)
		(layer "In11.Cu")
		(net "P5E_CPU0_G3_RX_DP<14>")
	)
	(segment
		(start 361.030266 -229.888288)
		(end 361.030266 -229.89667)
		(width 0.1143)
		(layer "In11.Cu")
		(net "P5E_CPU0_G3_RX_DP<14>")
	)
	(segment
		(start 361.499404 -224.93859)
		(end 361.499404 -225.85426)
		(width 0.1143)
		(layer "In11.Cu")
		(net "P5E_CPU0_G3_RX_DP<14>")
	)
	(segment
		(start 314.28817 -174.687992)
		(end 319.697862 -177.930302)
		(width 0.14224)
		(layer "In11.Cu")
		(net "P5E_CPU0_G3_RX_DP<14>")
	)
	(segment
		(start 361.92841 -224.370646)
		(end 361.597702 -224.7011)
		(width 0.1143)
		(layer "In11.Cu")
		(net "P5E_CPU0_G3_RX_DP<14>")
	)
	(segment
		(start 361.311952 -231.036622)
		(end 361.272836 -231.059482)
		(width 0.1143)
		(layer "In11.Cu")
		(net "P5E_CPU0_G3_RX_DP<14>")
	)
	(segment
		(start 361.27563 -228.750622)
		(end 361.311952 -228.771704)
		(width 0.1143)
		(layer "In11.Cu")
		(net "P5E_CPU0_G3_RX_DP<14>")
	)
	(segment
		(start 361.344464 -231.017826)
		(end 361.311952 -231.036622)
		(width 0.1143)
		(layer "In11.Cu")
		(net "P5E_CPU0_G3_RX_DP<14>")
	)
	(segment
		(start 361.969558 -221.128844)
		(end 361.969558 -221.308676)
		(width 0.1143)
		(layer "In11.Cu")
		(net "P5E_CPU0_G3_RX_DP<14>")
	)
	(segment
		(start 361.269534 -240.086896)
		(end 361.342432 -240.129568)
		(width 0.1143)
		(layer "In11.Cu")
		(net "P5E_CPU0_G3_RX_DP<14>")
	)
	(segment
		(start 392.022076 -17.840198)
		(end 391.813542 -18.229834)
		(width 0.14224)
		(layer "In11.Cu")
		(net "P5E_CPU0_G3_RX_DP<14>")
	)
	(segment
		(start 361.781852 -244.161564)
		(end 361.813602 -244.179852)
		(width 0.1143)
		(layer "In11.Cu")
		(net "P5E_CPU0_G3_RX_DP<14>")
	)
	(segment
		(start 361.272836 -231.988614)
		(end 361.342432 -232.029254)
		(width 0.1143)
		(layer "In11.Cu")
		(net "P5E_CPU0_G3_RX_DP<14>")
	)
	(segment
		(start 361.923838 -221.054676)
		(end 361.923838 -221.083124)
		(width 0.1143)
		(layer "In11.Cu")
		(net "P5E_CPU0_G3_RX_DP<14>")
	)
	(segment
		(start 361.969304 -221.30893)
		(end 361.969304 -221.80423)
		(width 0.1143)
		(layer "In11.Cu")
		(net "P5E_CPU0_G3_RX_DP<14>")
	)
	(segment
		(start 361.310174 -229.417626)
		(end 361.276646 -229.437184)
		(width 0.1143)
		(layer "In11.Cu")
		(net "P5E_CPU0_G3_RX_DP<14>")
	)
	(segment
		(start 361.779058 -245.780052)
		(end 361.780074 -245.78056)
		(width 0.1143)
		(layer "In11.Cu")
		(net "P5E_CPU0_G3_RX_DP<14>")
	)
	(segment
		(start 361.342432 -235.269532)
		(end 361.342432 -235.269278)
		(width 0.1143)
		(layer "In11.Cu")
		(net "P5E_CPU0_G3_RX_DP<14>")
	)
	(segment
		(start 309.547768 -169.94632)
		(end 314.28817 -174.687992)
		(width 0.14224)
		(layer "In11.Cu")
		(net "P5E_CPU0_G3_RX_DP<14>")
	)
	(segment
		(start 362.249466 -246.590058)
		(end 362.25226 -246.591836)
		(width 0.1143)
		(layer "In11.Cu")
		(net "P5E_CPU0_G3_RX_DP<14>")
	)
	(segment
		(start 319.697862 -177.930302)
		(end 320.578988 -178.519074)
		(width 0.14224)
		(layer "In11.Cu")
		(net "P5E_CPU0_G3_RX_DP<14>")
	)
	(segment
		(start 361.26293 -243.321586)
		(end 361.272836 -243.328698)
		(width 0.1143)
		(layer "In11.Cu")
		(net "P5E_CPU0_G3_RX_DP<14>")
	)
	(segment
		(start 361.780074 -245.78056)
		(end 361.782106 -245.78183)
		(width 0.1143)
		(layer "In11.Cu")
		(net "P5E_CPU0_G3_RX_DP<14>")
	)
	(segment
		(start 362.25226 -246.591836)
		(end 362.283502 -246.610124)
		(width 0.1143)
		(layer "In11.Cu")
		(net "P5E_CPU0_G3_RX_DP<14>")
	)
	(segment
		(start 362.212636 -222.268796)
		(end 362.249212 -222.290132)
		(width 0.1143)
		(layer "In11.Cu")
		(net "P5E_CPU0_G3_RX_DP<14>")
	)
	(segment
		(start 361.342432 -240.738914)
		(end 361.27182 -240.780062)
		(width 0.1143)
		(layer "In11.Cu")
		(net "P5E_CPU0_G3_RX_DP<14>")
	)
	(segment
		(start 395.320266 -4.963414)
		(end 395.611096 -5.254244)
		(width 0.14224)
		(layer "In11.Cu")
		(net "P5E_CPU0_G3_RX_DP<14>")
	)
	(segment
		(start 361.311952 -227.151692)
		(end 361.342432 -227.169472)
		(width 0.1143)
		(layer "In11.Cu")
		(net "P5E_CPU0_G3_RX_DP<14>")
	)
	(segment
		(start 362.253022 -222.939102)
		(end 362.248704 -222.941642)
		(width 0.1143)
		(layer "In11.Cu")
		(net "P5E_CPU0_G3_RX_DP<14>")
	)
	(segment
		(start 361.342432 -232.638854)
		(end 361.269534 -232.681272)
		(width 0.1143)
		(layer "In11.Cu")
		(net "P5E_CPU0_G3_RX_DP<14>")
	)
	(segment
		(start 357.824278 -209.05851)
		(end 361.923838 -215.9635)
		(width 0.14224)
		(layer "In11.Cu")
		(net "P5E_CPU0_G3_RX_DP<14>")
	)
	(segment
		(start 361.259628 -235.219494)
		(end 361.269534 -235.22686)
		(width 0.1143)
		(layer "In11.Cu")
		(net "P5E_CPU0_G3_RX_DP<14>")
	)
	(segment
		(start 318.785494 -122.846846)
		(end 315.849 -128.376426)
		(width 0.14224)
		(layer "In11.Cu")
		(net "P5E_CPU0_G3_RX_DP<14>")
	)
	(segment
		(start 306.640992 -162.927792)
		(end 309.547768 -169.94632)
		(width 0.14224)
		(layer "In11.Cu")
		(net "P5E_CPU0_G3_RX_DP<14>")
	)
	(segment
		(start 361.269534 -232.681272)
		(end 361.259628 -232.688638)
		(width 0.1143)
		(layer "In11.Cu")
		(net "P5E_CPU0_G3_RX_DP<14>")
	)
	(segment
		(start 361.27182 -241.708178)
		(end 361.342432 -241.749326)
		(width 0.1143)
		(layer "In11.Cu")
		(net "P5E_CPU0_G3_RX_DP<14>")
	)
	(segment
		(start 361.269534 -234.301284)
		(end 361.259628 -234.30865)
		(width 0.1143)
		(layer "In11.Cu")
		(net "P5E_CPU0_G3_RX_DP<14>")
	)
	(segment
		(start 361.342432 -242.358926)
		(end 361.27182 -242.39982)
		(width 0.1143)
		(layer "In11.Cu")
		(net "P5E_CPU0_G3_RX_DP<14>")
	)
	(segment
		(start 361.342432 -237.49889)
		(end 361.269534 -237.541308)
		(width 0.1143)
		(layer "In11.Cu")
		(net "P5E_CPU0_G3_RX_DP<14>")
	)
	(segment
		(start 361.344464 -229.397814)
		(end 361.310174 -229.417626)
		(width 0.1143)
		(layer "In11.Cu")
		(net "P5E_CPU0_G3_RX_DP<14>")
	)
	(segment
		(start 361.311952 -226.17684)
		(end 361.27563 -226.197922)
		(width 0.1143)
		(layer "In11.Cu")
		(net "P5E_CPU0_G3_RX_DP<14>")
	)
	(segment
		(start 362.249212 -222.290132)
		(end 362.250736 -222.291148)
		(width 0.1143)
		(layer "In11.Cu")
		(net "P5E_CPU0_G3_RX_DP<14>")
	)
	(segment
		(start 361.823254 -244.781324)
		(end 361.813602 -244.788436)
		(width 0.1143)
		(layer "In11.Cu")
		(net "P5E_CPU0_G3_RX_DP<14>")
	)
	(segment
		(start 361.742736 -244.138704)
		(end 361.781852 -244.161564)
		(width 0.1143)
		(layer "In11.Cu")
		(net "P5E_CPU0_G3_RX_DP<14>")
	)
	(segment
		(start 306.640992 -161.002726)
		(end 306.640992 -162.927792)
		(width 0.14224)
		(layer "In11.Cu")
		(net "P5E_CPU0_G3_RX_DP<14>")
	)
	(segment
		(start 361.269534 -235.921296)
		(end 361.259628 -235.928662)
		(width 0.1143)
		(layer "In11.Cu")
		(net "P5E_CPU0_G3_RX_DP<14>")
	)
	(segment
		(start 361.259628 -236.839506)
		(end 361.269534 -236.846872)
		(width 0.1143)
		(layer "In11.Cu")
		(net "P5E_CPU0_G3_RX_DP<14>")
	)
	(segment
		(start 361.342432 -233.64952)
		(end 361.342432 -233.649266)
		(width 0.1143)
		(layer "In11.Cu")
		(net "P5E_CPU0_G3_RX_DP<14>")
	)
	(segment
		(start 361.813602 -244.788436)
		(end 361.742736 -244.829584)
		(width 0.1143)
		(layer "In11.Cu")
		(net "P5E_CPU0_G3_RX_DP<14>")
	)
	(segment
		(start 320.578988 -178.519074)
		(end 357.824278 -209.05851)
		(width 0.14224)
		(layer "In11.Cu")
		(net "P5E_CPU0_G3_RX_DP<14>")
	)
	(segment
		(start 361.259628 -233.599482)
		(end 361.269534 -233.606848)
		(width 0.1143)
		(layer "In11.Cu")
		(net "P5E_CPU0_G3_RX_DP<14>")
	)
	(segment
		(start 361.269534 -235.22686)
		(end 361.342432 -235.269532)
		(width 0.1143)
		(layer "In11.Cu")
		(net "P5E_CPU0_G3_RX_DP<14>")
	)
	(segment
		(start 361.259628 -238.459518)
		(end 361.269534 -238.466884)
		(width 0.1143)
		(layer "In11.Cu")
		(net "P5E_CPU0_G3_RX_DP<14>")
	)
	(segment
		(start 391.813542 -18.229834)
		(end 367.176812 -56.278526)
		(width 0.14224)
		(layer "In11.Cu")
		(net "P5E_CPU0_G3_RX_DP<14>")
	)
	(segment
		(start 361.342432 -234.258866)
		(end 361.269534 -234.301284)
		(width 0.1143)
		(layer "In11.Cu")
		(net "P5E_CPU0_G3_RX_DP<14>")
	)
	(segment
		(start 361.342432 -236.889544)
		(end 361.342432 -236.88929)
		(width 0.1143)
		(layer "In11.Cu")
		(net "P5E_CPU0_G3_RX_DP<14>")
	)
	(segment
		(start 361.342432 -227.779072)
		(end 361.311952 -227.796852)
		(width 0.1143)
		(layer "In11.Cu")
		(net "P5E_CPU0_G3_RX_DP<14>")
	)
	(segment
		(start 395.611096 -5.254244)
		(end 395.611096 -11.991848)
		(width 0.14224)
		(layer "In11.Cu")
		(net "P5E_CPU0_G3_RX_DP<14>")
	)
	(segment
		(start 361.269534 -236.846872)
		(end 361.342432 -236.889544)
		(width 0.1143)
		(layer "In11.Cu")
		(net "P5E_CPU0_G3_RX_DP<14>")
	)
	(segment
		(start 361.742736 -245.758716)
		(end 361.779058 -245.780052)
		(width 0.1143)
		(layer "In11.Cu")
		(net "P5E_CPU0_G3_RX_DP<14>")
	)
	(segment
		(start 361.342432 -235.878878)
		(end 361.269534 -235.921296)
		(width 0.1143)
		(layer "In11.Cu")
		(net "P5E_CPU0_G3_RX_DP<14>")
	)
	(segment
		(start 361.971082 -223.452944)
		(end 361.971082 -224.267776)
		(width 0.1143)
		(layer "In11.Cu")
		(net "P5E_CPU0_G3_RX_DP<14>")
	)
	(segment
		(start 361.342432 -243.369592)
		(end 361.342432 -243.369338)
		(width 0.1143)
		(layer "In11.Cu")
		(net "P5E_CPU0_G3_RX_DP<14>")
	)
	(segment
		(start 361.923838 -215.9635)
		(end 361.923838 -221.054676)
		(width 0.14224)
		(layer "In11.Cu")
		(net "P5E_CPU0_G3_RX_DP<14>")
	)
	(segment
		(start 367.176812 -56.278526)
		(end 318.785494 -122.846846)
		(width 0.14224)
		(layer "In11.Cu")
		(net "P5E_CPU0_G3_RX_DP<14>")
	)
	(segment
		(start 361.342432 -240.129568)
		(end 361.342432 -240.129314)
		(width 0.1143)
		(layer "In11.Cu")
		(net "P5E_CPU0_G3_RX_DP<14>")
	)
	(segment
		(start 362.250736 -222.291148)
		(end 362.251752 -222.291656)
		(width 0.1143)
		(layer "In11.Cu")
		(net "P5E_CPU0_G3_RX_DP<14>")
	)
	(segment
		(start 361.259628 -240.07953)
		(end 361.269534 -240.086896)
		(width 0.1143)
		(layer "In11.Cu")
		(net "P5E_CPU0_G3_RX_DP<14>")
	)
	(segment
		(start 395.611096 -11.991848)
		(end 395.345666 -12.865862)
		(width 0.14224)
		(layer "In11.Cu")
		(net "P5E_CPU0_G3_RX_DP<14>")
	)
	(segment
		(start 395.345666 -12.865862)
		(end 392.022076 -17.840198)
		(width 0.14224)
		(layer "In11.Cu")
		(net "P5E_CPU0_G3_RX_DP<14>")
	)
	(segment
		(start 362.251752 -222.291656)
		(end 362.268516 -222.301308)
		(width 0.1143)
		(layer "In11.Cu")
		(net "P5E_CPU0_G3_RX_DP<14>")
	)
	(segment
		(start 309.105046 -146.976084)
		(end 306.640992 -161.002726)
		(width 0.14224)
		(layer "In11.Cu")
		(net "P5E_CPU0_G3_RX_DP<14>")
	)
	(segment
		(start 315.849 -128.376426)
		(end 309.105046 -146.976084)
		(width 0.14224)
		(layer "In11.Cu")
		(net "P5E_CPU0_G3_RX_DP<14>")
	)
	(segment
		(start 361.275376 -230.37038)
		(end 361.342432 -230.409496)
		(width 0.1143)
		(layer "In11.Cu")
		(net "P5E_CPU0_G3_RX_DP<14>")
	)
	(segment
		(start 361.27563 -227.13061)
		(end 361.311952 -227.151692)
		(width 0.1143)
		(layer "In11.Cu")
		(net "P5E_CPU0_G3_RX_DP<14>")
	)
	(segment
		(start 361.029758 -229.904036)
		(end 361.029504 -229.904036)
		(width 0.1143)
		(layer "In11.Cu")
		(net "P5E_CPU0_G3_RX_DP<14>")
	)
	(segment
		(start 362.4326 -246.844312)
		(end 362.36275 -246.914162)
		(width 0.1143)
		(layer "In11.Cu")
		(net "P5E_CPU0_G3_RX_DP<14>")
	)
	(segment
		(start 361.269534 -237.541308)
		(end 361.259628 -237.548674)
		(width 0.1143)
		(layer "In11.Cu")
		(net "P5E_CPU0_G3_RX_DP<14>")
	)
	(segment
		(start 362.36275 -246.914162)
		(end 362.064808 -246.914162)
		(width 0.1143)
		(layer "In11.Cu")
		(net "P5E_CPU0_G3_RX_DP<14>")
	)
	(segment
		(start 361.782106 -245.78183)
		(end 361.785916 -245.783862)
		(width 0.1143)
		(layer "In11.Cu")
		(net "P5E_CPU0_G3_RX_DP<14>")
	)
	(segment
		(start 361.342432 -239.118902)
		(end 361.269534 -239.16132)
		(width 0.1143)
		(layer "In11.Cu")
		(net "P5E_CPU0_G3_RX_DP<14>")
	)
	(segment
		(start 361.969558 -221.308676)
		(end 361.969304 -221.30893)
		(width 0.1143)
		(layer "In11.Cu")
		(net "P5E_CPU0_G3_RX_DP<14>")
	)
	(segment
		(start 361.032044 -229.87508)
		(end 361.030266 -229.888288)
		(width 0.1143)
		(layer "In11.Cu")
		(net "P5E_CPU0_G3_RX_DP<14>")
	)
	(segment
		(start 361.813602 -244.179852)
		(end 361.823254 -244.186964)
		(width 0.1143)
		(layer "In11.Cu")
		(net "P5E_CPU0_G3_RX_DP<14>")
	)
	(segment
		(start 361.311952 -228.771704)
		(end 361.342432 -228.789484)
		(width 0.1143)
		(layer "In11.Cu")
		(net "P5E_CPU0_G3_RX_DP<14>")
	)
	(segment
		(start 361.311952 -227.796852)
		(end 361.27563 -227.817934)
		(width 0.1143)
		(layer "In11.Cu")
		(net "P5E_CPU0_G3_RX_DP<14>")
	)
	(arc
		(start 361.499404 -225.85426)
		(mid 361.457855 -226.025682)
		(end 361.342432 -226.15906)
		(width 0.1143)
		(layer "In11.Cu")
		(net "P5E_CPU0_G3_RX_DP<14>")
	)
	(arc
		(start 361.272836 -231.059482)
		(mid 361.029509 -231.524048)
		(end 361.272836 -231.988614)
		(width 0.1143)
		(layer "In11.Cu")
		(net "P5E_CPU0_G3_RX_DP<14>")
	)
	(arc
		(start 361.597702 -224.7011)
		(mid 361.52495 -224.810076)
		(end 361.499404 -224.93859)
		(width 0.1143)
		(layer "In11.Cu")
		(net "P5E_CPU0_G3_RX_DP<14>")
	)
	(arc
		(start 361.969304 -221.80423)
		(mid 361.973805 -221.875922)
		(end 361.987338 -221.94647)
		(width 0.1143)
		(layer "In11.Cu")
		(net "P5E_CPU0_G3_RX_DP<14>")
	)
	(arc
		(start 361.342432 -236.88929)
		(mid 361.499409 -237.19409)
		(end 361.342432 -237.49889)
		(width 0.1143)
		(layer "In11.Cu")
		(net "P5E_CPU0_G3_RX_DP<14>")
	)
	(arc
		(start 361.342432 -238.509302)
		(mid 361.499409 -238.814102)
		(end 361.342432 -239.118902)
		(width 0.1143)
		(layer "In11.Cu")
		(net "P5E_CPU0_G3_RX_DP<14>")
	)
	(arc
		(start 361.342432 -230.409496)
		(mid 361.457859 -230.542872)
		(end 361.499404 -230.714296)
		(width 0.1143)
		(layer "In11.Cu")
		(net "P5E_CPU0_G3_RX_DP<14>")
	)
	(arc
		(start 361.276646 -229.437184)
		(mid 361.26069 -229.448848)
		(end 361.24515 -229.46106)
		(width 0.1143)
		(layer "In11.Cu")
		(net "P5E_CPU0_G3_RX_DP<14>")
	)
	(arc
		(start 362.068872 -222.125032)
		(mid 362.134237 -222.203431)
		(end 362.212636 -222.268796)
		(width 0.1143)
		(layer "In11.Cu")
		(net "P5E_CPU0_G3_RX_DP<14>")
	)
	(arc
		(start 361.259628 -235.928662)
		(mid 361.028029 -236.384084)
		(end 361.259628 -236.839506)
		(width 0.1143)
		(layer "In11.Cu")
		(net "P5E_CPU0_G3_RX_DP<14>")
	)
	(arc
		(start 361.029504 -242.864132)
		(mid 361.029998 -242.888538)
		(end 361.031536 -242.9129)
		(width 0.1143)
		(layer "In11.Cu")
		(net "P5E_CPU0_G3_RX_DP<14>")
	)
	(arc
		(start 361.342432 -232.029254)
		(mid 361.499409 -232.334054)
		(end 361.342432 -232.638854)
		(width 0.1143)
		(layer "In11.Cu")
		(net "P5E_CPU0_G3_RX_DP<14>")
	)
	(arc
		(start 361.971082 -224.267776)
		(mid 361.960003 -224.323473)
		(end 361.92841 -224.370646)
		(width 0.1143)
		(layer "In11.Cu")
		(net "P5E_CPU0_G3_RX_DP<14>")
	)
	(arc
		(start 361.031536 -242.9129)
		(mid 361.102142 -243.14279)
		(end 361.26293 -243.321586)
		(width 0.1143)
		(layer "In11.Cu")
		(net "P5E_CPU0_G3_RX_DP<14>")
	)
	(arc
		(start 361.342432 -241.749326)
		(mid 361.499409 -242.054126)
		(end 361.342432 -242.358926)
		(width 0.1143)
		(layer "In11.Cu")
		(net "P5E_CPU0_G3_RX_DP<14>")
	)
	(arc
		(start 361.27563 -226.197922)
		(mid 361.02974 -226.664266)
		(end 361.27563 -227.13061)
		(width 0.1143)
		(layer "In11.Cu")
		(net "P5E_CPU0_G3_RX_DP<14>")
	)
	(arc
		(start 361.342432 -243.369338)
		(mid 361.457859 -243.502714)
		(end 361.499404 -243.674138)
		(width 0.1143)
		(layer "In11.Cu")
		(net "P5E_CPU0_G3_RX_DP<14>")
	)
	(arc
		(start 361.342432 -235.269278)
		(mid 361.499409 -235.574078)
		(end 361.342432 -235.878878)
		(width 0.1143)
		(layer "In11.Cu")
		(net "P5E_CPU0_G3_RX_DP<14>")
	)
	(arc
		(start 361.499404 -229.094284)
		(mid 361.458438 -229.26469)
		(end 361.344464 -229.397814)
		(width 0.1143)
		(layer "In11.Cu")
		(net "P5E_CPU0_G3_RX_DP<14>")
	)
	(arc
		(start 361.259628 -237.548674)
		(mid 361.028029 -238.004096)
		(end 361.259628 -238.459518)
		(width 0.1143)
		(layer "In11.Cu")
		(net "P5E_CPU0_G3_RX_DP<14>")
	)
	(arc
		(start 361.966002 -246.100092)
		(mid 362.041977 -246.383115)
		(end 362.249466 -246.590058)
		(width 0.1143)
		(layer "In11.Cu")
		(net "P5E_CPU0_G3_RX_DP<14>")
	)
	(arc
		(start 361.342432 -228.789484)
		(mid 361.457859 -228.92286)
		(end 361.499404 -229.094284)
		(width 0.1143)
		(layer "In11.Cu")
		(net "P5E_CPU0_G3_RX_DP<14>")
	)
	(arc
		(start 361.785916 -245.783862)
		(mid 361.917797 -245.918158)
		(end 361.966002 -246.100092)
		(width 0.1143)
		(layer "In11.Cu")
		(net "P5E_CPU0_G3_RX_DP<14>")
	)
	(arc
		(start 361.742736 -244.829584)
		(mid 361.499409 -245.29415)
		(end 361.742736 -245.758716)
		(width 0.1143)
		(layer "In11.Cu")
		(net "P5E_CPU0_G3_RX_DP<14>")
	)
	(arc
		(start 362.283502 -222.310198)
		(mid 362.398178 -222.443389)
		(end 362.439458 -222.614236)
		(width 0.1143)
		(layer "In11.Cu")
		(net "P5E_CPU0_G3_RX_DP<14>")
	)
	(arc
		(start 361.987338 -221.94647)
		(mid 362.020303 -222.039313)
		(end 362.068872 -222.125032)
		(width 0.1143)
		(layer "In11.Cu")
		(net "P5E_CPU0_G3_RX_DP<14>")
	)
	(arc
		(start 361.259628 -232.688638)
		(mid 361.028029 -233.14406)
		(end 361.259628 -233.599482)
		(width 0.1143)
		(layer "In11.Cu")
		(net "P5E_CPU0_G3_RX_DP<14>")
	)
	(arc
		(start 361.499404 -230.714296)
		(mid 361.458438 -230.884702)
		(end 361.344464 -231.017826)
		(width 0.1143)
		(layer "In11.Cu")
		(net "P5E_CPU0_G3_RX_DP<14>")
	)
	(arc
		(start 361.499404 -243.674138)
		(mid 361.563919 -243.936357)
		(end 361.742736 -244.138704)
		(width 0.1143)
		(layer "In11.Cu")
		(net "P5E_CPU0_G3_RX_DP<14>")
	)
	(arc
		(start 362.283502 -246.610124)
		(mid 362.314349 -246.634863)
		(end 362.34243 -246.662702)
		(width 0.1143)
		(layer "In11.Cu")
		(net "P5E_CPU0_G3_RX_DP<14>")
	)
	(arc
		(start 361.27563 -227.817934)
		(mid 361.02974 -228.284278)
		(end 361.27563 -228.750622)
		(width 0.1143)
		(layer "In11.Cu")
		(net "P5E_CPU0_G3_RX_DP<14>")
	)
	(arc
		(start 361.342432 -240.129314)
		(mid 361.499409 -240.434114)
		(end 361.342432 -240.738914)
		(width 0.1143)
		(layer "In11.Cu")
		(net "P5E_CPU0_G3_RX_DP<14>")
	)
	(arc
		(start 362.248704 -222.941642)
		(mid 362.038636 -223.158593)
		(end 361.971082 -223.452944)
		(width 0.1143)
		(layer "In11.Cu")
		(net "P5E_CPU0_G3_RX_DP<14>")
	)
	(arc
		(start 361.27182 -242.39982)
		(mid 361.093638 -242.602223)
		(end 361.029504 -242.864132)
		(width 0.1143)
		(layer "In11.Cu")
		(net "P5E_CPU0_G3_RX_DP<14>")
	)
	(arc
		(start 361.259628 -239.168686)
		(mid 361.028029 -239.624108)
		(end 361.259628 -240.07953)
		(width 0.1143)
		(layer "In11.Cu")
		(net "P5E_CPU0_G3_RX_DP<14>")
	)
	(arc
		(start 361.823254 -244.186964)
		(mid 361.975522 -244.484144)
		(end 361.823254 -244.781324)
		(width 0.1143)
		(layer "In11.Cu")
		(net "P5E_CPU0_G3_RX_DP<14>")
	)
	(arc
		(start 361.27182 -240.780062)
		(mid 361.005562 -241.24412)
		(end 361.27182 -241.708178)
		(width 0.1143)
		(layer "In11.Cu")
		(net "P5E_CPU0_G3_RX_DP<14>")
	)
	(arc
		(start 361.259628 -234.30865)
		(mid 361.028029 -234.764072)
		(end 361.259628 -235.219494)
		(width 0.1143)
		(layer "In11.Cu")
		(net "P5E_CPU0_G3_RX_DP<14>")
	)
	(arc
		(start 362.439458 -222.614236)
		(mid 362.389477 -222.801481)
		(end 362.253022 -222.939102)
		(width 0.1143)
		(layer "In11.Cu")
		(net "P5E_CPU0_G3_RX_DP<14>")
	)
	(arc
		(start 361.342432 -233.649266)
		(mid 361.499409 -233.954066)
		(end 361.342432 -234.258866)
		(width 0.1143)
		(layer "In11.Cu")
		(net "P5E_CPU0_G3_RX_DP<14>")
	)
	(arc
		(start 361.342432 -227.169472)
		(mid 361.499409 -227.474272)
		(end 361.342432 -227.779072)
		(width 0.1143)
		(layer "In11.Cu")
		(net "P5E_CPU0_G3_RX_DP<14>")
	)
	(arc
		(start 361.24515 -229.46106)
		(mid 361.103627 -229.650073)
		(end 361.032044 -229.87508)
		(width 0.1143)
		(layer "In11.Cu")
		(net "P5E_CPU0_G3_RX_DP<14>")
	)
	(arc
		(start 361.029504 -229.904036)
		(mid 361.09474 -230.167627)
		(end 361.275376 -230.37038)
		(width 0.1143)
		(layer "In11.Cu")
		(net "P5E_CPU0_G3_RX_DP<14>")
	)
	(arc
		(start 362.34243 -246.662702)
		(mid 362.400049 -246.747286)
		(end 362.4326 -246.844312)
		(width 0.1143)
		(layer "In11.Cu")
		(net "P5E_CPU0_G3_RX_DP<14>")
	)
	(segment
		(start 397.246856 -8.320024)
		(end 397.246856 -7.709154)
		(width 0.12954)
		(layer "F.Cu")
		(net "P5E_CPU0_G3_RX_DP<13>")
	)
	(segment
		(start 397.246856 -7.709154)
		(end 397.38554 -7.57047)
		(width 0.12954)
		(layer "F.Cu")
		(net "P5E_CPU0_G3_RX_DP<13>")
	)
	(segment
		(start 397.38554 -7.57047)
		(end 397.38554 -6.99516)
		(width 0.12954)
		(layer "F.Cu")
		(net "P5E_CPU0_G3_RX_DP<13>")
	)
	(segment
		(start 361.597956 -243.940076)
		(end 362.064808 -243.674138)
		(width 0.12954)
		(layer "F.Cu")
		(net "P5E_CPU0_G3_RX_DP<13>")
	)
	(segment
		(start 397.38554 -6.99516)
		(end 397.115538 -6.725158)
		(width 0.12954)
		(layer "F.Cu")
		(net "P5E_CPU0_G3_RX_DP<13>")
	)
	(segment
		(start 362.261658 -227.79101)
		(end 362.260896 -227.791518)
		(width 0.1143)
		(layer "In11.Cu")
		(net "P5E_CPU0_G3_RX_DP<13>")
	)
	(segment
		(start 362.28528 -229.397052)
		(end 362.283756 -229.398068)
		(width 0.1143)
		(layer "In11.Cu")
		(net "P5E_CPU0_G3_RX_DP<13>")
	)
	(segment
		(start 362.187236 -241.690652)
		(end 362.21289 -241.70894)
		(width 0.1143)
		(layer "In11.Cu")
		(net "P5E_CPU0_G3_RX_DP<13>")
	)
	(segment
		(start 362.283502 -242.358418)
		(end 362.262166 -242.370864)
		(width 0.1143)
		(layer "In11.Cu")
		(net "P5E_CPU0_G3_RX_DP<13>")
	)
	(segment
		(start 362.251752 -227.151692)
		(end 362.283502 -227.16998)
		(width 0.1143)
		(layer "In11.Cu")
		(net "P5E_CPU0_G3_RX_DP<13>")
	)
	(segment
		(start 362.252514 -238.49203)
		(end 362.253784 -238.492792)
		(width 0.1143)
		(layer "In11.Cu")
		(net "P5E_CPU0_G3_RX_DP<13>")
	)
	(segment
		(start 362.260896 -227.791518)
		(end 362.259118 -227.792534)
		(width 0.1143)
		(layer "In11.Cu")
		(net "P5E_CPU0_G3_RX_DP<13>")
	)
	(segment
		(start 362.283502 -240.738406)
		(end 362.262166 -240.750852)
		(width 0.1143)
		(layer "In11.Cu")
		(net "P5E_CPU0_G3_RX_DP<13>")
	)
	(segment
		(start 362.259626 -240.752122)
		(end 362.258356 -240.752884)
		(width 0.1143)
		(layer "In11.Cu")
		(net "P5E_CPU0_G3_RX_DP<13>")
	)
	(segment
		(start 362.258356 -226.17303)
		(end 362.25734 -226.173538)
		(width 0.1143)
		(layer "In11.Cu")
		(net "P5E_CPU0_G3_RX_DP<13>")
	)
	(segment
		(start 395.650212 -15.145258)
		(end 395.650466 -15.145258)
		(width 0.14224)
		(layer "In11.Cu")
		(net "P5E_CPU0_G3_RX_DP<13>")
	)
	(segment
		(start 362.250228 -241.73053)
		(end 362.252514 -241.732054)
		(width 0.1143)
		(layer "In11.Cu")
		(net "P5E_CPU0_G3_RX_DP<13>")
	)
	(segment
		(start 394.811758 -18.879566)
		(end 394.853668 -19.018504)
		(width 0.14224)
		(layer "In11.Cu")
		(net "P5E_CPU0_G3_RX_DP<13>")
	)
	(segment
		(start 362.253784 -232.012744)
		(end 362.283502 -232.029762)
		(width 0.1143)
		(layer "In11.Cu")
		(net "P5E_CPU0_G3_RX_DP<13>")
	)
	(segment
		(start 362.259626 -234.272074)
		(end 362.258356 -234.272836)
		(width 0.1143)
		(layer "In11.Cu")
		(net "P5E_CPU0_G3_RX_DP<13>")
	)
	(segment
		(start 362.868718 -221.054676)
		(end 362.868718 -221.083124)
		(width 0.1143)
		(layer "In11.Cu")
		(net "P5E_CPU0_G3_RX_DP<13>")
	)
	(segment
		(start 362.283502 -235.87837)
		(end 362.262166 -235.890816)
		(width 0.1143)
		(layer "In11.Cu")
		(net "P5E_CPU0_G3_RX_DP<13>")
	)
	(segment
		(start 362.252514 -242.376198)
		(end 362.251752 -242.376706)
		(width 0.1143)
		(layer "In11.Cu")
		(net "P5E_CPU0_G3_RX_DP<13>")
	)
	(segment
		(start 362.259626 -239.13211)
		(end 362.258356 -239.132872)
		(width 0.1143)
		(layer "In11.Cu")
		(net "P5E_CPU0_G3_RX_DP<13>")
	)
	(segment
		(start 316.660022 -128.889506)
		(end 316.65037 -128.907794)
		(width 0.14224)
		(layer "In11.Cu")
		(net "P5E_CPU0_G3_RX_DP<13>")
	)
	(segment
		(start 362.258356 -234.272836)
		(end 362.257594 -234.273344)
		(width 0.1143)
		(layer "In11.Cu")
		(net "P5E_CPU0_G3_RX_DP<13>")
	)
	(segment
		(start 362.909612 -225.042222)
		(end 362.909612 -225.044254)
		(width 0.1143)
		(layer "In11.Cu")
		(net "P5E_CPU0_G3_RX_DP<13>")
	)
	(segment
		(start 394.242544 -17.252442)
		(end 394.12799 -17.527016)
		(width 0.14224)
		(layer "In11.Cu")
		(net "P5E_CPU0_G3_RX_DP<13>")
	)
	(segment
		(start 370.681758 -55.271416)
		(end 319.387474 -123.8377)
		(width 0.14224)
		(layer "In11.Cu")
		(net "P5E_CPU0_G3_RX_DP<13>")
	)
	(segment
		(start 362.25607 -242.374166)
		(end 362.255308 -242.374674)
		(width 0.1143)
		(layer "In11.Cu")
		(net "P5E_CPU0_G3_RX_DP<13>")
	)
	(segment
		(start 362.255308 -232.654602)
		(end 362.252514 -232.656126)
		(width 0.1143)
		(layer "In11.Cu")
		(net "P5E_CPU0_G3_RX_DP<13>")
	)
	(segment
		(start 362.259626 -232.652062)
		(end 362.258356 -232.652824)
		(width 0.1143)
		(layer "In11.Cu")
		(net "P5E_CPU0_G3_RX_DP<13>")
	)
	(segment
		(start 362.255562 -227.794566)
		(end 362.254292 -227.795328)
		(width 0.1143)
		(layer "In11.Cu")
		(net "P5E_CPU0_G3_RX_DP<13>")
	)
	(segment
		(start 362.253784 -243.352828)
		(end 362.283502 -243.369846)
		(width 0.1143)
		(layer "In11.Cu")
		(net "P5E_CPU0_G3_RX_DP<13>")
	)
	(segment
		(start 362.262166 -232.650792)
		(end 362.259626 -232.652062)
		(width 0.1143)
		(layer "In11.Cu")
		(net "P5E_CPU0_G3_RX_DP<13>")
	)
	(segment
		(start 362.283502 -237.498382)
		(end 362.262166 -237.510828)
		(width 0.1143)
		(layer "In11.Cu")
		(net "P5E_CPU0_G3_RX_DP<13>")
	)
	(segment
		(start 362.255308 -240.754662)
		(end 362.252514 -240.756186)
		(width 0.1143)
		(layer "In11.Cu")
		(net "P5E_CPU0_G3_RX_DP<13>")
	)
	(segment
		(start 362.251752 -233.631486)
		(end 362.252514 -233.631994)
		(width 0.1143)
		(layer "In11.Cu")
		(net "P5E_CPU0_G3_RX_DP<13>")
	)
	(segment
		(start 362.262166 -240.750852)
		(end 362.259626 -240.752122)
		(width 0.1143)
		(layer "In11.Cu")
		(net "P5E_CPU0_G3_RX_DP<13>")
	)
	(segment
		(start 362.251752 -232.011474)
		(end 362.252514 -232.011982)
		(width 0.1143)
		(layer "In11.Cu")
		(net "P5E_CPU0_G3_RX_DP<13>")
	)
	(segment
		(start 363.379258 -224.230946)
		(end 363.379512 -224.232978)
		(width 0.1143)
		(layer "In11.Cu")
		(net "P5E_CPU0_G3_RX_DP<13>")
	)
	(segment
		(start 363.192568 -224.55632)
		(end 363.190282 -224.557844)
		(width 0.1143)
		(layer "In11.Cu")
		(net "P5E_CPU0_G3_RX_DP<13>")
	)
	(segment
		(start 362.257594 -242.373404)
		(end 362.25607 -242.374166)
		(width 0.1143)
		(layer "In11.Cu")
		(net "P5E_CPU0_G3_RX_DP<13>")
	)
	(segment
		(start 362.914438 -221.128844)
		(end 362.914438 -221.308676)
		(width 0.1143)
		(layer "In11.Cu")
		(net "P5E_CPU0_G3_RX_DP<13>")
	)
	(segment
		(start 362.21543 -233.610404)
		(end 362.251752 -233.631486)
		(width 0.1143)
		(layer "In11.Cu")
		(net "P5E_CPU0_G3_RX_DP<13>")
	)
	(segment
		(start 362.258356 -239.132872)
		(end 362.257594 -239.13338)
		(width 0.1143)
		(layer "In11.Cu")
		(net "P5E_CPU0_G3_RX_DP<13>")
	)
	(segment
		(start 363.15269 -222.268796)
		(end 363.189266 -222.290132)
		(width 0.1143)
		(layer "In11.Cu")
		(net "P5E_CPU0_G3_RX_DP<13>")
	)
	(segment
		(start 362.25607 -239.134142)
		(end 362.255308 -239.13465)
		(width 0.1143)
		(layer "In11.Cu")
		(net "P5E_CPU0_G3_RX_DP<13>")
	)
	(segment
		(start 362.25734 -226.173538)
		(end 362.256578 -226.174046)
		(width 0.1143)
		(layer "In11.Cu")
		(net "P5E_CPU0_G3_RX_DP<13>")
	)
	(segment
		(start 362.283756 -229.398068)
		(end 362.222796 -229.433882)
		(width 0.1143)
		(layer "In11.Cu")
		(net "P5E_CPU0_G3_RX_DP<13>")
	)
	(segment
		(start 362.251752 -228.771704)
		(end 362.252514 -228.772212)
		(width 0.1143)
		(layer "In11.Cu")
		(net "P5E_CPU0_G3_RX_DP<13>")
	)
	(segment
		(start 362.251752 -239.136682)
		(end 362.21543 -239.157764)
		(width 0.1143)
		(layer "In11.Cu")
		(net "P5E_CPU0_G3_RX_DP<13>")
	)
	(segment
		(start 362.259626 -235.892086)
		(end 362.258356 -235.892848)
		(width 0.1143)
		(layer "In11.Cu")
		(net "P5E_CPU0_G3_RX_DP<13>")
	)
	(segment
		(start 362.252514 -235.89615)
		(end 362.251752 -235.896658)
		(width 0.1143)
		(layer "In11.Cu")
		(net "P5E_CPU0_G3_RX_DP<13>")
	)
	(segment
		(start 362.251244 -228.771704)
		(end 362.251752 -228.771704)
		(width 0.1143)
		(layer "In11.Cu")
		(net "P5E_CPU0_G3_RX_DP<13>")
	)
	(segment
		(start 362.251752 -235.896658)
		(end 362.248958 -235.898436)
		(width 0.1143)
		(layer "In11.Cu")
		(net "P5E_CPU0_G3_RX_DP<13>")
	)
	(segment
		(start 316.660276 -128.889506)
		(end 316.660022 -128.889506)
		(width 0.14224)
		(layer "In11.Cu")
		(net "P5E_CPU0_G3_RX_DP<13>")
	)
	(segment
		(start 362.257594 -234.273344)
		(end 362.25607 -234.274106)
		(width 0.1143)
		(layer "In11.Cu")
		(net "P5E_CPU0_G3_RX_DP<13>")
	)
	(segment
		(start 362.25607 -240.754154)
		(end 362.255308 -240.754662)
		(width 0.1143)
		(layer "In11.Cu")
		(net "P5E_CPU0_G3_RX_DP<13>")
	)
	(segment
		(start 362.25607 -232.654094)
		(end 362.255308 -232.654602)
		(width 0.1143)
		(layer "In11.Cu")
		(net "P5E_CPU0_G3_RX_DP<13>")
	)
	(segment
		(start 362.251752 -237.51667)
		(end 362.21543 -237.537752)
		(width 0.1143)
		(layer "In11.Cu")
		(net "P5E_CPU0_G3_RX_DP<13>")
	)
	(segment
		(start 362.285534 -231.017064)
		(end 362.28528 -231.017064)
		(width 0.1143)
		(layer "In11.Cu")
		(net "P5E_CPU0_G3_RX_DP<13>")
	)
	(segment
		(start 310.007 -147.23364)
		(end 307.628036 -160.774634)
		(width 0.14224)
		(layer "In11.Cu")
		(net "P5E_CPU0_G3_RX_DP<13>")
	)
	(segment
		(start 362.868718 -221.083124)
		(end 362.914438 -221.128844)
		(width 0.1143)
		(layer "In11.Cu")
		(net "P5E_CPU0_G3_RX_DP<13>")
	)
	(segment
		(start 362.259118 -227.792534)
		(end 362.258356 -227.793042)
		(width 0.1143)
		(layer "In11.Cu")
		(net "P5E_CPU0_G3_RX_DP<13>")
	)
	(segment
		(start 362.252514 -239.136174)
		(end 362.251752 -239.136682)
		(width 0.1143)
		(layer "In11.Cu")
		(net "P5E_CPU0_G3_RX_DP<13>")
	)
	(segment
		(start 307.628036 -162.874198)
		(end 310.338216 -169.418)
		(width 0.14224)
		(layer "In11.Cu")
		(net "P5E_CPU0_G3_RX_DP<13>")
	)
	(segment
		(start 362.255308 -234.274614)
		(end 362.252514 -234.276138)
		(width 0.1143)
		(layer "In11.Cu")
		(net "P5E_CPU0_G3_RX_DP<13>")
	)
	(segment
		(start 362.258356 -227.793042)
		(end 362.25734 -227.79355)
		(width 0.1143)
		(layer "In11.Cu")
		(net "P5E_CPU0_G3_RX_DP<13>")
	)
	(segment
		(start 362.253784 -241.732816)
		(end 362.283502 -241.749834)
		(width 0.1143)
		(layer "In11.Cu")
		(net "P5E_CPU0_G3_RX_DP<13>")
	)
	(segment
		(start 362.258356 -235.892848)
		(end 362.257594 -235.893356)
		(width 0.1143)
		(layer "In11.Cu")
		(net "P5E_CPU0_G3_RX_DP<13>")
	)
	(segment
		(start 363.223556 -222.309944)
		(end 363.226604 -222.31223)
		(width 0.1143)
		(layer "In11.Cu")
		(net "P5E_CPU0_G3_RX_DP<13>")
	)
	(segment
		(start 362.21289 -236.848904)
		(end 362.250228 -236.870494)
		(width 0.1143)
		(layer "In11.Cu")
		(net "P5E_CPU0_G3_RX_DP<13>")
	)
	(segment
		(start 362.257594 -239.13338)
		(end 362.25607 -239.134142)
		(width 0.1143)
		(layer "In11.Cu")
		(net "P5E_CPU0_G3_RX_DP<13>")
	)
	(segment
		(start 362.262166 -237.510828)
		(end 362.259626 -237.512098)
		(width 0.1143)
		(layer "In11.Cu")
		(net "P5E_CPU0_G3_RX_DP<13>")
	)
	(segment
		(start 362.283502 -239.118394)
		(end 362.262166 -239.13084)
		(width 0.1143)
		(layer "In11.Cu")
		(net "P5E_CPU0_G3_RX_DP<13>")
	)
	(segment
		(start 362.262166 -235.890816)
		(end 362.259626 -235.892086)
		(width 0.1143)
		(layer "In11.Cu")
		(net "P5E_CPU0_G3_RX_DP<13>")
	)
	(segment
		(start 362.253784 -236.87278)
		(end 362.283502 -236.889798)
		(width 0.1143)
		(layer "In11.Cu")
		(net "P5E_CPU0_G3_RX_DP<13>")
	)
	(segment
		(start 310.338216 -169.418)
		(end 314.865258 -173.946312)
		(width 0.14224)
		(layer "In11.Cu")
		(net "P5E_CPU0_G3_RX_DP<13>")
	)
	(segment
		(start 362.252514 -233.631994)
		(end 362.253784 -233.632756)
		(width 0.1143)
		(layer "In11.Cu")
		(net "P5E_CPU0_G3_RX_DP<13>")
	)
	(segment
		(start 362.26496 -227.789232)
		(end 362.263944 -227.78974)
		(width 0.1143)
		(layer "In11.Cu")
		(net "P5E_CPU0_G3_RX_DP<13>")
	)
	(segment
		(start 362.21289 -235.919264)
		(end 362.18495 -235.93933)
		(width 0.1143)
		(layer "In11.Cu")
		(net "P5E_CPU0_G3_RX_DP<13>")
	)
	(segment
		(start 394.12799 -17.527016)
		(end 394.12799 -17.696434)
		(width 0.14224)
		(layer "In11.Cu")
		(net "P5E_CPU0_G3_RX_DP<13>")
	)
	(segment
		(start 395.650466 -15.145258)
		(end 394.242544 -17.252442)
		(width 0.14224)
		(layer "In11.Cu")
		(net "P5E_CPU0_G3_RX_DP<13>")
	)
	(segment
		(start 362.263944 -227.78974)
		(end 362.263182 -227.790248)
		(width 0.1143)
		(layer "In11.Cu")
		(net "P5E_CPU0_G3_RX_DP<13>")
	)
	(segment
		(start 363.152944 -224.579434)
		(end 363.143292 -224.586292)
		(width 0.1143)
		(layer "In11.Cu")
		(net "P5E_CPU0_G3_RX_DP<13>")
	)
	(segment
		(start 362.255308 -239.13465)
		(end 362.252514 -239.136174)
		(width 0.1143)
		(layer "In11.Cu")
		(net "P5E_CPU0_G3_RX_DP<13>")
	)
	(segment
		(start 362.252514 -243.352066)
		(end 362.253784 -243.352828)
		(width 0.1143)
		(layer "In11.Cu")
		(net "P5E_CPU0_G3_RX_DP<13>")
	)
	(segment
		(start 362.255308 -237.514638)
		(end 362.252514 -237.516162)
		(width 0.1143)
		(layer "In11.Cu")
		(net "P5E_CPU0_G3_RX_DP<13>")
	)
	(segment
		(start 362.21289 -241.70894)
		(end 362.250228 -241.73053)
		(width 0.1143)
		(layer "In11.Cu")
		(net "P5E_CPU0_G3_RX_DP<13>")
	)
	(segment
		(start 362.257594 -237.513368)
		(end 362.25607 -237.51413)
		(width 0.1143)
		(layer "In11.Cu")
		(net "P5E_CPU0_G3_RX_DP<13>")
	)
	(segment
		(start 362.253784 -240.112804)
		(end 362.283502 -240.129822)
		(width 0.1143)
		(layer "In11.Cu")
		(net "P5E_CPU0_G3_RX_DP<13>")
	)
	(segment
		(start 362.21543 -235.230416)
		(end 362.251752 -235.251498)
		(width 0.1143)
		(layer "In11.Cu")
		(net "P5E_CPU0_G3_RX_DP<13>")
	)
	(segment
		(start 362.252514 -237.516162)
		(end 362.251752 -237.51667)
		(width 0.1143)
		(layer "In11.Cu")
		(net "P5E_CPU0_G3_RX_DP<13>")
	)
	(segment
		(start 319.387474 -123.8377)
		(end 316.660276 -128.889506)
		(width 0.14224)
		(layer "In11.Cu")
		(net "P5E_CPU0_G3_RX_DP<13>")
	)
	(segment
		(start 362.36275 -243.674138)
		(end 362.064808 -243.674138)
		(width 0.1143)
		(layer "In11.Cu")
		(net "P5E_CPU0_G3_RX_DP<13>")
	)
	(segment
		(start 362.909358 -221.313756)
		(end 362.909358 -221.80423)
		(width 0.1143)
		(layer "In11.Cu")
		(net "P5E_CPU0_G3_RX_DP<13>")
	)
	(segment
		(start 363.191806 -222.291656)
		(end 363.223556 -222.309944)
		(width 0.1143)
		(layer "In11.Cu")
		(net "P5E_CPU0_G3_RX_DP<13>")
	)
	(segment
		(start 362.09732 -229.545896)
		(end 362.09732 -229.54615)
		(width 0.1143)
		(layer "In11.Cu")
		(net "P5E_CPU0_G3_RX_DP<13>")
	)
	(segment
		(start 362.21289 -240.7793)
		(end 362.187236 -240.797588)
		(width 0.1143)
		(layer "In11.Cu")
		(net "P5E_CPU0_G3_RX_DP<13>")
	)
	(segment
		(start 362.21289 -242.399312)
		(end 362.18495 -242.419378)
		(width 0.1143)
		(layer "In11.Cu")
		(net "P5E_CPU0_G3_RX_DP<13>")
	)
	(segment
		(start 362.251752 -234.276646)
		(end 362.21543 -234.297728)
		(width 0.1143)
		(layer "In11.Cu")
		(net "P5E_CPU0_G3_RX_DP<13>")
	)
	(segment
		(start 363.226604 -222.916242)
		(end 363.223556 -222.918528)
		(width 0.1143)
		(layer "In11.Cu")
		(net "P5E_CPU0_G3_RX_DP<13>")
	)
	(segment
		(start 321.134232 -177.76825)
		(end 358.649778 -208.529682)
		(width 0.14224)
		(layer "In11.Cu")
		(net "P5E_CPU0_G3_RX_DP<13>")
	)
	(segment
		(start 362.255308 -235.894626)
		(end 362.252514 -235.89615)
		(width 0.1143)
		(layer "In11.Cu")
		(net "P5E_CPU0_G3_RX_DP<13>")
	)
	(segment
		(start 362.259626 -237.512098)
		(end 362.258356 -237.51286)
		(width 0.1143)
		(layer "In11.Cu")
		(net "P5E_CPU0_G3_RX_DP<13>")
	)
	(segment
		(start 362.251752 -240.756694)
		(end 362.248958 -240.758472)
		(width 0.1143)
		(layer "In11.Cu")
		(net "P5E_CPU0_G3_RX_DP<13>")
	)
	(segment
		(start 362.21543 -240.090452)
		(end 362.251752 -240.111534)
		(width 0.1143)
		(layer "In11.Cu")
		(net "P5E_CPU0_G3_RX_DP<13>")
	)
	(segment
		(start 362.258356 -232.652824)
		(end 362.257594 -232.653332)
		(width 0.1143)
		(layer "In11.Cu")
		(net "P5E_CPU0_G3_RX_DP<13>")
	)
	(segment
		(start 362.257594 -235.893356)
		(end 362.25607 -235.894118)
		(width 0.1143)
		(layer "In11.Cu")
		(net "P5E_CPU0_G3_RX_DP<13>")
	)
	(segment
		(start 363.19587 -224.554796)
		(end 363.195362 -224.55505)
		(width 0.1143)
		(layer "In11.Cu")
		(net "P5E_CPU0_G3_RX_DP<13>")
	)
	(segment
		(start 362.206286 -230.3653)
		(end 362.281724 -230.408988)
		(width 0.1143)
		(layer "In11.Cu")
		(net "P5E_CPU0_G3_RX_DP<13>")
	)
	(segment
		(start 362.25099 -227.151184)
		(end 362.251752 -227.151692)
		(width 0.1143)
		(layer "In11.Cu")
		(net "P5E_CPU0_G3_RX_DP<13>")
	)
	(segment
		(start 362.252514 -227.796344)
		(end 362.251752 -227.796852)
		(width 0.1143)
		(layer "In11.Cu")
		(net "P5E_CPU0_G3_RX_DP<13>")
	)
	(segment
		(start 362.753402 -225.348292)
		(end 362.68279 -225.389694)
		(width 0.1143)
		(layer "In11.Cu")
		(net "P5E_CPU0_G3_RX_DP<13>")
	)
	(segment
		(start 394.853668 -19.018504)
		(end 394.853668 -19.199098)
		(width 0.14224)
		(layer "In11.Cu")
		(net "P5E_CPU0_G3_RX_DP<13>")
	)
	(segment
		(start 362.252514 -240.112042)
		(end 362.253784 -240.112804)
		(width 0.1143)
		(layer "In11.Cu")
		(net "P5E_CPU0_G3_RX_DP<13>")
	)
	(segment
		(start 362.258356 -237.51286)
		(end 362.257594 -237.513368)
		(width 0.1143)
		(layer "In11.Cu")
		(net "P5E_CPU0_G3_RX_DP<13>")
	)
	(segment
		(start 362.257594 -240.753392)
		(end 362.25607 -240.754154)
		(width 0.1143)
		(layer "In11.Cu")
		(net "P5E_CPU0_G3_RX_DP<13>")
	)
	(segment
		(start 363.15142 -223.888046)
		(end 363.15142 -223.8883)
		(width 0.1143)
		(layer "In11.Cu")
		(net "P5E_CPU0_G3_RX_DP<13>")
	)
	(segment
		(start 362.18495 -243.308886)
		(end 362.21289 -243.328952)
		(width 0.1143)
		(layer "In11.Cu")
		(net "P5E_CPU0_G3_RX_DP<13>")
	)
	(segment
		(start 394.828522 -19.294348)
		(end 394.47343 -20.310094)
		(width 0.14224)
		(layer "In11.Cu")
		(net "P5E_CPU0_G3_RX_DP<13>")
	)
	(segment
		(start 362.283502 -226.158552)
		(end 362.258356 -226.17303)
		(width 0.1143)
		(layer "In11.Cu")
		(net "P5E_CPU0_G3_RX_DP<13>")
	)
	(segment
		(start 362.251752 -240.111534)
		(end 362.252514 -240.112042)
		(width 0.1143)
		(layer "In11.Cu")
		(net "P5E_CPU0_G3_RX_DP<13>")
	)
	(segment
		(start 362.251752 -235.251498)
		(end 362.252514 -235.252006)
		(width 0.1143)
		(layer "In11.Cu")
		(net "P5E_CPU0_G3_RX_DP<13>")
	)
	(segment
		(start 362.248958 -240.758472)
		(end 362.21289 -240.7793)
		(width 0.1143)
		(layer "In11.Cu")
		(net "P5E_CPU0_G3_RX_DP<13>")
	)
	(segment
		(start 363.191806 -222.936816)
		(end 363.15142 -222.960438)
		(width 0.1143)
		(layer "In11.Cu")
		(net "P5E_CPU0_G3_RX_DP<13>")
	)
	(segment
		(start 394.47343 -20.310094)
		(end 370.681758 -55.271416)
		(width 0.14224)
		(layer "In11.Cu")
		(net "P5E_CPU0_G3_RX_DP<13>")
	)
	(segment
		(start 320.19748 -177.142394)
		(end 321.134232 -177.76825)
		(width 0.14224)
		(layer "In11.Cu")
		(net "P5E_CPU0_G3_RX_DP<13>")
	)
	(segment
		(start 362.252514 -235.252006)
		(end 362.253784 -235.252768)
		(width 0.1143)
		(layer "In11.Cu")
		(net "P5E_CPU0_G3_RX_DP<13>")
	)
	(segment
		(start 362.283502 -227.778564)
		(end 362.267246 -227.787962)
		(width 0.1143)
		(layer "In11.Cu")
		(net "P5E_CPU0_G3_RX_DP<13>")
	)
	(segment
		(start 362.21543 -238.47044)
		(end 362.251752 -238.491522)
		(width 0.1143)
		(layer "In11.Cu")
		(net "P5E_CPU0_G3_RX_DP<13>")
	)
	(segment
		(start 362.252514 -228.772212)
		(end 362.253784 -228.772974)
		(width 0.1143)
		(layer "In11.Cu")
		(net "P5E_CPU0_G3_RX_DP<13>")
	)
	(segment
		(start 362.248958 -235.898436)
		(end 362.21289 -235.919264)
		(width 0.1143)
		(layer "In11.Cu")
		(net "P5E_CPU0_G3_RX_DP<13>")
	)
	(segment
		(start 362.868718 -215.635332)
		(end 362.868718 -221.054676)
		(width 0.14224)
		(layer "In11.Cu")
		(net "P5E_CPU0_G3_RX_DP<13>")
	)
	(segment
		(start 397.115538 -6.725158)
		(end 397.406368 -7.015988)
		(width 0.14224)
		(layer "In11.Cu")
		(net "P5E_CPU0_G3_RX_DP<13>")
	)
	(segment
		(start 362.25734 -227.79355)
		(end 362.255562 -227.794566)
		(width 0.1143)
		(layer "In11.Cu")
		(net "P5E_CPU0_G3_RX_DP<13>")
	)
	(segment
		(start 397.058134 -13.038328)
		(end 395.650212 -15.145258)
		(width 0.14224)
		(layer "In11.Cu")
		(net "P5E_CPU0_G3_RX_DP<13>")
	)
	(segment
		(start 314.865258 -173.946312)
		(end 320.19748 -177.142394)
		(width 0.14224)
		(layer "In11.Cu")
		(net "P5E_CPU0_G3_RX_DP<13>")
	)
	(segment
		(start 362.254292 -227.795328)
		(end 362.25353 -227.795836)
		(width 0.1143)
		(layer "In11.Cu")
		(net "P5E_CPU0_G3_RX_DP<13>")
	)
	(segment
		(start 397.406368 -11.89101)
		(end 397.058134 -13.038328)
		(width 0.14224)
		(layer "In11.Cu")
		(net "P5E_CPU0_G3_RX_DP<13>")
	)
	(segment
		(start 307.628036 -160.774634)
		(end 307.628036 -162.874198)
		(width 0.14224)
		(layer "In11.Cu")
		(net "P5E_CPU0_G3_RX_DP<13>")
	)
	(segment
		(start 362.252514 -232.656126)
		(end 362.251752 -232.656634)
		(width 0.1143)
		(layer "In11.Cu")
		(net "P5E_CPU0_G3_RX_DP<13>")
	)
	(segment
		(start 394.407136 -18.27403)
		(end 394.811758 -18.879566)
		(width 0.14224)
		(layer "In11.Cu")
		(net "P5E_CPU0_G3_RX_DP<13>")
	)
	(segment
		(start 362.18495 -236.828838)
		(end 362.21289 -236.848904)
		(width 0.1143)
		(layer "In11.Cu")
		(net "P5E_CPU0_G3_RX_DP<13>")
	)
	(segment
		(start 362.262166 -239.13084)
		(end 362.259626 -239.13211)
		(width 0.1143)
		(layer "In11.Cu")
		(net "P5E_CPU0_G3_RX_DP<13>")
	)
	(segment
		(start 363.189266 -222.290132)
		(end 363.19079 -222.291148)
		(width 0.1143)
		(layer "In11.Cu")
		(net "P5E_CPU0_G3_RX_DP<13>")
	)
	(segment
		(start 362.251752 -227.796852)
		(end 362.251244 -227.796852)
		(width 0.1143)
		(layer "In11.Cu")
		(net "P5E_CPU0_G3_RX_DP<13>")
	)
	(segment
		(start 362.252514 -232.011982)
		(end 362.253784 -232.012744)
		(width 0.1143)
		(layer "In11.Cu")
		(net "P5E_CPU0_G3_RX_DP<13>")
	)
	(segment
		(start 362.28528 -231.017064)
		(end 362.251752 -231.036622)
		(width 0.1143)
		(layer "In11.Cu")
		(net "P5E_CPU0_G3_RX_DP<13>")
	)
	(segment
		(start 362.25607 -237.51413)
		(end 362.255308 -237.514638)
		(width 0.1143)
		(layer "In11.Cu")
		(net "P5E_CPU0_G3_RX_DP<13>")
	)
	(segment
		(start 362.253784 -228.772974)
		(end 362.283502 -228.789992)
		(width 0.1143)
		(layer "In11.Cu")
		(net "P5E_CPU0_G3_RX_DP<13>")
	)
	(segment
		(start 363.379512 -224.232978)
		(end 363.379512 -224.234248)
		(width 0.1143)
		(layer "In11.Cu")
		(net "P5E_CPU0_G3_RX_DP<13>")
	)
	(segment
		(start 362.258356 -242.372896)
		(end 362.257594 -242.373404)
		(width 0.1143)
		(layer "In11.Cu")
		(net "P5E_CPU0_G3_RX_DP<13>")
	)
	(segment
		(start 362.250228 -236.870494)
		(end 362.252514 -236.872018)
		(width 0.1143)
		(layer "In11.Cu")
		(net "P5E_CPU0_G3_RX_DP<13>")
	)
	(segment
		(start 362.256578 -226.174046)
		(end 362.251752 -226.17684)
		(width 0.1143)
		(layer "In11.Cu")
		(net "P5E_CPU0_G3_RX_DP<13>")
	)
	(segment
		(start 362.21289 -243.328952)
		(end 362.250228 -243.350542)
		(width 0.1143)
		(layer "In11.Cu")
		(net "P5E_CPU0_G3_RX_DP<13>")
	)
	(segment
		(start 362.26623 -227.78847)
		(end 362.26496 -227.789232)
		(width 0.1143)
		(layer "In11.Cu")
		(net "P5E_CPU0_G3_RX_DP<13>")
	)
	(segment
		(start 316.65037 -128.907794)
		(end 310.007 -147.23364)
		(width 0.14224)
		(layer "In11.Cu")
		(net "P5E_CPU0_G3_RX_DP<13>")
	)
	(segment
		(start 363.190282 -224.557844)
		(end 363.152944 -224.579434)
		(width 0.1143)
		(layer "In11.Cu")
		(net "P5E_CPU0_G3_RX_DP<13>")
	)
	(segment
		(start 362.283502 -234.258358)
		(end 362.262166 -234.270804)
		(width 0.1143)
		(layer "In11.Cu")
		(net "P5E_CPU0_G3_RX_DP<13>")
	)
	(segment
		(start 362.25607 -234.274106)
		(end 362.255308 -234.274614)
		(width 0.1143)
		(layer "In11.Cu")
		(net "P5E_CPU0_G3_RX_DP<13>")
	)
	(segment
		(start 362.252514 -234.276138)
		(end 362.251752 -234.276646)
		(width 0.1143)
		(layer "In11.Cu")
		(net "P5E_CPU0_G3_RX_DP<13>")
	)
	(segment
		(start 397.406368 -7.015988)
		(end 397.406368 -11.89101)
		(width 0.14224)
		(layer "In11.Cu")
		(net "P5E_CPU0_G3_RX_DP<13>")
	)
	(segment
		(start 362.25353 -227.795836)
		(end 362.252514 -227.796344)
		(width 0.1143)
		(layer "In11.Cu")
		(net "P5E_CPU0_G3_RX_DP<13>")
	)
	(segment
		(start 362.262166 -242.370864)
		(end 362.259626 -242.372134)
		(width 0.1143)
		(layer "In11.Cu")
		(net "P5E_CPU0_G3_RX_DP<13>")
	)
	(segment
		(start 394.226034 -17.935702)
		(end 394.407136 -18.27403)
		(width 0.14224)
		(layer "In11.Cu")
		(net "P5E_CPU0_G3_RX_DP<13>")
	)
	(segment
		(start 362.257594 -232.653332)
		(end 362.25607 -232.654094)
		(width 0.1143)
		(layer "In11.Cu")
		(net "P5E_CPU0_G3_RX_DP<13>")
	)
	(segment
		(start 363.221778 -223.92894)
		(end 363.223556 -223.93021)
		(width 0.1143)
		(layer "In11.Cu")
		(net "P5E_CPU0_G3_RX_DP<13>")
	)
	(segment
		(start 363.19079 -222.291148)
		(end 363.191806 -222.291656)
		(width 0.1143)
		(layer "In11.Cu")
		(net "P5E_CPU0_G3_RX_DP<13>")
	)
	(segment
		(start 358.649778 -208.529682)
		(end 362.868718 -215.635332)
		(width 0.14224)
		(layer "In11.Cu")
		(net "P5E_CPU0_G3_RX_DP<13>")
	)
	(segment
		(start 362.251752 -232.656634)
		(end 362.21543 -232.677716)
		(width 0.1143)
		(layer "In11.Cu")
		(net "P5E_CPU0_G3_RX_DP<13>")
	)
	(segment
		(start 362.259626 -242.372134)
		(end 362.258356 -242.372896)
		(width 0.1143)
		(layer "In11.Cu")
		(net "P5E_CPU0_G3_RX_DP<13>")
	)
	(segment
		(start 362.255308 -242.374674)
		(end 362.252514 -242.376198)
		(width 0.1143)
		(layer "In11.Cu")
		(net "P5E_CPU0_G3_RX_DP<13>")
	)
	(segment
		(start 362.251752 -226.17684)
		(end 362.25099 -226.177348)
		(width 0.1143)
		(layer "In11.Cu")
		(net "P5E_CPU0_G3_RX_DP<13>")
	)
	(segment
		(start 362.253784 -235.252768)
		(end 362.283502 -235.269786)
		(width 0.1143)
		(layer "In11.Cu")
		(net "P5E_CPU0_G3_RX_DP<13>")
	)
	(segment
		(start 362.252514 -236.872018)
		(end 362.253784 -236.87278)
		(width 0.1143)
		(layer "In11.Cu")
		(net "P5E_CPU0_G3_RX_DP<13>")
	)
	(segment
		(start 362.248958 -242.378484)
		(end 362.21289 -242.399312)
		(width 0.1143)
		(layer "In11.Cu")
		(net "P5E_CPU0_G3_RX_DP<13>")
	)
	(segment
		(start 362.267246 -227.787962)
		(end 362.26623 -227.78847)
		(width 0.1143)
		(layer "In11.Cu")
		(net "P5E_CPU0_G3_RX_DP<13>")
	)
	(segment
		(start 362.25607 -235.894118)
		(end 362.255308 -235.894626)
		(width 0.1143)
		(layer "In11.Cu")
		(net "P5E_CPU0_G3_RX_DP<13>")
	)
	(segment
		(start 362.251752 -231.036622)
		(end 362.21543 -231.057704)
		(width 0.1143)
		(layer "In11.Cu")
		(net "P5E_CPU0_G3_RX_DP<13>")
	)
	(segment
		(start 362.253784 -233.632756)
		(end 362.283502 -233.649774)
		(width 0.1143)
		(layer "In11.Cu")
		(net "P5E_CPU0_G3_RX_DP<13>")
	)
	(segment
		(start 363.223556 -222.918528)
		(end 363.191806 -222.936816)
		(width 0.1143)
		(layer "In11.Cu")
		(net "P5E_CPU0_G3_RX_DP<13>")
	)
	(segment
		(start 362.258356 -240.752884)
		(end 362.257594 -240.753392)
		(width 0.1143)
		(layer "In11.Cu")
		(net "P5E_CPU0_G3_RX_DP<13>")
	)
	(segment
		(start 362.252514 -240.756186)
		(end 362.251752 -240.756694)
		(width 0.1143)
		(layer "In11.Cu")
		(net "P5E_CPU0_G3_RX_DP<13>")
	)
	(segment
		(start 363.195362 -224.55505)
		(end 363.192568 -224.55632)
		(width 0.1143)
		(layer "In11.Cu")
		(net "P5E_CPU0_G3_RX_DP<13>")
	)
	(segment
		(start 394.853668 -19.199098)
		(end 394.828522 -19.294348)
		(width 0.14224)
		(layer "In11.Cu")
		(net "P5E_CPU0_G3_RX_DP<13>")
	)
	(segment
		(start 362.251752 -238.491522)
		(end 362.252514 -238.49203)
		(width 0.1143)
		(layer "In11.Cu")
		(net "P5E_CPU0_G3_RX_DP<13>")
	)
	(segment
		(start 362.251752 -242.376706)
		(end 362.248958 -242.378484)
		(width 0.1143)
		(layer "In11.Cu")
		(net "P5E_CPU0_G3_RX_DP<13>")
	)
	(segment
		(start 362.914438 -221.308676)
		(end 362.909358 -221.313756)
		(width 0.1143)
		(layer "In11.Cu")
		(net "P5E_CPU0_G3_RX_DP<13>")
	)
	(segment
		(start 363.153452 -223.88957)
		(end 363.221778 -223.92894)
		(width 0.1143)
		(layer "In11.Cu")
		(net "P5E_CPU0_G3_RX_DP<13>")
	)
	(segment
		(start 362.21543 -231.990392)
		(end 362.251752 -232.011474)
		(width 0.1143)
		(layer "In11.Cu")
		(net "P5E_CPU0_G3_RX_DP<13>")
	)
	(segment
		(start 362.263182 -227.790248)
		(end 362.261658 -227.79101)
		(width 0.1143)
		(layer "In11.Cu")
		(net "P5E_CPU0_G3_RX_DP<13>")
	)
	(segment
		(start 362.262166 -234.270804)
		(end 362.259626 -234.272074)
		(width 0.1143)
		(layer "In11.Cu")
		(net "P5E_CPU0_G3_RX_DP<13>")
	)
	(segment
		(start 394.12799 -17.696434)
		(end 394.226034 -17.935702)
		(width 0.14224)
		(layer "In11.Cu")
		(net "P5E_CPU0_G3_RX_DP<13>")
	)
	(segment
		(start 362.252514 -241.732054)
		(end 362.253784 -241.732816)
		(width 0.1143)
		(layer "In11.Cu")
		(net "P5E_CPU0_G3_RX_DP<13>")
	)
	(segment
		(start 362.250228 -243.350542)
		(end 362.252514 -243.352066)
		(width 0.1143)
		(layer "In11.Cu")
		(net "P5E_CPU0_G3_RX_DP<13>")
	)
	(segment
		(start 362.283502 -232.638346)
		(end 362.262166 -232.650792)
		(width 0.1143)
		(layer "In11.Cu")
		(net "P5E_CPU0_G3_RX_DP<13>")
	)
	(segment
		(start 362.4326 -243.604288)
		(end 362.36275 -243.674138)
		(width 0.1143)
		(layer "In11.Cu")
		(net "P5E_CPU0_G3_RX_DP<13>")
	)
	(segment
		(start 362.253784 -238.492792)
		(end 362.283502 -238.50981)
		(width 0.1143)
		(layer "In11.Cu")
		(net "P5E_CPU0_G3_RX_DP<13>")
	)
	(arc
		(start 362.199174 -233.598974)
		(mid 362.207252 -233.60476)
		(end 362.21543 -233.610404)
		(width 0.1143)
		(layer "In11.Cu")
		(net "P5E_CPU0_G3_RX_DP<13>")
	)
	(arc
		(start 363.223556 -223.93021)
		(mid 363.334061 -224.063676)
		(end 363.379258 -224.230946)
		(width 0.1143)
		(layer "In11.Cu")
		(net "P5E_CPU0_G3_RX_DP<13>")
	)
	(arc
		(start 362.09732 -229.54615)
		(mid 362.00445 -229.722251)
		(end 361.971082 -229.918514)
		(width 0.1143)
		(layer "In11.Cu")
		(net "P5E_CPU0_G3_RX_DP<13>")
	)
	(arc
		(start 362.927392 -221.94647)
		(mid 363.011073 -222.127887)
		(end 363.15269 -222.268796)
		(width 0.1143)
		(layer "In11.Cu")
		(net "P5E_CPU0_G3_RX_DP<13>")
	)
	(arc
		(start 362.283502 -238.50981)
		(mid 362.43943 -238.814102)
		(end 362.283502 -239.118394)
		(width 0.1143)
		(layer "In11.Cu")
		(net "P5E_CPU0_G3_RX_DP<13>")
	)
	(arc
		(start 363.379512 -224.234248)
		(mid 363.330351 -224.418964)
		(end 363.19587 -224.554796)
		(width 0.1143)
		(layer "In11.Cu")
		(net "P5E_CPU0_G3_RX_DP<13>")
	)
	(arc
		(start 362.283502 -232.029762)
		(mid 362.43943 -232.334054)
		(end 362.283502 -232.638346)
		(width 0.1143)
		(layer "In11.Cu")
		(net "P5E_CPU0_G3_RX_DP<13>")
	)
	(arc
		(start 361.971082 -229.918514)
		(mid 362.046813 -230.163947)
		(end 362.206286 -230.3653)
		(width 0.1143)
		(layer "In11.Cu")
		(net "P5E_CPU0_G3_RX_DP<13>")
	)
	(arc
		(start 362.909612 -225.044254)
		(mid 362.868214 -225.215128)
		(end 362.753402 -225.348292)
		(width 0.1143)
		(layer "In11.Cu")
		(net "P5E_CPU0_G3_RX_DP<13>")
	)
	(arc
		(start 362.283502 -228.789992)
		(mid 362.398178 -228.923326)
		(end 362.439458 -229.094284)
		(width 0.1143)
		(layer "In11.Cu")
		(net "P5E_CPU0_G3_RX_DP<13>")
	)
	(arc
		(start 363.143292 -224.586292)
		(mid 362.971427 -224.786056)
		(end 362.909612 -225.042222)
		(width 0.1143)
		(layer "In11.Cu")
		(net "P5E_CPU0_G3_RX_DP<13>")
	)
	(arc
		(start 362.25099 -226.177348)
		(mid 361.970656 -226.664266)
		(end 362.25099 -227.151184)
		(width 0.1143)
		(layer "In11.Cu")
		(net "P5E_CPU0_G3_RX_DP<13>")
	)
	(arc
		(start 362.21543 -234.297728)
		(mid 362.207252 -234.303371)
		(end 362.199174 -234.309158)
		(width 0.1143)
		(layer "In11.Cu")
		(net "P5E_CPU0_G3_RX_DP<13>")
	)
	(arc
		(start 362.909358 -221.80423)
		(mid 362.913859 -221.875922)
		(end 362.927392 -221.94647)
		(width 0.1143)
		(layer "In11.Cu")
		(net "P5E_CPU0_G3_RX_DP<13>")
	)
	(arc
		(start 362.201206 -240.080546)
		(mid 362.20828 -240.085553)
		(end 362.21543 -240.090452)
		(width 0.1143)
		(layer "In11.Cu")
		(net "P5E_CPU0_G3_RX_DP<13>")
	)
	(arc
		(start 362.283502 -243.369846)
		(mid 362.380637 -243.472715)
		(end 362.4326 -243.604288)
		(width 0.1143)
		(layer "In11.Cu")
		(net "P5E_CPU0_G3_RX_DP<13>")
	)
	(arc
		(start 362.439458 -225.85426)
		(mid 362.398203 -226.025231)
		(end 362.283502 -226.158552)
		(width 0.1143)
		(layer "In11.Cu")
		(net "P5E_CPU0_G3_RX_DP<13>")
	)
	(arc
		(start 362.199174 -232.689146)
		(mid 361.97629 -233.14406)
		(end 362.199174 -233.598974)
		(width 0.1143)
		(layer "In11.Cu")
		(net "P5E_CPU0_G3_RX_DP<13>")
	)
	(arc
		(start 362.283502 -240.129822)
		(mid 362.43943 -240.434114)
		(end 362.283502 -240.738406)
		(width 0.1143)
		(layer "In11.Cu")
		(net "P5E_CPU0_G3_RX_DP<13>")
	)
	(arc
		(start 362.68279 -225.389694)
		(mid 362.503977 -225.592044)
		(end 362.439458 -225.85426)
		(width 0.1143)
		(layer "In11.Cu")
		(net "P5E_CPU0_G3_RX_DP<13>")
	)
	(arc
		(start 362.21543 -232.677716)
		(mid 362.207252 -232.683359)
		(end 362.199174 -232.689146)
		(width 0.1143)
		(layer "In11.Cu")
		(net "P5E_CPU0_G3_RX_DP<13>")
	)
	(arc
		(start 362.201206 -237.547658)
		(mid 361.973823 -238.004096)
		(end 362.201206 -238.460534)
		(width 0.1143)
		(layer "In11.Cu")
		(net "P5E_CPU0_G3_RX_DP<13>")
	)
	(arc
		(start 362.21543 -237.537752)
		(mid 362.208281 -237.542652)
		(end 362.201206 -237.547658)
		(width 0.1143)
		(layer "In11.Cu")
		(net "P5E_CPU0_G3_RX_DP<13>")
	)
	(arc
		(start 362.201206 -239.16767)
		(mid 361.973823 -239.624108)
		(end 362.201206 -240.080546)
		(width 0.1143)
		(layer "In11.Cu")
		(net "P5E_CPU0_G3_RX_DP<13>")
	)
	(arc
		(start 362.199174 -231.978962)
		(mid 362.207252 -231.984748)
		(end 362.21543 -231.990392)
		(width 0.1143)
		(layer "In11.Cu")
		(net "P5E_CPU0_G3_RX_DP<13>")
	)
	(arc
		(start 362.439458 -229.094284)
		(mid 362.398696 -229.264168)
		(end 362.28528 -229.397052)
		(width 0.1143)
		(layer "In11.Cu")
		(net "P5E_CPU0_G3_RX_DP<13>")
	)
	(arc
		(start 362.283502 -227.16998)
		(mid 362.43943 -227.474272)
		(end 362.283502 -227.778564)
		(width 0.1143)
		(layer "In11.Cu")
		(net "P5E_CPU0_G3_RX_DP<13>")
	)
	(arc
		(start 362.187236 -240.797588)
		(mid 361.958216 -241.24412)
		(end 362.187236 -241.690652)
		(width 0.1143)
		(layer "In11.Cu")
		(net "P5E_CPU0_G3_RX_DP<13>")
	)
	(arc
		(start 362.199174 -235.218986)
		(mid 362.207252 -235.224772)
		(end 362.21543 -235.230416)
		(width 0.1143)
		(layer "In11.Cu")
		(net "P5E_CPU0_G3_RX_DP<13>")
	)
	(arc
		(start 362.909104 -223.424242)
		(mid 362.973397 -223.685847)
		(end 363.15142 -223.888046)
		(width 0.1143)
		(layer "In11.Cu")
		(net "P5E_CPU0_G3_RX_DP<13>")
	)
	(arc
		(start 362.283502 -233.649774)
		(mid 362.43943 -233.954066)
		(end 362.283502 -234.258358)
		(width 0.1143)
		(layer "In11.Cu")
		(net "P5E_CPU0_G3_RX_DP<13>")
	)
	(arc
		(start 362.18495 -235.93933)
		(mid 361.95695 -236.384084)
		(end 362.18495 -236.828838)
		(width 0.1143)
		(layer "In11.Cu")
		(net "P5E_CPU0_G3_RX_DP<13>")
	)
	(arc
		(start 362.283502 -235.269786)
		(mid 362.43943 -235.574078)
		(end 362.283502 -235.87837)
		(width 0.1143)
		(layer "In11.Cu")
		(net "P5E_CPU0_G3_RX_DP<13>")
	)
	(arc
		(start 363.15142 -222.960438)
		(mid 362.973355 -223.162615)
		(end 362.909104 -223.424242)
		(width 0.1143)
		(layer "In11.Cu")
		(net "P5E_CPU0_G3_RX_DP<13>")
	)
	(arc
		(start 362.251244 -227.796852)
		(mid 361.970597 -228.284278)
		(end 362.251244 -228.771704)
		(width 0.1143)
		(layer "In11.Cu")
		(net "P5E_CPU0_G3_RX_DP<13>")
	)
	(arc
		(start 362.18495 -242.419378)
		(mid 361.95695 -242.864132)
		(end 362.18495 -243.308886)
		(width 0.1143)
		(layer "In11.Cu")
		(net "P5E_CPU0_G3_RX_DP<13>")
	)
	(arc
		(start 362.283502 -236.889798)
		(mid 362.43943 -237.19409)
		(end 362.283502 -237.498382)
		(width 0.1143)
		(layer "In11.Cu")
		(net "P5E_CPU0_G3_RX_DP<13>")
	)
	(arc
		(start 363.226604 -222.31223)
		(mid 363.381416 -222.614236)
		(end 363.226604 -222.916242)
		(width 0.1143)
		(layer "In11.Cu")
		(net "P5E_CPU0_G3_RX_DP<13>")
	)
	(arc
		(start 362.21543 -239.157764)
		(mid 362.208281 -239.162664)
		(end 362.201206 -239.16767)
		(width 0.1143)
		(layer "In11.Cu")
		(net "P5E_CPU0_G3_RX_DP<13>")
	)
	(arc
		(start 362.222796 -229.433882)
		(mid 362.154485 -229.483645)
		(end 362.09732 -229.545896)
		(width 0.1143)
		(layer "In11.Cu")
		(net "P5E_CPU0_G3_RX_DP<13>")
	)
	(arc
		(start 363.15142 -223.8883)
		(mid 363.152435 -223.888936)
		(end 363.153452 -223.88957)
		(width 0.1143)
		(layer "In11.Cu")
		(net "P5E_CPU0_G3_RX_DP<13>")
	)
	(arc
		(start 362.21543 -231.057704)
		(mid 362.034778 -231.260449)
		(end 361.969558 -231.524048)
		(width 0.1143)
		(layer "In11.Cu")
		(net "P5E_CPU0_G3_RX_DP<13>")
	)
	(arc
		(start 361.969558 -231.524048)
		(mid 361.969548 -231.52735)
		(end 361.969558 -231.530652)
		(width 0.1143)
		(layer "In11.Cu")
		(net "P5E_CPU0_G3_RX_DP<13>")
	)
	(arc
		(start 362.199174 -234.309158)
		(mid 361.97629 -234.764072)
		(end 362.199174 -235.218986)
		(width 0.1143)
		(layer "In11.Cu")
		(net "P5E_CPU0_G3_RX_DP<13>")
	)
	(arc
		(start 361.969558 -231.530652)
		(mid 362.03443 -231.780394)
		(end 362.199174 -231.978962)
		(width 0.1143)
		(layer "In11.Cu")
		(net "P5E_CPU0_G3_RX_DP<13>")
	)
	(arc
		(start 362.283502 -241.749834)
		(mid 362.43943 -242.054126)
		(end 362.283502 -242.358418)
		(width 0.1143)
		(layer "In11.Cu")
		(net "P5E_CPU0_G3_RX_DP<13>")
	)
	(arc
		(start 362.201206 -238.460534)
		(mid 362.20828 -238.465541)
		(end 362.21543 -238.47044)
		(width 0.1143)
		(layer "In11.Cu")
		(net "P5E_CPU0_G3_RX_DP<13>")
	)
	(arc
		(start 362.281724 -230.408988)
		(mid 362.439428 -230.712008)
		(end 362.285534 -231.017064)
		(width 0.1143)
		(layer "In11.Cu")
		(net "P5E_CPU0_G3_RX_DP<13>")
	)
	(segment
		(start 399.046954 -7.709154)
		(end 399.046954 -8.320024)
		(width 0.12954)
		(layer "F.Cu")
		(net "P5E_CPU0_G3_RX_DP<12>")
	)
	(segment
		(start 398.920208 -4.963414)
		(end 399.185638 -5.228844)
		(width 0.12954)
		(layer "F.Cu")
		(net "P5E_CPU0_G3_RX_DP<12>")
	)
	(segment
		(start 399.185638 -5.228844)
		(end 399.185638 -7.57047)
		(width 0.12954)
		(layer "F.Cu")
		(net "P5E_CPU0_G3_RX_DP<12>")
	)
	(segment
		(start 361.597956 -245.560088)
		(end 362.064808 -245.29415)
		(width 0.12954)
		(layer "F.Cu")
		(net "P5E_CPU0_G3_RX_DP<12>")
	)
	(segment
		(start 399.185638 -7.57047)
		(end 399.046954 -7.709154)
		(width 0.12954)
		(layer "F.Cu")
		(net "P5E_CPU0_G3_RX_DP<12>")
	)
	(segment
		(start 363.192568 -243.99621)
		(end 363.191806 -243.996718)
		(width 0.1143)
		(layer "In11.Cu")
		(net "P5E_CPU0_G3_RX_DP<12>")
	)
	(segment
		(start 363.19079 -234.277154)
		(end 363.18952 -234.277916)
		(width 0.1143)
		(layer "In11.Cu")
		(net "P5E_CPU0_G3_RX_DP<12>")
	)
	(segment
		(start 363.15269 -228.748844)
		(end 363.185202 -228.767894)
		(width 0.1143)
		(layer "In11.Cu")
		(net "P5E_CPU0_G3_RX_DP<12>")
	)
	(segment
		(start 320.688208 -176.348644)
		(end 321.696588 -177.022506)
		(width 0.14224)
		(layer "In11.Cu")
		(net "P5E_CPU0_G3_RX_DP<12>")
	)
	(segment
		(start 363.195362 -232.654602)
		(end 363.192568 -232.656126)
		(width 0.1143)
		(layer "In11.Cu")
		(net "P5E_CPU0_G3_RX_DP<12>")
	)
	(segment
		(start 363.189266 -233.629962)
		(end 363.19079 -233.630978)
		(width 0.1143)
		(layer "In11.Cu")
		(net "P5E_CPU0_G3_RX_DP<12>")
	)
	(segment
		(start 397.623538 -17.815052)
		(end 397.401542 -18.229834)
		(width 0.14224)
		(layer "In11.Cu")
		(net "P5E_CPU0_G3_RX_DP<12>")
	)
	(segment
		(start 363.198156 -240.753138)
		(end 363.196124 -240.754154)
		(width 0.1143)
		(layer "In11.Cu")
		(net "P5E_CPU0_G3_RX_DP<12>")
	)
	(segment
		(start 311.078626 -168.769284)
		(end 311.100216 -168.821354)
		(width 0.14224)
		(layer "In11.Cu")
		(net "P5E_CPU0_G3_RX_DP<12>")
	)
	(segment
		(start 363.192568 -242.376198)
		(end 363.191806 -242.376706)
		(width 0.1143)
		(layer "In11.Cu")
		(net "P5E_CPU0_G3_RX_DP<12>")
	)
	(segment
		(start 363.18952 -240.757964)
		(end 363.187234 -240.759488)
		(width 0.1143)
		(layer "In11.Cu")
		(net "P5E_CPU0_G3_RX_DP<12>")
	)
	(segment
		(start 363.859064 -221.128844)
		(end 363.859064 -221.308676)
		(width 0.1143)
		(layer "In11.Cu")
		(net "P5E_CPU0_G3_RX_DP<12>")
	)
	(segment
		(start 363.198156 -239.133126)
		(end 363.196124 -239.134142)
		(width 0.1143)
		(layer "In11.Cu")
		(net "P5E_CPU0_G3_RX_DP<12>")
	)
	(segment
		(start 363.187234 -240.759488)
		(end 363.15269 -240.779554)
		(width 0.1143)
		(layer "In11.Cu")
		(net "P5E_CPU0_G3_RX_DP<12>")
	)
	(segment
		(start 363.849666 -221.318074)
		(end 363.849666 -221.80423)
		(width 0.1143)
		(layer "In11.Cu")
		(net "P5E_CPU0_G3_RX_DP<12>")
	)
	(segment
		(start 363.18952 -239.137952)
		(end 363.187234 -239.139476)
		(width 0.1143)
		(layer "In11.Cu")
		(net "P5E_CPU0_G3_RX_DP<12>")
	)
	(segment
		(start 363.223556 -237.498382)
		(end 363.198156 -237.513114)
		(width 0.1143)
		(layer "In11.Cu")
		(net "P5E_CPU0_G3_RX_DP<12>")
	)
	(segment
		(start 363.69244 -225.349054)
		(end 363.622844 -225.389694)
		(width 0.1143)
		(layer "In11.Cu")
		(net "P5E_CPU0_G3_RX_DP<12>")
	)
	(segment
		(start 363.195362 -243.994686)
		(end 363.192568 -243.99621)
		(width 0.1143)
		(layer "In11.Cu")
		(net "P5E_CPU0_G3_RX_DP<12>")
	)
	(segment
		(start 363.192568 -240.756186)
		(end 363.191806 -240.756694)
		(width 0.1143)
		(layer "In11.Cu")
		(net "P5E_CPU0_G3_RX_DP<12>")
	)
	(segment
		(start 363.191806 -243.351558)
		(end 363.192568 -243.352066)
		(width 0.1143)
		(layer "In11.Cu")
		(net "P5E_CPU0_G3_RX_DP<12>")
	)
	(segment
		(start 363.15269 -243.328698)
		(end 363.189266 -243.350034)
		(width 0.1143)
		(layer "In11.Cu")
		(net "P5E_CPU0_G3_RX_DP<12>")
	)
	(segment
		(start 364.131606 -223.911668)
		(end 364.163356 -223.929956)
		(width 0.1143)
		(layer "In11.Cu")
		(net "P5E_CPU0_G3_RX_DP<12>")
	)
	(segment
		(start 363.196124 -237.51413)
		(end 363.195362 -237.514638)
		(width 0.1143)
		(layer "In11.Cu")
		(net "P5E_CPU0_G3_RX_DP<12>")
	)
	(segment
		(start 363.198156 -232.653078)
		(end 363.196124 -232.654094)
		(width 0.1143)
		(layer "In11.Cu")
		(net "P5E_CPU0_G3_RX_DP<12>")
	)
	(segment
		(start 363.189266 -226.178364)
		(end 363.186472 -226.179888)
		(width 0.1143)
		(layer "In11.Cu")
		(net "P5E_CPU0_G3_RX_DP<12>")
	)
	(segment
		(start 363.198156 -242.37315)
		(end 363.196124 -242.374166)
		(width 0.1143)
		(layer "In11.Cu")
		(net "P5E_CPU0_G3_RX_DP<12>")
	)
	(segment
		(start 363.191806 -228.771704)
		(end 363.223556 -228.789992)
		(width 0.1143)
		(layer "In11.Cu")
		(net "P5E_CPU0_G3_RX_DP<12>")
	)
	(segment
		(start 363.192568 -237.516162)
		(end 363.191806 -237.51667)
		(width 0.1143)
		(layer "In11.Cu")
		(net "P5E_CPU0_G3_RX_DP<12>")
	)
	(segment
		(start 362.752386 -244.788944)
		(end 362.68279 -244.829584)
		(width 0.1143)
		(layer "In11.Cu")
		(net "P5E_CPU0_G3_RX_DP<12>")
	)
	(segment
		(start 363.15269 -235.228638)
		(end 363.189266 -235.249974)
		(width 0.1143)
		(layer "In11.Cu")
		(net "P5E_CPU0_G3_RX_DP<12>")
	)
	(segment
		(start 362.36275 -245.29415)
		(end 362.064808 -245.29415)
		(width 0.1143)
		(layer "In11.Cu")
		(net "P5E_CPU0_G3_RX_DP<12>")
	)
	(segment
		(start 363.187234 -234.27944)
		(end 363.15269 -234.299506)
		(width 0.1143)
		(layer "In11.Cu")
		(net "P5E_CPU0_G3_RX_DP<12>")
	)
	(segment
		(start 363.18952 -242.377976)
		(end 363.187234 -242.3795)
		(width 0.1143)
		(layer "In11.Cu")
		(net "P5E_CPU0_G3_RX_DP<12>")
	)
	(segment
		(start 363.19079 -232.010966)
		(end 363.191806 -232.011474)
		(width 0.1143)
		(layer "In11.Cu")
		(net "P5E_CPU0_G3_RX_DP<12>")
	)
	(segment
		(start 359.353866 -207.886808)
		(end 363.813344 -215.39708)
		(width 0.14224)
		(layer "In11.Cu")
		(net "P5E_CPU0_G3_RX_DP<12>")
	)
	(segment
		(start 363.187234 -227.799646)
		(end 363.15269 -227.819712)
		(width 0.1143)
		(layer "In11.Cu")
		(net "P5E_CPU0_G3_RX_DP<12>")
	)
	(segment
		(start 363.19841 -226.17303)
		(end 363.197648 -226.173538)
		(width 0.1143)
		(layer "In11.Cu")
		(net "P5E_CPU0_G3_RX_DP<12>")
	)
	(segment
		(start 363.187234 -232.659428)
		(end 363.15269 -232.679494)
		(width 0.1143)
		(layer "In11.Cu")
		(net "P5E_CPU0_G3_RX_DP<12>")
	)
	(segment
		(start 363.195362 -234.274614)
		(end 363.192568 -234.276138)
		(width 0.1143)
		(layer "In11.Cu")
		(net "P5E_CPU0_G3_RX_DP<12>")
	)
	(segment
		(start 363.186472 -226.179888)
		(end 363.15269 -226.1997)
		(width 0.1143)
		(layer "In11.Cu")
		(net "P5E_CPU0_G3_RX_DP<12>")
	)
	(segment
		(start 363.18952 -227.798122)
		(end 363.187234 -227.799646)
		(width 0.1143)
		(layer "In11.Cu")
		(net "P5E_CPU0_G3_RX_DP<12>")
	)
	(segment
		(start 363.19968 -226.172268)
		(end 363.19841 -226.17303)
		(width 0.1143)
		(layer "In11.Cu")
		(net "P5E_CPU0_G3_RX_DP<12>")
	)
	(segment
		(start 363.189266 -238.489998)
		(end 363.19079 -238.491014)
		(width 0.1143)
		(layer "In11.Cu")
		(net "P5E_CPU0_G3_RX_DP<12>")
	)
	(segment
		(start 363.195362 -235.894626)
		(end 363.192568 -235.89615)
		(width 0.1143)
		(layer "In11.Cu")
		(net "P5E_CPU0_G3_RX_DP<12>")
	)
	(segment
		(start 363.18952 -243.997988)
		(end 363.187234 -243.999512)
		(width 0.1143)
		(layer "In11.Cu")
		(net "P5E_CPU0_G3_RX_DP<12>")
	)
	(segment
		(start 308.560216 -160.861248)
		(end 308.560216 -162.688016)
		(width 0.14224)
		(layer "In11.Cu")
		(net "P5E_CPU0_G3_RX_DP<12>")
	)
	(segment
		(start 363.223556 -242.358418)
		(end 363.198156 -242.37315)
		(width 0.1143)
		(layer "In11.Cu")
		(net "P5E_CPU0_G3_RX_DP<12>")
	)
	(segment
		(start 363.19079 -235.897166)
		(end 363.18952 -235.897928)
		(width 0.1143)
		(layer "In11.Cu")
		(net "P5E_CPU0_G3_RX_DP<12>")
	)
	(segment
		(start 317.507366 -129.300478)
		(end 310.906414 -147.50923)
		(width 0.14224)
		(layer "In11.Cu")
		(net "P5E_CPU0_G3_RX_DP<12>")
	)
	(segment
		(start 363.813344 -221.054676)
		(end 363.813344 -221.083124)
		(width 0.1143)
		(layer "In11.Cu")
		(net "P5E_CPU0_G3_RX_DP<12>")
	)
	(segment
		(start 363.196124 -243.994178)
		(end 363.195362 -243.994686)
		(width 0.1143)
		(layer "In11.Cu")
		(net "P5E_CPU0_G3_RX_DP<12>")
	)
	(segment
		(start 363.19079 -240.111026)
		(end 363.191806 -240.111534)
		(width 0.1143)
		(layer "In11.Cu")
		(net "P5E_CPU0_G3_RX_DP<12>")
	)
	(segment
		(start 315.541152 -173.263306)
		(end 320.688208 -176.348644)
		(width 0.14224)
		(layer "In11.Cu")
		(net "P5E_CPU0_G3_RX_DP<12>")
	)
	(segment
		(start 363.223556 -235.87837)
		(end 363.198156 -235.893102)
		(width 0.1143)
		(layer "In11.Cu")
		(net "P5E_CPU0_G3_RX_DP<12>")
	)
	(segment
		(start 363.189266 -228.77018)
		(end 363.19079 -228.771196)
		(width 0.1143)
		(layer "In11.Cu")
		(net "P5E_CPU0_G3_RX_DP<12>")
	)
	(segment
		(start 363.191806 -243.996718)
		(end 363.19079 -243.997226)
		(width 0.1143)
		(layer "In11.Cu")
		(net "P5E_CPU0_G3_RX_DP<12>")
	)
	(segment
		(start 364.13059 -223.91116)
		(end 364.131606 -223.911668)
		(width 0.1143)
		(layer "In11.Cu")
		(net "P5E_CPU0_G3_RX_DP<12>")
	)
	(segment
		(start 363.192568 -243.352066)
		(end 363.223556 -243.369846)
		(width 0.1143)
		(layer "In11.Cu")
		(net "P5E_CPU0_G3_RX_DP<12>")
	)
	(segment
		(start 363.189266 -243.350034)
		(end 363.19079 -243.35105)
		(width 0.1143)
		(layer "In11.Cu")
		(net "P5E_CPU0_G3_RX_DP<12>")
	)
	(segment
		(start 363.15269 -238.468662)
		(end 363.189266 -238.489998)
		(width 0.1143)
		(layer "In11.Cu")
		(net "P5E_CPU0_G3_RX_DP<12>")
	)
	(segment
		(start 363.223556 -226.158552)
		(end 363.20222 -226.170998)
		(width 0.1143)
		(layer "In11.Cu")
		(net "P5E_CPU0_G3_RX_DP<12>")
	)
	(segment
		(start 363.191806 -240.756694)
		(end 363.19079 -240.757202)
		(width 0.1143)
		(layer "In11.Cu")
		(net "P5E_CPU0_G3_RX_DP<12>")
	)
	(segment
		(start 363.813344 -221.083124)
		(end 363.859064 -221.128844)
		(width 0.1143)
		(layer "In11.Cu")
		(net "P5E_CPU0_G3_RX_DP<12>")
	)
	(segment
		(start 364.16361 -222.918528)
		(end 364.16361 -222.918274)
		(width 0.1143)
		(layer "In11.Cu")
		(net "P5E_CPU0_G3_RX_DP<12>")
	)
	(segment
		(start 363.19079 -227.79736)
		(end 363.18952 -227.798122)
		(width 0.1143)
		(layer "In11.Cu")
		(net "P5E_CPU0_G3_RX_DP<12>")
	)
	(segment
		(start 363.223556 -240.738406)
		(end 363.198156 -240.753138)
		(width 0.1143)
		(layer "In11.Cu")
		(net "P5E_CPU0_G3_RX_DP<12>")
	)
	(segment
		(start 363.191806 -240.111534)
		(end 363.192568 -240.112042)
		(width 0.1143)
		(layer "In11.Cu")
		(net "P5E_CPU0_G3_RX_DP<12>")
	)
	(segment
		(start 363.196124 -239.134142)
		(end 363.195362 -239.13465)
		(width 0.1143)
		(layer "In11.Cu")
		(net "P5E_CPU0_G3_RX_DP<12>")
	)
	(segment
		(start 363.191806 -239.136682)
		(end 363.19079 -239.13719)
		(width 0.1143)
		(layer "In11.Cu")
		(net "P5E_CPU0_G3_RX_DP<12>")
	)
	(segment
		(start 363.19079 -243.35105)
		(end 363.191806 -243.351558)
		(width 0.1143)
		(layer "In11.Cu")
		(net "P5E_CPU0_G3_RX_DP<12>")
	)
	(segment
		(start 363.19079 -240.757202)
		(end 363.18952 -240.757964)
		(width 0.1143)
		(layer "In11.Cu")
		(net "P5E_CPU0_G3_RX_DP<12>")
	)
	(segment
		(start 363.189266 -235.249974)
		(end 363.19079 -235.25099)
		(width 0.1143)
		(layer "In11.Cu")
		(net "P5E_CPU0_G3_RX_DP<12>")
	)
	(segment
		(start 321.696588 -177.022506)
		(end 359.353866 -207.886808)
		(width 0.14224)
		(layer "In11.Cu")
		(net "P5E_CPU0_G3_RX_DP<12>")
	)
	(segment
		(start 363.192568 -238.49203)
		(end 363.223556 -238.50981)
		(width 0.1143)
		(layer "In11.Cu")
		(net "P5E_CPU0_G3_RX_DP<12>")
	)
	(segment
		(start 363.192568 -235.89615)
		(end 363.191806 -235.896658)
		(width 0.1143)
		(layer "In11.Cu")
		(net "P5E_CPU0_G3_RX_DP<12>")
	)
	(segment
		(start 363.223556 -239.118394)
		(end 363.198156 -239.133126)
		(width 0.1143)
		(layer "In11.Cu")
		(net "P5E_CPU0_G3_RX_DP<12>")
	)
	(segment
		(start 364.128304 -223.909636)
		(end 364.13059 -223.91116)
		(width 0.1143)
		(layer "In11.Cu")
		(net "P5E_CPU0_G3_RX_DP<12>")
	)
	(segment
		(start 363.196124 -235.894118)
		(end 363.195362 -235.894626)
		(width 0.1143)
		(layer "In11.Cu")
		(net "P5E_CPU0_G3_RX_DP<12>")
	)
	(segment
		(start 308.560216 -162.688016)
		(end 311.078626 -168.76903)
		(width 0.14224)
		(layer "In11.Cu")
		(net "P5E_CPU0_G3_RX_DP<12>")
	)
	(segment
		(start 363.192568 -234.276138)
		(end 363.191806 -234.276646)
		(width 0.1143)
		(layer "In11.Cu")
		(net "P5E_CPU0_G3_RX_DP<12>")
	)
	(segment
		(start 363.192568 -227.1522)
		(end 363.223556 -227.16998)
		(width 0.1143)
		(layer "In11.Cu")
		(net "P5E_CPU0_G3_RX_DP<12>")
	)
	(segment
		(start 371.758972 -56.110632)
		(end 320.801492 -123.565666)
		(width 0.14224)
		(layer "In11.Cu")
		(net "P5E_CPU0_G3_RX_DP<12>")
	)
	(segment
		(start 363.198156 -235.893102)
		(end 363.196124 -235.894118)
		(width 0.1143)
		(layer "In11.Cu")
		(net "P5E_CPU0_G3_RX_DP<12>")
	)
	(segment
		(start 363.191806 -233.631486)
		(end 363.192568 -233.631994)
		(width 0.1143)
		(layer "In11.Cu")
		(net "P5E_CPU0_G3_RX_DP<12>")
	)
	(segment
		(start 363.153198 -229.439216)
		(end 363.15269 -229.43947)
		(width 0.1143)
		(layer "In11.Cu")
		(net "P5E_CPU0_G3_RX_DP<12>")
	)
	(segment
		(start 363.186726 -228.768656)
		(end 363.18825 -228.769672)
		(width 0.1143)
		(layer "In11.Cu")
		(net "P5E_CPU0_G3_RX_DP<12>")
	)
	(segment
		(start 363.15269 -227.128832)
		(end 363.155484 -227.130864)
		(width 0.1143)
		(layer "In11.Cu")
		(net "P5E_CPU0_G3_RX_DP<12>")
	)
	(segment
		(start 363.196124 -226.1743)
		(end 363.195362 -226.174808)
		(width 0.1143)
		(layer "In11.Cu")
		(net "P5E_CPU0_G3_RX_DP<12>")
	)
	(segment
		(start 363.155484 -227.130864)
		(end 363.191806 -227.151692)
		(width 0.1143)
		(layer "In11.Cu")
		(net "P5E_CPU0_G3_RX_DP<12>")
	)
	(segment
		(start 397.401542 -18.229834)
		(end 371.758972 -56.110632)
		(width 0.14224)
		(layer "In11.Cu")
		(net "P5E_CPU0_G3_RX_DP<12>")
	)
	(segment
		(start 363.192568 -240.112042)
		(end 363.223556 -240.129822)
		(width 0.1143)
		(layer "In11.Cu")
		(net "P5E_CPU0_G3_RX_DP<12>")
	)
	(segment
		(start 363.225334 -229.397052)
		(end 363.191806 -229.41661)
		(width 0.1143)
		(layer "In11.Cu")
		(net "P5E_CPU0_G3_RX_DP<12>")
	)
	(segment
		(start 363.19079 -241.731038)
		(end 363.191806 -241.731546)
		(width 0.1143)
		(layer "In11.Cu")
		(net "P5E_CPU0_G3_RX_DP<12>")
	)
	(segment
		(start 398.153382 -16.5354)
		(end 397.623538 -17.815052)
		(width 0.14224)
		(layer "In11.Cu")
		(net "P5E_CPU0_G3_RX_DP<12>")
	)
	(segment
		(start 363.191806 -234.276646)
		(end 363.19079 -234.277154)
		(width 0.1143)
		(layer "In11.Cu")
		(net "P5E_CPU0_G3_RX_DP<12>")
	)
	(segment
		(start 363.191806 -237.51667)
		(end 363.19079 -237.517178)
		(width 0.1143)
		(layer "In11.Cu")
		(net "P5E_CPU0_G3_RX_DP<12>")
	)
	(segment
		(start 363.859064 -221.308676)
		(end 363.849666 -221.318074)
		(width 0.1143)
		(layer "In11.Cu")
		(net "P5E_CPU0_G3_RX_DP<12>")
	)
	(segment
		(start 363.15269 -241.708686)
		(end 363.189266 -241.730022)
		(width 0.1143)
		(layer "In11.Cu")
		(net "P5E_CPU0_G3_RX_DP<12>")
	)
	(segment
		(start 363.192568 -233.631994)
		(end 363.223556 -233.649774)
		(width 0.1143)
		(layer "In11.Cu")
		(net "P5E_CPU0_G3_RX_DP<12>")
	)
	(segment
		(start 363.19079 -239.13719)
		(end 363.18952 -239.137952)
		(width 0.1143)
		(layer "In11.Cu")
		(net "P5E_CPU0_G3_RX_DP<12>")
	)
	(segment
		(start 363.191806 -241.731546)
		(end 363.192568 -241.732054)
		(width 0.1143)
		(layer "In11.Cu")
		(net "P5E_CPU0_G3_RX_DP<12>")
	)
	(segment
		(start 364.091982 -222.95993)
		(end 364.064296 -222.979742)
		(width 0.1143)
		(layer "In11.Cu")
		(net "P5E_CPU0_G3_RX_DP<12>")
	)
	(segment
		(start 363.197648 -226.173538)
		(end 363.196124 -226.1743)
		(width 0.1143)
		(layer "In11.Cu")
		(net "P5E_CPU0_G3_RX_DP<12>")
	)
	(segment
		(start 399.211038 -5.254244)
		(end 399.211038 -11.219434)
		(width 0.14224)
		(layer "In11.Cu")
		(net "P5E_CPU0_G3_RX_DP<12>")
	)
	(segment
		(start 399.211038 -11.219434)
		(end 398.153382 -16.5354)
		(width 0.14224)
		(layer "In11.Cu")
		(net "P5E_CPU0_G3_RX_DP<12>")
	)
	(segment
		(start 363.192568 -232.656126)
		(end 363.191806 -232.656634)
		(width 0.1143)
		(layer "In11.Cu")
		(net "P5E_CPU0_G3_RX_DP<12>")
	)
	(segment
		(start 364.14075 -222.309436)
		(end 364.20425 -222.346012)
		(width 0.1143)
		(layer "In11.Cu")
		(net "P5E_CPU0_G3_RX_DP<12>")
	)
	(segment
		(start 363.20222 -226.170998)
		(end 363.19968 -226.172268)
		(width 0.1143)
		(layer "In11.Cu")
		(net "P5E_CPU0_G3_RX_DP<12>")
	)
	(segment
		(start 363.191806 -226.17684)
		(end 363.19079 -226.177348)
		(width 0.1143)
		(layer "In11.Cu")
		(net "P5E_CPU0_G3_RX_DP<12>")
	)
	(segment
		(start 363.192568 -235.252006)
		(end 363.223556 -235.269786)
		(width 0.1143)
		(layer "In11.Cu")
		(net "P5E_CPU0_G3_RX_DP<12>")
	)
	(segment
		(start 363.223556 -234.258358)
		(end 363.198156 -234.27309)
		(width 0.1143)
		(layer "In11.Cu")
		(net "P5E_CPU0_G3_RX_DP<12>")
	)
	(segment
		(start 363.813344 -215.39708)
		(end 363.813344 -221.054676)
		(width 0.14224)
		(layer "In11.Cu")
		(net "P5E_CPU0_G3_RX_DP<12>")
	)
	(segment
		(start 363.196124 -234.274106)
		(end 363.195362 -234.274614)
		(width 0.1143)
		(layer "In11.Cu")
		(net "P5E_CPU0_G3_RX_DP<12>")
	)
	(segment
		(start 311.100216 -168.821354)
		(end 315.541152 -173.263306)
		(width 0.14224)
		(layer "In11.Cu")
		(net "P5E_CPU0_G3_RX_DP<12>")
	)
	(segment
		(start 363.187234 -235.899452)
		(end 363.15269 -235.919518)
		(width 0.1143)
		(layer "In11.Cu")
		(net "P5E_CPU0_G3_RX_DP<12>")
	)
	(segment
		(start 363.15523 -230.37038)
		(end 363.191806 -230.391716)
		(width 0.1143)
		(layer "In11.Cu")
		(net "P5E_CPU0_G3_RX_DP<12>")
	)
	(segment
		(start 362.445554 -245.211346)
		(end 362.36275 -245.29415)
		(width 0.1143)
		(layer "In11.Cu")
		(net "P5E_CPU0_G3_RX_DP<12>")
	)
	(segment
		(start 363.196124 -240.754154)
		(end 363.195362 -240.754662)
		(width 0.1143)
		(layer "In11.Cu")
		(net "P5E_CPU0_G3_RX_DP<12>")
	)
	(segment
		(start 363.191806 -229.41661)
		(end 363.153198 -229.439216)
		(width 0.1143)
		(layer "In11.Cu")
		(net "P5E_CPU0_G3_RX_DP<12>")
	)
	(segment
		(start 363.187234 -239.139476)
		(end 363.15269 -239.159542)
		(width 0.1143)
		(layer "In11.Cu")
		(net "P5E_CPU0_G3_RX_DP<12>")
	)
	(segment
		(start 363.19079 -233.630978)
		(end 363.191806 -233.631486)
		(width 0.1143)
		(layer "In11.Cu")
		(net "P5E_CPU0_G3_RX_DP<12>")
	)
	(segment
		(start 363.15269 -231.988614)
		(end 363.189266 -232.00995)
		(width 0.1143)
		(layer "In11.Cu")
		(net "P5E_CPU0_G3_RX_DP<12>")
	)
	(segment
		(start 364.16107 -224.539556)
		(end 364.095284 -224.57791)
		(width 0.1143)
		(layer "In11.Cu")
		(net "P5E_CPU0_G3_RX_DP<12>")
	)
	(segment
		(start 363.15269 -233.608626)
		(end 363.189266 -233.629962)
		(width 0.1143)
		(layer "In11.Cu")
		(net "P5E_CPU0_G3_RX_DP<12>")
	)
	(segment
		(start 363.191806 -238.491522)
		(end 363.192568 -238.49203)
		(width 0.1143)
		(layer "In11.Cu")
		(net "P5E_CPU0_G3_RX_DP<12>")
	)
	(segment
		(start 363.191806 -227.796852)
		(end 363.19079 -227.79736)
		(width 0.1143)
		(layer "In11.Cu")
		(net "P5E_CPU0_G3_RX_DP<12>")
	)
	(segment
		(start 363.19079 -236.871002)
		(end 363.191806 -236.87151)
		(width 0.1143)
		(layer "In11.Cu")
		(net "P5E_CPU0_G3_RX_DP<12>")
	)
	(segment
		(start 363.195362 -237.514638)
		(end 363.192568 -237.516162)
		(width 0.1143)
		(layer "In11.Cu")
		(net "P5E_CPU0_G3_RX_DP<12>")
	)
	(segment
		(start 363.191806 -236.87151)
		(end 363.192568 -236.872018)
		(width 0.1143)
		(layer "In11.Cu")
		(net "P5E_CPU0_G3_RX_DP<12>")
	)
	(segment
		(start 311.078626 -168.76903)
		(end 311.078626 -168.769284)
		(width 0.14224)
		(layer "In11.Cu")
		(net "P5E_CPU0_G3_RX_DP<12>")
	)
	(segment
		(start 363.189266 -241.730022)
		(end 363.19079 -241.731038)
		(width 0.1143)
		(layer "In11.Cu")
		(net "P5E_CPU0_G3_RX_DP<12>")
	)
	(segment
		(start 363.192568 -236.872018)
		(end 363.223556 -236.889798)
		(width 0.1143)
		(layer "In11.Cu")
		(net "P5E_CPU0_G3_RX_DP<12>")
	)
	(segment
		(start 364.162848 -222.918782)
		(end 364.091982 -222.95993)
		(width 0.1143)
		(layer "In11.Cu")
		(net "P5E_CPU0_G3_RX_DP<12>")
	)
	(segment
		(start 363.195362 -226.174808)
		(end 363.192568 -226.176332)
		(width 0.1143)
		(layer "In11.Cu")
		(net "P5E_CPU0_G3_RX_DP<12>")
	)
	(segment
		(start 363.15269 -240.088674)
		(end 363.189266 -240.11001)
		(width 0.1143)
		(layer "In11.Cu")
		(net "P5E_CPU0_G3_RX_DP<12>")
	)
	(segment
		(start 363.191806 -235.896658)
		(end 363.19079 -235.897166)
		(width 0.1143)
		(layer "In11.Cu")
		(net "P5E_CPU0_G3_RX_DP<12>")
	)
	(segment
		(start 363.195362 -239.13465)
		(end 363.192568 -239.136174)
		(width 0.1143)
		(layer "In11.Cu")
		(net "P5E_CPU0_G3_RX_DP<12>")
	)
	(segment
		(start 363.198156 -237.513114)
		(end 363.196124 -237.51413)
		(width 0.1143)
		(layer "In11.Cu")
		(net "P5E_CPU0_G3_RX_DP<12>")
	)
	(segment
		(start 364.064296 -223.868742)
		(end 364.093506 -223.88957)
		(width 0.1143)
		(layer "In11.Cu")
		(net "P5E_CPU0_G3_RX_DP<12>")
	)
	(segment
		(start 363.223556 -227.778564)
		(end 363.191806 -227.796852)
		(width 0.1143)
		(layer "In11.Cu")
		(net "P5E_CPU0_G3_RX_DP<12>")
	)
	(segment
		(start 363.18952 -234.277916)
		(end 363.187234 -234.27944)
		(width 0.1143)
		(layer "In11.Cu")
		(net "P5E_CPU0_G3_RX_DP<12>")
	)
	(segment
		(start 363.192568 -226.176332)
		(end 363.191806 -226.17684)
		(width 0.1143)
		(layer "In11.Cu")
		(net "P5E_CPU0_G3_RX_DP<12>")
	)
	(segment
		(start 363.225334 -231.017064)
		(end 363.15269 -231.059482)
		(width 0.1143)
		(layer "In11.Cu")
		(net "P5E_CPU0_G3_RX_DP<12>")
	)
	(segment
		(start 363.195362 -242.374674)
		(end 363.192568 -242.376198)
		(width 0.1143)
		(layer "In11.Cu")
		(net "P5E_CPU0_G3_RX_DP<12>")
	)
	(segment
		(start 363.19079 -232.657142)
		(end 363.18952 -232.657904)
		(width 0.1143)
		(layer "In11.Cu")
		(net "P5E_CPU0_G3_RX_DP<12>")
	)
	(segment
		(start 363.198156 -243.993162)
		(end 363.196124 -243.994178)
		(width 0.1143)
		(layer "In11.Cu")
		(net "P5E_CPU0_G3_RX_DP<12>")
	)
	(segment
		(start 363.196124 -232.654094)
		(end 363.195362 -232.654602)
		(width 0.1143)
		(layer "In11.Cu")
		(net "P5E_CPU0_G3_RX_DP<12>")
	)
	(segment
		(start 363.19079 -243.997226)
		(end 363.18952 -243.997988)
		(width 0.1143)
		(layer "In11.Cu")
		(net "P5E_CPU0_G3_RX_DP<12>")
	)
	(segment
		(start 363.192568 -241.732054)
		(end 363.223556 -241.749834)
		(width 0.1143)
		(layer "In11.Cu")
		(net "P5E_CPU0_G3_RX_DP<12>")
	)
	(segment
		(start 363.223556 -243.97843)
		(end 363.198156 -243.993162)
		(width 0.1143)
		(layer "In11.Cu")
		(net "P5E_CPU0_G3_RX_DP<12>")
	)
	(segment
		(start 363.187234 -242.3795)
		(end 363.15269 -242.399566)
		(width 0.1143)
		(layer "In11.Cu")
		(net "P5E_CPU0_G3_RX_DP<12>")
	)
	(segment
		(start 398.920208 -4.963414)
		(end 399.211038 -5.254244)
		(width 0.14224)
		(layer "In11.Cu")
		(net "P5E_CPU0_G3_RX_DP<12>")
	)
	(segment
		(start 363.191806 -242.376706)
		(end 363.19079 -242.377214)
		(width 0.1143)
		(layer "In11.Cu")
		(net "P5E_CPU0_G3_RX_DP<12>")
	)
	(segment
		(start 363.189266 -240.11001)
		(end 363.19079 -240.111026)
		(width 0.1143)
		(layer "In11.Cu")
		(net "P5E_CPU0_G3_RX_DP<12>")
	)
	(segment
		(start 363.19079 -237.517178)
		(end 363.18952 -237.51794)
		(width 0.1143)
		(layer "In11.Cu")
		(net "P5E_CPU0_G3_RX_DP<12>")
	)
	(segment
		(start 364.093506 -223.88957)
		(end 364.128304 -223.909636)
		(width 0.1143)
		(layer "In11.Cu")
		(net "P5E_CPU0_G3_RX_DP<12>")
	)
	(segment
		(start 363.196124 -242.374166)
		(end 363.195362 -242.374674)
		(width 0.1143)
		(layer "In11.Cu")
		(net "P5E_CPU0_G3_RX_DP<12>")
	)
	(segment
		(start 363.195362 -240.754662)
		(end 363.192568 -240.756186)
		(width 0.1143)
		(layer "In11.Cu")
		(net "P5E_CPU0_G3_RX_DP<12>")
	)
	(segment
		(start 364.319058 -224.225866)
		(end 364.318296 -224.240852)
		(width 0.1143)
		(layer "In11.Cu")
		(net "P5E_CPU0_G3_RX_DP<12>")
	)
	(segment
		(start 363.189266 -236.869986)
		(end 363.19079 -236.871002)
		(width 0.1143)
		(layer "In11.Cu")
		(net "P5E_CPU0_G3_RX_DP<12>")
	)
	(segment
		(start 363.185202 -228.767894)
		(end 363.186726 -228.768656)
		(width 0.1143)
		(layer "In11.Cu")
		(net "P5E_CPU0_G3_RX_DP<12>")
	)
	(segment
		(start 363.191806 -235.251498)
		(end 363.192568 -235.252006)
		(width 0.1143)
		(layer "In11.Cu")
		(net "P5E_CPU0_G3_RX_DP<12>")
	)
	(segment
		(start 363.19079 -235.25099)
		(end 363.191806 -235.251498)
		(width 0.1143)
		(layer "In11.Cu")
		(net "P5E_CPU0_G3_RX_DP<12>")
	)
	(segment
		(start 363.189266 -232.00995)
		(end 363.19079 -232.010966)
		(width 0.1143)
		(layer "In11.Cu")
		(net "P5E_CPU0_G3_RX_DP<12>")
	)
	(segment
		(start 363.191806 -232.011474)
		(end 363.223556 -232.029762)
		(width 0.1143)
		(layer "In11.Cu")
		(net "P5E_CPU0_G3_RX_DP<12>")
	)
	(segment
		(start 363.19079 -228.771196)
		(end 363.191806 -228.771704)
		(width 0.1143)
		(layer "In11.Cu")
		(net "P5E_CPU0_G3_RX_DP<12>")
	)
	(segment
		(start 363.198156 -234.27309)
		(end 363.196124 -234.274106)
		(width 0.1143)
		(layer "In11.Cu")
		(net "P5E_CPU0_G3_RX_DP<12>")
	)
	(segment
		(start 363.187234 -237.519464)
		(end 363.15269 -237.53953)
		(width 0.1143)
		(layer "In11.Cu")
		(net "P5E_CPU0_G3_RX_DP<12>")
	)
	(segment
		(start 364.16361 -222.918274)
		(end 364.162848 -222.918782)
		(width 0.1143)
		(layer "In11.Cu")
		(net "P5E_CPU0_G3_RX_DP<12>")
	)
	(segment
		(start 363.191806 -227.151692)
		(end 363.192568 -227.1522)
		(width 0.1143)
		(layer "In11.Cu")
		(net "P5E_CPU0_G3_RX_DP<12>")
	)
	(segment
		(start 363.18952 -237.51794)
		(end 363.187234 -237.519464)
		(width 0.1143)
		(layer "In11.Cu")
		(net "P5E_CPU0_G3_RX_DP<12>")
	)
	(segment
		(start 310.906414 -147.50923)
		(end 308.560216 -160.861248)
		(width 0.14224)
		(layer "In11.Cu")
		(net "P5E_CPU0_G3_RX_DP<12>")
	)
	(segment
		(start 363.19079 -238.491014)
		(end 363.191806 -238.491522)
		(width 0.1143)
		(layer "In11.Cu")
		(net "P5E_CPU0_G3_RX_DP<12>")
	)
	(segment
		(start 363.18952 -232.657904)
		(end 363.187234 -232.659428)
		(width 0.1143)
		(layer "In11.Cu")
		(net "P5E_CPU0_G3_RX_DP<12>")
	)
	(segment
		(start 363.18825 -228.769672)
		(end 363.189266 -228.77018)
		(width 0.1143)
		(layer "In11.Cu")
		(net "P5E_CPU0_G3_RX_DP<12>")
	)
	(segment
		(start 363.187234 -243.999512)
		(end 363.15269 -244.019578)
		(width 0.1143)
		(layer "In11.Cu")
		(net "P5E_CPU0_G3_RX_DP<12>")
	)
	(segment
		(start 363.18952 -235.897928)
		(end 363.187234 -235.899452)
		(width 0.1143)
		(layer "In11.Cu")
		(net "P5E_CPU0_G3_RX_DP<12>")
	)
	(segment
		(start 363.19079 -226.177348)
		(end 363.189266 -226.178364)
		(width 0.1143)
		(layer "In11.Cu")
		(net "P5E_CPU0_G3_RX_DP<12>")
	)
	(segment
		(start 363.191806 -230.391716)
		(end 363.223556 -230.410004)
		(width 0.1143)
		(layer "In11.Cu")
		(net "P5E_CPU0_G3_RX_DP<12>")
	)
	(segment
		(start 363.191806 -232.656634)
		(end 363.19079 -232.657142)
		(width 0.1143)
		(layer "In11.Cu")
		(net "P5E_CPU0_G3_RX_DP<12>")
	)
	(segment
		(start 363.19079 -242.377214)
		(end 363.18952 -242.377976)
		(width 0.1143)
		(layer "In11.Cu")
		(net "P5E_CPU0_G3_RX_DP<12>")
	)
	(segment
		(start 363.192568 -239.136174)
		(end 363.191806 -239.136682)
		(width 0.1143)
		(layer "In11.Cu")
		(net "P5E_CPU0_G3_RX_DP<12>")
	)
	(segment
		(start 363.223556 -232.638346)
		(end 363.198156 -232.653078)
		(width 0.1143)
		(layer "In11.Cu")
		(net "P5E_CPU0_G3_RX_DP<12>")
	)
	(segment
		(start 363.15269 -236.84865)
		(end 363.189266 -236.869986)
		(width 0.1143)
		(layer "In11.Cu")
		(net "P5E_CPU0_G3_RX_DP<12>")
	)
	(segment
		(start 320.801492 -123.565666)
		(end 317.507366 -129.300478)
		(width 0.14224)
		(layer "In11.Cu")
		(net "P5E_CPU0_G3_RX_DP<12>")
	)
	(arc
		(start 364.16869 -224.53346)
		(mid 364.1649 -224.536532)
		(end 364.16107 -224.539556)
		(width 0.1143)
		(layer "In11.Cu")
		(net "P5E_CPU0_G3_RX_DP<12>")
	)
	(arc
		(start 363.223556 -230.410004)
		(mid 363.338232 -230.543338)
		(end 363.379512 -230.714296)
		(width 0.1143)
		(layer "In11.Cu")
		(net "P5E_CPU0_G3_RX_DP<12>")
	)
	(arc
		(start 362.68279 -244.829584)
		(mid 362.530803 -244.986092)
		(end 362.449364 -245.188486)
		(width 0.1143)
		(layer "In11.Cu")
		(net "P5E_CPU0_G3_RX_DP<12>")
	)
	(arc
		(start 364.20425 -222.346012)
		(mid 364.312844 -222.641401)
		(end 364.16361 -222.918528)
		(width 0.1143)
		(layer "In11.Cu")
		(net "P5E_CPU0_G3_RX_DP<12>")
	)
	(arc
		(start 363.379512 -230.714296)
		(mid 363.33875 -230.88418)
		(end 363.225334 -231.017064)
		(width 0.1143)
		(layer "In11.Cu")
		(net "P5E_CPU0_G3_RX_DP<12>")
	)
	(arc
		(start 363.223556 -232.029762)
		(mid 363.379484 -232.334054)
		(end 363.223556 -232.638346)
		(width 0.1143)
		(layer "In11.Cu")
		(net "P5E_CPU0_G3_RX_DP<12>")
	)
	(arc
		(start 363.223556 -238.50981)
		(mid 363.379484 -238.814102)
		(end 363.223556 -239.118394)
		(width 0.1143)
		(layer "In11.Cu")
		(net "P5E_CPU0_G3_RX_DP<12>")
	)
	(arc
		(start 363.223556 -233.649774)
		(mid 363.379484 -233.954066)
		(end 363.223556 -234.258358)
		(width 0.1143)
		(layer "In11.Cu")
		(net "P5E_CPU0_G3_RX_DP<12>")
	)
	(arc
		(start 363.379512 -225.85426)
		(mid 363.338257 -226.025231)
		(end 363.223556 -226.158552)
		(width 0.1143)
		(layer "In11.Cu")
		(net "P5E_CPU0_G3_RX_DP<12>")
	)
	(arc
		(start 363.15269 -234.299506)
		(mid 362.909363 -234.764072)
		(end 363.15269 -235.228638)
		(width 0.1143)
		(layer "In11.Cu")
		(net "P5E_CPU0_G3_RX_DP<12>")
	)
	(arc
		(start 363.223556 -236.889798)
		(mid 363.379484 -237.19409)
		(end 363.223556 -237.498382)
		(width 0.1143)
		(layer "In11.Cu")
		(net "P5E_CPU0_G3_RX_DP<12>")
	)
	(arc
		(start 363.223556 -241.749834)
		(mid 363.379484 -242.054126)
		(end 363.223556 -242.358418)
		(width 0.1143)
		(layer "In11.Cu")
		(net "P5E_CPU0_G3_RX_DP<12>")
	)
	(arc
		(start 363.15269 -242.399566)
		(mid 362.909363 -242.864132)
		(end 363.15269 -243.328698)
		(width 0.1143)
		(layer "In11.Cu")
		(net "P5E_CPU0_G3_RX_DP<12>")
	)
	(arc
		(start 363.223556 -235.269786)
		(mid 363.379484 -235.574078)
		(end 363.223556 -235.87837)
		(width 0.1143)
		(layer "In11.Cu")
		(net "P5E_CPU0_G3_RX_DP<12>")
	)
	(arc
		(start 363.223556 -240.129822)
		(mid 363.379484 -240.434114)
		(end 363.223556 -240.738406)
		(width 0.1143)
		(layer "In11.Cu")
		(net "P5E_CPU0_G3_RX_DP<12>")
	)
	(arc
		(start 363.15269 -232.679494)
		(mid 362.909363 -233.14406)
		(end 363.15269 -233.608626)
		(width 0.1143)
		(layer "In11.Cu")
		(net "P5E_CPU0_G3_RX_DP<12>")
	)
	(arc
		(start 364.064296 -222.979742)
		(mid 363.836608 -223.424242)
		(end 364.064296 -223.868742)
		(width 0.1143)
		(layer "In11.Cu")
		(net "P5E_CPU0_G3_RX_DP<12>")
	)
	(arc
		(start 364.163356 -223.929956)
		(mid 364.27601 -224.059589)
		(end 364.319058 -224.225866)
		(width 0.1143)
		(layer "In11.Cu")
		(net "P5E_CPU0_G3_RX_DP<12>")
	)
	(arc
		(start 363.15269 -227.819712)
		(mid 362.909363 -228.284278)
		(end 363.15269 -228.748844)
		(width 0.1143)
		(layer "In11.Cu")
		(net "P5E_CPU0_G3_RX_DP<12>")
	)
	(arc
		(start 363.849412 -225.044254)
		(mid 363.807863 -225.215676)
		(end 363.69244 -225.349054)
		(width 0.1143)
		(layer "In11.Cu")
		(net "P5E_CPU0_G3_RX_DP<12>")
	)
	(arc
		(start 364.095284 -224.57791)
		(mid 363.914632 -224.780655)
		(end 363.849412 -225.044254)
		(width 0.1143)
		(layer "In11.Cu")
		(net "P5E_CPU0_G3_RX_DP<12>")
	)
	(arc
		(start 363.223556 -243.369846)
		(mid 363.379484 -243.674138)
		(end 363.223556 -243.97843)
		(width 0.1143)
		(layer "In11.Cu")
		(net "P5E_CPU0_G3_RX_DP<12>")
	)
	(arc
		(start 362.449364 -245.188486)
		(mid 362.447341 -245.199896)
		(end 362.445554 -245.211346)
		(width 0.1143)
		(layer "In11.Cu")
		(net "P5E_CPU0_G3_RX_DP<12>")
	)
	(arc
		(start 364.318296 -224.240852)
		(mid 364.267781 -224.399578)
		(end 364.16869 -224.53346)
		(width 0.1143)
		(layer "In11.Cu")
		(net "P5E_CPU0_G3_RX_DP<12>")
	)
	(arc
		(start 362.909358 -229.904036)
		(mid 362.974594 -230.167627)
		(end 363.15523 -230.37038)
		(width 0.1143)
		(layer "In11.Cu")
		(net "P5E_CPU0_G3_RX_DP<12>")
	)
	(arc
		(start 363.15269 -244.019578)
		(mid 362.973877 -244.221928)
		(end 362.909358 -244.484144)
		(width 0.1143)
		(layer "In11.Cu")
		(net "P5E_CPU0_G3_RX_DP<12>")
	)
	(arc
		(start 363.622844 -225.389694)
		(mid 363.444031 -225.592044)
		(end 363.379512 -225.85426)
		(width 0.1143)
		(layer "In11.Cu")
		(net "P5E_CPU0_G3_RX_DP<12>")
	)
	(arc
		(start 363.15269 -231.059482)
		(mid 362.909363 -231.524048)
		(end 363.15269 -231.988614)
		(width 0.1143)
		(layer "In11.Cu")
		(net "P5E_CPU0_G3_RX_DP<12>")
	)
	(arc
		(start 363.15269 -229.43947)
		(mid 362.973877 -229.64182)
		(end 362.909358 -229.904036)
		(width 0.1143)
		(layer "In11.Cu")
		(net "P5E_CPU0_G3_RX_DP<12>")
	)
	(arc
		(start 363.223556 -228.789992)
		(mid 363.338232 -228.923326)
		(end 363.379512 -229.094284)
		(width 0.1143)
		(layer "In11.Cu")
		(net "P5E_CPU0_G3_RX_DP<12>")
	)
	(arc
		(start 362.909358 -244.484144)
		(mid 362.867809 -244.655566)
		(end 362.752386 -244.788944)
		(width 0.1143)
		(layer "In11.Cu")
		(net "P5E_CPU0_G3_RX_DP<12>")
	)
	(arc
		(start 363.223556 -227.16998)
		(mid 363.379484 -227.474272)
		(end 363.223556 -227.778564)
		(width 0.1143)
		(layer "In11.Cu")
		(net "P5E_CPU0_G3_RX_DP<12>")
	)
	(arc
		(start 363.379512 -229.094284)
		(mid 363.33875 -229.264168)
		(end 363.225334 -229.397052)
		(width 0.1143)
		(layer "In11.Cu")
		(net "P5E_CPU0_G3_RX_DP<12>")
	)
	(arc
		(start 363.15269 -239.159542)
		(mid 362.909363 -239.624108)
		(end 363.15269 -240.088674)
		(width 0.1143)
		(layer "In11.Cu")
		(net "P5E_CPU0_G3_RX_DP<12>")
	)
	(arc
		(start 363.849666 -221.80423)
		(mid 363.92757 -222.095817)
		(end 364.14075 -222.309436)
		(width 0.1143)
		(layer "In11.Cu")
		(net "P5E_CPU0_G3_RX_DP<12>")
	)
	(arc
		(start 363.15269 -237.53953)
		(mid 362.909363 -238.004096)
		(end 363.15269 -238.468662)
		(width 0.1143)
		(layer "In11.Cu")
		(net "P5E_CPU0_G3_RX_DP<12>")
	)
	(arc
		(start 363.15269 -240.779554)
		(mid 362.909363 -241.24412)
		(end 363.15269 -241.708686)
		(width 0.1143)
		(layer "In11.Cu")
		(net "P5E_CPU0_G3_RX_DP<12>")
	)
	(arc
		(start 363.15269 -235.919518)
		(mid 362.909363 -236.384084)
		(end 363.15269 -236.84865)
		(width 0.1143)
		(layer "In11.Cu")
		(net "P5E_CPU0_G3_RX_DP<12>")
	)
	(arc
		(start 363.15269 -226.1997)
		(mid 362.909363 -226.664266)
		(end 363.15269 -227.128832)
		(width 0.1143)
		(layer "In11.Cu")
		(net "P5E_CPU0_G3_RX_DP<12>")
	)
	(segment
		(start 400.985482 -7.57047)
		(end 400.985482 -6.99516)
		(width 0.12954)
		(layer "F.Cu")
		(net "P5E_CPU0_G3_RX_DP<11>")
	)
	(segment
		(start 400.846798 -8.320024)
		(end 400.846798 -7.709154)
		(width 0.12954)
		(layer "F.Cu")
		(net "P5E_CPU0_G3_RX_DP<11>")
	)
	(segment
		(start 400.846798 -7.709154)
		(end 400.985482 -7.57047)
		(width 0.12954)
		(layer "F.Cu")
		(net "P5E_CPU0_G3_RX_DP<11>")
	)
	(segment
		(start 400.985482 -6.99516)
		(end 400.71548 -6.725158)
		(width 0.12954)
		(layer "F.Cu")
		(net "P5E_CPU0_G3_RX_DP<11>")
	)
	(segment
		(start 363.947964 -247.990106)
		(end 364.414816 -247.724168)
		(width 0.12954)
		(layer "F.Cu")
		(net "P5E_CPU0_G3_RX_DP<11>")
	)
	(segment
		(start 364.12932 -235.249974)
		(end 364.130844 -235.25099)
		(width 0.1143)
		(layer "In11.Cu")
		(net "P5E_CPU0_G3_RX_DP<11>")
	)
	(segment
		(start 364.123732 -246.58701)
		(end 364.12932 -246.590058)
		(width 0.1143)
		(layer "In11.Cu")
		(net "P5E_CPU0_G3_RX_DP<11>")
	)
	(segment
		(start 364.16361 -232.638346)
		(end 364.137956 -232.653078)
		(width 0.1143)
		(layer "In11.Cu")
		(net "P5E_CPU0_G3_RX_DP<11>")
	)
	(segment
		(start 364.132622 -235.89615)
		(end 364.13186 -235.896658)
		(width 0.1143)
		(layer "In11.Cu")
		(net "P5E_CPU0_G3_RX_DP<11>")
	)
	(segment
		(start 364.130844 -235.25099)
		(end 364.13186 -235.251498)
		(width 0.1143)
		(layer "In11.Cu")
		(net "P5E_CPU0_G3_RX_DP<11>")
	)
	(segment
		(start 364.123732 -244.966998)
		(end 364.12932 -244.970046)
		(width 0.1143)
		(layer "In11.Cu")
		(net "P5E_CPU0_G3_RX_DP<11>")
	)
	(segment
		(start 364.092744 -244.94871)
		(end 364.123732 -244.966998)
		(width 0.1143)
		(layer "In11.Cu")
		(net "P5E_CPU0_G3_RX_DP<11>")
	)
	(segment
		(start 364.13186 -246.591582)
		(end 364.132622 -246.59209)
		(width 0.1143)
		(layer "In11.Cu")
		(net "P5E_CPU0_G3_RX_DP<11>")
	)
	(segment
		(start 364.130844 -243.997226)
		(end 364.12932 -243.998242)
		(width 0.1143)
		(layer "In11.Cu")
		(net "P5E_CPU0_G3_RX_DP<11>")
	)
	(segment
		(start 364.130844 -245.617238)
		(end 364.092744 -245.63959)
		(width 0.1143)
		(layer "In11.Cu")
		(net "P5E_CPU0_G3_RX_DP<11>")
	)
	(segment
		(start 364.12932 -233.629962)
		(end 364.130844 -233.630978)
		(width 0.1143)
		(layer "In11.Cu")
		(net "P5E_CPU0_G3_RX_DP<11>")
	)
	(segment
		(start 364.132622 -246.59209)
		(end 364.133892 -246.592852)
		(width 0.1143)
		(layer "In11.Cu")
		(net "P5E_CPU0_G3_RX_DP<11>")
	)
	(segment
		(start 321.917822 -175.997108)
		(end 360.06532 -207.258666)
		(width 0.14224)
		(layer "In11.Cu")
		(net "P5E_CPU0_G3_RX_DP<11>")
	)
	(segment
		(start 364.135416 -243.994686)
		(end 364.133892 -243.995448)
		(width 0.1143)
		(layer "In11.Cu")
		(net "P5E_CPU0_G3_RX_DP<11>")
	)
	(segment
		(start 364.124748 -234.28071)
		(end 364.092744 -234.299506)
		(width 0.1143)
		(layer "In11.Cu")
		(net "P5E_CPU0_G3_RX_DP<11>")
	)
	(segment
		(start 364.13186 -234.276646)
		(end 364.130844 -234.277154)
		(width 0.1143)
		(layer "In11.Cu")
		(net "P5E_CPU0_G3_RX_DP<11>")
	)
	(segment
		(start 364.132622 -234.276138)
		(end 364.13186 -234.276646)
		(width 0.1143)
		(layer "In11.Cu")
		(net "P5E_CPU0_G3_RX_DP<11>")
	)
	(segment
		(start 364.135416 -233.633518)
		(end 364.16361 -233.649774)
		(width 0.1143)
		(layer "In11.Cu")
		(net "P5E_CPU0_G3_RX_DP<11>")
	)
	(segment
		(start 364.130844 -232.010966)
		(end 364.13186 -232.011474)
		(width 0.1143)
		(layer "In11.Cu")
		(net "P5E_CPU0_G3_RX_DP<11>")
	)
	(segment
		(start 364.133892 -232.012744)
		(end 364.135416 -232.013506)
		(width 0.1143)
		(layer "In11.Cu")
		(net "P5E_CPU0_G3_RX_DP<11>")
	)
	(segment
		(start 400.413728 -19.317462)
		(end 400.370294 -19.389852)
		(width 0.14224)
		(layer "In11.Cu")
		(net "P5E_CPU0_G3_RX_DP<11>")
	)
	(segment
		(start 364.13186 -241.731546)
		(end 364.132622 -241.732054)
		(width 0.1143)
		(layer "In11.Cu")
		(net "P5E_CPU0_G3_RX_DP<11>")
	)
	(segment
		(start 364.63351 -225.348546)
		(end 364.603792 -225.365564)
		(width 0.1143)
		(layer "In11.Cu")
		(net "P5E_CPU0_G3_RX_DP<11>")
	)
	(segment
		(start 365.25962 -222.614236)
		(end 365.259366 -222.614236)
		(width 0.1143)
		(layer "In11.Cu")
		(net "P5E_CPU0_G3_RX_DP<11>")
	)
	(segment
		(start 364.12932 -232.00995)
		(end 364.130844 -232.010966)
		(width 0.1143)
		(layer "In11.Cu")
		(net "P5E_CPU0_G3_RX_DP<11>")
	)
	(segment
		(start 364.124748 -232.660698)
		(end 364.092744 -232.679494)
		(width 0.1143)
		(layer "In11.Cu")
		(net "P5E_CPU0_G3_RX_DP<11>")
	)
	(segment
		(start 364.12932 -243.998242)
		(end 364.124748 -244.000782)
		(width 0.1143)
		(layer "In11.Cu")
		(net "P5E_CPU0_G3_RX_DP<11>")
	)
	(segment
		(start 364.137956 -239.133126)
		(end 364.137194 -239.133634)
		(width 0.1143)
		(layer "In11.Cu")
		(net "P5E_CPU0_G3_RX_DP<11>")
	)
	(segment
		(start 364.133892 -242.375436)
		(end 364.132622 -242.376198)
		(width 0.1143)
		(layer "In11.Cu")
		(net "P5E_CPU0_G3_RX_DP<11>")
	)
	(segment
		(start 364.092744 -243.328698)
		(end 364.123732 -243.346986)
		(width 0.1143)
		(layer "In11.Cu")
		(net "P5E_CPU0_G3_RX_DP<11>")
	)
	(segment
		(start 364.135416 -240.113566)
		(end 364.16361 -240.129822)
		(width 0.1143)
		(layer "In11.Cu")
		(net "P5E_CPU0_G3_RX_DP<11>")
	)
	(segment
		(start 364.124748 -240.760758)
		(end 364.092744 -240.779554)
		(width 0.1143)
		(layer "In11.Cu")
		(net "P5E_CPU0_G3_RX_DP<11>")
	)
	(segment
		(start 364.133892 -241.732816)
		(end 364.135416 -241.733578)
		(width 0.1143)
		(layer "In11.Cu")
		(net "P5E_CPU0_G3_RX_DP<11>")
	)
	(segment
		(start 309.59171 -162.742118)
		(end 311.819798 -168.122092)
		(width 0.14224)
		(layer "In11.Cu")
		(net "P5E_CPU0_G3_RX_DP<11>")
	)
	(segment
		(start 364.12932 -234.27817)
		(end 364.124748 -234.28071)
		(width 0.1143)
		(layer "In11.Cu")
		(net "P5E_CPU0_G3_RX_DP<11>")
	)
	(segment
		(start 364.135416 -234.274614)
		(end 364.133892 -234.275376)
		(width 0.1143)
		(layer "In11.Cu")
		(net "P5E_CPU0_G3_RX_DP<11>")
	)
	(segment
		(start 309.59171 -160.456626)
		(end 309.59171 -162.742118)
		(width 0.14224)
		(layer "In11.Cu")
		(net "P5E_CPU0_G3_RX_DP<11>")
	)
	(segment
		(start 364.137956 -232.653078)
		(end 364.137194 -232.653586)
		(width 0.1143)
		(layer "In11.Cu")
		(net "P5E_CPU0_G3_RX_DP<11>")
	)
	(segment
		(start 364.12932 -246.590058)
		(end 364.130844 -246.591074)
		(width 0.1143)
		(layer "In11.Cu")
		(net "P5E_CPU0_G3_RX_DP<11>")
	)
	(segment
		(start 400.240246 -18.552414)
		(end 400.442684 -19.04111)
		(width 0.14224)
		(layer "In11.Cu")
		(net "P5E_CPU0_G3_RX_DP<11>")
	)
	(segment
		(start 364.130844 -238.491014)
		(end 364.13186 -238.491522)
		(width 0.1143)
		(layer "In11.Cu")
		(net "P5E_CPU0_G3_RX_DP<11>")
	)
	(segment
		(start 364.123732 -241.726974)
		(end 364.12932 -241.730022)
		(width 0.1143)
		(layer "In11.Cu")
		(net "P5E_CPU0_G3_RX_DP<11>")
	)
	(segment
		(start 364.12932 -232.658158)
		(end 364.124748 -232.660698)
		(width 0.1143)
		(layer "In11.Cu")
		(net "P5E_CPU0_G3_RX_DP<11>")
	)
	(segment
		(start 364.092744 -235.228638)
		(end 364.123732 -235.246926)
		(width 0.1143)
		(layer "In11.Cu")
		(net "P5E_CPU0_G3_RX_DP<11>")
	)
	(segment
		(start 364.13186 -232.656634)
		(end 364.130844 -232.657142)
		(width 0.1143)
		(layer "In11.Cu")
		(net "P5E_CPU0_G3_RX_DP<11>")
	)
	(segment
		(start 364.16361 -242.358418)
		(end 364.133892 -242.375436)
		(width 0.1143)
		(layer "In11.Cu")
		(net "P5E_CPU0_G3_RX_DP<11>")
	)
	(segment
		(start 364.13186 -232.011474)
		(end 364.132622 -232.011982)
		(width 0.1143)
		(layer "In11.Cu")
		(net "P5E_CPU0_G3_RX_DP<11>")
	)
	(segment
		(start 364.569502 -225.38563)
		(end 364.562644 -225.389694)
		(width 0.1143)
		(layer "In11.Cu")
		(net "P5E_CPU0_G3_RX_DP<11>")
	)
	(segment
		(start 364.135416 -243.35359)
		(end 364.16361 -243.369846)
		(width 0.1143)
		(layer "In11.Cu")
		(net "P5E_CPU0_G3_RX_DP<11>")
	)
	(segment
		(start 399.764504 -17.356074)
		(end 399.764504 -17.777714)
		(width 0.14224)
		(layer "In11.Cu")
		(net "P5E_CPU0_G3_RX_DP<11>")
	)
	(segment
		(start 364.133892 -240.755424)
		(end 364.132622 -240.756186)
		(width 0.1143)
		(layer "In11.Cu")
		(net "P5E_CPU0_G3_RX_DP<11>")
	)
	(segment
		(start 364.16361 -243.97843)
		(end 364.137956 -243.993162)
		(width 0.1143)
		(layer "In11.Cu")
		(net "P5E_CPU0_G3_RX_DP<11>")
	)
	(segment
		(start 364.75797 -221.083124)
		(end 364.80369 -221.128844)
		(width 0.1143)
		(layer "In11.Cu")
		(net "P5E_CPU0_G3_RX_DP<11>")
	)
	(segment
		(start 364.123732 -233.626914)
		(end 364.12932 -233.629962)
		(width 0.1143)
		(layer "In11.Cu")
		(net "P5E_CPU0_G3_RX_DP<11>")
	)
	(segment
		(start 364.130844 -239.13719)
		(end 364.12932 -239.138206)
		(width 0.1143)
		(layer "In11.Cu")
		(net "P5E_CPU0_G3_RX_DP<11>")
	)
	(segment
		(start 364.13186 -235.896658)
		(end 364.130844 -235.897166)
		(width 0.1143)
		(layer "In11.Cu")
		(net "P5E_CPU0_G3_RX_DP<11>")
	)
	(segment
		(start 364.092744 -238.468662)
		(end 364.12932 -238.489998)
		(width 0.1143)
		(layer "In11.Cu")
		(net "P5E_CPU0_G3_RX_DP<11>")
	)
	(segment
		(start 364.095538 -228.750876)
		(end 364.13186 -228.771704)
		(width 0.1143)
		(layer "In11.Cu")
		(net "P5E_CPU0_G3_RX_DP<11>")
	)
	(segment
		(start 364.782608 -247.654318)
		(end 364.712758 -247.724168)
		(width 0.1143)
		(layer "In11.Cu")
		(net "P5E_CPU0_G3_RX_DP<11>")
	)
	(segment
		(start 364.13186 -233.631486)
		(end 364.132622 -233.631994)
		(width 0.1143)
		(layer "In11.Cu")
		(net "P5E_CPU0_G3_RX_DP<11>")
	)
	(segment
		(start 364.13186 -240.756694)
		(end 364.130844 -240.757202)
		(width 0.1143)
		(layer "In11.Cu")
		(net "P5E_CPU0_G3_RX_DP<11>")
	)
	(segment
		(start 364.124748 -239.140746)
		(end 364.092744 -239.159542)
		(width 0.1143)
		(layer "In11.Cu")
		(net "P5E_CPU0_G3_RX_DP<11>")
	)
	(segment
		(start 364.133892 -246.592852)
		(end 364.135416 -246.593614)
		(width 0.1143)
		(layer "In11.Cu")
		(net "P5E_CPU0_G3_RX_DP<11>")
	)
	(segment
		(start 364.137956 -243.993162)
		(end 364.137194 -243.99367)
		(width 0.1143)
		(layer "In11.Cu")
		(net "P5E_CPU0_G3_RX_DP<11>")
	)
	(segment
		(start 365.032798 -222.268796)
		(end 365.069374 -222.290132)
		(width 0.1143)
		(layer "In11.Cu")
		(net "P5E_CPU0_G3_RX_DP<11>")
	)
	(segment
		(start 365.102394 -224.539048)
		(end 365.032798 -224.579688)
		(width 0.1143)
		(layer "In11.Cu")
		(net "P5E_CPU0_G3_RX_DP<11>")
	)
	(segment
		(start 364.16361 -235.87837)
		(end 364.137956 -235.893102)
		(width 0.1143)
		(layer "In11.Cu")
		(net "P5E_CPU0_G3_RX_DP<11>")
	)
	(segment
		(start 364.095284 -230.37038)
		(end 364.13186 -230.391716)
		(width 0.1143)
		(layer "In11.Cu")
		(net "P5E_CPU0_G3_RX_DP<11>")
	)
	(segment
		(start 364.092744 -241.708686)
		(end 364.123732 -241.726974)
		(width 0.1143)
		(layer "In11.Cu")
		(net "P5E_CPU0_G3_RX_DP<11>")
	)
	(segment
		(start 364.712758 -247.724168)
		(end 364.414816 -247.724168)
		(width 0.1143)
		(layer "In11.Cu")
		(net "P5E_CPU0_G3_RX_DP<11>")
	)
	(segment
		(start 311.786016 -147.966938)
		(end 309.59171 -160.456626)
		(width 0.14224)
		(layer "In11.Cu")
		(net "P5E_CPU0_G3_RX_DP<11>")
	)
	(segment
		(start 364.132622 -240.756186)
		(end 364.13186 -240.756694)
		(width 0.1143)
		(layer "In11.Cu")
		(net "P5E_CPU0_G3_RX_DP<11>")
	)
	(segment
		(start 364.562898 -247.378728)
		(end 364.632494 -247.419368)
		(width 0.1143)
		(layer "In11.Cu")
		(net "P5E_CPU0_G3_RX_DP<11>")
	)
	(segment
		(start 364.130844 -240.757202)
		(end 364.12932 -240.758218)
		(width 0.1143)
		(layer "In11.Cu")
		(net "P5E_CPU0_G3_RX_DP<11>")
	)
	(segment
		(start 364.133892 -239.135412)
		(end 364.132622 -239.136174)
		(width 0.1143)
		(layer "In11.Cu")
		(net "P5E_CPU0_G3_RX_DP<11>")
	)
	(segment
		(start 364.123732 -240.106962)
		(end 364.12932 -240.11001)
		(width 0.1143)
		(layer "In11.Cu")
		(net "P5E_CPU0_G3_RX_DP<11>")
	)
	(segment
		(start 364.137956 -235.893102)
		(end 364.137194 -235.89361)
		(width 0.1143)
		(layer "In11.Cu")
		(net "P5E_CPU0_G3_RX_DP<11>")
	)
	(segment
		(start 364.130844 -236.871002)
		(end 364.13186 -236.87151)
		(width 0.1143)
		(layer "In11.Cu")
		(net "P5E_CPU0_G3_RX_DP<11>")
	)
	(segment
		(start 364.13186 -242.376706)
		(end 364.130844 -242.377214)
		(width 0.1143)
		(layer "In11.Cu")
		(net "P5E_CPU0_G3_RX_DP<11>")
	)
	(segment
		(start 364.12932 -244.970046)
		(end 364.130844 -244.971062)
		(width 0.1143)
		(layer "In11.Cu")
		(net "P5E_CPU0_G3_RX_DP<11>")
	)
	(segment
		(start 364.132622 -245.616222)
		(end 364.13186 -245.61673)
		(width 0.1143)
		(layer "In11.Cu")
		(net "P5E_CPU0_G3_RX_DP<11>")
	)
	(segment
		(start 364.137194 -243.99367)
		(end 364.136178 -243.994178)
		(width 0.1143)
		(layer "In11.Cu")
		(net "P5E_CPU0_G3_RX_DP<11>")
	)
	(segment
		(start 364.136178 -243.994178)
		(end 364.135416 -243.994686)
		(width 0.1143)
		(layer "In11.Cu")
		(net "P5E_CPU0_G3_RX_DP<11>")
	)
	(segment
		(start 311.819798 -168.122092)
		(end 316.368938 -172.672502)
		(width 0.14224)
		(layer "In11.Cu")
		(net "P5E_CPU0_G3_RX_DP<11>")
	)
	(segment
		(start 316.368938 -172.672502)
		(end 321.917822 -175.997108)
		(width 0.14224)
		(layer "In11.Cu")
		(net "P5E_CPU0_G3_RX_DP<11>")
	)
	(segment
		(start 364.130844 -242.377214)
		(end 364.092744 -242.399566)
		(width 0.1143)
		(layer "In11.Cu")
		(net "P5E_CPU0_G3_RX_DP<11>")
	)
	(segment
		(start 364.12932 -238.489998)
		(end 364.130844 -238.491014)
		(width 0.1143)
		(layer "In11.Cu")
		(net "P5E_CPU0_G3_RX_DP<11>")
	)
	(segment
		(start 364.13186 -229.41661)
		(end 364.095538 -229.437692)
		(width 0.1143)
		(layer "In11.Cu")
		(net "P5E_CPU0_G3_RX_DP<11>")
	)
	(segment
		(start 364.133892 -233.632756)
		(end 364.135416 -233.633518)
		(width 0.1143)
		(layer "In11.Cu")
		(net "P5E_CPU0_G3_RX_DP<11>")
	)
	(segment
		(start 364.132622 -232.656126)
		(end 364.13186 -232.656634)
		(width 0.1143)
		(layer "In11.Cu")
		(net "P5E_CPU0_G3_RX_DP<11>")
	)
	(segment
		(start 364.130844 -234.277154)
		(end 364.12932 -234.27817)
		(width 0.1143)
		(layer "In11.Cu")
		(net "P5E_CPU0_G3_RX_DP<11>")
	)
	(segment
		(start 364.136178 -232.654094)
		(end 364.135416 -232.654602)
		(width 0.1143)
		(layer "In11.Cu")
		(net "P5E_CPU0_G3_RX_DP<11>")
	)
	(segment
		(start 364.092744 -231.988614)
		(end 364.123732 -232.006902)
		(width 0.1143)
		(layer "In11.Cu")
		(net "P5E_CPU0_G3_RX_DP<11>")
	)
	(segment
		(start 364.132622 -235.252006)
		(end 364.133892 -235.252768)
		(width 0.1143)
		(layer "In11.Cu")
		(net "P5E_CPU0_G3_RX_DP<11>")
	)
	(segment
		(start 364.132622 -239.136174)
		(end 364.13186 -239.136682)
		(width 0.1143)
		(layer "In11.Cu")
		(net "P5E_CPU0_G3_RX_DP<11>")
	)
	(segment
		(start 364.16234 -227.779072)
		(end 364.092744 -227.819712)
		(width 0.1143)
		(layer "In11.Cu")
		(net "P5E_CPU0_G3_RX_DP<11>")
	)
	(segment
		(start 364.75797 -215.161622)
		(end 364.75797 -221.054676)
		(width 0.14224)
		(layer "In11.Cu")
		(net "P5E_CPU0_G3_RX_DP<11>")
	)
	(segment
		(start 364.16361 -245.598442)
		(end 364.133892 -245.61546)
		(width 0.1143)
		(layer "In11.Cu")
		(net "P5E_CPU0_G3_RX_DP<11>")
	)
	(segment
		(start 364.80369 -221.308676)
		(end 364.789466 -221.3229)
		(width 0.1143)
		(layer "In11.Cu")
		(net "P5E_CPU0_G3_RX_DP<11>")
	)
	(segment
		(start 364.133892 -243.352828)
		(end 364.135416 -243.35359)
		(width 0.1143)
		(layer "In11.Cu")
		(net "P5E_CPU0_G3_RX_DP<11>")
	)
	(segment
		(start 364.132622 -244.972078)
		(end 364.133892 -244.97284)
		(width 0.1143)
		(layer "In11.Cu")
		(net "P5E_CPU0_G3_RX_DP<11>")
	)
	(segment
		(start 364.16234 -226.15906)
		(end 364.092744 -226.1997)
		(width 0.1143)
		(layer "In11.Cu")
		(net "P5E_CPU0_G3_RX_DP<11>")
	)
	(segment
		(start 364.132622 -236.872018)
		(end 364.133892 -236.87278)
		(width 0.1143)
		(layer "In11.Cu")
		(net "P5E_CPU0_G3_RX_DP<11>")
	)
	(segment
		(start 364.137194 -235.89361)
		(end 364.136178 -235.894118)
		(width 0.1143)
		(layer "In11.Cu")
		(net "P5E_CPU0_G3_RX_DP<11>")
	)
	(segment
		(start 364.132622 -242.376198)
		(end 364.13186 -242.376706)
		(width 0.1143)
		(layer "In11.Cu")
		(net "P5E_CPU0_G3_RX_DP<11>")
	)
	(segment
		(start 364.12932 -240.11001)
		(end 364.130844 -240.111026)
		(width 0.1143)
		(layer "In11.Cu")
		(net "P5E_CPU0_G3_RX_DP<11>")
	)
	(segment
		(start 364.13186 -240.111534)
		(end 364.132622 -240.112042)
		(width 0.1143)
		(layer "In11.Cu")
		(net "P5E_CPU0_G3_RX_DP<11>")
	)
	(segment
		(start 400.442684 -19.04111)
		(end 400.442684 -19.191224)
		(width 0.14224)
		(layer "In11.Cu")
		(net "P5E_CPU0_G3_RX_DP<11>")
	)
	(segment
		(start 364.130844 -243.35105)
		(end 364.13186 -243.351558)
		(width 0.1143)
		(layer "In11.Cu")
		(net "P5E_CPU0_G3_RX_DP<11>")
	)
	(segment
		(start 400.370294 -19.389852)
		(end 384.979672 -41.954958)
		(width 0.14224)
		(layer "In11.Cu")
		(net "P5E_CPU0_G3_RX_DP<11>")
	)
	(segment
		(start 364.092744 -227.128832)
		(end 364.16234 -227.169472)
		(width 0.1143)
		(layer "In11.Cu")
		(net "P5E_CPU0_G3_RX_DP<11>")
	)
	(segment
		(start 364.12932 -241.730022)
		(end 364.130844 -241.731038)
		(width 0.1143)
		(layer "In11.Cu")
		(net "P5E_CPU0_G3_RX_DP<11>")
	)
	(segment
		(start 364.124748 -235.900722)
		(end 364.092744 -235.919518)
		(width 0.1143)
		(layer "In11.Cu")
		(net "P5E_CPU0_G3_RX_DP<11>")
	)
	(segment
		(start 364.13186 -236.87151)
		(end 364.132622 -236.872018)
		(width 0.1143)
		(layer "In11.Cu")
		(net "P5E_CPU0_G3_RX_DP<11>")
	)
	(segment
		(start 364.130844 -235.897166)
		(end 364.12932 -235.898182)
		(width 0.1143)
		(layer "In11.Cu")
		(net "P5E_CPU0_G3_RX_DP<11>")
	)
	(segment
		(start 364.133892 -235.895388)
		(end 364.132622 -235.89615)
		(width 0.1143)
		(layer "In11.Cu")
		(net "P5E_CPU0_G3_RX_DP<11>")
	)
	(segment
		(start 365.032798 -223.888808)
		(end 365.102394 -223.929448)
		(width 0.1143)
		(layer "In11.Cu")
		(net "P5E_CPU0_G3_RX_DP<11>")
	)
	(segment
		(start 364.165388 -231.017064)
		(end 364.092744 -231.059482)
		(width 0.1143)
		(layer "In11.Cu")
		(net "P5E_CPU0_G3_RX_DP<11>")
	)
	(segment
		(start 364.133892 -232.655364)
		(end 364.132622 -232.656126)
		(width 0.1143)
		(layer "In11.Cu")
		(net "P5E_CPU0_G3_RX_DP<11>")
	)
	(segment
		(start 365.070898 -222.291148)
		(end 365.071914 -222.291656)
		(width 0.1143)
		(layer "In11.Cu")
		(net "P5E_CPU0_G3_RX_DP<11>")
	)
	(segment
		(start 364.092744 -236.84865)
		(end 364.123732 -236.866938)
		(width 0.1143)
		(layer "In11.Cu")
		(net "P5E_CPU0_G3_RX_DP<11>")
	)
	(segment
		(start 364.123732 -232.006902)
		(end 364.12932 -232.00995)
		(width 0.1143)
		(layer "In11.Cu")
		(net "P5E_CPU0_G3_RX_DP<11>")
	)
	(segment
		(start 364.133892 -235.252768)
		(end 364.135416 -235.25353)
		(width 0.1143)
		(layer "In11.Cu")
		(net "P5E_CPU0_G3_RX_DP<11>")
	)
	(segment
		(start 364.130844 -237.517178)
		(end 364.092744 -237.53953)
		(width 0.1143)
		(layer "In11.Cu")
		(net "P5E_CPU0_G3_RX_DP<11>")
	)
	(segment
		(start 364.13186 -243.351558)
		(end 364.132622 -243.352066)
		(width 0.1143)
		(layer "In11.Cu")
		(net "P5E_CPU0_G3_RX_DP<11>")
	)
	(segment
		(start 399.975832 -18.288)
		(end 400.240246 -18.552414)
		(width 0.14224)
		(layer "In11.Cu")
		(net "P5E_CPU0_G3_RX_DP<11>")
	)
	(segment
		(start 364.133892 -234.275376)
		(end 364.132622 -234.276138)
		(width 0.1143)
		(layer "In11.Cu")
		(net "P5E_CPU0_G3_RX_DP<11>")
	)
	(segment
		(start 364.80369 -221.128844)
		(end 364.80369 -221.308676)
		(width 0.1143)
		(layer "In11.Cu")
		(net "P5E_CPU0_G3_RX_DP<11>")
	)
	(segment
		(start 364.135416 -244.973602)
		(end 364.16361 -244.989858)
		(width 0.1143)
		(layer "In11.Cu")
		(net "P5E_CPU0_G3_RX_DP<11>")
	)
	(segment
		(start 364.130844 -233.630978)
		(end 364.13186 -233.631486)
		(width 0.1143)
		(layer "In11.Cu")
		(net "P5E_CPU0_G3_RX_DP<11>")
	)
	(segment
		(start 364.130844 -241.731038)
		(end 364.13186 -241.731546)
		(width 0.1143)
		(layer "In11.Cu")
		(net "P5E_CPU0_G3_RX_DP<11>")
	)
	(segment
		(start 400.71548 -6.725158)
		(end 401.00631 -7.015988)
		(width 0.14224)
		(layer "In11.Cu")
		(net "P5E_CPU0_G3_RX_DP<11>")
	)
	(segment
		(start 365.071914 -222.291656)
		(end 365.103664 -222.309944)
		(width 0.1143)
		(layer "In11.Cu")
		(net "P5E_CPU0_G3_RX_DP<11>")
	)
	(segment
		(start 364.137194 -239.133634)
		(end 364.136178 -239.134142)
		(width 0.1143)
		(layer "In11.Cu")
		(net "P5E_CPU0_G3_RX_DP<11>")
	)
	(segment
		(start 399.764504 -17.777714)
		(end 399.975832 -18.288)
		(width 0.14224)
		(layer "In11.Cu")
		(net "P5E_CPU0_G3_RX_DP<11>")
	)
	(segment
		(start 364.13186 -239.136682)
		(end 364.130844 -239.13719)
		(width 0.1143)
		(layer "In11.Cu")
		(net "P5E_CPU0_G3_RX_DP<11>")
	)
	(segment
		(start 364.16361 -239.118394)
		(end 364.137956 -239.133126)
		(width 0.1143)
		(layer "In11.Cu")
		(net "P5E_CPU0_G3_RX_DP<11>")
	)
	(segment
		(start 364.132622 -237.516162)
		(end 364.13186 -237.51667)
		(width 0.1143)
		(layer "In11.Cu")
		(net "P5E_CPU0_G3_RX_DP<11>")
	)
	(segment
		(start 363.849666 -229.904036)
		(end 363.849412 -229.904036)
		(width 0.1143)
		(layer "In11.Cu")
		(net "P5E_CPU0_G3_RX_DP<11>")
	)
	(segment
		(start 364.12932 -236.869986)
		(end 364.130844 -236.871002)
		(width 0.1143)
		(layer "In11.Cu")
		(net "P5E_CPU0_G3_RX_DP<11>")
	)
	(segment
		(start 364.13186 -237.51667)
		(end 364.130844 -237.517178)
		(width 0.1143)
		(layer "In11.Cu")
		(net "P5E_CPU0_G3_RX_DP<11>")
	)
	(segment
		(start 364.092744 -233.608626)
		(end 364.123732 -233.626914)
		(width 0.1143)
		(layer "In11.Cu")
		(net "P5E_CPU0_G3_RX_DP<11>")
	)
	(segment
		(start 364.135416 -235.894626)
		(end 364.133892 -235.895388)
		(width 0.1143)
		(layer "In11.Cu")
		(net "P5E_CPU0_G3_RX_DP<11>")
	)
	(segment
		(start 364.132622 -243.99621)
		(end 364.13186 -243.996718)
		(width 0.1143)
		(layer "In11.Cu")
		(net "P5E_CPU0_G3_RX_DP<11>")
	)
	(segment
		(start 364.133892 -245.61546)
		(end 364.132622 -245.616222)
		(width 0.1143)
		(layer "In11.Cu")
		(net "P5E_CPU0_G3_RX_DP<11>")
	)
	(segment
		(start 364.16361 -234.258358)
		(end 364.137956 -234.27309)
		(width 0.1143)
		(layer "In11.Cu")
		(net "P5E_CPU0_G3_RX_DP<11>")
	)
	(segment
		(start 318.228472 -130.196082)
		(end 311.786016 -147.966938)
		(width 0.14224)
		(layer "In11.Cu")
		(net "P5E_CPU0_G3_RX_DP<11>")
	)
	(segment
		(start 364.092744 -240.088674)
		(end 364.123732 -240.106962)
		(width 0.1143)
		(layer "In11.Cu")
		(net "P5E_CPU0_G3_RX_DP<11>")
	)
	(segment
		(start 364.135416 -241.733578)
		(end 364.16361 -241.749834)
		(width 0.1143)
		(layer "In11.Cu")
		(net "P5E_CPU0_G3_RX_DP<11>")
	)
	(segment
		(start 364.13186 -228.771704)
		(end 364.16361 -228.789992)
		(width 0.1143)
		(layer "In11.Cu")
		(net "P5E_CPU0_G3_RX_DP<11>")
	)
	(segment
		(start 364.132622 -241.732054)
		(end 364.133892 -241.732816)
		(width 0.1143)
		(layer "In11.Cu")
		(net "P5E_CPU0_G3_RX_DP<11>")
	)
	(segment
		(start 364.13186 -238.491522)
		(end 364.16361 -238.50981)
		(width 0.1143)
		(layer "In11.Cu")
		(net "P5E_CPU0_G3_RX_DP<11>")
	)
	(segment
		(start 364.135416 -232.013506)
		(end 364.16361 -232.029762)
		(width 0.1143)
		(layer "In11.Cu")
		(net "P5E_CPU0_G3_RX_DP<11>")
	)
	(segment
		(start 401.00631 -7.015988)
		(end 401.00631 -11.113262)
		(width 0.14224)
		(layer "In11.Cu")
		(net "P5E_CPU0_G3_RX_DP<11>")
	)
	(segment
		(start 364.136178 -239.134142)
		(end 364.135416 -239.13465)
		(width 0.1143)
		(layer "In11.Cu")
		(net "P5E_CPU0_G3_RX_DP<11>")
	)
	(segment
		(start 364.130844 -244.971062)
		(end 364.13186 -244.97157)
		(width 0.1143)
		(layer "In11.Cu")
		(net "P5E_CPU0_G3_RX_DP<11>")
	)
	(segment
		(start 364.092744 -246.568722)
		(end 364.123732 -246.58701)
		(width 0.1143)
		(layer "In11.Cu")
		(net "P5E_CPU0_G3_RX_DP<11>")
	)
	(segment
		(start 364.602522 -225.366326)
		(end 364.60176 -225.366834)
		(width 0.1143)
		(layer "In11.Cu")
		(net "P5E_CPU0_G3_RX_DP<11>")
	)
	(segment
		(start 364.13186 -245.61673)
		(end 364.130844 -245.617238)
		(width 0.1143)
		(layer "In11.Cu")
		(net "P5E_CPU0_G3_RX_DP<11>")
	)
	(segment
		(start 364.137194 -232.653586)
		(end 364.136178 -232.654094)
		(width 0.1143)
		(layer "In11.Cu")
		(net "P5E_CPU0_G3_RX_DP<11>")
	)
	(segment
		(start 384.979672 -41.954958)
		(end 320.92011 -125.288294)
		(width 0.14224)
		(layer "In11.Cu")
		(net "P5E_CPU0_G3_RX_DP<11>")
	)
	(segment
		(start 364.13186 -235.251498)
		(end 364.132622 -235.252006)
		(width 0.1143)
		(layer "In11.Cu")
		(net "P5E_CPU0_G3_RX_DP<11>")
	)
	(segment
		(start 364.135416 -235.25353)
		(end 364.16361 -235.269786)
		(width 0.1143)
		(layer "In11.Cu")
		(net "P5E_CPU0_G3_RX_DP<11>")
	)
	(segment
		(start 364.60176 -225.366834)
		(end 364.570264 -225.385122)
		(width 0.1143)
		(layer "In11.Cu")
		(net "P5E_CPU0_G3_RX_DP<11>")
	)
	(segment
		(start 364.135416 -239.13465)
		(end 364.133892 -239.135412)
		(width 0.1143)
		(layer "In11.Cu")
		(net "P5E_CPU0_G3_RX_DP<11>")
	)
	(segment
		(start 364.130844 -232.657142)
		(end 364.12932 -232.658158)
		(width 0.1143)
		(layer "In11.Cu")
		(net "P5E_CPU0_G3_RX_DP<11>")
	)
	(segment
		(start 364.13186 -244.97157)
		(end 364.132622 -244.972078)
		(width 0.1143)
		(layer "In11.Cu")
		(net "P5E_CPU0_G3_RX_DP<11>")
	)
	(segment
		(start 364.12932 -240.758218)
		(end 364.124748 -240.760758)
		(width 0.1143)
		(layer "In11.Cu")
		(net "P5E_CPU0_G3_RX_DP<11>")
	)
	(segment
		(start 364.16361 -240.738406)
		(end 364.137956 -240.753138)
		(width 0.1143)
		(layer "In11.Cu")
		(net "P5E_CPU0_G3_RX_DP<11>")
	)
	(segment
		(start 364.137956 -234.27309)
		(end 364.137194 -234.273598)
		(width 0.1143)
		(layer "In11.Cu")
		(net "P5E_CPU0_G3_RX_DP<11>")
	)
	(segment
		(start 365.102394 -222.919036)
		(end 365.032798 -222.959676)
		(width 0.1143)
		(layer "In11.Cu")
		(net "P5E_CPU0_G3_RX_DP<11>")
	)
	(segment
		(start 364.12932 -243.350034)
		(end 364.130844 -243.35105)
		(width 0.1143)
		(layer "In11.Cu")
		(net "P5E_CPU0_G3_RX_DP<11>")
	)
	(segment
		(start 364.136178 -234.274106)
		(end 364.135416 -234.274614)
		(width 0.1143)
		(layer "In11.Cu")
		(net "P5E_CPU0_G3_RX_DP<11>")
	)
	(segment
		(start 364.137956 -240.753138)
		(end 364.137194 -240.753646)
		(width 0.1143)
		(layer "In11.Cu")
		(net "P5E_CPU0_G3_RX_DP<11>")
	)
	(segment
		(start 364.130844 -246.591074)
		(end 364.13186 -246.591582)
		(width 0.1143)
		(layer "In11.Cu")
		(net "P5E_CPU0_G3_RX_DP<11>")
	)
	(segment
		(start 364.789466 -221.3229)
		(end 364.789466 -221.80423)
		(width 0.1143)
		(layer "In11.Cu")
		(net "P5E_CPU0_G3_RX_DP<11>")
	)
	(segment
		(start 364.12932 -235.898182)
		(end 364.124748 -235.900722)
		(width 0.1143)
		(layer "In11.Cu")
		(net "P5E_CPU0_G3_RX_DP<11>")
	)
	(segment
		(start 364.135416 -240.754662)
		(end 364.133892 -240.755424)
		(width 0.1143)
		(layer "In11.Cu")
		(net "P5E_CPU0_G3_RX_DP<11>")
	)
	(segment
		(start 364.124748 -244.000782)
		(end 364.092744 -244.019578)
		(width 0.1143)
		(layer "In11.Cu")
		(net "P5E_CPU0_G3_RX_DP<11>")
	)
	(segment
		(start 364.123732 -243.346986)
		(end 364.12932 -243.350034)
		(width 0.1143)
		(layer "In11.Cu")
		(net "P5E_CPU0_G3_RX_DP<11>")
	)
	(segment
		(start 320.92011 -125.288294)
		(end 318.228472 -130.196082)
		(width 0.14224)
		(layer "In11.Cu")
		(net "P5E_CPU0_G3_RX_DP<11>")
	)
	(segment
		(start 364.136178 -235.894118)
		(end 364.135416 -235.894626)
		(width 0.1143)
		(layer "In11.Cu")
		(net "P5E_CPU0_G3_RX_DP<11>")
	)
	(segment
		(start 364.133892 -237.5154)
		(end 364.132622 -237.516162)
		(width 0.1143)
		(layer "In11.Cu")
		(net "P5E_CPU0_G3_RX_DP<11>")
	)
	(segment
		(start 364.137194 -240.753646)
		(end 364.136178 -240.754154)
		(width 0.1143)
		(layer "In11.Cu")
		(net "P5E_CPU0_G3_RX_DP<11>")
	)
	(segment
		(start 364.570264 -225.385122)
		(end 364.569502 -225.38563)
		(width 0.1143)
		(layer "In11.Cu")
		(net "P5E_CPU0_G3_RX_DP<11>")
	)
	(segment
		(start 364.133892 -240.112804)
		(end 364.135416 -240.113566)
		(width 0.1143)
		(layer "In11.Cu")
		(net "P5E_CPU0_G3_RX_DP<11>")
	)
	(segment
		(start 364.135416 -236.873542)
		(end 364.16361 -236.889798)
		(width 0.1143)
		(layer "In11.Cu")
		(net "P5E_CPU0_G3_RX_DP<11>")
	)
	(segment
		(start 360.06532 -207.258666)
		(end 364.75797 -215.161622)
		(width 0.14224)
		(layer "In11.Cu")
		(net "P5E_CPU0_G3_RX_DP<11>")
	)
	(segment
		(start 364.130844 -240.111026)
		(end 364.13186 -240.111534)
		(width 0.1143)
		(layer "In11.Cu")
		(net "P5E_CPU0_G3_RX_DP<11>")
	)
	(segment
		(start 364.137194 -234.273598)
		(end 364.136178 -234.274106)
		(width 0.1143)
		(layer "In11.Cu")
		(net "P5E_CPU0_G3_RX_DP<11>")
	)
	(segment
		(start 365.069374 -222.290132)
		(end 365.070898 -222.291148)
		(width 0.1143)
		(layer "In11.Cu")
		(net "P5E_CPU0_G3_RX_DP<11>")
	)
	(segment
		(start 364.132622 -232.011982)
		(end 364.133892 -232.012744)
		(width 0.1143)
		(layer "In11.Cu")
		(net "P5E_CPU0_G3_RX_DP<11>")
	)
	(segment
		(start 401.00631 -11.113262)
		(end 399.764504 -17.356074)
		(width 0.14224)
		(layer "In11.Cu")
		(net "P5E_CPU0_G3_RX_DP<11>")
	)
	(segment
		(start 364.132622 -240.112042)
		(end 364.133892 -240.112804)
		(width 0.1143)
		(layer "In11.Cu")
		(net "P5E_CPU0_G3_RX_DP<11>")
	)
	(segment
		(start 364.165388 -229.397052)
		(end 364.13186 -229.41661)
		(width 0.1143)
		(layer "In11.Cu")
		(net "P5E_CPU0_G3_RX_DP<11>")
	)
	(segment
		(start 364.133892 -244.97284)
		(end 364.135416 -244.973602)
		(width 0.1143)
		(layer "In11.Cu")
		(net "P5E_CPU0_G3_RX_DP<11>")
	)
	(segment
		(start 364.123732 -236.866938)
		(end 364.12932 -236.869986)
		(width 0.1143)
		(layer "In11.Cu")
		(net "P5E_CPU0_G3_RX_DP<11>")
	)
	(segment
		(start 364.132622 -233.631994)
		(end 364.133892 -233.632756)
		(width 0.1143)
		(layer "In11.Cu")
		(net "P5E_CPU0_G3_RX_DP<11>")
	)
	(segment
		(start 364.13186 -230.391716)
		(end 364.16361 -230.410004)
		(width 0.1143)
		(layer "In11.Cu")
		(net "P5E_CPU0_G3_RX_DP<11>")
	)
	(segment
		(start 364.135416 -246.593614)
		(end 364.16361 -246.60987)
		(width 0.1143)
		(layer "In11.Cu")
		(net "P5E_CPU0_G3_RX_DP<11>")
	)
	(segment
		(start 364.123732 -235.246926)
		(end 364.12932 -235.249974)
		(width 0.1143)
		(layer "In11.Cu")
		(net "P5E_CPU0_G3_RX_DP<11>")
	)
	(segment
		(start 364.603792 -225.365564)
		(end 364.602522 -225.366326)
		(width 0.1143)
		(layer "In11.Cu")
		(net "P5E_CPU0_G3_RX_DP<11>")
	)
	(segment
		(start 364.12932 -239.138206)
		(end 364.124748 -239.140746)
		(width 0.1143)
		(layer "In11.Cu")
		(net "P5E_CPU0_G3_RX_DP<11>")
	)
	(segment
		(start 364.135416 -232.654602)
		(end 364.133892 -232.655364)
		(width 0.1143)
		(layer "In11.Cu")
		(net "P5E_CPU0_G3_RX_DP<11>")
	)
	(segment
		(start 364.75797 -221.054676)
		(end 364.75797 -221.083124)
		(width 0.1143)
		(layer "In11.Cu")
		(net "P5E_CPU0_G3_RX_DP<11>")
	)
	(segment
		(start 364.16361 -237.498382)
		(end 364.133892 -237.5154)
		(width 0.1143)
		(layer "In11.Cu")
		(net "P5E_CPU0_G3_RX_DP<11>")
	)
	(segment
		(start 400.442684 -19.191224)
		(end 400.413728 -19.317462)
		(width 0.14224)
		(layer "In11.Cu")
		(net "P5E_CPU0_G3_RX_DP<11>")
	)
	(segment
		(start 364.133892 -236.87278)
		(end 364.135416 -236.873542)
		(width 0.1143)
		(layer "In11.Cu")
		(net "P5E_CPU0_G3_RX_DP<11>")
	)
	(segment
		(start 364.136178 -240.754154)
		(end 364.135416 -240.754662)
		(width 0.1143)
		(layer "In11.Cu")
		(net "P5E_CPU0_G3_RX_DP<11>")
	)
	(segment
		(start 364.092744 -228.748844)
		(end 364.095538 -228.750876)
		(width 0.1143)
		(layer "In11.Cu")
		(net "P5E_CPU0_G3_RX_DP<11>")
	)
	(segment
		(start 364.132622 -243.352066)
		(end 364.133892 -243.352828)
		(width 0.1143)
		(layer "In11.Cu")
		(net "P5E_CPU0_G3_RX_DP<11>")
	)
	(segment
		(start 364.133892 -243.995448)
		(end 364.132622 -243.99621)
		(width 0.1143)
		(layer "In11.Cu")
		(net "P5E_CPU0_G3_RX_DP<11>")
	)
	(segment
		(start 364.13186 -243.996718)
		(end 364.130844 -243.997226)
		(width 0.1143)
		(layer "In11.Cu")
		(net "P5E_CPU0_G3_RX_DP<11>")
	)
	(arc
		(start 364.092744 -240.779554)
		(mid 363.849417 -241.24412)
		(end 364.092744 -241.708686)
		(width 0.1143)
		(layer "In11.Cu")
		(net "P5E_CPU0_G3_RX_DP<11>")
	)
	(arc
		(start 364.16361 -238.50981)
		(mid 364.319538 -238.814102)
		(end 364.16361 -239.118394)
		(width 0.1143)
		(layer "In11.Cu")
		(net "P5E_CPU0_G3_RX_DP<11>")
	)
	(arc
		(start 364.095538 -229.437692)
		(mid 363.914886 -229.640437)
		(end 363.849666 -229.904036)
		(width 0.1143)
		(layer "In11.Cu")
		(net "P5E_CPU0_G3_RX_DP<11>")
	)
	(arc
		(start 364.632494 -247.419368)
		(mid 364.730259 -247.522344)
		(end 364.782608 -247.654318)
		(width 0.1143)
		(layer "In11.Cu")
		(net "P5E_CPU0_G3_RX_DP<11>")
	)
	(arc
		(start 364.092744 -226.1997)
		(mid 363.849417 -226.664266)
		(end 364.092744 -227.128832)
		(width 0.1143)
		(layer "In11.Cu")
		(net "P5E_CPU0_G3_RX_DP<11>")
	)
	(arc
		(start 364.16361 -243.369846)
		(mid 364.319538 -243.674138)
		(end 364.16361 -243.97843)
		(width 0.1143)
		(layer "In11.Cu")
		(net "P5E_CPU0_G3_RX_DP<11>")
	)
	(arc
		(start 364.319566 -230.714296)
		(mid 364.278804 -230.88418)
		(end 364.165388 -231.017064)
		(width 0.1143)
		(layer "In11.Cu")
		(net "P5E_CPU0_G3_RX_DP<11>")
	)
	(arc
		(start 364.092744 -242.399566)
		(mid 363.849417 -242.864132)
		(end 364.092744 -243.328698)
		(width 0.1143)
		(layer "In11.Cu")
		(net "P5E_CPU0_G3_RX_DP<11>")
	)
	(arc
		(start 364.092744 -234.299506)
		(mid 363.849417 -234.764072)
		(end 364.092744 -235.228638)
		(width 0.1143)
		(layer "In11.Cu")
		(net "P5E_CPU0_G3_RX_DP<11>")
	)
	(arc
		(start 364.8075 -221.94647)
		(mid 364.891241 -222.12783)
		(end 365.032798 -222.268796)
		(width 0.1143)
		(layer "In11.Cu")
		(net "P5E_CPU0_G3_RX_DP<11>")
	)
	(arc
		(start 364.319566 -229.094284)
		(mid 364.278804 -229.264168)
		(end 364.165388 -229.397052)
		(width 0.1143)
		(layer "In11.Cu")
		(net "P5E_CPU0_G3_RX_DP<11>")
	)
	(arc
		(start 364.092744 -239.159542)
		(mid 363.849417 -239.624108)
		(end 364.092744 -240.088674)
		(width 0.1143)
		(layer "In11.Cu")
		(net "P5E_CPU0_G3_RX_DP<11>")
	)
	(arc
		(start 365.032798 -222.959676)
		(mid 364.789471 -223.424242)
		(end 365.032798 -223.888808)
		(width 0.1143)
		(layer "In11.Cu")
		(net "P5E_CPU0_G3_RX_DP<11>")
	)
	(arc
		(start 365.102394 -223.929448)
		(mid 365.259371 -224.234248)
		(end 365.102394 -224.539048)
		(width 0.1143)
		(layer "In11.Cu")
		(net "P5E_CPU0_G3_RX_DP<11>")
	)
	(arc
		(start 364.789466 -225.044254)
		(mid 364.748211 -225.215225)
		(end 364.63351 -225.348546)
		(width 0.1143)
		(layer "In11.Cu")
		(net "P5E_CPU0_G3_RX_DP<11>")
	)
	(arc
		(start 364.16361 -228.789992)
		(mid 364.278286 -228.923326)
		(end 364.319566 -229.094284)
		(width 0.1143)
		(layer "In11.Cu")
		(net "P5E_CPU0_G3_RX_DP<11>")
	)
	(arc
		(start 365.259366 -222.614236)
		(mid 365.217817 -222.785658)
		(end 365.102394 -222.919036)
		(width 0.1143)
		(layer "In11.Cu")
		(net "P5E_CPU0_G3_RX_DP<11>")
	)
	(arc
		(start 364.789466 -221.80423)
		(mid 364.793967 -221.875922)
		(end 364.8075 -221.94647)
		(width 0.1143)
		(layer "In11.Cu")
		(net "P5E_CPU0_G3_RX_DP<11>")
	)
	(arc
		(start 364.16361 -241.749834)
		(mid 364.319538 -242.054126)
		(end 364.16361 -242.358418)
		(width 0.1143)
		(layer "In11.Cu")
		(net "P5E_CPU0_G3_RX_DP<11>")
	)
	(arc
		(start 364.16361 -246.60987)
		(mid 364.278286 -246.743204)
		(end 364.319566 -246.914162)
		(width 0.1143)
		(layer "In11.Cu")
		(net "P5E_CPU0_G3_RX_DP<11>")
	)
	(arc
		(start 364.16361 -244.989858)
		(mid 364.319538 -245.29415)
		(end 364.16361 -245.598442)
		(width 0.1143)
		(layer "In11.Cu")
		(net "P5E_CPU0_G3_RX_DP<11>")
	)
	(arc
		(start 365.032798 -224.579688)
		(mid 364.853985 -224.782038)
		(end 364.789466 -225.044254)
		(width 0.1143)
		(layer "In11.Cu")
		(net "P5E_CPU0_G3_RX_DP<11>")
	)
	(arc
		(start 364.092744 -245.63959)
		(mid 363.849417 -246.104156)
		(end 364.092744 -246.568722)
		(width 0.1143)
		(layer "In11.Cu")
		(net "P5E_CPU0_G3_RX_DP<11>")
	)
	(arc
		(start 364.319566 -246.914162)
		(mid 364.384081 -247.176381)
		(end 364.562898 -247.378728)
		(width 0.1143)
		(layer "In11.Cu")
		(net "P5E_CPU0_G3_RX_DP<11>")
	)
	(arc
		(start 364.092744 -231.059482)
		(mid 363.849417 -231.524048)
		(end 364.092744 -231.988614)
		(width 0.1143)
		(layer "In11.Cu")
		(net "P5E_CPU0_G3_RX_DP<11>")
	)
	(arc
		(start 365.103664 -222.309944)
		(mid 365.21834 -222.443278)
		(end 365.25962 -222.614236)
		(width 0.1143)
		(layer "In11.Cu")
		(net "P5E_CPU0_G3_RX_DP<11>")
	)
	(arc
		(start 364.16361 -240.129822)
		(mid 364.319538 -240.434114)
		(end 364.16361 -240.738406)
		(width 0.1143)
		(layer "In11.Cu")
		(net "P5E_CPU0_G3_RX_DP<11>")
	)
	(arc
		(start 364.319312 -225.85426)
		(mid 364.277763 -226.025682)
		(end 364.16234 -226.15906)
		(width 0.1143)
		(layer "In11.Cu")
		(net "P5E_CPU0_G3_RX_DP<11>")
	)
	(arc
		(start 364.562644 -225.389694)
		(mid 364.383831 -225.592044)
		(end 364.319312 -225.85426)
		(width 0.1143)
		(layer "In11.Cu")
		(net "P5E_CPU0_G3_RX_DP<11>")
	)
	(arc
		(start 364.16361 -236.889798)
		(mid 364.319538 -237.19409)
		(end 364.16361 -237.498382)
		(width 0.1143)
		(layer "In11.Cu")
		(net "P5E_CPU0_G3_RX_DP<11>")
	)
	(arc
		(start 364.092744 -232.679494)
		(mid 363.849417 -233.14406)
		(end 364.092744 -233.608626)
		(width 0.1143)
		(layer "In11.Cu")
		(net "P5E_CPU0_G3_RX_DP<11>")
	)
	(arc
		(start 364.092744 -235.919518)
		(mid 363.849417 -236.384084)
		(end 364.092744 -236.84865)
		(width 0.1143)
		(layer "In11.Cu")
		(net "P5E_CPU0_G3_RX_DP<11>")
	)
	(arc
		(start 364.16361 -235.269786)
		(mid 364.319538 -235.574078)
		(end 364.16361 -235.87837)
		(width 0.1143)
		(layer "In11.Cu")
		(net "P5E_CPU0_G3_RX_DP<11>")
	)
	(arc
		(start 364.092744 -244.019578)
		(mid 363.849417 -244.484144)
		(end 364.092744 -244.94871)
		(width 0.1143)
		(layer "In11.Cu")
		(net "P5E_CPU0_G3_RX_DP<11>")
	)
	(arc
		(start 364.092744 -227.819712)
		(mid 363.849417 -228.284278)
		(end 364.092744 -228.748844)
		(width 0.1143)
		(layer "In11.Cu")
		(net "P5E_CPU0_G3_RX_DP<11>")
	)
	(arc
		(start 364.16361 -230.410004)
		(mid 364.278286 -230.543338)
		(end 364.319566 -230.714296)
		(width 0.1143)
		(layer "In11.Cu")
		(net "P5E_CPU0_G3_RX_DP<11>")
	)
	(arc
		(start 364.092744 -237.53953)
		(mid 363.849417 -238.004096)
		(end 364.092744 -238.468662)
		(width 0.1143)
		(layer "In11.Cu")
		(net "P5E_CPU0_G3_RX_DP<11>")
	)
	(arc
		(start 363.849412 -229.904036)
		(mid 363.914648 -230.167627)
		(end 364.095284 -230.37038)
		(width 0.1143)
		(layer "In11.Cu")
		(net "P5E_CPU0_G3_RX_DP<11>")
	)
	(arc
		(start 364.16361 -232.029762)
		(mid 364.319538 -232.334054)
		(end 364.16361 -232.638346)
		(width 0.1143)
		(layer "In11.Cu")
		(net "P5E_CPU0_G3_RX_DP<11>")
	)
	(arc
		(start 364.16234 -227.169472)
		(mid 364.319317 -227.474272)
		(end 364.16234 -227.779072)
		(width 0.1143)
		(layer "In11.Cu")
		(net "P5E_CPU0_G3_RX_DP<11>")
	)
	(arc
		(start 364.16361 -233.649774)
		(mid 364.319538 -233.954066)
		(end 364.16361 -234.258358)
		(width 0.1143)
		(layer "In11.Cu")
		(net "P5E_CPU0_G3_RX_DP<11>")
	)
	(segment
		(start 402.78558 -5.228844)
		(end 402.78558 -7.57047)
		(width 0.12954)
		(layer "F.Cu")
		(net "P5E_CPU0_G3_RX_DP<10>")
	)
	(segment
		(start 363.947964 -244.750082)
		(end 364.414816 -244.484144)
		(width 0.12954)
		(layer "F.Cu")
		(net "P5E_CPU0_G3_RX_DP<10>")
	)
	(segment
		(start 402.646896 -7.709154)
		(end 402.646896 -8.320024)
		(width 0.12954)
		(layer "F.Cu")
		(net "P5E_CPU0_G3_RX_DP<10>")
	)
	(segment
		(start 402.78558 -7.57047)
		(end 402.646896 -7.709154)
		(width 0.12954)
		(layer "F.Cu")
		(net "P5E_CPU0_G3_RX_DP<10>")
	)
	(segment
		(start 402.52015 -4.963414)
		(end 402.78558 -5.228844)
		(width 0.12954)
		(layer "F.Cu")
		(net "P5E_CPU0_G3_RX_DP<10>")
	)
	(segment
		(start 312.658506 -148.399754)
		(end 310.52389 -160.550098)
		(width 0.14224)
		(layer "In11.Cu")
		(net "P5E_CPU0_G3_RX_DP<10>")
	)
	(segment
		(start 365.963708 -223.882966)
		(end 365.972344 -223.889062)
		(width 0.1143)
		(layer "In11.Cu")
		(net "P5E_CPU0_G3_RX_DP<10>")
	)
	(segment
		(start 365.540036 -225.36785)
		(end 365.538512 -225.368866)
		(width 0.1143)
		(layer "In11.Cu")
		(net "P5E_CPU0_G3_RX_DP<10>")
	)
	(segment
		(start 365.065564 -237.520226)
		(end 365.03356 -237.539022)
		(width 0.1143)
		(layer "In11.Cu")
		(net "P5E_CPU0_G3_RX_DP<10>")
	)
	(segment
		(start 365.032798 -238.468662)
		(end 365.050832 -238.47933)
		(width 0.1143)
		(layer "In11.Cu")
		(net "P5E_CPU0_G3_RX_DP<10>")
	)
	(segment
		(start 365.06658 -237.519718)
		(end 365.065564 -237.520226)
		(width 0.1143)
		(layer "In11.Cu")
		(net "P5E_CPU0_G3_RX_DP<10>")
	)
	(segment
		(start 365.032798 -240.088674)
		(end 365.050832 -240.099342)
		(width 0.1143)
		(layer "In11.Cu")
		(net "P5E_CPU0_G3_RX_DP<10>")
	)
	(segment
		(start 365.071914 -243.351558)
		(end 365.103664 -243.369846)
		(width 0.1143)
		(layer "In11.Cu")
		(net "P5E_CPU0_G3_RX_DP<10>")
	)
	(segment
		(start 319.177416 -130.418078)
		(end 312.658506 -148.399754)
		(width 0.14224)
		(layer "In11.Cu")
		(net "P5E_CPU0_G3_RX_DP<10>")
	)
	(segment
		(start 365.071914 -227.796852)
		(end 365.032798 -227.819712)
		(width 0.1143)
		(layer "In11.Cu")
		(net "P5E_CPU0_G3_RX_DP<10>")
	)
	(segment
		(start 366.043464 -222.918528)
		(end 366.042702 -222.919036)
		(width 0.1143)
		(layer "In11.Cu")
		(net "P5E_CPU0_G3_RX_DP<10>")
	)
	(segment
		(start 364.795562 -244.40134)
		(end 364.712758 -244.484144)
		(width 0.1143)
		(layer "In11.Cu")
		(net "P5E_CPU0_G3_RX_DP<10>")
	)
	(segment
		(start 365.06658 -240.759742)
		(end 365.065564 -240.76025)
		(width 0.1143)
		(layer "In11.Cu")
		(net "P5E_CPU0_G3_RX_DP<10>")
	)
	(segment
		(start 365.068866 -235.898436)
		(end 365.067342 -235.899198)
		(width 0.1143)
		(layer "In11.Cu")
		(net "P5E_CPU0_G3_RX_DP<10>")
	)
	(segment
		(start 365.035338 -230.37038)
		(end 365.070898 -230.391208)
		(width 0.1143)
		(layer "In11.Cu")
		(net "P5E_CPU0_G3_RX_DP<10>")
	)
	(segment
		(start 366.04067 -223.928178)
		(end 366.042448 -223.929448)
		(width 0.1143)
		(layer "In11.Cu")
		(net "P5E_CPU0_G3_RX_DP<10>")
	)
	(segment
		(start 316.872112 -171.856654)
		(end 322.32727 -175.12665)
		(width 0.14224)
		(layer "In11.Cu")
		(net "P5E_CPU0_G3_RX_DP<10>")
	)
	(segment
		(start 365.99495 -222.28175)
		(end 366.042448 -222.309436)
		(width 0.1143)
		(layer "In11.Cu")
		(net "P5E_CPU0_G3_RX_DP<10>")
	)
	(segment
		(start 312.675778 -167.659558)
		(end 316.872112 -171.856654)
		(width 0.14224)
		(layer "In11.Cu")
		(net "P5E_CPU0_G3_RX_DP<10>")
	)
	(segment
		(start 366.0394 -222.921068)
		(end 366.014 -222.938086)
		(width 0.1143)
		(layer "In11.Cu")
		(net "P5E_CPU0_G3_RX_DP<10>")
	)
	(segment
		(start 365.051086 -238.47933)
		(end 365.072422 -238.491776)
		(width 0.1143)
		(layer "In11.Cu")
		(net "P5E_CPU0_G3_RX_DP<10>")
	)
	(segment
		(start 365.972344 -223.889062)
		(end 366.04067 -223.928178)
		(width 0.1143)
		(layer "In11.Cu")
		(net "P5E_CPU0_G3_RX_DP<10>")
	)
	(segment
		(start 402.52015 -4.963414)
		(end 402.81098 -5.254244)
		(width 0.14224)
		(layer "In11.Cu")
		(net "P5E_CPU0_G3_RX_DP<10>")
	)
	(segment
		(start 365.538512 -225.368866)
		(end 365.505492 -225.387916)
		(width 0.1143)
		(layer "In11.Cu")
		(net "P5E_CPU0_G3_RX_DP<10>")
	)
	(segment
		(start 365.051086 -241.719354)
		(end 365.072422 -241.7318)
		(width 0.1143)
		(layer "In11.Cu")
		(net "P5E_CPU0_G3_RX_DP<10>")
	)
	(segment
		(start 360.798364 -206.653638)
		(end 360.798618 -206.653638)
		(width 0.14224)
		(layer "In11.Cu")
		(net "P5E_CPU0_G3_RX_DP<10>")
	)
	(segment
		(start 365.06658 -239.13973)
		(end 365.065564 -239.140238)
		(width 0.1143)
		(layer "In11.Cu")
		(net "P5E_CPU0_G3_RX_DP<10>")
	)
	(segment
		(start 365.071914 -230.391716)
		(end 365.072676 -230.392224)
		(width 0.1143)
		(layer "In11.Cu")
		(net "P5E_CPU0_G3_RX_DP<10>")
	)
	(segment
		(start 312.574686 -167.508428)
		(end 312.675778 -167.659558)
		(width 0.14224)
		(layer "In11.Cu")
		(net "P5E_CPU0_G3_RX_DP<10>")
	)
	(segment
		(start 365.079788 -237.512098)
		(end 365.067342 -237.51921)
		(width 0.1143)
		(layer "In11.Cu")
		(net "P5E_CPU0_G3_RX_DP<10>")
	)
	(segment
		(start 365.067342 -240.759234)
		(end 365.06658 -240.759742)
		(width 0.1143)
		(layer "In11.Cu")
		(net "P5E_CPU0_G3_RX_DP<10>")
	)
	(segment
		(start 365.050832 -240.099342)
		(end 365.051086 -240.099342)
		(width 0.1143)
		(layer "In11.Cu")
		(net "P5E_CPU0_G3_RX_DP<10>")
	)
	(segment
		(start 365.032798 -241.708686)
		(end 365.050832 -241.719354)
		(width 0.1143)
		(layer "In11.Cu")
		(net "P5E_CPU0_G3_RX_DP<10>")
	)
	(segment
		(start 365.040672 -235.914692)
		(end 365.03991 -235.9152)
		(width 0.1143)
		(layer "In11.Cu")
		(net "P5E_CPU0_G3_RX_DP<10>")
	)
	(segment
		(start 365.065564 -240.76025)
		(end 365.03356 -240.779046)
		(width 0.1143)
		(layer "In11.Cu")
		(net "P5E_CPU0_G3_RX_DP<10>")
	)
	(segment
		(start 365.071914 -232.011474)
		(end 365.103664 -232.029762)
		(width 0.1143)
		(layer "In11.Cu")
		(net "P5E_CPU0_G3_RX_DP<10>")
	)
	(segment
		(start 365.102648 -226.15906)
		(end 365.071914 -226.17684)
		(width 0.1143)
		(layer "In11.Cu")
		(net "P5E_CPU0_G3_RX_DP<10>")
	)
	(segment
		(start 365.749078 -221.128844)
		(end 365.749078 -221.308676)
		(width 0.1143)
		(layer "In11.Cu")
		(net "P5E_CPU0_G3_RX_DP<10>")
	)
	(segment
		(start 365.032798 -243.328698)
		(end 365.071914 -243.351558)
		(width 0.1143)
		(layer "In11.Cu")
		(net "P5E_CPU0_G3_RX_DP<10>")
	)
	(segment
		(start 403.25548 -17.708626)
		(end 403.253702 -17.71269)
		(width 0.14224)
		(layer "In11.Cu")
		(net "P5E_CPU0_G3_RX_DP<10>")
	)
	(segment
		(start 310.52389 -162.55619)
		(end 312.574686 -167.508428)
		(width 0.14224)
		(layer "In11.Cu")
		(net "P5E_CPU0_G3_RX_DP<10>")
	)
	(segment
		(start 365.103664 -232.638346)
		(end 365.072676 -232.656126)
		(width 0.1143)
		(layer "In11.Cu")
		(net "P5E_CPU0_G3_RX_DP<10>")
	)
	(segment
		(start 365.749078 -221.308676)
		(end 365.72952 -221.328234)
		(width 0.1143)
		(layer "In11.Cu")
		(net "P5E_CPU0_G3_RX_DP<10>")
	)
	(segment
		(start 365.072676 -232.656126)
		(end 365.071914 -232.656634)
		(width 0.1143)
		(layer "In11.Cu")
		(net "P5E_CPU0_G3_RX_DP<10>")
	)
	(segment
		(start 365.051086 -236.859318)
		(end 365.072422 -236.871764)
		(width 0.1143)
		(layer "In11.Cu")
		(net "P5E_CPU0_G3_RX_DP<10>")
	)
	(segment
		(start 365.703358 -221.054676)
		(end 365.703358 -221.083124)
		(width 0.1143)
		(layer "In11.Cu")
		(net "P5E_CPU0_G3_RX_DP<10>")
	)
	(segment
		(start 365.06658 -242.379754)
		(end 365.065564 -242.380262)
		(width 0.1143)
		(layer "In11.Cu")
		(net "P5E_CPU0_G3_RX_DP<10>")
	)
	(segment
		(start 402.989288 -18.229834)
		(end 402.988526 -18.231612)
		(width 0.14224)
		(layer "In11.Cu")
		(net "P5E_CPU0_G3_RX_DP<10>")
	)
	(segment
		(start 365.071914 -243.996718)
		(end 365.032798 -244.019578)
		(width 0.1143)
		(layer "In11.Cu")
		(net "P5E_CPU0_G3_RX_DP<10>")
	)
	(segment
		(start 365.103664 -234.258358)
		(end 365.071914 -234.276646)
		(width 0.1143)
		(layer "In11.Cu")
		(net "P5E_CPU0_G3_RX_DP<10>")
	)
	(segment
		(start 403.211538 -17.815052)
		(end 402.989288 -18.229834)
		(width 0.14224)
		(layer "In11.Cu")
		(net "P5E_CPU0_G3_RX_DP<10>")
	)
	(segment
		(start 365.035592 -227.130864)
		(end 365.071914 -227.151692)
		(width 0.1143)
		(layer "In11.Cu")
		(net "P5E_CPU0_G3_RX_DP<10>")
	)
	(segment
		(start 394.064744 -31.980886)
		(end 321.69989 -125.827028)
		(width 0.14224)
		(layer "In11.Cu")
		(net "P5E_CPU0_G3_RX_DP<10>")
	)
	(segment
		(start 365.071914 -228.771704)
		(end 365.072676 -228.772212)
		(width 0.1143)
		(layer "In11.Cu")
		(net "P5E_CPU0_G3_RX_DP<10>")
	)
	(segment
		(start 366.012984 -222.938594)
		(end 365.997998 -222.947484)
		(width 0.1143)
		(layer "In11.Cu")
		(net "P5E_CPU0_G3_RX_DP<10>")
	)
	(segment
		(start 365.997998 -222.947484)
		(end 365.97717 -222.956882)
		(width 0.1143)
		(layer "In11.Cu")
		(net "P5E_CPU0_G3_RX_DP<10>")
	)
	(segment
		(start 365.97717 -222.956882)
		(end 365.972598 -222.959422)
		(width 0.1143)
		(layer "In11.Cu")
		(net "P5E_CPU0_G3_RX_DP<10>")
	)
	(segment
		(start 321.69989 -125.827028)
		(end 319.177416 -130.418078)
		(width 0.14224)
		(layer "In11.Cu")
		(net "P5E_CPU0_G3_RX_DP<10>")
	)
	(segment
		(start 365.541814 -225.366834)
		(end 365.540036 -225.36785)
		(width 0.1143)
		(layer "In11.Cu")
		(net "P5E_CPU0_G3_RX_DP<10>")
	)
	(segment
		(start 365.103664 -243.97843)
		(end 365.071914 -243.996718)
		(width 0.1143)
		(layer "In11.Cu")
		(net "P5E_CPU0_G3_RX_DP<10>")
	)
	(segment
		(start 365.065564 -239.140238)
		(end 365.03356 -239.159034)
		(width 0.1143)
		(layer "In11.Cu")
		(net "P5E_CPU0_G3_RX_DP<10>")
	)
	(segment
		(start 365.070898 -232.657142)
		(end 365.032798 -232.679494)
		(width 0.1143)
		(layer "In11.Cu")
		(net "P5E_CPU0_G3_RX_DP<10>")
	)
	(segment
		(start 365.703358 -221.083124)
		(end 365.749078 -221.128844)
		(width 0.1143)
		(layer "In11.Cu")
		(net "P5E_CPU0_G3_RX_DP<10>")
	)
	(segment
		(start 365.079788 -240.752122)
		(end 365.067342 -240.759234)
		(width 0.1143)
		(layer "In11.Cu")
		(net "P5E_CPU0_G3_RX_DP<10>")
	)
	(segment
		(start 365.051086 -235.239306)
		(end 365.072422 -235.251752)
		(width 0.1143)
		(layer "In11.Cu")
		(net "P5E_CPU0_G3_RX_DP<10>")
	)
	(segment
		(start 402.988526 -18.231612)
		(end 394.064744 -31.980886)
		(width 0.14224)
		(layer "In11.Cu")
		(net "P5E_CPU0_G3_RX_DP<10>")
	)
	(segment
		(start 365.032798 -236.84865)
		(end 365.050832 -236.859318)
		(width 0.1143)
		(layer "In11.Cu")
		(net "P5E_CPU0_G3_RX_DP<10>")
	)
	(segment
		(start 365.032798 -231.988614)
		(end 365.071914 -232.011474)
		(width 0.1143)
		(layer "In11.Cu")
		(net "P5E_CPU0_G3_RX_DP<10>")
	)
	(segment
		(start 310.52389 -160.550098)
		(end 310.52389 -162.55619)
		(width 0.14224)
		(layer "In11.Cu")
		(net "P5E_CPU0_G3_RX_DP<10>")
	)
	(segment
		(start 366.042702 -222.919036)
		(end 366.0394 -222.921068)
		(width 0.1143)
		(layer "In11.Cu")
		(net "P5E_CPU0_G3_RX_DP<10>")
	)
	(segment
		(start 365.071914 -233.631486)
		(end 365.103664 -233.649774)
		(width 0.1143)
		(layer "In11.Cu")
		(net "P5E_CPU0_G3_RX_DP<10>")
	)
	(segment
		(start 365.073946 -230.392986)
		(end 365.07547 -230.393748)
		(width 0.1143)
		(layer "In11.Cu")
		(net "P5E_CPU0_G3_RX_DP<10>")
	)
	(segment
		(start 365.103664 -227.778564)
		(end 365.071914 -227.796852)
		(width 0.1143)
		(layer "In11.Cu")
		(net "P5E_CPU0_G3_RX_DP<10>")
	)
	(segment
		(start 365.105442 -229.397052)
		(end 365.032798 -229.43947)
		(width 0.1143)
		(layer "In11.Cu")
		(net "P5E_CPU0_G3_RX_DP<10>")
	)
	(segment
		(start 402.81098 -5.254244)
		(end 402.81098 -11.822684)
		(width 0.14224)
		(layer "In11.Cu")
		(net "P5E_CPU0_G3_RX_DP<10>")
	)
	(segment
		(start 365.032798 -228.748844)
		(end 365.069374 -228.77018)
		(width 0.1143)
		(layer "In11.Cu")
		(net "P5E_CPU0_G3_RX_DP<10>")
	)
	(segment
		(start 365.032798 -227.128832)
		(end 365.035592 -227.130864)
		(width 0.1143)
		(layer "In11.Cu")
		(net "P5E_CPU0_G3_RX_DP<10>")
	)
	(segment
		(start 365.050832 -238.47933)
		(end 365.051086 -238.47933)
		(width 0.1143)
		(layer "In11.Cu")
		(net "P5E_CPU0_G3_RX_DP<10>")
	)
	(segment
		(start 365.070898 -230.391208)
		(end 365.071914 -230.391716)
		(width 0.1143)
		(layer "In11.Cu")
		(net "P5E_CPU0_G3_RX_DP<10>")
	)
	(segment
		(start 365.03991 -235.9152)
		(end 365.03356 -235.91901)
		(width 0.1143)
		(layer "In11.Cu")
		(net "P5E_CPU0_G3_RX_DP<10>")
	)
	(segment
		(start 365.06658 -235.899706)
		(end 365.040672 -235.914692)
		(width 0.1143)
		(layer "In11.Cu")
		(net "P5E_CPU0_G3_RX_DP<10>")
	)
	(segment
		(start 365.573564 -225.348546)
		(end 365.541814 -225.366834)
		(width 0.1143)
		(layer "In11.Cu")
		(net "P5E_CPU0_G3_RX_DP<10>")
	)
	(segment
		(start 360.798618 -206.653638)
		(end 365.703358 -214.914988)
		(width 0.14224)
		(layer "In11.Cu")
		(net "P5E_CPU0_G3_RX_DP<10>")
	)
	(segment
		(start 364.712758 -244.484144)
		(end 364.414816 -244.484144)
		(width 0.1143)
		(layer "In11.Cu")
		(net "P5E_CPU0_G3_RX_DP<10>")
	)
	(segment
		(start 365.050832 -241.719354)
		(end 365.051086 -241.719354)
		(width 0.1143)
		(layer "In11.Cu")
		(net "P5E_CPU0_G3_RX_DP<10>")
	)
	(segment
		(start 403.253702 -17.71269)
		(end 403.211538 -17.815052)
		(width 0.14224)
		(layer "In11.Cu")
		(net "P5E_CPU0_G3_RX_DP<10>")
	)
	(segment
		(start 365.079788 -242.372134)
		(end 365.067342 -242.379246)
		(width 0.1143)
		(layer "In11.Cu")
		(net "P5E_CPU0_G3_RX_DP<10>")
	)
	(segment
		(start 365.971836 -222.268542)
		(end 365.99495 -222.28175)
		(width 0.1143)
		(layer "In11.Cu")
		(net "P5E_CPU0_G3_RX_DP<10>")
	)
	(segment
		(start 365.071914 -226.17684)
		(end 365.032798 -226.1997)
		(width 0.1143)
		(layer "In11.Cu")
		(net "P5E_CPU0_G3_RX_DP<10>")
	)
	(segment
		(start 366.014 -222.938086)
		(end 366.012984 -222.938594)
		(width 0.1143)
		(layer "In11.Cu")
		(net "P5E_CPU0_G3_RX_DP<10>")
	)
	(segment
		(start 322.32727 -175.12665)
		(end 360.798364 -206.653638)
		(width 0.14224)
		(layer "In11.Cu")
		(net "P5E_CPU0_G3_RX_DP<10>")
	)
	(segment
		(start 365.050832 -236.859318)
		(end 365.051086 -236.859318)
		(width 0.1143)
		(layer "In11.Cu")
		(net "P5E_CPU0_G3_RX_DP<10>")
	)
	(segment
		(start 365.067342 -242.379246)
		(end 365.06658 -242.379754)
		(width 0.1143)
		(layer "In11.Cu")
		(net "P5E_CPU0_G3_RX_DP<10>")
	)
	(segment
		(start 365.079788 -239.13211)
		(end 365.067342 -239.139222)
		(width 0.1143)
		(layer "In11.Cu")
		(net "P5E_CPU0_G3_RX_DP<10>")
	)
	(segment
		(start 402.81098 -11.822684)
		(end 403.25548 -16.336518)
		(width 0.14224)
		(layer "In11.Cu")
		(net "P5E_CPU0_G3_RX_DP<10>")
	)
	(segment
		(start 365.72952 -221.328234)
		(end 365.72952 -221.80423)
		(width 0.1143)
		(layer "In11.Cu")
		(net "P5E_CPU0_G3_RX_DP<10>")
	)
	(segment
		(start 365.032798 -235.228638)
		(end 365.050832 -235.239306)
		(width 0.1143)
		(layer "In11.Cu")
		(net "P5E_CPU0_G3_RX_DP<10>")
	)
	(segment
		(start 366.042448 -224.539048)
		(end 365.972852 -224.579688)
		(width 0.1143)
		(layer "In11.Cu")
		(net "P5E_CPU0_G3_RX_DP<10>")
	)
	(segment
		(start 365.067342 -237.51921)
		(end 365.06658 -237.519718)
		(width 0.1143)
		(layer "In11.Cu")
		(net "P5E_CPU0_G3_RX_DP<10>")
	)
	(segment
		(start 365.079788 -235.892086)
		(end 365.068866 -235.898436)
		(width 0.1143)
		(layer "In11.Cu")
		(net "P5E_CPU0_G3_RX_DP<10>")
	)
	(segment
		(start 365.032798 -233.608626)
		(end 365.071914 -233.631486)
		(width 0.1143)
		(layer "In11.Cu")
		(net "P5E_CPU0_G3_RX_DP<10>")
	)
	(segment
		(start 365.050832 -235.239306)
		(end 365.051086 -235.239306)
		(width 0.1143)
		(layer "In11.Cu")
		(net "P5E_CPU0_G3_RX_DP<10>")
	)
	(segment
		(start 365.067342 -235.899198)
		(end 365.06658 -235.899706)
		(width 0.1143)
		(layer "In11.Cu")
		(net "P5E_CPU0_G3_RX_DP<10>")
	)
	(segment
		(start 365.972598 -222.959422)
		(end 365.96447 -222.965264)
		(width 0.1143)
		(layer "In11.Cu")
		(net "P5E_CPU0_G3_RX_DP<10>")
	)
	(segment
		(start 365.072676 -228.772212)
		(end 365.073184 -228.772466)
		(width 0.1143)
		(layer "In11.Cu")
		(net "P5E_CPU0_G3_RX_DP<10>")
	)
	(segment
		(start 365.065564 -242.380262)
		(end 365.03356 -242.399058)
		(width 0.1143)
		(layer "In11.Cu")
		(net "P5E_CPU0_G3_RX_DP<10>")
	)
	(segment
		(start 365.703358 -214.914988)
		(end 365.703358 -221.054676)
		(width 0.14224)
		(layer "In11.Cu")
		(net "P5E_CPU0_G3_RX_DP<10>")
	)
	(segment
		(start 365.051086 -240.099342)
		(end 365.072422 -240.111788)
		(width 0.1143)
		(layer "In11.Cu")
		(net "P5E_CPU0_G3_RX_DP<10>")
	)
	(segment
		(start 365.07547 -230.393748)
		(end 365.103664 -230.410004)
		(width 0.1143)
		(layer "In11.Cu")
		(net "P5E_CPU0_G3_RX_DP<10>")
	)
	(segment
		(start 365.070898 -228.771196)
		(end 365.071914 -228.771704)
		(width 0.1143)
		(layer "In11.Cu")
		(net "P5E_CPU0_G3_RX_DP<10>")
	)
	(segment
		(start 365.069374 -228.77018)
		(end 365.070898 -228.771196)
		(width 0.1143)
		(layer "In11.Cu")
		(net "P5E_CPU0_G3_RX_DP<10>")
	)
	(segment
		(start 365.067342 -239.139222)
		(end 365.06658 -239.13973)
		(width 0.1143)
		(layer "In11.Cu")
		(net "P5E_CPU0_G3_RX_DP<10>")
	)
	(segment
		(start 365.036354 -234.296966)
		(end 365.03356 -234.298998)
		(width 0.1143)
		(layer "In11.Cu")
		(net "P5E_CPU0_G3_RX_DP<10>")
	)
	(segment
		(start 403.25548 -16.336518)
		(end 403.25548 -17.708626)
		(width 0.14224)
		(layer "In11.Cu")
		(net "P5E_CPU0_G3_RX_DP<10>")
	)
	(segment
		(start 365.071914 -232.656634)
		(end 365.070898 -232.657142)
		(width 0.1143)
		(layer "In11.Cu")
		(net "P5E_CPU0_G3_RX_DP<10>")
	)
	(segment
		(start 365.082074 -231.03078)
		(end 365.032798 -231.059482)
		(width 0.1143)
		(layer "In11.Cu")
		(net "P5E_CPU0_G3_RX_DP<10>")
	)
	(segment
		(start 365.071914 -234.276646)
		(end 365.036354 -234.296966)
		(width 0.1143)
		(layer "In11.Cu")
		(net "P5E_CPU0_G3_RX_DP<10>")
	)
	(segment
		(start 365.072676 -230.392224)
		(end 365.073946 -230.392986)
		(width 0.1143)
		(layer "In11.Cu")
		(net "P5E_CPU0_G3_RX_DP<10>")
	)
	(segment
		(start 365.071914 -227.151692)
		(end 365.103664 -227.16998)
		(width 0.1143)
		(layer "In11.Cu")
		(net "P5E_CPU0_G3_RX_DP<10>")
	)
	(arc
		(start 365.103664 -232.029762)
		(mid 365.252761 -232.334054)
		(end 365.103664 -232.638346)
		(width 0.1143)
		(layer "In11.Cu")
		(net "P5E_CPU0_G3_RX_DP<10>")
	)
	(arc
		(start 365.032798 -242.399566)
		(mid 364.789471 -242.864132)
		(end 365.032798 -243.328698)
		(width 0.1143)
		(layer "In11.Cu")
		(net "P5E_CPU0_G3_RX_DP<10>")
	)
	(arc
		(start 366.042448 -222.309436)
		(mid 366.157875 -222.442812)
		(end 366.19942 -222.614236)
		(width 0.1143)
		(layer "In11.Cu")
		(net "P5E_CPU0_G3_RX_DP<10>")
	)
	(arc
		(start 365.032798 -239.159542)
		(mid 364.789471 -239.624108)
		(end 365.032798 -240.088674)
		(width 0.1143)
		(layer "In11.Cu")
		(net "P5E_CPU0_G3_RX_DP<10>")
	)
	(arc
		(start 365.072422 -236.871764)
		(mid 365.257942 -237.189821)
		(end 365.079788 -237.512098)
		(width 0.1143)
		(layer "In11.Cu")
		(net "P5E_CPU0_G3_RX_DP<10>")
	)
	(arc
		(start 365.25962 -225.865436)
		(mid 365.215556 -226.030659)
		(end 365.102648 -226.15906)
		(width 0.1143)
		(layer "In11.Cu")
		(net "P5E_CPU0_G3_RX_DP<10>")
	)
	(arc
		(start 365.25962 -230.714296)
		(mid 365.21394 -230.896707)
		(end 365.082074 -231.03078)
		(width 0.1143)
		(layer "In11.Cu")
		(net "P5E_CPU0_G3_RX_DP<10>")
	)
	(arc
		(start 365.032798 -240.779554)
		(mid 364.789471 -241.24412)
		(end 365.032798 -241.708686)
		(width 0.1143)
		(layer "In11.Cu")
		(net "P5E_CPU0_G3_RX_DP<10>")
	)
	(arc
		(start 365.972852 -224.579688)
		(mid 365.794039 -224.782038)
		(end 365.72952 -225.044254)
		(width 0.1143)
		(layer "In11.Cu")
		(net "P5E_CPU0_G3_RX_DP<10>")
	)
	(arc
		(start 366.19942 -222.614236)
		(mid 366.158165 -222.785207)
		(end 366.043464 -222.918528)
		(width 0.1143)
		(layer "In11.Cu")
		(net "P5E_CPU0_G3_RX_DP<10>")
	)
	(arc
		(start 365.25962 -229.094284)
		(mid 365.218858 -229.264168)
		(end 365.105442 -229.397052)
		(width 0.1143)
		(layer "In11.Cu")
		(net "P5E_CPU0_G3_RX_DP<10>")
	)
	(arc
		(start 364.789466 -229.904036)
		(mid 364.854702 -230.167627)
		(end 365.035338 -230.37038)
		(width 0.1143)
		(layer "In11.Cu")
		(net "P5E_CPU0_G3_RX_DP<10>")
	)
	(arc
		(start 365.03356 -242.399058)
		(mid 365.033179 -242.399312)
		(end 365.032798 -242.399566)
		(width 0.1143)
		(layer "In11.Cu")
		(net "P5E_CPU0_G3_RX_DP<10>")
	)
	(arc
		(start 366.042448 -223.929448)
		(mid 366.199425 -224.234248)
		(end 366.042448 -224.539048)
		(width 0.1143)
		(layer "In11.Cu")
		(net "P5E_CPU0_G3_RX_DP<10>")
	)
	(arc
		(start 365.072422 -235.251752)
		(mid 365.257942 -235.569809)
		(end 365.079788 -235.892086)
		(width 0.1143)
		(layer "In11.Cu")
		(net "P5E_CPU0_G3_RX_DP<10>")
	)
	(arc
		(start 365.72952 -225.044254)
		(mid 365.688265 -225.215225)
		(end 365.573564 -225.348546)
		(width 0.1143)
		(layer "In11.Cu")
		(net "P5E_CPU0_G3_RX_DP<10>")
	)
	(arc
		(start 365.03356 -239.159034)
		(mid 365.033179 -239.159288)
		(end 365.032798 -239.159542)
		(width 0.1143)
		(layer "In11.Cu")
		(net "P5E_CPU0_G3_RX_DP<10>")
	)
	(arc
		(start 365.032798 -229.43947)
		(mid 364.853985 -229.64182)
		(end 364.789466 -229.904036)
		(width 0.1143)
		(layer "In11.Cu")
		(net "P5E_CPU0_G3_RX_DP<10>")
	)
	(arc
		(start 365.032798 -237.53953)
		(mid 364.789471 -238.004096)
		(end 365.032798 -238.468662)
		(width 0.1143)
		(layer "In11.Cu")
		(net "P5E_CPU0_G3_RX_DP<10>")
	)
	(arc
		(start 365.473996 -225.412554)
		(mid 365.341578 -225.585735)
		(end 365.267494 -225.79076)
		(width 0.1143)
		(layer "In11.Cu")
		(net "P5E_CPU0_G3_RX_DP<10>")
	)
	(arc
		(start 365.072422 -241.7318)
		(mid 365.257942 -242.049857)
		(end 365.079788 -242.372134)
		(width 0.1143)
		(layer "In11.Cu")
		(net "P5E_CPU0_G3_RX_DP<10>")
	)
	(arc
		(start 365.032798 -234.299506)
		(mid 364.789471 -234.764072)
		(end 365.032798 -235.228638)
		(width 0.1143)
		(layer "In11.Cu")
		(net "P5E_CPU0_G3_RX_DP<10>")
	)
	(arc
		(start 365.03356 -237.539022)
		(mid 365.033179 -237.539276)
		(end 365.032798 -237.53953)
		(width 0.1143)
		(layer "In11.Cu")
		(net "P5E_CPU0_G3_RX_DP<10>")
	)
	(arc
		(start 365.032798 -235.919518)
		(mid 364.789471 -236.384084)
		(end 365.032798 -236.84865)
		(width 0.1143)
		(layer "In11.Cu")
		(net "P5E_CPU0_G3_RX_DP<10>")
	)
	(arc
		(start 365.72952 -221.80423)
		(mid 365.793696 -222.066117)
		(end 365.971836 -222.268542)
		(width 0.1143)
		(layer "In11.Cu")
		(net "P5E_CPU0_G3_RX_DP<10>")
	)
	(arc
		(start 365.103664 -230.410004)
		(mid 365.216684 -230.54418)
		(end 365.25962 -230.714296)
		(width 0.1143)
		(layer "In11.Cu")
		(net "P5E_CPU0_G3_RX_DP<10>")
	)
	(arc
		(start 365.103664 -227.16998)
		(mid 365.252761 -227.474272)
		(end 365.103664 -227.778564)
		(width 0.1143)
		(layer "In11.Cu")
		(net "P5E_CPU0_G3_RX_DP<10>")
	)
	(arc
		(start 365.103664 -243.369846)
		(mid 365.252761 -243.674138)
		(end 365.103664 -243.97843)
		(width 0.1143)
		(layer "In11.Cu")
		(net "P5E_CPU0_G3_RX_DP<10>")
	)
	(arc
		(start 365.072422 -240.111788)
		(mid 365.257942 -240.429845)
		(end 365.079788 -240.752122)
		(width 0.1143)
		(layer "In11.Cu")
		(net "P5E_CPU0_G3_RX_DP<10>")
	)
	(arc
		(start 365.505492 -225.387916)
		(mid 365.489523 -225.399953)
		(end 365.473996 -225.412554)
		(width 0.1143)
		(layer "In11.Cu")
		(net "P5E_CPU0_G3_RX_DP<10>")
	)
	(arc
		(start 365.032798 -244.019578)
		(mid 364.880811 -244.176086)
		(end 364.799372 -244.37848)
		(width 0.1143)
		(layer "In11.Cu")
		(net "P5E_CPU0_G3_RX_DP<10>")
	)
	(arc
		(start 365.072422 -238.491776)
		(mid 365.257942 -238.809833)
		(end 365.079788 -239.13211)
		(width 0.1143)
		(layer "In11.Cu")
		(net "P5E_CPU0_G3_RX_DP<10>")
	)
	(arc
		(start 365.103664 -233.649774)
		(mid 365.255253 -233.954066)
		(end 365.103664 -234.258358)
		(width 0.1143)
		(layer "In11.Cu")
		(net "P5E_CPU0_G3_RX_DP<10>")
	)
	(arc
		(start 365.03356 -234.298998)
		(mid 365.033179 -234.299252)
		(end 365.032798 -234.299506)
		(width 0.1143)
		(layer "In11.Cu")
		(net "P5E_CPU0_G3_RX_DP<10>")
	)
	(arc
		(start 365.032798 -227.819712)
		(mid 364.789471 -228.284278)
		(end 365.032798 -228.748844)
		(width 0.1143)
		(layer "In11.Cu")
		(net "P5E_CPU0_G3_RX_DP<10>")
	)
	(arc
		(start 365.03356 -235.91901)
		(mid 365.033179 -235.919264)
		(end 365.032798 -235.919518)
		(width 0.1143)
		(layer "In11.Cu")
		(net "P5E_CPU0_G3_RX_DP<10>")
	)
	(arc
		(start 365.032798 -231.059482)
		(mid 364.789471 -231.524048)
		(end 365.032798 -231.988614)
		(width 0.1143)
		(layer "In11.Cu")
		(net "P5E_CPU0_G3_RX_DP<10>")
	)
	(arc
		(start 365.03356 -240.779046)
		(mid 365.033179 -240.7793)
		(end 365.032798 -240.779554)
		(width 0.1143)
		(layer "In11.Cu")
		(net "P5E_CPU0_G3_RX_DP<10>")
	)
	(arc
		(start 365.96447 -222.965264)
		(mid 365.729367 -223.423964)
		(end 365.963708 -223.882966)
		(width 0.1143)
		(layer "In11.Cu")
		(net "P5E_CPU0_G3_RX_DP<10>")
	)
	(arc
		(start 365.032798 -232.679494)
		(mid 364.789471 -233.14406)
		(end 365.032798 -233.608626)
		(width 0.1143)
		(layer "In11.Cu")
		(net "P5E_CPU0_G3_RX_DP<10>")
	)
	(arc
		(start 365.073184 -228.772466)
		(mid 365.209602 -228.908339)
		(end 365.25962 -229.094284)
		(width 0.1143)
		(layer "In11.Cu")
		(net "P5E_CPU0_G3_RX_DP<10>")
	)
	(arc
		(start 365.032798 -226.1997)
		(mid 364.789471 -226.664266)
		(end 365.032798 -227.128832)
		(width 0.1143)
		(layer "In11.Cu")
		(net "P5E_CPU0_G3_RX_DP<10>")
	)
	(arc
		(start 365.267494 -225.79076)
		(mid 365.262015 -225.827935)
		(end 365.25962 -225.865436)
		(width 0.1143)
		(layer "In11.Cu")
		(net "P5E_CPU0_G3_RX_DP<10>")
	)
	(arc
		(start 364.799372 -244.37848)
		(mid 364.797349 -244.38989)
		(end 364.795562 -244.40134)
		(width 0.1143)
		(layer "In11.Cu")
		(net "P5E_CPU0_G3_RX_DP<10>")
	)
	(segment
		(start 430.16678 -7.709408)
		(end 430.16678 -8.320024)
		(width 0.12954)
		(layer "F.Cu")
		(net "P5E_CPU0_G3_RX_DP<0>")
	)
	(segment
		(start 430.305718 -5.228844)
		(end 430.305718 -7.57047)
		(width 0.12954)
		(layer "F.Cu")
		(net "P5E_CPU0_G3_RX_DP<0>")
	)
	(segment
		(start 372.407942 -246.370094)
		(end 372.874794 -246.104156)
		(width 0.12954)
		(layer "F.Cu")
		(net "P5E_CPU0_G3_RX_DP<0>")
	)
	(segment
		(start 430.305718 -7.57047)
		(end 430.16678 -7.709408)
		(width 0.12954)
		(layer "F.Cu")
		(net "P5E_CPU0_G3_RX_DP<0>")
	)
	(segment
		(start 430.040288 -4.963414)
		(end 430.305718 -5.228844)
		(width 0.12954)
		(layer "F.Cu")
		(net "P5E_CPU0_G3_RX_DP<0>")
	)
	(segment
		(start 376.853704 -222.108522)
		(end 376.821954 -222.12681)
		(width 0.1143)
		(layer "In11.Cu")
		(net "P5E_CPU0_G3_RX_DP<0>")
	)
	(segment
		(start 376.361198 -222.931482)
		(end 376.359674 -222.932244)
		(width 0.1143)
		(layer "In11.Cu")
		(net "P5E_CPU0_G3_RX_DP<0>")
	)
	(segment
		(start 376.96394 -221.202758)
		(end 377.00966 -221.248478)
		(width 0.1143)
		(layer "In11.Cu")
		(net "P5E_CPU0_G3_RX_DP<0>")
	)
	(segment
		(start 376.96394 -219.253562)
		(end 376.96394 -221.17431)
		(width 0.14224)
		(layer "In11.Cu")
		(net "P5E_CPU0_G3_RX_DP<0>")
	)
	(segment
		(start 374.502426 -227.779072)
		(end 374.43283 -227.819712)
		(width 0.1143)
		(layer "In11.Cu")
		(net "P5E_CPU0_G3_RX_DP<0>")
	)
	(segment
		(start 376.291602 -214.096092)
		(end 376.96394 -219.253562)
		(width 0.14224)
		(layer "In11.Cu")
		(net "P5E_CPU0_G3_RX_DP<0>")
	)
	(segment
		(start 374.43283 -238.468662)
		(end 374.502426 -238.509302)
		(width 0.1143)
		(layer "In11.Cu")
		(net "P5E_CPU0_G3_RX_DP<0>")
	)
	(segment
		(start 368.178842 -200.362058)
		(end 376.291602 -214.096092)
		(width 0.14224)
		(layer "In11.Cu")
		(net "P5E_CPU0_G3_RX_DP<0>")
	)
	(segment
		(start 374.43283 -227.128832)
		(end 374.502426 -227.169472)
		(width 0.1143)
		(layer "In11.Cu")
		(net "P5E_CPU0_G3_RX_DP<0>")
	)
	(segment
		(start 374.471946 -228.771704)
		(end 374.502426 -228.789484)
		(width 0.1143)
		(layer "In11.Cu")
		(net "P5E_CPU0_G3_RX_DP<0>")
	)
	(segment
		(start 374.502426 -226.15906)
		(end 374.43283 -226.1997)
		(width 0.1143)
		(layer "In11.Cu")
		(net "P5E_CPU0_G3_RX_DP<0>")
	)
	(segment
		(start 374.504458 -231.017826)
		(end 374.471946 -231.036622)
		(width 0.1143)
		(layer "In11.Cu")
		(net "P5E_CPU0_G3_RX_DP<0>")
	)
	(segment
		(start 373.707152 -245.303548)
		(end 373.707152 -245.3132)
		(width 0.1143)
		(layer "In11.Cu")
		(net "P5E_CPU0_G3_RX_DP<0>")
	)
	(segment
		(start 374.43283 -240.088674)
		(end 374.502426 -240.129314)
		(width 0.1143)
		(layer "In11.Cu")
		(net "P5E_CPU0_G3_RX_DP<0>")
	)
	(segment
		(start 374.939306 -225.368358)
		(end 374.90273 -225.389694)
		(width 0.1143)
		(layer "In11.Cu")
		(net "P5E_CPU0_G3_RX_DP<0>")
	)
	(segment
		(start 373.172736 -246.104156)
		(end 372.874794 -246.104156)
		(width 0.1143)
		(layer "In11.Cu")
		(net "P5E_CPU0_G3_RX_DP<0>")
	)
	(segment
		(start 376.347228 -222.93961)
		(end 376.312684 -222.959676)
		(width 0.1143)
		(layer "In11.Cu")
		(net "P5E_CPU0_G3_RX_DP<0>")
	)
	(segment
		(start 430.84369 -18.866104)
		(end 430.837086 -18.881852)
		(width 0.14224)
		(layer "In11.Cu")
		(net "P5E_CPU0_G3_RX_DP<0>")
	)
	(segment
		(start 376.359674 -222.932244)
		(end 376.358404 -222.933006)
		(width 0.1143)
		(layer "In11.Cu")
		(net "P5E_CPU0_G3_RX_DP<0>")
	)
	(segment
		(start 374.941846 -225.366834)
		(end 374.94083 -225.367342)
		(width 0.1143)
		(layer "In11.Cu")
		(net "P5E_CPU0_G3_RX_DP<0>")
	)
	(segment
		(start 374.942608 -225.366326)
		(end 374.941846 -225.366834)
		(width 0.1143)
		(layer "In11.Cu")
		(net "P5E_CPU0_G3_RX_DP<0>")
	)
	(segment
		(start 375.37517 -224.57791)
		(end 375.372884 -224.579688)
		(width 0.1143)
		(layer "In11.Cu")
		(net "P5E_CPU0_G3_RX_DP<0>")
	)
	(segment
		(start 376.357642 -222.933514)
		(end 376.356118 -222.934276)
		(width 0.1143)
		(layer "In11.Cu")
		(net "P5E_CPU0_G3_RX_DP<0>")
	)
	(segment
		(start 374.94718 -225.363786)
		(end 374.946164 -225.364294)
		(width 0.1143)
		(layer "In11.Cu")
		(net "P5E_CPU0_G3_RX_DP<0>")
	)
	(segment
		(start 376.358404 -222.933006)
		(end 376.357642 -222.933514)
		(width 0.1143)
		(layer "In11.Cu")
		(net "P5E_CPU0_G3_RX_DP<0>")
	)
	(segment
		(start 326.985122 -137.338562)
		(end 327.947528 -154.380184)
		(width 0.14224)
		(layer "In11.Cu")
		(net "P5E_CPU0_G3_RX_DP<0>")
	)
	(segment
		(start 374.43283 -243.328698)
		(end 374.502426 -243.369338)
		(width 0.1143)
		(layer "In11.Cu")
		(net "P5E_CPU0_G3_RX_DP<0>")
	)
	(segment
		(start 376.96394 -221.17431)
		(end 376.96394 -221.202758)
		(width 0.1143)
		(layer "In11.Cu")
		(net "P5E_CPU0_G3_RX_DP<0>")
	)
	(segment
		(start 376.38355 -222.918528)
		(end 376.36323 -222.930212)
		(width 0.1143)
		(layer "In11.Cu")
		(net "P5E_CPU0_G3_RX_DP<0>")
	)
	(segment
		(start 374.502426 -243.978938)
		(end 374.43283 -244.019578)
		(width 0.1143)
		(layer "In11.Cu")
		(net "P5E_CPU0_G3_RX_DP<0>")
	)
	(segment
		(start 376.3518 -222.936816)
		(end 376.350784 -222.937324)
		(width 0.1143)
		(layer "In11.Cu")
		(net "P5E_CPU0_G3_RX_DP<0>")
	)
	(segment
		(start 374.43283 -235.228638)
		(end 374.502426 -235.269278)
		(width 0.1143)
		(layer "In11.Cu")
		(net "P5E_CPU0_G3_RX_DP<0>")
	)
	(segment
		(start 327.316846 -135.99795)
		(end 326.985122 -137.338562)
		(width 0.14224)
		(layer "In11.Cu")
		(net "P5E_CPU0_G3_RX_DP<0>")
	)
	(segment
		(start 375.411746 -224.556828)
		(end 375.37517 -224.57791)
		(width 0.1143)
		(layer "In11.Cu")
		(net "P5E_CPU0_G3_RX_DP<0>")
	)
	(segment
		(start 431.269394 -18.229834)
		(end 430.84369 -18.866104)
		(width 0.14224)
		(layer "In11.Cu")
		(net "P5E_CPU0_G3_RX_DP<0>")
	)
	(segment
		(start 376.821954 -222.12681)
		(end 376.782838 -222.14967)
		(width 0.1143)
		(layer "In11.Cu")
		(net "P5E_CPU0_G3_RX_DP<0>")
	)
	(segment
		(start 337.358228 -173.286928)
		(end 340.023958 -177.302668)
		(width 0.14224)
		(layer "In11.Cu")
		(net "P5E_CPU0_G3_RX_DP<0>")
	)
	(segment
		(start 430.040288 -4.963414)
		(end 430.331118 -5.254244)
		(width 0.14224)
		(layer "In11.Cu")
		(net "P5E_CPU0_G3_RX_DP<0>")
	)
	(segment
		(start 374.502426 -234.258866)
		(end 374.43283 -234.299506)
		(width 0.1143)
		(layer "In11.Cu")
		(net "P5E_CPU0_G3_RX_DP<0>")
	)
	(segment
		(start 373.25554 -246.021352)
		(end 373.172736 -246.104156)
		(width 0.1143)
		(layer "In11.Cu")
		(net "P5E_CPU0_G3_RX_DP<0>")
	)
	(segment
		(start 374.033796 -244.788182)
		(end 373.990616 -244.813328)
		(width 0.1143)
		(layer "In11.Cu")
		(net "P5E_CPU0_G3_RX_DP<0>")
	)
	(segment
		(start 340.023958 -177.302668)
		(end 368.178842 -200.362058)
		(width 0.14224)
		(layer "In11.Cu")
		(net "P5E_CPU0_G3_RX_DP<0>")
	)
	(segment
		(start 374.94083 -225.367342)
		(end 374.939306 -225.368358)
		(width 0.1143)
		(layer "In11.Cu")
		(net "P5E_CPU0_G3_RX_DP<0>")
	)
	(segment
		(start 374.471946 -229.41661)
		(end 374.43283 -229.43947)
		(width 0.1143)
		(layer "In11.Cu")
		(net "P5E_CPU0_G3_RX_DP<0>")
	)
	(segment
		(start 375.446544 -224.536254)
		(end 375.444512 -224.537778)
		(width 0.1143)
		(layer "In11.Cu")
		(net "P5E_CPU0_G3_RX_DP<0>")
	)
	(segment
		(start 429.395382 -21.003768)
		(end 426.520356 -24.442674)
		(width 0.14224)
		(layer "In11.Cu")
		(net "P5E_CPU0_G3_RX_DP<0>")
	)
	(segment
		(start 374.504458 -229.397814)
		(end 374.471946 -229.41661)
		(width 0.1143)
		(layer "In11.Cu")
		(net "P5E_CPU0_G3_RX_DP<0>")
	)
	(segment
		(start 430.836832 -18.881852)
		(end 429.395382 -21.003768)
		(width 0.14224)
		(layer "In11.Cu")
		(net "P5E_CPU0_G3_RX_DP<0>")
	)
	(segment
		(start 374.471946 -231.036622)
		(end 374.43283 -231.059482)
		(width 0.1143)
		(layer "In11.Cu")
		(net "P5E_CPU0_G3_RX_DP<0>")
	)
	(segment
		(start 374.43283 -233.608626)
		(end 374.502426 -233.649266)
		(width 0.1143)
		(layer "In11.Cu")
		(net "P5E_CPU0_G3_RX_DP<0>")
	)
	(segment
		(start 374.43283 -231.988614)
		(end 374.502426 -232.029254)
		(width 0.1143)
		(layer "In11.Cu")
		(net "P5E_CPU0_G3_RX_DP<0>")
	)
	(segment
		(start 375.91238 -223.729042)
		(end 375.842784 -223.769682)
		(width 0.1143)
		(layer "In11.Cu")
		(net "P5E_CPU0_G3_RX_DP<0>")
	)
	(segment
		(start 426.520356 -24.442674)
		(end 330.521564 -130.66776)
		(width 0.14224)
		(layer "In11.Cu")
		(net "P5E_CPU0_G3_RX_DP<0>")
	)
	(segment
		(start 374.502426 -242.358926)
		(end 374.43283 -242.399566)
		(width 0.1143)
		(layer "In11.Cu")
		(net "P5E_CPU0_G3_RX_DP<0>")
	)
	(segment
		(start 430.331118 -5.254244)
		(end 430.331118 -11.05408)
		(width 0.14224)
		(layer "In11.Cu")
		(net "P5E_CPU0_G3_RX_DP<0>")
	)
	(segment
		(start 376.350784 -222.937324)
		(end 376.349514 -222.938086)
		(width 0.1143)
		(layer "In11.Cu")
		(net "P5E_CPU0_G3_RX_DP<0>")
	)
	(segment
		(start 374.502426 -237.49889)
		(end 374.43283 -237.53953)
		(width 0.1143)
		(layer "In11.Cu")
		(net "P5E_CPU0_G3_RX_DP<0>")
	)
	(segment
		(start 374.973596 -225.348546)
		(end 374.948958 -225.36277)
		(width 0.1143)
		(layer "In11.Cu")
		(net "P5E_CPU0_G3_RX_DP<0>")
	)
	(segment
		(start 374.43537 -230.37038)
		(end 374.502426 -230.409496)
		(width 0.1143)
		(layer "In11.Cu")
		(net "P5E_CPU0_G3_RX_DP<0>")
	)
	(segment
		(start 374.502426 -235.878878)
		(end 374.43283 -235.919518)
		(width 0.1143)
		(layer "In11.Cu")
		(net "P5E_CPU0_G3_RX_DP<0>")
	)
	(segment
		(start 327.947528 -154.380184)
		(end 334.728566 -167.299894)
		(width 0.14224)
		(layer "In11.Cu")
		(net "P5E_CPU0_G3_RX_DP<0>")
	)
	(segment
		(start 374.43283 -228.748844)
		(end 374.433338 -228.749098)
		(width 0.1143)
		(layer "In11.Cu")
		(net "P5E_CPU0_G3_RX_DP<0>")
	)
	(segment
		(start 374.948958 -225.36277)
		(end 374.947942 -225.363278)
		(width 0.1143)
		(layer "In11.Cu")
		(net "P5E_CPU0_G3_RX_DP<0>")
	)
	(segment
		(start 374.946164 -225.364294)
		(end 374.945402 -225.364802)
		(width 0.1143)
		(layer "In11.Cu")
		(net "P5E_CPU0_G3_RX_DP<0>")
	)
	(segment
		(start 375.599452 -224.234248)
		(end 375.599452 -224.236534)
		(width 0.1143)
		(layer "In11.Cu")
		(net "P5E_CPU0_G3_RX_DP<0>")
	)
	(segment
		(start 374.502426 -239.118902)
		(end 374.43283 -239.159542)
		(width 0.1143)
		(layer "In11.Cu")
		(net "P5E_CPU0_G3_RX_DP<0>")
	)
	(segment
		(start 431.535332 -17.108424)
		(end 431.535332 -17.70888)
		(width 0.14224)
		(layer "In11.Cu")
		(net "P5E_CPU0_G3_RX_DP<0>")
	)
	(segment
		(start 375.444512 -224.537778)
		(end 375.411746 -224.556828)
		(width 0.1143)
		(layer "In11.Cu")
		(net "P5E_CPU0_G3_RX_DP<0>")
	)
	(segment
		(start 430.837086 -18.881852)
		(end 430.836832 -18.881852)
		(width 0.14224)
		(layer "In11.Cu")
		(net "P5E_CPU0_G3_RX_DP<0>")
	)
	(segment
		(start 374.433338 -228.749098)
		(end 374.471946 -228.771704)
		(width 0.1143)
		(layer "In11.Cu")
		(net "P5E_CPU0_G3_RX_DP<0>")
	)
	(segment
		(start 374.947942 -225.363278)
		(end 374.94718 -225.363786)
		(width 0.1143)
		(layer "In11.Cu")
		(net "P5E_CPU0_G3_RX_DP<0>")
	)
	(segment
		(start 376.355356 -222.934784)
		(end 376.352562 -222.936308)
		(width 0.1143)
		(layer "In11.Cu")
		(net "P5E_CPU0_G3_RX_DP<0>")
	)
	(segment
		(start 374.43283 -236.84865)
		(end 374.502426 -236.88929)
		(width 0.1143)
		(layer "In11.Cu")
		(net "P5E_CPU0_G3_RX_DP<0>")
	)
	(segment
		(start 430.331118 -11.05408)
		(end 431.535332 -17.108424)
		(width 0.14224)
		(layer "In11.Cu")
		(net "P5E_CPU0_G3_RX_DP<0>")
	)
	(segment
		(start 376.356118 -222.934276)
		(end 376.355356 -222.934784)
		(width 0.1143)
		(layer "In11.Cu")
		(net "P5E_CPU0_G3_RX_DP<0>")
	)
	(segment
		(start 377.00966 -221.248478)
		(end 377.00966 -221.80423)
		(width 0.1143)
		(layer "In11.Cu")
		(net "P5E_CPU0_G3_RX_DP<0>")
	)
	(segment
		(start 431.49139 -17.814798)
		(end 431.269394 -18.229834)
		(width 0.14224)
		(layer "In11.Cu")
		(net "P5E_CPU0_G3_RX_DP<0>")
	)
	(segment
		(start 431.533554 -17.712944)
		(end 431.49139 -17.814798)
		(width 0.14224)
		(layer "In11.Cu")
		(net "P5E_CPU0_G3_RX_DP<0>")
	)
	(segment
		(start 374.502426 -240.738914)
		(end 374.43283 -240.779554)
		(width 0.1143)
		(layer "In11.Cu")
		(net "P5E_CPU0_G3_RX_DP<0>")
	)
	(segment
		(start 374.43283 -241.708686)
		(end 374.502426 -241.749326)
		(width 0.1143)
		(layer "In11.Cu")
		(net "P5E_CPU0_G3_RX_DP<0>")
	)
	(segment
		(start 376.349514 -222.938086)
		(end 376.347228 -222.93961)
		(width 0.1143)
		(layer "In11.Cu")
		(net "P5E_CPU0_G3_RX_DP<0>")
	)
	(segment
		(start 374.943878 -225.365564)
		(end 374.942608 -225.366326)
		(width 0.1143)
		(layer "In11.Cu")
		(net "P5E_CPU0_G3_RX_DP<0>")
	)
	(segment
		(start 374.945402 -225.364802)
		(end 374.943878 -225.365564)
		(width 0.1143)
		(layer "In11.Cu")
		(net "P5E_CPU0_G3_RX_DP<0>")
	)
	(segment
		(start 374.502426 -232.638854)
		(end 374.43283 -232.679494)
		(width 0.1143)
		(layer "In11.Cu")
		(net "P5E_CPU0_G3_RX_DP<0>")
	)
	(segment
		(start 376.352562 -222.936308)
		(end 376.3518 -222.936816)
		(width 0.1143)
		(layer "In11.Cu")
		(net "P5E_CPU0_G3_RX_DP<0>")
	)
	(segment
		(start 431.535332 -17.70888)
		(end 431.533554 -17.712944)
		(width 0.14224)
		(layer "In11.Cu")
		(net "P5E_CPU0_G3_RX_DP<0>")
	)
	(segment
		(start 376.36323 -222.930212)
		(end 376.36196 -222.930974)
		(width 0.1143)
		(layer "In11.Cu")
		(net "P5E_CPU0_G3_RX_DP<0>")
	)
	(segment
		(start 330.521564 -130.66776)
		(end 327.316846 -135.99795)
		(width 0.14224)
		(layer "In11.Cu")
		(net "P5E_CPU0_G3_RX_DP<0>")
	)
	(segment
		(start 373.5324 -245.616476)
		(end 373.493538 -245.639082)
		(width 0.1143)
		(layer "In11.Cu")
		(net "P5E_CPU0_G3_RX_DP<0>")
	)
	(segment
		(start 334.728566 -167.299894)
		(end 337.358228 -173.286928)
		(width 0.14224)
		(layer "In11.Cu")
		(net "P5E_CPU0_G3_RX_DP<0>")
	)
	(segment
		(start 376.36196 -222.930974)
		(end 376.361198 -222.931482)
		(width 0.1143)
		(layer "In11.Cu")
		(net "P5E_CPU0_G3_RX_DP<0>")
	)
	(arc
		(start 374.43283 -227.819712)
		(mid 374.189503 -228.284278)
		(end 374.43283 -228.748844)
		(width 0.1143)
		(layer "In11.Cu")
		(net "P5E_CPU0_G3_RX_DP<0>")
	)
	(arc
		(start 376.069352 -223.424242)
		(mid 376.027803 -223.595664)
		(end 375.91238 -223.729042)
		(width 0.1143)
		(layer "In11.Cu")
		(net "P5E_CPU0_G3_RX_DP<0>")
	)
	(arc
		(start 374.43283 -237.53953)
		(mid 374.189503 -238.004096)
		(end 374.43283 -238.468662)
		(width 0.1143)
		(layer "In11.Cu")
		(net "P5E_CPU0_G3_RX_DP<0>")
	)
	(arc
		(start 374.502426 -232.029254)
		(mid 374.659403 -232.334054)
		(end 374.502426 -232.638854)
		(width 0.1143)
		(layer "In11.Cu")
		(net "P5E_CPU0_G3_RX_DP<0>")
	)
	(arc
		(start 374.659398 -230.714296)
		(mid 374.618432 -230.884702)
		(end 374.504458 -231.017826)
		(width 0.1143)
		(layer "In11.Cu")
		(net "P5E_CPU0_G3_RX_DP<0>")
	)
	(arc
		(start 373.493538 -245.639082)
		(mid 373.493157 -245.639336)
		(end 373.492776 -245.63959)
		(width 0.1143)
		(layer "In11.Cu")
		(net "P5E_CPU0_G3_RX_DP<0>")
	)
	(arc
		(start 375.599452 -224.236534)
		(mid 375.559008 -224.404758)
		(end 375.446544 -224.536254)
		(width 0.1143)
		(layer "In11.Cu")
		(net "P5E_CPU0_G3_RX_DP<0>")
	)
	(arc
		(start 374.659398 -229.094284)
		(mid 374.618432 -229.26469)
		(end 374.504458 -229.397814)
		(width 0.1143)
		(layer "In11.Cu")
		(net "P5E_CPU0_G3_RX_DP<0>")
	)
	(arc
		(start 374.659398 -225.85426)
		(mid 374.617849 -226.025682)
		(end 374.502426 -226.15906)
		(width 0.1143)
		(layer "In11.Cu")
		(net "P5E_CPU0_G3_RX_DP<0>")
	)
	(arc
		(start 373.492776 -245.63959)
		(mid 373.340789 -245.796098)
		(end 373.25935 -245.998492)
		(width 0.1143)
		(layer "In11.Cu")
		(net "P5E_CPU0_G3_RX_DP<0>")
	)
	(arc
		(start 374.189498 -244.484144)
		(mid 374.148305 -244.654933)
		(end 374.033796 -244.788182)
		(width 0.1143)
		(layer "In11.Cu")
		(net "P5E_CPU0_G3_RX_DP<0>")
	)
	(arc
		(start 374.502426 -240.129314)
		(mid 374.659403 -240.434114)
		(end 374.502426 -240.738914)
		(width 0.1143)
		(layer "In11.Cu")
		(net "P5E_CPU0_G3_RX_DP<0>")
	)
	(arc
		(start 374.43283 -229.43947)
		(mid 374.254017 -229.64182)
		(end 374.189498 -229.904036)
		(width 0.1143)
		(layer "In11.Cu")
		(net "P5E_CPU0_G3_RX_DP<0>")
	)
	(arc
		(start 374.502426 -236.88929)
		(mid 374.659403 -237.19409)
		(end 374.502426 -237.49889)
		(width 0.1143)
		(layer "In11.Cu")
		(net "P5E_CPU0_G3_RX_DP<0>")
	)
	(arc
		(start 376.539506 -222.614236)
		(mid 376.498251 -222.785207)
		(end 376.38355 -222.918528)
		(width 0.1143)
		(layer "In11.Cu")
		(net "P5E_CPU0_G3_RX_DP<0>")
	)
	(arc
		(start 375.842784 -223.769682)
		(mid 375.663971 -223.972032)
		(end 375.599452 -224.234248)
		(width 0.1143)
		(layer "In11.Cu")
		(net "P5E_CPU0_G3_RX_DP<0>")
	)
	(arc
		(start 374.502426 -233.649266)
		(mid 374.659403 -233.954066)
		(end 374.502426 -234.258866)
		(width 0.1143)
		(layer "In11.Cu")
		(net "P5E_CPU0_G3_RX_DP<0>")
	)
	(arc
		(start 376.312684 -222.959676)
		(mid 376.133871 -223.162026)
		(end 376.069352 -223.424242)
		(width 0.1143)
		(layer "In11.Cu")
		(net "P5E_CPU0_G3_RX_DP<0>")
	)
	(arc
		(start 374.502426 -227.169472)
		(mid 374.659403 -227.474272)
		(end 374.502426 -227.779072)
		(width 0.1143)
		(layer "In11.Cu")
		(net "P5E_CPU0_G3_RX_DP<0>")
	)
	(arc
		(start 373.990616 -244.813328)
		(mid 373.783132 -245.020415)
		(end 373.707152 -245.303548)
		(width 0.1143)
		(layer "In11.Cu")
		(net "P5E_CPU0_G3_RX_DP<0>")
	)
	(arc
		(start 374.502426 -238.509302)
		(mid 374.659403 -238.814102)
		(end 374.502426 -239.118902)
		(width 0.1143)
		(layer "In11.Cu")
		(net "P5E_CPU0_G3_RX_DP<0>")
	)
	(arc
		(start 374.43283 -232.679494)
		(mid 374.189503 -233.14406)
		(end 374.43283 -233.608626)
		(width 0.1143)
		(layer "In11.Cu")
		(net "P5E_CPU0_G3_RX_DP<0>")
	)
	(arc
		(start 374.189498 -229.904036)
		(mid 374.254734 -230.167627)
		(end 374.43537 -230.37038)
		(width 0.1143)
		(layer "In11.Cu")
		(net "P5E_CPU0_G3_RX_DP<0>")
	)
	(arc
		(start 374.502426 -241.749326)
		(mid 374.659403 -242.054126)
		(end 374.502426 -242.358926)
		(width 0.1143)
		(layer "In11.Cu")
		(net "P5E_CPU0_G3_RX_DP<0>")
	)
	(arc
		(start 374.43283 -239.159542)
		(mid 374.189503 -239.624108)
		(end 374.43283 -240.088674)
		(width 0.1143)
		(layer "In11.Cu")
		(net "P5E_CPU0_G3_RX_DP<0>")
	)
	(arc
		(start 374.43283 -231.059482)
		(mid 374.189503 -231.524048)
		(end 374.43283 -231.988614)
		(width 0.1143)
		(layer "In11.Cu")
		(net "P5E_CPU0_G3_RX_DP<0>")
	)
	(arc
		(start 376.782838 -222.14967)
		(mid 376.604025 -222.35202)
		(end 376.539506 -222.614236)
		(width 0.1143)
		(layer "In11.Cu")
		(net "P5E_CPU0_G3_RX_DP<0>")
	)
	(arc
		(start 374.502426 -230.409496)
		(mid 374.617853 -230.542872)
		(end 374.659398 -230.714296)
		(width 0.1143)
		(layer "In11.Cu")
		(net "P5E_CPU0_G3_RX_DP<0>")
	)
	(arc
		(start 373.25935 -245.998492)
		(mid 373.257327 -246.009902)
		(end 373.25554 -246.021352)
		(width 0.1143)
		(layer "In11.Cu")
		(net "P5E_CPU0_G3_RX_DP<0>")
	)
	(arc
		(start 374.43283 -240.779554)
		(mid 374.189503 -241.24412)
		(end 374.43283 -241.708686)
		(width 0.1143)
		(layer "In11.Cu")
		(net "P5E_CPU0_G3_RX_DP<0>")
	)
	(arc
		(start 374.43283 -242.399566)
		(mid 374.189503 -242.864132)
		(end 374.43283 -243.328698)
		(width 0.1143)
		(layer "In11.Cu")
		(net "P5E_CPU0_G3_RX_DP<0>")
	)
	(arc
		(start 374.502426 -228.789484)
		(mid 374.617853 -228.92286)
		(end 374.659398 -229.094284)
		(width 0.1143)
		(layer "In11.Cu")
		(net "P5E_CPU0_G3_RX_DP<0>")
	)
	(arc
		(start 374.43283 -226.1997)
		(mid 374.189503 -226.664266)
		(end 374.43283 -227.128832)
		(width 0.1143)
		(layer "In11.Cu")
		(net "P5E_CPU0_G3_RX_DP<0>")
	)
	(arc
		(start 374.43283 -234.299506)
		(mid 374.189503 -234.764072)
		(end 374.43283 -235.228638)
		(width 0.1143)
		(layer "In11.Cu")
		(net "P5E_CPU0_G3_RX_DP<0>")
	)
	(arc
		(start 375.372884 -224.579688)
		(mid 375.194071 -224.782038)
		(end 375.129552 -225.044254)
		(width 0.1143)
		(layer "In11.Cu")
		(net "P5E_CPU0_G3_RX_DP<0>")
	)
	(arc
		(start 374.502426 -243.369338)
		(mid 374.659403 -243.674138)
		(end 374.502426 -243.978938)
		(width 0.1143)
		(layer "In11.Cu")
		(net "P5E_CPU0_G3_RX_DP<0>")
	)
	(arc
		(start 374.43283 -235.919518)
		(mid 374.189503 -236.384084)
		(end 374.43283 -236.84865)
		(width 0.1143)
		(layer "In11.Cu")
		(net "P5E_CPU0_G3_RX_DP<0>")
	)
	(arc
		(start 373.707152 -245.3132)
		(mid 373.660262 -245.488151)
		(end 373.5324 -245.616476)
		(width 0.1143)
		(layer "In11.Cu")
		(net "P5E_CPU0_G3_RX_DP<0>")
	)
	(arc
		(start 377.00966 -221.80423)
		(mid 376.968405 -221.975201)
		(end 376.853704 -222.108522)
		(width 0.1143)
		(layer "In11.Cu")
		(net "P5E_CPU0_G3_RX_DP<0>")
	)
	(arc
		(start 375.129552 -225.044254)
		(mid 375.088297 -225.215225)
		(end 374.973596 -225.348546)
		(width 0.1143)
		(layer "In11.Cu")
		(net "P5E_CPU0_G3_RX_DP<0>")
	)
	(arc
		(start 374.502426 -235.269278)
		(mid 374.659403 -235.574078)
		(end 374.502426 -235.878878)
		(width 0.1143)
		(layer "In11.Cu")
		(net "P5E_CPU0_G3_RX_DP<0>")
	)
	(arc
		(start 374.90273 -225.389694)
		(mid 374.723917 -225.592044)
		(end 374.659398 -225.85426)
		(width 0.1143)
		(layer "In11.Cu")
		(net "P5E_CPU0_G3_RX_DP<0>")
	)
	(arc
		(start 374.43283 -244.019578)
		(mid 374.254017 -244.221928)
		(end 374.189498 -244.484144)
		(width 0.1143)
		(layer "In11.Cu")
		(net "P5E_CPU0_G3_RX_DP<0>")
	)
	(segment
		(start 405.046942 -8.320024)
		(end 405.046942 -7.709154)
		(width 0.12954)
		(layer "F.Cu")
		(net "P5E_CPU0_G3_RX_DN<9>")
	)
	(segment
		(start 405.046942 -7.709154)
		(end 404.908258 -7.57047)
		(width 0.12954)
		(layer "F.Cu")
		(net "P5E_CPU0_G3_RX_DN<9>")
	)
	(segment
		(start 404.908258 -6.996176)
		(end 405.179276 -6.725158)
		(width 0.12954)
		(layer "F.Cu")
		(net "P5E_CPU0_G3_RX_DN<9>")
	)
	(segment
		(start 404.908258 -7.57047)
		(end 404.908258 -6.996176)
		(width 0.12954)
		(layer "F.Cu")
		(net "P5E_CPU0_G3_RX_DN<9>")
	)
	(segment
		(start 364.888018 -246.370094)
		(end 365.35487 -246.104156)
		(width 0.12954)
		(layer "F.Cu")
		(net "P5E_CPU0_G3_RX_DN<9>")
	)
	(segment
		(start 366.578896 -225.531172)
		(end 366.57788 -225.53168)
		(width 0.1143)
		(layer "In11.Cu")
		(net "P5E_CPU0_G3_RX_DN<9>")
	)
	(segment
		(start 366.146842 -237.658656)
		(end 366.077246 -237.699296)
		(width 0.1143)
		(layer "In11.Cu")
		(net "P5E_CPU0_G3_RX_DN<9>")
	)
	(segment
		(start 311.73801 -162.313874)
		(end 313.639962 -166.906448)
		(width 0.14224)
		(layer "In11.Cu")
		(net "P5E_CPU0_G3_RX_DN<9>")
	)
	(segment
		(start 366.860074 -221.579948)
		(end 366.860074 -221.80423)
		(width 0.1143)
		(layer "In11.Cu")
		(net "P5E_CPU0_G3_RX_DN<9>")
	)
	(segment
		(start 313.835796 -148.716746)
		(end 311.73801 -160.65754)
		(width 0.14224)
		(layer "In11.Cu")
		(net "P5E_CPU0_G3_RX_DN<9>")
	)
	(segment
		(start 366.884458 -221.128844)
		(end 366.884458 -221.38767)
		(width 0.1143)
		(layer "In11.Cu")
		(net "P5E_CPU0_G3_RX_DN<9>")
	)
	(segment
		(start 364.987078 -246.034306)
		(end 365.056928 -246.104156)
		(width 0.1143)
		(layer "In11.Cu")
		(net "P5E_CPU0_G3_RX_DN<9>")
	)
	(segment
		(start 367.04778 -223.746822)
		(end 367.084102 -223.76765)
		(width 0.1143)
		(layer "In11.Cu")
		(net "P5E_CPU0_G3_RX_DN<9>")
	)
	(segment
		(start 406.18918 -19.552666)
		(end 402.703538 -24.546052)
		(width 0.14224)
		(layer "In11.Cu")
		(net "P5E_CPU0_G3_RX_DN<9>")
	)
	(segment
		(start 405.879554 -18.229834)
		(end 406.312624 -18.876772)
		(width 0.14224)
		(layer "In11.Cu")
		(net "P5E_CPU0_G3_RX_DN<9>")
	)
	(segment
		(start 366.582198 -225.52914)
		(end 366.580674 -225.530156)
		(width 0.1143)
		(layer "In11.Cu")
		(net "P5E_CPU0_G3_RX_DN<9>")
	)
	(segment
		(start 405.619966 -17.697958)
		(end 405.642572 -17.78762)
		(width 0.14224)
		(layer "In11.Cu")
		(net "P5E_CPU0_G3_RX_DN<9>")
	)
	(segment
		(start 366.107726 -229.58171)
		(end 366.075214 -229.600506)
		(width 0.1143)
		(layer "In11.Cu")
		(net "P5E_CPU0_G3_RX_DN<9>")
	)
	(segment
		(start 366.146842 -242.518692)
		(end 366.077246 -242.559332)
		(width 0.1143)
		(layer "In11.Cu")
		(net "P5E_CPU0_G3_RX_DN<9>")
	)
	(segment
		(start 366.146842 -229.55885)
		(end 366.14481 -229.560374)
		(width 0.1143)
		(layer "In11.Cu")
		(net "P5E_CPU0_G3_RX_DN<9>")
	)
	(segment
		(start 366.85982 -221.579694)
		(end 366.860074 -221.579948)
		(width 0.1143)
		(layer "In11.Cu")
		(net "P5E_CPU0_G3_RX_DN<9>")
	)
	(segment
		(start 366.146842 -239.278668)
		(end 366.077246 -239.319308)
		(width 0.1143)
		(layer "In11.Cu")
		(net "P5E_CPU0_G3_RX_DN<9>")
	)
	(segment
		(start 402.703538 -24.546052)
		(end 322.85178 -126.411482)
		(width 0.14224)
		(layer "In11.Cu")
		(net "P5E_CPU0_G3_RX_DN<9>")
	)
	(segment
		(start 366.077246 -236.688884)
		(end 366.146842 -236.729524)
		(width 0.1143)
		(layer "In11.Cu")
		(net "P5E_CPU0_G3_RX_DN<9>")
	)
	(segment
		(start 367.084102 -223.76765)
		(end 367.086896 -223.769682)
		(width 0.1143)
		(layer "In11.Cu")
		(net "P5E_CPU0_G3_RX_DN<9>")
	)
	(segment
		(start 366.616996 -225.50882)
		(end 366.610138 -225.512884)
		(width 0.1143)
		(layer "In11.Cu")
		(net "P5E_CPU0_G3_RX_DN<9>")
	)
	(segment
		(start 361.733846 -205.849474)
		(end 366.930178 -214.602822)
		(width 0.14224)
		(layer "In11.Cu")
		(net "P5E_CPU0_G3_RX_DN<9>")
	)
	(segment
		(start 313.639962 -166.906448)
		(end 317.62573 -170.892724)
		(width 0.14224)
		(layer "In11.Cu")
		(net "P5E_CPU0_G3_RX_DN<9>")
	)
	(segment
		(start 366.077246 -233.44886)
		(end 366.146842 -233.4895)
		(width 0.1143)
		(layer "In11.Cu")
		(net "P5E_CPU0_G3_RX_DN<9>")
	)
	(segment
		(start 366.580674 -225.530156)
		(end 366.578896 -225.531172)
		(width 0.1143)
		(layer "In11.Cu")
		(net "P5E_CPU0_G3_RX_DN<9>")
	)
	(segment
		(start 365.056928 -246.104156)
		(end 365.35487 -246.104156)
		(width 0.1143)
		(layer "In11.Cu")
		(net "P5E_CPU0_G3_RX_DN<9>")
	)
	(segment
		(start 365.676942 -244.94871)
		(end 365.62538 -244.978682)
		(width 0.1143)
		(layer "In11.Cu")
		(net "P5E_CPU0_G3_RX_DN<9>")
	)
	(segment
		(start 366.610138 -225.512884)
		(end 366.609376 -225.513392)
		(width 0.1143)
		(layer "In11.Cu")
		(net "P5E_CPU0_G3_RX_DN<9>")
	)
	(segment
		(start 366.146842 -240.89868)
		(end 366.077246 -240.93932)
		(width 0.1143)
		(layer "In11.Cu")
		(net "P5E_CPU0_G3_RX_DN<9>")
	)
	(segment
		(start 366.146842 -231.178862)
		(end 366.107726 -231.201722)
		(width 0.1143)
		(layer "In11.Cu")
		(net "P5E_CPU0_G3_RX_DN<9>")
	)
	(segment
		(start 367.04778 -223.101662)
		(end 367.01603 -223.11995)
		(width 0.1143)
		(layer "In11.Cu")
		(net "P5E_CPU0_G3_RX_DN<9>")
	)
	(segment
		(start 366.146842 -244.138704)
		(end 366.077246 -244.179344)
		(width 0.1143)
		(layer "In11.Cu")
		(net "P5E_CPU0_G3_RX_DN<9>")
	)
	(segment
		(start 365.167926 -245.781576)
		(end 365.136176 -245.799864)
		(width 0.1143)
		(layer "In11.Cu")
		(net "P5E_CPU0_G3_RX_DN<9>")
	)
	(segment
		(start 366.146842 -226.318826)
		(end 366.077246 -226.359466)
		(width 0.1143)
		(layer "In11.Cu")
		(net "P5E_CPU0_G3_RX_DN<9>")
	)
	(segment
		(start 366.85982 -221.412308)
		(end 366.85982 -221.579694)
		(width 0.1143)
		(layer "In11.Cu")
		(net "P5E_CPU0_G3_RX_DN<9>")
	)
	(segment
		(start 366.146842 -232.79862)
		(end 366.077246 -232.83926)
		(width 0.1143)
		(layer "In11.Cu")
		(net "P5E_CPU0_G3_RX_DN<9>")
	)
	(segment
		(start 366.077246 -235.068872)
		(end 366.146842 -235.109512)
		(width 0.1143)
		(layer "In11.Cu")
		(net "P5E_CPU0_G3_RX_DN<9>")
	)
	(segment
		(start 366.146842 -234.418632)
		(end 366.077246 -234.459272)
		(width 0.1143)
		(layer "In11.Cu")
		(net "P5E_CPU0_G3_RX_DN<9>")
	)
	(segment
		(start 365.437674 -245.303548)
		(end 365.437674 -245.3132)
		(width 0.1143)
		(layer "In11.Cu")
		(net "P5E_CPU0_G3_RX_DN<9>")
	)
	(segment
		(start 405.642572 -17.78762)
		(end 405.879554 -18.229834)
		(width 0.14224)
		(layer "In11.Cu")
		(net "P5E_CPU0_G3_RX_DN<9>")
	)
	(segment
		(start 366.575848 -225.53295)
		(end 366.54613 -225.549968)
		(width 0.1143)
		(layer "In11.Cu")
		(net "P5E_CPU0_G3_RX_DN<9>")
	)
	(segment
		(start 323.017388 -174.124112)
		(end 323.421502 -174.43958)
		(width 0.14224)
		(layer "In11.Cu")
		(net "P5E_CPU0_G3_RX_DN<9>")
	)
	(segment
		(start 366.146842 -227.938838)
		(end 366.077246 -227.979478)
		(width 0.1143)
		(layer "In11.Cu")
		(net "P5E_CPU0_G3_RX_DN<9>")
	)
	(segment
		(start 366.077246 -243.168932)
		(end 366.146842 -243.209572)
		(width 0.1143)
		(layer "In11.Cu")
		(net "P5E_CPU0_G3_RX_DN<9>")
	)
	(segment
		(start 366.077246 -231.828848)
		(end 366.146842 -231.869488)
		(width 0.1143)
		(layer "In11.Cu")
		(net "P5E_CPU0_G3_RX_DN<9>")
	)
	(segment
		(start 366.930178 -214.602822)
		(end 366.930178 -221.054676)
		(width 0.14224)
		(layer "In11.Cu")
		(net "P5E_CPU0_G3_RX_DN<9>")
	)
	(segment
		(start 406.312624 -18.876772)
		(end 406.312624 -19.353022)
		(width 0.14224)
		(layer "In11.Cu")
		(net "P5E_CPU0_G3_RX_DN<9>")
	)
	(segment
		(start 323.4944 -174.512478)
		(end 361.733846 -205.849474)
		(width 0.14224)
		(layer "In11.Cu")
		(net "P5E_CPU0_G3_RX_DN<9>")
	)
	(segment
		(start 322.85178 -126.411482)
		(end 320.170556 -131.246372)
		(width 0.14224)
		(layer "In11.Cu")
		(net "P5E_CPU0_G3_RX_DN<9>")
	)
	(segment
		(start 317.62573 -170.892724)
		(end 323.017388 -174.124112)
		(width 0.14224)
		(layer "In11.Cu")
		(net "P5E_CPU0_G3_RX_DN<9>")
	)
	(segment
		(start 366.077246 -226.969066)
		(end 366.146842 -227.009706)
		(width 0.1143)
		(layer "In11.Cu")
		(net "P5E_CPU0_G3_RX_DN<9>")
	)
	(segment
		(start 366.077246 -238.308896)
		(end 366.146842 -238.349536)
		(width 0.1143)
		(layer "In11.Cu")
		(net "P5E_CPU0_G3_RX_DN<9>")
	)
	(segment
		(start 366.146842 -236.038644)
		(end 366.077246 -236.079284)
		(width 0.1143)
		(layer "In11.Cu")
		(net "P5E_CPU0_G3_RX_DN<9>")
	)
	(segment
		(start 323.421502 -174.43958)
		(end 323.4944 -174.512478)
		(width 0.14224)
		(layer "In11.Cu")
		(net "P5E_CPU0_G3_RX_DN<9>")
	)
	(segment
		(start 366.14481 -229.560374)
		(end 366.107726 -229.58171)
		(width 0.1143)
		(layer "In11.Cu")
		(net "P5E_CPU0_G3_RX_DN<9>")
	)
	(segment
		(start 320.170556 -131.246372)
		(end 313.835796 -148.716746)
		(width 0.14224)
		(layer "In11.Cu")
		(net "P5E_CPU0_G3_RX_DN<9>")
	)
	(segment
		(start 366.077246 -230.208836)
		(end 366.144302 -230.247952)
		(width 0.1143)
		(layer "In11.Cu")
		(net "P5E_CPU0_G3_RX_DN<9>")
	)
	(segment
		(start 367.01603 -222.108522)
		(end 367.04778 -222.12681)
		(width 0.1143)
		(layer "In11.Cu")
		(net "P5E_CPU0_G3_RX_DN<9>")
	)
	(segment
		(start 366.930178 -221.054676)
		(end 366.930178 -221.083124)
		(width 0.1143)
		(layer "In11.Cu")
		(net "P5E_CPU0_G3_RX_DN<9>")
	)
	(segment
		(start 404.888446 -11.77925)
		(end 405.619966 -17.697958)
		(width 0.14224)
		(layer "In11.Cu")
		(net "P5E_CPU0_G3_RX_DN<9>")
	)
	(segment
		(start 367.086896 -224.698814)
		(end 367.0173 -224.739454)
		(width 0.1143)
		(layer "In11.Cu")
		(net "P5E_CPU0_G3_RX_DN<9>")
	)
	(segment
		(start 366.57788 -225.53168)
		(end 366.577118 -225.532188)
		(width 0.1143)
		(layer "In11.Cu")
		(net "P5E_CPU0_G3_RX_DN<9>")
	)
	(segment
		(start 366.077246 -239.928908)
		(end 366.146842 -239.969548)
		(width 0.1143)
		(layer "In11.Cu")
		(net "P5E_CPU0_G3_RX_DN<9>")
	)
	(segment
		(start 366.609376 -225.513392)
		(end 366.582198 -225.52914)
		(width 0.1143)
		(layer "In11.Cu")
		(net "P5E_CPU0_G3_RX_DN<9>")
	)
	(segment
		(start 406.312624 -19.353022)
		(end 406.18918 -19.552666)
		(width 0.14224)
		(layer "In11.Cu")
		(net "P5E_CPU0_G3_RX_DN<9>")
	)
	(segment
		(start 311.73801 -160.65754)
		(end 311.73801 -162.313874)
		(width 0.14224)
		(layer "In11.Cu")
		(net "P5E_CPU0_G3_RX_DN<9>")
	)
	(segment
		(start 366.107726 -231.201722)
		(end 366.075214 -231.220518)
		(width 0.1143)
		(layer "In11.Cu")
		(net "P5E_CPU0_G3_RX_DN<9>")
	)
	(segment
		(start 366.884458 -221.38767)
		(end 366.85982 -221.412308)
		(width 0.1143)
		(layer "In11.Cu")
		(net "P5E_CPU0_G3_RX_DN<9>")
	)
	(segment
		(start 366.930178 -221.083124)
		(end 366.884458 -221.128844)
		(width 0.1143)
		(layer "In11.Cu")
		(net "P5E_CPU0_G3_RX_DN<9>")
	)
	(segment
		(start 366.077246 -228.589078)
		(end 366.146842 -228.629718)
		(width 0.1143)
		(layer "In11.Cu")
		(net "P5E_CPU0_G3_RX_DN<9>")
	)
	(segment
		(start 366.577118 -225.532188)
		(end 366.575848 -225.53295)
		(width 0.1143)
		(layer "In11.Cu")
		(net "P5E_CPU0_G3_RX_DN<9>")
	)
	(segment
		(start 367.01603 -223.728534)
		(end 367.04778 -223.746822)
		(width 0.1143)
		(layer "In11.Cu")
		(net "P5E_CPU0_G3_RX_DN<9>")
	)
	(segment
		(start 366.077246 -241.54892)
		(end 366.146842 -241.58956)
		(width 0.1143)
		(layer "In11.Cu")
		(net "P5E_CPU0_G3_RX_DN<9>")
	)
	(segment
		(start 405.179276 -6.725158)
		(end 404.888446 -7.015988)
		(width 0.14224)
		(layer "In11.Cu")
		(net "P5E_CPU0_G3_RX_DN<9>")
	)
	(segment
		(start 404.888446 -7.015988)
		(end 404.888446 -11.77925)
		(width 0.14224)
		(layer "In11.Cu")
		(net "P5E_CPU0_G3_RX_DN<9>")
	)
	(arc
		(start 366.146842 -231.869488)
		(mid 366.390169 -232.334054)
		(end 366.146842 -232.79862)
		(width 0.1143)
		(layer "In11.Cu")
		(net "P5E_CPU0_G3_RX_DN<9>")
	)
	(arc
		(start 366.077246 -227.979478)
		(mid 365.920269 -228.284278)
		(end 366.077246 -228.589078)
		(width 0.1143)
		(layer "In11.Cu")
		(net "P5E_CPU0_G3_RX_DN<9>")
	)
	(arc
		(start 366.146842 -239.969548)
		(mid 366.390169 -240.434114)
		(end 366.146842 -240.89868)
		(width 0.1143)
		(layer "In11.Cu")
		(net "P5E_CPU0_G3_RX_DN<9>")
	)
	(arc
		(start 366.077246 -232.83926)
		(mid 365.920269 -233.14406)
		(end 366.077246 -233.44886)
		(width 0.1143)
		(layer "In11.Cu")
		(net "P5E_CPU0_G3_RX_DN<9>")
	)
	(arc
		(start 365.920274 -244.484144)
		(mid 365.855759 -244.746363)
		(end 365.676942 -244.94871)
		(width 0.1143)
		(layer "In11.Cu")
		(net "P5E_CPU0_G3_RX_DN<9>")
	)
	(arc
		(start 366.860074 -221.80423)
		(mid 366.904145 -221.973766)
		(end 367.01603 -222.108522)
		(width 0.1143)
		(layer "In11.Cu")
		(net "P5E_CPU0_G3_RX_DN<9>")
	)
	(arc
		(start 366.077246 -234.459272)
		(mid 365.920269 -234.764072)
		(end 366.077246 -235.068872)
		(width 0.1143)
		(layer "In11.Cu")
		(net "P5E_CPU0_G3_RX_DN<9>")
	)
	(arc
		(start 365.136176 -245.799864)
		(mid 365.039041 -245.902733)
		(end 364.987078 -246.034306)
		(width 0.1143)
		(layer "In11.Cu")
		(net "P5E_CPU0_G3_RX_DN<9>")
	)
	(arc
		(start 366.144302 -230.247952)
		(mid 366.324954 -230.450697)
		(end 366.390174 -230.714296)
		(width 0.1143)
		(layer "In11.Cu")
		(net "P5E_CPU0_G3_RX_DN<9>")
	)
	(arc
		(start 366.146842 -241.58956)
		(mid 366.390169 -242.054126)
		(end 366.146842 -242.518692)
		(width 0.1143)
		(layer "In11.Cu")
		(net "P5E_CPU0_G3_RX_DN<9>")
	)
	(arc
		(start 366.075214 -229.600506)
		(mid 365.961285 -229.733653)
		(end 365.920274 -229.904036)
		(width 0.1143)
		(layer "In11.Cu")
		(net "P5E_CPU0_G3_RX_DN<9>")
	)
	(arc
		(start 366.077246 -244.179344)
		(mid 365.961819 -244.31272)
		(end 365.920274 -244.484144)
		(width 0.1143)
		(layer "In11.Cu")
		(net "P5E_CPU0_G3_RX_DN<9>")
	)
	(arc
		(start 366.390174 -225.85426)
		(mid 366.325659 -226.116479)
		(end 366.146842 -226.318826)
		(width 0.1143)
		(layer "In11.Cu")
		(net "P5E_CPU0_G3_RX_DN<9>")
	)
	(arc
		(start 366.146842 -236.729524)
		(mid 366.390169 -237.19409)
		(end 366.146842 -237.658656)
		(width 0.1143)
		(layer "In11.Cu")
		(net "P5E_CPU0_G3_RX_DN<9>")
	)
	(arc
		(start 365.920274 -231.524048)
		(mid 365.961823 -231.69547)
		(end 366.077246 -231.828848)
		(width 0.1143)
		(layer "In11.Cu")
		(net "P5E_CPU0_G3_RX_DN<9>")
	)
	(arc
		(start 365.437674 -245.3132)
		(mid 365.365418 -245.583453)
		(end 365.167926 -245.781576)
		(width 0.1143)
		(layer "In11.Cu")
		(net "P5E_CPU0_G3_RX_DN<9>")
	)
	(arc
		(start 365.62538 -244.978682)
		(mid 365.487948 -245.115941)
		(end 365.437674 -245.303548)
		(width 0.1143)
		(layer "In11.Cu")
		(net "P5E_CPU0_G3_RX_DN<9>")
	)
	(arc
		(start 366.146842 -227.009706)
		(mid 366.390169 -227.474272)
		(end 366.146842 -227.938838)
		(width 0.1143)
		(layer "In11.Cu")
		(net "P5E_CPU0_G3_RX_DN<9>")
	)
	(arc
		(start 366.077246 -239.319308)
		(mid 365.920269 -239.624108)
		(end 366.077246 -239.928908)
		(width 0.1143)
		(layer "In11.Cu")
		(net "P5E_CPU0_G3_RX_DN<9>")
	)
	(arc
		(start 366.077246 -236.079284)
		(mid 365.920269 -236.384084)
		(end 366.077246 -236.688884)
		(width 0.1143)
		(layer "In11.Cu")
		(net "P5E_CPU0_G3_RX_DN<9>")
	)
	(arc
		(start 366.146842 -243.209572)
		(mid 366.390169 -243.674138)
		(end 366.146842 -244.138704)
		(width 0.1143)
		(layer "In11.Cu")
		(net "P5E_CPU0_G3_RX_DN<9>")
	)
	(arc
		(start 366.077246 -226.359466)
		(mid 365.920269 -226.664266)
		(end 366.077246 -226.969066)
		(width 0.1143)
		(layer "In11.Cu")
		(net "P5E_CPU0_G3_RX_DN<9>")
	)
	(arc
		(start 366.146842 -235.109512)
		(mid 366.390169 -235.574078)
		(end 366.146842 -236.038644)
		(width 0.1143)
		(layer "In11.Cu")
		(net "P5E_CPU0_G3_RX_DN<9>")
	)
	(arc
		(start 366.077246 -242.559332)
		(mid 365.920269 -242.864132)
		(end 366.077246 -243.168932)
		(width 0.1143)
		(layer "In11.Cu")
		(net "P5E_CPU0_G3_RX_DN<9>")
	)
	(arc
		(start 366.860328 -225.044254)
		(mid 366.795813 -225.306473)
		(end 366.616996 -225.50882)
		(width 0.1143)
		(layer "In11.Cu")
		(net "P5E_CPU0_G3_RX_DN<9>")
	)
	(arc
		(start 366.390174 -230.714296)
		(mid 366.325659 -230.976515)
		(end 366.146842 -231.178862)
		(width 0.1143)
		(layer "In11.Cu")
		(net "P5E_CPU0_G3_RX_DN<9>")
	)
	(arc
		(start 366.077246 -237.699296)
		(mid 365.920269 -238.004096)
		(end 366.077246 -238.308896)
		(width 0.1143)
		(layer "In11.Cu")
		(net "P5E_CPU0_G3_RX_DN<9>")
	)
	(arc
		(start 366.146842 -233.4895)
		(mid 366.390169 -233.954066)
		(end 366.146842 -234.418632)
		(width 0.1143)
		(layer "In11.Cu")
		(net "P5E_CPU0_G3_RX_DN<9>")
	)
	(arc
		(start 366.077246 -240.93932)
		(mid 365.920269 -241.24412)
		(end 366.077246 -241.54892)
		(width 0.1143)
		(layer "In11.Cu")
		(net "P5E_CPU0_G3_RX_DN<9>")
	)
	(arc
		(start 367.086896 -223.769682)
		(mid 367.330223 -224.234248)
		(end 367.086896 -224.698814)
		(width 0.1143)
		(layer "In11.Cu")
		(net "P5E_CPU0_G3_RX_DN<9>")
	)
	(arc
		(start 367.0173 -224.739454)
		(mid 366.901873 -224.87283)
		(end 366.860328 -225.044254)
		(width 0.1143)
		(layer "In11.Cu")
		(net "P5E_CPU0_G3_RX_DN<9>")
	)
	(arc
		(start 367.04778 -222.12681)
		(mid 367.328427 -222.614236)
		(end 367.04778 -223.101662)
		(width 0.1143)
		(layer "In11.Cu")
		(net "P5E_CPU0_G3_RX_DN<9>")
	)
	(arc
		(start 367.01603 -223.11995)
		(mid 366.860102 -223.424242)
		(end 367.01603 -223.728534)
		(width 0.1143)
		(layer "In11.Cu")
		(net "P5E_CPU0_G3_RX_DN<9>")
	)
	(arc
		(start 366.075214 -231.220518)
		(mid 365.961285 -231.353665)
		(end 365.920274 -231.524048)
		(width 0.1143)
		(layer "In11.Cu")
		(net "P5E_CPU0_G3_RX_DN<9>")
	)
	(arc
		(start 366.54613 -225.549968)
		(mid 366.431454 -225.683302)
		(end 366.390174 -225.85426)
		(width 0.1143)
		(layer "In11.Cu")
		(net "P5E_CPU0_G3_RX_DN<9>")
	)
	(arc
		(start 366.146842 -228.629718)
		(mid 366.390169 -229.094284)
		(end 366.146842 -229.55885)
		(width 0.1143)
		(layer "In11.Cu")
		(net "P5E_CPU0_G3_RX_DN<9>")
	)
	(arc
		(start 365.920274 -229.904036)
		(mid 365.961823 -230.075458)
		(end 366.077246 -230.208836)
		(width 0.1143)
		(layer "In11.Cu")
		(net "P5E_CPU0_G3_RX_DN<9>")
	)
	(arc
		(start 366.146842 -238.349536)
		(mid 366.390169 -238.814102)
		(end 366.146842 -239.278668)
		(width 0.1143)
		(layer "In11.Cu")
		(net "P5E_CPU0_G3_RX_DN<9>")
	)
	(segment
		(start 406.983946 -4.963414)
		(end 406.709118 -5.238242)
		(width 0.12954)
		(layer "F.Cu")
		(net "P5E_CPU0_G3_RX_DN<8>")
	)
	(segment
		(start 367.707926 -247.990106)
		(end 368.174778 -247.724168)
		(width 0.12954)
		(layer "F.Cu")
		(net "P5E_CPU0_G3_RX_DN<8>")
	)
	(segment
		(start 406.709118 -7.571486)
		(end 406.846786 -7.709154)
		(width 0.12954)
		(layer "F.Cu")
		(net "P5E_CPU0_G3_RX_DN<8>")
	)
	(segment
		(start 406.846786 -7.709154)
		(end 406.846786 -8.320024)
		(width 0.12954)
		(layer "F.Cu")
		(net "P5E_CPU0_G3_RX_DN<8>")
	)
	(segment
		(start 406.709118 -5.238242)
		(end 406.709118 -7.571486)
		(width 0.12954)
		(layer "F.Cu")
		(net "P5E_CPU0_G3_RX_DN<8>")
	)
	(segment
		(start 367.047018 -243.186204)
		(end 367.04778 -243.186712)
		(width 0.1143)
		(layer "In11.Cu")
		(net "P5E_CPU0_G3_RX_DN<8>")
	)
	(segment
		(start 367.048796 -236.707172)
		(end 367.05032 -236.708188)
		(width 0.1143)
		(layer "In11.Cu")
		(net "P5E_CPU0_G3_RX_DN<8>")
	)
	(segment
		(start 367.987834 -223.101662)
		(end 367.98758 -223.101662)
		(width 0.1143)
		(layer "In11.Cu")
		(net "P5E_CPU0_G3_RX_DN<8>")
	)
	(segment
		(start 367.055146 -244.811042)
		(end 367.055908 -244.81155)
		(width 0.1143)
		(layer "In11.Cu")
		(net "P5E_CPU0_G3_RX_DN<8>")
	)
	(segment
		(start 367.95583 -222.108522)
		(end 367.986818 -222.126302)
		(width 0.1143)
		(layer "In11.Cu")
		(net "P5E_CPU0_G3_RX_DN<8>")
	)
	(segment
		(start 367.044224 -240.923572)
		(end 367.041684 -240.925096)
		(width 0.1143)
		(layer "In11.Cu")
		(net "P5E_CPU0_G3_RX_DN<8>")
	)
	(segment
		(start 367.055908 -233.471466)
		(end 367.056924 -233.471974)
		(width 0.1143)
		(layer "In11.Cu")
		(net "P5E_CPU0_G3_RX_DN<8>")
	)
	(segment
		(start 367.039144 -244.16639)
		(end 367.01603 -244.179852)
		(width 0.1143)
		(layer "In11.Cu")
		(net "P5E_CPU0_G3_RX_DN<8>")
	)
	(segment
		(start 367.047018 -246.426228)
		(end 367.04778 -246.426736)
		(width 0.1143)
		(layer "In11.Cu")
		(net "P5E_CPU0_G3_RX_DN<8>")
	)
	(segment
		(start 367.794032 -247.641364)
		(end 367.876836 -247.724168)
		(width 0.1143)
		(layer "In11.Cu")
		(net "P5E_CPU0_G3_RX_DN<8>")
	)
	(segment
		(start 367.01603 -244.788436)
		(end 367.045748 -244.805454)
		(width 0.1143)
		(layer "In11.Cu")
		(net "P5E_CPU0_G3_RX_DN<8>")
	)
	(segment
		(start 367.051336 -235.088684)
		(end 367.05286 -235.0897)
		(width 0.1143)
		(layer "In11.Cu")
		(net "P5E_CPU0_G3_RX_DN<8>")
	)
	(segment
		(start 314.429902 -166.377366)
		(end 318.19977 -170.147996)
		(width 0.14224)
		(layer "In11.Cu")
		(net "P5E_CPU0_G3_RX_DN<8>")
	)
	(segment
		(start 367.045748 -232.82275)
		(end 367.044224 -232.823512)
		(width 0.1143)
		(layer "In11.Cu")
		(net "P5E_CPU0_G3_RX_DN<8>")
	)
	(segment
		(start 312.67019 -160.740852)
		(end 312.67019 -162.1282)
		(width 0.14224)
		(layer "In11.Cu")
		(net "P5E_CPU0_G3_RX_DN<8>")
	)
	(segment
		(start 367.05286 -241.569748)
		(end 367.053876 -241.570256)
		(width 0.1143)
		(layer "In11.Cu")
		(net "P5E_CPU0_G3_RX_DN<8>")
	)
	(segment
		(start 367.04778 -233.46664)
		(end 367.048796 -233.467148)
		(width 0.1143)
		(layer "In11.Cu")
		(net "P5E_CPU0_G3_RX_DN<8>")
	)
	(segment
		(start 367.086896 -232.79862)
		(end 367.080038 -232.802684)
		(width 0.1143)
		(layer "In11.Cu")
		(net "P5E_CPU0_G3_RX_DN<8>")
	)
	(segment
		(start 367.01603 -246.408448)
		(end 367.045748 -246.425466)
		(width 0.1143)
		(layer "In11.Cu")
		(net "P5E_CPU0_G3_RX_DN<8>")
	)
	(segment
		(start 367.079276 -236.043216)
		(end 367.04778 -236.061504)
		(width 0.1143)
		(layer "In11.Cu")
		(net "P5E_CPU0_G3_RX_DN<8>")
	)
	(segment
		(start 367.01603 -238.308388)
		(end 367.045748 -238.325406)
		(width 0.1143)
		(layer "In11.Cu")
		(net "P5E_CPU0_G3_RX_DN<8>")
	)
	(segment
		(start 367.048796 -235.08716)
		(end 367.05032 -235.088176)
		(width 0.1143)
		(layer "In11.Cu")
		(net "P5E_CPU0_G3_RX_DN<8>")
	)
	(segment
		(start 367.079276 -234.423204)
		(end 367.04778 -234.441492)
		(width 0.1143)
		(layer "In11.Cu")
		(net "P5E_CPU0_G3_RX_DN<8>")
	)
	(segment
		(start 367.048796 -245.781068)
		(end 367.04778 -245.781576)
		(width 0.1143)
		(layer "In11.Cu")
		(net "P5E_CPU0_G3_RX_DN<8>")
	)
	(segment
		(start 367.086896 -229.55885)
		(end 367.014252 -229.601268)
		(width 0.1143)
		(layer "In11.Cu")
		(net "P5E_CPU0_G3_RX_DN<8>")
	)
	(segment
		(start 367.05286 -235.0897)
		(end 367.053876 -235.090208)
		(width 0.1143)
		(layer "In11.Cu")
		(net "P5E_CPU0_G3_RX_DN<8>")
	)
	(segment
		(start 367.086896 -244.138704)
		(end 367.080038 -244.142768)
		(width 0.1143)
		(layer "In11.Cu")
		(net "P5E_CPU0_G3_RX_DN<8>")
	)
	(segment
		(start 367.080038 -236.042708)
		(end 367.079276 -236.043216)
		(width 0.1143)
		(layer "In11.Cu")
		(net "P5E_CPU0_G3_RX_DN<8>")
	)
	(segment
		(start 367.52022 -225.530156)
		(end 367.518696 -225.531172)
		(width 0.1143)
		(layer "In11.Cu")
		(net "P5E_CPU0_G3_RX_DN<8>")
	)
	(segment
		(start 367.047018 -239.94618)
		(end 367.04778 -239.946688)
		(width 0.1143)
		(layer "In11.Cu")
		(net "P5E_CPU0_G3_RX_DN<8>")
	)
	(segment
		(start 367.880392 -214.375492)
		(end 367.880392 -221.054676)
		(width 0.14224)
		(layer "In11.Cu")
		(net "P5E_CPU0_G3_RX_DN<8>")
	)
	(segment
		(start 409.12542 -17.46123)
		(end 409.12542 -17.76476)
		(width 0.14224)
		(layer "In11.Cu")
		(net "P5E_CPU0_G3_RX_DN<8>")
	)
	(segment
		(start 367.048796 -237.681008)
		(end 367.04778 -237.681516)
		(width 0.1143)
		(layer "In11.Cu")
		(net "P5E_CPU0_G3_RX_DN<8>")
	)
	(segment
		(start 367.04778 -232.82148)
		(end 367.047018 -232.821988)
		(width 0.1143)
		(layer "In11.Cu")
		(net "P5E_CPU0_G3_RX_DN<8>")
	)
	(segment
		(start 367.04778 -234.441492)
		(end 367.047018 -234.442)
		(width 0.1143)
		(layer "In11.Cu")
		(net "P5E_CPU0_G3_RX_DN<8>")
	)
	(segment
		(start 367.047018 -238.326168)
		(end 367.04778 -238.326676)
		(width 0.1143)
		(layer "In11.Cu")
		(net "P5E_CPU0_G3_RX_DN<8>")
	)
	(segment
		(start 367.045748 -236.062774)
		(end 367.044224 -236.063536)
		(width 0.1143)
		(layer "In11.Cu")
		(net "P5E_CPU0_G3_RX_DN<8>")
	)
	(segment
		(start 367.056924 -239.952022)
		(end 367.086896 -239.969548)
		(width 0.1143)
		(layer "In11.Cu")
		(net "P5E_CPU0_G3_RX_DN<8>")
	)
	(segment
		(start 367.045748 -240.92281)
		(end 367.044224 -240.923572)
		(width 0.1143)
		(layer "In11.Cu")
		(net "P5E_CPU0_G3_RX_DN<8>")
	)
	(segment
		(start 367.044224 -244.163596)
		(end 367.041684 -244.16512)
		(width 0.1143)
		(layer "In11.Cu")
		(net "P5E_CPU0_G3_RX_DN<8>")
	)
	(segment
		(start 367.053876 -239.950244)
		(end 367.055146 -239.951006)
		(width 0.1143)
		(layer "In11.Cu")
		(net "P5E_CPU0_G3_RX_DN<8>")
	)
	(segment
		(start 367.056924 -244.812058)
		(end 367.086896 -244.829584)
		(width 0.1143)
		(layer "In11.Cu")
		(net "P5E_CPU0_G3_RX_DN<8>")
	)
	(segment
		(start 367.98885 -223.74733)
		(end 367.990374 -223.748346)
		(width 0.1143)
		(layer "In11.Cu")
		(net "P5E_CPU0_G3_RX_DN<8>")
	)
	(segment
		(start 367.079276 -244.143276)
		(end 367.04778 -244.161564)
		(width 0.1143)
		(layer "In11.Cu")
		(net "P5E_CPU0_G3_RX_DN<8>")
	)
	(segment
		(start 406.693116 -11.530838)
		(end 407.001218 -12.546584)
		(width 0.14224)
		(layer "In11.Cu")
		(net "P5E_CPU0_G3_RX_DN<8>")
	)
	(segment
		(start 367.98758 -223.101662)
		(end 367.9571 -223.119442)
		(width 0.1143)
		(layer "In11.Cu")
		(net "P5E_CPU0_G3_RX_DN<8>")
	)
	(segment
		(start 403.153626 -26.914602)
		(end 323.717412 -126.887478)
		(width 0.14224)
		(layer "In11.Cu")
		(net "P5E_CPU0_G3_RX_DN<8>")
	)
	(segment
		(start 367.01603 -231.82834)
		(end 367.045748 -231.845358)
		(width 0.1143)
		(layer "In11.Cu")
		(net "P5E_CPU0_G3_RX_DN<8>")
	)
	(segment
		(start 367.055146 -231.850946)
		(end 367.055908 -231.851454)
		(width 0.1143)
		(layer "In11.Cu")
		(net "P5E_CPU0_G3_RX_DN<8>")
	)
	(segment
		(start 367.05032 -245.780052)
		(end 367.048796 -245.781068)
		(width 0.1143)
		(layer "In11.Cu")
		(net "P5E_CPU0_G3_RX_DN<8>")
	)
	(segment
		(start 367.045748 -234.442762)
		(end 367.044224 -234.443524)
		(width 0.1143)
		(layer "In11.Cu")
		(net "P5E_CPU0_G3_RX_DN<8>")
	)
	(segment
		(start 367.04778 -228.606858)
		(end 367.086896 -228.629718)
		(width 0.1143)
		(layer "In11.Cu")
		(net "P5E_CPU0_G3_RX_DN<8>")
	)
	(segment
		(start 367.041684 -239.305084)
		(end 367.039144 -239.306354)
		(width 0.1143)
		(layer "In11.Cu")
		(net "P5E_CPU0_G3_RX_DN<8>")
	)
	(segment
		(start 367.98758 -222.12681)
		(end 367.987834 -222.127064)
		(width 0.1143)
		(layer "In11.Cu")
		(net "P5E_CPU0_G3_RX_DN<8>")
	)
	(segment
		(start 367.039144 -234.446318)
		(end 367.01603 -234.45978)
		(width 0.1143)
		(layer "In11.Cu")
		(net "P5E_CPU0_G3_RX_DN<8>")
	)
	(segment
		(start 367.051336 -239.94872)
		(end 367.05286 -239.949736)
		(width 0.1143)
		(layer "In11.Cu")
		(net "P5E_CPU0_G3_RX_DN<8>")
	)
	(segment
		(start 367.01603 -233.448352)
		(end 367.045748 -233.46537)
		(width 0.1143)
		(layer "In11.Cu")
		(net "P5E_CPU0_G3_RX_DN<8>")
	)
	(segment
		(start 367.047018 -235.086144)
		(end 367.04778 -235.086652)
		(width 0.1143)
		(layer "In11.Cu")
		(net "P5E_CPU0_G3_RX_DN<8>")
	)
	(segment
		(start 367.834672 -221.128844)
		(end 367.834672 -221.387416)
		(width 0.1143)
		(layer "In11.Cu")
		(net "P5E_CPU0_G3_RX_DN<8>")
	)
	(segment
		(start 367.041684 -234.445048)
		(end 367.039144 -234.446318)
		(width 0.1143)
		(layer "In11.Cu")
		(net "P5E_CPU0_G3_RX_DN<8>")
	)
	(segment
		(start 409.054808 -17.935702)
		(end 408.740102 -18.523712)
		(width 0.14224)
		(layer "In11.Cu")
		(net "P5E_CPU0_G3_RX_DN<8>")
	)
	(segment
		(start 367.047018 -236.062012)
		(end 367.045748 -236.062774)
		(width 0.1143)
		(layer "In11.Cu")
		(net "P5E_CPU0_G3_RX_DN<8>")
	)
	(segment
		(start 367.056924 -241.572034)
		(end 367.086896 -241.58956)
		(width 0.1143)
		(layer "In11.Cu")
		(net "P5E_CPU0_G3_RX_DN<8>")
	)
	(segment
		(start 367.047018 -244.806216)
		(end 367.04778 -244.806724)
		(width 0.1143)
		(layer "In11.Cu")
		(net "P5E_CPU0_G3_RX_DN<8>")
	)
	(segment
		(start 367.04778 -239.301528)
		(end 367.047018 -239.302036)
		(width 0.1143)
		(layer "In11.Cu")
		(net "P5E_CPU0_G3_RX_DN<8>")
	)
	(segment
		(start 367.051336 -233.468672)
		(end 367.05286 -233.469688)
		(width 0.1143)
		(layer "In11.Cu")
		(net "P5E_CPU0_G3_RX_DN<8>")
	)
	(segment
		(start 367.086896 -242.518692)
		(end 367.05032 -242.540028)
		(width 0.1143)
		(layer "In11.Cu")
		(net "P5E_CPU0_G3_RX_DN<8>")
	)
	(segment
		(start 367.05032 -246.42826)
		(end 367.051336 -246.428768)
		(width 0.1143)
		(layer "In11.Cu")
		(net "P5E_CPU0_G3_RX_DN<8>")
	)
	(segment
		(start 367.01603 -230.208328)
		(end 367.04778 -230.226616)
		(width 0.1143)
		(layer "In11.Cu")
		(net "P5E_CPU0_G3_RX_DN<8>")
	)
	(segment
		(start 368.02695 -224.698814)
		(end 367.987834 -224.721674)
		(width 0.1143)
		(layer "In11.Cu")
		(net "P5E_CPU0_G3_RX_DN<8>")
	)
	(segment
		(start 367.056924 -235.091986)
		(end 367.086896 -235.109512)
		(width 0.1143)
		(layer "In11.Cu")
		(net "P5E_CPU0_G3_RX_DN<8>")
	)
	(segment
		(start 367.041684 -236.06506)
		(end 367.039144 -236.06633)
		(width 0.1143)
		(layer "In11.Cu")
		(net "P5E_CPU0_G3_RX_DN<8>")
	)
	(segment
		(start 367.053876 -231.850184)
		(end 367.055146 -231.850946)
		(width 0.1143)
		(layer "In11.Cu")
		(net "P5E_CPU0_G3_RX_DN<8>")
	)
	(segment
		(start 367.055908 -235.091478)
		(end 367.056924 -235.091986)
		(width 0.1143)
		(layer "In11.Cu")
		(net "P5E_CPU0_G3_RX_DN<8>")
	)
	(segment
		(start 367.987834 -224.721674)
		(end 367.9571 -224.739454)
		(width 0.1143)
		(layer "In11.Cu")
		(net "P5E_CPU0_G3_RX_DN<8>")
	)
	(segment
		(start 367.055146 -243.19103)
		(end 367.055908 -243.191538)
		(width 0.1143)
		(layer "In11.Cu")
		(net "P5E_CPU0_G3_RX_DN<8>")
	)
	(segment
		(start 367.047018 -234.442)
		(end 367.045748 -234.442762)
		(width 0.1143)
		(layer "In11.Cu")
		(net "P5E_CPU0_G3_RX_DN<8>")
	)
	(segment
		(start 323.717412 -126.887478)
		(end 320.942462 -131.852416)
		(width 0.14224)
		(layer "In11.Cu")
		(net "P5E_CPU0_G3_RX_DN<8>")
	)
	(segment
		(start 367.05286 -246.429784)
		(end 367.053876 -246.430292)
		(width 0.1143)
		(layer "In11.Cu")
		(net "P5E_CPU0_G3_RX_DN<8>")
	)
	(segment
		(start 367.044224 -232.823512)
		(end 367.041684 -232.825036)
		(width 0.1143)
		(layer "In11.Cu")
		(net "P5E_CPU0_G3_RX_DN<8>")
	)
	(segment
		(start 367.048796 -241.567208)
		(end 367.05032 -241.568224)
		(width 0.1143)
		(layer "In11.Cu")
		(net "P5E_CPU0_G3_RX_DN<8>")
	)
	(segment
		(start 367.056924 -231.851962)
		(end 367.086896 -231.869488)
		(width 0.1143)
		(layer "In11.Cu")
		(net "P5E_CPU0_G3_RX_DN<8>")
	)
	(segment
		(start 367.01603 -239.9284)
		(end 367.045748 -239.945418)
		(width 0.1143)
		(layer "In11.Cu")
		(net "P5E_CPU0_G3_RX_DN<8>")
	)
	(segment
		(start 367.05286 -236.709712)
		(end 367.053876 -236.71022)
		(width 0.1143)
		(layer "In11.Cu")
		(net "P5E_CPU0_G3_RX_DN<8>")
	)
	(segment
		(start 367.080038 -239.282732)
		(end 367.079276 -239.28324)
		(width 0.1143)
		(layer "In11.Cu")
		(net "P5E_CPU0_G3_RX_DN<8>")
	)
	(segment
		(start 367.01603 -241.548412)
		(end 367.045748 -241.56543)
		(width 0.1143)
		(layer "In11.Cu")
		(net "P5E_CPU0_G3_RX_DN<8>")
	)
	(segment
		(start 367.053876 -236.71022)
		(end 367.055146 -236.710982)
		(width 0.1143)
		(layer "In11.Cu")
		(net "P5E_CPU0_G3_RX_DN<8>")
	)
	(segment
		(start 367.056924 -246.43207)
		(end 367.086896 -246.449596)
		(width 0.1143)
		(layer "In11.Cu")
		(net "P5E_CPU0_G3_RX_DN<8>")
	)
	(segment
		(start 367.039144 -239.306354)
		(end 367.01603 -239.319816)
		(width 0.1143)
		(layer "In11.Cu")
		(net "P5E_CPU0_G3_RX_DN<8>")
	)
	(segment
		(start 367.045748 -233.46537)
		(end 367.047018 -233.466132)
		(width 0.1143)
		(layer "In11.Cu")
		(net "P5E_CPU0_G3_RX_DN<8>")
	)
	(segment
		(start 324.060566 -173.662086)
		(end 324.5358 -174.03318)
		(width 0.14224)
		(layer "In11.Cu")
		(net "P5E_CPU0_G3_RX_DN<8>")
	)
	(segment
		(start 367.045748 -231.845358)
		(end 367.047018 -231.84612)
		(width 0.1143)
		(layer "In11.Cu")
		(net "P5E_CPU0_G3_RX_DN<8>")
	)
	(segment
		(start 367.05032 -241.568224)
		(end 367.051336 -241.568732)
		(width 0.1143)
		(layer "In11.Cu")
		(net "P5E_CPU0_G3_RX_DN<8>")
	)
	(segment
		(start 367.051336 -236.708696)
		(end 367.05286 -236.709712)
		(width 0.1143)
		(layer "In11.Cu")
		(net "P5E_CPU0_G3_RX_DN<8>")
	)
	(segment
		(start 367.045748 -243.185442)
		(end 367.047018 -243.186204)
		(width 0.1143)
		(layer "In11.Cu")
		(net "P5E_CPU0_G3_RX_DN<8>")
	)
	(segment
		(start 367.05032 -239.948212)
		(end 367.051336 -239.94872)
		(width 0.1143)
		(layer "In11.Cu")
		(net "P5E_CPU0_G3_RX_DN<8>")
	)
	(segment
		(start 312.67019 -162.1282)
		(end 314.429902 -166.377112)
		(width 0.14224)
		(layer "In11.Cu")
		(net "P5E_CPU0_G3_RX_DN<8>")
	)
	(segment
		(start 367.041684 -240.925096)
		(end 367.039144 -240.926366)
		(width 0.1143)
		(layer "In11.Cu")
		(net "P5E_CPU0_G3_RX_DN<8>")
	)
	(segment
		(start 367.01603 -236.688376)
		(end 367.045748 -236.705394)
		(width 0.1143)
		(layer "In11.Cu")
		(net "P5E_CPU0_G3_RX_DN<8>")
	)
	(segment
		(start 367.05032 -242.540028)
		(end 367.048796 -242.541044)
		(width 0.1143)
		(layer "In11.Cu")
		(net "P5E_CPU0_G3_RX_DN<8>")
	)
	(segment
		(start 409.12542 -17.76476)
		(end 409.054808 -17.935702)
		(width 0.14224)
		(layer "In11.Cu")
		(net "P5E_CPU0_G3_RX_DN<8>")
	)
	(segment
		(start 367.055908 -241.571526)
		(end 367.056924 -241.572034)
		(width 0.1143)
		(layer "In11.Cu")
		(net "P5E_CPU0_G3_RX_DN<8>")
	)
	(segment
		(start 367.045748 -246.425466)
		(end 367.047018 -246.426228)
		(width 0.1143)
		(layer "In11.Cu")
		(net "P5E_CPU0_G3_RX_DN<8>")
	)
	(segment
		(start 367.047018 -239.302036)
		(end 367.045748 -239.302798)
		(width 0.1143)
		(layer "In11.Cu")
		(net "P5E_CPU0_G3_RX_DN<8>")
	)
	(segment
		(start 367.01603 -235.068364)
		(end 367.045748 -235.085382)
		(width 0.1143)
		(layer "In11.Cu")
		(net "P5E_CPU0_G3_RX_DN<8>")
	)
	(segment
		(start 367.055908 -243.191538)
		(end 367.056924 -243.192046)
		(width 0.1143)
		(layer "In11.Cu")
		(net "P5E_CPU0_G3_RX_DN<8>")
	)
	(segment
		(start 367.080038 -232.802684)
		(end 367.079276 -232.803192)
		(width 0.1143)
		(layer "In11.Cu")
		(net "P5E_CPU0_G3_RX_DN<8>")
	)
	(segment
		(start 367.048796 -231.847136)
		(end 367.05032 -231.848152)
		(width 0.1143)
		(layer "In11.Cu")
		(net "P5E_CPU0_G3_RX_DN<8>")
	)
	(segment
		(start 367.047018 -244.162072)
		(end 367.045748 -244.162834)
		(width 0.1143)
		(layer "In11.Cu")
		(net "P5E_CPU0_G3_RX_DN<8>")
	)
	(segment
		(start 367.01603 -243.168424)
		(end 367.045748 -243.185442)
		(width 0.1143)
		(layer "In11.Cu")
		(net "P5E_CPU0_G3_RX_DN<8>")
	)
	(segment
		(start 367.053876 -244.81028)
		(end 367.055146 -244.811042)
		(width 0.1143)
		(layer "In11.Cu")
		(net "P5E_CPU0_G3_RX_DN<8>")
	)
	(segment
		(start 367.04778 -241.5667)
		(end 367.048796 -241.567208)
		(width 0.1143)
		(layer "In11.Cu")
		(net "P5E_CPU0_G3_RX_DN<8>")
	)
	(segment
		(start 367.044224 -234.443524)
		(end 367.041684 -234.445048)
		(width 0.1143)
		(layer "In11.Cu")
		(net "P5E_CPU0_G3_RX_DN<8>")
	)
	(segment
		(start 314.73902 -148.965412)
		(end 312.67019 -160.740852)
		(width 0.14224)
		(layer "In11.Cu")
		(net "P5E_CPU0_G3_RX_DN<8>")
	)
	(segment
		(start 367.017046 -226.969066)
		(end 367.086642 -227.009706)
		(width 0.1143)
		(layer "In11.Cu")
		(net "P5E_CPU0_G3_RX_DN<8>")
	)
	(segment
		(start 367.041684 -244.16512)
		(end 367.039144 -244.16639)
		(width 0.1143)
		(layer "In11.Cu")
		(net "P5E_CPU0_G3_RX_DN<8>")
	)
	(segment
		(start 367.047018 -236.706156)
		(end 367.04778 -236.706664)
		(width 0.1143)
		(layer "In11.Cu")
		(net "P5E_CPU0_G3_RX_DN<8>")
	)
	(segment
		(start 367.987834 -223.746822)
		(end 367.98885 -223.74733)
		(width 0.1143)
		(layer "In11.Cu")
		(net "P5E_CPU0_G3_RX_DN<8>")
	)
	(segment
		(start 367.05286 -243.18976)
		(end 367.053876 -243.190268)
		(width 0.1143)
		(layer "In11.Cu")
		(net "P5E_CPU0_G3_RX_DN<8>")
	)
	(segment
		(start 367.04778 -236.706664)
		(end 367.048796 -236.707172)
		(width 0.1143)
		(layer "In11.Cu")
		(net "P5E_CPU0_G3_RX_DN<8>")
	)
	(segment
		(start 367.051336 -231.84866)
		(end 367.05286 -231.849676)
		(width 0.1143)
		(layer "In11.Cu")
		(net "P5E_CPU0_G3_RX_DN<8>")
	)
	(segment
		(start 367.086896 -245.758716)
		(end 367.05032 -245.780052)
		(width 0.1143)
		(layer "In11.Cu")
		(net "P5E_CPU0_G3_RX_DN<8>")
	)
	(segment
		(start 367.053876 -243.190268)
		(end 367.055146 -243.19103)
		(width 0.1143)
		(layer "In11.Cu")
		(net "P5E_CPU0_G3_RX_DN<8>")
	)
	(segment
		(start 367.053876 -246.430292)
		(end 367.055146 -246.431054)
		(width 0.1143)
		(layer "In11.Cu")
		(net "P5E_CPU0_G3_RX_DN<8>")
	)
	(segment
		(start 367.045748 -239.945418)
		(end 367.047018 -239.94618)
		(width 0.1143)
		(layer "In11.Cu")
		(net "P5E_CPU0_G3_RX_DN<8>")
	)
	(segment
		(start 367.080038 -240.902744)
		(end 367.079276 -240.903252)
		(width 0.1143)
		(layer "In11.Cu")
		(net "P5E_CPU0_G3_RX_DN<8>")
	)
	(segment
		(start 367.086896 -237.658656)
		(end 367.05032 -237.679992)
		(width 0.1143)
		(layer "In11.Cu")
		(net "P5E_CPU0_G3_RX_DN<8>")
	)
	(segment
		(start 367.086896 -234.418632)
		(end 367.080038 -234.422696)
		(width 0.1143)
		(layer "In11.Cu")
		(net "P5E_CPU0_G3_RX_DN<8>")
	)
	(segment
		(start 367.048796 -238.327184)
		(end 367.086896 -238.349536)
		(width 0.1143)
		(layer "In11.Cu")
		(net "P5E_CPU0_G3_RX_DN<8>")
	)
	(segment
		(start 367.041684 -232.825036)
		(end 367.039144 -232.826306)
		(width 0.1143)
		(layer "In11.Cu")
		(net "P5E_CPU0_G3_RX_DN<8>")
	)
	(segment
		(start 367.79962 -221.422468)
		(end 367.79962 -221.579694)
		(width 0.1143)
		(layer "In11.Cu")
		(net "P5E_CPU0_G3_RX_DN<8>")
	)
	(segment
		(start 367.04778 -230.226616)
		(end 367.084356 -230.247952)
		(width 0.1143)
		(layer "In11.Cu")
		(net "P5E_CPU0_G3_RX_DN<8>")
	)
	(segment
		(start 367.045748 -239.302798)
		(end 367.044224 -239.30356)
		(width 0.1143)
		(layer "In11.Cu")
		(net "P5E_CPU0_G3_RX_DN<8>")
	)
	(segment
		(start 367.079276 -239.28324)
		(end 367.04778 -239.301528)
		(width 0.1143)
		(layer "In11.Cu")
		(net "P5E_CPU0_G3_RX_DN<8>")
	)
	(segment
		(start 406.693116 -5.254244)
		(end 406.693116 -11.530838)
		(width 0.14224)
		(layer "In11.Cu")
		(net "P5E_CPU0_G3_RX_DN<8>")
	)
	(segment
		(start 367.053876 -241.570256)
		(end 367.055146 -241.571018)
		(width 0.1143)
		(layer "In11.Cu")
		(net "P5E_CPU0_G3_RX_DN<8>")
	)
	(segment
		(start 407.001218 -12.546584)
		(end 407.726134 -14.078712)
		(width 0.14224)
		(layer "In11.Cu")
		(net "P5E_CPU0_G3_RX_DN<8>")
	)
	(segment
		(start 367.086896 -239.278668)
		(end 367.080038 -239.282732)
		(width 0.1143)
		(layer "In11.Cu")
		(net "P5E_CPU0_G3_RX_DN<8>")
	)
	(segment
		(start 367.048796 -239.947196)
		(end 367.05032 -239.948212)
		(width 0.1143)
		(layer "In11.Cu")
		(net "P5E_CPU0_G3_RX_DN<8>")
	)
	(segment
		(start 367.04778 -244.806724)
		(end 367.048796 -244.807232)
		(width 0.1143)
		(layer "In11.Cu")
		(net "P5E_CPU0_G3_RX_DN<8>")
	)
	(segment
		(start 367.045748 -238.325406)
		(end 367.047018 -238.326168)
		(width 0.1143)
		(layer "In11.Cu")
		(net "P5E_CPU0_G3_RX_DN<8>")
	)
	(segment
		(start 367.053876 -235.090208)
		(end 367.055146 -235.09097)
		(width 0.1143)
		(layer "In11.Cu")
		(net "P5E_CPU0_G3_RX_DN<8>")
	)
	(segment
		(start 367.055908 -239.951514)
		(end 367.056924 -239.952022)
		(width 0.1143)
		(layer "In11.Cu")
		(net "P5E_CPU0_G3_RX_DN<8>")
	)
	(segment
		(start 367.047018 -232.821988)
		(end 367.045748 -232.82275)
		(width 0.1143)
		(layer "In11.Cu")
		(net "P5E_CPU0_G3_RX_DN<8>")
	)
	(segment
		(start 367.516918 -225.532188)
		(end 367.48593 -225.549968)
		(width 0.1143)
		(layer "In11.Cu")
		(net "P5E_CPU0_G3_RX_DN<8>")
	)
	(segment
		(start 367.05032 -233.468164)
		(end 367.051336 -233.468672)
		(width 0.1143)
		(layer "In11.Cu")
		(net "P5E_CPU0_G3_RX_DN<8>")
	)
	(segment
		(start 367.044224 -236.063536)
		(end 367.041684 -236.06506)
		(width 0.1143)
		(layer "In11.Cu")
		(net "P5E_CPU0_G3_RX_DN<8>")
	)
	(segment
		(start 367.79962 -221.579694)
		(end 367.799874 -221.579948)
		(width 0.1143)
		(layer "In11.Cu")
		(net "P5E_CPU0_G3_RX_DN<8>")
	)
	(segment
		(start 367.048796 -233.467148)
		(end 367.05032 -233.468164)
		(width 0.1143)
		(layer "In11.Cu")
		(net "P5E_CPU0_G3_RX_DN<8>")
	)
	(segment
		(start 367.04778 -245.781576)
		(end 367.01603 -245.799864)
		(width 0.1143)
		(layer "In11.Cu")
		(net "P5E_CPU0_G3_RX_DN<8>")
	)
	(segment
		(start 367.556796 -225.50882)
		(end 367.52022 -225.530156)
		(width 0.1143)
		(layer "In11.Cu")
		(net "P5E_CPU0_G3_RX_DN<8>")
	)
	(segment
		(start 367.990374 -223.748346)
		(end 368.02695 -223.769682)
		(width 0.1143)
		(layer "In11.Cu")
		(net "P5E_CPU0_G3_RX_DN<8>")
	)
	(segment
		(start 367.045748 -235.085382)
		(end 367.047018 -235.086144)
		(width 0.1143)
		(layer "In11.Cu")
		(net "P5E_CPU0_G3_RX_DN<8>")
	)
	(segment
		(start 367.048796 -242.541044)
		(end 367.04778 -242.541552)
		(width 0.1143)
		(layer "In11.Cu")
		(net "P5E_CPU0_G3_RX_DN<8>")
	)
	(segment
		(start 367.051336 -241.568732)
		(end 367.05286 -241.569748)
		(width 0.1143)
		(layer "In11.Cu")
		(net "P5E_CPU0_G3_RX_DN<8>")
	)
	(segment
		(start 367.051336 -244.808756)
		(end 367.05286 -244.809772)
		(width 0.1143)
		(layer "In11.Cu")
		(net "P5E_CPU0_G3_RX_DN<8>")
	)
	(segment
		(start 324.5358 -174.03318)
		(end 362.305092 -204.985366)
		(width 0.14224)
		(layer "In11.Cu")
		(net "P5E_CPU0_G3_RX_DN<8>")
	)
	(segment
		(start 367.05032 -231.848152)
		(end 367.051336 -231.84866)
		(width 0.1143)
		(layer "In11.Cu")
		(net "P5E_CPU0_G3_RX_DN<8>")
	)
	(segment
		(start 367.080038 -234.422696)
		(end 367.079276 -234.423204)
		(width 0.1143)
		(layer "In11.Cu")
		(net "P5E_CPU0_G3_RX_DN<8>")
	)
	(segment
		(start 408.740102 -18.523712)
		(end 403.153626 -26.914602)
		(width 0.14224)
		(layer "In11.Cu")
		(net "P5E_CPU0_G3_RX_DN<8>")
	)
	(segment
		(start 367.04778 -244.161564)
		(end 367.047018 -244.162072)
		(width 0.1143)
		(layer "In11.Cu")
		(net "P5E_CPU0_G3_RX_DN<8>")
	)
	(segment
		(start 367.055146 -233.470958)
		(end 367.055908 -233.471466)
		(width 0.1143)
		(layer "In11.Cu")
		(net "P5E_CPU0_G3_RX_DN<8>")
	)
	(segment
		(start 367.05032 -244.808248)
		(end 367.051336 -244.808756)
		(width 0.1143)
		(layer "In11.Cu")
		(net "P5E_CPU0_G3_RX_DN<8>")
	)
	(segment
		(start 367.086642 -226.318826)
		(end 367.017046 -226.359466)
		(width 0.1143)
		(layer "In11.Cu")
		(net "P5E_CPU0_G3_RX_DN<8>")
	)
	(segment
		(start 367.044224 -239.30356)
		(end 367.041684 -239.305084)
		(width 0.1143)
		(layer "In11.Cu")
		(net "P5E_CPU0_G3_RX_DN<8>")
	)
	(segment
		(start 367.05286 -231.849676)
		(end 367.053876 -231.850184)
		(width 0.1143)
		(layer "In11.Cu")
		(net "P5E_CPU0_G3_RX_DN<8>")
	)
	(segment
		(start 367.04778 -237.681516)
		(end 367.01603 -237.699804)
		(width 0.1143)
		(layer "In11.Cu")
		(net "P5E_CPU0_G3_RX_DN<8>")
	)
	(segment
		(start 367.045748 -236.705394)
		(end 367.047018 -236.706156)
		(width 0.1143)
		(layer "In11.Cu")
		(net "P5E_CPU0_G3_RX_DN<8>")
	)
	(segment
		(start 367.04778 -236.061504)
		(end 367.047018 -236.062012)
		(width 0.1143)
		(layer "In11.Cu")
		(net "P5E_CPU0_G3_RX_DN<8>")
	)
	(segment
		(start 320.942462 -131.852416)
		(end 314.73902 -148.965412)
		(width 0.14224)
		(layer "In11.Cu")
		(net "P5E_CPU0_G3_RX_DN<8>")
	)
	(segment
		(start 367.04778 -246.426736)
		(end 367.048796 -246.427244)
		(width 0.1143)
		(layer "In11.Cu")
		(net "P5E_CPU0_G3_RX_DN<8>")
	)
	(segment
		(start 406.983946 -4.963414)
		(end 406.693116 -5.254244)
		(width 0.14224)
		(layer "In11.Cu")
		(net "P5E_CPU0_G3_RX_DN<8>")
	)
	(segment
		(start 367.956084 -223.728534)
		(end 367.987834 -223.746822)
		(width 0.1143)
		(layer "In11.Cu")
		(net "P5E_CPU0_G3_RX_DN<8>")
	)
	(segment
		(start 367.047018 -233.466132)
		(end 367.04778 -233.46664)
		(width 0.1143)
		(layer "In11.Cu")
		(net "P5E_CPU0_G3_RX_DN<8>")
	)
	(segment
		(start 367.086896 -236.038644)
		(end 367.080038 -236.042708)
		(width 0.1143)
		(layer "In11.Cu")
		(net "P5E_CPU0_G3_RX_DN<8>")
	)
	(segment
		(start 367.017046 -228.589078)
		(end 367.04778 -228.606858)
		(width 0.1143)
		(layer "In11.Cu")
		(net "P5E_CPU0_G3_RX_DN<8>")
	)
	(segment
		(start 314.429902 -166.377112)
		(end 314.429902 -166.377366)
		(width 0.14224)
		(layer "In11.Cu")
		(net "P5E_CPU0_G3_RX_DN<8>")
	)
	(segment
		(start 367.876836 -247.724168)
		(end 368.174778 -247.724168)
		(width 0.1143)
		(layer "In11.Cu")
		(net "P5E_CPU0_G3_RX_DN<8>")
	)
	(segment
		(start 367.834672 -221.387416)
		(end 367.79962 -221.422468)
		(width 0.1143)
		(layer "In11.Cu")
		(net "P5E_CPU0_G3_RX_DN<8>")
	)
	(segment
		(start 367.04778 -231.846628)
		(end 367.048796 -231.847136)
		(width 0.1143)
		(layer "In11.Cu")
		(net "P5E_CPU0_G3_RX_DN<8>")
	)
	(segment
		(start 367.05032 -243.188236)
		(end 367.051336 -243.188744)
		(width 0.1143)
		(layer "In11.Cu")
		(net "P5E_CPU0_G3_RX_DN<8>")
	)
	(segment
		(start 367.518696 -225.531172)
		(end 367.51768 -225.53168)
		(width 0.1143)
		(layer "In11.Cu")
		(net "P5E_CPU0_G3_RX_DN<8>")
	)
	(segment
		(start 367.986818 -222.126302)
		(end 367.98758 -222.12681)
		(width 0.1143)
		(layer "In11.Cu")
		(net "P5E_CPU0_G3_RX_DN<8>")
	)
	(segment
		(start 367.079276 -240.903252)
		(end 367.04778 -240.92154)
		(width 0.1143)
		(layer "In11.Cu")
		(net "P5E_CPU0_G3_RX_DN<8>")
	)
	(segment
		(start 367.055146 -239.951006)
		(end 367.055908 -239.951514)
		(width 0.1143)
		(layer "In11.Cu")
		(net "P5E_CPU0_G3_RX_DN<8>")
	)
	(segment
		(start 367.086896 -240.89868)
		(end 367.080038 -240.902744)
		(width 0.1143)
		(layer "In11.Cu")
		(net "P5E_CPU0_G3_RX_DN<8>")
	)
	(segment
		(start 367.045748 -241.56543)
		(end 367.047018 -241.566192)
		(width 0.1143)
		(layer "In11.Cu")
		(net "P5E_CPU0_G3_RX_DN<8>")
	)
	(segment
		(start 367.880392 -221.083124)
		(end 367.834672 -221.128844)
		(width 0.1143)
		(layer "In11.Cu")
		(net "P5E_CPU0_G3_RX_DN<8>")
	)
	(segment
		(start 367.4872 -247.218962)
		(end 367.556796 -247.259602)
		(width 0.1143)
		(layer "In11.Cu")
		(net "P5E_CPU0_G3_RX_DN<8>")
	)
	(segment
		(start 367.056924 -236.711998)
		(end 367.086896 -236.729524)
		(width 0.1143)
		(layer "In11.Cu")
		(net "P5E_CPU0_G3_RX_DN<8>")
	)
	(segment
		(start 318.19977 -170.147996)
		(end 324.060566 -173.662086)
		(width 0.14224)
		(layer "In11.Cu")
		(net "P5E_CPU0_G3_RX_DN<8>")
	)
	(segment
		(start 367.055908 -236.71149)
		(end 367.056924 -236.711998)
		(width 0.1143)
		(layer "In11.Cu")
		(net "P5E_CPU0_G3_RX_DN<8>")
	)
	(segment
		(start 367.05032 -236.708188)
		(end 367.051336 -236.708696)
		(width 0.1143)
		(layer "In11.Cu")
		(net "P5E_CPU0_G3_RX_DN<8>")
	)
	(segment
		(start 367.05032 -235.088176)
		(end 367.051336 -235.088684)
		(width 0.1143)
		(layer "In11.Cu")
		(net "P5E_CPU0_G3_RX_DN<8>")
	)
	(segment
		(start 367.045748 -244.162834)
		(end 367.044224 -244.163596)
		(width 0.1143)
		(layer "In11.Cu")
		(net "P5E_CPU0_G3_RX_DN<8>")
	)
	(segment
		(start 367.05286 -239.949736)
		(end 367.053876 -239.950244)
		(width 0.1143)
		(layer "In11.Cu")
		(net "P5E_CPU0_G3_RX_DN<8>")
	)
	(segment
		(start 367.055146 -246.431054)
		(end 367.055908 -246.431562)
		(width 0.1143)
		(layer "In11.Cu")
		(net "P5E_CPU0_G3_RX_DN<8>")
	)
	(segment
		(start 367.056924 -233.471974)
		(end 367.086896 -233.4895)
		(width 0.1143)
		(layer "In11.Cu")
		(net "P5E_CPU0_G3_RX_DN<8>")
	)
	(segment
		(start 367.04778 -240.92154)
		(end 367.047018 -240.922048)
		(width 0.1143)
		(layer "In11.Cu")
		(net "P5E_CPU0_G3_RX_DN<8>")
	)
	(segment
		(start 367.04778 -242.541552)
		(end 367.01603 -242.55984)
		(width 0.1143)
		(layer "In11.Cu")
		(net "P5E_CPU0_G3_RX_DN<8>")
	)
	(segment
		(start 367.079276 -232.803192)
		(end 367.04778 -232.82148)
		(width 0.1143)
		(layer "In11.Cu")
		(net "P5E_CPU0_G3_RX_DN<8>")
	)
	(segment
		(start 367.51768 -225.53168)
		(end 367.516918 -225.532188)
		(width 0.1143)
		(layer "In11.Cu")
		(net "P5E_CPU0_G3_RX_DN<8>")
	)
	(segment
		(start 367.05286 -233.469688)
		(end 367.053876 -233.470196)
		(width 0.1143)
		(layer "In11.Cu")
		(net "P5E_CPU0_G3_RX_DN<8>")
	)
	(segment
		(start 367.039144 -236.06633)
		(end 367.01603 -236.079792)
		(width 0.1143)
		(layer "In11.Cu")
		(net "P5E_CPU0_G3_RX_DN<8>")
	)
	(segment
		(start 367.047018 -240.922048)
		(end 367.045748 -240.92281)
		(width 0.1143)
		(layer "In11.Cu")
		(net "P5E_CPU0_G3_RX_DN<8>")
	)
	(segment
		(start 367.048796 -244.807232)
		(end 367.05032 -244.808248)
		(width 0.1143)
		(layer "In11.Cu")
		(net "P5E_CPU0_G3_RX_DN<8>")
	)
	(segment
		(start 367.047018 -241.566192)
		(end 367.04778 -241.5667)
		(width 0.1143)
		(layer "In11.Cu")
		(net "P5E_CPU0_G3_RX_DN<8>")
	)
	(segment
		(start 367.055908 -231.851454)
		(end 367.056924 -231.851962)
		(width 0.1143)
		(layer "In11.Cu")
		(net "P5E_CPU0_G3_RX_DN<8>")
	)
	(segment
		(start 367.039144 -232.826306)
		(end 367.01603 -232.839768)
		(width 0.1143)
		(layer "In11.Cu")
		(net "P5E_CPU0_G3_RX_DN<8>")
	)
	(segment
		(start 367.04778 -235.086652)
		(end 367.048796 -235.08716)
		(width 0.1143)
		(layer "In11.Cu")
		(net "P5E_CPU0_G3_RX_DN<8>")
	)
	(segment
		(start 367.05032 -237.679992)
		(end 367.048796 -237.681008)
		(width 0.1143)
		(layer "In11.Cu")
		(net "P5E_CPU0_G3_RX_DN<8>")
	)
	(segment
		(start 367.04778 -239.946688)
		(end 367.048796 -239.947196)
		(width 0.1143)
		(layer "In11.Cu")
		(net "P5E_CPU0_G3_RX_DN<8>")
	)
	(segment
		(start 367.055908 -244.81155)
		(end 367.056924 -244.812058)
		(width 0.1143)
		(layer "In11.Cu")
		(net "P5E_CPU0_G3_RX_DN<8>")
	)
	(segment
		(start 367.055908 -246.431562)
		(end 367.056924 -246.43207)
		(width 0.1143)
		(layer "In11.Cu")
		(net "P5E_CPU0_G3_RX_DN<8>")
	)
	(segment
		(start 367.048796 -246.427244)
		(end 367.05032 -246.42826)
		(width 0.1143)
		(layer "In11.Cu")
		(net "P5E_CPU0_G3_RX_DN<8>")
	)
	(segment
		(start 367.05286 -244.809772)
		(end 367.053876 -244.81028)
		(width 0.1143)
		(layer "In11.Cu")
		(net "P5E_CPU0_G3_RX_DN<8>")
	)
	(segment
		(start 367.04778 -238.326676)
		(end 367.048796 -238.327184)
		(width 0.1143)
		(layer "In11.Cu")
		(net "P5E_CPU0_G3_RX_DN<8>")
	)
	(segment
		(start 367.055146 -241.571018)
		(end 367.055908 -241.571526)
		(width 0.1143)
		(layer "In11.Cu")
		(net "P5E_CPU0_G3_RX_DN<8>")
	)
	(segment
		(start 367.051336 -243.188744)
		(end 367.05286 -243.18976)
		(width 0.1143)
		(layer "In11.Cu")
		(net "P5E_CPU0_G3_RX_DN<8>")
	)
	(segment
		(start 367.051336 -246.428768)
		(end 367.05286 -246.429784)
		(width 0.1143)
		(layer "In11.Cu")
		(net "P5E_CPU0_G3_RX_DN<8>")
	)
	(segment
		(start 367.039144 -240.926366)
		(end 367.01603 -240.939828)
		(width 0.1143)
		(layer "In11.Cu")
		(net "P5E_CPU0_G3_RX_DN<8>")
	)
	(segment
		(start 367.045748 -244.805454)
		(end 367.047018 -244.806216)
		(width 0.1143)
		(layer "In11.Cu")
		(net "P5E_CPU0_G3_RX_DN<8>")
	)
	(segment
		(start 367.086896 -231.178862)
		(end 367.014252 -231.22128)
		(width 0.1143)
		(layer "In11.Cu")
		(net "P5E_CPU0_G3_RX_DN<8>")
	)
	(segment
		(start 367.04778 -243.186712)
		(end 367.048796 -243.18722)
		(width 0.1143)
		(layer "In11.Cu")
		(net "P5E_CPU0_G3_RX_DN<8>")
	)
	(segment
		(start 362.305092 -204.985366)
		(end 367.880392 -214.375492)
		(width 0.14224)
		(layer "In11.Cu")
		(net "P5E_CPU0_G3_RX_DN<8>")
	)
	(segment
		(start 367.880392 -221.054676)
		(end 367.880392 -221.083124)
		(width 0.1143)
		(layer "In11.Cu")
		(net "P5E_CPU0_G3_RX_DN<8>")
	)
	(segment
		(start 367.056924 -243.192046)
		(end 367.086896 -243.209572)
		(width 0.1143)
		(layer "In11.Cu")
		(net "P5E_CPU0_G3_RX_DN<8>")
	)
	(segment
		(start 367.799874 -221.579948)
		(end 367.799874 -221.80423)
		(width 0.1143)
		(layer "In11.Cu")
		(net "P5E_CPU0_G3_RX_DN<8>")
	)
	(segment
		(start 367.055146 -235.09097)
		(end 367.055908 -235.091478)
		(width 0.1143)
		(layer "In11.Cu")
		(net "P5E_CPU0_G3_RX_DN<8>")
	)
	(segment
		(start 367.055146 -236.710982)
		(end 367.055908 -236.71149)
		(width 0.1143)
		(layer "In11.Cu")
		(net "P5E_CPU0_G3_RX_DN<8>")
	)
	(segment
		(start 367.080038 -244.142768)
		(end 367.079276 -244.143276)
		(width 0.1143)
		(layer "In11.Cu")
		(net "P5E_CPU0_G3_RX_DN<8>")
	)
	(segment
		(start 367.086642 -227.938838)
		(end 367.017046 -227.979478)
		(width 0.1143)
		(layer "In11.Cu")
		(net "P5E_CPU0_G3_RX_DN<8>")
	)
	(segment
		(start 367.047018 -231.84612)
		(end 367.04778 -231.846628)
		(width 0.1143)
		(layer "In11.Cu")
		(net "P5E_CPU0_G3_RX_DN<8>")
	)
	(segment
		(start 367.048796 -243.18722)
		(end 367.05032 -243.188236)
		(width 0.1143)
		(layer "In11.Cu")
		(net "P5E_CPU0_G3_RX_DN<8>")
	)
	(segment
		(start 407.726134 -14.078712)
		(end 409.12542 -17.46123)
		(width 0.14224)
		(layer "In11.Cu")
		(net "P5E_CPU0_G3_RX_DN<8>")
	)
	(segment
		(start 367.053876 -233.470196)
		(end 367.055146 -233.470958)
		(width 0.1143)
		(layer "In11.Cu")
		(net "P5E_CPU0_G3_RX_DN<8>")
	)
	(arc
		(start 367.086896 -238.349536)
		(mid 367.330223 -238.814102)
		(end 367.086896 -239.278668)
		(width 0.1143)
		(layer "In11.Cu")
		(net "P5E_CPU0_G3_RX_DN<8>")
	)
	(arc
		(start 367.086896 -235.109512)
		(mid 367.330223 -235.574078)
		(end 367.086896 -236.038644)
		(width 0.1143)
		(layer "In11.Cu")
		(net "P5E_CPU0_G3_RX_DN<8>")
	)
	(arc
		(start 367.9571 -224.739454)
		(mid 367.841673 -224.87283)
		(end 367.800128 -225.044254)
		(width 0.1143)
		(layer "In11.Cu")
		(net "P5E_CPU0_G3_RX_DN<8>")
	)
	(arc
		(start 367.330228 -230.714296)
		(mid 367.265713 -230.976515)
		(end 367.086896 -231.178862)
		(width 0.1143)
		(layer "In11.Cu")
		(net "P5E_CPU0_G3_RX_DN<8>")
	)
	(arc
		(start 367.086642 -227.009706)
		(mid 367.329969 -227.474272)
		(end 367.086642 -227.938838)
		(width 0.1143)
		(layer "In11.Cu")
		(net "P5E_CPU0_G3_RX_DN<8>")
	)
	(arc
		(start 367.014252 -231.22128)
		(mid 366.900845 -231.354169)
		(end 366.860074 -231.524048)
		(width 0.1143)
		(layer "In11.Cu")
		(net "P5E_CPU0_G3_RX_DN<8>")
	)
	(arc
		(start 367.017046 -226.359466)
		(mid 366.860069 -226.664266)
		(end 367.017046 -226.969066)
		(width 0.1143)
		(layer "In11.Cu")
		(net "P5E_CPU0_G3_RX_DN<8>")
	)
	(arc
		(start 367.800128 -223.424242)
		(mid 367.841383 -223.595213)
		(end 367.956084 -223.728534)
		(width 0.1143)
		(layer "In11.Cu")
		(net "P5E_CPU0_G3_RX_DN<8>")
	)
	(arc
		(start 367.01603 -234.45978)
		(mid 366.860102 -234.764072)
		(end 367.01603 -235.068364)
		(width 0.1143)
		(layer "In11.Cu")
		(net "P5E_CPU0_G3_RX_DN<8>")
	)
	(arc
		(start 367.799874 -221.80423)
		(mid 367.842934 -221.974285)
		(end 367.95583 -222.108522)
		(width 0.1143)
		(layer "In11.Cu")
		(net "P5E_CPU0_G3_RX_DN<8>")
	)
	(arc
		(start 367.01603 -237.699804)
		(mid 366.860102 -238.004096)
		(end 367.01603 -238.308388)
		(width 0.1143)
		(layer "In11.Cu")
		(net "P5E_CPU0_G3_RX_DN<8>")
	)
	(arc
		(start 367.01603 -242.55984)
		(mid 366.860102 -242.864132)
		(end 367.01603 -243.168424)
		(width 0.1143)
		(layer "In11.Cu")
		(net "P5E_CPU0_G3_RX_DN<8>")
	)
	(arc
		(start 367.556796 -247.259602)
		(mid 367.708783 -247.41611)
		(end 367.790222 -247.618504)
		(width 0.1143)
		(layer "In11.Cu")
		(net "P5E_CPU0_G3_RX_DN<8>")
	)
	(arc
		(start 367.084356 -230.247952)
		(mid 367.265008 -230.450697)
		(end 367.330228 -230.714296)
		(width 0.1143)
		(layer "In11.Cu")
		(net "P5E_CPU0_G3_RX_DN<8>")
	)
	(arc
		(start 367.01603 -240.939828)
		(mid 366.860102 -241.24412)
		(end 367.01603 -241.548412)
		(width 0.1143)
		(layer "In11.Cu")
		(net "P5E_CPU0_G3_RX_DN<8>")
	)
	(arc
		(start 367.086896 -236.729524)
		(mid 367.330223 -237.19409)
		(end 367.086896 -237.658656)
		(width 0.1143)
		(layer "In11.Cu")
		(net "P5E_CPU0_G3_RX_DN<8>")
	)
	(arc
		(start 367.086896 -243.209572)
		(mid 367.330223 -243.674138)
		(end 367.086896 -244.138704)
		(width 0.1143)
		(layer "In11.Cu")
		(net "P5E_CPU0_G3_RX_DN<8>")
	)
	(arc
		(start 367.086896 -244.829584)
		(mid 367.330223 -245.29415)
		(end 367.086896 -245.758716)
		(width 0.1143)
		(layer "In11.Cu")
		(net "P5E_CPU0_G3_RX_DN<8>")
	)
	(arc
		(start 367.790222 -247.618504)
		(mid 367.792245 -247.629914)
		(end 367.794032 -247.641364)
		(width 0.1143)
		(layer "In11.Cu")
		(net "P5E_CPU0_G3_RX_DN<8>")
	)
	(arc
		(start 367.086896 -246.449596)
		(mid 367.265709 -246.651946)
		(end 367.330228 -246.914162)
		(width 0.1143)
		(layer "In11.Cu")
		(net "P5E_CPU0_G3_RX_DN<8>")
	)
	(arc
		(start 367.9571 -223.119442)
		(mid 367.841673 -223.252818)
		(end 367.800128 -223.424242)
		(width 0.1143)
		(layer "In11.Cu")
		(net "P5E_CPU0_G3_RX_DN<8>")
	)
	(arc
		(start 367.987834 -222.127064)
		(mid 368.267598 -222.614426)
		(end 367.987834 -223.101662)
		(width 0.1143)
		(layer "In11.Cu")
		(net "P5E_CPU0_G3_RX_DN<8>")
	)
	(arc
		(start 367.086896 -231.869488)
		(mid 367.330223 -232.334054)
		(end 367.086896 -232.79862)
		(width 0.1143)
		(layer "In11.Cu")
		(net "P5E_CPU0_G3_RX_DN<8>")
	)
	(arc
		(start 367.330228 -246.914162)
		(mid 367.371777 -247.085584)
		(end 367.4872 -247.218962)
		(width 0.1143)
		(layer "In11.Cu")
		(net "P5E_CPU0_G3_RX_DN<8>")
	)
	(arc
		(start 367.01603 -236.079792)
		(mid 366.860102 -236.384084)
		(end 367.01603 -236.688376)
		(width 0.1143)
		(layer "In11.Cu")
		(net "P5E_CPU0_G3_RX_DN<8>")
	)
	(arc
		(start 367.017046 -227.979478)
		(mid 366.860069 -228.284278)
		(end 367.017046 -228.589078)
		(width 0.1143)
		(layer "In11.Cu")
		(net "P5E_CPU0_G3_RX_DN<8>")
	)
	(arc
		(start 367.086896 -241.58956)
		(mid 367.330223 -242.054126)
		(end 367.086896 -242.518692)
		(width 0.1143)
		(layer "In11.Cu")
		(net "P5E_CPU0_G3_RX_DN<8>")
	)
	(arc
		(start 366.860074 -229.904036)
		(mid 366.901329 -230.075007)
		(end 367.01603 -230.208328)
		(width 0.1143)
		(layer "In11.Cu")
		(net "P5E_CPU0_G3_RX_DN<8>")
	)
	(arc
		(start 367.01603 -232.839768)
		(mid 366.860102 -233.14406)
		(end 367.01603 -233.448352)
		(width 0.1143)
		(layer "In11.Cu")
		(net "P5E_CPU0_G3_RX_DN<8>")
	)
	(arc
		(start 367.48593 -225.549968)
		(mid 367.371254 -225.683302)
		(end 367.329974 -225.85426)
		(width 0.1143)
		(layer "In11.Cu")
		(net "P5E_CPU0_G3_RX_DN<8>")
	)
	(arc
		(start 367.014252 -229.601268)
		(mid 366.900845 -229.734157)
		(end 366.860074 -229.904036)
		(width 0.1143)
		(layer "In11.Cu")
		(net "P5E_CPU0_G3_RX_DN<8>")
	)
	(arc
		(start 368.02695 -223.769682)
		(mid 368.270277 -224.234248)
		(end 368.02695 -224.698814)
		(width 0.1143)
		(layer "In11.Cu")
		(net "P5E_CPU0_G3_RX_DN<8>")
	)
	(arc
		(start 367.086896 -239.969548)
		(mid 367.330223 -240.434114)
		(end 367.086896 -240.89868)
		(width 0.1143)
		(layer "In11.Cu")
		(net "P5E_CPU0_G3_RX_DN<8>")
	)
	(arc
		(start 367.086896 -233.4895)
		(mid 367.330223 -233.954066)
		(end 367.086896 -234.418632)
		(width 0.1143)
		(layer "In11.Cu")
		(net "P5E_CPU0_G3_RX_DN<8>")
	)
	(arc
		(start 367.01603 -239.319816)
		(mid 366.860102 -239.624108)
		(end 367.01603 -239.9284)
		(width 0.1143)
		(layer "In11.Cu")
		(net "P5E_CPU0_G3_RX_DN<8>")
	)
	(arc
		(start 366.860074 -231.524048)
		(mid 366.901329 -231.695019)
		(end 367.01603 -231.82834)
		(width 0.1143)
		(layer "In11.Cu")
		(net "P5E_CPU0_G3_RX_DN<8>")
	)
	(arc
		(start 367.800128 -225.044254)
		(mid 367.735613 -225.306473)
		(end 367.556796 -225.50882)
		(width 0.1143)
		(layer "In11.Cu")
		(net "P5E_CPU0_G3_RX_DN<8>")
	)
	(arc
		(start 367.086896 -228.629718)
		(mid 367.330223 -229.094284)
		(end 367.086896 -229.55885)
		(width 0.1143)
		(layer "In11.Cu")
		(net "P5E_CPU0_G3_RX_DN<8>")
	)
	(arc
		(start 367.01603 -244.179852)
		(mid 366.860102 -244.484144)
		(end 367.01603 -244.788436)
		(width 0.1143)
		(layer "In11.Cu")
		(net "P5E_CPU0_G3_RX_DN<8>")
	)
	(arc
		(start 367.329974 -225.85426)
		(mid 367.265459 -226.116479)
		(end 367.086642 -226.318826)
		(width 0.1143)
		(layer "In11.Cu")
		(net "P5E_CPU0_G3_RX_DN<8>")
	)
	(arc
		(start 367.01603 -245.799864)
		(mid 366.860102 -246.104156)
		(end 367.01603 -246.408448)
		(width 0.1143)
		(layer "In11.Cu")
		(net "P5E_CPU0_G3_RX_DN<8>")
	)
	(segment
		(start 414.156906 -8.320024)
		(end 414.156906 -7.709154)
		(width 0.12954)
		(layer "F.Cu")
		(net "P5E_CPU0_G3_RX_DN<7>")
	)
	(segment
		(start 367.707926 -244.750082)
		(end 368.174778 -244.484144)
		(width 0.12954)
		(layer "F.Cu")
		(net "P5E_CPU0_G3_RX_DN<7>")
	)
	(segment
		(start 414.156906 -7.709154)
		(end 414.018222 -7.57047)
		(width 0.12954)
		(layer "F.Cu")
		(net "P5E_CPU0_G3_RX_DN<7>")
	)
	(segment
		(start 414.018222 -6.996176)
		(end 414.28924 -6.725158)
		(width 0.12954)
		(layer "F.Cu")
		(net "P5E_CPU0_G3_RX_DN<7>")
	)
	(segment
		(start 414.018222 -7.57047)
		(end 414.018222 -6.996176)
		(width 0.12954)
		(layer "F.Cu")
		(net "P5E_CPU0_G3_RX_DN<7>")
	)
	(segment
		(start 367.983516 -243.184172)
		(end 367.984278 -243.18468)
		(width 0.1143)
		(layer "In11.Cu")
		(net "P5E_CPU0_G3_RX_DN<7>")
	)
	(segment
		(start 367.984278 -236.063536)
		(end 367.983516 -236.064044)
		(width 0.1143)
		(layer "In11.Cu")
		(net "P5E_CPU0_G3_RX_DN<7>")
	)
	(segment
		(start 367.983516 -240.92408)
		(end 367.9825 -240.924588)
		(width 0.1143)
		(layer "In11.Cu")
		(net "P5E_CPU0_G3_RX_DN<7>")
	)
	(segment
		(start 367.988088 -236.061504)
		(end 367.987834 -236.061504)
		(width 0.1143)
		(layer "In11.Cu")
		(net "P5E_CPU0_G3_RX_DN<7>")
	)
	(segment
		(start 367.96599 -236.693964)
		(end 367.966752 -236.694472)
		(width 0.1143)
		(layer "In11.Cu")
		(net "P5E_CPU0_G3_RX_DN<7>")
	)
	(segment
		(start 367.985294 -239.303052)
		(end 367.984278 -239.30356)
		(width 0.1143)
		(layer "In11.Cu")
		(net "P5E_CPU0_G3_RX_DN<7>")
	)
	(segment
		(start 367.987072 -233.466132)
		(end 367.987834 -233.46664)
		(width 0.1143)
		(layer "In11.Cu")
		(net "P5E_CPU0_G3_RX_DN<7>")
	)
	(segment
		(start 409.937712 -22.192742)
		(end 324.453758 -127.61722)
		(width 0.14224)
		(layer "In11.Cu")
		(net "P5E_CPU0_G3_RX_DN<7>")
	)
	(segment
		(start 367.980468 -239.305846)
		(end 367.956084 -239.319816)
		(width 0.1143)
		(layer "In11.Cu")
		(net "P5E_CPU0_G3_RX_DN<7>")
	)
	(segment
		(start 411.245558 -17.815052)
		(end 411.467554 -18.229834)
		(width 0.14224)
		(layer "In11.Cu")
		(net "P5E_CPU0_G3_RX_DN<7>")
	)
	(segment
		(start 367.956084 -239.9284)
		(end 367.96599 -239.933988)
		(width 0.1143)
		(layer "In11.Cu")
		(net "P5E_CPU0_G3_RX_DN<7>")
	)
	(segment
		(start 367.981738 -242.545108)
		(end 367.980468 -242.54587)
		(width 0.1143)
		(layer "In11.Cu")
		(net "P5E_CPU0_G3_RX_DN<7>")
	)
	(segment
		(start 367.987072 -236.062012)
		(end 367.986056 -236.06252)
		(width 0.1143)
		(layer "In11.Cu")
		(net "P5E_CPU0_G3_RX_DN<7>")
	)
	(segment
		(start 367.987834 -236.706664)
		(end 367.988088 -236.706918)
		(width 0.1143)
		(layer "In11.Cu")
		(net "P5E_CPU0_G3_RX_DN<7>")
	)
	(segment
		(start 367.96599 -235.073952)
		(end 367.966752 -235.07446)
		(width 0.1143)
		(layer "In11.Cu")
		(net "P5E_CPU0_G3_RX_DN<7>")
	)
	(segment
		(start 413.99841 -7.015988)
		(end 413.99841 -11.593068)
		(width 0.14224)
		(layer "In11.Cu")
		(net "P5E_CPU0_G3_RX_DN<7>")
	)
	(segment
		(start 368.024156 -234.42041)
		(end 367.987834 -234.441492)
		(width 0.1143)
		(layer "In11.Cu")
		(net "P5E_CPU0_G3_RX_DN<7>")
	)
	(segment
		(start 367.985802 -227.962968)
		(end 367.956084 -227.979986)
		(width 0.1143)
		(layer "In11.Cu")
		(net "P5E_CPU0_G3_RX_DN<7>")
	)
	(segment
		(start 324.799198 -173.023022)
		(end 362.973112 -204.28331)
		(width 0.14224)
		(layer "In11.Cu")
		(net "P5E_CPU0_G3_RX_DN<7>")
	)
	(segment
		(start 367.990374 -230.22814)
		(end 367.99139 -230.228648)
		(width 0.1143)
		(layer "In11.Cu")
		(net "P5E_CPU0_G3_RX_DN<7>")
	)
	(segment
		(start 367.988088 -242.541552)
		(end 367.987834 -242.541552)
		(width 0.1143)
		(layer "In11.Cu")
		(net "P5E_CPU0_G3_RX_DN<7>")
	)
	(segment
		(start 411.201616 -17.542256)
		(end 411.201616 -17.70888)
		(width 0.14224)
		(layer "In11.Cu")
		(net "P5E_CPU0_G3_RX_DN<7>")
	)
	(segment
		(start 411.522672 -16.484346)
		(end 411.201616 -17.542256)
		(width 0.14224)
		(layer "In11.Cu")
		(net "P5E_CPU0_G3_RX_DN<7>")
	)
	(segment
		(start 368.89436 -214.230204)
		(end 369.725702 -220.86316)
		(width 0.14224)
		(layer "In11.Cu")
		(net "P5E_CPU0_G3_RX_DN<7>")
	)
	(segment
		(start 367.981992 -233.463338)
		(end 367.983516 -233.4641)
		(width 0.1143)
		(layer "In11.Cu")
		(net "P5E_CPU0_G3_RX_DN<7>")
	)
	(segment
		(start 367.988088 -237.681516)
		(end 367.987834 -237.681516)
		(width 0.1143)
		(layer "In11.Cu")
		(net "P5E_CPU0_G3_RX_DN<7>")
	)
	(segment
		(start 367.9571 -231.219248)
		(end 367.954306 -231.22128)
		(width 0.1143)
		(layer "In11.Cu")
		(net "P5E_CPU0_G3_RX_DN<7>")
	)
	(segment
		(start 367.987834 -231.846628)
		(end 368.024156 -231.86771)
		(width 0.1143)
		(layer "In11.Cu")
		(net "P5E_CPU0_G3_RX_DN<7>")
	)
	(segment
		(start 367.987072 -237.682024)
		(end 367.986056 -237.682532)
		(width 0.1143)
		(layer "In11.Cu")
		(net "P5E_CPU0_G3_RX_DN<7>")
	)
	(segment
		(start 367.978182 -228.601524)
		(end 367.981738 -228.603302)
		(width 0.1143)
		(layer "In11.Cu")
		(net "P5E_CPU0_G3_RX_DN<7>")
	)
	(segment
		(start 367.981992 -243.18341)
		(end 367.983516 -243.184172)
		(width 0.1143)
		(layer "In11.Cu")
		(net "P5E_CPU0_G3_RX_DN<7>")
	)
	(segment
		(start 367.981992 -231.843326)
		(end 367.983516 -231.844088)
		(width 0.1143)
		(layer "In11.Cu")
		(net "P5E_CPU0_G3_RX_DN<7>")
	)
	(segment
		(start 367.956084 -235.068364)
		(end 367.96599 -235.073952)
		(width 0.1143)
		(layer "In11.Cu")
		(net "P5E_CPU0_G3_RX_DN<7>")
	)
	(segment
		(start 413.4866 -13.544804)
		(end 411.522672 -16.484346)
		(width 0.14224)
		(layer "In11.Cu")
		(net "P5E_CPU0_G3_RX_DN<7>")
	)
	(segment
		(start 367.987834 -234.441492)
		(end 367.956084 -234.45978)
		(width 0.1143)
		(layer "In11.Cu")
		(net "P5E_CPU0_G3_RX_DN<7>")
	)
	(segment
		(start 368.024156 -227.940616)
		(end 367.987834 -227.961698)
		(width 0.1143)
		(layer "In11.Cu")
		(net "P5E_CPU0_G3_RX_DN<7>")
	)
	(segment
		(start 367.987834 -240.92154)
		(end 367.987072 -240.922048)
		(width 0.1143)
		(layer "In11.Cu")
		(net "P5E_CPU0_G3_RX_DN<7>")
	)
	(segment
		(start 369.400328 -222.290132)
		(end 369.398804 -222.291148)
		(width 0.1143)
		(layer "In11.Cu")
		(net "P5E_CPU0_G3_RX_DN<7>")
	)
	(segment
		(start 367.987072 -240.922048)
		(end 367.986056 -240.922556)
		(width 0.1143)
		(layer "In11.Cu")
		(net "P5E_CPU0_G3_RX_DN<7>")
	)
	(segment
		(start 369.679982 -221.128844)
		(end 369.679982 -221.80423)
		(width 0.1143)
		(layer "In11.Cu")
		(net "P5E_CPU0_G3_RX_DN<7>")
	)
	(segment
		(start 367.96599 -238.313976)
		(end 367.966752 -238.314484)
		(width 0.1143)
		(layer "In11.Cu")
		(net "P5E_CPU0_G3_RX_DN<7>")
	)
	(segment
		(start 367.983516 -239.304068)
		(end 367.9825 -239.304576)
		(width 0.1143)
		(layer "In11.Cu")
		(net "P5E_CPU0_G3_RX_DN<7>")
	)
	(segment
		(start 368.024156 -229.560628)
		(end 368.021362 -229.562152)
		(width 0.1143)
		(layer "In11.Cu")
		(net "P5E_CPU0_G3_RX_DN<7>")
	)
	(segment
		(start 368.433858 -225.545396)
		(end 368.431572 -225.54692)
		(width 0.1143)
		(layer "In11.Cu")
		(net "P5E_CPU0_G3_RX_DN<7>")
	)
	(segment
		(start 367.987834 -239.301528)
		(end 367.987072 -239.302036)
		(width 0.1143)
		(layer "In11.Cu")
		(net "P5E_CPU0_G3_RX_DN<7>")
	)
	(segment
		(start 367.983516 -237.684056)
		(end 367.9825 -237.684564)
		(width 0.1143)
		(layer "In11.Cu")
		(net "P5E_CPU0_G3_RX_DN<7>")
	)
	(segment
		(start 369.398804 -222.291148)
		(end 369.397788 -222.291656)
		(width 0.1143)
		(layer "In11.Cu")
		(net "P5E_CPU0_G3_RX_DN<7>")
	)
	(segment
		(start 367.984278 -239.30356)
		(end 367.983516 -239.304068)
		(width 0.1143)
		(layer "In11.Cu")
		(net "P5E_CPU0_G3_RX_DN<7>")
	)
	(segment
		(start 367.987072 -242.54206)
		(end 367.986056 -242.542568)
		(width 0.1143)
		(layer "In11.Cu")
		(net "P5E_CPU0_G3_RX_DN<7>")
	)
	(segment
		(start 367.987834 -238.326676)
		(end 367.988088 -238.32693)
		(width 0.1143)
		(layer "In11.Cu")
		(net "P5E_CPU0_G3_RX_DN<7>")
	)
	(segment
		(start 367.987072 -228.60635)
		(end 367.987834 -228.606858)
		(width 0.1143)
		(layer "In11.Cu")
		(net "P5E_CPU0_G3_RX_DN<7>")
	)
	(segment
		(start 367.988088 -240.92154)
		(end 367.987834 -240.92154)
		(width 0.1143)
		(layer "In11.Cu")
		(net "P5E_CPU0_G3_RX_DN<7>")
	)
	(segment
		(start 367.985802 -244.162834)
		(end 367.956084 -244.179852)
		(width 0.1143)
		(layer "In11.Cu")
		(net "P5E_CPU0_G3_RX_DN<7>")
	)
	(segment
		(start 367.98885 -230.227124)
		(end 367.990374 -230.22814)
		(width 0.1143)
		(layer "In11.Cu")
		(net "P5E_CPU0_G3_RX_DN<7>")
	)
	(segment
		(start 367.966752 -238.314484)
		(end 367.987834 -238.326676)
		(width 0.1143)
		(layer "In11.Cu")
		(net "P5E_CPU0_G3_RX_DN<7>")
	)
	(segment
		(start 369.40617 -222.28683)
		(end 369.403884 -222.2881)
		(width 0.1143)
		(layer "In11.Cu")
		(net "P5E_CPU0_G3_RX_DN<7>")
	)
	(segment
		(start 367.966752 -235.07446)
		(end 367.987834 -235.086652)
		(width 0.1143)
		(layer "In11.Cu")
		(net "P5E_CPU0_G3_RX_DN<7>")
	)
	(segment
		(start 367.956084 -236.688376)
		(end 367.96599 -236.693964)
		(width 0.1143)
		(layer "In11.Cu")
		(net "P5E_CPU0_G3_RX_DN<7>")
	)
	(segment
		(start 368.96675 -224.698814)
		(end 368.897154 -224.739454)
		(width 0.1143)
		(layer "In11.Cu")
		(net "P5E_CPU0_G3_RX_DN<7>")
	)
	(segment
		(start 367.987834 -232.82148)
		(end 367.956084 -232.839768)
		(width 0.1143)
		(layer "In11.Cu")
		(net "P5E_CPU0_G3_RX_DN<7>")
	)
	(segment
		(start 367.987072 -227.962206)
		(end 367.985802 -227.962968)
		(width 0.1143)
		(layer "In11.Cu")
		(net "P5E_CPU0_G3_RX_DN<7>")
	)
	(segment
		(start 367.96599 -239.933988)
		(end 367.966752 -239.934496)
		(width 0.1143)
		(layer "In11.Cu")
		(net "P5E_CPU0_G3_RX_DN<7>")
	)
	(segment
		(start 367.980468 -237.685834)
		(end 367.956084 -237.699804)
		(width 0.1143)
		(layer "In11.Cu")
		(net "P5E_CPU0_G3_RX_DN<7>")
	)
	(segment
		(start 367.981738 -237.685072)
		(end 367.980468 -237.685834)
		(width 0.1143)
		(layer "In11.Cu")
		(net "P5E_CPU0_G3_RX_DN<7>")
	)
	(segment
		(start 367.966752 -236.694472)
		(end 367.987834 -236.706664)
		(width 0.1143)
		(layer "In11.Cu")
		(net "P5E_CPU0_G3_RX_DN<7>")
	)
	(segment
		(start 368.454432 -225.533458)
		(end 368.433858 -225.545396)
		(width 0.1143)
		(layer "In11.Cu")
		(net "P5E_CPU0_G3_RX_DN<7>")
	)
	(segment
		(start 318.364362 -168.99382)
		(end 321.457066 -171.013628)
		(width 0.14224)
		(layer "In11.Cu")
		(net "P5E_CPU0_G3_RX_DN<7>")
	)
	(segment
		(start 367.997994 -231.195372)
		(end 367.9571 -231.219248)
		(width 0.1143)
		(layer "In11.Cu")
		(net "P5E_CPU0_G3_RX_DN<7>")
	)
	(segment
		(start 367.987834 -244.161564)
		(end 367.987072 -244.162072)
		(width 0.1143)
		(layer "In11.Cu")
		(net "P5E_CPU0_G3_RX_DN<7>")
	)
	(segment
		(start 321.72402 -132.435346)
		(end 315.643514 -149.20595)
		(width 0.14224)
		(layer "In11.Cu")
		(net "P5E_CPU0_G3_RX_DN<7>")
	)
	(segment
		(start 324.453758 -127.61722)
		(end 321.72402 -132.435346)
		(width 0.14224)
		(layer "In11.Cu")
		(net "P5E_CPU0_G3_RX_DN<7>")
	)
	(segment
		(start 367.986056 -242.542568)
		(end 367.985294 -242.543076)
		(width 0.1143)
		(layer "In11.Cu")
		(net "P5E_CPU0_G3_RX_DN<7>")
	)
	(segment
		(start 369.725702 -221.083124)
		(end 369.679982 -221.128844)
		(width 0.1143)
		(layer "In11.Cu")
		(net "P5E_CPU0_G3_RX_DN<7>")
	)
	(segment
		(start 369.401344 -222.289624)
		(end 369.400328 -222.290132)
		(width 0.1143)
		(layer "In11.Cu")
		(net "P5E_CPU0_G3_RX_DN<7>")
	)
	(segment
		(start 367.984278 -237.683548)
		(end 367.983516 -237.684056)
		(width 0.1143)
		(layer "In11.Cu")
		(net "P5E_CPU0_G3_RX_DN<7>")
	)
	(segment
		(start 367.987834 -237.681516)
		(end 367.987072 -237.682024)
		(width 0.1143)
		(layer "In11.Cu")
		(net "P5E_CPU0_G3_RX_DN<7>")
	)
	(segment
		(start 362.973112 -204.28331)
		(end 368.89436 -214.230204)
		(width 0.14224)
		(layer "In11.Cu")
		(net "P5E_CPU0_G3_RX_DN<7>")
	)
	(segment
		(start 369.403884 -222.2881)
		(end 369.402868 -222.288608)
		(width 0.1143)
		(layer "In11.Cu")
		(net "P5E_CPU0_G3_RX_DN<7>")
	)
	(segment
		(start 414.28924 -6.725158)
		(end 413.99841 -7.015988)
		(width 0.14224)
		(layer "In11.Cu")
		(net "P5E_CPU0_G3_RX_DN<7>")
	)
	(segment
		(start 367.9825 -240.924588)
		(end 367.981738 -240.925096)
		(width 0.1143)
		(layer "In11.Cu")
		(net "P5E_CPU0_G3_RX_DN<7>")
	)
	(segment
		(start 367.96599 -241.554)
		(end 367.966752 -241.554508)
		(width 0.1143)
		(layer "In11.Cu")
		(net "P5E_CPU0_G3_RX_DN<7>")
	)
	(segment
		(start 367.985294 -236.063028)
		(end 367.984278 -236.063536)
		(width 0.1143)
		(layer "In11.Cu")
		(net "P5E_CPU0_G3_RX_DN<7>")
	)
	(segment
		(start 368.457734 -225.53168)
		(end 368.454432 -225.533458)
		(width 0.1143)
		(layer "In11.Cu")
		(net "P5E_CPU0_G3_RX_DN<7>")
	)
	(segment
		(start 315.643514 -149.20595)
		(end 313.60237 -160.823148)
		(width 0.14224)
		(layer "In11.Cu")
		(net "P5E_CPU0_G3_RX_DN<7>")
	)
	(segment
		(start 369.397788 -222.291656)
		(end 369.366038 -222.309944)
		(width 0.1143)
		(layer "In11.Cu")
		(net "P5E_CPU0_G3_RX_DN<7>")
	)
	(segment
		(start 367.97996 -243.18214)
		(end 367.98123 -243.182902)
		(width 0.1143)
		(layer "In11.Cu")
		(net "P5E_CPU0_G3_RX_DN<7>")
	)
	(segment
		(start 367.984278 -240.923572)
		(end 367.983516 -240.92408)
		(width 0.1143)
		(layer "In11.Cu")
		(net "P5E_CPU0_G3_RX_DN<7>")
	)
	(segment
		(start 367.806986 -244.414294)
		(end 367.876836 -244.484144)
		(width 0.1143)
		(layer "In11.Cu")
		(net "P5E_CPU0_G3_RX_DN<7>")
	)
	(segment
		(start 367.981738 -228.603302)
		(end 367.9825 -228.60381)
		(width 0.1143)
		(layer "In11.Cu")
		(net "P5E_CPU0_G3_RX_DN<7>")
	)
	(segment
		(start 367.956084 -230.208328)
		(end 367.987834 -230.226616)
		(width 0.1143)
		(layer "In11.Cu")
		(net "P5E_CPU0_G3_RX_DN<7>")
	)
	(segment
		(start 411.900624 -18.877534)
		(end 411.900624 -19.37512)
		(width 0.14224)
		(layer "In11.Cu")
		(net "P5E_CPU0_G3_RX_DN<7>")
	)
	(segment
		(start 367.956084 -241.548412)
		(end 367.96599 -241.554)
		(width 0.1143)
		(layer "In11.Cu")
		(net "P5E_CPU0_G3_RX_DN<7>")
	)
	(segment
		(start 367.987072 -243.186204)
		(end 367.987834 -243.186712)
		(width 0.1143)
		(layer "In11.Cu")
		(net "P5E_CPU0_G3_RX_DN<7>")
	)
	(segment
		(start 367.97742 -231.840786)
		(end 367.97996 -231.842056)
		(width 0.1143)
		(layer "In11.Cu")
		(net "P5E_CPU0_G3_RX_DN<7>")
	)
	(segment
		(start 315.220096 -165.848792)
		(end 318.364362 -168.99382)
		(width 0.14224)
		(layer "In11.Cu")
		(net "P5E_CPU0_G3_RX_DN<7>")
	)
	(segment
		(start 367.987072 -244.162072)
		(end 367.985802 -244.162834)
		(width 0.1143)
		(layer "In11.Cu")
		(net "P5E_CPU0_G3_RX_DN<7>")
	)
	(segment
		(start 368.270028 -225.870262)
		(end 368.270028 -225.870516)
		(width 0.1143)
		(layer "In11.Cu")
		(net "P5E_CPU0_G3_RX_DN<7>")
	)
	(segment
		(start 367.9825 -228.60381)
		(end 367.983516 -228.604318)
		(width 0.1143)
		(layer "In11.Cu")
		(net "P5E_CPU0_G3_RX_DN<7>")
	)
	(segment
		(start 367.876836 -244.484144)
		(end 368.174778 -244.484144)
		(width 0.1143)
		(layer "In11.Cu")
		(net "P5E_CPU0_G3_RX_DN<7>")
	)
	(segment
		(start 368.019838 -230.245158)
		(end 368.021362 -230.246174)
		(width 0.1143)
		(layer "In11.Cu")
		(net "P5E_CPU0_G3_RX_DN<7>")
	)
	(segment
		(start 368.024156 -226.320604)
		(end 368.022632 -226.32162)
		(width 0.1143)
		(layer "In11.Cu")
		(net "P5E_CPU0_G3_RX_DN<7>")
	)
	(segment
		(start 367.980468 -240.925858)
		(end 367.956084 -240.939828)
		(width 0.1143)
		(layer "In11.Cu")
		(net "P5E_CPU0_G3_RX_DN<7>")
	)
	(segment
		(start 367.987072 -231.84612)
		(end 367.987834 -231.846628)
		(width 0.1143)
		(layer "In11.Cu")
		(net "P5E_CPU0_G3_RX_DN<7>")
	)
	(segment
		(start 367.987834 -230.226616)
		(end 367.98885 -230.227124)
		(width 0.1143)
		(layer "In11.Cu")
		(net "P5E_CPU0_G3_RX_DN<7>")
	)
	(segment
		(start 367.983516 -236.064044)
		(end 367.981484 -236.065314)
		(width 0.1143)
		(layer "In11.Cu")
		(net "P5E_CPU0_G3_RX_DN<7>")
	)
	(segment
		(start 413.99841 -11.593068)
		(end 413.724344 -12.97051)
		(width 0.14224)
		(layer "In11.Cu")
		(net "P5E_CPU0_G3_RX_DN<7>")
	)
	(segment
		(start 313.60237 -160.823148)
		(end 313.60237 -161.942272)
		(width 0.14224)
		(layer "In11.Cu")
		(net "P5E_CPU0_G3_RX_DN<7>")
	)
	(segment
		(start 367.987834 -236.061504)
		(end 367.987072 -236.062012)
		(width 0.1143)
		(layer "In11.Cu")
		(net "P5E_CPU0_G3_RX_DN<7>")
	)
	(segment
		(start 367.956084 -228.58857)
		(end 367.978182 -228.601524)
		(width 0.1143)
		(layer "In11.Cu")
		(net "P5E_CPU0_G3_RX_DN<7>")
	)
	(segment
		(start 367.987834 -242.541552)
		(end 367.987072 -242.54206)
		(width 0.1143)
		(layer "In11.Cu")
		(net "P5E_CPU0_G3_RX_DN<7>")
	)
	(segment
		(start 367.987834 -239.946688)
		(end 367.988088 -239.946942)
		(width 0.1143)
		(layer "In11.Cu")
		(net "P5E_CPU0_G3_RX_DN<7>")
	)
	(segment
		(start 368.49685 -225.50882)
		(end 368.45875 -225.531172)
		(width 0.1143)
		(layer "In11.Cu")
		(net "P5E_CPU0_G3_RX_DN<7>")
	)
	(segment
		(start 367.981738 -240.925096)
		(end 367.980468 -240.925858)
		(width 0.1143)
		(layer "In11.Cu")
		(net "P5E_CPU0_G3_RX_DN<7>")
	)
	(segment
		(start 367.956084 -238.308388)
		(end 367.96599 -238.313976)
		(width 0.1143)
		(layer "In11.Cu")
		(net "P5E_CPU0_G3_RX_DN<7>")
	)
	(segment
		(start 367.985294 -242.543076)
		(end 367.984278 -242.543584)
		(width 0.1143)
		(layer "In11.Cu")
		(net "P5E_CPU0_G3_RX_DN<7>")
	)
	(segment
		(start 367.984278 -231.844596)
		(end 367.987072 -231.84612)
		(width 0.1143)
		(layer "In11.Cu")
		(net "P5E_CPU0_G3_RX_DN<7>")
	)
	(segment
		(start 368.45875 -225.531172)
		(end 368.457734 -225.53168)
		(width 0.1143)
		(layer "In11.Cu")
		(net "P5E_CPU0_G3_RX_DN<7>")
	)
	(segment
		(start 367.966752 -239.934496)
		(end 367.987834 -239.946688)
		(width 0.1143)
		(layer "In11.Cu")
		(net "P5E_CPU0_G3_RX_DN<7>")
	)
	(segment
		(start 367.988088 -239.301528)
		(end 367.987834 -239.301528)
		(width 0.1143)
		(layer "In11.Cu")
		(net "P5E_CPU0_G3_RX_DN<7>")
	)
	(segment
		(start 367.97742 -233.460798)
		(end 367.97996 -233.462068)
		(width 0.1143)
		(layer "In11.Cu")
		(net "P5E_CPU0_G3_RX_DN<7>")
	)
	(segment
		(start 411.900624 -19.37512)
		(end 409.937712 -22.192742)
		(width 0.14224)
		(layer "In11.Cu")
		(net "P5E_CPU0_G3_RX_DN<7>")
	)
	(segment
		(start 367.981738 -239.305084)
		(end 367.980468 -239.305846)
		(width 0.1143)
		(layer "In11.Cu")
		(net "P5E_CPU0_G3_RX_DN<7>")
	)
	(segment
		(start 367.99139 -230.228648)
		(end 368.019838 -230.245158)
		(width 0.1143)
		(layer "In11.Cu")
		(net "P5E_CPU0_G3_RX_DN<7>")
	)
	(segment
		(start 368.897154 -223.729042)
		(end 368.96675 -223.769682)
		(width 0.1143)
		(layer "In11.Cu")
		(net "P5E_CPU0_G3_RX_DN<7>")
	)
	(segment
		(start 367.98123 -233.46283)
		(end 367.981992 -233.463338)
		(width 0.1143)
		(layer "In11.Cu")
		(net "P5E_CPU0_G3_RX_DN<7>")
	)
	(segment
		(start 411.467554 -18.229834)
		(end 411.900624 -18.877534)
		(width 0.14224)
		(layer "In11.Cu")
		(net "P5E_CPU0_G3_RX_DN<7>")
	)
	(segment
		(start 367.983516 -242.544092)
		(end 367.9825 -242.5446)
		(width 0.1143)
		(layer "In11.Cu")
		(net "P5E_CPU0_G3_RX_DN<7>")
	)
	(segment
		(start 369.402868 -222.288608)
		(end 369.401344 -222.289624)
		(width 0.1143)
		(layer "In11.Cu")
		(net "P5E_CPU0_G3_RX_DN<7>")
	)
	(segment
		(start 367.987834 -227.961698)
		(end 367.987072 -227.962206)
		(width 0.1143)
		(layer "In11.Cu")
		(net "P5E_CPU0_G3_RX_DN<7>")
	)
	(segment
		(start 367.966752 -241.554508)
		(end 367.987834 -241.5667)
		(width 0.1143)
		(layer "In11.Cu")
		(net "P5E_CPU0_G3_RX_DN<7>")
	)
	(segment
		(start 367.9825 -237.684564)
		(end 367.981738 -237.685072)
		(width 0.1143)
		(layer "In11.Cu")
		(net "P5E_CPU0_G3_RX_DN<7>")
	)
	(segment
		(start 367.985294 -237.68304)
		(end 367.984278 -237.683548)
		(width 0.1143)
		(layer "In11.Cu")
		(net "P5E_CPU0_G3_RX_DN<7>")
	)
	(segment
		(start 367.986056 -239.302544)
		(end 367.985294 -239.303052)
		(width 0.1143)
		(layer "In11.Cu")
		(net "P5E_CPU0_G3_RX_DN<7>")
	)
	(segment
		(start 367.987834 -241.5667)
		(end 367.988088 -241.566954)
		(width 0.1143)
		(layer "In11.Cu")
		(net "P5E_CPU0_G3_RX_DN<7>")
	)
	(segment
		(start 367.987834 -226.986846)
		(end 368.024156 -227.007928)
		(width 0.1143)
		(layer "In11.Cu")
		(net "P5E_CPU0_G3_RX_DN<7>")
	)
	(segment
		(start 367.983516 -231.844088)
		(end 367.984278 -231.844596)
		(width 0.1143)
		(layer "In11.Cu")
		(net "P5E_CPU0_G3_RX_DN<7>")
	)
	(segment
		(start 367.9825 -239.304576)
		(end 367.981738 -239.305084)
		(width 0.1143)
		(layer "In11.Cu")
		(net "P5E_CPU0_G3_RX_DN<7>")
	)
	(segment
		(start 367.97996 -233.462068)
		(end 367.98123 -233.46283)
		(width 0.1143)
		(layer "In11.Cu")
		(net "P5E_CPU0_G3_RX_DN<7>")
	)
	(segment
		(start 367.987072 -239.302036)
		(end 367.986056 -239.302544)
		(width 0.1143)
		(layer "In11.Cu")
		(net "P5E_CPU0_G3_RX_DN<7>")
	)
	(segment
		(start 368.021362 -229.562152)
		(end 367.987834 -229.58171)
		(width 0.1143)
		(layer "In11.Cu")
		(net "P5E_CPU0_G3_RX_DN<7>")
	)
	(segment
		(start 367.983516 -228.604318)
		(end 367.984278 -228.604826)
		(width 0.1143)
		(layer "In11.Cu")
		(net "P5E_CPU0_G3_RX_DN<7>")
	)
	(segment
		(start 367.987834 -243.186712)
		(end 368.024156 -243.207794)
		(width 0.1143)
		(layer "In11.Cu")
		(net "P5E_CPU0_G3_RX_DN<7>")
	)
	(segment
		(start 367.987834 -233.46664)
		(end 368.024156 -233.487722)
		(width 0.1143)
		(layer "In11.Cu")
		(net "P5E_CPU0_G3_RX_DN<7>")
	)
	(segment
		(start 367.956084 -226.968558)
		(end 367.987834 -226.986846)
		(width 0.1143)
		(layer "In11.Cu")
		(net "P5E_CPU0_G3_RX_DN<7>")
	)
	(segment
		(start 368.96675 -223.078802)
		(end 368.897154 -223.119442)
		(width 0.1143)
		(layer "In11.Cu")
		(net "P5E_CPU0_G3_RX_DN<7>")
	)
	(segment
		(start 369.436904 -222.268796)
		(end 369.40617 -222.28683)
		(width 0.1143)
		(layer "In11.Cu")
		(net "P5E_CPU0_G3_RX_DN<7>")
	)
	(segment
		(start 368.024156 -232.800398)
		(end 367.987834 -232.82148)
		(width 0.1143)
		(layer "In11.Cu")
		(net "P5E_CPU0_G3_RX_DN<7>")
	)
	(segment
		(start 367.984278 -243.18468)
		(end 367.987072 -243.186204)
		(width 0.1143)
		(layer "In11.Cu")
		(net "P5E_CPU0_G3_RX_DN<7>")
	)
	(segment
		(start 367.984278 -228.604826)
		(end 367.987072 -228.60635)
		(width 0.1143)
		(layer "In11.Cu")
		(net "P5E_CPU0_G3_RX_DN<7>")
	)
	(segment
		(start 367.984278 -233.464608)
		(end 367.987072 -233.466132)
		(width 0.1143)
		(layer "In11.Cu")
		(net "P5E_CPU0_G3_RX_DN<7>")
	)
	(segment
		(start 367.983516 -233.4641)
		(end 367.984278 -233.464608)
		(width 0.1143)
		(layer "In11.Cu")
		(net "P5E_CPU0_G3_RX_DN<7>")
	)
	(segment
		(start 313.60237 -161.942272)
		(end 315.220096 -165.848792)
		(width 0.14224)
		(layer "In11.Cu")
		(net "P5E_CPU0_G3_RX_DN<7>")
	)
	(segment
		(start 367.97996 -231.842056)
		(end 367.98123 -231.842818)
		(width 0.1143)
		(layer "In11.Cu")
		(net "P5E_CPU0_G3_RX_DN<7>")
	)
	(segment
		(start 321.457066 -171.013628)
		(end 322.346574 -171.502578)
		(width 0.14224)
		(layer "In11.Cu")
		(net "P5E_CPU0_G3_RX_DN<7>")
	)
	(segment
		(start 368.022632 -226.32162)
		(end 367.956084 -226.359974)
		(width 0.1143)
		(layer "In11.Cu")
		(net "P5E_CPU0_G3_RX_DN<7>")
	)
	(segment
		(start 369.725702 -221.054676)
		(end 369.725702 -221.083124)
		(width 0.1143)
		(layer "In11.Cu")
		(net "P5E_CPU0_G3_RX_DN<7>")
	)
	(segment
		(start 367.986056 -240.922556)
		(end 367.985294 -240.923064)
		(width 0.1143)
		(layer "In11.Cu")
		(net "P5E_CPU0_G3_RX_DN<7>")
	)
	(segment
		(start 367.987834 -235.086652)
		(end 367.988088 -235.086906)
		(width 0.1143)
		(layer "In11.Cu")
		(net "P5E_CPU0_G3_RX_DN<7>")
	)
	(segment
		(start 369.725702 -220.86316)
		(end 369.725702 -221.054676)
		(width 0.14224)
		(layer "In11.Cu")
		(net "P5E_CPU0_G3_RX_DN<7>")
	)
	(segment
		(start 367.985294 -240.923064)
		(end 367.984278 -240.923572)
		(width 0.1143)
		(layer "In11.Cu")
		(net "P5E_CPU0_G3_RX_DN<7>")
	)
	(segment
		(start 367.98123 -231.842818)
		(end 367.981992 -231.843326)
		(width 0.1143)
		(layer "In11.Cu")
		(net "P5E_CPU0_G3_RX_DN<7>")
	)
	(segment
		(start 367.956084 -243.168424)
		(end 367.97742 -243.18087)
		(width 0.1143)
		(layer "In11.Cu")
		(net "P5E_CPU0_G3_RX_DN<7>")
	)
	(segment
		(start 367.956084 -231.82834)
		(end 367.97742 -231.840786)
		(width 0.1143)
		(layer "In11.Cu")
		(net "P5E_CPU0_G3_RX_DN<7>")
	)
	(segment
		(start 322.346574 -171.502578)
		(end 324.799198 -173.023022)
		(width 0.14224)
		(layer "In11.Cu")
		(net "P5E_CPU0_G3_RX_DN<7>")
	)
	(segment
		(start 367.98123 -243.182902)
		(end 367.981992 -243.18341)
		(width 0.1143)
		(layer "In11.Cu")
		(net "P5E_CPU0_G3_RX_DN<7>")
	)
	(segment
		(start 367.987834 -229.58171)
		(end 367.955068 -229.60076)
		(width 0.1143)
		(layer "In11.Cu")
		(net "P5E_CPU0_G3_RX_DN<7>")
	)
	(segment
		(start 367.981484 -236.065314)
		(end 367.956084 -236.079792)
		(width 0.1143)
		(layer "In11.Cu")
		(net "P5E_CPU0_G3_RX_DN<7>")
	)
	(segment
		(start 367.955068 -229.60076)
		(end 367.954306 -229.601268)
		(width 0.1143)
		(layer "In11.Cu")
		(net "P5E_CPU0_G3_RX_DN<7>")
	)
	(segment
		(start 367.980468 -242.54587)
		(end 367.956084 -242.55984)
		(width 0.1143)
		(layer "In11.Cu")
		(net "P5E_CPU0_G3_RX_DN<7>")
	)
	(segment
		(start 367.984278 -242.543584)
		(end 367.983516 -242.544092)
		(width 0.1143)
		(layer "In11.Cu")
		(net "P5E_CPU0_G3_RX_DN<7>")
	)
	(segment
		(start 368.431572 -225.54692)
		(end 368.430556 -225.547428)
		(width 0.1143)
		(layer "In11.Cu")
		(net "P5E_CPU0_G3_RX_DN<7>")
	)
	(segment
		(start 367.986056 -236.06252)
		(end 367.985294 -236.063028)
		(width 0.1143)
		(layer "In11.Cu")
		(net "P5E_CPU0_G3_RX_DN<7>")
	)
	(segment
		(start 367.9825 -242.5446)
		(end 367.981738 -242.545108)
		(width 0.1143)
		(layer "In11.Cu")
		(net "P5E_CPU0_G3_RX_DN<7>")
	)
	(segment
		(start 413.724344 -12.97051)
		(end 413.4866 -13.544804)
		(width 0.14224)
		(layer "In11.Cu")
		(net "P5E_CPU0_G3_RX_DN<7>")
	)
	(segment
		(start 367.986056 -237.682532)
		(end 367.985294 -237.68304)
		(width 0.1143)
		(layer "In11.Cu")
		(net "P5E_CPU0_G3_RX_DN<7>")
	)
	(segment
		(start 411.201616 -17.70888)
		(end 411.245558 -17.815052)
		(width 0.14224)
		(layer "In11.Cu")
		(net "P5E_CPU0_G3_RX_DN<7>")
	)
	(segment
		(start 367.97742 -243.18087)
		(end 367.97996 -243.18214)
		(width 0.1143)
		(layer "In11.Cu")
		(net "P5E_CPU0_G3_RX_DN<7>")
	)
	(segment
		(start 367.956084 -233.448352)
		(end 367.97742 -233.460798)
		(width 0.1143)
		(layer "In11.Cu")
		(net "P5E_CPU0_G3_RX_DN<7>")
	)
	(segment
		(start 368.024156 -244.140482)
		(end 367.987834 -244.161564)
		(width 0.1143)
		(layer "In11.Cu")
		(net "P5E_CPU0_G3_RX_DN<7>")
	)
	(arc
		(start 368.040412 -227.019358)
		(mid 368.263296 -227.474272)
		(end 368.040412 -227.929186)
		(width 0.1143)
		(layer "In11.Cu")
		(net "P5E_CPU0_G3_RX_DN<7>")
	)
	(arc
		(start 368.03838 -234.410504)
		(mid 368.031306 -234.415511)
		(end 368.024156 -234.42041)
		(width 0.1143)
		(layer "In11.Cu")
		(net "P5E_CPU0_G3_RX_DN<7>")
	)
	(arc
		(start 368.040412 -243.219224)
		(mid 368.263296 -243.674138)
		(end 368.040412 -244.129052)
		(width 0.1143)
		(layer "In11.Cu")
		(net "P5E_CPU0_G3_RX_DN<7>")
	)
	(arc
		(start 367.956084 -240.939828)
		(mid 367.800156 -241.24412)
		(end 367.956084 -241.548412)
		(width 0.1143)
		(layer "In11.Cu")
		(net "P5E_CPU0_G3_RX_DN<7>")
	)
	(arc
		(start 367.988088 -241.566954)
		(mid 368.268735 -242.054316)
		(end 367.988088 -242.541552)
		(width 0.1143)
		(layer "In11.Cu")
		(net "P5E_CPU0_G3_RX_DN<7>")
	)
	(arc
		(start 368.897154 -223.119442)
		(mid 368.740177 -223.424242)
		(end 368.897154 -223.729042)
		(width 0.1143)
		(layer "In11.Cu")
		(net "P5E_CPU0_G3_RX_DN<7>")
	)
	(arc
		(start 367.987834 -228.606858)
		(mid 368.194457 -228.812637)
		(end 368.270028 -229.094284)
		(width 0.1143)
		(layer "In11.Cu")
		(net "P5E_CPU0_G3_RX_DN<7>")
	)
	(arc
		(start 369.679982 -221.80423)
		(mid 369.652066 -221.980206)
		(end 369.570762 -222.138748)
		(width 0.1143)
		(layer "In11.Cu")
		(net "P5E_CPU0_G3_RX_DN<7>")
	)
	(arc
		(start 367.988088 -235.086906)
		(mid 368.268735 -235.574268)
		(end 367.988088 -236.061504)
		(width 0.1143)
		(layer "In11.Cu")
		(net "P5E_CPU0_G3_RX_DN<7>")
	)
	(arc
		(start 367.800128 -231.524048)
		(mid 367.841383 -231.695019)
		(end 367.956084 -231.82834)
		(width 0.1143)
		(layer "In11.Cu")
		(net "P5E_CPU0_G3_RX_DN<7>")
	)
	(arc
		(start 368.270028 -225.870516)
		(mid 368.201067 -226.125047)
		(end 368.024156 -226.320604)
		(width 0.1143)
		(layer "In11.Cu")
		(net "P5E_CPU0_G3_RX_DN<7>")
	)
	(arc
		(start 369.210082 -222.614236)
		(mid 369.145567 -222.876455)
		(end 368.96675 -223.078802)
		(width 0.1143)
		(layer "In11.Cu")
		(net "P5E_CPU0_G3_RX_DN<7>")
	)
	(arc
		(start 367.956084 -232.839768)
		(mid 367.800156 -233.14406)
		(end 367.956084 -233.448352)
		(width 0.1143)
		(layer "In11.Cu")
		(net "P5E_CPU0_G3_RX_DN<7>")
	)
	(arc
		(start 368.037618 -229.550976)
		(mid 368.030923 -229.555852)
		(end 368.024156 -229.560628)
		(width 0.1143)
		(layer "In11.Cu")
		(net "P5E_CPU0_G3_RX_DN<7>")
	)
	(arc
		(start 368.897154 -224.739454)
		(mid 368.781727 -224.87283)
		(end 368.740182 -225.044254)
		(width 0.1143)
		(layer "In11.Cu")
		(net "P5E_CPU0_G3_RX_DN<7>")
	)
	(arc
		(start 368.040412 -232.788968)
		(mid 368.032334 -232.794754)
		(end 368.024156 -232.800398)
		(width 0.1143)
		(layer "In11.Cu")
		(net "P5E_CPU0_G3_RX_DN<7>")
	)
	(arc
		(start 368.270028 -230.710486)
		(mid 368.200013 -230.989949)
		(end 367.997994 -231.195372)
		(width 0.1143)
		(layer "In11.Cu")
		(net "P5E_CPU0_G3_RX_DN<7>")
	)
	(arc
		(start 368.040412 -227.929186)
		(mid 368.032334 -227.934972)
		(end 368.024156 -227.940616)
		(width 0.1143)
		(layer "In11.Cu")
		(net "P5E_CPU0_G3_RX_DN<7>")
	)
	(arc
		(start 368.270028 -229.094284)
		(mid 368.208583 -229.350496)
		(end 368.037618 -229.550976)
		(width 0.1143)
		(layer "In11.Cu")
		(net "P5E_CPU0_G3_RX_DN<7>")
	)
	(arc
		(start 367.988088 -239.946942)
		(mid 368.268735 -240.434304)
		(end 367.988088 -240.92154)
		(width 0.1143)
		(layer "In11.Cu")
		(net "P5E_CPU0_G3_RX_DN<7>")
	)
	(arc
		(start 367.956084 -244.179852)
		(mid 367.858949 -244.282721)
		(end 367.806986 -244.414294)
		(width 0.1143)
		(layer "In11.Cu")
		(net "P5E_CPU0_G3_RX_DN<7>")
	)
	(arc
		(start 368.2746 -225.826828)
		(mid 368.271415 -225.84845)
		(end 368.270028 -225.870262)
		(width 0.1143)
		(layer "In11.Cu")
		(net "P5E_CPU0_G3_RX_DN<7>")
	)
	(arc
		(start 369.570762 -222.138748)
		(mid 369.509243 -222.209342)
		(end 369.436904 -222.268796)
		(width 0.1143)
		(layer "In11.Cu")
		(net "P5E_CPU0_G3_RX_DN<7>")
	)
	(arc
		(start 368.03838 -233.497628)
		(mid 368.265763 -233.954066)
		(end 368.03838 -234.410504)
		(width 0.1143)
		(layer "In11.Cu")
		(net "P5E_CPU0_G3_RX_DN<7>")
	)
	(arc
		(start 367.988088 -236.706918)
		(mid 368.268735 -237.19428)
		(end 367.988088 -237.681516)
		(width 0.1143)
		(layer "In11.Cu")
		(net "P5E_CPU0_G3_RX_DN<7>")
	)
	(arc
		(start 368.040412 -231.87914)
		(mid 368.263296 -232.334054)
		(end 368.040412 -232.788968)
		(width 0.1143)
		(layer "In11.Cu")
		(net "P5E_CPU0_G3_RX_DN<7>")
	)
	(arc
		(start 368.040412 -244.129052)
		(mid 368.032334 -244.134838)
		(end 368.024156 -244.140482)
		(width 0.1143)
		(layer "In11.Cu")
		(net "P5E_CPU0_G3_RX_DN<7>")
	)
	(arc
		(start 367.956084 -237.699804)
		(mid 367.800156 -238.004096)
		(end 367.956084 -238.308388)
		(width 0.1143)
		(layer "In11.Cu")
		(net "P5E_CPU0_G3_RX_DN<7>")
	)
	(arc
		(start 367.988088 -238.32693)
		(mid 368.268735 -238.814292)
		(end 367.988088 -239.301528)
		(width 0.1143)
		(layer "In11.Cu")
		(net "P5E_CPU0_G3_RX_DN<7>")
	)
	(arc
		(start 368.024156 -243.207794)
		(mid 368.032334 -243.213437)
		(end 368.040412 -243.219224)
		(width 0.1143)
		(layer "In11.Cu")
		(net "P5E_CPU0_G3_RX_DN<7>")
	)
	(arc
		(start 367.956084 -227.979986)
		(mid 367.800156 -228.284278)
		(end 367.956084 -228.58857)
		(width 0.1143)
		(layer "In11.Cu")
		(net "P5E_CPU0_G3_RX_DN<7>")
	)
	(arc
		(start 368.421412 -225.55454)
		(mid 368.327495 -225.679624)
		(end 368.2746 -225.826828)
		(width 0.1143)
		(layer "In11.Cu")
		(net "P5E_CPU0_G3_RX_DN<7>")
	)
	(arc
		(start 367.956084 -234.45978)
		(mid 367.800156 -234.764072)
		(end 367.956084 -235.068364)
		(width 0.1143)
		(layer "In11.Cu")
		(net "P5E_CPU0_G3_RX_DN<7>")
	)
	(arc
		(start 367.954306 -231.22128)
		(mid 367.840899 -231.354169)
		(end 367.800128 -231.524048)
		(width 0.1143)
		(layer "In11.Cu")
		(net "P5E_CPU0_G3_RX_DN<7>")
	)
	(arc
		(start 367.800128 -229.904036)
		(mid 367.841383 -230.075007)
		(end 367.956084 -230.208328)
		(width 0.1143)
		(layer "In11.Cu")
		(net "P5E_CPU0_G3_RX_DN<7>")
	)
	(arc
		(start 368.740182 -225.044254)
		(mid 368.675667 -225.306473)
		(end 368.49685 -225.50882)
		(width 0.1143)
		(layer "In11.Cu")
		(net "P5E_CPU0_G3_RX_DN<7>")
	)
	(arc
		(start 368.021362 -230.246174)
		(mid 368.029795 -230.251814)
		(end 368.038126 -230.257604)
		(width 0.1143)
		(layer "In11.Cu")
		(net "P5E_CPU0_G3_RX_DN<7>")
	)
	(arc
		(start 367.954306 -229.601268)
		(mid 367.840899 -229.734157)
		(end 367.800128 -229.904036)
		(width 0.1143)
		(layer "In11.Cu")
		(net "P5E_CPU0_G3_RX_DN<7>")
	)
	(arc
		(start 367.956084 -226.359974)
		(mid 367.800156 -226.664266)
		(end 367.956084 -226.968558)
		(width 0.1143)
		(layer "In11.Cu")
		(net "P5E_CPU0_G3_RX_DN<7>")
	)
	(arc
		(start 368.038126 -230.257604)
		(mid 368.206302 -230.457307)
		(end 368.270028 -230.710486)
		(width 0.1143)
		(layer "In11.Cu")
		(net "P5E_CPU0_G3_RX_DN<7>")
	)
	(arc
		(start 368.96675 -223.769682)
		(mid 369.210077 -224.234248)
		(end 368.96675 -224.698814)
		(width 0.1143)
		(layer "In11.Cu")
		(net "P5E_CPU0_G3_RX_DN<7>")
	)
	(arc
		(start 368.024156 -231.86771)
		(mid 368.032334 -231.873353)
		(end 368.040412 -231.87914)
		(width 0.1143)
		(layer "In11.Cu")
		(net "P5E_CPU0_G3_RX_DN<7>")
	)
	(arc
		(start 368.024156 -227.007928)
		(mid 368.032334 -227.013571)
		(end 368.040412 -227.019358)
		(width 0.1143)
		(layer "In11.Cu")
		(net "P5E_CPU0_G3_RX_DN<7>")
	)
	(arc
		(start 367.956084 -242.55984)
		(mid 367.800156 -242.864132)
		(end 367.956084 -243.168424)
		(width 0.1143)
		(layer "In11.Cu")
		(net "P5E_CPU0_G3_RX_DN<7>")
	)
	(arc
		(start 368.024156 -233.487722)
		(mid 368.031305 -233.492622)
		(end 368.03838 -233.497628)
		(width 0.1143)
		(layer "In11.Cu")
		(net "P5E_CPU0_G3_RX_DN<7>")
	)
	(arc
		(start 367.956084 -239.319816)
		(mid 367.800156 -239.624108)
		(end 367.956084 -239.9284)
		(width 0.1143)
		(layer "In11.Cu")
		(net "P5E_CPU0_G3_RX_DN<7>")
	)
	(arc
		(start 368.430556 -225.547428)
		(mid 368.425956 -225.550949)
		(end 368.421412 -225.55454)
		(width 0.1143)
		(layer "In11.Cu")
		(net "P5E_CPU0_G3_RX_DN<7>")
	)
	(arc
		(start 367.956084 -236.079792)
		(mid 367.800156 -236.384084)
		(end 367.956084 -236.688376)
		(width 0.1143)
		(layer "In11.Cu")
		(net "P5E_CPU0_G3_RX_DN<7>")
	)
	(arc
		(start 369.366038 -222.309944)
		(mid 369.251362 -222.443278)
		(end 369.210082 -222.614236)
		(width 0.1143)
		(layer "In11.Cu")
		(net "P5E_CPU0_G3_RX_DN<7>")
	)
	(segment
		(start 415.818066 -5.239258)
		(end 415.818066 -7.57047)
		(width 0.12954)
		(layer "F.Cu")
		(net "P5E_CPU0_G3_RX_DN<6>")
	)
	(segment
		(start 415.95675 -7.709154)
		(end 415.95675 -8.320024)
		(width 0.12954)
		(layer "F.Cu")
		(net "P5E_CPU0_G3_RX_DN<6>")
	)
	(segment
		(start 415.818066 -7.57047)
		(end 415.95675 -7.709154)
		(width 0.12954)
		(layer "F.Cu")
		(net "P5E_CPU0_G3_RX_DN<6>")
	)
	(segment
		(start 367.707926 -246.370094)
		(end 368.174778 -246.104156)
		(width 0.12954)
		(layer "F.Cu")
		(net "P5E_CPU0_G3_RX_DN<6>")
	)
	(segment
		(start 416.09391 -4.963414)
		(end 415.818066 -5.239258)
		(width 0.12954)
		(layer "F.Cu")
		(net "P5E_CPU0_G3_RX_DN<6>")
	)
	(segment
		(start 368.96675 -234.418632)
		(end 368.897154 -234.459272)
		(width 0.1143)
		(layer "In11.Cu")
		(net "P5E_CPU0_G3_RX_DN<6>")
	)
	(segment
		(start 367.806986 -246.034306)
		(end 367.876836 -246.104156)
		(width 0.1143)
		(layer "In11.Cu")
		(net "P5E_CPU0_G3_RX_DN<6>")
	)
	(segment
		(start 369.397026 -225.532188)
		(end 369.395756 -225.53295)
		(width 0.1143)
		(layer "In11.Cu")
		(net "P5E_CPU0_G3_RX_DN<6>")
	)
	(segment
		(start 322.452746 -133.161786)
		(end 316.547246 -149.450044)
		(width 0.14224)
		(layer "In11.Cu")
		(net "P5E_CPU0_G3_RX_DN<6>")
	)
	(segment
		(start 416.09391 -4.963414)
		(end 415.80308 -5.254244)
		(width 0.14224)
		(layer "In11.Cu")
		(net "P5E_CPU0_G3_RX_DN<6>")
	)
	(segment
		(start 369.398804 -225.531172)
		(end 369.397788 -225.53168)
		(width 0.1143)
		(layer "In11.Cu")
		(net "P5E_CPU0_G3_RX_DN<6>")
	)
	(segment
		(start 368.96675 -226.318826)
		(end 368.897154 -226.359466)
		(width 0.1143)
		(layer "In11.Cu")
		(net "P5E_CPU0_G3_RX_DN<6>")
	)
	(segment
		(start 369.430046 -225.512884)
		(end 369.429284 -225.513392)
		(width 0.1143)
		(layer "In11.Cu")
		(net "P5E_CPU0_G3_RX_DN<6>")
	)
	(segment
		(start 368.96675 -240.89868)
		(end 368.897154 -240.93932)
		(width 0.1143)
		(layer "In11.Cu")
		(net "P5E_CPU0_G3_RX_DN<6>")
	)
	(segment
		(start 369.397788 -225.53168)
		(end 369.397026 -225.532188)
		(width 0.1143)
		(layer "In11.Cu")
		(net "P5E_CPU0_G3_RX_DN<6>")
	)
	(segment
		(start 368.897154 -230.208836)
		(end 368.96421 -230.247952)
		(width 0.1143)
		(layer "In11.Cu")
		(net "P5E_CPU0_G3_RX_DN<6>")
	)
	(segment
		(start 368.96675 -236.038644)
		(end 368.897154 -236.079284)
		(width 0.1143)
		(layer "In11.Cu")
		(net "P5E_CPU0_G3_RX_DN<6>")
	)
	(segment
		(start 368.96675 -237.658656)
		(end 368.897154 -237.699296)
		(width 0.1143)
		(layer "In11.Cu")
		(net "P5E_CPU0_G3_RX_DN<6>")
	)
	(segment
		(start 370.696744 -220.584776)
		(end 370.696744 -221.054676)
		(width 0.14224)
		(layer "In11.Cu")
		(net "P5E_CPU0_G3_RX_DN<6>")
	)
	(segment
		(start 368.897154 -226.969066)
		(end 368.96675 -227.009706)
		(width 0.1143)
		(layer "In11.Cu")
		(net "P5E_CPU0_G3_RX_DN<6>")
	)
	(segment
		(start 369.395756 -225.53295)
		(end 369.366038 -225.549968)
		(width 0.1143)
		(layer "In11.Cu")
		(net "P5E_CPU0_G3_RX_DN<6>")
	)
	(segment
		(start 368.897154 -243.168932)
		(end 368.96675 -243.209572)
		(width 0.1143)
		(layer "In11.Cu")
		(net "P5E_CPU0_G3_RX_DN<6>")
	)
	(segment
		(start 368.96675 -231.178862)
		(end 368.927634 -231.201722)
		(width 0.1143)
		(layer "In11.Cu")
		(net "P5E_CPU0_G3_RX_DN<6>")
	)
	(segment
		(start 414.728152 -17.731994)
		(end 414.66516 -17.879568)
		(width 0.14224)
		(layer "In11.Cu")
		(net "P5E_CPU0_G3_RX_DN<6>")
	)
	(segment
		(start 314.53455 -161.756344)
		(end 316.010544 -165.320472)
		(width 0.14224)
		(layer "In11.Cu")
		(net "P5E_CPU0_G3_RX_DN<6>")
	)
	(segment
		(start 368.96675 -242.518692)
		(end 368.897154 -242.559332)
		(width 0.1143)
		(layer "In11.Cu")
		(net "P5E_CPU0_G3_RX_DN<6>")
	)
	(segment
		(start 369.400582 -225.530156)
		(end 369.398804 -225.531172)
		(width 0.1143)
		(layer "In11.Cu")
		(net "P5E_CPU0_G3_RX_DN<6>")
	)
	(segment
		(start 369.429284 -225.513392)
		(end 369.404646 -225.527616)
		(width 0.1143)
		(layer "In11.Cu")
		(net "P5E_CPU0_G3_RX_DN<6>")
	)
	(segment
		(start 368.897154 -241.54892)
		(end 368.96675 -241.58956)
		(width 0.1143)
		(layer "In11.Cu")
		(net "P5E_CPU0_G3_RX_DN<6>")
	)
	(segment
		(start 369.436904 -225.50882)
		(end 369.430046 -225.512884)
		(width 0.1143)
		(layer "In11.Cu")
		(net "P5E_CPU0_G3_RX_DN<6>")
	)
	(segment
		(start 370.651024 -221.128844)
		(end 370.651024 -221.38767)
		(width 0.1143)
		(layer "In11.Cu")
		(net "P5E_CPU0_G3_RX_DN<6>")
	)
	(segment
		(start 318.95161 -168.262554)
		(end 322.858638 -170.60418)
		(width 0.14224)
		(layer "In11.Cu")
		(net "P5E_CPU0_G3_RX_DN<6>")
	)
	(segment
		(start 368.897154 -231.828848)
		(end 368.96675 -231.869488)
		(width 0.1143)
		(layer "In11.Cu")
		(net "P5E_CPU0_G3_RX_DN<6>")
	)
	(segment
		(start 367.876836 -246.104156)
		(end 368.174778 -246.104156)
		(width 0.1143)
		(layer "In11.Cu")
		(net "P5E_CPU0_G3_RX_DN<6>")
	)
	(segment
		(start 368.49685 -244.94871)
		(end 368.445288 -244.978682)
		(width 0.1143)
		(layer "In11.Cu")
		(net "P5E_CPU0_G3_RX_DN<6>")
	)
	(segment
		(start 326.12711 -172.788834)
		(end 327.176638 -173.739302)
		(width 0.14224)
		(layer "In11.Cu")
		(net "P5E_CPU0_G3_RX_DN<6>")
	)
	(segment
		(start 368.257582 -245.303548)
		(end 368.257582 -245.3132)
		(width 0.1143)
		(layer "In11.Cu")
		(net "P5E_CPU0_G3_RX_DN<6>")
	)
	(segment
		(start 322.858638 -170.60418)
		(end 326.12711 -172.788834)
		(width 0.14224)
		(layer "In11.Cu")
		(net "P5E_CPU0_G3_RX_DN<6>")
	)
	(segment
		(start 369.404646 -225.527616)
		(end 369.403122 -225.528632)
		(width 0.1143)
		(layer "In11.Cu")
		(net "P5E_CPU0_G3_RX_DN<6>")
	)
	(segment
		(start 370.376196 -222.269304)
		(end 370.37518 -222.270066)
		(width 0.1143)
		(layer "In11.Cu")
		(net "P5E_CPU0_G3_RX_DN<6>")
	)
	(segment
		(start 414.66516 -17.879568)
		(end 413.66313 -19.455638)
		(width 0.14224)
		(layer "In11.Cu")
		(net "P5E_CPU0_G3_RX_DN<6>")
	)
	(segment
		(start 370.696744 -221.083124)
		(end 370.651024 -221.128844)
		(width 0.1143)
		(layer "In11.Cu")
		(net "P5E_CPU0_G3_RX_DN<6>")
	)
	(segment
		(start 369.906804 -224.698814)
		(end 369.837208 -224.739454)
		(width 0.1143)
		(layer "In11.Cu")
		(net "P5E_CPU0_G3_RX_DN<6>")
	)
	(segment
		(start 368.96675 -239.278668)
		(end 368.897154 -239.319308)
		(width 0.1143)
		(layer "In11.Cu")
		(net "P5E_CPU0_G3_RX_DN<6>")
	)
	(segment
		(start 369.403122 -225.528632)
		(end 369.402106 -225.52914)
		(width 0.1143)
		(layer "In11.Cu")
		(net "P5E_CPU0_G3_RX_DN<6>")
	)
	(segment
		(start 370.620036 -221.418658)
		(end 370.620036 -221.80423)
		(width 0.1143)
		(layer "In11.Cu")
		(net "P5E_CPU0_G3_RX_DN<6>")
	)
	(segment
		(start 368.897154 -233.44886)
		(end 368.96675 -233.4895)
		(width 0.1143)
		(layer "In11.Cu")
		(net "P5E_CPU0_G3_RX_DN<6>")
	)
	(segment
		(start 324.696328 -129.259076)
		(end 322.452746 -133.161786)
		(width 0.14224)
		(layer "In11.Cu")
		(net "P5E_CPU0_G3_RX_DN<6>")
	)
	(segment
		(start 369.402106 -225.52914)
		(end 369.400582 -225.530156)
		(width 0.1143)
		(layer "In11.Cu")
		(net "P5E_CPU0_G3_RX_DN<6>")
	)
	(segment
		(start 369.906804 -223.078802)
		(end 369.837208 -223.119442)
		(width 0.1143)
		(layer "In11.Cu")
		(net "P5E_CPU0_G3_RX_DN<6>")
	)
	(segment
		(start 413.66313 -19.455638)
		(end 386.961126 -54.680612)
		(width 0.14224)
		(layer "In11.Cu")
		(net "P5E_CPU0_G3_RX_DN<6>")
	)
	(segment
		(start 314.53455 -160.905444)
		(end 314.53455 -161.756344)
		(width 0.14224)
		(layer "In11.Cu")
		(net "P5E_CPU0_G3_RX_DN<6>")
	)
	(segment
		(start 316.010544 -165.320472)
		(end 318.95161 -168.262554)
		(width 0.14224)
		(layer "In11.Cu")
		(net "P5E_CPU0_G3_RX_DN<6>")
	)
	(segment
		(start 368.897154 -228.589078)
		(end 368.96675 -228.629718)
		(width 0.1143)
		(layer "In11.Cu")
		(net "P5E_CPU0_G3_RX_DN<6>")
	)
	(segment
		(start 368.964718 -229.560374)
		(end 368.927634 -229.58171)
		(width 0.1143)
		(layer "In11.Cu")
		(net "P5E_CPU0_G3_RX_DN<6>")
	)
	(segment
		(start 363.898942 -203.835762)
		(end 369.904264 -214.06104)
		(width 0.14224)
		(layer "In11.Cu")
		(net "P5E_CPU0_G3_RX_DN<6>")
	)
	(segment
		(start 370.696744 -221.054676)
		(end 370.696744 -221.083124)
		(width 0.1143)
		(layer "In11.Cu")
		(net "P5E_CPU0_G3_RX_DN<6>")
	)
	(segment
		(start 369.837208 -223.729042)
		(end 369.906804 -223.769682)
		(width 0.1143)
		(layer "In11.Cu")
		(net "P5E_CPU0_G3_RX_DN<6>")
	)
	(segment
		(start 368.96675 -227.938838)
		(end 368.897154 -227.979478)
		(width 0.1143)
		(layer "In11.Cu")
		(net "P5E_CPU0_G3_RX_DN<6>")
	)
	(segment
		(start 368.96675 -229.55885)
		(end 368.964718 -229.560374)
		(width 0.1143)
		(layer "In11.Cu")
		(net "P5E_CPU0_G3_RX_DN<6>")
	)
	(segment
		(start 368.927634 -229.58171)
		(end 368.895122 -229.600506)
		(width 0.1143)
		(layer "In11.Cu")
		(net "P5E_CPU0_G3_RX_DN<6>")
	)
	(segment
		(start 368.897154 -238.308896)
		(end 368.96675 -238.349536)
		(width 0.1143)
		(layer "In11.Cu")
		(net "P5E_CPU0_G3_RX_DN<6>")
	)
	(segment
		(start 415.80308 -12.323826)
		(end 414.728152 -17.731994)
		(width 0.14224)
		(layer "In11.Cu")
		(net "P5E_CPU0_G3_RX_DN<6>")
	)
	(segment
		(start 368.897154 -239.928908)
		(end 368.96675 -239.969548)
		(width 0.1143)
		(layer "In11.Cu")
		(net "P5E_CPU0_G3_RX_DN<6>")
	)
	(segment
		(start 316.547246 -149.450044)
		(end 314.53455 -160.905444)
		(width 0.14224)
		(layer "In11.Cu")
		(net "P5E_CPU0_G3_RX_DN<6>")
	)
	(segment
		(start 368.927634 -231.201722)
		(end 368.895122 -231.220518)
		(width 0.1143)
		(layer "In11.Cu")
		(net "P5E_CPU0_G3_RX_DN<6>")
	)
	(segment
		(start 370.37518 -222.270066)
		(end 370.374164 -222.270574)
		(width 0.1143)
		(layer "In11.Cu")
		(net "P5E_CPU0_G3_RX_DN<6>")
	)
	(segment
		(start 415.80308 -5.254244)
		(end 415.80308 -12.323826)
		(width 0.14224)
		(layer "In11.Cu")
		(net "P5E_CPU0_G3_RX_DN<6>")
	)
	(segment
		(start 370.374164 -222.270574)
		(end 370.306092 -222.309944)
		(width 0.1143)
		(layer "In11.Cu")
		(net "P5E_CPU0_G3_RX_DN<6>")
	)
	(segment
		(start 368.96675 -244.138704)
		(end 368.897154 -244.179344)
		(width 0.1143)
		(layer "In11.Cu")
		(net "P5E_CPU0_G3_RX_DN<6>")
	)
	(segment
		(start 368.897154 -236.688884)
		(end 368.96675 -236.729524)
		(width 0.1143)
		(layer "In11.Cu")
		(net "P5E_CPU0_G3_RX_DN<6>")
	)
	(segment
		(start 327.176638 -173.739302)
		(end 363.898942 -203.835762)
		(width 0.14224)
		(layer "In11.Cu")
		(net "P5E_CPU0_G3_RX_DN<6>")
	)
	(segment
		(start 386.961126 -54.680612)
		(end 324.696328 -129.259076)
		(width 0.14224)
		(layer "In11.Cu")
		(net "P5E_CPU0_G3_RX_DN<6>")
	)
	(segment
		(start 368.96675 -232.79862)
		(end 368.897154 -232.83926)
		(width 0.1143)
		(layer "In11.Cu")
		(net "P5E_CPU0_G3_RX_DN<6>")
	)
	(segment
		(start 370.651024 -221.38767)
		(end 370.620036 -221.418658)
		(width 0.1143)
		(layer "In11.Cu")
		(net "P5E_CPU0_G3_RX_DN<6>")
	)
	(segment
		(start 369.904264 -214.06104)
		(end 370.696744 -220.584776)
		(width 0.14224)
		(layer "In11.Cu")
		(net "P5E_CPU0_G3_RX_DN<6>")
	)
	(segment
		(start 368.897154 -235.068872)
		(end 368.96675 -235.109512)
		(width 0.1143)
		(layer "In11.Cu")
		(net "P5E_CPU0_G3_RX_DN<6>")
	)
	(segment
		(start 367.987834 -245.781576)
		(end 367.956084 -245.799864)
		(width 0.1143)
		(layer "In11.Cu")
		(net "P5E_CPU0_G3_RX_DN<6>")
	)
	(arc
		(start 368.96675 -239.969548)
		(mid 369.210077 -240.434114)
		(end 368.96675 -240.89868)
		(width 0.1143)
		(layer "In11.Cu")
		(net "P5E_CPU0_G3_RX_DN<6>")
	)
	(arc
		(start 368.897154 -244.179344)
		(mid 368.781727 -244.31272)
		(end 368.740182 -244.484144)
		(width 0.1143)
		(layer "In11.Cu")
		(net "P5E_CPU0_G3_RX_DN<6>")
	)
	(arc
		(start 369.906804 -223.769682)
		(mid 370.150131 -224.234248)
		(end 369.906804 -224.698814)
		(width 0.1143)
		(layer "In11.Cu")
		(net "P5E_CPU0_G3_RX_DN<6>")
	)
	(arc
		(start 368.96421 -230.247952)
		(mid 369.144862 -230.450697)
		(end 369.210082 -230.714296)
		(width 0.1143)
		(layer "In11.Cu")
		(net "P5E_CPU0_G3_RX_DN<6>")
	)
	(arc
		(start 368.740182 -244.484144)
		(mid 368.675667 -244.746363)
		(end 368.49685 -244.94871)
		(width 0.1143)
		(layer "In11.Cu")
		(net "P5E_CPU0_G3_RX_DN<6>")
	)
	(arc
		(start 369.210082 -225.85426)
		(mid 369.145567 -226.116479)
		(end 368.96675 -226.318826)
		(width 0.1143)
		(layer "In11.Cu")
		(net "P5E_CPU0_G3_RX_DN<6>")
	)
	(arc
		(start 369.680236 -225.044254)
		(mid 369.615721 -225.306473)
		(end 369.436904 -225.50882)
		(width 0.1143)
		(layer "In11.Cu")
		(net "P5E_CPU0_G3_RX_DN<6>")
	)
	(arc
		(start 368.897154 -232.83926)
		(mid 368.740177 -233.14406)
		(end 368.897154 -233.44886)
		(width 0.1143)
		(layer "In11.Cu")
		(net "P5E_CPU0_G3_RX_DN<6>")
	)
	(arc
		(start 368.897154 -234.459272)
		(mid 368.740177 -234.764072)
		(end 368.897154 -235.068872)
		(width 0.1143)
		(layer "In11.Cu")
		(net "P5E_CPU0_G3_RX_DN<6>")
	)
	(arc
		(start 368.96675 -231.869488)
		(mid 369.210077 -232.334054)
		(end 368.96675 -232.79862)
		(width 0.1143)
		(layer "In11.Cu")
		(net "P5E_CPU0_G3_RX_DN<6>")
	)
	(arc
		(start 370.306092 -222.309944)
		(mid 370.191416 -222.443278)
		(end 370.150136 -222.614236)
		(width 0.1143)
		(layer "In11.Cu")
		(net "P5E_CPU0_G3_RX_DN<6>")
	)
	(arc
		(start 368.740182 -231.524048)
		(mid 368.781731 -231.69547)
		(end 368.897154 -231.828848)
		(width 0.1143)
		(layer "In11.Cu")
		(net "P5E_CPU0_G3_RX_DN<6>")
	)
	(arc
		(start 368.895122 -231.220518)
		(mid 368.781193 -231.353665)
		(end 368.740182 -231.524048)
		(width 0.1143)
		(layer "In11.Cu")
		(net "P5E_CPU0_G3_RX_DN<6>")
	)
	(arc
		(start 369.837208 -224.739454)
		(mid 369.721781 -224.87283)
		(end 369.680236 -225.044254)
		(width 0.1143)
		(layer "In11.Cu")
		(net "P5E_CPU0_G3_RX_DN<6>")
	)
	(arc
		(start 368.96675 -243.209572)
		(mid 369.210077 -243.674138)
		(end 368.96675 -244.138704)
		(width 0.1143)
		(layer "In11.Cu")
		(net "P5E_CPU0_G3_RX_DN<6>")
	)
	(arc
		(start 369.366038 -225.549968)
		(mid 369.251362 -225.683302)
		(end 369.210082 -225.85426)
		(width 0.1143)
		(layer "In11.Cu")
		(net "P5E_CPU0_G3_RX_DN<6>")
	)
	(arc
		(start 368.897154 -226.359466)
		(mid 368.740177 -226.664266)
		(end 368.897154 -226.969066)
		(width 0.1143)
		(layer "In11.Cu")
		(net "P5E_CPU0_G3_RX_DN<6>")
	)
	(arc
		(start 368.897154 -227.979478)
		(mid 368.740177 -228.284278)
		(end 368.897154 -228.589078)
		(width 0.1143)
		(layer "In11.Cu")
		(net "P5E_CPU0_G3_RX_DN<6>")
	)
	(arc
		(start 367.956084 -245.799864)
		(mid 367.858949 -245.902733)
		(end 367.806986 -246.034306)
		(width 0.1143)
		(layer "In11.Cu")
		(net "P5E_CPU0_G3_RX_DN<6>")
	)
	(arc
		(start 368.96675 -241.58956)
		(mid 369.210077 -242.054126)
		(end 368.96675 -242.518692)
		(width 0.1143)
		(layer "In11.Cu")
		(net "P5E_CPU0_G3_RX_DN<6>")
	)
	(arc
		(start 368.897154 -240.93932)
		(mid 368.740177 -241.24412)
		(end 368.897154 -241.54892)
		(width 0.1143)
		(layer "In11.Cu")
		(net "P5E_CPU0_G3_RX_DN<6>")
	)
	(arc
		(start 368.897154 -237.699296)
		(mid 368.740177 -238.004096)
		(end 368.897154 -238.308896)
		(width 0.1143)
		(layer "In11.Cu")
		(net "P5E_CPU0_G3_RX_DN<6>")
	)
	(arc
		(start 369.837208 -223.119442)
		(mid 369.680231 -223.424242)
		(end 369.837208 -223.729042)
		(width 0.1143)
		(layer "In11.Cu")
		(net "P5E_CPU0_G3_RX_DN<6>")
	)
	(arc
		(start 368.96675 -235.109512)
		(mid 369.210077 -235.574078)
		(end 368.96675 -236.038644)
		(width 0.1143)
		(layer "In11.Cu")
		(net "P5E_CPU0_G3_RX_DN<6>")
	)
	(arc
		(start 368.740182 -229.904036)
		(mid 368.781731 -230.075458)
		(end 368.897154 -230.208836)
		(width 0.1143)
		(layer "In11.Cu")
		(net "P5E_CPU0_G3_RX_DN<6>")
	)
	(arc
		(start 368.96675 -228.629718)
		(mid 369.210077 -229.094284)
		(end 368.96675 -229.55885)
		(width 0.1143)
		(layer "In11.Cu")
		(net "P5E_CPU0_G3_RX_DN<6>")
	)
	(arc
		(start 368.897154 -242.559332)
		(mid 368.740177 -242.864132)
		(end 368.897154 -243.168932)
		(width 0.1143)
		(layer "In11.Cu")
		(net "P5E_CPU0_G3_RX_DN<6>")
	)
	(arc
		(start 368.96675 -227.009706)
		(mid 369.210077 -227.474272)
		(end 368.96675 -227.938838)
		(width 0.1143)
		(layer "In11.Cu")
		(net "P5E_CPU0_G3_RX_DN<6>")
	)
	(arc
		(start 368.897154 -239.319308)
		(mid 368.740177 -239.624108)
		(end 368.897154 -239.928908)
		(width 0.1143)
		(layer "In11.Cu")
		(net "P5E_CPU0_G3_RX_DN<6>")
	)
	(arc
		(start 368.895122 -229.600506)
		(mid 368.781193 -229.733653)
		(end 368.740182 -229.904036)
		(width 0.1143)
		(layer "In11.Cu")
		(net "P5E_CPU0_G3_RX_DN<6>")
	)
	(arc
		(start 369.210082 -230.714296)
		(mid 369.145567 -230.976515)
		(end 368.96675 -231.178862)
		(width 0.1143)
		(layer "In11.Cu")
		(net "P5E_CPU0_G3_RX_DN<6>")
	)
	(arc
		(start 368.96675 -236.729524)
		(mid 369.210077 -237.19409)
		(end 368.96675 -237.658656)
		(width 0.1143)
		(layer "In11.Cu")
		(net "P5E_CPU0_G3_RX_DN<6>")
	)
	(arc
		(start 368.445288 -244.978682)
		(mid 368.307856 -245.115941)
		(end 368.257582 -245.303548)
		(width 0.1143)
		(layer "In11.Cu")
		(net "P5E_CPU0_G3_RX_DN<6>")
	)
	(arc
		(start 368.897154 -236.079284)
		(mid 368.740177 -236.384084)
		(end 368.897154 -236.688884)
		(width 0.1143)
		(layer "In11.Cu")
		(net "P5E_CPU0_G3_RX_DN<6>")
	)
	(arc
		(start 368.257582 -245.3132)
		(mid 368.185326 -245.583453)
		(end 367.987834 -245.781576)
		(width 0.1143)
		(layer "In11.Cu")
		(net "P5E_CPU0_G3_RX_DN<6>")
	)
	(arc
		(start 370.150136 -222.614236)
		(mid 370.085621 -222.876455)
		(end 369.906804 -223.078802)
		(width 0.1143)
		(layer "In11.Cu")
		(net "P5E_CPU0_G3_RX_DN<6>")
	)
	(arc
		(start 370.620036 -221.80423)
		(mid 370.555377 -222.066787)
		(end 370.376196 -222.269304)
		(width 0.1143)
		(layer "In11.Cu")
		(net "P5E_CPU0_G3_RX_DN<6>")
	)
	(arc
		(start 368.96675 -238.349536)
		(mid 369.210077 -238.814102)
		(end 368.96675 -239.278668)
		(width 0.1143)
		(layer "In11.Cu")
		(net "P5E_CPU0_G3_RX_DN<6>")
	)
	(arc
		(start 368.96675 -233.4895)
		(mid 369.210077 -233.954066)
		(end 368.96675 -234.418632)
		(width 0.1143)
		(layer "In11.Cu")
		(net "P5E_CPU0_G3_RX_DN<6>")
	)
	(segment
		(start 417.756848 -7.709154)
		(end 417.618164 -7.57047)
		(width 0.12954)
		(layer "F.Cu")
		(net "P5E_CPU0_G3_RX_DN<5>")
	)
	(segment
		(start 370.527834 -247.990106)
		(end 370.994686 -247.724168)
		(width 0.12954)
		(layer "F.Cu")
		(net "P5E_CPU0_G3_RX_DN<5>")
	)
	(segment
		(start 417.618164 -6.996176)
		(end 417.889182 -6.725158)
		(width 0.12954)
		(layer "F.Cu")
		(net "P5E_CPU0_G3_RX_DN<5>")
	)
	(segment
		(start 417.618164 -7.57047)
		(end 417.618164 -6.996176)
		(width 0.12954)
		(layer "F.Cu")
		(net "P5E_CPU0_G3_RX_DN<5>")
	)
	(segment
		(start 417.756848 -8.320024)
		(end 417.756848 -7.709154)
		(width 0.12954)
		(layer "F.Cu")
		(net "P5E_CPU0_G3_RX_DN<5>")
	)
	(segment
		(start 417.139374 -17.814798)
		(end 417.36137 -18.229834)
		(width 0.14224)
		(layer "In11.Cu")
		(net "P5E_CPU0_G3_RX_DN<5>")
	)
	(segment
		(start 369.868958 -239.30102)
		(end 369.867942 -239.301528)
		(width 0.1143)
		(layer "In11.Cu")
		(net "P5E_CPU0_G3_RX_DN<5>")
	)
	(segment
		(start 369.867942 -239.946688)
		(end 369.868958 -239.947196)
		(width 0.1143)
		(layer "In11.Cu")
		(net "P5E_CPU0_G3_RX_DN<5>")
	)
	(segment
		(start 369.907058 -242.518692)
		(end 369.870482 -242.540028)
		(width 0.1143)
		(layer "In11.Cu")
		(net "P5E_CPU0_G3_RX_DN<5>")
	)
	(segment
		(start 369.86718 -235.086144)
		(end 369.867942 -235.086652)
		(width 0.1143)
		(layer "In11.Cu")
		(net "P5E_CPU0_G3_RX_DN<5>")
	)
	(segment
		(start 369.836192 -236.688376)
		(end 369.86591 -236.705394)
		(width 0.1143)
		(layer "In11.Cu")
		(net "P5E_CPU0_G3_RX_DN<5>")
	)
	(segment
		(start 369.870482 -239.948212)
		(end 369.907058 -239.969548)
		(width 0.1143)
		(layer "In11.Cu")
		(net "P5E_CPU0_G3_RX_DN<5>")
	)
	(segment
		(start 369.868958 -236.707172)
		(end 369.870482 -236.708188)
		(width 0.1143)
		(layer "In11.Cu")
		(net "P5E_CPU0_G3_RX_DN<5>")
	)
	(segment
		(start 417.79444 -19.55038)
		(end 417.523676 -20.219416)
		(width 0.14224)
		(layer "In11.Cu")
		(net "P5E_CPU0_G3_RX_DN<5>")
	)
	(segment
		(start 323.25818 -133.683756)
		(end 317.448692 -149.707092)
		(width 0.14224)
		(layer "In11.Cu")
		(net "P5E_CPU0_G3_RX_DN<5>")
	)
	(segment
		(start 369.836192 -238.308388)
		(end 369.86591 -238.325406)
		(width 0.1143)
		(layer "In11.Cu")
		(net "P5E_CPU0_G3_RX_DN<5>")
	)
	(segment
		(start 372.256812 -222.268796)
		(end 372.187216 -222.309436)
		(width 0.1143)
		(layer "In11.Cu")
		(net "P5E_CPU0_G3_RX_DN<5>")
	)
	(segment
		(start 369.867942 -236.706664)
		(end 369.868958 -236.707172)
		(width 0.1143)
		(layer "In11.Cu")
		(net "P5E_CPU0_G3_RX_DN<5>")
	)
	(segment
		(start 369.907058 -245.758716)
		(end 369.870482 -245.780052)
		(width 0.1143)
		(layer "In11.Cu")
		(net "P5E_CPU0_G3_RX_DN<5>")
	)
	(segment
		(start 369.867942 -232.82148)
		(end 369.86718 -232.821988)
		(width 0.1143)
		(layer "In11.Cu")
		(net "P5E_CPU0_G3_RX_DN<5>")
	)
	(segment
		(start 369.86718 -240.922048)
		(end 369.86591 -240.92281)
		(width 0.1143)
		(layer "In11.Cu")
		(net "P5E_CPU0_G3_RX_DN<5>")
	)
	(segment
		(start 371.747796 -223.101662)
		(end 371.747034 -223.10217)
		(width 0.1143)
		(layer "In11.Cu")
		(net "P5E_CPU0_G3_RX_DN<5>")
	)
	(segment
		(start 369.86718 -233.466132)
		(end 369.867942 -233.46664)
		(width 0.1143)
		(layer "In11.Cu")
		(net "P5E_CPU0_G3_RX_DN<5>")
	)
	(segment
		(start 369.86718 -246.426228)
		(end 369.867942 -246.426736)
		(width 0.1143)
		(layer "In11.Cu")
		(net "P5E_CPU0_G3_RX_DN<5>")
	)
	(segment
		(start 369.907058 -237.658656)
		(end 369.870482 -237.679992)
		(width 0.1143)
		(layer "In11.Cu")
		(net "P5E_CPU0_G3_RX_DN<5>")
	)
	(segment
		(start 369.86591 -244.162834)
		(end 369.836192 -244.179852)
		(width 0.1143)
		(layer "In11.Cu")
		(net "P5E_CPU0_G3_RX_DN<5>")
	)
	(segment
		(start 372.54561 -220.646498)
		(end 372.54561 -221.17431)
		(width 0.14224)
		(layer "In11.Cu")
		(net "P5E_CPU0_G3_RX_DN<5>")
	)
	(segment
		(start 315.46673 -161.570416)
		(end 316.751716 -164.673026)
		(width 0.14224)
		(layer "In11.Cu")
		(net "P5E_CPU0_G3_RX_DN<5>")
	)
	(segment
		(start 369.867942 -230.226616)
		(end 369.904518 -230.247952)
		(width 0.1143)
		(layer "In11.Cu")
		(net "P5E_CPU0_G3_RX_DN<5>")
	)
	(segment
		(start 369.870482 -234.439968)
		(end 369.868958 -234.440984)
		(width 0.1143)
		(layer "In11.Cu")
		(net "P5E_CPU0_G3_RX_DN<5>")
	)
	(segment
		(start 369.86718 -231.84612)
		(end 369.867942 -231.846628)
		(width 0.1143)
		(layer "In11.Cu")
		(net "P5E_CPU0_G3_RX_DN<5>")
	)
	(segment
		(start 369.907058 -244.138704)
		(end 369.870482 -244.16004)
		(width 0.1143)
		(layer "In11.Cu")
		(net "P5E_CPU0_G3_RX_DN<5>")
	)
	(segment
		(start 370.846858 -224.698814)
		(end 370.807742 -224.721674)
		(width 0.1143)
		(layer "In11.Cu")
		(net "P5E_CPU0_G3_RX_DN<5>")
	)
	(segment
		(start 369.836192 -233.448352)
		(end 369.86591 -233.46537)
		(width 0.1143)
		(layer "In11.Cu")
		(net "P5E_CPU0_G3_RX_DN<5>")
	)
	(segment
		(start 369.868958 -231.847136)
		(end 369.870482 -231.848152)
		(width 0.1143)
		(layer "In11.Cu")
		(net "P5E_CPU0_G3_RX_DN<5>")
	)
	(segment
		(start 369.86591 -244.805454)
		(end 369.86718 -244.806216)
		(width 0.1143)
		(layer "In11.Cu")
		(net "P5E_CPU0_G3_RX_DN<5>")
	)
	(segment
		(start 372.54561 -221.202758)
		(end 372.49989 -221.248478)
		(width 0.1143)
		(layer "In11.Cu")
		(net "P5E_CPU0_G3_RX_DN<5>")
	)
	(segment
		(start 369.836192 -230.208328)
		(end 369.867942 -230.226616)
		(width 0.1143)
		(layer "In11.Cu")
		(net "P5E_CPU0_G3_RX_DN<5>")
	)
	(segment
		(start 369.867942 -236.061504)
		(end 369.86718 -236.062012)
		(width 0.1143)
		(layer "In11.Cu")
		(net "P5E_CPU0_G3_RX_DN<5>")
	)
	(segment
		(start 370.807742 -224.721674)
		(end 370.778786 -224.738438)
		(width 0.1143)
		(layer "In11.Cu")
		(net "P5E_CPU0_G3_RX_DN<5>")
	)
	(segment
		(start 369.867688 -229.58171)
		(end 369.835176 -229.600506)
		(width 0.1143)
		(layer "In11.Cu")
		(net "P5E_CPU0_G3_RX_DN<5>")
	)
	(segment
		(start 369.870482 -245.780052)
		(end 369.868958 -245.781068)
		(width 0.1143)
		(layer "In11.Cu")
		(net "P5E_CPU0_G3_RX_DN<5>")
	)
	(segment
		(start 369.86718 -239.94618)
		(end 369.867942 -239.946688)
		(width 0.1143)
		(layer "In11.Cu")
		(net "P5E_CPU0_G3_RX_DN<5>")
	)
	(segment
		(start 369.870482 -241.568224)
		(end 369.907058 -241.58956)
		(width 0.1143)
		(layer "In11.Cu")
		(net "P5E_CPU0_G3_RX_DN<5>")
	)
	(segment
		(start 369.867942 -244.161564)
		(end 369.86718 -244.162072)
		(width 0.1143)
		(layer "In11.Cu")
		(net "P5E_CPU0_G3_RX_DN<5>")
	)
	(segment
		(start 369.868958 -246.427244)
		(end 369.870482 -246.42826)
		(width 0.1143)
		(layer "In11.Cu")
		(net "P5E_CPU0_G3_RX_DN<5>")
	)
	(segment
		(start 369.86591 -231.845358)
		(end 369.86718 -231.84612)
		(width 0.1143)
		(layer "In11.Cu")
		(net "P5E_CPU0_G3_RX_DN<5>")
	)
	(segment
		(start 369.86718 -234.442)
		(end 369.86591 -234.442762)
		(width 0.1143)
		(layer "In11.Cu")
		(net "P5E_CPU0_G3_RX_DN<5>")
	)
	(segment
		(start 369.867942 -240.92154)
		(end 369.86718 -240.922048)
		(width 0.1143)
		(layer "In11.Cu")
		(net "P5E_CPU0_G3_RX_DN<5>")
	)
	(segment
		(start 369.86591 -238.325406)
		(end 369.86718 -238.326168)
		(width 0.1143)
		(layer "In11.Cu")
		(net "P5E_CPU0_G3_RX_DN<5>")
	)
	(segment
		(start 319.01511 -166.936928)
		(end 319.019682 -166.941754)
		(width 0.14224)
		(layer "In11.Cu")
		(net "P5E_CPU0_G3_RX_DN<5>")
	)
	(segment
		(start 369.86718 -236.062012)
		(end 369.86591 -236.062774)
		(width 0.1143)
		(layer "In11.Cu")
		(net "P5E_CPU0_G3_RX_DN<5>")
	)
	(segment
		(start 371.748812 -223.101154)
		(end 371.747796 -223.101662)
		(width 0.1143)
		(layer "In11.Cu")
		(net "P5E_CPU0_G3_RX_DN<5>")
	)
	(segment
		(start 369.836192 -244.788436)
		(end 369.86591 -244.805454)
		(width 0.1143)
		(layer "In11.Cu")
		(net "P5E_CPU0_G3_RX_DN<5>")
	)
	(segment
		(start 325.559674 -129.680462)
		(end 323.25818 -133.683756)
		(width 0.14224)
		(layer "In11.Cu")
		(net "P5E_CPU0_G3_RX_DN<5>")
	)
	(segment
		(start 369.906804 -227.938838)
		(end 369.837208 -227.979478)
		(width 0.1143)
		(layer "In11.Cu")
		(net "P5E_CPU0_G3_RX_DN<5>")
	)
	(segment
		(start 369.86591 -233.46537)
		(end 369.86718 -233.466132)
		(width 0.1143)
		(layer "In11.Cu")
		(net "P5E_CPU0_G3_RX_DN<5>")
	)
	(segment
		(start 369.870482 -236.708188)
		(end 369.907058 -236.729524)
		(width 0.1143)
		(layer "In11.Cu")
		(net "P5E_CPU0_G3_RX_DN<5>")
	)
	(segment
		(start 369.86591 -246.425466)
		(end 369.86718 -246.426228)
		(width 0.1143)
		(layer "In11.Cu")
		(net "P5E_CPU0_G3_RX_DN<5>")
	)
	(segment
		(start 417.79444 -18.877788)
		(end 417.79444 -19.55038)
		(width 0.14224)
		(layer "In11.Cu")
		(net "P5E_CPU0_G3_RX_DN<5>")
	)
	(segment
		(start 323.414644 -169.850308)
		(end 326.746362 -172.080936)
		(width 0.14224)
		(layer "In11.Cu")
		(net "P5E_CPU0_G3_RX_DN<5>")
	)
	(segment
		(start 317.448692 -149.707092)
		(end 315.46673 -160.987994)
		(width 0.14224)
		(layer "In11.Cu")
		(net "P5E_CPU0_G3_RX_DN<5>")
	)
	(segment
		(start 369.867942 -239.301528)
		(end 369.86718 -239.302036)
		(width 0.1143)
		(layer "In11.Cu")
		(net "P5E_CPU0_G3_RX_DN<5>")
	)
	(segment
		(start 326.746362 -172.080936)
		(end 327.652888 -172.902372)
		(width 0.14224)
		(layer "In11.Cu")
		(net "P5E_CPU0_G3_RX_DN<5>")
	)
	(segment
		(start 369.837208 -228.589078)
		(end 369.906804 -228.629718)
		(width 0.1143)
		(layer "In11.Cu")
		(net "P5E_CPU0_G3_RX_DN<5>")
	)
	(segment
		(start 369.868958 -236.060996)
		(end 369.867942 -236.061504)
		(width 0.1143)
		(layer "In11.Cu")
		(net "P5E_CPU0_G3_RX_DN<5>")
	)
	(segment
		(start 371.316758 -223.888808)
		(end 371.277642 -223.911668)
		(width 0.1143)
		(layer "In11.Cu")
		(net "P5E_CPU0_G3_RX_DN<5>")
	)
	(segment
		(start 370.614194 -247.641364)
		(end 370.696998 -247.724168)
		(width 0.1143)
		(layer "In11.Cu")
		(net "P5E_CPU0_G3_RX_DN<5>")
	)
	(segment
		(start 369.868958 -244.807232)
		(end 369.870482 -244.808248)
		(width 0.1143)
		(layer "In11.Cu")
		(net "P5E_CPU0_G3_RX_DN<5>")
	)
	(segment
		(start 372.54561 -221.17431)
		(end 372.54561 -221.202758)
		(width 0.1143)
		(layer "In11.Cu")
		(net "P5E_CPU0_G3_RX_DN<5>")
	)
	(segment
		(start 417.36137 -18.229834)
		(end 417.79444 -18.877788)
		(width 0.14224)
		(layer "In11.Cu")
		(net "P5E_CPU0_G3_RX_DN<5>")
	)
	(segment
		(start 417.598352 -7.015988)
		(end 417.598352 -12.482322)
		(width 0.14224)
		(layer "In11.Cu")
		(net "P5E_CPU0_G3_RX_DN<5>")
	)
	(segment
		(start 369.867942 -231.846628)
		(end 369.868958 -231.847136)
		(width 0.1143)
		(layer "In11.Cu")
		(net "P5E_CPU0_G3_RX_DN<5>")
	)
	(segment
		(start 417.095432 -17.70888)
		(end 417.139374 -17.814798)
		(width 0.14224)
		(layer "In11.Cu")
		(net "P5E_CPU0_G3_RX_DN<5>")
	)
	(segment
		(start 364.599474 -203.179934)
		(end 370.993162 -213.943946)
		(width 0.14224)
		(layer "In11.Cu")
		(net "P5E_CPU0_G3_RX_DN<5>")
	)
	(segment
		(start 370.33581 -225.53295)
		(end 370.306092 -225.549968)
		(width 0.1143)
		(layer "In11.Cu")
		(net "P5E_CPU0_G3_RX_DN<5>")
	)
	(segment
		(start 369.868958 -242.541044)
		(end 369.867942 -242.541552)
		(width 0.1143)
		(layer "In11.Cu")
		(net "P5E_CPU0_G3_RX_DN<5>")
	)
	(segment
		(start 371.745764 -223.102932)
		(end 371.716046 -223.11995)
		(width 0.1143)
		(layer "In11.Cu")
		(net "P5E_CPU0_G3_RX_DN<5>")
	)
	(segment
		(start 369.867942 -246.426736)
		(end 369.868958 -246.427244)
		(width 0.1143)
		(layer "In11.Cu")
		(net "P5E_CPU0_G3_RX_DN<5>")
	)
	(segment
		(start 369.868958 -239.947196)
		(end 369.870482 -239.948212)
		(width 0.1143)
		(layer "In11.Cu")
		(net "P5E_CPU0_G3_RX_DN<5>")
	)
	(segment
		(start 369.907058 -239.278668)
		(end 369.870482 -239.300004)
		(width 0.1143)
		(layer "In11.Cu")
		(net "P5E_CPU0_G3_RX_DN<5>")
	)
	(segment
		(start 369.86718 -244.806216)
		(end 369.867942 -244.806724)
		(width 0.1143)
		(layer "In11.Cu")
		(net "P5E_CPU0_G3_RX_DN<5>")
	)
	(segment
		(start 370.33708 -225.532188)
		(end 370.33581 -225.53295)
		(width 0.1143)
		(layer "In11.Cu")
		(net "P5E_CPU0_G3_RX_DN<5>")
	)
	(segment
		(start 417.095432 -17.5895)
		(end 417.095432 -17.70888)
		(width 0.14224)
		(layer "In11.Cu")
		(net "P5E_CPU0_G3_RX_DN<5>")
	)
	(segment
		(start 369.907058 -234.418632)
		(end 369.870482 -234.439968)
		(width 0.1143)
		(layer "In11.Cu")
		(net "P5E_CPU0_G3_RX_DN<5>")
	)
	(segment
		(start 369.907058 -232.79862)
		(end 369.870482 -232.819956)
		(width 0.1143)
		(layer "In11.Cu")
		(net "P5E_CPU0_G3_RX_DN<5>")
	)
	(segment
		(start 369.870482 -237.679992)
		(end 369.868958 -237.681008)
		(width 0.1143)
		(layer "In11.Cu")
		(net "P5E_CPU0_G3_RX_DN<5>")
	)
	(segment
		(start 369.907058 -236.038644)
		(end 369.870482 -236.05998)
		(width 0.1143)
		(layer "In11.Cu")
		(net "P5E_CPU0_G3_RX_DN<5>")
	)
	(segment
		(start 369.870482 -232.819956)
		(end 369.868958 -232.820972)
		(width 0.1143)
		(layer "In11.Cu")
		(net "P5E_CPU0_G3_RX_DN<5>")
	)
	(segment
		(start 369.836192 -246.408448)
		(end 369.86591 -246.425466)
		(width 0.1143)
		(layer "In11.Cu")
		(net "P5E_CPU0_G3_RX_DN<5>")
	)
	(segment
		(start 369.86718 -244.162072)
		(end 369.86591 -244.162834)
		(width 0.1143)
		(layer "In11.Cu")
		(net "P5E_CPU0_G3_RX_DN<5>")
	)
	(segment
		(start 369.868958 -238.327184)
		(end 369.907058 -238.349536)
		(width 0.1143)
		(layer "In11.Cu")
		(net "P5E_CPU0_G3_RX_DN<5>")
	)
	(segment
		(start 370.993162 -213.943946)
		(end 372.54561 -220.646498)
		(width 0.14224)
		(layer "In11.Cu")
		(net "P5E_CPU0_G3_RX_DN<5>")
	)
	(segment
		(start 369.868958 -243.18722)
		(end 369.870482 -243.188236)
		(width 0.1143)
		(layer "In11.Cu")
		(net "P5E_CPU0_G3_RX_DN<5>")
	)
	(segment
		(start 320.301112 -167.979598)
		(end 323.414644 -169.850308)
		(width 0.14224)
		(layer "In11.Cu")
		(net "P5E_CPU0_G3_RX_DN<5>")
	)
	(segment
		(start 370.376958 -225.50882)
		(end 370.3701 -225.512884)
		(width 0.1143)
		(layer "In11.Cu")
		(net "P5E_CPU0_G3_RX_DN<5>")
	)
	(segment
		(start 369.868958 -237.681008)
		(end 369.867942 -237.681516)
		(width 0.1143)
		(layer "In11.Cu")
		(net "P5E_CPU0_G3_RX_DN<5>")
	)
	(segment
		(start 371.277642 -223.911668)
		(end 371.247162 -223.929448)
		(width 0.1143)
		(layer "In11.Cu")
		(net "P5E_CPU0_G3_RX_DN<5>")
	)
	(segment
		(start 327.652888 -172.902372)
		(end 364.599474 -203.179934)
		(width 0.14224)
		(layer "In11.Cu")
		(net "P5E_CPU0_G3_RX_DN<5>")
	)
	(segment
		(start 369.870482 -236.05998)
		(end 369.868958 -236.060996)
		(width 0.1143)
		(layer "In11.Cu")
		(net "P5E_CPU0_G3_RX_DN<5>")
	)
	(segment
		(start 369.867942 -235.086652)
		(end 369.868958 -235.08716)
		(width 0.1143)
		(layer "In11.Cu")
		(net "P5E_CPU0_G3_RX_DN<5>")
	)
	(segment
		(start 369.86591 -240.92281)
		(end 369.836192 -240.939828)
		(width 0.1143)
		(layer "In11.Cu")
		(net "P5E_CPU0_G3_RX_DN<5>")
	)
	(segment
		(start 369.86591 -243.185442)
		(end 369.86718 -243.186204)
		(width 0.1143)
		(layer "In11.Cu")
		(net "P5E_CPU0_G3_RX_DN<5>")
	)
	(segment
		(start 320.29527 -167.976042)
		(end 320.301366 -167.979598)
		(width 0.14224)
		(layer "In11.Cu")
		(net "P5E_CPU0_G3_RX_DN<5>")
	)
	(segment
		(start 369.870482 -246.42826)
		(end 369.907058 -246.449596)
		(width 0.1143)
		(layer "In11.Cu")
		(net "P5E_CPU0_G3_RX_DN<5>")
	)
	(segment
		(start 319.819782 -167.667178)
		(end 320.22542 -167.938704)
		(width 0.14224)
		(layer "In11.Cu")
		(net "P5E_CPU0_G3_RX_DN<5>")
	)
	(segment
		(start 369.867942 -243.186712)
		(end 369.868958 -243.18722)
		(width 0.1143)
		(layer "In11.Cu")
		(net "P5E_CPU0_G3_RX_DN<5>")
	)
	(segment
		(start 369.836192 -239.9284)
		(end 369.86591 -239.945418)
		(width 0.1143)
		(layer "In11.Cu")
		(net "P5E_CPU0_G3_RX_DN<5>")
	)
	(segment
		(start 369.870482 -244.16004)
		(end 369.868958 -244.161056)
		(width 0.1143)
		(layer "In11.Cu")
		(net "P5E_CPU0_G3_RX_DN<5>")
	)
	(segment
		(start 369.868958 -245.781068)
		(end 369.867942 -245.781576)
		(width 0.1143)
		(layer "In11.Cu")
		(net "P5E_CPU0_G3_RX_DN<5>")
	)
	(segment
		(start 369.906804 -229.55885)
		(end 369.904772 -229.560374)
		(width 0.1143)
		(layer "In11.Cu")
		(net "P5E_CPU0_G3_RX_DN<5>")
	)
	(segment
		(start 370.338858 -225.531172)
		(end 370.337842 -225.53168)
		(width 0.1143)
		(layer "In11.Cu")
		(net "P5E_CPU0_G3_RX_DN<5>")
	)
	(segment
		(start 369.907058 -231.178862)
		(end 369.834414 -231.22128)
		(width 0.1143)
		(layer "In11.Cu")
		(net "P5E_CPU0_G3_RX_DN<5>")
	)
	(segment
		(start 319.019682 -166.941754)
		(end 319.819782 -167.667178)
		(width 0.14224)
		(layer "In11.Cu")
		(net "P5E_CPU0_G3_RX_DN<5>")
	)
	(segment
		(start 369.86718 -232.821988)
		(end 369.86591 -232.82275)
		(width 0.1143)
		(layer "In11.Cu")
		(net "P5E_CPU0_G3_RX_DN<5>")
	)
	(segment
		(start 417.889182 -6.725158)
		(end 417.598352 -7.015988)
		(width 0.14224)
		(layer "In11.Cu")
		(net "P5E_CPU0_G3_RX_DN<5>")
	)
	(segment
		(start 369.870482 -240.920016)
		(end 369.868958 -240.921032)
		(width 0.1143)
		(layer "In11.Cu")
		(net "P5E_CPU0_G3_RX_DN<5>")
	)
	(segment
		(start 369.867942 -237.681516)
		(end 369.836192 -237.699804)
		(width 0.1143)
		(layer "In11.Cu")
		(net "P5E_CPU0_G3_RX_DN<5>")
	)
	(segment
		(start 369.86718 -239.302036)
		(end 369.86591 -239.302798)
		(width 0.1143)
		(layer "In11.Cu")
		(net "P5E_CPU0_G3_RX_DN<5>")
	)
	(segment
		(start 369.867942 -234.441492)
		(end 369.86718 -234.442)
		(width 0.1143)
		(layer "In11.Cu")
		(net "P5E_CPU0_G3_RX_DN<5>")
	)
	(segment
		(start 369.86718 -236.706156)
		(end 369.867942 -236.706664)
		(width 0.1143)
		(layer "In11.Cu")
		(net "P5E_CPU0_G3_RX_DN<5>")
	)
	(segment
		(start 370.307362 -247.218962)
		(end 370.376958 -247.259602)
		(width 0.1143)
		(layer "In11.Cu")
		(net "P5E_CPU0_G3_RX_DN<5>")
	)
	(segment
		(start 369.836192 -231.82834)
		(end 369.86591 -231.845358)
		(width 0.1143)
		(layer "In11.Cu")
		(net "P5E_CPU0_G3_RX_DN<5>")
	)
	(segment
		(start 369.868958 -233.467148)
		(end 369.870482 -233.468164)
		(width 0.1143)
		(layer "In11.Cu")
		(net "P5E_CPU0_G3_RX_DN<5>")
	)
	(segment
		(start 369.868958 -244.161056)
		(end 369.867942 -244.161564)
		(width 0.1143)
		(layer "In11.Cu")
		(net "P5E_CPU0_G3_RX_DN<5>")
	)
	(segment
		(start 369.870482 -239.300004)
		(end 369.868958 -239.30102)
		(width 0.1143)
		(layer "In11.Cu")
		(net "P5E_CPU0_G3_RX_DN<5>")
	)
	(segment
		(start 369.868958 -240.921032)
		(end 369.867942 -240.92154)
		(width 0.1143)
		(layer "In11.Cu")
		(net "P5E_CPU0_G3_RX_DN<5>")
	)
	(segment
		(start 369.868958 -234.440984)
		(end 369.867942 -234.441492)
		(width 0.1143)
		(layer "In11.Cu")
		(net "P5E_CPU0_G3_RX_DN<5>")
	)
	(segment
		(start 369.867942 -245.781576)
		(end 369.836192 -245.799864)
		(width 0.1143)
		(layer "In11.Cu")
		(net "P5E_CPU0_G3_RX_DN<5>")
	)
	(segment
		(start 369.86591 -239.945418)
		(end 369.86718 -239.94618)
		(width 0.1143)
		(layer "In11.Cu")
		(net "P5E_CPU0_G3_RX_DN<5>")
	)
	(segment
		(start 417.523676 -20.219416)
		(end 388.407402 -54.403244)
		(width 0.14224)
		(layer "In11.Cu")
		(net "P5E_CPU0_G3_RX_DN<5>")
	)
	(segment
		(start 369.907058 -240.89868)
		(end 369.870482 -240.920016)
		(width 0.1143)
		(layer "In11.Cu")
		(net "P5E_CPU0_G3_RX_DN<5>")
	)
	(segment
		(start 369.86718 -243.186204)
		(end 369.867942 -243.186712)
		(width 0.1143)
		(layer "In11.Cu")
		(net "P5E_CPU0_G3_RX_DN<5>")
	)
	(segment
		(start 371.747034 -223.10217)
		(end 371.745764 -223.102932)
		(width 0.1143)
		(layer "In11.Cu")
		(net "P5E_CPU0_G3_RX_DN<5>")
	)
	(segment
		(start 369.86591 -236.062774)
		(end 369.836192 -236.079792)
		(width 0.1143)
		(layer "In11.Cu")
		(net "P5E_CPU0_G3_RX_DN<5>")
	)
	(segment
		(start 417.598352 -12.482322)
		(end 417.095432 -17.5895)
		(width 0.14224)
		(layer "In11.Cu")
		(net "P5E_CPU0_G3_RX_DN<5>")
	)
	(segment
		(start 369.836192 -235.068364)
		(end 369.86591 -235.085382)
		(width 0.1143)
		(layer "In11.Cu")
		(net "P5E_CPU0_G3_RX_DN<5>")
	)
	(segment
		(start 369.836192 -243.168424)
		(end 369.86591 -243.185442)
		(width 0.1143)
		(layer "In11.Cu")
		(net "P5E_CPU0_G3_RX_DN<5>")
	)
	(segment
		(start 369.868958 -235.08716)
		(end 369.870482 -235.088176)
		(width 0.1143)
		(layer "In11.Cu")
		(net "P5E_CPU0_G3_RX_DN<5>")
	)
	(segment
		(start 369.86591 -241.56543)
		(end 369.86718 -241.566192)
		(width 0.1143)
		(layer "In11.Cu")
		(net "P5E_CPU0_G3_RX_DN<5>")
	)
	(segment
		(start 369.86718 -238.326168)
		(end 369.867942 -238.326676)
		(width 0.1143)
		(layer "In11.Cu")
		(net "P5E_CPU0_G3_RX_DN<5>")
	)
	(segment
		(start 369.867942 -238.326676)
		(end 369.868958 -238.327184)
		(width 0.1143)
		(layer "In11.Cu")
		(net "P5E_CPU0_G3_RX_DN<5>")
	)
	(segment
		(start 369.867942 -233.46664)
		(end 369.868958 -233.467148)
		(width 0.1143)
		(layer "In11.Cu")
		(net "P5E_CPU0_G3_RX_DN<5>")
	)
	(segment
		(start 369.86591 -232.82275)
		(end 369.836192 -232.839768)
		(width 0.1143)
		(layer "In11.Cu")
		(net "P5E_CPU0_G3_RX_DN<5>")
	)
	(segment
		(start 315.46673 -160.987994)
		(end 315.46673 -161.570416)
		(width 0.14224)
		(layer "In11.Cu")
		(net "P5E_CPU0_G3_RX_DN<5>")
	)
	(segment
		(start 369.867942 -244.806724)
		(end 369.868958 -244.807232)
		(width 0.1143)
		(layer "In11.Cu")
		(net "P5E_CPU0_G3_RX_DN<5>")
	)
	(segment
		(start 369.870482 -242.540028)
		(end 369.868958 -242.541044)
		(width 0.1143)
		(layer "In11.Cu")
		(net "P5E_CPU0_G3_RX_DN<5>")
	)
	(segment
		(start 369.870482 -233.468164)
		(end 369.907058 -233.4895)
		(width 0.1143)
		(layer "In11.Cu")
		(net "P5E_CPU0_G3_RX_DN<5>")
	)
	(segment
		(start 369.906804 -226.318826)
		(end 369.837208 -226.359466)
		(width 0.1143)
		(layer "In11.Cu")
		(net "P5E_CPU0_G3_RX_DN<5>")
	)
	(segment
		(start 369.86591 -235.085382)
		(end 369.86718 -235.086144)
		(width 0.1143)
		(layer "In11.Cu")
		(net "P5E_CPU0_G3_RX_DN<5>")
	)
	(segment
		(start 369.837208 -226.969066)
		(end 369.906804 -227.009706)
		(width 0.1143)
		(layer "In11.Cu")
		(net "P5E_CPU0_G3_RX_DN<5>")
	)
	(segment
		(start 372.49989 -221.248478)
		(end 372.49989 -221.80423)
		(width 0.1143)
		(layer "In11.Cu")
		(net "P5E_CPU0_G3_RX_DN<5>")
	)
	(segment
		(start 388.407402 -54.403244)
		(end 325.559674 -129.680462)
		(width 0.14224)
		(layer "In11.Cu")
		(net "P5E_CPU0_G3_RX_DN<5>")
	)
	(segment
		(start 369.868958 -232.820972)
		(end 369.867942 -232.82148)
		(width 0.1143)
		(layer "In11.Cu")
		(net "P5E_CPU0_G3_RX_DN<5>")
	)
	(segment
		(start 369.870482 -244.808248)
		(end 369.907058 -244.829584)
		(width 0.1143)
		(layer "In11.Cu")
		(net "P5E_CPU0_G3_RX_DN<5>")
	)
	(segment
		(start 369.904772 -229.560374)
		(end 369.867688 -229.58171)
		(width 0.1143)
		(layer "In11.Cu")
		(net "P5E_CPU0_G3_RX_DN<5>")
	)
	(segment
		(start 369.868958 -241.567208)
		(end 369.870482 -241.568224)
		(width 0.1143)
		(layer "In11.Cu")
		(net "P5E_CPU0_G3_RX_DN<5>")
	)
	(segment
		(start 369.870482 -243.188236)
		(end 369.907058 -243.209572)
		(width 0.1143)
		(layer "In11.Cu")
		(net "P5E_CPU0_G3_RX_DN<5>")
	)
	(segment
		(start 370.369338 -225.513392)
		(end 370.338858 -225.531172)
		(width 0.1143)
		(layer "In11.Cu")
		(net "P5E_CPU0_G3_RX_DN<5>")
	)
	(segment
		(start 369.86718 -241.566192)
		(end 369.867942 -241.5667)
		(width 0.1143)
		(layer "In11.Cu")
		(net "P5E_CPU0_G3_RX_DN<5>")
	)
	(segment
		(start 369.870482 -235.088176)
		(end 369.907058 -235.109512)
		(width 0.1143)
		(layer "In11.Cu")
		(net "P5E_CPU0_G3_RX_DN<5>")
	)
	(segment
		(start 370.3701 -225.512884)
		(end 370.369338 -225.513392)
		(width 0.1143)
		(layer "In11.Cu")
		(net "P5E_CPU0_G3_RX_DN<5>")
	)
	(segment
		(start 320.301366 -167.979598)
		(end 320.301112 -167.979598)
		(width 0.14224)
		(layer "In11.Cu")
		(net "P5E_CPU0_G3_RX_DN<5>")
	)
	(segment
		(start 369.836192 -241.548412)
		(end 369.86591 -241.56543)
		(width 0.1143)
		(layer "In11.Cu")
		(net "P5E_CPU0_G3_RX_DN<5>")
	)
	(segment
		(start 369.867942 -242.541552)
		(end 369.836192 -242.55984)
		(width 0.1143)
		(layer "In11.Cu")
		(net "P5E_CPU0_G3_RX_DN<5>")
	)
	(segment
		(start 369.86591 -236.705394)
		(end 369.86718 -236.706156)
		(width 0.1143)
		(layer "In11.Cu")
		(net "P5E_CPU0_G3_RX_DN<5>")
	)
	(segment
		(start 371.750336 -223.100138)
		(end 371.748812 -223.101154)
		(width 0.1143)
		(layer "In11.Cu")
		(net "P5E_CPU0_G3_RX_DN<5>")
	)
	(segment
		(start 316.751716 -164.673026)
		(end 319.01511 -166.936928)
		(width 0.14224)
		(layer "In11.Cu")
		(net "P5E_CPU0_G3_RX_DN<5>")
	)
	(segment
		(start 371.786912 -223.078802)
		(end 371.750336 -223.100138)
		(width 0.1143)
		(layer "In11.Cu")
		(net "P5E_CPU0_G3_RX_DN<5>")
	)
	(segment
		(start 370.696998 -247.724168)
		(end 370.994686 -247.724168)
		(width 0.1143)
		(layer "In11.Cu")
		(net "P5E_CPU0_G3_RX_DN<5>")
	)
	(segment
		(start 369.867942 -241.5667)
		(end 369.868958 -241.567208)
		(width 0.1143)
		(layer "In11.Cu")
		(net "P5E_CPU0_G3_RX_DN<5>")
	)
	(segment
		(start 320.22542 -167.938704)
		(end 320.29527 -167.976042)
		(width 0.14224)
		(layer "In11.Cu")
		(net "P5E_CPU0_G3_RX_DN<5>")
	)
	(segment
		(start 369.870482 -231.848152)
		(end 369.907058 -231.869488)
		(width 0.1143)
		(layer "In11.Cu")
		(net "P5E_CPU0_G3_RX_DN<5>")
	)
	(segment
		(start 369.86591 -234.442762)
		(end 369.836192 -234.45978)
		(width 0.1143)
		(layer "In11.Cu")
		(net "P5E_CPU0_G3_RX_DN<5>")
	)
	(segment
		(start 369.86591 -239.302798)
		(end 369.836192 -239.319816)
		(width 0.1143)
		(layer "In11.Cu")
		(net "P5E_CPU0_G3_RX_DN<5>")
	)
	(segment
		(start 370.337842 -225.53168)
		(end 370.33708 -225.532188)
		(width 0.1143)
		(layer "In11.Cu")
		(net "P5E_CPU0_G3_RX_DN<5>")
	)
	(segment
		(start 370.778786 -224.738438)
		(end 370.777262 -224.739454)
		(width 0.1143)
		(layer "In11.Cu")
		(net "P5E_CPU0_G3_RX_DN<5>")
	)
	(arc
		(start 369.907058 -236.729524)
		(mid 370.150385 -237.19409)
		(end 369.907058 -237.658656)
		(width 0.1143)
		(layer "In11.Cu")
		(net "P5E_CPU0_G3_RX_DN<5>")
	)
	(arc
		(start 370.376958 -247.259602)
		(mid 370.528945 -247.41611)
		(end 370.610384 -247.618504)
		(width 0.1143)
		(layer "In11.Cu")
		(net "P5E_CPU0_G3_RX_DN<5>")
	)
	(arc
		(start 372.030244 -222.614236)
		(mid 371.965729 -222.876455)
		(end 371.786912 -223.078802)
		(width 0.1143)
		(layer "In11.Cu")
		(net "P5E_CPU0_G3_RX_DN<5>")
	)
	(arc
		(start 369.836192 -239.319816)
		(mid 369.680264 -239.624108)
		(end 369.836192 -239.9284)
		(width 0.1143)
		(layer "In11.Cu")
		(net "P5E_CPU0_G3_RX_DN<5>")
	)
	(arc
		(start 369.907058 -241.58956)
		(mid 370.150385 -242.054126)
		(end 369.907058 -242.518692)
		(width 0.1143)
		(layer "In11.Cu")
		(net "P5E_CPU0_G3_RX_DN<5>")
	)
	(arc
		(start 369.836192 -240.939828)
		(mid 369.680264 -241.24412)
		(end 369.836192 -241.548412)
		(width 0.1143)
		(layer "In11.Cu")
		(net "P5E_CPU0_G3_RX_DN<5>")
	)
	(arc
		(start 370.306092 -225.549968)
		(mid 370.191416 -225.683302)
		(end 370.150136 -225.85426)
		(width 0.1143)
		(layer "In11.Cu")
		(net "P5E_CPU0_G3_RX_DN<5>")
	)
	(arc
		(start 369.834414 -231.22128)
		(mid 369.721007 -231.354169)
		(end 369.680236 -231.524048)
		(width 0.1143)
		(layer "In11.Cu")
		(net "P5E_CPU0_G3_RX_DN<5>")
	)
	(arc
		(start 372.187216 -222.309436)
		(mid 372.071789 -222.442812)
		(end 372.030244 -222.614236)
		(width 0.1143)
		(layer "In11.Cu")
		(net "P5E_CPU0_G3_RX_DN<5>")
	)
	(arc
		(start 369.836192 -245.799864)
		(mid 369.680264 -246.104156)
		(end 369.836192 -246.408448)
		(width 0.1143)
		(layer "In11.Cu")
		(net "P5E_CPU0_G3_RX_DN<5>")
	)
	(arc
		(start 369.836192 -232.839768)
		(mid 369.680264 -233.14406)
		(end 369.836192 -233.448352)
		(width 0.1143)
		(layer "In11.Cu")
		(net "P5E_CPU0_G3_RX_DN<5>")
	)
	(arc
		(start 369.836192 -234.45978)
		(mid 369.680264 -234.764072)
		(end 369.836192 -235.068364)
		(width 0.1143)
		(layer "In11.Cu")
		(net "P5E_CPU0_G3_RX_DN<5>")
	)
	(arc
		(start 369.907058 -235.109512)
		(mid 370.150385 -235.574078)
		(end 369.907058 -236.038644)
		(width 0.1143)
		(layer "In11.Cu")
		(net "P5E_CPU0_G3_RX_DN<5>")
	)
	(arc
		(start 369.680236 -231.524048)
		(mid 369.721491 -231.695019)
		(end 369.836192 -231.82834)
		(width 0.1143)
		(layer "In11.Cu")
		(net "P5E_CPU0_G3_RX_DN<5>")
	)
	(arc
		(start 369.835176 -229.600506)
		(mid 369.721247 -229.733653)
		(end 369.680236 -229.904036)
		(width 0.1143)
		(layer "In11.Cu")
		(net "P5E_CPU0_G3_RX_DN<5>")
	)
	(arc
		(start 369.837208 -227.979478)
		(mid 369.680231 -228.284278)
		(end 369.837208 -228.589078)
		(width 0.1143)
		(layer "In11.Cu")
		(net "P5E_CPU0_G3_RX_DN<5>")
	)
	(arc
		(start 370.15039 -230.714296)
		(mid 370.085875 -230.976515)
		(end 369.907058 -231.178862)
		(width 0.1143)
		(layer "In11.Cu")
		(net "P5E_CPU0_G3_RX_DN<5>")
	)
	(arc
		(start 370.15039 -246.914162)
		(mid 370.191939 -247.085584)
		(end 370.307362 -247.218962)
		(width 0.1143)
		(layer "In11.Cu")
		(net "P5E_CPU0_G3_RX_DN<5>")
	)
	(arc
		(start 369.907058 -239.969548)
		(mid 370.150385 -240.434114)
		(end 369.907058 -240.89868)
		(width 0.1143)
		(layer "In11.Cu")
		(net "P5E_CPU0_G3_RX_DN<5>")
	)
	(arc
		(start 369.906804 -228.629718)
		(mid 370.150131 -229.094284)
		(end 369.906804 -229.55885)
		(width 0.1143)
		(layer "In11.Cu")
		(net "P5E_CPU0_G3_RX_DN<5>")
	)
	(arc
		(start 370.610384 -247.618504)
		(mid 370.612407 -247.629914)
		(end 370.614194 -247.641364)
		(width 0.1143)
		(layer "In11.Cu")
		(net "P5E_CPU0_G3_RX_DN<5>")
	)
	(arc
		(start 370.777262 -224.739454)
		(mid 370.661835 -224.87283)
		(end 370.62029 -225.044254)
		(width 0.1143)
		(layer "In11.Cu")
		(net "P5E_CPU0_G3_RX_DN<5>")
	)
	(arc
		(start 372.49989 -221.80423)
		(mid 372.435516 -222.066434)
		(end 372.256812 -222.268796)
		(width 0.1143)
		(layer "In11.Cu")
		(net "P5E_CPU0_G3_RX_DN<5>")
	)
	(arc
		(start 370.62029 -225.044254)
		(mid 370.555775 -225.306473)
		(end 370.376958 -225.50882)
		(width 0.1143)
		(layer "In11.Cu")
		(net "P5E_CPU0_G3_RX_DN<5>")
	)
	(arc
		(start 369.836192 -236.079792)
		(mid 369.680264 -236.384084)
		(end 369.836192 -236.688376)
		(width 0.1143)
		(layer "In11.Cu")
		(net "P5E_CPU0_G3_RX_DN<5>")
	)
	(arc
		(start 369.836192 -237.699804)
		(mid 369.680264 -238.004096)
		(end 369.836192 -238.308388)
		(width 0.1143)
		(layer "In11.Cu")
		(net "P5E_CPU0_G3_RX_DN<5>")
	)
	(arc
		(start 369.907058 -246.449596)
		(mid 370.085871 -246.651946)
		(end 370.15039 -246.914162)
		(width 0.1143)
		(layer "In11.Cu")
		(net "P5E_CPU0_G3_RX_DN<5>")
	)
	(arc
		(start 369.907058 -233.4895)
		(mid 370.150385 -233.954066)
		(end 369.907058 -234.418632)
		(width 0.1143)
		(layer "In11.Cu")
		(net "P5E_CPU0_G3_RX_DN<5>")
	)
	(arc
		(start 371.56009 -223.424242)
		(mid 371.495575 -223.686461)
		(end 371.316758 -223.888808)
		(width 0.1143)
		(layer "In11.Cu")
		(net "P5E_CPU0_G3_RX_DN<5>")
	)
	(arc
		(start 370.150136 -225.85426)
		(mid 370.085621 -226.116479)
		(end 369.906804 -226.318826)
		(width 0.1143)
		(layer "In11.Cu")
		(net "P5E_CPU0_G3_RX_DN<5>")
	)
	(arc
		(start 369.906804 -227.009706)
		(mid 370.150131 -227.474272)
		(end 369.906804 -227.938838)
		(width 0.1143)
		(layer "In11.Cu")
		(net "P5E_CPU0_G3_RX_DN<5>")
	)
	(arc
		(start 369.836192 -242.55984)
		(mid 369.680264 -242.864132)
		(end 369.836192 -243.168424)
		(width 0.1143)
		(layer "In11.Cu")
		(net "P5E_CPU0_G3_RX_DN<5>")
	)
	(arc
		(start 371.247162 -223.929448)
		(mid 371.131735 -224.062824)
		(end 371.09019 -224.234248)
		(width 0.1143)
		(layer "In11.Cu")
		(net "P5E_CPU0_G3_RX_DN<5>")
	)
	(arc
		(start 369.907058 -243.209572)
		(mid 370.150385 -243.674138)
		(end 369.907058 -244.138704)
		(width 0.1143)
		(layer "In11.Cu")
		(net "P5E_CPU0_G3_RX_DN<5>")
	)
	(arc
		(start 369.904518 -230.247952)
		(mid 370.08517 -230.450697)
		(end 370.15039 -230.714296)
		(width 0.1143)
		(layer "In11.Cu")
		(net "P5E_CPU0_G3_RX_DN<5>")
	)
	(arc
		(start 369.907058 -238.349536)
		(mid 370.150385 -238.814102)
		(end 369.907058 -239.278668)
		(width 0.1143)
		(layer "In11.Cu")
		(net "P5E_CPU0_G3_RX_DN<5>")
	)
	(arc
		(start 369.836192 -244.179852)
		(mid 369.680264 -244.484144)
		(end 369.836192 -244.788436)
		(width 0.1143)
		(layer "In11.Cu")
		(net "P5E_CPU0_G3_RX_DN<5>")
	)
	(arc
		(start 371.09019 -224.234248)
		(mid 371.025675 -224.496467)
		(end 370.846858 -224.698814)
		(width 0.1143)
		(layer "In11.Cu")
		(net "P5E_CPU0_G3_RX_DN<5>")
	)
	(arc
		(start 369.907058 -231.869488)
		(mid 370.150385 -232.334054)
		(end 369.907058 -232.79862)
		(width 0.1143)
		(layer "In11.Cu")
		(net "P5E_CPU0_G3_RX_DN<5>")
	)
	(arc
		(start 371.716046 -223.11995)
		(mid 371.60137 -223.253284)
		(end 371.56009 -223.424242)
		(width 0.1143)
		(layer "In11.Cu")
		(net "P5E_CPU0_G3_RX_DN<5>")
	)
	(arc
		(start 369.837208 -226.359466)
		(mid 369.680231 -226.664266)
		(end 369.837208 -226.969066)
		(width 0.1143)
		(layer "In11.Cu")
		(net "P5E_CPU0_G3_RX_DN<5>")
	)
	(arc
		(start 369.680236 -229.904036)
		(mid 369.721491 -230.075007)
		(end 369.836192 -230.208328)
		(width 0.1143)
		(layer "In11.Cu")
		(net "P5E_CPU0_G3_RX_DN<5>")
	)
	(arc
		(start 369.907058 -244.829584)
		(mid 370.150385 -245.29415)
		(end 369.907058 -245.758716)
		(width 0.1143)
		(layer "In11.Cu")
		(net "P5E_CPU0_G3_RX_DN<5>")
	)
	(segment
		(start 419.556946 -7.709662)
		(end 419.556946 -8.320024)
		(width 0.12954)
		(layer "F.Cu")
		(net "P5E_CPU0_G3_RX_DN<4>")
	)
	(segment
		(start 419.418262 -5.239004)
		(end 419.418262 -7.57047)
		(width 0.12954)
		(layer "F.Cu")
		(net "P5E_CPU0_G3_RX_DN<4>")
	)
	(segment
		(start 419.5572 -7.709408)
		(end 419.556946 -7.709662)
		(width 0.12954)
		(layer "F.Cu")
		(net "P5E_CPU0_G3_RX_DN<4>")
	)
	(segment
		(start 419.418262 -7.57047)
		(end 419.5572 -7.709408)
		(width 0.12954)
		(layer "F.Cu")
		(net "P5E_CPU0_G3_RX_DN<4>")
	)
	(segment
		(start 419.693852 -4.963414)
		(end 419.418262 -5.239004)
		(width 0.12954)
		(layer "F.Cu")
		(net "P5E_CPU0_G3_RX_DN<4>")
	)
	(segment
		(start 370.527834 -244.750082)
		(end 370.994686 -244.484144)
		(width 0.12954)
		(layer "F.Cu")
		(net "P5E_CPU0_G3_RX_DN<4>")
	)
	(segment
		(start 373.485664 -221.202758)
		(end 373.439944 -221.248478)
		(width 0.1143)
		(layer "In11.Cu")
		(net "P5E_CPU0_G3_RX_DN<4>")
	)
	(segment
		(start 373.439944 -221.248478)
		(end 373.439944 -221.80423)
		(width 0.1143)
		(layer "In11.Cu")
		(net "P5E_CPU0_G3_RX_DN<4>")
	)
	(segment
		(start 420.607236 -17.76476)
		(end 420.536624 -17.935702)
		(width 0.14224)
		(layer "In11.Cu")
		(net "P5E_CPU0_G3_RX_DN<4>")
	)
	(segment
		(start 370.776246 -243.168424)
		(end 370.805964 -243.185442)
		(width 0.1143)
		(layer "In11.Cu")
		(net "P5E_CPU0_G3_RX_DN<4>")
	)
	(segment
		(start 372.68785 -223.101662)
		(end 372.6561 -223.11995)
		(width 0.1143)
		(layer "In11.Cu")
		(net "P5E_CPU0_G3_RX_DN<4>")
	)
	(segment
		(start 370.776246 -236.688376)
		(end 370.786152 -236.693964)
		(width 0.1143)
		(layer "In11.Cu")
		(net "P5E_CPU0_G3_RX_DN<4>")
	)
	(segment
		(start 370.818156 -231.195372)
		(end 370.777262 -231.219248)
		(width 0.1143)
		(layer "In11.Cu")
		(net "P5E_CPU0_G3_RX_DN<4>")
	)
	(segment
		(start 370.802662 -228.60381)
		(end 370.803678 -228.604318)
		(width 0.1143)
		(layer "In11.Cu")
		(net "P5E_CPU0_G3_RX_DN<4>")
	)
	(segment
		(start 370.805964 -244.162834)
		(end 370.776246 -244.179852)
		(width 0.1143)
		(layer "In11.Cu")
		(net "P5E_CPU0_G3_RX_DN<4>")
	)
	(segment
		(start 326.50557 -130.002534)
		(end 324.011544 -134.341108)
		(width 0.14224)
		(layer "In11.Cu")
		(net "P5E_CPU0_G3_RX_DN<4>")
	)
	(segment
		(start 371.09019 -225.870262)
		(end 371.09019 -225.870516)
		(width 0.1143)
		(layer "In11.Cu")
		(net "P5E_CPU0_G3_RX_DN<4>")
	)
	(segment
		(start 370.776246 -233.448352)
		(end 370.805964 -233.46537)
		(width 0.1143)
		(layer "In11.Cu")
		(net "P5E_CPU0_G3_RX_DN<4>")
	)
	(segment
		(start 419.10127 -20.192492)
		(end 387.908546 -56.455564)
		(width 0.14224)
		(layer "In11.Cu")
		(net "P5E_CPU0_G3_RX_DN<4>")
	)
	(segment
		(start 330.615036 -174.12462)
		(end 365.32439 -202.561698)
		(width 0.14224)
		(layer "In11.Cu")
		(net "P5E_CPU0_G3_RX_DN<4>")
	)
	(segment
		(start 370.786914 -236.694472)
		(end 370.807996 -236.706664)
		(width 0.1143)
		(layer "In11.Cu")
		(net "P5E_CPU0_G3_RX_DN<4>")
	)
	(segment
		(start 370.807234 -236.062012)
		(end 370.806218 -236.06252)
		(width 0.1143)
		(layer "In11.Cu")
		(net "P5E_CPU0_G3_RX_DN<4>")
	)
	(segment
		(start 370.807234 -233.466132)
		(end 370.807996 -233.46664)
		(width 0.1143)
		(layer "In11.Cu")
		(net "P5E_CPU0_G3_RX_DN<4>")
	)
	(segment
		(start 370.807234 -228.60635)
		(end 370.807996 -228.606858)
		(width 0.1143)
		(layer "In11.Cu")
		(net "P5E_CPU0_G3_RX_DN<4>")
	)
	(segment
		(start 323.825108 -169.004996)
		(end 323.834252 -169.002964)
		(width 0.14224)
		(layer "In11.Cu")
		(net "P5E_CPU0_G3_RX_DN<4>")
	)
	(segment
		(start 370.806218 -240.922556)
		(end 370.805456 -240.923064)
		(width 0.1143)
		(layer "In11.Cu")
		(net "P5E_CPU0_G3_RX_DN<4>")
	)
	(segment
		(start 370.80825 -236.061504)
		(end 370.807996 -236.061504)
		(width 0.1143)
		(layer "In11.Cu")
		(net "P5E_CPU0_G3_RX_DN<4>")
	)
	(segment
		(start 370.8019 -242.545108)
		(end 370.80063 -242.54587)
		(width 0.1143)
		(layer "In11.Cu")
		(net "P5E_CPU0_G3_RX_DN<4>")
	)
	(segment
		(start 370.807996 -239.946688)
		(end 370.80825 -239.946942)
		(width 0.1143)
		(layer "In11.Cu")
		(net "P5E_CPU0_G3_RX_DN<4>")
	)
	(segment
		(start 328.956162 -172.621956)
		(end 330.615036 -174.12462)
		(width 0.14224)
		(layer "In11.Cu")
		(net "P5E_CPU0_G3_RX_DN<4>")
	)
	(segment
		(start 370.80063 -237.685834)
		(end 370.776246 -237.699804)
		(width 0.1143)
		(layer "In11.Cu")
		(net "P5E_CPU0_G3_RX_DN<4>")
	)
	(segment
		(start 370.800376 -228.60254)
		(end 370.8019 -228.603302)
		(width 0.1143)
		(layer "In11.Cu")
		(net "P5E_CPU0_G3_RX_DN<4>")
	)
	(segment
		(start 370.803678 -240.92408)
		(end 370.802662 -240.924588)
		(width 0.1143)
		(layer "In11.Cu")
		(net "P5E_CPU0_G3_RX_DN<4>")
	)
	(segment
		(start 370.807996 -233.46664)
		(end 370.844318 -233.487722)
		(width 0.1143)
		(layer "In11.Cu")
		(net "P5E_CPU0_G3_RX_DN<4>")
	)
	(segment
		(start 370.80444 -236.063536)
		(end 370.803678 -236.064044)
		(width 0.1143)
		(layer "In11.Cu")
		(net "P5E_CPU0_G3_RX_DN<4>")
	)
	(segment
		(start 318.353186 -149.94763)
		(end 316.399164 -161.068766)
		(width 0.14224)
		(layer "In11.Cu")
		(net "P5E_CPU0_G3_RX_DN<4>")
	)
	(segment
		(start 370.776246 -239.9284)
		(end 370.786152 -239.933988)
		(width 0.1143)
		(layer "In11.Cu")
		(net "P5E_CPU0_G3_RX_DN<4>")
	)
	(segment
		(start 370.807234 -227.962206)
		(end 370.805964 -227.962968)
		(width 0.1143)
		(layer "In11.Cu")
		(net "P5E_CPU0_G3_RX_DN<4>")
	)
	(segment
		(start 419.403022 -11.407648)
		(end 420.607236 -17.461992)
		(width 0.14224)
		(layer "In11.Cu")
		(net "P5E_CPU0_G3_RX_DN<4>")
	)
	(segment
		(start 319.967356 -166.529258)
		(end 323.825108 -169.004996)
		(width 0.14224)
		(layer "In11.Cu")
		(net "P5E_CPU0_G3_RX_DN<4>")
	)
	(segment
		(start 370.807234 -231.84612)
		(end 370.807996 -231.846628)
		(width 0.1143)
		(layer "In11.Cu")
		(net "P5E_CPU0_G3_RX_DN<4>")
	)
	(segment
		(start 327.295764 -171.32681)
		(end 328.956162 -172.621956)
		(width 0.14224)
		(layer "In11.Cu")
		(net "P5E_CPU0_G3_RX_DN<4>")
	)
	(segment
		(start 370.77523 -229.60076)
		(end 370.774468 -229.601268)
		(width 0.1143)
		(layer "In11.Cu")
		(net "P5E_CPU0_G3_RX_DN<4>")
	)
	(segment
		(start 370.844318 -229.560628)
		(end 370.841524 -229.562152)
		(width 0.1143)
		(layer "In11.Cu")
		(net "P5E_CPU0_G3_RX_DN<4>")
	)
	(segment
		(start 371.317012 -225.50882)
		(end 371.278912 -225.531172)
		(width 0.1143)
		(layer "In11.Cu")
		(net "P5E_CPU0_G3_RX_DN<4>")
	)
	(segment
		(start 370.806218 -242.542568)
		(end 370.805456 -242.543076)
		(width 0.1143)
		(layer "In11.Cu")
		(net "P5E_CPU0_G3_RX_DN<4>")
	)
	(segment
		(start 370.80825 -237.681516)
		(end 370.807996 -237.681516)
		(width 0.1143)
		(layer "In11.Cu")
		(net "P5E_CPU0_G3_RX_DN<4>")
	)
	(segment
		(start 370.8019 -240.925096)
		(end 370.80063 -240.925858)
		(width 0.1143)
		(layer "In11.Cu")
		(net "P5E_CPU0_G3_RX_DN<4>")
	)
	(segment
		(start 316.399418 -161.385504)
		(end 317.560198 -164.157914)
		(width 0.14224)
		(layer "In11.Cu")
		(net "P5E_CPU0_G3_RX_DN<4>")
	)
	(segment
		(start 370.844318 -232.800398)
		(end 370.807996 -232.82148)
		(width 0.1143)
		(layer "In11.Cu")
		(net "P5E_CPU0_G3_RX_DN<4>")
	)
	(segment
		(start 370.805964 -243.185442)
		(end 370.807234 -243.186204)
		(width 0.1143)
		(layer "In11.Cu")
		(net "P5E_CPU0_G3_RX_DN<4>")
	)
	(segment
		(start 371.277896 -225.53168)
		(end 371.274594 -225.533458)
		(width 0.1143)
		(layer "In11.Cu")
		(net "P5E_CPU0_G3_RX_DN<4>")
	)
	(segment
		(start 371.71884 -224.738438)
		(end 371.717316 -224.739454)
		(width 0.1143)
		(layer "In11.Cu")
		(net "P5E_CPU0_G3_RX_DN<4>")
	)
	(segment
		(start 372.724172 -223.08058)
		(end 372.68785 -223.101662)
		(width 0.1143)
		(layer "In11.Cu")
		(net "P5E_CPU0_G3_RX_DN<4>")
	)
	(segment
		(start 372.256812 -223.888808)
		(end 372.217696 -223.911668)
		(width 0.1143)
		(layer "In11.Cu")
		(net "P5E_CPU0_G3_RX_DN<4>")
	)
	(segment
		(start 370.80444 -242.543584)
		(end 370.803678 -242.544092)
		(width 0.1143)
		(layer "In11.Cu")
		(net "P5E_CPU0_G3_RX_DN<4>")
	)
	(segment
		(start 316.399164 -161.068766)
		(end 316.399164 -161.374074)
		(width 0.14224)
		(layer "In11.Cu")
		(net "P5E_CPU0_G3_RX_DN<4>")
	)
	(segment
		(start 370.807996 -238.326676)
		(end 370.80825 -238.32693)
		(width 0.1143)
		(layer "In11.Cu")
		(net "P5E_CPU0_G3_RX_DN<4>")
	)
	(segment
		(start 370.786152 -239.933988)
		(end 370.786914 -239.934496)
		(width 0.1143)
		(layer "In11.Cu")
		(net "P5E_CPU0_G3_RX_DN<4>")
	)
	(segment
		(start 370.807234 -243.186204)
		(end 370.807996 -243.186712)
		(width 0.1143)
		(layer "In11.Cu")
		(net "P5E_CPU0_G3_RX_DN<4>")
	)
	(segment
		(start 365.32439 -202.561698)
		(end 371.991128 -213.788498)
		(width 0.14224)
		(layer "In11.Cu")
		(net "P5E_CPU0_G3_RX_DN<4>")
	)
	(segment
		(start 370.809012 -230.227124)
		(end 370.810536 -230.22814)
		(width 0.1143)
		(layer "In11.Cu")
		(net "P5E_CPU0_G3_RX_DN<4>")
	)
	(segment
		(start 370.807996 -244.161564)
		(end 370.807234 -244.162072)
		(width 0.1143)
		(layer "In11.Cu")
		(net "P5E_CPU0_G3_RX_DN<4>")
	)
	(segment
		(start 370.807996 -229.58171)
		(end 370.77523 -229.60076)
		(width 0.1143)
		(layer "In11.Cu")
		(net "P5E_CPU0_G3_RX_DN<4>")
	)
	(segment
		(start 371.278912 -225.531172)
		(end 371.277896 -225.53168)
		(width 0.1143)
		(layer "In11.Cu")
		(net "P5E_CPU0_G3_RX_DN<4>")
	)
	(segment
		(start 370.807234 -239.302036)
		(end 370.806218 -239.302544)
		(width 0.1143)
		(layer "In11.Cu")
		(net "P5E_CPU0_G3_RX_DN<4>")
	)
	(segment
		(start 370.786152 -238.313976)
		(end 370.786914 -238.314484)
		(width 0.1143)
		(layer "In11.Cu")
		(net "P5E_CPU0_G3_RX_DN<4>")
	)
	(segment
		(start 370.777262 -231.219248)
		(end 370.774468 -231.22128)
		(width 0.1143)
		(layer "In11.Cu")
		(net "P5E_CPU0_G3_RX_DN<4>")
	)
	(segment
		(start 316.399164 -161.374074)
		(end 316.399418 -161.374582)
		(width 0.14224)
		(layer "In11.Cu")
		(net "P5E_CPU0_G3_RX_DN<4>")
	)
	(segment
		(start 373.485664 -221.17431)
		(end 373.485664 -221.202758)
		(width 0.1143)
		(layer "In11.Cu")
		(net "P5E_CPU0_G3_RX_DN<4>")
	)
	(segment
		(start 370.807996 -237.681516)
		(end 370.807234 -237.682024)
		(width 0.1143)
		(layer "In11.Cu")
		(net "P5E_CPU0_G3_RX_DN<4>")
	)
	(segment
		(start 370.786152 -241.554)
		(end 370.786914 -241.554508)
		(width 0.1143)
		(layer "In11.Cu")
		(net "P5E_CPU0_G3_RX_DN<4>")
	)
	(segment
		(start 370.844318 -234.42041)
		(end 370.807996 -234.441492)
		(width 0.1143)
		(layer "In11.Cu")
		(net "P5E_CPU0_G3_RX_DN<4>")
	)
	(segment
		(start 370.804186 -230.22433)
		(end 370.807996 -230.226616)
		(width 0.1143)
		(layer "In11.Cu")
		(net "P5E_CPU0_G3_RX_DN<4>")
	)
	(segment
		(start 370.807996 -226.986846)
		(end 370.844318 -227.007928)
		(width 0.1143)
		(layer "In11.Cu")
		(net "P5E_CPU0_G3_RX_DN<4>")
	)
	(segment
		(start 370.80444 -237.683548)
		(end 370.803678 -237.684056)
		(width 0.1143)
		(layer "In11.Cu")
		(net "P5E_CPU0_G3_RX_DN<4>")
	)
	(segment
		(start 419.403022 -5.254244)
		(end 419.403022 -11.407648)
		(width 0.14224)
		(layer "In11.Cu")
		(net "P5E_CPU0_G3_RX_DN<4>")
	)
	(segment
		(start 370.80063 -239.305846)
		(end 370.776246 -239.319816)
		(width 0.1143)
		(layer "In11.Cu")
		(net "P5E_CPU0_G3_RX_DN<4>")
	)
	(segment
		(start 387.908546 -56.455564)
		(end 326.50557 -130.002534)
		(width 0.14224)
		(layer "In11.Cu")
		(net "P5E_CPU0_G3_RX_DN<4>")
	)
	(segment
		(start 370.807996 -230.226616)
		(end 370.809012 -230.227124)
		(width 0.1143)
		(layer "In11.Cu")
		(net "P5E_CPU0_G3_RX_DN<4>")
	)
	(segment
		(start 370.807996 -227.961698)
		(end 370.807234 -227.962206)
		(width 0.1143)
		(layer "In11.Cu")
		(net "P5E_CPU0_G3_RX_DN<4>")
	)
	(segment
		(start 370.8019 -228.603302)
		(end 370.802662 -228.60381)
		(width 0.1143)
		(layer "In11.Cu")
		(net "P5E_CPU0_G3_RX_DN<4>")
	)
	(segment
		(start 370.807996 -236.061504)
		(end 370.807234 -236.062012)
		(width 0.1143)
		(layer "In11.Cu")
		(net "P5E_CPU0_G3_RX_DN<4>")
	)
	(segment
		(start 370.807996 -236.706664)
		(end 370.80825 -236.706918)
		(width 0.1143)
		(layer "In11.Cu")
		(net "P5E_CPU0_G3_RX_DN<4>")
	)
	(segment
		(start 370.803678 -228.604318)
		(end 370.80444 -228.604826)
		(width 0.1143)
		(layer "In11.Cu")
		(net "P5E_CPU0_G3_RX_DN<4>")
	)
	(segment
		(start 371.786912 -224.698814)
		(end 371.747796 -224.721674)
		(width 0.1143)
		(layer "In11.Cu")
		(net "P5E_CPU0_G3_RX_DN<4>")
	)
	(segment
		(start 370.810536 -230.22814)
		(end 370.811552 -230.228648)
		(width 0.1143)
		(layer "In11.Cu")
		(net "P5E_CPU0_G3_RX_DN<4>")
	)
	(segment
		(start 316.399418 -161.374582)
		(end 316.399418 -161.385504)
		(width 0.14224)
		(layer "In11.Cu")
		(net "P5E_CPU0_G3_RX_DN<4>")
	)
	(segment
		(start 371.25402 -225.545396)
		(end 371.251734 -225.54692)
		(width 0.1143)
		(layer "In11.Cu")
		(net "P5E_CPU0_G3_RX_DN<4>")
	)
	(segment
		(start 370.80063 -242.54587)
		(end 370.776246 -242.55984)
		(width 0.1143)
		(layer "In11.Cu")
		(net "P5E_CPU0_G3_RX_DN<4>")
	)
	(segment
		(start 370.807996 -232.82148)
		(end 370.776246 -232.839768)
		(width 0.1143)
		(layer "In11.Cu")
		(net "P5E_CPU0_G3_RX_DN<4>")
	)
	(segment
		(start 370.786152 -236.693964)
		(end 370.786914 -236.694472)
		(width 0.1143)
		(layer "In11.Cu")
		(net "P5E_CPU0_G3_RX_DN<4>")
	)
	(segment
		(start 370.80444 -239.30356)
		(end 370.803678 -239.304068)
		(width 0.1143)
		(layer "In11.Cu")
		(net "P5E_CPU0_G3_RX_DN<4>")
	)
	(segment
		(start 370.842794 -226.32162)
		(end 370.776246 -226.359974)
		(width 0.1143)
		(layer "In11.Cu")
		(net "P5E_CPU0_G3_RX_DN<4>")
	)
	(segment
		(start 370.807996 -242.541552)
		(end 370.807234 -242.54206)
		(width 0.1143)
		(layer "In11.Cu")
		(net "P5E_CPU0_G3_RX_DN<4>")
	)
	(segment
		(start 370.807996 -240.92154)
		(end 370.807234 -240.922048)
		(width 0.1143)
		(layer "In11.Cu")
		(net "P5E_CPU0_G3_RX_DN<4>")
	)
	(segment
		(start 371.991128 -213.788498)
		(end 372.013988 -213.826598)
		(width 0.14224)
		(layer "In11.Cu")
		(net "P5E_CPU0_G3_RX_DN<4>")
	)
	(segment
		(start 370.786914 -241.554508)
		(end 370.807996 -241.5667)
		(width 0.1143)
		(layer "In11.Cu")
		(net "P5E_CPU0_G3_RX_DN<4>")
	)
	(segment
		(start 370.80825 -240.92154)
		(end 370.807996 -240.92154)
		(width 0.1143)
		(layer "In11.Cu")
		(net "P5E_CPU0_G3_RX_DN<4>")
	)
	(segment
		(start 370.805456 -237.68304)
		(end 370.80444 -237.683548)
		(width 0.1143)
		(layer "In11.Cu")
		(net "P5E_CPU0_G3_RX_DN<4>")
	)
	(segment
		(start 324.011544 -134.341108)
		(end 318.353186 -149.94763)
		(width 0.14224)
		(layer "In11.Cu")
		(net "P5E_CPU0_G3_RX_DN<4>")
	)
	(segment
		(start 370.806218 -236.06252)
		(end 370.805456 -236.063028)
		(width 0.1143)
		(layer "In11.Cu")
		(net "P5E_CPU0_G3_RX_DN<4>")
	)
	(segment
		(start 371.274594 -225.533458)
		(end 371.25402 -225.545396)
		(width 0.1143)
		(layer "In11.Cu")
		(net "P5E_CPU0_G3_RX_DN<4>")
	)
	(segment
		(start 370.802662 -239.304576)
		(end 370.8019 -239.305084)
		(width 0.1143)
		(layer "In11.Cu")
		(net "P5E_CPU0_G3_RX_DN<4>")
	)
	(segment
		(start 370.807234 -244.162072)
		(end 370.805964 -244.162834)
		(width 0.1143)
		(layer "In11.Cu")
		(net "P5E_CPU0_G3_RX_DN<4>")
	)
	(segment
		(start 370.776246 -226.968558)
		(end 370.807996 -226.986846)
		(width 0.1143)
		(layer "In11.Cu")
		(net "P5E_CPU0_G3_RX_DN<4>")
	)
	(segment
		(start 370.806218 -237.682532)
		(end 370.805456 -237.68304)
		(width 0.1143)
		(layer "In11.Cu")
		(net "P5E_CPU0_G3_RX_DN<4>")
	)
	(segment
		(start 373.485664 -220.358208)
		(end 373.485664 -221.17431)
		(width 0.14224)
		(layer "In11.Cu")
		(net "P5E_CPU0_G3_RX_DN<4>")
	)
	(segment
		(start 370.803678 -242.544092)
		(end 370.802662 -242.5446)
		(width 0.1143)
		(layer "In11.Cu")
		(net "P5E_CPU0_G3_RX_DN<4>")
	)
	(segment
		(start 370.786152 -235.073952)
		(end 370.786914 -235.07446)
		(width 0.1143)
		(layer "In11.Cu")
		(net "P5E_CPU0_G3_RX_DN<4>")
	)
	(segment
		(start 370.807234 -240.922048)
		(end 370.806218 -240.922556)
		(width 0.1143)
		(layer "In11.Cu")
		(net "P5E_CPU0_G3_RX_DN<4>")
	)
	(segment
		(start 371.747796 -224.721674)
		(end 371.71884 -224.738438)
		(width 0.1143)
		(layer "In11.Cu")
		(net "P5E_CPU0_G3_RX_DN<4>")
	)
	(segment
		(start 370.844318 -226.320604)
		(end 370.842794 -226.32162)
		(width 0.1143)
		(layer "In11.Cu")
		(net "P5E_CPU0_G3_RX_DN<4>")
	)
	(segment
		(start 370.807996 -234.441492)
		(end 370.776246 -234.45978)
		(width 0.1143)
		(layer "In11.Cu")
		(net "P5E_CPU0_G3_RX_DN<4>")
	)
	(segment
		(start 323.834252 -169.002964)
		(end 327.295764 -171.32681)
		(width 0.14224)
		(layer "In11.Cu")
		(net "P5E_CPU0_G3_RX_DN<4>")
	)
	(segment
		(start 370.776246 -241.548412)
		(end 370.786152 -241.554)
		(width 0.1143)
		(layer "In11.Cu")
		(net "P5E_CPU0_G3_RX_DN<4>")
	)
	(segment
		(start 372.013988 -213.826598)
		(end 373.485664 -220.358208)
		(width 0.14224)
		(layer "In11.Cu")
		(net "P5E_CPU0_G3_RX_DN<4>")
	)
	(segment
		(start 373.196866 -222.268796)
		(end 373.126 -222.309944)
		(width 0.1143)
		(layer "In11.Cu")
		(net "P5E_CPU0_G3_RX_DN<4>")
	)
	(segment
		(start 370.776246 -231.82834)
		(end 370.805964 -231.845358)
		(width 0.1143)
		(layer "In11.Cu")
		(net "P5E_CPU0_G3_RX_DN<4>")
	)
	(segment
		(start 370.805456 -236.063028)
		(end 370.80444 -236.063536)
		(width 0.1143)
		(layer "In11.Cu")
		(net "P5E_CPU0_G3_RX_DN<4>")
	)
	(segment
		(start 370.627148 -244.414294)
		(end 370.696998 -244.484144)
		(width 0.1143)
		(layer "In11.Cu")
		(net "P5E_CPU0_G3_RX_DN<4>")
	)
	(segment
		(start 370.786914 -238.314484)
		(end 370.807996 -238.326676)
		(width 0.1143)
		(layer "In11.Cu")
		(net "P5E_CPU0_G3_RX_DN<4>")
	)
	(segment
		(start 370.844318 -244.140482)
		(end 370.807996 -244.161564)
		(width 0.1143)
		(layer "In11.Cu")
		(net "P5E_CPU0_G3_RX_DN<4>")
	)
	(segment
		(start 370.802662 -240.924588)
		(end 370.8019 -240.925096)
		(width 0.1143)
		(layer "In11.Cu")
		(net "P5E_CPU0_G3_RX_DN<4>")
	)
	(segment
		(start 370.807996 -231.846628)
		(end 370.844318 -231.86771)
		(width 0.1143)
		(layer "In11.Cu")
		(net "P5E_CPU0_G3_RX_DN<4>")
	)
	(segment
		(start 370.802662 -242.5446)
		(end 370.8019 -242.545108)
		(width 0.1143)
		(layer "In11.Cu")
		(net "P5E_CPU0_G3_RX_DN<4>")
	)
	(segment
		(start 370.80063 -240.925858)
		(end 370.776246 -240.939828)
		(width 0.1143)
		(layer "In11.Cu")
		(net "P5E_CPU0_G3_RX_DN<4>")
	)
	(segment
		(start 370.776246 -228.58857)
		(end 370.800376 -228.60254)
		(width 0.1143)
		(layer "In11.Cu")
		(net "P5E_CPU0_G3_RX_DN<4>")
	)
	(segment
		(start 419.213284 -20.033996)
		(end 419.10127 -20.192492)
		(width 0.14224)
		(layer "In11.Cu")
		(net "P5E_CPU0_G3_RX_DN<4>")
	)
	(segment
		(start 370.807234 -242.54206)
		(end 370.806218 -242.542568)
		(width 0.1143)
		(layer "In11.Cu")
		(net "P5E_CPU0_G3_RX_DN<4>")
	)
	(segment
		(start 372.217696 -223.911668)
		(end 372.187216 -223.929448)
		(width 0.1143)
		(layer "In11.Cu")
		(net "P5E_CPU0_G3_RX_DN<4>")
	)
	(segment
		(start 370.776246 -230.208328)
		(end 370.804186 -230.22433)
		(width 0.1143)
		(layer "In11.Cu")
		(net "P5E_CPU0_G3_RX_DN<4>")
	)
	(segment
		(start 370.80825 -242.541552)
		(end 370.807996 -242.541552)
		(width 0.1143)
		(layer "In11.Cu")
		(net "P5E_CPU0_G3_RX_DN<4>")
	)
	(segment
		(start 370.807996 -243.186712)
		(end 370.844318 -243.207794)
		(width 0.1143)
		(layer "In11.Cu")
		(net "P5E_CPU0_G3_RX_DN<4>")
	)
	(segment
		(start 370.776246 -238.308388)
		(end 370.786152 -238.313976)
		(width 0.1143)
		(layer "In11.Cu")
		(net "P5E_CPU0_G3_RX_DN<4>")
	)
	(segment
		(start 370.811552 -230.228648)
		(end 370.84 -230.245158)
		(width 0.1143)
		(layer "In11.Cu")
		(net "P5E_CPU0_G3_RX_DN<4>")
	)
	(segment
		(start 370.805964 -233.46537)
		(end 370.807234 -233.466132)
		(width 0.1143)
		(layer "In11.Cu")
		(net "P5E_CPU0_G3_RX_DN<4>")
	)
	(segment
		(start 370.807996 -235.086652)
		(end 370.80825 -235.086906)
		(width 0.1143)
		(layer "In11.Cu")
		(net "P5E_CPU0_G3_RX_DN<4>")
	)
	(segment
		(start 370.841524 -229.562152)
		(end 370.807996 -229.58171)
		(width 0.1143)
		(layer "In11.Cu")
		(net "P5E_CPU0_G3_RX_DN<4>")
	)
	(segment
		(start 370.807996 -239.301528)
		(end 370.807234 -239.302036)
		(width 0.1143)
		(layer "In11.Cu")
		(net "P5E_CPU0_G3_RX_DN<4>")
	)
	(segment
		(start 370.802662 -237.684564)
		(end 370.8019 -237.685072)
		(width 0.1143)
		(layer "In11.Cu")
		(net "P5E_CPU0_G3_RX_DN<4>")
	)
	(segment
		(start 370.80825 -239.301528)
		(end 370.807996 -239.301528)
		(width 0.1143)
		(layer "In11.Cu")
		(net "P5E_CPU0_G3_RX_DN<4>")
	)
	(segment
		(start 370.805456 -240.923064)
		(end 370.80444 -240.923572)
		(width 0.1143)
		(layer "In11.Cu")
		(net "P5E_CPU0_G3_RX_DN<4>")
	)
	(segment
		(start 370.844318 -227.940616)
		(end 370.807996 -227.961698)
		(width 0.1143)
		(layer "In11.Cu")
		(net "P5E_CPU0_G3_RX_DN<4>")
	)
	(segment
		(start 370.8019 -237.685072)
		(end 370.80063 -237.685834)
		(width 0.1143)
		(layer "In11.Cu")
		(net "P5E_CPU0_G3_RX_DN<4>")
	)
	(segment
		(start 370.805964 -231.845358)
		(end 370.807234 -231.84612)
		(width 0.1143)
		(layer "In11.Cu")
		(net "P5E_CPU0_G3_RX_DN<4>")
	)
	(segment
		(start 370.696998 -244.484144)
		(end 370.994686 -244.484144)
		(width 0.1143)
		(layer "In11.Cu")
		(net "P5E_CPU0_G3_RX_DN<4>")
	)
	(segment
		(start 370.805456 -239.303052)
		(end 370.80444 -239.30356)
		(width 0.1143)
		(layer "In11.Cu")
		(net "P5E_CPU0_G3_RX_DN<4>")
	)
	(segment
		(start 419.693852 -4.963414)
		(end 419.403022 -5.254244)
		(width 0.14224)
		(layer "In11.Cu")
		(net "P5E_CPU0_G3_RX_DN<4>")
	)
	(segment
		(start 370.786914 -239.934496)
		(end 370.807996 -239.946688)
		(width 0.1143)
		(layer "In11.Cu")
		(net "P5E_CPU0_G3_RX_DN<4>")
	)
	(segment
		(start 370.806218 -239.302544)
		(end 370.805456 -239.303052)
		(width 0.1143)
		(layer "In11.Cu")
		(net "P5E_CPU0_G3_RX_DN<4>")
	)
	(segment
		(start 370.805456 -242.543076)
		(end 370.80444 -242.543584)
		(width 0.1143)
		(layer "In11.Cu")
		(net "P5E_CPU0_G3_RX_DN<4>")
	)
	(segment
		(start 370.807996 -241.5667)
		(end 370.80825 -241.566954)
		(width 0.1143)
		(layer "In11.Cu")
		(net "P5E_CPU0_G3_RX_DN<4>")
	)
	(segment
		(start 370.803678 -239.304068)
		(end 370.802662 -239.304576)
		(width 0.1143)
		(layer "In11.Cu")
		(net "P5E_CPU0_G3_RX_DN<4>")
	)
	(segment
		(start 370.776246 -235.068364)
		(end 370.786152 -235.073952)
		(width 0.1143)
		(layer "In11.Cu")
		(net "P5E_CPU0_G3_RX_DN<4>")
	)
	(segment
		(start 317.560198 -164.157914)
		(end 319.967356 -166.529258)
		(width 0.14224)
		(layer "In11.Cu")
		(net "P5E_CPU0_G3_RX_DN<4>")
	)
	(segment
		(start 420.219378 -18.52803)
		(end 419.213284 -20.033996)
		(width 0.14224)
		(layer "In11.Cu")
		(net "P5E_CPU0_G3_RX_DN<4>")
	)
	(segment
		(start 370.807234 -237.682024)
		(end 370.806218 -237.682532)
		(width 0.1143)
		(layer "In11.Cu")
		(net "P5E_CPU0_G3_RX_DN<4>")
	)
	(segment
		(start 370.8019 -239.305084)
		(end 370.80063 -239.305846)
		(width 0.1143)
		(layer "In11.Cu")
		(net "P5E_CPU0_G3_RX_DN<4>")
	)
	(segment
		(start 371.251734 -225.54692)
		(end 371.250718 -225.547428)
		(width 0.1143)
		(layer "In11.Cu")
		(net "P5E_CPU0_G3_RX_DN<4>")
	)
	(segment
		(start 370.801646 -236.065314)
		(end 370.776246 -236.079792)
		(width 0.1143)
		(layer "In11.Cu")
		(net "P5E_CPU0_G3_RX_DN<4>")
	)
	(segment
		(start 370.803678 -237.684056)
		(end 370.802662 -237.684564)
		(width 0.1143)
		(layer "In11.Cu")
		(net "P5E_CPU0_G3_RX_DN<4>")
	)
	(segment
		(start 420.536624 -17.935702)
		(end 420.219378 -18.52803)
		(width 0.14224)
		(layer "In11.Cu")
		(net "P5E_CPU0_G3_RX_DN<4>")
	)
	(segment
		(start 370.80444 -240.923572)
		(end 370.803678 -240.92408)
		(width 0.1143)
		(layer "In11.Cu")
		(net "P5E_CPU0_G3_RX_DN<4>")
	)
	(segment
		(start 370.803678 -236.064044)
		(end 370.801646 -236.065314)
		(width 0.1143)
		(layer "In11.Cu")
		(net "P5E_CPU0_G3_RX_DN<4>")
	)
	(segment
		(start 370.805964 -227.962968)
		(end 370.776246 -227.979986)
		(width 0.1143)
		(layer "In11.Cu")
		(net "P5E_CPU0_G3_RX_DN<4>")
	)
	(segment
		(start 420.607236 -17.461992)
		(end 420.607236 -17.76476)
		(width 0.14224)
		(layer "In11.Cu")
		(net "P5E_CPU0_G3_RX_DN<4>")
	)
	(segment
		(start 370.84 -230.245158)
		(end 370.841524 -230.246174)
		(width 0.1143)
		(layer "In11.Cu")
		(net "P5E_CPU0_G3_RX_DN<4>")
	)
	(segment
		(start 370.786914 -235.07446)
		(end 370.807996 -235.086652)
		(width 0.1143)
		(layer "In11.Cu")
		(net "P5E_CPU0_G3_RX_DN<4>")
	)
	(segment
		(start 370.80444 -228.604826)
		(end 370.807234 -228.60635)
		(width 0.1143)
		(layer "In11.Cu")
		(net "P5E_CPU0_G3_RX_DN<4>")
	)
	(arc
		(start 372.6561 -223.11995)
		(mid 372.541424 -223.253284)
		(end 372.500144 -223.424242)
		(width 0.1143)
		(layer "In11.Cu")
		(net "P5E_CPU0_G3_RX_DN<4>")
	)
	(arc
		(start 372.187216 -223.929448)
		(mid 372.071789 -224.062824)
		(end 372.030244 -224.234248)
		(width 0.1143)
		(layer "In11.Cu")
		(net "P5E_CPU0_G3_RX_DN<4>")
	)
	(arc
		(start 370.860574 -227.929186)
		(mid 370.852496 -227.934972)
		(end 370.844318 -227.940616)
		(width 0.1143)
		(layer "In11.Cu")
		(net "P5E_CPU0_G3_RX_DN<4>")
	)
	(arc
		(start 370.62029 -229.904036)
		(mid 370.661545 -230.075007)
		(end 370.776246 -230.208328)
		(width 0.1143)
		(layer "In11.Cu")
		(net "P5E_CPU0_G3_RX_DN<4>")
	)
	(arc
		(start 372.740428 -223.06915)
		(mid 372.73235 -223.074936)
		(end 372.724172 -223.08058)
		(width 0.1143)
		(layer "In11.Cu")
		(net "P5E_CPU0_G3_RX_DN<4>")
	)
	(arc
		(start 370.776246 -242.55984)
		(mid 370.620318 -242.864132)
		(end 370.776246 -243.168424)
		(width 0.1143)
		(layer "In11.Cu")
		(net "P5E_CPU0_G3_RX_DN<4>")
	)
	(arc
		(start 370.80825 -236.706918)
		(mid 371.088897 -237.19428)
		(end 370.80825 -237.681516)
		(width 0.1143)
		(layer "In11.Cu")
		(net "P5E_CPU0_G3_RX_DN<4>")
	)
	(arc
		(start 370.860574 -227.019358)
		(mid 371.083458 -227.474272)
		(end 370.860574 -227.929186)
		(width 0.1143)
		(layer "In11.Cu")
		(net "P5E_CPU0_G3_RX_DN<4>")
	)
	(arc
		(start 371.560344 -225.044254)
		(mid 371.495829 -225.306473)
		(end 371.317012 -225.50882)
		(width 0.1143)
		(layer "In11.Cu")
		(net "P5E_CPU0_G3_RX_DN<4>")
	)
	(arc
		(start 370.844318 -233.487722)
		(mid 370.851467 -233.492622)
		(end 370.858542 -233.497628)
		(width 0.1143)
		(layer "In11.Cu")
		(net "P5E_CPU0_G3_RX_DN<4>")
	)
	(arc
		(start 370.62029 -231.524048)
		(mid 370.661545 -231.695019)
		(end 370.776246 -231.82834)
		(width 0.1143)
		(layer "In11.Cu")
		(net "P5E_CPU0_G3_RX_DN<4>")
	)
	(arc
		(start 372.500144 -223.424242)
		(mid 372.435629 -223.686461)
		(end 372.256812 -223.888808)
		(width 0.1143)
		(layer "In11.Cu")
		(net "P5E_CPU0_G3_RX_DN<4>")
	)
	(arc
		(start 370.776246 -226.359974)
		(mid 370.620318 -226.664266)
		(end 370.776246 -226.968558)
		(width 0.1143)
		(layer "In11.Cu")
		(net "P5E_CPU0_G3_RX_DN<4>")
	)
	(arc
		(start 371.717316 -224.739454)
		(mid 371.601889 -224.87283)
		(end 371.560344 -225.044254)
		(width 0.1143)
		(layer "In11.Cu")
		(net "P5E_CPU0_G3_RX_DN<4>")
	)
	(arc
		(start 370.776246 -234.45978)
		(mid 370.620318 -234.764072)
		(end 370.776246 -235.068364)
		(width 0.1143)
		(layer "In11.Cu")
		(net "P5E_CPU0_G3_RX_DN<4>")
	)
	(arc
		(start 371.09019 -225.870516)
		(mid 371.021229 -226.125047)
		(end 370.844318 -226.320604)
		(width 0.1143)
		(layer "In11.Cu")
		(net "P5E_CPU0_G3_RX_DN<4>")
	)
	(arc
		(start 372.970044 -222.62084)
		(mid 372.905172 -222.870582)
		(end 372.740428 -223.06915)
		(width 0.1143)
		(layer "In11.Cu")
		(net "P5E_CPU0_G3_RX_DN<4>")
	)
	(arc
		(start 370.776246 -232.839768)
		(mid 370.620318 -233.14406)
		(end 370.776246 -233.448352)
		(width 0.1143)
		(layer "In11.Cu")
		(net "P5E_CPU0_G3_RX_DN<4>")
	)
	(arc
		(start 372.970044 -222.614236)
		(mid 372.970054 -222.617538)
		(end 372.970044 -222.62084)
		(width 0.1143)
		(layer "In11.Cu")
		(net "P5E_CPU0_G3_RX_DN<4>")
	)
	(arc
		(start 370.80825 -235.086906)
		(mid 371.088897 -235.574268)
		(end 370.80825 -236.061504)
		(width 0.1143)
		(layer "In11.Cu")
		(net "P5E_CPU0_G3_RX_DN<4>")
	)
	(arc
		(start 370.860574 -231.87914)
		(mid 371.083458 -232.334054)
		(end 370.860574 -232.788968)
		(width 0.1143)
		(layer "In11.Cu")
		(net "P5E_CPU0_G3_RX_DN<4>")
	)
	(arc
		(start 370.776246 -236.079792)
		(mid 370.620318 -236.384084)
		(end 370.776246 -236.688376)
		(width 0.1143)
		(layer "In11.Cu")
		(net "P5E_CPU0_G3_RX_DN<4>")
	)
	(arc
		(start 370.776246 -239.319816)
		(mid 370.620318 -239.624108)
		(end 370.776246 -239.9284)
		(width 0.1143)
		(layer "In11.Cu")
		(net "P5E_CPU0_G3_RX_DN<4>")
	)
	(arc
		(start 370.776246 -244.179852)
		(mid 370.679111 -244.282721)
		(end 370.627148 -244.414294)
		(width 0.1143)
		(layer "In11.Cu")
		(net "P5E_CPU0_G3_RX_DN<4>")
	)
	(arc
		(start 370.844318 -231.86771)
		(mid 370.852496 -231.873353)
		(end 370.860574 -231.87914)
		(width 0.1143)
		(layer "In11.Cu")
		(net "P5E_CPU0_G3_RX_DN<4>")
	)
	(arc
		(start 370.774468 -231.22128)
		(mid 370.661061 -231.354169)
		(end 370.62029 -231.524048)
		(width 0.1143)
		(layer "In11.Cu")
		(net "P5E_CPU0_G3_RX_DN<4>")
	)
	(arc
		(start 370.858542 -233.497628)
		(mid 371.085925 -233.954066)
		(end 370.858542 -234.410504)
		(width 0.1143)
		(layer "In11.Cu")
		(net "P5E_CPU0_G3_RX_DN<4>")
	)
	(arc
		(start 370.844318 -243.207794)
		(mid 370.852496 -243.213437)
		(end 370.860574 -243.219224)
		(width 0.1143)
		(layer "In11.Cu")
		(net "P5E_CPU0_G3_RX_DN<4>")
	)
	(arc
		(start 370.844318 -227.007928)
		(mid 370.852496 -227.013571)
		(end 370.860574 -227.019358)
		(width 0.1143)
		(layer "In11.Cu")
		(net "P5E_CPU0_G3_RX_DN<4>")
	)
	(arc
		(start 370.807996 -228.606858)
		(mid 371.014619 -228.812637)
		(end 371.09019 -229.094284)
		(width 0.1143)
		(layer "In11.Cu")
		(net "P5E_CPU0_G3_RX_DN<4>")
	)
	(arc
		(start 370.776246 -240.939828)
		(mid 370.620318 -241.24412)
		(end 370.776246 -241.548412)
		(width 0.1143)
		(layer "In11.Cu")
		(net "P5E_CPU0_G3_RX_DN<4>")
	)
	(arc
		(start 370.80825 -238.32693)
		(mid 371.088897 -238.814292)
		(end 370.80825 -239.301528)
		(width 0.1143)
		(layer "In11.Cu")
		(net "P5E_CPU0_G3_RX_DN<4>")
	)
	(arc
		(start 370.80825 -239.946942)
		(mid 371.088897 -240.434304)
		(end 370.80825 -240.92154)
		(width 0.1143)
		(layer "In11.Cu")
		(net "P5E_CPU0_G3_RX_DN<4>")
	)
	(arc
		(start 370.80825 -241.566954)
		(mid 371.088897 -242.054316)
		(end 370.80825 -242.541552)
		(width 0.1143)
		(layer "In11.Cu")
		(net "P5E_CPU0_G3_RX_DN<4>")
	)
	(arc
		(start 371.094762 -225.826828)
		(mid 371.091577 -225.84845)
		(end 371.09019 -225.870262)
		(width 0.1143)
		(layer "In11.Cu")
		(net "P5E_CPU0_G3_RX_DN<4>")
	)
	(arc
		(start 370.776246 -227.979986)
		(mid 370.620318 -228.284278)
		(end 370.776246 -228.58857)
		(width 0.1143)
		(layer "In11.Cu")
		(net "P5E_CPU0_G3_RX_DN<4>")
	)
	(arc
		(start 370.860574 -244.129052)
		(mid 370.852496 -244.134838)
		(end 370.844318 -244.140482)
		(width 0.1143)
		(layer "In11.Cu")
		(net "P5E_CPU0_G3_RX_DN<4>")
	)
	(arc
		(start 371.09019 -230.710486)
		(mid 371.020175 -230.989949)
		(end 370.818156 -231.195372)
		(width 0.1143)
		(layer "In11.Cu")
		(net "P5E_CPU0_G3_RX_DN<4>")
	)
	(arc
		(start 370.858288 -230.257604)
		(mid 371.026464 -230.457307)
		(end 371.09019 -230.710486)
		(width 0.1143)
		(layer "In11.Cu")
		(net "P5E_CPU0_G3_RX_DN<4>")
	)
	(arc
		(start 371.09019 -229.094284)
		(mid 371.028745 -229.350496)
		(end 370.85778 -229.550976)
		(width 0.1143)
		(layer "In11.Cu")
		(net "P5E_CPU0_G3_RX_DN<4>")
	)
	(arc
		(start 370.841524 -230.246174)
		(mid 370.849957 -230.251814)
		(end 370.858288 -230.257604)
		(width 0.1143)
		(layer "In11.Cu")
		(net "P5E_CPU0_G3_RX_DN<4>")
	)
	(arc
		(start 370.776246 -237.699804)
		(mid 370.620318 -238.004096)
		(end 370.776246 -238.308388)
		(width 0.1143)
		(layer "In11.Cu")
		(net "P5E_CPU0_G3_RX_DN<4>")
	)
	(arc
		(start 370.85778 -229.550976)
		(mid 370.851085 -229.555852)
		(end 370.844318 -229.560628)
		(width 0.1143)
		(layer "In11.Cu")
		(net "P5E_CPU0_G3_RX_DN<4>")
	)
	(arc
		(start 370.774468 -229.601268)
		(mid 370.661061 -229.734157)
		(end 370.62029 -229.904036)
		(width 0.1143)
		(layer "In11.Cu")
		(net "P5E_CPU0_G3_RX_DN<4>")
	)
	(arc
		(start 370.860574 -232.788968)
		(mid 370.852496 -232.794754)
		(end 370.844318 -232.800398)
		(width 0.1143)
		(layer "In11.Cu")
		(net "P5E_CPU0_G3_RX_DN<4>")
	)
	(arc
		(start 371.241574 -225.55454)
		(mid 371.147657 -225.679624)
		(end 371.094762 -225.826828)
		(width 0.1143)
		(layer "In11.Cu")
		(net "P5E_CPU0_G3_RX_DN<4>")
	)
	(arc
		(start 371.250718 -225.547428)
		(mid 371.246118 -225.550949)
		(end 371.241574 -225.55454)
		(width 0.1143)
		(layer "In11.Cu")
		(net "P5E_CPU0_G3_RX_DN<4>")
	)
	(arc
		(start 370.860574 -243.219224)
		(mid 371.083458 -243.674138)
		(end 370.860574 -244.129052)
		(width 0.1143)
		(layer "In11.Cu")
		(net "P5E_CPU0_G3_RX_DN<4>")
	)
	(arc
		(start 370.858542 -234.410504)
		(mid 370.851468 -234.415511)
		(end 370.844318 -234.42041)
		(width 0.1143)
		(layer "In11.Cu")
		(net "P5E_CPU0_G3_RX_DN<4>")
	)
	(arc
		(start 372.030244 -224.234248)
		(mid 371.965729 -224.496467)
		(end 371.786912 -224.698814)
		(width 0.1143)
		(layer "In11.Cu")
		(net "P5E_CPU0_G3_RX_DN<4>")
	)
	(arc
		(start 373.439944 -221.80423)
		(mid 373.375497 -222.066382)
		(end 373.196866 -222.268796)
		(width 0.1143)
		(layer "In11.Cu")
		(net "P5E_CPU0_G3_RX_DN<4>")
	)
	(arc
		(start 373.126 -222.309944)
		(mid 373.014203 -222.444745)
		(end 372.970044 -222.614236)
		(width 0.1143)
		(layer "In11.Cu")
		(net "P5E_CPU0_G3_RX_DN<4>")
	)
	(segment
		(start 425.366942 -8.320024)
		(end 425.366942 -7.709154)
		(width 0.12954)
		(layer "F.Cu")
		(net "P5E_CPU0_G3_RX_DN<3>")
	)
	(segment
		(start 425.228258 -6.996176)
		(end 425.499276 -6.725158)
		(width 0.12954)
		(layer "F.Cu")
		(net "P5E_CPU0_G3_RX_DN<3>")
	)
	(segment
		(start 425.228258 -7.57047)
		(end 425.228258 -6.996176)
		(width 0.12954)
		(layer "F.Cu")
		(net "P5E_CPU0_G3_RX_DN<3>")
	)
	(segment
		(start 425.366942 -7.709154)
		(end 425.228258 -7.57047)
		(width 0.12954)
		(layer "F.Cu")
		(net "P5E_CPU0_G3_RX_DN<3>")
	)
	(segment
		(start 370.527834 -246.370094)
		(end 370.994686 -246.104156)
		(width 0.12954)
		(layer "F.Cu")
		(net "P5E_CPU0_G3_RX_DN<3>")
	)
	(segment
		(start 402.02993 -43.803062)
		(end 402.030184 -43.80611)
		(width 0.14224)
		(layer "In11.Cu")
		(net "P5E_CPU0_G3_RX_DN<3>")
	)
	(segment
		(start 371.786912 -242.518692)
		(end 371.717316 -242.559332)
		(width 0.1143)
		(layer "In11.Cu")
		(net "P5E_CPU0_G3_RX_DN<3>")
	)
	(segment
		(start 371.717316 -228.589078)
		(end 371.786912 -228.629718)
		(width 0.1143)
		(layer "In11.Cu")
		(net "P5E_CPU0_G3_RX_DN<3>")
	)
	(segment
		(start 371.717316 -241.54892)
		(end 371.786912 -241.58956)
		(width 0.1143)
		(layer "In11.Cu")
		(net "P5E_CPU0_G3_RX_DN<3>")
	)
	(segment
		(start 374.425718 -221.202758)
		(end 374.379998 -221.248478)
		(width 0.1143)
		(layer "In11.Cu")
		(net "P5E_CPU0_G3_RX_DN<3>")
	)
	(segment
		(start 373.663972 -223.080834)
		(end 373.62765 -223.101662)
		(width 0.1143)
		(layer "In11.Cu")
		(net "P5E_CPU0_G3_RX_DN<3>")
	)
	(segment
		(start 371.747796 -229.58171)
		(end 371.715284 -229.600506)
		(width 0.1143)
		(layer "In11.Cu")
		(net "P5E_CPU0_G3_RX_DN<3>")
	)
	(segment
		(start 325.194676 -168.690798)
		(end 329.603862 -171.794678)
		(width 0.14224)
		(layer "In11.Cu")
		(net "P5E_CPU0_G3_RX_DN<3>")
	)
	(segment
		(start 371.717316 -231.828848)
		(end 371.786912 -231.869488)
		(width 0.1143)
		(layer "In11.Cu")
		(net "P5E_CPU0_G3_RX_DN<3>")
	)
	(segment
		(start 372.217188 -225.532188)
		(end 372.215918 -225.53295)
		(width 0.1143)
		(layer "In11.Cu")
		(net "P5E_CPU0_G3_RX_DN<3>")
	)
	(segment
		(start 370.627148 -246.034306)
		(end 370.696998 -246.104156)
		(width 0.1143)
		(layer "In11.Cu")
		(net "P5E_CPU0_G3_RX_DN<3>")
	)
	(segment
		(start 333.009494 -174.878238)
		(end 366.213898 -202.071224)
		(width 0.14224)
		(layer "In11.Cu")
		(net "P5E_CPU0_G3_RX_DN<3>")
	)
	(segment
		(start 372.215918 -225.53295)
		(end 372.1862 -225.549968)
		(width 0.1143)
		(layer "In11.Cu")
		(net "P5E_CPU0_G3_RX_DN<3>")
	)
	(segment
		(start 425.208446 -12.409678)
		(end 423.24274 -16.566388)
		(width 0.14224)
		(layer "In11.Cu")
		(net "P5E_CPU0_G3_RX_DN<3>")
	)
	(segment
		(start 317.621158 -161.870898)
		(end 318.320166 -163.558728)
		(width 0.14224)
		(layer "In11.Cu")
		(net "P5E_CPU0_G3_RX_DN<3>")
	)
	(segment
		(start 318.320166 -163.558728)
		(end 319.970658 -165.209728)
		(width 0.14224)
		(layer "In11.Cu")
		(net "P5E_CPU0_G3_RX_DN<3>")
	)
	(segment
		(start 422.727374 -17.815052)
		(end 422.949624 -18.229834)
		(width 0.14224)
		(layer "In11.Cu")
		(net "P5E_CPU0_G3_RX_DN<3>")
	)
	(segment
		(start 372.21795 -225.53168)
		(end 372.217188 -225.532188)
		(width 0.1143)
		(layer "In11.Cu")
		(net "P5E_CPU0_G3_RX_DN<3>")
	)
	(segment
		(start 371.786912 -236.038644)
		(end 371.717316 -236.079284)
		(width 0.1143)
		(layer "In11.Cu")
		(net "P5E_CPU0_G3_RX_DN<3>")
	)
	(segment
		(start 371.786912 -237.658656)
		(end 371.717316 -237.699296)
		(width 0.1143)
		(layer "In11.Cu")
		(net "P5E_CPU0_G3_RX_DN<3>")
	)
	(segment
		(start 373.15775 -223.911668)
		(end 373.126 -223.929956)
		(width 0.1143)
		(layer "In11.Cu")
		(net "P5E_CPU0_G3_RX_DN<3>")
	)
	(segment
		(start 372.970044 -224.233232)
		(end 372.970044 -224.33026)
		(width 0.1143)
		(layer "In11.Cu")
		(net "P5E_CPU0_G3_RX_DN<3>")
	)
	(segment
		(start 327.284842 -130.52425)
		(end 324.855332 -134.75081)
		(width 0.14224)
		(layer "In11.Cu")
		(net "P5E_CPU0_G3_RX_DN<3>")
	)
	(segment
		(start 373.194072 -223.890586)
		(end 373.15775 -223.911668)
		(width 0.1143)
		(layer "In11.Cu")
		(net "P5E_CPU0_G3_RX_DN<3>")
	)
	(segment
		(start 402.030184 -43.80611)
		(end 401.948396 -43.895772)
		(width 0.14224)
		(layer "In11.Cu")
		(net "P5E_CPU0_G3_RX_DN<3>")
	)
	(segment
		(start 374.425718 -220.25737)
		(end 374.425718 -221.17431)
		(width 0.14224)
		(layer "In11.Cu")
		(net "P5E_CPU0_G3_RX_DN<3>")
	)
	(segment
		(start 371.786912 -231.178862)
		(end 371.747796 -231.201722)
		(width 0.1143)
		(layer "In11.Cu")
		(net "P5E_CPU0_G3_RX_DN<3>")
	)
	(segment
		(start 370.696998 -246.104156)
		(end 370.994686 -246.104156)
		(width 0.1143)
		(layer "In11.Cu")
		(net "P5E_CPU0_G3_RX_DN<3>")
	)
	(segment
		(start 371.78488 -229.560374)
		(end 371.747796 -229.58171)
		(width 0.1143)
		(layer "In11.Cu")
		(net "P5E_CPU0_G3_RX_DN<3>")
	)
	(segment
		(start 371.717316 -239.928908)
		(end 371.786912 -239.969548)
		(width 0.1143)
		(layer "In11.Cu")
		(net "P5E_CPU0_G3_RX_DN<3>")
	)
	(segment
		(start 371.786912 -229.55885)
		(end 371.78488 -229.560374)
		(width 0.1143)
		(layer "In11.Cu")
		(net "P5E_CPU0_G3_RX_DN<3>")
	)
	(segment
		(start 371.717316 -233.44886)
		(end 371.786912 -233.4895)
		(width 0.1143)
		(layer "In11.Cu")
		(net "P5E_CPU0_G3_RX_DN<3>")
	)
	(segment
		(start 373.666766 -223.078802)
		(end 373.663972 -223.080834)
		(width 0.1143)
		(layer "In11.Cu")
		(net "P5E_CPU0_G3_RX_DN<3>")
	)
	(segment
		(start 329.603862 -171.794678)
		(end 333.009494 -174.878238)
		(width 0.14224)
		(layer "In11.Cu")
		(net "P5E_CPU0_G3_RX_DN<3>")
	)
	(segment
		(start 371.786912 -234.418632)
		(end 371.717316 -234.459272)
		(width 0.1143)
		(layer "In11.Cu")
		(net "P5E_CPU0_G3_RX_DN<3>")
	)
	(segment
		(start 371.747796 -231.201722)
		(end 371.715284 -231.220518)
		(width 0.1143)
		(layer "In11.Cu")
		(net "P5E_CPU0_G3_RX_DN<3>")
	)
	(segment
		(start 373.62765 -223.101662)
		(end 373.5959 -223.11995)
		(width 0.1143)
		(layer "In11.Cu")
		(net "P5E_CPU0_G3_RX_DN<3>")
	)
	(segment
		(start 371.317012 -244.94871)
		(end 371.26545 -244.978682)
		(width 0.1143)
		(layer "In11.Cu")
		(net "P5E_CPU0_G3_RX_DN<3>")
	)
	(segment
		(start 371.717316 -235.068872)
		(end 371.786912 -235.109512)
		(width 0.1143)
		(layer "In11.Cu")
		(net "P5E_CPU0_G3_RX_DN<3>")
	)
	(segment
		(start 319.304924 -150.059136)
		(end 317.470536 -160.500314)
		(width 0.14224)
		(layer "In11.Cu")
		(net "P5E_CPU0_G3_RX_DN<3>")
	)
	(segment
		(start 401.948396 -43.895772)
		(end 401.947126 -43.897042)
		(width 0.14224)
		(layer "In11.Cu")
		(net "P5E_CPU0_G3_RX_DN<3>")
	)
	(segment
		(start 372.224046 -225.528124)
		(end 372.220998 -225.529902)
		(width 0.1143)
		(layer "In11.Cu")
		(net "P5E_CPU0_G3_RX_DN<3>")
	)
	(segment
		(start 374.13692 -222.268796)
		(end 374.066054 -222.309944)
		(width 0.1143)
		(layer "In11.Cu")
		(net "P5E_CPU0_G3_RX_DN<3>")
	)
	(segment
		(start 372.658894 -224.738438)
		(end 372.65737 -224.739454)
		(width 0.1143)
		(layer "In11.Cu")
		(net "P5E_CPU0_G3_RX_DN<3>")
	)
	(segment
		(start 422.949624 -18.229834)
		(end 423.314368 -18.775426)
		(width 0.14224)
		(layer "In11.Cu")
		(net "P5E_CPU0_G3_RX_DN<3>")
	)
	(segment
		(start 371.077744 -245.303548)
		(end 371.077744 -245.3132)
		(width 0.1143)
		(layer "In11.Cu")
		(net "P5E_CPU0_G3_RX_DN<3>")
	)
	(segment
		(start 374.425718 -221.17431)
		(end 374.425718 -221.202758)
		(width 0.1143)
		(layer "In11.Cu")
		(net "P5E_CPU0_G3_RX_DN<3>")
	)
	(segment
		(start 371.786912 -239.278668)
		(end 371.717316 -239.319308)
		(width 0.1143)
		(layer "In11.Cu")
		(net "P5E_CPU0_G3_RX_DN<3>")
	)
	(segment
		(start 324.855332 -134.75081)
		(end 319.304924 -150.059136)
		(width 0.14224)
		(layer "In11.Cu")
		(net "P5E_CPU0_G3_RX_DN<3>")
	)
	(segment
		(start 317.470536 -160.500314)
		(end 317.621158 -161.870898)
		(width 0.14224)
		(layer "In11.Cu")
		(net "P5E_CPU0_G3_RX_DN<3>")
	)
	(segment
		(start 372.249446 -225.513392)
		(end 372.224808 -225.527616)
		(width 0.1143)
		(layer "In11.Cu")
		(net "P5E_CPU0_G3_RX_DN<3>")
	)
	(segment
		(start 372.970298 -224.231708)
		(end 372.970044 -224.233232)
		(width 0.1143)
		(layer "In11.Cu")
		(net "P5E_CPU0_G3_RX_DN<3>")
	)
	(segment
		(start 423.000678 -20.665694)
		(end 402.02993 -43.803062)
		(width 0.14224)
		(layer "In11.Cu")
		(net "P5E_CPU0_G3_RX_DN<3>")
	)
	(segment
		(start 373.048022 -213.642956)
		(end 374.425718 -220.25737)
		(width 0.14224)
		(layer "In11.Cu")
		(net "P5E_CPU0_G3_RX_DN<3>")
	)
	(segment
		(start 371.786912 -240.89868)
		(end 371.717316 -240.93932)
		(width 0.1143)
		(layer "In11.Cu")
		(net "P5E_CPU0_G3_RX_DN<3>")
	)
	(segment
		(start 371.717316 -226.969066)
		(end 371.786912 -227.009706)
		(width 0.1143)
		(layer "In11.Cu")
		(net "P5E_CPU0_G3_RX_DN<3>")
	)
	(segment
		(start 371.786912 -232.79862)
		(end 371.717316 -232.83926)
		(width 0.1143)
		(layer "In11.Cu")
		(net "P5E_CPU0_G3_RX_DN<3>")
	)
	(segment
		(start 372.224808 -225.527616)
		(end 372.224046 -225.528124)
		(width 0.1143)
		(layer "In11.Cu")
		(net "P5E_CPU0_G3_RX_DN<3>")
	)
	(segment
		(start 366.213898 -202.071224)
		(end 373.048022 -213.642956)
		(width 0.14224)
		(layer "In11.Cu")
		(net "P5E_CPU0_G3_RX_DN<3>")
	)
	(segment
		(start 423.413682 -19.014694)
		(end 423.413682 -19.668236)
		(width 0.14224)
		(layer "In11.Cu")
		(net "P5E_CPU0_G3_RX_DN<3>")
	)
	(segment
		(start 422.683432 -17.403318)
		(end 422.683432 -17.70888)
		(width 0.14224)
		(layer "In11.Cu")
		(net "P5E_CPU0_G3_RX_DN<3>")
	)
	(segment
		(start 423.314368 -18.775426)
		(end 423.413682 -19.014694)
		(width 0.14224)
		(layer "In11.Cu")
		(net "P5E_CPU0_G3_RX_DN<3>")
	)
	(segment
		(start 371.717316 -236.688884)
		(end 371.786912 -236.729524)
		(width 0.1143)
		(layer "In11.Cu")
		(net "P5E_CPU0_G3_RX_DN<3>")
	)
	(segment
		(start 425.499276 -6.725158)
		(end 425.208446 -7.015988)
		(width 0.14224)
		(layer "In11.Cu")
		(net "P5E_CPU0_G3_RX_DN<3>")
	)
	(segment
		(start 422.683432 -17.70888)
		(end 422.727374 -17.815052)
		(width 0.14224)
		(layer "In11.Cu")
		(net "P5E_CPU0_G3_RX_DN<3>")
	)
	(segment
		(start 401.947126 -43.897042)
		(end 374.95099 -73.431146)
		(width 0.14224)
		(layer "In11.Cu")
		(net "P5E_CPU0_G3_RX_DN<3>")
	)
	(segment
		(start 371.786912 -244.138704)
		(end 371.717316 -244.179344)
		(width 0.1143)
		(layer "In11.Cu")
		(net "P5E_CPU0_G3_RX_DN<3>")
	)
	(segment
		(start 374.379998 -221.248478)
		(end 374.379998 -221.80423)
		(width 0.1143)
		(layer "In11.Cu")
		(net "P5E_CPU0_G3_RX_DN<3>")
	)
	(segment
		(start 372.220998 -225.529902)
		(end 372.220236 -225.53041)
		(width 0.1143)
		(layer "In11.Cu")
		(net "P5E_CPU0_G3_RX_DN<3>")
	)
	(segment
		(start 371.786912 -226.318826)
		(end 371.717316 -226.359466)
		(width 0.1143)
		(layer "In11.Cu")
		(net "P5E_CPU0_G3_RX_DN<3>")
	)
	(segment
		(start 371.717316 -230.208836)
		(end 371.784372 -230.247952)
		(width 0.1143)
		(layer "In11.Cu")
		(net "P5E_CPU0_G3_RX_DN<3>")
	)
	(segment
		(start 372.220236 -225.53041)
		(end 372.218966 -225.531172)
		(width 0.1143)
		(layer "In11.Cu")
		(net "P5E_CPU0_G3_RX_DN<3>")
	)
	(segment
		(start 371.717316 -243.168932)
		(end 371.786912 -243.209572)
		(width 0.1143)
		(layer "In11.Cu")
		(net "P5E_CPU0_G3_RX_DN<3>")
	)
	(segment
		(start 374.95099 -73.431146)
		(end 327.284842 -130.52425)
		(width 0.14224)
		(layer "In11.Cu")
		(net "P5E_CPU0_G3_RX_DN<3>")
	)
	(segment
		(start 319.970658 -165.209728)
		(end 325.194676 -168.690798)
		(width 0.14224)
		(layer "In11.Cu")
		(net "P5E_CPU0_G3_RX_DN<3>")
	)
	(segment
		(start 371.786912 -227.938838)
		(end 371.717316 -227.979478)
		(width 0.1143)
		(layer "In11.Cu")
		(net "P5E_CPU0_G3_RX_DN<3>")
	)
	(segment
		(start 372.257066 -225.50882)
		(end 372.250208 -225.512884)
		(width 0.1143)
		(layer "In11.Cu")
		(net "P5E_CPU0_G3_RX_DN<3>")
	)
	(segment
		(start 425.208446 -7.015988)
		(end 425.208446 -12.409678)
		(width 0.14224)
		(layer "In11.Cu")
		(net "P5E_CPU0_G3_RX_DN<3>")
	)
	(segment
		(start 372.218966 -225.531172)
		(end 372.21795 -225.53168)
		(width 0.1143)
		(layer "In11.Cu")
		(net "P5E_CPU0_G3_RX_DN<3>")
	)
	(segment
		(start 423.413682 -19.668236)
		(end 423.000678 -20.665694)
		(width 0.14224)
		(layer "In11.Cu")
		(net "P5E_CPU0_G3_RX_DN<3>")
	)
	(segment
		(start 423.24274 -16.566388)
		(end 422.683432 -17.403318)
		(width 0.14224)
		(layer "In11.Cu")
		(net "P5E_CPU0_G3_RX_DN<3>")
	)
	(segment
		(start 372.812818 -224.637092)
		(end 372.72722 -224.699068)
		(width 0.1143)
		(layer "In11.Cu")
		(net "P5E_CPU0_G3_RX_DN<3>")
	)
	(segment
		(start 370.807996 -245.781576)
		(end 370.776246 -245.799864)
		(width 0.1143)
		(layer "In11.Cu")
		(net "P5E_CPU0_G3_RX_DN<3>")
	)
	(segment
		(start 372.72722 -224.699068)
		(end 372.658894 -224.738438)
		(width 0.1143)
		(layer "In11.Cu")
		(net "P5E_CPU0_G3_RX_DN<3>")
	)
	(segment
		(start 371.717316 -238.308896)
		(end 371.786912 -238.349536)
		(width 0.1143)
		(layer "In11.Cu")
		(net "P5E_CPU0_G3_RX_DN<3>")
	)
	(segment
		(start 372.250208 -225.512884)
		(end 372.249446 -225.513392)
		(width 0.1143)
		(layer "In11.Cu")
		(net "P5E_CPU0_G3_RX_DN<3>")
	)
	(arc
		(start 373.439944 -223.430846)
		(mid 373.375072 -223.680588)
		(end 373.210328 -223.879156)
		(width 0.1143)
		(layer "In11.Cu")
		(net "P5E_CPU0_G3_RX_DN<3>")
	)
	(arc
		(start 371.786912 -241.58956)
		(mid 372.030239 -242.054126)
		(end 371.786912 -242.518692)
		(width 0.1143)
		(layer "In11.Cu")
		(net "P5E_CPU0_G3_RX_DN<3>")
	)
	(arc
		(start 371.784372 -230.247952)
		(mid 371.965024 -230.450697)
		(end 372.030244 -230.714296)
		(width 0.1143)
		(layer "In11.Cu")
		(net "P5E_CPU0_G3_RX_DN<3>")
	)
	(arc
		(start 371.786912 -243.209572)
		(mid 372.030239 -243.674138)
		(end 371.786912 -244.138704)
		(width 0.1143)
		(layer "In11.Cu")
		(net "P5E_CPU0_G3_RX_DN<3>")
	)
	(arc
		(start 371.560344 -229.904036)
		(mid 371.601893 -230.075458)
		(end 371.717316 -230.208836)
		(width 0.1143)
		(layer "In11.Cu")
		(net "P5E_CPU0_G3_RX_DN<3>")
	)
	(arc
		(start 371.717316 -242.559332)
		(mid 371.560339 -242.864132)
		(end 371.717316 -243.168932)
		(width 0.1143)
		(layer "In11.Cu")
		(net "P5E_CPU0_G3_RX_DN<3>")
	)
	(arc
		(start 371.717316 -232.83926)
		(mid 371.560339 -233.14406)
		(end 371.717316 -233.44886)
		(width 0.1143)
		(layer "In11.Cu")
		(net "P5E_CPU0_G3_RX_DN<3>")
	)
	(arc
		(start 371.717316 -227.979478)
		(mid 371.560339 -228.284278)
		(end 371.717316 -228.589078)
		(width 0.1143)
		(layer "In11.Cu")
		(net "P5E_CPU0_G3_RX_DN<3>")
	)
	(arc
		(start 372.030244 -230.714296)
		(mid 371.965729 -230.976515)
		(end 371.786912 -231.178862)
		(width 0.1143)
		(layer "In11.Cu")
		(net "P5E_CPU0_G3_RX_DN<3>")
	)
	(arc
		(start 373.210328 -223.879156)
		(mid 373.20225 -223.884942)
		(end 373.194072 -223.890586)
		(width 0.1143)
		(layer "In11.Cu")
		(net "P5E_CPU0_G3_RX_DN<3>")
	)
	(arc
		(start 371.717316 -239.319308)
		(mid 371.560339 -239.624108)
		(end 371.717316 -239.928908)
		(width 0.1143)
		(layer "In11.Cu")
		(net "P5E_CPU0_G3_RX_DN<3>")
	)
	(arc
		(start 372.970044 -224.33026)
		(mid 372.928445 -224.502639)
		(end 372.812818 -224.637092)
		(width 0.1143)
		(layer "In11.Cu")
		(net "P5E_CPU0_G3_RX_DN<3>")
	)
	(arc
		(start 371.786912 -228.629718)
		(mid 372.030239 -229.094284)
		(end 371.786912 -229.55885)
		(width 0.1143)
		(layer "In11.Cu")
		(net "P5E_CPU0_G3_RX_DN<3>")
	)
	(arc
		(start 372.500398 -225.044254)
		(mid 372.435883 -225.306473)
		(end 372.257066 -225.50882)
		(width 0.1143)
		(layer "In11.Cu")
		(net "P5E_CPU0_G3_RX_DN<3>")
	)
	(arc
		(start 371.717316 -240.93932)
		(mid 371.560339 -241.24412)
		(end 371.717316 -241.54892)
		(width 0.1143)
		(layer "In11.Cu")
		(net "P5E_CPU0_G3_RX_DN<3>")
	)
	(arc
		(start 371.786912 -233.4895)
		(mid 372.030239 -233.954066)
		(end 371.786912 -234.418632)
		(width 0.1143)
		(layer "In11.Cu")
		(net "P5E_CPU0_G3_RX_DN<3>")
	)
	(arc
		(start 373.439944 -223.424242)
		(mid 373.439954 -223.427544)
		(end 373.439944 -223.430846)
		(width 0.1143)
		(layer "In11.Cu")
		(net "P5E_CPU0_G3_RX_DN<3>")
	)
	(arc
		(start 371.786912 -239.969548)
		(mid 372.030239 -240.434114)
		(end 371.786912 -240.89868)
		(width 0.1143)
		(layer "In11.Cu")
		(net "P5E_CPU0_G3_RX_DN<3>")
	)
	(arc
		(start 373.5959 -223.11995)
		(mid 373.484103 -223.254751)
		(end 373.439944 -223.424242)
		(width 0.1143)
		(layer "In11.Cu")
		(net "P5E_CPU0_G3_RX_DN<3>")
	)
	(arc
		(start 371.717316 -236.079284)
		(mid 371.560339 -236.384084)
		(end 371.717316 -236.688884)
		(width 0.1143)
		(layer "In11.Cu")
		(net "P5E_CPU0_G3_RX_DN<3>")
	)
	(arc
		(start 371.786912 -236.729524)
		(mid 372.030239 -237.19409)
		(end 371.786912 -237.658656)
		(width 0.1143)
		(layer "In11.Cu")
		(net "P5E_CPU0_G3_RX_DN<3>")
	)
	(arc
		(start 372.65737 -224.739454)
		(mid 372.541943 -224.87283)
		(end 372.500398 -225.044254)
		(width 0.1143)
		(layer "In11.Cu")
		(net "P5E_CPU0_G3_RX_DN<3>")
	)
	(arc
		(start 372.030244 -225.85426)
		(mid 371.965729 -226.116479)
		(end 371.786912 -226.318826)
		(width 0.1143)
		(layer "In11.Cu")
		(net "P5E_CPU0_G3_RX_DN<3>")
	)
	(arc
		(start 371.560344 -244.484144)
		(mid 371.495829 -244.746363)
		(end 371.317012 -244.94871)
		(width 0.1143)
		(layer "In11.Cu")
		(net "P5E_CPU0_G3_RX_DN<3>")
	)
	(arc
		(start 371.560344 -231.524048)
		(mid 371.601893 -231.69547)
		(end 371.717316 -231.828848)
		(width 0.1143)
		(layer "In11.Cu")
		(net "P5E_CPU0_G3_RX_DN<3>")
	)
	(arc
		(start 371.715284 -229.600506)
		(mid 371.601355 -229.733653)
		(end 371.560344 -229.904036)
		(width 0.1143)
		(layer "In11.Cu")
		(net "P5E_CPU0_G3_RX_DN<3>")
	)
	(arc
		(start 372.1862 -225.549968)
		(mid 372.071524 -225.683302)
		(end 372.030244 -225.85426)
		(width 0.1143)
		(layer "In11.Cu")
		(net "P5E_CPU0_G3_RX_DN<3>")
	)
	(arc
		(start 371.786912 -235.109512)
		(mid 372.030239 -235.574078)
		(end 371.786912 -236.038644)
		(width 0.1143)
		(layer "In11.Cu")
		(net "P5E_CPU0_G3_RX_DN<3>")
	)
	(arc
		(start 373.126 -223.929956)
		(mid 373.014786 -224.063624)
		(end 372.970298 -224.231708)
		(width 0.1143)
		(layer "In11.Cu")
		(net "P5E_CPU0_G3_RX_DN<3>")
	)
	(arc
		(start 374.066054 -222.309944)
		(mid 373.951378 -222.443278)
		(end 373.910098 -222.614236)
		(width 0.1143)
		(layer "In11.Cu")
		(net "P5E_CPU0_G3_RX_DN<3>")
	)
	(arc
		(start 371.717316 -234.459272)
		(mid 371.560339 -234.764072)
		(end 371.717316 -235.068872)
		(width 0.1143)
		(layer "In11.Cu")
		(net "P5E_CPU0_G3_RX_DN<3>")
	)
	(arc
		(start 373.910098 -222.614236)
		(mid 373.845583 -222.876455)
		(end 373.666766 -223.078802)
		(width 0.1143)
		(layer "In11.Cu")
		(net "P5E_CPU0_G3_RX_DN<3>")
	)
	(arc
		(start 371.786912 -231.869488)
		(mid 372.030239 -232.334054)
		(end 371.786912 -232.79862)
		(width 0.1143)
		(layer "In11.Cu")
		(net "P5E_CPU0_G3_RX_DN<3>")
	)
	(arc
		(start 371.786912 -227.009706)
		(mid 372.030239 -227.474272)
		(end 371.786912 -227.938838)
		(width 0.1143)
		(layer "In11.Cu")
		(net "P5E_CPU0_G3_RX_DN<3>")
	)
	(arc
		(start 371.717316 -244.179344)
		(mid 371.601889 -244.31272)
		(end 371.560344 -244.484144)
		(width 0.1143)
		(layer "In11.Cu")
		(net "P5E_CPU0_G3_RX_DN<3>")
	)
	(arc
		(start 371.786912 -238.349536)
		(mid 372.030239 -238.814102)
		(end 371.786912 -239.278668)
		(width 0.1143)
		(layer "In11.Cu")
		(net "P5E_CPU0_G3_RX_DN<3>")
	)
	(arc
		(start 370.776246 -245.799864)
		(mid 370.679111 -245.902733)
		(end 370.627148 -246.034306)
		(width 0.1143)
		(layer "In11.Cu")
		(net "P5E_CPU0_G3_RX_DN<3>")
	)
	(arc
		(start 371.26545 -244.978682)
		(mid 371.128018 -245.115941)
		(end 371.077744 -245.303548)
		(width 0.1143)
		(layer "In11.Cu")
		(net "P5E_CPU0_G3_RX_DN<3>")
	)
	(arc
		(start 371.077744 -245.3132)
		(mid 371.005488 -245.583453)
		(end 370.807996 -245.781576)
		(width 0.1143)
		(layer "In11.Cu")
		(net "P5E_CPU0_G3_RX_DN<3>")
	)
	(arc
		(start 371.715284 -231.220518)
		(mid 371.601355 -231.353665)
		(end 371.560344 -231.524048)
		(width 0.1143)
		(layer "In11.Cu")
		(net "P5E_CPU0_G3_RX_DN<3>")
	)
	(arc
		(start 371.717316 -226.359466)
		(mid 371.560339 -226.664266)
		(end 371.717316 -226.969066)
		(width 0.1143)
		(layer "In11.Cu")
		(net "P5E_CPU0_G3_RX_DN<3>")
	)
	(arc
		(start 371.717316 -237.699296)
		(mid 371.560339 -238.004096)
		(end 371.717316 -238.308896)
		(width 0.1143)
		(layer "In11.Cu")
		(net "P5E_CPU0_G3_RX_DN<3>")
	)
	(arc
		(start 374.379998 -221.80423)
		(mid 374.315551 -222.066382)
		(end 374.13692 -222.268796)
		(width 0.1143)
		(layer "In11.Cu")
		(net "P5E_CPU0_G3_RX_DN<3>")
	)
	(segment
		(start 373.347996 -247.990106)
		(end 373.814848 -247.724168)
		(width 0.12954)
		(layer "F.Cu")
		(net "P5E_CPU0_G3_RX_DN<2>")
	)
	(segment
		(start 427.166786 -7.709662)
		(end 427.166786 -8.320024)
		(width 0.12954)
		(layer "F.Cu")
		(net "P5E_CPU0_G3_RX_DN<2>")
	)
	(segment
		(start 427.028102 -7.57047)
		(end 427.16704 -7.709408)
		(width 0.12954)
		(layer "F.Cu")
		(net "P5E_CPU0_G3_RX_DN<2>")
	)
	(segment
		(start 427.303946 -4.963414)
		(end 427.028102 -5.239258)
		(width 0.12954)
		(layer "F.Cu")
		(net "P5E_CPU0_G3_RX_DN<2>")
	)
	(segment
		(start 427.16704 -7.709408)
		(end 427.166786 -7.709662)
		(width 0.12954)
		(layer "F.Cu")
		(net "P5E_CPU0_G3_RX_DN<2>")
	)
	(segment
		(start 427.028102 -5.239258)
		(end 427.028102 -7.57047)
		(width 0.12954)
		(layer "F.Cu")
		(net "P5E_CPU0_G3_RX_DN<2>")
	)
	(segment
		(start 372.683278 -234.444032)
		(end 372.6561 -234.45978)
		(width 0.1143)
		(layer "In11.Cu")
		(net "P5E_CPU0_G3_RX_DN<2>")
	)
	(segment
		(start 372.687088 -244.806216)
		(end 372.68785 -244.806724)
		(width 0.1143)
		(layer "In11.Cu")
		(net "P5E_CPU0_G3_RX_DN<2>")
	)
	(segment
		(start 372.683532 -228.604318)
		(end 372.684294 -228.604826)
		(width 0.1143)
		(layer "In11.Cu")
		(net "P5E_CPU0_G3_RX_DN<2>")
	)
	(segment
		(start 372.685818 -244.162834)
		(end 372.683278 -244.164104)
		(width 0.1143)
		(layer "In11.Cu")
		(net "P5E_CPU0_G3_RX_DN<2>")
	)
	(segment
		(start 372.6561 -230.208328)
		(end 372.68785 -230.226616)
		(width 0.1143)
		(layer "In11.Cu")
		(net "P5E_CPU0_G3_RX_DN<2>")
	)
	(segment
		(start 372.726966 -236.038644)
		(end 372.69039 -236.05998)
		(width 0.1143)
		(layer "In11.Cu")
		(net "P5E_CPU0_G3_RX_DN<2>")
	)
	(segment
		(start 325.693532 -135.4963)
		(end 325.379334 -136.938766)
		(width 0.14224)
		(layer "In11.Cu")
		(net "P5E_CPU0_G3_RX_DN<2>")
	)
	(segment
		(start 326.208898 -154.577288)
		(end 333.01686 -167.534082)
		(width 0.14224)
		(layer "In11.Cu")
		(net "P5E_CPU0_G3_RX_DN<2>")
	)
	(segment
		(start 374.12803 -213.62035)
		(end 375.365772 -220.006418)
		(width 0.14224)
		(layer "In11.Cu")
		(net "P5E_CPU0_G3_RX_DN<2>")
	)
	(segment
		(start 372.683278 -240.92408)
		(end 372.6561 -240.939828)
		(width 0.1143)
		(layer "In11.Cu")
		(net "P5E_CPU0_G3_RX_DN<2>")
	)
	(segment
		(start 372.6561 -243.168424)
		(end 372.685818 -243.185442)
		(width 0.1143)
		(layer "In11.Cu")
		(net "P5E_CPU0_G3_RX_DN<2>")
	)
	(segment
		(start 372.69039 -236.05998)
		(end 372.688866 -236.060996)
		(width 0.1143)
		(layer "In11.Cu")
		(net "P5E_CPU0_G3_RX_DN<2>")
	)
	(segment
		(start 372.685818 -236.705394)
		(end 372.687088 -236.706156)
		(width 0.1143)
		(layer "In11.Cu")
		(net "P5E_CPU0_G3_RX_DN<2>")
	)
	(segment
		(start 372.719346 -244.825012)
		(end 372.720108 -244.82552)
		(width 0.1143)
		(layer "In11.Cu")
		(net "P5E_CPU0_G3_RX_DN<2>")
	)
	(segment
		(start 372.68785 -235.086652)
		(end 372.719346 -235.10494)
		(width 0.1143)
		(layer "In11.Cu")
		(net "P5E_CPU0_G3_RX_DN<2>")
	)
	(segment
		(start 372.726966 -242.518692)
		(end 372.69039 -242.540028)
		(width 0.1143)
		(layer "In11.Cu")
		(net "P5E_CPU0_G3_RX_DN<2>")
	)
	(segment
		(start 372.6561 -241.548412)
		(end 372.685818 -241.56543)
		(width 0.1143)
		(layer "In11.Cu")
		(net "P5E_CPU0_G3_RX_DN<2>")
	)
	(segment
		(start 372.687088 -232.821988)
		(end 372.685818 -232.82275)
		(width 0.1143)
		(layer "In11.Cu")
		(net "P5E_CPU0_G3_RX_DN<2>")
	)
	(segment
		(start 372.687088 -226.986338)
		(end 372.68785 -226.986846)
		(width 0.1143)
		(layer "In11.Cu")
		(net "P5E_CPU0_G3_RX_DN<2>")
	)
	(segment
		(start 372.720108 -243.205508)
		(end 372.726966 -243.209572)
		(width 0.1143)
		(layer "In11.Cu")
		(net "P5E_CPU0_G3_RX_DN<2>")
	)
	(segment
		(start 372.719346 -246.445024)
		(end 372.720108 -246.445532)
		(width 0.1143)
		(layer "In11.Cu")
		(net "P5E_CPU0_G3_RX_DN<2>")
	)
	(segment
		(start 375.07418 -222.270574)
		(end 375.006108 -222.309944)
		(width 0.1143)
		(layer "In11.Cu")
		(net "P5E_CPU0_G3_RX_DN<2>")
	)
	(segment
		(start 372.719346 -231.864916)
		(end 372.720108 -231.865424)
		(width 0.1143)
		(layer "In11.Cu")
		(net "P5E_CPU0_G3_RX_DN<2>")
	)
	(segment
		(start 372.726966 -226.318826)
		(end 372.696232 -226.33686)
		(width 0.1143)
		(layer "In11.Cu")
		(net "P5E_CPU0_G3_RX_DN<2>")
	)
	(segment
		(start 372.68785 -245.781576)
		(end 372.6561 -245.799864)
		(width 0.1143)
		(layer "In11.Cu")
		(net "P5E_CPU0_G3_RX_DN<2>")
	)
	(segment
		(start 372.685818 -243.185442)
		(end 372.687088 -243.186204)
		(width 0.1143)
		(layer "In11.Cu")
		(net "P5E_CPU0_G3_RX_DN<2>")
	)
	(segment
		(start 373.628158 -224.721674)
		(end 373.625618 -224.722944)
		(width 0.1143)
		(layer "In11.Cu")
		(net "P5E_CPU0_G3_RX_DN<2>")
	)
	(segment
		(start 372.68785 -236.706664)
		(end 372.719346 -236.724952)
		(width 0.1143)
		(layer "In11.Cu")
		(net "P5E_CPU0_G3_RX_DN<2>")
	)
	(segment
		(start 372.726966 -237.658656)
		(end 372.69039 -237.679992)
		(width 0.1143)
		(layer "In11.Cu")
		(net "P5E_CPU0_G3_RX_DN<2>")
	)
	(segment
		(start 375.365772 -221.17431)
		(end 375.365772 -221.202758)
		(width 0.1143)
		(layer "In11.Cu")
		(net "P5E_CPU0_G3_RX_DN<2>")
	)
	(segment
		(start 372.68785 -238.326676)
		(end 372.688866 -238.327184)
		(width 0.1143)
		(layer "In11.Cu")
		(net "P5E_CPU0_G3_RX_DN<2>")
	)
	(segment
		(start 372.69039 -240.920016)
		(end 372.688866 -240.921032)
		(width 0.1143)
		(layer "In11.Cu")
		(net "P5E_CPU0_G3_RX_DN<2>")
	)
	(segment
		(start 372.685818 -239.302798)
		(end 372.683278 -239.304068)
		(width 0.1143)
		(layer "In11.Cu")
		(net "P5E_CPU0_G3_RX_DN<2>")
	)
	(segment
		(start 372.691406 -226.339654)
		(end 372.69039 -226.340162)
		(width 0.1143)
		(layer "In11.Cu")
		(net "P5E_CPU0_G3_RX_DN<2>")
	)
	(segment
		(start 372.685818 -231.845358)
		(end 372.687088 -231.84612)
		(width 0.1143)
		(layer "In11.Cu")
		(net "P5E_CPU0_G3_RX_DN<2>")
	)
	(segment
		(start 372.688866 -237.681008)
		(end 372.68785 -237.681516)
		(width 0.1143)
		(layer "In11.Cu")
		(net "P5E_CPU0_G3_RX_DN<2>")
	)
	(segment
		(start 372.720108 -235.105448)
		(end 372.726966 -235.109512)
		(width 0.1143)
		(layer "In11.Cu")
		(net "P5E_CPU0_G3_RX_DN<2>")
	)
	(segment
		(start 372.719346 -243.205)
		(end 372.720108 -243.205508)
		(width 0.1143)
		(layer "In11.Cu")
		(net "P5E_CPU0_G3_RX_DN<2>")
	)
	(segment
		(start 372.688866 -234.440984)
		(end 372.68785 -234.441492)
		(width 0.1143)
		(layer "In11.Cu")
		(net "P5E_CPU0_G3_RX_DN<2>")
	)
	(segment
		(start 373.625618 -224.722944)
		(end 373.596154 -224.739962)
		(width 0.1143)
		(layer "In11.Cu")
		(net "P5E_CPU0_G3_RX_DN<2>")
	)
	(segment
		(start 372.68785 -246.426736)
		(end 372.719346 -246.445024)
		(width 0.1143)
		(layer "In11.Cu")
		(net "P5E_CPU0_G3_RX_DN<2>")
	)
	(segment
		(start 372.68785 -244.806724)
		(end 372.719346 -244.825012)
		(width 0.1143)
		(layer "In11.Cu")
		(net "P5E_CPU0_G3_RX_DN<2>")
	)
	(segment
		(start 372.687088 -231.84612)
		(end 372.68785 -231.846628)
		(width 0.1143)
		(layer "In11.Cu")
		(net "P5E_CPU0_G3_RX_DN<2>")
	)
	(segment
		(start 372.69039 -226.340162)
		(end 372.688866 -226.341178)
		(width 0.1143)
		(layer "In11.Cu")
		(net "P5E_CPU0_G3_RX_DN<2>")
	)
	(segment
		(start 425.570396 -18.906236)
		(end 424.598846 -20.807934)
		(width 0.14224)
		(layer "In11.Cu")
		(net "P5E_CPU0_G3_RX_DN<2>")
	)
	(segment
		(start 372.693946 -226.33813)
		(end 372.69293 -226.338638)
		(width 0.1143)
		(layer "In11.Cu")
		(net "P5E_CPU0_G3_RX_DN<2>")
	)
	(segment
		(start 372.685818 -236.062774)
		(end 372.683278 -236.064044)
		(width 0.1143)
		(layer "In11.Cu")
		(net "P5E_CPU0_G3_RX_DN<2>")
	)
	(segment
		(start 366.948974 -201.467974)
		(end 374.12803 -213.62035)
		(width 0.14224)
		(layer "In11.Cu")
		(net "P5E_CPU0_G3_RX_DN<2>")
	)
	(segment
		(start 373.434102 -247.641364)
		(end 373.516906 -247.724168)
		(width 0.1143)
		(layer "In11.Cu")
		(net "P5E_CPU0_G3_RX_DN<2>")
	)
	(segment
		(start 372.6561 -244.788436)
		(end 372.685818 -244.805454)
		(width 0.1143)
		(layer "In11.Cu")
		(net "P5E_CPU0_G3_RX_DN<2>")
	)
	(segment
		(start 372.688866 -227.96119)
		(end 372.68785 -227.961698)
		(width 0.1143)
		(layer "In11.Cu")
		(net "P5E_CPU0_G3_RX_DN<2>")
	)
	(segment
		(start 372.69039 -226.98837)
		(end 372.691406 -226.988878)
		(width 0.1143)
		(layer "In11.Cu")
		(net "P5E_CPU0_G3_RX_DN<2>")
	)
	(segment
		(start 325.379334 -136.938766)
		(end 326.208898 -154.577288)
		(width 0.14224)
		(layer "In11.Cu")
		(net "P5E_CPU0_G3_RX_DN<2>")
	)
	(segment
		(start 373.516906 -247.724168)
		(end 373.814848 -247.724168)
		(width 0.1143)
		(layer "In11.Cu")
		(net "P5E_CPU0_G3_RX_DN<2>")
	)
	(segment
		(start 372.687088 -227.962206)
		(end 372.685818 -227.962968)
		(width 0.1143)
		(layer "In11.Cu")
		(net "P5E_CPU0_G3_RX_DN<2>")
	)
	(segment
		(start 372.68785 -228.606858)
		(end 372.688866 -228.607366)
		(width 0.1143)
		(layer "In11.Cu")
		(net "P5E_CPU0_G3_RX_DN<2>")
	)
	(segment
		(start 372.69293 -226.338638)
		(end 372.691406 -226.339654)
		(width 0.1143)
		(layer "In11.Cu")
		(net "P5E_CPU0_G3_RX_DN<2>")
	)
	(segment
		(start 372.6561 -239.9284)
		(end 372.685818 -239.945418)
		(width 0.1143)
		(layer "In11.Cu")
		(net "P5E_CPU0_G3_RX_DN<2>")
	)
	(segment
		(start 372.685818 -227.962968)
		(end 372.683278 -227.964238)
		(width 0.1143)
		(layer "In11.Cu")
		(net "P5E_CPU0_G3_RX_DN<2>")
	)
	(segment
		(start 372.687088 -244.162072)
		(end 372.685818 -244.162834)
		(width 0.1143)
		(layer "In11.Cu")
		(net "P5E_CPU0_G3_RX_DN<2>")
	)
	(segment
		(start 372.6561 -238.308388)
		(end 372.685818 -238.325406)
		(width 0.1143)
		(layer "In11.Cu")
		(net "P5E_CPU0_G3_RX_DN<2>")
	)
	(segment
		(start 372.68785 -226.341686)
		(end 372.687088 -226.342194)
		(width 0.1143)
		(layer "In11.Cu")
		(net "P5E_CPU0_G3_RX_DN<2>")
	)
	(segment
		(start 372.687088 -243.186204)
		(end 372.68785 -243.186712)
		(width 0.1143)
		(layer "In11.Cu")
		(net "P5E_CPU0_G3_RX_DN<2>")
	)
	(segment
		(start 372.688866 -242.541044)
		(end 372.68785 -242.541552)
		(width 0.1143)
		(layer "In11.Cu")
		(net "P5E_CPU0_G3_RX_DN<2>")
	)
	(segment
		(start 372.688866 -226.987354)
		(end 372.69039 -226.98837)
		(width 0.1143)
		(layer "In11.Cu")
		(net "P5E_CPU0_G3_RX_DN<2>")
	)
	(segment
		(start 372.687088 -241.566192)
		(end 372.68785 -241.5667)
		(width 0.1143)
		(layer "In11.Cu")
		(net "P5E_CPU0_G3_RX_DN<2>")
	)
	(segment
		(start 372.720108 -246.445532)
		(end 372.726966 -246.449596)
		(width 0.1143)
		(layer "In11.Cu")
		(net "P5E_CPU0_G3_RX_DN<2>")
	)
	(segment
		(start 372.681246 -228.603048)
		(end 372.682008 -228.603556)
		(width 0.1143)
		(layer "In11.Cu")
		(net "P5E_CPU0_G3_RX_DN<2>")
	)
	(segment
		(start 372.726966 -244.138704)
		(end 372.69039 -244.16004)
		(width 0.1143)
		(layer "In11.Cu")
		(net "P5E_CPU0_G3_RX_DN<2>")
	)
	(segment
		(start 372.68785 -227.961698)
		(end 372.687088 -227.962206)
		(width 0.1143)
		(layer "In11.Cu")
		(net "P5E_CPU0_G3_RX_DN<2>")
	)
	(segment
		(start 372.726966 -232.79862)
		(end 372.69039 -232.819956)
		(width 0.1143)
		(layer "In11.Cu")
		(net "P5E_CPU0_G3_RX_DN<2>")
	)
	(segment
		(start 373.196866 -225.50882)
		(end 373.12727 -225.54946)
		(width 0.1143)
		(layer "In11.Cu")
		(net "P5E_CPU0_G3_RX_DN<2>")
	)
	(segment
		(start 372.69039 -244.16004)
		(end 372.688866 -244.161056)
		(width 0.1143)
		(layer "In11.Cu")
		(net "P5E_CPU0_G3_RX_DN<2>")
	)
	(segment
		(start 426.195236 -17.764252)
		(end 426.195236 -17.76476)
		(width 0.14224)
		(layer "In11.Cu")
		(net "P5E_CPU0_G3_RX_DN<2>")
	)
	(segment
		(start 427.303946 -4.963414)
		(end 427.013116 -5.254244)
		(width 0.14224)
		(layer "In11.Cu")
		(net "P5E_CPU0_G3_RX_DN<2>")
	)
	(segment
		(start 372.685818 -246.425466)
		(end 372.687088 -246.426228)
		(width 0.1143)
		(layer "In11.Cu")
		(net "P5E_CPU0_G3_RX_DN<2>")
	)
	(segment
		(start 372.68785 -233.46664)
		(end 372.719346 -233.484928)
		(width 0.1143)
		(layer "In11.Cu")
		(net "P5E_CPU0_G3_RX_DN<2>")
	)
	(segment
		(start 372.687088 -246.426228)
		(end 372.68785 -246.426736)
		(width 0.1143)
		(layer "In11.Cu")
		(net "P5E_CPU0_G3_RX_DN<2>")
	)
	(segment
		(start 372.683278 -227.964238)
		(end 372.6561 -227.979986)
		(width 0.1143)
		(layer "In11.Cu")
		(net "P5E_CPU0_G3_RX_DN<2>")
	)
	(segment
		(start 372.691406 -226.988878)
		(end 372.726966 -227.009706)
		(width 0.1143)
		(layer "In11.Cu")
		(net "P5E_CPU0_G3_RX_DN<2>")
	)
	(segment
		(start 375.320052 -221.248478)
		(end 375.320052 -221.80423)
		(width 0.1143)
		(layer "In11.Cu")
		(net "P5E_CPU0_G3_RX_DN<2>")
	)
	(segment
		(start 372.720108 -241.585496)
		(end 372.726966 -241.58956)
		(width 0.1143)
		(layer "In11.Cu")
		(net "P5E_CPU0_G3_RX_DN<2>")
	)
	(segment
		(start 372.68785 -241.5667)
		(end 372.719346 -241.584988)
		(width 0.1143)
		(layer "In11.Cu")
		(net "P5E_CPU0_G3_RX_DN<2>")
	)
	(segment
		(start 372.683278 -232.82402)
		(end 372.6561 -232.839768)
		(width 0.1143)
		(layer "In11.Cu")
		(net "P5E_CPU0_G3_RX_DN<2>")
	)
	(segment
		(start 372.720108 -231.865424)
		(end 372.726966 -231.869488)
		(width 0.1143)
		(layer "In11.Cu")
		(net "P5E_CPU0_G3_RX_DN<2>")
	)
	(segment
		(start 372.687088 -234.442)
		(end 372.685818 -234.442762)
		(width 0.1143)
		(layer "In11.Cu")
		(net "P5E_CPU0_G3_RX_DN<2>")
	)
	(segment
		(start 372.720108 -239.965484)
		(end 372.726966 -239.969548)
		(width 0.1143)
		(layer "In11.Cu")
		(net "P5E_CPU0_G3_RX_DN<2>")
	)
	(segment
		(start 372.683278 -244.164104)
		(end 372.6561 -244.179852)
		(width 0.1143)
		(layer "In11.Cu")
		(net "P5E_CPU0_G3_RX_DN<2>")
	)
	(segment
		(start 372.68785 -232.82148)
		(end 372.687088 -232.821988)
		(width 0.1143)
		(layer "In11.Cu")
		(net "P5E_CPU0_G3_RX_DN<2>")
	)
	(segment
		(start 372.6561 -233.448352)
		(end 372.685818 -233.46537)
		(width 0.1143)
		(layer "In11.Cu")
		(net "P5E_CPU0_G3_RX_DN<2>")
	)
	(segment
		(start 372.687088 -226.342194)
		(end 372.6561 -226.359974)
		(width 0.1143)
		(layer "In11.Cu")
		(net "P5E_CPU0_G3_RX_DN<2>")
	)
	(segment
		(start 372.719346 -236.724952)
		(end 372.720108 -236.72546)
		(width 0.1143)
		(layer "In11.Cu")
		(net "P5E_CPU0_G3_RX_DN<2>")
	)
	(segment
		(start 372.683278 -239.304068)
		(end 372.6561 -239.319816)
		(width 0.1143)
		(layer "In11.Cu")
		(net "P5E_CPU0_G3_RX_DN<2>")
	)
	(segment
		(start 375.365772 -220.006418)
		(end 375.365772 -221.17431)
		(width 0.14224)
		(layer "In11.Cu")
		(net "P5E_CPU0_G3_RX_DN<2>")
	)
	(segment
		(start 372.69039 -245.780052)
		(end 372.688866 -245.781068)
		(width 0.1143)
		(layer "In11.Cu")
		(net "P5E_CPU0_G3_RX_DN<2>")
	)
	(segment
		(start 372.68785 -239.946688)
		(end 372.719346 -239.964976)
		(width 0.1143)
		(layer "In11.Cu")
		(net "P5E_CPU0_G3_RX_DN<2>")
	)
	(segment
		(start 333.01686 -167.534082)
		(end 336.32775 -174.977806)
		(width 0.14224)
		(layer "In11.Cu")
		(net "P5E_CPU0_G3_RX_DN<2>")
	)
	(segment
		(start 372.687088 -235.086144)
		(end 372.68785 -235.086652)
		(width 0.1143)
		(layer "In11.Cu")
		(net "P5E_CPU0_G3_RX_DN<2>")
	)
	(segment
		(start 375.075196 -222.270066)
		(end 375.07418 -222.270574)
		(width 0.1143)
		(layer "In11.Cu")
		(net "P5E_CPU0_G3_RX_DN<2>")
	)
	(segment
		(start 372.6561 -231.82834)
		(end 372.685818 -231.845358)
		(width 0.1143)
		(layer "In11.Cu")
		(net "P5E_CPU0_G3_RX_DN<2>")
	)
	(segment
		(start 427.013116 -5.254244)
		(end 427.013116 -13.652246)
		(width 0.14224)
		(layer "In11.Cu")
		(net "P5E_CPU0_G3_RX_DN<2>")
	)
	(segment
		(start 372.726966 -239.278668)
		(end 372.69039 -239.300004)
		(width 0.1143)
		(layer "In11.Cu")
		(net "P5E_CPU0_G3_RX_DN<2>")
	)
	(segment
		(start 372.720108 -236.72546)
		(end 372.726966 -236.729524)
		(width 0.1143)
		(layer "In11.Cu")
		(net "P5E_CPU0_G3_RX_DN<2>")
	)
	(segment
		(start 372.688866 -228.607366)
		(end 372.726966 -228.629718)
		(width 0.1143)
		(layer "In11.Cu")
		(net "P5E_CPU0_G3_RX_DN<2>")
	)
	(segment
		(start 372.726966 -240.89868)
		(end 372.69039 -240.920016)
		(width 0.1143)
		(layer "In11.Cu")
		(net "P5E_CPU0_G3_RX_DN<2>")
	)
	(segment
		(start 372.726966 -229.55885)
		(end 372.654322 -229.601268)
		(width 0.1143)
		(layer "In11.Cu")
		(net "P5E_CPU0_G3_RX_DN<2>")
	)
	(segment
		(start 372.720108 -233.485436)
		(end 372.726966 -233.4895)
		(width 0.1143)
		(layer "In11.Cu")
		(net "P5E_CPU0_G3_RX_DN<2>")
	)
	(segment
		(start 372.685818 -232.82275)
		(end 372.683278 -232.82402)
		(width 0.1143)
		(layer "In11.Cu")
		(net "P5E_CPU0_G3_RX_DN<2>")
	)
	(segment
		(start 336.32775 -174.977806)
		(end 338.47278 -178.14544)
		(width 0.14224)
		(layer "In11.Cu")
		(net "P5E_CPU0_G3_RX_DN<2>")
	)
	(segment
		(start 372.726966 -231.178862)
		(end 372.654322 -231.22128)
		(width 0.1143)
		(layer "In11.Cu")
		(net "P5E_CPU0_G3_RX_DN<2>")
	)
	(segment
		(start 372.688866 -244.161056)
		(end 372.68785 -244.161564)
		(width 0.1143)
		(layer "In11.Cu")
		(net "P5E_CPU0_G3_RX_DN<2>")
	)
	(segment
		(start 372.719346 -233.484928)
		(end 372.720108 -233.485436)
		(width 0.1143)
		(layer "In11.Cu")
		(net "P5E_CPU0_G3_RX_DN<2>")
	)
	(segment
		(start 372.68785 -244.161564)
		(end 372.687088 -244.162072)
		(width 0.1143)
		(layer "In11.Cu")
		(net "P5E_CPU0_G3_RX_DN<2>")
	)
	(segment
		(start 372.68785 -236.061504)
		(end 372.687088 -236.062012)
		(width 0.1143)
		(layer "In11.Cu")
		(net "P5E_CPU0_G3_RX_DN<2>")
	)
	(segment
		(start 374.60682 -223.078802)
		(end 374.567704 -223.101662)
		(width 0.1143)
		(layer "In11.Cu")
		(net "P5E_CPU0_G3_RX_DN<2>")
	)
	(segment
		(start 329.10526 -129.800096)
		(end 325.693532 -135.4963)
		(width 0.14224)
		(layer "In11.Cu")
		(net "P5E_CPU0_G3_RX_DN<2>")
	)
	(segment
		(start 372.68785 -230.226616)
		(end 372.724426 -230.247952)
		(width 0.1143)
		(layer "In11.Cu")
		(net "P5E_CPU0_G3_RX_DN<2>")
	)
	(segment
		(start 372.719346 -235.10494)
		(end 372.720108 -235.105448)
		(width 0.1143)
		(layer "In11.Cu")
		(net "P5E_CPU0_G3_RX_DN<2>")
	)
	(segment
		(start 372.6561 -235.068364)
		(end 372.685818 -235.085382)
		(width 0.1143)
		(layer "In11.Cu")
		(net "P5E_CPU0_G3_RX_DN<2>")
	)
	(segment
		(start 425.88942 -18.375122)
		(end 425.570396 -18.906236)
		(width 0.14224)
		(layer "In11.Cu")
		(net "P5E_CPU0_G3_RX_DN<2>")
	)
	(segment
		(start 372.685818 -241.56543)
		(end 372.687088 -241.566192)
		(width 0.1143)
		(layer "In11.Cu")
		(net "P5E_CPU0_G3_RX_DN<2>")
	)
	(segment
		(start 372.68785 -243.186712)
		(end 372.719346 -243.205)
		(width 0.1143)
		(layer "In11.Cu")
		(net "P5E_CPU0_G3_RX_DN<2>")
	)
	(segment
		(start 372.726966 -227.938838)
		(end 372.688866 -227.96119)
		(width 0.1143)
		(layer "In11.Cu")
		(net "P5E_CPU0_G3_RX_DN<2>")
	)
	(segment
		(start 372.68785 -234.441492)
		(end 372.687088 -234.442)
		(width 0.1143)
		(layer "In11.Cu")
		(net "P5E_CPU0_G3_RX_DN<2>")
	)
	(segment
		(start 375.365772 -221.202758)
		(end 375.320052 -221.248478)
		(width 0.1143)
		(layer "In11.Cu")
		(net "P5E_CPU0_G3_RX_DN<2>")
	)
	(segment
		(start 375.076212 -222.269304)
		(end 375.075196 -222.270066)
		(width 0.1143)
		(layer "In11.Cu")
		(net "P5E_CPU0_G3_RX_DN<2>")
	)
	(segment
		(start 372.687088 -240.922048)
		(end 372.685818 -240.92281)
		(width 0.1143)
		(layer "In11.Cu")
		(net "P5E_CPU0_G3_RX_DN<2>")
	)
	(segment
		(start 372.720108 -244.82552)
		(end 372.726966 -244.829584)
		(width 0.1143)
		(layer "In11.Cu")
		(net "P5E_CPU0_G3_RX_DN<2>")
	)
	(segment
		(start 372.69039 -239.300004)
		(end 372.688866 -239.30102)
		(width 0.1143)
		(layer "In11.Cu")
		(net "P5E_CPU0_G3_RX_DN<2>")
	)
	(segment
		(start 372.688866 -239.30102)
		(end 372.68785 -239.301528)
		(width 0.1143)
		(layer "In11.Cu")
		(net "P5E_CPU0_G3_RX_DN<2>")
	)
	(segment
		(start 372.687088 -228.60635)
		(end 372.68785 -228.606858)
		(width 0.1143)
		(layer "In11.Cu")
		(net "P5E_CPU0_G3_RX_DN<2>")
	)
	(segment
		(start 372.68023 -228.60254)
		(end 372.681246 -228.603048)
		(width 0.1143)
		(layer "In11.Cu")
		(net "P5E_CPU0_G3_RX_DN<2>")
	)
	(segment
		(start 372.69039 -232.819956)
		(end 372.688866 -232.820972)
		(width 0.1143)
		(layer "In11.Cu")
		(net "P5E_CPU0_G3_RX_DN<2>")
	)
	(segment
		(start 372.685818 -234.442762)
		(end 372.683278 -234.444032)
		(width 0.1143)
		(layer "In11.Cu")
		(net "P5E_CPU0_G3_RX_DN<2>")
	)
	(segment
		(start 372.6561 -228.58857)
		(end 372.68023 -228.60254)
		(width 0.1143)
		(layer "In11.Cu")
		(net "P5E_CPU0_G3_RX_DN<2>")
	)
	(segment
		(start 372.6561 -236.688376)
		(end 372.685818 -236.705394)
		(width 0.1143)
		(layer "In11.Cu")
		(net "P5E_CPU0_G3_RX_DN<2>")
	)
	(segment
		(start 372.685818 -244.805454)
		(end 372.687088 -244.806216)
		(width 0.1143)
		(layer "In11.Cu")
		(net "P5E_CPU0_G3_RX_DN<2>")
	)
	(segment
		(start 372.69039 -234.439968)
		(end 372.688866 -234.440984)
		(width 0.1143)
		(layer "In11.Cu")
		(net "P5E_CPU0_G3_RX_DN<2>")
	)
	(segment
		(start 372.726966 -245.758716)
		(end 372.69039 -245.780052)
		(width 0.1143)
		(layer "In11.Cu")
		(net "P5E_CPU0_G3_RX_DN<2>")
	)
	(segment
		(start 372.687088 -238.326168)
		(end 372.68785 -238.326676)
		(width 0.1143)
		(layer "In11.Cu")
		(net "P5E_CPU0_G3_RX_DN<2>")
	)
	(segment
		(start 372.685818 -239.945418)
		(end 372.687088 -239.94618)
		(width 0.1143)
		(layer "In11.Cu")
		(net "P5E_CPU0_G3_RX_DN<2>")
	)
	(segment
		(start 372.719346 -239.964976)
		(end 372.720108 -239.965484)
		(width 0.1143)
		(layer "In11.Cu")
		(net "P5E_CPU0_G3_RX_DN<2>")
	)
	(segment
		(start 372.685818 -238.325406)
		(end 372.687088 -238.326168)
		(width 0.1143)
		(layer "In11.Cu")
		(net "P5E_CPU0_G3_RX_DN<2>")
	)
	(segment
		(start 372.696232 -226.33686)
		(end 372.693946 -226.33813)
		(width 0.1143)
		(layer "In11.Cu")
		(net "P5E_CPU0_G3_RX_DN<2>")
	)
	(segment
		(start 372.688866 -245.781068)
		(end 372.68785 -245.781576)
		(width 0.1143)
		(layer "In11.Cu")
		(net "P5E_CPU0_G3_RX_DN<2>")
	)
	(segment
		(start 372.682008 -228.603556)
		(end 372.683532 -228.604318)
		(width 0.1143)
		(layer "In11.Cu")
		(net "P5E_CPU0_G3_RX_DN<2>")
	)
	(segment
		(start 372.6561 -226.968558)
		(end 372.687088 -226.986338)
		(width 0.1143)
		(layer "In11.Cu")
		(net "P5E_CPU0_G3_RX_DN<2>")
	)
	(segment
		(start 424.598846 -20.807934)
		(end 329.10526 -129.800096)
		(width 0.14224)
		(layer "In11.Cu")
		(net "P5E_CPU0_G3_RX_DN<2>")
	)
	(segment
		(start 374.567704 -223.101662)
		(end 374.537224 -223.119442)
		(width 0.1143)
		(layer "In11.Cu")
		(net "P5E_CPU0_G3_RX_DN<2>")
	)
	(segment
		(start 372.726966 -234.418632)
		(end 372.69039 -234.439968)
		(width 0.1143)
		(layer "In11.Cu")
		(net "P5E_CPU0_G3_RX_DN<2>")
	)
	(segment
		(start 372.688866 -240.921032)
		(end 372.68785 -240.92154)
		(width 0.1143)
		(layer "In11.Cu")
		(net "P5E_CPU0_G3_RX_DN<2>")
	)
	(segment
		(start 372.68785 -237.681516)
		(end 372.6561 -237.699804)
		(width 0.1143)
		(layer "In11.Cu")
		(net "P5E_CPU0_G3_RX_DN<2>")
	)
	(segment
		(start 372.685818 -235.085382)
		(end 372.687088 -235.086144)
		(width 0.1143)
		(layer "In11.Cu")
		(net "P5E_CPU0_G3_RX_DN<2>")
	)
	(segment
		(start 372.69039 -237.679992)
		(end 372.688866 -237.681008)
		(width 0.1143)
		(layer "In11.Cu")
		(net "P5E_CPU0_G3_RX_DN<2>")
	)
	(segment
		(start 372.687088 -236.062012)
		(end 372.685818 -236.062774)
		(width 0.1143)
		(layer "In11.Cu")
		(net "P5E_CPU0_G3_RX_DN<2>")
	)
	(segment
		(start 372.688866 -236.060996)
		(end 372.68785 -236.061504)
		(width 0.1143)
		(layer "In11.Cu")
		(net "P5E_CPU0_G3_RX_DN<2>")
	)
	(segment
		(start 372.68785 -239.301528)
		(end 372.687088 -239.302036)
		(width 0.1143)
		(layer "In11.Cu")
		(net "P5E_CPU0_G3_RX_DN<2>")
	)
	(segment
		(start 372.68785 -226.986846)
		(end 372.688866 -226.987354)
		(width 0.1143)
		(layer "In11.Cu")
		(net "P5E_CPU0_G3_RX_DN<2>")
	)
	(segment
		(start 372.68785 -240.92154)
		(end 372.687088 -240.922048)
		(width 0.1143)
		(layer "In11.Cu")
		(net "P5E_CPU0_G3_RX_DN<2>")
	)
	(segment
		(start 374.07342 -223.926654)
		(end 374.073674 -223.926908)
		(width 0.1143)
		(layer "In11.Cu")
		(net "P5E_CPU0_G3_RX_DN<2>")
	)
	(segment
		(start 372.688866 -238.327184)
		(end 372.726966 -238.349536)
		(width 0.1143)
		(layer "In11.Cu")
		(net "P5E_CPU0_G3_RX_DN<2>")
	)
	(segment
		(start 372.687088 -239.302036)
		(end 372.685818 -239.302798)
		(width 0.1143)
		(layer "In11.Cu")
		(net "P5E_CPU0_G3_RX_DN<2>")
	)
	(segment
		(start 372.687088 -239.94618)
		(end 372.68785 -239.946688)
		(width 0.1143)
		(layer "In11.Cu")
		(net "P5E_CPU0_G3_RX_DN<2>")
	)
	(segment
		(start 372.683278 -236.064044)
		(end 372.6561 -236.079792)
		(width 0.1143)
		(layer "In11.Cu")
		(net "P5E_CPU0_G3_RX_DN<2>")
	)
	(segment
		(start 372.68785 -242.541552)
		(end 372.6561 -242.55984)
		(width 0.1143)
		(layer "In11.Cu")
		(net "P5E_CPU0_G3_RX_DN<2>")
	)
	(segment
		(start 427.013116 -13.652246)
		(end 426.195236 -17.764252)
		(width 0.14224)
		(layer "In11.Cu")
		(net "P5E_CPU0_G3_RX_DN<2>")
	)
	(segment
		(start 372.687088 -233.466132)
		(end 372.68785 -233.46664)
		(width 0.1143)
		(layer "In11.Cu")
		(net "P5E_CPU0_G3_RX_DN<2>")
	)
	(segment
		(start 372.688866 -232.820972)
		(end 372.68785 -232.82148)
		(width 0.1143)
		(layer "In11.Cu")
		(net "P5E_CPU0_G3_RX_DN<2>")
	)
	(segment
		(start 372.684294 -228.604826)
		(end 372.687088 -228.60635)
		(width 0.1143)
		(layer "In11.Cu")
		(net "P5E_CPU0_G3_RX_DN<2>")
	)
	(segment
		(start 372.719346 -241.584988)
		(end 372.720108 -241.585496)
		(width 0.1143)
		(layer "In11.Cu")
		(net "P5E_CPU0_G3_RX_DN<2>")
	)
	(segment
		(start 372.68785 -231.846628)
		(end 372.719346 -231.864916)
		(width 0.1143)
		(layer "In11.Cu")
		(net "P5E_CPU0_G3_RX_DN<2>")
	)
	(segment
		(start 372.688866 -226.341178)
		(end 372.68785 -226.341686)
		(width 0.1143)
		(layer "In11.Cu")
		(net "P5E_CPU0_G3_RX_DN<2>")
	)
	(segment
		(start 338.47278 -178.14544)
		(end 366.948974 -201.467974)
		(width 0.14224)
		(layer "In11.Cu")
		(net "P5E_CPU0_G3_RX_DN<2>")
	)
	(segment
		(start 372.69039 -242.540028)
		(end 372.688866 -242.541044)
		(width 0.1143)
		(layer "In11.Cu")
		(net "P5E_CPU0_G3_RX_DN<2>")
	)
	(segment
		(start 372.685818 -240.92281)
		(end 372.683278 -240.92408)
		(width 0.1143)
		(layer "In11.Cu")
		(net "P5E_CPU0_G3_RX_DN<2>")
	)
	(segment
		(start 426.195236 -17.76476)
		(end 426.124624 -17.935702)
		(width 0.14224)
		(layer "In11.Cu")
		(net "P5E_CPU0_G3_RX_DN<2>")
	)
	(segment
		(start 372.687088 -236.706156)
		(end 372.68785 -236.706664)
		(width 0.1143)
		(layer "In11.Cu")
		(net "P5E_CPU0_G3_RX_DN<2>")
	)
	(segment
		(start 373.12727 -247.218962)
		(end 373.196866 -247.259602)
		(width 0.1143)
		(layer "In11.Cu")
		(net "P5E_CPU0_G3_RX_DN<2>")
	)
	(segment
		(start 426.124624 -17.935702)
		(end 425.88942 -18.375122)
		(width 0.14224)
		(layer "In11.Cu")
		(net "P5E_CPU0_G3_RX_DN<2>")
	)
	(segment
		(start 372.6561 -246.408448)
		(end 372.685818 -246.425466)
		(width 0.1143)
		(layer "In11.Cu")
		(net "P5E_CPU0_G3_RX_DN<2>")
	)
	(segment
		(start 372.685818 -233.46537)
		(end 372.687088 -233.466132)
		(width 0.1143)
		(layer "In11.Cu")
		(net "P5E_CPU0_G3_RX_DN<2>")
	)
	(arc
		(start 375.006108 -222.309944)
		(mid 374.891432 -222.443278)
		(end 374.850152 -222.614236)
		(width 0.1143)
		(layer "In11.Cu")
		(net "P5E_CPU0_G3_RX_DN<2>")
	)
	(arc
		(start 372.500144 -229.904036)
		(mid 372.541399 -230.075007)
		(end 372.6561 -230.208328)
		(width 0.1143)
		(layer "In11.Cu")
		(net "P5E_CPU0_G3_RX_DN<2>")
	)
	(arc
		(start 372.6561 -245.799864)
		(mid 372.500172 -246.104156)
		(end 372.6561 -246.408448)
		(width 0.1143)
		(layer "In11.Cu")
		(net "P5E_CPU0_G3_RX_DN<2>")
	)
	(arc
		(start 372.6561 -234.45978)
		(mid 372.500172 -234.764072)
		(end 372.6561 -235.068364)
		(width 0.1143)
		(layer "In11.Cu")
		(net "P5E_CPU0_G3_RX_DN<2>")
	)
	(arc
		(start 374.34393 -223.53143)
		(mid 374.281829 -223.667508)
		(end 374.204992 -223.795844)
		(width 0.1143)
		(layer "In11.Cu")
		(net "P5E_CPU0_G3_RX_DN<2>")
	)
	(arc
		(start 373.430292 -247.618504)
		(mid 373.432315 -247.629914)
		(end 373.434102 -247.641364)
		(width 0.1143)
		(layer "In11.Cu")
		(net "P5E_CPU0_G3_RX_DN<2>")
	)
	(arc
		(start 372.726966 -236.729524)
		(mid 372.970293 -237.19409)
		(end 372.726966 -237.658656)
		(width 0.1143)
		(layer "In11.Cu")
		(net "P5E_CPU0_G3_RX_DN<2>")
	)
	(arc
		(start 372.6561 -237.699804)
		(mid 372.500172 -238.004096)
		(end 372.6561 -238.308388)
		(width 0.1143)
		(layer "In11.Cu")
		(net "P5E_CPU0_G3_RX_DN<2>")
	)
	(arc
		(start 374.850152 -222.614236)
		(mid 374.785637 -222.876455)
		(end 374.60682 -223.078802)
		(width 0.1143)
		(layer "In11.Cu")
		(net "P5E_CPU0_G3_RX_DN<2>")
	)
	(arc
		(start 373.910098 -224.234248)
		(mid 373.834593 -224.515826)
		(end 373.628158 -224.721674)
		(width 0.1143)
		(layer "In11.Cu")
		(net "P5E_CPU0_G3_RX_DN<2>")
	)
	(arc
		(start 372.970298 -246.914162)
		(mid 373.011847 -247.085584)
		(end 373.12727 -247.218962)
		(width 0.1143)
		(layer "In11.Cu")
		(net "P5E_CPU0_G3_RX_DN<2>")
	)
	(arc
		(start 372.6561 -232.839768)
		(mid 372.500172 -233.14406)
		(end 372.6561 -233.448352)
		(width 0.1143)
		(layer "In11.Cu")
		(net "P5E_CPU0_G3_RX_DN<2>")
	)
	(arc
		(start 372.6561 -242.55984)
		(mid 372.500172 -242.864132)
		(end 372.6561 -243.168424)
		(width 0.1143)
		(layer "In11.Cu")
		(net "P5E_CPU0_G3_RX_DN<2>")
	)
	(arc
		(start 375.320052 -221.80423)
		(mid 375.255393 -222.066787)
		(end 375.076212 -222.269304)
		(width 0.1143)
		(layer "In11.Cu")
		(net "P5E_CPU0_G3_RX_DN<2>")
	)
	(arc
		(start 372.724426 -230.247952)
		(mid 372.905078 -230.450697)
		(end 372.970298 -230.714296)
		(width 0.1143)
		(layer "In11.Cu")
		(net "P5E_CPU0_G3_RX_DN<2>")
	)
	(arc
		(start 372.726966 -238.349536)
		(mid 372.970293 -238.814102)
		(end 372.726966 -239.278668)
		(width 0.1143)
		(layer "In11.Cu")
		(net "P5E_CPU0_G3_RX_DN<2>")
	)
	(arc
		(start 372.654322 -231.22128)
		(mid 372.540915 -231.354169)
		(end 372.500144 -231.524048)
		(width 0.1143)
		(layer "In11.Cu")
		(net "P5E_CPU0_G3_RX_DN<2>")
	)
	(arc
		(start 374.3833 -223.374966)
		(mid 374.368393 -223.4544)
		(end 374.34393 -223.53143)
		(width 0.1143)
		(layer "In11.Cu")
		(net "P5E_CPU0_G3_RX_DN<2>")
	)
	(arc
		(start 372.6561 -236.079792)
		(mid 372.500172 -236.384084)
		(end 372.6561 -236.688376)
		(width 0.1143)
		(layer "In11.Cu")
		(net "P5E_CPU0_G3_RX_DN<2>")
	)
	(arc
		(start 372.6561 -244.179852)
		(mid 372.500172 -244.484144)
		(end 372.6561 -244.788436)
		(width 0.1143)
		(layer "In11.Cu")
		(net "P5E_CPU0_G3_RX_DN<2>")
	)
	(arc
		(start 372.726966 -227.009706)
		(mid 372.970293 -227.474272)
		(end 372.726966 -227.938838)
		(width 0.1143)
		(layer "In11.Cu")
		(net "P5E_CPU0_G3_RX_DN<2>")
	)
	(arc
		(start 373.440198 -225.044254)
		(mid 373.375683 -225.306473)
		(end 373.196866 -225.50882)
		(width 0.1143)
		(layer "In11.Cu")
		(net "P5E_CPU0_G3_RX_DN<2>")
	)
	(arc
		(start 372.726966 -241.58956)
		(mid 372.970293 -242.054126)
		(end 372.726966 -242.518692)
		(width 0.1143)
		(layer "In11.Cu")
		(net "P5E_CPU0_G3_RX_DN<2>")
	)
	(arc
		(start 374.537224 -223.119442)
		(mid 374.43368 -223.2312)
		(end 374.3833 -223.374966)
		(width 0.1143)
		(layer "In11.Cu")
		(net "P5E_CPU0_G3_RX_DN<2>")
	)
	(arc
		(start 372.726966 -233.4895)
		(mid 372.970293 -233.954066)
		(end 372.726966 -234.418632)
		(width 0.1143)
		(layer "In11.Cu")
		(net "P5E_CPU0_G3_RX_DN<2>")
	)
	(arc
		(start 373.196866 -247.259602)
		(mid 373.348853 -247.41611)
		(end 373.430292 -247.618504)
		(width 0.1143)
		(layer "In11.Cu")
		(net "P5E_CPU0_G3_RX_DN<2>")
	)
	(arc
		(start 372.726966 -244.829584)
		(mid 372.970293 -245.29415)
		(end 372.726966 -245.758716)
		(width 0.1143)
		(layer "In11.Cu")
		(net "P5E_CPU0_G3_RX_DN<2>")
	)
	(arc
		(start 372.970298 -230.714296)
		(mid 372.905783 -230.976515)
		(end 372.726966 -231.178862)
		(width 0.1143)
		(layer "In11.Cu")
		(net "P5E_CPU0_G3_RX_DN<2>")
	)
	(arc
		(start 372.654322 -229.601268)
		(mid 372.540915 -229.734157)
		(end 372.500144 -229.904036)
		(width 0.1143)
		(layer "In11.Cu")
		(net "P5E_CPU0_G3_RX_DN<2>")
	)
	(arc
		(start 372.6561 -240.939828)
		(mid 372.500172 -241.24412)
		(end 372.6561 -241.548412)
		(width 0.1143)
		(layer "In11.Cu")
		(net "P5E_CPU0_G3_RX_DN<2>")
	)
	(arc
		(start 373.596154 -224.739962)
		(mid 373.481478 -224.873296)
		(end 373.440198 -225.044254)
		(width 0.1143)
		(layer "In11.Cu")
		(net "P5E_CPU0_G3_RX_DN<2>")
	)
	(arc
		(start 372.6561 -226.359974)
		(mid 372.500172 -226.664266)
		(end 372.6561 -226.968558)
		(width 0.1143)
		(layer "In11.Cu")
		(net "P5E_CPU0_G3_RX_DN<2>")
	)
	(arc
		(start 372.6561 -239.319816)
		(mid 372.500172 -239.624108)
		(end 372.6561 -239.9284)
		(width 0.1143)
		(layer "In11.Cu")
		(net "P5E_CPU0_G3_RX_DN<2>")
	)
	(arc
		(start 372.970298 -225.85426)
		(mid 372.905783 -226.116479)
		(end 372.726966 -226.318826)
		(width 0.1143)
		(layer "In11.Cu")
		(net "P5E_CPU0_G3_RX_DN<2>")
	)
	(arc
		(start 372.726966 -235.109512)
		(mid 372.970293 -235.574078)
		(end 372.726966 -236.038644)
		(width 0.1143)
		(layer "In11.Cu")
		(net "P5E_CPU0_G3_RX_DN<2>")
	)
	(arc
		(start 374.073674 -223.926908)
		(mid 373.953547 -224.060182)
		(end 373.910098 -224.234248)
		(width 0.1143)
		(layer "In11.Cu")
		(net "P5E_CPU0_G3_RX_DN<2>")
	)
	(arc
		(start 372.726966 -231.869488)
		(mid 372.970293 -232.334054)
		(end 372.726966 -232.79862)
		(width 0.1143)
		(layer "In11.Cu")
		(net "P5E_CPU0_G3_RX_DN<2>")
	)
	(arc
		(start 372.726966 -246.449596)
		(mid 372.905779 -246.651946)
		(end 372.970298 -246.914162)
		(width 0.1143)
		(layer "In11.Cu")
		(net "P5E_CPU0_G3_RX_DN<2>")
	)
	(arc
		(start 372.726966 -228.629718)
		(mid 372.970293 -229.094284)
		(end 372.726966 -229.55885)
		(width 0.1143)
		(layer "In11.Cu")
		(net "P5E_CPU0_G3_RX_DN<2>")
	)
	(arc
		(start 373.12727 -225.54946)
		(mid 373.011843 -225.682836)
		(end 372.970298 -225.85426)
		(width 0.1143)
		(layer "In11.Cu")
		(net "P5E_CPU0_G3_RX_DN<2>")
	)
	(arc
		(start 374.204992 -223.795844)
		(mid 374.145414 -223.867495)
		(end 374.07342 -223.926654)
		(width 0.1143)
		(layer "In11.Cu")
		(net "P5E_CPU0_G3_RX_DN<2>")
	)
	(arc
		(start 372.726966 -239.969548)
		(mid 372.970293 -240.434114)
		(end 372.726966 -240.89868)
		(width 0.1143)
		(layer "In11.Cu")
		(net "P5E_CPU0_G3_RX_DN<2>")
	)
	(arc
		(start 372.726966 -243.209572)
		(mid 372.970293 -243.674138)
		(end 372.726966 -244.138704)
		(width 0.1143)
		(layer "In11.Cu")
		(net "P5E_CPU0_G3_RX_DN<2>")
	)
	(arc
		(start 372.6561 -227.979986)
		(mid 372.500172 -228.284278)
		(end 372.6561 -228.58857)
		(width 0.1143)
		(layer "In11.Cu")
		(net "P5E_CPU0_G3_RX_DN<2>")
	)
	(arc
		(start 372.500144 -231.524048)
		(mid 372.541399 -231.695019)
		(end 372.6561 -231.82834)
		(width 0.1143)
		(layer "In11.Cu")
		(net "P5E_CPU0_G3_RX_DN<2>")
	)
	(segment
		(start 428.8282 -7.57047)
		(end 428.8282 -6.996176)
		(width 0.12954)
		(layer "F.Cu")
		(net "P5E_CPU0_G3_RX_DN<1>")
	)
	(segment
		(start 428.966884 -7.709154)
		(end 428.8282 -7.57047)
		(width 0.12954)
		(layer "F.Cu")
		(net "P5E_CPU0_G3_RX_DN<1>")
	)
	(segment
		(start 428.966884 -8.320024)
		(end 428.966884 -7.709154)
		(width 0.12954)
		(layer "F.Cu")
		(net "P5E_CPU0_G3_RX_DN<1>")
	)
	(segment
		(start 373.347996 -244.750082)
		(end 373.814848 -244.484144)
		(width 0.12954)
		(layer "F.Cu")
		(net "P5E_CPU0_G3_RX_DN<1>")
	)
	(segment
		(start 428.8282 -6.996176)
		(end 429.099218 -6.725158)
		(width 0.12954)
		(layer "F.Cu")
		(net "P5E_CPU0_G3_RX_DN<1>")
	)
	(segment
		(start 428.305468 -17.70888)
		(end 428.34941 -17.815052)
		(width 0.14224)
		(layer "In11.Cu")
		(net "P5E_CPU0_G3_RX_DN<1>")
	)
	(segment
		(start 373.627142 -227.962206)
		(end 373.625872 -227.962968)
		(width 0.1143)
		(layer "In11.Cu")
		(net "P5E_CPU0_G3_RX_DN<1>")
	)
	(segment
		(start 376.305572 -221.202758)
		(end 376.259852 -221.248478)
		(width 0.1143)
		(layer "In11.Cu")
		(net "P5E_CPU0_G3_RX_DN<1>")
	)
	(segment
		(start 429.099218 -6.725158)
		(end 428.808388 -7.015988)
		(width 0.14224)
		(layer "In11.Cu")
		(net "P5E_CPU0_G3_RX_DN<1>")
	)
	(segment
		(start 373.638064 -231.195372)
		(end 373.59717 -231.219248)
		(width 0.1143)
		(layer "In11.Cu")
		(net "P5E_CPU0_G3_RX_DN<1>")
	)
	(segment
		(start 428.808388 -7.015988)
		(end 428.808388 -12.526518)
		(width 0.14224)
		(layer "In11.Cu")
		(net "P5E_CPU0_G3_RX_DN<1>")
	)
	(segment
		(start 373.627904 -229.58171)
		(end 373.595138 -229.60076)
		(width 0.1143)
		(layer "In11.Cu")
		(net "P5E_CPU0_G3_RX_DN<1>")
	)
	(segment
		(start 329.85329 -130.403854)
		(end 326.662796 -135.71982)
		(width 0.14224)
		(layer "In11.Cu")
		(net "P5E_CPU0_G3_RX_DN<1>")
	)
	(segment
		(start 373.627904 -239.946688)
		(end 373.628158 -239.946942)
		(width 0.1143)
		(layer "In11.Cu")
		(net "P5E_CPU0_G3_RX_DN<1>")
	)
	(segment
		(start 373.627904 -243.186712)
		(end 373.664226 -243.207794)
		(width 0.1143)
		(layer "In11.Cu")
		(net "P5E_CPU0_G3_RX_DN<1>")
	)
	(segment
		(start 373.627904 -239.301528)
		(end 373.627142 -239.302036)
		(width 0.1143)
		(layer "In11.Cu")
		(net "P5E_CPU0_G3_RX_DN<1>")
	)
	(segment
		(start 428.34941 -17.815052)
		(end 428.571406 -18.229834)
		(width 0.14224)
		(layer "In11.Cu")
		(net "P5E_CPU0_G3_RX_DN<1>")
	)
	(segment
		(start 373.627142 -233.466132)
		(end 373.627904 -233.46664)
		(width 0.1143)
		(layer "In11.Cu")
		(net "P5E_CPU0_G3_RX_DN<1>")
	)
	(segment
		(start 373.623586 -237.684056)
		(end 373.62257 -237.684564)
		(width 0.1143)
		(layer "In11.Cu")
		(net "P5E_CPU0_G3_RX_DN<1>")
	)
	(segment
		(start 373.628158 -242.541552)
		(end 373.627904 -242.541552)
		(width 0.1143)
		(layer "In11.Cu")
		(net "P5E_CPU0_G3_RX_DN<1>")
	)
	(segment
		(start 373.60606 -235.073952)
		(end 373.606822 -235.07446)
		(width 0.1143)
		(layer "In11.Cu")
		(net "P5E_CPU0_G3_RX_DN<1>")
	)
	(segment
		(start 373.664226 -234.42041)
		(end 373.627904 -234.441492)
		(width 0.1143)
		(layer "In11.Cu")
		(net "P5E_CPU0_G3_RX_DN<1>")
	)
	(segment
		(start 373.659908 -230.245158)
		(end 373.661432 -230.246174)
		(width 0.1143)
		(layer "In11.Cu")
		(net "P5E_CPU0_G3_RX_DN<1>")
	)
	(segment
		(start 375.320052 -223.345756)
		(end 375.320052 -223.424242)
		(width 0.1143)
		(layer "In11.Cu")
		(net "P5E_CPU0_G3_RX_DN<1>")
	)
	(segment
		(start 373.627904 -231.846628)
		(end 373.664226 -231.86771)
		(width 0.1143)
		(layer "In11.Cu")
		(net "P5E_CPU0_G3_RX_DN<1>")
	)
	(segment
		(start 373.623586 -239.304068)
		(end 373.62257 -239.304576)
		(width 0.1143)
		(layer "In11.Cu")
		(net "P5E_CPU0_G3_RX_DN<1>")
	)
	(segment
		(start 373.621808 -242.545108)
		(end 373.620538 -242.54587)
		(width 0.1143)
		(layer "In11.Cu")
		(net "P5E_CPU0_G3_RX_DN<1>")
	)
	(segment
		(start 374.582944 -224.713038)
		(end 374.582944 -224.713292)
		(width 0.1143)
		(layer "In11.Cu")
		(net "P5E_CPU0_G3_RX_DN<1>")
	)
	(segment
		(start 373.59717 -231.219248)
		(end 373.594376 -231.22128)
		(width 0.1143)
		(layer "In11.Cu")
		(net "P5E_CPU0_G3_RX_DN<1>")
	)
	(segment
		(start 373.662702 -226.32162)
		(end 373.596154 -226.359974)
		(width 0.1143)
		(layer "In11.Cu")
		(net "P5E_CPU0_G3_RX_DN<1>")
	)
	(segment
		(start 337.067144 -174.220886)
		(end 339.566758 -177.810668)
		(width 0.14224)
		(layer "In11.Cu")
		(net "P5E_CPU0_G3_RX_DN<1>")
	)
	(segment
		(start 373.627142 -228.60635)
		(end 373.627904 -228.606858)
		(width 0.1143)
		(layer "In11.Cu")
		(net "P5E_CPU0_G3_RX_DN<1>")
	)
	(segment
		(start 373.627904 -242.541552)
		(end 373.627142 -242.54206)
		(width 0.1143)
		(layer "In11.Cu")
		(net "P5E_CPU0_G3_RX_DN<1>")
	)
	(segment
		(start 376.01525 -222.269812)
		(end 376.014234 -222.270574)
		(width 0.1143)
		(layer "In11.Cu")
		(net "P5E_CPU0_G3_RX_DN<1>")
	)
	(segment
		(start 373.628158 -236.061504)
		(end 373.627904 -236.061504)
		(width 0.1143)
		(layer "In11.Cu")
		(net "P5E_CPU0_G3_RX_DN<1>")
	)
	(segment
		(start 373.625872 -243.185442)
		(end 373.627142 -243.186204)
		(width 0.1143)
		(layer "In11.Cu")
		(net "P5E_CPU0_G3_RX_DN<1>")
	)
	(segment
		(start 373.625872 -227.962968)
		(end 373.596154 -227.979986)
		(width 0.1143)
		(layer "In11.Cu")
		(net "P5E_CPU0_G3_RX_DN<1>")
	)
	(segment
		(start 373.596154 -226.968558)
		(end 373.627904 -226.986846)
		(width 0.1143)
		(layer "In11.Cu")
		(net "P5E_CPU0_G3_RX_DN<1>")
	)
	(segment
		(start 375.546874 -223.078802)
		(end 375.507758 -223.101662)
		(width 0.1143)
		(layer "In11.Cu")
		(net "P5E_CPU0_G3_RX_DN<1>")
	)
	(segment
		(start 428.305468 -17.5895)
		(end 428.305468 -17.70888)
		(width 0.14224)
		(layer "In11.Cu")
		(net "P5E_CPU0_G3_RX_DN<1>")
	)
	(segment
		(start 376.305572 -219.700348)
		(end 376.305572 -221.17431)
		(width 0.14224)
		(layer "In11.Cu")
		(net "P5E_CPU0_G3_RX_DN<1>")
	)
	(segment
		(start 373.630444 -230.22814)
		(end 373.63146 -230.228648)
		(width 0.1143)
		(layer "In11.Cu")
		(net "P5E_CPU0_G3_RX_DN<1>")
	)
	(segment
		(start 374.073928 -225.545396)
		(end 374.071642 -225.54692)
		(width 0.1143)
		(layer "In11.Cu")
		(net "P5E_CPU0_G3_RX_DN<1>")
	)
	(segment
		(start 373.628158 -239.301528)
		(end 373.627904 -239.301528)
		(width 0.1143)
		(layer "In11.Cu")
		(net "P5E_CPU0_G3_RX_DN<1>")
	)
	(segment
		(start 373.627142 -237.682024)
		(end 373.626126 -237.682532)
		(width 0.1143)
		(layer "In11.Cu")
		(net "P5E_CPU0_G3_RX_DN<1>")
	)
	(segment
		(start 373.6213 -228.603048)
		(end 373.622062 -228.603556)
		(width 0.1143)
		(layer "In11.Cu")
		(net "P5E_CPU0_G3_RX_DN<1>")
	)
	(segment
		(start 373.624348 -242.543584)
		(end 373.623586 -242.544092)
		(width 0.1143)
		(layer "In11.Cu")
		(net "P5E_CPU0_G3_RX_DN<1>")
	)
	(segment
		(start 373.62892 -230.227124)
		(end 373.630444 -230.22814)
		(width 0.1143)
		(layer "In11.Cu")
		(net "P5E_CPU0_G3_RX_DN<1>")
	)
	(segment
		(start 373.627904 -235.086652)
		(end 373.628158 -235.086906)
		(width 0.1143)
		(layer "In11.Cu")
		(net "P5E_CPU0_G3_RX_DN<1>")
	)
	(segment
		(start 339.566758 -177.810668)
		(end 367.676938 -200.832974)
		(width 0.14224)
		(layer "In11.Cu")
		(net "P5E_CPU0_G3_RX_DN<1>")
	)
	(segment
		(start 373.627904 -240.92154)
		(end 373.627142 -240.922048)
		(width 0.1143)
		(layer "In11.Cu")
		(net "P5E_CPU0_G3_RX_DN<1>")
	)
	(segment
		(start 373.622062 -228.603556)
		(end 373.623586 -228.604318)
		(width 0.1143)
		(layer "In11.Cu")
		(net "P5E_CPU0_G3_RX_DN<1>")
	)
	(segment
		(start 373.627904 -227.961698)
		(end 373.627142 -227.962206)
		(width 0.1143)
		(layer "In11.Cu")
		(net "P5E_CPU0_G3_RX_DN<1>")
	)
	(segment
		(start 373.627904 -230.226616)
		(end 373.62892 -230.227124)
		(width 0.1143)
		(layer "In11.Cu")
		(net "P5E_CPU0_G3_RX_DN<1>")
	)
	(segment
		(start 373.60606 -241.554)
		(end 373.606822 -241.554508)
		(width 0.1143)
		(layer "In11.Cu")
		(net "P5E_CPU0_G3_RX_DN<1>")
	)
	(segment
		(start 373.620538 -237.685834)
		(end 373.596154 -237.699804)
		(width 0.1143)
		(layer "In11.Cu")
		(net "P5E_CPU0_G3_RX_DN<1>")
	)
	(segment
		(start 375.07418 -223.890586)
		(end 374.998742 -223.935036)
		(width 0.1143)
		(layer "In11.Cu")
		(net "P5E_CPU0_G3_RX_DN<1>")
	)
	(segment
		(start 376.01398 -222.270574)
		(end 375.947178 -222.309436)
		(width 0.1143)
		(layer "In11.Cu")
		(net "P5E_CPU0_G3_RX_DN<1>")
	)
	(segment
		(start 326.662796 -135.71982)
		(end 326.320658 -137.10031)
		(width 0.14224)
		(layer "In11.Cu")
		(net "P5E_CPU0_G3_RX_DN<1>")
	)
	(segment
		(start 428.571406 -18.229834)
		(end 428.936404 -18.77568)
		(width 0.14224)
		(layer "In11.Cu")
		(net "P5E_CPU0_G3_RX_DN<1>")
	)
	(segment
		(start 373.606822 -238.314484)
		(end 373.627904 -238.326676)
		(width 0.1143)
		(layer "In11.Cu")
		(net "P5E_CPU0_G3_RX_DN<1>")
	)
	(segment
		(start 374.606058 -224.699576)
		(end 374.582944 -224.713038)
		(width 0.1143)
		(layer "In11.Cu")
		(net "P5E_CPU0_G3_RX_DN<1>")
	)
	(segment
		(start 373.596154 -241.548412)
		(end 373.60606 -241.554)
		(width 0.1143)
		(layer "In11.Cu")
		(net "P5E_CPU0_G3_RX_DN<1>")
	)
	(segment
		(start 373.60606 -238.313976)
		(end 373.606822 -238.314484)
		(width 0.1143)
		(layer "In11.Cu")
		(net "P5E_CPU0_G3_RX_DN<1>")
	)
	(segment
		(start 429.010826 -18.99666)
		(end 429.010826 -18.997422)
		(width 0.14224)
		(layer "In11.Cu")
		(net "P5E_CPU0_G3_RX_DN<1>")
	)
	(segment
		(start 373.60606 -239.933988)
		(end 373.606822 -239.934496)
		(width 0.1143)
		(layer "In11.Cu")
		(net "P5E_CPU0_G3_RX_DN<1>")
	)
	(segment
		(start 373.624348 -239.30356)
		(end 373.623586 -239.304068)
		(width 0.1143)
		(layer "In11.Cu")
		(net "P5E_CPU0_G3_RX_DN<1>")
	)
	(segment
		(start 373.626126 -236.06252)
		(end 373.625364 -236.063028)
		(width 0.1143)
		(layer "In11.Cu")
		(net "P5E_CPU0_G3_RX_DN<1>")
	)
	(segment
		(start 373.627142 -240.922048)
		(end 373.626126 -240.922556)
		(width 0.1143)
		(layer "In11.Cu")
		(net "P5E_CPU0_G3_RX_DN<1>")
	)
	(segment
		(start 429.026574 -19.077178)
		(end 429.026574 -19.229324)
		(width 0.14224)
		(layer "In11.Cu")
		(net "P5E_CPU0_G3_RX_DN<1>")
	)
	(segment
		(start 428.799752 -12.569952)
		(end 428.305468 -17.5895)
		(width 0.14224)
		(layer "In11.Cu")
		(net "P5E_CPU0_G3_RX_DN<1>")
	)
	(segment
		(start 373.627142 -236.062012)
		(end 373.626126 -236.06252)
		(width 0.1143)
		(layer "In11.Cu")
		(net "P5E_CPU0_G3_RX_DN<1>")
	)
	(segment
		(start 373.620538 -242.54587)
		(end 373.596154 -242.55984)
		(width 0.1143)
		(layer "In11.Cu")
		(net "P5E_CPU0_G3_RX_DN<1>")
	)
	(segment
		(start 373.606822 -241.554508)
		(end 373.627904 -241.5667)
		(width 0.1143)
		(layer "In11.Cu")
		(net "P5E_CPU0_G3_RX_DN<1>")
	)
	(segment
		(start 373.624348 -236.063536)
		(end 373.623586 -236.064044)
		(width 0.1143)
		(layer "In11.Cu")
		(net "P5E_CPU0_G3_RX_DN<1>")
	)
	(segment
		(start 374.071642 -225.54692)
		(end 374.070626 -225.547428)
		(width 0.1143)
		(layer "In11.Cu")
		(net "P5E_CPU0_G3_RX_DN<1>")
	)
	(segment
		(start 376.259852 -221.248478)
		(end 376.259852 -221.80423)
		(width 0.1143)
		(layer "In11.Cu")
		(net "P5E_CPU0_G3_RX_DN<1>")
	)
	(segment
		(start 373.62257 -240.924588)
		(end 373.621808 -240.925096)
		(width 0.1143)
		(layer "In11.Cu")
		(net "P5E_CPU0_G3_RX_DN<1>")
	)
	(segment
		(start 374.13692 -225.50882)
		(end 374.09882 -225.531172)
		(width 0.1143)
		(layer "In11.Cu")
		(net "P5E_CPU0_G3_RX_DN<1>")
	)
	(segment
		(start 373.625364 -237.68304)
		(end 373.624348 -237.683548)
		(width 0.1143)
		(layer "In11.Cu")
		(net "P5E_CPU0_G3_RX_DN<1>")
	)
	(segment
		(start 373.625364 -240.923064)
		(end 373.624348 -240.923572)
		(width 0.1143)
		(layer "In11.Cu")
		(net "P5E_CPU0_G3_RX_DN<1>")
	)
	(segment
		(start 373.627142 -242.54206)
		(end 373.626126 -242.542568)
		(width 0.1143)
		(layer "In11.Cu")
		(net "P5E_CPU0_G3_RX_DN<1>")
	)
	(segment
		(start 373.627142 -239.302036)
		(end 373.626126 -239.302544)
		(width 0.1143)
		(layer "In11.Cu")
		(net "P5E_CPU0_G3_RX_DN<1>")
	)
	(segment
		(start 373.596154 -239.9284)
		(end 373.60606 -239.933988)
		(width 0.1143)
		(layer "In11.Cu")
		(net "P5E_CPU0_G3_RX_DN<1>")
	)
	(segment
		(start 373.626126 -237.682532)
		(end 373.625364 -237.68304)
		(width 0.1143)
		(layer "In11.Cu")
		(net "P5E_CPU0_G3_RX_DN<1>")
	)
	(segment
		(start 373.62257 -239.304576)
		(end 373.621808 -239.305084)
		(width 0.1143)
		(layer "In11.Cu")
		(net "P5E_CPU0_G3_RX_DN<1>")
	)
	(segment
		(start 373.625364 -239.303052)
		(end 373.624348 -239.30356)
		(width 0.1143)
		(layer "In11.Cu")
		(net "P5E_CPU0_G3_RX_DN<1>")
	)
	(segment
		(start 375.476008 -223.11995)
		(end 375.412 -223.165924)
		(width 0.1143)
		(layer "In11.Cu")
		(net "P5E_CPU0_G3_RX_DN<1>")
	)
	(segment
		(start 426.332396 -23.292308)
		(end 329.85329 -130.403854)
		(width 0.14224)
		(layer "In11.Cu")
		(net "P5E_CPU0_G3_RX_DN<1>")
	)
	(segment
		(start 373.664226 -229.560628)
		(end 373.661432 -229.562152)
		(width 0.1143)
		(layer "In11.Cu")
		(net "P5E_CPU0_G3_RX_DN<1>")
	)
	(segment
		(start 429.010826 -18.997422)
		(end 429.026574 -19.077178)
		(width 0.14224)
		(layer "In11.Cu")
		(net "P5E_CPU0_G3_RX_DN<1>")
	)
	(segment
		(start 373.623586 -228.604318)
		(end 373.624348 -228.604826)
		(width 0.1143)
		(layer "In11.Cu")
		(net "P5E_CPU0_G3_RX_DN<1>")
	)
	(segment
		(start 373.624348 -240.923572)
		(end 373.623586 -240.92408)
		(width 0.1143)
		(layer "In11.Cu")
		(net "P5E_CPU0_G3_RX_DN<1>")
	)
	(segment
		(start 373.60606 -236.693964)
		(end 373.606822 -236.694472)
		(width 0.1143)
		(layer "In11.Cu")
		(net "P5E_CPU0_G3_RX_DN<1>")
	)
	(segment
		(start 373.623586 -236.064044)
		(end 373.621554 -236.065314)
		(width 0.1143)
		(layer "In11.Cu")
		(net "P5E_CPU0_G3_RX_DN<1>")
	)
	(segment
		(start 373.447056 -244.414294)
		(end 373.516906 -244.484144)
		(width 0.1143)
		(layer "In11.Cu")
		(net "P5E_CPU0_G3_RX_DN<1>")
	)
	(segment
		(start 373.606822 -236.694472)
		(end 373.627904 -236.706664)
		(width 0.1143)
		(layer "In11.Cu")
		(net "P5E_CPU0_G3_RX_DN<1>")
	)
	(segment
		(start 375.226072 -213.57463)
		(end 376.305572 -219.700348)
		(width 0.14224)
		(layer "In11.Cu")
		(net "P5E_CPU0_G3_RX_DN<1>")
	)
	(segment
		(start 373.621554 -236.065314)
		(end 373.596154 -236.079792)
		(width 0.1143)
		(layer "In11.Cu")
		(net "P5E_CPU0_G3_RX_DN<1>")
	)
	(segment
		(start 373.620538 -240.925858)
		(end 373.596154 -240.939828)
		(width 0.1143)
		(layer "In11.Cu")
		(net "P5E_CPU0_G3_RX_DN<1>")
	)
	(segment
		(start 374.09882 -225.531172)
		(end 374.097804 -225.53168)
		(width 0.1143)
		(layer "In11.Cu")
		(net "P5E_CPU0_G3_RX_DN<1>")
	)
	(segment
		(start 373.624094 -230.22433)
		(end 373.627904 -230.226616)
		(width 0.1143)
		(layer "In11.Cu")
		(net "P5E_CPU0_G3_RX_DN<1>")
	)
	(segment
		(start 373.625872 -244.162834)
		(end 373.596154 -244.179852)
		(width 0.1143)
		(layer "In11.Cu")
		(net "P5E_CPU0_G3_RX_DN<1>")
	)
	(segment
		(start 373.595138 -229.60076)
		(end 373.594376 -229.601268)
		(width 0.1143)
		(layer "In11.Cu")
		(net "P5E_CPU0_G3_RX_DN<1>")
	)
	(segment
		(start 327.27519 -154.530044)
		(end 333.664814 -166.70274)
		(width 0.14224)
		(layer "In11.Cu")
		(net "P5E_CPU0_G3_RX_DN<1>")
	)
	(segment
		(start 373.626126 -240.922556)
		(end 373.625364 -240.923064)
		(width 0.1143)
		(layer "In11.Cu")
		(net "P5E_CPU0_G3_RX_DN<1>")
	)
	(segment
		(start 374.097804 -225.53168)
		(end 374.094502 -225.533458)
		(width 0.1143)
		(layer "In11.Cu")
		(net "P5E_CPU0_G3_RX_DN<1>")
	)
	(segment
		(start 374.582944 -224.713292)
		(end 374.537224 -224.739454)
		(width 0.1143)
		(layer "In11.Cu")
		(net "P5E_CPU0_G3_RX_DN<1>")
	)
	(segment
		(start 374.094502 -225.533458)
		(end 374.073928 -225.545396)
		(width 0.1143)
		(layer "In11.Cu")
		(net "P5E_CPU0_G3_RX_DN<1>")
	)
	(segment
		(start 373.596154 -238.308388)
		(end 373.60606 -238.313976)
		(width 0.1143)
		(layer "In11.Cu")
		(net "P5E_CPU0_G3_RX_DN<1>")
	)
	(segment
		(start 429.026574 -19.229324)
		(end 428.645828 -20.370038)
		(width 0.14224)
		(layer "In11.Cu")
		(net "P5E_CPU0_G3_RX_DN<1>")
	)
	(segment
		(start 373.596154 -243.168424)
		(end 373.625872 -243.185442)
		(width 0.1143)
		(layer "In11.Cu")
		(net "P5E_CPU0_G3_RX_DN<1>")
	)
	(segment
		(start 373.625364 -236.063028)
		(end 373.624348 -236.063536)
		(width 0.1143)
		(layer "In11.Cu")
		(net "P5E_CPU0_G3_RX_DN<1>")
	)
	(segment
		(start 373.620538 -239.305846)
		(end 373.596154 -239.319816)
		(width 0.1143)
		(layer "In11.Cu")
		(net "P5E_CPU0_G3_RX_DN<1>")
	)
	(segment
		(start 373.627904 -238.326676)
		(end 373.628158 -238.32693)
		(width 0.1143)
		(layer "In11.Cu")
		(net "P5E_CPU0_G3_RX_DN<1>")
	)
	(segment
		(start 373.625872 -231.845358)
		(end 373.627142 -231.84612)
		(width 0.1143)
		(layer "In11.Cu")
		(net "P5E_CPU0_G3_RX_DN<1>")
	)
	(segment
		(start 373.63146 -230.228648)
		(end 373.659908 -230.245158)
		(width 0.1143)
		(layer "In11.Cu")
		(net "P5E_CPU0_G3_RX_DN<1>")
	)
	(segment
		(start 376.014234 -222.270574)
		(end 376.01398 -222.270574)
		(width 0.1143)
		(layer "In11.Cu")
		(net "P5E_CPU0_G3_RX_DN<1>")
	)
	(segment
		(start 373.625872 -233.46537)
		(end 373.627142 -233.466132)
		(width 0.1143)
		(layer "In11.Cu")
		(net "P5E_CPU0_G3_RX_DN<1>")
	)
	(segment
		(start 373.628158 -240.92154)
		(end 373.627904 -240.92154)
		(width 0.1143)
		(layer "In11.Cu")
		(net "P5E_CPU0_G3_RX_DN<1>")
	)
	(segment
		(start 373.627904 -241.5667)
		(end 373.628158 -241.566954)
		(width 0.1143)
		(layer "In11.Cu")
		(net "P5E_CPU0_G3_RX_DN<1>")
	)
	(segment
		(start 428.808388 -12.526518)
		(end 428.799752 -12.569952)
		(width 0.14224)
		(layer "In11.Cu")
		(net "P5E_CPU0_G3_RX_DN<1>")
	)
	(segment
		(start 373.627142 -231.84612)
		(end 373.627904 -231.846628)
		(width 0.1143)
		(layer "In11.Cu")
		(net "P5E_CPU0_G3_RX_DN<1>")
	)
	(segment
		(start 373.627904 -237.681516)
		(end 373.627142 -237.682024)
		(width 0.1143)
		(layer "In11.Cu")
		(net "P5E_CPU0_G3_RX_DN<1>")
	)
	(segment
		(start 373.625364 -242.543076)
		(end 373.624348 -242.543584)
		(width 0.1143)
		(layer "In11.Cu")
		(net "P5E_CPU0_G3_RX_DN<1>")
	)
	(segment
		(start 373.628158 -237.681516)
		(end 373.627904 -237.681516)
		(width 0.1143)
		(layer "In11.Cu")
		(net "P5E_CPU0_G3_RX_DN<1>")
	)
	(segment
		(start 373.664226 -244.140482)
		(end 373.627904 -244.161564)
		(width 0.1143)
		(layer "In11.Cu")
		(net "P5E_CPU0_G3_RX_DN<1>")
	)
	(segment
		(start 373.627904 -236.061504)
		(end 373.627142 -236.062012)
		(width 0.1143)
		(layer "In11.Cu")
		(net "P5E_CPU0_G3_RX_DN<1>")
	)
	(segment
		(start 428.645828 -20.370038)
		(end 426.332396 -23.292308)
		(width 0.14224)
		(layer "In11.Cu")
		(net "P5E_CPU0_G3_RX_DN<1>")
	)
	(segment
		(start 373.627904 -234.441492)
		(end 373.596154 -234.45978)
		(width 0.1143)
		(layer "In11.Cu")
		(net "P5E_CPU0_G3_RX_DN<1>")
	)
	(segment
		(start 373.62257 -242.5446)
		(end 373.621808 -242.545108)
		(width 0.1143)
		(layer "In11.Cu")
		(net "P5E_CPU0_G3_RX_DN<1>")
	)
	(segment
		(start 373.627904 -233.46664)
		(end 373.664226 -233.487722)
		(width 0.1143)
		(layer "In11.Cu")
		(net "P5E_CPU0_G3_RX_DN<1>")
	)
	(segment
		(start 373.623586 -240.92408)
		(end 373.62257 -240.924588)
		(width 0.1143)
		(layer "In11.Cu")
		(net "P5E_CPU0_G3_RX_DN<1>")
	)
	(segment
		(start 373.661432 -229.562152)
		(end 373.627904 -229.58171)
		(width 0.1143)
		(layer "In11.Cu")
		(net "P5E_CPU0_G3_RX_DN<1>")
	)
	(segment
		(start 373.596154 -233.448352)
		(end 373.625872 -233.46537)
		(width 0.1143)
		(layer "In11.Cu")
		(net "P5E_CPU0_G3_RX_DN<1>")
	)
	(segment
		(start 373.596154 -235.068364)
		(end 373.60606 -235.073952)
		(width 0.1143)
		(layer "In11.Cu")
		(net "P5E_CPU0_G3_RX_DN<1>")
	)
	(segment
		(start 373.621808 -239.305084)
		(end 373.620538 -239.305846)
		(width 0.1143)
		(layer "In11.Cu")
		(net "P5E_CPU0_G3_RX_DN<1>")
	)
	(segment
		(start 373.596154 -230.208328)
		(end 373.624094 -230.22433)
		(width 0.1143)
		(layer "In11.Cu")
		(net "P5E_CPU0_G3_RX_DN<1>")
	)
	(segment
		(start 333.664814 -166.70274)
		(end 337.067144 -174.220886)
		(width 0.14224)
		(layer "In11.Cu")
		(net "P5E_CPU0_G3_RX_DN<1>")
	)
	(segment
		(start 373.596154 -231.82834)
		(end 373.625872 -231.845358)
		(width 0.1143)
		(layer "In11.Cu")
		(net "P5E_CPU0_G3_RX_DN<1>")
	)
	(segment
		(start 373.62257 -237.684564)
		(end 373.621808 -237.685072)
		(width 0.1143)
		(layer "In11.Cu")
		(net "P5E_CPU0_G3_RX_DN<1>")
	)
	(segment
		(start 373.596154 -236.688376)
		(end 373.60606 -236.693964)
		(width 0.1143)
		(layer "In11.Cu")
		(net "P5E_CPU0_G3_RX_DN<1>")
	)
	(segment
		(start 375.507758 -223.101662)
		(end 375.476008 -223.11995)
		(width 0.1143)
		(layer "In11.Cu")
		(net "P5E_CPU0_G3_RX_DN<1>")
	)
	(segment
		(start 373.664226 -227.940616)
		(end 373.627904 -227.961698)
		(width 0.1143)
		(layer "In11.Cu")
		(net "P5E_CPU0_G3_RX_DN<1>")
	)
	(segment
		(start 373.621808 -237.685072)
		(end 373.620538 -237.685834)
		(width 0.1143)
		(layer "In11.Cu")
		(net "P5E_CPU0_G3_RX_DN<1>")
	)
	(segment
		(start 373.621808 -240.925096)
		(end 373.620538 -240.925858)
		(width 0.1143)
		(layer "In11.Cu")
		(net "P5E_CPU0_G3_RX_DN<1>")
	)
	(segment
		(start 373.627142 -244.162072)
		(end 373.625872 -244.162834)
		(width 0.1143)
		(layer "In11.Cu")
		(net "P5E_CPU0_G3_RX_DN<1>")
	)
	(segment
		(start 326.320658 -137.10031)
		(end 327.27519 -154.530044)
		(width 0.14224)
		(layer "In11.Cu")
		(net "P5E_CPU0_G3_RX_DN<1>")
	)
	(segment
		(start 373.624348 -237.683548)
		(end 373.623586 -237.684056)
		(width 0.1143)
		(layer "In11.Cu")
		(net "P5E_CPU0_G3_RX_DN<1>")
	)
	(segment
		(start 367.676938 -200.832974)
		(end 375.226072 -213.57463)
		(width 0.14224)
		(layer "In11.Cu")
		(net "P5E_CPU0_G3_RX_DN<1>")
	)
	(segment
		(start 373.627142 -243.186204)
		(end 373.627904 -243.186712)
		(width 0.1143)
		(layer "In11.Cu")
		(net "P5E_CPU0_G3_RX_DN<1>")
	)
	(segment
		(start 373.910098 -225.870262)
		(end 373.910098 -225.870516)
		(width 0.1143)
		(layer "In11.Cu")
		(net "P5E_CPU0_G3_RX_DN<1>")
	)
	(segment
		(start 373.627904 -236.706664)
		(end 373.628158 -236.706918)
		(width 0.1143)
		(layer "In11.Cu")
		(net "P5E_CPU0_G3_RX_DN<1>")
	)
	(segment
		(start 373.627904 -232.82148)
		(end 373.596154 -232.839768)
		(width 0.1143)
		(layer "In11.Cu")
		(net "P5E_CPU0_G3_RX_DN<1>")
	)
	(segment
		(start 373.627904 -226.986846)
		(end 373.664226 -227.007928)
		(width 0.1143)
		(layer "In11.Cu")
		(net "P5E_CPU0_G3_RX_DN<1>")
	)
	(segment
		(start 373.664226 -226.320604)
		(end 373.662702 -226.32162)
		(width 0.1143)
		(layer "In11.Cu")
		(net "P5E_CPU0_G3_RX_DN<1>")
	)
	(segment
		(start 428.994824 -18.916396)
		(end 429.010826 -18.99666)
		(width 0.14224)
		(layer "In11.Cu")
		(net "P5E_CPU0_G3_RX_DN<1>")
	)
	(segment
		(start 373.624348 -228.604826)
		(end 373.627142 -228.60635)
		(width 0.1143)
		(layer "In11.Cu")
		(net "P5E_CPU0_G3_RX_DN<1>")
	)
	(segment
		(start 373.664226 -232.800398)
		(end 373.627904 -232.82148)
		(width 0.1143)
		(layer "In11.Cu")
		(net "P5E_CPU0_G3_RX_DN<1>")
	)
	(segment
		(start 428.936404 -18.77568)
		(end 428.994824 -18.916396)
		(width 0.14224)
		(layer "In11.Cu")
		(net "P5E_CPU0_G3_RX_DN<1>")
	)
	(segment
		(start 376.305572 -221.17431)
		(end 376.305572 -221.202758)
		(width 0.1143)
		(layer "In11.Cu")
		(net "P5E_CPU0_G3_RX_DN<1>")
	)
	(segment
		(start 373.606822 -239.934496)
		(end 373.627904 -239.946688)
		(width 0.1143)
		(layer "In11.Cu")
		(net "P5E_CPU0_G3_RX_DN<1>")
	)
	(segment
		(start 373.623586 -242.544092)
		(end 373.62257 -242.5446)
		(width 0.1143)
		(layer "In11.Cu")
		(net "P5E_CPU0_G3_RX_DN<1>")
	)
	(segment
		(start 373.606822 -235.07446)
		(end 373.627904 -235.086652)
		(width 0.1143)
		(layer "In11.Cu")
		(net "P5E_CPU0_G3_RX_DN<1>")
	)
	(segment
		(start 373.627904 -244.161564)
		(end 373.627142 -244.162072)
		(width 0.1143)
		(layer "In11.Cu")
		(net "P5E_CPU0_G3_RX_DN<1>")
	)
	(segment
		(start 374.850152 -224.221802)
		(end 374.850152 -224.234248)
		(width 0.1143)
		(layer "In11.Cu")
		(net "P5E_CPU0_G3_RX_DN<1>")
	)
	(segment
		(start 373.516906 -244.484144)
		(end 373.814848 -244.484144)
		(width 0.1143)
		(layer "In11.Cu")
		(net "P5E_CPU0_G3_RX_DN<1>")
	)
	(segment
		(start 373.620284 -228.60254)
		(end 373.6213 -228.603048)
		(width 0.1143)
		(layer "In11.Cu")
		(net "P5E_CPU0_G3_RX_DN<1>")
	)
	(segment
		(start 373.626126 -242.542568)
		(end 373.625364 -242.543076)
		(width 0.1143)
		(layer "In11.Cu")
		(net "P5E_CPU0_G3_RX_DN<1>")
	)
	(segment
		(start 373.626126 -239.302544)
		(end 373.625364 -239.303052)
		(width 0.1143)
		(layer "In11.Cu")
		(net "P5E_CPU0_G3_RX_DN<1>")
	)
	(segment
		(start 373.596154 -228.58857)
		(end 373.620284 -228.60254)
		(width 0.1143)
		(layer "In11.Cu")
		(net "P5E_CPU0_G3_RX_DN<1>")
	)
	(arc
		(start 374.061482 -225.55454)
		(mid 373.967565 -225.679624)
		(end 373.91467 -225.826828)
		(width 0.1143)
		(layer "In11.Cu")
		(net "P5E_CPU0_G3_RX_DN<1>")
	)
	(arc
		(start 373.596154 -244.179852)
		(mid 373.499019 -244.282721)
		(end 373.447056 -244.414294)
		(width 0.1143)
		(layer "In11.Cu")
		(net "P5E_CPU0_G3_RX_DN<1>")
	)
	(arc
		(start 373.596154 -237.699804)
		(mid 373.440226 -238.004096)
		(end 373.596154 -238.308388)
		(width 0.1143)
		(layer "In11.Cu")
		(net "P5E_CPU0_G3_RX_DN<1>")
	)
	(arc
		(start 373.627904 -228.606858)
		(mid 373.834527 -228.812637)
		(end 373.910098 -229.094284)
		(width 0.1143)
		(layer "In11.Cu")
		(net "P5E_CPU0_G3_RX_DN<1>")
	)
	(arc
		(start 373.596154 -232.839768)
		(mid 373.440226 -233.14406)
		(end 373.596154 -233.448352)
		(width 0.1143)
		(layer "In11.Cu")
		(net "P5E_CPU0_G3_RX_DN<1>")
	)
	(arc
		(start 374.537224 -224.739454)
		(mid 374.421797 -224.87283)
		(end 374.380252 -225.044254)
		(width 0.1143)
		(layer "In11.Cu")
		(net "P5E_CPU0_G3_RX_DN<1>")
	)
	(arc
		(start 373.91467 -225.826828)
		(mid 373.911485 -225.84845)
		(end 373.910098 -225.870262)
		(width 0.1143)
		(layer "In11.Cu")
		(net "P5E_CPU0_G3_RX_DN<1>")
	)
	(arc
		(start 373.628158 -238.32693)
		(mid 373.908805 -238.814292)
		(end 373.628158 -239.301528)
		(width 0.1143)
		(layer "In11.Cu")
		(net "P5E_CPU0_G3_RX_DN<1>")
	)
	(arc
		(start 373.628158 -239.946942)
		(mid 373.908805 -240.434304)
		(end 373.628158 -240.92154)
		(width 0.1143)
		(layer "In11.Cu")
		(net "P5E_CPU0_G3_RX_DN<1>")
	)
	(arc
		(start 373.910098 -225.870516)
		(mid 373.841137 -226.125047)
		(end 373.664226 -226.320604)
		(width 0.1143)
		(layer "In11.Cu")
		(net "P5E_CPU0_G3_RX_DN<1>")
	)
	(arc
		(start 373.596154 -236.079792)
		(mid 373.440226 -236.384084)
		(end 373.596154 -236.688376)
		(width 0.1143)
		(layer "In11.Cu")
		(net "P5E_CPU0_G3_RX_DN<1>")
	)
	(arc
		(start 373.664226 -233.487722)
		(mid 373.671375 -233.492622)
		(end 373.67845 -233.497628)
		(width 0.1143)
		(layer "In11.Cu")
		(net "P5E_CPU0_G3_RX_DN<1>")
	)
	(arc
		(start 373.596154 -242.55984)
		(mid 373.440226 -242.864132)
		(end 373.596154 -243.168424)
		(width 0.1143)
		(layer "In11.Cu")
		(net "P5E_CPU0_G3_RX_DN<1>")
	)
	(arc
		(start 373.596154 -226.359974)
		(mid 373.440226 -226.664266)
		(end 373.596154 -226.968558)
		(width 0.1143)
		(layer "In11.Cu")
		(net "P5E_CPU0_G3_RX_DN<1>")
	)
	(arc
		(start 374.998742 -223.935036)
		(mid 374.88951 -224.060315)
		(end 374.850152 -224.221802)
		(width 0.1143)
		(layer "In11.Cu")
		(net "P5E_CPU0_G3_RX_DN<1>")
	)
	(arc
		(start 373.594376 -231.22128)
		(mid 373.480969 -231.354169)
		(end 373.440198 -231.524048)
		(width 0.1143)
		(layer "In11.Cu")
		(net "P5E_CPU0_G3_RX_DN<1>")
	)
	(arc
		(start 373.440198 -229.904036)
		(mid 373.481453 -230.075007)
		(end 373.596154 -230.208328)
		(width 0.1143)
		(layer "In11.Cu")
		(net "P5E_CPU0_G3_RX_DN<1>")
	)
	(arc
		(start 373.678196 -230.257604)
		(mid 373.846372 -230.457307)
		(end 373.910098 -230.710486)
		(width 0.1143)
		(layer "In11.Cu")
		(net "P5E_CPU0_G3_RX_DN<1>")
	)
	(arc
		(start 373.67845 -233.497628)
		(mid 373.905833 -233.954066)
		(end 373.67845 -234.410504)
		(width 0.1143)
		(layer "In11.Cu")
		(net "P5E_CPU0_G3_RX_DN<1>")
	)
	(arc
		(start 375.412 -223.165924)
		(mid 375.344363 -223.244755)
		(end 375.320052 -223.345756)
		(width 0.1143)
		(layer "In11.Cu")
		(net "P5E_CPU0_G3_RX_DN<1>")
	)
	(arc
		(start 373.596154 -239.319816)
		(mid 373.440226 -239.624108)
		(end 373.596154 -239.9284)
		(width 0.1143)
		(layer "In11.Cu")
		(net "P5E_CPU0_G3_RX_DN<1>")
	)
	(arc
		(start 373.680482 -244.129052)
		(mid 373.672404 -244.134838)
		(end 373.664226 -244.140482)
		(width 0.1143)
		(layer "In11.Cu")
		(net "P5E_CPU0_G3_RX_DN<1>")
	)
	(arc
		(start 373.680482 -232.788968)
		(mid 373.672404 -232.794754)
		(end 373.664226 -232.800398)
		(width 0.1143)
		(layer "In11.Cu")
		(net "P5E_CPU0_G3_RX_DN<1>")
	)
	(arc
		(start 374.380252 -225.044254)
		(mid 374.315737 -225.306473)
		(end 374.13692 -225.50882)
		(width 0.1143)
		(layer "In11.Cu")
		(net "P5E_CPU0_G3_RX_DN<1>")
	)
	(arc
		(start 373.680482 -227.929186)
		(mid 373.672404 -227.934972)
		(end 373.664226 -227.940616)
		(width 0.1143)
		(layer "In11.Cu")
		(net "P5E_CPU0_G3_RX_DN<1>")
	)
	(arc
		(start 375.090436 -223.879156)
		(mid 375.082358 -223.884942)
		(end 375.07418 -223.890586)
		(width 0.1143)
		(layer "In11.Cu")
		(net "P5E_CPU0_G3_RX_DN<1>")
	)
	(arc
		(start 373.661432 -230.246174)
		(mid 373.669865 -230.251814)
		(end 373.678196 -230.257604)
		(width 0.1143)
		(layer "In11.Cu")
		(net "P5E_CPU0_G3_RX_DN<1>")
	)
	(arc
		(start 373.664226 -227.007928)
		(mid 373.672404 -227.013571)
		(end 373.680482 -227.019358)
		(width 0.1143)
		(layer "In11.Cu")
		(net "P5E_CPU0_G3_RX_DN<1>")
	)
	(arc
		(start 373.910098 -230.710486)
		(mid 373.840083 -230.989949)
		(end 373.638064 -231.195372)
		(width 0.1143)
		(layer "In11.Cu")
		(net "P5E_CPU0_G3_RX_DN<1>")
	)
	(arc
		(start 373.680482 -227.019358)
		(mid 373.903366 -227.474272)
		(end 373.680482 -227.929186)
		(width 0.1143)
		(layer "In11.Cu")
		(net "P5E_CPU0_G3_RX_DN<1>")
	)
	(arc
		(start 373.440198 -231.524048)
		(mid 373.481453 -231.695019)
		(end 373.596154 -231.82834)
		(width 0.1143)
		(layer "In11.Cu")
		(net "P5E_CPU0_G3_RX_DN<1>")
	)
	(arc
		(start 374.070626 -225.547428)
		(mid 374.066026 -225.550949)
		(end 374.061482 -225.55454)
		(width 0.1143)
		(layer "In11.Cu")
		(net "P5E_CPU0_G3_RX_DN<1>")
	)
	(arc
		(start 373.677688 -229.550976)
		(mid 373.670993 -229.555852)
		(end 373.664226 -229.560628)
		(width 0.1143)
		(layer "In11.Cu")
		(net "P5E_CPU0_G3_RX_DN<1>")
	)
	(arc
		(start 373.594376 -229.601268)
		(mid 373.480969 -229.734157)
		(end 373.440198 -229.904036)
		(width 0.1143)
		(layer "In11.Cu")
		(net "P5E_CPU0_G3_RX_DN<1>")
	)
	(arc
		(start 373.680482 -243.219224)
		(mid 373.903366 -243.674138)
		(end 373.680482 -244.129052)
		(width 0.1143)
		(layer "In11.Cu")
		(net "P5E_CPU0_G3_RX_DN<1>")
	)
	(arc
		(start 373.67845 -234.410504)
		(mid 373.671376 -234.415511)
		(end 373.664226 -234.42041)
		(width 0.1143)
		(layer "In11.Cu")
		(net "P5E_CPU0_G3_RX_DN<1>")
	)
	(arc
		(start 376.259852 -221.80423)
		(mid 376.195034 -222.067219)
		(end 376.01525 -222.269812)
		(width 0.1143)
		(layer "In11.Cu")
		(net "P5E_CPU0_G3_RX_DN<1>")
	)
	(arc
		(start 373.628158 -236.706918)
		(mid 373.908805 -237.19428)
		(end 373.628158 -237.681516)
		(width 0.1143)
		(layer "In11.Cu")
		(net "P5E_CPU0_G3_RX_DN<1>")
	)
	(arc
		(start 374.850152 -224.234248)
		(mid 374.78543 -224.496987)
		(end 374.606058 -224.699576)
		(width 0.1143)
		(layer "In11.Cu")
		(net "P5E_CPU0_G3_RX_DN<1>")
	)
	(arc
		(start 375.790206 -222.614236)
		(mid 375.725691 -222.876455)
		(end 375.546874 -223.078802)
		(width 0.1143)
		(layer "In11.Cu")
		(net "P5E_CPU0_G3_RX_DN<1>")
	)
	(arc
		(start 373.664226 -231.86771)
		(mid 373.672404 -231.873353)
		(end 373.680482 -231.87914)
		(width 0.1143)
		(layer "In11.Cu")
		(net "P5E_CPU0_G3_RX_DN<1>")
	)
	(arc
		(start 373.596154 -240.939828)
		(mid 373.440226 -241.24412)
		(end 373.596154 -241.548412)
		(width 0.1143)
		(layer "In11.Cu")
		(net "P5E_CPU0_G3_RX_DN<1>")
	)
	(arc
		(start 375.320052 -223.430846)
		(mid 375.25518 -223.680588)
		(end 375.090436 -223.879156)
		(width 0.1143)
		(layer "In11.Cu")
		(net "P5E_CPU0_G3_RX_DN<1>")
	)
	(arc
		(start 373.664226 -243.207794)
		(mid 373.672404 -243.213437)
		(end 373.680482 -243.219224)
		(width 0.1143)
		(layer "In11.Cu")
		(net "P5E_CPU0_G3_RX_DN<1>")
	)
	(arc
		(start 373.628158 -241.566954)
		(mid 373.908805 -242.054316)
		(end 373.628158 -242.541552)
		(width 0.1143)
		(layer "In11.Cu")
		(net "P5E_CPU0_G3_RX_DN<1>")
	)
	(arc
		(start 375.320052 -223.424242)
		(mid 375.320062 -223.427544)
		(end 375.320052 -223.430846)
		(width 0.1143)
		(layer "In11.Cu")
		(net "P5E_CPU0_G3_RX_DN<1>")
	)
	(arc
		(start 373.910098 -229.094284)
		(mid 373.848653 -229.350496)
		(end 373.677688 -229.550976)
		(width 0.1143)
		(layer "In11.Cu")
		(net "P5E_CPU0_G3_RX_DN<1>")
	)
	(arc
		(start 373.596154 -234.45978)
		(mid 373.440226 -234.764072)
		(end 373.596154 -235.068364)
		(width 0.1143)
		(layer "In11.Cu")
		(net "P5E_CPU0_G3_RX_DN<1>")
	)
	(arc
		(start 375.947178 -222.309436)
		(mid 375.831751 -222.442812)
		(end 375.790206 -222.614236)
		(width 0.1143)
		(layer "In11.Cu")
		(net "P5E_CPU0_G3_RX_DN<1>")
	)
	(arc
		(start 373.596154 -227.979986)
		(mid 373.440226 -228.284278)
		(end 373.596154 -228.58857)
		(width 0.1143)
		(layer "In11.Cu")
		(net "P5E_CPU0_G3_RX_DN<1>")
	)
	(arc
		(start 373.628158 -235.086906)
		(mid 373.908805 -235.574268)
		(end 373.628158 -236.061504)
		(width 0.1143)
		(layer "In11.Cu")
		(net "P5E_CPU0_G3_RX_DN<1>")
	)
	(arc
		(start 373.680482 -231.87914)
		(mid 373.903366 -232.334054)
		(end 373.680482 -232.788968)
		(width 0.1143)
		(layer "In11.Cu")
		(net "P5E_CPU0_G3_RX_DN<1>")
	)
	(segment
		(start 394.246862 -7.709154)
		(end 394.108178 -7.57047)
		(width 0.12954)
		(layer "F.Cu")
		(net "P5E_CPU0_G3_RX_DN<15>")
	)
	(segment
		(start 394.246862 -8.320024)
		(end 394.246862 -7.709154)
		(width 0.12954)
		(layer "F.Cu")
		(net "P5E_CPU0_G3_RX_DN<15>")
	)
	(segment
		(start 394.108178 -6.996176)
		(end 394.379196 -6.725158)
		(width 0.12954)
		(layer "F.Cu")
		(net "P5E_CPU0_G3_RX_DN<15>")
	)
	(segment
		(start 362.53801 -248.800112)
		(end 363.004862 -248.534174)
		(width 0.12954)
		(layer "F.Cu")
		(net "P5E_CPU0_G3_RX_DN<15>")
	)
	(segment
		(start 394.108178 -7.57047)
		(end 394.108178 -6.996176)
		(width 0.12954)
		(layer "F.Cu")
		(net "P5E_CPU0_G3_RX_DN<15>")
	)
	(segment
		(start 389.035036 -16.980154)
		(end 388.832852 -17.468342)
		(width 0.14224)
		(layer "In11.Cu")
		(net "P5E_CPU0_G3_RX_DN<15>")
	)
	(segment
		(start 361.870752 -247.232678)
		(end 361.871768 -247.233186)
		(width 0.1143)
		(layer "In11.Cu")
		(net "P5E_CPU0_G3_RX_DN<15>")
	)
	(segment
		(start 360.892852 -245.929404)
		(end 361.331256 -246.367808)
		(width 0.1143)
		(layer "In11.Cu")
		(net "P5E_CPU0_G3_RX_DN<15>")
	)
	(segment
		(start 394.088366 -11.911584)
		(end 393.665202 -12.933172)
		(width 0.14224)
		(layer "In11.Cu")
		(net "P5E_CPU0_G3_RX_DN<15>")
	)
	(segment
		(start 313.692286 -175.089312)
		(end 319.340992 -178.474624)
		(width 0.14224)
		(layer "In11.Cu")
		(net "P5E_CPU0_G3_RX_DN<15>")
	)
	(segment
		(start 360.872532 -245.84406)
		(end 360.892852 -245.86438)
		(width 0.1143)
		(layer "In11.Cu")
		(net "P5E_CPU0_G3_RX_DN<15>")
	)
	(segment
		(start 361.878372 -247.236996)
		(end 361.914186 -247.257824)
		(width 0.1143)
		(layer "In11.Cu")
		(net "P5E_CPU0_G3_RX_DN<15>")
	)
	(segment
		(start 361.189778 -221.474284)
		(end 360.635296 -222.813118)
		(width 0.14224)
		(layer "In11.Cu")
		(net "P5E_CPU0_G3_RX_DN<15>")
	)
	(segment
		(start 362.347764 -248.046748)
		(end 362.34878 -248.047256)
		(width 0.1143)
		(layer "In11.Cu")
		(net "P5E_CPU0_G3_RX_DN<15>")
	)
	(segment
		(start 305.990752 -160.939734)
		(end 305.990752 -163.286694)
		(width 0.14224)
		(layer "In11.Cu")
		(net "P5E_CPU0_G3_RX_DN<15>")
	)
	(segment
		(start 362.34878 -248.047256)
		(end 362.38688 -248.069608)
		(width 0.1143)
		(layer "In11.Cu")
		(net "P5E_CPU0_G3_RX_DN<15>")
	)
	(segment
		(start 393.665202 -12.933172)
		(end 389.502904 -16.349218)
		(width 0.14224)
		(layer "In11.Cu")
		(net "P5E_CPU0_G3_RX_DN<15>")
	)
	(segment
		(start 320.185542 -179.039012)
		(end 320.196972 -179.046886)
		(width 0.14224)
		(layer "In11.Cu")
		(net "P5E_CPU0_G3_RX_DN<15>")
	)
	(segment
		(start 318.1731 -122.560842)
		(end 315.05525 -128.465072)
		(width 0.14224)
		(layer "In11.Cu")
		(net "P5E_CPU0_G3_RX_DN<15>")
	)
	(segment
		(start 362.70692 -248.534174)
		(end 363.004862 -248.534174)
		(width 0.1143)
		(layer "In11.Cu")
		(net "P5E_CPU0_G3_RX_DN<15>")
	)
	(segment
		(start 315.05525 -128.465072)
		(end 308.538118 -146.440652)
		(width 0.14224)
		(layer "In11.Cu")
		(net "P5E_CPU0_G3_RX_DN<15>")
	)
	(segment
		(start 361.871768 -247.233186)
		(end 361.87253 -247.233694)
		(width 0.1143)
		(layer "In11.Cu")
		(net "P5E_CPU0_G3_RX_DN<15>")
	)
	(segment
		(start 361.873546 -247.234202)
		(end 361.874308 -247.23471)
		(width 0.1143)
		(layer "In11.Cu")
		(net "P5E_CPU0_G3_RX_DN<15>")
	)
	(segment
		(start 362.347002 -248.04624)
		(end 362.347764 -248.046748)
		(width 0.1143)
		(layer "In11.Cu")
		(net "P5E_CPU0_G3_RX_DN<15>")
	)
	(segment
		(start 319.340992 -178.474624)
		(end 320.185542 -179.039266)
		(width 0.14224)
		(layer "In11.Cu")
		(net "P5E_CPU0_G3_RX_DN<15>")
	)
	(segment
		(start 369.030758 -51.900328)
		(end 318.1731 -122.560842)
		(width 0.14224)
		(layer "In11.Cu")
		(net "P5E_CPU0_G3_RX_DN<15>")
	)
	(segment
		(start 361.189778 -216.03716)
		(end 361.189778 -221.474284)
		(width 0.14224)
		(layer "In11.Cu")
		(net "P5E_CPU0_G3_RX_DN<15>")
	)
	(segment
		(start 357.281734 -209.455004)
		(end 361.189778 -216.03716)
		(width 0.14224)
		(layer "In11.Cu")
		(net "P5E_CPU0_G3_RX_DN<15>")
	)
	(segment
		(start 320.185542 -179.039266)
		(end 320.185542 -179.039012)
		(width 0.14224)
		(layer "In11.Cu")
		(net "P5E_CPU0_G3_RX_DN<15>")
	)
	(segment
		(start 361.87253 -247.233694)
		(end 361.873546 -247.234202)
		(width 0.1143)
		(layer "In11.Cu")
		(net "P5E_CPU0_G3_RX_DN<15>")
	)
	(segment
		(start 361.846114 -247.218454)
		(end 361.870752 -247.232678)
		(width 0.1143)
		(layer "In11.Cu")
		(net "P5E_CPU0_G3_RX_DN<15>")
	)
	(segment
		(start 361.40771 -246.426736)
		(end 361.446826 -246.449596)
		(width 0.1143)
		(layer "In11.Cu")
		(net "P5E_CPU0_G3_RX_DN<15>")
	)
	(segment
		(start 320.196972 -179.046886)
		(end 357.281734 -209.455004)
		(width 0.14224)
		(layer "In11.Cu")
		(net "P5E_CPU0_G3_RX_DN<15>")
	)
	(segment
		(start 308.538118 -146.440652)
		(end 305.990752 -160.939734)
		(width 0.14224)
		(layer "In11.Cu")
		(net "P5E_CPU0_G3_RX_DN<15>")
	)
	(segment
		(start 361.877864 -247.236742)
		(end 361.878372 -247.236996)
		(width 0.1143)
		(layer "In11.Cu")
		(net "P5E_CPU0_G3_RX_DN<15>")
	)
	(segment
		(start 361.874308 -247.23471)
		(end 361.875832 -247.235472)
		(width 0.1143)
		(layer "In11.Cu")
		(net "P5E_CPU0_G3_RX_DN<15>")
	)
	(segment
		(start 386.113274 -25.298654)
		(end 369.030758 -51.900328)
		(width 0.14224)
		(layer "In11.Cu")
		(net "P5E_CPU0_G3_RX_DN<15>")
	)
	(segment
		(start 394.379196 -6.725158)
		(end 394.088366 -7.015988)
		(width 0.14224)
		(layer "In11.Cu")
		(net "P5E_CPU0_G3_RX_DN<15>")
	)
	(segment
		(start 394.088366 -7.015988)
		(end 394.088366 -11.911584)
		(width 0.14224)
		(layer "In11.Cu")
		(net "P5E_CPU0_G3_RX_DN<15>")
	)
	(segment
		(start 361.877102 -247.236234)
		(end 361.877864 -247.236742)
		(width 0.1143)
		(layer "In11.Cu")
		(net "P5E_CPU0_G3_RX_DN<15>")
	)
	(segment
		(start 386.874766 -23.673816)
		(end 386.113274 -25.298654)
		(width 0.14224)
		(layer "In11.Cu")
		(net "P5E_CPU0_G3_RX_DN<15>")
	)
	(segment
		(start 389.502904 -16.349218)
		(end 389.035036 -16.980154)
		(width 0.14224)
		(layer "In11.Cu")
		(net "P5E_CPU0_G3_RX_DN<15>")
	)
	(segment
		(start 361.875832 -247.235472)
		(end 361.877102 -247.236234)
		(width 0.1143)
		(layer "In11.Cu")
		(net "P5E_CPU0_G3_RX_DN<15>")
	)
	(segment
		(start 360.635296 -222.813118)
		(end 360.635296 -245.606824)
		(width 0.14224)
		(layer "In11.Cu")
		(net "P5E_CPU0_G3_RX_DN<15>")
	)
	(segment
		(start 308.888892 -170.284648)
		(end 313.692286 -175.089312)
		(width 0.14224)
		(layer "In11.Cu")
		(net "P5E_CPU0_G3_RX_DN<15>")
	)
	(segment
		(start 388.832852 -17.468342)
		(end 386.874766 -23.673816)
		(width 0.14224)
		(layer "In11.Cu")
		(net "P5E_CPU0_G3_RX_DN<15>")
	)
	(segment
		(start 362.316014 -248.02846)
		(end 362.347002 -248.04624)
		(width 0.1143)
		(layer "In11.Cu")
		(net "P5E_CPU0_G3_RX_DN<15>")
	)
	(segment
		(start 305.990752 -163.286694)
		(end 308.888892 -170.284648)
		(width 0.14224)
		(layer "In11.Cu")
		(net "P5E_CPU0_G3_RX_DN<15>")
	)
	(segment
		(start 360.635296 -245.606824)
		(end 360.872532 -245.84406)
		(width 0.14224)
		(layer "In11.Cu")
		(net "P5E_CPU0_G3_RX_DN<15>")
	)
	(segment
		(start 362.624116 -248.45137)
		(end 362.70692 -248.534174)
		(width 0.1143)
		(layer "In11.Cu")
		(net "P5E_CPU0_G3_RX_DN<15>")
	)
	(segment
		(start 360.892852 -245.86438)
		(end 360.892852 -245.929404)
		(width 0.1143)
		(layer "In11.Cu")
		(net "P5E_CPU0_G3_RX_DN<15>")
	)
	(arc
		(start 361.94111 -247.278144)
		(mid 362.08445 -247.461483)
		(end 362.156502 -247.682766)
		(width 0.1143)
		(layer "In11.Cu")
		(net "P5E_CPU0_G3_RX_DN<15>")
	)
	(arc
		(start 361.446826 -246.449596)
		(mid 361.625639 -246.651946)
		(end 361.690158 -246.914162)
		(width 0.1143)
		(layer "In11.Cu")
		(net "P5E_CPU0_G3_RX_DN<15>")
	)
	(arc
		(start 361.914186 -247.257824)
		(mid 361.927799 -247.267784)
		(end 361.94111 -247.278144)
		(width 0.1143)
		(layer "In11.Cu")
		(net "P5E_CPU0_G3_RX_DN<15>")
	)
	(arc
		(start 362.38688 -248.069608)
		(mid 362.538867 -248.226116)
		(end 362.620306 -248.42851)
		(width 0.1143)
		(layer "In11.Cu")
		(net "P5E_CPU0_G3_RX_DN<15>")
	)
	(arc
		(start 362.156502 -247.682766)
		(mid 362.158932 -247.703928)
		(end 362.160312 -247.725184)
		(width 0.1143)
		(layer "In11.Cu")
		(net "P5E_CPU0_G3_RX_DN<15>")
	)
	(arc
		(start 361.690158 -246.914162)
		(mid 361.731413 -247.085133)
		(end 361.846114 -247.218454)
		(width 0.1143)
		(layer "In11.Cu")
		(net "P5E_CPU0_G3_RX_DN<15>")
	)
	(arc
		(start 361.331256 -246.367808)
		(mid 361.367571 -246.399752)
		(end 361.40771 -246.426736)
		(width 0.1143)
		(layer "In11.Cu")
		(net "P5E_CPU0_G3_RX_DN<15>")
	)
	(arc
		(start 362.160312 -247.725184)
		(mid 362.204556 -247.894061)
		(end 362.316014 -248.02846)
		(width 0.1143)
		(layer "In11.Cu")
		(net "P5E_CPU0_G3_RX_DN<15>")
	)
	(arc
		(start 362.620306 -248.42851)
		(mid 362.622329 -248.43992)
		(end 362.624116 -248.45137)
		(width 0.1143)
		(layer "In11.Cu")
		(net "P5E_CPU0_G3_RX_DN<15>")
	)
	(segment
		(start 396.04696 -7.709408)
		(end 396.04696 -8.320024)
		(width 0.12954)
		(layer "F.Cu")
		(net "P5E_CPU0_G3_RX_DN<14>")
	)
	(segment
		(start 396.183866 -4.963414)
		(end 395.908022 -5.239258)
		(width 0.12954)
		(layer "F.Cu")
		(net "P5E_CPU0_G3_RX_DN<14>")
	)
	(segment
		(start 395.908022 -5.239258)
		(end 395.908022 -7.57047)
		(width 0.12954)
		(layer "F.Cu")
		(net "P5E_CPU0_G3_RX_DN<14>")
	)
	(segment
		(start 362.53801 -247.1801)
		(end 363.004862 -246.914162)
		(width 0.12954)
		(layer "F.Cu")
		(net "P5E_CPU0_G3_RX_DN<14>")
	)
	(segment
		(start 395.908022 -7.57047)
		(end 396.04696 -7.709408)
		(width 0.12954)
		(layer "F.Cu")
		(net "P5E_CPU0_G3_RX_DN<14>")
	)
	(segment
		(start 362.344208 -246.424704)
		(end 362.348272 -246.42699)
		(width 0.1143)
		(layer "In11.Cu")
		(net "P5E_CPU0_G3_RX_DN<14>")
	)
	(segment
		(start 361.37723 -243.168932)
		(end 361.446826 -243.209572)
		(width 0.1143)
		(layer "In11.Cu")
		(net "P5E_CPU0_G3_RX_DN<14>")
	)
	(segment
		(start 362.316014 -222.108522)
		(end 362.345732 -222.12554)
		(width 0.1143)
		(layer "In11.Cu")
		(net "P5E_CPU0_G3_RX_DN<14>")
	)
	(segment
		(start 306.922932 -161.027364)
		(end 306.922932 -162.871658)
		(width 0.14224)
		(layer "In11.Cu")
		(net "P5E_CPU0_G3_RX_DN<14>")
	)
	(segment
		(start 361.220258 -242.864132)
		(end 361.220258 -242.867434)
		(width 0.1143)
		(layer "In11.Cu")
		(net "P5E_CPU0_G3_RX_DN<14>")
	)
	(segment
		(start 362.347002 -222.126302)
		(end 362.347764 -222.12681)
		(width 0.1143)
		(layer "In11.Cu")
		(net "P5E_CPU0_G3_RX_DN<14>")
	)
	(segment
		(start 361.374944 -239.320578)
		(end 361.372912 -239.322102)
		(width 0.1143)
		(layer "In11.Cu")
		(net "P5E_CPU0_G3_RX_DN<14>")
	)
	(segment
		(start 361.446826 -239.278668)
		(end 361.40771 -239.301528)
		(width 0.1143)
		(layer "In11.Cu")
		(net "P5E_CPU0_G3_RX_DN<14>")
	)
	(segment
		(start 361.446826 -234.418632)
		(end 361.40771 -234.441492)
		(width 0.1143)
		(layer "In11.Cu")
		(net "P5E_CPU0_G3_RX_DN<14>")
	)
	(segment
		(start 362.70692 -246.914162)
		(end 363.004862 -246.914162)
		(width 0.1143)
		(layer "In11.Cu")
		(net "P5E_CPU0_G3_RX_DN<14>")
	)
	(segment
		(start 361.374944 -236.080554)
		(end 361.372912 -236.082078)
		(width 0.1143)
		(layer "In11.Cu")
		(net "P5E_CPU0_G3_RX_DN<14>")
	)
	(segment
		(start 361.372912 -235.066078)
		(end 361.374944 -235.067602)
		(width 0.1143)
		(layer "In11.Cu")
		(net "P5E_CPU0_G3_RX_DN<14>")
	)
	(segment
		(start 361.374944 -239.927638)
		(end 361.446826 -239.969548)
		(width 0.1143)
		(layer "In11.Cu")
		(net "P5E_CPU0_G3_RX_DN<14>")
	)
	(segment
		(start 316.107318 -128.491234)
		(end 309.378604 -147.048982)
		(width 0.14224)
		(layer "In11.Cu")
		(net "P5E_CPU0_G3_RX_DN<14>")
	)
	(segment
		(start 361.220766 -229.90175)
		(end 361.22102 -229.90175)
		(width 0.1143)
		(layer "In11.Cu")
		(net "P5E_CPU0_G3_RX_DN<14>")
	)
	(segment
		(start 361.446826 -226.318826)
		(end 361.37723 -226.359466)
		(width 0.1143)
		(layer "In11.Cu")
		(net "P5E_CPU0_G3_RX_DN<14>")
	)
	(segment
		(start 361.874054 -245.614444)
		(end 361.875324 -245.615206)
		(width 0.1143)
		(layer "In11.Cu")
		(net "P5E_CPU0_G3_RX_DN<14>")
	)
	(segment
		(start 361.37723 -228.589078)
		(end 361.446826 -228.629718)
		(width 0.1143)
		(layer "In11.Cu")
		(net "P5E_CPU0_G3_RX_DN<14>")
	)
	(segment
		(start 395.893036 -12.033758)
		(end 395.603476 -12.987782)
		(width 0.14224)
		(layer "In11.Cu")
		(net "P5E_CPU0_G3_RX_DN<14>")
	)
	(segment
		(start 361.374944 -236.687614)
		(end 361.446826 -236.729524)
		(width 0.1143)
		(layer "In11.Cu")
		(net "P5E_CPU0_G3_RX_DN<14>")
	)
	(segment
		(start 361.40771 -231.201722)
		(end 361.375198 -231.220518)
		(width 0.1143)
		(layer "In11.Cu")
		(net "P5E_CPU0_G3_RX_DN<14>")
	)
	(segment
		(start 361.372912 -239.926114)
		(end 361.374944 -239.927638)
		(width 0.1143)
		(layer "In11.Cu")
		(net "P5E_CPU0_G3_RX_DN<14>")
	)
	(segment
		(start 314.462922 -174.463964)
		(end 319.848992 -177.691796)
		(width 0.14224)
		(layer "In11.Cu")
		(net "P5E_CPU0_G3_RX_DN<14>")
	)
	(segment
		(start 361.689904 -225.854006)
		(end 361.690158 -225.85426)
		(width 0.1143)
		(layer "In11.Cu")
		(net "P5E_CPU0_G3_RX_DN<14>")
	)
	(segment
		(start 309.786782 -169.786554)
		(end 314.462922 -174.46371)
		(width 0.14224)
		(layer "In11.Cu")
		(net "P5E_CPU0_G3_RX_DN<14>")
	)
	(segment
		(start 362.624116 -246.831358)
		(end 362.70692 -246.914162)
		(width 0.1143)
		(layer "In11.Cu")
		(net "P5E_CPU0_G3_RX_DN<14>")
	)
	(segment
		(start 361.446826 -236.038644)
		(end 361.40771 -236.061504)
		(width 0.1143)
		(layer "In11.Cu")
		(net "P5E_CPU0_G3_RX_DN<14>")
	)
	(segment
		(start 362.349288 -223.103694)
		(end 362.349034 -223.103948)
		(width 0.1143)
		(layer "In11.Cu")
		(net "P5E_CPU0_G3_RX_DN<14>")
	)
	(segment
		(start 362.160058 -221.128844)
		(end 362.160058 -221.38767)
		(width 0.1143)
		(layer "In11.Cu")
		(net "P5E_CPU0_G3_RX_DN<14>")
	)
	(segment
		(start 361.689904 -224.938844)
		(end 361.689904 -225.854006)
		(width 0.1143)
		(layer "In11.Cu")
		(net "P5E_CPU0_G3_RX_DN<14>")
	)
	(segment
		(start 361.374944 -235.067602)
		(end 361.446826 -235.109512)
		(width 0.1143)
		(layer "In11.Cu")
		(net "P5E_CPU0_G3_RX_DN<14>")
	)
	(segment
		(start 361.22102 -229.90175)
		(end 361.220512 -229.911656)
		(width 0.1143)
		(layer "In11.Cu")
		(net "P5E_CPU0_G3_RX_DN<14>")
	)
	(segment
		(start 320.747136 -178.292252)
		(end 358.041448 -208.87182)
		(width 0.14224)
		(layer "In11.Cu")
		(net "P5E_CPU0_G3_RX_DN<14>")
	)
	(segment
		(start 362.347764 -222.12681)
		(end 362.34878 -222.127318)
		(width 0.1143)
		(layer "In11.Cu")
		(net "P5E_CPU0_G3_RX_DN<14>")
	)
	(segment
		(start 361.374944 -233.44759)
		(end 361.446826 -233.4895)
		(width 0.1143)
		(layer "In11.Cu")
		(net "P5E_CPU0_G3_RX_DN<14>")
	)
	(segment
		(start 319.02527 -122.996706)
		(end 316.107318 -128.491234)
		(width 0.14224)
		(layer "In11.Cu")
		(net "P5E_CPU0_G3_RX_DN<14>")
	)
	(segment
		(start 361.374436 -243.1669)
		(end 361.37723 -243.168932)
		(width 0.1143)
		(layer "In11.Cu")
		(net "P5E_CPU0_G3_RX_DN<14>")
	)
	(segment
		(start 361.40771 -239.301528)
		(end 361.374944 -239.320578)
		(width 0.1143)
		(layer "In11.Cu")
		(net "P5E_CPU0_G3_RX_DN<14>")
	)
	(segment
		(start 361.40771 -232.82148)
		(end 361.374944 -232.84053)
		(width 0.1143)
		(layer "In11.Cu")
		(net "P5E_CPU0_G3_RX_DN<14>")
	)
	(segment
		(start 361.40771 -234.441492)
		(end 361.374944 -234.460542)
		(width 0.1143)
		(layer "In11.Cu")
		(net "P5E_CPU0_G3_RX_DN<14>")
	)
	(segment
		(start 361.37723 -231.828848)
		(end 361.446826 -231.869488)
		(width 0.1143)
		(layer "In11.Cu")
		(net "P5E_CPU0_G3_RX_DN<14>")
	)
	(segment
		(start 361.917996 -244.948202)
		(end 361.846368 -244.989858)
		(width 0.1143)
		(layer "In11.Cu")
		(net "P5E_CPU0_G3_RX_DN<14>")
	)
	(segment
		(start 361.917996 -244.020086)
		(end 361.935522 -244.03304)
		(width 0.1143)
		(layer "In11.Cu")
		(net "P5E_CPU0_G3_RX_DN<14>")
	)
	(segment
		(start 392.264138 -17.985486)
		(end 392.055604 -18.375122)
		(width 0.14224)
		(layer "In11.Cu")
		(net "P5E_CPU0_G3_RX_DN<14>")
	)
	(segment
		(start 361.374944 -237.700566)
		(end 361.372912 -237.70209)
		(width 0.1143)
		(layer "In11.Cu")
		(net "P5E_CPU0_G3_RX_DN<14>")
	)
	(segment
		(start 362.205778 -221.083124)
		(end 362.160058 -221.128844)
		(width 0.1143)
		(layer "In11.Cu")
		(net "P5E_CPU0_G3_RX_DN<14>")
	)
	(segment
		(start 361.372912 -236.68609)
		(end 361.374944 -236.687614)
		(width 0.1143)
		(layer "In11.Cu")
		(net "P5E_CPU0_G3_RX_DN<14>")
	)
	(segment
		(start 361.446826 -227.938838)
		(end 361.37723 -227.979478)
		(width 0.1143)
		(layer "In11.Cu")
		(net "P5E_CPU0_G3_RX_DN<14>")
	)
	(segment
		(start 361.875324 -245.615206)
		(end 361.876086 -245.615714)
		(width 0.1143)
		(layer "In11.Cu")
		(net "P5E_CPU0_G3_RX_DN<14>")
	)
	(segment
		(start 361.446826 -231.178862)
		(end 361.40771 -231.201722)
		(width 0.1143)
		(layer "In11.Cu")
		(net "P5E_CPU0_G3_RX_DN<14>")
	)
	(segment
		(start 362.063284 -224.505266)
		(end 361.732576 -224.83572)
		(width 0.1143)
		(layer "In11.Cu")
		(net "P5E_CPU0_G3_RX_DN<14>")
	)
	(segment
		(start 362.205778 -221.054676)
		(end 362.205778 -221.083124)
		(width 0.1143)
		(layer "In11.Cu")
		(net "P5E_CPU0_G3_RX_DN<14>")
	)
	(segment
		(start 362.348272 -246.42699)
		(end 362.349034 -246.427498)
		(width 0.1143)
		(layer "In11.Cu")
		(net "P5E_CPU0_G3_RX_DN<14>")
	)
	(segment
		(start 392.055604 -18.375122)
		(end 367.409476 -56.438038)
		(width 0.14224)
		(layer "In11.Cu")
		(net "P5E_CPU0_G3_RX_DN<14>")
	)
	(segment
		(start 362.345732 -222.12554)
		(end 362.347002 -222.126302)
		(width 0.1143)
		(layer "In11.Cu")
		(net "P5E_CPU0_G3_RX_DN<14>")
	)
	(segment
		(start 362.205778 -215.88603)
		(end 362.205778 -221.054676)
		(width 0.14224)
		(layer "In11.Cu")
		(net "P5E_CPU0_G3_RX_DN<14>")
	)
	(segment
		(start 367.409476 -56.438038)
		(end 319.02527 -122.996706)
		(width 0.14224)
		(layer "In11.Cu")
		(net "P5E_CPU0_G3_RX_DN<14>")
	)
	(segment
		(start 361.876086 -245.615714)
		(end 361.877102 -245.616222)
		(width 0.1143)
		(layer "In11.Cu")
		(net "P5E_CPU0_G3_RX_DN<14>")
	)
	(segment
		(start 396.183866 -4.963414)
		(end 395.893036 -5.254244)
		(width 0.14224)
		(layer "In11.Cu")
		(net "P5E_CPU0_G3_RX_DN<14>")
	)
	(segment
		(start 361.374944 -238.307626)
		(end 361.446826 -238.349536)
		(width 0.1143)
		(layer "In11.Cu")
		(net "P5E_CPU0_G3_RX_DN<14>")
	)
	(segment
		(start 362.159804 -221.387924)
		(end 362.159804 -221.804484)
		(width 0.1143)
		(layer "In11.Cu")
		(net "P5E_CPU0_G3_RX_DN<14>")
	)
	(segment
		(start 306.922932 -162.871658)
		(end 309.786782 -169.786554)
		(width 0.14224)
		(layer "In11.Cu")
		(net "P5E_CPU0_G3_RX_DN<14>")
	)
	(segment
		(start 361.732576 -224.83572)
		(end 361.732576 -224.835974)
		(width 0.1143)
		(layer "In11.Cu")
		(net "P5E_CPU0_G3_RX_DN<14>")
	)
	(segment
		(start 314.462922 -174.46371)
		(end 314.462922 -174.463964)
		(width 0.14224)
		(layer "In11.Cu")
		(net "P5E_CPU0_G3_RX_DN<14>")
	)
	(segment
		(start 395.893036 -5.254244)
		(end 395.893036 -12.033758)
		(width 0.14224)
		(layer "In11.Cu")
		(net "P5E_CPU0_G3_RX_DN<14>")
	)
	(segment
		(start 361.367832 -241.543586)
		(end 361.446826 -241.58956)
		(width 0.1143)
		(layer "In11.Cu")
		(net "P5E_CPU0_G3_RX_DN<14>")
	)
	(segment
		(start 361.446826 -237.658656)
		(end 361.40771 -237.681516)
		(width 0.1143)
		(layer "In11.Cu")
		(net "P5E_CPU0_G3_RX_DN<14>")
	)
	(segment
		(start 361.37723 -226.969066)
		(end 361.446826 -227.009706)
		(width 0.1143)
		(layer "In11.Cu")
		(net "P5E_CPU0_G3_RX_DN<14>")
	)
	(segment
		(start 361.372912 -233.446066)
		(end 361.374944 -233.44759)
		(width 0.1143)
		(layer "In11.Cu")
		(net "P5E_CPU0_G3_RX_DN<14>")
	)
	(segment
		(start 362.349034 -246.427498)
		(end 362.38688 -246.449596)
		(width 0.1143)
		(layer "In11.Cu")
		(net "P5E_CPU0_G3_RX_DN<14>")
	)
	(segment
		(start 362.160058 -221.38767)
		(end 362.159804 -221.387924)
		(width 0.1143)
		(layer "In11.Cu")
		(net "P5E_CPU0_G3_RX_DN<14>")
	)
	(segment
		(start 361.37723 -230.208836)
		(end 361.444286 -230.247952)
		(width 0.1143)
		(layer "In11.Cu")
		(net "P5E_CPU0_G3_RX_DN<14>")
	)
	(segment
		(start 361.877864 -245.61673)
		(end 361.878372 -245.616984)
		(width 0.1143)
		(layer "In11.Cu")
		(net "P5E_CPU0_G3_RX_DN<14>")
	)
	(segment
		(start 361.220004 -242.864132)
		(end 361.220258 -242.864132)
		(width 0.1143)
		(layer "In11.Cu")
		(net "P5E_CPU0_G3_RX_DN<14>")
	)
	(segment
		(start 358.041448 -208.87182)
		(end 362.205778 -215.88603)
		(width 0.14224)
		(layer "In11.Cu")
		(net "P5E_CPU0_G3_RX_DN<14>")
	)
	(segment
		(start 361.40771 -236.061504)
		(end 361.374944 -236.080554)
		(width 0.1143)
		(layer "In11.Cu")
		(net "P5E_CPU0_G3_RX_DN<14>")
	)
	(segment
		(start 361.446826 -242.518692)
		(end 361.374944 -242.560602)
		(width 0.1143)
		(layer "In11.Cu")
		(net "P5E_CPU0_G3_RX_DN<14>")
	)
	(segment
		(start 361.846368 -244.989858)
		(end 361.846114 -244.989858)
		(width 0.1143)
		(layer "In11.Cu")
		(net "P5E_CPU0_G3_RX_DN<14>")
	)
	(segment
		(start 362.34878 -222.127318)
		(end 362.38688 -222.14967)
		(width 0.1143)
		(layer "In11.Cu")
		(net "P5E_CPU0_G3_RX_DN<14>")
	)
	(segment
		(start 361.374944 -234.460542)
		(end 361.372912 -234.462066)
		(width 0.1143)
		(layer "In11.Cu")
		(net "P5E_CPU0_G3_RX_DN<14>")
	)
	(segment
		(start 309.378604 -147.048982)
		(end 306.922932 -161.027364)
		(width 0.14224)
		(layer "In11.Cu")
		(net "P5E_CPU0_G3_RX_DN<14>")
	)
	(segment
		(start 362.159804 -221.804484)
		(end 362.160058 -221.80423)
		(width 0.1143)
		(layer "In11.Cu")
		(net "P5E_CPU0_G3_RX_DN<14>")
	)
	(segment
		(start 361.446826 -229.55885)
		(end 361.380532 -229.597458)
		(width 0.1143)
		(layer "In11.Cu")
		(net "P5E_CPU0_G3_RX_DN<14>")
	)
	(segment
		(start 395.603476 -12.987782)
		(end 392.264138 -17.985486)
		(width 0.14224)
		(layer "In11.Cu")
		(net "P5E_CPU0_G3_RX_DN<14>")
	)
	(segment
		(start 361.446826 -240.89868)
		(end 361.367832 -240.944654)
		(width 0.1143)
		(layer "In11.Cu")
		(net "P5E_CPU0_G3_RX_DN<14>")
	)
	(segment
		(start 319.848992 -177.691796)
		(end 320.747136 -178.292252)
		(width 0.14224)
		(layer "In11.Cu")
		(net "P5E_CPU0_G3_RX_DN<14>")
	)
	(segment
		(start 361.846114 -243.97843)
		(end 361.917996 -244.020086)
		(width 0.1143)
		(layer "In11.Cu")
		(net "P5E_CPU0_G3_RX_DN<14>")
	)
	(segment
		(start 361.446826 -232.79862)
		(end 361.40771 -232.82148)
		(width 0.1143)
		(layer "In11.Cu")
		(net "P5E_CPU0_G3_RX_DN<14>")
	)
	(segment
		(start 361.40771 -237.681516)
		(end 361.374944 -237.700566)
		(width 0.1143)
		(layer "In11.Cu")
		(net "P5E_CPU0_G3_RX_DN<14>")
	)
	(segment
		(start 361.374944 -232.84053)
		(end 361.372912 -232.842054)
		(width 0.1143)
		(layer "In11.Cu")
		(net "P5E_CPU0_G3_RX_DN<14>")
	)
	(segment
		(start 361.877102 -245.616222)
		(end 361.877864 -245.61673)
		(width 0.1143)
		(layer "In11.Cu")
		(net "P5E_CPU0_G3_RX_DN<14>")
	)
	(segment
		(start 361.846114 -245.598442)
		(end 361.874054 -245.614444)
		(width 0.1143)
		(layer "In11.Cu")
		(net "P5E_CPU0_G3_RX_DN<14>")
	)
	(segment
		(start 361.935522 -244.935248)
		(end 361.917996 -244.948202)
		(width 0.1143)
		(layer "In11.Cu")
		(net "P5E_CPU0_G3_RX_DN<14>")
	)
	(segment
		(start 361.372912 -238.306102)
		(end 361.374944 -238.307626)
		(width 0.1143)
		(layer "In11.Cu")
		(net "P5E_CPU0_G3_RX_DN<14>")
	)
	(segment
		(start 362.161582 -223.444054)
		(end 362.161582 -224.26803)
		(width 0.1143)
		(layer "In11.Cu")
		(net "P5E_CPU0_G3_RX_DN<14>")
	)
	(segment
		(start 362.349034 -223.103948)
		(end 362.347256 -223.104964)
		(width 0.1143)
		(layer "In11.Cu")
		(net "P5E_CPU0_G3_RX_DN<14>")
	)
	(arc
		(start 361.446826 -233.4895)
		(mid 361.690153 -233.954066)
		(end 361.446826 -234.418632)
		(width 0.1143)
		(layer "In11.Cu")
		(net "P5E_CPU0_G3_RX_DN<14>")
	)
	(arc
		(start 361.220512 -229.911656)
		(mid 361.263617 -230.078854)
		(end 361.37723 -230.208836)
		(width 0.1143)
		(layer "In11.Cu")
		(net "P5E_CPU0_G3_RX_DN<14>")
	)
	(arc
		(start 361.446826 -241.58956)
		(mid 361.690153 -242.054126)
		(end 361.446826 -242.518692)
		(width 0.1143)
		(layer "In11.Cu")
		(net "P5E_CPU0_G3_RX_DN<14>")
	)
	(arc
		(start 362.483654 -246.534686)
		(mid 362.570876 -246.662164)
		(end 362.620306 -246.808498)
		(width 0.1143)
		(layer "In11.Cu")
		(net "P5E_CPU0_G3_RX_DN<14>")
	)
	(arc
		(start 361.446826 -228.629718)
		(mid 361.690153 -229.094284)
		(end 361.446826 -229.55885)
		(width 0.1143)
		(layer "In11.Cu")
		(net "P5E_CPU0_G3_RX_DN<14>")
	)
	(arc
		(start 362.630212 -222.614236)
		(mid 362.554922 -222.896361)
		(end 362.349288 -223.103694)
		(width 0.1143)
		(layer "In11.Cu")
		(net "P5E_CPU0_G3_RX_DN<14>")
	)
	(arc
		(start 361.446826 -235.109512)
		(mid 361.690153 -235.574078)
		(end 361.446826 -236.038644)
		(width 0.1143)
		(layer "In11.Cu")
		(net "P5E_CPU0_G3_RX_DN<14>")
	)
	(arc
		(start 361.446826 -238.349536)
		(mid 361.690153 -238.814102)
		(end 361.446826 -239.278668)
		(width 0.1143)
		(layer "In11.Cu")
		(net "P5E_CPU0_G3_RX_DN<14>")
	)
	(arc
		(start 362.161582 -224.26803)
		(mid 362.135988 -224.396408)
		(end 362.063284 -224.505266)
		(width 0.1143)
		(layer "In11.Cu")
		(net "P5E_CPU0_G3_RX_DN<14>")
	)
	(arc
		(start 361.446826 -243.209572)
		(mid 361.625639 -243.411922)
		(end 361.690158 -243.674138)
		(width 0.1143)
		(layer "In11.Cu")
		(net "P5E_CPU0_G3_RX_DN<14>")
	)
	(arc
		(start 361.372912 -239.322102)
		(mid 361.218732 -239.624108)
		(end 361.372912 -239.926114)
		(width 0.1143)
		(layer "In11.Cu")
		(net "P5E_CPU0_G3_RX_DN<14>")
	)
	(arc
		(start 362.38688 -246.449596)
		(mid 362.437692 -246.489382)
		(end 362.483654 -246.534686)
		(width 0.1143)
		(layer "In11.Cu")
		(net "P5E_CPU0_G3_RX_DN<14>")
	)
	(arc
		(start 362.344716 -223.106234)
		(mid 362.206037 -223.249619)
		(end 362.161582 -223.444054)
		(width 0.1143)
		(layer "In11.Cu")
		(net "P5E_CPU0_G3_RX_DN<14>")
	)
	(arc
		(start 362.347256 -223.104964)
		(mid 362.345985 -223.105596)
		(end 362.344716 -223.106234)
		(width 0.1143)
		(layer "In11.Cu")
		(net "P5E_CPU0_G3_RX_DN<14>")
	)
	(arc
		(start 361.367832 -240.944654)
		(mid 361.196111 -241.24412)
		(end 361.367832 -241.543586)
		(width 0.1143)
		(layer "In11.Cu")
		(net "P5E_CPU0_G3_RX_DN<14>")
	)
	(arc
		(start 361.690158 -225.85426)
		(mid 361.625643 -226.116479)
		(end 361.446826 -226.318826)
		(width 0.1143)
		(layer "In11.Cu")
		(net "P5E_CPU0_G3_RX_DN<14>")
	)
	(arc
		(start 361.732576 -224.835974)
		(mid 361.70104 -224.883171)
		(end 361.689904 -224.938844)
		(width 0.1143)
		(layer "In11.Cu")
		(net "P5E_CPU0_G3_RX_DN<14>")
	)
	(arc
		(start 361.690158 -230.714296)
		(mid 361.625643 -230.976515)
		(end 361.446826 -231.178862)
		(width 0.1143)
		(layer "In11.Cu")
		(net "P5E_CPU0_G3_RX_DN<14>")
	)
	(arc
		(start 361.446826 -239.969548)
		(mid 361.690153 -240.434114)
		(end 361.446826 -240.89868)
		(width 0.1143)
		(layer "In11.Cu")
		(net "P5E_CPU0_G3_RX_DN<14>")
	)
	(arc
		(start 361.446826 -236.729524)
		(mid 361.690153 -237.19409)
		(end 361.446826 -237.658656)
		(width 0.1143)
		(layer "In11.Cu")
		(net "P5E_CPU0_G3_RX_DN<14>")
	)
	(arc
		(start 361.935522 -244.03304)
		(mid 362.166036 -244.484144)
		(end 361.935522 -244.935248)
		(width 0.1143)
		(layer "In11.Cu")
		(net "P5E_CPU0_G3_RX_DN<14>")
	)
	(arc
		(start 361.690158 -243.674138)
		(mid 361.731413 -243.845109)
		(end 361.846114 -243.97843)
		(width 0.1143)
		(layer "In11.Cu")
		(net "P5E_CPU0_G3_RX_DN<14>")
	)
	(arc
		(start 361.37723 -226.359466)
		(mid 361.220253 -226.664266)
		(end 361.37723 -226.969066)
		(width 0.1143)
		(layer "In11.Cu")
		(net "P5E_CPU0_G3_RX_DN<14>")
	)
	(arc
		(start 361.221528 -242.897406)
		(mid 361.268234 -243.049032)
		(end 361.374436 -243.1669)
		(width 0.1143)
		(layer "In11.Cu")
		(net "P5E_CPU0_G3_RX_DN<14>")
	)
	(arc
		(start 361.220258 -242.867434)
		(mid 361.220585 -242.882433)
		(end 361.221528 -242.897406)
		(width 0.1143)
		(layer "In11.Cu")
		(net "P5E_CPU0_G3_RX_DN<14>")
	)
	(arc
		(start 362.171996 -221.898464)
		(mid 362.193874 -221.95989)
		(end 362.226098 -222.016574)
		(width 0.1143)
		(layer "In11.Cu")
		(net "P5E_CPU0_G3_RX_DN<14>")
	)
	(arc
		(start 361.37723 -227.979478)
		(mid 361.220253 -228.284278)
		(end 361.37723 -228.589078)
		(width 0.1143)
		(layer "In11.Cu")
		(net "P5E_CPU0_G3_RX_DN<14>")
	)
	(arc
		(start 362.156502 -246.100092)
		(mid 362.206798 -246.287594)
		(end 362.344208 -246.424704)
		(width 0.1143)
		(layer "In11.Cu")
		(net "P5E_CPU0_G3_RX_DN<14>")
	)
	(arc
		(start 361.372912 -236.082078)
		(mid 361.218732 -236.384084)
		(end 361.372912 -236.68609)
		(width 0.1143)
		(layer "In11.Cu")
		(net "P5E_CPU0_G3_RX_DN<14>")
	)
	(arc
		(start 361.846114 -244.989858)
		(mid 361.690186 -245.29415)
		(end 361.846114 -245.598442)
		(width 0.1143)
		(layer "In11.Cu")
		(net "P5E_CPU0_G3_RX_DN<14>")
	)
	(arc
		(start 361.446826 -227.009706)
		(mid 361.690153 -227.474272)
		(end 361.446826 -227.938838)
		(width 0.1143)
		(layer "In11.Cu")
		(net "P5E_CPU0_G3_RX_DN<14>")
	)
	(arc
		(start 361.372912 -237.70209)
		(mid 361.218732 -238.004096)
		(end 361.372912 -238.306102)
		(width 0.1143)
		(layer "In11.Cu")
		(net "P5E_CPU0_G3_RX_DN<14>")
	)
	(arc
		(start 361.878372 -245.616984)
		(mid 362.082035 -245.821356)
		(end 362.156502 -246.100092)
		(width 0.1143)
		(layer "In11.Cu")
		(net "P5E_CPU0_G3_RX_DN<14>")
	)
	(arc
		(start 361.375198 -231.220518)
		(mid 361.261269 -231.353665)
		(end 361.220258 -231.524048)
		(width 0.1143)
		(layer "In11.Cu")
		(net "P5E_CPU0_G3_RX_DN<14>")
	)
	(arc
		(start 361.220258 -231.524048)
		(mid 361.261807 -231.69547)
		(end 361.37723 -231.828848)
		(width 0.1143)
		(layer "In11.Cu")
		(net "P5E_CPU0_G3_RX_DN<14>")
	)
	(arc
		(start 361.372912 -232.842054)
		(mid 361.218732 -233.14406)
		(end 361.372912 -233.446066)
		(width 0.1143)
		(layer "In11.Cu")
		(net "P5E_CPU0_G3_RX_DN<14>")
	)
	(arc
		(start 362.38688 -222.14967)
		(mid 362.565693 -222.35202)
		(end 362.630212 -222.614236)
		(width 0.1143)
		(layer "In11.Cu")
		(net "P5E_CPU0_G3_RX_DN<14>")
	)
	(arc
		(start 362.160058 -221.80423)
		(mid 362.163016 -221.851729)
		(end 362.171996 -221.898464)
		(width 0.1143)
		(layer "In11.Cu")
		(net "P5E_CPU0_G3_RX_DN<14>")
	)
	(arc
		(start 361.370626 -229.604824)
		(mid 361.271215 -229.740937)
		(end 361.220766 -229.90175)
		(width 0.1143)
		(layer "In11.Cu")
		(net "P5E_CPU0_G3_RX_DN<14>")
	)
	(arc
		(start 362.620306 -246.808498)
		(mid 362.622329 -246.819908)
		(end 362.624116 -246.831358)
		(width 0.1143)
		(layer "In11.Cu")
		(net "P5E_CPU0_G3_RX_DN<14>")
	)
	(arc
		(start 361.372912 -234.462066)
		(mid 361.218732 -234.764072)
		(end 361.372912 -235.066078)
		(width 0.1143)
		(layer "In11.Cu")
		(net "P5E_CPU0_G3_RX_DN<14>")
	)
	(arc
		(start 361.444286 -230.247952)
		(mid 361.624938 -230.450697)
		(end 361.690158 -230.714296)
		(width 0.1143)
		(layer "In11.Cu")
		(net "P5E_CPU0_G3_RX_DN<14>")
	)
	(arc
		(start 362.226098 -222.016574)
		(mid 362.267081 -222.066436)
		(end 362.316014 -222.108522)
		(width 0.1143)
		(layer "In11.Cu")
		(net "P5E_CPU0_G3_RX_DN<14>")
	)
	(arc
		(start 361.380532 -229.597458)
		(mid 361.375549 -229.6011)
		(end 361.370626 -229.604824)
		(width 0.1143)
		(layer "In11.Cu")
		(net "P5E_CPU0_G3_RX_DN<14>")
	)
	(arc
		(start 361.374944 -242.560602)
		(mid 361.261015 -242.693749)
		(end 361.220004 -242.864132)
		(width 0.1143)
		(layer "In11.Cu")
		(net "P5E_CPU0_G3_RX_DN<14>")
	)
	(arc
		(start 361.446826 -231.869488)
		(mid 361.690153 -232.334054)
		(end 361.446826 -232.79862)
		(width 0.1143)
		(layer "In11.Cu")
		(net "P5E_CPU0_G3_RX_DN<14>")
	)
	(segment
		(start 397.70812 -6.996176)
		(end 397.979138 -6.725158)
		(width 0.12954)
		(layer "F.Cu")
		(net "P5E_CPU0_G3_RX_DN<13>")
	)
	(segment
		(start 397.846804 -8.320024)
		(end 397.846804 -7.709154)
		(width 0.12954)
		(layer "F.Cu")
		(net "P5E_CPU0_G3_RX_DN<13>")
	)
	(segment
		(start 362.53801 -243.940076)
		(end 363.004862 -243.674138)
		(width 0.12954)
		(layer "F.Cu")
		(net "P5E_CPU0_G3_RX_DN<13>")
	)
	(segment
		(start 397.70812 -7.57047)
		(end 397.70812 -6.996176)
		(width 0.12954)
		(layer "F.Cu")
		(net "P5E_CPU0_G3_RX_DN<13>")
	)
	(segment
		(start 397.846804 -7.709154)
		(end 397.70812 -7.57047)
		(width 0.12954)
		(layer "F.Cu")
		(net "P5E_CPU0_G3_RX_DN<13>")
	)
	(segment
		(start 362.38688 -237.658656)
		(end 362.35132 -237.679484)
		(width 0.1143)
		(layer "In11.Cu")
		(net "P5E_CPU0_G3_RX_DN<13>")
	)
	(segment
		(start 362.70692 -243.674138)
		(end 363.004862 -243.674138)
		(width 0.1143)
		(layer "In11.Cu")
		(net "P5E_CPU0_G3_RX_DN<13>")
	)
	(segment
		(start 363.099858 -221.804484)
		(end 363.100112 -221.80423)
		(width 0.1143)
		(layer "In11.Cu")
		(net "P5E_CPU0_G3_RX_DN<13>")
	)
	(segment
		(start 362.34878 -238.327184)
		(end 362.350304 -238.3282)
		(width 0.1143)
		(layer "In11.Cu")
		(net "P5E_CPU0_G3_RX_DN<13>")
	)
	(segment
		(start 362.316014 -231.82834)
		(end 362.347002 -231.84612)
		(width 0.1143)
		(layer "In11.Cu")
		(net "P5E_CPU0_G3_RX_DN<13>")
	)
	(segment
		(start 363.104938 -221.128844)
		(end 363.104938 -221.38767)
		(width 0.1143)
		(layer "In11.Cu")
		(net "P5E_CPU0_G3_RX_DN<13>")
	)
	(segment
		(start 362.316014 -238.308388)
		(end 362.347002 -238.326168)
		(width 0.1143)
		(layer "In11.Cu")
		(net "P5E_CPU0_G3_RX_DN<13>")
	)
	(segment
		(start 362.347764 -235.086652)
		(end 362.34878 -235.08716)
		(width 0.1143)
		(layer "In11.Cu")
		(net "P5E_CPU0_G3_RX_DN<13>")
	)
	(segment
		(start 362.38688 -240.89868)
		(end 362.35132 -240.919508)
		(width 0.1143)
		(layer "In11.Cu")
		(net "P5E_CPU0_G3_RX_DN<13>")
	)
	(segment
		(start 394.72743 -20.43811)
		(end 370.911374 -55.435246)
		(width 0.14224)
		(layer "In11.Cu")
		(net "P5E_CPU0_G3_RX_DN<13>")
	)
	(segment
		(start 310.280558 -147.306538)
		(end 307.909976 -160.799272)
		(width 0.14224)
		(layer "In11.Cu")
		(net "P5E_CPU0_G3_RX_DN<13>")
	)
	(segment
		(start 362.347764 -239.301528)
		(end 362.347002 -239.302036)
		(width 0.1143)
		(layer "In11.Cu")
		(net "P5E_CPU0_G3_RX_DN<13>")
	)
	(segment
		(start 362.34878 -239.947196)
		(end 362.350304 -239.948212)
		(width 0.1143)
		(layer "In11.Cu")
		(net "P5E_CPU0_G3_RX_DN<13>")
	)
	(segment
		(start 362.347764 -233.46664)
		(end 362.34878 -233.467148)
		(width 0.1143)
		(layer "In11.Cu")
		(net "P5E_CPU0_G3_RX_DN<13>")
	)
	(segment
		(start 362.34878 -233.467148)
		(end 362.350304 -233.468164)
		(width 0.1143)
		(layer "In11.Cu")
		(net "P5E_CPU0_G3_RX_DN<13>")
	)
	(segment
		(start 362.38688 -239.278668)
		(end 362.35132 -239.299496)
		(width 0.1143)
		(layer "In11.Cu")
		(net "P5E_CPU0_G3_RX_DN<13>")
	)
	(segment
		(start 363.328712 -222.150432)
		(end 363.339634 -222.158814)
		(width 0.1143)
		(layer "In11.Cu")
		(net "P5E_CPU0_G3_RX_DN<13>")
	)
	(segment
		(start 362.347002 -240.922048)
		(end 362.316014 -240.939828)
		(width 0.1143)
		(layer "In11.Cu")
		(net "P5E_CPU0_G3_RX_DN<13>")
	)
	(segment
		(start 363.339634 -223.069658)
		(end 363.328712 -223.07804)
		(width 0.1143)
		(layer "In11.Cu")
		(net "P5E_CPU0_G3_RX_DN<13>")
	)
	(segment
		(start 362.380784 -229.562406)
		(end 362.38053 -229.56266)
		(width 0.1143)
		(layer "In11.Cu")
		(net "P5E_CPU0_G3_RX_DN<13>")
	)
	(segment
		(start 362.347002 -236.706156)
		(end 362.347764 -236.706664)
		(width 0.1143)
		(layer "In11.Cu")
		(net "P5E_CPU0_G3_RX_DN<13>")
	)
	(segment
		(start 362.34878 -243.18722)
		(end 362.350304 -243.188236)
		(width 0.1143)
		(layer "In11.Cu")
		(net "P5E_CPU0_G3_RX_DN<13>")
	)
	(segment
		(start 395.135608 -18.975832)
		(end 395.135608 -19.235674)
		(width 0.14224)
		(layer "In11.Cu")
		(net "P5E_CPU0_G3_RX_DN<13>")
	)
	(segment
		(start 362.362242 -227.953316)
		(end 362.360718 -227.954332)
		(width 0.1143)
		(layer "In11.Cu")
		(net "P5E_CPU0_G3_RX_DN<13>")
	)
	(segment
		(start 362.38688 -234.418632)
		(end 362.35132 -234.43946)
		(width 0.1143)
		(layer "In11.Cu")
		(net "P5E_CPU0_G3_RX_DN<13>")
	)
	(segment
		(start 362.336334 -228.600254)
		(end 362.347764 -228.606858)
		(width 0.1143)
		(layer "In11.Cu")
		(net "P5E_CPU0_G3_RX_DN<13>")
	)
	(segment
		(start 362.347764 -237.681516)
		(end 362.347002 -237.682024)
		(width 0.1143)
		(layer "In11.Cu")
		(net "P5E_CPU0_G3_RX_DN<13>")
	)
	(segment
		(start 362.350304 -243.188236)
		(end 362.38688 -243.209572)
		(width 0.1143)
		(layer "In11.Cu")
		(net "P5E_CPU0_G3_RX_DN<13>")
	)
	(segment
		(start 362.38688 -231.178862)
		(end 362.314236 -231.22128)
		(width 0.1143)
		(layer "In11.Cu")
		(net "P5E_CPU0_G3_RX_DN<13>")
	)
	(segment
		(start 362.34878 -232.820972)
		(end 362.347764 -232.82148)
		(width 0.1143)
		(layer "In11.Cu")
		(net "P5E_CPU0_G3_RX_DN<13>")
	)
	(segment
		(start 363.100112 -225.042222)
		(end 363.100112 -225.044254)
		(width 0.1143)
		(layer "In11.Cu")
		(net "P5E_CPU0_G3_RX_DN<13>")
	)
	(segment
		(start 362.350304 -235.088176)
		(end 362.38688 -235.109512)
		(width 0.1143)
		(layer "In11.Cu")
		(net "P5E_CPU0_G3_RX_DN<13>")
	)
	(segment
		(start 362.350304 -234.439968)
		(end 362.34878 -234.440984)
		(width 0.1143)
		(layer "In11.Cu")
		(net "P5E_CPU0_G3_RX_DN<13>")
	)
	(segment
		(start 395.135608 -19.235674)
		(end 395.098524 -19.376898)
		(width 0.14224)
		(layer "In11.Cu")
		(net "P5E_CPU0_G3_RX_DN<13>")
	)
	(segment
		(start 363.287818 -224.721674)
		(end 363.287056 -224.722182)
		(width 0.1143)
		(layer "In11.Cu")
		(net "P5E_CPU0_G3_RX_DN<13>")
	)
	(segment
		(start 362.347002 -232.821988)
		(end 362.316014 -232.839768)
		(width 0.1143)
		(layer "In11.Cu")
		(net "P5E_CPU0_G3_RX_DN<13>")
	)
	(segment
		(start 395.098524 -19.376898)
		(end 394.72743 -20.43811)
		(width 0.14224)
		(layer "In11.Cu")
		(net "P5E_CPU0_G3_RX_DN<13>")
	)
	(segment
		(start 363.290104 -224.720404)
		(end 363.287818 -224.721674)
		(width 0.1143)
		(layer "In11.Cu")
		(net "P5E_CPU0_G3_RX_DN<13>")
	)
	(segment
		(start 362.350304 -233.468164)
		(end 362.38688 -233.4895)
		(width 0.1143)
		(layer "In11.Cu")
		(net "P5E_CPU0_G3_RX_DN<13>")
	)
	(segment
		(start 363.099858 -221.39275)
		(end 363.099858 -221.804484)
		(width 0.1143)
		(layer "In11.Cu")
		(net "P5E_CPU0_G3_RX_DN<13>")
	)
	(segment
		(start 362.347764 -231.846628)
		(end 362.34878 -231.847136)
		(width 0.1143)
		(layer "In11.Cu")
		(net "P5E_CPU0_G3_RX_DN<13>")
	)
	(segment
		(start 362.35132 -234.43946)
		(end 362.350304 -234.439968)
		(width 0.1143)
		(layer "In11.Cu")
		(net "P5E_CPU0_G3_RX_DN<13>")
	)
	(segment
		(start 362.347002 -238.326168)
		(end 362.347764 -238.326676)
		(width 0.1143)
		(layer "In11.Cu")
		(net "P5E_CPU0_G3_RX_DN<13>")
	)
	(segment
		(start 362.37926 -227.94341)
		(end 362.378498 -227.943918)
		(width 0.1143)
		(layer "In11.Cu")
		(net "P5E_CPU0_G3_RX_DN<13>")
	)
	(segment
		(start 363.328712 -223.07804)
		(end 363.254544 -223.120966)
		(width 0.1143)
		(layer "In11.Cu")
		(net "P5E_CPU0_G3_RX_DN<13>")
	)
	(segment
		(start 362.35132 -232.819448)
		(end 362.350304 -232.819956)
		(width 0.1143)
		(layer "In11.Cu")
		(net "P5E_CPU0_G3_RX_DN<13>")
	)
	(segment
		(start 363.329474 -223.770698)
		(end 363.341412 -223.780096)
		(width 0.1143)
		(layer "In11.Cu")
		(net "P5E_CPU0_G3_RX_DN<13>")
	)
	(segment
		(start 362.34878 -235.08716)
		(end 362.350304 -235.088176)
		(width 0.1143)
		(layer "In11.Cu")
		(net "P5E_CPU0_G3_RX_DN<13>")
	)
	(segment
		(start 362.296202 -243.1542)
		(end 362.316014 -243.168424)
		(width 0.1143)
		(layer "In11.Cu")
		(net "P5E_CPU0_G3_RX_DN<13>")
	)
	(segment
		(start 362.38688 -232.79862)
		(end 362.35132 -232.819448)
		(width 0.1143)
		(layer "In11.Cu")
		(net "P5E_CPU0_G3_RX_DN<13>")
	)
	(segment
		(start 362.347764 -239.946688)
		(end 362.34878 -239.947196)
		(width 0.1143)
		(layer "In11.Cu")
		(net "P5E_CPU0_G3_RX_DN<13>")
	)
	(segment
		(start 319.62598 -123.9901)
		(end 316.908434 -129.023364)
		(width 0.14224)
		(layer "In11.Cu")
		(net "P5E_CPU0_G3_RX_DN<13>")
	)
	(segment
		(start 362.34878 -226.987354)
		(end 362.38688 -227.009706)
		(width 0.1143)
		(layer "In11.Cu")
		(net "P5E_CPU0_G3_RX_DN<13>")
	)
	(segment
		(start 362.347764 -228.606858)
		(end 362.34878 -228.607366)
		(width 0.1143)
		(layer "In11.Cu")
		(net "P5E_CPU0_G3_RX_DN<13>")
	)
	(segment
		(start 362.316014 -239.9284)
		(end 362.347002 -239.94618)
		(width 0.1143)
		(layer "In11.Cu")
		(net "P5E_CPU0_G3_RX_DN<13>")
	)
	(segment
		(start 363.287818 -222.12681)
		(end 363.288834 -222.127318)
		(width 0.1143)
		(layer "In11.Cu")
		(net "P5E_CPU0_G3_RX_DN<13>")
	)
	(segment
		(start 362.350304 -240.920016)
		(end 362.34878 -240.921032)
		(width 0.1143)
		(layer "In11.Cu")
		(net "P5E_CPU0_G3_RX_DN<13>")
	)
	(segment
		(start 362.353098 -226.338384)
		(end 362.352336 -226.338892)
		(width 0.1143)
		(layer "In11.Cu")
		(net "P5E_CPU0_G3_RX_DN<13>")
	)
	(segment
		(start 362.316014 -241.548412)
		(end 362.347002 -241.566192)
		(width 0.1143)
		(layer "In11.Cu")
		(net "P5E_CPU0_G3_RX_DN<13>")
	)
	(segment
		(start 394.40993 -17.583658)
		(end 394.40993 -17.640554)
		(width 0.14224)
		(layer "In11.Cu")
		(net "P5E_CPU0_G3_RX_DN<13>")
	)
	(segment
		(start 362.352336 -226.338892)
		(end 362.351828 -226.339146)
		(width 0.1143)
		(layer "In11.Cu")
		(net "P5E_CPU0_G3_RX_DN<13>")
	)
	(segment
		(start 362.347764 -232.82148)
		(end 362.347002 -232.821988)
		(width 0.1143)
		(layer "In11.Cu")
		(net "P5E_CPU0_G3_RX_DN<13>")
	)
	(segment
		(start 362.347764 -241.5667)
		(end 362.34878 -241.567208)
		(width 0.1143)
		(layer "In11.Cu")
		(net "P5E_CPU0_G3_RX_DN<13>")
	)
	(segment
		(start 362.350304 -242.540028)
		(end 362.34878 -242.541044)
		(width 0.1143)
		(layer "In11.Cu")
		(net "P5E_CPU0_G3_RX_DN<13>")
	)
	(segment
		(start 362.378498 -227.943918)
		(end 362.362242 -227.953316)
		(width 0.1143)
		(layer "In11.Cu")
		(net "P5E_CPU0_G3_RX_DN<13>")
	)
	(segment
		(start 397.315944 -13.160248)
		(end 394.492226 -17.3863)
		(width 0.14224)
		(layer "In11.Cu")
		(net "P5E_CPU0_G3_RX_DN<13>")
	)
	(segment
		(start 362.347764 -240.92154)
		(end 362.347002 -240.922048)
		(width 0.1143)
		(layer "In11.Cu")
		(net "P5E_CPU0_G3_RX_DN<13>")
	)
	(segment
		(start 394.492226 -17.3863)
		(end 394.40993 -17.583658)
		(width 0.14224)
		(layer "In11.Cu")
		(net "P5E_CPU0_G3_RX_DN<13>")
	)
	(segment
		(start 362.38053 -229.56266)
		(end 362.319316 -229.598474)
		(width 0.1143)
		(layer "In11.Cu")
		(net "P5E_CPU0_G3_RX_DN<13>")
	)
	(segment
		(start 363.285786 -222.12554)
		(end 363.287056 -222.126302)
		(width 0.1143)
		(layer "In11.Cu")
		(net "P5E_CPU0_G3_RX_DN<13>")
	)
	(segment
		(start 310.57723 -169.258234)
		(end 315.04001 -173.722284)
		(width 0.14224)
		(layer "In11.Cu")
		(net "P5E_CPU0_G3_RX_DN<13>")
	)
	(segment
		(start 362.350304 -236.05998)
		(end 362.34878 -236.060996)
		(width 0.1143)
		(layer "In11.Cu")
		(net "P5E_CPU0_G3_RX_DN<13>")
	)
	(segment
		(start 362.350304 -239.300004)
		(end 362.34878 -239.30102)
		(width 0.1143)
		(layer "In11.Cu")
		(net "P5E_CPU0_G3_RX_DN<13>")
	)
	(segment
		(start 362.34878 -242.541044)
		(end 362.347764 -242.541552)
		(width 0.1143)
		(layer "In11.Cu")
		(net "P5E_CPU0_G3_RX_DN<13>")
	)
	(segment
		(start 362.347002 -231.84612)
		(end 362.347764 -231.846628)
		(width 0.1143)
		(layer "In11.Cu")
		(net "P5E_CPU0_G3_RX_DN<13>")
	)
	(segment
		(start 362.352082 -227.959158)
		(end 362.350558 -227.960174)
		(width 0.1143)
		(layer "In11.Cu")
		(net "P5E_CPU0_G3_RX_DN<13>")
	)
	(segment
		(start 362.38688 -229.55885)
		(end 362.380784 -229.562406)
		(width 0.1143)
		(layer "In11.Cu")
		(net "P5E_CPU0_G3_RX_DN<13>")
	)
	(segment
		(start 362.347002 -234.442)
		(end 362.316014 -234.45978)
		(width 0.1143)
		(layer "In11.Cu")
		(net "P5E_CPU0_G3_RX_DN<13>")
	)
	(segment
		(start 307.909976 -162.818064)
		(end 310.57723 -169.258234)
		(width 0.14224)
		(layer "In11.Cu")
		(net "P5E_CPU0_G3_RX_DN<13>")
	)
	(segment
		(start 362.35132 -236.059472)
		(end 362.350304 -236.05998)
		(width 0.1143)
		(layer "In11.Cu")
		(net "P5E_CPU0_G3_RX_DN<13>")
	)
	(segment
		(start 316.908434 -129.023364)
		(end 310.280558 -147.306538)
		(width 0.14224)
		(layer "In11.Cu")
		(net "P5E_CPU0_G3_RX_DN<13>")
	)
	(segment
		(start 362.350304 -236.708188)
		(end 362.38688 -236.729524)
		(width 0.1143)
		(layer "In11.Cu")
		(net "P5E_CPU0_G3_RX_DN<13>")
	)
	(segment
		(start 362.34878 -236.707172)
		(end 362.350304 -236.708188)
		(width 0.1143)
		(layer "In11.Cu")
		(net "P5E_CPU0_G3_RX_DN<13>")
	)
	(segment
		(start 362.34878 -239.30102)
		(end 362.347764 -239.301528)
		(width 0.1143)
		(layer "In11.Cu")
		(net "P5E_CPU0_G3_RX_DN<13>")
	)
	(segment
		(start 362.85678 -225.50882)
		(end 362.787184 -225.54946)
		(width 0.1143)
		(layer "In11.Cu")
		(net "P5E_CPU0_G3_RX_DN<13>")
	)
	(segment
		(start 397.688308 -11.93292)
		(end 397.315944 -13.160248)
		(width 0.14224)
		(layer "In11.Cu")
		(net "P5E_CPU0_G3_RX_DN<13>")
	)
	(segment
		(start 362.347764 -234.441492)
		(end 362.347002 -234.442)
		(width 0.1143)
		(layer "In11.Cu")
		(net "P5E_CPU0_G3_RX_DN<13>")
	)
	(segment
		(start 358.866948 -208.342992)
		(end 363.150658 -215.557862)
		(width 0.14224)
		(layer "In11.Cu")
		(net "P5E_CPU0_G3_RX_DN<13>")
	)
	(segment
		(start 362.34878 -241.567208)
		(end 362.350304 -241.568224)
		(width 0.1143)
		(layer "In11.Cu")
		(net "P5E_CPU0_G3_RX_DN<13>")
	)
	(segment
		(start 362.35132 -237.679484)
		(end 362.350304 -237.679992)
		(width 0.1143)
		(layer "In11.Cu")
		(net "P5E_CPU0_G3_RX_DN<13>")
	)
	(segment
		(start 362.350304 -231.848152)
		(end 362.38688 -231.869488)
		(width 0.1143)
		(layer "In11.Cu")
		(net "P5E_CPU0_G3_RX_DN<13>")
	)
	(segment
		(start 362.347002 -239.94618)
		(end 362.347764 -239.946688)
		(width 0.1143)
		(layer "In11.Cu")
		(net "P5E_CPU0_G3_RX_DN<13>")
	)
	(segment
		(start 394.649198 -18.128742)
		(end 395.069568 -18.757646)
		(width 0.14224)
		(layer "In11.Cu")
		(net "P5E_CPU0_G3_RX_DN<13>")
	)
	(segment
		(start 362.38688 -242.518692)
		(end 362.35132 -242.53952)
		(width 0.1143)
		(layer "In11.Cu")
		(net "P5E_CPU0_G3_RX_DN<13>")
	)
	(segment
		(start 362.347764 -236.706664)
		(end 362.34878 -236.707172)
		(width 0.1143)
		(layer "In11.Cu")
		(net "P5E_CPU0_G3_RX_DN<13>")
	)
	(segment
		(start 362.347002 -241.566192)
		(end 362.347764 -241.5667)
		(width 0.1143)
		(layer "In11.Cu")
		(net "P5E_CPU0_G3_RX_DN<13>")
	)
	(segment
		(start 362.347002 -237.682024)
		(end 362.316014 -237.699804)
		(width 0.1143)
		(layer "In11.Cu")
		(net "P5E_CPU0_G3_RX_DN<13>")
	)
	(segment
		(start 362.34878 -228.607366)
		(end 362.350304 -228.608382)
		(width 0.1143)
		(layer "In11.Cu")
		(net "P5E_CPU0_G3_RX_DN<13>")
	)
	(segment
		(start 363.256068 -222.108522)
		(end 363.285786 -222.12554)
		(width 0.1143)
		(layer "In11.Cu")
		(net "P5E_CPU0_G3_RX_DN<13>")
	)
	(segment
		(start 362.351066 -226.339654)
		(end 362.346494 -226.342194)
		(width 0.1143)
		(layer "In11.Cu")
		(net "P5E_CPU0_G3_RX_DN<13>")
	)
	(segment
		(start 362.386118 -227.939346)
		(end 362.37926 -227.94341)
		(width 0.1143)
		(layer "In11.Cu")
		(net "P5E_CPU0_G3_RX_DN<13>")
	)
	(segment
		(start 363.150658 -221.083124)
		(end 363.104938 -221.128844)
		(width 0.1143)
		(layer "In11.Cu")
		(net "P5E_CPU0_G3_RX_DN<13>")
	)
	(segment
		(start 362.34878 -234.440984)
		(end 362.347764 -234.441492)
		(width 0.1143)
		(layer "In11.Cu")
		(net "P5E_CPU0_G3_RX_DN<13>")
	)
	(segment
		(start 363.255814 -223.728534)
		(end 363.329474 -223.770698)
		(width 0.1143)
		(layer "In11.Cu")
		(net "P5E_CPU0_G3_RX_DN<13>")
	)
	(segment
		(start 362.296202 -236.674152)
		(end 362.316014 -236.688376)
		(width 0.1143)
		(layer "In11.Cu")
		(net "P5E_CPU0_G3_RX_DN<13>")
	)
	(segment
		(start 362.347764 -242.541552)
		(end 362.347002 -242.54206)
		(width 0.1143)
		(layer "In11.Cu")
		(net "P5E_CPU0_G3_RX_DN<13>")
	)
	(segment
		(start 362.350304 -228.608382)
		(end 362.38688 -228.629718)
		(width 0.1143)
		(layer "In11.Cu")
		(net "P5E_CPU0_G3_RX_DN<13>")
	)
	(segment
		(start 321.30238 -177.541428)
		(end 358.866948 -208.342992)
		(width 0.14224)
		(layer "In11.Cu")
		(net "P5E_CPU0_G3_RX_DN<13>")
	)
	(segment
		(start 362.34878 -236.060996)
		(end 362.347764 -236.061504)
		(width 0.1143)
		(layer "In11.Cu")
		(net "P5E_CPU0_G3_RX_DN<13>")
	)
	(segment
		(start 362.316014 -236.079792)
		(end 362.296202 -236.094016)
		(width 0.1143)
		(layer "In11.Cu")
		(net "P5E_CPU0_G3_RX_DN<13>")
	)
	(segment
		(start 363.287056 -222.126302)
		(end 363.287818 -222.12681)
		(width 0.1143)
		(layer "In11.Cu")
		(net "P5E_CPU0_G3_RX_DN<13>")
	)
	(segment
		(start 320.34861 -176.903888)
		(end 321.30238 -177.541428)
		(width 0.14224)
		(layer "In11.Cu")
		(net "P5E_CPU0_G3_RX_DN<13>")
	)
	(segment
		(start 363.256068 -224.739962)
		(end 363.25429 -224.741232)
		(width 0.1143)
		(layer "In11.Cu")
		(net "P5E_CPU0_G3_RX_DN<13>")
	)
	(segment
		(start 397.979138 -6.725158)
		(end 397.688308 -7.015988)
		(width 0.14224)
		(layer "In11.Cu")
		(net "P5E_CPU0_G3_RX_DN<13>")
	)
	(segment
		(start 397.688308 -7.015988)
		(end 397.688308 -11.93292)
		(width 0.14224)
		(layer "In11.Cu")
		(net "P5E_CPU0_G3_RX_DN<13>")
	)
	(segment
		(start 362.347002 -235.086144)
		(end 362.347764 -235.086652)
		(width 0.1143)
		(layer "In11.Cu")
		(net "P5E_CPU0_G3_RX_DN<13>")
	)
	(segment
		(start 362.316014 -235.068364)
		(end 362.347002 -235.086144)
		(width 0.1143)
		(layer "In11.Cu")
		(net "P5E_CPU0_G3_RX_DN<13>")
	)
	(segment
		(start 362.316014 -243.168424)
		(end 362.347002 -243.186204)
		(width 0.1143)
		(layer "In11.Cu")
		(net "P5E_CPU0_G3_RX_DN<13>")
	)
	(segment
		(start 362.350304 -232.819956)
		(end 362.34878 -232.820972)
		(width 0.1143)
		(layer "In11.Cu")
		(net "P5E_CPU0_G3_RX_DN<13>")
	)
	(segment
		(start 362.34878 -227.96119)
		(end 362.336334 -227.968302)
		(width 0.1143)
		(layer "In11.Cu")
		(net "P5E_CPU0_G3_RX_DN<13>")
	)
	(segment
		(start 362.34878 -231.847136)
		(end 362.350304 -231.848152)
		(width 0.1143)
		(layer "In11.Cu")
		(net "P5E_CPU0_G3_RX_DN<13>")
	)
	(segment
		(start 362.316014 -236.688376)
		(end 362.347002 -236.706156)
		(width 0.1143)
		(layer "In11.Cu")
		(net "P5E_CPU0_G3_RX_DN<13>")
	)
	(segment
		(start 362.38688 -236.038644)
		(end 362.35132 -236.059472)
		(width 0.1143)
		(layer "In11.Cu")
		(net "P5E_CPU0_G3_RX_DN<13>")
	)
	(segment
		(start 362.350304 -241.568224)
		(end 362.38688 -241.58956)
		(width 0.1143)
		(layer "In11.Cu")
		(net "P5E_CPU0_G3_RX_DN<13>")
	)
	(segment
		(start 362.349542 -227.960682)
		(end 362.34878 -227.96119)
		(width 0.1143)
		(layer "In11.Cu")
		(net "P5E_CPU0_G3_RX_DN<13>")
	)
	(segment
		(start 362.386118 -226.319334)
		(end 362.353098 -226.338384)
		(width 0.1143)
		(layer "In11.Cu")
		(net "P5E_CPU0_G3_RX_DN<13>")
	)
	(segment
		(start 362.316014 -233.448352)
		(end 362.347002 -233.466132)
		(width 0.1143)
		(layer "In11.Cu")
		(net "P5E_CPU0_G3_RX_DN<13>")
	)
	(segment
		(start 362.347002 -233.466132)
		(end 362.347764 -233.46664)
		(width 0.1143)
		(layer "In11.Cu")
		(net "P5E_CPU0_G3_RX_DN<13>")
	)
	(segment
		(start 363.287056 -224.722182)
		(end 363.256068 -224.739962)
		(width 0.1143)
		(layer "In11.Cu")
		(net "P5E_CPU0_G3_RX_DN<13>")
	)
	(segment
		(start 362.316014 -240.939828)
		(end 362.298234 -240.952528)
		(width 0.1143)
		(layer "In11.Cu")
		(net "P5E_CPU0_G3_RX_DN<13>")
	)
	(segment
		(start 363.150658 -221.054676)
		(end 363.150658 -221.083124)
		(width 0.1143)
		(layer "In11.Cu")
		(net "P5E_CPU0_G3_RX_DN<13>")
	)
	(segment
		(start 363.150658 -215.557862)
		(end 363.150658 -221.054676)
		(width 0.14224)
		(layer "In11.Cu")
		(net "P5E_CPU0_G3_RX_DN<13>")
	)
	(segment
		(start 362.624116 -243.591334)
		(end 362.70692 -243.674138)
		(width 0.1143)
		(layer "In11.Cu")
		(net "P5E_CPU0_G3_RX_DN<13>")
	)
	(segment
		(start 362.347002 -239.302036)
		(end 362.316014 -239.319816)
		(width 0.1143)
		(layer "In11.Cu")
		(net "P5E_CPU0_G3_RX_DN<13>")
	)
	(segment
		(start 362.319062 -230.210106)
		(end 362.38434 -230.247952)
		(width 0.1143)
		(layer "In11.Cu")
		(net "P5E_CPU0_G3_RX_DN<13>")
	)
	(segment
		(start 362.347764 -236.061504)
		(end 362.347002 -236.062012)
		(width 0.1143)
		(layer "In11.Cu")
		(net "P5E_CPU0_G3_RX_DN<13>")
	)
	(segment
		(start 362.34878 -237.681008)
		(end 362.347764 -237.681516)
		(width 0.1143)
		(layer "In11.Cu")
		(net "P5E_CPU0_G3_RX_DN<13>")
	)
	(segment
		(start 363.104938 -221.38767)
		(end 363.099858 -221.39275)
		(width 0.1143)
		(layer "In11.Cu")
		(net "P5E_CPU0_G3_RX_DN<13>")
	)
	(segment
		(start 315.04001 -173.722284)
		(end 320.34861 -176.903888)
		(width 0.14224)
		(layer "In11.Cu")
		(net "P5E_CPU0_G3_RX_DN<13>")
	)
	(segment
		(start 362.347002 -242.54206)
		(end 362.316014 -242.55984)
		(width 0.1143)
		(layer "In11.Cu")
		(net "P5E_CPU0_G3_RX_DN<13>")
	)
	(segment
		(start 307.909976 -160.799272)
		(end 307.909976 -162.818064)
		(width 0.14224)
		(layer "In11.Cu")
		(net "P5E_CPU0_G3_RX_DN<13>")
	)
	(segment
		(start 362.350304 -238.3282)
		(end 362.38688 -238.349536)
		(width 0.1143)
		(layer "In11.Cu")
		(net "P5E_CPU0_G3_RX_DN<13>")
	)
	(segment
		(start 362.350558 -227.960174)
		(end 362.349542 -227.960682)
		(width 0.1143)
		(layer "In11.Cu")
		(net "P5E_CPU0_G3_RX_DN<13>")
	)
	(segment
		(start 362.35132 -240.919508)
		(end 362.350304 -240.920016)
		(width 0.1143)
		(layer "In11.Cu")
		(net "P5E_CPU0_G3_RX_DN<13>")
	)
	(segment
		(start 362.350304 -237.679992)
		(end 362.34878 -237.681008)
		(width 0.1143)
		(layer "In11.Cu")
		(net "P5E_CPU0_G3_RX_DN<13>")
	)
	(segment
		(start 362.351828 -226.339146)
		(end 362.351066 -226.339654)
		(width 0.1143)
		(layer "In11.Cu")
		(net "P5E_CPU0_G3_RX_DN<13>")
	)
	(segment
		(start 362.35132 -239.299496)
		(end 362.350304 -239.300004)
		(width 0.1143)
		(layer "In11.Cu")
		(net "P5E_CPU0_G3_RX_DN<13>")
	)
	(segment
		(start 362.35132 -242.53952)
		(end 362.350304 -242.540028)
		(width 0.1143)
		(layer "In11.Cu")
		(net "P5E_CPU0_G3_RX_DN<13>")
	)
	(segment
		(start 362.347764 -243.186712)
		(end 362.34878 -243.18722)
		(width 0.1143)
		(layer "In11.Cu")
		(net "P5E_CPU0_G3_RX_DN<13>")
	)
	(segment
		(start 395.069568 -18.757646)
		(end 395.135608 -18.975832)
		(width 0.14224)
		(layer "In11.Cu")
		(net "P5E_CPU0_G3_RX_DN<13>")
	)
	(segment
		(start 370.911374 -55.435246)
		(end 319.62598 -123.9901)
		(width 0.14224)
		(layer "In11.Cu")
		(net "P5E_CPU0_G3_RX_DN<13>")
	)
	(segment
		(start 362.298234 -241.535712)
		(end 362.316014 -241.548412)
		(width 0.1143)
		(layer "In11.Cu")
		(net "P5E_CPU0_G3_RX_DN<13>")
	)
	(segment
		(start 362.34878 -240.921032)
		(end 362.347764 -240.92154)
		(width 0.1143)
		(layer "In11.Cu")
		(net "P5E_CPU0_G3_RX_DN<13>")
	)
	(segment
		(start 362.316014 -242.55984)
		(end 362.296202 -242.574064)
		(width 0.1143)
		(layer "In11.Cu")
		(net "P5E_CPU0_G3_RX_DN<13>")
	)
	(segment
		(start 394.481558 -17.81556)
		(end 394.649198 -18.128742)
		(width 0.14224)
		(layer "In11.Cu")
		(net "P5E_CPU0_G3_RX_DN<13>")
	)
	(segment
		(start 362.347002 -243.186204)
		(end 362.347764 -243.186712)
		(width 0.1143)
		(layer "In11.Cu")
		(net "P5E_CPU0_G3_RX_DN<13>")
	)
	(segment
		(start 394.40993 -17.640554)
		(end 394.481558 -17.81556)
		(width 0.14224)
		(layer "In11.Cu")
		(net "P5E_CPU0_G3_RX_DN<13>")
	)
	(segment
		(start 362.360718 -227.954332)
		(end 362.352082 -227.959158)
		(width 0.1143)
		(layer "In11.Cu")
		(net "P5E_CPU0_G3_RX_DN<13>")
	)
	(segment
		(start 362.346748 -226.986338)
		(end 362.34878 -226.987354)
		(width 0.1143)
		(layer "In11.Cu")
		(net "P5E_CPU0_G3_RX_DN<13>")
	)
	(segment
		(start 362.347002 -236.062012)
		(end 362.316014 -236.079792)
		(width 0.1143)
		(layer "In11.Cu")
		(net "P5E_CPU0_G3_RX_DN<13>")
	)
	(segment
		(start 362.347764 -238.326676)
		(end 362.34878 -238.327184)
		(width 0.1143)
		(layer "In11.Cu")
		(net "P5E_CPU0_G3_RX_DN<13>")
	)
	(segment
		(start 363.288834 -222.127318)
		(end 363.328712 -222.150432)
		(width 0.1143)
		(layer "In11.Cu")
		(net "P5E_CPU0_G3_RX_DN<13>")
	)
	(segment
		(start 362.350304 -239.948212)
		(end 362.38688 -239.969548)
		(width 0.1143)
		(layer "In11.Cu")
		(net "P5E_CPU0_G3_RX_DN<13>")
	)
	(arc
		(start 362.336334 -227.968302)
		(mid 362.161384 -228.284278)
		(end 362.336334 -228.600254)
		(width 0.1143)
		(layer "In11.Cu")
		(net "P5E_CPU0_G3_RX_DN<13>")
	)
	(arc
		(start 363.100112 -221.80423)
		(mid 363.10307 -221.851729)
		(end 363.11205 -221.898464)
		(width 0.1143)
		(layer "In11.Cu")
		(net "P5E_CPU0_G3_RX_DN<13>")
	)
	(arc
		(start 362.316014 -232.839768)
		(mid 362.166917 -233.14406)
		(end 362.316014 -233.448352)
		(width 0.1143)
		(layer "In11.Cu")
		(net "P5E_CPU0_G3_RX_DN<13>")
	)
	(arc
		(start 363.166152 -222.016574)
		(mid 363.207135 -222.066436)
		(end 363.256068 -222.108522)
		(width 0.1143)
		(layer "In11.Cu")
		(net "P5E_CPU0_G3_RX_DN<13>")
	)
	(arc
		(start 362.787184 -225.54946)
		(mid 362.671757 -225.682836)
		(end 362.630212 -225.85426)
		(width 0.1143)
		(layer "In11.Cu")
		(net "P5E_CPU0_G3_RX_DN<13>")
	)
	(arc
		(start 362.298234 -240.952528)
		(mid 362.148812 -241.24412)
		(end 362.298234 -241.535712)
		(width 0.1143)
		(layer "In11.Cu")
		(net "P5E_CPU0_G3_RX_DN<13>")
	)
	(arc
		(start 362.296202 -242.574064)
		(mid 362.147488 -242.864132)
		(end 362.296202 -243.1542)
		(width 0.1143)
		(layer "In11.Cu")
		(net "P5E_CPU0_G3_RX_DN<13>")
	)
	(arc
		(start 362.316014 -234.45978)
		(mid 362.166917 -234.764072)
		(end 362.316014 -235.068364)
		(width 0.1143)
		(layer "In11.Cu")
		(net "P5E_CPU0_G3_RX_DN<13>")
	)
	(arc
		(start 362.38688 -235.109512)
		(mid 362.630207 -235.574078)
		(end 362.38688 -236.038644)
		(width 0.1143)
		(layer "In11.Cu")
		(net "P5E_CPU0_G3_RX_DN<13>")
	)
	(arc
		(start 362.38688 -236.729524)
		(mid 362.630207 -237.19409)
		(end 362.38688 -237.658656)
		(width 0.1143)
		(layer "In11.Cu")
		(net "P5E_CPU0_G3_RX_DN<13>")
	)
	(arc
		(start 362.38688 -227.938838)
		(mid 362.386499 -227.939092)
		(end 362.386118 -227.939346)
		(width 0.1143)
		(layer "In11.Cu")
		(net "P5E_CPU0_G3_RX_DN<13>")
	)
	(arc
		(start 363.341412 -223.780096)
		(mid 363.50461 -223.97818)
		(end 363.570012 -224.226374)
		(width 0.1143)
		(layer "In11.Cu")
		(net "P5E_CPU0_G3_RX_DN<13>")
	)
	(arc
		(start 362.38688 -239.969548)
		(mid 362.630207 -240.434114)
		(end 362.38688 -240.89868)
		(width 0.1143)
		(layer "In11.Cu")
		(net "P5E_CPU0_G3_RX_DN<13>")
	)
	(arc
		(start 363.339634 -222.158814)
		(mid 363.571965 -222.614236)
		(end 363.339634 -223.069658)
		(width 0.1143)
		(layer "In11.Cu")
		(net "P5E_CPU0_G3_RX_DN<13>")
	)
	(arc
		(start 363.11205 -221.898464)
		(mid 363.133928 -221.95989)
		(end 363.166152 -222.016574)
		(width 0.1143)
		(layer "In11.Cu")
		(net "P5E_CPU0_G3_RX_DN<13>")
	)
	(arc
		(start 362.346494 -226.342194)
		(mid 362.161169 -226.664376)
		(end 362.346748 -226.986338)
		(width 0.1143)
		(layer "In11.Cu")
		(net "P5E_CPU0_G3_RX_DN<13>")
	)
	(arc
		(start 362.38688 -238.349536)
		(mid 362.630207 -238.814102)
		(end 362.38688 -239.278668)
		(width 0.1143)
		(layer "In11.Cu")
		(net "P5E_CPU0_G3_RX_DN<13>")
	)
	(arc
		(start 362.314236 -231.22128)
		(mid 362.200829 -231.354169)
		(end 362.160058 -231.524048)
		(width 0.1143)
		(layer "In11.Cu")
		(net "P5E_CPU0_G3_RX_DN<13>")
	)
	(arc
		(start 363.25429 -224.741232)
		(mid 363.140885 -224.873127)
		(end 363.100112 -225.042222)
		(width 0.1143)
		(layer "In11.Cu")
		(net "P5E_CPU0_G3_RX_DN<13>")
	)
	(arc
		(start 362.38688 -227.009706)
		(mid 362.630207 -227.474272)
		(end 362.38688 -227.938838)
		(width 0.1143)
		(layer "In11.Cu")
		(net "P5E_CPU0_G3_RX_DN<13>")
	)
	(arc
		(start 362.316014 -237.699804)
		(mid 362.164425 -238.004096)
		(end 362.316014 -238.308388)
		(width 0.1143)
		(layer "In11.Cu")
		(net "P5E_CPU0_G3_RX_DN<13>")
	)
	(arc
		(start 362.249974 -229.660196)
		(mid 362.187018 -229.77768)
		(end 362.16209 -229.908608)
		(width 0.1143)
		(layer "In11.Cu")
		(net "P5E_CPU0_G3_RX_DN<13>")
	)
	(arc
		(start 363.570012 -224.234248)
		(mid 363.495032 -224.514732)
		(end 363.290104 -224.720404)
		(width 0.1143)
		(layer "In11.Cu")
		(net "P5E_CPU0_G3_RX_DN<13>")
	)
	(arc
		(start 362.38688 -233.4895)
		(mid 362.630207 -233.954066)
		(end 362.38688 -234.418632)
		(width 0.1143)
		(layer "In11.Cu")
		(net "P5E_CPU0_G3_RX_DN<13>")
	)
	(arc
		(start 363.254544 -223.120966)
		(mid 363.099967 -223.425054)
		(end 363.255814 -223.728534)
		(width 0.1143)
		(layer "In11.Cu")
		(net "P5E_CPU0_G3_RX_DN<13>")
	)
	(arc
		(start 363.100112 -225.044254)
		(mid 363.035597 -225.306473)
		(end 362.85678 -225.50882)
		(width 0.1143)
		(layer "In11.Cu")
		(net "P5E_CPU0_G3_RX_DN<13>")
	)
	(arc
		(start 362.38688 -243.209572)
		(mid 362.538867 -243.36608)
		(end 362.620306 -243.568474)
		(width 0.1143)
		(layer "In11.Cu")
		(net "P5E_CPU0_G3_RX_DN<13>")
	)
	(arc
		(start 362.296202 -236.094016)
		(mid 362.147488 -236.384084)
		(end 362.296202 -236.674152)
		(width 0.1143)
		(layer "In11.Cu")
		(net "P5E_CPU0_G3_RX_DN<13>")
	)
	(arc
		(start 362.38688 -231.869488)
		(mid 362.630207 -232.334054)
		(end 362.38688 -232.79862)
		(width 0.1143)
		(layer "In11.Cu")
		(net "P5E_CPU0_G3_RX_DN<13>")
	)
	(arc
		(start 362.16209 -229.908608)
		(mid 362.214487 -230.072945)
		(end 362.319062 -230.210106)
		(width 0.1143)
		(layer "In11.Cu")
		(net "P5E_CPU0_G3_RX_DN<13>")
	)
	(arc
		(start 362.160058 -231.524048)
		(mid 362.204129 -231.693584)
		(end 362.316014 -231.82834)
		(width 0.1143)
		(layer "In11.Cu")
		(net "P5E_CPU0_G3_RX_DN<13>")
	)
	(arc
		(start 362.38688 -241.58956)
		(mid 362.630207 -242.054126)
		(end 362.38688 -242.518692)
		(width 0.1143)
		(layer "In11.Cu")
		(net "P5E_CPU0_G3_RX_DN<13>")
	)
	(arc
		(start 362.38688 -228.629718)
		(mid 362.630207 -229.094284)
		(end 362.38688 -229.55885)
		(width 0.1143)
		(layer "In11.Cu")
		(net "P5E_CPU0_G3_RX_DN<13>")
	)
	(arc
		(start 362.630212 -225.85426)
		(mid 362.565697 -226.116479)
		(end 362.38688 -226.318826)
		(width 0.1143)
		(layer "In11.Cu")
		(net "P5E_CPU0_G3_RX_DN<13>")
	)
	(arc
		(start 362.620306 -243.568474)
		(mid 362.622329 -243.579884)
		(end 362.624116 -243.591334)
		(width 0.1143)
		(layer "In11.Cu")
		(net "P5E_CPU0_G3_RX_DN<13>")
	)
	(arc
		(start 362.319316 -229.598474)
		(mid 362.281596 -229.625906)
		(end 362.249974 -229.660196)
		(width 0.1143)
		(layer "In11.Cu")
		(net "P5E_CPU0_G3_RX_DN<13>")
	)
	(arc
		(start 362.38688 -226.318826)
		(mid 362.386499 -226.31908)
		(end 362.386118 -226.319334)
		(width 0.1143)
		(layer "In11.Cu")
		(net "P5E_CPU0_G3_RX_DN<13>")
	)
	(arc
		(start 363.570012 -224.226374)
		(mid 363.570025 -224.230311)
		(end 363.570012 -224.234248)
		(width 0.1143)
		(layer "In11.Cu")
		(net "P5E_CPU0_G3_RX_DN<13>")
	)
	(arc
		(start 362.38434 -230.247952)
		(mid 362.630228 -230.712746)
		(end 362.38688 -231.178862)
		(width 0.1143)
		(layer "In11.Cu")
		(net "P5E_CPU0_G3_RX_DN<13>")
	)
	(arc
		(start 362.316014 -239.319816)
		(mid 362.164425 -239.624108)
		(end 362.316014 -239.9284)
		(width 0.1143)
		(layer "In11.Cu")
		(net "P5E_CPU0_G3_RX_DN<13>")
	)
	(segment
		(start 399.508218 -5.239004)
		(end 399.508218 -7.57047)
		(width 0.12954)
		(layer "F.Cu")
		(net "P5E_CPU0_G3_RX_DN<12>")
	)
	(segment
		(start 399.647156 -7.709408)
		(end 399.646902 -7.709662)
		(width 0.12954)
		(layer "F.Cu")
		(net "P5E_CPU0_G3_RX_DN<12>")
	)
	(segment
		(start 362.53801 -245.560088)
		(end 363.004862 -245.29415)
		(width 0.12954)
		(layer "F.Cu")
		(net "P5E_CPU0_G3_RX_DN<12>")
	)
	(segment
		(start 399.646902 -7.709662)
		(end 399.646902 -8.320024)
		(width 0.12954)
		(layer "F.Cu")
		(net "P5E_CPU0_G3_RX_DN<12>")
	)
	(segment
		(start 399.783808 -4.963414)
		(end 399.508218 -5.239004)
		(width 0.12954)
		(layer "F.Cu")
		(net "P5E_CPU0_G3_RX_DN<12>")
	)
	(segment
		(start 399.508218 -7.57047)
		(end 399.647156 -7.709408)
		(width 0.12954)
		(layer "F.Cu")
		(net "P5E_CPU0_G3_RX_DN<12>")
	)
	(segment
		(start 362.85678 -244.94871)
		(end 362.787184 -244.98935)
		(width 0.1143)
		(layer "In11.Cu")
		(net "P5E_CPU0_G3_RX_DN<12>")
	)
	(segment
		(start 363.320076 -233.485436)
		(end 363.326934 -233.4895)
		(width 0.1143)
		(layer "In11.Cu")
		(net "P5E_CPU0_G3_RX_DN<12>")
	)
	(segment
		(start 364.040166 -221.804484)
		(end 364.04042 -221.80423)
		(width 0.1143)
		(layer "In11.Cu")
		(net "P5E_CPU0_G3_RX_DN<12>")
	)
	(segment
		(start 363.287818 -237.681516)
		(end 363.287056 -237.682024)
		(width 0.1143)
		(layer "In11.Cu")
		(net "P5E_CPU0_G3_RX_DN<12>")
	)
	(segment
		(start 363.326934 -239.278668)
		(end 363.294168 -239.297718)
		(width 0.1143)
		(layer "In11.Cu")
		(net "P5E_CPU0_G3_RX_DN<12>")
	)
	(segment
		(start 363.287056 -227.962206)
		(end 363.285786 -227.962968)
		(width 0.1143)
		(layer "In11.Cu")
		(net "P5E_CPU0_G3_RX_DN<12>")
	)
	(segment
		(start 363.292136 -242.539012)
		(end 363.290358 -242.540028)
		(width 0.1143)
		(layer "In11.Cu")
		(net "P5E_CPU0_G3_RX_DN<12>")
	)
	(segment
		(start 363.256068 -239.9284)
		(end 363.285786 -239.945418)
		(width 0.1143)
		(layer "In11.Cu")
		(net "P5E_CPU0_G3_RX_DN<12>")
	)
	(segment
		(start 363.326934 -244.138704)
		(end 363.294168 -244.157754)
		(width 0.1143)
		(layer "In11.Cu")
		(net "P5E_CPU0_G3_RX_DN<12>")
	)
	(segment
		(start 363.320076 -241.585496)
		(end 363.326934 -241.58956)
		(width 0.1143)
		(layer "In11.Cu")
		(net "P5E_CPU0_G3_RX_DN<12>")
	)
	(segment
		(start 363.283246 -244.164104)
		(end 363.256068 -244.179852)
		(width 0.1143)
		(layer "In11.Cu")
		(net "P5E_CPU0_G3_RX_DN<12>")
	)
	(segment
		(start 364.049564 -221.128844)
		(end 364.049564 -221.38767)
		(width 0.1143)
		(layer "In11.Cu")
		(net "P5E_CPU0_G3_RX_DN<12>")
	)
	(segment
		(start 363.287056 -237.682024)
		(end 363.285786 -237.682786)
		(width 0.1143)
		(layer "In11.Cu")
		(net "P5E_CPU0_G3_RX_DN<12>")
	)
	(segment
		(start 364.095284 -221.054676)
		(end 364.095284 -221.083124)
		(width 0.1143)
		(layer "In11.Cu")
		(net "P5E_CPU0_G3_RX_DN<12>")
	)
	(segment
		(start 363.281722 -226.345242)
		(end 363.279182 -226.346512)
		(width 0.1143)
		(layer "In11.Cu")
		(net "P5E_CPU0_G3_RX_DN<12>")
	)
	(segment
		(start 363.288834 -234.440984)
		(end 363.287818 -234.441492)
		(width 0.1143)
		(layer "In11.Cu")
		(net "P5E_CPU0_G3_RX_DN<12>")
	)
	(segment
		(start 363.287056 -242.54206)
		(end 363.285786 -242.542822)
		(width 0.1143)
		(layer "In11.Cu")
		(net "P5E_CPU0_G3_RX_DN<12>")
	)
	(segment
		(start 363.320076 -238.345472)
		(end 363.326934 -238.349536)
		(width 0.1143)
		(layer "In11.Cu")
		(net "P5E_CPU0_G3_RX_DN<12>")
	)
	(segment
		(start 362.63707 -245.2243)
		(end 362.70692 -245.29415)
		(width 0.1143)
		(layer "In11.Cu")
		(net "P5E_CPU0_G3_RX_DN<12>")
	)
	(segment
		(start 363.285786 -235.085382)
		(end 363.287056 -235.086144)
		(width 0.1143)
		(layer "In11.Cu")
		(net "P5E_CPU0_G3_RX_DN<12>")
	)
	(segment
		(start 364.510066 -224.234248)
		(end 364.509812 -224.234248)
		(width 0.1143)
		(layer "In11.Cu")
		(net "P5E_CPU0_G3_RX_DN<12>")
	)
	(segment
		(start 397.643604 -18.375122)
		(end 397.643858 -18.375122)
		(width 0.14224)
		(layer "In11.Cu")
		(net "P5E_CPU0_G3_RX_DN<12>")
	)
	(segment
		(start 363.288834 -236.060996)
		(end 363.287818 -236.061504)
		(width 0.1143)
		(layer "In11.Cu")
		(net "P5E_CPU0_G3_RX_DN<12>")
	)
	(segment
		(start 363.292136 -237.678976)
		(end 363.290358 -237.679992)
		(width 0.1143)
		(layer "In11.Cu")
		(net "P5E_CPU0_G3_RX_DN<12>")
	)
	(segment
		(start 363.319314 -227.005134)
		(end 363.320076 -227.005642)
		(width 0.1143)
		(layer "In11.Cu")
		(net "P5E_CPU0_G3_RX_DN<12>")
	)
	(segment
		(start 363.290358 -244.16004)
		(end 363.288834 -244.161056)
		(width 0.1143)
		(layer "In11.Cu")
		(net "P5E_CPU0_G3_RX_DN<12>")
	)
	(segment
		(start 364.195868 -223.11995)
		(end 364.175802 -223.134428)
		(width 0.1143)
		(layer "In11.Cu")
		(net "P5E_CPU0_G3_RX_DN<12>")
	)
	(segment
		(start 363.283246 -242.544092)
		(end 363.256068 -242.55984)
		(width 0.1143)
		(layer "In11.Cu")
		(net "P5E_CPU0_G3_RX_DN<12>")
	)
	(segment
		(start 317.76416 -129.419604)
		(end 311.179972 -147.582128)
		(width 0.14224)
		(layer "In11.Cu")
		(net "P5E_CPU0_G3_RX_DN<12>")
	)
	(segment
		(start 363.287818 -243.186712)
		(end 363.319314 -243.205)
		(width 0.1143)
		(layer "In11.Cu")
		(net "P5E_CPU0_G3_RX_DN<12>")
	)
	(segment
		(start 363.288834 -227.96119)
		(end 363.287818 -227.961698)
		(width 0.1143)
		(layer "In11.Cu")
		(net "P5E_CPU0_G3_RX_DN<12>")
	)
	(segment
		(start 364.175802 -223.714056)
		(end 364.195868 -223.728534)
		(width 0.1143)
		(layer "In11.Cu")
		(net "P5E_CPU0_G3_RX_DN<12>")
	)
	(segment
		(start 311.33923 -168.661334)
		(end 311.33923 -168.661588)
		(width 0.14224)
		(layer "In11.Cu")
		(net "P5E_CPU0_G3_RX_DN<12>")
	)
	(segment
		(start 363.294168 -232.81767)
		(end 363.293406 -232.818178)
		(width 0.1143)
		(layer "In11.Cu")
		(net "P5E_CPU0_G3_RX_DN<12>")
	)
	(segment
		(start 363.287818 -242.541552)
		(end 363.287056 -242.54206)
		(width 0.1143)
		(layer "In11.Cu")
		(net "P5E_CPU0_G3_RX_DN<12>")
	)
	(segment
		(start 363.256068 -230.208328)
		(end 363.287818 -230.226616)
		(width 0.1143)
		(layer "In11.Cu")
		(net "P5E_CPU0_G3_RX_DN<12>")
	)
	(segment
		(start 363.287818 -234.441492)
		(end 363.287056 -234.442)
		(width 0.1143)
		(layer "In11.Cu")
		(net "P5E_CPU0_G3_RX_DN<12>")
	)
	(segment
		(start 363.287818 -226.986846)
		(end 363.319314 -227.005134)
		(width 0.1143)
		(layer "In11.Cu")
		(net "P5E_CPU0_G3_RX_DN<12>")
	)
	(segment
		(start 363.2835 -226.344226)
		(end 363.282484 -226.344734)
		(width 0.1143)
		(layer "In11.Cu")
		(net "P5E_CPU0_G3_RX_DN<12>")
	)
	(segment
		(start 363.320076 -239.965484)
		(end 363.326934 -239.969548)
		(width 0.1143)
		(layer "In11.Cu")
		(net "P5E_CPU0_G3_RX_DN<12>")
	)
	(segment
		(start 363.287056 -228.60635)
		(end 363.287818 -228.606858)
		(width 0.1143)
		(layer "In11.Cu")
		(net "P5E_CPU0_G3_RX_DN<12>")
	)
	(segment
		(start 363.319314 -236.724952)
		(end 363.320076 -236.72546)
		(width 0.1143)
		(layer "In11.Cu")
		(net "P5E_CPU0_G3_RX_DN<12>")
	)
	(segment
		(start 363.326934 -242.518692)
		(end 363.294168 -242.537742)
		(width 0.1143)
		(layer "In11.Cu")
		(net "P5E_CPU0_G3_RX_DN<12>")
	)
	(segment
		(start 363.290358 -226.340162)
		(end 363.288834 -226.341178)
		(width 0.1143)
		(layer "In11.Cu")
		(net "P5E_CPU0_G3_RX_DN<12>")
	)
	(segment
		(start 363.326934 -240.89868)
		(end 363.294168 -240.91773)
		(width 0.1143)
		(layer "In11.Cu")
		(net "P5E_CPU0_G3_RX_DN<12>")
	)
	(segment
		(start 363.290358 -237.679992)
		(end 363.288834 -237.681008)
		(width 0.1143)
		(layer "In11.Cu")
		(net "P5E_CPU0_G3_RX_DN<12>")
	)
	(segment
		(start 308.842156 -160.885886)
		(end 308.842156 -162.631882)
		(width 0.14224)
		(layer "In11.Cu")
		(net "P5E_CPU0_G3_RX_DN<12>")
	)
	(segment
		(start 363.288834 -240.921032)
		(end 363.287818 -240.92154)
		(width 0.1143)
		(layer "In11.Cu")
		(net "P5E_CPU0_G3_RX_DN<12>")
	)
	(segment
		(start 363.326934 -237.658656)
		(end 363.294168 -237.677706)
		(width 0.1143)
		(layer "In11.Cu")
		(net "P5E_CPU0_G3_RX_DN<12>")
	)
	(segment
		(start 363.285786 -239.302798)
		(end 363.283246 -239.304068)
		(width 0.1143)
		(layer "In11.Cu")
		(net "P5E_CPU0_G3_RX_DN<12>")
	)
	(segment
		(start 321.037458 -123.721622)
		(end 317.76416 -129.419604)
		(width 0.14224)
		(layer "In11.Cu")
		(net "P5E_CPU0_G3_RX_DN<12>")
	)
	(segment
		(start 363.2962 -226.33686)
		(end 363.291374 -226.339654)
		(width 0.1143)
		(layer "In11.Cu")
		(net "P5E_CPU0_G3_RX_DN<12>")
	)
	(segment
		(start 363.294168 -242.537742)
		(end 363.293406 -242.53825)
		(width 0.1143)
		(layer "In11.Cu")
		(net "P5E_CPU0_G3_RX_DN<12>")
	)
	(segment
		(start 363.287056 -241.566192)
		(end 363.287818 -241.5667)
		(width 0.1143)
		(layer "In11.Cu")
		(net "P5E_CPU0_G3_RX_DN<12>")
	)
	(segment
		(start 363.287818 -232.82148)
		(end 363.287056 -232.821988)
		(width 0.1143)
		(layer "In11.Cu")
		(net "P5E_CPU0_G3_RX_DN<12>")
	)
	(segment
		(start 399.492978 -5.254244)
		(end 399.492978 -11.247374)
		(width 0.14224)
		(layer "In11.Cu")
		(net "P5E_CPU0_G3_RX_DN<12>")
	)
	(segment
		(start 363.293406 -236.058202)
		(end 363.292136 -236.058964)
		(width 0.1143)
		(layer "In11.Cu")
		(net "P5E_CPU0_G3_RX_DN<12>")
	)
	(segment
		(start 364.25886 -223.083628)
		(end 364.258098 -223.084136)
		(width 0.1143)
		(layer "In11.Cu")
		(net "P5E_CPU0_G3_RX_DN<12>")
	)
	(segment
		(start 364.226856 -223.746314)
		(end 364.227618 -223.746822)
		(width 0.1143)
		(layer "In11.Cu")
		(net "P5E_CPU0_G3_RX_DN<12>")
	)
	(segment
		(start 363.287056 -235.086144)
		(end 363.287818 -235.086652)
		(width 0.1143)
		(layer "In11.Cu")
		(net "P5E_CPU0_G3_RX_DN<12>")
	)
	(segment
		(start 363.287056 -239.94618)
		(end 363.287818 -239.946688)
		(width 0.1143)
		(layer "In11.Cu")
		(net "P5E_CPU0_G3_RX_DN<12>")
	)
	(segment
		(start 363.288834 -228.607366)
		(end 363.326934 -228.629718)
		(width 0.1143)
		(layer "In11.Cu")
		(net "P5E_CPU0_G3_RX_DN<12>")
	)
	(segment
		(start 363.285786 -231.845358)
		(end 363.287056 -231.84612)
		(width 0.1143)
		(layer "In11.Cu")
		(net "P5E_CPU0_G3_RX_DN<12>")
	)
	(segment
		(start 363.256068 -236.688376)
		(end 363.285786 -236.705394)
		(width 0.1143)
		(layer "In11.Cu")
		(net "P5E_CPU0_G3_RX_DN<12>")
	)
	(segment
		(start 363.320076 -236.72546)
		(end 363.326934 -236.729524)
		(width 0.1143)
		(layer "In11.Cu")
		(net "P5E_CPU0_G3_RX_DN<12>")
	)
	(segment
		(start 363.256068 -241.548412)
		(end 363.285786 -241.56543)
		(width 0.1143)
		(layer "In11.Cu")
		(net "P5E_CPU0_G3_RX_DN<12>")
	)
	(segment
		(start 363.279182 -226.346512)
		(end 363.256068 -226.359974)
		(width 0.1143)
		(layer "In11.Cu")
		(net "P5E_CPU0_G3_RX_DN<12>")
	)
	(segment
		(start 363.285786 -236.062774)
		(end 363.283246 -236.064044)
		(width 0.1143)
		(layer "In11.Cu")
		(net "P5E_CPU0_G3_RX_DN<12>")
	)
	(segment
		(start 363.326934 -226.318826)
		(end 363.297724 -226.335844)
		(width 0.1143)
		(layer "In11.Cu")
		(net "P5E_CPU0_G3_RX_DN<12>")
	)
	(segment
		(start 363.285786 -234.442762)
		(end 363.283246 -234.444032)
		(width 0.1143)
		(layer "In11.Cu")
		(net "P5E_CPU0_G3_RX_DN<12>")
	)
	(segment
		(start 363.288834 -237.681008)
		(end 363.287818 -237.681516)
		(width 0.1143)
		(layer "In11.Cu")
		(net "P5E_CPU0_G3_RX_DN<12>")
	)
	(segment
		(start 363.285786 -241.56543)
		(end 363.287056 -241.566192)
		(width 0.1143)
		(layer "In11.Cu")
		(net "P5E_CPU0_G3_RX_DN<12>")
	)
	(segment
		(start 363.287056 -233.466132)
		(end 363.287818 -233.46664)
		(width 0.1143)
		(layer "In11.Cu")
		(net "P5E_CPU0_G3_RX_DN<12>")
	)
	(segment
		(start 364.095284 -215.31961)
		(end 364.095284 -221.054676)
		(width 0.14224)
		(layer "In11.Cu")
		(net "P5E_CPU0_G3_RX_DN<12>")
	)
	(segment
		(start 363.293406 -234.43819)
		(end 363.292136 -234.438952)
		(width 0.1143)
		(layer "In11.Cu")
		(net "P5E_CPU0_G3_RX_DN<12>")
	)
	(segment
		(start 363.319314 -239.964976)
		(end 363.320076 -239.965484)
		(width 0.1143)
		(layer "In11.Cu")
		(net "P5E_CPU0_G3_RX_DN<12>")
	)
	(segment
		(start 308.842156 -162.631882)
		(end 311.33923 -168.661334)
		(width 0.14224)
		(layer "In11.Cu")
		(net "P5E_CPU0_G3_RX_DN<12>")
	)
	(segment
		(start 364.228634 -223.74733)
		(end 364.266734 -223.769682)
		(width 0.1143)
		(layer "In11.Cu")
		(net "P5E_CPU0_G3_RX_DN<12>")
	)
	(segment
		(start 363.294168 -234.437682)
		(end 363.293406 -234.43819)
		(width 0.1143)
		(layer "In11.Cu")
		(net "P5E_CPU0_G3_RX_DN<12>")
	)
	(segment
		(start 311.33923 -168.661588)
		(end 315.715904 -173.039278)
		(width 0.14224)
		(layer "In11.Cu")
		(net "P5E_CPU0_G3_RX_DN<12>")
	)
	(segment
		(start 363.288834 -244.161056)
		(end 363.287818 -244.161564)
		(width 0.1143)
		(layer "In11.Cu")
		(net "P5E_CPU0_G3_RX_DN<12>")
	)
	(segment
		(start 363.320076 -235.105448)
		(end 363.326934 -235.109512)
		(width 0.1143)
		(layer "In11.Cu")
		(net "P5E_CPU0_G3_RX_DN<12>")
	)
	(segment
		(start 363.290358 -239.300004)
		(end 363.288834 -239.30102)
		(width 0.1143)
		(layer "In11.Cu")
		(net "P5E_CPU0_G3_RX_DN<12>")
	)
	(segment
		(start 364.095284 -221.083124)
		(end 364.049564 -221.128844)
		(width 0.1143)
		(layer "In11.Cu")
		(net "P5E_CPU0_G3_RX_DN<12>")
	)
	(segment
		(start 364.26648 -224.698814)
		(end 364.196884 -224.739454)
		(width 0.1143)
		(layer "In11.Cu")
		(net "P5E_CPU0_G3_RX_DN<12>")
	)
	(segment
		(start 363.287056 -232.821988)
		(end 363.285786 -232.82275)
		(width 0.1143)
		(layer "In11.Cu")
		(net "P5E_CPU0_G3_RX_DN<12>")
	)
	(segment
		(start 363.287818 -227.961698)
		(end 363.287056 -227.962206)
		(width 0.1143)
		(layer "In11.Cu")
		(net "P5E_CPU0_G3_RX_DN<12>")
	)
	(segment
		(start 364.227618 -223.746822)
		(end 364.228634 -223.74733)
		(width 0.1143)
		(layer "In11.Cu")
		(net "P5E_CPU0_G3_RX_DN<12>")
	)
	(segment
		(start 363.285786 -227.962968)
		(end 363.283246 -227.964238)
		(width 0.1143)
		(layer "In11.Cu")
		(net "P5E_CPU0_G3_RX_DN<12>")
	)
	(segment
		(start 363.256068 -235.068364)
		(end 363.285786 -235.085382)
		(width 0.1143)
		(layer "In11.Cu")
		(net "P5E_CPU0_G3_RX_DN<12>")
	)
	(segment
		(start 397.878808 -17.935702)
		(end 397.643604 -18.375122)
		(width 0.14224)
		(layer "In11.Cu")
		(net "P5E_CPU0_G3_RX_DN<12>")
	)
	(segment
		(start 363.287818 -228.606858)
		(end 363.288834 -228.607366)
		(width 0.1143)
		(layer "In11.Cu")
		(net "P5E_CPU0_G3_RX_DN<12>")
	)
	(segment
		(start 363.290358 -242.540028)
		(end 363.288834 -242.541044)
		(width 0.1143)
		(layer "In11.Cu")
		(net "P5E_CPU0_G3_RX_DN<12>")
	)
	(segment
		(start 363.285786 -239.945418)
		(end 363.287056 -239.94618)
		(width 0.1143)
		(layer "In11.Cu")
		(net "P5E_CPU0_G3_RX_DN<12>")
	)
	(segment
		(start 363.287818 -230.226616)
		(end 363.324394 -230.247952)
		(width 0.1143)
		(layer "In11.Cu")
		(net "P5E_CPU0_G3_RX_DN<12>")
	)
	(segment
		(start 363.287056 -240.922048)
		(end 363.285786 -240.92281)
		(width 0.1143)
		(layer "In11.Cu")
		(net "P5E_CPU0_G3_RX_DN<12>")
	)
	(segment
		(start 363.287818 -236.061504)
		(end 363.287056 -236.062012)
		(width 0.1143)
		(layer "In11.Cu")
		(net "P5E_CPU0_G3_RX_DN<12>")
	)
	(segment
		(start 362.70692 -245.29415)
		(end 363.004862 -245.29415)
		(width 0.1143)
		(layer "In11.Cu")
		(net "P5E_CPU0_G3_RX_DN<12>")
	)
	(segment
		(start 363.285786 -236.705394)
		(end 363.287056 -236.706156)
		(width 0.1143)
		(layer "In11.Cu")
		(net "P5E_CPU0_G3_RX_DN<12>")
	)
	(segment
		(start 363.279182 -228.601524)
		(end 363.283246 -228.604064)
		(width 0.1143)
		(layer "In11.Cu")
		(net "P5E_CPU0_G3_RX_DN<12>")
	)
	(segment
		(start 363.326934 -231.178862)
		(end 363.25429 -231.22128)
		(width 0.1143)
		(layer "In11.Cu")
		(net "P5E_CPU0_G3_RX_DN<12>")
	)
	(segment
		(start 363.256068 -243.168424)
		(end 363.285786 -243.185442)
		(width 0.1143)
		(layer "In11.Cu")
		(net "P5E_CPU0_G3_RX_DN<12>")
	)
	(segment
		(start 363.292136 -236.058964)
		(end 363.290358 -236.05998)
		(width 0.1143)
		(layer "In11.Cu")
		(net "P5E_CPU0_G3_RX_DN<12>")
	)
	(segment
		(start 363.283246 -232.82402)
		(end 363.256068 -232.839768)
		(width 0.1143)
		(layer "In11.Cu")
		(net "P5E_CPU0_G3_RX_DN<12>")
	)
	(segment
		(start 363.256068 -231.82834)
		(end 363.285786 -231.845358)
		(width 0.1143)
		(layer "In11.Cu")
		(net "P5E_CPU0_G3_RX_DN<12>")
	)
	(segment
		(start 363.290358 -234.439968)
		(end 363.288834 -234.440984)
		(width 0.1143)
		(layer "In11.Cu")
		(net "P5E_CPU0_G3_RX_DN<12>")
	)
	(segment
		(start 363.285786 -232.82275)
		(end 363.283246 -232.82402)
		(width 0.1143)
		(layer "In11.Cu")
		(net "P5E_CPU0_G3_RX_DN<12>")
	)
	(segment
		(start 363.285786 -243.185442)
		(end 363.287056 -243.186204)
		(width 0.1143)
		(layer "In11.Cu")
		(net "P5E_CPU0_G3_RX_DN<12>")
	)
	(segment
		(start 363.287818 -233.46664)
		(end 363.319314 -233.484928)
		(width 0.1143)
		(layer "In11.Cu")
		(net "P5E_CPU0_G3_RX_DN<12>")
	)
	(segment
		(start 363.287056 -244.162072)
		(end 363.285786 -244.162834)
		(width 0.1143)
		(layer "In11.Cu")
		(net "P5E_CPU0_G3_RX_DN<12>")
	)
	(segment
		(start 363.288834 -242.541044)
		(end 363.287818 -242.541552)
		(width 0.1143)
		(layer "In11.Cu")
		(net "P5E_CPU0_G3_RX_DN<12>")
	)
	(segment
		(start 363.288834 -231.847136)
		(end 363.326934 -231.869488)
		(width 0.1143)
		(layer "In11.Cu")
		(net "P5E_CPU0_G3_RX_DN<12>")
	)
	(segment
		(start 363.293406 -237.678214)
		(end 363.292136 -237.678976)
		(width 0.1143)
		(layer "In11.Cu")
		(net "P5E_CPU0_G3_RX_DN<12>")
	)
	(segment
		(start 363.320076 -243.205508)
		(end 363.326934 -243.209572)
		(width 0.1143)
		(layer "In11.Cu")
		(net "P5E_CPU0_G3_RX_DN<12>")
	)
	(segment
		(start 363.283246 -236.064044)
		(end 363.256068 -236.079792)
		(width 0.1143)
		(layer "In11.Cu")
		(net "P5E_CPU0_G3_RX_DN<12>")
	)
	(segment
		(start 363.288834 -239.30102)
		(end 363.287818 -239.301528)
		(width 0.1143)
		(layer "In11.Cu")
		(net "P5E_CPU0_G3_RX_DN<12>")
	)
	(segment
		(start 363.287818 -239.946688)
		(end 363.319314 -239.964976)
		(width 0.1143)
		(layer "In11.Cu")
		(net "P5E_CPU0_G3_RX_DN<12>")
	)
	(segment
		(start 363.757718 -225.53168)
		(end 363.727238 -225.54946)
		(width 0.1143)
		(layer "In11.Cu")
		(net "P5E_CPU0_G3_RX_DN<12>")
	)
	(segment
		(start 364.509812 -224.234248)
		(end 364.508288 -224.258886)
		(width 0.1143)
		(layer "In11.Cu")
		(net "P5E_CPU0_G3_RX_DN<12>")
	)
	(segment
		(start 363.287818 -239.301528)
		(end 363.287056 -239.302036)
		(width 0.1143)
		(layer "In11.Cu")
		(net "P5E_CPU0_G3_RX_DN<12>")
	)
	(segment
		(start 363.285786 -233.46537)
		(end 363.287056 -233.466132)
		(width 0.1143)
		(layer "In11.Cu")
		(net "P5E_CPU0_G3_RX_DN<12>")
	)
	(segment
		(start 363.287056 -243.186204)
		(end 363.287818 -243.186712)
		(width 0.1143)
		(layer "In11.Cu")
		(net "P5E_CPU0_G3_RX_DN<12>")
	)
	(segment
		(start 359.571036 -207.700118)
		(end 364.095284 -215.31961)
		(width 0.14224)
		(layer "In11.Cu")
		(net "P5E_CPU0_G3_RX_DN<12>")
	)
	(segment
		(start 363.283246 -239.304068)
		(end 363.256068 -239.319816)
		(width 0.1143)
		(layer "In11.Cu")
		(net "P5E_CPU0_G3_RX_DN<12>")
	)
	(segment
		(start 363.283246 -227.964238)
		(end 363.256068 -227.979986)
		(width 0.1143)
		(layer "In11.Cu")
		(net "P5E_CPU0_G3_RX_DN<12>")
	)
	(segment
		(start 363.292136 -239.298988)
		(end 363.290358 -239.300004)
		(width 0.1143)
		(layer "In11.Cu")
		(net "P5E_CPU0_G3_RX_DN<12>")
	)
	(segment
		(start 363.287056 -236.062012)
		(end 363.285786 -236.062774)
		(width 0.1143)
		(layer "In11.Cu")
		(net "P5E_CPU0_G3_RX_DN<12>")
	)
	(segment
		(start 363.287056 -226.342194)
		(end 363.284262 -226.343718)
		(width 0.1143)
		(layer "In11.Cu")
		(net "P5E_CPU0_G3_RX_DN<12>")
	)
	(segment
		(start 363.288834 -226.341178)
		(end 363.287818 -226.341686)
		(width 0.1143)
		(layer "In11.Cu")
		(net "P5E_CPU0_G3_RX_DN<12>")
	)
	(segment
		(start 363.294168 -240.91773)
		(end 363.293406 -240.918238)
		(width 0.1143)
		(layer "In11.Cu")
		(net "P5E_CPU0_G3_RX_DN<12>")
	)
	(segment
		(start 363.294168 -239.297718)
		(end 363.293406 -239.298226)
		(width 0.1143)
		(layer "In11.Cu")
		(net "P5E_CPU0_G3_RX_DN<12>")
	)
	(segment
		(start 363.291374 -226.339654)
		(end 363.290358 -226.340162)
		(width 0.1143)
		(layer "In11.Cu")
		(net "P5E_CPU0_G3_RX_DN<12>")
	)
	(segment
		(start 363.290358 -236.05998)
		(end 363.288834 -236.060996)
		(width 0.1143)
		(layer "In11.Cu")
		(net "P5E_CPU0_G3_RX_DN<12>")
	)
	(segment
		(start 363.297724 -226.335844)
		(end 363.2962 -226.33686)
		(width 0.1143)
		(layer "In11.Cu")
		(net "P5E_CPU0_G3_RX_DN<12>")
	)
	(segment
		(start 363.293406 -242.53825)
		(end 363.292136 -242.539012)
		(width 0.1143)
		(layer "In11.Cu")
		(net "P5E_CPU0_G3_RX_DN<12>")
	)
	(segment
		(start 364.040166 -221.397068)
		(end 364.040166 -221.804484)
		(width 0.1143)
		(layer "In11.Cu")
		(net "P5E_CPU0_G3_RX_DN<12>")
	)
	(segment
		(start 363.326934 -227.938838)
		(end 363.288834 -227.96119)
		(width 0.1143)
		(layer "In11.Cu")
		(net "P5E_CPU0_G3_RX_DN<12>")
	)
	(segment
		(start 363.256068 -228.58857)
		(end 363.279182 -228.601524)
		(width 0.1143)
		(layer "In11.Cu")
		(net "P5E_CPU0_G3_RX_DN<12>")
	)
	(segment
		(start 363.287056 -231.84612)
		(end 363.287818 -231.846628)
		(width 0.1143)
		(layer "In11.Cu")
		(net "P5E_CPU0_G3_RX_DN<12>")
	)
	(segment
		(start 363.285786 -237.682786)
		(end 363.283246 -237.684056)
		(width 0.1143)
		(layer "In11.Cu")
		(net "P5E_CPU0_G3_RX_DN<12>")
	)
	(segment
		(start 363.287056 -226.986338)
		(end 363.287818 -226.986846)
		(width 0.1143)
		(layer "In11.Cu")
		(net "P5E_CPU0_G3_RX_DN<12>")
	)
	(segment
		(start 363.293406 -232.818178)
		(end 363.292136 -232.81894)
		(width 0.1143)
		(layer "In11.Cu")
		(net "P5E_CPU0_G3_RX_DN<12>")
	)
	(segment
		(start 363.285786 -242.542822)
		(end 363.283246 -242.544092)
		(width 0.1143)
		(layer "In11.Cu")
		(net "P5E_CPU0_G3_RX_DN<12>")
	)
	(segment
		(start 363.319314 -238.344964)
		(end 363.320076 -238.345472)
		(width 0.1143)
		(layer "In11.Cu")
		(net "P5E_CPU0_G3_RX_DN<12>")
	)
	(segment
		(start 363.287056 -234.442)
		(end 363.285786 -234.442762)
		(width 0.1143)
		(layer "In11.Cu")
		(net "P5E_CPU0_G3_RX_DN<12>")
	)
	(segment
		(start 397.643858 -18.375122)
		(end 371.988588 -56.27497)
		(width 0.14224)
		(layer "In11.Cu")
		(net "P5E_CPU0_G3_RX_DN<12>")
	)
	(segment
		(start 363.79404 -225.510598)
		(end 363.757718 -225.53168)
		(width 0.1143)
		(layer "In11.Cu")
		(net "P5E_CPU0_G3_RX_DN<12>")
	)
	(segment
		(start 363.326934 -236.038644)
		(end 363.294168 -236.057694)
		(width 0.1143)
		(layer "In11.Cu")
		(net "P5E_CPU0_G3_RX_DN<12>")
	)
	(segment
		(start 363.326934 -234.418632)
		(end 363.294168 -234.437682)
		(width 0.1143)
		(layer "In11.Cu")
		(net "P5E_CPU0_G3_RX_DN<12>")
	)
	(segment
		(start 363.292136 -232.81894)
		(end 363.290358 -232.819956)
		(width 0.1143)
		(layer "In11.Cu")
		(net "P5E_CPU0_G3_RX_DN<12>")
	)
	(segment
		(start 363.283246 -237.684056)
		(end 363.256068 -237.699804)
		(width 0.1143)
		(layer "In11.Cu")
		(net "P5E_CPU0_G3_RX_DN<12>")
	)
	(segment
		(start 363.294168 -244.157754)
		(end 363.293406 -244.158262)
		(width 0.1143)
		(layer "In11.Cu")
		(net "P5E_CPU0_G3_RX_DN<12>")
	)
	(segment
		(start 363.256068 -226.968558)
		(end 363.287056 -226.986338)
		(width 0.1143)
		(layer "In11.Cu")
		(net "P5E_CPU0_G3_RX_DN<12>")
	)
	(segment
		(start 363.293406 -240.918238)
		(end 363.292136 -240.919)
		(width 0.1143)
		(layer "In11.Cu")
		(net "P5E_CPU0_G3_RX_DN<12>")
	)
	(segment
		(start 363.285786 -240.92281)
		(end 363.283246 -240.92408)
		(width 0.1143)
		(layer "In11.Cu")
		(net "P5E_CPU0_G3_RX_DN<12>")
	)
	(segment
		(start 363.293406 -239.298226)
		(end 363.292136 -239.298988)
		(width 0.1143)
		(layer "In11.Cu")
		(net "P5E_CPU0_G3_RX_DN<12>")
	)
	(segment
		(start 364.223046 -223.744028)
		(end 364.223808 -223.744536)
		(width 0.1143)
		(layer "In11.Cu")
		(net "P5E_CPU0_G3_RX_DN<12>")
	)
	(segment
		(start 363.287818 -240.92154)
		(end 363.287056 -240.922048)
		(width 0.1143)
		(layer "In11.Cu")
		(net "P5E_CPU0_G3_RX_DN<12>")
	)
	(segment
		(start 363.283246 -228.604064)
		(end 363.287056 -228.60635)
		(width 0.1143)
		(layer "In11.Cu")
		(net "P5E_CPU0_G3_RX_DN<12>")
	)
	(segment
		(start 364.258098 -223.084136)
		(end 364.195868 -223.11995)
		(width 0.1143)
		(layer "In11.Cu")
		(net "P5E_CPU0_G3_RX_DN<12>")
	)
	(segment
		(start 363.292136 -240.919)
		(end 363.290358 -240.920016)
		(width 0.1143)
		(layer "In11.Cu")
		(net "P5E_CPU0_G3_RX_DN<12>")
	)
	(segment
		(start 320.839338 -176.110138)
		(end 321.864736 -176.795684)
		(width 0.14224)
		(layer "In11.Cu")
		(net "P5E_CPU0_G3_RX_DN<12>")
	)
	(segment
		(start 363.294168 -237.677706)
		(end 363.293406 -237.678214)
		(width 0.1143)
		(layer "In11.Cu")
		(net "P5E_CPU0_G3_RX_DN<12>")
	)
	(segment
		(start 363.290358 -232.819956)
		(end 363.288834 -232.820972)
		(width 0.1143)
		(layer "In11.Cu")
		(net "P5E_CPU0_G3_RX_DN<12>")
	)
	(segment
		(start 363.294168 -236.057694)
		(end 363.293406 -236.058202)
		(width 0.1143)
		(layer "In11.Cu")
		(net "P5E_CPU0_G3_RX_DN<12>")
	)
	(segment
		(start 363.256068 -238.308388)
		(end 363.285786 -238.325406)
		(width 0.1143)
		(layer "In11.Cu")
		(net "P5E_CPU0_G3_RX_DN<12>")
	)
	(segment
		(start 363.319314 -241.584988)
		(end 363.320076 -241.585496)
		(width 0.1143)
		(layer "In11.Cu")
		(net "P5E_CPU0_G3_RX_DN<12>")
	)
	(segment
		(start 363.287818 -238.326676)
		(end 363.319314 -238.344964)
		(width 0.1143)
		(layer "In11.Cu")
		(net "P5E_CPU0_G3_RX_DN<12>")
	)
	(segment
		(start 363.283246 -240.92408)
		(end 363.256068 -240.939828)
		(width 0.1143)
		(layer "In11.Cu")
		(net "P5E_CPU0_G3_RX_DN<12>")
	)
	(segment
		(start 363.287818 -226.341686)
		(end 363.287056 -226.342194)
		(width 0.1143)
		(layer "In11.Cu")
		(net "P5E_CPU0_G3_RX_DN<12>")
	)
	(segment
		(start 363.319314 -235.10494)
		(end 363.320076 -235.105448)
		(width 0.1143)
		(layer "In11.Cu")
		(net "P5E_CPU0_G3_RX_DN<12>")
	)
	(segment
		(start 363.320076 -227.005642)
		(end 363.326934 -227.009706)
		(width 0.1143)
		(layer "In11.Cu")
		(net "P5E_CPU0_G3_RX_DN<12>")
	)
	(segment
		(start 363.287818 -236.706664)
		(end 363.319314 -236.724952)
		(width 0.1143)
		(layer "In11.Cu")
		(net "P5E_CPU0_G3_RX_DN<12>")
	)
	(segment
		(start 321.864736 -176.795684)
		(end 359.571036 -207.700118)
		(width 0.14224)
		(layer "In11.Cu")
		(net "P5E_CPU0_G3_RX_DN<12>")
	)
	(segment
		(start 364.195868 -223.728534)
		(end 364.223046 -223.744028)
		(width 0.1143)
		(layer "In11.Cu")
		(net "P5E_CPU0_G3_RX_DN<12>")
	)
	(segment
		(start 363.326934 -232.79862)
		(end 363.294168 -232.81767)
		(width 0.1143)
		(layer "In11.Cu")
		(net "P5E_CPU0_G3_RX_DN<12>")
	)
	(segment
		(start 371.987826 -56.275478)
		(end 321.037458 -123.721622)
		(width 0.14224)
		(layer "In11.Cu")
		(net "P5E_CPU0_G3_RX_DN<12>")
	)
	(segment
		(start 363.292136 -234.438952)
		(end 363.290358 -234.439968)
		(width 0.1143)
		(layer "In11.Cu")
		(net "P5E_CPU0_G3_RX_DN<12>")
	)
	(segment
		(start 364.225586 -223.745552)
		(end 364.226856 -223.746314)
		(width 0.1143)
		(layer "In11.Cu")
		(net "P5E_CPU0_G3_RX_DN<12>")
	)
	(segment
		(start 364.049564 -221.38767)
		(end 364.040166 -221.397068)
		(width 0.1143)
		(layer "In11.Cu")
		(net "P5E_CPU0_G3_RX_DN<12>")
	)
	(segment
		(start 399.492978 -11.247374)
		(end 398.424654 -16.617696)
		(width 0.14224)
		(layer "In11.Cu")
		(net "P5E_CPU0_G3_RX_DN<12>")
	)
	(segment
		(start 311.179972 -147.582128)
		(end 308.842156 -160.885886)
		(width 0.14224)
		(layer "In11.Cu")
		(net "P5E_CPU0_G3_RX_DN<12>")
	)
	(segment
		(start 363.292136 -244.159024)
		(end 363.290358 -244.16004)
		(width 0.1143)
		(layer "In11.Cu")
		(net "P5E_CPU0_G3_RX_DN<12>")
	)
	(segment
		(start 363.319314 -243.205)
		(end 363.320076 -243.205508)
		(width 0.1143)
		(layer "In11.Cu")
		(net "P5E_CPU0_G3_RX_DN<12>")
	)
	(segment
		(start 363.284262 -226.343718)
		(end 363.2835 -226.344226)
		(width 0.1143)
		(layer "In11.Cu")
		(net "P5E_CPU0_G3_RX_DN<12>")
	)
	(segment
		(start 363.319314 -233.484928)
		(end 363.320076 -233.485436)
		(width 0.1143)
		(layer "In11.Cu")
		(net "P5E_CPU0_G3_RX_DN<12>")
	)
	(segment
		(start 363.287818 -231.846628)
		(end 363.288834 -231.847136)
		(width 0.1143)
		(layer "In11.Cu")
		(net "P5E_CPU0_G3_RX_DN<12>")
	)
	(segment
		(start 363.285786 -238.325406)
		(end 363.287056 -238.326168)
		(width 0.1143)
		(layer "In11.Cu")
		(net "P5E_CPU0_G3_RX_DN<12>")
	)
	(segment
		(start 363.287056 -239.302036)
		(end 363.285786 -239.302798)
		(width 0.1143)
		(layer "In11.Cu")
		(net "P5E_CPU0_G3_RX_DN<12>")
	)
	(segment
		(start 363.287818 -241.5667)
		(end 363.319314 -241.584988)
		(width 0.1143)
		(layer "In11.Cu")
		(net "P5E_CPU0_G3_RX_DN<12>")
	)
	(segment
		(start 315.715904 -173.039278)
		(end 320.839338 -176.110138)
		(width 0.14224)
		(layer "In11.Cu")
		(net "P5E_CPU0_G3_RX_DN<12>")
	)
	(segment
		(start 363.293406 -244.158262)
		(end 363.292136 -244.159024)
		(width 0.1143)
		(layer "In11.Cu")
		(net "P5E_CPU0_G3_RX_DN<12>")
	)
	(segment
		(start 363.288834 -232.820972)
		(end 363.287818 -232.82148)
		(width 0.1143)
		(layer "In11.Cu")
		(net "P5E_CPU0_G3_RX_DN<12>")
	)
	(segment
		(start 363.282484 -226.344734)
		(end 363.281722 -226.345242)
		(width 0.1143)
		(layer "In11.Cu")
		(net "P5E_CPU0_G3_RX_DN<12>")
	)
	(segment
		(start 363.326934 -229.55885)
		(end 363.25429 -229.601268)
		(width 0.1143)
		(layer "In11.Cu")
		(net "P5E_CPU0_G3_RX_DN<12>")
	)
	(segment
		(start 363.287818 -244.161564)
		(end 363.287056 -244.162072)
		(width 0.1143)
		(layer "In11.Cu")
		(net "P5E_CPU0_G3_RX_DN<12>")
	)
	(segment
		(start 363.290358 -240.920016)
		(end 363.288834 -240.921032)
		(width 0.1143)
		(layer "In11.Cu")
		(net "P5E_CPU0_G3_RX_DN<12>")
	)
	(segment
		(start 363.287818 -235.086652)
		(end 363.319314 -235.10494)
		(width 0.1143)
		(layer "In11.Cu")
		(net "P5E_CPU0_G3_RX_DN<12>")
	)
	(segment
		(start 364.236254 -222.144336)
		(end 364.31982 -222.192596)
		(width 0.1143)
		(layer "In11.Cu")
		(net "P5E_CPU0_G3_RX_DN<12>")
	)
	(segment
		(start 398.424654 -16.617696)
		(end 397.878808 -17.935702)
		(width 0.14224)
		(layer "In11.Cu")
		(net "P5E_CPU0_G3_RX_DN<12>")
	)
	(segment
		(start 363.283246 -234.444032)
		(end 363.256068 -234.45978)
		(width 0.1143)
		(layer "In11.Cu")
		(net "P5E_CPU0_G3_RX_DN<12>")
	)
	(segment
		(start 399.783808 -4.963414)
		(end 399.492978 -5.254244)
		(width 0.14224)
		(layer "In11.Cu")
		(net "P5E_CPU0_G3_RX_DN<12>")
	)
	(segment
		(start 363.287056 -236.706156)
		(end 363.287818 -236.706664)
		(width 0.1143)
		(layer "In11.Cu")
		(net "P5E_CPU0_G3_RX_DN<12>")
	)
	(segment
		(start 364.223808 -223.744536)
		(end 364.225586 -223.745552)
		(width 0.1143)
		(layer "In11.Cu")
		(net "P5E_CPU0_G3_RX_DN<12>")
	)
	(segment
		(start 371.988588 -56.27497)
		(end 371.987826 -56.275478)
		(width 0.14224)
		(layer "In11.Cu")
		(net "P5E_CPU0_G3_RX_DN<12>")
	)
	(segment
		(start 363.287056 -238.326168)
		(end 363.287818 -238.326676)
		(width 0.1143)
		(layer "In11.Cu")
		(net "P5E_CPU0_G3_RX_DN<12>")
	)
	(segment
		(start 364.265464 -223.079818)
		(end 364.25886 -223.083628)
		(width 0.1143)
		(layer "In11.Cu")
		(net "P5E_CPU0_G3_RX_DN<12>")
	)
	(segment
		(start 363.285786 -244.162834)
		(end 363.283246 -244.164104)
		(width 0.1143)
		(layer "In11.Cu")
		(net "P5E_CPU0_G3_RX_DN<12>")
	)
	(segment
		(start 363.256068 -233.448352)
		(end 363.285786 -233.46537)
		(width 0.1143)
		(layer "In11.Cu")
		(net "P5E_CPU0_G3_RX_DN<12>")
	)
	(arc
		(start 363.256068 -240.939828)
		(mid 363.10014 -241.24412)
		(end 363.256068 -241.548412)
		(width 0.1143)
		(layer "In11.Cu")
		(net "P5E_CPU0_G3_RX_DN<12>")
	)
	(arc
		(start 363.326934 -243.209572)
		(mid 363.570261 -243.674138)
		(end 363.326934 -244.138704)
		(width 0.1143)
		(layer "In11.Cu")
		(net "P5E_CPU0_G3_RX_DN<12>")
	)
	(arc
		(start 364.507018 -224.26803)
		(mid 364.435857 -224.489661)
		(end 364.295944 -224.6757)
		(width 0.1143)
		(layer "In11.Cu")
		(net "P5E_CPU0_G3_RX_DN<12>")
	)
	(arc
		(start 363.256068 -242.55984)
		(mid 363.10014 -242.864132)
		(end 363.256068 -243.168424)
		(width 0.1143)
		(layer "In11.Cu")
		(net "P5E_CPU0_G3_RX_DN<12>")
	)
	(arc
		(start 363.256068 -236.079792)
		(mid 363.10014 -236.384084)
		(end 363.256068 -236.688376)
		(width 0.1143)
		(layer "In11.Cu")
		(net "P5E_CPU0_G3_RX_DN<12>")
	)
	(arc
		(start 363.256068 -232.839768)
		(mid 363.10014 -233.14406)
		(end 363.256068 -233.448352)
		(width 0.1143)
		(layer "In11.Cu")
		(net "P5E_CPU0_G3_RX_DN<12>")
	)
	(arc
		(start 363.100112 -231.524048)
		(mid 363.141367 -231.695019)
		(end 363.256068 -231.82834)
		(width 0.1143)
		(layer "In11.Cu")
		(net "P5E_CPU0_G3_RX_DN<12>")
	)
	(arc
		(start 363.326934 -239.969548)
		(mid 363.570261 -240.434114)
		(end 363.326934 -240.89868)
		(width 0.1143)
		(layer "In11.Cu")
		(net "P5E_CPU0_G3_RX_DN<12>")
	)
	(arc
		(start 364.508288 -224.258886)
		(mid 364.507668 -224.26346)
		(end 364.507018 -224.26803)
		(width 0.1143)
		(layer "In11.Cu")
		(net "P5E_CPU0_G3_RX_DN<12>")
	)
	(arc
		(start 363.727238 -225.54946)
		(mid 363.611811 -225.682836)
		(end 363.570266 -225.85426)
		(width 0.1143)
		(layer "In11.Cu")
		(net "P5E_CPU0_G3_RX_DN<12>")
	)
	(arc
		(start 364.279434 -223.069912)
		(mid 364.272487 -223.074918)
		(end 364.265464 -223.079818)
		(width 0.1143)
		(layer "In11.Cu")
		(net "P5E_CPU0_G3_RX_DN<12>")
	)
	(arc
		(start 363.25429 -231.22128)
		(mid 363.140883 -231.354169)
		(end 363.100112 -231.524048)
		(width 0.1143)
		(layer "In11.Cu")
		(net "P5E_CPU0_G3_RX_DN<12>")
	)
	(arc
		(start 363.100112 -244.484144)
		(mid 363.035597 -244.746363)
		(end 362.85678 -244.94871)
		(width 0.1143)
		(layer "In11.Cu")
		(net "P5E_CPU0_G3_RX_DN<12>")
	)
	(arc
		(start 363.324394 -230.247952)
		(mid 363.505046 -230.450697)
		(end 363.570266 -230.714296)
		(width 0.1143)
		(layer "In11.Cu")
		(net "P5E_CPU0_G3_RX_DN<12>")
	)
	(arc
		(start 362.787184 -244.98935)
		(mid 362.689419 -245.092326)
		(end 362.63707 -245.2243)
		(width 0.1143)
		(layer "In11.Cu")
		(net "P5E_CPU0_G3_RX_DN<12>")
	)
	(arc
		(start 363.25429 -229.601268)
		(mid 363.140883 -229.734157)
		(end 363.100112 -229.904036)
		(width 0.1143)
		(layer "In11.Cu")
		(net "P5E_CPU0_G3_RX_DN<12>")
	)
	(arc
		(start 364.04042 -221.80423)
		(mid 364.092808 -222.000509)
		(end 364.236254 -222.144336)
		(width 0.1143)
		(layer "In11.Cu")
		(net "P5E_CPU0_G3_RX_DN<12>")
	)
	(arc
		(start 364.266734 -223.769682)
		(mid 364.445547 -223.972032)
		(end 364.510066 -224.234248)
		(width 0.1143)
		(layer "In11.Cu")
		(net "P5E_CPU0_G3_RX_DN<12>")
	)
	(arc
		(start 363.326934 -236.729524)
		(mid 363.570261 -237.19409)
		(end 363.326934 -237.658656)
		(width 0.1143)
		(layer "In11.Cu")
		(net "P5E_CPU0_G3_RX_DN<12>")
	)
	(arc
		(start 363.326934 -228.629718)
		(mid 363.570261 -229.094284)
		(end 363.326934 -229.55885)
		(width 0.1143)
		(layer "In11.Cu")
		(net "P5E_CPU0_G3_RX_DN<12>")
	)
	(arc
		(start 363.256068 -227.979986)
		(mid 363.10014 -228.284278)
		(end 363.256068 -228.58857)
		(width 0.1143)
		(layer "In11.Cu")
		(net "P5E_CPU0_G3_RX_DN<12>")
	)
	(arc
		(start 363.326934 -227.009706)
		(mid 363.570261 -227.474272)
		(end 363.326934 -227.938838)
		(width 0.1143)
		(layer "In11.Cu")
		(net "P5E_CPU0_G3_RX_DN<12>")
	)
	(arc
		(start 363.326934 -231.869488)
		(mid 363.570261 -232.334054)
		(end 363.326934 -232.79862)
		(width 0.1143)
		(layer "In11.Cu")
		(net "P5E_CPU0_G3_RX_DN<12>")
	)
	(arc
		(start 364.295944 -224.6757)
		(mid 364.287126 -224.682902)
		(end 364.278164 -224.689924)
		(width 0.1143)
		(layer "In11.Cu")
		(net "P5E_CPU0_G3_RX_DN<12>")
	)
	(arc
		(start 363.570266 -225.85426)
		(mid 363.505751 -226.116479)
		(end 363.326934 -226.318826)
		(width 0.1143)
		(layer "In11.Cu")
		(net "P5E_CPU0_G3_RX_DN<12>")
	)
	(arc
		(start 363.326934 -241.58956)
		(mid 363.570261 -242.054126)
		(end 363.326934 -242.518692)
		(width 0.1143)
		(layer "In11.Cu")
		(net "P5E_CPU0_G3_RX_DN<12>")
	)
	(arc
		(start 364.278164 -224.689924)
		(mid 364.272352 -224.694408)
		(end 364.26648 -224.698814)
		(width 0.1143)
		(layer "In11.Cu")
		(net "P5E_CPU0_G3_RX_DN<12>")
	)
	(arc
		(start 363.100112 -229.904036)
		(mid 363.141367 -230.075007)
		(end 363.256068 -230.208328)
		(width 0.1143)
		(layer "In11.Cu")
		(net "P5E_CPU0_G3_RX_DN<12>")
	)
	(arc
		(start 363.256068 -237.699804)
		(mid 363.10014 -238.004096)
		(end 363.256068 -238.308388)
		(width 0.1143)
		(layer "In11.Cu")
		(net "P5E_CPU0_G3_RX_DN<12>")
	)
	(arc
		(start 363.256068 -226.359974)
		(mid 363.10014 -226.664266)
		(end 363.256068 -226.968558)
		(width 0.1143)
		(layer "In11.Cu")
		(net "P5E_CPU0_G3_RX_DN<12>")
	)
	(arc
		(start 363.326934 -233.4895)
		(mid 363.570261 -233.954066)
		(end 363.326934 -234.418632)
		(width 0.1143)
		(layer "In11.Cu")
		(net "P5E_CPU0_G3_RX_DN<12>")
	)
	(arc
		(start 364.31982 -222.192596)
		(mid 364.330101 -222.202378)
		(end 364.34014 -222.212408)
		(width 0.1143)
		(layer "In11.Cu")
		(net "P5E_CPU0_G3_RX_DN<12>")
	)
	(arc
		(start 363.326934 -235.109512)
		(mid 363.570261 -235.574078)
		(end 363.326934 -236.038644)
		(width 0.1143)
		(layer "In11.Cu")
		(net "P5E_CPU0_G3_RX_DN<12>")
	)
	(arc
		(start 363.256068 -234.45978)
		(mid 363.10014 -234.764072)
		(end 363.256068 -235.068364)
		(width 0.1143)
		(layer "In11.Cu")
		(net "P5E_CPU0_G3_RX_DN<12>")
	)
	(arc
		(start 363.256068 -244.179852)
		(mid 363.141392 -244.313186)
		(end 363.100112 -244.484144)
		(width 0.1143)
		(layer "In11.Cu")
		(net "P5E_CPU0_G3_RX_DN<12>")
	)
	(arc
		(start 363.570266 -230.714296)
		(mid 363.505751 -230.976515)
		(end 363.326934 -231.178862)
		(width 0.1143)
		(layer "In11.Cu")
		(net "P5E_CPU0_G3_RX_DN<12>")
	)
	(arc
		(start 363.326934 -238.349536)
		(mid 363.570261 -238.814102)
		(end 363.326934 -239.278668)
		(width 0.1143)
		(layer "In11.Cu")
		(net "P5E_CPU0_G3_RX_DN<12>")
	)
	(arc
		(start 363.256068 -239.319816)
		(mid 363.10014 -239.624108)
		(end 363.256068 -239.9284)
		(width 0.1143)
		(layer "In11.Cu")
		(net "P5E_CPU0_G3_RX_DN<12>")
	)
	(arc
		(start 364.175802 -223.134428)
		(mid 364.027295 -223.424242)
		(end 364.175802 -223.714056)
		(width 0.1143)
		(layer "In11.Cu")
		(net "P5E_CPU0_G3_RX_DN<12>")
	)
	(arc
		(start 364.34014 -222.212408)
		(mid 364.503012 -222.654804)
		(end 364.279434 -223.069912)
		(width 0.1143)
		(layer "In11.Cu")
		(net "P5E_CPU0_G3_RX_DN<12>")
	)
	(arc
		(start 364.196884 -224.739454)
		(mid 364.081457 -224.87283)
		(end 364.039912 -225.044254)
		(width 0.1143)
		(layer "In11.Cu")
		(net "P5E_CPU0_G3_RX_DN<12>")
	)
	(arc
		(start 364.039912 -225.044254)
		(mid 363.974676 -225.307845)
		(end 363.79404 -225.510598)
		(width 0.1143)
		(layer "In11.Cu")
		(net "P5E_CPU0_G3_RX_DN<12>")
	)
	(segment
		(start 364.888018 -247.990106)
		(end 365.35487 -247.724168)
		(width 0.12954)
		(layer "F.Cu")
		(net "P5E_CPU0_G3_RX_DN<11>")
	)
	(segment
		(start 401.308062 -6.996176)
		(end 401.57908 -6.725158)
		(width 0.12954)
		(layer "F.Cu")
		(net "P5E_CPU0_G3_RX_DN<11>")
	)
	(segment
		(start 401.446746 -7.709154)
		(end 401.308062 -7.57047)
		(width 0.12954)
		(layer "F.Cu")
		(net "P5E_CPU0_G3_RX_DN<11>")
	)
	(segment
		(start 401.446746 -8.320024)
		(end 401.446746 -7.709154)
		(width 0.12954)
		(layer "F.Cu")
		(net "P5E_CPU0_G3_RX_DN<11>")
	)
	(segment
		(start 401.308062 -7.57047)
		(end 401.308062 -6.996176)
		(width 0.12954)
		(layer "F.Cu")
		(net "P5E_CPU0_G3_RX_DN<11>")
	)
	(segment
		(start 364.232444 -241.569494)
		(end 364.266988 -241.58956)
		(width 0.1143)
		(layer "In11.Cu")
		(net "P5E_CPU0_G3_RX_DN<11>")
	)
	(segment
		(start 364.232444 -246.42953)
		(end 364.266988 -246.449596)
		(width 0.1143)
		(layer "In11.Cu")
		(net "P5E_CPU0_G3_RX_DN<11>")
	)
	(segment
		(start 364.232444 -239.949482)
		(end 364.266988 -239.969548)
		(width 0.1143)
		(layer "In11.Cu")
		(net "P5E_CPU0_G3_RX_DN<11>")
	)
	(segment
		(start 364.221776 -234.445048)
		(end 364.22076 -234.445556)
		(width 0.1143)
		(layer "In11.Cu")
		(net "P5E_CPU0_G3_RX_DN<11>")
	)
	(segment
		(start 321.156838 -125.44298)
		(end 318.486282 -130.312668)
		(width 0.14224)
		(layer "In11.Cu")
		(net "P5E_CPU0_G3_RX_DN<11>")
	)
	(segment
		(start 364.22076 -240.925604)
		(end 364.196122 -240.939828)
		(width 0.1143)
		(layer "In11.Cu")
		(net "P5E_CPU0_G3_RX_DN<11>")
	)
	(segment
		(start 364.224316 -239.944656)
		(end 364.22711 -239.94618)
		(width 0.1143)
		(layer "In11.Cu")
		(net "P5E_CPU0_G3_RX_DN<11>")
	)
	(segment
		(start 364.227872 -239.946688)
		(end 364.228888 -239.947196)
		(width 0.1143)
		(layer "In11.Cu")
		(net "P5E_CPU0_G3_RX_DN<11>")
	)
	(segment
		(start 364.259368 -234.423204)
		(end 364.23473 -234.437428)
		(width 0.1143)
		(layer "In11.Cu")
		(net "P5E_CPU0_G3_RX_DN<11>")
	)
	(segment
		(start 364.228888 -244.161056)
		(end 364.227872 -244.161564)
		(width 0.1143)
		(layer "In11.Cu")
		(net "P5E_CPU0_G3_RX_DN<11>")
	)
	(segment
		(start 364.227872 -242.541552)
		(end 364.196122 -242.55984)
		(width 0.1143)
		(layer "In11.Cu")
		(net "P5E_CPU0_G3_RX_DN<11>")
	)
	(segment
		(start 364.979966 -221.803976)
		(end 364.98022 -221.80423)
		(width 0.1143)
		(layer "In11.Cu")
		(net "P5E_CPU0_G3_RX_DN<11>")
	)
	(segment
		(start 364.232444 -243.189506)
		(end 364.266988 -243.209572)
		(width 0.1143)
		(layer "In11.Cu")
		(net "P5E_CPU0_G3_RX_DN<11>")
	)
	(segment
		(start 364.222538 -234.44454)
		(end 364.221776 -234.445048)
		(width 0.1143)
		(layer "In11.Cu")
		(net "P5E_CPU0_G3_RX_DN<11>")
	)
	(segment
		(start 364.220252 -246.422418)
		(end 364.221776 -246.42318)
		(width 0.1143)
		(layer "In11.Cu")
		(net "P5E_CPU0_G3_RX_DN<11>")
	)
	(segment
		(start 364.230666 -234.439968)
		(end 364.228888 -234.440984)
		(width 0.1143)
		(layer "In11.Cu")
		(net "P5E_CPU0_G3_RX_DN<11>")
	)
	(segment
		(start 364.22076 -239.305592)
		(end 364.196122 -239.319816)
		(width 0.1143)
		(layer "In11.Cu")
		(net "P5E_CPU0_G3_RX_DN<11>")
	)
	(segment
		(start 364.224316 -233.464608)
		(end 364.22711 -233.466132)
		(width 0.1143)
		(layer "In11.Cu")
		(net "P5E_CPU0_G3_RX_DN<11>")
	)
	(segment
		(start 364.26013 -244.142768)
		(end 364.259368 -244.143276)
		(width 0.1143)
		(layer "In11.Cu")
		(net "P5E_CPU0_G3_RX_DN<11>")
	)
	(segment
		(start 400.724624 -19.223228)
		(end 400.67865 -19.424142)
		(width 0.14224)
		(layer "In11.Cu")
		(net "P5E_CPU0_G3_RX_DN<11>")
	)
	(segment
		(start 364.221776 -243.183156)
		(end 364.222538 -243.183664)
		(width 0.1143)
		(layer "In11.Cu")
		(net "P5E_CPU0_G3_RX_DN<11>")
	)
	(segment
		(start 364.223554 -244.804184)
		(end 364.224316 -244.804692)
		(width 0.1143)
		(layer "In11.Cu")
		(net "P5E_CPU0_G3_RX_DN<11>")
	)
	(segment
		(start 312.058812 -167.962326)
		(end 316.54369 -172.448474)
		(width 0.14224)
		(layer "In11.Cu")
		(net "P5E_CPU0_G3_RX_DN<11>")
	)
	(segment
		(start 400.47926 -18.392648)
		(end 400.724624 -18.984976)
		(width 0.14224)
		(layer "In11.Cu")
		(net "P5E_CPU0_G3_RX_DN<11>")
	)
	(segment
		(start 364.69701 -225.532188)
		(end 364.666022 -225.549968)
		(width 0.1143)
		(layer "In11.Cu")
		(net "P5E_CPU0_G3_RX_DN<11>")
	)
	(segment
		(start 364.232444 -244.809518)
		(end 364.266988 -244.829584)
		(width 0.1143)
		(layer "In11.Cu")
		(net "P5E_CPU0_G3_RX_DN<11>")
	)
	(segment
		(start 364.223554 -233.4641)
		(end 364.224316 -233.464608)
		(width 0.1143)
		(layer "In11.Cu")
		(net "P5E_CPU0_G3_RX_DN<11>")
	)
	(segment
		(start 364.22076 -232.825544)
		(end 364.196122 -232.839768)
		(width 0.1143)
		(layer "In11.Cu")
		(net "P5E_CPU0_G3_RX_DN<11>")
	)
	(segment
		(start 364.22711 -234.442)
		(end 364.224316 -234.443524)
		(width 0.1143)
		(layer "In11.Cu")
		(net "P5E_CPU0_G3_RX_DN<11>")
	)
	(segment
		(start 364.221776 -231.843072)
		(end 364.222538 -231.84358)
		(width 0.1143)
		(layer "In11.Cu")
		(net "P5E_CPU0_G3_RX_DN<11>")
	)
	(segment
		(start 364.230666 -232.819956)
		(end 364.228888 -232.820972)
		(width 0.1143)
		(layer "In11.Cu")
		(net "P5E_CPU0_G3_RX_DN<11>")
	)
	(segment
		(start 364.197138 -228.589078)
		(end 364.227872 -228.606858)
		(width 0.1143)
		(layer "In11.Cu")
		(net "P5E_CPU0_G3_RX_DN<11>")
	)
	(segment
		(start 364.22711 -238.326168)
		(end 364.227872 -238.326676)
		(width 0.1143)
		(layer "In11.Cu")
		(net "P5E_CPU0_G3_RX_DN<11>")
	)
	(segment
		(start 364.224316 -232.823512)
		(end 364.223554 -232.82402)
		(width 0.1143)
		(layer "In11.Cu")
		(net "P5E_CPU0_G3_RX_DN<11>")
	)
	(segment
		(start 364.230158 -236.707934)
		(end 364.232444 -236.709458)
		(width 0.1143)
		(layer "In11.Cu")
		(net "P5E_CPU0_G3_RX_DN<11>")
	)
	(segment
		(start 364.227872 -244.806724)
		(end 364.228888 -244.807232)
		(width 0.1143)
		(layer "In11.Cu")
		(net "P5E_CPU0_G3_RX_DN<11>")
	)
	(segment
		(start 364.223554 -236.704124)
		(end 364.224316 -236.704632)
		(width 0.1143)
		(layer "In11.Cu")
		(net "P5E_CPU0_G3_RX_DN<11>")
	)
	(segment
		(start 364.222538 -232.824528)
		(end 364.221776 -232.825036)
		(width 0.1143)
		(layer "In11.Cu")
		(net "P5E_CPU0_G3_RX_DN<11>")
	)
	(segment
		(start 365.161576 -222.123254)
		(end 365.163608 -222.12427)
		(width 0.1143)
		(layer "In11.Cu")
		(net "P5E_CPU0_G3_RX_DN<11>")
	)
	(segment
		(start 364.23219 -239.298988)
		(end 364.230666 -239.300004)
		(width 0.1143)
		(layer "In11.Cu")
		(net "P5E_CPU0_G3_RX_DN<11>")
	)
	(segment
		(start 364.667292 -247.218962)
		(end 364.736888 -247.259602)
		(width 0.1143)
		(layer "In11.Cu")
		(net "P5E_CPU0_G3_RX_DN<11>")
	)
	(segment
		(start 364.259368 -232.803192)
		(end 364.23473 -232.817416)
		(width 0.1143)
		(layer "In11.Cu")
		(net "P5E_CPU0_G3_RX_DN<11>")
	)
	(segment
		(start 364.196122 -235.068364)
		(end 364.220252 -235.082334)
		(width 0.1143)
		(layer "In11.Cu")
		(net "P5E_CPU0_G3_RX_DN<11>")
	)
	(segment
		(start 364.222538 -240.924588)
		(end 364.221776 -240.925096)
		(width 0.1143)
		(layer "In11.Cu")
		(net "P5E_CPU0_G3_RX_DN<11>")
	)
	(segment
		(start 364.23473 -239.297464)
		(end 364.233206 -239.29848)
		(width 0.1143)
		(layer "In11.Cu")
		(net "P5E_CPU0_G3_RX_DN<11>")
	)
	(segment
		(start 364.228888 -245.781068)
		(end 364.227872 -245.781576)
		(width 0.1143)
		(layer "In11.Cu")
		(net "P5E_CPU0_G3_RX_DN<11>")
	)
	(segment
		(start 364.222538 -243.183664)
		(end 364.223554 -243.184172)
		(width 0.1143)
		(layer "In11.Cu")
		(net "P5E_CPU0_G3_RX_DN<11>")
	)
	(segment
		(start 364.230158 -243.187982)
		(end 364.232444 -243.189506)
		(width 0.1143)
		(layer "In11.Cu")
		(net "P5E_CPU0_G3_RX_DN<11>")
	)
	(segment
		(start 400.2151 -18.128234)
		(end 400.47926 -18.392648)
		(width 0.14224)
		(layer "In11.Cu")
		(net "P5E_CPU0_G3_RX_DN<11>")
	)
	(segment
		(start 400.608038 -19.541998)
		(end 385.208272 -42.120566)
		(width 0.14224)
		(layer "In11.Cu")
		(net "P5E_CPU0_G3_RX_DN<11>")
	)
	(segment
		(start 364.221776 -232.825036)
		(end 364.22076 -232.825544)
		(width 0.1143)
		(layer "In11.Cu")
		(net "P5E_CPU0_G3_RX_DN<11>")
	)
	(segment
		(start 364.230158 -244.807994)
		(end 364.232444 -244.809518)
		(width 0.1143)
		(layer "In11.Cu")
		(net "P5E_CPU0_G3_RX_DN<11>")
	)
	(segment
		(start 364.228888 -231.847136)
		(end 364.230158 -231.847898)
		(width 0.1143)
		(layer "In11.Cu")
		(net "P5E_CPU0_G3_RX_DN<11>")
	)
	(segment
		(start 364.221776 -240.925096)
		(end 364.22076 -240.925604)
		(width 0.1143)
		(layer "In11.Cu")
		(net "P5E_CPU0_G3_RX_DN<11>")
	)
	(segment
		(start 365.450374 -222.614236)
		(end 365.45012 -222.614236)
		(width 0.1143)
		(layer "In11.Cu")
		(net "P5E_CPU0_G3_RX_DN<11>")
	)
	(segment
		(start 364.227872 -246.426736)
		(end 364.228888 -246.427244)
		(width 0.1143)
		(layer "In11.Cu")
		(net "P5E_CPU0_G3_RX_DN<11>")
	)
	(segment
		(start 364.221776 -236.703108)
		(end 364.222538 -236.703616)
		(width 0.1143)
		(layer "In11.Cu")
		(net "P5E_CPU0_G3_RX_DN<11>")
	)
	(segment
		(start 364.230666 -244.16004)
		(end 364.228888 -244.161056)
		(width 0.1143)
		(layer "In11.Cu")
		(net "P5E_CPU0_G3_RX_DN<11>")
	)
	(segment
		(start 364.227872 -243.186712)
		(end 364.228888 -243.18722)
		(width 0.1143)
		(layer "In11.Cu")
		(net "P5E_CPU0_G3_RX_DN<11>")
	)
	(segment
		(start 312.059574 -148.039836)
		(end 309.87365 -160.481264)
		(width 0.14224)
		(layer "In11.Cu")
		(net "P5E_CPU0_G3_RX_DN<11>")
	)
	(segment
		(start 364.23473 -240.917476)
		(end 364.233206 -240.918492)
		(width 0.1143)
		(layer "In11.Cu")
		(net "P5E_CPU0_G3_RX_DN<11>")
	)
	(segment
		(start 364.223554 -236.064044)
		(end 364.222538 -236.064552)
		(width 0.1143)
		(layer "In11.Cu")
		(net "P5E_CPU0_G3_RX_DN<11>")
	)
	(segment
		(start 364.228888 -238.327184)
		(end 364.266988 -238.349536)
		(width 0.1143)
		(layer "In11.Cu")
		(net "P5E_CPU0_G3_RX_DN<11>")
	)
	(segment
		(start 364.220252 -244.802406)
		(end 364.221776 -244.803168)
		(width 0.1143)
		(layer "In11.Cu")
		(net "P5E_CPU0_G3_RX_DN<11>")
	)
	(segment
		(start 364.22584 -238.325406)
		(end 364.22711 -238.326168)
		(width 0.1143)
		(layer "In11.Cu")
		(net "P5E_CPU0_G3_RX_DN<11>")
	)
	(segment
		(start 364.224316 -239.30356)
		(end 364.223554 -239.304068)
		(width 0.1143)
		(layer "In11.Cu")
		(net "P5E_CPU0_G3_RX_DN<11>")
	)
	(segment
		(start 364.196122 -233.448352)
		(end 364.220252 -233.462322)
		(width 0.1143)
		(layer "In11.Cu")
		(net "P5E_CPU0_G3_RX_DN<11>")
	)
	(segment
		(start 364.228888 -236.060996)
		(end 364.227872 -236.061504)
		(width 0.1143)
		(layer "In11.Cu")
		(net "P5E_CPU0_G3_RX_DN<11>")
	)
	(segment
		(start 364.23473 -244.1575)
		(end 364.233206 -244.158516)
		(width 0.1143)
		(layer "In11.Cu")
		(net "P5E_CPU0_G3_RX_DN<11>")
	)
	(segment
		(start 364.221776 -239.943132)
		(end 364.222538 -239.94364)
		(width 0.1143)
		(layer "In11.Cu")
		(net "P5E_CPU0_G3_RX_DN<11>")
	)
	(segment
		(start 364.228888 -243.18722)
		(end 364.230158 -243.187982)
		(width 0.1143)
		(layer "In11.Cu")
		(net "P5E_CPU0_G3_RX_DN<11>")
	)
	(segment
		(start 364.228888 -242.541044)
		(end 364.227872 -242.541552)
		(width 0.1143)
		(layer "In11.Cu")
		(net "P5E_CPU0_G3_RX_DN<11>")
	)
	(segment
		(start 364.220252 -233.462322)
		(end 364.221776 -233.463084)
		(width 0.1143)
		(layer "In11.Cu")
		(net "P5E_CPU0_G3_RX_DN<11>")
	)
	(segment
		(start 364.230412 -245.780052)
		(end 364.228888 -245.781068)
		(width 0.1143)
		(layer "In11.Cu")
		(net "P5E_CPU0_G3_RX_DN<11>")
	)
	(segment
		(start 364.222538 -244.803676)
		(end 364.223554 -244.804184)
		(width 0.1143)
		(layer "In11.Cu")
		(net "P5E_CPU0_G3_RX_DN<11>")
	)
	(segment
		(start 364.224316 -244.804692)
		(end 364.22711 -244.806216)
		(width 0.1143)
		(layer "In11.Cu")
		(net "P5E_CPU0_G3_RX_DN<11>")
	)
	(segment
		(start 322.080636 -175.765714)
		(end 360.28249 -207.071976)
		(width 0.14224)
		(layer "In11.Cu")
		(net "P5E_CPU0_G3_RX_DN<11>")
	)
	(segment
		(start 364.23473 -232.817416)
		(end 364.233206 -232.818432)
		(width 0.1143)
		(layer "In11.Cu")
		(net "P5E_CPU0_G3_RX_DN<11>")
	)
	(segment
		(start 364.223554 -231.844088)
		(end 364.224316 -231.844596)
		(width 0.1143)
		(layer "In11.Cu")
		(net "P5E_CPU0_G3_RX_DN<11>")
	)
	(segment
		(start 364.221776 -233.463084)
		(end 364.222538 -233.463592)
		(width 0.1143)
		(layer "In11.Cu")
		(net "P5E_CPU0_G3_RX_DN<11>")
	)
	(segment
		(start 365.206788 -223.078802)
		(end 365.137192 -223.119442)
		(width 0.1143)
		(layer "In11.Cu")
		(net "P5E_CPU0_G3_RX_DN<11>")
	)
	(segment
		(start 364.223554 -235.084112)
		(end 364.224316 -235.08462)
		(width 0.1143)
		(layer "In11.Cu")
		(net "P5E_CPU0_G3_RX_DN<11>")
	)
	(segment
		(start 364.259368 -240.903252)
		(end 364.23473 -240.917476)
		(width 0.1143)
		(layer "In11.Cu")
		(net "P5E_CPU0_G3_RX_DN<11>")
	)
	(segment
		(start 364.23219 -232.81894)
		(end 364.230666 -232.819956)
		(width 0.1143)
		(layer "In11.Cu")
		(net "P5E_CPU0_G3_RX_DN<11>")
	)
	(segment
		(start 364.22711 -235.086144)
		(end 364.227872 -235.086652)
		(width 0.1143)
		(layer "In11.Cu")
		(net "P5E_CPU0_G3_RX_DN<11>")
	)
	(segment
		(start 364.223554 -239.304068)
		(end 364.222538 -239.304576)
		(width 0.1143)
		(layer "In11.Cu")
		(net "P5E_CPU0_G3_RX_DN<11>")
	)
	(segment
		(start 364.228888 -246.427244)
		(end 364.230158 -246.428006)
		(width 0.1143)
		(layer "In11.Cu")
		(net "P5E_CPU0_G3_RX_DN<11>")
	)
	(segment
		(start 364.223554 -234.444032)
		(end 364.222538 -234.44454)
		(width 0.1143)
		(layer "In11.Cu")
		(net "P5E_CPU0_G3_RX_DN<11>")
	)
	(segment
		(start 400.67865 -19.424142)
		(end 400.608038 -19.541998)
		(width 0.14224)
		(layer "In11.Cu")
		(net "P5E_CPU0_G3_RX_DN<11>")
	)
	(segment
		(start 364.227872 -230.226616)
		(end 364.264448 -230.247952)
		(width 0.1143)
		(layer "In11.Cu")
		(net "P5E_CPU0_G3_RX_DN<11>")
	)
	(segment
		(start 365.136176 -222.108522)
		(end 365.161576 -222.123254)
		(width 0.1143)
		(layer "In11.Cu")
		(net "P5E_CPU0_G3_RX_DN<11>")
	)
	(segment
		(start 364.232444 -235.089446)
		(end 364.266988 -235.109512)
		(width 0.1143)
		(layer "In11.Cu")
		(net "P5E_CPU0_G3_RX_DN<11>")
	)
	(segment
		(start 364.227872 -240.92154)
		(end 364.22711 -240.922048)
		(width 0.1143)
		(layer "In11.Cu")
		(net "P5E_CPU0_G3_RX_DN<11>")
	)
	(segment
		(start 364.99419 -221.38767)
		(end 364.979966 -221.401894)
		(width 0.1143)
		(layer "In11.Cu")
		(net "P5E_CPU0_G3_RX_DN<11>")
	)
	(segment
		(start 364.22711 -244.162072)
		(end 364.224316 -244.163596)
		(width 0.1143)
		(layer "In11.Cu")
		(net "P5E_CPU0_G3_RX_DN<11>")
	)
	(segment
		(start 365.03991 -221.054676)
		(end 365.03991 -221.083124)
		(width 0.1143)
		(layer "In11.Cu")
		(net "P5E_CPU0_G3_RX_DN<11>")
	)
	(segment
		(start 364.227872 -236.061504)
		(end 364.22711 -236.062012)
		(width 0.1143)
		(layer "In11.Cu")
		(net "P5E_CPU0_G3_RX_DN<11>")
	)
	(segment
		(start 364.23219 -236.058964)
		(end 364.230666 -236.05998)
		(width 0.1143)
		(layer "In11.Cu")
		(net "P5E_CPU0_G3_RX_DN<11>")
	)
	(segment
		(start 364.222538 -239.94364)
		(end 364.223554 -239.944148)
		(width 0.1143)
		(layer "In11.Cu")
		(net "P5E_CPU0_G3_RX_DN<11>")
	)
	(segment
		(start 364.220252 -239.94237)
		(end 364.221776 -239.943132)
		(width 0.1143)
		(layer "In11.Cu")
		(net "P5E_CPU0_G3_RX_DN<11>")
	)
	(segment
		(start 365.03991 -221.083124)
		(end 364.99419 -221.128844)
		(width 0.1143)
		(layer "In11.Cu")
		(net "P5E_CPU0_G3_RX_DN<11>")
	)
	(segment
		(start 364.223554 -246.424196)
		(end 364.224316 -246.424704)
		(width 0.1143)
		(layer "In11.Cu")
		(net "P5E_CPU0_G3_RX_DN<11>")
	)
	(segment
		(start 364.224316 -236.704632)
		(end 364.22711 -236.706156)
		(width 0.1143)
		(layer "In11.Cu")
		(net "P5E_CPU0_G3_RX_DN<11>")
	)
	(segment
		(start 364.221776 -246.42318)
		(end 364.222538 -246.423688)
		(width 0.1143)
		(layer "In11.Cu")
		(net "P5E_CPU0_G3_RX_DN<11>")
	)
	(segment
		(start 364.227872 -245.781576)
		(end 364.196122 -245.799864)
		(width 0.1143)
		(layer "In11.Cu")
		(net "P5E_CPU0_G3_RX_DN<11>")
	)
	(segment
		(start 364.196122 -236.688376)
		(end 364.220252 -236.702346)
		(width 0.1143)
		(layer "In11.Cu")
		(net "P5E_CPU0_G3_RX_DN<11>")
	)
	(segment
		(start 364.697772 -225.53168)
		(end 364.69701 -225.532188)
		(width 0.1143)
		(layer "In11.Cu")
		(net "P5E_CPU0_G3_RX_DN<11>")
	)
	(segment
		(start 364.266988 -240.89868)
		(end 364.26013 -240.902744)
		(width 0.1143)
		(layer "In11.Cu")
		(net "P5E_CPU0_G3_RX_DN<11>")
	)
	(segment
		(start 364.222538 -244.164612)
		(end 364.221776 -244.16512)
		(width 0.1143)
		(layer "In11.Cu")
		(net "P5E_CPU0_G3_RX_DN<11>")
	)
	(segment
		(start 364.223554 -243.184172)
		(end 364.224316 -243.18468)
		(width 0.1143)
		(layer "In11.Cu")
		(net "P5E_CPU0_G3_RX_DN<11>")
	)
	(segment
		(start 364.233206 -240.918492)
		(end 364.23219 -240.919)
		(width 0.1143)
		(layer "In11.Cu")
		(net "P5E_CPU0_G3_RX_DN<11>")
	)
	(segment
		(start 364.227872 -234.441492)
		(end 364.22711 -234.442)
		(width 0.1143)
		(layer "In11.Cu")
		(net "P5E_CPU0_G3_RX_DN<11>")
	)
	(segment
		(start 364.224316 -240.923572)
		(end 364.223554 -240.92408)
		(width 0.1143)
		(layer "In11.Cu")
		(net "P5E_CPU0_G3_RX_DN<11>")
	)
	(segment
		(start 364.266988 -231.178862)
		(end 364.194344 -231.22128)
		(width 0.1143)
		(layer "In11.Cu")
		(net "P5E_CPU0_G3_RX_DN<11>")
	)
	(segment
		(start 364.974124 -247.641364)
		(end 365.056928 -247.724168)
		(width 0.1143)
		(layer "In11.Cu")
		(net "P5E_CPU0_G3_RX_DN<11>")
	)
	(segment
		(start 364.22711 -239.302036)
		(end 364.224316 -239.30356)
		(width 0.1143)
		(layer "In11.Cu")
		(net "P5E_CPU0_G3_RX_DN<11>")
	)
	(segment
		(start 364.266988 -245.758716)
		(end 364.230412 -245.780052)
		(width 0.1143)
		(layer "In11.Cu")
		(net "P5E_CPU0_G3_RX_DN<11>")
	)
	(segment
		(start 364.233206 -236.058456)
		(end 364.23219 -236.058964)
		(width 0.1143)
		(layer "In11.Cu")
		(net "P5E_CPU0_G3_RX_DN<11>")
	)
	(segment
		(start 364.223554 -232.82402)
		(end 364.222538 -232.824528)
		(width 0.1143)
		(layer "In11.Cu")
		(net "P5E_CPU0_G3_RX_DN<11>")
	)
	(segment
		(start 364.224316 -235.08462)
		(end 364.22711 -235.086144)
		(width 0.1143)
		(layer "In11.Cu")
		(net "P5E_CPU0_G3_RX_DN<11>")
	)
	(segment
		(start 364.23473 -236.05744)
		(end 364.233206 -236.058456)
		(width 0.1143)
		(layer "In11.Cu")
		(net "P5E_CPU0_G3_RX_DN<11>")
	)
	(segment
		(start 364.222538 -235.083604)
		(end 364.223554 -235.084112)
		(width 0.1143)
		(layer "In11.Cu")
		(net "P5E_CPU0_G3_RX_DN<11>")
	)
	(segment
		(start 365.137192 -223.729042)
		(end 365.206788 -223.769682)
		(width 0.1143)
		(layer "In11.Cu")
		(net "P5E_CPU0_G3_RX_DN<11>")
	)
	(segment
		(start 401.28825 -11.141202)
		(end 400.046444 -17.384014)
		(width 0.14224)
		(layer "In11.Cu")
		(net "P5E_CPU0_G3_RX_DN<11>")
	)
	(segment
		(start 364.233206 -234.438444)
		(end 364.23219 -234.438952)
		(width 0.1143)
		(layer "In11.Cu")
		(net "P5E_CPU0_G3_RX_DN<11>")
	)
	(segment
		(start 365.167926 -222.12681)
		(end 365.168942 -222.127318)
		(width 0.1143)
		(layer "In11.Cu")
		(net "P5E_CPU0_G3_RX_DN<11>")
	)
	(segment
		(start 364.22711 -233.466132)
		(end 364.227872 -233.46664)
		(width 0.1143)
		(layer "In11.Cu")
		(net "P5E_CPU0_G3_RX_DN<11>")
	)
	(segment
		(start 364.22076 -244.165628)
		(end 364.196122 -244.179852)
		(width 0.1143)
		(layer "In11.Cu")
		(net "P5E_CPU0_G3_RX_DN<11>")
	)
	(segment
		(start 364.233206 -244.158516)
		(end 364.23219 -244.159024)
		(width 0.1143)
		(layer "In11.Cu")
		(net "P5E_CPU0_G3_RX_DN<11>")
	)
	(segment
		(start 400.724624 -18.984976)
		(end 400.724624 -19.223228)
		(width 0.14224)
		(layer "In11.Cu")
		(net "P5E_CPU0_G3_RX_DN<11>")
	)
	(segment
		(start 364.222538 -231.84358)
		(end 364.223554 -231.844088)
		(width 0.1143)
		(layer "In11.Cu")
		(net "P5E_CPU0_G3_RX_DN<11>")
	)
	(segment
		(start 364.227872 -233.46664)
		(end 364.228888 -233.467148)
		(width 0.1143)
		(layer "In11.Cu")
		(net "P5E_CPU0_G3_RX_DN<11>")
	)
	(segment
		(start 364.223554 -239.944148)
		(end 364.224316 -239.944656)
		(width 0.1143)
		(layer "In11.Cu")
		(net "P5E_CPU0_G3_RX_DN<11>")
	)
	(segment
		(start 364.22711 -246.426228)
		(end 364.227872 -246.426736)
		(width 0.1143)
		(layer "In11.Cu")
		(net "P5E_CPU0_G3_RX_DN<11>")
	)
	(segment
		(start 364.266988 -242.518692)
		(end 364.230412 -242.540028)
		(width 0.1143)
		(layer "In11.Cu")
		(net "P5E_CPU0_G3_RX_DN<11>")
	)
	(segment
		(start 364.220252 -241.562382)
		(end 364.221776 -241.563144)
		(width 0.1143)
		(layer "In11.Cu")
		(net "P5E_CPU0_G3_RX_DN<11>")
	)
	(segment
		(start 364.26013 -239.282732)
		(end 364.259368 -239.28324)
		(width 0.1143)
		(layer "In11.Cu")
		(net "P5E_CPU0_G3_RX_DN<11>")
	)
	(segment
		(start 400.046444 -17.72158)
		(end 400.2151 -18.128234)
		(width 0.14224)
		(layer "In11.Cu")
		(net "P5E_CPU0_G3_RX_DN<11>")
	)
	(segment
		(start 364.222538 -246.423688)
		(end 364.223554 -246.424196)
		(width 0.1143)
		(layer "In11.Cu")
		(net "P5E_CPU0_G3_RX_DN<11>")
	)
	(segment
		(start 364.227872 -238.326676)
		(end 364.228888 -238.327184)
		(width 0.1143)
		(layer "In11.Cu")
		(net "P5E_CPU0_G3_RX_DN<11>")
	)
	(segment
		(start 364.222538 -233.463592)
		(end 364.223554 -233.4641)
		(width 0.1143)
		(layer "In11.Cu")
		(net "P5E_CPU0_G3_RX_DN<11>")
	)
	(segment
		(start 364.26013 -240.902744)
		(end 364.259368 -240.903252)
		(width 0.1143)
		(layer "In11.Cu")
		(net "P5E_CPU0_G3_RX_DN<11>")
	)
	(segment
		(start 364.224316 -246.424704)
		(end 364.22711 -246.426228)
		(width 0.1143)
		(layer "In11.Cu")
		(net "P5E_CPU0_G3_RX_DN<11>")
	)
	(segment
		(start 360.28249 -207.071976)
		(end 365.03991 -215.084152)
		(width 0.14224)
		(layer "In11.Cu")
		(net "P5E_CPU0_G3_RX_DN<11>")
	)
	(segment
		(start 364.230158 -231.847898)
		(end 364.232444 -231.849422)
		(width 0.1143)
		(layer "In11.Cu")
		(net "P5E_CPU0_G3_RX_DN<11>")
	)
	(segment
		(start 364.233206 -239.29848)
		(end 364.23219 -239.298988)
		(width 0.1143)
		(layer "In11.Cu")
		(net "P5E_CPU0_G3_RX_DN<11>")
	)
	(segment
		(start 364.222538 -239.304576)
		(end 364.221776 -239.305084)
		(width 0.1143)
		(layer "In11.Cu")
		(net "P5E_CPU0_G3_RX_DN<11>")
	)
	(segment
		(start 364.221776 -244.16512)
		(end 364.22076 -244.165628)
		(width 0.1143)
		(layer "In11.Cu")
		(net "P5E_CPU0_G3_RX_DN<11>")
	)
	(segment
		(start 401.57908 -6.725158)
		(end 401.28825 -7.015988)
		(width 0.14224)
		(layer "In11.Cu")
		(net "P5E_CPU0_G3_RX_DN<11>")
	)
	(segment
		(start 364.230158 -246.428006)
		(end 364.232444 -246.42953)
		(width 0.1143)
		(layer "In11.Cu")
		(net "P5E_CPU0_G3_RX_DN<11>")
	)
	(segment
		(start 365.168942 -222.127318)
		(end 365.207042 -222.14967)
		(width 0.1143)
		(layer "In11.Cu")
		(net "P5E_CPU0_G3_RX_DN<11>")
	)
	(segment
		(start 364.23219 -244.159024)
		(end 364.230666 -244.16004)
		(width 0.1143)
		(layer "In11.Cu")
		(net "P5E_CPU0_G3_RX_DN<11>")
	)
	(segment
		(start 364.22711 -240.922048)
		(end 364.224316 -240.923572)
		(width 0.1143)
		(layer "In11.Cu")
		(net "P5E_CPU0_G3_RX_DN<11>")
	)
	(segment
		(start 364.224316 -236.063536)
		(end 364.223554 -236.064044)
		(width 0.1143)
		(layer "In11.Cu")
		(net "P5E_CPU0_G3_RX_DN<11>")
	)
	(segment
		(start 364.230412 -237.679992)
		(end 364.228888 -237.681008)
		(width 0.1143)
		(layer "In11.Cu")
		(net "P5E_CPU0_G3_RX_DN<11>")
	)
	(segment
		(start 364.230666 -239.300004)
		(end 364.228888 -239.30102)
		(width 0.1143)
		(layer "In11.Cu")
		(net "P5E_CPU0_G3_RX_DN<11>")
	)
	(segment
		(start 364.259368 -244.143276)
		(end 364.23473 -244.1575)
		(width 0.1143)
		(layer "In11.Cu")
		(net "P5E_CPU0_G3_RX_DN<11>")
	)
	(segment
		(start 364.227872 -231.846628)
		(end 364.228888 -231.847136)
		(width 0.1143)
		(layer "In11.Cu")
		(net "P5E_CPU0_G3_RX_DN<11>")
	)
	(segment
		(start 364.222538 -236.064552)
		(end 364.221776 -236.06506)
		(width 0.1143)
		(layer "In11.Cu")
		(net "P5E_CPU0_G3_RX_DN<11>")
	)
	(segment
		(start 364.230666 -236.05998)
		(end 364.228888 -236.060996)
		(width 0.1143)
		(layer "In11.Cu")
		(net "P5E_CPU0_G3_RX_DN<11>")
	)
	(segment
		(start 364.227872 -244.161564)
		(end 364.22711 -244.162072)
		(width 0.1143)
		(layer "In11.Cu")
		(net "P5E_CPU0_G3_RX_DN<11>")
	)
	(segment
		(start 364.220252 -231.84231)
		(end 364.221776 -231.843072)
		(width 0.1143)
		(layer "In11.Cu")
		(net "P5E_CPU0_G3_RX_DN<11>")
	)
	(segment
		(start 364.230158 -235.087922)
		(end 364.232444 -235.089446)
		(width 0.1143)
		(layer "In11.Cu")
		(net "P5E_CPU0_G3_RX_DN<11>")
	)
	(segment
		(start 364.230158 -241.56797)
		(end 364.232444 -241.569494)
		(width 0.1143)
		(layer "In11.Cu")
		(net "P5E_CPU0_G3_RX_DN<11>")
	)
	(segment
		(start 364.266734 -227.938838)
		(end 364.197138 -227.979478)
		(width 0.1143)
		(layer "In11.Cu")
		(net "P5E_CPU0_G3_RX_DN<11>")
	)
	(segment
		(start 364.223554 -244.164104)
		(end 364.222538 -244.164612)
		(width 0.1143)
		(layer "In11.Cu")
		(net "P5E_CPU0_G3_RX_DN<11>")
	)
	(segment
		(start 365.16437 -222.124778)
		(end 365.167164 -222.126302)
		(width 0.1143)
		(layer "In11.Cu")
		(net "P5E_CPU0_G3_RX_DN<11>")
	)
	(segment
		(start 364.22711 -231.84612)
		(end 364.227872 -231.846628)
		(width 0.1143)
		(layer "In11.Cu")
		(net "P5E_CPU0_G3_RX_DN<11>")
	)
	(segment
		(start 364.220252 -243.182394)
		(end 364.221776 -243.183156)
		(width 0.1143)
		(layer "In11.Cu")
		(net "P5E_CPU0_G3_RX_DN<11>")
	)
	(segment
		(start 309.87365 -162.685984)
		(end 312.058812 -167.962326)
		(width 0.14224)
		(layer "In11.Cu")
		(net "P5E_CPU0_G3_RX_DN<11>")
	)
	(segment
		(start 365.03991 -215.084152)
		(end 365.03991 -221.054676)
		(width 0.14224)
		(layer "In11.Cu")
		(net "P5E_CPU0_G3_RX_DN<11>")
	)
	(segment
		(start 364.228888 -232.820972)
		(end 364.227872 -232.82148)
		(width 0.1143)
		(layer "In11.Cu")
		(net "P5E_CPU0_G3_RX_DN<11>")
	)
	(segment
		(start 364.26013 -232.802684)
		(end 364.259368 -232.803192)
		(width 0.1143)
		(layer "In11.Cu")
		(net "P5E_CPU0_G3_RX_DN<11>")
	)
	(segment
		(start 364.228888 -240.921032)
		(end 364.227872 -240.92154)
		(width 0.1143)
		(layer "In11.Cu")
		(net "P5E_CPU0_G3_RX_DN<11>")
	)
	(segment
		(start 364.196122 -239.9284)
		(end 364.220252 -239.94237)
		(width 0.1143)
		(layer "In11.Cu")
		(net "P5E_CPU0_G3_RX_DN<11>")
	)
	(segment
		(start 364.26013 -234.422696)
		(end 364.259368 -234.423204)
		(width 0.1143)
		(layer "In11.Cu")
		(net "P5E_CPU0_G3_RX_DN<11>")
	)
	(segment
		(start 364.196122 -230.208328)
		(end 364.227872 -230.226616)
		(width 0.1143)
		(layer "In11.Cu")
		(net "P5E_CPU0_G3_RX_DN<11>")
	)
	(segment
		(start 364.196122 -241.548412)
		(end 364.220252 -241.562382)
		(width 0.1143)
		(layer "In11.Cu")
		(net "P5E_CPU0_G3_RX_DN<11>")
	)
	(segment
		(start 365.056928 -247.724168)
		(end 365.35487 -247.724168)
		(width 0.1143)
		(layer "In11.Cu")
		(net "P5E_CPU0_G3_RX_DN<11>")
	)
	(segment
		(start 364.227872 -228.606858)
		(end 364.266988 -228.629718)
		(width 0.1143)
		(layer "In11.Cu")
		(net "P5E_CPU0_G3_RX_DN<11>")
	)
	(segment
		(start 364.228888 -234.440984)
		(end 364.227872 -234.441492)
		(width 0.1143)
		(layer "In11.Cu")
		(net "P5E_CPU0_G3_RX_DN<11>")
	)
	(segment
		(start 364.233206 -232.818432)
		(end 364.23219 -232.81894)
		(width 0.1143)
		(layer "In11.Cu")
		(net "P5E_CPU0_G3_RX_DN<11>")
	)
	(segment
		(start 364.224316 -244.163596)
		(end 364.223554 -244.164104)
		(width 0.1143)
		(layer "In11.Cu")
		(net "P5E_CPU0_G3_RX_DN<11>")
	)
	(segment
		(start 400.046444 -17.384014)
		(end 400.046444 -17.72158)
		(width 0.14224)
		(layer "In11.Cu")
		(net "P5E_CPU0_G3_RX_DN<11>")
	)
	(segment
		(start 364.224316 -231.844596)
		(end 364.22711 -231.84612)
		(width 0.1143)
		(layer "In11.Cu")
		(net "P5E_CPU0_G3_RX_DN<11>")
	)
	(segment
		(start 364.698788 -225.531172)
		(end 364.697772 -225.53168)
		(width 0.1143)
		(layer "In11.Cu")
		(net "P5E_CPU0_G3_RX_DN<11>")
	)
	(segment
		(start 364.23473 -234.437428)
		(end 364.233206 -234.438444)
		(width 0.1143)
		(layer "In11.Cu")
		(net "P5E_CPU0_G3_RX_DN<11>")
	)
	(segment
		(start 364.266988 -244.138704)
		(end 364.26013 -244.142768)
		(width 0.1143)
		(layer "In11.Cu")
		(net "P5E_CPU0_G3_RX_DN<11>")
	)
	(segment
		(start 364.266734 -226.318826)
		(end 364.197138 -226.359466)
		(width 0.1143)
		(layer "In11.Cu")
		(net "P5E_CPU0_G3_RX_DN<11>")
	)
	(segment
		(start 364.224316 -234.443524)
		(end 364.223554 -234.444032)
		(width 0.1143)
		(layer "In11.Cu")
		(net "P5E_CPU0_G3_RX_DN<11>")
	)
	(segment
		(start 364.220252 -235.082334)
		(end 364.221776 -235.083096)
		(width 0.1143)
		(layer "In11.Cu")
		(net "P5E_CPU0_G3_RX_DN<11>")
	)
	(segment
		(start 364.228888 -233.467148)
		(end 364.230158 -233.46791)
		(width 0.1143)
		(layer "In11.Cu")
		(net "P5E_CPU0_G3_RX_DN<11>")
	)
	(segment
		(start 364.230158 -239.947958)
		(end 364.232444 -239.949482)
		(width 0.1143)
		(layer "In11.Cu")
		(net "P5E_CPU0_G3_RX_DN<11>")
	)
	(segment
		(start 364.22711 -236.706156)
		(end 364.227872 -236.706664)
		(width 0.1143)
		(layer "In11.Cu")
		(net "P5E_CPU0_G3_RX_DN<11>")
	)
	(segment
		(start 364.228888 -239.947196)
		(end 364.230158 -239.947958)
		(width 0.1143)
		(layer "In11.Cu")
		(net "P5E_CPU0_G3_RX_DN<11>")
	)
	(segment
		(start 364.196122 -246.408448)
		(end 364.220252 -246.422418)
		(width 0.1143)
		(layer "In11.Cu")
		(net "P5E_CPU0_G3_RX_DN<11>")
	)
	(segment
		(start 364.221776 -235.083096)
		(end 364.222538 -235.083604)
		(width 0.1143)
		(layer "In11.Cu")
		(net "P5E_CPU0_G3_RX_DN<11>")
	)
	(segment
		(start 365.163608 -222.12427)
		(end 365.16437 -222.124778)
		(width 0.1143)
		(layer "In11.Cu")
		(net "P5E_CPU0_G3_RX_DN<11>")
	)
	(segment
		(start 385.208272 -42.120566)
		(end 321.156838 -125.44298)
		(width 0.14224)
		(layer "In11.Cu")
		(net "P5E_CPU0_G3_RX_DN<11>")
	)
	(segment
		(start 318.486282 -130.312668)
		(end 312.059574 -148.039836)
		(width 0.14224)
		(layer "In11.Cu")
		(net "P5E_CPU0_G3_RX_DN<11>")
	)
	(segment
		(start 364.228888 -236.707172)
		(end 364.230158 -236.707934)
		(width 0.1143)
		(layer "In11.Cu")
		(net "P5E_CPU0_G3_RX_DN<11>")
	)
	(segment
		(start 364.23219 -240.919)
		(end 364.230666 -240.920016)
		(width 0.1143)
		(layer "In11.Cu")
		(net "P5E_CPU0_G3_RX_DN<11>")
	)
	(segment
		(start 364.223554 -241.56416)
		(end 364.224316 -241.564668)
		(width 0.1143)
		(layer "In11.Cu")
		(net "P5E_CPU0_G3_RX_DN<11>")
	)
	(segment
		(start 364.22711 -241.566192)
		(end 364.227872 -241.5667)
		(width 0.1143)
		(layer "In11.Cu")
		(net "P5E_CPU0_G3_RX_DN<11>")
	)
	(segment
		(start 364.227872 -237.681516)
		(end 364.196122 -237.699804)
		(width 0.1143)
		(layer "In11.Cu")
		(net "P5E_CPU0_G3_RX_DN<11>")
	)
	(segment
		(start 364.224316 -241.564668)
		(end 364.22711 -241.566192)
		(width 0.1143)
		(layer "In11.Cu")
		(net "P5E_CPU0_G3_RX_DN<11>")
	)
	(segment
		(start 364.266988 -236.038644)
		(end 364.26013 -236.042708)
		(width 0.1143)
		(layer "In11.Cu")
		(net "P5E_CPU0_G3_RX_DN<11>")
	)
	(segment
		(start 364.259368 -236.043216)
		(end 364.23473 -236.05744)
		(width 0.1143)
		(layer "In11.Cu")
		(net "P5E_CPU0_G3_RX_DN<11>")
	)
	(segment
		(start 364.197138 -226.969066)
		(end 364.266734 -227.009706)
		(width 0.1143)
		(layer "In11.Cu")
		(net "P5E_CPU0_G3_RX_DN<11>")
	)
	(segment
		(start 364.22711 -232.821988)
		(end 364.224316 -232.823512)
		(width 0.1143)
		(layer "In11.Cu")
		(net "P5E_CPU0_G3_RX_DN<11>")
	)
	(segment
		(start 364.22076 -236.065568)
		(end 364.196122 -236.079792)
		(width 0.1143)
		(layer "In11.Cu")
		(net "P5E_CPU0_G3_RX_DN<11>")
	)
	(segment
		(start 365.167164 -222.126302)
		(end 365.167926 -222.12681)
		(width 0.1143)
		(layer "In11.Cu")
		(net "P5E_CPU0_G3_RX_DN<11>")
	)
	(segment
		(start 364.22711 -239.94618)
		(end 364.227872 -239.946688)
		(width 0.1143)
		(layer "In11.Cu")
		(net "P5E_CPU0_G3_RX_DN<11>")
	)
	(segment
		(start 364.196122 -244.788436)
		(end 364.220252 -244.802406)
		(width 0.1143)
		(layer "In11.Cu")
		(net "P5E_CPU0_G3_RX_DN<11>")
	)
	(segment
		(start 364.228888 -239.30102)
		(end 364.227872 -239.301528)
		(width 0.1143)
		(layer "In11.Cu")
		(net "P5E_CPU0_G3_RX_DN<11>")
	)
	(segment
		(start 364.232444 -233.469434)
		(end 364.266988 -233.4895)
		(width 0.1143)
		(layer "In11.Cu")
		(net "P5E_CPU0_G3_RX_DN<11>")
	)
	(segment
		(start 364.232444 -231.849422)
		(end 364.266988 -231.869488)
		(width 0.1143)
		(layer "In11.Cu")
		(net "P5E_CPU0_G3_RX_DN<11>")
	)
	(segment
		(start 364.227872 -236.706664)
		(end 364.228888 -236.707172)
		(width 0.1143)
		(layer "In11.Cu")
		(net "P5E_CPU0_G3_RX_DN<11>")
	)
	(segment
		(start 364.228888 -235.08716)
		(end 364.230158 -235.087922)
		(width 0.1143)
		(layer "In11.Cu")
		(net "P5E_CPU0_G3_RX_DN<11>")
	)
	(segment
		(start 364.222538 -236.703616)
		(end 364.223554 -236.704124)
		(width 0.1143)
		(layer "In11.Cu")
		(net "P5E_CPU0_G3_RX_DN<11>")
	)
	(segment
		(start 364.700312 -225.530156)
		(end 364.698788 -225.531172)
		(width 0.1143)
		(layer "In11.Cu")
		(net "P5E_CPU0_G3_RX_DN<11>")
	)
	(segment
		(start 364.22711 -243.186204)
		(end 364.227872 -243.186712)
		(width 0.1143)
		(layer "In11.Cu")
		(net "P5E_CPU0_G3_RX_DN<11>")
	)
	(segment
		(start 364.230158 -233.46791)
		(end 364.232444 -233.469434)
		(width 0.1143)
		(layer "In11.Cu")
		(net "P5E_CPU0_G3_RX_DN<11>")
	)
	(segment
		(start 365.206788 -224.698814)
		(end 365.137192 -224.739454)
		(width 0.1143)
		(layer "In11.Cu")
		(net "P5E_CPU0_G3_RX_DN<11>")
	)
	(segment
		(start 364.232444 -236.709458)
		(end 364.266988 -236.729524)
		(width 0.1143)
		(layer "In11.Cu")
		(net "P5E_CPU0_G3_RX_DN<11>")
	)
	(segment
		(start 364.22076 -234.445556)
		(end 364.196122 -234.45978)
		(width 0.1143)
		(layer "In11.Cu")
		(net "P5E_CPU0_G3_RX_DN<11>")
	)
	(segment
		(start 364.228888 -241.567208)
		(end 364.230158 -241.56797)
		(width 0.1143)
		(layer "In11.Cu")
		(net "P5E_CPU0_G3_RX_DN<11>")
	)
	(segment
		(start 364.979966 -221.401894)
		(end 364.979966 -221.803976)
		(width 0.1143)
		(layer "In11.Cu")
		(net "P5E_CPU0_G3_RX_DN<11>")
	)
	(segment
		(start 364.266988 -232.79862)
		(end 364.26013 -232.802684)
		(width 0.1143)
		(layer "In11.Cu")
		(net "P5E_CPU0_G3_RX_DN<11>")
	)
	(segment
		(start 316.54369 -172.448474)
		(end 322.080636 -175.765714)
		(width 0.14224)
		(layer "In11.Cu")
		(net "P5E_CPU0_G3_RX_DN<11>")
	)
	(segment
		(start 364.222538 -241.563652)
		(end 364.223554 -241.56416)
		(width 0.1143)
		(layer "In11.Cu")
		(net "P5E_CPU0_G3_RX_DN<11>")
	)
	(segment
		(start 364.230666 -240.920016)
		(end 364.228888 -240.921032)
		(width 0.1143)
		(layer "In11.Cu")
		(net "P5E_CPU0_G3_RX_DN<11>")
	)
	(segment
		(start 364.230412 -242.540028)
		(end 364.228888 -242.541044)
		(width 0.1143)
		(layer "In11.Cu")
		(net "P5E_CPU0_G3_RX_DN<11>")
	)
	(segment
		(start 364.22711 -236.062012)
		(end 364.224316 -236.063536)
		(width 0.1143)
		(layer "In11.Cu")
		(net "P5E_CPU0_G3_RX_DN<11>")
	)
	(segment
		(start 364.196122 -231.82834)
		(end 364.220252 -231.84231)
		(width 0.1143)
		(layer "In11.Cu")
		(net "P5E_CPU0_G3_RX_DN<11>")
	)
	(segment
		(start 364.26013 -236.042708)
		(end 364.259368 -236.043216)
		(width 0.1143)
		(layer "In11.Cu")
		(net "P5E_CPU0_G3_RX_DN<11>")
	)
	(segment
		(start 364.196122 -238.308388)
		(end 364.22584 -238.325406)
		(width 0.1143)
		(layer "In11.Cu")
		(net "P5E_CPU0_G3_RX_DN<11>")
	)
	(segment
		(start 364.23219 -234.438952)
		(end 364.230666 -234.439968)
		(width 0.1143)
		(layer "In11.Cu")
		(net "P5E_CPU0_G3_RX_DN<11>")
	)
	(segment
		(start 364.227872 -239.301528)
		(end 364.22711 -239.302036)
		(width 0.1143)
		(layer "In11.Cu")
		(net "P5E_CPU0_G3_RX_DN<11>")
	)
	(segment
		(start 364.196122 -243.168424)
		(end 364.220252 -243.182394)
		(width 0.1143)
		(layer "In11.Cu")
		(net "P5E_CPU0_G3_RX_DN<11>")
	)
	(segment
		(start 364.221776 -241.563144)
		(end 364.222538 -241.563652)
		(width 0.1143)
		(layer "In11.Cu")
		(net "P5E_CPU0_G3_RX_DN<11>")
	)
	(segment
		(start 364.221776 -244.803168)
		(end 364.222538 -244.803676)
		(width 0.1143)
		(layer "In11.Cu")
		(net "P5E_CPU0_G3_RX_DN<11>")
	)
	(segment
		(start 364.259368 -239.28324)
		(end 364.23473 -239.297464)
		(width 0.1143)
		(layer "In11.Cu")
		(net "P5E_CPU0_G3_RX_DN<11>")
	)
	(segment
		(start 364.221776 -236.06506)
		(end 364.22076 -236.065568)
		(width 0.1143)
		(layer "In11.Cu")
		(net "P5E_CPU0_G3_RX_DN<11>")
	)
	(segment
		(start 309.87365 -160.481264)
		(end 309.87365 -162.685984)
		(width 0.14224)
		(layer "In11.Cu")
		(net "P5E_CPU0_G3_RX_DN<11>")
	)
	(segment
		(start 364.228888 -237.681008)
		(end 364.227872 -237.681516)
		(width 0.1143)
		(layer "In11.Cu")
		(net "P5E_CPU0_G3_RX_DN<11>")
	)
	(segment
		(start 364.266988 -239.278668)
		(end 364.26013 -239.282732)
		(width 0.1143)
		(layer "In11.Cu")
		(net "P5E_CPU0_G3_RX_DN<11>")
	)
	(segment
		(start 364.227872 -241.5667)
		(end 364.228888 -241.567208)
		(width 0.1143)
		(layer "In11.Cu")
		(net "P5E_CPU0_G3_RX_DN<11>")
	)
	(segment
		(start 364.99419 -221.128844)
		(end 364.99419 -221.38767)
		(width 0.1143)
		(layer "In11.Cu")
		(net "P5E_CPU0_G3_RX_DN<11>")
	)
	(segment
		(start 364.266988 -229.55885)
		(end 364.194344 -229.601268)
		(width 0.1143)
		(layer "In11.Cu")
		(net "P5E_CPU0_G3_RX_DN<11>")
	)
	(segment
		(start 364.221776 -239.305084)
		(end 364.22076 -239.305592)
		(width 0.1143)
		(layer "In11.Cu")
		(net "P5E_CPU0_G3_RX_DN<11>")
	)
	(segment
		(start 364.22711 -244.806216)
		(end 364.227872 -244.806724)
		(width 0.1143)
		(layer "In11.Cu")
		(net "P5E_CPU0_G3_RX_DN<11>")
	)
	(segment
		(start 364.227872 -232.82148)
		(end 364.22711 -232.821988)
		(width 0.1143)
		(layer "In11.Cu")
		(net "P5E_CPU0_G3_RX_DN<11>")
	)
	(segment
		(start 364.266988 -237.658656)
		(end 364.230412 -237.679992)
		(width 0.1143)
		(layer "In11.Cu")
		(net "P5E_CPU0_G3_RX_DN<11>")
	)
	(segment
		(start 364.223554 -240.92408)
		(end 364.222538 -240.924588)
		(width 0.1143)
		(layer "In11.Cu")
		(net "P5E_CPU0_G3_RX_DN<11>")
	)
	(segment
		(start 364.224316 -243.18468)
		(end 364.22711 -243.186204)
		(width 0.1143)
		(layer "In11.Cu")
		(net "P5E_CPU0_G3_RX_DN<11>")
	)
	(segment
		(start 364.266988 -234.418632)
		(end 364.26013 -234.422696)
		(width 0.1143)
		(layer "In11.Cu")
		(net "P5E_CPU0_G3_RX_DN<11>")
	)
	(segment
		(start 364.228888 -244.807232)
		(end 364.230158 -244.807994)
		(width 0.1143)
		(layer "In11.Cu")
		(net "P5E_CPU0_G3_RX_DN<11>")
	)
	(segment
		(start 364.227872 -235.086652)
		(end 364.228888 -235.08716)
		(width 0.1143)
		(layer "In11.Cu")
		(net "P5E_CPU0_G3_RX_DN<11>")
	)
	(segment
		(start 364.736888 -225.50882)
		(end 364.700312 -225.530156)
		(width 0.1143)
		(layer "In11.Cu")
		(net "P5E_CPU0_G3_RX_DN<11>")
	)
	(segment
		(start 401.28825 -7.015988)
		(end 401.28825 -11.141202)
		(width 0.14224)
		(layer "In11.Cu")
		(net "P5E_CPU0_G3_RX_DN<11>")
	)
	(segment
		(start 364.220252 -236.702346)
		(end 364.221776 -236.703108)
		(width 0.1143)
		(layer "In11.Cu")
		(net "P5E_CPU0_G3_RX_DN<11>")
	)
	(arc
		(start 364.196122 -239.319816)
		(mid 364.040194 -239.624108)
		(end 364.196122 -239.9284)
		(width 0.1143)
		(layer "In11.Cu")
		(net "P5E_CPU0_G3_RX_DN<11>")
	)
	(arc
		(start 364.992158 -221.898464)
		(mid 365.014036 -221.95989)
		(end 365.04626 -222.016574)
		(width 0.1143)
		(layer "In11.Cu")
		(net "P5E_CPU0_G3_RX_DN<11>")
	)
	(arc
		(start 365.137192 -224.739454)
		(mid 365.021765 -224.87283)
		(end 364.98022 -225.044254)
		(width 0.1143)
		(layer "In11.Cu")
		(net "P5E_CPU0_G3_RX_DN<11>")
	)
	(arc
		(start 364.51032 -230.714296)
		(mid 364.445805 -230.976515)
		(end 364.266988 -231.178862)
		(width 0.1143)
		(layer "In11.Cu")
		(net "P5E_CPU0_G3_RX_DN<11>")
	)
	(arc
		(start 364.196122 -245.799864)
		(mid 364.040194 -246.104156)
		(end 364.196122 -246.408448)
		(width 0.1143)
		(layer "In11.Cu")
		(net "P5E_CPU0_G3_RX_DN<11>")
	)
	(arc
		(start 364.266988 -235.109512)
		(mid 364.510315 -235.574078)
		(end 364.266988 -236.038644)
		(width 0.1143)
		(layer "In11.Cu")
		(net "P5E_CPU0_G3_RX_DN<11>")
	)
	(arc
		(start 364.040166 -231.524048)
		(mid 364.081421 -231.695019)
		(end 364.196122 -231.82834)
		(width 0.1143)
		(layer "In11.Cu")
		(net "P5E_CPU0_G3_RX_DN<11>")
	)
	(arc
		(start 364.196122 -236.079792)
		(mid 364.040194 -236.384084)
		(end 364.196122 -236.688376)
		(width 0.1143)
		(layer "In11.Cu")
		(net "P5E_CPU0_G3_RX_DN<11>")
	)
	(arc
		(start 364.266988 -241.58956)
		(mid 364.510315 -242.054126)
		(end 364.266988 -242.518692)
		(width 0.1143)
		(layer "In11.Cu")
		(net "P5E_CPU0_G3_RX_DN<11>")
	)
	(arc
		(start 364.666022 -225.549968)
		(mid 364.551346 -225.683302)
		(end 364.510066 -225.85426)
		(width 0.1143)
		(layer "In11.Cu")
		(net "P5E_CPU0_G3_RX_DN<11>")
	)
	(arc
		(start 364.266988 -246.449596)
		(mid 364.445801 -246.651946)
		(end 364.51032 -246.914162)
		(width 0.1143)
		(layer "In11.Cu")
		(net "P5E_CPU0_G3_RX_DN<11>")
	)
	(arc
		(start 364.197138 -227.979478)
		(mid 364.040161 -228.284278)
		(end 364.197138 -228.589078)
		(width 0.1143)
		(layer "In11.Cu")
		(net "P5E_CPU0_G3_RX_DN<11>")
	)
	(arc
		(start 364.196122 -232.839768)
		(mid 364.040194 -233.14406)
		(end 364.196122 -233.448352)
		(width 0.1143)
		(layer "In11.Cu")
		(net "P5E_CPU0_G3_RX_DN<11>")
	)
	(arc
		(start 364.266988 -244.829584)
		(mid 364.510315 -245.29415)
		(end 364.266988 -245.758716)
		(width 0.1143)
		(layer "In11.Cu")
		(net "P5E_CPU0_G3_RX_DN<11>")
	)
	(arc
		(start 364.196122 -237.699804)
		(mid 364.040194 -238.004096)
		(end 364.196122 -238.308388)
		(width 0.1143)
		(layer "In11.Cu")
		(net "P5E_CPU0_G3_RX_DN<11>")
	)
	(arc
		(start 364.970314 -247.618504)
		(mid 364.972337 -247.629914)
		(end 364.974124 -247.641364)
		(width 0.1143)
		(layer "In11.Cu")
		(net "P5E_CPU0_G3_RX_DN<11>")
	)
	(arc
		(start 364.98022 -225.044254)
		(mid 364.915705 -225.306473)
		(end 364.736888 -225.50882)
		(width 0.1143)
		(layer "In11.Cu")
		(net "P5E_CPU0_G3_RX_DN<11>")
	)
	(arc
		(start 365.137192 -223.119442)
		(mid 364.980215 -223.424242)
		(end 365.137192 -223.729042)
		(width 0.1143)
		(layer "In11.Cu")
		(net "P5E_CPU0_G3_RX_DN<11>")
	)
	(arc
		(start 364.266988 -238.349536)
		(mid 364.510315 -238.814102)
		(end 364.266988 -239.278668)
		(width 0.1143)
		(layer "In11.Cu")
		(net "P5E_CPU0_G3_RX_DN<11>")
	)
	(arc
		(start 364.196122 -244.179852)
		(mid 364.040194 -244.484144)
		(end 364.196122 -244.788436)
		(width 0.1143)
		(layer "In11.Cu")
		(net "P5E_CPU0_G3_RX_DN<11>")
	)
	(arc
		(start 364.266988 -239.969548)
		(mid 364.510315 -240.434114)
		(end 364.266988 -240.89868)
		(width 0.1143)
		(layer "In11.Cu")
		(net "P5E_CPU0_G3_RX_DN<11>")
	)
	(arc
		(start 364.040166 -229.904036)
		(mid 364.081421 -230.075007)
		(end 364.196122 -230.208328)
		(width 0.1143)
		(layer "In11.Cu")
		(net "P5E_CPU0_G3_RX_DN<11>")
	)
	(arc
		(start 364.197138 -226.359466)
		(mid 364.040161 -226.664266)
		(end 364.197138 -226.969066)
		(width 0.1143)
		(layer "In11.Cu")
		(net "P5E_CPU0_G3_RX_DN<11>")
	)
	(arc
		(start 364.266988 -236.729524)
		(mid 364.510315 -237.19409)
		(end 364.266988 -237.658656)
		(width 0.1143)
		(layer "In11.Cu")
		(net "P5E_CPU0_G3_RX_DN<11>")
	)
	(arc
		(start 364.736888 -247.259602)
		(mid 364.888875 -247.41611)
		(end 364.970314 -247.618504)
		(width 0.1143)
		(layer "In11.Cu")
		(net "P5E_CPU0_G3_RX_DN<11>")
	)
	(arc
		(start 364.194344 -229.601268)
		(mid 364.080937 -229.734157)
		(end 364.040166 -229.904036)
		(width 0.1143)
		(layer "In11.Cu")
		(net "P5E_CPU0_G3_RX_DN<11>")
	)
	(arc
		(start 364.196122 -240.939828)
		(mid 364.040194 -241.24412)
		(end 364.196122 -241.548412)
		(width 0.1143)
		(layer "In11.Cu")
		(net "P5E_CPU0_G3_RX_DN<11>")
	)
	(arc
		(start 364.51032 -246.914162)
		(mid 364.551869 -247.085584)
		(end 364.667292 -247.218962)
		(width 0.1143)
		(layer "In11.Cu")
		(net "P5E_CPU0_G3_RX_DN<11>")
	)
	(arc
		(start 364.266988 -228.629718)
		(mid 364.510315 -229.094284)
		(end 364.266988 -229.55885)
		(width 0.1143)
		(layer "In11.Cu")
		(net "P5E_CPU0_G3_RX_DN<11>")
	)
	(arc
		(start 364.510066 -225.85426)
		(mid 364.445551 -226.116479)
		(end 364.266734 -226.318826)
		(width 0.1143)
		(layer "In11.Cu")
		(net "P5E_CPU0_G3_RX_DN<11>")
	)
	(arc
		(start 365.206788 -223.769682)
		(mid 365.450115 -224.234248)
		(end 365.206788 -224.698814)
		(width 0.1143)
		(layer "In11.Cu")
		(net "P5E_CPU0_G3_RX_DN<11>")
	)
	(arc
		(start 364.266988 -233.4895)
		(mid 364.510315 -233.954066)
		(end 364.266988 -234.418632)
		(width 0.1143)
		(layer "In11.Cu")
		(net "P5E_CPU0_G3_RX_DN<11>")
	)
	(arc
		(start 365.45012 -222.614236)
		(mid 365.385605 -222.876455)
		(end 365.206788 -223.078802)
		(width 0.1143)
		(layer "In11.Cu")
		(net "P5E_CPU0_G3_RX_DN<11>")
	)
	(arc
		(start 364.194344 -231.22128)
		(mid 364.080937 -231.354169)
		(end 364.040166 -231.524048)
		(width 0.1143)
		(layer "In11.Cu")
		(net "P5E_CPU0_G3_RX_DN<11>")
	)
	(arc
		(start 365.04626 -222.016574)
		(mid 365.087243 -222.066436)
		(end 365.136176 -222.108522)
		(width 0.1143)
		(layer "In11.Cu")
		(net "P5E_CPU0_G3_RX_DN<11>")
	)
	(arc
		(start 364.264448 -230.247952)
		(mid 364.4451 -230.450697)
		(end 364.51032 -230.714296)
		(width 0.1143)
		(layer "In11.Cu")
		(net "P5E_CPU0_G3_RX_DN<11>")
	)
	(arc
		(start 364.196122 -242.55984)
		(mid 364.040194 -242.864132)
		(end 364.196122 -243.168424)
		(width 0.1143)
		(layer "In11.Cu")
		(net "P5E_CPU0_G3_RX_DN<11>")
	)
	(arc
		(start 364.98022 -221.80423)
		(mid 364.983178 -221.851729)
		(end 364.992158 -221.898464)
		(width 0.1143)
		(layer "In11.Cu")
		(net "P5E_CPU0_G3_RX_DN<11>")
	)
	(arc
		(start 364.196122 -234.45978)
		(mid 364.040194 -234.764072)
		(end 364.196122 -235.068364)
		(width 0.1143)
		(layer "In11.Cu")
		(net "P5E_CPU0_G3_RX_DN<11>")
	)
	(arc
		(start 365.207042 -222.14967)
		(mid 365.385855 -222.35202)
		(end 365.450374 -222.614236)
		(width 0.1143)
		(layer "In11.Cu")
		(net "P5E_CPU0_G3_RX_DN<11>")
	)
	(arc
		(start 364.266988 -231.869488)
		(mid 364.510315 -232.334054)
		(end 364.266988 -232.79862)
		(width 0.1143)
		(layer "In11.Cu")
		(net "P5E_CPU0_G3_RX_DN<11>")
	)
	(arc
		(start 364.266734 -227.009706)
		(mid 364.510061 -227.474272)
		(end 364.266734 -227.938838)
		(width 0.1143)
		(layer "In11.Cu")
		(net "P5E_CPU0_G3_RX_DN<11>")
	)
	(arc
		(start 364.266988 -243.209572)
		(mid 364.510315 -243.674138)
		(end 364.266988 -244.138704)
		(width 0.1143)
		(layer "In11.Cu")
		(net "P5E_CPU0_G3_RX_DN<11>")
	)
	(segment
		(start 364.888018 -244.750082)
		(end 365.35487 -244.484144)
		(width 0.12954)
		(layer "F.Cu")
		(net "P5E_CPU0_G3_RX_DN<10>")
	)
	(segment
		(start 403.247098 -7.709408)
		(end 403.246844 -7.709662)
		(width 0.12954)
		(layer "F.Cu")
		(net "P5E_CPU0_G3_RX_DN<10>")
	)
	(segment
		(start 403.10816 -7.57047)
		(end 403.247098 -7.709408)
		(width 0.12954)
		(layer "F.Cu")
		(net "P5E_CPU0_G3_RX_DN<10>")
	)
	(segment
		(start 403.38375 -4.963414)
		(end 403.10816 -5.239004)
		(width 0.12954)
		(layer "F.Cu")
		(net "P5E_CPU0_G3_RX_DN<10>")
	)
	(segment
		(start 403.10816 -5.239004)
		(end 403.10816 -7.57047)
		(width 0.12954)
		(layer "F.Cu")
		(net "P5E_CPU0_G3_RX_DN<10>")
	)
	(segment
		(start 403.246844 -7.709662)
		(end 403.246844 -8.320024)
		(width 0.12954)
		(layer "F.Cu")
		(net "P5E_CPU0_G3_RX_DN<10>")
	)
	(segment
		(start 365.16056 -239.305846)
		(end 365.136176 -239.319816)
		(width 0.1143)
		(layer "In11.Cu")
		(net "P5E_CPU0_G3_RX_DN<10>")
	)
	(segment
		(start 365.162592 -242.5446)
		(end 365.16183 -242.545108)
		(width 0.1143)
		(layer "In11.Cu")
		(net "P5E_CPU0_G3_RX_DN<10>")
	)
	(segment
		(start 365.165386 -237.68304)
		(end 365.16437 -237.683548)
		(width 0.1143)
		(layer "In11.Cu")
		(net "P5E_CPU0_G3_RX_DN<10>")
	)
	(segment
		(start 365.16437 -236.063536)
		(end 365.163608 -236.064044)
		(width 0.1143)
		(layer "In11.Cu")
		(net "P5E_CPU0_G3_RX_DN<10>")
	)
	(segment
		(start 365.136176 -226.968558)
		(end 365.167926 -226.986846)
		(width 0.1143)
		(layer "In11.Cu")
		(net "P5E_CPU0_G3_RX_DN<10>")
	)
	(segment
		(start 365.16056 -240.925858)
		(end 365.136176 -240.939828)
		(width 0.1143)
		(layer "In11.Cu")
		(net "P5E_CPU0_G3_RX_DN<10>")
	)
	(segment
		(start 365.167926 -237.681516)
		(end 365.167164 -237.682024)
		(width 0.1143)
		(layer "In11.Cu")
		(net "P5E_CPU0_G3_RX_DN<10>")
	)
	(segment
		(start 366.14608 -223.76892)
		(end 366.146842 -223.769682)
		(width 0.1143)
		(layer "In11.Cu")
		(net "P5E_CPU0_G3_RX_DN<10>")
	)
	(segment
		(start 403.38375 -4.963414)
		(end 403.09292 -5.254244)
		(width 0.14224)
		(layer "In11.Cu")
		(net "P5E_CPU0_G3_RX_DN<10>")
	)
	(segment
		(start 361.015788 -206.466948)
		(end 365.985298 -214.837518)
		(width 0.14224)
		(layer "In11.Cu")
		(net "P5E_CPU0_G3_RX_DN<10>")
	)
	(segment
		(start 365.163608 -242.544092)
		(end 365.162592 -242.5446)
		(width 0.1143)
		(layer "In11.Cu")
		(net "P5E_CPU0_G3_RX_DN<10>")
	)
	(segment
		(start 365.167164 -240.922048)
		(end 365.166148 -240.922556)
		(width 0.1143)
		(layer "In11.Cu")
		(net "P5E_CPU0_G3_RX_DN<10>")
	)
	(segment
		(start 365.166148 -240.922556)
		(end 365.165386 -240.923064)
		(width 0.1143)
		(layer "In11.Cu")
		(net "P5E_CPU0_G3_RX_DN<10>")
	)
	(segment
		(start 365.146844 -236.694472)
		(end 365.167926 -236.706664)
		(width 0.1143)
		(layer "In11.Cu")
		(net "P5E_CPU0_G3_RX_DN<10>")
	)
	(segment
		(start 365.163608 -237.684056)
		(end 365.162592 -237.684564)
		(width 0.1143)
		(layer "In11.Cu")
		(net "P5E_CPU0_G3_RX_DN<10>")
	)
	(segment
		(start 365.167926 -230.226616)
		(end 365.168942 -230.227124)
		(width 0.1143)
		(layer "In11.Cu")
		(net "P5E_CPU0_G3_RX_DN<10>")
	)
	(segment
		(start 365.16437 -239.30356)
		(end 365.163608 -239.304068)
		(width 0.1143)
		(layer "In11.Cu")
		(net "P5E_CPU0_G3_RX_DN<10>")
	)
	(segment
		(start 366.136174 -223.763078)
		(end 366.144048 -223.76765)
		(width 0.1143)
		(layer "In11.Cu")
		(net "P5E_CPU0_G3_RX_DN<10>")
	)
	(segment
		(start 364.987078 -244.414294)
		(end 365.056928 -244.484144)
		(width 0.1143)
		(layer "In11.Cu")
		(net "P5E_CPU0_G3_RX_DN<10>")
	)
	(segment
		(start 365.16437 -242.543584)
		(end 365.163608 -242.544092)
		(width 0.1143)
		(layer "In11.Cu")
		(net "P5E_CPU0_G3_RX_DN<10>")
	)
	(segment
		(start 365.167926 -229.58171)
		(end 365.13516 -229.60076)
		(width 0.1143)
		(layer "In11.Cu")
		(net "P5E_CPU0_G3_RX_DN<10>")
	)
	(segment
		(start 365.167926 -226.986846)
		(end 365.204248 -227.007928)
		(width 0.1143)
		(layer "In11.Cu")
		(net "P5E_CPU0_G3_RX_DN<10>")
	)
	(segment
		(start 365.167164 -239.302036)
		(end 365.166148 -239.302544)
		(width 0.1143)
		(layer "In11.Cu")
		(net "P5E_CPU0_G3_RX_DN<10>")
	)
	(segment
		(start 365.136176 -231.82834)
		(end 365.167926 -231.846628)
		(width 0.1143)
		(layer "In11.Cu")
		(net "P5E_CPU0_G3_RX_DN<10>")
	)
	(segment
		(start 403.460204 -17.948402)
		(end 403.45995 -17.948402)
		(width 0.14224)
		(layer "In11.Cu")
		(net "P5E_CPU0_G3_RX_DN<10>")
	)
	(segment
		(start 365.167926 -235.086652)
		(end 365.16818 -235.086906)
		(width 0.1143)
		(layer "In11.Cu")
		(net "P5E_CPU0_G3_RX_DN<10>")
	)
	(segment
		(start 365.137192 -231.219248)
		(end 365.134398 -231.22128)
		(width 0.1143)
		(layer "In11.Cu")
		(net "P5E_CPU0_G3_RX_DN<10>")
	)
	(segment
		(start 366.085882 -223.116902)
		(end 366.072928 -223.122744)
		(width 0.1143)
		(layer "In11.Cu")
		(net "P5E_CPU0_G3_RX_DN<10>")
	)
	(segment
		(start 365.16183 -237.685072)
		(end 365.16056 -237.685834)
		(width 0.1143)
		(layer "In11.Cu")
		(net "P5E_CPU0_G3_RX_DN<10>")
	)
	(segment
		(start 365.136176 -233.448352)
		(end 365.167926 -233.46664)
		(width 0.1143)
		(layer "In11.Cu")
		(net "P5E_CPU0_G3_RX_DN<10>")
	)
	(segment
		(start 365.162592 -240.924588)
		(end 365.16183 -240.925096)
		(width 0.1143)
		(layer "In11.Cu")
		(net "P5E_CPU0_G3_RX_DN<10>")
	)
	(segment
		(start 365.634524 -225.533458)
		(end 365.61395 -225.545396)
		(width 0.1143)
		(layer "In11.Cu")
		(net "P5E_CPU0_G3_RX_DN<10>")
	)
	(segment
		(start 365.16818 -242.541552)
		(end 365.167926 -242.541552)
		(width 0.1143)
		(layer "In11.Cu")
		(net "P5E_CPU0_G3_RX_DN<10>")
	)
	(segment
		(start 312.824876 -167.374824)
		(end 312.894726 -167.479726)
		(width 0.14224)
		(layer "In11.Cu")
		(net "P5E_CPU0_G3_RX_DN<10>")
	)
	(segment
		(start 365.167164 -236.062012)
		(end 365.166148 -236.06252)
		(width 0.1143)
		(layer "In11.Cu")
		(net "P5E_CPU0_G3_RX_DN<10>")
	)
	(segment
		(start 321.936618 -125.981968)
		(end 319.435226 -130.534918)
		(width 0.14224)
		(layer "In11.Cu")
		(net "P5E_CPU0_G3_RX_DN<10>")
	)
	(segment
		(start 322.490084 -174.89551)
		(end 361.015788 -206.466948)
		(width 0.14224)
		(layer "In11.Cu")
		(net "P5E_CPU0_G3_RX_DN<10>")
	)
	(segment
		(start 365.16183 -239.305084)
		(end 365.16056 -239.305846)
		(width 0.1143)
		(layer "In11.Cu")
		(net "P5E_CPU0_G3_RX_DN<10>")
	)
	(segment
		(start 365.16818 -237.681516)
		(end 365.167926 -237.681516)
		(width 0.1143)
		(layer "In11.Cu")
		(net "P5E_CPU0_G3_RX_DN<10>")
	)
	(segment
		(start 365.165894 -228.605588)
		(end 365.167164 -228.60635)
		(width 0.1143)
		(layer "In11.Cu")
		(net "P5E_CPU0_G3_RX_DN<10>")
	)
	(segment
		(start 365.16183 -240.925096)
		(end 365.16056 -240.925858)
		(width 0.1143)
		(layer "In11.Cu")
		(net "P5E_CPU0_G3_RX_DN<10>")
	)
	(segment
		(start 365.204248 -234.42041)
		(end 365.167926 -234.441492)
		(width 0.1143)
		(layer "In11.Cu")
		(net "P5E_CPU0_G3_RX_DN<10>")
	)
	(segment
		(start 365.146082 -241.554)
		(end 365.146844 -241.554508)
		(width 0.1143)
		(layer "In11.Cu")
		(net "P5E_CPU0_G3_RX_DN<10>")
	)
	(segment
		(start 403.53742 -16.322548)
		(end 403.53742 -17.76476)
		(width 0.14224)
		(layer "In11.Cu")
		(net "P5E_CPU0_G3_RX_DN<10>")
	)
	(segment
		(start 365.167926 -233.46664)
		(end 365.204248 -233.487722)
		(width 0.1143)
		(layer "In11.Cu")
		(net "P5E_CPU0_G3_RX_DN<10>")
	)
	(segment
		(start 365.136176 -238.308388)
		(end 365.146082 -238.313976)
		(width 0.1143)
		(layer "In11.Cu")
		(net "P5E_CPU0_G3_RX_DN<10>")
	)
	(segment
		(start 365.165386 -242.543076)
		(end 365.16437 -242.543584)
		(width 0.1143)
		(layer "In11.Cu")
		(net "P5E_CPU0_G3_RX_DN<10>")
	)
	(segment
		(start 365.167926 -236.706664)
		(end 365.16818 -236.706918)
		(width 0.1143)
		(layer "In11.Cu")
		(net "P5E_CPU0_G3_RX_DN<10>")
	)
	(segment
		(start 365.170466 -230.22814)
		(end 365.171482 -230.228648)
		(width 0.1143)
		(layer "In11.Cu")
		(net "P5E_CPU0_G3_RX_DN<10>")
	)
	(segment
		(start 365.204248 -227.940616)
		(end 365.167926 -227.961698)
		(width 0.1143)
		(layer "In11.Cu")
		(net "P5E_CPU0_G3_RX_DN<10>")
	)
	(segment
		(start 365.165386 -240.923064)
		(end 365.16437 -240.923572)
		(width 0.1143)
		(layer "In11.Cu")
		(net "P5E_CPU0_G3_RX_DN<10>")
	)
	(segment
		(start 365.167926 -239.301528)
		(end 365.167164 -239.302036)
		(width 0.1143)
		(layer "In11.Cu")
		(net "P5E_CPU0_G3_RX_DN<10>")
	)
	(segment
		(start 365.939578 -221.38767)
		(end 365.92002 -221.407228)
		(width 0.1143)
		(layer "In11.Cu")
		(net "P5E_CPU0_G3_RX_DN<10>")
	)
	(segment
		(start 365.204248 -226.320604)
		(end 365.202724 -226.32162)
		(width 0.1143)
		(layer "In11.Cu")
		(net "P5E_CPU0_G3_RX_DN<10>")
	)
	(segment
		(start 365.166148 -239.302544)
		(end 365.165386 -239.303052)
		(width 0.1143)
		(layer "In11.Cu")
		(net "P5E_CPU0_G3_RX_DN<10>")
	)
	(segment
		(start 365.16818 -240.92154)
		(end 365.167926 -240.92154)
		(width 0.1143)
		(layer "In11.Cu")
		(net "P5E_CPU0_G3_RX_DN<10>")
	)
	(segment
		(start 365.136176 -235.068364)
		(end 365.146082 -235.073952)
		(width 0.1143)
		(layer "In11.Cu")
		(net "P5E_CPU0_G3_RX_DN<10>")
	)
	(segment
		(start 365.201454 -229.562152)
		(end 365.167926 -229.58171)
		(width 0.1143)
		(layer "In11.Cu")
		(net "P5E_CPU0_G3_RX_DN<10>")
	)
	(segment
		(start 365.939578 -221.128844)
		(end 365.939578 -221.38767)
		(width 0.1143)
		(layer "In11.Cu")
		(net "P5E_CPU0_G3_RX_DN<10>")
	)
	(segment
		(start 365.146844 -241.554508)
		(end 365.167926 -241.5667)
		(width 0.1143)
		(layer "In11.Cu")
		(net "P5E_CPU0_G3_RX_DN<10>")
	)
	(segment
		(start 365.146082 -239.933988)
		(end 365.146844 -239.934496)
		(width 0.1143)
		(layer "In11.Cu")
		(net "P5E_CPU0_G3_RX_DN<10>")
	)
	(segment
		(start 365.146082 -238.313976)
		(end 365.146844 -238.314484)
		(width 0.1143)
		(layer "In11.Cu")
		(net "P5E_CPU0_G3_RX_DN<10>")
	)
	(segment
		(start 365.167926 -243.186712)
		(end 365.204248 -243.207794)
		(width 0.1143)
		(layer "In11.Cu")
		(net "P5E_CPU0_G3_RX_DN<10>")
	)
	(segment
		(start 365.162592 -239.304576)
		(end 365.16183 -239.305084)
		(width 0.1143)
		(layer "In11.Cu")
		(net "P5E_CPU0_G3_RX_DN<10>")
	)
	(segment
		(start 365.19993 -230.245158)
		(end 365.201454 -230.246174)
		(width 0.1143)
		(layer "In11.Cu")
		(net "P5E_CPU0_G3_RX_DN<10>")
	)
	(segment
		(start 365.16437 -240.923572)
		(end 365.163608 -240.92408)
		(width 0.1143)
		(layer "In11.Cu")
		(net "P5E_CPU0_G3_RX_DN<10>")
	)
	(segment
		(start 366.135412 -223.762824)
		(end 366.136174 -223.763078)
		(width 0.1143)
		(layer "In11.Cu")
		(net "P5E_CPU0_G3_RX_DN<10>")
	)
	(segment
		(start 365.985298 -221.054676)
		(end 365.985298 -221.083124)
		(width 0.1143)
		(layer "In11.Cu")
		(net "P5E_CPU0_G3_RX_DN<10>")
	)
	(segment
		(start 403.493732 -17.871186)
		(end 403.493478 -17.871186)
		(width 0.14224)
		(layer "In11.Cu")
		(net "P5E_CPU0_G3_RX_DN<10>")
	)
	(segment
		(start 365.167926 -240.92154)
		(end 365.167164 -240.922048)
		(width 0.1143)
		(layer "In11.Cu")
		(net "P5E_CPU0_G3_RX_DN<10>")
	)
	(segment
		(start 366.072928 -223.122744)
		(end 366.070388 -223.124014)
		(width 0.1143)
		(layer "In11.Cu")
		(net "P5E_CPU0_G3_RX_DN<10>")
	)
	(segment
		(start 365.162592 -237.684564)
		(end 365.16183 -237.685072)
		(width 0.1143)
		(layer "In11.Cu")
		(net "P5E_CPU0_G3_RX_DN<10>")
	)
	(segment
		(start 403.09292 -11.808714)
		(end 403.53742 -16.322548)
		(width 0.14224)
		(layer "In11.Cu")
		(net "P5E_CPU0_G3_RX_DN<10>")
	)
	(segment
		(start 365.166148 -236.06252)
		(end 365.165386 -236.063028)
		(width 0.1143)
		(layer "In11.Cu")
		(net "P5E_CPU0_G3_RX_DN<10>")
	)
	(segment
		(start 403.467062 -17.935448)
		(end 403.460204 -17.948402)
		(width 0.14224)
		(layer "In11.Cu")
		(net "P5E_CPU0_G3_RX_DN<10>")
	)
	(segment
		(start 365.92002 -221.407228)
		(end 365.92002 -221.80423)
		(width 0.1143)
		(layer "In11.Cu")
		(net "P5E_CPU0_G3_RX_DN<10>")
	)
	(segment
		(start 365.16437 -237.683548)
		(end 365.163608 -237.684056)
		(width 0.1143)
		(layer "In11.Cu")
		(net "P5E_CPU0_G3_RX_DN<10>")
	)
	(segment
		(start 365.167926 -234.441492)
		(end 365.136176 -234.45978)
		(width 0.1143)
		(layer "In11.Cu")
		(net "P5E_CPU0_G3_RX_DN<10>")
	)
	(segment
		(start 365.16056 -237.685834)
		(end 365.136176 -237.699804)
		(width 0.1143)
		(layer "In11.Cu")
		(net "P5E_CPU0_G3_RX_DN<10>")
	)
	(segment
		(start 365.146844 -239.934496)
		(end 365.167926 -239.946688)
		(width 0.1143)
		(layer "In11.Cu")
		(net "P5E_CPU0_G3_RX_DN<10>")
	)
	(segment
		(start 365.637826 -225.53168)
		(end 365.634524 -225.533458)
		(width 0.1143)
		(layer "In11.Cu")
		(net "P5E_CPU0_G3_RX_DN<10>")
	)
	(segment
		(start 365.45012 -225.870262)
		(end 365.45012 -225.870516)
		(width 0.1143)
		(layer "In11.Cu")
		(net "P5E_CPU0_G3_RX_DN<10>")
	)
	(segment
		(start 403.493478 -17.871186)
		(end 403.467062 -17.935448)
		(width 0.14224)
		(layer "In11.Cu")
		(net "P5E_CPU0_G3_RX_DN<10>")
	)
	(segment
		(start 366.074706 -223.728026)
		(end 366.07496 -223.728026)
		(width 0.1143)
		(layer "In11.Cu")
		(net "P5E_CPU0_G3_RX_DN<10>")
	)
	(segment
		(start 365.167926 -244.161564)
		(end 365.136176 -244.179852)
		(width 0.1143)
		(layer "In11.Cu")
		(net "P5E_CPU0_G3_RX_DN<10>")
	)
	(segment
		(start 365.167926 -241.5667)
		(end 365.16818 -241.566954)
		(width 0.1143)
		(layer "In11.Cu")
		(net "P5E_CPU0_G3_RX_DN<10>")
	)
	(segment
		(start 365.167164 -228.60635)
		(end 365.167926 -228.606858)
		(width 0.1143)
		(layer "In11.Cu")
		(net "P5E_CPU0_G3_RX_DN<10>")
	)
	(segment
		(start 365.146844 -235.07446)
		(end 365.167926 -235.086652)
		(width 0.1143)
		(layer "In11.Cu")
		(net "P5E_CPU0_G3_RX_DN<10>")
	)
	(segment
		(start 312.932064 -148.472652)
		(end 310.80583 -160.574736)
		(width 0.14224)
		(layer "In11.Cu")
		(net "P5E_CPU0_G3_RX_DN<10>")
	)
	(segment
		(start 403.45995 -17.948402)
		(end 403.231604 -18.375122)
		(width 0.14224)
		(layer "In11.Cu")
		(net "P5E_CPU0_G3_RX_DN<10>")
	)
	(segment
		(start 365.171482 -230.228648)
		(end 365.19993 -230.245158)
		(width 0.1143)
		(layer "In11.Cu")
		(net "P5E_CPU0_G3_RX_DN<10>")
	)
	(segment
		(start 319.435226 -130.534918)
		(end 312.932064 -148.472652)
		(width 0.14224)
		(layer "In11.Cu")
		(net "P5E_CPU0_G3_RX_DN<10>")
	)
	(segment
		(start 365.178086 -231.195372)
		(end 365.137192 -231.219248)
		(width 0.1143)
		(layer "In11.Cu")
		(net "P5E_CPU0_G3_RX_DN<10>")
	)
	(segment
		(start 365.202724 -226.32162)
		(end 365.136176 -226.359974)
		(width 0.1143)
		(layer "In11.Cu")
		(net "P5E_CPU0_G3_RX_DN<10>")
	)
	(segment
		(start 365.167164 -242.54206)
		(end 365.166148 -242.542568)
		(width 0.1143)
		(layer "In11.Cu")
		(net "P5E_CPU0_G3_RX_DN<10>")
	)
	(segment
		(start 365.136176 -241.548412)
		(end 365.146082 -241.554)
		(width 0.1143)
		(layer "In11.Cu")
		(net "P5E_CPU0_G3_RX_DN<10>")
	)
	(segment
		(start 365.676942 -225.50882)
		(end 365.638842 -225.531172)
		(width 0.1143)
		(layer "In11.Cu")
		(net "P5E_CPU0_G3_RX_DN<10>")
	)
	(segment
		(start 365.638842 -225.531172)
		(end 365.637826 -225.53168)
		(width 0.1143)
		(layer "In11.Cu")
		(net "P5E_CPU0_G3_RX_DN<10>")
	)
	(segment
		(start 366.110012 -223.103186)
		(end 366.103408 -223.106488)
		(width 0.1143)
		(layer "In11.Cu")
		(net "P5E_CPU0_G3_RX_DN<10>")
	)
	(segment
		(start 365.166148 -237.682532)
		(end 365.165386 -237.68304)
		(width 0.1143)
		(layer "In11.Cu")
		(net "P5E_CPU0_G3_RX_DN<10>")
	)
	(segment
		(start 365.204248 -232.800398)
		(end 365.167926 -232.82148)
		(width 0.1143)
		(layer "In11.Cu")
		(net "P5E_CPU0_G3_RX_DN<10>")
	)
	(segment
		(start 365.204248 -244.140482)
		(end 365.167926 -244.161564)
		(width 0.1143)
		(layer "In11.Cu")
		(net "P5E_CPU0_G3_RX_DN<10>")
	)
	(segment
		(start 365.163608 -236.064044)
		(end 365.161576 -236.065314)
		(width 0.1143)
		(layer "In11.Cu")
		(net "P5E_CPU0_G3_RX_DN<10>")
	)
	(segment
		(start 365.167926 -227.961698)
		(end 365.136176 -227.979986)
		(width 0.1143)
		(layer "In11.Cu")
		(net "P5E_CPU0_G3_RX_DN<10>")
	)
	(segment
		(start 365.161576 -236.065314)
		(end 365.136176 -236.079792)
		(width 0.1143)
		(layer "In11.Cu")
		(net "P5E_CPU0_G3_RX_DN<10>")
	)
	(segment
		(start 365.985298 -214.837518)
		(end 365.985298 -221.054676)
		(width 0.14224)
		(layer "In11.Cu")
		(net "P5E_CPU0_G3_RX_DN<10>")
	)
	(segment
		(start 366.07496 -222.10776)
		(end 366.146842 -222.14967)
		(width 0.1143)
		(layer "In11.Cu")
		(net "P5E_CPU0_G3_RX_DN<10>")
	)
	(segment
		(start 365.167926 -236.061504)
		(end 365.167164 -236.062012)
		(width 0.1143)
		(layer "In11.Cu")
		(net "P5E_CPU0_G3_RX_DN<10>")
	)
	(segment
		(start 365.165386 -239.303052)
		(end 365.16437 -239.30356)
		(width 0.1143)
		(layer "In11.Cu")
		(net "P5E_CPU0_G3_RX_DN<10>")
	)
	(segment
		(start 366.142524 -223.081342)
		(end 366.142524 -223.081596)
		(width 0.1143)
		(layer "In11.Cu")
		(net "P5E_CPU0_G3_RX_DN<10>")
	)
	(segment
		(start 366.07496 -223.728026)
		(end 366.135412 -223.762824)
		(width 0.1143)
		(layer "In11.Cu")
		(net "P5E_CPU0_G3_RX_DN<10>")
	)
	(segment
		(start 365.13516 -229.60076)
		(end 365.134398 -229.601268)
		(width 0.1143)
		(layer "In11.Cu")
		(net "P5E_CPU0_G3_RX_DN<10>")
	)
	(segment
		(start 403.53742 -17.76476)
		(end 403.493732 -17.871186)
		(width 0.14224)
		(layer "In11.Cu")
		(net "P5E_CPU0_G3_RX_DN<10>")
	)
	(segment
		(start 365.985298 -221.083124)
		(end 365.939578 -221.128844)
		(width 0.1143)
		(layer "In11.Cu")
		(net "P5E_CPU0_G3_RX_DN<10>")
	)
	(segment
		(start 403.231604 -18.375122)
		(end 394.295122 -32.143954)
		(width 0.14224)
		(layer "In11.Cu")
		(net "P5E_CPU0_G3_RX_DN<10>")
	)
	(segment
		(start 365.146082 -236.693964)
		(end 365.146844 -236.694472)
		(width 0.1143)
		(layer "In11.Cu")
		(net "P5E_CPU0_G3_RX_DN<10>")
	)
	(segment
		(start 365.163608 -240.92408)
		(end 365.162592 -240.924588)
		(width 0.1143)
		(layer "In11.Cu")
		(net "P5E_CPU0_G3_RX_DN<10>")
	)
	(segment
		(start 365.136176 -236.688376)
		(end 365.146082 -236.693964)
		(width 0.1143)
		(layer "In11.Cu")
		(net "P5E_CPU0_G3_RX_DN<10>")
	)
	(segment
		(start 365.16183 -242.545108)
		(end 365.16056 -242.54587)
		(width 0.1143)
		(layer "In11.Cu")
		(net "P5E_CPU0_G3_RX_DN<10>")
	)
	(segment
		(start 365.146844 -238.314484)
		(end 365.167926 -238.326676)
		(width 0.1143)
		(layer "In11.Cu")
		(net "P5E_CPU0_G3_RX_DN<10>")
	)
	(segment
		(start 365.163608 -239.304068)
		(end 365.162592 -239.304576)
		(width 0.1143)
		(layer "In11.Cu")
		(net "P5E_CPU0_G3_RX_DN<10>")
	)
	(segment
		(start 365.136176 -230.208328)
		(end 365.167926 -230.226616)
		(width 0.1143)
		(layer "In11.Cu")
		(net "P5E_CPU0_G3_RX_DN<10>")
	)
	(segment
		(start 366.146842 -223.078802)
		(end 366.142524 -223.081342)
		(width 0.1143)
		(layer "In11.Cu")
		(net "P5E_CPU0_G3_RX_DN<10>")
	)
	(segment
		(start 317.046864 -171.632626)
		(end 322.490084 -174.89551)
		(width 0.14224)
		(layer "In11.Cu")
		(net "P5E_CPU0_G3_RX_DN<10>")
	)
	(segment
		(start 365.166148 -242.542568)
		(end 365.165386 -242.543076)
		(width 0.1143)
		(layer "In11.Cu")
		(net "P5E_CPU0_G3_RX_DN<10>")
	)
	(segment
		(start 366.142524 -223.081596)
		(end 366.110012 -223.103186)
		(width 0.1143)
		(layer "In11.Cu")
		(net "P5E_CPU0_G3_RX_DN<10>")
	)
	(segment
		(start 312.894726 -167.479726)
		(end 317.046864 -171.632626)
		(width 0.14224)
		(layer "In11.Cu")
		(net "P5E_CPU0_G3_RX_DN<10>")
	)
	(segment
		(start 366.146842 -224.698814)
		(end 366.077246 -224.739454)
		(width 0.1143)
		(layer "In11.Cu")
		(net "P5E_CPU0_G3_RX_DN<10>")
	)
	(segment
		(start 366.103408 -223.106488)
		(end 366.085882 -223.116902)
		(width 0.1143)
		(layer "In11.Cu")
		(net "P5E_CPU0_G3_RX_DN<10>")
	)
	(segment
		(start 365.167926 -231.846628)
		(end 365.204248 -231.86771)
		(width 0.1143)
		(layer "In11.Cu")
		(net "P5E_CPU0_G3_RX_DN<10>")
	)
	(segment
		(start 365.167926 -239.946688)
		(end 365.16818 -239.946942)
		(width 0.1143)
		(layer "In11.Cu")
		(net "P5E_CPU0_G3_RX_DN<10>")
	)
	(segment
		(start 310.80583 -160.574736)
		(end 310.80583 -162.500056)
		(width 0.14224)
		(layer "In11.Cu")
		(net "P5E_CPU0_G3_RX_DN<10>")
	)
	(segment
		(start 365.167164 -237.682024)
		(end 365.166148 -237.682532)
		(width 0.1143)
		(layer "In11.Cu")
		(net "P5E_CPU0_G3_RX_DN<10>")
	)
	(segment
		(start 365.167926 -232.82148)
		(end 365.136176 -232.839768)
		(width 0.1143)
		(layer "In11.Cu")
		(net "P5E_CPU0_G3_RX_DN<10>")
	)
	(segment
		(start 403.09292 -5.254244)
		(end 403.09292 -11.808714)
		(width 0.14224)
		(layer "In11.Cu")
		(net "P5E_CPU0_G3_RX_DN<10>")
	)
	(segment
		(start 365.136176 -239.9284)
		(end 365.146082 -239.933988)
		(width 0.1143)
		(layer "In11.Cu")
		(net "P5E_CPU0_G3_RX_DN<10>")
	)
	(segment
		(start 365.611664 -225.54692)
		(end 365.610648 -225.547428)
		(width 0.1143)
		(layer "In11.Cu")
		(net "P5E_CPU0_G3_RX_DN<10>")
	)
	(segment
		(start 365.16056 -242.54587)
		(end 365.136176 -242.55984)
		(width 0.1143)
		(layer "In11.Cu")
		(net "P5E_CPU0_G3_RX_DN<10>")
	)
	(segment
		(start 365.136176 -243.168424)
		(end 365.167926 -243.186712)
		(width 0.1143)
		(layer "In11.Cu")
		(net "P5E_CPU0_G3_RX_DN<10>")
	)
	(segment
		(start 365.168942 -230.227124)
		(end 365.170466 -230.22814)
		(width 0.1143)
		(layer "In11.Cu")
		(net "P5E_CPU0_G3_RX_DN<10>")
	)
	(segment
		(start 365.167926 -238.326676)
		(end 365.16818 -238.32693)
		(width 0.1143)
		(layer "In11.Cu")
		(net "P5E_CPU0_G3_RX_DN<10>")
	)
	(segment
		(start 365.165386 -236.063028)
		(end 365.16437 -236.063536)
		(width 0.1143)
		(layer "In11.Cu")
		(net "P5E_CPU0_G3_RX_DN<10>")
	)
	(segment
		(start 365.146082 -235.073952)
		(end 365.146844 -235.07446)
		(width 0.1143)
		(layer "In11.Cu")
		(net "P5E_CPU0_G3_RX_DN<10>")
	)
	(segment
		(start 365.16818 -239.301528)
		(end 365.167926 -239.301528)
		(width 0.1143)
		(layer "In11.Cu")
		(net "P5E_CPU0_G3_RX_DN<10>")
	)
	(segment
		(start 365.056928 -244.484144)
		(end 365.35487 -244.484144)
		(width 0.1143)
		(layer "In11.Cu")
		(net "P5E_CPU0_G3_RX_DN<10>")
	)
	(segment
		(start 365.16818 -236.061504)
		(end 365.167926 -236.061504)
		(width 0.1143)
		(layer "In11.Cu")
		(net "P5E_CPU0_G3_RX_DN<10>")
	)
	(segment
		(start 365.167926 -242.541552)
		(end 365.167164 -242.54206)
		(width 0.1143)
		(layer "In11.Cu")
		(net "P5E_CPU0_G3_RX_DN<10>")
	)
	(segment
		(start 310.80583 -162.500056)
		(end 312.824876 -167.374824)
		(width 0.14224)
		(layer "In11.Cu")
		(net "P5E_CPU0_G3_RX_DN<10>")
	)
	(segment
		(start 394.295122 -32.143954)
		(end 321.936618 -125.981968)
		(width 0.14224)
		(layer "In11.Cu")
		(net "P5E_CPU0_G3_RX_DN<10>")
	)
	(segment
		(start 365.204248 -229.560628)
		(end 365.201454 -229.562152)
		(width 0.1143)
		(layer "In11.Cu")
		(net "P5E_CPU0_G3_RX_DN<10>")
	)
	(segment
		(start 365.61395 -225.545396)
		(end 365.611664 -225.54692)
		(width 0.1143)
		(layer "In11.Cu")
		(net "P5E_CPU0_G3_RX_DN<10>")
	)
	(segment
		(start 366.144048 -223.76765)
		(end 366.14608 -223.76892)
		(width 0.1143)
		(layer "In11.Cu")
		(net "P5E_CPU0_G3_RX_DN<10>")
	)
	(segment
		(start 365.136176 -228.58857)
		(end 365.165894 -228.605588)
		(width 0.1143)
		(layer "In11.Cu")
		(net "P5E_CPU0_G3_RX_DN<10>")
	)
	(arc
		(start 365.167926 -228.606858)
		(mid 365.374549 -228.812637)
		(end 365.45012 -229.094284)
		(width 0.1143)
		(layer "In11.Cu")
		(net "P5E_CPU0_G3_RX_DN<10>")
	)
	(arc
		(start 365.134398 -229.601268)
		(mid 365.020991 -229.734157)
		(end 364.98022 -229.904036)
		(width 0.1143)
		(layer "In11.Cu")
		(net "P5E_CPU0_G3_RX_DN<10>")
	)
	(arc
		(start 366.146842 -223.769682)
		(mid 366.390169 -224.234248)
		(end 366.146842 -224.698814)
		(width 0.1143)
		(layer "In11.Cu")
		(net "P5E_CPU0_G3_RX_DN<10>")
	)
	(arc
		(start 365.134398 -231.22128)
		(mid 365.020991 -231.354169)
		(end 364.98022 -231.524048)
		(width 0.1143)
		(layer "In11.Cu")
		(net "P5E_CPU0_G3_RX_DN<10>")
	)
	(arc
		(start 365.204248 -233.487722)
		(mid 365.211397 -233.492622)
		(end 365.218472 -233.497628)
		(width 0.1143)
		(layer "In11.Cu")
		(net "P5E_CPU0_G3_RX_DN<10>")
	)
	(arc
		(start 365.21771 -229.550976)
		(mid 365.211015 -229.555852)
		(end 365.204248 -229.560628)
		(width 0.1143)
		(layer "In11.Cu")
		(net "P5E_CPU0_G3_RX_DN<10>")
	)
	(arc
		(start 365.220504 -244.129052)
		(mid 365.212426 -244.134838)
		(end 365.204248 -244.140482)
		(width 0.1143)
		(layer "In11.Cu")
		(net "P5E_CPU0_G3_RX_DN<10>")
	)
	(arc
		(start 365.45012 -230.710486)
		(mid 365.380105 -230.989949)
		(end 365.178086 -231.195372)
		(width 0.1143)
		(layer "In11.Cu")
		(net "P5E_CPU0_G3_RX_DN<10>")
	)
	(arc
		(start 365.204248 -243.207794)
		(mid 365.212426 -243.213437)
		(end 365.220504 -243.219224)
		(width 0.1143)
		(layer "In11.Cu")
		(net "P5E_CPU0_G3_RX_DN<10>")
	)
	(arc
		(start 366.146842 -222.14967)
		(mid 366.390169 -222.614236)
		(end 366.146842 -223.078802)
		(width 0.1143)
		(layer "In11.Cu")
		(net "P5E_CPU0_G3_RX_DN<10>")
	)
	(arc
		(start 365.16818 -241.566954)
		(mid 365.448827 -242.054316)
		(end 365.16818 -242.541552)
		(width 0.1143)
		(layer "In11.Cu")
		(net "P5E_CPU0_G3_RX_DN<10>")
	)
	(arc
		(start 364.98022 -229.904036)
		(mid 365.021475 -230.075007)
		(end 365.136176 -230.208328)
		(width 0.1143)
		(layer "In11.Cu")
		(net "P5E_CPU0_G3_RX_DN<10>")
	)
	(arc
		(start 364.98022 -231.524048)
		(mid 365.021475 -231.695019)
		(end 365.136176 -231.82834)
		(width 0.1143)
		(layer "In11.Cu")
		(net "P5E_CPU0_G3_RX_DN<10>")
	)
	(arc
		(start 366.077246 -224.739454)
		(mid 365.961819 -224.87283)
		(end 365.920274 -225.044254)
		(width 0.1143)
		(layer "In11.Cu")
		(net "P5E_CPU0_G3_RX_DN<10>")
	)
	(arc
		(start 365.920274 -225.044254)
		(mid 365.855759 -225.306473)
		(end 365.676942 -225.50882)
		(width 0.1143)
		(layer "In11.Cu")
		(net "P5E_CPU0_G3_RX_DN<10>")
	)
	(arc
		(start 365.220504 -227.929186)
		(mid 365.212426 -227.934972)
		(end 365.204248 -227.940616)
		(width 0.1143)
		(layer "In11.Cu")
		(net "P5E_CPU0_G3_RX_DN<10>")
	)
	(arc
		(start 365.92002 -221.80423)
		(mid 365.960986 -221.974636)
		(end 366.07496 -222.10776)
		(width 0.1143)
		(layer "In11.Cu")
		(net "P5E_CPU0_G3_RX_DN<10>")
	)
	(arc
		(start 365.218472 -234.410504)
		(mid 365.211398 -234.415511)
		(end 365.204248 -234.42041)
		(width 0.1143)
		(layer "In11.Cu")
		(net "P5E_CPU0_G3_RX_DN<10>")
	)
	(arc
		(start 365.45012 -229.094284)
		(mid 365.388675 -229.350496)
		(end 365.21771 -229.550976)
		(width 0.1143)
		(layer "In11.Cu")
		(net "P5E_CPU0_G3_RX_DN<10>")
	)
	(arc
		(start 365.136176 -239.319816)
		(mid 364.980248 -239.624108)
		(end 365.136176 -239.9284)
		(width 0.1143)
		(layer "In11.Cu")
		(net "P5E_CPU0_G3_RX_DN<10>")
	)
	(arc
		(start 365.136176 -236.079792)
		(mid 364.980248 -236.384084)
		(end 365.136176 -236.688376)
		(width 0.1143)
		(layer "In11.Cu")
		(net "P5E_CPU0_G3_RX_DN<10>")
	)
	(arc
		(start 365.220504 -231.87914)
		(mid 365.443388 -232.334054)
		(end 365.220504 -232.788968)
		(width 0.1143)
		(layer "In11.Cu")
		(net "P5E_CPU0_G3_RX_DN<10>")
	)
	(arc
		(start 365.45012 -225.870516)
		(mid 365.381159 -226.125047)
		(end 365.204248 -226.320604)
		(width 0.1143)
		(layer "In11.Cu")
		(net "P5E_CPU0_G3_RX_DN<10>")
	)
	(arc
		(start 365.218472 -233.497628)
		(mid 365.445855 -233.954066)
		(end 365.218472 -234.410504)
		(width 0.1143)
		(layer "In11.Cu")
		(net "P5E_CPU0_G3_RX_DN<10>")
	)
	(arc
		(start 365.201454 -230.246174)
		(mid 365.209887 -230.251814)
		(end 365.218218 -230.257604)
		(width 0.1143)
		(layer "In11.Cu")
		(net "P5E_CPU0_G3_RX_DN<10>")
	)
	(arc
		(start 365.16818 -239.946942)
		(mid 365.448827 -240.434304)
		(end 365.16818 -240.92154)
		(width 0.1143)
		(layer "In11.Cu")
		(net "P5E_CPU0_G3_RX_DN<10>")
	)
	(arc
		(start 365.204248 -227.007928)
		(mid 365.212426 -227.013571)
		(end 365.220504 -227.019358)
		(width 0.1143)
		(layer "In11.Cu")
		(net "P5E_CPU0_G3_RX_DN<10>")
	)
	(arc
		(start 365.16818 -238.32693)
		(mid 365.448827 -238.814292)
		(end 365.16818 -239.301528)
		(width 0.1143)
		(layer "In11.Cu")
		(net "P5E_CPU0_G3_RX_DN<10>")
	)
	(arc
		(start 365.136176 -237.699804)
		(mid 364.980248 -238.004096)
		(end 365.136176 -238.308388)
		(width 0.1143)
		(layer "In11.Cu")
		(net "P5E_CPU0_G3_RX_DN<10>")
	)
	(arc
		(start 365.610648 -225.547428)
		(mid 365.606048 -225.550949)
		(end 365.601504 -225.55454)
		(width 0.1143)
		(layer "In11.Cu")
		(net "P5E_CPU0_G3_RX_DN<10>")
	)
	(arc
		(start 365.220504 -232.788968)
		(mid 365.212426 -232.794754)
		(end 365.204248 -232.800398)
		(width 0.1143)
		(layer "In11.Cu")
		(net "P5E_CPU0_G3_RX_DN<10>")
	)
	(arc
		(start 365.220504 -243.219224)
		(mid 365.443388 -243.674138)
		(end 365.220504 -244.129052)
		(width 0.1143)
		(layer "In11.Cu")
		(net "P5E_CPU0_G3_RX_DN<10>")
	)
	(arc
		(start 365.136176 -242.55984)
		(mid 364.980248 -242.864132)
		(end 365.136176 -243.168424)
		(width 0.1143)
		(layer "In11.Cu")
		(net "P5E_CPU0_G3_RX_DN<10>")
	)
	(arc
		(start 365.204248 -231.86771)
		(mid 365.212426 -231.873353)
		(end 365.220504 -231.87914)
		(width 0.1143)
		(layer "In11.Cu")
		(net "P5E_CPU0_G3_RX_DN<10>")
	)
	(arc
		(start 365.601504 -225.55454)
		(mid 365.507587 -225.679624)
		(end 365.454692 -225.826828)
		(width 0.1143)
		(layer "In11.Cu")
		(net "P5E_CPU0_G3_RX_DN<10>")
	)
	(arc
		(start 365.136176 -240.939828)
		(mid 364.980248 -241.24412)
		(end 365.136176 -241.548412)
		(width 0.1143)
		(layer "In11.Cu")
		(net "P5E_CPU0_G3_RX_DN<10>")
	)
	(arc
		(start 365.16818 -236.706918)
		(mid 365.448827 -237.19428)
		(end 365.16818 -237.681516)
		(width 0.1143)
		(layer "In11.Cu")
		(net "P5E_CPU0_G3_RX_DN<10>")
	)
	(arc
		(start 365.220504 -227.019358)
		(mid 365.443388 -227.474272)
		(end 365.220504 -227.929186)
		(width 0.1143)
		(layer "In11.Cu")
		(net "P5E_CPU0_G3_RX_DN<10>")
	)
	(arc
		(start 365.16818 -235.086906)
		(mid 365.448827 -235.574268)
		(end 365.16818 -236.061504)
		(width 0.1143)
		(layer "In11.Cu")
		(net "P5E_CPU0_G3_RX_DN<10>")
	)
	(arc
		(start 365.218218 -230.257604)
		(mid 365.386394 -230.457307)
		(end 365.45012 -230.710486)
		(width 0.1143)
		(layer "In11.Cu")
		(net "P5E_CPU0_G3_RX_DN<10>")
	)
	(arc
		(start 365.136176 -226.359974)
		(mid 364.980248 -226.664266)
		(end 365.136176 -226.968558)
		(width 0.1143)
		(layer "In11.Cu")
		(net "P5E_CPU0_G3_RX_DN<10>")
	)
	(arc
		(start 365.136176 -232.839768)
		(mid 364.980248 -233.14406)
		(end 365.136176 -233.448352)
		(width 0.1143)
		(layer "In11.Cu")
		(net "P5E_CPU0_G3_RX_DN<10>")
	)
	(arc
		(start 366.070388 -223.124014)
		(mid 365.920029 -223.427139)
		(end 366.074706 -223.728026)
		(width 0.1143)
		(layer "In11.Cu")
		(net "P5E_CPU0_G3_RX_DN<10>")
	)
	(arc
		(start 365.136176 -234.45978)
		(mid 364.980248 -234.764072)
		(end 365.136176 -235.068364)
		(width 0.1143)
		(layer "In11.Cu")
		(net "P5E_CPU0_G3_RX_DN<10>")
	)
	(arc
		(start 365.136176 -244.179852)
		(mid 365.039041 -244.282721)
		(end 364.987078 -244.414294)
		(width 0.1143)
		(layer "In11.Cu")
		(net "P5E_CPU0_G3_RX_DN<10>")
	)
	(arc
		(start 365.136176 -227.979986)
		(mid 364.980248 -228.284278)
		(end 365.136176 -228.58857)
		(width 0.1143)
		(layer "In11.Cu")
		(net "P5E_CPU0_G3_RX_DN<10>")
	)
	(arc
		(start 365.454692 -225.826828)
		(mid 365.451507 -225.84845)
		(end 365.45012 -225.870262)
		(width 0.1143)
		(layer "In11.Cu")
		(net "P5E_CPU0_G3_RX_DN<10>")
	)
	(segment
		(start 430.628298 -5.239004)
		(end 430.628298 -7.57047)
		(width 0.12954)
		(layer "F.Cu")
		(net "P5E_CPU0_G3_RX_DN<0>")
	)
	(segment
		(start 430.767236 -7.709408)
		(end 430.766982 -7.709662)
		(width 0.12954)
		(layer "F.Cu")
		(net "P5E_CPU0_G3_RX_DN<0>")
	)
	(segment
		(start 373.347996 -246.370094)
		(end 373.814848 -246.104156)
		(width 0.12954)
		(layer "F.Cu")
		(net "P5E_CPU0_G3_RX_DN<0>")
	)
	(segment
		(start 430.628298 -7.57047)
		(end 430.767236 -7.709408)
		(width 0.12954)
		(layer "F.Cu")
		(net "P5E_CPU0_G3_RX_DN<0>")
	)
	(segment
		(start 430.903888 -4.963414)
		(end 430.628298 -5.239004)
		(width 0.12954)
		(layer "F.Cu")
		(net "P5E_CPU0_G3_RX_DN<0>")
	)
	(segment
		(start 430.766982 -7.709662)
		(end 430.766982 -8.320024)
		(width 0.12954)
		(layer "F.Cu")
		(net "P5E_CPU0_G3_RX_DN<0>")
	)
	(segment
		(start 429.62068 -21.173948)
		(end 426.733462 -24.62784)
		(width 0.14224)
		(layer "In11.Cu")
		(net "P5E_CPU0_G3_RX_DN<0>")
	)
	(segment
		(start 368.396266 -200.175622)
		(end 376.56389 -214.002366)
		(width 0.14224)
		(layer "In11.Cu")
		(net "P5E_CPU0_G3_RX_DN<0>")
	)
	(segment
		(start 373.447056 -246.034306)
		(end 373.516906 -246.104156)
		(width 0.1143)
		(layer "In11.Cu")
		(net "P5E_CPU0_G3_RX_DN<0>")
	)
	(segment
		(start 376.957082 -222.268796)
		(end 376.886216 -222.309944)
		(width 0.1143)
		(layer "In11.Cu")
		(net "P5E_CPU0_G3_RX_DN<0>")
	)
	(segment
		(start 431.817272 -17.080484)
		(end 431.817272 -17.765014)
		(width 0.14224)
		(layer "In11.Cu")
		(net "P5E_CPU0_G3_RX_DN<0>")
	)
	(segment
		(start 376.016774 -223.888808)
		(end 375.946162 -223.93021)
		(width 0.1143)
		(layer "In11.Cu")
		(net "P5E_CPU0_G3_RX_DN<0>")
	)
	(segment
		(start 374.60682 -226.318826)
		(end 374.537224 -226.359466)
		(width 0.1143)
		(layer "In11.Cu")
		(net "P5E_CPU0_G3_RX_DN<0>")
	)
	(segment
		(start 431.093372 -19.00047)
		(end 431.08626 -19.01698)
		(width 0.14224)
		(layer "In11.Cu")
		(net "P5E_CPU0_G3_RX_DN<0>")
	)
	(segment
		(start 377.20016 -221.248478)
		(end 377.20016 -221.80423)
		(width 0.1143)
		(layer "In11.Cu")
		(net "P5E_CPU0_G3_RX_DN<0>")
	)
	(segment
		(start 375.069354 -225.513392)
		(end 375.044716 -225.527616)
		(width 0.1143)
		(layer "In11.Cu")
		(net "P5E_CPU0_G3_RX_DN<0>")
	)
	(segment
		(start 340.23554 -177.111152)
		(end 368.396266 -200.175622)
		(width 0.14224)
		(layer "In11.Cu")
		(net "P5E_CPU0_G3_RX_DN<0>")
	)
	(segment
		(start 373.897652 -245.303548)
		(end 373.897652 -245.3132)
		(width 0.1143)
		(layer "In11.Cu")
		(net "P5E_CPU0_G3_RX_DN<0>")
	)
	(segment
		(start 328.225658 -154.303222)
		(end 334.98282 -167.177466)
		(width 0.14224)
		(layer "In11.Cu")
		(net "P5E_CPU0_G3_RX_DN<0>")
	)
	(segment
		(start 375.559828 -224.68967)
		(end 375.549922 -224.697036)
		(width 0.1143)
		(layer "In11.Cu")
		(net "P5E_CPU0_G3_RX_DN<0>")
	)
	(segment
		(start 377.24588 -219.23502)
		(end 377.24588 -221.17431)
		(width 0.14224)
		(layer "In11.Cu")
		(net "P5E_CPU0_G3_RX_DN<0>")
	)
	(segment
		(start 327.580498 -136.106916)
		(end 327.269094 -137.364978)
		(width 0.14224)
		(layer "In11.Cu")
		(net "P5E_CPU0_G3_RX_DN<0>")
	)
	(segment
		(start 374.567704 -229.58171)
		(end 374.535192 -229.600506)
		(width 0.1143)
		(layer "In11.Cu")
		(net "P5E_CPU0_G3_RX_DN<0>")
	)
	(segment
		(start 376.56389 -214.002366)
		(end 377.24588 -219.23502)
		(width 0.14224)
		(layer "In11.Cu")
		(net "P5E_CPU0_G3_RX_DN<0>")
	)
	(segment
		(start 376.450352 -223.100138)
		(end 376.448828 -223.101154)
		(width 0.1143)
		(layer "In11.Cu")
		(net "P5E_CPU0_G3_RX_DN<0>")
	)
	(segment
		(start 375.549922 -224.697036)
		(end 375.479056 -224.738184)
		(width 0.1143)
		(layer "In11.Cu")
		(net "P5E_CPU0_G3_RX_DN<0>")
	)
	(segment
		(start 374.604788 -229.560374)
		(end 374.567704 -229.58171)
		(width 0.1143)
		(layer "In11.Cu")
		(net "P5E_CPU0_G3_RX_DN<0>")
	)
	(segment
		(start 375.040906 -225.529902)
		(end 375.040144 -225.53041)
		(width 0.1143)
		(layer "In11.Cu")
		(net "P5E_CPU0_G3_RX_DN<0>")
	)
	(segment
		(start 374.60682 -236.038644)
		(end 374.537224 -236.079284)
		(width 0.1143)
		(layer "In11.Cu")
		(net "P5E_CPU0_G3_RX_DN<0>")
	)
	(segment
		(start 431.817272 -17.765014)
		(end 431.74666 -17.935702)
		(width 0.14224)
		(layer "In11.Cu")
		(net "P5E_CPU0_G3_RX_DN<0>")
	)
	(segment
		(start 431.08626 -19.01698)
		(end 431.085498 -19.017996)
		(width 0.14224)
		(layer "In11.Cu")
		(net "P5E_CPU0_G3_RX_DN<0>")
	)
	(segment
		(start 374.537224 -238.308896)
		(end 374.60682 -238.349536)
		(width 0.1143)
		(layer "In11.Cu")
		(net "P5E_CPU0_G3_RX_DN<0>")
	)
	(segment
		(start 376.44705 -223.10217)
		(end 376.44578 -223.102932)
		(width 0.1143)
		(layer "In11.Cu")
		(net "P5E_CPU0_G3_RX_DN<0>")
	)
	(segment
		(start 376.486928 -223.078802)
		(end 376.451368 -223.09963)
		(width 0.1143)
		(layer "In11.Cu")
		(net "P5E_CPU0_G3_RX_DN<0>")
	)
	(segment
		(start 374.537224 -239.928908)
		(end 374.60682 -239.969548)
		(width 0.1143)
		(layer "In11.Cu")
		(net "P5E_CPU0_G3_RX_DN<0>")
	)
	(segment
		(start 376.44578 -223.102932)
		(end 376.44324 -223.104202)
		(width 0.1143)
		(layer "In11.Cu")
		(net "P5E_CPU0_G3_RX_DN<0>")
	)
	(segment
		(start 334.98282 -167.177466)
		(end 337.60664 -173.151038)
		(width 0.14224)
		(layer "In11.Cu")
		(net "P5E_CPU0_G3_RX_DN<0>")
	)
	(segment
		(start 374.537224 -231.828848)
		(end 374.60682 -231.869488)
		(width 0.1143)
		(layer "In11.Cu")
		(net "P5E_CPU0_G3_RX_DN<0>")
	)
	(segment
		(start 375.076974 -225.50882)
		(end 375.070116 -225.512884)
		(width 0.1143)
		(layer "In11.Cu")
		(net "P5E_CPU0_G3_RX_DN<0>")
	)
	(segment
		(start 373.516906 -246.104156)
		(end 373.814848 -246.104156)
		(width 0.1143)
		(layer "In11.Cu")
		(net "P5E_CPU0_G3_RX_DN<0>")
	)
	(segment
		(start 375.043954 -225.528124)
		(end 375.040906 -225.529902)
		(width 0.1143)
		(layer "In11.Cu")
		(net "P5E_CPU0_G3_RX_DN<0>")
	)
	(segment
		(start 430.903888 -4.963414)
		(end 430.613058 -5.254244)
		(width 0.14224)
		(layer "In11.Cu")
		(net "P5E_CPU0_G3_RX_DN<0>")
	)
	(segment
		(start 374.60682 -239.278668)
		(end 374.537224 -239.319308)
		(width 0.1143)
		(layer "In11.Cu")
		(net "P5E_CPU0_G3_RX_DN<0>")
	)
	(segment
		(start 375.035826 -225.53295)
		(end 375.006108 -225.549968)
		(width 0.1143)
		(layer "In11.Cu")
		(net "P5E_CPU0_G3_RX_DN<0>")
	)
	(segment
		(start 374.60682 -232.79862)
		(end 374.537224 -232.83926)
		(width 0.1143)
		(layer "In11.Cu")
		(net "P5E_CPU0_G3_RX_DN<0>")
	)
	(segment
		(start 374.60682 -229.55885)
		(end 374.604788 -229.560374)
		(width 0.1143)
		(layer "In11.Cu")
		(net "P5E_CPU0_G3_RX_DN<0>")
	)
	(segment
		(start 376.448828 -223.101154)
		(end 376.447812 -223.101662)
		(width 0.1143)
		(layer "In11.Cu")
		(net "P5E_CPU0_G3_RX_DN<0>")
	)
	(segment
		(start 377.24588 -221.202758)
		(end 377.20016 -221.248478)
		(width 0.1143)
		(layer "In11.Cu")
		(net "P5E_CPU0_G3_RX_DN<0>")
	)
	(segment
		(start 375.044716 -225.527616)
		(end 375.043954 -225.528124)
		(width 0.1143)
		(layer "In11.Cu")
		(net "P5E_CPU0_G3_RX_DN<0>")
	)
	(segment
		(start 374.537224 -243.168932)
		(end 374.60682 -243.209572)
		(width 0.1143)
		(layer "In11.Cu")
		(net "P5E_CPU0_G3_RX_DN<0>")
	)
	(segment
		(start 374.60682 -237.658656)
		(end 374.537224 -237.699296)
		(width 0.1143)
		(layer "In11.Cu")
		(net "P5E_CPU0_G3_RX_DN<0>")
	)
	(segment
		(start 376.451368 -223.09963)
		(end 376.450352 -223.100138)
		(width 0.1143)
		(layer "In11.Cu")
		(net "P5E_CPU0_G3_RX_DN<0>")
	)
	(segment
		(start 327.269094 -137.364978)
		(end 328.225658 -154.303222)
		(width 0.14224)
		(layer "In11.Cu")
		(net "P5E_CPU0_G3_RX_DN<0>")
	)
	(segment
		(start 375.789952 -224.234248)
		(end 375.789952 -224.236534)
		(width 0.1143)
		(layer "In11.Cu")
		(net "P5E_CPU0_G3_RX_DN<0>")
	)
	(segment
		(start 374.60682 -227.938838)
		(end 374.537224 -227.979478)
		(width 0.1143)
		(layer "In11.Cu")
		(net "P5E_CPU0_G3_RX_DN<0>")
	)
	(segment
		(start 374.537224 -235.068872)
		(end 374.60682 -235.109512)
		(width 0.1143)
		(layer "In11.Cu")
		(net "P5E_CPU0_G3_RX_DN<0>")
	)
	(segment
		(start 330.749402 -130.83667)
		(end 327.580498 -136.106916)
		(width 0.14224)
		(layer "In11.Cu")
		(net "P5E_CPU0_G3_RX_DN<0>")
	)
	(segment
		(start 374.537224 -228.589078)
		(end 374.60682 -228.629718)
		(width 0.1143)
		(layer "In11.Cu")
		(net "P5E_CPU0_G3_RX_DN<0>")
	)
	(segment
		(start 375.479056 -224.738184)
		(end 375.478294 -224.738692)
		(width 0.1143)
		(layer "In11.Cu")
		(net "P5E_CPU0_G3_RX_DN<0>")
	)
	(segment
		(start 375.037096 -225.532188)
		(end 375.035826 -225.53295)
		(width 0.1143)
		(layer "In11.Cu")
		(net "P5E_CPU0_G3_RX_DN<0>")
	)
	(segment
		(start 374.537224 -236.688884)
		(end 374.60682 -236.729524)
		(width 0.1143)
		(layer "In11.Cu")
		(net "P5E_CPU0_G3_RX_DN<0>")
	)
	(segment
		(start 337.60664 -173.151292)
		(end 340.23554 -177.111152)
		(width 0.14224)
		(layer "In11.Cu")
		(net "P5E_CPU0_G3_RX_DN<0>")
	)
	(segment
		(start 373.627904 -245.781576)
		(end 373.596154 -245.799864)
		(width 0.1143)
		(layer "In11.Cu")
		(net "P5E_CPU0_G3_RX_DN<0>")
	)
	(segment
		(start 374.60682 -234.418632)
		(end 374.537224 -234.459272)
		(width 0.1143)
		(layer "In11.Cu")
		(net "P5E_CPU0_G3_RX_DN<0>")
	)
	(segment
		(start 374.60682 -240.89868)
		(end 374.537224 -240.93932)
		(width 0.1143)
		(layer "In11.Cu")
		(net "P5E_CPU0_G3_RX_DN<0>")
	)
	(segment
		(start 431.511456 -18.375122)
		(end 431.093372 -19.00047)
		(width 0.14224)
		(layer "In11.Cu")
		(net "P5E_CPU0_G3_RX_DN<0>")
	)
	(segment
		(start 430.613058 -11.02614)
		(end 431.817272 -17.080484)
		(width 0.14224)
		(layer "In11.Cu")
		(net "P5E_CPU0_G3_RX_DN<0>")
	)
	(segment
		(start 374.60682 -242.518692)
		(end 374.537224 -242.559332)
		(width 0.1143)
		(layer "In11.Cu")
		(net "P5E_CPU0_G3_RX_DN<0>")
	)
	(segment
		(start 375.037858 -225.53168)
		(end 375.037096 -225.532188)
		(width 0.1143)
		(layer "In11.Cu")
		(net "P5E_CPU0_G3_RX_DN<0>")
	)
	(segment
		(start 374.537224 -226.969066)
		(end 374.60682 -227.009706)
		(width 0.1143)
		(layer "In11.Cu")
		(net "P5E_CPU0_G3_RX_DN<0>")
	)
	(segment
		(start 426.733462 -24.62784)
		(end 330.749402 -130.83667)
		(width 0.14224)
		(layer "In11.Cu")
		(net "P5E_CPU0_G3_RX_DN<0>")
	)
	(segment
		(start 374.537224 -241.54892)
		(end 374.60682 -241.58956)
		(width 0.1143)
		(layer "In11.Cu")
		(net "P5E_CPU0_G3_RX_DN<0>")
	)
	(segment
		(start 377.24588 -221.17431)
		(end 377.24588 -221.202758)
		(width 0.1143)
		(layer "In11.Cu")
		(net "P5E_CPU0_G3_RX_DN<0>")
	)
	(segment
		(start 374.13692 -244.94871)
		(end 374.085358 -244.978682)
		(width 0.1143)
		(layer "In11.Cu")
		(net "P5E_CPU0_G3_RX_DN<0>")
	)
	(segment
		(start 431.085498 -19.017996)
		(end 429.62068 -21.173948)
		(width 0.14224)
		(layer "In11.Cu")
		(net "P5E_CPU0_G3_RX_DN<0>")
	)
	(segment
		(start 375.040144 -225.53041)
		(end 375.038874 -225.531172)
		(width 0.1143)
		(layer "In11.Cu")
		(net "P5E_CPU0_G3_RX_DN<0>")
	)
	(segment
		(start 376.44324 -223.104202)
		(end 376.416062 -223.11995)
		(width 0.1143)
		(layer "In11.Cu")
		(net "P5E_CPU0_G3_RX_DN<0>")
	)
	(segment
		(start 375.070116 -225.512884)
		(end 375.069354 -225.513392)
		(width 0.1143)
		(layer "In11.Cu")
		(net "P5E_CPU0_G3_RX_DN<0>")
	)
	(segment
		(start 337.60664 -173.151038)
		(end 337.60664 -173.151292)
		(width 0.14224)
		(layer "In11.Cu")
		(net "P5E_CPU0_G3_RX_DN<0>")
	)
	(segment
		(start 374.60682 -231.178862)
		(end 374.567704 -231.201722)
		(width 0.1143)
		(layer "In11.Cu")
		(net "P5E_CPU0_G3_RX_DN<0>")
	)
	(segment
		(start 431.74666 -17.935702)
		(end 431.511456 -18.375122)
		(width 0.14224)
		(layer "In11.Cu")
		(net "P5E_CPU0_G3_RX_DN<0>")
	)
	(segment
		(start 374.567704 -231.201722)
		(end 374.535192 -231.220518)
		(width 0.1143)
		(layer "In11.Cu")
		(net "P5E_CPU0_G3_RX_DN<0>")
	)
	(segment
		(start 374.537224 -230.208836)
		(end 374.60428 -230.247952)
		(width 0.1143)
		(layer "In11.Cu")
		(net "P5E_CPU0_G3_RX_DN<0>")
	)
	(segment
		(start 374.60682 -244.138704)
		(end 374.537224 -244.179344)
		(width 0.1143)
		(layer "In11.Cu")
		(net "P5E_CPU0_G3_RX_DN<0>")
	)
	(segment
		(start 375.478294 -224.738692)
		(end 375.477278 -224.739454)
		(width 0.1143)
		(layer "In11.Cu")
		(net "P5E_CPU0_G3_RX_DN<0>")
	)
	(segment
		(start 430.613058 -5.254244)
		(end 430.613058 -11.02614)
		(width 0.14224)
		(layer "In11.Cu")
		(net "P5E_CPU0_G3_RX_DN<0>")
	)
	(segment
		(start 376.447812 -223.101662)
		(end 376.44705 -223.10217)
		(width 0.1143)
		(layer "In11.Cu")
		(net "P5E_CPU0_G3_RX_DN<0>")
	)
	(segment
		(start 375.038874 -225.531172)
		(end 375.037858 -225.53168)
		(width 0.1143)
		(layer "In11.Cu")
		(net "P5E_CPU0_G3_RX_DN<0>")
	)
	(segment
		(start 374.537224 -233.44886)
		(end 374.60682 -233.4895)
		(width 0.1143)
		(layer "In11.Cu")
		(net "P5E_CPU0_G3_RX_DN<0>")
	)
	(arc
		(start 374.537224 -240.93932)
		(mid 374.380247 -241.24412)
		(end 374.537224 -241.54892)
		(width 0.1143)
		(layer "In11.Cu")
		(net "P5E_CPU0_G3_RX_DN<0>")
	)
	(arc
		(start 376.260106 -223.424242)
		(mid 376.195591 -223.686461)
		(end 376.016774 -223.888808)
		(width 0.1143)
		(layer "In11.Cu")
		(net "P5E_CPU0_G3_RX_DN<0>")
	)
	(arc
		(start 374.60682 -227.009706)
		(mid 374.850147 -227.474272)
		(end 374.60682 -227.938838)
		(width 0.1143)
		(layer "In11.Cu")
		(net "P5E_CPU0_G3_RX_DN<0>")
	)
	(arc
		(start 374.380252 -231.524048)
		(mid 374.421801 -231.69547)
		(end 374.537224 -231.828848)
		(width 0.1143)
		(layer "In11.Cu")
		(net "P5E_CPU0_G3_RX_DN<0>")
	)
	(arc
		(start 375.477278 -224.739454)
		(mid 375.361851 -224.87283)
		(end 375.320306 -225.044254)
		(width 0.1143)
		(layer "In11.Cu")
		(net "P5E_CPU0_G3_RX_DN<0>")
	)
	(arc
		(start 374.60682 -236.729524)
		(mid 374.850147 -237.19409)
		(end 374.60682 -237.658656)
		(width 0.1143)
		(layer "In11.Cu")
		(net "P5E_CPU0_G3_RX_DN<0>")
	)
	(arc
		(start 376.73026 -222.614236)
		(mid 376.665745 -222.876455)
		(end 376.486928 -223.078802)
		(width 0.1143)
		(layer "In11.Cu")
		(net "P5E_CPU0_G3_RX_DN<0>")
	)
	(arc
		(start 374.537224 -237.699296)
		(mid 374.380247 -238.004096)
		(end 374.537224 -238.308896)
		(width 0.1143)
		(layer "In11.Cu")
		(net "P5E_CPU0_G3_RX_DN<0>")
	)
	(arc
		(start 373.596154 -245.799864)
		(mid 373.499019 -245.902733)
		(end 373.447056 -246.034306)
		(width 0.1143)
		(layer "In11.Cu")
		(net "P5E_CPU0_G3_RX_DN<0>")
	)
	(arc
		(start 373.897652 -245.3132)
		(mid 373.825396 -245.583453)
		(end 373.627904 -245.781576)
		(width 0.1143)
		(layer "In11.Cu")
		(net "P5E_CPU0_G3_RX_DN<0>")
	)
	(arc
		(start 374.085358 -244.978682)
		(mid 373.947926 -245.115941)
		(end 373.897652 -245.303548)
		(width 0.1143)
		(layer "In11.Cu")
		(net "P5E_CPU0_G3_RX_DN<0>")
	)
	(arc
		(start 374.60428 -230.247952)
		(mid 374.784932 -230.450697)
		(end 374.850152 -230.714296)
		(width 0.1143)
		(layer "In11.Cu")
		(net "P5E_CPU0_G3_RX_DN<0>")
	)
	(arc
		(start 374.850152 -225.85426)
		(mid 374.785637 -226.116479)
		(end 374.60682 -226.318826)
		(width 0.1143)
		(layer "In11.Cu")
		(net "P5E_CPU0_G3_RX_DN<0>")
	)
	(arc
		(start 374.537224 -236.079284)
		(mid 374.380247 -236.384084)
		(end 374.537224 -236.688884)
		(width 0.1143)
		(layer "In11.Cu")
		(net "P5E_CPU0_G3_RX_DN<0>")
	)
	(arc
		(start 375.006108 -225.549968)
		(mid 374.891432 -225.683302)
		(end 374.850152 -225.85426)
		(width 0.1143)
		(layer "In11.Cu")
		(net "P5E_CPU0_G3_RX_DN<0>")
	)
	(arc
		(start 374.60682 -238.349536)
		(mid 374.850147 -238.814102)
		(end 374.60682 -239.278668)
		(width 0.1143)
		(layer "In11.Cu")
		(net "P5E_CPU0_G3_RX_DN<0>")
	)
	(arc
		(start 376.886216 -222.309944)
		(mid 376.77154 -222.443278)
		(end 376.73026 -222.614236)
		(width 0.1143)
		(layer "In11.Cu")
		(net "P5E_CPU0_G3_RX_DN<0>")
	)
	(arc
		(start 374.537224 -234.459272)
		(mid 374.380247 -234.764072)
		(end 374.537224 -235.068872)
		(width 0.1143)
		(layer "In11.Cu")
		(net "P5E_CPU0_G3_RX_DN<0>")
	)
	(arc
		(start 374.60682 -228.629718)
		(mid 374.850147 -229.094284)
		(end 374.60682 -229.55885)
		(width 0.1143)
		(layer "In11.Cu")
		(net "P5E_CPU0_G3_RX_DN<0>")
	)
	(arc
		(start 374.60682 -233.4895)
		(mid 374.850147 -233.954066)
		(end 374.60682 -234.418632)
		(width 0.1143)
		(layer "In11.Cu")
		(net "P5E_CPU0_G3_RX_DN<0>")
	)
	(arc
		(start 374.60682 -235.109512)
		(mid 374.850147 -235.574078)
		(end 374.60682 -236.038644)
		(width 0.1143)
		(layer "In11.Cu")
		(net "P5E_CPU0_G3_RX_DN<0>")
	)
	(arc
		(start 377.20016 -221.80423)
		(mid 377.135713 -222.066382)
		(end 376.957082 -222.268796)
		(width 0.1143)
		(layer "In11.Cu")
		(net "P5E_CPU0_G3_RX_DN<0>")
	)
	(arc
		(start 374.380252 -244.484144)
		(mid 374.315737 -244.746363)
		(end 374.13692 -244.94871)
		(width 0.1143)
		(layer "In11.Cu")
		(net "P5E_CPU0_G3_RX_DN<0>")
	)
	(arc
		(start 374.535192 -231.220518)
		(mid 374.421263 -231.353665)
		(end 374.380252 -231.524048)
		(width 0.1143)
		(layer "In11.Cu")
		(net "P5E_CPU0_G3_RX_DN<0>")
	)
	(arc
		(start 374.537224 -227.979478)
		(mid 374.380247 -228.284278)
		(end 374.537224 -228.589078)
		(width 0.1143)
		(layer "In11.Cu")
		(net "P5E_CPU0_G3_RX_DN<0>")
	)
	(arc
		(start 374.60682 -241.58956)
		(mid 374.850147 -242.054126)
		(end 374.60682 -242.518692)
		(width 0.1143)
		(layer "In11.Cu")
		(net "P5E_CPU0_G3_RX_DN<0>")
	)
	(arc
		(start 375.789952 -224.236534)
		(mid 375.729189 -224.490685)
		(end 375.559828 -224.68967)
		(width 0.1143)
		(layer "In11.Cu")
		(net "P5E_CPU0_G3_RX_DN<0>")
	)
	(arc
		(start 375.946162 -223.93021)
		(mid 375.831319 -224.063358)
		(end 375.789952 -224.234248)
		(width 0.1143)
		(layer "In11.Cu")
		(net "P5E_CPU0_G3_RX_DN<0>")
	)
	(arc
		(start 374.537224 -242.559332)
		(mid 374.380247 -242.864132)
		(end 374.537224 -243.168932)
		(width 0.1143)
		(layer "In11.Cu")
		(net "P5E_CPU0_G3_RX_DN<0>")
	)
	(arc
		(start 374.537224 -226.359466)
		(mid 374.380247 -226.664266)
		(end 374.537224 -226.969066)
		(width 0.1143)
		(layer "In11.Cu")
		(net "P5E_CPU0_G3_RX_DN<0>")
	)
	(arc
		(start 374.850152 -230.714296)
		(mid 374.785637 -230.976515)
		(end 374.60682 -231.178862)
		(width 0.1143)
		(layer "In11.Cu")
		(net "P5E_CPU0_G3_RX_DN<0>")
	)
	(arc
		(start 374.380252 -229.904036)
		(mid 374.421801 -230.075458)
		(end 374.537224 -230.208836)
		(width 0.1143)
		(layer "In11.Cu")
		(net "P5E_CPU0_G3_RX_DN<0>")
	)
	(arc
		(start 374.537224 -244.179344)
		(mid 374.421797 -244.31272)
		(end 374.380252 -244.484144)
		(width 0.1143)
		(layer "In11.Cu")
		(net "P5E_CPU0_G3_RX_DN<0>")
	)
	(arc
		(start 374.60682 -231.869488)
		(mid 374.850147 -232.334054)
		(end 374.60682 -232.79862)
		(width 0.1143)
		(layer "In11.Cu")
		(net "P5E_CPU0_G3_RX_DN<0>")
	)
	(arc
		(start 374.535192 -229.600506)
		(mid 374.421263 -229.733653)
		(end 374.380252 -229.904036)
		(width 0.1143)
		(layer "In11.Cu")
		(net "P5E_CPU0_G3_RX_DN<0>")
	)
	(arc
		(start 374.60682 -239.969548)
		(mid 374.850147 -240.434114)
		(end 374.60682 -240.89868)
		(width 0.1143)
		(layer "In11.Cu")
		(net "P5E_CPU0_G3_RX_DN<0>")
	)
	(arc
		(start 374.537224 -232.83926)
		(mid 374.380247 -233.14406)
		(end 374.537224 -233.44886)
		(width 0.1143)
		(layer "In11.Cu")
		(net "P5E_CPU0_G3_RX_DN<0>")
	)
	(arc
		(start 376.416062 -223.11995)
		(mid 376.301386 -223.253284)
		(end 376.260106 -223.424242)
		(width 0.1143)
		(layer "In11.Cu")
		(net "P5E_CPU0_G3_RX_DN<0>")
	)
	(arc
		(start 374.537224 -239.319308)
		(mid 374.380247 -239.624108)
		(end 374.537224 -239.928908)
		(width 0.1143)
		(layer "In11.Cu")
		(net "P5E_CPU0_G3_RX_DN<0>")
	)
	(arc
		(start 375.320306 -225.044254)
		(mid 375.255791 -225.306473)
		(end 375.076974 -225.50882)
		(width 0.1143)
		(layer "In11.Cu")
		(net "P5E_CPU0_G3_RX_DN<0>")
	)
	(arc
		(start 374.60682 -243.209572)
		(mid 374.850147 -243.674138)
		(end 374.60682 -244.138704)
		(width 0.1143)
		(layer "In11.Cu")
		(net "P5E_CPU0_G3_RX_DN<0>")
	)
	(segment
		(start 370.828062 -287.59023)
		(end 371.294914 -287.856168)
		(width 0.12954)
		(layer "F.Cu")
		(net "P5E_CPU0_P3_RX_DP<9>")
	)
	(segment
		(start 381.570484 -394.385292)
		(end 382.091184 -394.385292)
		(width 0.127)
		(layer "F.Cu")
		(net "P5E_CPU0_P3_RX_DP<9>")
	)
	(segment
		(start 370.168932 -294.013128)
		(end 370.168932 -294.012874)
		(width 0.1143)
		(layer "In4.Cu")
		(net "P5E_CPU0_P3_RX_DP<9>")
	)
	(segment
		(start 370.204746 -293.060374)
		(end 370.179092 -293.045642)
		(width 0.1143)
		(layer "In4.Cu")
		(net "P5E_CPU0_P3_RX_DP<9>")
	)
	(segment
		(start 370.606066 -288.361882)
		(end 370.676932 -288.320734)
		(width 0.1143)
		(layer "In4.Cu")
		(net "P5E_CPU0_P3_RX_DP<9>")
	)
	(segment
		(start 382.53797 -382.20015)
		(end 383.705862 -379.380496)
		(width 0.14224)
		(layer "In4.Cu")
		(net "P5E_CPU0_P3_RX_DP<9>")
	)
	(segment
		(start 369.697762 -290.608512)
		(end 369.667282 -290.590732)
		(width 0.1143)
		(layer "In4.Cu")
		(net "P5E_CPU0_P3_RX_DP<9>")
	)
	(segment
		(start 370.141246 -292.408864)
		(end 370.14404 -292.40734)
		(width 0.1143)
		(layer "In4.Cu")
		(net "P5E_CPU0_P3_RX_DP<9>")
	)
	(segment
		(start 370.173504 -294.01008)
		(end 370.175282 -294.00881)
		(width 0.1143)
		(layer "In4.Cu")
		(net "P5E_CPU0_P3_RX_DP<9>")
	)
	(segment
		(start 383.95529 -375.228358)
		(end 388.770114 -359.356152)
		(width 0.14224)
		(layer "In4.Cu")
		(net "P5E_CPU0_P3_RX_DP<9>")
	)
	(segment
		(start 370.1669 -292.393878)
		(end 370.186966 -292.383718)
		(width 0.1143)
		(layer "In4.Cu")
		(net "P5E_CPU0_P3_RX_DP<9>")
	)
	(segment
		(start 371.871748 -301.231808)
		(end 370.933472 -299.827696)
		(width 0.14224)
		(layer "In4.Cu")
		(net "P5E_CPU0_P3_RX_DP<9>")
	)
	(segment
		(start 370.181124 -291.426646)
		(end 370.175282 -291.422582)
		(width 0.1143)
		(layer "In4.Cu")
		(net "P5E_CPU0_P3_RX_DP<9>")
	)
	(segment
		(start 370.933472 -299.827696)
		(end 370.035328 -297.66006)
		(width 0.14224)
		(layer "In4.Cu")
		(net "P5E_CPU0_P3_RX_DP<9>")
	)
	(segment
		(start 370.16563 -293.03726)
		(end 370.135912 -293.019988)
		(width 0.1143)
		(layer "In4.Cu")
		(net "P5E_CPU0_P3_RX_DP<9>")
	)
	(segment
		(start 370.160804 -294.018462)
		(end 370.1669 -294.014398)
		(width 0.1143)
		(layer "In4.Cu")
		(net "P5E_CPU0_P3_RX_DP<9>")
	)
	(segment
		(start 370.16436 -291.416486)
		(end 370.163598 -291.415978)
		(width 0.1143)
		(layer "In4.Cu")
		(net "P5E_CPU0_P3_RX_DP<9>")
	)
	(segment
		(start 370.996972 -287.856168)
		(end 371.294914 -287.856168)
		(width 0.1143)
		(layer "In4.Cu")
		(net "P5E_CPU0_P3_RX_DP<9>")
	)
	(segment
		(start 370.168932 -293.039038)
		(end 370.167916 -293.03853)
		(width 0.1143)
		(layer "In4.Cu")
		(net "P5E_CPU0_P3_RX_DP<9>")
	)
	(segment
		(start 370.172488 -289.150298)
		(end 370.172742 -289.150552)
		(width 0.1143)
		(layer "In4.Cu")
		(net "P5E_CPU0_P3_RX_DP<9>")
	)
	(segment
		(start 370.195348 -291.436044)
		(end 370.181124 -291.426646)
		(width 0.1143)
		(layer "In4.Cu")
		(net "P5E_CPU0_P3_RX_DP<9>")
	)
	(segment
		(start 369.736878 -290.631372)
		(end 369.697762 -290.608512)
		(width 0.1143)
		(layer "In4.Cu")
		(net "P5E_CPU0_P3_RX_DP<9>")
	)
	(segment
		(start 370.165376 -294.657018)
		(end 370.165376 -294.657272)
		(width 0.1143)
		(layer "In4.Cu")
		(net "P5E_CPU0_P3_RX_DP<9>")
	)
	(segment
		(start 382.448562 -393.842494)
		(end 382.448562 -393.428982)
		(width 0.14224)
		(layer "In4.Cu")
		(net "P5E_CPU0_P3_RX_DP<9>")
	)
	(segment
		(start 370.20754 -291.443156)
		(end 370.195348 -291.436044)
		(width 0.1143)
		(layer "In4.Cu")
		(net "P5E_CPU0_P3_RX_DP<9>")
	)
	(segment
		(start 370.135912 -295.651682)
		(end 370.167662 -295.633394)
		(width 0.1143)
		(layer "In4.Cu")
		(net "P5E_CPU0_P3_RX_DP<9>")
	)
	(segment
		(start 370.14404 -292.40734)
		(end 370.144802 -292.406832)
		(width 0.1143)
		(layer "In4.Cu")
		(net "P5E_CPU0_P3_RX_DP<9>")
	)
	(segment
		(start 370.172234 -294.010842)
		(end 370.173504 -294.01008)
		(width 0.1143)
		(layer "In4.Cu")
		(net "P5E_CPU0_P3_RX_DP<9>")
	)
	(segment
		(start 370.161312 -292.396418)
		(end 370.162582 -292.39591)
		(width 0.1143)
		(layer "In4.Cu")
		(net "P5E_CPU0_P3_RX_DP<9>")
	)
	(segment
		(start 382.360424 -393.930632)
		(end 382.448562 -393.842494)
		(width 0.14224)
		(layer "In4.Cu")
		(net "P5E_CPU0_P3_RX_DP<9>")
	)
	(segment
		(start 370.175282 -294.00881)
		(end 370.188744 -294.000174)
		(width 0.1143)
		(layer "In4.Cu")
		(net "P5E_CPU0_P3_RX_DP<9>")
	)
	(segment
		(start 370.140484 -292.409372)
		(end 370.141246 -292.408864)
		(width 0.1143)
		(layer "In4.Cu")
		(net "P5E_CPU0_P3_RX_DP<9>")
	)
	(segment
		(start 370.450364 -288.66592)
		(end 370.45011 -288.66592)
		(width 0.1143)
		(layer "In4.Cu")
		(net "P5E_CPU0_P3_RX_DP<9>")
	)
	(segment
		(start 370.168932 -294.012874)
		(end 370.170456 -294.011858)
		(width 0.1143)
		(layer "In4.Cu")
		(net "P5E_CPU0_P3_RX_DP<9>")
	)
	(segment
		(start 370.168932 -294.65905)
		(end 370.167916 -294.658542)
		(width 0.1143)
		(layer "In4.Cu")
		(net "P5E_CPU0_P3_RX_DP<9>")
	)
	(segment
		(start 382.132586 -393.113006)
		(end 382.135634 -392.7348)
		(width 0.14224)
		(layer "In4.Cu")
		(net "P5E_CPU0_P3_RX_DP<9>")
	)
	(segment
		(start 369.979956 -296.382186)
		(end 369.979956 -295.955974)
		(width 0.1143)
		(layer "In4.Cu")
		(net "P5E_CPU0_P3_RX_DP<9>")
	)
	(segment
		(start 383.705862 -379.380496)
		(end 383.705862 -376.910092)
		(width 0.14224)
		(layer "In4.Cu")
		(net "P5E_CPU0_P3_RX_DP<9>")
	)
	(segment
		(start 370.207032 -294.681402)
		(end 370.170456 -294.660066)
		(width 0.1143)
		(layer "In4.Cu")
		(net "P5E_CPU0_P3_RX_DP<9>")
	)
	(segment
		(start 370.167916 -293.03853)
		(end 370.166646 -293.037768)
		(width 0.1143)
		(layer "In4.Cu")
		(net "P5E_CPU0_P3_RX_DP<9>")
	)
	(segment
		(start 370.18976 -293.999666)
		(end 370.190522 -293.999158)
		(width 0.1143)
		(layer "In4.Cu")
		(net "P5E_CPU0_P3_RX_DP<9>")
	)
	(segment
		(start 386.261102 -325.863966)
		(end 386.261102 -325.863712)
		(width 0.14224)
		(layer "In4.Cu")
		(net "P5E_CPU0_P3_RX_DP<9>")
	)
	(segment
		(start 370.163598 -291.415978)
		(end 370.162074 -291.415216)
		(width 0.1143)
		(layer "In4.Cu")
		(net "P5E_CPU0_P3_RX_DP<9>")
	)
	(segment
		(start 370.188744 -294.000174)
		(end 370.18976 -293.999666)
		(width 0.1143)
		(layer "In4.Cu")
		(net "P5E_CPU0_P3_RX_DP<9>")
	)
	(segment
		(start 370.167916 -291.418518)
		(end 370.167154 -291.41801)
		(width 0.1143)
		(layer "In4.Cu")
		(net "P5E_CPU0_P3_RX_DP<9>")
	)
	(segment
		(start 370.135912 -292.411912)
		(end 370.140484 -292.409372)
		(width 0.1143)
		(layer "In4.Cu")
		(net "P5E_CPU0_P3_RX_DP<9>")
	)
	(segment
		(start 370.170456 -294.011858)
		(end 370.172234 -294.010842)
		(width 0.1143)
		(layer "In4.Cu")
		(net "P5E_CPU0_P3_RX_DP<9>")
	)
	(segment
		(start 370.175282 -291.422836)
		(end 370.17325 -291.421566)
		(width 0.1143)
		(layer "In4.Cu")
		(net "P5E_CPU0_P3_RX_DP<9>")
	)
	(segment
		(start 370.144802 -292.406832)
		(end 370.148358 -292.404546)
		(width 0.1143)
		(layer "In4.Cu")
		(net "P5E_CPU0_P3_RX_DP<9>")
	)
	(segment
		(start 370.162582 -292.39591)
		(end 370.1669 -292.393878)
		(width 0.1143)
		(layer "In4.Cu")
		(net "P5E_CPU0_P3_RX_DP<9>")
	)
	(segment
		(start 388.78764 -336.904584)
		(end 387.386322 -329.10272)
		(width 0.14224)
		(layer "In4.Cu")
		(net "P5E_CPU0_P3_RX_DP<9>")
	)
	(segment
		(start 370.144294 -289.166808)
		(end 370.172488 -289.150298)
		(width 0.1143)
		(layer "In4.Cu")
		(net "P5E_CPU0_P3_RX_DP<9>")
	)
	(segment
		(start 380.571248 -311.832244)
		(end 371.871748 -301.231808)
		(width 0.14224)
		(layer "In4.Cu")
		(net "P5E_CPU0_P3_RX_DP<9>")
	)
	(segment
		(start 370.190522 -293.999158)
		(end 370.204492 -293.99103)
		(width 0.1143)
		(layer "In4.Cu")
		(net "P5E_CPU0_P3_RX_DP<9>")
	)
	(segment
		(start 370.170456 -293.040054)
		(end 370.168932 -293.039038)
		(width 0.1143)
		(layer "In4.Cu")
		(net "P5E_CPU0_P3_RX_DP<9>")
	)
	(segment
		(start 370.025676 -296.456354)
		(end 370.025676 -296.427906)
		(width 0.1143)
		(layer "In4.Cu")
		(net "P5E_CPU0_P3_RX_DP<9>")
	)
	(segment
		(start 370.166646 -293.037768)
		(end 370.16563 -293.03726)
		(width 0.1143)
		(layer "In4.Cu")
		(net "P5E_CPU0_P3_RX_DP<9>")
	)
	(segment
		(start 370.170456 -294.660066)
		(end 370.168932 -294.65905)
		(width 0.1143)
		(layer "In4.Cu")
		(net "P5E_CPU0_P3_RX_DP<9>")
	)
	(segment
		(start 382.091184 -394.385292)
		(end 382.18618 -394.031216)
		(width 0.14224)
		(layer "In4.Cu")
		(net "P5E_CPU0_P3_RX_DP<9>")
	)
	(segment
		(start 370.186966 -292.383718)
		(end 370.206524 -292.372542)
		(width 0.1143)
		(layer "In4.Cu")
		(net "P5E_CPU0_P3_RX_DP<9>")
	)
	(segment
		(start 370.179092 -293.045642)
		(end 370.17071 -293.0398)
		(width 0.1143)
		(layer "In4.Cu")
		(net "P5E_CPU0_P3_RX_DP<9>")
	)
	(segment
		(start 370.17325 -291.421566)
		(end 370.172234 -291.421058)
		(width 0.1143)
		(layer "In4.Cu")
		(net "P5E_CPU0_P3_RX_DP<9>")
	)
	(segment
		(start 370.17071 -293.0398)
		(end 370.170456 -293.040054)
		(width 0.1143)
		(layer "In4.Cu")
		(net "P5E_CPU0_P3_RX_DP<9>")
	)
	(segment
		(start 370.17071 -291.420042)
		(end 370.168932 -291.419026)
		(width 0.1143)
		(layer "In4.Cu")
		(net "P5E_CPU0_P3_RX_DP<9>")
	)
	(segment
		(start 382.53797 -382.365504)
		(end 382.53797 -382.20015)
		(width 0.14224)
		(layer "In4.Cu")
		(net "P5E_CPU0_P3_RX_DP<9>")
	)
	(segment
		(start 370.152422 -294.023034)
		(end 370.160804 -294.018462)
		(width 0.1143)
		(layer "In4.Cu")
		(net "P5E_CPU0_P3_RX_DP<9>")
	)
	(segment
		(start 382.135634 -392.7348)
		(end 382.400556 -392.468862)
		(width 0.14224)
		(layer "In4.Cu")
		(net "P5E_CPU0_P3_RX_DP<9>")
	)
	(segment
		(start 386.261102 -325.863712)
		(end 382.900682 -316.189868)
		(width 0.14224)
		(layer "In4.Cu")
		(net "P5E_CPU0_P3_RX_DP<9>")
	)
	(segment
		(start 370.914168 -287.938972)
		(end 370.996972 -287.856168)
		(width 0.1143)
		(layer "In4.Cu")
		(net "P5E_CPU0_P3_RX_DP<9>")
	)
	(segment
		(start 370.168932 -291.419026)
		(end 370.167916 -291.418518)
		(width 0.1143)
		(layer "In4.Cu")
		(net "P5E_CPU0_P3_RX_DP<9>")
	)
	(segment
		(start 370.166138 -294.657526)
		(end 370.165376 -294.657018)
		(width 0.1143)
		(layer "In4.Cu")
		(net "P5E_CPU0_P3_RX_DP<9>")
	)
	(segment
		(start 382.400556 -390.87044)
		(end 382.646428 -387.363716)
		(width 0.14224)
		(layer "In4.Cu")
		(net "P5E_CPU0_P3_RX_DP<9>")
	)
	(segment
		(start 387.386322 -329.10272)
		(end 386.261102 -325.863966)
		(width 0.14224)
		(layer "In4.Cu")
		(net "P5E_CPU0_P3_RX_DP<9>")
	)
	(segment
		(start 369.667282 -289.981132)
		(end 369.71097 -289.955732)
		(width 0.1143)
		(layer "In4.Cu")
		(net "P5E_CPU0_P3_RX_DP<9>")
	)
	(segment
		(start 370.172234 -291.421058)
		(end 370.17071 -291.420042)
		(width 0.1143)
		(layer "In4.Cu")
		(net "P5E_CPU0_P3_RX_DP<9>")
	)
	(segment
		(start 370.025676 -296.427906)
		(end 369.979956 -296.382186)
		(width 0.1143)
		(layer "In4.Cu")
		(net "P5E_CPU0_P3_RX_DP<9>")
	)
	(segment
		(start 370.167916 -294.658542)
		(end 370.166138 -294.657526)
		(width 0.1143)
		(layer "In4.Cu")
		(net "P5E_CPU0_P3_RX_DP<9>")
	)
	(segment
		(start 382.448562 -393.428982)
		(end 382.132586 -393.113006)
		(width 0.14224)
		(layer "In4.Cu")
		(net "P5E_CPU0_P3_RX_DP<9>")
	)
	(segment
		(start 370.136166 -294.032432)
		(end 370.152422 -294.023034)
		(width 0.1143)
		(layer "In4.Cu")
		(net "P5E_CPU0_P3_RX_DP<9>")
	)
	(segment
		(start 370.175282 -291.422582)
		(end 370.175282 -291.422836)
		(width 0.1143)
		(layer "In4.Cu")
		(net "P5E_CPU0_P3_RX_DP<9>")
	)
	(segment
		(start 370.450364 -295.146476)
		(end 370.450364 -295.145968)
		(width 0.1143)
		(layer "In4.Cu")
		(net "P5E_CPU0_P3_RX_DP<9>")
	)
	(segment
		(start 370.167662 -295.633394)
		(end 370.208302 -295.609518)
		(width 0.1143)
		(layer "In4.Cu")
		(net "P5E_CPU0_P3_RX_DP<9>")
	)
	(segment
		(start 370.025676 -297.611292)
		(end 370.025676 -296.456354)
		(width 0.14224)
		(layer "In4.Cu")
		(net "P5E_CPU0_P3_RX_DP<9>")
	)
	(segment
		(start 370.167154 -291.41801)
		(end 370.16436 -291.416486)
		(width 0.1143)
		(layer "In4.Cu")
		(net "P5E_CPU0_P3_RX_DP<9>")
	)
	(segment
		(start 382.900682 -316.189868)
		(end 380.571248 -311.832244)
		(width 0.14224)
		(layer "In4.Cu")
		(net "P5E_CPU0_P3_RX_DP<9>")
	)
	(segment
		(start 370.162074 -291.415216)
		(end 370.161312 -291.414708)
		(width 0.1143)
		(layer "In4.Cu")
		(net "P5E_CPU0_P3_RX_DP<9>")
	)
	(segment
		(start 370.148358 -292.404546)
		(end 370.161312 -292.396418)
		(width 0.1143)
		(layer "In4.Cu")
		(net "P5E_CPU0_P3_RX_DP<9>")
	)
	(segment
		(start 370.1669 -294.014398)
		(end 370.168932 -294.013128)
		(width 0.1143)
		(layer "In4.Cu")
		(net "P5E_CPU0_P3_RX_DP<9>")
	)
	(segment
		(start 388.78764 -359.23728)
		(end 388.78764 -336.904584)
		(width 0.14224)
		(layer "In4.Cu")
		(net "P5E_CPU0_P3_RX_DP<9>")
	)
	(segment
		(start 382.656588 -386.895848)
		(end 382.53797 -382.365504)
		(width 0.14224)
		(layer "In4.Cu")
		(net "P5E_CPU0_P3_RX_DP<9>")
	)
	(segment
		(start 382.18618 -394.031216)
		(end 382.360424 -393.930632)
		(width 0.14224)
		(layer "In4.Cu")
		(net "P5E_CPU0_P3_RX_DP<9>")
	)
	(segment
		(start 382.400556 -392.468862)
		(end 382.400556 -390.87044)
		(width 0.14224)
		(layer "In4.Cu")
		(net "P5E_CPU0_P3_RX_DP<9>")
	)
	(arc
		(start 369.98021 -291.084254)
		(mid 369.913065 -290.828502)
		(end 369.736878 -290.631372)
		(width 0.1143)
		(layer "In4.Cu")
		(net "P5E_CPU0_P3_RX_DP<9>")
	)
	(arc
		(start 369.979956 -295.955974)
		(mid 370.024544 -295.786709)
		(end 370.135912 -295.651682)
		(width 0.1143)
		(layer "In4.Cu")
		(net "P5E_CPU0_P3_RX_DP<9>")
	)
	(arc
		(start 370.208302 -295.609518)
		(mid 370.386145 -295.407696)
		(end 370.450364 -295.146476)
		(width 0.1143)
		(layer "In4.Cu")
		(net "P5E_CPU0_P3_RX_DP<9>")
	)
	(arc
		(start 369.988846 -289.470592)
		(mid 370.029958 -289.29996)
		(end 370.144294 -289.166808)
		(width 0.1143)
		(layer "In4.Cu")
		(net "P5E_CPU0_P3_RX_DP<9>")
	)
	(arc
		(start 370.135912 -293.019988)
		(mid 369.980085 -292.71595)
		(end 370.135912 -292.411912)
		(width 0.1143)
		(layer "In4.Cu")
		(net "P5E_CPU0_P3_RX_DP<9>")
	)
	(arc
		(start 370.035328 -297.66006)
		(mid 370.028116 -297.63615)
		(end 370.025676 -297.611292)
		(width 0.14224)
		(layer "In4.Cu")
		(net "P5E_CPU0_P3_RX_DP<9>")
	)
	(arc
		(start 370.450364 -295.145968)
		(mid 370.385849 -294.883749)
		(end 370.207032 -294.681402)
		(width 0.1143)
		(layer "In4.Cu")
		(net "P5E_CPU0_P3_RX_DP<9>")
	)
	(arc
		(start 370.204492 -293.99103)
		(mid 370.448774 -293.525807)
		(end 370.204746 -293.060374)
		(width 0.1143)
		(layer "In4.Cu")
		(net "P5E_CPU0_P3_RX_DP<9>")
	)
	(arc
		(start 370.910358 -287.961832)
		(mid 370.912381 -287.950422)
		(end 370.914168 -287.938972)
		(width 0.1143)
		(layer "In4.Cu")
		(net "P5E_CPU0_P3_RX_DP<9>")
	)
	(arc
		(start 370.206524 -292.372542)
		(mid 370.450377 -291.908103)
		(end 370.20754 -291.443156)
		(width 0.1143)
		(layer "In4.Cu")
		(net "P5E_CPU0_P3_RX_DP<9>")
	)
	(arc
		(start 370.45011 -288.66592)
		(mid 370.491369 -288.495063)
		(end 370.606066 -288.361882)
		(width 0.1143)
		(layer "In4.Cu")
		(net "P5E_CPU0_P3_RX_DP<9>")
	)
	(arc
		(start 369.667282 -290.590732)
		(mid 369.510305 -290.285932)
		(end 369.667282 -289.981132)
		(width 0.1143)
		(layer "In4.Cu")
		(net "P5E_CPU0_P3_RX_DP<9>")
	)
	(arc
		(start 382.646428 -387.363716)
		(mid 382.657136 -387.129904)
		(end 382.656588 -386.895848)
		(width 0.14224)
		(layer "In4.Cu")
		(net "P5E_CPU0_P3_RX_DP<9>")
	)
	(arc
		(start 370.172742 -289.150552)
		(mid 370.37603 -288.945174)
		(end 370.450364 -288.66592)
		(width 0.1143)
		(layer "In4.Cu")
		(net "P5E_CPU0_P3_RX_DP<9>")
	)
	(arc
		(start 370.676932 -288.320734)
		(mid 370.828919 -288.164226)
		(end 370.910358 -287.961832)
		(width 0.1143)
		(layer "In4.Cu")
		(net "P5E_CPU0_P3_RX_DP<9>")
	)
	(arc
		(start 369.71097 -289.955732)
		(mid 369.914567 -289.750186)
		(end 369.988846 -289.470592)
		(width 0.1143)
		(layer "In4.Cu")
		(net "P5E_CPU0_P3_RX_DP<9>")
	)
	(arc
		(start 370.161312 -291.414708)
		(mid 370.030298 -291.271674)
		(end 369.98021 -291.084254)
		(width 0.1143)
		(layer "In4.Cu")
		(net "P5E_CPU0_P3_RX_DP<9>")
	)
	(arc
		(start 383.705862 -376.910092)
		(mid 383.768565 -376.060029)
		(end 383.95529 -375.228358)
		(width 0.14224)
		(layer "In4.Cu")
		(net "P5E_CPU0_P3_RX_DP<9>")
	)
	(arc
		(start 388.770114 -359.356152)
		(mid 388.783277 -359.297364)
		(end 388.78764 -359.23728)
		(width 0.14224)
		(layer "In4.Cu")
		(net "P5E_CPU0_P3_RX_DP<9>")
	)
	(arc
		(start 370.165376 -294.657272)
		(mid 369.98143 -294.352817)
		(end 370.136166 -294.032432)
		(width 0.1143)
		(layer "In4.Cu")
		(net "P5E_CPU0_P3_RX_DP<9>")
	)
	(segment
		(start 368.0079 -289.209988)
		(end 368.474752 -289.475926)
		(width 0.12954)
		(layer "F.Cu")
		(net "P5E_CPU0_P3_RX_DP<8>")
	)
	(segment
		(start 380.370588 -394.385292)
		(end 380.891288 -394.385292)
		(width 0.127)
		(layer "F.Cu")
		(net "P5E_CPU0_P3_RX_DP<8>")
	)
	(segment
		(start 369.227608 -294.658542)
		(end 369.197128 -294.640762)
		(width 0.1143)
		(layer "In4.Cu")
		(net "P5E_CPU0_P3_RX_DP<8>")
	)
	(segment
		(start 382.080516 -316.669928)
		(end 379.738128 -312.286904)
		(width 0.14224)
		(layer "In4.Cu")
		(net "P5E_CPU0_P3_RX_DP<8>")
	)
	(segment
		(start 380.938786 -378.417582)
		(end 380.347982 -377.826778)
		(width 0.14224)
		(layer "In4.Cu")
		(net "P5E_CPU0_P3_RX_DP<8>")
	)
	(segment
		(start 368.287808 -289.798506)
		(end 368.286792 -289.797998)
		(width 0.1143)
		(layer "In4.Cu")
		(net "P5E_CPU0_P3_RX_DP<8>")
	)
	(segment
		(start 381.42037 -381.839724)
		(end 382.004062 -380.430532)
		(width 0.14224)
		(layer "In4.Cu")
		(net "P5E_CPU0_P3_RX_DP<8>")
	)
	(segment
		(start 369.266724 -293.06139)
		(end 369.227608 -293.03853)
		(width 0.1143)
		(layer "In4.Cu")
		(net "P5E_CPU0_P3_RX_DP<8>")
	)
	(segment
		(start 381.48006 -378.702824)
		(end 381.179832 -378.578618)
		(width 0.14224)
		(layer "In4.Cu")
		(net "P5E_CPU0_P3_RX_DP<8>")
	)
	(segment
		(start 369.040156 -296.38879)
		(end 369.040156 -295.955974)
		(width 0.1143)
		(layer "In4.Cu")
		(net "P5E_CPU0_P3_RX_DP<8>")
	)
	(segment
		(start 381.160528 -393.930632)
		(end 381.248666 -393.842494)
		(width 0.14224)
		(layer "In4.Cu")
		(net "P5E_CPU0_P3_RX_DP<8>")
	)
	(segment
		(start 368.789966 -290.627308)
		(end 368.789204 -290.6268)
		(width 0.1143)
		(layer "In4.Cu")
		(net "P5E_CPU0_P3_RX_DP<8>")
	)
	(segment
		(start 368.789204 -290.6268)
		(end 368.764566 -290.612576)
		(width 0.1143)
		(layer "In4.Cu")
		(net "P5E_CPU0_P3_RX_DP<8>")
	)
	(segment
		(start 368.758724 -290.60902)
		(end 368.757708 -290.608512)
		(width 0.1143)
		(layer "In4.Cu")
		(net "P5E_CPU0_P3_RX_DP<8>")
	)
	(segment
		(start 369.266724 -294.681402)
		(end 369.227608 -294.658542)
		(width 0.1143)
		(layer "In4.Cu")
		(net "P5E_CPU0_P3_RX_DP<8>")
	)
	(segment
		(start 368.763042 -290.61156)
		(end 368.762026 -290.611052)
		(width 0.1143)
		(layer "In4.Cu")
		(net "P5E_CPU0_P3_RX_DP<8>")
	)
	(segment
		(start 381.509524 -385.83108)
		(end 381.42037 -382.426972)
		(width 0.14224)
		(layer "In4.Cu")
		(net "P5E_CPU0_P3_RX_DP<8>")
	)
	(segment
		(start 380.891288 -394.385292)
		(end 380.986284 -394.031216)
		(width 0.14224)
		(layer "In4.Cu")
		(net "P5E_CPU0_P3_RX_DP<8>")
	)
	(segment
		(start 371.051582 -301.703232)
		(end 370.044218 -300.195488)
		(width 0.14224)
		(layer "In4.Cu")
		(net "P5E_CPU0_P3_RX_DP<8>")
	)
	(segment
		(start 368.10696 -289.545776)
		(end 368.17681 -289.475926)
		(width 0.1143)
		(layer "In4.Cu")
		(net "P5E_CPU0_P3_RX_DP<8>")
	)
	(segment
		(start 368.762026 -290.611052)
		(end 368.760502 -290.610036)
		(width 0.1143)
		(layer "In4.Cu")
		(net "P5E_CPU0_P3_RX_DP<8>")
	)
	(segment
		(start 368.286792 -289.797998)
		(end 368.256058 -289.780218)
		(width 0.1143)
		(layer "In4.Cu")
		(net "P5E_CPU0_P3_RX_DP<8>")
	)
	(segment
		(start 382.004062 -380.430532)
		(end 382.004062 -379.498098)
		(width 0.14224)
		(layer "In4.Cu")
		(net "P5E_CPU0_P3_RX_DP<8>")
	)
	(segment
		(start 380.935738 -392.734546)
		(end 381.240538 -392.429746)
		(width 0.14224)
		(layer "In4.Cu")
		(net "P5E_CPU0_P3_RX_DP<8>")
	)
	(segment
		(start 386.475478 -329.3237)
		(end 384.27787 -322.996814)
		(width 0.14224)
		(layer "In4.Cu")
		(net "P5E_CPU0_P3_RX_DP<8>")
	)
	(segment
		(start 369.085876 -296.462958)
		(end 369.085876 -296.43451)
		(width 0.1143)
		(layer "In4.Cu")
		(net "P5E_CPU0_P3_RX_DP<8>")
	)
	(segment
		(start 369.227608 -292.39337)
		(end 369.266724 -292.37051)
		(width 0.1143)
		(layer "In4.Cu")
		(net "P5E_CPU0_P3_RX_DP<8>")
	)
	(segment
		(start 380.292864 -377.693682)
		(end 380.292864 -376.36196)
		(width 0.14224)
		(layer "In4.Cu")
		(net "P5E_CPU0_P3_RX_DP<8>")
	)
	(segment
		(start 368.757708 -290.608512)
		(end 368.756946 -290.608004)
		(width 0.1143)
		(layer "In4.Cu")
		(net "P5E_CPU0_P3_RX_DP<8>")
	)
	(segment
		(start 387.85546 -357.45293)
		(end 387.85546 -337.0072)
		(width 0.14224)
		(layer "In4.Cu")
		(net "P5E_CPU0_P3_RX_DP<8>")
	)
	(segment
		(start 369.227608 -291.418518)
		(end 369.197128 -291.400738)
		(width 0.1143)
		(layer "In4.Cu")
		(net "P5E_CPU0_P3_RX_DP<8>")
	)
	(segment
		(start 384.27787 -322.996814)
		(end 384.27787 -322.99656)
		(width 0.14224)
		(layer "In4.Cu")
		(net "P5E_CPU0_P3_RX_DP<8>")
	)
	(segment
		(start 368.760502 -290.610036)
		(end 368.758724 -290.60902)
		(width 0.1143)
		(layer "In4.Cu")
		(net "P5E_CPU0_P3_RX_DP<8>")
	)
	(segment
		(start 369.197128 -294.031162)
		(end 369.227608 -294.013382)
		(width 0.1143)
		(layer "In4.Cu")
		(net "P5E_CPU0_P3_RX_DP<8>")
	)
	(segment
		(start 369.227608 -294.013382)
		(end 369.266724 -293.990522)
		(width 0.1143)
		(layer "In4.Cu")
		(net "P5E_CPU0_P3_RX_DP<8>")
	)
	(segment
		(start 369.266724 -291.441378)
		(end 369.227608 -291.418518)
		(width 0.1143)
		(layer "In4.Cu")
		(net "P5E_CPU0_P3_RX_DP<8>")
	)
	(segment
		(start 381.42037 -382.426972)
		(end 381.42037 -381.839724)
		(width 0.14224)
		(layer "In4.Cu")
		(net "P5E_CPU0_P3_RX_DP<8>")
	)
	(segment
		(start 370.044218 -300.195488)
		(end 369.159536 -298.05884)
		(width 0.14224)
		(layer "In4.Cu")
		(net "P5E_CPU0_P3_RX_DP<8>")
	)
	(segment
		(start 369.085876 -296.43451)
		(end 369.040156 -296.38879)
		(width 0.1143)
		(layer "In4.Cu")
		(net "P5E_CPU0_P3_RX_DP<8>")
	)
	(segment
		(start 380.986284 -394.031216)
		(end 381.160528 -393.930632)
		(width 0.14224)
		(layer "In4.Cu")
		(net "P5E_CPU0_P3_RX_DP<8>")
	)
	(segment
		(start 381.240538 -392.429746)
		(end 381.240538 -390.558274)
		(width 0.14224)
		(layer "In4.Cu")
		(net "P5E_CPU0_P3_RX_DP<8>")
	)
	(segment
		(start 380.93269 -393.113006)
		(end 380.935738 -392.734546)
		(width 0.14224)
		(layer "In4.Cu")
		(net "P5E_CPU0_P3_RX_DP<8>")
	)
	(segment
		(start 369.197128 -292.41115)
		(end 369.227608 -292.39337)
		(width 0.1143)
		(layer "In4.Cu")
		(net "P5E_CPU0_P3_RX_DP<8>")
	)
	(segment
		(start 369.085876 -297.688508)
		(end 369.085876 -296.462958)
		(width 0.14224)
		(layer "In4.Cu")
		(net "P5E_CPU0_P3_RX_DP<8>")
	)
	(segment
		(start 369.197128 -295.651174)
		(end 369.266724 -295.610534)
		(width 0.1143)
		(layer "In4.Cu")
		(net "P5E_CPU0_P3_RX_DP<8>")
	)
	(segment
		(start 381.240538 -390.558274)
		(end 381.48133 -387.121654)
		(width 0.14224)
		(layer "In4.Cu")
		(net "P5E_CPU0_P3_RX_DP<8>")
	)
	(segment
		(start 380.292864 -376.36196)
		(end 380.293118 -376.362214)
		(width 0.14224)
		(layer "In4.Cu")
		(net "P5E_CPU0_P3_RX_DP<8>")
	)
	(segment
		(start 368.764566 -290.612576)
		(end 368.763042 -290.61156)
		(width 0.1143)
		(layer "In4.Cu")
		(net "P5E_CPU0_P3_RX_DP<8>")
	)
	(segment
		(start 381.248666 -393.842494)
		(end 381.248666 -393.428982)
		(width 0.14224)
		(layer "In4.Cu")
		(net "P5E_CPU0_P3_RX_DP<8>")
	)
	(segment
		(start 369.227608 -293.03853)
		(end 369.197128 -293.02075)
		(width 0.1143)
		(layer "In4.Cu")
		(net "P5E_CPU0_P3_RX_DP<8>")
	)
	(segment
		(start 380.479046 -375.42597)
		(end 387.792468 -357.77043)
		(width 0.14224)
		(layer "In4.Cu")
		(net "P5E_CPU0_P3_RX_DP<8>")
	)
	(segment
		(start 379.738128 -312.286904)
		(end 371.051582 -301.703232)
		(width 0.14224)
		(layer "In4.Cu")
		(net "P5E_CPU0_P3_RX_DP<8>")
	)
	(segment
		(start 368.17681 -289.475926)
		(end 368.474752 -289.475926)
		(width 0.1143)
		(layer "In4.Cu")
		(net "P5E_CPU0_P3_RX_DP<8>")
	)
	(segment
		(start 384.27787 -322.99656)
		(end 382.080516 -316.669928)
		(width 0.14224)
		(layer "In4.Cu")
		(net "P5E_CPU0_P3_RX_DP<8>")
	)
	(segment
		(start 381.248666 -393.428982)
		(end 380.93269 -393.113006)
		(width 0.14224)
		(layer "In4.Cu")
		(net "P5E_CPU0_P3_RX_DP<8>")
	)
	(segment
		(start 387.85546 -337.0072)
		(end 386.475478 -329.3237)
		(width 0.14224)
		(layer "In4.Cu")
		(net "P5E_CPU0_P3_RX_DP<8>")
	)
	(segment
		(start 368.290602 -289.800284)
		(end 368.287808 -289.798506)
		(width 0.1143)
		(layer "In4.Cu")
		(net "P5E_CPU0_P3_RX_DP<8>")
	)
	(segment
		(start 368.796824 -290.631372)
		(end 368.789966 -290.627308)
		(width 0.1143)
		(layer "In4.Cu")
		(net "P5E_CPU0_P3_RX_DP<8>")
	)
	(arc
		(start 368.256058 -289.780218)
		(mid 368.158923 -289.677349)
		(end 368.10696 -289.545776)
		(width 0.1143)
		(layer "In4.Cu")
		(net "P5E_CPU0_P3_RX_DP<8>")
	)
	(arc
		(start 369.197128 -293.02075)
		(mid 369.040151 -292.71595)
		(end 369.197128 -292.41115)
		(width 0.1143)
		(layer "In4.Cu")
		(net "P5E_CPU0_P3_RX_DP<8>")
	)
	(arc
		(start 369.266724 -295.610534)
		(mid 369.510051 -295.145968)
		(end 369.266724 -294.681402)
		(width 0.1143)
		(layer "In4.Cu")
		(net "P5E_CPU0_P3_RX_DP<8>")
	)
	(arc
		(start 387.792468 -357.77043)
		(mid 387.839582 -357.61478)
		(end 387.85546 -357.45293)
		(width 0.14224)
		(layer "In4.Cu")
		(net "P5E_CPU0_P3_RX_DP<8>")
	)
	(arc
		(start 369.159536 -298.05884)
		(mid 369.104468 -297.877301)
		(end 369.085876 -297.688508)
		(width 0.14224)
		(layer "In4.Cu")
		(net "P5E_CPU0_P3_RX_DP<8>")
	)
	(arc
		(start 369.040156 -291.095938)
		(mid 368.975641 -290.833719)
		(end 368.796824 -290.631372)
		(width 0.1143)
		(layer "In4.Cu")
		(net "P5E_CPU0_P3_RX_DP<8>")
	)
	(arc
		(start 381.48133 -387.121654)
		(mid 381.510952 -386.476706)
		(end 381.509524 -385.83108)
		(width 0.14224)
		(layer "In4.Cu")
		(net "P5E_CPU0_P3_RX_DP<8>")
	)
	(arc
		(start 381.968248 -379.282452)
		(mid 381.843072 -379.028316)
		(end 381.656844 -378.814838)
		(width 0.14224)
		(layer "In4.Cu")
		(net "P5E_CPU0_P3_RX_DP<8>")
	)
	(arc
		(start 369.197128 -291.400738)
		(mid 369.081701 -291.267362)
		(end 369.040156 -291.095938)
		(width 0.1143)
		(layer "In4.Cu")
		(net "P5E_CPU0_P3_RX_DP<8>")
	)
	(arc
		(start 381.179832 -378.578618)
		(mid 381.051381 -378.509968)
		(end 380.938786 -378.417582)
		(width 0.14224)
		(layer "In4.Cu")
		(net "P5E_CPU0_P3_RX_DP<8>")
	)
	(arc
		(start 369.266724 -292.37051)
		(mid 369.510051 -291.905944)
		(end 369.266724 -291.441378)
		(width 0.1143)
		(layer "In4.Cu")
		(net "P5E_CPU0_P3_RX_DP<8>")
	)
	(arc
		(start 368.756946 -290.608004)
		(mid 368.619544 -290.471171)
		(end 368.56924 -290.2839)
		(width 0.1143)
		(layer "In4.Cu")
		(net "P5E_CPU0_P3_RX_DP<8>")
	)
	(arc
		(start 382.004062 -379.498098)
		(mid 381.995028 -379.388801)
		(end 381.968248 -379.282452)
		(width 0.14224)
		(layer "In4.Cu")
		(net "P5E_CPU0_P3_RX_DP<8>")
	)
	(arc
		(start 381.656844 -378.814838)
		(mid 381.572885 -378.751831)
		(end 381.48006 -378.702824)
		(width 0.14224)
		(layer "In4.Cu")
		(net "P5E_CPU0_P3_RX_DP<8>")
	)
	(arc
		(start 369.197128 -294.640762)
		(mid 369.040151 -294.335962)
		(end 369.197128 -294.031162)
		(width 0.1143)
		(layer "In4.Cu")
		(net "P5E_CPU0_P3_RX_DP<8>")
	)
	(arc
		(start 368.56924 -290.2839)
		(mid 368.494601 -290.004823)
		(end 368.290602 -289.800284)
		(width 0.1143)
		(layer "In4.Cu")
		(net "P5E_CPU0_P3_RX_DP<8>")
	)
	(arc
		(start 369.040156 -295.955974)
		(mid 369.081705 -295.784552)
		(end 369.197128 -295.651174)
		(width 0.1143)
		(layer "In4.Cu")
		(net "P5E_CPU0_P3_RX_DP<8>")
	)
	(arc
		(start 380.293118 -376.362214)
		(mid 380.339977 -375.884936)
		(end 380.479046 -375.42597)
		(width 0.14224)
		(layer "In4.Cu")
		(net "P5E_CPU0_P3_RX_DP<8>")
	)
	(arc
		(start 380.347982 -377.826778)
		(mid 380.30718 -377.765713)
		(end 380.292864 -377.693682)
		(width 0.14224)
		(layer "In4.Cu")
		(net "P5E_CPU0_P3_RX_DP<8>")
	)
	(arc
		(start 369.266724 -293.990522)
		(mid 369.510051 -293.525956)
		(end 369.266724 -293.06139)
		(width 0.1143)
		(layer "In4.Cu")
		(net "P5E_CPU0_P3_RX_DP<8>")
	)
	(segment
		(start 383.97053 -394.385292)
		(end 384.49123 -394.385292)
		(width 0.127)
		(layer "F.Cu")
		(net "P5E_CPU0_P3_RX_DP<11>")
	)
	(segment
		(start 370.828062 -289.209988)
		(end 371.294914 -289.475926)
		(width 0.12954)
		(layer "F.Cu")
		(net "P5E_CPU0_P3_RX_DP<11>")
	)
	(segment
		(start 371.609366 -290.6268)
		(end 371.584728 -290.612576)
		(width 0.1143)
		(layer "In4.Cu")
		(net "P5E_CPU0_P3_RX_DP<11>")
	)
	(segment
		(start 372.086886 -291.441378)
		(end 372.04777 -291.418518)
		(width 0.1143)
		(layer "In4.Cu")
		(net "P5E_CPU0_P3_RX_DP<11>")
	)
	(segment
		(start 384.848608 -393.428982)
		(end 384.532632 -393.113006)
		(width 0.14224)
		(layer "In4.Cu")
		(net "P5E_CPU0_P3_RX_DP<11>")
	)
	(segment
		(start 371.860318 -296.348658)
		(end 371.860318 -295.955974)
		(width 0.1143)
		(layer "In4.Cu")
		(net "P5E_CPU0_P3_RX_DP<11>")
	)
	(segment
		(start 371.57787 -290.608512)
		(end 371.577108 -290.608004)
		(width 0.1143)
		(layer "In4.Cu")
		(net "P5E_CPU0_P3_RX_DP<11>")
	)
	(segment
		(start 372.04777 -295.633394)
		(end 372.086886 -295.610534)
		(width 0.1143)
		(layer "In4.Cu")
		(net "P5E_CPU0_P3_RX_DP<11>")
	)
	(segment
		(start 387.100572 -376.297444)
		(end 387.183884 -375.621804)
		(width 0.14224)
		(layer "In4.Cu")
		(net "P5E_CPU0_P3_RX_DP<11>")
	)
	(segment
		(start 384.848608 -393.842494)
		(end 384.848608 -393.428982)
		(width 0.14224)
		(layer "In4.Cu")
		(net "P5E_CPU0_P3_RX_DP<11>")
	)
	(segment
		(start 371.110764 -289.800284)
		(end 371.10797 -289.798506)
		(width 0.1143)
		(layer "In4.Cu")
		(net "P5E_CPU0_P3_RX_DP<11>")
	)
	(segment
		(start 387.183884 -375.621804)
		(end 390.639808 -361.827064)
		(width 0.14224)
		(layer "In4.Cu")
		(net "P5E_CPU0_P3_RX_DP<11>")
	)
	(segment
		(start 371.906038 -296.422826)
		(end 371.906038 -296.394378)
		(width 0.1143)
		(layer "In4.Cu")
		(net "P5E_CPU0_P3_RX_DP<11>")
	)
	(segment
		(start 372.04777 -293.03853)
		(end 372.01729 -293.02075)
		(width 0.1143)
		(layer "In4.Cu")
		(net "P5E_CPU0_P3_RX_DP<11>")
	)
	(segment
		(start 384.49123 -394.385292)
		(end 384.586226 -394.031216)
		(width 0.14224)
		(layer "In4.Cu")
		(net "P5E_CPU0_P3_RX_DP<11>")
	)
	(segment
		(start 371.10797 -289.798506)
		(end 371.106954 -289.797998)
		(width 0.1143)
		(layer "In4.Cu")
		(net "P5E_CPU0_P3_RX_DP<11>")
	)
	(segment
		(start 372.04777 -294.013382)
		(end 372.086886 -293.990522)
		(width 0.1143)
		(layer "In4.Cu")
		(net "P5E_CPU0_P3_RX_DP<11>")
	)
	(segment
		(start 387.100572 -377.527058)
		(end 387.100572 -376.297444)
		(width 0.14224)
		(layer "In4.Cu")
		(net "P5E_CPU0_P3_RX_DP<11>")
	)
	(segment
		(start 390.652 -336.718656)
		(end 389.197342 -328.621136)
		(width 0.14224)
		(layer "In4.Cu")
		(net "P5E_CPU0_P3_RX_DP<11>")
	)
	(segment
		(start 373.430292 -300.173644)
		(end 372.62562 -298.990258)
		(width 0.14224)
		(layer "In4.Cu")
		(net "P5E_CPU0_P3_RX_DP<11>")
	)
	(segment
		(start 385.045966 -390.134602)
		(end 387.686042 -383.760218)
		(width 0.14224)
		(layer "In4.Cu")
		(net "P5E_CPU0_P3_RX_DP<11>")
	)
	(segment
		(start 372.04777 -294.658542)
		(end 372.01729 -294.640762)
		(width 0.1143)
		(layer "In4.Cu")
		(net "P5E_CPU0_P3_RX_DP<11>")
	)
	(segment
		(start 384.84048 -392.387328)
		(end 384.84048 -391.16762)
		(width 0.14224)
		(layer "In4.Cu")
		(net "P5E_CPU0_P3_RX_DP<11>")
	)
	(segment
		(start 386.899404 -322.005706)
		(end 384.60172 -315.39053)
		(width 0.14224)
		(layer "In4.Cu")
		(net "P5E_CPU0_P3_RX_DP<11>")
	)
	(segment
		(start 372.04777 -291.418518)
		(end 372.01729 -291.400738)
		(width 0.1143)
		(layer "In4.Cu")
		(net "P5E_CPU0_P3_RX_DP<11>")
	)
	(segment
		(start 382.142238 -310.790082)
		(end 373.430292 -300.173644)
		(width 0.14224)
		(layer "In4.Cu")
		(net "P5E_CPU0_P3_RX_DP<11>")
	)
	(segment
		(start 372.04777 -292.39337)
		(end 372.086886 -292.37051)
		(width 0.1143)
		(layer "In4.Cu")
		(net "P5E_CPU0_P3_RX_DP<11>")
	)
	(segment
		(start 371.610128 -290.627308)
		(end 371.609366 -290.6268)
		(width 0.1143)
		(layer "In4.Cu")
		(net "P5E_CPU0_P3_RX_DP<11>")
	)
	(segment
		(start 371.616986 -290.631372)
		(end 371.610128 -290.627308)
		(width 0.1143)
		(layer "In4.Cu")
		(net "P5E_CPU0_P3_RX_DP<11>")
	)
	(segment
		(start 372.01729 -294.031162)
		(end 372.04777 -294.013382)
		(width 0.1143)
		(layer "In4.Cu")
		(net "P5E_CPU0_P3_RX_DP<11>")
	)
	(segment
		(start 371.580664 -290.610036)
		(end 371.578886 -290.60902)
		(width 0.1143)
		(layer "In4.Cu")
		(net "P5E_CPU0_P3_RX_DP<11>")
	)
	(segment
		(start 371.906038 -296.394378)
		(end 371.860318 -296.348658)
		(width 0.1143)
		(layer "In4.Cu")
		(net "P5E_CPU0_P3_RX_DP<11>")
	)
	(segment
		(start 387.745986 -378.417582)
		(end 387.274054 -377.94565)
		(width 0.14224)
		(layer "In4.Cu")
		(net "P5E_CPU0_P3_RX_DP<11>")
	)
	(segment
		(start 384.535934 -392.691874)
		(end 384.84048 -392.387328)
		(width 0.14224)
		(layer "In4.Cu")
		(net "P5E_CPU0_P3_RX_DP<11>")
	)
	(segment
		(start 387.686042 -383.760218)
		(end 388.550404 -382.466596)
		(width 0.14224)
		(layer "In4.Cu")
		(net "P5E_CPU0_P3_RX_DP<11>")
	)
	(segment
		(start 388.811262 -381.607314)
		(end 388.811262 -379.598174)
		(width 0.14224)
		(layer "In4.Cu")
		(net "P5E_CPU0_P3_RX_DP<11>")
	)
	(segment
		(start 370.927122 -289.545776)
		(end 370.996972 -289.475926)
		(width 0.1143)
		(layer "In4.Cu")
		(net "P5E_CPU0_P3_RX_DP<11>")
	)
	(segment
		(start 371.106954 -289.797998)
		(end 371.07622 -289.780218)
		(width 0.1143)
		(layer "In4.Cu")
		(net "P5E_CPU0_P3_RX_DP<11>")
	)
	(segment
		(start 384.76047 -393.930632)
		(end 384.848608 -393.842494)
		(width 0.14224)
		(layer "In4.Cu")
		(net "P5E_CPU0_P3_RX_DP<11>")
	)
	(segment
		(start 372.01729 -295.651174)
		(end 372.04777 -295.633394)
		(width 0.1143)
		(layer "In4.Cu")
		(net "P5E_CPU0_P3_RX_DP<11>")
	)
	(segment
		(start 371.584728 -290.612576)
		(end 371.583204 -290.61156)
		(width 0.1143)
		(layer "In4.Cu")
		(net "P5E_CPU0_P3_RX_DP<11>")
	)
	(segment
		(start 390.652 -361.727496)
		(end 390.652 -336.718656)
		(width 0.14224)
		(layer "In4.Cu")
		(net "P5E_CPU0_P3_RX_DP<11>")
	)
	(segment
		(start 372.62562 -298.990258)
		(end 371.91569 -297.276012)
		(width 0.14224)
		(layer "In4.Cu")
		(net "P5E_CPU0_P3_RX_DP<11>")
	)
	(segment
		(start 372.01729 -292.41115)
		(end 372.04777 -292.39337)
		(width 0.1143)
		(layer "In4.Cu")
		(net "P5E_CPU0_P3_RX_DP<11>")
	)
	(segment
		(start 384.586226 -394.031216)
		(end 384.76047 -393.930632)
		(width 0.14224)
		(layer "In4.Cu")
		(net "P5E_CPU0_P3_RX_DP<11>")
	)
	(segment
		(start 384.60172 -315.39053)
		(end 382.142238 -310.790082)
		(width 0.14224)
		(layer "In4.Cu")
		(net "P5E_CPU0_P3_RX_DP<11>")
	)
	(segment
		(start 371.578886 -290.60902)
		(end 371.57787 -290.608512)
		(width 0.1143)
		(layer "In4.Cu")
		(net "P5E_CPU0_P3_RX_DP<11>")
	)
	(segment
		(start 388.306564 -378.732796)
		(end 388.073646 -378.636276)
		(width 0.14224)
		(layer "In4.Cu")
		(net "P5E_CPU0_P3_RX_DP<11>")
	)
	(segment
		(start 389.197342 -328.621136)
		(end 386.899404 -322.005706)
		(width 0.14224)
		(layer "In4.Cu")
		(net "P5E_CPU0_P3_RX_DP<11>")
	)
	(segment
		(start 372.086886 -294.681402)
		(end 372.04777 -294.658542)
		(width 0.1143)
		(layer "In4.Cu")
		(net "P5E_CPU0_P3_RX_DP<11>")
	)
	(segment
		(start 371.906038 -297.227244)
		(end 371.906038 -296.422826)
		(width 0.14224)
		(layer "In4.Cu")
		(net "P5E_CPU0_P3_RX_DP<11>")
	)
	(segment
		(start 372.086886 -293.06139)
		(end 372.04777 -293.03853)
		(width 0.1143)
		(layer "In4.Cu")
		(net "P5E_CPU0_P3_RX_DP<11>")
	)
	(segment
		(start 384.532632 -393.113006)
		(end 384.535934 -392.691874)
		(width 0.14224)
		(layer "In4.Cu")
		(net "P5E_CPU0_P3_RX_DP<11>")
	)
	(segment
		(start 371.582188 -290.611052)
		(end 371.580664 -290.610036)
		(width 0.1143)
		(layer "In4.Cu")
		(net "P5E_CPU0_P3_RX_DP<11>")
	)
	(segment
		(start 371.583204 -290.61156)
		(end 371.582188 -290.611052)
		(width 0.1143)
		(layer "In4.Cu")
		(net "P5E_CPU0_P3_RX_DP<11>")
	)
	(segment
		(start 370.996972 -289.475926)
		(end 371.294914 -289.475926)
		(width 0.1143)
		(layer "In4.Cu")
		(net "P5E_CPU0_P3_RX_DP<11>")
	)
	(arc
		(start 372.01729 -291.400738)
		(mid 371.901863 -291.267362)
		(end 371.860318 -291.095938)
		(width 0.1143)
		(layer "In4.Cu")
		(net "P5E_CPU0_P3_RX_DP<11>")
	)
	(arc
		(start 371.577108 -290.608004)
		(mid 371.439706 -290.471171)
		(end 371.389402 -290.2839)
		(width 0.1143)
		(layer "In4.Cu")
		(net "P5E_CPU0_P3_RX_DP<11>")
	)
	(arc
		(start 372.086886 -293.990522)
		(mid 372.330213 -293.525956)
		(end 372.086886 -293.06139)
		(width 0.1143)
		(layer "In4.Cu")
		(net "P5E_CPU0_P3_RX_DP<11>")
	)
	(arc
		(start 388.576566 -378.915676)
		(mid 388.450799 -378.810602)
		(end 388.306564 -378.732796)
		(width 0.14224)
		(layer "In4.Cu")
		(net "P5E_CPU0_P3_RX_DP<11>")
	)
	(arc
		(start 371.91569 -297.276012)
		(mid 371.908445 -297.252105)
		(end 371.906038 -297.227244)
		(width 0.14224)
		(layer "In4.Cu")
		(net "P5E_CPU0_P3_RX_DP<11>")
	)
	(arc
		(start 387.274054 -377.94565)
		(mid 387.145675 -377.753613)
		(end 387.100572 -377.527058)
		(width 0.14224)
		(layer "In4.Cu")
		(net "P5E_CPU0_P3_RX_DP<11>")
	)
	(arc
		(start 371.389402 -290.2839)
		(mid 371.314763 -290.004823)
		(end 371.110764 -289.800284)
		(width 0.1143)
		(layer "In4.Cu")
		(net "P5E_CPU0_P3_RX_DP<11>")
	)
	(arc
		(start 372.01729 -293.02075)
		(mid 371.860313 -292.71595)
		(end 372.01729 -292.41115)
		(width 0.1143)
		(layer "In4.Cu")
		(net "P5E_CPU0_P3_RX_DP<11>")
	)
	(arc
		(start 371.860318 -295.955974)
		(mid 371.901867 -295.784552)
		(end 372.01729 -295.651174)
		(width 0.1143)
		(layer "In4.Cu")
		(net "P5E_CPU0_P3_RX_DP<11>")
	)
	(arc
		(start 371.860318 -291.095938)
		(mid 371.795803 -290.833719)
		(end 371.616986 -290.631372)
		(width 0.1143)
		(layer "In4.Cu")
		(net "P5E_CPU0_P3_RX_DP<11>")
	)
	(arc
		(start 372.086886 -292.37051)
		(mid 372.330213 -291.905944)
		(end 372.086886 -291.441378)
		(width 0.1143)
		(layer "In4.Cu")
		(net "P5E_CPU0_P3_RX_DP<11>")
	)
	(arc
		(start 388.550404 -382.466596)
		(mid 388.744565 -382.056304)
		(end 388.811262 -381.607314)
		(width 0.14224)
		(layer "In4.Cu")
		(net "P5E_CPU0_P3_RX_DP<11>")
	)
	(arc
		(start 384.84048 -391.16762)
		(mid 384.892351 -390.640992)
		(end 385.045966 -390.134602)
		(width 0.14224)
		(layer "In4.Cu")
		(net "P5E_CPU0_P3_RX_DP<11>")
	)
	(arc
		(start 390.639808 -361.827064)
		(mid 390.648976 -361.777655)
		(end 390.652 -361.727496)
		(width 0.14224)
		(layer "In4.Cu")
		(net "P5E_CPU0_P3_RX_DP<11>")
	)
	(arc
		(start 388.790434 -379.40996)
		(mid 388.753237 -379.265408)
		(end 388.707122 -379.123448)
		(width 0.14224)
		(layer "In4.Cu")
		(net "P5E_CPU0_P3_RX_DP<11>")
	)
	(arc
		(start 372.01729 -294.640762)
		(mid 371.860313 -294.335962)
		(end 372.01729 -294.031162)
		(width 0.1143)
		(layer "In4.Cu")
		(net "P5E_CPU0_P3_RX_DP<11>")
	)
	(arc
		(start 388.811262 -379.598174)
		(mid 388.806081 -379.503488)
		(end 388.790434 -379.40996)
		(width 0.14224)
		(layer "In4.Cu")
		(net "P5E_CPU0_P3_RX_DP<11>")
	)
	(arc
		(start 388.073646 -378.636276)
		(mid 387.89906 -378.543043)
		(end 387.745986 -378.417582)
		(width 0.14224)
		(layer "In4.Cu")
		(net "P5E_CPU0_P3_RX_DP<11>")
	)
	(arc
		(start 388.707122 -379.123448)
		(mid 388.652964 -379.012578)
		(end 388.576566 -378.915676)
		(width 0.14224)
		(layer "In4.Cu")
		(net "P5E_CPU0_P3_RX_DP<11>")
	)
	(arc
		(start 371.07622 -289.780218)
		(mid 370.979085 -289.677349)
		(end 370.927122 -289.545776)
		(width 0.1143)
		(layer "In4.Cu")
		(net "P5E_CPU0_P3_RX_DP<11>")
	)
	(arc
		(start 372.086886 -295.610534)
		(mid 372.330213 -295.145968)
		(end 372.086886 -294.681402)
		(width 0.1143)
		(layer "In4.Cu")
		(net "P5E_CPU0_P3_RX_DP<11>")
	)
	(segment
		(start 370.828062 -290.83)
		(end 371.294914 -291.095938)
		(width 0.12954)
		(layer "F.Cu")
		(net "P5E_CPU0_P3_RX_DP<10>")
	)
	(segment
		(start 382.770634 -394.385292)
		(end 383.291334 -394.385292)
		(width 0.127)
		(layer "F.Cu")
		(net "P5E_CPU0_P3_RX_DP<10>")
	)
	(segment
		(start 371.10797 -295.633394)
		(end 371.108478 -295.633394)
		(width 0.1143)
		(layer "In4.Cu")
		(net "P5E_CPU0_P3_RX_DP<10>")
	)
	(segment
		(start 371.07622 -294.03167)
		(end 371.10162 -294.016938)
		(width 0.1143)
		(layer "In4.Cu")
		(net "P5E_CPU0_P3_RX_DP<10>")
	)
	(segment
		(start 370.996972 -291.095938)
		(end 371.294914 -291.095938)
		(width 0.1143)
		(layer "In4.Cu")
		(net "P5E_CPU0_P3_RX_DP<10>")
	)
	(segment
		(start 381.346964 -311.295796)
		(end 372.588028 -300.623224)
		(width 0.14224)
		(layer "In4.Cu")
		(net "P5E_CPU0_P3_RX_DP<10>")
	)
	(segment
		(start 383.634996 -389.770112)
		(end 383.791968 -386.574538)
		(width 0.14224)
		(layer "In4.Cu")
		(net "P5E_CPU0_P3_RX_DP<10>")
	)
	(segment
		(start 371.108478 -293.03853)
		(end 371.10797 -293.03853)
		(width 0.1143)
		(layer "In4.Cu")
		(net "P5E_CPU0_P3_RX_DP<10>")
	)
	(segment
		(start 386.04063 -373.003572)
		(end 389.702294 -360.933492)
		(width 0.14224)
		(layer "In4.Cu")
		(net "P5E_CPU0_P3_RX_DP<10>")
	)
	(segment
		(start 370.927122 -291.165788)
		(end 370.996972 -291.095938)
		(width 0.1143)
		(layer "In4.Cu")
		(net "P5E_CPU0_P3_RX_DP<10>")
	)
	(segment
		(start 389.71982 -360.81462)
		(end 389.71982 -336.809842)
		(width 0.14224)
		(layer "In4.Cu")
		(net "P5E_CPU0_P3_RX_DP<10>")
	)
	(segment
		(start 371.07622 -295.651682)
		(end 371.107208 -295.633902)
		(width 0.1143)
		(layer "In4.Cu")
		(net "P5E_CPU0_P3_RX_DP<10>")
	)
	(segment
		(start 383.634996 -392.325352)
		(end 383.634996 -389.770112)
		(width 0.14224)
		(layer "In4.Cu")
		(net "P5E_CPU0_P3_RX_DP<10>")
	)
	(segment
		(start 371.103652 -294.015922)
		(end 371.104414 -294.015414)
		(width 0.1143)
		(layer "In4.Cu")
		(net "P5E_CPU0_P3_RX_DP<10>")
	)
	(segment
		(start 371.107208 -294.01389)
		(end 371.10797 -294.013382)
		(width 0.1143)
		(layer "In4.Cu")
		(net "P5E_CPU0_P3_RX_DP<10>")
	)
	(segment
		(start 383.3368 -392.62431)
		(end 383.634996 -392.325352)
		(width 0.14224)
		(layer "In4.Cu")
		(net "P5E_CPU0_P3_RX_DP<10>")
	)
	(segment
		(start 371.801136 -299.44568)
		(end 370.983256 -297.470322)
		(width 0.14224)
		(layer "In4.Cu")
		(net "P5E_CPU0_P3_RX_DP<10>")
	)
	(segment
		(start 383.761996 -385.41706)
		(end 383.761742 -385.415282)
		(width 0.14224)
		(layer "In4.Cu")
		(net "P5E_CPU0_P3_RX_DP<10>")
	)
	(segment
		(start 370.965984 -297.383454)
		(end 370.965984 -296.489374)
		(width 0.14224)
		(layer "In4.Cu")
		(net "P5E_CPU0_P3_RX_DP<10>")
	)
	(segment
		(start 383.74955 -315.79058)
		(end 381.346964 -311.295796)
		(width 0.14224)
		(layer "In4.Cu")
		(net "P5E_CPU0_P3_RX_DP<10>")
	)
	(segment
		(start 384.821684 -379.095762)
		(end 384.821938 -379.096016)
		(width 0.14224)
		(layer "In4.Cu")
		(net "P5E_CPU0_P3_RX_DP<10>")
	)
	(segment
		(start 383.38633 -394.031216)
		(end 383.560574 -393.930632)
		(width 0.14224)
		(layer "In4.Cu")
		(net "P5E_CPU0_P3_RX_DP<10>")
	)
	(segment
		(start 383.648712 -393.842494)
		(end 383.648712 -393.428982)
		(width 0.14224)
		(layer "In4.Cu")
		(net "P5E_CPU0_P3_RX_DP<10>")
	)
	(segment
		(start 383.332736 -393.113006)
		(end 383.3368 -392.62431)
		(width 0.14224)
		(layer "In4.Cu")
		(net "P5E_CPU0_P3_RX_DP<10>")
	)
	(segment
		(start 371.10797 -291.418518)
		(end 371.07622 -291.40023)
		(width 0.1143)
		(layer "In4.Cu")
		(net "P5E_CPU0_P3_RX_DP<10>")
	)
	(segment
		(start 383.796032 -381.726694)
		(end 384.769106 -379.269752)
		(width 0.14224)
		(layer "In4.Cu")
		(net "P5E_CPU0_P3_RX_DP<10>")
	)
	(segment
		(start 371.10797 -293.03853)
		(end 371.07622 -293.020242)
		(width 0.1143)
		(layer "In4.Cu")
		(net "P5E_CPU0_P3_RX_DP<10>")
	)
	(segment
		(start 371.10543 -294.014906)
		(end 371.106192 -294.014398)
		(width 0.1143)
		(layer "In4.Cu")
		(net "P5E_CPU0_P3_RX_DP<10>")
	)
	(segment
		(start 371.10797 -294.658542)
		(end 371.07622 -294.640254)
		(width 0.1143)
		(layer "In4.Cu")
		(net "P5E_CPU0_P3_RX_DP<10>")
	)
	(segment
		(start 384.769106 -379.269752)
		(end 384.768852 -379.269752)
		(width 0.14224)
		(layer "In4.Cu")
		(net "P5E_CPU0_P3_RX_DP<10>")
	)
	(segment
		(start 388.293864 -328.87158)
		(end 387.153912 -325.590408)
		(width 0.14224)
		(layer "In4.Cu")
		(net "P5E_CPU0_P3_RX_DP<10>")
	)
	(segment
		(start 371.104414 -294.015414)
		(end 371.10543 -294.014906)
		(width 0.1143)
		(layer "In4.Cu")
		(net "P5E_CPU0_P3_RX_DP<10>")
	)
	(segment
		(start 371.108478 -294.658542)
		(end 371.10797 -294.658542)
		(width 0.1143)
		(layer "In4.Cu")
		(net "P5E_CPU0_P3_RX_DP<10>")
	)
	(segment
		(start 384.821938 -379.096016)
		(end 386.009896 -373.126508)
		(width 0.14224)
		(layer "In4.Cu")
		(net "P5E_CPU0_P3_RX_DP<10>")
	)
	(segment
		(start 383.79527 -381.728726)
		(end 383.796032 -381.726694)
		(width 0.14224)
		(layer "In4.Cu")
		(net "P5E_CPU0_P3_RX_DP<10>")
	)
	(segment
		(start 387.153912 -325.590154)
		(end 383.74955 -315.79058)
		(width 0.14224)
		(layer "In4.Cu")
		(net "P5E_CPU0_P3_RX_DP<10>")
	)
	(segment
		(start 383.560574 -393.930632)
		(end 383.648712 -393.842494)
		(width 0.14224)
		(layer "In4.Cu")
		(net "P5E_CPU0_P3_RX_DP<10>")
	)
	(segment
		(start 383.648712 -393.428982)
		(end 383.332736 -393.113006)
		(width 0.14224)
		(layer "In4.Cu")
		(net "P5E_CPU0_P3_RX_DP<10>")
	)
	(segment
		(start 383.791968 -386.574538)
		(end 383.761996 -385.41706)
		(width 0.14224)
		(layer "In4.Cu")
		(net "P5E_CPU0_P3_RX_DP<10>")
	)
	(segment
		(start 372.588028 -300.623224)
		(end 371.801136 -299.44568)
		(width 0.14224)
		(layer "In4.Cu")
		(net "P5E_CPU0_P3_RX_DP<10>")
	)
	(segment
		(start 371.10797 -294.013382)
		(end 371.108478 -294.013382)
		(width 0.1143)
		(layer "In4.Cu")
		(net "P5E_CPU0_P3_RX_DP<10>")
	)
	(segment
		(start 371.10162 -294.016938)
		(end 371.103652 -294.015922)
		(width 0.1143)
		(layer "In4.Cu")
		(net "P5E_CPU0_P3_RX_DP<10>")
	)
	(segment
		(start 383.761742 -385.415282)
		(end 383.68097 -382.350264)
		(width 0.14224)
		(layer "In4.Cu")
		(net "P5E_CPU0_P3_RX_DP<10>")
	)
	(segment
		(start 371.107208 -295.633902)
		(end 371.10797 -295.633394)
		(width 0.1143)
		(layer "In4.Cu")
		(net "P5E_CPU0_P3_RX_DP<10>")
	)
	(segment
		(start 389.71982 -336.809842)
		(end 388.293864 -328.87158)
		(width 0.14224)
		(layer "In4.Cu")
		(net "P5E_CPU0_P3_RX_DP<10>")
	)
	(segment
		(start 370.965984 -296.460926)
		(end 370.920264 -296.415206)
		(width 0.1143)
		(layer "In4.Cu")
		(net "P5E_CPU0_P3_RX_DP<10>")
	)
	(segment
		(start 371.07622 -292.411658)
		(end 371.10797 -292.39337)
		(width 0.1143)
		(layer "In4.Cu")
		(net "P5E_CPU0_P3_RX_DP<10>")
	)
	(segment
		(start 371.106192 -294.014398)
		(end 371.107208 -294.01389)
		(width 0.1143)
		(layer "In4.Cu")
		(net "P5E_CPU0_P3_RX_DP<10>")
	)
	(segment
		(start 383.291334 -394.385292)
		(end 383.38633 -394.031216)
		(width 0.14224)
		(layer "In4.Cu")
		(net "P5E_CPU0_P3_RX_DP<10>")
	)
	(segment
		(start 370.920264 -296.415206)
		(end 370.920264 -295.955974)
		(width 0.1143)
		(layer "In4.Cu")
		(net "P5E_CPU0_P3_RX_DP<10>")
	)
	(segment
		(start 387.153912 -325.590408)
		(end 387.153912 -325.590154)
		(width 0.14224)
		(layer "In4.Cu")
		(net "P5E_CPU0_P3_RX_DP<10>")
	)
	(segment
		(start 370.965984 -296.489374)
		(end 370.965984 -296.460926)
		(width 0.1143)
		(layer "In4.Cu")
		(net "P5E_CPU0_P3_RX_DP<10>")
	)
	(arc
		(start 371.108478 -295.633394)
		(mid 371.389125 -295.145968)
		(end 371.108478 -294.658542)
		(width 0.1143)
		(layer "In4.Cu")
		(net "P5E_CPU0_P3_RX_DP<10>")
	)
	(arc
		(start 371.07622 -293.020242)
		(mid 370.920292 -292.71595)
		(end 371.07622 -292.411658)
		(width 0.1143)
		(layer "In4.Cu")
		(net "P5E_CPU0_P3_RX_DP<10>")
	)
	(arc
		(start 371.07622 -291.40023)
		(mid 370.979085 -291.297361)
		(end 370.927122 -291.165788)
		(width 0.1143)
		(layer "In4.Cu")
		(net "P5E_CPU0_P3_RX_DP<10>")
	)
	(arc
		(start 371.108478 -294.013382)
		(mid 371.389125 -293.525956)
		(end 371.108478 -293.03853)
		(width 0.1143)
		(layer "In4.Cu")
		(net "P5E_CPU0_P3_RX_DP<10>")
	)
	(arc
		(start 371.07622 -294.640254)
		(mid 370.920292 -294.335962)
		(end 371.07622 -294.03167)
		(width 0.1143)
		(layer "In4.Cu")
		(net "P5E_CPU0_P3_RX_DP<10>")
	)
	(arc
		(start 371.10797 -292.39337)
		(mid 371.388617 -291.905944)
		(end 371.10797 -291.418518)
		(width 0.1143)
		(layer "In4.Cu")
		(net "P5E_CPU0_P3_RX_DP<10>")
	)
	(arc
		(start 389.702294 -360.933492)
		(mid 389.715457 -360.874704)
		(end 389.71982 -360.81462)
		(width 0.14224)
		(layer "In4.Cu")
		(net "P5E_CPU0_P3_RX_DP<10>")
	)
	(arc
		(start 370.983256 -297.470322)
		(mid 370.970343 -297.427738)
		(end 370.965984 -297.383454)
		(width 0.14224)
		(layer "In4.Cu")
		(net "P5E_CPU0_P3_RX_DP<10>")
	)
	(arc
		(start 384.768852 -379.269752)
		(mid 384.799544 -379.184055)
		(end 384.821684 -379.095762)
		(width 0.14224)
		(layer "In4.Cu")
		(net "P5E_CPU0_P3_RX_DP<10>")
	)
	(arc
		(start 383.68097 -382.350264)
		(mid 383.705242 -382.033449)
		(end 383.79527 -381.728726)
		(width 0.14224)
		(layer "In4.Cu")
		(net "P5E_CPU0_P3_RX_DP<10>")
	)
	(arc
		(start 370.920264 -295.955974)
		(mid 370.961519 -295.785003)
		(end 371.07622 -295.651682)
		(width 0.1143)
		(layer "In4.Cu")
		(net "P5E_CPU0_P3_RX_DP<10>")
	)
	(arc
		(start 386.009896 -373.126508)
		(mid 386.023752 -373.064662)
		(end 386.04063 -373.003572)
		(width 0.14224)
		(layer "In4.Cu")
		(net "P5E_CPU0_P3_RX_DP<10>")
	)
	(segment
		(start 381.170434 -393.69238)
		(end 381.691134 -393.69238)
		(width 0.127)
		(layer "F.Cu")
		(net "P5E_CPU0_P3_RX_DN<9>")
	)
	(segment
		(start 369.888008 -287.59023)
		(end 370.35486 -287.856168)
		(width 0.12954)
		(layer "F.Cu")
		(net "P5E_CPU0_P3_RX_DN<9>")
	)
	(segment
		(start 382.374648 -386.903214)
		(end 382.315466 -384.639566)
		(width 0.14224)
		(layer "In4.Cu")
		(net "P5E_CPU0_P3_RX_DN<9>")
	)
	(segment
		(start 381.691134 -393.69238)
		(end 382.044448 -393.787376)
		(width 0.14224)
		(layer "In4.Cu")
		(net "P5E_CPU0_P3_RX_DN<9>")
	)
	(segment
		(start 370.071904 -293.848536)
		(end 370.072666 -293.848028)
		(width 0.1143)
		(layer "In4.Cu")
		(net "P5E_CPU0_P3_RX_DN<9>")
	)
	(segment
		(start 370.063522 -291.578284)
		(end 370.055394 -291.573204)
		(width 0.1143)
		(layer "In4.Cu")
		(net "P5E_CPU0_P3_RX_DN<9>")
	)
	(segment
		(start 370.070888 -291.582856)
		(end 370.069364 -291.58184)
		(width 0.1143)
		(layer "In4.Cu")
		(net "P5E_CPU0_P3_RX_DN<9>")
	)
	(segment
		(start 387.46049 -331.112114)
		(end 387.46049 -331.112368)
		(width 0.14224)
		(layer "In4.Cu")
		(net "P5E_CPU0_P3_RX_DN<9>")
	)
	(segment
		(start 370.06784 -292.229794)
		(end 370.081556 -292.22319)
		(width 0.1143)
		(layer "In4.Cu")
		(net "P5E_CPU0_P3_RX_DN<9>")
	)
	(segment
		(start 370.069364 -291.58184)
		(end 370.068348 -291.581332)
		(width 0.1143)
		(layer "In4.Cu")
		(net "P5E_CPU0_P3_RX_DN<9>")
	)
	(segment
		(start 387.11251 -329.174348)
		(end 384.876802 -322.73875)
		(width 0.14224)
		(layer "In4.Cu")
		(net "P5E_CPU0_P3_RX_DN<9>")
	)
	(segment
		(start 382.296924 -383.938526)
		(end 382.25603 -382.369314)
		(width 0.14224)
		(layer "In4.Cu")
		(net "P5E_CPU0_P3_RX_DN<9>")
	)
	(segment
		(start 370.077746 -288.98469)
		(end 370.081556 -288.982658)
		(width 0.1143)
		(layer "In4.Cu")
		(net "P5E_CPU0_P3_RX_DN<9>")
	)
	(segment
		(start 370.071904 -294.823388)
		(end 370.070888 -294.82288)
		(width 0.1143)
		(layer "In4.Cu")
		(net "P5E_CPU0_P3_RX_DN<9>")
	)
	(segment
		(start 370.073936 -293.847266)
		(end 370.07546 -293.846504)
		(width 0.1143)
		(layer "In4.Cu")
		(net "P5E_CPU0_P3_RX_DN<9>")
	)
	(segment
		(start 383.423922 -379.324362)
		(end 383.423922 -376.910092)
		(width 0.14224)
		(layer "In4.Cu")
		(net "P5E_CPU0_P3_RX_DN<9>")
	)
	(segment
		(start 370.08562 -292.221158)
		(end 370.09705 -292.21557)
		(width 0.1143)
		(layer "In4.Cu")
		(net "P5E_CPU0_P3_RX_DN<9>")
	)
	(segment
		(start 370.087906 -293.838122)
		(end 370.10213 -293.829994)
		(width 0.1143)
		(layer "In4.Cu")
		(net "P5E_CPU0_P3_RX_DN<9>")
	)
	(segment
		(start 370.103654 -294.841676)
		(end 370.073936 -294.824658)
		(width 0.1143)
		(layer "In4.Cu")
		(net "P5E_CPU0_P3_RX_DN<9>")
	)
	(segment
		(start 370.073174 -288.987484)
		(end 370.077746 -288.98469)
		(width 0.1143)
		(layer "In4.Cu")
		(net "P5E_CPU0_P3_RX_DN<9>")
	)
	(segment
		(start 384.877056 -322.73875)
		(end 382.641602 -316.303406)
		(width 0.14224)
		(layer "In4.Cu")
		(net "P5E_CPU0_P3_RX_DN<9>")
	)
	(segment
		(start 369.632484 -290.791138)
		(end 369.602004 -290.773358)
		(width 0.1143)
		(layer "In4.Cu")
		(net "P5E_CPU0_P3_RX_DN<9>")
	)
	(segment
		(start 370.08308 -292.222174)
		(end 370.08562 -292.221158)
		(width 0.1143)
		(layer "In4.Cu")
		(net "P5E_CPU0_P3_RX_DN<9>")
	)
	(segment
		(start 382.232916 -389.229854)
		(end 382.105662 -389.083296)
		(width 0.14224)
		(layer "In4.Cu")
		(net "P5E_CPU0_P3_RX_DN<9>")
	)
	(segment
		(start 370.069618 -288.98977)
		(end 370.073174 -288.987484)
		(width 0.1143)
		(layer "In4.Cu")
		(net "P5E_CPU0_P3_RX_DN<9>")
	)
	(segment
		(start 370.683536 -299.9613)
		(end 369.774724 -297.76801)
		(width 0.14224)
		(layer "In4.Cu")
		(net "P5E_CPU0_P3_RX_DN<9>")
	)
	(segment
		(start 370.072666 -293.848028)
		(end 370.073936 -293.847266)
		(width 0.1143)
		(layer "In4.Cu")
		(net "P5E_CPU0_P3_RX_DN<9>")
	)
	(segment
		(start 388.5057 -359.237534)
		(end 388.5057 -336.92973)
		(width 0.14224)
		(layer "In4.Cu")
		(net "P5E_CPU0_P3_RX_DN<9>")
	)
	(segment
		(start 370.06149 -293.855394)
		(end 370.070888 -293.849044)
		(width 0.1143)
		(layer "In4.Cu")
		(net "P5E_CPU0_P3_RX_DN<9>")
	)
	(segment
		(start 370.065808 -291.579808)
		(end 370.064792 -291.579046)
		(width 0.1143)
		(layer "In4.Cu")
		(net "P5E_CPU0_P3_RX_DN<9>")
	)
	(segment
		(start 369.562888 -289.821366)
		(end 369.613942 -289.791394)
		(width 0.1143)
		(layer "In4.Cu")
		(net "P5E_CPU0_P3_RX_DN<9>")
	)
	(segment
		(start 370.072666 -291.583872)
		(end 370.071904 -291.583364)
		(width 0.1143)
		(layer "In4.Cu")
		(net "P5E_CPU0_P3_RX_DN<9>")
	)
	(segment
		(start 381.854456 -392.617198)
		(end 382.118616 -392.352022)
		(width 0.14224)
		(layer "In4.Cu")
		(net "P5E_CPU0_P3_RX_DN<9>")
	)
	(segment
		(start 369.743736 -296.427906)
		(end 369.789456 -296.382186)
		(width 0.1143)
		(layer "In4.Cu")
		(net "P5E_CPU0_P3_RX_DN<9>")
	)
	(segment
		(start 382.13538 -388.657338)
		(end 382.282192 -388.530084)
		(width 0.14224)
		(layer "In4.Cu")
		(net "P5E_CPU0_P3_RX_DN<9>")
	)
	(segment
		(start 382.281684 -388.52983)
		(end 382.364996 -387.343904)
		(width 0.14224)
		(layer "In4.Cu")
		(net "P5E_CPU0_P3_RX_DN<9>")
	)
	(segment
		(start 382.282192 -388.530084)
		(end 382.281684 -388.52983)
		(width 0.14224)
		(layer "In4.Cu")
		(net "P5E_CPU0_P3_RX_DN<9>")
	)
	(segment
		(start 370.049298 -292.241732)
		(end 370.062252 -292.233096)
		(width 0.1143)
		(layer "In4.Cu")
		(net "P5E_CPU0_P3_RX_DN<9>")
	)
	(segment
		(start 370.070888 -294.82288)
		(end 370.068856 -294.82161)
		(width 0.1143)
		(layer "In4.Cu")
		(net "P5E_CPU0_P3_RX_DN<9>")
	)
	(segment
		(start 370.072666 -294.823896)
		(end 370.071904 -294.823388)
		(width 0.1143)
		(layer "In4.Cu")
		(net "P5E_CPU0_P3_RX_DN<9>")
	)
	(segment
		(start 384.876802 -322.73875)
		(end 384.877056 -322.73875)
		(width 0.14224)
		(layer "In4.Cu")
		(net "P5E_CPU0_P3_RX_DN<9>")
	)
	(segment
		(start 370.10213 -293.22141)
		(end 370.079524 -293.208456)
		(width 0.1143)
		(layer "In4.Cu")
		(net "P5E_CPU0_P3_RX_DN<9>")
	)
	(segment
		(start 387.46049 -331.112368)
		(end 387.11251 -329.174348)
		(width 0.14224)
		(layer "In4.Cu")
		(net "P5E_CPU0_P3_RX_DN<9>")
	)
	(segment
		(start 370.081556 -292.22319)
		(end 370.08308 -292.222174)
		(width 0.1143)
		(layer "In4.Cu")
		(net "P5E_CPU0_P3_RX_DN<9>")
	)
	(segment
		(start 370.058696 -293.856918)
		(end 370.06149 -293.855394)
		(width 0.1143)
		(layer "In4.Cu")
		(net "P5E_CPU0_P3_RX_DN<9>")
	)
	(segment
		(start 370.034058 -295.490392)
		(end 370.10467 -295.449244)
		(width 0.1143)
		(layer "In4.Cu")
		(net "P5E_CPU0_P3_RX_DN<9>")
	)
	(segment
		(start 370.070888 -293.849044)
		(end 370.071904 -293.848536)
		(width 0.1143)
		(layer "In4.Cu")
		(net "P5E_CPU0_P3_RX_DN<9>")
	)
	(segment
		(start 382.105662 -389.083296)
		(end 382.13538 -388.657338)
		(width 0.14224)
		(layer "In4.Cu")
		(net "P5E_CPU0_P3_RX_DN<9>")
	)
	(segment
		(start 382.044956 -393.786868)
		(end 382.166622 -393.716764)
		(width 0.14224)
		(layer "In4.Cu")
		(net "P5E_CPU0_P3_RX_DN<9>")
	)
	(segment
		(start 382.16332 -384.079242)
		(end 382.296924 -383.938526)
		(width 0.14224)
		(layer "In4.Cu")
		(net "P5E_CPU0_P3_RX_DN<9>")
	)
	(segment
		(start 382.166622 -393.716764)
		(end 382.166622 -393.545822)
		(width 0.14224)
		(layer "In4.Cu")
		(net "P5E_CPU0_P3_RX_DN<9>")
	)
	(segment
		(start 382.056386 -389.782558)
		(end 382.203198 -389.655304)
		(width 0.14224)
		(layer "In4.Cu")
		(net "P5E_CPU0_P3_RX_DN<9>")
	)
	(segment
		(start 369.602004 -290.773358)
		(end 369.562888 -290.750498)
		(width 0.1143)
		(layer "In4.Cu")
		(net "P5E_CPU0_P3_RX_DN<9>")
	)
	(segment
		(start 382.641602 -316.303406)
		(end 380.335536 -311.989724)
		(width 0.14224)
		(layer "In4.Cu")
		(net "P5E_CPU0_P3_RX_DN<9>")
	)
	(segment
		(start 369.743736 -296.456354)
		(end 369.743736 -296.427906)
		(width 0.1143)
		(layer "In4.Cu")
		(net "P5E_CPU0_P3_RX_DN<9>")
	)
	(segment
		(start 370.259864 -295.146222)
		(end 370.259864 -295.145968)
		(width 0.1143)
		(layer "In4.Cu")
		(net "P5E_CPU0_P3_RX_DN<9>")
	)
	(segment
		(start 370.064792 -291.579046)
		(end 370.063522 -291.578284)
		(width 0.1143)
		(layer "In4.Cu")
		(net "P5E_CPU0_P3_RX_DN<9>")
	)
	(segment
		(start 383.685288 -375.14657)
		(end 388.500112 -359.274364)
		(width 0.14224)
		(layer "In4.Cu")
		(net "P5E_CPU0_P3_RX_DN<9>")
	)
	(segment
		(start 388.5057 -336.92973)
		(end 387.46049 -331.112114)
		(width 0.14224)
		(layer "In4.Cu")
		(net "P5E_CPU0_P3_RX_DN<9>")
	)
	(segment
		(start 370.070888 -293.202868)
		(end 370.069364 -293.201852)
		(width 0.1143)
		(layer "In4.Cu")
		(net "P5E_CPU0_P3_RX_DN<9>")
	)
	(segment
		(start 380.335536 -311.989724)
		(end 371.644926 -301.399956)
		(width 0.14224)
		(layer "In4.Cu")
		(net "P5E_CPU0_P3_RX_DN<9>")
	)
	(segment
		(start 370.071904 -293.203376)
		(end 370.070888 -293.202868)
		(width 0.1143)
		(layer "In4.Cu")
		(net "P5E_CPU0_P3_RX_DN<9>")
	)
	(segment
		(start 382.203198 -389.655304)
		(end 382.202944 -389.655304)
		(width 0.14224)
		(layer "In4.Cu")
		(net "P5E_CPU0_P3_RX_DN<9>")
	)
	(segment
		(start 382.118616 -392.352022)
		(end 382.118616 -390.860534)
		(width 0.14224)
		(layer "In4.Cu")
		(net "P5E_CPU0_P3_RX_DN<9>")
	)
	(segment
		(start 370.069364 -288.98977)
		(end 370.069618 -288.98977)
		(width 0.1143)
		(layer "In4.Cu")
		(net "P5E_CPU0_P3_RX_DN<9>")
	)
	(segment
		(start 369.743736 -297.611038)
		(end 369.743736 -296.456354)
		(width 0.14224)
		(layer "In4.Cu")
		(net "P5E_CPU0_P3_RX_DN<9>")
	)
	(segment
		(start 370.032788 -292.251384)
		(end 370.049298 -292.241732)
		(width 0.1143)
		(layer "In4.Cu")
		(net "P5E_CPU0_P3_RX_DN<9>")
	)
	(segment
		(start 370.722652 -287.926018)
		(end 370.652802 -287.856168)
		(width 0.1143)
		(layer "In4.Cu")
		(net "P5E_CPU0_P3_RX_DN<9>")
	)
	(segment
		(start 370.033042 -293.871904)
		(end 370.058696 -293.856918)
		(width 0.1143)
		(layer "In4.Cu")
		(net "P5E_CPU0_P3_RX_DN<9>")
	)
	(segment
		(start 370.103654 -291.603176)
		(end 370.094256 -291.597588)
		(width 0.1143)
		(layer "In4.Cu")
		(net "P5E_CPU0_P3_RX_DN<9>")
	)
	(segment
		(start 382.232662 -389.231124)
		(end 382.232916 -389.229854)
		(width 0.14224)
		(layer "In4.Cu")
		(net "P5E_CPU0_P3_RX_DN<9>")
	)
	(segment
		(start 382.202944 -389.655304)
		(end 382.232662 -389.231124)
		(width 0.14224)
		(layer "In4.Cu")
		(net "P5E_CPU0_P3_RX_DN<9>")
	)
	(segment
		(start 382.166622 -393.545822)
		(end 381.84963 -393.22883)
		(width 0.14224)
		(layer "In4.Cu")
		(net "P5E_CPU0_P3_RX_DN<9>")
	)
	(segment
		(start 370.073936 -291.584634)
		(end 370.072666 -291.583872)
		(width 0.1143)
		(layer "In4.Cu")
		(net "P5E_CPU0_P3_RX_DN<9>")
	)
	(segment
		(start 369.789456 -296.382186)
		(end 369.789456 -295.955974)
		(width 0.1143)
		(layer "In4.Cu")
		(net "P5E_CPU0_P3_RX_DN<9>")
	)
	(segment
		(start 370.076476 -291.585904)
		(end 370.073936 -291.584634)
		(width 0.1143)
		(layer "In4.Cu")
		(net "P5E_CPU0_P3_RX_DN<9>")
	)
	(segment
		(start 381.84963 -393.22883)
		(end 381.854456 -392.617198)
		(width 0.14224)
		(layer "In4.Cu")
		(net "P5E_CPU0_P3_RX_DN<9>")
	)
	(segment
		(start 370.071904 -291.583364)
		(end 370.070888 -291.582856)
		(width 0.1143)
		(layer "In4.Cu")
		(net "P5E_CPU0_P3_RX_DN<9>")
	)
	(segment
		(start 370.062252 -292.233096)
		(end 370.06784 -292.229794)
		(width 0.1143)
		(layer "In4.Cu")
		(net "P5E_CPU0_P3_RX_DN<9>")
	)
	(segment
		(start 370.07546 -293.846504)
		(end 370.087906 -293.838122)
		(width 0.1143)
		(layer "In4.Cu")
		(net "P5E_CPU0_P3_RX_DN<9>")
	)
	(segment
		(start 382.118616 -390.860534)
		(end 382.153922 -390.35482)
		(width 0.14224)
		(layer "In4.Cu")
		(net "P5E_CPU0_P3_RX_DN<9>")
	)
	(segment
		(start 370.073936 -294.824658)
		(end 370.072666 -294.823896)
		(width 0.1143)
		(layer "In4.Cu")
		(net "P5E_CPU0_P3_RX_DN<9>")
	)
	(segment
		(start 371.644926 -301.399956)
		(end 370.683536 -299.9613)
		(width 0.14224)
		(layer "In4.Cu")
		(net "P5E_CPU0_P3_RX_DN<9>")
	)
	(segment
		(start 382.315466 -384.639566)
		(end 382.174496 -384.506216)
		(width 0.14224)
		(layer "In4.Cu")
		(net "P5E_CPU0_P3_RX_DN<9>")
	)
	(segment
		(start 382.174496 -384.506216)
		(end 382.16332 -384.079242)
		(width 0.14224)
		(layer "In4.Cu")
		(net "P5E_CPU0_P3_RX_DN<9>")
	)
	(segment
		(start 370.094256 -291.597588)
		(end 370.076476 -291.585904)
		(width 0.1143)
		(layer "In4.Cu")
		(net "P5E_CPU0_P3_RX_DN<9>")
	)
	(segment
		(start 370.068348 -291.581332)
		(end 370.065808 -291.579808)
		(width 0.1143)
		(layer "In4.Cu")
		(net "P5E_CPU0_P3_RX_DN<9>")
	)
	(segment
		(start 382.044448 -393.787376)
		(end 382.044956 -393.786868)
		(width 0.14224)
		(layer "In4.Cu")
		(net "P5E_CPU0_P3_RX_DN<9>")
	)
	(segment
		(start 370.041678 -289.006026)
		(end 370.069364 -288.98977)
		(width 0.1143)
		(layer "In4.Cu")
		(net "P5E_CPU0_P3_RX_DN<9>")
	)
	(segment
		(start 382.25603 -382.144016)
		(end 383.423922 -379.324362)
		(width 0.14224)
		(layer "In4.Cu")
		(net "P5E_CPU0_P3_RX_DN<9>")
	)
	(segment
		(start 382.153922 -390.35482)
		(end 382.026668 -390.208516)
		(width 0.14224)
		(layer "In4.Cu")
		(net "P5E_CPU0_P3_RX_DN<9>")
	)
	(segment
		(start 370.09705 -292.21557)
		(end 370.103654 -292.21176)
		(width 0.1143)
		(layer "In4.Cu")
		(net "P5E_CPU0_P3_RX_DN<9>")
	)
	(segment
		(start 370.069364 -293.201852)
		(end 370.032788 -293.180516)
		(width 0.1143)
		(layer "In4.Cu")
		(net "P5E_CPU0_P3_RX_DN<9>")
	)
	(segment
		(start 370.502942 -288.201354)
		(end 370.57457 -288.159698)
		(width 0.1143)
		(layer "In4.Cu")
		(net "P5E_CPU0_P3_RX_DN<9>")
	)
	(segment
		(start 370.079524 -293.208456)
		(end 370.071904 -293.203376)
		(width 0.1143)
		(layer "In4.Cu")
		(net "P5E_CPU0_P3_RX_DN<9>")
	)
	(segment
		(start 382.25603 -382.369314)
		(end 382.25603 -382.144016)
		(width 0.14224)
		(layer "In4.Cu")
		(net "P5E_CPU0_P3_RX_DN<9>")
	)
	(segment
		(start 370.652802 -287.856168)
		(end 370.35486 -287.856168)
		(width 0.1143)
		(layer "In4.Cu")
		(net "P5E_CPU0_P3_RX_DN<9>")
	)
	(segment
		(start 382.026668 -390.208516)
		(end 382.056386 -389.782558)
		(width 0.14224)
		(layer "In4.Cu")
		(net "P5E_CPU0_P3_RX_DN<9>")
	)
	(arc
		(start 382.364996 -387.343904)
		(mid 382.375113 -387.123675)
		(end 382.374648 -386.903214)
		(width 0.14224)
		(layer "In4.Cu")
		(net "P5E_CPU0_P3_RX_DN<9>")
	)
	(arc
		(start 369.789456 -295.9481)
		(mid 369.854802 -295.699877)
		(end 370.018056 -295.501822)
		(width 0.1143)
		(layer "In4.Cu")
		(net "P5E_CPU0_P3_RX_DN<9>")
	)
	(arc
		(start 370.259864 -295.145968)
		(mid 370.218524 -294.974953)
		(end 370.103654 -294.841676)
		(width 0.1143)
		(layer "In4.Cu")
		(net "P5E_CPU0_P3_RX_DN<9>")
	)
	(arc
		(start 388.500112 -359.274364)
		(mid 388.504258 -359.256154)
		(end 388.5057 -359.237534)
		(width 0.14224)
		(layer "In4.Cu")
		(net "P5E_CPU0_P3_RX_DN<9>")
	)
	(arc
		(start 370.068856 -294.82161)
		(mid 369.790624 -294.356516)
		(end 370.033042 -293.871904)
		(width 0.1143)
		(layer "In4.Cu")
		(net "P5E_CPU0_P3_RX_DN<9>")
	)
	(arc
		(start 370.10467 -295.449244)
		(mid 370.218765 -295.316423)
		(end 370.259864 -295.146222)
		(width 0.1143)
		(layer "In4.Cu")
		(net "P5E_CPU0_P3_RX_DN<9>")
	)
	(arc
		(start 369.789456 -291.088064)
		(mid 369.746159 -290.920988)
		(end 369.632484 -290.791138)
		(width 0.1143)
		(layer "In4.Cu")
		(net "P5E_CPU0_P3_RX_DN<9>")
	)
	(arc
		(start 370.10213 -293.829994)
		(mid 370.258058 -293.525702)
		(end 370.10213 -293.22141)
		(width 0.1143)
		(layer "In4.Cu")
		(net "P5E_CPU0_P3_RX_DN<9>")
	)
	(arc
		(start 383.423922 -376.910092)
		(mid 383.489556 -376.018689)
		(end 383.685288 -375.14657)
		(width 0.14224)
		(layer "In4.Cu")
		(net "P5E_CPU0_P3_RX_DN<9>")
	)
	(arc
		(start 370.57457 -288.159698)
		(mid 370.67101 -288.057043)
		(end 370.722652 -287.926018)
		(width 0.1143)
		(layer "In4.Cu")
		(net "P5E_CPU0_P3_RX_DN<9>")
	)
	(arc
		(start 369.789456 -295.955974)
		(mid 369.789443 -295.952037)
		(end 369.789456 -295.9481)
		(width 0.1143)
		(layer "In4.Cu")
		(net "P5E_CPU0_P3_RX_DN<9>")
	)
	(arc
		(start 370.103654 -292.21176)
		(mid 370.259582 -291.907468)
		(end 370.103654 -291.603176)
		(width 0.1143)
		(layer "In4.Cu")
		(net "P5E_CPU0_P3_RX_DN<9>")
	)
	(arc
		(start 370.081556 -288.982658)
		(mid 370.209376 -288.852207)
		(end 370.25961 -288.676588)
		(width 0.1143)
		(layer "In4.Cu")
		(net "P5E_CPU0_P3_RX_DN<9>")
	)
	(arc
		(start 370.018056 -295.501822)
		(mid 370.02563 -295.496297)
		(end 370.033296 -295.4909)
		(width 0.1143)
		(layer "In4.Cu")
		(net "P5E_CPU0_P3_RX_DN<9>")
	)
	(arc
		(start 369.613942 -289.791394)
		(mid 369.748925 -289.655592)
		(end 369.798346 -289.470592)
		(width 0.1143)
		(layer "In4.Cu")
		(net "P5E_CPU0_P3_RX_DN<9>")
	)
	(arc
		(start 370.25961 -288.676588)
		(mid 370.321601 -288.408416)
		(end 370.502942 -288.201354)
		(width 0.1143)
		(layer "In4.Cu")
		(net "P5E_CPU0_P3_RX_DN<9>")
	)
	(arc
		(start 370.032788 -293.180516)
		(mid 369.789461 -292.71595)
		(end 370.032788 -292.251384)
		(width 0.1143)
		(layer "In4.Cu")
		(net "P5E_CPU0_P3_RX_DN<9>")
	)
	(arc
		(start 369.798346 -289.470592)
		(mid 369.862861 -289.208373)
		(end 370.041678 -289.006026)
		(width 0.1143)
		(layer "In4.Cu")
		(net "P5E_CPU0_P3_RX_DN<9>")
	)
	(arc
		(start 369.774724 -297.76801)
		(mid 369.751497 -297.691052)
		(end 369.743736 -297.611038)
		(width 0.14224)
		(layer "In4.Cu")
		(net "P5E_CPU0_P3_RX_DN<9>")
	)
	(arc
		(start 370.055394 -291.573204)
		(mid 369.862912 -291.363253)
		(end 369.789456 -291.088064)
		(width 0.1143)
		(layer "In4.Cu")
		(net "P5E_CPU0_P3_RX_DN<9>")
	)
	(arc
		(start 370.033296 -295.4909)
		(mid 370.033677 -295.490646)
		(end 370.034058 -295.490392)
		(width 0.1143)
		(layer "In4.Cu")
		(net "P5E_CPU0_P3_RX_DN<9>")
	)
	(arc
		(start 369.562888 -290.750498)
		(mid 369.319561 -290.285932)
		(end 369.562888 -289.821366)
		(width 0.1143)
		(layer "In4.Cu")
		(net "P5E_CPU0_P3_RX_DN<9>")
	)
	(segment
		(start 367.067846 -289.209988)
		(end 367.534698 -289.475926)
		(width 0.12954)
		(layer "F.Cu")
		(net "P5E_CPU0_P3_RX_DN<8>")
	)
	(segment
		(start 379.970538 -393.69238)
		(end 380.491238 -393.69238)
		(width 0.127)
		(layer "F.Cu")
		(net "P5E_CPU0_P3_RX_DN<8>")
	)
	(segment
		(start 381.067056 -388.997698)
		(end 381.06731 -388.997698)
		(width 0.14224)
		(layer "In4.Cu")
		(net "P5E_CPU0_P3_RX_DN<8>")
	)
	(segment
		(start 381.116332 -388.297928)
		(end 381.116078 -388.297928)
		(width 0.14224)
		(layer "In4.Cu")
		(net "P5E_CPU0_P3_RX_DN<8>")
	)
	(segment
		(start 381.06731 -388.997698)
		(end 380.940056 -388.85114)
		(width 0.14224)
		(layer "In4.Cu")
		(net "P5E_CPU0_P3_RX_DN<8>")
	)
	(segment
		(start 367.915444 -289.55873)
		(end 367.83264 -289.475926)
		(width 0.1143)
		(layer "In4.Cu")
		(net "P5E_CPU0_P3_RX_DN<8>")
	)
	(segment
		(start 368.666268 -290.775898)
		(end 368.663728 -290.774628)
		(width 0.1143)
		(layer "In4.Cu")
		(net "P5E_CPU0_P3_RX_DN<8>")
	)
	(segment
		(start 370.82476 -301.87138)
		(end 369.794282 -300.329092)
		(width 0.14224)
		(layer "In4.Cu")
		(net "P5E_CPU0_P3_RX_DN<8>")
	)
	(segment
		(start 381.168656 -383.594864)
		(end 381.13843 -382.430782)
		(width 0.14224)
		(layer "In4.Cu")
		(net "P5E_CPU0_P3_RX_DN<8>")
	)
	(segment
		(start 380.84506 -393.786868)
		(end 380.966726 -393.716764)
		(width 0.14224)
		(layer "In4.Cu")
		(net "P5E_CPU0_P3_RX_DN<8>")
	)
	(segment
		(start 380.966726 -393.545822)
		(end 380.649734 -393.22883)
		(width 0.14224)
		(layer "In4.Cu")
		(net "P5E_CPU0_P3_RX_DN<8>")
	)
	(segment
		(start 380.010924 -377.693682)
		(end 380.010924 -376.362214)
		(width 0.14224)
		(layer "In4.Cu")
		(net "P5E_CPU0_P3_RX_DN<8>")
	)
	(segment
		(start 368.849656 -296.38879)
		(end 368.849656 -296.172382)
		(width 0.1143)
		(layer "In4.Cu")
		(net "P5E_CPU0_P3_RX_DN<8>")
	)
	(segment
		(start 380.739396 -378.616972)
		(end 380.148592 -378.026168)
		(width 0.14224)
		(layer "In4.Cu")
		(net "P5E_CPU0_P3_RX_DN<8>")
	)
	(segment
		(start 381.13843 -382.430782)
		(end 381.13843 -381.78359)
		(width 0.14224)
		(layer "In4.Cu")
		(net "P5E_CPU0_P3_RX_DN<8>")
	)
	(segment
		(start 380.844552 -393.787376)
		(end 380.84506 -393.786868)
		(width 0.14224)
		(layer "In4.Cu")
		(net "P5E_CPU0_P3_RX_DN<8>")
	)
	(segment
		(start 369.13185 -294.823388)
		(end 369.092734 -294.800528)
		(width 0.1143)
		(layer "In4.Cu")
		(net "P5E_CPU0_P3_RX_DN<8>")
	)
	(segment
		(start 368.668808 -290.777422)
		(end 368.667792 -290.776914)
		(width 0.1143)
		(layer "In4.Cu")
		(net "P5E_CPU0_P3_RX_DN<8>")
	)
	(segment
		(start 368.661696 -290.773358)
		(end 368.65179 -290.767262)
		(width 0.1143)
		(layer "In4.Cu")
		(net "P5E_CPU0_P3_RX_DN<8>")
	)
	(segment
		(start 368.803936 -297.688508)
		(end 368.803936 -296.462958)
		(width 0.14224)
		(layer "In4.Cu")
		(net "P5E_CPU0_P3_RX_DN<8>")
	)
	(segment
		(start 369.13185 -293.203376)
		(end 369.092734 -293.180516)
		(width 0.1143)
		(layer "In4.Cu")
		(net "P5E_CPU0_P3_RX_DN<8>")
	)
	(segment
		(start 380.958598 -392.312652)
		(end 380.958598 -390.548368)
		(width 0.14224)
		(layer "In4.Cu")
		(net "P5E_CPU0_P3_RX_DN<8>")
	)
	(segment
		(start 369.16233 -291.601144)
		(end 369.13185 -291.583364)
		(width 0.1143)
		(layer "In4.Cu")
		(net "P5E_CPU0_P3_RX_DN<8>")
	)
	(segment
		(start 380.861062 -389.97636)
		(end 380.89078 -389.550402)
		(width 0.14224)
		(layer "In4.Cu")
		(net "P5E_CPU0_P3_RX_DN<8>")
	)
	(segment
		(start 369.13185 -292.228524)
		(end 369.16233 -292.210744)
		(width 0.1143)
		(layer "In4.Cu")
		(net "P5E_CPU0_P3_RX_DN<8>")
	)
	(segment
		(start 380.65456 -392.61669)
		(end 380.958598 -392.312652)
		(width 0.14224)
		(layer "In4.Cu")
		(net "P5E_CPU0_P3_RX_DN<8>")
	)
	(segment
		(start 381.362458 -378.959364)
		(end 381.072136 -378.839222)
		(width 0.14224)
		(layer "In4.Cu")
		(net "P5E_CPU0_P3_RX_DN<8>")
	)
	(segment
		(start 368.803936 -296.43451)
		(end 368.849656 -296.38879)
		(width 0.1143)
		(layer "In4.Cu")
		(net "P5E_CPU0_P3_RX_DN<8>")
	)
	(segment
		(start 387.57352 -357.453184)
		(end 387.57352 -337.032346)
		(width 0.14224)
		(layer "In4.Cu")
		(net "P5E_CPU0_P3_RX_DN<8>")
	)
	(segment
		(start 369.16233 -294.841168)
		(end 369.13185 -294.823388)
		(width 0.1143)
		(layer "In4.Cu")
		(net "P5E_CPU0_P3_RX_DN<8>")
	)
	(segment
		(start 380.218442 -375.31802)
		(end 387.531864 -357.66248)
		(width 0.14224)
		(layer "In4.Cu")
		(net "P5E_CPU0_P3_RX_DN<8>")
	)
	(segment
		(start 380.89078 -389.550402)
		(end 381.037592 -389.423148)
		(width 0.14224)
		(layer "In4.Cu")
		(net "P5E_CPU0_P3_RX_DN<8>")
	)
	(segment
		(start 380.491238 -393.69238)
		(end 380.844552 -393.787376)
		(width 0.14224)
		(layer "In4.Cu")
		(net "P5E_CPU0_P3_RX_DN<8>")
	)
	(segment
		(start 381.046228 -384.1623)
		(end 381.035052 -383.73558)
		(width 0.14224)
		(layer "In4.Cu")
		(net "P5E_CPU0_P3_RX_DN<8>")
	)
	(segment
		(start 381.722122 -380.374398)
		(end 381.722122 -379.498352)
		(width 0.14224)
		(layer "In4.Cu")
		(net "P5E_CPU0_P3_RX_DN<8>")
	)
	(segment
		(start 381.037592 -389.423148)
		(end 381.037084 -389.422894)
		(width 0.14224)
		(layer "In4.Cu")
		(net "P5E_CPU0_P3_RX_DN<8>")
	)
	(segment
		(start 387.57352 -337.032346)
		(end 386.201666 -329.395328)
		(width 0.14224)
		(layer "In4.Cu")
		(net "P5E_CPU0_P3_RX_DN<8>")
	)
	(segment
		(start 369.13185 -291.583364)
		(end 369.092734 -291.560504)
		(width 0.1143)
		(layer "In4.Cu")
		(net "P5E_CPU0_P3_RX_DN<8>")
	)
	(segment
		(start 386.201666 -329.395328)
		(end 381.821182 -316.783466)
		(width 0.14224)
		(layer "In4.Cu")
		(net "P5E_CPU0_P3_RX_DN<8>")
	)
	(segment
		(start 367.83264 -289.475926)
		(end 367.534698 -289.475926)
		(width 0.1143)
		(layer "In4.Cu")
		(net "P5E_CPU0_P3_RX_DN<8>")
	)
	(segment
		(start 368.849656 -296.172382)
		(end 368.849402 -295.955974)
		(width 0.1143)
		(layer "In4.Cu")
		(net "P5E_CPU0_P3_RX_DN<8>")
	)
	(segment
		(start 369.13185 -293.848536)
		(end 369.16233 -293.830756)
		(width 0.1143)
		(layer "In4.Cu")
		(net "P5E_CPU0_P3_RX_DN<8>")
	)
	(segment
		(start 369.16233 -293.221156)
		(end 369.13185 -293.203376)
		(width 0.1143)
		(layer "In4.Cu")
		(net "P5E_CPU0_P3_RX_DN<8>")
	)
	(segment
		(start 368.693446 -290.791646)
		(end 368.668808 -290.777422)
		(width 0.1143)
		(layer "In4.Cu")
		(net "P5E_CPU0_P3_RX_DN<8>")
	)
	(segment
		(start 368.195098 -289.96513)
		(end 368.192304 -289.963606)
		(width 0.1143)
		(layer "In4.Cu")
		(net "P5E_CPU0_P3_RX_DN<8>")
	)
	(segment
		(start 381.035052 -383.73558)
		(end 381.168656 -383.594864)
		(width 0.14224)
		(layer "In4.Cu")
		(net "P5E_CPU0_P3_RX_DN<8>")
	)
	(segment
		(start 380.958598 -390.548368)
		(end 380.988316 -390.122918)
		(width 0.14224)
		(layer "In4.Cu")
		(net "P5E_CPU0_P3_RX_DN<8>")
	)
	(segment
		(start 380.940056 -388.85114)
		(end 380.969774 -388.425182)
		(width 0.14224)
		(layer "In4.Cu")
		(net "P5E_CPU0_P3_RX_DN<8>")
	)
	(segment
		(start 381.227584 -385.838446)
		(end 381.187198 -384.295904)
		(width 0.14224)
		(layer "In4.Cu")
		(net "P5E_CPU0_P3_RX_DN<8>")
	)
	(segment
		(start 368.803936 -296.462958)
		(end 368.803936 -296.43451)
		(width 0.1143)
		(layer "In4.Cu")
		(net "P5E_CPU0_P3_RX_DN<8>")
	)
	(segment
		(start 379.502416 -312.444384)
		(end 370.82476 -301.87138)
		(width 0.14224)
		(layer "In4.Cu")
		(net "P5E_CPU0_P3_RX_DN<8>")
	)
	(segment
		(start 368.667792 -290.776914)
		(end 368.666268 -290.775898)
		(width 0.1143)
		(layer "In4.Cu")
		(net "P5E_CPU0_P3_RX_DN<8>")
	)
	(segment
		(start 380.649734 -393.22883)
		(end 380.65456 -392.61669)
		(width 0.14224)
		(layer "In4.Cu")
		(net "P5E_CPU0_P3_RX_DN<8>")
	)
	(segment
		(start 368.663728 -290.774628)
		(end 368.662458 -290.773866)
		(width 0.1143)
		(layer "In4.Cu")
		(net "P5E_CPU0_P3_RX_DN<8>")
	)
	(segment
		(start 381.187198 -384.295904)
		(end 381.046228 -384.1623)
		(width 0.14224)
		(layer "In4.Cu")
		(net "P5E_CPU0_P3_RX_DN<8>")
	)
	(segment
		(start 369.092734 -293.871396)
		(end 369.13185 -293.848536)
		(width 0.1143)
		(layer "In4.Cu")
		(net "P5E_CPU0_P3_RX_DN<8>")
	)
	(segment
		(start 380.966726 -393.716764)
		(end 380.966726 -393.545822)
		(width 0.14224)
		(layer "In4.Cu")
		(net "P5E_CPU0_P3_RX_DN<8>")
	)
	(segment
		(start 368.191542 -289.963098)
		(end 368.153442 -289.941)
		(width 0.1143)
		(layer "In4.Cu")
		(net "P5E_CPU0_P3_RX_DN<8>")
	)
	(segment
		(start 381.13843 -381.78359)
		(end 381.722122 -380.374398)
		(width 0.14224)
		(layer "In4.Cu")
		(net "P5E_CPU0_P3_RX_DN<8>")
	)
	(segment
		(start 381.821182 -316.783466)
		(end 379.502416 -312.444384)
		(width 0.14224)
		(layer "In4.Cu")
		(net "P5E_CPU0_P3_RX_DN<8>")
	)
	(segment
		(start 368.662458 -290.773866)
		(end 368.661696 -290.773358)
		(width 0.1143)
		(layer "In4.Cu")
		(net "P5E_CPU0_P3_RX_DN<8>")
	)
	(segment
		(start 369.092734 -292.251384)
		(end 369.13185 -292.228524)
		(width 0.1143)
		(layer "In4.Cu")
		(net "P5E_CPU0_P3_RX_DN<8>")
	)
	(segment
		(start 369.094258 -295.490392)
		(end 369.16233 -295.450768)
		(width 0.1143)
		(layer "In4.Cu")
		(net "P5E_CPU0_P3_RX_DN<8>")
	)
	(segment
		(start 369.794282 -300.329092)
		(end 368.898932 -298.16679)
		(width 0.14224)
		(layer "In4.Cu")
		(net "P5E_CPU0_P3_RX_DN<8>")
	)
	(segment
		(start 381.116078 -388.297928)
		(end 381.199898 -387.101842)
		(width 0.14224)
		(layer "In4.Cu")
		(net "P5E_CPU0_P3_RX_DN<8>")
	)
	(segment
		(start 381.037084 -389.422894)
		(end 381.067056 -388.997698)
		(width 0.14224)
		(layer "In4.Cu")
		(net "P5E_CPU0_P3_RX_DN<8>")
	)
	(segment
		(start 380.969774 -388.425182)
		(end 381.116332 -388.297928)
		(width 0.14224)
		(layer "In4.Cu")
		(net "P5E_CPU0_P3_RX_DN<8>")
	)
	(segment
		(start 368.192304 -289.963606)
		(end 368.191542 -289.963098)
		(width 0.1143)
		(layer "In4.Cu")
		(net "P5E_CPU0_P3_RX_DN<8>")
	)
	(segment
		(start 380.988316 -390.122918)
		(end 380.861062 -389.97636)
		(width 0.14224)
		(layer "In4.Cu")
		(net "P5E_CPU0_P3_RX_DN<8>")
	)
	(arc
		(start 368.37874 -290.2839)
		(mid 368.329551 -290.099949)
		(end 368.195098 -289.96513)
		(width 0.1143)
		(layer "In4.Cu")
		(net "P5E_CPU0_P3_RX_DN<8>")
	)
	(arc
		(start 381.701294 -379.373384)
		(mid 381.608384 -379.184803)
		(end 381.470154 -379.02642)
		(width 0.14224)
		(layer "In4.Cu")
		(net "P5E_CPU0_P3_RX_DN<8>")
	)
	(arc
		(start 368.849402 -295.955974)
		(mid 368.914342 -295.692944)
		(end 369.094258 -295.490392)
		(width 0.1143)
		(layer "In4.Cu")
		(net "P5E_CPU0_P3_RX_DN<8>")
	)
	(arc
		(start 368.65179 -290.767262)
		(mid 368.451732 -290.561473)
		(end 368.37874 -290.2839)
		(width 0.1143)
		(layer "In4.Cu")
		(net "P5E_CPU0_P3_RX_DN<8>")
	)
	(arc
		(start 368.898932 -298.16679)
		(mid 368.827859 -297.932329)
		(end 368.803936 -297.688508)
		(width 0.14224)
		(layer "In4.Cu")
		(net "P5E_CPU0_P3_RX_DN<8>")
	)
	(arc
		(start 369.092734 -291.560504)
		(mid 368.913921 -291.358154)
		(end 368.849402 -291.095938)
		(width 0.1143)
		(layer "In4.Cu")
		(net "P5E_CPU0_P3_RX_DN<8>")
	)
	(arc
		(start 380.148592 -378.026168)
		(mid 380.046718 -377.873608)
		(end 380.010924 -377.693682)
		(width 0.14224)
		(layer "In4.Cu")
		(net "P5E_CPU0_P3_RX_DN<8>")
	)
	(arc
		(start 369.092734 -294.800528)
		(mid 368.849407 -294.335962)
		(end 369.092734 -293.871396)
		(width 0.1143)
		(layer "In4.Cu")
		(net "P5E_CPU0_P3_RX_DN<8>")
	)
	(arc
		(start 381.470154 -379.02642)
		(mid 381.419082 -378.988437)
		(end 381.362458 -378.959364)
		(width 0.14224)
		(layer "In4.Cu")
		(net "P5E_CPU0_P3_RX_DN<8>")
	)
	(arc
		(start 369.092734 -293.180516)
		(mid 368.849407 -292.71595)
		(end 369.092734 -292.251384)
		(width 0.1143)
		(layer "In4.Cu")
		(net "P5E_CPU0_P3_RX_DN<8>")
	)
	(arc
		(start 368.153442 -289.941)
		(mid 368.153061 -289.940746)
		(end 368.15268 -289.940492)
		(width 0.1143)
		(layer "In4.Cu")
		(net "P5E_CPU0_P3_RX_DN<8>")
	)
	(arc
		(start 387.531864 -357.66248)
		(mid 387.562996 -357.559882)
		(end 387.57352 -357.453184)
		(width 0.14224)
		(layer "In4.Cu")
		(net "P5E_CPU0_P3_RX_DN<8>")
	)
	(arc
		(start 368.15268 -289.940492)
		(mid 368.000693 -289.783984)
		(end 367.919254 -289.58159)
		(width 0.1143)
		(layer "In4.Cu")
		(net "P5E_CPU0_P3_RX_DN<8>")
	)
	(arc
		(start 381.199898 -387.101842)
		(mid 381.228929 -386.470477)
		(end 381.227584 -385.838446)
		(width 0.14224)
		(layer "In4.Cu")
		(net "P5E_CPU0_P3_RX_DN<8>")
	)
	(arc
		(start 369.16233 -293.830756)
		(mid 369.319307 -293.525956)
		(end 369.16233 -293.221156)
		(width 0.1143)
		(layer "In4.Cu")
		(net "P5E_CPU0_P3_RX_DN<8>")
	)
	(arc
		(start 380.010924 -376.362214)
		(mid 380.063254 -375.829896)
		(end 380.218442 -375.31802)
		(width 0.14224)
		(layer "In4.Cu")
		(net "P5E_CPU0_P3_RX_DN<8>")
	)
	(arc
		(start 368.849402 -291.095938)
		(mid 368.808147 -290.924967)
		(end 368.693446 -290.791646)
		(width 0.1143)
		(layer "In4.Cu")
		(net "P5E_CPU0_P3_RX_DN<8>")
	)
	(arc
		(start 369.16233 -292.210744)
		(mid 369.319307 -291.905944)
		(end 369.16233 -291.601144)
		(width 0.1143)
		(layer "In4.Cu")
		(net "P5E_CPU0_P3_RX_DN<8>")
	)
	(arc
		(start 381.722122 -379.498352)
		(mid 381.716859 -379.43501)
		(end 381.701294 -379.373384)
		(width 0.14224)
		(layer "In4.Cu")
		(net "P5E_CPU0_P3_RX_DN<8>")
	)
	(arc
		(start 369.16233 -295.450768)
		(mid 369.319307 -295.145968)
		(end 369.16233 -294.841168)
		(width 0.1143)
		(layer "In4.Cu")
		(net "P5E_CPU0_P3_RX_DN<8>")
	)
	(arc
		(start 367.919254 -289.58159)
		(mid 367.917231 -289.57018)
		(end 367.915444 -289.55873)
		(width 0.1143)
		(layer "In4.Cu")
		(net "P5E_CPU0_P3_RX_DN<8>")
	)
	(arc
		(start 381.072136 -378.839222)
		(mid 380.894817 -378.74449)
		(end 380.739396 -378.616972)
		(width 0.14224)
		(layer "In4.Cu")
		(net "P5E_CPU0_P3_RX_DN<8>")
	)
	(segment
		(start 369.888008 -289.209988)
		(end 370.35486 -289.475926)
		(width 0.12954)
		(layer "F.Cu")
		(net "P5E_CPU0_P3_RX_DN<11>")
	)
	(segment
		(start 383.57048 -393.69238)
		(end 384.09118 -393.69238)
		(width 0.127)
		(layer "F.Cu")
		(net "P5E_CPU0_P3_RX_DN<11>")
	)
	(segment
		(start 371.481858 -290.773358)
		(end 371.471952 -290.767262)
		(width 0.1143)
		(layer "In4.Cu")
		(net "P5E_CPU0_P3_RX_DN<11>")
	)
	(segment
		(start 373.203978 -300.342808)
		(end 372.376192 -299.124878)
		(width 0.14224)
		(layer "In4.Cu")
		(net "P5E_CPU0_P3_RX_DN<11>")
	)
	(segment
		(start 384.566668 -393.545822)
		(end 384.249676 -393.22883)
		(width 0.14224)
		(layer "In4.Cu")
		(net "P5E_CPU0_P3_RX_DN<11>")
	)
	(segment
		(start 371.982492 -291.601144)
		(end 371.952012 -291.583364)
		(width 0.1143)
		(layer "In4.Cu")
		(net "P5E_CPU0_P3_RX_DN<11>")
	)
	(segment
		(start 371.624098 -296.422826)
		(end 371.624098 -296.394378)
		(width 0.1143)
		(layer "In4.Cu")
		(net "P5E_CPU0_P3_RX_DN<11>")
	)
	(segment
		(start 387.436106 -383.626614)
		(end 388.315962 -382.309878)
		(width 0.14224)
		(layer "In4.Cu")
		(net "P5E_CPU0_P3_RX_DN<11>")
	)
	(segment
		(start 388.529322 -381.60706)
		(end 388.529322 -379.59792)
		(width 0.14224)
		(layer "In4.Cu")
		(net "P5E_CPU0_P3_RX_DN<11>")
	)
	(segment
		(start 385.337812 -388.693152)
		(end 385.50088 -388.298944)
		(width 0.14224)
		(layer "In4.Cu")
		(net "P5E_CPU0_P3_RX_DN<11>")
	)
	(segment
		(start 384.445002 -393.786868)
		(end 384.566668 -393.716764)
		(width 0.14224)
		(layer "In4.Cu")
		(net "P5E_CPU0_P3_RX_DN<11>")
	)
	(segment
		(start 381.906526 -310.947562)
		(end 373.203978 -300.342808)
		(width 0.14224)
		(layer "In4.Cu")
		(net "P5E_CPU0_P3_RX_DN<11>")
	)
	(segment
		(start 386.818632 -377.527058)
		(end 386.818632 -376.279918)
		(width 0.14224)
		(layer "In4.Cu")
		(net "P5E_CPU0_P3_RX_DN<11>")
	)
	(segment
		(start 385.590034 -387.725412)
		(end 385.769358 -387.65099)
		(width 0.14224)
		(layer "In4.Cu")
		(net "P5E_CPU0_P3_RX_DN<11>")
	)
	(segment
		(start 384.55854 -392.270488)
		(end 384.55854 -391.16762)
		(width 0.14224)
		(layer "In4.Cu")
		(net "P5E_CPU0_P3_RX_DN<11>")
	)
	(segment
		(start 371.952012 -294.823388)
		(end 371.912896 -294.800528)
		(width 0.1143)
		(layer "In4.Cu")
		(net "P5E_CPU0_P3_RX_DN<11>")
	)
	(segment
		(start 384.254756 -392.574272)
		(end 384.55854 -392.270488)
		(width 0.14224)
		(layer "In4.Cu")
		(net "P5E_CPU0_P3_RX_DN<11>")
	)
	(segment
		(start 371.624098 -296.394378)
		(end 371.669818 -296.348658)
		(width 0.1143)
		(layer "In4.Cu")
		(net "P5E_CPU0_P3_RX_DN<11>")
	)
	(segment
		(start 384.566668 -393.716764)
		(end 384.566668 -393.545822)
		(width 0.14224)
		(layer "In4.Cu")
		(net "P5E_CPU0_P3_RX_DN<11>")
	)
	(segment
		(start 371.487954 -290.776914)
		(end 371.48643 -290.775898)
		(width 0.1143)
		(layer "In4.Cu")
		(net "P5E_CPU0_P3_RX_DN<11>")
	)
	(segment
		(start 384.994912 -389.161782)
		(end 385.158234 -388.76732)
		(width 0.14224)
		(layer "In4.Cu")
		(net "P5E_CPU0_P3_RX_DN<11>")
	)
	(segment
		(start 384.444494 -393.787376)
		(end 384.445002 -393.786868)
		(width 0.14224)
		(layer "In4.Cu")
		(net "P5E_CPU0_P3_RX_DN<11>")
	)
	(segment
		(start 386.818632 -376.279918)
		(end 386.906008 -375.569988)
		(width 0.14224)
		(layer "In4.Cu")
		(net "P5E_CPU0_P3_RX_DN<11>")
	)
	(segment
		(start 384.09118 -393.69238)
		(end 384.444494 -393.787376)
		(width 0.14224)
		(layer "In4.Cu")
		(net "P5E_CPU0_P3_RX_DN<11>")
	)
	(segment
		(start 390.37006 -361.72775)
		(end 390.37006 -336.743802)
		(width 0.14224)
		(layer "In4.Cu")
		(net "P5E_CPU0_P3_RX_DN<11>")
	)
	(segment
		(start 387.546596 -378.616972)
		(end 387.074664 -378.14504)
		(width 0.14224)
		(layer "In4.Cu")
		(net "P5E_CPU0_P3_RX_DN<11>")
	)
	(segment
		(start 371.912896 -295.491408)
		(end 371.982492 -295.450768)
		(width 0.1143)
		(layer "In4.Cu")
		(net "P5E_CPU0_P3_RX_DN<11>")
	)
	(segment
		(start 371.513608 -290.791646)
		(end 371.48897 -290.777422)
		(width 0.1143)
		(layer "In4.Cu")
		(net "P5E_CPU0_P3_RX_DN<11>")
	)
	(segment
		(start 371.952012 -292.228524)
		(end 371.982492 -292.210744)
		(width 0.1143)
		(layer "In4.Cu")
		(net "P5E_CPU0_P3_RX_DN<11>")
	)
	(segment
		(start 370.652802 -289.475926)
		(end 370.35486 -289.475926)
		(width 0.1143)
		(layer "In4.Cu")
		(net "P5E_CPU0_P3_RX_DN<11>")
	)
	(segment
		(start 371.952012 -293.848536)
		(end 371.982492 -293.830756)
		(width 0.1143)
		(layer "In4.Cu")
		(net "P5E_CPU0_P3_RX_DN<11>")
	)
	(segment
		(start 371.48262 -290.773866)
		(end 371.481858 -290.773358)
		(width 0.1143)
		(layer "In4.Cu")
		(net "P5E_CPU0_P3_RX_DN<11>")
	)
	(segment
		(start 385.069334 -389.341106)
		(end 384.994912 -389.161782)
		(width 0.14224)
		(layer "In4.Cu")
		(net "P5E_CPU0_P3_RX_DN<11>")
	)
	(segment
		(start 371.952012 -291.583364)
		(end 371.912896 -291.560504)
		(width 0.1143)
		(layer "In4.Cu")
		(net "P5E_CPU0_P3_RX_DN<11>")
	)
	(segment
		(start 385.932426 -387.256782)
		(end 385.858258 -387.077712)
		(width 0.14224)
		(layer "In4.Cu")
		(net "P5E_CPU0_P3_RX_DN<11>")
	)
	(segment
		(start 390.37006 -336.743802)
		(end 388.92353 -328.692764)
		(width 0.14224)
		(layer "In4.Cu")
		(net "P5E_CPU0_P3_RX_DN<11>")
	)
	(segment
		(start 371.952012 -293.203376)
		(end 371.912896 -293.180516)
		(width 0.1143)
		(layer "In4.Cu")
		(net "P5E_CPU0_P3_RX_DN<11>")
	)
	(segment
		(start 385.858258 -387.077712)
		(end 386.02158 -386.68325)
		(width 0.14224)
		(layer "In4.Cu")
		(net "P5E_CPU0_P3_RX_DN<11>")
	)
	(segment
		(start 371.011704 -289.963098)
		(end 370.973604 -289.941)
		(width 0.1143)
		(layer "In4.Cu")
		(net "P5E_CPU0_P3_RX_DN<11>")
	)
	(segment
		(start 388.19836 -378.9934)
		(end 387.965442 -378.89688)
		(width 0.14224)
		(layer "In4.Cu")
		(net "P5E_CPU0_P3_RX_DN<11>")
	)
	(segment
		(start 371.48643 -290.775898)
		(end 371.48389 -290.774628)
		(width 0.1143)
		(layer "In4.Cu")
		(net "P5E_CPU0_P3_RX_DN<11>")
	)
	(segment
		(start 371.48897 -290.777422)
		(end 371.487954 -290.776914)
		(width 0.1143)
		(layer "In4.Cu")
		(net "P5E_CPU0_P3_RX_DN<11>")
	)
	(segment
		(start 386.200904 -386.608828)
		(end 387.436106 -383.626614)
		(width 0.14224)
		(layer "In4.Cu")
		(net "P5E_CPU0_P3_RX_DN<11>")
	)
	(segment
		(start 386.906008 -375.569988)
		(end 390.36625 -361.758738)
		(width 0.14224)
		(layer "In4.Cu")
		(net "P5E_CPU0_P3_RX_DN<11>")
	)
	(segment
		(start 384.342386 -315.504068)
		(end 381.906526 -310.947562)
		(width 0.14224)
		(layer "In4.Cu")
		(net "P5E_CPU0_P3_RX_DN<11>")
	)
	(segment
		(start 371.012466 -289.963606)
		(end 371.011704 -289.963098)
		(width 0.1143)
		(layer "In4.Cu")
		(net "P5E_CPU0_P3_RX_DN<11>")
	)
	(segment
		(start 371.982492 -293.221156)
		(end 371.952012 -293.203376)
		(width 0.1143)
		(layer "In4.Cu")
		(net "P5E_CPU0_P3_RX_DN<11>")
	)
	(segment
		(start 385.158234 -388.76732)
		(end 385.337812 -388.693152)
		(width 0.14224)
		(layer "In4.Cu")
		(net "P5E_CPU0_P3_RX_DN<11>")
	)
	(segment
		(start 371.912896 -292.251384)
		(end 371.952012 -292.228524)
		(width 0.1143)
		(layer "In4.Cu")
		(net "P5E_CPU0_P3_RX_DN<11>")
	)
	(segment
		(start 370.735606 -289.55873)
		(end 370.652802 -289.475926)
		(width 0.1143)
		(layer "In4.Cu")
		(net "P5E_CPU0_P3_RX_DN<11>")
	)
	(segment
		(start 385.50088 -388.298944)
		(end 385.426712 -388.119874)
		(width 0.14224)
		(layer "In4.Cu")
		(net "P5E_CPU0_P3_RX_DN<11>")
	)
	(segment
		(start 384.249676 -393.22883)
		(end 384.254756 -392.574272)
		(width 0.14224)
		(layer "In4.Cu")
		(net "P5E_CPU0_P3_RX_DN<11>")
	)
	(segment
		(start 372.376192 -299.124878)
		(end 371.655086 -297.383708)
		(width 0.14224)
		(layer "In4.Cu")
		(net "P5E_CPU0_P3_RX_DN<11>")
	)
	(segment
		(start 385.769358 -387.65099)
		(end 385.932426 -387.256782)
		(width 0.14224)
		(layer "In4.Cu")
		(net "P5E_CPU0_P3_RX_DN<11>")
	)
	(segment
		(start 371.669818 -296.348658)
		(end 371.669818 -295.955974)
		(width 0.1143)
		(layer "In4.Cu")
		(net "P5E_CPU0_P3_RX_DN<11>")
	)
	(segment
		(start 384.785362 -390.026652)
		(end 385.069334 -389.341106)
		(width 0.14224)
		(layer "In4.Cu")
		(net "P5E_CPU0_P3_RX_DN<11>")
	)
	(segment
		(start 385.426712 -388.119874)
		(end 385.590034 -387.725412)
		(width 0.14224)
		(layer "In4.Cu")
		(net "P5E_CPU0_P3_RX_DN<11>")
	)
	(segment
		(start 371.912896 -293.871396)
		(end 371.952012 -293.848536)
		(width 0.1143)
		(layer "In4.Cu")
		(net "P5E_CPU0_P3_RX_DN<11>")
	)
	(segment
		(start 371.624098 -297.22699)
		(end 371.624098 -296.422826)
		(width 0.14224)
		(layer "In4.Cu")
		(net "P5E_CPU0_P3_RX_DN<11>")
	)
	(segment
		(start 388.92353 -328.692764)
		(end 384.342386 -315.504068)
		(width 0.14224)
		(layer "In4.Cu")
		(net "P5E_CPU0_P3_RX_DN<11>")
	)
	(segment
		(start 371.48389 -290.774628)
		(end 371.48262 -290.773866)
		(width 0.1143)
		(layer "In4.Cu")
		(net "P5E_CPU0_P3_RX_DN<11>")
	)
	(segment
		(start 386.02158 -386.68325)
		(end 386.200904 -386.608828)
		(width 0.14224)
		(layer "In4.Cu")
		(net "P5E_CPU0_P3_RX_DN<11>")
	)
	(segment
		(start 371.982492 -294.841168)
		(end 371.952012 -294.823388)
		(width 0.1143)
		(layer "In4.Cu")
		(net "P5E_CPU0_P3_RX_DN<11>")
	)
	(segment
		(start 371.01526 -289.96513)
		(end 371.012466 -289.963606)
		(width 0.1143)
		(layer "In4.Cu")
		(net "P5E_CPU0_P3_RX_DN<11>")
	)
	(arc
		(start 370.973604 -289.941)
		(mid 370.973223 -289.940746)
		(end 370.972842 -289.940492)
		(width 0.1143)
		(layer "In4.Cu")
		(net "P5E_CPU0_P3_RX_DN<11>")
	)
	(arc
		(start 387.074664 -378.14504)
		(mid 386.88516 -377.861522)
		(end 386.818632 -377.527058)
		(width 0.14224)
		(layer "In4.Cu")
		(net "P5E_CPU0_P3_RX_DN<11>")
	)
	(arc
		(start 371.669818 -295.955974)
		(mid 371.734192 -295.69377)
		(end 371.912896 -295.491408)
		(width 0.1143)
		(layer "In4.Cu")
		(net "P5E_CPU0_P3_RX_DN<11>")
	)
	(arc
		(start 371.655086 -297.383708)
		(mid 371.631883 -297.306874)
		(end 371.624098 -297.22699)
		(width 0.14224)
		(layer "In4.Cu")
		(net "P5E_CPU0_P3_RX_DN<11>")
	)
	(arc
		(start 370.972842 -289.940492)
		(mid 370.820855 -289.783984)
		(end 370.739416 -289.58159)
		(width 0.1143)
		(layer "In4.Cu")
		(net "P5E_CPU0_P3_RX_DN<11>")
	)
	(arc
		(start 370.739416 -289.58159)
		(mid 370.737393 -289.57018)
		(end 370.735606 -289.55873)
		(width 0.1143)
		(layer "In4.Cu")
		(net "P5E_CPU0_P3_RX_DN<11>")
	)
	(arc
		(start 371.669564 -291.095938)
		(mid 371.628309 -290.924967)
		(end 371.513608 -290.791646)
		(width 0.1143)
		(layer "In4.Cu")
		(net "P5E_CPU0_P3_RX_DN<11>")
	)
	(arc
		(start 371.912896 -291.560504)
		(mid 371.734083 -291.358154)
		(end 371.669564 -291.095938)
		(width 0.1143)
		(layer "In4.Cu")
		(net "P5E_CPU0_P3_RX_DN<11>")
	)
	(arc
		(start 384.55854 -391.16762)
		(mid 384.615777 -390.58597)
		(end 384.785362 -390.026652)
		(width 0.14224)
		(layer "In4.Cu")
		(net "P5E_CPU0_P3_RX_DN<11>")
	)
	(arc
		(start 388.374128 -379.112018)
		(mid 388.292184 -379.043912)
		(end 388.19836 -378.9934)
		(width 0.14224)
		(layer "In4.Cu")
		(net "P5E_CPU0_P3_RX_DN<11>")
	)
	(arc
		(start 371.982492 -292.210744)
		(mid 372.139469 -291.905944)
		(end 371.982492 -291.601144)
		(width 0.1143)
		(layer "In4.Cu")
		(net "P5E_CPU0_P3_RX_DN<11>")
	)
	(arc
		(start 388.315962 -382.309878)
		(mid 388.474754 -381.974295)
		(end 388.529322 -381.60706)
		(width 0.14224)
		(layer "In4.Cu")
		(net "P5E_CPU0_P3_RX_DN<11>")
	)
	(arc
		(start 371.982492 -293.830756)
		(mid 372.139469 -293.525956)
		(end 371.982492 -293.221156)
		(width 0.1143)
		(layer "In4.Cu")
		(net "P5E_CPU0_P3_RX_DN<11>")
	)
	(arc
		(start 371.912896 -293.180516)
		(mid 371.669569 -292.71595)
		(end 371.912896 -292.251384)
		(width 0.1143)
		(layer "In4.Cu")
		(net "P5E_CPU0_P3_RX_DN<11>")
	)
	(arc
		(start 388.529322 -379.59792)
		(mid 388.525712 -379.534533)
		(end 388.515098 -379.471936)
		(width 0.14224)
		(layer "In4.Cu")
		(net "P5E_CPU0_P3_RX_DN<11>")
	)
	(arc
		(start 390.36625 -361.758738)
		(mid 390.369108 -361.743361)
		(end 390.37006 -361.72775)
		(width 0.14224)
		(layer "In4.Cu")
		(net "P5E_CPU0_P3_RX_DN<11>")
	)
	(arc
		(start 388.515098 -379.471936)
		(mid 388.496671 -379.396387)
		(end 388.475474 -379.321568)
		(width 0.14224)
		(layer "In4.Cu")
		(net "P5E_CPU0_P3_RX_DN<11>")
	)
	(arc
		(start 388.475474 -379.321568)
		(mid 388.459233 -379.270172)
		(end 388.441692 -379.219206)
		(width 0.14224)
		(layer "In4.Cu")
		(net "P5E_CPU0_P3_RX_DN<11>")
	)
	(arc
		(start 388.441692 -379.219206)
		(mid 388.413711 -379.161954)
		(end 388.374128 -379.112018)
		(width 0.14224)
		(layer "In4.Cu")
		(net "P5E_CPU0_P3_RX_DN<11>")
	)
	(arc
		(start 371.982492 -295.450768)
		(mid 372.139469 -295.145968)
		(end 371.982492 -294.841168)
		(width 0.1143)
		(layer "In4.Cu")
		(net "P5E_CPU0_P3_RX_DN<11>")
	)
	(arc
		(start 387.965442 -378.89688)
		(mid 387.742264 -378.77751)
		(end 387.546596 -378.616972)
		(width 0.14224)
		(layer "In4.Cu")
		(net "P5E_CPU0_P3_RX_DN<11>")
	)
	(arc
		(start 371.471952 -290.767262)
		(mid 371.271894 -290.561473)
		(end 371.198902 -290.2839)
		(width 0.1143)
		(layer "In4.Cu")
		(net "P5E_CPU0_P3_RX_DN<11>")
	)
	(arc
		(start 371.912896 -294.800528)
		(mid 371.669569 -294.335962)
		(end 371.912896 -293.871396)
		(width 0.1143)
		(layer "In4.Cu")
		(net "P5E_CPU0_P3_RX_DN<11>")
	)
	(arc
		(start 371.198902 -290.2839)
		(mid 371.149713 -290.099949)
		(end 371.01526 -289.96513)
		(width 0.1143)
		(layer "In4.Cu")
		(net "P5E_CPU0_P3_RX_DN<11>")
	)
	(segment
		(start 369.888008 -290.83)
		(end 370.35486 -291.095938)
		(width 0.12954)
		(layer "F.Cu")
		(net "P5E_CPU0_P3_RX_DN<10>")
	)
	(segment
		(start 382.370584 -393.69238)
		(end 382.891284 -393.69238)
		(width 0.127)
		(layer "F.Cu")
		(net "P5E_CPU0_P3_RX_DN<10>")
	)
	(segment
		(start 385.770882 -372.92153)
		(end 389.432292 -360.851704)
		(width 0.14224)
		(layer "In4.Cu")
		(net "P5E_CPU0_P3_RX_DN<10>")
	)
	(segment
		(start 385.770628 -372.922038)
		(end 385.770882 -372.92153)
		(width 0.14224)
		(layer "In4.Cu")
		(net "P5E_CPU0_P3_RX_DN<10>")
	)
	(segment
		(start 388.728966 -332.889098)
		(end 388.020052 -328.943208)
		(width 0.14224)
		(layer "In4.Cu")
		(net "P5E_CPU0_P3_RX_DN<10>")
	)
	(segment
		(start 386.887212 -325.682864)
		(end 385.755134 -322.423282)
		(width 0.14224)
		(layer "In4.Cu")
		(net "P5E_CPU0_P3_RX_DN<10>")
	)
	(segment
		(start 371.011958 -293.203376)
		(end 371.010942 -293.202868)
		(width 0.1143)
		(layer "In4.Cu")
		(net "P5E_CPU0_P3_RX_DN<10>")
	)
	(segment
		(start 370.684044 -296.460926)
		(end 370.729764 -296.415206)
		(width 0.1143)
		(layer "In4.Cu")
		(net "P5E_CPU0_P3_RX_DN<10>")
	)
	(segment
		(start 383.44983 -384.29692)
		(end 383.309114 -384.163316)
		(width 0.14224)
		(layer "In4.Cu")
		(net "P5E_CPU0_P3_RX_DN<10>")
	)
	(segment
		(start 371.02415 -293.210234)
		(end 371.01272 -293.20363)
		(width 0.1143)
		(layer "In4.Cu")
		(net "P5E_CPU0_P3_RX_DN<10>")
	)
	(segment
		(start 384.545078 -379.040644)
		(end 385.748276 -372.995698)
		(width 0.14224)
		(layer "In4.Cu")
		(net "P5E_CPU0_P3_RX_DN<10>")
	)
	(segment
		(start 370.684044 -297.383454)
		(end 370.684044 -296.489374)
		(width 0.14224)
		(layer "In4.Cu")
		(net "P5E_CPU0_P3_RX_DN<10>")
	)
	(segment
		(start 381.111252 -311.453276)
		(end 372.361206 -300.791372)
		(width 0.14224)
		(layer "In4.Cu")
		(net "P5E_CPU0_P3_RX_DN<10>")
	)
	(segment
		(start 370.735606 -291.178742)
		(end 370.652802 -291.095938)
		(width 0.1143)
		(layer "In4.Cu")
		(net "P5E_CPU0_P3_RX_DN<10>")
	)
	(segment
		(start 383.338832 -385.290822)
		(end 383.327656 -384.864102)
		(width 0.14224)
		(layer "In4.Cu")
		(net "P5E_CPU0_P3_RX_DN<10>")
	)
	(segment
		(start 371.010942 -293.202868)
		(end 370.972842 -293.180516)
		(width 0.1143)
		(layer "In4.Cu")
		(net "P5E_CPU0_P3_RX_DN<10>")
	)
	(segment
		(start 370.972842 -292.251384)
		(end 371.012466 -292.22827)
		(width 0.1143)
		(layer "In4.Cu")
		(net "P5E_CPU0_P3_RX_DN<10>")
	)
	(segment
		(start 370.972842 -293.871396)
		(end 371.023388 -293.841932)
		(width 0.1143)
		(layer "In4.Cu")
		(net "P5E_CPU0_P3_RX_DN<10>")
	)
	(segment
		(start 371.02415 -294.830246)
		(end 371.01272 -294.823642)
		(width 0.1143)
		(layer "In4.Cu")
		(net "P5E_CPU0_P3_RX_DN<10>")
	)
	(segment
		(start 370.973858 -295.490646)
		(end 371.010434 -295.469564)
		(width 0.1143)
		(layer "In4.Cu")
		(net "P5E_CPU0_P3_RX_DN<10>")
	)
	(segment
		(start 383.48031 -385.438904)
		(end 383.479802 -385.424426)
		(width 0.14224)
		(layer "In4.Cu")
		(net "P5E_CPU0_P3_RX_DN<10>")
	)
	(segment
		(start 383.480564 -385.440682)
		(end 383.48031 -385.438904)
		(width 0.14224)
		(layer "In4.Cu")
		(net "P5E_CPU0_P3_RX_DN<10>")
	)
	(segment
		(start 388.020052 -328.943208)
		(end 386.887466 -325.682864)
		(width 0.14224)
		(layer "In4.Cu")
		(net "P5E_CPU0_P3_RX_DN<10>")
	)
	(segment
		(start 383.27203 -388.613396)
		(end 383.292858 -388.18693)
		(width 0.14224)
		(layer "In4.Cu")
		(net "P5E_CPU0_P3_RX_DN<10>")
	)
	(segment
		(start 383.402332 -388.75716)
		(end 383.27203 -388.613396)
		(width 0.14224)
		(layer "In4.Cu")
		(net "P5E_CPU0_P3_RX_DN<10>")
	)
	(segment
		(start 383.309114 -384.163316)
		(end 383.297938 -383.736596)
		(width 0.14224)
		(layer "In4.Cu")
		(net "P5E_CPU0_P3_RX_DN<10>")
	)
	(segment
		(start 382.891284 -393.69238)
		(end 383.244598 -393.787376)
		(width 0.14224)
		(layer "In4.Cu")
		(net "P5E_CPU0_P3_RX_DN<10>")
	)
	(segment
		(start 370.73586 -291.178742)
		(end 370.735606 -291.178742)
		(width 0.1143)
		(layer "In4.Cu")
		(net "P5E_CPU0_P3_RX_DN<10>")
	)
	(segment
		(start 370.684044 -296.489374)
		(end 370.684044 -296.460926)
		(width 0.1143)
		(layer "In4.Cu")
		(net "P5E_CPU0_P3_RX_DN<10>")
	)
	(segment
		(start 385.748276 -372.995698)
		(end 385.770628 -372.922038)
		(width 0.14224)
		(layer "In4.Cu")
		(net "P5E_CPU0_P3_RX_DN<10>")
	)
	(segment
		(start 383.479802 -385.424426)
		(end 383.338832 -385.290822)
		(width 0.14224)
		(layer "In4.Cu")
		(net "P5E_CPU0_P3_RX_DN<10>")
	)
	(segment
		(start 385.755134 -322.423282)
		(end 385.755134 -322.423536)
		(width 0.14224)
		(layer "In4.Cu")
		(net "P5E_CPU0_P3_RX_DN<10>")
	)
	(segment
		(start 383.366772 -393.545822)
		(end 383.04978 -393.22883)
		(width 0.14224)
		(layer "In4.Cu")
		(net "P5E_CPU0_P3_RX_DN<10>")
	)
	(segment
		(start 383.353056 -389.763)
		(end 383.402332 -388.75716)
		(width 0.14224)
		(layer "In4.Cu")
		(net "P5E_CPU0_P3_RX_DN<10>")
	)
	(segment
		(start 371.010434 -295.469564)
		(end 371.011958 -295.468548)
		(width 0.1143)
		(layer "In4.Cu")
		(net "P5E_CPU0_P3_RX_DN<10>")
	)
	(segment
		(start 389.43788 -336.834988)
		(end 388.728712 -332.889098)
		(width 0.14224)
		(layer "In4.Cu")
		(net "P5E_CPU0_P3_RX_DN<10>")
	)
	(segment
		(start 383.49047 -315.904118)
		(end 381.111252 -311.453276)
		(width 0.14224)
		(layer "In4.Cu")
		(net "P5E_CPU0_P3_RX_DN<10>")
	)
	(segment
		(start 383.245106 -393.786868)
		(end 383.366772 -393.716764)
		(width 0.14224)
		(layer "In4.Cu")
		(net "P5E_CPU0_P3_RX_DN<10>")
	)
	(segment
		(start 370.652802 -291.095938)
		(end 370.35486 -291.095938)
		(width 0.1143)
		(layer "In4.Cu")
		(net "P5E_CPU0_P3_RX_DN<10>")
	)
	(segment
		(start 383.366772 -393.716764)
		(end 383.366772 -393.545822)
		(width 0.14224)
		(layer "In4.Cu")
		(net "P5E_CPU0_P3_RX_DN<10>")
	)
	(segment
		(start 383.04978 -393.22883)
		(end 383.055622 -392.506708)
		(width 0.14224)
		(layer "In4.Cu")
		(net "P5E_CPU0_P3_RX_DN<10>")
	)
	(segment
		(start 371.011958 -295.468548)
		(end 371.023388 -295.461944)
		(width 0.1143)
		(layer "In4.Cu")
		(net "P5E_CPU0_P3_RX_DN<10>")
	)
	(segment
		(start 370.729764 -296.415206)
		(end 370.729764 -295.955974)
		(width 0.1143)
		(layer "In4.Cu")
		(net "P5E_CPU0_P3_RX_DN<10>")
	)
	(segment
		(start 386.887466 -325.682864)
		(end 386.887212 -325.682864)
		(width 0.14224)
		(layer "In4.Cu")
		(net "P5E_CPU0_P3_RX_DN<10>")
	)
	(segment
		(start 383.297938 -383.736596)
		(end 383.431288 -383.59588)
		(width 0.14224)
		(layer "In4.Cu")
		(net "P5E_CPU0_P3_RX_DN<10>")
	)
	(segment
		(start 389.43788 -360.814874)
		(end 389.43788 -336.834988)
		(width 0.14224)
		(layer "In4.Cu")
		(net "P5E_CPU0_P3_RX_DN<10>")
	)
	(segment
		(start 383.534666 -381.620776)
		(end 384.508248 -379.161802)
		(width 0.14224)
		(layer "In4.Cu")
		(net "P5E_CPU0_P3_RX_DN<10>")
	)
	(segment
		(start 383.327656 -384.864102)
		(end 383.461006 -384.723386)
		(width 0.14224)
		(layer "In4.Cu")
		(net "P5E_CPU0_P3_RX_DN<10>")
	)
	(segment
		(start 383.509774 -386.571236)
		(end 383.48031 -385.440682)
		(width 0.14224)
		(layer "In4.Cu")
		(net "P5E_CPU0_P3_RX_DN<10>")
	)
	(segment
		(start 371.01272 -293.20363)
		(end 371.011958 -293.203376)
		(width 0.1143)
		(layer "In4.Cu")
		(net "P5E_CPU0_P3_RX_DN<10>")
	)
	(segment
		(start 388.728712 -332.889098)
		(end 388.728966 -332.889098)
		(width 0.14224)
		(layer "In4.Cu")
		(net "P5E_CPU0_P3_RX_DN<10>")
	)
	(segment
		(start 383.436876 -388.056628)
		(end 383.509774 -386.571236)
		(width 0.14224)
		(layer "In4.Cu")
		(net "P5E_CPU0_P3_RX_DN<10>")
	)
	(segment
		(start 371.01272 -294.823642)
		(end 371.011958 -294.823388)
		(width 0.1143)
		(layer "In4.Cu")
		(net "P5E_CPU0_P3_RX_DN<10>")
	)
	(segment
		(start 383.292858 -388.18693)
		(end 383.436876 -388.056628)
		(width 0.14224)
		(layer "In4.Cu")
		(net "P5E_CPU0_P3_RX_DN<10>")
	)
	(segment
		(start 371.012466 -291.583364)
		(end 370.973604 -291.561012)
		(width 0.1143)
		(layer "In4.Cu")
		(net "P5E_CPU0_P3_RX_DN<10>")
	)
	(segment
		(start 383.055622 -392.506708)
		(end 383.353056 -392.208766)
		(width 0.14224)
		(layer "In4.Cu")
		(net "P5E_CPU0_P3_RX_DN<10>")
	)
	(segment
		(start 383.431288 -383.59588)
		(end 383.39903 -382.358138)
		(width 0.14224)
		(layer "In4.Cu")
		(net "P5E_CPU0_P3_RX_DN<10>")
	)
	(segment
		(start 383.244598 -393.787376)
		(end 383.245106 -393.786868)
		(width 0.14224)
		(layer "In4.Cu")
		(net "P5E_CPU0_P3_RX_DN<10>")
	)
	(segment
		(start 383.353056 -392.208766)
		(end 383.353056 -389.763)
		(width 0.14224)
		(layer "In4.Cu")
		(net "P5E_CPU0_P3_RX_DN<10>")
	)
	(segment
		(start 383.48031 -385.440682)
		(end 383.480564 -385.440682)
		(width 0.14224)
		(layer "In4.Cu")
		(net "P5E_CPU0_P3_RX_DN<10>")
	)
	(segment
		(start 383.461006 -384.723386)
		(end 383.44983 -384.29692)
		(width 0.14224)
		(layer "In4.Cu")
		(net "P5E_CPU0_P3_RX_DN<10>")
	)
	(segment
		(start 371.011958 -294.823388)
		(end 371.010942 -294.82288)
		(width 0.1143)
		(layer "In4.Cu")
		(net "P5E_CPU0_P3_RX_DN<10>")
	)
	(segment
		(start 385.755134 -322.423536)
		(end 383.49047 -315.904118)
		(width 0.14224)
		(layer "In4.Cu")
		(net "P5E_CPU0_P3_RX_DN<10>")
	)
	(segment
		(start 371.010942 -294.82288)
		(end 370.972842 -294.800528)
		(width 0.1143)
		(layer "In4.Cu")
		(net "P5E_CPU0_P3_RX_DN<10>")
	)
	(segment
		(start 371.5512 -299.579284)
		(end 370.722652 -297.578272)
		(width 0.14224)
		(layer "In4.Cu")
		(net "P5E_CPU0_P3_RX_DN<10>")
	)
	(segment
		(start 372.361206 -300.791372)
		(end 371.5512 -299.579284)
		(width 0.14224)
		(layer "In4.Cu")
		(net "P5E_CPU0_P3_RX_DN<10>")
	)
	(arc
		(start 370.972842 -293.180516)
		(mid 370.729515 -292.71595)
		(end 370.972842 -292.251384)
		(width 0.1143)
		(layer "In4.Cu")
		(net "P5E_CPU0_P3_RX_DN<10>")
	)
	(arc
		(start 384.508248 -379.161802)
		(mid 384.52965 -379.102131)
		(end 384.545078 -379.040644)
		(width 0.14224)
		(layer "In4.Cu")
		(net "P5E_CPU0_P3_RX_DN<10>")
	)
	(arc
		(start 370.729764 -295.955974)
		(mid 370.794486 -295.693235)
		(end 370.973858 -295.490646)
		(width 0.1143)
		(layer "In4.Cu")
		(net "P5E_CPU0_P3_RX_DN<10>")
	)
	(arc
		(start 370.972842 -294.800528)
		(mid 370.729515 -294.335962)
		(end 370.972842 -293.871396)
		(width 0.1143)
		(layer "In4.Cu")
		(net "P5E_CPU0_P3_RX_DN<10>")
	)
	(arc
		(start 370.973604 -291.561012)
		(mid 370.815048 -291.394564)
		(end 370.73586 -291.178742)
		(width 0.1143)
		(layer "In4.Cu")
		(net "P5E_CPU0_P3_RX_DN<10>")
	)
	(arc
		(start 371.023388 -293.841932)
		(mid 371.198338 -293.526346)
		(end 371.02415 -293.210234)
		(width 0.1143)
		(layer "In4.Cu")
		(net "P5E_CPU0_P3_RX_DN<10>")
	)
	(arc
		(start 371.023388 -295.461944)
		(mid 371.198338 -295.146358)
		(end 371.02415 -294.830246)
		(width 0.1143)
		(layer "In4.Cu")
		(net "P5E_CPU0_P3_RX_DN<10>")
	)
	(arc
		(start 370.722652 -297.578272)
		(mid 370.693734 -297.482766)
		(end 370.684044 -297.383454)
		(width 0.14224)
		(layer "In4.Cu")
		(net "P5E_CPU0_P3_RX_DN<10>")
	)
	(arc
		(start 371.012466 -292.22827)
		(mid 371.197884 -291.90588)
		(end 371.012466 -291.583364)
		(width 0.1143)
		(layer "In4.Cu")
		(net "P5E_CPU0_P3_RX_DN<10>")
	)
	(arc
		(start 383.39903 -382.358138)
		(mid 383.427871 -381.982289)
		(end 383.534666 -381.620776)
		(width 0.14224)
		(layer "In4.Cu")
		(net "P5E_CPU0_P3_RX_DN<10>")
	)
	(arc
		(start 389.432292 -360.851704)
		(mid 389.436438 -360.833494)
		(end 389.43788 -360.814874)
		(width 0.14224)
		(layer "In4.Cu")
		(net "P5E_CPU0_P3_RX_DN<10>")
	)
	(segment
		(start 307.728874 -34.001964)
		(end 306.941474 -34.001964)
		(width 0.508)
		(layer "F.Cu")
		(net "P3V_BAT_R")
	)
	(segment
		(start 306.154074 -34.001964)
		(end 306.941474 -34.001964)
		(width 0.508)
		(layer "F.Cu")
		(net "P3V_BAT_R")
	)
	(segment
		(start 148.944076 -23.684992)
		(end 148.944076 -24.370792)
		(width 0.508)
		(layer "F.Cu")
		(net "P3V_BAT_R")
	)
	(via
		(at 148.944076 -24.370792)
		(size 0.508)
		(drill 0.254)
		(layers "F.Cu" "B.Cu")
		(net "P3V_BAT_R")
	)
	(via
		(at 216.967054 -36.337748)
		(size 0.508)
		(drill 0.254)
		(layers "F.Cu" "B.Cu")
		(net "P3V_BAT_R")
	)
	(via
		(at 306.941474 -34.001964)
		(size 0.508)
		(drill 0.254)
		(layers "F.Cu" "B.Cu")
		(net "P3V_BAT_R")
	)
	(segment
		(start 217.2716 -45.9994)
		(end 217.2716 -36.642294)
		(width 0.508)
		(layer "In2.Cu")
		(net "P3V_BAT_R")
	)
	(segment
		(start 268.33576 -63.26124)
		(end 239.79632 -63.26124)
		(width 0.508)
		(layer "In2.Cu")
		(net "P3V_BAT_R")
	)
	(segment
		(start 217.2716 -36.642294)
		(end 216.967054 -36.337748)
		(width 0.508)
		(layer "In2.Cu")
		(net "P3V_BAT_R")
	)
	(segment
		(start 232.02138 -60.26912)
		(end 229.5144 -60.26912)
		(width 0.508)
		(layer "In2.Cu")
		(net "P3V_BAT_R")
	)
	(segment
		(start 297.595036 -34.001964)
		(end 268.33576 -63.26124)
		(width 0.508)
		(layer "In2.Cu")
		(net "P3V_BAT_R")
	)
	(segment
		(start 233.44886 -58.84164)
		(end 232.02138 -60.26912)
		(width 0.508)
		(layer "In2.Cu")
		(net "P3V_BAT_R")
	)
	(segment
		(start 219.5068 -48.2346)
		(end 217.2716 -45.9994)
		(width 0.508)
		(layer "In2.Cu")
		(net "P3V_BAT_R")
	)
	(segment
		(start 239.79632 -63.26124)
		(end 235.37672 -58.84164)
		(width 0.508)
		(layer "In2.Cu")
		(net "P3V_BAT_R")
	)
	(segment
		(start 219.5068 -50.26152)
		(end 219.5068 -48.2346)
		(width 0.508)
		(layer "In2.Cu")
		(net "P3V_BAT_R")
	)
	(segment
		(start 235.37672 -58.84164)
		(end 233.44886 -58.84164)
		(width 0.508)
		(layer "In2.Cu")
		(net "P3V_BAT_R")
	)
	(segment
		(start 229.5144 -60.26912)
		(end 219.5068 -50.26152)
		(width 0.508)
		(layer "In2.Cu")
		(net "P3V_BAT_R")
	)
	(segment
		(start 306.941474 -34.001964)
		(end 297.595036 -34.001964)
		(width 0.508)
		(layer "In2.Cu")
		(net "P3V_BAT_R")
	)
	(segment
		(start 178.769518 -38.012878)
		(end 168.89222 -28.13558)
		(width 0.508)
		(layer "In15.Cu")
		(net "P3V_BAT_R")
	)
	(segment
		(start 194.437 -37.211)
		(end 193.267584 -38.380416)
		(width 0.508)
		(layer "In15.Cu")
		(net "P3V_BAT_R")
	)
	(segment
		(start 168.89222 -28.13558)
		(end 163.40582 -28.13558)
		(width 0.508)
		(layer "In15.Cu")
		(net "P3V_BAT_R")
	)
	(segment
		(start 216.967054 -36.337748)
		(end 214.134192 -36.337748)
		(width 0.508)
		(layer "In15.Cu")
		(net "P3V_BAT_R")
	)
	(segment
		(start 193.267584 -38.380416)
		(end 186.268868 -38.380416)
		(width 0.508)
		(layer "In15.Cu")
		(net "P3V_BAT_R")
	)
	(segment
		(start 214.134192 -36.337748)
		(end 210.7057 -39.76624)
		(width 0.508)
		(layer "In15.Cu")
		(net "P3V_BAT_R")
	)
	(segment
		(start 196.26326 -37.211)
		(end 194.437 -37.211)
		(width 0.508)
		(layer "In15.Cu")
		(net "P3V_BAT_R")
	)
	(segment
		(start 149.44598 -23.13178)
		(end 148.944076 -23.633684)
		(width 0.508)
		(layer "In15.Cu")
		(net "P3V_BAT_R")
	)
	(segment
		(start 210.7057 -39.76624)
		(end 198.8185 -39.76624)
		(width 0.508)
		(layer "In15.Cu")
		(net "P3V_BAT_R")
	)
	(segment
		(start 158.40202 -23.13178)
		(end 149.44598 -23.13178)
		(width 0.508)
		(layer "In15.Cu")
		(net "P3V_BAT_R")
	)
	(segment
		(start 163.40582 -28.13558)
		(end 158.40202 -23.13178)
		(width 0.508)
		(layer "In15.Cu")
		(net "P3V_BAT_R")
	)
	(segment
		(start 148.944076 -23.633684)
		(end 148.944076 -24.370792)
		(width 0.508)
		(layer "In15.Cu")
		(net "P3V_BAT_R")
	)
	(segment
		(start 185.90133 -38.012878)
		(end 178.769518 -38.012878)
		(width 0.508)
		(layer "In15.Cu")
		(net "P3V_BAT_R")
	)
	(segment
		(start 198.8185 -39.76624)
		(end 196.26326 -37.211)
		(width 0.508)
		(layer "In15.Cu")
		(net "P3V_BAT_R")
	)
	(segment
		(start 186.268868 -38.380416)
		(end 185.90133 -38.012878)
		(width 0.508)
		(layer "In15.Cu")
		(net "P3V_BAT_R")
	)
	(segment
		(start 304.134774 -34.001964)
		(end 305.353974 -34.001964)
		(width 0.508)
		(layer "F.Cu")
		(net "P3V_BAT")
	)
	(segment
		(start 304.134774 -34.001964)
		(end 293.720012 -34.001964)
		(width 0.508)
		(layer "F.Cu")
		(net "P3V_BAT")
	)
	(via
		(at 304.134774 -34.001964)
		(size 0.762)
		(drill 0.381)
		(layers "F.Cu" "B.Cu")
		(net "P3V_BAT")
	)
	(segment
		(start 309.329074 -33.351978)
		(end 310.116474 -33.351978)
		(width 0.4572)
		(layer "F.Cu")
		(net "P3V3_RTC_AUX")
	)
	(segment
		(start 324.099174 -22.234906)
		(end 324.099174 -21.618956)
		(width 0.4064)
		(layer "F.Cu")
		(net "P3V3_RTC_AUX")
	)
	(segment
		(start 301.793148 -25.322276)
		(end 302.409098 -25.322276)
		(width 0.4064)
		(layer "F.Cu")
		(net "P3V3_RTC_AUX")
	)
	(via
		(at 324.099174 -21.618956)
		(size 0.508)
		(drill 0.254)
		(layers "F.Cu" "B.Cu")
		(net "P3V3_RTC_AUX")
	)
	(via
		(at 302.409098 -25.322276)
		(size 0.508)
		(drill 0.254)
		(layers "F.Cu" "B.Cu")
		(net "P3V3_RTC_AUX")
	)
	(via
		(at 310.116474 -33.351978)
		(size 0.508)
		(drill 0.254)
		(layers "F.Cu" "B.Cu")
		(net "P3V3_RTC_AUX")
	)
	(segment
		(start 302.409098 -25.322276)
		(end 302.409098 -26.533602)
		(width 0.508)
		(layer "B.Cu")
		(net "P3V3_RTC_AUX")
	)
	(segment
		(start 302.409098 -26.533602)
		(end 309.227474 -33.351978)
		(width 0.508)
		(layer "B.Cu")
		(net "P3V3_RTC_AUX")
	)
	(segment
		(start 323.764402 -21.953728)
		(end 324.099174 -21.618956)
		(width 0.4572)
		(layer "B.Cu")
		(net "P3V3_RTC_AUX")
	)
	(segment
		(start 322.046346 -26.70302)
		(end 323.764402 -24.984964)
		(width 0.4572)
		(layer "B.Cu")
		(net "P3V3_RTC_AUX")
	)
	(segment
		(start 323.764402 -24.984964)
		(end 323.764402 -21.953728)
		(width 0.4572)
		(layer "B.Cu")
		(net "P3V3_RTC_AUX")
	)
	(segment
		(start 302.864774 -24.8666)
		(end 316.332362 -24.8666)
		(width 0.4572)
		(layer "B.Cu")
		(net "P3V3_RTC_AUX")
	)
	(segment
		(start 302.409098 -25.322276)
		(end 302.864774 -24.8666)
		(width 0.4572)
		(layer "B.Cu")
		(net "P3V3_RTC_AUX")
	)
	(segment
		(start 316.332362 -24.8666)
		(end 318.168782 -26.70302)
		(width 0.4572)
		(layer "B.Cu")
		(net "P3V3_RTC_AUX")
	)
	(segment
		(start 309.227474 -33.351978)
		(end 310.116474 -33.351978)
		(width 0.508)
		(layer "B.Cu")
		(net "P3V3_RTC_AUX")
	)
	(segment
		(start 318.168782 -26.70302)
		(end 322.046346 -26.70302)
		(width 0.4572)
		(layer "B.Cu")
		(net "P3V3_RTC_AUX")
	)
	(segment
		(start 92.897706 -55.717948)
		(end 92.89796 -55.717694)
		(width 0.10668)
		(layer "F.Cu")
		(net "P3V3_OCP_VCC_2")
	)
	(segment
		(start 93.69806 -54.701694)
		(end 93.69806 -54.81701)
		(width 0.10668)
		(layer "F.Cu")
		(net "P3V3_OCP_VCC_2")
	)
	(segment
		(start 92.451428 -57.582308)
		(end 92.451428 -56.801512)
		(width 0.10668)
		(layer "F.Cu")
		(net "P3V3_OCP_VCC_2")
	)
	(segment
		(start 92.89796 -55.61711)
		(end 92.89796 -55.717694)
		(width 0.10668)
		(layer "F.Cu")
		(net "P3V3_OCP_VCC_2")
	)
	(segment
		(start 92.897706 -56.355234)
		(end 92.897706 -55.717948)
		(width 0.10668)
		(layer "F.Cu")
		(net "P3V3_OCP_VCC_2")
	)
	(segment
		(start 93.69806 -54.81701)
		(end 92.89796 -55.61711)
		(width 0.10668)
		(layer "F.Cu")
		(net "P3V3_OCP_VCC_2")
	)
	(segment
		(start 92.451428 -56.801512)
		(end 92.897706 -56.355234)
		(width 0.10668)
		(layer "F.Cu")
		(net "P3V3_OCP_VCC_2")
	)
	(via
		(at 92.897706 -56.355234)
		(size 0.508)
		(drill 0.254)
		(layers "F.Cu" "B.Cu")
		(net "P3V3_OCP_VCC_2")
	)
	(segment
		(start 433.722272 -106.77398)
		(end 433.27574 -106.327448)
		(width 0.10668)
		(layer "F.Cu")
		(net "P3V3_OCP_VCC_1")
	)
	(segment
		(start 434.443632 -106.77398)
		(end 433.722272 -106.77398)
		(width 0.10668)
		(layer "F.Cu")
		(net "P3V3_OCP_VCC_1")
	)
	(segment
		(start 433.27574 -106.327448)
		(end 432.579018 -106.327448)
		(width 0.10668)
		(layer "F.Cu")
		(net "P3V3_OCP_VCC_1")
	)
	(segment
		(start 434.443632 -106.77398)
		(end 435.590188 -106.77398)
		(width 0.10668)
		(layer "F.Cu")
		(net "P3V3_OCP_VCC_1")
	)
	(segment
		(start 435.590188 -106.77398)
		(end 435.597808 -106.76636)
		(width 0.10668)
		(layer "F.Cu")
		(net "P3V3_OCP_VCC_1")
	)
	(via
		(at 433.722272 -106.77398)
		(size 0.508)
		(drill 0.254)
		(layers "F.Cu" "B.Cu")
		(net "P3V3_OCP_VCC_1")
	)
	(segment
		(start 88.700864 -54.69255)
		(end 88.419178 -54.974236)
		(width 0.381)
		(layer "F.Cu")
		(net "P3V3_OCP_V3_2_R")
	)
	(segment
		(start 76.835 -63.60795)
		(end 78.878938 -63.60795)
		(width 0.381)
		(layer "F.Cu")
		(net "P3V3_OCP_V3_2_R")
	)
	(segment
		(start 75.30465 -39.676324)
		(end 75.305412 -39.675562)
		(width 0.2286)
		(layer "F.Cu")
		(net "P3V3_OCP_V3_2_R")
	)
	(segment
		(start 74.543412 -39.676324)
		(end 75.30465 -39.676324)
		(width 0.2286)
		(layer "F.Cu")
		(net "P3V3_OCP_V3_2_R")
	)
	(segment
		(start 79.629 -61.23305)
		(end 79.629 -62.857888)
		(width 0.381)
		(layer "F.Cu")
		(net "P3V3_OCP_V3_2_R")
	)
	(segment
		(start 74.10831 -39.569898)
		(end 74.109072 -39.57066)
		(width 0.2286)
		(layer "F.Cu")
		(net "P3V3_OCP_V3_2_R")
	)
	(segment
		(start 83.209638 -61.214)
		(end 83.621626 -60.802012)
		(width 0.381)
		(layer "F.Cu")
		(net "P3V3_OCP_V3_2_R")
	)
	(segment
		(start 75.305412 -40.310308)
		(end 75.304396 -40.311324)
		(width 0.381)
		(layer "F.Cu")
		(net "P3V3_OCP_V3_2_R")
	)
	(segment
		(start 88.419178 -54.974236)
		(end 88.419178 -55.98668)
		(width 0.381)
		(layer "F.Cu")
		(net "P3V3_OCP_V3_2_R")
	)
	(segment
		(start 89.49436 -54.69255)
		(end 88.700864 -54.69255)
		(width 0.381)
		(layer "F.Cu")
		(net "P3V3_OCP_V3_2_R")
	)
	(segment
		(start 74.109072 -39.57066)
		(end 74.437748 -39.57066)
		(width 0.2286)
		(layer "F.Cu")
		(net "P3V3_OCP_V3_2_R")
	)
	(segment
		(start 74.437748 -39.57066)
		(end 74.543412 -39.676324)
		(width 0.2286)
		(layer "F.Cu")
		(net "P3V3_OCP_V3_2_R")
	)
	(segment
		(start 78.878938 -63.60795)
		(end 79.629 -62.857888)
		(width 0.381)
		(layer "F.Cu")
		(net "P3V3_OCP_V3_2_R")
	)
	(segment
		(start 83.209638 -61.214)
		(end 79.64805 -61.214)
		(width 0.381)
		(layer "F.Cu")
		(net "P3V3_OCP_V3_2_R")
	)
	(segment
		(start 79.64805 -61.214)
		(end 79.629 -61.23305)
		(width 0.381)
		(layer "F.Cu")
		(net "P3V3_OCP_V3_2_R")
	)
	(segment
		(start 75.305412 -39.675562)
		(end 75.305412 -40.310308)
		(width 0.381)
		(layer "F.Cu")
		(net "P3V3_OCP_V3_2_R")
	)
	(segment
		(start 89.498932 -53.697378)
		(end 89.498932 -54.687978)
		(width 0.381)
		(layer "F.Cu")
		(net "P3V3_OCP_V3_2_R")
	)
	(segment
		(start 89.498932 -54.687978)
		(end 89.49436 -54.69255)
		(width 0.381)
		(layer "F.Cu")
		(net "P3V3_OCP_V3_2_R")
	)
	(via
		(at 88.419178 -55.98668)
		(size 0.508)
		(drill 0.254)
		(layers "F.Cu" "B.Cu")
		(net "P3V3_OCP_V3_2_R")
	)
	(via
		(at 84.589874 -64.852296)
		(size 0.762)
		(drill 0.381)
		(layers "F.Cu" "B.Cu")
		(net "P3V3_OCP_V3_2_R")
	)
	(via
		(at 81.30413 -58.87974)
		(size 0.508)
		(drill 0.254)
		(layers "F.Cu" "B.Cu")
		(net "P3V3_OCP_V3_2_R")
	)
	(via
		(at 75.304396 -40.311324)
		(size 0.508)
		(drill 0.254)
		(layers "F.Cu" "B.Cu")
		(net "P3V3_OCP_V3_2_R")
	)
	(segment
		(start 76.884784 -42.237914)
		(end 76.884784 -56.08447)
		(width 0.381)
		(layer "B.Cu")
		(net "P3V3_OCP_V3_2_R")
	)
	(segment
		(start 76.884784 -56.08447)
		(end 79.654146 -58.853832)
		(width 0.381)
		(layer "B.Cu")
		(net "P3V3_OCP_V3_2_R")
	)
	(segment
		(start 75.304396 -40.311324)
		(end 75.304396 -40.657526)
		(width 0.381)
		(layer "B.Cu")
		(net "P3V3_OCP_V3_2_R")
	)
	(segment
		(start 84.47024 -55.716424)
		(end 83.41614 -56.770524)
		(width 0.381)
		(layer "B.Cu")
		(net "P3V3_OCP_V3_2_R")
	)
	(segment
		(start 81.278222 -58.853832)
		(end 81.30413 -58.87974)
		(width 0.381)
		(layer "B.Cu")
		(net "P3V3_OCP_V3_2_R")
	)
	(segment
		(start 83.41614 -56.770524)
		(end 83.413346 -56.770524)
		(width 0.381)
		(layer "B.Cu")
		(net "P3V3_OCP_V3_2_R")
	)
	(segment
		(start 88.148922 -55.716424)
		(end 84.47024 -55.716424)
		(width 0.381)
		(layer "B.Cu")
		(net "P3V3_OCP_V3_2_R")
	)
	(segment
		(start 79.654146 -58.853832)
		(end 81.278222 -58.853832)
		(width 0.381)
		(layer "B.Cu")
		(net "P3V3_OCP_V3_2_R")
	)
	(segment
		(start 75.304396 -40.657526)
		(end 76.884784 -42.237914)
		(width 0.381)
		(layer "B.Cu")
		(net "P3V3_OCP_V3_2_R")
	)
	(segment
		(start 88.419178 -55.98668)
		(end 88.148922 -55.716424)
		(width 0.381)
		(layer "B.Cu")
		(net "P3V3_OCP_V3_2_R")
	)
	(segment
		(start 83.413346 -56.770524)
		(end 81.30413 -58.87974)
		(width 0.381)
		(layer "B.Cu")
		(net "P3V3_OCP_V3_2_R")
	)
	(segment
		(start 153.249376 -38.00856)
		(end 153.886662 -38.00856)
		(width 0.381)
		(layer "F.Cu")
		(net "P3V3_OCP_V3_2")
	)
	(segment
		(start 153.249376 -39.02456)
		(end 153.630376 -38.64356)
		(width 0.381)
		(layer "F.Cu")
		(net "P3V3_OCP_V3_2")
	)
	(segment
		(start 102.963472 -38.678612)
		(end 103.785162 -38.678612)
		(width 0.381)
		(layer "F.Cu")
		(net "P3V3_OCP_V3_2")
	)
	(segment
		(start 102.963472 -39.886636)
		(end 102.963472 -38.678612)
		(width 0.381)
		(layer "F.Cu")
		(net "P3V3_OCP_V3_2")
	)
	(segment
		(start 149.713442 -40.003476)
		(end 151.19604 -40.003476)
		(width 0.508)
		(layer "F.Cu")
		(net "P3V3_OCP_V3_2")
	)
	(segment
		(start 153.630376 -38.64356)
		(end 153.886662 -38.64356)
		(width 0.381)
		(layer "F.Cu")
		(net "P3V3_OCP_V3_2")
	)
	(segment
		(start 151.19604 -40.003476)
		(end 151.63292 -40.003476)
		(width 0.508)
		(layer "F.Cu")
		(net "P3V3_OCP_V3_2")
	)
	(segment
		(start 151.63292 -40.003476)
		(end 152.032208 -40.402764)
		(width 0.508)
		(layer "F.Cu")
		(net "P3V3_OCP_V3_2")
	)
	(segment
		(start 59.867038 -11.26998)
		(end 59.867038 -10.09777)
		(width 0.381)
		(layer "F.Cu")
		(net "P3V3_OCP_V3_2")
	)
	(via
		(at 80.637888 -57.205118)
		(size 0.508)
		(drill 0.254)
		(layers "F.Cu" "B.Cu")
		(net "P3V3_OCP_V3_2")
	)
	(via
		(at 64.527684 -10.01395)
		(size 0.508)
		(drill 0.254)
		(layers "F.Cu" "B.Cu")
		(net "P3V3_OCP_V3_2")
	)
	(via
		(at 81.27238 -57.954418)
		(size 0.508)
		(drill 0.254)
		(layers "F.Cu" "B.Cu")
		(net "P3V3_OCP_V3_2")
	)
	(via
		(at 153.886662 -38.00856)
		(size 0.508)
		(drill 0.254)
		(layers "F.Cu" "B.Cu")
		(net "P3V3_OCP_V3_2")
	)
	(via
		(at 62.538864 -9.99871)
		(size 0.508)
		(drill 0.254)
		(layers "F.Cu" "B.Cu")
		(net "P3V3_OCP_V3_2")
	)
	(via
		(at 67.67068 -9.93648)
		(size 0.508)
		(drill 0.254)
		(layers "F.Cu" "B.Cu")
		(net "P3V3_OCP_V3_2")
	)
	(via
		(at 60.466986 -9.43991)
		(size 0.508)
		(drill 0.254)
		(layers "F.Cu" "B.Cu")
		(net "P3V3_OCP_V3_2")
	)
	(via
		(at 153.886662 -38.64356)
		(size 0.508)
		(drill 0.254)
		(layers "F.Cu" "B.Cu")
		(net "P3V3_OCP_V3_2")
	)
	(via
		(at 73.841864 -10.16508)
		(size 0.508)
		(drill 0.254)
		(layers "F.Cu" "B.Cu")
		(net "P3V3_OCP_V3_2")
	)
	(via
		(at 71.809864 -10.16508)
		(size 0.508)
		(drill 0.254)
		(layers "F.Cu" "B.Cu")
		(net "P3V3_OCP_V3_2")
	)
	(via
		(at 75.873864 -10.16508)
		(size 0.508)
		(drill 0.254)
		(layers "F.Cu" "B.Cu")
		(net "P3V3_OCP_V3_2")
	)
	(via
		(at 61.522864 -9.99871)
		(size 0.508)
		(drill 0.254)
		(layers "F.Cu" "B.Cu")
		(net "P3V3_OCP_V3_2")
	)
	(via
		(at 59.867038 -10.09777)
		(size 0.508)
		(drill 0.254)
		(layers "F.Cu" "B.Cu")
		(net "P3V3_OCP_V3_2")
	)
	(via
		(at 63.554864 -9.99871)
		(size 0.508)
		(drill 0.254)
		(layers "F.Cu" "B.Cu")
		(net "P3V3_OCP_V3_2")
	)
	(via
		(at 76.25842 -3.76428)
		(size 0.508)
		(drill 0.254)
		(layers "F.Cu" "B.Cu")
		(net "P3V3_OCP_V3_2")
	)
	(via
		(at 103.785162 -38.678612)
		(size 0.508)
		(drill 0.254)
		(layers "F.Cu" "B.Cu")
		(net "P3V3_OCP_V3_2")
	)
	(via
		(at 152.032208 -40.402764)
		(size 0.508)
		(drill 0.254)
		(layers "F.Cu" "B.Cu")
		(net "P3V3_OCP_V3_2")
	)
	(via
		(at 80.637888 -56.454548)
		(size 0.508)
		(drill 0.254)
		(layers "F.Cu" "B.Cu")
		(net "P3V3_OCP_V3_2")
	)
	(segment
		(start 88.3539 -43.492166)
		(end 88.3539 -48.738536)
		(width 0.4572)
		(layer "B.Cu")
		(net "P3V3_OCP_V3_2")
	)
	(segment
		(start 103.785162 -38.678612)
		(end 102.456234 -40.00754)
		(width 0.4572)
		(layer "B.Cu")
		(net "P3V3_OCP_V3_2")
	)
	(segment
		(start 96.139508 -41.297606)
		(end 90.54846 -41.297606)
		(width 0.4572)
		(layer "B.Cu")
		(net "P3V3_OCP_V3_2")
	)
	(segment
		(start 76.20508 -10.867898)
		(end 75.87488 -10.537698)
		(width 0.381)
		(layer "B.Cu")
		(net "P3V3_OCP_V3_2")
	)
	(segment
		(start 71.809864 -10.86866)
		(end 71.809864 -10.16508)
		(width 0.381)
		(layer "B.Cu")
		(net "P3V3_OCP_V3_2")
	)
	(segment
		(start 75.57008 -3.851148)
		(end 75.602338 -3.851148)
		(width 0.4572)
		(layer "B.Cu")
		(net "P3V3_OCP_V3_2")
	)
	(segment
		(start 75.689206 -3.76428)
		(end 76.25842 -3.76428)
		(width 0.4572)
		(layer "B.Cu")
		(net "P3V3_OCP_V3_2")
	)
	(segment
		(start 75.602338 -3.851148)
		(end 75.689206 -3.76428)
		(width 0.4572)
		(layer "B.Cu")
		(net "P3V3_OCP_V3_2")
	)
	(segment
		(start 75.87488 -10.166096)
		(end 75.873864 -10.16508)
		(width 0.381)
		(layer "B.Cu")
		(net "P3V3_OCP_V3_2")
	)
	(segment
		(start 73.841864 -10.86866)
		(end 73.841864 -10.16508)
		(width 0.381)
		(layer "B.Cu")
		(net "P3V3_OCP_V3_2")
	)
	(segment
		(start 75.873864 -9.50468)
		(end 75.873864 -10.16508)
		(width 0.381)
		(layer "B.Cu")
		(net "P3V3_OCP_V3_2")
	)
	(segment
		(start 88.3539 -48.738536)
		(end 80.637888 -56.454548)
		(width 0.4572)
		(layer "B.Cu")
		(net "P3V3_OCP_V3_2")
	)
	(segment
		(start 102.456234 -40.00754)
		(end 97.429574 -40.00754)
		(width 0.4572)
		(layer "B.Cu")
		(net "P3V3_OCP_V3_2")
	)
	(segment
		(start 90.54846 -41.297606)
		(end 88.3539 -43.492166)
		(width 0.4572)
		(layer "B.Cu")
		(net "P3V3_OCP_V3_2")
	)
	(segment
		(start 75.87488 -10.537698)
		(end 75.87488 -10.166096)
		(width 0.381)
		(layer "B.Cu")
		(net "P3V3_OCP_V3_2")
	)
	(segment
		(start 97.429574 -40.00754)
		(end 96.139508 -41.297606)
		(width 0.4572)
		(layer "B.Cu")
		(net "P3V3_OCP_V3_2")
	)
	(segment
		(start 151.650192 -40.78478)
		(end 144.98447 -40.78478)
		(width 0.4572)
		(layer "In6.Cu")
		(net "P3V3_OCP_V3_2")
	)
	(segment
		(start 130.709416 -41.129712)
		(end 129.419604 -42.419524)
		(width 0.4572)
		(layer "In6.Cu")
		(net "P3V3_OCP_V3_2")
	)
	(segment
		(start 144.98447 -40.78478)
		(end 144.132046 -41.637204)
		(width 0.4572)
		(layer "In6.Cu")
		(net "P3V3_OCP_V3_2")
	)
	(segment
		(start 138.627612 -41.129712)
		(end 130.709416 -41.129712)
		(width 0.4572)
		(layer "In6.Cu")
		(net "P3V3_OCP_V3_2")
	)
	(segment
		(start 139.733274 -40.02405)
		(end 138.627612 -41.129712)
		(width 0.4572)
		(layer "In6.Cu")
		(net "P3V3_OCP_V3_2")
	)
	(segment
		(start 129.419604 -42.419524)
		(end 119.686324 -42.419524)
		(width 0.4572)
		(layer "In6.Cu")
		(net "P3V3_OCP_V3_2")
	)
	(segment
		(start 152.032208 -40.402764)
		(end 151.650192 -40.78478)
		(width 0.4572)
		(layer "In6.Cu")
		(net "P3V3_OCP_V3_2")
	)
	(segment
		(start 115.945412 -38.678612)
		(end 103.785162 -38.678612)
		(width 0.4572)
		(layer "In6.Cu")
		(net "P3V3_OCP_V3_2")
	)
	(segment
		(start 142.982696 -41.637204)
		(end 141.369542 -40.02405)
		(width 0.4572)
		(layer "In6.Cu")
		(net "P3V3_OCP_V3_2")
	)
	(segment
		(start 119.686324 -42.419524)
		(end 115.945412 -38.678612)
		(width 0.4572)
		(layer "In6.Cu")
		(net "P3V3_OCP_V3_2")
	)
	(segment
		(start 141.369542 -40.02405)
		(end 139.733274 -40.02405)
		(width 0.4572)
		(layer "In6.Cu")
		(net "P3V3_OCP_V3_2")
	)
	(segment
		(start 144.132046 -41.637204)
		(end 142.982696 -41.637204)
		(width 0.4572)
		(layer "In6.Cu")
		(net "P3V3_OCP_V3_2")
	)
	(segment
		(start 62.387734 -39.594028)
		(end 62.174882 -39.381176)
		(width 0.10668)
		(layer "F.Cu")
		(net "P3V3_OCP_UV_2_R1")
	)
	(segment
		(start 62.353444 -40.56507)
		(end 62.387734 -40.53078)
		(width 0.10668)
		(layer "F.Cu")
		(net "P3V3_OCP_UV_2_R1")
	)
	(segment
		(start 62.387734 -40.53078)
		(end 62.387734 -39.594028)
		(width 0.10668)
		(layer "F.Cu")
		(net "P3V3_OCP_UV_2_R1")
	)
	(segment
		(start 62.174882 -39.381176)
		(end 61.53277 -39.381176)
		(width 0.10668)
		(layer "F.Cu")
		(net "P3V3_OCP_UV_2_R1")
	)
	(via
		(at 62.353444 -40.56507)
		(size 0.508)
		(drill 0.254)
		(layers "F.Cu" "B.Cu")
		(net "P3V3_OCP_UV_2_R1")
	)
	(segment
		(start 62.353444 -40.56507)
		(end 62.384178 -40.595804)
		(width 0.10668)
		(layer "B.Cu")
		(net "P3V3_OCP_UV_2_R1")
	)
	(segment
		(start 94.047818 -62.085474)
		(end 94.835472 -61.29782)
		(width 0.10668)
		(layer "B.Cu")
		(net "P3V3_OCP_UV_2_R1")
	)
	(segment
		(start 62.384178 -40.595804)
		(end 62.384178 -41.92397)
		(width 0.10668)
		(layer "B.Cu")
		(net "P3V3_OCP_UV_2_R1")
	)
	(segment
		(start 94.835472 -61.29782)
		(end 94.835472 -60.820808)
		(width 0.10668)
		(layer "B.Cu")
		(net "P3V3_OCP_UV_2_R1")
	)
	(segment
		(start 58.861452 -45.446696)
		(end 58.861452 -50.837084)
		(width 0.10668)
		(layer "B.Cu")
		(net "P3V3_OCP_UV_2_R1")
	)
	(segment
		(start 58.861452 -50.837084)
		(end 70.109842 -62.085474)
		(width 0.10668)
		(layer "B.Cu")
		(net "P3V3_OCP_UV_2_R1")
	)
	(segment
		(start 70.109842 -62.085474)
		(end 76.344526 -62.085474)
		(width 0.10668)
		(layer "B.Cu")
		(net "P3V3_OCP_UV_2_R1")
	)
	(segment
		(start 77.216 -61.214)
		(end 79.392526 -61.214)
		(width 0.10668)
		(layer "B.Cu")
		(net "P3V3_OCP_UV_2_R1")
	)
	(segment
		(start 62.384178 -41.92397)
		(end 58.861452 -45.446696)
		(width 0.10668)
		(layer "B.Cu")
		(net "P3V3_OCP_UV_2_R1")
	)
	(segment
		(start 79.392526 -61.214)
		(end 80.264 -62.085474)
		(width 0.10668)
		(layer "B.Cu")
		(net "P3V3_OCP_UV_2_R1")
	)
	(segment
		(start 76.344526 -62.085474)
		(end 77.216 -61.214)
		(width 0.10668)
		(layer "B.Cu")
		(net "P3V3_OCP_UV_2_R1")
	)
	(segment
		(start 80.264 -62.085474)
		(end 94.047818 -62.085474)
		(width 0.10668)
		(layer "B.Cu")
		(net "P3V3_OCP_UV_2_R1")
	)
	(segment
		(start 92.451428 -59.082432)
		(end 92.451428 -60.279026)
		(width 0.10668)
		(layer "F.Cu")
		(net "P3V3_OCP_UV_2")
	)
	(segment
		(start 93.020896 -60.848494)
		(end 93.996256 -60.848494)
		(width 0.10668)
		(layer "F.Cu")
		(net "P3V3_OCP_UV_2")
	)
	(segment
		(start 94.99092 -60.86221)
		(end 94.009972 -60.86221)
		(width 0.10668)
		(layer "F.Cu")
		(net "P3V3_OCP_UV_2")
	)
	(segment
		(start 92.851986 -60.679584)
		(end 93.020896 -60.848494)
		(width 0.10668)
		(layer "F.Cu")
		(net "P3V3_OCP_UV_2")
	)
	(segment
		(start 94.009972 -60.86221)
		(end 93.996256 -60.848494)
		(width 0.10668)
		(layer "F.Cu")
		(net "P3V3_OCP_UV_2")
	)
	(segment
		(start 92.451428 -60.279026)
		(end 92.851986 -60.679584)
		(width 0.10668)
		(layer "F.Cu")
		(net "P3V3_OCP_UV_2")
	)
	(via
		(at 92.851986 -60.679584)
		(size 0.508)
		(drill 0.254)
		(layers "F.Cu" "B.Cu")
		(net "P3V3_OCP_UV_2")
	)
	(segment
		(start 93.24721 -60.820808)
		(end 93.105986 -60.679584)
		(width 0.10668)
		(layer "B.Cu")
		(net "P3V3_OCP_UV_2")
	)
	(segment
		(start 93.105986 -60.679584)
		(end 92.851986 -60.679584)
		(width 0.10668)
		(layer "B.Cu")
		(net "P3V3_OCP_UV_2")
	)
	(segment
		(start 94.035372 -60.820808)
		(end 93.24721 -60.820808)
		(width 0.10668)
		(layer "B.Cu")
		(net "P3V3_OCP_UV_2")
	)
	(segment
		(start 457.85151 -40.45585)
		(end 457.85151 -39.765478)
		(width 0.10668)
		(layer "F.Cu")
		(net "P3V3_OCP_UV_1_R1")
	)
	(via
		(at 457.85151 -39.765478)
		(size 0.508)
		(drill 0.254)
		(layers "F.Cu" "B.Cu")
		(net "P3V3_OCP_UV_1_R1")
	)
	(via
		(at 429.8823 -110.940088)
		(size 0.508)
		(drill 0.254)
		(layers "F.Cu" "B.Cu")
		(net "P3V3_OCP_UV_1_R1")
	)
	(segment
		(start 429.40224 -109.267498)
		(end 429.8823 -109.747558)
		(width 0.10668)
		(layer "B.Cu")
		(net "P3V3_OCP_UV_1_R1")
	)
	(segment
		(start 429.8823 -109.747558)
		(end 429.8823 -110.940088)
		(width 0.10668)
		(layer "B.Cu")
		(net "P3V3_OCP_UV_1_R1")
	)
	(segment
		(start 423.202354 -57.574434)
		(end 423.202354 -59.041284)
		(width 0.11684)
		(layer "In11.Cu")
		(net "P3V3_OCP_UV_1_R1")
	)
	(segment
		(start 442.87694 -82.214212)
		(end 453.243442 -92.580714)
		(width 0.11684)
		(layer "In11.Cu")
		(net "P3V3_OCP_UV_1_R1")
	)
	(segment
		(start 432.63566 -42.878756)
		(end 430.170844 -45.343572)
		(width 0.11684)
		(layer "In11.Cu")
		(net "P3V3_OCP_UV_1_R1")
	)
	(segment
		(start 453.243442 -92.580714)
		(end 453.243442 -93.776038)
		(width 0.11684)
		(layer "In11.Cu")
		(net "P3V3_OCP_UV_1_R1")
	)
	(segment
		(start 433.91074 -37.061648)
		(end 432.63566 -38.336728)
		(width 0.11684)
		(layer "In11.Cu")
		(net "P3V3_OCP_UV_1_R1")
	)
	(segment
		(start 453.950324 -36.558474)
		(end 437.092344 -36.558474)
		(width 0.11684)
		(layer "In11.Cu")
		(net "P3V3_OCP_UV_1_R1")
	)
	(segment
		(start 432.63566 -38.336728)
		(end 432.63566 -42.878756)
		(width 0.11684)
		(layer "In11.Cu")
		(net "P3V3_OCP_UV_1_R1")
	)
	(segment
		(start 457.85151 -39.765478)
		(end 457.873608 -39.74338)
		(width 0.11684)
		(layer "In11.Cu")
		(net "P3V3_OCP_UV_1_R1")
	)
	(segment
		(start 421.952674 -56.324754)
		(end 423.202354 -57.574434)
		(width 0.11684)
		(layer "In11.Cu")
		(net "P3V3_OCP_UV_1_R1")
	)
	(segment
		(start 425.402756 -82.214212)
		(end 442.87694 -82.214212)
		(width 0.11684)
		(layer "In11.Cu")
		(net "P3V3_OCP_UV_1_R1")
	)
	(segment
		(start 432.688492 -113.74628)
		(end 429.8823 -110.940088)
		(width 0.11684)
		(layer "In11.Cu")
		(net "P3V3_OCP_UV_1_R1")
	)
	(segment
		(start 437.092344 -36.558474)
		(end 436.58917 -37.061648)
		(width 0.11684)
		(layer "In11.Cu")
		(net "P3V3_OCP_UV_1_R1")
	)
	(segment
		(start 457.255626 -109.216952)
		(end 452.726298 -113.74628)
		(width 0.11684)
		(layer "In11.Cu")
		(net "P3V3_OCP_UV_1_R1")
	)
	(segment
		(start 452.726298 -113.74628)
		(end 432.688492 -113.74628)
		(width 0.11684)
		(layer "In11.Cu")
		(net "P3V3_OCP_UV_1_R1")
	)
	(segment
		(start 420.648638 -77.460094)
		(end 425.402756 -82.214212)
		(width 0.11684)
		(layer "In11.Cu")
		(net "P3V3_OCP_UV_1_R1")
	)
	(segment
		(start 436.58917 -37.061648)
		(end 433.91074 -37.061648)
		(width 0.11684)
		(layer "In11.Cu")
		(net "P3V3_OCP_UV_1_R1")
	)
	(segment
		(start 457.873608 -39.74338)
		(end 457.13523 -39.74338)
		(width 0.11684)
		(layer "In11.Cu")
		(net "P3V3_OCP_UV_1_R1")
	)
	(segment
		(start 430.170844 -45.343572)
		(end 425.51731 -45.343572)
		(width 0.11684)
		(layer "In11.Cu")
		(net "P3V3_OCP_UV_1_R1")
	)
	(segment
		(start 425.51731 -45.343572)
		(end 421.952674 -48.908208)
		(width 0.11684)
		(layer "In11.Cu")
		(net "P3V3_OCP_UV_1_R1")
	)
	(segment
		(start 457.255626 -97.788222)
		(end 457.255626 -109.216952)
		(width 0.11684)
		(layer "In11.Cu")
		(net "P3V3_OCP_UV_1_R1")
	)
	(segment
		(start 421.952674 -48.908208)
		(end 421.952674 -56.324754)
		(width 0.11684)
		(layer "In11.Cu")
		(net "P3V3_OCP_UV_1_R1")
	)
	(segment
		(start 453.243442 -93.776038)
		(end 457.255626 -97.788222)
		(width 0.11684)
		(layer "In11.Cu")
		(net "P3V3_OCP_UV_1_R1")
	)
	(segment
		(start 423.202354 -59.041284)
		(end 420.648638 -61.595)
		(width 0.11684)
		(layer "In11.Cu")
		(net "P3V3_OCP_UV_1_R1")
	)
	(segment
		(start 457.13523 -39.74338)
		(end 453.950324 -36.558474)
		(width 0.11684)
		(layer "In11.Cu")
		(net "P3V3_OCP_UV_1_R1")
	)
	(segment
		(start 420.648638 -61.595)
		(end 420.648638 -77.460094)
		(width 0.11684)
		(layer "In11.Cu")
		(net "P3V3_OCP_UV_1_R1")
	)
	(segment
		(start 429.312832 -108.853224)
		(end 429.299116 -108.86694)
		(width 0.10668)
		(layer "F.Cu")
		(net "P3V3_OCP_UV_1")
	)
	(segment
		(start 429.312832 -107.872276)
		(end 429.312832 -108.853224)
		(width 0.10668)
		(layer "F.Cu")
		(net "P3V3_OCP_UV_1")
	)
	(segment
		(start 429.312832 -107.872276)
		(end 429.312832 -107.15117)
		(width 0.10668)
		(layer "F.Cu")
		(net "P3V3_OCP_UV_1")
	)
	(segment
		(start 429.312832 -107.15117)
		(end 430.136554 -106.327448)
		(width 0.10668)
		(layer "F.Cu")
		(net "P3V3_OCP_UV_1")
	)
	(segment
		(start 430.136554 -106.327448)
		(end 431.078894 -106.327448)
		(width 0.10668)
		(layer "F.Cu")
		(net "P3V3_OCP_UV_1")
	)
	(via
		(at 429.312832 -107.15117)
		(size 0.508)
		(drill 0.254)
		(layers "F.Cu" "B.Cu")
		(net "P3V3_OCP_UV_1")
	)
	(segment
		(start 429.312832 -108.37799)
		(end 429.312832 -107.15117)
		(width 0.10668)
		(layer "B.Cu")
		(net "P3V3_OCP_UV_1")
	)
	(segment
		(start 429.40224 -108.467398)
		(end 429.312832 -108.37799)
		(width 0.10668)
		(layer "B.Cu")
		(net "P3V3_OCP_UV_1")
	)
	(segment
		(start 436.6768 -94.148148)
		(end 436.6768 -94.275148)
		(width 0.381)
		(layer "F.Cu")
		(net "P3V3_OCP_SFF_R")
	)
	(segment
		(start 439.28792 -93.8276)
		(end 438.667652 -93.8276)
		(width 0.254)
		(layer "F.Cu")
		(net "P3V3_OCP_SFF_R")
	)
	(segment
		(start 435.468776 -101.586284)
		(end 435.468776 -102.67188)
		(width 0.381)
		(layer "F.Cu")
		(net "P3V3_OCP_SFF_R")
	)
	(segment
		(start 416.19805 -96.901)
		(end 416.179 -96.92005)
		(width 0.4572)
		(layer "F.Cu")
		(net "P3V3_OCP_SFF_R")
	)
	(segment
		(start 437.515 -93.671898)
		(end 437.15305 -93.671898)
		(width 0.381)
		(layer "F.Cu")
		(net "P3V3_OCP_SFF_R")
	)
	(segment
		(start 416.179 -96.92005)
		(end 416.179 -98.290888)
		(width 0.4572)
		(layer "F.Cu")
		(net "P3V3_OCP_SFF_R")
	)
	(segment
		(start 414.920938 -98.290888)
		(end 416.179 -98.290888)
		(width 0.4572)
		(layer "F.Cu")
		(net "P3V3_OCP_SFF_R")
	)
	(segment
		(start 423.672 -96.012)
		(end 417.08705 -96.012)
		(width 0.4572)
		(layer "F.Cu")
		(net "P3V3_OCP_SFF_R")
	)
	(segment
		(start 438.667652 -93.8276)
		(end 438.51195 -93.671898)
		(width 0.254)
		(layer "F.Cu")
		(net "P3V3_OCP_SFF_R")
	)
	(segment
		(start 435.468776 -102.67188)
		(end 435.621176 -102.82428)
		(width 0.381)
		(layer "F.Cu")
		(net "P3V3_OCP_SFF_R")
	)
	(segment
		(start 427.93666 -103.95966)
		(end 427.93666 -101.539548)
		(width 0.381)
		(layer "F.Cu")
		(net "P3V3_OCP_SFF_R")
	)
	(segment
		(start 435.623208 -103.368348)
		(end 436.608474 -103.368348)
		(width 0.381)
		(layer "F.Cu")
		(net "P3V3_OCP_SFF_R")
	)
	(segment
		(start 427.93666 -101.539548)
		(end 428.41164 -101.064568)
		(width 0.381)
		(layer "F.Cu")
		(net "P3V3_OCP_SFF_R")
	)
	(segment
		(start 414.655 -98.02495)
		(end 414.920938 -98.290888)
		(width 0.4572)
		(layer "F.Cu")
		(net "P3V3_OCP_SFF_R")
	)
	(segment
		(start 434.94706 -101.064568)
		(end 435.468776 -101.586284)
		(width 0.381)
		(layer "F.Cu")
		(net "P3V3_OCP_SFF_R")
	)
	(segment
		(start 437.15305 -93.671898)
		(end 436.6768 -94.148148)
		(width 0.381)
		(layer "F.Cu")
		(net "P3V3_OCP_SFF_R")
	)
	(segment
		(start 417.08705 -96.012)
		(end 416.19805 -96.901)
		(width 0.4572)
		(layer "F.Cu")
		(net "P3V3_OCP_SFF_R")
	)
	(segment
		(start 438.51195 -93.671898)
		(end 437.515 -93.671898)
		(width 0.381)
		(layer "F.Cu")
		(net "P3V3_OCP_SFF_R")
	)
	(segment
		(start 435.621176 -103.37038)
		(end 435.623208 -103.368348)
		(width 0.381)
		(layer "F.Cu")
		(net "P3V3_OCP_SFF_R")
	)
	(segment
		(start 413.766 -98.02495)
		(end 414.655 -98.02495)
		(width 0.4572)
		(layer "F.Cu")
		(net "P3V3_OCP_SFF_R")
	)
	(segment
		(start 428.41164 -101.064568)
		(end 434.94706 -101.064568)
		(width 0.381)
		(layer "F.Cu")
		(net "P3V3_OCP_SFF_R")
	)
	(segment
		(start 435.621176 -102.82428)
		(end 435.621176 -103.37038)
		(width 0.381)
		(layer "F.Cu")
		(net "P3V3_OCP_SFF_R")
	)
	(via
		(at 431.34788 -93.891608)
		(size 0.508)
		(drill 0.254)
		(layers "F.Cu" "B.Cu")
		(net "P3V3_OCP_SFF_R")
	)
	(via
		(at 426.72508 -106.713528)
		(size 0.762)
		(drill 0.381)
		(layers "F.Cu" "B.Cu")
		(net "P3V3_OCP_SFF_R")
	)
	(via
		(at 436.6768 -94.275148)
		(size 0.508)
		(drill 0.254)
		(layers "F.Cu" "B.Cu")
		(net "P3V3_OCP_SFF_R")
	)
	(segment
		(start 436.6768 -94.275148)
		(end 436.29326 -93.891608)
		(width 0.4572)
		(layer "In2.Cu")
		(net "P3V3_OCP_SFF_R")
	)
	(segment
		(start 436.29326 -93.891608)
		(end 431.34788 -93.891608)
		(width 0.4572)
		(layer "In2.Cu")
		(net "P3V3_OCP_SFF_R")
	)
	(segment
		(start 409.362402 -77.113384)
		(end 410.8196 -77.113384)
		(width 0.4064)
		(layer "F.Cu")
		(net "P3V3_OCP_SFF")
	)
	(segment
		(start 434.366924 -10.101072)
		(end 434.366924 -11.26998)
		(width 0.381)
		(layer "F.Cu")
		(net "P3V3_OCP_SFF")
	)
	(segment
		(start 454.61301 -38.565836)
		(end 453.99706 -38.565836)
		(width 0.4572)
		(layer "F.Cu")
		(net "P3V3_OCP_SFF")
	)
	(segment
		(start 454.61301 -38.565836)
		(end 454.61301 -37.295836)
		(width 0.4572)
		(layer "F.Cu")
		(net "P3V3_OCP_SFF")
	)
	(segment
		(start 434.366924 -11.26998)
		(end 434.366924 -12.440412)
		(width 0.381)
		(layer "F.Cu")
		(net "P3V3_OCP_SFF")
	)
	(segment
		(start 410.8196 -77.113384)
		(end 411.456886 -77.113384)
		(width 0.4572)
		(layer "F.Cu")
		(net "P3V3_OCP_SFF")
	)
	(segment
		(start 412.872936 -75.880468)
		(end 413.488886 -75.880468)
		(width 0.4572)
		(layer "F.Cu")
		(net "P3V3_OCP_SFF")
	)
	(segment
		(start 412.872936 -74.864468)
		(end 413.488886 -74.864468)
		(width 0.4572)
		(layer "F.Cu")
		(net "P3V3_OCP_SFF")
	)
	(via
		(at 451.54088 -9.599168)
		(size 0.508)
		(drill 0.254)
		(layers "F.Cu" "B.Cu")
		(net "P3V3_OCP_SFF")
	)
	(via
		(at 453.99706 -38.565836)
		(size 0.508)
		(drill 0.254)
		(layers "F.Cu" "B.Cu")
		(net "P3V3_OCP_SFF")
	)
	(via
		(at 435.28488 -99.479608)
		(size 0.508)
		(drill 0.254)
		(layers "F.Cu" "B.Cu")
		(net "P3V3_OCP_SFF")
	)
	(via
		(at 436.1434 -96.002348)
		(size 0.762)
		(drill 0.381)
		(layers "F.Cu" "B.Cu")
		(net "P3V3_OCP_SFF")
	)
	(via
		(at 449.314824 -9.539732)
		(size 0.508)
		(drill 0.254)
		(layers "F.Cu" "B.Cu")
		(net "P3V3_OCP_SFF")
	)
	(via
		(at 435.28488 -97.701608)
		(size 0.508)
		(drill 0.254)
		(layers "F.Cu" "B.Cu")
		(net "P3V3_OCP_SFF")
	)
	(via
		(at 436.17388 -99.479608)
		(size 0.508)
		(drill 0.254)
		(layers "F.Cu" "B.Cu")
		(net "P3V3_OCP_SFF")
	)
	(via
		(at 437.293512 -37.417248)
		(size 0.508)
		(drill 0.254)
		(layers "F.Cu" "B.Cu")
		(net "P3V3_OCP_SFF")
	)
	(via
		(at 436.17388 -98.590608)
		(size 0.508)
		(drill 0.254)
		(layers "F.Cu" "B.Cu")
		(net "P3V3_OCP_SFF")
	)
	(via
		(at 436.17388 -97.701608)
		(size 0.508)
		(drill 0.254)
		(layers "F.Cu" "B.Cu")
		(net "P3V3_OCP_SFF")
	)
	(via
		(at 413.488886 -75.880468)
		(size 0.508)
		(drill 0.254)
		(layers "F.Cu" "B.Cu")
		(net "P3V3_OCP_SFF")
	)
	(via
		(at 435.28488 -96.812608)
		(size 0.508)
		(drill 0.254)
		(layers "F.Cu" "B.Cu")
		(net "P3V3_OCP_SFF")
	)
	(via
		(at 434.366924 -10.101072)
		(size 0.508)
		(drill 0.254)
		(layers "F.Cu" "B.Cu")
		(net "P3V3_OCP_SFF")
	)
	(via
		(at 413.488886 -74.864468)
		(size 0.508)
		(drill 0.254)
		(layers "F.Cu" "B.Cu")
		(net "P3V3_OCP_SFF")
	)
	(via
		(at 434.366924 -12.440412)
		(size 0.508)
		(drill 0.254)
		(layers "F.Cu" "B.Cu")
		(net "P3V3_OCP_SFF")
	)
	(via
		(at 411.456886 -77.113384)
		(size 0.508)
		(drill 0.254)
		(layers "F.Cu" "B.Cu")
		(net "P3V3_OCP_SFF")
	)
	(via
		(at 435.28488 -98.590608)
		(size 0.508)
		(drill 0.254)
		(layers "F.Cu" "B.Cu")
		(net "P3V3_OCP_SFF")
	)
	(via
		(at 436.17388 -96.812608)
		(size 0.508)
		(drill 0.254)
		(layers "F.Cu" "B.Cu")
		(net "P3V3_OCP_SFF")
	)
	(segment
		(start 452.62546 -10.20572)
		(end 452.605394 -10.225786)
		(width 0.381)
		(layer "B.Cu")
		(net "P3V3_OCP_SFF")
	)
	(segment
		(start 451.54088 -10.22604)
		(end 451.54088 -9.599168)
		(width 0.381)
		(layer "B.Cu")
		(net "P3V3_OCP_SFF")
	)
	(segment
		(start 448.579748 -10.167112)
		(end 449.527676 -10.167112)
		(width 0.4064)
		(layer "B.Cu")
		(net "P3V3_OCP_SFF")
	)
	(segment
		(start 451.558406 -10.225786)
		(end 451.549516 -10.234676)
		(width 0.381)
		(layer "B.Cu")
		(net "P3V3_OCP_SFF")
	)
	(segment
		(start 451.549516 -10.234676)
		(end 451.54088 -10.22604)
		(width 0.381)
		(layer "B.Cu")
		(net "P3V3_OCP_SFF")
	)
	(segment
		(start 452.605394 -10.225786)
		(end 451.558406 -10.225786)
		(width 0.381)
		(layer "B.Cu")
		(net "P3V3_OCP_SFF")
	)
	(segment
		(start 451.54088 -9.561068)
		(end 450.736462 -8.75665)
		(width 0.381)
		(layer "B.Cu")
		(net "P3V3_OCP_SFF")
	)
	(segment
		(start 451.54088 -9.599168)
		(end 451.54088 -9.561068)
		(width 0.381)
		(layer "B.Cu")
		(net "P3V3_OCP_SFF")
	)
	(segment
		(start 449.527676 -10.167112)
		(end 449.5546 -10.194036)
		(width 0.4064)
		(layer "B.Cu")
		(net "P3V3_OCP_SFF")
	)
	(segment
		(start 449.5546 -9.779508)
		(end 449.314824 -9.539732)
		(width 0.4064)
		(layer "B.Cu")
		(net "P3V3_OCP_SFF")
	)
	(segment
		(start 450.736462 -8.75665)
		(end 450.534278 -8.75665)
		(width 0.381)
		(layer "B.Cu")
		(net "P3V3_OCP_SFF")
	)
	(segment
		(start 449.5546 -10.194036)
		(end 449.5546 -9.779508)
		(width 0.4064)
		(layer "B.Cu")
		(net "P3V3_OCP_SFF")
	)
	(segment
		(start 451.54088 -9.599168)
		(end 450.8881 -10.251948)
		(width 0.4572)
		(layer "In2.Cu")
		(net "P3V3_OCP_SFF")
	)
	(segment
		(start 450.8881 -10.251948)
		(end 450.02704 -10.251948)
		(width 0.4572)
		(layer "In2.Cu")
		(net "P3V3_OCP_SFF")
	)
	(segment
		(start 452.672196 -38.565836)
		(end 453.99706 -38.565836)
		(width 0.4572)
		(layer "In2.Cu")
		(net "P3V3_OCP_SFF")
	)
	(segment
		(start 437.990488 -36.720272)
		(end 450.826632 -36.720272)
		(width 0.4572)
		(layer "In2.Cu")
		(net "P3V3_OCP_SFF")
	)
	(segment
		(start 437.293512 -37.417248)
		(end 437.990488 -36.720272)
		(width 0.4572)
		(layer "In2.Cu")
		(net "P3V3_OCP_SFF")
	)
	(segment
		(start 450.02704 -10.251948)
		(end 449.314824 -9.539732)
		(width 0.4572)
		(layer "In2.Cu")
		(net "P3V3_OCP_SFF")
	)
	(segment
		(start 450.826632 -36.720272)
		(end 452.672196 -38.565836)
		(width 0.4572)
		(layer "In2.Cu")
		(net "P3V3_OCP_SFF")
	)
	(segment
		(start 412.25597 -77.113384)
		(end 413.488886 -75.880468)
		(width 0.4572)
		(layer "In4.Cu")
		(net "P3V3_OCP_SFF")
	)
	(segment
		(start 415.014664 -74.864468)
		(end 413.488886 -74.864468)
		(width 0.4572)
		(layer "In4.Cu")
		(net "P3V3_OCP_SFF")
	)
	(segment
		(start 413.488886 -74.864468)
		(end 413.488886 -75.880468)
		(width 0.4572)
		(layer "In4.Cu")
		(net "P3V3_OCP_SFF")
	)
	(segment
		(start 427.613318 -57.277)
		(end 425.978828 -57.277)
		(width 0.4572)
		(layer "In4.Cu")
		(net "P3V3_OCP_SFF")
	)
	(segment
		(start 428.402496 -56.487822)
		(end 427.613318 -57.277)
		(width 0.4572)
		(layer "In4.Cu")
		(net "P3V3_OCP_SFF")
	)
	(segment
		(start 411.456886 -77.113384)
		(end 412.25597 -77.113384)
		(width 0.4572)
		(layer "In4.Cu")
		(net "P3V3_OCP_SFF")
	)
	(segment
		(start 418.228018 -65.02781)
		(end 418.228018 -71.651114)
		(width 0.4572)
		(layer "In4.Cu")
		(net "P3V3_OCP_SFF")
	)
	(segment
		(start 418.228018 -71.651114)
		(end 415.014664 -74.864468)
		(width 0.4572)
		(layer "In4.Cu")
		(net "P3V3_OCP_SFF")
	)
	(segment
		(start 425.978828 -57.277)
		(end 418.228018 -65.02781)
		(width 0.4572)
		(layer "In4.Cu")
		(net "P3V3_OCP_SFF")
	)
	(segment
		(start 434.366924 -10.101072)
		(end 436.420006 -8.04799)
		(width 0.508)
		(layer "In13.Cu")
		(net "P3V3_OCP_SFF")
	)
	(segment
		(start 447.823082 -8.04799)
		(end 449.314824 -9.539732)
		(width 0.508)
		(layer "In13.Cu")
		(net "P3V3_OCP_SFF")
	)
	(segment
		(start 436.420006 -8.04799)
		(end 447.823082 -8.04799)
		(width 0.508)
		(layer "In13.Cu")
		(net "P3V3_OCP_SFF")
	)
	(segment
		(start 94.465902 -57.582308)
		(end 94.86138 -57.18683)
		(width 0.10668)
		(layer "F.Cu")
		(net "P3V3_OCP_SENSE_2")
	)
	(segment
		(start 92.951554 -57.582308)
		(end 94.465902 -57.582308)
		(width 0.10668)
		(layer "F.Cu")
		(net "P3V3_OCP_SENSE_2")
	)
	(segment
		(start 95.787972 -56.446166)
		(end 95.160084 -56.446166)
		(width 0.10668)
		(layer "F.Cu")
		(net "P3V3_OCP_SENSE_2")
	)
	(segment
		(start 95.160084 -56.446166)
		(end 94.86138 -56.74487)
		(width 0.10668)
		(layer "F.Cu")
		(net "P3V3_OCP_SENSE_2")
	)
	(segment
		(start 94.86138 -56.74487)
		(end 94.86138 -57.18683)
		(width 0.10668)
		(layer "F.Cu")
		(net "P3V3_OCP_SENSE_2")
	)
	(via
		(at 95.787972 -56.446166)
		(size 0.508)
		(drill 0.254)
		(layers "F.Cu" "B.Cu")
		(net "P3V3_OCP_SENSE_2")
	)
	(segment
		(start 433.716176 -109.66323)
		(end 433.716176 -108.991654)
		(width 0.10668)
		(layer "F.Cu")
		(net "P3V3_OCP_SENSE_1")
	)
	(segment
		(start 433.716176 -108.991654)
		(end 433.461922 -108.7374)
		(width 0.10668)
		(layer "F.Cu")
		(net "P3V3_OCP_SENSE_1")
	)
	(segment
		(start 432.974496 -107.223052)
		(end 432.974496 -108.7374)
		(width 0.10668)
		(layer "F.Cu")
		(net "P3V3_OCP_SENSE_1")
	)
	(segment
		(start 432.579018 -106.827574)
		(end 432.974496 -107.223052)
		(width 0.10668)
		(layer "F.Cu")
		(net "P3V3_OCP_SENSE_1")
	)
	(segment
		(start 433.461922 -108.7374)
		(end 432.974496 -108.7374)
		(width 0.10668)
		(layer "F.Cu")
		(net "P3V3_OCP_SENSE_1")
	)
	(via
		(at 433.716176 -109.66323)
		(size 0.508)
		(drill 0.254)
		(layers "F.Cu" "B.Cu")
		(net "P3V3_OCP_SENSE_1")
	)
	(segment
		(start 94.9833 -59.80557)
		(end 94.069408 -59.80557)
		(width 0.10668)
		(layer "F.Cu")
		(net "P3V3_OCP_REG_2")
	)
	(segment
		(start 93.674692 -59.80557)
		(end 92.951554 -59.082432)
		(width 0.10668)
		(layer "F.Cu")
		(net "P3V3_OCP_REG_2")
	)
	(segment
		(start 94.069408 -59.80557)
		(end 93.674692 -59.80557)
		(width 0.10668)
		(layer "F.Cu")
		(net "P3V3_OCP_REG_2")
	)
	(via
		(at 94.069408 -59.80557)
		(size 0.508)
		(drill 0.254)
		(layers "F.Cu" "B.Cu")
		(net "P3V3_OCP_REG_2")
	)
	(segment
		(start 431.078894 -106.827574)
		(end 430.64557 -107.260898)
		(width 0.10668)
		(layer "F.Cu")
		(net "P3V3_OCP_REG_1")
	)
	(segment
		(start 430.355756 -107.550712)
		(end 430.355756 -108.85932)
		(width 0.10668)
		(layer "F.Cu")
		(net "P3V3_OCP_REG_1")
	)
	(segment
		(start 430.64557 -107.260898)
		(end 430.355756 -107.550712)
		(width 0.10668)
		(layer "F.Cu")
		(net "P3V3_OCP_REG_1")
	)
	(via
		(at 430.64557 -107.260898)
		(size 0.508)
		(drill 0.254)
		(layers "F.Cu" "B.Cu")
		(net "P3V3_OCP_REG_1")
	)
	(segment
		(start 88.905842 -60.23102)
		(end 89.28354 -59.853322)
		(width 0.10668)
		(layer "F.Cu")
		(net "P3V3_OCP_PWRGD_2")
	)
	(segment
		(start 89.408 -59.853322)
		(end 89.408 -59.35091)
		(width 0.10668)
		(layer "F.Cu")
		(net "P3V3_OCP_PWRGD_2")
	)
	(segment
		(start 89.676478 -59.082432)
		(end 89.951306 -59.082432)
		(width 0.10668)
		(layer "F.Cu")
		(net "P3V3_OCP_PWRGD_2")
	)
	(segment
		(start 89.28354 -59.853322)
		(end 89.408 -59.853322)
		(width 0.10668)
		(layer "F.Cu")
		(net "P3V3_OCP_PWRGD_2")
	)
	(segment
		(start 88.06053 -60.23102)
		(end 88.905842 -60.23102)
		(width 0.10668)
		(layer "F.Cu")
		(net "P3V3_OCP_PWRGD_2")
	)
	(segment
		(start 89.408 -59.35091)
		(end 89.676478 -59.082432)
		(width 0.10668)
		(layer "F.Cu")
		(net "P3V3_OCP_PWRGD_2")
	)
	(via
		(at 89.408 -59.853322)
		(size 0.508)
		(drill 0.254)
		(layers "F.Cu" "B.Cu")
		(net "P3V3_OCP_PWRGD_2")
	)
	(segment
		(start 431.078894 -103.827326)
		(end 431.078894 -103.276908)
		(width 0.10668)
		(layer "F.Cu")
		(net "P3V3_OCP_PWRGD_1")
	)
	(segment
		(start 429.379634 -103.276908)
		(end 428.880016 -102.77729)
		(width 0.10668)
		(layer "F.Cu")
		(net "P3V3_OCP_PWRGD_1")
	)
	(segment
		(start 431.078894 -103.276908)
		(end 429.379634 -103.276908)
		(width 0.10668)
		(layer "F.Cu")
		(net "P3V3_OCP_PWRGD_1")
	)
	(via
		(at 431.078894 -103.276908)
		(size 0.508)
		(drill 0.254)
		(layers "F.Cu" "B.Cu")
		(net "P3V3_OCP_PWRGD_1")
	)
	(segment
		(start 91.951302 -61.015626)
		(end 92.75064 -61.814964)
		(width 0.10668)
		(layer "F.Cu")
		(net "P3V3_OCP_OV_2")
	)
	(segment
		(start 93.83014 -61.81471)
		(end 93.996256 -61.648594)
		(width 0.10668)
		(layer "F.Cu")
		(net "P3V3_OCP_OV_2")
	)
	(segment
		(start 94.761304 -61.648594)
		(end 93.996256 -61.648594)
		(width 0.10668)
		(layer "F.Cu")
		(net "P3V3_OCP_OV_2")
	)
	(segment
		(start 91.951302 -59.082432)
		(end 91.951302 -61.015626)
		(width 0.10668)
		(layer "F.Cu")
		(net "P3V3_OCP_OV_2")
	)
	(segment
		(start 92.75064 -61.814964)
		(end 92.751148 -61.814964)
		(width 0.10668)
		(layer "F.Cu")
		(net "P3V3_OCP_OV_2")
	)
	(segment
		(start 92.751402 -61.81471)
		(end 93.83014 -61.81471)
		(width 0.10668)
		(layer "F.Cu")
		(net "P3V3_OCP_OV_2")
	)
	(segment
		(start 92.751148 -61.814964)
		(end 92.751402 -61.81471)
		(width 0.10668)
		(layer "F.Cu")
		(net "P3V3_OCP_OV_2")
	)
	(segment
		(start 94.99092 -61.87821)
		(end 94.761304 -61.648594)
		(width 0.10668)
		(layer "F.Cu")
		(net "P3V3_OCP_OV_2")
	)
	(via
		(at 92.751148 -61.814964)
		(size 0.762)
		(drill 0.381)
		(layers "F.Cu" "B.Cu")
		(net "P3V3_OCP_OV_2")
	)
	(segment
		(start 429.597566 -105.827322)
		(end 428.518066 -106.906822)
		(width 0.10668)
		(layer "F.Cu")
		(net "P3V3_OCP_OV_1")
	)
	(segment
		(start 428.518066 -107.87761)
		(end 428.518066 -108.63199)
		(width 0.10668)
		(layer "F.Cu")
		(net "P3V3_OCP_OV_1")
	)
	(segment
		(start 428.518066 -107.866942)
		(end 428.512732 -107.872276)
		(width 0.10668)
		(layer "F.Cu")
		(net "P3V3_OCP_OV_1")
	)
	(segment
		(start 428.512732 -107.872276)
		(end 428.518066 -107.87761)
		(width 0.10668)
		(layer "F.Cu")
		(net "P3V3_OCP_OV_1")
	)
	(segment
		(start 428.518066 -106.906822)
		(end 428.518066 -107.866942)
		(width 0.10668)
		(layer "F.Cu")
		(net "P3V3_OCP_OV_1")
	)
	(segment
		(start 428.518066 -108.63199)
		(end 428.283116 -108.86694)
		(width 0.10668)
		(layer "F.Cu")
		(net "P3V3_OCP_OV_1")
	)
	(segment
		(start 431.078894 -105.827322)
		(end 430.2887 -105.827322)
		(width 0.10668)
		(layer "F.Cu")
		(net "P3V3_OCP_OV_1")
	)
	(segment
		(start 430.2887 -105.827322)
		(end 429.597566 -105.827322)
		(width 0.10668)
		(layer "F.Cu")
		(net "P3V3_OCP_OV_1")
	)
	(via
		(at 430.2887 -105.827322)
		(size 0.508)
		(drill 0.254)
		(layers "F.Cu" "B.Cu")
		(net "P3V3_OCP_OV_1")
	)
	(segment
		(start 90.378788 -71.09587)
		(end 90.764614 -71.481696)
		(width 0.10668)
		(layer "F.Cu")
		(net "P3V3_OCP_MODE_2")
	)
	(segment
		(start 92.113354 -72.111108)
		(end 91.394026 -72.111108)
		(width 0.10668)
		(layer "F.Cu")
		(net "P3V3_OCP_MODE_2")
	)
	(segment
		(start 89.567512 -72.06361)
		(end 89.567512 -71.10095)
		(width 0.10668)
		(layer "F.Cu")
		(net "P3V3_OCP_MODE_2")
	)
	(segment
		(start 91.394026 -72.111108)
		(end 90.764614 -71.481696)
		(width 0.10668)
		(layer "F.Cu")
		(net "P3V3_OCP_MODE_2")
	)
	(segment
		(start 89.567512 -71.10095)
		(end 89.562432 -71.09587)
		(width 0.10668)
		(layer "F.Cu")
		(net "P3V3_OCP_MODE_2")
	)
	(segment
		(start 89.562432 -71.09587)
		(end 90.378788 -71.09587)
		(width 0.10668)
		(layer "F.Cu")
		(net "P3V3_OCP_MODE_2")
	)
	(via
		(at 90.764614 -71.481696)
		(size 0.762)
		(drill 0.381)
		(layers "F.Cu" "B.Cu")
		(net "P3V3_OCP_MODE_2")
	)
	(segment
		(start 421.54094 -101.670358)
		(end 422.55694 -101.670358)
		(width 0.10668)
		(layer "F.Cu")
		(net "P3V3_OCP_MODE_1")
	)
	(segment
		(start 422.04894 -102.921308)
		(end 421.024812 -103.945436)
		(width 0.10668)
		(layer "F.Cu")
		(net "P3V3_OCP_MODE_1")
	)
	(segment
		(start 422.55694 -101.670358)
		(end 422.55694 -102.413308)
		(width 0.10668)
		(layer "F.Cu")
		(net "P3V3_OCP_MODE_1")
	)
	(segment
		(start 422.55694 -102.413308)
		(end 422.04894 -102.921308)
		(width 0.10668)
		(layer "F.Cu")
		(net "P3V3_OCP_MODE_1")
	)
	(segment
		(start 421.024812 -103.945436)
		(end 421.024812 -104.20731)
		(width 0.10668)
		(layer "F.Cu")
		(net "P3V3_OCP_MODE_1")
	)
	(via
		(at 422.04894 -102.921308)
		(size 0.762)
		(drill 0.381)
		(layers "F.Cu" "B.Cu")
		(net "P3V3_OCP_MODE_1")
	)
	(segment
		(start 92.113354 -72.61098)
		(end 91.03233 -72.61098)
		(width 0.10668)
		(layer "F.Cu")
		(net "P3V3_OCP_ILIMIT_2")
	)
	(segment
		(start 90.380312 -73.262998)
		(end 90.777314 -72.865996)
		(width 0.10668)
		(layer "F.Cu")
		(net "P3V3_OCP_ILIMIT_2")
	)
	(segment
		(start 91.03233 -72.61098)
		(end 90.777314 -72.865996)
		(width 0.10668)
		(layer "F.Cu")
		(net "P3V3_OCP_ILIMIT_2")
	)
	(segment
		(start 90.380312 -74.12101)
		(end 90.380312 -73.262998)
		(width 0.10668)
		(layer "F.Cu")
		(net "P3V3_OCP_ILIMIT_2")
	)
	(via
		(at 90.777314 -72.865996)
		(size 0.762)
		(drill 0.381)
		(layers "F.Cu" "B.Cu")
		(net "P3V3_OCP_ILIMIT_2")
	)
	(segment
		(start 420.27094 -102.870508)
		(end 420.52494 -103.124508)
		(width 0.10668)
		(layer "F.Cu")
		(net "P3V3_OCP_ILIMIT_1")
	)
	(segment
		(start 419.76294 -102.362508)
		(end 420.27094 -102.870508)
		(width 0.10668)
		(layer "F.Cu")
		(net "P3V3_OCP_ILIMIT_1")
	)
	(segment
		(start 420.52494 -103.124508)
		(end 420.52494 -104.20731)
		(width 0.10668)
		(layer "F.Cu")
		(net "P3V3_OCP_ILIMIT_1")
	)
	(segment
		(start 419.76294 -101.670358)
		(end 419.76294 -102.362508)
		(width 0.10668)
		(layer "F.Cu")
		(net "P3V3_OCP_ILIMIT_1")
	)
	(via
		(at 420.27094 -102.870508)
		(size 0.762)
		(drill 0.381)
		(layers "F.Cu" "B.Cu")
		(net "P3V3_OCP_ILIMIT_1")
	)
	(segment
		(start 95.551498 -71.21398)
		(end 95.527114 -71.189596)
		(width 0.10668)
		(layer "F.Cu")
		(net "P3V3_OCP_GATE_PU207_2")
	)
	(segment
		(start 94.11335 -72.111108)
		(end 94.605602 -72.111108)
		(width 0.10668)
		(layer "F.Cu")
		(net "P3V3_OCP_GATE_PU207_2")
	)
	(segment
		(start 94.605602 -72.111108)
		(end 95.527114 -71.189596)
		(width 0.10668)
		(layer "F.Cu")
		(net "P3V3_OCP_GATE_PU207_2")
	)
	(segment
		(start 96.777302 -71.21398)
		(end 95.551498 -71.21398)
		(width 0.10668)
		(layer "F.Cu")
		(net "P3V3_OCP_GATE_PU207_2")
	)
	(via
		(at 95.527114 -71.189596)
		(size 0.762)
		(drill 0.381)
		(layers "F.Cu" "B.Cu")
		(net "P3V3_OCP_GATE_PU207_2")
	)
	(segment
		(start 435.623208 -104.168448)
		(end 436.608474 -104.168448)
		(width 0.10668)
		(layer "F.Cu")
		(net "P3V3_OCP_GATE_PU202_1")
	)
	(segment
		(start 435.621176 -104.17048)
		(end 435.623208 -104.168448)
		(width 0.10668)
		(layer "F.Cu")
		(net "P3V3_OCP_GATE_PU202_1")
	)
	(segment
		(start 435.621176 -104.17048)
		(end 434.605176 -104.17048)
		(width 0.10668)
		(layer "F.Cu")
		(net "P3V3_OCP_GATE_PU202_1")
	)
	(segment
		(start 432.579018 -104.327452)
		(end 433.77612 -104.327452)
		(width 0.10668)
		(layer "F.Cu")
		(net "P3V3_OCP_GATE_PU202_1")
	)
	(segment
		(start 434.605176 -104.17048)
		(end 434.448204 -104.327452)
		(width 0.10668)
		(layer "F.Cu")
		(net "P3V3_OCP_GATE_PU202_1")
	)
	(segment
		(start 433.77612 -104.327452)
		(end 434.448204 -104.327452)
		(width 0.10668)
		(layer "F.Cu")
		(net "P3V3_OCP_GATE_PU202_1")
	)
	(via
		(at 433.77612 -104.327452)
		(size 0.508)
		(drill 0.254)
		(layers "F.Cu" "B.Cu")
		(net "P3V3_OCP_GATE_PU202_1")
	)
	(segment
		(start 90.299032 -54.697122)
		(end 90.29446 -54.69255)
		(width 0.10668)
		(layer "F.Cu")
		(net "P3V3_OCP_GATE_2")
	)
	(segment
		(start 90.451432 -56.90743)
		(end 90.40114 -56.857138)
		(width 0.10668)
		(layer "F.Cu")
		(net "P3V3_OCP_GATE_2")
	)
	(segment
		(start 90.299032 -55.713122)
		(end 90.299032 -54.697122)
		(width 0.10668)
		(layer "F.Cu")
		(net "P3V3_OCP_GATE_2")
	)
	(segment
		(start 90.29446 -54.69255)
		(end 90.29446 -53.70195)
		(width 0.10668)
		(layer "F.Cu")
		(net "P3V3_OCP_GATE_2")
	)
	(segment
		(start 90.40114 -56.857138)
		(end 90.299032 -56.75503)
		(width 0.10668)
		(layer "F.Cu")
		(net "P3V3_OCP_GATE_2")
	)
	(segment
		(start 90.29446 -53.70195)
		(end 90.299032 -53.697378)
		(width 0.10668)
		(layer "F.Cu")
		(net "P3V3_OCP_GATE_2")
	)
	(segment
		(start 90.451432 -57.582308)
		(end 90.451432 -56.90743)
		(width 0.10668)
		(layer "F.Cu")
		(net "P3V3_OCP_GATE_2")
	)
	(segment
		(start 90.299032 -56.75503)
		(end 90.299032 -55.713122)
		(width 0.10668)
		(layer "F.Cu")
		(net "P3V3_OCP_GATE_2")
	)
	(via
		(at 90.40114 -56.857138)
		(size 0.508)
		(drill 0.254)
		(layers "F.Cu" "B.Cu")
		(net "P3V3_OCP_GATE_2")
	)
	(segment
		(start 421.94734 -108.845858)
		(end 421.94734 -107.620308)
		(width 0.10668)
		(layer "F.Cu")
		(net "P3V3_OCP_GATE_1")
	)
	(segment
		(start 421.024812 -106.69778)
		(end 421.024812 -106.207306)
		(width 0.10668)
		(layer "F.Cu")
		(net "P3V3_OCP_GATE_1")
	)
	(segment
		(start 421.92194 -108.871258)
		(end 421.94734 -108.845858)
		(width 0.10668)
		(layer "F.Cu")
		(net "P3V3_OCP_GATE_1")
	)
	(segment
		(start 421.94734 -107.620308)
		(end 421.024812 -106.69778)
		(width 0.10668)
		(layer "F.Cu")
		(net "P3V3_OCP_GATE_1")
	)
	(via
		(at 421.94734 -107.620308)
		(size 0.762)
		(drill 0.381)
		(layers "F.Cu" "B.Cu")
		(net "P3V3_OCP_GATE_1")
	)
	(segment
		(start 89.408 -58.583322)
		(end 89.409016 -58.582306)
		(width 0.10668)
		(layer "F.Cu")
		(net "P3V3_OCP_FAULT_2")
	)
	(segment
		(start 88.368378 -57.16778)
		(end 89.408 -58.207402)
		(width 0.10668)
		(layer "F.Cu")
		(net "P3V3_OCP_FAULT_2")
	)
	(segment
		(start 89.408 -58.207402)
		(end 89.408 -58.583322)
		(width 0.10668)
		(layer "F.Cu")
		(net "P3V3_OCP_FAULT_2")
	)
	(segment
		(start 89.409016 -58.582306)
		(end 89.951306 -58.582306)
		(width 0.10668)
		(layer "F.Cu")
		(net "P3V3_OCP_FAULT_2")
	)
	(segment
		(start 87.957914 -57.16778)
		(end 88.368378 -57.16778)
		(width 0.10668)
		(layer "F.Cu")
		(net "P3V3_OCP_FAULT_2")
	)
	(via
		(at 89.408 -58.583322)
		(size 0.508)
		(drill 0.254)
		(layers "F.Cu" "B.Cu")
		(net "P3V3_OCP_FAULT_2")
	)
	(segment
		(start 431.57902 -103.650288)
		(end 431.57902 -103.827326)
		(width 0.10668)
		(layer "F.Cu")
		(net "P3V3_OCP_FAULT_1")
	)
	(segment
		(start 432.551586 -102.677722)
		(end 431.57902 -103.650288)
		(width 0.10668)
		(layer "F.Cu")
		(net "P3V3_OCP_FAULT_1")
	)
	(segment
		(start 432.551586 -101.97719)
		(end 432.551586 -102.677722)
		(width 0.10668)
		(layer "F.Cu")
		(net "P3V3_OCP_FAULT_1")
	)
	(via
		(at 432.551586 -102.677722)
		(size 0.508)
		(drill 0.254)
		(layers "F.Cu" "B.Cu")
		(net "P3V3_OCP_FAULT_1")
	)
	(segment
		(start 59.574684 -40.404034)
		(end 60.298584 -41.127934)
		(width 0.10668)
		(layer "F.Cu")
		(net "P3V3_OCP_EN_2_R")
	)
	(segment
		(start 59.309762 -40.380666)
		(end 59.33313 -40.404034)
		(width 0.10668)
		(layer "F.Cu")
		(net "P3V3_OCP_EN_2_R")
	)
	(segment
		(start 61.063378 -40.031162)
		(end 61.53277 -40.031162)
		(width 0.10668)
		(layer "F.Cu")
		(net "P3V3_OCP_EN_2_R")
	)
	(segment
		(start 59.309762 -39.878)
		(end 59.309762 -40.380666)
		(width 0.10668)
		(layer "F.Cu")
		(net "P3V3_OCP_EN_2_R")
	)
	(segment
		(start 59.33313 -40.404034)
		(end 59.574684 -40.404034)
		(width 0.10668)
		(layer "F.Cu")
		(net "P3V3_OCP_EN_2_R")
	)
	(segment
		(start 60.888118 -40.206422)
		(end 61.063378 -40.031162)
		(width 0.10668)
		(layer "F.Cu")
		(net "P3V3_OCP_EN_2_R")
	)
	(segment
		(start 60.298584 -41.64711)
		(end 60.888118 -41.057576)
		(width 0.10668)
		(layer "F.Cu")
		(net "P3V3_OCP_EN_2_R")
	)
	(segment
		(start 60.888118 -41.057576)
		(end 60.888118 -40.206422)
		(width 0.10668)
		(layer "F.Cu")
		(net "P3V3_OCP_EN_2_R")
	)
	(segment
		(start 58.297064 -39.404036)
		(end 58.300112 -39.407084)
		(width 0.10668)
		(layer "F.Cu")
		(net "P3V3_OCP_EN_2_R")
	)
	(segment
		(start 57.93867 -39.76243)
		(end 58.297064 -39.404036)
		(width 0.10668)
		(layer "F.Cu")
		(net "P3V3_OCP_EN_2_R")
	)
	(segment
		(start 58.300112 -39.407084)
		(end 59.33313 -39.407084)
		(width 0.10668)
		(layer "F.Cu")
		(net "P3V3_OCP_EN_2_R")
	)
	(segment
		(start 59.33313 -39.407084)
		(end 59.33313 -39.854632)
		(width 0.10668)
		(layer "F.Cu")
		(net "P3V3_OCP_EN_2_R")
	)
	(segment
		(start 57.17286 -39.76243)
		(end 57.93867 -39.76243)
		(width 0.10668)
		(layer "F.Cu")
		(net "P3V3_OCP_EN_2_R")
	)
	(segment
		(start 60.298584 -41.127934)
		(end 60.298584 -41.64711)
		(width 0.10668)
		(layer "F.Cu")
		(net "P3V3_OCP_EN_2_R")
	)
	(segment
		(start 59.33313 -39.854632)
		(end 59.309762 -39.878)
		(width 0.10668)
		(layer "F.Cu")
		(net "P3V3_OCP_EN_2_R")
	)
	(via
		(at 60.298584 -41.64711)
		(size 0.762)
		(drill 0.381)
		(layers "F.Cu" "B.Cu")
		(net "P3V3_OCP_EN_2_R")
	)
	(segment
		(start 96.777302 -72.571102)
		(end 96.904302 -72.444102)
		(width 0.10668)
		(layer "F.Cu")
		(net "P3V3_OCP_EN_2")
	)
	(segment
		(start 95.65513 -72.99198)
		(end 95.527114 -73.119996)
		(width 0.10668)
		(layer "F.Cu")
		(net "P3V3_OCP_EN_2")
	)
	(segment
		(start 95.527114 -73.119996)
		(end 95.524066 -73.116948)
		(width 0.10668)
		(layer "F.Cu")
		(net "P3V3_OCP_EN_2")
	)
	(segment
		(start 56.458358 -34.697162)
		(end 56.458358 -36.75634)
		(width 0.10668)
		(layer "F.Cu")
		(net "P3V3_OCP_EN_2")
	)
	(segment
		(start 97.80016 -72.444102)
		(end 99.036632 -71.20763)
		(width 0.10668)
		(layer "F.Cu")
		(net "P3V3_OCP_EN_2")
	)
	(segment
		(start 96.904302 -72.444102)
		(end 97.80016 -72.444102)
		(width 0.10668)
		(layer "F.Cu")
		(net "P3V3_OCP_EN_2")
	)
	(segment
		(start 99.036632 -71.20763)
		(end 99.037648 -71.20763)
		(width 0.10668)
		(layer "F.Cu")
		(net "P3V3_OCP_EN_2")
	)
	(segment
		(start 59.520074 -27.485594)
		(end 60.452 -28.41752)
		(width 0.10668)
		(layer "F.Cu")
		(net "P3V3_OCP_EN_2")
	)
	(segment
		(start 94.404688 -72.61098)
		(end 94.11335 -72.61098)
		(width 0.10668)
		(layer "F.Cu")
		(net "P3V3_OCP_EN_2")
	)
	(segment
		(start 58.57494 -31.72206)
		(end 58.57494 -32.58058)
		(width 0.10668)
		(layer "F.Cu")
		(net "P3V3_OCP_EN_2")
	)
	(segment
		(start 94.910656 -73.116948)
		(end 94.404688 -72.61098)
		(width 0.10668)
		(layer "F.Cu")
		(net "P3V3_OCP_EN_2")
	)
	(segment
		(start 96.777302 -72.99198)
		(end 95.65513 -72.99198)
		(width 0.10668)
		(layer "F.Cu")
		(net "P3V3_OCP_EN_2")
	)
	(segment
		(start 95.524066 -73.116948)
		(end 94.910656 -73.116948)
		(width 0.10668)
		(layer "F.Cu")
		(net "P3V3_OCP_EN_2")
	)
	(segment
		(start 96.777302 -72.99198)
		(end 96.777302 -72.571102)
		(width 0.10668)
		(layer "F.Cu")
		(net "P3V3_OCP_EN_2")
	)
	(segment
		(start 58.57494 -32.58058)
		(end 56.458358 -34.697162)
		(width 0.10668)
		(layer "F.Cu")
		(net "P3V3_OCP_EN_2")
	)
	(segment
		(start 60.452 -28.41752)
		(end 60.452 -29.845)
		(width 0.10668)
		(layer "F.Cu")
		(net "P3V3_OCP_EN_2")
	)
	(segment
		(start 60.452 -29.845)
		(end 58.57494 -31.72206)
		(width 0.10668)
		(layer "F.Cu")
		(net "P3V3_OCP_EN_2")
	)
	(segment
		(start 59.520074 -26.234644)
		(end 59.520074 -27.485594)
		(width 0.10668)
		(layer "F.Cu")
		(net "P3V3_OCP_EN_2")
	)
	(via
		(at 59.520074 -26.234644)
		(size 0.508)
		(drill 0.254)
		(layers "F.Cu" "B.Cu")
		(net "P3V3_OCP_EN_2")
	)
	(via
		(at 99.037648 -71.20763)
		(size 0.508)
		(drill 0.254)
		(layers "F.Cu" "B.Cu")
		(net "P3V3_OCP_EN_2")
	)
	(via
		(at 95.527114 -73.119996)
		(size 0.762)
		(drill 0.381)
		(layers "F.Cu" "B.Cu")
		(net "P3V3_OCP_EN_2")
	)
	(segment
		(start 60.904628 -27.619198)
		(end 62.518544 -27.619198)
		(width 0.10668)
		(layer "B.Cu")
		(net "P3V3_OCP_EN_2")
	)
	(segment
		(start 59.520074 -26.234644)
		(end 60.904628 -27.619198)
		(width 0.10668)
		(layer "B.Cu")
		(net "P3V3_OCP_EN_2")
	)
	(segment
		(start 62.518544 -27.619198)
		(end 62.794388 -27.895042)
		(width 0.10668)
		(layer "B.Cu")
		(net "P3V3_OCP_EN_2")
	)
	(segment
		(start 62.794388 -27.895042)
		(end 62.794388 -28.382722)
		(width 0.10668)
		(layer "B.Cu")
		(net "P3V3_OCP_EN_2")
	)
	(segment
		(start 98.003614 -53.6448)
		(end 87.687404 -53.6448)
		(width 0.11684)
		(layer "In6.Cu")
		(net "P3V3_OCP_EN_2")
	)
	(segment
		(start 58.990738 -26.234644)
		(end 59.520074 -26.234644)
		(width 0.11684)
		(layer "In6.Cu")
		(net "P3V3_OCP_EN_2")
	)
	(segment
		(start 99.037648 -71.20763)
		(end 99.037648 -71.206614)
		(width 0.11684)
		(layer "In6.Cu")
		(net "P3V3_OCP_EN_2")
	)
	(segment
		(start 100.164646 -70.079616)
		(end 100.164646 -55.805832)
		(width 0.11684)
		(layer "In6.Cu")
		(net "P3V3_OCP_EN_2")
	)
	(segment
		(start 77.031596 -42.988992)
		(end 56.85282 -42.988992)
		(width 0.11684)
		(layer "In6.Cu")
		(net "P3V3_OCP_EN_2")
	)
	(segment
		(start 51.29149 -35.107118)
		(end 56.232806 -30.165802)
		(width 0.11684)
		(layer "In6.Cu")
		(net "P3V3_OCP_EN_2")
	)
	(segment
		(start 100.164646 -55.805832)
		(end 98.003614 -53.6448)
		(width 0.11684)
		(layer "In6.Cu")
		(net "P3V3_OCP_EN_2")
	)
	(segment
		(start 56.232806 -28.992576)
		(end 58.990738 -26.234644)
		(width 0.11684)
		(layer "In6.Cu")
		(net "P3V3_OCP_EN_2")
	)
	(segment
		(start 99.037648 -71.206614)
		(end 100.164646 -70.079616)
		(width 0.11684)
		(layer "In6.Cu")
		(net "P3V3_OCP_EN_2")
	)
	(segment
		(start 56.232806 -30.165802)
		(end 56.232806 -28.992576)
		(width 0.11684)
		(layer "In6.Cu")
		(net "P3V3_OCP_EN_2")
	)
	(segment
		(start 51.29149 -37.427662)
		(end 51.29149 -35.107118)
		(width 0.11684)
		(layer "In6.Cu")
		(net "P3V3_OCP_EN_2")
	)
	(segment
		(start 56.85282 -42.988992)
		(end 51.29149 -37.427662)
		(width 0.11684)
		(layer "In6.Cu")
		(net "P3V3_OCP_EN_2")
	)
	(segment
		(start 87.687404 -53.6448)
		(end 77.031596 -42.988992)
		(width 0.11684)
		(layer "In6.Cu")
		(net "P3V3_OCP_EN_2")
	)
	(segment
		(start 420.01694 -107.620308)
		(end 420.01694 -108.785406)
		(width 0.10668)
		(layer "F.Cu")
		(net "P3V3_OCP_EN_1_R2")
	)
	(segment
		(start 420.06266 -108.831126)
		(end 421.01643 -108.831126)
		(width 0.10668)
		(layer "F.Cu")
		(net "P3V3_OCP_EN_1_R2")
	)
	(segment
		(start 420.01694 -107.112562)
		(end 420.01694 -107.620308)
		(width 0.10668)
		(layer "F.Cu")
		(net "P3V3_OCP_EN_1_R2")
	)
	(segment
		(start 420.52494 -106.604562)
		(end 420.01694 -107.112562)
		(width 0.10668)
		(layer "F.Cu")
		(net "P3V3_OCP_EN_1_R2")
	)
	(segment
		(start 420.52494 -106.207306)
		(end 420.52494 -106.604562)
		(width 0.10668)
		(layer "F.Cu")
		(net "P3V3_OCP_EN_1_R2")
	)
	(segment
		(start 420.01694 -108.785406)
		(end 420.06266 -108.831126)
		(width 0.10668)
		(layer "F.Cu")
		(net "P3V3_OCP_EN_1_R2")
	)
	(segment
		(start 419.10889 -108.831126)
		(end 420.06266 -108.831126)
		(width 0.10668)
		(layer "F.Cu")
		(net "P3V3_OCP_EN_1_R2")
	)
	(via
		(at 420.01694 -107.620308)
		(size 0.762)
		(drill 0.381)
		(layers "F.Cu" "B.Cu")
		(net "P3V3_OCP_EN_1_R2")
	)
	(segment
		(start 453.169782 -42.157396)
		(end 453.609456 -42.59707)
		(width 0.10668)
		(layer "F.Cu")
		(net "P3V3_OCP_EN_1_R")
	)
	(segment
		(start 453.609456 -42.59707)
		(end 454.937876 -42.59707)
		(width 0.10668)
		(layer "F.Cu")
		(net "P3V3_OCP_EN_1_R")
	)
	(segment
		(start 451.96252 -40.61714)
		(end 452.22287 -40.35679)
		(width 0.10668)
		(layer "F.Cu")
		(net "P3V3_OCP_EN_1_R")
	)
	(segment
		(start 451.96252 -41.89984)
		(end 451.96252 -40.61714)
		(width 0.10668)
		(layer "F.Cu")
		(net "P3V3_OCP_EN_1_R")
	)
	(segment
		(start 455.41311 -41.105836)
		(end 456.63231 -41.105836)
		(width 0.10668)
		(layer "F.Cu")
		(net "P3V3_OCP_EN_1_R")
	)
	(segment
		(start 452.220076 -42.157396)
		(end 451.96252 -41.89984)
		(width 0.10668)
		(layer "F.Cu")
		(net "P3V3_OCP_EN_1_R")
	)
	(segment
		(start 454.937876 -42.59707)
		(end 455.41311 -42.121836)
		(width 0.10668)
		(layer "F.Cu")
		(net "P3V3_OCP_EN_1_R")
	)
	(segment
		(start 455.41311 -42.121836)
		(end 455.41311 -41.105836)
		(width 0.10668)
		(layer "F.Cu")
		(net "P3V3_OCP_EN_1_R")
	)
	(segment
		(start 457.85151 -41.105836)
		(end 456.63231 -41.105836)
		(width 0.10668)
		(layer "F.Cu")
		(net "P3V3_OCP_EN_1_R")
	)
	(segment
		(start 453.169782 -42.157396)
		(end 452.220076 -42.157396)
		(width 0.10668)
		(layer "F.Cu")
		(net "P3V3_OCP_EN_1_R")
	)
	(segment
		(start 452.22287 -40.35679)
		(end 453.169782 -40.35679)
		(width 0.10668)
		(layer "F.Cu")
		(net "P3V3_OCP_EN_1_R")
	)
	(via
		(at 456.63231 -41.105836)
		(size 0.762)
		(drill 0.381)
		(layers "F.Cu" "B.Cu")
		(net "P3V3_OCP_EN_1_R")
	)
	(segment
		(start 172.595794 -113.24082)
		(end 171.714922 -112.359948)
		(width 0.10668)
		(layer "F.Cu")
		(net "P3V3_OCP_SFF_EN")
	)
	(segment
		(start 171.714922 -112.359948)
		(end 171.59605 -112.359948)
		(width 0.10668)
		(layer "F.Cu")
		(net "P3V3_OCP_SFF_EN")
	)
	(segment
		(start 176.05502 -113.24082)
		(end 173.5836 -113.24082)
		(width 0.10668)
		(layer "F.Cu")
		(net "P3V3_OCP_SFF_EN")
	)
	(segment
		(start 177.922174 -113.05286)
		(end 177.525934 -112.65662)
		(width 0.10668)
		(layer "F.Cu")
		(net "P3V3_OCP_SFF_EN")
	)
	(segment
		(start 176.63922 -112.65662)
		(end 176.05502 -113.24082)
		(width 0.10668)
		(layer "F.Cu")
		(net "P3V3_OCP_SFF_EN")
	)
	(segment
		(start 173.5836 -113.24082)
		(end 172.595794 -113.24082)
		(width 0.10668)
		(layer "F.Cu")
		(net "P3V3_OCP_SFF_EN")
	)
	(segment
		(start 177.525934 -112.65662)
		(end 176.63922 -112.65662)
		(width 0.10668)
		(layer "F.Cu")
		(net "P3V3_OCP_SFF_EN")
	)
	(via
		(at 173.5836 -113.24082)
		(size 0.762)
		(drill 0.381)
		(layers "F.Cu" "B.Cu")
		(net "P3V3_OCP_SFF_EN")
	)
	(segment
		(start 95.527114 -75.050396)
		(end 96.496886 -75.050396)
		(width 0.10668)
		(layer "F.Cu")
		(net "P3V3_OCP_DVDT_2")
	)
	(segment
		(start 95.527114 -75.050396)
		(end 94.691708 -74.21499)
		(width 0.10668)
		(layer "F.Cu")
		(net "P3V3_OCP_DVDT_2")
	)
	(segment
		(start 94.691708 -74.21499)
		(end 94.691708 -73.45934)
		(width 0.10668)
		(layer "F.Cu")
		(net "P3V3_OCP_DVDT_2")
	)
	(segment
		(start 94.691708 -73.45934)
		(end 94.34322 -73.110852)
		(width 0.10668)
		(layer "F.Cu")
		(net "P3V3_OCP_DVDT_2")
	)
	(segment
		(start 96.496886 -75.050396)
		(end 96.777302 -74.76998)
		(width 0.10668)
		(layer "F.Cu")
		(net "P3V3_OCP_DVDT_2")
	)
	(segment
		(start 94.34322 -73.110852)
		(end 94.11335 -73.110852)
		(width 0.10668)
		(layer "F.Cu")
		(net "P3V3_OCP_DVDT_2")
	)
	(via
		(at 95.527114 -75.050396)
		(size 0.762)
		(drill 0.381)
		(layers "F.Cu" "B.Cu")
		(net "P3V3_OCP_DVDT_2")
	)
	(segment
		(start 418.84854 -106.858308)
		(end 418.08654 -107.620308)
		(width 0.10668)
		(layer "F.Cu")
		(net "P3V3_OCP_DVDT_1")
	)
	(segment
		(start 419.63594 -106.858308)
		(end 418.84854 -106.858308)
		(width 0.10668)
		(layer "F.Cu")
		(net "P3V3_OCP_DVDT_1")
	)
	(segment
		(start 418.08654 -107.620308)
		(end 418.08654 -108.704126)
		(width 0.10668)
		(layer "F.Cu")
		(net "P3V3_OCP_DVDT_1")
	)
	(segment
		(start 418.08654 -108.704126)
		(end 418.21354 -108.831126)
		(width 0.10668)
		(layer "F.Cu")
		(net "P3V3_OCP_DVDT_1")
	)
	(segment
		(start 420.025068 -106.207306)
		(end 420.025068 -106.46918)
		(width 0.10668)
		(layer "F.Cu")
		(net "P3V3_OCP_DVDT_1")
	)
	(segment
		(start 420.025068 -106.46918)
		(end 419.63594 -106.858308)
		(width 0.10668)
		(layer "F.Cu")
		(net "P3V3_OCP_DVDT_1")
	)
	(via
		(at 418.08654 -107.620308)
		(size 0.762)
		(drill 0.381)
		(layers "F.Cu" "B.Cu")
		(net "P3V3_OCP_DVDT_1")
	)
	(segment
		(start 92.951554 -58.082434)
		(end 93.991938 -58.082434)
		(width 0.10668)
		(layer "F.Cu")
		(net "P3V3_OCP_CB_2")
	)
	(segment
		(start 93.991938 -58.082434)
		(end 94.063058 -58.153554)
		(width 0.10668)
		(layer "F.Cu")
		(net "P3V3_OCP_CB_2")
	)
	(segment
		(start 94.783656 -58.153554)
		(end 94.86138 -58.07583)
		(width 0.10668)
		(layer "F.Cu")
		(net "P3V3_OCP_CB_2")
	)
	(segment
		(start 94.063058 -58.153554)
		(end 94.783656 -58.153554)
		(width 0.10668)
		(layer "F.Cu")
		(net "P3V3_OCP_CB_2")
	)
	(via
		(at 94.063058 -58.153554)
		(size 0.508)
		(drill 0.254)
		(layers "F.Cu" "B.Cu")
		(net "P3V3_OCP_CB_2")
	)
	(segment
		(start 432.085496 -106.834178)
		(end 432.078892 -106.827574)
		(width 0.10668)
		(layer "F.Cu")
		(net "P3V3_OCP_CB_1")
	)
	(segment
		(start 432.085496 -107.645708)
		(end 432.085496 -106.834178)
		(width 0.10668)
		(layer "F.Cu")
		(net "P3V3_OCP_CB_1")
	)
	(segment
		(start 432.085496 -108.7374)
		(end 432.085496 -107.645708)
		(width 0.10668)
		(layer "F.Cu")
		(net "P3V3_OCP_CB_1")
	)
	(via
		(at 432.085496 -107.645708)
		(size 0.508)
		(drill 0.254)
		(layers "F.Cu" "B.Cu")
		(net "P3V3_OCP_CB_1")
	)
	(segment
		(start 65.691766 -41.537128)
		(end 63.662306 -41.537128)
		(width 0.10668)
		(layer "F.Cu")
		(net "P3V3_OCP_2_EN_G")
	)
	(segment
		(start 64.708024 -40.608758)
		(end 65.018666 -40.9194)
		(width 0.10668)
		(layer "F.Cu")
		(net "P3V3_OCP_2_EN_G")
	)
	(segment
		(start 63.028576 -40.031162)
		(end 63.43269 -40.031162)
		(width 0.10668)
		(layer "F.Cu")
		(net "P3V3_OCP_2_EN_G")
	)
	(segment
		(start 62.904116 -40.155622)
		(end 63.028576 -40.031162)
		(width 0.10668)
		(layer "F.Cu")
		(net "P3V3_OCP_2_EN_G")
	)
	(segment
		(start 62.904116 -40.537384)
		(end 62.904116 -40.155622)
		(width 0.10668)
		(layer "F.Cu")
		(net "P3V3_OCP_2_EN_G")
	)
	(segment
		(start 63.43269 -41.307512)
		(end 63.43269 -40.681148)
		(width 0.10668)
		(layer "F.Cu")
		(net "P3V3_OCP_2_EN_G")
	)
	(segment
		(start 65.911984 -41.31691)
		(end 65.691766 -41.537128)
		(width 0.10668)
		(layer "F.Cu")
		(net "P3V3_OCP_2_EN_G")
	)
	(segment
		(start 65.514474 -40.9194)
		(end 65.911984 -41.31691)
		(width 0.10668)
		(layer "F.Cu")
		(net "P3V3_OCP_2_EN_G")
	)
	(segment
		(start 63.43269 -40.681148)
		(end 63.04788 -40.681148)
		(width 0.10668)
		(layer "F.Cu")
		(net "P3V3_OCP_2_EN_G")
	)
	(segment
		(start 65.018666 -40.9194)
		(end 65.514474 -40.9194)
		(width 0.10668)
		(layer "F.Cu")
		(net "P3V3_OCP_2_EN_G")
	)
	(segment
		(start 63.662306 -41.537128)
		(end 63.43269 -41.307512)
		(width 0.10668)
		(layer "F.Cu")
		(net "P3V3_OCP_2_EN_G")
	)
	(segment
		(start 63.04788 -40.681148)
		(end 62.904116 -40.537384)
		(width 0.10668)
		(layer "F.Cu")
		(net "P3V3_OCP_2_EN_G")
	)
	(via
		(at 65.911984 -41.31691)
		(size 0.762)
		(drill 0.381)
		(layers "F.Cu" "B.Cu")
		(net "P3V3_OCP_2_EN_G")
	)
	(segment
		(start 460.337154 -41.755822)
		(end 460.98587 -42.404538)
		(width 0.10668)
		(layer "F.Cu")
		(net "P3V3_OCP_1_EN_G")
	)
	(segment
		(start 459.75143 -41.755822)
		(end 459.75143 -41.105836)
		(width 0.10668)
		(layer "F.Cu")
		(net "P3V3_OCP_1_EN_G")
	)
	(segment
		(start 459.75143 -41.755822)
		(end 460.337154 -41.755822)
		(width 0.10668)
		(layer "F.Cu")
		(net "P3V3_OCP_1_EN_G")
	)
	(segment
		(start 462.20507 -42.404538)
		(end 460.98587 -42.404538)
		(width 0.10668)
		(layer "F.Cu")
		(net "P3V3_OCP_1_EN_G")
	)
	(via
		(at 460.98587 -42.404538)
		(size 0.762)
		(drill 0.381)
		(layers "F.Cu" "B.Cu")
		(net "P3V3_OCP_1_EN_G")
	)
	(segment
		(start 149.91969 -102.688898)
		(end 149.27834 -102.688898)
		(width 0.381)
		(layer "F.Cu")
		(net "P3V3_M2_0")
	)
	(via
		(at 168.346374 -52.796948)
		(size 0.508)
		(drill 0.254)
		(layers "F.Cu" "B.Cu")
		(net "P3V3_M2_0")
	)
	(via
		(at 167.609774 -53.533548)
		(size 0.508)
		(drill 0.254)
		(layers "F.Cu" "B.Cu")
		(net "P3V3_M2_0")
	)
	(via
		(at 149.27834 -102.688898)
		(size 0.508)
		(drill 0.254)
		(layers "F.Cu" "B.Cu")
		(net "P3V3_M2_0")
	)
	(via
		(at 167.609774 -52.898548)
		(size 0.508)
		(drill 0.254)
		(layers "F.Cu" "B.Cu")
		(net "P3V3_M2_0")
	)
	(via
		(at 169.075354 -37.513768)
		(size 0.508)
		(drill 0.254)
		(layers "F.Cu" "B.Cu")
		(net "P3V3_M2_0")
	)
	(via
		(at 168.371774 -38.077648)
		(size 0.508)
		(drill 0.254)
		(layers "F.Cu" "B.Cu")
		(net "P3V3_M2_0")
	)
	(via
		(at 167.609774 -52.263548)
		(size 0.508)
		(drill 0.254)
		(layers "F.Cu" "B.Cu")
		(net "P3V3_M2_0")
	)
	(via
		(at 168.371774 -37.315648)
		(size 0.508)
		(drill 0.254)
		(layers "F.Cu" "B.Cu")
		(net "P3V3_M2_0")
	)
	(via
		(at 168.346374 -53.431948)
		(size 0.508)
		(drill 0.254)
		(layers "F.Cu" "B.Cu")
		(net "P3V3_M2_0")
	)
	(via
		(at 168.346374 -52.161948)
		(size 0.508)
		(drill 0.254)
		(layers "F.Cu" "B.Cu")
		(net "P3V3_M2_0")
	)
	(via
		(at 162.581336 -57.686702)
		(size 0.508)
		(drill 0.254)
		(layers "F.Cu" "B.Cu")
		(net "P3V3_M2_0")
	)
	(segment
		(start 160.699704 -67.92341)
		(end 156.49067 -72.132444)
		(width 0.508)
		(layer "In11.Cu")
		(net "P3V3_M2_0")
	)
	(segment
		(start 150.641558 -101.32568)
		(end 149.27834 -102.688898)
		(width 0.508)
		(layer "In11.Cu")
		(net "P3V3_M2_0")
	)
	(segment
		(start 162.581336 -57.686702)
		(end 160.699704 -59.568334)
		(width 0.508)
		(layer "In11.Cu")
		(net "P3V3_M2_0")
	)
	(segment
		(start 150.641558 -92.924122)
		(end 150.641558 -101.32568)
		(width 0.508)
		(layer "In11.Cu")
		(net "P3V3_M2_0")
	)
	(segment
		(start 156.49067 -72.132444)
		(end 156.49067 -87.07501)
		(width 0.508)
		(layer "In11.Cu")
		(net "P3V3_M2_0")
	)
	(segment
		(start 160.699704 -59.568334)
		(end 160.699704 -67.92341)
		(width 0.508)
		(layer "In11.Cu")
		(net "P3V3_M2_0")
	)
	(segment
		(start 156.49067 -87.07501)
		(end 150.641558 -92.924122)
		(width 0.508)
		(layer "In11.Cu")
		(net "P3V3_M2_0")
	)
	(segment
		(start 220.374972 -73.1012)
		(end 220.374972 -73.484994)
		(width 0.10668)
		(layer "F.Cu")
		(net "P3V3_E1S_VCC_0")
	)
	(segment
		(start 220.363034 -73.496932)
		(end 220.374972 -73.484994)
		(width 0.10668)
		(layer "F.Cu")
		(net "P3V3_E1S_VCC_0")
	)
	(segment
		(start 220.121226 -72.560434)
		(end 220.121226 -72.847454)
		(width 0.10668)
		(layer "F.Cu")
		(net "P3V3_E1S_VCC_0")
	)
	(segment
		(start 220.821504 -71.860156)
		(end 220.121226 -72.560434)
		(width 0.10668)
		(layer "F.Cu")
		(net "P3V3_E1S_VCC_0")
	)
	(segment
		(start 220.821504 -71.62038)
		(end 220.821504 -71.860156)
		(width 0.10668)
		(layer "F.Cu")
		(net "P3V3_E1S_VCC_0")
	)
	(segment
		(start 220.363034 -74.62774)
		(end 220.363034 -73.496932)
		(width 0.10668)
		(layer "F.Cu")
		(net "P3V3_E1S_VCC_0")
	)
	(segment
		(start 220.121226 -72.847454)
		(end 220.374972 -73.1012)
		(width 0.10668)
		(layer "F.Cu")
		(net "P3V3_E1S_VCC_0")
	)
	(via
		(at 220.121226 -72.847454)
		(size 0.508)
		(drill 0.254)
		(layers "F.Cu" "B.Cu")
		(net "P3V3_E1S_VCC_0")
	)
	(segment
		(start 253.413006 -68.296536)
		(end 249.484896 -68.296536)
		(width 0.10668)
		(layer "F.Cu")
		(net "P3V3_E1S_UV_0_R")
	)
	(segment
		(start 249.484896 -68.296536)
		(end 248.480326 -67.291966)
		(width 0.10668)
		(layer "F.Cu")
		(net "P3V3_E1S_UV_0_R")
	)
	(via
		(at 248.480326 -67.291966)
		(size 0.508)
		(drill 0.254)
		(layers "F.Cu" "B.Cu")
		(net "P3V3_E1S_UV_0_R")
	)
	(via
		(at 220.396054 -67.954398)
		(size 0.508)
		(drill 0.254)
		(layers "F.Cu" "B.Cu")
		(net "P3V3_E1S_UV_0_R")
	)
	(segment
		(start 219.745052 -67.260978)
		(end 220.396054 -67.91198)
		(width 0.10668)
		(layer "B.Cu")
		(net "P3V3_E1S_UV_0_R")
	)
	(segment
		(start 219.082112 -67.260978)
		(end 219.745052 -67.260978)
		(width 0.10668)
		(layer "B.Cu")
		(net "P3V3_E1S_UV_0_R")
	)
	(segment
		(start 220.396054 -67.91198)
		(end 220.396054 -67.954398)
		(width 0.10668)
		(layer "B.Cu")
		(net "P3V3_E1S_UV_0_R")
	)
	(segment
		(start 220.396054 -67.247008)
		(end 221.003622 -66.63944)
		(width 0.11684)
		(layer "In2.Cu")
		(net "P3V3_E1S_UV_0_R")
	)
	(segment
		(start 247.258332 -66.069972)
		(end 248.480326 -67.291966)
		(width 0.11684)
		(layer "In2.Cu")
		(net "P3V3_E1S_UV_0_R")
	)
	(segment
		(start 220.396054 -67.954398)
		(end 220.396054 -67.247008)
		(width 0.11684)
		(layer "In2.Cu")
		(net "P3V3_E1S_UV_0_R")
	)
	(segment
		(start 225.696018 -66.63944)
		(end 226.265486 -66.069972)
		(width 0.11684)
		(layer "In2.Cu")
		(net "P3V3_E1S_UV_0_R")
	)
	(segment
		(start 226.265486 -66.069972)
		(end 247.258332 -66.069972)
		(width 0.11684)
		(layer "In2.Cu")
		(net "P3V3_E1S_UV_0_R")
	)
	(segment
		(start 221.003622 -66.63944)
		(end 225.696018 -66.63944)
		(width 0.11684)
		(layer "In2.Cu")
		(net "P3V3_E1S_UV_0_R")
	)
	(segment
		(start 220.821504 -70.120256)
		(end 220.821504 -69.69125)
		(width 0.10668)
		(layer "F.Cu")
		(net "P3V3_E1S_UV_0")
	)
	(segment
		(start 218.282012 -68.340478)
		(end 219.26296 -68.340478)
		(width 0.10668)
		(layer "F.Cu")
		(net "P3V3_E1S_UV_0")
	)
	(segment
		(start 219.26296 -68.340478)
		(end 219.276676 -68.354194)
		(width 0.10668)
		(layer "F.Cu")
		(net "P3V3_E1S_UV_0")
	)
	(segment
		(start 219.484448 -68.354194)
		(end 219.276676 -68.354194)
		(width 0.10668)
		(layer "F.Cu")
		(net "P3V3_E1S_UV_0")
	)
	(segment
		(start 220.821504 -69.69125)
		(end 220.498416 -69.368162)
		(width 0.10668)
		(layer "F.Cu")
		(net "P3V3_E1S_UV_0")
	)
	(segment
		(start 220.498416 -69.368162)
		(end 219.484448 -68.354194)
		(width 0.10668)
		(layer "F.Cu")
		(net "P3V3_E1S_UV_0")
	)
	(via
		(at 220.498416 -69.368162)
		(size 0.508)
		(drill 0.254)
		(layers "F.Cu" "B.Cu")
		(net "P3V3_E1S_UV_0")
	)
	(segment
		(start 219.191332 -68.061078)
		(end 220.498416 -69.368162)
		(width 0.10668)
		(layer "B.Cu")
		(net "P3V3_E1S_UV_0")
	)
	(segment
		(start 219.082112 -68.061078)
		(end 219.191332 -68.061078)
		(width 0.10668)
		(layer "B.Cu")
		(net "P3V3_E1S_UV_0")
	)
	(segment
		(start 217.485976 -72.757538)
		(end 217.953336 -72.757538)
		(width 0.10668)
		(layer "F.Cu")
		(net "P3V3_E1S_SENSE_0")
	)
	(segment
		(start 220.321378 -71.62038)
		(end 219.9259 -72.015858)
		(width 0.10668)
		(layer "F.Cu")
		(net "P3V3_E1S_SENSE_0")
	)
	(segment
		(start 217.953336 -72.757538)
		(end 218.411552 -72.299322)
		(width 0.10668)
		(layer "F.Cu")
		(net "P3V3_E1S_SENSE_0")
	)
	(segment
		(start 219.9259 -72.015858)
		(end 218.411552 -72.015858)
		(width 0.10668)
		(layer "F.Cu")
		(net "P3V3_E1S_SENSE_0")
	)
	(segment
		(start 218.411552 -72.299322)
		(end 218.411552 -72.015858)
		(width 0.10668)
		(layer "F.Cu")
		(net "P3V3_E1S_SENSE_0")
	)
	(via
		(at 217.485976 -72.757538)
		(size 0.508)
		(drill 0.254)
		(layers "F.Cu" "B.Cu")
		(net "P3V3_E1S_SENSE_0")
	)
	(segment
		(start 218.289632 -69.397118)
		(end 219.19946 -69.397118)
		(width 0.10668)
		(layer "F.Cu")
		(net "P3V3_E1S_REG_0")
	)
	(segment
		(start 219.19946 -69.397118)
		(end 219.228416 -69.368162)
		(width 0.10668)
		(layer "F.Cu")
		(net "P3V3_E1S_REG_0")
	)
	(segment
		(start 219.569284 -69.368162)
		(end 220.321378 -70.120256)
		(width 0.10668)
		(layer "F.Cu")
		(net "P3V3_E1S_REG_0")
	)
	(segment
		(start 219.228416 -69.368162)
		(end 219.569284 -69.368162)
		(width 0.10668)
		(layer "F.Cu")
		(net "P3V3_E1S_REG_0")
	)
	(via
		(at 219.228416 -69.368162)
		(size 0.508)
		(drill 0.254)
		(layers "F.Cu" "B.Cu")
		(net "P3V3_E1S_REG_0")
	)
	(segment
		(start 224.498662 -67.921378)
		(end 223.863916 -67.921378)
		(width 0.10668)
		(layer "F.Cu")
		(net "P3V3_E1S_PWRGD_0")
	)
	(segment
		(start 223.863916 -69.577966)
		(end 223.321626 -70.120256)
		(width 0.10668)
		(layer "F.Cu")
		(net "P3V3_E1S_PWRGD_0")
	)
	(segment
		(start 223.863916 -67.921378)
		(end 223.863916 -69.577966)
		(width 0.10668)
		(layer "F.Cu")
		(net "P3V3_E1S_PWRGD_0")
	)
	(via
		(at 223.863916 -67.921378)
		(size 0.508)
		(drill 0.254)
		(layers "F.Cu" "B.Cu")
		(net "P3V3_E1S_PWRGD_0")
	)
	(segment
		(start 220.60408 -66.968116)
		(end 220.434154 -66.968116)
		(width 0.10668)
		(layer "F.Cu")
		(net "P3V3_E1S_OV_0")
	)
	(segment
		(start 219.715842 -67.114928)
		(end 219.276676 -67.554094)
		(width 0.10668)
		(layer "F.Cu")
		(net "P3V3_E1S_OV_0")
	)
	(segment
		(start 220.287342 -67.114928)
		(end 219.715842 -67.114928)
		(width 0.10668)
		(layer "F.Cu")
		(net "P3V3_E1S_OV_0")
	)
	(segment
		(start 218.282012 -67.324478)
		(end 219.04706 -67.324478)
		(width 0.10668)
		(layer "F.Cu")
		(net "P3V3_E1S_OV_0")
	)
	(segment
		(start 220.434154 -66.968116)
		(end 220.287342 -67.114928)
		(width 0.10668)
		(layer "F.Cu")
		(net "P3V3_E1S_OV_0")
	)
	(segment
		(start 219.04706 -67.324478)
		(end 219.276676 -67.554094)
		(width 0.10668)
		(layer "F.Cu")
		(net "P3V3_E1S_OV_0")
	)
	(segment
		(start 221.32163 -70.120256)
		(end 221.32163 -67.685666)
		(width 0.10668)
		(layer "F.Cu")
		(net "P3V3_E1S_OV_0")
	)
	(segment
		(start 221.32163 -67.685666)
		(end 220.60408 -66.968116)
		(width 0.10668)
		(layer "F.Cu")
		(net "P3V3_E1S_OV_0")
	)
	(via
		(at 220.60408 -66.968116)
		(size 0.762)
		(drill 0.381)
		(layers "F.Cu" "B.Cu")
		(net "P3V3_E1S_OV_0")
	)
	(segment
		(start 192.999868 -68.407534)
		(end 192.999868 -67.392042)
		(width 0.10668)
		(layer "F.Cu")
		(net "P3V3_E1S_MODE_0")
	)
	(segment
		(start 192.999614 -68.407788)
		(end 192.999868 -68.407534)
		(width 0.10668)
		(layer "F.Cu")
		(net "P3V3_E1S_MODE_0")
	)
	(segment
		(start 195.536566 -68.923916)
		(end 195.274946 -68.923916)
		(width 0.10668)
		(layer "F.Cu")
		(net "P3V3_E1S_MODE_0")
	)
	(segment
		(start 193.742818 -67.391788)
		(end 194.250818 -67.899788)
		(width 0.10668)
		(layer "F.Cu")
		(net "P3V3_E1S_MODE_0")
	)
	(segment
		(start 195.274946 -68.923916)
		(end 194.250818 -67.899788)
		(width 0.10668)
		(layer "F.Cu")
		(net "P3V3_E1S_MODE_0")
	)
	(segment
		(start 192.999868 -67.392042)
		(end 192.999614 -67.391788)
		(width 0.10668)
		(layer "F.Cu")
		(net "P3V3_E1S_MODE_0")
	)
	(segment
		(start 192.999614 -67.391788)
		(end 193.742818 -67.391788)
		(width 0.10668)
		(layer "F.Cu")
		(net "P3V3_E1S_MODE_0")
	)
	(via
		(at 194.250818 -67.899788)
		(size 0.762)
		(drill 0.381)
		(layers "F.Cu" "B.Cu")
		(net "P3V3_E1S_MODE_0")
	)
	(segment
		(start 192.999868 -70.185788)
		(end 193.900806 -69.28485)
		(width 0.10668)
		(layer "F.Cu")
		(net "P3V3_E1S_ILIMIT_0")
	)
	(segment
		(start 194.045332 -69.28485)
		(end 194.7291 -69.28485)
		(width 0.10668)
		(layer "F.Cu")
		(net "P3V3_E1S_ILIMIT_0")
	)
	(segment
		(start 194.7291 -69.28485)
		(end 194.868038 -69.423788)
		(width 0.10668)
		(layer "F.Cu")
		(net "P3V3_E1S_ILIMIT_0")
	)
	(segment
		(start 194.868038 -69.423788)
		(end 195.536566 -69.423788)
		(width 0.10668)
		(layer "F.Cu")
		(net "P3V3_E1S_ILIMIT_0")
	)
	(segment
		(start 193.900806 -69.28485)
		(end 194.045332 -69.28485)
		(width 0.10668)
		(layer "F.Cu")
		(net "P3V3_E1S_ILIMIT_0")
	)
	(via
		(at 194.045332 -69.28485)
		(size 0.762)
		(drill 0.381)
		(layers "F.Cu" "B.Cu")
		(net "P3V3_E1S_ILIMIT_0")
	)
	(segment
		(start 197.95109 -68.923916)
		(end 198.873618 -68.001388)
		(width 0.10668)
		(layer "F.Cu")
		(net "P3V3_E1S_GATE_0_PU293")
	)
	(segment
		(start 198.975218 -68.026788)
		(end 198.949818 -68.001388)
		(width 0.10668)
		(layer "F.Cu")
		(net "P3V3_E1S_GATE_0_PU293")
	)
	(segment
		(start 200.200514 -68.026788)
		(end 198.975218 -68.026788)
		(width 0.10668)
		(layer "F.Cu")
		(net "P3V3_E1S_GATE_0_PU293")
	)
	(segment
		(start 197.536562 -68.923916)
		(end 197.95109 -68.923916)
		(width 0.10668)
		(layer "F.Cu")
		(net "P3V3_E1S_GATE_0_PU293")
	)
	(segment
		(start 198.873618 -68.001388)
		(end 198.949818 -68.001388)
		(width 0.10668)
		(layer "F.Cu")
		(net "P3V3_E1S_GATE_0_PU293")
	)
	(via
		(at 198.949818 -68.001388)
		(size 0.762)
		(drill 0.381)
		(layers "F.Cu" "B.Cu")
		(net "P3V3_E1S_GATE_0_PU293")
	)
	(segment
		(start 222.984314 -74.51598)
		(end 222.978472 -74.510138)
		(width 0.10668)
		(layer "F.Cu")
		(net "P3V3_E1S_GATE_0")
	)
	(segment
		(start 222.978472 -74.510138)
		(end 222.978472 -73.524618)
		(width 0.10668)
		(layer "F.Cu")
		(net "P3V3_E1S_GATE_0")
	)
	(segment
		(start 222.8215 -72.295258)
		(end 222.871792 -72.34555)
		(width 0.10668)
		(layer "F.Cu")
		(net "P3V3_E1S_GATE_0")
	)
	(segment
		(start 222.871792 -72.34555)
		(end 222.97136 -72.445118)
		(width 0.10668)
		(layer "F.Cu")
		(net "P3V3_E1S_GATE_0")
	)
	(segment
		(start 222.97136 -72.445118)
		(end 222.97136 -73.517506)
		(width 0.10668)
		(layer "F.Cu")
		(net "P3V3_E1S_GATE_0")
	)
	(segment
		(start 222.984314 -75.53071)
		(end 222.984314 -74.51598)
		(width 0.10668)
		(layer "F.Cu")
		(net "P3V3_E1S_GATE_0")
	)
	(segment
		(start 222.978472 -73.524618)
		(end 222.97136 -73.517506)
		(width 0.10668)
		(layer "F.Cu")
		(net "P3V3_E1S_GATE_0")
	)
	(segment
		(start 222.8215 -71.62038)
		(end 222.8215 -72.295258)
		(width 0.10668)
		(layer "F.Cu")
		(net "P3V3_E1S_GATE_0")
	)
	(via
		(at 222.871792 -72.34555)
		(size 0.508)
		(drill 0.254)
		(layers "F.Cu" "B.Cu")
		(net "P3V3_E1S_GATE_0")
	)
	(segment
		(start 224.984056 -72.227694)
		(end 224.77095 -72.227694)
		(width 0.10668)
		(layer "F.Cu")
		(net "P3V3_E1S_FAULT_0")
	)
	(segment
		(start 225.171762 -72.039988)
		(end 225.171762 -71.592948)
		(width 0.10668)
		(layer "F.Cu")
		(net "P3V3_E1S_FAULT_0")
	)
	(segment
		(start 224.984056 -72.227694)
		(end 225.171762 -72.039988)
		(width 0.10668)
		(layer "F.Cu")
		(net "P3V3_E1S_FAULT_0")
	)
	(segment
		(start 224.77095 -72.227694)
		(end 224.544636 -72.00138)
		(width 0.10668)
		(layer "F.Cu")
		(net "P3V3_E1S_FAULT_0")
	)
	(segment
		(start 223.531176 -70.620382)
		(end 223.321626 -70.620382)
		(width 0.10668)
		(layer "F.Cu")
		(net "P3V3_E1S_FAULT_0")
	)
	(segment
		(start 224.544636 -71.633842)
		(end 223.531176 -70.620382)
		(width 0.10668)
		(layer "F.Cu")
		(net "P3V3_E1S_FAULT_0")
	)
	(segment
		(start 224.544636 -72.00138)
		(end 224.544636 -71.633842)
		(width 0.10668)
		(layer "F.Cu")
		(net "P3V3_E1S_FAULT_0")
	)
	(via
		(at 224.984056 -72.227694)
		(size 0.508)
		(drill 0.254)
		(layers "F.Cu" "B.Cu")
		(net "P3V3_E1S_FAULT_0")
	)
	(segment
		(start 197.536562 -69.423788)
		(end 197.934072 -69.423788)
		(width 0.10668)
		(layer "F.Cu")
		(net "P3V3_E1S_EN_0_R2")
	)
	(segment
		(start 197.934072 -69.423788)
		(end 198.442072 -69.931788)
		(width 0.10668)
		(layer "F.Cu")
		(net "P3V3_E1S_EN_0_R2")
	)
	(segment
		(start 199.076818 -69.804788)
		(end 198.949818 -69.931788)
		(width 0.10668)
		(layer "F.Cu")
		(net "P3V3_E1S_EN_0_R2")
	)
	(segment
		(start 198.442072 -69.931788)
		(end 198.949818 -69.931788)
		(width 0.10668)
		(layer "F.Cu")
		(net "P3V3_E1S_EN_0_R2")
	)
	(segment
		(start 200.200514 -69.804788)
		(end 199.076818 -69.804788)
		(width 0.10668)
		(layer "F.Cu")
		(net "P3V3_E1S_EN_0_R2")
	)
	(via
		(at 198.949818 -69.931788)
		(size 0.762)
		(drill 0.381)
		(layers "F.Cu" "B.Cu")
		(net "P3V3_E1S_EN_0_R2")
	)
	(segment
		(start 200.200514 -71.582788)
		(end 200.200514 -71.583042)
		(width 0.10668)
		(layer "F.Cu")
		(net "P3V3_E1S_DVDT_0")
	)
	(segment
		(start 199.921368 -71.862188)
		(end 198.949818 -71.862188)
		(width 0.10668)
		(layer "F.Cu")
		(net "P3V3_E1S_DVDT_0")
	)
	(segment
		(start 198.949818 -71.095108)
		(end 198.949818 -71.862188)
		(width 0.10668)
		(layer "F.Cu")
		(net "P3V3_E1S_DVDT_0")
	)
	(segment
		(start 197.77837 -69.92366)
		(end 198.949818 -71.095108)
		(width 0.10668)
		(layer "F.Cu")
		(net "P3V3_E1S_DVDT_0")
	)
	(segment
		(start 197.536562 -69.92366)
		(end 197.77837 -69.92366)
		(width 0.10668)
		(layer "F.Cu")
		(net "P3V3_E1S_DVDT_0")
	)
	(segment
		(start 200.200514 -71.583042)
		(end 199.921368 -71.862188)
		(width 0.10668)
		(layer "F.Cu")
		(net "P3V3_E1S_DVDT_0")
	)
	(via
		(at 198.949818 -71.862188)
		(size 0.762)
		(drill 0.381)
		(layers "F.Cu" "B.Cu")
		(net "P3V3_E1S_DVDT_0")
	)
	(segment
		(start 218.418156 -71.120254)
		(end 218.411552 -71.126858)
		(width 0.10668)
		(layer "F.Cu")
		(net "P3V3_E1S_CB_0")
	)
	(segment
		(start 219.26042 -71.120254)
		(end 218.418156 -71.120254)
		(width 0.10668)
		(layer "F.Cu")
		(net "P3V3_E1S_CB_0")
	)
	(segment
		(start 220.321378 -71.120254)
		(end 219.26042 -71.120254)
		(width 0.10668)
		(layer "F.Cu")
		(net "P3V3_E1S_CB_0")
	)
	(via
		(at 219.26042 -71.120254)
		(size 0.508)
		(drill 0.254)
		(layers "F.Cu" "B.Cu")
		(net "P3V3_E1S_CB_0")
	)
	(segment
		(start 190.721996 -115.452906)
		(end 191.111886 -115.842796)
		(width 0.10668)
		(layer "F.Cu")
		(net "P3V3_E1S_0_EN_R")
	)
	(via
		(at 199.104758 -120.737376)
		(size 0.508)
		(drill 0.254)
		(layers "F.Cu" "B.Cu")
		(net "P3V3_E1S_0_EN_R")
	)
	(via
		(at 191.111886 -115.842796)
		(size 0.4572)
		(drill 0.254)
		(layers "F.Cu" "B.Cu")
		(net "P3V3_E1S_0_EN_R")
	)
	(segment
		(start 199.564498 -120.277636)
		(end 200.092818 -120.277636)
		(width 0.10668)
		(layer "B.Cu")
		(net "P3V3_E1S_0_EN_R")
	)
	(segment
		(start 199.104758 -120.737376)
		(end 199.564498 -120.277636)
		(width 0.10668)
		(layer "B.Cu")
		(net "P3V3_E1S_0_EN_R")
	)
	(segment
		(start 200.092818 -120.277636)
		(end 200.552558 -120.737376)
		(width 0.10668)
		(layer "B.Cu")
		(net "P3V3_E1S_0_EN_R")
	)
	(segment
		(start 198.917814 -121.268236)
		(end 197.154292 -121.268236)
		(width 0.11684)
		(layer "In2.Cu")
		(net "P3V3_E1S_0_EN_R")
	)
	(segment
		(start 199.104758 -121.081292)
		(end 198.917814 -121.268236)
		(width 0.11684)
		(layer "In2.Cu")
		(net "P3V3_E1S_0_EN_R")
	)
	(segment
		(start 196.069712 -119.243348)
		(end 193.06794 -116.241576)
		(width 0.11684)
		(layer "In2.Cu")
		(net "P3V3_E1S_0_EN_R")
	)
	(segment
		(start 196.788532 -120.902476)
		(end 196.788532 -119.387112)
		(width 0.11684)
		(layer "In2.Cu")
		(net "P3V3_E1S_0_EN_R")
	)
	(segment
		(start 196.788532 -119.387112)
		(end 196.644768 -119.243348)
		(width 0.11684)
		(layer "In2.Cu")
		(net "P3V3_E1S_0_EN_R")
	)
	(segment
		(start 196.644768 -119.243348)
		(end 196.069712 -119.243348)
		(width 0.11684)
		(layer "In2.Cu")
		(net "P3V3_E1S_0_EN_R")
	)
	(segment
		(start 199.104758 -120.737376)
		(end 199.104758 -121.081292)
		(width 0.11684)
		(layer "In2.Cu")
		(net "P3V3_E1S_0_EN_R")
	)
	(segment
		(start 197.154292 -121.268236)
		(end 196.788532 -120.902476)
		(width 0.11684)
		(layer "In2.Cu")
		(net "P3V3_E1S_0_EN_R")
	)
	(segment
		(start 193.06794 -116.241576)
		(end 191.510666 -116.241576)
		(width 0.11684)
		(layer "In2.Cu")
		(net "P3V3_E1S_0_EN_R")
	)
	(segment
		(start 191.510666 -116.241576)
		(end 191.111886 -115.842796)
		(width 0.11684)
		(layer "In2.Cu")
		(net "P3V3_E1S_0_EN_R")
	)
	(segment
		(start 223.79305 -75.539346)
		(end 223.79305 -76.581)
		(width 0.4572)
		(layer "F.Cu")
		(net "P3V3_E1S_0_R")
	)
	(segment
		(start 225.856546 -67.114928)
		(end 226.274376 -67.532758)
		(width 0.508)
		(layer "F.Cu")
		(net "P3V3_E1S_0_R")
	)
	(segment
		(start 222.772986 -67.114928)
		(end 225.856546 -67.114928)
		(width 0.508)
		(layer "F.Cu")
		(net "P3V3_E1S_0_R")
	)
	(segment
		(start 216.659714 -54.70525)
		(end 217.407236 -54.70525)
		(width 0.254)
		(layer "F.Cu")
		(net "P3V3_E1S_0_R")
	)
	(segment
		(start 226.274376 -67.532758)
		(end 226.274376 -72.68337)
		(width 0.508)
		(layer "F.Cu")
		(net "P3V3_E1S_0_R")
	)
	(segment
		(start 221.361 -79.629)
		(end 221.996 -78.994)
		(width 0.4572)
		(layer "F.Cu")
		(net "P3V3_E1S_0_R")
	)
	(segment
		(start 226.274376 -72.68337)
		(end 224.447608 -74.510138)
		(width 0.508)
		(layer "F.Cu")
		(net "P3V3_E1S_0_R")
	)
	(segment
		(start 223.766888 -78.994)
		(end 223.774 -78.986888)
		(width 0.4572)
		(layer "F.Cu")
		(net "P3V3_E1S_0_R")
	)
	(segment
		(start 223.79305 -76.581)
		(end 223.774 -76.60005)
		(width 0.4572)
		(layer "F.Cu")
		(net "P3V3_E1S_0_R")
	)
	(segment
		(start 223.774 -76.60005)
		(end 223.774 -78.986888)
		(width 0.4572)
		(layer "F.Cu")
		(net "P3V3_E1S_0_R")
	)
	(segment
		(start 221.361 -80.37195)
		(end 221.361 -79.629)
		(width 0.4572)
		(layer "F.Cu")
		(net "P3V3_E1S_0_R")
	)
	(segment
		(start 223.778572 -74.510138)
		(end 223.778572 -75.524868)
		(width 0.4572)
		(layer "F.Cu")
		(net "P3V3_E1S_0_R")
	)
	(segment
		(start 223.784414 -75.53071)
		(end 223.79305 -75.539346)
		(width 0.4572)
		(layer "F.Cu")
		(net "P3V3_E1S_0_R")
	)
	(segment
		(start 221.996 -78.994)
		(end 223.766888 -78.994)
		(width 0.4572)
		(layer "F.Cu")
		(net "P3V3_E1S_0_R")
	)
	(segment
		(start 223.778572 -75.524868)
		(end 223.784414 -75.53071)
		(width 0.4572)
		(layer "F.Cu")
		(net "P3V3_E1S_0_R")
	)
	(segment
		(start 224.447608 -74.510138)
		(end 223.778572 -74.510138)
		(width 0.508)
		(layer "F.Cu")
		(net "P3V3_E1S_0_R")
	)
	(via
		(at 217.407236 -54.70525)
		(size 0.508)
		(drill 0.254)
		(layers "F.Cu" "B.Cu")
		(net "P3V3_E1S_0_R")
	)
	(via
		(at 220.352366 -58.874152)
		(size 0.508)
		(drill 0.254)
		(layers "F.Cu" "B.Cu")
		(net "P3V3_E1S_0_R")
	)
	(segment
		(start 220.352366 -57.42178)
		(end 217.635836 -54.70525)
		(width 0.381)
		(layer "B.Cu")
		(net "P3V3_E1S_0_R")
	)
	(segment
		(start 220.352366 -58.874152)
		(end 220.352366 -57.42178)
		(width 0.381)
		(layer "B.Cu")
		(net "P3V3_E1S_0_R")
	)
	(segment
		(start 217.156538 -54.955948)
		(end 217.407236 -54.70525)
		(width 0.4572)
		(layer "B.Cu")
		(net "P3V3_E1S_0_R")
	)
	(segment
		(start 217.635836 -54.70525)
		(end 217.407236 -54.70525)
		(width 0.381)
		(layer "B.Cu")
		(net "P3V3_E1S_0_R")
	)
	(segment
		(start 216.58453 -54.955948)
		(end 217.156538 -54.955948)
		(width 0.4572)
		(layer "B.Cu")
		(net "P3V3_E1S_0_R")
	)
	(segment
		(start 254.821182 -68.946522)
		(end 255.312926 -68.946522)
		(width 0.10668)
		(layer "F.Cu")
		(net "P3V3_E1S_0_EN_G")
	)
	(segment
		(start 254.660146 -69.107558)
		(end 254.821182 -68.946522)
		(width 0.10668)
		(layer "F.Cu")
		(net "P3V3_E1S_0_EN_G")
	)
	(segment
		(start 255.312926 -69.596508)
		(end 254.787146 -69.596508)
		(width 0.10668)
		(layer "F.Cu")
		(net "P3V3_E1S_0_EN_G")
	)
	(segment
		(start 254.660146 -69.469508)
		(end 254.660146 -69.107558)
		(width 0.10668)
		(layer "F.Cu")
		(net "P3V3_E1S_0_EN_G")
	)
	(segment
		(start 255.312926 -69.596508)
		(end 256.547112 -69.596508)
		(width 0.10668)
		(layer "F.Cu")
		(net "P3V3_E1S_0_EN_G")
	)
	(segment
		(start 257.766312 -69.596508)
		(end 256.547112 -69.596508)
		(width 0.10668)
		(layer "F.Cu")
		(net "P3V3_E1S_0_EN_G")
	)
	(segment
		(start 254.787146 -69.596508)
		(end 254.660146 -69.469508)
		(width 0.10668)
		(layer "F.Cu")
		(net "P3V3_E1S_0_EN_G")
	)
	(via
		(at 256.547112 -69.596508)
		(size 0.762)
		(drill 0.381)
		(layers "F.Cu" "B.Cu")
		(net "P3V3_E1S_0_EN_G")
	)
	(segment
		(start 221.27083 -42.255948)
		(end 221.27083 -41.620948)
		(width 0.381)
		(layer "F.Cu")
		(net "P3V3_E1S_0")
	)
	(segment
		(start 234.274614 -67.449954)
		(end 234.699048 -67.874388)
		(width 0.254)
		(layer "F.Cu")
		(net "P3V3_E1S_0")
	)
	(segment
		(start 222.07093 -44.922948)
		(end 222.680784 -44.922948)
		(width 0.381)
		(layer "F.Cu")
		(net "P3V3_E1S_0")
	)
	(segment
		(start 236.562392 -67.874388)
		(end 235.068872 -67.874388)
		(width 0.3556)
		(layer "F.Cu")
		(net "P3V3_E1S_0")
	)
	(segment
		(start 223.80956 -46.524926)
		(end 223.095312 -46.524926)
		(width 0.381)
		(layer "F.Cu")
		(net "P3V3_E1S_0")
	)
	(segment
		(start 220.797882 -42.255948)
		(end 220.540834 -41.9989)
		(width 0.254)
		(layer "F.Cu")
		(net "P3V3_E1S_0")
	)
	(segment
		(start 222.07093 -43.525948)
		(end 222.680784 -43.525948)
		(width 0.381)
		(layer "F.Cu")
		(net "P3V3_E1S_0")
	)
	(segment
		(start 234.274614 -67.02425)
		(end 234.274614 -67.449954)
		(width 0.254)
		(layer "F.Cu")
		(net "P3V3_E1S_0")
	)
	(segment
		(start 239.90808 -47.003208)
		(end 239.90808 -46.251876)
		(width 0.508)
		(layer "F.Cu")
		(net "P3V3_E1S_0")
	)
	(segment
		(start 218.935046 -42.688256)
		(end 218.360752 -42.688256)
		(width 0.4572)
		(layer "F.Cu")
		(net "P3V3_E1S_0")
	)
	(segment
		(start 234.699048 -67.874388)
		(end 235.068872 -67.874388)
		(width 0.254)
		(layer "F.Cu")
		(net "P3V3_E1S_0")
	)
	(segment
		(start 221.27083 -42.255948)
		(end 220.797882 -42.255948)
		(width 0.254)
		(layer "F.Cu")
		(net "P3V3_E1S_0")
	)
	(segment
		(start 219.624402 -41.9989)
		(end 218.935046 -42.688256)
		(width 0.4572)
		(layer "F.Cu")
		(net "P3V3_E1S_0")
	)
	(segment
		(start 220.540834 -41.9989)
		(end 219.624402 -41.9989)
		(width 0.4572)
		(layer "F.Cu")
		(net "P3V3_E1S_0")
	)
	(segment
		(start 223.8121 -47.612046)
		(end 223.068134 -47.612046)
		(width 0.381)
		(layer "F.Cu")
		(net "P3V3_E1S_0")
	)
	(via
		(at 226.471734 -52.619148)
		(size 0.508)
		(drill 0.254)
		(layers "F.Cu" "B.Cu")
		(net "P3V3_E1S_0")
	)
	(via
		(at 223.068134 -47.612046)
		(size 0.508)
		(drill 0.254)
		(layers "F.Cu" "B.Cu")
		(net "P3V3_E1S_0")
	)
	(via
		(at 237.685834 -48.620426)
		(size 0.508)
		(drill 0.254)
		(layers "F.Cu" "B.Cu")
		(net "P3V3_E1S_0")
	)
	(via
		(at 227.741734 -53.254148)
		(size 0.508)
		(drill 0.254)
		(layers "F.Cu" "B.Cu")
		(net "P3V3_E1S_0")
	)
	(via
		(at 225.78822 -52.533042)
		(size 0.508)
		(drill 0.254)
		(layers "F.Cu" "B.Cu")
		(net "P3V3_E1S_0")
	)
	(via
		(at 227.106734 -53.254148)
		(size 0.508)
		(drill 0.254)
		(layers "F.Cu" "B.Cu")
		(net "P3V3_E1S_0")
	)
	(via
		(at 227.106734 -52.619148)
		(size 0.508)
		(drill 0.254)
		(layers "F.Cu" "B.Cu")
		(net "P3V3_E1S_0")
	)
	(via
		(at 222.680784 -44.922948)
		(size 0.508)
		(drill 0.254)
		(layers "F.Cu" "B.Cu")
		(net "P3V3_E1S_0")
	)
	(via
		(at 238.574834 -48.620426)
		(size 0.508)
		(drill 0.254)
		(layers "F.Cu" "B.Cu")
		(net "P3V3_E1S_0")
	)
	(via
		(at 234.274614 -67.02425)
		(size 0.508)
		(drill 0.254)
		(layers "F.Cu" "B.Cu")
		(net "P3V3_E1S_0")
	)
	(via
		(at 225.78822 -53.168042)
		(size 0.508)
		(drill 0.254)
		(layers "F.Cu" "B.Cu")
		(net "P3V3_E1S_0")
	)
	(via
		(at 227.741734 -52.619148)
		(size 0.508)
		(drill 0.254)
		(layers "F.Cu" "B.Cu")
		(net "P3V3_E1S_0")
	)
	(via
		(at 221.27083 -41.620948)
		(size 0.508)
		(drill 0.254)
		(layers "F.Cu" "B.Cu")
		(net "P3V3_E1S_0")
	)
	(via
		(at 220.954854 -53.228748)
		(size 0.762)
		(drill 0.381)
		(layers "F.Cu" "B.Cu")
		(net "P3V3_E1S_0")
	)
	(via
		(at 222.680784 -43.525948)
		(size 0.508)
		(drill 0.254)
		(layers "F.Cu" "B.Cu")
		(net "P3V3_E1S_0")
	)
	(via
		(at 223.095312 -46.524926)
		(size 0.508)
		(drill 0.254)
		(layers "F.Cu" "B.Cu")
		(net "P3V3_E1S_0")
	)
	(via
		(at 239.90808 -46.251876)
		(size 0.508)
		(drill 0.254)
		(layers "F.Cu" "B.Cu")
		(net "P3V3_E1S_0")
	)
	(via
		(at 226.471734 -53.254148)
		(size 0.508)
		(drill 0.254)
		(layers "F.Cu" "B.Cu")
		(net "P3V3_E1S_0")
	)
	(segment
		(start 239.41278 -61.886084)
		(end 239.41278 -49.458372)
		(width 0.4572)
		(layer "In11.Cu")
		(net "P3V3_E1S_0")
	)
	(segment
		(start 234.274614 -67.02425)
		(end 239.41278 -61.886084)
		(width 0.4572)
		(layer "In11.Cu")
		(net "P3V3_E1S_0")
	)
	(segment
		(start 239.41278 -49.458372)
		(end 238.574834 -48.620426)
		(width 0.4572)
		(layer "In11.Cu")
		(net "P3V3_E1S_0")
	)
	(segment
		(start 453.36841 -47.257462)
		(end 453.36841 -47.173134)
		(width 0.254)
		(layer "F.Cu")
		(net "P3V3_AUX_VOS")
	)
	(segment
		(start 454.137522 -47.78502)
		(end 453.609964 -47.257462)
		(width 0.254)
		(layer "F.Cu")
		(net "P3V3_AUX_VOS")
	)
	(segment
		(start 453.609964 -47.257462)
		(end 453.36841 -47.257462)
		(width 0.254)
		(layer "F.Cu")
		(net "P3V3_AUX_VOS")
	)
	(segment
		(start 454.137522 -48.817022)
		(end 454.137522 -47.78502)
		(width 0.254)
		(layer "F.Cu")
		(net "P3V3_AUX_VOS")
	)
	(segment
		(start 453.36841 -47.173134)
		(end 453.156066 -46.96079)
		(width 0.254)
		(layer "F.Cu")
		(net "P3V3_AUX_VOS")
	)
	(segment
		(start 453.156066 -46.96079)
		(end 453.156066 -46.345602)
		(width 0.254)
		(layer "F.Cu")
		(net "P3V3_AUX_VOS")
	)
	(via
		(at 453.36841 -47.257462)
		(size 0.508)
		(drill 0.254)
		(layers "F.Cu" "B.Cu")
		(net "P3V3_AUX_VOS")
	)
	(segment
		(start 461.31226 -53.055266)
		(end 461.342232 -53.025294)
		(width 0.254)
		(layer "F.Cu")
		(net "P3V3_AUX_VDRV")
	)
	(segment
		(start 459.489048 -50.817018)
		(end 460.131922 -51.459892)
		(width 0.254)
		(layer "F.Cu")
		(net "P3V3_AUX_VDRV")
	)
	(segment
		(start 460.801974 -52.096416)
		(end 461.342232 -52.096416)
		(width 0.254)
		(layer "F.Cu")
		(net "P3V3_AUX_VDRV")
	)
	(segment
		(start 460.131922 -51.459892)
		(end 460.204058 -51.459892)
		(width 0.254)
		(layer "F.Cu")
		(net "P3V3_AUX_VDRV")
	)
	(segment
		(start 458.850238 -50.817018)
		(end 459.489048 -50.817018)
		(width 0.254)
		(layer "F.Cu")
		(net "P3V3_AUX_VDRV")
	)
	(segment
		(start 460.204058 -51.4985)
		(end 460.801974 -52.096416)
		(width 0.254)
		(layer "F.Cu")
		(net "P3V3_AUX_VDRV")
	)
	(segment
		(start 461.342232 -53.025294)
		(end 461.342232 -52.096416)
		(width 0.254)
		(layer "F.Cu")
		(net "P3V3_AUX_VDRV")
	)
	(segment
		(start 460.204058 -51.459892)
		(end 460.204058 -51.4985)
		(width 0.254)
		(layer "F.Cu")
		(net "P3V3_AUX_VDRV")
	)
	(via
		(at 461.31226 -53.055266)
		(size 0.508)
		(drill 0.254)
		(layers "F.Cu" "B.Cu")
		(net "P3V3_AUX_VDRV")
	)
	(segment
		(start 460.063596 -50.316892)
		(end 458.850238 -50.316892)
		(width 0.254)
		(layer "F.Cu")
		(net "P3V3_AUX_VCC")
	)
	(segment
		(start 461.689196 -50.190146)
		(end 460.190342 -50.190146)
		(width 0.254)
		(layer "F.Cu")
		(net "P3V3_AUX_VCC")
	)
	(segment
		(start 461.689196 -50.190146)
		(end 461.689196 -50.949352)
		(width 0.254)
		(layer "F.Cu")
		(net "P3V3_AUX_VCC")
	)
	(segment
		(start 460.190342 -50.190146)
		(end 460.063596 -50.316892)
		(width 0.254)
		(layer "F.Cu")
		(net "P3V3_AUX_VCC")
	)
	(segment
		(start 461.689196 -50.949352)
		(end 461.342232 -51.296316)
		(width 0.254)
		(layer "F.Cu")
		(net "P3V3_AUX_VCC")
	)
	(via
		(at 460.063596 -50.316892)
		(size 0.508)
		(drill 0.254)
		(layers "F.Cu" "B.Cu")
		(net "P3V3_AUX_VCC")
	)
	(segment
		(start 453.402954 -45.59554)
		(end 453.402954 -45.104812)
		(width 0.1524)
		(layer "F.Cu")
		(net "P3V3_AUX_SS")
	)
	(segment
		(start 454.75017 -48.179228)
		(end 454.75017 -46.802802)
		(width 0.254)
		(layer "F.Cu")
		(net "P3V3_AUX_SS")
	)
	(segment
		(start 454.47204 -46.664626)
		(end 453.402954 -45.59554)
		(width 0.1524)
		(layer "F.Cu")
		(net "P3V3_AUX_SS")
	)
	(segment
		(start 454.75017 -46.802802)
		(end 454.611994 -46.664626)
		(width 0.254)
		(layer "F.Cu")
		(net "P3V3_AUX_SS")
	)
	(segment
		(start 454.611994 -46.664626)
		(end 454.47204 -46.664626)
		(width 0.1524)
		(layer "F.Cu")
		(net "P3V3_AUX_SS")
	)
	(via
		(at 453.402954 -45.104812)
		(size 0.762)
		(drill 0.381)
		(layers "F.Cu" "B.Cu")
		(net "P3V3_AUX_SS")
	)
	(segment
		(start 457.947268 -46.961552)
		(end 458.244194 -46.664626)
		(width 0.254)
		(layer "F.Cu")
		(net "P3V3_AUX_MODE")
	)
	(segment
		(start 458.25029 -47.873412)
		(end 457.85278 -47.475902)
		(width 0.254)
		(layer "F.Cu")
		(net "P3V3_AUX_MODE")
	)
	(segment
		(start 457.947268 -47.381414)
		(end 457.947268 -46.961552)
		(width 0.254)
		(layer "F.Cu")
		(net "P3V3_AUX_MODE")
	)
	(segment
		(start 458.25029 -48.179228)
		(end 458.25029 -47.873412)
		(width 0.254)
		(layer "F.Cu")
		(net "P3V3_AUX_MODE")
	)
	(segment
		(start 457.85278 -47.475902)
		(end 457.947268 -47.381414)
		(width 0.254)
		(layer "F.Cu")
		(net "P3V3_AUX_MODE")
	)
	(via
		(at 459.63713 -45.918374)
		(size 0.6604)
		(drill 0.3302)
		(layers "F.Cu" "B.Cu")
		(net "P3V3_AUX_MODE")
	)
	(via
		(at 457.85278 -47.475902)
		(size 0.508)
		(drill 0.254)
		(layers "F.Cu" "B.Cu")
		(net "P3V3_AUX_MODE")
	)
	(segment
		(start 458.898752 -45.918374)
		(end 459.63713 -45.918374)
		(width 0.1524)
		(layer "B.Cu")
		(net "P3V3_AUX_MODE")
	)
	(segment
		(start 458.423264 -46.393862)
		(end 458.898752 -45.918374)
		(width 0.1524)
		(layer "B.Cu")
		(net "P3V3_AUX_MODE")
	)
	(segment
		(start 457.85278 -46.970696)
		(end 458.423264 -46.400212)
		(width 0.1524)
		(layer "B.Cu")
		(net "P3V3_AUX_MODE")
	)
	(segment
		(start 457.85278 -47.475902)
		(end 457.85278 -46.970696)
		(width 0.1524)
		(layer "B.Cu")
		(net "P3V3_AUX_MODE")
	)
	(segment
		(start 458.423264 -46.400212)
		(end 458.423264 -46.393862)
		(width 0.1524)
		(layer "B.Cu")
		(net "P3V3_AUX_MODE")
	)
	(segment
		(start 458.985366 -48.47971)
		(end 458.985366 -47.60595)
		(width 0.1524)
		(layer "F.Cu")
		(net "P3V3_AUX_ILIM")
	)
	(segment
		(start 458.862938 -48.817022)
		(end 458.862938 -48.602138)
		(width 0.1524)
		(layer "F.Cu")
		(net "P3V3_AUX_ILIM")
	)
	(segment
		(start 458.862938 -48.602138)
		(end 458.985366 -48.47971)
		(width 0.1524)
		(layer "F.Cu")
		(net "P3V3_AUX_ILIM")
	)
	(segment
		(start 458.985366 -47.60595)
		(end 458.84338 -47.463964)
		(width 0.1524)
		(layer "F.Cu")
		(net "P3V3_AUX_ILIM")
	)
	(segment
		(start 459.158594 -47.14875)
		(end 459.158594 -46.664626)
		(width 0.1524)
		(layer "F.Cu")
		(net "P3V3_AUX_ILIM")
	)
	(segment
		(start 458.84338 -47.463964)
		(end 459.158594 -47.14875)
		(width 0.1524)
		(layer "F.Cu")
		(net "P3V3_AUX_ILIM")
	)
	(via
		(at 458.84338 -47.463964)
		(size 0.508)
		(drill 0.254)
		(layers "F.Cu" "B.Cu")
		(net "P3V3_AUX_ILIM")
	)
	(segment
		(start 455.615294 -46.584108)
		(end 456.360276 -46.584108)
		(width 0.254)
		(layer "F.Cu")
		(net "P3V3_AUX_FB")
	)
	(segment
		(start 456.440794 -46.664626)
		(end 457.329794 -46.664626)
		(width 0.254)
		(layer "F.Cu")
		(net "P3V3_AUX_FB")
	)
	(segment
		(start 455.250296 -47.072042)
		(end 455.534776 -46.787562)
		(width 0.254)
		(layer "F.Cu")
		(net "P3V3_AUX_FB")
	)
	(segment
		(start 455.534776 -46.664626)
		(end 455.615294 -46.584108)
		(width 0.254)
		(layer "F.Cu")
		(net "P3V3_AUX_FB")
	)
	(segment
		(start 455.534776 -46.787562)
		(end 455.534776 -46.664626)
		(width 0.254)
		(layer "F.Cu")
		(net "P3V3_AUX_FB")
	)
	(segment
		(start 455.250296 -48.191928)
		(end 455.250296 -47.072042)
		(width 0.254)
		(layer "F.Cu")
		(net "P3V3_AUX_FB")
	)
	(segment
		(start 456.360276 -46.584108)
		(end 456.440794 -46.664626)
		(width 0.254)
		(layer "F.Cu")
		(net "P3V3_AUX_FB")
	)
	(segment
		(start 453.47128 -49.040288)
		(end 453.747886 -49.316894)
		(width 0.10668)
		(layer "F.Cu")
		(net "P3V3_AUX_EN")
	)
	(segment
		(start 452.515732 -47.90567)
		(end 452.515986 -47.905924)
		(width 0.10668)
		(layer "F.Cu")
		(net "P3V3_AUX_EN")
	)
	(segment
		(start 452.5391 -47.475394)
		(end 452.515732 -47.498762)
		(width 0.10668)
		(layer "F.Cu")
		(net "P3V3_AUX_EN")
	)
	(segment
		(start 452.515986 -48.439832)
		(end 452.5391 -48.462946)
		(width 0.10668)
		(layer "F.Cu")
		(net "P3V3_AUX_EN")
	)
	(segment
		(start 452.893938 -48.462946)
		(end 453.47128 -49.040288)
		(width 0.10668)
		(layer "F.Cu")
		(net "P3V3_AUX_EN")
	)
	(segment
		(start 452.5391 -48.462946)
		(end 452.893938 -48.462946)
		(width 0.10668)
		(layer "F.Cu")
		(net "P3V3_AUX_EN")
	)
	(segment
		(start 452.515986 -47.905924)
		(end 452.515986 -48.439832)
		(width 0.10668)
		(layer "F.Cu")
		(net "P3V3_AUX_EN")
	)
	(segment
		(start 452.515732 -47.498762)
		(end 452.515732 -47.90567)
		(width 0.10668)
		(layer "F.Cu")
		(net "P3V3_AUX_EN")
	)
	(segment
		(start 453.747886 -49.316894)
		(end 454.150222 -49.316894)
		(width 0.10668)
		(layer "F.Cu")
		(net "P3V3_AUX_EN")
	)
	(via
		(at 453.47128 -49.040288)
		(size 0.508)
		(drill 0.254)
		(layers "F.Cu" "B.Cu")
		(net "P3V3_AUX_EN")
	)
	(segment
		(start 456.690476 -46.378876)
		(end 455.597768 -46.378876)
		(width 0.10668)
		(layer "B.Cu")
		(net "P3V3_AUX_EN")
	)
	(segment
		(start 455.597768 -46.378876)
		(end 455.07783 -46.898814)
		(width 0.10668)
		(layer "B.Cu")
		(net "P3V3_AUX_EN")
	)
	(segment
		(start 454.47458 -47.706788)
		(end 453.47128 -48.710088)
		(width 0.10668)
		(layer "B.Cu")
		(net "P3V3_AUX_EN")
	)
	(segment
		(start 455.07783 -46.898814)
		(end 455.07783 -47.706788)
		(width 0.10668)
		(layer "B.Cu")
		(net "P3V3_AUX_EN")
	)
	(segment
		(start 455.07783 -47.706788)
		(end 454.47458 -47.706788)
		(width 0.10668)
		(layer "B.Cu")
		(net "P3V3_AUX_EN")
	)
	(segment
		(start 453.47128 -48.710088)
		(end 453.47128 -49.040288)
		(width 0.10668)
		(layer "B.Cu")
		(net "P3V3_AUX_EN")
	)
	(segment
		(start 307.404516 -437.098694)
		(end 306.77358 -437.098694)
		(width 0.381)
		(layer "F.Cu")
		(net "P3V3_AUX")
	)
	(segment
		(start 264.26795 -104.572816)
		(end 262.85317 -104.572816)
		(width 0.381)
		(layer "F.Cu")
		(net "P3V3_AUX")
	)
	(segment
		(start 102.154736 -118.483126)
		(end 102.154736 -119.099076)
		(width 0.4064)
		(layer "F.Cu")
		(net "P3V3_AUX")
	)
	(segment
		(start 118.09095 -421.513)
		(end 118.09095 -422.275)
		(width 0.381)
		(layer "F.Cu")
		(net "P3V3_AUX")
	)
	(segment
		(start 291.202618 -427.332648)
		(end 290.076382 -427.332648)
		(width 0.3556)
		(layer "F.Cu")
		(net "P3V3_AUX")
	)
	(segment
		(start 444.59652 -434.399182)
		(end 444.59652 -433.696872)
		(width 0.381)
		(layer "F.Cu")
		(net "P3V3_AUX")
	)
	(segment
		(start 420.246302 -440.412886)
		(end 420.877238 -440.412886)
		(width 0.381)
		(layer "F.Cu")
		(net "P3V3_AUX")
	)
	(segment
		(start 157.557978 -56.368696)
		(end 157.595316 -56.331358)
		(width 0.4572)
		(layer "F.Cu")
		(net "P3V3_AUX")
	)
	(segment
		(start 105.659936 -118.463568)
		(end 105.659936 -119.079518)
		(width 0.4064)
		(layer "F.Cu")
		(net "P3V3_AUX")
	)
	(segment
		(start 15.18412 -78.830678)
		(end 14.641322 -78.830678)
		(width 0.4064)
		(layer "F.Cu")
		(net "P3V3_AUX")
	)
	(segment
		(start 191.160146 -193.93535)
		(end 192.303146 -193.93535)
		(width 0.4572)
		(layer "F.Cu")
		(net "P3V3_AUX")
	)
	(segment
		(start 273.183604 -108.594906)
		(end 272.77695 -108.594906)
		(width 0.381)
		(layer "F.Cu")
		(net "P3V3_AUX")
	)
	(segment
		(start 156.84119 -103.338884)
		(end 156.30779 -103.338884)
		(width 0.4064)
		(layer "F.Cu")
		(net "P3V3_AUX")
	)
	(segment
		(start 185.777124 -95.696024)
		(end 185.777124 -95.080074)
		(width 0.4572)
		(layer "F.Cu")
		(net "P3V3_AUX")
	)
	(segment
		(start 156.96819 -98.355658)
		(end 156.30779 -98.355658)
		(width 0.4064)
		(layer "F.Cu")
		(net "P3V3_AUX")
	)
	(segment
		(start 28.537662 -418.239448)
		(end 28.537662 -418.849048)
		(width 0.381)
		(layer "F.Cu")
		(net "P3V3_AUX")
	)
	(segment
		(start 117.513862 -17.784064)
		(end 117.513862 -18.42135)
		(width 0.381)
		(layer "F.Cu")
		(net "P3V3_AUX")
	)
	(segment
		(start 300.785276 -14.48181)
		(end 300.167548 -14.48181)
		(width 0.381)
		(layer "F.Cu")
		(net "P3V3_AUX")
	)
	(segment
		(start 330.617068 -136.473946)
		(end 331.233018 -136.473946)
		(width 0.381)
		(layer "F.Cu")
		(net "P3V3_AUX")
	)
	(segment
		(start 172.140372 -416.484816)
		(end 172.140372 -417.551616)
		(width 0.381)
		(layer "F.Cu")
		(net "P3V3_AUX")
	)
	(segment
		(start 100.920296 -426.22978)
		(end 100.920296 -426.84573)
		(width 0.381)
		(layer "F.Cu")
		(net "P3V3_AUX")
	)
	(segment
		(start 120.79605 -421.513)
		(end 121.294652 -422.011602)
		(width 0.381)
		(layer "F.Cu")
		(net "P3V3_AUX")
	)
	(segment
		(start 178.72202 -111.452914)
		(end 178.33213 -111.063024)
		(width 0.254)
		(layer "F.Cu")
		(net "P3V3_AUX")
	)
	(segment
		(start 197.84695 -94.234)
		(end 197.231 -94.234)
		(width 0.381)
		(layer "F.Cu")
		(net "P3V3_AUX")
	)
	(segment
		(start 159.932116 -36.339272)
		(end 158.93796 -37.333428)
		(width 0.4572)
		(layer "F.Cu")
		(net "P3V3_AUX")
	)
	(segment
		(start 96.28886 -38.415214)
		(end 96.689418 -38.815772)
		(width 0.381)
		(layer "F.Cu")
		(net "P3V3_AUX")
	)
	(segment
		(start 33.617662 -418.239448)
		(end 33.617662 -418.849048)
		(width 0.381)
		(layer "F.Cu")
		(net "P3V3_AUX")
	)
	(segment
		(start 342.442546 -24.297386)
		(end 342.442546 -24.913336)
		(width 0.4064)
		(layer "F.Cu")
		(net "P3V3_AUX")
	)
	(segment
		(start 301.800768 -147.06981)
		(end 301.800768 -145.896838)
		(width 0.254)
		(layer "F.Cu")
		(net "P3V3_AUX")
	)
	(segment
		(start 19.666458 -418.290248)
		(end 19.666458 -417.68014)
		(width 0.381)
		(layer "F.Cu")
		(net "P3V3_AUX")
	)
	(segment
		(start 461.187038 -99.164394)
		(end 461.516476 -99.493832)
		(width 0.381)
		(layer "F.Cu")
		(net "P3V3_AUX")
	)
	(segment
		(start 119.126 -426.72)
		(end 118.745 -426.339)
		(width 0.381)
		(layer "F.Cu")
		(net "P3V3_AUX")
	)
	(segment
		(start 279.12695 -416.306)
		(end 278.511 -416.306)
		(width 0.381)
		(layer "F.Cu")
		(net "P3V3_AUX")
	)
	(segment
		(start 84.922106 -41.95318)
		(end 84.922106 -43.47718)
		(width 0.3556)
		(layer "F.Cu")
		(net "P3V3_AUX")
	)
	(segment
		(start 214.234522 -42.688256)
		(end 215.58123 -41.341548)
		(width 0.4572)
		(layer "F.Cu")
		(net "P3V3_AUX")
	)
	(segment
		(start 192.661032 -24.919432)
		(end 192.454276 -24.919432)
		(width 0.4572)
		(layer "F.Cu")
		(net "P3V3_AUX")
	)
	(segment
		(start 157.11805 -106.172)
		(end 157.11805 -105.695242)
		(width 0.381)
		(layer "F.Cu")
		(net "P3V3_AUX")
	)
	(segment
		(start 302.123348 -431.2539)
		(end 302.123348 -431.884836)
		(width 0.381)
		(layer "F.Cu")
		(net "P3V3_AUX")
	)
	(segment
		(start 188.322204 -113.85296)
		(end 188.712094 -113.46307)
		(width 0.254)
		(layer "F.Cu")
		(net "P3V3_AUX")
	)
	(segment
		(start 455.534776 -45.864526)
		(end 456.440794 -45.864526)
		(width 0.381)
		(layer "F.Cu")
		(net "P3V3_AUX")
	)
	(segment
		(start 163.182046 -102.984046)
		(end 161.83864 -102.984046)
		(width 0.4572)
		(layer "F.Cu")
		(net "P3V3_AUX")
	)
	(segment
		(start 105.918 -422.89095)
		(end 106.68 -422.89095)
		(width 0.381)
		(layer "F.Cu")
		(net "P3V3_AUX")
	)
	(segment
		(start 191.522096 -111.452914)
		(end 191.911986 -111.063024)
		(width 0.254)
		(layer "F.Cu")
		(net "P3V3_AUX")
	)
	(segment
		(start 199.8472 -193.93535)
		(end 198.7042 -193.93535)
		(width 0.4572)
		(layer "F.Cu")
		(net "P3V3_AUX")
	)
	(segment
		(start 150.020274 -115.377468)
		(end 150.020274 -116.429028)
		(width 0.381)
		(layer "F.Cu")
		(net "P3V3_AUX")
	)
	(segment
		(start 214.131144 -120.65)
		(end 212.99805 -120.65)
		(width 0.381)
		(layer "F.Cu")
		(net "P3V3_AUX")
	)
	(segment
		(start 297.886374 -119.339614)
		(end 298.495974 -119.339614)
		(width 0.381)
		(layer "F.Cu")
		(net "P3V3_AUX")
	)
	(segment
		(start 255.810258 -110.090204)
		(end 254.927354 -110.090204)
		(width 0.4064)
		(layer "F.Cu")
		(net "P3V3_AUX")
	)
	(segment
		(start 82.706718 -20.616672)
		(end 82.706718 -19.542252)
		(width 0.381)
		(layer "F.Cu")
		(net "P3V3_AUX")
	)
	(segment
		(start 374.971564 -426.567854)
		(end 375.526554 -426.567854)
		(width 0.254)
		(layer "F.Cu")
		(net "P3V3_AUX")
	)
	(segment
		(start 217.554048 -100.471986)
		(end 216.535 -100.471986)
		(width 0.381)
		(layer "F.Cu")
		(net "P3V3_AUX")
	)
	(segment
		(start 15.799308 -427.883066)
		(end 15.799308 -427.232064)
		(width 0.3556)
		(layer "F.Cu")
		(net "P3V3_AUX")
	)
	(segment
		(start 87.94623 -58.21172)
		(end 88.55583 -58.21172)
		(width 0.254)
		(layer "F.Cu")
		(net "P3V3_AUX")
	)
	(segment
		(start 191.52362 -419.355778)
		(end 191.52362 -420.626032)
		(width 0.508)
		(layer "F.Cu")
		(net "P3V3_AUX")
	)
	(segment
		(start 43.66895 -437.134)
		(end 43.66895 -436.367936)
		(width 0.381)
		(layer "F.Cu")
		(net "P3V3_AUX")
	)
	(segment
		(start 206.456026 -129.032)
		(end 207.589374 -127.898652)
		(width 0.381)
		(layer "F.Cu")
		(net "P3V3_AUX")
	)
	(segment
		(start 186.722004 -114.652806)
		(end 187.111894 -114.262916)
		(width 0.254)
		(layer "F.Cu")
		(net "P3V3_AUX")
	)
	(segment
		(start 257.28295 -141.732)
		(end 257.28295 -142.367)
		(width 0.381)
		(layer "F.Cu")
		(net "P3V3_AUX")
	)
	(segment
		(start 254.40005 -38.683946)
		(end 254.40005 -38.92931)
		(width 0.4572)
		(layer "F.Cu")
		(net "P3V3_AUX")
	)
	(segment
		(start 156.398214 -56.368696)
		(end 157.557978 -56.368696)
		(width 0.4572)
		(layer "F.Cu")
		(net "P3V3_AUX")
	)
	(segment
		(start 196.088 -133.968998)
		(end 196.088 -134.584948)
		(width 0.4064)
		(layer "F.Cu")
		(net "P3V3_AUX")
	)
	(segment
		(start 127.381 -106.53395)
		(end 126.619 -106.53395)
		(width 0.381)
		(layer "F.Cu")
		(net "P3V3_AUX")
	)
	(segment
		(start 151.53005 -114.173)
		(end 152.017984 -114.660934)
		(width 0.381)
		(layer "F.Cu")
		(net "P3V3_AUX")
	)
	(segment
		(start 164.973 -95.61195)
		(end 164.973 -94.869)
		(width 0.381)
		(layer "F.Cu")
		(net "P3V3_AUX")
	)
	(segment
		(start 9.34466 -78.180692)
		(end 8.707374 -78.180692)
		(width 0.4064)
		(layer "F.Cu")
		(net "P3V3_AUX")
	)
	(segment
		(start 103.453946 -56.22036)
		(end 103.911146 -56.67756)
		(width 0.381)
		(layer "F.Cu")
		(net "P3V3_AUX")
	)
	(segment
		(start 181.869334 -56.352948)
		(end 181.177184 -56.352948)
		(width 0.381)
		(layer "F.Cu")
		(net "P3V3_AUX")
	)
	(segment
		(start 156.554678 -45.64888)
		(end 156.554678 -46.286166)
		(width 0.4572)
		(layer "F.Cu")
		(net "P3V3_AUX")
	)
	(segment
		(start 182.664608 -414.186624)
		(end 183.168798 -414.186624)
		(width 0.381)
		(layer "F.Cu")
		(net "P3V3_AUX")
	)
	(segment
		(start 83.442048 -312.32475)
		(end 73.33361 -312.32475)
		(width 0.4572)
		(layer "F.Cu")
		(net "P3V3_AUX")
	)
	(segment
		(start 177.748946 -413.414972)
		(end 177.19294 -413.414972)
		(width 0.381)
		(layer "F.Cu")
		(net "P3V3_AUX")
	)
	(segment
		(start 102.76205 -77.216)
		(end 104.14 -77.216)
		(width 0.381)
		(layer "F.Cu")
		(net "P3V3_AUX")
	)
	(segment
		(start 217.481912 -68.340478)
		(end 216.819734 -68.340478)
		(width 0.4572)
		(layer "F.Cu")
		(net "P3V3_AUX")
	)
	(segment
		(start 332.25994 -16.379444)
		(end 332.25994 -16.995394)
		(width 0.4572)
		(layer "F.Cu")
		(net "P3V3_AUX")
	)
	(segment
		(start 295.169844 -19.433286)
		(end 295.169844 -18.780506)
		(width 0.381)
		(layer "F.Cu")
		(net "P3V3_AUX")
	)
	(segment
		(start 286.19323 -397.570198)
		(end 286.19323 -398.235932)
		(width 0.4318)
		(layer "F.Cu")
		(net "P3V3_AUX")
	)
	(segment
		(start 159.18307 -76.93152)
		(end 159.18307 -77.496924)
		(width 0.4572)
		(layer "F.Cu")
		(net "P3V3_AUX")
	)
	(segment
		(start 454.847452 -20.902168)
		(end 454.2155 -20.902168)
		(width 0.3556)
		(layer "F.Cu")
		(net "P3V3_AUX")
	)
	(segment
		(start 163.30295 -110.200948)
		(end 162.359594 -110.200948)
		(width 0.4572)
		(layer "F.Cu")
		(net "P3V3_AUX")
	)
	(segment
		(start 181.17185 -40.071548)
		(end 181.42585 -40.325548)
		(width 0.4572)
		(layer "F.Cu")
		(net "P3V3_AUX")
	)
	(segment
		(start 36.795964 -193.93535)
		(end 37.938964 -193.93535)
		(width 0.4572)
		(layer "F.Cu")
		(net "P3V3_AUX")
	)
	(segment
		(start 297.886374 -115.148614)
		(end 298.495974 -115.148614)
		(width 0.4572)
		(layer "F.Cu")
		(net "P3V3_AUX")
	)
	(segment
		(start 300.172628 -14.47673)
		(end 300.167548 -14.48181)
		(width 0.381)
		(layer "F.Cu")
		(net "P3V3_AUX")
	)
	(segment
		(start 55.35295 -39.751)
		(end 54.737254 -39.751)
		(width 0.381)
		(layer "F.Cu")
		(net "P3V3_AUX")
	)
	(segment
		(start 338.683346 -24.297386)
		(end 338.683346 -24.913336)
		(width 0.4064)
		(layer "F.Cu")
		(net "P3V3_AUX")
	)
	(segment
		(start 274.169124 -122.880628)
		(end 273.75739 -122.880628)
		(width 0.381)
		(layer "F.Cu")
		(net "P3V3_AUX")
	)
	(segment
		(start 64.83858 -54.62143)
		(end 64.197484 -54.62143)
		(width 0.381)
		(layer "F.Cu")
		(net "P3V3_AUX")
	)
	(segment
		(start 165.576758 -352.67011)
		(end 165.576758 -353.332796)
		(width 0.381)
		(layer "F.Cu")
		(net "P3V3_AUX")
	)
	(segment
		(start 19.640804 -36.878514)
		(end 20.250404 -36.878514)
		(width 0.381)
		(layer "F.Cu")
		(net "P3V3_AUX")
	)
	(segment
		(start 163.30295 -112.359948)
		(end 162.433 -112.359948)
		(width 0.4572)
		(layer "F.Cu")
		(net "P3V3_AUX")
	)
	(segment
		(start 137.46353 -55.484014)
		(end 137.33653 -55.357014)
		(width 0.4572)
		(layer "F.Cu")
		(net "P3V3_AUX")
	)
	(segment
		(start 255.312926 -74.44105)
		(end 256.685034 -74.44105)
		(width 0.381)
		(layer "F.Cu")
		(net "P3V3_AUX")
	)
	(segment
		(start 429.755808 -431.532538)
		(end 429.755808 -430.891188)
		(width 0.381)
		(layer "F.Cu")
		(net "P3V3_AUX")
	)
	(segment
		(start 21.70811 -193.93535)
		(end 22.85111 -193.93535)
		(width 0.4572)
		(layer "F.Cu")
		(net "P3V3_AUX")
	)
	(segment
		(start 453.319896 -102.598728)
		(end 452.710296 -102.598728)
		(width 0.381)
		(layer "F.Cu")
		(net "P3V3_AUX")
	)
	(segment
		(start 146.53895 -121.793)
		(end 146.53895 -122.53595)
		(width 0.381)
		(layer "F.Cu")
		(net "P3V3_AUX")
	)
	(segment
		(start 55.35295 -39.125144)
		(end 55.35295 -39.751)
		(width 0.381)
		(layer "F.Cu")
		(net "P3V3_AUX")
	)
	(segment
		(start 371.272308 -425.018708)
		(end 370.660676 -425.63034)
		(width 0.381)
		(layer "F.Cu")
		(net "P3V3_AUX")
	)
	(segment
		(start 292.280086 -193.935096)
		(end 293.423086 -193.935096)
		(width 0.4572)
		(layer "F.Cu")
		(net "P3V3_AUX")
	)
	(segment
		(start 458.637386 -103.646224)
		(end 458.668882 -103.614728)
		(width 0.381)
		(layer "F.Cu")
		(net "P3V3_AUX")
	)
	(segment
		(start 100.342192 -31.395162)
		(end 100.342192 -30.779212)
		(width 0.381)
		(layer "F.Cu")
		(net "P3V3_AUX")
	)
	(segment
		(start 25.613868 -436.483252)
		(end 26.056082 -436.483252)
		(width 0.381)
		(layer "F.Cu")
		(net "P3V3_AUX")
	)
	(segment
		(start 32.891222 -434.173884)
		(end 31.764732 -434.173884)
		(width 0.381)
		(layer "F.Cu")
		(net "P3V3_AUX")
	)
	(segment
		(start 276.952202 -111.91367)
		(end 276.342602 -111.91367)
		(width 0.381)
		(layer "F.Cu")
		(net "P3V3_AUX")
	)
	(segment
		(start 205.121256 -103.762048)
		(end 205.121256 -102.56647)
		(width 0.381)
		(layer "F.Cu")
		(net "P3V3_AUX")
	)
	(segment
		(start 166.8272 -429.57115)
		(end 167.256714 -429.141636)
		(width 0.381)
		(layer "F.Cu")
		(net "P3V3_AUX")
	)
	(segment
		(start 204.12075 -97.772728)
		(end 204.592936 -98.244914)
		(width 0.381)
		(layer "F.Cu")
		(net "P3V3_AUX")
	)
	(segment
		(start 200.487026 -113.559844)
		(end 200.552558 -113.625376)
		(width 0.4064)
		(layer "F.Cu")
		(net "P3V3_AUX")
	)
	(segment
		(start 211.172298 -14.087094)
		(end 211.172298 -14.892528)
		(width 0.381)
		(layer "F.Cu")
		(net "P3V3_AUX")
	)
	(segment
		(start 197.669658 -124.801376)
		(end 197.799198 -124.801376)
		(width 0.4064)
		(layer "F.Cu")
		(net "P3V3_AUX")
	)
	(segment
		(start 273.778726 -118.618)
		(end 274.48256 -118.618)
		(width 0.381)
		(layer "F.Cu")
		(net "P3V3_AUX")
	)
	(segment
		(start 137.033762 -151.216614)
		(end 136.669018 -150.85187)
		(width 0.508)
		(layer "F.Cu")
		(net "P3V3_AUX")
	)
	(segment
		(start 154.677872 -65.700148)
		(end 154.398472 -65.420748)
		(width 0.381)
		(layer "F.Cu")
		(net "P3V3_AUX")
	)
	(segment
		(start 47.18304 -433.657502)
		(end 47.18304 -433.617878)
		(width 0.381)
		(layer "F.Cu")
		(net "P3V3_AUX")
	)
	(segment
		(start 210.464654 -15.425674)
		(end 210.9978 -14.892528)
		(width 0.381)
		(layer "F.Cu")
		(net "P3V3_AUX")
	)
	(segment
		(start 463.770218 -109.646212)
		(end 464.434682 -109.646212)
		(width 0.381)
		(layer "F.Cu")
		(net "P3V3_AUX")
	)
	(segment
		(start 178.221894 -354.366322)
		(end 178.229006 -354.373434)
		(width 0.508)
		(layer "F.Cu")
		(net "P3V3_AUX")
	)
	(segment
		(start 372.06682 -14.999716)
		(end 371.904006 -14.836902)
		(width 0.508)
		(layer "F.Cu")
		(net "P3V3_AUX")
	)
	(segment
		(start 136.544558 -61.88202)
		(end 136.188958 -61.88202)
		(width 0.4572)
		(layer "F.Cu")
		(net "P3V3_AUX")
	)
	(segment
		(start 42.52595 -436.499)
		(end 42.545 -436.51805)
		(width 0.381)
		(layer "F.Cu")
		(net "P3V3_AUX")
	)
	(segment
		(start 157.037024 -27.08783)
		(end 156.406088 -27.08783)
		(width 0.4572)
		(layer "F.Cu")
		(net "P3V3_AUX")
	)
	(segment
		(start 105.485946 -56.058054)
		(end 104.86644 -56.67756)
		(width 0.381)
		(layer "F.Cu")
		(net "P3V3_AUX")
	)
	(segment
		(start 301.841408 -114.859308)
		(end 301.231808 -114.859308)
		(width 0.381)
		(layer "F.Cu")
		(net "P3V3_AUX")
	)
	(segment
		(start 145.740628 -101.894132)
		(end 147.16379 -101.894132)
		(width 0.3556)
		(layer "F.Cu")
		(net "P3V3_AUX")
	)
	(segment
		(start 145.176748 -74.715116)
		(end 144.989042 -74.902822)
		(width 0.381)
		(layer "F.Cu")
		(net "P3V3_AUX")
	)
	(segment
		(start 214.339424 -22.630384)
		(end 214.613744 -22.904704)
		(width 0.381)
		(layer "F.Cu")
		(net "P3V3_AUX")
	)
	(segment
		(start 279.022556 -438.401714)
		(end 279.653492 -438.401714)
		(width 0.381)
		(layer "F.Cu")
		(net "P3V3_AUX")
	)
	(segment
		(start 145.363438 -40.003476)
		(end 143.88084 -40.003476)
		(width 0.508)
		(layer "F.Cu")
		(net "P3V3_AUX")
	)
	(segment
		(start 136.188958 -61.88202)
		(end 134.614158 -61.88202)
		(width 0.4064)
		(layer "F.Cu")
		(net "P3V3_AUX")
	)
	(segment
		(start 316.408562 -118.898162)
		(end 316.421008 -118.910608)
		(width 0.381)
		(layer "F.Cu")
		(net "P3V3_AUX")
	)
	(segment
		(start 20.860258 -428.589948)
		(end 20.860258 -427.980348)
		(width 0.3556)
		(layer "F.Cu")
		(net "P3V3_AUX")
	)
	(segment
		(start 314.967366 -110.55477)
		(end 315.576966 -110.55477)
		(width 0.381)
		(layer "F.Cu")
		(net "P3V3_AUX")
	)
	(segment
		(start 166.228014 -114.318796)
		(end 166.228014 -114.202972)
		(width 0.4572)
		(layer "F.Cu")
		(net "P3V3_AUX")
	)
	(segment
		(start 140.846302 -60.458096)
		(end 141.114018 -60.19038)
		(width 0.4572)
		(layer "F.Cu")
		(net "P3V3_AUX")
	)
	(segment
		(start 170.970702 -439.340244)
		(end 170.970702 -438.724294)
		(width 0.381)
		(layer "F.Cu")
		(net "P3V3_AUX")
	)
	(segment
		(start 145.074894 -59.898534)
		(end 144.458944 -59.898534)
		(width 0.4572)
		(layer "F.Cu")
		(net "P3V3_AUX")
	)
	(segment
		(start 359.568242 -406.967436)
		(end 358.766618 -406.967436)
		(width 0.381)
		(layer "F.Cu")
		(net "P3V3_AUX")
	)
	(segment
		(start 254.192786 -125.52045)
		(end 254.192786 -126.91745)
		(width 0.381)
		(layer "F.Cu")
		(net "P3V3_AUX")
	)
	(segment
		(start 119.36095 -427.208696)
		(end 119.36095 -426.72)
		(width 0.381)
		(layer "F.Cu")
		(net "P3V3_AUX")
	)
	(segment
		(start 428.120302 -433.986686)
		(end 427.489366 -433.986686)
		(width 0.381)
		(layer "F.Cu")
		(net "P3V3_AUX")
	)
	(segment
		(start 19.663664 -365.649002)
		(end 20.50796 -365.649002)
		(width 0.381)
		(layer "F.Cu")
		(net "P3V3_AUX")
	)
	(segment
		(start 114.12982 -67.41922)
		(end 114.12982 -68.811394)
		(width 0.381)
		(layer "F.Cu")
		(net "P3V3_AUX")
	)
	(segment
		(start 299.82414 -193.935096)
		(end 300.96714 -193.935096)
		(width 0.4572)
		(layer "F.Cu")
		(net "P3V3_AUX")
	)
	(segment
		(start 254.192786 -125.52045)
		(end 254.192786 -124.50445)
		(width 0.381)
		(layer "F.Cu")
		(net "P3V3_AUX")
	)
	(segment
		(start 369.455446 -27.906472)
		(end 369.455446 -27.290522)
		(width 0.4572)
		(layer "F.Cu")
		(net "P3V3_AUX")
	)
	(segment
		(start 461.557878 -94.317566)
		(end 461.517746 -94.277434)
		(width 0.381)
		(layer "F.Cu")
		(net "P3V3_AUX")
	)
	(segment
		(start 412.551626 -364.3503)
		(end 412.82239 -364.079536)
		(width 0.3556)
		(layer "F.Cu")
		(net "P3V3_AUX")
	)
	(segment
		(start 211.932266 -111.646208)
		(end 211.862924 -111.576866)
		(width 0.381)
		(layer "F.Cu")
		(net "P3V3_AUX")
	)
	(segment
		(start 377.541536 -32.723582)
		(end 376.89028 -32.723582)
		(width 0.4572)
		(layer "F.Cu")
		(net "P3V3_AUX")
	)
	(segment
		(start 429.774604 -430.872392)
		(end 429.774604 -429.706278)
		(width 0.2286)
		(layer "F.Cu")
		(net "P3V3_AUX")
	)
	(segment
		(start 403.5552 -77.113384)
		(end 402.917914 -77.113384)
		(width 0.4064)
		(layer "F.Cu")
		(net "P3V3_AUX")
	)
	(segment
		(start 115.856512 -17.784064)
		(end 117.513862 -17.784064)
		(width 0.508)
		(layer "F.Cu")
		(net "P3V3_AUX")
	)
	(segment
		(start 188.322204 -117.052852)
		(end 188.712094 -117.442742)
		(width 0.254)
		(layer "F.Cu")
		(net "P3V3_AUX")
	)
	(segment
		(start 32.19704 -426.920152)
		(end 32.19704 -427.325282)
		(width 0.4572)
		(layer "F.Cu")
		(net "P3V3_AUX")
	)
	(segment
		(start 140.846302 -60.849764)
		(end 140.846302 -60.458096)
		(width 0.4572)
		(layer "F.Cu")
		(net "P3V3_AUX")
	)
	(segment
		(start 31.764732 -434.173884)
		(end 31.043118 -433.45227)
		(width 0.381)
		(layer "F.Cu")
		(net "P3V3_AUX")
	)
	(segment
		(start 417.86937 -354.17633)
		(end 417.27374 -354.17633)
		(width 0.3556)
		(layer "F.Cu")
		(net "P3V3_AUX")
	)
	(segment
		(start 398.797272 -134.92988)
		(end 398.797272 -135.66013)
		(width 0.4064)
		(layer "F.Cu")
		(net "P3V3_AUX")
	)
	(segment
		(start 270.073628 -113.156746)
		(end 270.680434 -113.156746)
		(width 0.381)
		(layer "F.Cu")
		(net "P3V3_AUX")
	)
	(segment
		(start 39.459662 -429.390048)
		(end 39.459662 -428.712122)
		(width 0.381)
		(layer "F.Cu")
		(net "P3V3_AUX")
	)
	(segment
		(start 104.843834 -134.890002)
		(end 104.843834 -133.30428)
		(width 0.508)
		(layer "F.Cu")
		(net "P3V3_AUX")
	)
	(segment
		(start 36.18611 -422.273222)
		(end 36.18611 -422.418002)
		(width 0.254)
		(layer "F.Cu")
		(net "P3V3_AUX")
	)
	(segment
		(start 161.30524 -36.339272)
		(end 159.932116 -36.339272)
		(width 0.4572)
		(layer "F.Cu")
		(net "P3V3_AUX")
	)
	(segment
		(start 178.671474 -163.01847)
		(end 173.314614 -168.37533)
		(width 0.4572)
		(layer "F.Cu")
		(net "P3V3_AUX")
	)
	(segment
		(start 461.169004 -107.018836)
		(end 461.193896 -107.043728)
		(width 0.381)
		(layer "F.Cu")
		(net "P3V3_AUX")
	)
	(segment
		(start 178.72202 -118.652798)
		(end 178.33213 -119.042688)
		(width 0.254)
		(layer "F.Cu")
		(net "P3V3_AUX")
	)
	(segment
		(start 7.254748 -131.32435)
		(end 7.934198 -131.32435)
		(width 0.381)
		(layer "F.Cu")
		(net "P3V3_AUX")
	)
	(segment
		(start 213.19744 -29.846778)
		(end 213.19744 -29.175202)
		(width 0.4064)
		(layer "F.Cu")
		(net "P3V3_AUX")
	)
	(segment
		(start 168.527984 -193.93535)
		(end 169.670984 -193.93535)
		(width 0.4572)
		(layer "F.Cu")
		(net "P3V3_AUX")
	)
	(segment
		(start 297.886374 -117.942614)
		(end 298.495974 -117.942614)
		(width 0.381)
		(layer "F.Cu")
		(net "P3V3_AUX")
	)
	(segment
		(start 266.975082 -122.782076)
		(end 267.615162 -122.782076)
		(width 0.381)
		(layer "F.Cu")
		(net "P3V3_AUX")
	)
	(segment
		(start 215.58123 -41.341548)
		(end 215.58123 -40.674798)
		(width 0.4572)
		(layer "F.Cu")
		(net "P3V3_AUX")
	)
	(segment
		(start 445.557148 -92.468192)
		(end 446.2272 -92.468192)
		(width 0.381)
		(layer "F.Cu")
		(net "P3V3_AUX")
	)
	(segment
		(start 460.529686 -99.164394)
		(end 461.187038 -99.164394)
		(width 0.381)
		(layer "F.Cu")
		(net "P3V3_AUX")
	)
	(segment
		(start 173.314614 -168.37533)
		(end 169.604182 -169.912284)
		(width 0.4572)
		(layer "F.Cu")
		(net "P3V3_AUX")
	)
	(segment
		(start 281.686 -423.81805)
		(end 281.686 -424.461178)
		(width 0.381)
		(layer "F.Cu")
		(net "P3V3_AUX")
	)
	(segment
		(start 431.55616 -193.935096)
		(end 432.69916 -193.935096)
		(width 0.4572)
		(layer "F.Cu")
		(net "P3V3_AUX")
	)
	(segment
		(start 128.506728 -47.121064)
		(end 127.890778 -47.121064)
		(width 0.381)
		(layer "F.Cu")
		(net "P3V3_AUX")
	)
	(segment
		(start 139.845542 -101.494844)
		(end 140.486892 -101.494844)
		(width 0.4064)
		(layer "F.Cu")
		(net "P3V3_AUX")
	)
	(segment
		(start 254.192786 -117.51945)
		(end 253.583186 -117.51945)
		(width 0.381)
		(layer "F.Cu")
		(net "P3V3_AUX")
	)
	(segment
		(start 254.192786 -121.71045)
		(end 253.583186 -121.71045)
		(width 0.381)
		(layer "F.Cu")
		(net "P3V3_AUX")
	)
	(segment
		(start 454.2155 -20.902168)
		(end 454.203816 -20.913852)
		(width 0.3556)
		(layer "F.Cu")
		(net "P3V3_AUX")
	)
	(segment
		(start 54.114446 -323.279516)
		(end 25.6667 -323.279516)
		(width 0.4572)
		(layer "F.Cu")
		(net "P3V3_AUX")
	)
	(segment
		(start 320.571368 -115.410488)
		(end 321.367658 -115.410488)
		(width 0.381)
		(layer "F.Cu")
		(net "P3V3_AUX")
	)
	(segment
		(start 341.33536 -16.379444)
		(end 341.33536 -16.995394)
		(width 0.4572)
		(layer "F.Cu")
		(net "P3V3_AUX")
	)
	(segment
		(start 363.718094 -418.360098)
		(end 364.213394 -418.855398)
		(width 0.381)
		(layer "F.Cu")
		(net "P3V3_AUX")
	)
	(segment
		(start 277.608792 -121.77522)
		(end 278.242776 -121.77522)
		(width 0.381)
		(layer "F.Cu")
		(net "P3V3_AUX")
	)
	(segment
		(start 119.017796 -53.49748)
		(end 119.017796 -54.128416)
		(width 0.4572)
		(layer "F.Cu")
		(net "P3V3_AUX")
	)
	(segment
		(start 21.577046 -97.083626)
		(end 22.23008 -97.083626)
		(width 0.381)
		(layer "F.Cu")
		(net "P3V3_AUX")
	)
	(segment
		(start 182.123334 -56.098948)
		(end 181.869334 -56.352948)
		(width 0.381)
		(layer "F.Cu")
		(net "P3V3_AUX")
	)
	(segment
		(start 86.08695 -72.39)
		(end 86.08695 -70.97395)
		(width 0.381)
		(layer "F.Cu")
		(net "P3V3_AUX")
	)
	(segment
		(start 314.537852 -119.475504)
		(end 315.308996 -119.475504)
		(width 0.381)
		(layer "F.Cu")
		(net "P3V3_AUX")
	)
	(segment
		(start 191.055498 -426.229526)
		(end 191.729106 -426.229526)
		(width 0.381)
		(layer "F.Cu")
		(net "P3V3_AUX")
	)
	(segment
		(start 105.918 -422.89095)
		(end 104.234488 -422.89095)
		(width 0.381)
		(layer "F.Cu")
		(net "P3V3_AUX")
	)
	(segment
		(start 430.677066 -101.97719)
		(end 430.677066 -102.61219)
		(width 0.4572)
		(layer "F.Cu")
		(net "P3V3_AUX")
	)
	(segment
		(start 429.299116 -110.273084)
		(end 429.299116 -109.66704)
		(width 0.4572)
		(layer "F.Cu")
		(net "P3V3_AUX")
	)
	(segment
		(start 136.669018 -150.85187)
		(end 136.669018 -150.533608)
		(width 0.508)
		(layer "F.Cu")
		(net "P3V3_AUX")
	)
	(segment
		(start 275.174202 -119.91467)
		(end 274.619466 -119.91467)
		(width 0.381)
		(layer "F.Cu")
		(net "P3V3_AUX")
	)
	(segment
		(start 95.79102 -60.86221)
		(end 96.523048 -60.86221)
		(width 0.254)
		(layer "F.Cu")
		(net "P3V3_AUX")
	)
	(segment
		(start 171.426632 -417.678616)
		(end 171.426632 -417.698174)
		(width 0.381)
		(layer "F.Cu")
		(net "P3V3_AUX")
	)
	(segment
		(start 55.573676 -38.904418)
		(end 55.35295 -39.125144)
		(width 0.381)
		(layer "F.Cu")
		(net "P3V3_AUX")
	)
	(segment
		(start 294.681402 -366.08004)
		(end 294.681402 -367.189258)
		(width 0.381)
		(layer "F.Cu")
		(net "P3V3_AUX")
	)
	(segment
		(start 255.780794 -137.648696)
		(end 255.149858 -137.648696)
		(width 0.381)
		(layer "F.Cu")
		(net "P3V3_AUX")
	)
	(segment
		(start 8.979408 -423.821098)
		(end 8.363458 -423.821098)
		(width 0.381)
		(layer "F.Cu")
		(net "P3V3_AUX")
	)
	(segment
		(start 105.24871 -59.802268)
		(end 104.63276 -59.802268)
		(width 0.4572)
		(layer "F.Cu")
		(net "P3V3_AUX")
	)
	(segment
		(start 361.16006 -418.329618)
		(end 361.77601 -418.329618)
		(width 0.381)
		(layer "F.Cu")
		(net "P3V3_AUX")
	)
	(segment
		(start 363.962188 -411.369764)
		(end 363.962188 -411.048962)
		(width 0.381)
		(layer "F.Cu")
		(net "P3V3_AUX")
	)
	(segment
		(start 138.026902 -55.484014)
		(end 137.46353 -55.484014)
		(width 0.4572)
		(layer "F.Cu")
		(net "P3V3_AUX")
	)
	(segment
		(start 181.42585 -40.325548)
		(end 181.42585 -42.12209)
		(width 0.4572)
		(layer "F.Cu")
		(net "P3V3_AUX")
	)
	(segment
		(start 74.35596 -57.15)
		(end 74.422 -57.08396)
		(width 0.381)
		(layer "F.Cu")
		(net "P3V3_AUX")
	)
	(segment
		(start 210.9978 -14.892528)
		(end 211.172298 -14.892528)
		(width 0.381)
		(layer "F.Cu")
		(net "P3V3_AUX")
	)
	(segment
		(start 97.279968 -426.217334)
		(end 98.36785 -426.217334)
		(width 0.4064)
		(layer "F.Cu")
		(net "P3V3_AUX")
	)
	(segment
		(start 370.813584 -14.836902)
		(end 370.03228 -14.836902)
		(width 0.508)
		(layer "F.Cu")
		(net "P3V3_AUX")
	)
	(segment
		(start 425.54144 -437.813958)
		(end 425.54144 -437.198008)
		(width 0.381)
		(layer "F.Cu")
		(net "P3V3_AUX")
	)
	(segment
		(start 302.20412 -424.9547)
		(end 302.20412 -424.555158)
		(width 0.381)
		(layer "F.Cu")
		(net "P3V3_AUX")
	)
	(segment
		(start 413.916368 -365.764064)
		(end 413.880808 -365.728504)
		(width 0.3556)
		(layer "F.Cu")
		(net "P3V3_AUX")
	)
	(segment
		(start 418.286692 -58.397648)
		(end 418.316664 -58.42762)
		(width 0.4064)
		(layer "F.Cu")
		(net "P3V3_AUX")
	)
	(segment
		(start 150.100792 -53.083714)
		(end 149.413976 -53.083714)
		(width 0.381)
		(layer "F.Cu")
		(net "P3V3_AUX")
	)
	(segment
		(start 274.425664 -122.624088)
		(end 274.169124 -122.880628)
		(width 0.381)
		(layer "F.Cu")
		(net "P3V3_AUX")
	)
	(segment
		(start 217.676222 -101.228398)
		(end 217.36685 -101.53777)
		(width 0.381)
		(layer "F.Cu")
		(net "P3V3_AUX")
	)
	(segment
		(start 131.894072 -40.723312)
		(end 131.894072 -42.526712)
		(width 0.1778)
		(layer "F.Cu")
		(net "P3V3_AUX")
	)
	(segment
		(start 36.281868 -437.449214)
		(end 36.897818 -437.449214)
		(width 0.381)
		(layer "F.Cu")
		(net "P3V3_AUX")
	)
	(segment
		(start 210.208622 -125.234446)
		(end 210.573112 -124.869956)
		(width 0.4064)
		(layer "F.Cu")
		(net "P3V3_AUX")
	)
	(segment
		(start 300.167548 -15.62481)
		(end 300.785276 -15.62481)
		(width 0.381)
		(layer "F.Cu")
		(net "P3V3_AUX")
	)
	(segment
		(start 74.422 -56.53405)
		(end 73.66 -56.53405)
		(width 0.381)
		(layer "F.Cu")
		(net "P3V3_AUX")
	)
	(segment
		(start 177.171604 -413.436308)
		(end 176.79162 -413.436308)
		(width 0.381)
		(layer "F.Cu")
		(net "P3V3_AUX")
	)
	(segment
		(start 163.02355 -440.182)
		(end 163.02355 -439.551064)
		(width 0.381)
		(layer "F.Cu")
		(net "P3V3_AUX")
	)
	(segment
		(start 124.233178 -49.153064)
		(end 123.617228 -49.153064)
		(width 0.4572)
		(layer "F.Cu")
		(net "P3V3_AUX")
	)
	(segment
		(start 166.43604 -96.204786)
		(end 166.43604 -96.602042)
		(width 0.381)
		(layer "F.Cu")
		(net "P3V3_AUX")
	)
	(segment
		(start 12.982956 -92.287598)
		(end 12.982956 -91.658948)
		(width 0.381)
		(layer "F.Cu")
		(net "P3V3_AUX")
	)
	(segment
		(start 453.319896 -106.408728)
		(end 452.710296 -106.408728)
		(width 0.381)
		(layer "F.Cu")
		(net "P3V3_AUX")
	)
	(segment
		(start 259.6769 -138.048746)
		(end 259.131308 -137.503154)
		(width 0.1778)
		(layer "F.Cu")
		(net "P3V3_AUX")
	)
	(segment
		(start 49.38395 -39.751)
		(end 49.38395 -39.310564)
		(width 0.381)
		(layer "F.Cu")
		(net "P3V3_AUX")
	)
	(segment
		(start 158.93796 -37.333428)
		(end 158.885128 -37.333428)
		(width 0.4572)
		(layer "F.Cu")
		(net "P3V3_AUX")
	)
	(segment
		(start 20.880832 -411.707584)
		(end 20.880832 -410.564584)
		(width 0.381)
		(layer "F.Cu")
		(net "P3V3_AUX")
	)
	(segment
		(start 38.0746 -437.627014)
		(end 38.733984 -437.627014)
		(width 0.381)
		(layer "F.Cu")
		(net "P3V3_AUX")
	)
	(segment
		(start 307.368194 -193.935096)
		(end 308.511194 -193.935096)
		(width 0.4572)
		(layer "F.Cu")
		(net "P3V3_AUX")
	)
	(segment
		(start 280.070306 -430.791366)
		(end 280.707592 -430.791366)
		(width 0.381)
		(layer "F.Cu")
		(net "P3V3_AUX")
	)
	(segment
		(start 179.244752 -419.231318)
		(end 180.177694 -419.231318)
		(width 0.381)
		(layer "F.Cu")
		(net "P3V3_AUX")
	)
	(segment
		(start 103.886 -422.542462)
		(end 103.886 -422.21404)
		(width 0.381)
		(layer "F.Cu")
		(net "P3V3_AUX")
	)
	(segment
		(start 365.821976 -423.602912)
		(end 365.766858 -423.65803)
		(width 0.381)
		(layer "F.Cu")
		(net "P3V3_AUX")
	)
	(segment
		(start 192.951608 -95.66529)
		(end 192.951608 -95.087948)
		(width 0.4572)
		(layer "F.Cu")
		(net "P3V3_AUX")
	)
	(segment
		(start 110.152942 -19.58975)
		(end 110.152942 -18.78584)
		(width 0.381)
		(layer "F.Cu")
		(net "P3V3_AUX")
	)
	(segment
		(start 133.094222 -33.023556)
		(end 133.094222 -32.236156)
		(width 0.1778)
		(layer "F.Cu")
		(net "P3V3_AUX")
	)
	(segment
		(start 162.275012 -435.467506)
		(end 161.999676 -435.742842)
		(width 0.381)
		(layer "F.Cu")
		(net "P3V3_AUX")
	)
	(segment
		(start 290.744402 -124.414026)
		(end 290.744402 -125.049026)
		(width 0.4572)
		(layer "F.Cu")
		(net "P3V3_AUX")
	)
	(segment
		(start 111.251238 -43.65498)
		(end 111.251238 -43.358054)
		(width 0.381)
		(layer "F.Cu")
		(net "P3V3_AUX")
	)
	(segment
		(start 461.193896 -107.043728)
		(end 461.193896 -107.678728)
		(width 0.381)
		(layer "F.Cu")
		(net "P3V3_AUX")
	)
	(segment
		(start 16.373348 -421.2336)
		(end 16.373348 -420.528496)
		(width 0.254)
		(layer "F.Cu")
		(net "P3V3_AUX")
	)
	(segment
		(start 85.65896 -70.54596)
		(end 85.299042 -70.54596)
		(width 0.381)
		(layer "F.Cu")
		(net "P3V3_AUX")
	)
	(segment
		(start 120.79605 -431.038)
		(end 121.539 -431.038)
		(width 0.381)
		(layer "F.Cu")
		(net "P3V3_AUX")
	)
	(segment
		(start 251.074174 -132.337556)
		(end 251.074174 -131.067556)
		(width 0.4064)
		(layer "F.Cu")
		(net "P3V3_AUX")
	)
	(segment
		(start 147.187412 -57.676034)
		(end 147.42668 -57.676034)
		(width 0.254)
		(layer "F.Cu")
		(net "P3V3_AUX")
	)
	(segment
		(start 14.4526 -79.0194)
		(end 13.90396 -79.0194)
		(width 0.4064)
		(layer "F.Cu")
		(net "P3V3_AUX")
	)
	(segment
		(start 74.10831 -38.5699)
		(end 75.268074 -38.5699)
		(width 0.2286)
		(layer "F.Cu")
		(net "P3V3_AUX")
	)
	(segment
		(start 269.868142 -108.472986)
		(end 268.680692 -108.472986)
		(width 0.3556)
		(layer "F.Cu")
		(net "P3V3_AUX")
	)
	(segment
		(start 438.277 -95.957898)
		(end 438.9882 -95.957898)
		(width 0.381)
		(layer "F.Cu")
		(net "P3V3_AUX")
	)
	(segment
		(start 65.643506 -55.375556)
		(end 65.643506 -54.356)
		(width 0.381)
		(layer "F.Cu")
		(net "P3V3_AUX")
	)
	(segment
		(start 157.922722 -196.264784)
		(end 157.922722 -197.24878)
		(width 0.4572)
		(layer "F.Cu")
		(net "P3V3_AUX")
	)
	(segment
		(start 202.577954 -97.772728)
		(end 204.12075 -97.772728)
		(width 0.381)
		(layer "F.Cu")
		(net "P3V3_AUX")
	)
	(segment
		(start 202.79995 -99.695)
		(end 202.79995 -99.95408)
		(width 0.381)
		(layer "F.Cu")
		(net "P3V3_AUX")
	)
	(segment
		(start 70.46976 -57.291986)
		(end 70.739 -57.291986)
		(width 0.381)
		(layer "F.Cu")
		(net "P3V3_AUX")
	)
	(segment
		(start 252.62205 -38.683946)
		(end 252.62205 -39.262558)
		(width 0.4572)
		(layer "F.Cu")
		(net "P3V3_AUX")
	)
	(segment
		(start 162.77971 -436.799736)
		(end 163.02355 -437.043576)
		(width 0.381)
		(layer "F.Cu")
		(net "P3V3_AUX")
	)
	(segment
		(start 54.708552 -322.68541)
		(end 54.114446 -323.279516)
		(width 0.4572)
		(layer "F.Cu")
		(net "P3V3_AUX")
	)
	(segment
		(start 146.138392 -121.793)
		(end 146.53895 -121.793)
		(width 0.381)
		(layer "F.Cu")
		(net "P3V3_AUX")
	)
	(segment
		(start 254.192786 -118.91645)
		(end 253.583186 -118.91645)
		(width 0.381)
		(layer "F.Cu")
		(net "P3V3_AUX")
	)
	(segment
		(start 34.633662 -418.239448)
		(end 34.633662 -418.849048)
		(width 0.381)
		(layer "F.Cu")
		(net "P3V3_AUX")
	)
	(segment
		(start 86.241128 -309.52567)
		(end 83.442048 -312.32475)
		(width 0.4572)
		(layer "F.Cu")
		(net "P3V3_AUX")
	)
	(segment
		(start 366.415066 -423.602912)
		(end 366.415066 -423.031412)
		(width 0.381)
		(layer "F.Cu")
		(net "P3V3_AUX")
	)
	(segment
		(start 106.04881 -57.486042)
		(end 106.70921 -57.486042)
		(width 0.4572)
		(layer "F.Cu")
		(net "P3V3_AUX")
	)
	(segment
		(start 37.333428 -134.873238)
		(end 36.720018 -134.873238)
		(width 0.3556)
		(layer "F.Cu")
		(net "P3V3_AUX")
	)
	(segment
		(start 217.36685 -101.53777)
		(end 217.36685 -101.92512)
		(width 0.381)
		(layer "F.Cu")
		(net "P3V3_AUX")
	)
	(segment
		(start 166.71671 -117.210332)
		(end 166.539418 -117.210332)
		(width 0.4572)
		(layer "F.Cu")
		(net "P3V3_AUX")
	)
	(segment
		(start 209.922872 -36.172394)
		(end 209.922618 -36.17214)
		(width 0.2286)
		(layer "F.Cu")
		(net "P3V3_AUX")
	)
	(segment
		(start 182.072788 -164.761418)
		(end 181.6989 -164.761418)
		(width 0.4064)
		(layer "F.Cu")
		(net "P3V3_AUX")
	)
	(segment
		(start 74.422 -57.08396)
		(end 74.422 -56.53405)
		(width 0.381)
		(layer "F.Cu")
		(net "P3V3_AUX")
	)
	(segment
		(start 144.76095 -119.761)
		(end 144.76095 -120.777)
		(width 0.381)
		(layer "F.Cu")
		(net "P3V3_AUX")
	)
	(segment
		(start 429.29556 -110.27664)
		(end 429.299116 -110.273084)
		(width 0.4572)
		(layer "F.Cu")
		(net "P3V3_AUX")
	)
	(segment
		(start 89.809828 -141.02461)
		(end 89.728802 -140.943584)
		(width 0.381)
		(layer "F.Cu")
		(net "P3V3_AUX")
	)
	(segment
		(start 119.36095 -426.72)
		(end 119.126 -426.72)
		(width 0.381)
		(layer "F.Cu")
		(net "P3V3_AUX")
	)
	(segment
		(start 118.21795 -431.038)
		(end 117.475 -431.038)
		(width 0.381)
		(layer "F.Cu")
		(net "P3V3_AUX")
	)
	(segment
		(start 269.868142 -109.122972)
		(end 268.680692 -109.122972)
		(width 0.3556)
		(layer "F.Cu")
		(net "P3V3_AUX")
	)
	(segment
		(start 14.078458 -417.784026)
		(end 14.43101 -417.431474)
		(width 0.381)
		(layer "F.Cu")
		(net "P3V3_AUX")
	)
	(segment
		(start 104.234488 -422.89095)
		(end 103.886 -422.542462)
		(width 0.381)
		(layer "F.Cu")
		(net "P3V3_AUX")
	)
	(segment
		(start 255.780794 -140.518896)
		(end 255.149858 -140.518896)
		(width 0.381)
		(layer "F.Cu")
		(net "P3V3_AUX")
	)
	(segment
		(start 105.44556 -65.57391)
		(end 104.82961 -65.57391)
		(width 0.381)
		(layer "F.Cu")
		(net "P3V3_AUX")
	)
	(segment
		(start 179.23764 -149.735794)
		(end 179.606448 -150.104602)
		(width 0.4064)
		(layer "F.Cu")
		(net "P3V3_AUX")
	)
	(segment
		(start 123.471686 -59.182)
		(end 122.739658 -59.182)
		(width 0.4572)
		(layer "F.Cu")
		(net "P3V3_AUX")
	)
	(segment
		(start 193.089022 -24.491442)
		(end 192.661032 -24.919432)
		(width 0.4572)
		(layer "F.Cu")
		(net "P3V3_AUX")
	)
	(segment
		(start 104.2289 -418.973)
		(end 104.507792 -419.251892)
		(width 0.381)
		(layer "F.Cu")
		(net "P3V3_AUX")
	)
	(segment
		(start 272.194274 -353.896422)
		(end 270.856202 -352.55835)
		(width 0.508)
		(layer "F.Cu")
		(net "P3V3_AUX")
	)
	(segment
		(start 24.216868 -435.290214)
		(end 24.216868 -435.925214)
		(width 0.381)
		(layer "F.Cu")
		(net "P3V3_AUX")
	)
	(segment
		(start 217.388186 -53.95595)
		(end 217.137488 -53.705252)
		(width 0.254)
		(layer "F.Cu")
		(net "P3V3_AUX")
	)
	(segment
		(start 35.65271 -426.510196)
		(end 35.502596 -426.510196)
		(width 0.1778)
		(layer "F.Cu")
		(net "P3V3_AUX")
	)
	(segment
		(start 371.904006 -14.836902)
		(end 370.813584 -14.836902)
		(width 0.508)
		(layer "F.Cu")
		(net "P3V3_AUX")
	)
	(segment
		(start 44.32935 -104.7369)
		(end 43.71848 -104.7369)
		(width 0.381)
		(layer "F.Cu")
		(net "P3V3_AUX")
	)
	(segment
		(start 96.928178 -403.844252)
		(end 97.230438 -403.541992)
		(width 0.3302)
		(layer "F.Cu")
		(net "P3V3_AUX")
	)
	(segment
		(start 17.7292 -68.128642)
		(end 18.405348 -68.128642)
		(width 0.381)
		(layer "F.Cu")
		(net "P3V3_AUX")
	)
	(segment
		(start 151.944324 -207.370426)
		(end 148.529548 -207.370426)
		(width 0.4572)
		(layer "F.Cu")
		(net "P3V3_AUX")
	)
	(segment
		(start 51.577494 -30.607508)
		(end 51.577494 -31.877508)
		(width 0.4064)
		(layer "F.Cu")
		(net "P3V3_AUX")
	)
	(segment
		(start 366.415066 -423.602912)
		(end 365.821976 -423.602912)
		(width 0.381)
		(layer "F.Cu")
		(net "P3V3_AUX")
	)
	(segment
		(start 254.40005 -38.92931)
		(end 253.98603 -39.34333)
		(width 0.4572)
		(layer "F.Cu")
		(net "P3V3_AUX")
	)
	(segment
		(start 295.4909 -369.375436)
		(end 296.2529 -369.375436)
		(width 0.381)
		(layer "F.Cu")
		(net "P3V3_AUX")
	)
	(segment
		(start 305.575208 -439.877962)
		(end 305.98745 -439.877962)
		(width 0.381)
		(layer "F.Cu")
		(net "P3V3_AUX")
	)
	(segment
		(start 436.796942 -403.00021)
		(end 435.06898 -403.00021)
		(width 0.381)
		(layer "F.Cu")
		(net "P3V3_AUX")
	)
	(segment
		(start 49.25695 -436.372)
		(end 49.276 -436.39105)
		(width 0.381)
		(layer "F.Cu")
		(net "P3V3_AUX")
	)
	(segment
		(start 327.692258 -101.88575)
		(end 327.692258 -102.52075)
		(width 0.381)
		(layer "F.Cu")
		(net "P3V3_AUX")
	)
	(segment
		(start 153.14295 -104.648)
		(end 152.370536 -104.648)
		(width 0.381)
		(layer "F.Cu")
		(net "P3V3_AUX")
	)
	(segment
		(start 186.722004 -112.25276)
		(end 187.111894 -111.86287)
		(width 0.254)
		(layer "F.Cu")
		(net "P3V3_AUX")
	)
	(segment
		(start 269.911068 -112.994186)
		(end 270.073628 -113.156746)
		(width 0.381)
		(layer "F.Cu")
		(net "P3V3_AUX")
	)
	(segment
		(start 82.071464 -19.542252)
		(end 82.070702 -19.543014)
		(width 0.4572)
		(layer "F.Cu")
		(net "P3V3_AUX")
	)
	(segment
		(start 251.074174 -131.067556)
		(end 250.458224 -131.067556)
		(width 0.381)
		(layer "F.Cu")
		(net "P3V3_AUX")
	)
	(segment
		(start 355.106732 -413.046418)
		(end 355.106732 -413.677354)
		(width 0.381)
		(layer "F.Cu")
		(net "P3V3_AUX")
	)
	(segment
		(start 124.167392 -16.50111)
		(end 124.929646 -16.50111)
		(width 0.4572)
		(layer "F.Cu")
		(net "P3V3_AUX")
	)
	(segment
		(start 297.886374 -112.354614)
		(end 298.495974 -112.354614)
		(width 0.381)
		(layer "F.Cu")
		(net "P3V3_AUX")
	)
	(segment
		(start 158.683198 -200.631552)
		(end 151.944324 -207.370426)
		(width 0.4572)
		(layer "F.Cu")
		(net "P3V3_AUX")
	)
	(segment
		(start 367.050066 -427.800262)
		(end 367.050066 -428.416212)
		(width 0.381)
		(layer "F.Cu")
		(net "P3V3_AUX")
	)
	(segment
		(start 359.059988 -415.992818)
		(end 358.422702 -415.992818)
		(width 0.381)
		(layer "F.Cu")
		(net "P3V3_AUX")
	)
	(segment
		(start 92.319094 -33.02127)
		(end 92.359734 -33.06191)
		(width 0.381)
		(layer "F.Cu")
		(net "P3V3_AUX")
	)
	(segment
		(start 212.593682 -115.716812)
		(end 211.899754 -115.716812)
		(width 0.381)
		(layer "F.Cu")
		(net "P3V3_AUX")
	)
	(segment
		(start 166.73195 -120.360948)
		(end 166.119556 -120.360948)
		(width 0.4572)
		(layer "F.Cu")
		(net "P3V3_AUX")
	)
	(segment
		(start 49.25695 -37.846)
		(end 48.893984 -37.846)
		(width 0.381)
		(layer "F.Cu")
		(net "P3V3_AUX")
	)
	(segment
		(start 185.922158 -112.25276)
		(end 186.312048 -111.86287)
		(width 0.254)
		(layer "F.Cu")
		(net "P3V3_AUX")
	)
	(segment
		(start 116.36121 -61.202062)
		(end 116.998496 -61.202062)
		(width 0.4572)
		(layer "F.Cu")
		(net "P3V3_AUX")
	)
	(segment
		(start 424.012106 -193.935096)
		(end 425.155106 -193.935096)
		(width 0.4572)
		(layer "F.Cu")
		(net "P3V3_AUX")
	)
	(segment
		(start 376.503692 -427.2153)
		(end 376.630692 -427.3423)
		(width 0.254)
		(layer "F.Cu")
		(net "P3V3_AUX")
	)
	(segment
		(start 25.789128 -39.074852)
		(end 24.629364 -39.074852)
		(width 0.2286)
		(layer "F.Cu")
		(net "P3V3_AUX")
	)
	(segment
		(start 429.755808 -430.891188)
		(end 429.774604 -430.872392)
		(width 0.2286)
		(layer "F.Cu")
		(net "P3V3_AUX")
	)
	(segment
		(start 412.551626 -364.889288)
		(end 412.551626 -364.3503)
		(width 0.3556)
		(layer "F.Cu")
		(net "P3V3_AUX")
	)
	(segment
		(start 413.044132 -365.381794)
		(end 412.551626 -364.889288)
		(width 0.3556)
		(layer "F.Cu")
		(net "P3V3_AUX")
	)
	(segment
		(start 187.522104 -112.25276)
		(end 187.911994 -111.86287)
		(width 0.254)
		(layer "F.Cu")
		(net "P3V3_AUX")
	)
	(segment
		(start 158.502858 -194.902836)
		(end 158.502858 -195.684648)
		(width 0.4572)
		(layer "F.Cu")
		(net "P3V3_AUX")
	)
	(segment
		(start 258.538472 -137.503154)
		(end 258.500372 -137.465054)
		(width 0.381)
		(layer "F.Cu")
		(net "P3V3_AUX")
	)
	(segment
		(start 49.276 -436.39105)
		(end 49.276 -437.019954)
		(width 0.381)
		(layer "F.Cu")
		(net "P3V3_AUX")
	)
	(segment
		(start 217.137488 -53.705252)
		(end 216.659714 -53.705252)
		(width 0.254)
		(layer "F.Cu")
		(net "P3V3_AUX")
	)
	(segment
		(start 153.14295 -105.311194)
		(end 153.14295 -104.648)
		(width 0.381)
		(layer "F.Cu")
		(net "P3V3_AUX")
	)
	(segment
		(start 36.519612 -428.012098)
		(end 36.519612 -427.377098)
		(width 0.381)
		(layer "F.Cu")
		(net "P3V3_AUX")
	)
	(segment
		(start 167.23106 -174.16526)
		(end 167.009318 -174.16526)
		(width 0.4572)
		(layer "F.Cu")
		(net "P3V3_AUX")
	)
	(segment
		(start 210.208622 -127.091694)
		(end 210.208622 -126.469648)
		(width 0.4064)
		(layer "F.Cu")
		(net "P3V3_AUX")
	)
	(segment
		(start 327.692258 -102.52075)
		(end 327.65492 -102.558088)
		(width 0.2286)
		(layer "F.Cu")
		(net "P3V3_AUX")
	)
	(segment
		(start 94.205552 -40.139112)
		(end 94.205552 -39.4335)
		(width 0.381)
		(layer "F.Cu")
		(net "P3V3_AUX")
	)
	(segment
		(start 254.192786 -113.32845)
		(end 254.192786 -114.72545)
		(width 0.4572)
		(layer "F.Cu")
		(net "P3V3_AUX")
	)
	(segment
		(start 284.317694 -435.904386)
		(end 284.317694 -435.288436)
		(width 0.381)
		(layer "F.Cu")
		(net "P3V3_AUX")
	)
	(segment
		(start 446.644268 -193.935096)
		(end 447.787268 -193.935096)
		(width 0.4572)
		(layer "F.Cu")
		(net "P3V3_AUX")
	)
	(segment
		(start 118.999 -435.50205)
		(end 118.364 -435.50205)
		(width 0.381)
		(layer "F.Cu")
		(net "P3V3_AUX")
	)
	(segment
		(start 113.684304 -418.699696)
		(end 113.284 -419.1)
		(width 0.381)
		(layer "F.Cu")
		(net "P3V3_AUX")
	)
	(segment
		(start 48.478694 -30.607508)
		(end 48.478694 -31.877508)
		(width 0.4064)
		(layer "F.Cu")
		(net "P3V3_AUX")
	)
	(segment
		(start 150.000208 -116.449094)
		(end 150.000208 -116.734844)
		(width 0.4064)
		(layer "F.Cu")
		(net "P3V3_AUX")
	)
	(segment
		(start 437.795924 -405.672544)
		(end 437.795924 -403.999192)
		(width 0.381)
		(layer "F.Cu")
		(net "P3V3_AUX")
	)
	(segment
		(start 161.097976 -129.695702)
		(end 160.40354 -129.695702)
		(width 0.381)
		(layer "F.Cu")
		(net "P3V3_AUX")
	)
	(segment
		(start 377.98629 -32.278828)
		(end 377.541536 -32.723582)
		(width 0.4572)
		(layer "F.Cu")
		(net "P3V3_AUX")
	)
	(segment
		(start 138.371834 -48.325024)
		(end 138.987784 -48.325024)
		(width 0.4572)
		(layer "F.Cu")
		(net "P3V3_AUX")
	)
	(segment
		(start 186.722004 -115.452906)
		(end 187.111894 -115.842796)
		(width 0.254)
		(layer "F.Cu")
		(net "P3V3_AUX")
	)
	(segment
		(start 131.094226 -33.023556)
		(end 131.094226 -31.475426)
		(width 0.1778)
		(layer "F.Cu")
		(net "P3V3_AUX")
	)
	(segment
		(start 126.404878 -49.153064)
		(end 125.788928 -49.153064)
		(width 0.4572)
		(layer "F.Cu")
		(net "P3V3_AUX")
	)
	(segment
		(start 364.302548 -14.050518)
		(end 364.302548 -13.434568)
		(width 0.4572)
		(layer "F.Cu")
		(net "P3V3_AUX")
	)
	(segment
		(start 365.907066 -422.523412)
		(end 365.907066 -421.945562)
		(width 0.381)
		(layer "F.Cu")
		(net "P3V3_AUX")
	)
	(segment
		(start 86.08695 -70.97395)
		(end 85.65896 -70.54596)
		(width 0.381)
		(layer "F.Cu")
		(net "P3V3_AUX")
	)
	(segment
		(start 67.81165 -36.294568)
		(end 67.81165 -35.588956)
		(width 0.4064)
		(layer "F.Cu")
		(net "P3V3_AUX")
	)
	(segment
		(start 390.28243 -78.439264)
		(end 390.891268 -78.439264)
		(width 0.4572)
		(layer "F.Cu")
		(net "P3V3_AUX")
	)
	(segment
		(start 97.652078 -404.326344)
		(end 97.457768 -404.132034)
		(width 0.3302)
		(layer "F.Cu")
		(net "P3V3_AUX")
	)
	(segment
		(start 254.192786 -123.10745)
		(end 253.583186 -123.10745)
		(width 0.381)
		(layer "F.Cu")
		(net "P3V3_AUX")
	)
	(segment
		(start 363.914436 -408.931364)
		(end 363.281976 -408.931364)
		(width 0.381)
		(layer "F.Cu")
		(net "P3V3_AUX")
	)
	(segment
		(start 305.98745 -439.877962)
		(end 306.232052 -440.122564)
		(width 0.381)
		(layer "F.Cu")
		(net "P3V3_AUX")
	)
	(segment
		(start 166.539418 -117.210332)
		(end 165.976046 -116.64696)
		(width 0.4572)
		(layer "F.Cu")
		(net "P3V3_AUX")
	)
	(segment
		(start 210.086956 -29.876242)
		(end 209.070956 -29.876242)
		(width 0.4064)
		(layer "F.Cu")
		(net "P3V3_AUX")
	)
	(segment
		(start 319.1764 -364.744)
		(end 319.1764 -364.363)
		(width 0.381)
		(layer "F.Cu")
		(net "P3V3_AUX")
	)
	(segment
		(start 184.322212 -115.452906)
		(end 183.932322 -115.842796)
		(width 0.254)
		(layer "F.Cu")
		(net "P3V3_AUX")
	)
	(segment
		(start 185.922158 -108.252768)
		(end 186.312048 -107.862878)
		(width 0.254)
		(layer "F.Cu")
		(net "P3V3_AUX")
	)
	(segment
		(start 146.776186 -55.313834)
		(end 147.407122 -55.313834)
		(width 0.4064)
		(layer "F.Cu")
		(net "P3V3_AUX")
	)
	(segment
		(start 209.922872 -37.331904)
		(end 209.922872 -36.172394)
		(width 0.2286)
		(layer "F.Cu")
		(net "P3V3_AUX")
	)
	(segment
		(start 157.595316 -56.331358)
		(end 157.595316 -55.696612)
		(width 0.4572)
		(layer "F.Cu")
		(net "P3V3_AUX")
	)
	(segment
		(start 165.11905 -107.315)
		(end 166.178992 -107.315)
		(width 0.381)
		(layer "F.Cu")
		(net "P3V3_AUX")
	)
	(segment
		(start 301.841408 -110.795308)
		(end 301.231808 -110.795308)
		(width 0.381)
		(layer "F.Cu")
		(net "P3V3_AUX")
	)
	(segment
		(start 207.15605 -100.055934)
		(end 207.515714 -100.415598)
		(width 0.381)
		(layer "F.Cu")
		(net "P3V3_AUX")
	)
	(segment
		(start 199.695562 -113.551716)
		(end 199.70369 -113.559844)
		(width 0.4064)
		(layer "F.Cu")
		(net "P3V3_AUX")
	)
	(segment
		(start 158.502858 -195.684648)
		(end 157.922722 -196.264784)
		(width 0.4572)
		(layer "F.Cu")
		(net "P3V3_AUX")
	)
	(segment
		(start 290.05022 -395.231366)
		(end 288.900362 -395.231366)
		(width 0.254)
		(layer "F.Cu")
		(net "P3V3_AUX")
	)
	(segment
		(start 307.404516 -433.542694)
		(end 306.77358 -433.542694)
		(width 0.381)
		(layer "F.Cu")
		(net "P3V3_AUX")
	)
	(segment
		(start 405.012398 -77.113384)
		(end 403.5552 -77.113384)
		(width 0.4064)
		(layer "F.Cu")
		(net "P3V3_AUX")
	)
	(segment
		(start 429.513492 -436.564786)
		(end 429.823372 -436.254906)
		(width 0.381)
		(layer "F.Cu")
		(net "P3V3_AUX")
	)
	(segment
		(start 161.999676 -435.742842)
		(end 161.999676 -436.47233)
		(width 0.381)
		(layer "F.Cu")
		(net "P3V3_AUX")
	)
	(segment
		(start 7.129272 -75.744578)
		(end 8.42772 -75.744578)
		(width 0.4064)
		(layer "F.Cu")
		(net "P3V3_AUX")
	)
	(segment
		(start 351.086166 -440.211972)
		(end 350.470216 -440.211972)
		(width 0.381)
		(layer "F.Cu")
		(net "P3V3_AUX")
	)
	(segment
		(start 169.17416 -170.342306)
		(end 169.17416 -172.22216)
		(width 0.4572)
		(layer "F.Cu")
		(net "P3V3_AUX")
	)
	(segment
		(start 338.31022 -16.38808)
		(end 338.31022 -17.00403)
		(width 0.4572)
		(layer "F.Cu")
		(net "P3V3_AUX")
	)
	(segment
		(start 9.34466 -71.860664)
		(end 8.707374 -71.860664)
		(width 0.4064)
		(layer "F.Cu")
		(net "P3V3_AUX")
	)
	(segment
		(start 75.64501 -148.051266)
		(end 75.64501 -147.417536)
		(width 0.381)
		(layer "F.Cu")
		(net "P3V3_AUX")
	)
	(segment
		(start 85.598 -72.39)
		(end 86.08695 -72.39)
		(width 0.381)
		(layer "F.Cu")
		(net "P3V3_AUX")
	)
	(segment
		(start 113.684304 -418.479478)
		(end 113.684304 -418.699696)
		(width 0.381)
		(layer "F.Cu")
		(net "P3V3_AUX")
	)
	(segment
		(start 118.999254 -424.688)
		(end 119.497602 -424.189652)
		(width 0.381)
		(layer "F.Cu")
		(net "P3V3_AUX")
	)
	(segment
		(start 276.46503 -114.70767)
		(end 276.33676 -114.83594)
		(width 0.381)
		(layer "F.Cu")
		(net "P3V3_AUX")
	)
	(segment
		(start 209.96021 -37.369242)
		(end 210.59521 -37.369242)
		(width 0.4572)
		(layer "F.Cu")
		(net "P3V3_AUX")
	)
	(segment
		(start 114.12982 -69.71792)
		(end 113.75136 -70.09638)
		(width 0.381)
		(layer "F.Cu")
		(net "P3V3_AUX")
	)
	(segment
		(start 82.706718 -19.542252)
		(end 82.071464 -19.542252)
		(width 0.4572)
		(layer "F.Cu")
		(net "P3V3_AUX")
	)
	(segment
		(start 172.140372 -417.551616)
		(end 171.553632 -417.551616)
		(width 0.381)
		(layer "F.Cu")
		(net "P3V3_AUX")
	)
	(segment
		(start 379.170438 -32.278828)
		(end 377.98629 -32.278828)
		(width 0.4572)
		(layer "F.Cu")
		(net "P3V3_AUX")
	)
	(segment
		(start 182.722012 -113.05286)
		(end 182.332122 -112.66297)
		(width 0.254)
		(layer "F.Cu")
		(net "P3V3_AUX")
	)
	(segment
		(start 207.589374 -127.898652)
		(end 209.739992 -127.898652)
		(width 0.381)
		(layer "F.Cu")
		(net "P3V3_AUX")
	)
	(segment
		(start 97.230438 -403.541992)
		(end 97.230438 -403.231604)
		(width 0.3302)
		(layer "F.Cu")
		(net "P3V3_AUX")
	)
	(segment
		(start 438.455308 -406.188672)
		(end 438.312052 -406.188672)
		(width 0.381)
		(layer "F.Cu")
		(net "P3V3_AUX")
	)
	(segment
		(start 163.02355 -436.153052)
		(end 163.02355 -436.555896)
		(width 0.381)
		(layer "F.Cu")
		(net "P3V3_AUX")
	)
	(segment
		(start 419.230302 -437.834786)
		(end 418.599366 -437.834786)
		(width 0.381)
		(layer "F.Cu")
		(net "P3V3_AUX")
	)
	(segment
		(start 20.955 -436.964074)
		(end 21.636228 -436.964074)
		(width 0.381)
		(layer "F.Cu")
		(net "P3V3_AUX")
	)
	(segment
		(start 38.697662 -418.239448)
		(end 38.697662 -418.849048)
		(width 0.381)
		(layer "F.Cu")
		(net "P3V3_AUX")
	)
	(segment
		(start 166.73195 -114.822732)
		(end 166.228014 -114.318796)
		(width 0.4572)
		(layer "F.Cu")
		(net "P3V3_AUX")
	)
	(segment
		(start 276.952202 -113.31067)
		(end 276.342602 -113.31067)
		(width 0.381)
		(layer "F.Cu")
		(net "P3V3_AUX")
	)
	(segment
		(start 304.762408 -116.891308)
		(end 303.724818 -116.891308)
		(width 0.381)
		(layer "F.Cu")
		(net "P3V3_AUX")
	)
	(segment
		(start 36.519612 -427.377098)
		(end 35.833812 -426.691298)
		(width 0.254)
		(layer "F.Cu")
		(net "P3V3_AUX")
	)
	(segment
		(start 38.78707 -171.140628)
		(end 38.78707 -169.793412)
		(width 0.3556)
		(layer "F.Cu")
		(net "P3V3_AUX")
	)
	(segment
		(start 329.993244 -41.16197)
		(end 329.992228 -41.160954)
		(width 0.3556)
		(layer "F.Cu")
		(net "P3V3_AUX")
	)
	(segment
		(start 376.630692 -427.3423)
		(end 376.630692 -428.239428)
		(width 0.254)
		(layer "F.Cu")
		(net "P3V3_AUX")
	)
	(segment
		(start 196.06895 -92.456)
		(end 195.326 -92.456)
		(width 0.381)
		(layer "F.Cu")
		(net "P3V3_AUX")
	)
	(segment
		(start 202.875896 -92.964)
		(end 204.089 -92.964)
		(width 0.381)
		(layer "F.Cu")
		(net "P3V3_AUX")
	)
	(segment
		(start 19.45005 -364.236)
		(end 19.45005 -365.435388)
		(width 0.381)
		(layer "F.Cu")
		(net "P3V3_AUX")
	)
	(segment
		(start 9.34466 -70.560692)
		(end 8.707374 -70.560692)
		(width 0.4064)
		(layer "F.Cu")
		(net "P3V3_AUX")
	)
	(segment
		(start 15.18412 -71.210678)
		(end 13.91412 -71.210678)
		(width 0.4064)
		(layer "F.Cu")
		(net "P3V3_AUX")
	)
	(segment
		(start 193.294 -57.10682)
		(end 192.437766 -57.963054)
		(width 0.381)
		(layer "F.Cu")
		(net "P3V3_AUX")
	)
	(segment
		(start 452.355966 -46.345602)
		(end 452.355966 -45.569632)
		(width 0.3048)
		(layer "F.Cu")
		(net "P3V3_AUX")
	)
	(segment
		(start 137.33653 -55.357014)
		(end 137.33653 -55.339996)
		(width 0.4572)
		(layer "F.Cu")
		(net "P3V3_AUX")
	)
	(segment
		(start 376.174 -427.2153)
		(end 376.503692 -427.2153)
		(width 0.254)
		(layer "F.Cu")
		(net "P3V3_AUX")
	)
	(segment
		(start 214.010748 -42.688256)
		(end 214.234522 -42.688256)
		(width 0.4572)
		(layer "F.Cu")
		(net "P3V3_AUX")
	)
	(segment
		(start 116.078 -418.35705)
		(end 116.078 -419.1)
		(width 0.381)
		(layer "F.Cu")
		(net "P3V3_AUX")
	)
	(segment
		(start 295.169844 -17.813274)
		(end 295.663874 -17.319244)
		(width 0.381)
		(layer "F.Cu")
		(net "P3V3_AUX")
	)
	(segment
		(start 114.790474 -61.202062)
		(end 116.36121 -61.202062)
		(width 0.4064)
		(layer "F.Cu")
		(net "P3V3_AUX")
	)
	(segment
		(start 124.195332 -15.26667)
		(end 124.929646 -15.26667)
		(width 0.4572)
		(layer "F.Cu")
		(net "P3V3_AUX")
	)
	(segment
		(start 406.875996 -136.231376)
		(end 407.667714 -136.231376)
		(width 0.4064)
		(layer "F.Cu")
		(net "P3V3_AUX")
	)
	(segment
		(start 181.6989 -164.761418)
		(end 181.568344 -164.891974)
		(width 0.4064)
		(layer "F.Cu")
		(net "P3V3_AUX")
	)
	(segment
		(start 96.928178 -403.959822)
		(end 96.928178 -403.844252)
		(width 0.3302)
		(layer "F.Cu")
		(net "P3V3_AUX")
	)
	(segment
		(start 142.14348 -122.13717)
		(end 141.828266 -122.452384)
		(width 0.381)
		(layer "F.Cu")
		(net "P3V3_AUX")
	)
	(segment
		(start 98.150172 -36.911788)
		(end 97.63125 -37.43071)
		(width 0.381)
		(layer "F.Cu")
		(net "P3V3_AUX")
	)
	(segment
		(start 297.886374 -113.751614)
		(end 298.495974 -113.751614)
		(width 0.381)
		(layer "F.Cu")
		(net "P3V3_AUX")
	)
	(segment
		(start 73.33361 -312.32475)
		(end 62.97295 -322.68541)
		(width 0.4572)
		(layer "F.Cu")
		(net "P3V3_AUX")
	)
	(segment
		(start 459.81112 -38.565836)
		(end 461.01127 -38.565836)
		(width 0.4572)
		(layer "F.Cu")
		(net "P3V3_AUX")
	)
	(segment
		(start 108.839 -415.81705)
		(end 108.839 -415.880042)
		(width 0.381)
		(layer "F.Cu")
		(net "P3V3_AUX")
	)
	(segment
		(start 12.13866 -396.06093)
		(end 12.384532 -396.06093)
		(width 0.381)
		(layer "F.Cu")
		(net "P3V3_AUX")
	)
	(segment
		(start 180.80863 -150.061168)
		(end 181.504082 -150.061168)
		(width 0.4064)
		(layer "F.Cu")
		(net "P3V3_AUX")
	)
	(segment
		(start 125.857 -41.8592)
		(end 125.240288 -42.475912)
		(width 0.381)
		(layer "F.Cu")
		(net "P3V3_AUX")
	)
	(segment
		(start 121.539 -440.309)
		(end 120.79605 -440.309)
		(width 0.381)
		(layer "F.Cu")
		(net "P3V3_AUX")
	)
	(segment
		(start 286.19323 -398.235932)
		(end 286.471106 -398.513808)
		(width 0.4318)
		(layer "F.Cu")
		(net "P3V3_AUX")
	)
	(segment
		(start 150.000208 -116.734844)
		(end 150.502366 -117.237002)
		(width 0.4064)
		(layer "F.Cu")
		(net "P3V3_AUX")
	)
	(segment
		(start 225.171762 -70.792848)
		(end 224.537016 -70.792848)
		(width 0.4572)
		(layer "F.Cu")
		(net "P3V3_AUX")
	)
	(segment
		(start 439.100214 -193.935096)
		(end 440.243214 -193.935096)
		(width 0.4572)
		(layer "F.Cu")
		(net "P3V3_AUX")
	)
	(segment
		(start 372.537228 -138.424158)
		(end 371.766338 -138.424158)
		(width 0.381)
		(layer "F.Cu")
		(net "P3V3_AUX")
	)
	(segment
		(start 37.853112 -369.312444)
		(end 37.67836 -369.487196)
		(width 0.381)
		(layer "F.Cu")
		(net "P3V3_AUX")
	)
	(segment
		(start 318.300608 -22.17928)
		(end 318.300608 -21.56333)
		(width 0.4572)
		(layer "F.Cu")
		(net "P3V3_AUX")
	)
	(segment
		(start 161.268156 -36.302188)
		(end 161.30524 -36.339272)
		(width 0.4572)
		(layer "F.Cu")
		(net "P3V3_AUX")
	)
	(segment
		(start 96.689418 -38.815772)
		(end 97.57537 -38.815772)
		(width 0.381)
		(layer "F.Cu")
		(net "P3V3_AUX")
	)
	(segment
		(start 98.380296 -426.22978)
		(end 98.380296 -426.84573)
		(width 0.381)
		(layer "F.Cu")
		(net "P3V3_AUX")
	)
	(segment
		(start 98.36785 -426.217334)
		(end 98.380296 -426.22978)
		(width 0.4064)
		(layer "F.Cu")
		(net "P3V3_AUX")
	)
	(segment
		(start 188.322204 -116.252752)
		(end 188.712094 -116.642642)
		(width 0.254)
		(layer "F.Cu")
		(net "P3V3_AUX")
	)
	(segment
		(start 25.05583 -435.925214)
		(end 25.613868 -436.483252)
		(width 0.381)
		(layer "F.Cu")
		(net "P3V3_AUX")
	)
	(segment
		(start 149.990048 -27.506168)
		(end 150.21179 -27.72791)
		(width 0.4572)
		(layer "F.Cu")
		(net "P3V3_AUX")
	)
	(segment
		(start 123.078748 -72.429116)
		(end 122.891042 -72.616822)
		(width 0.381)
		(layer "F.Cu")
		(net "P3V3_AUX")
	)
	(segment
		(start 69.596 -52.578)
		(end 69.469 -52.705)
		(width 0.381)
		(layer "F.Cu")
		(net "P3V3_AUX")
	)
	(segment
		(start 218.799664 -102.2223)
		(end 217.66403 -102.2223)
		(width 0.381)
		(layer "F.Cu")
		(net "P3V3_AUX")
	)
	(segment
		(start 166.71671 -116.274088)
		(end 166.712392 -116.26977)
		(width 0.4572)
		(layer "F.Cu")
		(net "P3V3_AUX")
	)
	(segment
		(start 97.457768 -404.132034)
		(end 97.10039 -404.132034)
		(width 0.3302)
		(layer "F.Cu")
		(net "P3V3_AUX")
	)
	(segment
		(start 41.33596 -436.499)
		(end 42.52595 -436.499)
		(width 0.381)
		(layer "F.Cu")
		(net "P3V3_AUX")
	)
	(segment
		(start 449.01993 -94.602808)
		(end 449.65112 -94.602808)
		(width 0.381)
		(layer "F.Cu")
		(net "P3V3_AUX")
	)
	(segment
		(start 282.575 -423.81805)
		(end 282.575 -424.461178)
		(width 0.381)
		(layer "F.Cu")
		(net "P3V3_AUX")
	)
	(segment
		(start 86.868 -71.26605)
		(end 87.384636 -71.782686)
		(width 0.381)
		(layer "F.Cu")
		(net "P3V3_AUX")
	)
	(segment
		(start 156.96819 -103.465884)
		(end 156.84119 -103.338884)
		(width 0.4064)
		(layer "F.Cu")
		(net "P3V3_AUX")
	)
	(segment
		(start 182.722012 -114.652806)
		(end 182.332122 -114.262916)
		(width 0.254)
		(layer "F.Cu")
		(net "P3V3_AUX")
	)
	(segment
		(start 181.922166 -116.252752)
		(end 181.532276 -116.642642)
		(width 0.254)
		(layer "F.Cu")
		(net "P3V3_AUX")
	)
	(segment
		(start 171.553632 -417.551616)
		(end 171.426632 -417.678616)
		(width 0.381)
		(layer "F.Cu")
		(net "P3V3_AUX")
	)
	(segment
		(start 209.070956 -29.266896)
		(end 209.07121 -29.266642)
		(width 0.4064)
		(layer "F.Cu")
		(net "P3V3_AUX")
	)
	(segment
		(start 75.305412 -37.897562)
		(end 75.305412 -38.532562)
		(width 0.381)
		(layer "F.Cu")
		(net "P3V3_AUX")
	)
	(segment
		(start 375.526554 -426.567854)
		(end 376.174 -427.2153)
		(width 0.254)
		(layer "F.Cu")
		(net "P3V3_AUX")
	)
	(segment
		(start 38.78707 -169.793412)
		(end 38.816788 -169.763694)
		(width 0.3556)
		(layer "F.Cu")
		(net "P3V3_AUX")
	)
	(segment
		(start 463.771996 -108.567728)
		(end 463.771996 -107.936792)
		(width 0.381)
		(layer "F.Cu")
		(net "P3V3_AUX")
	)
	(segment
		(start 97.63125 -37.43071)
		(end 97.196402 -37.865558)
		(width 0.381)
		(layer "F.Cu")
		(net "P3V3_AUX")
	)
	(segment
		(start 10.7061 -394.62837)
		(end 12.13866 -396.06093)
		(width 0.381)
		(layer "F.Cu")
		(net "P3V3_AUX")
	)
	(segment
		(start 193.089022 -25.565862)
		(end 192.454276 -25.565862)
		(width 0.4572)
		(layer "F.Cu")
		(net "P3V3_AUX")
	)
	(segment
		(start 167.99052 -123.46813)
		(end 168.44772 -123.01093)
		(width 0.4572)
		(layer "F.Cu")
		(net "P3V3_AUX")
	)
	(segment
		(start 99.35591 -79.05496)
		(end 97.110042 -79.05496)
		(width 0.381)
		(layer "F.Cu")
		(net "P3V3_AUX")
	)
	(segment
		(start 273.908266 -353.896422)
		(end 272.194274 -353.896422)
		(width 0.508)
		(layer "F.Cu")
		(net "P3V3_AUX")
	)
	(segment
		(start 182.722012 -115.452906)
		(end 182.332122 -115.842796)
		(width 0.254)
		(layer "F.Cu")
		(net "P3V3_AUX")
	)
	(segment
		(start 463.58937 -38.565836)
		(end 464.20532 -38.565836)
		(width 0.4572)
		(layer "F.Cu")
		(net "P3V3_AUX")
	)
	(segment
		(start 15.067788 -92.287598)
		(end 15.067788 -91.618308)
		(width 0.381)
		(layer "F.Cu")
		(net "P3V3_AUX")
	)
	(segment
		(start 47.18304 -433.617878)
		(end 46.737778 -433.172616)
		(width 0.381)
		(layer "F.Cu")
		(net "P3V3_AUX")
	)
	(segment
		(start 65.022476 -54.62143)
		(end 65.287906 -54.356)
		(width 0.381)
		(layer "F.Cu")
		(net "P3V3_AUX")
	)
	(segment
		(start 205.662276 -125.817376)
		(end 206.530956 -125.817376)
		(width 0.4572)
		(layer "F.Cu")
		(net "P3V3_AUX")
	)
	(segment
		(start 319.905888 -22.971506)
		(end 319.905888 -23.587456)
		(width 0.4572)
		(layer "F.Cu")
		(net "P3V3_AUX")
	)
	(segment
		(start 274.619466 -119.91467)
		(end 274.465796 -119.761)
		(width 0.381)
		(layer "F.Cu")
		(net "P3V3_AUX")
	)
	(segment
		(start 125.240288 -42.475912)
		(end 125.240288 -42.57675)
		(width 0.381)
		(layer "F.Cu")
		(net "P3V3_AUX")
	)
	(segment
		(start 75.268074 -38.5699)
		(end 75.305412 -38.532562)
		(width 0.2286)
		(layer "F.Cu")
		(net "P3V3_AUX")
	)
	(segment
		(start 56.146954 -38.904418)
		(end 55.573676 -38.904418)
		(width 0.381)
		(layer "F.Cu")
		(net "P3V3_AUX")
	)
	(segment
		(start 191.522096 -114.652806)
		(end 191.911986 -114.262916)
		(width 0.254)
		(layer "F.Cu")
		(net "P3V3_AUX")
	)
	(segment
		(start 138.827002 -59.83224)
		(end 139.184634 -59.474608)
		(width 0.4572)
		(layer "F.Cu")
		(net "P3V3_AUX")
	)
	(segment
		(start 439.28792 -94.827598)
		(end 438.74055 -94.827598)
		(width 0.254)
		(layer "F.Cu")
		(net "P3V3_AUX")
	)
	(segment
		(start 20.880832 -410.564584)
		(end 20.880832 -409.421584)
		(width 0.381)
		(layer "F.Cu")
		(net "P3V3_AUX")
	)
	(segment
		(start 295.663874 -17.319244)
		(end 297.015408 -17.319244)
		(width 0.381)
		(layer "F.Cu")
		(net "P3V3_AUX")
	)
	(segment
		(start 146.474688 -56.57596)
		(end 146.474688 -55.615332)
		(width 0.1778)
		(layer "F.Cu")
		(net "P3V3_AUX")
	)
	(segment
		(start 44.340018 -193.93535)
		(end 45.483018 -193.93535)
		(width 0.4572)
		(layer "F.Cu")
		(net "P3V3_AUX")
	)
	(segment
		(start 320.553588 -115.428268)
		(end 320.571368 -115.410488)
		(width 0.381)
		(layer "F.Cu")
		(net "P3V3_AUX")
	)
	(segment
		(start 274.57527 -362.066332)
		(end 274.57527 -354.563426)
		(width 0.508)
		(layer "F.Cu")
		(net "P3V3_AUX")
	)
	(segment
		(start 165.08349 -79.06512)
		(end 163.111434 -79.06512)
		(width 0.4572)
		(layer "F.Cu")
		(net "P3V3_AUX")
	)
	(segment
		(start 143.88084 -40.003476)
		(end 143.243554 -40.003476)
		(width 0.508)
		(layer "F.Cu")
		(net "P3V3_AUX")
	)
	(segment
		(start 343.458546 -24.28875)
		(end 343.458546 -24.9047)
		(width 0.4064)
		(layer "F.Cu")
		(net "P3V3_AUX")
	)
	(segment
		(start 209.070956 -29.876242)
		(end 209.070956 -29.266896)
		(width 0.4064)
		(layer "F.Cu")
		(net "P3V3_AUX")
	)
	(segment
		(start 397.876268 -75.518264)
		(end 397.83893 -75.555602)
		(width 0.2286)
		(layer "F.Cu")
		(net "P3V3_AUX")
	)
	(segment
		(start 192.437766 -60.78093)
		(end 192.437766 -57.963054)
		(width 0.381)
		(layer "F.Cu")
		(net "P3V3_AUX")
	)
	(segment
		(start 357.60406 -418.329618)
		(end 358.22001 -418.329618)
		(width 0.381)
		(layer "F.Cu")
		(net "P3V3_AUX")
	)
	(segment
		(start 48.478694 -31.877508)
		(end 46.97222 -31.877508)
		(width 0.4064)
		(layer "F.Cu")
		(net "P3V3_AUX")
	)
	(segment
		(start 168.44772 -123.01093)
		(end 168.496996 -123.01093)
		(width 0.4572)
		(layer "F.Cu")
		(net "P3V3_AUX")
	)
	(segment
		(start 210.464654 -15.685008)
		(end 210.464654 -15.425674)
		(width 0.381)
		(layer "F.Cu")
		(net "P3V3_AUX")
	)
	(segment
		(start 276.952202 -116.10467)
		(end 276.342602 -116.10467)
		(width 0.381)
		(layer "F.Cu")
		(net "P3V3_AUX")
	)
	(segment
		(start 124.235972 -13.99413)
		(end 124.929646 -13.99413)
		(width 0.4572)
		(layer "F.Cu")
		(net "P3V3_AUX")
	)
	(segment
		(start 252.62205 -39.262558)
		(end 252.541278 -39.34333)
		(width 0.4572)
		(layer "F.Cu")
		(net "P3V3_AUX")
	)
	(segment
		(start 204.592936 -98.244914)
		(end 204.347826 -98.490024)
		(width 0.381)
		(layer "F.Cu")
		(net "P3V3_AUX")
	)
	(segment
		(start 36.18611 -422.418002)
		(end 35.862514 -422.741598)
		(width 0.254)
		(layer "F.Cu")
		(net "P3V3_AUX")
	)
	(segment
		(start 214.339424 -22.278594)
		(end 214.339424 -22.630384)
		(width 0.381)
		(layer "F.Cu")
		(net "P3V3_AUX")
	)
	(segment
		(start 257.15214 -73.973944)
		(end 257.894836 -73.973944)
		(width 0.381)
		(layer "F.Cu")
		(net "P3V3_AUX")
	)
	(segment
		(start 278.242776 -121.77522)
		(end 278.243792 -121.774204)
		(width 0.381)
		(layer "F.Cu")
		(net "P3V3_AUX")
	)
	(segment
		(start 367.050066 -428.416212)
		(end 368.052604 -428.416212)
		(width 0.381)
		(layer "F.Cu")
		(net "P3V3_AUX")
	)
	(segment
		(start 188.322204 -113.05286)
		(end 188.712094 -112.66297)
		(width 0.254)
		(layer "F.Cu")
		(net "P3V3_AUX")
	)
	(segment
		(start 274.57527 -354.563426)
		(end 273.908266 -353.896422)
		(width 0.508)
		(layer "F.Cu")
		(net "P3V3_AUX")
	)
	(segment
		(start 24.216868 -435.925214)
		(end 25.05583 -435.925214)
		(width 0.381)
		(layer "F.Cu")
		(net "P3V3_AUX")
	)
	(segment
		(start 184.322212 -113.85296)
		(end 183.932322 -113.46307)
		(width 0.254)
		(layer "F.Cu")
		(net "P3V3_AUX")
	)
	(segment
		(start 254.540004 -108.804964)
		(end 255.152144 -108.804964)
		(width 0.4064)
		(layer "F.Cu")
		(net "P3V3_AUX")
	)
	(segment
		(start 261.868666 -75.770994)
		(end 262.53186 -75.770994)
		(width 0.4064)
		(layer "F.Cu")
		(net "P3V3_AUX")
	)
	(segment
		(start 163.02355 -438.912)
		(end 163.02355 -439.551064)
		(width 0.381)
		(layer "F.Cu")
		(net "P3V3_AUX")
	)
	(segment
		(start 453.319896 -104.249728)
		(end 452.710296 -104.249728)
		(width 0.381)
		(layer "F.Cu")
		(net "P3V3_AUX")
	)
	(segment
		(start 21.776944 -353.245166)
		(end 21.776944 -353.465638)
		(width 0.381)
		(layer "F.Cu")
		(net "P3V3_AUX")
	)
	(segment
		(start 136.961118 -62.29858)
		(end 136.544558 -61.88202)
		(width 0.4572)
		(layer "F.Cu")
		(net "P3V3_AUX")
	)
	(segment
		(start 320.553588 -116.632228)
		(end 320.553588 -126.410466)
		(width 0.381)
		(layer "F.Cu")
		(net "P3V3_AUX")
	)
	(segment
		(start 87.157814 -57.16778)
		(end 87.157814 -56.800496)
		(width 0.254)
		(layer "F.Cu")
		(net "P3V3_AUX")
	)
	(segment
		(start 152.991312 -27.08783)
		(end 152.991312 -27.701748)
		(width 0.4572)
		(layer "F.Cu")
		(net "P3V3_AUX")
	)
	(segment
		(start 96.28378 -37.865558)
		(end 96.28886 -37.870638)
		(width 0.381)
		(layer "F.Cu")
		(net "P3V3_AUX")
	)
	(segment
		(start 283.216858 -405.466804)
		(end 283.216858 -406.092152)
		(width 0.381)
		(layer "F.Cu")
		(net "P3V3_AUX")
	)
	(segment
		(start 327.65492 -102.558088)
		(end 326.495156 -102.558088)
		(width 0.2286)
		(layer "F.Cu")
		(net "P3V3_AUX")
	)
	(segment
		(start 438.629552 -421.37711)
		(end 438.629552 -422.52011)
		(width 0.381)
		(layer "F.Cu")
		(net "P3V3_AUX")
	)
	(segment
		(start 54.737254 -39.751)
		(end 54.671214 -39.68496)
		(width 0.381)
		(layer "F.Cu")
		(net "P3V3_AUX")
	)
	(segment
		(start 145.823178 -74.715116)
		(end 145.176748 -74.715116)
		(width 0.381)
		(layer "F.Cu")
		(net "P3V3_AUX")
	)
	(segment
		(start 118.89105 -424.688)
		(end 118.999254 -424.688)
		(width 0.381)
		(layer "F.Cu")
		(net "P3V3_AUX")
	)
	(segment
		(start 179.23764 -149.589236)
		(end 179.23764 -149.735794)
		(width 0.4064)
		(layer "F.Cu")
		(net "P3V3_AUX")
	)
	(segment
		(start 120.79605 -434.467)
		(end 121.539 -434.467)
		(width 0.381)
		(layer "F.Cu")
		(net "P3V3_AUX")
	)
	(segment
		(start 188.849 -95.703898)
		(end 188.849 -95.087948)
		(width 0.4572)
		(layer "F.Cu")
		(net "P3V3_AUX")
	)
	(segment
		(start 32.347662 -430.799748)
		(end 32.347662 -430.190148)
		(width 0.381)
		(layer "F.Cu")
		(net "P3V3_AUX")
	)
	(segment
		(start 438.74055 -94.827598)
		(end 438.277 -95.291148)
		(width 0.381)
		(layer "F.Cu")
		(net "P3V3_AUX")
	)
	(segment
		(start 438.488836 -167.876474)
		(end 438.488836 -166.703502)
		(width 0.3048)
		(layer "F.Cu")
		(net "P3V3_AUX")
	)
	(segment
		(start 104.86644 -56.67756)
		(end 104.54894 -56.67756)
		(width 0.381)
		(layer "F.Cu")
		(net "P3V3_AUX")
	)
	(segment
		(start 397.83893 -75.555602)
		(end 396.679166 -75.555602)
		(width 0.2286)
		(layer "F.Cu")
		(net "P3V3_AUX")
	)
	(segment
		(start 85.344 -72.136)
		(end 85.598 -72.39)
		(width 0.381)
		(layer "F.Cu")
		(net "P3V3_AUX")
	)
	(segment
		(start 320.09842 -105.44175)
		(end 320.707258 -105.44175)
		(width 0.4572)
		(layer "F.Cu")
		(net "P3V3_AUX")
	)
	(segment
		(start 210.208622 -126.469648)
		(end 210.208622 -125.234446)
		(width 0.4064)
		(layer "F.Cu")
		(net "P3V3_AUX")
	)
	(segment
		(start 366.534446 -27.906472)
		(end 366.534446 -27.290522)
		(width 0.4572)
		(layer "F.Cu")
		(net "P3V3_AUX")
	)
	(segment
		(start 196.431408 -105.497376)
		(end 197.123558 -105.497376)
		(width 0.381)
		(layer "F.Cu")
		(net "P3V3_AUX")
	)
	(segment
		(start 31.447994 -133.188964)
		(end 30.075378 -133.188964)
		(width 0.381)
		(layer "F.Cu")
		(net "P3V3_AUX")
	)
	(segment
		(start 103.911146 -56.67756)
		(end 104.54894 -56.67756)
		(width 0.381)
		(layer "F.Cu")
		(net "P3V3_AUX")
	)
	(segment
		(start 461.557878 -94.317566)
		(end 461.557878 -94.952566)
		(width 0.381)
		(layer "F.Cu")
		(net "P3V3_AUX")
	)
	(segment
		(start 360.583988 -409.788868)
		(end 360.583988 -410.464)
		(width 0.381)
		(layer "F.Cu")
		(net "P3V3_AUX")
	)
	(segment
		(start 131.094226 -31.475426)
		(end 130.498088 -30.879288)
		(width 0.1778)
		(layer "F.Cu")
		(net "P3V3_AUX")
	)
	(segment
		(start 352.45548 -434.857652)
		(end 352.45548 -435.975252)
		(width 0.4318)
		(layer "F.Cu")
		(net "P3V3_AUX")
	)
	(segment
		(start 165.71595 -99.06)
		(end 165.71595 -98.024696)
		(width 0.381)
		(layer "F.Cu")
		(net "P3V3_AUX")
	)
	(segment
		(start 163.144454 -39.90594)
		(end 162.842194 -40.2082)
		(width 0.4572)
		(layer "F.Cu")
		(net "P3V3_AUX")
	)
	(segment
		(start 139.845542 -105.225596)
		(end 140.486892 -105.225596)
		(width 0.4064)
		(layer "F.Cu")
		(net "P3V3_AUX")
	)
	(segment
		(start 124.860812 -60.482226)
		(end 124.860558 -60.48248)
		(width 0.4572)
		(layer "F.Cu")
		(net "P3V3_AUX")
	)
	(segment
		(start 183.414416 -413.941006)
		(end 183.414416 -413.068262)
		(width 0.381)
		(layer "F.Cu")
		(net "P3V3_AUX")
	)
	(segment
		(start 329.2348 -16.379444)
		(end 329.2348 -16.995394)
		(width 0.4572)
		(layer "F.Cu")
		(net "P3V3_AUX")
	)
	(segment
		(start 89.809828 -144.88541)
		(end 89.193878 -144.88541)
		(width 0.381)
		(layer "F.Cu")
		(net "P3V3_AUX")
	)
	(segment
		(start 48.06696 -436.372)
		(end 49.25695 -436.372)
		(width 0.381)
		(layer "F.Cu")
		(net "P3V3_AUX")
	)
	(segment
		(start 23.012654 -352.009456)
		(end 21.776944 -353.245166)
		(width 0.381)
		(layer "F.Cu")
		(net "P3V3_AUX")
	)
	(segment
		(start 461.320896 -103.614728)
		(end 461.320896 -104.249728)
		(width 0.381)
		(layer "F.Cu")
		(net "P3V3_AUX")
	)
	(segment
		(start 35.532822 -433.112164)
		(end 36.142422 -433.112164)
		(width 0.381)
		(layer "F.Cu")
		(net "P3V3_AUX")
	)
	(segment
		(start 372.537228 -142.488158)
		(end 371.921278 -142.488158)
		(width 0.381)
		(layer "F.Cu")
		(net "P3V3_AUX")
	)
	(segment
		(start 108.533946 -55.282084)
		(end 107.90301 -55.282084)
		(width 0.4572)
		(layer "F.Cu")
		(net "P3V3_AUX")
	)
	(segment
		(start 182.722012 -117.052852)
		(end 182.332122 -117.442742)
		(width 0.254)
		(layer "F.Cu")
		(net "P3V3_AUX")
	)
	(segment
		(start 290.469828 -122.782076)
		(end 290.744402 -123.05665)
		(width 0.381)
		(layer "F.Cu")
		(net "P3V3_AUX")
	)
	(segment
		(start 205.63205 -129.032)
		(end 206.456026 -129.032)
		(width 0.381)
		(layer "F.Cu")
		(net "P3V3_AUX")
	)
	(segment
		(start 301.800768 -145.896838)
		(end 301.819818 -145.877788)
		(width 0.254)
		(layer "F.Cu")
		(net "P3V3_AUX")
	)
	(segment
		(start 197.934834 -124.937012)
		(end 199.61733 -124.937012)
		(width 0.4064)
		(layer "F.Cu")
		(net "P3V3_AUX")
	)
	(segment
		(start 149.535642 -105.624884)
		(end 148.894292 -105.624884)
		(width 0.4064)
		(layer "F.Cu")
		(net "P3V3_AUX")
	)
	(segment
		(start 304.796952 -119.475504)
		(end 303.728882 -119.475504)
		(width 0.254)
		(layer "F.Cu")
		(net "P3V3_AUX")
	)
	(segment
		(start 29.214064 -80.824324)
		(end 29.214064 -81.46161)
		(width 0.4064)
		(layer "F.Cu")
		(net "P3V3_AUX")
	)
	(segment
		(start 394.297408 -322.627752)
		(end 394.424408 -322.500752)
		(width 0.3556)
		(layer "F.Cu")
		(net "P3V3_AUX")
	)
	(segment
		(start 284.736032 -193.935096)
		(end 285.879032 -193.935096)
		(width 0.4572)
		(layer "F.Cu")
		(net "P3V3_AUX")
	)
	(segment
		(start 185.801 -99.894898)
		(end 184.785 -99.894898)
		(width 0.381)
		(layer "F.Cu")
		(net "P3V3_AUX")
	)
	(segment
		(start 191.52362 -420.626032)
		(end 190.886334 -420.626032)
		(width 0.381)
		(layer "F.Cu")
		(net "P3V3_AUX")
	)
	(segment
		(start 114.551968 -66.997072)
		(end 114.12982 -67.41922)
		(width 0.381)
		(layer "F.Cu")
		(net "P3V3_AUX")
	)
	(segment
		(start 169.480992 -434.869336)
		(end 169.686732 -435.075076)
		(width 0.381)
		(layer "F.Cu")
		(net "P3V3_AUX")
	)
	(segment
		(start 119.99595 -424.688)
		(end 119.497602 -424.189652)
		(width 0.381)
		(layer "F.Cu")
		(net "P3V3_AUX")
	)
	(segment
		(start 445.557148 -93.484192)
		(end 446.2272 -93.484192)
		(width 0.381)
		(layer "F.Cu")
		(net "P3V3_AUX")
	)
	(segment
		(start 119.017796 -52.48148)
		(end 119.017796 -53.49748)
		(width 0.4572)
		(layer "F.Cu")
		(net "P3V3_AUX")
	)
	(segment
		(start 164.144706 -42.177462)
		(end 163.5252 -42.177462)
		(width 0.254)
		(layer "F.Cu")
		(net "P3V3_AUX")
	)
	(segment
		(start 431.751486 -101.97719)
		(end 431.751486 -102.61219)
		(width 0.4572)
		(layer "F.Cu")
		(net "P3V3_AUX")
	)
	(segment
		(start 439.072782 -435.67731)
		(end 439.703718 -435.67731)
		(width 0.381)
		(layer "F.Cu")
		(net "P3V3_AUX")
	)
	(segment
		(start 318.90335 -365.01705)
		(end 319.1764 -364.744)
		(width 0.381)
		(layer "F.Cu")
		(net "P3V3_AUX")
	)
	(segment
		(start 15.18412 -69.178678)
		(end 14.546834 -69.178678)
		(width 0.4064)
		(layer "F.Cu")
		(net "P3V3_AUX")
	)
	(segment
		(start 184.785 -99.894898)
		(end 184.785 -99.278948)
		(width 0.381)
		(layer "F.Cu")
		(net "P3V3_AUX")
	)
	(segment
		(start 43.66895 -435.61)
		(end 43.66895 -436.367936)
		(width 0.381)
		(layer "F.Cu")
		(net "P3V3_AUX")
	)
	(segment
		(start 182.320692 -408.26309)
		(end 182.320692 -408.114754)
		(width 0.4572)
		(layer "F.Cu")
		(net "P3V3_AUX")
	)
	(segment
		(start 112.672876 -418.490908)
		(end 113.284 -419.1)
		(width 0.381)
		(layer "F.Cu")
		(net "P3V3_AUX")
	)
	(segment
		(start 166.624 -132.35305)
		(end 167.49395 -132.35305)
		(width 0.381)
		(layer "F.Cu")
		(net "P3V3_AUX")
	)
	(segment
		(start 118.51005 -419.24605)
		(end 118.745 -419.481)
		(width 0.381)
		(layer "F.Cu")
		(net "P3V3_AUX")
	)
	(segment
		(start 147.42668 -57.676034)
		(end 147.83943 -58.088784)
		(width 0.254)
		(layer "F.Cu")
		(net "P3V3_AUX")
	)
	(segment
		(start 49.38395 -39.310564)
		(end 49.17694 -39.103554)
		(width 0.381)
		(layer "F.Cu")
		(net "P3V3_AUX")
	)
	(segment
		(start 413.880808 -365.728504)
		(end 413.044132 -365.381794)
		(width 0.3556)
		(layer "F.Cu")
		(net "P3V3_AUX")
	)
	(segment
		(start 114.490246 -399.593816)
		(end 114.719354 -399.593816)
		(width 0.3048)
		(layer "F.Cu")
		(net "P3V3_AUX")
	)
	(segment
		(start 181.568344 -164.891974)
		(end 180.772308 -164.891974)
		(width 0.4064)
		(layer "F.Cu")
		(net "P3V3_AUX")
	)
	(segment
		(start 160.29305 -108.458)
		(end 160.29305 -109.191552)
		(width 0.381)
		(layer "F.Cu")
		(net "P3V3_AUX")
	)
	(segment
		(start 213.445598 -27.268424)
		(end 211.992464 -27.268424)
		(width 0.381)
		(layer "F.Cu")
		(net "P3V3_AUX")
	)
	(segment
		(start 214.019384 -14.845792)
		(end 214.019638 -14.845792)
		(width 0.381)
		(layer "F.Cu")
		(net "P3V3_AUX")
	)
	(segment
		(start 167.256714 -429.141636)
		(end 167.256714 -428.99711)
		(width 0.381)
		(layer "F.Cu")
		(net "P3V3_AUX")
	)
	(segment
		(start 147.82419 -95.612458)
		(end 147.16379 -95.612458)
		(width 0.4064)
		(layer "F.Cu")
		(net "P3V3_AUX")
	)
	(segment
		(start 429.87341 -423.20591)
		(end 429.87341 -422.58996)
		(width 0.381)
		(layer "F.Cu")
		(net "P3V3_AUX")
	)
	(segment
		(start 320.553588 -126.410466)
		(end 330.617068 -136.473946)
		(width 0.381)
		(layer "F.Cu")
		(net "P3V3_AUX")
	)
	(segment
		(start 59.428126 -193.93535)
		(end 60.571126 -193.93535)
		(width 0.4572)
		(layer "F.Cu")
		(net "P3V3_AUX")
	)
	(segment
		(start 98.150172 -36.305998)
		(end 98.073972 -36.229798)
		(width 0.381)
		(layer "F.Cu")
		(net "P3V3_AUX")
	)
	(segment
		(start 109.474 -416.515042)
		(end 109.474 -416.687)
		(width 0.381)
		(layer "F.Cu")
		(net "P3V3_AUX")
	)
	(segment
		(start 212.99805 -120.65)
		(end 212.99805 -121.298716)
		(width 0.381)
		(layer "F.Cu")
		(net "P3V3_AUX")
	)
	(segment
		(start 118.318534 -62.932056)
		(end 118.12016 -62.932056)
		(width 0.4572)
		(layer "F.Cu")
		(net "P3V3_AUX")
	)
	(segment
		(start 276.952202 -114.70767)
		(end 276.46503 -114.70767)
		(width 0.381)
		(layer "F.Cu")
		(net "P3V3_AUX")
	)
	(segment
		(start 99.751134 -35.30092)
		(end 98.1329 -35.30092)
		(width 0.381)
		(layer "F.Cu")
		(net "P3V3_AUX")
	)
	(segment
		(start 16.368268 -128.91516)
		(end 16.368268 -129.709418)
		(width 0.4572)
		(layer "F.Cu")
		(net "P3V3_AUX")
	)
	(segment
		(start 209.959956 -37.369242)
		(end 209.96021 -37.369242)
		(width 0.4572)
		(layer "F.Cu")
		(net "P3V3_AUX")
	)
	(segment
		(start 157.298136 -347.260164)
		(end 156.473398 -347.260164)
		(width 0.4572)
		(layer "F.Cu")
		(net "P3V3_AUX")
	)
	(segment
		(start 163.144454 -38.894004)
		(end 163.144454 -39.90594)
		(width 0.4572)
		(layer "F.Cu")
		(net "P3V3_AUX")
	)
	(segment
		(start 19.45005 -365.435388)
		(end 19.663664 -365.649002)
		(width 0.381)
		(layer "F.Cu")
		(net "P3V3_AUX")
	)
	(segment
		(start 216.30005 -96.774)
		(end 217.056208 -96.774)
		(width 0.381)
		(layer "F.Cu")
		(net "P3V3_AUX")
	)
	(segment
		(start 394.424408 -322.500752)
		(end 394.891768 -322.500752)
		(width 0.3556)
		(layer "F.Cu")
		(net "P3V3_AUX")
	)
	(segment
		(start 287.339024 -398.513808)
		(end 287.97631 -398.513808)
		(width 0.4572)
		(layer "F.Cu")
		(net "P3V3_AUX")
	)
	(segment
		(start 103.886 -426.86605)
		(end 103.886 -427.609)
		(width 0.381)
		(layer "F.Cu")
		(net "P3V3_AUX")
	)
	(segment
		(start 352.45548 -434.857652)
		(end 353.07143 -434.857652)
		(width 0.381)
		(layer "F.Cu")
		(net "P3V3_AUX")
	)
	(segment
		(start 284.773878 -13.373354)
		(end 284.397704 -13.749528)
		(width 0.4572)
		(layer "F.Cu")
		(net "P3V3_AUX")
	)
	(segment
		(start 306.100988 -424.956986)
		(end 305.485038 -424.956986)
		(width 0.381)
		(layer "F.Cu")
		(net "P3V3_AUX")
	)
	(segment
		(start 100.343462 -80.80375)
		(end 99.42195 -79.882238)
		(width 0.381)
		(layer "F.Cu")
		(net "P3V3_AUX")
	)
	(segment
		(start 212.32495 -99.822)
		(end 211.606638 -99.822)
		(width 0.381)
		(layer "F.Cu")
		(net "P3V3_AUX")
	)
	(segment
		(start 157.353 -111.48695)
		(end 158.032196 -111.48695)
		(width 0.381)
		(layer "F.Cu")
		(net "P3V3_AUX")
	)
	(segment
		(start 159.390334 -192.760092)
		(end 158.502858 -194.902836)
		(width 0.4572)
		(layer "F.Cu")
		(net "P3V3_AUX")
	)
	(segment
		(start 25.826466 -39.037514)
		(end 25.789128 -39.074852)
		(width 0.2286)
		(layer "F.Cu")
		(net "P3V3_AUX")
	)
	(segment
		(start 130.498088 -30.879288)
		(end 130.498088 -30.78988)
		(width 0.1778)
		(layer "F.Cu")
		(net "P3V3_AUX")
	)
	(segment
		(start 179.606448 -150.104602)
		(end 180.765196 -150.104602)
		(width 0.4064)
		(layer "F.Cu")
		(net "P3V3_AUX")
	)
	(segment
		(start 288.87928 -395.252448)
		(end 288.298382 -395.252448)
		(width 0.254)
		(layer "F.Cu")
		(net "P3V3_AUX")
	)
	(segment
		(start 105.44556 -67.60591)
		(end 104.82961 -67.60591)
		(width 0.381)
		(layer "F.Cu")
		(net "P3V3_AUX")
	)
	(segment
		(start 165.54069 -78.60792)
		(end 165.08349 -79.06512)
		(width 0.4572)
		(layer "F.Cu")
		(net "P3V3_AUX")
	)
	(segment
		(start 181.42585 -42.12209)
		(end 180.412136 -43.135804)
		(width 0.4572)
		(layer "F.Cu")
		(net "P3V3_AUX")
	)
	(segment
		(start 157.595316 -55.696612)
		(end 157.59557 -55.696358)
		(width 0.4572)
		(layer "F.Cu")
		(net "P3V3_AUX")
	)
	(segment
		(start 16.796258 -428.589948)
		(end 16.796258 -427.980348)
		(width 0.3556)
		(layer "F.Cu")
		(net "P3V3_AUX")
	)
	(segment
		(start 139.184634 -59.474608)
		(end 139.508992 -59.474608)
		(width 0.4572)
		(layer "F.Cu")
		(net "P3V3_AUX")
	)
	(segment
		(start 165.976046 -116.64696)
		(end 165.976046 -116.469668)
		(width 0.4572)
		(layer "F.Cu")
		(net "P3V3_AUX")
	)
	(segment
		(start 165.11905 -106.299)
		(end 165.11905 -107.315)
		(width 0.381)
		(layer "F.Cu")
		(net "P3V3_AUX")
	)
	(segment
		(start 139.749784 -47.709074)
		(end 139.749784 -48.325024)
		(width 0.4572)
		(layer "F.Cu")
		(net "P3V3_AUX")
	)
	(segment
		(start 165.843204 -95.61195)
		(end 166.43604 -96.204786)
		(width 0.381)
		(layer "F.Cu")
		(net "P3V3_AUX")
	)
	(segment
		(start 97.10039 -404.132034)
		(end 96.928178 -403.959822)
		(width 0.3302)
		(layer "F.Cu")
		(net "P3V3_AUX")
	)
	(segment
		(start 257.125724 -131.355084)
		(end 257.379724 -131.609084)
		(width 0.3556)
		(layer "F.Cu")
		(net "P3V3_AUX")
	)
	(segment
		(start 188.322204 -115.452906)
		(end 188.712094 -115.842796)
		(width 0.254)
		(layer "F.Cu")
		(net "P3V3_AUX")
	)
	(segment
		(start 199.70369 -113.559844)
		(end 200.487026 -113.559844)
		(width 0.4064)
		(layer "F.Cu")
		(net "P3V3_AUX")
	)
	(segment
		(start 118.11 -419.24605)
		(end 118.51005 -419.24605)
		(width 0.381)
		(layer "F.Cu")
		(net "P3V3_AUX")
	)
	(segment
		(start 361.625388 -410.66212)
		(end 361.625388 -409.947364)
		(width 0.381)
		(layer "F.Cu")
		(net "P3V3_AUX")
	)
	(segment
		(start 306.020216 -431.256186)
		(end 306.020216 -431.887122)
		(width 0.381)
		(layer "F.Cu")
		(net "P3V3_AUX")
	)
	(segment
		(start 15.18412 -79.467964)
		(end 15.18412 -78.830678)
		(width 0.4064)
		(layer "F.Cu")
		(net "P3V3_AUX")
	)
	(segment
		(start 40.31996 -433.68595)
		(end 39.83355 -433.19954)
		(width 0.381)
		(layer "F.Cu")
		(net "P3V3_AUX")
	)
	(segment
		(start 281.827732 -392.305794)
		(end 282.657042 -392.305794)
		(width 0.381)
		(layer "F.Cu")
		(net "P3V3_AUX")
	)
	(segment
		(start 96.28886 -37.870638)
		(end 96.28886 -38.415214)
		(width 0.381)
		(layer "F.Cu")
		(net "P3V3_AUX")
	)
	(segment
		(start 186.722004 -116.252752)
		(end 187.111894 -116.642642)
		(width 0.254)
		(layer "F.Cu")
		(net "P3V3_AUX")
	)
	(segment
		(start 340.715346 -24.297386)
		(end 340.715346 -24.913336)
		(width 0.4064)
		(layer "F.Cu")
		(net "P3V3_AUX")
	)
	(segment
		(start 267.615162 -122.782076)
		(end 268.19987 -123.366784)
		(width 0.381)
		(layer "F.Cu")
		(net "P3V3_AUX")
	)
	(segment
		(start 302.109378 -435.633622)
		(end 302.109378 -436.249572)
		(width 0.381)
		(layer "F.Cu")
		(net "P3V3_AUX")
	)
	(segment
		(start 190.721996 -108.252768)
		(end 191.111886 -107.862878)
		(width 0.254)
		(layer "F.Cu")
		(net "P3V3_AUX")
	)
	(segment
		(start 157.277308 -352.229928)
		(end 156.74721 -352.229928)
		(width 0.381)
		(layer "F.Cu")
		(net "P3V3_AUX")
	)
	(segment
		(start 31.043118 -433.45227)
		(end 30.507178 -433.45227)
		(width 0.381)
		(layer "F.Cu")
		(net "P3V3_AUX")
	)
	(segment
		(start 33.002728 -422.91)
		(end 32.112712 -422.019984)
		(width 0.1778)
		(layer "F.Cu")
		(net "P3V3_AUX")
	)
	(segment
		(start 138.371834 -50.611024)
		(end 138.987784 -50.611024)
		(width 0.4572)
		(layer "F.Cu")
		(net "P3V3_AUX")
	)
	(segment
		(start 170.970702 -436.632096)
		(end 170.970702 -436.016146)
		(width 0.381)
		(layer "F.Cu")
		(net "P3V3_AUX")
	)
	(segment
		(start 368.427 -410.82595)
		(end 368.427 -410.083)
		(width 0.381)
		(layer "F.Cu")
		(net "P3V3_AUX")
	)
	(segment
		(start 438.629552 -423.66311)
		(end 438.629552 -422.52011)
		(width 0.381)
		(layer "F.Cu")
		(net "P3V3_AUX")
	)
	(segment
		(start 42.545 -436.51805)
		(end 42.545 -436.86476)
		(width 0.381)
		(layer "F.Cu")
		(net "P3V3_AUX")
	)
	(segment
		(start 184.322212 -116.252752)
		(end 183.932322 -116.642642)
		(width 0.254)
		(layer "F.Cu")
		(net "P3V3_AUX")
	)
	(segment
		(start 105.44556 -63.54191)
		(end 105.08361 -63.54191)
		(width 0.381)
		(layer "F.Cu")
		(net "P3V3_AUX")
	)
	(segment
		(start 31.331662 -430.769014)
		(end 31.331662 -430.159414)
		(width 0.381)
		(layer "F.Cu")
		(net "P3V3_AUX")
	)
	(segment
		(start 119.37365 -436.893462)
		(end 119.37365 -435.8767)
		(width 0.381)
		(layer "F.Cu")
		(net "P3V3_AUX")
	)
	(segment
		(start 196.39407 -105.460038)
		(end 196.431408 -105.497376)
		(width 0.381)
		(layer "F.Cu")
		(net "P3V3_AUX")
	)
	(segment
		(start 8.979408 -422.551098)
		(end 8.979408 -423.821098)
		(width 0.381)
		(layer "F.Cu")
		(net "P3V3_AUX")
	)
	(segment
		(start 434.43144 -434.067458)
		(end 434.43144 -433.451508)
		(width 0.381)
		(layer "F.Cu")
		(net "P3V3_AUX")
	)
	(segment
		(start 188.322204 -114.652806)
		(end 188.712094 -114.262916)
		(width 0.254)
		(layer "F.Cu")
		(net "P3V3_AUX")
	)
	(segment
		(start 101.346 -413.331152)
		(end 101.046788 -413.630364)
		(width 0.381)
		(layer "F.Cu")
		(net "P3V3_AUX")
	)
	(segment
		(start 126.404878 -47.121064)
		(end 125.788928 -47.121064)
		(width 0.381)
		(layer "F.Cu")
		(net "P3V3_AUX")
	)
	(segment
		(start 318.300608 -24.8793)
		(end 318.300608 -24.26335)
		(width 0.4572)
		(layer "F.Cu")
		(net "P3V3_AUX")
	)
	(segment
		(start 99.650296 -426.22978)
		(end 99.650296 -426.84573)
		(width 0.381)
		(layer "F.Cu")
		(net "P3V3_AUX")
	)
	(segment
		(start 133.094222 -32.236156)
		(end 133.348222 -31.982156)
		(width 0.1778)
		(layer "F.Cu")
		(net "P3V3_AUX")
	)
	(segment
		(start 251.074174 -134.892796)
		(end 251.074174 -133.622796)
		(width 0.4064)
		(layer "F.Cu")
		(net "P3V3_AUX")
	)
	(segment
		(start 159.18307 -77.496924)
		(end 159.124142 -77.555852)
		(width 0.4572)
		(layer "F.Cu")
		(net "P3V3_AUX")
	)
	(segment
		(start 103.453946 -55.282084)
		(end 103.453946 -56.22036)
		(width 0.381)
		(layer "F.Cu")
		(net "P3V3_AUX")
	)
	(segment
		(start 217.569034 -100.457)
		(end 217.554048 -100.471986)
		(width 0.381)
		(layer "F.Cu")
		(net "P3V3_AUX")
	)
	(segment
		(start 125.857 -40.992044)
		(end 125.857 -41.8592)
		(width 0.381)
		(layer "F.Cu")
		(net "P3V3_AUX")
	)
	(segment
		(start 437.795924 -403.999192)
		(end 436.796942 -403.00021)
		(width 0.381)
		(layer "F.Cu")
		(net "P3V3_AUX")
	)
	(segment
		(start 454.188068 -193.935096)
		(end 455.331068 -193.935096)
		(width 0.4572)
		(layer "F.Cu")
		(net "P3V3_AUX")
	)
	(segment
		(start 205.796896 -104.013)
		(end 205.372208 -104.013)
		(width 0.381)
		(layer "F.Cu")
		(net "P3V3_AUX")
	)
	(segment
		(start 438.507886 -166.684452)
		(end 438.507886 -166.024814)
		(width 0.3556)
		(layer "F.Cu")
		(net "P3V3_AUX")
	)
	(segment
		(start 256.192274 -131.355084)
		(end 257.125724 -131.355084)
		(width 0.3556)
		(layer "F.Cu")
		(net "P3V3_AUX")
	)
	(segment
		(start 214.019638 -13.90396)
		(end 213.720934 -13.605256)
		(width 0.381)
		(layer "F.Cu")
		(net "P3V3_AUX")
	)
	(segment
		(start 89.728802 -140.943584)
		(end 89.158572 -140.943584)
		(width 0.381)
		(layer "F.Cu")
		(net "P3V3_AUX")
	)
	(segment
		(start 156.74721 -352.229928)
		(end 156.62021 -352.102928)
		(width 0.381)
		(layer "F.Cu")
		(net "P3V3_AUX")
	)
	(segment
		(start 193.294 -54.75605)
		(end 193.294 -57.10682)
		(width 0.381)
		(layer "F.Cu")
		(net "P3V3_AUX")
	)
	(segment
		(start 353.5045 -430.590452)
		(end 353.5045 -431.227738)
		(width 0.381)
		(layer "F.Cu")
		(net "P3V3_AUX")
	)
	(segment
		(start 363.962188 -411.048962)
		(end 364.316264 -410.694886)
		(width 0.381)
		(layer "F.Cu")
		(net "P3V3_AUX")
	)
	(segment
		(start 167.009318 -174.16526)
		(end 159.390334 -181.784244)
		(width 0.4572)
		(layer "F.Cu")
		(net "P3V3_AUX")
	)
	(segment
		(start 28.036012 -424.259502)
		(end 28.645612 -424.259502)
		(width 0.381)
		(layer "F.Cu")
		(net "P3V3_AUX")
	)
	(segment
		(start 160.841436 -117.206014)
		(end 161.46526 -117.206014)
		(width 0.4064)
		(layer "F.Cu")
		(net "P3V3_AUX")
	)
	(segment
		(start 357.684832 -413.046418)
		(end 357.684832 -413.677354)
		(width 0.381)
		(layer "F.Cu")
		(net "P3V3_AUX")
	)
	(segment
		(start 370.03228 -14.836902)
		(end 369.52428 -15.344902)
		(width 0.508)
		(layer "F.Cu")
		(net "P3V3_AUX")
	)
	(segment
		(start 261.868666 -72.976994)
		(end 262.53186 -72.976994)
		(width 0.4064)
		(layer "F.Cu")
		(net "P3V3_AUX")
	)
	(segment
		(start 119.458486 -427.923452)
		(end 119.458486 -427.306232)
		(width 0.381)
		(layer "F.Cu")
		(net "P3V3_AUX")
	)
	(segment
		(start 320.553588 -116.632228)
		(end 320.553588 -115.428268)
		(width 0.381)
		(layer "F.Cu")
		(net "P3V3_AUX")
	)
	(segment
		(start 190.20028 -35.017456)
		(end 190.810134 -35.017456)
		(width 0.381)
		(layer "F.Cu")
		(net "P3V3_AUX")
	)
	(segment
		(start 288.900362 -395.231366)
		(end 288.87928 -395.252448)
		(width 0.254)
		(layer "F.Cu")
		(net "P3V3_AUX")
	)
	(segment
		(start 449.843652 -429.25111)
		(end 449.843652 -430.010824)
		(width 0.381)
		(layer "F.Cu")
		(net "P3V3_AUX")
	)
	(segment
		(start 318.300608 -24.8793)
		(end 316.62497 -24.8793)
		(width 0.4064)
		(layer "F.Cu")
		(net "P3V3_AUX")
	)
	(segment
		(start 269.648178 -193.935096)
		(end 270.791178 -193.935096)
		(width 0.4572)
		(layer "F.Cu")
		(net "P3V3_AUX")
	)
	(segment
		(start 255.152144 -108.804964)
		(end 255.810258 -109.463078)
		(width 0.4064)
		(layer "F.Cu")
		(net "P3V3_AUX")
	)
	(segment
		(start 103.90505 -418.973)
		(end 104.2289 -418.973)
		(width 0.381)
		(layer "F.Cu")
		(net "P3V3_AUX")
	)
	(segment
		(start 51.577494 -31.877508)
		(end 50.946558 -31.877508)
		(width 0.4064)
		(layer "F.Cu")
		(net "P3V3_AUX")
	)
	(segment
		(start 121.411238 -41.5798)
		(end 121.411238 -43.350942)
		(width 0.381)
		(layer "F.Cu")
		(net "P3V3_AUX")
	)
	(segment
		(start 178.72202 -115.452906)
		(end 178.33213 -115.842796)
		(width 0.254)
		(layer "F.Cu")
		(net "P3V3_AUX")
	)
	(segment
		(start 176.072038 -193.93535)
		(end 177.215038 -193.93535)
		(width 0.4572)
		(layer "F.Cu")
		(net "P3V3_AUX")
	)
	(segment
		(start 9.666732 -404.976584)
		(end 9.666732 -404.21687)
		(width 0.381)
		(layer "F.Cu")
		(net "P3V3_AUX")
	)
	(segment
		(start 278.254206 -431.591466)
		(end 277.61692 -431.591466)
		(width 0.381)
		(layer "F.Cu")
		(net "P3V3_AUX")
	)
	(segment
		(start 311.412636 -113.60277)
		(end 311.316116 -113.50625)
		(width 0.381)
		(layer "F.Cu")
		(net "P3V3_AUX")
	)
	(segment
		(start 148.529548 -207.370426)
		(end 147.680934 -206.521812)
		(width 0.4572)
		(layer "F.Cu")
		(net "P3V3_AUX")
	)
	(segment
		(start 318.262 -365.01705)
		(end 318.90335 -365.01705)
		(width 0.381)
		(layer "F.Cu")
		(net "P3V3_AUX")
	)
	(segment
		(start 372.06682 -15.637002)
		(end 372.06682 -14.999716)
		(width 0.4572)
		(layer "F.Cu")
		(net "P3V3_AUX")
	)
	(segment
		(start 65.287906 -54.356)
		(end 65.643506 -54.356)
		(width 0.381)
		(layer "F.Cu")
		(net "P3V3_AUX")
	)
	(segment
		(start 368.06378 -427.811438)
		(end 368.06378 -428.427388)
		(width 0.381)
		(layer "F.Cu")
		(net "P3V3_AUX")
	)
	(segment
		(start 351.007172 -425.295314)
		(end 351.007172 -425.92625)
		(width 0.381)
		(layer "F.Cu")
		(net "P3V3_AUX")
	)
	(segment
		(start 453.319896 -108.059728)
		(end 452.710296 -108.059728)
		(width 0.381)
		(layer "F.Cu")
		(net "P3V3_AUX")
	)
	(segment
		(start 185.122058 -115.452906)
		(end 184.732168 -115.842796)
		(width 0.254)
		(layer "F.Cu")
		(net "P3V3_AUX")
	)
	(segment
		(start 439.072782 -439.52541)
		(end 439.703718 -439.52541)
		(width 0.381)
		(layer "F.Cu")
		(net "P3V3_AUX")
	)
	(segment
		(start 159.390334 -181.784244)
		(end 159.390334 -192.760092)
		(width 0.4572)
		(layer "F.Cu")
		(net "P3V3_AUX")
	)
	(segment
		(start 152.343104 -106.11104)
		(end 153.14295 -105.311194)
		(width 0.381)
		(layer "F.Cu")
		(net "P3V3_AUX")
	)
	(segment
		(start 458.668882 -103.614728)
		(end 461.320896 -103.614728)
		(width 0.381)
		(layer "F.Cu")
		(net "P3V3_AUX")
	)
	(segment
		(start 13.537946 -140.30071)
		(end 13.537946 -139.66698)
		(width 0.381)
		(layer "F.Cu")
		(net "P3V3_AUX")
	)
	(segment
		(start 145.740628 -98.355658)
		(end 147.16379 -98.355658)
		(width 0.3556)
		(layer "F.Cu")
		(net "P3V3_AUX")
	)
	(segment
		(start 290.744402 -123.05665)
		(end 290.744402 -124.414026)
		(width 0.381)
		(layer "F.Cu")
		(net "P3V3_AUX")
	)
	(segment
		(start 117.66296 -62.474856)
		(end 117.66296 -62.22492)
		(width 0.4572)
		(layer "F.Cu")
		(net "P3V3_AUX")
	)
	(segment
		(start 37.402262 -430.190148)
		(end 37.402262 -430.871122)
		(width 0.381)
		(layer "F.Cu")
		(net "P3V3_AUX")
	)
	(segment
		(start 196.387974 -105.460038)
		(end 196.39407 -105.460038)
		(width 0.381)
		(layer "F.Cu")
		(net "P3V3_AUX")
	)
	(segment
		(start 393.764008 -322.627752)
		(end 394.297408 -322.627752)
		(width 0.3556)
		(layer "F.Cu")
		(net "P3V3_AUX")
	)
	(segment
		(start 46.737778 -433.172616)
		(end 46.688502 -433.172616)
		(width 0.381)
		(layer "F.Cu")
		(net "P3V3_AUX")
	)
	(segment
		(start 164.973 -95.61195)
		(end 165.843204 -95.61195)
		(width 0.381)
		(layer "F.Cu")
		(net "P3V3_AUX")
	)
	(segment
		(start 191.055498 -428.096426)
		(end 191.055498 -427.480476)
		(width 0.381)
		(layer "F.Cu")
		(net "P3V3_AUX")
	)
	(segment
		(start 211.992464 -27.969718)
		(end 213.197694 -29.174948)
		(width 0.381)
		(layer "F.Cu")
		(net "P3V3_AUX")
	)
	(segment
		(start 135.094218 -33.023556)
		(end 135.094218 -32.236156)
		(width 0.1778)
		(layer "F.Cu")
		(net "P3V3_AUX")
	)
	(segment
		(start 157.922722 -197.24878)
		(end 158.683198 -198.009256)
		(width 0.4572)
		(layer "F.Cu")
		(net "P3V3_AUX")
	)
	(segment
		(start 110.235238 -41.5798)
		(end 110.235238 -42.2656)
		(width 0.4572)
		(layer "F.Cu")
		(net "P3V3_AUX")
	)
	(segment
		(start 166.71671 -117.301772)
		(end 166.71671 -117.210332)
		(width 0.4572)
		(layer "F.Cu")
		(net "P3V3_AUX")
	)
	(segment
		(start 419.555168 -58.42762)
		(end 419.58514 -58.397648)
		(width 0.4064)
		(layer "F.Cu")
		(net "P3V3_AUX")
	)
	(segment
		(start 147.447 -123.444)
		(end 148.406104 -123.444)
		(width 0.381)
		(layer "F.Cu")
		(net "P3V3_AUX")
	)
	(segment
		(start 139.80795 -114.554)
		(end 139.80795 -113.93805)
		(width 0.381)
		(layer "F.Cu")
		(net "P3V3_AUX")
	)
	(segment
		(start 69.977 -57.784746)
		(end 70.46976 -57.291986)
		(width 0.381)
		(layer "F.Cu")
		(net "P3V3_AUX")
	)
	(segment
		(start 119.37365 -435.8767)
		(end 118.999 -435.50205)
		(width 0.381)
		(layer "F.Cu")
		(net "P3V3_AUX")
	)
	(segment
		(start 186.722004 -113.85296)
		(end 187.111894 -113.46307)
		(width 0.254)
		(layer "F.Cu")
		(net "P3V3_AUX")
	)
	(segment
		(start 109.165136 -118.44401)
		(end 109.165136 -119.05996)
		(width 0.4064)
		(layer "F.Cu")
		(net "P3V3_AUX")
	)
	(segment
		(start 111.251238 -41.5798)
		(end 111.251238 -42.2656)
		(width 0.4572)
		(layer "F.Cu")
		(net "P3V3_AUX")
	)
	(segment
		(start 178.760374 -163.01847)
		(end 178.671474 -163.01847)
		(width 0.4572)
		(layer "F.Cu")
		(net "P3V3_AUX")
	)
	(segment
		(start 430.022 -58.82005)
		(end 430.022 -59.436)
		(width 0.4572)
		(layer "F.Cu")
		(net "P3V3_AUX")
	)
	(segment
		(start 115.389152 -400.263614)
		(end 115.389152 -400.513804)
		(width 0.3048)
		(layer "F.Cu")
		(net "P3V3_AUX")
	)
	(segment
		(start 365.518446 -27.906472)
		(end 365.518446 -27.290522)
		(width 0.4572)
		(layer "F.Cu")
		(net "P3V3_AUX")
	)
	(segment
		(start 286.171132 -13.373354)
		(end 284.773878 -13.373354)
		(width 0.4572)
		(layer "F.Cu")
		(net "P3V3_AUX")
	)
	(segment
		(start 186.380374 -95.080074)
		(end 185.777124 -95.080074)
		(width 0.4572)
		(layer "F.Cu")
		(net "P3V3_AUX")
	)
	(segment
		(start 305.353974 -32.701992)
		(end 304.738024 -32.701992)
		(width 0.4064)
		(layer "F.Cu")
		(net "P3V3_AUX")
	)
	(segment
		(start 178.830224 -146.686524)
		(end 178.830224 -146.070574)
		(width 0.4572)
		(layer "F.Cu")
		(net "P3V3_AUX")
	)
	(segment
		(start 444.36792 -437.028082)
		(end 444.36792 -436.412132)
		(width 0.381)
		(layer "F.Cu")
		(net "P3V3_AUX")
	)
	(segment
		(start 181.922166 -113.85296)
		(end 181.532276 -113.46307)
		(width 0.254)
		(layer "F.Cu")
		(net "P3V3_AUX")
	)
	(segment
		(start 165.54069 -78.000606)
		(end 165.54069 -78.60792)
		(width 0.4572)
		(layer "F.Cu")
		(net "P3V3_AUX")
	)
	(segment
		(start 206.050896 -101.473)
		(end 206.050896 -100.577396)
		(width 0.381)
		(layer "F.Cu")
		(net "P3V3_AUX")
	)
	(segment
		(start 270.856202 -352.55835)
		(end 270.856202 -351.94875)
		(width 0.381)
		(layer "F.Cu")
		(net "P3V3_AUX")
	)
	(segment
		(start 270.693134 -116.321586)
		(end 269.936214 -116.321586)
		(width 0.381)
		(layer "F.Cu")
		(net "P3V3_AUX")
	)
	(segment
		(start 156.96819 -95.612458)
		(end 156.30779 -95.612458)
		(width 0.4064)
		(layer "F.Cu")
		(net "P3V3_AUX")
	)
	(segment
		(start 14.078458 -418.290248)
		(end 14.078458 -417.784026)
		(width 0.381)
		(layer "F.Cu")
		(net "P3V3_AUX")
	)
	(segment
		(start 458.634592 -107.018836)
		(end 461.169004 -107.018836)
		(width 0.381)
		(layer "F.Cu")
		(net "P3V3_AUX")
	)
	(segment
		(start 199.61733 -124.937012)
		(end 199.921368 -124.632974)
		(width 0.4064)
		(layer "F.Cu")
		(net "P3V3_AUX")
	)
	(segment
		(start 210.377786 -127.260858)
		(end 210.208622 -127.091694)
		(width 0.4064)
		(layer "F.Cu")
		(net "P3V3_AUX")
	)
	(segment
		(start 200.51395 -103.505)
		(end 199.898 -103.505)
		(width 0.381)
		(layer "F.Cu")
		(net "P3V3_AUX")
	)
	(segment
		(start 281.621738 -388.31647)
		(end 281.621738 -388.274052)
		(width 0.381)
		(layer "F.Cu")
		(net "P3V3_AUX")
	)
	(segment
		(start 118.12016 -62.932056)
		(end 117.66296 -62.474856)
		(width 0.4572)
		(layer "F.Cu")
		(net "P3V3_AUX")
	)
	(segment
		(start 20.880832 -409.421584)
		(end 21.547582 -409.421584)
		(width 0.381)
		(layer "F.Cu")
		(net "P3V3_AUX")
	)
	(segment
		(start 180.765196 -150.104602)
		(end 180.80863 -150.061168)
		(width 0.4064)
		(layer "F.Cu")
		(net "P3V3_AUX")
	)
	(segment
		(start 163.02355 -436.555896)
		(end 162.77971 -436.799736)
		(width 0.381)
		(layer "F.Cu")
		(net "P3V3_AUX")
	)
	(segment
		(start 320.097658 -105.442512)
		(end 320.09842 -105.44175)
		(width 0.4572)
		(layer "F.Cu")
		(net "P3V3_AUX")
	)
	(segment
		(start 461.516476 -100.470208)
		(end 461.516476 -101.105208)
		(width 0.381)
		(layer "F.Cu")
		(net "P3V3_AUX")
	)
	(segment
		(start 8.42772 -75.744578)
		(end 9.065006 -75.744578)
		(width 0.4064)
		(layer "F.Cu")
		(net "P3V3_AUX")
	)
	(segment
		(start 205.372208 -104.013)
		(end 205.121256 -103.762048)
		(width 0.381)
		(layer "F.Cu")
		(net "P3V3_AUX")
	)
	(segment
		(start 113.465102 -399.593816)
		(end 114.490246 -399.593816)
		(width 0.3302)
		(layer "F.Cu")
		(net "P3V3_AUX")
	)
	(segment
		(start 134.840218 -31.982156)
		(end 134.764018 -31.982156)
		(width 0.1778)
		(layer "F.Cu")
		(net "P3V3_AUX")
	)
	(segment
		(start 48.893984 -37.846)
		(end 48.581056 -37.533072)
		(width 0.381)
		(layer "F.Cu")
		(net "P3V3_AUX")
	)
	(segment
		(start 254.192786 -116.12245)
		(end 253.583186 -116.12245)
		(width 0.381)
		(layer "F.Cu")
		(net "P3V3_AUX")
	)
	(segment
		(start 62.97295 -322.68541)
		(end 54.708552 -322.68541)
		(width 0.4572)
		(layer "F.Cu")
		(net "P3V3_AUX")
	)
	(segment
		(start 278.254206 -432.756056)
		(end 278.254206 -431.591466)
		(width 0.4318)
		(layer "F.Cu")
		(net "P3V3_AUX")
	)
	(segment
		(start 185.122058 -114.652806)
		(end 184.732168 -114.262916)
		(width 0.254)
		(layer "F.Cu")
		(net "P3V3_AUX")
	)
	(segment
		(start 14.82471 -140.30071)
		(end 14.82471 -139.65809)
		(width 0.381)
		(layer "F.Cu")
		(net "P3V3_AUX")
	)
	(segment
		(start 283.112718 -387.684772)
		(end 283.112718 -388.31647)
		(width 0.381)
		(layer "F.Cu")
		(net "P3V3_AUX")
	)
	(segment
		(start 214.56904 -121.087896)
		(end 214.131144 -120.65)
		(width 0.381)
		(layer "F.Cu")
		(net "P3V3_AUX")
	)
	(segment
		(start 391.690606 -73.359264)
		(end 392.300206 -73.359264)
		(width 0.381)
		(layer "F.Cu")
		(net "P3V3_AUX")
	)
	(segment
		(start 438.277 -95.291148)
		(end 438.277 -95.957898)
		(width 0.381)
		(layer "F.Cu")
		(net "P3V3_AUX")
	)
	(segment
		(start 113.449862 -399.609056)
		(end 113.465102 -399.593816)
		(width 0.3302)
		(layer "F.Cu")
		(net "P3V3_AUX")
	)
	(segment
		(start 38.816788 -169.763694)
		(end 38.816788 -169.037)
		(width 0.3556)
		(layer "F.Cu")
		(net "P3V3_AUX")
	)
	(segment
		(start 301.819818 -145.877788)
		(end 301.819818 -145.238978)
		(width 0.254)
		(layer "F.Cu")
		(net "P3V3_AUX")
	)
	(segment
		(start 303.728882 -119.475504)
		(end 303.724818 -119.479568)
		(width 0.254)
		(layer "F.Cu")
		(net "P3V3_AUX")
	)
	(segment
		(start 108.839 -415.880042)
		(end 109.474 -416.515042)
		(width 0.381)
		(layer "F.Cu")
		(net "P3V3_AUX")
	)
	(segment
		(start 166.71671 -117.210332)
		(end 166.71671 -116.274088)
		(width 0.4572)
		(layer "F.Cu")
		(net "P3V3_AUX")
	)
	(segment
		(start 47.18304 -439.153554)
		(end 47.18304 -439.843164)
		(width 0.381)
		(layer "F.Cu")
		(net "P3V3_AUX")
	)
	(segment
		(start 149.990048 -27.08783)
		(end 149.990048 -27.506168)
		(width 0.4572)
		(layer "F.Cu")
		(net "P3V3_AUX")
	)
	(segment
		(start 438.488836 -166.703502)
		(end 438.507886 -166.684452)
		(width 0.3048)
		(layer "F.Cu")
		(net "P3V3_AUX")
	)
	(segment
		(start 144.76095 -120.777)
		(end 144.76095 -120.81002)
		(width 0.381)
		(layer "F.Cu")
		(net "P3V3_AUX")
	)
	(segment
		(start 32.327088 -426.790104)
		(end 32.19704 -426.920152)
		(width 0.4572)
		(layer "F.Cu")
		(net "P3V3_AUX")
	)
	(segment
		(start 166.73195 -120.360948)
		(end 166.73195 -119.344948)
		(width 0.4572)
		(layer "F.Cu")
		(net "P3V3_AUX")
	)
	(segment
		(start 183.168798 -414.186624)
		(end 183.414416 -413.941006)
		(width 0.381)
		(layer "F.Cu")
		(net "P3V3_AUX")
	)
	(segment
		(start 268.19987 -125.104398)
		(end 268.19987 -124.469398)
		(width 0.381)
		(layer "F.Cu")
		(net "P3V3_AUX")
	)
	(segment
		(start 99.42195 -79.121)
		(end 99.35591 -79.05496)
		(width 0.381)
		(layer "F.Cu")
		(net "P3V3_AUX")
	)
	(segment
		(start 112.597946 -55.282084)
		(end 112.597946 -55.891684)
		(width 0.4572)
		(layer "F.Cu")
		(net "P3V3_AUX")
	)
	(segment
		(start 276.952202 -124.368814)
		(end 276.342602 -124.368814)
		(width 0.381)
		(layer "F.Cu")
		(net "P3V3_AUX")
	)
	(segment
		(start 167.955468 -125.762004)
		(end 167.955468 -123.718066)
		(width 0.4572)
		(layer "F.Cu")
		(net "P3V3_AUX")
	)
	(segment
		(start 211.992464 -27.268424)
		(end 211.992464 -27.969718)
		(width 0.381)
		(layer "F.Cu")
		(net "P3V3_AUX")
	)
	(segment
		(start 167.955468 -123.718066)
		(end 167.99052 -123.683014)
		(width 0.4572)
		(layer "F.Cu")
		(net "P3V3_AUX")
	)
	(segment
		(start 97.196402 -37.865558)
		(end 96.28378 -37.865558)
		(width 0.381)
		(layer "F.Cu")
		(net "P3V3_AUX")
	)
	(segment
		(start 257.894836 -73.973944)
		(end 258.53009 -73.973944)
		(width 0.381)
		(layer "F.Cu")
		(net "P3V3_AUX")
	)
	(segment
		(start 258.351528 -108.179108)
		(end 259.269992 -108.179108)
		(width 0.4064)
		(layer "F.Cu")
		(net "P3V3_AUX")
	)
	(segment
		(start 218.16695 -100.457)
		(end 217.569034 -100.457)
		(width 0.381)
		(layer "F.Cu")
		(net "P3V3_AUX")
	)
	(segment
		(start 9.34466 -79.480664)
		(end 8.707374 -79.480664)
		(width 0.4064)
		(layer "F.Cu")
		(net "P3V3_AUX")
	)
	(segment
		(start 35.833812 -426.691298)
		(end 35.65271 -426.510196)
		(width 0.1778)
		(layer "F.Cu")
		(net "P3V3_AUX")
	)
	(segment
		(start 154.884628 -98.355658)
		(end 156.30779 -98.355658)
		(width 0.3556)
		(layer "F.Cu")
		(net "P3V3_AUX")
	)
	(segment
		(start 416.468052 -193.935096)
		(end 417.611052 -193.935096)
		(width 0.4572)
		(layer "F.Cu")
		(net "P3V3_AUX")
	)
	(segment
		(start 302.800258 -41.906698)
		(end 302.190658 -41.906698)
		(width 0.3556)
		(layer "F.Cu")
		(net "P3V3_AUX")
	)
	(segment
		(start 121.411238 -43.350942)
		(end 120.38076 -44.38142)
		(width 0.381)
		(layer "F.Cu")
		(net "P3V3_AUX")
	)
	(segment
		(start 213.19744 -29.175202)
		(end 213.197694 -29.174948)
		(width 0.4064)
		(layer "F.Cu")
		(net "P3V3_AUX")
	)
	(segment
		(start 376.89028 -32.723582)
		(end 376.89028 -33.63087)
		(width 0.4572)
		(layer "F.Cu")
		(net "P3V3_AUX")
	)
	(segment
		(start 300.172628 -13.41501)
		(end 300.172628 -14.47673)
		(width 0.381)
		(layer "F.Cu")
		(net "P3V3_AUX")
	)
	(segment
		(start 182.320692 -408.114754)
		(end 182.14594 -407.940002)
		(width 0.4572)
		(layer "F.Cu")
		(net "P3V3_AUX")
	)
	(segment
		(start 272.77695 -108.594906)
		(end 272.458942 -108.912914)
		(width 0.381)
		(layer "F.Cu")
		(net "P3V3_AUX")
	)
	(segment
		(start 214.019638 -14.845792)
		(end 214.019638 -13.90396)
		(width 0.381)
		(layer "F.Cu")
		(net "P3V3_AUX")
	)
	(segment
		(start 176.79162 -413.436308)
		(end 176.398428 -413.436308)
		(width 0.381)
		(layer "F.Cu")
		(net "P3V3_AUX")
	)
	(segment
		(start 330.642722 -41.16197)
		(end 329.993244 -41.16197)
		(width 0.3556)
		(layer "F.Cu")
		(net "P3V3_AUX")
	)
	(segment
		(start 180.177694 -419.231318)
		(end 181.297834 -420.351458)
		(width 0.381)
		(layer "F.Cu")
		(net "P3V3_AUX")
	)
	(segment
		(start 316.421008 -118.910608)
		(end 316.421008 -119.566182)
		(width 0.381)
		(layer "F.Cu")
		(net "P3V3_AUX")
	)
	(segment
		(start 35.694112 -422.91)
		(end 35.502596 -422.91)
		(width 0.1778)
		(layer "F.Cu")
		(net "P3V3_AUX")
	)
	(segment
		(start 139.80795 -113.93805)
		(end 140.33754 -113.40846)
		(width 0.381)
		(layer "F.Cu")
		(net "P3V3_AUX")
	)
	(segment
		(start 21.67763 -432.437794)
		(end 21.06803 -432.437794)
		(width 0.381)
		(layer "F.Cu")
		(net "P3V3_AUX")
	)
	(segment
		(start 419.58514 -58.397648)
		(end 420.222426 -58.397648)
		(width 0.4064)
		(layer "F.Cu")
		(net "P3V3_AUX")
	)
	(segment
		(start 20.880832 -411.707584)
		(end 20.880832 -412.850584)
		(width 0.381)
		(layer "F.Cu")
		(net "P3V3_AUX")
	)
	(segment
		(start 64.83858 -54.62143)
		(end 65.022476 -54.62143)
		(width 0.381)
		(layer "F.Cu")
		(net "P3V3_AUX")
	)
	(segment
		(start 183.616092 -193.93535)
		(end 184.759092 -193.93535)
		(width 0.4572)
		(layer "F.Cu")
		(net "P3V3_AUX")
	)
	(segment
		(start 144.093438 -123.837954)
		(end 146.138392 -121.793)
		(width 0.381)
		(layer "F.Cu")
		(net "P3V3_AUX")
	)
	(segment
		(start 176.563782 -426.332396)
		(end 175.65624 -427.239938)
		(width 0.381)
		(layer "F.Cu")
		(net "P3V3_AUX")
	)
	(segment
		(start 64.197484 -54.62143)
		(end 64.17564 -54.643274)
		(width 0.381)
		(layer "F.Cu")
		(net "P3V3_AUX")
	)
	(segment
		(start 105.485946 -55.282084)
		(end 105.485946 -56.058054)
		(width 0.381)
		(layer "F.Cu")
		(net "P3V3_AUX")
	)
	(segment
		(start 268.19987 -123.366784)
		(end 268.19987 -124.469398)
		(width 0.381)
		(layer "F.Cu")
		(net "P3V3_AUX")
	)
	(segment
		(start 419.230302 -433.986686)
		(end 418.599366 -433.986686)
		(width 0.381)
		(layer "F.Cu")
		(net "P3V3_AUX")
	)
	(segment
		(start 297.886374 -122.349514)
		(end 298.495974 -122.349514)
		(width 0.4572)
		(layer "F.Cu")
		(net "P3V3_AUX")
	)
	(segment
		(start 192.47358 -413.564832)
		(end 191.836294 -413.564832)
		(width 0.381)
		(layer "F.Cu")
		(net "P3V3_AUX")
	)
	(segment
		(start 92.359734 -33.06191)
		(end 92.359734 -32.42691)
		(width 0.381)
		(layer "F.Cu")
		(net "P3V3_AUX")
	)
	(segment
		(start 315.886338 -118.898162)
		(end 316.408562 -118.898162)
		(width 0.381)
		(layer "F.Cu")
		(net "P3V3_AUX")
	)
	(segment
		(start 147.16379 -95.612458)
		(end 145.740628 -95.612458)
		(width 0.3556)
		(layer "F.Cu")
		(net "P3V3_AUX")
	)
	(segment
		(start 211.654136 -13.605256)
		(end 211.172298 -14.087094)
		(width 0.381)
		(layer "F.Cu")
		(net "P3V3_AUX")
	)
	(segment
		(start 14.641322 -78.830678)
		(end 14.4526 -79.0194)
		(width 0.4064)
		(layer "F.Cu")
		(net "P3V3_AUX")
	)
	(segment
		(start 321.506596 -100.36175)
		(end 322.116196 -100.36175)
		(width 0.381)
		(layer "F.Cu")
		(net "P3V3_AUX")
	)
	(segment
		(start 37.853112 -368.855498)
		(end 37.853112 -369.312444)
		(width 0.381)
		(layer "F.Cu")
		(net "P3V3_AUX")
	)
	(segment
		(start 104.902 -426.86605)
		(end 104.902 -427.609)
		(width 0.381)
		(layer "F.Cu")
		(net "P3V3_AUX")
	)
	(segment
		(start 193.779902 -378.660406)
		(end 192.573402 -378.660406)
		(width 0.4572)
		(layer "F.Cu")
		(net "P3V3_AUX")
	)
	(segment
		(start 110.565946 -55.282084)
		(end 109.549946 -55.282084)
		(width 0.4572)
		(layer "F.Cu")
		(net "P3V3_AUX")
	)
	(segment
		(start 119.458486 -427.306232)
		(end 119.36095 -427.208696)
		(width 0.381)
		(layer "F.Cu")
		(net "P3V3_AUX")
	)
	(segment
		(start 53.594 -435.62905)
		(end 53.594 -436.28945)
		(width 0.381)
		(layer "F.Cu")
		(net "P3V3_AUX")
	)
	(segment
		(start 335.28508 -16.396716)
		(end 335.28508 -17.012666)
		(width 0.4572)
		(layer "F.Cu")
		(net "P3V3_AUX")
	)
	(segment
		(start 210.83905 -104.013)
		(end 211.582 -104.013)
		(width 0.381)
		(layer "F.Cu")
		(net "P3V3_AUX")
	)
	(segment
		(start 276.952202 -125.638814)
		(end 276.342602 -125.638814)
		(width 0.381)
		(layer "F.Cu")
		(net "P3V3_AUX")
	)
	(segment
		(start 420.3573 -37.277548)
		(end 419.74135 -37.277548)
		(width 0.4572)
		(layer "F.Cu")
		(net "P3V3_AUX")
	)
	(segment
		(start 461.516476 -99.493832)
		(end 461.516476 -100.470208)
		(width 0.381)
		(layer "F.Cu")
		(net "P3V3_AUX")
	)
	(segment
		(start 18.232628 -41.958514)
		(end 18.231866 -41.959276)
		(width 0.4572)
		(layer "F.Cu")
		(net "P3V3_AUX")
	)
	(segment
		(start 369.739418 -32.573468)
		(end 369.739418 -31.936182)
		(width 0.4064)
		(layer "F.Cu")
		(net "P3V3_AUX")
	)
	(segment
		(start 176.978056 -426.332396)
		(end 176.563782 -426.332396)
		(width 0.381)
		(layer "F.Cu")
		(net "P3V3_AUX")
	)
	(segment
		(start 180.772308 -164.891974)
		(end 180.772308 -164.219382)
		(width 0.4064)
		(layer "F.Cu")
		(net "P3V3_AUX")
	)
	(segment
		(start 273.778726 -119.761)
		(end 274.465796 -119.761)
		(width 0.381)
		(layer "F.Cu")
		(net "P3V3_AUX")
	)
	(segment
		(start 21.577046 -100.54971)
		(end 22.23008 -100.54971)
		(width 0.381)
		(layer "F.Cu")
		(net "P3V3_AUX")
	)
	(segment
		(start 147.82419 -101.894132)
		(end 147.16379 -101.894132)
		(width 0.4064)
		(layer "F.Cu")
		(net "P3V3_AUX")
	)
	(segment
		(start 166.73195 -115.280948)
		(end 166.73195 -114.822732)
		(width 0.4572)
		(layer "F.Cu")
		(net "P3V3_AUX")
	)
	(segment
		(start 304.777648 -118.179088)
		(end 303.724818 -118.179088)
		(width 0.381)
		(layer "F.Cu")
		(net "P3V3_AUX")
	)
	(segment
		(start 69.977 -58.65495)
		(end 69.977 -57.784746)
		(width 0.381)
		(layer "F.Cu")
		(net "P3V3_AUX")
	)
	(segment
		(start 161.999676 -436.47233)
		(end 161.34334 -436.47233)
		(width 0.381)
		(layer "F.Cu")
		(net "P3V3_AUX")
	)
	(segment
		(start 301.841408 -112.827308)
		(end 301.231808 -112.827308)
		(width 0.381)
		(layer "F.Cu")
		(net "P3V3_AUX")
	)
	(segment
		(start 21.577046 -99.413314)
		(end 22.23008 -99.413314)
		(width 0.381)
		(layer "F.Cu")
		(net "P3V3_AUX")
	)
	(segment
		(start 169.17416 -172.22216)
		(end 167.23106 -174.16526)
		(width 0.4572)
		(layer "F.Cu")
		(net "P3V3_AUX")
	)
	(segment
		(start 253.98603 -39.34333)
		(end 253.89332 -39.34333)
		(width 0.4572)
		(layer "F.Cu")
		(net "P3V3_AUX")
	)
	(segment
		(start 113.283238 -41.5798)
		(end 113.283238 -42.2656)
		(width 0.4572)
		(layer "F.Cu")
		(net "P3V3_AUX")
	)
	(segment
		(start 117.330474 -54.636162)
		(end 117.330474 -54.026562)
		(width 0.4572)
		(layer "F.Cu")
		(net "P3V3_AUX")
	)
	(segment
		(start 149.973284 -121.826274)
		(end 149.29993 -121.826274)
		(width 0.4064)
		(layer "F.Cu")
		(net "P3V3_AUX")
	)
	(segment
		(start 105.13695 -421.005)
		(end 104.521 -421.005)
		(width 0.381)
		(layer "F.Cu")
		(net "P3V3_AUX")
	)
	(segment
		(start 351.65538 -432.825652)
		(end 351.03943 -432.825652)
		(width 0.381)
		(layer "F.Cu")
		(net "P3V3_AUX")
	)
	(segment
		(start 366.415066 -423.031412)
		(end 365.907066 -422.523412)
		(width 0.381)
		(layer "F.Cu")
		(net "P3V3_AUX")
	)
	(segment
		(start 103.86695 -415.798)
		(end 103.86695 -415.095182)
		(width 0.381)
		(layer "F.Cu")
		(net "P3V3_AUX")
	)
	(segment
		(start 455.534776 -45.864526)
		(end 455.534776 -45.233082)
		(width 0.381)
		(layer "F.Cu")
		(net "P3V3_AUX")
	)
	(segment
		(start 367.931446 -29.735272)
		(end 367.931446 -29.119322)
		(width 0.4572)
		(layer "F.Cu")
		(net "P3V3_AUX")
	)
	(segment
		(start 255.810258 -109.463078)
		(end 255.810258 -110.090204)
		(width 0.4064)
		(layer "F.Cu")
		(net "P3V3_AUX")
	)
	(segment
		(start 254.192786 -114.72545)
		(end 253.583186 -114.72545)
		(width 0.381)
		(layer "F.Cu")
		(net "P3V3_AUX")
	)
	(segment
		(start 185.122058 -112.25276)
		(end 184.732168 -111.86287)
		(width 0.254)
		(layer "F.Cu")
		(net "P3V3_AUX")
	)
	(segment
		(start 148.438108 -21.106892)
		(end 148.59 -20.955)
		(width 0.381)
		(layer "F.Cu")
		(net "P3V3_AUX")
	)
	(segment
		(start 150.102316 -55.188358)
		(end 149.492716 -55.188358)
		(width 0.4572)
		(layer "F.Cu")
		(net "P3V3_AUX")
	)
	(segment
		(start 97.745296 -422.03243)
		(end 97.05721 -422.03243)
		(width 0.381)
		(layer "F.Cu")
		(net "P3V3_AUX")
	)
	(segment
		(start 454.847452 -19.827748)
		(end 454.2155 -19.827748)
		(width 0.4572)
		(layer "F.Cu")
		(net "P3V3_AUX")
	)
	(segment
		(start 308.420516 -436.120794)
		(end 309.051452 -436.120794)
		(width 0.381)
		(layer "F.Cu")
		(net "P3V3_AUX")
	)
	(segment
		(start 225.171762 -69.718428)
		(end 224.537016 -69.718428)
		(width 0.4572)
		(layer "F.Cu")
		(net "P3V3_AUX")
	)
	(segment
		(start 217.66403 -102.2223)
		(end 217.36685 -101.92512)
		(width 0.381)
		(layer "F.Cu")
		(net "P3V3_AUX")
	)
	(segment
		(start 53.57495 -435.61)
		(end 53.594 -435.62905)
		(width 0.381)
		(layer "F.Cu")
		(net "P3V3_AUX")
	)
	(segment
		(start 98.150172 -36.305998)
		(end 98.150172 -36.911788)
		(width 0.381)
		(layer "F.Cu")
		(net "P3V3_AUX")
	)
	(segment
		(start 70.71995 -58.65495)
		(end 69.977 -58.65495)
		(width 0.381)
		(layer "F.Cu")
		(net "P3V3_AUX")
	)
	(segment
		(start 29.252164 -193.93535)
		(end 30.395164 -193.93535)
		(width 0.4572)
		(layer "F.Cu")
		(net "P3V3_AUX")
	)
	(segment
		(start 135.094218 -32.236156)
		(end 134.840218 -31.982156)
		(width 0.1778)
		(layer "F.Cu")
		(net "P3V3_AUX")
	)
	(segment
		(start 157.11805 -105.695242)
		(end 156.971492 -105.548684)
		(width 0.381)
		(layer "F.Cu")
		(net "P3V3_AUX")
	)
	(segment
		(start 286.471106 -398.513808)
		(end 287.339024 -398.513808)
		(width 0.4318)
		(layer "F.Cu")
		(net "P3V3_AUX")
	)
	(segment
		(start 154.690064 -66.054732)
		(end 154.677872 -66.04254)
		(width 0.381)
		(layer "F.Cu")
		(net "P3V3_AUX")
	)
	(segment
		(start 218.16695 -101.228398)
		(end 217.676222 -101.228398)
		(width 0.381)
		(layer "F.Cu")
		(net "P3V3_AUX")
	)
	(segment
		(start 437.962802 -424.80611)
		(end 438.629552 -424.80611)
		(width 0.381)
		(layer "F.Cu")
		(net "P3V3_AUX")
	)
	(segment
		(start 260.340094 -138.048746)
		(end 259.6769 -138.048746)
		(width 0.1778)
		(layer "F.Cu")
		(net "P3V3_AUX")
	)
	(segment
		(start 97.745296 -420.37508)
		(end 97.745296 -422.03243)
		(width 0.508)
		(layer "F.Cu")
		(net "P3V3_AUX")
	)
	(segment
		(start 146.53895 -122.53595)
		(end 147.447 -123.444)
		(width 0.381)
		(layer "F.Cu")
		(net "P3V3_AUX")
	)
	(segment
		(start 150.102316 -57.220358)
		(end 149.492716 -57.220358)
		(width 0.4572)
		(layer "F.Cu")
		(net "P3V3_AUX")
	)
	(segment
		(start 314.167266 -113.60277)
		(end 311.412636 -113.60277)
		(width 0.381)
		(layer "F.Cu")
		(net "P3V3_AUX")
	)
	(segment
		(start 114.12982 -68.811394)
		(end 114.12982 -69.71792)
		(width 0.381)
		(layer "F.Cu")
		(net "P3V3_AUX")
	)
	(segment
		(start 114.719354 -399.593816)
		(end 115.389152 -400.263614)
		(width 0.3048)
		(layer "F.Cu")
		(net "P3V3_AUX")
	)
	(segment
		(start 105.08361 -63.54191)
		(end 104.82961 -63.79591)
		(width 0.381)
		(layer "F.Cu")
		(net "P3V3_AUX")
	)
	(segment
		(start 281.621738 -388.274052)
		(end 281.1018 -387.754114)
		(width 0.381)
		(layer "F.Cu")
		(net "P3V3_AUX")
	)
	(segment
		(start 424.217338 -366.197896)
		(end 424.217338 -366.854994)
		(width 0.3556)
		(layer "F.Cu")
		(net "P3V3_AUX")
	)
	(segment
		(start 66.52895 -56.261)
		(end 65.643506 -55.375556)
		(width 0.381)
		(layer "F.Cu")
		(net "P3V3_AUX")
	)
	(segment
		(start 157.549596 -45.64888)
		(end 156.554678 -45.64888)
		(width 0.4064)
		(layer "F.Cu")
		(net "P3V3_AUX")
	)
	(segment
		(start 169.686732 -435.075076)
		(end 169.686732 -436.903368)
		(width 0.381)
		(layer "F.Cu")
		(net "P3V3_AUX")
	)
	(segment
		(start 440.807602 -429.77816)
		(end 440.807602 -430.39411)
		(width 0.381)
		(layer "F.Cu")
		(net "P3V3_AUX")
	)
	(segment
		(start 90.759026 -33.02127)
		(end 92.319094 -33.02127)
		(width 0.381)
		(layer "F.Cu")
		(net "P3V3_AUX")
	)
	(segment
		(start 117.347238 -41.5798)
		(end 117.347238 -42.2656)
		(width 0.4572)
		(layer "F.Cu")
		(net "P3V3_AUX")
	)
	(segment
		(start 192.53962 -423.204132)
		(end 192.53962 -423.820082)
		(width 0.381)
		(layer "F.Cu")
		(net "P3V3_AUX")
	)
	(segment
		(start 144.76095 -120.81002)
		(end 143.4338 -122.13717)
		(width 0.381)
		(layer "F.Cu")
		(net "P3V3_AUX")
	)
	(segment
		(start 123.725178 -72.429116)
		(end 123.078748 -72.429116)
		(width 0.381)
		(layer "F.Cu")
		(net "P3V3_AUX")
	)
	(segment
		(start 18.841466 -41.958514)
		(end 18.232628 -41.958514)
		(width 0.4572)
		(layer "F.Cu")
		(net "P3V3_AUX")
	)
	(segment
		(start 368.052604 -428.416212)
		(end 368.06378 -428.427388)
		(width 0.381)
		(layer "F.Cu")
		(net "P3V3_AUX")
	)
	(segment
		(start 28.036012 -425.275502)
		(end 28.645612 -425.275502)
		(width 0.381)
		(layer "F.Cu")
		(net "P3V3_AUX")
	)
	(segment
		(start 213.802468 -26.911554)
		(end 213.445598 -27.268424)
		(width 0.381)
		(layer "F.Cu")
		(net "P3V3_AUX")
	)
	(segment
		(start 146.474688 -55.615332)
		(end 146.776186 -55.313834)
		(width 0.1778)
		(layer "F.Cu")
		(net "P3V3_AUX")
	)
	(segment
		(start 370.660676 -425.63034)
		(end 370.31676 -425.63034)
		(width 0.381)
		(layer "F.Cu")
		(net "P3V3_AUX")
	)
	(segment
		(start 33.002728 -426.510196)
		(end 32.327088 -426.790104)
		(width 0.1778)
		(layer "F.Cu")
		(net "P3V3_AUX")
	)
	(segment
		(start 218.16695 -100.457)
		(end 218.16695 -101.228398)
		(width 0.381)
		(layer "F.Cu")
		(net "P3V3_AUX")
	)
	(segment
		(start 302.20412 -424.555158)
		(end 302.416464 -424.342814)
		(width 0.381)
		(layer "F.Cu")
		(net "P3V3_AUX")
	)
	(segment
		(start 99.42195 -79.882238)
		(end 99.42195 -79.121)
		(width 0.381)
		(layer "F.Cu")
		(net "P3V3_AUX")
	)
	(segment
		(start 314.967366 -109.53877)
		(end 315.576966 -109.53877)
		(width 0.381)
		(layer "F.Cu")
		(net "P3V3_AUX")
	)
	(segment
		(start 147.82419 -98.355658)
		(end 147.16379 -98.355658)
		(width 0.4064)
		(layer "F.Cu")
		(net "P3V3_AUX")
	)
	(segment
		(start 19.45005 -364.236)
		(end 20.07997 -364.236)
		(width 0.381)
		(layer "F.Cu")
		(net "P3V3_AUX")
	)
	(segment
		(start 67.81165 -35.588956)
		(end 67.810634 -35.58794)
		(width 0.4064)
		(layer "F.Cu")
		(net "P3V3_AUX")
	)
	(segment
		(start 182.14594 -407.940002)
		(end 182.14594 -407.059892)
		(width 0.4572)
		(layer "F.Cu")
		(net "P3V3_AUX")
	)
	(segment
		(start 272.15338 -120.78335)
		(end 271.492726 -120.78335)
		(width 0.381)
		(layer "F.Cu")
		(net "P3V3_AUX")
	)
	(segment
		(start 178.229006 -354.373434)
		(end 178.229006 -355.48443)
		(width 0.508)
		(layer "F.Cu")
		(net "P3V3_AUX")
	)
	(segment
		(start 209.739992 -127.898652)
		(end 210.377786 -127.260858)
		(width 0.381)
		(layer "F.Cu")
		(net "P3V3_AUX")
	)
	(segment
		(start 197.799198 -124.801376)
		(end 197.934834 -124.937012)
		(width 0.4064)
		(layer "F.Cu")
		(net "P3V3_AUX")
	)
	(segment
		(start 353.585272 -425.295314)
		(end 353.585272 -425.92625)
		(width 0.381)
		(layer "F.Cu")
		(net "P3V3_AUX")
	)
	(segment
		(start 98.073972 -36.229798)
		(end 96.633538 -36.229798)
		(width 0.381)
		(layer "F.Cu")
		(net "P3V3_AUX")
	)
	(segment
		(start 259.131308 -137.503154)
		(end 258.538472 -137.503154)
		(width 0.381)
		(layer "F.Cu")
		(net "P3V3_AUX")
	)
	(segment
		(start 438.629552 -424.80611)
		(end 438.629552 -423.66311)
		(width 0.381)
		(layer "F.Cu")
		(net "P3V3_AUX")
	)
	(segment
		(start 308.598316 -430.240186)
		(end 308.598316 -429.60925)
		(width 0.381)
		(layer "F.Cu")
		(net "P3V3_AUX")
	)
	(segment
		(start 308.420516 -439.676794)
		(end 309.051452 -439.676794)
		(width 0.381)
		(layer "F.Cu")
		(net "P3V3_AUX")
	)
	(segment
		(start 163.182046 -102.015544)
		(end 163.19627 -102.00132)
		(width 0.4572)
		(layer "F.Cu")
		(net "P3V3_AUX")
	)
	(segment
		(start 16.20012 -75.744578)
		(end 14.901672 -75.744578)
		(width 0.4064)
		(layer "F.Cu")
		(net "P3V3_AUX")
	)
	(segment
		(start 101.046788 -413.630364)
		(end 101.046788 -413.92221)
		(width 0.381)
		(layer "F.Cu")
		(net "P3V3_AUX")
	)
	(segment
		(start 107.33405 -13.909548)
		(end 107.94365 -13.909548)
		(width 0.4572)
		(layer "F.Cu")
		(net "P3V3_AUX")
	)
	(segment
		(start 454.2155 -19.827748)
		(end 454.203816 -19.839432)
		(width 0.4572)
		(layer "F.Cu")
		(net "P3V3_AUX")
	)
	(segment
		(start 276.952202 -118.89867)
		(end 276.342602 -118.89867)
		(width 0.381)
		(layer "F.Cu")
		(net "P3V3_AUX")
	)
	(segment
		(start 185.922158 -114.652806)
		(end 186.312048 -114.262916)
		(width 0.254)
		(layer "F.Cu")
		(net "P3V3_AUX")
	)
	(segment
		(start 417.27374 -354.17633)
		(end 416.836098 -354.613972)
		(width 0.3556)
		(layer "F.Cu")
		(net "P3V3_AUX")
	)
	(segment
		(start 29.214064 -75.634088)
		(end 29.214064 -76.271374)
		(width 0.4064)
		(layer "F.Cu")
		(net "P3V3_AUX")
	)
	(segment
		(start 22.892258 -428.589948)
		(end 22.892258 -427.980348)
		(width 0.3556)
		(layer "F.Cu")
		(net "P3V3_AUX")
	)
	(segment
		(start 32.112712 -421.916098)
		(end 32.112712 -421.281098)
		(width 0.381)
		(layer "F.Cu")
		(net "P3V3_AUX")
	)
	(segment
		(start 314.167266 -114.23777)
		(end 314.167266 -113.60277)
		(width 0.381)
		(layer "F.Cu")
		(net "P3V3_AUX")
	)
	(segment
		(start 169.604182 -169.912284)
		(end 169.17416 -170.342306)
		(width 0.4572)
		(layer "F.Cu")
		(net "P3V3_AUX")
	)
	(segment
		(start 192.913 -95.703898)
		(end 192.951608 -95.66529)
		(width 0.4572)
		(layer "F.Cu")
		(net "P3V3_AUX")
	)
	(segment
		(start 16.837406 -75.744578)
		(end 16.20012 -75.744578)
		(width 0.4064)
		(layer "F.Cu")
		(net "P3V3_AUX")
	)
	(segment
		(start 154.677872 -66.04254)
		(end 154.677872 -65.700148)
		(width 0.381)
		(layer "F.Cu")
		(net "P3V3_AUX")
	)
	(segment
		(start 204.347826 -98.490024)
		(end 203.825348 -98.490024)
		(width 0.381)
		(layer "F.Cu")
		(net "P3V3_AUX")
	)
	(segment
		(start 438.312052 -406.188672)
		(end 437.795924 -405.672544)
		(width 0.381)
		(layer "F.Cu")
		(net "P3V3_AUX")
	)
	(segment
		(start 206.248 -193.93535)
		(end 207.391 -193.93535)
		(width 0.4572)
		(layer "F.Cu")
		(net "P3V3_AUX")
	)
	(segment
		(start 30.075378 -133.798564)
		(end 30.075378 -133.188964)
		(width 0.4064)
		(layer "F.Cu")
		(net "P3V3_AUX")
	)
	(segment
		(start 422.148 -55.35295)
		(end 422.48074 -55.02021)
		(width 0.381)
		(layer "F.Cu")
		(net "P3V3_AUX")
	)
	(segment
		(start 163.182046 -102.984046)
		(end 163.182046 -102.015544)
		(width 0.4572)
		(layer "F.Cu")
		(net "P3V3_AUX")
	)
	(segment
		(start 369.231418 -33.081468)
		(end 369.739418 -32.573468)
		(width 0.3556)
		(layer "F.Cu")
		(net "P3V3_AUX")
	)
	(segment
		(start 184.322212 -114.652806)
		(end 183.932322 -114.262916)
		(width 0.254)
		(layer "F.Cu")
		(net "P3V3_AUX")
	)
	(segment
		(start 429.136302 -436.564786)
		(end 429.513492 -436.564786)
		(width 0.381)
		(layer "F.Cu")
		(net "P3V3_AUX")
	)
	(segment
		(start 54.671214 -39.68496)
		(end 53.904896 -39.68496)
		(width 0.381)
		(layer "F.Cu")
		(net "P3V3_AUX")
	)
	(segment
		(start 87.157814 -56.800496)
		(end 87.402924 -56.555386)
		(width 0.254)
		(layer "F.Cu")
		(net "P3V3_AUX")
	)
	(segment
		(start 209.96021 -37.369242)
		(end 209.922872 -37.331904)
		(width 0.2286)
		(layer "F.Cu")
		(net "P3V3_AUX")
	)
	(segment
		(start 156.30779 -95.612458)
		(end 154.884628 -95.612458)
		(width 0.3556)
		(layer "F.Cu")
		(net "P3V3_AUX")
	)
	(segment
		(start 70.33895 -52.578)
		(end 69.596 -52.578)
		(width 0.381)
		(layer "F.Cu")
		(net "P3V3_AUX")
	)
	(segment
		(start 74.35596 -57.855104)
		(end 74.35596 -57.15)
		(width 0.381)
		(layer "F.Cu")
		(net "P3V3_AUX")
	)
	(segment
		(start 461.517746 -94.277434)
		(end 460.387446 -94.277434)
		(width 0.381)
		(layer "F.Cu")
		(net "P3V3_AUX")
	)
	(segment
		(start 359.059988 -414.809178)
		(end 359.059988 -415.992818)
		(width 0.4318)
		(layer "F.Cu")
		(net "P3V3_AUX")
	)
	(segment
		(start 295.169844 -18.780506)
		(end 295.169844 -17.813274)
		(width 0.381)
		(layer "F.Cu")
		(net "P3V3_AUX")
	)
	(segment
		(start 177.19294 -413.414972)
		(end 177.171604 -413.436308)
		(width 0.381)
		(layer "F.Cu")
		(net "P3V3_AUX")
	)
	(segment
		(start 301.75835 -362.839)
		(end 300.9646 -362.839)
		(width 0.381)
		(layer "F.Cu")
		(net "P3V3_AUX")
	)
	(segment
		(start 259.44195 -143.764)
		(end 259.44195 -144.427956)
		(width 0.381)
		(layer "F.Cu")
		(net "P3V3_AUX")
	)
	(segment
		(start 212.593682 -111.646208)
		(end 211.932266 -111.646208)
		(width 0.381)
		(layer "F.Cu")
		(net "P3V3_AUX")
	)
	(segment
		(start 42.545 -436.86476)
		(end 42.282618 -437.127142)
		(width 0.381)
		(layer "F.Cu")
		(net "P3V3_AUX")
	)
	(segment
		(start 169.05605 -434.869336)
		(end 169.480992 -434.869336)
		(width 0.381)
		(layer "F.Cu")
		(net "P3V3_AUX")
	)
	(segment
		(start 157.81274 -45.385736)
		(end 157.549596 -45.64888)
		(width 0.4064)
		(layer "F.Cu")
		(net "P3V3_AUX")
	)
	(segment
		(start 461.01127 -38.565836)
		(end 461.01127 -37.92855)
		(width 0.4064)
		(layer "F.Cu")
		(net "P3V3_AUX")
	)
	(segment
		(start 16.364458 -418.290248)
		(end 16.364458 -417.447984)
		(width 0.381)
		(layer "F.Cu")
		(net "P3V3_AUX")
	)
	(segment
		(start 371.272308 -424.424602)
		(end 371.272308 -425.018708)
		(width 0.381)
		(layer "F.Cu")
		(net "P3V3_AUX")
	)
	(segment
		(start 147.83943 -58.088784)
		(end 148.035264 -58.088784)
		(width 0.254)
		(layer "F.Cu")
		(net "P3V3_AUX")
	)
	(segment
		(start 204.594714 -96.77908)
		(end 203.87564 -96.77908)
		(width 0.381)
		(layer "F.Cu")
		(net "P3V3_AUX")
	)
	(segment
		(start 315.308996 -119.475504)
		(end 315.886338 -118.898162)
		(width 0.381)
		(layer "F.Cu")
		(net "P3V3_AUX")
	)
	(segment
		(start 413.302196 -360.7943)
		(end 413.937196 -360.7943)
		(width 0.3556)
		(layer "F.Cu")
		(net "P3V3_AUX")
	)
	(segment
		(start 279.022556 -435.823614)
		(end 279.653492 -435.823614)
		(width 0.381)
		(layer "F.Cu")
		(net "P3V3_AUX")
	)
	(segment
		(start 32.891222 -434.808884)
		(end 32.891222 -434.173884)
		(width 0.381)
		(layer "F.Cu")
		(net "P3V3_AUX")
	)
	(segment
		(start 282.657042 -392.305794)
		(end 282.927298 -392.035538)
		(width 0.381)
		(layer "F.Cu")
		(net "P3V3_AUX")
	)
	(segment
		(start 35.862514 -422.741598)
		(end 35.694112 -422.91)
		(width 0.1778)
		(layer "F.Cu")
		(net "P3V3_AUX")
	)
	(segment
		(start 108.206794 -135.306054)
		(end 108.206794 -133.321552)
		(width 0.4572)
		(layer "F.Cu")
		(net "P3V3_AUX")
	)
	(segment
		(start 111.977678 -44.38142)
		(end 111.251238 -43.65498)
		(width 0.381)
		(layer "F.Cu")
		(net "P3V3_AUX")
	)
	(segment
		(start 103.013764 -37.6682)
		(end 102.397814 -37.6682)
		(width 0.381)
		(layer "F.Cu")
		(net "P3V3_AUX")
	)
	(segment
		(start 163.02355 -437.043576)
		(end 163.02355 -437.423052)
		(width 0.381)
		(layer "F.Cu")
		(net "P3V3_AUX")
	)
	(segment
		(start 25.826466 -38.402514)
		(end 25.826466 -39.037514)
		(width 0.381)
		(layer "F.Cu")
		(net "P3V3_AUX")
	)
	(segment
		(start 150.020274 -116.429028)
		(end 150.000208 -116.449094)
		(width 0.381)
		(layer "F.Cu")
		(net "P3V3_AUX")
	)
	(segment
		(start 115.315238 -41.5798)
		(end 115.315238 -42.2656)
		(width 0.4572)
		(layer "F.Cu")
		(net "P3V3_AUX")
	)
	(segment
		(start 17.305782 -403.941534)
		(end 17.305782 -403.325584)
		(width 0.381)
		(layer "F.Cu")
		(net "P3V3_AUX")
	)
	(segment
		(start 297.886374 -116.545614)
		(end 298.495974 -116.545614)
		(width 0.381)
		(layer "F.Cu")
		(net "P3V3_AUX")
	)
	(segment
		(start 196.780912 -39.046912)
		(end 196.15658 -39.046912)
		(width 0.381)
		(layer "F.Cu")
		(net "P3V3_AUX")
	)
	(segment
		(start 276.952202 -123.08967)
		(end 276.342602 -123.08967)
		(width 0.381)
		(layer "F.Cu")
		(net "P3V3_AUX")
	)
	(segment
		(start 256.685034 -74.44105)
		(end 257.15214 -73.973944)
		(width 0.381)
		(layer "F.Cu")
		(net "P3V3_AUX")
	)
	(segment
		(start 254.192786 -120.31345)
		(end 253.583186 -120.31345)
		(width 0.381)
		(layer "F.Cu")
		(net "P3V3_AUX")
	)
	(segment
		(start 369.231418 -34.243772)
		(end 369.231418 -33.081468)
		(width 0.3556)
		(layer "F.Cu")
		(net "P3V3_AUX")
	)
	(segment
		(start 32.112712 -422.019984)
		(end 32.112712 -421.916098)
		(width 0.1778)
		(layer "F.Cu")
		(net "P3V3_AUX")
	)
	(segment
		(start 390.281668 -78.440026)
		(end 390.28243 -78.439264)
		(width 0.4572)
		(layer "F.Cu")
		(net "P3V3_AUX")
	)
	(segment
		(start 161.268156 -34.92373)
		(end 161.268156 -36.302188)
		(width 0.4572)
		(layer "F.Cu")
		(net "P3V3_AUX")
	)
	(segment
		(start 418.316664 -58.42762)
		(end 419.555168 -58.42762)
		(width 0.4064)
		(layer "F.Cu")
		(net "P3V3_AUX")
	)
	(segment
		(start 438.056782 -433.09921)
		(end 437.365648 -433.09921)
		(width 0.381)
		(layer "F.Cu")
		(net "P3V3_AUX")
	)
	(segment
		(start 425.54144 -434.067458)
		(end 424.815 -434.067458)
		(width 0.381)
		(layer "F.Cu")
		(net "P3V3_AUX")
	)
	(segment
		(start 158.683198 -198.009256)
		(end 158.683198 -200.631552)
		(width 0.4572)
		(layer "F.Cu")
		(net "P3V3_AUX")
	)
	(segment
		(start 420.246302 -436.564786)
		(end 420.877238 -436.564786)
		(width 0.381)
		(layer "F.Cu")
		(net "P3V3_AUX")
	)
	(segment
		(start 274.42668 -123.896628)
		(end 273.75739 -123.896628)
		(width 0.381)
		(layer "F.Cu")
		(net "P3V3_AUX")
	)
	(segment
		(start 422.48074 -55.02021)
		(end 422.48074 -54.733952)
		(width 0.381)
		(layer "F.Cu")
		(net "P3V3_AUX")
	)
	(segment
		(start 119.118634 -59.884056)
		(end 119.728234 -59.884056)
		(width 0.4572)
		(layer "F.Cu")
		(net "P3V3_AUX")
	)
	(segment
		(start 109.549946 -55.282084)
		(end 108.533946 -55.282084)
		(width 0.4572)
		(layer "F.Cu")
		(net "P3V3_AUX")
	)
	(segment
		(start 154.690064 -69.665088)
		(end 154.690064 -66.054732)
		(width 0.381)
		(layer "F.Cu")
		(net "P3V3_AUX")
	)
	(segment
		(start 155.12415 -103.338884)
		(end 156.30779 -103.338884)
		(width 0.3556)
		(layer "F.Cu")
		(net "P3V3_AUX")
	)
	(segment
		(start 177.544984 -146.686524)
		(end 177.544984 -146.070574)
		(width 0.4572)
		(layer "F.Cu")
		(net "P3V3_AUX")
	)
	(segment
		(start 185.922158 -115.452906)
		(end 186.312048 -115.842796)
		(width 0.254)
		(layer "F.Cu")
		(net "P3V3_AUX")
	)
	(segment
		(start 120.38076 -44.38142)
		(end 111.977678 -44.38142)
		(width 0.381)
		(layer "F.Cu")
		(net "P3V3_AUX")
	)
	(segment
		(start 143.4338 -122.13717)
		(end 142.14348 -122.13717)
		(width 0.381)
		(layer "F.Cu")
		(net "P3V3_AUX")
	)
	(segment
		(start 202.79995 -99.95408)
		(end 202.189334 -100.564696)
		(width 0.381)
		(layer "F.Cu")
		(net "P3V3_AUX")
	)
	(segment
		(start 304.701448 -430.2379)
		(end 304.701448 -429.606964)
		(width 0.381)
		(layer "F.Cu")
		(net "P3V3_AUX")
	)
	(segment
		(start 289.728148 -122.782076)
		(end 290.469828 -122.782076)
		(width 0.381)
		(layer "F.Cu")
		(net "P3V3_AUX")
	)
	(segment
		(start 345.467686 -24.28875)
		(end 345.467686 -24.9047)
		(width 0.4064)
		(layer "F.Cu")
		(net "P3V3_AUX")
	)
	(segment
		(start 167.99052 -123.683014)
		(end 167.99052 -123.46813)
		(width 0.4572)
		(layer "F.Cu")
		(net "P3V3_AUX")
	)
	(segment
		(start 302.800258 -40.890698)
		(end 302.190658 -40.890698)
		(width 0.3556)
		(layer "F.Cu")
		(net "P3V3_AUX")
	)
	(segment
		(start 251.074174 -133.622796)
		(end 251.074174 -132.337556)
		(width 0.4064)
		(layer "F.Cu")
		(net "P3V3_AUX")
	)
	(segment
		(start 162.275012 -434.272436)
		(end 162.275012 -435.467506)
		(width 0.381)
		(layer "F.Cu")
		(net "P3V3_AUX")
	)
	(segment
		(start 207.15605 -99.695)
		(end 207.15605 -100.055934)
		(width 0.381)
		(layer "F.Cu")
		(net "P3V3_AUX")
	)
	(segment
		(start 114.299238 -41.5798)
		(end 114.299238 -42.2656)
		(width 0.4572)
		(layer "F.Cu")
		(net "P3V3_AUX")
	)
	(segment
		(start 254.192786 -126.91745)
		(end 253.574804 -126.91745)
		(width 0.381)
		(layer "F.Cu")
		(net "P3V3_AUX")
	)
	(segment
		(start 15.18412 -71.847964)
		(end 15.18412 -71.210678)
		(width 0.4064)
		(layer "F.Cu")
		(net "P3V3_AUX")
	)
	(segment
		(start 176.398428 -413.436308)
		(end 176.136554 -413.698182)
		(width 0.381)
		(layer "F.Cu")
		(net "P3V3_AUX")
	)
	(segment
		(start 125.592586 -60.482226)
		(end 124.860812 -60.482226)
		(width 0.4572)
		(layer "F.Cu")
		(net "P3V3_AUX")
	)
	(segment
		(start 52.38496 -435.61)
		(end 53.57495 -435.61)
		(width 0.381)
		(layer "F.Cu")
		(net "P3V3_AUX")
	)
	(segment
		(start 186.576462 -95.276162)
		(end 186.380374 -95.080074)
		(width 0.4572)
		(layer "F.Cu")
		(net "P3V3_AUX")
	)
	(segment
		(start 51.884072 -193.93535)
		(end 53.027072 -193.93535)
		(width 0.4572)
		(layer "F.Cu")
		(net "P3V3_AUX")
	)
	(segment
		(start 419.094666 -157.218634)
		(end 418.378132 -157.218634)
		(width 0.4572)
		(layer "F.Cu")
		(net "P3V3_AUX")
	)
	(segment
		(start 64.17564 -54.643274)
		(end 63.539624 -54.643274)
		(width 0.381)
		(layer "F.Cu")
		(net "P3V3_AUX")
	)
	(segment
		(start 186.804046 -95.276162)
		(end 186.576462 -95.276162)
		(width 0.4572)
		(layer "F.Cu")
		(net "P3V3_AUX")
	)
	(segment
		(start 438.056782 -436.94731)
		(end 437.425846 -436.94731)
		(width 0.381)
		(layer "F.Cu")
		(net "P3V3_AUX")
	)
	(segment
		(start 25.6667 -323.279516)
		(end 24.33066 -324.615556)
		(width 0.4572)
		(layer "F.Cu")
		(net "P3V3_AUX")
	)
	(segment
		(start 191.522096 -118.652798)
		(end 191.911986 -119.042688)
		(width 0.254)
		(layer "F.Cu")
		(net "P3V3_AUX")
	)
	(segment
		(start 397.876268 -74.883264)
		(end 397.876268 -75.518264)
		(width 0.381)
		(layer "F.Cu")
		(net "P3V3_AUX")
	)
	(segment
		(start 16.110966 -92.287598)
		(end 16.110966 -91.618308)
		(width 0.381)
		(layer "F.Cu")
		(net "P3V3_AUX")
	)
	(segment
		(start 113.613946 -55.282084)
		(end 113.613946 -55.891684)
		(width 0.4572)
		(layer "F.Cu")
		(net "P3V3_AUX")
	)
	(segment
		(start 84.922106 -41.29532)
		(end 84.922106 -41.95318)
		(width 0.4064)
		(layer "F.Cu")
		(net "P3V3_AUX")
	)
	(segment
		(start 213.720934 -13.605256)
		(end 211.654136 -13.605256)
		(width 0.381)
		(layer "F.Cu")
		(net "P3V3_AUX")
	)
	(segment
		(start 210.34883 -42.382948)
		(end 209.634328 -42.382948)
		(width 0.4572)
		(layer "F.Cu")
		(net "P3V3_AUX")
	)
	(segment
		(start 361.625388 -411.354016)
		(end 361.625388 -410.66212)
		(width 0.381)
		(layer "F.Cu")
		(net "P3V3_AUX")
	)
	(segment
		(start 277.192232 -193.935096)
		(end 278.335232 -193.935096)
		(width 0.4572)
		(layer "F.Cu")
		(net "P3V3_AUX")
	)
	(segment
		(start 103.86695 -415.095182)
		(end 104.026208 -414.935924)
		(width 0.381)
		(layer "F.Cu")
		(net "P3V3_AUX")
	)
	(segment
		(start 276.952202 -117.50167)
		(end 276.342602 -117.50167)
		(width 0.381)
		(layer "F.Cu")
		(net "P3V3_AUX")
	)
	(segment
		(start 147.877022 -21.106892)
		(end 148.438108 -21.106892)
		(width 0.381)
		(layer "F.Cu")
		(net "P3V3_AUX")
	)
	(via
		(at 28.036012 -424.259502)
		(size 0.508)
		(drill 0.254)
		(layers "F.Cu" "B.Cu")
		(net "P3V3_AUX")
	)
	(via
		(at 269.936214 -116.321586)
		(size 0.508)
		(drill 0.254)
		(layers "F.Cu" "B.Cu")
		(net "P3V3_AUX")
	)
	(via
		(at 328.699876 -65.692782)
		(size 0.508)
		(drill 0.254)
		(layers "F.Cu" "B.Cu")
		(net "P3V3_AUX")
	)
	(via
		(at 424.217338 -366.854994)
		(size 0.508)
		(drill 0.254)
		(layers "F.Cu" "B.Cu")
		(net "P3V3_AUX")
	)
	(via
		(at 336.827876 -65.692782)
		(size 0.508)
		(drill 0.254)
		(layers "F.Cu" "B.Cu")
		(net "P3V3_AUX")
	)
	(via
		(at 98.50247 -410.159708)
		(size 0.508)
		(drill 0.254)
		(layers "F.Cu" "B.Cu")
		(net "P3V3_AUX")
	)
	(via
		(at 178.33213 -119.042688)
		(size 0.4572)
		(drill 0.254)
		(layers "F.Cu" "B.Cu")
		(net "P3V3_AUX")
	)
	(via
		(at 418.41674 -104.501188)
		(size 0.508)
		(drill 0.254)
		(layers "F.Cu" "B.Cu")
		(net "P3V3_AUX")
	)
	(via
		(at 439.703718 -439.52541)
		(size 0.508)
		(drill 0.254)
		(layers "F.Cu" "B.Cu")
		(net "P3V3_AUX")
	)
	(via
		(at 180.669692 -414.663636)
		(size 0.508)
		(drill 0.254)
		(layers "F.Cu" "B.Cu")
		(net "P3V3_AUX")
	)
	(via
		(at 184.785 -99.278948)
		(size 0.508)
		(drill 0.254)
		(layers "F.Cu" "B.Cu")
		(net "P3V3_AUX")
	)
	(via
		(at 276.342602 -123.08967)
		(size 0.508)
		(drill 0.254)
		(layers "F.Cu" "B.Cu")
		(net "P3V3_AUX")
	)
	(via
		(at 322.603876 -65.692782)
		(size 0.508)
		(drill 0.254)
		(layers "F.Cu" "B.Cu")
		(net "P3V3_AUX")
	)
	(via
		(at 47.18304 -439.843164)
		(size 0.508)
		(drill 0.254)
		(layers "F.Cu" "B.Cu")
		(net "P3V3_AUX")
	)
	(via
		(at 15.18412 -71.847964)
		(size 0.508)
		(drill 0.254)
		(layers "F.Cu" "B.Cu")
		(net "P3V3_AUX")
	)
	(via
		(at 210.046062 -236.329728)
		(size 0.508)
		(drill 0.254)
		(layers "F.Cu" "B.Cu")
		(net "P3V3_AUX")
	)
	(via
		(at 210.035648 -120.901206)
		(size 0.508)
		(drill 0.254)
		(layers "F.Cu" "B.Cu")
		(net "P3V3_AUX")
	)
	(via
		(at 117.347238 -42.2656)
		(size 0.508)
		(drill 0.254)
		(layers "F.Cu" "B.Cu")
		(net "P3V3_AUX")
	)
	(via
		(at 42.282618 -437.127142)
		(size 0.508)
		(drill 0.254)
		(layers "F.Cu" "B.Cu")
		(net "P3V3_AUX")
	)
	(via
		(at 255.149858 -137.648696)
		(size 0.508)
		(drill 0.254)
		(layers "F.Cu" "B.Cu")
		(net "P3V3_AUX")
	)
	(via
		(at 224.537016 -70.792848)
		(size 0.508)
		(drill 0.254)
		(layers "F.Cu" "B.Cu")
		(net "P3V3_AUX")
	)
	(via
		(at 102.154736 -118.483126)
		(size 0.508)
		(drill 0.254)
		(layers "F.Cu" "B.Cu")
		(net "P3V3_AUX")
	)
	(via
		(at 250.458224 -131.067556)
		(size 0.508)
		(drill 0.254)
		(layers "F.Cu" "B.Cu")
		(net "P3V3_AUX")
	)
	(via
		(at 38.733984 -437.627014)
		(size 0.508)
		(drill 0.254)
		(layers "F.Cu" "B.Cu")
		(net "P3V3_AUX")
	)
	(via
		(at 464.434682 -109.646212)
		(size 0.508)
		(drill 0.254)
		(layers "F.Cu" "B.Cu")
		(net "P3V3_AUX")
	)
	(via
		(at 113.2332 -414.8328)
		(size 0.508)
		(drill 0.254)
		(layers "F.Cu" "B.Cu")
		(net "P3V3_AUX")
	)
	(via
		(at 104.521 -421.005)
		(size 0.508)
		(drill 0.254)
		(layers "F.Cu" "B.Cu")
		(net "P3V3_AUX")
	)
	(via
		(at 156.554678 -46.286166)
		(size 0.508)
		(drill 0.254)
		(layers "F.Cu" "B.Cu")
		(net "P3V3_AUX")
	)
	(via
		(at 309.051452 -436.120794)
		(size 0.508)
		(drill 0.254)
		(layers "F.Cu" "B.Cu")
		(net "P3V3_AUX")
	)
	(via
		(at 221.617032 -76.777342)
		(size 0.508)
		(drill 0.254)
		(layers "F.Cu" "B.Cu")
		(net "P3V3_AUX")
	)
	(via
		(at 452.710296 -104.249728)
		(size 0.508)
		(drill 0.254)
		(layers "F.Cu" "B.Cu")
		(net "P3V3_AUX")
	)
	(via
		(at 139.508992 -59.474608)
		(size 0.508)
		(drill 0.254)
		(layers "F.Cu" "B.Cu")
		(net "P3V3_AUX")
	)
	(via
		(at 101.046788 -413.92221)
		(size 0.508)
		(drill 0.254)
		(layers "F.Cu" "B.Cu")
		(net "P3V3_AUX")
	)
	(via
		(at 156.473398 -347.260164)
		(size 0.508)
		(drill 0.254)
		(layers "F.Cu" "B.Cu")
		(net "P3V3_AUX")
	)
	(via
		(at 420.877238 -436.564786)
		(size 0.508)
		(drill 0.254)
		(layers "F.Cu" "B.Cu")
		(net "P3V3_AUX")
	)
	(via
		(at 274.42668 -123.896628)
		(size 0.508)
		(drill 0.254)
		(layers "F.Cu" "B.Cu")
		(net "P3V3_AUX")
	)
	(via
		(at 143.801592 -82.423508)
		(size 0.508)
		(drill 0.254)
		(layers "F.Cu" "B.Cu")
		(net "P3V3_AUX")
	)
	(via
		(at 435.06898 -403.00021)
		(size 0.508)
		(drill 0.254)
		(layers "F.Cu" "B.Cu")
		(net "P3V3_AUX")
	)
	(via
		(at 446.728088 -71.592186)
		(size 0.508)
		(drill 0.254)
		(layers "F.Cu" "B.Cu")
		(net "P3V3_AUX")
	)
	(via
		(at 434.43144 -433.451508)
		(size 0.508)
		(drill 0.254)
		(layers "F.Cu" "B.Cu")
		(net "P3V3_AUX")
	)
	(via
		(at 376.630692 -428.239428)
		(size 0.508)
		(drill 0.254)
		(layers "F.Cu" "B.Cu")
		(net "P3V3_AUX")
	)
	(via
		(at 355.498146 -421.026082)
		(size 0.508)
		(drill 0.254)
		(layers "F.Cu" "B.Cu")
		(net "P3V3_AUX")
	)
	(via
		(at 203.87564 -96.77908)
		(size 0.508)
		(drill 0.254)
		(layers "F.Cu" "B.Cu")
		(net "P3V3_AUX")
	)
	(via
		(at 30.075378 -133.798564)
		(size 0.508)
		(drill 0.254)
		(layers "F.Cu" "B.Cu")
		(net "P3V3_AUX")
	)
	(via
		(at 29.214064 -81.46161)
		(size 0.508)
		(drill 0.254)
		(layers "F.Cu" "B.Cu")
		(net "P3V3_AUX")
	)
	(via
		(at 8.784336 -334.071976)
		(size 0.508)
		(drill 0.254)
		(layers "F.Cu" "B.Cu")
		(net "P3V3_AUX")
	)
	(via
		(at 303.724818 -118.179088)
		(size 0.508)
		(drill 0.254)
		(layers "F.Cu" "B.Cu")
		(net "P3V3_AUX")
	)
	(via
		(at 429.823372 -436.254906)
		(size 0.508)
		(drill 0.254)
		(layers "F.Cu" "B.Cu")
		(net "P3V3_AUX")
	)
	(via
		(at 221.150688 -75.05319)
		(size 0.508)
		(drill 0.254)
		(layers "F.Cu" "B.Cu")
		(net "P3V3_AUX")
	)
	(via
		(at 64.692276 -96.144842)
		(size 0.508)
		(drill 0.254)
		(layers "F.Cu" "B.Cu")
		(net "P3V3_AUX")
	)
	(via
		(at 394.891768 -322.500752)
		(size 0.508)
		(drill 0.254)
		(layers "F.Cu" "B.Cu")
		(net "P3V3_AUX")
	)
	(via
		(at 31.331662 -430.769014)
		(size 0.508)
		(drill 0.254)
		(layers "F.Cu" "B.Cu")
		(net "P3V3_AUX")
	)
	(via
		(at 302.190658 -40.890698)
		(size 0.508)
		(drill 0.254)
		(layers "F.Cu" "B.Cu")
		(net "P3V3_AUX")
	)
	(via
		(at 274.576794 -427.354746)
		(size 0.508)
		(drill 0.254)
		(layers "F.Cu" "B.Cu")
		(net "P3V3_AUX")
	)
	(via
		(at 12.384532 -396.06093)
		(size 0.508)
		(drill 0.254)
		(layers "F.Cu" "B.Cu")
		(net "P3V3_AUX")
	)
	(via
		(at 290.076382 -427.332648)
		(size 0.508)
		(drill 0.254)
		(layers "F.Cu" "B.Cu")
		(net "P3V3_AUX")
	)
	(via
		(at 62.956186 -95.348806)
		(size 0.508)
		(drill 0.254)
		(layers "F.Cu" "B.Cu")
		(net "P3V3_AUX")
	)
	(via
		(at 182.332122 -115.842796)
		(size 0.4572)
		(drill 0.254)
		(layers "F.Cu" "B.Cu")
		(net "P3V3_AUX")
	)
	(via
		(at 165.576758 -353.332796)
		(size 0.508)
		(drill 0.254)
		(layers "F.Cu" "B.Cu")
		(net "P3V3_AUX")
	)
	(via
		(at 274.556982 -428.81423)
		(size 0.508)
		(drill 0.254)
		(layers "F.Cu" "B.Cu")
		(net "P3V3_AUX")
	)
	(via
		(at 116.078 -419.1)
		(size 0.508)
		(drill 0.254)
		(layers "F.Cu" "B.Cu")
		(net "P3V3_AUX")
	)
	(via
		(at 363.281976 -408.931364)
		(size 0.508)
		(drill 0.254)
		(layers "F.Cu" "B.Cu")
		(net "P3V3_AUX")
	)
	(via
		(at 445.204088 -71.592186)
		(size 0.508)
		(drill 0.254)
		(layers "F.Cu" "B.Cu")
		(net "P3V3_AUX")
	)
	(via
		(at 207.515714 -100.415598)
		(size 0.508)
		(drill 0.254)
		(layers "F.Cu" "B.Cu")
		(net "P3V3_AUX")
	)
	(via
		(at 304.738024 -32.701992)
		(size 0.508)
		(drill 0.254)
		(layers "F.Cu" "B.Cu")
		(net "P3V3_AUX")
	)
	(via
		(at 162.73526 -432.700938)
		(size 0.508)
		(drill 0.254)
		(layers "F.Cu" "B.Cu")
		(net "P3V3_AUX")
	)
	(via
		(at 283.112718 -387.684772)
		(size 0.508)
		(drill 0.254)
		(layers "F.Cu" "B.Cu")
		(net "P3V3_AUX")
	)
	(via
		(at 258.500372 -137.465054)
		(size 0.508)
		(drill 0.254)
		(layers "F.Cu" "B.Cu")
		(net "P3V3_AUX")
	)
	(via
		(at 448.201542 -68.492878)
		(size 0.508)
		(drill 0.254)
		(layers "F.Cu" "B.Cu")
		(net "P3V3_AUX")
	)
	(via
		(at 32.19704 -427.325282)
		(size 0.508)
		(drill 0.254)
		(layers "F.Cu" "B.Cu")
		(net "P3V3_AUX")
	)
	(via
		(at 182.332122 -114.262916)
		(size 0.4572)
		(drill 0.254)
		(layers "F.Cu" "B.Cu")
		(net "P3V3_AUX")
	)
	(via
		(at 283.056076 -430.767744)
		(size 0.508)
		(drill 0.254)
		(layers "F.Cu" "B.Cu")
		(net "P3V3_AUX")
	)
	(via
		(at 92.359734 -32.42691)
		(size 0.508)
		(drill 0.254)
		(layers "F.Cu" "B.Cu")
		(net "P3V3_AUX")
	)
	(via
		(at 139.662916 -103.199692)
		(size 0.508)
		(drill 0.254)
		(layers "F.Cu" "B.Cu")
		(net "P3V3_AUX")
	)
	(via
		(at 156.96819 -103.465884)
		(size 0.508)
		(drill 0.254)
		(layers "F.Cu" "B.Cu")
		(net "P3V3_AUX")
	)
	(via
		(at 118.745 -419.481)
		(size 0.508)
		(drill 0.254)
		(layers "F.Cu" "B.Cu")
		(net "P3V3_AUX")
	)
	(via
		(at 430.53508 -372.267734)
		(size 0.508)
		(drill 0.254)
		(layers "F.Cu" "B.Cu")
		(net "P3V3_AUX")
	)
	(via
		(at 113.75136 -70.09638)
		(size 0.508)
		(drill 0.254)
		(layers "F.Cu" "B.Cu")
		(net "P3V3_AUX")
	)
	(via
		(at 164.963856 -429.55972)
		(size 0.508)
		(drill 0.254)
		(layers "F.Cu" "B.Cu")
		(net "P3V3_AUX")
	)
	(via
		(at 210.080352 -237.080298)
		(size 0.508)
		(drill 0.254)
		(layers "F.Cu" "B.Cu")
		(net "P3V3_AUX")
	)
	(via
		(at 211.397596 -324.434454)
		(size 0.508)
		(drill 0.254)
		(layers "F.Cu" "B.Cu")
		(net "P3V3_AUX")
	)
	(via
		(at 91.737434 -56.670956)
		(size 0.508)
		(drill 0.254)
		(layers "F.Cu" "B.Cu")
		(net "P3V3_AUX")
	)
	(via
		(at 171.18584 -414.792668)
		(size 0.508)
		(drill 0.254)
		(layers "F.Cu" "B.Cu")
		(net "P3V3_AUX")
	)
	(via
		(at 210.047332 -238.54156)
		(size 0.508)
		(drill 0.254)
		(layers "F.Cu" "B.Cu")
		(net "P3V3_AUX")
	)
	(via
		(at 110.97895 -418.973)
		(size 0.508)
		(drill 0.254)
		(layers "F.Cu" "B.Cu")
		(net "P3V3_AUX")
	)
	(via
		(at 413.302196 -360.7943)
		(size 0.508)
		(drill 0.254)
		(layers "F.Cu" "B.Cu")
		(net "P3V3_AUX")
	)
	(via
		(at 202.189334 -100.564696)
		(size 0.508)
		(drill 0.254)
		(layers "F.Cu" "B.Cu")
		(net "P3V3_AUX")
	)
	(via
		(at 364.302548 -13.434568)
		(size 0.508)
		(drill 0.254)
		(layers "F.Cu" "B.Cu")
		(net "P3V3_AUX")
	)
	(via
		(at 25.89657 -367.95964)
		(size 0.508)
		(drill 0.254)
		(layers "F.Cu" "B.Cu")
		(net "P3V3_AUX")
	)
	(via
		(at 371.766338 -138.424158)
		(size 0.508)
		(drill 0.254)
		(layers "F.Cu" "B.Cu")
		(net "P3V3_AUX")
	)
	(via
		(at 210.047332 -237.77956)
		(size 0.508)
		(drill 0.254)
		(layers "F.Cu" "B.Cu")
		(net "P3V3_AUX")
	)
	(via
		(at 220.982032 -76.777342)
		(size 0.508)
		(drill 0.254)
		(layers "F.Cu" "B.Cu")
		(net "P3V3_AUX")
	)
	(via
		(at 445.013588 -68.527676)
		(size 0.508)
		(drill 0.254)
		(layers "F.Cu" "B.Cu")
		(net "P3V3_AUX")
	)
	(via
		(at 17.305782 -403.325584)
		(size 0.508)
		(drill 0.254)
		(layers "F.Cu" "B.Cu")
		(net "P3V3_AUX")
	)
	(via
		(at 110.363 -416.941)
		(size 0.508)
		(drill 0.254)
		(layers "F.Cu" "B.Cu")
		(net "P3V3_AUX")
	)
	(via
		(at 182.332122 -112.66297)
		(size 0.4572)
		(drill 0.254)
		(layers "F.Cu" "B.Cu")
		(net "P3V3_AUX")
	)
	(via
		(at 91.737434 -56.035956)
		(size 0.508)
		(drill 0.254)
		(layers "F.Cu" "B.Cu")
		(net "P3V3_AUX")
	)
	(via
		(at 303.724818 -116.891308)
		(size 0.508)
		(drill 0.254)
		(layers "F.Cu" "B.Cu")
		(net "P3V3_AUX")
	)
	(via
		(at 276.342602 -124.368814)
		(size 0.508)
		(drill 0.254)
		(layers "F.Cu" "B.Cu")
		(net "P3V3_AUX")
	)
	(via
		(at 122.891042 -72.616822)
		(size 0.508)
		(drill 0.254)
		(layers "F.Cu" "B.Cu")
		(net "P3V3_AUX")
	)
	(via
		(at 50.946558 -31.877508)
		(size 0.508)
		(drill 0.254)
		(layers "F.Cu" "B.Cu")
		(net "P3V3_AUX")
	)
	(via
		(at 449.65112 -94.602808)
		(size 0.508)
		(drill 0.254)
		(layers "F.Cu" "B.Cu")
		(net "P3V3_AUX")
	)
	(via
		(at 149.413976 -53.083714)
		(size 0.508)
		(drill 0.254)
		(layers "F.Cu" "B.Cu")
		(net "P3V3_AUX")
	)
	(via
		(at 306.77358 -437.098694)
		(size 0.508)
		(drill 0.254)
		(layers "F.Cu" "B.Cu")
		(net "P3V3_AUX")
	)
	(via
		(at 428.087282 -439.307986)
		(size 0.508)
		(drill 0.254)
		(layers "F.Cu" "B.Cu")
		(net "P3V3_AUX")
	)
	(via
		(at 301.231808 -112.827308)
		(size 0.508)
		(drill 0.254)
		(layers "F.Cu" "B.Cu")
		(net "P3V3_AUX")
	)
	(via
		(at 214.339424 -22.278594)
		(size 0.508)
		(drill 0.254)
		(layers "F.Cu" "B.Cu")
		(net "P3V3_AUX")
	)
	(via
		(at 104.843834 -133.30428)
		(size 0.508)
		(drill 0.254)
		(layers "F.Cu" "B.Cu")
		(net "P3V3_AUX")
	)
	(via
		(at 22.892258 -428.589948)
		(size 0.508)
		(drill 0.254)
		(layers "F.Cu" "B.Cu")
		(net "P3V3_AUX")
	)
	(via
		(at 147.44319 -33.796224)
		(size 0.508)
		(drill 0.254)
		(layers "F.Cu" "B.Cu")
		(net "P3V3_AUX")
	)
	(via
		(at 124.929646 -13.99413)
		(size 0.508)
		(drill 0.254)
		(layers "F.Cu" "B.Cu")
		(net "P3V3_AUX")
	)
	(via
		(at 283.696918 -382.733042)
		(size 0.508)
		(drill 0.254)
		(layers "F.Cu" "B.Cu")
		(net "P3V3_AUX")
	)
	(via
		(at 274.57527 -362.066332)
		(size 0.508)
		(drill 0.254)
		(layers "F.Cu" "B.Cu")
		(net "P3V3_AUX")
	)
	(via
		(at 171.576238 -428.562262)
		(size 0.508)
		(drill 0.254)
		(layers "F.Cu" "B.Cu")
		(net "P3V3_AUX")
	)
	(via
		(at 390.281668 -78.440026)
		(size 0.508)
		(drill 0.254)
		(layers "F.Cu" "B.Cu")
		(net "P3V3_AUX")
	)
	(via
		(at 340.891876 -65.692782)
		(size 0.508)
		(drill 0.254)
		(layers "F.Cu" "B.Cu")
		(net "P3V3_AUX")
	)
	(via
		(at 398.797272 -135.66013)
		(size 0.508)
		(drill 0.254)
		(layers "F.Cu" "B.Cu")
		(net "P3V3_AUX")
	)
	(via
		(at 253.583186 -117.51945)
		(size 0.508)
		(drill 0.254)
		(layers "F.Cu" "B.Cu")
		(net "P3V3_AUX")
	)
	(via
		(at 147.680934 -206.521812)
		(size 0.508)
		(drill 0.254)
		(layers "F.Cu" "B.Cu")
		(net "P3V3_AUX")
	)
	(via
		(at 156.62021 -352.102928)
		(size 0.508)
		(drill 0.254)
		(layers "F.Cu" "B.Cu")
		(net "P3V3_AUX")
	)
	(via
		(at 308.598316 -429.60925)
		(size 0.508)
		(drill 0.254)
		(layers "F.Cu" "B.Cu")
		(net "P3V3_AUX")
	)
	(via
		(at 317.57239 -77.039978)
		(size 0.508)
		(drill 0.254)
		(layers "F.Cu" "B.Cu")
		(net "P3V3_AUX")
	)
	(via
		(at 178.33213 -111.063024)
		(size 0.4572)
		(drill 0.254)
		(layers "F.Cu" "B.Cu")
		(net "P3V3_AUX")
	)
	(via
		(at 187.111894 -116.642642)
		(size 0.4572)
		(drill 0.254)
		(layers "F.Cu" "B.Cu")
		(net "P3V3_AUX")
	)
	(via
		(at 186.312048 -107.862878)
		(size 0.4572)
		(drill 0.254)
		(layers "F.Cu" "B.Cu")
		(net "P3V3_AUX")
	)
	(via
		(at 99.650296 -426.84573)
		(size 0.508)
		(drill 0.254)
		(layers "F.Cu" "B.Cu")
		(net "P3V3_AUX")
	)
	(via
		(at 158.885128 -37.333428)
		(size 0.508)
		(drill 0.254)
		(layers "F.Cu" "B.Cu")
		(net "P3V3_AUX")
	)
	(via
		(at 159.383984 -19.044158)
		(size 0.508)
		(drill 0.254)
		(layers "F.Cu" "B.Cu")
		(net "P3V3_AUX")
	)
	(via
		(at 183.932322 -113.46307)
		(size 0.4572)
		(drill 0.254)
		(layers "F.Cu" "B.Cu")
		(net "P3V3_AUX")
	)
	(via
		(at 241.173 -221.107)
		(size 0.508)
		(drill 0.254)
		(layers "F.Cu" "B.Cu")
		(net "P3V3_AUX")
	)
	(via
		(at 91.102434 -56.035956)
		(size 0.508)
		(drill 0.254)
		(layers "F.Cu" "B.Cu")
		(net "P3V3_AUX")
	)
	(via
		(at 273.816064 -429.566578)
		(size 0.508)
		(drill 0.254)
		(layers "F.Cu" "B.Cu")
		(net "P3V3_AUX")
	)
	(via
		(at 150.502366 -117.237002)
		(size 0.508)
		(drill 0.254)
		(layers "F.Cu" "B.Cu")
		(net "P3V3_AUX")
	)
	(via
		(at 443.76848 -434.549296)
		(size 0.508)
		(drill 0.254)
		(layers "F.Cu" "B.Cu")
		(net "P3V3_AUX")
	)
	(via
		(at 169.029126 -14.86535)
		(size 0.508)
		(drill 0.254)
		(layers "F.Cu" "B.Cu")
		(net "P3V3_AUX")
	)
	(via
		(at 224.537016 -69.718428)
		(size 0.508)
		(drill 0.254)
		(layers "F.Cu" "B.Cu")
		(net "P3V3_AUX")
	)
	(via
		(at 7.254748 -131.32435)
		(size 0.508)
		(drill 0.254)
		(layers "F.Cu" "B.Cu")
		(net "P3V3_AUX")
	)
	(via
		(at 445.966088 -70.830186)
		(size 0.508)
		(drill 0.254)
		(layers "F.Cu" "B.Cu")
		(net "P3V3_AUX")
	)
	(via
		(at 281.1018 -387.754114)
		(size 0.508)
		(drill 0.254)
		(layers "F.Cu" "B.Cu")
		(net "P3V3_AUX")
	)
	(via
		(at 113.284 -419.1)
		(size 0.508)
		(drill 0.254)
		(layers "F.Cu" "B.Cu")
		(net "P3V3_AUX")
	)
	(via
		(at 318.300608 -24.26335)
		(size 0.508)
		(drill 0.254)
		(layers "F.Cu" "B.Cu")
		(net "P3V3_AUX")
	)
	(via
		(at 104.63276 -59.802268)
		(size 0.508)
		(drill 0.254)
		(layers "F.Cu" "B.Cu")
		(net "P3V3_AUX")
	)
	(via
		(at 303.276 -359.283)
		(size 0.508)
		(drill 0.254)
		(layers "F.Cu" "B.Cu")
		(net "P3V3_AUX")
	)
	(via
		(at 170.970702 -436.016146)
		(size 0.508)
		(drill 0.254)
		(layers "F.Cu" "B.Cu")
		(net "P3V3_AUX")
	)
	(via
		(at 445.775588 -67.765676)
		(size 0.508)
		(drill 0.254)
		(layers "F.Cu" "B.Cu")
		(net "P3V3_AUX")
	)
	(via
		(at 219.96654 -241.366548)
		(size 0.508)
		(drill 0.254)
		(layers "F.Cu" "B.Cu")
		(net "P3V3_AUX")
	)
	(via
		(at 188.712094 -112.66297)
		(size 0.4572)
		(drill 0.254)
		(layers "F.Cu" "B.Cu")
		(net "P3V3_AUX")
	)
	(via
		(at 207.391 -193.93535)
		(size 0.4826)
		(drill 0.254)
		(layers "F.Cu" "B.Cu")
		(net "P3V3_AUX")
	)
	(via
		(at 161.34334 -436.47233)
		(size 0.508)
		(drill 0.254)
		(layers "F.Cu" "B.Cu")
		(net "P3V3_AUX")
	)
	(via
		(at 186.312048 -115.842796)
		(size 0.4572)
		(drill 0.254)
		(layers "F.Cu" "B.Cu")
		(net "P3V3_AUX")
	)
	(via
		(at 123.617228 -49.153064)
		(size 0.508)
		(drill 0.254)
		(layers "F.Cu" "B.Cu")
		(net "P3V3_AUX")
	)
	(via
		(at 361.77601 -418.329618)
		(size 0.508)
		(drill 0.254)
		(layers "F.Cu" "B.Cu")
		(net "P3V3_AUX")
	)
	(via
		(at 177.544984 -146.070574)
		(size 0.508)
		(drill 0.254)
		(layers "F.Cu" "B.Cu")
		(net "P3V3_AUX")
	)
	(via
		(at 190.682118 -81.256378)
		(size 0.508)
		(drill 0.254)
		(layers "F.Cu" "B.Cu")
		(net "P3V3_AUX")
	)
	(via
		(at 346.987876 -65.692782)
		(size 0.508)
		(drill 0.254)
		(layers "F.Cu" "B.Cu")
		(net "P3V3_AUX")
	)
	(via
		(at 355.106732 -413.677354)
		(size 0.508)
		(drill 0.254)
		(layers "F.Cu" "B.Cu")
		(net "P3V3_AUX")
	)
	(via
		(at 141.114018 -60.19038)
		(size 0.508)
		(drill 0.254)
		(layers "F.Cu" "B.Cu")
		(net "P3V3_AUX")
	)
	(via
		(at 162.73018 -18.889726)
		(size 0.508)
		(drill 0.254)
		(layers "F.Cu" "B.Cu")
		(net "P3V3_AUX")
	)
	(via
		(at 163.5252 -42.177462)
		(size 0.508)
		(drill 0.254)
		(layers "F.Cu" "B.Cu")
		(net "P3V3_AUX")
	)
	(via
		(at 16.575278 -419.847014)
		(size 0.508)
		(drill 0.254)
		(layers "F.Cu" "B.Cu")
		(net "P3V3_AUX")
	)
	(via
		(at 171.426632 -417.698174)
		(size 0.508)
		(drill 0.254)
		(layers "F.Cu" "B.Cu")
		(net "P3V3_AUX")
	)
	(via
		(at 21.776944 -353.465638)
		(size 0.508)
		(drill 0.254)
		(layers "F.Cu" "B.Cu")
		(net "P3V3_AUX")
	)
	(via
		(at 87.384636 -71.782686)
		(size 0.508)
		(drill 0.254)
		(layers "F.Cu" "B.Cu")
		(net "P3V3_AUX")
	)
	(via
		(at 110.235238 -42.2656)
		(size 0.508)
		(drill 0.254)
		(layers "F.Cu" "B.Cu")
		(net "P3V3_AUX")
	)
	(via
		(at 447.439542 -67.730878)
		(size 0.508)
		(drill 0.254)
		(layers "F.Cu" "B.Cu")
		(net "P3V3_AUX")
	)
	(via
		(at 93.896434 -74.831956)
		(size 0.508)
		(drill 0.254)
		(layers "F.Cu" "B.Cu")
		(net "P3V3_AUX")
	)
	(via
		(at 111.251238 -42.2656)
		(size 0.508)
		(drill 0.254)
		(layers "F.Cu" "B.Cu")
		(net "P3V3_AUX")
	)
	(via
		(at 8.932418 -413.231584)
		(size 0.508)
		(drill 0.254)
		(layers "F.Cu" "B.Cu")
		(net "P3V3_AUX")
	)
	(via
		(at 274.465796 -119.761)
		(size 0.508)
		(drill 0.254)
		(layers "F.Cu" "B.Cu")
		(net "P3V3_AUX")
	)
	(via
		(at 187.111894 -115.842796)
		(size 0.4572)
		(drill 0.254)
		(layers "F.Cu" "B.Cu")
		(net "P3V3_AUX")
	)
	(via
		(at 427.97095 -33.467548)
		(size 0.508)
		(drill 0.254)
		(layers "F.Cu" "B.Cu")
		(net "P3V3_AUX")
	)
	(via
		(at 149.535642 -105.624884)
		(size 0.508)
		(drill 0.254)
		(layers "F.Cu" "B.Cu")
		(net "P3V3_AUX")
	)
	(via
		(at 301.231808 -114.859308)
		(size 0.508)
		(drill 0.254)
		(layers "F.Cu" "B.Cu")
		(net "P3V3_AUX")
	)
	(via
		(at 294.681402 -367.189258)
		(size 0.508)
		(drill 0.254)
		(layers "F.Cu" "B.Cu")
		(net "P3V3_AUX")
	)
	(via
		(at 397.247618 -346.25407)
		(size 0.508)
		(drill 0.254)
		(layers "F.Cu" "B.Cu")
		(net "P3V3_AUX")
	)
	(via
		(at 445.775588 -68.527676)
		(size 0.508)
		(drill 0.254)
		(layers "F.Cu" "B.Cu")
		(net "P3V3_AUX")
	)
	(via
		(at 253.583186 -114.72545)
		(size 0.508)
		(drill 0.254)
		(layers "F.Cu" "B.Cu")
		(net "P3V3_AUX")
	)
	(via
		(at 138.7729 -10.048748)
		(size 0.508)
		(drill 0.254)
		(layers "F.Cu" "B.Cu")
		(net "P3V3_AUX")
	)
	(via
		(at 438.507886 -166.024814)
		(size 0.508)
		(drill 0.254)
		(layers "F.Cu" "B.Cu")
		(net "P3V3_AUX")
	)
	(via
		(at 89.158572 -140.943584)
		(size 0.508)
		(drill 0.254)
		(layers "F.Cu" "B.Cu")
		(net "P3V3_AUX")
	)
	(via
		(at 9.131808 -140.10767)
		(size 0.508)
		(drill 0.254)
		(layers "F.Cu" "B.Cu")
		(net "P3V3_AUX")
	)
	(via
		(at 255.149858 -140.518896)
		(size 0.508)
		(drill 0.254)
		(layers "F.Cu" "B.Cu")
		(net "P3V3_AUX")
	)
	(via
		(at 338.31022 -17.00403)
		(size 0.508)
		(drill 0.254)
		(layers "F.Cu" "B.Cu")
		(net "P3V3_AUX")
	)
	(via
		(at 447.439542 -68.492878)
		(size 0.508)
		(drill 0.254)
		(layers "F.Cu" "B.Cu")
		(net "P3V3_AUX")
	)
	(via
		(at 22.23008 -97.083626)
		(size 0.508)
		(drill 0.254)
		(layers "F.Cu" "B.Cu")
		(net "P3V3_AUX")
	)
	(via
		(at 434.086 -104.993948)
		(size 0.508)
		(drill 0.254)
		(layers "F.Cu" "B.Cu")
		(net "P3V3_AUX")
	)
	(via
		(at 459.389988 -43.400726)
		(size 0.508)
		(drill 0.254)
		(layers "F.Cu" "B.Cu")
		(net "P3V3_AUX")
	)
	(via
		(at 351.007172 -425.92625)
		(size 0.508)
		(drill 0.254)
		(layers "F.Cu" "B.Cu")
		(net "P3V3_AUX")
	)
	(via
		(at 85.344 -72.136)
		(size 0.508)
		(drill 0.254)
		(layers "F.Cu" "B.Cu")
		(net "P3V3_AUX")
	)
	(via
		(at 32.891222 -434.808884)
		(size 0.508)
		(drill 0.254)
		(layers "F.Cu" "B.Cu")
		(net "P3V3_AUX")
	)
	(via
		(at 262.53186 -75.770994)
		(size 0.508)
		(drill 0.254)
		(layers "F.Cu" "B.Cu")
		(net "P3V3_AUX")
	)
	(via
		(at 175.86706 -428.648876)
		(size 0.508)
		(drill 0.254)
		(layers "F.Cu" "B.Cu")
		(net "P3V3_AUX")
	)
	(via
		(at 9.065006 -75.744578)
		(size 0.508)
		(drill 0.254)
		(layers "F.Cu" "B.Cu")
		(net "P3V3_AUX")
	)
	(via
		(at 23.622 -362.204)
		(size 0.508)
		(drill 0.254)
		(layers "F.Cu" "B.Cu")
		(net "P3V3_AUX")
	)
	(via
		(at 424.815 -434.067458)
		(size 0.508)
		(drill 0.254)
		(layers "F.Cu" "B.Cu")
		(net "P3V3_AUX")
	)
	(via
		(at 20.955 -436.964074)
		(size 0.508)
		(drill 0.254)
		(layers "F.Cu" "B.Cu")
		(net "P3V3_AUX")
	)
	(via
		(at 357.330756 -419.719506)
		(size 0.508)
		(drill 0.254)
		(layers "F.Cu" "B.Cu")
		(net "P3V3_AUX")
	)
	(via
		(at 178.481482 -414.96361)
		(size 0.508)
		(drill 0.254)
		(layers "F.Cu" "B.Cu")
		(net "P3V3_AUX")
	)
	(via
		(at 152.370536 -104.648)
		(size 0.508)
		(drill 0.254)
		(layers "F.Cu" "B.Cu")
		(net "P3V3_AUX")
	)
	(via
		(at 219.21597 -239.126014)
		(size 0.508)
		(drill 0.254)
		(layers "F.Cu" "B.Cu")
		(net "P3V3_AUX")
	)
	(via
		(at 169.670984 -193.93535)
		(size 0.4826)
		(drill 0.254)
		(layers "F.Cu" "B.Cu")
		(net "P3V3_AUX")
	)
	(via
		(at 190.810134 -35.017456)
		(size 0.508)
		(drill 0.254)
		(layers "F.Cu" "B.Cu")
		(net "P3V3_AUX")
	)
	(via
		(at 17.361916 -333.780638)
		(size 0.508)
		(drill 0.254)
		(layers "F.Cu" "B.Cu")
		(net "P3V3_AUX")
	)
	(via
		(at 67.810634 -35.58794)
		(size 0.508)
		(drill 0.254)
		(layers "F.Cu" "B.Cu")
		(net "P3V3_AUX")
	)
	(via
		(at 284.317694 -435.288436)
		(size 0.508)
		(drill 0.254)
		(layers "F.Cu" "B.Cu")
		(net "P3V3_AUX")
	)
	(via
		(at 358.22001 -418.329618)
		(size 0.508)
		(drill 0.254)
		(layers "F.Cu" "B.Cu")
		(net "P3V3_AUX")
	)
	(via
		(at 172.570902 -419.925754)
		(size 0.508)
		(drill 0.254)
		(layers "F.Cu" "B.Cu")
		(net "P3V3_AUX")
	)
	(via
		(at 276.204934 -38.027864)
		(size 0.508)
		(drill 0.254)
		(layers "F.Cu" "B.Cu")
		(net "P3V3_AUX")
	)
	(via
		(at 358.422702 -415.992818)
		(size 0.508)
		(drill 0.254)
		(layers "F.Cu" "B.Cu")
		(net "P3V3_AUX")
	)
	(via
		(at 33.617662 -418.239448)
		(size 0.508)
		(drill 0.254)
		(layers "F.Cu" "B.Cu")
		(net "P3V3_AUX")
	)
	(via
		(at 421.92575 -429.450754)
		(size 0.508)
		(drill 0.254)
		(layers "F.Cu" "B.Cu")
		(net "P3V3_AUX")
	)
	(via
		(at 312.443876 -65.692782)
		(size 0.508)
		(drill 0.254)
		(layers "F.Cu" "B.Cu")
		(net "P3V3_AUX")
	)
	(via
		(at 459.129384 -67.724782)
		(size 0.508)
		(drill 0.254)
		(layers "F.Cu" "B.Cu")
		(net "P3V3_AUX")
	)
	(via
		(at 419.10508 -104.508808)
		(size 0.508)
		(drill 0.254)
		(layers "F.Cu" "B.Cu")
		(net "P3V3_AUX")
	)
	(via
		(at 60.571126 -193.93535)
		(size 0.4826)
		(drill 0.254)
		(layers "F.Cu" "B.Cu")
		(net "P3V3_AUX")
	)
	(via
		(at 16.13916 -111.455708)
		(size 0.508)
		(drill 0.254)
		(layers "F.Cu" "B.Cu")
		(net "P3V3_AUX")
	)
	(via
		(at 197.231 -94.234)
		(size 0.508)
		(drill 0.254)
		(layers "F.Cu" "B.Cu")
		(net "P3V3_AUX")
	)
	(via
		(at 215.58123 -40.674798)
		(size 0.508)
		(drill 0.254)
		(layers "F.Cu" "B.Cu")
		(net "P3V3_AUX")
	)
	(via
		(at 257.28295 -141.732)
		(size 0.508)
		(drill 0.254)
		(layers "F.Cu" "B.Cu")
		(net "P3V3_AUX")
	)
	(via
		(at 233.907838 -223.997266)
		(size 0.508)
		(drill 0.254)
		(layers "F.Cu" "B.Cu")
		(net "P3V3_AUX")
	)
	(via
		(at 180.772308 -164.219382)
		(size 0.508)
		(drill 0.254)
		(layers "F.Cu" "B.Cu")
		(net "P3V3_AUX")
	)
	(via
		(at 107.94365 -13.909548)
		(size 0.508)
		(drill 0.254)
		(layers "F.Cu" "B.Cu")
		(net "P3V3_AUX")
	)
	(via
		(at 104.507792 -419.251892)
		(size 0.508)
		(drill 0.254)
		(layers "F.Cu" "B.Cu")
		(net "P3V3_AUX")
	)
	(via
		(at 52.782978 -427.050708)
		(size 0.508)
		(drill 0.254)
		(layers "F.Cu" "B.Cu")
		(net "P3V3_AUX")
	)
	(via
		(at 236.119162 -223.266)
		(size 0.508)
		(drill 0.254)
		(layers "F.Cu" "B.Cu")
		(net "P3V3_AUX")
	)
	(via
		(at 134.764018 -31.982156)
		(size 0.508)
		(drill 0.254)
		(layers "F.Cu" "B.Cu")
		(net "P3V3_AUX")
	)
	(via
		(at 274.576794 -428.116746)
		(size 0.508)
		(drill 0.254)
		(layers "F.Cu" "B.Cu")
		(net "P3V3_AUX")
	)
	(via
		(at 119.017796 -54.128416)
		(size 0.508)
		(drill 0.254)
		(layers "F.Cu" "B.Cu")
		(net "P3V3_AUX")
	)
	(via
		(at 62.914276 -96.144842)
		(size 0.508)
		(drill 0.254)
		(layers "F.Cu" "B.Cu")
		(net "P3V3_AUX")
	)
	(via
		(at 210.464654 -15.685008)
		(size 0.508)
		(drill 0.254)
		(layers "F.Cu" "B.Cu")
		(net "P3V3_AUX")
	)
	(via
		(at 156.971492 -105.548684)
		(size 0.508)
		(drill 0.254)
		(layers "F.Cu" "B.Cu")
		(net "P3V3_AUX")
	)
	(via
		(at 453.475344 -368.31651)
		(size 0.508)
		(drill 0.254)
		(layers "F.Cu" "B.Cu")
		(net "P3V3_AUX")
	)
	(via
		(at 436.856886 -28.629102)
		(size 0.508)
		(drill 0.254)
		(layers "F.Cu" "B.Cu")
		(net "P3V3_AUX")
	)
	(via
		(at 324.635876 -65.692782)
		(size 0.508)
		(drill 0.254)
		(layers "F.Cu" "B.Cu")
		(net "P3V3_AUX")
	)
	(via
		(at 430.022 -59.436)
		(size 0.508)
		(drill 0.254)
		(layers "F.Cu" "B.Cu")
		(net "P3V3_AUX")
	)
	(via
		(at 97.191068 -426.968666)
		(size 0.508)
		(drill 0.254)
		(layers "F.Cu" "B.Cu")
		(net "P3V3_AUX")
	)
	(via
		(at 168.496996 -123.01093)
		(size 0.508)
		(drill 0.254)
		(layers "F.Cu" "B.Cu")
		(net "P3V3_AUX")
	)
	(via
		(at 452.72579 -368.32413)
		(size 0.508)
		(drill 0.254)
		(layers "F.Cu" "B.Cu")
		(net "P3V3_AUX")
	)
	(via
		(at 193.899536 -70.924674)
		(size 0.508)
		(drill 0.254)
		(layers "F.Cu" "B.Cu")
		(net "P3V3_AUX")
	)
	(via
		(at 118.09095 -422.275)
		(size 0.508)
		(drill 0.254)
		(layers "F.Cu" "B.Cu")
		(net "P3V3_AUX")
	)
	(via
		(at 188.25464 -437.1721)
		(size 0.508)
		(drill 0.254)
		(layers "F.Cu" "B.Cu")
		(net "P3V3_AUX")
	)
	(via
		(at 62.578234 -196.186552)
		(size 0.508)
		(drill 0.254)
		(layers "F.Cu" "B.Cu")
		(net "P3V3_AUX")
	)
	(via
		(at 21.06803 -432.437794)
		(size 0.508)
		(drill 0.254)
		(layers "F.Cu" "B.Cu")
		(net "P3V3_AUX")
	)
	(via
		(at 330.617068 -136.473946)
		(size 0.508)
		(drill 0.254)
		(layers "F.Cu" "B.Cu")
		(net "P3V3_AUX")
	)
	(via
		(at 112.597946 -55.891684)
		(size 0.508)
		(drill 0.254)
		(layers "F.Cu" "B.Cu")
		(net "P3V3_AUX")
	)
	(via
		(at 118.745 -426.339)
		(size 0.508)
		(drill 0.254)
		(layers "F.Cu" "B.Cu")
		(net "P3V3_AUX")
	)
	(via
		(at 253.583186 -116.12245)
		(size 0.508)
		(drill 0.254)
		(layers "F.Cu" "B.Cu")
		(net "P3V3_AUX")
	)
	(via
		(at 46.688502 -433.172616)
		(size 0.508)
		(drill 0.254)
		(layers "F.Cu" "B.Cu")
		(net "P3V3_AUX")
	)
	(via
		(at 53.395118 -423.825162)
		(size 0.508)
		(drill 0.254)
		(layers "F.Cu" "B.Cu")
		(net "P3V3_AUX")
	)
	(via
		(at 162.433 -112.359948)
		(size 0.508)
		(drill 0.254)
		(layers "F.Cu" "B.Cu")
		(net "P3V3_AUX")
	)
	(via
		(at 199.921368 -124.632974)
		(size 0.508)
		(drill 0.254)
		(layers "F.Cu" "B.Cu")
		(net "P3V3_AUX")
	)
	(via
		(at 412.82239 -364.079536)
		(size 0.508)
		(drill 0.254)
		(layers "F.Cu" "B.Cu")
		(net "P3V3_AUX")
	)
	(via
		(at 69.469 -52.705)
		(size 0.508)
		(drill 0.254)
		(layers "F.Cu" "B.Cu")
		(net "P3V3_AUX")
	)
	(via
		(at 20.250404 -36.878514)
		(size 0.508)
		(drill 0.254)
		(layers "F.Cu" "B.Cu")
		(net "P3V3_AUX")
	)
	(via
		(at 453.109584 -68.994782)
		(size 0.508)
		(drill 0.254)
		(layers "F.Cu" "B.Cu")
		(net "P3V3_AUX")
	)
	(via
		(at 104.54894 -56.67756)
		(size 0.508)
		(drill 0.254)
		(layers "F.Cu" "B.Cu")
		(net "P3V3_AUX")
	)
	(via
		(at 402.917914 -77.113384)
		(size 0.508)
		(drill 0.254)
		(layers "F.Cu" "B.Cu")
		(net "P3V3_AUX")
	)
	(via
		(at 306.020216 -431.887122)
		(size 0.508)
		(drill 0.254)
		(layers "F.Cu" "B.Cu")
		(net "P3V3_AUX")
	)
	(via
		(at 191.111886 -107.862878)
		(size 0.4572)
		(drill 0.254)
		(layers "F.Cu" "B.Cu")
		(net "P3V3_AUX")
	)
	(via
		(at 170.970702 -438.724294)
		(size 0.508)
		(drill 0.254)
		(layers "F.Cu" "B.Cu")
		(net "P3V3_AUX")
	)
	(via
		(at 372.06682 -14.999716)
		(size 0.508)
		(drill 0.254)
		(layers "F.Cu" "B.Cu")
		(net "P3V3_AUX")
	)
	(via
		(at 28.537662 -418.239448)
		(size 0.508)
		(drill 0.254)
		(layers "F.Cu" "B.Cu")
		(net "P3V3_AUX")
	)
	(via
		(at 368.06378 -428.427388)
		(size 0.508)
		(drill 0.254)
		(layers "F.Cu" "B.Cu")
		(net "P3V3_AUX")
	)
	(via
		(at 310.411876 -65.692782)
		(size 0.508)
		(drill 0.254)
		(layers "F.Cu" "B.Cu")
		(net "P3V3_AUX")
	)
	(via
		(at 273.814794 -428.116746)
		(size 0.508)
		(drill 0.254)
		(layers "F.Cu" "B.Cu")
		(net "P3V3_AUX")
	)
	(via
		(at 445.013588 -67.765676)
		(size 0.508)
		(drill 0.254)
		(layers "F.Cu" "B.Cu")
		(net "P3V3_AUX")
	)
	(via
		(at 188.712094 -113.46307)
		(size 0.4572)
		(drill 0.254)
		(layers "F.Cu" "B.Cu")
		(net "P3V3_AUX")
	)
	(via
		(at 100.920296 -426.84573)
		(size 0.508)
		(drill 0.254)
		(layers "F.Cu" "B.Cu")
		(net "P3V3_AUX")
	)
	(via
		(at 338.683346 -24.913336)
		(size 0.508)
		(drill 0.254)
		(layers "F.Cu" "B.Cu")
		(net "P3V3_AUX")
	)
	(via
		(at 338.859876 -65.692782)
		(size 0.508)
		(drill 0.254)
		(layers "F.Cu" "B.Cu")
		(net "P3V3_AUX")
	)
	(via
		(at 240.919 -237.998)
		(size 0.508)
		(drill 0.254)
		(layers "F.Cu" "B.Cu")
		(net "P3V3_AUX")
	)
	(via
		(at 183.932322 -116.642642)
		(size 0.4572)
		(drill 0.254)
		(layers "F.Cu" "B.Cu")
		(net "P3V3_AUX")
	)
	(via
		(at 430.677066 -102.61219)
		(size 0.508)
		(drill 0.254)
		(layers "F.Cu" "B.Cu")
		(net "P3V3_AUX")
	)
	(via
		(at 221.785688 -75.05319)
		(size 0.508)
		(drill 0.254)
		(layers "F.Cu" "B.Cu")
		(net "P3V3_AUX")
	)
	(via
		(at 103.886 -427.609)
		(size 0.508)
		(drill 0.254)
		(layers "F.Cu" "B.Cu")
		(net "P3V3_AUX")
	)
	(via
		(at 188.22162 -438.633362)
		(size 0.508)
		(drill 0.254)
		(layers "F.Cu" "B.Cu")
		(net "P3V3_AUX")
	)
	(via
		(at 178.760374 -163.01847)
		(size 0.508)
		(drill 0.254)
		(layers "F.Cu" "B.Cu")
		(net "P3V3_AUX")
	)
	(via
		(at 100.342192 -30.779212)
		(size 0.508)
		(drill 0.254)
		(layers "F.Cu" "B.Cu")
		(net "P3V3_AUX")
	)
	(via
		(at 270.791178 -193.935096)
		(size 0.4826)
		(drill 0.254)
		(layers "F.Cu" "B.Cu")
		(net "P3V3_AUX")
	)
	(via
		(at 204.841094 -78.89494)
		(size 0.508)
		(drill 0.254)
		(layers "F.Cu" "B.Cu")
		(net "P3V3_AUX")
	)
	(via
		(at 178.33213 -115.842796)
		(size 0.4572)
		(drill 0.254)
		(layers "F.Cu" "B.Cu")
		(net "P3V3_AUX")
	)
	(via
		(at 20.860258 -428.589948)
		(size 0.508)
		(drill 0.254)
		(layers "F.Cu" "B.Cu")
		(net "P3V3_AUX")
	)
	(via
		(at 216.819734 -68.340478)
		(size 0.508)
		(drill 0.254)
		(layers "F.Cu" "B.Cu")
		(net "P3V3_AUX")
	)
	(via
		(at 455.534776 -45.233082)
		(size 0.508)
		(drill 0.254)
		(layers "F.Cu" "B.Cu")
		(net "P3V3_AUX")
	)
	(via
		(at 103.849424 -412.35249)
		(size 0.508)
		(drill 0.254)
		(layers "F.Cu" "B.Cu")
		(net "P3V3_AUX")
	)
	(via
		(at 196.088 -134.584948)
		(size 0.508)
		(drill 0.254)
		(layers "F.Cu" "B.Cu")
		(net "P3V3_AUX")
	)
	(via
		(at 138.987784 -50.611024)
		(size 0.508)
		(drill 0.254)
		(layers "F.Cu" "B.Cu")
		(net "P3V3_AUX")
	)
	(via
		(at 187.911994 -111.86287)
		(size 0.4572)
		(drill 0.254)
		(layers "F.Cu" "B.Cu")
		(net "P3V3_AUX")
	)
	(via
		(at 447.490088 -70.830186)
		(size 0.508)
		(drill 0.254)
		(layers "F.Cu" "B.Cu")
		(net "P3V3_AUX")
	)
	(via
		(at 282.575 -424.461178)
		(size 0.508)
		(drill 0.254)
		(layers "F.Cu" "B.Cu")
		(net "P3V3_AUX")
	)
	(via
		(at 211.899754 -115.716812)
		(size 0.508)
		(drill 0.254)
		(layers "F.Cu" "B.Cu")
		(net "P3V3_AUX")
	)
	(via
		(at 192.437766 -60.78093)
		(size 0.508)
		(drill 0.254)
		(layers "F.Cu" "B.Cu")
		(net "P3V3_AUX")
	)
	(via
		(at 22.85111 -193.93535)
		(size 0.4826)
		(drill 0.254)
		(layers "F.Cu" "B.Cu")
		(net "P3V3_AUX")
	)
	(via
		(at 351.03943 -432.825652)
		(size 0.508)
		(drill 0.254)
		(layers "F.Cu" "B.Cu")
		(net "P3V3_AUX")
	)
	(via
		(at 254.303784 -56.870092)
		(size 0.508)
		(drill 0.254)
		(layers "F.Cu" "B.Cu")
		(net "P3V3_AUX")
	)
	(via
		(at 121.703592 -80.137508)
		(size 0.508)
		(drill 0.254)
		(layers "F.Cu" "B.Cu")
		(net "P3V3_AUX")
	)
	(via
		(at 8.707374 -79.480664)
		(size 0.508)
		(drill 0.254)
		(layers "F.Cu" "B.Cu")
		(net "P3V3_AUX")
	)
	(via
		(at 105.537 -424.815)
		(size 0.508)
		(drill 0.254)
		(layers "F.Cu" "B.Cu")
		(net "P3V3_AUX")
	)
	(via
		(at 192.53962 -423.820082)
		(size 0.508)
		(drill 0.254)
		(layers "F.Cu" "B.Cu")
		(net "P3V3_AUX")
	)
	(via
		(at 463.771996 -107.936792)
		(size 0.508)
		(drill 0.254)
		(layers "F.Cu" "B.Cu")
		(net "P3V3_AUX")
	)
	(via
		(at 268.680692 -109.122972)
		(size 0.508)
		(drill 0.254)
		(layers "F.Cu" "B.Cu")
		(net "P3V3_AUX")
	)
	(via
		(at 104.82961 -65.57391)
		(size 0.508)
		(drill 0.254)
		(layers "F.Cu" "B.Cu")
		(net "P3V3_AUX")
	)
	(via
		(at 113.613946 -55.891684)
		(size 0.508)
		(drill 0.254)
		(layers "F.Cu" "B.Cu")
		(net "P3V3_AUX")
	)
	(via
		(at 326.667876 -65.692782)
		(size 0.508)
		(drill 0.254)
		(layers "F.Cu" "B.Cu")
		(net "P3V3_AUX")
	)
	(via
		(at 75.305412 -37.897562)
		(size 0.508)
		(drill 0.254)
		(layers "F.Cu" "B.Cu")
		(net "P3V3_AUX")
	)
	(via
		(at 210.377786 -127.260858)
		(size 0.508)
		(drill 0.254)
		(layers "F.Cu" "B.Cu")
		(net "P3V3_AUX")
	)
	(via
		(at 177.215038 -193.93535)
		(size 0.4826)
		(drill 0.254)
		(layers "F.Cu" "B.Cu")
		(net "P3V3_AUX")
	)
	(via
		(at 150.21179 -27.72791)
		(size 0.508)
		(drill 0.254)
		(layers "F.Cu" "B.Cu")
		(net "P3V3_AUX")
	)
	(via
		(at 130.498088 -30.78988)
		(size 0.508)
		(drill 0.254)
		(layers "F.Cu" "B.Cu")
		(net "P3V3_AUX")
	)
	(via
		(at 273.781774 -428.816008)
		(size 0.508)
		(drill 0.254)
		(layers "F.Cu" "B.Cu")
		(net "P3V3_AUX")
	)
	(via
		(at 8.784336 -332.166976)
		(size 0.508)
		(drill 0.254)
		(layers "F.Cu" "B.Cu")
		(net "P3V3_AUX")
	)
	(via
		(at 278.243792 -121.774204)
		(size 0.508)
		(drill 0.254)
		(layers "F.Cu" "B.Cu")
		(net "P3V3_AUX")
	)
	(via
		(at 178.430174 -12.275058)
		(size 0.508)
		(drill 0.254)
		(layers "F.Cu" "B.Cu")
		(net "P3V3_AUX")
	)
	(via
		(at 240.46942 -327.842626)
		(size 0.508)
		(drill 0.254)
		(layers "F.Cu" "B.Cu")
		(net "P3V3_AUX")
	)
	(via
		(at 107.90301 -55.282084)
		(size 0.508)
		(drill 0.254)
		(layers "F.Cu" "B.Cu")
		(net "P3V3_AUX")
	)
	(via
		(at 105.659936 -118.463568)
		(size 0.508)
		(drill 0.254)
		(layers "F.Cu" "B.Cu")
		(net "P3V3_AUX")
	)
	(via
		(at 148.20519 -33.15462)
		(size 0.508)
		(drill 0.254)
		(layers "F.Cu" "B.Cu")
		(net "P3V3_AUX")
	)
	(via
		(at 438.9882 -95.957898)
		(size 0.508)
		(drill 0.254)
		(layers "F.Cu" "B.Cu")
		(net "P3V3_AUX")
	)
	(via
		(at 418.599366 -433.986686)
		(size 0.508)
		(drill 0.254)
		(layers "F.Cu" "B.Cu")
		(net "P3V3_AUX")
	)
	(via
		(at 451.814184 -68.994782)
		(size 0.508)
		(drill 0.254)
		(layers "F.Cu" "B.Cu")
		(net "P3V3_AUX")
	)
	(via
		(at 98.1329 -35.30092)
		(size 0.508)
		(drill 0.254)
		(layers "F.Cu" "B.Cu")
		(net "P3V3_AUX")
	)
	(via
		(at 119.497602 -424.189652)
		(size 0.508)
		(drill 0.254)
		(layers "F.Cu" "B.Cu")
		(net "P3V3_AUX")
	)
	(via
		(at 463.314542 -143.549878)
		(size 0.508)
		(drill 0.254)
		(layers "F.Cu" "B.Cu")
		(net "P3V3_AUX")
	)
	(via
		(at 461.516476 -101.105208)
		(size 0.508)
		(drill 0.254)
		(layers "F.Cu" "B.Cu")
		(net "P3V3_AUX")
	)
	(via
		(at 259.44195 -144.427956)
		(size 0.508)
		(drill 0.254)
		(layers "F.Cu" "B.Cu")
		(net "P3V3_AUX")
	)
	(via
		(at 172.145452 -29.318712)
		(size 0.508)
		(drill 0.254)
		(layers "F.Cu" "B.Cu")
		(net "P3V3_AUX")
	)
	(via
		(at 276.33676 -114.83594)
		(size 0.508)
		(drill 0.254)
		(layers "F.Cu" "B.Cu")
		(net "P3V3_AUX")
	)
	(via
		(at 22.23008 -99.413314)
		(size 0.508)
		(drill 0.254)
		(layers "F.Cu" "B.Cu")
		(net "P3V3_AUX")
	)
	(via
		(at 448.963542 -67.730878)
		(size 0.508)
		(drill 0.254)
		(layers "F.Cu" "B.Cu")
		(net "P3V3_AUX")
	)
	(via
		(at 257.379724 -131.609084)
		(size 0.508)
		(drill 0.254)
		(layers "F.Cu" "B.Cu")
		(net "P3V3_AUX")
	)
	(via
		(at 91.088972 -56.674766)
		(size 0.508)
		(drill 0.254)
		(layers "F.Cu" "B.Cu")
		(net "P3V3_AUX")
	)
	(via
		(at 262.53186 -72.976994)
		(size 0.508)
		(drill 0.254)
		(layers "F.Cu" "B.Cu")
		(net "P3V3_AUX")
	)
	(via
		(at 226.566984 -292.025578)
		(size 0.508)
		(drill 0.254)
		(layers "F.Cu" "B.Cu")
		(net "P3V3_AUX")
	)
	(via
		(at 125.788928 -49.153064)
		(size 0.508)
		(drill 0.254)
		(layers "F.Cu" "B.Cu")
		(net "P3V3_AUX")
	)
	(via
		(at 284.457648 -383.512314)
		(size 0.508)
		(drill 0.254)
		(layers "F.Cu" "B.Cu")
		(net "P3V3_AUX")
	)
	(via
		(at 191.911986 -111.063024)
		(size 0.4572)
		(drill 0.254)
		(layers "F.Cu" "B.Cu")
		(net "P3V3_AUX")
	)
	(via
		(at 268.680692 -108.472986)
		(size 0.508)
		(drill 0.254)
		(layers "F.Cu" "B.Cu")
		(net "P3V3_AUX")
	)
	(via
		(at 28.036012 -425.275502)
		(size 0.508)
		(drill 0.254)
		(layers "F.Cu" "B.Cu")
		(net "P3V3_AUX")
	)
	(via
		(at 15.729458 -417.447984)
		(size 0.508)
		(drill 0.254)
		(layers "F.Cu" "B.Cu")
		(net "P3V3_AUX")
	)
	(via
		(at 445.966088 -71.592186)
		(size 0.508)
		(drill 0.254)
		(layers "F.Cu" "B.Cu")
		(net "P3V3_AUX")
	)
	(via
		(at 449.843652 -430.010824)
		(size 0.508)
		(drill 0.254)
		(layers "F.Cu" "B.Cu")
		(net "P3V3_AUX")
	)
	(via
		(at 425.54144 -437.198008)
		(size 0.508)
		(drill 0.254)
		(layers "F.Cu" "B.Cu")
		(net "P3V3_AUX")
	)
	(via
		(at 109.474 -416.687)
		(size 0.508)
		(drill 0.254)
		(layers "F.Cu" "B.Cu")
		(net "P3V3_AUX")
	)
	(via
		(at 186.312048 -114.262916)
		(size 0.4572)
		(drill 0.254)
		(layers "F.Cu" "B.Cu")
		(net "P3V3_AUX")
	)
	(via
		(at 170.636692 -432.953668)
		(size 0.508)
		(drill 0.254)
		(layers "F.Cu" "B.Cu")
		(net "P3V3_AUX")
	)
	(via
		(at 147.44319 -33.15462)
		(size 0.508)
		(drill 0.254)
		(layers "F.Cu" "B.Cu")
		(net "P3V3_AUX")
	)
	(via
		(at 340.715346 -24.913336)
		(size 0.508)
		(drill 0.254)
		(layers "F.Cu" "B.Cu")
		(net "P3V3_AUX")
	)
	(via
		(at 30.395164 -193.93535)
		(size 0.4826)
		(drill 0.254)
		(layers "F.Cu" "B.Cu")
		(net "P3V3_AUX")
	)
	(via
		(at 281.223974 -410.442918)
		(size 0.508)
		(drill 0.254)
		(layers "F.Cu" "B.Cu")
		(net "P3V3_AUX")
	)
	(via
		(at 306.77358 -433.542694)
		(size 0.508)
		(drill 0.254)
		(layers "F.Cu" "B.Cu")
		(net "P3V3_AUX")
	)
	(via
		(at 206.530956 -125.817376)
		(size 0.508)
		(drill 0.254)
		(layers "F.Cu" "B.Cu")
		(net "P3V3_AUX")
	)
	(via
		(at 121.539 -434.467)
		(size 0.508)
		(drill 0.254)
		(layers "F.Cu" "B.Cu")
		(net "P3V3_AUX")
	)
	(via
		(at 20.07997 -364.236)
		(size 0.508)
		(drill 0.254)
		(layers "F.Cu" "B.Cu")
		(net "P3V3_AUX")
	)
	(via
		(at 385.256278 -136.519158)
		(size 0.508)
		(drill 0.254)
		(layers "F.Cu" "B.Cu")
		(net "P3V3_AUX")
	)
	(via
		(at 53.027072 -193.93535)
		(size 0.4826)
		(drill 0.254)
		(layers "F.Cu" "B.Cu")
		(net "P3V3_AUX")
	)
	(via
		(at 298.634404 -428.428404)
		(size 0.508)
		(drill 0.254)
		(layers "F.Cu" "B.Cu")
		(net "P3V3_AUX")
	)
	(via
		(at 52.782978 -430.887886)
		(size 0.508)
		(drill 0.254)
		(layers "F.Cu" "B.Cu")
		(net "P3V3_AUX")
	)
	(via
		(at 148.59 -20.955)
		(size 0.508)
		(drill 0.254)
		(layers "F.Cu" "B.Cu")
		(net "P3V3_AUX")
	)
	(via
		(at 113.449862 -399.609056)
		(size 0.508)
		(drill 0.254)
		(layers "F.Cu" "B.Cu")
		(net "P3V3_AUX")
	)
	(via
		(at 452.710296 -108.059728)
		(size 0.508)
		(drill 0.254)
		(layers "F.Cu" "B.Cu")
		(net "P3V3_AUX")
	)
	(via
		(at 16.796258 -428.589948)
		(size 0.508)
		(drill 0.254)
		(layers "F.Cu" "B.Cu")
		(net "P3V3_AUX")
	)
	(via
		(at 43.66895 -436.367936)
		(size 0.508)
		(drill 0.254)
		(layers "F.Cu" "B.Cu")
		(net "P3V3_AUX")
	)
	(via
		(at 165.976046 -116.469668)
		(size 0.508)
		(drill 0.254)
		(layers "F.Cu" "B.Cu")
		(net "P3V3_AUX")
	)
	(via
		(at 18.405348 -68.128642)
		(size 0.508)
		(drill 0.254)
		(layers "F.Cu" "B.Cu")
		(net "P3V3_AUX")
	)
	(via
		(at 125.788928 -47.121064)
		(size 0.508)
		(drill 0.254)
		(layers "F.Cu" "B.Cu")
		(net "P3V3_AUX")
	)
	(via
		(at 189.24905 -423.08145)
		(size 0.508)
		(drill 0.254)
		(layers "F.Cu" "B.Cu")
		(net "P3V3_AUX")
	)
	(via
		(at 279.653492 -438.401714)
		(size 0.508)
		(drill 0.254)
		(layers "F.Cu" "B.Cu")
		(net "P3V3_AUX")
	)
	(via
		(at 64.734186 -95.348806)
		(size 0.508)
		(drill 0.254)
		(layers "F.Cu" "B.Cu")
		(net "P3V3_AUX")
	)
	(via
		(at 104.82961 -67.60591)
		(size 0.508)
		(drill 0.254)
		(layers "F.Cu" "B.Cu")
		(net "P3V3_AUX")
	)
	(via
		(at 258.53009 -73.973944)
		(size 0.508)
		(drill 0.254)
		(layers "F.Cu" "B.Cu")
		(net "P3V3_AUX")
	)
	(via
		(at 192.951608 -95.087948)
		(size 0.508)
		(drill 0.254)
		(layers "F.Cu" "B.Cu")
		(net "P3V3_AUX")
	)
	(via
		(at 334.795876 -65.692782)
		(size 0.508)
		(drill 0.254)
		(layers "F.Cu" "B.Cu")
		(net "P3V3_AUX")
	)
	(via
		(at 108.206794 -133.321552)
		(size 0.508)
		(drill 0.254)
		(layers "F.Cu" "B.Cu")
		(net "P3V3_AUX")
	)
	(via
		(at 148.035264 -58.088784)
		(size 0.508)
		(drill 0.254)
		(layers "F.Cu" "B.Cu")
		(net "P3V3_AUX")
	)
	(via
		(at 318.539876 -65.692782)
		(size 0.508)
		(drill 0.254)
		(layers "F.Cu" "B.Cu")
		(net "P3V3_AUX")
	)
	(via
		(at 453.493632 -369.15979)
		(size 0.508)
		(drill 0.254)
		(layers "F.Cu" "B.Cu")
		(net "P3V3_AUX")
	)
	(via
		(at 397.876268 -74.883264)
		(size 0.508)
		(drill 0.254)
		(layers "F.Cu" "B.Cu")
		(net "P3V3_AUX")
	)
	(via
		(at 451.010782 -67.733164)
		(size 0.508)
		(drill 0.254)
		(layers "F.Cu" "B.Cu")
		(net "P3V3_AUX")
	)
	(via
		(at 357.684832 -413.677354)
		(size 0.508)
		(drill 0.254)
		(layers "F.Cu" "B.Cu")
		(net "P3V3_AUX")
	)
	(via
		(at 183.932322 -115.842796)
		(size 0.4572)
		(drill 0.254)
		(layers "F.Cu" "B.Cu")
		(net "P3V3_AUX")
	)
	(via
		(at 296.2529 -369.375436)
		(size 0.508)
		(drill 0.254)
		(layers "F.Cu" "B.Cu")
		(net "P3V3_AUX")
	)
	(via
		(at 448.963542 -68.492878)
		(size 0.508)
		(drill 0.254)
		(layers "F.Cu" "B.Cu")
		(net "P3V3_AUX")
	)
	(via
		(at 70.71995 -58.65495)
		(size 0.508)
		(drill 0.254)
		(layers "F.Cu" "B.Cu")
		(net "P3V3_AUX")
	)
	(via
		(at 113.2332 -415.544)
		(size 0.508)
		(drill 0.254)
		(layers "F.Cu" "B.Cu")
		(net "P3V3_AUX")
	)
	(via
		(at 183.414416 -413.068262)
		(size 0.508)
		(drill 0.254)
		(layers "F.Cu" "B.Cu")
		(net "P3V3_AUX")
	)
	(via
		(at 75.64501 -147.417536)
		(size 0.508)
		(drill 0.254)
		(layers "F.Cu" "B.Cu")
		(net "P3V3_AUX")
	)
	(via
		(at 452.713598 -369.110514)
		(size 0.508)
		(drill 0.254)
		(layers "F.Cu" "B.Cu")
		(net "P3V3_AUX")
	)
	(via
		(at 124.929646 -15.26667)
		(size 0.508)
		(drill 0.254)
		(layers "F.Cu" "B.Cu")
		(net "P3V3_AUX")
	)
	(via
		(at 8.784336 -332.801976)
		(size 0.508)
		(drill 0.254)
		(layers "F.Cu" "B.Cu")
		(net "P3V3_AUX")
	)
	(via
		(at 116.51615 -133.21792)
		(size 0.508)
		(drill 0.254)
		(layers "F.Cu" "B.Cu")
		(net "P3V3_AUX")
	)
	(via
		(at 49.276 -437.019954)
		(size 0.508)
		(drill 0.254)
		(layers "F.Cu" "B.Cu")
		(net "P3V3_AUX")
	)
	(via
		(at 36.897818 -437.449214)
		(size 0.508)
		(drill 0.254)
		(layers "F.Cu" "B.Cu")
		(net "P3V3_AUX")
	)
	(via
		(at 104.82961 -63.79591)
		(size 0.508)
		(drill 0.254)
		(layers "F.Cu" "B.Cu")
		(net "P3V3_AUX")
	)
	(via
		(at 156.96819 -95.612458)
		(size 0.508)
		(drill 0.254)
		(layers "F.Cu" "B.Cu")
		(net "P3V3_AUX")
	)
	(via
		(at 332.25994 -16.995394)
		(size 0.508)
		(drill 0.254)
		(layers "F.Cu" "B.Cu")
		(net "P3V3_AUX")
	)
	(via
		(at 329.2348 -16.995394)
		(size 0.508)
		(drill 0.254)
		(layers "F.Cu" "B.Cu")
		(net "P3V3_AUX")
	)
	(via
		(at 444.36792 -436.412132)
		(size 0.508)
		(drill 0.254)
		(layers "F.Cu" "B.Cu")
		(net "P3V3_AUX")
	)
	(via
		(at 253.583186 -118.91645)
		(size 0.508)
		(drill 0.254)
		(layers "F.Cu" "B.Cu")
		(net "P3V3_AUX")
	)
	(via
		(at 162.359594 -110.200948)
		(size 0.508)
		(drill 0.254)
		(layers "F.Cu" "B.Cu")
		(net "P3V3_AUX")
	)
	(via
		(at 162.17646 -8.46836)
		(size 0.508)
		(drill 0.254)
		(layers "F.Cu" "B.Cu")
		(net "P3V3_AUX")
	)
	(via
		(at 209.285332 -237.77956)
		(size 0.508)
		(drill 0.254)
		(layers "F.Cu" "B.Cu")
		(net "P3V3_AUX")
	)
	(via
		(at 162.842194 -40.2082)
		(size 0.508)
		(drill 0.254)
		(layers "F.Cu" "B.Cu")
		(net "P3V3_AUX")
	)
	(via
		(at 161.46526 -117.206014)
		(size 0.508)
		(drill 0.254)
		(layers "F.Cu" "B.Cu")
		(net "P3V3_AUX")
	)
	(via
		(at 172.100494 -30.075886)
		(size 0.508)
		(drill 0.254)
		(layers "F.Cu" "B.Cu")
		(net "P3V3_AUX")
	)
	(via
		(at 437.962802 -424.80611)
		(size 0.508)
		(drill 0.254)
		(layers "F.Cu" "B.Cu")
		(net "P3V3_AUX")
	)
	(via
		(at 219.20454 -240.604548)
		(size 0.508)
		(drill 0.254)
		(layers "F.Cu" "B.Cu")
		(net "P3V3_AUX")
	)
	(via
		(at 184.732168 -111.86287)
		(size 0.4572)
		(drill 0.254)
		(layers "F.Cu" "B.Cu")
		(net "P3V3_AUX")
	)
	(via
		(at 254.927354 -110.090204)
		(size 0.508)
		(drill 0.254)
		(layers "F.Cu" "B.Cu")
		(net "P3V3_AUX")
	)
	(via
		(at 195.326 -92.456)
		(size 0.508)
		(drill 0.254)
		(layers "F.Cu" "B.Cu")
		(net "P3V3_AUX")
	)
	(via
		(at 464.20532 -38.565836)
		(size 0.508)
		(drill 0.254)
		(layers "F.Cu" "B.Cu")
		(net "P3V3_AUX")
	)
	(via
		(at 451.814184 -68.359782)
		(size 0.508)
		(drill 0.254)
		(layers "F.Cu" "B.Cu")
		(net "P3V3_AUX")
	)
	(via
		(at 187.111894 -111.86287)
		(size 0.4572)
		(drill 0.254)
		(layers "F.Cu" "B.Cu")
		(net "P3V3_AUX")
	)
	(via
		(at 268.19987 -125.104398)
		(size 0.508)
		(drill 0.254)
		(layers "F.Cu" "B.Cu")
		(net "P3V3_AUX")
	)
	(via
		(at 455.331068 -193.935096)
		(size 0.4826)
		(drill 0.254)
		(layers "F.Cu" "B.Cu")
		(net "P3V3_AUX")
	)
	(via
		(at 109.165136 -118.44401)
		(size 0.508)
		(drill 0.254)
		(layers "F.Cu" "B.Cu")
		(net "P3V3_AUX")
	)
	(via
		(at 115.315238 -42.2656)
		(size 0.508)
		(drill 0.254)
		(layers "F.Cu" "B.Cu")
		(net "P3V3_AUX")
	)
	(via
		(at 332.763876 -65.692782)
		(size 0.508)
		(drill 0.254)
		(layers "F.Cu" "B.Cu")
		(net "P3V3_AUX")
	)
	(via
		(at 300.96714 -193.935096)
		(size 0.4826)
		(drill 0.254)
		(layers "F.Cu" "B.Cu")
		(net "P3V3_AUX")
	)
	(via
		(at 219.96527 -239.154716)
		(size 0.508)
		(drill 0.254)
		(layers "F.Cu" "B.Cu")
		(net "P3V3_AUX")
	)
	(via
		(at 161.83864 -102.984046)
		(size 0.508)
		(drill 0.254)
		(layers "F.Cu" "B.Cu")
		(net "P3V3_AUX")
	)
	(via
		(at 93.134434 -75.466956)
		(size 0.508)
		(drill 0.254)
		(layers "F.Cu" "B.Cu")
		(net "P3V3_AUX")
	)
	(via
		(at 274.565364 -429.59528)
		(size 0.508)
		(drill 0.254)
		(layers "F.Cu" "B.Cu")
		(net "P3V3_AUX")
	)
	(via
		(at 213.197694 -29.174948)
		(size 0.508)
		(drill 0.254)
		(layers "F.Cu" "B.Cu")
		(net "P3V3_AUX")
	)
	(via
		(at 10.147808 -140.10767)
		(size 0.508)
		(drill 0.254)
		(layers "F.Cu" "B.Cu")
		(net "P3V3_AUX")
	)
	(via
		(at 237.041436 -290.844732)
		(size 0.508)
		(drill 0.254)
		(layers "F.Cu" "B.Cu")
		(net "P3V3_AUX")
	)
	(via
		(at 420.877238 -440.412886)
		(size 0.508)
		(drill 0.254)
		(layers "F.Cu" "B.Cu")
		(net "P3V3_AUX")
	)
	(via
		(at 32.347662 -430.799748)
		(size 0.508)
		(drill 0.254)
		(layers "F.Cu" "B.Cu")
		(net "P3V3_AUX")
	)
	(via
		(at 230.385874 -370.136674)
		(size 0.508)
		(drill 0.254)
		(layers "F.Cu" "B.Cu")
		(net "P3V3_AUX")
	)
	(via
		(at 459.129384 -67.089782)
		(size 0.508)
		(drill 0.254)
		(layers "F.Cu" "B.Cu")
		(net "P3V3_AUX")
	)
	(via
		(at 193.929 -99.278948)
		(size 0.508)
		(drill 0.254)
		(layers "F.Cu" "B.Cu")
		(net "P3V3_AUX")
	)
	(via
		(at 360.583988 -410.464)
		(size 0.508)
		(drill 0.254)
		(layers "F.Cu" "B.Cu")
		(net "P3V3_AUX")
	)
	(via
		(at 193.919602 -71.58736)
		(size 0.508)
		(drill 0.254)
		(layers "F.Cu" "B.Cu")
		(net "P3V3_AUX")
	)
	(via
		(at 450.577966 -420.358824)
		(size 0.508)
		(drill 0.254)
		(layers "F.Cu" "B.Cu")
		(net "P3V3_AUX")
	)
	(via
		(at 276.342602 -111.91367)
		(size 0.508)
		(drill 0.254)
		(layers "F.Cu" "B.Cu")
		(net "P3V3_AUX")
	)
	(via
		(at 272.458942 -108.912914)
		(size 0.508)
		(drill 0.254)
		(layers "F.Cu" "B.Cu")
		(net "P3V3_AUX")
	)
	(via
		(at 181.297834 -420.351458)
		(size 0.508)
		(drill 0.254)
		(layers "F.Cu" "B.Cu")
		(net "P3V3_AUX")
	)
	(via
		(at 445.204088 -70.830186)
		(size 0.508)
		(drill 0.254)
		(layers "F.Cu" "B.Cu")
		(net "P3V3_AUX")
	)
	(via
		(at 211.414868 -323.755004)
		(size 0.508)
		(drill 0.254)
		(layers "F.Cu" "B.Cu")
		(net "P3V3_AUX")
	)
	(via
		(at 432.69916 -193.935096)
		(size 0.4826)
		(drill 0.254)
		(layers "F.Cu" "B.Cu")
		(net "P3V3_AUX")
	)
	(via
		(at 309.051452 -439.676794)
		(size 0.508)
		(drill 0.254)
		(layers "F.Cu" "B.Cu")
		(net "P3V3_AUX")
	)
	(via
		(at 100.343462 -80.80375)
		(size 0.508)
		(drill 0.254)
		(layers "F.Cu" "B.Cu")
		(net "P3V3_AUX")
	)
	(via
		(at 165.71595 -98.024696)
		(size 0.508)
		(drill 0.254)
		(layers "F.Cu" "B.Cu")
		(net "P3V3_AUX")
	)
	(via
		(at 36.18611 -422.273222)
		(size 0.508)
		(drill 0.254)
		(layers "F.Cu" "B.Cu")
		(net "P3V3_AUX")
	)
	(via
		(at 138.987784 -48.325024)
		(size 0.508)
		(drill 0.254)
		(layers "F.Cu" "B.Cu")
		(net "P3V3_AUX")
	)
	(via
		(at 139.749784 -48.325024)
		(size 0.508)
		(drill 0.254)
		(layers "F.Cu" "B.Cu")
		(net "P3V3_AUX")
	)
	(via
		(at 180.412136 -43.135804)
		(size 0.508)
		(drill 0.254)
		(layers "F.Cu" "B.Cu")
		(net "P3V3_AUX")
	)
	(via
		(at 284.457648 -384.211576)
		(size 0.508)
		(drill 0.254)
		(layers "F.Cu" "B.Cu")
		(net "P3V3_AUX")
	)
	(via
		(at 163.02355 -439.551064)
		(size 0.508)
		(drill 0.254)
		(layers "F.Cu" "B.Cu")
		(net "P3V3_AUX")
	)
	(via
		(at 364.213394 -418.855398)
		(size 0.508)
		(drill 0.254)
		(layers "F.Cu" "B.Cu")
		(net "P3V3_AUX")
	)
	(via
		(at 181.532276 -116.642642)
		(size 0.4572)
		(drill 0.254)
		(layers "F.Cu" "B.Cu")
		(net "P3V3_AUX")
	)
	(via
		(at 461.320896 -104.249728)
		(size 0.508)
		(drill 0.254)
		(layers "F.Cu" "B.Cu")
		(net "P3V3_AUX")
	)
	(via
		(at 440.243214 -193.935096)
		(size 0.4826)
		(drill 0.254)
		(layers "F.Cu" "B.Cu")
		(net "P3V3_AUX")
	)
	(via
		(at 269.911068 -112.994186)
		(size 0.508)
		(drill 0.254)
		(layers "F.Cu" "B.Cu")
		(net "P3V3_AUX")
	)
	(via
		(at 171.081192 -424.0657)
		(size 0.508)
		(drill 0.254)
		(layers "F.Cu" "B.Cu")
		(net "P3V3_AUX")
	)
	(via
		(at 147.82419 -95.612458)
		(size 0.508)
		(drill 0.254)
		(layers "F.Cu" "B.Cu")
		(net "P3V3_AUX")
	)
	(via
		(at 290.744402 -125.049026)
		(size 0.508)
		(drill 0.254)
		(layers "F.Cu" "B.Cu")
		(net "P3V3_AUX")
	)
	(via
		(at 277.61692 -431.591466)
		(size 0.508)
		(drill 0.254)
		(layers "F.Cu" "B.Cu")
		(net "P3V3_AUX")
	)
	(via
		(at 241.149378 -288.939732)
		(size 0.508)
		(drill 0.254)
		(layers "F.Cu" "B.Cu")
		(net "P3V3_AUX")
	)
	(via
		(at 42.33418 -127.7366)
		(size 0.508)
		(drill 0.254)
		(layers "F.Cu" "B.Cu")
		(net "P3V3_AUX")
	)
	(via
		(at 203.825348 -98.490024)
		(size 0.508)
		(drill 0.254)
		(layers "F.Cu" "B.Cu")
		(net "P3V3_AUX")
	)
	(via
		(at 117.475 -431.038)
		(size 0.508)
		(drill 0.254)
		(layers "F.Cu" "B.Cu")
		(net "P3V3_AUX")
	)
	(via
		(at 22.23008 -100.54971)
		(size 0.508)
		(drill 0.254)
		(layers "F.Cu" "B.Cu")
		(net "P3V3_AUX")
	)
	(via
		(at 24.33066 -324.615556)
		(size 0.508)
		(drill 0.254)
		(layers "F.Cu" "B.Cu")
		(net "P3V3_AUX")
	)
	(via
		(at 45.746162 -423.905934)
		(size 0.508)
		(drill 0.254)
		(layers "F.Cu" "B.Cu")
		(net "P3V3_AUX")
	)
	(via
		(at 267.33627 -103.270304)
		(size 0.508)
		(drill 0.254)
		(layers "F.Cu" "B.Cu")
		(net "P3V3_AUX")
	)
	(via
		(at 278.335232 -193.935096)
		(size 0.4826)
		(drill 0.254)
		(layers "F.Cu" "B.Cu")
		(net "P3V3_AUX")
	)
	(via
		(at 293.243 -425.958)
		(size 0.508)
		(drill 0.254)
		(layers "F.Cu" "B.Cu")
		(net "P3V3_AUX")
	)
	(via
		(at 187.111894 -113.46307)
		(size 0.4572)
		(drill 0.254)
		(layers "F.Cu" "B.Cu")
		(net "P3V3_AUX")
	)
	(via
		(at 166.228014 -114.202972)
		(size 0.508)
		(drill 0.254)
		(layers "F.Cu" "B.Cu")
		(net "P3V3_AUX")
	)
	(via
		(at 284.397704 -13.749528)
		(size 0.508)
		(drill 0.254)
		(layers "F.Cu" "B.Cu")
		(net "P3V3_AUX")
	)
	(via
		(at 166.116 -118.319296)
		(size 0.508)
		(drill 0.254)
		(layers "F.Cu" "B.Cu")
		(net "P3V3_AUX")
	)
	(via
		(at 461.193896 -107.678728)
		(size 0.508)
		(drill 0.254)
		(layers "F.Cu" "B.Cu")
		(net "P3V3_AUX")
	)
	(via
		(at 166.119556 -120.360948)
		(size 0.508)
		(drill 0.254)
		(layers "F.Cu" "B.Cu")
		(net "P3V3_AUX")
	)
	(via
		(at 240.46942 -328.477626)
		(size 0.508)
		(drill 0.254)
		(layers "F.Cu" "B.Cu")
		(net "P3V3_AUX")
	)
	(via
		(at 73.66 -56.53405)
		(size 0.508)
		(drill 0.254)
		(layers "F.Cu" "B.Cu")
		(net "P3V3_AUX")
	)
	(via
		(at 73.505822 -126.73584)
		(size 0.508)
		(drill 0.254)
		(layers "F.Cu" "B.Cu")
		(net "P3V3_AUX")
	)
	(via
		(at 306.232052 -440.122564)
		(size 0.508)
		(drill 0.254)
		(layers "F.Cu" "B.Cu")
		(net "P3V3_AUX")
	)
	(via
		(at 371.921278 -142.488158)
		(size 0.508)
		(drill 0.254)
		(layers "F.Cu" "B.Cu")
		(net "P3V3_AUX")
	)
	(via
		(at 37.938964 -193.93535)
		(size 0.4826)
		(drill 0.254)
		(layers "F.Cu" "B.Cu")
		(net "P3V3_AUX")
	)
	(via
		(at 8.707374 -78.180692)
		(size 0.508)
		(drill 0.254)
		(layers "F.Cu" "B.Cu")
		(net "P3V3_AUX")
	)
	(via
		(at 205.121256 -102.56647)
		(size 0.508)
		(drill 0.254)
		(layers "F.Cu" "B.Cu")
		(net "P3V3_AUX")
	)
	(via
		(at 112.85474 -61.81598)
		(size 0.508)
		(drill 0.254)
		(layers "F.Cu" "B.Cu")
		(net "P3V3_AUX")
	)
	(via
		(at 147.208494 -18.56486)
		(size 0.508)
		(drill 0.254)
		(layers "F.Cu" "B.Cu")
		(net "P3V3_AUX")
	)
	(via
		(at 164.973 -94.869)
		(size 0.508)
		(drill 0.254)
		(layers "F.Cu" "B.Cu")
		(net "P3V3_AUX")
	)
	(via
		(at 369.455446 -27.290522)
		(size 0.508)
		(drill 0.254)
		(layers "F.Cu" "B.Cu")
		(net "P3V3_AUX")
	)
	(via
		(at 102.528878 -138.91641)
		(size 0.508)
		(drill 0.254)
		(layers "F.Cu" "B.Cu")
		(net "P3V3_AUX")
	)
	(via
		(at 302.109378 -436.249572)
		(size 0.508)
		(drill 0.254)
		(layers "F.Cu" "B.Cu")
		(net "P3V3_AUX")
	)
	(via
		(at 50.760122 -434.298598)
		(size 0.508)
		(drill 0.254)
		(layers "F.Cu" "B.Cu")
		(net "P3V3_AUX")
	)
	(via
		(at 183.932322 -114.262916)
		(size 0.4572)
		(drill 0.254)
		(layers "F.Cu" "B.Cu")
		(net "P3V3_AUX")
	)
	(via
		(at 187.45962 -438.633362)
		(size 0.508)
		(drill 0.254)
		(layers "F.Cu" "B.Cu")
		(net "P3V3_AUX")
	)
	(via
		(at 444.59652 -433.696872)
		(size 0.508)
		(drill 0.254)
		(layers "F.Cu" "B.Cu")
		(net "P3V3_AUX")
	)
	(via
		(at 315.576966 -110.55477)
		(size 0.508)
		(drill 0.254)
		(layers "F.Cu" "B.Cu")
		(net "P3V3_AUX")
	)
	(via
		(at 219.99956 -239.905286)
		(size 0.508)
		(drill 0.254)
		(layers "F.Cu" "B.Cu")
		(net "P3V3_AUX")
	)
	(via
		(at 452.710296 -102.598728)
		(size 0.508)
		(drill 0.254)
		(layers "F.Cu" "B.Cu")
		(net "P3V3_AUX")
	)
	(via
		(at 190.886334 -420.626032)
		(size 0.508)
		(drill 0.254)
		(layers "F.Cu" "B.Cu")
		(net "P3V3_AUX")
	)
	(via
		(at 181.532276 -113.46307)
		(size 0.4572)
		(drill 0.254)
		(layers "F.Cu" "B.Cu")
		(net "P3V3_AUX")
	)
	(via
		(at 330.731876 -65.692782)
		(size 0.508)
		(drill 0.254)
		(layers "F.Cu" "B.Cu")
		(net "P3V3_AUX")
	)
	(via
		(at 9.666732 -404.21687)
		(size 0.508)
		(drill 0.254)
		(layers "F.Cu" "B.Cu")
		(net "P3V3_AUX")
	)
	(via
		(at 302.123348 -431.884836)
		(size 0.508)
		(drill 0.254)
		(layers "F.Cu" "B.Cu")
		(net "P3V3_AUX")
	)
	(via
		(at 305.485038 -424.956986)
		(size 0.508)
		(drill 0.254)
		(layers "F.Cu" "B.Cu")
		(net "P3V3_AUX")
	)
	(via
		(at 158.032196 -111.48695)
		(size 0.508)
		(drill 0.254)
		(layers "F.Cu" "B.Cu")
		(net "P3V3_AUX")
	)
	(via
		(at 367.050066 -428.416212)
		(size 0.508)
		(drill 0.254)
		(layers "F.Cu" "B.Cu")
		(net "P3V3_AUX")
	)
	(via
		(at 187.45962 -437.871362)
		(size 0.508)
		(drill 0.254)
		(layers "F.Cu" "B.Cu")
		(net "P3V3_AUX")
	)
	(via
		(at 96.523048 -60.86221)
		(size 0.508)
		(drill 0.254)
		(layers "F.Cu" "B.Cu")
		(net "P3V3_AUX")
	)
	(via
		(at 429.755808 -431.532538)
		(size 0.508)
		(drill 0.254)
		(layers "F.Cu" "B.Cu")
		(net "P3V3_AUX")
	)
	(via
		(at 192.454276 -25.565862)
		(size 0.508)
		(drill 0.254)
		(layers "F.Cu" "B.Cu")
		(net "P3V3_AUX")
	)
	(via
		(at 115.677188 -62.002162)
		(size 0.508)
		(drill 0.254)
		(layers "F.Cu" "B.Cu")
		(net "P3V3_AUX")
	)
	(via
		(at 451.814184 -67.089782)
		(size 0.508)
		(drill 0.254)
		(layers "F.Cu" "B.Cu")
		(net "P3V3_AUX")
	)
	(via
		(at 451.010782 -69.003164)
		(size 0.508)
		(drill 0.254)
		(layers "F.Cu" "B.Cu")
		(net "P3V3_AUX")
	)
	(via
		(at 121.539 -440.309)
		(size 0.508)
		(drill 0.254)
		(layers "F.Cu" "B.Cu")
		(net "P3V3_AUX")
	)
	(via
		(at 16.368268 -129.709418)
		(size 0.508)
		(drill 0.254)
		(layers "F.Cu" "B.Cu")
		(net "P3V3_AUX")
	)
	(via
		(at 285.879032 -193.935096)
		(size 0.4826)
		(drill 0.254)
		(layers "F.Cu" "B.Cu")
		(net "P3V3_AUX")
	)
	(via
		(at 163.111434 -79.06512)
		(size 0.508)
		(drill 0.254)
		(layers "F.Cu" "B.Cu")
		(net "P3V3_AUX")
	)
	(via
		(at 301.819818 -145.238978)
		(size 0.508)
		(drill 0.254)
		(layers "F.Cu" "B.Cu")
		(net "P3V3_AUX")
	)
	(via
		(at 298.495974 -117.942614)
		(size 0.508)
		(drill 0.254)
		(layers "F.Cu" "B.Cu")
		(net "P3V3_AUX")
	)
	(via
		(at 196.387974 -105.460038)
		(size 0.508)
		(drill 0.254)
		(layers "F.Cu" "B.Cu")
		(net "P3V3_AUX")
	)
	(via
		(at 219.20454 -241.366548)
		(size 0.508)
		(drill 0.254)
		(layers "F.Cu" "B.Cu")
		(net "P3V3_AUX")
	)
	(via
		(at 42.35704 -128.74752)
		(size 0.508)
		(drill 0.254)
		(layers "F.Cu" "B.Cu")
		(net "P3V3_AUX")
	)
	(via
		(at 454.203816 -19.839432)
		(size 0.508)
		(drill 0.254)
		(layers "F.Cu" "B.Cu")
		(net "P3V3_AUX")
	)
	(via
		(at 96.928178 -403.959822)
		(size 0.508)
		(drill 0.254)
		(layers "F.Cu" "B.Cu")
		(net "P3V3_AUX")
	)
	(via
		(at 104.026208 -414.935924)
		(size 0.508)
		(drill 0.254)
		(layers "F.Cu" "B.Cu")
		(net "P3V3_AUX")
	)
	(via
		(at 446.728088 -70.830186)
		(size 0.508)
		(drill 0.254)
		(layers "F.Cu" "B.Cu")
		(net "P3V3_AUX")
	)
	(via
		(at 427.97095 -34.737548)
		(size 0.508)
		(drill 0.254)
		(layers "F.Cu" "B.Cu")
		(net "P3V3_AUX")
	)
	(via
		(at 302.416464 -424.342814)
		(size 0.508)
		(drill 0.254)
		(layers "F.Cu" "B.Cu")
		(net "P3V3_AUX")
	)
	(via
		(at 369.739418 -31.936182)
		(size 0.508)
		(drill 0.254)
		(layers "F.Cu" "B.Cu")
		(net "P3V3_AUX")
	)
	(via
		(at 104.267 -26.640282)
		(size 0.508)
		(drill 0.254)
		(layers "F.Cu" "B.Cu")
		(net "P3V3_AUX")
	)
	(via
		(at 97.05721 -422.03243)
		(size 0.508)
		(drill 0.254)
		(layers "F.Cu" "B.Cu")
		(net "P3V3_AUX")
	)
	(via
		(at 209.296762 -236.301026)
		(size 0.508)
		(drill 0.254)
		(layers "F.Cu" "B.Cu")
		(net "P3V3_AUX")
	)
	(via
		(at 446.537588 -68.527676)
		(size 0.508)
		(drill 0.254)
		(layers "F.Cu" "B.Cu")
		(net "P3V3_AUX")
	)
	(via
		(at 310.411876 -79.810864)
		(size 0.508)
		(drill 0.254)
		(layers "F.Cu" "B.Cu")
		(net "P3V3_AUX")
	)
	(via
		(at 84.922106 -41.29532)
		(size 0.508)
		(drill 0.254)
		(layers "F.Cu" "B.Cu")
		(net "P3V3_AUX")
	)
	(via
		(at 365.766858 -423.65803)
		(size 0.508)
		(drill 0.254)
		(layers "F.Cu" "B.Cu")
		(net "P3V3_AUX")
	)
	(via
		(at 454.203816 -20.913852)
		(size 0.508)
		(drill 0.254)
		(layers "F.Cu" "B.Cu")
		(net "P3V3_AUX")
	)
	(via
		(at 156.96819 -98.355658)
		(size 0.508)
		(drill 0.254)
		(layers "F.Cu" "B.Cu")
		(net "P3V3_AUX")
	)
	(via
		(at 29.214064 -76.271374)
		(size 0.508)
		(drill 0.254)
		(layers "F.Cu" "B.Cu")
		(net "P3V3_AUX")
	)
	(via
		(at 38.816788 -169.037)
		(size 0.508)
		(drill 0.254)
		(layers "F.Cu" "B.Cu")
		(net "P3V3_AUX")
	)
	(via
		(at 456.609196 -69.722746)
		(size 0.508)
		(drill 0.254)
		(layers "F.Cu" "B.Cu")
		(net "P3V3_AUX")
	)
	(via
		(at 298.495974 -122.349514)
		(size 0.508)
		(drill 0.254)
		(layers "F.Cu" "B.Cu")
		(net "P3V3_AUX")
	)
	(via
		(at 433.451 -105.628948)
		(size 0.508)
		(drill 0.254)
		(layers "F.Cu" "B.Cu")
		(net "P3V3_AUX")
	)
	(via
		(at 429.87341 -422.58996)
		(size 0.508)
		(drill 0.254)
		(layers "F.Cu" "B.Cu")
		(net "P3V3_AUX")
	)
	(via
		(at 303.397412 -431.783744)
		(size 0.508)
		(drill 0.254)
		(layers "F.Cu" "B.Cu")
		(net "P3V3_AUX")
	)
	(via
		(at 18.231866 -41.959276)
		(size 0.508)
		(drill 0.254)
		(layers "F.Cu" "B.Cu")
		(net "P3V3_AUX")
	)
	(via
		(at 45.483018 -193.93535)
		(size 0.4826)
		(drill 0.254)
		(layers "F.Cu" "B.Cu")
		(net "P3V3_AUX")
	)
	(via
		(at 293.423086 -193.935096)
		(size 0.4826)
		(drill 0.254)
		(layers "F.Cu" "B.Cu")
		(net "P3V3_AUX")
	)
	(via
		(at 131.894072 -42.526712)
		(size 0.508)
		(drill 0.254)
		(layers "F.Cu" "B.Cu")
		(net "P3V3_AUX")
	)
	(via
		(at 437.365648 -433.09921)
		(size 0.508)
		(drill 0.254)
		(layers "F.Cu" "B.Cu")
		(net "P3V3_AUX")
	)
	(via
		(at 117.66296 -62.22492)
		(size 0.508)
		(drill 0.254)
		(layers "F.Cu" "B.Cu")
		(net "P3V3_AUX")
	)
	(via
		(at 283.696918 -384.973576)
		(size 0.508)
		(drill 0.254)
		(layers "F.Cu" "B.Cu")
		(net "P3V3_AUX")
	)
	(via
		(at 233.495088 -250.642628)
		(size 0.508)
		(drill 0.254)
		(layers "F.Cu" "B.Cu")
		(net "P3V3_AUX")
	)
	(via
		(at 211.862924 -111.576866)
		(size 0.508)
		(drill 0.254)
		(layers "F.Cu" "B.Cu")
		(net "P3V3_AUX")
	)
	(via
		(at 253.583186 -120.31345)
		(size 0.508)
		(drill 0.254)
		(layers "F.Cu" "B.Cu")
		(net "P3V3_AUX")
	)
	(via
		(at 358.766618 -406.967436)
		(size 0.508)
		(drill 0.254)
		(layers "F.Cu" "B.Cu")
		(net "P3V3_AUX")
	)
	(via
		(at 272.15338 -120.78335)
		(size 0.508)
		(drill 0.254)
		(layers "F.Cu" "B.Cu")
		(net "P3V3_AUX")
	)
	(via
		(at 8.363458 -423.821098)
		(size 0.508)
		(drill 0.254)
		(layers "F.Cu" "B.Cu")
		(net "P3V3_AUX")
	)
	(via
		(at 87.402924 -56.555386)
		(size 0.508)
		(drill 0.254)
		(layers "F.Cu" "B.Cu")
		(net "P3V3_AUX")
	)
	(via
		(at 320.571876 -65.692782)
		(size 0.508)
		(drill 0.254)
		(layers "F.Cu" "B.Cu")
		(net "P3V3_AUX")
	)
	(via
		(at 169.686732 -436.903368)
		(size 0.508)
		(drill 0.254)
		(layers "F.Cu" "B.Cu")
		(net "P3V3_AUX")
	)
	(via
		(at 286.004 -424.794426)
		(size 0.508)
		(drill 0.254)
		(layers "F.Cu" "B.Cu")
		(net "P3V3_AUX")
	)
	(via
		(at 186.312048 -111.86287)
		(size 0.4572)
		(drill 0.254)
		(layers "F.Cu" "B.Cu")
		(net "P3V3_AUX")
	)
	(via
		(at 160.29305 -109.191552)
		(size 0.508)
		(drill 0.254)
		(layers "F.Cu" "B.Cu")
		(net "P3V3_AUX")
	)
	(via
		(at 283.696918 -384.211576)
		(size 0.508)
		(drill 0.254)
		(layers "F.Cu" "B.Cu")
		(net "P3V3_AUX")
	)
	(via
		(at 182.320692 -408.26309)
		(size 0.508)
		(drill 0.254)
		(layers "F.Cu" "B.Cu")
		(net "P3V3_AUX")
	)
	(via
		(at 97.63125 -37.43071)
		(size 0.508)
		(drill 0.254)
		(layers "F.Cu" "B.Cu")
		(net "P3V3_AUX")
	)
	(via
		(at 298.495974 -112.354614)
		(size 0.508)
		(drill 0.254)
		(layers "F.Cu" "B.Cu")
		(net "P3V3_AUX")
	)
	(via
		(at 21.547582 -409.421584)
		(size 0.508)
		(drill 0.254)
		(layers "F.Cu" "B.Cu")
		(net "P3V3_AUX")
	)
	(via
		(at 154.398472 -65.420748)
		(size 0.508)
		(drill 0.254)
		(layers "F.Cu" "B.Cu")
		(net "P3V3_AUX")
	)
	(via
		(at 195.58 -96.719898)
		(size 0.508)
		(drill 0.254)
		(layers "F.Cu" "B.Cu")
		(net "P3V3_AUX")
	)
	(via
		(at 167.111934 -7.839456)
		(size 0.508)
		(drill 0.254)
		(layers "F.Cu" "B.Cu")
		(net "P3V3_AUX")
	)
	(via
		(at 302.190658 -41.906698)
		(size 0.508)
		(drill 0.254)
		(layers "F.Cu" "B.Cu")
		(net "P3V3_AUX")
	)
	(via
		(at 454.831196 -69.722746)
		(size 0.508)
		(drill 0.254)
		(layers "F.Cu" "B.Cu")
		(net "P3V3_AUX")
	)
	(via
		(at 368.427 -410.083)
		(size 0.508)
		(drill 0.254)
		(layers "F.Cu" "B.Cu")
		(net "P3V3_AUX")
	)
	(via
		(at 224.786444 -50.502566)
		(size 0.508)
		(drill 0.254)
		(layers "F.Cu" "B.Cu")
		(net "P3V3_AUX")
	)
	(via
		(at 319.1764 -364.363)
		(size 0.508)
		(drill 0.254)
		(layers "F.Cu" "B.Cu")
		(net "P3V3_AUX")
	)
	(via
		(at 167.256714 -428.99711)
		(size 0.508)
		(drill 0.254)
		(layers "F.Cu" "B.Cu")
		(net "P3V3_AUX")
	)
	(via
		(at 167.654732 -418.817806)
		(size 0.508)
		(drill 0.254)
		(layers "F.Cu" "B.Cu")
		(net "P3V3_AUX")
	)
	(via
		(at 451.010782 -68.368164)
		(size 0.508)
		(drill 0.254)
		(layers "F.Cu" "B.Cu")
		(net "P3V3_AUX")
	)
	(via
		(at 253.89332 -39.34333)
		(size 0.508)
		(drill 0.254)
		(layers "F.Cu" "B.Cu")
		(net "P3V3_AUX")
	)
	(via
		(at 39.459662 -428.712122)
		(size 0.508)
		(drill 0.254)
		(layers "F.Cu" "B.Cu")
		(net "P3V3_AUX")
	)
	(via
		(at 321.367658 -115.410488)
		(size 0.508)
		(drill 0.254)
		(layers "F.Cu" "B.Cu")
		(net "P3V3_AUX")
	)
	(via
		(at 464.076542 -143.549878)
		(size 0.508)
		(drill 0.254)
		(layers "F.Cu" "B.Cu")
		(net "P3V3_AUX")
	)
	(via
		(at 439.703718 -435.67731)
		(size 0.508)
		(drill 0.254)
		(layers "F.Cu" "B.Cu")
		(net "P3V3_AUX")
	)
	(via
		(at 149.492716 -55.188358)
		(size 0.508)
		(drill 0.254)
		(layers "F.Cu" "B.Cu")
		(net "P3V3_AUX")
	)
	(via
		(at 82.070702 -19.543014)
		(size 0.508)
		(drill 0.254)
		(layers "F.Cu" "B.Cu")
		(net "P3V3_AUX")
	)
	(via
		(at 53.551582 -421.860218)
		(size 0.508)
		(drill 0.254)
		(layers "F.Cu" "B.Cu")
		(net "P3V3_AUX")
	)
	(via
		(at 188.22162 -437.871362)
		(size 0.508)
		(drill 0.254)
		(layers "F.Cu" "B.Cu")
		(net "P3V3_AUX")
	)
	(via
		(at 117.330474 -54.026562)
		(size 0.508)
		(drill 0.254)
		(layers "F.Cu" "B.Cu")
		(net "P3V3_AUX")
	)
	(via
		(at 93.769434 -75.466956)
		(size 0.508)
		(drill 0.254)
		(layers "F.Cu" "B.Cu")
		(net "P3V3_AUX")
	)
	(via
		(at 433.451 -104.993948)
		(size 0.508)
		(drill 0.254)
		(layers "F.Cu" "B.Cu")
		(net "P3V3_AUX")
	)
	(via
		(at 182.332122 -117.442742)
		(size 0.4572)
		(drill 0.254)
		(layers "F.Cu" "B.Cu")
		(net "P3V3_AUX")
	)
	(via
		(at 288.298382 -395.252448)
		(size 0.508)
		(drill 0.254)
		(layers "F.Cu" "B.Cu")
		(net "P3V3_AUX")
	)
	(via
		(at 353.07143 -434.857652)
		(size 0.508)
		(drill 0.254)
		(layers "F.Cu" "B.Cu")
		(net "P3V3_AUX")
	)
	(via
		(at 15.799308 -427.883066)
		(size 0.508)
		(drill 0.254)
		(layers "F.Cu" "B.Cu")
		(net "P3V3_AUX")
	)
	(via
		(at 139.845542 -101.494844)
		(size 0.508)
		(drill 0.254)
		(layers "F.Cu" "B.Cu")
		(net "P3V3_AUX")
	)
	(via
		(at 98.50247 -410.794708)
		(size 0.508)
		(drill 0.254)
		(layers "F.Cu" "B.Cu")
		(net "P3V3_AUX")
	)
	(via
		(at 176.136554 -413.698182)
		(size 0.508)
		(drill 0.254)
		(layers "F.Cu" "B.Cu")
		(net "P3V3_AUX")
	)
	(via
		(at 34.633662 -418.239448)
		(size 0.508)
		(drill 0.254)
		(layers "F.Cu" "B.Cu")
		(net "P3V3_AUX")
	)
	(via
		(at 343.458546 -24.9047)
		(size 0.508)
		(drill 0.254)
		(layers "F.Cu" "B.Cu")
		(net "P3V3_AUX")
	)
	(via
		(at 178.587908 -423.050716)
		(size 0.508)
		(drill 0.254)
		(layers "F.Cu" "B.Cu")
		(net "P3V3_AUX")
	)
	(via
		(at 253.574804 -126.91745)
		(size 0.508)
		(drill 0.254)
		(layers "F.Cu" "B.Cu")
		(net "P3V3_AUX")
	)
	(via
		(at 12.982956 -91.658948)
		(size 0.508)
		(drill 0.254)
		(layers "F.Cu" "B.Cu")
		(net "P3V3_AUX")
	)
	(via
		(at 342.442546 -24.913336)
		(size 0.508)
		(drill 0.254)
		(layers "F.Cu" "B.Cu")
		(net "P3V3_AUX")
	)
	(via
		(at 230.378 -228.543358)
		(size 0.508)
		(drill 0.254)
		(layers "F.Cu" "B.Cu")
		(net "P3V3_AUX")
	)
	(via
		(at 158.671006 -14.798548)
		(size 0.508)
		(drill 0.254)
		(layers "F.Cu" "B.Cu")
		(net "P3V3_AUX")
	)
	(via
		(at 418.41674 -103.866188)
		(size 0.508)
		(drill 0.254)
		(layers "F.Cu" "B.Cu")
		(net "P3V3_AUX")
	)
	(via
		(at 37.402262 -430.871122)
		(size 0.508)
		(drill 0.254)
		(layers "F.Cu" "B.Cu")
		(net "P3V3_AUX")
	)
	(via
		(at 94.205552 -39.4335)
		(size 0.508)
		(drill 0.254)
		(layers "F.Cu" "B.Cu")
		(net "P3V3_AUX")
	)
	(via
		(at 452.710296 -106.408728)
		(size 0.508)
		(drill 0.254)
		(layers "F.Cu" "B.Cu")
		(net "P3V3_AUX")
	)
	(via
		(at 280.707592 -430.791366)
		(size 0.508)
		(drill 0.254)
		(layers "F.Cu" "B.Cu")
		(net "P3V3_AUX")
	)
	(via
		(at 273.814794 -427.354746)
		(size 0.508)
		(drill 0.254)
		(layers "F.Cu" "B.Cu")
		(net "P3V3_AUX")
	)
	(via
		(at 147.407122 -55.313834)
		(size 0.508)
		(drill 0.254)
		(layers "F.Cu" "B.Cu")
		(net "P3V3_AUX")
	)
	(via
		(at 8.707374 -71.860664)
		(size 0.508)
		(drill 0.254)
		(layers "F.Cu" "B.Cu")
		(net "P3V3_AUX")
	)
	(via
		(at 56.146954 -38.904418)
		(size 0.508)
		(drill 0.254)
		(layers "F.Cu" "B.Cu")
		(net "P3V3_AUX")
	)
	(via
		(at 422.48074 -54.733952)
		(size 0.508)
		(drill 0.254)
		(layers "F.Cu" "B.Cu")
		(net "P3V3_AUX")
	)
	(via
		(at 124.929646 -16.50111)
		(size 0.508)
		(drill 0.254)
		(layers "F.Cu" "B.Cu")
		(net "P3V3_AUX")
	)
	(via
		(at 19.666458 -417.68014)
		(size 0.508)
		(drill 0.254)
		(layers "F.Cu" "B.Cu")
		(net "P3V3_AUX")
	)
	(via
		(at 157.59557 -55.696358)
		(size 0.508)
		(drill 0.254)
		(layers "F.Cu" "B.Cu")
		(net "P3V3_AUX")
	)
	(via
		(at 274.425664 -122.624088)
		(size 0.508)
		(drill 0.254)
		(layers "F.Cu" "B.Cu")
		(net "P3V3_AUX")
	)
	(via
		(at 283.696918 -383.514092)
		(size 0.508)
		(drill 0.254)
		(layers "F.Cu" "B.Cu")
		(net "P3V3_AUX")
	)
	(via
		(at 451.814184 -67.724782)
		(size 0.508)
		(drill 0.254)
		(layers "F.Cu" "B.Cu")
		(net "P3V3_AUX")
	)
	(via
		(at 15.067788 -91.618308)
		(size 0.508)
		(drill 0.254)
		(layers "F.Cu" "B.Cu")
		(net "P3V3_AUX")
	)
	(via
		(at 327.692258 -101.88575)
		(size 0.508)
		(drill 0.254)
		(layers "F.Cu" "B.Cu")
		(net "P3V3_AUX")
	)
	(via
		(at 431.751486 -102.61219)
		(size 0.508)
		(drill 0.254)
		(layers "F.Cu" "B.Cu")
		(net "P3V3_AUX")
	)
	(via
		(at 429.29556 -110.27664)
		(size 0.508)
		(drill 0.254)
		(layers "F.Cu" "B.Cu")
		(net "P3V3_AUX")
	)
	(via
		(at 121.294652 -422.011602)
		(size 0.508)
		(drill 0.254)
		(layers "F.Cu" "B.Cu")
		(net "P3V3_AUX")
	)
	(via
		(at 185.777124 -95.080074)
		(size 0.508)
		(drill 0.254)
		(layers "F.Cu" "B.Cu")
		(net "P3V3_AUX")
	)
	(via
		(at 427.489366 -433.986686)
		(size 0.508)
		(drill 0.254)
		(layers "F.Cu" "B.Cu")
		(net "P3V3_AUX")
	)
	(via
		(at 62.183772 -29.348684)
		(size 0.508)
		(drill 0.254)
		(layers "F.Cu" "B.Cu")
		(net "P3V3_AUX")
	)
	(via
		(at 451.010782 -66.463164)
		(size 0.508)
		(drill 0.254)
		(layers "F.Cu" "B.Cu")
		(net "P3V3_AUX")
	)
	(via
		(at 86.241128 -309.52567)
		(size 0.508)
		(drill 0.254)
		(layers "F.Cu" "B.Cu")
		(net "P3V3_AUX")
	)
	(via
		(at 453.475344 -367.68151)
		(size 0.508)
		(drill 0.254)
		(layers "F.Cu" "B.Cu")
		(net "P3V3_AUX")
	)
	(via
		(at 448.201542 -67.730878)
		(size 0.508)
		(drill 0.254)
		(layers "F.Cu" "B.Cu")
		(net "P3V3_AUX")
	)
	(via
		(at 147.82419 -101.894132)
		(size 0.508)
		(drill 0.254)
		(layers "F.Cu" "B.Cu")
		(net "P3V3_AUX")
	)
	(via
		(at 253.583186 -123.10745)
		(size 0.508)
		(drill 0.254)
		(layers "F.Cu" "B.Cu")
		(net "P3V3_AUX")
	)
	(via
		(at 209.634328 -42.382948)
		(size 0.508)
		(drill 0.254)
		(layers "F.Cu" "B.Cu")
		(net "P3V3_AUX")
	)
	(via
		(at 453.551036 -369.906804)
		(size 0.508)
		(drill 0.254)
		(layers "F.Cu" "B.Cu")
		(net "P3V3_AUX")
	)
	(via
		(at 276.342602 -113.31067)
		(size 0.508)
		(drill 0.254)
		(layers "F.Cu" "B.Cu")
		(net "P3V3_AUX")
	)
	(via
		(at 89.193878 -144.88541)
		(size 0.508)
		(drill 0.254)
		(layers "F.Cu" "B.Cu")
		(net "P3V3_AUX")
	)
	(via
		(at 62.183772 -28.332684)
		(size 0.508)
		(drill 0.254)
		(layers "F.Cu" "B.Cu")
		(net "P3V3_AUX")
	)
	(via
		(at 300.785276 -15.62481)
		(size 0.508)
		(drill 0.254)
		(layers "F.Cu" "B.Cu")
		(net "P3V3_AUX")
	)
	(via
		(at 211.606638 -99.822)
		(size 0.508)
		(drill 0.254)
		(layers "F.Cu" "B.Cu")
		(net "P3V3_AUX")
	)
	(via
		(at 141.828266 -122.452384)
		(size 0.508)
		(drill 0.254)
		(layers "F.Cu" "B.Cu")
		(net "P3V3_AUX")
	)
	(via
		(at 8.707374 -70.560692)
		(size 0.508)
		(drill 0.254)
		(layers "F.Cu" "B.Cu")
		(net "P3V3_AUX")
	)
	(via
		(at 191.836294 -413.564832)
		(size 0.508)
		(drill 0.254)
		(layers "F.Cu" "B.Cu")
		(net "P3V3_AUX")
	)
	(via
		(at 206.050896 -100.577396)
		(size 0.508)
		(drill 0.254)
		(layers "F.Cu" "B.Cu")
		(net "P3V3_AUX")
	)
	(via
		(at 446.537588 -67.765676)
		(size 0.508)
		(drill 0.254)
		(layers "F.Cu" "B.Cu")
		(net "P3V3_AUX")
	)
	(via
		(at 133.348222 -31.982156)
		(size 0.508)
		(drill 0.254)
		(layers "F.Cu" "B.Cu")
		(net "P3V3_AUX")
	)
	(via
		(at 192.573402 -378.660406)
		(size 0.508)
		(drill 0.254)
		(layers "F.Cu" "B.Cu")
		(net "P3V3_AUX")
	)
	(via
		(at 184.732168 -114.262916)
		(size 0.4572)
		(drill 0.254)
		(layers "F.Cu" "B.Cu")
		(net "P3V3_AUX")
	)
	(via
		(at 361.625388 -410.66212)
		(size 0.508)
		(drill 0.254)
		(layers "F.Cu" "B.Cu")
		(net "P3V3_AUX")
	)
	(via
		(at 110.152942 -18.78584)
		(size 0.508)
		(drill 0.254)
		(layers "F.Cu" "B.Cu")
		(net "P3V3_AUX")
	)
	(via
		(at 187.47105 -436.392828)
		(size 0.508)
		(drill 0.254)
		(layers "F.Cu" "B.Cu")
		(net "P3V3_AUX")
	)
	(via
		(at 53.594 -436.28945)
		(size 0.508)
		(drill 0.254)
		(layers "F.Cu" "B.Cu")
		(net "P3V3_AUX")
	)
	(via
		(at 278.511 -416.306)
		(size 0.508)
		(drill 0.254)
		(layers "F.Cu" "B.Cu")
		(net "P3V3_AUX")
	)
	(via
		(at 127.890778 -47.121064)
		(size 0.508)
		(drill 0.254)
		(layers "F.Cu" "B.Cu")
		(net "P3V3_AUX")
	)
	(via
		(at 196.15658 -39.046912)
		(size 0.508)
		(drill 0.254)
		(layers "F.Cu" "B.Cu")
		(net "P3V3_AUX")
	)
	(via
		(at 48.581056 -37.533072)
		(size 0.508)
		(drill 0.254)
		(layers "F.Cu" "B.Cu")
		(net "P3V3_AUX")
	)
	(via
		(at 281.686 -424.461178)
		(size 0.508)
		(drill 0.254)
		(layers "F.Cu" "B.Cu")
		(net "P3V3_AUX")
	)
	(via
		(at 287.97631 -398.513808)
		(size 0.508)
		(drill 0.254)
		(layers "F.Cu" "B.Cu")
		(net "P3V3_AUX")
	)
	(via
		(at 276.342602 -125.638814)
		(size 0.508)
		(drill 0.254)
		(layers "F.Cu" "B.Cu")
		(net "P3V3_AUX")
	)
	(via
		(at 153.2509 -18.705068)
		(size 0.508)
		(drill 0.254)
		(layers "F.Cu" "B.Cu")
		(net "P3V3_AUX")
	)
	(via
		(at 281.891994 -410.442918)
		(size 0.508)
		(drill 0.254)
		(layers "F.Cu" "B.Cu")
		(net "P3V3_AUX")
	)
	(via
		(at 140.33754 -113.40846)
		(size 0.508)
		(drill 0.254)
		(layers "F.Cu" "B.Cu")
		(net "P3V3_AUX")
	)
	(via
		(at 407.667714 -136.231376)
		(size 0.508)
		(drill 0.254)
		(layers "F.Cu" "B.Cu")
		(net "P3V3_AUX")
	)
	(via
		(at 392.300206 -73.359264)
		(size 0.508)
		(drill 0.254)
		(layers "F.Cu" "B.Cu")
		(net "P3V3_AUX")
	)
	(via
		(at 144.093438 -123.837954)
		(size 0.508)
		(drill 0.254)
		(layers "F.Cu" "B.Cu")
		(net "P3V3_AUX")
	)
	(via
		(at 166.178992 -107.315)
		(size 0.508)
		(drill 0.254)
		(layers "F.Cu" "B.Cu")
		(net "P3V3_AUX")
	)
	(via
		(at 126.619 -106.53395)
		(size 0.508)
		(drill 0.254)
		(layers "F.Cu" "B.Cu")
		(net "P3V3_AUX")
	)
	(via
		(at 344.955876 -65.692782)
		(size 0.508)
		(drill 0.254)
		(layers "F.Cu" "B.Cu")
		(net "P3V3_AUX")
	)
	(via
		(at 192.454276 -24.919432)
		(size 0.508)
		(drill 0.254)
		(layers "F.Cu" "B.Cu")
		(net "P3V3_AUX")
	)
	(via
		(at 36.142422 -433.112164)
		(size 0.508)
		(drill 0.254)
		(layers "F.Cu" "B.Cu")
		(net "P3V3_AUX")
	)
	(via
		(at 93.896434 -74.196956)
		(size 0.508)
		(drill 0.254)
		(layers "F.Cu" "B.Cu")
		(net "P3V3_AUX")
	)
	(via
		(at 36.519612 -428.012098)
		(size 0.508)
		(drill 0.254)
		(layers "F.Cu" "B.Cu")
		(net "P3V3_AUX")
	)
	(via
		(at 437.425846 -436.94731)
		(size 0.508)
		(drill 0.254)
		(layers "F.Cu" "B.Cu")
		(net "P3V3_AUX")
	)
	(via
		(at 19.73072 -96.74733)
		(size 0.508)
		(drill 0.254)
		(layers "F.Cu" "B.Cu")
		(net "P3V3_AUX")
	)
	(via
		(at 19.73072 -96.11233)
		(size 0.508)
		(drill 0.254)
		(layers "F.Cu" "B.Cu")
		(net "P3V3_AUX")
	)
	(via
		(at 370.31676 -425.63034)
		(size 0.508)
		(drill 0.254)
		(layers "F.Cu" "B.Cu")
		(net "P3V3_AUX")
	)
	(via
		(at 308.379876 -65.692782)
		(size 0.508)
		(drill 0.254)
		(layers "F.Cu" "B.Cu")
		(net "P3V3_AUX")
	)
	(via
		(at 357.637842 -416.23107)
		(size 0.508)
		(drill 0.254)
		(layers "F.Cu" "B.Cu")
		(net "P3V3_AUX")
	)
	(via
		(at 14.43101 -417.431474)
		(size 0.508)
		(drill 0.254)
		(layers "F.Cu" "B.Cu")
		(net "P3V3_AUX")
	)
	(via
		(at 16.364458 -417.447984)
		(size 0.508)
		(drill 0.254)
		(layers "F.Cu" "B.Cu")
		(net "P3V3_AUX")
	)
	(via
		(at 453.109584 -68.359782)
		(size 0.508)
		(drill 0.254)
		(layers "F.Cu" "B.Cu")
		(net "P3V3_AUX")
	)
	(via
		(at 8.932418 -413.86887)
		(size 0.508)
		(drill 0.254)
		(layers "F.Cu" "B.Cu")
		(net "P3V3_AUX")
	)
	(via
		(at 159.124142 -77.555852)
		(size 0.508)
		(drill 0.254)
		(layers "F.Cu" "B.Cu")
		(net "P3V3_AUX")
	)
	(via
		(at 335.28508 -17.012666)
		(size 0.508)
		(drill 0.254)
		(layers "F.Cu" "B.Cu")
		(net "P3V3_AUX")
	)
	(via
		(at 25.826466 -38.402514)
		(size 0.508)
		(drill 0.254)
		(layers "F.Cu" "B.Cu")
		(net "P3V3_AUX")
	)
	(via
		(at 104.902 -427.609)
		(size 0.508)
		(drill 0.254)
		(layers "F.Cu" "B.Cu")
		(net "P3V3_AUX")
	)
	(via
		(at 114.299238 -42.2656)
		(size 0.508)
		(drill 0.254)
		(layers "F.Cu" "B.Cu")
		(net "P3V3_AUX")
	)
	(via
		(at 462.552542 -143.549878)
		(size 0.508)
		(drill 0.254)
		(layers "F.Cu" "B.Cu")
		(net "P3V3_AUX")
	)
	(via
		(at 63.591186 -95.348806)
		(size 0.508)
		(drill 0.254)
		(layers "F.Cu" "B.Cu")
		(net "P3V3_AUX")
	)
	(via
		(at 322.116196 -100.36175)
		(size 0.508)
		(drill 0.254)
		(layers "F.Cu" "B.Cu")
		(net "P3V3_AUX")
	)
	(via
		(at 39.83355 -433.19954)
		(size 0.508)
		(drill 0.254)
		(layers "F.Cu" "B.Cu")
		(net "P3V3_AUX")
	)
	(via
		(at 152.991312 -27.701748)
		(size 0.508)
		(drill 0.254)
		(layers "F.Cu" "B.Cu")
		(net "P3V3_AUX")
	)
	(via
		(at 366.027462 -142.37589)
		(size 0.508)
		(drill 0.254)
		(layers "F.Cu" "B.Cu")
		(net "P3V3_AUX")
	)
	(via
		(at 319.137538 -202.902312)
		(size 0.508)
		(drill 0.254)
		(layers "F.Cu" "B.Cu")
		(net "P3V3_AUX")
	)
	(via
		(at 118.364 -435.50205)
		(size 0.508)
		(drill 0.254)
		(layers "F.Cu" "B.Cu")
		(net "P3V3_AUX")
	)
	(via
		(at 461.01127 -37.92855)
		(size 0.508)
		(drill 0.254)
		(layers "F.Cu" "B.Cu")
		(net "P3V3_AUX")
	)
	(via
		(at 284.457648 -384.973576)
		(size 0.508)
		(drill 0.254)
		(layers "F.Cu" "B.Cu")
		(net "P3V3_AUX")
	)
	(via
		(at 45.719746 -431.585624)
		(size 0.508)
		(drill 0.254)
		(layers "F.Cu" "B.Cu")
		(net "P3V3_AUX")
	)
	(via
		(at 301.452534 -46.21022)
		(size 0.508)
		(drill 0.254)
		(layers "F.Cu" "B.Cu")
		(net "P3V3_AUX")
	)
	(via
		(at 304.701448 -429.606964)
		(size 0.508)
		(drill 0.254)
		(layers "F.Cu" "B.Cu")
		(net "P3V3_AUX")
	)
	(via
		(at 455.720196 -69.722746)
		(size 0.508)
		(drill 0.254)
		(layers "F.Cu" "B.Cu")
		(net "P3V3_AUX")
	)
	(via
		(at 453.137524 -34.89833)
		(size 0.508)
		(drill 0.254)
		(layers "F.Cu" "B.Cu")
		(net "P3V3_AUX")
	)
	(via
		(at 178.830224 -146.070574)
		(size 0.508)
		(drill 0.254)
		(layers "F.Cu" "B.Cu")
		(net "P3V3_AUX")
	)
	(via
		(at 434.086 -105.628948)
		(size 0.508)
		(drill 0.254)
		(layers "F.Cu" "B.Cu")
		(net "P3V3_AUX")
	)
	(via
		(at 204.089 -92.964)
		(size 0.508)
		(drill 0.254)
		(layers "F.Cu" "B.Cu")
		(net "P3V3_AUX")
	)
	(via
		(at 14.82471 -140.30071)
		(size 0.508)
		(drill 0.254)
		(layers "F.Cu" "B.Cu")
		(net "P3V3_AUX")
	)
	(via
		(at 125.857 -40.992044)
		(size 0.508)
		(drill 0.254)
		(layers "F.Cu" "B.Cu")
		(net "P3V3_AUX")
	)
	(via
		(at 16.110966 -91.618308)
		(size 0.508)
		(drill 0.254)
		(layers "F.Cu" "B.Cu")
		(net "P3V3_AUX")
	)
	(via
		(at 47.033942 -430.565052)
		(size 0.508)
		(drill 0.254)
		(layers "F.Cu" "B.Cu")
		(net "P3V3_AUX")
	)
	(via
		(at 178.229006 -355.48443)
		(size 0.508)
		(drill 0.254)
		(layers "F.Cu" "B.Cu")
		(net "P3V3_AUX")
	)
	(via
		(at 188.712094 -114.262916)
		(size 0.4572)
		(drill 0.254)
		(layers "F.Cu" "B.Cu")
		(net "P3V3_AUX")
	)
	(via
		(at 215.11133 -329.179174)
		(size 0.508)
		(drill 0.254)
		(layers "F.Cu" "B.Cu")
		(net "P3V3_AUX")
	)
	(via
		(at 330.642722 -41.16197)
		(size 0.508)
		(drill 0.254)
		(layers "F.Cu" "B.Cu")
		(net "P3V3_AUX")
	)
	(via
		(at 181.504082 -150.061168)
		(size 0.508)
		(drill 0.254)
		(layers "F.Cu" "B.Cu")
		(net "P3V3_AUX")
	)
	(via
		(at 447.787268 -193.935096)
		(size 0.4826)
		(drill 0.254)
		(layers "F.Cu" "B.Cu")
		(net "P3V3_AUX")
	)
	(via
		(at 276.342602 -116.10467)
		(size 0.508)
		(drill 0.254)
		(layers "F.Cu" "B.Cu")
		(net "P3V3_AUX")
	)
	(via
		(at 37.67836 -369.487196)
		(size 0.508)
		(drill 0.254)
		(layers "F.Cu" "B.Cu")
		(net "P3V3_AUX")
	)
	(via
		(at 117.513862 -18.42135)
		(size 0.508)
		(drill 0.254)
		(layers "F.Cu" "B.Cu")
		(net "P3V3_AUX")
	)
	(via
		(at 452.355966 -45.569632)
		(size 0.508)
		(drill 0.254)
		(layers "F.Cu" "B.Cu")
		(net "P3V3_AUX")
	)
	(via
		(at 209.07121 -29.266642)
		(size 0.508)
		(drill 0.254)
		(layers "F.Cu" "B.Cu")
		(net "P3V3_AUX")
	)
	(via
		(at 156.406088 -27.08783)
		(size 0.508)
		(drill 0.254)
		(layers "F.Cu" "B.Cu")
		(net "P3V3_AUX")
	)
	(via
		(at 209.305144 -237.082076)
		(size 0.508)
		(drill 0.254)
		(layers "F.Cu" "B.Cu")
		(net "P3V3_AUX")
	)
	(via
		(at 65.643506 -54.356)
		(size 0.508)
		(drill 0.254)
		(layers "F.Cu" "B.Cu")
		(net "P3V3_AUX")
	)
	(via
		(at 191.911986 -119.042688)
		(size 0.4572)
		(drill 0.254)
		(layers "F.Cu" "B.Cu")
		(net "P3V3_AUX")
	)
	(via
		(at 301.452534 -47.09922)
		(size 0.508)
		(drill 0.254)
		(layers "F.Cu" "B.Cu")
		(net "P3V3_AUX")
	)
	(via
		(at 193.311018 -71.21017)
		(size 0.508)
		(drill 0.254)
		(layers "F.Cu" "B.Cu")
		(net "P3V3_AUX")
	)
	(via
		(at 217.388186 -53.95595)
		(size 0.508)
		(drill 0.254)
		(layers "F.Cu" "B.Cu")
		(net "P3V3_AUX")
	)
	(via
		(at 219.96654 -240.604548)
		(size 0.508)
		(drill 0.254)
		(layers "F.Cu" "B.Cu")
		(net "P3V3_AUX")
	)
	(via
		(at 366.534446 -27.290522)
		(size 0.508)
		(drill 0.254)
		(layers "F.Cu" "B.Cu")
		(net "P3V3_AUX")
	)
	(via
		(at 262.85317 -104.572816)
		(size 0.508)
		(drill 0.254)
		(layers "F.Cu" "B.Cu")
		(net "P3V3_AUX")
	)
	(via
		(at 199.8472 -193.93535)
		(size 0.4826)
		(drill 0.254)
		(layers "F.Cu" "B.Cu")
		(net "P3V3_AUX")
	)
	(via
		(at 188.712094 -116.642642)
		(size 0.4572)
		(drill 0.254)
		(layers "F.Cu" "B.Cu")
		(net "P3V3_AUX")
	)
	(via
		(at 314.167266 -114.23777)
		(size 0.508)
		(drill 0.254)
		(layers "F.Cu" "B.Cu")
		(net "P3V3_AUX")
	)
	(via
		(at 252.541278 -39.34333)
		(size 0.508)
		(drill 0.254)
		(layers "F.Cu" "B.Cu")
		(net "P3V3_AUX")
	)
	(via
		(at 187.111894 -114.262916)
		(size 0.4572)
		(drill 0.254)
		(layers "F.Cu" "B.Cu")
		(net "P3V3_AUX")
	)
	(via
		(at 459.129384 -68.994782)
		(size 0.508)
		(drill 0.254)
		(layers "F.Cu" "B.Cu")
		(net "P3V3_AUX")
	)
	(via
		(at 367.931446 -29.119322)
		(size 0.508)
		(drill 0.254)
		(layers "F.Cu" "B.Cu")
		(net "P3V3_AUX")
	)
	(via
		(at 192.303146 -193.93535)
		(size 0.4826)
		(drill 0.254)
		(layers "F.Cu" "B.Cu")
		(net "P3V3_AUX")
	)
	(via
		(at 229.205028 -288.939732)
		(size 0.508)
		(drill 0.254)
		(layers "F.Cu" "B.Cu")
		(net "P3V3_AUX")
	)
	(via
		(at 104.14 -77.216)
		(size 0.508)
		(drill 0.254)
		(layers "F.Cu" "B.Cu")
		(net "P3V3_AUX")
	)
	(via
		(at 164.49802 -416.946588)
		(size 0.508)
		(drill 0.254)
		(layers "F.Cu" "B.Cu")
		(net "P3V3_AUX")
	)
	(via
		(at 212.99805 -121.298716)
		(size 0.508)
		(drill 0.254)
		(layers "F.Cu" "B.Cu")
		(net "P3V3_AUX")
	)
	(via
		(at 174.26305 -420.898828)
		(size 0.508)
		(drill 0.254)
		(layers "F.Cu" "B.Cu")
		(net "P3V3_AUX")
	)
	(via
		(at 121.539 -431.038)
		(size 0.508)
		(drill 0.254)
		(layers "F.Cu" "B.Cu")
		(net "P3V3_AUX")
	)
	(via
		(at 219.224352 -239.907064)
		(size 0.508)
		(drill 0.254)
		(layers "F.Cu" "B.Cu")
		(net "P3V3_AUX")
	)
	(via
		(at 276.342602 -117.50167)
		(size 0.508)
		(drill 0.254)
		(layers "F.Cu" "B.Cu")
		(net "P3V3_AUX")
	)
	(via
		(at 451.010782 -67.098164)
		(size 0.508)
		(drill 0.254)
		(layers "F.Cu" "B.Cu")
		(net "P3V3_AUX")
	)
	(via
		(at 259.269992 -108.179108)
		(size 0.508)
		(drill 0.254)
		(layers "F.Cu" "B.Cu")
		(net "P3V3_AUX")
	)
	(via
		(at 218.16695 -101.228398)
		(size 0.508)
		(drill 0.254)
		(layers "F.Cu" "B.Cu")
		(net "P3V3_AUX")
	)
	(via
		(at 184.732168 -115.842796)
		(size 0.4572)
		(drill 0.254)
		(layers "F.Cu" "B.Cu")
		(net "P3V3_AUX")
	)
	(via
		(at 161.313368 -324.383908)
		(size 0.508)
		(drill 0.254)
		(layers "F.Cu" "B.Cu")
		(net "P3V3_AUX")
	)
	(via
		(at 16.837406 -75.744578)
		(size 0.508)
		(drill 0.254)
		(layers "F.Cu" "B.Cu")
		(net "P3V3_AUX")
	)
	(via
		(at 13.537946 -140.30071)
		(size 0.508)
		(drill 0.254)
		(layers "F.Cu" "B.Cu")
		(net "P3V3_AUX")
	)
	(via
		(at 318.300608 -21.56333)
		(size 0.508)
		(drill 0.254)
		(layers "F.Cu" "B.Cu")
		(net "P3V3_AUX")
	)
	(via
		(at 122.739658 -59.182)
		(size 0.508)
		(drill 0.254)
		(layers "F.Cu" "B.Cu")
		(net "P3V3_AUX")
	)
	(via
		(at 88.55583 -58.21172)
		(size 0.508)
		(drill 0.254)
		(layers "F.Cu" "B.Cu")
		(net "P3V3_AUX")
	)
	(via
		(at 139.845542 -105.225596)
		(size 0.508)
		(drill 0.254)
		(layers "F.Cu" "B.Cu")
		(net "P3V3_AUX")
	)
	(via
		(at 222.057976 -72.909938)
		(size 0.508)
		(drill 0.254)
		(layers "F.Cu" "B.Cu")
		(net "P3V3_AUX")
	)
	(via
		(at 434.39842 -439.332116)
		(size 0.508)
		(drill 0.254)
		(layers "F.Cu" "B.Cu")
		(net "P3V3_AUX")
	)
	(via
		(at 450.577966 -420.99611)
		(size 0.508)
		(drill 0.254)
		(layers "F.Cu" "B.Cu")
		(net "P3V3_AUX")
	)
	(via
		(at 167.49395 -132.35305)
		(size 0.508)
		(drill 0.254)
		(layers "F.Cu" "B.Cu")
		(net "P3V3_AUX")
	)
	(via
		(at 276.342602 -118.89867)
		(size 0.508)
		(drill 0.254)
		(layers "F.Cu" "B.Cu")
		(net "P3V3_AUX")
	)
	(via
		(at 210.59521 -37.369242)
		(size 0.508)
		(drill 0.254)
		(layers "F.Cu" "B.Cu")
		(net "P3V3_AUX")
	)
	(via
		(at 274.48256 -118.618)
		(size 0.508)
		(drill 0.254)
		(layers "F.Cu" "B.Cu")
		(net "P3V3_AUX")
	)
	(via
		(at 244.729 -217.098626)
		(size 0.508)
		(drill 0.254)
		(layers "F.Cu" "B.Cu")
		(net "P3V3_AUX")
	)
	(via
		(at 144.989042 -74.902822)
		(size 0.508)
		(drill 0.254)
		(layers "F.Cu" "B.Cu")
		(net "P3V3_AUX")
	)
	(via
		(at 152.017984 -114.660934)
		(size 0.508)
		(drill 0.254)
		(layers "F.Cu" "B.Cu")
		(net "P3V3_AUX")
	)
	(via
		(at 308.511194 -193.935096)
		(size 0.4826)
		(drill 0.254)
		(layers "F.Cu" "B.Cu")
		(net "P3V3_AUX")
	)
	(via
		(at 119.728234 -59.884056)
		(size 0.508)
		(drill 0.254)
		(layers "F.Cu" "B.Cu")
		(net "P3V3_AUX")
	)
	(via
		(at 320.097658 -105.442512)
		(size 0.508)
		(drill 0.254)
		(layers "F.Cu" "B.Cu")
		(net "P3V3_AUX")
	)
	(via
		(at 147.82419 -98.355658)
		(size 0.508)
		(drill 0.254)
		(layers "F.Cu" "B.Cu")
		(net "P3V3_AUX")
	)
	(via
		(at 419.74135 -37.277548)
		(size 0.508)
		(drill 0.254)
		(layers "F.Cu" "B.Cu")
		(net "P3V3_AUX")
	)
	(via
		(at 283.061156 -431.510186)
		(size 0.508)
		(drill 0.254)
		(layers "F.Cu" "B.Cu")
		(net "P3V3_AUX")
	)
	(via
		(at 37.333428 -134.873238)
		(size 0.508)
		(drill 0.254)
		(layers "F.Cu" "B.Cu")
		(net "P3V3_AUX")
	)
	(via
		(at 319.905888 -23.587456)
		(size 0.508)
		(drill 0.254)
		(layers "F.Cu" "B.Cu")
		(net "P3V3_AUX")
	)
	(via
		(at 32.112712 -421.281098)
		(size 0.508)
		(drill 0.254)
		(layers "F.Cu" "B.Cu")
		(net "P3V3_AUX")
	)
	(via
		(at 211.582 -104.013)
		(size 0.508)
		(drill 0.254)
		(layers "F.Cu" "B.Cu")
		(net "P3V3_AUX")
	)
	(via
		(at 188.712094 -117.442742)
		(size 0.4572)
		(drill 0.254)
		(layers "F.Cu" "B.Cu")
		(net "P3V3_AUX")
	)
	(via
		(at 295.169844 -19.433286)
		(size 0.508)
		(drill 0.254)
		(layers "F.Cu" "B.Cu")
		(net "P3V3_AUX")
	)
	(via
		(at 282.927298 -392.035538)
		(size 0.508)
		(drill 0.254)
		(layers "F.Cu" "B.Cu")
		(net "P3V3_AUX")
	)
	(via
		(at 43.71848 -104.7369)
		(size 0.508)
		(drill 0.254)
		(layers "F.Cu" "B.Cu")
		(net "P3V3_AUX")
	)
	(via
		(at 452.76262 -369.882166)
		(size 0.508)
		(drill 0.254)
		(layers "F.Cu" "B.Cu")
		(net "P3V3_AUX")
	)
	(via
		(at 46.97222 -31.877508)
		(size 0.508)
		(drill 0.254)
		(layers "F.Cu" "B.Cu")
		(net "P3V3_AUX")
	)
	(via
		(at 104.2416 -27.275282)
		(size 0.508)
		(drill 0.254)
		(layers "F.Cu" "B.Cu")
		(net "P3V3_AUX")
	)
	(via
		(at 187.479432 -437.173878)
		(size 0.508)
		(drill 0.254)
		(layers "F.Cu" "B.Cu")
		(net "P3V3_AUX")
	)
	(via
		(at 350.470216 -440.211972)
		(size 0.508)
		(drill 0.254)
		(layers "F.Cu" "B.Cu")
		(net "P3V3_AUX")
	)
	(via
		(at 447.490088 -71.592186)
		(size 0.508)
		(drill 0.254)
		(layers "F.Cu" "B.Cu")
		(net "P3V3_AUX")
	)
	(via
		(at 209.285332 -238.54156)
		(size 0.508)
		(drill 0.254)
		(layers "F.Cu" "B.Cu")
		(net "P3V3_AUX")
	)
	(via
		(at 172.078904 -8.462518)
		(size 0.508)
		(drill 0.254)
		(layers "F.Cu" "B.Cu")
		(net "P3V3_AUX")
	)
	(via
		(at 149.492716 -57.220358)
		(size 0.508)
		(drill 0.254)
		(layers "F.Cu" "B.Cu")
		(net "P3V3_AUX")
	)
	(via
		(at 452.721726 -367.685574)
		(size 0.508)
		(drill 0.254)
		(layers "F.Cu" "B.Cu")
		(net "P3V3_AUX")
	)
	(via
		(at 284.457648 -382.761744)
		(size 0.508)
		(drill 0.254)
		(layers "F.Cu" "B.Cu")
		(net "P3V3_AUX")
	)
	(via
		(at 8.784336 -333.436976)
		(size 0.508)
		(drill 0.254)
		(layers "F.Cu" "B.Cu")
		(net "P3V3_AUX")
	)
	(via
		(at 136.669018 -150.533608)
		(size 0.508)
		(drill 0.254)
		(layers "F.Cu" "B.Cu")
		(net "P3V3_AUX")
	)
	(via
		(at 182.123334 -56.098948)
		(size 0.508)
		(drill 0.254)
		(layers "F.Cu" "B.Cu")
		(net "P3V3_AUX")
	)
	(via
		(at 320.664078 -202.898756)
		(size 0.508)
		(drill 0.254)
		(layers "F.Cu" "B.Cu")
		(net "P3V3_AUX")
	)
	(via
		(at 217.056208 -96.774)
		(size 0.508)
		(drill 0.254)
		(layers "F.Cu" "B.Cu")
		(net "P3V3_AUX")
	)
	(via
		(at 98.380296 -426.84573)
		(size 0.508)
		(drill 0.254)
		(layers "F.Cu" "B.Cu")
		(net "P3V3_AUX")
	)
	(via
		(at 279.653492 -435.823614)
		(size 0.508)
		(drill 0.254)
		(layers "F.Cu" "B.Cu")
		(net "P3V3_AUX")
	)
	(via
		(at 14.546834 -69.178678)
		(size 0.508)
		(drill 0.254)
		(layers "F.Cu" "B.Cu")
		(net "P3V3_AUX")
	)
	(via
		(at 174.502572 -14.822678)
		(size 0.508)
		(drill 0.254)
		(layers "F.Cu" "B.Cu")
		(net "P3V3_AUX")
	)
	(via
		(at 143.243554 -40.003476)
		(size 0.508)
		(drill 0.254)
		(layers "F.Cu" "B.Cu")
		(net "P3V3_AUX")
	)
	(via
		(at 418.599366 -437.834786)
		(size 0.508)
		(drill 0.254)
		(layers "F.Cu" "B.Cu")
		(net "P3V3_AUX")
	)
	(via
		(at 459.129384 -68.359782)
		(size 0.508)
		(drill 0.254)
		(layers "F.Cu" "B.Cu")
		(net "P3V3_AUX")
	)
	(via
		(at 188.22035 -436.42153)
		(size 0.508)
		(drill 0.254)
		(layers "F.Cu" "B.Cu")
		(net "P3V3_AUX")
	)
	(via
		(at 301.231808 -110.795308)
		(size 0.508)
		(drill 0.254)
		(layers "F.Cu" "B.Cu")
		(net "P3V3_AUX")
	)
	(via
		(at 144.458944 -59.898534)
		(size 0.508)
		(drill 0.254)
		(layers "F.Cu" "B.Cu")
		(net "P3V3_AUX")
	)
	(via
		(at 188.849 -95.087948)
		(size 0.508)
		(drill 0.254)
		(layers "F.Cu" "B.Cu")
		(net "P3V3_AUX")
	)
	(via
		(at 193.195956 -72.1614)
		(size 0.508)
		(drill 0.254)
		(layers "F.Cu" "B.Cu")
		(net "P3V3_AUX")
	)
	(via
		(at 457.498196 -69.722746)
		(size 0.508)
		(drill 0.254)
		(layers "F.Cu" "B.Cu")
		(net "P3V3_AUX")
	)
	(via
		(at 105.283 -416.32505)
		(size 0.508)
		(drill 0.254)
		(layers "F.Cu" "B.Cu")
		(net "P3V3_AUX")
	)
	(via
		(at 342.923876 -65.692782)
		(size 0.508)
		(drill 0.254)
		(layers "F.Cu" "B.Cu")
		(net "P3V3_AUX")
	)
	(via
		(at 461.557878 -94.952566)
		(size 0.508)
		(drill 0.254)
		(layers "F.Cu" "B.Cu")
		(net "P3V3_AUX")
	)
	(via
		(at 200.43775 -134.47395)
		(size 0.508)
		(drill 0.254)
		(layers "F.Cu" "B.Cu")
		(net "P3V3_AUX")
	)
	(via
		(at 453.109584 -67.724782)
		(size 0.508)
		(drill 0.254)
		(layers "F.Cu" "B.Cu")
		(net "P3V3_AUX")
	)
	(via
		(at 63.549276 -96.144842)
		(size 0.508)
		(drill 0.254)
		(layers "F.Cu" "B.Cu")
		(net "P3V3_AUX")
	)
	(via
		(at 191.055498 -427.480476)
		(size 0.508)
		(drill 0.254)
		(layers "F.Cu" "B.Cu")
		(net "P3V3_AUX")
	)
	(via
		(at 102.397814 -37.6682)
		(size 0.508)
		(drill 0.254)
		(layers "F.Cu" "B.Cu")
		(net "P3V3_AUX")
	)
	(via
		(at 298.495974 -119.339614)
		(size 0.508)
		(drill 0.254)
		(layers "F.Cu" "B.Cu")
		(net "P3V3_AUX")
	)
	(via
		(at 300.785276 -14.48181)
		(size 0.508)
		(drill 0.254)
		(layers "F.Cu" "B.Cu")
		(net "P3V3_AUX")
	)
	(via
		(at 298.495974 -116.545614)
		(size 0.508)
		(drill 0.254)
		(layers "F.Cu" "B.Cu")
		(net "P3V3_AUX")
	)
	(via
		(at 283.216858 -406.092152)
		(size 0.508)
		(drill 0.254)
		(layers "F.Cu" "B.Cu")
		(net "P3V3_AUX")
	)
	(via
		(at 418.378132 -157.218634)
		(size 0.508)
		(drill 0.254)
		(layers "F.Cu" "B.Cu")
		(net "P3V3_AUX")
	)
	(via
		(at 191.729106 -426.229526)
		(size 0.508)
		(drill 0.254)
		(layers "F.Cu" "B.Cu")
		(net "P3V3_AUX")
	)
	(via
		(at 353.5045 -431.227738)
		(size 0.508)
		(drill 0.254)
		(layers "F.Cu" "B.Cu")
		(net "P3V3_AUX")
	)
	(via
		(at 106.70921 -57.486042)
		(size 0.508)
		(drill 0.254)
		(layers "F.Cu" "B.Cu")
		(net "P3V3_AUX")
	)
	(via
		(at 199.695562 -113.551716)
		(size 0.508)
		(drill 0.254)
		(layers "F.Cu" "B.Cu")
		(net "P3V3_AUX")
	)
	(via
		(at 316.421008 -119.566182)
		(size 0.508)
		(drill 0.254)
		(layers "F.Cu" "B.Cu")
		(net "P3V3_AUX")
	)
	(via
		(at 298.495974 -113.751614)
		(size 0.508)
		(drill 0.254)
		(layers "F.Cu" "B.Cu")
		(net "P3V3_AUX")
	)
	(via
		(at 436.856886 -29.645102)
		(size 0.508)
		(drill 0.254)
		(layers "F.Cu" "B.Cu")
		(net "P3V3_AUX")
	)
	(via
		(at 162.621468 -416.547554)
		(size 0.508)
		(drill 0.254)
		(layers "F.Cu" "B.Cu")
		(net "P3V3_AUX")
	)
	(via
		(at 185.704226 -418.591238)
		(size 0.508)
		(drill 0.254)
		(layers "F.Cu" "B.Cu")
		(net "P3V3_AUX")
	)
	(via
		(at 160.40354 -129.695702)
		(size 0.508)
		(drill 0.254)
		(layers "F.Cu" "B.Cu")
		(net "P3V3_AUX")
	)
	(via
		(at 208.236312 -73.168002)
		(size 0.508)
		(drill 0.254)
		(layers "F.Cu" "B.Cu")
		(net "P3V3_AUX")
	)
	(via
		(at 175.65624 -427.239938)
		(size 0.508)
		(drill 0.254)
		(layers "F.Cu" "B.Cu")
		(net "P3V3_AUX")
	)
	(via
		(at 417.611052 -193.935096)
		(size 0.4826)
		(drill 0.254)
		(layers "F.Cu" "B.Cu")
		(net "P3V3_AUX")
	)
	(via
		(at 300.9646 -362.839)
		(size 0.508)
		(drill 0.254)
		(layers "F.Cu" "B.Cu")
		(net "P3V3_AUX")
	)
	(via
		(at 148.20519 -33.796224)
		(size 0.508)
		(drill 0.254)
		(layers "F.Cu" "B.Cu")
		(net "P3V3_AUX")
	)
	(via
		(at 425.155106 -193.935096)
		(size 0.4826)
		(drill 0.254)
		(layers "F.Cu" "B.Cu")
		(net "P3V3_AUX")
	)
	(via
		(at 419.10508 -103.873808)
		(size 0.508)
		(drill 0.254)
		(layers "F.Cu" "B.Cu")
		(net "P3V3_AUX")
	)
	(via
		(at 315.576966 -109.53877)
		(size 0.508)
		(drill 0.254)
		(layers "F.Cu" "B.Cu")
		(net "P3V3_AUX")
	)
	(via
		(at 446.2272 -92.468192)
		(size 0.508)
		(drill 0.254)
		(layers "F.Cu" "B.Cu")
		(net "P3V3_AUX")
	)
	(via
		(at 149.29993 -121.826274)
		(size 0.508)
		(drill 0.254)
		(layers "F.Cu" "B.Cu")
		(net "P3V3_AUX")
	)
	(via
		(at 111.251238 -43.358054)
		(size 0.508)
		(drill 0.254)
		(layers "F.Cu" "B.Cu")
		(net "P3V3_AUX")
	)
	(via
		(at 353.585272 -425.92625)
		(size 0.508)
		(drill 0.254)
		(layers "F.Cu" "B.Cu")
		(net "P3V3_AUX")
	)
	(via
		(at 451.814184 -66.454782)
		(size 0.508)
		(drill 0.254)
		(layers "F.Cu" "B.Cu")
		(net "P3V3_AUX")
	)
	(via
		(at 38.697662 -418.239448)
		(size 0.508)
		(drill 0.254)
		(layers "F.Cu" "B.Cu")
		(net "P3V3_AUX")
	)
	(via
		(at 116.998496 -61.202062)
		(size 0.508)
		(drill 0.254)
		(layers "F.Cu" "B.Cu")
		(net "P3V3_AUX")
	)
	(via
		(at 420.222426 -58.397648)
		(size 0.508)
		(drill 0.254)
		(layers "F.Cu" "B.Cu")
		(net "P3V3_AUX")
	)
	(via
		(at 364.316264 -410.694886)
		(size 0.508)
		(drill 0.254)
		(layers "F.Cu" "B.Cu")
		(net "P3V3_AUX")
	)
	(via
		(at 106.68 -422.89095)
		(size 0.508)
		(drill 0.254)
		(layers "F.Cu" "B.Cu")
		(net "P3V3_AUX")
	)
	(via
		(at 376.89028 -33.63087)
		(size 0.508)
		(drill 0.254)
		(layers "F.Cu" "B.Cu")
		(net "P3V3_AUX")
	)
	(via
		(at 341.33536 -16.995394)
		(size 0.508)
		(drill 0.254)
		(layers "F.Cu" "B.Cu")
		(net "P3V3_AUX")
	)
	(via
		(at 212.725254 -58.329068)
		(size 0.508)
		(drill 0.254)
		(layers "F.Cu" "B.Cu")
		(net "P3V3_AUX")
	)
	(via
		(at 49.17694 -39.103554)
		(size 0.508)
		(drill 0.254)
		(layers "F.Cu" "B.Cu")
		(net "P3V3_AUX")
	)
	(via
		(at 241.09553 -420.40683)
		(size 0.508)
		(drill 0.254)
		(layers "F.Cu" "B.Cu")
		(net "P3V3_AUX")
	)
	(via
		(at 298.495974 -115.148614)
		(size 0.508)
		(drill 0.254)
		(layers "F.Cu" "B.Cu")
		(net "P3V3_AUX")
	)
	(via
		(at 124.860558 -60.48248)
		(size 0.508)
		(drill 0.254)
		(layers "F.Cu" "B.Cu")
		(net "P3V3_AUX")
	)
	(via
		(at 440.807602 -430.39411)
		(size 0.508)
		(drill 0.254)
		(layers "F.Cu" "B.Cu")
		(net "P3V3_AUX")
	)
	(via
		(at 303.724818 -119.479568)
		(size 0.508)
		(drill 0.254)
		(layers "F.Cu" "B.Cu")
		(net "P3V3_AUX")
	)
	(via
		(at 15.18412 -79.467964)
		(size 0.508)
		(drill 0.254)
		(layers "F.Cu" "B.Cu")
		(net "P3V3_AUX")
	)
	(via
		(at 113.283238 -42.2656)
		(size 0.508)
		(drill 0.254)
		(layers "F.Cu" "B.Cu")
		(net "P3V3_AUX")
	)
	(via
		(at 162.77971 -436.799736)
		(size 0.508)
		(drill 0.254)
		(layers "F.Cu" "B.Cu")
		(net "P3V3_AUX")
	)
	(via
		(at 446.2272 -93.484192)
		(size 0.508)
		(drill 0.254)
		(layers "F.Cu" "B.Cu")
		(net "P3V3_AUX")
	)
	(via
		(at 191.911986 -114.262916)
		(size 0.4572)
		(drill 0.254)
		(layers "F.Cu" "B.Cu")
		(net "P3V3_AUX")
	)
	(via
		(at 16.373348 -420.528496)
		(size 0.508)
		(drill 0.254)
		(layers "F.Cu" "B.Cu")
		(net "P3V3_AUX")
	)
	(via
		(at 188.712094 -115.842796)
		(size 0.4572)
		(drill 0.254)
		(layers "F.Cu" "B.Cu")
		(net "P3V3_AUX")
	)
	(via
		(at 69.101716 -203.482448)
		(size 0.508)
		(drill 0.254)
		(layers "F.Cu" "B.Cu")
		(net "P3V3_AUX")
	)
	(via
		(at 253.583186 -121.71045)
		(size 0.508)
		(drill 0.254)
		(layers "F.Cu" "B.Cu")
		(net "P3V3_AUX")
	)
	(via
		(at 137.33653 -55.339996)
		(size 0.508)
		(drill 0.254)
		(layers "F.Cu" "B.Cu")
		(net "P3V3_AUX")
	)
	(via
		(at 136.961118 -62.29858)
		(size 0.508)
		(drill 0.254)
		(layers "F.Cu" "B.Cu")
		(net "P3V3_AUX")
	)
	(via
		(at 193.931032 -72.238616)
		(size 0.508)
		(drill 0.254)
		(layers "F.Cu" "B.Cu")
		(net "P3V3_AUX")
	)
	(via
		(at 184.759092 -193.93535)
		(size 0.4826)
		(drill 0.254)
		(layers "F.Cu" "B.Cu")
		(net "P3V3_AUX")
	)
	(via
		(at 199.898 -103.505)
		(size 0.508)
		(drill 0.254)
		(layers "F.Cu" "B.Cu")
		(net "P3V3_AUX")
	)
	(via
		(at 24.216868 -435.290214)
		(size 0.508)
		(drill 0.254)
		(layers "F.Cu" "B.Cu")
		(net "P3V3_AUX")
	)
	(via
		(at 416.836098 -354.613972)
		(size 0.508)
		(drill 0.254)
		(layers "F.Cu" "B.Cu")
		(net "P3V3_AUX")
	)
	(via
		(at 215.120474 -328.032872)
		(size 0.508)
		(drill 0.254)
		(layers "F.Cu" "B.Cu")
		(net "P3V3_AUX")
	)
	(via
		(at 345.467686 -24.9047)
		(size 0.508)
		(drill 0.254)
		(layers "F.Cu" "B.Cu")
		(net "P3V3_AUX")
	)
	(via
		(at 365.518446 -27.290522)
		(size 0.508)
		(drill 0.254)
		(layers "F.Cu" "B.Cu")
		(net "P3V3_AUX")
	)
	(via
		(at 170.561 -99.278948)
		(size 0.508)
		(drill 0.254)
		(layers "F.Cu" "B.Cu")
		(net "P3V3_AUX")
	)
	(segment
		(start 164.403532 -430.19853)
		(end 164.963856 -429.638206)
		(width 0.4572)
		(layer "B.Cu")
		(net "P3V3_AUX")
	)
	(segment
		(start 159.383984 -19.656044)
		(end 159.383984 -19.044158)
		(width 0.4572)
		(layer "B.Cu")
		(net "P3V3_AUX")
	)
	(segment
		(start 114.73434 -61.36386)
		(end 115.219734 -61.36386)
		(width 0.4572)
		(layer "B.Cu")
		(net "P3V3_AUX")
	)
	(segment
		(start 153.990802 -17.251172)
		(end 153.990802 -18.247868)
		(width 0.4572)
		(layer "B.Cu")
		(net "P3V3_AUX")
	)
	(segment
		(start 187.111894 -113.57356)
		(end 186.822588 -113.862866)
		(width 0.254)
		(layer "B.Cu")
		(net "P3V3_AUX")
	)
	(segment
		(start 323.365622 -203.517246)
		(end 323.386958 -203.517246)
		(width 0.381)
		(layer "B.Cu")
		(net "P3V3_AUX")
	)
	(segment
		(start 60.509912 -193.996564)
		(end 60.571126 -193.93535)
		(width 0.381)
		(layer "B.Cu")
		(net "P3V3_AUX")
	)
	(segment
		(start 437.808116 -429.102774)
		(end 438.620916 -429.102774)
		(width 0.508)
		(layer "B.Cu")
		(net "P3V3_AUX")
	)
	(segment
		(start 169.05097 -193.996564)
		(end 169.112184 -193.93535)
		(width 0.381)
		(layer "B.Cu")
		(net "P3V3_AUX")
	)
	(segment
		(start 244.729 -217.78595)
		(end 244.729 -217.098626)
		(width 0.4572)
		(layer "B.Cu")
		(net "P3V3_AUX")
	)
	(segment
		(start 201.9808 -138.32205)
		(end 202.438 -137.86485)
		(width 0.4572)
		(layer "B.Cu")
		(net "P3V3_AUX")
	)
	(segment
		(start 189.112144 -113.80089)
		(end 189.112144 -113.862866)
		(width 0.254)
		(layer "B.Cu")
		(net "P3V3_AUX")
	)
	(segment
		(start 184.332372 -113.862866)
		(end 183.932322 -114.262916)
		(width 0.254)
		(layer "B.Cu")
		(net "P3V3_AUX")
	)
	(segment
		(start 204.27823 -79.392272)
		(end 204.775562 -78.89494)
		(width 0.381)
		(layer "B.Cu")
		(net "P3V3_AUX")
	)
	(segment
		(start 193.24447 -72.853042)
		(end 193.195956 -72.804528)
		(width 0.3048)
		(layer "B.Cu")
		(net "P3V3_AUX")
	)
	(segment
		(start 152.044908 -18.705068)
		(end 153.2509 -18.705068)
		(width 0.4572)
		(layer "B.Cu")
		(net "P3V3_AUX")
	)
	(segment
		(start 185.058558 -115.842796)
		(end 184.732168 -115.842796)
		(width 0.254)
		(layer "B.Cu")
		(net "P3V3_AUX")
	)
	(segment
		(start 322.676012 -202.827636)
		(end 323.365622 -203.517246)
		(width 0.381)
		(layer "B.Cu")
		(net "P3V3_AUX")
	)
	(segment
		(start 16.985234 -406.70861)
		(end 16.200882 -406.70861)
		(width 0.4572)
		(layer "B.Cu")
		(net "P3V3_AUX")
	)
	(segment
		(start 159.02432 -15.225522)
		(end 158.671006 -14.872208)
		(width 0.4572)
		(layer "B.Cu")
		(net "P3V3_AUX")
	)
	(segment
		(start 178.481482 -414.283144)
		(end 178.481482 -414.96361)
		(width 0.4572)
		(layer "B.Cu")
		(net "P3V3_AUX")
	)
	(segment
		(start 186.711844 -113.86312)
		(end 186.312048 -114.262916)
		(width 0.254)
		(layer "B.Cu")
		(net "P3V3_AUX")
	)
	(segment
		(start 181.932326 -113.99012)
		(end 182.205122 -114.262916)
		(width 0.254)
		(layer "B.Cu")
		(net "P3V3_AUX")
	)
	(segment
		(start 189.112144 -114.662966)
		(end 189.112144 -115.022376)
		(width 0.254)
		(layer "B.Cu")
		(net "P3V3_AUX")
	)
	(segment
		(start 73.129394 -127.112268)
		(end 73.505822 -126.73584)
		(width 0.4572)
		(layer "B.Cu")
		(net "P3V3_AUX")
	)
	(segment
		(start 449.460366 -430.39411)
		(end 440.807602 -430.39411)
		(width 0.508)
		(layer "B.Cu")
		(net "P3V3_AUX")
	)
	(segment
		(start 167.654732 -418.085524)
		(end 167.654732 -418.817806)
		(width 0.4572)
		(layer "B.Cu")
		(net "P3V3_AUX")
	)
	(segment
		(start 104.018842 -419.251892)
		(end 104.507792 -419.251892)
		(width 0.4572)
		(layer "B.Cu")
		(net "P3V3_AUX")
	)
	(segment
		(start 21.526246 -409.44292)
		(end 21.547582 -409.421584)
		(width 0.4572)
		(layer "B.Cu")
		(net "P3V3_AUX")
	)
	(segment
		(start 97.191068 -426.179996)
		(end 97.191068 -426.968666)
		(width 0.4572)
		(layer "B.Cu")
		(net "P3V3_AUX")
	)
	(segment
		(start 180.509164 -24.055832)
		(end 181.525164 -24.055832)
		(width 0.4572)
		(layer "B.Cu")
		(net "P3V3_AUX")
	)
	(segment
		(start 173.301914 -13.816838)
		(end 173.665642 -13.816838)
		(width 0.4572)
		(layer "B.Cu")
		(net "P3V3_AUX")
	)
	(segment
		(start 328.699876 -66.308732)
		(end 328.699876 -65.692782)
		(width 0.4572)
		(layer "B.Cu")
		(net "P3V3_AUX")
	)
	(segment
		(start 145.331434 -204.079602)
		(end 145.331434 -204.605128)
		(width 0.508)
		(layer "B.Cu")
		(net "P3V3_AUX")
	)
	(segment
		(start 171.577 -99.894898)
		(end 171.17695 -99.894898)
		(width 0.3048)
		(layer "B.Cu")
		(net "P3V3_AUX")
	)
	(segment
		(start 184.785 -99.894898)
		(end 184.823354 -99.856544)
		(width 0.381)
		(layer "B.Cu")
		(net "P3V3_AUX")
	)
	(segment
		(start 187.111894 -111.86287)
		(end 186.993276 -111.86287)
		(width 0.254)
		(layer "B.Cu")
		(net "P3V3_AUX")
	)
	(segment
		(start 292.608 -425.68495)
		(end 292.96995 -425.68495)
		(width 0.4572)
		(layer "B.Cu")
		(net "P3V3_AUX")
	)
	(segment
		(start 33.0454 -426.850302)
		(end 32.91078 -426.984922)
		(width 0.381)
		(layer "B.Cu")
		(net "P3V3_AUX")
	)
	(segment
		(start 185.458608 -116.242846)
		(end 185.058558 -115.842796)
		(width 0.254)
		(layer "B.Cu")
		(net "P3V3_AUX")
	)
	(segment
		(start 183.85282 -24.39162)
		(end 183.85282 -28.28798)
		(width 0.4572)
		(layer "B.Cu")
		(net "P3V3_AUX")
	)
	(segment
		(start 75.51801 -147.544536)
		(end 75.64501 -147.417536)
		(width 0.508)
		(layer "B.Cu")
		(net "P3V3_AUX")
	)
	(segment
		(start 188.712094 -116.642642)
		(end 188.712094 -117.442742)
		(width 0.254)
		(layer "B.Cu")
		(net "P3V3_AUX")
	)
	(segment
		(start 147.248118 -206.521812)
		(end 147.680934 -206.521812)
		(width 0.508)
		(layer "B.Cu")
		(net "P3V3_AUX")
	)
	(segment
		(start 291.92474 -193.99631)
		(end 292.803072 -193.99631)
		(width 0.381)
		(layer "B.Cu")
		(net "P3V3_AUX")
	)
	(segment
		(start 158.840678 -16.553942)
		(end 159.02432 -16.3703)
		(width 0.4572)
		(layer "B.Cu")
		(net "P3V3_AUX")
	)
	(segment
		(start 52.74564 -426.403262)
		(end 52.782978 -426.4406)
		(width 0.381)
		(layer "B.Cu")
		(net "P3V3_AUX")
	)
	(segment
		(start 270.171164 -193.99631)
		(end 270.232378 -193.935096)
		(width 0.381)
		(layer "B.Cu")
		(net "P3V3_AUX")
	)
	(segment
		(start 277.051008 -193.781934)
		(end 278.18207 -193.781934)
		(width 0.381)
		(layer "B.Cu")
		(net "P3V3_AUX")
	)
	(segment
		(start 342.923876 -66.308732)
		(end 342.923876 -65.692782)
		(width 0.4572)
		(layer "B.Cu")
		(net "P3V3_AUX")
	)
	(segment
		(start 439.6232 -193.99631)
		(end 439.684414 -193.935096)
		(width 0.381)
		(layer "B.Cu")
		(net "P3V3_AUX")
	)
	(segment
		(start 184.735724 -111.866426)
		(end 184.732168 -111.86287)
		(width 0.254)
		(layer "B.Cu")
		(net "P3V3_AUX")
	)
	(segment
		(start 446.288668 -193.99631)
		(end 447.167254 -193.99631)
		(width 0.381)
		(layer "B.Cu")
		(net "P3V3_AUX")
	)
	(segment
		(start 319.137538 -203.331826)
		(end 319.322958 -203.517246)
		(width 0.381)
		(layer "B.Cu")
		(net "P3V3_AUX")
	)
	(segment
		(start 184.732168 -114.62258)
		(end 184.332372 -115.022376)
		(width 0.254)
		(layer "B.Cu")
		(net "P3V3_AUX")
	)
	(segment
		(start 185.858658 -115.842796)
		(end 185.458608 -116.242846)
		(width 0.254)
		(layer "B.Cu")
		(net "P3V3_AUX")
	)
	(segment
		(start 185.081164 -418.591238)
		(end 185.704226 -418.591238)
		(width 0.381)
		(layer "B.Cu")
		(net "P3V3_AUX")
	)
	(segment
		(start 340.891876 -66.308732)
		(end 340.891876 -65.692782)
		(width 0.4572)
		(layer "B.Cu")
		(net "P3V3_AUX")
	)
	(segment
		(start 438.744614 -193.99631)
		(end 439.6232 -193.99631)
		(width 0.381)
		(layer "B.Cu")
		(net "P3V3_AUX")
	)
	(segment
		(start 105.13695 -421.005)
		(end 104.521 -421.005)
		(width 0.4572)
		(layer "B.Cu")
		(net "P3V3_AUX")
	)
	(segment
		(start 233.013758 -223.997266)
		(end 231.958134 -223.997266)
		(width 0.4572)
		(layer "B.Cu")
		(net "P3V3_AUX")
	)
	(segment
		(start 173.665642 -13.816838)
		(end 174.011082 -14.162278)
		(width 0.4572)
		(layer "B.Cu")
		(net "P3V3_AUX")
	)
	(segment
		(start 193.195956 -72.804528)
		(end 193.195956 -72.1614)
		(width 0.3048)
		(layer "B.Cu")
		(net "P3V3_AUX")
	)
	(segment
		(start 191.382904 -80.37449)
		(end 191.382904 -80.555592)
		(width 0.4572)
		(layer "B.Cu")
		(net "P3V3_AUX")
	)
	(segment
		(start 207.91805 -71.480426)
		(end 208.568544 -71.480426)
		(width 0.4064)
		(layer "B.Cu")
		(net "P3V3_AUX")
	)
	(segment
		(start 191.744346 -193.93535)
		(end 192.303146 -193.93535)
		(width 0.381)
		(layer "B.Cu")
		(net "P3V3_AUX")
	)
	(segment
		(start 168.36644 -16.729964)
		(end 169.029126 -16.067278)
		(width 0.4572)
		(layer "B.Cu")
		(net "P3V3_AUX")
	)
	(segment
		(start 172.056044 -414.792668)
		(end 171.18584 -414.792668)
		(width 0.4572)
		(layer "B.Cu")
		(net "P3V3_AUX")
	)
	(segment
		(start 298.565316 -426.128942)
		(end 298.565316 -427.19244)
		(width 0.254)
		(layer "B.Cu")
		(net "P3V3_AUX")
	)
	(segment
		(start 181.932326 -115.443)
		(end 182.332122 -115.842796)
		(width 0.254)
		(layer "B.Cu")
		(net "P3V3_AUX")
	)
	(segment
		(start 428.5869 -33.467548)
		(end 427.97095 -33.467548)
		(width 0.4064)
		(layer "B.Cu")
		(net "P3V3_AUX")
	)
	(segment
		(start 319.137538 -202.902312)
		(end 319.137538 -203.331826)
		(width 0.381)
		(layer "B.Cu")
		(net "P3V3_AUX")
	)
	(segment
		(start 146.369532 -17.725898)
		(end 147.208494 -18.56486)
		(width 0.4572)
		(layer "B.Cu")
		(net "P3V3_AUX")
	)
	(segment
		(start 183.557164 -24.055832)
		(end 183.557164 -24.095964)
		(width 0.4572)
		(layer "B.Cu")
		(net "P3V3_AUX")
	)
	(segment
		(start 177.382932 -414.435544)
		(end 177.836322 -414.435544)
		(width 0.4572)
		(layer "B.Cu")
		(net "P3V3_AUX")
	)
	(segment
		(start 184.139078 -193.996564)
		(end 184.200292 -193.93535)
		(width 0.381)
		(layer "B.Cu")
		(net "P3V3_AUX")
	)
	(segment
		(start 331.239114 -136.474962)
		(end 330.618084 -136.474962)
		(width 0.508)
		(layer "B.Cu")
		(net "P3V3_AUX")
	)
	(segment
		(start 174.26305 -420.243)
		(end 174.26305 -420.898828)
		(width 0.4572)
		(layer "B.Cu")
		(net "P3V3_AUX")
	)
	(segment
		(start 181.932326 -116.162074)
		(end 181.932326 -116.242846)
		(width 0.254)
		(layer "B.Cu")
		(net "P3V3_AUX")
	)
	(segment
		(start 186.711844 -113.862866)
		(end 187.111894 -114.262916)
		(width 0.254)
		(layer "B.Cu")
		(net "P3V3_AUX")
	)
	(segment
		(start 284.710124 -193.666872)
		(end 285.610808 -193.666872)
		(width 0.381)
		(layer "B.Cu")
		(net "P3V3_AUX")
	)
	(segment
		(start 22.29231 -193.93535)
		(end 22.85111 -193.93535)
		(width 0.381)
		(layer "B.Cu")
		(net "P3V3_AUX")
	)
	(segment
		(start 198.374 -141.12621)
		(end 198.978012 -140.522198)
		(width 0.4572)
		(layer "B.Cu")
		(net "P3V3_AUX")
	)
	(segment
		(start 270.232378 -193.935096)
		(end 270.791178 -193.935096)
		(width 0.381)
		(layer "B.Cu")
		(net "P3V3_AUX")
	)
	(segment
		(start 201.041 -139.51204)
		(end 201.041 -138.32205)
		(width 0.4572)
		(layer "B.Cu")
		(net "P3V3_AUX")
	)
	(segment
		(start 174.317914 -14.162278)
		(end 174.317914 -14.468348)
		(width 0.4572)
		(layer "B.Cu")
		(net "P3V3_AUX")
	)
	(segment
		(start 182.332122 -112.663224)
		(end 181.532276 -113.46307)
		(width 0.254)
		(layer "B.Cu")
		(net "P3V3_AUX")
	)
	(segment
		(start 193.929 -99.894898)
		(end 193.929 -99.278948)
		(width 0.381)
		(layer "B.Cu")
		(net "P3V3_AUX")
	)
	(segment
		(start 87.585042 -308.759606)
		(end 87.585042 -305.926744)
		(width 0.508)
		(layer "B.Cu")
		(net "P3V3_AUX")
	)
	(segment
		(start 102.528878 -139.53236)
		(end 102.528878 -138.91641)
		(width 0.381)
		(layer "B.Cu")
		(net "P3V3_AUX")
	)
	(segment
		(start 32.91078 -426.984922)
		(end 32.5374 -426.984922)
		(width 0.381)
		(layer "B.Cu")
		(net "P3V3_AUX")
	)
	(segment
		(start 385.256278 -137.135108)
		(end 385.256278 -136.519158)
		(width 0.381)
		(layer "B.Cu")
		(net "P3V3_AUX")
	)
	(segment
		(start 103.759 -418.99205)
		(end 104.018842 -419.251892)
		(width 0.4572)
		(layer "B.Cu")
		(net "P3V3_AUX")
	)
	(segment
		(start 460.005938 -43.400726)
		(end 459.389988 -43.400726)
		(width 0.4572)
		(layer "B.Cu")
		(net "P3V3_AUX")
	)
	(segment
		(start 189.112144 -113.985802)
		(end 188.83503 -114.262916)
		(width 0.254)
		(layer "B.Cu")
		(net "P3V3_AUX")
	)
	(segment
		(start 174.26305 -420.243)
		(end 174.900844 -420.243)
		(width 0.3556)
		(layer "B.Cu")
		(net "P3V3_AUX")
	)
	(segment
		(start 46.434502 -422.928034)
		(end 46.434502 -423.905934)
		(width 0.4572)
		(layer "B.Cu")
		(net "P3V3_AUX")
	)
	(segment
		(start 168.155366 -355.911404)
		(end 165.576758 -353.332796)
		(width 0.508)
		(layer "B.Cu")
		(net "P3V3_AUX")
	)
	(segment
		(start 181.182518 -414.15081)
		(end 180.669692 -414.663636)
		(width 0.4572)
		(layer "B.Cu")
		(net "P3V3_AUX")
	)
	(segment
		(start 186.711844 -112.263174)
		(end 186.711844 -112.262666)
		(width 0.254)
		(layer "B.Cu")
		(net "P3V3_AUX")
	)
	(segment
		(start 298.565316 -427.19244)
		(end 298.634404 -427.261528)
		(width 0.254)
		(layer "B.Cu")
		(net "P3V3_AUX")
	)
	(segment
		(start 167.777668 -417.962588)
		(end 167.654732 -418.085524)
		(width 0.4572)
		(layer "B.Cu")
		(net "P3V3_AUX")
	)
	(segment
		(start 438.620916 -429.219106)
		(end 438.620916 -429.102774)
		(width 0.508)
		(layer "B.Cu")
		(net "P3V3_AUX")
	)
	(segment
		(start 59.801252 -193.996564)
		(end 60.509912 -193.996564)
		(width 0.381)
		(layer "B.Cu")
		(net "P3V3_AUX")
	)
	(segment
		(start 163.246816 -436.33263)
		(end 162.77971 -436.799736)
		(width 0.4572)
		(layer "B.Cu")
		(net "P3V3_AUX")
	)
	(segment
		(start 184.823354 -99.856544)
		(end 184.823354 -99.317302)
		(width 0.381)
		(layer "B.Cu")
		(net "P3V3_AUX")
	)
	(segment
		(start 439.79592 -430.39411)
		(end 438.620916 -429.219106)
		(width 0.508)
		(layer "B.Cu")
		(net "P3V3_AUX")
	)
	(segment
		(start 310.411876 -79.175864)
		(end 310.411876 -79.810864)
		(width 0.4572)
		(layer "B.Cu")
		(net "P3V3_AUX")
	)
	(segment
		(start 449.843652 -430.010824)
		(end 449.460366 -430.39411)
		(width 0.508)
		(layer "B.Cu")
		(net "P3V3_AUX")
	)
	(segment
		(start 416.112452 -193.99631)
		(end 416.991038 -193.99631)
		(width 0.381)
		(layer "B.Cu")
		(net "P3V3_AUX")
	)
	(segment
		(start 168.172384 -193.996564)
		(end 169.05097 -193.996564)
		(width 0.381)
		(layer "B.Cu")
		(net "P3V3_AUX")
	)
	(segment
		(start 324.635876 -66.308732)
		(end 324.635876 -65.692782)
		(width 0.4572)
		(layer "B.Cu")
		(net "P3V3_AUX")
	)
	(segment
		(start 110.97895 -418.211)
		(end 110.97895 -418.973)
		(width 0.4572)
		(layer "B.Cu")
		(net "P3V3_AUX")
	)
	(segment
		(start 172.593 -99.894898)
		(end 171.577 -99.894898)
		(width 0.3048)
		(layer "B.Cu")
		(net "P3V3_AUX")
	)
	(segment
		(start 431.8762 -193.795904)
		(end 432.559968 -193.795904)
		(width 0.381)
		(layer "B.Cu")
		(net "P3V3_AUX")
	)
	(segment
		(start 175.86706 -427.92269)
		(end 175.86706 -428.648876)
		(width 0.4572)
		(layer "B.Cu")
		(net "P3V3_AUX")
	)
	(segment
		(start 322.603876 -66.308732)
		(end 322.603876 -65.692782)
		(width 0.4572)
		(layer "B.Cu")
		(net "P3V3_AUX")
	)
	(segment
		(start 437.984138 -424.784774)
		(end 437.962802 -424.80611)
		(width 0.4572)
		(layer "B.Cu")
		(net "P3V3_AUX")
	)
	(segment
		(start 52.782978 -430.24298)
		(end 52.782978 -430.887886)
		(width 0.381)
		(layer "B.Cu")
		(net "P3V3_AUX")
	)
	(segment
		(start 163.31184 -432.700938)
		(end 162.73526 -432.700938)
		(width 0.4572)
		(layer "B.Cu")
		(net "P3V3_AUX")
	)
	(segment
		(start 163.387532 -436.33263)
		(end 163.246816 -436.33263)
		(width 0.4572)
		(layer "B.Cu")
		(net "P3V3_AUX")
	)
	(segment
		(start 171.30395 -98.535998)
		(end 170.561 -99.278948)
		(width 0.3048)
		(layer "B.Cu")
		(net "P3V3_AUX")
	)
	(segment
		(start 10.337292 -404.21687)
		(end 9.666732 -404.21687)
		(width 0.4572)
		(layer "B.Cu")
		(net "P3V3_AUX")
	)
	(segment
		(start 438.620916 -429.102774)
		(end 438.620916 -427.089824)
		(width 0.508)
		(layer "B.Cu")
		(net "P3V3_AUX")
	)
	(segment
		(start 185.058558 -114.262916)
		(end 185.458608 -113.862866)
		(width 0.254)
		(layer "B.Cu")
		(net "P3V3_AUX")
	)
	(segment
		(start 188.774324 -113.46307)
		(end 189.112144 -113.80089)
		(width 0.254)
		(layer "B.Cu")
		(net "P3V3_AUX")
	)
	(segment
		(start 194.056 -29.845)
		(end 192.542922 -31.358078)
		(width 0.508)
		(layer "B.Cu")
		(net "P3V3_AUX")
	)
	(segment
		(start 318.539876 -66.308732)
		(end 318.539876 -65.692782)
		(width 0.4572)
		(layer "B.Cu")
		(net "P3V3_AUX")
	)
	(segment
		(start 181.932326 -113.862866)
		(end 181.932326 -113.99012)
		(width 0.254)
		(layer "B.Cu")
		(net "P3V3_AUX")
	)
	(segment
		(start 22.231096 -193.996564)
		(end 22.29231 -193.93535)
		(width 0.381)
		(layer "B.Cu")
		(net "P3V3_AUX")
	)
	(segment
		(start 424.596306 -193.935096)
		(end 425.155106 -193.935096)
		(width 0.381)
		(layer "B.Cu")
		(net "P3V3_AUX")
	)
	(segment
		(start 150.988776 -18.093944)
		(end 151.433784 -18.093944)
		(width 0.4572)
		(layer "B.Cu")
		(net "P3V3_AUX")
	)
	(segment
		(start 164.215318 -416.663886)
		(end 164.49802 -416.946588)
		(width 0.4572)
		(layer "B.Cu")
		(net "P3V3_AUX")
	)
	(segment
		(start 188.712094 -113.46307)
		(end 188.774324 -113.46307)
		(width 0.254)
		(layer "B.Cu")
		(net "P3V3_AUX")
	)
	(segment
		(start 121.066306 -80.137508)
		(end 121.703592 -80.137508)
		(width 0.4572)
		(layer "B.Cu")
		(net "P3V3_AUX")
	)
	(segment
		(start 192.287652 -79.80299)
		(end 191.954404 -79.80299)
		(width 0.4572)
		(layer "B.Cu")
		(net "P3V3_AUX")
	)
	(segment
		(start 184.732168 -115.422172)
		(end 184.732168 -115.842796)
		(width 0.254)
		(layer "B.Cu")
		(net "P3V3_AUX")
	)
	(segment
		(start 68.515484 -203.298552)
		(end 68.318634 -203.101702)
		(width 0.381)
		(layer "B.Cu")
		(net "P3V3_AUX")
	)
	(segment
		(start 212.725 -57.461658)
		(end 212.725 -58.328814)
		(width 0.4572)
		(layer "B.Cu")
		(net "P3V3_AUX")
	)
	(segment
		(start 163.359084 -8.613394)
		(end 162.321494 -8.613394)
		(width 0.4064)
		(layer "B.Cu")
		(net "P3V3_AUX")
	)
	(segment
		(start 174.580296 -421.216074)
		(end 174.26305 -420.898828)
		(width 0.4572)
		(layer "B.Cu")
		(net "P3V3_AUX")
	)
	(segment
		(start 232.857802 -250.642628)
		(end 233.495088 -250.642628)
		(width 0.4572)
		(layer "B.Cu")
		(net "P3V3_AUX")
	)
	(segment
		(start 176.556924 -193.996564)
		(end 176.618138 -193.93535)
		(width 0.4572)
		(layer "B.Cu")
		(net "P3V3_AUX")
	)
	(segment
		(start 117.141244 -415.51225)
		(end 117.141244 -415.196274)
		(width 0.3556)
		(layer "B.Cu")
		(net "P3V3_AUX")
	)
	(segment
		(start 162.621468 -416.547554)
		(end 161.60496 -415.531046)
		(width 0.381)
		(layer "B.Cu")
		(net "P3V3_AUX")
	)
	(segment
		(start 155.02001 -17.251172)
		(end 153.990802 -17.251172)
		(width 0.4572)
		(layer "B.Cu")
		(net "P3V3_AUX")
	)
	(segment
		(start 36.567872 -193.790062)
		(end 37.793676 -193.790062)
		(width 0.508)
		(layer "B.Cu")
		(net "P3V3_AUX")
	)
	(segment
		(start 50.975768 -434.082952)
		(end 50.760122 -434.298598)
		(width 0.381)
		(layer "B.Cu")
		(net "P3V3_AUX")
	)
	(segment
		(start 172.593 -98.535998)
		(end 173.609 -98.535998)
		(width 0.3048)
		(layer "B.Cu")
		(net "P3V3_AUX")
	)
	(segment
		(start 330.618084 -136.474962)
		(end 330.617068 -136.473946)
		(width 0.508)
		(layer "B.Cu")
		(net "P3V3_AUX")
	)
	(segment
		(start 172.056044 -415.808668)
		(end 172.056044 -414.792668)
		(width 0.4572)
		(layer "B.Cu")
		(net "P3V3_AUX")
	)
	(segment
		(start 169.286428 -424.117262)
		(end 170.372786 -424.117262)
		(width 0.3048)
		(layer "B.Cu")
		(net "P3V3_AUX")
	)
	(segment
		(start 304.01895 -359.283)
		(end 303.276 -359.283)
		(width 0.4572)
		(layer "B.Cu")
		(net "P3V3_AUX")
	)
	(segment
		(start 187.111894 -115.842796)
		(end 187.111894 -116.642642)
		(width 0.254)
		(layer "B.Cu")
		(net "P3V3_AUX")
	)
	(segment
		(start 20.743418 -409.44292)
		(end 21.526246 -409.44292)
		(width 0.4572)
		(layer "B.Cu")
		(net "P3V3_AUX")
	)
	(segment
		(start 424.535092 -193.99631)
		(end 424.596306 -193.935096)
		(width 0.381)
		(layer "B.Cu")
		(net "P3V3_AUX")
	)
	(segment
		(start 16.200882 -406.70861)
		(end 16.043402 -406.86609)
		(width 0.4572)
		(layer "B.Cu")
		(net "P3V3_AUX")
	)
	(segment
		(start 204.775562 -78.89494)
		(end 204.841094 -78.89494)
		(width 0.381)
		(layer "B.Cu")
		(net "P3V3_AUX")
	)
	(segment
		(start 161.313368 -324.383908)
		(end 161.313368 -324.86346)
		(width 0.508)
		(layer "B.Cu")
		(net "P3V3_AUX")
	)
	(segment
		(start 429.103282 -436.014622)
		(end 429.583088 -436.014622)
		(width 0.4572)
		(layer "B.Cu")
		(net "P3V3_AUX")
	)
	(segment
		(start 115.219734 -61.36386)
		(end 115.677188 -61.821314)
		(width 0.4572)
		(layer "B.Cu")
		(net "P3V3_AUX")
	)
	(segment
		(start 189.112144 -115.442746)
		(end 188.712094 -115.842796)
		(width 0.254)
		(layer "B.Cu")
		(net "P3V3_AUX")
	)
	(segment
		(start 447.228468 -193.935096)
		(end 447.787268 -193.935096)
		(width 0.381)
		(layer "B.Cu")
		(net "P3V3_AUX")
	)
	(segment
		(start 189.24905 -422.402)
		(end 189.24905 -423.08145)
		(width 0.4572)
		(layer "B.Cu")
		(net "P3V3_AUX")
	)
	(segment
		(start 437.962802 -424.80611)
		(end 437.141366 -425.627546)
		(width 0.508)
		(layer "B.Cu")
		(net "P3V3_AUX")
	)
	(segment
		(start 174.317914 -14.468348)
		(end 174.502572 -14.653006)
		(width 0.4572)
		(layer "B.Cu")
		(net "P3V3_AUX")
	)
	(segment
		(start 170.636692 -432.953668)
		(end 170.636692 -431.949098)
		(width 0.4572)
		(layer "B.Cu")
		(net "P3V3_AUX")
	)
	(segment
		(start 440.807602 -430.39411)
		(end 439.79592 -430.39411)
		(width 0.508)
		(layer "B.Cu")
		(net "P3V3_AUX")
	)
	(segment
		(start 330.731876 -66.308732)
		(end 330.731876 -65.692782)
		(width 0.4572)
		(layer "B.Cu")
		(net "P3V3_AUX")
	)
	(segment
		(start 172.210222 -419.925754)
		(end 171.912788 -419.62832)
		(width 0.4572)
		(layer "B.Cu")
		(net "P3V3_AUX")
	)
	(segment
		(start 241.938048 -289.133788)
		(end 241.743992 -288.939732)
		(width 0.4572)
		(layer "B.Cu")
		(net "P3V3_AUX")
	)
	(segment
		(start 181.932072 -113.862866)
		(end 181.532276 -113.46307)
		(width 0.254)
		(layer "B.Cu")
		(net "P3V3_AUX")
	)
	(segment
		(start 36.440618 -193.9798)
		(end 36.440618 -193.917316)
		(width 0.508)
		(layer "B.Cu")
		(net "P3V3_AUX")
	)
	(segment
		(start 181.525164 -24.055832)
		(end 182.541164 -24.055832)
		(width 0.4572)
		(layer "B.Cu")
		(net "P3V3_AUX")
	)
	(segment
		(start 186.312048 -114.62258)
		(end 186.711844 -115.022376)
		(width 0.254)
		(layer "B.Cu")
		(net "P3V3_AUX")
	)
	(segment
		(start 69.101716 -203.482448)
		(end 68.91782 -203.298552)
		(width 0.381)
		(layer "B.Cu")
		(net "P3V3_AUX")
	)
	(segment
		(start 332.763876 -66.308732)
		(end 332.763876 -65.692782)
		(width 0.4572)
		(layer "B.Cu")
		(net "P3V3_AUX")
	)
	(segment
		(start 156.67101 -17.251172)
		(end 155.02001 -17.251172)
		(width 0.4572)
		(layer "B.Cu")
		(net "P3V3_AUX")
	)
	(segment
		(start 292.96995 -425.68495)
		(end 293.243 -425.958)
		(width 0.4572)
		(layer "B.Cu")
		(net "P3V3_AUX")
	)
	(segment
		(start 224.786444 -50.502566)
		(end 232.148126 -50.502566)
		(width 0.381)
		(layer "B.Cu")
		(net "P3V3_AUX")
	)
	(segment
		(start 162.321494 -8.613394)
		(end 162.17646 -8.46836)
		(width 0.4064)
		(layer "B.Cu")
		(net "P3V3_AUX")
	)
	(segment
		(start 320.664078 -202.898756)
		(end 320.735198 -202.827636)
		(width 0.381)
		(layer "B.Cu")
		(net "P3V3_AUX")
	)
	(segment
		(start 241.173 -221.84995)
		(end 241.173 -221.107)
		(width 0.381)
		(layer "B.Cu")
		(net "P3V3_AUX")
	)
	(segment
		(start 202.438 -136.4742)
		(end 200.43775 -134.47395)
		(width 0.4572)
		(layer "B.Cu")
		(net "P3V3_AUX")
	)
	(segment
		(start 454.622408 -193.935096)
		(end 455.331068 -193.935096)
		(width 0.4572)
		(layer "B.Cu")
		(net "P3V3_AUX")
	)
	(segment
		(start 431.20056 -193.99631)
		(end 431.39233 -193.99631)
		(width 0.381)
		(layer "B.Cu")
		(net "P3V3_AUX")
	)
	(segment
		(start 169.112184 -193.93535)
		(end 169.670984 -193.93535)
		(width 0.381)
		(layer "B.Cu")
		(net "P3V3_AUX")
	)
	(segment
		(start 175.767238 -419.376606)
		(end 176.071022 -419.376606)
		(width 0.3556)
		(layer "B.Cu")
		(net "P3V3_AUX")
	)
	(segment
		(start 170.372786 -424.117262)
		(end 170.424348 -424.0657)
		(width 0.3048)
		(layer "B.Cu")
		(net "P3V3_AUX")
	)
	(segment
		(start 421.92575 -428.757334)
		(end 421.92575 -429.450754)
		(width 0.254)
		(layer "B.Cu")
		(net "P3V3_AUX")
	)
	(segment
		(start 105.537 -424.815)
		(end 104.92105 -424.815)
		(width 0.4572)
		(layer "B.Cu")
		(net "P3V3_AUX")
	)
	(segment
		(start 112.4204 -414.02)
		(end 113.2332 -414.8328)
		(width 0.4572)
		(layer "B.Cu")
		(net "P3V3_AUX")
	)
	(segment
		(start 117.141244 -415.196274)
		(end 116.888514 -414.943544)
		(width 0.3556)
		(layer "B.Cu")
		(net "P3V3_AUX")
	)
	(segment
		(start 171.440602 -8.462518)
		(end 172.078904 -8.462518)
		(width 0.4572)
		(layer "B.Cu")
		(net "P3V3_AUX")
	)
	(segment
		(start 171.912788 -419.62832)
		(end 171.912788 -419.206426)
		(width 0.4572)
		(layer "B.Cu")
		(net "P3V3_AUX")
	)
	(segment
		(start 320.735198 -202.827636)
		(end 322.676012 -202.827636)
		(width 0.381)
		(layer "B.Cu")
		(net "P3V3_AUX")
	)
	(segment
		(start 30.16504 -193.705226)
		(end 30.395164 -193.93535)
		(width 0.381)
		(layer "B.Cu")
		(net "P3V3_AUX")
	)
	(segment
		(start 88.105234 -305.406552)
		(end 90.772234 -305.406552)
		(width 0.508)
		(layer "B.Cu")
		(net "P3V3_AUX")
	)
	(segment
		(start 175.107092 -421.216074)
		(end 174.580296 -421.216074)
		(width 0.4572)
		(layer "B.Cu")
		(net "P3V3_AUX")
	)
	(segment
		(start 37.793676 -193.790062)
		(end 37.938964 -193.93535)
		(width 0.508)
		(layer "B.Cu")
		(net "P3V3_AUX")
	)
	(segment
		(start 181.932326 -113.862866)
		(end 181.932072 -113.862866)
		(width 0.254)
		(layer "B.Cu")
		(net "P3V3_AUX")
	)
	(segment
		(start 163.387532 -433.75453)
		(end 163.387532 -432.77663)
		(width 0.4572)
		(layer "B.Cu")
		(net "P3V3_AUX")
	)
	(segment
		(start 181.297834 -420.97706)
		(end 181.297834 -420.351458)
		(width 0.4572)
		(layer "B.Cu")
		(net "P3V3_AUX")
	)
	(segment
		(start 181.932326 -114.662712)
		(end 181.932326 -115.022376)
		(width 0.254)
		(layer "B.Cu")
		(net "P3V3_AUX")
	)
	(segment
		(start 240.157 -237.230666)
		(end 239.509554 -237.230666)
		(width 0.254)
		(layer "B.Cu")
		(net "P3V3_AUX")
	)
	(segment
		(start 187.911994 -111.86287)
		(end 187.7695 -111.720376)
		(width 0.254)
		(layer "B.Cu")
		(net "P3V3_AUX")
	)
	(segment
		(start 186.711844 -112.262666)
		(end 186.312048 -111.86287)
		(width 0.254)
		(layer "B.Cu")
		(net "P3V3_AUX")
	)
	(segment
		(start 269.292578 -193.99631)
		(end 270.171164 -193.99631)
		(width 0.381)
		(layer "B.Cu")
		(net "P3V3_AUX")
	)
	(segment
		(start 86.872064 -309.472584)
		(end 87.585042 -308.759606)
		(width 0.508)
		(layer "B.Cu")
		(net "P3V3_AUX")
	)
	(segment
		(start 190.582296 -35.017456)
		(end 190.810134 -35.017456)
		(width 0.4572)
		(layer "B.Cu")
		(net "P3V3_AUX")
	)
	(segment
		(start 159.02432 -16.3703)
		(end 159.02432 -15.225522)
		(width 0.4572)
		(layer "B.Cu")
		(net "P3V3_AUX")
	)
	(segment
		(start 193.460116 -25.565862)
		(end 194.056 -26.161746)
		(width 0.508)
		(layer "B.Cu")
		(net "P3V3_AUX")
	)
	(segment
		(start 161.313368 -324.86346)
		(end 161.627058 -325.17715)
		(width 0.508)
		(layer "B.Cu")
		(net "P3V3_AUX")
	)
	(segment
		(start 184.823354 -99.317302)
		(end 184.785 -99.278948)
		(width 0.381)
		(layer "B.Cu")
		(net "P3V3_AUX")
	)
	(segment
		(start 237.910878 -290.844732)
		(end 237.041436 -290.844732)
		(width 0.4572)
		(layer "B.Cu")
		(net "P3V3_AUX")
	)
	(segment
		(start 198.978012 -140.522198)
		(end 200.812908 -140.522198)
		(width 0.4572)
		(layer "B.Cu")
		(net "P3V3_AUX")
	)
	(segment
		(start 292.864286 -193.935096)
		(end 293.423086 -193.935096)
		(width 0.381)
		(layer "B.Cu")
		(net "P3V3_AUX")
	)
	(segment
		(start 112.65662 -61.61786)
		(end 112.85474 -61.81598)
		(width 0.4572)
		(layer "B.Cu")
		(net "P3V3_AUX")
	)
	(segment
		(start 338.859876 -66.308732)
		(end 338.859876 -65.692782)
		(width 0.4572)
		(layer "B.Cu")
		(net "P3V3_AUX")
	)
	(segment
		(start 432.559968 -193.795904)
		(end 432.69916 -193.935096)
		(width 0.381)
		(layer "B.Cu")
		(net "P3V3_AUX")
	)
	(segment
		(start 160.103312 -416.176206)
		(end 160.198308 -416.08121)
		(width 0.3302)
		(layer "B.Cu")
		(net "P3V3_AUX")
	)
	(segment
		(start 172.570902 -419.925754)
		(end 172.210222 -419.925754)
		(width 0.4572)
		(layer "B.Cu")
		(net "P3V3_AUX")
	)
	(segment
		(start 209.992468 -120.944386)
		(end 210.035648 -120.901206)
		(width 0.4572)
		(layer "B.Cu")
		(net "P3V3_AUX")
	)
	(segment
		(start 185.858658 -114.262916)
		(end 186.312048 -114.262916)
		(width 0.254)
		(layer "B.Cu")
		(net "P3V3_AUX")
	)
	(segment
		(start 191.683132 -193.996564)
		(end 191.744346 -193.93535)
		(width 0.381)
		(layer "B.Cu")
		(net "P3V3_AUX")
	)
	(segment
		(start 428.5869 -34.737548)
		(end 427.97095 -34.737548)
		(width 0.4064)
		(layer "B.Cu")
		(net "P3V3_AUX")
	)
	(segment
		(start 237.06963 -224.115884)
		(end 237.690406 -224.73666)
		(width 0.4572)
		(layer "B.Cu")
		(net "P3V3_AUX")
	)
	(segment
		(start 144.102582 -17.713198)
		(end 144.115282 -17.725898)
		(width 0.4572)
		(layer "B.Cu")
		(net "P3V3_AUX")
	)
	(segment
		(start 229.576122 -228.543358)
		(end 230.378 -228.543358)
		(width 0.381)
		(layer "B.Cu")
		(net "P3V3_AUX")
	)
	(segment
		(start 181.182518 -413.349694)
		(end 181.182518 -414.15081)
		(width 0.4572)
		(layer "B.Cu")
		(net "P3V3_AUX")
	)
	(segment
		(start 114.273584 -418.110416)
		(end 113.284 -419.1)
		(width 0.3556)
		(layer "B.Cu")
		(net "P3V3_AUX")
	)
	(segment
		(start 24.36495 -362.204)
		(end 23.622 -362.204)
		(width 0.4572)
		(layer "B.Cu")
		(net "P3V3_AUX")
	)
	(segment
		(start 181.182518 -415.176462)
		(end 180.669692 -414.663636)
		(width 0.4572)
		(layer "B.Cu")
		(net "P3V3_AUX")
	)
	(segment
		(start 188.712094 -112.66297)
		(end 188.712094 -113.46307)
		(width 0.254)
		(layer "B.Cu")
		(net "P3V3_AUX")
	)
	(segment
		(start 185.458608 -111.866426)
		(end 184.735724 -111.866426)
		(width 0.254)
		(layer "B.Cu")
		(net "P3V3_AUX")
	)
	(segment
		(start 104.648 -416.32505)
		(end 105.283 -416.32505)
		(width 0.4572)
		(layer "B.Cu")
		(net "P3V3_AUX")
	)
	(segment
		(start 336.827876 -66.308732)
		(end 336.827876 -65.692782)
		(width 0.4572)
		(layer "B.Cu")
		(net "P3V3_AUX")
	)
	(segment
		(start 36.440618 -193.917316)
		(end 36.567872 -193.790062)
		(width 0.508)
		(layer "B.Cu")
		(net "P3V3_AUX")
	)
	(segment
		(start 116.078 -418.35705)
		(end 116.078 -419.1)
		(width 0.4572)
		(layer "B.Cu")
		(net "P3V3_AUX")
	)
	(segment
		(start 153.533602 -18.705068)
		(end 153.2509 -18.705068)
		(width 0.4572)
		(layer "B.Cu")
		(net "P3V3_AUX")
	)
	(segment
		(start 184.332372 -113.862866)
		(end 184.332372 -113.86312)
		(width 0.254)
		(layer "B.Cu")
		(net "P3V3_AUX")
	)
	(segment
		(start 75.51801 -148.051266)
		(end 75.51801 -147.544536)
		(width 0.508)
		(layer "B.Cu")
		(net "P3V3_AUX")
	)
	(segment
		(start 52.407058 -193.996564)
		(end 52.468272 -193.93535)
		(width 0.381)
		(layer "B.Cu")
		(net "P3V3_AUX")
	)
	(segment
		(start 171.17695 -99.894898)
		(end 170.561 -99.278948)
		(width 0.3048)
		(layer "B.Cu")
		(net "P3V3_AUX")
	)
	(segment
		(start 357.637842 -416.91687)
		(end 357.637842 -416.23107)
		(width 0.4572)
		(layer "B.Cu")
		(net "P3V3_AUX")
	)
	(segment
		(start 87.585042 -305.926744)
		(end 88.105234 -305.406552)
		(width 0.508)
		(layer "B.Cu")
		(net "P3V3_AUX")
	)
	(segment
		(start 201.041 -140.294106)
		(end 201.041 -139.51204)
		(width 0.4572)
		(layer "B.Cu")
		(net "P3V3_AUX")
	)
	(segment
		(start 174.966122 -13.908278)
		(end 174.712122 -14.162278)
		(width 0.4572)
		(layer "B.Cu")
		(net "P3V3_AUX")
	)
	(segment
		(start 188.816742 -115.842796)
		(end 188.712094 -115.842796)
		(width 0.254)
		(layer "B.Cu")
		(net "P3V3_AUX")
	)
	(segment
		(start 168.367202 -14.86535)
		(end 169.029126 -14.86535)
		(width 0.4572)
		(layer "B.Cu")
		(net "P3V3_AUX")
	)
	(segment
		(start 158.671006 -14.872208)
		(end 158.671006 -14.798548)
		(width 0.4572)
		(layer "B.Cu")
		(net "P3V3_AUX")
	)
	(segment
		(start 166.164514 -116.2812)
		(end 165.976046 -116.469668)
		(width 0.4064)
		(layer "B.Cu")
		(net "P3V3_AUX")
	)
	(segment
		(start 290.049458 -427.359572)
		(end 290.076382 -427.332648)
		(width 0.4572)
		(layer "B.Cu")
		(net "P3V3_AUX")
	)
	(segment
		(start 232.457244 -50.193448)
		(end 235.8009 -50.193448)
		(width 0.381)
		(layer "B.Cu")
		(net "P3V3_AUX")
	)
	(segment
		(start 208.568544 -71.480426)
		(end 209.040984 -71.952866)
		(width 0.4064)
		(layer "B.Cu")
		(net "P3V3_AUX")
	)
	(segment
		(start 205.37424 -79.736188)
		(end 204.570076 -79.736188)
		(width 0.381)
		(layer "B.Cu")
		(net "P3V3_AUX")
	)
	(segment
		(start 153.990802 -18.247868)
		(end 153.533602 -18.705068)
		(width 0.4572)
		(layer "B.Cu")
		(net "P3V3_AUX")
	)
	(segment
		(start 186.312048 -114.262916)
		(end 186.312048 -114.62258)
		(width 0.254)
		(layer "B.Cu")
		(net "P3V3_AUX")
	)
	(segment
		(start 163.387532 -432.77663)
		(end 163.31184 -432.700938)
		(width 0.4572)
		(layer "B.Cu")
		(net "P3V3_AUX")
	)
	(segment
		(start 236.119162 -224.115884)
		(end 237.06963 -224.115884)
		(width 0.4572)
		(layer "B.Cu")
		(net "P3V3_AUX")
	)
	(segment
		(start 177.803302 -355.48443)
		(end 177.376328 -355.911404)
		(width 0.508)
		(layer "B.Cu")
		(net "P3V3_AUX")
	)
	(segment
		(start 186.711844 -113.862866)
		(end 186.711844 -113.86312)
		(width 0.254)
		(layer "B.Cu")
		(net "P3V3_AUX")
	)
	(segment
		(start 52.782978 -426.4406)
		(end 52.782978 -427.050708)
		(width 0.381)
		(layer "B.Cu")
		(net "P3V3_AUX")
	)
	(segment
		(start 237.690406 -224.73666)
		(end 237.690406 -225.277172)
		(width 0.4572)
		(layer "B.Cu")
		(net "P3V3_AUX")
	)
	(segment
		(start 447.167254 -193.99631)
		(end 447.228468 -193.935096)
		(width 0.381)
		(layer "B.Cu")
		(net "P3V3_AUX")
	)
	(segment
		(start 233.907838 -223.997266)
		(end 233.013758 -223.997266)
		(width 0.4572)
		(layer "B.Cu")
		(net "P3V3_AUX")
	)
	(segment
		(start 166.696644 -8.613394)
		(end 167.111934 -8.198104)
		(width 0.4064)
		(layer "B.Cu")
		(net "P3V3_AUX")
	)
	(segment
		(start 453.832468 -193.99631)
		(end 454.561194 -193.99631)
		(width 0.4572)
		(layer "B.Cu")
		(net "P3V3_AUX")
	)
	(segment
		(start 186.312048 -115.842796)
		(end 187.111894 -115.842796)
		(width 0.254)
		(layer "B.Cu")
		(net "P3V3_AUX")
	)
	(segment
		(start 199.227186 -193.996564)
		(end 199.2884 -193.93535)
		(width 0.381)
		(layer "B.Cu")
		(net "P3V3_AUX")
	)
	(segment
		(start 160.306258 -320.798952)
		(end 156.551884 -320.798952)
		(width 0.381)
		(layer "B.Cu")
		(net "P3V3_AUX")
	)
	(segment
		(start 200.43775 -134.47395)
		(end 199.517 -134.47395)
		(width 0.4572)
		(layer "B.Cu")
		(net "P3V3_AUX")
	)
	(segment
		(start 144.115282 -17.725898)
		(end 146.369532 -17.725898)
		(width 0.4572)
		(layer "B.Cu")
		(net "P3V3_AUX")
	)
	(segment
		(start 169.686732 -436.251858)
		(end 169.686732 -436.903368)
		(width 0.4572)
		(layer "B.Cu")
		(net "P3V3_AUX")
	)
	(segment
		(start 216.60993 -53.177948)
		(end 216.610184 -53.177948)
		(width 0.4572)
		(layer "B.Cu")
		(net "P3V3_AUX")
	)
	(segment
		(start 366.645698 -143.687038)
		(end 366.645698 -144.495774)
		(width 0.381)
		(layer "B.Cu")
		(net "P3V3_AUX")
	)
	(segment
		(start 45.282358 -193.73469)
		(end 45.483018 -193.93535)
		(width 0.508)
		(layer "B.Cu")
		(net "P3V3_AUX")
	)
	(segment
		(start 186.312048 -115.422172)
		(end 186.312048 -115.842796)
		(width 0.254)
		(layer "B.Cu")
		(net "P3V3_AUX")
	)
	(segment
		(start 11.245596 -405.125174)
		(end 10.337292 -404.21687)
		(width 0.4572)
		(layer "B.Cu")
		(net "P3V3_AUX")
	)
	(segment
		(start 104.555544 -413.232346)
		(end 104.107488 -413.232346)
		(width 0.4572)
		(layer "B.Cu")
		(net "P3V3_AUX")
	)
	(segment
		(start 184.269126 -113.862866)
		(end 183.932322 -113.526062)
		(width 0.254)
		(layer "B.Cu")
		(net "P3V3_AUX")
	)
	(segment
		(start 138.7729 -9.43864)
		(end 138.7729 -10.048748)
		(width 0.254)
		(layer "B.Cu")
		(net "P3V3_AUX")
	)
	(segment
		(start 187.111894 -113.46307)
		(end 187.111894 -113.57356)
		(width 0.254)
		(layer "B.Cu")
		(net "P3V3_AUX")
	)
	(segment
		(start 367.144808 -142.574772)
		(end 366.226344 -142.574772)
		(width 0.381)
		(layer "B.Cu")
		(net "P3V3_AUX")
	)
	(segment
		(start 151.433784 -18.093944)
		(end 152.044908 -18.705068)
		(width 0.4572)
		(layer "B.Cu")
		(net "P3V3_AUX")
	)
	(segment
		(start 175.333914 -13.908278)
		(end 174.966122 -13.908278)
		(width 0.4572)
		(layer "B.Cu")
		(net "P3V3_AUX")
	)
	(segment
		(start 298.634404 -427.261528)
		(end 298.634404 -428.428404)
		(width 0.254)
		(layer "B.Cu")
		(net "P3V3_AUX")
	)
	(segment
		(start 215.73363 -329.179174)
		(end 215.11133 -329.179174)
		(width 0.381)
		(layer "B.Cu")
		(net "P3V3_AUX")
	)
	(segment
		(start 143.801592 -81.786222)
		(end 143.801592 -82.423508)
		(width 0.4572)
		(layer "B.Cu")
		(net "P3V3_AUX")
	)
	(segment
		(start 171.577 -98.535998)
		(end 172.593 -98.535998)
		(width 0.3048)
		(layer "B.Cu")
		(net "P3V3_AUX")
	)
	(segment
		(start 171.576238 -427.923706)
		(end 171.576238 -428.562262)
		(width 0.4572)
		(layer "B.Cu")
		(net "P3V3_AUX")
	)
	(segment
		(start 200.812908 -140.522198)
		(end 201.041 -140.294106)
		(width 0.4572)
		(layer "B.Cu")
		(net "P3V3_AUX")
	)
	(segment
		(start 344.955876 -66.308732)
		(end 344.955876 -65.692782)
		(width 0.4572)
		(layer "B.Cu")
		(net "P3V3_AUX")
	)
	(segment
		(start 52.782978 -427.66488)
		(end 52.782978 -427.050708)
		(width 0.381)
		(layer "B.Cu")
		(net "P3V3_AUX")
	)
	(segment
		(start 232.857802 -249.372628)
		(end 232.857802 -250.642628)
		(width 0.3302)
		(layer "B.Cu")
		(net "P3V3_AUX")
	)
	(segment
		(start 198.3867 -193.996564)
		(end 199.227186 -193.996564)
		(width 0.381)
		(layer "B.Cu")
		(net "P3V3_AUX")
	)
	(segment
		(start 177.376328 -355.911404)
		(end 168.155366 -355.911404)
		(width 0.508)
		(layer "B.Cu")
		(net "P3V3_AUX")
	)
	(segment
		(start 308.44998 -193.99631)
		(end 308.511194 -193.935096)
		(width 0.381)
		(layer "B.Cu")
		(net "P3V3_AUX")
	)
	(segment
		(start 164.963856 -429.638206)
		(end 164.963856 -429.55972)
		(width 0.4572)
		(layer "B.Cu")
		(net "P3V3_AUX")
	)
	(segment
		(start 416.991038 -193.99631)
		(end 417.052252 -193.935096)
		(width 0.381)
		(layer "B.Cu")
		(net "P3V3_AUX")
	)
	(segment
		(start 183.85282 -28.28798)
		(end 190.582296 -35.017456)
		(width 0.4572)
		(layer "B.Cu")
		(net "P3V3_AUX")
	)
	(segment
		(start 29.154628 -193.705226)
		(end 30.16504 -193.705226)
		(width 0.381)
		(layer "B.Cu")
		(net "P3V3_AUX")
	)
	(segment
		(start 182.205122 -114.262916)
		(end 182.332122 -114.262916)
		(width 0.254)
		(layer "B.Cu")
		(net "P3V3_AUX")
	)
	(segment
		(start 437.141366 -425.627546)
		(end 437.141366 -428.436024)
		(width 0.508)
		(layer "B.Cu")
		(net "P3V3_AUX")
	)
	(segment
		(start 183.557164 -24.095964)
		(end 183.85282 -24.39162)
		(width 0.4572)
		(layer "B.Cu")
		(net "P3V3_AUX")
	)
	(segment
		(start 160.103312 -416.664902)
		(end 160.103312 -416.176206)
		(width 0.3302)
		(layer "B.Cu")
		(net "P3V3_AUX")
	)
	(segment
		(start 176.618138 -193.93535)
		(end 177.215038 -193.93535)
		(width 0.4572)
		(layer "B.Cu")
		(net "P3V3_AUX")
	)
	(segment
		(start 52.74564 -423.825162)
		(end 53.395118 -423.825162)
		(width 0.381)
		(layer "B.Cu")
		(net "P3V3_AUX")
	)
	(segment
		(start 431.39233 -193.99631)
		(end 431.8762 -193.795904)
		(width 0.381)
		(layer "B.Cu")
		(net "P3V3_AUX")
	)
	(segment
		(start 192.454276 -24.919432)
		(end 192.454276 -25.565862)
		(width 0.508)
		(layer "B.Cu")
		(net "P3V3_AUX")
	)
	(segment
		(start 187.7695 -111.720376)
		(end 187.254388 -111.720376)
		(width 0.254)
		(layer "B.Cu")
		(net "P3V3_AUX")
	)
	(segment
		(start 299.46854 -193.99631)
		(end 300.347126 -193.99631)
		(width 0.381)
		(layer "B.Cu")
		(net "P3V3_AUX")
	)
	(segment
		(start 195.55333 -72.853042)
		(end 193.24447 -72.853042)
		(width 0.3048)
		(layer "B.Cu")
		(net "P3V3_AUX")
	)
	(segment
		(start 189.112144 -116.242846)
		(end 189.112144 -116.138198)
		(width 0.254)
		(layer "B.Cu")
		(net "P3V3_AUX")
	)
	(segment
		(start 170.424348 -424.0657)
		(end 171.081192 -424.0657)
		(width 0.3048)
		(layer "B.Cu")
		(net "P3V3_AUX")
	)
	(segment
		(start 163.155376 -111.637572)
		(end 162.433 -112.359948)
		(width 0.4572)
		(layer "B.Cu")
		(net "P3V3_AUX")
	)
	(segment
		(start 156.473398 -341.10041)
		(end 156.473398 -347.260164)
		(width 0.508)
		(layer "B.Cu")
		(net "P3V3_AUX")
	)
	(segment
		(start 177.988722 -414.283144)
		(end 178.481482 -414.283144)
		(width 0.4572)
		(layer "B.Cu")
		(net "P3V3_AUX")
	)
	(segment
		(start 181.182518 -415.216594)
		(end 181.182518 -415.176462)
		(width 0.4572)
		(layer "B.Cu")
		(net "P3V3_AUX")
	)
	(segment
		(start 69.29882 -203.679552)
		(end 69.101716 -203.482448)
		(width 0.381)
		(layer "B.Cu")
		(net "P3V3_AUX")
	)
	(segment
		(start 184.200292 -193.93535)
		(end 184.759092 -193.93535)
		(width 0.381)
		(layer "B.Cu")
		(net "P3V3_AUX")
	)
	(segment
		(start 183.260492 -193.996564)
		(end 184.139078 -193.996564)
		(width 0.381)
		(layer "B.Cu")
		(net "P3V3_AUX")
	)
	(segment
		(start 242.535964 -221.39529)
		(end 242.081304 -221.84995)
		(width 0.381)
		(layer "B.Cu")
		(net "P3V3_AUX")
	)
	(segment
		(start 207.33004 -193.99631)
		(end 207.391 -193.93535)
		(width 0.381)
		(layer "B.Cu")
		(net "P3V3_AUX")
	)
	(segment
		(start 166.73195 -118.328948)
		(end 166.722298 -118.319296)
		(width 0.4064)
		(layer "B.Cu")
		(net "P3V3_AUX")
	)
	(segment
		(start 173.609 -99.894898)
		(end 172.593 -99.894898)
		(width 0.3048)
		(layer "B.Cu")
		(net "P3V3_AUX")
	)
	(segment
		(start 178.430174 -13.356082)
		(end 178.430174 -12.275058)
		(width 0.4572)
		(layer "B.Cu")
		(net "P3V3_AUX")
	)
	(segment
		(start 184.332372 -113.862866)
		(end 184.269126 -113.862866)
		(width 0.254)
		(layer "B.Cu")
		(net "P3V3_AUX")
	)
	(segment
		(start 184.732168 -114.262916)
		(end 185.058558 -114.262916)
		(width 0.254)
		(layer "B.Cu")
		(net "P3V3_AUX")
	)
	(segment
		(start 236.119162 -224.115884)
		(end 236.119162 -223.266)
		(width 0.4572)
		(layer "B.Cu")
		(net "P3V3_AUX")
	)
	(segment
		(start 164.215318 -415.75101)
		(end 164.215318 -416.663886)
		(width 0.4572)
		(layer "B.Cu")
		(net "P3V3_AUX")
	)
	(segment
		(start 182.251604 -115.842796)
		(end 181.932326 -116.162074)
		(width 0.254)
		(layer "B.Cu")
		(net "P3V3_AUX")
	)
	(segment
		(start 112.19434 -61.61786)
		(end 112.65662 -61.61786)
		(width 0.4572)
		(layer "B.Cu")
		(net "P3V3_AUX")
	)
	(segment
		(start 192.542922 -31.358078)
		(end 192.542922 -33.284668)
		(width 0.508)
		(layer "B.Cu")
		(net "P3V3_AUX")
	)
	(segment
		(start 308.379876 -66.308732)
		(end 308.379876 -65.692782)
		(width 0.4572)
		(layer "B.Cu")
		(net "P3V3_AUX")
	)
	(segment
		(start 194.304158 -79.14259)
		(end 192.948052 -79.14259)
		(width 0.3556)
		(layer "B.Cu")
		(net "P3V3_AUX")
	)
	(segment
		(start 310.411876 -66.308732)
		(end 310.411876 -65.692782)
		(width 0.4572)
		(layer "B.Cu")
		(net "P3V3_AUX")
	)
	(segment
		(start 186.711844 -115.022376)
		(end 186.312048 -115.422172)
		(width 0.254)
		(layer "B.Cu")
		(net "P3V3_AUX")
	)
	(segment
		(start 103.849424 -412.974282)
		(end 103.849424 -412.35249)
		(width 0.4572)
		(layer "B.Cu")
		(net "P3V3_AUX")
	)
	(segment
		(start 276.836632 -193.99631)
		(end 277.051008 -193.781934)
		(width 0.381)
		(layer "B.Cu")
		(net "P3V3_AUX")
	)
	(segment
		(start 367.144808 -142.574772)
		(end 367.144808 -143.187928)
		(width 0.381)
		(layer "B.Cu")
		(net "P3V3_AUX")
	)
	(segment
		(start 174.900844 -420.243)
		(end 175.767238 -419.376606)
		(width 0.3556)
		(layer "B.Cu")
		(net "P3V3_AUX")
	)
	(segment
		(start 53.49367 -422.777666)
		(end 53.49367 -421.91813)
		(width 0.4572)
		(layer "B.Cu")
		(net "P3V3_AUX")
	)
	(segment
		(start 186.993276 -111.86287)
		(end 186.711844 -112.144302)
		(width 0.254)
		(layer "B.Cu")
		(net "P3V3_AUX")
	)
	(segment
		(start 194.945 -96.719898)
		(end 195.58 -96.719898)
		(width 0.4572)
		(layer "B.Cu")
		(net "P3V3_AUX")
	)
	(segment
		(start 171.577 -98.535998)
		(end 171.30395 -98.535998)
		(width 0.3048)
		(layer "B.Cu")
		(net "P3V3_AUX")
	)
	(segment
		(start 25.146 -367.55705)
		(end 25.54859 -367.95964)
		(width 0.4572)
		(layer "B.Cu")
		(net "P3V3_AUX")
	)
	(segment
		(start 184.332372 -113.86312)
		(end 184.732168 -114.262916)
		(width 0.254)
		(layer "B.Cu")
		(net "P3V3_AUX")
	)
	(segment
		(start 160.198308 -416.08121)
		(end 160.198308 -415.531046)
		(width 0.3302)
		(layer "B.Cu")
		(net "P3V3_AUX")
	)
	(segment
		(start 366.226344 -142.574772)
		(end 366.027462 -142.37589)
		(width 0.381)
		(layer "B.Cu")
		(net "P3V3_AUX")
	)
	(segment
		(start 110.97895 -416.941)
		(end 110.363 -416.941)
		(width 0.4572)
		(layer "B.Cu")
		(net "P3V3_AUX")
	)
	(segment
		(start 216.610184 -53.177948)
		(end 217.388186 -53.95595)
		(width 0.4572)
		(layer "B.Cu")
		(net "P3V3_AUX")
	)
	(segment
		(start 316.93739 -77.039978)
		(end 317.57239 -77.039978)
		(width 0.4572)
		(layer "B.Cu")
		(net "P3V3_AUX")
	)
	(segment
		(start 112.28705 -414.02)
		(end 112.4204 -414.02)
		(width 0.4572)
		(layer "B.Cu")
		(net "P3V3_AUX")
	)
	(segment
		(start 257.379724 -132.225034)
		(end 257.379724 -131.609084)
		(width 0.381)
		(layer "B.Cu")
		(net "P3V3_AUX")
	)
	(segment
		(start 188.712094 -114.262916)
		(end 189.112144 -114.662966)
		(width 0.254)
		(layer "B.Cu")
		(net "P3V3_AUX")
	)
	(segment
		(start 417.052252 -193.935096)
		(end 417.611052 -193.935096)
		(width 0.381)
		(layer "B.Cu")
		(net "P3V3_AUX")
	)
	(segment
		(start 174.011082 -14.162278)
		(end 174.317914 -14.162278)
		(width 0.4572)
		(layer "B.Cu")
		(net "P3V3_AUX")
	)
	(segment
		(start 158.01848 -14.143228)
		(end 158.01848 -14.146022)
		(width 0.4572)
		(layer "B.Cu")
		(net "P3V3_AUX")
	)
	(segment
		(start 16.043402 -406.86609)
		(end 13.720318 -406.86609)
		(width 0.4572)
		(layer "B.Cu")
		(net "P3V3_AUX")
	)
	(segment
		(start 312.443876 -66.308732)
		(end 312.443876 -65.692782)
		(width 0.4572)
		(layer "B.Cu")
		(net "P3V3_AUX")
	)
	(segment
		(start 44.213272 -193.73469)
		(end 45.282358 -193.73469)
		(width 0.508)
		(layer "B.Cu")
		(net "P3V3_AUX")
	)
	(segment
		(start 215.742774 -328.032872)
		(end 215.120474 -328.032872)
		(width 0.381)
		(layer "B.Cu")
		(net "P3V3_AUX")
	)
	(segment
		(start 320.571876 -66.308732)
		(end 320.571876 -65.692782)
		(width 0.4572)
		(layer "B.Cu")
		(net "P3V3_AUX")
	)
	(segment
		(start 184.332372 -116.242846)
		(end 183.932322 -115.842796)
		(width 0.254)
		(layer "B.Cu")
		(net "P3V3_AUX")
	)
	(segment
		(start 62.578234 -196.186552)
		(end 63.219584 -196.186552)
		(width 0.381)
		(layer "B.Cu")
		(net "P3V3_AUX")
	)
	(segment
		(start 182.332122 -114.262916)
		(end 181.932326 -114.662712)
		(width 0.254)
		(layer "B.Cu")
		(net "P3V3_AUX")
	)
	(segment
		(start 184.332372 -116.242846)
		(end 184.732168 -115.84305)
		(width 0.254)
		(layer "B.Cu")
		(net "P3V3_AUX")
	)
	(segment
		(start 167.111934 -8.198104)
		(end 167.111934 -7.839456)
		(width 0.4064)
		(layer "B.Cu")
		(net "P3V3_AUX")
	)
	(segment
		(start 192.454276 -25.565862)
		(end 193.460116 -25.565862)
		(width 0.508)
		(layer "B.Cu")
		(net "P3V3_AUX")
	)
	(segment
		(start 52.782978 -431.504852)
		(end 52.782978 -430.887886)
		(width 0.381)
		(layer "B.Cu")
		(net "P3V3_AUX")
	)
	(segment
		(start 28.86329 -193.996564)
		(end 29.154628 -193.705226)
		(width 0.381)
		(layer "B.Cu")
		(net "P3V3_AUX")
	)
	(segment
		(start 300.40834 -193.935096)
		(end 300.96714 -193.935096)
		(width 0.381)
		(layer "B.Cu")
		(net "P3V3_AUX")
	)
	(segment
		(start 201.041 -138.32205)
		(end 201.9808 -138.32205)
		(width 0.4572)
		(layer "B.Cu")
		(net "P3V3_AUX")
	)
	(segment
		(start 232.148126 -50.502566)
		(end 232.457244 -50.193448)
		(width 0.381)
		(layer "B.Cu")
		(net "P3V3_AUX")
	)
	(segment
		(start 241.756692 -420.40683)
		(end 241.09553 -420.40683)
		(width 0.4572)
		(layer "B.Cu")
		(net "P3V3_AUX")
	)
	(segment
		(start 240.181384 -237.25505)
		(end 240.157 -237.230666)
		(width 0.254)
		(layer "B.Cu")
		(net "P3V3_AUX")
	)
	(segment
		(start 104.107488 -413.232346)
		(end 103.849424 -412.974282)
		(width 0.4572)
		(layer "B.Cu")
		(net "P3V3_AUX")
	)
	(segment
		(start 241.743992 -288.939732)
		(end 241.149378 -288.939732)
		(width 0.4572)
		(layer "B.Cu")
		(net "P3V3_AUX")
	)
	(segment
		(start 326.667876 -66.308732)
		(end 326.667876 -65.692782)
		(width 0.4572)
		(layer "B.Cu")
		(net "P3V3_AUX")
	)
	(segment
		(start 75.64501 -147.417536)
		(end 75.64501 -140.118846)
		(width 0.4572)
		(layer "B.Cu")
		(net "P3V3_AUX")
	)
	(segment
		(start 158.01848 -14.146022)
		(end 158.671006 -14.798548)
		(width 0.4572)
		(layer "B.Cu")
		(net "P3V3_AUX")
	)
	(segment
		(start 177.836322 -414.435544)
		(end 177.988722 -414.283144)
		(width 0.4572)
		(layer "B.Cu")
		(net "P3V3_AUX")
	)
	(segment
		(start 357.330756 -419.02888)
		(end 357.330756 -419.719506)
		(width 0.4572)
		(layer "B.Cu")
		(net "P3V3_AUX")
	)
	(segment
		(start 186.711844 -112.144302)
		(end 186.711844 -112.262666)
		(width 0.254)
		(layer "B.Cu")
		(net "P3V3_AUX")
	)
	(segment
		(start 189.112144 -116.348256)
		(end 188.817758 -116.642642)
		(width 0.254)
		(layer "B.Cu")
		(net "P3V3_AUX")
	)
	(segment
		(start 184.732168 -114.262916)
		(end 184.732168 -114.62258)
		(width 0.254)
		(layer "B.Cu")
		(net "P3V3_AUX")
	)
	(segment
		(start 192.948052 -79.14259)
		(end 192.287652 -79.80299)
		(width 0.381)
		(layer "B.Cu")
		(net "P3V3_AUX")
	)
	(segment
		(start 145.331434 -204.605128)
		(end 147.248118 -206.521812)
		(width 0.508)
		(layer "B.Cu")
		(net "P3V3_AUX")
	)
	(segment
		(start 240.919 -237.25505)
		(end 240.181384 -237.25505)
		(width 0.254)
		(layer "B.Cu")
		(net "P3V3_AUX")
	)
	(segment
		(start 165.199568 -416.946588)
		(end 164.49802 -416.946588)
		(width 0.4572)
		(layer "B.Cu")
		(net "P3V3_AUX")
	)
	(segment
		(start 90.772234 -305.406552)
		(end 91.108784 -305.406552)
		(width 0.381)
		(layer "B.Cu")
		(net "P3V3_AUX")
	)
	(segment
		(start 205.896718 -79.21371)
		(end 205.37424 -79.736188)
		(width 0.3556)
		(layer "B.Cu")
		(net "P3V3_AUX")
	)
	(segment
		(start 73.129394 -137.60323)
		(end 73.129394 -127.112268)
		(width 0.4572)
		(layer "B.Cu")
		(net "P3V3_AUX")
	)
	(segment
		(start 86.294214 -309.472584)
		(end 86.872064 -309.472584)
		(width 0.508)
		(layer "B.Cu")
		(net "P3V3_AUX")
	)
	(segment
		(start 174.502572 -14.653006)
		(end 174.502572 -14.822678)
		(width 0.4572)
		(layer "B.Cu")
		(net "P3V3_AUX")
	)
	(segment
		(start 242.081304 -221.84995)
		(end 241.173 -221.84995)
		(width 0.381)
		(layer "B.Cu")
		(net "P3V3_AUX")
	)
	(segment
		(start 204.27823 -79.444342)
		(end 204.27823 -79.392272)
		(width 0.381)
		(layer "B.Cu")
		(net "P3V3_AUX")
	)
	(segment
		(start 166.716202 -116.2812)
		(end 166.164514 -116.2812)
		(width 0.4064)
		(layer "B.Cu")
		(net "P3V3_AUX")
	)
	(segment
		(start 68.91782 -203.298552)
		(end 68.515484 -203.298552)
		(width 0.381)
		(layer "B.Cu")
		(net "P3V3_AUX")
	)
	(segment
		(start 289.442906 -427.359572)
		(end 290.049458 -427.359572)
		(width 0.4572)
		(layer "B.Cu")
		(net "P3V3_AUX")
	)
	(segment
		(start 319.322958 -203.517246)
		(end 318.306958 -203.517246)
		(width 0.381)
		(layer "B.Cu")
		(net "P3V3_AUX")
	)
	(segment
		(start 21.319236 -193.996564)
		(end 22.231096 -193.996564)
		(width 0.381)
		(layer "B.Cu")
		(net "P3V3_AUX")
	)
	(segment
		(start 229.799642 -288.939732)
		(end 229.205028 -288.939732)
		(width 0.4572)
		(layer "B.Cu")
		(net "P3V3_AUX")
	)
	(segment
		(start 175.716438 -193.996564)
		(end 176.556924 -193.996564)
		(width 0.4572)
		(layer "B.Cu")
		(net "P3V3_AUX")
	)
	(segment
		(start 278.18207 -193.781934)
		(end 278.335232 -193.935096)
		(width 0.381)
		(layer "B.Cu")
		(net "P3V3_AUX")
	)
	(segment
		(start 170.636692 -431.949098)
		(end 170.52925 -431.841656)
		(width 0.4572)
		(layer "B.Cu")
		(net "P3V3_AUX")
	)
	(segment
		(start 165.663626 -17.417288)
		(end 166.35095 -16.729964)
		(width 0.4572)
		(layer "B.Cu")
		(net "P3V3_AUX")
	)
	(segment
		(start 32.5374 -426.984922)
		(end 32.19704 -427.325282)
		(width 0.381)
		(layer "B.Cu")
		(net "P3V3_AUX")
	)
	(segment
		(start 165.349428 -17.417288)
		(end 165.663626 -17.417288)
		(width 0.4572)
		(layer "B.Cu")
		(net "P3V3_AUX")
	)
	(segment
		(start 184.332372 -116.242846)
		(end 184.2135 -116.242846)
		(width 0.254)
		(layer "B.Cu")
		(net "P3V3_AUX")
	)
	(segment
		(start 231.701086 -224.254314)
		(end 231.701086 -225.216974)
		(width 0.4572)
		(layer "B.Cu")
		(net "P3V3_AUX")
	)
	(segment
		(start 354.812854 -421.026082)
		(end 355.498146 -421.026082)
		(width 0.4572)
		(layer "B.Cu")
		(net "P3V3_AUX")
	)
	(segment
		(start 181.932326 -116.242846)
		(end 181.932072 -116.242846)
		(width 0.254)
		(layer "B.Cu")
		(net "P3V3_AUX")
	)
	(segment
		(start 181.932072 -116.242846)
		(end 181.532276 -116.642642)
		(width 0.254)
		(layer "B.Cu")
		(net "P3V3_AUX")
	)
	(segment
		(start 286.004 -425.55795)
		(end 286.004 -424.794426)
		(width 0.4572)
		(layer "B.Cu")
		(net "P3V3_AUX")
	)
	(segment
		(start 194.056 -26.161746)
		(end 194.056 -29.845)
		(width 0.508)
		(layer "B.Cu")
		(net "P3V3_AUX")
	)
	(segment
		(start 191.382904 -80.555592)
		(end 190.682118 -81.256378)
		(width 0.4572)
		(layer "B.Cu")
		(net "P3V3_AUX")
	)
	(segment
		(start 184.2135 -116.242846)
		(end 183.932322 -116.524024)
		(width 0.254)
		(layer "B.Cu")
		(net "P3V3_AUX")
	)
	(segment
		(start 212.725 -58.328814)
		(end 212.725254 -58.329068)
		(width 0.4572)
		(layer "B.Cu")
		(net "P3V3_AUX")
	)
	(segment
		(start 284.380686 -193.99631)
		(end 284.710124 -193.666872)
		(width 0.381)
		(layer "B.Cu")
		(net "P3V3_AUX")
	)
	(segment
		(start 190.804546 -193.996564)
		(end 191.683132 -193.996564)
		(width 0.381)
		(layer "B.Cu")
		(net "P3V3_AUX")
	)
	(segment
		(start 206.374746 -79.21371)
		(end 205.896718 -79.21371)
		(width 0.3556)
		(layer "B.Cu")
		(net "P3V3_AUX")
	)
	(segment
		(start 300.347126 -193.99631)
		(end 300.40834 -193.935096)
		(width 0.381)
		(layer "B.Cu")
		(net "P3V3_AUX")
	)
	(segment
		(start 421.90289 -428.734474)
		(end 421.92575 -428.757334)
		(width 0.254)
		(layer "B.Cu")
		(net "P3V3_AUX")
	)
	(segment
		(start 53.551582 -421.180768)
		(end 53.551582 -421.860218)
		(width 0.4572)
		(layer "B.Cu")
		(net "P3V3_AUX")
	)
	(segment
		(start 161.627058 -325.17715)
		(end 161.627058 -335.94675)
		(width 0.508)
		(layer "B.Cu")
		(net "P3V3_AUX")
	)
	(segment
		(start 242.535964 -220.963998)
		(end 242.535964 -221.39529)
		(width 0.381)
		(layer "B.Cu")
		(net "P3V3_AUX")
	)
	(segment
		(start 115.677188 -61.821314)
		(end 115.677188 -62.002162)
		(width 0.4572)
		(layer "B.Cu")
		(net "P3V3_AUX")
	)
	(segment
		(start 178.229006 -355.48443)
		(end 177.803302 -355.48443)
		(width 0.508)
		(layer "B.Cu")
		(net "P3V3_AUX")
	)
	(segment
		(start 225.966528 -290.844732)
		(end 225.966528 -291.425122)
		(width 0.381)
		(layer "B.Cu")
		(net "P3V3_AUX")
	)
	(segment
		(start 109.728 -417.42995)
		(end 109.87405 -417.42995)
		(width 0.4572)
		(layer "B.Cu")
		(net "P3V3_AUX")
	)
	(segment
		(start 189.112144 -113.862866)
		(end 189.112144 -113.985802)
		(width 0.254)
		(layer "B.Cu")
		(net "P3V3_AUX")
	)
	(segment
		(start 421.90289 -427.605952)
		(end 421.90289 -428.734474)
		(width 0.254)
		(layer "B.Cu")
		(net "P3V3_AUX")
	)
	(segment
		(start 166.35095 -16.729964)
		(end 168.36644 -16.729964)
		(width 0.4572)
		(layer "B.Cu")
		(net "P3V3_AUX")
	)
	(segment
		(start 186.822588 -113.862866)
		(end 186.711844 -113.862866)
		(width 0.254)
		(layer "B.Cu")
		(net "P3V3_AUX")
	)
	(segment
		(start 172.877734 -8.462518)
		(end 172.078904 -8.462518)
		(width 0.4572)
		(layer "B.Cu")
		(net "P3V3_AUX")
	)
	(segment
		(start 209.040984 -71.952866)
		(end 209.040984 -73.168002)
		(width 0.4064)
		(layer "B.Cu")
		(net "P3V3_AUX")
	)
	(segment
		(start 191.954404 -79.80299)
		(end 191.382904 -80.37449)
		(width 0.4572)
		(layer "B.Cu")
		(net "P3V3_AUX")
	)
	(segment
		(start 428.087282 -438.592722)
		(end 428.087282 -439.307986)
		(width 0.4572)
		(layer "B.Cu")
		(net "P3V3_AUX")
	)
	(segment
		(start 161.60496 -415.531046)
		(end 160.198308 -415.531046)
		(width 0.381)
		(layer "B.Cu")
		(net "P3V3_AUX")
	)
	(segment
		(start 225.966528 -291.425122)
		(end 226.566984 -292.025578)
		(width 0.381)
		(layer "B.Cu")
		(net "P3V3_AUX")
	)
	(segment
		(start 169.029126 -16.067278)
		(end 169.029126 -14.86535)
		(width 0.4572)
		(layer "B.Cu")
		(net "P3V3_AUX")
	)
	(segment
		(start 181.532276 -116.642896)
		(end 182.332122 -117.442742)
		(width 0.254)
		(layer "B.Cu")
		(net "P3V3_AUX")
	)
	(segment
		(start 163.644326 -111.637572)
		(end 163.155376 -111.637572)
		(width 0.4572)
		(layer "B.Cu")
		(net "P3V3_AUX")
	)
	(segment
		(start 231.958134 -223.997266)
		(end 231.701086 -224.254314)
		(width 0.4572)
		(layer "B.Cu")
		(net "P3V3_AUX")
	)
	(segment
		(start 367.144808 -143.187928)
		(end 366.645698 -143.687038)
		(width 0.381)
		(layer "B.Cu")
		(net "P3V3_AUX")
	)
	(segment
		(start 192.542922 -33.284668)
		(end 190.810134 -35.017456)
		(width 0.508)
		(layer "B.Cu")
		(net "P3V3_AUX")
	)
	(segment
		(start 186.312048 -115.842796)
		(end 185.858658 -115.842796)
		(width 0.254)
		(layer "B.Cu")
		(net "P3V3_AUX")
	)
	(segment
		(start 116.888514 -414.943544)
		(end 114.73434 -414.943544)
		(width 0.3556)
		(layer "B.Cu")
		(net "P3V3_AUX")
	)
	(segment
		(start 86.241128 -309.52567)
		(end 86.294214 -309.472584)
		(width 0.508)
		(layer "B.Cu")
		(net "P3V3_AUX")
	)
	(segment
		(start 334.795876 -66.308732)
		(end 334.795876 -65.692782)
		(width 0.4572)
		(layer "B.Cu")
		(net "P3V3_AUX")
	)
	(segment
		(start 181.932326 -115.022376)
		(end 181.932326 -115.443)
		(width 0.254)
		(layer "B.Cu")
		(net "P3V3_AUX")
	)
	(segment
		(start 46.434502 -423.905934)
		(end 45.746162 -423.905934)
		(width 0.4572)
		(layer "B.Cu")
		(net "P3V3_AUX")
	)
	(segment
		(start 209.148426 -120.944386)
		(end 209.992468 -120.944386)
		(width 0.4572)
		(layer "B.Cu")
		(net "P3V3_AUX")
	)
	(segment
		(start 321.100958 -203.517246)
		(end 321.100958 -203.335636)
		(width 0.381)
		(layer "B.Cu")
		(net "P3V3_AUX")
	)
	(segment
		(start 182.541164 -24.055832)
		(end 183.557164 -24.055832)
		(width 0.4572)
		(layer "B.Cu")
		(net "P3V3_AUX")
	)
	(segment
		(start 166.716202 -116.2812)
		(end 166.716202 -115.28552)
		(width 0.4572)
		(layer "B.Cu")
		(net "P3V3_AUX")
	)
	(segment
		(start 346.987876 -66.308732)
		(end 346.987876 -65.692782)
		(width 0.4572)
		(layer "B.Cu")
		(net "P3V3_AUX")
	)
	(segment
		(start 69.772784 -203.679552)
		(end 69.29882 -203.679552)
		(width 0.381)
		(layer "B.Cu")
		(net "P3V3_AUX")
	)
	(segment
		(start 285.610808 -193.666872)
		(end 285.879032 -193.935096)
		(width 0.381)
		(layer "B.Cu")
		(net "P3V3_AUX")
	)
	(segment
		(start 166.722298 -118.319296)
		(end 166.116 -118.319296)
		(width 0.4064)
		(layer "B.Cu")
		(net "P3V3_AUX")
	)
	(segment
		(start 454.561194 -193.99631)
		(end 454.622408 -193.935096)
		(width 0.4572)
		(layer "B.Cu")
		(net "P3V3_AUX")
	)
	(segment
		(start 182.332122 -115.842796)
		(end 182.251604 -115.842796)
		(width 0.254)
		(layer "B.Cu")
		(net "P3V3_AUX")
	)
	(segment
		(start 51.766978 -434.082952)
		(end 50.975768 -434.082952)
		(width 0.381)
		(layer "B.Cu")
		(net "P3V3_AUX")
	)
	(segment
		(start 184.332372 -115.022376)
		(end 184.732168 -115.422172)
		(width 0.254)
		(layer "B.Cu")
		(net "P3V3_AUX")
	)
	(segment
		(start 434.39842 -438.51195)
		(end 434.39842 -439.332116)
		(width 0.4572)
		(layer "B.Cu")
		(net "P3V3_AUX")
	)
	(segment
		(start 188.83503 -114.262916)
		(end 188.712094 -114.262916)
		(width 0.254)
		(layer "B.Cu")
		(net "P3V3_AUX")
	)
	(segment
		(start 161.313368 -321.806062)
		(end 160.306258 -320.798952)
		(width 0.508)
		(layer "B.Cu")
		(net "P3V3_AUX")
	)
	(segment
		(start 437.141366 -428.436024)
		(end 437.808116 -429.102774)
		(width 0.508)
		(layer "B.Cu")
		(net "P3V3_AUX")
	)
	(segment
		(start 183.932322 -116.524024)
		(end 183.932322 -116.642642)
		(width 0.254)
		(layer "B.Cu")
		(net "P3V3_AUX")
	)
	(segment
		(start 189.112144 -116.242846)
		(end 189.112144 -116.348256)
		(width 0.254)
		(layer "B.Cu")
		(net "P3V3_AUX")
	)
	(segment
		(start 114.273584 -415.4043)
		(end 114.273584 -418.110416)
		(width 0.3556)
		(layer "B.Cu")
		(net "P3V3_AUX")
	)
	(segment
		(start 429.583088 -436.014622)
		(end 429.823372 -436.254906)
		(width 0.4572)
		(layer "B.Cu")
		(net "P3V3_AUX")
	)
	(segment
		(start 182.332122 -112.66297)
		(end 182.332122 -112.663224)
		(width 0.254)
		(layer "B.Cu")
		(net "P3V3_AUX")
	)
	(segment
		(start 189.112144 -115.022376)
		(end 189.112144 -115.442746)
		(width 0.254)
		(layer "B.Cu")
		(net "P3V3_AUX")
	)
	(segment
		(start 63.219584 -196.186552)
		(end 63.219584 -197.202552)
		(width 0.381)
		(layer "B.Cu")
		(net "P3V3_AUX")
	)
	(segment
		(start 307.74132 -193.99631)
		(end 308.44998 -193.99631)
		(width 0.381)
		(layer "B.Cu")
		(net "P3V3_AUX")
	)
	(segment
		(start 114.73434 -414.943544)
		(end 114.273584 -415.4043)
		(width 0.3556)
		(layer "B.Cu")
		(net "P3V3_AUX")
	)
	(segment
		(start 423.656506 -193.99631)
		(end 424.535092 -193.99631)
		(width 0.381)
		(layer "B.Cu")
		(net "P3V3_AUX")
	)
	(segment
		(start 240.919 -237.25505)
		(end 240.919 -237.998)
		(width 0.381)
		(layer "B.Cu")
		(net "P3V3_AUX")
	)
	(segment
		(start 25.54859 -367.95964)
		(end 25.89657 -367.95964)
		(width 0.4572)
		(layer "B.Cu")
		(net "P3V3_AUX")
	)
	(segment
		(start 185.458608 -113.862866)
		(end 185.858658 -114.262916)
		(width 0.254)
		(layer "B.Cu")
		(net "P3V3_AUX")
	)
	(segment
		(start 189.112144 -116.138198)
		(end 188.816742 -115.842796)
		(width 0.254)
		(layer "B.Cu")
		(net "P3V3_AUX")
	)
	(segment
		(start 181.532276 -116.642642)
		(end 181.532276 -116.642896)
		(width 0.254)
		(layer "B.Cu")
		(net "P3V3_AUX")
	)
	(segment
		(start 43.976798 -193.971164)
		(end 44.213272 -193.73469)
		(width 0.508)
		(layer "B.Cu")
		(net "P3V3_AUX")
	)
	(segment
		(start 206.62138 -193.99631)
		(end 207.33004 -193.99631)
		(width 0.381)
		(layer "B.Cu")
		(net "P3V3_AUX")
	)
	(segment
		(start 152.992836 -17.251172)
		(end 153.990802 -17.251172)
		(width 0.4572)
		(layer "B.Cu")
		(net "P3V3_AUX")
	)
	(segment
		(start 109.87405 -417.42995)
		(end 110.363 -416.941)
		(width 0.4572)
		(layer "B.Cu")
		(net "P3V3_AUX")
	)
	(segment
		(start 209.040984 -73.168002)
		(end 208.236312 -73.168002)
		(width 0.4064)
		(layer "B.Cu")
		(net "P3V3_AUX")
	)
	(segment
		(start 321.100958 -203.335636)
		(end 320.664078 -202.898756)
		(width 0.381)
		(layer "B.Cu")
		(net "P3V3_AUX")
	)
	(segment
		(start 75.64501 -140.118846)
		(end 73.129394 -137.60323)
		(width 0.4572)
		(layer "B.Cu")
		(net "P3V3_AUX")
	)
	(segment
		(start 188.817758 -116.642642)
		(end 188.712094 -116.642642)
		(width 0.254)
		(layer "B.Cu")
		(net "P3V3_AUX")
	)
	(segment
		(start 46.359318 -431.585624)
		(end 45.719746 -431.585624)
		(width 0.381)
		(layer "B.Cu")
		(net "P3V3_AUX")
	)
	(segment
		(start 438.766966 -424.784774)
		(end 437.984138 -424.784774)
		(width 0.4572)
		(layer "B.Cu")
		(net "P3V3_AUX")
	)
	(segment
		(start 161.627058 -335.94675)
		(end 156.473398 -341.10041)
		(width 0.508)
		(layer "B.Cu")
		(net "P3V3_AUX")
	)
	(segment
		(start 162.73018 -19.656044)
		(end 162.73018 -18.889726)
		(width 0.4572)
		(layer "B.Cu")
		(net "P3V3_AUX")
	)
	(segment
		(start 161.313368 -324.383908)
		(end 161.313368 -321.806062)
		(width 0.508)
		(layer "B.Cu")
		(net "P3V3_AUX")
	)
	(segment
		(start 187.254388 -111.720376)
		(end 187.111894 -111.86287)
		(width 0.254)
		(layer "B.Cu")
		(net "P3V3_AUX")
	)
	(segment
		(start 174.712122 -14.162278)
		(end 174.317914 -14.162278)
		(width 0.4572)
		(layer "B.Cu")
		(net "P3V3_AUX")
	)
	(segment
		(start 166.73195 -116.296948)
		(end 166.716202 -116.2812)
		(width 0.4572)
		(layer "B.Cu")
		(net "P3V3_AUX")
	)
	(segment
		(start 229.993698 -289.133788)
		(end 229.799642 -288.939732)
		(width 0.4572)
		(layer "B.Cu")
		(net "P3V3_AUX")
	)
	(segment
		(start 183.932322 -113.526062)
		(end 183.932322 -113.46307)
		(width 0.254)
		(layer "B.Cu")
		(net "P3V3_AUX")
	)
	(segment
		(start 439.684414 -193.935096)
		(end 440.243214 -193.935096)
		(width 0.381)
		(layer "B.Cu")
		(net "P3V3_AUX")
	)
	(segment
		(start 149.718776 -18.093944)
		(end 150.988776 -18.093944)
		(width 0.4572)
		(layer "B.Cu")
		(net "P3V3_AUX")
	)
	(segment
		(start 53.49367 -421.91813)
		(end 53.551582 -421.860218)
		(width 0.4572)
		(layer "B.Cu")
		(net "P3V3_AUX")
	)
	(segment
		(start 292.803072 -193.99631)
		(end 292.864286 -193.935096)
		(width 0.381)
		(layer "B.Cu")
		(net "P3V3_AUX")
	)
	(segment
		(start 184.732168 -115.84305)
		(end 184.732168 -115.842796)
		(width 0.254)
		(layer "B.Cu")
		(net "P3V3_AUX")
	)
	(segment
		(start 198.374 -143.87195)
		(end 198.374 -141.12621)
		(width 0.4572)
		(layer "B.Cu")
		(net "P3V3_AUX")
	)
	(segment
		(start 202.438 -137.86485)
		(end 202.438 -136.4742)
		(width 0.4572)
		(layer "B.Cu")
		(net "P3V3_AUX")
	)
	(segment
		(start 51.520598 -193.996564)
		(end 52.407058 -193.996564)
		(width 0.381)
		(layer "B.Cu")
		(net "P3V3_AUX")
	)
	(segment
		(start 11.979402 -405.125174)
		(end 11.245596 -405.125174)
		(width 0.4572)
		(layer "B.Cu")
		(net "P3V3_AUX")
	)
	(segment
		(start 46.359318 -430.565052)
		(end 47.033942 -430.565052)
		(width 0.381)
		(layer "B.Cu")
		(net "P3V3_AUX")
	)
	(segment
		(start 13.720318 -406.86609)
		(end 11.979402 -405.125174)
		(width 0.4572)
		(layer "B.Cu")
		(net "P3V3_AUX")
	)
	(segment
		(start 52.468272 -193.93535)
		(end 53.027072 -193.93535)
		(width 0.381)
		(layer "B.Cu")
		(net "P3V3_AUX")
	)
	(segment
		(start 199.2884 -193.93535)
		(end 199.8472 -193.93535)
		(width 0.381)
		(layer "B.Cu")
		(net "P3V3_AUX")
	)
	(segment
		(start 204.570076 -79.736188)
		(end 204.27823 -79.444342)
		(width 0.381)
		(layer "B.Cu")
		(net "P3V3_AUX")
	)
	(segment
		(start 311.869836 -194.708526)
		(end 313.253882 -194.708526)
		(width 0.4572)
		(layer "In2.Cu")
		(net "P3V3_AUX")
	)
	(segment
		(start 407.667714 -136.231376)
		(end 406.875488 -137.023602)
		(width 0.4572)
		(layer "In2.Cu")
		(net "P3V3_AUX")
	)
	(segment
		(start 320.242184 -200.061322)
		(end 320.242184 -201.453242)
		(width 0.4572)
		(layer "In2.Cu")
		(net "P3V3_AUX")
	)
	(segment
		(start 342.224614 -14.058138)
		(end 363.678978 -14.058138)
		(width 0.4572)
		(layer "In2.Cu")
		(net "P3V3_AUX")
	)
	(segment
		(start 320.664078 -203.657454)
		(end 320.664078 -202.898756)
		(width 0.4572)
		(layer "In2.Cu")
		(net "P3V3_AUX")
	)
	(segment
		(start 24.33066 -324.615556)
		(end 23.613618 -324.615556)
		(width 0.4572)
		(layer "In2.Cu")
		(net "P3V3_AUX")
	)
	(segment
		(start 370.341906 -138.45667)
		(end 371.733826 -138.45667)
		(width 0.4572)
		(layer "In2.Cu")
		(net "P3V3_AUX")
	)
	(segment
		(start 72.84085 -56.53405)
		(end 70.71995 -58.65495)
		(width 0.4572)
		(layer "In2.Cu")
		(net "P3V3_AUX")
	)
	(segment
		(start 319.137538 -202.557888)
		(end 319.137538 -202.902312)
		(width 0.4572)
		(layer "In2.Cu")
		(net "P3V3_AUX")
	)
	(segment
		(start 366.027462 -142.37589)
		(end 366.422686 -142.37589)
		(width 0.4572)
		(layer "In2.Cu")
		(net "P3V3_AUX")
	)
	(segment
		(start 311.096406 -193.935096)
		(end 311.869836 -194.708526)
		(width 0.4572)
		(layer "In2.Cu")
		(net "P3V3_AUX")
	)
	(segment
		(start 23.613618 -324.615556)
		(end 19.08429 -329.144884)
		(width 0.4572)
		(layer "In2.Cu")
		(net "P3V3_AUX")
	)
	(segment
		(start 341.33536 -16.995394)
		(end 341.33536 -14.947392)
		(width 0.4572)
		(layer "In2.Cu")
		(net "P3V3_AUX")
	)
	(segment
		(start 320.340736 -203.980796)
		(end 320.664078 -203.657454)
		(width 0.4572)
		(layer "In2.Cu")
		(net "P3V3_AUX")
	)
	(segment
		(start 320.242184 -201.453242)
		(end 319.137538 -202.557888)
		(width 0.4572)
		(layer "In2.Cu")
		(net "P3V3_AUX")
	)
	(segment
		(start 341.33536 -14.947392)
		(end 342.224614 -14.058138)
		(width 0.4572)
		(layer "In2.Cu")
		(net "P3V3_AUX")
	)
	(segment
		(start 19.08429 -329.144884)
		(end 19.08429 -332.058264)
		(width 0.4572)
		(layer "In2.Cu")
		(net "P3V3_AUX")
	)
	(segment
		(start 308.511194 -193.935096)
		(end 311.096406 -193.935096)
		(width 0.4572)
		(layer "In2.Cu")
		(net "P3V3_AUX")
	)
	(segment
		(start 371.733826 -138.45667)
		(end 371.766338 -138.424158)
		(width 0.4572)
		(layer "In2.Cu")
		(net "P3V3_AUX")
	)
	(segment
		(start 363.678978 -14.058138)
		(end 364.302548 -13.434568)
		(width 0.4572)
		(layer "In2.Cu")
		(net "P3V3_AUX")
	)
	(segment
		(start 400.160744 -137.023602)
		(end 398.797272 -135.66013)
		(width 0.4572)
		(layer "In2.Cu")
		(net "P3V3_AUX")
	)
	(segment
		(start 73.66 -56.53405)
		(end 72.84085 -56.53405)
		(width 0.4572)
		(layer "In2.Cu")
		(net "P3V3_AUX")
	)
	(segment
		(start 19.08429 -332.058264)
		(end 17.361916 -333.780638)
		(width 0.4572)
		(layer "In2.Cu")
		(net "P3V3_AUX")
	)
	(segment
		(start 406.875488 -137.023602)
		(end 400.160744 -137.023602)
		(width 0.4572)
		(layer "In2.Cu")
		(net "P3V3_AUX")
	)
	(segment
		(start 313.253882 -194.708526)
		(end 314.931806 -196.38645)
		(width 0.4572)
		(layer "In2.Cu")
		(net "P3V3_AUX")
	)
	(segment
		(start 314.931806 -196.38645)
		(end 316.567312 -196.38645)
		(width 0.4572)
		(layer "In2.Cu")
		(net "P3V3_AUX")
	)
	(segment
		(start 316.567312 -196.38645)
		(end 320.242184 -200.061322)
		(width 0.4572)
		(layer "In2.Cu")
		(net "P3V3_AUX")
	)
	(segment
		(start 319.137538 -202.902312)
		(end 319.137538 -203.496418)
		(width 0.4572)
		(layer "In2.Cu")
		(net "P3V3_AUX")
	)
	(segment
		(start 319.137538 -203.496418)
		(end 319.621916 -203.980796)
		(width 0.4572)
		(layer "In2.Cu")
		(net "P3V3_AUX")
	)
	(segment
		(start 319.621916 -203.980796)
		(end 320.340736 -203.980796)
		(width 0.4572)
		(layer "In2.Cu")
		(net "P3V3_AUX")
	)
	(segment
		(start 366.422686 -142.37589)
		(end 370.341906 -138.45667)
		(width 0.4572)
		(layer "In2.Cu")
		(net "P3V3_AUX")
	)
	(segment
		(start 61.865256 -193.569082)
		(end 62.19698 -193.900806)
		(width 0.4572)
		(layer "In4.Cu")
		(net "P3V3_AUX")
	)
	(segment
		(start 370.61394 -142.164562)
		(end 370.61394 -139.576556)
		(width 0.4572)
		(layer "In4.Cu")
		(net "P3V3_AUX")
	)
	(segment
		(start 396.228316 -328.833988)
		(end 397.283178 -327.779126)
		(width 0.4572)
		(layer "In4.Cu")
		(net "P3V3_AUX")
	)
	(segment
		(start 62.578234 -196.186552)
		(end 67.731386 -201.339704)
		(width 0.4572)
		(layer "In4.Cu")
		(net "P3V3_AUX")
	)
	(segment
		(start 211.343748 -324.488302)
		(end 211.397596 -324.434454)
		(width 0.508)
		(layer "In4.Cu")
		(net "P3V3_AUX")
	)
	(segment
		(start 193.460116 -378.660406)
		(end 192.573402 -378.660406)
		(width 0.508)
		(layer "In4.Cu")
		(net "P3V3_AUX")
	)
	(segment
		(start 372.06682 -16.176244)
		(end 372.06682 -14.999716)
		(width 0.4572)
		(layer "In4.Cu")
		(net "P3V3_AUX")
	)
	(segment
		(start 194.19062 -379.39091)
		(end 193.460116 -378.660406)
		(width 0.508)
		(layer "In4.Cu")
		(net "P3V3_AUX")
	)
	(segment
		(start 197.376542 -376.566176)
		(end 197.376542 -378.602494)
		(width 0.508)
		(layer "In4.Cu")
		(net "P3V3_AUX")
	)
	(segment
		(start 69.64426 -202.293728)
		(end 69.64426 -203.159106)
		(width 0.4572)
		(layer "In4.Cu")
		(net "P3V3_AUX")
	)
	(segment
		(start 426.101002 -372.267734)
		(end 430.53508 -372.267734)
		(width 0.4572)
		(layer "In4.Cu")
		(net "P3V3_AUX")
	)
	(segment
		(start 396.603982 -323.566282)
		(end 395.403578 -323.566282)
		(width 0.4572)
		(layer "In4.Cu")
		(net "P3V3_AUX")
	)
	(segment
		(start 69.64426 -203.159106)
		(end 69.320918 -203.482448)
		(width 0.4572)
		(layer "In4.Cu")
		(net "P3V3_AUX")
	)
	(segment
		(start 396.228316 -345.234768)
		(end 396.228316 -328.833988)
		(width 0.4572)
		(layer "In4.Cu")
		(net "P3V3_AUX")
	)
	(segment
		(start 397.283178 -327.779126)
		(end 397.283178 -324.245478)
		(width 0.4572)
		(layer "In4.Cu")
		(net "P3V3_AUX")
	)
	(segment
		(start 397.247618 -346.25407)
		(end 396.228316 -345.234768)
		(width 0.4572)
		(layer "In4.Cu")
		(net "P3V3_AUX")
	)
	(segment
		(start 397.283178 -324.245478)
		(end 396.603982 -323.566282)
		(width 0.4572)
		(layer "In4.Cu")
		(net "P3V3_AUX")
	)
	(segment
		(start 60.894722 -193.569082)
		(end 61.865256 -193.569082)
		(width 0.4572)
		(layer "In4.Cu")
		(net "P3V3_AUX")
	)
	(segment
		(start 371.766338 -138.424158)
		(end 373.998998 -138.424158)
		(width 0.4572)
		(layer "In4.Cu")
		(net "P3V3_AUX")
	)
	(segment
		(start 161.313368 -324.383908)
		(end 162.635438 -323.061838)
		(width 0.508)
		(layer "In4.Cu")
		(net "P3V3_AUX")
	)
	(segment
		(start 68.690236 -201.339704)
		(end 69.64426 -202.293728)
		(width 0.4572)
		(layer "In4.Cu")
		(net "P3V3_AUX")
	)
	(segment
		(start 395.403578 -323.566282)
		(end 394.891768 -323.054472)
		(width 0.4572)
		(layer "In4.Cu")
		(net "P3V3_AUX")
	)
	(segment
		(start 197.376542 -378.602494)
		(end 196.588126 -379.39091)
		(width 0.508)
		(layer "In4.Cu")
		(net "P3V3_AUX")
	)
	(segment
		(start 228.784658 -371.73789)
		(end 202.204828 -371.73789)
		(width 0.508)
		(layer "In4.Cu")
		(net "P3V3_AUX")
	)
	(segment
		(start 377.14047 -135.282686)
		(end 385.12242 -135.282686)
		(width 0.4572)
		(layer "In4.Cu")
		(net "P3V3_AUX")
	)
	(segment
		(start 60.571126 -193.93535)
		(end 60.571126 -193.892678)
		(width 0.4572)
		(layer "In4.Cu")
		(net "P3V3_AUX")
	)
	(segment
		(start 62.19698 -193.900806)
		(end 62.19698 -195.805298)
		(width 0.4572)
		(layer "In4.Cu")
		(net "P3V3_AUX")
	)
	(segment
		(start 364.302548 -13.434568)
		(end 368.296444 -17.428464)
		(width 0.4572)
		(layer "In4.Cu")
		(net "P3V3_AUX")
	)
	(segment
		(start 230.385874 -370.136674)
		(end 228.784658 -371.73789)
		(width 0.508)
		(layer "In4.Cu")
		(net "P3V3_AUX")
	)
	(segment
		(start 385.12242 -135.282686)
		(end 385.446016 -135.606282)
		(width 0.4572)
		(layer "In4.Cu")
		(net "P3V3_AUX")
	)
	(segment
		(start 202.204828 -371.73789)
		(end 197.376542 -376.566176)
		(width 0.508)
		(layer "In4.Cu")
		(net "P3V3_AUX")
	)
	(segment
		(start 162.635438 -323.061838)
		(end 207.49641 -323.061838)
		(width 0.508)
		(layer "In4.Cu")
		(net "P3V3_AUX")
	)
	(segment
		(start 394.891768 -323.054472)
		(end 394.891768 -322.500752)
		(width 0.4572)
		(layer "In4.Cu")
		(net "P3V3_AUX")
	)
	(segment
		(start 370.937536 -142.488158)
		(end 370.61394 -142.164562)
		(width 0.4572)
		(layer "In4.Cu")
		(net "P3V3_AUX")
	)
	(segment
		(start 370.8146 -17.428464)
		(end 372.06682 -16.176244)
		(width 0.4572)
		(layer "In4.Cu")
		(net "P3V3_AUX")
	)
	(segment
		(start 60.571126 -193.892678)
		(end 60.894722 -193.569082)
		(width 0.4572)
		(layer "In4.Cu")
		(net "P3V3_AUX")
	)
	(segment
		(start 69.320918 -203.482448)
		(end 69.101716 -203.482448)
		(width 0.4572)
		(layer "In4.Cu")
		(net "P3V3_AUX")
	)
	(segment
		(start 67.731386 -201.339704)
		(end 68.690236 -201.339704)
		(width 0.4572)
		(layer "In4.Cu")
		(net "P3V3_AUX")
	)
	(segment
		(start 373.998998 -138.424158)
		(end 377.14047 -135.282686)
		(width 0.4572)
		(layer "In4.Cu")
		(net "P3V3_AUX")
	)
	(segment
		(start 208.922874 -324.488302)
		(end 211.343748 -324.488302)
		(width 0.508)
		(layer "In4.Cu")
		(net "P3V3_AUX")
	)
	(segment
		(start 370.61394 -139.576556)
		(end 371.766338 -138.424158)
		(width 0.4572)
		(layer "In4.Cu")
		(net "P3V3_AUX")
	)
	(segment
		(start 424.217338 -366.854994)
		(end 424.217338 -370.38407)
		(width 0.4572)
		(layer "In4.Cu")
		(net "P3V3_AUX")
	)
	(segment
		(start 62.19698 -195.805298)
		(end 62.578234 -196.186552)
		(width 0.4572)
		(layer "In4.Cu")
		(net "P3V3_AUX")
	)
	(segment
		(start 196.588126 -379.39091)
		(end 194.19062 -379.39091)
		(width 0.508)
		(layer "In4.Cu")
		(net "P3V3_AUX")
	)
	(segment
		(start 207.49641 -323.061838)
		(end 208.922874 -324.488302)
		(width 0.508)
		(layer "In4.Cu")
		(net "P3V3_AUX")
	)
	(segment
		(start 385.446016 -135.606282)
		(end 385.446016 -136.32942)
		(width 0.4572)
		(layer "In4.Cu")
		(net "P3V3_AUX")
	)
	(segment
		(start 368.296444 -17.428464)
		(end 370.8146 -17.428464)
		(width 0.4572)
		(layer "In4.Cu")
		(net "P3V3_AUX")
	)
	(segment
		(start 424.217338 -370.38407)
		(end 426.101002 -372.267734)
		(width 0.4572)
		(layer "In4.Cu")
		(net "P3V3_AUX")
	)
	(segment
		(start 385.446016 -136.32942)
		(end 385.256278 -136.519158)
		(width 0.4572)
		(layer "In4.Cu")
		(net "P3V3_AUX")
	)
	(segment
		(start 371.921278 -142.488158)
		(end 370.937536 -142.488158)
		(width 0.4572)
		(layer "In4.Cu")
		(net "P3V3_AUX")
	)
	(segment
		(start 25.89657 -367.95964)
		(end 27.031442 -369.094512)
		(width 0.4572)
		(layer "In6.Cu")
		(net "P3V3_AUX")
	)
	(segment
		(start 452.577454 -44.474384)
		(end 454.776078 -44.474384)
		(width 0.4572)
		(layer "In6.Cu")
		(net "P3V3_AUX")
	)
	(segment
		(start 299.84065 -364.414562)
		(end 299.84065 -366.504982)
		(width 0.4572)
		(layer "In6.Cu")
		(net "P3V3_AUX")
	)
	(segment
		(start 30.612334 -371.730524)
		(end 31.587948 -370.75491)
		(width 0.4572)
		(layer "In6.Cu")
		(net "P3V3_AUX")
	)
	(segment
		(start 462.350612 -47.610014)
		(end 461.105758 -46.36516)
		(width 0.4572)
		(layer "In6.Cu")
		(net "P3V3_AUX")
	)
	(segment
		(start 300.238668 -362.839)
		(end 300.9646 -362.839)
		(width 0.4572)
		(layer "In6.Cu")
		(net "P3V3_AUX")
	)
	(segment
		(start 302.419004 -359.283)
		(end 302.095408 -358.959404)
		(width 0.4572)
		(layer "In6.Cu")
		(net "P3V3_AUX")
	)
	(segment
		(start 36.492942 -370.75491)
		(end 37.67836 -369.569492)
		(width 0.4572)
		(layer "In6.Cu")
		(net "P3V3_AUX")
	)
	(segment
		(start 452.355966 -44.695872)
		(end 452.577454 -44.474384)
		(width 0.4572)
		(layer "In6.Cu")
		(net "P3V3_AUX")
	)
	(segment
		(start 23.261828 -356.797102)
		(end 23.261828 -356.355904)
		(width 0.4572)
		(layer "In6.Cu")
		(net "P3V3_AUX")
	)
	(segment
		(start 459.129384 -67.089782)
		(end 463.193892 -63.025274)
		(width 0.4572)
		(layer "In6.Cu")
		(net "P3V3_AUX")
	)
	(segment
		(start 454.776078 -44.474384)
		(end 455.534776 -45.233082)
		(width 0.4572)
		(layer "In6.Cu")
		(net "P3V3_AUX")
	)
	(segment
		(start 300.9646 -363.290612)
		(end 299.84065 -364.414562)
		(width 0.4572)
		(layer "In6.Cu")
		(net "P3V3_AUX")
	)
	(segment
		(start 299.423582 -360.491278)
		(end 299.423582 -362.023914)
		(width 0.4572)
		(layer "In6.Cu")
		(net "P3V3_AUX")
	)
	(segment
		(start 461.105758 -46.36516)
		(end 456.666854 -46.36516)
		(width 0.4572)
		(layer "In6.Cu")
		(net "P3V3_AUX")
	)
	(segment
		(start 463.193892 -54.60365)
		(end 462.350612 -53.76037)
		(width 0.4572)
		(layer "In6.Cu")
		(net "P3V3_AUX")
	)
	(segment
		(start 23.261828 -356.355904)
		(end 21.776944 -354.87102)
		(width 0.4572)
		(layer "In6.Cu")
		(net "P3V3_AUX")
	)
	(segment
		(start 303.276 -359.283)
		(end 302.419004 -359.283)
		(width 0.4572)
		(layer "In6.Cu")
		(net "P3V3_AUX")
	)
	(segment
		(start 300.9646 -362.839)
		(end 300.9646 -363.290612)
		(width 0.4572)
		(layer "In6.Cu")
		(net "P3V3_AUX")
	)
	(segment
		(start 299.84065 -366.504982)
		(end 296.970196 -369.375436)
		(width 0.4572)
		(layer "In6.Cu")
		(net "P3V3_AUX")
	)
	(segment
		(start 37.67836 -369.569492)
		(end 37.67836 -369.487196)
		(width 0.4572)
		(layer "In6.Cu")
		(net "P3V3_AUX")
	)
	(segment
		(start 21.776944 -354.87102)
		(end 21.776944 -353.465638)
		(width 0.4572)
		(layer "In6.Cu")
		(net "P3V3_AUX")
	)
	(segment
		(start 456.666854 -46.36516)
		(end 455.534776 -45.233082)
		(width 0.4572)
		(layer "In6.Cu")
		(net "P3V3_AUX")
	)
	(segment
		(start 296.970196 -369.375436)
		(end 296.2529 -369.375436)
		(width 0.4572)
		(layer "In6.Cu")
		(net "P3V3_AUX")
	)
	(segment
		(start 27.031442 -369.094512)
		(end 27.031442 -369.774216)
		(width 0.4572)
		(layer "In6.Cu")
		(net "P3V3_AUX")
	)
	(segment
		(start 22.704298 -357.354632)
		(end 23.261828 -356.797102)
		(width 0.4572)
		(layer "In6.Cu")
		(net "P3V3_AUX")
	)
	(segment
		(start 22.704298 -361.286298)
		(end 22.704298 -357.354632)
		(width 0.4572)
		(layer "In6.Cu")
		(net "P3V3_AUX")
	)
	(segment
		(start 28.98775 -371.730524)
		(end 30.612334 -371.730524)
		(width 0.4572)
		(layer "In6.Cu")
		(net "P3V3_AUX")
	)
	(segment
		(start 300.955456 -358.959404)
		(end 299.423582 -360.491278)
		(width 0.4572)
		(layer "In6.Cu")
		(net "P3V3_AUX")
	)
	(segment
		(start 299.423582 -362.023914)
		(end 300.238668 -362.839)
		(width 0.4572)
		(layer "In6.Cu")
		(net "P3V3_AUX")
	)
	(segment
		(start 31.587948 -370.75491)
		(end 36.492942 -370.75491)
		(width 0.4572)
		(layer "In6.Cu")
		(net "P3V3_AUX")
	)
	(segment
		(start 27.031442 -369.774216)
		(end 28.98775 -371.730524)
		(width 0.4572)
		(layer "In6.Cu")
		(net "P3V3_AUX")
	)
	(segment
		(start 302.095408 -358.959404)
		(end 300.955456 -358.959404)
		(width 0.4572)
		(layer "In6.Cu")
		(net "P3V3_AUX")
	)
	(segment
		(start 452.355966 -45.569632)
		(end 452.355966 -44.695872)
		(width 0.4572)
		(layer "In6.Cu")
		(net "P3V3_AUX")
	)
	(segment
		(start 462.350612 -53.76037)
		(end 462.350612 -47.610014)
		(width 0.4572)
		(layer "In6.Cu")
		(net "P3V3_AUX")
	)
	(segment
		(start 463.193892 -63.025274)
		(end 463.193892 -54.60365)
		(width 0.4572)
		(layer "In6.Cu")
		(net "P3V3_AUX")
	)
	(segment
		(start 23.622 -362.204)
		(end 22.704298 -361.286298)
		(width 0.4572)
		(layer "In6.Cu")
		(net "P3V3_AUX")
	)
	(segment
		(start 414.512252 -370.305584)
		(end 423.069258 -370.305584)
		(width 0.4572)
		(layer "In11.Cu")
		(net "P3V3_AUX")
	)
	(segment
		(start 155.612846 -352.98888)
		(end 155.612846 -354.568252)
		(width 0.4572)
		(layer "In11.Cu")
		(net "P3V3_AUX")
	)
	(segment
		(start 88.635078 -144.88541)
		(end 88.285828 -144.53616)
		(width 0.4572)
		(layer "In11.Cu")
		(net "P3V3_AUX")
	)
	(segment
		(start 412.518606 -364.079536)
		(end 412.82239 -364.079536)
		(width 0.4572)
		(layer "In11.Cu")
		(net "P3V3_AUX")
	)
	(segment
		(start 12.384532 -401.009104)
		(end 13.728192 -402.352764)
		(width 0.4572)
		(layer "In11.Cu")
		(net "P3V3_AUX")
	)
	(segment
		(start 155.612846 -354.568252)
		(end 156.216604 -355.17201)
		(width 0.4572)
		(layer "In11.Cu")
		(net "P3V3_AUX")
	)
	(segment
		(start 88.285828 -144.53616)
		(end 86.578948 -144.53616)
		(width 0.4572)
		(layer "In11.Cu")
		(net "P3V3_AUX")
	)
	(segment
		(start 156.62021 -352.102928)
		(end 156.498798 -352.102928)
		(width 0.4572)
		(layer "In11.Cu")
		(net "P3V3_AUX")
	)
	(segment
		(start 86.255352 -144.859756)
		(end 83.354926 -144.859756)
		(width 0.4572)
		(layer "In11.Cu")
		(net "P3V3_AUX")
	)
	(segment
		(start 254.306578 -39.34333)
		(end 255.266952 -38.382956)
		(width 0.4572)
		(layer "In11.Cu")
		(net "P3V3_AUX")
	)
	(segment
		(start 136.669018 -143.351758)
		(end 129.813812 -136.496552)
		(width 1.016)
		(layer "In11.Cu")
		(net "P3V3_AUX")
	)
	(segment
		(start 412.706312 -365.468154)
		(end 413.974788 -366.73663)
		(width 0.4572)
		(layer "In11.Cu")
		(net "P3V3_AUX")
	)
	(segment
		(start 9.444228 -410.128466)
		(end 9.444228 -411.582616)
		(width 0.4572)
		(layer "In11.Cu")
		(net "P3V3_AUX")
	)
	(segment
		(start 89.193878 -144.88541)
		(end 88.635078 -144.88541)
		(width 0.4572)
		(layer "In11.Cu")
		(net "P3V3_AUX")
	)
	(segment
		(start 119.794782 -136.496552)
		(end 116.51615 -133.21792)
		(width 1.016)
		(layer "In11.Cu")
		(net "P3V3_AUX")
	)
	(segment
		(start 89.193878 -140.943584)
		(end 89.158572 -140.943584)
		(width 0.4572)
		(layer "In11.Cu")
		(net "P3V3_AUX")
	)
	(segment
		(start 411.720538 -362.375958)
		(end 411.720538 -363.281468)
		(width 0.4572)
		(layer "In11.Cu")
		(net "P3V3_AUX")
	)
	(segment
		(start 10.050018 -409.522676)
		(end 9.444228 -410.128466)
		(width 0.4572)
		(layer "In11.Cu")
		(net "P3V3_AUX")
	)
	(segment
		(start 19.385026 -406.42667)
		(end 19.385026 -407.259028)
		(width 0.4572)
		(layer "In11.Cu")
		(net "P3V3_AUX")
	)
	(segment
		(start 83.354926 -144.859756)
		(end 80.797146 -147.417536)
		(width 0.4572)
		(layer "In11.Cu")
		(net "P3V3_AUX")
	)
	(segment
		(start 89.920572 -144.451832)
		(end 89.920572 -141.670278)
		(width 0.4572)
		(layer "In11.Cu")
		(net "P3V3_AUX")
	)
	(segment
		(start 80.797146 -147.417536)
		(end 75.64501 -147.417536)
		(width 0.4572)
		(layer "In11.Cu")
		(net "P3V3_AUX")
	)
	(segment
		(start 271.281652 -43.596306)
		(end 276.204934 -38.673024)
		(width 0.4572)
		(layer "In11.Cu")
		(net "P3V3_AUX")
	)
	(segment
		(start 417.801806 -347.64472)
		(end 417.801806 -353.648264)
		(width 0.4572)
		(layer "In11.Cu")
		(net "P3V3_AUX")
	)
	(segment
		(start 13.728192 -403.772878)
		(end 14.170406 -404.215092)
		(width 0.4572)
		(layer "In11.Cu")
		(net "P3V3_AUX")
	)
	(segment
		(start 413.974788 -369.76812)
		(end 414.512252 -370.305584)
		(width 0.4572)
		(layer "In11.Cu")
		(net "P3V3_AUX")
	)
	(segment
		(start 17.305782 -404.347426)
		(end 19.385026 -406.42667)
		(width 0.4572)
		(layer "In11.Cu")
		(net "P3V3_AUX")
	)
	(segment
		(start 414.7058 -344.548714)
		(end 417.801806 -347.64472)
		(width 0.4572)
		(layer "In11.Cu")
		(net "P3V3_AUX")
	)
	(segment
		(start 155.659328 -351.142046)
		(end 156.62021 -352.102928)
		(width 0.4572)
		(layer "In11.Cu")
		(net "P3V3_AUX")
	)
	(segment
		(start 10.050018 -405.565864)
		(end 10.050018 -409.522676)
		(width 0.4572)
		(layer "In11.Cu")
		(net "P3V3_AUX")
	)
	(segment
		(start 413.302196 -360.7943)
		(end 411.720538 -362.375958)
		(width 0.4572)
		(layer "In11.Cu")
		(net "P3V3_AUX")
	)
	(segment
		(start 413.974788 -366.73663)
		(end 413.974788 -369.76812)
		(width 0.4572)
		(layer "In11.Cu")
		(net "P3V3_AUX")
	)
	(segment
		(start 257.833876 -38.382956)
		(end 263.047226 -43.596306)
		(width 0.4572)
		(layer "In11.Cu")
		(net "P3V3_AUX")
	)
	(segment
		(start 9.444228 -411.582616)
		(end 9.642094 -412.06039)
		(width 0.4572)
		(layer "In11.Cu")
		(net "P3V3_AUX")
	)
	(segment
		(start 9.642094 -412.06039)
		(end 9.642094 -412.521908)
		(width 0.4572)
		(layer "In11.Cu")
		(net "P3V3_AUX")
	)
	(segment
		(start 411.720538 -363.281468)
		(end 412.518606 -364.079536)
		(width 0.4572)
		(layer "In11.Cu")
		(net "P3V3_AUX")
	)
	(segment
		(start 423.069258 -370.305584)
		(end 424.217338 -369.157504)
		(width 0.4572)
		(layer "In11.Cu")
		(net "P3V3_AUX")
	)
	(segment
		(start 14.170406 -404.215092)
		(end 16.416274 -404.215092)
		(width 0.4572)
		(layer "In11.Cu")
		(net "P3V3_AUX")
	)
	(segment
		(start 156.394912 -347.260164)
		(end 155.659328 -347.995748)
		(width 0.4572)
		(layer "In11.Cu")
		(net "P3V3_AUX")
	)
	(segment
		(start 156.216604 -355.17201)
		(end 164.600636 -355.17201)
		(width 0.4572)
		(layer "In11.Cu")
		(net "P3V3_AUX")
	)
	(segment
		(start 89.920572 -141.670278)
		(end 89.193878 -140.943584)
		(width 0.4572)
		(layer "In11.Cu")
		(net "P3V3_AUX")
	)
	(segment
		(start 412.82239 -364.079536)
		(end 412.706312 -364.195614)
		(width 0.4572)
		(layer "In11.Cu")
		(net "P3V3_AUX")
	)
	(segment
		(start 9.642094 -412.521908)
		(end 8.932418 -413.231584)
		(width 0.4572)
		(layer "In11.Cu")
		(net "P3V3_AUX")
	)
	(segment
		(start 252.541278 -39.34333)
		(end 253.89332 -39.34333)
		(width 0.4572)
		(layer "In11.Cu")
		(net "P3V3_AUX")
	)
	(segment
		(start 136.669018 -150.533608)
		(end 136.669018 -143.351758)
		(width 1.016)
		(layer "In11.Cu")
		(net "P3V3_AUX")
	)
	(segment
		(start 12.384532 -396.06093)
		(end 12.384532 -401.009104)
		(width 0.4572)
		(layer "In11.Cu")
		(net "P3V3_AUX")
	)
	(segment
		(start 89.193878 -144.88541)
		(end 89.486994 -144.88541)
		(width 0.4572)
		(layer "In11.Cu")
		(net "P3V3_AUX")
	)
	(segment
		(start 416.836098 -354.613972)
		(end 413.302196 -358.147874)
		(width 0.4572)
		(layer "In11.Cu")
		(net "P3V3_AUX")
	)
	(segment
		(start 403.980142 -344.548714)
		(end 414.7058 -344.548714)
		(width 0.4572)
		(layer "In11.Cu")
		(net "P3V3_AUX")
	)
	(segment
		(start 89.486994 -144.88541)
		(end 89.920572 -144.451832)
		(width 0.4572)
		(layer "In11.Cu")
		(net "P3V3_AUX")
	)
	(segment
		(start 19.385026 -407.259028)
		(end 21.547582 -409.421584)
		(width 0.4572)
		(layer "In11.Cu")
		(net "P3V3_AUX")
	)
	(segment
		(start 253.89332 -39.34333)
		(end 254.306578 -39.34333)
		(width 0.4572)
		(layer "In11.Cu")
		(net "P3V3_AUX")
	)
	(segment
		(start 17.305782 -403.325584)
		(end 17.305782 -404.347426)
		(width 0.4572)
		(layer "In11.Cu")
		(net "P3V3_AUX")
	)
	(segment
		(start 255.266952 -38.382956)
		(end 257.833876 -38.382956)
		(width 0.4572)
		(layer "In11.Cu")
		(net "P3V3_AUX")
	)
	(segment
		(start 263.047226 -43.596306)
		(end 271.281652 -43.596306)
		(width 0.4572)
		(layer "In11.Cu")
		(net "P3V3_AUX")
	)
	(segment
		(start 156.473398 -347.260164)
		(end 156.394912 -347.260164)
		(width 0.4572)
		(layer "In11.Cu")
		(net "P3V3_AUX")
	)
	(segment
		(start 164.600636 -355.17201)
		(end 165.576758 -354.195888)
		(width 0.4572)
		(layer "In11.Cu")
		(net "P3V3_AUX")
	)
	(segment
		(start 16.416274 -404.215092)
		(end 17.305782 -403.325584)
		(width 0.4572)
		(layer "In11.Cu")
		(net "P3V3_AUX")
	)
	(segment
		(start 156.498798 -352.102928)
		(end 155.612846 -352.98888)
		(width 0.4572)
		(layer "In11.Cu")
		(net "P3V3_AUX")
	)
	(segment
		(start 155.659328 -347.995748)
		(end 155.659328 -351.142046)
		(width 0.4572)
		(layer "In11.Cu")
		(net "P3V3_AUX")
	)
	(segment
		(start 402.274786 -346.25407)
		(end 403.980142 -344.548714)
		(width 0.4572)
		(layer "In11.Cu")
		(net "P3V3_AUX")
	)
	(segment
		(start 276.204934 -38.673024)
		(end 276.204934 -38.027864)
		(width 0.4572)
		(layer "In11.Cu")
		(net "P3V3_AUX")
	)
	(segment
		(start 417.801806 -353.648264)
		(end 416.836098 -354.613972)
		(width 0.4572)
		(layer "In11.Cu")
		(net "P3V3_AUX")
	)
	(segment
		(start 413.302196 -358.147874)
		(end 413.302196 -360.7943)
		(width 0.4572)
		(layer "In11.Cu")
		(net "P3V3_AUX")
	)
	(segment
		(start 397.247618 -346.25407)
		(end 402.274786 -346.25407)
		(width 0.4572)
		(layer "In11.Cu")
		(net "P3V3_AUX")
	)
	(segment
		(start 9.666732 -404.21687)
		(end 9.666732 -405.182578)
		(width 0.4572)
		(layer "In11.Cu")
		(net "P3V3_AUX")
	)
	(segment
		(start 424.217338 -369.157504)
		(end 424.217338 -366.854994)
		(width 0.4572)
		(layer "In11.Cu")
		(net "P3V3_AUX")
	)
	(segment
		(start 9.666732 -405.182578)
		(end 10.050018 -405.565864)
		(width 0.4572)
		(layer "In11.Cu")
		(net "P3V3_AUX")
	)
	(segment
		(start 13.728192 -402.352764)
		(end 13.728192 -403.772878)
		(width 0.4572)
		(layer "In11.Cu")
		(net "P3V3_AUX")
	)
	(segment
		(start 129.813812 -136.496552)
		(end 119.794782 -136.496552)
		(width 1.016)
		(layer "In11.Cu")
		(net "P3V3_AUX")
	)
	(segment
		(start 165.576758 -354.195888)
		(end 165.576758 -353.332796)
		(width 0.4572)
		(layer "In11.Cu")
		(net "P3V3_AUX")
	)
	(segment
		(start 412.706312 -364.195614)
		(end 412.706312 -365.468154)
		(width 0.4572)
		(layer "In11.Cu")
		(net "P3V3_AUX")
	)
	(segment
		(start 86.578948 -144.53616)
		(end 86.255352 -144.859756)
		(width 0.4572)
		(layer "In11.Cu")
		(net "P3V3_AUX")
	)
	(segment
		(start 457.200508 -72.373236)
		(end 457.91628 -73.089008)
		(width 0.508)
		(layer "In13.Cu")
		(net "P3V3_AUX")
	)
	(segment
		(start 74.65187 -51.056286)
		(end 74.717402 -50.990754)
		(width 0.4572)
		(layer "In13.Cu")
		(net "P3V3_AUX")
	)
	(segment
		(start 449.692268 -72.373236)
		(end 450.40804 -71.657464)
		(width 0.508)
		(layer "In13.Cu")
		(net "P3V3_AUX")
	)
	(segment
		(start 456.484736 -73.089008)
		(end 457.200508 -72.373236)
		(width 0.508)
		(layer "In13.Cu")
		(net "P3V3_AUX")
	)
	(segment
		(start 366.027462 -131.185666)
		(end 366.027462 -142.37589)
		(width 0.4572)
		(layer "In13.Cu")
		(net "P3V3_AUX")
	)
	(segment
		(start 67.294506 -52.705)
		(end 69.469 -52.705)
		(width 0.4572)
		(layer "In13.Cu")
		(net "P3V3_AUX")
	)
	(segment
		(start 448.976496 -73.089008)
		(end 449.692268 -72.373236)
		(width 0.508)
		(layer "In13.Cu")
		(net "P3V3_AUX")
	)
	(segment
		(start 456.484736 -71.657464)
		(end 457.200508 -72.373236)
		(width 0.508)
		(layer "In13.Cu")
		(net "P3V3_AUX")
	)
	(segment
		(start 199.80402 -133.84022)
		(end 200.43775 -134.47395)
		(width 0.4572)
		(layer "In13.Cu")
		(net "P3V3_AUX")
	)
	(segment
		(start 201.07148 -133.84022)
		(end 200.43775 -134.47395)
		(width 0.4572)
		(layer "In13.Cu")
		(net "P3V3_AUX")
	)
	(segment
		(start 457.200508 -72.373236)
		(end 457.91628 -71.657464)
		(width 0.508)
		(layer "In13.Cu")
		(net "P3V3_AUX")
	)
	(segment
		(start 206.472282 -133.84022)
		(end 201.07148 -133.84022)
		(width 0.4572)
		(layer "In13.Cu")
		(net "P3V3_AUX")
	)
	(segment
		(start 212.52307 -133.76656)
		(end 206.545942 -133.76656)
		(width 0.4572)
		(layer "In13.Cu")
		(net "P3V3_AUX")
	)
	(segment
		(start 449.692268 -72.373236)
		(end 450.40804 -73.089008)
		(width 0.508)
		(layer "In13.Cu")
		(net "P3V3_AUX")
	)
	(segment
		(start 196.832728 -133.84022)
		(end 199.80402 -133.84022)
		(width 0.4572)
		(layer "In13.Cu")
		(net "P3V3_AUX")
	)
	(segment
		(start 448.976496 -71.657464)
		(end 449.692268 -72.373236)
		(width 0.508)
		(layer "In13.Cu")
		(net "P3V3_AUX")
	)
	(segment
		(start 206.545942 -133.76656)
		(end 206.472282 -133.84022)
		(width 0.4572)
		(layer "In13.Cu")
		(net "P3V3_AUX")
	)
	(segment
		(start 72.516746 -51.056286)
		(end 74.65187 -51.056286)
		(width 0.4572)
		(layer "In13.Cu")
		(net "P3V3_AUX")
	)
	(segment
		(start 69.469 -52.705)
		(end 70.868032 -52.705)
		(width 0.4572)
		(layer "In13.Cu")
		(net "P3V3_AUX")
	)
	(segment
		(start 65.643506 -54.356)
		(end 67.294506 -52.705)
		(width 0.4572)
		(layer "In13.Cu")
		(net "P3V3_AUX")
	)
	(segment
		(start 366.34039 -130.872738)
		(end 366.027462 -131.185666)
		(width 0.4572)
		(layer "In13.Cu")
		(net "P3V3_AUX")
	)
	(segment
		(start 70.868032 -52.705)
		(end 72.516746 -51.056286)
		(width 0.4572)
		(layer "In13.Cu")
		(net "P3V3_AUX")
	)
	(segment
		(start 196.088 -134.584948)
		(end 196.832728 -133.84022)
		(width 0.4572)
		(layer "In13.Cu")
		(net "P3V3_AUX")
	)
	(segment
		(start 455.40676 -21.33219)
		(end 454.988422 -20.913852)
		(width 0.4572)
		(layer "In15.Cu")
		(net "P3V3_AUX")
	)
	(segment
		(start 454.181972 -31.48584)
		(end 455.40676 -30.261052)
		(width 0.4572)
		(layer "In15.Cu")
		(net "P3V3_AUX")
	)
	(segment
		(start 454.988422 -20.913852)
		(end 454.203816 -20.913852)
		(width 0.4572)
		(layer "In15.Cu")
		(net "P3V3_AUX")
	)
	(segment
		(start 147.680934 -207.382364)
		(end 147.680934 -206.521812)
		(width 0.508)
		(layer "In15.Cu")
		(net "P3V3_AUX")
	)
	(segment
		(start 438.507886 -164.187886)
		(end 438.507886 -166.024814)
		(width 0.4572)
		(layer "In15.Cu")
		(net "P3V3_AUX")
	)
	(segment
		(start 454.181972 -33.853882)
		(end 454.181972 -31.48584)
		(width 0.4572)
		(layer "In15.Cu")
		(net "P3V3_AUX")
	)
	(segment
		(start 262.743442 -423.969942)
		(end 257.931158 -419.157658)
		(width 0.4572)
		(layer "In15.Cu")
		(net "P3V3_AUX")
	)
	(segment
		(start 317.523368 -369.1763)
		(end 319.1764 -367.523268)
		(width 0.4572)
		(layer "In15.Cu")
		(net "P3V3_AUX")
	)
	(segment
		(start 276.629876 -423.839894)
		(end 276.499828 -423.969942)
		(width 0.4572)
		(layer "In15.Cu")
		(net "P3V3_AUX")
	)
	(segment
		(start 148.478748 -208.180178)
		(end 147.680934 -207.382364)
		(width 0.508)
		(layer "In15.Cu")
		(net "P3V3_AUX")
	)
	(segment
		(start 241.09553 -419.748462)
		(end 241.09553 -420.40683)
		(width 0.4572)
		(layer "In15.Cu")
		(net "P3V3_AUX")
	)
	(segment
		(start 297.521122 -369.1763)
		(end 317.523368 -369.1763)
		(width 0.4572)
		(layer "In15.Cu")
		(net "P3V3_AUX")
	)
	(segment
		(start 297.488102 -369.14328)
		(end 297.521122 -369.1763)
		(width 0.4572)
		(layer "In15.Cu")
		(net "P3V3_AUX")
	)
	(segment
		(start 453.137524 -34.89833)
		(end 454.181972 -33.853882)
		(width 0.4572)
		(layer "In15.Cu")
		(net "P3V3_AUX")
	)
	(segment
		(start 257.931158 -419.157658)
		(end 241.686334 -419.157658)
		(width 0.4572)
		(layer "In15.Cu")
		(net "P3V3_AUX")
	)
	(segment
		(start 319.1764 -367.523268)
		(end 319.1764 -364.363)
		(width 0.4572)
		(layer "In15.Cu")
		(net "P3V3_AUX")
	)
	(segment
		(start 419.655498 -158.496)
		(end 432.816 -158.496)
		(width 0.4572)
		(layer "In15.Cu")
		(net "P3V3_AUX")
	)
	(segment
		(start 276.499828 -423.969942)
		(end 262.743442 -423.969942)
		(width 0.4572)
		(layer "In15.Cu")
		(net "P3V3_AUX")
	)
	(segment
		(start 241.686334 -419.157658)
		(end 241.09553 -419.748462)
		(width 0.4572)
		(layer "In15.Cu")
		(net "P3V3_AUX")
	)
	(segment
		(start 454.203816 -19.839432)
		(end 454.203816 -20.913852)
		(width 0.4572)
		(layer "In15.Cu")
		(net "P3V3_AUX")
	)
	(segment
		(start 455.40676 -30.261052)
		(end 455.40676 -21.33219)
		(width 0.4572)
		(layer "In15.Cu")
		(net "P3V3_AUX")
	)
	(segment
		(start 432.816 -158.496)
		(end 438.507886 -164.187886)
		(width 0.4572)
		(layer "In15.Cu")
		(net "P3V3_AUX")
	)
	(segment
		(start 162.094164 -208.180178)
		(end 148.478748 -208.180178)
		(width 0.508)
		(layer "In15.Cu")
		(net "P3V3_AUX")
	)
	(segment
		(start 418.378132 -157.218634)
		(end 419.655498 -158.496)
		(width 0.4572)
		(layer "In15.Cu")
		(net "P3V3_AUX")
	)
	(segment
		(start 162.171126 -208.25714)
		(end 162.094164 -208.180178)
		(width 0.508)
		(layer "In15.Cu")
		(net "P3V3_AUX")
	)
	(segment
		(start 289.315652 -174.244)
		(end 305.27244 -190.200788)
		(width 0.4572)
		(layer "F.Cu")
		(net "P3V3")
	)
	(segment
		(start 304.927254 -193.99631)
		(end 304.423826 -193.99631)
		(width 0.4572)
		(layer "F.Cu")
		(net "P3V3")
	)
	(segment
		(start 118.89105 -125.349)
		(end 117.482112 -125.349)
		(width 0.381)
		(layer "F.Cu")
		(net "P3V3")
	)
	(segment
		(start 109.659674 -128.27)
		(end 112.903 -128.27)
		(width 0.381)
		(layer "F.Cu")
		(net "P3V3")
	)
	(segment
		(start 305.27244 -193.651124)
		(end 304.927254 -193.99631)
		(width 0.4572)
		(layer "F.Cu")
		(net "P3V3")
	)
	(segment
		(start 281.681936 -174.244)
		(end 289.315652 -174.244)
		(width 0.4572)
		(layer "F.Cu")
		(net "P3V3")
	)
	(segment
		(start 117.482112 -124.086112)
		(end 117.482112 -125.349)
		(width 0.381)
		(layer "F.Cu")
		(net "P3V3")
	)
	(segment
		(start 167.094408 -179.215542)
		(end 167.094408 -180.475128)
		(width 0.4572)
		(layer "F.Cu")
		(net "P3V3")
	)
	(segment
		(start 113.538 -127.635)
		(end 118.618 -127.635)
		(width 0.381)
		(layer "F.Cu")
		(net "P3V3")
	)
	(segment
		(start 112.649 -123.55195)
		(end 116.94795 -123.55195)
		(width 0.381)
		(layer "F.Cu")
		(net "P3V3")
	)
	(segment
		(start 172.334428 -172.541692)
		(end 172.334428 -173.975522)
		(width 0.4572)
		(layer "F.Cu")
		(net "P3V3")
	)
	(segment
		(start 172.477938 -172.398182)
		(end 172.334428 -172.541692)
		(width 0.4572)
		(layer "F.Cu")
		(net "P3V3")
	)
	(segment
		(start 157.489652 -57.368694)
		(end 157.595316 -57.474358)
		(width 0.254)
		(layer "F.Cu")
		(net "P3V3")
	)
	(segment
		(start 163.737544 -183.831992)
		(end 163.737544 -187.401454)
		(width 0.4572)
		(layer "F.Cu")
		(net "P3V3")
	)
	(segment
		(start 116.94795 -123.55195)
		(end 117.482112 -124.086112)
		(width 0.381)
		(layer "F.Cu")
		(net "P3V3")
	)
	(segment
		(start 163.737544 -187.401454)
		(end 164.162486 -187.826396)
		(width 0.4572)
		(layer "F.Cu")
		(net "P3V3")
	)
	(segment
		(start 305.27244 -190.200788)
		(end 305.27244 -193.651124)
		(width 0.4572)
		(layer "F.Cu")
		(net "P3V3")
	)
	(segment
		(start 156.398214 -57.368694)
		(end 157.489652 -57.368694)
		(width 0.254)
		(layer "F.Cu")
		(net "P3V3")
	)
	(segment
		(start 109.165136 -128.764538)
		(end 109.659674 -128.27)
		(width 0.381)
		(layer "F.Cu")
		(net "P3V3")
	)
	(segment
		(start 164.162486 -187.826396)
		(end 170.727624 -187.826396)
		(width 0.4572)
		(layer "F.Cu")
		(net "P3V3")
	)
	(segment
		(start 172.334428 -173.975522)
		(end 167.094408 -179.215542)
		(width 0.4572)
		(layer "F.Cu")
		(net "P3V3")
	)
	(segment
		(start 118.999 -125.24105)
		(end 118.89105 -125.349)
		(width 0.381)
		(layer "F.Cu")
		(net "P3V3")
	)
	(segment
		(start 157.595316 -57.474358)
		(end 157.595316 -58.109104)
		(width 0.4572)
		(layer "F.Cu")
		(net "P3V3")
	)
	(segment
		(start 118.999 -127.254)
		(end 118.999 -125.24105)
		(width 0.381)
		(layer "F.Cu")
		(net "P3V3")
	)
	(segment
		(start 329.992228 -42.176954)
		(end 330.601828 -42.176954)
		(width 0.3556)
		(layer "F.Cu")
		(net "P3V3")
	)
	(segment
		(start 112.903 -128.27)
		(end 113.538 -127.635)
		(width 0.381)
		(layer "F.Cu")
		(net "P3V3")
	)
	(segment
		(start 425.579286 -52.438554)
		(end 426.417486 -52.438554)
		(width 0.4572)
		(layer "F.Cu")
		(net "P3V3")
	)
	(segment
		(start 157.595316 -58.109104)
		(end 157.59557 -58.109358)
		(width 0.4572)
		(layer "F.Cu")
		(net "P3V3")
	)
	(segment
		(start 171.227242 -187.326778)
		(end 171.227242 -186.965082)
		(width 0.4572)
		(layer "F.Cu")
		(net "P3V3")
	)
	(segment
		(start 277.18258 -169.744644)
		(end 281.681936 -174.244)
		(width 0.4572)
		(layer "F.Cu")
		(net "P3V3")
	)
	(segment
		(start 118.618 -127.635)
		(end 118.999 -127.254)
		(width 0.381)
		(layer "F.Cu")
		(net "P3V3")
	)
	(segment
		(start 170.727624 -187.826396)
		(end 171.227242 -187.326778)
		(width 0.4572)
		(layer "F.Cu")
		(net "P3V3")
	)
	(segment
		(start 167.094408 -180.475128)
		(end 163.737544 -183.831992)
		(width 0.4572)
		(layer "F.Cu")
		(net "P3V3")
	)
	(via
		(at 440.809634 -73.833228)
		(size 0.508)
		(drill 0.254)
		(layers "F.Cu" "B.Cu")
		(net "P3V3")
	)
	(via
		(at 439.483754 -77.655928)
		(size 0.508)
		(drill 0.254)
		(layers "F.Cu" "B.Cu")
		(net "P3V3")
	)
	(via
		(at 443.6999 -193.99631)
		(size 0.4826)
		(drill 0.254)
		(layers "F.Cu" "B.Cu")
		(net "P3V3")
	)
	(via
		(at 188.215778 -193.996564)
		(size 0.4826)
		(drill 0.254)
		(layers "F.Cu" "B.Cu")
		(net "P3V3")
	)
	(via
		(at 172.477938 -172.398182)
		(size 0.508)
		(drill 0.254)
		(layers "F.Cu" "B.Cu")
		(net "P3V3")
	)
	(via
		(at 442.714634 -74.595228)
		(size 0.508)
		(drill 0.254)
		(layers "F.Cu" "B.Cu")
		(net "P3V3")
	)
	(via
		(at 421.067738 -193.99631)
		(size 0.4826)
		(drill 0.254)
		(layers "F.Cu" "B.Cu")
		(net "P3V3")
	)
	(via
		(at 304.423826 -193.99631)
		(size 0.4826)
		(drill 0.254)
		(layers "F.Cu" "B.Cu")
		(net "P3V3")
	)
	(via
		(at 15.051786 -187.305188)
		(size 0.508)
		(drill 0.254)
		(layers "F.Cu" "B.Cu")
		(net "P3V3")
	)
	(via
		(at 236.728 -216.027)
		(size 0.508)
		(drill 0.254)
		(layers "F.Cu" "B.Cu")
		(net "P3V3")
	)
	(via
		(at 442.059314 -77.645768)
		(size 0.508)
		(drill 0.254)
		(layers "F.Cu" "B.Cu")
		(net "P3V3")
	)
	(via
		(at 441.444634 -76.119228)
		(size 0.508)
		(drill 0.254)
		(layers "F.Cu" "B.Cu")
		(net "P3V3")
	)
	(via
		(at 320.540126 -55.75427)
		(size 0.508)
		(drill 0.254)
		(layers "F.Cu" "B.Cu")
		(net "P3V3")
	)
	(via
		(at 33.813496 -193.996564)
		(size 0.4826)
		(drill 0.254)
		(layers "F.Cu" "B.Cu")
		(net "P3V3")
	)
	(via
		(at 289.335718 -193.99631)
		(size 0.4826)
		(drill 0.254)
		(layers "F.Cu" "B.Cu")
		(net "P3V3")
	)
	(via
		(at 18.778982 -195.251324)
		(size 0.4826)
		(drill 0.254)
		(layers "F.Cu" "B.Cu")
		(net "P3V3")
	)
	(via
		(at 22.91715 -158.077154)
		(size 0.508)
		(drill 0.254)
		(layers "F.Cu" "B.Cu")
		(net "P3V3")
	)
	(via
		(at 316.507876 -65.692782)
		(size 0.508)
		(drill 0.254)
		(layers "F.Cu" "B.Cu")
		(net "P3V3")
	)
	(via
		(at 439.504074 -76.129388)
		(size 0.508)
		(drill 0.254)
		(layers "F.Cu" "B.Cu")
		(net "P3V3")
	)
	(via
		(at 162.764216 -61.816234)
		(size 0.508)
		(drill 0.254)
		(layers "F.Cu" "B.Cu")
		(net "P3V3")
	)
	(via
		(at 296.879772 -193.99631)
		(size 0.4826)
		(drill 0.254)
		(layers "F.Cu" "B.Cu")
		(net "P3V3")
	)
	(via
		(at 18.78584 -194.58686)
		(size 0.4826)
		(drill 0.254)
		(layers "F.Cu" "B.Cu")
		(net "P3V3")
	)
	(via
		(at 440.789314 -76.883768)
		(size 0.508)
		(drill 0.254)
		(layers "F.Cu" "B.Cu")
		(net "P3V3")
	)
	(via
		(at 241.554 -217.27795)
		(size 0.508)
		(drill 0.254)
		(layers "F.Cu" "B.Cu")
		(net "P3V3")
	)
	(via
		(at 439.483754 -76.893928)
		(size 0.508)
		(drill 0.254)
		(layers "F.Cu" "B.Cu")
		(net "P3V3")
	)
	(via
		(at 173.127924 -193.996564)
		(size 0.4826)
		(drill 0.254)
		(layers "F.Cu" "B.Cu")
		(net "P3V3")
	)
	(via
		(at 440.118754 -77.655928)
		(size 0.508)
		(drill 0.254)
		(layers "F.Cu" "B.Cu")
		(net "P3V3")
	)
	(via
		(at 171.227242 -186.965082)
		(size 0.508)
		(drill 0.254)
		(layers "F.Cu" "B.Cu")
		(net "P3V3")
	)
	(via
		(at 48.939704 -193.996564)
		(size 0.4826)
		(drill 0.254)
		(layers "F.Cu" "B.Cu")
		(net "P3V3")
	)
	(via
		(at 195.759832 -193.996564)
		(size 0.4826)
		(drill 0.254)
		(layers "F.Cu" "B.Cu")
		(net "P3V3")
	)
	(via
		(at 109.165136 -128.764538)
		(size 0.508)
		(drill 0.254)
		(layers "F.Cu" "B.Cu")
		(net "P3V3")
	)
	(via
		(at 442.059314 -76.883768)
		(size 0.508)
		(drill 0.254)
		(layers "F.Cu" "B.Cu")
		(net "P3V3")
	)
	(via
		(at 47.76597 -185.860436)
		(size 0.508)
		(drill 0.254)
		(layers "F.Cu" "B.Cu")
		(net "P3V3")
	)
	(via
		(at 26.307796 -193.996564)
		(size 0.4826)
		(drill 0.254)
		(layers "F.Cu" "B.Cu")
		(net "P3V3")
	)
	(via
		(at 440.139074 -76.129388)
		(size 0.508)
		(drill 0.254)
		(layers "F.Cu" "B.Cu")
		(net "P3V3")
	)
	(via
		(at 236.36605 -219.47505)
		(size 0.508)
		(drill 0.254)
		(layers "F.Cu" "B.Cu")
		(net "P3V3")
	)
	(via
		(at 442.079634 -74.595228)
		(size 0.508)
		(drill 0.254)
		(layers "F.Cu" "B.Cu")
		(net "P3V3")
	)
	(via
		(at 22.91715 -156.045154)
		(size 0.508)
		(drill 0.254)
		(layers "F.Cu" "B.Cu")
		(net "P3V3")
	)
	(via
		(at 274.247864 -193.99631)
		(size 0.4826)
		(drill 0.254)
		(layers "F.Cu" "B.Cu")
		(net "P3V3")
	)
	(via
		(at 440.789314 -77.645768)
		(size 0.508)
		(drill 0.254)
		(layers "F.Cu" "B.Cu")
		(net "P3V3")
	)
	(via
		(at 22.91715 -155.029154)
		(size 0.508)
		(drill 0.254)
		(layers "F.Cu" "B.Cu")
		(net "P3V3")
	)
	(via
		(at 442.079634 -75.357228)
		(size 0.508)
		(drill 0.254)
		(layers "F.Cu" "B.Cu")
		(net "P3V3")
	)
	(via
		(at 443.400434 -74.595228)
		(size 0.508)
		(drill 0.254)
		(layers "F.Cu" "B.Cu")
		(net "P3V3")
	)
	(via
		(at 440.139074 -75.367388)
		(size 0.508)
		(drill 0.254)
		(layers "F.Cu" "B.Cu")
		(net "P3V3")
	)
	(via
		(at 269.969742 -124.50572)
		(size 0.508)
		(drill 0.254)
		(layers "F.Cu" "B.Cu")
		(net "P3V3")
	)
	(via
		(at 165.58387 -193.996564)
		(size 0.4826)
		(drill 0.254)
		(layers "F.Cu" "B.Cu")
		(net "P3V3")
	)
	(via
		(at 277.18258 -169.744644)
		(size 0.508)
		(drill 0.254)
		(layers "F.Cu" "B.Cu")
		(net "P3V3")
	)
	(via
		(at 413.523684 -193.99631)
		(size 0.508)
		(drill 0.254)
		(layers "F.Cu" "B.Cu")
		(net "P3V3")
	)
	(via
		(at 162.764216 -59.784234)
		(size 0.508)
		(drill 0.254)
		(layers "F.Cu" "B.Cu")
		(net "P3V3")
	)
	(via
		(at 442.714634 -73.833228)
		(size 0.508)
		(drill 0.254)
		(layers "F.Cu" "B.Cu")
		(net "P3V3")
	)
	(via
		(at 162.764216 -60.800234)
		(size 0.508)
		(drill 0.254)
		(layers "F.Cu" "B.Cu")
		(net "P3V3")
	)
	(via
		(at 441.424314 -77.645768)
		(size 0.508)
		(drill 0.254)
		(layers "F.Cu" "B.Cu")
		(net "P3V3")
	)
	(via
		(at 443.400434 -73.833228)
		(size 0.508)
		(drill 0.254)
		(layers "F.Cu" "B.Cu")
		(net "P3V3")
	)
	(via
		(at 241.046 -216.027)
		(size 0.508)
		(drill 0.254)
		(layers "F.Cu" "B.Cu")
		(net "P3V3")
	)
	(via
		(at 440.809634 -76.119228)
		(size 0.508)
		(drill 0.254)
		(layers "F.Cu" "B.Cu")
		(net "P3V3")
	)
	(via
		(at 203.303886 -193.99631)
		(size 0.4826)
		(drill 0.254)
		(layers "F.Cu" "B.Cu")
		(net "P3V3")
	)
	(via
		(at 180.671978 -193.996564)
		(size 0.4826)
		(drill 0.254)
		(layers "F.Cu" "B.Cu")
		(net "P3V3")
	)
	(via
		(at 442.079634 -73.833228)
		(size 0.508)
		(drill 0.254)
		(layers "F.Cu" "B.Cu")
		(net "P3V3")
	)
	(via
		(at 162.002216 -61.816234)
		(size 0.508)
		(drill 0.254)
		(layers "F.Cu" "B.Cu")
		(net "P3V3")
	)
	(via
		(at 441.444634 -75.357228)
		(size 0.508)
		(drill 0.254)
		(layers "F.Cu" "B.Cu")
		(net "P3V3")
	)
	(via
		(at 440.809634 -74.595228)
		(size 0.508)
		(drill 0.254)
		(layers "F.Cu" "B.Cu")
		(net "P3V3")
	)
	(via
		(at 442.079634 -76.119228)
		(size 0.508)
		(drill 0.254)
		(layers "F.Cu" "B.Cu")
		(net "P3V3")
	)
	(via
		(at 330.601828 -42.176954)
		(size 0.508)
		(drill 0.254)
		(layers "F.Cu" "B.Cu")
		(net "P3V3")
	)
	(via
		(at 440.139074 -74.605388)
		(size 0.508)
		(drill 0.254)
		(layers "F.Cu" "B.Cu")
		(net "P3V3")
	)
	(via
		(at 439.504074 -75.367388)
		(size 0.508)
		(drill 0.254)
		(layers "F.Cu" "B.Cu")
		(net "P3V3")
	)
	(via
		(at 281.791664 -193.99631)
		(size 0.4826)
		(drill 0.254)
		(layers "F.Cu" "B.Cu")
		(net "P3V3")
	)
	(via
		(at 162.002216 -59.784234)
		(size 0.508)
		(drill 0.254)
		(layers "F.Cu" "B.Cu")
		(net "P3V3")
	)
	(via
		(at 428.611792 -193.99631)
		(size 0.4826)
		(drill 0.254)
		(layers "F.Cu" "B.Cu")
		(net "P3V3")
	)
	(via
		(at 135.065262 -115.120928)
		(size 0.508)
		(drill 0.254)
		(layers "F.Cu" "B.Cu")
		(net "P3V3")
	)
	(via
		(at 451.2437 -193.99631)
		(size 0.508)
		(drill 0.254)
		(layers "F.Cu" "B.Cu")
		(net "P3V3")
	)
	(via
		(at 59.286902 -91.660218)
		(size 0.508)
		(drill 0.254)
		(layers "F.Cu" "B.Cu")
		(net "P3V3")
	)
	(via
		(at 22.91715 -157.061154)
		(size 0.508)
		(drill 0.254)
		(layers "F.Cu" "B.Cu")
		(net "P3V3")
	)
	(via
		(at 441.424314 -76.883768)
		(size 0.508)
		(drill 0.254)
		(layers "F.Cu" "B.Cu")
		(net "P3V3")
	)
	(via
		(at 61.064902 -91.660218)
		(size 0.508)
		(drill 0.254)
		(layers "F.Cu" "B.Cu")
		(net "P3V3")
	)
	(via
		(at 56.483758 -193.996564)
		(size 0.4826)
		(drill 0.254)
		(layers "F.Cu" "B.Cu")
		(net "P3V3")
	)
	(via
		(at 59.921902 -91.660218)
		(size 0.508)
		(drill 0.254)
		(layers "F.Cu" "B.Cu")
		(net "P3V3")
	)
	(via
		(at 439.504074 -74.605388)
		(size 0.508)
		(drill 0.254)
		(layers "F.Cu" "B.Cu")
		(net "P3V3")
	)
	(via
		(at 440.809634 -75.357228)
		(size 0.508)
		(drill 0.254)
		(layers "F.Cu" "B.Cu")
		(net "P3V3")
	)
	(via
		(at 162.002216 -60.800234)
		(size 0.508)
		(drill 0.254)
		(layers "F.Cu" "B.Cu")
		(net "P3V3")
	)
	(via
		(at 426.417486 -52.438554)
		(size 0.508)
		(drill 0.254)
		(layers "F.Cu" "B.Cu")
		(net "P3V3")
	)
	(via
		(at 440.118754 -76.893928)
		(size 0.508)
		(drill 0.254)
		(layers "F.Cu" "B.Cu")
		(net "P3V3")
	)
	(via
		(at 82.399124 -93.406976)
		(size 0.508)
		(drill 0.254)
		(layers "F.Cu" "B.Cu")
		(net "P3V3")
	)
	(via
		(at 266.70381 -193.99631)
		(size 0.4826)
		(drill 0.254)
		(layers "F.Cu" "B.Cu")
		(net "P3V3")
	)
	(via
		(at 157.59557 -58.109358)
		(size 0.508)
		(drill 0.254)
		(layers "F.Cu" "B.Cu")
		(net "P3V3")
	)
	(via
		(at 436.155846 -193.99631)
		(size 0.4826)
		(drill 0.254)
		(layers "F.Cu" "B.Cu")
		(net "P3V3")
	)
	(via
		(at 441.444634 -73.833228)
		(size 0.508)
		(drill 0.254)
		(layers "F.Cu" "B.Cu")
		(net "P3V3")
	)
	(via
		(at 441.444634 -74.595228)
		(size 0.508)
		(drill 0.254)
		(layers "F.Cu" "B.Cu")
		(net "P3V3")
	)
	(via
		(at 41.39565 -193.996564)
		(size 0.4826)
		(drill 0.254)
		(layers "F.Cu" "B.Cu")
		(net "P3V3")
	)
	(via
		(at 444.843408 -74.520044)
		(size 0.508)
		(drill 0.254)
		(layers "F.Cu" "B.Cu")
		(net "P3V3")
	)
	(segment
		(start 166.64051 -190.821564)
		(end 167.37076 -190.821564)
		(width 0.4572)
		(layer "B.Cu")
		(net "P3V3")
	)
	(segment
		(start 237.690406 -220.927168)
		(end 237.690406 -219.929456)
		(width 0.4572)
		(layer "B.Cu")
		(net "P3V3")
	)
	(segment
		(start 298.126404 -190.82131)
		(end 297.963336 -190.82131)
		(width 0.508)
		(layer "B.Cu")
		(net "P3V3")
	)
	(segment
		(start 237.236 -219.47505)
		(end 236.36605 -219.47505)
		(width 0.4572)
		(layer "B.Cu")
		(net "P3V3")
	)
	(segment
		(start 15.051786 -187.305188)
		(end 15.937484 -188.190886)
		(width 0.4572)
		(layer "B.Cu")
		(net "P3V3")
	)
	(segment
		(start 414.496504 -191.20231)
		(end 414.496504 -192.07226)
		(width 0.381)
		(layer "B.Cu")
		(net "P3V3")
	)
	(segment
		(start 297.963336 -190.82131)
		(end 297.669458 -191.115188)
		(width 0.508)
		(layer "B.Cu")
		(net "P3V3")
	)
	(segment
		(start 237.690406 -219.929456)
		(end 237.236 -219.47505)
		(width 0.4572)
		(layer "B.Cu")
		(net "P3V3")
	)
	(segment
		(start 15.937484 -188.190886)
		(end 43.87723 -188.190886)
		(width 0.4572)
		(layer "B.Cu")
		(net "P3V3")
	)
	(segment
		(start 47.76597 -185.860436)
		(end 47.482506 -186.1439)
		(width 0.508)
		(layer "B.Cu")
		(net "P3V3")
	)
	(segment
		(start 49.860962 -190.821564)
		(end 50.186336 -190.821564)
		(width 0.508)
		(layer "B.Cu")
		(net "P3V3")
	)
	(segment
		(start 297.669458 -191.115188)
		(end 297.669458 -193.936874)
		(width 0.508)
		(layer "B.Cu")
		(net "P3V3")
	)
	(segment
		(start 167.37076 -190.821564)
		(end 171.227242 -186.965082)
		(width 0.4572)
		(layer "B.Cu")
		(net "P3V3")
	)
	(segment
		(start 46.20768 -185.860436)
		(end 47.76597 -185.860436)
		(width 0.4572)
		(layer "B.Cu")
		(net "P3V3")
	)
	(segment
		(start 47.482506 -188.443108)
		(end 49.860962 -190.821564)
		(width 0.508)
		(layer "B.Cu")
		(net "P3V3")
	)
	(segment
		(start 33.867344 -193.996564)
		(end 33.81375 -193.996564)
		(width 0.381)
		(layer "B.Cu")
		(net "P3V3")
	)
	(segment
		(start 157.59557 -59.068208)
		(end 158.311596 -59.784234)
		(width 0.4572)
		(layer "B.Cu")
		(net "P3V3")
	)
	(segment
		(start 297.669458 -193.936874)
		(end 297.610022 -193.99631)
		(width 0.508)
		(layer "B.Cu")
		(net "P3V3")
	)
	(segment
		(start 157.59557 -58.109358)
		(end 157.59557 -59.068208)
		(width 0.4572)
		(layer "B.Cu")
		(net "P3V3")
	)
	(segment
		(start 43.87723 -188.190886)
		(end 46.20768 -185.860436)
		(width 0.4572)
		(layer "B.Cu")
		(net "P3V3")
	)
	(segment
		(start 158.311596 -59.784234)
		(end 162.002216 -59.784234)
		(width 0.4572)
		(layer "B.Cu")
		(net "P3V3")
	)
	(segment
		(start 15.051786 -187.305188)
		(end 14.097762 -188.259212)
		(width 0.4572)
		(layer "B.Cu")
		(net "P3V3")
	)
	(segment
		(start 414.496504 -192.07226)
		(end 414.351978 -192.216786)
		(width 0.381)
		(layer "B.Cu")
		(net "P3V3")
	)
	(segment
		(start 236.728 -216.027)
		(end 237.47095 -216.027)
		(width 0.4572)
		(layer "B.Cu")
		(net "P3V3")
	)
	(segment
		(start 316.507876 -66.308732)
		(end 316.507876 -65.692782)
		(width 0.4572)
		(layer "B.Cu")
		(net "P3V3")
	)
	(segment
		(start 47.482506 -186.1439)
		(end 47.482506 -188.443108)
		(width 0.508)
		(layer "B.Cu")
		(net "P3V3")
	)
	(segment
		(start 33.81375 -193.996564)
		(end 33.813496 -193.996564)
		(width 0.4572)
		(layer "B.Cu")
		(net "P3V3")
	)
	(segment
		(start 240.792 -217.27795)
		(end 241.554 -217.27795)
		(width 0.4572)
		(layer "B.Cu")
		(net "P3V3")
	)
	(segment
		(start 166.64051 -190.821564)
		(end 166.64051 -192.062354)
		(width 0.381)
		(layer "B.Cu")
		(net "P3V3")
	)
	(segment
		(start 56.473852 -193.996564)
		(end 56.483758 -193.996564)
		(width 0.381)
		(layer "B.Cu")
		(net "P3V3")
	)
	(segment
		(start 241.046 -216.027)
		(end 240.30305 -216.027)
		(width 0.4572)
		(layer "B.Cu")
		(net "P3V3")
	)
	(segment
		(start 414.351978 -192.216786)
		(end 414.351978 -193.48831)
		(width 0.381)
		(layer "B.Cu")
		(net "P3V3")
	)
	(segment
		(start 297.610022 -193.99631)
		(end 296.879772 -193.99631)
		(width 0.508)
		(layer "B.Cu")
		(net "P3V3")
	)
	(segment
		(start 26.32329 -193.996564)
		(end 26.307796 -193.996564)
		(width 0.381)
		(layer "B.Cu")
		(net "P3V3")
	)
	(segment
		(start 14.097762 -188.259212)
		(end 14.097762 -191.962278)
		(width 0.4572)
		(layer "B.Cu")
		(net "P3V3")
	)
	(segment
		(start 174.275496 -165.624002)
		(end 174.275496 -154.49042)
		(width 0.4572)
		(layer "In2.Cu")
		(net "P3V3")
	)
	(segment
		(start 277.18258 -169.744644)
		(end 274.737576 -169.744644)
		(width 0.4572)
		(layer "In2.Cu")
		(net "P3V3")
	)
	(segment
		(start 135.065262 -132.830062)
		(end 135.065262 -115.120928)
		(width 0.4572)
		(layer "In2.Cu")
		(net "P3V3")
	)
	(segment
		(start 271.276318 -128.405382)
		(end 269.969742 -127.098806)
		(width 0.4572)
		(layer "In2.Cu")
		(net "P3V3")
	)
	(segment
		(start 268.543532 -163.5506)
		(end 268.543532 -137.932668)
		(width 0.4572)
		(layer "In2.Cu")
		(net "P3V3")
	)
	(segment
		(start 171.343574 -171.658026)
		(end 171.343574 -168.555924)
		(width 0.4572)
		(layer "In2.Cu")
		(net "P3V3")
	)
	(segment
		(start 271.276318 -135.199882)
		(end 271.276318 -128.405382)
		(width 0.4572)
		(layer "In2.Cu")
		(net "P3V3")
	)
	(segment
		(start 268.543532 -137.932668)
		(end 271.276318 -135.199882)
		(width 0.4572)
		(layer "In2.Cu")
		(net "P3V3")
	)
	(segment
		(start 269.969742 -127.098806)
		(end 269.969742 -124.50572)
		(width 0.4572)
		(layer "In2.Cu")
		(net "P3V3")
	)
	(segment
		(start 155.281122 -153.045922)
		(end 135.065262 -132.830062)
		(width 0.4572)
		(layer "In2.Cu")
		(net "P3V3")
	)
	(segment
		(start 172.477938 -172.398182)
		(end 172.08373 -172.398182)
		(width 0.4572)
		(layer "In2.Cu")
		(net "P3V3")
	)
	(segment
		(start 274.737576 -169.744644)
		(end 268.543532 -163.5506)
		(width 0.4572)
		(layer "In2.Cu")
		(net "P3V3")
	)
	(segment
		(start 172.830998 -153.045922)
		(end 155.281122 -153.045922)
		(width 0.4572)
		(layer "In2.Cu")
		(net "P3V3")
	)
	(segment
		(start 174.275496 -154.49042)
		(end 172.830998 -153.045922)
		(width 0.4572)
		(layer "In2.Cu")
		(net "P3V3")
	)
	(segment
		(start 172.08373 -172.398182)
		(end 171.343574 -171.658026)
		(width 0.4572)
		(layer "In2.Cu")
		(net "P3V3")
	)
	(segment
		(start 171.343574 -168.555924)
		(end 174.275496 -165.624002)
		(width 0.4572)
		(layer "In2.Cu")
		(net "P3V3")
	)
	(segment
		(start 107.405932 -124.322586)
		(end 107.405932 -117.978936)
		(width 0.4572)
		(layer "In4.Cu")
		(net "P3V3")
	)
	(segment
		(start 332.629002 -47.169832)
		(end 332.629002 -54.6608)
		(width 0.4572)
		(layer "In4.Cu")
		(net "P3V3")
	)
	(segment
		(start 330.157074 -57.132728)
		(end 321.918584 -57.132728)
		(width 0.4572)
		(layer "In4.Cu")
		(net "P3V3")
	)
	(segment
		(start 96.117918 -107.12577)
		(end 82.399124 -93.406976)
		(width 0.4572)
		(layer "In4.Cu")
		(net "P3V3")
	)
	(segment
		(start 107.405932 -117.978936)
		(end 104.75722 -115.330224)
		(width 0.4572)
		(layer "In4.Cu")
		(net "P3V3")
	)
	(segment
		(start 329.639168 -44.179998)
		(end 332.629002 -47.169832)
		(width 0.4572)
		(layer "In4.Cu")
		(net "P3V3")
	)
	(segment
		(start 104.75722 -112.993678)
		(end 98.889312 -107.12577)
		(width 0.4572)
		(layer "In4.Cu")
		(net "P3V3")
	)
	(segment
		(start 330.601828 -42.176954)
		(end 330.006452 -42.176954)
		(width 0.4572)
		(layer "In4.Cu")
		(net "P3V3")
	)
	(segment
		(start 330.006452 -42.176954)
		(end 329.639168 -42.544238)
		(width 0.4572)
		(layer "In4.Cu")
		(net "P3V3")
	)
	(segment
		(start 109.165136 -126.08179)
		(end 107.405932 -124.322586)
		(width 0.4572)
		(layer "In4.Cu")
		(net "P3V3")
	)
	(segment
		(start 104.75722 -115.330224)
		(end 104.75722 -112.993678)
		(width 0.4572)
		(layer "In4.Cu")
		(net "P3V3")
	)
	(segment
		(start 98.889312 -107.12577)
		(end 96.117918 -107.12577)
		(width 0.4572)
		(layer "In4.Cu")
		(net "P3V3")
	)
	(segment
		(start 332.629002 -54.6608)
		(end 330.157074 -57.132728)
		(width 0.4572)
		(layer "In4.Cu")
		(net "P3V3")
	)
	(segment
		(start 321.918584 -57.132728)
		(end 320.540126 -55.75427)
		(width 0.4572)
		(layer "In4.Cu")
		(net "P3V3")
	)
	(segment
		(start 329.639168 -42.544238)
		(end 329.639168 -44.179998)
		(width 0.4572)
		(layer "In4.Cu")
		(net "P3V3")
	)
	(segment
		(start 109.165136 -128.764538)
		(end 109.165136 -126.08179)
		(width 0.4572)
		(layer "In4.Cu")
		(net "P3V3")
	)
	(segment
		(start 440.809634 -73.833228)
		(end 438.268872 -73.833228)
		(width 0.4572)
		(layer "In6.Cu")
		(net "P3V3")
	)
	(segment
		(start 436.471568 -72.035924)
		(end 436.471568 -62.492636)
		(width 0.4572)
		(layer "In6.Cu")
		(net "P3V3")
	)
	(segment
		(start 438.268872 -73.833228)
		(end 436.471568 -72.035924)
		(width 0.4572)
		(layer "In6.Cu")
		(net "P3V3")
	)
	(segment
		(start 436.471568 -62.492636)
		(end 426.417486 -52.438554)
		(width 0.4572)
		(layer "In6.Cu")
		(net "P3V3")
	)
	(segment
		(start 370.370608 -393.69238)
		(end 370.891308 -393.69238)
		(width 0.127)
		(layer "F.Cu")
		(net "P5E_CPU0_P3_RX_DN<0>")
	)
	(segment
		(start 361.89793 -286.780224)
		(end 362.364782 -287.045908)
		(width 0.12954)
		(layer "F.Cu")
		(net "P5E_CPU0_P3_RX_DN<0>")
	)
	(segment
		(start 362.467906 -287.438846)
		(end 362.576364 -287.361122)
		(width 0.1143)
		(layer "In4.Cu")
		(net "P5E_CPU0_P3_RX_DN<0>")
	)
	(segment
		(start 366.153954 -388.011162)
		(end 365.759492 -387.84784)
		(width 0.14224)
		(layer "In4.Cu")
		(net "P5E_CPU0_P3_RX_DN<0>")
	)
	(segment
		(start 367.052606 -388.38378)
		(end 366.978438 -388.204456)
		(width 0.14224)
		(layer "In4.Cu")
		(net "P5E_CPU0_P3_RX_DN<0>")
	)
	(segment
		(start 379.299216 -353.267772)
		(end 380.105158 -349.178118)
		(width 0.14224)
		(layer "In4.Cu")
		(net "P5E_CPU0_P3_RX_DN<0>")
	)
	(segment
		(start 362.662724 -287.045908)
		(end 362.364782 -287.045908)
		(width 0.1143)
		(layer "In4.Cu")
		(net "P5E_CPU0_P3_RX_DN<0>")
	)
	(segment
		(start 361.611926 -288.9885)
		(end 361.642406 -288.97072)
		(width 0.1143)
		(layer "In4.Cu")
		(net "P5E_CPU0_P3_RX_DN<0>")
	)
	(segment
		(start 365.685324 -387.668262)
		(end 364.1598 -387.036056)
		(width 0.14224)
		(layer "In4.Cu")
		(net "P5E_CPU0_P3_RX_DN<0>")
	)
	(segment
		(start 362.044488 -288.200084)
		(end 362.048044 -288.198052)
		(width 0.1143)
		(layer "In4.Cu")
		(net "P5E_CPU0_P3_RX_DN<0>")
	)
	(segment
		(start 370.65839 -389.72998)
		(end 367.626138 -388.473188)
		(width 0.14224)
		(layer "In4.Cu")
		(net "P5E_CPU0_P3_RX_DN<0>")
	)
	(segment
		(start 371.059202 -392.039094)
		(end 371.358668 -391.739882)
		(width 0.14224)
		(layer "In4.Cu")
		(net "P5E_CPU0_P3_RX_DN<0>")
	)
	(segment
		(start 360.961686 -289.548316)
		(end 360.981752 -289.52825)
		(width 0.1143)
		(layer "In4.Cu")
		(net "P5E_CPU0_P3_RX_DN<0>")
	)
	(segment
		(start 361.799378 -288.66592)
		(end 361.799632 -288.66592)
		(width 0.1143)
		(layer "In4.Cu")
		(net "P5E_CPU0_P3_RX_DN<0>")
	)
	(segment
		(start 360.981752 -289.52825)
		(end 361.04576 -289.52825)
		(width 0.1143)
		(layer "In4.Cu")
		(net "P5E_CPU0_P3_RX_DN<0>")
	)
	(segment
		(start 371.366796 -393.545822)
		(end 371.049804 -393.22883)
		(width 0.14224)
		(layer "In4.Cu")
		(net "P5E_CPU0_P3_RX_DN<0>")
	)
	(segment
		(start 373.39524 -316.855602)
		(end 364.855506 -306.448968)
		(width 0.14224)
		(layer "In4.Cu")
		(net "P5E_CPU0_P3_RX_DN<0>")
	)
	(segment
		(start 363.181138 -382.54178)
		(end 363.358684 -382.364234)
		(width 0.14224)
		(layer "In4.Cu")
		(net "P5E_CPU0_P3_RX_DN<0>")
	)
	(segment
		(start 371.358668 -391.739882)
		(end 371.358668 -390.76376)
		(width 0.14224)
		(layer "In4.Cu")
		(net "P5E_CPU0_P3_RX_DN<0>")
	)
	(segment
		(start 362.27004 -287.852612)
		(end 362.27004 -287.852358)
		(width 0.1143)
		(layer "In4.Cu")
		(net "P5E_CPU0_P3_RX_DN<0>")
	)
	(segment
		(start 366.978438 -388.204456)
		(end 366.333278 -387.936994)
		(width 0.14224)
		(layer "In4.Cu")
		(net "P5E_CPU0_P3_RX_DN<0>")
	)
	(segment
		(start 362.467144 -287.439354)
		(end 362.467906 -287.438846)
		(width 0.1143)
		(layer "In4.Cu")
		(net "P5E_CPU0_P3_RX_DN<0>")
	)
	(segment
		(start 367.626138 -388.473188)
		(end 367.447068 -388.547356)
		(width 0.14224)
		(layer "In4.Cu")
		(net "P5E_CPU0_P3_RX_DN<0>")
	)
	(segment
		(start 371.24513 -393.786868)
		(end 371.366796 -393.716764)
		(width 0.14224)
		(layer "In4.Cu")
		(net "P5E_CPU0_P3_RX_DN<0>")
	)
	(segment
		(start 361.611672 -288.988754)
		(end 361.611926 -288.9885)
		(width 0.1143)
		(layer "In4.Cu")
		(net "P5E_CPU0_P3_RX_DN<0>")
	)
	(segment
		(start 380.105158 -349.178118)
		(end 380.105158 -337.75523)
		(width 0.14224)
		(layer "In4.Cu")
		(net "P5E_CPU0_P3_RX_DN<0>")
	)
	(segment
		(start 360.614468 -290.15944)
		(end 360.779822 -289.760152)
		(width 0.14224)
		(layer "In4.Cu")
		(net "P5E_CPU0_P3_RX_DN<0>")
	)
	(segment
		(start 363.795818 -376.28957)
		(end 379.218698 -353.46132)
		(width 0.14224)
		(layer "In4.Cu")
		(net "P5E_CPU0_P3_RX_DN<0>")
	)
	(segment
		(start 360.614468 -296.000678)
		(end 360.614468 -290.15944)
		(width 0.14224)
		(layer "In4.Cu")
		(net "P5E_CPU0_P3_RX_DN<0>")
	)
	(segment
		(start 380.103126 -337.732624)
		(end 378.952252 -331.32522)
		(width 0.14224)
		(layer "In4.Cu")
		(net "P5E_CPU0_P3_RX_DN<0>")
	)
	(segment
		(start 364.855506 -306.448968)
		(end 363.047534 -303.742852)
		(width 0.14224)
		(layer "In4.Cu")
		(net "P5E_CPU0_P3_RX_DN<0>")
	)
	(segment
		(start 361.04576 -289.52825)
		(end 361.496356 -289.077654)
		(width 0.1143)
		(layer "In4.Cu")
		(net "P5E_CPU0_P3_RX_DN<0>")
	)
	(segment
		(start 362.732828 -287.116012)
		(end 362.662724 -287.045908)
		(width 0.1143)
		(layer "In4.Cu")
		(net "P5E_CPU0_P3_RX_DN<0>")
	)
	(segment
		(start 362.048298 -288.197798)
		(end 362.081826 -288.17824)
		(width 0.1143)
		(layer "In4.Cu")
		(net "P5E_CPU0_P3_RX_DN<0>")
	)
	(segment
		(start 374.91416 -319.697862)
		(end 373.39524 -316.855602)
		(width 0.14224)
		(layer "In4.Cu")
		(net "P5E_CPU0_P3_RX_DN<0>")
	)
	(segment
		(start 379.299216 -353.268026)
		(end 379.299216 -353.267772)
		(width 0.14224)
		(layer "In4.Cu")
		(net "P5E_CPU0_P3_RX_DN<0>")
	)
	(segment
		(start 367.447068 -388.547356)
		(end 367.052606 -388.38378)
		(width 0.14224)
		(layer "In4.Cu")
		(net "P5E_CPU0_P3_RX_DN<0>")
	)
	(segment
		(start 360.961686 -289.548062)
		(end 360.961686 -289.548316)
		(width 0.1143)
		(layer "In4.Cu")
		(net "P5E_CPU0_P3_RX_DN<0>")
	)
	(segment
		(start 363.45495 -382.132078)
		(end 363.45495 -377.404376)
		(width 0.14224)
		(layer "In4.Cu")
		(net "P5E_CPU0_P3_RX_DN<0>")
	)
	(segment
		(start 366.333278 -387.936994)
		(end 366.153954 -388.011162)
		(width 0.14224)
		(layer "In4.Cu")
		(net "P5E_CPU0_P3_RX_DN<0>")
	)
	(segment
		(start 360.779822 -289.729926)
		(end 360.961686 -289.548062)
		(width 0.14224)
		(layer "In4.Cu")
		(net "P5E_CPU0_P3_RX_DN<0>")
	)
	(segment
		(start 371.366796 -393.716764)
		(end 371.366796 -393.545822)
		(width 0.14224)
		(layer "In4.Cu")
		(net "P5E_CPU0_P3_RX_DN<0>")
	)
	(segment
		(start 371.049804 -393.22883)
		(end 371.059202 -392.039094)
		(width 0.14224)
		(layer "In4.Cu")
		(net "P5E_CPU0_P3_RX_DN<0>")
	)
	(segment
		(start 362.467144 -287.439862)
		(end 362.467144 -287.439354)
		(width 0.1143)
		(layer "In4.Cu")
		(net "P5E_CPU0_P3_RX_DN<0>")
	)
	(segment
		(start 362.081826 -288.17824)
		(end 362.082842 -288.177732)
		(width 0.1143)
		(layer "In4.Cu")
		(net "P5E_CPU0_P3_RX_DN<0>")
	)
	(segment
		(start 370.891308 -393.69238)
		(end 371.244622 -393.787376)
		(width 0.14224)
		(layer "In4.Cu")
		(net "P5E_CPU0_P3_RX_DN<0>")
	)
	(segment
		(start 362.042202 -288.201862)
		(end 362.043726 -288.2011)
		(width 0.1143)
		(layer "In4.Cu")
		(net "P5E_CPU0_P3_RX_DN<0>")
	)
	(segment
		(start 362.048044 -288.198052)
		(end 362.048298 -288.197798)
		(width 0.1143)
		(layer "In4.Cu")
		(net "P5E_CPU0_P3_RX_DN<0>")
	)
	(segment
		(start 363.047534 -303.742852)
		(end 361.33278 -299.610018)
		(width 0.14224)
		(layer "In4.Cu")
		(net "P5E_CPU0_P3_RX_DN<0>")
	)
	(segment
		(start 362.043726 -288.2011)
		(end 362.044488 -288.200084)
		(width 0.1143)
		(layer "In4.Cu")
		(net "P5E_CPU0_P3_RX_DN<0>")
	)
	(segment
		(start 371.099334 -390.156954)
		(end 370.699792 -389.757412)
		(width 0.14224)
		(layer "In4.Cu")
		(net "P5E_CPU0_P3_RX_DN<0>")
	)
	(segment
		(start 361.24515 -299.320966)
		(end 360.643932 -296.29989)
		(width 0.14224)
		(layer "In4.Cu")
		(net "P5E_CPU0_P3_RX_DN<0>")
	)
	(segment
		(start 362.269786 -287.853628)
		(end 362.27004 -287.852612)
		(width 0.1143)
		(layer "In4.Cu")
		(net "P5E_CPU0_P3_RX_DN<0>")
	)
	(segment
		(start 371.244622 -393.787376)
		(end 371.24513 -393.786868)
		(width 0.14224)
		(layer "In4.Cu")
		(net "P5E_CPU0_P3_RX_DN<0>")
	)
	(segment
		(start 378.952252 -331.32522)
		(end 374.91416 -319.697862)
		(width 0.14224)
		(layer "In4.Cu")
		(net "P5E_CPU0_P3_RX_DN<0>")
	)
	(segment
		(start 362.040678 -288.202878)
		(end 362.042202 -288.201862)
		(width 0.1143)
		(layer "In4.Cu")
		(net "P5E_CPU0_P3_RX_DN<0>")
	)
	(segment
		(start 365.759492 -387.84784)
		(end 365.685324 -387.668262)
		(width 0.14224)
		(layer "In4.Cu")
		(net "P5E_CPU0_P3_RX_DN<0>")
	)
	(segment
		(start 362.97362 -385.259072)
		(end 362.97362 -383.042668)
		(width 0.14224)
		(layer "In4.Cu")
		(net "P5E_CPU0_P3_RX_DN<0>")
	)
	(segment
		(start 360.779822 -289.760152)
		(end 360.779822 -289.729926)
		(width 0.14224)
		(layer "In4.Cu")
		(net "P5E_CPU0_P3_RX_DN<0>")
	)
	(arc
		(start 362.97362 -383.042668)
		(mid 363.027559 -382.771587)
		(end 363.181138 -382.54178)
		(width 0.14224)
		(layer "In4.Cu")
		(net "P5E_CPU0_P3_RX_DN<0>")
	)
	(arc
		(start 363.358684 -382.364234)
		(mid 363.429908 -382.257734)
		(end 363.45495 -382.132078)
		(width 0.14224)
		(layer "In4.Cu")
		(net "P5E_CPU0_P3_RX_DN<0>")
	)
	(arc
		(start 361.642406 -288.97072)
		(mid 361.757833 -288.837344)
		(end 361.799378 -288.66592)
		(width 0.1143)
		(layer "In4.Cu")
		(net "P5E_CPU0_P3_RX_DN<0>")
	)
	(arc
		(start 364.1598 -387.036056)
		(mid 363.297242 -386.327447)
		(end 362.97362 -385.259072)
		(width 0.14224)
		(layer "In4.Cu")
		(net "P5E_CPU0_P3_RX_DN<0>")
	)
	(arc
		(start 362.27004 -287.852358)
		(mid 362.286623 -287.717006)
		(end 362.335572 -287.589722)
		(width 0.1143)
		(layer "In4.Cu")
		(net "P5E_CPU0_P3_RX_DN<0>")
	)
	(arc
		(start 371.358668 -390.76376)
		(mid 371.291019 -390.433853)
		(end 371.099334 -390.156954)
		(width 0.14224)
		(layer "In4.Cu")
		(net "P5E_CPU0_P3_RX_DN<0>")
	)
	(arc
		(start 380.105158 -337.75523)
		(mid 380.104652 -337.743881)
		(end 380.103126 -337.732624)
		(width 0.14224)
		(layer "In4.Cu")
		(net "P5E_CPU0_P3_RX_DN<0>")
	)
	(arc
		(start 370.699792 -389.757412)
		(mid 370.680435 -389.741671)
		(end 370.65839 -389.72998)
		(width 0.14224)
		(layer "In4.Cu")
		(net "P5E_CPU0_P3_RX_DN<0>")
	)
	(arc
		(start 362.082842 -288.177732)
		(mid 362.219709 -288.040708)
		(end 362.269786 -287.853628)
		(width 0.1143)
		(layer "In4.Cu")
		(net "P5E_CPU0_P3_RX_DN<0>")
	)
	(arc
		(start 361.33278 -299.610018)
		(mid 361.281855 -299.467648)
		(end 361.24515 -299.320966)
		(width 0.14224)
		(layer "In4.Cu")
		(net "P5E_CPU0_P3_RX_DN<0>")
	)
	(arc
		(start 362.576364 -287.361122)
		(mid 362.678186 -287.253625)
		(end 362.732828 -287.116012)
		(width 0.1143)
		(layer "In4.Cu")
		(net "P5E_CPU0_P3_RX_DN<0>")
	)
	(arc
		(start 361.496356 -289.077654)
		(mid 361.551129 -289.029462)
		(end 361.611672 -288.988754)
		(width 0.1143)
		(layer "In4.Cu")
		(net "P5E_CPU0_P3_RX_DN<0>")
	)
	(arc
		(start 363.45495 -377.404376)
		(mid 363.541945 -376.821455)
		(end 363.795818 -376.28957)
		(width 0.14224)
		(layer "In4.Cu")
		(net "P5E_CPU0_P3_RX_DN<0>")
	)
	(arc
		(start 362.335572 -287.589722)
		(mid 362.392822 -287.507301)
		(end 362.467144 -287.439862)
		(width 0.1143)
		(layer "In4.Cu")
		(net "P5E_CPU0_P3_RX_DN<0>")
	)
	(arc
		(start 379.218698 -353.46132)
		(mid 379.268644 -353.368707)
		(end 379.299216 -353.268026)
		(width 0.14224)
		(layer "In4.Cu")
		(net "P5E_CPU0_P3_RX_DN<0>")
	)
	(arc
		(start 360.643932 -296.29989)
		(mid 360.621847 -296.151008)
		(end 360.614468 -296.000678)
		(width 0.14224)
		(layer "In4.Cu")
		(net "P5E_CPU0_P3_RX_DN<0>")
	)
	(arc
		(start 361.799632 -288.66592)
		(mid 361.863438 -288.404867)
		(end 362.040678 -288.202878)
		(width 0.1143)
		(layer "In4.Cu")
		(net "P5E_CPU0_P3_RX_DN<0>")
	)
	(segment
		(start 370.770658 -394.385292)
		(end 371.291358 -394.385292)
		(width 0.127)
		(layer "F.Cu")
		(net "P5E_CPU0_P3_RX_DP<0>")
	)
	(segment
		(start 362.837984 -286.780224)
		(end 363.304836 -287.045908)
		(width 0.12954)
		(layer "F.Cu")
		(net "P5E_CPU0_P3_RX_DP<0>")
	)
	(segment
		(start 360.896408 -290.215574)
		(end 361.040426 -289.868102)
		(width 0.14224)
		(layer "In4.Cu")
		(net "P5E_CPU0_P3_RX_DP<0>")
	)
	(segment
		(start 371.648736 -393.842494)
		(end 371.648736 -393.428982)
		(width 0.14224)
		(layer "In4.Cu")
		(net "P5E_CPU0_P3_RX_DP<0>")
	)
	(segment
		(start 371.33276 -393.113006)
		(end 371.34038 -392.15695)
		(width 0.14224)
		(layer "In4.Cu")
		(net "P5E_CPU0_P3_RX_DP<0>")
	)
	(segment
		(start 370.766594 -389.469376)
		(end 364.268004 -386.775452)
		(width 0.14224)
		(layer "In4.Cu")
		(net "P5E_CPU0_P3_RX_DP<0>")
	)
	(segment
		(start 362.46054 -287.853628)
		(end 362.46054 -287.852612)
		(width 0.1143)
		(layer "In4.Cu")
		(net "P5E_CPU0_P3_RX_DP<0>")
	)
	(segment
		(start 361.040426 -289.868102)
		(end 361.161076 -289.747452)
		(width 0.14224)
		(layer "In4.Cu")
		(net "P5E_CPU0_P3_RX_DP<0>")
	)
	(segment
		(start 362.920026 -287.151572)
		(end 362.92028 -287.151572)
		(width 0.1143)
		(layer "In4.Cu")
		(net "P5E_CPU0_P3_RX_DP<0>")
	)
	(segment
		(start 361.707684 -289.153346)
		(end 361.7468 -289.130486)
		(width 0.1143)
		(layer "In4.Cu")
		(net "P5E_CPU0_P3_RX_DP<0>")
	)
	(segment
		(start 371.560598 -393.930632)
		(end 371.648736 -393.842494)
		(width 0.14224)
		(layer "In4.Cu")
		(net "P5E_CPU0_P3_RX_DP<0>")
	)
	(segment
		(start 365.082328 -306.28082)
		(end 363.29747 -303.609248)
		(width 0.14224)
		(layer "In4.Cu")
		(net "P5E_CPU0_P3_RX_DP<0>")
	)
	(segment
		(start 363.29747 -303.609248)
		(end 361.593384 -299.501814)
		(width 0.14224)
		(layer "In4.Cu")
		(net "P5E_CPU0_P3_RX_DP<0>")
	)
	(segment
		(start 360.896408 -296.000424)
		(end 360.896408 -290.215574)
		(width 0.14224)
		(layer "In4.Cu")
		(net "P5E_CPU0_P3_RX_DP<0>")
	)
	(segment
		(start 371.296692 -389.955532)
		(end 370.899182 -389.558022)
		(width 0.14224)
		(layer "In4.Cu")
		(net "P5E_CPU0_P3_RX_DP<0>")
	)
	(segment
		(start 364.029752 -376.447558)
		(end 379.452632 -353.619308)
		(width 0.14224)
		(layer "In4.Cu")
		(net "P5E_CPU0_P3_RX_DP<0>")
	)
	(segment
		(start 361.521756 -299.265848)
		(end 360.920538 -296.244772)
		(width 0.14224)
		(layer "In4.Cu")
		(net "P5E_CPU0_P3_RX_DP<0>")
	)
	(segment
		(start 361.161076 -289.747452)
		(end 361.181142 -289.727386)
		(width 0.1143)
		(layer "In4.Cu")
		(net "P5E_CPU0_P3_RX_DP<0>")
	)
	(segment
		(start 363.006894 -287.045908)
		(end 363.304836 -287.045908)
		(width 0.1143)
		(layer "In4.Cu")
		(net "P5E_CPU0_P3_RX_DP<0>")
	)
	(segment
		(start 371.648736 -393.428982)
		(end 371.33276 -393.113006)
		(width 0.14224)
		(layer "In4.Cu")
		(net "P5E_CPU0_P3_RX_DP<0>")
	)
	(segment
		(start 361.181142 -289.727386)
		(end 361.181142 -289.662362)
		(width 0.1143)
		(layer "In4.Cu")
		(net "P5E_CPU0_P3_RX_DP<0>")
	)
	(segment
		(start 362.579158 -287.59404)
		(end 362.687616 -287.516062)
		(width 0.1143)
		(layer "In4.Cu")
		(net "P5E_CPU0_P3_RX_DP<0>")
	)
	(segment
		(start 371.386354 -394.031216)
		(end 371.560598 -393.930632)
		(width 0.14224)
		(layer "In4.Cu")
		(net "P5E_CPU0_P3_RX_DP<0>")
	)
	(segment
		(start 363.25556 -385.259326)
		(end 363.25556 -383.042668)
		(width 0.14224)
		(layer "In4.Cu")
		(net "P5E_CPU0_P3_RX_DP<0>")
	)
	(segment
		(start 362.177838 -288.343594)
		(end 362.178346 -288.342832)
		(width 0.1143)
		(layer "In4.Cu")
		(net "P5E_CPU0_P3_RX_DP<0>")
	)
	(segment
		(start 363.380528 -382.74117)
		(end 363.558074 -382.563624)
		(width 0.14224)
		(layer "In4.Cu")
		(net "P5E_CPU0_P3_RX_DP<0>")
	)
	(segment
		(start 362.14431 -288.363152)
		(end 362.177838 -288.343594)
		(width 0.1143)
		(layer "In4.Cu")
		(net "P5E_CPU0_P3_RX_DP<0>")
	)
	(segment
		(start 363.73689 -382.132078)
		(end 363.73689 -377.404376)
		(width 0.14224)
		(layer "In4.Cu")
		(net "P5E_CPU0_P3_RX_DP<0>")
	)
	(segment
		(start 373.630952 -316.698122)
		(end 365.082328 -306.28082)
		(width 0.14224)
		(layer "In4.Cu")
		(net "P5E_CPU0_P3_RX_DP<0>")
	)
	(segment
		(start 361.181142 -289.662362)
		(end 361.63123 -289.212274)
		(width 0.1143)
		(layer "In4.Cu")
		(net "P5E_CPU0_P3_RX_DP<0>")
	)
	(segment
		(start 371.291358 -394.385292)
		(end 371.386354 -394.031216)
		(width 0.14224)
		(layer "In4.Cu")
		(net "P5E_CPU0_P3_RX_DP<0>")
	)
	(segment
		(start 379.576076 -353.322382)
		(end 380.387098 -349.205804)
		(width 0.14224)
		(layer "In4.Cu")
		(net "P5E_CPU0_P3_RX_DP<0>")
	)
	(segment
		(start 380.380748 -337.683094)
		(end 379.226064 -331.253592)
		(width 0.14224)
		(layer "In4.Cu")
		(net "P5E_CPU0_P3_RX_DP<0>")
	)
	(segment
		(start 379.226064 -331.253592)
		(end 375.173494 -319.584324)
		(width 0.14224)
		(layer "In4.Cu")
		(net "P5E_CPU0_P3_RX_DP<0>")
	)
	(segment
		(start 362.92409 -287.128712)
		(end 363.006894 -287.045908)
		(width 0.1143)
		(layer "In4.Cu")
		(net "P5E_CPU0_P3_RX_DP<0>")
	)
	(segment
		(start 371.34038 -392.15695)
		(end 371.640608 -391.856976)
		(width 0.14224)
		(layer "In4.Cu")
		(net "P5E_CPU0_P3_RX_DP<0>")
	)
	(segment
		(start 371.640608 -391.856976)
		(end 371.640608 -390.763506)
		(width 0.14224)
		(layer "In4.Cu")
		(net "P5E_CPU0_P3_RX_DP<0>")
	)
	(segment
		(start 380.387098 -349.205804)
		(end 380.387098 -337.755484)
		(width 0.14224)
		(layer "In4.Cu")
		(net "P5E_CPU0_P3_RX_DP<0>")
	)
	(segment
		(start 375.173494 -319.584324)
		(end 373.630952 -316.698122)
		(width 0.14224)
		(layer "In4.Cu")
		(net "P5E_CPU0_P3_RX_DP<0>")
	)
	(arc
		(start 362.503466 -287.679892)
		(mid 362.536369 -287.632606)
		(end 362.579158 -287.59404)
		(width 0.1143)
		(layer "In4.Cu")
		(net "P5E_CPU0_P3_RX_DP<0>")
	)
	(arc
		(start 361.593384 -299.501814)
		(mid 361.551754 -299.385596)
		(end 361.521756 -299.265848)
		(width 0.14224)
		(layer "In4.Cu")
		(net "P5E_CPU0_P3_RX_DP<0>")
	)
	(arc
		(start 362.46054 -287.852612)
		(mid 362.46054 -287.852358)
		(end 362.46054 -287.852104)
		(width 0.1143)
		(layer "In4.Cu")
		(net "P5E_CPU0_P3_RX_DP<0>")
	)
	(arc
		(start 370.899182 -389.558022)
		(mid 370.837246 -389.507183)
		(end 370.766594 -389.469376)
		(width 0.14224)
		(layer "In4.Cu")
		(net "P5E_CPU0_P3_RX_DP<0>")
	)
	(arc
		(start 380.387098 -337.755484)
		(mid 380.385528 -337.719148)
		(end 380.380748 -337.683094)
		(width 0.14224)
		(layer "In4.Cu")
		(net "P5E_CPU0_P3_RX_DP<0>")
	)
	(arc
		(start 362.178346 -288.342832)
		(mid 362.384928 -288.136006)
		(end 362.46054 -287.853628)
		(width 0.1143)
		(layer "In4.Cu")
		(net "P5E_CPU0_P3_RX_DP<0>")
	)
	(arc
		(start 361.990132 -288.66592)
		(mid 362.030894 -288.496036)
		(end 362.14431 -288.363152)
		(width 0.1143)
		(layer "In4.Cu")
		(net "P5E_CPU0_P3_RX_DP<0>")
	)
	(arc
		(start 360.920538 -296.244772)
		(mid 360.902466 -296.123191)
		(end 360.896408 -296.000424)
		(width 0.14224)
		(layer "In4.Cu")
		(net "P5E_CPU0_P3_RX_DP<0>")
	)
	(arc
		(start 379.452632 -353.619308)
		(mid 379.529223 -353.477028)
		(end 379.576076 -353.322382)
		(width 0.14224)
		(layer "In4.Cu")
		(net "P5E_CPU0_P3_RX_DP<0>")
	)
	(arc
		(start 362.92028 -287.151572)
		(mid 362.922303 -287.140162)
		(end 362.92409 -287.128712)
		(width 0.1143)
		(layer "In4.Cu")
		(net "P5E_CPU0_P3_RX_DP<0>")
	)
	(arc
		(start 363.73689 -377.404376)
		(mid 363.811755 -376.904066)
		(end 364.029752 -376.447558)
		(width 0.14224)
		(layer "In4.Cu")
		(net "P5E_CPU0_P3_RX_DP<0>")
	)
	(arc
		(start 371.640608 -390.763506)
		(mid 371.550914 -390.3245)
		(end 371.296692 -389.955532)
		(width 0.14224)
		(layer "In4.Cu")
		(net "P5E_CPU0_P3_RX_DP<0>")
	)
	(arc
		(start 361.63123 -289.212274)
		(mid 361.667545 -289.18033)
		(end 361.707684 -289.153346)
		(width 0.1143)
		(layer "In4.Cu")
		(net "P5E_CPU0_P3_RX_DP<0>")
	)
	(arc
		(start 362.687616 -287.516062)
		(mid 362.838923 -287.356194)
		(end 362.920026 -287.151572)
		(width 0.1143)
		(layer "In4.Cu")
		(net "P5E_CPU0_P3_RX_DP<0>")
	)
	(arc
		(start 364.268004 -386.775452)
		(mid 363.5319 -386.170907)
		(end 363.25556 -385.259326)
		(width 0.14224)
		(layer "In4.Cu")
		(net "P5E_CPU0_P3_RX_DP<0>")
	)
	(arc
		(start 361.7468 -289.130486)
		(mid 361.925613 -288.928136)
		(end 361.990132 -288.66592)
		(width 0.1143)
		(layer "In4.Cu")
		(net "P5E_CPU0_P3_RX_DP<0>")
	)
	(arc
		(start 362.46054 -287.852104)
		(mid 362.471399 -287.763354)
		(end 362.503466 -287.679892)
		(width 0.1143)
		(layer "In4.Cu")
		(net "P5E_CPU0_P3_RX_DP<0>")
	)
	(arc
		(start 363.558074 -382.563624)
		(mid 363.690424 -382.365643)
		(end 363.73689 -382.132078)
		(width 0.14224)
		(layer "In4.Cu")
		(net "P5E_CPU0_P3_RX_DP<0>")
	)
	(arc
		(start 363.25556 -383.042668)
		(mid 363.288038 -382.879481)
		(end 363.380528 -382.74117)
		(width 0.14224)
		(layer "In4.Cu")
		(net "P5E_CPU0_P3_RX_DP<0>")
	)
	(segment
		(start 39.575994 -422.207182)
		(end 40.007794 -422.638982)
		(width 0.12954)
		(layer "F.Cu")
		(net "P2E_MB_BMC_TX_C_DP<0>")
	)
	(segment
		(start 132.60832 -17.874742)
		(end 132.878322 -18.144744)
		(width 0.12954)
		(layer "F.Cu")
		(net "P2E_MB_BMC_TX_C_DP<0>")
	)
	(segment
		(start 132.747004 -17.11325)
		(end 132.60832 -17.251934)
		(width 0.12954)
		(layer "F.Cu")
		(net "P2E_MB_BMC_TX_C_DP<0>")
	)
	(segment
		(start 132.60832 -17.251934)
		(end 132.60832 -17.874742)
		(width 0.12954)
		(layer "F.Cu")
		(net "P2E_MB_BMC_TX_C_DP<0>")
	)
	(segment
		(start 39.575994 -422.06037)
		(end 39.575994 -422.207182)
		(width 0.12954)
		(layer "F.Cu")
		(net "P2E_MB_BMC_TX_C_DP<0>")
	)
	(segment
		(start 132.747004 -16.549878)
		(end 132.747004 -17.11325)
		(width 0.12954)
		(layer "F.Cu")
		(net "P2E_MB_BMC_TX_C_DP<0>")
	)
	(segment
		(start 3.896868 -381.585216)
		(end 10.723626 -388.411974)
		(width 0.14224)
		(layer "In15.Cu")
		(net "P2E_MB_BMC_TX_C_DP<0>")
	)
	(segment
		(start 81.26349 -47.097442)
		(end 60.447428 -55.719726)
		(width 0.14224)
		(layer "In15.Cu")
		(net "P2E_MB_BMC_TX_C_DP<0>")
	)
	(segment
		(start 38.795706 -61.148468)
		(end 28.817824 -75.39482)
		(width 0.14224)
		(layer "In15.Cu")
		(net "P2E_MB_BMC_TX_C_DP<0>")
	)
	(segment
		(start 28.817824 -75.39482)
		(end 27.911044 -77.583284)
		(width 0.14224)
		(layer "In15.Cu")
		(net "P2E_MB_BMC_TX_C_DP<0>")
	)
	(segment
		(start 113.697258 -35.737546)
		(end 103.193088 -40.088312)
		(width 0.14224)
		(layer "In15.Cu")
		(net "P2E_MB_BMC_TX_C_DP<0>")
	)
	(segment
		(start 120.746266 -21.099018)
		(end 119.823992 -22.021292)
		(width 0.14224)
		(layer "In15.Cu")
		(net "P2E_MB_BMC_TX_C_DP<0>")
	)
	(segment
		(start 10.4902 -102.728014)
		(end 8.681466 -104.536748)
		(width 0.14224)
		(layer "In15.Cu")
		(net "P2E_MB_BMC_TX_C_DP<0>")
	)
	(segment
		(start 8.704072 -410.006546)
		(end 9.34847 -411.562042)
		(width 0.14224)
		(layer "In15.Cu")
		(net "P2E_MB_BMC_TX_C_DP<0>")
	)
	(segment
		(start 16.859504 -101.64826)
		(end 13.097002 -101.64826)
		(width 0.14224)
		(layer "In15.Cu")
		(net "P2E_MB_BMC_TX_C_DP<0>")
	)
	(segment
		(start 119.340884 -23.18766)
		(end 119.340884 -24.721566)
		(width 0.14224)
		(layer "In15.Cu")
		(net "P2E_MB_BMC_TX_C_DP<0>")
	)
	(segment
		(start 7.707376 -396.441676)
		(end 7.707376 -405.567642)
		(width 0.14224)
		(layer "In15.Cu")
		(net "P2E_MB_BMC_TX_C_DP<0>")
	)
	(segment
		(start 18.28038 -100.409502)
		(end 18.062448 -100.936552)
		(width 0.14224)
		(layer "In15.Cu")
		(net "P2E_MB_BMC_TX_C_DP<0>")
	)
	(segment
		(start 6.203442 -116.787422)
		(end 7.979918 -119.324374)
		(width 0.14224)
		(layer "In15.Cu")
		(net "P2E_MB_BMC_TX_C_DP<0>")
	)
	(segment
		(start 10.723626 -393.425426)
		(end 7.707376 -396.441676)
		(width 0.14224)
		(layer "In15.Cu")
		(net "P2E_MB_BMC_TX_C_DP<0>")
	)
	(segment
		(start 18.81378 -421.21836)
		(end 20.692618 -419.339522)
		(width 0.14224)
		(layer "In15.Cu")
		(net "P2E_MB_BMC_TX_C_DP<0>")
	)
	(segment
		(start 39.716964 -422.348152)
		(end 40.007794 -422.638982)
		(width 0.14224)
		(layer "In15.Cu")
		(net "P2E_MB_BMC_TX_C_DP<0>")
	)
	(segment
		(start 82.407252 -45.95368)
		(end 81.26349 -47.097442)
		(width 0.14224)
		(layer "In15.Cu")
		(net "P2E_MB_BMC_TX_C_DP<0>")
	)
	(segment
		(start 17.23136 -133.995414)
		(end 17.23136 -136.177528)
		(width 0.14224)
		(layer "In15.Cu")
		(net "P2E_MB_BMC_TX_C_DP<0>")
	)
	(segment
		(start 8.485378 -409.47848)
		(end 8.704072 -410.006546)
		(width 0.14224)
		(layer "In15.Cu")
		(net "P2E_MB_BMC_TX_C_DP<0>")
	)
	(segment
		(start 15.383256 -142.27048)
		(end 5.177536 -157.544008)
		(width 0.14224)
		(layer "In15.Cu")
		(net "P2E_MB_BMC_TX_C_DP<0>")
	)
	(segment
		(start 18.59534 -96.472248)
		(end 18.59534 -98.82632)
		(width 0.14224)
		(layer "In15.Cu")
		(net "P2E_MB_BMC_TX_C_DP<0>")
	)
	(segment
		(start 92.285566 -41.86174)
		(end 82.407252 -45.95368)
		(width 0.14224)
		(layer "In15.Cu")
		(net "P2E_MB_BMC_TX_C_DP<0>")
	)
	(segment
		(start 5.697474 -108.797598)
		(end 5.246116 -111.358172)
		(width 0.14224)
		(layer "In15.Cu")
		(net "P2E_MB_BMC_TX_C_DP<0>")
	)
	(segment
		(start 119.340884 -24.721566)
		(end 115.54206 -33.892744)
		(width 0.14224)
		(layer "In15.Cu")
		(net "P2E_MB_BMC_TX_C_DP<0>")
	)
	(segment
		(start 5.177536 -157.544008)
		(end 3.896868 -161.765234)
		(width 0.14224)
		(layer "In15.Cu")
		(net "P2E_MB_BMC_TX_C_DP<0>")
	)
	(segment
		(start 12.43076 -419.511988)
		(end 14.137132 -421.21836)
		(width 0.14224)
		(layer "In15.Cu")
		(net "P2E_MB_BMC_TX_C_DP<0>")
	)
	(segment
		(start 14.137132 -421.21836)
		(end 18.81378 -421.21836)
		(width 0.14224)
		(layer "In15.Cu")
		(net "P2E_MB_BMC_TX_C_DP<0>")
	)
	(segment
		(start 39.716964 -421.661082)
		(end 39.716964 -422.348152)
		(width 0.14224)
		(layer "In15.Cu")
		(net "P2E_MB_BMC_TX_C_DP<0>")
	)
	(segment
		(start 3.896868 -161.765234)
		(end 3.896868 -381.585216)
		(width 0.14224)
		(layer "In15.Cu")
		(net "P2E_MB_BMC_TX_C_DP<0>")
	)
	(segment
		(start 60.447428 -55.719726)
		(end 41.87063 -58.995056)
		(width 0.14224)
		(layer "In15.Cu")
		(net "P2E_MB_BMC_TX_C_DP<0>")
	)
	(segment
		(start 10.723626 -388.411974)
		(end 10.723626 -393.425426)
		(width 0.14224)
		(layer "In15.Cu")
		(net "P2E_MB_BMC_TX_C_DP<0>")
	)
	(segment
		(start 39.336218 -420.94912)
		(end 39.716964 -421.661082)
		(width 0.14224)
		(layer "In15.Cu")
		(net "P2E_MB_BMC_TX_C_DP<0>")
	)
	(segment
		(start 99.567238 -41.86174)
		(end 92.285566 -41.86174)
		(width 0.14224)
		(layer "In15.Cu")
		(net "P2E_MB_BMC_TX_C_DP<0>")
	)
	(segment
		(start 7.979918 -119.324374)
		(end 13.399008 -124.74321)
		(width 0.14224)
		(layer "In15.Cu")
		(net "P2E_MB_BMC_TX_C_DP<0>")
	)
	(segment
		(start 13.097002 -101.64826)
		(end 10.4902 -102.728014)
		(width 0.14224)
		(layer "In15.Cu")
		(net "P2E_MB_BMC_TX_C_DP<0>")
	)
	(segment
		(start 13.399008 -124.74321)
		(end 17.23136 -133.995414)
		(width 0.14224)
		(layer "In15.Cu")
		(net "P2E_MB_BMC_TX_C_DP<0>")
	)
	(segment
		(start 9.34847 -411.562042)
		(end 11.141456 -413.355028)
		(width 0.14224)
		(layer "In15.Cu")
		(net "P2E_MB_BMC_TX_C_DP<0>")
	)
	(segment
		(start 115.54206 -33.892744)
		(end 113.697258 -35.737546)
		(width 0.14224)
		(layer "In15.Cu")
		(net "P2E_MB_BMC_TX_C_DP<0>")
	)
	(segment
		(start 132.878322 -18.144744)
		(end 132.587492 -18.435574)
		(width 0.14224)
		(layer "In15.Cu")
		(net "P2E_MB_BMC_TX_C_DP<0>")
	)
	(segment
		(start 17.23136 -136.177528)
		(end 15.383256 -142.27048)
		(width 0.14224)
		(layer "In15.Cu")
		(net "P2E_MB_BMC_TX_C_DP<0>")
	)
	(segment
		(start 12.43076 -415.780474)
		(end 12.43076 -419.511988)
		(width 0.14224)
		(layer "In15.Cu")
		(net "P2E_MB_BMC_TX_C_DP<0>")
	)
	(segment
		(start 11.141456 -414.49117)
		(end 12.43076 -415.780474)
		(width 0.14224)
		(layer "In15.Cu")
		(net "P2E_MB_BMC_TX_C_DP<0>")
	)
	(segment
		(start 132.2832 -19.05)
		(end 125.692916 -19.05)
		(width 0.14224)
		(layer "In15.Cu")
		(net "P2E_MB_BMC_TX_C_DP<0>")
	)
	(segment
		(start 8.681466 -104.536748)
		(end 5.697474 -108.797598)
		(width 0.14224)
		(layer "In15.Cu")
		(net "P2E_MB_BMC_TX_C_DP<0>")
	)
	(segment
		(start 18.062448 -100.936552)
		(end 17.697704 -101.301042)
		(width 0.14224)
		(layer "In15.Cu")
		(net "P2E_MB_BMC_TX_C_DP<0>")
	)
	(segment
		(start 20.692618 -419.339522)
		(end 36.928044 -419.339522)
		(width 0.14224)
		(layer "In15.Cu")
		(net "P2E_MB_BMC_TX_C_DP<0>")
	)
	(segment
		(start 17.697704 -101.301042)
		(end 16.859504 -101.64826)
		(width 0.14224)
		(layer "In15.Cu")
		(net "P2E_MB_BMC_TX_C_DP<0>")
	)
	(segment
		(start 103.193088 -40.088312)
		(end 102.7303 -40.551354)
		(width 0.14224)
		(layer "In15.Cu")
		(net "P2E_MB_BMC_TX_C_DP<0>")
	)
	(segment
		(start 132.587492 -18.435574)
		(end 132.587492 -18.745708)
		(width 0.14224)
		(layer "In15.Cu")
		(net "P2E_MB_BMC_TX_C_DP<0>")
	)
	(segment
		(start 119.823992 -22.021292)
		(end 119.340884 -23.18766)
		(width 0.14224)
		(layer "In15.Cu")
		(net "P2E_MB_BMC_TX_C_DP<0>")
	)
	(segment
		(start 27.911044 -77.583284)
		(end 18.59534 -96.472248)
		(width 0.14224)
		(layer "In15.Cu")
		(net "P2E_MB_BMC_TX_C_DP<0>")
	)
	(segment
		(start 125.692916 -19.05)
		(end 120.746266 -21.099018)
		(width 0.14224)
		(layer "In15.Cu")
		(net "P2E_MB_BMC_TX_C_DP<0>")
	)
	(segment
		(start 41.87063 -58.995056)
		(end 38.795706 -61.148468)
		(width 0.14224)
		(layer "In15.Cu")
		(net "P2E_MB_BMC_TX_C_DP<0>")
	)
	(segment
		(start 18.59534 -98.82632)
		(end 18.28038 -100.409502)
		(width 0.14224)
		(layer "In15.Cu")
		(net "P2E_MB_BMC_TX_C_DP<0>")
	)
	(segment
		(start 5.246116 -111.358172)
		(end 6.203442 -116.787422)
		(width 0.14224)
		(layer "In15.Cu")
		(net "P2E_MB_BMC_TX_C_DP<0>")
	)
	(segment
		(start 36.928044 -419.339522)
		(end 39.336218 -420.94912)
		(width 0.14224)
		(layer "In15.Cu")
		(net "P2E_MB_BMC_TX_C_DP<0>")
	)
	(segment
		(start 102.7303 -40.551354)
		(end 99.567238 -41.86174)
		(width 0.14224)
		(layer "In15.Cu")
		(net "P2E_MB_BMC_TX_C_DP<0>")
	)
	(segment
		(start 7.707376 -405.567642)
		(end 8.485378 -409.47848)
		(width 0.14224)
		(layer "In15.Cu")
		(net "P2E_MB_BMC_TX_C_DP<0>")
	)
	(segment
		(start 11.141456 -413.355028)
		(end 11.141456 -414.49117)
		(width 0.14224)
		(layer "In15.Cu")
		(net "P2E_MB_BMC_TX_C_DP<0>")
	)
	(segment
		(start 132.587492 -18.745708)
		(end 132.2832 -19.05)
		(width 0.14224)
		(layer "In15.Cu")
		(net "P2E_MB_BMC_TX_C_DP<0>")
	)
	(segment
		(start 132.28574 -17.873726)
		(end 132.014722 -18.144744)
		(width 0.12954)
		(layer "F.Cu")
		(net "P2E_MB_BMC_TX_C_DN<0>")
	)
	(segment
		(start 132.147056 -17.090898)
		(end 132.28574 -17.229582)
		(width 0.12954)
		(layer "F.Cu")
		(net "P2E_MB_BMC_TX_C_DN<0>")
	)
	(segment
		(start 132.147056 -16.549878)
		(end 132.147056 -17.090898)
		(width 0.12954)
		(layer "F.Cu")
		(net "P2E_MB_BMC_TX_C_DN<0>")
	)
	(segment
		(start 39.575994 -423.070782)
		(end 39.144194 -422.638982)
		(width 0.12954)
		(layer "F.Cu")
		(net "P2E_MB_BMC_TX_C_DN<0>")
	)
	(segment
		(start 39.575994 -423.21734)
		(end 39.575994 -423.070782)
		(width 0.12954)
		(layer "F.Cu")
		(net "P2E_MB_BMC_TX_C_DN<0>")
	)
	(segment
		(start 132.28574 -17.229582)
		(end 132.28574 -17.873726)
		(width 0.12954)
		(layer "F.Cu")
		(net "P2E_MB_BMC_TX_C_DN<0>")
	)
	(segment
		(start 3.614928 -161.723324)
		(end 3.614928 -381.702056)
		(width 0.14224)
		(layer "In15.Cu")
		(net "P2E_MB_BMC_TX_C_DN<0>")
	)
	(segment
		(start 17.82318 -100.776786)
		(end 17.537938 -101.062028)
		(width 0.14224)
		(layer "In15.Cu")
		(net "P2E_MB_BMC_TX_C_DN<0>")
	)
	(segment
		(start 120.5865 -20.860004)
		(end 119.584978 -21.861526)
		(width 0.14224)
		(layer "In15.Cu")
		(net "P2E_MB_BMC_TX_C_DN<0>")
	)
	(segment
		(start 18.009108 -100.327206)
		(end 17.82318 -100.776786)
		(width 0.14224)
		(layer "In15.Cu")
		(net "P2E_MB_BMC_TX_C_DN<0>")
	)
	(segment
		(start 13.040868 -101.36632)
		(end 10.330434 -102.489)
		(width 0.14224)
		(layer "In15.Cu")
		(net "P2E_MB_BMC_TX_C_DN<0>")
	)
	(segment
		(start 4.959604 -111.358172)
		(end 5.936488 -116.897912)
		(width 0.14224)
		(layer "In15.Cu")
		(net "P2E_MB_BMC_TX_C_DN<0>")
	)
	(segment
		(start 39.435024 -421.731948)
		(end 39.435024 -422.348152)
		(width 0.14224)
		(layer "In15.Cu")
		(net "P2E_MB_BMC_TX_C_DN<0>")
	)
	(segment
		(start 10.859516 -413.471868)
		(end 10.859516 -414.60801)
		(width 0.14224)
		(layer "In15.Cu")
		(net "P2E_MB_BMC_TX_C_DN<0>")
	)
	(segment
		(start 41.759886 -58.728102)
		(end 38.593268 -60.94603)
		(width 0.14224)
		(layer "In15.Cu")
		(net "P2E_MB_BMC_TX_C_DN<0>")
	)
	(segment
		(start 36.842446 -419.621462)
		(end 39.120572 -421.144446)
		(width 0.14224)
		(layer "In15.Cu")
		(net "P2E_MB_BMC_TX_C_DN<0>")
	)
	(segment
		(start 18.3134 -96.406462)
		(end 18.3134 -98.79838)
		(width 0.14224)
		(layer "In15.Cu")
		(net "P2E_MB_BMC_TX_C_DN<0>")
	)
	(segment
		(start 5.43052 -108.687108)
		(end 4.959604 -111.358172)
		(width 0.14224)
		(layer "In15.Cu")
		(net "P2E_MB_BMC_TX_C_DN<0>")
	)
	(segment
		(start 39.435024 -422.348152)
		(end 39.144194 -422.638982)
		(width 0.14224)
		(layer "In15.Cu")
		(net "P2E_MB_BMC_TX_C_DN<0>")
	)
	(segment
		(start 39.120572 -421.144446)
		(end 39.435024 -421.731948)
		(width 0.14224)
		(layer "In15.Cu")
		(net "P2E_MB_BMC_TX_C_DN<0>")
	)
	(segment
		(start 10.330434 -102.489)
		(end 8.46455 -104.354884)
		(width 0.14224)
		(layer "In15.Cu")
		(net "P2E_MB_BMC_TX_C_DN<0>")
	)
	(segment
		(start 10.441686 -393.308586)
		(end 7.425436 -396.324836)
		(width 0.14224)
		(layer "In15.Cu")
		(net "P2E_MB_BMC_TX_C_DN<0>")
	)
	(segment
		(start 16.94942 -136.135618)
		(end 15.125446 -142.14856)
		(width 0.14224)
		(layer "In15.Cu")
		(net "P2E_MB_BMC_TX_C_DN<0>")
	)
	(segment
		(start 10.859516 -414.60801)
		(end 12.14882 -415.897314)
		(width 0.14224)
		(layer "In15.Cu")
		(net "P2E_MB_BMC_TX_C_DN<0>")
	)
	(segment
		(start 10.441686 -388.528814)
		(end 10.441686 -393.308586)
		(width 0.14224)
		(layer "In15.Cu")
		(net "P2E_MB_BMC_TX_C_DN<0>")
	)
	(segment
		(start 115.303046 -33.732978)
		(end 113.537492 -35.498532)
		(width 0.14224)
		(layer "In15.Cu")
		(net "P2E_MB_BMC_TX_C_DN<0>")
	)
	(segment
		(start 18.93062 -421.5003)
		(end 20.809458 -419.621462)
		(width 0.14224)
		(layer "In15.Cu")
		(net "P2E_MB_BMC_TX_C_DN<0>")
	)
	(segment
		(start 15.125446 -142.14856)
		(end 4.919726 -157.422088)
		(width 0.14224)
		(layer "In15.Cu")
		(net "P2E_MB_BMC_TX_C_DN<0>")
	)
	(segment
		(start 92.229432 -41.5798)
		(end 82.247486 -45.714666)
		(width 0.14224)
		(layer "In15.Cu")
		(net "P2E_MB_BMC_TX_C_DN<0>")
	)
	(segment
		(start 8.214106 -409.560776)
		(end 9.109456 -411.721808)
		(width 0.14224)
		(layer "In15.Cu")
		(net "P2E_MB_BMC_TX_C_DN<0>")
	)
	(segment
		(start 13.159994 -124.902976)
		(end 16.94942 -134.051548)
		(width 0.14224)
		(layer "In15.Cu")
		(net "P2E_MB_BMC_TX_C_DN<0>")
	)
	(segment
		(start 99.511104 -41.5798)
		(end 92.229432 -41.5798)
		(width 0.14224)
		(layer "In15.Cu")
		(net "P2E_MB_BMC_TX_C_DN<0>")
	)
	(segment
		(start 17.537938 -101.062028)
		(end 16.80337 -101.36632)
		(width 0.14224)
		(layer "In15.Cu")
		(net "P2E_MB_BMC_TX_C_DN<0>")
	)
	(segment
		(start 20.809458 -419.621462)
		(end 36.842446 -419.621462)
		(width 0.14224)
		(layer "In15.Cu")
		(net "P2E_MB_BMC_TX_C_DN<0>")
	)
	(segment
		(start 132.305552 -18.435574)
		(end 132.305552 -18.628868)
		(width 0.14224)
		(layer "In15.Cu")
		(net "P2E_MB_BMC_TX_C_DN<0>")
	)
	(segment
		(start 119.058944 -24.665432)
		(end 115.303046 -33.732978)
		(width 0.14224)
		(layer "In15.Cu")
		(net "P2E_MB_BMC_TX_C_DN<0>")
	)
	(segment
		(start 4.919726 -157.422088)
		(end 3.614928 -161.723324)
		(width 0.14224)
		(layer "In15.Cu")
		(net "P2E_MB_BMC_TX_C_DN<0>")
	)
	(segment
		(start 132.305552 -18.628868)
		(end 132.16636 -18.76806)
		(width 0.14224)
		(layer "In15.Cu")
		(net "P2E_MB_BMC_TX_C_DN<0>")
	)
	(segment
		(start 60.367926 -55.447184)
		(end 41.759886 -58.728102)
		(width 0.14224)
		(layer "In15.Cu")
		(net "P2E_MB_BMC_TX_C_DN<0>")
	)
	(segment
		(start 18.3134 -98.79838)
		(end 18.009108 -100.327206)
		(width 0.14224)
		(layer "In15.Cu")
		(net "P2E_MB_BMC_TX_C_DN<0>")
	)
	(segment
		(start 125.636782 -18.76806)
		(end 120.5865 -20.860004)
		(width 0.14224)
		(layer "In15.Cu")
		(net "P2E_MB_BMC_TX_C_DN<0>")
	)
	(segment
		(start 38.593268 -60.94603)
		(end 28.568904 -75.258168)
		(width 0.14224)
		(layer "In15.Cu")
		(net "P2E_MB_BMC_TX_C_DN<0>")
	)
	(segment
		(start 28.568904 -75.258168)
		(end 27.653996 -77.466952)
		(width 0.14224)
		(layer "In15.Cu")
		(net "P2E_MB_BMC_TX_C_DN<0>")
	)
	(segment
		(start 16.80337 -101.36632)
		(end 13.040868 -101.36632)
		(width 0.14224)
		(layer "In15.Cu")
		(net "P2E_MB_BMC_TX_C_DN<0>")
	)
	(segment
		(start 132.16636 -18.76806)
		(end 125.636782 -18.76806)
		(width 0.14224)
		(layer "In15.Cu")
		(net "P2E_MB_BMC_TX_C_DN<0>")
	)
	(segment
		(start 14.020292 -421.5003)
		(end 18.93062 -421.5003)
		(width 0.14224)
		(layer "In15.Cu")
		(net "P2E_MB_BMC_TX_C_DN<0>")
	)
	(segment
		(start 81.103724 -46.858428)
		(end 60.367926 -55.447184)
		(width 0.14224)
		(layer "In15.Cu")
		(net "P2E_MB_BMC_TX_C_DN<0>")
	)
	(segment
		(start 12.14882 -419.628828)
		(end 14.020292 -421.5003)
		(width 0.14224)
		(layer "In15.Cu")
		(net "P2E_MB_BMC_TX_C_DN<0>")
	)
	(segment
		(start 3.614928 -381.702056)
		(end 10.441686 -388.528814)
		(width 0.14224)
		(layer "In15.Cu")
		(net "P2E_MB_BMC_TX_C_DN<0>")
	)
	(segment
		(start 119.584978 -21.861526)
		(end 119.058944 -23.131526)
		(width 0.14224)
		(layer "In15.Cu")
		(net "P2E_MB_BMC_TX_C_DN<0>")
	)
	(segment
		(start 82.247486 -45.714666)
		(end 81.103724 -46.858428)
		(width 0.14224)
		(layer "In15.Cu")
		(net "P2E_MB_BMC_TX_C_DN<0>")
	)
	(segment
		(start 16.94942 -134.051548)
		(end 16.94942 -136.135618)
		(width 0.14224)
		(layer "In15.Cu")
		(net "P2E_MB_BMC_TX_C_DN<0>")
	)
	(segment
		(start 119.058944 -23.131526)
		(end 119.058944 -24.665432)
		(width 0.14224)
		(layer "In15.Cu")
		(net "P2E_MB_BMC_TX_C_DN<0>")
	)
	(segment
		(start 102.570534 -40.31234)
		(end 99.511104 -41.5798)
		(width 0.14224)
		(layer "In15.Cu")
		(net "P2E_MB_BMC_TX_C_DN<0>")
	)
	(segment
		(start 7.425436 -396.324836)
		(end 7.425436 -405.595582)
		(width 0.14224)
		(layer "In15.Cu")
		(net "P2E_MB_BMC_TX_C_DN<0>")
	)
	(segment
		(start 132.014722 -18.144744)
		(end 132.305552 -18.435574)
		(width 0.14224)
		(layer "In15.Cu")
		(net "P2E_MB_BMC_TX_C_DN<0>")
	)
	(segment
		(start 113.537492 -35.498532)
		(end 103.033322 -39.849298)
		(width 0.14224)
		(layer "In15.Cu")
		(net "P2E_MB_BMC_TX_C_DN<0>")
	)
	(segment
		(start 9.109456 -411.721808)
		(end 10.859516 -413.471868)
		(width 0.14224)
		(layer "In15.Cu")
		(net "P2E_MB_BMC_TX_C_DN<0>")
	)
	(segment
		(start 7.425436 -405.595582)
		(end 8.214106 -409.560776)
		(width 0.14224)
		(layer "In15.Cu")
		(net "P2E_MB_BMC_TX_C_DN<0>")
	)
	(segment
		(start 5.936488 -116.897912)
		(end 7.763002 -119.506238)
		(width 0.14224)
		(layer "In15.Cu")
		(net "P2E_MB_BMC_TX_C_DN<0>")
	)
	(segment
		(start 12.14882 -415.897314)
		(end 12.14882 -419.628828)
		(width 0.14224)
		(layer "In15.Cu")
		(net "P2E_MB_BMC_TX_C_DN<0>")
	)
	(segment
		(start 27.653996 -77.466952)
		(end 18.3134 -96.406462)
		(width 0.14224)
		(layer "In15.Cu")
		(net "P2E_MB_BMC_TX_C_DN<0>")
	)
	(segment
		(start 8.46455 -104.354884)
		(end 5.43052 -108.687108)
		(width 0.14224)
		(layer "In15.Cu")
		(net "P2E_MB_BMC_TX_C_DN<0>")
	)
	(segment
		(start 103.033322 -39.849298)
		(end 102.570534 -40.31234)
		(width 0.14224)
		(layer "In15.Cu")
		(net "P2E_MB_BMC_TX_C_DN<0>")
	)
	(segment
		(start 7.763002 -119.506238)
		(end 13.159994 -124.902976)
		(width 0.14224)
		(layer "In15.Cu")
		(net "P2E_MB_BMC_TX_C_DN<0>")
	)
	(segment
		(start 28.13685 -421.267382)
		(end 27.704542 -421.69969)
		(width 0.12954)
		(layer "F.Cu")
		(net "P2E_MB_BMC_TX_BUF_C_DP<0>")
	)
	(segment
		(start 28.13685 -421.069008)
		(end 28.13685 -421.267382)
		(width 0.12954)
		(layer "F.Cu")
		(net "P2E_MB_BMC_TX_BUF_C_DP<0>")
	)
	(segment
		(start 30.288738 -422.751758)
		(end 41.076118 -420.605966)
		(width 0.14224)
		(layer "In2.Cu")
		(net "P2E_MB_BMC_TX_BUF_C_DP<0>")
	)
	(segment
		(start 41.076118 -420.605966)
		(end 47.765208 -413.916876)
		(width 0.14224)
		(layer "In2.Cu")
		(net "P2E_MB_BMC_TX_BUF_C_DP<0>")
	)
	(segment
		(start 68.186554 -420.62654)
		(end 68.64985 -421.089836)
		(width 0.14224)
		(layer "In2.Cu")
		(net "P2E_MB_BMC_TX_BUF_C_DP<0>")
	)
	(segment
		(start 27.995372 -421.99052)
		(end 27.995372 -422.396158)
		(width 0.14224)
		(layer "In2.Cu")
		(net "P2E_MB_BMC_TX_BUF_C_DP<0>")
	)
	(segment
		(start 67.51066 -416.939476)
		(end 67.51066 -420.33444)
		(width 0.14224)
		(layer "In2.Cu")
		(net "P2E_MB_BMC_TX_BUF_C_DP<0>")
	)
	(segment
		(start 67.80276 -420.62654)
		(end 68.186554 -420.62654)
		(width 0.14224)
		(layer "In2.Cu")
		(net "P2E_MB_BMC_TX_BUF_C_DP<0>")
	)
	(segment
		(start 27.995372 -422.396158)
		(end 28.350972 -422.751758)
		(width 0.14224)
		(layer "In2.Cu")
		(net "P2E_MB_BMC_TX_BUF_C_DP<0>")
	)
	(segment
		(start 27.704542 -421.69969)
		(end 27.995372 -421.99052)
		(width 0.14224)
		(layer "In2.Cu")
		(net "P2E_MB_BMC_TX_BUF_C_DP<0>")
	)
	(segment
		(start 67.51066 -420.33444)
		(end 67.80276 -420.62654)
		(width 0.14224)
		(layer "In2.Cu")
		(net "P2E_MB_BMC_TX_BUF_C_DP<0>")
	)
	(segment
		(start 61.336428 -413.916876)
		(end 66.716656 -416.145472)
		(width 0.14224)
		(layer "In2.Cu")
		(net "P2E_MB_BMC_TX_BUF_C_DP<0>")
	)
	(segment
		(start 47.765208 -413.916876)
		(end 61.336428 -413.916876)
		(width 0.14224)
		(layer "In2.Cu")
		(net "P2E_MB_BMC_TX_BUF_C_DP<0>")
	)
	(segment
		(start 66.716656 -416.145472)
		(end 67.51066 -416.939476)
		(width 0.14224)
		(layer "In2.Cu")
		(net "P2E_MB_BMC_TX_BUF_C_DP<0>")
	)
	(segment
		(start 28.350972 -422.751758)
		(end 30.288738 -422.751758)
		(width 0.14224)
		(layer "In2.Cu")
		(net "P2E_MB_BMC_TX_BUF_C_DP<0>")
	)
	(segment
		(start 28.13558 -422.330626)
		(end 28.13558 -422.132252)
		(width 0.12954)
		(layer "F.Cu")
		(net "P2E_MB_BMC_TX_BUF_C_DN<0>")
	)
	(segment
		(start 28.13558 -422.132252)
		(end 28.568142 -421.69969)
		(width 0.12954)
		(layer "F.Cu")
		(net "P2E_MB_BMC_TX_BUF_C_DN<0>")
	)
	(segment
		(start 67.7926 -416.822636)
		(end 67.7926 -420.2176)
		(width 0.14224)
		(layer "In2.Cu")
		(net "P2E_MB_BMC_TX_BUF_C_DN<0>")
	)
	(segment
		(start 41.779444 -419.50386)
		(end 42.080942 -419.202362)
		(width 0.14224)
		(layer "In2.Cu")
		(net "P2E_MB_BMC_TX_BUF_C_DN<0>")
	)
	(segment
		(start 28.467812 -422.469818)
		(end 30.260798 -422.469818)
		(width 0.14224)
		(layer "In2.Cu")
		(net "P2E_MB_BMC_TX_BUF_C_DN<0>")
	)
	(segment
		(start 42.577004 -418.7063)
		(end 47.648368 -413.634936)
		(width 0.14224)
		(layer "In2.Cu")
		(net "P2E_MB_BMC_TX_BUF_C_DN<0>")
	)
	(segment
		(start 66.876422 -415.906458)
		(end 67.7926 -416.822636)
		(width 0.14224)
		(layer "In2.Cu")
		(net "P2E_MB_BMC_TX_BUF_C_DN<0>")
	)
	(segment
		(start 68.19519 -420.3446)
		(end 68.64985 -419.88994)
		(width 0.14224)
		(layer "In2.Cu")
		(net "P2E_MB_BMC_TX_BUF_C_DN<0>")
	)
	(segment
		(start 28.277312 -422.279318)
		(end 28.467812 -422.469818)
		(width 0.14224)
		(layer "In2.Cu")
		(net "P2E_MB_BMC_TX_BUF_C_DN<0>")
	)
	(segment
		(start 41.283636 -419.999668)
		(end 41.283636 -419.805866)
		(width 0.14224)
		(layer "In2.Cu")
		(net "P2E_MB_BMC_TX_BUF_C_DN<0>")
	)
	(segment
		(start 28.277312 -421.99052)
		(end 28.277312 -422.279318)
		(width 0.14224)
		(layer "In2.Cu")
		(net "P2E_MB_BMC_TX_BUF_C_DN<0>")
	)
	(segment
		(start 42.080942 -419.202362)
		(end 42.080942 -419.008306)
		(width 0.14224)
		(layer "In2.Cu")
		(net "P2E_MB_BMC_TX_BUF_C_DN<0>")
	)
	(segment
		(start 41.283636 -419.805866)
		(end 41.585642 -419.50386)
		(width 0.14224)
		(layer "In2.Cu")
		(net "P2E_MB_BMC_TX_BUF_C_DN<0>")
	)
	(segment
		(start 40.93718 -420.346124)
		(end 41.283636 -419.999668)
		(width 0.14224)
		(layer "In2.Cu")
		(net "P2E_MB_BMC_TX_BUF_C_DN<0>")
	)
	(segment
		(start 42.080942 -419.008306)
		(end 42.382948 -418.7063)
		(width 0.14224)
		(layer "In2.Cu")
		(net "P2E_MB_BMC_TX_BUF_C_DN<0>")
	)
	(segment
		(start 30.260798 -422.469818)
		(end 40.93718 -420.346124)
		(width 0.14224)
		(layer "In2.Cu")
		(net "P2E_MB_BMC_TX_BUF_C_DN<0>")
	)
	(segment
		(start 42.382948 -418.7063)
		(end 42.577004 -418.7063)
		(width 0.14224)
		(layer "In2.Cu")
		(net "P2E_MB_BMC_TX_BUF_C_DN<0>")
	)
	(segment
		(start 41.585642 -419.50386)
		(end 41.779444 -419.50386)
		(width 0.14224)
		(layer "In2.Cu")
		(net "P2E_MB_BMC_TX_BUF_C_DN<0>")
	)
	(segment
		(start 61.392562 -413.634936)
		(end 66.876422 -415.906458)
		(width 0.14224)
		(layer "In2.Cu")
		(net "P2E_MB_BMC_TX_BUF_C_DN<0>")
	)
	(segment
		(start 47.648368 -413.634936)
		(end 61.392562 -413.634936)
		(width 0.14224)
		(layer "In2.Cu")
		(net "P2E_MB_BMC_TX_BUF_C_DN<0>")
	)
	(segment
		(start 67.7926 -420.2176)
		(end 67.9196 -420.3446)
		(width 0.14224)
		(layer "In2.Cu")
		(net "P2E_MB_BMC_TX_BUF_C_DN<0>")
	)
	(segment
		(start 28.568142 -421.69969)
		(end 28.277312 -421.99052)
		(width 0.14224)
		(layer "In2.Cu")
		(net "P2E_MB_BMC_TX_BUF_C_DN<0>")
	)
	(segment
		(start 67.9196 -420.3446)
		(end 68.19519 -420.3446)
		(width 0.14224)
		(layer "In2.Cu")
		(net "P2E_MB_BMC_TX_BUF_C_DN<0>")
	)
	(segment
		(start 27.754326 -428.755302)
		(end 27.754326 -428.615602)
		(width 0.12954)
		(layer "F.Cu")
		(net "P2E_MB_BMC_RX_DP<0>")
	)
	(segment
		(start 27.754326 -428.615602)
		(end 28.186126 -428.183802)
		(width 0.12954)
		(layer "F.Cu")
		(net "P2E_MB_BMC_RX_DP<0>")
	)
	(segment
		(start 70.612 -411.192472)
		(end 47.090076 -411.192472)
		(width 0.14224)
		(layer "In2.Cu")
		(net "P2E_MB_BMC_RX_DP<0>")
	)
	(segment
		(start 26.979372 -429.826674)
		(end 27.895296 -428.91075)
		(width 0.14224)
		(layer "In2.Cu")
		(net "P2E_MB_BMC_RX_DP<0>")
	)
	(segment
		(start 25.175464 -429.826674)
		(end 26.979372 -429.826674)
		(width 0.14224)
		(layer "In2.Cu")
		(net "P2E_MB_BMC_RX_DP<0>")
	)
	(segment
		(start 69.108828 -424.2308)
		(end 69.4817 -424.2308)
		(width 0.14224)
		(layer "In2.Cu")
		(net "P2E_MB_BMC_RX_DP<0>")
	)
	(segment
		(start 71.341234 -413.977836)
		(end 71.341234 -411.921706)
		(width 0.14224)
		(layer "In2.Cu")
		(net "P2E_MB_BMC_RX_DP<0>")
	)
	(segment
		(start 39.351204 -418.931344)
		(end 25.54478 -418.931344)
		(width 0.14224)
		(layer "In2.Cu")
		(net "P2E_MB_BMC_RX_DP<0>")
	)
	(segment
		(start 68.64985 -424.689778)
		(end 69.108828 -424.2308)
		(width 0.14224)
		(layer "In2.Cu")
		(net "P2E_MB_BMC_RX_DP<0>")
	)
	(segment
		(start 69.4817 -424.2308)
		(end 69.7738 -423.9387)
		(width 0.14224)
		(layer "In2.Cu")
		(net "P2E_MB_BMC_RX_DP<0>")
	)
	(segment
		(start 24.127968 -420.348156)
		(end 24.127968 -428.779178)
		(width 0.14224)
		(layer "In2.Cu")
		(net "P2E_MB_BMC_RX_DP<0>")
	)
	(segment
		(start 27.895296 -428.91075)
		(end 27.895296 -428.474632)
		(width 0.14224)
		(layer "In2.Cu")
		(net "P2E_MB_BMC_RX_DP<0>")
	)
	(segment
		(start 47.090076 -411.192472)
		(end 39.351204 -418.931344)
		(width 0.14224)
		(layer "In2.Cu")
		(net "P2E_MB_BMC_RX_DP<0>")
	)
	(segment
		(start 69.7738 -417.762182)
		(end 71.341234 -413.977836)
		(width 0.14224)
		(layer "In2.Cu")
		(net "P2E_MB_BMC_RX_DP<0>")
	)
	(segment
		(start 69.7738 -423.9387)
		(end 69.7738 -417.762182)
		(width 0.14224)
		(layer "In2.Cu")
		(net "P2E_MB_BMC_RX_DP<0>")
	)
	(segment
		(start 27.895296 -428.474632)
		(end 28.186126 -428.183802)
		(width 0.14224)
		(layer "In2.Cu")
		(net "P2E_MB_BMC_RX_DP<0>")
	)
	(segment
		(start 24.127968 -428.779178)
		(end 25.175464 -429.826674)
		(width 0.14224)
		(layer "In2.Cu")
		(net "P2E_MB_BMC_RX_DP<0>")
	)
	(segment
		(start 25.54478 -418.931344)
		(end 24.127968 -420.348156)
		(width 0.14224)
		(layer "In2.Cu")
		(net "P2E_MB_BMC_RX_DP<0>")
	)
	(segment
		(start 71.341234 -411.921706)
		(end 70.612 -411.192472)
		(width 0.14224)
		(layer "In2.Cu")
		(net "P2E_MB_BMC_RX_DP<0>")
	)
	(segment
		(start 27.754326 -427.612302)
		(end 27.754326 -427.752002)
		(width 0.12954)
		(layer "F.Cu")
		(net "P2E_MB_BMC_RX_DN<0>")
	)
	(segment
		(start 27.754326 -427.752002)
		(end 27.322526 -428.183802)
		(width 0.12954)
		(layer "F.Cu")
		(net "P2E_MB_BMC_RX_DN<0>")
	)
	(segment
		(start 47.206916 -411.474412)
		(end 44.253404 -414.427924)
		(width 0.14224)
		(layer "In2.Cu")
		(net "P2E_MB_BMC_RX_DN<0>")
	)
	(segment
		(start 68.64985 -423.489882)
		(end 69.108828 -423.94886)
		(width 0.14224)
		(layer "In2.Cu")
		(net "P2E_MB_BMC_RX_DN<0>")
	)
	(segment
		(start 32.488632 -419.213284)
		(end 32.061912 -419.213284)
		(width 0.14224)
		(layer "In2.Cu")
		(net "P2E_MB_BMC_RX_DN<0>")
	)
	(segment
		(start 70.01256 -416.090608)
		(end 70.175882 -415.696146)
		(width 0.14224)
		(layer "In2.Cu")
		(net "P2E_MB_BMC_RX_DN<0>")
	)
	(segment
		(start 70.444106 -415.048446)
		(end 70.607428 -414.653984)
		(width 0.14224)
		(layer "In2.Cu")
		(net "P2E_MB_BMC_RX_DN<0>")
	)
	(segment
		(start 31.498032 -419.350444)
		(end 31.360872 -419.213284)
		(width 0.14224)
		(layer "In2.Cu")
		(net "P2E_MB_BMC_RX_DN<0>")
	)
	(segment
		(start 69.654928 -417.31184)
		(end 69.58076 -417.13277)
		(width 0.14224)
		(layer "In2.Cu")
		(net "P2E_MB_BMC_RX_DN<0>")
	)
	(segment
		(start 42.658284 -416.023044)
		(end 42.658284 -416.2171)
		(width 0.14224)
		(layer "In2.Cu")
		(net "P2E_MB_BMC_RX_DN<0>")
	)
	(segment
		(start 26.703274 -419.350444)
		(end 26.276554 -419.350444)
		(width 0.14224)
		(layer "In2.Cu")
		(net "P2E_MB_BMC_RX_DN<0>")
	)
	(segment
		(start 41.364662 -417.316666)
		(end 41.063164 -417.618164)
		(width 0.14224)
		(layer "In2.Cu")
		(net "P2E_MB_BMC_RX_DN<0>")
	)
	(segment
		(start 32.061912 -419.213284)
		(end 31.924752 -419.350444)
		(width 0.14224)
		(layer "In2.Cu")
		(net "P2E_MB_BMC_RX_DN<0>")
	)
	(segment
		(start 69.744082 -416.738308)
		(end 69.92366 -416.663886)
		(width 0.14224)
		(layer "In2.Cu")
		(net "P2E_MB_BMC_RX_DN<0>")
	)
	(segment
		(start 41.063164 -417.81222)
		(end 40.761158 -418.114226)
		(width 0.14224)
		(layer "In2.Cu")
		(net "P2E_MB_BMC_RX_DN<0>")
	)
	(segment
		(start 39.468044 -419.213284)
		(end 39.041324 -419.213284)
		(width 0.14224)
		(layer "In2.Cu")
		(net "P2E_MB_BMC_RX_DN<0>")
	)
	(segment
		(start 24.409908 -425.79798)
		(end 24.409908 -426.2247)
		(width 0.14224)
		(layer "In2.Cu")
		(net "P2E_MB_BMC_RX_DN<0>")
	)
	(segment
		(start 27.613356 -428.474632)
		(end 27.322526 -428.183802)
		(width 0.14224)
		(layer "In2.Cu")
		(net "P2E_MB_BMC_RX_DN<0>")
	)
	(segment
		(start 24.409908 -428.0535)
		(end 24.409908 -428.662338)
		(width 0.14224)
		(layer "In2.Cu")
		(net "P2E_MB_BMC_RX_DN<0>")
	)
	(segment
		(start 70.786752 -414.579562)
		(end 71.059294 -413.921702)
		(width 0.14224)
		(layer "In2.Cu")
		(net "P2E_MB_BMC_RX_DN<0>")
	)
	(segment
		(start 69.92366 -416.663886)
		(end 70.086728 -416.269678)
		(width 0.14224)
		(layer "In2.Cu")
		(net "P2E_MB_BMC_RX_DN<0>")
	)
	(segment
		(start 40.761158 -418.114226)
		(end 40.567102 -418.114226)
		(width 0.14224)
		(layer "In2.Cu")
		(net "P2E_MB_BMC_RX_DN<0>")
	)
	(segment
		(start 38.340284 -419.213284)
		(end 37.336984 -419.213284)
		(width 0.14224)
		(layer "In2.Cu")
		(net "P2E_MB_BMC_RX_DN<0>")
	)
	(segment
		(start 38.477444 -419.350444)
		(end 38.340284 -419.213284)
		(width 0.14224)
		(layer "In2.Cu")
		(net "P2E_MB_BMC_RX_DN<0>")
	)
	(segment
		(start 39.041324 -419.213284)
		(end 38.904164 -419.350444)
		(width 0.14224)
		(layer "In2.Cu")
		(net "P2E_MB_BMC_RX_DN<0>")
	)
	(segment
		(start 26.862532 -429.544734)
		(end 27.613356 -428.79391)
		(width 0.14224)
		(layer "In2.Cu")
		(net "P2E_MB_BMC_RX_DN<0>")
	)
	(segment
		(start 31.924752 -419.350444)
		(end 31.498032 -419.350444)
		(width 0.14224)
		(layer "In2.Cu")
		(net "P2E_MB_BMC_RX_DN<0>")
	)
	(segment
		(start 70.355206 -415.621724)
		(end 70.518274 -415.227516)
		(width 0.14224)
		(layer "In2.Cu")
		(net "P2E_MB_BMC_RX_DN<0>")
	)
	(segment
		(start 41.063164 -417.618164)
		(end 41.063164 -417.81222)
		(width 0.14224)
		(layer "In2.Cu")
		(net "P2E_MB_BMC_RX_DN<0>")
	)
	(segment
		(start 27.452828 -419.350444)
		(end 27.315668 -419.213284)
		(width 0.14224)
		(layer "In2.Cu")
		(net "P2E_MB_BMC_RX_DN<0>")
	)
	(segment
		(start 29.885132 -419.213284)
		(end 29.458412 -419.213284)
		(width 0.14224)
		(layer "In2.Cu")
		(net "P2E_MB_BMC_RX_DN<0>")
	)
	(segment
		(start 28.757372 -419.213284)
		(end 28.016708 -419.213284)
		(width 0.14224)
		(layer "In2.Cu")
		(net "P2E_MB_BMC_RX_DN<0>")
	)
	(segment
		(start 34.317432 -419.213284)
		(end 34.180272 -419.350444)
		(width 0.14224)
		(layer "In2.Cu")
		(net "P2E_MB_BMC_RX_DN<0>")
	)
	(segment
		(start 24.409908 -426.2247)
		(end 24.547068 -426.36186)
		(width 0.14224)
		(layer "In2.Cu")
		(net "P2E_MB_BMC_RX_DN<0>")
	)
	(segment
		(start 33.052512 -419.350444)
		(end 32.625792 -419.350444)
		(width 0.14224)
		(layer "In2.Cu")
		(net "P2E_MB_BMC_RX_DN<0>")
	)
	(segment
		(start 25.292304 -429.544734)
		(end 26.862532 -429.544734)
		(width 0.14224)
		(layer "In2.Cu")
		(net "P2E_MB_BMC_RX_DN<0>")
	)
	(segment
		(start 70.607428 -414.653984)
		(end 70.786752 -414.579562)
		(width 0.14224)
		(layer "In2.Cu")
		(net "P2E_MB_BMC_RX_DN<0>")
	)
	(segment
		(start 24.547068 -425.66082)
		(end 24.409908 -425.79798)
		(width 0.14224)
		(layer "In2.Cu")
		(net "P2E_MB_BMC_RX_DN<0>")
	)
	(segment
		(start 42.658284 -416.2171)
		(end 42.356278 -416.519106)
		(width 0.14224)
		(layer "In2.Cu")
		(net "P2E_MB_BMC_RX_DN<0>")
	)
	(segment
		(start 24.547068 -427.91634)
		(end 24.409908 -428.0535)
		(width 0.14224)
		(layer "In2.Cu")
		(net "P2E_MB_BMC_RX_DN<0>")
	)
	(segment
		(start 33.753552 -419.350444)
		(end 33.616392 -419.213284)
		(width 0.14224)
		(layer "In2.Cu")
		(net "P2E_MB_BMC_RX_DN<0>")
	)
	(segment
		(start 31.360872 -419.213284)
		(end 30.586172 -419.213284)
		(width 0.14224)
		(layer "In2.Cu")
		(net "P2E_MB_BMC_RX_DN<0>")
	)
	(segment
		(start 28.016708 -419.213284)
		(end 27.879548 -419.350444)
		(width 0.14224)
		(layer "In2.Cu")
		(net "P2E_MB_BMC_RX_DN<0>")
	)
	(segment
		(start 36.773104 -419.350444)
		(end 36.635944 -419.213284)
		(width 0.14224)
		(layer "In2.Cu")
		(net "P2E_MB_BMC_RX_DN<0>")
	)
	(segment
		(start 44.253404 -414.427924)
		(end 44.253404 -414.62198)
		(width 0.14224)
		(layer "In2.Cu")
		(net "P2E_MB_BMC_RX_DN<0>")
	)
	(segment
		(start 30.022292 -419.350444)
		(end 29.885132 -419.213284)
		(width 0.14224)
		(layer "In2.Cu")
		(net "P2E_MB_BMC_RX_DN<0>")
	)
	(segment
		(start 37.199824 -419.350444)
		(end 36.773104 -419.350444)
		(width 0.14224)
		(layer "In2.Cu")
		(net "P2E_MB_BMC_RX_DN<0>")
	)
	(segment
		(start 24.409908 -427.35246)
		(end 24.547068 -427.48962)
		(width 0.14224)
		(layer "In2.Cu")
		(net "P2E_MB_BMC_RX_DN<0>")
	)
	(segment
		(start 30.586172 -419.213284)
		(end 30.449012 -419.350444)
		(width 0.14224)
		(layer "In2.Cu")
		(net "P2E_MB_BMC_RX_DN<0>")
	)
	(segment
		(start 34.180272 -419.350444)
		(end 33.753552 -419.350444)
		(width 0.14224)
		(layer "In2.Cu")
		(net "P2E_MB_BMC_RX_DN<0>")
	)
	(segment
		(start 28.894532 -419.350444)
		(end 28.757372 -419.213284)
		(width 0.14224)
		(layer "In2.Cu")
		(net "P2E_MB_BMC_RX_DN<0>")
	)
	(segment
		(start 29.321252 -419.350444)
		(end 28.894532 -419.350444)
		(width 0.14224)
		(layer "In2.Cu")
		(net "P2E_MB_BMC_RX_DN<0>")
	)
	(segment
		(start 29.458412 -419.213284)
		(end 29.321252 -419.350444)
		(width 0.14224)
		(layer "In2.Cu")
		(net "P2E_MB_BMC_RX_DN<0>")
	)
	(segment
		(start 36.635944 -419.213284)
		(end 34.317432 -419.213284)
		(width 0.14224)
		(layer "In2.Cu")
		(net "P2E_MB_BMC_RX_DN<0>")
	)
	(segment
		(start 33.189672 -419.213284)
		(end 33.052512 -419.350444)
		(width 0.14224)
		(layer "In2.Cu")
		(net "P2E_MB_BMC_RX_DN<0>")
	)
	(segment
		(start 69.36486 -423.94886)
		(end 69.49186 -423.82186)
		(width 0.14224)
		(layer "In2.Cu")
		(net "P2E_MB_BMC_RX_DN<0>")
	)
	(segment
		(start 24.547068 -427.48962)
		(end 24.547068 -427.91634)
		(width 0.14224)
		(layer "In2.Cu")
		(net "P2E_MB_BMC_RX_DN<0>")
	)
	(segment
		(start 41.860724 -417.01466)
		(end 41.558718 -417.316666)
		(width 0.14224)
		(layer "In2.Cu")
		(net "P2E_MB_BMC_RX_DN<0>")
	)
	(segment
		(start 27.613356 -428.79391)
		(end 27.613356 -428.474632)
		(width 0.14224)
		(layer "In2.Cu")
		(net "P2E_MB_BMC_RX_DN<0>")
	)
	(segment
		(start 24.547068 -426.36186)
		(end 24.547068 -426.78858)
		(width 0.14224)
		(layer "In2.Cu")
		(net "P2E_MB_BMC_RX_DN<0>")
	)
	(segment
		(start 69.49186 -423.82186)
		(end 69.49186 -417.706048)
		(width 0.14224)
		(layer "In2.Cu")
		(net "P2E_MB_BMC_RX_DN<0>")
	)
	(segment
		(start 71.059294 -413.921702)
		(end 71.059294 -412.038546)
		(width 0.14224)
		(layer "In2.Cu")
		(net "P2E_MB_BMC_RX_DN<0>")
	)
	(segment
		(start 43.455844 -415.41954)
		(end 43.153838 -415.721546)
		(width 0.14224)
		(layer "In2.Cu")
		(net "P2E_MB_BMC_RX_DN<0>")
	)
	(segment
		(start 24.547068 -426.78858)
		(end 24.409908 -426.92574)
		(width 0.14224)
		(layer "In2.Cu")
		(net "P2E_MB_BMC_RX_DN<0>")
	)
	(segment
		(start 30.449012 -419.350444)
		(end 30.022292 -419.350444)
		(width 0.14224)
		(layer "In2.Cu")
		(net "P2E_MB_BMC_RX_DN<0>")
	)
	(segment
		(start 42.162222 -416.519106)
		(end 41.860724 -416.820604)
		(width 0.14224)
		(layer "In2.Cu")
		(net "P2E_MB_BMC_RX_DN<0>")
	)
	(segment
		(start 24.547068 -425.2341)
		(end 24.547068 -425.66082)
		(width 0.14224)
		(layer "In2.Cu")
		(net "P2E_MB_BMC_RX_DN<0>")
	)
	(segment
		(start 70.49516 -411.474412)
		(end 47.206916 -411.474412)
		(width 0.14224)
		(layer "In2.Cu")
		(net "P2E_MB_BMC_RX_DN<0>")
	)
	(segment
		(start 33.616392 -419.213284)
		(end 33.189672 -419.213284)
		(width 0.14224)
		(layer "In2.Cu")
		(net "P2E_MB_BMC_RX_DN<0>")
	)
	(segment
		(start 26.139394 -419.213284)
		(end 25.66162 -419.213284)
		(width 0.14224)
		(layer "In2.Cu")
		(net "P2E_MB_BMC_RX_DN<0>")
	)
	(segment
		(start 41.860724 -416.820604)
		(end 41.860724 -417.01466)
		(width 0.14224)
		(layer "In2.Cu")
		(net "P2E_MB_BMC_RX_DN<0>")
	)
	(segment
		(start 26.276554 -419.350444)
		(end 26.139394 -419.213284)
		(width 0.14224)
		(layer "In2.Cu")
		(net "P2E_MB_BMC_RX_DN<0>")
	)
	(segment
		(start 26.840434 -419.213284)
		(end 26.703274 -419.350444)
		(width 0.14224)
		(layer "In2.Cu")
		(net "P2E_MB_BMC_RX_DN<0>")
	)
	(segment
		(start 27.315668 -419.213284)
		(end 26.840434 -419.213284)
		(width 0.14224)
		(layer "In2.Cu")
		(net "P2E_MB_BMC_RX_DN<0>")
	)
	(segment
		(start 43.153838 -415.721546)
		(end 42.959782 -415.721546)
		(width 0.14224)
		(layer "In2.Cu")
		(net "P2E_MB_BMC_RX_DN<0>")
	)
	(segment
		(start 70.518274 -415.227516)
		(end 70.444106 -415.048446)
		(width 0.14224)
		(layer "In2.Cu")
		(net "P2E_MB_BMC_RX_DN<0>")
	)
	(segment
		(start 43.757342 -414.923986)
		(end 43.455844 -415.225484)
		(width 0.14224)
		(layer "In2.Cu")
		(net "P2E_MB_BMC_RX_DN<0>")
	)
	(segment
		(start 69.49186 -417.706048)
		(end 69.654928 -417.31184)
		(width 0.14224)
		(layer "In2.Cu")
		(net "P2E_MB_BMC_RX_DN<0>")
	)
	(segment
		(start 24.409908 -428.662338)
		(end 25.292304 -429.544734)
		(width 0.14224)
		(layer "In2.Cu")
		(net "P2E_MB_BMC_RX_DN<0>")
	)
	(segment
		(start 27.879548 -419.350444)
		(end 27.452828 -419.350444)
		(width 0.14224)
		(layer "In2.Cu")
		(net "P2E_MB_BMC_RX_DN<0>")
	)
	(segment
		(start 42.356278 -416.519106)
		(end 42.162222 -416.519106)
		(width 0.14224)
		(layer "In2.Cu")
		(net "P2E_MB_BMC_RX_DN<0>")
	)
	(segment
		(start 43.951398 -414.923986)
		(end 43.757342 -414.923986)
		(width 0.14224)
		(layer "In2.Cu")
		(net "P2E_MB_BMC_RX_DN<0>")
	)
	(segment
		(start 24.409908 -425.09694)
		(end 24.547068 -425.2341)
		(width 0.14224)
		(layer "In2.Cu")
		(net "P2E_MB_BMC_RX_DN<0>")
	)
	(segment
		(start 43.455844 -415.225484)
		(end 43.455844 -415.41954)
		(width 0.14224)
		(layer "In2.Cu")
		(net "P2E_MB_BMC_RX_DN<0>")
	)
	(segment
		(start 24.409908 -426.92574)
		(end 24.409908 -427.35246)
		(width 0.14224)
		(layer "In2.Cu")
		(net "P2E_MB_BMC_RX_DN<0>")
	)
	(segment
		(start 38.904164 -419.350444)
		(end 38.477444 -419.350444)
		(width 0.14224)
		(layer "In2.Cu")
		(net "P2E_MB_BMC_RX_DN<0>")
	)
	(segment
		(start 69.108828 -423.94886)
		(end 69.36486 -423.94886)
		(width 0.14224)
		(layer "In2.Cu")
		(net "P2E_MB_BMC_RX_DN<0>")
	)
	(segment
		(start 70.175882 -415.696146)
		(end 70.355206 -415.621724)
		(width 0.14224)
		(layer "In2.Cu")
		(net "P2E_MB_BMC_RX_DN<0>")
	)
	(segment
		(start 37.336984 -419.213284)
		(end 37.199824 -419.350444)
		(width 0.14224)
		(layer "In2.Cu")
		(net "P2E_MB_BMC_RX_DN<0>")
	)
	(segment
		(start 44.253404 -414.62198)
		(end 43.951398 -414.923986)
		(width 0.14224)
		(layer "In2.Cu")
		(net "P2E_MB_BMC_RX_DN<0>")
	)
	(segment
		(start 42.959782 -415.721546)
		(end 42.658284 -416.023044)
		(width 0.14224)
		(layer "In2.Cu")
		(net "P2E_MB_BMC_RX_DN<0>")
	)
	(segment
		(start 32.625792 -419.350444)
		(end 32.488632 -419.213284)
		(width 0.14224)
		(layer "In2.Cu")
		(net "P2E_MB_BMC_RX_DN<0>")
	)
	(segment
		(start 69.58076 -417.13277)
		(end 69.744082 -416.738308)
		(width 0.14224)
		(layer "In2.Cu")
		(net "P2E_MB_BMC_RX_DN<0>")
	)
	(segment
		(start 41.558718 -417.316666)
		(end 41.364662 -417.316666)
		(width 0.14224)
		(layer "In2.Cu")
		(net "P2E_MB_BMC_RX_DN<0>")
	)
	(segment
		(start 25.66162 -419.213284)
		(end 24.409908 -420.464996)
		(width 0.14224)
		(layer "In2.Cu")
		(net "P2E_MB_BMC_RX_DN<0>")
	)
	(segment
		(start 71.059294 -412.038546)
		(end 70.49516 -411.474412)
		(width 0.14224)
		(layer "In2.Cu")
		(net "P2E_MB_BMC_RX_DN<0>")
	)
	(segment
		(start 70.086728 -416.269678)
		(end 70.01256 -416.090608)
		(width 0.14224)
		(layer "In2.Cu")
		(net "P2E_MB_BMC_RX_DN<0>")
	)
	(segment
		(start 40.567102 -418.114226)
		(end 39.468044 -419.213284)
		(width 0.14224)
		(layer "In2.Cu")
		(net "P2E_MB_BMC_RX_DN<0>")
	)
	(segment
		(start 24.409908 -420.464996)
		(end 24.409908 -425.09694)
		(width 0.14224)
		(layer "In2.Cu")
		(net "P2E_MB_BMC_RX_DN<0>")
	)
	(segment
		(start 39.55034 -426.341794)
		(end 39.98214 -425.909994)
		(width 0.12954)
		(layer "F.Cu")
		(net "P2E_MB_BMC_RX_BUF_DP<0>")
	)
	(segment
		(start 132.60832 -10.518902)
		(end 132.88391 -10.243312)
		(width 0.12954)
		(layer "F.Cu")
		(net "P2E_MB_BMC_RX_BUF_DP<0>")
	)
	(segment
		(start 132.747004 -12.995148)
		(end 132.60832 -12.856464)
		(width 0.12954)
		(layer "F.Cu")
		(net "P2E_MB_BMC_RX_BUF_DP<0>")
	)
	(segment
		(start 132.60832 -12.856464)
		(end 132.60832 -10.518902)
		(width 0.12954)
		(layer "F.Cu")
		(net "P2E_MB_BMC_RX_BUF_DP<0>")
	)
	(segment
		(start 132.747004 -13.599922)
		(end 132.747004 -12.995148)
		(width 0.12954)
		(layer "F.Cu")
		(net "P2E_MB_BMC_RX_BUF_DP<0>")
	)
	(segment
		(start 39.55034 -426.563536)
		(end 39.55034 -426.341794)
		(width 0.12954)
		(layer "F.Cu")
		(net "P2E_MB_BMC_RX_BUF_DP<0>")
	)
	(segment
		(start 35.620452 -410.189426)
		(end 35.620452 -396.397988)
		(width 0.14224)
		(layer "In15.Cu")
		(net "P2E_MB_BMC_RX_BUF_DP<0>")
	)
	(segment
		(start 84.729066 -47.477934)
		(end 85.86851 -46.33849)
		(width 0.14224)
		(layer "In15.Cu")
		(net "P2E_MB_BMC_RX_BUF_DP<0>")
	)
	(segment
		(start 41.131998 -418.437822)
		(end 41.131744 -418.437822)
		(width 0.14224)
		(layer "In15.Cu")
		(net "P2E_MB_BMC_RX_BUF_DP<0>")
	)
	(segment
		(start 134.366 -19.05)
		(end 134.366 -17.299432)
		(width 0.14224)
		(layer "In15.Cu")
		(net "P2E_MB_BMC_RX_BUF_DP<0>")
	)
	(segment
		(start 11.180064 -104.093264)
		(end 12.464796 -103.561388)
		(width 0.14224)
		(layer "In15.Cu")
		(net "P2E_MB_BMC_RX_BUF_DP<0>")
	)
	(segment
		(start 59.466226 -57.423812)
		(end 60.157106 -57.302146)
		(width 0.14224)
		(layer "In15.Cu")
		(net "P2E_MB_BMC_RX_BUF_DP<0>")
	)
	(segment
		(start 85.86851 -46.33849)
		(end 93.180916 -43.30954)
		(width 0.14224)
		(layer "In15.Cu")
		(net "P2E_MB_BMC_RX_BUF_DP<0>")
	)
	(segment
		(start 103.595932 -42.16781)
		(end 104.274874 -41.96207)
		(width 0.14224)
		(layer "In15.Cu")
		(net "P2E_MB_BMC_RX_BUF_DP<0>")
	)
	(segment
		(start 7.990332 -336.478626)
		(end 5.461 -284.98546)
		(width 0.14224)
		(layer "In15.Cu")
		(net "P2E_MB_BMC_RX_BUF_DP<0>")
	)
	(segment
		(start 7.56666 -116.223034)
		(end 6.708902 -111.358172)
		(width 0.14224)
		(layer "In15.Cu")
		(net "P2E_MB_BMC_RX_BUF_DP<0>")
	)
	(segment
		(start 9.930384 -105.342944)
		(end 11.180064 -104.093264)
		(width 0.14224)
		(layer "In15.Cu")
		(net "P2E_MB_BMC_RX_BUF_DP<0>")
	)
	(segment
		(start 18.67154 -139.735814)
		(end 18.67154 -132.235956)
		(width 0.14224)
		(layer "In15.Cu")
		(net "P2E_MB_BMC_RX_BUF_DP<0>")
	)
	(segment
		(start 40.253666 -417.123372)
		(end 40.253412 -417.123372)
		(width 0.14224)
		(layer "In15.Cu")
		(net "P2E_MB_BMC_RX_BUF_DP<0>")
	)
	(segment
		(start 16.218154 -352.122994)
		(end 16.218154 -344.706448)
		(width 0.14224)
		(layer "In15.Cu")
		(net "P2E_MB_BMC_RX_BUF_DP<0>")
	)
	(segment
		(start 58.7756 -57.545732)
		(end 58.934604 -57.656984)
		(width 0.14224)
		(layer "In15.Cu")
		(net "P2E_MB_BMC_RX_BUF_DP<0>")
	)
	(segment
		(start 60.847732 -57.180226)
		(end 61.645292 -57.039764)
		(width 0.14224)
		(layer "In15.Cu")
		(net "P2E_MB_BMC_RX_BUF_DP<0>")
	)
	(segment
		(start 41.131744 -418.437822)
		(end 40.903906 -418.096954)
		(width 0.14224)
		(layer "In15.Cu")
		(net "P2E_MB_BMC_RX_BUF_DP<0>")
	)
	(segment
		(start 40.90416 -418.096954)
		(end 40.253666 -417.123372)
		(width 0.14224)
		(layer "In15.Cu")
		(net "P2E_MB_BMC_RX_BUF_DP<0>")
	)
	(segment
		(start 31.494984 -385.366514)
		(end 29.134054 -379.6665)
		(width 0.14224)
		(layer "In15.Cu")
		(net "P2E_MB_BMC_RX_BUF_DP<0>")
	)
	(segment
		(start 23.014178 -370.435886)
		(end 20.322032 -370.435886)
		(width 0.14224)
		(layer "In15.Cu")
		(net "P2E_MB_BMC_RX_BUF_DP<0>")
	)
	(segment
		(start 29.134054 -376.555762)
		(end 23.014178 -370.435886)
		(width 0.14224)
		(layer "In15.Cu")
		(net "P2E_MB_BMC_RX_BUF_DP<0>")
	)
	(segment
		(start 39.684198 -425.361354)
		(end 40.805354 -424.240198)
		(width 0.14224)
		(layer "In15.Cu")
		(net "P2E_MB_BMC_RX_BUF_DP<0>")
	)
	(segment
		(start 41.45661 -418.92347)
		(end 41.131998 -418.437822)
		(width 0.14224)
		(layer "In15.Cu")
		(net "P2E_MB_BMC_RX_BUF_DP<0>")
	)
	(segment
		(start 8.799576 -117.983762)
		(end 7.56666 -116.223034)
		(width 0.14224)
		(layer "In15.Cu")
		(net "P2E_MB_BMC_RX_BUF_DP<0>")
	)
	(segment
		(start 42.756582 -424.240198)
		(end 43.448732 -423.548048)
		(width 0.14224)
		(layer "In15.Cu")
		(net "P2E_MB_BMC_RX_BUF_DP<0>")
	)
	(segment
		(start 75.427078 -51.331114)
		(end 77.659484 -50.406554)
		(width 0.14224)
		(layer "In15.Cu")
		(net "P2E_MB_BMC_RX_BUF_DP<0>")
	)
	(segment
		(start 40.38727 -61.877194)
		(end 42.4688 -60.42025)
		(width 0.14224)
		(layer "In15.Cu")
		(net "P2E_MB_BMC_RX_BUF_DP<0>")
	)
	(segment
		(start 77.659484 -50.406554)
		(end 77.659738 -50.406046)
		(width 0.14224)
		(layer "In15.Cu")
		(net "P2E_MB_BMC_RX_BUF_DP<0>")
	)
	(segment
		(start 134.366 -17.299432)
		(end 132.59308 -13.013182)
		(width 0.14224)
		(layer "In15.Cu")
		(net "P2E_MB_BMC_RX_BUF_DP<0>")
	)
	(segment
		(start 93.180916 -43.30954)
		(end 99.831906 -43.30954)
		(width 0.14224)
		(layer "In15.Cu")
		(net "P2E_MB_BMC_RX_BUF_DP<0>")
	)
	(segment
		(start 40.805354 -424.240198)
		(end 42.756582 -424.240198)
		(width 0.14224)
		(layer "In15.Cu")
		(net "P2E_MB_BMC_RX_BUF_DP<0>")
	)
	(segment
		(start 13.462 -166.37)
		(end 16.33093 -163.50107)
		(width 0.14224)
		(layer "In15.Cu")
		(net "P2E_MB_BMC_RX_BUF_DP<0>")
	)
	(segment
		(start 16.33093 -163.50107)
		(end 18.67154 -139.735814)
		(width 0.14224)
		(layer "In15.Cu")
		(net "P2E_MB_BMC_RX_BUF_DP<0>")
	)
	(segment
		(start 35.620452 -396.397988)
		(end 31.494984 -392.27252)
		(width 0.14224)
		(layer "In15.Cu")
		(net "P2E_MB_BMC_RX_BUF_DP<0>")
	)
	(segment
		(start 112.866932 -37.89807)
		(end 114.95278 -36.911534)
		(width 0.14224)
		(layer "In15.Cu")
		(net "P2E_MB_BMC_RX_BUF_DP<0>")
	)
	(segment
		(start 116.625624 -35.23869)
		(end 120.781064 -25.206706)
		(width 0.14224)
		(layer "In15.Cu")
		(net "P2E_MB_BMC_RX_BUF_DP<0>")
	)
	(segment
		(start 7.714996 -108.507276)
		(end 9.930384 -105.342944)
		(width 0.14224)
		(layer "In15.Cu")
		(net "P2E_MB_BMC_RX_BUF_DP<0>")
	)
	(segment
		(start 104.274874 -41.96207)
		(end 112.866678 -37.898578)
		(width 0.14224)
		(layer "In15.Cu")
		(net "P2E_MB_BMC_RX_BUF_DP<0>")
	)
	(segment
		(start 58.934604 -57.656984)
		(end 59.354974 -57.58307)
		(width 0.14224)
		(layer "In15.Cu")
		(net "P2E_MB_BMC_RX_BUF_DP<0>")
	)
	(segment
		(start 7.503668 -109.048296)
		(end 7.748778 -108.698284)
		(width 0.14224)
		(layer "In15.Cu")
		(net "P2E_MB_BMC_RX_BUF_DP<0>")
	)
	(segment
		(start 60.31611 -57.413398)
		(end 60.73648 -57.339484)
		(width 0.14224)
		(layer "In15.Cu")
		(net "P2E_MB_BMC_RX_BUF_DP<0>")
	)
	(segment
		(start 7.31266 -109.081824)
		(end 7.503668 -109.048296)
		(width 0.14224)
		(layer "In15.Cu")
		(net "P2E_MB_BMC_RX_BUF_DP<0>")
	)
	(segment
		(start 40.253412 -417.123372)
		(end 35.620452 -410.189426)
		(width 0.14224)
		(layer "In15.Cu")
		(net "P2E_MB_BMC_RX_BUF_DP<0>")
	)
	(segment
		(start 17.971516 -103.018844)
		(end 18.155412 -102.942644)
		(width 0.14224)
		(layer "In15.Cu")
		(net "P2E_MB_BMC_RX_BUF_DP<0>")
	)
	(segment
		(start 41.45661 -418.923724)
		(end 41.45661 -418.92347)
		(width 0.14224)
		(layer "In15.Cu")
		(net "P2E_MB_BMC_RX_BUF_DP<0>")
	)
	(segment
		(start 121.145554 -22.73681)
		(end 121.457466 -22.424898)
		(width 0.14224)
		(layer "In15.Cu")
		(net "P2E_MB_BMC_RX_BUF_DP<0>")
	)
	(segment
		(start 16.218154 -344.706448)
		(end 7.990332 -336.478626)
		(width 0.14224)
		(layer "In15.Cu")
		(net "P2E_MB_BMC_RX_BUF_DP<0>")
	)
	(segment
		(start 114.95278 -36.911534)
		(end 116.625624 -35.23869)
		(width 0.14224)
		(layer "In15.Cu")
		(net "P2E_MB_BMC_RX_BUF_DP<0>")
	)
	(segment
		(start 5.461 -168.529)
		(end 7.62 -166.37)
		(width 0.14224)
		(layer "In15.Cu")
		(net "P2E_MB_BMC_RX_BUF_DP<0>")
	)
	(segment
		(start 99.831906 -43.30954)
		(end 103.595678 -42.168572)
		(width 0.14224)
		(layer "In15.Cu")
		(net "P2E_MB_BMC_RX_BUF_DP<0>")
	)
	(segment
		(start 12.464796 -103.561388)
		(end 17.971516 -103.018844)
		(width 0.14224)
		(layer "In15.Cu")
		(net "P2E_MB_BMC_RX_BUF_DP<0>")
	)
	(segment
		(start 120.781064 -25.206706)
		(end 120.781064 -23.617428)
		(width 0.14224)
		(layer "In15.Cu")
		(net "P2E_MB_BMC_RX_BUF_DP<0>")
	)
	(segment
		(start 103.595678 -42.168572)
		(end 103.595932 -42.16781)
		(width 0.14224)
		(layer "In15.Cu")
		(net "P2E_MB_BMC_RX_BUF_DP<0>")
	)
	(segment
		(start 39.684198 -425.612052)
		(end 39.684198 -425.361354)
		(width 0.14224)
		(layer "In15.Cu")
		(net "P2E_MB_BMC_RX_BUF_DP<0>")
	)
	(segment
		(start 126.04877 -20.5232)
		(end 132.8928 -20.5232)
		(width 0.14224)
		(layer "In15.Cu")
		(net "P2E_MB_BMC_RX_BUF_DP<0>")
	)
	(segment
		(start 60.157106 -57.302146)
		(end 60.31611 -57.413398)
		(width 0.14224)
		(layer "In15.Cu")
		(net "P2E_MB_BMC_RX_BUF_DP<0>")
	)
	(segment
		(start 7.04215 -109.468412)
		(end 7.31266 -109.081824)
		(width 0.14224)
		(layer "In15.Cu")
		(net "P2E_MB_BMC_RX_BUF_DP<0>")
	)
	(segment
		(start 112.866678 -37.898578)
		(end 112.866932 -37.89807)
		(width 0.14224)
		(layer "In15.Cu")
		(net "P2E_MB_BMC_RX_BUF_DP<0>")
	)
	(segment
		(start 21.693124 -94.805246)
		(end 27.95778 -82.102198)
		(width 0.14224)
		(layer "In15.Cu")
		(net "P2E_MB_BMC_RX_BUF_DP<0>")
	)
	(segment
		(start 132.8928 -20.5232)
		(end 134.366 -19.05)
		(width 0.14224)
		(layer "In15.Cu")
		(net "P2E_MB_BMC_RX_BUF_DP<0>")
	)
	(segment
		(start 75.426824 -51.331876)
		(end 75.427078 -51.331114)
		(width 0.14224)
		(layer "In15.Cu")
		(net "P2E_MB_BMC_RX_BUF_DP<0>")
	)
	(segment
		(start 19.515074 -101.582982)
		(end 21.693124 -94.805246)
		(width 0.14224)
		(layer "In15.Cu")
		(net "P2E_MB_BMC_RX_BUF_DP<0>")
	)
	(segment
		(start 17.292066 -367.40592)
		(end 17.292066 -363.027468)
		(width 0.14224)
		(layer "In15.Cu")
		(net "P2E_MB_BMC_RX_BUF_DP<0>")
	)
	(segment
		(start 59.354974 -57.58307)
		(end 59.466226 -57.423812)
		(width 0.14224)
		(layer "In15.Cu")
		(net "P2E_MB_BMC_RX_BUF_DP<0>")
	)
	(segment
		(start 7.62 -166.37)
		(end 13.462 -166.37)
		(width 0.14224)
		(layer "In15.Cu")
		(net "P2E_MB_BMC_RX_BUF_DP<0>")
	)
	(segment
		(start 18.67154 -132.235956)
		(end 15.576296 -124.760482)
		(width 0.14224)
		(layer "In15.Cu")
		(net "P2E_MB_BMC_RX_BUF_DP<0>")
	)
	(segment
		(start 132.59308 -13.013182)
		(end 132.59308 -10.534142)
		(width 0.14224)
		(layer "In15.Cu")
		(net "P2E_MB_BMC_RX_BUF_DP<0>")
	)
	(segment
		(start 6.708902 -111.358172)
		(end 7.04215 -109.468412)
		(width 0.14224)
		(layer "In15.Cu")
		(net "P2E_MB_BMC_RX_BUF_DP<0>")
	)
	(segment
		(start 120.781064 -23.617428)
		(end 121.145554 -22.73681)
		(width 0.14224)
		(layer "In15.Cu")
		(net "P2E_MB_BMC_RX_BUF_DP<0>")
	)
	(segment
		(start 121.457466 -22.424898)
		(end 126.04877 -20.5232)
		(width 0.14224)
		(layer "In15.Cu")
		(net "P2E_MB_BMC_RX_BUF_DP<0>")
	)
	(segment
		(start 18.155412 -102.942644)
		(end 19.515074 -101.582982)
		(width 0.14224)
		(layer "In15.Cu")
		(net "P2E_MB_BMC_RX_BUF_DP<0>")
	)
	(segment
		(start 39.98214 -425.909994)
		(end 39.684198 -425.612052)
		(width 0.14224)
		(layer "In15.Cu")
		(net "P2E_MB_BMC_RX_BUF_DP<0>")
	)
	(segment
		(start 43.448732 -423.548048)
		(end 43.448732 -421.905176)
		(width 0.14224)
		(layer "In15.Cu")
		(net "P2E_MB_BMC_RX_BUF_DP<0>")
	)
	(segment
		(start 43.448732 -421.905176)
		(end 41.45661 -418.923724)
		(width 0.14224)
		(layer "In15.Cu")
		(net "P2E_MB_BMC_RX_BUF_DP<0>")
	)
	(segment
		(start 17.292066 -363.027468)
		(end 16.218154 -352.122994)
		(width 0.14224)
		(layer "In15.Cu")
		(net "P2E_MB_BMC_RX_BUF_DP<0>")
	)
	(segment
		(start 27.95778 -82.102198)
		(end 30.905196 -77.892148)
		(width 0.14224)
		(layer "In15.Cu")
		(net "P2E_MB_BMC_RX_BUF_DP<0>")
	)
	(segment
		(start 29.134054 -379.6665)
		(end 29.134054 -376.555762)
		(width 0.14224)
		(layer "In15.Cu")
		(net "P2E_MB_BMC_RX_BUF_DP<0>")
	)
	(segment
		(start 7.748778 -108.698284)
		(end 7.714996 -108.507276)
		(width 0.14224)
		(layer "In15.Cu")
		(net "P2E_MB_BMC_RX_BUF_DP<0>")
	)
	(segment
		(start 60.73648 -57.339484)
		(end 60.847732 -57.180226)
		(width 0.14224)
		(layer "In15.Cu")
		(net "P2E_MB_BMC_RX_BUF_DP<0>")
	)
	(segment
		(start 61.645292 -57.039764)
		(end 75.426824 -51.331876)
		(width 0.14224)
		(layer "In15.Cu")
		(net "P2E_MB_BMC_RX_BUF_DP<0>")
	)
	(segment
		(start 31.494984 -392.27252)
		(end 31.494984 -385.366514)
		(width 0.14224)
		(layer "In15.Cu")
		(net "P2E_MB_BMC_RX_BUF_DP<0>")
	)
	(segment
		(start 132.59308 -10.534142)
		(end 132.88391 -10.243312)
		(width 0.14224)
		(layer "In15.Cu")
		(net "P2E_MB_BMC_RX_BUF_DP<0>")
	)
	(segment
		(start 15.576296 -124.760482)
		(end 8.799576 -117.983762)
		(width 0.14224)
		(layer "In15.Cu")
		(net "P2E_MB_BMC_RX_BUF_DP<0>")
	)
	(segment
		(start 42.4688 -60.42025)
		(end 58.7756 -57.545732)
		(width 0.14224)
		(layer "In15.Cu")
		(net "P2E_MB_BMC_RX_BUF_DP<0>")
	)
	(segment
		(start 30.905196 -77.892148)
		(end 40.38727 -61.877194)
		(width 0.14224)
		(layer "In15.Cu")
		(net "P2E_MB_BMC_RX_BUF_DP<0>")
	)
	(segment
		(start 20.322032 -370.435886)
		(end 17.292066 -367.40592)
		(width 0.14224)
		(layer "In15.Cu")
		(net "P2E_MB_BMC_RX_BUF_DP<0>")
	)
	(segment
		(start 77.659738 -50.406046)
		(end 84.729066 -47.477934)
		(width 0.14224)
		(layer "In15.Cu")
		(net "P2E_MB_BMC_RX_BUF_DP<0>")
	)
	(segment
		(start 40.903906 -418.096954)
		(end 40.90416 -418.096954)
		(width 0.14224)
		(layer "In15.Cu")
		(net "P2E_MB_BMC_RX_BUF_DP<0>")
	)
	(segment
		(start 5.461 -284.98546)
		(end 5.461 -168.529)
		(width 0.14224)
		(layer "In15.Cu")
		(net "P2E_MB_BMC_RX_BUF_DP<0>")
	)
	(segment
		(start 132.147056 -13.599922)
		(end 132.147056 -13.062204)
		(width 0.12954)
		(layer "F.Cu")
		(net "P2E_MB_BMC_RX_BUF_DN<0>")
	)
	(segment
		(start 39.55034 -425.256706)
		(end 39.55034 -425.478194)
		(width 0.12954)
		(layer "F.Cu")
		(net "P2E_MB_BMC_RX_BUF_DN<0>")
	)
	(segment
		(start 39.55034 -425.478194)
		(end 39.11854 -425.909994)
		(width 0.12954)
		(layer "F.Cu")
		(net "P2E_MB_BMC_RX_BUF_DN<0>")
	)
	(segment
		(start 132.28574 -10.508742)
		(end 132.02031 -10.243312)
		(width 0.12954)
		(layer "F.Cu")
		(net "P2E_MB_BMC_RX_BUF_DN<0>")
	)
	(segment
		(start 132.147056 -13.062204)
		(end 132.28574 -12.92352)
		(width 0.12954)
		(layer "F.Cu")
		(net "P2E_MB_BMC_RX_BUF_DN<0>")
	)
	(segment
		(start 132.28574 -12.92352)
		(end 132.28574 -10.508742)
		(width 0.12954)
		(layer "F.Cu")
		(net "P2E_MB_BMC_RX_BUF_DN<0>")
	)
	(segment
		(start 75.31862 -51.070764)
		(end 75.319382 -51.07051)
		(width 0.14224)
		(layer "In15.Cu")
		(net "P2E_MB_BMC_RX_BUF_DN<0>")
	)
	(segment
		(start 31.213044 -385.422648)
		(end 28.852114 -379.722634)
		(width 0.14224)
		(layer "In15.Cu")
		(net "P2E_MB_BMC_RX_BUF_DN<0>")
	)
	(segment
		(start 15.936214 -344.823288)
		(end 7.71398 -336.601054)
		(width 0.14224)
		(layer "In15.Cu")
		(net "P2E_MB_BMC_RX_BUF_DN<0>")
	)
	(segment
		(start 43.166792 -421.990774)
		(end 41.286938 -419.177724)
		(width 0.14224)
		(layer "In15.Cu")
		(net "P2E_MB_BMC_RX_BUF_DN<0>")
	)
	(segment
		(start 41.096692 -419.139878)
		(end 40.859456 -418.784786)
		(width 0.14224)
		(layer "In15.Cu")
		(net "P2E_MB_BMC_RX_BUF_DN<0>")
	)
	(segment
		(start 17.010126 -363.041438)
		(end 15.936214 -352.136964)
		(width 0.14224)
		(layer "In15.Cu")
		(net "P2E_MB_BMC_RX_BUF_DN<0>")
	)
	(segment
		(start 40.859456 -418.784786)
		(end 40.897302 -418.59454)
		(width 0.14224)
		(layer "In15.Cu")
		(net "P2E_MB_BMC_RX_BUF_DN<0>")
	)
	(segment
		(start 77.454252 -50.186336)
		(end 77.454506 -50.185828)
		(width 0.14224)
		(layer "In15.Cu")
		(net "P2E_MB_BMC_RX_BUF_DN<0>")
	)
	(segment
		(start 133.33095 -15.535656)
		(end 133.30936 -15.483332)
		(width 0.14224)
		(layer "In15.Cu")
		(net "P2E_MB_BMC_RX_BUF_DN<0>")
	)
	(segment
		(start 40.670226 -418.25418)
		(end 40.669718 -418.253672)
		(width 0.14224)
		(layer "In15.Cu")
		(net "P2E_MB_BMC_RX_BUF_DN<0>")
	)
	(segment
		(start 18.3896 -139.721844)
		(end 18.3896 -132.29209)
		(width 0.14224)
		(layer "In15.Cu")
		(net "P2E_MB_BMC_RX_BUF_DN<0>")
	)
	(segment
		(start 99.789996 -43.0276)
		(end 103.513636 -41.898824)
		(width 0.14224)
		(layer "In15.Cu")
		(net "P2E_MB_BMC_RX_BUF_DN<0>")
	)
	(segment
		(start 12.395454 -103.284782)
		(end 17.902174 -102.742238)
		(width 0.14224)
		(layer "In15.Cu")
		(net "P2E_MB_BMC_RX_BUF_DN<0>")
	)
	(segment
		(start 77.454506 -50.185828)
		(end 77.551534 -50.145696)
		(width 0.14224)
		(layer "In15.Cu")
		(net "P2E_MB_BMC_RX_BUF_DN<0>")
	)
	(segment
		(start 132.31114 -10.534142)
		(end 132.02031 -10.243312)
		(width 0.14224)
		(layer "In15.Cu")
		(net "P2E_MB_BMC_RX_BUF_DN<0>")
	)
	(segment
		(start 75.259438 -51.09591)
		(end 75.259438 -51.095402)
		(width 0.14224)
		(layer "In15.Cu")
		(net "P2E_MB_BMC_RX_BUF_DN<0>")
	)
	(segment
		(start 84.5693 -47.23892)
		(end 85.708744 -46.099476)
		(width 0.14224)
		(layer "In15.Cu")
		(net "P2E_MB_BMC_RX_BUF_DN<0>")
	)
	(segment
		(start 7.299706 -116.333524)
		(end 6.42239 -111.358172)
		(width 0.14224)
		(layer "In15.Cu")
		(net "P2E_MB_BMC_RX_BUF_DN<0>")
	)
	(segment
		(start 40.669718 -418.253672)
		(end 40.40886 -417.86302)
		(width 0.14224)
		(layer "In15.Cu")
		(net "P2E_MB_BMC_RX_BUF_DN<0>")
	)
	(segment
		(start 39.402258 -425.244514)
		(end 40.688514 -423.958258)
		(width 0.14224)
		(layer "In15.Cu")
		(net "P2E_MB_BMC_RX_BUF_DN<0>")
	)
	(segment
		(start 134.08406 -18.93316)
		(end 134.08406 -17.355566)
		(width 0.14224)
		(layer "In15.Cu")
		(net "P2E_MB_BMC_RX_BUF_DN<0>")
	)
	(segment
		(start 20.205192 -370.717826)
		(end 17.010126 -367.52276)
		(width 0.14224)
		(layer "In15.Cu")
		(net "P2E_MB_BMC_RX_BUF_DN<0>")
	)
	(segment
		(start 40.01897 -417.28009)
		(end 35.338512 -410.275024)
		(width 0.14224)
		(layer "In15.Cu")
		(net "P2E_MB_BMC_RX_BUF_DN<0>")
	)
	(segment
		(start 15.936214 -352.136964)
		(end 15.936214 -344.823288)
		(width 0.14224)
		(layer "In15.Cu")
		(net "P2E_MB_BMC_RX_BUF_DN<0>")
	)
	(segment
		(start 18.3896 -132.29209)
		(end 15.337282 -124.920248)
		(width 0.14224)
		(layer "In15.Cu")
		(net "P2E_MB_BMC_RX_BUF_DN<0>")
	)
	(segment
		(start 28.852114 -379.722634)
		(end 28.852114 -376.672602)
		(width 0.14224)
		(layer "In15.Cu")
		(net "P2E_MB_BMC_RX_BUF_DN<0>")
	)
	(segment
		(start 112.658144 -37.68471)
		(end 114.787934 -36.6776)
		(width 0.14224)
		(layer "In15.Cu")
		(net "P2E_MB_BMC_RX_BUF_DN<0>")
	)
	(segment
		(start 133.30936 -15.483078)
		(end 133.146292 -15.08887)
		(width 0.14224)
		(layer "In15.Cu")
		(net "P2E_MB_BMC_RX_BUF_DN<0>")
	)
	(segment
		(start 24.030432 -372.044722)
		(end 23.728426 -371.742716)
		(width 0.14224)
		(layer "In15.Cu")
		(net "P2E_MB_BMC_RX_BUF_DN<0>")
	)
	(segment
		(start 93.124782 -43.0276)
		(end 99.789996 -43.0276)
		(width 0.14224)
		(layer "In15.Cu")
		(net "P2E_MB_BMC_RX_BUF_DN<0>")
	)
	(segment
		(start 40.175688 -61.681106)
		(end 42.35831 -60.153296)
		(width 0.14224)
		(layer "In15.Cu")
		(net "P2E_MB_BMC_RX_BUF_DN<0>")
	)
	(segment
		(start 132.31114 -13.069316)
		(end 132.31114 -10.534142)
		(width 0.14224)
		(layer "In15.Cu")
		(net "P2E_MB_BMC_RX_BUF_DN<0>")
	)
	(segment
		(start 104.17302 -41.698164)
		(end 112.65789 -37.685218)
		(width 0.14224)
		(layer "In15.Cu")
		(net "P2E_MB_BMC_RX_BUF_DN<0>")
	)
	(segment
		(start 116.38661 -35.078924)
		(end 120.499124 -25.150572)
		(width 0.14224)
		(layer "In15.Cu")
		(net "P2E_MB_BMC_RX_BUF_DN<0>")
	)
	(segment
		(start 13.34516 -166.08806)
		(end 16.060166 -163.373054)
		(width 0.14224)
		(layer "In15.Cu")
		(net "P2E_MB_BMC_RX_BUF_DN<0>")
	)
	(segment
		(start 23.728426 -371.548914)
		(end 22.897338 -370.717826)
		(width 0.14224)
		(layer "In15.Cu")
		(net "P2E_MB_BMC_RX_BUF_DN<0>")
	)
	(segment
		(start 120.499124 -25.150572)
		(end 120.499124 -23.561294)
		(width 0.14224)
		(layer "In15.Cu")
		(net "P2E_MB_BMC_RX_BUF_DN<0>")
	)
	(segment
		(start 103.513636 -41.898062)
		(end 104.17302 -41.698164)
		(width 0.14224)
		(layer "In15.Cu")
		(net "P2E_MB_BMC_RX_BUF_DN<0>")
	)
	(segment
		(start 134.08406 -17.355566)
		(end 133.33349 -15.541244)
		(width 0.14224)
		(layer "In15.Cu")
		(net "P2E_MB_BMC_RX_BUF_DN<0>")
	)
	(segment
		(start 132.8039 -14.619986)
		(end 132.878322 -14.440916)
		(width 0.14224)
		(layer "In15.Cu")
		(net "P2E_MB_BMC_RX_BUF_DN<0>")
	)
	(segment
		(start 133.33095 -15.540228)
		(end 133.33095 -15.535656)
		(width 0.14224)
		(layer "In15.Cu")
		(net "P2E_MB_BMC_RX_BUF_DN<0>")
	)
	(segment
		(start 17.010126 -367.52276)
		(end 17.010126 -363.041438)
		(width 0.14224)
		(layer "In15.Cu")
		(net "P2E_MB_BMC_RX_BUF_DN<0>")
	)
	(segment
		(start 133.146292 -15.08887)
		(end 132.966968 -15.014448)
		(width 0.14224)
		(layer "In15.Cu")
		(net "P2E_MB_BMC_RX_BUF_DN<0>")
	)
	(segment
		(start 132.77596 -20.24126)
		(end 134.08406 -18.93316)
		(width 0.14224)
		(layer "In15.Cu")
		(net "P2E_MB_BMC_RX_BUF_DN<0>")
	)
	(segment
		(start 17.902174 -102.742238)
		(end 17.995646 -102.70363)
		(width 0.14224)
		(layer "In15.Cu")
		(net "P2E_MB_BMC_RX_BUF_DN<0>")
	)
	(segment
		(start 39.981124 -417.470336)
		(end 40.01897 -417.28009)
		(width 0.14224)
		(layer "In15.Cu")
		(net "P2E_MB_BMC_RX_BUF_DN<0>")
	)
	(segment
		(start 120.499124 -23.561294)
		(end 120.90654 -22.577044)
		(width 0.14224)
		(layer "In15.Cu")
		(net "P2E_MB_BMC_RX_BUF_DN<0>")
	)
	(segment
		(start 75.259438 -51.095402)
		(end 75.31862 -51.070764)
		(width 0.14224)
		(layer "In15.Cu")
		(net "P2E_MB_BMC_RX_BUF_DN<0>")
	)
	(segment
		(start 40.218614 -417.825428)
		(end 39.981124 -417.470336)
		(width 0.14224)
		(layer "In15.Cu")
		(net "P2E_MB_BMC_RX_BUF_DN<0>")
	)
	(segment
		(start 120.90654 -22.577044)
		(end 121.2977 -22.185884)
		(width 0.14224)
		(layer "In15.Cu")
		(net "P2E_MB_BMC_RX_BUF_DN<0>")
	)
	(segment
		(start 43.166792 -423.431208)
		(end 43.166792 -421.990774)
		(width 0.14224)
		(layer "In15.Cu")
		(net "P2E_MB_BMC_RX_BUF_DN<0>")
	)
	(segment
		(start 16.060166 -163.373054)
		(end 18.3896 -139.721844)
		(width 0.14224)
		(layer "In15.Cu")
		(net "P2E_MB_BMC_RX_BUF_DN<0>")
	)
	(segment
		(start 103.51389 -41.89857)
		(end 103.513636 -41.898062)
		(width 0.14224)
		(layer "In15.Cu")
		(net "P2E_MB_BMC_RX_BUF_DN<0>")
	)
	(segment
		(start 114.787934 -36.6776)
		(end 116.38661 -35.078924)
		(width 0.14224)
		(layer "In15.Cu")
		(net "P2E_MB_BMC_RX_BUF_DN<0>")
	)
	(segment
		(start 75.319382 -51.07051)
		(end 77.454252 -50.186336)
		(width 0.14224)
		(layer "In15.Cu")
		(net "P2E_MB_BMC_RX_BUF_DN<0>")
	)
	(segment
		(start 7.71398 -336.601054)
		(end 5.17906 -284.992572)
		(width 0.14224)
		(layer "In15.Cu")
		(net "P2E_MB_BMC_RX_BUF_DN<0>")
	)
	(segment
		(start 133.30936 -15.483332)
		(end 133.30936 -15.483078)
		(width 0.14224)
		(layer "In15.Cu")
		(net "P2E_MB_BMC_RX_BUF_DN<0>")
	)
	(segment
		(start 39.11854 -425.909994)
		(end 39.402258 -425.626276)
		(width 0.14224)
		(layer "In15.Cu")
		(net "P2E_MB_BMC_RX_BUF_DN<0>")
	)
	(segment
		(start 22.897338 -370.717826)
		(end 20.205192 -370.717826)
		(width 0.14224)
		(layer "In15.Cu")
		(net "P2E_MB_BMC_RX_BUF_DN<0>")
	)
	(segment
		(start 121.2977 -22.185884)
		(end 125.992636 -20.24126)
		(width 0.14224)
		(layer "In15.Cu")
		(net "P2E_MB_BMC_RX_BUF_DN<0>")
	)
	(segment
		(start 103.513636 -41.898824)
		(end 103.51389 -41.89857)
		(width 0.14224)
		(layer "In15.Cu")
		(net "P2E_MB_BMC_RX_BUF_DN<0>")
	)
	(segment
		(start 11.020298 -103.85425)
		(end 12.395454 -103.284782)
		(width 0.14224)
		(layer "In15.Cu")
		(net "P2E_MB_BMC_RX_BUF_DN<0>")
	)
	(segment
		(start 61.56579 -56.767222)
		(end 75.259438 -51.09591)
		(width 0.14224)
		(layer "In15.Cu")
		(net "P2E_MB_BMC_RX_BUF_DN<0>")
	)
	(segment
		(start 8.58266 -118.165626)
		(end 7.299706 -116.333524)
		(width 0.14224)
		(layer "In15.Cu")
		(net "P2E_MB_BMC_RX_BUF_DN<0>")
	)
	(segment
		(start 132.966968 -15.014448)
		(end 132.8039 -14.619986)
		(width 0.14224)
		(layer "In15.Cu")
		(net "P2E_MB_BMC_RX_BUF_DN<0>")
	)
	(segment
		(start 132.878322 -14.440916)
		(end 132.31114 -13.069316)
		(width 0.14224)
		(layer "In15.Cu")
		(net "P2E_MB_BMC_RX_BUF_DN<0>")
	)
	(segment
		(start 6.42239 -111.358172)
		(end 6.775196 -109.357922)
		(width 0.14224)
		(layer "In15.Cu")
		(net "P2E_MB_BMC_RX_BUF_DN<0>")
	)
	(segment
		(start 30.66796 -77.73924)
		(end 40.175688 -61.681106)
		(width 0.14224)
		(layer "In15.Cu")
		(net "P2E_MB_BMC_RX_BUF_DN<0>")
	)
	(segment
		(start 35.338512 -396.514828)
		(end 31.213044 -392.38936)
		(width 0.14224)
		(layer "In15.Cu")
		(net "P2E_MB_BMC_RX_BUF_DN<0>")
	)
	(segment
		(start 40.688514 -423.958258)
		(end 42.639742 -423.958258)
		(width 0.14224)
		(layer "In15.Cu")
		(net "P2E_MB_BMC_RX_BUF_DN<0>")
	)
	(segment
		(start 39.402258 -425.626276)
		(end 39.402258 -425.244514)
		(width 0.14224)
		(layer "In15.Cu")
		(net "P2E_MB_BMC_RX_BUF_DN<0>")
	)
	(segment
		(start 40.897302 -418.59454)
		(end 40.670226 -418.25418)
		(width 0.14224)
		(layer "In15.Cu")
		(net "P2E_MB_BMC_RX_BUF_DN<0>")
	)
	(segment
		(start 17.995646 -102.70363)
		(end 19.267424 -101.431852)
		(width 0.14224)
		(layer "In15.Cu")
		(net "P2E_MB_BMC_RX_BUF_DN<0>")
	)
	(segment
		(start 27.714194 -81.957926)
		(end 30.66796 -77.73924)
		(width 0.14224)
		(layer "In15.Cu")
		(net "P2E_MB_BMC_RX_BUF_DN<0>")
	)
	(segment
		(start 77.551534 -50.145696)
		(end 77.552042 -50.145442)
		(width 0.14224)
		(layer "In15.Cu")
		(net "P2E_MB_BMC_RX_BUF_DN<0>")
	)
	(segment
		(start 85.708744 -46.099476)
		(end 93.124782 -43.0276)
		(width 0.14224)
		(layer "In15.Cu")
		(net "P2E_MB_BMC_RX_BUF_DN<0>")
	)
	(segment
		(start 5.17906 -168.41216)
		(end 7.50316 -166.08806)
		(width 0.14224)
		(layer "In15.Cu")
		(net "P2E_MB_BMC_RX_BUF_DN<0>")
	)
	(segment
		(start 28.852114 -376.672602)
		(end 24.224234 -372.044722)
		(width 0.14224)
		(layer "In15.Cu")
		(net "P2E_MB_BMC_RX_BUF_DN<0>")
	)
	(segment
		(start 42.35831 -60.153296)
		(end 61.56579 -56.767222)
		(width 0.14224)
		(layer "In15.Cu")
		(net "P2E_MB_BMC_RX_BUF_DN<0>")
	)
	(segment
		(start 15.337282 -124.920248)
		(end 8.58266 -118.165626)
		(width 0.14224)
		(layer "In15.Cu")
		(net "P2E_MB_BMC_RX_BUF_DN<0>")
	)
	(segment
		(start 31.213044 -392.38936)
		(end 31.213044 -385.422648)
		(width 0.14224)
		(layer "In15.Cu")
		(net "P2E_MB_BMC_RX_BUF_DN<0>")
	)
	(segment
		(start 6.775196 -109.357922)
		(end 9.713468 -105.16108)
		(width 0.14224)
		(layer "In15.Cu")
		(net "P2E_MB_BMC_RX_BUF_DN<0>")
	)
	(segment
		(start 19.267424 -101.431852)
		(end 21.430996 -94.699074)
		(width 0.14224)
		(layer "In15.Cu")
		(net "P2E_MB_BMC_RX_BUF_DN<0>")
	)
	(segment
		(start 112.65789 -37.685218)
		(end 112.658144 -37.68471)
		(width 0.14224)
		(layer "In15.Cu")
		(net "P2E_MB_BMC_RX_BUF_DN<0>")
	)
	(segment
		(start 40.40886 -417.86302)
		(end 40.218614 -417.825428)
		(width 0.14224)
		(layer "In15.Cu")
		(net "P2E_MB_BMC_RX_BUF_DN<0>")
	)
	(segment
		(start 35.338512 -410.275024)
		(end 35.338512 -396.514828)
		(width 0.14224)
		(layer "In15.Cu")
		(net "P2E_MB_BMC_RX_BUF_DN<0>")
	)
	(segment
		(start 42.639742 -423.958258)
		(end 43.166792 -423.431208)
		(width 0.14224)
		(layer "In15.Cu")
		(net "P2E_MB_BMC_RX_BUF_DN<0>")
	)
	(segment
		(start 125.992636 -20.24126)
		(end 132.77596 -20.24126)
		(width 0.14224)
		(layer "In15.Cu")
		(net "P2E_MB_BMC_RX_BUF_DN<0>")
	)
	(segment
		(start 24.224234 -372.044722)
		(end 24.030432 -372.044722)
		(width 0.14224)
		(layer "In15.Cu")
		(net "P2E_MB_BMC_RX_BUF_DN<0>")
	)
	(segment
		(start 77.552042 -50.145442)
		(end 84.5693 -47.23892)
		(width 0.14224)
		(layer "In15.Cu")
		(net "P2E_MB_BMC_RX_BUF_DN<0>")
	)
	(segment
		(start 21.430996 -94.699074)
		(end 27.714194 -81.957926)
		(width 0.14224)
		(layer "In15.Cu")
		(net "P2E_MB_BMC_RX_BUF_DN<0>")
	)
	(segment
		(start 5.17906 -284.992572)
		(end 5.17906 -168.41216)
		(width 0.14224)
		(layer "In15.Cu")
		(net "P2E_MB_BMC_RX_BUF_DN<0>")
	)
	(segment
		(start 41.286938 -419.177724)
		(end 41.096692 -419.139878)
		(width 0.14224)
		(layer "In15.Cu")
		(net "P2E_MB_BMC_RX_BUF_DN<0>")
	)
	(segment
		(start 7.50316 -166.08806)
		(end 13.34516 -166.08806)
		(width 0.14224)
		(layer "In15.Cu")
		(net "P2E_MB_BMC_RX_BUF_DN<0>")
	)
	(segment
		(start 23.728426 -371.742716)
		(end 23.728426 -371.548914)
		(width 0.14224)
		(layer "In15.Cu")
		(net "P2E_MB_BMC_RX_BUF_DN<0>")
	)
	(segment
		(start 9.713468 -105.16108)
		(end 11.020298 -103.85425)
		(width 0.14224)
		(layer "In15.Cu")
		(net "P2E_MB_BMC_RX_BUF_DN<0>")
	)
	(segment
		(start 133.33349 -15.541244)
		(end 133.33095 -15.540228)
		(width 0.14224)
		(layer "In15.Cu")
		(net "P2E_MB_BMC_RX_BUF_DN<0>")
	)
	(segment
		(start 307.281326 -26.272236)
		(end 306.031646 -26.272236)
		(width 0.10668)
		(layer "F.Cu")
		(net "P1V5_BAT_OUT")
	)
	(segment
		(start 296.396664 -19.466306)
		(end 296.215562 -19.647408)
		(width 0.10668)
		(layer "F.Cu")
		(net "P1V5_BAT_OUT")
	)
	(segment
		(start 299.149262 -27.3558)
		(end 295.511474 -23.718012)
		(width 0.10668)
		(layer "F.Cu")
		(net "P1V5_BAT_OUT")
	)
	(segment
		(start 297.650916 -19.306032)
		(end 297.490642 -19.466306)
		(width 0.10668)
		(layer "F.Cu")
		(net "P1V5_BAT_OUT")
	)
	(segment
		(start 320.635884 -27.47391)
		(end 308.483 -27.47391)
		(width 0.10668)
		(layer "F.Cu")
		(net "P1V5_BAT_OUT")
	)
	(segment
		(start 296.215562 -20.331684)
		(end 295.511474 -21.035772)
		(width 0.10668)
		(layer "F.Cu")
		(net "P1V5_BAT_OUT")
	)
	(segment
		(start 326.330056 -24.81453)
		(end 325.922386 -25.2222)
		(width 0.10668)
		(layer "F.Cu")
		(net "P1V5_BAT_OUT")
	)
	(segment
		(start 305.484784 -26.272236)
		(end 304.40122 -27.3558)
		(width 0.10668)
		(layer "F.Cu")
		(net "P1V5_BAT_OUT")
	)
	(segment
		(start 304.40122 -27.3558)
		(end 299.149262 -27.3558)
		(width 0.10668)
		(layer "F.Cu")
		(net "P1V5_BAT_OUT")
	)
	(segment
		(start 325.922386 -25.2222)
		(end 322.887594 -25.2222)
		(width 0.10668)
		(layer "F.Cu")
		(net "P1V5_BAT_OUT")
	)
	(segment
		(start 326.330056 -24.226266)
		(end 326.330056 -24.81453)
		(width 0.10668)
		(layer "F.Cu")
		(net "P1V5_BAT_OUT")
	)
	(segment
		(start 296.215562 -19.647408)
		(end 296.215562 -20.331684)
		(width 0.10668)
		(layer "F.Cu")
		(net "P1V5_BAT_OUT")
	)
	(segment
		(start 322.887594 -25.2222)
		(end 320.635884 -27.47391)
		(width 0.10668)
		(layer "F.Cu")
		(net "P1V5_BAT_OUT")
	)
	(segment
		(start 308.483 -27.47391)
		(end 307.281326 -26.272236)
		(width 0.10668)
		(layer "F.Cu")
		(net "P1V5_BAT_OUT")
	)
	(segment
		(start 297.490642 -19.466306)
		(end 296.396664 -19.466306)
		(width 0.10668)
		(layer "F.Cu")
		(net "P1V5_BAT_OUT")
	)
	(segment
		(start 295.511474 -23.718012)
		(end 295.511474 -21.035772)
		(width 0.10668)
		(layer "F.Cu")
		(net "P1V5_BAT_OUT")
	)
	(segment
		(start 306.031646 -26.272236)
		(end 305.484784 -26.272236)
		(width 0.10668)
		(layer "F.Cu")
		(net "P1V5_BAT_OUT")
	)
	(via
		(at 295.511474 -21.035772)
		(size 0.762)
		(drill 0.381)
		(layers "F.Cu" "B.Cu")
		(net "P1V5_BAT_OUT")
	)
	(segment
		(start 385.769358 -309.290212)
		(end 385.769358 -302.902112)
		(width 0.4572)
		(layer "F.Cu")
		(net "P1V5_BAT")
	)
	(segment
		(start 303.653952 -23.14575)
		(end 303.653952 -23.7617)
		(width 0.4064)
		(layer "F.Cu")
		(net "P1V5_BAT")
	)
	(segment
		(start 157.25521 -328.618342)
		(end 149.42312 -328.618342)
		(width 0.4572)
		(layer "F.Cu")
		(net "P1V5_BAT")
	)
	(segment
		(start 373.64797 -266.530074)
		(end 374.114822 -266.796012)
		(width 0.350012)
		(layer "F.Cu")
		(net "P1V5_BAT")
	)
	(segment
		(start 162.885374 -324.002908)
		(end 161.43097 -325.457312)
		(width 0.4572)
		(layer "F.Cu")
		(net "P1V5_BAT")
	)
	(segment
		(start 148.051774 -324.005448)
		(end 150.049484 -322.007738)
		(width 0.4572)
		(layer "F.Cu")
		(net "P1V5_BAT")
	)
	(segment
		(start 150.049484 -322.007738)
		(end 150.049484 -321.733672)
		(width 0.4064)
		(layer "F.Cu")
		(net "P1V5_BAT")
	)
	(segment
		(start 150.049484 -321.733672)
		(end 151.194262 -321.733672)
		(width 0.4064)
		(layer "F.Cu")
		(net "P1V5_BAT")
	)
	(segment
		(start 161.43097 -325.457312)
		(end 160.41624 -325.457312)
		(width 0.4572)
		(layer "F.Cu")
		(net "P1V5_BAT")
	)
	(segment
		(start 160.41624 -325.457312)
		(end 157.25521 -328.618342)
		(width 0.4572)
		(layer "F.Cu")
		(net "P1V5_BAT")
	)
	(segment
		(start 367.088674 -353.212654)
		(end 367.088674 -327.841102)
		(width 0.508)
		(layer "F.Cu")
		(net "P1V5_BAT")
	)
	(segment
		(start 339.813138 -306.161694)
		(end 339.516466 -305.445414)
		(width 0.508)
		(layer "F.Cu")
		(net "P1V5_BAT")
	)
	(segment
		(start 149.42312 -328.618342)
		(end 148.051774 -327.246996)
		(width 0.4572)
		(layer "F.Cu")
		(net "P1V5_BAT")
	)
	(segment
		(start 339.516466 -303.193704)
		(end 340.996778 -301.713392)
		(width 0.508)
		(layer "F.Cu")
		(net "P1V5_BAT")
	)
	(segment
		(start 148.051774 -327.246996)
		(end 148.051774 -324.005448)
		(width 0.4572)
		(layer "F.Cu")
		(net "P1V5_BAT")
	)
	(segment
		(start 386.50672 -310.027574)
		(end 385.769358 -309.290212)
		(width 0.4572)
		(layer "F.Cu")
		(net "P1V5_BAT")
	)
	(segment
		(start 408.597608 -331.047852)
		(end 409.752038 -329.893422)
		(width 0.4572)
		(layer "F.Cu")
		(net "P1V5_BAT")
	)
	(segment
		(start 208.80959 -316.56401)
		(end 207.945736 -317.427864)
		(width 0.4572)
		(layer "F.Cu")
		(net "P1V5_BAT")
	)
	(segment
		(start 367.088674 -327.841102)
		(end 364.472728 -325.225156)
		(width 0.508)
		(layer "F.Cu")
		(net "P1V5_BAT")
	)
	(segment
		(start 409.752038 -322.917058)
		(end 405.13762 -318.30264)
		(width 0.4572)
		(layer "F.Cu")
		(net "P1V5_BAT")
	)
	(segment
		(start 400.590766 -310.875172)
		(end 392.938 -310.875172)
		(width 0.4572)
		(layer "F.Cu")
		(net "P1V5_BAT")
	)
	(segment
		(start 207.945736 -317.427864)
		(end 207.945736 -320.656204)
		(width 0.4572)
		(layer "F.Cu")
		(net "P1V5_BAT")
	)
	(segment
		(start 405.13762 -315.422026)
		(end 400.590766 -310.875172)
		(width 0.4572)
		(layer "F.Cu")
		(net "P1V5_BAT")
	)
	(segment
		(start 207.756252 -320.845688)
		(end 165.027864 -320.845688)
		(width 0.4572)
		(layer "F.Cu")
		(net "P1V5_BAT")
	)
	(segment
		(start 343.929208 -312.595514)
		(end 339.813138 -308.479444)
		(width 0.508)
		(layer "F.Cu")
		(net "P1V5_BAT")
	)
	(segment
		(start 356.667308 -312.595514)
		(end 343.929208 -312.595514)
		(width 0.508)
		(layer "F.Cu")
		(net "P1V5_BAT")
	)
	(segment
		(start 209.988912 -316.56401)
		(end 208.80959 -316.56401)
		(width 0.4572)
		(layer "F.Cu")
		(net "P1V5_BAT")
	)
	(segment
		(start 339.516466 -305.445414)
		(end 339.516466 -303.193704)
		(width 0.508)
		(layer "F.Cu")
		(net "P1V5_BAT")
	)
	(segment
		(start 165.027864 -320.845688)
		(end 162.885374 -322.988178)
		(width 0.4572)
		(layer "F.Cu")
		(net "P1V5_BAT")
	)
	(segment
		(start 392.938 -310.875172)
		(end 392.090402 -310.027574)
		(width 0.4572)
		(layer "F.Cu")
		(net "P1V5_BAT")
	)
	(segment
		(start 385.769358 -302.902112)
		(end 386.389118 -302.282352)
		(width 0.4572)
		(layer "F.Cu")
		(net "P1V5_BAT")
	)
	(segment
		(start 207.945736 -320.656204)
		(end 207.756252 -320.845688)
		(width 0.4572)
		(layer "F.Cu")
		(net "P1V5_BAT")
	)
	(segment
		(start 364.472728 -320.400934)
		(end 356.667308 -312.595514)
		(width 0.508)
		(layer "F.Cu")
		(net "P1V5_BAT")
	)
	(segment
		(start 339.813138 -308.479444)
		(end 339.813138 -306.161694)
		(width 0.508)
		(layer "F.Cu")
		(net "P1V5_BAT")
	)
	(segment
		(start 392.090402 -310.027574)
		(end 386.50672 -310.027574)
		(width 0.4572)
		(layer "F.Cu")
		(net "P1V5_BAT")
	)
	(segment
		(start 409.752038 -329.893422)
		(end 409.752038 -322.917058)
		(width 0.4572)
		(layer "F.Cu")
		(net "P1V5_BAT")
	)
	(segment
		(start 405.13762 -318.30264)
		(end 405.13762 -315.422026)
		(width 0.4572)
		(layer "F.Cu")
		(net "P1V5_BAT")
	)
	(segment
		(start 162.885374 -322.988178)
		(end 162.885374 -324.002908)
		(width 0.4572)
		(layer "F.Cu")
		(net "P1V5_BAT")
	)
	(segment
		(start 357.075994 -363.225334)
		(end 367.088674 -353.212654)
		(width 0.508)
		(layer "F.Cu")
		(net "P1V5_BAT")
	)
	(segment
		(start 364.472728 -325.225156)
		(end 364.472728 -320.400934)
		(width 0.508)
		(layer "F.Cu")
		(net "P1V5_BAT")
	)
	(via
		(at 303.653952 -23.7617)
		(size 0.508)
		(drill 0.254)
		(layers "F.Cu" "B.Cu")
		(net "P1V5_BAT")
	)
	(via
		(at 333.00543 -26.603706)
		(size 0.508)
		(drill 0.254)
		(layers "F.Cu" "B.Cu")
		(net "P1V5_BAT")
	)
	(via
		(at 408.597608 -331.047852)
		(size 0.508)
		(drill 0.254)
		(layers "F.Cu" "B.Cu")
		(net "P1V5_BAT")
	)
	(via
		(at 406.534874 -356.79634)
		(size 0.508)
		(drill 0.254)
		(layers "F.Cu" "B.Cu")
		(net "P1V5_BAT")
	)
	(via
		(at 332.195678 -26.251662)
		(size 0.508)
		(drill 0.254)
		(layers "F.Cu" "B.Cu")
		(net "P1V5_BAT")
	)
	(via
		(at 413.297624 -60.528962)
		(size 0.508)
		(drill 0.254)
		(layers "F.Cu" "B.Cu")
		(net "P1V5_BAT")
	)
	(via
		(at 386.389118 -302.282352)
		(size 0.508)
		(drill 0.254)
		(layers "F.Cu" "B.Cu")
		(net "P1V5_BAT")
	)
	(via
		(at 434.172106 -161.861754)
		(size 0.508)
		(drill 0.254)
		(layers "F.Cu" "B.Cu")
		(net "P1V5_BAT")
	)
	(via
		(at 374.114822 -266.796012)
		(size 0.4064)
		(drill 0.2032)
		(layers "F.Cu" "B.Cu")
		(net "P1V5_BAT")
	)
	(via
		(at 151.194262 -321.733672)
		(size 0.762)
		(drill 0.254)
		(layers "F.Cu" "B.Cu")
		(net "P1V5_BAT")
	)
	(via
		(at 333.743554 -26.603706)
		(size 0.508)
		(drill 0.254)
		(layers "F.Cu" "B.Cu")
		(net "P1V5_BAT")
	)
	(via
		(at 417.871402 -324.150736)
		(size 0.508)
		(drill 0.254)
		(layers "F.Cu" "B.Cu")
		(net "P1V5_BAT")
	)
	(via
		(at 263.62533 -317.885318)
		(size 0.508)
		(drill 0.254)
		(layers "F.Cu" "B.Cu")
		(net "P1V5_BAT")
	)
	(via
		(at 357.075994 -363.225334)
		(size 0.508)
		(drill 0.254)
		(layers "F.Cu" "B.Cu")
		(net "P1V5_BAT")
	)
	(via
		(at 209.988912 -316.56401)
		(size 0.508)
		(drill 0.254)
		(layers "F.Cu" "B.Cu")
		(net "P1V5_BAT")
	)
	(via
		(at 340.996778 -301.713392)
		(size 0.508)
		(drill 0.254)
		(layers "F.Cu" "B.Cu")
		(net "P1V5_BAT")
	)
	(segment
		(start 304.562764 -311.191148)
		(end 303.376076 -312.377836)
		(width 0.508)
		(layer "B.Cu")
		(net "P1V5_BAT")
	)
	(segment
		(start 299.596556 -319.810892)
		(end 264.80008 -319.810892)
		(width 0.508)
		(layer "B.Cu")
		(net "P1V5_BAT")
	)
	(segment
		(start 301.596044 -317.811404)
		(end 299.596556 -319.810892)
		(width 0.508)
		(layer "B.Cu")
		(net "P1V5_BAT")
	)
	(segment
		(start 336.258154 -301.713392)
		(end 333.588614 -299.043852)
		(width 0.508)
		(layer "B.Cu")
		(net "P1V5_BAT")
	)
	(segment
		(start 400.582638 -356.79634)
		(end 394.153644 -363.225334)
		(width 0.4572)
		(layer "B.Cu")
		(net "P1V5_BAT")
	)
	(segment
		(start 320.145156 -299.043852)
		(end 307.99786 -311.191148)
		(width 0.508)
		(layer "B.Cu")
		(net "P1V5_BAT")
	)
	(segment
		(start 333.588614 -299.043852)
		(end 320.145156 -299.043852)
		(width 0.508)
		(layer "B.Cu")
		(net "P1V5_BAT")
	)
	(segment
		(start 263.62533 -318.636142)
		(end 263.62533 -317.885318)
		(width 0.508)
		(layer "B.Cu")
		(net "P1V5_BAT")
	)
	(segment
		(start 307.99786 -311.191148)
		(end 304.562764 -311.191148)
		(width 0.508)
		(layer "B.Cu")
		(net "P1V5_BAT")
	)
	(segment
		(start 406.534874 -356.79634)
		(end 400.582638 -356.79634)
		(width 0.4572)
		(layer "B.Cu")
		(net "P1V5_BAT")
	)
	(segment
		(start 303.376076 -315.032136)
		(end 301.596044 -316.812168)
		(width 0.508)
		(layer "B.Cu")
		(net "P1V5_BAT")
	)
	(segment
		(start 303.376076 -312.377836)
		(end 303.376076 -315.032136)
		(width 0.508)
		(layer "B.Cu")
		(net "P1V5_BAT")
	)
	(segment
		(start 408.597608 -331.047852)
		(end 408.597608 -330.387452)
		(width 0.4572)
		(layer "B.Cu")
		(net "P1V5_BAT")
	)
	(segment
		(start 394.153644 -363.225334)
		(end 357.075994 -363.225334)
		(width 0.4572)
		(layer "B.Cu")
		(net "P1V5_BAT")
	)
	(segment
		(start 264.80008 -319.810892)
		(end 263.62533 -318.636142)
		(width 0.508)
		(layer "B.Cu")
		(net "P1V5_BAT")
	)
	(segment
		(start 340.996778 -301.713392)
		(end 336.258154 -301.713392)
		(width 0.508)
		(layer "B.Cu")
		(net "P1V5_BAT")
	)
	(segment
		(start 301.596044 -316.812168)
		(end 301.596044 -317.811404)
		(width 0.508)
		(layer "B.Cu")
		(net "P1V5_BAT")
	)
	(segment
		(start 405.454866 -32.2961)
		(end 373.266208 -32.2961)
		(width 0.508)
		(layer "In2.Cu")
		(net "P1V5_BAT")
	)
	(segment
		(start 382.040638 -297.933872)
		(end 386.389118 -302.282352)
		(width 0.4572)
		(layer "In2.Cu")
		(net "P1V5_BAT")
	)
	(segment
		(start 374.819926 -277.73122)
		(end 374.781826 -277.753318)
		(width 0.11684)
		(layer "In2.Cu")
		(net "P1V5_BAT")
	)
	(segment
		(start 372.138702 -33.423606)
		(end 368.672618 -33.423606)
		(width 0.508)
		(layer "In2.Cu")
		(net "P1V5_BAT")
	)
	(segment
		(start 374.819926 -284.211268)
		(end 374.781826 -284.233366)
		(width 0.11684)
		(layer "In2.Cu")
		(net "P1V5_BAT")
	)
	(segment
		(start 368.672618 -33.423606)
		(end 367.86058 -34.235644)
		(width 0.508)
		(layer "In2.Cu")
		(net "P1V5_BAT")
	)
	(segment
		(start 375.054876 -285.42615)
		(end 375.054622 -285.42615)
		(width 0.11684)
		(layer "In2.Cu")
		(net "P1V5_BAT")
	)
	(segment
		(start 374.817132 -281.779472)
		(end 374.822466 -281.782774)
		(width 0.11684)
		(layer "In2.Cu")
		(net "P1V5_BAT")
	)
	(segment
		(start 375.054876 -293.525956)
		(end 375.054622 -293.525956)
		(width 0.11684)
		(layer "In2.Cu")
		(net "P1V5_BAT")
	)
	(segment
		(start 374.819926 -278.540972)
		(end 374.85193 -278.559514)
		(width 0.11684)
		(layer "In2.Cu")
		(net "P1V5_BAT")
	)
	(segment
		(start 374.85193 -284.192726)
		(end 374.819926 -284.211268)
		(width 0.11684)
		(layer "In2.Cu")
		(net "P1V5_BAT")
	)
	(segment
		(start 374.854216 -292.290754)
		(end 374.819926 -292.31082)
		(width 0.11684)
		(layer "In2.Cu")
		(net "P1V5_BAT")
	)
	(segment
		(start 411.111192 -37.952426)
		(end 405.454866 -32.2961)
		(width 0.508)
		(layer "In2.Cu")
		(net "P1V5_BAT")
	)
	(segment
		(start 375.054876 -282.186126)
		(end 375.054622 -282.186126)
		(width 0.11684)
		(layer "In2.Cu")
		(net "P1V5_BAT")
	)
	(segment
		(start 375.289826 -293.930832)
		(end 375.32564 -293.95166)
		(width 0.11684)
		(layer "In2.Cu")
		(net "P1V5_BAT")
	)
	(segment
		(start 374.817132 -268.819376)
		(end 374.819926 -268.821154)
		(width 0.11684)
		(layer "In2.Cu")
		(net "P1V5_BAT")
	)
	(segment
		(start 374.819926 -272.871184)
		(end 374.781826 -272.893282)
		(width 0.11684)
		(layer "In2.Cu")
		(net "P1V5_BAT")
	)
	(segment
		(start 374.816878 -286.639)
		(end 374.822466 -286.642302)
		(width 0.11684)
		(layer "In2.Cu")
		(net "P1V5_BAT")
	)
	(segment
		(start 375.054876 -280.566114)
		(end 375.054622 -280.566114)
		(width 0.11684)
		(layer "In2.Cu")
		(net "P1V5_BAT")
	)
	(segment
		(start 374.85193 -285.812738)
		(end 374.819926 -285.83128)
		(width 0.11684)
		(layer "In2.Cu")
		(net "P1V5_BAT")
	)
	(segment
		(start 374.819926 -290.690808)
		(end 374.784112 -290.711636)
		(width 0.11684)
		(layer "In2.Cu")
		(net "P1V5_BAT")
	)
	(segment
		(start 374.819926 -292.31082)
		(end 374.784112 -292.331648)
		(width 0.11684)
		(layer "In2.Cu")
		(net "P1V5_BAT")
	)
	(segment
		(start 374.819926 -289.881056)
		(end 374.854216 -289.901122)
		(width 0.11684)
		(layer "In2.Cu")
		(net "P1V5_BAT")
	)
	(segment
		(start 377.625356 -296.584624)
		(end 378.974604 -297.933872)
		(width 0.4572)
		(layer "In2.Cu")
		(net "P1V5_BAT")
	)
	(segment
		(start 374.85193 -280.952702)
		(end 374.819926 -280.971244)
		(width 0.11684)
		(layer "In2.Cu")
		(net "P1V5_BAT")
	)
	(segment
		(start 374.817132 -275.299424)
		(end 374.819926 -275.301202)
		(width 0.11684)
		(layer "In2.Cu")
		(net "P1V5_BAT")
	)
	(segment
		(start 374.817132 -291.49929)
		(end 374.822466 -291.502592)
		(width 0.11684)
		(layer "In2.Cu")
		(net "P1V5_BAT")
	)
	(segment
		(start 375.054876 -291.905944)
		(end 375.054622 -291.905944)
		(width 0.11684)
		(layer "In2.Cu")
		(net "P1V5_BAT")
	)
	(segment
		(start 374.819926 -268.821154)
		(end 374.819926 -268.8209)
		(width 0.11684)
		(layer "In2.Cu")
		(net "P1V5_BAT")
	)
	(segment
		(start 374.316498 -267.991844)
		(end 374.349772 -268.011148)
		(width 0.11684)
		(layer "In2.Cu")
		(net "P1V5_BAT")
	)
	(segment
		(start 374.821958 -271.249902)
		(end 374.819926 -271.251172)
		(width 0.11684)
		(layer "In2.Cu")
		(net "P1V5_BAT")
	)
	(segment
		(start 374.819926 -270.441166)
		(end 374.819926 -270.440912)
		(width 0.11684)
		(layer "In2.Cu")
		(net "P1V5_BAT")
	)
	(segment
		(start 374.819926 -287.451038)
		(end 374.784112 -287.471866)
		(width 0.11684)
		(layer "In2.Cu")
		(net "P1V5_BAT")
	)
	(segment
		(start 374.819926 -276.921214)
		(end 374.819926 -276.92096)
		(width 0.11684)
		(layer "In2.Cu")
		(net "P1V5_BAT")
	)
	(segment
		(start 374.821958 -290.689792)
		(end 374.819926 -290.691062)
		(width 0.11684)
		(layer "In2.Cu")
		(net "P1V5_BAT")
	)
	(segment
		(start 374.819926 -282.591256)
		(end 374.781826 -282.613354)
		(width 0.11684)
		(layer "In2.Cu")
		(net "P1V5_BAT")
	)
	(segment
		(start 374.819926 -279.351232)
		(end 374.781826 -279.37333)
		(width 0.11684)
		(layer "In2.Cu")
		(net "P1V5_BAT")
	)
	(segment
		(start 337.02498 -34.235644)
		(end 333.743554 -30.954218)
		(width 0.508)
		(layer "In2.Cu")
		(net "P1V5_BAT")
	)
	(segment
		(start 374.821958 -279.349962)
		(end 374.819926 -279.351232)
		(width 0.11684)
		(layer "In2.Cu")
		(net "P1V5_BAT")
	)
	(segment
		(start 374.784112 -289.860228)
		(end 374.819926 -289.881056)
		(width 0.11684)
		(layer "In2.Cu")
		(net "P1V5_BAT")
	)
	(segment
		(start 374.817132 -285.019496)
		(end 374.822466 -285.022798)
		(width 0.11684)
		(layer "In2.Cu")
		(net "P1V5_BAT")
	)
	(segment
		(start 374.817132 -273.679412)
		(end 374.819926 -273.68119)
		(width 0.11684)
		(layer "In2.Cu")
		(net "P1V5_BAT")
	)
	(segment
		(start 374.821958 -269.62989)
		(end 374.819926 -269.63116)
		(width 0.11684)
		(layer "In2.Cu")
		(net "P1V5_BAT")
	)
	(segment
		(start 374.819926 -275.300948)
		(end 374.85193 -275.31949)
		(width 0.11684)
		(layer "In2.Cu")
		(net "P1V5_BAT")
	)
	(segment
		(start 374.819926 -276.92096)
		(end 374.85193 -276.939502)
		(width 0.11684)
		(layer "In2.Cu")
		(net "P1V5_BAT")
	)
	(segment
		(start 374.85193 -282.572714)
		(end 374.819926 -282.591256)
		(width 0.11684)
		(layer "In2.Cu")
		(net "P1V5_BAT")
	)
	(segment
		(start 375.054876 -288.66592)
		(end 375.054622 -288.66592)
		(width 0.11684)
		(layer "In2.Cu")
		(net "P1V5_BAT")
	)
	(segment
		(start 374.819926 -275.301202)
		(end 374.819926 -275.300948)
		(width 0.11684)
		(layer "In2.Cu")
		(net "P1V5_BAT")
	)
	(segment
		(start 378.974604 -297.933872)
		(end 382.040638 -297.933872)
		(width 0.4572)
		(layer "In2.Cu")
		(net "P1V5_BAT")
	)
	(segment
		(start 374.819926 -280.971244)
		(end 374.781826 -280.993342)
		(width 0.11684)
		(layer "In2.Cu")
		(net "P1V5_BAT")
	)
	(segment
		(start 374.85193 -287.432496)
		(end 374.819926 -287.451038)
		(width 0.11684)
		(layer "In2.Cu")
		(net "P1V5_BAT")
	)
	(segment
		(start 375.054876 -287.045908)
		(end 375.054622 -287.045908)
		(width 0.11684)
		(layer "In2.Cu")
		(net "P1V5_BAT")
	)
	(segment
		(start 411.111192 -58.62447)
		(end 411.111192 -37.952426)
		(width 0.508)
		(layer "In2.Cu")
		(net "P1V5_BAT")
	)
	(segment
		(start 333.743554 -30.954218)
		(end 333.743554 -26.603706)
		(width 0.508)
		(layer "In2.Cu")
		(net "P1V5_BAT")
	)
	(segment
		(start 374.819926 -268.8209)
		(end 374.85193 -268.839442)
		(width 0.11684)
		(layer "In2.Cu")
		(net "P1V5_BAT")
	)
	(segment
		(start 375.855738 -294.815006)
		(end 376.106436 -295.065704)
		(width 0.11684)
		(layer "In2.Cu")
		(net "P1V5_BAT")
	)
	(segment
		(start 374.819926 -273.68119)
		(end 374.819926 -273.680936)
		(width 0.11684)
		(layer "In2.Cu")
		(net "P1V5_BAT")
	)
	(segment
		(start 374.817132 -272.0594)
		(end 374.822466 -272.062702)
		(width 0.11684)
		(layer "In2.Cu")
		(net "P1V5_BAT")
	)
	(segment
		(start 374.821958 -274.489926)
		(end 374.819926 -274.491196)
		(width 0.11684)
		(layer "In2.Cu")
		(net "P1V5_BAT")
	)
	(segment
		(start 413.015684 -60.528962)
		(end 411.111192 -58.62447)
		(width 0.508)
		(layer "In2.Cu")
		(net "P1V5_BAT")
	)
	(segment
		(start 374.819926 -271.251172)
		(end 374.781826 -271.27327)
		(width 0.11684)
		(layer "In2.Cu")
		(net "P1V5_BAT")
	)
	(segment
		(start 375.054876 -272.466054)
		(end 375.054622 -272.466054)
		(width 0.11684)
		(layer "In2.Cu")
		(net "P1V5_BAT")
	)
	(segment
		(start 374.817132 -283.399484)
		(end 374.822466 -283.402786)
		(width 0.11684)
		(layer "In2.Cu")
		(net "P1V5_BAT")
	)
	(segment
		(start 375.054876 -283.806138)
		(end 375.054622 -283.806138)
		(width 0.11684)
		(layer "In2.Cu")
		(net "P1V5_BAT")
	)
	(segment
		(start 373.266208 -32.2961)
		(end 372.138702 -33.423606)
		(width 0.508)
		(layer "In2.Cu")
		(net "P1V5_BAT")
	)
	(segment
		(start 374.114822 -266.796012)
		(end 374.114822 -267.606018)
		(width 0.11684)
		(layer "In2.Cu")
		(net "P1V5_BAT")
	)
	(segment
		(start 374.819926 -285.83128)
		(end 374.781826 -285.853378)
		(width 0.11684)
		(layer "In2.Cu")
		(net "P1V5_BAT")
	)
	(segment
		(start 374.821958 -277.72995)
		(end 374.819926 -277.73122)
		(width 0.11684)
		(layer "In2.Cu")
		(net "P1V5_BAT")
	)
	(segment
		(start 374.819926 -276.111208)
		(end 374.781826 -276.133306)
		(width 0.11684)
		(layer "In2.Cu")
		(net "P1V5_BAT")
	)
	(segment
		(start 374.817132 -280.15946)
		(end 374.822466 -280.162762)
		(width 0.11684)
		(layer "In2.Cu")
		(net "P1V5_BAT")
	)
	(segment
		(start 374.819926 -290.691062)
		(end 374.819926 -290.690808)
		(width 0.11684)
		(layer "In2.Cu")
		(net "P1V5_BAT")
	)
	(segment
		(start 374.819926 -269.63116)
		(end 374.781826 -269.653258)
		(width 0.11684)
		(layer "In2.Cu")
		(net "P1V5_BAT")
	)
	(segment
		(start 374.349772 -268.011148)
		(end 374.385332 -268.031722)
		(width 0.11684)
		(layer "In2.Cu")
		(net "P1V5_BAT")
	)
	(segment
		(start 374.819926 -289.070796)
		(end 374.81764 -289.07232)
		(width 0.11684)
		(layer "In2.Cu")
		(net "P1V5_BAT")
	)
	(segment
		(start 376.106436 -295.065704)
		(end 377.625356 -296.584624)
		(width 0.254)
		(layer "In2.Cu")
		(net "P1V5_BAT")
	)
	(segment
		(start 375.727722 -294.72255)
		(end 375.759726 -294.741092)
		(width 0.11684)
		(layer "In2.Cu")
		(net "P1V5_BAT")
	)
	(segment
		(start 374.816878 -288.259012)
		(end 374.822466 -288.262314)
		(width 0.11684)
		(layer "In2.Cu")
		(net "P1V5_BAT")
	)
	(segment
		(start 374.817132 -278.539448)
		(end 374.819926 -278.541226)
		(width 0.11684)
		(layer "In2.Cu")
		(net "P1V5_BAT")
	)
	(segment
		(start 367.86058 -34.235644)
		(end 337.02498 -34.235644)
		(width 0.508)
		(layer "In2.Cu")
		(net "P1V5_BAT")
	)
	(segment
		(start 374.819926 -274.491196)
		(end 374.781826 -274.513294)
		(width 0.11684)
		(layer "In2.Cu")
		(net "P1V5_BAT")
	)
	(segment
		(start 413.297624 -60.528962)
		(end 413.015684 -60.528962)
		(width 0.508)
		(layer "In2.Cu")
		(net "P1V5_BAT")
	)
	(segment
		(start 374.817132 -270.439388)
		(end 374.819926 -270.441166)
		(width 0.11684)
		(layer "In2.Cu")
		(net "P1V5_BAT")
	)
	(segment
		(start 374.854216 -289.05073)
		(end 374.819926 -289.070796)
		(width 0.11684)
		(layer "In2.Cu")
		(net "P1V5_BAT")
	)
	(segment
		(start 375.251726 -293.908734)
		(end 375.289826 -293.930832)
		(width 0.11684)
		(layer "In2.Cu")
		(net "P1V5_BAT")
	)
	(segment
		(start 374.817132 -293.119302)
		(end 374.822466 -293.122604)
		(width 0.11684)
		(layer "In2.Cu")
		(net "P1V5_BAT")
	)
	(segment
		(start 374.584976 -289.475926)
		(end 374.584722 -289.475926)
		(width 0.11684)
		(layer "In2.Cu")
		(net "P1V5_BAT")
	)
	(segment
		(start 374.819926 -270.440912)
		(end 374.85193 -270.459454)
		(width 0.11684)
		(layer "In2.Cu")
		(net "P1V5_BAT")
	)
	(segment
		(start 374.821958 -276.109938)
		(end 374.819926 -276.111208)
		(width 0.11684)
		(layer "In2.Cu")
		(net "P1V5_BAT")
	)
	(segment
		(start 374.819926 -273.680936)
		(end 374.85193 -273.699478)
		(width 0.11684)
		(layer "In2.Cu")
		(net "P1V5_BAT")
	)
	(segment
		(start 374.85193 -272.852642)
		(end 374.819926 -272.871184)
		(width 0.11684)
		(layer "In2.Cu")
		(net "P1V5_BAT")
	)
	(segment
		(start 374.817132 -276.919436)
		(end 374.819926 -276.921214)
		(width 0.11684)
		(layer "In2.Cu")
		(net "P1V5_BAT")
	)
	(segment
		(start 374.819926 -278.541226)
		(end 374.819926 -278.540972)
		(width 0.11684)
		(layer "In2.Cu")
		(net "P1V5_BAT")
	)
	(arc
		(start 374.584722 -279.756108)
		(mid 374.646971 -279.988883)
		(end 374.817132 -280.15946)
		(width 0.11684)
		(layer "In2.Cu")
		(net "P1V5_BAT")
	)
	(arc
		(start 375.054622 -277.32609)
		(mid 374.992296 -277.559134)
		(end 374.821958 -277.72995)
		(width 0.11684)
		(layer "In2.Cu")
		(net "P1V5_BAT")
	)
	(arc
		(start 374.781826 -282.613354)
		(mid 374.636869 -282.780852)
		(end 374.584722 -282.996132)
		(width 0.11684)
		(layer "In2.Cu")
		(net "P1V5_BAT")
	)
	(arc
		(start 374.784112 -290.711636)
		(mid 374.63757 -290.879474)
		(end 374.584722 -291.095938)
		(width 0.11684)
		(layer "In2.Cu")
		(net "P1V5_BAT")
	)
	(arc
		(start 374.85193 -278.559514)
		(mid 375.000909 -278.72784)
		(end 375.054622 -278.946102)
		(width 0.11684)
		(layer "In2.Cu")
		(net "P1V5_BAT")
	)
	(arc
		(start 374.85193 -270.459454)
		(mid 375.000909 -270.62778)
		(end 375.054622 -270.846042)
		(width 0.11684)
		(layer "In2.Cu")
		(net "P1V5_BAT")
	)
	(arc
		(start 374.784112 -292.331648)
		(mid 374.63757 -292.499486)
		(end 374.584722 -292.71595)
		(width 0.11684)
		(layer "In2.Cu")
		(net "P1V5_BAT")
	)
	(arc
		(start 375.054622 -274.086066)
		(mid 374.992296 -274.31911)
		(end 374.821958 -274.489926)
		(width 0.11684)
		(layer "In2.Cu")
		(net "P1V5_BAT")
	)
	(arc
		(start 374.584722 -271.656048)
		(mid 374.646971 -271.888823)
		(end 374.817132 -272.0594)
		(width 0.11684)
		(layer "In2.Cu")
		(net "P1V5_BAT")
	)
	(arc
		(start 374.781826 -277.753318)
		(mid 374.636869 -277.920816)
		(end 374.584722 -278.136096)
		(width 0.11684)
		(layer "In2.Cu")
		(net "P1V5_BAT")
	)
	(arc
		(start 374.584722 -282.996132)
		(mid 374.646971 -283.228907)
		(end 374.817132 -283.399484)
		(width 0.11684)
		(layer "In2.Cu")
		(net "P1V5_BAT")
	)
	(arc
		(start 374.85193 -275.31949)
		(mid 375.000909 -275.487816)
		(end 375.054622 -275.706078)
		(width 0.11684)
		(layer "In2.Cu")
		(net "P1V5_BAT")
	)
	(arc
		(start 374.822466 -286.642302)
		(mid 374.992642 -286.813031)
		(end 375.054876 -287.045908)
		(width 0.11684)
		(layer "In2.Cu")
		(net "P1V5_BAT")
	)
	(arc
		(start 375.054622 -293.525956)
		(mid 375.106798 -293.741221)
		(end 375.251726 -293.908734)
		(width 0.11684)
		(layer "In2.Cu")
		(net "P1V5_BAT")
	)
	(arc
		(start 374.584722 -292.71595)
		(mid 374.646971 -292.948725)
		(end 374.817132 -293.119302)
		(width 0.11684)
		(layer "In2.Cu")
		(net "P1V5_BAT")
	)
	(arc
		(start 374.781826 -284.233366)
		(mid 374.636869 -284.400864)
		(end 374.584722 -284.616144)
		(width 0.11684)
		(layer "In2.Cu")
		(net "P1V5_BAT")
	)
	(arc
		(start 374.85193 -268.839442)
		(mid 375.000909 -269.007768)
		(end 375.054622 -269.22603)
		(width 0.11684)
		(layer "In2.Cu")
		(net "P1V5_BAT")
	)
	(arc
		(start 374.85193 -276.939502)
		(mid 375.000909 -277.107828)
		(end 375.054622 -277.32609)
		(width 0.11684)
		(layer "In2.Cu")
		(net "P1V5_BAT")
	)
	(arc
		(start 374.822466 -288.262314)
		(mid 374.992642 -288.433043)
		(end 375.054876 -288.66592)
		(width 0.11684)
		(layer "In2.Cu")
		(net "P1V5_BAT")
	)
	(arc
		(start 374.385332 -268.031722)
		(mid 374.531874 -268.19956)
		(end 374.584722 -268.416024)
		(width 0.11684)
		(layer "In2.Cu")
		(net "P1V5_BAT")
	)
	(arc
		(start 374.781826 -269.653258)
		(mid 374.636869 -269.820756)
		(end 374.584722 -270.036036)
		(width 0.11684)
		(layer "In2.Cu")
		(net "P1V5_BAT")
	)
	(arc
		(start 374.784112 -287.471866)
		(mid 374.63757 -287.639704)
		(end 374.584722 -287.856168)
		(width 0.11684)
		(layer "In2.Cu")
		(net "P1V5_BAT")
	)
	(arc
		(start 375.054622 -291.905944)
		(mid 375.001518 -292.122878)
		(end 374.854216 -292.290754)
		(width 0.11684)
		(layer "In2.Cu")
		(net "P1V5_BAT")
	)
	(arc
		(start 374.781826 -285.853378)
		(mid 374.636869 -286.020876)
		(end 374.584722 -286.236156)
		(width 0.11684)
		(layer "In2.Cu")
		(net "P1V5_BAT")
	)
	(arc
		(start 375.054622 -282.186126)
		(mid 375.000868 -282.404366)
		(end 374.85193 -282.572714)
		(width 0.11684)
		(layer "In2.Cu")
		(net "P1V5_BAT")
	)
	(arc
		(start 374.584722 -291.095938)
		(mid 374.646971 -291.328713)
		(end 374.817132 -291.49929)
		(width 0.11684)
		(layer "In2.Cu")
		(net "P1V5_BAT")
	)
	(arc
		(start 375.759726 -294.741092)
		(mid 375.810123 -294.774942)
		(end 375.855738 -294.815006)
		(width 0.11684)
		(layer "In2.Cu")
		(net "P1V5_BAT")
	)
	(arc
		(start 374.584722 -289.475926)
		(mid 374.637528 -289.692411)
		(end 374.784112 -289.860228)
		(width 0.11684)
		(layer "In2.Cu")
		(net "P1V5_BAT")
	)
	(arc
		(start 375.52503 -294.335962)
		(mid 375.578784 -294.554202)
		(end 375.727722 -294.72255)
		(width 0.11684)
		(layer "In2.Cu")
		(net "P1V5_BAT")
	)
	(arc
		(start 374.584722 -276.516084)
		(mid 374.646971 -276.748859)
		(end 374.817132 -276.919436)
		(width 0.11684)
		(layer "In2.Cu")
		(net "P1V5_BAT")
	)
	(arc
		(start 374.584722 -278.136096)
		(mid 374.646971 -278.368871)
		(end 374.817132 -278.539448)
		(width 0.11684)
		(layer "In2.Cu")
		(net "P1V5_BAT")
	)
	(arc
		(start 374.822466 -280.162762)
		(mid 374.992572 -280.333371)
		(end 375.054876 -280.566114)
		(width 0.11684)
		(layer "In2.Cu")
		(net "P1V5_BAT")
	)
	(arc
		(start 374.822466 -281.782774)
		(mid 374.992572 -281.953383)
		(end 375.054876 -282.186126)
		(width 0.11684)
		(layer "In2.Cu")
		(net "P1V5_BAT")
	)
	(arc
		(start 374.781826 -279.37333)
		(mid 374.636869 -279.540828)
		(end 374.584722 -279.756108)
		(width 0.11684)
		(layer "In2.Cu")
		(net "P1V5_BAT")
	)
	(arc
		(start 375.054622 -275.706078)
		(mid 374.992296 -275.939122)
		(end 374.821958 -276.109938)
		(width 0.11684)
		(layer "In2.Cu")
		(net "P1V5_BAT")
	)
	(arc
		(start 374.85193 -273.699478)
		(mid 375.000909 -273.867804)
		(end 375.054622 -274.086066)
		(width 0.11684)
		(layer "In2.Cu")
		(net "P1V5_BAT")
	)
	(arc
		(start 375.054622 -269.22603)
		(mid 374.992296 -269.459074)
		(end 374.821958 -269.62989)
		(width 0.11684)
		(layer "In2.Cu")
		(net "P1V5_BAT")
	)
	(arc
		(start 374.781826 -276.133306)
		(mid 374.636869 -276.300804)
		(end 374.584722 -276.516084)
		(width 0.11684)
		(layer "In2.Cu")
		(net "P1V5_BAT")
	)
	(arc
		(start 374.781826 -271.27327)
		(mid 374.636869 -271.440768)
		(end 374.584722 -271.656048)
		(width 0.11684)
		(layer "In2.Cu")
		(net "P1V5_BAT")
	)
	(arc
		(start 375.054622 -287.045908)
		(mid 375.000868 -287.264148)
		(end 374.85193 -287.432496)
		(width 0.11684)
		(layer "In2.Cu")
		(net "P1V5_BAT")
	)
	(arc
		(start 374.584722 -281.37612)
		(mid 374.646971 -281.608895)
		(end 374.817132 -281.779472)
		(width 0.11684)
		(layer "In2.Cu")
		(net "P1V5_BAT")
	)
	(arc
		(start 374.822466 -293.122604)
		(mid 374.992572 -293.293213)
		(end 375.054876 -293.525956)
		(width 0.11684)
		(layer "In2.Cu")
		(net "P1V5_BAT")
	)
	(arc
		(start 375.054622 -288.66592)
		(mid 375.001518 -288.882854)
		(end 374.854216 -289.05073)
		(width 0.11684)
		(layer "In2.Cu")
		(net "P1V5_BAT")
	)
	(arc
		(start 375.054622 -283.806138)
		(mid 375.000868 -284.024378)
		(end 374.85193 -284.192726)
		(width 0.11684)
		(layer "In2.Cu")
		(net "P1V5_BAT")
	)
	(arc
		(start 375.054622 -272.466054)
		(mid 375.000868 -272.684294)
		(end 374.85193 -272.852642)
		(width 0.11684)
		(layer "In2.Cu")
		(net "P1V5_BAT")
	)
	(arc
		(start 375.054622 -280.566114)
		(mid 375.000868 -280.784354)
		(end 374.85193 -280.952702)
		(width 0.11684)
		(layer "In2.Cu")
		(net "P1V5_BAT")
	)
	(arc
		(start 374.584722 -284.616144)
		(mid 374.646971 -284.848919)
		(end 374.817132 -285.019496)
		(width 0.11684)
		(layer "In2.Cu")
		(net "P1V5_BAT")
	)
	(arc
		(start 375.32564 -293.95166)
		(mid 375.472182 -294.119498)
		(end 375.52503 -294.335962)
		(width 0.11684)
		(layer "In2.Cu")
		(net "P1V5_BAT")
	)
	(arc
		(start 375.054622 -285.42615)
		(mid 375.000868 -285.64439)
		(end 374.85193 -285.812738)
		(width 0.11684)
		(layer "In2.Cu")
		(net "P1V5_BAT")
	)
	(arc
		(start 374.584722 -273.27606)
		(mid 374.646971 -273.508835)
		(end 374.817132 -273.679412)
		(width 0.11684)
		(layer "In2.Cu")
		(net "P1V5_BAT")
	)
	(arc
		(start 374.781826 -272.893282)
		(mid 374.636869 -273.06078)
		(end 374.584722 -273.27606)
		(width 0.11684)
		(layer "In2.Cu")
		(net "P1V5_BAT")
	)
	(arc
		(start 374.822466 -283.402786)
		(mid 374.992572 -283.573395)
		(end 375.054876 -283.806138)
		(width 0.11684)
		(layer "In2.Cu")
		(net "P1V5_BAT")
	)
	(arc
		(start 375.054622 -270.846042)
		(mid 374.992296 -271.079086)
		(end 374.821958 -271.249902)
		(width 0.11684)
		(layer "In2.Cu")
		(net "P1V5_BAT")
	)
	(arc
		(start 374.781826 -274.513294)
		(mid 374.636869 -274.680792)
		(end 374.584722 -274.896072)
		(width 0.11684)
		(layer "In2.Cu")
		(net "P1V5_BAT")
	)
	(arc
		(start 374.584722 -287.856168)
		(mid 374.64699 -288.088585)
		(end 374.816878 -288.259012)
		(width 0.11684)
		(layer "In2.Cu")
		(net "P1V5_BAT")
	)
	(arc
		(start 374.584722 -274.896072)
		(mid 374.646971 -275.128847)
		(end 374.817132 -275.299424)
		(width 0.11684)
		(layer "In2.Cu")
		(net "P1V5_BAT")
	)
	(arc
		(start 374.114822 -267.606018)
		(mid 374.168282 -267.823696)
		(end 374.316498 -267.991844)
		(width 0.11684)
		(layer "In2.Cu")
		(net "P1V5_BAT")
	)
	(arc
		(start 374.584722 -268.416024)
		(mid 374.646971 -268.648799)
		(end 374.817132 -268.819376)
		(width 0.11684)
		(layer "In2.Cu")
		(net "P1V5_BAT")
	)
	(arc
		(start 375.054622 -290.285932)
		(mid 374.992296 -290.518976)
		(end 374.821958 -290.689792)
		(width 0.11684)
		(layer "In2.Cu")
		(net "P1V5_BAT")
	)
	(arc
		(start 374.854216 -289.901122)
		(mid 375.001519 -290.068998)
		(end 375.054622 -290.285932)
		(width 0.11684)
		(layer "In2.Cu")
		(net "P1V5_BAT")
	)
	(arc
		(start 374.81764 -289.07232)
		(mid 374.647369 -289.243028)
		(end 374.584976 -289.475926)
		(width 0.11684)
		(layer "In2.Cu")
		(net "P1V5_BAT")
	)
	(arc
		(start 374.584722 -270.036036)
		(mid 374.646971 -270.268811)
		(end 374.817132 -270.439388)
		(width 0.11684)
		(layer "In2.Cu")
		(net "P1V5_BAT")
	)
	(arc
		(start 374.781826 -280.993342)
		(mid 374.636869 -281.16084)
		(end 374.584722 -281.37612)
		(width 0.11684)
		(layer "In2.Cu")
		(net "P1V5_BAT")
	)
	(arc
		(start 374.822466 -291.502592)
		(mid 374.992572 -291.673201)
		(end 375.054876 -291.905944)
		(width 0.11684)
		(layer "In2.Cu")
		(net "P1V5_BAT")
	)
	(arc
		(start 374.822466 -272.062702)
		(mid 374.992572 -272.233311)
		(end 375.054876 -272.466054)
		(width 0.11684)
		(layer "In2.Cu")
		(net "P1V5_BAT")
	)
	(arc
		(start 374.822466 -285.022798)
		(mid 374.992572 -285.193407)
		(end 375.054876 -285.42615)
		(width 0.11684)
		(layer "In2.Cu")
		(net "P1V5_BAT")
	)
	(arc
		(start 375.054622 -278.946102)
		(mid 374.992296 -279.179146)
		(end 374.821958 -279.349962)
		(width 0.11684)
		(layer "In2.Cu")
		(net "P1V5_BAT")
	)
	(arc
		(start 374.584722 -286.236156)
		(mid 374.64699 -286.468573)
		(end 374.816878 -286.639)
		(width 0.11684)
		(layer "In2.Cu")
		(net "P1V5_BAT")
	)
	(segment
		(start 407.015188 -356.316026)
		(end 406.534874 -356.79634)
		(width 0.4572)
		(layer "In4.Cu")
		(net "P1V5_BAT")
	)
	(segment
		(start 408.597608 -332.010004)
		(end 406.880822 -333.72679)
		(width 0.4572)
		(layer "In4.Cu")
		(net "P1V5_BAT")
	)
	(segment
		(start 406.880822 -333.72679)
		(end 406.880822 -337.914234)
		(width 0.4572)
		(layer "In4.Cu")
		(net "P1V5_BAT")
	)
	(segment
		(start 404.92172 -346.836492)
		(end 407.015188 -348.92996)
		(width 0.4572)
		(layer "In4.Cu")
		(net "P1V5_BAT")
	)
	(segment
		(start 407.015188 -348.92996)
		(end 407.015188 -356.316026)
		(width 0.4572)
		(layer "In4.Cu")
		(net "P1V5_BAT")
	)
	(segment
		(start 404.92172 -345.482164)
		(end 404.92172 -346.836492)
		(width 0.4572)
		(layer "In4.Cu")
		(net "P1V5_BAT")
	)
	(segment
		(start 405.536146 -339.25891)
		(end 405.536146 -344.867738)
		(width 0.4572)
		(layer "In4.Cu")
		(net "P1V5_BAT")
	)
	(segment
		(start 408.597608 -331.047852)
		(end 408.597608 -332.010004)
		(width 0.4572)
		(layer "In4.Cu")
		(net "P1V5_BAT")
	)
	(segment
		(start 405.536146 -344.867738)
		(end 404.92172 -345.482164)
		(width 0.4572)
		(layer "In4.Cu")
		(net "P1V5_BAT")
	)
	(segment
		(start 406.880822 -337.914234)
		(end 405.536146 -339.25891)
		(width 0.4572)
		(layer "In4.Cu")
		(net "P1V5_BAT")
	)
	(segment
		(start 434.172106 -161.861754)
		(end 436.503318 -164.192966)
		(width 0.508)
		(layer "In6.Cu")
		(net "P1V5_BAT")
	)
	(segment
		(start 419.27653 -322.636388)
		(end 417.871402 -324.041516)
		(width 0.508)
		(layer "In6.Cu")
		(net "P1V5_BAT")
	)
	(segment
		(start 436.503318 -164.192966)
		(end 441.50534 -164.192966)
		(width 0.508)
		(layer "In6.Cu")
		(net "P1V5_BAT")
	)
	(segment
		(start 417.871402 -324.041516)
		(end 417.871402 -324.150736)
		(width 0.508)
		(layer "In6.Cu")
		(net "P1V5_BAT")
	)
	(segment
		(start 451.752716 -322.636388)
		(end 419.27653 -322.636388)
		(width 0.508)
		(layer "In6.Cu")
		(net "P1V5_BAT")
	)
	(segment
		(start 459.352396 -315.036708)
		(end 451.752716 -322.636388)
		(width 0.508)
		(layer "In6.Cu")
		(net "P1V5_BAT")
	)
	(segment
		(start 447.365628 -177.13452)
		(end 459.352396 -189.121288)
		(width 0.508)
		(layer "In6.Cu")
		(net "P1V5_BAT")
	)
	(segment
		(start 441.50534 -164.192966)
		(end 447.365628 -170.053254)
		(width 0.508)
		(layer "In6.Cu")
		(net "P1V5_BAT")
	)
	(segment
		(start 459.352396 -189.121288)
		(end 459.352396 -315.036708)
		(width 0.508)
		(layer "In6.Cu")
		(net "P1V5_BAT")
	)
	(segment
		(start 447.365628 -170.053254)
		(end 447.365628 -177.13452)
		(width 0.508)
		(layer "In6.Cu")
		(net "P1V5_BAT")
	)
	(segment
		(start 413.484568 -126.346712)
		(end 413.484568 -79.387446)
		(width 0.508)
		(layer "In11.Cu")
		(net "P1V5_BAT")
	)
	(segment
		(start 410.657802 -323.338952)
		(end 410.657802 -329.865482)
		(width 0.508)
		(layer "In11.Cu")
		(net "P1V5_BAT")
	)
	(segment
		(start 414.983676 -71.568056)
		(end 414.109154 -70.693534)
		(width 0.508)
		(layer "In11.Cu")
		(net "P1V5_BAT")
	)
	(segment
		(start 434.172106 -161.861754)
		(end 434.172106 -147.03425)
		(width 0.508)
		(layer "In11.Cu")
		(net "P1V5_BAT")
	)
	(segment
		(start 414.109154 -70.693534)
		(end 414.109154 -61.340492)
		(width 0.508)
		(layer "In11.Cu")
		(net "P1V5_BAT")
	)
	(segment
		(start 409.475432 -331.047852)
		(end 408.597608 -331.047852)
		(width 0.508)
		(layer "In11.Cu")
		(net "P1V5_BAT")
	)
	(segment
		(start 414.983676 -77.888338)
		(end 414.983676 -71.568056)
		(width 0.508)
		(layer "In11.Cu")
		(net "P1V5_BAT")
	)
	(segment
		(start 414.109154 -61.340492)
		(end 413.297624 -60.528962)
		(width 0.508)
		(layer "In11.Cu")
		(net "P1V5_BAT")
	)
	(segment
		(start 410.657802 -329.865482)
		(end 409.475432 -331.047852)
		(width 0.508)
		(layer "In11.Cu")
		(net "P1V5_BAT")
	)
	(segment
		(start 417.871402 -324.150736)
		(end 415.779458 -322.058792)
		(width 0.508)
		(layer "In11.Cu")
		(net "P1V5_BAT")
	)
	(segment
		(start 413.484568 -79.387446)
		(end 414.983676 -77.888338)
		(width 0.508)
		(layer "In11.Cu")
		(net "P1V5_BAT")
	)
	(segment
		(start 415.779458 -322.058792)
		(end 411.937962 -322.058792)
		(width 0.508)
		(layer "In11.Cu")
		(net "P1V5_BAT")
	)
	(segment
		(start 411.937962 -322.058792)
		(end 410.657802 -323.338952)
		(width 0.508)
		(layer "In11.Cu")
		(net "P1V5_BAT")
	)
	(segment
		(start 434.172106 -147.03425)
		(end 413.484568 -126.346712)
		(width 0.508)
		(layer "In11.Cu")
		(net "P1V5_BAT")
	)
	(segment
		(start 264.364724 -316.018672)
		(end 264.364724 -317.450724)
		(width 0.4572)
		(layer "In13.Cu")
		(net "P1V5_BAT")
	)
	(segment
		(start 255.139698 -265.049508)
		(end 263.690608 -273.600418)
		(width 0.4572)
		(layer "In13.Cu")
		(net "P1V5_BAT")
	)
	(segment
		(start 216.049606 -265.049508)
		(end 255.139698 -265.049508)
		(width 0.4572)
		(layer "In13.Cu")
		(net "P1V5_BAT")
	)
	(segment
		(start 209.988912 -316.56401)
		(end 209.988912 -315.019436)
		(width 0.4572)
		(layer "In13.Cu")
		(net "P1V5_BAT")
	)
	(segment
		(start 209.05724 -314.087764)
		(end 209.05724 -312.122058)
		(width 0.4572)
		(layer "In13.Cu")
		(net "P1V5_BAT")
	)
	(segment
		(start 209.81543 -271.283684)
		(end 216.049606 -265.049508)
		(width 0.4572)
		(layer "In13.Cu")
		(net "P1V5_BAT")
	)
	(segment
		(start 263.690608 -315.344556)
		(end 264.364724 -316.018672)
		(width 0.4572)
		(layer "In13.Cu")
		(net "P1V5_BAT")
	)
	(segment
		(start 263.93013 -317.885318)
		(end 263.62533 -317.885318)
		(width 0.4572)
		(layer "In13.Cu")
		(net "P1V5_BAT")
	)
	(segment
		(start 209.81543 -311.363868)
		(end 209.81543 -271.283684)
		(width 0.4572)
		(layer "In13.Cu")
		(net "P1V5_BAT")
	)
	(segment
		(start 209.05724 -312.122058)
		(end 209.81543 -311.363868)
		(width 0.4572)
		(layer "In13.Cu")
		(net "P1V5_BAT")
	)
	(segment
		(start 209.988912 -315.019436)
		(end 209.05724 -314.087764)
		(width 0.4572)
		(layer "In13.Cu")
		(net "P1V5_BAT")
	)
	(segment
		(start 263.690608 -273.600418)
		(end 263.690608 -315.344556)
		(width 0.4572)
		(layer "In13.Cu")
		(net "P1V5_BAT")
	)
	(segment
		(start 264.364724 -317.450724)
		(end 263.93013 -317.885318)
		(width 0.4572)
		(layer "In13.Cu")
		(net "P1V5_BAT")
	)
	(segment
		(start 188.28258 -29.358336)
		(end 188.28258 -28.26766)
		(width 0.10668)
		(layer "F.Cu")
		(net "P12V_SCM_VCC")
	)
	(segment
		(start 188.292232 -28.258008)
		(end 188.292232 -27.620722)
		(width 0.10668)
		(layer "F.Cu")
		(net "P12V_SCM_VCC")
	)
	(segment
		(start 188.28258 -28.26766)
		(end 188.292232 -28.258008)
		(width 0.10668)
		(layer "F.Cu")
		(net "P12V_SCM_VCC")
	)
	(segment
		(start 188.292232 -27.620722)
		(end 188.292486 -27.620468)
		(width 0.10668)
		(layer "F.Cu")
		(net "P12V_SCM_VCC")
	)
	(segment
		(start 188.738764 -27.17419)
		(end 188.292486 -27.620468)
		(width 0.10668)
		(layer "F.Cu")
		(net "P12V_SCM_VCC")
	)
	(segment
		(start 188.738764 -26.393394)
		(end 188.738764 -27.17419)
		(width 0.10668)
		(layer "F.Cu")
		(net "P12V_SCM_VCC")
	)
	(via
		(at 188.292486 -27.620468)
		(size 0.508)
		(drill 0.254)
		(layers "F.Cu" "B.Cu")
		(net "P12V_SCM_VCC")
	)
	(segment
		(start 193.985388 -41.011602)
		(end 194.143122 -41.169336)
		(width 0.10668)
		(layer "F.Cu")
		(net "P12V_SCM_UV_R")
	)
	(segment
		(start 190.83274 -41.011602)
		(end 193.985388 -41.011602)
		(width 0.10668)
		(layer "F.Cu")
		(net "P12V_SCM_UV_R")
	)
	(segment
		(start 194.510152 -41.536366)
		(end 194.143122 -41.169336)
		(width 0.10668)
		(layer "F.Cu")
		(net "P12V_SCM_UV_R")
	)
	(segment
		(start 194.628516 -43.849544)
		(end 194.510152 -43.73118)
		(width 0.10668)
		(layer "F.Cu")
		(net "P12V_SCM_UV_R")
	)
	(segment
		(start 195.25615 -43.849544)
		(end 194.628516 -43.849544)
		(width 0.10668)
		(layer "F.Cu")
		(net "P12V_SCM_UV_R")
	)
	(segment
		(start 194.510152 -43.73118)
		(end 194.510152 -41.536366)
		(width 0.10668)
		(layer "F.Cu")
		(net "P12V_SCM_UV_R")
	)
	(via
		(at 194.143122 -41.169336)
		(size 0.762)
		(drill 0.381)
		(layers "F.Cu" "B.Cu")
		(net "P12V_SCM_UV_R")
	)
	(segment
		(start 187.915296 -23.955756)
		(end 187.915296 -23.127208)
		(width 0.10668)
		(layer "F.Cu")
		(net "P12V_SCM_UV")
	)
	(segment
		(start 188.738764 -24.89327)
		(end 188.738764 -24.779224)
		(width 0.10668)
		(layer "F.Cu")
		(net "P12V_SCM_UV")
	)
	(segment
		(start 186.199272 -23.113492)
		(end 187.207906 -23.113492)
		(width 0.10668)
		(layer "F.Cu")
		(net "P12V_SCM_UV")
	)
	(segment
		(start 187.207906 -23.113492)
		(end 187.221622 -23.127208)
		(width 0.10668)
		(layer "F.Cu")
		(net "P12V_SCM_UV")
	)
	(segment
		(start 188.738764 -24.779224)
		(end 187.915296 -23.955756)
		(width 0.10668)
		(layer "F.Cu")
		(net "P12V_SCM_UV")
	)
	(segment
		(start 190.03264 -41.011602)
		(end 189.237874 -41.011602)
		(width 0.10668)
		(layer "F.Cu")
		(net "P12V_SCM_UV")
	)
	(segment
		(start 187.221622 -23.127208)
		(end 187.915296 -23.127208)
		(width 0.10668)
		(layer "F.Cu")
		(net "P12V_SCM_UV")
	)
	(via
		(at 189.237874 -41.011602)
		(size 0.508)
		(drill 0.254)
		(layers "F.Cu" "B.Cu")
		(net "P12V_SCM_UV")
	)
	(via
		(at 187.915296 -23.127208)
		(size 0.508)
		(drill 0.254)
		(layers "F.Cu" "B.Cu")
		(net "P12V_SCM_UV")
	)
	(segment
		(start 194.6783 -33.139126)
		(end 189.488826 -38.3286)
		(width 0.10668)
		(layer "B.Cu")
		(net "P12V_SCM_UV")
	)
	(segment
		(start 194.6783 -22.97938)
		(end 194.6783 -33.139126)
		(width 0.10668)
		(layer "B.Cu")
		(net "P12V_SCM_UV")
	)
	(segment
		(start 189.488826 -38.3286)
		(end 189.488826 -40.76065)
		(width 0.10668)
		(layer "B.Cu")
		(net "P12V_SCM_UV")
	)
	(segment
		(start 187.915296 -23.127208)
		(end 188.246512 -23.127208)
		(width 0.10668)
		(layer "B.Cu")
		(net "P12V_SCM_UV")
	)
	(segment
		(start 190.2333 -21.14042)
		(end 192.83934 -21.14042)
		(width 0.10668)
		(layer "B.Cu")
		(net "P12V_SCM_UV")
	)
	(segment
		(start 188.246512 -23.127208)
		(end 190.2333 -21.14042)
		(width 0.10668)
		(layer "B.Cu")
		(net "P12V_SCM_UV")
	)
	(segment
		(start 192.83934 -21.14042)
		(end 194.6783 -22.97938)
		(width 0.10668)
		(layer "B.Cu")
		(net "P12V_SCM_UV")
	)
	(segment
		(start 189.488826 -40.76065)
		(end 189.237874 -41.011602)
		(width 0.10668)
		(layer "B.Cu")
		(net "P12V_SCM_UV")
	)
	(segment
		(start 178.193954 -30.33776)
		(end 178.193954 -31.096712)
		(width 0.10668)
		(layer "F.Cu")
		(net "P12V_SCM_TIMER")
	)
	(segment
		(start 178.996086 -31.898844)
		(end 179.058062 -31.96082)
		(width 0.10668)
		(layer "F.Cu")
		(net "P12V_SCM_TIMER")
	)
	(segment
		(start 179.058062 -31.96082)
		(end 179.058062 -32.535622)
		(width 0.10668)
		(layer "F.Cu")
		(net "P12V_SCM_TIMER")
	)
	(segment
		(start 178.193954 -31.096712)
		(end 178.996086 -31.898844)
		(width 0.10668)
		(layer "F.Cu")
		(net "P12V_SCM_TIMER")
	)
	(via
		(at 178.996086 -31.898844)
		(size 0.508)
		(drill 0.254)
		(layers "F.Cu" "B.Cu")
		(net "P12V_SCM_TIMER")
	)
	(segment
		(start 176.391062 -32.038798)
		(end 176.668684 -31.761176)
		(width 0.10668)
		(layer "F.Cu")
		(net "P12V_SCM_SS")
	)
	(segment
		(start 177.06721 -30.941264)
		(end 177.06721 -31.618682)
		(width 0.10668)
		(layer "F.Cu")
		(net "P12V_SCM_SS")
	)
	(segment
		(start 176.391062 -32.535622)
		(end 176.391062 -32.038798)
		(width 0.10668)
		(layer "F.Cu")
		(net "P12V_SCM_SS")
	)
	(segment
		(start 177.19421 -30.814264)
		(end 177.06721 -30.941264)
		(width 0.10668)
		(layer "F.Cu")
		(net "P12V_SCM_SS")
	)
	(segment
		(start 176.668684 -31.761176)
		(end 176.924716 -31.761176)
		(width 0.10668)
		(layer "F.Cu")
		(net "P12V_SCM_SS")
	)
	(segment
		(start 177.19421 -30.33776)
		(end 177.19421 -30.814264)
		(width 0.10668)
		(layer "F.Cu")
		(net "P12V_SCM_SS")
	)
	(segment
		(start 177.06721 -31.618682)
		(end 176.924716 -31.761176)
		(width 0.10668)
		(layer "F.Cu")
		(net "P12V_SCM_SS")
	)
	(via
		(at 176.924716 -31.761176)
		(size 0.762)
		(drill 0.381)
		(layers "F.Cu" "B.Cu")
		(net "P12V_SCM_SS")
	)
	(segment
		(start 186.345576 -26.772108)
		(end 186.328812 -26.788872)
		(width 0.10668)
		(layer "F.Cu")
		(net "P12V_SCM_SENSE")
	)
	(segment
		(start 187.709048 -26.393394)
		(end 187.330334 -26.772108)
		(width 0.10668)
		(layer "F.Cu")
		(net "P12V_SCM_SENSE")
	)
	(segment
		(start 187.330334 -26.772108)
		(end 186.345576 -26.772108)
		(width 0.10668)
		(layer "F.Cu")
		(net "P12V_SCM_SENSE")
	)
	(segment
		(start 188.238638 -26.393394)
		(end 187.709048 -26.393394)
		(width 0.10668)
		(layer "F.Cu")
		(net "P12V_SCM_SENSE")
	)
	(segment
		(start 186.328812 -27.36723)
		(end 186.141106 -27.554936)
		(width 0.10668)
		(layer "F.Cu")
		(net "P12V_SCM_SENSE")
	)
	(segment
		(start 186.328812 -26.788872)
		(end 186.328812 -27.36723)
		(width 0.10668)
		(layer "F.Cu")
		(net "P12V_SCM_SENSE")
	)
	(segment
		(start 186.141106 -27.554936)
		(end 185.58764 -27.554936)
		(width 0.10668)
		(layer "F.Cu")
		(net "P12V_SCM_SENSE")
	)
	(via
		(at 185.58764 -27.554936)
		(size 0.508)
		(drill 0.254)
		(layers "F.Cu" "B.Cu")
		(net "P12V_SCM_SENSE")
	)
	(segment
		(start 188.238638 -24.815038)
		(end 187.570872 -24.147272)
		(width 0.10668)
		(layer "F.Cu")
		(net "P12V_SCM_REG")
	)
	(segment
		(start 186.250072 -24.126952)
		(end 186.885834 -24.126952)
		(width 0.10668)
		(layer "F.Cu")
		(net "P12V_SCM_REG")
	)
	(segment
		(start 186.906154 -24.147272)
		(end 186.885834 -24.126952)
		(width 0.10668)
		(layer "F.Cu")
		(net "P12V_SCM_REG")
	)
	(segment
		(start 186.206892 -24.170132)
		(end 186.250072 -24.126952)
		(width 0.10668)
		(layer "F.Cu")
		(net "P12V_SCM_REG")
	)
	(segment
		(start 187.570872 -24.147272)
		(end 186.906154 -24.147272)
		(width 0.10668)
		(layer "F.Cu")
		(net "P12V_SCM_REG")
	)
	(segment
		(start 188.238638 -24.89327)
		(end 188.238638 -24.815038)
		(width 0.10668)
		(layer "F.Cu")
		(net "P12V_SCM_REG")
	)
	(via
		(at 186.885834 -24.126952)
		(size 0.508)
		(drill 0.254)
		(layers "F.Cu" "B.Cu")
		(net "P12V_SCM_REG")
	)
	(segment
		(start 192.30975 -30.269688)
		(end 193.283332 -30.269688)
		(width 0.508)
		(layer "F.Cu")
		(net "P12V_SCM_R")
	)
	(segment
		(start 194.191636 -29.361384)
		(end 194.191636 -22.780752)
		(width 0.508)
		(layer "F.Cu")
		(net "P12V_SCM_R")
	)
	(segment
		(start 191.69634 -30.269688)
		(end 192.30975 -30.269688)
		(width 0.4572)
		(layer "F.Cu")
		(net "P12V_SCM_R")
	)
	(segment
		(start 194.191636 -22.780752)
		(end 193.428112 -22.017228)
		(width 0.508)
		(layer "F.Cu")
		(net "P12V_SCM_R")
	)
	(segment
		(start 208.922874 -36.172394)
		(end 208.92262 -36.17214)
		(width 0.254)
		(layer "F.Cu")
		(net "P12V_SCM_R")
	)
	(segment
		(start 208.508854 -37.366448)
		(end 208.508854 -36.909248)
		(width 0.254)
		(layer "F.Cu")
		(net "P12V_SCM_R")
	)
	(segment
		(start 193.283332 -30.269688)
		(end 194.191636 -29.361384)
		(width 0.508)
		(layer "F.Cu")
		(net "P12V_SCM_R")
	)
	(segment
		(start 208.922874 -36.495228)
		(end 208.922874 -36.172394)
		(width 0.254)
		(layer "F.Cu")
		(net "P12V_SCM_R")
	)
	(segment
		(start 193.428112 -22.017228)
		(end 190.56096 -22.017228)
		(width 0.508)
		(layer "F.Cu")
		(net "P12V_SCM_R")
	)
	(segment
		(start 176.26711 -22.65807)
		(end 176.146968 -22.537928)
		(width 0.254)
		(layer "F.Cu")
		(net "P12V_SCM_R")
	)
	(segment
		(start 176.146968 -22.537928)
		(end 173.58487 -22.537928)
		(width 0.254)
		(layer "F.Cu")
		(net "P12V_SCM_R")
	)
	(segment
		(start 191.69634 -30.269688)
		(end 191.69634 -29.28366)
		(width 0.4572)
		(layer "F.Cu")
		(net "P12V_SCM_R")
	)
	(segment
		(start 208.508854 -36.909248)
		(end 208.922874 -36.495228)
		(width 0.254)
		(layer "F.Cu")
		(net "P12V_SCM_R")
	)
	(segment
		(start 173.58487 -22.537928)
		(end 171.664122 -24.458676)
		(width 0.4572)
		(layer "F.Cu")
		(net "P12V_SCM_R")
	)
	(segment
		(start 171.664122 -24.458676)
		(end 171.664122 -26.44394)
		(width 0.4572)
		(layer "F.Cu")
		(net "P12V_SCM_R")
	)
	(segment
		(start 191.69634 -29.28366)
		(end 191.695832 -29.283152)
		(width 0.4572)
		(layer "F.Cu")
		(net "P12V_SCM_R")
	)
	(via
		(at 176.878234 -19.942048)
		(size 0.508)
		(drill 0.254)
		(layers "F.Cu" "B.Cu")
		(net "P12V_SCM_R")
	)
	(via
		(at 190.508636 -22.856952)
		(size 0.508)
		(drill 0.254)
		(layers "F.Cu" "B.Cu")
		(net "P12V_SCM_R")
	)
	(via
		(at 198.836026 -37.965634)
		(size 0.508)
		(drill 0.254)
		(layers "F.Cu" "B.Cu")
		(net "P12V_SCM_R")
	)
	(via
		(at 178.491134 -25.949148)
		(size 0.508)
		(drill 0.254)
		(layers "F.Cu" "B.Cu")
		(net "P12V_SCM_R")
	)
	(via
		(at 190.508636 -23.593552)
		(size 0.508)
		(drill 0.254)
		(layers "F.Cu" "B.Cu")
		(net "P12V_SCM_R")
	)
	(via
		(at 176.968912 -21.349208)
		(size 0.508)
		(drill 0.254)
		(layers "F.Cu" "B.Cu")
		(net "P12V_SCM_R")
	)
	(via
		(at 176.332134 -26.634948)
		(size 0.508)
		(drill 0.254)
		(layers "F.Cu" "B.Cu")
		(net "P12V_SCM_R")
	)
	(via
		(at 180.921914 -27.107388)
		(size 0.508)
		(drill 0.254)
		(layers "F.Cu" "B.Cu")
		(net "P12V_SCM_R")
	)
	(via
		(at 208.508854 -37.366448)
		(size 0.508)
		(drill 0.254)
		(layers "F.Cu" "B.Cu")
		(net "P12V_SCM_R")
	)
	(via
		(at 177.221134 -26.634948)
		(size 0.508)
		(drill 0.254)
		(layers "F.Cu" "B.Cu")
		(net "P12V_SCM_R")
	)
	(via
		(at 177.602134 -25.949148)
		(size 0.508)
		(drill 0.254)
		(layers "F.Cu" "B.Cu")
		(net "P12V_SCM_R")
	)
	(via
		(at 177.472594 -21.85289)
		(size 0.508)
		(drill 0.254)
		(layers "F.Cu" "B.Cu")
		(net "P12V_SCM_R")
	)
	(via
		(at 176.713134 -25.949148)
		(size 0.508)
		(drill 0.254)
		(layers "F.Cu" "B.Cu")
		(net "P12V_SCM_R")
	)
	(via
		(at 198.160386 -37.328094)
		(size 0.508)
		(drill 0.254)
		(layers "F.Cu" "B.Cu")
		(net "P12V_SCM_R")
	)
	(via
		(at 179.507134 -25.517348)
		(size 0.508)
		(drill 0.254)
		(layers "F.Cu" "B.Cu")
		(net "P12V_SCM_R")
	)
	(via
		(at 176.968912 -20.714208)
		(size 0.508)
		(drill 0.254)
		(layers "F.Cu" "B.Cu")
		(net "P12V_SCM_R")
	)
	(via
		(at 178.110134 -26.634948)
		(size 0.508)
		(drill 0.254)
		(layers "F.Cu" "B.Cu")
		(net "P12V_SCM_R")
	)
	(segment
		(start 208.56448 -36.204398)
		(end 208.56448 -37.310822)
		(width 0.4572)
		(layer "B.Cu")
		(net "P12V_SCM_R")
	)
	(segment
		(start 200.159112 -36.642548)
		(end 198.836026 -37.965634)
		(width 0.4572)
		(layer "B.Cu")
		(net "P12V_SCM_R")
	)
	(segment
		(start 202.93203 -36.642548)
		(end 200.159112 -36.642548)
		(width 0.4572)
		(layer "B.Cu")
		(net "P12V_SCM_R")
	)
	(segment
		(start 208.56448 -37.310822)
		(end 208.508854 -37.366448)
		(width 0.4572)
		(layer "B.Cu")
		(net "P12V_SCM_R")
	)
	(segment
		(start 192.05575 -22.694392)
		(end 192.288922 -22.694392)
		(width 0.10668)
		(layer "F.Cu")
		(net "P12V_SCM_PWRGD")
	)
	(segment
		(start 191.714882 -24.524462)
		(end 191.714882 -23.03526)
		(width 0.10668)
		(layer "F.Cu")
		(net "P12V_SCM_PWRGD")
	)
	(segment
		(start 191.714882 -23.03526)
		(end 192.05575 -22.694392)
		(width 0.10668)
		(layer "F.Cu")
		(net "P12V_SCM_PWRGD")
	)
	(segment
		(start 191.485012 -24.89327)
		(end 191.714882 -24.6634)
		(width 0.10668)
		(layer "F.Cu")
		(net "P12V_SCM_PWRGD")
	)
	(segment
		(start 191.238886 -24.89327)
		(end 191.485012 -24.89327)
		(width 0.10668)
		(layer "F.Cu")
		(net "P12V_SCM_PWRGD")
	)
	(segment
		(start 191.714882 -24.6634)
		(end 191.714882 -24.524462)
		(width 0.10668)
		(layer "F.Cu")
		(net "P12V_SCM_PWRGD")
	)
	(via
		(at 191.714882 -24.524462)
		(size 0.508)
		(drill 0.254)
		(layers "F.Cu" "B.Cu")
		(net "P12V_SCM_PWRGD")
	)
	(segment
		(start 173.899322 -28.43784)
		(end 172.878242 -28.43784)
		(width 0.10668)
		(layer "F.Cu")
		(net "P12V_SCM_OV_FB")
	)
	(segment
		(start 172.878242 -28.43784)
		(end 171.511468 -28.43784)
		(width 0.10668)
		(layer "F.Cu")
		(net "P12V_SCM_OV_FB")
	)
	(segment
		(start 171.511468 -28.43784)
		(end 171.511468 -27.396694)
		(width 0.10668)
		(layer "F.Cu")
		(net "P12V_SCM_OV_FB")
	)
	(segment
		(start 175.294036 -28.43784)
		(end 173.899322 -28.43784)
		(width 0.10668)
		(layer "F.Cu")
		(net "P12V_SCM_OV_FB")
	)
	(segment
		(start 171.511468 -27.396694)
		(end 171.664122 -27.24404)
		(width 0.10668)
		(layer "F.Cu")
		(net "P12V_SCM_OV_FB")
	)
	(via
		(at 171.511468 -28.43784)
		(size 0.762)
		(drill 0.381)
		(layers "F.Cu" "B.Cu")
		(net "P12V_SCM_OV_FB")
	)
	(segment
		(start 187.221622 -22.327108)
		(end 186.428888 -22.327108)
		(width 0.10668)
		(layer "F.Cu")
		(net "P12V_SCM_OV")
	)
	(segment
		(start 188.4299 -22.60854)
		(end 189.23889 -23.41753)
		(width 0.10668)
		(layer "F.Cu")
		(net "P12V_SCM_OV")
	)
	(segment
		(start 189.23889 -23.41753)
		(end 189.23889 -24.89327)
		(width 0.10668)
		(layer "F.Cu")
		(net "P12V_SCM_OV")
	)
	(segment
		(start 188.226192 -22.327108)
		(end 188.4299 -22.1234)
		(width 0.10668)
		(layer "F.Cu")
		(net "P12V_SCM_OV")
	)
	(segment
		(start 188.4299 -22.1234)
		(end 188.4299 -22.60854)
		(width 0.10668)
		(layer "F.Cu")
		(net "P12V_SCM_OV")
	)
	(segment
		(start 186.428888 -22.327108)
		(end 186.199272 -22.097492)
		(width 0.10668)
		(layer "F.Cu")
		(net "P12V_SCM_OV")
	)
	(segment
		(start 187.221622 -22.327108)
		(end 188.226192 -22.327108)
		(width 0.10668)
		(layer "F.Cu")
		(net "P12V_SCM_OV")
	)
	(via
		(at 188.4299 -22.1234)
		(size 0.762)
		(drill 0.381)
		(layers "F.Cu" "B.Cu")
		(net "P12V_SCM_OV")
	)
	(via
		(at 178.097434 -33.264602)
		(size 0.6604)
		(drill 0.3302)
		(layers "F.Cu" "B.Cu")
		(net "P12V_SCM_ISET_R")
	)
	(segment
		(start 179.793646 -33.088072)
		(end 179.679346 -33.088072)
		(width 0.10668)
		(layer "B.Cu")
		(net "P12V_SCM_ISET_R")
	)
	(segment
		(start 176.754028 -33.006538)
		(end 176.285398 -32.537908)
		(width 0.10668)
		(layer "B.Cu")
		(net "P12V_SCM_ISET_R")
	)
	(segment
		(start 179.584604 -32.99333)
		(end 179.177696 -32.99333)
		(width 0.10668)
		(layer "B.Cu")
		(net "P12V_SCM_ISET_R")
	)
	(segment
		(start 179.177696 -32.99333)
		(end 178.906424 -33.264602)
		(width 0.10668)
		(layer "B.Cu")
		(net "P12V_SCM_ISET_R")
	)
	(segment
		(start 178.906424 -33.264602)
		(end 178.097434 -33.264602)
		(width 0.10668)
		(layer "B.Cu")
		(net "P12V_SCM_ISET_R")
	)
	(segment
		(start 177.83937 -33.006538)
		(end 176.754028 -33.006538)
		(width 0.10668)
		(layer "B.Cu")
		(net "P12V_SCM_ISET_R")
	)
	(segment
		(start 179.679346 -33.088072)
		(end 179.584604 -32.99333)
		(width 0.10668)
		(layer "B.Cu")
		(net "P12V_SCM_ISET_R")
	)
	(segment
		(start 176.285398 -32.537908)
		(end 176.264316 -32.537908)
		(width 0.10668)
		(layer "B.Cu")
		(net "P12V_SCM_ISET_R")
	)
	(segment
		(start 178.097434 -33.264602)
		(end 177.83937 -33.006538)
		(width 0.10668)
		(layer "B.Cu")
		(net "P12V_SCM_ISET_R")
	)
	(segment
		(start 177.694082 -31.364682)
		(end 177.694082 -30.33776)
		(width 0.10668)
		(layer "F.Cu")
		(net "P12V_SCM_ISET")
	)
	(segment
		(start 177.694082 -32.200342)
		(end 177.694082 -31.705296)
		(width 0.10668)
		(layer "F.Cu")
		(net "P12V_SCM_ISET")
	)
	(segment
		(start 178.044602 -32.550862)
		(end 177.694082 -32.200342)
		(width 0.10668)
		(layer "F.Cu")
		(net "P12V_SCM_ISET")
	)
	(segment
		(start 177.647092 -31.411672)
		(end 177.694082 -31.364682)
		(width 0.10668)
		(layer "F.Cu")
		(net "P12V_SCM_ISET")
	)
	(segment
		(start 177.694082 -31.705296)
		(end 177.647092 -31.658306)
		(width 0.10668)
		(layer "F.Cu")
		(net "P12V_SCM_ISET")
	)
	(segment
		(start 177.647092 -31.658306)
		(end 177.647092 -31.411672)
		(width 0.10668)
		(layer "F.Cu")
		(net "P12V_SCM_ISET")
	)
	(via
		(at 177.647092 -31.411672)
		(size 0.508)
		(drill 0.254)
		(layers "F.Cu" "B.Cu")
		(net "P12V_SCM_ISET")
	)
	(segment
		(start 176.264316 -31.737808)
		(end 176.287684 -31.761176)
		(width 0.10668)
		(layer "B.Cu")
		(net "P12V_SCM_ISET")
	)
	(segment
		(start 176.287684 -31.761176)
		(end 177.297588 -31.761176)
		(width 0.10668)
		(layer "B.Cu")
		(net "P12V_SCM_ISET")
	)
	(segment
		(start 177.297588 -31.761176)
		(end 177.647092 -31.411672)
		(width 0.10668)
		(layer "B.Cu")
		(net "P12V_SCM_ISET")
	)
	(segment
		(start 176.194212 -30.754574)
		(end 176.194212 -30.338014)
		(width 0.254)
		(layer "F.Cu")
		(net "P12V_SCM_IMON")
	)
	(segment
		(start 174.613062 -32.535622)
		(end 173.597062 -32.535622)
		(width 0.254)
		(layer "F.Cu")
		(net "P12V_SCM_IMON")
	)
	(segment
		(start 173.597062 -32.535622)
		(end 172.230288 -32.535622)
		(width 0.254)
		(layer "F.Cu")
		(net "P12V_SCM_IMON")
	)
	(segment
		(start 176.194212 -30.338014)
		(end 176.193958 -30.33776)
		(width 0.254)
		(layer "F.Cu")
		(net "P12V_SCM_IMON")
	)
	(segment
		(start 174.613062 -32.335724)
		(end 176.194212 -30.754574)
		(width 0.254)
		(layer "F.Cu")
		(net "P12V_SCM_IMON")
	)
	(segment
		(start 174.613062 -32.535622)
		(end 174.613062 -32.335724)
		(width 0.254)
		(layer "F.Cu")
		(net "P12V_SCM_IMON")
	)
	(via
		(at 172.230288 -32.535622)
		(size 0.762)
		(drill 0.381)
		(layers "F.Cu" "B.Cu")
		(net "P12V_SCM_IMON")
	)
	(segment
		(start 190.895732 -29.283152)
		(end 190.895732 -28.267152)
		(width 0.10668)
		(layer "F.Cu")
		(net "P12V_SCM_GATE")
	)
	(segment
		(start 190.625984 -27.139138)
		(end 190.678054 -27.087068)
		(width 0.10668)
		(layer "F.Cu")
		(net "P12V_SCM_GATE")
	)
	(segment
		(start 190.89624 -30.269688)
		(end 190.89624 -29.28366)
		(width 0.10668)
		(layer "F.Cu")
		(net "P12V_SCM_GATE")
	)
	(segment
		(start 190.73876 -26.393394)
		(end 190.73876 -27.026362)
		(width 0.10668)
		(layer "F.Cu")
		(net "P12V_SCM_GATE")
	)
	(segment
		(start 190.89624 -29.28366)
		(end 190.895732 -29.283152)
		(width 0.10668)
		(layer "F.Cu")
		(net "P12V_SCM_GATE")
	)
	(segment
		(start 190.625984 -27.979624)
		(end 190.625984 -27.139138)
		(width 0.10668)
		(layer "F.Cu")
		(net "P12V_SCM_GATE")
	)
	(segment
		(start 190.73876 -27.026362)
		(end 190.678054 -27.087068)
		(width 0.10668)
		(layer "F.Cu")
		(net "P12V_SCM_GATE")
	)
	(segment
		(start 190.895732 -28.267152)
		(end 190.895732 -28.249372)
		(width 0.10668)
		(layer "F.Cu")
		(net "P12V_SCM_GATE")
	)
	(segment
		(start 190.895732 -28.249372)
		(end 190.625984 -27.979624)
		(width 0.10668)
		(layer "F.Cu")
		(net "P12V_SCM_GATE")
	)
	(via
		(at 190.678054 -27.087068)
		(size 0.508)
		(drill 0.254)
		(layers "F.Cu" "B.Cu")
		(net "P12V_SCM_GATE")
	)
	(segment
		(start 179.694078 -30.312614)
		(end 179.694078 -30.641798)
		(width 0.10668)
		(layer "F.Cu")
		(net "P12V_SCM_EN_R2")
	)
	(segment
		(start 180.074062 -31.021782)
		(end 180.074062 -32.535622)
		(width 0.10668)
		(layer "F.Cu")
		(net "P12V_SCM_EN_R2")
	)
	(segment
		(start 180.074062 -32.535622)
		(end 180.934614 -32.535622)
		(width 0.10668)
		(layer "F.Cu")
		(net "P12V_SCM_EN_R2")
	)
	(segment
		(start 179.694078 -30.641798)
		(end 180.074062 -31.021782)
		(width 0.10668)
		(layer "F.Cu")
		(net "P12V_SCM_EN_R2")
	)
	(via
		(at 180.934614 -32.535622)
		(size 0.508)
		(drill 0.254)
		(layers "F.Cu" "B.Cu")
		(net "P12V_SCM_EN_R2")
	)
	(segment
		(start 195.25615 -43.199558)
		(end 196.567552 -43.199558)
		(width 0.10668)
		(layer "F.Cu")
		(net "P12V_SCM_EN_R")
	)
	(segment
		(start 196.81063 -42.95648)
		(end 196.570854 -43.196256)
		(width 0.10668)
		(layer "F.Cu")
		(net "P12V_SCM_EN_R")
	)
	(segment
		(start 196.567552 -43.199558)
		(end 196.570854 -43.196256)
		(width 0.10668)
		(layer "F.Cu")
		(net "P12V_SCM_EN_R")
	)
	(segment
		(start 196.81063 -41.466516)
		(end 196.81063 -42.95648)
		(width 0.10668)
		(layer "F.Cu")
		(net "P12V_SCM_EN_R")
	)
	(via
		(at 196.570854 -43.196256)
		(size 0.762)
		(drill 0.381)
		(layers "F.Cu" "B.Cu")
		(net "P12V_SCM_EN_R")
	)
	(segment
		(start 190.82385 -42.554398)
		(end 191.230504 -42.554398)
		(width 0.10668)
		(layer "F.Cu")
		(net "P12V_SCM_EN_G")
	)
	(segment
		(start 192.77203 -42.549572)
		(end 191.998854 -43.322748)
		(width 0.10668)
		(layer "F.Cu")
		(net "P12V_SCM_EN_G")
	)
	(segment
		(start 193.741548 -43.199558)
		(end 193.35623 -43.199558)
		(width 0.10668)
		(layer "F.Cu")
		(net "P12V_SCM_EN_G")
	)
	(segment
		(start 193.35623 -42.549572)
		(end 192.77203 -42.549572)
		(width 0.10668)
		(layer "F.Cu")
		(net "P12V_SCM_EN_G")
	)
	(segment
		(start 193.900806 -42.625264)
		(end 193.900806 -43.0403)
		(width 0.10668)
		(layer "F.Cu")
		(net "P12V_SCM_EN_G")
	)
	(segment
		(start 191.230504 -42.554398)
		(end 191.998854 -43.322748)
		(width 0.10668)
		(layer "F.Cu")
		(net "P12V_SCM_EN_G")
	)
	(segment
		(start 193.900806 -43.0403)
		(end 193.741548 -43.199558)
		(width 0.10668)
		(layer "F.Cu")
		(net "P12V_SCM_EN_G")
	)
	(segment
		(start 193.825114 -42.549572)
		(end 193.900806 -42.625264)
		(width 0.10668)
		(layer "F.Cu")
		(net "P12V_SCM_EN_G")
	)
	(segment
		(start 193.35623 -42.549572)
		(end 193.825114 -42.549572)
		(width 0.10668)
		(layer "F.Cu")
		(net "P12V_SCM_EN_G")
	)
	(via
		(at 191.998854 -43.322748)
		(size 0.762)
		(drill 0.381)
		(layers "F.Cu" "B.Cu")
		(net "P12V_SCM_EN_G")
	)
	(segment
		(start 191.389254 -37.834824)
		(end 190.13043 -36.576)
		(width 0.10668)
		(layer "F.Cu")
		(net "P12V_SCM_EN")
	)
	(segment
		(start 187.821824 -35.802824)
		(end 185.117486 -35.802824)
		(width 0.10668)
		(layer "F.Cu")
		(net "P12V_SCM_EN")
	)
	(segment
		(start 197.61073 -41.466516)
		(end 197.61073 -40.171878)
		(width 0.10668)
		(layer "F.Cu")
		(net "P12V_SCM_EN")
	)
	(segment
		(start 197.577456 -40.138604)
		(end 197.577456 -39.050468)
		(width 0.10668)
		(layer "F.Cu")
		(net "P12V_SCM_EN")
	)
	(segment
		(start 180.62194 -33.44418)
		(end 180.513482 -33.335722)
		(width 0.10668)
		(layer "F.Cu")
		(net "P12V_SCM_EN")
	)
	(segment
		(start 180.513482 -33.335722)
		(end 180.074062 -33.335722)
		(width 0.10668)
		(layer "F.Cu")
		(net "P12V_SCM_EN")
	)
	(segment
		(start 197.581012 -39.046912)
		(end 197.581012 -39.046658)
		(width 0.10668)
		(layer "F.Cu")
		(net "P12V_SCM_EN")
	)
	(segment
		(start 181.807866 -35.814)
		(end 180.62194 -34.628074)
		(width 0.10668)
		(layer "F.Cu")
		(net "P12V_SCM_EN")
	)
	(segment
		(start 197.577456 -39.050468)
		(end 197.581012 -39.046912)
		(width 0.10668)
		(layer "F.Cu")
		(net "P12V_SCM_EN")
	)
	(segment
		(start 190.13043 -36.576)
		(end 188.595 -36.576)
		(width 0.10668)
		(layer "F.Cu")
		(net "P12V_SCM_EN")
	)
	(segment
		(start 183.007 -35.814)
		(end 181.807866 -35.814)
		(width 0.10668)
		(layer "F.Cu")
		(net "P12V_SCM_EN")
	)
	(segment
		(start 197.61073 -40.171878)
		(end 197.577456 -40.138604)
		(width 0.10668)
		(layer "F.Cu")
		(net "P12V_SCM_EN")
	)
	(segment
		(start 197.581012 -39.046658)
		(end 196.967602 -38.433248)
		(width 0.10668)
		(layer "F.Cu")
		(net "P12V_SCM_EN")
	)
	(segment
		(start 184.34431 -36.576)
		(end 183.769 -36.576)
		(width 0.10668)
		(layer "F.Cu")
		(net "P12V_SCM_EN")
	)
	(segment
		(start 191.389254 -38.433248)
		(end 191.389254 -37.834824)
		(width 0.10668)
		(layer "F.Cu")
		(net "P12V_SCM_EN")
	)
	(segment
		(start 196.967602 -38.433248)
		(end 193.809366 -38.433248)
		(width 0.10668)
		(layer "F.Cu")
		(net "P12V_SCM_EN")
	)
	(segment
		(start 185.117486 -35.802824)
		(end 184.34431 -36.576)
		(width 0.10668)
		(layer "F.Cu")
		(net "P12V_SCM_EN")
	)
	(segment
		(start 191.389254 -38.433248)
		(end 193.809366 -38.433248)
		(width 0.10668)
		(layer "F.Cu")
		(net "P12V_SCM_EN")
	)
	(segment
		(start 180.62194 -34.628074)
		(end 180.62194 -33.44418)
		(width 0.10668)
		(layer "F.Cu")
		(net "P12V_SCM_EN")
	)
	(segment
		(start 188.595 -36.576)
		(end 187.821824 -35.802824)
		(width 0.10668)
		(layer "F.Cu")
		(net "P12V_SCM_EN")
	)
	(segment
		(start 183.769 -36.576)
		(end 183.007 -35.814)
		(width 0.10668)
		(layer "F.Cu")
		(net "P12V_SCM_EN")
	)
	(via
		(at 191.389254 -38.433248)
		(size 0.762)
		(drill 0.381)
		(layers "F.Cu" "B.Cu")
		(net "P12V_SCM_EN")
	)
	(segment
		(start 188.238638 -25.893268)
		(end 187.212732 -25.893268)
		(width 0.10668)
		(layer "F.Cu")
		(net "P12V_SCM_CB")
	)
	(segment
		(start 187.012072 -25.899872)
		(end 186.328812 -25.899872)
		(width 0.10668)
		(layer "F.Cu")
		(net "P12V_SCM_CB")
	)
	(segment
		(start 187.212732 -25.893268)
		(end 187.1091 -25.9969)
		(width 0.10668)
		(layer "F.Cu")
		(net "P12V_SCM_CB")
	)
	(segment
		(start 187.1091 -25.9969)
		(end 187.012072 -25.899872)
		(width 0.10668)
		(layer "F.Cu")
		(net "P12V_SCM_CB")
	)
	(via
		(at 187.1091 -25.9969)
		(size 0.508)
		(drill 0.254)
		(layers "F.Cu" "B.Cu")
		(net "P12V_SCM_CB")
	)
	(segment
		(start 174.297594 -23.238968)
		(end 175.438308 -23.238968)
		(width 0.10668)
		(layer "F.Cu")
		(net "P12V_SCM_AVIN_PD")
	)
	(segment
		(start 175.438308 -23.238968)
		(end 175.483012 -23.283672)
		(width 0.10668)
		(layer "F.Cu")
		(net "P12V_SCM_AVIN_PD")
	)
	(via
		(at 174.297594 -23.238968)
		(size 0.762)
		(drill 0.381)
		(layers "F.Cu" "B.Cu")
		(net "P12V_SCM_AVIN_PD")
	)
	(via
		(at 193.096134 -15.781528)
		(size 0.508)
		(drill 0.254)
		(layers "F.Cu" "B.Cu")
		(net "P12V_SCM")
	)
	(via
		(at 199.756014 -30.133798)
		(size 0.508)
		(drill 0.254)
		(layers "F.Cu" "B.Cu")
		(net "P12V_SCM")
	)
	(via
		(at 193.858134 -16.543528)
		(size 0.508)
		(drill 0.254)
		(layers "F.Cu" "B.Cu")
		(net "P12V_SCM")
	)
	(via
		(at 199.435974 -30.720538)
		(size 0.508)
		(drill 0.254)
		(layers "F.Cu" "B.Cu")
		(net "P12V_SCM")
	)
	(via
		(at 200.070974 -30.720538)
		(size 0.508)
		(drill 0.254)
		(layers "F.Cu" "B.Cu")
		(net "P12V_SCM")
	)
	(via
		(at 199.121014 -30.133798)
		(size 0.508)
		(drill 0.254)
		(layers "F.Cu" "B.Cu")
		(net "P12V_SCM")
	)
	(via
		(at 192.461134 -16.416528)
		(size 0.508)
		(drill 0.254)
		(layers "F.Cu" "B.Cu")
		(net "P12V_SCM")
	)
	(via
		(at 193.731134 -15.781528)
		(size 0.508)
		(drill 0.254)
		(layers "F.Cu" "B.Cu")
		(net "P12V_SCM")
	)
	(via
		(at 191.927734 -13.106908)
		(size 0.508)
		(drill 0.254)
		(layers "F.Cu" "B.Cu")
		(net "P12V_SCM")
	)
	(via
		(at 192.689734 -13.106908)
		(size 0.508)
		(drill 0.254)
		(layers "F.Cu" "B.Cu")
		(net "P12V_SCM")
	)
	(via
		(at 192.461134 -15.781528)
		(size 0.508)
		(drill 0.254)
		(layers "F.Cu" "B.Cu")
		(net "P12V_SCM")
	)
	(via
		(at 198.486014 -30.133798)
		(size 0.508)
		(drill 0.254)
		(layers "F.Cu" "B.Cu")
		(net "P12V_SCM")
	)
	(via
		(at 193.096134 -16.416528)
		(size 0.508)
		(drill 0.254)
		(layers "F.Cu" "B.Cu")
		(net "P12V_SCM")
	)
	(via
		(at 200.391014 -30.133798)
		(size 0.508)
		(drill 0.254)
		(layers "F.Cu" "B.Cu")
		(net "P12V_SCM")
	)
	(via
		(at 200.705974 -30.720538)
		(size 0.508)
		(drill 0.254)
		(layers "F.Cu" "B.Cu")
		(net "P12V_SCM")
	)
	(via
		(at 201.340974 -30.720538)
		(size 0.508)
		(drill 0.254)
		(layers "F.Cu" "B.Cu")
		(net "P12V_SCM")
	)
	(segment
		(start 199.390508 -34.089848)
		(end 199.390508 -30.766004)
		(width 0.4572)
		(layer "B.Cu")
		(net "P12V_SCM")
	)
	(segment
		(start 202.273662 -34.71418)
		(end 200.01484 -34.71418)
		(width 0.4572)
		(layer "B.Cu")
		(net "P12V_SCM")
	)
	(segment
		(start 199.390508 -30.766004)
		(end 199.435974 -30.720538)
		(width 0.4572)
		(layer "B.Cu")
		(net "P12V_SCM")
	)
	(segment
		(start 202.93203 -35.372548)
		(end 202.273662 -34.71418)
		(width 0.4572)
		(layer "B.Cu")
		(net "P12V_SCM")
	)
	(segment
		(start 200.01484 -34.71418)
		(end 199.390508 -34.089848)
		(width 0.4572)
		(layer "B.Cu")
		(net "P12V_SCM")
	)
	(segment
		(start 264.76833 -419.628828)
		(end 264.76833 -418.169598)
		(width 0.381)
		(layer "F.Cu")
		(net "P12V_PSU_FUSE")
	)
	(segment
		(start 264.801858 -418.13607)
		(end 254.395478 -418.13607)
		(width 0.381)
		(layer "F.Cu")
		(net "P12V_PSU_FUSE")
	)
	(segment
		(start 254.395478 -418.13607)
		(end 253.982728 -417.72332)
		(width 0.381)
		(layer "F.Cu")
		(net "P12V_PSU_FUSE")
	)
	(segment
		(start 264.76833 -418.169598)
		(end 264.801858 -418.13607)
		(width 0.381)
		(layer "F.Cu")
		(net "P12V_PSU_FUSE")
	)
	(segment
		(start 197.999858 -378.160534)
		(end 200.33234 -378.160534)
		(width 0.4572)
		(layer "F.Cu")
		(net "P12V_PSU")
	)
	(via
		(at 242.19408 -401.21078)
		(size 0.508)
		(drill 0.254)
		(layers "F.Cu" "B.Cu")
		(net "P12V_PSU")
	)
	(via
		(at 208.782158 -401.920202)
		(size 0.508)
		(drill 0.254)
		(layers "F.Cu" "B.Cu")
		(net "P12V_PSU")
	)
	(via
		(at 269.295626 -401.290282)
		(size 0.508)
		(drill 0.254)
		(layers "F.Cu" "B.Cu")
		(net "P12V_PSU")
	)
	(via
		(at 201.0537 -405.773382)
		(size 0.508)
		(drill 0.254)
		(layers "F.Cu" "B.Cu")
		(net "P12V_PSU")
	)
	(via
		(at 254.04064 -398.19834)
		(size 0.508)
		(drill 0.254)
		(layers "F.Cu" "B.Cu")
		(net "P12V_PSU")
	)
	(via
		(at 262.0645 -401.24634)
		(size 0.508)
		(drill 0.254)
		(layers "F.Cu" "B.Cu")
		(net "P12V_PSU")
	)
	(via
		(at 246.00408 -398.92478)
		(size 0.508)
		(drill 0.254)
		(layers "F.Cu" "B.Cu")
		(net "P12V_PSU")
	)
	(via
		(at 275.691346 -403.616922)
		(size 0.508)
		(drill 0.254)
		(layers "F.Cu" "B.Cu")
		(net "P12V_PSU")
	)
	(via
		(at 187.959492 -406.517602)
		(size 0.508)
		(drill 0.254)
		(layers "F.Cu" "B.Cu")
		(net "P12V_PSU")
	)
	(via
		(at 270.057626 -400.528282)
		(size 0.508)
		(drill 0.254)
		(layers "F.Cu" "B.Cu")
		(net "P12V_PSU")
	)
	(via
		(at 246.00408 -398.16278)
		(size 0.508)
		(drill 0.254)
		(layers "F.Cu" "B.Cu")
		(net "P12V_PSU")
	)
	(via
		(at 223.1517 -408.059382)
		(size 0.508)
		(drill 0.254)
		(layers "F.Cu" "B.Cu")
		(net "P12V_PSU")
	)
	(via
		(at 208.6737 -406.535382)
		(size 0.508)
		(drill 0.254)
		(layers "F.Cu" "B.Cu")
		(net "P12V_PSU")
	)
	(via
		(at 245.24208 -399.68678)
		(size 0.508)
		(drill 0.254)
		(layers "F.Cu" "B.Cu")
		(net "P12V_PSU")
	)
	(via
		(at 198.7677 -405.011382)
		(size 0.508)
		(drill 0.254)
		(layers "F.Cu" "B.Cu")
		(net "P12V_PSU")
	)
	(via
		(at 230.0097 -408.059382)
		(size 0.508)
		(drill 0.254)
		(layers "F.Cu" "B.Cu")
		(net "P12V_PSU")
	)
	(via
		(at 233.0577 -406.535382)
		(size 0.508)
		(drill 0.254)
		(layers "F.Cu" "B.Cu")
		(net "P12V_PSU")
	)
	(via
		(at 260.5405 -403.53234)
		(size 0.508)
		(drill 0.254)
		(layers "F.Cu" "B.Cu")
		(net "P12V_PSU")
	)
	(via
		(at 258.2545 -400.48434)
		(size 0.508)
		(drill 0.254)
		(layers "F.Cu" "B.Cu")
		(net "P12V_PSU")
	)
	(via
		(at 199.5297 -408.059382)
		(size 0.508)
		(drill 0.254)
		(layers "F.Cu" "B.Cu")
		(net "P12V_PSU")
	)
	(via
		(at 229.2477 -408.059382)
		(size 0.508)
		(drill 0.254)
		(layers "F.Cu" "B.Cu")
		(net "P12V_PSU")
	)
	(via
		(at 197.2437 -407.297382)
		(size 0.508)
		(drill 0.254)
		(layers "F.Cu" "B.Cu")
		(net "P12V_PSU")
	)
	(via
		(at 198.0057 -408.059382)
		(size 0.508)
		(drill 0.254)
		(layers "F.Cu" "B.Cu")
		(net "P12V_PSU")
	)
	(via
		(at 269.295626 -399.766282)
		(size 0.508)
		(drill 0.254)
		(layers "F.Cu" "B.Cu")
		(net "P12V_PSU")
	)
	(via
		(at 259.0165 -403.53234)
		(size 0.508)
		(drill 0.254)
		(layers "F.Cu" "B.Cu")
		(net "P12V_PSU")
	)
	(via
		(at 231.5337 -405.773382)
		(size 0.508)
		(drill 0.254)
		(layers "F.Cu" "B.Cu")
		(net "P12V_PSU")
	)
	(via
		(at 198.0057 -405.011382)
		(size 0.508)
		(drill 0.254)
		(layers "F.Cu" "B.Cu")
		(net "P12V_PSU")
	)
	(via
		(at 253.27864 -402.00834)
		(size 0.508)
		(drill 0.254)
		(layers "F.Cu" "B.Cu")
		(net "P12V_PSU")
	)
	(via
		(at 269.295626 -402.052282)
		(size 0.508)
		(drill 0.254)
		(layers "F.Cu" "B.Cu")
		(net "P12V_PSU")
	)
	(via
		(at 222.3897 -405.773382)
		(size 0.508)
		(drill 0.254)
		(layers "F.Cu" "B.Cu")
		(net "P12V_PSU")
	)
	(via
		(at 253.27864 -401.24634)
		(size 0.508)
		(drill 0.254)
		(layers "F.Cu" "B.Cu")
		(net "P12V_PSU")
	)
	(via
		(at 232.2957 -408.059382)
		(size 0.508)
		(drill 0.254)
		(layers "F.Cu" "B.Cu")
		(net "P12V_PSU")
	)
	(via
		(at 254.04064 -402.77034)
		(size 0.508)
		(drill 0.254)
		(layers "F.Cu" "B.Cu")
		(net "P12V_PSU")
	)
	(via
		(at 253.27864 -402.77034)
		(size 0.508)
		(drill 0.254)
		(layers "F.Cu" "B.Cu")
		(net "P12V_PSU")
	)
	(via
		(at 220.8657 -407.297382)
		(size 0.508)
		(drill 0.254)
		(layers "F.Cu" "B.Cu")
		(net "P12V_PSU")
	)
	(via
		(at 252.51664 -398.19834)
		(size 0.508)
		(drill 0.254)
		(layers "F.Cu" "B.Cu")
		(net "P12V_PSU")
	)
	(via
		(at 250.23064 -399.72234)
		(size 0.508)
		(drill 0.254)
		(layers "F.Cu" "B.Cu")
		(net "P12V_PSU")
	)
	(via
		(at 184.85612 -401.919694)
		(size 0.508)
		(drill 0.254)
		(layers "F.Cu" "B.Cu")
		(net "P12V_PSU")
	)
	(via
		(at 188.721492 -408.092402)
		(size 0.508)
		(drill 0.254)
		(layers "F.Cu" "B.Cu")
		(net "P12V_PSU")
	)
	(via
		(at 251.75464 -402.00834)
		(size 0.508)
		(drill 0.254)
		(layers "F.Cu" "B.Cu")
		(net "P12V_PSU")
	)
	(via
		(at 277.215346 -399.044922)
		(size 0.508)
		(drill 0.254)
		(layers "F.Cu" "B.Cu")
		(net "P12V_PSU")
	)
	(via
		(at 245.24208 -398.16278)
		(size 0.508)
		(drill 0.254)
		(layers "F.Cu" "B.Cu")
		(net "P12V_PSU")
	)
	(via
		(at 198.7677 -406.535382)
		(size 0.508)
		(drill 0.254)
		(layers "F.Cu" "B.Cu")
		(net "P12V_PSU")
	)
	(via
		(at 278.739346 -400.568922)
		(size 0.508)
		(drill 0.254)
		(layers "F.Cu" "B.Cu")
		(net "P12V_PSU")
	)
	(via
		(at 268.533626 -402.052282)
		(size 0.508)
		(drill 0.254)
		(layers "F.Cu" "B.Cu")
		(net "P12V_PSU")
	)
	(via
		(at 275.691346 -401.330922)
		(size 0.508)
		(drill 0.254)
		(layers "F.Cu" "B.Cu")
		(net "P12V_PSU")
	)
	(via
		(at 242.19408 -401.97278)
		(size 0.508)
		(drill 0.254)
		(layers "F.Cu" "B.Cu")
		(net "P12V_PSU")
	)
	(via
		(at 269.295626 -399.004282)
		(size 0.508)
		(drill 0.254)
		(layers "F.Cu" "B.Cu")
		(net "P12V_PSU")
	)
	(via
		(at 210.1977 -408.059382)
		(size 0.508)
		(drill 0.254)
		(layers "F.Cu" "B.Cu")
		(net "P12V_PSU")
	)
	(via
		(at 220.8657 -405.011382)
		(size 0.508)
		(drill 0.254)
		(layers "F.Cu" "B.Cu")
		(net "P12V_PSU")
	)
	(via
		(at 253.27864 -400.48434)
		(size 0.508)
		(drill 0.254)
		(layers "F.Cu" "B.Cu")
		(net "P12V_PSU")
	)
	(via
		(at 221.6277 -405.011382)
		(size 0.508)
		(drill 0.254)
		(layers "F.Cu" "B.Cu")
		(net "P12V_PSU")
	)
	(via
		(at 275.691346 -399.806922)
		(size 0.508)
		(drill 0.254)
		(layers "F.Cu" "B.Cu")
		(net "P12V_PSU")
	)
	(via
		(at 230.118158 -403.223222)
		(size 0.508)
		(drill 0.254)
		(layers "F.Cu" "B.Cu")
		(net "P12V_PSU")
	)
	(via
		(at 232.2957 -405.773382)
		(size 0.508)
		(drill 0.254)
		(layers "F.Cu" "B.Cu")
		(net "P12V_PSU")
	)
	(via
		(at 241.43208 -401.97278)
		(size 0.508)
		(drill 0.254)
		(layers "F.Cu" "B.Cu")
		(net "P12V_PSU")
	)
	(via
		(at 186.435492 -406.517602)
		(size 0.508)
		(drill 0.254)
		(layers "F.Cu" "B.Cu")
		(net "P12V_PSU")
	)
	(via
		(at 277.977346 -403.616922)
		(size 0.508)
		(drill 0.254)
		(layers "F.Cu" "B.Cu")
		(net "P12V_PSU")
	)
	(via
		(at 220.1037 -405.773382)
		(size 0.508)
		(drill 0.254)
		(layers "F.Cu" "B.Cu")
		(net "P12V_PSU")
	)
	(via
		(at 197.2437 -405.773382)
		(size 0.508)
		(drill 0.254)
		(layers "F.Cu" "B.Cu")
		(net "P12V_PSU")
	)
	(via
		(at 241.43208 -402.73478)
		(size 0.508)
		(drill 0.254)
		(layers "F.Cu" "B.Cu")
		(net "P12V_PSU")
	)
	(via
		(at 270.057626 -402.814282)
		(size 0.508)
		(drill 0.254)
		(layers "F.Cu" "B.Cu")
		(net "P12V_PSU")
	)
	(via
		(at 198.0057 -405.773382)
		(size 0.508)
		(drill 0.254)
		(layers "F.Cu" "B.Cu")
		(net "P12V_PSU")
	)
	(via
		(at 199.5297 -405.773382)
		(size 0.508)
		(drill 0.254)
		(layers "F.Cu" "B.Cu")
		(net "P12V_PSU")
	)
	(via
		(at 210.1977 -405.773382)
		(size 0.508)
		(drill 0.254)
		(layers "F.Cu" "B.Cu")
		(net "P12V_PSU")
	)
	(via
		(at 269.295626 -402.814282)
		(size 0.508)
		(drill 0.254)
		(layers "F.Cu" "B.Cu")
		(net "P12V_PSU")
	)
	(via
		(at 186.27852 -400.616674)
		(size 0.508)
		(drill 0.254)
		(layers "F.Cu" "B.Cu")
		(net "P12V_PSU")
	)
	(via
		(at 211.601558 -400.617182)
		(size 0.508)
		(drill 0.254)
		(layers "F.Cu" "B.Cu")
		(net "P12V_PSU")
	)
	(via
		(at 250.99264 -402.00834)
		(size 0.508)
		(drill 0.254)
		(layers "F.Cu" "B.Cu")
		(net "P12V_PSU")
	)
	(via
		(at 250.23064 -398.19834)
		(size 0.508)
		(drill 0.254)
		(layers "F.Cu" "B.Cu")
		(net "P12V_PSU")
	)
	(via
		(at 200.2917 -407.297382)
		(size 0.508)
		(drill 0.254)
		(layers "F.Cu" "B.Cu")
		(net "P12V_PSU")
	)
	(via
		(at 252.51664 -401.24634)
		(size 0.508)
		(drill 0.254)
		(layers "F.Cu" "B.Cu")
		(net "P12V_PSU")
	)
	(via
		(at 221.6277 -405.773382)
		(size 0.508)
		(drill 0.254)
		(layers "F.Cu" "B.Cu")
		(net "P12V_PSU")
	)
	(via
		(at 258.2545 -402.77034)
		(size 0.508)
		(drill 0.254)
		(layers "F.Cu" "B.Cu")
		(net "P12V_PSU")
	)
	(via
		(at 221.095062 -410.581602)
		(size 0.762)
		(drill 0.381)
		(layers "F.Cu" "B.Cu")
		(net "P12V_PSU")
	)
	(via
		(at 244.48008 -401.97278)
		(size 0.508)
		(drill 0.254)
		(layers "F.Cu" "B.Cu")
		(net "P12V_PSU")
	)
	(via
		(at 244.48008 -402.73478)
		(size 0.508)
		(drill 0.254)
		(layers "F.Cu" "B.Cu")
		(net "P12V_PSU")
	)
	(via
		(at 268.533626 -399.766282)
		(size 0.508)
		(drill 0.254)
		(layers "F.Cu" "B.Cu")
		(net "P12V_PSU")
	)
	(via
		(at 184.85612 -400.616674)
		(size 0.508)
		(drill 0.254)
		(layers "F.Cu" "B.Cu")
		(net "P12V_PSU")
	)
	(via
		(at 187.67552 -400.616674)
		(size 0.508)
		(drill 0.254)
		(layers "F.Cu" "B.Cu")
		(net "P12V_PSU")
	)
	(via
		(at 270.819626 -403.576282)
		(size 0.508)
		(drill 0.254)
		(layers "F.Cu" "B.Cu")
		(net "P12V_PSU")
	)
	(via
		(at 246.00408 -400.44878)
		(size 0.508)
		(drill 0.254)
		(layers "F.Cu" "B.Cu")
		(net "P12V_PSU")
	)
	(via
		(at 251.75464 -400.48434)
		(size 0.508)
		(drill 0.254)
		(layers "F.Cu" "B.Cu")
		(net "P12V_PSU")
	)
	(via
		(at 252.51664 -403.53234)
		(size 0.508)
		(drill 0.254)
		(layers "F.Cu" "B.Cu")
		(net "P12V_PSU")
	)
	(via
		(at 258.2545 -398.19834)
		(size 0.508)
		(drill 0.254)
		(layers "F.Cu" "B.Cu")
		(net "P12V_PSU")
	)
	(via
		(at 244.48008 -400.44878)
		(size 0.508)
		(drill 0.254)
		(layers "F.Cu" "B.Cu")
		(net "P12V_PSU")
	)
	(via
		(at 187.197492 -408.092402)
		(size 0.508)
		(drill 0.254)
		(layers "F.Cu" "B.Cu")
		(net "P12V_PSU")
	)
	(via
		(at 277.977346 -402.854922)
		(size 0.508)
		(drill 0.254)
		(layers "F.Cu" "B.Cu")
		(net "P12V_PSU")
	)
	(via
		(at 210.204558 -400.617182)
		(size 0.508)
		(drill 0.254)
		(layers "F.Cu" "B.Cu")
		(net "P12V_PSU")
	)
	(via
		(at 187.959492 -407.330402)
		(size 0.508)
		(drill 0.254)
		(layers "F.Cu" "B.Cu")
		(net "P12V_PSU")
	)
	(via
		(at 231.5337 -405.011382)
		(size 0.508)
		(drill 0.254)
		(layers "F.Cu" "B.Cu")
		(net "P12V_PSU")
	)
	(via
		(at 245.24208 -402.73478)
		(size 0.508)
		(drill 0.254)
		(layers "F.Cu" "B.Cu")
		(net "P12V_PSU")
	)
	(via
		(at 201.0537 -408.059382)
		(size 0.508)
		(drill 0.254)
		(layers "F.Cu" "B.Cu")
		(net "P12V_PSU")
	)
	(via
		(at 275.691346 -398.282922)
		(size 0.508)
		(drill 0.254)
		(layers "F.Cu" "B.Cu")
		(net "P12V_PSU")
	)
	(via
		(at 233.0577 -405.773382)
		(size 0.508)
		(drill 0.254)
		(layers "F.Cu" "B.Cu")
		(net "P12V_PSU")
	)
	(via
		(at 189.483492 -404.993602)
		(size 0.508)
		(drill 0.254)
		(layers "F.Cu" "B.Cu")
		(net "P12V_PSU")
	)
	(via
		(at 250.23064 -402.77034)
		(size 0.508)
		(drill 0.254)
		(layers "F.Cu" "B.Cu")
		(net "P12V_PSU")
	)
	(via
		(at 277.215346 -401.330922)
		(size 0.508)
		(drill 0.254)
		(layers "F.Cu" "B.Cu")
		(net "P12V_PSU")
	)
	(via
		(at 201.0537 -407.297382)
		(size 0.508)
		(drill 0.254)
		(layers "F.Cu" "B.Cu")
		(net "P12V_PSU")
	)
	(via
		(at 243.71808 -399.68678)
		(size 0.508)
		(drill 0.254)
		(layers "F.Cu" "B.Cu")
		(net "P12V_PSU")
	)
	(via
		(at 232.937558 -403.223222)
		(size 0.508)
		(drill 0.254)
		(layers "F.Cu" "B.Cu")
		(net "P12V_PSU")
	)
	(via
		(at 219.3417 -405.011382)
		(size 0.508)
		(drill 0.254)
		(layers "F.Cu" "B.Cu")
		(net "P12V_PSU")
	)
	(via
		(at 268.533626 -400.528282)
		(size 0.508)
		(drill 0.254)
		(layers "F.Cu" "B.Cu")
		(net "P12V_PSU")
	)
	(via
		(at 269.295626 -400.528282)
		(size 0.508)
		(drill 0.254)
		(layers "F.Cu" "B.Cu")
		(net "P12V_PSU")
	)
	(via
		(at 243.71808 -398.92478)
		(size 0.508)
		(drill 0.254)
		(layers "F.Cu" "B.Cu")
		(net "P12V_PSU")
	)
	(via
		(at 188.721492 -407.330402)
		(size 0.508)
		(drill 0.254)
		(layers "F.Cu" "B.Cu")
		(net "P12V_PSU")
	)
	(via
		(at 259.7785 -402.00834)
		(size 0.508)
		(drill 0.254)
		(layers "F.Cu" "B.Cu")
		(net "P12V_PSU")
	)
	(via
		(at 261.3025 -398.19834)
		(size 0.508)
		(drill 0.254)
		(layers "F.Cu" "B.Cu")
		(net "P12V_PSU")
	)
	(via
		(at 246.00408 -401.21078)
		(size 0.508)
		(drill 0.254)
		(layers "F.Cu" "B.Cu")
		(net "P12V_PSU")
	)
	(via
		(at 262.0645 -398.19834)
		(size 0.508)
		(drill 0.254)
		(layers "F.Cu" "B.Cu")
		(net "P12V_PSU")
	)
	(via
		(at 228.4857 -408.059382)
		(size 0.508)
		(drill 0.254)
		(layers "F.Cu" "B.Cu")
		(net "P12V_PSU")
	)
	(via
		(at 261.3025 -403.53234)
		(size 0.508)
		(drill 0.254)
		(layers "F.Cu" "B.Cu")
		(net "P12V_PSU")
	)
	(via
		(at 258.2545 -399.72234)
		(size 0.508)
		(drill 0.254)
		(layers "F.Cu" "B.Cu")
		(net "P12V_PSU")
	)
	(via
		(at 198.114158 -403.223222)
		(size 0.508)
		(drill 0.254)
		(layers "F.Cu" "B.Cu")
		(net "P12V_PSU")
	)
	(via
		(at 230.0097 -406.535382)
		(size 0.508)
		(drill 0.254)
		(layers "F.Cu" "B.Cu")
		(net "P12V_PSU")
	)
	(via
		(at 261.3025 -398.96034)
		(size 0.508)
		(drill 0.254)
		(layers "F.Cu" "B.Cu")
		(net "P12V_PSU")
	)
	(via
		(at 262.0645 -402.77034)
		(size 0.508)
		(drill 0.254)
		(layers "F.Cu" "B.Cu")
		(net "P12V_PSU")
	)
	(via
		(at 260.5405 -402.00834)
		(size 0.508)
		(drill 0.254)
		(layers "F.Cu" "B.Cu")
		(net "P12V_PSU")
	)
	(via
		(at 198.114158 -400.617182)
		(size 0.508)
		(drill 0.254)
		(layers "F.Cu" "B.Cu")
		(net "P12V_PSU")
	)
	(via
		(at 201.0537 -406.535382)
		(size 0.508)
		(drill 0.254)
		(layers "F.Cu" "B.Cu")
		(net "P12V_PSU")
	)
	(via
		(at 187.959492 -408.092402)
		(size 0.508)
		(drill 0.254)
		(layers "F.Cu" "B.Cu")
		(net "P12V_PSU")
	)
	(via
		(at 217.35923 -410.460444)
		(size 0.762)
		(drill 0.381)
		(layers "F.Cu" "B.Cu")
		(net "P12V_PSU")
	)
	(via
		(at 277.215346 -399.806922)
		(size 0.508)
		(drill 0.254)
		(layers "F.Cu" "B.Cu")
		(net "P12V_PSU")
	)
	(via
		(at 259.0165 -401.24634)
		(size 0.508)
		(drill 0.254)
		(layers "F.Cu" "B.Cu")
		(net "P12V_PSU")
	)
	(via
		(at 219.450158 -403.223222)
		(size 0.508)
		(drill 0.254)
		(layers "F.Cu" "B.Cu")
		(net "P12V_PSU")
	)
	(via
		(at 252.51664 -402.77034)
		(size 0.508)
		(drill 0.254)
		(layers "F.Cu" "B.Cu")
		(net "P12V_PSU")
	)
	(via
		(at 212.4837 -408.059382)
		(size 0.508)
		(drill 0.254)
		(layers "F.Cu" "B.Cu")
		(net "P12V_PSU")
	)
	(via
		(at 243.71808 -398.16278)
		(size 0.508)
		(drill 0.254)
		(layers "F.Cu" "B.Cu")
		(net "P12V_PSU")
	)
	(via
		(at 275.691346 -400.568922)
		(size 0.508)
		(drill 0.254)
		(layers "F.Cu" "B.Cu")
		(net "P12V_PSU")
	)
	(via
		(at 211.7217 -408.059382)
		(size 0.508)
		(drill 0.254)
		(layers "F.Cu" "B.Cu")
		(net "P12V_PSU")
	)
	(via
		(at 250.23064 -402.00834)
		(size 0.508)
		(drill 0.254)
		(layers "F.Cu" "B.Cu")
		(net "P12V_PSU")
	)
	(via
		(at 222.269558 -400.617182)
		(size 0.508)
		(drill 0.254)
		(layers "F.Cu" "B.Cu")
		(net "P12V_PSU")
	)
	(via
		(at 230.7717 -408.059382)
		(size 0.508)
		(drill 0.254)
		(layers "F.Cu" "B.Cu")
		(net "P12V_PSU")
	)
	(via
		(at 230.0097 -405.011382)
		(size 0.508)
		(drill 0.254)
		(layers "F.Cu" "B.Cu")
		(net "P12V_PSU")
	)
	(via
		(at 188.721492 -404.993602)
		(size 0.508)
		(drill 0.254)
		(layers "F.Cu" "B.Cu")
		(net "P12V_PSU")
	)
	(via
		(at 278.739346 -403.616922)
		(size 0.508)
		(drill 0.254)
		(layers "F.Cu" "B.Cu")
		(net "P12V_PSU")
	)
	(via
		(at 199.5297 -406.535382)
		(size 0.508)
		(drill 0.254)
		(layers "F.Cu" "B.Cu")
		(net "P12V_PSU")
	)
	(via
		(at 210.1977 -407.297382)
		(size 0.508)
		(drill 0.254)
		(layers "F.Cu" "B.Cu")
		(net "P12V_PSU")
	)
	(via
		(at 251.75464 -398.19834)
		(size 0.508)
		(drill 0.254)
		(layers "F.Cu" "B.Cu")
		(net "P12V_PSU")
	)
	(via
		(at 242.95608 -401.21078)
		(size 0.508)
		(drill 0.254)
		(layers "F.Cu" "B.Cu")
		(net "P12V_PSU")
	)
	(via
		(at 277.977346 -401.330922)
		(size 0.508)
		(drill 0.254)
		(layers "F.Cu" "B.Cu")
		(net "P12V_PSU")
	)
	(via
		(at 189.483492 -407.330402)
		(size 0.508)
		(drill 0.254)
		(layers "F.Cu" "B.Cu")
		(net "P12V_PSU")
	)
	(via
		(at 262.0645 -403.53234)
		(size 0.508)
		(drill 0.254)
		(layers "F.Cu" "B.Cu")
		(net "P12V_PSU")
	)
	(via
		(at 185.673492 -407.330402)
		(size 0.508)
		(drill 0.254)
		(layers "F.Cu" "B.Cu")
		(net "P12V_PSU")
	)
	(via
		(at 189.483492 -405.755602)
		(size 0.508)
		(drill 0.254)
		(layers "F.Cu" "B.Cu")
		(net "P12V_PSU")
	)
	(via
		(at 270.819626 -398.242282)
		(size 0.508)
		(drill 0.254)
		(layers "F.Cu" "B.Cu")
		(net "P12V_PSU")
	)
	(via
		(at 242.19408 -403.49678)
		(size 0.508)
		(drill 0.254)
		(layers "F.Cu" "B.Cu")
		(net "P12V_PSU")
	)
	(via
		(at 260.5405 -402.77034)
		(size 0.508)
		(drill 0.254)
		(layers "F.Cu" "B.Cu")
		(net "P12V_PSU")
	)
	(via
		(at 186.27852 -403.222714)
		(size 0.508)
		(drill 0.254)
		(layers "F.Cu" "B.Cu")
		(net "P12V_PSU")
	)
	(via
		(at 267.009626 -399.766282)
		(size 0.508)
		(drill 0.254)
		(layers "F.Cu" "B.Cu")
		(net "P12V_PSU")
	)
	(via
		(at 262.0645 -400.48434)
		(size 0.508)
		(drill 0.254)
		(layers "F.Cu" "B.Cu")
		(net "P12V_PSU")
	)
	(via
		(at 267.009626 -402.052282)
		(size 0.508)
		(drill 0.254)
		(layers "F.Cu" "B.Cu")
		(net "P12V_PSU")
	)
	(via
		(at 242.19408 -398.92478)
		(size 0.508)
		(drill 0.254)
		(layers "F.Cu" "B.Cu")
		(net "P12V_PSU")
	)
	(via
		(at 270.819626 -399.004282)
		(size 0.508)
		(drill 0.254)
		(layers "F.Cu" "B.Cu")
		(net "P12V_PSU")
	)
	(via
		(at 252.51664 -399.72234)
		(size 0.508)
		(drill 0.254)
		(layers "F.Cu" "B.Cu")
		(net "P12V_PSU")
	)
	(via
		(at 231.540558 -400.617182)
		(size 0.508)
		(drill 0.254)
		(layers "F.Cu" "B.Cu")
		(net "P12V_PSU")
	)
	(via
		(at 242.95608 -398.92478)
		(size 0.508)
		(drill 0.254)
		(layers "F.Cu" "B.Cu")
		(net "P12V_PSU")
	)
	(via
		(at 267.009626 -400.528282)
		(size 0.508)
		(drill 0.254)
		(layers "F.Cu" "B.Cu")
		(net "P12V_PSU")
	)
	(via
		(at 220.8657 -408.059382)
		(size 0.508)
		(drill 0.254)
		(layers "F.Cu" "B.Cu")
		(net "P12V_PSU")
	)
	(via
		(at 259.7785 -400.48434)
		(size 0.508)
		(drill 0.254)
		(layers "F.Cu" "B.Cu")
		(net "P12V_PSU")
	)
	(via
		(at 198.7677 -405.773382)
		(size 0.508)
		(drill 0.254)
		(layers "F.Cu" "B.Cu")
		(net "P12V_PSU")
	)
	(via
		(at 244.48008 -399.68678)
		(size 0.508)
		(drill 0.254)
		(layers "F.Cu" "B.Cu")
		(net "P12V_PSU")
	)
	(via
		(at 197.2437 -408.059382)
		(size 0.508)
		(drill 0.254)
		(layers "F.Cu" "B.Cu")
		(net "P12V_PSU")
	)
	(via
		(at 208.6737 -405.773382)
		(size 0.508)
		(drill 0.254)
		(layers "F.Cu" "B.Cu")
		(net "P12V_PSU")
	)
	(via
		(at 267.009626 -401.290282)
		(size 0.508)
		(drill 0.254)
		(layers "F.Cu" "B.Cu")
		(net "P12V_PSU")
	)
	(via
		(at 261.3025 -400.48434)
		(size 0.508)
		(drill 0.254)
		(layers "F.Cu" "B.Cu")
		(net "P12V_PSU")
	)
	(via
		(at 229.2477 -407.297382)
		(size 0.508)
		(drill 0.254)
		(layers "F.Cu" "B.Cu")
		(net "P12V_PSU")
	)
	(via
		(at 242.95608 -403.49678)
		(size 0.508)
		(drill 0.254)
		(layers "F.Cu" "B.Cu")
		(net "P12V_PSU")
	)
	(via
		(at 198.114158 -401.920202)
		(size 0.508)
		(drill 0.254)
		(layers "F.Cu" "B.Cu")
		(net "P12V_PSU")
	)
	(via
		(at 186.435492 -404.993602)
		(size 0.508)
		(drill 0.254)
		(layers "F.Cu" "B.Cu")
		(net "P12V_PSU")
	)
	(via
		(at 270.057626 -399.004282)
		(size 0.508)
		(drill 0.254)
		(layers "F.Cu" "B.Cu")
		(net "P12V_PSU")
	)
	(via
		(at 254.04064 -402.00834)
		(size 0.508)
		(drill 0.254)
		(layers "F.Cu" "B.Cu")
		(net "P12V_PSU")
	)
	(via
		(at 266.247626 -398.242282)
		(size 0.508)
		(drill 0.254)
		(layers "F.Cu" "B.Cu")
		(net "P12V_PSU")
	)
	(via
		(at 211.601558 -403.223222)
		(size 0.508)
		(drill 0.254)
		(layers "F.Cu" "B.Cu")
		(net "P12V_PSU")
	)
	(via
		(at 267.009626 -402.814282)
		(size 0.508)
		(drill 0.254)
		(layers "F.Cu" "B.Cu")
		(net "P12V_PSU")
	)
	(via
		(at 219.3417 -405.773382)
		(size 0.508)
		(drill 0.254)
		(layers "F.Cu" "B.Cu")
		(net "P12V_PSU")
	)
	(via
		(at 184.85612 -403.222714)
		(size 0.508)
		(drill 0.254)
		(layers "F.Cu" "B.Cu")
		(net "P12V_PSU")
	)
	(via
		(at 200.2917 -405.011382)
		(size 0.508)
		(drill 0.254)
		(layers "F.Cu" "B.Cu")
		(net "P12V_PSU")
	)
	(via
		(at 254.04064 -399.72234)
		(size 0.508)
		(drill 0.254)
		(layers "F.Cu" "B.Cu")
		(net "P12V_PSU")
	)
	(via
		(at 217.8177 -408.059382)
		(size 0.508)
		(drill 0.254)
		(layers "F.Cu" "B.Cu")
		(net "P12V_PSU")
	)
	(via
		(at 254.04064 -401.24634)
		(size 0.508)
		(drill 0.254)
		(layers "F.Cu" "B.Cu")
		(net "P12V_PSU")
	)
	(via
		(at 242.95608 -402.73478)
		(size 0.508)
		(drill 0.254)
		(layers "F.Cu" "B.Cu")
		(net "P12V_PSU")
	)
	(via
		(at 199.536558 -403.223222)
		(size 0.508)
		(drill 0.254)
		(layers "F.Cu" "B.Cu")
		(net "P12V_PSU")
	)
	(via
		(at 220.872558 -403.223222)
		(size 0.508)
		(drill 0.254)
		(layers "F.Cu" "B.Cu")
		(net "P12V_PSU")
	)
	(via
		(at 277.977346 -398.282922)
		(size 0.508)
		(drill 0.254)
		(layers "F.Cu" "B.Cu")
		(net "P12V_PSU")
	)
	(via
		(at 267.771626 -402.814282)
		(size 0.508)
		(drill 0.254)
		(layers "F.Cu" "B.Cu")
		(net "P12V_PSU")
	)
	(via
		(at 187.197492 -404.993602)
		(size 0.508)
		(drill 0.254)
		(layers "F.Cu" "B.Cu")
		(net "P12V_PSU")
	)
	(via
		(at 232.2957 -406.535382)
		(size 0.508)
		(drill 0.254)
		(layers "F.Cu" "B.Cu")
		(net "P12V_PSU")
	)
	(via
		(at 262.0645 -399.72234)
		(size 0.508)
		(drill 0.254)
		(layers "F.Cu" "B.Cu")
		(net "P12V_PSU")
	)
	(via
		(at 219.450158 -401.920202)
		(size 0.508)
		(drill 0.254)
		(layers "F.Cu" "B.Cu")
		(net "P12V_PSU")
	)
	(via
		(at 251.75464 -398.96034)
		(size 0.508)
		(drill 0.254)
		(layers "F.Cu" "B.Cu")
		(net "P12V_PSU")
	)
	(via
		(at 200.2917 -406.535382)
		(size 0.508)
		(drill 0.254)
		(layers "F.Cu" "B.Cu")
		(net "P12V_PSU")
	)
	(via
		(at 244.48008 -398.92478)
		(size 0.508)
		(drill 0.254)
		(layers "F.Cu" "B.Cu")
		(net "P12V_PSU")
	)
	(via
		(at 276.453346 -399.806922)
		(size 0.508)
		(drill 0.254)
		(layers "F.Cu" "B.Cu")
		(net "P12V_PSU")
	)
	(via
		(at 231.5337 -406.535382)
		(size 0.508)
		(drill 0.254)
		(layers "F.Cu" "B.Cu")
		(net "P12V_PSU")
	)
	(via
		(at 199.536558 -400.617182)
		(size 0.508)
		(drill 0.254)
		(layers "F.Cu" "B.Cu")
		(net "P12V_PSU")
	)
	(via
		(at 267.009626 -403.576282)
		(size 0.508)
		(drill 0.254)
		(layers "F.Cu" "B.Cu")
		(net "P12V_PSU")
	)
	(via
		(at 268.533626 -403.576282)
		(size 0.508)
		(drill 0.254)
		(layers "F.Cu" "B.Cu")
		(net "P12V_PSU")
	)
	(via
		(at 209.4357 -405.773382)
		(size 0.508)
		(drill 0.254)
		(layers "F.Cu" "B.Cu")
		(net "P12V_PSU")
	)
	(via
		(at 230.0097 -407.297382)
		(size 0.508)
		(drill 0.254)
		(layers "F.Cu" "B.Cu")
		(net "P12V_PSU")
	)
	(via
		(at 252.51664 -398.96034)
		(size 0.508)
		(drill 0.254)
		(layers "F.Cu" "B.Cu")
		(net "P12V_PSU")
	)
	(via
		(at 221.6277 -406.535382)
		(size 0.508)
		(drill 0.254)
		(layers "F.Cu" "B.Cu")
		(net "P12V_PSU")
	)
	(via
		(at 245.24208 -403.49678)
		(size 0.508)
		(drill 0.254)
		(layers "F.Cu" "B.Cu")
		(net "P12V_PSU")
	)
	(via
		(at 277.977346 -399.044922)
		(size 0.508)
		(drill 0.254)
		(layers "F.Cu" "B.Cu")
		(net "P12V_PSU")
	)
	(via
		(at 259.7785 -398.96034)
		(size 0.508)
		(drill 0.254)
		(layers "F.Cu" "B.Cu")
		(net "P12V_PSU")
	)
	(via
		(at 245.24208 -401.97278)
		(size 0.508)
		(drill 0.254)
		(layers "F.Cu" "B.Cu")
		(net "P12V_PSU")
	)
	(via
		(at 222.269558 -401.920202)
		(size 0.508)
		(drill 0.254)
		(layers "F.Cu" "B.Cu")
		(net "P12V_PSU")
	)
	(via
		(at 233.8197 -407.297382)
		(size 0.508)
		(drill 0.254)
		(layers "F.Cu" "B.Cu")
		(net "P12V_PSU")
	)
	(via
		(at 209.4357 -406.535382)
		(size 0.508)
		(drill 0.254)
		(layers "F.Cu" "B.Cu")
		(net "P12V_PSU")
	)
	(via
		(at 258.2545 -402.00834)
		(size 0.508)
		(drill 0.254)
		(layers "F.Cu" "B.Cu")
		(net "P12V_PSU")
	)
	(via
		(at 220.1037 -405.011382)
		(size 0.508)
		(drill 0.254)
		(layers "F.Cu" "B.Cu")
		(net "P12V_PSU")
	)
	(via
		(at 222.269558 -403.223222)
		(size 0.508)
		(drill 0.254)
		(layers "F.Cu" "B.Cu")
		(net "P12V_PSU")
	)
	(via
		(at 210.1977 -406.535382)
		(size 0.508)
		(drill 0.254)
		(layers "F.Cu" "B.Cu")
		(net "P12V_PSU")
	)
	(via
		(at 267.771626 -399.766282)
		(size 0.508)
		(drill 0.254)
		(layers "F.Cu" "B.Cu")
		(net "P12V_PSU")
	)
	(via
		(at 233.0577 -408.059382)
		(size 0.508)
		(drill 0.254)
		(layers "F.Cu" "B.Cu")
		(net "P12V_PSU")
	)
	(via
		(at 231.5337 -407.297382)
		(size 0.508)
		(drill 0.254)
		(layers "F.Cu" "B.Cu")
		(net "P12V_PSU")
	)
	(via
		(at 232.937558 -400.617182)
		(size 0.508)
		(drill 0.254)
		(layers "F.Cu" "B.Cu")
		(net "P12V_PSU")
	)
	(via
		(at 242.19408 -398.16278)
		(size 0.508)
		(drill 0.254)
		(layers "F.Cu" "B.Cu")
		(net "P12V_PSU")
	)
	(via
		(at 250.99264 -399.72234)
		(size 0.508)
		(drill 0.254)
		(layers "F.Cu" "B.Cu")
		(net "P12V_PSU")
	)
	(via
		(at 187.67552 -403.222714)
		(size 0.508)
		(drill 0.254)
		(layers "F.Cu" "B.Cu")
		(net "P12V_PSU")
	)
	(via
		(at 250.23064 -401.24634)
		(size 0.508)
		(drill 0.254)
		(layers "F.Cu" "B.Cu")
		(net "P12V_PSU")
	)
	(via
		(at 243.71808 -403.49678)
		(size 0.508)
		(drill 0.254)
		(layers "F.Cu" "B.Cu")
		(net "P12V_PSU")
	)
	(via
		(at 242.19408 -402.73478)
		(size 0.508)
		(drill 0.254)
		(layers "F.Cu" "B.Cu")
		(net "P12V_PSU")
	)
	(via
		(at 277.215346 -402.854922)
		(size 0.508)
		(drill 0.254)
		(layers "F.Cu" "B.Cu")
		(net "P12V_PSU")
	)
	(via
		(at 201.0537 -405.011382)
		(size 0.508)
		(drill 0.254)
		(layers "F.Cu" "B.Cu")
		(net "P12V_PSU")
	)
	(via
		(at 267.009626 -398.242282)
		(size 0.508)
		(drill 0.254)
		(layers "F.Cu" "B.Cu")
		(net "P12V_PSU")
	)
	(via
		(at 208.782158 -400.617182)
		(size 0.508)
		(drill 0.254)
		(layers "F.Cu" "B.Cu")
		(net "P12V_PSU")
	)
	(via
		(at 209.4357 -408.059382)
		(size 0.508)
		(drill 0.254)
		(layers "F.Cu" "B.Cu")
		(net "P12V_PSU")
	)
	(via
		(at 277.215346 -403.616922)
		(size 0.508)
		(drill 0.254)
		(layers "F.Cu" "B.Cu")
		(net "P12V_PSU")
	)
	(via
		(at 224.16389 -410.642054)
		(size 0.762)
		(drill 0.381)
		(layers "F.Cu" "B.Cu")
		(net "P12V_PSU")
	)
	(via
		(at 200.2917 -408.059382)
		(size 0.508)
		(drill 0.254)
		(layers "F.Cu" "B.Cu")
		(net "P12V_PSU")
	)
	(via
		(at 187.959492 -405.755602)
		(size 0.508)
		(drill 0.254)
		(layers "F.Cu" "B.Cu")
		(net "P12V_PSU")
	)
	(via
		(at 275.691346 -399.044922)
		(size 0.508)
		(drill 0.254)
		(layers "F.Cu" "B.Cu")
		(net "P12V_PSU")
	)
	(via
		(at 186.435492 -408.092402)
		(size 0.508)
		(drill 0.254)
		(layers "F.Cu" "B.Cu")
		(net "P12V_PSU")
	)
	(via
		(at 198.0057 -406.535382)
		(size 0.508)
		(drill 0.254)
		(layers "F.Cu" "B.Cu")
		(net "P12V_PSU")
	)
	(via
		(at 270.819626 -401.290282)
		(size 0.508)
		(drill 0.254)
		(layers "F.Cu" "B.Cu")
		(net "P12V_PSU")
	)
	(via
		(at 185.673492 -406.517602)
		(size 0.508)
		(drill 0.254)
		(layers "F.Cu" "B.Cu")
		(net "P12V_PSU")
	)
	(via
		(at 222.3897 -407.297382)
		(size 0.508)
		(drill 0.254)
		(layers "F.Cu" "B.Cu")
		(net "P12V_PSU")
	)
	(via
		(at 219.3417 -407.297382)
		(size 0.508)
		(drill 0.254)
		(layers "F.Cu" "B.Cu")
		(net "P12V_PSU")
	)
	(via
		(at 246.00408 -401.97278)
		(size 0.508)
		(drill 0.254)
		(layers "F.Cu" "B.Cu")
		(net "P12V_PSU")
	)
	(via
		(at 266.247626 -402.814282)
		(size 0.508)
		(drill 0.254)
		(layers "F.Cu" "B.Cu")
		(net "P12V_PSU")
	)
	(via
		(at 259.7785 -403.53234)
		(size 0.508)
		(drill 0.254)
		(layers "F.Cu" "B.Cu")
		(net "P12V_PSU")
	)
	(via
		(at 211.7217 -406.535382)
		(size 0.508)
		(drill 0.254)
		(layers "F.Cu" "B.Cu")
		(net "P12V_PSU")
	)
	(via
		(at 250.99264 -398.19834)
		(size 0.508)
		(drill 0.254)
		(layers "F.Cu" "B.Cu")
		(net "P12V_PSU")
	)
	(via
		(at 259.0165 -400.48434)
		(size 0.508)
		(drill 0.254)
		(layers "F.Cu" "B.Cu")
		(net "P12V_PSU")
	)
	(via
		(at 212.4837 -407.297382)
		(size 0.508)
		(drill 0.254)
		(layers "F.Cu" "B.Cu")
		(net "P12V_PSU")
	)
	(via
		(at 250.23064 -400.48434)
		(size 0.508)
		(drill 0.254)
		(layers "F.Cu" "B.Cu")
		(net "P12V_PSU")
	)
	(via
		(at 250.99264 -401.24634)
		(size 0.508)
		(drill 0.254)
		(layers "F.Cu" "B.Cu")
		(net "P12V_PSU")
	)
	(via
		(at 251.75464 -402.77034)
		(size 0.508)
		(drill 0.254)
		(layers "F.Cu" "B.Cu")
		(net "P12V_PSU")
	)
	(via
		(at 187.197492 -405.755602)
		(size 0.508)
		(drill 0.254)
		(layers "F.Cu" "B.Cu")
		(net "P12V_PSU")
	)
	(via
		(at 211.7217 -405.011382)
		(size 0.508)
		(drill 0.254)
		(layers "F.Cu" "B.Cu")
		(net "P12V_PSU")
	)
	(via
		(at 210.9597 -407.297382)
		(size 0.508)
		(drill 0.254)
		(layers "F.Cu" "B.Cu")
		(net "P12V_PSU")
	)
	(via
		(at 230.118158 -401.920202)
		(size 0.508)
		(drill 0.254)
		(layers "F.Cu" "B.Cu")
		(net "P12V_PSU")
	)
	(via
		(at 208.6737 -408.059382)
		(size 0.508)
		(drill 0.254)
		(layers "F.Cu" "B.Cu")
		(net "P12V_PSU")
	)
	(via
		(at 270.819626 -402.814282)
		(size 0.508)
		(drill 0.254)
		(layers "F.Cu" "B.Cu")
		(net "P12V_PSU")
	)
	(via
		(at 189.483492 -406.517602)
		(size 0.508)
		(drill 0.254)
		(layers "F.Cu" "B.Cu")
		(net "P12V_PSU")
	)
	(via
		(at 277.977346 -400.568922)
		(size 0.508)
		(drill 0.254)
		(layers "F.Cu" "B.Cu")
		(net "P12V_PSU")
	)
	(via
		(at 258.2545 -401.24634)
		(size 0.508)
		(drill 0.254)
		(layers "F.Cu" "B.Cu")
		(net "P12V_PSU")
	)
	(via
		(at 266.247626 -403.576282)
		(size 0.508)
		(drill 0.254)
		(layers "F.Cu" "B.Cu")
		(net "P12V_PSU")
	)
	(via
		(at 220.8657 -405.773382)
		(size 0.508)
		(drill 0.254)
		(layers "F.Cu" "B.Cu")
		(net "P12V_PSU")
	)
	(via
		(at 270.819626 -400.528282)
		(size 0.508)
		(drill 0.254)
		(layers "F.Cu" "B.Cu")
		(net "P12V_PSU")
	)
	(via
		(at 259.7785 -398.19834)
		(size 0.508)
		(drill 0.254)
		(layers "F.Cu" "B.Cu")
		(net "P12V_PSU")
	)
	(via
		(at 244.48008 -403.49678)
		(size 0.508)
		(drill 0.254)
		(layers "F.Cu" "B.Cu")
		(net "P12V_PSU")
	)
	(via
		(at 211.7217 -405.773382)
		(size 0.508)
		(drill 0.254)
		(layers "F.Cu" "B.Cu")
		(net "P12V_PSU")
	)
	(via
		(at 276.453346 -402.854922)
		(size 0.508)
		(drill 0.254)
		(layers "F.Cu" "B.Cu")
		(net "P12V_PSU")
	)
	(via
		(at 261.3025 -399.72234)
		(size 0.508)
		(drill 0.254)
		(layers "F.Cu" "B.Cu")
		(net "P12V_PSU")
	)
	(via
		(at 222.3897 -408.059382)
		(size 0.508)
		(drill 0.254)
		(layers "F.Cu" "B.Cu")
		(net "P12V_PSU")
	)
	(via
		(at 262.0645 -398.96034)
		(size 0.508)
		(drill 0.254)
		(layers "F.Cu" "B.Cu")
		(net "P12V_PSU")
	)
	(via
		(at 250.99264 -398.96034)
		(size 0.508)
		(drill 0.254)
		(layers "F.Cu" "B.Cu")
		(net "P12V_PSU")
	)
	(via
		(at 261.3025 -401.24634)
		(size 0.508)
		(drill 0.254)
		(layers "F.Cu" "B.Cu")
		(net "P12V_PSU")
	)
	(via
		(at 270.057626 -403.576282)
		(size 0.508)
		(drill 0.254)
		(layers "F.Cu" "B.Cu")
		(net "P12V_PSU")
	)
	(via
		(at 186.435492 -407.330402)
		(size 0.508)
		(drill 0.254)
		(layers "F.Cu" "B.Cu")
		(net "P12V_PSU")
	)
	(via
		(at 252.51664 -400.48434)
		(size 0.508)
		(drill 0.254)
		(layers "F.Cu" "B.Cu")
		(net "P12V_PSU")
	)
	(via
		(at 260.5405 -401.24634)
		(size 0.508)
		(drill 0.254)
		(layers "F.Cu" "B.Cu")
		(net "P12V_PSU")
	)
	(via
		(at 250.23064 -398.96034)
		(size 0.508)
		(drill 0.254)
		(layers "F.Cu" "B.Cu")
		(net "P12V_PSU")
	)
	(via
		(at 266.247626 -401.290282)
		(size 0.508)
		(drill 0.254)
		(layers "F.Cu" "B.Cu")
		(net "P12V_PSU")
	)
	(via
		(at 230.7717 -405.773382)
		(size 0.508)
		(drill 0.254)
		(layers "F.Cu" "B.Cu")
		(net "P12V_PSU")
	)
	(via
		(at 270.057626 -401.290282)
		(size 0.508)
		(drill 0.254)
		(layers "F.Cu" "B.Cu")
		(net "P12V_PSU")
	)
	(via
		(at 270.057626 -399.766282)
		(size 0.508)
		(drill 0.254)
		(layers "F.Cu" "B.Cu")
		(net "P12V_PSU")
	)
	(via
		(at 187.959492 -404.993602)
		(size 0.508)
		(drill 0.254)
		(layers "F.Cu" "B.Cu")
		(net "P12V_PSU")
	)
	(via
		(at 185.673492 -404.993602)
		(size 0.508)
		(drill 0.254)
		(layers "F.Cu" "B.Cu")
		(net "P12V_PSU")
	)
	(via
		(at 185.673492 -408.092402)
		(size 0.508)
		(drill 0.254)
		(layers "F.Cu" "B.Cu")
		(net "P12V_PSU")
	)
	(via
		(at 242.95608 -399.68678)
		(size 0.508)
		(drill 0.254)
		(layers "F.Cu" "B.Cu")
		(net "P12V_PSU")
	)
	(via
		(at 270.057626 -398.242282)
		(size 0.508)
		(drill 0.254)
		(layers "F.Cu" "B.Cu")
		(net "P12V_PSU")
	)
	(via
		(at 200.933558 -400.617182)
		(size 0.508)
		(drill 0.254)
		(layers "F.Cu" "B.Cu")
		(net "P12V_PSU")
	)
	(via
		(at 277.977346 -399.806922)
		(size 0.508)
		(drill 0.254)
		(layers "F.Cu" "B.Cu")
		(net "P12V_PSU")
	)
	(via
		(at 242.19408 -400.44878)
		(size 0.508)
		(drill 0.254)
		(layers "F.Cu" "B.Cu")
		(net "P12V_PSU")
	)
	(via
		(at 259.7785 -401.24634)
		(size 0.508)
		(drill 0.254)
		(layers "F.Cu" "B.Cu")
		(net "P12V_PSU")
	)
	(via
		(at 197.2437 -405.011382)
		(size 0.508)
		(drill 0.254)
		(layers "F.Cu" "B.Cu")
		(net "P12V_PSU")
	)
	(via
		(at 270.057626 -402.052282)
		(size 0.508)
		(drill 0.254)
		(layers "F.Cu" "B.Cu")
		(net "P12V_PSU")
	)
	(via
		(at 253.27864 -403.53234)
		(size 0.508)
		(drill 0.254)
		(layers "F.Cu" "B.Cu")
		(net "P12V_PSU")
	)
	(via
		(at 219.3417 -406.535382)
		(size 0.508)
		(drill 0.254)
		(layers "F.Cu" "B.Cu")
		(net "P12V_PSU")
	)
	(via
		(at 250.99264 -400.48434)
		(size 0.508)
		(drill 0.254)
		(layers "F.Cu" "B.Cu")
		(net "P12V_PSU")
	)
	(via
		(at 231.5337 -408.059382)
		(size 0.508)
		(drill 0.254)
		(layers "F.Cu" "B.Cu")
		(net "P12V_PSU")
	)
	(via
		(at 268.533626 -399.004282)
		(size 0.508)
		(drill 0.254)
		(layers "F.Cu" "B.Cu")
		(net "P12V_PSU")
	)
	(via
		(at 189.483492 -408.092402)
		(size 0.508)
		(drill 0.254)
		(layers "F.Cu" "B.Cu")
		(net "P12V_PSU")
	)
	(via
		(at 186.435492 -405.755602)
		(size 0.508)
		(drill 0.254)
		(layers "F.Cu" "B.Cu")
		(net "P12V_PSU")
	)
	(via
		(at 208.6737 -405.011382)
		(size 0.508)
		(drill 0.254)
		(layers "F.Cu" "B.Cu")
		(net "P12V_PSU")
	)
	(via
		(at 253.27864 -398.19834)
		(size 0.508)
		(drill 0.254)
		(layers "F.Cu" "B.Cu")
		(net "P12V_PSU")
	)
	(via
		(at 267.771626 -398.242282)
		(size 0.508)
		(drill 0.254)
		(layers "F.Cu" "B.Cu")
		(net "P12V_PSU")
	)
	(via
		(at 261.3025 -402.77034)
		(size 0.508)
		(drill 0.254)
		(layers "F.Cu" "B.Cu")
		(net "P12V_PSU")
	)
	(via
		(at 244.48008 -398.16278)
		(size 0.508)
		(drill 0.254)
		(layers "F.Cu" "B.Cu")
		(net "P12V_PSU")
	)
	(via
		(at 209.4357 -407.297382)
		(size 0.508)
		(drill 0.254)
		(layers "F.Cu" "B.Cu")
		(net "P12V_PSU")
	)
	(via
		(at 210.9597 -408.059382)
		(size 0.508)
		(drill 0.254)
		(layers "F.Cu" "B.Cu")
		(net "P12V_PSU")
	)
	(via
		(at 278.739346 -402.854922)
		(size 0.508)
		(drill 0.254)
		(layers "F.Cu" "B.Cu")
		(net "P12V_PSU")
	)
	(via
		(at 269.295626 -403.576282)
		(size 0.508)
		(drill 0.254)
		(layers "F.Cu" "B.Cu")
		(net "P12V_PSU")
	)
	(via
		(at 209.4357 -405.011382)
		(size 0.508)
		(drill 0.254)
		(layers "F.Cu" "B.Cu")
		(net "P12V_PSU")
	)
	(via
		(at 222.3897 -406.535382)
		(size 0.508)
		(drill 0.254)
		(layers "F.Cu" "B.Cu")
		(net "P12V_PSU")
	)
	(via
		(at 230.7717 -406.535382)
		(size 0.508)
		(drill 0.254)
		(layers "F.Cu" "B.Cu")
		(net "P12V_PSU")
	)
	(via
		(at 267.771626 -403.576282)
		(size 0.508)
		(drill 0.254)
		(layers "F.Cu" "B.Cu")
		(net "P12V_PSU")
	)
	(via
		(at 267.771626 -401.290282)
		(size 0.508)
		(drill 0.254)
		(layers "F.Cu" "B.Cu")
		(net "P12V_PSU")
	)
	(via
		(at 246.00408 -402.73478)
		(size 0.508)
		(drill 0.254)
		(layers "F.Cu" "B.Cu")
		(net "P12V_PSU")
	)
	(via
		(at 254.04064 -398.96034)
		(size 0.508)
		(drill 0.254)
		(layers "F.Cu" "B.Cu")
		(net "P12V_PSU")
	)
	(via
		(at 230.118158 -400.617182)
		(size 0.508)
		(drill 0.254)
		(layers "F.Cu" "B.Cu")
		(net "P12V_PSU")
	)
	(via
		(at 250.99264 -402.77034)
		(size 0.508)
		(drill 0.254)
		(layers "F.Cu" "B.Cu")
		(net "P12V_PSU")
	)
	(via
		(at 241.43208 -400.44878)
		(size 0.508)
		(drill 0.254)
		(layers "F.Cu" "B.Cu")
		(net "P12V_PSU")
	)
	(via
		(at 199.5297 -405.011382)
		(size 0.508)
		(drill 0.254)
		(layers "F.Cu" "B.Cu")
		(net "P12V_PSU")
	)
	(via
		(at 218.5797 -407.297382)
		(size 0.508)
		(drill 0.254)
		(layers "F.Cu" "B.Cu")
		(net "P12V_PSU")
	)
	(via
		(at 270.819626 -399.766282)
		(size 0.508)
		(drill 0.254)
		(layers "F.Cu" "B.Cu")
		(net "P12V_PSU")
	)
	(via
		(at 251.75464 -403.53234)
		(size 0.508)
		(drill 0.254)
		(layers "F.Cu" "B.Cu")
		(net "P12V_PSU")
	)
	(via
		(at 243.71808 -402.73478)
		(size 0.508)
		(drill 0.254)
		(layers "F.Cu" "B.Cu")
		(net "P12V_PSU")
	)
	(via
		(at 259.7785 -402.77034)
		(size 0.508)
		(drill 0.254)
		(layers "F.Cu" "B.Cu")
		(net "P12V_PSU")
	)
	(via
		(at 278.739346 -398.282922)
		(size 0.508)
		(drill 0.254)
		(layers "F.Cu" "B.Cu")
		(net "P12V_PSU")
	)
	(via
		(at 277.215346 -398.282922)
		(size 0.508)
		(drill 0.254)
		(layers "F.Cu" "B.Cu")
		(net "P12V_PSU")
	)
	(via
		(at 276.453346 -398.282922)
		(size 0.508)
		(drill 0.254)
		(layers "F.Cu" "B.Cu")
		(net "P12V_PSU")
	)
	(via
		(at 207.9117 -407.297382)
		(size 0.508)
		(drill 0.254)
		(layers "F.Cu" "B.Cu")
		(net "P12V_PSU")
	)
	(via
		(at 243.71808 -401.97278)
		(size 0.508)
		(drill 0.254)
		(layers "F.Cu" "B.Cu")
		(net "P12V_PSU")
	)
	(via
		(at 278.739346 -402.092922)
		(size 0.508)
		(drill 0.254)
		(layers "F.Cu" "B.Cu")
		(net "P12V_PSU")
	)
	(via
		(at 197.2437 -406.535382)
		(size 0.508)
		(drill 0.254)
		(layers "F.Cu" "B.Cu")
		(net "P12V_PSU")
	)
	(via
		(at 232.2957 -405.011382)
		(size 0.508)
		(drill 0.254)
		(layers "F.Cu" "B.Cu")
		(net "P12V_PSU")
	)
	(via
		(at 241.43208 -398.92478)
		(size 0.508)
		(drill 0.254)
		(layers "F.Cu" "B.Cu")
		(net "P12V_PSU")
	)
	(via
		(at 223.1517 -407.297382)
		(size 0.508)
		(drill 0.254)
		(layers "F.Cu" "B.Cu")
		(net "P12V_PSU")
	)
	(via
		(at 188.721492 -405.755602)
		(size 0.508)
		(drill 0.254)
		(layers "F.Cu" "B.Cu")
		(net "P12V_PSU")
	)
	(via
		(at 233.0577 -405.011382)
		(size 0.508)
		(drill 0.254)
		(layers "F.Cu" "B.Cu")
		(net "P12V_PSU")
	)
	(via
		(at 262.0645 -402.00834)
		(size 0.508)
		(drill 0.254)
		(layers "F.Cu" "B.Cu")
		(net "P12V_PSU")
	)
	(via
		(at 230.7717 -407.297382)
		(size 0.508)
		(drill 0.254)
		(layers "F.Cu" "B.Cu")
		(net "P12V_PSU")
	)
	(via
		(at 210.1977 -405.011382)
		(size 0.508)
		(drill 0.254)
		(layers "F.Cu" "B.Cu")
		(net "P12V_PSU")
	)
	(via
		(at 278.739346 -401.330922)
		(size 0.508)
		(drill 0.254)
		(layers "F.Cu" "B.Cu")
		(net "P12V_PSU")
	)
	(via
		(at 269.295626 -398.242282)
		(size 0.508)
		(drill 0.254)
		(layers "F.Cu" "B.Cu")
		(net "P12V_PSU")
	)
	(via
		(at 207.9117 -408.059382)
		(size 0.508)
		(drill 0.254)
		(layers "F.Cu" "B.Cu")
		(net "P12V_PSU")
	)
	(via
		(at 233.8197 -408.059382)
		(size 0.508)
		(drill 0.254)
		(layers "F.Cu" "B.Cu")
		(net "P12V_PSU")
	)
	(via
		(at 220.1037 -406.535382)
		(size 0.508)
		(drill 0.254)
		(layers "F.Cu" "B.Cu")
		(net "P12V_PSU")
	)
	(via
		(at 259.7785 -399.72234)
		(size 0.508)
		(drill 0.254)
		(layers "F.Cu" "B.Cu")
		(net "P12V_PSU")
	)
	(via
		(at 266.247626 -402.052282)
		(size 0.508)
		(drill 0.254)
		(layers "F.Cu" "B.Cu")
		(net "P12V_PSU")
	)
	(via
		(at 207.1497 -408.059382)
		(size 0.508)
		(drill 0.254)
		(layers "F.Cu" "B.Cu")
		(net "P12V_PSU")
	)
	(via
		(at 260.5405 -398.96034)
		(size 0.508)
		(drill 0.254)
		(layers "F.Cu" "B.Cu")
		(net "P12V_PSU")
	)
	(via
		(at 210.9597 -406.535382)
		(size 0.508)
		(drill 0.254)
		(layers "F.Cu" "B.Cu")
		(net "P12V_PSU")
	)
	(via
		(at 261.3025 -402.00834)
		(size 0.508)
		(drill 0.254)
		(layers "F.Cu" "B.Cu")
		(net "P12V_PSU")
	)
	(via
		(at 246.00408 -403.49678)
		(size 0.508)
		(drill 0.254)
		(layers "F.Cu" "B.Cu")
		(net "P12V_PSU")
	)
	(via
		(at 251.75464 -401.24634)
		(size 0.508)
		(drill 0.254)
		(layers "F.Cu" "B.Cu")
		(net "P12V_PSU")
	)
	(via
		(at 259.0165 -398.96034)
		(size 0.508)
		(drill 0.254)
		(layers "F.Cu" "B.Cu")
		(net "P12V_PSU")
	)
	(via
		(at 221.6277 -407.297382)
		(size 0.508)
		(drill 0.254)
		(layers "F.Cu" "B.Cu")
		(net "P12V_PSU")
	)
	(via
		(at 187.197492 -406.517602)
		(size 0.508)
		(drill 0.254)
		(layers "F.Cu" "B.Cu")
		(net "P12V_PSU")
	)
	(via
		(at 253.27864 -398.96034)
		(size 0.508)
		(drill 0.254)
		(layers "F.Cu" "B.Cu")
		(net "P12V_PSU")
	)
	(via
		(at 276.453346 -400.568922)
		(size 0.508)
		(drill 0.254)
		(layers "F.Cu" "B.Cu")
		(net "P12V_PSU")
	)
	(via
		(at 253.27864 -399.72234)
		(size 0.508)
		(drill 0.254)
		(layers "F.Cu" "B.Cu")
		(net "P12V_PSU")
	)
	(via
		(at 187.197492 -407.330402)
		(size 0.508)
		(drill 0.254)
		(layers "F.Cu" "B.Cu")
		(net "P12V_PSU")
	)
	(via
		(at 266.247626 -399.766282)
		(size 0.508)
		(drill 0.254)
		(layers "F.Cu" "B.Cu")
		(net "P12V_PSU")
	)
	(via
		(at 268.533626 -402.814282)
		(size 0.508)
		(drill 0.254)
		(layers "F.Cu" "B.Cu")
		(net "P12V_PSU")
	)
	(via
		(at 276.453346 -403.616922)
		(size 0.508)
		(drill 0.254)
		(layers "F.Cu" "B.Cu")
		(net "P12V_PSU")
	)
	(via
		(at 208.782158 -403.223222)
		(size 0.508)
		(drill 0.254)
		(layers "F.Cu" "B.Cu")
		(net "P12V_PSU")
	)
	(via
		(at 210.204558 -403.223222)
		(size 0.508)
		(drill 0.254)
		(layers "F.Cu" "B.Cu")
		(net "P12V_PSU")
	)
	(via
		(at 275.691346 -402.092922)
		(size 0.508)
		(drill 0.254)
		(layers "F.Cu" "B.Cu")
		(net "P12V_PSU")
	)
	(via
		(at 276.453346 -402.092922)
		(size 0.508)
		(drill 0.254)
		(layers "F.Cu" "B.Cu")
		(net "P12V_PSU")
	)
	(via
		(at 241.43208 -399.68678)
		(size 0.508)
		(drill 0.254)
		(layers "F.Cu" "B.Cu")
		(net "P12V_PSU")
	)
	(via
		(at 230.7717 -405.011382)
		(size 0.508)
		(drill 0.254)
		(layers "F.Cu" "B.Cu")
		(net "P12V_PSU")
	)
	(via
		(at 185.673492 -405.755602)
		(size 0.508)
		(drill 0.254)
		(layers "F.Cu" "B.Cu")
		(net "P12V_PSU")
	)
	(via
		(at 245.24208 -400.44878)
		(size 0.508)
		(drill 0.254)
		(layers "F.Cu" "B.Cu")
		(net "P12V_PSU")
	)
	(via
		(at 219.3417 -408.059382)
		(size 0.508)
		(drill 0.254)
		(layers "F.Cu" "B.Cu")
		(net "P12V_PSU")
	)
	(via
		(at 242.19408 -399.68678)
		(size 0.508)
		(drill 0.254)
		(layers "F.Cu" "B.Cu")
		(net "P12V_PSU")
	)
	(via
		(at 242.95608 -400.44878)
		(size 0.508)
		(drill 0.254)
		(layers "F.Cu" "B.Cu")
		(net "P12V_PSU")
	)
	(via
		(at 241.43208 -401.21078)
		(size 0.508)
		(drill 0.254)
		(layers "F.Cu" "B.Cu")
		(net "P12V_PSU")
	)
	(via
		(at 278.739346 -399.044922)
		(size 0.508)
		(drill 0.254)
		(layers "F.Cu" "B.Cu")
		(net "P12V_PSU")
	)
	(via
		(at 200.933558 -403.223222)
		(size 0.508)
		(drill 0.254)
		(layers "F.Cu" "B.Cu")
		(net "P12V_PSU")
	)
	(via
		(at 233.0577 -407.297382)
		(size 0.508)
		(drill 0.254)
		(layers "F.Cu" "B.Cu")
		(net "P12V_PSU")
	)
	(via
		(at 198.7677 -408.059382)
		(size 0.508)
		(drill 0.254)
		(layers "F.Cu" "B.Cu")
		(net "P12V_PSU")
	)
	(via
		(at 241.43208 -403.49678)
		(size 0.508)
		(drill 0.254)
		(layers "F.Cu" "B.Cu")
		(net "P12V_PSU")
	)
	(via
		(at 277.215346 -402.092922)
		(size 0.508)
		(drill 0.254)
		(layers "F.Cu" "B.Cu")
		(net "P12V_PSU")
	)
	(via
		(at 211.7217 -407.297382)
		(size 0.508)
		(drill 0.254)
		(layers "F.Cu" "B.Cu")
		(net "P12V_PSU")
	)
	(via
		(at 254.04064 -400.48434)
		(size 0.508)
		(drill 0.254)
		(layers "F.Cu" "B.Cu")
		(net "P12V_PSU")
	)
	(via
		(at 267.771626 -402.052282)
		(size 0.508)
		(drill 0.254)
		(layers "F.Cu" "B.Cu")
		(net "P12V_PSU")
	)
	(via
		(at 267.009626 -399.004282)
		(size 0.508)
		(drill 0.254)
		(layers "F.Cu" "B.Cu")
		(net "P12V_PSU")
	)
	(via
		(at 266.247626 -399.004282)
		(size 0.508)
		(drill 0.254)
		(layers "F.Cu" "B.Cu")
		(net "P12V_PSU")
	)
	(via
		(at 245.24208 -398.92478)
		(size 0.508)
		(drill 0.254)
		(layers "F.Cu" "B.Cu")
		(net "P12V_PSU")
	)
	(via
		(at 259.0165 -398.19834)
		(size 0.508)
		(drill 0.254)
		(layers "F.Cu" "B.Cu")
		(net "P12V_PSU")
	)
	(via
		(at 230.0097 -405.773382)
		(size 0.508)
		(drill 0.254)
		(layers "F.Cu" "B.Cu")
		(net "P12V_PSU")
	)
	(via
		(at 251.75464 -399.72234)
		(size 0.508)
		(drill 0.254)
		(layers "F.Cu" "B.Cu")
		(net "P12V_PSU")
	)
	(via
		(at 242.95608 -398.16278)
		(size 0.508)
		(drill 0.254)
		(layers "F.Cu" "B.Cu")
		(net "P12V_PSU")
	)
	(via
		(at 260.5405 -400.48434)
		(size 0.508)
		(drill 0.254)
		(layers "F.Cu" "B.Cu")
		(net "P12V_PSU")
	)
	(via
		(at 250.99264 -403.53234)
		(size 0.508)
		(drill 0.254)
		(layers "F.Cu" "B.Cu")
		(net "P12V_PSU")
	)
	(via
		(at 268.533626 -398.242282)
		(size 0.508)
		(drill 0.254)
		(layers "F.Cu" "B.Cu")
		(net "P12V_PSU")
	)
	(via
		(at 208.6737 -407.297382)
		(size 0.508)
		(drill 0.254)
		(layers "F.Cu" "B.Cu")
		(net "P12V_PSU")
	)
	(via
		(at 250.23064 -403.53234)
		(size 0.508)
		(drill 0.254)
		(layers "F.Cu" "B.Cu")
		(net "P12V_PSU")
	)
	(via
		(at 258.2545 -398.96034)
		(size 0.508)
		(drill 0.254)
		(layers "F.Cu" "B.Cu")
		(net "P12V_PSU")
	)
	(via
		(at 259.0165 -399.72234)
		(size 0.508)
		(drill 0.254)
		(layers "F.Cu" "B.Cu")
		(net "P12V_PSU")
	)
	(via
		(at 221.6277 -408.059382)
		(size 0.508)
		(drill 0.254)
		(layers "F.Cu" "B.Cu")
		(net "P12V_PSU")
	)
	(via
		(at 276.453346 -401.330922)
		(size 0.508)
		(drill 0.254)
		(layers "F.Cu" "B.Cu")
		(net "P12V_PSU")
	)
	(via
		(at 218.5797 -408.059382)
		(size 0.508)
		(drill 0.254)
		(layers "F.Cu" "B.Cu")
		(net "P12V_PSU")
	)
	(via
		(at 243.71808 -400.44878)
		(size 0.508)
		(drill 0.254)
		(layers "F.Cu" "B.Cu")
		(net "P12V_PSU")
	)
	(via
		(at 219.450158 -400.617182)
		(size 0.508)
		(drill 0.254)
		(layers "F.Cu" "B.Cu")
		(net "P12V_PSU")
	)
	(via
		(at 260.5405 -398.19834)
		(size 0.508)
		(drill 0.254)
		(layers "F.Cu" "B.Cu")
		(net "P12V_PSU")
	)
	(via
		(at 242.95608 -401.97278)
		(size 0.508)
		(drill 0.254)
		(layers "F.Cu" "B.Cu")
		(net "P12V_PSU")
	)
	(via
		(at 187.67552 -401.919694)
		(size 0.508)
		(drill 0.254)
		(layers "F.Cu" "B.Cu")
		(net "P12V_PSU")
	)
	(via
		(at 276.453346 -399.044922)
		(size 0.508)
		(drill 0.254)
		(layers "F.Cu" "B.Cu")
		(net "P12V_PSU")
	)
	(via
		(at 266.247626 -400.528282)
		(size 0.508)
		(drill 0.254)
		(layers "F.Cu" "B.Cu")
		(net "P12V_PSU")
	)
	(via
		(at 200.933558 -401.920202)
		(size 0.508)
		(drill 0.254)
		(layers "F.Cu" "B.Cu")
		(net "P12V_PSU")
	)
	(via
		(at 200.33234 -378.160534)
		(size 0.508)
		(drill 0.254)
		(layers "F.Cu" "B.Cu")
		(net "P12V_PSU")
	)
	(via
		(at 220.872558 -400.617182)
		(size 0.508)
		(drill 0.254)
		(layers "F.Cu" "B.Cu")
		(net "P12V_PSU")
	)
	(via
		(at 252.51664 -402.00834)
		(size 0.508)
		(drill 0.254)
		(layers "F.Cu" "B.Cu")
		(net "P12V_PSU")
	)
	(via
		(at 232.937558 -401.920202)
		(size 0.508)
		(drill 0.254)
		(layers "F.Cu" "B.Cu")
		(net "P12V_PSU")
	)
	(via
		(at 275.691346 -402.854922)
		(size 0.508)
		(drill 0.254)
		(layers "F.Cu" "B.Cu")
		(net "P12V_PSU")
	)
	(via
		(at 232.2957 -407.297382)
		(size 0.508)
		(drill 0.254)
		(layers "F.Cu" "B.Cu")
		(net "P12V_PSU")
	)
	(via
		(at 198.7677 -407.297382)
		(size 0.508)
		(drill 0.254)
		(layers "F.Cu" "B.Cu")
		(net "P12V_PSU")
	)
	(via
		(at 231.540558 -403.223222)
		(size 0.508)
		(drill 0.254)
		(layers "F.Cu" "B.Cu")
		(net "P12V_PSU")
	)
	(via
		(at 254.04064 -403.53234)
		(size 0.508)
		(drill 0.254)
		(layers "F.Cu" "B.Cu")
		(net "P12V_PSU")
	)
	(via
		(at 260.5405 -399.72234)
		(size 0.508)
		(drill 0.254)
		(layers "F.Cu" "B.Cu")
		(net "P12V_PSU")
	)
	(via
		(at 220.8657 -406.535382)
		(size 0.508)
		(drill 0.254)
		(layers "F.Cu" "B.Cu")
		(net "P12V_PSU")
	)
	(via
		(at 246.00408 -399.68678)
		(size 0.508)
		(drill 0.254)
		(layers "F.Cu" "B.Cu")
		(net "P12V_PSU")
	)
	(via
		(at 270.819626 -402.052282)
		(size 0.508)
		(drill 0.254)
		(layers "F.Cu" "B.Cu")
		(net "P12V_PSU")
	)
	(via
		(at 220.1037 -407.297382)
		(size 0.508)
		(drill 0.254)
		(layers "F.Cu" "B.Cu")
		(net "P12V_PSU")
	)
	(via
		(at 198.0057 -407.297382)
		(size 0.508)
		(drill 0.254)
		(layers "F.Cu" "B.Cu")
		(net "P12V_PSU")
	)
	(via
		(at 243.71808 -401.21078)
		(size 0.508)
		(drill 0.254)
		(layers "F.Cu" "B.Cu")
		(net "P12V_PSU")
	)
	(via
		(at 210.9597 -405.011382)
		(size 0.508)
		(drill 0.254)
		(layers "F.Cu" "B.Cu")
		(net "P12V_PSU")
	)
	(via
		(at 222.3897 -405.011382)
		(size 0.508)
		(drill 0.254)
		(layers "F.Cu" "B.Cu")
		(net "P12V_PSU")
	)
	(via
		(at 268.533626 -401.290282)
		(size 0.508)
		(drill 0.254)
		(layers "F.Cu" "B.Cu")
		(net "P12V_PSU")
	)
	(via
		(at 210.9597 -405.773382)
		(size 0.508)
		(drill 0.254)
		(layers "F.Cu" "B.Cu")
		(net "P12V_PSU")
	)
	(via
		(at 267.771626 -400.528282)
		(size 0.508)
		(drill 0.254)
		(layers "F.Cu" "B.Cu")
		(net "P12V_PSU")
	)
	(via
		(at 278.739346 -399.806922)
		(size 0.508)
		(drill 0.254)
		(layers "F.Cu" "B.Cu")
		(net "P12V_PSU")
	)
	(via
		(at 245.24208 -401.21078)
		(size 0.508)
		(drill 0.254)
		(layers "F.Cu" "B.Cu")
		(net "P12V_PSU")
	)
	(via
		(at 259.0165 -402.77034)
		(size 0.508)
		(drill 0.254)
		(layers "F.Cu" "B.Cu")
		(net "P12V_PSU")
	)
	(via
		(at 277.215346 -400.568922)
		(size 0.508)
		(drill 0.254)
		(layers "F.Cu" "B.Cu")
		(net "P12V_PSU")
	)
	(via
		(at 200.2917 -405.773382)
		(size 0.508)
		(drill 0.254)
		(layers "F.Cu" "B.Cu")
		(net "P12V_PSU")
	)
	(via
		(at 220.1037 -408.059382)
		(size 0.508)
		(drill 0.254)
		(layers "F.Cu" "B.Cu")
		(net "P12V_PSU")
	)
	(via
		(at 258.2545 -403.53234)
		(size 0.508)
		(drill 0.254)
		(layers "F.Cu" "B.Cu")
		(net "P12V_PSU")
	)
	(via
		(at 244.48008 -401.21078)
		(size 0.508)
		(drill 0.254)
		(layers "F.Cu" "B.Cu")
		(net "P12V_PSU")
	)
	(via
		(at 211.601558 -401.920202)
		(size 0.508)
		(drill 0.254)
		(layers "F.Cu" "B.Cu")
		(net "P12V_PSU")
	)
	(via
		(at 277.977346 -402.092922)
		(size 0.508)
		(drill 0.254)
		(layers "F.Cu" "B.Cu")
		(net "P12V_PSU")
	)
	(via
		(at 267.771626 -399.004282)
		(size 0.508)
		(drill 0.254)
		(layers "F.Cu" "B.Cu")
		(net "P12V_PSU")
	)
	(via
		(at 199.5297 -407.297382)
		(size 0.508)
		(drill 0.254)
		(layers "F.Cu" "B.Cu")
		(net "P12V_PSU")
	)
	(via
		(at 259.0165 -402.00834)
		(size 0.508)
		(drill 0.254)
		(layers "F.Cu" "B.Cu")
		(net "P12V_PSU")
	)
	(via
		(at 241.43208 -398.16278)
		(size 0.508)
		(drill 0.254)
		(layers "F.Cu" "B.Cu")
		(net "P12V_PSU")
	)
	(via
		(at 188.721492 -406.517602)
		(size 0.508)
		(drill 0.254)
		(layers "F.Cu" "B.Cu")
		(net "P12V_PSU")
	)
	(segment
		(start 182.65521 -401.919694)
		(end 182.000398 -401.264882)
		(width 0.4572)
		(layer "In15.Cu")
		(net "P12V_PSU")
	)
	(segment
		(start 182.000398 -401.264882)
		(end 182.000398 -400.312382)
		(width 0.4572)
		(layer "In15.Cu")
		(net "P12V_PSU")
	)
	(segment
		(start 182.49773 -395.141958)
		(end 188.839348 -388.80034)
		(width 0.4572)
		(layer "In15.Cu")
		(net "P12V_PSU")
	)
	(segment
		(start 197.305676 -378.894848)
		(end 198.31558 -377.884944)
		(width 0.4572)
		(layer "In15.Cu")
		(net "P12V_PSU")
	)
	(segment
		(start 182.49773 -399.81505)
		(end 182.49773 -395.141958)
		(width 0.4572)
		(layer "In15.Cu")
		(net "P12V_PSU")
	)
	(segment
		(start 184.85612 -401.919694)
		(end 182.65521 -401.919694)
		(width 0.4572)
		(layer "In15.Cu")
		(net "P12V_PSU")
	)
	(segment
		(start 197.305676 -381.972312)
		(end 197.305676 -378.894848)
		(width 0.4572)
		(layer "In15.Cu")
		(net "P12V_PSU")
	)
	(segment
		(start 188.839348 -388.80034)
		(end 192.916302 -388.80034)
		(width 0.4572)
		(layer "In15.Cu")
		(net "P12V_PSU")
	)
	(segment
		(start 194.750944 -384.527044)
		(end 197.305676 -381.972312)
		(width 0.4572)
		(layer "In15.Cu")
		(net "P12V_PSU")
	)
	(segment
		(start 192.916302 -388.80034)
		(end 194.750944 -386.965698)
		(width 0.4572)
		(layer "In15.Cu")
		(net "P12V_PSU")
	)
	(segment
		(start 194.750944 -386.965698)
		(end 194.750944 -384.527044)
		(width 0.4572)
		(layer "In15.Cu")
		(net "P12V_PSU")
	)
	(segment
		(start 198.31558 -377.884944)
		(end 200.05675 -377.884944)
		(width 0.4572)
		(layer "In15.Cu")
		(net "P12V_PSU")
	)
	(segment
		(start 200.05675 -377.884944)
		(end 200.33234 -378.160534)
		(width 0.4572)
		(layer "In15.Cu")
		(net "P12V_PSU")
	)
	(segment
		(start 182.000398 -400.312382)
		(end 182.49773 -399.81505)
		(width 0.4572)
		(layer "In15.Cu")
		(net "P12V_PSU")
	)
	(segment
		(start 78.184502 -24.313896)
		(end 78.185264 -24.314658)
		(width 0.10668)
		(layer "F.Cu")
		(net "P12V_OCP_VCC_2")
	)
	(segment
		(start 77.55001 -23.3299)
		(end 77.528928 -23.308818)
		(width 0.10668)
		(layer "F.Cu")
		(net "P12V_OCP_VCC_2")
	)
	(segment
		(start 78.35646 -22.481286)
		(end 77.528928 -23.308818)
		(width 0.10668)
		(layer "F.Cu")
		(net "P12V_OCP_VCC_2")
	)
	(segment
		(start 78.35646 -21.444204)
		(end 78.35646 -22.481286)
		(width 0.10668)
		(layer "F.Cu")
		(net "P12V_OCP_VCC_2")
	)
	(segment
		(start 77.55001 -24.313896)
		(end 78.184502 -24.313896)
		(width 0.10668)
		(layer "F.Cu")
		(net "P12V_OCP_VCC_2")
	)
	(segment
		(start 77.55001 -24.313896)
		(end 77.55001 -23.3299)
		(width 0.10668)
		(layer "F.Cu")
		(net "P12V_OCP_VCC_2")
	)
	(via
		(at 78.185264 -24.314658)
		(size 0.508)
		(drill 0.254)
		(layers "F.Cu" "B.Cu")
		(net "P12V_OCP_VCC_2")
	)
	(segment
		(start 450.050662 -22.876002)
		(end 450.488558 -22.438106)
		(width 0.10668)
		(layer "F.Cu")
		(net "P12V_OCP_VCC_1")
	)
	(segment
		(start 450.497194 -22.42947)
		(end 450.488558 -22.438106)
		(width 0.10668)
		(layer "F.Cu")
		(net "P12V_OCP_VCC_1")
	)
	(segment
		(start 450.050662 -23.594314)
		(end 450.050662 -22.876002)
		(width 0.10668)
		(layer "F.Cu")
		(net "P12V_OCP_VCC_1")
	)
	(segment
		(start 450.060314 -24.70023)
		(end 450.060314 -23.603966)
		(width 0.10668)
		(layer "F.Cu")
		(net "P12V_OCP_VCC_1")
	)
	(segment
		(start 450.497194 -21.7297)
		(end 450.497194 -22.42947)
		(width 0.10668)
		(layer "F.Cu")
		(net "P12V_OCP_VCC_1")
	)
	(segment
		(start 450.060314 -23.603966)
		(end 450.050662 -23.594314)
		(width 0.10668)
		(layer "F.Cu")
		(net "P12V_OCP_VCC_1")
	)
	(via
		(at 450.488558 -22.438106)
		(size 0.508)
		(drill 0.254)
		(layers "F.Cu" "B.Cu")
		(net "P12V_OCP_VCC_1")
	)
	(segment
		(start 61.543438 -32.287972)
		(end 61.543438 -32.942022)
		(width 0.254)
		(layer "F.Cu")
		(net "P12V_OCP_V3_2_ISENSE_MPS_TIC")
	)
	(segment
		(start 324.037198 -44.716954)
		(end 324.646798 -44.716954)
		(width 0.254)
		(layer "F.Cu")
		(net "P12V_OCP_V3_2_ISENSE_MPS_TIC")
	)
	(segment
		(start 61.543438 -32.942022)
		(end 61.282834 -33.202626)
		(width 0.254)
		(layer "F.Cu")
		(net "P12V_OCP_V3_2_ISENSE_MPS_TIC")
	)
	(via
		(at 61.282834 -33.202626)
		(size 0.508)
		(drill 0.254)
		(layers "F.Cu" "B.Cu")
		(net "P12V_OCP_V3_2_ISENSE_MPS_TIC")
	)
	(via
		(at 324.646798 -44.716954)
		(size 0.508)
		(drill 0.254)
		(layers "F.Cu" "B.Cu")
		(net "P12V_OCP_V3_2_ISENSE_MPS_TIC")
	)
	(via
		(at 320.839084 -30.739588)
		(size 0.508)
		(drill 0.254)
		(layers "F.Cu" "B.Cu")
		(net "P12V_OCP_V3_2_ISENSE_MPS_TIC")
	)
	(segment
		(start 322.8975 -42.967656)
		(end 324.646798 -44.716954)
		(width 0.254)
		(layer "In4.Cu")
		(net "P12V_OCP_V3_2_ISENSE_MPS_TIC")
	)
	(segment
		(start 322.8975 -30.408372)
		(end 322.8975 -42.967656)
		(width 0.254)
		(layer "In4.Cu")
		(net "P12V_OCP_V3_2_ISENSE_MPS_TIC")
	)
	(segment
		(start 320.846704 -30.739588)
		(end 321.43192 -30.154372)
		(width 0.254)
		(layer "In4.Cu")
		(net "P12V_OCP_V3_2_ISENSE_MPS_TIC")
	)
	(segment
		(start 322.6435 -30.154372)
		(end 322.8975 -30.408372)
		(width 0.254)
		(layer "In4.Cu")
		(net "P12V_OCP_V3_2_ISENSE_MPS_TIC")
	)
	(segment
		(start 320.839084 -30.739588)
		(end 320.846704 -30.739588)
		(width 0.254)
		(layer "In4.Cu")
		(net "P12V_OCP_V3_2_ISENSE_MPS_TIC")
	)
	(segment
		(start 321.43192 -30.154372)
		(end 322.6435 -30.154372)
		(width 0.254)
		(layer "In4.Cu")
		(net "P12V_OCP_V3_2_ISENSE_MPS_TIC")
	)
	(segment
		(start 154.582876 -45.87494)
		(end 148.4884 -45.87494)
		(width 0.254)
		(layer "In6.Cu")
		(net "P12V_OCP_V3_2_ISENSE_MPS_TIC")
	)
	(segment
		(start 61.503814 -32.981646)
		(end 61.282834 -33.202626)
		(width 0.254)
		(layer "In6.Cu")
		(net "P12V_OCP_V3_2_ISENSE_MPS_TIC")
	)
	(segment
		(start 96.44761 -39.63289)
		(end 94.414086 -40.4749)
		(width 0.254)
		(layer "In6.Cu")
		(net "P12V_OCP_V3_2_ISENSE_MPS_TIC")
	)
	(segment
		(start 260.65226 -63.79464)
		(end 239.027462 -63.79464)
		(width 0.254)
		(layer "In6.Cu")
		(net "P12V_OCP_V3_2_ISENSE_MPS_TIC")
	)
	(segment
		(start 193.285364 -43.918378)
		(end 191.913002 -45.29074)
		(width 0.254)
		(layer "In6.Cu")
		(net "P12V_OCP_V3_2_ISENSE_MPS_TIC")
	)
	(segment
		(start 98.964242 -39.63289)
		(end 96.44761 -39.63289)
		(width 0.254)
		(layer "In6.Cu")
		(net "P12V_OCP_V3_2_ISENSE_MPS_TIC")
	)
	(segment
		(start 187.89396 -45.29074)
		(end 182.975504 -40.372284)
		(width 0.254)
		(layer "In6.Cu")
		(net "P12V_OCP_V3_2_ISENSE_MPS_TIC")
	)
	(segment
		(start 70.920102 -33.866836)
		(end 70.819518 -33.96742)
		(width 0.254)
		(layer "In6.Cu")
		(net "P12V_OCP_V3_2_ISENSE_MPS_TIC")
	)
	(segment
		(start 292.33876 -30.52318)
		(end 290.559236 -32.302704)
		(width 0.254)
		(layer "In6.Cu")
		(net "P12V_OCP_V3_2_ISENSE_MPS_TIC")
	)
	(segment
		(start 320.839084 -30.739588)
		(end 320.813684 -30.739588)
		(width 0.254)
		(layer "In6.Cu")
		(net "P12V_OCP_V3_2_ISENSE_MPS_TIC")
	)
	(segment
		(start 62.70498 -32.981646)
		(end 61.503814 -32.981646)
		(width 0.254)
		(layer "In6.Cu")
		(net "P12V_OCP_V3_2_ISENSE_MPS_TIC")
	)
	(segment
		(start 115.444016 -44.80814)
		(end 115.443508 -44.80814)
		(width 0.254)
		(layer "In6.Cu")
		(net "P12V_OCP_V3_2_ISENSE_MPS_TIC")
	)
	(segment
		(start 290.559236 -39.426896)
		(end 270.101822 -59.88431)
		(width 0.254)
		(layer "In6.Cu")
		(net "P12V_OCP_V3_2_ISENSE_MPS_TIC")
	)
	(segment
		(start 107.508802 -45.37964)
		(end 103.740204 -41.611042)
		(width 0.254)
		(layer "In6.Cu")
		(net "P12V_OCP_V3_2_ISENSE_MPS_TIC")
	)
	(segment
		(start 239.027462 -63.79464)
		(end 238.453168 -64.368934)
		(width 0.254)
		(layer "In6.Cu")
		(net "P12V_OCP_V3_2_ISENSE_MPS_TIC")
	)
	(segment
		(start 115.871752 -44.380404)
		(end 115.444016 -44.80814)
		(width 0.254)
		(layer "In6.Cu")
		(net "P12V_OCP_V3_2_ISENSE_MPS_TIC")
	)
	(segment
		(start 103.740204 -41.611042)
		(end 98.964242 -39.63289)
		(width 0.254)
		(layer "In6.Cu")
		(net "P12V_OCP_V3_2_ISENSE_MPS_TIC")
	)
	(segment
		(start 290.559236 -32.302704)
		(end 290.559236 -39.426896)
		(width 0.254)
		(layer "In6.Cu")
		(net "P12V_OCP_V3_2_ISENSE_MPS_TIC")
	)
	(segment
		(start 162.531552 -39.405052)
		(end 160.789366 -41.147238)
		(width 0.254)
		(layer "In6.Cu")
		(net "P12V_OCP_V3_2_ISENSE_MPS_TIC")
	)
	(segment
		(start 148.4884 -45.87494)
		(end 147.4216 -44.80814)
		(width 0.254)
		(layer "In6.Cu")
		(net "P12V_OCP_V3_2_ISENSE_MPS_TIC")
	)
	(segment
		(start 115.443508 -44.80814)
		(end 114.872008 -45.37964)
		(width 0.254)
		(layer "In6.Cu")
		(net "P12V_OCP_V3_2_ISENSE_MPS_TIC")
	)
	(segment
		(start 158.121096 -45.690536)
		(end 154.76728 -45.690536)
		(width 0.254)
		(layer "In6.Cu")
		(net "P12V_OCP_V3_2_ISENSE_MPS_TIC")
	)
	(segment
		(start 264.56259 -59.88431)
		(end 260.65226 -63.79464)
		(width 0.254)
		(layer "In6.Cu")
		(net "P12V_OCP_V3_2_ISENSE_MPS_TIC")
	)
	(segment
		(start 211.98586 -43.384724)
		(end 211.452206 -43.918378)
		(width 0.254)
		(layer "In6.Cu")
		(net "P12V_OCP_V3_2_ISENSE_MPS_TIC")
	)
	(segment
		(start 238.453168 -64.368934)
		(end 227.917756 -64.368934)
		(width 0.254)
		(layer "In6.Cu")
		(net "P12V_OCP_V3_2_ISENSE_MPS_TIC")
	)
	(segment
		(start 154.76728 -45.690536)
		(end 154.582876 -45.87494)
		(width 0.254)
		(layer "In6.Cu")
		(net "P12V_OCP_V3_2_ISENSE_MPS_TIC")
	)
	(segment
		(start 160.789366 -41.147238)
		(end 160.789366 -43.022266)
		(width 0.254)
		(layer "In6.Cu")
		(net "P12V_OCP_V3_2_ISENSE_MPS_TIC")
	)
	(segment
		(start 69.071998 -33.398968)
		(end 63.122302 -33.398968)
		(width 0.254)
		(layer "In6.Cu")
		(net "P12V_OCP_V3_2_ISENSE_MPS_TIC")
	)
	(segment
		(start 73.699624 -33.866836)
		(end 70.920102 -33.866836)
		(width 0.254)
		(layer "In6.Cu")
		(net "P12V_OCP_V3_2_ISENSE_MPS_TIC")
	)
	(segment
		(start 270.101822 -59.88431)
		(end 264.56259 -59.88431)
		(width 0.254)
		(layer "In6.Cu")
		(net "P12V_OCP_V3_2_ISENSE_MPS_TIC")
	)
	(segment
		(start 89.246456 -40.4749)
		(end 84.478114 -35.706558)
		(width 0.254)
		(layer "In6.Cu")
		(net "P12V_OCP_V3_2_ISENSE_MPS_TIC")
	)
	(segment
		(start 129.082546 -44.80814)
		(end 128.65481 -44.380404)
		(width 0.254)
		(layer "In6.Cu")
		(net "P12V_OCP_V3_2_ISENSE_MPS_TIC")
	)
	(segment
		(start 78.141322 -35.706558)
		(end 73.699624 -33.866836)
		(width 0.254)
		(layer "In6.Cu")
		(net "P12V_OCP_V3_2_ISENSE_MPS_TIC")
	)
	(segment
		(start 147.4216 -44.80814)
		(end 129.082546 -44.80814)
		(width 0.254)
		(layer "In6.Cu")
		(net "P12V_OCP_V3_2_ISENSE_MPS_TIC")
	)
	(segment
		(start 70.819518 -33.96742)
		(end 69.64045 -33.96742)
		(width 0.254)
		(layer "In6.Cu")
		(net "P12V_OCP_V3_2_ISENSE_MPS_TIC")
	)
	(segment
		(start 84.478114 -35.706558)
		(end 78.141322 -35.706558)
		(width 0.254)
		(layer "In6.Cu")
		(net "P12V_OCP_V3_2_ISENSE_MPS_TIC")
	)
	(segment
		(start 218.50223 -54.953408)
		(end 218.50223 -47.507144)
		(width 0.254)
		(layer "In6.Cu")
		(net "P12V_OCP_V3_2_ISENSE_MPS_TIC")
	)
	(segment
		(start 179.852066 -39.405052)
		(end 162.531552 -39.405052)
		(width 0.254)
		(layer "In6.Cu")
		(net "P12V_OCP_V3_2_ISENSE_MPS_TIC")
	)
	(segment
		(start 160.789366 -43.022266)
		(end 158.121096 -45.690536)
		(width 0.254)
		(layer "In6.Cu")
		(net "P12V_OCP_V3_2_ISENSE_MPS_TIC")
	)
	(segment
		(start 320.597276 -30.52318)
		(end 292.33876 -30.52318)
		(width 0.254)
		(layer "In6.Cu")
		(net "P12V_OCP_V3_2_ISENSE_MPS_TIC")
	)
	(segment
		(start 227.917756 -64.368934)
		(end 218.50223 -54.953408)
		(width 0.254)
		(layer "In6.Cu")
		(net "P12V_OCP_V3_2_ISENSE_MPS_TIC")
	)
	(segment
		(start 320.813684 -30.739588)
		(end 320.597276 -30.52318)
		(width 0.254)
		(layer "In6.Cu")
		(net "P12V_OCP_V3_2_ISENSE_MPS_TIC")
	)
	(segment
		(start 191.913002 -45.29074)
		(end 187.89396 -45.29074)
		(width 0.254)
		(layer "In6.Cu")
		(net "P12V_OCP_V3_2_ISENSE_MPS_TIC")
	)
	(segment
		(start 114.872008 -45.37964)
		(end 107.508802 -45.37964)
		(width 0.254)
		(layer "In6.Cu")
		(net "P12V_OCP_V3_2_ISENSE_MPS_TIC")
	)
	(segment
		(start 128.65481 -44.380404)
		(end 115.871752 -44.380404)
		(width 0.254)
		(layer "In6.Cu")
		(net "P12V_OCP_V3_2_ISENSE_MPS_TIC")
	)
	(segment
		(start 211.452206 -43.918378)
		(end 193.285364 -43.918378)
		(width 0.254)
		(layer "In6.Cu")
		(net "P12V_OCP_V3_2_ISENSE_MPS_TIC")
	)
	(segment
		(start 180.819298 -40.372284)
		(end 179.852066 -39.405052)
		(width 0.254)
		(layer "In6.Cu")
		(net "P12V_OCP_V3_2_ISENSE_MPS_TIC")
	)
	(segment
		(start 214.37981 -43.384724)
		(end 211.98586 -43.384724)
		(width 0.254)
		(layer "In6.Cu")
		(net "P12V_OCP_V3_2_ISENSE_MPS_TIC")
	)
	(segment
		(start 63.122302 -33.398968)
		(end 62.70498 -32.981646)
		(width 0.254)
		(layer "In6.Cu")
		(net "P12V_OCP_V3_2_ISENSE_MPS_TIC")
	)
	(segment
		(start 182.975504 -40.372284)
		(end 180.819298 -40.372284)
		(width 0.254)
		(layer "In6.Cu")
		(net "P12V_OCP_V3_2_ISENSE_MPS_TIC")
	)
	(segment
		(start 218.50223 -47.507144)
		(end 214.37981 -43.384724)
		(width 0.254)
		(layer "In6.Cu")
		(net "P12V_OCP_V3_2_ISENSE_MPS_TIC")
	)
	(segment
		(start 69.64045 -33.96742)
		(end 69.071998 -33.398968)
		(width 0.254)
		(layer "In6.Cu")
		(net "P12V_OCP_V3_2_ISENSE_MPS_TIC")
	)
	(segment
		(start 94.414086 -40.4749)
		(end 89.246456 -40.4749)
		(width 0.254)
		(layer "In6.Cu")
		(net "P12V_OCP_V3_2_ISENSE_MPS_TIC")
	)
	(segment
		(start 62.559438 -32.287972)
		(end 62.559438 -32.994346)
		(width 0.254)
		(layer "F.Cu")
		(net "P12V_OCP_V3_2_ISENSE_MPS_MAM")
	)
	(segment
		(start 312.742072 -32.572706)
		(end 313.351672 -32.572706)
		(width 0.254)
		(layer "F.Cu")
		(net "P12V_OCP_V3_2_ISENSE_MPS_MAM")
	)
	(segment
		(start 62.559438 -32.994346)
		(end 61.928502 -33.625282)
		(width 0.254)
		(layer "F.Cu")
		(net "P12V_OCP_V3_2_ISENSE_MPS_MAM")
	)
	(via
		(at 61.928502 -33.625282)
		(size 0.762)
		(drill 0.254)
		(layers "F.Cu" "B.Cu")
		(net "P12V_OCP_V3_2_ISENSE_MPS_MAM")
	)
	(via
		(at 313.351672 -32.572706)
		(size 0.508)
		(drill 0.254)
		(layers "F.Cu" "B.Cu")
		(net "P12V_OCP_V3_2_ISENSE_MPS_MAM")
	)
	(segment
		(start 69.000116 -34.577528)
		(end 71.072248 -34.577528)
		(width 0.254)
		(layer "In6.Cu")
		(net "P12V_OCP_V3_2_ISENSE_MPS_MAM")
	)
	(segment
		(start 153.136854 -46.33214)
		(end 153.728928 -46.924214)
		(width 0.254)
		(layer "In6.Cu")
		(net "P12V_OCP_V3_2_ISENSE_MPS_MAM")
	)
	(segment
		(start 238.65459 -64.854836)
		(end 239.228884 -64.280542)
		(width 0.254)
		(layer "In6.Cu")
		(net "P12V_OCP_V3_2_ISENSE_MPS_MAM")
	)
	(segment
		(start 153.728928 -46.924214)
		(end 159.9819 -46.924214)
		(width 0.254)
		(layer "In6.Cu")
		(net "P12V_OCP_V3_2_ISENSE_MPS_MAM")
	)
	(segment
		(start 291.045138 -39.628318)
		(end 291.045138 -32.504126)
		(width 0.254)
		(layer "In6.Cu")
		(net "P12V_OCP_V3_2_ISENSE_MPS_MAM")
	)
	(segment
		(start 62.880748 -34.577528)
		(end 66.550032 -34.577528)
		(width 0.254)
		(layer "In6.Cu")
		(net "P12V_OCP_V3_2_ISENSE_MPS_MAM")
	)
	(segment
		(start 84.225384 -36.316666)
		(end 88.840818 -40.9321)
		(width 0.254)
		(layer "In6.Cu")
		(net "P12V_OCP_V3_2_ISENSE_MPS_MAM")
	)
	(segment
		(start 103.48087 -41.998646)
		(end 107.319064 -45.83684)
		(width 0.254)
		(layer "In6.Cu")
		(net "P12V_OCP_V3_2_ISENSE_MPS_MAM")
	)
	(segment
		(start 218.016328 -47.708566)
		(end 218.016328 -55.15483)
		(width 0.254)
		(layer "In6.Cu")
		(net "P12V_OCP_V3_2_ISENSE_MPS_MAM")
	)
	(segment
		(start 128.892808 -45.26534)
		(end 146.9898 -45.26534)
		(width 0.254)
		(layer "In6.Cu")
		(net "P12V_OCP_V3_2_ISENSE_MPS_MAM")
	)
	(segment
		(start 264.764012 -60.370212)
		(end 270.303244 -60.370212)
		(width 0.254)
		(layer "In6.Cu")
		(net "P12V_OCP_V3_2_ISENSE_MPS_MAM")
	)
	(segment
		(start 212.37448 -43.871388)
		(end 214.17915 -43.871388)
		(width 0.254)
		(layer "In6.Cu")
		(net "P12V_OCP_V3_2_ISENSE_MPS_MAM")
	)
	(segment
		(start 180.629814 -40.829484)
		(end 182.78602 -40.829484)
		(width 0.254)
		(layer "In6.Cu")
		(net "P12V_OCP_V3_2_ISENSE_MPS_MAM")
	)
	(segment
		(start 71.172832 -34.476944)
		(end 73.855072 -34.476944)
		(width 0.254)
		(layer "In6.Cu")
		(net "P12V_OCP_V3_2_ISENSE_MPS_MAM")
	)
	(segment
		(start 260.853682 -64.280542)
		(end 264.764012 -60.370212)
		(width 0.254)
		(layer "In6.Cu")
		(net "P12V_OCP_V3_2_ISENSE_MPS_MAM")
	)
	(segment
		(start 227.716334 -64.854836)
		(end 238.65459 -64.854836)
		(width 0.254)
		(layer "In6.Cu")
		(net "P12V_OCP_V3_2_ISENSE_MPS_MAM")
	)
	(segment
		(start 239.228884 -64.280542)
		(end 260.853682 -64.280542)
		(width 0.254)
		(layer "In6.Cu")
		(net "P12V_OCP_V3_2_ISENSE_MPS_MAM")
	)
	(segment
		(start 146.9898 -45.26534)
		(end 148.0566 -46.33214)
		(width 0.254)
		(layer "In6.Cu")
		(net "P12V_OCP_V3_2_ISENSE_MPS_MAM")
	)
	(segment
		(start 61.928502 -33.625282)
		(end 62.880748 -34.577528)
		(width 0.254)
		(layer "In6.Cu")
		(net "P12V_OCP_V3_2_ISENSE_MPS_MAM")
	)
	(segment
		(start 99.46132 -40.333676)
		(end 103.48087 -41.998646)
		(width 0.254)
		(layer "In6.Cu")
		(net "P12V_OCP_V3_2_ISENSE_MPS_MAM")
	)
	(segment
		(start 179.764182 -39.963852)
		(end 180.629814 -40.829484)
		(width 0.254)
		(layer "In6.Cu")
		(net "P12V_OCP_V3_2_ISENSE_MPS_MAM")
	)
	(segment
		(start 68.58762 -34.165032)
		(end 69.000116 -34.577528)
		(width 0.254)
		(layer "In6.Cu")
		(net "P12V_OCP_V3_2_ISENSE_MPS_MAM")
	)
	(segment
		(start 115.062 -45.83684)
		(end 116.061236 -44.837604)
		(width 0.254)
		(layer "In6.Cu")
		(net "P12V_OCP_V3_2_ISENSE_MPS_MAM")
	)
	(segment
		(start 71.072248 -34.577528)
		(end 71.172832 -34.476944)
		(width 0.254)
		(layer "In6.Cu")
		(net "P12V_OCP_V3_2_ISENSE_MPS_MAM")
	)
	(segment
		(start 182.78602 -40.829484)
		(end 187.704476 -45.74794)
		(width 0.254)
		(layer "In6.Cu")
		(net "P12V_OCP_V3_2_ISENSE_MPS_MAM")
	)
	(segment
		(start 96.822006 -40.333676)
		(end 99.46132 -40.333676)
		(width 0.254)
		(layer "In6.Cu")
		(net "P12V_OCP_V3_2_ISENSE_MPS_MAM")
	)
	(segment
		(start 107.319064 -45.83684)
		(end 115.062 -45.83684)
		(width 0.254)
		(layer "In6.Cu")
		(net "P12V_OCP_V3_2_ISENSE_MPS_MAM")
	)
	(segment
		(start 193.474848 -44.375578)
		(end 211.87029 -44.375578)
		(width 0.254)
		(layer "In6.Cu")
		(net "P12V_OCP_V3_2_ISENSE_MPS_MAM")
	)
	(segment
		(start 66.962528 -34.165032)
		(end 68.58762 -34.165032)
		(width 0.254)
		(layer "In6.Cu")
		(net "P12V_OCP_V3_2_ISENSE_MPS_MAM")
	)
	(segment
		(start 88.840818 -40.9321)
		(end 95.377254 -40.9321)
		(width 0.254)
		(layer "In6.Cu")
		(net "P12V_OCP_V3_2_ISENSE_MPS_MAM")
	)
	(segment
		(start 128.465072 -44.837604)
		(end 128.892808 -45.26534)
		(width 0.254)
		(layer "In6.Cu")
		(net "P12V_OCP_V3_2_ISENSE_MPS_MAM")
	)
	(segment
		(start 211.87029 -44.375578)
		(end 212.37448 -43.871388)
		(width 0.254)
		(layer "In6.Cu")
		(net "P12V_OCP_V3_2_ISENSE_MPS_MAM")
	)
	(segment
		(start 95.377254 -40.9321)
		(end 96.822006 -40.333676)
		(width 0.254)
		(layer "In6.Cu")
		(net "P12V_OCP_V3_2_ISENSE_MPS_MAM")
	)
	(segment
		(start 187.704476 -45.74794)
		(end 192.102486 -45.74794)
		(width 0.254)
		(layer "In6.Cu")
		(net "P12V_OCP_V3_2_ISENSE_MPS_MAM")
	)
	(segment
		(start 311.788048 -31.009082)
		(end 313.351672 -32.572706)
		(width 0.254)
		(layer "In6.Cu")
		(net "P12V_OCP_V3_2_ISENSE_MPS_MAM")
	)
	(segment
		(start 166.942262 -39.963852)
		(end 179.764182 -39.963852)
		(width 0.254)
		(layer "In6.Cu")
		(net "P12V_OCP_V3_2_ISENSE_MPS_MAM")
	)
	(segment
		(start 192.102486 -45.74794)
		(end 193.474848 -44.375578)
		(width 0.254)
		(layer "In6.Cu")
		(net "P12V_OCP_V3_2_ISENSE_MPS_MAM")
	)
	(segment
		(start 292.540182 -31.009082)
		(end 311.788048 -31.009082)
		(width 0.254)
		(layer "In6.Cu")
		(net "P12V_OCP_V3_2_ISENSE_MPS_MAM")
	)
	(segment
		(start 214.17915 -43.871388)
		(end 218.016328 -47.708566)
		(width 0.254)
		(layer "In6.Cu")
		(net "P12V_OCP_V3_2_ISENSE_MPS_MAM")
	)
	(segment
		(start 78.297024 -36.316666)
		(end 84.225384 -36.316666)
		(width 0.254)
		(layer "In6.Cu")
		(net "P12V_OCP_V3_2_ISENSE_MPS_MAM")
	)
	(segment
		(start 148.0566 -46.33214)
		(end 153.136854 -46.33214)
		(width 0.254)
		(layer "In6.Cu")
		(net "P12V_OCP_V3_2_ISENSE_MPS_MAM")
	)
	(segment
		(start 66.550032 -34.577528)
		(end 66.962528 -34.165032)
		(width 0.254)
		(layer "In6.Cu")
		(net "P12V_OCP_V3_2_ISENSE_MPS_MAM")
	)
	(segment
		(start 270.303244 -60.370212)
		(end 291.045138 -39.628318)
		(width 0.254)
		(layer "In6.Cu")
		(net "P12V_OCP_V3_2_ISENSE_MPS_MAM")
	)
	(segment
		(start 73.855072 -34.476944)
		(end 78.297024 -36.316666)
		(width 0.254)
		(layer "In6.Cu")
		(net "P12V_OCP_V3_2_ISENSE_MPS_MAM")
	)
	(segment
		(start 291.045138 -32.504126)
		(end 292.540182 -31.009082)
		(width 0.254)
		(layer "In6.Cu")
		(net "P12V_OCP_V3_2_ISENSE_MPS_MAM")
	)
	(segment
		(start 116.061236 -44.837604)
		(end 128.465072 -44.837604)
		(width 0.254)
		(layer "In6.Cu")
		(net "P12V_OCP_V3_2_ISENSE_MPS_MAM")
	)
	(segment
		(start 159.9819 -46.924214)
		(end 166.942262 -39.963852)
		(width 0.254)
		(layer "In6.Cu")
		(net "P12V_OCP_V3_2_ISENSE_MPS_MAM")
	)
	(segment
		(start 218.016328 -55.15483)
		(end 227.716334 -64.854836)
		(width 0.254)
		(layer "In6.Cu")
		(net "P12V_OCP_V3_2_ISENSE_MPS_MAM")
	)
	(segment
		(start 59.727338 -32.287972)
		(end 59.727338 -31.60649)
		(width 0.254)
		(layer "F.Cu")
		(net "P12V_OCP_V3_2_ISENSE_MAM_TIC")
	)
	(segment
		(start 322.436998 -44.716954)
		(end 322.086732 -44.716954)
		(width 0.254)
		(layer "F.Cu")
		(net "P12V_OCP_V3_2_ISENSE_MAM_TIC")
	)
	(segment
		(start 322.086732 -44.716954)
		(end 321.827398 -44.45762)
		(width 0.254)
		(layer "F.Cu")
		(net "P12V_OCP_V3_2_ISENSE_MAM_TIC")
	)
	(via
		(at 322.363084 -30.739588)
		(size 0.508)
		(drill 0.254)
		(layers "F.Cu" "B.Cu")
		(net "P12V_OCP_V3_2_ISENSE_MAM_TIC")
	)
	(via
		(at 321.827398 -44.45762)
		(size 0.508)
		(drill 0.254)
		(layers "F.Cu" "B.Cu")
		(net "P12V_OCP_V3_2_ISENSE_MAM_TIC")
	)
	(via
		(at 59.727338 -31.60649)
		(size 0.508)
		(drill 0.254)
		(layers "F.Cu" "B.Cu")
		(net "P12V_OCP_V3_2_ISENSE_MAM_TIC")
	)
	(segment
		(start 322.363084 -30.739588)
		(end 322.363084 -43.921934)
		(width 0.254)
		(layer "In4.Cu")
		(net "P12V_OCP_V3_2_ISENSE_MAM_TIC")
	)
	(segment
		(start 322.363084 -43.921934)
		(end 321.827398 -44.45762)
		(width 0.254)
		(layer "In4.Cu")
		(net "P12V_OCP_V3_2_ISENSE_MAM_TIC")
	)
	(segment
		(start 128.844548 -43.923204)
		(end 115.682014 -43.923204)
		(width 0.254)
		(layer "In6.Cu")
		(net "P12V_OCP_V3_2_ISENSE_MAM_TIC")
	)
	(segment
		(start 115.254024 -44.35094)
		(end 114.682524 -44.92244)
		(width 0.254)
		(layer "In6.Cu")
		(net "P12V_OCP_V3_2_ISENSE_MAM_TIC")
	)
	(segment
		(start 129.272284 -44.35094)
		(end 128.844548 -43.923204)
		(width 0.254)
		(layer "In6.Cu")
		(net "P12V_OCP_V3_2_ISENSE_MAM_TIC")
	)
	(segment
		(start 322.363084 -30.739588)
		(end 321.648836 -30.02534)
		(width 0.254)
		(layer "In6.Cu")
		(net "P12V_OCP_V3_2_ISENSE_MAM_TIC")
	)
	(segment
		(start 63.361824 -32.934148)
		(end 62.034166 -31.60649)
		(width 0.254)
		(layer "In6.Cu")
		(net "P12V_OCP_V3_2_ISENSE_MAM_TIC")
	)
	(segment
		(start 219.00007 -54.74716)
		(end 219.00007 -47.300896)
		(width 0.254)
		(layer "In6.Cu")
		(net "P12V_OCP_V3_2_ISENSE_MAM_TIC")
	)
	(segment
		(start 147.249388 -44.35094)
		(end 129.272284 -44.35094)
		(width 0.254)
		(layer "In6.Cu")
		(net "P12V_OCP_V3_2_ISENSE_MAM_TIC")
	)
	(segment
		(start 181.008782 -39.915084)
		(end 179.76723 -38.673532)
		(width 0.254)
		(layer "In6.Cu")
		(net "P12V_OCP_V3_2_ISENSE_MAM_TIC")
	)
	(segment
		(start 260.446012 -63.2968)
		(end 238.821214 -63.2968)
		(width 0.254)
		(layer "In6.Cu")
		(net "P12V_OCP_V3_2_ISENSE_MAM_TIC")
	)
	(segment
		(start 62.034166 -31.60649)
		(end 59.727338 -31.60649)
		(width 0.254)
		(layer "In6.Cu")
		(net "P12V_OCP_V3_2_ISENSE_MAM_TIC")
	)
	(segment
		(start 176.834038 -38.673532)
		(end 176.007776 -37.84727)
		(width 0.254)
		(layer "In6.Cu")
		(net "P12V_OCP_V3_2_ISENSE_MAM_TIC")
	)
	(segment
		(start 172.505116 -38.781228)
		(end 162.476434 -38.781228)
		(width 0.254)
		(layer "In6.Cu")
		(net "P12V_OCP_V3_2_ISENSE_MAM_TIC")
	)
	(segment
		(start 73.738994 -33.368996)
		(end 70.713854 -33.368996)
		(width 0.254)
		(layer "In6.Cu")
		(net "P12V_OCP_V3_2_ISENSE_MAM_TIC")
	)
	(segment
		(start 149.561296 -43.853608)
		(end 147.74672 -43.853608)
		(width 0.254)
		(layer "In6.Cu")
		(net "P12V_OCP_V3_2_ISENSE_MAM_TIC")
	)
	(segment
		(start 264.356342 -59.38647)
		(end 260.446012 -63.2968)
		(width 0.254)
		(layer "In6.Cu")
		(net "P12V_OCP_V3_2_ISENSE_MAM_TIC")
	)
	(segment
		(start 69.311266 -32.934148)
		(end 63.361824 -32.934148)
		(width 0.254)
		(layer "In6.Cu")
		(net "P12V_OCP_V3_2_ISENSE_MAM_TIC")
	)
	(segment
		(start 214.586058 -42.886884)
		(end 211.779612 -42.886884)
		(width 0.254)
		(layer "In6.Cu")
		(net "P12V_OCP_V3_2_ISENSE_MAM_TIC")
	)
	(segment
		(start 114.682524 -44.92244)
		(end 108.630974 -44.92244)
		(width 0.254)
		(layer "In6.Cu")
		(net "P12V_OCP_V3_2_ISENSE_MAM_TIC")
	)
	(segment
		(start 69.846698 -33.46958)
		(end 69.311266 -32.934148)
		(width 0.254)
		(layer "In6.Cu")
		(net "P12V_OCP_V3_2_ISENSE_MAM_TIC")
	)
	(segment
		(start 160.248346 -41.009316)
		(end 160.248346 -42.859198)
		(width 0.254)
		(layer "In6.Cu")
		(net "P12V_OCP_V3_2_ISENSE_MAM_TIC")
	)
	(segment
		(start 94.323154 -40.0177)
		(end 89.493344 -40.0177)
		(width 0.254)
		(layer "In6.Cu")
		(net "P12V_OCP_V3_2_ISENSE_MAM_TIC")
	)
	(segment
		(start 115.254278 -44.35094)
		(end 115.254024 -44.35094)
		(width 0.254)
		(layer "In6.Cu")
		(net "P12V_OCP_V3_2_ISENSE_MAM_TIC")
	)
	(segment
		(start 290.061396 -39.220648)
		(end 269.895574 -59.38647)
		(width 0.254)
		(layer "In6.Cu")
		(net "P12V_OCP_V3_2_ISENSE_MAM_TIC")
	)
	(segment
		(start 115.682014 -43.923204)
		(end 115.254278 -44.35094)
		(width 0.254)
		(layer "In6.Cu")
		(net "P12V_OCP_V3_2_ISENSE_MAM_TIC")
	)
	(segment
		(start 190.805308 -44.800012)
		(end 188.230002 -44.800012)
		(width 0.254)
		(layer "In6.Cu")
		(net "P12V_OCP_V3_2_ISENSE_MAM_TIC")
	)
	(segment
		(start 96.489774 -39.120318)
		(end 94.323154 -40.0177)
		(width 0.254)
		(layer "In6.Cu")
		(net "P12V_OCP_V3_2_ISENSE_MAM_TIC")
	)
	(segment
		(start 89.493344 -40.0177)
		(end 84.684362 -35.208718)
		(width 0.254)
		(layer "In6.Cu")
		(net "P12V_OCP_V3_2_ISENSE_MAM_TIC")
	)
	(segment
		(start 179.76723 -38.673532)
		(end 176.834038 -38.673532)
		(width 0.254)
		(layer "In6.Cu")
		(net "P12V_OCP_V3_2_ISENSE_MAM_TIC")
	)
	(segment
		(start 238.821214 -63.2968)
		(end 238.24692 -63.871094)
		(width 0.254)
		(layer "In6.Cu")
		(net "P12V_OCP_V3_2_ISENSE_MAM_TIC")
	)
	(segment
		(start 78.180946 -35.208718)
		(end 73.738994 -33.368996)
		(width 0.254)
		(layer "In6.Cu")
		(net "P12V_OCP_V3_2_ISENSE_MAM_TIC")
	)
	(segment
		(start 219.00007 -47.300896)
		(end 214.586058 -42.886884)
		(width 0.254)
		(layer "In6.Cu")
		(net "P12V_OCP_V3_2_ISENSE_MAM_TIC")
	)
	(segment
		(start 292.132512 -30.02534)
		(end 290.061396 -32.096456)
		(width 0.254)
		(layer "In6.Cu")
		(net "P12V_OCP_V3_2_ISENSE_MAM_TIC")
	)
	(segment
		(start 238.24692 -63.871094)
		(end 228.124004 -63.871094)
		(width 0.254)
		(layer "In6.Cu")
		(net "P12V_OCP_V3_2_ISENSE_MAM_TIC")
	)
	(segment
		(start 192.293748 -43.311572)
		(end 190.805308 -44.800012)
		(width 0.254)
		(layer "In6.Cu")
		(net "P12V_OCP_V3_2_ISENSE_MAM_TIC")
	)
	(segment
		(start 211.779612 -42.886884)
		(end 211.354924 -43.311572)
		(width 0.254)
		(layer "In6.Cu")
		(net "P12V_OCP_V3_2_ISENSE_MAM_TIC")
	)
	(segment
		(start 228.124004 -63.871094)
		(end 219.00007 -54.74716)
		(width 0.254)
		(layer "In6.Cu")
		(net "P12V_OCP_V3_2_ISENSE_MAM_TIC")
	)
	(segment
		(start 70.713854 -33.368996)
		(end 70.61327 -33.46958)
		(width 0.254)
		(layer "In6.Cu")
		(net "P12V_OCP_V3_2_ISENSE_MAM_TIC")
	)
	(segment
		(start 183.345074 -39.915084)
		(end 181.008782 -39.915084)
		(width 0.254)
		(layer "In6.Cu")
		(net "P12V_OCP_V3_2_ISENSE_MAM_TIC")
	)
	(segment
		(start 290.061396 -32.096456)
		(end 290.061396 -39.220648)
		(width 0.254)
		(layer "In6.Cu")
		(net "P12V_OCP_V3_2_ISENSE_MAM_TIC")
	)
	(segment
		(start 84.684362 -35.208718)
		(end 78.180946 -35.208718)
		(width 0.254)
		(layer "In6.Cu")
		(net "P12V_OCP_V3_2_ISENSE_MAM_TIC")
	)
	(segment
		(start 269.895574 -59.38647)
		(end 264.356342 -59.38647)
		(width 0.254)
		(layer "In6.Cu")
		(net "P12V_OCP_V3_2_ISENSE_MAM_TIC")
	)
	(segment
		(start 188.230002 -44.800012)
		(end 183.345074 -39.915084)
		(width 0.254)
		(layer "In6.Cu")
		(net "P12V_OCP_V3_2_ISENSE_MAM_TIC")
	)
	(segment
		(start 98.922078 -39.120318)
		(end 96.489774 -39.120318)
		(width 0.254)
		(layer "In6.Cu")
		(net "P12V_OCP_V3_2_ISENSE_MAM_TIC")
	)
	(segment
		(start 176.007776 -37.84727)
		(end 173.439074 -37.84727)
		(width 0.254)
		(layer "In6.Cu")
		(net "P12V_OCP_V3_2_ISENSE_MAM_TIC")
	)
	(segment
		(start 151.125428 -45.41774)
		(end 149.561296 -43.853608)
		(width 0.254)
		(layer "In6.Cu")
		(net "P12V_OCP_V3_2_ISENSE_MAM_TIC")
	)
	(segment
		(start 157.914848 -45.192696)
		(end 154.561032 -45.192696)
		(width 0.254)
		(layer "In6.Cu")
		(net "P12V_OCP_V3_2_ISENSE_MAM_TIC")
	)
	(segment
		(start 162.476434 -38.781228)
		(end 160.248346 -41.009316)
		(width 0.254)
		(layer "In6.Cu")
		(net "P12V_OCP_V3_2_ISENSE_MAM_TIC")
	)
	(segment
		(start 154.335988 -45.41774)
		(end 151.125428 -45.41774)
		(width 0.254)
		(layer "In6.Cu")
		(net "P12V_OCP_V3_2_ISENSE_MAM_TIC")
	)
	(segment
		(start 321.648836 -30.02534)
		(end 292.132512 -30.02534)
		(width 0.254)
		(layer "In6.Cu")
		(net "P12V_OCP_V3_2_ISENSE_MAM_TIC")
	)
	(segment
		(start 108.630974 -44.92244)
		(end 105.591102 -41.882568)
		(width 0.254)
		(layer "In6.Cu")
		(net "P12V_OCP_V3_2_ISENSE_MAM_TIC")
	)
	(segment
		(start 70.61327 -33.46958)
		(end 69.846698 -33.46958)
		(width 0.254)
		(layer "In6.Cu")
		(net "P12V_OCP_V3_2_ISENSE_MAM_TIC")
	)
	(segment
		(start 211.354924 -43.311572)
		(end 192.293748 -43.311572)
		(width 0.254)
		(layer "In6.Cu")
		(net "P12V_OCP_V3_2_ISENSE_MAM_TIC")
	)
	(segment
		(start 147.74672 -43.853608)
		(end 147.249388 -44.35094)
		(width 0.254)
		(layer "In6.Cu")
		(net "P12V_OCP_V3_2_ISENSE_MAM_TIC")
	)
	(segment
		(start 173.439074 -37.84727)
		(end 172.505116 -38.781228)
		(width 0.254)
		(layer "In6.Cu")
		(net "P12V_OCP_V3_2_ISENSE_MAM_TIC")
	)
	(segment
		(start 154.561032 -45.192696)
		(end 154.335988 -45.41774)
		(width 0.254)
		(layer "In6.Cu")
		(net "P12V_OCP_V3_2_ISENSE_MAM_TIC")
	)
	(segment
		(start 105.591102 -41.882568)
		(end 98.922078 -39.120318)
		(width 0.254)
		(layer "In6.Cu")
		(net "P12V_OCP_V3_2_ISENSE_MAM_TIC")
	)
	(segment
		(start 160.248346 -42.859198)
		(end 157.914848 -45.192696)
		(width 0.254)
		(layer "In6.Cu")
		(net "P12V_OCP_V3_2_ISENSE_MAM_TIC")
	)
	(segment
		(start 311.141872 -32.572706)
		(end 310.264048 -32.572706)
		(width 0.254)
		(layer "F.Cu")
		(net "P12V_OCP_V3_2_ISENSE_MAM_MAM")
	)
	(segment
		(start 60.527438 -31.487872)
		(end 60.527438 -30.87497)
		(width 0.254)
		(layer "F.Cu")
		(net "P12V_OCP_V3_2_ISENSE_MAM_MAM")
	)
	(via
		(at 310.264048 -32.572706)
		(size 0.508)
		(drill 0.254)
		(layers "F.Cu" "B.Cu")
		(net "P12V_OCP_V3_2_ISENSE_MAM_MAM")
	)
	(via
		(at 60.527438 -30.87497)
		(size 0.508)
		(drill 0.254)
		(layers "F.Cu" "B.Cu")
		(net "P12V_OCP_V3_2_ISENSE_MAM_MAM")
	)
	(segment
		(start 58.925206 -33.372806)
		(end 59.750198 -34.197798)
		(width 0.254)
		(layer "In6.Cu")
		(net "P12V_OCP_V3_2_ISENSE_MAM_MAM")
	)
	(segment
		(start 78.171548 -36.785042)
		(end 84.031328 -36.785042)
		(width 0.254)
		(layer "In6.Cu")
		(net "P12V_OCP_V3_2_ISENSE_MAM_MAM")
	)
	(segment
		(start 167.136318 -40.432228)
		(end 179.585874 -40.432228)
		(width 0.254)
		(layer "In6.Cu")
		(net "P12V_OCP_V3_2_ISENSE_MAM_MAM")
	)
	(segment
		(start 59.750198 -34.197798)
		(end 61.843158 -34.197798)
		(width 0.254)
		(layer "In6.Cu")
		(net "P12V_OCP_V3_2_ISENSE_MAM_MAM")
	)
	(segment
		(start 60.527438 -30.87497)
		(end 59.052206 -30.87497)
		(width 0.254)
		(layer "In6.Cu")
		(net "P12V_OCP_V3_2_ISENSE_MAM_MAM")
	)
	(segment
		(start 160.175956 -47.39259)
		(end 167.136318 -40.432228)
		(width 0.254)
		(layer "In6.Cu")
		(net "P12V_OCP_V3_2_ISENSE_MAM_MAM")
	)
	(segment
		(start 187.514992 -46.20514)
		(end 192.29197 -46.20514)
		(width 0.254)
		(layer "In6.Cu")
		(net "P12V_OCP_V3_2_ISENSE_MAM_MAM")
	)
	(segment
		(start 68.405502 -35.045904)
		(end 71.266304 -35.045904)
		(width 0.254)
		(layer "In6.Cu")
		(net "P12V_OCP_V3_2_ISENSE_MAM_MAM")
	)
	(segment
		(start 68.211446 -34.851848)
		(end 68.405502 -35.045904)
		(width 0.254)
		(layer "In6.Cu")
		(net "P12V_OCP_V3_2_ISENSE_MAM_MAM")
	)
	(segment
		(start 58.925206 -31.00197)
		(end 58.925206 -33.372806)
		(width 0.254)
		(layer "In6.Cu")
		(net "P12V_OCP_V3_2_ISENSE_MAM_MAM")
	)
	(segment
		(start 66.375026 -35.680142)
		(end 67.20332 -34.851848)
		(width 0.254)
		(layer "In6.Cu")
		(net "P12V_OCP_V3_2_ISENSE_MAM_MAM")
	)
	(segment
		(start 115.251484 -46.29404)
		(end 116.25072 -45.294804)
		(width 0.254)
		(layer "In6.Cu")
		(net "P12V_OCP_V3_2_ISENSE_MAM_MAM")
	)
	(segment
		(start 61.843158 -34.197798)
		(end 63.325502 -35.680142)
		(width 0.254)
		(layer "In6.Cu")
		(net "P12V_OCP_V3_2_ISENSE_MAM_MAM")
	)
	(segment
		(start 291.513514 -39.822374)
		(end 291.513514 -32.698182)
		(width 0.254)
		(layer "In6.Cu")
		(net "P12V_OCP_V3_2_ISENSE_MAM_MAM")
	)
	(segment
		(start 59.052206 -30.87497)
		(end 58.925206 -31.00197)
		(width 0.254)
		(layer "In6.Cu")
		(net "P12V_OCP_V3_2_ISENSE_MAM_MAM")
	)
	(segment
		(start 192.29197 -46.20514)
		(end 193.40449 -45.09262)
		(width 0.254)
		(layer "In6.Cu")
		(net "P12V_OCP_V3_2_ISENSE_MAM_MAM")
	)
	(segment
		(start 238.848646 -65.323212)
		(end 239.42294 -64.748918)
		(width 0.254)
		(layer "In6.Cu")
		(net "P12V_OCP_V3_2_ISENSE_MAM_MAM")
	)
	(segment
		(start 128.264158 -45.294804)
		(end 128.691894 -45.72254)
		(width 0.254)
		(layer "In6.Cu")
		(net "P12V_OCP_V3_2_ISENSE_MAM_MAM")
	)
	(segment
		(start 264.958068 -60.838588)
		(end 270.4973 -60.838588)
		(width 0.254)
		(layer "In6.Cu")
		(net "P12V_OCP_V3_2_ISENSE_MAM_MAM")
	)
	(segment
		(start 291.513514 -32.698182)
		(end 292.734238 -31.477458)
		(width 0.254)
		(layer "In6.Cu")
		(net "P12V_OCP_V3_2_ISENSE_MAM_MAM")
	)
	(segment
		(start 100.714302 -41.450514)
		(end 103.397558 -42.562018)
		(width 0.254)
		(layer "In6.Cu")
		(net "P12V_OCP_V3_2_ISENSE_MAM_MAM")
	)
	(segment
		(start 182.596536 -41.286684)
		(end 187.514992 -46.20514)
		(width 0.254)
		(layer "In6.Cu")
		(net "P12V_OCP_V3_2_ISENSE_MAM_MAM")
	)
	(segment
		(start 67.20332 -34.851848)
		(end 68.211446 -34.851848)
		(width 0.254)
		(layer "In6.Cu")
		(net "P12V_OCP_V3_2_ISENSE_MAM_MAM")
	)
	(segment
		(start 128.691894 -45.72254)
		(end 146.6596 -45.72254)
		(width 0.254)
		(layer "In6.Cu")
		(net "P12V_OCP_V3_2_ISENSE_MAM_MAM")
	)
	(segment
		(start 214.73795 -45.09262)
		(end 216.704164 -47.058834)
		(width 0.254)
		(layer "In6.Cu")
		(net "P12V_OCP_V3_2_ISENSE_MAM_MAM")
	)
	(segment
		(start 71.266304 -35.045904)
		(end 71.366888 -34.94532)
		(width 0.254)
		(layer "In6.Cu")
		(net "P12V_OCP_V3_2_ISENSE_MAM_MAM")
	)
	(segment
		(start 107.12958 -46.29404)
		(end 115.251484 -46.29404)
		(width 0.254)
		(layer "In6.Cu")
		(net "P12V_OCP_V3_2_ISENSE_MAM_MAM")
	)
	(segment
		(start 146.6596 -45.72254)
		(end 147.7264 -46.78934)
		(width 0.254)
		(layer "In6.Cu")
		(net "P12V_OCP_V3_2_ISENSE_MAM_MAM")
	)
	(segment
		(start 216.704164 -56.10225)
		(end 225.925126 -65.323212)
		(width 0.254)
		(layer "In6.Cu")
		(net "P12V_OCP_V3_2_ISENSE_MAM_MAM")
	)
	(segment
		(start 71.366888 -34.94532)
		(end 73.729596 -34.94532)
		(width 0.254)
		(layer "In6.Cu")
		(net "P12V_OCP_V3_2_ISENSE_MAM_MAM")
	)
	(segment
		(start 180.44033 -41.286684)
		(end 182.596536 -41.286684)
		(width 0.254)
		(layer "In6.Cu")
		(net "P12V_OCP_V3_2_ISENSE_MAM_MAM")
	)
	(segment
		(start 261.047738 -64.748918)
		(end 264.958068 -60.838588)
		(width 0.254)
		(layer "In6.Cu")
		(net "P12V_OCP_V3_2_ISENSE_MAM_MAM")
	)
	(segment
		(start 73.729596 -34.94532)
		(end 78.171548 -36.785042)
		(width 0.254)
		(layer "In6.Cu")
		(net "P12V_OCP_V3_2_ISENSE_MAM_MAM")
	)
	(segment
		(start 103.397558 -42.562018)
		(end 107.12958 -46.29404)
		(width 0.254)
		(layer "In6.Cu")
		(net "P12V_OCP_V3_2_ISENSE_MAM_MAM")
	)
	(segment
		(start 88.6968 -41.450514)
		(end 100.714302 -41.450514)
		(width 0.254)
		(layer "In6.Cu")
		(net "P12V_OCP_V3_2_ISENSE_MAM_MAM")
	)
	(segment
		(start 239.42294 -64.748918)
		(end 261.047738 -64.748918)
		(width 0.254)
		(layer "In6.Cu")
		(net "P12V_OCP_V3_2_ISENSE_MAM_MAM")
	)
	(segment
		(start 292.734238 -31.477458)
		(end 309.1688 -31.477458)
		(width 0.254)
		(layer "In6.Cu")
		(net "P12V_OCP_V3_2_ISENSE_MAM_MAM")
	)
	(segment
		(start 147.7264 -46.78934)
		(end 152.931622 -46.78934)
		(width 0.254)
		(layer "In6.Cu")
		(net "P12V_OCP_V3_2_ISENSE_MAM_MAM")
	)
	(segment
		(start 179.585874 -40.432228)
		(end 180.44033 -41.286684)
		(width 0.254)
		(layer "In6.Cu")
		(net "P12V_OCP_V3_2_ISENSE_MAM_MAM")
	)
	(segment
		(start 225.925126 -65.323212)
		(end 238.848646 -65.323212)
		(width 0.254)
		(layer "In6.Cu")
		(net "P12V_OCP_V3_2_ISENSE_MAM_MAM")
	)
	(segment
		(start 153.534872 -47.39259)
		(end 160.175956 -47.39259)
		(width 0.254)
		(layer "In6.Cu")
		(net "P12V_OCP_V3_2_ISENSE_MAM_MAM")
	)
	(segment
		(start 63.325502 -35.680142)
		(end 66.375026 -35.680142)
		(width 0.254)
		(layer "In6.Cu")
		(net "P12V_OCP_V3_2_ISENSE_MAM_MAM")
	)
	(segment
		(start 116.25072 -45.294804)
		(end 128.264158 -45.294804)
		(width 0.254)
		(layer "In6.Cu")
		(net "P12V_OCP_V3_2_ISENSE_MAM_MAM")
	)
	(segment
		(start 84.031328 -36.785042)
		(end 88.6968 -41.450514)
		(width 0.254)
		(layer "In6.Cu")
		(net "P12V_OCP_V3_2_ISENSE_MAM_MAM")
	)
	(segment
		(start 309.1688 -31.477458)
		(end 310.264048 -32.572706)
		(width 0.254)
		(layer "In6.Cu")
		(net "P12V_OCP_V3_2_ISENSE_MAM_MAM")
	)
	(segment
		(start 216.704164 -47.058834)
		(end 216.704164 -56.10225)
		(width 0.254)
		(layer "In6.Cu")
		(net "P12V_OCP_V3_2_ISENSE_MAM_MAM")
	)
	(segment
		(start 270.4973 -60.838588)
		(end 291.513514 -39.822374)
		(width 0.254)
		(layer "In6.Cu")
		(net "P12V_OCP_V3_2_ISENSE_MAM_MAM")
	)
	(segment
		(start 193.40449 -45.09262)
		(end 214.73795 -45.09262)
		(width 0.254)
		(layer "In6.Cu")
		(net "P12V_OCP_V3_2_ISENSE_MAM_MAM")
	)
	(segment
		(start 152.931622 -46.78934)
		(end 153.534872 -47.39259)
		(width 0.254)
		(layer "In6.Cu")
		(net "P12V_OCP_V3_2_ISENSE_MAM_MAM")
	)
	(segment
		(start 70.052438 -30.544008)
		(end 70.051422 -30.542992)
		(width 0.10668)
		(layer "F.Cu")
		(net "P12V_OCP_V3_2_EN_2_R3")
	)
	(segment
		(start 70.052438 -31.487872)
		(end 70.052438 -30.544008)
		(width 0.10668)
		(layer "F.Cu")
		(net "P12V_OCP_V3_2_EN_2_R3")
	)
	(segment
		(start 69.672454 -30.164024)
		(end 70.051422 -30.542992)
		(width 0.10668)
		(layer "F.Cu")
		(net "P12V_OCP_V3_2_EN_2_R3")
	)
	(segment
		(start 69.672454 -29.264864)
		(end 69.672454 -30.164024)
		(width 0.10668)
		(layer "F.Cu")
		(net "P12V_OCP_V3_2_EN_2_R3")
	)
	(segment
		(start 70.058788 -31.494222)
		(end 70.052438 -31.487872)
		(width 0.10668)
		(layer "F.Cu")
		(net "P12V_OCP_V3_2_EN_2_R3")
	)
	(segment
		(start 71.064882 -31.494222)
		(end 70.058788 -31.494222)
		(width 0.10668)
		(layer "F.Cu")
		(net "P12V_OCP_V3_2_EN_2_R3")
	)
	(via
		(at 70.051422 -30.542992)
		(size 0.508)
		(drill 0.254)
		(layers "F.Cu" "B.Cu")
		(net "P12V_OCP_V3_2_EN_2_R3")
	)
	(segment
		(start 61.2394 -25.983692)
		(end 61.845698 -26.58999)
		(width 0.4572)
		(layer "F.Cu")
		(net "P12V_OCP_V3_2")
	)
	(segment
		(start 66.307716 -21.38299)
		(end 62.022736 -21.38299)
		(width 0.4572)
		(layer "F.Cu")
		(net "P12V_OCP_V3_2")
	)
	(segment
		(start 61.2394 -22.166326)
		(end 61.2394 -25.983692)
		(width 0.4572)
		(layer "F.Cu")
		(net "P12V_OCP_V3_2")
	)
	(segment
		(start 25.109678 -40.07485)
		(end 24.629364 -40.07485)
		(width 0.254)
		(layer "F.Cu")
		(net "P12V_OCP_V3_2")
	)
	(segment
		(start 25.826466 -40.81526)
		(end 25.82545 -40.816276)
		(width 0.381)
		(layer "F.Cu")
		(net "P12V_OCP_V3_2")
	)
	(segment
		(start 81.324196 -25.357582)
		(end 81.325212 -25.358598)
		(width 0.4572)
		(layer "F.Cu")
		(net "P12V_OCP_V3_2")
	)
	(segment
		(start 81.324196 -24.346408)
		(end 81.324196 -25.357582)
		(width 0.4572)
		(layer "F.Cu")
		(net "P12V_OCP_V3_2")
	)
	(segment
		(start 83.808062 -23.826724)
		(end 83.300062 -24.334724)
		(width 0.508)
		(layer "F.Cu")
		(net "P12V_OCP_V3_2")
	)
	(segment
		(start 81.312512 -24.334724)
		(end 81.324196 -24.346408)
		(width 0.508)
		(layer "F.Cu")
		(net "P12V_OCP_V3_2")
	)
	(segment
		(start 83.808062 -17.463008)
		(end 83.808062 -23.826724)
		(width 0.508)
		(layer "F.Cu")
		(net "P12V_OCP_V3_2")
	)
	(segment
		(start 25.826466 -40.180514)
		(end 25.826466 -40.81526)
		(width 0.381)
		(layer "F.Cu")
		(net "P12V_OCP_V3_2")
	)
	(segment
		(start 25.215342 -40.180514)
		(end 25.109678 -40.07485)
		(width 0.254)
		(layer "F.Cu")
		(net "P12V_OCP_V3_2")
	)
	(segment
		(start 80.280764 -16.97101)
		(end 83.316064 -16.97101)
		(width 0.508)
		(layer "F.Cu")
		(net "P12V_OCP_V3_2")
	)
	(segment
		(start 83.300062 -24.334724)
		(end 81.312512 -24.334724)
		(width 0.508)
		(layer "F.Cu")
		(net "P12V_OCP_V3_2")
	)
	(segment
		(start 62.022736 -21.38299)
		(end 61.2394 -22.166326)
		(width 0.4572)
		(layer "F.Cu")
		(net "P12V_OCP_V3_2")
	)
	(segment
		(start 83.316064 -16.97101)
		(end 83.808062 -17.463008)
		(width 0.508)
		(layer "F.Cu")
		(net "P12V_OCP_V3_2")
	)
	(segment
		(start 25.826466 -40.180514)
		(end 25.215342 -40.180514)
		(width 0.254)
		(layer "F.Cu")
		(net "P12V_OCP_V3_2")
	)
	(via
		(at 68.558664 -24.88311)
		(size 0.508)
		(drill 0.254)
		(layers "F.Cu" "B.Cu")
		(net "P12V_OCP_V3_2")
	)
	(via
		(at 66.399664 -25.56891)
		(size 0.508)
		(drill 0.254)
		(layers "F.Cu" "B.Cu")
		(net "P12V_OCP_V3_2")
	)
	(via
		(at 66.882264 -22.26691)
		(size 0.508)
		(drill 0.254)
		(layers "F.Cu" "B.Cu")
		(net "P12V_OCP_V3_2")
	)
	(via
		(at 79.921862 -18.238724)
		(size 0.508)
		(drill 0.254)
		(layers "F.Cu" "B.Cu")
		(net "P12V_OCP_V3_2")
	)
	(via
		(at 66.780664 -24.88311)
		(size 0.508)
		(drill 0.254)
		(layers "F.Cu" "B.Cu")
		(net "P12V_OCP_V3_2")
	)
	(via
		(at 66.774822 -19.692366)
		(size 0.508)
		(drill 0.254)
		(layers "F.Cu" "B.Cu")
		(net "P12V_OCP_V3_2")
	)
	(via
		(at 66.774822 -20.327366)
		(size 0.508)
		(drill 0.254)
		(layers "F.Cu" "B.Cu")
		(net "P12V_OCP_V3_2")
	)
	(via
		(at 66.848228 -18.642584)
		(size 0.508)
		(drill 0.254)
		(layers "F.Cu" "B.Cu")
		(net "P12V_OCP_V3_2")
	)
	(via
		(at 77.84338 -16.55064)
		(size 0.508)
		(drill 0.254)
		(layers "F.Cu" "B.Cu")
		(net "P12V_OCP_V3_2")
	)
	(via
		(at 25.82545 -40.816276)
		(size 0.508)
		(drill 0.254)
		(layers "F.Cu" "B.Cu")
		(net "P12V_OCP_V3_2")
	)
	(via
		(at 68.177664 -25.56891)
		(size 0.508)
		(drill 0.254)
		(layers "F.Cu" "B.Cu")
		(net "P12V_OCP_V3_2")
	)
	(via
		(at 67.669664 -24.88311)
		(size 0.508)
		(drill 0.254)
		(layers "F.Cu" "B.Cu")
		(net "P12V_OCP_V3_2")
	)
	(via
		(at 77.178408 -16.520668)
		(size 0.508)
		(drill 0.254)
		(layers "F.Cu" "B.Cu")
		(net "P12V_OCP_V3_2")
	)
	(via
		(at 67.288664 -25.56891)
		(size 0.508)
		(drill 0.254)
		(layers "F.Cu" "B.Cu")
		(net "P12V_OCP_V3_2")
	)
	(via
		(at 69.498464 -24.55291)
		(size 0.508)
		(drill 0.254)
		(layers "F.Cu" "B.Cu")
		(net "P12V_OCP_V3_2")
	)
	(via
		(at 79.921862 -17.502124)
		(size 0.508)
		(drill 0.254)
		(layers "F.Cu" "B.Cu")
		(net "P12V_OCP_V3_2")
	)
	(segment
		(start 21.872194 -44.028106)
		(end 25.084024 -40.816276)
		(width 0.508)
		(layer "In15.Cu")
		(net "P12V_OCP_V3_2")
	)
	(segment
		(start 15.89024 -38.551612)
		(end 15.89024 -42.280078)
		(width 0.508)
		(layer "In15.Cu")
		(net "P12V_OCP_V3_2")
	)
	(segment
		(start 15.89024 -42.280078)
		(end 17.638268 -44.028106)
		(width 0.508)
		(layer "In15.Cu")
		(net "P12V_OCP_V3_2")
	)
	(segment
		(start 25.084024 -40.816276)
		(end 25.82545 -40.816276)
		(width 0.508)
		(layer "In15.Cu")
		(net "P12V_OCP_V3_2")
	)
	(segment
		(start 32.88792 -21.553932)
		(end 15.89024 -38.551612)
		(width 0.508)
		(layer "In15.Cu")
		(net "P12V_OCP_V3_2")
	)
	(segment
		(start 65.177416 -21.553932)
		(end 32.88792 -21.553932)
		(width 0.508)
		(layer "In15.Cu")
		(net "P12V_OCP_V3_2")
	)
	(segment
		(start 17.638268 -44.028106)
		(end 21.872194 -44.028106)
		(width 0.508)
		(layer "In15.Cu")
		(net "P12V_OCP_V3_2")
	)
	(segment
		(start 66.0654 -39.087298)
		(end 65.219072 -39.087298)
		(width 0.10668)
		(layer "F.Cu")
		(net "P12V_OCP_UV_2_R")
	)
	(segment
		(start 64.089026 -37.957252)
		(end 64.724534 -38.59276)
		(width 0.10668)
		(layer "F.Cu")
		(net "P12V_OCP_UV_2_R")
	)
	(segment
		(start 65.219072 -39.087298)
		(end 64.724534 -38.59276)
		(width 0.10668)
		(layer "F.Cu")
		(net "P12V_OCP_UV_2_R")
	)
	(segment
		(start 63.42253 -37.957252)
		(end 64.089026 -37.957252)
		(width 0.10668)
		(layer "F.Cu")
		(net "P12V_OCP_UV_2_R")
	)
	(via
		(at 64.724534 -38.59276)
		(size 0.762)
		(drill 0.381)
		(layers "F.Cu" "B.Cu")
		(net "P12V_OCP_UV_2_R")
	)
	(segment
		(start 78.35646 -19.396202)
		(end 78.35646 -19.94408)
		(width 0.10668)
		(layer "F.Cu")
		(net "P12V_OCP_UV_2")
	)
	(segment
		(start 77.67828 -18.718022)
		(end 78.35646 -19.396202)
		(width 0.10668)
		(layer "F.Cu")
		(net "P12V_OCP_UV_2")
	)
	(segment
		(start 77.523848 -18.066512)
		(end 76.515214 -18.066512)
		(width 0.10668)
		(layer "F.Cu")
		(net "P12V_OCP_UV_2")
	)
	(segment
		(start 66.4718 -40.7162)
		(end 66.675 -40.9194)
		(width 0.10668)
		(layer "F.Cu")
		(net "P12V_OCP_UV_2")
	)
	(segment
		(start 66.4718 -40.4876)
		(end 66.4718 -40.7162)
		(width 0.10668)
		(layer "F.Cu")
		(net "P12V_OCP_UV_2")
	)
	(segment
		(start 77.67828 -18.220944)
		(end 77.537564 -18.080228)
		(width 0.10668)
		(layer "F.Cu")
		(net "P12V_OCP_UV_2")
	)
	(segment
		(start 66.0654 -39.887398)
		(end 66.0654 -40.0812)
		(width 0.10668)
		(layer "F.Cu")
		(net "P12V_OCP_UV_2")
	)
	(segment
		(start 77.537564 -18.080228)
		(end 77.523848 -18.066512)
		(width 0.10668)
		(layer "F.Cu")
		(net "P12V_OCP_UV_2")
	)
	(segment
		(start 77.67828 -18.718022)
		(end 77.67828 -18.220944)
		(width 0.10668)
		(layer "F.Cu")
		(net "P12V_OCP_UV_2")
	)
	(segment
		(start 66.0654 -40.0812)
		(end 66.4718 -40.4876)
		(width 0.10668)
		(layer "F.Cu")
		(net "P12V_OCP_UV_2")
	)
	(via
		(at 66.675 -40.9194)
		(size 0.508)
		(drill 0.254)
		(layers "F.Cu" "B.Cu")
		(net "P12V_OCP_UV_2")
	)
	(via
		(at 77.67828 -18.718022)
		(size 0.508)
		(drill 0.254)
		(layers "F.Cu" "B.Cu")
		(net "P12V_OCP_UV_2")
	)
	(segment
		(start 75.4634 -25.443434)
		(end 77.55128 -23.355554)
		(width 0.11684)
		(layer "In4.Cu")
		(net "P12V_OCP_UV_2")
	)
	(segment
		(start 67.893692 -32.815022)
		(end 68.374514 -32.3342)
		(width 0.11684)
		(layer "In4.Cu")
		(net "P12V_OCP_UV_2")
	)
	(segment
		(start 77.55128 -18.845022)
		(end 77.67828 -18.718022)
		(width 0.11684)
		(layer "In4.Cu")
		(net "P12V_OCP_UV_2")
	)
	(segment
		(start 66.053462 -32.815022)
		(end 67.893692 -32.815022)
		(width 0.11684)
		(layer "In4.Cu")
		(net "P12V_OCP_UV_2")
	)
	(segment
		(start 74.5236 -32.3342)
		(end 75.4634 -31.3944)
		(width 0.11684)
		(layer "In4.Cu")
		(net "P12V_OCP_UV_2")
	)
	(segment
		(start 66.3194 -39.245286)
		(end 64.85382 -37.779706)
		(width 0.11684)
		(layer "In4.Cu")
		(net "P12V_OCP_UV_2")
	)
	(segment
		(start 77.55128 -23.355554)
		(end 77.55128 -18.845022)
		(width 0.11684)
		(layer "In4.Cu")
		(net "P12V_OCP_UV_2")
	)
	(segment
		(start 66.4718 -40.4876)
		(end 66.3194 -40.3352)
		(width 0.11684)
		(layer "In4.Cu")
		(net "P12V_OCP_UV_2")
	)
	(segment
		(start 68.374514 -32.3342)
		(end 74.5236 -32.3342)
		(width 0.11684)
		(layer "In4.Cu")
		(net "P12V_OCP_UV_2")
	)
	(segment
		(start 64.85382 -36.574222)
		(end 64.31661 -36.037012)
		(width 0.11684)
		(layer "In4.Cu")
		(net "P12V_OCP_UV_2")
	)
	(segment
		(start 66.4718 -40.7162)
		(end 66.4718 -40.4876)
		(width 0.11684)
		(layer "In4.Cu")
		(net "P12V_OCP_UV_2")
	)
	(segment
		(start 64.31661 -34.551874)
		(end 66.053462 -32.815022)
		(width 0.11684)
		(layer "In4.Cu")
		(net "P12V_OCP_UV_2")
	)
	(segment
		(start 64.85382 -37.779706)
		(end 64.85382 -36.574222)
		(width 0.11684)
		(layer "In4.Cu")
		(net "P12V_OCP_UV_2")
	)
	(segment
		(start 75.4634 -31.3944)
		(end 75.4634 -25.443434)
		(width 0.11684)
		(layer "In4.Cu")
		(net "P12V_OCP_UV_2")
	)
	(segment
		(start 64.31661 -36.037012)
		(end 64.31661 -34.551874)
		(width 0.11684)
		(layer "In4.Cu")
		(net "P12V_OCP_UV_2")
	)
	(segment
		(start 66.3194 -40.3352)
		(end 66.3194 -39.245286)
		(width 0.11684)
		(layer "In4.Cu")
		(net "P12V_OCP_UV_2")
	)
	(segment
		(start 66.675 -40.9194)
		(end 66.4718 -40.7162)
		(width 0.11684)
		(layer "In4.Cu")
		(net "P12V_OCP_UV_2")
	)
	(segment
		(start 455.41311 -39.835836)
		(end 456.63231 -39.835836)
		(width 0.10668)
		(layer "F.Cu")
		(net "P12V_OCP_UV_1_R")
	)
	(segment
		(start 457.464668 -39.220394)
		(end 464.399884 -39.220394)
		(width 0.10668)
		(layer "F.Cu")
		(net "P12V_OCP_UV_1_R")
	)
	(segment
		(start 456.849226 -39.835836)
		(end 457.464668 -39.220394)
		(width 0.10668)
		(layer "F.Cu")
		(net "P12V_OCP_UV_1_R")
	)
	(segment
		(start 465.167472 -41.556432)
		(end 465.366862 -41.755822)
		(width 0.10668)
		(layer "F.Cu")
		(net "P12V_OCP_UV_1_R")
	)
	(segment
		(start 465.167472 -39.987982)
		(end 465.167472 -41.556432)
		(width 0.10668)
		(layer "F.Cu")
		(net "P12V_OCP_UV_1_R")
	)
	(segment
		(start 456.63231 -39.835836)
		(end 456.849226 -39.835836)
		(width 0.10668)
		(layer "F.Cu")
		(net "P12V_OCP_UV_1_R")
	)
	(segment
		(start 465.366862 -41.755822)
		(end 466.119464 -41.755822)
		(width 0.10668)
		(layer "F.Cu")
		(net "P12V_OCP_UV_1_R")
	)
	(segment
		(start 464.399884 -39.220394)
		(end 465.167472 -39.987982)
		(width 0.10668)
		(layer "F.Cu")
		(net "P12V_OCP_UV_1_R")
	)
	(via
		(at 456.63231 -39.835836)
		(size 0.762)
		(drill 0.381)
		(layers "F.Cu" "B.Cu")
		(net "P12V_OCP_UV_1_R")
	)
	(segment
		(start 448.966336 -18.449798)
		(end 448.980052 -18.463514)
		(width 0.10668)
		(layer "F.Cu")
		(net "P12V_OCP_UV_1")
	)
	(segment
		(start 450.497194 -19.307556)
		(end 449.664836 -18.475198)
		(width 0.10668)
		(layer "F.Cu")
		(net "P12V_OCP_UV_1")
	)
	(segment
		(start 448.980052 -18.463514)
		(end 449.653152 -18.463514)
		(width 0.10668)
		(layer "F.Cu")
		(net "P12V_OCP_UV_1")
	)
	(segment
		(start 449.653152 -18.463514)
		(end 449.664836 -18.475198)
		(width 0.10668)
		(layer "F.Cu")
		(net "P12V_OCP_UV_1")
	)
	(segment
		(start 454.61301 -39.835836)
		(end 453.99706 -39.835836)
		(width 0.10668)
		(layer "F.Cu")
		(net "P12V_OCP_UV_1")
	)
	(segment
		(start 447.957702 -18.449798)
		(end 448.966336 -18.449798)
		(width 0.10668)
		(layer "F.Cu")
		(net "P12V_OCP_UV_1")
	)
	(segment
		(start 450.497194 -20.229576)
		(end 450.497194 -19.307556)
		(width 0.10668)
		(layer "F.Cu")
		(net "P12V_OCP_UV_1")
	)
	(via
		(at 449.664836 -18.475198)
		(size 0.508)
		(drill 0.254)
		(layers "F.Cu" "B.Cu")
		(net "P12V_OCP_UV_1")
	)
	(via
		(at 453.99706 -39.835836)
		(size 0.508)
		(drill 0.254)
		(layers "F.Cu" "B.Cu")
		(net "P12V_OCP_UV_1")
	)
	(segment
		(start 451.188836 -37.027612)
		(end 451.188836 -26.73858)
		(width 0.10668)
		(layer "B.Cu")
		(net "P12V_OCP_UV_1")
	)
	(segment
		(start 453.99706 -39.835836)
		(end 451.188836 -37.027612)
		(width 0.10668)
		(layer "B.Cu")
		(net "P12V_OCP_UV_1")
	)
	(segment
		(start 449.664836 -19.079464)
		(end 449.664836 -18.475198)
		(width 0.10668)
		(layer "B.Cu")
		(net "P12V_OCP_UV_1")
	)
	(segment
		(start 449.937124 -25.486868)
		(end 449.937124 -19.351752)
		(width 0.10668)
		(layer "B.Cu")
		(net "P12V_OCP_UV_1")
	)
	(segment
		(start 449.937124 -19.351752)
		(end 449.664836 -19.079464)
		(width 0.10668)
		(layer "B.Cu")
		(net "P12V_OCP_UV_1")
	)
	(segment
		(start 451.188836 -26.73858)
		(end 449.937124 -25.486868)
		(width 0.10668)
		(layer "B.Cu")
		(net "P12V_OCP_UV_1")
	)
	(segment
		(start 68.449698 -30.75813)
		(end 69.036438 -31.34487)
		(width 0.10668)
		(layer "F.Cu")
		(net "P12V_OCP_TIMER_2")
	)
	(segment
		(start 69.036438 -31.34487)
		(end 69.036438 -31.487872)
		(width 0.10668)
		(layer "F.Cu")
		(net "P12V_OCP_TIMER_2")
	)
	(segment
		(start 68.17233 -30.480762)
		(end 68.449698 -30.75813)
		(width 0.10668)
		(layer "F.Cu")
		(net "P12V_OCP_TIMER_2")
	)
	(segment
		(start 68.17233 -29.29001)
		(end 68.17233 -30.480762)
		(width 0.10668)
		(layer "F.Cu")
		(net "P12V_OCP_TIMER_2")
	)
	(via
		(at 68.449698 -30.75813)
		(size 0.508)
		(drill 0.254)
		(layers "F.Cu" "B.Cu")
		(net "P12V_OCP_TIMER_2")
	)
	(segment
		(start 442.853064 -30.870652)
		(end 443.223904 -31.241492)
		(width 0.10668)
		(layer "F.Cu")
		(net "P12V_OCP_TIMER_1")
	)
	(segment
		(start 442.853064 -29.575506)
		(end 442.853064 -30.870652)
		(width 0.10668)
		(layer "F.Cu")
		(net "P12V_OCP_TIMER_1")
	)
	(segment
		(start 443.717172 -31.773368)
		(end 443.717172 -31.73476)
		(width 0.10668)
		(layer "F.Cu")
		(net "P12V_OCP_TIMER_1")
	)
	(segment
		(start 443.717172 -31.73476)
		(end 443.223904 -31.241492)
		(width 0.10668)
		(layer "F.Cu")
		(net "P12V_OCP_TIMER_1")
	)
	(via
		(at 443.223904 -31.241492)
		(size 0.508)
		(drill 0.254)
		(layers "F.Cu" "B.Cu")
		(net "P12V_OCP_TIMER_1")
	)
	(segment
		(start 67.172586 -30.684724)
		(end 67.172586 -29.29001)
		(width 0.10668)
		(layer "F.Cu")
		(net "P12V_OCP_SS_2")
	)
	(segment
		(start 66.369438 -31.487872)
		(end 67.130422 -30.726888)
		(width 0.10668)
		(layer "F.Cu")
		(net "P12V_OCP_SS_2")
	)
	(segment
		(start 67.130422 -30.726888)
		(end 67.172586 -30.684724)
		(width 0.10668)
		(layer "F.Cu")
		(net "P12V_OCP_SS_2")
	)
	(via
		(at 67.130422 -30.726888)
		(size 0.508)
		(drill 0.254)
		(layers "F.Cu" "B.Cu")
		(net "P12V_OCP_SS_2")
	)
	(segment
		(start 441.85332 -30.691328)
		(end 441.880244 -30.718252)
		(width 0.10668)
		(layer "F.Cu")
		(net "P12V_OCP_SS_1")
	)
	(segment
		(start 441.050172 -31.548324)
		(end 441.880244 -30.718252)
		(width 0.10668)
		(layer "F.Cu")
		(net "P12V_OCP_SS_1")
	)
	(segment
		(start 441.050172 -31.773368)
		(end 441.050172 -31.548324)
		(width 0.10668)
		(layer "F.Cu")
		(net "P12V_OCP_SS_1")
	)
	(segment
		(start 441.85332 -29.575506)
		(end 441.85332 -30.691328)
		(width 0.10668)
		(layer "F.Cu")
		(net "P12V_OCP_SS_1")
	)
	(via
		(at 441.880244 -30.718252)
		(size 0.508)
		(drill 0.254)
		(layers "F.Cu" "B.Cu")
		(net "P12V_OCP_SS_1")
	)
	(segment
		(start 436.224172 -34.376106)
		(end 436.215536 -34.384742)
		(width 0.254)
		(layer "F.Cu")
		(net "P12V_OCP_SFF_ISENSE_MPS_TIC")
	)
	(segment
		(start 322.436998 -45.86351)
		(end 321.827398 -45.86351)
		(width 0.254)
		(layer "F.Cu")
		(net "P12V_OCP_SFF_ISENSE_MPS_TIC")
	)
	(segment
		(start 436.224172 -32.573468)
		(end 436.224172 -34.376106)
		(width 0.254)
		(layer "F.Cu")
		(net "P12V_OCP_SFF_ISENSE_MPS_TIC")
	)
	(via
		(at 436.215536 -34.384742)
		(size 0.508)
		(drill 0.254)
		(layers "F.Cu" "B.Cu")
		(net "P12V_OCP_SFF_ISENSE_MPS_TIC")
	)
	(via
		(at 322.311014 -52.328318)
		(size 0.508)
		(drill 0.254)
		(layers "F.Cu" "B.Cu")
		(net "P12V_OCP_SFF_ISENSE_MPS_TIC")
	)
	(via
		(at 321.827398 -45.86351)
		(size 0.508)
		(drill 0.254)
		(layers "F.Cu" "B.Cu")
		(net "P12V_OCP_SFF_ISENSE_MPS_TIC")
	)
	(segment
		(start 322.240656 -51.74996)
		(end 322.240656 -46.276768)
		(width 0.254)
		(layer "B.Cu")
		(net "P12V_OCP_SFF_ISENSE_MPS_TIC")
	)
	(segment
		(start 322.311014 -52.328318)
		(end 322.311014 -51.820318)
		(width 0.254)
		(layer "B.Cu")
		(net "P12V_OCP_SFF_ISENSE_MPS_TIC")
	)
	(segment
		(start 322.311014 -51.820318)
		(end 322.240656 -51.74996)
		(width 0.254)
		(layer "B.Cu")
		(net "P12V_OCP_SFF_ISENSE_MPS_TIC")
	)
	(segment
		(start 322.240656 -46.276768)
		(end 321.827398 -45.86351)
		(width 0.254)
		(layer "B.Cu")
		(net "P12V_OCP_SFF_ISENSE_MPS_TIC")
	)
	(segment
		(start 428.065184 -29.505148)
		(end 430.147984 -31.587948)
		(width 0.254)
		(layer "In6.Cu")
		(net "P12V_OCP_SFF_ISENSE_MPS_TIC")
	)
	(segment
		(start 331.13472 -52.758848)
		(end 379.685804 -52.758848)
		(width 0.254)
		(layer "In6.Cu")
		(net "P12V_OCP_SFF_ISENSE_MPS_TIC")
	)
	(segment
		(start 431.3682 -31.587948)
		(end 434.164994 -34.384742)
		(width 0.254)
		(layer "In6.Cu")
		(net "P12V_OCP_SFF_ISENSE_MPS_TIC")
	)
	(segment
		(start 322.311014 -52.328318)
		(end 330.70419 -52.328318)
		(width 0.254)
		(layer "In6.Cu")
		(net "P12V_OCP_SFF_ISENSE_MPS_TIC")
	)
	(segment
		(start 402.939504 -29.505148)
		(end 428.065184 -29.505148)
		(width 0.254)
		(layer "In6.Cu")
		(net "P12V_OCP_SFF_ISENSE_MPS_TIC")
	)
	(segment
		(start 430.147984 -31.587948)
		(end 431.3682 -31.587948)
		(width 0.254)
		(layer "In6.Cu")
		(net "P12V_OCP_SFF_ISENSE_MPS_TIC")
	)
	(segment
		(start 379.685804 -52.758848)
		(end 402.939504 -29.505148)
		(width 0.254)
		(layer "In6.Cu")
		(net "P12V_OCP_SFF_ISENSE_MPS_TIC")
	)
	(segment
		(start 434.164994 -34.384742)
		(end 436.215536 -34.384742)
		(width 0.254)
		(layer "In6.Cu")
		(net "P12V_OCP_SFF_ISENSE_MPS_TIC")
	)
	(segment
		(start 330.70419 -52.328318)
		(end 331.13472 -52.758848)
		(width 0.254)
		(layer "In6.Cu")
		(net "P12V_OCP_SFF_ISENSE_MPS_TIC")
	)
	(segment
		(start 437.240172 -32.573468)
		(end 437.240172 -34.376106)
		(width 0.254)
		(layer "F.Cu")
		(net "P12V_OCP_SFF_ISENSE_MPS_MAM")
	)
	(segment
		(start 312.742072 -33.715706)
		(end 313.351672 -33.715706)
		(width 0.254)
		(layer "F.Cu")
		(net "P12V_OCP_SFF_ISENSE_MPS_MAM")
	)
	(segment
		(start 437.240172 -34.376106)
		(end 437.231536 -34.384742)
		(width 0.254)
		(layer "F.Cu")
		(net "P12V_OCP_SFF_ISENSE_MPS_MAM")
	)
	(via
		(at 331.8002 -51.794918)
		(size 0.508)
		(drill 0.254)
		(layers "F.Cu" "B.Cu")
		(net "P12V_OCP_SFF_ISENSE_MPS_MAM")
	)
	(via
		(at 313.351672 -33.715706)
		(size 0.508)
		(drill 0.254)
		(layers "F.Cu" "B.Cu")
		(net "P12V_OCP_SFF_ISENSE_MPS_MAM")
	)
	(via
		(at 437.231536 -34.384742)
		(size 0.762)
		(drill 0.254)
		(layers "F.Cu" "B.Cu")
		(net "P12V_OCP_SFF_ISENSE_MPS_MAM")
	)
	(segment
		(start 314.148724 -44.851828)
		(end 314.148724 -34.512758)
		(width 0.254)
		(layer "In4.Cu")
		(net "P12V_OCP_SFF_ISENSE_MPS_MAM")
	)
	(segment
		(start 314.148724 -34.512758)
		(end 313.351672 -33.715706)
		(width 0.254)
		(layer "In4.Cu")
		(net "P12V_OCP_SFF_ISENSE_MPS_MAM")
	)
	(segment
		(start 331.8002 -51.794918)
		(end 321.091814 -51.794918)
		(width 0.254)
		(layer "In4.Cu")
		(net "P12V_OCP_SFF_ISENSE_MPS_MAM")
	)
	(segment
		(start 321.091814 -51.794918)
		(end 314.148724 -44.851828)
		(width 0.254)
		(layer "In4.Cu")
		(net "P12V_OCP_SFF_ISENSE_MPS_MAM")
	)
	(segment
		(start 433.959 -33.061148)
		(end 435.907942 -33.061148)
		(width 0.254)
		(layer "In6.Cu")
		(net "P12V_OCP_SFF_ISENSE_MPS_MAM")
	)
	(segment
		(start 379.550422 -51.794918)
		(end 402.957792 -28.387548)
		(width 0.254)
		(layer "In6.Cu")
		(net "P12V_OCP_SFF_ISENSE_MPS_MAM")
	)
	(segment
		(start 331.8002 -51.794918)
		(end 379.550422 -51.794918)
		(width 0.254)
		(layer "In6.Cu")
		(net "P12V_OCP_SFF_ISENSE_MPS_MAM")
	)
	(segment
		(start 402.957792 -28.387548)
		(end 429.2854 -28.387548)
		(width 0.254)
		(layer "In6.Cu")
		(net "P12V_OCP_SFF_ISENSE_MPS_MAM")
	)
	(segment
		(start 429.2854 -28.387548)
		(end 433.959 -33.061148)
		(width 0.254)
		(layer "In6.Cu")
		(net "P12V_OCP_SFF_ISENSE_MPS_MAM")
	)
	(segment
		(start 435.907942 -33.061148)
		(end 437.231536 -34.384742)
		(width 0.254)
		(layer "In6.Cu")
		(net "P12V_OCP_SFF_ISENSE_MPS_MAM")
	)
	(segment
		(start 435.181248 -35.889438)
		(end 436.018686 -35.889438)
		(width 0.254)
		(layer "F.Cu")
		(net "P12V_OCP_SFF_ISENSE_MAM_TIC")
	)
	(segment
		(start 324.037198 -45.86351)
		(end 324.646798 -45.86351)
		(width 0.254)
		(layer "F.Cu")
		(net "P12V_OCP_SFF_ISENSE_MAM_TIC")
	)
	(via
		(at 436.018686 -35.889438)
		(size 0.508)
		(drill 0.254)
		(layers "F.Cu" "B.Cu")
		(net "P12V_OCP_SFF_ISENSE_MAM_TIC")
	)
	(via
		(at 324.979538 -54.176168)
		(size 0.508)
		(drill 0.254)
		(layers "F.Cu" "B.Cu")
		(net "P12V_OCP_SFF_ISENSE_MAM_TIC")
	)
	(via
		(at 324.646798 -45.86351)
		(size 0.508)
		(drill 0.254)
		(layers "F.Cu" "B.Cu")
		(net "P12V_OCP_SFF_ISENSE_MAM_TIC")
	)
	(segment
		(start 325.006208 -46.22292)
		(end 325.133208 -46.22292)
		(width 0.254)
		(layer "B.Cu")
		(net "P12V_OCP_SFF_ISENSE_MAM_TIC")
	)
	(segment
		(start 325.533004 -53.622702)
		(end 324.979538 -54.176168)
		(width 0.254)
		(layer "B.Cu")
		(net "P12V_OCP_SFF_ISENSE_MAM_TIC")
	)
	(segment
		(start 325.533004 -46.622716)
		(end 325.533004 -53.622702)
		(width 0.254)
		(layer "B.Cu")
		(net "P12V_OCP_SFF_ISENSE_MAM_TIC")
	)
	(segment
		(start 324.646798 -45.86351)
		(end 325.006208 -46.22292)
		(width 0.254)
		(layer "B.Cu")
		(net "P12V_OCP_SFF_ISENSE_MAM_TIC")
	)
	(segment
		(start 325.133208 -46.22292)
		(end 325.533004 -46.622716)
		(width 0.254)
		(layer "B.Cu")
		(net "P12V_OCP_SFF_ISENSE_MAM_TIC")
	)
	(segment
		(start 399.3388 -35.397948)
		(end 430.7586 -35.397948)
		(width 0.254)
		(layer "In6.Cu")
		(net "P12V_OCP_SFF_ISENSE_MAM_TIC")
	)
	(segment
		(start 324.979538 -54.176168)
		(end 329.983592 -54.176168)
		(width 0.254)
		(layer "In6.Cu")
		(net "P12V_OCP_SFF_ISENSE_MAM_TIC")
	)
	(segment
		(start 330.186792 -54.379368)
		(end 380.35738 -54.379368)
		(width 0.254)
		(layer "In6.Cu")
		(net "P12V_OCP_SFF_ISENSE_MAM_TIC")
	)
	(segment
		(start 380.35738 -54.379368)
		(end 399.3388 -35.397948)
		(width 0.254)
		(layer "In6.Cu")
		(net "P12V_OCP_SFF_ISENSE_MAM_TIC")
	)
	(segment
		(start 329.983592 -54.176168)
		(end 330.186792 -54.379368)
		(width 0.254)
		(layer "In6.Cu")
		(net "P12V_OCP_SFF_ISENSE_MAM_TIC")
	)
	(segment
		(start 431.25009 -35.889438)
		(end 436.018686 -35.889438)
		(width 0.254)
		(layer "In6.Cu")
		(net "P12V_OCP_SFF_ISENSE_MAM_TIC")
	)
	(segment
		(start 430.7586 -35.397948)
		(end 431.25009 -35.889438)
		(width 0.254)
		(layer "In6.Cu")
		(net "P12V_OCP_SFF_ISENSE_MAM_TIC")
	)
	(segment
		(start 433.10048 -36.47694)
		(end 433.10048 -32.502348)
		(width 0.254)
		(layer "F.Cu")
		(net "P12V_OCP_SFF_ISENSE_MAM_MAM")
	)
	(segment
		(start 433.10048 -32.502348)
		(end 433.82946 -31.773368)
		(width 0.254)
		(layer "F.Cu")
		(net "P12V_OCP_SFF_ISENSE_MAM_MAM")
	)
	(segment
		(start 311.141872 -33.715706)
		(end 310.617108 -33.715706)
		(width 0.254)
		(layer "F.Cu")
		(net "P12V_OCP_SFF_ISENSE_MAM_MAM")
	)
	(segment
		(start 310.617108 -33.715706)
		(end 310.238394 -34.09442)
		(width 0.254)
		(layer "F.Cu")
		(net "P12V_OCP_SFF_ISENSE_MAM_MAM")
	)
	(segment
		(start 433.82946 -31.773368)
		(end 435.208172 -31.773368)
		(width 0.254)
		(layer "F.Cu")
		(net "P12V_OCP_SFF_ISENSE_MAM_MAM")
	)
	(via
		(at 310.238394 -34.09442)
		(size 0.508)
		(drill 0.254)
		(layers "F.Cu" "B.Cu")
		(net "P12V_OCP_SFF_ISENSE_MAM_MAM")
	)
	(via
		(at 433.10048 -36.47694)
		(size 0.508)
		(drill 0.254)
		(layers "F.Cu" "B.Cu")
		(net "P12V_OCP_SFF_ISENSE_MAM_MAM")
	)
	(via
		(at 322.41744 -55.786528)
		(size 0.508)
		(drill 0.254)
		(layers "F.Cu" "B.Cu")
		(net "P12V_OCP_SFF_ISENSE_MAM_MAM")
	)
	(segment
		(start 322.41744 -55.786528)
		(end 322.41744 -54.107588)
		(width 0.254)
		(layer "In4.Cu")
		(net "P12V_OCP_SFF_ISENSE_MAM_MAM")
	)
	(segment
		(start 313.309 -44.999148)
		(end 313.309 -38.285928)
		(width 0.254)
		(layer "In4.Cu")
		(net "P12V_OCP_SFF_ISENSE_MAM_MAM")
	)
	(segment
		(start 322.41744 -54.107588)
		(end 313.309 -44.999148)
		(width 0.254)
		(layer "In4.Cu")
		(net "P12V_OCP_SFF_ISENSE_MAM_MAM")
	)
	(segment
		(start 313.309 -38.285928)
		(end 310.238394 -35.215322)
		(width 0.254)
		(layer "In4.Cu")
		(net "P12V_OCP_SFF_ISENSE_MAM_MAM")
	)
	(segment
		(start 310.238394 -35.215322)
		(end 310.238394 -34.09442)
		(width 0.254)
		(layer "In4.Cu")
		(net "P12V_OCP_SFF_ISENSE_MAM_MAM")
	)
	(segment
		(start 431.389282 -43.611546)
		(end 415.068258 -43.611546)
		(width 0.254)
		(layer "In6.Cu")
		(net "P12V_OCP_SFF_ISENSE_MAM_MAM")
	)
	(segment
		(start 323.014848 -56.383936)
		(end 322.41744 -55.786528)
		(width 0.254)
		(layer "In6.Cu")
		(net "P12V_OCP_SFF_ISENSE_MAM_MAM")
	)
	(segment
		(start 432.31308 -37.26434)
		(end 432.31308 -42.687748)
		(width 0.254)
		(layer "In6.Cu")
		(net "P12V_OCP_SFF_ISENSE_MAM_MAM")
	)
	(segment
		(start 392.703304 -44.778168)
		(end 381.161544 -56.319928)
		(width 0.254)
		(layer "In6.Cu")
		(net "P12V_OCP_SFF_ISENSE_MAM_MAM")
	)
	(segment
		(start 380.6317 -56.38419)
		(end 380.631446 -56.383936)
		(width 0.254)
		(layer "In6.Cu")
		(net "P12V_OCP_SFF_ISENSE_MAM_MAM")
	)
	(segment
		(start 413.901636 -44.778168)
		(end 392.703304 -44.778168)
		(width 0.254)
		(layer "In6.Cu")
		(net "P12V_OCP_SFF_ISENSE_MAM_MAM")
	)
	(segment
		(start 381.161544 -56.319928)
		(end 381.017526 -56.319928)
		(width 0.254)
		(layer "In6.Cu")
		(net "P12V_OCP_SFF_ISENSE_MAM_MAM")
	)
	(segment
		(start 381.017526 -56.319928)
		(end 380.953264 -56.38419)
		(width 0.254)
		(layer "In6.Cu")
		(net "P12V_OCP_SFF_ISENSE_MAM_MAM")
	)
	(segment
		(start 380.953264 -56.38419)
		(end 380.6317 -56.38419)
		(width 0.254)
		(layer "In6.Cu")
		(net "P12V_OCP_SFF_ISENSE_MAM_MAM")
	)
	(segment
		(start 432.31308 -42.687748)
		(end 431.389282 -43.611546)
		(width 0.254)
		(layer "In6.Cu")
		(net "P12V_OCP_SFF_ISENSE_MAM_MAM")
	)
	(segment
		(start 415.068258 -43.611546)
		(end 413.901636 -44.778168)
		(width 0.254)
		(layer "In6.Cu")
		(net "P12V_OCP_SFF_ISENSE_MAM_MAM")
	)
	(segment
		(start 380.631446 -56.383936)
		(end 323.014848 -56.383936)
		(width 0.254)
		(layer "In6.Cu")
		(net "P12V_OCP_SFF_ISENSE_MAM_MAM")
	)
	(segment
		(start 433.10048 -36.47694)
		(end 432.31308 -37.26434)
		(width 0.254)
		(layer "In6.Cu")
		(net "P12V_OCP_SFF_ISENSE_MAM_MAM")
	)
	(segment
		(start 397.876268 -76.661264)
		(end 397.265144 -76.661264)
		(width 0.254)
		(layer "F.Cu")
		(net "P12V_OCP_SFF")
	)
	(segment
		(start 453.454262 -24.619458)
		(end 453.443594 -24.630126)
		(width 0.4572)
		(layer "F.Cu")
		(net "P12V_OCP_SFF")
	)
	(segment
		(start 437.806084 -22.014688)
		(end 436.526432 -23.29434)
		(width 0.4572)
		(layer "F.Cu")
		(net "P12V_OCP_SFF")
	)
	(segment
		(start 399.165064 -81.051146)
		(end 399.165064 -78.37678)
		(width 0.508)
		(layer "F.Cu")
		(net "P12V_OCP_SFF")
	)
	(segment
		(start 455.697844 -17.867122)
		(end 455.697844 -23.957026)
		(width 0.508)
		(layer "F.Cu")
		(net "P12V_OCP_SFF")
	)
	(segment
		(start 436.526432 -23.29434)
		(end 436.526432 -25.656286)
		(width 0.4572)
		(layer "F.Cu")
		(net "P12V_OCP_SFF")
	)
	(segment
		(start 440.993022 -22.816058)
		(end 440.993022 -22.628098)
		(width 0.4572)
		(layer "F.Cu")
		(net "P12V_OCP_SFF")
	)
	(segment
		(start 455.19213 -17.361408)
		(end 455.697844 -17.867122)
		(width 0.508)
		(layer "F.Cu")
		(net "P12V_OCP_SFF")
	)
	(segment
		(start 397.265144 -76.661264)
		(end 397.15948 -76.5556)
		(width 0.254)
		(layer "F.Cu")
		(net "P12V_OCP_SFF")
	)
	(segment
		(start 452.605394 -17.361408)
		(end 455.19213 -17.361408)
		(width 0.508)
		(layer "F.Cu")
		(net "P12V_OCP_SFF")
	)
	(segment
		(start 453.443594 -24.630126)
		(end 453.443594 -25.638506)
		(width 0.4572)
		(layer "F.Cu")
		(net "P12V_OCP_SFF")
	)
	(segment
		(start 455.035412 -24.619458)
		(end 453.454262 -24.619458)
		(width 0.508)
		(layer "F.Cu")
		(net "P12V_OCP_SFF")
	)
	(segment
		(start 455.697844 -23.957026)
		(end 455.035412 -24.619458)
		(width 0.508)
		(layer "F.Cu")
		(net "P12V_OCP_SFF")
	)
	(segment
		(start 440.993022 -22.628098)
		(end 440.379612 -22.014688)
		(width 0.4572)
		(layer "F.Cu")
		(net "P12V_OCP_SFF")
	)
	(segment
		(start 397.15948 -76.5556)
		(end 396.679166 -76.5556)
		(width 0.254)
		(layer "F.Cu")
		(net "P12V_OCP_SFF")
	)
	(segment
		(start 399.165064 -78.37678)
		(end 397.876268 -77.087984)
		(width 0.508)
		(layer "F.Cu")
		(net "P12V_OCP_SFF")
	)
	(segment
		(start 440.379612 -22.014688)
		(end 437.806084 -22.014688)
		(width 0.4572)
		(layer "F.Cu")
		(net "P12V_OCP_SFF")
	)
	(segment
		(start 397.876268 -77.087984)
		(end 397.876268 -76.661264)
		(width 0.508)
		(layer "F.Cu")
		(net "P12V_OCP_SFF")
	)
	(via
		(at 442.371734 -19.459702)
		(size 0.508)
		(drill 0.254)
		(layers "F.Cu" "B.Cu")
		(net "P12V_OCP_SFF")
	)
	(via
		(at 441.129674 -25.982422)
		(size 0.508)
		(drill 0.254)
		(layers "F.Cu" "B.Cu")
		(net "P12V_OCP_SFF")
	)
	(via
		(at 450.670676 -16.010382)
		(size 0.508)
		(drill 0.254)
		(layers "F.Cu" "B.Cu")
		(net "P12V_OCP_SFF")
	)
	(via
		(at 442.371734 -20.348702)
		(size 0.508)
		(drill 0.254)
		(layers "F.Cu" "B.Cu")
		(net "P12V_OCP_SFF")
	)
	(via
		(at 441.56249 -25.461976)
		(size 0.508)
		(drill 0.254)
		(layers "F.Cu" "B.Cu")
		(net "P12V_OCP_SFF")
	)
	(via
		(at 450.669914 -14.526514)
		(size 0.508)
		(drill 0.254)
		(layers "F.Cu" "B.Cu")
		(net "P12V_OCP_SFF")
	)
	(via
		(at 442.018674 -25.982422)
		(size 0.508)
		(drill 0.254)
		(layers "F.Cu" "B.Cu")
		(net "P12V_OCP_SFF")
	)
	(via
		(at 444.166244 -24.741632)
		(size 0.508)
		(drill 0.254)
		(layers "F.Cu" "B.Cu")
		(net "P12V_OCP_SFF")
	)
	(via
		(at 442.45149 -25.461976)
		(size 0.508)
		(drill 0.254)
		(layers "F.Cu" "B.Cu")
		(net "P12V_OCP_SFF")
	)
	(via
		(at 443.34049 -25.461976)
		(size 0.508)
		(drill 0.254)
		(layers "F.Cu" "B.Cu")
		(net "P12V_OCP_SFF")
	)
	(via
		(at 452.054976 -17.798542)
		(size 0.508)
		(drill 0.254)
		(layers "F.Cu" "B.Cu")
		(net "P12V_OCP_SFF")
	)
	(via
		(at 442.371734 -18.824702)
		(size 0.508)
		(drill 0.254)
		(layers "F.Cu" "B.Cu")
		(net "P12V_OCP_SFF")
	)
	(via
		(at 442.371734 -20.983702)
		(size 0.508)
		(drill 0.254)
		(layers "F.Cu" "B.Cu")
		(net "P12V_OCP_SFF")
	)
	(via
		(at 399.165064 -81.051146)
		(size 0.508)
		(drill 0.254)
		(layers "F.Cu" "B.Cu")
		(net "P12V_OCP_SFF")
	)
	(via
		(at 452.054976 -18.535142)
		(size 0.508)
		(drill 0.254)
		(layers "F.Cu" "B.Cu")
		(net "P12V_OCP_SFF")
	)
	(via
		(at 442.907674 -25.982422)
		(size 0.508)
		(drill 0.254)
		(layers "F.Cu" "B.Cu")
		(net "P12V_OCP_SFF")
	)
	(via
		(at 450.670676 -15.273782)
		(size 0.508)
		(drill 0.254)
		(layers "F.Cu" "B.Cu")
		(net "P12V_OCP_SFF")
	)
	(segment
		(start 408.606244 -75.285092)
		(end 402.84019 -81.051146)
		(width 0.508)
		(layer "B.Cu")
		(net "P12V_OCP_SFF")
	)
	(segment
		(start 436.89397 -27.156664)
		(end 436.03037 -28.020264)
		(width 0.508)
		(layer "B.Cu")
		(net "P12V_OCP_SFF")
	)
	(segment
		(start 424.803824 -42.30116)
		(end 411.608016 -55.496968)
		(width 0.508)
		(layer "B.Cu")
		(net "P12V_OCP_SFF")
	)
	(segment
		(start 450.669914 -15.27302)
		(end 450.670676 -15.273782)
		(width 0.508)
		(layer "B.Cu")
		(net "P12V_OCP_SFF")
	)
	(segment
		(start 440.264042 -27.156664)
		(end 436.89397 -27.156664)
		(width 0.508)
		(layer "B.Cu")
		(net "P12V_OCP_SFF")
	)
	(segment
		(start 436.03037 -28.020264)
		(end 436.03037 -30.789626)
		(width 0.508)
		(layer "B.Cu")
		(net "P12V_OCP_SFF")
	)
	(segment
		(start 435.271672 -31.548324)
		(end 434.292248 -31.548324)
		(width 0.508)
		(layer "B.Cu")
		(net "P12V_OCP_SFF")
	)
	(segment
		(start 450.669914 -14.526514)
		(end 450.669914 -15.27302)
		(width 0.508)
		(layer "B.Cu")
		(net "P12V_OCP_SFF")
	)
	(segment
		(start 411.608016 -55.496968)
		(end 411.608016 -65.196212)
		(width 0.508)
		(layer "B.Cu")
		(net "P12V_OCP_SFF")
	)
	(segment
		(start 424.803824 -38.972998)
		(end 424.803824 -42.30116)
		(width 0.508)
		(layer "B.Cu")
		(net "P12V_OCP_SFF")
	)
	(segment
		(start 441.129674 -26.291032)
		(end 440.264042 -27.156664)
		(width 0.508)
		(layer "B.Cu")
		(net "P12V_OCP_SFF")
	)
	(segment
		(start 425.056554 -28.29433)
		(end 423.28719 -30.063694)
		(width 0.508)
		(layer "B.Cu")
		(net "P12V_OCP_SFF")
	)
	(segment
		(start 402.84019 -81.051146)
		(end 399.165064 -81.051146)
		(width 0.508)
		(layer "B.Cu")
		(net "P12V_OCP_SFF")
	)
	(segment
		(start 436.03037 -30.789626)
		(end 435.271672 -31.548324)
		(width 0.508)
		(layer "B.Cu")
		(net "P12V_OCP_SFF")
	)
	(segment
		(start 423.28719 -37.456364)
		(end 424.803824 -38.972998)
		(width 0.508)
		(layer "B.Cu")
		(net "P12V_OCP_SFF")
	)
	(segment
		(start 423.28719 -30.063694)
		(end 423.28719 -37.456364)
		(width 0.508)
		(layer "B.Cu")
		(net "P12V_OCP_SFF")
	)
	(segment
		(start 434.292248 -31.548324)
		(end 431.038254 -28.29433)
		(width 0.508)
		(layer "B.Cu")
		(net "P12V_OCP_SFF")
	)
	(segment
		(start 411.608016 -65.196212)
		(end 408.606244 -68.197984)
		(width 0.508)
		(layer "B.Cu")
		(net "P12V_OCP_SFF")
	)
	(segment
		(start 441.129674 -25.982422)
		(end 441.129674 -26.291032)
		(width 0.508)
		(layer "B.Cu")
		(net "P12V_OCP_SFF")
	)
	(segment
		(start 408.606244 -68.197984)
		(end 408.606244 -75.285092)
		(width 0.508)
		(layer "B.Cu")
		(net "P12V_OCP_SFF")
	)
	(segment
		(start 452.054976 -18.535142)
		(end 452.054976 -17.798542)
		(width 0.508)
		(layer "B.Cu")
		(net "P12V_OCP_SFF")
	)
	(segment
		(start 431.038254 -28.29433)
		(end 425.056554 -28.29433)
		(width 0.508)
		(layer "B.Cu")
		(net "P12V_OCP_SFF")
	)
	(segment
		(start 75.946508 -22.5298)
		(end 75.946508 -21.839682)
		(width 0.10668)
		(layer "F.Cu")
		(net "P12V_OCP_SENSE_2")
	)
	(segment
		(start 60.527438 -32.287972)
		(end 60.527438 -33.044638)
		(width 0.10668)
		(layer "F.Cu")
		(net "P12V_OCP_SENSE_2")
	)
	(segment
		(start 75.946508 -21.839682)
		(end 77.460856 -21.839682)
		(width 0.10668)
		(layer "F.Cu")
		(net "P12V_OCP_SENSE_2")
	)
	(segment
		(start 60.527438 -33.044638)
		(end 60.6044 -33.1216)
		(width 0.10668)
		(layer "F.Cu")
		(net "P12V_OCP_SENSE_2")
	)
	(segment
		(start 77.460856 -21.839682)
		(end 77.856334 -21.444204)
		(width 0.10668)
		(layer "F.Cu")
		(net "P12V_OCP_SENSE_2")
	)
	(via
		(at 60.6044 -33.1216)
		(size 0.508)
		(drill 0.254)
		(layers "F.Cu" "B.Cu")
		(net "P12V_OCP_SENSE_2")
	)
	(via
		(at 75.946508 -22.5298)
		(size 0.508)
		(drill 0.254)
		(layers "F.Cu" "B.Cu")
		(net "P12V_OCP_SENSE_2")
	)
	(segment
		(start 61.5188 -34.2138)
		(end 63.066422 -34.2138)
		(width 0.11684)
		(layer "In4.Cu")
		(net "P12V_OCP_SENSE_2")
	)
	(segment
		(start 63.066422 -34.2138)
		(end 65.923414 -31.356808)
		(width 0.11684)
		(layer "In4.Cu")
		(net "P12V_OCP_SENSE_2")
	)
	(segment
		(start 69.257926 -31.9278)
		(end 73.9394 -31.9278)
		(width 0.11684)
		(layer "In4.Cu")
		(net "P12V_OCP_SENSE_2")
	)
	(segment
		(start 75.349862 -24.066246)
		(end 75.349862 -23.126446)
		(width 0.11684)
		(layer "In4.Cu")
		(net "P12V_OCP_SENSE_2")
	)
	(segment
		(start 74.97572 -30.89148)
		(end 74.97572 -24.440388)
		(width 0.11684)
		(layer "In4.Cu")
		(net "P12V_OCP_SENSE_2")
	)
	(segment
		(start 73.9394 -31.9278)
		(end 74.97572 -30.89148)
		(width 0.11684)
		(layer "In4.Cu")
		(net "P12V_OCP_SENSE_2")
	)
	(segment
		(start 75.349862 -23.126446)
		(end 75.946508 -22.5298)
		(width 0.11684)
		(layer "In4.Cu")
		(net "P12V_OCP_SENSE_2")
	)
	(segment
		(start 68.686934 -31.356808)
		(end 69.257926 -31.9278)
		(width 0.11684)
		(layer "In4.Cu")
		(net "P12V_OCP_SENSE_2")
	)
	(segment
		(start 65.923414 -31.356808)
		(end 68.686934 -31.356808)
		(width 0.11684)
		(layer "In4.Cu")
		(net "P12V_OCP_SENSE_2")
	)
	(segment
		(start 74.97572 -24.440388)
		(end 75.349862 -24.066246)
		(width 0.11684)
		(layer "In4.Cu")
		(net "P12V_OCP_SENSE_2")
	)
	(segment
		(start 60.6044 -33.1216)
		(end 60.6044 -33.2994)
		(width 0.11684)
		(layer "In4.Cu")
		(net "P12V_OCP_SENSE_2")
	)
	(segment
		(start 60.6044 -33.2994)
		(end 61.5188 -34.2138)
		(width 0.11684)
		(layer "In4.Cu")
		(net "P12V_OCP_SENSE_2")
	)
	(segment
		(start 435.181248 -33.76803)
		(end 435.203346 -33.745932)
		(width 0.10668)
		(layer "F.Cu")
		(net "P12V_OCP_SENSE_1")
	)
	(segment
		(start 435.181248 -35.089338)
		(end 435.181248 -33.76803)
		(width 0.10668)
		(layer "F.Cu")
		(net "P12V_OCP_SENSE_1")
	)
	(segment
		(start 447.905886 -22.864318)
		(end 447.399918 -22.864318)
		(width 0.10668)
		(layer "F.Cu")
		(net "P12V_OCP_SENSE_1")
	)
	(segment
		(start 448.087242 -22.682962)
		(end 447.905886 -22.864318)
		(width 0.10668)
		(layer "F.Cu")
		(net "P12V_OCP_SENSE_1")
	)
	(segment
		(start 448.087242 -22.125178)
		(end 448.087242 -22.682962)
		(width 0.10668)
		(layer "F.Cu")
		(net "P12V_OCP_SENSE_1")
	)
	(segment
		(start 435.208172 -33.741106)
		(end 435.208172 -32.573468)
		(width 0.10668)
		(layer "F.Cu")
		(net "P12V_OCP_SENSE_1")
	)
	(segment
		(start 449.997068 -21.7297)
		(end 449.75653 -21.7297)
		(width 0.10668)
		(layer "F.Cu")
		(net "P12V_OCP_SENSE_1")
	)
	(segment
		(start 435.203346 -33.745932)
		(end 435.208172 -33.741106)
		(width 0.10668)
		(layer "F.Cu")
		(net "P12V_OCP_SENSE_1")
	)
	(segment
		(start 449.75653 -21.7297)
		(end 449.36156 -22.12467)
		(width 0.10668)
		(layer "F.Cu")
		(net "P12V_OCP_SENSE_1")
	)
	(segment
		(start 449.36156 -22.12467)
		(end 448.08775 -22.12467)
		(width 0.10668)
		(layer "F.Cu")
		(net "P12V_OCP_SENSE_1")
	)
	(segment
		(start 448.08775 -22.12467)
		(end 448.087242 -22.125178)
		(width 0.10668)
		(layer "F.Cu")
		(net "P12V_OCP_SENSE_1")
	)
	(via
		(at 435.203346 -33.745932)
		(size 0.508)
		(drill 0.254)
		(layers "F.Cu" "B.Cu")
		(net "P12V_OCP_SENSE_1")
	)
	(via
		(at 447.399918 -22.864318)
		(size 0.508)
		(drill 0.254)
		(layers "F.Cu" "B.Cu")
		(net "P12V_OCP_SENSE_1")
	)
	(segment
		(start 450.965316 -26.831544)
		(end 450.965316 -32.366458)
		(width 0.10668)
		(layer "B.Cu")
		(net "P12V_OCP_SENSE_1")
	)
	(segment
		(start 449.106544 -22.864318)
		(end 449.713604 -23.471378)
		(width 0.10668)
		(layer "B.Cu")
		(net "P12V_OCP_SENSE_1")
	)
	(segment
		(start 449.585842 -33.745932)
		(end 435.203346 -33.745932)
		(width 0.10668)
		(layer "B.Cu")
		(net "P12V_OCP_SENSE_1")
	)
	(segment
		(start 449.713604 -25.579832)
		(end 450.965316 -26.831544)
		(width 0.10668)
		(layer "B.Cu")
		(net "P12V_OCP_SENSE_1")
	)
	(segment
		(start 447.399918 -22.864318)
		(end 449.106544 -22.864318)
		(width 0.10668)
		(layer "B.Cu")
		(net "P12V_OCP_SENSE_1")
	)
	(segment
		(start 450.965316 -32.366458)
		(end 449.585842 -33.745932)
		(width 0.10668)
		(layer "B.Cu")
		(net "P12V_OCP_SENSE_1")
	)
	(segment
		(start 449.713604 -23.471378)
		(end 449.713604 -25.579832)
		(width 0.10668)
		(layer "B.Cu")
		(net "P12V_OCP_SENSE_1")
	)
	(segment
		(start 76.480416 -19.220942)
		(end 75.824588 -19.220942)
		(width 0.10668)
		(layer "F.Cu")
		(net "P12V_OCP_REG_2")
	)
	(segment
		(start 77.133958 -19.221704)
		(end 77.856334 -19.94408)
		(width 0.10668)
		(layer "F.Cu")
		(net "P12V_OCP_REG_2")
	)
	(segment
		(start 76.481178 -19.221704)
		(end 76.480416 -19.220942)
		(width 0.10668)
		(layer "F.Cu")
		(net "P12V_OCP_REG_2")
	)
	(segment
		(start 76.481178 -19.221704)
		(end 77.133958 -19.221704)
		(width 0.10668)
		(layer "F.Cu")
		(net "P12V_OCP_REG_2")
	)
	(via
		(at 76.481178 -19.221704)
		(size 0.508)
		(drill 0.254)
		(layers "F.Cu" "B.Cu")
		(net "P12V_OCP_REG_2")
	)
	(segment
		(start 449.04914 -19.506438)
		(end 449.060824 -19.518122)
		(width 0.10668)
		(layer "F.Cu")
		(net "P12V_OCP_REG_1")
	)
	(segment
		(start 447.965322 -19.506438)
		(end 449.04914 -19.506438)
		(width 0.10668)
		(layer "F.Cu")
		(net "P12V_OCP_REG_1")
	)
	(segment
		(start 449.361052 -19.518122)
		(end 449.060824 -19.518122)
		(width 0.10668)
		(layer "F.Cu")
		(net "P12V_OCP_REG_1")
	)
	(segment
		(start 449.997068 -20.229576)
		(end 449.997068 -20.154138)
		(width 0.10668)
		(layer "F.Cu")
		(net "P12V_OCP_REG_1")
	)
	(segment
		(start 449.997068 -20.154138)
		(end 449.361052 -19.518122)
		(width 0.10668)
		(layer "F.Cu")
		(net "P12V_OCP_REG_1")
	)
	(via
		(at 449.060824 -19.518122)
		(size 0.508)
		(drill 0.254)
		(layers "F.Cu" "B.Cu")
		(net "P12V_OCP_REG_1")
	)
	(segment
		(start 81.22158 -19.94408)
		(end 80.856582 -19.94408)
		(width 0.10668)
		(layer "F.Cu")
		(net "P12V_OCP_PWRGD_2")
	)
	(segment
		(start 81.620868 -17.745202)
		(end 81.32826 -18.03781)
		(width 0.10668)
		(layer "F.Cu")
		(net "P12V_OCP_PWRGD_2")
	)
	(segment
		(start 81.32826 -19.8374)
		(end 81.22158 -19.94408)
		(width 0.10668)
		(layer "F.Cu")
		(net "P12V_OCP_PWRGD_2")
	)
	(segment
		(start 81.32826 -19.722592)
		(end 81.32826 -19.8374)
		(width 0.10668)
		(layer "F.Cu")
		(net "P12V_OCP_PWRGD_2")
	)
	(segment
		(start 81.32826 -18.03781)
		(end 81.32826 -19.722592)
		(width 0.10668)
		(layer "F.Cu")
		(net "P12V_OCP_PWRGD_2")
	)
	(segment
		(start 81.906618 -17.745202)
		(end 81.620868 -17.745202)
		(width 0.10668)
		(layer "F.Cu")
		(net "P12V_OCP_PWRGD_2")
	)
	(via
		(at 81.32826 -19.722592)
		(size 0.508)
		(drill 0.254)
		(layers "F.Cu" "B.Cu")
		(net "P12V_OCP_PWRGD_2")
	)
	(segment
		(start 453.417432 -19.323812)
		(end 453.417432 -19.80946)
		(width 0.10668)
		(layer "F.Cu")
		(net "P12V_OCP_PWRGD_1")
	)
	(segment
		(start 453.417432 -18.660618)
		(end 454.047352 -18.030698)
		(width 0.10668)
		(layer "F.Cu")
		(net "P12V_OCP_PWRGD_1")
	)
	(segment
		(start 453.417432 -19.80946)
		(end 452.997316 -20.229576)
		(width 0.10668)
		(layer "F.Cu")
		(net "P12V_OCP_PWRGD_1")
	)
	(segment
		(start 453.417432 -19.323812)
		(end 453.417432 -18.660618)
		(width 0.10668)
		(layer "F.Cu")
		(net "P12V_OCP_PWRGD_1")
	)
	(via
		(at 453.417432 -19.323812)
		(size 0.508)
		(drill 0.254)
		(layers "F.Cu" "B.Cu")
		(net "P12V_OCP_PWRGD_1")
	)
	(segment
		(start 61.845698 -27.39009)
		(end 60.434728 -27.39009)
		(width 0.10668)
		(layer "F.Cu")
		(net "P12V_OCP_OV_FB_2")
	)
	(segment
		(start 63.877698 -27.39009)
		(end 62.861698 -27.39009)
		(width 0.10668)
		(layer "F.Cu")
		(net "P12V_OCP_OV_FB_2")
	)
	(segment
		(start 65.272412 -27.39009)
		(end 63.877698 -27.39009)
		(width 0.10668)
		(layer "F.Cu")
		(net "P12V_OCP_OV_FB_2")
	)
	(segment
		(start 62.861698 -27.39009)
		(end 61.845698 -27.39009)
		(width 0.10668)
		(layer "F.Cu")
		(net "P12V_OCP_OV_FB_2")
	)
	(segment
		(start 60.434728 -27.39009)
		(end 60.433966 -27.390852)
		(width 0.10668)
		(layer "F.Cu")
		(net "P12V_OCP_OV_FB_2")
	)
	(via
		(at 60.433966 -27.390852)
		(size 0.762)
		(drill 0.381)
		(layers "F.Cu" "B.Cu")
		(net "P12V_OCP_OV_FB_2")
	)
	(segment
		(start 439.953146 -27.675586)
		(end 438.558432 -27.675586)
		(width 0.10668)
		(layer "F.Cu")
		(net "P12V_OCP_OV_FB_1")
	)
	(segment
		(start 437.542432 -27.675586)
		(end 436.323232 -27.675586)
		(width 0.10668)
		(layer "F.Cu")
		(net "P12V_OCP_OV_FB_1")
	)
	(segment
		(start 436.323232 -26.659586)
		(end 436.526432 -26.456386)
		(width 0.10668)
		(layer "F.Cu")
		(net "P12V_OCP_OV_FB_1")
	)
	(segment
		(start 438.558432 -27.675586)
		(end 437.542432 -27.675586)
		(width 0.10668)
		(layer "F.Cu")
		(net "P12V_OCP_OV_FB_1")
	)
	(segment
		(start 436.323232 -27.675586)
		(end 436.323232 -26.659586)
		(width 0.10668)
		(layer "F.Cu")
		(net "P12V_OCP_OV_FB_1")
	)
	(via
		(at 436.323232 -27.675586)
		(size 0.762)
		(drill 0.381)
		(layers "F.Cu" "B.Cu")
		(net "P12V_OCP_OV_FB_1")
	)
	(segment
		(start 77.537564 -17.280128)
		(end 77.9018 -17.280128)
		(width 0.10668)
		(layer "F.Cu")
		(net "P12V_OCP_OV_2")
	)
	(segment
		(start 77.9018 -17.280128)
		(end 78.920594 -18.298922)
		(width 0.10668)
		(layer "F.Cu")
		(net "P12V_OCP_OV_2")
	)
	(segment
		(start 78.856586 -19.94408)
		(end 78.856586 -19.278346)
		(width 0.10668)
		(layer "F.Cu")
		(net "P12V_OCP_OV_2")
	)
	(segment
		(start 78.856586 -19.278346)
		(end 78.85557 -19.27733)
		(width 0.10668)
		(layer "F.Cu")
		(net "P12V_OCP_OV_2")
	)
	(segment
		(start 76.515214 -17.050512)
		(end 76.74483 -17.280128)
		(width 0.10668)
		(layer "F.Cu")
		(net "P12V_OCP_OV_2")
	)
	(segment
		(start 78.920594 -19.212306)
		(end 78.85557 -19.27733)
		(width 0.10668)
		(layer "F.Cu")
		(net "P12V_OCP_OV_2")
	)
	(segment
		(start 78.920594 -18.298922)
		(end 78.920594 -19.212306)
		(width 0.10668)
		(layer "F.Cu")
		(net "P12V_OCP_OV_2")
	)
	(segment
		(start 76.74483 -17.280128)
		(end 77.537564 -17.280128)
		(width 0.10668)
		(layer "F.Cu")
		(net "P12V_OCP_OV_2")
	)
	(via
		(at 78.85557 -19.27733)
		(size 0.508)
		(drill 0.254)
		(layers "F.Cu" "B.Cu")
		(net "P12V_OCP_OV_2")
	)
	(segment
		(start 448.750436 -17.433798)
		(end 448.980052 -17.663414)
		(width 0.10668)
		(layer "F.Cu")
		(net "P12V_OCP_OV_1")
	)
	(segment
		(start 447.957702 -17.433798)
		(end 448.750436 -17.433798)
		(width 0.10668)
		(layer "F.Cu")
		(net "P12V_OCP_OV_1")
	)
	(segment
		(start 448.980052 -17.663414)
		(end 450.014594 -17.663414)
		(width 0.10668)
		(layer "F.Cu")
		(net "P12V_OCP_OV_1")
	)
	(segment
		(start 450.99732 -20.229576)
		(end 450.99732 -18.64614)
		(width 0.10668)
		(layer "F.Cu")
		(net "P12V_OCP_OV_1")
	)
	(segment
		(start 450.99732 -18.64614)
		(end 450.988684 -18.637504)
		(width 0.10668)
		(layer "F.Cu")
		(net "P12V_OCP_OV_1")
	)
	(segment
		(start 450.014594 -17.663414)
		(end 450.988684 -18.637504)
		(width 0.10668)
		(layer "F.Cu")
		(net "P12V_OCP_OV_1")
	)
	(via
		(at 450.988684 -18.637504)
		(size 0.508)
		(drill 0.254)
		(layers "F.Cu" "B.Cu")
		(net "P12V_OCP_OV_1")
	)
	(segment
		(start 67.987672 -32.376872)
		(end 67.564 -31.9532)
		(width 0.10668)
		(layer "F.Cu")
		(net "P12V_OCP_ISET_2")
	)
	(segment
		(start 67.564 -31.9532)
		(end 67.564 -31.851854)
		(width 0.10668)
		(layer "F.Cu")
		(net "P12V_OCP_ISET_2")
	)
	(segment
		(start 67.672458 -31.743396)
		(end 67.672458 -29.29001)
		(width 0.10668)
		(layer "F.Cu")
		(net "P12V_OCP_ISET_2")
	)
	(segment
		(start 68.147438 -32.376872)
		(end 67.987672 -32.376872)
		(width 0.10668)
		(layer "F.Cu")
		(net "P12V_OCP_ISET_2")
	)
	(segment
		(start 67.564 -31.851854)
		(end 67.672458 -31.743396)
		(width 0.10668)
		(layer "F.Cu")
		(net "P12V_OCP_ISET_2")
	)
	(via
		(at 67.564 -31.9532)
		(size 0.508)
		(drill 0.254)
		(layers "F.Cu" "B.Cu")
		(net "P12V_OCP_ISET_2")
	)
	(segment
		(start 442.828172 -32.662368)
		(end 442.828172 -31.83636)
		(width 0.10668)
		(layer "F.Cu")
		(net "P12V_OCP_ISET_1")
	)
	(segment
		(start 442.828172 -31.83636)
		(end 442.430408 -31.438596)
		(width 0.10668)
		(layer "F.Cu")
		(net "P12V_OCP_ISET_1")
	)
	(segment
		(start 442.353192 -30.175454)
		(end 442.42609 -30.248352)
		(width 0.10668)
		(layer "F.Cu")
		(net "P12V_OCP_ISET_1")
	)
	(segment
		(start 442.42609 -30.248352)
		(end 442.42609 -31.434278)
		(width 0.10668)
		(layer "F.Cu")
		(net "P12V_OCP_ISET_1")
	)
	(segment
		(start 442.353192 -29.575506)
		(end 442.353192 -30.175454)
		(width 0.10668)
		(layer "F.Cu")
		(net "P12V_OCP_ISET_1")
	)
	(segment
		(start 442.42609 -31.434278)
		(end 442.430408 -31.438596)
		(width 0.10668)
		(layer "F.Cu")
		(net "P12V_OCP_ISET_1")
	)
	(via
		(at 442.430408 -31.438596)
		(size 0.762)
		(drill 0.381)
		(layers "F.Cu" "B.Cu")
		(net "P12V_OCP_ISET_1")
	)
	(segment
		(start 61.543438 -31.487872)
		(end 61.543692 -31.487618)
		(width 0.254)
		(layer "F.Cu")
		(net "P12V_OCP_IMON_2")
	)
	(segment
		(start 61.543692 -31.123128)
		(end 61.517784 -31.09722)
		(width 0.254)
		(layer "F.Cu")
		(net "P12V_OCP_IMON_2")
	)
	(segment
		(start 62.269878 -30.30347)
		(end 61.517784 -30.30347)
		(width 0.254)
		(layer "F.Cu")
		(net "P12V_OCP_IMON_2")
	)
	(segment
		(start 62.559438 -30.59303)
		(end 62.269878 -30.30347)
		(width 0.254)
		(layer "F.Cu")
		(net "P12V_OCP_IMON_2")
	)
	(segment
		(start 61.543692 -31.487618)
		(end 61.543692 -31.123128)
		(width 0.254)
		(layer "F.Cu")
		(net "P12V_OCP_IMON_2")
	)
	(segment
		(start 63.575438 -31.487872)
		(end 64.591438 -31.487872)
		(width 0.254)
		(layer "F.Cu")
		(net "P12V_OCP_IMON_2")
	)
	(segment
		(start 62.559438 -31.487872)
		(end 62.559438 -30.59303)
		(width 0.254)
		(layer "F.Cu")
		(net "P12V_OCP_IMON_2")
	)
	(segment
		(start 66.172334 -29.29001)
		(end 66.172334 -29.95295)
		(width 0.254)
		(layer "F.Cu")
		(net "P12V_OCP_IMON_2")
	)
	(segment
		(start 66.172334 -29.95295)
		(end 64.637412 -31.487872)
		(width 0.254)
		(layer "F.Cu")
		(net "P12V_OCP_IMON_2")
	)
	(segment
		(start 62.559438 -31.487872)
		(end 63.575438 -31.487872)
		(width 0.254)
		(layer "F.Cu")
		(net "P12V_OCP_IMON_2")
	)
	(segment
		(start 61.517784 -31.09722)
		(end 61.517784 -30.30347)
		(width 0.254)
		(layer "F.Cu")
		(net "P12V_OCP_IMON_2")
	)
	(segment
		(start 64.637412 -31.487872)
		(end 64.591438 -31.487872)
		(width 0.254)
		(layer "F.Cu")
		(net "P12V_OCP_IMON_2")
	)
	(via
		(at 61.517784 -30.30347)
		(size 0.762)
		(drill 0.381)
		(layers "F.Cu" "B.Cu")
		(net "P12V_OCP_IMON_2")
	)
	(segment
		(start 439.953146 -31.092394)
		(end 439.956194 -31.092394)
		(width 0.254)
		(layer "F.Cu")
		(net "P12V_OCP_IMON_1")
	)
	(segment
		(start 436.086504 -31.6357)
		(end 436.086504 -30.550612)
		(width 0.254)
		(layer "F.Cu")
		(net "P12V_OCP_IMON_1")
	)
	(segment
		(start 437.240172 -30.905958)
		(end 436.884826 -30.550612)
		(width 0.254)
		(layer "F.Cu")
		(net "P12V_OCP_IMON_1")
	)
	(segment
		(start 438.256172 -31.773368)
		(end 437.240172 -31.773368)
		(width 0.254)
		(layer "F.Cu")
		(net "P12V_OCP_IMON_1")
	)
	(segment
		(start 436.224172 -31.773368)
		(end 436.086504 -31.6357)
		(width 0.254)
		(layer "F.Cu")
		(net "P12V_OCP_IMON_1")
	)
	(segment
		(start 439.272172 -31.773368)
		(end 438.256172 -31.773368)
		(width 0.254)
		(layer "F.Cu")
		(net "P12V_OCP_IMON_1")
	)
	(segment
		(start 439.272172 -31.773368)
		(end 439.953146 -31.092394)
		(width 0.254)
		(layer "F.Cu")
		(net "P12V_OCP_IMON_1")
	)
	(segment
		(start 437.240172 -31.773368)
		(end 437.240172 -30.905958)
		(width 0.254)
		(layer "F.Cu")
		(net "P12V_OCP_IMON_1")
	)
	(segment
		(start 439.956194 -31.092394)
		(end 440.853068 -30.19552)
		(width 0.254)
		(layer "F.Cu")
		(net "P12V_OCP_IMON_1")
	)
	(segment
		(start 436.884826 -30.550612)
		(end 436.086504 -30.550612)
		(width 0.254)
		(layer "F.Cu")
		(net "P12V_OCP_IMON_1")
	)
	(segment
		(start 440.853068 -30.19552)
		(end 440.853068 -29.575506)
		(width 0.254)
		(layer "F.Cu")
		(net "P12V_OCP_IMON_1")
	)
	(via
		(at 436.086504 -30.550612)
		(size 0.762)
		(drill 0.381)
		(layers "F.Cu" "B.Cu")
		(net "P12V_OCP_IMON_1")
	)
	(segment
		(start 80.356456 -22.44979)
		(end 80.513428 -22.606762)
		(width 0.10668)
		(layer "F.Cu")
		(net "P12V_OCP_GATE_2")
	)
	(segment
		(start 80.524096 -24.346408)
		(end 80.524096 -23.32863)
		(width 0.10668)
		(layer "F.Cu")
		(net "P12V_OCP_GATE_2")
	)
	(segment
		(start 80.524096 -23.32863)
		(end 80.513428 -23.317962)
		(width 0.10668)
		(layer "F.Cu")
		(net "P12V_OCP_GATE_2")
	)
	(segment
		(start 80.356456 -21.444204)
		(end 80.356456 -22.44979)
		(width 0.10668)
		(layer "F.Cu")
		(net "P12V_OCP_GATE_2")
	)
	(segment
		(start 80.525112 -25.358598)
		(end 80.525112 -24.347424)
		(width 0.10668)
		(layer "F.Cu")
		(net "P12V_OCP_GATE_2")
	)
	(segment
		(start 80.513428 -22.606762)
		(end 80.513428 -23.317962)
		(width 0.10668)
		(layer "F.Cu")
		(net "P12V_OCP_GATE_2")
	)
	(segment
		(start 80.525112 -24.347424)
		(end 80.524096 -24.346408)
		(width 0.10668)
		(layer "F.Cu")
		(net "P12V_OCP_GATE_2")
	)
	(via
		(at 80.513428 -22.606762)
		(size 0.508)
		(drill 0.254)
		(layers "F.Cu" "B.Cu")
		(net "P12V_OCP_GATE_2")
	)
	(segment
		(start 452.488554 -22.412452)
		(end 452.488554 -23.43785)
		(width 0.10668)
		(layer "F.Cu")
		(net "P12V_OCP_GATE_1")
	)
	(segment
		(start 452.643494 -25.638506)
		(end 452.643494 -24.630126)
		(width 0.10668)
		(layer "F.Cu")
		(net "P12V_OCP_GATE_1")
	)
	(segment
		(start 452.654162 -24.619458)
		(end 452.654162 -23.603458)
		(width 0.10668)
		(layer "F.Cu")
		(net "P12V_OCP_GATE_1")
	)
	(segment
		(start 452.643494 -24.630126)
		(end 452.654162 -24.619458)
		(width 0.10668)
		(layer "F.Cu")
		(net "P12V_OCP_GATE_1")
	)
	(segment
		(start 452.49719 -21.7297)
		(end 452.49719 -22.403816)
		(width 0.10668)
		(layer "F.Cu")
		(net "P12V_OCP_GATE_1")
	)
	(segment
		(start 452.488554 -23.43785)
		(end 452.654162 -23.603458)
		(width 0.10668)
		(layer "F.Cu")
		(net "P12V_OCP_GATE_1")
	)
	(segment
		(start 452.49719 -22.403816)
		(end 452.488554 -22.412452)
		(width 0.10668)
		(layer "F.Cu")
		(net "P12V_OCP_GATE_1")
	)
	(via
		(at 452.488554 -22.412452)
		(size 0.508)
		(drill 0.254)
		(layers "F.Cu" "B.Cu")
		(net "P12V_OCP_GATE_1")
	)
	(via
		(at 64.2112 -29.1592)
		(size 0.508)
		(drill 0.254)
		(layers "F.Cu" "B.Cu")
		(net "P12V_OCP_FLTB_2")
	)
	(via
		(at 439.177684 -30.017212)
		(size 0.508)
		(drill 0.254)
		(layers "F.Cu" "B.Cu")
		(net "P12V_OCP_FLTB_1")
	)
	(segment
		(start 82.706718 -21.416772)
		(end 82.009996 -21.416772)
		(width 0.10668)
		(layer "F.Cu")
		(net "P12V_OCP_FAULT_2")
	)
	(segment
		(start 82.009996 -21.416772)
		(end 82.009234 -21.417534)
		(width 0.10668)
		(layer "F.Cu")
		(net "P12V_OCP_FAULT_2")
	)
	(segment
		(start 80.856582 -20.444206)
		(end 81.035906 -20.444206)
		(width 0.10668)
		(layer "F.Cu")
		(net "P12V_OCP_FAULT_2")
	)
	(segment
		(start 81.035906 -20.444206)
		(end 82.009234 -21.417534)
		(width 0.10668)
		(layer "F.Cu")
		(net "P12V_OCP_FAULT_2")
	)
	(via
		(at 82.009234 -21.417534)
		(size 0.508)
		(drill 0.254)
		(layers "F.Cu" "B.Cu")
		(net "P12V_OCP_FAULT_2")
	)
	(segment
		(start 453.184514 -20.729702)
		(end 454.090024 -21.635212)
		(width 0.10668)
		(layer "F.Cu")
		(net "P12V_OCP_FAULT_1")
	)
	(segment
		(start 454.15708 -21.702268)
		(end 454.090024 -21.635212)
		(width 0.10668)
		(layer "F.Cu")
		(net "P12V_OCP_FAULT_1")
	)
	(segment
		(start 454.847452 -21.702268)
		(end 454.15708 -21.702268)
		(width 0.10668)
		(layer "F.Cu")
		(net "P12V_OCP_FAULT_1")
	)
	(segment
		(start 452.997316 -20.729702)
		(end 453.184514 -20.729702)
		(width 0.10668)
		(layer "F.Cu")
		(net "P12V_OCP_FAULT_1")
	)
	(via
		(at 454.090024 -21.635212)
		(size 0.508)
		(drill 0.254)
		(layers "F.Cu" "B.Cu")
		(net "P12V_OCP_FAULT_1")
	)
	(segment
		(start 67.825112 -34.874708)
		(end 66.882264 -34.874708)
		(width 0.10668)
		(layer "F.Cu")
		(net "P12V_OCP_EN_2_R")
	)
	(segment
		(start 65.464944 -37.308028)
		(end 65.972944 -36.800028)
		(width 0.10668)
		(layer "F.Cu")
		(net "P12V_OCP_EN_2_R")
	)
	(segment
		(start 64.752982 -37.307266)
		(end 64.753744 -37.308028)
		(width 0.10668)
		(layer "F.Cu")
		(net "P12V_OCP_EN_2_R")
	)
	(segment
		(start 63.42253 -37.307266)
		(end 64.752982 -37.307266)
		(width 0.10668)
		(layer "F.Cu")
		(net "P12V_OCP_EN_2_R")
	)
	(segment
		(start 64.753744 -37.308028)
		(end 65.464944 -37.308028)
		(width 0.10668)
		(layer "F.Cu")
		(net "P12V_OCP_EN_2_R")
	)
	(segment
		(start 65.972944 -36.800028)
		(end 65.972944 -35.784028)
		(width 0.10668)
		(layer "F.Cu")
		(net "P12V_OCP_EN_2_R")
	)
	(segment
		(start 66.882264 -34.874708)
		(end 65.972944 -35.784028)
		(width 0.10668)
		(layer "F.Cu")
		(net "P12V_OCP_EN_2_R")
	)
	(via
		(at 64.753744 -37.308028)
		(size 0.762)
		(drill 0.381)
		(layers "F.Cu" "B.Cu")
		(net "P12V_OCP_EN_2_R")
	)
	(segment
		(start 444.353188 -30.138116)
		(end 444.699644 -30.484572)
		(width 0.10668)
		(layer "F.Cu")
		(net "P12V_OCP_EN_1_R2")
	)
	(segment
		(start 446.359788 -31.774384)
		(end 446.358772 -31.773368)
		(width 0.10668)
		(layer "F.Cu")
		(net "P12V_OCP_EN_1_R2")
	)
	(segment
		(start 444.733172 -30.5181)
		(end 444.699644 -30.484572)
		(width 0.10668)
		(layer "F.Cu")
		(net "P12V_OCP_EN_1_R2")
	)
	(segment
		(start 444.733172 -31.773368)
		(end 444.733172 -30.5181)
		(width 0.10668)
		(layer "F.Cu")
		(net "P12V_OCP_EN_1_R2")
	)
	(segment
		(start 446.358772 -31.773368)
		(end 444.733172 -31.773368)
		(width 0.10668)
		(layer "F.Cu")
		(net "P12V_OCP_EN_1_R2")
	)
	(segment
		(start 444.353188 -29.55036)
		(end 444.353188 -30.138116)
		(width 0.10668)
		(layer "F.Cu")
		(net "P12V_OCP_EN_1_R2")
	)
	(via
		(at 444.699644 -30.484572)
		(size 0.508)
		(drill 0.254)
		(layers "F.Cu" "B.Cu")
		(net "P12V_OCP_EN_1_R2")
	)
	(segment
		(start 468.557864 -41.105836)
		(end 467.338664 -41.105836)
		(width 0.10668)
		(layer "F.Cu")
		(net "P12V_OCP_EN_1_R")
	)
	(segment
		(start 468.557864 -42.121836)
		(end 468.557864 -41.105836)
		(width 0.10668)
		(layer "F.Cu")
		(net "P12V_OCP_EN_1_R")
	)
	(segment
		(start 468.550244 -43.252898)
		(end 468.557864 -43.245278)
		(width 0.10668)
		(layer "F.Cu")
		(net "P12V_OCP_EN_1_R")
	)
	(segment
		(start 468.557864 -43.245278)
		(end 468.557864 -42.121836)
		(width 0.10668)
		(layer "F.Cu")
		(net "P12V_OCP_EN_1_R")
	)
	(segment
		(start 466.119464 -41.105836)
		(end 467.338664 -41.105836)
		(width 0.10668)
		(layer "F.Cu")
		(net "P12V_OCP_EN_1_R")
	)
	(via
		(at 467.338664 -41.105836)
		(size 0.762)
		(drill 0.381)
		(layers "F.Cu" "B.Cu")
		(net "P12V_OCP_EN_1_R")
	)
	(segment
		(start 181.122066 -113.05286)
		(end 180.732176 -112.66297)
		(width 0.10668)
		(layer "F.Cu")
		(net "P12V_OCP_SFF_EN")
	)
	(segment
		(start 167.53205 -110.200948)
		(end 168.148 -110.200948)
		(width 0.10668)
		(layer "F.Cu")
		(net "P12V_OCP_SFF_EN")
	)
	(via
		(at 180.732176 -112.66297)
		(size 0.4572)
		(drill 0.254)
		(layers "F.Cu" "B.Cu")
		(net "P12V_OCP_SFF_EN")
	)
	(via
		(at 168.148 -110.200948)
		(size 0.508)
		(drill 0.254)
		(layers "F.Cu" "B.Cu")
		(net "P12V_OCP_SFF_EN")
	)
	(segment
		(start 168.148 -110.200948)
		(end 168.615868 -110.668816)
		(width 0.11684)
		(layer "In2.Cu")
		(net "P12V_OCP_SFF_EN")
	)
	(segment
		(start 173.766988 -111.288576)
		(end 175.54956 -111.288576)
		(width 0.11684)
		(layer "In2.Cu")
		(net "P12V_OCP_SFF_EN")
	)
	(segment
		(start 180.132482 -112.271556)
		(end 180.523896 -112.66297)
		(width 0.11684)
		(layer "In2.Cu")
		(net "P12V_OCP_SFF_EN")
	)
	(segment
		(start 176.53254 -112.271556)
		(end 180.132482 -112.271556)
		(width 0.11684)
		(layer "In2.Cu")
		(net "P12V_OCP_SFF_EN")
	)
	(segment
		(start 173.147228 -110.668816)
		(end 173.766988 -111.288576)
		(width 0.11684)
		(layer "In2.Cu")
		(net "P12V_OCP_SFF_EN")
	)
	(segment
		(start 175.54956 -111.288576)
		(end 176.53254 -112.271556)
		(width 0.11684)
		(layer "In2.Cu")
		(net "P12V_OCP_SFF_EN")
	)
	(segment
		(start 168.615868 -110.668816)
		(end 173.147228 -110.668816)
		(width 0.11684)
		(layer "In2.Cu")
		(net "P12V_OCP_SFF_EN")
	)
	(segment
		(start 180.523896 -112.66297)
		(end 180.732176 -112.66297)
		(width 0.11684)
		(layer "In2.Cu")
		(net "P12V_OCP_SFF_EN")
	)
	(segment
		(start 76.65212 -21.0566)
		(end 76.546202 -20.950682)
		(width 0.10668)
		(layer "F.Cu")
		(net "P12V_OCP_CB_2")
	)
	(segment
		(start 76.546202 -20.950682)
		(end 75.946508 -20.950682)
		(width 0.10668)
		(layer "F.Cu")
		(net "P12V_OCP_CB_2")
	)
	(segment
		(start 77.856334 -20.944078)
		(end 76.764642 -20.944078)
		(width 0.10668)
		(layer "F.Cu")
		(net "P12V_OCP_CB_2")
	)
	(segment
		(start 76.764642 -20.944078)
		(end 76.65212 -21.0566)
		(width 0.10668)
		(layer "F.Cu")
		(net "P12V_OCP_CB_2")
	)
	(via
		(at 76.65212 -21.0566)
		(size 0.508)
		(drill 0.254)
		(layers "F.Cu" "B.Cu")
		(net "P12V_OCP_CB_2")
	)
	(segment
		(start 448.84086 -21.236178)
		(end 448.852544 -21.247862)
		(width 0.10668)
		(layer "F.Cu")
		(net "P12V_OCP_CB_1")
	)
	(segment
		(start 448.870832 -21.229574)
		(end 448.852544 -21.247862)
		(width 0.10668)
		(layer "F.Cu")
		(net "P12V_OCP_CB_1")
	)
	(segment
		(start 448.087242 -21.236178)
		(end 448.84086 -21.236178)
		(width 0.10668)
		(layer "F.Cu")
		(net "P12V_OCP_CB_1")
	)
	(segment
		(start 449.997068 -21.229574)
		(end 448.870832 -21.229574)
		(width 0.10668)
		(layer "F.Cu")
		(net "P12V_OCP_CB_1")
	)
	(via
		(at 448.852544 -21.247862)
		(size 0.508)
		(drill 0.254)
		(layers "F.Cu" "B.Cu")
		(net "P12V_OCP_CB_1")
	)
	(segment
		(start 65.461388 -22.235922)
		(end 64.329056 -22.235922)
		(width 0.10668)
		(layer "F.Cu")
		(net "P12V_OCP_AVIN_PD_2")
	)
	(segment
		(start 64.329056 -22.235922)
		(end 64.283844 -22.19071)
		(width 0.10668)
		(layer "F.Cu")
		(net "P12V_OCP_AVIN_PD_2")
	)
	(via
		(at 64.283844 -22.19071)
		(size 0.762)
		(drill 0.381)
		(layers "F.Cu" "B.Cu")
		(net "P12V_OCP_AVIN_PD_2")
	)
	(via
		(at 439.320686 -22.863556)
		(size 0.762)
		(drill 0.381)
		(layers "F.Cu" "B.Cu")
		(net "P12V_OCP_AVIN_PD_1")
	)
	(segment
		(start 61.52261 -36.65728)
		(end 62.174374 -36.65728)
		(width 0.10668)
		(layer "F.Cu")
		(net "P12V_OCP_2_EN_G")
	)
	(segment
		(start 62.247272 -36.730178)
		(end 62.247272 -37.12337)
		(width 0.10668)
		(layer "F.Cu")
		(net "P12V_OCP_2_EN_G")
	)
	(segment
		(start 62.247272 -37.12337)
		(end 62.063376 -37.307266)
		(width 0.10668)
		(layer "F.Cu")
		(net "P12V_OCP_2_EN_G")
	)
	(segment
		(start 61.52261 -37.307266)
		(end 60.188602 -37.307266)
		(width 0.10668)
		(layer "F.Cu")
		(net "P12V_OCP_2_EN_G")
	)
	(segment
		(start 62.063376 -37.307266)
		(end 61.52261 -37.307266)
		(width 0.10668)
		(layer "F.Cu")
		(net "P12V_OCP_2_EN_G")
	)
	(segment
		(start 60.188602 -37.307266)
		(end 60.176664 -37.295328)
		(width 0.10668)
		(layer "F.Cu")
		(net "P12V_OCP_2_EN_G")
	)
	(segment
		(start 59.46775 -36.083748)
		(end 59.46775 -36.586414)
		(width 0.10668)
		(layer "F.Cu")
		(net "P12V_OCP_2_EN_G")
	)
	(segment
		(start 62.174374 -36.65728)
		(end 62.247272 -36.730178)
		(width 0.10668)
		(layer "F.Cu")
		(net "P12V_OCP_2_EN_G")
	)
	(segment
		(start 59.46775 -36.586414)
		(end 60.176664 -37.295328)
		(width 0.10668)
		(layer "F.Cu")
		(net "P12V_OCP_2_EN_G")
	)
	(via
		(at 60.176664 -37.295328)
		(size 0.762)
		(drill 0.381)
		(layers "F.Cu" "B.Cu")
		(net "P12V_OCP_2_EN_G")
	)
	(segment
		(start 463.590132 -39.826438)
		(end 464.219544 -40.45585)
		(width 0.10668)
		(layer "F.Cu")
		(net "P12V_OCP_1_EN_G")
	)
	(segment
		(start 464.219544 -41.105836)
		(end 464.219544 -40.45585)
		(width 0.10668)
		(layer "F.Cu")
		(net "P12V_OCP_1_EN_G")
	)
	(segment
		(start 462.20507 -39.826438)
		(end 463.590132 -39.826438)
		(width 0.10668)
		(layer "F.Cu")
		(net "P12V_OCP_1_EN_G")
	)
	(segment
		(start 462.20507 -39.826438)
		(end 460.98587 -39.826438)
		(width 0.10668)
		(layer "F.Cu")
		(net "P12V_OCP_1_EN_G")
	)
	(via
		(at 460.98587 -39.826438)
		(size 0.762)
		(drill 0.381)
		(layers "F.Cu" "B.Cu")
		(net "P12V_OCP_1_EN_G")
	)
	(segment
		(start 255.025652 -43.502072)
		(end 255.447546 -43.502072)
		(width 0.10668)
		(layer "F.Cu")
		(net "P12V_E1S_VCC_0")
	)
	(segment
		(start 254.718058 -43.809666)
		(end 255.025652 -43.502072)
		(width 0.10668)
		(layer "F.Cu")
		(net "P12V_E1S_VCC_0")
	)
	(segment
		(start 253.963932 -43.05554)
		(end 254.718058 -43.809666)
		(width 0.10668)
		(layer "F.Cu")
		(net "P12V_E1S_VCC_0")
	)
	(segment
		(start 253.582932 -43.05554)
		(end 253.963932 -43.05554)
		(width 0.10668)
		(layer "F.Cu")
		(net "P12V_E1S_VCC_0")
	)
	(segment
		(start 256.489454 -43.504612)
		(end 255.450086 -43.504612)
		(width 0.10668)
		(layer "F.Cu")
		(net "P12V_E1S_VCC_0")
	)
	(segment
		(start 255.450086 -43.504612)
		(end 255.447546 -43.502072)
		(width 0.10668)
		(layer "F.Cu")
		(net "P12V_E1S_VCC_0")
	)
	(via
		(at 254.718058 -43.809666)
		(size 0.508)
		(drill 0.254)
		(layers "F.Cu" "B.Cu")
		(net "P12V_E1S_VCC_0")
	)
	(segment
		(start 252.858524 -60.11418)
		(end 253.3142 -59.658504)
		(width 0.10668)
		(layer "F.Cu")
		(net "P12V_E1S_UV_0_R")
	)
	(segment
		(start 252.985778 -65.588388)
		(end 252.858524 -65.461134)
		(width 0.10668)
		(layer "F.Cu")
		(net "P12V_E1S_UV_0_R")
	)
	(segment
		(start 252.858524 -65.461134)
		(end 252.858524 -60.11418)
		(width 0.10668)
		(layer "F.Cu")
		(net "P12V_E1S_UV_0_R")
	)
	(segment
		(start 253.413006 -65.588388)
		(end 252.985778 -65.588388)
		(width 0.10668)
		(layer "F.Cu")
		(net "P12V_E1S_UV_0_R")
	)
	(via
		(at 253.3142 -59.658504)
		(size 0.508)
		(drill 0.254)
		(layers "F.Cu" "B.Cu")
		(net "P12V_E1S_UV_0_R")
	)
	(segment
		(start 255.50368 -53.29936)
		(end 254.896874 -53.906166)
		(width 0.10668)
		(layer "B.Cu")
		(net "P12V_E1S_UV_0_R")
	)
	(segment
		(start 255.50368 -49.23282)
		(end 255.50368 -53.29936)
		(width 0.10668)
		(layer "B.Cu")
		(net "P12V_E1S_UV_0_R")
	)
	(segment
		(start 252.856746 -48.57242)
		(end 254.84328 -48.57242)
		(width 0.10668)
		(layer "B.Cu")
		(net "P12V_E1S_UV_0_R")
	)
	(segment
		(start 254.896874 -58.07583)
		(end 253.3142 -59.658504)
		(width 0.10668)
		(layer "B.Cu")
		(net "P12V_E1S_UV_0_R")
	)
	(segment
		(start 250.07697 -45.861732)
		(end 250.146058 -45.861732)
		(width 0.10668)
		(layer "B.Cu")
		(net "P12V_E1S_UV_0_R")
	)
	(segment
		(start 254.84328 -48.57242)
		(end 255.50368 -49.23282)
		(width 0.10668)
		(layer "B.Cu")
		(net "P12V_E1S_UV_0_R")
	)
	(segment
		(start 250.146058 -45.861732)
		(end 252.856746 -48.57242)
		(width 0.10668)
		(layer "B.Cu")
		(net "P12V_E1S_UV_0_R")
	)
	(segment
		(start 254.896874 -53.906166)
		(end 254.896874 -58.07583)
		(width 0.10668)
		(layer "B.Cu")
		(net "P12V_E1S_UV_0_R")
	)
	(segment
		(start 250.424188 -43.652694)
		(end 250.316746 -43.760136)
		(width 0.10668)
		(layer "F.Cu")
		(net "P12V_E1S_UV_0")
	)
	(segment
		(start 252.082808 -43.05554)
		(end 251.485654 -43.652694)
		(width 0.10668)
		(layer "F.Cu")
		(net "P12V_E1S_UV_0")
	)
	(segment
		(start 251.485654 -43.652694)
		(end 250.424188 -43.652694)
		(width 0.10668)
		(layer "F.Cu")
		(net "P12V_E1S_UV_0")
	)
	(segment
		(start 250.316746 -43.760136)
		(end 250.316746 -44.572682)
		(width 0.10668)
		(layer "F.Cu")
		(net "P12V_E1S_UV_0")
	)
	(segment
		(start 250.30303 -44.586398)
		(end 250.316746 -44.572682)
		(width 0.10668)
		(layer "F.Cu")
		(net "P12V_E1S_UV_0")
	)
	(segment
		(start 250.30303 -45.595032)
		(end 250.30303 -44.586398)
		(width 0.10668)
		(layer "F.Cu")
		(net "P12V_E1S_UV_0")
	)
	(via
		(at 250.424188 -43.652694)
		(size 0.508)
		(drill 0.254)
		(layers "F.Cu" "B.Cu")
		(net "P12V_E1S_UV_0")
	)
	(segment
		(start 250.07697 -44.652438)
		(end 250.424188 -44.30522)
		(width 0.10668)
		(layer "B.Cu")
		(net "P12V_E1S_UV_0")
	)
	(segment
		(start 250.424188 -44.30522)
		(end 250.424188 -43.652694)
		(width 0.10668)
		(layer "B.Cu")
		(net "P12V_E1S_UV_0")
	)
	(segment
		(start 250.07697 -45.061632)
		(end 250.07697 -44.652438)
		(width 0.10668)
		(layer "B.Cu")
		(net "P12V_E1S_UV_0")
	)
	(segment
		(start 256.729992 -50.320956)
		(end 256.386076 -50.664872)
		(width 0.10668)
		(layer "F.Cu")
		(net "P12V_E1S_TIMER_0")
	)
	(segment
		(start 256.386076 -50.668174)
		(end 256.1717 -50.88255)
		(width 0.10668)
		(layer "F.Cu")
		(net "P12V_E1S_TIMER_0")
	)
	(segment
		(start 256.1717 -50.88255)
		(end 255.261618 -50.88255)
		(width 0.10668)
		(layer "F.Cu")
		(net "P12V_E1S_TIMER_0")
	)
	(segment
		(start 256.991104 -50.320956)
		(end 257.215894 -50.545746)
		(width 0.10668)
		(layer "F.Cu")
		(net "P12V_E1S_TIMER_0")
	)
	(segment
		(start 256.386076 -50.664872)
		(end 256.386076 -50.668174)
		(width 0.10668)
		(layer "F.Cu")
		(net "P12V_E1S_TIMER_0")
	)
	(segment
		(start 256.82448 -50.320956)
		(end 256.729992 -50.320956)
		(width 0.10668)
		(layer "F.Cu")
		(net "P12V_E1S_TIMER_0")
	)
	(segment
		(start 257.215894 -50.545746)
		(end 257.46583 -50.545746)
		(width 0.10668)
		(layer "F.Cu")
		(net "P12V_E1S_TIMER_0")
	)
	(segment
		(start 256.82448 -50.320956)
		(end 256.991104 -50.320956)
		(width 0.10668)
		(layer "F.Cu")
		(net "P12V_E1S_TIMER_0")
	)
	(via
		(at 256.82448 -50.320956)
		(size 0.508)
		(drill 0.254)
		(layers "F.Cu" "B.Cu")
		(net "P12V_E1S_TIMER_0")
	)
	(segment
		(start 255.634998 -51.882294)
		(end 255.261618 -51.882294)
		(width 0.10668)
		(layer "F.Cu")
		(net "P12V_E1S_SS_0")
	)
	(segment
		(start 257.45948 -52.685442)
		(end 256.873248 -52.685442)
		(width 0.10668)
		(layer "F.Cu")
		(net "P12V_E1S_SS_0")
	)
	(segment
		(start 256.500122 -52.747418)
		(end 255.634998 -51.882294)
		(width 0.10668)
		(layer "F.Cu")
		(net "P12V_E1S_SS_0")
	)
	(segment
		(start 256.873248 -52.685442)
		(end 256.811272 -52.747418)
		(width 0.10668)
		(layer "F.Cu")
		(net "P12V_E1S_SS_0")
	)
	(segment
		(start 256.811272 -52.747418)
		(end 256.500122 -52.747418)
		(width 0.10668)
		(layer "F.Cu")
		(net "P12V_E1S_SS_0")
	)
	(via
		(at 256.811272 -52.747418)
		(size 0.508)
		(drill 0.254)
		(layers "F.Cu" "B.Cu")
		(net "P12V_E1S_SS_0")
	)
	(segment
		(start 258.25958 -58.527442)
		(end 258.960874 -58.527442)
		(width 0.10668)
		(layer "F.Cu")
		(net "P12V_E1S_SENSE_0")
	)
	(segment
		(start 253.97841 -43.951144)
		(end 253.582932 -43.555666)
		(width 0.10668)
		(layer "F.Cu")
		(net "P12V_E1S_SENSE_0")
	)
	(segment
		(start 253.97841 -45.465492)
		(end 254.691388 -45.465492)
		(width 0.10668)
		(layer "F.Cu")
		(net "P12V_E1S_SENSE_0")
	)
	(segment
		(start 253.97841 -45.465492)
		(end 253.97841 -43.951144)
		(width 0.10668)
		(layer "F.Cu")
		(net "P12V_E1S_SENSE_0")
	)
	(segment
		(start 254.691388 -45.465492)
		(end 254.741934 -45.414946)
		(width 0.10668)
		(layer "F.Cu")
		(net "P12V_E1S_SENSE_0")
	)
	(via
		(at 254.741934 -45.414946)
		(size 0.508)
		(drill 0.254)
		(layers "F.Cu" "B.Cu")
		(net "P12V_E1S_SENSE_0")
	)
	(via
		(at 258.960874 -58.527442)
		(size 0.508)
		(drill 0.254)
		(layers "F.Cu" "B.Cu")
		(net "P12V_E1S_SENSE_0")
	)
	(segment
		(start 258.68376 -49.10074)
		(end 257.937 -49.8475)
		(width 0.11684)
		(layer "In11.Cu")
		(net "P12V_E1S_SENSE_0")
	)
	(segment
		(start 256.286 -45.943012)
		(end 256.286 -46.43882)
		(width 0.11684)
		(layer "In11.Cu")
		(net "P12V_E1S_SENSE_0")
	)
	(segment
		(start 256.286 -46.43882)
		(end 256.667 -46.81982)
		(width 0.11684)
		(layer "In11.Cu")
		(net "P12V_E1S_SENSE_0")
	)
	(segment
		(start 255.757934 -45.414946)
		(end 256.286 -45.943012)
		(width 0.11684)
		(layer "In11.Cu")
		(net "P12V_E1S_SENSE_0")
	)
	(segment
		(start 254.741934 -45.414946)
		(end 255.757934 -45.414946)
		(width 0.11684)
		(layer "In11.Cu")
		(net "P12V_E1S_SENSE_0")
	)
	(segment
		(start 256.667 -46.81982)
		(end 259.16382 -46.81982)
		(width 0.11684)
		(layer "In11.Cu")
		(net "P12V_E1S_SENSE_0")
	)
	(segment
		(start 259.16382 -46.81982)
		(end 259.54736 -47.20336)
		(width 0.11684)
		(layer "In11.Cu")
		(net "P12V_E1S_SENSE_0")
	)
	(segment
		(start 258.76758 -49.10074)
		(end 258.68376 -49.10074)
		(width 0.11684)
		(layer "In11.Cu")
		(net "P12V_E1S_SENSE_0")
	)
	(segment
		(start 257.937 -57.503568)
		(end 258.960874 -58.527442)
		(width 0.11684)
		(layer "In11.Cu")
		(net "P12V_E1S_SENSE_0")
	)
	(segment
		(start 257.937 -49.8475)
		(end 257.937 -57.503568)
		(width 0.11684)
		(layer "In11.Cu")
		(net "P12V_E1S_SENSE_0")
	)
	(segment
		(start 259.54736 -47.20336)
		(end 259.54736 -48.32096)
		(width 0.11684)
		(layer "In11.Cu")
		(net "P12V_E1S_SENSE_0")
	)
	(segment
		(start 259.54736 -48.32096)
		(end 258.76758 -49.10074)
		(width 0.11684)
		(layer "In11.Cu")
		(net "P12V_E1S_SENSE_0")
	)
	(segment
		(start 252.082808 -43.555666)
		(end 251.35967 -44.278804)
		(width 0.10668)
		(layer "F.Cu")
		(net "P12V_E1S_REG_0")
	)
	(segment
		(start 251.35967 -44.5516)
		(end 251.35967 -45.587412)
		(width 0.10668)
		(layer "F.Cu")
		(net "P12V_E1S_REG_0")
	)
	(segment
		(start 251.35967 -44.278804)
		(end 251.35967 -44.5516)
		(width 0.10668)
		(layer "F.Cu")
		(net "P12V_E1S_REG_0")
	)
	(via
		(at 251.35967 -44.5516)
		(size 0.508)
		(drill 0.254)
		(layers "F.Cu" "B.Cu")
		(net "P12V_E1S_REG_0")
	)
	(segment
		(start 250.317 -39.944548)
		(end 250.557538 -40.185086)
		(width 0.10668)
		(layer "F.Cu")
		(net "P12V_E1S_PWRGD_0")
	)
	(segment
		(start 250.557538 -40.185086)
		(end 251.712476 -40.185086)
		(width 0.10668)
		(layer "F.Cu")
		(net "P12V_E1S_PWRGD_0")
	)
	(segment
		(start 250.317 -39.464996)
		(end 250.317 -39.944548)
		(width 0.10668)
		(layer "F.Cu")
		(net "P12V_E1S_PWRGD_0")
	)
	(segment
		(start 251.712476 -40.185086)
		(end 252.082808 -40.555418)
		(width 0.10668)
		(layer "F.Cu")
		(net "P12V_E1S_PWRGD_0")
	)
	(via
		(at 250.557538 -40.185086)
		(size 0.508)
		(drill 0.254)
		(layers "F.Cu" "B.Cu")
		(net "P12V_E1S_PWRGD_0")
	)
	(segment
		(start 253.361698 -56.193182)
		(end 253.361698 -57.209182)
		(width 0.10668)
		(layer "F.Cu")
		(net "P12V_E1S_OV_FB_0")
	)
	(segment
		(start 253.361698 -57.209182)
		(end 253.361698 -58.418222)
		(width 0.10668)
		(layer "F.Cu")
		(net "P12V_E1S_OV_FB_0")
	)
	(segment
		(start 253.361698 -53.782468)
		(end 253.361698 -55.177182)
		(width 0.10668)
		(layer "F.Cu")
		(net "P12V_E1S_OV_FB_0")
	)
	(segment
		(start 253.361698 -58.418222)
		(end 253.355094 -58.424826)
		(width 0.10668)
		(layer "F.Cu")
		(net "P12V_E1S_OV_FB_0")
	)
	(segment
		(start 253.361698 -55.177182)
		(end 253.361698 -56.193182)
		(width 0.10668)
		(layer "F.Cu")
		(net "P12V_E1S_OV_FB_0")
	)
	(via
		(at 253.355094 -58.424826)
		(size 0.762)
		(drill 0.381)
		(layers "F.Cu" "B.Cu")
		(net "P12V_E1S_OV_FB_0")
	)
	(segment
		(start 250.806458 -42.555414)
		(end 249.378724 -43.983148)
		(width 0.10668)
		(layer "F.Cu")
		(net "P12V_E1S_OV_0")
	)
	(segment
		(start 252.082808 -42.555414)
		(end 251.142754 -42.555414)
		(width 0.10668)
		(layer "F.Cu")
		(net "P12V_E1S_OV_0")
	)
	(segment
		(start 249.28703 -44.802298)
		(end 249.516646 -44.572682)
		(width 0.10668)
		(layer "F.Cu")
		(net "P12V_E1S_OV_0")
	)
	(segment
		(start 249.28703 -45.595032)
		(end 249.28703 -44.802298)
		(width 0.10668)
		(layer "F.Cu")
		(net "P12V_E1S_OV_0")
	)
	(segment
		(start 249.378724 -44.43476)
		(end 249.516646 -44.572682)
		(width 0.10668)
		(layer "F.Cu")
		(net "P12V_E1S_OV_0")
	)
	(segment
		(start 249.378724 -43.983148)
		(end 249.378724 -44.43476)
		(width 0.10668)
		(layer "F.Cu")
		(net "P12V_E1S_OV_0")
	)
	(segment
		(start 251.142754 -42.555414)
		(end 250.806458 -42.555414)
		(width 0.10668)
		(layer "F.Cu")
		(net "P12V_E1S_OV_0")
	)
	(via
		(at 251.142754 -42.555414)
		(size 0.508)
		(drill 0.254)
		(layers "F.Cu" "B.Cu")
		(net "P12V_E1S_OV_0")
	)
	(via
		(at 258.409694 -51.589686)
		(size 0.6604)
		(drill 0.3302)
		(layers "F.Cu" "B.Cu")
		(net "P12V_E1S_ISET_0_R")
	)
	(segment
		(start 258.208018 -51.791362)
		(end 258.409694 -51.589686)
		(width 0.10668)
		(layer "B.Cu")
		(net "P12V_E1S_ISET_0_R")
	)
	(segment
		(start 258.208018 -52.718462)
		(end 258.208018 -51.791362)
		(width 0.10668)
		(layer "B.Cu")
		(net "P12V_E1S_ISET_0_R")
	)
	(segment
		(start 258.409694 -51.589686)
		(end 259.185918 -50.813462)
		(width 0.10668)
		(layer "B.Cu")
		(net "P12V_E1S_ISET_0_R")
	)
	(segment
		(start 259.185918 -50.813462)
		(end 259.565394 -50.813462)
		(width 0.10668)
		(layer "B.Cu")
		(net "P12V_E1S_ISET_0_R")
	)
	(segment
		(start 257.44043 -51.587146)
		(end 257.104642 -51.587146)
		(width 0.10668)
		(layer "F.Cu")
		(net "P12V_E1S_ISET_0")
	)
	(segment
		(start 257.104642 -51.587146)
		(end 256.996438 -51.69535)
		(width 0.10668)
		(layer "F.Cu")
		(net "P12V_E1S_ISET_0")
	)
	(segment
		(start 256.062734 -51.69535)
		(end 255.749806 -51.382422)
		(width 0.10668)
		(layer "F.Cu")
		(net "P12V_E1S_ISET_0")
	)
	(segment
		(start 255.749806 -51.382422)
		(end 255.261618 -51.382422)
		(width 0.10668)
		(layer "F.Cu")
		(net "P12V_E1S_ISET_0")
	)
	(segment
		(start 256.996438 -51.69535)
		(end 256.062734 -51.69535)
		(width 0.10668)
		(layer "F.Cu")
		(net "P12V_E1S_ISET_0")
	)
	(via
		(at 256.062734 -51.69535)
		(size 0.508)
		(drill 0.254)
		(layers "F.Cu" "B.Cu")
		(net "P12V_E1S_ISET_0")
	)
	(segment
		(start 257.897376 -53.462428)
		(end 257.95351 -53.518562)
		(width 0.10668)
		(layer "B.Cu")
		(net "P12V_E1S_ISET_0")
	)
	(segment
		(start 256.79908 -53.462428)
		(end 257.897376 -53.462428)
		(width 0.10668)
		(layer "B.Cu")
		(net "P12V_E1S_ISET_0")
	)
	(segment
		(start 256.062734 -51.69535)
		(end 256.062734 -52.726082)
		(width 0.10668)
		(layer "B.Cu")
		(net "P12V_E1S_ISET_0")
	)
	(segment
		(start 257.95351 -53.518562)
		(end 258.208018 -53.518562)
		(width 0.10668)
		(layer "B.Cu")
		(net "P12V_E1S_ISET_0")
	)
	(segment
		(start 256.062734 -52.726082)
		(end 256.79908 -53.462428)
		(width 0.10668)
		(layer "B.Cu")
		(net "P12V_E1S_ISET_0")
	)
	(segment
		(start 256.546096 -54.281832)
		(end 256.770886 -54.281832)
		(width 0.254)
		(layer "F.Cu")
		(net "P12V_E1S_IMON_0")
	)
	(segment
		(start 256.224786 -53.452522)
		(end 256.224786 -53.960522)
		(width 0.254)
		(layer "F.Cu")
		(net "P12V_E1S_IMON_0")
	)
	(segment
		(start 256.952496 -54.463442)
		(end 257.45948 -54.463442)
		(width 0.254)
		(layer "F.Cu")
		(net "P12V_E1S_IMON_0")
	)
	(segment
		(start 256.224786 -53.960522)
		(end 256.546096 -54.281832)
		(width 0.254)
		(layer "F.Cu")
		(net "P12V_E1S_IMON_0")
	)
	(segment
		(start 255.261618 -52.882546)
		(end 255.65481 -52.882546)
		(width 0.254)
		(layer "F.Cu")
		(net "P12V_E1S_IMON_0")
	)
	(segment
		(start 256.770886 -54.281832)
		(end 256.952496 -54.463442)
		(width 0.254)
		(layer "F.Cu")
		(net "P12V_E1S_IMON_0")
	)
	(segment
		(start 255.65481 -52.882546)
		(end 256.224786 -53.452522)
		(width 0.254)
		(layer "F.Cu")
		(net "P12V_E1S_IMON_0")
	)
	(segment
		(start 257.45948 -56.495442)
		(end 257.45948 -57.511442)
		(width 0.254)
		(layer "F.Cu")
		(net "P12V_E1S_IMON_0")
	)
	(segment
		(start 257.45948 -55.479442)
		(end 257.45948 -56.495442)
		(width 0.254)
		(layer "F.Cu")
		(net "P12V_E1S_IMON_0")
	)
	(segment
		(start 257.45948 -54.463442)
		(end 257.45948 -55.479442)
		(width 0.254)
		(layer "F.Cu")
		(net "P12V_E1S_IMON_0")
	)
	(via
		(at 256.770886 -54.281832)
		(size 0.508)
		(drill 0.254)
		(layers "F.Cu" "B.Cu")
		(net "P12V_E1S_IMON_0")
	)
	(segment
		(start 255.45669 -40.898572)
		(end 256.47269 -40.898572)
		(width 0.10668)
		(layer "F.Cu")
		(net "P12V_E1S_GATE_0")
	)
	(segment
		(start 257.53949 -40.898572)
		(end 257.66649 -40.771572)
		(width 0.10668)
		(layer "F.Cu")
		(net "P12V_E1S_GATE_0")
	)
	(segment
		(start 255.299718 -41.055544)
		(end 255.45669 -40.898572)
		(width 0.10668)
		(layer "F.Cu")
		(net "P12V_E1S_GATE_0")
	)
	(segment
		(start 256.47269 -40.898572)
		(end 257.53949 -40.898572)
		(width 0.10668)
		(layer "F.Cu")
		(net "P12V_E1S_GATE_0")
	)
	(segment
		(start 257.27279 -39.082472)
		(end 257.66649 -39.476172)
		(width 0.10668)
		(layer "F.Cu")
		(net "P12V_E1S_GATE_0")
	)
	(segment
		(start 257.66649 -39.476172)
		(end 257.66649 -40.771572)
		(width 0.10668)
		(layer "F.Cu")
		(net "P12V_E1S_GATE_0")
	)
	(segment
		(start 253.582932 -41.055544)
		(end 255.299718 -41.055544)
		(width 0.10668)
		(layer "F.Cu")
		(net "P12V_E1S_GATE_0")
	)
	(via
		(at 257.66649 -40.771572)
		(size 0.762)
		(drill 0.381)
		(layers "F.Cu" "B.Cu")
		(net "P12V_E1S_GATE_0")
	)
	(via
		(at 255.432814 -54.602126)
		(size 0.508)
		(drill 0.254)
		(layers "F.Cu" "B.Cu")
		(net "P12V_E1S_FLTB_0")
	)
	(segment
		(start 252.89383 -40.053006)
		(end 252.775974 -40.053006)
		(width 0.10668)
		(layer "F.Cu")
		(net "P12V_E1S_FAULT_0")
	)
	(segment
		(start 253.21768 -39.729156)
		(end 252.89383 -40.053006)
		(width 0.10668)
		(layer "F.Cu")
		(net "P12V_E1S_FAULT_0")
	)
	(segment
		(start 253.59995 -38.683946)
		(end 253.21768 -39.066216)
		(width 0.10668)
		(layer "F.Cu")
		(net "P12V_E1S_FAULT_0")
	)
	(segment
		(start 253.21768 -39.066216)
		(end 253.21768 -39.729156)
		(width 0.10668)
		(layer "F.Cu")
		(net "P12V_E1S_FAULT_0")
	)
	(segment
		(start 252.582934 -40.246046)
		(end 252.775974 -40.053006)
		(width 0.10668)
		(layer "F.Cu")
		(net "P12V_E1S_FAULT_0")
	)
	(segment
		(start 252.582934 -40.555418)
		(end 252.582934 -40.246046)
		(width 0.10668)
		(layer "F.Cu")
		(net "P12V_E1S_FAULT_0")
	)
	(via
		(at 252.775974 -40.053006)
		(size 0.508)
		(drill 0.254)
		(layers "F.Cu" "B.Cu")
		(net "P12V_E1S_FAULT_0")
	)
	(segment
		(start 255.81102 -49.382426)
		(end 256.17297 -49.020476)
		(width 0.10668)
		(layer "F.Cu")
		(net "P12V_E1S_EN_0_R2")
	)
	(segment
		(start 255.236472 -49.382426)
		(end 255.81102 -49.382426)
		(width 0.10668)
		(layer "F.Cu")
		(net "P12V_E1S_EN_0_R2")
	)
	(segment
		(start 256.17297 -49.020476)
		(end 256.265172 -49.020476)
		(width 0.10668)
		(layer "F.Cu")
		(net "P12V_E1S_EN_0_R2")
	)
	(segment
		(start 257.10896 -49.020476)
		(end 257.49123 -49.402746)
		(width 0.10668)
		(layer "F.Cu")
		(net "P12V_E1S_EN_0_R2")
	)
	(segment
		(start 256.265172 -49.020476)
		(end 257.10896 -49.020476)
		(width 0.10668)
		(layer "F.Cu")
		(net "P12V_E1S_EN_0_R2")
	)
	(via
		(at 256.265172 -49.020476)
		(size 0.508)
		(drill 0.254)
		(layers "F.Cu" "B.Cu")
		(net "P12V_E1S_EN_0_R2")
	)
	(segment
		(start 252.17882 -66.238374)
		(end 250.95962 -66.238374)
		(width 0.10668)
		(layer "F.Cu")
		(net "P12V_E1S_EN_0_R")
	)
	(segment
		(start 253.413006 -66.238374)
		(end 252.17882 -66.238374)
		(width 0.10668)
		(layer "F.Cu")
		(net "P12V_E1S_EN_0_R")
	)
	(segment
		(start 250.95962 -66.238374)
		(end 250.95962 -67.254374)
		(width 0.10668)
		(layer "F.Cu")
		(net "P12V_E1S_EN_0_R")
	)
	(via
		(at 252.17882 -66.238374)
		(size 0.762)
		(drill 0.381)
		(layers "F.Cu" "B.Cu")
		(net "P12V_E1S_EN_0_R")
	)
	(segment
		(start 253.082806 -43.555666)
		(end 253.082806 -44.844208)
		(width 0.10668)
		(layer "F.Cu")
		(net "P12V_E1S_CB_0")
	)
	(segment
		(start 253.082806 -44.844208)
		(end 253.089664 -44.851066)
		(width 0.10668)
		(layer "F.Cu")
		(net "P12V_E1S_CB_0")
	)
	(segment
		(start 253.08941 -44.85132)
		(end 253.089664 -44.851066)
		(width 0.10668)
		(layer "F.Cu")
		(net "P12V_E1S_CB_0")
	)
	(segment
		(start 253.08941 -45.465492)
		(end 253.08941 -44.85132)
		(width 0.10668)
		(layer "F.Cu")
		(net "P12V_E1S_CB_0")
	)
	(via
		(at 253.089664 -44.851066)
		(size 0.508)
		(drill 0.254)
		(layers "F.Cu" "B.Cu")
		(net "P12V_E1S_CB_0")
	)
	(segment
		(start 248.176034 -53.625242)
		(end 248.176034 -54.790086)
		(width 0.10668)
		(layer "F.Cu")
		(net "P12V_E1S_AVIN_PD_0")
	)
	(segment
		(start 248.207784 -53.593492)
		(end 248.176034 -53.625242)
		(width 0.10668)
		(layer "F.Cu")
		(net "P12V_E1S_AVIN_PD_0")
	)
	(via
		(at 248.176034 -54.790086)
		(size 0.762)
		(drill 0.381)
		(layers "F.Cu" "B.Cu")
		(net "P12V_E1S_AVIN_PD_0")
	)
	(segment
		(start 196.073014 -114.648996)
		(end 195.79082 -114.366802)
		(width 0.10668)
		(layer "F.Cu")
		(net "P12V_E1S_0_EN")
	)
	(segment
		(start 195.66382 -114.250216)
		(end 193.524632 -114.250216)
		(width 0.10668)
		(layer "F.Cu")
		(net "P12V_E1S_0_EN")
	)
	(segment
		(start 196.30009 -114.689128)
		(end 196.259958 -114.648996)
		(width 0.10668)
		(layer "F.Cu")
		(net "P12V_E1S_0_EN")
	)
	(segment
		(start 196.259958 -114.648996)
		(end 196.073014 -114.648996)
		(width 0.10668)
		(layer "F.Cu")
		(net "P12V_E1S_0_EN")
	)
	(segment
		(start 196.479922 -114.689128)
		(end 196.30009 -114.689128)
		(width 0.10668)
		(layer "F.Cu")
		(net "P12V_E1S_0_EN")
	)
	(segment
		(start 193.524632 -114.250216)
		(end 193.122042 -114.652806)
		(width 0.10668)
		(layer "F.Cu")
		(net "P12V_E1S_0_EN")
	)
	(segment
		(start 196.869558 -114.641376)
		(end 196.527674 -114.641376)
		(width 0.10668)
		(layer "F.Cu")
		(net "P12V_E1S_0_EN")
	)
	(segment
		(start 195.79082 -114.366802)
		(end 195.780406 -114.366802)
		(width 0.10668)
		(layer "F.Cu")
		(net "P12V_E1S_0_EN")
	)
	(segment
		(start 195.780406 -114.366802)
		(end 195.66382 -114.250216)
		(width 0.10668)
		(layer "F.Cu")
		(net "P12V_E1S_0_EN")
	)
	(segment
		(start 196.527674 -114.641376)
		(end 196.479922 -114.689128)
		(width 0.10668)
		(layer "F.Cu")
		(net "P12V_E1S_0_EN")
	)
	(via
		(at 196.259958 -114.648996)
		(size 0.508)
		(drill 0.254)
		(layers "F.Cu" "B.Cu")
		(net "P12V_E1S_0_EN")
	)
	(segment
		(start 258.25958 -56.495442)
		(end 258.916424 -56.495442)
		(width 0.254)
		(layer "F.Cu")
		(net "P12V_E1S_0_ISENSE_MPS_TIC")
	)
	(via
		(at 258.916424 -56.495442)
		(size 0.508)
		(drill 0.254)
		(layers "F.Cu" "B.Cu")
		(net "P12V_E1S_0_ISENSE_MPS_TIC")
	)
	(segment
		(start 255.678178 -58.92292)
		(end 255.678178 -58.306462)
		(width 0.254)
		(layer "B.Cu")
		(net "P12V_E1S_0_ISENSE_MPS_TIC")
	)
	(segment
		(start 255.678178 -58.306462)
		(end 257.489198 -56.495442)
		(width 0.254)
		(layer "B.Cu")
		(net "P12V_E1S_0_ISENSE_MPS_TIC")
	)
	(segment
		(start 293.185088 -39.326312)
		(end 272.428716 -60.082684)
		(width 0.254)
		(layer "B.Cu")
		(net "P12V_E1S_0_ISENSE_MPS_TIC")
	)
	(segment
		(start 268.965172 -60.960508)
		(end 257.715766 -60.960508)
		(width 0.254)
		(layer "B.Cu")
		(net "P12V_E1S_0_ISENSE_MPS_TIC")
	)
	(segment
		(start 272.428716 -60.082684)
		(end 269.842996 -60.082684)
		(width 0.254)
		(layer "B.Cu")
		(net "P12V_E1S_0_ISENSE_MPS_TIC")
	)
	(segment
		(start 269.842996 -60.082684)
		(end 268.965172 -60.960508)
		(width 0.254)
		(layer "B.Cu")
		(net "P12V_E1S_0_ISENSE_MPS_TIC")
	)
	(segment
		(start 307.173884 -41.53789)
		(end 304.962306 -39.326312)
		(width 0.254)
		(layer "B.Cu")
		(net "P12V_E1S_0_ISENSE_MPS_TIC")
	)
	(segment
		(start 257.715766 -60.960508)
		(end 255.678178 -58.92292)
		(width 0.254)
		(layer "B.Cu")
		(net "P12V_E1S_0_ISENSE_MPS_TIC")
	)
	(segment
		(start 315.585094 -41.53789)
		(end 307.173884 -41.53789)
		(width 0.254)
		(layer "B.Cu")
		(net "P12V_E1S_0_ISENSE_MPS_TIC")
	)
	(segment
		(start 257.489198 -56.495442)
		(end 258.916424 -56.495442)
		(width 0.254)
		(layer "B.Cu")
		(net "P12V_E1S_0_ISENSE_MPS_TIC")
	)
	(segment
		(start 304.962306 -39.326312)
		(end 293.185088 -39.326312)
		(width 0.254)
		(layer "B.Cu")
		(net "P12V_E1S_0_ISENSE_MPS_TIC")
	)
	(segment
		(start 258.25958 -57.511442)
		(end 259.44576 -57.511442)
		(width 0.254)
		(layer "F.Cu")
		(net "P12V_E1S_0_ISENSE_MPS_MAM")
	)
	(via
		(at 259.44576 -57.511442)
		(size 0.762)
		(drill 0.254)
		(layers "F.Cu" "B.Cu")
		(net "P12V_E1S_0_ISENSE_MPS_MAM")
	)
	(segment
		(start 260.129274 -58.194956)
		(end 259.44576 -57.511442)
		(width 0.254)
		(layer "B.Cu")
		(net "P12V_E1S_0_ISENSE_MPS_MAM")
	)
	(segment
		(start 292.402768 -37.438584)
		(end 271.646396 -58.194956)
		(width 0.254)
		(layer "B.Cu")
		(net "P12V_E1S_0_ISENSE_MPS_MAM")
	)
	(segment
		(start 325.635112 -33.451292)
		(end 324.668642 -33.451292)
		(width 0.254)
		(layer "B.Cu")
		(net "P12V_E1S_0_ISENSE_MPS_MAM")
	)
	(segment
		(start 320.68135 -37.438584)
		(end 292.402768 -37.438584)
		(width 0.254)
		(layer "B.Cu")
		(net "P12V_E1S_0_ISENSE_MPS_MAM")
	)
	(segment
		(start 271.646396 -58.194956)
		(end 260.129274 -58.194956)
		(width 0.254)
		(layer "B.Cu")
		(net "P12V_E1S_0_ISENSE_MPS_MAM")
	)
	(segment
		(start 324.668642 -33.451292)
		(end 320.68135 -37.438584)
		(width 0.254)
		(layer "B.Cu")
		(net "P12V_E1S_0_ISENSE_MPS_MAM")
	)
	(segment
		(start 257.009138 -59.327542)
		(end 256.977134 -59.359546)
		(width 0.254)
		(layer "F.Cu")
		(net "P12V_E1S_0_ISENSE_MAM_TIC")
	)
	(segment
		(start 258.25958 -59.327542)
		(end 257.009138 -59.327542)
		(width 0.254)
		(layer "F.Cu")
		(net "P12V_E1S_0_ISENSE_MAM_TIC")
	)
	(via
		(at 256.977134 -59.359546)
		(size 0.508)
		(drill 0.254)
		(layers "F.Cu" "B.Cu")
		(net "P12V_E1S_0_ISENSE_MAM_TIC")
	)
	(segment
		(start 292.973506 -38.815772)
		(end 272.217134 -59.572144)
		(width 0.254)
		(layer "B.Cu")
		(net "P12V_E1S_0_ISENSE_MAM_TIC")
	)
	(segment
		(start 306.32019 -38.815772)
		(end 292.973506 -38.815772)
		(width 0.254)
		(layer "B.Cu")
		(net "P12V_E1S_0_ISENSE_MAM_TIC")
	)
	(segment
		(start 272.217134 -59.572144)
		(end 257.189732 -59.572144)
		(width 0.254)
		(layer "B.Cu")
		(net "P12V_E1S_0_ISENSE_MAM_TIC")
	)
	(segment
		(start 315.585094 -39.93769)
		(end 307.442108 -39.93769)
		(width 0.254)
		(layer "B.Cu")
		(net "P12V_E1S_0_ISENSE_MAM_TIC")
	)
	(segment
		(start 307.442108 -39.93769)
		(end 306.32019 -38.815772)
		(width 0.254)
		(layer "B.Cu")
		(net "P12V_E1S_0_ISENSE_MAM_TIC")
	)
	(segment
		(start 257.189732 -59.572144)
		(end 256.977134 -59.359546)
		(width 0.254)
		(layer "B.Cu")
		(net "P12V_E1S_0_ISENSE_MAM_TIC")
	)
	(segment
		(start 257.45948 -58.527442)
		(end 256.211578 -58.527442)
		(width 0.254)
		(layer "F.Cu")
		(net "P12V_E1S_0_ISENSE_MAM_MAM")
	)
	(via
		(at 256.211578 -58.527442)
		(size 0.762)
		(drill 0.254)
		(layers "F.Cu" "B.Cu")
		(net "P12V_E1S_0_ISENSE_MAM_MAM")
	)
	(segment
		(start 292.69817 -38.151308)
		(end 271.941798 -58.90768)
		(width 0.254)
		(layer "B.Cu")
		(net "P12V_E1S_0_ISENSE_MAM_MAM")
	)
	(segment
		(start 269.842996 -58.90768)
		(end 269.689834 -59.060842)
		(width 0.254)
		(layer "B.Cu")
		(net "P12V_E1S_0_ISENSE_MAM_MAM")
	)
	(segment
		(start 257.678682 -59.060842)
		(end 257.145282 -58.527442)
		(width 0.254)
		(layer "B.Cu")
		(net "P12V_E1S_0_ISENSE_MAM_MAM")
	)
	(segment
		(start 322.535296 -38.151308)
		(end 292.69817 -38.151308)
		(width 0.254)
		(layer "B.Cu")
		(net "P12V_E1S_0_ISENSE_MAM_MAM")
	)
	(segment
		(start 271.941798 -58.90768)
		(end 269.842996 -58.90768)
		(width 0.254)
		(layer "B.Cu")
		(net "P12V_E1S_0_ISENSE_MAM_MAM")
	)
	(segment
		(start 257.145282 -58.527442)
		(end 256.211578 -58.527442)
		(width 0.254)
		(layer "B.Cu")
		(net "P12V_E1S_0_ISENSE_MAM_MAM")
	)
	(segment
		(start 269.689834 -59.060842)
		(end 257.678682 -59.060842)
		(width 0.254)
		(layer "B.Cu")
		(net "P12V_E1S_0_ISENSE_MAM_MAM")
	)
	(segment
		(start 325.635112 -35.051492)
		(end 322.535296 -38.151308)
		(width 0.254)
		(layer "B.Cu")
		(net "P12V_E1S_0_ISENSE_MAM_MAM")
	)
	(segment
		(start 254.889 -66.88836)
		(end 254.726948 -66.726308)
		(width 0.10668)
		(layer "F.Cu")
		(net "P12V_E1S_0_EN_G")
	)
	(segment
		(start 256.928112 -67.26936)
		(end 257.766312 -67.26936)
		(width 0.10668)
		(layer "F.Cu")
		(net "P12V_E1S_0_EN_G")
	)
	(segment
		(start 255.312926 -66.88836)
		(end 256.547112 -66.88836)
		(width 0.10668)
		(layer "F.Cu")
		(net "P12V_E1S_0_EN_G")
	)
	(segment
		(start 254.726948 -66.365374)
		(end 254.853948 -66.238374)
		(width 0.10668)
		(layer "F.Cu")
		(net "P12V_E1S_0_EN_G")
	)
	(segment
		(start 255.312926 -66.88836)
		(end 254.889 -66.88836)
		(width 0.10668)
		(layer "F.Cu")
		(net "P12V_E1S_0_EN_G")
	)
	(segment
		(start 254.726948 -66.726308)
		(end 254.726948 -66.365374)
		(width 0.10668)
		(layer "F.Cu")
		(net "P12V_E1S_0_EN_G")
	)
	(segment
		(start 256.547112 -66.88836)
		(end 256.928112 -67.26936)
		(width 0.10668)
		(layer "F.Cu")
		(net "P12V_E1S_0_EN_G")
	)
	(segment
		(start 254.853948 -66.238374)
		(end 255.312926 -66.238374)
		(width 0.10668)
		(layer "F.Cu")
		(net "P12V_E1S_0_EN_G")
	)
	(via
		(at 256.547112 -66.88836)
		(size 0.762)
		(drill 0.381)
		(layers "F.Cu" "B.Cu")
		(net "P12V_E1S_0_EN_G")
	)
	(segment
		(start 248.400824 -58.077862)
		(end 247.334278 -57.011316)
		(width 0.254)
		(layer "F.Cu")
		(net "P12V_E1S_0")
	)
	(segment
		(start 256.47269 -39.082472)
		(end 256.47269 -40.098472)
		(width 0.4572)
		(layer "F.Cu")
		(net "P12V_E1S_0")
	)
	(segment
		(start 327.692258 -103.66375)
		(end 327.081134 -103.66375)
		(width 0.254)
		(layer "F.Cu")
		(net "P12V_E1S_0")
	)
	(segment
		(start 327.081134 -103.66375)
		(end 326.97547 -103.558086)
		(width 0.254)
		(layer "F.Cu")
		(net "P12V_E1S_0")
	)
	(segment
		(start 255.646428 -39.082472)
		(end 256.47269 -39.082472)
		(width 0.4572)
		(layer "F.Cu")
		(net "P12V_E1S_0")
	)
	(segment
		(start 252.248416 -57.522618)
		(end 251.693172 -58.077862)
		(width 0.254)
		(layer "F.Cu")
		(net "P12V_E1S_0")
	)
	(segment
		(start 251.693172 -58.077862)
		(end 248.400824 -58.077862)
		(width 0.254)
		(layer "F.Cu")
		(net "P12V_E1S_0")
	)
	(segment
		(start 326.97547 -103.558086)
		(end 326.495156 -103.558086)
		(width 0.254)
		(layer "F.Cu")
		(net "P12V_E1S_0")
	)
	(segment
		(start 247.334278 -53.050948)
		(end 247.384824 -53.000402)
		(width 0.254)
		(layer "F.Cu")
		(net "P12V_E1S_0")
	)
	(segment
		(start 252.561598 -57.209182)
		(end 252.248416 -57.522364)
		(width 0.254)
		(layer "F.Cu")
		(net "P12V_E1S_0")
	)
	(segment
		(start 247.334278 -57.011316)
		(end 247.334278 -53.050948)
		(width 0.254)
		(layer "F.Cu")
		(net "P12V_E1S_0")
	)
	(segment
		(start 327.692258 -104.30129)
		(end 327.692258 -103.66375)
		(width 0.381)
		(layer "F.Cu")
		(net "P12V_E1S_0")
	)
	(segment
		(start 252.248416 -57.522364)
		(end 252.248416 -57.522618)
		(width 0.254)
		(layer "F.Cu")
		(net "P12V_E1S_0")
	)
	(segment
		(start 255.347978 -39.380922)
		(end 255.646428 -39.082472)
		(width 0.4572)
		(layer "F.Cu")
		(net "P12V_E1S_0")
	)
	(via
		(at 249.202448 -40.945816)
		(size 0.508)
		(drill 0.254)
		(layers "F.Cu" "B.Cu")
		(net "P12V_E1S_0")
	)
	(via
		(at 250.449334 -49.555146)
		(size 0.508)
		(drill 0.254)
		(layers "F.Cu" "B.Cu")
		(net "P12V_E1S_0")
	)
	(via
		(at 251.516134 -51.612546)
		(size 0.508)
		(drill 0.254)
		(layers "F.Cu" "B.Cu")
		(net "P12V_E1S_0")
	)
	(via
		(at 251.516134 -50.723546)
		(size 0.508)
		(drill 0.254)
		(layers "F.Cu" "B.Cu")
		(net "P12V_E1S_0")
	)
	(via
		(at 327.692258 -104.30129)
		(size 0.508)
		(drill 0.254)
		(layers "F.Cu" "B.Cu")
		(net "P12V_E1S_0")
	)
	(via
		(at 250.779534 -52.222146)
		(size 0.508)
		(drill 0.254)
		(layers "F.Cu" "B.Cu")
		(net "P12V_E1S_0")
	)
	(via
		(at 245.857522 -52.022502)
		(size 0.508)
		(drill 0.254)
		(layers "F.Cu" "B.Cu")
		(net "P12V_E1S_0")
	)
	(via
		(at 251.516134 -52.501546)
		(size 0.508)
		(drill 0.254)
		(layers "F.Cu" "B.Cu")
		(net "P12V_E1S_0")
	)
	(via
		(at 249.401838 -50.451766)
		(size 0.762)
		(drill 0.381)
		(layers "F.Cu" "B.Cu")
		(net "P12V_E1S_0")
	)
	(via
		(at 250.779534 -51.333146)
		(size 0.508)
		(drill 0.254)
		(layers "F.Cu" "B.Cu")
		(net "P12V_E1S_0")
	)
	(via
		(at 249.905266 -51.349148)
		(size 0.508)
		(drill 0.254)
		(layers "F.Cu" "B.Cu")
		(net "P12V_E1S_0")
	)
	(via
		(at 248.214134 -52.171346)
		(size 0.508)
		(drill 0.254)
		(layers "F.Cu" "B.Cu")
		(net "P12V_E1S_0")
	)
	(via
		(at 247.840246 -51.320446)
		(size 0.508)
		(drill 0.254)
		(layers "F.Cu" "B.Cu")
		(net "P12V_E1S_0")
	)
	(via
		(at 255.347978 -39.380922)
		(size 0.508)
		(drill 0.254)
		(layers "F.Cu" "B.Cu")
		(net "P12V_E1S_0")
	)
	(via
		(at 250.779534 -50.444146)
		(size 0.508)
		(drill 0.254)
		(layers "F.Cu" "B.Cu")
		(net "P12V_E1S_0")
	)
	(via
		(at 246.873522 -52.022502)
		(size 0.508)
		(drill 0.254)
		(layers "F.Cu" "B.Cu")
		(net "P12V_E1S_0")
	)
	(via
		(at 247.825514 -40.94988)
		(size 0.508)
		(drill 0.254)
		(layers "F.Cu" "B.Cu")
		(net "P12V_E1S_0")
	)
	(via
		(at 248.881646 -51.320446)
		(size 0.508)
		(drill 0.254)
		(layers "F.Cu" "B.Cu")
		(net "P12V_E1S_0")
	)
	(segment
		(start 293.687754 -86.996016)
		(end 261.16661 -86.996016)
		(width 0.508)
		(layer "B.Cu")
		(net "P12V_E1S_0")
	)
	(segment
		(start 242.041934 -65.470024)
		(end 242.041934 -59.025028)
		(width 0.508)
		(layer "B.Cu")
		(net "P12V_E1S_0")
	)
	(segment
		(start 327.692258 -104.30129)
		(end 326.743822 -104.30129)
		(width 0.508)
		(layer "B.Cu")
		(net "P12V_E1S_0")
	)
	(segment
		(start 253.626366 -79.455772)
		(end 253.626366 -77.054456)
		(width 0.508)
		(layer "B.Cu")
		(net "P12V_E1S_0")
	)
	(segment
		(start 240.41989 -57.402984)
		(end 240.41989 -53.232558)
		(width 0.508)
		(layer "B.Cu")
		(net "P12V_E1S_0")
	)
	(segment
		(start 316.687962 -104.667812)
		(end 311.35955 -104.667812)
		(width 0.508)
		(layer "B.Cu")
		(net "P12V_E1S_0")
	)
	(segment
		(start 324.001892 -107.04322)
		(end 319.06337 -107.04322)
		(width 0.508)
		(layer "B.Cu")
		(net "P12V_E1S_0")
	)
	(segment
		(start 326.743822 -104.30129)
		(end 324.001892 -107.04322)
		(width 0.508)
		(layer "B.Cu")
		(net "P12V_E1S_0")
	)
	(segment
		(start 319.06337 -107.04322)
		(end 316.687962 -104.667812)
		(width 0.508)
		(layer "B.Cu")
		(net "P12V_E1S_0")
	)
	(segment
		(start 243.01069 -50.641758)
		(end 246.380762 -50.641758)
		(width 0.508)
		(layer "B.Cu")
		(net "P12V_E1S_0")
	)
	(segment
		(start 253.626366 -77.054456)
		(end 242.041934 -65.470024)
		(width 0.508)
		(layer "B.Cu")
		(net "P12V_E1S_0")
	)
	(segment
		(start 242.041934 -59.025028)
		(end 240.41989 -57.402984)
		(width 0.508)
		(layer "B.Cu")
		(net "P12V_E1S_0")
	)
	(segment
		(start 261.16661 -86.996016)
		(end 253.626366 -79.455772)
		(width 0.508)
		(layer "B.Cu")
		(net "P12V_E1S_0")
	)
	(segment
		(start 240.41989 -53.232558)
		(end 243.01069 -50.641758)
		(width 0.508)
		(layer "B.Cu")
		(net "P12V_E1S_0")
	)
	(segment
		(start 311.35955 -104.667812)
		(end 293.687754 -86.996016)
		(width 0.508)
		(layer "B.Cu")
		(net "P12V_E1S_0")
	)
	(segment
		(start 139.46505 -116.224304)
		(end 139.46505 -116.586)
		(width 0.381)
		(layer "F.Cu")
		(net "P12V_AUX")
	)
	(segment
		(start 459.293468 -49.81702)
		(end 458.850238 -49.81702)
		(width 0.254)
		(layer "F.Cu")
		(net "P12V_AUX")
	)
	(segment
		(start 384.513328 -139.186158)
		(end 385.129278 -139.186158)
		(width 0.381)
		(layer "F.Cu")
		(net "P12V_AUX")
	)
	(segment
		(start 319.080896 -363.23905)
		(end 318.262 -363.23905)
		(width 0.381)
		(layer "F.Cu")
		(net "P12V_AUX")
	)
	(segment
		(start 460.292196 -49.186846)
		(end 460.292196 -48.666146)
		(width 0.254)
		(layer "F.Cu")
		(net "P12V_AUX")
	)
	(segment
		(start 203.94168 -143.973296)
		(end 205.146402 -145.178018)
		(width 0.381)
		(layer "F.Cu")
		(net "P12V_AUX")
	)
	(segment
		(start 137.96518 -110.423198)
		(end 137.480802 -110.907576)
		(width 0.381)
		(layer "F.Cu")
		(net "P12V_AUX")
	)
	(segment
		(start 60.937648 -36.083748)
		(end 60.956952 -36.064444)
		(width 0.254)
		(layer "F.Cu")
		(net "P12V_AUX")
	)
	(segment
		(start 137.480802 -110.907576)
		(end 137.480802 -111.566198)
		(width 0.381)
		(layer "F.Cu")
		(net "P12V_AUX")
	)
	(segment
		(start 136.25195 -113.157)
		(end 136.19099 -113.21796)
		(width 0.381)
		(layer "F.Cu")
		(net "P12V_AUX")
	)
	(segment
		(start 43.54195 -100.34016)
		(end 44.27728 -100.34016)
		(width 0.381)
		(layer "F.Cu")
		(net "P12V_AUX")
	)
	(segment
		(start 211.074 -129.94005)
		(end 211.074 -130.687064)
		(width 0.381)
		(layer "F.Cu")
		(net "P12V_AUX")
	)
	(segment
		(start 329.992228 -46.748954)
		(end 330.601828 -46.748954)
		(width 0.3556)
		(layer "F.Cu")
		(net "P12V_AUX")
	)
	(segment
		(start 460.558896 -49.453546)
		(end 460.292196 -49.186846)
		(width 0.254)
		(layer "F.Cu")
		(net "P12V_AUX")
	)
	(segment
		(start 460.292196 -48.666146)
		(end 459.784196 -49.174146)
		(width 0.254)
		(layer "F.Cu")
		(net "P12V_AUX")
	)
	(segment
		(start 462.20507 -41.604438)
		(end 461.567784 -41.604438)
		(width 0.4064)
		(layer "F.Cu")
		(net "P12V_AUX")
	)
	(segment
		(start 140.115544 -108.054394)
		(end 139.072366 -108.054394)
		(width 0.4064)
		(layer "F.Cu")
		(net "P12V_AUX")
	)
	(segment
		(start 149.968712 -119.098822)
		(end 149.58441 -119.098822)
		(width 0.4064)
		(layer "F.Cu")
		(net "P12V_AUX")
	)
	(segment
		(start 205.265782 -137.527792)
		(end 203.94168 -138.851894)
		(width 0.381)
		(layer "F.Cu")
		(net "P12V_AUX")
	)
	(segment
		(start 134.366 -107.188)
		(end 138.205972 -107.188)
		(width 0.381)
		(layer "F.Cu")
		(net "P12V_AUX")
	)
	(segment
		(start 136.25195 -113.157)
		(end 136.25195 -114.02695)
		(width 0.381)
		(layer "F.Cu")
		(net "P12V_AUX")
	)
	(segment
		(start 136.25195 -112.79505)
		(end 136.25195 -113.157)
		(width 0.381)
		(layer "F.Cu")
		(net "P12V_AUX")
	)
	(segment
		(start 64.708024 -39.808658)
		(end 65.341246 -39.808658)
		(width 0.381)
		(layer "F.Cu")
		(net "P12V_AUX")
	)
	(segment
		(start 149.225 -119.019574)
		(end 148.971 -118.765574)
		(width 0.381)
		(layer "F.Cu")
		(net "P12V_AUX")
	)
	(segment
		(start 205.33995 -135.763)
		(end 204.70876 -135.763)
		(width 0.381)
		(layer "F.Cu")
		(net "P12V_AUX")
	)
	(segment
		(start 137.480802 -111.566198)
		(end 136.25195 -112.79505)
		(width 0.381)
		(layer "F.Cu")
		(net "P12V_AUX")
	)
	(segment
		(start 102.348284 -141.20241)
		(end 103.28021 -141.20241)
		(width 0.4572)
		(layer "F.Cu")
		(net "P12V_AUX")
	)
	(segment
		(start 130.429 -107.95)
		(end 133.604 -107.95)
		(width 0.381)
		(layer "F.Cu")
		(net "P12V_AUX")
	)
	(segment
		(start 207.382618 -145.178018)
		(end 209.6008 -147.3962)
		(width 0.381)
		(layer "F.Cu")
		(net "P12V_AUX")
	)
	(segment
		(start 190.02375 -42.554398)
		(end 190.02375 -43.336972)
		(width 0.4064)
		(layer "F.Cu")
		(net "P12V_AUX")
	)
	(segment
		(start 35.65144 -108.49737)
		(end 35.65144 -109.26064)
		(width 0.381)
		(layer "F.Cu")
		(net "P12V_AUX")
	)
	(segment
		(start 133.604 -107.95)
		(end 134.366 -107.188)
		(width 0.381)
		(layer "F.Cu")
		(net "P12V_AUX")
	)
	(segment
		(start 38.916102 -366.37595)
		(end 39.228522 -366.06353)
		(width 0.381)
		(layer "F.Cu")
		(net "P12V_AUX")
	)
	(segment
		(start 149.225 -119.458232)
		(end 149.225 -119.019574)
		(width 0.381)
		(layer "F.Cu")
		(net "P12V_AUX")
	)
	(segment
		(start 257.766312 -66.46926)
		(end 257.766312 -65.77838)
		(width 0.4572)
		(layer "F.Cu")
		(net "P12V_AUX")
	)
	(segment
		(start 140.486892 -107.683046)
		(end 140.115544 -108.054394)
		(width 0.4064)
		(layer "F.Cu")
		(net "P12V_AUX")
	)
	(segment
		(start 75.715114 -18.066512)
		(end 75.290426 -18.4912)
		(width 0.4572)
		(layer "F.Cu")
		(net "P12V_AUX")
	)
	(segment
		(start 148.971 -118.765574)
		(end 148.971 -118.76405)
		(width 0.381)
		(layer "F.Cu")
		(net "P12V_AUX")
	)
	(segment
		(start 257.766312 -68.796408)
		(end 257.766312 -68.180458)
		(width 0.4572)
		(layer "F.Cu")
		(net "P12V_AUX")
	)
	(segment
		(start 205.146402 -145.178018)
		(end 207.382618 -145.178018)
		(width 0.381)
		(layer "F.Cu")
		(net "P12V_AUX")
	)
	(segment
		(start 190.09995 -44.577)
		(end 190.02375 -44.5008)
		(width 0.381)
		(layer "F.Cu")
		(net "P12V_AUX")
	)
	(segment
		(start 136.19099 -113.21796)
		(end 134.57301 -113.21796)
		(width 0.381)
		(layer "F.Cu")
		(net "P12V_AUX")
	)
	(segment
		(start 75.290426 -18.4912)
		(end 75.12177 -18.4912)
		(width 0.4572)
		(layer "F.Cu")
		(net "P12V_AUX")
	)
	(segment
		(start 201.134218 -387.160516)
		(end 200.476358 -387.160516)
		(width 0.4572)
		(layer "F.Cu")
		(net "P12V_AUX")
	)
	(segment
		(start 38.354 -366.37595)
		(end 38.916102 -366.37595)
		(width 0.381)
		(layer "F.Cu")
		(net "P12V_AUX")
	)
	(segment
		(start 200.476358 -387.160516)
		(end 197.999858 -387.160516)
		(width 0.4572)
		(layer "F.Cu")
		(net "P12V_AUX")
	)
	(segment
		(start 426.974 -366.54105)
		(end 427.670214 -366.54105)
		(width 0.3556)
		(layer "F.Cu")
		(net "P12V_AUX")
	)
	(segment
		(start 139.52601 -116.52504)
		(end 141.01699 -116.52504)
		(width 0.381)
		(layer "F.Cu")
		(net "P12V_AUX")
	)
	(segment
		(start 139.46505 -116.586)
		(end 139.52601 -116.52504)
		(width 0.381)
		(layer "F.Cu")
		(net "P12V_AUX")
	)
	(segment
		(start 136.25195 -114.02695)
		(end 138.176 -115.951)
		(width 0.381)
		(layer "F.Cu")
		(net "P12V_AUX")
	)
	(segment
		(start 146.06905 -115.443)
		(end 146.06905 -114.620802)
		(width 0.381)
		(layer "F.Cu")
		(net "P12V_AUX")
	)
	(segment
		(start 211.074 -130.687064)
		(end 211.276692 -130.889756)
		(width 0.381)
		(layer "F.Cu")
		(net "P12V_AUX")
	)
	(segment
		(start 190.02375 -44.5008)
		(end 190.02375 -43.336972)
		(width 0.381)
		(layer "F.Cu")
		(net "P12V_AUX")
	)
	(segment
		(start 149.58441 -119.098822)
		(end 149.225 -119.458232)
		(width 0.4064)
		(layer "F.Cu")
		(net "P12V_AUX")
	)
	(segment
		(start 212.0265 -144.9705)
		(end 212.0265 -144.601438)
		(width 0.381)
		(layer "F.Cu")
		(net "P12V_AUX")
	)
	(segment
		(start 459.784196 -49.174146)
		(end 459.784196 -49.326292)
		(width 0.254)
		(layer "F.Cu")
		(net "P12V_AUX")
	)
	(segment
		(start 65.341246 -39.808658)
		(end 65.342008 -39.80942)
		(width 0.381)
		(layer "F.Cu")
		(net "P12V_AUX")
	)
	(segment
		(start 46.70806 -99.20859)
		(end 46.70806 -98.59772)
		(width 0.381)
		(layer "F.Cu")
		(net "P12V_AUX")
	)
	(segment
		(start 130.048 -108.331)
		(end 130.429 -107.95)
		(width 0.381)
		(layer "F.Cu")
		(net "P12V_AUX")
	)
	(segment
		(start 139.191746 -115.951)
		(end 139.46505 -116.224304)
		(width 0.381)
		(layer "F.Cu")
		(net "P12V_AUX")
	)
	(segment
		(start 160.777936 -119.089424)
		(end 160.777936 -119.751348)
		(width 0.4064)
		(layer "F.Cu")
		(net "P12V_AUX")
	)
	(segment
		(start 209.6008 -147.3962)
		(end 212.0265 -144.9705)
		(width 0.381)
		(layer "F.Cu")
		(net "P12V_AUX")
	)
	(segment
		(start 138.205972 -107.188)
		(end 139.072366 -108.054394)
		(width 0.381)
		(layer "F.Cu")
		(net "P12V_AUX")
	)
	(segment
		(start 447.157602 -18.449798)
		(end 446.512442 -18.449798)
		(width 0.4572)
		(layer "F.Cu")
		(net "P12V_AUX")
	)
	(segment
		(start 103.28021 -141.20241)
		(end 103.7717 -141.6939)
		(width 0.4572)
		(layer "F.Cu")
		(net "P12V_AUX")
	)
	(segment
		(start 250.30303 -46.395132)
		(end 250.30303 -47.088806)
		(width 0.4572)
		(layer "F.Cu")
		(net "P12V_AUX")
	)
	(segment
		(start 178.28895 -408.559)
		(end 177.673 -408.559)
		(width 0.381)
		(layer "F.Cu")
		(net "P12V_AUX")
	)
	(segment
		(start 462.20507 -40.626538)
		(end 461.567784 -40.626538)
		(width 0.4064)
		(layer "F.Cu")
		(net "P12V_AUX")
	)
	(segment
		(start 130.048 -109.07395)
		(end 130.048 -108.331)
		(width 0.381)
		(layer "F.Cu")
		(net "P12V_AUX")
	)
	(segment
		(start 60.26785 -36.083748)
		(end 60.937648 -36.083748)
		(width 0.254)
		(layer "F.Cu")
		(net "P12V_AUX")
	)
	(segment
		(start 203.94168 -138.851894)
		(end 203.94168 -143.973296)
		(width 0.381)
		(layer "F.Cu")
		(net "P12V_AUX")
	)
	(segment
		(start 138.176 -115.951)
		(end 139.191746 -115.951)
		(width 0.381)
		(layer "F.Cu")
		(net "P12V_AUX")
	)
	(segment
		(start 459.784196 -49.326292)
		(end 459.293468 -49.81702)
		(width 0.254)
		(layer "F.Cu")
		(net "P12V_AUX")
	)
	(via
		(at 245.686072 -379.400816)
		(size 0.508)
		(drill 0.254)
		(layers "F.Cu" "B.Cu")
		(net "P12V_AUX")
	)
	(via
		(at 232.1179 -396.019782)
		(size 0.508)
		(drill 0.254)
		(layers "F.Cu" "B.Cu")
		(net "P12V_AUX")
	)
	(via
		(at 118.194074 -146.337528)
		(size 0.508)
		(drill 0.254)
		(layers "F.Cu" "B.Cu")
		(net "P12V_AUX")
	)
	(via
		(at 260.096 -378.765816)
		(size 0.508)
		(drill 0.254)
		(layers "F.Cu" "B.Cu")
		(net "P12V_AUX")
	)
	(via
		(at 87.129874 -153.542492)
		(size 0.508)
		(drill 0.254)
		(layers "F.Cu" "B.Cu")
		(net "P12V_AUX")
	)
	(via
		(at 88.61806 -104.55148)
		(size 0.508)
		(drill 0.254)
		(layers "F.Cu" "B.Cu")
		(net "P12V_AUX")
	)
	(via
		(at 441.194444 -28.504642)
		(size 0.4572)
		(drill 0.254)
		(layers "F.Cu" "B.Cu")
		(net "P12V_AUX")
	)
	(via
		(at 177.444146 -29.255212)
		(size 0.4572)
		(drill 0.254)
		(layers "F.Cu" "B.Cu")
		(net "P12V_AUX")
	)
	(via
		(at 91.811856 -350.545908)
		(size 0.508)
		(drill 0.254)
		(layers "F.Cu" "B.Cu")
		(net "P12V_AUX")
	)
	(via
		(at 201.6379 -397.543782)
		(size 0.508)
		(drill 0.254)
		(layers "F.Cu" "B.Cu")
		(net "P12V_AUX")
	)
	(via
		(at 85.605874 -154.304492)
		(size 0.508)
		(drill 0.254)
		(layers "F.Cu" "B.Cu")
		(net "P12V_AUX")
	)
	(via
		(at 330.74864 -133.328664)
		(size 0.508)
		(drill 0.254)
		(layers "F.Cu" "B.Cu")
		(net "P12V_AUX")
	)
	(via
		(at 14.922754 -197.540372)
		(size 0.508)
		(drill 0.254)
		(layers "F.Cu" "B.Cu")
		(net "P12V_AUX")
	)
	(via
		(at 288.87801 -364.151672)
		(size 0.508)
		(drill 0.254)
		(layers "F.Cu" "B.Cu")
		(net "P12V_AUX")
	)
	(via
		(at 332.007718 -133.577838)
		(size 0.508)
		(drill 0.254)
		(layers "F.Cu" "B.Cu")
		(net "P12V_AUX")
	)
	(via
		(at 66.52133 -27.573224)
		(size 0.4572)
		(drill 0.254)
		(layers "F.Cu" "B.Cu")
		(net "P12V_AUX")
	)
	(via
		(at 222.9739 -396.019782)
		(size 0.508)
		(drill 0.254)
		(layers "F.Cu" "B.Cu")
		(net "P12V_AUX")
	)
	(via
		(at 176.544224 -28.620212)
		(size 0.4572)
		(drill 0.254)
		(layers "F.Cu" "B.Cu")
		(net "P12V_AUX")
	)
	(via
		(at 446.512442 -18.449798)
		(size 0.508)
		(drill 0.254)
		(layers "F.Cu" "B.Cu")
		(net "P12V_AUX")
	)
	(via
		(at 178.344068 -28.620212)
		(size 0.4572)
		(drill 0.254)
		(layers "F.Cu" "B.Cu")
		(net "P12V_AUX")
	)
	(via
		(at 371.273832 -155.182316)
		(size 0.508)
		(drill 0.254)
		(layers "F.Cu" "B.Cu")
		(net "P12V_AUX")
	)
	(via
		(at 180.238146 -361.282742)
		(size 0.508)
		(drill 0.254)
		(layers "F.Cu" "B.Cu")
		(net "P12V_AUX")
	)
	(via
		(at 84.173314 -155.066492)
		(size 0.508)
		(drill 0.254)
		(layers "F.Cu" "B.Cu")
		(net "P12V_AUX")
	)
	(via
		(at 248.226072 -379.400816)
		(size 0.508)
		(drill 0.254)
		(layers "F.Cu" "B.Cu")
		(net "P12V_AUX")
	)
	(via
		(at 182.143146 -363.289342)
		(size 0.508)
		(drill 0.254)
		(layers "F.Cu" "B.Cu")
		(net "P12V_AUX")
	)
	(via
		(at 365.939832 -157.468316)
		(size 0.508)
		(drill 0.254)
		(layers "F.Cu" "B.Cu")
		(net "P12V_AUX")
	)
	(via
		(at 268.570964 -378.765816)
		(size 0.508)
		(drill 0.254)
		(layers "F.Cu" "B.Cu")
		(net "P12V_AUX")
	)
	(via
		(at 238.481108 -380.670816)
		(size 0.508)
		(drill 0.254)
		(layers "F.Cu" "B.Cu")
		(net "P12V_AUX")
	)
	(via
		(at 381.631444 -153.755852)
		(size 0.508)
		(drill 0.254)
		(layers "F.Cu" "B.Cu")
		(net "P12V_AUX")
	)
	(via
		(at 276.630892 -380.035816)
		(size 0.508)
		(drill 0.254)
		(layers "F.Cu" "B.Cu")
		(net "P12V_AUX")
	)
	(via
		(at 90.762328 -353.539044)
		(size 0.508)
		(drill 0.254)
		(layers "F.Cu" "B.Cu")
		(net "P12V_AUX")
	)
	(via
		(at 180.238146 -363.289342)
		(size 0.508)
		(drill 0.254)
		(layers "F.Cu" "B.Cu")
		(net "P12V_AUX")
	)
	(via
		(at 88.575134 -157.060392)
		(size 0.508)
		(drill 0.254)
		(layers "F.Cu" "B.Cu")
		(net "P12V_AUX")
	)
	(via
		(at 253.526036 -380.670816)
		(size 0.508)
		(drill 0.254)
		(layers "F.Cu" "B.Cu")
		(net "P12V_AUX")
	)
	(via
		(at 381.631444 -154.390852)
		(size 0.508)
		(drill 0.254)
		(layers "F.Cu" "B.Cu")
		(net "P12V_AUX")
	)
	(via
		(at 434.668422 -40.355012)
		(size 0.508)
		(drill 0.254)
		(layers "F.Cu" "B.Cu")
		(net "P12V_AUX")
	)
	(via
		(at 116.187474 -146.464528)
		(size 0.508)
		(drill 0.254)
		(layers "F.Cu" "B.Cu")
		(net "P12V_AUX")
	)
	(via
		(at 233.6419 -396.019782)
		(size 0.508)
		(drill 0.254)
		(layers "F.Cu" "B.Cu")
		(net "P12V_AUX")
	)
	(via
		(at 253.544324 -51.632612)
		(size 0.4572)
		(drill 0.254)
		(layers "F.Cu" "B.Cu")
		(net "P12V_AUX")
	)
	(via
		(at 210.7819 -398.305782)
		(size 0.508)
		(drill 0.254)
		(layers "F.Cu" "B.Cu")
		(net "P12V_AUX")
	)
	(via
		(at 250.47575 -272.931636)
		(size 0.508)
		(drill 0.254)
		(layers "F.Cu" "B.Cu")
		(net "P12V_AUX")
	)
	(via
		(at 139.072366 -108.054394)
		(size 0.508)
		(drill 0.254)
		(layers "F.Cu" "B.Cu")
		(net "P12V_AUX")
	)
	(via
		(at 210.0199 -396.781782)
		(size 0.508)
		(drill 0.254)
		(layers "F.Cu" "B.Cu")
		(net "P12V_AUX")
	)
	(via
		(at 67.421252 -27.573224)
		(size 0.4572)
		(drill 0.254)
		(layers "F.Cu" "B.Cu")
		(net "P12V_AUX")
	)
	(via
		(at 212.3059 -396.781782)
		(size 0.508)
		(drill 0.254)
		(layers "F.Cu" "B.Cu")
		(net "P12V_AUX")
	)
	(via
		(at 222.9739 -398.305782)
		(size 0.508)
		(drill 0.254)
		(layers "F.Cu" "B.Cu")
		(net "P12V_AUX")
	)
	(via
		(at 452.481442 -415.771076)
		(size 0.508)
		(drill 0.254)
		(layers "F.Cu" "B.Cu")
		(net "P12V_AUX")
	)
	(via
		(at 447.279776 -29.660342)
		(size 0.508)
		(drill 0.254)
		(layers "F.Cu" "B.Cu")
		(net "P12V_AUX")
	)
	(via
		(at 185.098436 -33.550352)
		(size 0.508)
		(drill 0.254)
		(layers "F.Cu" "B.Cu")
		(net "P12V_AUX")
	)
	(via
		(at 69.22135 -28.208224)
		(size 0.4572)
		(drill 0.254)
		(layers "F.Cu" "B.Cu")
		(net "P12V_AUX")
	)
	(via
		(at 450.430646 -414.512252)
		(size 0.508)
		(drill 0.254)
		(layers "F.Cu" "B.Cu")
		(net "P12V_AUX")
	)
	(via
		(at 251.23775 -272.931636)
		(size 0.508)
		(drill 0.254)
		(layers "F.Cu" "B.Cu")
		(net "P12V_AUX")
	)
	(via
		(at 251.621036 -381.305816)
		(size 0.508)
		(drill 0.254)
		(layers "F.Cu" "B.Cu")
		(net "P12V_AUX")
	)
	(via
		(at 23.024846 -406.020778)
		(size 0.508)
		(drill 0.254)
		(layers "F.Cu" "B.Cu")
		(net "P12V_AUX")
	)
	(via
		(at 83.847686 -153.132282)
		(size 0.508)
		(drill 0.254)
		(layers "F.Cu" "B.Cu")
		(net "P12V_AUX")
	)
	(via
		(at 367.463832 -156.706316)
		(size 0.508)
		(drill 0.254)
		(layers "F.Cu" "B.Cu")
		(net "P12V_AUX")
	)
	(via
		(at 116.140992 -71.156322)
		(size 0.508)
		(drill 0.254)
		(layers "F.Cu" "B.Cu")
		(net "P12V_AUX")
	)
	(via
		(at 187.142628 -395.857984)
		(size 0.508)
		(drill 0.254)
		(layers "F.Cu" "B.Cu")
		(net "P12V_AUX")
	)
	(via
		(at 264.125964 -381.305816)
		(size 0.508)
		(drill 0.254)
		(layers "F.Cu" "B.Cu")
		(net "P12V_AUX")
	)
	(via
		(at 89.906856 -351.815908)
		(size 0.508)
		(drill 0.254)
		(layers "F.Cu" "B.Cu")
		(net "P12V_AUX")
	)
	(via
		(at 223.413828 -273.071082)
		(size 0.508)
		(drill 0.254)
		(layers "F.Cu" "B.Cu")
		(net "P12V_AUX")
	)
	(via
		(at 213.0679 -395.257782)
		(size 0.508)
		(drill 0.254)
		(layers "F.Cu" "B.Cu")
		(net "P12V_AUX")
	)
	(via
		(at 208.4959 -396.019782)
		(size 0.508)
		(drill 0.254)
		(layers "F.Cu" "B.Cu")
		(net "P12V_AUX")
	)
	(via
		(at 260.096 -380.035816)
		(size 0.508)
		(drill 0.254)
		(layers "F.Cu" "B.Cu")
		(net "P12V_AUX")
	)
	(via
		(at 92.958666 -352.460814)
		(size 0.508)
		(drill 0.254)
		(layers "F.Cu" "B.Cu")
		(net "P12V_AUX")
	)
	(via
		(at 277.265892 -380.670816)
		(size 0.508)
		(drill 0.254)
		(layers "F.Cu" "B.Cu")
		(net "P12V_AUX")
	)
	(via
		(at 84.843874 -156.590492)
		(size 0.508)
		(drill 0.254)
		(layers "F.Cu" "B.Cu")
		(net "P12V_AUX")
	)
	(via
		(at 275.360892 -381.305816)
		(size 0.508)
		(drill 0.254)
		(layers "F.Cu" "B.Cu")
		(net "P12V_AUX")
	)
	(via
		(at 118.194074 -143.924528)
		(size 0.508)
		(drill 0.254)
		(layers "F.Cu" "B.Cu")
		(net "P12V_AUX")
	)
	(via
		(at 332.467204 -133.124194)
		(size 0.508)
		(drill 0.254)
		(layers "F.Cu" "B.Cu")
		(net "P12V_AUX")
	)
	(via
		(at 241.656108 -378.765816)
		(size 0.508)
		(drill 0.254)
		(layers "F.Cu" "B.Cu")
		(net "P12V_AUX")
	)
	(via
		(at 231.3559 -396.019782)
		(size 0.508)
		(drill 0.254)
		(layers "F.Cu" "B.Cu")
		(net "P12V_AUX")
	)
	(via
		(at 381.123444 -152.384252)
		(size 0.508)
		(drill 0.254)
		(layers "F.Cu" "B.Cu")
		(net "P12V_AUX")
	)
	(via
		(at 232.8799 -396.019782)
		(size 0.508)
		(drill 0.254)
		(layers "F.Cu" "B.Cu")
		(net "P12V_AUX")
	)
	(via
		(at 63.015622 -23.405084)
		(size 0.508)
		(drill 0.254)
		(layers "F.Cu" "B.Cu")
		(net "P12V_AUX")
	)
	(via
		(at 198.5899 -396.019782)
		(size 0.508)
		(drill 0.254)
		(layers "F.Cu" "B.Cu")
		(net "P12V_AUX")
	)
	(via
		(at 88.001856 -353.085908)
		(size 0.508)
		(drill 0.254)
		(layers "F.Cu" "B.Cu")
		(net "P12V_AUX")
	)
	(via
		(at 243.561108 -378.765816)
		(size 0.508)
		(drill 0.254)
		(layers "F.Cu" "B.Cu")
		(net "P12V_AUX")
	)
	(via
		(at 219.9259 -395.257782)
		(size 0.508)
		(drill 0.254)
		(layers "F.Cu" "B.Cu")
		(net "P12V_AUX")
	)
	(via
		(at 287.60801 -362.411772)
		(size 0.508)
		(drill 0.254)
		(layers "F.Cu" "B.Cu")
		(net "P12V_AUX")
	)
	(via
		(at 222.651828 -270.645382)
		(size 0.508)
		(drill 0.254)
		(layers "F.Cu" "B.Cu")
		(net "P12V_AUX")
	)
	(via
		(at 262.001 -378.765816)
		(size 0.508)
		(drill 0.254)
		(layers "F.Cu" "B.Cu")
		(net "P12V_AUX")
	)
	(via
		(at 372.797832 -155.182316)
		(size 0.508)
		(drill 0.254)
		(layers "F.Cu" "B.Cu")
		(net "P12V_AUX")
	)
	(via
		(at 237.179612 -380.670816)
		(size 0.508)
		(drill 0.254)
		(layers "F.Cu" "B.Cu")
		(net "P12V_AUX")
	)
	(via
		(at 209.2579 -396.019782)
		(size 0.508)
		(drill 0.254)
		(layers "F.Cu" "B.Cu")
		(net "P12V_AUX")
	)
	(via
		(at 338.193126 -359.112312)
		(size 0.508)
		(drill 0.254)
		(layers "F.Cu" "B.Cu")
		(net "P12V_AUX")
	)
	(via
		(at 435.430422 -39.694612)
		(size 0.508)
		(drill 0.254)
		(layers "F.Cu" "B.Cu")
		(net "P12V_AUX")
	)
	(via
		(at 120.835674 -145.829528)
		(size 0.508)
		(drill 0.254)
		(layers "F.Cu" "B.Cu")
		(net "P12V_AUX")
	)
	(via
		(at 88.001856 -350.545908)
		(size 0.508)
		(drill 0.254)
		(layers "F.Cu" "B.Cu")
		(net "P12V_AUX")
	)
	(via
		(at 436.751222 -40.355012)
		(size 0.508)
		(drill 0.254)
		(layers "F.Cu" "B.Cu")
		(net "P12V_AUX")
	)
	(via
		(at 272.600928 -378.765816)
		(size 0.508)
		(drill 0.254)
		(layers "F.Cu" "B.Cu")
		(net "P12V_AUX")
	)
	(via
		(at 119.464074 -143.924528)
		(size 0.508)
		(drill 0.254)
		(layers "F.Cu" "B.Cu")
		(net "P12V_AUX")
	)
	(via
		(at 182.143146 -359.911142)
		(size 0.508)
		(drill 0.254)
		(layers "F.Cu" "B.Cu")
		(net "P12V_AUX")
	)
	(via
		(at 119.464074 -146.337528)
		(size 0.508)
		(drill 0.254)
		(layers "F.Cu" "B.Cu")
		(net "P12V_AUX")
	)
	(via
		(at 137.619232 -73.594722)
		(size 0.508)
		(drill 0.254)
		(layers "F.Cu" "B.Cu")
		(net "P12V_AUX")
	)
	(via
		(at 252.891036 -380.670816)
		(size 0.508)
		(drill 0.254)
		(layers "F.Cu" "B.Cu")
		(net "P12V_AUX")
	)
	(via
		(at 15.557754 -198.175372)
		(size 0.508)
		(drill 0.254)
		(layers "F.Cu" "B.Cu")
		(net "P12V_AUX")
	)
	(via
		(at 335.942686 -361.059984)
		(size 0.508)
		(drill 0.254)
		(layers "F.Cu" "B.Cu")
		(net "P12V_AUX")
	)
	(via
		(at 211.5439 -395.257782)
		(size 0.508)
		(drill 0.254)
		(layers "F.Cu" "B.Cu")
		(net "P12V_AUX")
	)
	(via
		(at 341.966042 -358.045004)
		(size 0.508)
		(drill 0.254)
		(layers "F.Cu" "B.Cu")
		(net "P12V_AUX")
	)
	(via
		(at 253.544324 -52.532534)
		(size 0.4572)
		(drill 0.254)
		(layers "F.Cu" "B.Cu")
		(net "P12V_AUX")
	)
	(via
		(at 368.225832 -155.944316)
		(size 0.508)
		(drill 0.254)
		(layers "F.Cu" "B.Cu")
		(net "P12V_AUX")
	)
	(via
		(at 337.448906 -358.464612)
		(size 0.508)
		(drill 0.254)
		(layers "F.Cu" "B.Cu")
		(net "P12V_AUX")
	)
	(via
		(at 252.891036 -379.400816)
		(size 0.508)
		(drill 0.254)
		(layers "F.Cu" "B.Cu")
		(net "P12V_AUX")
	)
	(via
		(at 263.490964 -381.305816)
		(size 0.508)
		(drill 0.254)
		(layers "F.Cu" "B.Cu")
		(net "P12V_AUX")
	)
	(via
		(at 25.787096 -404.763732)
		(size 0.508)
		(drill 0.254)
		(layers "F.Cu" "B.Cu")
		(net "P12V_AUX")
	)
	(via
		(at 203.927964 -347.241622)
		(size 0.508)
		(drill 0.254)
		(layers "F.Cu" "B.Cu")
		(net "P12V_AUX")
	)
	(via
		(at 244.831108 -378.765816)
		(size 0.508)
		(drill 0.254)
		(layers "F.Cu" "B.Cu")
		(net "P12V_AUX")
	)
	(via
		(at 76.499466 -28.652724)
		(size 0.508)
		(drill 0.254)
		(layers "F.Cu" "B.Cu")
		(net "P12V_AUX")
	)
	(via
		(at 459.476348 -177.30597)
		(size 0.508)
		(drill 0.254)
		(layers "F.Cu" "B.Cu")
		(net "P12V_AUX")
	)
	(via
		(at 264.760964 -380.670816)
		(size 0.508)
		(drill 0.254)
		(layers "F.Cu" "B.Cu")
		(net "P12V_AUX")
	)
	(via
		(at 47.131732 -360.94924)
		(size 0.508)
		(drill 0.254)
		(layers "F.Cu" "B.Cu")
		(net "P12V_AUX")
	)
	(via
		(at 88.654128 -353.73945)
		(size 0.508)
		(drill 0.254)
		(layers "F.Cu" "B.Cu")
		(net "P12V_AUX")
	)
	(via
		(at 256.701036 -378.765816)
		(size 0.508)
		(drill 0.254)
		(layers "F.Cu" "B.Cu")
		(net "P12V_AUX")
	)
	(via
		(at 88.653874 -154.304492)
		(size 0.508)
		(drill 0.254)
		(layers "F.Cu" "B.Cu")
		(net "P12V_AUX")
	)
	(via
		(at 219.1639 -397.543782)
		(size 0.508)
		(drill 0.254)
		(layers "F.Cu" "B.Cu")
		(net "P12V_AUX")
	)
	(via
		(at 243.561108 -379.400816)
		(size 0.508)
		(drill 0.254)
		(layers "F.Cu" "B.Cu")
		(net "P12V_AUX")
	)
	(via
		(at 251.99975 -271.267936)
		(size 0.508)
		(drill 0.254)
		(layers "F.Cu" "B.Cu")
		(net "P12V_AUX")
	)
	(via
		(at 182.143146 -363.924342)
		(size 0.508)
		(drill 0.254)
		(layers "F.Cu" "B.Cu")
		(net "P12V_AUX")
	)
	(via
		(at 233.6419 -398.305782)
		(size 0.508)
		(drill 0.254)
		(layers "F.Cu" "B.Cu")
		(net "P12V_AUX")
	)
	(via
		(at 200.1139 -396.781782)
		(size 0.508)
		(drill 0.254)
		(layers "F.Cu" "B.Cu")
		(net "P12V_AUX")
	)
	(via
		(at 67.421252 -28.208224)
		(size 0.4572)
		(drill 0.254)
		(layers "F.Cu" "B.Cu")
		(net "P12V_AUX")
	)
	(via
		(at 379.193044 -157.075632)
		(size 0.508)
		(drill 0.254)
		(layers "F.Cu" "B.Cu")
		(net "P12V_AUX")
	)
	(via
		(at 91.701874 -157.327092)
		(size 0.508)
		(drill 0.254)
		(layers "F.Cu" "B.Cu")
		(net "P12V_AUX")
	)
	(via
		(at 120.200674 -143.924528)
		(size 0.508)
		(drill 0.254)
		(layers "F.Cu" "B.Cu")
		(net "P12V_AUX")
	)
	(via
		(at 264.760964 -380.035816)
		(size 0.508)
		(drill 0.254)
		(layers "F.Cu" "B.Cu")
		(net "P12V_AUX")
	)
	(via
		(at 342.023446 -360.430064)
		(size 0.508)
		(drill 0.254)
		(layers "F.Cu" "B.Cu")
		(net "P12V_AUX")
	)
	(via
		(at 76.499466 -27.204924)
		(size 0.508)
		(drill 0.254)
		(layers "F.Cu" "B.Cu")
		(net "P12V_AUX")
	)
	(via
		(at 368.411252 -156.810456)
		(size 0.508)
		(drill 0.254)
		(layers "F.Cu" "B.Cu")
		(net "P12V_AUX")
	)
	(via
		(at 258.191 -379.400816)
		(size 0.508)
		(drill 0.254)
		(layers "F.Cu" "B.Cu")
		(net "P12V_AUX")
	)
	(via
		(at 200.8759 -399.067782)
		(size 0.508)
		(drill 0.254)
		(layers "F.Cu" "B.Cu")
		(net "P12V_AUX")
	)
	(via
		(at 267.935964 -378.765816)
		(size 0.508)
		(drill 0.254)
		(layers "F.Cu" "B.Cu")
		(net "P12V_AUX")
	)
	(via
		(at 85.605874 -155.066492)
		(size 0.508)
		(drill 0.254)
		(layers "F.Cu" "B.Cu")
		(net "P12V_AUX")
	)
	(via
		(at 291.02177 -364.16869)
		(size 0.508)
		(drill 0.254)
		(layers "F.Cu" "B.Cu")
		(net "P12V_AUX")
	)
	(via
		(at 185.618628 -398.905984)
		(size 0.508)
		(drill 0.254)
		(layers "F.Cu" "B.Cu")
		(net "P12V_AUX")
	)
	(via
		(at 231.3559 -397.543782)
		(size 0.508)
		(drill 0.254)
		(layers "F.Cu" "B.Cu")
		(net "P12V_AUX")
	)
	(via
		(at 229.8319 -398.305782)
		(size 0.508)
		(drill 0.254)
		(layers "F.Cu" "B.Cu")
		(net "P12V_AUX")
	)
	(via
		(at 231.3559 -396.781782)
		(size 0.508)
		(drill 0.254)
		(layers "F.Cu" "B.Cu")
		(net "P12V_AUX")
	)
	(via
		(at 90.939874 -154.304492)
		(size 0.508)
		(drill 0.254)
		(layers "F.Cu" "B.Cu")
		(net "P12V_AUX")
	)
	(via
		(at 90.541856 -351.815908)
		(size 0.508)
		(drill 0.254)
		(layers "F.Cu" "B.Cu")
		(net "P12V_AUX")
	)
	(via
		(at 178.344068 -29.255212)
		(size 0.4572)
		(drill 0.254)
		(layers "F.Cu" "B.Cu")
		(net "P12V_AUX")
	)
	(via
		(at 120.200674 -145.194528)
		(size 0.508)
		(drill 0.254)
		(layers "F.Cu" "B.Cu")
		(net "P12V_AUX")
	)
	(via
		(at 234.4039 -397.543782)
		(size 0.508)
		(drill 0.254)
		(layers "F.Cu" "B.Cu")
		(net "P12V_AUX")
	)
	(via
		(at 204.562964 -347.241622)
		(size 0.508)
		(drill 0.254)
		(layers "F.Cu" "B.Cu")
		(net "P12V_AUX")
	)
	(via
		(at 442.662564 -359.654348)
		(size 0.508)
		(drill 0.254)
		(layers "F.Cu" "B.Cu")
		(net "P12V_AUX")
	)
	(via
		(at 340.703662 -359.121964)
		(size 0.508)
		(drill 0.254)
		(layers "F.Cu" "B.Cu")
		(net "P12V_AUX")
	)
	(via
		(at 335.924906 -358.464612)
		(size 0.508)
		(drill 0.254)
		(layers "F.Cu" "B.Cu")
		(net "P12V_AUX")
	)
	(via
		(at 211.5439 -398.305782)
		(size 0.508)
		(drill 0.254)
		(layers "F.Cu" "B.Cu")
		(net "P12V_AUX")
	)
	(via
		(at 367.463832 -155.944316)
		(size 0.508)
		(drill 0.254)
		(layers "F.Cu" "B.Cu")
		(net "P12V_AUX")
	)
	(via
		(at 88.001856 -351.180908)
		(size 0.508)
		(drill 0.254)
		(layers "F.Cu" "B.Cu")
		(net "P12V_AUX")
	)
	(via
		(at 93.081856 -351.815908)
		(size 0.508)
		(drill 0.254)
		(layers "F.Cu" "B.Cu")
		(net "P12V_AUX")
	)
	(via
		(at 185.618628 -398.143984)
		(size 0.508)
		(drill 0.254)
		(layers "F.Cu" "B.Cu")
		(net "P12V_AUX")
	)
	(via
		(at 458.597508 -181.85003)
		(size 0.508)
		(drill 0.254)
		(layers "F.Cu" "B.Cu")
		(net "P12V_AUX")
	)
	(via
		(at 255.580134 -41.858946)
		(size 0.508)
		(drill 0.254)
		(layers "F.Cu" "B.Cu")
		(net "P12V_AUX")
	)
	(via
		(at 248.226072 -381.305816)
		(size 0.508)
		(drill 0.254)
		(layers "F.Cu" "B.Cu")
		(net "P12V_AUX")
	)
	(via
		(at 249.71375 -272.931636)
		(size 0.508)
		(drill 0.254)
		(layers "F.Cu" "B.Cu")
		(net "P12V_AUX")
	)
	(via
		(at 15.557754 -200.715372)
		(size 0.508)
		(drill 0.254)
		(layers "F.Cu" "B.Cu")
		(net "P12V_AUX")
	)
	(via
		(at 14.238478 -201.3585)
		(size 0.508)
		(drill 0.254)
		(layers "F.Cu" "B.Cu")
		(net "P12V_AUX")
	)
	(via
		(at 270.695928 -381.305816)
		(size 0.508)
		(drill 0.254)
		(layers "F.Cu" "B.Cu")
		(net "P12V_AUX")
	)
	(via
		(at 254.179324 -49.832514)
		(size 0.4572)
		(drill 0.254)
		(layers "F.Cu" "B.Cu")
		(net "P12V_AUX")
	)
	(via
		(at 116.822474 -146.464528)
		(size 0.508)
		(drill 0.254)
		(layers "F.Cu" "B.Cu")
		(net "P12V_AUX")
	)
	(via
		(at 182.143146 -359.276142)
		(size 0.508)
		(drill 0.254)
		(layers "F.Cu" "B.Cu")
		(net "P12V_AUX")
	)
	(via
		(at 341.269066 -361.070144)
		(size 0.508)
		(drill 0.254)
		(layers "F.Cu" "B.Cu")
		(net "P12V_AUX")
	)
	(via
		(at 223.7359 -397.543782)
		(size 0.508)
		(drill 0.254)
		(layers "F.Cu" "B.Cu")
		(net "P12V_AUX")
	)
	(via
		(at 261.366 -379.400816)
		(size 0.508)
		(drill 0.254)
		(layers "F.Cu" "B.Cu")
		(net "P12V_AUX")
	)
	(via
		(at 93.716856 -351.815908)
		(size 0.508)
		(drill 0.254)
		(layers "F.Cu" "B.Cu")
		(net "P12V_AUX")
	)
	(via
		(at 181.508146 -359.276142)
		(size 0.508)
		(drill 0.254)
		(layers "F.Cu" "B.Cu")
		(net "P12V_AUX")
	)
	(via
		(at 93.609668 -352.460306)
		(size 0.508)
		(drill 0.254)
		(layers "F.Cu" "B.Cu")
		(net "P12V_AUX")
	)
	(via
		(at 290.23945 -361.565952)
		(size 0.508)
		(drill 0.254)
		(layers "F.Cu" "B.Cu")
		(net "P12V_AUX")
	)
	(via
		(at 451.750176 -24.885142)
		(size 0.508)
		(drill 0.254)
		(layers "F.Cu" "B.Cu")
		(net "P12V_AUX")
	)
	(via
		(at 434.668422 -41.650412)
		(size 0.508)
		(drill 0.254)
		(layers "F.Cu" "B.Cu")
		(net "P12V_AUX")
	)
	(via
		(at 186.380628 -398.143984)
		(size 0.508)
		(drill 0.254)
		(layers "F.Cu" "B.Cu")
		(net "P12V_AUX")
	)
	(via
		(at 342.031066 -361.070144)
		(size 0.508)
		(drill 0.254)
		(layers "F.Cu" "B.Cu")
		(net "P12V_AUX")
	)
	(via
		(at 230.5939 -395.257782)
		(size 0.508)
		(drill 0.254)
		(layers "F.Cu" "B.Cu")
		(net "P12V_AUX")
	)
	(via
		(at 337.466686 -361.059984)
		(size 0.508)
		(drill 0.254)
		(layers "F.Cu" "B.Cu")
		(net "P12V_AUX")
	)
	(via
		(at 47.766732 -361.58424)
		(size 0.508)
		(drill 0.254)
		(layers "F.Cu" "B.Cu")
		(net "P12V_AUX")
	)
	(via
		(at 339.727286 -358.474772)
		(size 0.508)
		(drill 0.254)
		(layers "F.Cu" "B.Cu")
		(net "P12V_AUX")
	)
	(via
		(at 441.392564 -358.282748)
		(size 0.508)
		(drill 0.254)
		(layers "F.Cu" "B.Cu")
		(net "P12V_AUX")
	)
	(via
		(at 256.469134 -41.858946)
		(size 0.508)
		(drill 0.254)
		(layers "F.Cu" "B.Cu")
		(net "P12V_AUX")
	)
	(via
		(at 14.238478 -199.4535)
		(size 0.508)
		(drill 0.254)
		(layers "F.Cu" "B.Cu")
		(net "P12V_AUX")
	)
	(via
		(at 190.058294 -28.588208)
		(size 0.508)
		(drill 0.254)
		(layers "F.Cu" "B.Cu")
		(net "P12V_AUX")
	)
	(via
		(at 436.090822 -41.015412)
		(size 0.508)
		(drill 0.254)
		(layers "F.Cu" "B.Cu")
		(net "P12V_AUX")
	)
	(via
		(at 47.131732 -362.85424)
		(size 0.508)
		(drill 0.254)
		(layers "F.Cu" "B.Cu")
		(net "P12V_AUX")
	)
	(via
		(at 24.415496 -405.373332)
		(size 0.508)
		(drill 0.254)
		(layers "F.Cu" "B.Cu")
		(net "P12V_AUX")
	)
	(via
		(at 35.55492 -128.88468)
		(size 0.508)
		(drill 0.254)
		(layers "F.Cu" "B.Cu")
		(net "P12V_AUX")
	)
	(via
		(at 253.802134 -48.081946)
		(size 0.508)
		(drill 0.254)
		(layers "F.Cu" "B.Cu")
		(net "P12V_AUX")
	)
	(via
		(at 48.382682 -360.697272)
		(size 0.508)
		(drill 0.254)
		(layers "F.Cu" "B.Cu")
		(net "P12V_AUX")
	)
	(via
		(at 271.330928 -380.670816)
		(size 0.508)
		(drill 0.254)
		(layers "F.Cu" "B.Cu")
		(net "P12V_AUX")
	)
	(via
		(at 210.0199 -395.257782)
		(size 0.508)
		(drill 0.254)
		(layers "F.Cu" "B.Cu")
		(net "P12V_AUX")
	)
	(via
		(at 234.4039 -395.257782)
		(size 0.508)
		(drill 0.254)
		(layers "F.Cu" "B.Cu")
		(net "P12V_AUX")
	)
	(via
		(at 256.066036 -379.400816)
		(size 0.508)
		(drill 0.254)
		(layers "F.Cu" "B.Cu")
		(net "P12V_AUX")
	)
	(via
		(at 93.716856 -350.545908)
		(size 0.508)
		(drill 0.254)
		(layers "F.Cu" "B.Cu")
		(net "P12V_AUX")
	)
	(via
		(at 49.017682 -360.697272)
		(size 0.508)
		(drill 0.254)
		(layers "F.Cu" "B.Cu")
		(net "P12V_AUX")
	)
	(via
		(at 201.6379 -398.305782)
		(size 0.508)
		(drill 0.254)
		(layers "F.Cu" "B.Cu")
		(net "P12V_AUX")
	)
	(via
		(at 52.211732 -359.67924)
		(size 0.508)
		(drill 0.254)
		(layers "F.Cu" "B.Cu")
		(net "P12V_AUX")
	)
	(via
		(at 343.537286 -358.474772)
		(size 0.508)
		(drill 0.254)
		(layers "F.Cu" "B.Cu")
		(net "P12V_AUX")
	)
	(via
		(at 244.196108 -379.400816)
		(size 0.508)
		(drill 0.254)
		(layers "F.Cu" "B.Cu")
		(net "P12V_AUX")
	)
	(via
		(at 65.342008 -39.80942)
		(size 0.508)
		(drill 0.254)
		(layers "F.Cu" "B.Cu")
		(net "P12V_AUX")
	)
	(via
		(at 35.53206 -127.87376)
		(size 0.508)
		(drill 0.254)
		(layers "F.Cu" "B.Cu")
		(net "P12V_AUX")
	)
	(via
		(at 319.080896 -363.23905)
		(size 0.508)
		(drill 0.254)
		(layers "F.Cu" "B.Cu")
		(net "P12V_AUX")
	)
	(via
		(at 188.666628 -396.619984)
		(size 0.508)
		(drill 0.254)
		(layers "F.Cu" "B.Cu")
		(net "P12V_AUX")
	)
	(via
		(at 138.335512 -74.074782)
		(size 0.508)
		(drill 0.254)
		(layers "F.Cu" "B.Cu")
		(net "P12V_AUX")
	)
	(via
		(at 366.701832 -156.706316)
		(size 0.508)
		(drill 0.254)
		(layers "F.Cu" "B.Cu")
		(net "P12V_AUX")
	)
	(via
		(at 273.870928 -378.765816)
		(size 0.508)
		(drill 0.254)
		(layers "F.Cu" "B.Cu")
		(net "P12V_AUX")
	)
	(via
		(at 239.751108 -379.400816)
		(size 0.508)
		(drill 0.254)
		(layers "F.Cu" "B.Cu")
		(net "P12V_AUX")
	)
	(via
		(at 285.59125 -361.565952)
		(size 0.508)
		(drill 0.254)
		(layers "F.Cu" "B.Cu")
		(net "P12V_AUX")
	)
	(via
		(at 87.129874 -155.066492)
		(size 0.508)
		(drill 0.254)
		(layers "F.Cu" "B.Cu")
		(net "P12V_AUX")
	)
	(via
		(at 344.299286 -359.109772)
		(size 0.508)
		(drill 0.254)
		(layers "F.Cu" "B.Cu")
		(net "P12V_AUX")
	)
	(via
		(at 89.25306 -103.91648)
		(size 0.508)
		(drill 0.254)
		(layers "F.Cu" "B.Cu")
		(net "P12V_AUX")
	)
	(via
		(at 89.271856 -351.180908)
		(size 0.508)
		(drill 0.254)
		(layers "F.Cu" "B.Cu")
		(net "P12V_AUX")
	)
	(via
		(at 14.922754 -198.810372)
		(size 0.508)
		(drill 0.254)
		(layers "F.Cu" "B.Cu")
		(net "P12V_AUX")
	)
	(via
		(at 372.035832 -155.944316)
		(size 0.508)
		(drill 0.254)
		(layers "F.Cu" "B.Cu")
		(net "P12V_AUX")
	)
	(via
		(at 240.386108 -378.765816)
		(size 0.508)
		(drill 0.254)
		(layers "F.Cu" "B.Cu")
		(net "P12V_AUX")
	)
	(via
		(at 149.225 -119.458232)
		(size 0.508)
		(drill 0.254)
		(layers "F.Cu" "B.Cu")
		(net "P12V_AUX")
	)
	(via
		(at 291.02177 -363.53369)
		(size 0.508)
		(drill 0.254)
		(layers "F.Cu" "B.Cu")
		(net "P12V_AUX")
	)
	(via
		(at 338.213446 -360.430064)
		(size 0.508)
		(drill 0.254)
		(layers "F.Cu" "B.Cu")
		(net "P12V_AUX")
	)
	(via
		(at 246.321072 -380.670816)
		(size 0.508)
		(drill 0.254)
		(layers "F.Cu" "B.Cu")
		(net "P12V_AUX")
	)
	(via
		(at 120.200674 -145.829528)
		(size 0.508)
		(drill 0.254)
		(layers "F.Cu" "B.Cu")
		(net "P12V_AUX")
	)
	(via
		(at 246.956072 -381.305816)
		(size 0.508)
		(drill 0.254)
		(layers "F.Cu" "B.Cu")
		(net "P12V_AUX")
	)
	(via
		(at 231.3559 -398.305782)
		(size 0.508)
		(drill 0.254)
		(layers "F.Cu" "B.Cu")
		(net "P12V_AUX")
	)
	(via
		(at 441.392564 -362.295948)
		(size 0.508)
		(drill 0.254)
		(layers "F.Cu" "B.Cu")
		(net "P12V_AUX")
	)
	(via
		(at 92.446856 -351.815908)
		(size 0.508)
		(drill 0.254)
		(layers "F.Cu" "B.Cu")
		(net "P12V_AUX")
	)
	(via
		(at 379.129544 -155.005532)
		(size 0.508)
		(drill 0.254)
		(layers "F.Cu" "B.Cu")
		(net "P12V_AUX")
	)
	(via
		(at 160.777936 -119.751348)
		(size 0.508)
		(drill 0.254)
		(layers "F.Cu" "B.Cu")
		(net "P12V_AUX")
	)
	(via
		(at 233.6419 -396.781782)
		(size 0.508)
		(drill 0.254)
		(layers "F.Cu" "B.Cu")
		(net "P12V_AUX")
	)
	(via
		(at 180.873146 -359.276142)
		(size 0.508)
		(drill 0.254)
		(layers "F.Cu" "B.Cu")
		(net "P12V_AUX")
	)
	(via
		(at 242.291108 -378.765816)
		(size 0.508)
		(drill 0.254)
		(layers "F.Cu" "B.Cu")
		(net "P12V_AUX")
	)
	(via
		(at 87.366856 -351.180908)
		(size 0.508)
		(drill 0.254)
		(layers "F.Cu" "B.Cu")
		(net "P12V_AUX")
	)
	(via
		(at 66.52133 -28.208224)
		(size 0.4572)
		(drill 0.254)
		(layers "F.Cu" "B.Cu")
		(net "P12V_AUX")
	)
	(via
		(at 15.557754 -198.810372)
		(size 0.508)
		(drill 0.254)
		(layers "F.Cu" "B.Cu")
		(net "P12V_AUX")
	)
	(via
		(at 286.97301 -364.151672)
		(size 0.508)
		(drill 0.254)
		(layers "F.Cu" "B.Cu")
		(net "P12V_AUX")
	)
	(via
		(at 72.606662 -29.363924)
		(size 0.508)
		(drill 0.254)
		(layers "F.Cu" "B.Cu")
		(net "P12V_AUX")
	)
	(via
		(at 239.751108 -381.305816)
		(size 0.508)
		(drill 0.254)
		(layers "F.Cu" "B.Cu")
		(net "P12V_AUX")
	)
	(via
		(at 338.203286 -358.474772)
		(size 0.508)
		(drill 0.254)
		(layers "F.Cu" "B.Cu")
		(net "P12V_AUX")
	)
	(via
		(at 222.2119 -396.019782)
		(size 0.508)
		(drill 0.254)
		(layers "F.Cu" "B.Cu")
		(net "P12V_AUX")
	)
	(via
		(at 239.116108 -378.765816)
		(size 0.508)
		(drill 0.254)
		(layers "F.Cu" "B.Cu")
		(net "P12V_AUX")
	)
	(via
		(at 246.321072 -379.400816)
		(size 0.508)
		(drill 0.254)
		(layers "F.Cu" "B.Cu")
		(net "P12V_AUX")
	)
	(via
		(at 87.366856 -350.545908)
		(size 0.508)
		(drill 0.254)
		(layers "F.Cu" "B.Cu")
		(net "P12V_AUX")
	)
	(via
		(at 453.80021 -414.4772)
		(size 0.508)
		(drill 0.254)
		(layers "F.Cu" "B.Cu")
		(net "P12V_AUX")
	)
	(via
		(at 234.4039 -396.781782)
		(size 0.508)
		(drill 0.254)
		(layers "F.Cu" "B.Cu")
		(net "P12V_AUX")
	)
	(via
		(at 87.932514 -155.960572)
		(size 0.508)
		(drill 0.254)
		(layers "F.Cu" "B.Cu")
		(net "P12V_AUX")
	)
	(via
		(at 88.653874 -153.542492)
		(size 0.508)
		(drill 0.254)
		(layers "F.Cu" "B.Cu")
		(net "P12V_AUX")
	)
	(via
		(at 435.430422 -42.285412)
		(size 0.508)
		(drill 0.254)
		(layers "F.Cu" "B.Cu")
		(net "P12V_AUX")
	)
	(via
		(at 237.846108 -381.305816)
		(size 0.508)
		(drill 0.254)
		(layers "F.Cu" "B.Cu")
		(net "P12V_AUX")
	)
	(via
		(at 47.131732 -359.67924)
		(size 0.508)
		(drill 0.254)
		(layers "F.Cu" "B.Cu")
		(net "P12V_AUX")
	)
	(via
		(at 271.330928 -380.035816)
		(size 0.508)
		(drill 0.254)
		(layers "F.Cu" "B.Cu")
		(net "P12V_AUX")
	)
	(via
		(at 276.630892 -381.305816)
		(size 0.508)
		(drill 0.254)
		(layers "F.Cu" "B.Cu")
		(net "P12V_AUX")
	)
	(via
		(at 450.681852 -425.92371)
		(size 0.508)
		(drill 0.254)
		(layers "F.Cu" "B.Cu")
		(net "P12V_AUX")
	)
	(via
		(at 93.56217 -354.45827)
		(size 0.508)
		(drill 0.254)
		(layers "F.Cu" "B.Cu")
		(net "P12V_AUX")
	)
	(via
		(at 146.06905 -114.620802)
		(size 0.508)
		(drill 0.254)
		(layers "F.Cu" "B.Cu")
		(net "P12V_AUX")
	)
	(via
		(at 266.030964 -380.670816)
		(size 0.508)
		(drill 0.254)
		(layers "F.Cu" "B.Cu")
		(net "P12V_AUX")
	)
	(via
		(at 338.965286 -359.787444)
		(size 0.508)
		(drill 0.254)
		(layers "F.Cu" "B.Cu")
		(net "P12V_AUX")
	)
	(via
		(at 120.835674 -144.559528)
		(size 0.508)
		(drill 0.254)
		(layers "F.Cu" "B.Cu")
		(net "P12V_AUX")
	)
	(via
		(at 117.559074 -146.337528)
		(size 0.508)
		(drill 0.254)
		(layers "F.Cu" "B.Cu")
		(net "P12V_AUX")
	)
	(via
		(at 86.367874 -157.327092)
		(size 0.508)
		(drill 0.254)
		(layers "F.Cu" "B.Cu")
		(net "P12V_AUX")
	)
	(via
		(at 438.173622 -41.650412)
		(size 0.508)
		(drill 0.254)
		(layers "F.Cu" "B.Cu")
		(net "P12V_AUX")
	)
	(via
		(at 251.23775 -269.604236)
		(size 0.508)
		(drill 0.254)
		(layers "F.Cu" "B.Cu")
		(net "P12V_AUX")
	)
	(via
		(at 90.060018 -352.46691)
		(size 0.508)
		(drill 0.254)
		(layers "F.Cu" "B.Cu")
		(net "P12V_AUX")
	)
	(via
		(at 90.177874 -157.327092)
		(size 0.508)
		(drill 0.254)
		(layers "F.Cu" "B.Cu")
		(net "P12V_AUX")
	)
	(via
		(at 446.009776 -27.552142)
		(size 0.508)
		(drill 0.254)
		(layers "F.Cu" "B.Cu")
		(net "P12V_AUX")
	)
	(via
		(at 224.175828 -273.071082)
		(size 0.508)
		(drill 0.254)
		(layers "F.Cu" "B.Cu")
		(net "P12V_AUX")
	)
	(via
		(at 381.758444 -153.019252)
		(size 0.508)
		(drill 0.254)
		(layers "F.Cu" "B.Cu")
		(net "P12V_AUX")
	)
	(via
		(at 188.043312 -431.387504)
		(size 0.508)
		(drill 0.254)
		(layers "F.Cu" "B.Cu")
		(net "P12V_AUX")
	)
	(via
		(at 200.1139 -396.019782)
		(size 0.508)
		(drill 0.254)
		(layers "F.Cu" "B.Cu")
		(net "P12V_AUX")
	)
	(via
		(at 90.939874 -155.828492)
		(size 0.508)
		(drill 0.254)
		(layers "F.Cu" "B.Cu")
		(net "P12V_AUX")
	)
	(via
		(at 275.360892 -379.400816)
		(size 0.508)
		(drill 0.254)
		(layers "F.Cu" "B.Cu")
		(net "P12V_AUX")
	)
	(via
		(at 267.935964 -379.400816)
		(size 0.508)
		(drill 0.254)
		(layers "F.Cu" "B.Cu")
		(net "P12V_AUX")
	)
	(via
		(at 23.729696 -405.373332)
		(size 0.508)
		(drill 0.254)
		(layers "F.Cu" "B.Cu")
		(net "P12V_AUX")
	)
	(via
		(at 15.557754 -199.445372)
		(size 0.508)
		(drill 0.254)
		(layers "F.Cu" "B.Cu")
		(net "P12V_AUX")
	)
	(via
		(at 265.395964 -378.765816)
		(size 0.508)
		(drill 0.254)
		(layers "F.Cu" "B.Cu")
		(net "P12V_AUX")
	)
	(via
		(at 188.666628 -398.143984)
		(size 0.508)
		(drill 0.254)
		(layers "F.Cu" "B.Cu")
		(net "P12V_AUX")
	)
	(via
		(at 366.701832 -155.182316)
		(size 0.508)
		(drill 0.254)
		(layers "F.Cu" "B.Cu")
		(net "P12V_AUX")
	)
	(via
		(at 342.608662 -359.121964)
		(size 0.508)
		(drill 0.254)
		(layers "F.Cu" "B.Cu")
		(net "P12V_AUX")
	)
	(via
		(at 443.894464 -27.869642)
		(size 0.4572)
		(drill 0.254)
		(layers "F.Cu" "B.Cu")
		(net "P12V_AUX")
	)
	(via
		(at 368.987832 -155.182316)
		(size 0.508)
		(drill 0.254)
		(layers "F.Cu" "B.Cu")
		(net "P12V_AUX")
	)
	(via
		(at 385.129278 -139.186158)
		(size 0.508)
		(drill 0.254)
		(layers "F.Cu" "B.Cu")
		(net "P12V_AUX")
	)
	(via
		(at 263.490964 -379.400816)
		(size 0.508)
		(drill 0.254)
		(layers "F.Cu" "B.Cu")
		(net "P12V_AUX")
	)
	(via
		(at 91.176856 -351.180908)
		(size 0.508)
		(drill 0.254)
		(layers "F.Cu" "B.Cu")
		(net "P12V_AUX")
	)
	(via
		(at 49.652682 -360.062272)
		(size 0.508)
		(drill 0.254)
		(layers "F.Cu" "B.Cu")
		(net "P12V_AUX")
	)
	(via
		(at 117.559074 -143.924528)
		(size 0.508)
		(drill 0.254)
		(layers "F.Cu" "B.Cu")
		(net "P12V_AUX")
	)
	(via
		(at 258.191 -378.765816)
		(size 0.508)
		(drill 0.254)
		(layers "F.Cu" "B.Cu")
		(net "P12V_AUX")
	)
	(via
		(at 275.360892 -378.765816)
		(size 0.508)
		(drill 0.254)
		(layers "F.Cu" "B.Cu")
		(net "P12V_AUX")
	)
	(via
		(at 119.464074 -145.194528)
		(size 0.508)
		(drill 0.254)
		(layers "F.Cu" "B.Cu")
		(net "P12V_AUX")
	)
	(via
		(at 267.300964 -378.765816)
		(size 0.508)
		(drill 0.254)
		(layers "F.Cu" "B.Cu")
		(net "P12V_AUX")
	)
	(via
		(at 436.751222 -41.015412)
		(size 0.508)
		(drill 0.254)
		(layers "F.Cu" "B.Cu")
		(net "P12V_AUX")
	)
	(via
		(at 458.597508 -180.58003)
		(size 0.508)
		(drill 0.254)
		(layers "F.Cu" "B.Cu")
		(net "P12V_AUX")
	)
	(via
		(at 200.8759 -396.781782)
		(size 0.508)
		(drill 0.254)
		(layers "F.Cu" "B.Cu")
		(net "P12V_AUX")
	)
	(via
		(at 239.116108 -380.035816)
		(size 0.508)
		(drill 0.254)
		(layers "F.Cu" "B.Cu")
		(net "P12V_AUX")
	)
	(via
		(at 231.3559 -399.067782)
		(size 0.508)
		(drill 0.254)
		(layers "F.Cu" "B.Cu")
		(net "P12V_AUX")
	)
	(via
		(at 46.496732 -362.85424)
		(size 0.508)
		(drill 0.254)
		(layers "F.Cu" "B.Cu")
		(net "P12V_AUX")
	)
	(via
		(at 116.187474 -145.829528)
		(size 0.508)
		(drill 0.254)
		(layers "F.Cu" "B.Cu")
		(net "P12V_AUX")
	)
	(via
		(at 87.305134 -157.060392)
		(size 0.508)
		(drill 0.254)
		(layers "F.Cu" "B.Cu")
		(net "P12V_AUX")
	)
	(via
		(at 372.797832 -158.230316)
		(size 0.508)
		(drill 0.254)
		(layers "F.Cu" "B.Cu")
		(net "P12V_AUX")
	)
	(via
		(at 285.60141 -364.151672)
		(size 0.508)
		(drill 0.254)
		(layers "F.Cu" "B.Cu")
		(net "P12V_AUX")
	)
	(via
		(at 251.99975 -270.505936)
		(size 0.508)
		(drill 0.254)
		(layers "F.Cu" "B.Cu")
		(net "P12V_AUX")
	)
	(via
		(at 232.1179 -395.257782)
		(size 0.508)
		(drill 0.254)
		(layers "F.Cu" "B.Cu")
		(net "P12V_AUX")
	)
	(via
		(at 450.430646 -415.782252)
		(size 0.508)
		(drill 0.254)
		(layers "F.Cu" "B.Cu")
		(net "P12V_AUX")
	)
	(via
		(at 185.618628 -397.381984)
		(size 0.508)
		(drill 0.254)
		(layers "F.Cu" "B.Cu")
		(net "P12V_AUX")
	)
	(via
		(at 88.61806 -103.91648)
		(size 0.508)
		(drill 0.254)
		(layers "F.Cu" "B.Cu")
		(net "P12V_AUX")
	)
	(via
		(at 254.691134 -41.858946)
		(size 0.508)
		(drill 0.254)
		(layers "F.Cu" "B.Cu")
		(net "P12V_AUX")
	)
	(via
		(at 46.496732 -360.94924)
		(size 0.508)
		(drill 0.254)
		(layers "F.Cu" "B.Cu")
		(net "P12V_AUX")
	)
	(via
		(at 368.987832 -154.420316)
		(size 0.508)
		(drill 0.254)
		(layers "F.Cu" "B.Cu")
		(net "P12V_AUX")
	)
	(via
		(at 289.61461 -364.151672)
		(size 0.508)
		(drill 0.254)
		(layers "F.Cu" "B.Cu")
		(net "P12V_AUX")
	)
	(via
		(at 379.129544 -154.370532)
		(size 0.508)
		(drill 0.254)
		(layers "F.Cu" "B.Cu")
		(net "P12V_AUX")
	)
	(via
		(at 409.39085 -133.2738)
		(size 0.508)
		(drill 0.254)
		(layers "F.Cu" "B.Cu")
		(net "P12V_AUX")
	)
	(via
		(at 252.256036 -379.400816)
		(size 0.508)
		(drill 0.254)
		(layers "F.Cu" "B.Cu")
		(net "P12V_AUX")
	)
	(via
		(at 92.446856 -351.180908)
		(size 0.508)
		(drill 0.254)
		(layers "F.Cu" "B.Cu")
		(net "P12V_AUX")
	)
	(via
		(at 23.03145 -404.058882)
		(size 0.508)
		(drill 0.254)
		(layers "F.Cu" "B.Cu")
		(net "P12V_AUX")
	)
	(via
		(at 345.061286 -358.474772)
		(size 0.508)
		(drill 0.254)
		(layers "F.Cu" "B.Cu")
		(net "P12V_AUX")
	)
	(via
		(at 233.6419 -395.257782)
		(size 0.508)
		(drill 0.254)
		(layers "F.Cu" "B.Cu")
		(net "P12V_AUX")
	)
	(via
		(at 372.035832 -156.706316)
		(size 0.508)
		(drill 0.254)
		(layers "F.Cu" "B.Cu")
		(net "P12V_AUX")
	)
	(via
		(at 200.1139 -399.067782)
		(size 0.508)
		(drill 0.254)
		(layers "F.Cu" "B.Cu")
		(net "P12V_AUX")
	)
	(via
		(at 198.5899 -398.305782)
		(size 0.508)
		(drill 0.254)
		(layers "F.Cu" "B.Cu")
		(net "P12V_AUX")
	)
	(via
		(at 188.666628 -397.381984)
		(size 0.508)
		(drill 0.254)
		(layers "F.Cu" "B.Cu")
		(net "P12V_AUX")
	)
	(via
		(at 371.273832 -158.230316)
		(size 0.508)
		(drill 0.254)
		(layers "F.Cu" "B.Cu")
		(net "P12V_AUX")
	)
	(via
		(at 239.116108 -380.670816)
		(size 0.508)
		(drill 0.254)
		(layers "F.Cu" "B.Cu")
		(net "P12V_AUX")
	)
	(via
		(at 50.287682 -361.332272)
		(size 0.508)
		(drill 0.254)
		(layers "F.Cu" "B.Cu")
		(net "P12V_AUX")
	)
	(via
		(at 120.200674 -144.559528)
		(size 0.508)
		(drill 0.254)
		(layers "F.Cu" "B.Cu")
		(net "P12V_AUX")
	)
	(via
		(at 442.662564 -358.917748)
		(size 0.508)
		(drill 0.254)
		(layers "F.Cu" "B.Cu")
		(net "P12V_AUX")
	)
	(via
		(at 449.387976 -28.898342)
		(size 0.508)
		(drill 0.254)
		(layers "F.Cu" "B.Cu")
		(net "P12V_AUX")
	)
	(via
		(at 442.662564 -361.559348)
		(size 0.508)
		(drill 0.254)
		(layers "F.Cu" "B.Cu")
		(net "P12V_AUX")
	)
	(via
		(at 232.1179 -399.067782)
		(size 0.508)
		(drill 0.254)
		(layers "F.Cu" "B.Cu")
		(net "P12V_AUX")
	)
	(via
		(at 276.630892 -380.670816)
		(size 0.508)
		(drill 0.254)
		(layers "F.Cu" "B.Cu")
		(net "P12V_AUX")
	)
	(via
		(at 458.587348 -177.94097)
		(size 0.508)
		(drill 0.254)
		(layers "F.Cu" "B.Cu")
		(net "P12V_AUX")
	)
	(via
		(at 221.889828 -271.407382)
		(size 0.508)
		(drill 0.254)
		(layers "F.Cu" "B.Cu")
		(net "P12V_AUX")
	)
	(via
		(at 251.621036 -379.400816)
		(size 0.508)
		(drill 0.254)
		(layers "F.Cu" "B.Cu")
		(net "P12V_AUX")
	)
	(via
		(at 182.990236 -34.312352)
		(size 0.508)
		(drill 0.254)
		(layers "F.Cu" "B.Cu")
		(net "P12V_AUX")
	)
	(via
		(at 291.01161 -361.58297)
		(size 0.508)
		(drill 0.254)
		(layers "F.Cu" "B.Cu")
		(net "P12V_AUX")
	)
	(via
		(at 289.61461 -362.246672)
		(size 0.508)
		(drill 0.254)
		(layers "F.Cu" "B.Cu")
		(net "P12V_AUX")
	)
	(via
		(at 118.194074 -145.194528)
		(size 0.508)
		(drill 0.254)
		(layers "F.Cu" "B.Cu")
		(net "P12V_AUX")
	)
	(via
		(at 212.3059 -399.067782)
		(size 0.508)
		(drill 0.254)
		(layers "F.Cu" "B.Cu")
		(net "P12V_AUX")
	)
	(via
		(at 88.602312 -354.429568)
		(size 0.508)
		(drill 0.254)
		(layers "F.Cu" "B.Cu")
		(net "P12V_AUX")
	)
	(via
		(at 233.6419 -397.543782)
		(size 0.508)
		(drill 0.254)
		(layers "F.Cu" "B.Cu")
		(net "P12V_AUX")
	)
	(via
		(at 289.61461 -363.516672)
		(size 0.508)
		(drill 0.254)
		(layers "F.Cu" "B.Cu")
		(net "P12V_AUX")
	)
	(via
		(at 343.547446 -360.430064)
		(size 0.508)
		(drill 0.254)
		(layers "F.Cu" "B.Cu")
		(net "P12V_AUX")
	)
	(via
		(at 247.591072 -381.305816)
		(size 0.508)
		(drill 0.254)
		(layers "F.Cu" "B.Cu")
		(net "P12V_AUX")
	)
	(via
		(at 440.122564 -358.917748)
		(size 0.508)
		(drill 0.254)
		(layers "F.Cu" "B.Cu")
		(net "P12V_AUX")
	)
	(via
		(at 434.668422 -39.694612)
		(size 0.508)
		(drill 0.254)
		(layers "F.Cu" "B.Cu")
		(net "P12V_AUX")
	)
	(via
		(at 91.701874 -154.304492)
		(size 0.508)
		(drill 0.254)
		(layers "F.Cu" "B.Cu")
		(net "P12V_AUX")
	)
	(via
		(at 437.688736 -23.701502)
		(size 0.508)
		(drill 0.254)
		(layers "F.Cu" "B.Cu")
		(net "P12V_AUX")
	)
	(via
		(at 221.4499 -396.019782)
		(size 0.508)
		(drill 0.254)
		(layers "F.Cu" "B.Cu")
		(net "P12V_AUX")
	)
	(via
		(at 451.795642 -415.771076)
		(size 0.508)
		(drill 0.254)
		(layers "F.Cu" "B.Cu")
		(net "P12V_AUX")
	)
	(via
		(at 197.8279 -396.781782)
		(size 0.508)
		(drill 0.254)
		(layers "F.Cu" "B.Cu")
		(net "P12V_AUX")
	)
	(via
		(at 266.665964 -378.765816)
		(size 0.508)
		(drill 0.254)
		(layers "F.Cu" "B.Cu")
		(net "P12V_AUX")
	)
	(via
		(at 257.045714 -48.010826)
		(size 0.508)
		(drill 0.254)
		(layers "F.Cu" "B.Cu")
		(net "P12V_AUX")
	)
	(via
		(at 186.380628 -397.381984)
		(size 0.508)
		(drill 0.254)
		(layers "F.Cu" "B.Cu")
		(net "P12V_AUX")
	)
	(via
		(at 338.983066 -361.070144)
		(size 0.508)
		(drill 0.254)
		(layers "F.Cu" "B.Cu")
		(net "P12V_AUX")
	)
	(via
		(at 242.926108 -379.400816)
		(size 0.508)
		(drill 0.254)
		(layers "F.Cu" "B.Cu")
		(net "P12V_AUX")
	)
	(via
		(at 371.273832 -156.706316)
		(size 0.508)
		(drill 0.254)
		(layers "F.Cu" "B.Cu")
		(net "P12V_AUX")
	)
	(via
		(at 180.238146 -360.647742)
		(size 0.508)
		(drill 0.254)
		(layers "F.Cu" "B.Cu")
		(net "P12V_AUX")
	)
	(via
		(at 88.653874 -155.066492)
		(size 0.508)
		(drill 0.254)
		(layers "F.Cu" "B.Cu")
		(net "P12V_AUX")
	)
	(via
		(at 49.652682 -361.332272)
		(size 0.508)
		(drill 0.254)
		(layers "F.Cu" "B.Cu")
		(net "P12V_AUX")
	)
	(via
		(at 457.698348 -178.57597)
		(size 0.508)
		(drill 0.254)
		(layers "F.Cu" "B.Cu")
		(net "P12V_AUX")
	)
	(via
		(at 257.358134 -41.858946)
		(size 0.508)
		(drill 0.254)
		(layers "F.Cu" "B.Cu")
		(net "P12V_AUX")
	)
	(via
		(at 257.766312 -65.77838)
		(size 0.508)
		(drill 0.254)
		(layers "F.Cu" "B.Cu")
		(net "P12V_AUX")
	)
	(via
		(at 201.6379 -399.067782)
		(size 0.508)
		(drill 0.254)
		(layers "F.Cu" "B.Cu")
		(net "P12V_AUX")
	)
	(via
		(at 275.995892 -381.305816)
		(size 0.508)
		(drill 0.254)
		(layers "F.Cu" "B.Cu")
		(net "P12V_AUX")
	)
	(via
		(at 84.843874 -157.327092)
		(size 0.508)
		(drill 0.254)
		(layers "F.Cu" "B.Cu")
		(net "P12V_AUX")
	)
	(via
		(at 90.541856 -351.180908)
		(size 0.508)
		(drill 0.254)
		(layers "F.Cu" "B.Cu")
		(net "P12V_AUX")
	)
	(via
		(at 223.7359 -396.019782)
		(size 0.508)
		(drill 0.254)
		(layers "F.Cu" "B.Cu")
		(net "P12V_AUX")
	)
	(via
		(at 221.4499 -396.781782)
		(size 0.508)
		(drill 0.254)
		(layers "F.Cu" "B.Cu")
		(net "P12V_AUX")
	)
	(via
		(at 257.556 -381.305816)
		(size 0.508)
		(drill 0.254)
		(layers "F.Cu" "B.Cu")
		(net "P12V_AUX")
	)
	(via
		(at 190.190628 -397.381984)
		(size 0.508)
		(drill 0.254)
		(layers "F.Cu" "B.Cu")
		(net "P12V_AUX")
	)
	(via
		(at 343.555066 -361.070144)
		(size 0.508)
		(drill 0.254)
		(layers "F.Cu" "B.Cu")
		(net "P12V_AUX")
	)
	(via
		(at 92.95892 -353.798124)
		(size 0.508)
		(drill 0.254)
		(layers "F.Cu" "B.Cu")
		(net "P12V_AUX")
	)
	(via
		(at 379.789944 -154.390852)
		(size 0.508)
		(drill 0.254)
		(layers "F.Cu" "B.Cu")
		(net "P12V_AUX")
	)
	(via
		(at 86.367874 -154.304492)
		(size 0.508)
		(drill 0.254)
		(layers "F.Cu" "B.Cu")
		(net "P12V_AUX")
	)
	(via
		(at 177.444146 -28.620212)
		(size 0.4572)
		(drill 0.254)
		(layers "F.Cu" "B.Cu")
		(net "P12V_AUX")
	)
	(via
		(at 380.488444 -153.019252)
		(size 0.508)
		(drill 0.254)
		(layers "F.Cu" "B.Cu")
		(net "P12V_AUX")
	)
	(via
		(at 457.698348 -179.84597)
		(size 0.508)
		(drill 0.254)
		(layers "F.Cu" "B.Cu")
		(net "P12V_AUX")
	)
	(via
		(at 436.751222 -42.285412)
		(size 0.508)
		(drill 0.254)
		(layers "F.Cu" "B.Cu")
		(net "P12V_AUX")
	)
	(via
		(at 211.276692 -130.889756)
		(size 0.508)
		(drill 0.254)
		(layers "F.Cu" "B.Cu")
		(net "P12V_AUX")
	)
	(via
		(at 212.3059 -398.305782)
		(size 0.508)
		(drill 0.254)
		(layers "F.Cu" "B.Cu")
		(net "P12V_AUX")
	)
	(via
		(at 211.5439 -397.543782)
		(size 0.508)
		(drill 0.254)
		(layers "F.Cu" "B.Cu")
		(net "P12V_AUX")
	)
	(via
		(at 442.094366 -28.504642)
		(size 0.4572)
		(drill 0.254)
		(layers "F.Cu" "B.Cu")
		(net "P12V_AUX")
	)
	(via
		(at 365.939832 -155.182316)
		(size 0.508)
		(drill 0.254)
		(layers "F.Cu" "B.Cu")
		(net "P12V_AUX")
	)
	(via
		(at 177.673 -408.559)
		(size 0.508)
		(drill 0.254)
		(layers "F.Cu" "B.Cu")
		(net "P12V_AUX")
	)
	(via
		(at 180.238146 -359.911142)
		(size 0.508)
		(drill 0.254)
		(layers "F.Cu" "B.Cu")
		(net "P12V_AUX")
	)
	(via
		(at 408.728164 -133.2738)
		(size 0.508)
		(drill 0.254)
		(layers "F.Cu" "B.Cu")
		(net "P12V_AUX")
	)
	(via
		(at 372.035832 -158.230316)
		(size 0.508)
		(drill 0.254)
		(layers "F.Cu" "B.Cu")
		(net "P12V_AUX")
	)
	(via
		(at 247.591072 -380.670816)
		(size 0.508)
		(drill 0.254)
		(layers "F.Cu" "B.Cu")
		(net "P12V_AUX")
	)
	(via
		(at 222.2119 -399.067782)
		(size 0.508)
		(drill 0.254)
		(layers "F.Cu" "B.Cu")
		(net "P12V_AUX")
	)
	(via
		(at 221.889828 -270.645382)
		(size 0.508)
		(drill 0.254)
		(layers "F.Cu" "B.Cu")
		(net "P12V_AUX")
	)
	(via
		(at 48.382682 -360.062272)
		(size 0.508)
		(drill 0.254)
		(layers "F.Cu" "B.Cu")
		(net "P12V_AUX")
	)
	(via
		(at 210.7819 -396.019782)
		(size 0.508)
		(drill 0.254)
		(layers "F.Cu" "B.Cu")
		(net "P12V_AUX")
	)
	(via
		(at 223.413828 -269.743682)
		(size 0.508)
		(drill 0.254)
		(layers "F.Cu" "B.Cu")
		(net "P12V_AUX")
	)
	(via
		(at 286.23641 -363.516672)
		(size 0.508)
		(drill 0.254)
		(layers "F.Cu" "B.Cu")
		(net "P12V_AUX")
	)
	(via
		(at 116.822474 -144.559528)
		(size 0.508)
		(drill 0.254)
		(layers "F.Cu" "B.Cu")
		(net "P12V_AUX")
	)
	(via
		(at 340.489286 -359.787444)
		(size 0.508)
		(drill 0.254)
		(layers "F.Cu" "B.Cu")
		(net "P12V_AUX")
	)
	(via
		(at 232.8799 -396.781782)
		(size 0.508)
		(drill 0.254)
		(layers "F.Cu" "B.Cu")
		(net "P12V_AUX")
	)
	(via
		(at 372.797832 -156.706316)
		(size 0.508)
		(drill 0.254)
		(layers "F.Cu" "B.Cu")
		(net "P12V_AUX")
	)
	(via
		(at 270.695928 -380.035816)
		(size 0.508)
		(drill 0.254)
		(layers "F.Cu" "B.Cu")
		(net "P12V_AUX")
	)
	(via
		(at 458.587348 -179.21097)
		(size 0.508)
		(drill 0.254)
		(layers "F.Cu" "B.Cu")
		(net "P12V_AUX")
	)
	(via
		(at 256.066036 -378.765816)
		(size 0.508)
		(drill 0.254)
		(layers "F.Cu" "B.Cu")
		(net "P12V_AUX")
	)
	(via
		(at 338.203286 -359.787444)
		(size 0.508)
		(drill 0.254)
		(layers "F.Cu" "B.Cu")
		(net "P12V_AUX")
	)
	(via
		(at 138.12012 -74.718672)
		(size 0.508)
		(drill 0.254)
		(layers "F.Cu" "B.Cu")
		(net "P12V_AUX")
	)
	(via
		(at 88.636856 -352.450908)
		(size 0.508)
		(drill 0.254)
		(layers "F.Cu" "B.Cu")
		(net "P12V_AUX")
	)
	(via
		(at 47.766732 -359.67924)
		(size 0.508)
		(drill 0.254)
		(layers "F.Cu" "B.Cu")
		(net "P12V_AUX")
	)
	(via
		(at 257.556 -380.035816)
		(size 0.508)
		(drill 0.254)
		(layers "F.Cu" "B.Cu")
		(net "P12V_AUX")
	)
	(via
		(at 116.187474 -144.559528)
		(size 0.508)
		(drill 0.254)
		(layers "F.Cu" "B.Cu")
		(net "P12V_AUX")
	)
	(via
		(at 262.636 -379.400816)
		(size 0.508)
		(drill 0.254)
		(layers "F.Cu" "B.Cu")
		(net "P12V_AUX")
	)
	(via
		(at 240.386108 -380.035816)
		(size 0.508)
		(drill 0.254)
		(layers "F.Cu" "B.Cu")
		(net "P12V_AUX")
	)
	(via
		(at 230.5939 -396.781782)
		(size 0.508)
		(drill 0.254)
		(layers "F.Cu" "B.Cu")
		(net "P12V_AUX")
	)
	(via
		(at 379.193044 -156.440632)
		(size 0.508)
		(drill 0.254)
		(layers "F.Cu" "B.Cu")
		(net "P12V_AUX")
	)
	(via
		(at 180.238146 -362.552742)
		(size 0.508)
		(drill 0.254)
		(layers "F.Cu" "B.Cu")
		(net "P12V_AUX")
	)
	(via
		(at 211.5439 -396.019782)
		(size 0.508)
		(drill 0.254)
		(layers "F.Cu" "B.Cu")
		(net "P12V_AUX")
	)
	(via
		(at 339.745066 -361.070144)
		(size 0.508)
		(drill 0.254)
		(layers "F.Cu" "B.Cu")
		(net "P12V_AUX")
	)
	(via
		(at 118.829074 -145.194528)
		(size 0.508)
		(drill 0.254)
		(layers "F.Cu" "B.Cu")
		(net "P12V_AUX")
	)
	(via
		(at 443.894464 -28.504642)
		(size 0.4572)
		(drill 0.254)
		(layers "F.Cu" "B.Cu")
		(net "P12V_AUX")
	)
	(via
		(at 338.955126 -359.112312)
		(size 0.508)
		(drill 0.254)
		(layers "F.Cu" "B.Cu")
		(net "P12V_AUX")
	)
	(via
		(at 253.544324 -50.73269)
		(size 0.4572)
		(drill 0.254)
		(layers "F.Cu" "B.Cu")
		(net "P12V_AUX")
	)
	(via
		(at 208.4959 -395.257782)
		(size 0.762)
		(drill 0.254)
		(layers "F.Cu" "B.Cu")
		(net "P12V_AUX")
	)
	(via
		(at 237.846108 -379.400816)
		(size 0.508)
		(drill 0.254)
		(layers "F.Cu" "B.Cu")
		(net "P12V_AUX")
	)
	(via
		(at 369.749832 -154.420316)
		(size 0.508)
		(drill 0.254)
		(layers "F.Cu" "B.Cu")
		(net "P12V_AUX")
	)
	(via
		(at 222.2119 -395.257782)
		(size 0.508)
		(drill 0.254)
		(layers "F.Cu" "B.Cu")
		(net "P12V_AUX")
	)
	(via
		(at 68.321174 -27.573224)
		(size 0.4572)
		(drill 0.254)
		(layers "F.Cu" "B.Cu")
		(net "P12V_AUX")
	)
	(via
		(at 340.696042 -358.045004)
		(size 0.508)
		(drill 0.254)
		(layers "F.Cu" "B.Cu")
		(net "P12V_AUX")
	)
	(via
		(at 257.556 -379.400816)
		(size 0.508)
		(drill 0.254)
		(layers "F.Cu" "B.Cu")
		(net "P12V_AUX")
	)
	(via
		(at 90.127328 -353.539044)
		(size 0.508)
		(drill 0.254)
		(layers "F.Cu" "B.Cu")
		(net "P12V_AUX")
	)
	(via
		(at 460.365348 -178.57597)
		(size 0.508)
		(drill 0.254)
		(layers "F.Cu" "B.Cu")
		(net "P12V_AUX")
	)
	(via
		(at 341.973662 -359.121964)
		(size 0.508)
		(drill 0.254)
		(layers "F.Cu" "B.Cu")
		(net "P12V_AUX")
	)
	(via
		(at 249.015758 -54.79796)
		(size 0.508)
		(drill 0.254)
		(layers "F.Cu" "B.Cu")
		(net "P12V_AUX")
	)
	(via
		(at 339.727286 -359.787444)
		(size 0.508)
		(drill 0.254)
		(layers "F.Cu" "B.Cu")
		(net "P12V_AUX")
	)
	(via
		(at 223.7359 -396.781782)
		(size 0.508)
		(drill 0.254)
		(layers "F.Cu" "B.Cu")
		(net "P12V_AUX")
	)
	(via
		(at 288.86785 -361.731052)
		(size 0.508)
		(drill 0.254)
		(layers "F.Cu" "B.Cu")
		(net "P12V_AUX")
	)
	(via
		(at 286.97301 -362.411772)
		(size 0.508)
		(drill 0.254)
		(layers "F.Cu" "B.Cu")
		(net "P12V_AUX")
	)
	(via
		(at 257.784854 -48.081946)
		(size 0.508)
		(drill 0.254)
		(layers "F.Cu" "B.Cu")
		(net "P12V_AUX")
	)
	(via
		(at 442.027564 -358.917748)
		(size 0.508)
		(drill 0.254)
		(layers "F.Cu" "B.Cu")
		(net "P12V_AUX")
	)
	(via
		(at 408.728164 -133.9342)
		(size 0.508)
		(drill 0.254)
		(layers "F.Cu" "B.Cu")
		(net "P12V_AUX")
	)
	(via
		(at 190.190628 -396.619984)
		(size 0.508)
		(drill 0.254)
		(layers "F.Cu" "B.Cu")
		(net "P12V_AUX")
	)
	(via
		(at 380.488444 -157.095952)
		(size 0.508)
		(drill 0.254)
		(layers "F.Cu" "B.Cu")
		(net "P12V_AUX")
	)
	(via
		(at 51.54803 -359.64114)
		(size 0.508)
		(drill 0.254)
		(layers "F.Cu" "B.Cu")
		(net "P12V_AUX")
	)
	(via
		(at 90.177874 -154.304492)
		(size 0.508)
		(drill 0.254)
		(layers "F.Cu" "B.Cu")
		(net "P12V_AUX")
	)
	(via
		(at 343.537286 -357.839772)
		(size 0.508)
		(drill 0.254)
		(layers "F.Cu" "B.Cu")
		(net "P12V_AUX")
	)
	(via
		(at 189.428628 -397.381984)
		(size 0.508)
		(drill 0.254)
		(layers "F.Cu" "B.Cu")
		(net "P12V_AUX")
	)
	(via
		(at 252.256036 -378.765816)
		(size 0.508)
		(drill 0.254)
		(layers "F.Cu" "B.Cu")
		(net "P12V_AUX")
	)
	(via
		(at 199.3519 -396.781782)
		(size 0.508)
		(drill 0.254)
		(layers "F.Cu" "B.Cu")
		(net "P12V_AUX")
	)
	(via
		(at 247.591072 -378.765816)
		(size 0.508)
		(drill 0.254)
		(layers "F.Cu" "B.Cu")
		(net "P12V_AUX")
	)
	(via
		(at 8.932418 -406.119584)
		(size 0.508)
		(drill 0.254)
		(layers "F.Cu" "B.Cu")
		(net "P12V_AUX")
	)
	(via
		(at 84.173314 -157.327092)
		(size 0.508)
		(drill 0.254)
		(layers "F.Cu" "B.Cu")
		(net "P12V_AUX")
	)
	(via
		(at 259.054854 -45.668946)
		(size 0.508)
		(drill 0.254)
		(layers "F.Cu" "B.Cu")
		(net "P12V_AUX")
	)
	(via
		(at 441.392564 -358.917748)
		(size 0.508)
		(drill 0.254)
		(layers "F.Cu" "B.Cu")
		(net "P12V_AUX")
	)
	(via
		(at 242.291108 -381.305816)
		(size 0.508)
		(drill 0.254)
		(layers "F.Cu" "B.Cu")
		(net "P12V_AUX")
	)
	(via
		(at 79.007462 -27.204924)
		(size 0.508)
		(drill 0.254)
		(layers "F.Cu" "B.Cu")
		(net "P12V_AUX")
	)
	(via
		(at 89.271856 -350.545908)
		(size 0.508)
		(drill 0.254)
		(layers "F.Cu" "B.Cu")
		(net "P12V_AUX")
	)
	(via
		(at 263.490964 -380.670816)
		(size 0.508)
		(drill 0.254)
		(layers "F.Cu" "B.Cu")
		(net "P12V_AUX")
	)
	(via
		(at 180.238146 -359.276142)
		(size 0.508)
		(drill 0.254)
		(layers "F.Cu" "B.Cu")
		(net "P12V_AUX")
	)
	(via
		(at 442.027564 -360.924348)
		(size 0.508)
		(drill 0.254)
		(layers "F.Cu" "B.Cu")
		(net "P12V_AUX")
	)
	(via
		(at 89.271856 -351.815908)
		(size 0.508)
		(drill 0.254)
		(layers "F.Cu" "B.Cu")
		(net "P12V_AUX")
	)
	(via
		(at 255.564894 -48.010826)
		(size 0.508)
		(drill 0.254)
		(layers "F.Cu" "B.Cu")
		(net "P12V_AUX")
	)
	(via
		(at 263.490964 -380.035816)
		(size 0.508)
		(drill 0.254)
		(layers "F.Cu" "B.Cu")
		(net "P12V_AUX")
	)
	(via
		(at 381.123444 -153.019252)
		(size 0.508)
		(drill 0.254)
		(layers "F.Cu" "B.Cu")
		(net "P12V_AUX")
	)
	(via
		(at 270.060928 -378.765816)
		(size 0.508)
		(drill 0.254)
		(layers "F.Cu" "B.Cu")
		(net "P12V_AUX")
	)
	(via
		(at 90.177874 -155.066492)
		(size 0.508)
		(drill 0.254)
		(layers "F.Cu" "B.Cu")
		(net "P12V_AUX")
	)
	(via
		(at 288.87801 -362.411772)
		(size 0.508)
		(drill 0.254)
		(layers "F.Cu" "B.Cu")
		(net "P12V_AUX")
	)
	(via
		(at 254.161036 -380.035816)
		(size 0.508)
		(drill 0.254)
		(layers "F.Cu" "B.Cu")
		(net "P12V_AUX")
	)
	(via
		(at 453.172576 -28.237942)
		(size 0.508)
		(drill 0.254)
		(layers "F.Cu" "B.Cu")
		(net "P12V_AUX")
	)
	(via
		(at 85.605874 -155.828492)
		(size 0.508)
		(drill 0.254)
		(layers "F.Cu" "B.Cu")
		(net "P12V_AUX")
	)
	(via
		(at 91.330018 -352.46691)
		(size 0.508)
		(drill 0.254)
		(layers "F.Cu" "B.Cu")
		(net "P12V_AUX")
	)
	(via
		(at 205.197964 -347.770958)
		(size 0.508)
		(drill 0.254)
		(layers "F.Cu" "B.Cu")
		(net "P12V_AUX")
	)
	(via
		(at 341.331042 -358.045004)
		(size 0.508)
		(drill 0.254)
		(layers "F.Cu" "B.Cu")
		(net "P12V_AUX")
	)
	(via
		(at 343.537286 -359.109772)
		(size 0.508)
		(drill 0.254)
		(layers "F.Cu" "B.Cu")
		(net "P12V_AUX")
	)
	(via
		(at 240.386108 -381.305816)
		(size 0.508)
		(drill 0.254)
		(layers "F.Cu" "B.Cu")
		(net "P12V_AUX")
	)
	(via
		(at 241.021108 -381.305816)
		(size 0.508)
		(drill 0.254)
		(layers "F.Cu" "B.Cu")
		(net "P12V_AUX")
	)
	(via
		(at 118.829074 -146.337528)
		(size 0.508)
		(drill 0.254)
		(layers "F.Cu" "B.Cu")
		(net "P12V_AUX")
	)
	(via
		(at 336.697066 -360.419904)
		(size 0.508)
		(drill 0.254)
		(layers "F.Cu" "B.Cu")
		(net "P12V_AUX")
	)
	(via
		(at 197.8279 -395.257782)
		(size 0.762)
		(drill 0.254)
		(layers "F.Cu" "B.Cu")
		(net "P12V_AUX")
	)
	(via
		(at 239.751108 -380.035816)
		(size 0.508)
		(drill 0.254)
		(layers "F.Cu" "B.Cu")
		(net "P12V_AUX")
	)
	(via
		(at 25.787096 -405.398732)
		(size 0.508)
		(drill 0.254)
		(layers "F.Cu" "B.Cu")
		(net "P12V_AUX")
	)
	(via
		(at 289.60445 -361.565952)
		(size 0.508)
		(drill 0.254)
		(layers "F.Cu" "B.Cu")
		(net "P12V_AUX")
	)
	(via
		(at 202.3999 -396.781782)
		(size 0.508)
		(drill 0.254)
		(layers "F.Cu" "B.Cu")
		(net "P12V_AUX")
	)
	(via
		(at 181.847236 -29.841952)
		(size 0.508)
		(drill 0.254)
		(layers "F.Cu" "B.Cu")
		(net "P12V_AUX")
	)
	(via
		(at 219.9259 -397.543782)
		(size 0.508)
		(drill 0.254)
		(layers "F.Cu" "B.Cu")
		(net "P12V_AUX")
	)
	(via
		(at 247.591072 -380.035816)
		(size 0.508)
		(drill 0.254)
		(layers "F.Cu" "B.Cu")
		(net "P12V_AUX")
	)
	(via
		(at 344.299286 -359.787444)
		(size 0.508)
		(drill 0.254)
		(layers "F.Cu" "B.Cu")
		(net "P12V_AUX")
	)
	(via
		(at 90.939874 -155.066492)
		(size 0.508)
		(drill 0.254)
		(layers "F.Cu" "B.Cu")
		(net "P12V_AUX")
	)
	(via
		(at 187.904628 -398.143984)
		(size 0.508)
		(drill 0.254)
		(layers "F.Cu" "B.Cu")
		(net "P12V_AUX")
	)
	(via
		(at 212.3059 -395.257782)
		(size 0.508)
		(drill 0.254)
		(layers "F.Cu" "B.Cu")
		(net "P12V_AUX")
	)
	(via
		(at 266.030964 -378.765816)
		(size 0.508)
		(drill 0.254)
		(layers "F.Cu" "B.Cu")
		(net "P12V_AUX")
	)
	(via
		(at 119.464074 -144.559528)
		(size 0.508)
		(drill 0.254)
		(layers "F.Cu" "B.Cu")
		(net "P12V_AUX")
	)
	(via
		(at 71.336662 -27.255724)
		(size 0.508)
		(drill 0.254)
		(layers "F.Cu" "B.Cu")
		(net "P12V_AUX")
	)
	(via
		(at 271.965928 -378.765816)
		(size 0.508)
		(drill 0.254)
		(layers "F.Cu" "B.Cu")
		(net "P12V_AUX")
	)
	(via
		(at 459.476348 -179.21097)
		(size 0.508)
		(drill 0.254)
		(layers "F.Cu" "B.Cu")
		(net "P12V_AUX")
	)
	(via
		(at 459.486508 -181.85003)
		(size 0.508)
		(drill 0.254)
		(layers "F.Cu" "B.Cu")
		(net "P12V_AUX")
	)
	(via
		(at 92.911168 -354.458778)
		(size 0.508)
		(drill 0.254)
		(layers "F.Cu" "B.Cu")
		(net "P12V_AUX")
	)
	(via
		(at 285.60141 -363.516672)
		(size 0.508)
		(drill 0.254)
		(layers "F.Cu" "B.Cu")
		(net "P12V_AUX")
	)
	(via
		(at 254.161036 -379.400816)
		(size 0.508)
		(drill 0.254)
		(layers "F.Cu" "B.Cu")
		(net "P12V_AUX")
	)
	(via
		(at 372.035832 -155.182316)
		(size 0.508)
		(drill 0.254)
		(layers "F.Cu" "B.Cu")
		(net "P12V_AUX")
	)
	(via
		(at 84.843874 -155.066492)
		(size 0.508)
		(drill 0.254)
		(layers "F.Cu" "B.Cu")
		(net "P12V_AUX")
	)
	(via
		(at 220.6879 -397.543782)
		(size 0.508)
		(drill 0.254)
		(layers "F.Cu" "B.Cu")
		(net "P12V_AUX")
	)
	(via
		(at 270.060928 -380.035816)
		(size 0.508)
		(drill 0.254)
		(layers "F.Cu" "B.Cu")
		(net "P12V_AUX")
	)
	(via
		(at 277.265892 -381.305816)
		(size 0.508)
		(drill 0.254)
		(layers "F.Cu" "B.Cu")
		(net "P12V_AUX")
	)
	(via
		(at 446.517776 -29.660342)
		(size 0.508)
		(drill 0.254)
		(layers "F.Cu" "B.Cu")
		(net "P12V_AUX")
	)
	(via
		(at 79.007462 -28.652724)
		(size 0.508)
		(drill 0.254)
		(layers "F.Cu" "B.Cu")
		(net "P12V_AUX")
	)
	(via
		(at 185.618628 -396.619984)
		(size 0.508)
		(drill 0.254)
		(layers "F.Cu" "B.Cu")
		(net "P12V_AUX")
	)
	(via
		(at 87.366856 -353.720908)
		(size 0.508)
		(drill 0.254)
		(layers "F.Cu" "B.Cu")
		(net "P12V_AUX")
	)
	(via
		(at 275.995892 -380.035816)
		(size 0.508)
		(drill 0.254)
		(layers "F.Cu" "B.Cu")
		(net "P12V_AUX")
	)
	(via
		(at 258.826 -380.035816)
		(size 0.508)
		(drill 0.254)
		(layers "F.Cu" "B.Cu")
		(net "P12V_AUX")
	)
	(via
		(at 342.013286 -359.787444)
		(size 0.508)
		(drill 0.254)
		(layers "F.Cu" "B.Cu")
		(net "P12V_AUX")
	)
	(via
		(at 437.411622 -41.015412)
		(size 0.508)
		(drill 0.254)
		(layers "F.Cu" "B.Cu")
		(net "P12V_AUX")
	)
	(via
		(at 460.375508 -180.58003)
		(size 0.508)
		(drill 0.254)
		(layers "F.Cu" "B.Cu")
		(net "P12V_AUX")
	)
	(via
		(at 220.6879 -396.781782)
		(size 0.508)
		(drill 0.254)
		(layers "F.Cu" "B.Cu")
		(net "P12V_AUX")
	)
	(via
		(at 90.695018 -352.46691)
		(size 0.508)
		(drill 0.254)
		(layers "F.Cu" "B.Cu")
		(net "P12V_AUX")
	)
	(via
		(at 258.826 -378.765816)
		(size 0.508)
		(drill 0.254)
		(layers "F.Cu" "B.Cu")
		(net "P12V_AUX")
	)
	(via
		(at 440.757564 -358.917748)
		(size 0.508)
		(drill 0.254)
		(layers "F.Cu" "B.Cu")
		(net "P12V_AUX")
	)
	(via
		(at 440.757564 -362.295948)
		(size 0.508)
		(drill 0.254)
		(layers "F.Cu" "B.Cu")
		(net "P12V_AUX")
	)
	(via
		(at 210.0199 -399.067782)
		(size 0.508)
		(drill 0.254)
		(layers "F.Cu" "B.Cu")
		(net "P12V_AUX")
	)
	(via
		(at 186.380628 -395.095984)
		(size 0.508)
		(drill 0.254)
		(layers "F.Cu" "B.Cu")
		(net "P12V_AUX")
	)
	(via
		(at 342.793066 -361.070144)
		(size 0.508)
		(drill 0.254)
		(layers "F.Cu" "B.Cu")
		(net "P12V_AUX")
	)
	(via
		(at 269.425928 -380.035816)
		(size 0.508)
		(drill 0.254)
		(layers "F.Cu" "B.Cu")
		(net "P12V_AUX")
	)
	(via
		(at 84.709508 -152.404826)
		(size 0.508)
		(drill 0.254)
		(layers "F.Cu" "B.Cu")
		(net "P12V_AUX")
	)
	(via
		(at 90.730832 -354.386642)
		(size 0.508)
		(drill 0.254)
		(layers "F.Cu" "B.Cu")
		(net "P12V_AUX")
	)
	(via
		(at 242.291108 -379.400816)
		(size 0.508)
		(drill 0.254)
		(layers "F.Cu" "B.Cu")
		(net "P12V_AUX")
	)
	(via
		(at 264.125964 -379.400816)
		(size 0.508)
		(drill 0.254)
		(layers "F.Cu" "B.Cu")
		(net "P12V_AUX")
	)
	(via
		(at 116.00688 -72.430132)
		(size 0.508)
		(drill 0.254)
		(layers "F.Cu" "B.Cu")
		(net "P12V_AUX")
	)
	(via
		(at 14.922754 -199.445372)
		(size 0.508)
		(drill 0.254)
		(layers "F.Cu" "B.Cu")
		(net "P12V_AUX")
	)
	(via
		(at 442.027564 -360.289348)
		(size 0.508)
		(drill 0.254)
		(layers "F.Cu" "B.Cu")
		(net "P12V_AUX")
	)
	(via
		(at 286.98063 -363.488732)
		(size 0.508)
		(drill 0.254)
		(layers "F.Cu" "B.Cu")
		(net "P12V_AUX")
	)
	(via
		(at 50.287682 -360.697272)
		(size 0.508)
		(drill 0.254)
		(layers "F.Cu" "B.Cu")
		(net "P12V_AUX")
	)
	(via
		(at 287.60801 -364.151672)
		(size 0.508)
		(drill 0.254)
		(layers "F.Cu" "B.Cu")
		(net "P12V_AUX")
	)
	(via
		(at 451.109842 -415.110676)
		(size 0.508)
		(drill 0.254)
		(layers "F.Cu" "B.Cu")
		(net "P12V_AUX")
	)
	(via
		(at 71.336662 -27.916124)
		(size 0.508)
		(drill 0.254)
		(layers "F.Cu" "B.Cu")
		(net "P12V_AUX")
	)
	(via
		(at 89.25306 -104.55148)
		(size 0.508)
		(drill 0.254)
		(layers "F.Cu" "B.Cu")
		(net "P12V_AUX")
	)
	(via
		(at 366.701832 -157.468316)
		(size 0.508)
		(drill 0.254)
		(layers "F.Cu" "B.Cu")
		(net "P12V_AUX")
	)
	(via
		(at 239.751108 -380.670816)
		(size 0.508)
		(drill 0.254)
		(layers "F.Cu" "B.Cu")
		(net "P12V_AUX")
	)
	(via
		(at 277.265892 -378.765816)
		(size 0.508)
		(drill 0.254)
		(layers "F.Cu" "B.Cu")
		(net "P12V_AUX")
	)
	(via
		(at 457.698348 -179.21097)
		(size 0.508)
		(drill 0.254)
		(layers "F.Cu" "B.Cu")
		(net "P12V_AUX")
	)
	(via
		(at 199.3519 -398.305782)
		(size 0.508)
		(drill 0.254)
		(layers "F.Cu" "B.Cu")
		(net "P12V_AUX")
	)
	(via
		(at 409.39085 -133.9342)
		(size 0.508)
		(drill 0.254)
		(layers "F.Cu" "B.Cu")
		(net "P12V_AUX")
	)
	(via
		(at 197.8279 -396.019782)
		(size 0.508)
		(drill 0.254)
		(layers "F.Cu" "B.Cu")
		(net "P12V_AUX")
	)
	(via
		(at 461.567784 -40.626538)
		(size 0.508)
		(drill 0.254)
		(layers "F.Cu" "B.Cu")
		(net "P12V_AUX")
	)
	(via
		(at 238.481108 -378.765816)
		(size 0.508)
		(drill 0.254)
		(layers "F.Cu" "B.Cu")
		(net "P12V_AUX")
	)
	(via
		(at 380.488444 -155.660852)
		(size 0.508)
		(drill 0.254)
		(layers "F.Cu" "B.Cu")
		(net "P12V_AUX")
	)
	(via
		(at 251.99975 -272.931636)
		(size 0.508)
		(drill 0.254)
		(layers "F.Cu" "B.Cu")
		(net "P12V_AUX")
	)
	(via
		(at 89.415874 -153.542492)
		(size 0.508)
		(drill 0.254)
		(layers "F.Cu" "B.Cu")
		(net "P12V_AUX")
	)
	(via
		(at 46.496732 -360.31424)
		(size 0.508)
		(drill 0.254)
		(layers "F.Cu" "B.Cu")
		(net "P12V_AUX")
	)
	(via
		(at 187.142628 -396.619984)
		(size 0.508)
		(drill 0.254)
		(layers "F.Cu" "B.Cu")
		(net "P12V_AUX")
	)
	(via
		(at 210.7819 -396.781782)
		(size 0.508)
		(drill 0.254)
		(layers "F.Cu" "B.Cu")
		(net "P12V_AUX")
	)
	(via
		(at 245.686072 -378.765816)
		(size 0.508)
		(drill 0.254)
		(layers "F.Cu" "B.Cu")
		(net "P12V_AUX")
	)
	(via
		(at 185.399172 -23.113492)
		(size 0.508)
		(drill 0.254)
		(layers "F.Cu" "B.Cu")
		(net "P12V_AUX")
	)
	(via
		(at 442.027564 -361.559348)
		(size 0.508)
		(drill 0.254)
		(layers "F.Cu" "B.Cu")
		(net "P12V_AUX")
	)
	(via
		(at 370.511832 -154.420316)
		(size 0.508)
		(drill 0.254)
		(layers "F.Cu" "B.Cu")
		(net "P12V_AUX")
	)
	(via
		(at 270.060928 -381.305816)
		(size 0.508)
		(drill 0.254)
		(layers "F.Cu" "B.Cu")
		(net "P12V_AUX")
	)
	(via
		(at 290.24961 -362.881672)
		(size 0.508)
		(drill 0.254)
		(layers "F.Cu" "B.Cu")
		(net "P12V_AUX")
	)
	(via
		(at 254.161036 -380.670816)
		(size 0.508)
		(drill 0.254)
		(layers "F.Cu" "B.Cu")
		(net "P12V_AUX")
	)
	(via
		(at 369.046252 -156.810456)
		(size 0.508)
		(drill 0.254)
		(layers "F.Cu" "B.Cu")
		(net "P12V_AUX")
	)
	(via
		(at 271.330928 -379.400816)
		(size 0.508)
		(drill 0.254)
		(layers "F.Cu" "B.Cu")
		(net "P12V_AUX")
	)
	(via
		(at 250.47575 -269.604236)
		(size 0.508)
		(drill 0.254)
		(layers "F.Cu" "B.Cu")
		(net "P12V_AUX")
	)
	(via
		(at 246.321072 -378.765816)
		(size 0.508)
		(drill 0.254)
		(layers "F.Cu" "B.Cu")
		(net "P12V_AUX")
	)
	(via
		(at 252.891036 -378.765816)
		(size 0.508)
		(drill 0.254)
		(layers "F.Cu" "B.Cu")
		(net "P12V_AUX")
	)
	(via
		(at 47.131732 -362.21924)
		(size 0.508)
		(drill 0.254)
		(layers "F.Cu" "B.Cu")
		(net "P12V_AUX")
	)
	(via
		(at 435.430422 -40.355012)
		(size 0.508)
		(drill 0.254)
		(layers "F.Cu" "B.Cu")
		(net "P12V_AUX")
	)
	(via
		(at 120.835674 -146.464528)
		(size 0.508)
		(drill 0.254)
		(layers "F.Cu" "B.Cu")
		(net "P12V_AUX")
	)
	(via
		(at 120.200674 -146.464528)
		(size 0.508)
		(drill 0.254)
		(layers "F.Cu" "B.Cu")
		(net "P12V_AUX")
	)
	(via
		(at 254.796036 -379.400816)
		(size 0.508)
		(drill 0.254)
		(layers "F.Cu" "B.Cu")
		(net "P12V_AUX")
	)
	(via
		(at 200.8759 -397.543782)
		(size 0.508)
		(drill 0.254)
		(layers "F.Cu" "B.Cu")
		(net "P12V_AUX")
	)
	(via
		(at 288.25063 -363.488732)
		(size 0.508)
		(drill 0.254)
		(layers "F.Cu" "B.Cu")
		(net "P12V_AUX")
	)
	(via
		(at 259.461 -381.305816)
		(size 0.508)
		(drill 0.254)
		(layers "F.Cu" "B.Cu")
		(net "P12V_AUX")
	)
	(via
		(at 93.081856 -350.545908)
		(size 0.508)
		(drill 0.254)
		(layers "F.Cu" "B.Cu")
		(net "P12V_AUX")
	)
	(via
		(at 241.021108 -379.400816)
		(size 0.508)
		(drill 0.254)
		(layers "F.Cu" "B.Cu")
		(net "P12V_AUX")
	)
	(via
		(at 460.365348 -177.30597)
		(size 0.508)
		(drill 0.254)
		(layers "F.Cu" "B.Cu")
		(net "P12V_AUX")
	)
	(via
		(at 223.7359 -395.257782)
		(size 0.508)
		(drill 0.254)
		(layers "F.Cu" "B.Cu")
		(net "P12V_AUX")
	)
	(via
		(at 219.9259 -398.305782)
		(size 0.508)
		(drill 0.254)
		(layers "F.Cu" "B.Cu")
		(net "P12V_AUX")
	)
	(via
		(at 452.481442 -415.136076)
		(size 0.508)
		(drill 0.254)
		(layers "F.Cu" "B.Cu")
		(net "P12V_AUX")
	)
	(via
		(at 47.766732 -360.94924)
		(size 0.508)
		(drill 0.254)
		(layers "F.Cu" "B.Cu")
		(net "P12V_AUX")
	)
	(via
		(at 270.695928 -380.670816)
		(size 0.508)
		(drill 0.254)
		(layers "F.Cu" "B.Cu")
		(net "P12V_AUX")
	)
	(via
		(at 210.7819 -399.067782)
		(size 0.508)
		(drill 0.254)
		(layers "F.Cu" "B.Cu")
		(net "P12V_AUX")
	)
	(via
		(at 273.870928 -379.400816)
		(size 0.508)
		(drill 0.254)
		(layers "F.Cu" "B.Cu")
		(net "P12V_AUX")
	)
	(via
		(at 269.425928 -381.305816)
		(size 0.508)
		(drill 0.254)
		(layers "F.Cu" "B.Cu")
		(net "P12V_AUX")
	)
	(via
		(at 221.4499 -397.543782)
		(size 0.508)
		(drill 0.254)
		(layers "F.Cu" "B.Cu")
		(net "P12V_AUX")
	)
	(via
		(at 273.235928 -379.400816)
		(size 0.508)
		(drill 0.254)
		(layers "F.Cu" "B.Cu")
		(net "P12V_AUX")
	)
	(via
		(at 259.461 -380.035816)
		(size 0.508)
		(drill 0.254)
		(layers "F.Cu" "B.Cu")
		(net "P12V_AUX")
	)
	(via
		(at 86.367874 -155.066492)
		(size 0.508)
		(drill 0.254)
		(layers "F.Cu" "B.Cu")
		(net "P12V_AUX")
	)
	(via
		(at 447.965576 -26.967942)
		(size 0.508)
		(drill 0.254)
		(layers "F.Cu" "B.Cu")
		(net "P12V_AUX")
	)
	(via
		(at 442.027564 -362.295948)
		(size 0.508)
		(drill 0.254)
		(layers "F.Cu" "B.Cu")
		(net "P12V_AUX")
	)
	(via
		(at 258.826 -380.670816)
		(size 0.508)
		(drill 0.254)
		(layers "F.Cu" "B.Cu")
		(net "P12V_AUX")
	)
	(via
		(at 237.179612 -381.305816)
		(size 0.508)
		(drill 0.254)
		(layers "F.Cu" "B.Cu")
		(net "P12V_AUX")
	)
	(via
		(at 440.757564 -358.282748)
		(size 0.508)
		(drill 0.254)
		(layers "F.Cu" "B.Cu")
		(net "P12V_AUX")
	)
	(via
		(at 372.035832 -154.420316)
		(size 0.508)
		(drill 0.254)
		(layers "F.Cu" "B.Cu")
		(net "P12V_AUX")
	)
	(via
		(at 209.2579 -395.257782)
		(size 0.508)
		(drill 0.254)
		(layers "F.Cu" "B.Cu")
		(net "P12V_AUX")
	)
	(via
		(at 436.751222 -39.694612)
		(size 0.508)
		(drill 0.254)
		(layers "F.Cu" "B.Cu")
		(net "P12V_AUX")
	)
	(via
		(at 252.256036 -381.305816)
		(size 0.508)
		(drill 0.254)
		(layers "F.Cu" "B.Cu")
		(net "P12V_AUX")
	)
	(via
		(at 380.488444 -156.460952)
		(size 0.508)
		(drill 0.254)
		(layers "F.Cu" "B.Cu")
		(net "P12V_AUX")
	)
	(via
		(at 238.481108 -380.035816)
		(size 0.508)
		(drill 0.254)
		(layers "F.Cu" "B.Cu")
		(net "P12V_AUX")
	)
	(via
		(at 255.431036 -378.765816)
		(size 0.508)
		(drill 0.254)
		(layers "F.Cu" "B.Cu")
		(net "P12V_AUX")
	)
	(via
		(at 219.9259 -399.067782)
		(size 0.508)
		(drill 0.254)
		(layers "F.Cu" "B.Cu")
		(net "P12V_AUX")
	)
	(via
		(at 379.853444 -153.019252)
		(size 0.508)
		(drill 0.254)
		(layers "F.Cu" "B.Cu")
		(net "P12V_AUX")
	)
	(via
		(at 185.098436 -32.102552)
		(size 0.508)
		(drill 0.254)
		(layers "F.Cu" "B.Cu")
		(net "P12V_AUX")
	)
	(via
		(at 91.811856 -351.180908)
		(size 0.508)
		(drill 0.254)
		(layers "F.Cu" "B.Cu")
		(net "P12V_AUX")
	)
	(via
		(at 89.415874 -154.304492)
		(size 0.508)
		(drill 0.254)
		(layers "F.Cu" "B.Cu")
		(net "P12V_AUX")
	)
	(via
		(at 459.486508 -180.58003)
		(size 0.508)
		(drill 0.254)
		(layers "F.Cu" "B.Cu")
		(net "P12V_AUX")
	)
	(via
		(at 331.304138 -132.902198)
		(size 0.508)
		(drill 0.254)
		(layers "F.Cu" "B.Cu")
		(net "P12V_AUX")
	)
	(via
		(at 339.717126 -359.112312)
		(size 0.508)
		(drill 0.254)
		(layers "F.Cu" "B.Cu")
		(net "P12V_AUX")
	)
	(via
		(at 237.846108 -380.035816)
		(size 0.508)
		(drill 0.254)
		(layers "F.Cu" "B.Cu")
		(net "P12V_AUX")
	)
	(via
		(at 286.96285 -361.731052)
		(size 0.508)
		(drill 0.254)
		(layers "F.Cu" "B.Cu")
		(net "P12V_AUX")
	)
	(via
		(at 187.142628 -398.143984)
		(size 0.508)
		(drill 0.254)
		(layers "F.Cu" "B.Cu")
		(net "P12V_AUX")
	)
	(via
		(at 338.203286 -357.839772)
		(size 0.508)
		(drill 0.254)
		(layers "F.Cu" "B.Cu")
		(net "P12V_AUX")
	)
	(via
		(at 187.904628 -395.857984)
		(size 0.508)
		(drill 0.254)
		(layers "F.Cu" "B.Cu")
		(net "P12V_AUX")
	)
	(via
		(at 380.488444 -155.025852)
		(size 0.508)
		(drill 0.254)
		(layers "F.Cu" "B.Cu")
		(net "P12V_AUX")
	)
	(via
		(at 241.656108 -379.400816)
		(size 0.508)
		(drill 0.254)
		(layers "F.Cu" "B.Cu")
		(net "P12V_AUX")
	)
	(via
		(at 87.297514 -155.960572)
		(size 0.508)
		(drill 0.254)
		(layers "F.Cu" "B.Cu")
		(net "P12V_AUX")
	)
	(via
		(at 450.430646 -415.147252)
		(size 0.508)
		(drill 0.254)
		(layers "F.Cu" "B.Cu")
		(net "P12V_AUX")
	)
	(via
		(at 187.904628 -398.905984)
		(size 0.508)
		(drill 0.254)
		(layers "F.Cu" "B.Cu")
		(net "P12V_AUX")
	)
	(via
		(at 90.177874 -155.828492)
		(size 0.508)
		(drill 0.254)
		(layers "F.Cu" "B.Cu")
		(net "P12V_AUX")
	)
	(via
		(at 269.425928 -378.765816)
		(size 0.508)
		(drill 0.254)
		(layers "F.Cu" "B.Cu")
		(net "P12V_AUX")
	)
	(via
		(at 381.758444 -157.095952)
		(size 0.508)
		(drill 0.254)
		(layers "F.Cu" "B.Cu")
		(net "P12V_AUX")
	)
	(via
		(at 265.395964 -380.035816)
		(size 0.508)
		(drill 0.254)
		(layers "F.Cu" "B.Cu")
		(net "P12V_AUX")
	)
	(via
		(at 51.54803 -360.27614)
		(size 0.508)
		(drill 0.254)
		(layers "F.Cu" "B.Cu")
		(net "P12V_AUX")
	)
	(via
		(at 246.321072 -381.305816)
		(size 0.508)
		(drill 0.254)
		(layers "F.Cu" "B.Cu")
		(net "P12V_AUX")
	)
	(via
		(at 87.940134 -157.060392)
		(size 0.508)
		(drill 0.254)
		(layers "F.Cu" "B.Cu")
		(net "P12V_AUX")
	)
	(via
		(at 239.116108 -381.305816)
		(size 0.508)
		(drill 0.254)
		(layers "F.Cu" "B.Cu")
		(net "P12V_AUX")
	)
	(via
		(at 187.904628 -397.381984)
		(size 0.508)
		(drill 0.254)
		(layers "F.Cu" "B.Cu")
		(net "P12V_AUX")
	)
	(via
		(at 47.766732 -360.31424)
		(size 0.508)
		(drill 0.254)
		(layers "F.Cu" "B.Cu")
		(net "P12V_AUX")
	)
	(via
		(at 264.760964 -381.305816)
		(size 0.508)
		(drill 0.254)
		(layers "F.Cu" "B.Cu")
		(net "P12V_AUX")
	)
	(via
		(at 286.23641 -364.151672)
		(size 0.508)
		(drill 0.254)
		(layers "F.Cu" "B.Cu")
		(net "P12V_AUX")
	)
	(via
		(at 190.000636 -29.537152)
		(size 0.508)
		(drill 0.254)
		(layers "F.Cu" "B.Cu")
		(net "P12V_AUX")
	)
	(via
		(at 250.131072 -378.765816)
		(size 0.508)
		(drill 0.254)
		(layers "F.Cu" "B.Cu")
		(net "P12V_AUX")
	)
	(via
		(at 259.461 -378.765816)
		(size 0.508)
		(drill 0.254)
		(layers "F.Cu" "B.Cu")
		(net "P12V_AUX")
	)
	(via
		(at 449.744846 -414.512252)
		(size 0.508)
		(drill 0.254)
		(layers "F.Cu" "B.Cu")
		(net "P12V_AUX")
	)
	(via
		(at 460.365348 -179.84597)
		(size 0.508)
		(drill 0.254)
		(layers "F.Cu" "B.Cu")
		(net "P12V_AUX")
	)
	(via
		(at 260.096 -381.305816)
		(size 0.508)
		(drill 0.254)
		(layers "F.Cu" "B.Cu")
		(net "P12V_AUX")
	)
	(via
		(at 258.191 -381.305816)
		(size 0.508)
		(drill 0.254)
		(layers "F.Cu" "B.Cu")
		(net "P12V_AUX")
	)
	(via
		(at 89.88806 -104.55148)
		(size 0.508)
		(drill 0.254)
		(layers "F.Cu" "B.Cu")
		(net "P12V_AUX")
	)
	(via
		(at 289.61461 -362.881672)
		(size 0.508)
		(drill 0.254)
		(layers "F.Cu" "B.Cu")
		(net "P12V_AUX")
	)
	(via
		(at 181.508146 -363.924342)
		(size 0.508)
		(drill 0.254)
		(layers "F.Cu" "B.Cu")
		(net "P12V_AUX")
	)
	(via
		(at 250.131072 -379.400816)
		(size 0.508)
		(drill 0.254)
		(layers "F.Cu" "B.Cu")
		(net "P12V_AUX")
	)
	(via
		(at 286.23641 -362.246672)
		(size 0.508)
		(drill 0.254)
		(layers "F.Cu" "B.Cu")
		(net "P12V_AUX")
	)
	(via
		(at 199.3519 -397.543782)
		(size 0.508)
		(drill 0.254)
		(layers "F.Cu" "B.Cu")
		(net "P12V_AUX")
	)
	(via
		(at 336.676746 -359.102152)
		(size 0.508)
		(drill 0.254)
		(layers "F.Cu" "B.Cu")
		(net "P12V_AUX")
	)
	(via
		(at 381.123444 -157.095952)
		(size 0.508)
		(drill 0.254)
		(layers "F.Cu" "B.Cu")
		(net "P12V_AUX")
	)
	(via
		(at 264.760964 -379.400816)
		(size 0.508)
		(drill 0.254)
		(layers "F.Cu" "B.Cu")
		(net "P12V_AUX")
	)
	(via
		(at 201.6379 -396.781782)
		(size 0.508)
		(drill 0.254)
		(layers "F.Cu" "B.Cu")
		(net "P12V_AUX")
	)
	(via
		(at 366.701832 -158.230316)
		(size 0.508)
		(drill 0.254)
		(layers "F.Cu" "B.Cu")
		(net "P12V_AUX")
	)
	(via
		(at 92.446856 -350.545908)
		(size 0.508)
		(drill 0.254)
		(layers "F.Cu" "B.Cu")
		(net "P12V_AUX")
	)
	(via
		(at 209.2579 -398.305782)
		(size 0.508)
		(drill 0.254)
		(layers "F.Cu" "B.Cu")
		(net "P12V_AUX")
	)
	(via
		(at 266.030964 -381.305816)
		(size 0.508)
		(drill 0.254)
		(layers "F.Cu" "B.Cu")
		(net "P12V_AUX")
	)
	(via
		(at 371.273832 -154.420316)
		(size 0.508)
		(drill 0.254)
		(layers "F.Cu" "B.Cu")
		(net "P12V_AUX")
	)
	(via
		(at 266.665964 -379.400816)
		(size 0.508)
		(drill 0.254)
		(layers "F.Cu" "B.Cu")
		(net "P12V_AUX")
	)
	(via
		(at 253.526036 -381.305816)
		(size 0.508)
		(drill 0.254)
		(layers "F.Cu" "B.Cu")
		(net "P12V_AUX")
	)
	(via
		(at 366.701832 -155.944316)
		(size 0.508)
		(drill 0.254)
		(layers "F.Cu" "B.Cu")
		(net "P12V_AUX")
	)
	(via
		(at 116.822474 -145.194528)
		(size 0.508)
		(drill 0.254)
		(layers "F.Cu" "B.Cu")
		(net "P12V_AUX")
	)
	(via
		(at 92.25026 -352.431858)
		(size 0.508)
		(drill 0.254)
		(layers "F.Cu" "B.Cu")
		(net "P12V_AUX")
	)
	(via
		(at 257.556 -378.765816)
		(size 0.508)
		(drill 0.254)
		(layers "F.Cu" "B.Cu")
		(net "P12V_AUX")
	)
	(via
		(at 220.6879 -399.067782)
		(size 0.508)
		(drill 0.254)
		(layers "F.Cu" "B.Cu")
		(net "P12V_AUX")
	)
	(via
		(at 230.5939 -397.543782)
		(size 0.508)
		(drill 0.254)
		(layers "F.Cu" "B.Cu")
		(net "P12V_AUX")
	)
	(via
		(at 246.956072 -380.670816)
		(size 0.508)
		(drill 0.254)
		(layers "F.Cu" "B.Cu")
		(net "P12V_AUX")
	)
	(via
		(at 427.670214 -366.54105)
		(size 0.508)
		(drill 0.254)
		(layers "F.Cu" "B.Cu")
		(net "P12V_AUX")
	)
	(via
		(at 277.265892 -379.400816)
		(size 0.508)
		(drill 0.254)
		(layers "F.Cu" "B.Cu")
		(net "P12V_AUX")
	)
	(via
		(at 442.662564 -360.289348)
		(size 0.508)
		(drill 0.254)
		(layers "F.Cu" "B.Cu")
		(net "P12V_AUX")
	)
	(via
		(at 341.338662 -359.121964)
		(size 0.508)
		(drill 0.254)
		(layers "F.Cu" "B.Cu")
		(net "P12V_AUX")
	)
	(via
		(at 248.861072 -378.765816)
		(size 0.508)
		(drill 0.254)
		(layers "F.Cu" "B.Cu")
		(net "P12V_AUX")
	)
	(via
		(at 368.225832 -154.420316)
		(size 0.508)
		(drill 0.254)
		(layers "F.Cu" "B.Cu")
		(net "P12V_AUX")
	)
	(via
		(at 461.567784 -41.604438)
		(size 0.508)
		(drill 0.254)
		(layers "F.Cu" "B.Cu")
		(net "P12V_AUX")
	)
	(via
		(at 438.173622 -42.285412)
		(size 0.508)
		(drill 0.254)
		(layers "F.Cu" "B.Cu")
		(net "P12V_AUX")
	)
	(via
		(at 179.244244 -29.255212)
		(size 0.4572)
		(drill 0.254)
		(layers "F.Cu" "B.Cu")
		(net "P12V_AUX")
	)
	(via
		(at 344.309446 -360.430064)
		(size 0.508)
		(drill 0.254)
		(layers "F.Cu" "B.Cu")
		(net "P12V_AUX")
	)
	(via
		(at 238.481108 -379.400816)
		(size 0.508)
		(drill 0.254)
		(layers "F.Cu" "B.Cu")
		(net "P12V_AUX")
	)
	(via
		(at 288.23285 -361.731052)
		(size 0.508)
		(drill 0.254)
		(layers "F.Cu" "B.Cu")
		(net "P12V_AUX")
	)
	(via
		(at 449.744846 -415.147252)
		(size 0.508)
		(drill 0.254)
		(layers "F.Cu" "B.Cu")
		(net "P12V_AUX")
	)
	(via
		(at 259.461 -380.670816)
		(size 0.508)
		(drill 0.254)
		(layers "F.Cu" "B.Cu")
		(net "P12V_AUX")
	)
	(via
		(at 221.889828 -272.169382)
		(size 0.508)
		(drill 0.254)
		(layers "F.Cu" "B.Cu")
		(net "P12V_AUX")
	)
	(via
		(at 93.609922 -353.162616)
		(size 0.508)
		(drill 0.254)
		(layers "F.Cu" "B.Cu")
		(net "P12V_AUX")
	)
	(via
		(at 262.001 -379.400816)
		(size 0.508)
		(drill 0.254)
		(layers "F.Cu" "B.Cu")
		(net "P12V_AUX")
	)
	(via
		(at 237.179612 -380.035816)
		(size 0.508)
		(drill 0.254)
		(layers "F.Cu" "B.Cu")
		(net "P12V_AUX")
	)
	(via
		(at 275.995892 -378.765816)
		(size 0.508)
		(drill 0.254)
		(layers "F.Cu" "B.Cu")
		(net "P12V_AUX")
	)
	(via
		(at 381.123444 -156.460952)
		(size 0.508)
		(drill 0.254)
		(layers "F.Cu" "B.Cu")
		(net "P12V_AUX")
	)
	(via
		(at 239.751108 -378.765816)
		(size 0.508)
		(drill 0.254)
		(layers "F.Cu" "B.Cu")
		(net "P12V_AUX")
	)
	(via
		(at 380.488444 -154.390852)
		(size 0.508)
		(drill 0.254)
		(layers "F.Cu" "B.Cu")
		(net "P12V_AUX")
	)
	(via
		(at 202.3999 -396.019782)
		(size 0.508)
		(drill 0.254)
		(layers "F.Cu" "B.Cu")
		(net "P12V_AUX")
	)
	(via
		(at 440.757564 -362.930948)
		(size 0.508)
		(drill 0.254)
		(layers "F.Cu" "B.Cu")
		(net "P12V_AUX")
	)
	(via
		(at 185.098436 -32.839152)
		(size 0.508)
		(drill 0.254)
		(layers "F.Cu" "B.Cu")
		(net "P12V_AUX")
	)
	(via
		(at 258.496054 -48.020986)
		(size 0.508)
		(drill 0.254)
		(layers "F.Cu" "B.Cu")
		(net "P12V_AUX")
	)
	(via
		(at 335.914746 -359.102152)
		(size 0.508)
		(drill 0.254)
		(layers "F.Cu" "B.Cu")
		(net "P12V_AUX")
	)
	(via
		(at 458.587348 -179.84597)
		(size 0.508)
		(drill 0.254)
		(layers "F.Cu" "B.Cu")
		(net "P12V_AUX")
	)
	(via
		(at 271.965928 -380.670816)
		(size 0.508)
		(drill 0.254)
		(layers "F.Cu" "B.Cu")
		(net "P12V_AUX")
	)
	(via
		(at 271.965928 -379.400816)
		(size 0.508)
		(drill 0.254)
		(layers "F.Cu" "B.Cu")
		(net "P12V_AUX")
	)
	(via
		(at 79.35214 -22.62124)
		(size 0.508)
		(drill 0.254)
		(layers "F.Cu" "B.Cu")
		(net "P12V_AUX")
	)
	(via
		(at 39.228522 -366.06353)
		(size 0.508)
		(drill 0.254)
		(layers "F.Cu" "B.Cu")
		(net "P12V_AUX")
	)
	(via
		(at 381.758444 -156.460952)
		(size 0.508)
		(drill 0.254)
		(layers "F.Cu" "B.Cu")
		(net "P12V_AUX")
	)
	(via
		(at 367.463832 -155.182316)
		(size 0.508)
		(drill 0.254)
		(layers "F.Cu" "B.Cu")
		(net "P12V_AUX")
	)
	(via
		(at 258.191 -380.035816)
		(size 0.508)
		(drill 0.254)
		(layers "F.Cu" "B.Cu")
		(net "P12V_AUX")
	)
	(via
		(at 89.415874 -155.066492)
		(size 0.508)
		(drill 0.254)
		(layers "F.Cu" "B.Cu")
		(net "P12V_AUX")
	)
	(via
		(at 168.952418 -350.732344)
		(size 0.508)
		(drill 0.254)
		(layers "F.Cu" "B.Cu")
		(net "P12V_AUX")
	)
	(via
		(at 209.2579 -397.543782)
		(size 0.508)
		(drill 0.254)
		(layers "F.Cu" "B.Cu")
		(net "P12V_AUX")
	)
	(via
		(at 86.367874 -153.542492)
		(size 0.508)
		(drill 0.254)
		(layers "F.Cu" "B.Cu")
		(net "P12V_AUX")
	)
	(via
		(at 251.621036 -378.765816)
		(size 0.508)
		(drill 0.254)
		(layers "F.Cu" "B.Cu")
		(net "P12V_AUX")
	)
	(via
		(at 253.526036 -378.765816)
		(size 0.508)
		(drill 0.254)
		(layers "F.Cu" "B.Cu")
		(net "P12V_AUX")
	)
	(via
		(at 25.129998 -406.045924)
		(size 0.508)
		(drill 0.254)
		(layers "F.Cu" "B.Cu")
		(net "P12V_AUX")
	)
	(via
		(at 276.630892 -378.765816)
		(size 0.508)
		(drill 0.254)
		(layers "F.Cu" "B.Cu")
		(net "P12V_AUX")
	)
	(via
		(at 221.4499 -395.257782)
		(size 0.508)
		(drill 0.254)
		(layers "F.Cu" "B.Cu")
		(net "P12V_AUX")
	)
	(via
		(at 241.021108 -378.765816)
		(size 0.508)
		(drill 0.254)
		(layers "F.Cu" "B.Cu")
		(net "P12V_AUX")
	)
	(via
		(at 369.749832 -155.182316)
		(size 0.508)
		(drill 0.254)
		(layers "F.Cu" "B.Cu")
		(net "P12V_AUX")
	)
	(via
		(at 221.889828 -273.071082)
		(size 0.508)
		(drill 0.254)
		(layers "F.Cu" "B.Cu")
		(net "P12V_AUX")
	)
	(via
		(at 237.846108 -380.670816)
		(size 0.508)
		(drill 0.254)
		(layers "F.Cu" "B.Cu")
		(net "P12V_AUX")
	)
	(via
		(at 250.30303 -47.088806)
		(size 0.508)
		(drill 0.254)
		(layers "F.Cu" "B.Cu")
		(net "P12V_AUX")
	)
	(via
		(at 87.366856 -352.450908)
		(size 0.508)
		(drill 0.254)
		(layers "F.Cu" "B.Cu")
		(net "P12V_AUX")
	)
	(via
		(at 220.6879 -396.019782)
		(size 0.508)
		(drill 0.254)
		(layers "F.Cu" "B.Cu")
		(net "P12V_AUX")
	)
	(via
		(at 246.321072 -380.035816)
		(size 0.508)
		(drill 0.254)
		(layers "F.Cu" "B.Cu")
		(net "P12V_AUX")
	)
	(via
		(at 15.557754 -201.350372)
		(size 0.508)
		(drill 0.254)
		(layers "F.Cu" "B.Cu")
		(net "P12V_AUX")
	)
	(via
		(at 120.835674 -143.924528)
		(size 0.508)
		(drill 0.254)
		(layers "F.Cu" "B.Cu")
		(net "P12V_AUX")
	)
	(via
		(at 93.081856 -351.180908)
		(size 0.508)
		(drill 0.254)
		(layers "F.Cu" "B.Cu")
		(net "P12V_AUX")
	)
	(via
		(at 460.375508 -181.85003)
		(size 0.508)
		(drill 0.254)
		(layers "F.Cu" "B.Cu")
		(net "P12V_AUX")
	)
	(via
		(at 248.226072 -378.765816)
		(size 0.508)
		(drill 0.254)
		(layers "F.Cu" "B.Cu")
		(net "P12V_AUX")
	)
	(via
		(at 245.686072 -380.670816)
		(size 0.508)
		(drill 0.254)
		(layers "F.Cu" "B.Cu")
		(net "P12V_AUX")
	)
	(via
		(at 260.731 -379.400816)
		(size 0.508)
		(drill 0.254)
		(layers "F.Cu" "B.Cu")
		(net "P12V_AUX")
	)
	(via
		(at 154.657044 -125.5776)
		(size 0.508)
		(drill 0.254)
		(layers "F.Cu" "B.Cu")
		(net "P12V_AUX")
	)
	(via
		(at 381.758444 -152.384252)
		(size 0.508)
		(drill 0.254)
		(layers "F.Cu" "B.Cu")
		(net "P12V_AUX")
	)
	(via
		(at 438.173622 -39.694612)
		(size 0.508)
		(drill 0.254)
		(layers "F.Cu" "B.Cu")
		(net "P12V_AUX")
	)
	(via
		(at 441.194444 -27.869642)
		(size 0.4572)
		(drill 0.254)
		(layers "F.Cu" "B.Cu")
		(net "P12V_AUX")
	)
	(via
		(at 208.4959 -396.781782)
		(size 0.508)
		(drill 0.254)
		(layers "F.Cu" "B.Cu")
		(net "P12V_AUX")
	)
	(via
		(at 88.636856 -350.545908)
		(size 0.508)
		(drill 0.254)
		(layers "F.Cu" "B.Cu")
		(net "P12V_AUX")
	)
	(via
		(at 251.99975 -269.604236)
		(size 0.508)
		(drill 0.254)
		(layers "F.Cu" "B.Cu")
		(net "P12V_AUX")
	)
	(via
		(at 458.597508 -181.21503)
		(size 0.508)
		(drill 0.254)
		(layers "F.Cu" "B.Cu")
		(net "P12V_AUX")
	)
	(via
		(at 179.244244 -28.620212)
		(size 0.4572)
		(drill 0.254)
		(layers "F.Cu" "B.Cu")
		(net "P12V_AUX")
	)
	(via
		(at 201.6379 -395.257782)
		(size 0.508)
		(drill 0.254)
		(layers "F.Cu" "B.Cu")
		(net "P12V_AUX")
	)
	(via
		(at 50.903632 -360.362246)
		(size 0.508)
		(drill 0.254)
		(layers "F.Cu" "B.Cu")
		(net "P12V_AUX")
	)
	(via
		(at 222.9739 -399.067782)
		(size 0.508)
		(drill 0.254)
		(layers "F.Cu" "B.Cu")
		(net "P12V_AUX")
	)
	(via
		(at 258.369054 -45.643546)
		(size 0.508)
		(drill 0.254)
		(layers "F.Cu" "B.Cu")
		(net "P12V_AUX")
	)
	(via
		(at 248.861072 -379.400816)
		(size 0.508)
		(drill 0.254)
		(layers "F.Cu" "B.Cu")
		(net "P12V_AUX")
	)
	(via
		(at 290.24961 -363.516672)
		(size 0.508)
		(drill 0.254)
		(layers "F.Cu" "B.Cu")
		(net "P12V_AUX")
	)
	(via
		(at 222.9739 -397.543782)
		(size 0.508)
		(drill 0.254)
		(layers "F.Cu" "B.Cu")
		(net "P12V_AUX")
	)
	(via
		(at 271.330928 -378.765816)
		(size 0.508)
		(drill 0.254)
		(layers "F.Cu" "B.Cu")
		(net "P12V_AUX")
	)
	(via
		(at 265.395964 -381.305816)
		(size 0.508)
		(drill 0.254)
		(layers "F.Cu" "B.Cu")
		(net "P12V_AUX")
	)
	(via
		(at 68.321174 -28.208224)
		(size 0.4572)
		(drill 0.254)
		(layers "F.Cu" "B.Cu")
		(net "P12V_AUX")
	)
	(via
		(at 339.727286 -357.839772)
		(size 0.508)
		(drill 0.254)
		(layers "F.Cu" "B.Cu")
		(net "P12V_AUX")
	)
	(via
		(at 453.172576 -27.501342)
		(size 0.508)
		(drill 0.254)
		(layers "F.Cu" "B.Cu")
		(net "P12V_AUX")
	)
	(via
		(at 341.261446 -360.430064)
		(size 0.508)
		(drill 0.254)
		(layers "F.Cu" "B.Cu")
		(net "P12V_AUX")
	)
	(via
		(at 447.152776 -26.967942)
		(size 0.508)
		(drill 0.254)
		(layers "F.Cu" "B.Cu")
		(net "P12V_AUX")
	)
	(via
		(at 458.587348 -178.57597)
		(size 0.508)
		(drill 0.254)
		(layers "F.Cu" "B.Cu")
		(net "P12V_AUX")
	)
	(via
		(at 186.380628 -395.857984)
		(size 0.508)
		(drill 0.254)
		(layers "F.Cu" "B.Cu")
		(net "P12V_AUX")
	)
	(via
		(at 365.939832 -156.706316)
		(size 0.508)
		(drill 0.254)
		(layers "F.Cu" "B.Cu")
		(net "P12V_AUX")
	)
	(via
		(at 232.1179 -398.305782)
		(size 0.508)
		(drill 0.254)
		(layers "F.Cu" "B.Cu")
		(net "P12V_AUX")
	)
	(via
		(at 219.1639 -395.257782)
		(size 0.762)
		(drill 0.254)
		(layers "F.Cu" "B.Cu")
		(net "P12V_AUX")
	)
	(via
		(at 434.668422 -41.015412)
		(size 0.508)
		(drill 0.254)
		(layers "F.Cu" "B.Cu")
		(net "P12V_AUX")
	)
	(via
		(at 341.251286 -359.787444)
		(size 0.508)
		(drill 0.254)
		(layers "F.Cu" "B.Cu")
		(net "P12V_AUX")
	)
	(via
		(at 249.71375 -269.604236)
		(size 0.508)
		(drill 0.254)
		(layers "F.Cu" "B.Cu")
		(net "P12V_AUX")
	)
	(via
		(at 120.835674 -145.194528)
		(size 0.508)
		(drill 0.254)
		(layers "F.Cu" "B.Cu")
		(net "P12V_AUX")
	)
	(via
		(at 212.3059 -397.543782)
		(size 0.508)
		(drill 0.254)
		(layers "F.Cu" "B.Cu")
		(net "P12V_AUX")
	)
	(via
		(at 264.125964 -380.670816)
		(size 0.508)
		(drill 0.254)
		(layers "F.Cu" "B.Cu")
		(net "P12V_AUX")
	)
	(via
		(at 250.766072 -379.400816)
		(size 0.508)
		(drill 0.254)
		(layers "F.Cu" "B.Cu")
		(net "P12V_AUX")
	)
	(via
		(at 453.802496 -415.803334)
		(size 0.508)
		(drill 0.254)
		(layers "F.Cu" "B.Cu")
		(net "P12V_AUX")
	)
	(via
		(at 205.197964 -347.135958)
		(size 0.508)
		(drill 0.254)
		(layers "F.Cu" "B.Cu")
		(net "P12V_AUX")
	)
	(via
		(at 440.122564 -362.930948)
		(size 0.508)
		(drill 0.254)
		(layers "F.Cu" "B.Cu")
		(net "P12V_AUX")
	)
	(via
		(at 248.226072 -380.670816)
		(size 0.508)
		(drill 0.254)
		(layers "F.Cu" "B.Cu")
		(net "P12V_AUX")
	)
	(via
		(at 456.809348 -179.21097)
		(size 0.508)
		(drill 0.254)
		(layers "F.Cu" "B.Cu")
		(net "P12V_AUX")
	)
	(via
		(at 251.23775 -270.505936)
		(size 0.508)
		(drill 0.254)
		(layers "F.Cu" "B.Cu")
		(net "P12V_AUX")
	)
	(via
		(at 211.5439 -396.781782)
		(size 0.508)
		(drill 0.254)
		(layers "F.Cu" "B.Cu")
		(net "P12V_AUX")
	)
	(via
		(at 234.4039 -396.019782)
		(size 0.508)
		(drill 0.254)
		(layers "F.Cu" "B.Cu")
		(net "P12V_AUX")
	)
	(via
		(at 367.463832 -158.230316)
		(size 0.508)
		(drill 0.254)
		(layers "F.Cu" "B.Cu")
		(net "P12V_AUX")
	)
	(via
		(at 368.225832 -155.182316)
		(size 0.508)
		(drill 0.254)
		(layers "F.Cu" "B.Cu")
		(net "P12V_AUX")
	)
	(via
		(at 219.1639 -396.019782)
		(size 0.508)
		(drill 0.254)
		(layers "F.Cu" "B.Cu")
		(net "P12V_AUX")
	)
	(via
		(at 210.0199 -396.019782)
		(size 0.508)
		(drill 0.254)
		(layers "F.Cu" "B.Cu")
		(net "P12V_AUX")
	)
	(via
		(at 258.191 -380.670816)
		(size 0.508)
		(drill 0.254)
		(layers "F.Cu" "B.Cu")
		(net "P12V_AUX")
	)
	(via
		(at 442.027564 -358.282748)
		(size 0.508)
		(drill 0.254)
		(layers "F.Cu" "B.Cu")
		(net "P12V_AUX")
	)
	(via
		(at 459.486508 -181.21503)
		(size 0.508)
		(drill 0.254)
		(layers "F.Cu" "B.Cu")
		(net "P12V_AUX")
	)
	(via
		(at 200.8759 -398.305782)
		(size 0.508)
		(drill 0.254)
		(layers "F.Cu" "B.Cu")
		(net "P12V_AUX")
	)
	(via
		(at 118.194074 -144.559528)
		(size 0.508)
		(drill 0.254)
		(layers "F.Cu" "B.Cu")
		(net "P12V_AUX")
	)
	(via
		(at 249.496072 -379.400816)
		(size 0.508)
		(drill 0.254)
		(layers "F.Cu" "B.Cu")
		(net "P12V_AUX")
	)
	(via
		(at 222.9739 -395.257782)
		(size 0.508)
		(drill 0.254)
		(layers "F.Cu" "B.Cu")
		(net "P12V_AUX")
	)
	(via
		(at 189.428628 -395.857984)
		(size 0.508)
		(drill 0.254)
		(layers "F.Cu" "B.Cu")
		(net "P12V_AUX")
	)
	(via
		(at 189.428628 -396.619984)
		(size 0.508)
		(drill 0.254)
		(layers "F.Cu" "B.Cu")
		(net "P12V_AUX")
	)
	(via
		(at 436.751222 -41.650412)
		(size 0.508)
		(drill 0.254)
		(layers "F.Cu" "B.Cu")
		(net "P12V_AUX")
	)
	(via
		(at 85.605874 -156.590492)
		(size 0.508)
		(drill 0.254)
		(layers "F.Cu" "B.Cu")
		(net "P12V_AUX")
	)
	(via
		(at 14.922754 -200.715372)
		(size 0.508)
		(drill 0.254)
		(layers "F.Cu" "B.Cu")
		(net "P12V_AUX")
	)
	(via
		(at 200.1139 -397.543782)
		(size 0.508)
		(drill 0.254)
		(layers "F.Cu" "B.Cu")
		(net "P12V_AUX")
	)
	(via
		(at 434.668422 -42.285412)
		(size 0.508)
		(drill 0.254)
		(layers "F.Cu" "B.Cu")
		(net "P12V_AUX")
	)
	(via
		(at 15.557754 -196.905372)
		(size 0.508)
		(drill 0.254)
		(layers "F.Cu" "B.Cu")
		(net "P12V_AUX")
	)
	(via
		(at 345.061286 -359.109772)
		(size 0.508)
		(drill 0.254)
		(layers "F.Cu" "B.Cu")
		(net "P12V_AUX")
	)
	(via
		(at 438.173622 -40.355012)
		(size 0.508)
		(drill 0.254)
		(layers "F.Cu" "B.Cu")
		(net "P12V_AUX")
	)
	(via
		(at 90.939874 -156.590492)
		(size 0.508)
		(drill 0.254)
		(layers "F.Cu" "B.Cu")
		(net "P12V_AUX")
	)
	(via
		(at 338.965286 -358.474772)
		(size 0.508)
		(drill 0.254)
		(layers "F.Cu" "B.Cu")
		(net "P12V_AUX")
	)
	(via
		(at 251.621036 -380.035816)
		(size 0.508)
		(drill 0.254)
		(layers "F.Cu" "B.Cu")
		(net "P12V_AUX")
	)
	(via
		(at 343.537286 -359.787444)
		(size 0.508)
		(drill 0.254)
		(layers "F.Cu" "B.Cu")
		(net "P12V_AUX")
	)
	(via
		(at 254.179324 -51.632612)
		(size 0.4572)
		(drill 0.254)
		(layers "F.Cu" "B.Cu")
		(net "P12V_AUX")
	)
	(via
		(at 440.122564 -362.295948)
		(size 0.508)
		(drill 0.254)
		(layers "F.Cu" "B.Cu")
		(net "P12V_AUX")
	)
	(via
		(at 251.23775 -271.267936)
		(size 0.508)
		(drill 0.254)
		(layers "F.Cu" "B.Cu")
		(net "P12V_AUX")
	)
	(via
		(at 253.526036 -380.035816)
		(size 0.508)
		(drill 0.254)
		(layers "F.Cu" "B.Cu")
		(net "P12V_AUX")
	)
	(via
		(at 285.60141 -362.246672)
		(size 0.508)
		(drill 0.254)
		(layers "F.Cu" "B.Cu")
		(net "P12V_AUX")
	)
	(via
		(at 222.651828 -272.169382)
		(size 0.508)
		(drill 0.254)
		(layers "F.Cu" "B.Cu")
		(net "P12V_AUX")
	)
	(via
		(at 49.017682 -360.062272)
		(size 0.508)
		(drill 0.254)
		(layers "F.Cu" "B.Cu")
		(net "P12V_AUX")
	)
	(via
		(at 90.541856 -350.545908)
		(size 0.508)
		(drill 0.254)
		(layers "F.Cu" "B.Cu")
		(net "P12V_AUX")
	)
	(via
		(at 335.935066 -360.419904)
		(size 0.508)
		(drill 0.254)
		(layers "F.Cu" "B.Cu")
		(net "P12V_AUX")
	)
	(via
		(at 246.956072 -379.400816)
		(size 0.508)
		(drill 0.254)
		(layers "F.Cu" "B.Cu")
		(net "P12V_AUX")
	)
	(via
		(at 256.701036 -379.400816)
		(size 0.508)
		(drill 0.254)
		(layers "F.Cu" "B.Cu")
		(net "P12V_AUX")
	)
	(via
		(at 211.5439 -399.067782)
		(size 0.508)
		(drill 0.254)
		(layers "F.Cu" "B.Cu")
		(net "P12V_AUX")
	)
	(via
		(at 287.59785 -361.731052)
		(size 0.508)
		(drill 0.254)
		(layers "F.Cu" "B.Cu")
		(net "P12V_AUX")
	)
	(via
		(at 460.365348 -177.94097)
		(size 0.508)
		(drill 0.254)
		(layers "F.Cu" "B.Cu")
		(net "P12V_AUX")
	)
	(via
		(at 337.448906 -359.777284)
		(size 0.508)
		(drill 0.254)
		(layers "F.Cu" "B.Cu")
		(net "P12V_AUX")
	)
	(via
		(at 84.173314 -156.590492)
		(size 0.508)
		(drill 0.254)
		(layers "F.Cu" "B.Cu")
		(net "P12V_AUX")
	)
	(via
		(at 242.291108 -380.670816)
		(size 0.508)
		(drill 0.254)
		(layers "F.Cu" "B.Cu")
		(net "P12V_AUX")
	)
	(via
		(at 367.463832 -157.468316)
		(size 0.508)
		(drill 0.254)
		(layers "F.Cu" "B.Cu")
		(net "P12V_AUX")
	)
	(via
		(at 187.142628 -397.381984)
		(size 0.508)
		(drill 0.254)
		(layers "F.Cu" "B.Cu")
		(net "P12V_AUX")
	)
	(via
		(at 239.116108 -379.400816)
		(size 0.508)
		(drill 0.254)
		(layers "F.Cu" "B.Cu")
		(net "P12V_AUX")
	)
	(via
		(at 190.02375 -43.336972)
		(size 0.508)
		(drill 0.254)
		(layers "F.Cu" "B.Cu")
		(net "P12V_AUX")
	)
	(via
		(at 52.846732 -359.67924)
		(size 0.508)
		(drill 0.254)
		(layers "F.Cu" "B.Cu")
		(net "P12V_AUX")
	)
	(via
		(at 241.021108 -380.035816)
		(size 0.508)
		(drill 0.254)
		(layers "F.Cu" "B.Cu")
		(net "P12V_AUX")
	)
	(via
		(at 88.001856 -351.815908)
		(size 0.508)
		(drill 0.254)
		(layers "F.Cu" "B.Cu")
		(net "P12V_AUX")
	)
	(via
		(at 204.70876 -135.763)
		(size 0.508)
		(drill 0.254)
		(layers "F.Cu" "B.Cu")
		(net "P12V_AUX")
	)
	(via
		(at 199.3519 -396.019782)
		(size 0.508)
		(drill 0.254)
		(layers "F.Cu" "B.Cu")
		(net "P12V_AUX")
	)
	(via
		(at 437.637936 -25.835102)
		(size 0.508)
		(drill 0.254)
		(layers "F.Cu" "B.Cu")
		(net "P12V_AUX")
	)
	(via
		(at 208.4959 -397.543782)
		(size 0.508)
		(drill 0.254)
		(layers "F.Cu" "B.Cu")
		(net "P12V_AUX")
	)
	(via
		(at 260.731 -378.765816)
		(size 0.508)
		(drill 0.254)
		(layers "F.Cu" "B.Cu")
		(net "P12V_AUX")
	)
	(via
		(at 200.8759 -396.019782)
		(size 0.508)
		(drill 0.254)
		(layers "F.Cu" "B.Cu")
		(net "P12V_AUX")
	)
	(via
		(at 275.995892 -379.400816)
		(size 0.508)
		(drill 0.254)
		(layers "F.Cu" "B.Cu")
		(net "P12V_AUX")
	)
	(via
		(at 44.27728 -100.34016)
		(size 0.508)
		(drill 0.254)
		(layers "F.Cu" "B.Cu")
		(net "P12V_AUX")
	)
	(via
		(at 92.250514 -353.769168)
		(size 0.508)
		(drill 0.254)
		(layers "F.Cu" "B.Cu")
		(net "P12V_AUX")
	)
	(via
		(at 344.299286 -358.474772)
		(size 0.508)
		(drill 0.254)
		(layers "F.Cu" "B.Cu")
		(net "P12V_AUX")
	)
	(via
		(at 89.906856 -350.545908)
		(size 0.508)
		(drill 0.254)
		(layers "F.Cu" "B.Cu")
		(net "P12V_AUX")
	)
	(via
		(at 14.922754 -198.175372)
		(size 0.508)
		(drill 0.254)
		(layers "F.Cu" "B.Cu")
		(net "P12V_AUX")
	)
	(via
		(at 187.904628 -395.095984)
		(size 0.508)
		(drill 0.254)
		(layers "F.Cu" "B.Cu")
		(net "P12V_AUX")
	)
	(via
		(at 409.744926 -135.082026)
		(size 0.508)
		(drill 0.254)
		(layers "F.Cu" "B.Cu")
		(net "P12V_AUX")
	)
	(via
		(at 25.101296 -404.763732)
		(size 0.508)
		(drill 0.254)
		(layers "F.Cu" "B.Cu")
		(net "P12V_AUX")
	)
	(via
		(at 264.125964 -378.765816)
		(size 0.508)
		(drill 0.254)
		(layers "F.Cu" "B.Cu")
		(net "P12V_AUX")
	)
	(via
		(at 232.8799 -398.305782)
		(size 0.508)
		(drill 0.254)
		(layers "F.Cu" "B.Cu")
		(net "P12V_AUX")
	)
	(via
		(at 262.636 -378.765816)
		(size 0.508)
		(drill 0.254)
		(layers "F.Cu" "B.Cu")
		(net "P12V_AUX")
	)
	(via
		(at 379.789944 -153.755852)
		(size 0.508)
		(drill 0.254)
		(layers "F.Cu" "B.Cu")
		(net "P12V_AUX")
	)
	(via
		(at 210.0199 -397.543782)
		(size 0.508)
		(drill 0.254)
		(layers "F.Cu" "B.Cu")
		(net "P12V_AUX")
	)
	(via
		(at 116.187474 -145.194528)
		(size 0.508)
		(drill 0.254)
		(layers "F.Cu" "B.Cu")
		(net "P12V_AUX")
	)
	(via
		(at 435.430422 -41.650412)
		(size 0.508)
		(drill 0.254)
		(layers "F.Cu" "B.Cu")
		(net "P12V_AUX")
	)
	(via
		(at 87.891874 -153.542492)
		(size 0.508)
		(drill 0.254)
		(layers "F.Cu" "B.Cu")
		(net "P12V_AUX")
	)
	(via
		(at 275.995892 -380.670816)
		(size 0.508)
		(drill 0.254)
		(layers "F.Cu" "B.Cu")
		(net "P12V_AUX")
	)
	(via
		(at 436.090822 -39.694612)
		(size 0.508)
		(drill 0.254)
		(layers "F.Cu" "B.Cu")
		(net "P12V_AUX")
	)
	(via
		(at 453.148192 -415.13125)
		(size 0.508)
		(drill 0.254)
		(layers "F.Cu" "B.Cu")
		(net "P12V_AUX")
	)
	(via
		(at 253.526036 -379.400816)
		(size 0.508)
		(drill 0.254)
		(layers "F.Cu" "B.Cu")
		(net "P12V_AUX")
	)
	(via
		(at 91.701874 -155.828492)
		(size 0.508)
		(drill 0.254)
		(layers "F.Cu" "B.Cu")
		(net "P12V_AUX")
	)
	(via
		(at 202.3999 -397.543782)
		(size 0.508)
		(drill 0.254)
		(layers "F.Cu" "B.Cu")
		(net "P12V_AUX")
	)
	(via
		(at 244.831108 -379.400816)
		(size 0.508)
		(drill 0.254)
		(layers "F.Cu" "B.Cu")
		(net "P12V_AUX")
	)
	(via
		(at 221.4499 -399.067782)
		(size 0.508)
		(drill 0.254)
		(layers "F.Cu" "B.Cu")
		(net "P12V_AUX")
	)
	(via
		(at 245.686072 -381.305816)
		(size 0.508)
		(drill 0.254)
		(layers "F.Cu" "B.Cu")
		(net "P12V_AUX")
	)
	(via
		(at 229.8319 -396.781782)
		(size 0.508)
		(drill 0.254)
		(layers "F.Cu" "B.Cu")
		(net "P12V_AUX")
	)
	(via
		(at 456.809348 -177.94097)
		(size 0.508)
		(drill 0.254)
		(layers "F.Cu" "B.Cu")
		(net "P12V_AUX")
	)
	(via
		(at 137.96518 -110.423198)
		(size 0.508)
		(drill 0.254)
		(layers "F.Cu" "B.Cu")
		(net "P12V_AUX")
	)
	(via
		(at 229.8319 -399.067782)
		(size 0.508)
		(drill 0.254)
		(layers "F.Cu" "B.Cu")
		(net "P12V_AUX")
	)
	(via
		(at 237.179612 -378.765816)
		(size 0.508)
		(drill 0.254)
		(layers "F.Cu" "B.Cu")
		(net "P12V_AUX")
	)
	(via
		(at 115.447572 -71.321422)
		(size 0.508)
		(drill 0.254)
		(layers "F.Cu" "B.Cu")
		(net "P12V_AUX")
	)
	(via
		(at 116.187474 -143.924528)
		(size 0.508)
		(drill 0.254)
		(layers "F.Cu" "B.Cu")
		(net "P12V_AUX")
	)
	(via
		(at 241.656108 -380.035816)
		(size 0.508)
		(drill 0.254)
		(layers "F.Cu" "B.Cu")
		(net "P12V_AUX")
	)
	(via
		(at 92.95892 -353.163124)
		(size 0.508)
		(drill 0.254)
		(layers "F.Cu" "B.Cu")
		(net "P12V_AUX")
	)
	(via
		(at 252.891036 -380.035816)
		(size 0.508)
		(drill 0.254)
		(layers "F.Cu" "B.Cu")
		(net "P12V_AUX")
	)
	(via
		(at 24.444198 -406.020524)
		(size 0.508)
		(drill 0.254)
		(layers "F.Cu" "B.Cu")
		(net "P12V_AUX")
	)
	(via
		(at 186.380628 -398.905984)
		(size 0.508)
		(drill 0.254)
		(layers "F.Cu" "B.Cu")
		(net "P12V_AUX")
	)
	(via
		(at 367.463832 -154.420316)
		(size 0.508)
		(drill 0.254)
		(layers "F.Cu" "B.Cu")
		(net "P12V_AUX")
	)
	(via
		(at 342.775286 -359.787444)
		(size 0.508)
		(drill 0.254)
		(layers "F.Cu" "B.Cu")
		(net "P12V_AUX")
	)
	(via
		(at 47.766732 -362.21924)
		(size 0.508)
		(drill 0.254)
		(layers "F.Cu" "B.Cu")
		(net "P12V_AUX")
	)
	(via
		(at 247.591072 -379.400816)
		(size 0.508)
		(drill 0.254)
		(layers "F.Cu" "B.Cu")
		(net "P12V_AUX")
	)
	(via
		(at 187.142628 -398.905984)
		(size 0.508)
		(drill 0.254)
		(layers "F.Cu" "B.Cu")
		(net "P12V_AUX")
	)
	(via
		(at 208.4959 -398.305782)
		(size 0.508)
		(drill 0.254)
		(layers "F.Cu" "B.Cu")
		(net "P12V_AUX")
	)
	(via
		(at 442.994288 -27.869642)
		(size 0.4572)
		(drill 0.254)
		(layers "F.Cu" "B.Cu")
		(net "P12V_AUX")
	)
	(via
		(at 459.476348 -178.57597)
		(size 0.508)
		(drill 0.254)
		(layers "F.Cu" "B.Cu")
		(net "P12V_AUX")
	)
	(via
		(at 272.600928 -379.400816)
		(size 0.508)
		(drill 0.254)
		(layers "F.Cu" "B.Cu")
		(net "P12V_AUX")
	)
	(via
		(at 180.873146 -363.289342)
		(size 0.508)
		(drill 0.254)
		(layers "F.Cu" "B.Cu")
		(net "P12V_AUX")
	)
	(via
		(at 372.797832 -154.420316)
		(size 0.508)
		(drill 0.254)
		(layers "F.Cu" "B.Cu")
		(net "P12V_AUX")
	)
	(via
		(at 116.822474 -145.829528)
		(size 0.508)
		(drill 0.254)
		(layers "F.Cu" "B.Cu")
		(net "P12V_AUX")
	)
	(via
		(at 264.125964 -380.035816)
		(size 0.508)
		(drill 0.254)
		(layers "F.Cu" "B.Cu")
		(net "P12V_AUX")
	)
	(via
		(at 60.956952 -36.064444)
		(size 0.508)
		(drill 0.254)
		(layers "F.Cu" "B.Cu")
		(net "P12V_AUX")
	)
	(via
		(at 201.6379 -396.019782)
		(size 0.508)
		(drill 0.254)
		(layers "F.Cu" "B.Cu")
		(net "P12V_AUX")
	)
	(via
		(at 242.291108 -380.035816)
		(size 0.508)
		(drill 0.254)
		(layers "F.Cu" "B.Cu")
		(net "P12V_AUX")
	)
	(via
		(at 271.965928 -380.035816)
		(size 0.508)
		(drill 0.254)
		(layers "F.Cu" "B.Cu")
		(net "P12V_AUX")
	)
	(via
		(at 116.140992 -71.791322)
		(size 0.508)
		(drill 0.254)
		(layers "F.Cu" "B.Cu")
		(net "P12V_AUX")
	)
	(via
		(at 210.7819 -395.257782)
		(size 0.508)
		(drill 0.254)
		(layers "F.Cu" "B.Cu")
		(net "P12V_AUX")
	)
	(via
		(at 73.292462 -26.671524)
		(size 0.508)
		(drill 0.254)
		(layers "F.Cu" "B.Cu")
		(net "P12V_AUX")
	)
	(via
		(at 117.559074 -145.194528)
		(size 0.508)
		(drill 0.254)
		(layers "F.Cu" "B.Cu")
		(net "P12V_AUX")
	)
	(via
		(at 337.459066 -360.419904)
		(size 0.508)
		(drill 0.254)
		(layers "F.Cu" "B.Cu")
		(net "P12V_AUX")
	)
	(via
		(at 181.847236 -29.105352)
		(size 0.508)
		(drill 0.254)
		(layers "F.Cu" "B.Cu")
		(net "P12V_AUX")
	)
	(via
		(at 88.636856 -351.815908)
		(size 0.508)
		(drill 0.254)
		(layers "F.Cu" "B.Cu")
		(net "P12V_AUX")
	)
	(via
		(at 291.02177 -362.89869)
		(size 0.508)
		(drill 0.254)
		(layers "F.Cu" "B.Cu")
		(net "P12V_AUX")
	)
	(via
		(at 190.190628 -395.857984)
		(size 0.508)
		(drill 0.254)
		(layers "F.Cu" "B.Cu")
		(net "P12V_AUX")
	)
	(via
		(at 442.994288 -28.504642)
		(size 0.4572)
		(drill 0.254)
		(layers "F.Cu" "B.Cu")
		(net "P12V_AUX")
	)
	(via
		(at 456.809348 -179.84597)
		(size 0.508)
		(drill 0.254)
		(layers "F.Cu" "B.Cu")
		(net "P12V_AUX")
	)
	(via
		(at 14.238478 -200.7235)
		(size 0.508)
		(drill 0.254)
		(layers "F.Cu" "B.Cu")
		(net "P12V_AUX")
	)
	(via
		(at 257.632454 -45.643546)
		(size 0.508)
		(drill 0.254)
		(layers "F.Cu" "B.Cu")
		(net "P12V_AUX")
	)
	(via
		(at 368.987832 -155.944316)
		(size 0.508)
		(drill 0.254)
		(layers "F.Cu" "B.Cu")
		(net "P12V_AUX")
	)
	(via
		(at 231.3559 -395.257782)
		(size 0.508)
		(drill 0.254)
		(layers "F.Cu" "B.Cu")
		(net "P12V_AUX")
	)
	(via
		(at 184.803034 -395.821662)
		(size 0.508)
		(drill 0.254)
		(layers "F.Cu" "B.Cu")
		(net "P12V_AUX")
	)
	(via
		(at 242.926108 -378.765816)
		(size 0.508)
		(drill 0.254)
		(layers "F.Cu" "B.Cu")
		(net "P12V_AUX")
	)
	(via
		(at 89.88806 -103.91648)
		(size 0.508)
		(drill 0.254)
		(layers "F.Cu" "B.Cu")
		(net "P12V_AUX")
	)
	(via
		(at 251.621036 -380.670816)
		(size 0.508)
		(drill 0.254)
		(layers "F.Cu" "B.Cu")
		(net "P12V_AUX")
	)
	(via
		(at 275.360892 -380.035816)
		(size 0.508)
		(drill 0.254)
		(layers "F.Cu" "B.Cu")
		(net "P12V_AUX")
	)
	(via
		(at 371.273832 -155.944316)
		(size 0.508)
		(drill 0.254)
		(layers "F.Cu" "B.Cu")
		(net "P12V_AUX")
	)
	(via
		(at 252.256036 -380.670816)
		(size 0.508)
		(drill 0.254)
		(layers "F.Cu" "B.Cu")
		(net "P12V_AUX")
	)
	(via
		(at 197.8279 -398.305782)
		(size 0.508)
		(drill 0.254)
		(layers "F.Cu" "B.Cu")
		(net "P12V_AUX")
	)
	(via
		(at 200.1139 -395.257782)
		(size 0.508)
		(drill 0.254)
		(layers "F.Cu" "B.Cu")
		(net "P12V_AUX")
	)
	(via
		(at 288.24301 -362.411772)
		(size 0.508)
		(drill 0.254)
		(layers "F.Cu" "B.Cu")
		(net "P12V_AUX")
	)
	(via
		(at 224.175828 -269.743682)
		(size 0.508)
		(drill 0.254)
		(layers "F.Cu" "B.Cu")
		(net "P12V_AUX")
	)
	(via
		(at 435.430422 -41.015412)
		(size 0.508)
		(drill 0.254)
		(layers "F.Cu" "B.Cu")
		(net "P12V_AUX")
	)
	(via
		(at 453.148192 -415.76625)
		(size 0.508)
		(drill 0.254)
		(layers "F.Cu" "B.Cu")
		(net "P12V_AUX")
	)
	(via
		(at 253.544324 -49.832514)
		(size 0.4572)
		(drill 0.254)
		(layers "F.Cu" "B.Cu")
		(net "P12V_AUX")
	)
	(via
		(at 90.939874 -157.327092)
		(size 0.508)
		(drill 0.254)
		(layers "F.Cu" "B.Cu")
		(net "P12V_AUX")
	)
	(via
		(at 287.61563 -363.488732)
		(size 0.508)
		(drill 0.254)
		(layers "F.Cu" "B.Cu")
		(net "P12V_AUX")
	)
	(via
		(at 84.843874 -155.828492)
		(size 0.508)
		(drill 0.254)
		(layers "F.Cu" "B.Cu")
		(net "P12V_AUX")
	)
	(via
		(at 269.425928 -379.400816)
		(size 0.508)
		(drill 0.254)
		(layers "F.Cu" "B.Cu")
		(net "P12V_AUX")
	)
	(via
		(at 91.701874 -156.590492)
		(size 0.508)
		(drill 0.254)
		(layers "F.Cu" "B.Cu")
		(net "P12V_AUX")
	)
	(via
		(at 451.795642 -415.110676)
		(size 0.508)
		(drill 0.254)
		(layers "F.Cu" "B.Cu")
		(net "P12V_AUX")
	)
	(via
		(at 187.142628 -395.095984)
		(size 0.508)
		(drill 0.254)
		(layers "F.Cu" "B.Cu")
		(net "P12V_AUX")
	)
	(via
		(at 90.177874 -153.542492)
		(size 0.508)
		(drill 0.254)
		(layers "F.Cu" "B.Cu")
		(net "P12V_AUX")
	)
	(via
		(at 89.906856 -351.180908)
		(size 0.508)
		(drill 0.254)
		(layers "F.Cu" "B.Cu")
		(net "P12V_AUX")
	)
	(via
		(at 219.1639 -398.305782)
		(size 0.508)
		(drill 0.254)
		(layers "F.Cu" "B.Cu")
		(net "P12V_AUX")
	)
	(via
		(at 86.367874 -156.590492)
		(size 0.508)
		(drill 0.254)
		(layers "F.Cu" "B.Cu")
		(net "P12V_AUX")
	)
	(via
		(at 458.587348 -177.30597)
		(size 0.508)
		(drill 0.254)
		(layers "F.Cu" "B.Cu")
		(net "P12V_AUX")
	)
	(via
		(at 76.499466 -27.941524)
		(size 0.508)
		(drill 0.254)
		(layers "F.Cu" "B.Cu")
		(net "P12V_AUX")
	)
	(via
		(at 25.815798 -406.045924)
		(size 0.508)
		(drill 0.254)
		(layers "F.Cu" "B.Cu")
		(net "P12V_AUX")
	)
	(via
		(at 263.490964 -378.765816)
		(size 0.508)
		(drill 0.254)
		(layers "F.Cu" "B.Cu")
		(net "P12V_AUX")
	)
	(via
		(at 264.760964 -378.765816)
		(size 0.508)
		(drill 0.254)
		(layers "F.Cu" "B.Cu")
		(net "P12V_AUX")
	)
	(via
		(at 91.176856 -351.815908)
		(size 0.508)
		(drill 0.254)
		(layers "F.Cu" "B.Cu")
		(net "P12V_AUX")
	)
	(via
		(at 181.508146 -359.911142)
		(size 0.508)
		(drill 0.254)
		(layers "F.Cu" "B.Cu")
		(net "P12V_AUX")
	)
	(via
		(at 336.704686 -361.059984)
		(size 0.508)
		(drill 0.254)
		(layers "F.Cu" "B.Cu")
		(net "P12V_AUX")
	)
	(via
		(at 268.570964 -379.400816)
		(size 0.508)
		(drill 0.254)
		(layers "F.Cu" "B.Cu")
		(net "P12V_AUX")
	)
	(via
		(at 436.090822 -42.285412)
		(size 0.508)
		(drill 0.254)
		(layers "F.Cu" "B.Cu")
		(net "P12V_AUX")
	)
	(via
		(at 230.5939 -396.019782)
		(size 0.508)
		(drill 0.254)
		(layers "F.Cu" "B.Cu")
		(net "P12V_AUX")
	)
	(via
		(at 365.939832 -154.420316)
		(size 0.508)
		(drill 0.254)
		(layers "F.Cu" "B.Cu")
		(net "P12V_AUX")
	)
	(via
		(at 441.392564 -362.930948)
		(size 0.508)
		(drill 0.254)
		(layers "F.Cu" "B.Cu")
		(net "P12V_AUX")
	)
	(via
		(at 90.177874 -156.590492)
		(size 0.508)
		(drill 0.254)
		(layers "F.Cu" "B.Cu")
		(net "P12V_AUX")
	)
	(via
		(at 340.499446 -360.430064)
		(size 0.508)
		(drill 0.254)
		(layers "F.Cu" "B.Cu")
		(net "P12V_AUX")
	)
	(via
		(at 46.496732 -361.58424)
		(size 0.508)
		(drill 0.254)
		(layers "F.Cu" "B.Cu")
		(net "P12V_AUX")
	)
	(via
		(at 275.360892 -380.670816)
		(size 0.508)
		(drill 0.254)
		(layers "F.Cu" "B.Cu")
		(net "P12V_AUX")
	)
	(via
		(at 251.23775 -272.029936)
		(size 0.508)
		(drill 0.254)
		(layers "F.Cu" "B.Cu")
		(net "P12V_AUX")
	)
	(via
		(at 88.001856 -353.720908)
		(size 0.508)
		(drill 0.254)
		(layers "F.Cu" "B.Cu")
		(net "P12V_AUX")
	)
	(via
		(at 208.4959 -399.067782)
		(size 0.508)
		(drill 0.254)
		(layers "F.Cu" "B.Cu")
		(net "P12V_AUX")
	)
	(via
		(at 198.5899 -395.257782)
		(size 0.508)
		(drill 0.254)
		(layers "F.Cu" "B.Cu")
		(net "P12V_AUX")
	)
	(via
		(at 277.265892 -380.035816)
		(size 0.508)
		(drill 0.254)
		(layers "F.Cu" "B.Cu")
		(net "P12V_AUX")
	)
	(via
		(at 249.496072 -378.765816)
		(size 0.508)
		(drill 0.254)
		(layers "F.Cu" "B.Cu")
		(net "P12V_AUX")
	)
	(via
		(at 222.9739 -396.781782)
		(size 0.508)
		(drill 0.254)
		(layers "F.Cu" "B.Cu")
		(net "P12V_AUX")
	)
	(via
		(at 237.846108 -378.765816)
		(size 0.508)
		(drill 0.254)
		(layers "F.Cu" "B.Cu")
		(net "P12V_AUX")
	)
	(via
		(at 186.380628 -396.619984)
		(size 0.508)
		(drill 0.254)
		(layers "F.Cu" "B.Cu")
		(net "P12V_AUX")
	)
	(via
		(at 274.505928 -379.400816)
		(size 0.508)
		(drill 0.254)
		(layers "F.Cu" "B.Cu")
		(net "P12V_AUX")
	)
	(via
		(at 460.375508 -181.21503)
		(size 0.508)
		(drill 0.254)
		(layers "F.Cu" "B.Cu")
		(net "P12V_AUX")
	)
	(via
		(at 15.557754 -197.540372)
		(size 0.508)
		(drill 0.254)
		(layers "F.Cu" "B.Cu")
		(net "P12V_AUX")
	)
	(via
		(at 187.904628 -396.619984)
		(size 0.508)
		(drill 0.254)
		(layers "F.Cu" "B.Cu")
		(net "P12V_AUX")
	)
	(via
		(at 91.811856 -351.815908)
		(size 0.508)
		(drill 0.254)
		(layers "F.Cu" "B.Cu")
		(net "P12V_AUX")
	)
	(via
		(at 232.8799 -397.543782)
		(size 0.508)
		(drill 0.254)
		(layers "F.Cu" "B.Cu")
		(net "P12V_AUX")
	)
	(via
		(at 24.415496 -404.738332)
		(size 0.508)
		(drill 0.254)
		(layers "F.Cu" "B.Cu")
		(net "P12V_AUX")
	)
	(via
		(at 288.88563 -363.488732)
		(size 0.508)
		(drill 0.254)
		(layers "F.Cu" "B.Cu")
		(net "P12V_AUX")
	)
	(via
		(at 260.096 -379.400816)
		(size 0.508)
		(drill 0.254)
		(layers "F.Cu" "B.Cu")
		(net "P12V_AUX")
	)
	(via
		(at 438.173622 -41.015412)
		(size 0.508)
		(drill 0.254)
		(layers "F.Cu" "B.Cu")
		(net "P12V_AUX")
	)
	(via
		(at 190.190628 -395.095984)
		(size 0.508)
		(drill 0.254)
		(layers "F.Cu" "B.Cu")
		(net "P12V_AUX")
	)
	(via
		(at 270.695928 -379.400816)
		(size 0.508)
		(drill 0.254)
		(layers "F.Cu" "B.Cu")
		(net "P12V_AUX")
	)
	(via
		(at 258.826 -379.400816)
		(size 0.508)
		(drill 0.254)
		(layers "F.Cu" "B.Cu")
		(net "P12V_AUX")
	)
	(via
		(at 338.975446 -360.430064)
		(size 0.508)
		(drill 0.254)
		(layers "F.Cu" "B.Cu")
		(net "P12V_AUX")
	)
	(via
		(at 233.6419 -399.067782)
		(size 0.508)
		(drill 0.254)
		(layers "F.Cu" "B.Cu")
		(net "P12V_AUX")
	)
	(via
		(at 188.666628 -398.905984)
		(size 0.508)
		(drill 0.254)
		(layers "F.Cu" "B.Cu")
		(net "P12V_AUX")
	)
	(via
		(at 219.1639 -399.067782)
		(size 0.508)
		(drill 0.254)
		(layers "F.Cu" "B.Cu")
		(net "P12V_AUX")
	)
	(via
		(at 331.359764 -133.538722)
		(size 0.508)
		(drill 0.254)
		(layers "F.Cu" "B.Cu")
		(net "P12V_AUX")
	)
	(via
		(at 457.7207 -180.57876)
		(size 0.508)
		(drill 0.254)
		(layers "F.Cu" "B.Cu")
		(net "P12V_AUX")
	)
	(via
		(at 92.202762 -354.429822)
		(size 0.508)
		(drill 0.254)
		(layers "F.Cu" "B.Cu")
		(net "P12V_AUX")
	)
	(via
		(at 449.387976 -27.450542)
		(size 0.508)
		(drill 0.254)
		(layers "F.Cu" "B.Cu")
		(net "P12V_AUX")
	)
	(via
		(at 198.5899 -397.543782)
		(size 0.508)
		(drill 0.254)
		(layers "F.Cu" "B.Cu")
		(net "P12V_AUX")
	)
	(via
		(at 261.366 -378.765816)
		(size 0.508)
		(drill 0.254)
		(layers "F.Cu" "B.Cu")
		(net "P12V_AUX")
	)
	(via
		(at 213.0679 -396.781782)
		(size 0.508)
		(drill 0.254)
		(layers "F.Cu" "B.Cu")
		(net "P12V_AUX")
	)
	(via
		(at 372.797832 -155.944316)
		(size 0.508)
		(drill 0.254)
		(layers "F.Cu" "B.Cu")
		(net "P12V_AUX")
	)
	(via
		(at 366.701832 -154.420316)
		(size 0.508)
		(drill 0.254)
		(layers "F.Cu" "B.Cu")
		(net "P12V_AUX")
	)
	(via
		(at 87.319358 -354.372164)
		(size 0.508)
		(drill 0.254)
		(layers "F.Cu" "B.Cu")
		(net "P12V_AUX")
	)
	(via
		(at 442.094366 -27.869642)
		(size 0.4572)
		(drill 0.254)
		(layers "F.Cu" "B.Cu")
		(net "P12V_AUX")
	)
	(via
		(at 345.061286 -359.787444)
		(size 0.508)
		(drill 0.254)
		(layers "F.Cu" "B.Cu")
		(net "P12V_AUX")
	)
	(via
		(at 118.829074 -143.924528)
		(size 0.508)
		(drill 0.254)
		(layers "F.Cu" "B.Cu")
		(net "P12V_AUX")
	)
	(via
		(at 229.8319 -396.019782)
		(size 0.508)
		(drill 0.254)
		(layers "F.Cu" "B.Cu")
		(net "P12V_AUX")
	)
	(via
		(at 260.096 -380.670816)
		(size 0.508)
		(drill 0.254)
		(layers "F.Cu" "B.Cu")
		(net "P12V_AUX")
	)
	(via
		(at 337.438746 -359.102152)
		(size 0.508)
		(drill 0.254)
		(layers "F.Cu" "B.Cu")
		(net "P12V_AUX")
	)
	(via
		(at 436.090822 -41.650412)
		(size 0.508)
		(drill 0.254)
		(layers "F.Cu" "B.Cu")
		(net "P12V_AUX")
	)
	(via
		(at 14.922754 -201.350372)
		(size 0.508)
		(drill 0.254)
		(layers "F.Cu" "B.Cu")
		(net "P12V_AUX")
	)
	(via
		(at 83.847686 -153.894282)
		(size 0.508)
		(drill 0.254)
		(layers "F.Cu" "B.Cu")
		(net "P12V_AUX")
	)
	(via
		(at 339.737446 -360.430064)
		(size 0.508)
		(drill 0.254)
		(layers "F.Cu" "B.Cu")
		(net "P12V_AUX")
	)
	(via
		(at 198.5899 -399.067782)
		(size 0.508)
		(drill 0.254)
		(layers "F.Cu" "B.Cu")
		(net "P12V_AUX")
	)
	(via
		(at 436.090822 -40.355012)
		(size 0.508)
		(drill 0.254)
		(layers "F.Cu" "B.Cu")
		(net "P12V_AUX")
	)
	(via
		(at 369.681252 -156.810456)
		(size 0.508)
		(drill 0.254)
		(layers "F.Cu" "B.Cu")
		(net "P12V_AUX")
	)
	(via
		(at 379.853444 -152.384252)
		(size 0.508)
		(drill 0.254)
		(layers "F.Cu" "B.Cu")
		(net "P12V_AUX")
	)
	(via
		(at 286.23641 -362.881672)
		(size 0.508)
		(drill 0.254)
		(layers "F.Cu" "B.Cu")
		(net "P12V_AUX")
	)
	(via
		(at 241.656108 -380.670816)
		(size 0.508)
		(drill 0.254)
		(layers "F.Cu" "B.Cu")
		(net "P12V_AUX")
	)
	(via
		(at 212.3059 -396.019782)
		(size 0.508)
		(drill 0.254)
		(layers "F.Cu" "B.Cu")
		(net "P12V_AUX")
	)
	(via
		(at 79.007462 -27.941524)
		(size 0.508)
		(drill 0.254)
		(layers "F.Cu" "B.Cu")
		(net "P12V_AUX")
	)
	(via
		(at 270.060928 -379.400816)
		(size 0.508)
		(drill 0.254)
		(layers "F.Cu" "B.Cu")
		(net "P12V_AUX")
	)
	(via
		(at 449.387976 -28.187142)
		(size 0.508)
		(drill 0.254)
		(layers "F.Cu" "B.Cu")
		(net "P12V_AUX")
	)
	(via
		(at 219.1639 -396.781782)
		(size 0.508)
		(drill 0.254)
		(layers "F.Cu" "B.Cu")
		(net "P12V_AUX")
	)
	(via
		(at 371.273832 -157.468316)
		(size 0.508)
		(drill 0.254)
		(layers "F.Cu" "B.Cu")
		(net "P12V_AUX")
	)
	(via
		(at 222.651828 -269.743682)
		(size 0.508)
		(drill 0.254)
		(layers "F.Cu" "B.Cu")
		(net "P12V_AUX")
	)
	(via
		(at 270.060928 -380.670816)
		(size 0.508)
		(drill 0.254)
		(layers "F.Cu" "B.Cu")
		(net "P12V_AUX")
	)
	(via
		(at 182.228236 -34.312352)
		(size 0.508)
		(drill 0.254)
		(layers "F.Cu" "B.Cu")
		(net "P12V_AUX")
	)
	(via
		(at 180.238146 -363.924342)
		(size 0.508)
		(drill 0.254)
		(layers "F.Cu" "B.Cu")
		(net "P12V_AUX")
	)
	(via
		(at 372.035832 -157.468316)
		(size 0.508)
		(drill 0.254)
		(layers "F.Cu" "B.Cu")
		(net "P12V_AUX")
	)
	(via
		(at 259.791454 -45.668946)
		(size 0.508)
		(drill 0.254)
		(layers "F.Cu" "B.Cu")
		(net "P12V_AUX")
	)
	(via
		(at 380.488444 -153.755852)
		(size 0.508)
		(drill 0.254)
		(layers "F.Cu" "B.Cu")
		(net "P12V_AUX")
	)
	(via
		(at 23.03145 -405.328882)
		(size 0.508)
		(drill 0.254)
		(layers "F.Cu" "B.Cu")
		(net "P12V_AUX")
	)
	(via
		(at 91.176856 -350.545908)
		(size 0.508)
		(drill 0.254)
		(layers "F.Cu" "B.Cu")
		(net "P12V_AUX")
	)
	(via
		(at 267.300964 -379.400816)
		(size 0.508)
		(drill 0.254)
		(layers "F.Cu" "B.Cu")
		(net "P12V_AUX")
	)
	(via
		(at 437.411622 -39.694612)
		(size 0.508)
		(drill 0.254)
		(layers "F.Cu" "B.Cu")
		(net "P12V_AUX")
	)
	(via
		(at 460.558896 -49.453546)
		(size 0.508)
		(drill 0.254)
		(layers "F.Cu" "B.Cu")
		(net "P12V_AUX")
	)
	(via
		(at 230.5939 -399.067782)
		(size 0.508)
		(drill 0.254)
		(layers "F.Cu" "B.Cu")
		(net "P12V_AUX")
	)
	(via
		(at 252.256036 -380.035816)
		(size 0.508)
		(drill 0.254)
		(layers "F.Cu" "B.Cu")
		(net "P12V_AUX")
	)
	(via
		(at 255.431036 -379.400816)
		(size 0.508)
		(drill 0.254)
		(layers "F.Cu" "B.Cu")
		(net "P12V_AUX")
	)
	(via
		(at 254.691134 -48.081946)
		(size 0.508)
		(drill 0.254)
		(layers "F.Cu" "B.Cu")
		(net "P12V_AUX")
	)
	(via
		(at 23.729696 -404.738332)
		(size 0.508)
		(drill 0.254)
		(layers "F.Cu" "B.Cu")
		(net "P12V_AUX")
	)
	(via
		(at 220.6879 -395.257782)
		(size 0.508)
		(drill 0.254)
		(layers "F.Cu" "B.Cu")
		(net "P12V_AUX")
	)
	(via
		(at 25.101296 -405.398732)
		(size 0.508)
		(drill 0.254)
		(layers "F.Cu" "B.Cu")
		(net "P12V_AUX")
	)
	(via
		(at 285.60141 -362.881672)
		(size 0.508)
		(drill 0.254)
		(layers "F.Cu" "B.Cu")
		(net "P12V_AUX")
	)
	(via
		(at 457.698348 -177.94097)
		(size 0.508)
		(drill 0.254)
		(layers "F.Cu" "B.Cu")
		(net "P12V_AUX")
	)
	(via
		(at 89.492328 -353.539044)
		(size 0.508)
		(drill 0.254)
		(layers "F.Cu" "B.Cu")
		(net "P12V_AUX")
	)
	(via
		(at 62.964822 -25.538684)
		(size 0.508)
		(drill 0.254)
		(layers "F.Cu" "B.Cu")
		(net "P12V_AUX")
	)
	(via
		(at 220.6879 -398.305782)
		(size 0.508)
		(drill 0.254)
		(layers "F.Cu" "B.Cu")
		(net "P12V_AUX")
	)
	(via
		(at 437.411622 -40.355012)
		(size 0.508)
		(drill 0.254)
		(layers "F.Cu" "B.Cu")
		(net "P12V_AUX")
	)
	(via
		(at 219.9259 -396.781782)
		(size 0.508)
		(drill 0.254)
		(layers "F.Cu" "B.Cu")
		(net "P12V_AUX")
	)
	(via
		(at 87.891874 -155.066492)
		(size 0.508)
		(drill 0.254)
		(layers "F.Cu" "B.Cu")
		(net "P12V_AUX")
	)
	(via
		(at 365.939832 -158.230316)
		(size 0.508)
		(drill 0.254)
		(layers "F.Cu" "B.Cu")
		(net "P12V_AUX")
	)
	(via
		(at 181.034436 -29.105352)
		(size 0.508)
		(drill 0.254)
		(layers "F.Cu" "B.Cu")
		(net "P12V_AUX")
	)
	(via
		(at 254.179324 -50.73269)
		(size 0.4572)
		(drill 0.254)
		(layers "F.Cu" "B.Cu")
		(net "P12V_AUX")
	)
	(via
		(at 189.428628 -395.095984)
		(size 0.508)
		(drill 0.254)
		(layers "F.Cu" "B.Cu")
		(net "P12V_AUX")
	)
	(via
		(at 372.797832 -157.468316)
		(size 0.508)
		(drill 0.254)
		(layers "F.Cu" "B.Cu")
		(net "P12V_AUX")
	)
	(via
		(at 84.173314 -155.828492)
		(size 0.508)
		(drill 0.254)
		(layers "F.Cu" "B.Cu")
		(net "P12V_AUX")
	)
	(via
		(at 103.7717 -141.6939)
		(size 0.508)
		(drill 0.254)
		(layers "F.Cu" "B.Cu")
		(net "P12V_AUX")
	)
	(via
		(at 251.99975 -272.029936)
		(size 0.508)
		(drill 0.254)
		(layers "F.Cu" "B.Cu")
		(net "P12V_AUX")
	)
	(via
		(at 172.987716 -26.585672)
		(size 0.508)
		(drill 0.254)
		(layers "F.Cu" "B.Cu")
		(net "P12V_AUX")
	)
	(via
		(at 291.02177 -362.26369)
		(size 0.508)
		(drill 0.254)
		(layers "F.Cu" "B.Cu")
		(net "P12V_AUX")
	)
	(via
		(at 379.129544 -155.640532)
		(size 0.508)
		(drill 0.254)
		(layers "F.Cu" "B.Cu")
		(net "P12V_AUX")
	)
	(via
		(at 47.131732 -361.58424)
		(size 0.508)
		(drill 0.254)
		(layers "F.Cu" "B.Cu")
		(net "P12V_AUX")
	)
	(via
		(at 288.24301 -364.151672)
		(size 0.508)
		(drill 0.254)
		(layers "F.Cu" "B.Cu")
		(net "P12V_AUX")
	)
	(via
		(at 459.476348 -177.94097)
		(size 0.508)
		(drill 0.254)
		(layers "F.Cu" "B.Cu")
		(net "P12V_AUX")
	)
	(via
		(at 200.8759 -395.257782)
		(size 0.508)
		(drill 0.254)
		(layers "F.Cu" "B.Cu")
		(net "P12V_AUX")
	)
	(via
		(at 50.287682 -360.062272)
		(size 0.508)
		(drill 0.254)
		(layers "F.Cu" "B.Cu")
		(net "P12V_AUX")
	)
	(via
		(at 257.556 -380.670816)
		(size 0.508)
		(drill 0.254)
		(layers "F.Cu" "B.Cu")
		(net "P12V_AUX")
	)
	(via
		(at 75.12177 -18.4912)
		(size 0.508)
		(drill 0.254)
		(layers "F.Cu" "B.Cu")
		(net "P12V_AUX")
	)
	(via
		(at 10.792714 -416.218624)
		(size 0.508)
		(drill 0.254)
		(layers "F.Cu" "B.Cu")
		(net "P12V_AUX")
	)
	(via
		(at 138.335512 -73.439782)
		(size 0.508)
		(drill 0.254)
		(layers "F.Cu" "B.Cu")
		(net "P12V_AUX")
	)
	(via
		(at 222.2119 -398.305782)
		(size 0.508)
		(drill 0.254)
		(layers "F.Cu" "B.Cu")
		(net "P12V_AUX")
	)
	(via
		(at 379.789944 -155.660852)
		(size 0.508)
		(drill 0.254)
		(layers "F.Cu" "B.Cu")
		(net "P12V_AUX")
	)
	(via
		(at 254.161036 -378.765816)
		(size 0.508)
		(drill 0.254)
		(layers "F.Cu" "B.Cu")
		(net "P12V_AUX")
	)
	(via
		(at 87.366856 -351.815908)
		(size 0.508)
		(drill 0.254)
		(layers "F.Cu" "B.Cu")
		(net "P12V_AUX")
	)
	(via
		(at 48.382682 -361.332272)
		(size 0.508)
		(drill 0.254)
		(layers "F.Cu" "B.Cu")
		(net "P12V_AUX")
	)
	(via
		(at 232.1179 -396.781782)
		(size 0.508)
		(drill 0.254)
		(layers "F.Cu" "B.Cu")
		(net "P12V_AUX")
	)
	(via
		(at 437.411622 -41.650412)
		(size 0.508)
		(drill 0.254)
		(layers "F.Cu" "B.Cu")
		(net "P12V_AUX")
	)
	(via
		(at 331.93101 -132.772404)
		(size 0.508)
		(drill 0.254)
		(layers "F.Cu" "B.Cu")
		(net "P12V_AUX")
	)
	(via
		(at 459.476348 -179.84597)
		(size 0.508)
		(drill 0.254)
		(layers "F.Cu" "B.Cu")
		(net "P12V_AUX")
	)
	(via
		(at 369.749832 -155.944316)
		(size 0.508)
		(drill 0.254)
		(layers "F.Cu" "B.Cu")
		(net "P12V_AUX")
	)
	(via
		(at 456.809348 -177.30597)
		(size 0.508)
		(drill 0.254)
		(layers "F.Cu" "B.Cu")
		(net "P12V_AUX")
	)
	(via
		(at 245.686072 -380.035816)
		(size 0.508)
		(drill 0.254)
		(layers "F.Cu" "B.Cu")
		(net "P12V_AUX")
	)
	(via
		(at 290.24961 -364.151672)
		(size 0.508)
		(drill 0.254)
		(layers "F.Cu" "B.Cu")
		(net "P12V_AUX")
	)
	(via
		(at 221.889828 -269.743682)
		(size 0.508)
		(drill 0.254)
		(layers "F.Cu" "B.Cu")
		(net "P12V_AUX")
	)
	(via
		(at 200.1139 -398.305782)
		(size 0.508)
		(drill 0.254)
		(layers "F.Cu" "B.Cu")
		(net "P12V_AUX")
	)
	(via
		(at 370.306092 -157.948376)
		(size 0.508)
		(drill 0.254)
		(layers "F.Cu" "B.Cu")
		(net "P12V_AUX")
	)
	(via
		(at 71.844662 -29.363924)
		(size 0.508)
		(drill 0.254)
		(layers "F.Cu" "B.Cu")
		(net "P12V_AUX")
	)
	(via
		(at 210.7819 -397.543782)
		(size 0.508)
		(drill 0.254)
		(layers "F.Cu" "B.Cu")
		(net "P12V_AUX")
	)
	(via
		(at 181.034436 -29.841952)
		(size 0.508)
		(drill 0.254)
		(layers "F.Cu" "B.Cu")
		(net "P12V_AUX")
	)
	(via
		(at 244.196108 -378.765816)
		(size 0.508)
		(drill 0.254)
		(layers "F.Cu" "B.Cu")
		(net "P12V_AUX")
	)
	(via
		(at 87.129874 -154.304492)
		(size 0.508)
		(drill 0.254)
		(layers "F.Cu" "B.Cu")
		(net "P12V_AUX")
	)
	(via
		(at 460.365348 -179.21097)
		(size 0.508)
		(drill 0.254)
		(layers "F.Cu" "B.Cu")
		(net "P12V_AUX")
	)
	(via
		(at 266.030964 -379.400816)
		(size 0.508)
		(drill 0.254)
		(layers "F.Cu" "B.Cu")
		(net "P12V_AUX")
	)
	(via
		(at 241.021108 -380.670816)
		(size 0.508)
		(drill 0.254)
		(layers "F.Cu" "B.Cu")
		(net "P12V_AUX")
	)
	(via
		(at 338.965286 -357.839772)
		(size 0.508)
		(drill 0.254)
		(layers "F.Cu" "B.Cu")
		(net "P12V_AUX")
	)
	(via
		(at 456.809348 -178.57597)
		(size 0.508)
		(drill 0.254)
		(layers "F.Cu" "B.Cu")
		(net "P12V_AUX")
	)
	(via
		(at 381.631444 -155.660852)
		(size 0.508)
		(drill 0.254)
		(layers "F.Cu" "B.Cu")
		(net "P12V_AUX")
	)
	(via
		(at 222.651828 -273.071082)
		(size 0.508)
		(drill 0.254)
		(layers "F.Cu" "B.Cu")
		(net "P12V_AUX")
	)
	(via
		(at 238.481108 -381.305816)
		(size 0.508)
		(drill 0.254)
		(layers "F.Cu" "B.Cu")
		(net "P12V_AUX")
	)
	(via
		(at 198.5899 -396.781782)
		(size 0.508)
		(drill 0.254)
		(layers "F.Cu" "B.Cu")
		(net "P12V_AUX")
	)
	(via
		(at 248.226072 -380.035816)
		(size 0.508)
		(drill 0.254)
		(layers "F.Cu" "B.Cu")
		(net "P12V_AUX")
	)
	(via
		(at 89.487502 -354.386642)
		(size 0.508)
		(drill 0.254)
		(layers "F.Cu" "B.Cu")
		(net "P12V_AUX")
	)
	(via
		(at 86.367874 -155.828492)
		(size 0.508)
		(drill 0.254)
		(layers "F.Cu" "B.Cu")
		(net "P12V_AUX")
	)
	(via
		(at 118.829074 -144.559528)
		(size 0.508)
		(drill 0.254)
		(layers "F.Cu" "B.Cu")
		(net "P12V_AUX")
	)
	(via
		(at 274.505928 -378.765816)
		(size 0.508)
		(drill 0.254)
		(layers "F.Cu" "B.Cu")
		(net "P12V_AUX")
	)
	(via
		(at 85.605874 -157.327092)
		(size 0.508)
		(drill 0.254)
		(layers "F.Cu" "B.Cu")
		(net "P12V_AUX")
	)
	(via
		(at 46.496732 -362.21924)
		(size 0.508)
		(drill 0.254)
		(layers "F.Cu" "B.Cu")
		(net "P12V_AUX")
	)
	(via
		(at 185.618628 -395.857984)
		(size 0.508)
		(drill 0.254)
		(layers "F.Cu" "B.Cu")
		(net "P12V_AUX")
	)
	(via
		(at 368.401092 -157.948376)
		(size 0.508)
		(drill 0.254)
		(layers "F.Cu" "B.Cu")
		(net "P12V_AUX")
	)
	(via
		(at 446.009776 -28.212542)
		(size 0.508)
		(drill 0.254)
		(layers "F.Cu" "B.Cu")
		(net "P12V_AUX")
	)
	(via
		(at 232.8799 -395.257782)
		(size 0.508)
		(drill 0.254)
		(layers "F.Cu" "B.Cu")
		(net "P12V_AUX")
	)
	(via
		(at 240.386108 -379.400816)
		(size 0.508)
		(drill 0.254)
		(layers "F.Cu" "B.Cu")
		(net "P12V_AUX")
	)
	(via
		(at 35.65144 -109.26064)
		(size 0.508)
		(drill 0.254)
		(layers "F.Cu" "B.Cu")
		(net "P12V_AUX")
	)
	(via
		(at 453.172576 -28.949142)
		(size 0.508)
		(drill 0.254)
		(layers "F.Cu" "B.Cu")
		(net "P12V_AUX")
	)
	(via
		(at 266.030964 -380.035816)
		(size 0.508)
		(drill 0.254)
		(layers "F.Cu" "B.Cu")
		(net "P12V_AUX")
	)
	(via
		(at 89.210134 -157.060392)
		(size 0.508)
		(drill 0.254)
		(layers "F.Cu" "B.Cu")
		(net "P12V_AUX")
	)
	(via
		(at 197.8279 -399.067782)
		(size 0.508)
		(drill 0.254)
		(layers "F.Cu" "B.Cu")
		(net "P12V_AUX")
	)
	(via
		(at 451.109842 -415.771076)
		(size 0.508)
		(drill 0.254)
		(layers "F.Cu" "B.Cu")
		(net "P12V_AUX")
	)
	(via
		(at 271.965928 -381.305816)
		(size 0.508)
		(drill 0.254)
		(layers "F.Cu" "B.Cu")
		(net "P12V_AUX")
	)
	(via
		(at 379.853444 -156.460952)
		(size 0.508)
		(drill 0.254)
		(layers "F.Cu" "B.Cu")
		(net "P12V_AUX")
	)
	(via
		(at 379.129544 -153.735532)
		(size 0.508)
		(drill 0.254)
		(layers "F.Cu" "B.Cu")
		(net "P12V_AUX")
	)
	(via
		(at 14.922754 -200.080372)
		(size 0.508)
		(drill 0.254)
		(layers "F.Cu" "B.Cu")
		(net "P12V_AUX")
	)
	(via
		(at 181.508146 -363.289342)
		(size 0.508)
		(drill 0.254)
		(layers "F.Cu" "B.Cu")
		(net "P12V_AUX")
	)
	(via
		(at 23.03145 -404.693882)
		(size 0.508)
		(drill 0.254)
		(layers "F.Cu" "B.Cu")
		(net "P12V_AUX")
	)
	(via
		(at 199.3519 -395.257782)
		(size 0.508)
		(drill 0.254)
		(layers "F.Cu" "B.Cu")
		(net "P12V_AUX")
	)
	(via
		(at 442.662564 -358.282748)
		(size 0.508)
		(drill 0.254)
		(layers "F.Cu" "B.Cu")
		(net "P12V_AUX")
	)
	(via
		(at 254.796036 -378.765816)
		(size 0.508)
		(drill 0.254)
		(layers "F.Cu" "B.Cu")
		(net "P12V_AUX")
	)
	(via
		(at 69.22135 -27.573224)
		(size 0.4572)
		(drill 0.254)
		(layers "F.Cu" "B.Cu")
		(net "P12V_AUX")
	)
	(via
		(at 89.202514 -155.960572)
		(size 0.508)
		(drill 0.254)
		(layers "F.Cu" "B.Cu")
		(net "P12V_AUX")
	)
	(via
		(at 72.479662 -26.671524)
		(size 0.508)
		(drill 0.254)
		(layers "F.Cu" "B.Cu")
		(net "P12V_AUX")
	)
	(via
		(at 213.0679 -397.543782)
		(size 0.508)
		(drill 0.254)
		(layers "F.Cu" "B.Cu")
		(net "P12V_AUX")
	)
	(via
		(at 453.793352 -415.155888)
		(size 0.508)
		(drill 0.254)
		(layers "F.Cu" "B.Cu")
		(net "P12V_AUX")
	)
	(via
		(at 47.131732 -360.31424)
		(size 0.508)
		(drill 0.254)
		(layers "F.Cu" "B.Cu")
		(net "P12V_AUX")
	)
	(via
		(at 176.544224 -29.255212)
		(size 0.4572)
		(drill 0.254)
		(layers "F.Cu" "B.Cu")
		(net "P12V_AUX")
	)
	(via
		(at 249.023124 -55.443882)
		(size 0.508)
		(drill 0.254)
		(layers "F.Cu" "B.Cu")
		(net "P12V_AUX")
	)
	(via
		(at 221.4499 -398.305782)
		(size 0.508)
		(drill 0.254)
		(layers "F.Cu" "B.Cu")
		(net "P12V_AUX")
	)
	(via
		(at 457.698348 -177.30597)
		(size 0.508)
		(drill 0.254)
		(layers "F.Cu" "B.Cu")
		(net "P12V_AUX")
	)
	(via
		(at 213.0679 -396.019782)
		(size 0.508)
		(drill 0.254)
		(layers "F.Cu" "B.Cu")
		(net "P12V_AUX")
	)
	(via
		(at 381.631444 -155.025852)
		(size 0.508)
		(drill 0.254)
		(layers "F.Cu" "B.Cu")
		(net "P12V_AUX")
	)
	(via
		(at 286.22625 -361.565952)
		(size 0.508)
		(drill 0.254)
		(layers "F.Cu" "B.Cu")
		(net "P12V_AUX")
	)
	(via
		(at 88.636856 -353.085908)
		(size 0.508)
		(drill 0.254)
		(layers "F.Cu" "B.Cu")
		(net "P12V_AUX")
	)
	(via
		(at 46.70806 -98.59772)
		(size 0.508)
		(drill 0.254)
		(layers "F.Cu" "B.Cu")
		(net "P12V_AUX")
	)
	(via
		(at 241.656108 -381.305816)
		(size 0.508)
		(drill 0.254)
		(layers "F.Cu" "B.Cu")
		(net "P12V_AUX")
	)
	(via
		(at 49.017682 -361.332272)
		(size 0.508)
		(drill 0.254)
		(layers "F.Cu" "B.Cu")
		(net "P12V_AUX")
	)
	(via
		(at 271.330928 -381.305816)
		(size 0.508)
		(drill 0.254)
		(layers "F.Cu" "B.Cu")
		(net "P12V_AUX")
	)
	(via
		(at 369.671092 -157.948376)
		(size 0.508)
		(drill 0.254)
		(layers "F.Cu" "B.Cu")
		(net "P12V_AUX")
	)
	(via
		(at 365.939832 -155.944316)
		(size 0.508)
		(drill 0.254)
		(layers "F.Cu" "B.Cu")
		(net "P12V_AUX")
	)
	(via
		(at 89.425018 -352.46691)
		(size 0.508)
		(drill 0.254)
		(layers "F.Cu" "B.Cu")
		(net "P12V_AUX")
	)
	(via
		(at 222.651828 -271.407382)
		(size 0.508)
		(drill 0.254)
		(layers "F.Cu" "B.Cu")
		(net "P12V_AUX")
	)
	(via
		(at 246.956072 -380.035816)
		(size 0.508)
		(drill 0.254)
		(layers "F.Cu" "B.Cu")
		(net "P12V_AUX")
	)
	(via
		(at 15.557754 -200.080372)
		(size 0.508)
		(drill 0.254)
		(layers "F.Cu" "B.Cu")
		(net "P12V_AUX")
	)
	(via
		(at 87.366856 -353.085908)
		(size 0.508)
		(drill 0.254)
		(layers "F.Cu" "B.Cu")
		(net "P12V_AUX")
	)
	(via
		(at 369.036092 -157.948376)
		(size 0.508)
		(drill 0.254)
		(layers "F.Cu" "B.Cu")
		(net "P12V_AUX")
	)
	(via
		(at 201.134218 -387.160516)
		(size 0.508)
		(drill 0.254)
		(layers "F.Cu" "B.Cu")
		(net "P12V_AUX")
	)
	(via
		(at 210.0199 -398.305782)
		(size 0.508)
		(drill 0.254)
		(layers "F.Cu" "B.Cu")
		(net "P12V_AUX")
	)
	(via
		(at 185.618628 -395.095984)
		(size 0.762)
		(drill 0.254)
		(layers "F.Cu" "B.Cu")
		(net "P12V_AUX")
	)
	(via
		(at 93.609922 -353.797616)
		(size 0.508)
		(drill 0.254)
		(layers "F.Cu" "B.Cu")
		(net "P12V_AUX")
	)
	(via
		(at 336.686906 -359.777284)
		(size 0.508)
		(drill 0.254)
		(layers "F.Cu" "B.Cu")
		(net "P12V_AUX")
	)
	(via
		(at 442.027564 -359.654348)
		(size 0.508)
		(drill 0.254)
		(layers "F.Cu" "B.Cu")
		(net "P12V_AUX")
	)
	(via
		(at 52.211732 -360.31424)
		(size 0.508)
		(drill 0.254)
		(layers "F.Cu" "B.Cu")
		(net "P12V_AUX")
	)
	(via
		(at 116.822474 -143.924528)
		(size 0.508)
		(drill 0.254)
		(layers "F.Cu" "B.Cu")
		(net "P12V_AUX")
	)
	(via
		(at 370.316252 -156.810456)
		(size 0.508)
		(drill 0.254)
		(layers "F.Cu" "B.Cu")
		(net "P12V_AUX")
	)
	(via
		(at 335.924906 -359.777284)
		(size 0.508)
		(drill 0.254)
		(layers "F.Cu" "B.Cu")
		(net "P12V_AUX")
	)
	(via
		(at 276.630892 -379.400816)
		(size 0.508)
		(drill 0.254)
		(layers "F.Cu" "B.Cu")
		(net "P12V_AUX")
	)
	(via
		(at 52.847494 -360.32567)
		(size 0.508)
		(drill 0.254)
		(layers "F.Cu" "B.Cu")
		(net "P12V_AUX")
	)
	(via
		(at 209.2579 -399.067782)
		(size 0.508)
		(drill 0.254)
		(layers "F.Cu" "B.Cu")
		(net "P12V_AUX")
	)
	(via
		(at 199.3519 -399.067782)
		(size 0.508)
		(drill 0.254)
		(layers "F.Cu" "B.Cu")
		(net "P12V_AUX")
	)
	(via
		(at 257.766312 -68.180458)
		(size 0.508)
		(drill 0.254)
		(layers "F.Cu" "B.Cu")
		(net "P12V_AUX")
	)
	(via
		(at 270.695928 -378.765816)
		(size 0.508)
		(drill 0.254)
		(layers "F.Cu" "B.Cu")
		(net "P12V_AUX")
	)
	(via
		(at 202.3999 -395.257782)
		(size 0.508)
		(drill 0.254)
		(layers "F.Cu" "B.Cu")
		(net "P12V_AUX")
	)
	(via
		(at 180.873146 -359.911142)
		(size 0.508)
		(drill 0.254)
		(layers "F.Cu" "B.Cu")
		(net "P12V_AUX")
	)
	(via
		(at 330.601828 -46.748954)
		(size 0.508)
		(drill 0.254)
		(layers "F.Cu" "B.Cu")
		(net "P12V_AUX")
	)
	(via
		(at 90.939874 -153.542492)
		(size 0.508)
		(drill 0.254)
		(layers "F.Cu" "B.Cu")
		(net "P12V_AUX")
	)
	(via
		(at 92.250514 -353.134168)
		(size 0.508)
		(drill 0.254)
		(layers "F.Cu" "B.Cu")
		(net "P12V_AUX")
	)
	(via
		(at 49.652682 -360.697272)
		(size 0.508)
		(drill 0.254)
		(layers "F.Cu" "B.Cu")
		(net "P12V_AUX")
	)
	(via
		(at 184.803034 -395.059662)
		(size 0.508)
		(drill 0.254)
		(layers "F.Cu" "B.Cu")
		(net "P12V_AUX")
	)
	(via
		(at 440.122564 -358.282748)
		(size 0.508)
		(drill 0.254)
		(layers "F.Cu" "B.Cu")
		(net "P12V_AUX")
	)
	(via
		(at 380.488444 -152.384252)
		(size 0.508)
		(drill 0.254)
		(layers "F.Cu" "B.Cu")
		(net "P12V_AUX")
	)
	(via
		(at 84.709508 -153.166826)
		(size 0.508)
		(drill 0.254)
		(layers "F.Cu" "B.Cu")
		(net "P12V_AUX")
	)
	(via
		(at 259.461 -379.400816)
		(size 0.508)
		(drill 0.254)
		(layers "F.Cu" "B.Cu")
		(net "P12V_AUX")
	)
	(via
		(at 345.061286 -357.839772)
		(size 0.508)
		(drill 0.254)
		(layers "F.Cu" "B.Cu")
		(net "P12V_AUX")
	)
	(via
		(at 379.853444 -157.095952)
		(size 0.508)
		(drill 0.254)
		(layers "F.Cu" "B.Cu")
		(net "P12V_AUX")
	)
	(via
		(at 23.758398 -406.020524)
		(size 0.508)
		(drill 0.254)
		(layers "F.Cu" "B.Cu")
		(net "P12V_AUX")
	)
	(via
		(at 229.8319 -397.543782)
		(size 0.508)
		(drill 0.254)
		(layers "F.Cu" "B.Cu")
		(net "P12V_AUX")
	)
	(via
		(at 265.395964 -379.400816)
		(size 0.508)
		(drill 0.254)
		(layers "F.Cu" "B.Cu")
		(net "P12V_AUX")
	)
	(via
		(at 273.235928 -378.765816)
		(size 0.508)
		(drill 0.254)
		(layers "F.Cu" "B.Cu")
		(net "P12V_AUX")
	)
	(via
		(at 88.567514 -155.960572)
		(size 0.508)
		(drill 0.254)
		(layers "F.Cu" "B.Cu")
		(net "P12V_AUX")
	)
	(via
		(at 437.411622 -42.285412)
		(size 0.508)
		(drill 0.254)
		(layers "F.Cu" "B.Cu")
		(net "P12V_AUX")
	)
	(via
		(at 14.238478 -200.0885)
		(size 0.508)
		(drill 0.254)
		(layers "F.Cu" "B.Cu")
		(net "P12V_AUX")
	)
	(via
		(at 342.785446 -360.430064)
		(size 0.508)
		(drill 0.254)
		(layers "F.Cu" "B.Cu")
		(net "P12V_AUX")
	)
	(via
		(at 250.766072 -378.765816)
		(size 0.508)
		(drill 0.254)
		(layers "F.Cu" "B.Cu")
		(net "P12V_AUX")
	)
	(via
		(at 14.922754 -196.905372)
		(size 0.508)
		(drill 0.254)
		(layers "F.Cu" "B.Cu")
		(net "P12V_AUX")
	)
	(via
		(at 379.789944 -155.025852)
		(size 0.508)
		(drill 0.254)
		(layers "F.Cu" "B.Cu")
		(net "P12V_AUX")
	)
	(via
		(at 219.9259 -396.019782)
		(size 0.508)
		(drill 0.254)
		(layers "F.Cu" "B.Cu")
		(net "P12V_AUX")
	)
	(via
		(at 252.891036 -381.305816)
		(size 0.508)
		(drill 0.254)
		(layers "F.Cu" "B.Cu")
		(net "P12V_AUX")
	)
	(via
		(at 50.903632 -359.727246)
		(size 0.508)
		(drill 0.254)
		(layers "F.Cu" "B.Cu")
		(net "P12V_AUX")
	)
	(via
		(at 91.404186 -354.386642)
		(size 0.508)
		(drill 0.254)
		(layers "F.Cu" "B.Cu")
		(net "P12V_AUX")
	)
	(via
		(at 87.891874 -154.304492)
		(size 0.508)
		(drill 0.254)
		(layers "F.Cu" "B.Cu")
		(net "P12V_AUX")
	)
	(via
		(at 50.941732 -361.073954)
		(size 0.508)
		(drill 0.254)
		(layers "F.Cu" "B.Cu")
		(net "P12V_AUX")
	)
	(via
		(at 88.636856 -351.180908)
		(size 0.508)
		(drill 0.254)
		(layers "F.Cu" "B.Cu")
		(net "P12V_AUX")
	)
	(via
		(at 209.2579 -396.781782)
		(size 0.508)
		(drill 0.254)
		(layers "F.Cu" "B.Cu")
		(net "P12V_AUX")
	)
	(via
		(at 87.960708 -354.391468)
		(size 0.508)
		(drill 0.254)
		(layers "F.Cu" "B.Cu")
		(net "P12V_AUX")
	)
	(via
		(at 46.496732 -359.67924)
		(size 0.508)
		(drill 0.254)
		(layers "F.Cu" "B.Cu")
		(net "P12V_AUX")
	)
	(via
		(at 258.826 -381.305816)
		(size 0.508)
		(drill 0.254)
		(layers "F.Cu" "B.Cu")
		(net "P12V_AUX")
	)
	(via
		(at 370.511832 -155.182316)
		(size 0.508)
		(drill 0.254)
		(layers "F.Cu" "B.Cu")
		(net "P12V_AUX")
	)
	(via
		(at 340.507066 -361.070144)
		(size 0.508)
		(drill 0.254)
		(layers "F.Cu" "B.Cu")
		(net "P12V_AUX")
	)
	(via
		(at 344.299286 -357.839772)
		(size 0.508)
		(drill 0.254)
		(layers "F.Cu" "B.Cu")
		(net "P12V_AUX")
	)
	(via
		(at 88.001856 -352.450908)
		(size 0.508)
		(drill 0.254)
		(layers "F.Cu" "B.Cu")
		(net "P12V_AUX")
	)
	(via
		(at 14.238478 -198.8185)
		(size 0.508)
		(drill 0.254)
		(layers "F.Cu" "B.Cu")
		(net "P12V_AUX")
	)
	(via
		(at 254.161036 -381.305816)
		(size 0.508)
		(drill 0.254)
		(layers "F.Cu" "B.Cu")
		(net "P12V_AUX")
	)
	(via
		(at 197.8279 -397.543782)
		(size 0.508)
		(drill 0.254)
		(layers "F.Cu" "B.Cu")
		(net "P12V_AUX")
	)
	(via
		(at 183.676036 -31.619952)
		(size 0.508)
		(drill 0.254)
		(layers "F.Cu" "B.Cu")
		(net "P12V_AUX")
	)
	(via
		(at 342.601042 -358.045004)
		(size 0.508)
		(drill 0.254)
		(layers "F.Cu" "B.Cu")
		(net "P12V_AUX")
	)
	(via
		(at 222.2119 -396.781782)
		(size 0.508)
		(drill 0.254)
		(layers "F.Cu" "B.Cu")
		(net "P12V_AUX")
	)
	(via
		(at 237.179612 -379.400816)
		(size 0.508)
		(drill 0.254)
		(layers "F.Cu" "B.Cu")
		(net "P12V_AUX")
	)
	(via
		(at 182.863236 -31.619952)
		(size 0.508)
		(drill 0.254)
		(layers "F.Cu" "B.Cu")
		(net "P12V_AUX")
	)
	(via
		(at 269.425928 -380.670816)
		(size 0.508)
		(drill 0.254)
		(layers "F.Cu" "B.Cu")
		(net "P12V_AUX")
	)
	(via
		(at 91.701874 -155.066492)
		(size 0.508)
		(drill 0.254)
		(layers "F.Cu" "B.Cu")
		(net "P12V_AUX")
	)
	(via
		(at 265.395964 -380.670816)
		(size 0.508)
		(drill 0.254)
		(layers "F.Cu" "B.Cu")
		(net "P12V_AUX")
	)
	(via
		(at 451.66407 -23.109428)
		(size 0.508)
		(drill 0.254)
		(layers "F.Cu" "B.Cu")
		(net "P12V_AUX")
	)
	(via
		(at 188.666628 -395.857984)
		(size 0.508)
		(drill 0.254)
		(layers "F.Cu" "B.Cu")
		(net "P12V_AUX")
	)
	(via
		(at 370.511832 -155.944316)
		(size 0.508)
		(drill 0.254)
		(layers "F.Cu" "B.Cu")
		(net "P12V_AUX")
	)
	(via
		(at 230.5939 -398.305782)
		(size 0.508)
		(drill 0.254)
		(layers "F.Cu" "B.Cu")
		(net "P12V_AUX")
	)
	(via
		(at 240.386108 -380.670816)
		(size 0.508)
		(drill 0.254)
		(layers "F.Cu" "B.Cu")
		(net "P12V_AUX")
	)
	(via
		(at 117.559074 -144.559528)
		(size 0.508)
		(drill 0.254)
		(layers "F.Cu" "B.Cu")
		(net "P12V_AUX")
	)
	(via
		(at 338.221066 -361.070144)
		(size 0.508)
		(drill 0.254)
		(layers "F.Cu" "B.Cu")
		(net "P12V_AUX")
	)
	(via
		(at 232.8799 -399.067782)
		(size 0.508)
		(drill 0.254)
		(layers "F.Cu" "B.Cu")
		(net "P12V_AUX")
	)
	(via
		(at 91.397328 -353.539044)
		(size 0.508)
		(drill 0.254)
		(layers "F.Cu" "B.Cu")
		(net "P12V_AUX")
	)
	(via
		(at 180.873146 -363.924342)
		(size 0.508)
		(drill 0.254)
		(layers "F.Cu" "B.Cu")
		(net "P12V_AUX")
	)
	(via
		(at 180.238146 -361.917742)
		(size 0.508)
		(drill 0.254)
		(layers "F.Cu" "B.Cu")
		(net "P12V_AUX")
	)
	(via
		(at 442.662564 -360.924348)
		(size 0.508)
		(drill 0.254)
		(layers "F.Cu" "B.Cu")
		(net "P12V_AUX")
	)
	(via
		(at 448.526916 -418.199824)
		(size 0.508)
		(drill 0.254)
		(layers "F.Cu" "B.Cu")
		(net "P12V_AUX")
	)
	(via
		(at 457.340716 -45.016166)
		(size 0.508)
		(drill 0.254)
		(layers "F.Cu" "B.Cu")
		(net "P12V_AUX")
	)
	(via
		(at 209.6008 -147.3962)
		(size 0.508)
		(drill 0.254)
		(layers "F.Cu" "B.Cu")
		(net "P12V_AUX")
	)
	(via
		(at 222.2119 -397.543782)
		(size 0.508)
		(drill 0.254)
		(layers "F.Cu" "B.Cu")
		(net "P12V_AUX")
	)
	(via
		(at 93.716856 -351.180908)
		(size 0.508)
		(drill 0.254)
		(layers "F.Cu" "B.Cu")
		(net "P12V_AUX")
	)
	(via
		(at 246.956072 -378.765816)
		(size 0.508)
		(drill 0.254)
		(layers "F.Cu" "B.Cu")
		(net "P12V_AUX")
	)
	(via
		(at 232.1179 -397.543782)
		(size 0.508)
		(drill 0.254)
		(layers "F.Cu" "B.Cu")
		(net "P12V_AUX")
	)
	(via
		(at 336.686906 -358.464612)
		(size 0.508)
		(drill 0.254)
		(layers "F.Cu" "B.Cu")
		(net "P12V_AUX")
	)
	(via
		(at 188.666628 -395.095984)
		(size 0.508)
		(drill 0.254)
		(layers "F.Cu" "B.Cu")
		(net "P12V_AUX")
	)
	(via
		(at 254.179324 -52.532534)
		(size 0.4572)
		(drill 0.254)
		(layers "F.Cu" "B.Cu")
		(net "P12V_AUX")
	)
	(via
		(at 229.8319 -395.257782)
		(size 0.762)
		(drill 0.254)
		(layers "F.Cu" "B.Cu")
		(net "P12V_AUX")
	)
	(via
		(at 290.24961 -362.246672)
		(size 0.508)
		(drill 0.254)
		(layers "F.Cu" "B.Cu")
		(net "P12V_AUX")
	)
	(segment
		(start 188.215524 -42.817288)
		(end 188.74359 -43.345354)
		(width 0.4572)
		(layer "B.Cu")
		(net "P12V_AUX")
	)
	(segment
		(start 457.340716 -45.047408)
		(end 456.809348 -45.578776)
		(width 0.381)
		(layer "B.Cu")
		(net "P12V_AUX")
	)
	(segment
		(start 188.043312 -431.387504)
		(end 188.043312 -430.614582)
		(width 0.4572)
		(layer "B.Cu")
		(net "P12V_AUX")
	)
	(segment
		(start 149.225 -119.458232)
		(end 149.58441 -119.098822)
		(width 0.4572)
		(layer "B.Cu")
		(net "P12V_AUX")
	)
	(segment
		(start 9.666732 -406.119584)
		(end 8.932418 -406.119584)
		(width 0.4572)
		(layer "B.Cu")
		(net "P12V_AUX")
	)
	(segment
		(start 440.122564 -363.132116)
		(end 437.831484 -365.423196)
		(width 0.381)
		(layer "B.Cu")
		(net "P12V_AUX")
	)
	(segment
		(start 149.58441 -119.098822)
		(end 151.285702 -119.098822)
		(width 0.4572)
		(layer "B.Cu")
		(net "P12V_AUX")
	)
	(segment
		(start 249.023124 -55.443882)
		(end 249.023124 -57.833768)
		(width 0.4572)
		(layer "B.Cu")
		(net "P12V_AUX")
	)
	(segment
		(start 456.809348 -45.578776)
		(end 456.690476 -45.578776)
		(width 0.381)
		(layer "B.Cu")
		(net "P12V_AUX")
	)
	(segment
		(start 65.694306 -30.012894)
		(end 66.425572 -28.247848)
		(width 0.4572)
		(layer "B.Cu")
		(net "P12V_AUX")
	)
	(segment
		(start 63.5762 -34.253678)
		(end 63.5762 -32.131)
		(width 0.4572)
		(layer "B.Cu")
		(net "P12V_AUX")
	)
	(segment
		(start 409.744926 -136.863074)
		(end 409.744926 -135.082026)
		(width 0.4572)
		(layer "B.Cu")
		(net "P12V_AUX")
	)
	(segment
		(start 151.285702 -119.098822)
		(end 151.436324 -118.9482)
		(width 0.4572)
		(layer "B.Cu")
		(net "P12V_AUX")
	)
	(segment
		(start 185.098436 -33.550352)
		(end 185.098436 -38.3032)
		(width 0.4572)
		(layer "B.Cu")
		(net "P12V_AUX")
	)
	(segment
		(start 407.67 -138.938)
		(end 409.744926 -136.863074)
		(width 0.4572)
		(layer "B.Cu")
		(net "P12V_AUX")
	)
	(segment
		(start 64.5668 -39.034212)
		(end 65.342008 -39.80942)
		(width 0.4572)
		(layer "B.Cu")
		(net "P12V_AUX")
	)
	(segment
		(start 188.290454 -430.017682)
		(end 188.290454 -428.965106)
		(width 0.4572)
		(layer "B.Cu")
		(net "P12V_AUX")
	)
	(segment
		(start 151.436324 -118.9482)
		(end 159.35198 -118.9482)
		(width 0.4572)
		(layer "B.Cu")
		(net "P12V_AUX")
	)
	(segment
		(start 255.528318 -64.338962)
		(end 256.326894 -64.338962)
		(width 0.4572)
		(layer "B.Cu")
		(net "P12V_AUX")
	)
	(segment
		(start 159.35198 -118.9482)
		(end 160.155128 -119.751348)
		(width 0.4572)
		(layer "B.Cu")
		(net "P12V_AUX")
	)
	(segment
		(start 10.792714 -416.218624)
		(end 12.234418 -414.77692)
		(width 0.4572)
		(layer "B.Cu")
		(net "P12V_AUX")
	)
	(segment
		(start 429.009556 -366.54105)
		(end 427.670214 -366.54105)
		(width 0.381)
		(layer "B.Cu")
		(net "P12V_AUX")
	)
	(segment
		(start 403.225 -138.938)
		(end 407.67 -138.938)
		(width 0.4572)
		(layer "B.Cu")
		(net "P12V_AUX")
	)
	(segment
		(start 62.156594 -36.064444)
		(end 64.5668 -38.47465)
		(width 0.4572)
		(layer "B.Cu")
		(net "P12V_AUX")
	)
	(segment
		(start 66.425572 -28.247848)
		(end 66.52133 -28.208224)
		(width 0.4572)
		(layer "B.Cu")
		(net "P12V_AUX")
	)
	(segment
		(start 63.5762 -32.131)
		(end 65.694306 -30.012894)
		(width 0.4572)
		(layer "B.Cu")
		(net "P12V_AUX")
	)
	(segment
		(start 188.290454 -428.965106)
		(end 188.27496 -428.949612)
		(width 0.4572)
		(layer "B.Cu")
		(net "P12V_AUX")
	)
	(segment
		(start 160.155128 -119.751348)
		(end 160.777936 -119.751348)
		(width 0.4572)
		(layer "B.Cu")
		(net "P12V_AUX")
	)
	(segment
		(start 437.831484 -365.423196)
		(end 430.12741 -365.423196)
		(width 0.381)
		(layer "B.Cu")
		(net "P12V_AUX")
	)
	(segment
		(start 64.5668 -38.47465)
		(end 64.5668 -39.034212)
		(width 0.4572)
		(layer "B.Cu")
		(net "P12V_AUX")
	)
	(segment
		(start 168.336468 -350.732344)
		(end 168.952418 -350.732344)
		(width 0.4572)
		(layer "B.Cu")
		(net "P12V_AUX")
	)
	(segment
		(start 399.796 -142.367)
		(end 403.225 -138.938)
		(width 0.4572)
		(layer "B.Cu")
		(net "P12V_AUX")
	)
	(segment
		(start 457.340716 -45.016166)
		(end 457.340716 -45.047408)
		(width 0.381)
		(layer "B.Cu")
		(net "P12V_AUX")
	)
	(segment
		(start 430.12741 -365.423196)
		(end 429.009556 -366.54105)
		(width 0.381)
		(layer "B.Cu")
		(net "P12V_AUX")
	)
	(segment
		(start 60.956952 -36.064444)
		(end 62.156594 -36.064444)
		(width 0.4572)
		(layer "B.Cu")
		(net "P12V_AUX")
	)
	(segment
		(start 60.956952 -36.064444)
		(end 60.956952 -35.6108)
		(width 0.4572)
		(layer "B.Cu")
		(net "P12V_AUX")
	)
	(segment
		(start 450.046852 -425.92371)
		(end 450.681852 -425.92371)
		(width 0.381)
		(layer "B.Cu")
		(net "P12V_AUX")
	)
	(segment
		(start 190.015368 -43.345354)
		(end 190.02375 -43.336972)
		(width 0.4572)
		(layer "B.Cu")
		(net "P12V_AUX")
	)
	(segment
		(start 60.956952 -35.6108)
		(end 61.414152 -35.1536)
		(width 0.4572)
		(layer "B.Cu")
		(net "P12V_AUX")
	)
	(segment
		(start 187.22721 -40.431974)
		(end 188.215524 -42.817288)
		(width 0.4572)
		(layer "B.Cu")
		(net "P12V_AUX")
	)
	(segment
		(start 188.74359 -43.345354)
		(end 190.015368 -43.345354)
		(width 0.4572)
		(layer "B.Cu")
		(net "P12V_AUX")
	)
	(segment
		(start 188.043312 -430.614582)
		(end 188.290454 -430.017682)
		(width 0.4572)
		(layer "B.Cu")
		(net "P12V_AUX")
	)
	(segment
		(start 249.023124 -57.833768)
		(end 255.528318 -64.338962)
		(width 0.4572)
		(layer "B.Cu")
		(net "P12V_AUX")
	)
	(segment
		(start 440.122564 -363.027468)
		(end 440.122564 -363.132116)
		(width 0.381)
		(layer "B.Cu")
		(net "P12V_AUX")
	)
	(segment
		(start 256.326894 -64.338962)
		(end 257.766312 -65.77838)
		(width 0.4572)
		(layer "B.Cu")
		(net "P12V_AUX")
	)
	(segment
		(start 399.796 -143.61795)
		(end 399.796 -142.367)
		(width 0.4572)
		(layer "B.Cu")
		(net "P12V_AUX")
	)
	(segment
		(start 448.526916 -418.199824)
		(end 447.275966 -419.450774)
		(width 0.4572)
		(layer "B.Cu")
		(net "P12V_AUX")
	)
	(segment
		(start 61.414152 -35.1536)
		(end 62.676278 -35.1536)
		(width 0.4572)
		(layer "B.Cu")
		(net "P12V_AUX")
	)
	(segment
		(start 188.27496 -428.949612)
		(end 188.27496 -427.56201)
		(width 0.4572)
		(layer "B.Cu")
		(net "P12V_AUX")
	)
	(segment
		(start 62.676278 -35.1536)
		(end 63.5762 -34.253678)
		(width 0.4572)
		(layer "B.Cu")
		(net "P12V_AUX")
	)
	(segment
		(start 185.098436 -38.3032)
		(end 187.22721 -40.431974)
		(width 0.4572)
		(layer "B.Cu")
		(net "P12V_AUX")
	)
	(segment
		(start 137.96518 -110.423198)
		(end 137.96518 -109.16158)
		(width 0.4572)
		(layer "In2.Cu")
		(net "P12V_AUX")
	)
	(segment
		(start 137.96518 -109.16158)
		(end 139.072366 -108.054394)
		(width 0.4572)
		(layer "In2.Cu")
		(net "P12V_AUX")
	)
	(segment
		(start 154.657044 -125.5776)
		(end 153.1747 -121.999502)
		(width 0.4572)
		(layer "In11.Cu")
		(net "P12V_AUX")
	)
	(segment
		(start 153.1747 -121.999502)
		(end 153.1747 -114.215164)
		(width 0.4572)
		(layer "In11.Cu")
		(net "P12V_AUX")
	)
	(segment
		(start 146.06905 -114.620802)
		(end 139.502642 -108.054394)
		(width 0.4572)
		(layer "In11.Cu")
		(net "P12V_AUX")
	)
	(segment
		(start 153.1747 -114.215164)
		(end 150.846536 -111.887)
		(width 0.4572)
		(layer "In11.Cu")
		(net "P12V_AUX")
	)
	(segment
		(start 147.230846 -113.253012)
		(end 147.230846 -113.459006)
		(width 0.4572)
		(layer "In11.Cu")
		(net "P12V_AUX")
	)
	(segment
		(start 147.230846 -113.459006)
		(end 146.06905 -114.620802)
		(width 0.4572)
		(layer "In11.Cu")
		(net "P12V_AUX")
	)
	(segment
		(start 150.846536 -111.887)
		(end 148.596858 -111.887)
		(width 0.4572)
		(layer "In11.Cu")
		(net "P12V_AUX")
	)
	(segment
		(start 257.766312 -68.180458)
		(end 257.766312 -65.77838)
		(width 0.4572)
		(layer "In11.Cu")
		(net "P12V_AUX")
	)
	(segment
		(start 139.502642 -108.054394)
		(end 139.072366 -108.054394)
		(width 0.4572)
		(layer "In11.Cu")
		(net "P12V_AUX")
	)
	(segment
		(start 148.596858 -111.887)
		(end 147.230846 -113.253012)
		(width 0.4572)
		(layer "In11.Cu")
		(net "P12V_AUX")
	)
	(segment
		(start 152.613106 -119.458232)
		(end 153.303986 -120.149112)
		(width 0.4572)
		(layer "In15.Cu")
		(net "P12V_AUX")
	)
	(segment
		(start 457.387452 -43.782488)
		(end 456.930252 -43.325288)
		(width 0.4572)
		(layer "In15.Cu")
		(net "P12V_AUX")
	)
	(segment
		(start 149.225 -119.458232)
		(end 152.613106 -119.458232)
		(width 0.4572)
		(layer "In15.Cu")
		(net "P12V_AUX")
	)
	(segment
		(start 438.188862 -39.694612)
		(end 441.462414 -36.42106)
		(width 0.4572)
		(layer "In15.Cu")
		(net "P12V_AUX")
	)
	(segment
		(start 457.387452 -44.96943)
		(end 457.387452 -43.782488)
		(width 0.4572)
		(layer "In15.Cu")
		(net "P12V_AUX")
	)
	(segment
		(start 460.558896 -49.453546)
		(end 460.558896 -46.982634)
		(width 0.4572)
		(layer "In15.Cu")
		(net "P12V_AUX")
	)
	(segment
		(start 457.76515 -46.244256)
		(end 457.387452 -45.866558)
		(width 0.4572)
		(layer "In15.Cu")
		(net "P12V_AUX")
	)
	(segment
		(start 456.930252 -43.325288)
		(end 452.753984 -43.325288)
		(width 0.4572)
		(layer "In15.Cu")
		(net "P12V_AUX")
	)
	(segment
		(start 451.214998 -39.00043)
		(end 451.214998 -41.786302)
		(width 0.4572)
		(layer "In15.Cu")
		(net "P12V_AUX")
	)
	(segment
		(start 457.340716 -45.016166)
		(end 457.387452 -44.96943)
		(width 0.4572)
		(layer "In15.Cu")
		(net "P12V_AUX")
	)
	(segment
		(start 438.173622 -39.694612)
		(end 438.188862 -39.694612)
		(width 0.4572)
		(layer "In15.Cu")
		(net "P12V_AUX")
	)
	(segment
		(start 451.214998 -41.786302)
		(end 452.753984 -43.325288)
		(width 0.4572)
		(layer "In15.Cu")
		(net "P12V_AUX")
	)
	(segment
		(start 448.635628 -36.42106)
		(end 451.214998 -39.00043)
		(width 0.4572)
		(layer "In15.Cu")
		(net "P12V_AUX")
	)
	(segment
		(start 457.387452 -45.866558)
		(end 457.387452 -45.062902)
		(width 0.4572)
		(layer "In15.Cu")
		(net "P12V_AUX")
	)
	(segment
		(start 441.462414 -36.42106)
		(end 448.635628 -36.42106)
		(width 0.4572)
		(layer "In15.Cu")
		(net "P12V_AUX")
	)
	(segment
		(start 153.303986 -124.224542)
		(end 154.657044 -125.5776)
		(width 0.4572)
		(layer "In15.Cu")
		(net "P12V_AUX")
	)
	(segment
		(start 460.558896 -46.982634)
		(end 459.820518 -46.244256)
		(width 0.4572)
		(layer "In15.Cu")
		(net "P12V_AUX")
	)
	(segment
		(start 457.387452 -45.062902)
		(end 457.340716 -45.016166)
		(width 0.4572)
		(layer "In15.Cu")
		(net "P12V_AUX")
	)
	(segment
		(start 153.303986 -120.149112)
		(end 153.303986 -124.224542)
		(width 0.4572)
		(layer "In15.Cu")
		(net "P12V_AUX")
	)
	(segment
		(start 459.820518 -46.244256)
		(end 457.76515 -46.244256)
		(width 0.4572)
		(layer "In15.Cu")
		(net "P12V_AUX")
	)
	(segment
		(start 193.167 -133.168898)
		(end 193.167 -132.382006)
		(width 0.10668)
		(layer "F.Cu")
		(net "P12V_ALL_PWROK_R")
	)
	(segment
		(start 189.12205 -120.252744)
		(end 189.51194 -120.642634)
		(width 0.10668)
		(layer "F.Cu")
		(net "P12V_ALL_PWROK_R")
	)
	(via
		(at 189.51194 -120.642634)
		(size 0.4572)
		(drill 0.254)
		(layers "F.Cu" "B.Cu")
		(net "P12V_ALL_PWROK_R")
	)
	(via
		(at 193.167 -132.382006)
		(size 0.508)
		(drill 0.254)
		(layers "F.Cu" "B.Cu")
		(net "P12V_ALL_PWROK_R")
	)
	(segment
		(start 190.596774 -121.049542)
		(end 189.918848 -121.049542)
		(width 0.11684)
		(layer "In2.Cu")
		(net "P12V_ALL_PWROK_R")
	)
	(segment
		(start 190.713868 -121.166636)
		(end 190.596774 -121.049542)
		(width 0.11684)
		(layer "In2.Cu")
		(net "P12V_ALL_PWROK_R")
	)
	(segment
		(start 190.983108 -124.354336)
		(end 190.713868 -124.085096)
		(width 0.11684)
		(layer "In2.Cu")
		(net "P12V_ALL_PWROK_R")
	)
	(segment
		(start 190.713868 -124.085096)
		(end 190.713868 -121.166636)
		(width 0.11684)
		(layer "In2.Cu")
		(net "P12V_ALL_PWROK_R")
	)
	(segment
		(start 193.695066 -131.338574)
		(end 193.695066 -126.019814)
		(width 0.11684)
		(layer "In2.Cu")
		(net "P12V_ALL_PWROK_R")
	)
	(segment
		(start 193.167 -131.86664)
		(end 193.695066 -131.338574)
		(width 0.11684)
		(layer "In2.Cu")
		(net "P12V_ALL_PWROK_R")
	)
	(segment
		(start 193.695066 -126.019814)
		(end 192.029588 -124.354336)
		(width 0.11684)
		(layer "In2.Cu")
		(net "P12V_ALL_PWROK_R")
	)
	(segment
		(start 189.918848 -121.049542)
		(end 189.51194 -120.642634)
		(width 0.11684)
		(layer "In2.Cu")
		(net "P12V_ALL_PWROK_R")
	)
	(segment
		(start 193.167 -132.382006)
		(end 193.167 -131.86664)
		(width 0.11684)
		(layer "In2.Cu")
		(net "P12V_ALL_PWROK_R")
	)
	(segment
		(start 192.029588 -124.354336)
		(end 190.983108 -124.354336)
		(width 0.11684)
		(layer "In2.Cu")
		(net "P12V_ALL_PWROK_R")
	)
	(segment
		(start 350.25203 -17.308068)
		(end 348.93123 -18.628868)
		(width 0.10668)
		(layer "F.Cu")
		(net "P12V_ALL_PWROK_N")
	)
	(segment
		(start 350.25203 -16.843502)
		(end 350.25203 -17.308068)
		(width 0.10668)
		(layer "F.Cu")
		(net "P12V_ALL_PWROK_N")
	)
	(segment
		(start 349.807784 -16.399256)
		(end 350.25203 -16.843502)
		(width 0.10668)
		(layer "F.Cu")
		(net "P12V_ALL_PWROK_N")
	)
	(segment
		(start 348.93123 -18.628868)
		(end 348.93123 -19.016726)
		(width 0.10668)
		(layer "F.Cu")
		(net "P12V_ALL_PWROK_N")
	)
	(segment
		(start 348.9325 -16.399256)
		(end 349.807784 -16.399256)
		(width 0.10668)
		(layer "F.Cu")
		(net "P12V_ALL_PWROK_N")
	)
	(via
		(at 350.25203 -17.308068)
		(size 0.762)
		(drill 0.381)
		(layers "F.Cu" "B.Cu")
		(net "P12V_ALL_PWROK_N")
	)
	(segment
		(start 193.167 -133.968998)
		(end 193.167 -134.58063)
		(width 0.10668)
		(layer "F.Cu")
		(net "P12V_ALL_PWROK")
	)
	(segment
		(start 349.931228 -21.256498)
		(end 349.931228 -22.247098)
		(width 0.10668)
		(layer "F.Cu")
		(net "P12V_ALL_PWROK")
	)
	(via
		(at 250.80976 -128.204468)
		(size 0.508)
		(drill 0.254)
		(layers "F.Cu" "B.Cu")
		(net "P12V_ALL_PWROK")
	)
	(via
		(at 249.772932 -114.052604)
		(size 0.508)
		(drill 0.254)
		(layers "F.Cu" "B.Cu")
		(net "P12V_ALL_PWROK")
	)
	(via
		(at 193.167 -134.58063)
		(size 0.508)
		(drill 0.254)
		(layers "F.Cu" "B.Cu")
		(net "P12V_ALL_PWROK")
	)
	(via
		(at 257.402584 -71.324724)
		(size 0.508)
		(drill 0.254)
		(layers "F.Cu" "B.Cu")
		(net "P12V_ALL_PWROK")
	)
	(via
		(at 349.931228 -22.247098)
		(size 0.508)
		(drill 0.254)
		(layers "F.Cu" "B.Cu")
		(net "P12V_ALL_PWROK")
	)
	(segment
		(start 193.68897 -135.1026)
		(end 194.67322 -135.1026)
		(width 0.11684)
		(layer "In2.Cu")
		(net "P12V_ALL_PWROK")
	)
	(segment
		(start 203.586842 -133.162548)
		(end 245.492778 -133.162548)
		(width 0.11684)
		(layer "In2.Cu")
		(net "P12V_ALL_PWROK")
	)
	(segment
		(start 201.204068 -135.545322)
		(end 203.586842 -133.162548)
		(width 0.11684)
		(layer "In2.Cu")
		(net "P12V_ALL_PWROK")
	)
	(segment
		(start 250.590812 -128.423416)
		(end 250.80976 -128.204468)
		(width 0.11684)
		(layer "In2.Cu")
		(net "P12V_ALL_PWROK")
	)
	(segment
		(start 245.492778 -133.162548)
		(end 250.23191 -128.423416)
		(width 0.11684)
		(layer "In2.Cu")
		(net "P12V_ALL_PWROK")
	)
	(segment
		(start 196.759576 -135.808212)
		(end 197.022466 -135.545322)
		(width 0.11684)
		(layer "In2.Cu")
		(net "P12V_ALL_PWROK")
	)
	(segment
		(start 250.23191 -128.423416)
		(end 250.590812 -128.423416)
		(width 0.11684)
		(layer "In2.Cu")
		(net "P12V_ALL_PWROK")
	)
	(segment
		(start 194.67322 -135.1026)
		(end 195.378832 -135.808212)
		(width 0.11684)
		(layer "In2.Cu")
		(net "P12V_ALL_PWROK")
	)
	(segment
		(start 193.167 -134.58063)
		(end 193.68897 -135.1026)
		(width 0.11684)
		(layer "In2.Cu")
		(net "P12V_ALL_PWROK")
	)
	(segment
		(start 197.022466 -135.545322)
		(end 201.204068 -135.545322)
		(width 0.11684)
		(layer "In2.Cu")
		(net "P12V_ALL_PWROK")
	)
	(segment
		(start 195.378832 -135.808212)
		(end 196.759576 -135.808212)
		(width 0.11684)
		(layer "In2.Cu")
		(net "P12V_ALL_PWROK")
	)
	(segment
		(start 250.17984 -126.74092)
		(end 250.17984 -114.459512)
		(width 0.11684)
		(layer "In4.Cu")
		(net "P12V_ALL_PWROK")
	)
	(segment
		(start 250.80976 -127.37084)
		(end 250.17984 -126.74092)
		(width 0.11684)
		(layer "In4.Cu")
		(net "P12V_ALL_PWROK")
	)
	(segment
		(start 250.17984 -114.459512)
		(end 249.772932 -114.052604)
		(width 0.11684)
		(layer "In4.Cu")
		(net "P12V_ALL_PWROK")
	)
	(segment
		(start 250.80976 -128.204468)
		(end 250.80976 -127.37084)
		(width 0.11684)
		(layer "In4.Cu")
		(net "P12V_ALL_PWROK")
	)
	(segment
		(start 328.682858 -27.544776)
		(end 343.916 -27.544776)
		(width 0.11684)
		(layer "In6.Cu")
		(net "P12V_ALL_PWROK")
	)
	(segment
		(start 292.669214 -42.9387)
		(end 303.540414 -42.9387)
		(width 0.11684)
		(layer "In6.Cu")
		(net "P12V_ALL_PWROK")
	)
	(segment
		(start 324.74535 -33.432496)
		(end 327.542144 -30.635702)
		(width 0.11684)
		(layer "In6.Cu")
		(net "P12V_ALL_PWROK")
	)
	(segment
		(start 266.18438 -64.050164)
		(end 271.55775 -64.050164)
		(width 0.11684)
		(layer "In6.Cu")
		(net "P12V_ALL_PWROK")
	)
	(segment
		(start 257.402584 -71.324724)
		(end 257.728974 -70.998334)
		(width 0.11684)
		(layer "In6.Cu")
		(net "P12V_ALL_PWROK")
	)
	(segment
		(start 303.540414 -42.9387)
		(end 304.05832 -43.456606)
		(width 0.11684)
		(layer "In6.Cu")
		(net "P12V_ALL_PWROK")
	)
	(segment
		(start 327.542144 -28.68549)
		(end 328.682858 -27.544776)
		(width 0.11684)
		(layer "In6.Cu")
		(net "P12V_ALL_PWROK")
	)
	(segment
		(start 307.801772 -43.456606)
		(end 307.989478 -43.2689)
		(width 0.11684)
		(layer "In6.Cu")
		(net "P12V_ALL_PWROK")
	)
	(segment
		(start 271.55775 -64.050164)
		(end 292.669214 -42.9387)
		(width 0.11684)
		(layer "In6.Cu")
		(net "P12V_ALL_PWROK")
	)
	(segment
		(start 307.989478 -43.2689)
		(end 316.49035 -43.2689)
		(width 0.11684)
		(layer "In6.Cu")
		(net "P12V_ALL_PWROK")
	)
	(segment
		(start 319.061084 -40.225726)
		(end 324.74535 -34.54146)
		(width 0.11684)
		(layer "In6.Cu")
		(net "P12V_ALL_PWROK")
	)
	(segment
		(start 319.061084 -40.698166)
		(end 319.061084 -40.225726)
		(width 0.11684)
		(layer "In6.Cu")
		(net "P12V_ALL_PWROK")
	)
	(segment
		(start 316.49035 -43.2689)
		(end 319.061084 -40.698166)
		(width 0.11684)
		(layer "In6.Cu")
		(net "P12V_ALL_PWROK")
	)
	(segment
		(start 324.74535 -34.54146)
		(end 324.74535 -33.432496)
		(width 0.11684)
		(layer "In6.Cu")
		(net "P12V_ALL_PWROK")
	)
	(segment
		(start 347.467428 -23.993348)
		(end 348.184978 -23.993348)
		(width 0.11684)
		(layer "In6.Cu")
		(net "P12V_ALL_PWROK")
	)
	(segment
		(start 348.184978 -23.993348)
		(end 349.931228 -22.247098)
		(width 0.11684)
		(layer "In6.Cu")
		(net "P12V_ALL_PWROK")
	)
	(segment
		(start 327.542144 -30.635702)
		(end 327.542144 -28.68549)
		(width 0.11684)
		(layer "In6.Cu")
		(net "P12V_ALL_PWROK")
	)
	(segment
		(start 257.728974 -70.998334)
		(end 259.23621 -70.998334)
		(width 0.11684)
		(layer "In6.Cu")
		(net "P12V_ALL_PWROK")
	)
	(segment
		(start 343.916 -27.544776)
		(end 347.467428 -23.993348)
		(width 0.11684)
		(layer "In6.Cu")
		(net "P12V_ALL_PWROK")
	)
	(segment
		(start 259.23621 -70.998334)
		(end 266.18438 -64.050164)
		(width 0.11684)
		(layer "In6.Cu")
		(net "P12V_ALL_PWROK")
	)
	(segment
		(start 304.05832 -43.456606)
		(end 307.801772 -43.456606)
		(width 0.11684)
		(layer "In6.Cu")
		(net "P12V_ALL_PWROK")
	)
	(segment
		(start 256.93878 -73.10628)
		(end 256.93878 -90.013028)
		(width 0.11684)
		(layer "In11.Cu")
		(net "P12V_ALL_PWROK")
	)
	(segment
		(start 258.4196 -95.562928)
		(end 254.48768 -99.494848)
		(width 0.11684)
		(layer "In11.Cu")
		(net "P12V_ALL_PWROK")
	)
	(segment
		(start 254.48768 -107.237784)
		(end 249.772932 -111.952532)
		(width 0.11684)
		(layer "In11.Cu")
		(net "P12V_ALL_PWROK")
	)
	(segment
		(start 257.402584 -71.324724)
		(end 257.402584 -72.642476)
		(width 0.11684)
		(layer "In11.Cu")
		(net "P12V_ALL_PWROK")
	)
	(segment
		(start 257.402584 -72.642476)
		(end 256.93878 -73.10628)
		(width 0.11684)
		(layer "In11.Cu")
		(net "P12V_ALL_PWROK")
	)
	(segment
		(start 249.772932 -111.952532)
		(end 249.772932 -114.052604)
		(width 0.11684)
		(layer "In11.Cu")
		(net "P12V_ALL_PWROK")
	)
	(segment
		(start 254.48768 -99.494848)
		(end 254.48768 -107.237784)
		(width 0.11684)
		(layer "In11.Cu")
		(net "P12V_ALL_PWROK")
	)
	(segment
		(start 258.4196 -91.493848)
		(end 258.4196 -95.562928)
		(width 0.11684)
		(layer "In11.Cu")
		(net "P12V_ALL_PWROK")
	)
	(segment
		(start 256.93878 -90.013028)
		(end 258.4196 -91.493848)
		(width 0.11684)
		(layer "In11.Cu")
		(net "P12V_ALL_PWROK")
	)
	(segment
		(start 168.270682 -113.622582)
		(end 165.964616 -113.622582)
		(width 0.10668)
		(layer "F.Cu")
		(net "OC_ALERT_N")
	)
	(segment
		(start 170.30954 -114.00536)
		(end 169.34434 -114.00536)
		(width 0.10668)
		(layer "F.Cu")
		(net "OC_ALERT_N")
	)
	(segment
		(start 172.41012 -114.21618)
		(end 171.979336 -113.785396)
		(width 0.10668)
		(layer "F.Cu")
		(net "OC_ALERT_N")
	)
	(segment
		(start 164.10305 -114.264948)
		(end 165.32225 -114.264948)
		(width 0.10668)
		(layer "F.Cu")
		(net "OC_ALERT_N")
	)
	(segment
		(start 165.964616 -113.622582)
		(end 165.32225 -114.264948)
		(width 0.10668)
		(layer "F.Cu")
		(net "OC_ALERT_N")
	)
	(segment
		(start 168.501568 -113.853468)
		(end 168.270682 -113.622582)
		(width 0.10668)
		(layer "F.Cu")
		(net "OC_ALERT_N")
	)
	(segment
		(start 177.122074 -113.85296)
		(end 176.4284 -113.85296)
		(width 0.10668)
		(layer "F.Cu")
		(net "OC_ALERT_N")
	)
	(segment
		(start 169.192448 -113.853468)
		(end 168.501568 -113.853468)
		(width 0.10668)
		(layer "F.Cu")
		(net "OC_ALERT_N")
	)
	(segment
		(start 176.4284 -113.85296)
		(end 176.06518 -114.21618)
		(width 0.10668)
		(layer "F.Cu")
		(net "OC_ALERT_N")
	)
	(segment
		(start 169.34434 -114.00536)
		(end 169.192448 -113.853468)
		(width 0.10668)
		(layer "F.Cu")
		(net "OC_ALERT_N")
	)
	(segment
		(start 170.529504 -113.785396)
		(end 170.30954 -114.00536)
		(width 0.10668)
		(layer "F.Cu")
		(net "OC_ALERT_N")
	)
	(segment
		(start 171.979336 -113.785396)
		(end 170.529504 -113.785396)
		(width 0.10668)
		(layer "F.Cu")
		(net "OC_ALERT_N")
	)
	(segment
		(start 176.06518 -114.21618)
		(end 172.41012 -114.21618)
		(width 0.10668)
		(layer "F.Cu")
		(net "OC_ALERT_N")
	)
	(via
		(at 165.32225 -114.264948)
		(size 0.762)
		(drill 0.381)
		(layers "F.Cu" "B.Cu")
		(net "OC_ALERT_N")
	)
	(segment
		(start 92.922344 -41.46931)
		(end 92.148152 -40.695118)
		(width 0.10668)
		(layer "F.Cu")
		(net "OCP_V3_2_WAKE_BUFF_R_N")
	)
	(segment
		(start 92.148152 -35.68573)
		(end 92.554044 -35.279838)
		(width 0.10668)
		(layer "F.Cu")
		(net "OCP_V3_2_WAKE_BUFF_R_N")
	)
	(segment
		(start 94.205552 -41.445942)
		(end 94.182184 -41.46931)
		(width 0.10668)
		(layer "F.Cu")
		(net "OCP_V3_2_WAKE_BUFF_R_N")
	)
	(segment
		(start 92.148152 -40.695118)
		(end 92.148152 -35.68573)
		(width 0.10668)
		(layer "F.Cu")
		(net "OCP_V3_2_WAKE_BUFF_R_N")
	)
	(segment
		(start 92.554044 -35.279838)
		(end 94.233746 -35.279838)
		(width 0.10668)
		(layer "F.Cu")
		(net "OCP_V3_2_WAKE_BUFF_R_N")
	)
	(segment
		(start 94.182184 -41.46931)
		(end 92.922344 -41.46931)
		(width 0.10668)
		(layer "F.Cu")
		(net "OCP_V3_2_WAKE_BUFF_R_N")
	)
	(via
		(at 92.922344 -41.46931)
		(size 0.762)
		(drill 0.381)
		(layers "F.Cu" "B.Cu")
		(net "OCP_V3_2_WAKE_BUFF_R_N")
	)
	(segment
		(start 97.57537 -40.115744)
		(end 96.28886 -40.115744)
		(width 0.10668)
		(layer "F.Cu")
		(net "OCP_V3_2_WAKE_BUFF_N")
	)
	(segment
		(start 95.005652 -40.139112)
		(end 95.005652 -41.445942)
		(width 0.10668)
		(layer "F.Cu")
		(net "OCP_V3_2_WAKE_BUFF_N")
	)
	(segment
		(start 96.28886 -40.115744)
		(end 95.02902 -40.115744)
		(width 0.10668)
		(layer "F.Cu")
		(net "OCP_V3_2_WAKE_BUFF_N")
	)
	(segment
		(start 95.02902 -40.115744)
		(end 95.005652 -40.139112)
		(width 0.10668)
		(layer "F.Cu")
		(net "OCP_V3_2_WAKE_BUFF_N")
	)
	(via
		(at 96.28886 -40.115744)
		(size 0.762)
		(drill 0.381)
		(layers "F.Cu" "B.Cu")
		(net "OCP_V3_2_WAKE_BUFF_N")
	)
	(segment
		(start 143.054832 -97.705672)
		(end 142.800832 -97.451672)
		(width 0.10668)
		(layer "F.Cu")
		(net "OCP_V3_2_RBT_ARB_OUT")
	)
	(segment
		(start 143.740632 -97.705672)
		(end 143.054832 -97.705672)
		(width 0.10668)
		(layer "F.Cu")
		(net "OCP_V3_2_RBT_ARB_OUT")
	)
	(via
		(at 142.800832 -97.451672)
		(size 0.508)
		(drill 0.254)
		(layers "F.Cu" "B.Cu")
		(net "OCP_V3_2_RBT_ARB_OUT")
	)
	(via
		(at 202.163934 -79.416148)
		(size 0.508)
		(drill 0.254)
		(layers "F.Cu" "B.Cu")
		(net "OCP_V3_2_RBT_ARB_OUT")
	)
	(via
		(at 198.090536 -71.55307)
		(size 0.508)
		(drill 0.254)
		(layers "F.Cu" "B.Cu")
		(net "OCP_V3_2_RBT_ARB_OUT")
	)
	(segment
		(start 195.55333 -71.55307)
		(end 198.090536 -71.55307)
		(width 0.10668)
		(layer "B.Cu")
		(net "OCP_V3_2_RBT_ARB_OUT")
	)
	(segment
		(start 202.645264 -78.579218)
		(end 202.163934 -79.060548)
		(width 0.10668)
		(layer "B.Cu")
		(net "OCP_V3_2_RBT_ARB_OUT")
	)
	(segment
		(start 202.163934 -79.060548)
		(end 202.163934 -79.416148)
		(width 0.10668)
		(layer "B.Cu")
		(net "OCP_V3_2_RBT_ARB_OUT")
	)
	(segment
		(start 202.645264 -78.247748)
		(end 202.645264 -78.579218)
		(width 0.10668)
		(layer "B.Cu")
		(net "OCP_V3_2_RBT_ARB_OUT")
	)
	(segment
		(start 200.560686 -79.416148)
		(end 202.163934 -79.416148)
		(width 0.11684)
		(layer "In11.Cu")
		(net "OCP_V3_2_RBT_ARB_OUT")
	)
	(segment
		(start 199.806052 -78.661514)
		(end 200.560686 -79.416148)
		(width 0.11684)
		(layer "In11.Cu")
		(net "OCP_V3_2_RBT_ARB_OUT")
	)
	(segment
		(start 199.806052 -75.208892)
		(end 199.806052 -78.661514)
		(width 0.11684)
		(layer "In11.Cu")
		(net "OCP_V3_2_RBT_ARB_OUT")
	)
	(segment
		(start 198.090536 -73.493376)
		(end 199.806052 -75.208892)
		(width 0.11684)
		(layer "In11.Cu")
		(net "OCP_V3_2_RBT_ARB_OUT")
	)
	(segment
		(start 198.090536 -71.55307)
		(end 198.090536 -73.493376)
		(width 0.11684)
		(layer "In11.Cu")
		(net "OCP_V3_2_RBT_ARB_OUT")
	)
	(segment
		(start 165.47846 -83.460336)
		(end 158.29915 -90.639646)
		(width 0.11684)
		(layer "In15.Cu")
		(net "OCP_V3_2_RBT_ARB_OUT")
	)
	(segment
		(start 147.510754 -90.639646)
		(end 143.301466 -94.848934)
		(width 0.11684)
		(layer "In15.Cu")
		(net "OCP_V3_2_RBT_ARB_OUT")
	)
	(segment
		(start 143.301466 -96.951038)
		(end 142.800832 -97.451672)
		(width 0.11684)
		(layer "In15.Cu")
		(net "OCP_V3_2_RBT_ARB_OUT")
	)
	(segment
		(start 198.807578 -82.772504)
		(end 188.38926 -82.772504)
		(width 0.11684)
		(layer "In15.Cu")
		(net "OCP_V3_2_RBT_ARB_OUT")
	)
	(segment
		(start 188.38926 -82.772504)
		(end 187.701428 -83.460336)
		(width 0.11684)
		(layer "In15.Cu")
		(net "OCP_V3_2_RBT_ARB_OUT")
	)
	(segment
		(start 187.701428 -83.460336)
		(end 165.47846 -83.460336)
		(width 0.11684)
		(layer "In15.Cu")
		(net "OCP_V3_2_RBT_ARB_OUT")
	)
	(segment
		(start 158.29915 -90.639646)
		(end 147.510754 -90.639646)
		(width 0.11684)
		(layer "In15.Cu")
		(net "OCP_V3_2_RBT_ARB_OUT")
	)
	(segment
		(start 202.163934 -79.416148)
		(end 198.807578 -82.772504)
		(width 0.11684)
		(layer "In15.Cu")
		(net "OCP_V3_2_RBT_ARB_OUT")
	)
	(segment
		(start 143.301466 -94.848934)
		(end 143.301466 -96.951038)
		(width 0.11684)
		(layer "In15.Cu")
		(net "OCP_V3_2_RBT_ARB_OUT")
	)
	(via
		(at 204.569314 -78.14818)
		(size 0.6604)
		(drill 0.3302)
		(layers "F.Cu" "B.Cu")
		(net "OCP_V3_2_RBT_ARB_IN_R")
	)
	(segment
		(start 204.803756 -77.913738)
		(end 204.569314 -78.14818)
		(width 0.10668)
		(layer "B.Cu")
		(net "OCP_V3_2_RBT_ARB_IN_R")
	)
	(segment
		(start 203.445364 -78.247748)
		(end 203.44765 -78.245462)
		(width 0.10668)
		(layer "B.Cu")
		(net "OCP_V3_2_RBT_ARB_IN_R")
	)
	(segment
		(start 206.374746 -77.913738)
		(end 204.803756 -77.913738)
		(width 0.10668)
		(layer "B.Cu")
		(net "OCP_V3_2_RBT_ARB_IN_R")
	)
	(segment
		(start 204.472032 -78.245462)
		(end 204.569314 -78.14818)
		(width 0.10668)
		(layer "B.Cu")
		(net "OCP_V3_2_RBT_ARB_IN_R")
	)
	(segment
		(start 203.445364 -78.247748)
		(end 203.445364 -77.231748)
		(width 0.10668)
		(layer "B.Cu")
		(net "OCP_V3_2_RBT_ARB_IN_R")
	)
	(segment
		(start 203.44765 -78.245462)
		(end 204.472032 -78.245462)
		(width 0.10668)
		(layer "B.Cu")
		(net "OCP_V3_2_RBT_ARB_IN_R")
	)
	(segment
		(start 143.008604 -94.962472)
		(end 142.75562 -94.709488)
		(width 0.10668)
		(layer "F.Cu")
		(net "OCP_V3_2_RBT_ARB_IN")
	)
	(segment
		(start 143.740632 -94.962472)
		(end 143.008604 -94.962472)
		(width 0.10668)
		(layer "F.Cu")
		(net "OCP_V3_2_RBT_ARB_IN")
	)
	(via
		(at 202.817222 -76.549758)
		(size 0.508)
		(drill 0.254)
		(layers "F.Cu" "B.Cu")
		(net "OCP_V3_2_RBT_ARB_IN")
	)
	(via
		(at 142.75562 -94.709488)
		(size 0.508)
		(drill 0.254)
		(layers "F.Cu" "B.Cu")
		(net "OCP_V3_2_RBT_ARB_IN")
	)
	(segment
		(start 202.817222 -76.549758)
		(end 202.817222 -76.83246)
		(width 0.10668)
		(layer "B.Cu")
		(net "OCP_V3_2_RBT_ARB_IN")
	)
	(segment
		(start 202.817222 -76.83246)
		(end 202.645264 -77.004418)
		(width 0.10668)
		(layer "B.Cu")
		(net "OCP_V3_2_RBT_ARB_IN")
	)
	(segment
		(start 202.645264 -77.004418)
		(end 202.645264 -77.231748)
		(width 0.10668)
		(layer "B.Cu")
		(net "OCP_V3_2_RBT_ARB_IN")
	)
	(segment
		(start 158.215838 -90.255598)
		(end 147.20951 -90.255598)
		(width 0.11684)
		(layer "In15.Cu")
		(net "OCP_V3_2_RBT_ARB_IN")
	)
	(segment
		(start 198.378064 -82.452464)
		(end 166.018972 -82.452464)
		(width 0.11684)
		(layer "In15.Cu")
		(net "OCP_V3_2_RBT_ARB_IN")
	)
	(segment
		(start 203.129134 -76.86167)
		(end 203.129134 -77.701394)
		(width 0.11684)
		(layer "In15.Cu")
		(net "OCP_V3_2_RBT_ARB_IN")
	)
	(segment
		(start 147.20951 -90.255598)
		(end 142.75562 -94.709488)
		(width 0.11684)
		(layer "In15.Cu")
		(net "OCP_V3_2_RBT_ARB_IN")
	)
	(segment
		(start 203.129134 -77.701394)
		(end 198.378064 -82.452464)
		(width 0.11684)
		(layer "In15.Cu")
		(net "OCP_V3_2_RBT_ARB_IN")
	)
	(segment
		(start 202.817222 -76.549758)
		(end 203.129134 -76.86167)
		(width 0.11684)
		(layer "In15.Cu")
		(net "OCP_V3_2_RBT_ARB_IN")
	)
	(segment
		(start 166.018972 -82.452464)
		(end 158.215838 -90.255598)
		(width 0.11684)
		(layer "In15.Cu")
		(net "OCP_V3_2_RBT_ARB_IN")
	)
	(segment
		(start 16.746982 -8.320024)
		(end 16.746982 -7.215124)
		(width 0.10668)
		(layer "F.Cu")
		(net "OCP_V3_2_PWRBRK_N")
	)
	(segment
		(start 258.351528 -106.909108)
		(end 259.269992 -106.909108)
		(width 0.10668)
		(layer "F.Cu")
		(net "OCP_V3_2_PWRBRK_N")
	)
	(via
		(at 259.269992 -106.909108)
		(size 0.508)
		(drill 0.254)
		(layers "F.Cu" "B.Cu")
		(net "OCP_V3_2_PWRBRK_N")
	)
	(via
		(at 124.566426 -91.983052)
		(size 0.508)
		(drill 0.254)
		(layers "F.Cu" "B.Cu")
		(net "OCP_V3_2_PWRBRK_N")
	)
	(via
		(at 16.746982 -7.215124)
		(size 0.508)
		(drill 0.254)
		(layers "F.Cu" "B.Cu")
		(net "OCP_V3_2_PWRBRK_N")
	)
	(segment
		(start 177.59934 -90.96248)
		(end 177.699162 -91.062302)
		(width 0.11684)
		(layer "In2.Cu")
		(net "OCP_V3_2_PWRBRK_N")
	)
	(segment
		(start 198.719694 -93.80982)
		(end 199.482964 -93.80982)
		(width 0.11684)
		(layer "In2.Cu")
		(net "OCP_V3_2_PWRBRK_N")
	)
	(segment
		(start 176.013364 -90.96248)
		(end 177.59934 -90.96248)
		(width 0.11684)
		(layer "In2.Cu")
		(net "OCP_V3_2_PWRBRK_N")
	)
	(segment
		(start 159.736282 -91.983052)
		(end 160.657286 -91.062048)
		(width 0.11684)
		(layer "In2.Cu")
		(net "OCP_V3_2_PWRBRK_N")
	)
	(segment
		(start 209.6135 -92.44838)
		(end 215.769698 -98.604578)
		(width 0.11684)
		(layer "In2.Cu")
		(net "OCP_V3_2_PWRBRK_N")
	)
	(segment
		(start 203.875386 -92.44838)
		(end 209.6135 -92.44838)
		(width 0.11684)
		(layer "In2.Cu")
		(net "OCP_V3_2_PWRBRK_N")
	)
	(segment
		(start 228.614986 -106.0958)
		(end 258.456684 -106.0958)
		(width 0.11684)
		(layer "In2.Cu")
		(net "OCP_V3_2_PWRBRK_N")
	)
	(segment
		(start 215.769698 -98.604578)
		(end 221.123764 -98.604578)
		(width 0.11684)
		(layer "In2.Cu")
		(net "OCP_V3_2_PWRBRK_N")
	)
	(segment
		(start 200.38949 -92.903294)
		(end 203.420472 -92.903294)
		(width 0.11684)
		(layer "In2.Cu")
		(net "OCP_V3_2_PWRBRK_N")
	)
	(segment
		(start 258.456684 -106.0958)
		(end 259.269992 -106.909108)
		(width 0.11684)
		(layer "In2.Cu")
		(net "OCP_V3_2_PWRBRK_N")
	)
	(segment
		(start 173.550326 -90.83294)
		(end 173.779434 -91.062048)
		(width 0.11684)
		(layer "In2.Cu")
		(net "OCP_V3_2_PWRBRK_N")
	)
	(segment
		(start 196.936868 -93.337634)
		(end 198.247508 -93.337634)
		(width 0.11684)
		(layer "In2.Cu")
		(net "OCP_V3_2_PWRBRK_N")
	)
	(segment
		(start 160.657286 -91.062048)
		(end 172.08119 -91.062048)
		(width 0.11684)
		(layer "In2.Cu")
		(net "OCP_V3_2_PWRBRK_N")
	)
	(segment
		(start 177.699162 -91.062302)
		(end 194.661536 -91.062302)
		(width 0.11684)
		(layer "In2.Cu")
		(net "OCP_V3_2_PWRBRK_N")
	)
	(segment
		(start 124.566426 -91.983052)
		(end 159.736282 -91.983052)
		(width 0.11684)
		(layer "In2.Cu")
		(net "OCP_V3_2_PWRBRK_N")
	)
	(segment
		(start 194.661536 -91.062302)
		(end 196.936868 -93.337634)
		(width 0.11684)
		(layer "In2.Cu")
		(net "OCP_V3_2_PWRBRK_N")
	)
	(segment
		(start 173.779434 -91.062048)
		(end 175.913796 -91.062048)
		(width 0.11684)
		(layer "In2.Cu")
		(net "OCP_V3_2_PWRBRK_N")
	)
	(segment
		(start 199.482964 -93.80982)
		(end 200.38949 -92.903294)
		(width 0.11684)
		(layer "In2.Cu")
		(net "OCP_V3_2_PWRBRK_N")
	)
	(segment
		(start 203.420472 -92.903294)
		(end 203.875386 -92.44838)
		(width 0.11684)
		(layer "In2.Cu")
		(net "OCP_V3_2_PWRBRK_N")
	)
	(segment
		(start 175.913796 -91.062048)
		(end 176.013364 -90.96248)
		(width 0.11684)
		(layer "In2.Cu")
		(net "OCP_V3_2_PWRBRK_N")
	)
	(segment
		(start 221.123764 -98.604578)
		(end 228.614986 -106.0958)
		(width 0.11684)
		(layer "In2.Cu")
		(net "OCP_V3_2_PWRBRK_N")
	)
	(segment
		(start 198.247508 -93.337634)
		(end 198.719694 -93.80982)
		(width 0.11684)
		(layer "In2.Cu")
		(net "OCP_V3_2_PWRBRK_N")
	)
	(segment
		(start 172.310298 -90.83294)
		(end 173.550326 -90.83294)
		(width 0.11684)
		(layer "In2.Cu")
		(net "OCP_V3_2_PWRBRK_N")
	)
	(segment
		(start 172.08119 -91.062048)
		(end 172.310298 -90.83294)
		(width 0.11684)
		(layer "In2.Cu")
		(net "OCP_V3_2_PWRBRK_N")
	)
	(segment
		(start 78.083664 -5.782818)
		(end 76.91882 -4.617974)
		(width 0.11684)
		(layer "In11.Cu")
		(net "OCP_V3_2_PWRBRK_N")
	)
	(segment
		(start 86.080854 -29.662628)
		(end 86.080854 -21.97354)
		(width 0.11684)
		(layer "In11.Cu")
		(net "OCP_V3_2_PWRBRK_N")
	)
	(segment
		(start 105.254806 -77.695552)
		(end 105.254806 -76.075794)
		(width 0.11684)
		(layer "In11.Cu")
		(net "OCP_V3_2_PWRBRK_N")
	)
	(segment
		(start 49.723802 -4.32689)
		(end 46.47565 -4.32689)
		(width 0.11684)
		(layer "In11.Cu")
		(net "OCP_V3_2_PWRBRK_N")
	)
	(segment
		(start 33.88614 -4.326636)
		(end 33.07969 -3.520186)
		(width 0.11684)
		(layer "In11.Cu")
		(net "OCP_V3_2_PWRBRK_N")
	)
	(segment
		(start 80.826864 -19.251676)
		(end 81.291684 -18.786856)
		(width 0.11684)
		(layer "In11.Cu")
		(net "OCP_V3_2_PWRBRK_N")
	)
	(segment
		(start 108.30687 -80.747616)
		(end 105.254806 -77.695552)
		(width 0.11684)
		(layer "In11.Cu")
		(net "OCP_V3_2_PWRBRK_N")
	)
	(segment
		(start 36.999672 -3.69951)
		(end 36.372546 -4.326636)
		(width 0.11684)
		(layer "In11.Cu")
		(net "OCP_V3_2_PWRBRK_N")
	)
	(segment
		(start 63.858902 -5.178044)
		(end 62.201044 -3.520186)
		(width 0.11684)
		(layer "In11.Cu")
		(net "OCP_V3_2_PWRBRK_N")
	)
	(segment
		(start 66.143886 -5.178044)
		(end 63.858902 -5.178044)
		(width 0.11684)
		(layer "In11.Cu")
		(net "OCP_V3_2_PWRBRK_N")
	)
	(segment
		(start 116.76253 -89.203276)
		(end 109.325156 -81.765902)
		(width 0.11684)
		(layer "In11.Cu")
		(net "OCP_V3_2_PWRBRK_N")
	)
	(segment
		(start 66.703956 -4.617974)
		(end 66.143886 -5.178044)
		(width 0.11684)
		(layer "In11.Cu")
		(net "OCP_V3_2_PWRBRK_N")
	)
	(segment
		(start 100.014532 -59.814714)
		(end 94.77248 -54.572662)
		(width 0.11684)
		(layer "In11.Cu")
		(net "OCP_V3_2_PWRBRK_N")
	)
	(segment
		(start 33.07969 -3.520186)
		(end 19.549364 -3.520186)
		(width 0.11684)
		(layer "In11.Cu")
		(net "OCP_V3_2_PWRBRK_N")
	)
	(segment
		(start 100.014532 -70.83552)
		(end 100.014532 -59.814714)
		(width 0.11684)
		(layer "In11.Cu")
		(net "OCP_V3_2_PWRBRK_N")
	)
	(segment
		(start 89.530682 -54.572662)
		(end 81.735422 -46.777402)
		(width 0.11684)
		(layer "In11.Cu")
		(net "OCP_V3_2_PWRBRK_N")
	)
	(segment
		(start 81.735422 -46.777402)
		(end 81.735422 -34.00806)
		(width 0.11684)
		(layer "In11.Cu")
		(net "OCP_V3_2_PWRBRK_N")
	)
	(segment
		(start 46.47565 -4.32689)
		(end 45.84827 -3.69951)
		(width 0.11684)
		(layer "In11.Cu")
		(net "OCP_V3_2_PWRBRK_N")
	)
	(segment
		(start 86.080854 -21.97354)
		(end 84.876894 -20.76958)
		(width 0.11684)
		(layer "In11.Cu")
		(net "OCP_V3_2_PWRBRK_N")
	)
	(segment
		(start 19.549364 -3.520186)
		(end 16.746982 -6.322568)
		(width 0.11684)
		(layer "In11.Cu")
		(net "OCP_V3_2_PWRBRK_N")
	)
	(segment
		(start 78.554072 -10.71118)
		(end 78.554072 -8.694928)
		(width 0.11684)
		(layer "In11.Cu")
		(net "OCP_V3_2_PWRBRK_N")
	)
	(segment
		(start 84.876894 -20.76958)
		(end 81.657952 -20.76958)
		(width 0.11684)
		(layer "In11.Cu")
		(net "OCP_V3_2_PWRBRK_N")
	)
	(segment
		(start 81.735422 -34.00806)
		(end 86.080854 -29.662628)
		(width 0.11684)
		(layer "In11.Cu")
		(net "OCP_V3_2_PWRBRK_N")
	)
	(segment
		(start 50.530506 -3.520186)
		(end 49.723802 -4.32689)
		(width 0.11684)
		(layer "In11.Cu")
		(net "OCP_V3_2_PWRBRK_N")
	)
	(segment
		(start 121.738898 -91.983052)
		(end 118.959122 -89.203276)
		(width 0.11684)
		(layer "In11.Cu")
		(net "OCP_V3_2_PWRBRK_N")
	)
	(segment
		(start 109.325156 -81.765902)
		(end 109.325156 -81.330546)
		(width 0.11684)
		(layer "In11.Cu")
		(net "OCP_V3_2_PWRBRK_N")
	)
	(segment
		(start 81.291684 -18.786856)
		(end 81.291684 -13.448792)
		(width 0.11684)
		(layer "In11.Cu")
		(net "OCP_V3_2_PWRBRK_N")
	)
	(segment
		(start 124.566426 -91.983052)
		(end 121.738898 -91.983052)
		(width 0.11684)
		(layer "In11.Cu")
		(net "OCP_V3_2_PWRBRK_N")
	)
	(segment
		(start 36.372546 -4.326636)
		(end 33.88614 -4.326636)
		(width 0.11684)
		(layer "In11.Cu")
		(net "OCP_V3_2_PWRBRK_N")
	)
	(segment
		(start 80.826864 -19.938492)
		(end 80.826864 -19.251676)
		(width 0.11684)
		(layer "In11.Cu")
		(net "OCP_V3_2_PWRBRK_N")
	)
	(segment
		(start 105.254806 -76.075794)
		(end 100.014532 -70.83552)
		(width 0.11684)
		(layer "In11.Cu")
		(net "OCP_V3_2_PWRBRK_N")
	)
	(segment
		(start 78.083664 -8.22452)
		(end 78.083664 -5.782818)
		(width 0.11684)
		(layer "In11.Cu")
		(net "OCP_V3_2_PWRBRK_N")
	)
	(segment
		(start 81.291684 -13.448792)
		(end 78.554072 -10.71118)
		(width 0.11684)
		(layer "In11.Cu")
		(net "OCP_V3_2_PWRBRK_N")
	)
	(segment
		(start 78.554072 -8.694928)
		(end 78.083664 -8.22452)
		(width 0.11684)
		(layer "In11.Cu")
		(net "OCP_V3_2_PWRBRK_N")
	)
	(segment
		(start 108.742226 -80.747616)
		(end 108.30687 -80.747616)
		(width 0.11684)
		(layer "In11.Cu")
		(net "OCP_V3_2_PWRBRK_N")
	)
	(segment
		(start 109.325156 -81.330546)
		(end 108.742226 -80.747616)
		(width 0.11684)
		(layer "In11.Cu")
		(net "OCP_V3_2_PWRBRK_N")
	)
	(segment
		(start 81.657952 -20.76958)
		(end 80.826864 -19.938492)
		(width 0.11684)
		(layer "In11.Cu")
		(net "OCP_V3_2_PWRBRK_N")
	)
	(segment
		(start 45.84827 -3.69951)
		(end 36.999672 -3.69951)
		(width 0.11684)
		(layer "In11.Cu")
		(net "OCP_V3_2_PWRBRK_N")
	)
	(segment
		(start 62.201044 -3.520186)
		(end 50.530506 -3.520186)
		(width 0.11684)
		(layer "In11.Cu")
		(net "OCP_V3_2_PWRBRK_N")
	)
	(segment
		(start 76.91882 -4.617974)
		(end 66.703956 -4.617974)
		(width 0.11684)
		(layer "In11.Cu")
		(net "OCP_V3_2_PWRBRK_N")
	)
	(segment
		(start 118.959122 -89.203276)
		(end 116.76253 -89.203276)
		(width 0.11684)
		(layer "In11.Cu")
		(net "OCP_V3_2_PWRBRK_N")
	)
	(segment
		(start 94.77248 -54.572662)
		(end 89.530682 -54.572662)
		(width 0.11684)
		(layer "In11.Cu")
		(net "OCP_V3_2_PWRBRK_N")
	)
	(segment
		(start 16.746982 -6.322568)
		(end 16.746982 -7.215124)
		(width 0.11684)
		(layer "In11.Cu")
		(net "OCP_V3_2_PWRBRK_N")
	)
	(segment
		(start 256.059432 -106.905044)
		(end 257.547364 -106.905044)
		(width 0.10668)
		(layer "F.Cu")
		(net "OCP_V3_2_PWRBRK_BUFF_N")
	)
	(segment
		(start 254.540004 -106.905044)
		(end 256.059432 -106.905044)
		(width 0.10668)
		(layer "F.Cu")
		(net "OCP_V3_2_PWRBRK_BUFF_N")
	)
	(segment
		(start 257.551428 -106.909108)
		(end 257.551428 -108.179108)
		(width 0.10668)
		(layer "F.Cu")
		(net "OCP_V3_2_PWRBRK_BUFF_N")
	)
	(segment
		(start 257.547364 -106.905044)
		(end 257.551428 -106.909108)
		(width 0.10668)
		(layer "F.Cu")
		(net "OCP_V3_2_PWRBRK_BUFF_N")
	)
	(via
		(at 256.059432 -106.905044)
		(size 0.762)
		(drill 0.381)
		(layers "F.Cu" "B.Cu")
		(net "OCP_V3_2_PWRBRK_BUFF_N")
	)
	(segment
		(start 148.73859 -95.117158)
		(end 148.73859 -94.501208)
		(width 0.10668)
		(layer "F.Cu")
		(net "OCP_V3_2_PRSNT_ALL_R_N")
	)
	(segment
		(start 149.69617 -96.074738)
		(end 149.69617 -97.92462)
		(width 0.10668)
		(layer "F.Cu")
		(net "OCP_V3_2_PRSNT_ALL_R_N")
	)
	(segment
		(start 149.265132 -98.355658)
		(end 148.73859 -98.355658)
		(width 0.10668)
		(layer "F.Cu")
		(net "OCP_V3_2_PRSNT_ALL_R_N")
	)
	(segment
		(start 149.69617 -97.92462)
		(end 149.265132 -98.355658)
		(width 0.10668)
		(layer "F.Cu")
		(net "OCP_V3_2_PRSNT_ALL_R_N")
	)
	(segment
		(start 148.73859 -95.117158)
		(end 149.69617 -96.074738)
		(width 0.10668)
		(layer "F.Cu")
		(net "OCP_V3_2_PRSNT_ALL_R_N")
	)
	(segment
		(start 11.351768 -74.394568)
		(end 10.538968 -74.394568)
		(width 0.10668)
		(layer "F.Cu")
		(net "OCP_V3_2_PRSNT_ALL_R_N")
	)
	(via
		(at 148.73859 -94.501208)
		(size 0.508)
		(drill 0.254)
		(layers "F.Cu" "B.Cu")
		(net "OCP_V3_2_PRSNT_ALL_R_N")
	)
	(via
		(at 10.538968 -74.394568)
		(size 0.508)
		(drill 0.254)
		(layers "F.Cu" "B.Cu")
		(net "OCP_V3_2_PRSNT_ALL_R_N")
	)
	(segment
		(start 8.84301 -74.394568)
		(end 10.538968 -74.394568)
		(width 0.10668)
		(layer "B.Cu")
		(net "OCP_V3_2_PRSNT_ALL_R_N")
	)
	(segment
		(start 148.73859 -94.501208)
		(end 147.33778 -93.100398)
		(width 0.10668)
		(layer "B.Cu")
		(net "OCP_V3_2_PRSNT_ALL_R_N")
	)
	(segment
		(start 147.33778 -93.100398)
		(end 142.98676 -93.100398)
		(width 0.10668)
		(layer "B.Cu")
		(net "OCP_V3_2_PRSNT_ALL_R_N")
	)
	(segment
		(start 7.366 -75.871578)
		(end 8.84301 -74.394568)
		(width 0.10668)
		(layer "B.Cu")
		(net "OCP_V3_2_PRSNT_ALL_R_N")
	)
	(segment
		(start 10.392918 -83.574382)
		(end 10.024618 -83.942682)
		(width 0.10668)
		(layer "B.Cu")
		(net "OCP_V3_2_PRSNT_ALL_R_N")
	)
	(segment
		(start 7.366 -82.295746)
		(end 7.366 -75.871578)
		(width 0.10668)
		(layer "B.Cu")
		(net "OCP_V3_2_PRSNT_ALL_R_N")
	)
	(segment
		(start 9.012936 -83.942682)
		(end 7.366 -82.295746)
		(width 0.10668)
		(layer "B.Cu")
		(net "OCP_V3_2_PRSNT_ALL_R_N")
	)
	(segment
		(start 142.98676 -93.100398)
		(end 133.460744 -83.574382)
		(width 0.10668)
		(layer "B.Cu")
		(net "OCP_V3_2_PRSNT_ALL_R_N")
	)
	(segment
		(start 133.460744 -83.574382)
		(end 10.392918 -83.574382)
		(width 0.10668)
		(layer "B.Cu")
		(net "OCP_V3_2_PRSNT_ALL_R_N")
	)
	(segment
		(start 10.024618 -83.942682)
		(end 9.012936 -83.942682)
		(width 0.10668)
		(layer "B.Cu")
		(net "OCP_V3_2_PRSNT_ALL_R_N")
	)
	(segment
		(start 148.73859 -97.136458)
		(end 147.041616 -97.136458)
		(width 0.10668)
		(layer "F.Cu")
		(net "OCP_V3_2_PRSNT_ALL_R3_N")
	)
	(segment
		(start 147.041616 -97.136458)
		(end 146.167602 -96.262444)
		(width 0.10668)
		(layer "F.Cu")
		(net "OCP_V3_2_PRSNT_ALL_R3_N")
	)
	(segment
		(start 148.73859 -95.917258)
		(end 148.73859 -97.136458)
		(width 0.10668)
		(layer "F.Cu")
		(net "OCP_V3_2_PRSNT_ALL_R3_N")
	)
	(segment
		(start 146.167602 -96.262444)
		(end 145.740628 -96.262444)
		(width 0.10668)
		(layer "F.Cu")
		(net "OCP_V3_2_PRSNT_ALL_R3_N")
	)
	(via
		(at 148.73859 -97.136458)
		(size 0.762)
		(drill 0.381)
		(layers "F.Cu" "B.Cu")
		(net "OCP_V3_2_PRSNT_ALL_R3_N")
	)
	(segment
		(start 147.438872 -100.374958)
		(end 146.069558 -99.005644)
		(width 0.10668)
		(layer "F.Cu")
		(net "OCP_V3_2_PRSNT_ALL_R1_N")
	)
	(segment
		(start 146.069558 -99.005644)
		(end 145.740628 -99.005644)
		(width 0.10668)
		(layer "F.Cu")
		(net "OCP_V3_2_PRSNT_ALL_R1_N")
	)
	(segment
		(start 148.73859 -100.374958)
		(end 147.438872 -100.374958)
		(width 0.10668)
		(layer "F.Cu")
		(net "OCP_V3_2_PRSNT_ALL_R1_N")
	)
	(segment
		(start 148.73859 -100.374958)
		(end 148.73859 -99.155758)
		(width 0.10668)
		(layer "F.Cu")
		(net "OCP_V3_2_PRSNT_ALL_R1_N")
	)
	(via
		(at 148.73859 -100.374958)
		(size 0.762)
		(drill 0.381)
		(layers "F.Cu" "B.Cu")
		(net "OCP_V3_2_PRSNT_ALL_R1_N")
	)
	(segment
		(start 10.782046 -70.560692)
		(end 10.14476 -70.560692)
		(width 0.10668)
		(layer "F.Cu")
		(net "OCP_V3_2_PRSNT3_R_N")
	)
	(segment
		(start 6.29031 -73.229216)
		(end 8.325104 -71.194422)
		(width 0.10668)
		(layer "F.Cu")
		(net "OCP_V3_2_PRSNT3_R_N")
	)
	(segment
		(start 12.0142 -70.560692)
		(end 10.782046 -70.560692)
		(width 0.10668)
		(layer "F.Cu")
		(net "OCP_V3_2_PRSNT3_R_N")
	)
	(segment
		(start 16.746982 -11.26998)
		(end 16.746982 -12.37488)
		(width 0.10668)
		(layer "F.Cu")
		(net "OCP_V3_2_PRSNT3_R_N")
	)
	(segment
		(start 9.51103 -71.194422)
		(end 10.14476 -70.560692)
		(width 0.10668)
		(layer "F.Cu")
		(net "OCP_V3_2_PRSNT3_R_N")
	)
	(segment
		(start 6.607302 -74.394568)
		(end 6.29031 -74.077576)
		(width 0.10668)
		(layer "F.Cu")
		(net "OCP_V3_2_PRSNT3_R_N")
	)
	(segment
		(start 8.325104 -71.194422)
		(end 9.51103 -71.194422)
		(width 0.10668)
		(layer "F.Cu")
		(net "OCP_V3_2_PRSNT3_R_N")
	)
	(segment
		(start 6.29031 -74.077576)
		(end 6.29031 -73.229216)
		(width 0.10668)
		(layer "F.Cu")
		(net "OCP_V3_2_PRSNT3_R_N")
	)
	(segment
		(start 7.129272 -74.394568)
		(end 6.607302 -74.394568)
		(width 0.10668)
		(layer "F.Cu")
		(net "OCP_V3_2_PRSNT3_R_N")
	)
	(via
		(at 10.782046 -70.560692)
		(size 0.508)
		(drill 0.254)
		(layers "F.Cu" "B.Cu")
		(net "OCP_V3_2_PRSNT3_R_N")
	)
	(via
		(at 16.746982 -12.37488)
		(size 0.508)
		(drill 0.254)
		(layers "F.Cu" "B.Cu")
		(net "OCP_V3_2_PRSNT3_R_N")
	)
	(segment
		(start 6.796532 -66.575178)
		(end 6.796532 -66.42481)
		(width 0.11684)
		(layer "In4.Cu")
		(net "OCP_V3_2_PRSNT3_R_N")
	)
	(segment
		(start 1.605788 -41.78046)
		(end 8.131048 -35.2552)
		(width 0.11684)
		(layer "In4.Cu")
		(net "OCP_V3_2_PRSNT3_R_N")
	)
	(segment
		(start 10.782046 -70.560692)
		(end 6.796532 -66.575178)
		(width 0.11684)
		(layer "In4.Cu")
		(net "OCP_V3_2_PRSNT3_R_N")
	)
	(segment
		(start 18.636742 -35.2552)
		(end 18.753582 -35.13836)
		(width 0.11684)
		(layer "In4.Cu")
		(net "OCP_V3_2_PRSNT3_R_N")
	)
	(segment
		(start 12.578588 -15.023846)
		(end 15.227554 -12.37488)
		(width 0.11684)
		(layer "In4.Cu")
		(net "OCP_V3_2_PRSNT3_R_N")
	)
	(segment
		(start 12.578588 -19.905726)
		(end 12.578588 -15.023846)
		(width 0.11684)
		(layer "In4.Cu")
		(net "OCP_V3_2_PRSNT3_R_N")
	)
	(segment
		(start 6.796532 -66.42481)
		(end 1.605788 -61.234066)
		(width 0.11684)
		(layer "In4.Cu")
		(net "OCP_V3_2_PRSNT3_R_N")
	)
	(segment
		(start 8.131048 -35.2552)
		(end 18.636742 -35.2552)
		(width 0.11684)
		(layer "In4.Cu")
		(net "OCP_V3_2_PRSNT3_R_N")
	)
	(segment
		(start 15.227554 -12.37488)
		(end 16.746982 -12.37488)
		(width 0.11684)
		(layer "In4.Cu")
		(net "OCP_V3_2_PRSNT3_R_N")
	)
	(segment
		(start 1.605788 -61.234066)
		(end 1.605788 -41.78046)
		(width 0.11684)
		(layer "In4.Cu")
		(net "OCP_V3_2_PRSNT3_R_N")
	)
	(segment
		(start 18.753582 -26.08072)
		(end 12.578588 -19.905726)
		(width 0.11684)
		(layer "In4.Cu")
		(net "OCP_V3_2_PRSNT3_R_N")
	)
	(segment
		(start 18.753582 -35.13836)
		(end 18.753582 -26.08072)
		(width 0.11684)
		(layer "In4.Cu")
		(net "OCP_V3_2_PRSNT3_R_N")
	)
	(segment
		(start 59.26709 -8.320024)
		(end 59.26709 -4.48691)
		(width 0.10668)
		(layer "F.Cu")
		(net "OCP_V3_2_PRSNT2_R_N")
	)
	(segment
		(start 8.30707 -72.517)
		(end 10.01776 -72.517)
		(width 0.10668)
		(layer "F.Cu")
		(net "OCP_V3_2_PRSNT2_R_N")
	)
	(segment
		(start 10.01776 -72.517)
		(end 10.14476 -72.39)
		(width 0.10668)
		(layer "F.Cu")
		(net "OCP_V3_2_PRSNT2_R_N")
	)
	(segment
		(start 12.0142 -71.860664)
		(end 10.782046 -71.860664)
		(width 0.10668)
		(layer "F.Cu")
		(net "OCP_V3_2_PRSNT2_R_N")
	)
	(segment
		(start 10.782046 -71.860664)
		(end 10.14476 -71.860664)
		(width 0.10668)
		(layer "F.Cu")
		(net "OCP_V3_2_PRSNT2_R_N")
	)
	(segment
		(start 7.129272 -73.694798)
		(end 8.30707 -72.517)
		(width 0.10668)
		(layer "F.Cu")
		(net "OCP_V3_2_PRSNT2_R_N")
	)
	(segment
		(start 10.14476 -72.39)
		(end 10.14476 -71.860664)
		(width 0.10668)
		(layer "F.Cu")
		(net "OCP_V3_2_PRSNT2_R_N")
	)
	(via
		(at 10.782046 -71.860664)
		(size 0.508)
		(drill 0.254)
		(layers "F.Cu" "B.Cu")
		(net "OCP_V3_2_PRSNT2_R_N")
	)
	(via
		(at 59.26709 -4.48691)
		(size 0.508)
		(drill 0.254)
		(layers "F.Cu" "B.Cu")
		(net "OCP_V3_2_PRSNT2_R_N")
	)
	(segment
		(start 59.26709 -4.261866)
		(end 59.26709 -4.48691)
		(width 0.10668)
		(layer "B.Cu")
		(net "OCP_V3_2_PRSNT2_R_N")
	)
	(segment
		(start 12.626848 -58.82259)
		(end 33.871408 -37.57803)
		(width 0.10668)
		(layer "B.Cu")
		(net "OCP_V3_2_PRSNT2_R_N")
	)
	(segment
		(start 10.782046 -71.860664)
		(end 11.508486 -71.860664)
		(width 0.10668)
		(layer "B.Cu")
		(net "OCP_V3_2_PRSNT2_R_N")
	)
	(segment
		(start 12.626848 -70.742302)
		(end 12.626848 -58.82259)
		(width 0.10668)
		(layer "B.Cu")
		(net "OCP_V3_2_PRSNT2_R_N")
	)
	(segment
		(start 11.508486 -71.860664)
		(end 12.626848 -70.742302)
		(width 0.10668)
		(layer "B.Cu")
		(net "OCP_V3_2_PRSNT2_R_N")
	)
	(segment
		(start 33.871408 -18.741136)
		(end 35.49523 -17.117314)
		(width 0.10668)
		(layer "B.Cu")
		(net "OCP_V3_2_PRSNT2_R_N")
	)
	(segment
		(start 35.49523 -17.117314)
		(end 35.49523 -7.224268)
		(width 0.10668)
		(layer "B.Cu")
		(net "OCP_V3_2_PRSNT2_R_N")
	)
	(segment
		(start 33.871408 -37.57803)
		(end 33.871408 -18.741136)
		(width 0.10668)
		(layer "B.Cu")
		(net "OCP_V3_2_PRSNT2_R_N")
	)
	(segment
		(start 58.225944 -3.22072)
		(end 59.26709 -4.261866)
		(width 0.10668)
		(layer "B.Cu")
		(net "OCP_V3_2_PRSNT2_R_N")
	)
	(segment
		(start 50.174398 -3.22072)
		(end 58.225944 -3.22072)
		(width 0.10668)
		(layer "B.Cu")
		(net "OCP_V3_2_PRSNT2_R_N")
	)
	(segment
		(start 48.795432 -1.841754)
		(end 50.174398 -3.22072)
		(width 0.10668)
		(layer "B.Cu")
		(net "OCP_V3_2_PRSNT2_R_N")
	)
	(segment
		(start 40.877744 -1.841754)
		(end 48.795432 -1.841754)
		(width 0.10668)
		(layer "B.Cu")
		(net "OCP_V3_2_PRSNT2_R_N")
	)
	(segment
		(start 35.49523 -7.224268)
		(end 40.877744 -1.841754)
		(width 0.10668)
		(layer "B.Cu")
		(net "OCP_V3_2_PRSNT2_R_N")
	)
	(segment
		(start 10.018776 -77.089)
		(end 9.891776 -76.962)
		(width 0.10668)
		(layer "F.Cu")
		(net "OCP_V3_2_PRSNT23_R_N")
	)
	(segment
		(start 9.891776 -76.962)
		(end 9.568942 -77.284834)
		(width 0.10668)
		(layer "F.Cu")
		(net "OCP_V3_2_PRSNT23_R_N")
	)
	(segment
		(start 9.568942 -77.284834)
		(end 7.25805 -77.284834)
		(width 0.10668)
		(layer "F.Cu")
		(net "OCP_V3_2_PRSNT23_R_N")
	)
	(segment
		(start 11.15695 -77.089)
		(end 10.018776 -77.089)
		(width 0.10668)
		(layer "F.Cu")
		(net "OCP_V3_2_PRSNT23_R_N")
	)
	(segment
		(start 7.25805 -77.284834)
		(end 4.367784 -74.394568)
		(width 0.10668)
		(layer "F.Cu")
		(net "OCP_V3_2_PRSNT23_R_N")
	)
	(segment
		(start 4.367784 -74.394568)
		(end 3.579368 -74.394568)
		(width 0.10668)
		(layer "F.Cu")
		(net "OCP_V3_2_PRSNT23_R_N")
	)
	(via
		(at 9.891776 -76.962)
		(size 0.762)
		(drill 0.381)
		(layers "F.Cu" "B.Cu")
		(net "OCP_V3_2_PRSNT23_R_N")
	)
	(segment
		(start 4.066286 -75.044808)
		(end 6.58114 -77.559662)
		(width 0.10668)
		(layer "F.Cu")
		(net "OCP_V3_2_PRSNT1_R_N")
	)
	(segment
		(start 10.782046 -78.180692)
		(end 11.378438 -78.180692)
		(width 0.10668)
		(layer "F.Cu")
		(net "OCP_V3_2_PRSNT1_R_N")
	)
	(segment
		(start 37.856922 -7.463536)
		(end 37.57168 -7.178294)
		(width 0.10668)
		(layer "F.Cu")
		(net "OCP_V3_2_PRSNT1_R_N")
	)
	(segment
		(start 37.856922 -8.320024)
		(end 37.856922 -7.463536)
		(width 0.10668)
		(layer "F.Cu")
		(net "OCP_V3_2_PRSNT1_R_N")
	)
	(segment
		(start 3.579368 -75.044808)
		(end 4.066286 -75.044808)
		(width 0.10668)
		(layer "F.Cu")
		(net "OCP_V3_2_PRSNT1_R_N")
	)
	(segment
		(start 9.52373 -77.559662)
		(end 10.14476 -78.180692)
		(width 0.10668)
		(layer "F.Cu")
		(net "OCP_V3_2_PRSNT1_R_N")
	)
	(segment
		(start 10.14476 -78.180692)
		(end 10.782046 -78.180692)
		(width 0.10668)
		(layer "F.Cu")
		(net "OCP_V3_2_PRSNT1_R_N")
	)
	(segment
		(start 11.56716 -78.369414)
		(end 12.00404 -78.369414)
		(width 0.10668)
		(layer "F.Cu")
		(net "OCP_V3_2_PRSNT1_R_N")
	)
	(segment
		(start 11.378438 -78.180692)
		(end 11.56716 -78.369414)
		(width 0.10668)
		(layer "F.Cu")
		(net "OCP_V3_2_PRSNT1_R_N")
	)
	(segment
		(start 6.58114 -77.559662)
		(end 9.52373 -77.559662)
		(width 0.10668)
		(layer "F.Cu")
		(net "OCP_V3_2_PRSNT1_R_N")
	)
	(via
		(at 37.57168 -7.178294)
		(size 0.508)
		(drill 0.254)
		(layers "F.Cu" "B.Cu")
		(net "OCP_V3_2_PRSNT1_R_N")
	)
	(via
		(at 10.782046 -78.180692)
		(size 0.508)
		(drill 0.254)
		(layers "F.Cu" "B.Cu")
		(net "OCP_V3_2_PRSNT1_R_N")
	)
	(segment
		(start 36.295838 -17.899888)
		(end 36.295838 -8.202676)
		(width 0.10668)
		(layer "B.Cu")
		(net "OCP_V3_2_PRSNT1_R_N")
	)
	(segment
		(start 11.989308 -78.180692)
		(end 12.982448 -77.187552)
		(width 0.10668)
		(layer "B.Cu")
		(net "OCP_V3_2_PRSNT1_R_N")
	)
	(segment
		(start 10.782046 -78.180692)
		(end 11.989308 -78.180692)
		(width 0.10668)
		(layer "B.Cu")
		(net "OCP_V3_2_PRSNT1_R_N")
	)
	(segment
		(start 37.385752 -34.452814)
		(end 37.385752 -18.989802)
		(width 0.10668)
		(layer "B.Cu")
		(net "OCP_V3_2_PRSNT1_R_N")
	)
	(segment
		(start 36.295838 -8.202676)
		(end 37.32022 -7.178294)
		(width 0.10668)
		(layer "B.Cu")
		(net "OCP_V3_2_PRSNT1_R_N")
	)
	(segment
		(start 12.982448 -77.187552)
		(end 12.982448 -58.856118)
		(width 0.10668)
		(layer "B.Cu")
		(net "OCP_V3_2_PRSNT1_R_N")
	)
	(segment
		(start 37.32022 -7.178294)
		(end 37.57168 -7.178294)
		(width 0.10668)
		(layer "B.Cu")
		(net "OCP_V3_2_PRSNT1_R_N")
	)
	(segment
		(start 12.982448 -58.856118)
		(end 37.385752 -34.452814)
		(width 0.10668)
		(layer "B.Cu")
		(net "OCP_V3_2_PRSNT1_R_N")
	)
	(segment
		(start 37.385752 -18.989802)
		(end 36.295838 -17.899888)
		(width 0.10668)
		(layer "B.Cu")
		(net "OCP_V3_2_PRSNT1_R_N")
	)
	(segment
		(start 4.131056 -75.744578)
		(end 7.237984 -78.851506)
		(width 0.10668)
		(layer "F.Cu")
		(net "OCP_V3_2_PRSNT0_R_N")
	)
	(segment
		(start 12.00404 -79.669386)
		(end 10.970768 -79.669386)
		(width 0.10668)
		(layer "F.Cu")
		(net "OCP_V3_2_PRSNT0_R_N")
	)
	(segment
		(start 10.970768 -79.669386)
		(end 10.782046 -79.480664)
		(width 0.10668)
		(layer "F.Cu")
		(net "OCP_V3_2_PRSNT0_R_N")
	)
	(segment
		(start 37.856922 -11.26998)
		(end 37.856922 -12.308078)
		(width 0.10668)
		(layer "F.Cu")
		(net "OCP_V3_2_PRSNT0_R_N")
	)
	(segment
		(start 37.856922 -12.308078)
		(end 37.79012 -12.37488)
		(width 0.10668)
		(layer "F.Cu")
		(net "OCP_V3_2_PRSNT0_R_N")
	)
	(segment
		(start 3.579368 -75.744578)
		(end 4.131056 -75.744578)
		(width 0.10668)
		(layer "F.Cu")
		(net "OCP_V3_2_PRSNT0_R_N")
	)
	(segment
		(start 10.782046 -79.480664)
		(end 10.14476 -79.480664)
		(width 0.10668)
		(layer "F.Cu")
		(net "OCP_V3_2_PRSNT0_R_N")
	)
	(segment
		(start 7.237984 -78.851506)
		(end 9.515602 -78.851506)
		(width 0.10668)
		(layer "F.Cu")
		(net "OCP_V3_2_PRSNT0_R_N")
	)
	(segment
		(start 9.515602 -78.851506)
		(end 10.14476 -79.480664)
		(width 0.10668)
		(layer "F.Cu")
		(net "OCP_V3_2_PRSNT0_R_N")
	)
	(via
		(at 37.79012 -12.37488)
		(size 0.508)
		(drill 0.254)
		(layers "F.Cu" "B.Cu")
		(net "OCP_V3_2_PRSNT0_R_N")
	)
	(via
		(at 10.782046 -79.480664)
		(size 0.508)
		(drill 0.254)
		(layers "F.Cu" "B.Cu")
		(net "OCP_V3_2_PRSNT0_R_N")
	)
	(segment
		(start 38.18636 -34.038794)
		(end 13.459968 -58.765186)
		(width 0.10668)
		(layer "B.Cu")
		(net "OCP_V3_2_PRSNT0_R_N")
	)
	(segment
		(start 13.459968 -77.345286)
		(end 11.32459 -79.480664)
		(width 0.10668)
		(layer "B.Cu")
		(net "OCP_V3_2_PRSNT0_R_N")
	)
	(segment
		(start 13.459968 -58.765186)
		(end 13.459968 -77.345286)
		(width 0.10668)
		(layer "B.Cu")
		(net "OCP_V3_2_PRSNT0_R_N")
	)
	(segment
		(start 38.18636 -19.745706)
		(end 38.18636 -34.038794)
		(width 0.10668)
		(layer "B.Cu")
		(net "OCP_V3_2_PRSNT0_R_N")
	)
	(segment
		(start 40.05453 -16.209518)
		(end 40.05453 -17.877536)
		(width 0.10668)
		(layer "B.Cu")
		(net "OCP_V3_2_PRSNT0_R_N")
	)
	(segment
		(start 37.79012 -12.37488)
		(end 37.79012 -13.945108)
		(width 0.10668)
		(layer "B.Cu")
		(net "OCP_V3_2_PRSNT0_R_N")
	)
	(segment
		(start 37.79012 -13.945108)
		(end 40.05453 -16.209518)
		(width 0.10668)
		(layer "B.Cu")
		(net "OCP_V3_2_PRSNT0_R_N")
	)
	(segment
		(start 40.05453 -17.877536)
		(end 38.18636 -19.745706)
		(width 0.10668)
		(layer "B.Cu")
		(net "OCP_V3_2_PRSNT0_R_N")
	)
	(segment
		(start 11.32459 -79.480664)
		(end 10.782046 -79.480664)
		(width 0.10668)
		(layer "B.Cu")
		(net "OCP_V3_2_PRSNT0_R_N")
	)
	(segment
		(start 8.87095 -74.336148)
		(end 8.68172 -74.525378)
		(width 0.10668)
		(layer "F.Cu")
		(net "OCP_V3_2_PRSNT01_R_N")
	)
	(segment
		(start 8.87095 -73.279)
		(end 8.87095 -74.336148)
		(width 0.10668)
		(layer "F.Cu")
		(net "OCP_V3_2_PRSNT01_R_N")
	)
	(segment
		(start 8.16229 -75.044808)
		(end 7.129272 -75.044808)
		(width 0.10668)
		(layer "F.Cu")
		(net "OCP_V3_2_PRSNT01_R_N")
	)
	(segment
		(start 8.68172 -74.525378)
		(end 8.16229 -75.044808)
		(width 0.10668)
		(layer "F.Cu")
		(net "OCP_V3_2_PRSNT01_R_N")
	)
	(via
		(at 8.68172 -74.525378)
		(size 0.762)
		(drill 0.381)
		(layers "F.Cu" "B.Cu")
		(net "OCP_V3_2_PRSNT01_R_N")
	)
	(segment
		(start 79.870554 -68.81495)
		(end 79.655924 -68.81495)
		(width 0.10668)
		(layer "F.Cu")
		(net "OCP_V3_2_P3V3_PWRGD")
	)
	(segment
		(start 86.84133 -58.51652)
		(end 87.14613 -58.21172)
		(width 0.10668)
		(layer "F.Cu")
		(net "OCP_V3_2_P3V3_PWRGD")
	)
	(segment
		(start 88.06053 -59.43092)
		(end 86.84133 -59.43092)
		(width 0.10668)
		(layer "F.Cu")
		(net "OCP_V3_2_P3V3_PWRGD")
	)
	(segment
		(start 67.420998 -59.905138)
		(end 65.556638 -59.905138)
		(width 0.10668)
		(layer "F.Cu")
		(net "OCP_V3_2_P3V3_PWRGD")
	)
	(segment
		(start 62.37605 -56.50992)
		(end 62.37605 -55.32247)
		(width 0.10668)
		(layer "F.Cu")
		(net "OCP_V3_2_P3V3_PWRGD")
	)
	(segment
		(start 79.908908 -67.912996)
		(end 81.019904 -66.802)
		(width 0.10668)
		(layer "F.Cu")
		(net "OCP_V3_2_P3V3_PWRGD")
	)
	(segment
		(start 86.84133 -59.43092)
		(end 86.84133 -58.51652)
		(width 0.10668)
		(layer "F.Cu")
		(net "OCP_V3_2_P3V3_PWRGD")
	)
	(segment
		(start 81.019904 -66.802)
		(end 81.04505 -66.802)
		(width 0.10668)
		(layer "F.Cu")
		(net "OCP_V3_2_P3V3_PWRGD")
	)
	(segment
		(start 74.897234 -64.05626)
		(end 71.57212 -64.05626)
		(width 0.10668)
		(layer "F.Cu")
		(net "OCP_V3_2_P3V3_PWRGD")
	)
	(segment
		(start 79.876396 -68.820792)
		(end 79.870554 -68.81495)
		(width 0.10668)
		(layer "F.Cu")
		(net "OCP_V3_2_P3V3_PWRGD")
	)
	(segment
		(start 79.908908 -68.838064)
		(end 79.891636 -68.820792)
		(width 0.10668)
		(layer "F.Cu")
		(net "OCP_V3_2_P3V3_PWRGD")
	)
	(segment
		(start 71.57212 -64.05626)
		(end 67.420998 -59.905138)
		(width 0.10668)
		(layer "F.Cu")
		(net "OCP_V3_2_P3V3_PWRGD")
	)
	(segment
		(start 61.696854 -54.643274)
		(end 61.139832 -54.643274)
		(width 0.10668)
		(layer "F.Cu")
		(net "OCP_V3_2_P3V3_PWRGD")
	)
	(segment
		(start 79.891636 -68.820792)
		(end 79.876396 -68.820792)
		(width 0.10668)
		(layer "F.Cu")
		(net "OCP_V3_2_P3V3_PWRGD")
	)
	(segment
		(start 65.556638 -59.905138)
		(end 62.85611 -57.20461)
		(width 0.10668)
		(layer "F.Cu")
		(net "OCP_V3_2_P3V3_PWRGD")
	)
	(segment
		(start 79.908908 -68.838064)
		(end 79.908908 -67.912996)
		(width 0.10668)
		(layer "F.Cu")
		(net "OCP_V3_2_P3V3_PWRGD")
	)
	(segment
		(start 62.85611 -56.98998)
		(end 62.37605 -56.50992)
		(width 0.10668)
		(layer "F.Cu")
		(net "OCP_V3_2_P3V3_PWRGD")
	)
	(segment
		(start 62.85611 -57.20461)
		(end 62.85611 -56.98998)
		(width 0.10668)
		(layer "F.Cu")
		(net "OCP_V3_2_P3V3_PWRGD")
	)
	(segment
		(start 79.655924 -68.81495)
		(end 74.897234 -64.05626)
		(width 0.10668)
		(layer "F.Cu")
		(net "OCP_V3_2_P3V3_PWRGD")
	)
	(segment
		(start 62.37605 -55.32247)
		(end 61.696854 -54.643274)
		(width 0.10668)
		(layer "F.Cu")
		(net "OCP_V3_2_P3V3_PWRGD")
	)
	(segment
		(start 81.04505 -66.802)
		(end 81.04505 -66.05905)
		(width 0.10668)
		(layer "F.Cu")
		(net "OCP_V3_2_P3V3_PWRGD")
	)
	(via
		(at 81.04505 -66.05905)
		(size 0.508)
		(drill 0.254)
		(layers "F.Cu" "B.Cu")
		(net "OCP_V3_2_P3V3_PWRGD")
	)
	(via
		(at 86.84133 -59.43092)
		(size 0.762)
		(drill 0.254)
		(layers "F.Cu" "B.Cu")
		(net "OCP_V3_2_P3V3_PWRGD")
	)
	(segment
		(start 86.84133 -59.43092)
		(end 81.04505 -65.2272)
		(width 0.11684)
		(layer "In2.Cu")
		(net "OCP_V3_2_P3V3_PWRGD")
	)
	(segment
		(start 81.04505 -65.2272)
		(end 81.04505 -66.05905)
		(width 0.11684)
		(layer "In2.Cu")
		(net "OCP_V3_2_P3V3_PWRGD")
	)
	(segment
		(start 143.740632 -99.005644)
		(end 141.286992 -99.005644)
		(width 0.10668)
		(layer "F.Cu")
		(net "OCP_V3_2_NOT_PRSNT_RBT_ARB_IN")
	)
	(segment
		(start 142.195042 -96.262444)
		(end 141.286992 -97.170494)
		(width 0.10668)
		(layer "F.Cu")
		(net "OCP_V3_2_NOT_PRSNT_RBT_ARB_IN")
	)
	(segment
		(start 143.740632 -96.262444)
		(end 142.195042 -96.262444)
		(width 0.10668)
		(layer "F.Cu")
		(net "OCP_V3_2_NOT_PRSNT_RBT_ARB_IN")
	)
	(segment
		(start 141.286992 -97.170494)
		(end 141.286992 -99.005644)
		(width 0.10668)
		(layer "F.Cu")
		(net "OCP_V3_2_NOT_PRSNT_RBT_ARB_IN")
	)
	(via
		(at 141.286992 -99.005644)
		(size 0.762)
		(drill 0.381)
		(layers "F.Cu" "B.Cu")
		(net "OCP_V3_2_NOT_PRSNT_RBT_ARB_IN")
	)
	(segment
		(start 76.889864 -10.077704)
		(end 76.889864 -9.83869)
		(width 0.10668)
		(layer "F.Cu")
		(net "OCP_V3_2_MAIN_PWR_EN_R")
	)
	(segment
		(start 76.889864 -9.83869)
		(end 77.026008 -9.702546)
		(width 0.10668)
		(layer "F.Cu")
		(net "OCP_V3_2_MAIN_PWR_EN_R")
	)
	(segment
		(start 77.461872 -10.649712)
		(end 76.889864 -10.077704)
		(width 0.10668)
		(layer "F.Cu")
		(net "OCP_V3_2_MAIN_PWR_EN_R")
	)
	(segment
		(start 77.461872 -11.26998)
		(end 77.461872 -10.649712)
		(width 0.10668)
		(layer "F.Cu")
		(net "OCP_V3_2_MAIN_PWR_EN_R")
	)
	(via
		(at 77.026008 -9.702546)
		(size 0.508)
		(drill 0.254)
		(layers "F.Cu" "B.Cu")
		(net "OCP_V3_2_MAIN_PWR_EN_R")
	)
	(segment
		(start 77.14488 -10.867898)
		(end 76.89088 -10.613898)
		(width 0.10668)
		(layer "B.Cu")
		(net "OCP_V3_2_MAIN_PWR_EN_R")
	)
	(segment
		(start 76.89088 -10.210546)
		(end 76.889864 -10.20953)
		(width 0.10668)
		(layer "B.Cu")
		(net "OCP_V3_2_MAIN_PWR_EN_R")
	)
	(segment
		(start 76.889864 -9.83869)
		(end 77.026008 -9.702546)
		(width 0.10668)
		(layer "B.Cu")
		(net "OCP_V3_2_MAIN_PWR_EN_R")
	)
	(segment
		(start 76.889864 -10.20953)
		(end 76.889864 -9.83869)
		(width 0.10668)
		(layer "B.Cu")
		(net "OCP_V3_2_MAIN_PWR_EN_R")
	)
	(segment
		(start 76.89088 -10.613898)
		(end 76.89088 -10.210546)
		(width 0.10668)
		(layer "B.Cu")
		(net "OCP_V3_2_MAIN_PWR_EN_R")
	)
	(segment
		(start 179.52212 -113.05286)
		(end 179.13223 -112.66297)
		(width 0.10668)
		(layer "F.Cu")
		(net "OCP_V3_2_MAIN_PWR_EN")
	)
	(via
		(at 77.867764 -12.75715)
		(size 0.508)
		(drill 0.254)
		(layers "F.Cu" "B.Cu")
		(net "OCP_V3_2_MAIN_PWR_EN")
	)
	(via
		(at 167.373046 -35.51936)
		(size 0.508)
		(drill 0.254)
		(layers "F.Cu" "B.Cu")
		(net "OCP_V3_2_MAIN_PWR_EN")
	)
	(via
		(at 175.9077 -113.46942)
		(size 0.6604)
		(drill 0.3302)
		(layers "F.Cu" "B.Cu")
		(net "OCP_V3_2_MAIN_PWR_EN")
	)
	(via
		(at 179.13223 -112.66297)
		(size 0.4572)
		(drill 0.254)
		(layers "F.Cu" "B.Cu")
		(net "OCP_V3_2_MAIN_PWR_EN")
	)
	(segment
		(start 77.707236 -11.667998)
		(end 77.707998 -11.66876)
		(width 0.10668)
		(layer "B.Cu")
		(net "OCP_V3_2_MAIN_PWR_EN")
	)
	(segment
		(start 78.159864 -12.46505)
		(end 77.867764 -12.75715)
		(width 0.10668)
		(layer "B.Cu")
		(net "OCP_V3_2_MAIN_PWR_EN")
	)
	(segment
		(start 175.9077 -113.46942)
		(end 176.130458 -113.46942)
		(width 0.10668)
		(layer "B.Cu")
		(net "OCP_V3_2_MAIN_PWR_EN")
	)
	(segment
		(start 176.130458 -113.46942)
		(end 176.540668 -113.05921)
		(width 0.10668)
		(layer "B.Cu")
		(net "OCP_V3_2_MAIN_PWR_EN")
	)
	(segment
		(start 78.159864 -11.66876)
		(end 78.159864 -12.46505)
		(width 0.10668)
		(layer "B.Cu")
		(net "OCP_V3_2_MAIN_PWR_EN")
	)
	(segment
		(start 178.73599 -113.05921)
		(end 179.13223 -112.66297)
		(width 0.10668)
		(layer "B.Cu")
		(net "OCP_V3_2_MAIN_PWR_EN")
	)
	(segment
		(start 77.14488 -11.667998)
		(end 77.707236 -11.667998)
		(width 0.10668)
		(layer "B.Cu")
		(net "OCP_V3_2_MAIN_PWR_EN")
	)
	(segment
		(start 77.707998 -11.66876)
		(end 78.159864 -11.66876)
		(width 0.10668)
		(layer "B.Cu")
		(net "OCP_V3_2_MAIN_PWR_EN")
	)
	(segment
		(start 176.540668 -113.05921)
		(end 178.73599 -113.05921)
		(width 0.10668)
		(layer "B.Cu")
		(net "OCP_V3_2_MAIN_PWR_EN")
	)
	(segment
		(start 142.689072 -36.338256)
		(end 144.599914 -36.338256)
		(width 0.11684)
		(layer "In6.Cu")
		(net "OCP_V3_2_MAIN_PWR_EN")
	)
	(segment
		(start 141.479524 -37.547804)
		(end 142.689072 -36.338256)
		(width 0.11684)
		(layer "In6.Cu")
		(net "OCP_V3_2_MAIN_PWR_EN")
	)
	(segment
		(start 97.3582 -33.03524)
		(end 99.96424 -35.64128)
		(width 0.11684)
		(layer "In6.Cu")
		(net "OCP_V3_2_MAIN_PWR_EN")
	)
	(segment
		(start 104.270048 -37.15258)
		(end 115.9256 -37.15258)
		(width 0.11684)
		(layer "In6.Cu")
		(net "OCP_V3_2_MAIN_PWR_EN")
	)
	(segment
		(start 161.45383 -36.87572)
		(end 164.515292 -36.87572)
		(width 0.11684)
		(layer "In6.Cu")
		(net "OCP_V3_2_MAIN_PWR_EN")
	)
	(segment
		(start 130.341116 -40.2082)
		(end 138.0236 -40.2082)
		(width 0.11684)
		(layer "In6.Cu")
		(net "OCP_V3_2_MAIN_PWR_EN")
	)
	(segment
		(start 164.515292 -36.87572)
		(end 165.871652 -35.51936)
		(width 0.11684)
		(layer "In6.Cu")
		(net "OCP_V3_2_MAIN_PWR_EN")
	)
	(segment
		(start 120.280684 -41.507664)
		(end 129.041652 -41.507664)
		(width 0.11684)
		(layer "In6.Cu")
		(net "OCP_V3_2_MAIN_PWR_EN")
	)
	(segment
		(start 81.623154 -16.51254)
		(end 97.618804 -16.51254)
		(width 0.11684)
		(layer "In6.Cu")
		(net "OCP_V3_2_MAIN_PWR_EN")
	)
	(segment
		(start 144.599914 -36.338256)
		(end 147.758404 -39.496746)
		(width 0.11684)
		(layer "In6.Cu")
		(net "OCP_V3_2_MAIN_PWR_EN")
	)
	(segment
		(start 97.618804 -16.51254)
		(end 100.475796 -19.369532)
		(width 0.11684)
		(layer "In6.Cu")
		(net "OCP_V3_2_MAIN_PWR_EN")
	)
	(segment
		(start 165.871652 -35.51936)
		(end 167.373046 -35.51936)
		(width 0.11684)
		(layer "In6.Cu")
		(net "OCP_V3_2_MAIN_PWR_EN")
	)
	(segment
		(start 77.867764 -12.75715)
		(end 81.623154 -16.51254)
		(width 0.11684)
		(layer "In6.Cu")
		(net "OCP_V3_2_MAIN_PWR_EN")
	)
	(segment
		(start 115.9256 -37.15258)
		(end 120.280684 -41.507664)
		(width 0.11684)
		(layer "In6.Cu")
		(net "OCP_V3_2_MAIN_PWR_EN")
	)
	(segment
		(start 140.683996 -37.547804)
		(end 141.479524 -37.547804)
		(width 0.11684)
		(layer "In6.Cu")
		(net "OCP_V3_2_MAIN_PWR_EN")
	)
	(segment
		(start 99.96424 -35.64128)
		(end 102.758748 -35.64128)
		(width 0.11684)
		(layer "In6.Cu")
		(net "OCP_V3_2_MAIN_PWR_EN")
	)
	(segment
		(start 100.475796 -26.05278)
		(end 97.3582 -29.170376)
		(width 0.11684)
		(layer "In6.Cu")
		(net "OCP_V3_2_MAIN_PWR_EN")
	)
	(segment
		(start 138.0236 -40.2082)
		(end 140.683996 -37.547804)
		(width 0.11684)
		(layer "In6.Cu")
		(net "OCP_V3_2_MAIN_PWR_EN")
	)
	(segment
		(start 129.041652 -41.507664)
		(end 130.341116 -40.2082)
		(width 0.11684)
		(layer "In6.Cu")
		(net "OCP_V3_2_MAIN_PWR_EN")
	)
	(segment
		(start 97.3582 -29.170376)
		(end 97.3582 -33.03524)
		(width 0.11684)
		(layer "In6.Cu")
		(net "OCP_V3_2_MAIN_PWR_EN")
	)
	(segment
		(start 158.461456 -39.868094)
		(end 161.45383 -36.87572)
		(width 0.11684)
		(layer "In6.Cu")
		(net "OCP_V3_2_MAIN_PWR_EN")
	)
	(segment
		(start 147.758404 -39.496746)
		(end 152.805892 -39.496746)
		(width 0.11684)
		(layer "In6.Cu")
		(net "OCP_V3_2_MAIN_PWR_EN")
	)
	(segment
		(start 100.475796 -19.369532)
		(end 100.475796 -26.05278)
		(width 0.11684)
		(layer "In6.Cu")
		(net "OCP_V3_2_MAIN_PWR_EN")
	)
	(segment
		(start 153.17724 -39.868094)
		(end 158.461456 -39.868094)
		(width 0.11684)
		(layer "In6.Cu")
		(net "OCP_V3_2_MAIN_PWR_EN")
	)
	(segment
		(start 152.805892 -39.496746)
		(end 153.17724 -39.868094)
		(width 0.11684)
		(layer "In6.Cu")
		(net "OCP_V3_2_MAIN_PWR_EN")
	)
	(segment
		(start 102.758748 -35.64128)
		(end 104.270048 -37.15258)
		(width 0.11684)
		(layer "In6.Cu")
		(net "OCP_V3_2_MAIN_PWR_EN")
	)
	(segment
		(start 174.598584 -93.615256)
		(end 174.195994 -93.212666)
		(width 0.11684)
		(layer "In11.Cu")
		(net "OCP_V3_2_MAIN_PWR_EN")
	)
	(segment
		(start 177.926238 -108.42371)
		(end 177.32375 -107.821222)
		(width 0.11684)
		(layer "In11.Cu")
		(net "OCP_V3_2_MAIN_PWR_EN")
	)
	(segment
		(start 178.73726 -111.693198)
		(end 178.508406 -111.464344)
		(width 0.11684)
		(layer "In11.Cu")
		(net "OCP_V3_2_MAIN_PWR_EN")
	)
	(segment
		(start 169.97426 -49.718468)
		(end 169.97426 -41.436036)
		(width 0.11684)
		(layer "In11.Cu")
		(net "OCP_V3_2_MAIN_PWR_EN")
	)
	(segment
		(start 177.32375 -102.468172)
		(end 175.17491 -100.319332)
		(width 0.11684)
		(layer "In11.Cu")
		(net "OCP_V3_2_MAIN_PWR_EN")
	)
	(segment
		(start 177.926238 -111.247936)
		(end 177.926238 -108.42371)
		(width 0.11684)
		(layer "In11.Cu")
		(net "OCP_V3_2_MAIN_PWR_EN")
	)
	(segment
		(start 174.575724 -90.100404)
		(end 174.598584 -90.100404)
		(width 0.11684)
		(layer "In11.Cu")
		(net "OCP_V3_2_MAIN_PWR_EN")
	)
	(segment
		(start 178.508406 -111.464344)
		(end 178.142646 -111.464344)
		(width 0.11684)
		(layer "In11.Cu")
		(net "OCP_V3_2_MAIN_PWR_EN")
	)
	(segment
		(start 169.1894 -78.600808)
		(end 169.1894 -50.503328)
		(width 0.11684)
		(layer "In11.Cu")
		(net "OCP_V3_2_MAIN_PWR_EN")
	)
	(segment
		(start 179.13223 -112.66297)
		(end 178.73726 -112.268)
		(width 0.11684)
		(layer "In11.Cu")
		(net "OCP_V3_2_MAIN_PWR_EN")
	)
	(segment
		(start 174.195994 -93.212666)
		(end 174.195994 -90.480134)
		(width 0.11684)
		(layer "In11.Cu")
		(net "OCP_V3_2_MAIN_PWR_EN")
	)
	(segment
		(start 175.134524 -84.545932)
		(end 169.1894 -78.600808)
		(width 0.11684)
		(layer "In11.Cu")
		(net "OCP_V3_2_MAIN_PWR_EN")
	)
	(segment
		(start 175.17491 -99.107244)
		(end 174.598584 -98.530918)
		(width 0.11684)
		(layer "In11.Cu")
		(net "OCP_V3_2_MAIN_PWR_EN")
	)
	(segment
		(start 174.195994 -90.480134)
		(end 174.575724 -90.100404)
		(width 0.11684)
		(layer "In11.Cu")
		(net "OCP_V3_2_MAIN_PWR_EN")
	)
	(segment
		(start 178.142646 -111.464344)
		(end 177.926238 -111.247936)
		(width 0.11684)
		(layer "In11.Cu")
		(net "OCP_V3_2_MAIN_PWR_EN")
	)
	(segment
		(start 174.598584 -90.100404)
		(end 175.134524 -89.564464)
		(width 0.11684)
		(layer "In11.Cu")
		(net "OCP_V3_2_MAIN_PWR_EN")
	)
	(segment
		(start 167.373046 -38.834822)
		(end 167.373046 -35.51936)
		(width 0.11684)
		(layer "In11.Cu")
		(net "OCP_V3_2_MAIN_PWR_EN")
	)
	(segment
		(start 175.134524 -89.564464)
		(end 175.134524 -84.545932)
		(width 0.11684)
		(layer "In11.Cu")
		(net "OCP_V3_2_MAIN_PWR_EN")
	)
	(segment
		(start 174.598584 -98.530918)
		(end 174.598584 -93.615256)
		(width 0.11684)
		(layer "In11.Cu")
		(net "OCP_V3_2_MAIN_PWR_EN")
	)
	(segment
		(start 178.73726 -112.268)
		(end 178.73726 -111.693198)
		(width 0.11684)
		(layer "In11.Cu")
		(net "OCP_V3_2_MAIN_PWR_EN")
	)
	(segment
		(start 175.17491 -100.319332)
		(end 175.17491 -99.107244)
		(width 0.11684)
		(layer "In11.Cu")
		(net "OCP_V3_2_MAIN_PWR_EN")
	)
	(segment
		(start 177.32375 -107.821222)
		(end 177.32375 -102.468172)
		(width 0.11684)
		(layer "In11.Cu")
		(net "OCP_V3_2_MAIN_PWR_EN")
	)
	(segment
		(start 169.1894 -50.503328)
		(end 169.97426 -49.718468)
		(width 0.11684)
		(layer "In11.Cu")
		(net "OCP_V3_2_MAIN_PWR_EN")
	)
	(segment
		(start 169.97426 -41.436036)
		(end 167.373046 -38.834822)
		(width 0.11684)
		(layer "In11.Cu")
		(net "OCP_V3_2_MAIN_PWR_EN")
	)
	(segment
		(start 60.667646 -18.535396)
		(end 60.666884 -18.536158)
		(width 0.10668)
		(layer "F.Cu")
		(net "OCP_V3_2_ISO_BIF2_EN")
	)
	(segment
		(start 60.666884 -16.981678)
		(end 61.027564 -16.620998)
		(width 0.10668)
		(layer "F.Cu")
		(net "OCP_V3_2_ISO_BIF2_EN")
	)
	(segment
		(start 61.50483 -18.252948)
		(end 61.222382 -18.535396)
		(width 0.10668)
		(layer "F.Cu")
		(net "OCP_V3_2_ISO_BIF2_EN")
	)
	(segment
		(start 61.222382 -18.535396)
		(end 60.667646 -18.535396)
		(width 0.10668)
		(layer "F.Cu")
		(net "OCP_V3_2_ISO_BIF2_EN")
	)
	(segment
		(start 60.666884 -18.536158)
		(end 60.666884 -16.981678)
		(width 0.10668)
		(layer "F.Cu")
		(net "OCP_V3_2_ISO_BIF2_EN")
	)
	(via
		(at 60.666884 -18.536158)
		(size 0.508)
		(drill 0.254)
		(layers "F.Cu" "B.Cu")
		(net "OCP_V3_2_ISO_BIF2_EN")
	)
	(segment
		(start 61.70168 -16.962882)
		(end 61.70168 -17.25041)
		(width 0.10668)
		(layer "F.Cu")
		(net "OCP_V3_2_ISO_BIF1_EN")
	)
	(segment
		(start 62.043564 -16.620998)
		(end 61.70168 -16.962882)
		(width 0.10668)
		(layer "F.Cu")
		(net "OCP_V3_2_ISO_BIF1_EN")
	)
	(via
		(at 61.70168 -17.25041)
		(size 0.508)
		(drill 0.254)
		(layers "F.Cu" "B.Cu")
		(net "OCP_V3_2_ISO_BIF1_EN")
	)
	(segment
		(start 61.70168 -17.25041)
		(end 61.413898 -16.962628)
		(width 0.10668)
		(layer "B.Cu")
		(net "OCP_V3_2_ISO_BIF1_EN")
	)
	(segment
		(start 61.413898 -16.962628)
		(end 61.413898 -15.98041)
		(width 0.10668)
		(layer "B.Cu")
		(net "OCP_V3_2_ISO_BIF1_EN")
	)
	(segment
		(start 63.059564 -16.620998)
		(end 63.059564 -17.391126)
		(width 0.10668)
		(layer "F.Cu")
		(net "OCP_V3_2_ISO_BIF0_EN")
	)
	(segment
		(start 63.059564 -17.391126)
		(end 63.115698 -17.44726)
		(width 0.10668)
		(layer "F.Cu")
		(net "OCP_V3_2_ISO_BIF0_EN")
	)
	(via
		(at 63.115698 -17.44726)
		(size 0.508)
		(drill 0.254)
		(layers "F.Cu" "B.Cu")
		(net "OCP_V3_2_ISO_BIF0_EN")
	)
	(segment
		(start 62.68847 -16.680942)
		(end 62.68847 -15.98041)
		(width 0.10668)
		(layer "B.Cu")
		(net "OCP_V3_2_ISO_BIF0_EN")
	)
	(segment
		(start 63.115698 -17.10817)
		(end 62.68847 -16.680942)
		(width 0.10668)
		(layer "B.Cu")
		(net "OCP_V3_2_ISO_BIF0_EN")
	)
	(segment
		(start 63.115698 -17.44726)
		(end 63.115698 -17.10817)
		(width 0.10668)
		(layer "B.Cu")
		(net "OCP_V3_2_ISO_BIF0_EN")
	)
	(segment
		(start 75.662028 -6.217666)
		(end 76.071984 -5.80771)
		(width 0.10668)
		(layer "F.Cu")
		(net "OCP_V3_2_ISO2_RBT_ARB_OUT")
	)
	(segment
		(start 75.662028 -8.320024)
		(end 75.662028 -6.217666)
		(width 0.10668)
		(layer "F.Cu")
		(net "OCP_V3_2_ISO2_RBT_ARB_OUT")
	)
	(via
		(at 190.22441 -40.286432)
		(size 0.508)
		(drill 0.254)
		(layers "F.Cu" "B.Cu")
		(net "OCP_V3_2_ISO2_RBT_ARB_OUT")
	)
	(via
		(at 197.464934 -70.602348)
		(size 0.508)
		(drill 0.254)
		(layers "F.Cu" "B.Cu")
		(net "OCP_V3_2_ISO2_RBT_ARB_OUT")
	)
	(via
		(at 76.071984 -5.80771)
		(size 0.508)
		(drill 0.254)
		(layers "F.Cu" "B.Cu")
		(net "OCP_V3_2_ISO2_RBT_ARB_OUT")
	)
	(segment
		(start 197.164198 -70.903084)
		(end 197.464934 -70.602348)
		(width 0.10668)
		(layer "B.Cu")
		(net "OCP_V3_2_ISO2_RBT_ARB_OUT")
	)
	(segment
		(start 195.55333 -70.903084)
		(end 197.164198 -70.903084)
		(width 0.10668)
		(layer "B.Cu")
		(net "OCP_V3_2_ISO2_RBT_ARB_OUT")
	)
	(segment
		(start 195.690744 -47.762922)
		(end 191.72555 -43.797728)
		(width 0.11684)
		(layer "In4.Cu")
		(net "OCP_V3_2_ISO2_RBT_ARB_OUT")
	)
	(segment
		(start 191.72555 -42.604944)
		(end 190.22441 -41.103804)
		(width 0.11684)
		(layer "In4.Cu")
		(net "OCP_V3_2_ISO2_RBT_ARB_OUT")
	)
	(segment
		(start 197.464934 -67.408298)
		(end 195.690744 -65.634108)
		(width 0.11684)
		(layer "In4.Cu")
		(net "OCP_V3_2_ISO2_RBT_ARB_OUT")
	)
	(segment
		(start 191.72555 -43.797728)
		(end 191.72555 -42.604944)
		(width 0.11684)
		(layer "In4.Cu")
		(net "OCP_V3_2_ISO2_RBT_ARB_OUT")
	)
	(segment
		(start 190.22441 -41.103804)
		(end 190.22441 -40.286432)
		(width 0.11684)
		(layer "In4.Cu")
		(net "OCP_V3_2_ISO2_RBT_ARB_OUT")
	)
	(segment
		(start 197.464934 -70.602348)
		(end 197.464934 -67.408298)
		(width 0.11684)
		(layer "In4.Cu")
		(net "OCP_V3_2_ISO2_RBT_ARB_OUT")
	)
	(segment
		(start 195.690744 -65.634108)
		(end 195.690744 -47.762922)
		(width 0.11684)
		(layer "In4.Cu")
		(net "OCP_V3_2_ISO2_RBT_ARB_OUT")
	)
	(segment
		(start 176.802796 -35.816286)
		(end 177.686462 -36.699952)
		(width 0.11684)
		(layer "In6.Cu")
		(net "OCP_V3_2_ISO2_RBT_ARB_OUT")
	)
	(segment
		(start 78.053184 -7.74573)
		(end 80.532478 -10.225024)
		(width 0.11684)
		(layer "In6.Cu")
		(net "OCP_V3_2_ISO2_RBT_ARB_OUT")
	)
	(segment
		(start 77.555852 -5.554726)
		(end 78.053184 -6.052058)
		(width 0.11684)
		(layer "In6.Cu")
		(net "OCP_V3_2_ISO2_RBT_ARB_OUT")
	)
	(segment
		(start 102.060756 -18.712688)
		(end 102.060756 -26.709624)
		(width 0.11684)
		(layer "In6.Cu")
		(net "OCP_V3_2_ISO2_RBT_ARB_OUT")
	)
	(segment
		(start 98.94316 -32.378396)
		(end 100.621084 -34.05632)
		(width 0.11684)
		(layer "In6.Cu")
		(net "OCP_V3_2_ISO2_RBT_ARB_OUT")
	)
	(segment
		(start 129.138172 -29.2354)
		(end 134.1628 -29.2354)
		(width 0.11684)
		(layer "In6.Cu")
		(net "OCP_V3_2_ISO2_RBT_ARB_OUT")
	)
	(segment
		(start 98.94316 -29.82722)
		(end 98.94316 -32.378396)
		(width 0.11684)
		(layer "In6.Cu")
		(net "OCP_V3_2_ISO2_RBT_ARB_OUT")
	)
	(segment
		(start 146.366484 -35.863022)
		(end 164.478716 -35.863022)
		(width 0.11684)
		(layer "In6.Cu")
		(net "OCP_V3_2_ISO2_RBT_ARB_OUT")
	)
	(segment
		(start 181.826916 -37.941504)
		(end 184.554368 -37.941504)
		(width 0.11684)
		(layer "In6.Cu")
		(net "OCP_V3_2_ISO2_RBT_ARB_OUT")
	)
	(segment
		(start 124.47016 -32.06496)
		(end 125.44044 -32.06496)
		(width 0.11684)
		(layer "In6.Cu")
		(net "OCP_V3_2_ISO2_RBT_ARB_OUT")
	)
	(segment
		(start 80.532478 -10.225024)
		(end 80.532478 -13.166852)
		(width 0.11684)
		(layer "In6.Cu")
		(net "OCP_V3_2_ISO2_RBT_ARB_OUT")
	)
	(segment
		(start 100.621084 -34.05632)
		(end 103.415592 -34.05632)
		(width 0.11684)
		(layer "In6.Cu")
		(net "OCP_V3_2_ISO2_RBT_ARB_OUT")
	)
	(segment
		(start 180.585364 -36.699952)
		(end 181.826916 -37.941504)
		(width 0.11684)
		(layer "In6.Cu")
		(net "OCP_V3_2_ISO2_RBT_ARB_OUT")
	)
	(segment
		(start 121.9454 -31.98622)
		(end 122.10542 -31.8262)
		(width 0.11684)
		(layer "In6.Cu")
		(net "OCP_V3_2_ISO2_RBT_ARB_OUT")
	)
	(segment
		(start 122.10542 -31.8262)
		(end 124.2314 -31.8262)
		(width 0.11684)
		(layer "In6.Cu")
		(net "OCP_V3_2_ISO2_RBT_ARB_OUT")
	)
	(segment
		(start 114.63274 -35.55746)
		(end 118.364 -31.8262)
		(width 0.11684)
		(layer "In6.Cu")
		(net "OCP_V3_2_ISO2_RBT_ARB_OUT")
	)
	(segment
		(start 186.445906 -39.833042)
		(end 189.77102 -39.833042)
		(width 0.11684)
		(layer "In6.Cu")
		(net "OCP_V3_2_ISO2_RBT_ARB_OUT")
	)
	(segment
		(start 120.41124 -31.8262)
		(end 120.57126 -31.98622)
		(width 0.11684)
		(layer "In6.Cu")
		(net "OCP_V3_2_ISO2_RBT_ARB_OUT")
	)
	(segment
		(start 76.071984 -5.80771)
		(end 76.324968 -5.554726)
		(width 0.11684)
		(layer "In6.Cu")
		(net "OCP_V3_2_ISO2_RBT_ARB_OUT")
	)
	(segment
		(start 80.532478 -13.166852)
		(end 82.293206 -14.92758)
		(width 0.11684)
		(layer "In6.Cu")
		(net "OCP_V3_2_ISO2_RBT_ARB_OUT")
	)
	(segment
		(start 124.2314 -31.8262)
		(end 124.47016 -32.06496)
		(width 0.11684)
		(layer "In6.Cu")
		(net "OCP_V3_2_ISO2_RBT_ARB_OUT")
	)
	(segment
		(start 126.5682 -30.9372)
		(end 127.436372 -30.9372)
		(width 0.11684)
		(layer "In6.Cu")
		(net "OCP_V3_2_ISO2_RBT_ARB_OUT")
	)
	(segment
		(start 166.273734 -34.068004)
		(end 173.130718 -34.068004)
		(width 0.11684)
		(layer "In6.Cu")
		(net "OCP_V3_2_ISO2_RBT_ARB_OUT")
	)
	(segment
		(start 103.415592 -34.05632)
		(end 104.916732 -35.55746)
		(width 0.11684)
		(layer "In6.Cu")
		(net "OCP_V3_2_ISO2_RBT_ARB_OUT")
	)
	(segment
		(start 177.686462 -36.699952)
		(end 180.585364 -36.699952)
		(width 0.11684)
		(layer "In6.Cu")
		(net "OCP_V3_2_ISO2_RBT_ARB_OUT")
	)
	(segment
		(start 136.2964 -31.369)
		(end 138.557 -31.369)
		(width 0.11684)
		(layer "In6.Cu")
		(net "OCP_V3_2_ISO2_RBT_ARB_OUT")
	)
	(segment
		(start 118.364 -31.8262)
		(end 120.41124 -31.8262)
		(width 0.11684)
		(layer "In6.Cu")
		(net "OCP_V3_2_ISO2_RBT_ARB_OUT")
	)
	(segment
		(start 184.554368 -37.941504)
		(end 186.445906 -39.833042)
		(width 0.11684)
		(layer "In6.Cu")
		(net "OCP_V3_2_ISO2_RBT_ARB_OUT")
	)
	(segment
		(start 102.060756 -26.709624)
		(end 98.94316 -29.82722)
		(width 0.11684)
		(layer "In6.Cu")
		(net "OCP_V3_2_ISO2_RBT_ARB_OUT")
	)
	(segment
		(start 78.053184 -6.052058)
		(end 78.053184 -7.74573)
		(width 0.11684)
		(layer "In6.Cu")
		(net "OCP_V3_2_ISO2_RBT_ARB_OUT")
	)
	(segment
		(start 189.77102 -39.833042)
		(end 190.22441 -40.286432)
		(width 0.11684)
		(layer "In6.Cu")
		(net "OCP_V3_2_ISO2_RBT_ARB_OUT")
	)
	(segment
		(start 120.57126 -31.98622)
		(end 121.9454 -31.98622)
		(width 0.11684)
		(layer "In6.Cu")
		(net "OCP_V3_2_ISO2_RBT_ARB_OUT")
	)
	(segment
		(start 127.436372 -30.9372)
		(end 129.138172 -29.2354)
		(width 0.11684)
		(layer "In6.Cu")
		(net "OCP_V3_2_ISO2_RBT_ARB_OUT")
	)
	(segment
		(start 144.560798 -34.057336)
		(end 146.366484 -35.863022)
		(width 0.11684)
		(layer "In6.Cu")
		(net "OCP_V3_2_ISO2_RBT_ARB_OUT")
	)
	(segment
		(start 98.275648 -14.92758)
		(end 102.060756 -18.712688)
		(width 0.11684)
		(layer "In6.Cu")
		(net "OCP_V3_2_ISO2_RBT_ARB_OUT")
	)
	(segment
		(start 173.130718 -34.068004)
		(end 174.879 -35.816286)
		(width 0.11684)
		(layer "In6.Cu")
		(net "OCP_V3_2_ISO2_RBT_ARB_OUT")
	)
	(segment
		(start 134.1628 -29.2354)
		(end 136.2964 -31.369)
		(width 0.11684)
		(layer "In6.Cu")
		(net "OCP_V3_2_ISO2_RBT_ARB_OUT")
	)
	(segment
		(start 125.44044 -32.06496)
		(end 126.5682 -30.9372)
		(width 0.11684)
		(layer "In6.Cu")
		(net "OCP_V3_2_ISO2_RBT_ARB_OUT")
	)
	(segment
		(start 174.879 -35.816286)
		(end 176.802796 -35.816286)
		(width 0.11684)
		(layer "In6.Cu")
		(net "OCP_V3_2_ISO2_RBT_ARB_OUT")
	)
	(segment
		(start 138.557 -31.369)
		(end 141.245336 -34.057336)
		(width 0.11684)
		(layer "In6.Cu")
		(net "OCP_V3_2_ISO2_RBT_ARB_OUT")
	)
	(segment
		(start 164.478716 -35.863022)
		(end 166.273734 -34.068004)
		(width 0.11684)
		(layer "In6.Cu")
		(net "OCP_V3_2_ISO2_RBT_ARB_OUT")
	)
	(segment
		(start 82.293206 -14.92758)
		(end 98.275648 -14.92758)
		(width 0.11684)
		(layer "In6.Cu")
		(net "OCP_V3_2_ISO2_RBT_ARB_OUT")
	)
	(segment
		(start 76.324968 -5.554726)
		(end 77.555852 -5.554726)
		(width 0.11684)
		(layer "In6.Cu")
		(net "OCP_V3_2_ISO2_RBT_ARB_OUT")
	)
	(segment
		(start 141.245336 -34.057336)
		(end 144.560798 -34.057336)
		(width 0.11684)
		(layer "In6.Cu")
		(net "OCP_V3_2_ISO2_RBT_ARB_OUT")
	)
	(segment
		(start 104.916732 -35.55746)
		(end 114.63274 -35.55746)
		(width 0.11684)
		(layer "In6.Cu")
		(net "OCP_V3_2_ISO2_RBT_ARB_OUT")
	)
	(segment
		(start 76.261976 -8.320024)
		(end 76.261976 -7.20471)
		(width 0.10668)
		(layer "F.Cu")
		(net "OCP_V3_2_ISO1_RBT_ARB_IN")
	)
	(via
		(at 204.691234 -77.422248)
		(size 0.508)
		(drill 0.254)
		(layers "F.Cu" "B.Cu")
		(net "OCP_V3_2_ISO1_RBT_ARB_IN")
	)
	(via
		(at 76.261976 -7.20471)
		(size 0.508)
		(drill 0.254)
		(layers "F.Cu" "B.Cu")
		(net "OCP_V3_2_ISO1_RBT_ARB_IN")
	)
	(via
		(at 192.100962 -40.237918)
		(size 0.508)
		(drill 0.254)
		(layers "F.Cu" "B.Cu")
		(net "OCP_V3_2_ISO1_RBT_ARB_IN")
	)
	(segment
		(start 206.374746 -77.263752)
		(end 204.84973 -77.263752)
		(width 0.10668)
		(layer "B.Cu")
		(net "OCP_V3_2_ISO1_RBT_ARB_IN")
	)
	(segment
		(start 204.84973 -77.263752)
		(end 204.691234 -77.422248)
		(width 0.10668)
		(layer "B.Cu")
		(net "OCP_V3_2_ISO1_RBT_ARB_IN")
	)
	(segment
		(start 202.91552 -65.704466)
		(end 197.118732 -59.907678)
		(width 0.11684)
		(layer "In4.Cu")
		(net "OCP_V3_2_ISO1_RBT_ARB_IN")
	)
	(segment
		(start 204.99197 -77.121512)
		(end 204.99197 -69.800216)
		(width 0.11684)
		(layer "In4.Cu")
		(net "OCP_V3_2_ISO1_RBT_ARB_IN")
	)
	(segment
		(start 202.91552 -67.723766)
		(end 202.91552 -65.704466)
		(width 0.11684)
		(layer "In4.Cu")
		(net "OCP_V3_2_ISO1_RBT_ARB_IN")
	)
	(segment
		(start 204.691234 -77.422248)
		(end 204.99197 -77.121512)
		(width 0.11684)
		(layer "In4.Cu")
		(net "OCP_V3_2_ISO1_RBT_ARB_IN")
	)
	(segment
		(start 197.118732 -45.255688)
		(end 192.100962 -40.237918)
		(width 0.11684)
		(layer "In4.Cu")
		(net "OCP_V3_2_ISO1_RBT_ARB_IN")
	)
	(segment
		(start 204.99197 -69.800216)
		(end 202.91552 -67.723766)
		(width 0.11684)
		(layer "In4.Cu")
		(net "OCP_V3_2_ISO1_RBT_ARB_IN")
	)
	(segment
		(start 197.118732 -59.907678)
		(end 197.118732 -45.255688)
		(width 0.11684)
		(layer "In4.Cu")
		(net "OCP_V3_2_ISO1_RBT_ARB_IN")
	)
	(segment
		(start 80.212438 -10.357612)
		(end 77.780134 -7.925308)
		(width 0.11684)
		(layer "In6.Cu")
		(net "OCP_V3_2_ISO1_RBT_ARB_IN")
	)
	(segment
		(start 116.0145 -35.8775)
		(end 104.784144 -35.8775)
		(width 0.11684)
		(layer "In6.Cu")
		(net "OCP_V3_2_ISO1_RBT_ARB_IN")
	)
	(segment
		(start 123.063 -34.9504)
		(end 121.9708 -34.9504)
		(width 0.11684)
		(layer "In6.Cu")
		(net "OCP_V3_2_ISO1_RBT_ARB_IN")
	)
	(segment
		(start 100.488496 -34.37636)
		(end 98.62312 -32.510984)
		(width 0.11684)
		(layer "In6.Cu")
		(net "OCP_V3_2_ISO1_RBT_ARB_IN")
	)
	(segment
		(start 121.6152 -34.5948)
		(end 117.2972 -34.5948)
		(width 0.11684)
		(layer "In6.Cu")
		(net "OCP_V3_2_ISO1_RBT_ARB_IN")
	)
	(segment
		(start 141.112748 -34.377376)
		(end 138.739372 -32.004)
		(width 0.11684)
		(layer "In6.Cu")
		(net "OCP_V3_2_ISO1_RBT_ARB_IN")
	)
	(segment
		(start 76.982574 -7.925308)
		(end 76.261976 -7.20471)
		(width 0.11684)
		(layer "In6.Cu")
		(net "OCP_V3_2_ISO1_RBT_ARB_IN")
	)
	(segment
		(start 146.233896 -36.183062)
		(end 144.42821 -34.377376)
		(width 0.11684)
		(layer "In6.Cu")
		(net "OCP_V3_2_ISO1_RBT_ARB_IN")
	)
	(segment
		(start 177.553874 -37.019992)
		(end 176.670208 -36.136326)
		(width 0.11684)
		(layer "In6.Cu")
		(net "OCP_V3_2_ISO1_RBT_ARB_IN")
	)
	(segment
		(start 123.4567 -34.5567)
		(end 123.063 -34.9504)
		(width 0.11684)
		(layer "In6.Cu")
		(net "OCP_V3_2_ISO1_RBT_ARB_IN")
	)
	(segment
		(start 124.07392 -32.41548)
		(end 123.4567 -33.0327)
		(width 0.11684)
		(layer "In6.Cu")
		(net "OCP_V3_2_ISO1_RBT_ARB_IN")
	)
	(segment
		(start 117.2972 -34.5948)
		(end 116.0145 -35.8775)
		(width 0.11684)
		(layer "In6.Cu")
		(net "OCP_V3_2_ISO1_RBT_ARB_IN")
	)
	(segment
		(start 189.833504 -40.788082)
		(end 189.454536 -40.409114)
		(width 0.11684)
		(layer "In6.Cu")
		(net "OCP_V3_2_ISO1_RBT_ARB_IN")
	)
	(segment
		(start 174.746412 -36.136326)
		(end 172.99813 -34.388044)
		(width 0.11684)
		(layer "In6.Cu")
		(net "OCP_V3_2_ISO1_RBT_ARB_IN")
	)
	(segment
		(start 138.739372 -32.004)
		(end 136.478772 -32.004)
		(width 0.11684)
		(layer "In6.Cu")
		(net "OCP_V3_2_ISO1_RBT_ARB_IN")
	)
	(segment
		(start 176.670208 -36.136326)
		(end 174.746412 -36.136326)
		(width 0.11684)
		(layer "In6.Cu")
		(net "OCP_V3_2_ISO1_RBT_ARB_IN")
	)
	(segment
		(start 180.452776 -37.019992)
		(end 177.553874 -37.019992)
		(width 0.11684)
		(layer "In6.Cu")
		(net "OCP_V3_2_ISO1_RBT_ARB_IN")
	)
	(segment
		(start 98.62312 -32.510984)
		(end 98.62312 -29.694632)
		(width 0.11684)
		(layer "In6.Cu")
		(net "OCP_V3_2_ISO1_RBT_ARB_IN")
	)
	(segment
		(start 186.56935 -40.409114)
		(end 184.42178 -38.261544)
		(width 0.11684)
		(layer "In6.Cu")
		(net "OCP_V3_2_ISO1_RBT_ARB_IN")
	)
	(segment
		(start 172.99813 -34.388044)
		(end 166.406322 -34.388044)
		(width 0.11684)
		(layer "In6.Cu")
		(net "OCP_V3_2_ISO1_RBT_ARB_IN")
	)
	(segment
		(start 126.41072 -32.41548)
		(end 124.07392 -32.41548)
		(width 0.11684)
		(layer "In6.Cu")
		(net "OCP_V3_2_ISO1_RBT_ARB_IN")
	)
	(segment
		(start 129.2098 -29.6164)
		(end 126.41072 -32.41548)
		(width 0.11684)
		(layer "In6.Cu")
		(net "OCP_V3_2_ISO1_RBT_ARB_IN")
	)
	(segment
		(start 80.212438 -13.29944)
		(end 80.212438 -10.357612)
		(width 0.11684)
		(layer "In6.Cu")
		(net "OCP_V3_2_ISO1_RBT_ARB_IN")
	)
	(segment
		(start 164.611304 -36.183062)
		(end 146.233896 -36.183062)
		(width 0.11684)
		(layer "In6.Cu")
		(net "OCP_V3_2_ISO1_RBT_ARB_IN")
	)
	(segment
		(start 121.9708 -34.9504)
		(end 121.6152 -34.5948)
		(width 0.11684)
		(layer "In6.Cu")
		(net "OCP_V3_2_ISO1_RBT_ARB_IN")
	)
	(segment
		(start 166.406322 -34.388044)
		(end 164.611304 -36.183062)
		(width 0.11684)
		(layer "In6.Cu")
		(net "OCP_V3_2_ISO1_RBT_ARB_IN")
	)
	(segment
		(start 191.550798 -40.788082)
		(end 189.833504 -40.788082)
		(width 0.11684)
		(layer "In6.Cu")
		(net "OCP_V3_2_ISO1_RBT_ARB_IN")
	)
	(segment
		(start 103.283004 -34.37636)
		(end 100.488496 -34.37636)
		(width 0.11684)
		(layer "In6.Cu")
		(net "OCP_V3_2_ISO1_RBT_ARB_IN")
	)
	(segment
		(start 181.694328 -38.261544)
		(end 180.452776 -37.019992)
		(width 0.11684)
		(layer "In6.Cu")
		(net "OCP_V3_2_ISO1_RBT_ARB_IN")
	)
	(segment
		(start 98.14306 -15.24762)
		(end 82.160618 -15.24762)
		(width 0.11684)
		(layer "In6.Cu")
		(net "OCP_V3_2_ISO1_RBT_ARB_IN")
	)
	(segment
		(start 134.091172 -29.6164)
		(end 129.2098 -29.6164)
		(width 0.11684)
		(layer "In6.Cu")
		(net "OCP_V3_2_ISO1_RBT_ARB_IN")
	)
	(segment
		(start 136.478772 -32.004)
		(end 134.091172 -29.6164)
		(width 0.11684)
		(layer "In6.Cu")
		(net "OCP_V3_2_ISO1_RBT_ARB_IN")
	)
	(segment
		(start 192.100962 -40.237918)
		(end 191.550798 -40.788082)
		(width 0.11684)
		(layer "In6.Cu")
		(net "OCP_V3_2_ISO1_RBT_ARB_IN")
	)
	(segment
		(start 101.740716 -26.577036)
		(end 101.740716 -18.845276)
		(width 0.11684)
		(layer "In6.Cu")
		(net "OCP_V3_2_ISO1_RBT_ARB_IN")
	)
	(segment
		(start 144.42821 -34.377376)
		(end 141.112748 -34.377376)
		(width 0.11684)
		(layer "In6.Cu")
		(net "OCP_V3_2_ISO1_RBT_ARB_IN")
	)
	(segment
		(start 189.454536 -40.409114)
		(end 186.56935 -40.409114)
		(width 0.11684)
		(layer "In6.Cu")
		(net "OCP_V3_2_ISO1_RBT_ARB_IN")
	)
	(segment
		(start 104.784144 -35.8775)
		(end 103.283004 -34.37636)
		(width 0.11684)
		(layer "In6.Cu")
		(net "OCP_V3_2_ISO1_RBT_ARB_IN")
	)
	(segment
		(start 123.4567 -33.0327)
		(end 123.4567 -34.5567)
		(width 0.11684)
		(layer "In6.Cu")
		(net "OCP_V3_2_ISO1_RBT_ARB_IN")
	)
	(segment
		(start 184.42178 -38.261544)
		(end 181.694328 -38.261544)
		(width 0.11684)
		(layer "In6.Cu")
		(net "OCP_V3_2_ISO1_RBT_ARB_IN")
	)
	(segment
		(start 82.160618 -15.24762)
		(end 80.212438 -13.29944)
		(width 0.11684)
		(layer "In6.Cu")
		(net "OCP_V3_2_ISO1_RBT_ARB_IN")
	)
	(segment
		(start 101.740716 -18.845276)
		(end 98.14306 -15.24762)
		(width 0.11684)
		(layer "In6.Cu")
		(net "OCP_V3_2_ISO1_RBT_ARB_IN")
	)
	(segment
		(start 98.62312 -29.694632)
		(end 101.740716 -26.577036)
		(width 0.11684)
		(layer "In6.Cu")
		(net "OCP_V3_2_ISO1_RBT_ARB_IN")
	)
	(segment
		(start 77.780134 -7.925308)
		(end 76.982574 -7.925308)
		(width 0.11684)
		(layer "In6.Cu")
		(net "OCP_V3_2_ISO1_RBT_ARB_IN")
	)
	(segment
		(start 75.061064 -8.319008)
		(end 75.06208 -8.320024)
		(width 0.10668)
		(layer "F.Cu")
		(net "OCP_V3_2_ID1")
	)
	(segment
		(start 75.061064 -6.69671)
		(end 75.061064 -8.319008)
		(width 0.10668)
		(layer "F.Cu")
		(net "OCP_V3_2_ID1")
	)
	(via
		(at 75.061064 -6.69671)
		(size 0.508)
		(drill 0.254)
		(layers "F.Cu" "B.Cu")
		(net "OCP_V3_2_ID1")
	)
	(segment
		(start 75.061064 -6.18617)
		(end 75.061064 -6.69671)
		(width 0.10668)
		(layer "B.Cu")
		(net "OCP_V3_2_ID1")
	)
	(segment
		(start 75.57008 -4.651248)
		(end 75.57008 -5.060442)
		(width 0.10668)
		(layer "B.Cu")
		(net "OCP_V3_2_ID1")
	)
	(segment
		(start 75.57008 -5.060442)
		(end 75.06208 -5.568442)
		(width 0.10668)
		(layer "B.Cu")
		(net "OCP_V3_2_ID1")
	)
	(segment
		(start 75.06208 -6.185154)
		(end 75.061064 -6.18617)
		(width 0.10668)
		(layer "B.Cu")
		(net "OCP_V3_2_ID1")
	)
	(segment
		(start 74.55408 -4.651248)
		(end 75.57008 -4.651248)
		(width 0.10668)
		(layer "B.Cu")
		(net "OCP_V3_2_ID1")
	)
	(segment
		(start 75.06208 -5.568442)
		(end 75.06208 -6.185154)
		(width 0.10668)
		(layer "B.Cu")
		(net "OCP_V3_2_ID1")
	)
	(segment
		(start 74.461878 -11.26998)
		(end 74.461878 -12.83335)
		(width 0.10668)
		(layer "F.Cu")
		(net "OCP_V3_2_ID0")
	)
	(via
		(at 74.461878 -12.83335)
		(size 0.508)
		(drill 0.254)
		(layers "F.Cu" "B.Cu")
		(net "OCP_V3_2_ID0")
	)
	(segment
		(start 72.825864 -11.66876)
		(end 73.2536 -12.096496)
		(width 0.10668)
		(layer "B.Cu")
		(net "OCP_V3_2_ID0")
	)
	(segment
		(start 71.809864 -11.66876)
		(end 72.825864 -11.66876)
		(width 0.10668)
		(layer "B.Cu")
		(net "OCP_V3_2_ID0")
	)
	(segment
		(start 73.625202 -12.83335)
		(end 74.461878 -12.83335)
		(width 0.10668)
		(layer "B.Cu")
		(net "OCP_V3_2_ID0")
	)
	(segment
		(start 73.2536 -12.461748)
		(end 73.625202 -12.83335)
		(width 0.10668)
		(layer "B.Cu")
		(net "OCP_V3_2_ID0")
	)
	(segment
		(start 73.2536 -12.096496)
		(end 73.2536 -12.461748)
		(width 0.10668)
		(layer "B.Cu")
		(net "OCP_V3_2_ID0")
	)
	(segment
		(start 61.027564 -15.820898)
		(end 60.892436 -15.68577)
		(width 0.10668)
		(layer "F.Cu")
		(net "OCP_V3_2_BIF2_R_N")
	)
	(segment
		(start 60.892436 -14.58849)
		(end 61.361828 -14.119098)
		(width 0.10668)
		(layer "F.Cu")
		(net "OCP_V3_2_BIF2_R_N")
	)
	(segment
		(start 60.892436 -15.68577)
		(end 60.892436 -14.58849)
		(width 0.10668)
		(layer "F.Cu")
		(net "OCP_V3_2_BIF2_R_N")
	)
	(segment
		(start 61.361828 -13.393928)
		(end 61.091064 -13.123164)
		(width 0.10668)
		(layer "F.Cu")
		(net "OCP_V3_2_BIF2_R_N")
	)
	(segment
		(start 61.091064 -11.29411)
		(end 61.066934 -11.26998)
		(width 0.10668)
		(layer "F.Cu")
		(net "OCP_V3_2_BIF2_R_N")
	)
	(segment
		(start 61.361828 -14.119098)
		(end 61.361828 -13.393928)
		(width 0.10668)
		(layer "F.Cu")
		(net "OCP_V3_2_BIF2_R_N")
	)
	(segment
		(start 61.091064 -13.123164)
		(end 61.091064 -11.29411)
		(width 0.10668)
		(layer "F.Cu")
		(net "OCP_V3_2_BIF2_R_N")
	)
	(via
		(at 60.892436 -14.58849)
		(size 0.762)
		(drill 0.381)
		(layers "F.Cu" "B.Cu")
		(net "OCP_V3_2_BIF2_R_N")
	)
	(segment
		(start 62.116208 -14.462506)
		(end 61.562742 -15.015972)
		(width 0.10668)
		(layer "F.Cu")
		(net "OCP_V3_2_BIF1_R_N")
	)
	(segment
		(start 61.666882 -12.878054)
		(end 62.31382 -13.524992)
		(width 0.10668)
		(layer "F.Cu")
		(net "OCP_V3_2_BIF1_R_N")
	)
	(segment
		(start 62.31382 -13.524992)
		(end 62.31382 -14.462506)
		(width 0.10668)
		(layer "F.Cu")
		(net "OCP_V3_2_BIF1_R_N")
	)
	(segment
		(start 61.562742 -15.340076)
		(end 62.043564 -15.820898)
		(width 0.10668)
		(layer "F.Cu")
		(net "OCP_V3_2_BIF1_R_N")
	)
	(segment
		(start 62.31382 -14.462506)
		(end 62.116208 -14.462506)
		(width 0.10668)
		(layer "F.Cu")
		(net "OCP_V3_2_BIF1_R_N")
	)
	(segment
		(start 61.562742 -15.015972)
		(end 61.562742 -15.340076)
		(width 0.10668)
		(layer "F.Cu")
		(net "OCP_V3_2_BIF1_R_N")
	)
	(segment
		(start 61.666882 -11.26998)
		(end 61.666882 -12.878054)
		(width 0.10668)
		(layer "F.Cu")
		(net "OCP_V3_2_BIF1_R_N")
	)
	(via
		(at 62.31382 -14.462506)
		(size 0.762)
		(drill 0.381)
		(layers "F.Cu" "B.Cu")
		(net "OCP_V3_2_BIF1_R_N")
	)
	(segment
		(start 62.267084 -13.092938)
		(end 63.476886 -14.30274)
		(width 0.10668)
		(layer "F.Cu")
		(net "OCP_V3_2_BIF0_R_N")
	)
	(segment
		(start 63.476886 -14.978634)
		(end 63.476886 -15.403576)
		(width 0.10668)
		(layer "F.Cu")
		(net "OCP_V3_2_BIF0_R_N")
	)
	(segment
		(start 62.267084 -11.26998)
		(end 62.267084 -13.092938)
		(width 0.10668)
		(layer "F.Cu")
		(net "OCP_V3_2_BIF0_R_N")
	)
	(segment
		(start 63.476886 -14.30274)
		(end 63.476886 -14.978634)
		(width 0.10668)
		(layer "F.Cu")
		(net "OCP_V3_2_BIF0_R_N")
	)
	(segment
		(start 63.476886 -15.403576)
		(end 63.059564 -15.820898)
		(width 0.10668)
		(layer "F.Cu")
		(net "OCP_V3_2_BIF0_R_N")
	)
	(via
		(at 63.476886 -14.978634)
		(size 0.762)
		(drill 0.381)
		(layers "F.Cu" "B.Cu")
		(net "OCP_V3_2_BIF0_R_N")
	)
	(segment
		(start 51.577494 -27.76982)
		(end 51.577494 -28.707588)
		(width 0.10668)
		(layer "F.Cu")
		(net "OCP_V3_2_AUX_PWR_EN_R3")
	)
	(segment
		(start 52.418996 -26.928318)
		(end 51.577494 -27.76982)
		(width 0.10668)
		(layer "F.Cu")
		(net "OCP_V3_2_AUX_PWR_EN_R3")
	)
	(segment
		(start 52.877466 -25.709118)
		(end 52.877466 -26.928318)
		(width 0.10668)
		(layer "F.Cu")
		(net "OCP_V3_2_AUX_PWR_EN_R3")
	)
	(segment
		(start 52.877466 -26.928318)
		(end 52.418996 -26.928318)
		(width 0.10668)
		(layer "F.Cu")
		(net "OCP_V3_2_AUX_PWR_EN_R3")
	)
	(via
		(at 52.877466 -26.928318)
		(size 0.762)
		(drill 0.381)
		(layers "F.Cu" "B.Cu")
		(net "OCP_V3_2_AUX_PWR_EN_R3")
	)
	(segment
		(start 49.778666 -25.709118)
		(end 49.778666 -26.928318)
		(width 0.10668)
		(layer "F.Cu")
		(net "OCP_V3_2_AUX_PWR_EN_R1")
	)
	(segment
		(start 48.478694 -27.76982)
		(end 48.478694 -28.707588)
		(width 0.10668)
		(layer "F.Cu")
		(net "OCP_V3_2_AUX_PWR_EN_R1")
	)
	(segment
		(start 49.778666 -26.928318)
		(end 49.320196 -26.928318)
		(width 0.10668)
		(layer "F.Cu")
		(net "OCP_V3_2_AUX_PWR_EN_R1")
	)
	(segment
		(start 49.320196 -26.928318)
		(end 48.478694 -27.76982)
		(width 0.10668)
		(layer "F.Cu")
		(net "OCP_V3_2_AUX_PWR_EN_R1")
	)
	(via
		(at 49.778666 -26.928318)
		(size 0.762)
		(drill 0.381)
		(layers "F.Cu" "B.Cu")
		(net "OCP_V3_2_AUX_PWR_EN_R1")
	)
	(segment
		(start 59.26709 -14.564614)
		(end 60.011564 -15.309088)
		(width 0.10668)
		(layer "F.Cu")
		(net "OCP_V3_2_AUX_PWR_EN_R")
	)
	(segment
		(start 59.26709 -11.26998)
		(end 59.26709 -14.564614)
		(width 0.10668)
		(layer "F.Cu")
		(net "OCP_V3_2_AUX_PWR_EN_R")
	)
	(segment
		(start 60.011564 -15.309088)
		(end 60.011564 -15.820898)
		(width 0.10668)
		(layer "F.Cu")
		(net "OCP_V3_2_AUX_PWR_EN_R")
	)
	(via
		(at 59.26709 -14.564614)
		(size 0.762)
		(drill 0.381)
		(layers "F.Cu" "B.Cu")
		(net "OCP_V3_2_AUX_PWR_EN_R")
	)
	(segment
		(start 59.737244 -24.909018)
		(end 59.737244 -21.568156)
		(width 0.10668)
		(layer "F.Cu")
		(net "OCP_V3_2_AUX_PWR_EN")
	)
	(segment
		(start 72.644 -52.578)
		(end 73.152 -53.086)
		(width 0.10668)
		(layer "F.Cu")
		(net "OCP_V3_2_AUX_PWR_EN")
	)
	(segment
		(start 60.387484 -19.268948)
		(end 61.50483 -19.268948)
		(width 0.10668)
		(layer "F.Cu")
		(net "OCP_V3_2_AUX_PWR_EN")
	)
	(segment
		(start 59.737244 -21.568156)
		(end 61.50483 -19.80057)
		(width 0.10668)
		(layer "F.Cu")
		(net "OCP_V3_2_AUX_PWR_EN")
	)
	(segment
		(start 71.13905 -53.594)
		(end 71.13905 -52.578)
		(width 0.10668)
		(layer "F.Cu")
		(net "OCP_V3_2_AUX_PWR_EN")
	)
	(segment
		(start 49.778666 -24.909018)
		(end 52.877466 -24.909018)
		(width 0.10668)
		(layer "F.Cu")
		(net "OCP_V3_2_AUX_PWR_EN")
	)
	(segment
		(start 60.011564 -16.620998)
		(end 60.011564 -18.893028)
		(width 0.10668)
		(layer "F.Cu")
		(net "OCP_V3_2_AUX_PWR_EN")
	)
	(segment
		(start 60.011564 -18.893028)
		(end 60.387484 -19.268948)
		(width 0.10668)
		(layer "F.Cu")
		(net "OCP_V3_2_AUX_PWR_EN")
	)
	(segment
		(start 71.13905 -52.578)
		(end 72.644 -52.578)
		(width 0.10668)
		(layer "F.Cu")
		(net "OCP_V3_2_AUX_PWR_EN")
	)
	(segment
		(start 61.50483 -19.80057)
		(end 61.50483 -19.268948)
		(width 0.10668)
		(layer "F.Cu")
		(net "OCP_V3_2_AUX_PWR_EN")
	)
	(segment
		(start 52.877466 -24.909018)
		(end 59.737244 -24.909018)
		(width 0.10668)
		(layer "F.Cu")
		(net "OCP_V3_2_AUX_PWR_EN")
	)
	(via
		(at 59.737244 -24.909018)
		(size 0.508)
		(drill 0.254)
		(layers "F.Cu" "B.Cu")
		(net "OCP_V3_2_AUX_PWR_EN")
	)
	(via
		(at 73.152 -53.086)
		(size 0.508)
		(drill 0.254)
		(layers "F.Cu" "B.Cu")
		(net "OCP_V3_2_AUX_PWR_EN")
	)
	(segment
		(start 74.08926 -52.14874)
		(end 73.152 -53.086)
		(width 0.11684)
		(layer "In6.Cu")
		(net "OCP_V3_2_AUX_PWR_EN")
	)
	(segment
		(start 59.737244 -24.909018)
		(end 58.76036 -24.909018)
		(width 0.11684)
		(layer "In6.Cu")
		(net "OCP_V3_2_AUX_PWR_EN")
	)
	(segment
		(start 74.08926 -44.973748)
		(end 74.08926 -52.14874)
		(width 0.11684)
		(layer "In6.Cu")
		(net "OCP_V3_2_AUX_PWR_EN")
	)
	(segment
		(start 72.539098 -43.423586)
		(end 74.08926 -44.973748)
		(width 0.11684)
		(layer "In6.Cu")
		(net "OCP_V3_2_AUX_PWR_EN")
	)
	(segment
		(start 56.672734 -43.423586)
		(end 72.539098 -43.423586)
		(width 0.11684)
		(layer "In6.Cu")
		(net "OCP_V3_2_AUX_PWR_EN")
	)
	(segment
		(start 55.811166 -29.96946)
		(end 50.856896 -34.92373)
		(width 0.11684)
		(layer "In6.Cu")
		(net "OCP_V3_2_AUX_PWR_EN")
	)
	(segment
		(start 55.811166 -27.858212)
		(end 55.811166 -29.96946)
		(width 0.11684)
		(layer "In6.Cu")
		(net "OCP_V3_2_AUX_PWR_EN")
	)
	(segment
		(start 50.856896 -37.607748)
		(end 56.672734 -43.423586)
		(width 0.11684)
		(layer "In6.Cu")
		(net "OCP_V3_2_AUX_PWR_EN")
	)
	(segment
		(start 58.76036 -24.909018)
		(end 55.811166 -27.858212)
		(width 0.11684)
		(layer "In6.Cu")
		(net "OCP_V3_2_AUX_PWR_EN")
	)
	(segment
		(start 50.856896 -34.92373)
		(end 50.856896 -37.607748)
		(width 0.11684)
		(layer "In6.Cu")
		(net "OCP_V3_2_AUX_PWR_EN")
	)
	(segment
		(start 60.466986 -8.320024)
		(end 60.466986 -6.66369)
		(width 0.10668)
		(layer "F.Cu")
		(net "OCP_V3_2_PRSNTA_R_N")
	)
	(via
		(at 60.466986 -6.66369)
		(size 0.508)
		(drill 0.254)
		(layers "F.Cu" "B.Cu")
		(net "OCP_V3_2_PRSNTA_R_N")
	)
	(segment
		(start 60.468002 -6.664706)
		(end 60.466986 -6.66369)
		(width 0.10668)
		(layer "B.Cu")
		(net "OCP_V3_2_PRSNTA_R_N")
	)
	(segment
		(start 60.468002 -7.919212)
		(end 60.468002 -6.664706)
		(width 0.10668)
		(layer "B.Cu")
		(net "OCP_V3_2_PRSNTA_R_N")
	)
	(segment
		(start 220.321378 -97.08642)
		(end 220.48978 -97.08642)
		(width 0.10668)
		(layer "F.Cu")
		(net "OCP_V3_1_P3V3_PWRGD")
	)
	(segment
		(start 220.26626 -99.194874)
		(end 220.4212 -99.349814)
		(width 0.10668)
		(layer "F.Cu")
		(net "OCP_V3_1_P3V3_PWRGD")
	)
	(segment
		(start 412.75 -98.02495)
		(end 412.75 -97.383346)
		(width 0.10668)
		(layer "F.Cu")
		(net "OCP_V3_1_P3V3_PWRGD")
	)
	(segment
		(start 220.48978 -97.08642)
		(end 220.726 -97.32264)
		(width 0.10668)
		(layer "F.Cu")
		(net "OCP_V3_1_P3V3_PWRGD")
	)
	(segment
		(start 169.620692 -92.268294)
		(end 169.681398 -92.329)
		(width 0.10668)
		(layer "F.Cu")
		(net "OCP_V3_1_P3V3_PWRGD")
	)
	(segment
		(start 220.4212 -101.75748)
		(end 220.88602 -102.2223)
		(width 0.10668)
		(layer "F.Cu")
		(net "OCP_V3_1_P3V3_PWRGD")
	)
	(segment
		(start 220.726 -97.32264)
		(end 220.726 -98.14814)
		(width 0.10668)
		(layer "F.Cu")
		(net "OCP_V3_1_P3V3_PWRGD")
	)
	(segment
		(start 429.876966 -102.61219)
		(end 429.876966 -101.97719)
		(width 0.10668)
		(layer "F.Cu")
		(net "OCP_V3_1_P3V3_PWRGD")
	)
	(segment
		(start 220.36405 -98.51009)
		(end 220.26626 -98.51009)
		(width 0.10668)
		(layer "F.Cu")
		(net "OCP_V3_1_P3V3_PWRGD")
	)
	(segment
		(start 169.681398 -92.329)
		(end 172.930312 -92.329)
		(width 0.10668)
		(layer "F.Cu")
		(net "OCP_V3_1_P3V3_PWRGD")
	)
	(segment
		(start 220.88602 -102.2223)
		(end 221.199456 -102.2223)
		(width 0.10668)
		(layer "F.Cu")
		(net "OCP_V3_1_P3V3_PWRGD")
	)
	(segment
		(start 220.4212 -99.349814)
		(end 220.4212 -101.75748)
		(width 0.10668)
		(layer "F.Cu")
		(net "OCP_V3_1_P3V3_PWRGD")
	)
	(segment
		(start 429.876966 -101.97719)
		(end 428.880016 -101.97719)
		(width 0.10668)
		(layer "F.Cu")
		(net "OCP_V3_1_P3V3_PWRGD")
	)
	(segment
		(start 218.534488 -95.29953)
		(end 220.321378 -97.08642)
		(width 0.10668)
		(layer "F.Cu")
		(net "OCP_V3_1_P3V3_PWRGD")
	)
	(segment
		(start 220.726 -98.14814)
		(end 220.36405 -98.51009)
		(width 0.10668)
		(layer "F.Cu")
		(net "OCP_V3_1_P3V3_PWRGD")
	)
	(segment
		(start 220.26626 -98.51009)
		(end 220.26626 -99.194874)
		(width 0.10668)
		(layer "F.Cu")
		(net "OCP_V3_1_P3V3_PWRGD")
	)
	(via
		(at 172.930312 -92.329)
		(size 0.508)
		(drill 0.254)
		(layers "F.Cu" "B.Cu")
		(net "OCP_V3_1_P3V3_PWRGD")
	)
	(via
		(at 429.876966 -102.61219)
		(size 0.508)
		(drill 0.254)
		(layers "F.Cu" "B.Cu")
		(net "OCP_V3_1_P3V3_PWRGD")
	)
	(via
		(at 412.75 -97.383346)
		(size 0.508)
		(drill 0.254)
		(layers "F.Cu" "B.Cu")
		(net "OCP_V3_1_P3V3_PWRGD")
	)
	(via
		(at 218.534488 -95.29953)
		(size 0.508)
		(drill 0.254)
		(layers "F.Cu" "B.Cu")
		(net "OCP_V3_1_P3V3_PWRGD")
	)
	(segment
		(start 281.104086 -94.445328)
		(end 315.954918 -94.445328)
		(width 0.11684)
		(layer "In6.Cu")
		(net "OCP_V3_1_P3V3_PWRGD")
	)
	(segment
		(start 232.02519 -94.306136)
		(end 233.371898 -95.652844)
		(width 0.11684)
		(layer "In6.Cu")
		(net "OCP_V3_1_P3V3_PWRGD")
	)
	(segment
		(start 256.109978 -95.652844)
		(end 259.612892 -92.14993)
		(width 0.11684)
		(layer "In6.Cu")
		(net "OCP_V3_1_P3V3_PWRGD")
	)
	(segment
		(start 411.22219 -95.855536)
		(end 412.75 -97.383346)
		(width 0.11684)
		(layer "In6.Cu")
		(net "OCP_V3_1_P3V3_PWRGD")
	)
	(segment
		(start 315.954918 -94.445328)
		(end 317.365126 -95.855536)
		(width 0.11684)
		(layer "In6.Cu")
		(net "OCP_V3_1_P3V3_PWRGD")
	)
	(segment
		(start 259.612892 -92.14993)
		(end 263.032748 -92.14993)
		(width 0.11684)
		(layer "In6.Cu")
		(net "OCP_V3_1_P3V3_PWRGD")
	)
	(segment
		(start 273.699224 -91.687904)
		(end 274.16125 -92.14993)
		(width 0.11684)
		(layer "In6.Cu")
		(net "OCP_V3_1_P3V3_PWRGD")
	)
	(segment
		(start 206.209646 -93.65869)
		(end 201.428858 -88.877902)
		(width 0.11684)
		(layer "In6.Cu")
		(net "OCP_V3_1_P3V3_PWRGD")
	)
	(segment
		(start 274.16125 -92.14993)
		(end 278.808688 -92.14993)
		(width 0.11684)
		(layer "In6.Cu")
		(net "OCP_V3_1_P3V3_PWRGD")
	)
	(segment
		(start 263.494774 -91.687904)
		(end 273.699224 -91.687904)
		(width 0.11684)
		(layer "In6.Cu")
		(net "OCP_V3_1_P3V3_PWRGD")
	)
	(segment
		(start 201.428858 -88.877902)
		(end 176.38141 -88.877902)
		(width 0.11684)
		(layer "In6.Cu")
		(net "OCP_V3_1_P3V3_PWRGD")
	)
	(segment
		(start 218.534488 -95.29953)
		(end 216.893648 -93.65869)
		(width 0.11684)
		(layer "In6.Cu")
		(net "OCP_V3_1_P3V3_PWRGD")
	)
	(segment
		(start 423.120312 -95.855536)
		(end 429.876966 -102.61219)
		(width 0.11684)
		(layer "In6.Cu")
		(net "OCP_V3_1_P3V3_PWRGD")
	)
	(segment
		(start 216.893648 -93.65869)
		(end 206.209646 -93.65869)
		(width 0.11684)
		(layer "In6.Cu")
		(net "OCP_V3_1_P3V3_PWRGD")
	)
	(segment
		(start 317.365126 -95.855536)
		(end 411.22219 -95.855536)
		(width 0.11684)
		(layer "In6.Cu")
		(net "OCP_V3_1_P3V3_PWRGD")
	)
	(segment
		(start 412.75 -97.383346)
		(end 414.27781 -95.855536)
		(width 0.11684)
		(layer "In6.Cu")
		(net "OCP_V3_1_P3V3_PWRGD")
	)
	(segment
		(start 219.527882 -94.306136)
		(end 232.02519 -94.306136)
		(width 0.11684)
		(layer "In6.Cu")
		(net "OCP_V3_1_P3V3_PWRGD")
	)
	(segment
		(start 414.27781 -95.855536)
		(end 423.120312 -95.855536)
		(width 0.11684)
		(layer "In6.Cu")
		(net "OCP_V3_1_P3V3_PWRGD")
	)
	(segment
		(start 263.032748 -92.14993)
		(end 263.494774 -91.687904)
		(width 0.11684)
		(layer "In6.Cu")
		(net "OCP_V3_1_P3V3_PWRGD")
	)
	(segment
		(start 233.371898 -95.652844)
		(end 256.109978 -95.652844)
		(width 0.11684)
		(layer "In6.Cu")
		(net "OCP_V3_1_P3V3_PWRGD")
	)
	(segment
		(start 176.38141 -88.877902)
		(end 172.930312 -92.329)
		(width 0.11684)
		(layer "In6.Cu")
		(net "OCP_V3_1_P3V3_PWRGD")
	)
	(segment
		(start 278.808688 -92.14993)
		(end 281.104086 -94.445328)
		(width 0.11684)
		(layer "In6.Cu")
		(net "OCP_V3_1_P3V3_PWRGD")
	)
	(segment
		(start 218.534488 -95.29953)
		(end 219.527882 -94.306136)
		(width 0.11684)
		(layer "In6.Cu")
		(net "OCP_V3_1_P3V3_PWRGD")
	)
	(segment
		(start 464.569556 -37.549836)
		(end 465.116164 -38.096444)
		(width 0.10668)
		(layer "F.Cu")
		(net "OCP_SFF_WAKE_BUFF_R_N")
	)
	(segment
		(start 162.218116 -33.262824)
		(end 163.242244 -34.286952)
		(width 0.10668)
		(layer "F.Cu")
		(net "OCP_SFF_WAKE_BUFF_R_N")
	)
	(segment
		(start 463.58937 -37.549836)
		(end 464.569556 -37.549836)
		(width 0.10668)
		(layer "F.Cu")
		(net "OCP_SFF_WAKE_BUFF_R_N")
	)
	(segment
		(start 163.242244 -34.286952)
		(end 164.021008 -34.286952)
		(width 0.10668)
		(layer "F.Cu")
		(net "OCP_SFF_WAKE_BUFF_R_N")
	)
	(segment
		(start 162.218116 -32.523938)
		(end 162.218116 -33.262824)
		(width 0.10668)
		(layer "F.Cu")
		(net "OCP_SFF_WAKE_BUFF_R_N")
	)
	(via
		(at 164.021008 -34.286952)
		(size 0.508)
		(drill 0.254)
		(layers "F.Cu" "B.Cu")
		(net "OCP_SFF_WAKE_BUFF_R_N")
	)
	(via
		(at 465.116164 -38.096444)
		(size 0.508)
		(drill 0.254)
		(layers "F.Cu" "B.Cu")
		(net "OCP_SFF_WAKE_BUFF_R_N")
	)
	(segment
		(start 420.887652 -12.822936)
		(end 420.015924 -13.694664)
		(width 0.11684)
		(layer "In15.Cu")
		(net "OCP_SFF_WAKE_BUFF_R_N")
	)
	(segment
		(start 271.59458 -58.997088)
		(end 258.962398 -58.997088)
		(width 0.11684)
		(layer "In15.Cu")
		(net "OCP_SFF_WAKE_BUFF_R_N")
	)
	(segment
		(start 245.206012 -57.813702)
		(end 224.554796 -57.813702)
		(width 0.11684)
		(layer "In15.Cu")
		(net "OCP_SFF_WAKE_BUFF_R_N")
	)
	(segment
		(start 190.02756 -39.636192)
		(end 189.583314 -40.080438)
		(width 0.11684)
		(layer "In15.Cu")
		(net "OCP_SFF_WAKE_BUFF_R_N")
	)
	(segment
		(start 424.83151 -2.80289)
		(end 420.887652 -6.746748)
		(width 0.11684)
		(layer "In15.Cu")
		(net "OCP_SFF_WAKE_BUFF_R_N")
	)
	(segment
		(start 377.438412 -13.694664)
		(end 374.519698 -16.613378)
		(width 0.11684)
		(layer "In15.Cu")
		(net "OCP_SFF_WAKE_BUFF_R_N")
	)
	(segment
		(start 355.762306 -13.694664)
		(end 326.909938 -13.694664)
		(width 0.11684)
		(layer "In15.Cu")
		(net "OCP_SFF_WAKE_BUFF_R_N")
	)
	(segment
		(start 198.120762 -41.214802)
		(end 196.542152 -39.636192)
		(width 0.11684)
		(layer "In15.Cu")
		(net "OCP_SFF_WAKE_BUFF_R_N")
	)
	(segment
		(start 452.503032 -4.811522)
		(end 450.590412 -2.898902)
		(width 0.11684)
		(layer "In15.Cu")
		(net "OCP_SFF_WAKE_BUFF_R_N")
	)
	(segment
		(start 318.732154 -26.810208)
		(end 303.78146 -26.810208)
		(width 0.11684)
		(layer "In15.Cu")
		(net "OCP_SFF_WAKE_BUFF_R_N")
	)
	(segment
		(start 420.015924 -13.694664)
		(end 377.438412 -13.694664)
		(width 0.11684)
		(layer "In15.Cu")
		(net "OCP_SFF_WAKE_BUFF_R_N")
	)
	(segment
		(start 321.473576 -19.131026)
		(end 321.473576 -24.068786)
		(width 0.11684)
		(layer "In15.Cu")
		(net "OCP_SFF_WAKE_BUFF_R_N")
	)
	(segment
		(start 446.518284 -2.898902)
		(end 444.628016 -4.78917)
		(width 0.11684)
		(layer "In15.Cu")
		(net "OCP_SFF_WAKE_BUFF_R_N")
	)
	(segment
		(start 454.788016 -9.02462)
		(end 452.503032 -6.739636)
		(width 0.11684)
		(layer "In15.Cu")
		(net "OCP_SFF_WAKE_BUFF_R_N")
	)
	(segment
		(start 172.52823 -34.286952)
		(end 164.021008 -34.286952)
		(width 0.11684)
		(layer "In15.Cu")
		(net "OCP_SFF_WAKE_BUFF_R_N")
	)
	(segment
		(start 218.02598 -48.30826)
		(end 215.154002 -45.436282)
		(width 0.11684)
		(layer "In15.Cu")
		(net "OCP_SFF_WAKE_BUFF_R_N")
	)
	(segment
		(start 321.473576 -24.068786)
		(end 318.732154 -26.810208)
		(width 0.11684)
		(layer "In15.Cu")
		(net "OCP_SFF_WAKE_BUFF_R_N")
	)
	(segment
		(start 247.540526 -60.148216)
		(end 245.206012 -57.813702)
		(width 0.11684)
		(layer "In15.Cu")
		(net "OCP_SFF_WAKE_BUFF_R_N")
	)
	(segment
		(start 258.962398 -58.997088)
		(end 257.81127 -60.148216)
		(width 0.11684)
		(layer "In15.Cu")
		(net "OCP_SFF_WAKE_BUFF_R_N")
	)
	(segment
		(start 215.154002 -45.436282)
		(end 208.23174 -45.436282)
		(width 0.11684)
		(layer "In15.Cu")
		(net "OCP_SFF_WAKE_BUFF_R_N")
	)
	(segment
		(start 224.554796 -57.813702)
		(end 218.02598 -51.284886)
		(width 0.11684)
		(layer "In15.Cu")
		(net "OCP_SFF_WAKE_BUFF_R_N")
	)
	(segment
		(start 464.177126 -37.521642)
		(end 462.736438 -37.521642)
		(width 0.11684)
		(layer "In15.Cu")
		(net "OCP_SFF_WAKE_BUFF_R_N")
	)
	(segment
		(start 465.116164 -38.096444)
		(end 464.751928 -38.096444)
		(width 0.11684)
		(layer "In15.Cu")
		(net "OCP_SFF_WAKE_BUFF_R_N")
	)
	(segment
		(start 456.886056 -26.16962)
		(end 456.886056 -13.344144)
		(width 0.11684)
		(layer "In15.Cu")
		(net "OCP_SFF_WAKE_BUFF_R_N")
	)
	(segment
		(start 420.887652 -6.746748)
		(end 420.887652 -12.822936)
		(width 0.11684)
		(layer "In15.Cu")
		(net "OCP_SFF_WAKE_BUFF_R_N")
	)
	(segment
		(start 437.786272 -2.80289)
		(end 424.83151 -2.80289)
		(width 0.11684)
		(layer "In15.Cu")
		(net "OCP_SFF_WAKE_BUFF_R_N")
	)
	(segment
		(start 196.542152 -39.636192)
		(end 190.02756 -39.636192)
		(width 0.11684)
		(layer "In15.Cu")
		(net "OCP_SFF_WAKE_BUFF_R_N")
	)
	(segment
		(start 204.01026 -41.214802)
		(end 198.120762 -41.214802)
		(width 0.11684)
		(layer "In15.Cu")
		(net "OCP_SFF_WAKE_BUFF_R_N")
	)
	(segment
		(start 439.772552 -4.78917)
		(end 437.786272 -2.80289)
		(width 0.11684)
		(layer "In15.Cu")
		(net "OCP_SFF_WAKE_BUFF_R_N")
	)
	(segment
		(start 461.157828 -30.441392)
		(end 456.886056 -26.16962)
		(width 0.11684)
		(layer "In15.Cu")
		(net "OCP_SFF_WAKE_BUFF_R_N")
	)
	(segment
		(start 303.78146 -26.810208)
		(end 271.59458 -58.997088)
		(width 0.11684)
		(layer "In15.Cu")
		(net "OCP_SFF_WAKE_BUFF_R_N")
	)
	(segment
		(start 450.590412 -2.898902)
		(end 446.518284 -2.898902)
		(width 0.11684)
		(layer "In15.Cu")
		(net "OCP_SFF_WAKE_BUFF_R_N")
	)
	(segment
		(start 218.02598 -51.284886)
		(end 218.02598 -48.30826)
		(width 0.11684)
		(layer "In15.Cu")
		(net "OCP_SFF_WAKE_BUFF_R_N")
	)
	(segment
		(start 454.788016 -11.246104)
		(end 454.788016 -9.02462)
		(width 0.11684)
		(layer "In15.Cu")
		(net "OCP_SFF_WAKE_BUFF_R_N")
	)
	(segment
		(start 326.909938 -13.694664)
		(end 321.473576 -19.131026)
		(width 0.11684)
		(layer "In15.Cu")
		(net "OCP_SFF_WAKE_BUFF_R_N")
	)
	(segment
		(start 358.68102 -16.613378)
		(end 355.762306 -13.694664)
		(width 0.11684)
		(layer "In15.Cu")
		(net "OCP_SFF_WAKE_BUFF_R_N")
	)
	(segment
		(start 185.95721 -40.080438)
		(end 185.12663 -39.249858)
		(width 0.11684)
		(layer "In15.Cu")
		(net "OCP_SFF_WAKE_BUFF_R_N")
	)
	(segment
		(start 461.157828 -35.943032)
		(end 461.157828 -30.441392)
		(width 0.11684)
		(layer "In15.Cu")
		(net "OCP_SFF_WAKE_BUFF_R_N")
	)
	(segment
		(start 452.503032 -6.739636)
		(end 452.503032 -4.811522)
		(width 0.11684)
		(layer "In15.Cu")
		(net "OCP_SFF_WAKE_BUFF_R_N")
	)
	(segment
		(start 374.519698 -16.613378)
		(end 358.68102 -16.613378)
		(width 0.11684)
		(layer "In15.Cu")
		(net "OCP_SFF_WAKE_BUFF_R_N")
	)
	(segment
		(start 456.886056 -13.344144)
		(end 454.788016 -11.246104)
		(width 0.11684)
		(layer "In15.Cu")
		(net "OCP_SFF_WAKE_BUFF_R_N")
	)
	(segment
		(start 189.583314 -40.080438)
		(end 185.95721 -40.080438)
		(width 0.11684)
		(layer "In15.Cu")
		(net "OCP_SFF_WAKE_BUFF_R_N")
	)
	(segment
		(start 257.81127 -60.148216)
		(end 247.540526 -60.148216)
		(width 0.11684)
		(layer "In15.Cu")
		(net "OCP_SFF_WAKE_BUFF_R_N")
	)
	(segment
		(start 185.12663 -39.249858)
		(end 177.491136 -39.249858)
		(width 0.11684)
		(layer "In15.Cu")
		(net "OCP_SFF_WAKE_BUFF_R_N")
	)
	(segment
		(start 462.736438 -37.521642)
		(end 461.157828 -35.943032)
		(width 0.11684)
		(layer "In15.Cu")
		(net "OCP_SFF_WAKE_BUFF_R_N")
	)
	(segment
		(start 444.628016 -4.78917)
		(end 439.772552 -4.78917)
		(width 0.11684)
		(layer "In15.Cu")
		(net "OCP_SFF_WAKE_BUFF_R_N")
	)
	(segment
		(start 464.751928 -38.096444)
		(end 464.177126 -37.521642)
		(width 0.11684)
		(layer "In15.Cu")
		(net "OCP_SFF_WAKE_BUFF_R_N")
	)
	(segment
		(start 177.491136 -39.249858)
		(end 172.52823 -34.286952)
		(width 0.11684)
		(layer "In15.Cu")
		(net "OCP_SFF_WAKE_BUFF_R_N")
	)
	(segment
		(start 208.23174 -45.436282)
		(end 204.01026 -41.214802)
		(width 0.11684)
		(layer "In15.Cu")
		(net "OCP_SFF_WAKE_BUFF_R_N")
	)
	(segment
		(start 459.81112 -37.265864)
		(end 460.83601 -37.265864)
		(width 0.10668)
		(layer "F.Cu")
		(net "OCP_SFF_WAKE_BUFF_N")
	)
	(segment
		(start 462.78927 -37.549836)
		(end 462.251298 -37.011864)
		(width 0.10668)
		(layer "F.Cu")
		(net "OCP_SFF_WAKE_BUFF_N")
	)
	(segment
		(start 462.78927 -38.565836)
		(end 462.78927 -37.549836)
		(width 0.10668)
		(layer "F.Cu")
		(net "OCP_SFF_WAKE_BUFF_N")
	)
	(segment
		(start 460.83601 -37.265864)
		(end 461.09001 -37.011864)
		(width 0.10668)
		(layer "F.Cu")
		(net "OCP_SFF_WAKE_BUFF_N")
	)
	(segment
		(start 462.251298 -37.011864)
		(end 461.09001 -37.011864)
		(width 0.10668)
		(layer "F.Cu")
		(net "OCP_SFF_WAKE_BUFF_N")
	)
	(via
		(at 461.09001 -37.011864)
		(size 0.762)
		(drill 0.381)
		(layers "F.Cu" "B.Cu")
		(net "OCP_SFF_WAKE_BUFF_N")
	)
	(segment
		(start 390.549384 -6.46303)
		(end 390.153144 -6.85927)
		(width 0.12954)
		(layer "F.Cu")
		(net "USB2_P11_DP")
	)
	(segment
		(start 387.87197 -15.511526)
		(end 387.87197 -17.327626)
		(width 0.12954)
		(layer "F.Cu")
		(net "USB2_P11_DP")
	)
	(segment
		(start 387.87197 -14.358366)
		(end 387.87197 -14.744446)
		(width 0.12954)
		(layer "F.Cu")
		(net "USB2_P11_DP")
	)
	(segment
		(start 389.064754 -12.012422)
		(end 389.064754 -12.281916)
		(width 0.12954)
		(layer "F.Cu")
		(net "USB2_P11_DP")
	)
	(segment
		(start 389.33755 -7.674864)
		(end 389.33755 -8.060944)
		(width 0.12954)
		(layer "F.Cu")
		(net "USB2_P11_DP")
	)
	(segment
		(start 390.153144 -6.85927)
		(end 390.153144 -7.128764)
		(width 0.12954)
		(layer "F.Cu")
		(net "USB2_P11_DP")
	)
	(segment
		(start 388.06247 -14.167866)
		(end 387.87197 -14.358366)
		(width 0.12954)
		(layer "F.Cu")
		(net "USB2_P11_DP")
	)
	(segment
		(start 389.33755 -9.981184)
		(end 389.33755 -10.586466)
		(width 0.12954)
		(layer "F.Cu")
		(net "USB2_P11_DP")
	)
	(segment
		(start 387.87197 -13.205206)
		(end 387.87197 -13.591286)
		(width 0.12954)
		(layer "F.Cu")
		(net "USB2_P11_DP")
	)
	(segment
		(start 389.52805 -8.637524)
		(end 389.33755 -8.828024)
		(width 0.12954)
		(layer "F.Cu")
		(net "USB2_P11_DP")
	)
	(segment
		(start 389.52805 -11.163046)
		(end 389.33755 -11.353546)
		(width 0.12954)
		(layer "F.Cu")
		(net "USB2_P11_DP")
	)
	(segment
		(start 387.87197 -14.744446)
		(end 388.06247 -14.934946)
		(width 0.12954)
		(layer "F.Cu")
		(net "USB2_P11_DP")
	)
	(segment
		(start 389.33755 -8.828024)
		(end 389.33755 -9.214104)
		(width 0.12954)
		(layer "F.Cu")
		(net "USB2_P11_DP")
	)
	(segment
		(start 389.52805 -8.251444)
		(end 389.52805 -8.637524)
		(width 0.12954)
		(layer "F.Cu")
		(net "USB2_P11_DP")
	)
	(segment
		(start 388.06247 -13.781786)
		(end 388.06247 -14.167866)
		(width 0.12954)
		(layer "F.Cu")
		(net "USB2_P11_DP")
	)
	(segment
		(start 389.064754 -12.281916)
		(end 388.79145 -12.55522)
		(width 0.12954)
		(layer "F.Cu")
		(net "USB2_P11_DP")
	)
	(segment
		(start 390.164066 -22.039834)
		(end 390.513316 -22.389084)
		(width 0.12954)
		(layer "F.Cu")
		(net "USB2_P11_DP")
	)
	(segment
		(start 388.79145 -12.55522)
		(end 388.521956 -12.55522)
		(width 0.12954)
		(layer "F.Cu")
		(net "USB2_P11_DP")
	)
	(segment
		(start 391.9855 -7.57047)
		(end 391.9855 -6.916674)
		(width 0.12954)
		(layer "F.Cu")
		(net "USB2_P11_DP")
	)
	(segment
		(start 389.33755 -9.214104)
		(end 389.52805 -9.404604)
		(width 0.12954)
		(layer "F.Cu")
		(net "USB2_P11_DP")
	)
	(segment
		(start 390.153144 -7.128764)
		(end 389.87984 -7.402068)
		(width 0.12954)
		(layer "F.Cu")
		(net "USB2_P11_DP")
	)
	(segment
		(start 389.33755 -10.586466)
		(end 389.52805 -10.776966)
		(width 0.12954)
		(layer "F.Cu")
		(net "USB2_P11_DP")
	)
	(segment
		(start 389.87984 -7.402068)
		(end 389.610346 -7.402068)
		(width 0.12954)
		(layer "F.Cu")
		(net "USB2_P11_DP")
	)
	(segment
		(start 389.33755 -8.060944)
		(end 389.52805 -8.251444)
		(width 0.12954)
		(layer "F.Cu")
		(net "USB2_P11_DP")
	)
	(segment
		(start 389.52805 -9.790684)
		(end 389.33755 -9.981184)
		(width 0.12954)
		(layer "F.Cu")
		(net "USB2_P11_DP")
	)
	(segment
		(start 389.33755 -11.739626)
		(end 389.064754 -12.012422)
		(width 0.12954)
		(layer "F.Cu")
		(net "USB2_P11_DP")
	)
	(segment
		(start 391.846816 -8.320024)
		(end 391.846816 -7.709154)
		(width 0.12954)
		(layer "F.Cu")
		(net "USB2_P11_DP")
	)
	(segment
		(start 390.164066 -19.619722)
		(end 390.164066 -22.039834)
		(width 0.12954)
		(layer "F.Cu")
		(net "USB2_P11_DP")
	)
	(segment
		(start 391.531856 -6.46303)
		(end 390.549384 -6.46303)
		(width 0.12954)
		(layer "F.Cu")
		(net "USB2_P11_DP")
	)
	(segment
		(start 388.521956 -12.55522)
		(end 387.87197 -13.205206)
		(width 0.12954)
		(layer "F.Cu")
		(net "USB2_P11_DP")
	)
	(segment
		(start 389.610346 -7.402068)
		(end 389.33755 -7.674864)
		(width 0.12954)
		(layer "F.Cu")
		(net "USB2_P11_DP")
	)
	(segment
		(start 389.52805 -9.404604)
		(end 389.52805 -9.790684)
		(width 0.12954)
		(layer "F.Cu")
		(net "USB2_P11_DP")
	)
	(segment
		(start 387.87197 -17.327626)
		(end 390.164066 -19.619722)
		(width 0.12954)
		(layer "F.Cu")
		(net "USB2_P11_DP")
	)
	(segment
		(start 387.87197 -13.591286)
		(end 388.06247 -13.781786)
		(width 0.12954)
		(layer "F.Cu")
		(net "USB2_P11_DP")
	)
	(segment
		(start 391.9855 -6.916674)
		(end 391.531856 -6.46303)
		(width 0.12954)
		(layer "F.Cu")
		(net "USB2_P11_DP")
	)
	(segment
		(start 388.06247 -14.934946)
		(end 388.06247 -15.321026)
		(width 0.12954)
		(layer "F.Cu")
		(net "USB2_P11_DP")
	)
	(segment
		(start 388.06247 -15.321026)
		(end 387.87197 -15.511526)
		(width 0.12954)
		(layer "F.Cu")
		(net "USB2_P11_DP")
	)
	(segment
		(start 391.846816 -7.709154)
		(end 391.9855 -7.57047)
		(width 0.12954)
		(layer "F.Cu")
		(net "USB2_P11_DP")
	)
	(segment
		(start 389.52805 -10.776966)
		(end 389.52805 -11.163046)
		(width 0.12954)
		(layer "F.Cu")
		(net "USB2_P11_DP")
	)
	(segment
		(start 389.33755 -11.353546)
		(end 389.33755 -11.739626)
		(width 0.12954)
		(layer "F.Cu")
		(net "USB2_P11_DP")
	)
	(segment
		(start 387.54939 -17.461484)
		(end 387.54939 -13.071348)
		(width 0.12954)
		(layer "F.Cu")
		(net "USB2_P11_DN")
	)
	(segment
		(start 390.415526 -6.14045)
		(end 391.665714 -6.14045)
		(width 0.12954)
		(layer "F.Cu")
		(net "USB2_P11_DN")
	)
	(segment
		(start 389.01497 -7.541006)
		(end 390.415526 -6.14045)
		(width 0.12954)
		(layer "F.Cu")
		(net "USB2_P11_DN")
	)
	(segment
		(start 392.446764 -7.709154)
		(end 392.446764 -8.320024)
		(width 0.12954)
		(layer "F.Cu")
		(net "USB2_P11_DN")
	)
	(segment
		(start 387.54939 -13.071348)
		(end 389.01497 -11.605768)
		(width 0.12954)
		(layer "F.Cu")
		(net "USB2_P11_DN")
	)
	(segment
		(start 389.841486 -22.044914)
		(end 389.841486 -19.75358)
		(width 0.12954)
		(layer "F.Cu")
		(net "USB2_P11_DN")
	)
	(segment
		(start 389.497316 -22.389084)
		(end 389.841486 -22.044914)
		(width 0.12954)
		(layer "F.Cu")
		(net "USB2_P11_DN")
	)
	(segment
		(start 389.01497 -11.605768)
		(end 389.01497 -7.541006)
		(width 0.12954)
		(layer "F.Cu")
		(net "USB2_P11_DN")
	)
	(segment
		(start 389.841486 -19.75358)
		(end 387.54939 -17.461484)
		(width 0.12954)
		(layer "F.Cu")
		(net "USB2_P11_DN")
	)
	(segment
		(start 392.30808 -6.782816)
		(end 392.30808 -7.57047)
		(width 0.12954)
		(layer "F.Cu")
		(net "USB2_P11_DN")
	)
	(segment
		(start 391.665714 -6.14045)
		(end 392.30808 -6.782816)
		(width 0.12954)
		(layer "F.Cu")
		(net "USB2_P11_DN")
	)
	(segment
		(start 392.30808 -7.57047)
		(end 392.446764 -7.709154)
		(width 0.12954)
		(layer "F.Cu")
		(net "USB2_P11_DN")
	)
	(segment
		(start 152.198832 -97.705672)
		(end 151.944832 -97.451672)
		(width 0.10668)
		(layer "F.Cu")
		(net "OCP_SFF_RBT_ARB_OUT")
	)
	(segment
		(start 152.884632 -97.705672)
		(end 152.198832 -97.705672)
		(width 0.10668)
		(layer "F.Cu")
		(net "OCP_SFF_RBT_ARB_OUT")
	)
	(via
		(at 209.051652 -70.180454)
		(size 0.508)
		(drill 0.254)
		(layers "F.Cu" "B.Cu")
		(net "OCP_SFF_RBT_ARB_OUT")
	)
	(via
		(at 151.944832 -97.451672)
		(size 0.508)
		(drill 0.254)
		(layers "F.Cu" "B.Cu")
		(net "OCP_SFF_RBT_ARB_OUT")
	)
	(via
		(at 193.157348 -75.098148)
		(size 0.508)
		(drill 0.254)
		(layers "F.Cu" "B.Cu")
		(net "OCP_SFF_RBT_ARB_OUT")
	)
	(segment
		(start 191.271144 -76.361036)
		(end 192.534032 -75.098148)
		(width 0.10668)
		(layer "B.Cu")
		(net "OCP_SFF_RBT_ARB_OUT")
	)
	(segment
		(start 192.534032 -75.098148)
		(end 193.157348 -75.098148)
		(width 0.10668)
		(layer "B.Cu")
		(net "OCP_SFF_RBT_ARB_OUT")
	)
	(segment
		(start 191.271144 -76.87818)
		(end 191.271144 -76.361036)
		(width 0.10668)
		(layer "B.Cu")
		(net "OCP_SFF_RBT_ARB_OUT")
	)
	(segment
		(start 207.91805 -70.180454)
		(end 209.051652 -70.180454)
		(width 0.10668)
		(layer "B.Cu")
		(net "OCP_SFF_RBT_ARB_OUT")
	)
	(segment
		(start 175.215296 -82.226404)
		(end 178.01082 -82.226404)
		(width 0.11684)
		(layer "In6.Cu")
		(net "OCP_SFF_RBT_ARB_OUT")
	)
	(segment
		(start 167.169846 -82.226658)
		(end 175.215042 -82.226658)
		(width 0.11684)
		(layer "In6.Cu")
		(net "OCP_SFF_RBT_ARB_OUT")
	)
	(segment
		(start 192.584578 -75.098148)
		(end 193.157348 -75.098148)
		(width 0.11684)
		(layer "In6.Cu")
		(net "OCP_SFF_RBT_ARB_OUT")
	)
	(segment
		(start 184.57545 -82.226658)
		(end 190.858648 -75.94346)
		(width 0.11684)
		(layer "In6.Cu")
		(net "OCP_SFF_RBT_ARB_OUT")
	)
	(segment
		(start 191.739266 -75.94346)
		(end 192.584578 -75.098148)
		(width 0.11684)
		(layer "In6.Cu")
		(net "OCP_SFF_RBT_ARB_OUT")
	)
	(segment
		(start 178.01082 -82.226404)
		(end 178.011074 -82.226658)
		(width 0.11684)
		(layer "In6.Cu")
		(net "OCP_SFF_RBT_ARB_OUT")
	)
	(segment
		(start 190.858648 -75.94346)
		(end 191.739266 -75.94346)
		(width 0.11684)
		(layer "In6.Cu")
		(net "OCP_SFF_RBT_ARB_OUT")
	)
	(segment
		(start 178.011074 -82.226658)
		(end 184.57545 -82.226658)
		(width 0.11684)
		(layer "In6.Cu")
		(net "OCP_SFF_RBT_ARB_OUT")
	)
	(segment
		(start 175.215042 -82.226658)
		(end 175.215296 -82.226404)
		(width 0.11684)
		(layer "In6.Cu")
		(net "OCP_SFF_RBT_ARB_OUT")
	)
	(segment
		(start 151.944832 -97.451672)
		(end 167.169846 -82.226658)
		(width 0.11684)
		(layer "In6.Cu")
		(net "OCP_SFF_RBT_ARB_OUT")
	)
	(segment
		(start 206.014828 -74.313288)
		(end 209.051652 -71.276464)
		(width 0.11684)
		(layer "In15.Cu")
		(net "OCP_SFF_RBT_ARB_OUT")
	)
	(segment
		(start 209.051652 -71.276464)
		(end 209.051652 -70.180454)
		(width 0.11684)
		(layer "In15.Cu")
		(net "OCP_SFF_RBT_ARB_OUT")
	)
	(segment
		(start 193.157348 -75.098148)
		(end 193.942208 -74.313288)
		(width 0.11684)
		(layer "In15.Cu")
		(net "OCP_SFF_RBT_ARB_OUT")
	)
	(segment
		(start 193.942208 -74.313288)
		(end 206.014828 -74.313288)
		(width 0.11684)
		(layer "In15.Cu")
		(net "OCP_SFF_RBT_ARB_OUT")
	)
	(via
		(at 192.515998 -78.492604)
		(size 0.6604)
		(drill 0.3302)
		(layers "F.Cu" "B.Cu")
		(net "OCP_SFF_RBT_ARB_IN_R")
	)
	(segment
		(start 191.271144 -78.65618)
		(end 191.271144 -77.67828)
		(width 0.10668)
		(layer "B.Cu")
		(net "OCP_SFF_RBT_ARB_IN_R")
	)
	(segment
		(start 192.515998 -78.492604)
		(end 192.352422 -78.65618)
		(width 0.10668)
		(layer "B.Cu")
		(net "OCP_SFF_RBT_ARB_IN_R")
	)
	(segment
		(start 194.304158 -77.842618)
		(end 193.165984 -77.842618)
		(width 0.10668)
		(layer "B.Cu")
		(net "OCP_SFF_RBT_ARB_IN_R")
	)
	(segment
		(start 192.352422 -78.65618)
		(end 191.271144 -78.65618)
		(width 0.10668)
		(layer "B.Cu")
		(net "OCP_SFF_RBT_ARB_IN_R")
	)
	(segment
		(start 193.165984 -77.842618)
		(end 192.515998 -78.492604)
		(width 0.10668)
		(layer "B.Cu")
		(net "OCP_SFF_RBT_ARB_IN_R")
	)
	(segment
		(start 147.29079 -93.174058)
		(end 147.29079 -94.393258)
		(width 0.10668)
		(layer "F.Cu")
		(net "OCP_SFF_RBT_ARB_IN_MUX2_R")
	)
	(segment
		(start 145.740628 -94.962472)
		(end 146.721576 -94.962472)
		(width 0.10668)
		(layer "F.Cu")
		(net "OCP_SFF_RBT_ARB_IN_MUX2_R")
	)
	(segment
		(start 146.721576 -94.962472)
		(end 147.29079 -94.393258)
		(width 0.10668)
		(layer "F.Cu")
		(net "OCP_SFF_RBT_ARB_IN_MUX2_R")
	)
	(via
		(at 147.29079 -94.393258)
		(size 0.762)
		(drill 0.381)
		(layers "F.Cu" "B.Cu")
		(net "OCP_SFF_RBT_ARB_IN_MUX2_R")
	)
	(segment
		(start 155.570428 -97.705672)
		(end 155.824428 -97.451672)
		(width 0.10668)
		(layer "F.Cu")
		(net "OCP_SFF_RBT_ARB_IN_MUX2")
	)
	(segment
		(start 148.09089 -93.174058)
		(end 148.883878 -93.174058)
		(width 0.10668)
		(layer "F.Cu")
		(net "OCP_SFF_RBT_ARB_IN_MUX2")
	)
	(segment
		(start 154.884628 -97.705672)
		(end 155.570428 -97.705672)
		(width 0.10668)
		(layer "F.Cu")
		(net "OCP_SFF_RBT_ARB_IN_MUX2")
	)
	(via
		(at 155.824428 -97.451672)
		(size 0.508)
		(drill 0.254)
		(layers "F.Cu" "B.Cu")
		(net "OCP_SFF_RBT_ARB_IN_MUX2")
	)
	(via
		(at 148.883878 -93.174058)
		(size 0.508)
		(drill 0.254)
		(layers "F.Cu" "B.Cu")
		(net "OCP_SFF_RBT_ARB_IN_MUX2")
	)
	(segment
		(start 148.883878 -93.174058)
		(end 150.445978 -94.736158)
		(width 0.11684)
		(layer "In2.Cu")
		(net "OCP_SFF_RBT_ARB_IN_MUX2")
	)
	(segment
		(start 153.12644 -97.451672)
		(end 155.824428 -97.451672)
		(width 0.11684)
		(layer "In2.Cu")
		(net "OCP_SFF_RBT_ARB_IN_MUX2")
	)
	(segment
		(start 150.445978 -94.736158)
		(end 150.445978 -94.77121)
		(width 0.11684)
		(layer "In2.Cu")
		(net "OCP_SFF_RBT_ARB_IN_MUX2")
	)
	(segment
		(start 150.445978 -94.77121)
		(end 153.12644 -97.451672)
		(width 0.11684)
		(layer "In2.Cu")
		(net "OCP_SFF_RBT_ARB_IN_MUX2")
	)
	(segment
		(start 156.43479 -93.174058)
		(end 156.43479 -94.393258)
		(width 0.10668)
		(layer "F.Cu")
		(net "OCP_SFF_RBT_ARB_IN_MUX1_R")
	)
	(segment
		(start 154.884628 -94.962472)
		(end 155.865576 -94.962472)
		(width 0.10668)
		(layer "F.Cu")
		(net "OCP_SFF_RBT_ARB_IN_MUX1_R")
	)
	(segment
		(start 155.865576 -94.962472)
		(end 156.43479 -94.393258)
		(width 0.10668)
		(layer "F.Cu")
		(net "OCP_SFF_RBT_ARB_IN_MUX1_R")
	)
	(via
		(at 156.43479 -94.393258)
		(size 0.762)
		(drill 0.381)
		(layers "F.Cu" "B.Cu")
		(net "OCP_SFF_RBT_ARB_IN_MUX1_R")
	)
	(segment
		(start 157.23489 -93.174058)
		(end 157.23489 -93.863668)
		(width 0.10668)
		(layer "F.Cu")
		(net "OCP_SFF_RBT_ARB_IN_MUX1")
	)
	(segment
		(start 145.740628 -97.705672)
		(end 146.426428 -97.705672)
		(width 0.10668)
		(layer "F.Cu")
		(net "OCP_SFF_RBT_ARB_IN_MUX1")
	)
	(segment
		(start 146.426428 -97.705672)
		(end 146.680428 -97.451672)
		(width 0.10668)
		(layer "F.Cu")
		(net "OCP_SFF_RBT_ARB_IN_MUX1")
	)
	(via
		(at 146.680428 -97.451672)
		(size 0.508)
		(drill 0.254)
		(layers "F.Cu" "B.Cu")
		(net "OCP_SFF_RBT_ARB_IN_MUX1")
	)
	(via
		(at 157.23489 -93.863668)
		(size 0.508)
		(drill 0.254)
		(layers "F.Cu" "B.Cu")
		(net "OCP_SFF_RBT_ARB_IN_MUX1")
	)
	(segment
		(start 148.042376 -97.451672)
		(end 146.680428 -97.451672)
		(width 0.11684)
		(layer "In15.Cu")
		(net "OCP_SFF_RBT_ARB_IN_MUX1")
	)
	(segment
		(start 157.23489 -93.863668)
		(end 151.63038 -93.863668)
		(width 0.11684)
		(layer "In15.Cu")
		(net "OCP_SFF_RBT_ARB_IN_MUX1")
	)
	(segment
		(start 151.63038 -93.863668)
		(end 148.042376 -97.451672)
		(width 0.11684)
		(layer "In15.Cu")
		(net "OCP_SFF_RBT_ARB_IN_MUX1")
	)
	(segment
		(start 152.884632 -94.962472)
		(end 152.38095 -94.962472)
		(width 0.10668)
		(layer "F.Cu")
		(net "OCP_SFF_RBT_ARB_IN")
	)
	(segment
		(start 152.38095 -94.962472)
		(end 151.997156 -94.578678)
		(width 0.10668)
		(layer "F.Cu")
		(net "OCP_SFF_RBT_ARB_IN")
	)
	(via
		(at 190.23076 -79.651352)
		(size 0.6604)
		(drill 0.3302)
		(layers "F.Cu" "B.Cu")
		(net "OCP_SFF_RBT_ARB_IN")
	)
	(via
		(at 151.997156 -94.578678)
		(size 0.508)
		(drill 0.254)
		(layers "F.Cu" "B.Cu")
		(net "OCP_SFF_RBT_ARB_IN")
	)
	(via
		(at 162.817302 -82.412586)
		(size 0.508)
		(drill 0.254)
		(layers "F.Cu" "B.Cu")
		(net "OCP_SFF_RBT_ARB_IN")
	)
	(segment
		(start 190.167514 -79.714598)
		(end 188.50356 -79.714598)
		(width 0.10668)
		(layer "B.Cu")
		(net "OCP_SFF_RBT_ARB_IN")
	)
	(segment
		(start 190.23076 -79.651352)
		(end 190.167514 -79.714598)
		(width 0.10668)
		(layer "B.Cu")
		(net "OCP_SFF_RBT_ARB_IN")
	)
	(segment
		(start 186.873896 -81.344262)
		(end 163.885626 -81.344262)
		(width 0.10668)
		(layer "B.Cu")
		(net "OCP_SFF_RBT_ARB_IN")
	)
	(segment
		(start 191.271144 -79.45628)
		(end 190.425832 -79.45628)
		(width 0.10668)
		(layer "B.Cu")
		(net "OCP_SFF_RBT_ARB_IN")
	)
	(segment
		(start 163.885626 -81.344262)
		(end 162.817302 -82.412586)
		(width 0.10668)
		(layer "B.Cu")
		(net "OCP_SFF_RBT_ARB_IN")
	)
	(segment
		(start 188.50356 -79.714598)
		(end 186.873896 -81.344262)
		(width 0.10668)
		(layer "B.Cu")
		(net "OCP_SFF_RBT_ARB_IN")
	)
	(segment
		(start 190.425832 -79.45628)
		(end 190.23076 -79.651352)
		(width 0.10668)
		(layer "B.Cu")
		(net "OCP_SFF_RBT_ARB_IN")
	)
	(segment
		(start 162.817302 -85.938106)
		(end 154.17673 -94.578678)
		(width 0.11684)
		(layer "In6.Cu")
		(net "OCP_SFF_RBT_ARB_IN")
	)
	(segment
		(start 162.817302 -82.412586)
		(end 162.817302 -85.938106)
		(width 0.11684)
		(layer "In6.Cu")
		(net "OCP_SFF_RBT_ARB_IN")
	)
	(segment
		(start 154.17673 -94.578678)
		(end 151.997156 -94.578678)
		(width 0.11684)
		(layer "In6.Cu")
		(net "OCP_SFF_RBT_ARB_IN")
	)
	(segment
		(start 391.246868 -8.320024)
		(end 391.246868 -7.723124)
		(width 0.10668)
		(layer "F.Cu")
		(net "OCP_SFF_PWRBRK_N")
	)
	(segment
		(start 374.64492 -14.969236)
		(end 373.920766 -14.245082)
		(width 0.10668)
		(layer "F.Cu")
		(net "OCP_SFF_PWRBRK_N")
	)
	(segment
		(start 374.64492 -15.637002)
		(end 374.64492 -14.969236)
		(width 0.10668)
		(layer "F.Cu")
		(net "OCP_SFF_PWRBRK_N")
	)
	(segment
		(start 391.246868 -7.723124)
		(end 390.738868 -7.215124)
		(width 0.10668)
		(layer "F.Cu")
		(net "OCP_SFF_PWRBRK_N")
	)
	(via
		(at 373.920766 -14.245082)
		(size 0.508)
		(drill 0.254)
		(layers "F.Cu" "B.Cu")
		(net "OCP_SFF_PWRBRK_N")
	)
	(via
		(at 390.738868 -7.215124)
		(size 0.508)
		(drill 0.254)
		(layers "F.Cu" "B.Cu")
		(net "OCP_SFF_PWRBRK_N")
	)
	(segment
		(start 390.738868 -7.215124)
		(end 390.738868 -9.351264)
		(width 0.11684)
		(layer "In2.Cu")
		(net "OCP_SFF_PWRBRK_N")
	)
	(segment
		(start 376.189748 -16.514064)
		(end 373.920766 -14.245082)
		(width 0.11684)
		(layer "In2.Cu")
		(net "OCP_SFF_PWRBRK_N")
	)
	(segment
		(start 390.738868 -9.351264)
		(end 383.576068 -16.514064)
		(width 0.11684)
		(layer "In2.Cu")
		(net "OCP_SFF_PWRBRK_N")
	)
	(segment
		(start 383.576068 -16.514064)
		(end 376.189748 -16.514064)
		(width 0.11684)
		(layer "In2.Cu")
		(net "OCP_SFF_PWRBRK_N")
	)
	(segment
		(start 369.52428 -13.444982)
		(end 371.04828 -13.444982)
		(width 0.10668)
		(layer "F.Cu")
		(net "OCP_SFF_PWRBRK_BUFF_N")
	)
	(segment
		(start 373.84482 -15.637002)
		(end 372.86692 -15.637002)
		(width 0.10668)
		(layer "F.Cu")
		(net "OCP_SFF_PWRBRK_BUFF_N")
	)
	(segment
		(start 372.86692 -15.637002)
		(end 372.86692 -14.675358)
		(width 0.10668)
		(layer "F.Cu")
		(net "OCP_SFF_PWRBRK_BUFF_N")
	)
	(segment
		(start 372.86692 -14.675358)
		(end 371.636544 -13.444982)
		(width 0.10668)
		(layer "F.Cu")
		(net "OCP_SFF_PWRBRK_BUFF_N")
	)
	(segment
		(start 371.636544 -13.444982)
		(end 371.04828 -13.444982)
		(width 0.10668)
		(layer "F.Cu")
		(net "OCP_SFF_PWRBRK_BUFF_N")
	)
	(via
		(at 371.04828 -13.444982)
		(size 0.762)
		(drill 0.381)
		(layers "F.Cu" "B.Cu")
		(net "OCP_SFF_PWRBRK_BUFF_N")
	)
	(segment
		(start 158.699962 -95.93453)
		(end 158.699962 -98.064828)
		(width 0.10668)
		(layer "F.Cu")
		(net "OCP_SFF_PRSNT_ALL_R_N")
	)
	(segment
		(start 158.699962 -98.064828)
		(end 158.409132 -98.355658)
		(width 0.10668)
		(layer "F.Cu")
		(net "OCP_SFF_PRSNT_ALL_R_N")
	)
	(segment
		(start 157.88259 -95.117158)
		(end 158.699962 -95.93453)
		(width 0.10668)
		(layer "F.Cu")
		(net "OCP_SFF_PRSNT_ALL_R_N")
	)
	(segment
		(start 157.88259 -95.117158)
		(end 157.88259 -84.164932)
		(width 0.10668)
		(layer "F.Cu")
		(net "OCP_SFF_PRSNT_ALL_R_N")
	)
	(segment
		(start 15.803372 -75.044808)
		(end 15.892018 -74.956162)
		(width 0.10668)
		(layer "F.Cu")
		(net "OCP_SFF_PRSNT_ALL_R_N")
	)
	(segment
		(start 14.901672 -75.044808)
		(end 15.803372 -75.044808)
		(width 0.10668)
		(layer "F.Cu")
		(net "OCP_SFF_PRSNT_ALL_R_N")
	)
	(segment
		(start 158.409132 -98.355658)
		(end 157.88259 -98.355658)
		(width 0.10668)
		(layer "F.Cu")
		(net "OCP_SFF_PRSNT_ALL_R_N")
	)
	(via
		(at 15.892018 -74.956162)
		(size 0.508)
		(drill 0.254)
		(layers "F.Cu" "B.Cu")
		(net "OCP_SFF_PRSNT_ALL_R_N")
	)
	(via
		(at 157.88259 -84.164932)
		(size 0.508)
		(drill 0.254)
		(layers "F.Cu" "B.Cu")
		(net "OCP_SFF_PRSNT_ALL_R_N")
	)
	(segment
		(start 15.892018 -74.956162)
		(end 15.714472 -75.133708)
		(width 0.10668)
		(layer "B.Cu")
		(net "OCP_SFF_PRSNT_ALL_R_N")
	)
	(segment
		(start 136.05002 -84.164932)
		(end 157.88259 -84.164932)
		(width 0.10668)
		(layer "B.Cu")
		(net "OCP_SFF_PRSNT_ALL_R_N")
	)
	(segment
		(start 20.674838 -82.17408)
		(end 134.059168 -82.17408)
		(width 0.10668)
		(layer "B.Cu")
		(net "OCP_SFF_PRSNT_ALL_R_N")
	)
	(segment
		(start 134.059168 -82.17408)
		(end 136.05002 -84.164932)
		(width 0.10668)
		(layer "B.Cu")
		(net "OCP_SFF_PRSNT_ALL_R_N")
	)
	(segment
		(start 15.714472 -75.133708)
		(end 15.714472 -77.213714)
		(width 0.10668)
		(layer "B.Cu")
		(net "OCP_SFF_PRSNT_ALL_R_N")
	)
	(segment
		(start 15.714472 -77.213714)
		(end 20.674838 -82.17408)
		(width 0.10668)
		(layer "B.Cu")
		(net "OCP_SFF_PRSNT_ALL_R_N")
	)
	(segment
		(start 155.311602 -96.262444)
		(end 154.884628 -96.262444)
		(width 0.10668)
		(layer "F.Cu")
		(net "OCP_SFF_PRSNT_ALL_R3_N")
	)
	(segment
		(start 156.185616 -97.136458)
		(end 155.311602 -96.262444)
		(width 0.10668)
		(layer "F.Cu")
		(net "OCP_SFF_PRSNT_ALL_R3_N")
	)
	(segment
		(start 157.88259 -97.136458)
		(end 156.185616 -97.136458)
		(width 0.10668)
		(layer "F.Cu")
		(net "OCP_SFF_PRSNT_ALL_R3_N")
	)
	(segment
		(start 157.88259 -95.917258)
		(end 157.88259 -97.136458)
		(width 0.10668)
		(layer "F.Cu")
		(net "OCP_SFF_PRSNT_ALL_R3_N")
	)
	(via
		(at 157.88259 -97.136458)
		(size 0.762)
		(drill 0.381)
		(layers "F.Cu" "B.Cu")
		(net "OCP_SFF_PRSNT_ALL_R3_N")
	)
	(segment
		(start 157.88259 -100.374958)
		(end 157.88259 -99.155758)
		(width 0.10668)
		(layer "F.Cu")
		(net "OCP_SFF_PRSNT_ALL_R1_N")
	)
	(segment
		(start 155.213558 -99.005644)
		(end 154.884628 -99.005644)
		(width 0.10668)
		(layer "F.Cu")
		(net "OCP_SFF_PRSNT_ALL_R1_N")
	)
	(segment
		(start 156.582872 -100.374958)
		(end 155.213558 -99.005644)
		(width 0.10668)
		(layer "F.Cu")
		(net "OCP_SFF_PRSNT_ALL_R1_N")
	)
	(segment
		(start 157.88259 -100.374958)
		(end 156.582872 -100.374958)
		(width 0.10668)
		(layer "F.Cu")
		(net "OCP_SFF_PRSNT_ALL_R1_N")
	)
	(via
		(at 157.88259 -100.374958)
		(size 0.762)
		(drill 0.381)
		(layers "F.Cu" "B.Cu")
		(net "OCP_SFF_PRSNT_ALL_R1_N")
	)
	(segment
		(start 436.011066 -5.05714)
		(end 436.155592 -5.05714)
		(width 0.10668)
		(layer "F.Cu")
		(net "OCP_SFF_PRSNTA_R_N")
	)
	(segment
		(start 434.966872 -8.320024)
		(end 434.966872 -6.101334)
		(width 0.10668)
		(layer "F.Cu")
		(net "OCP_SFF_PRSNTA_R_N")
	)
	(segment
		(start 434.966872 -6.101334)
		(end 436.011066 -5.05714)
		(width 0.10668)
		(layer "F.Cu")
		(net "OCP_SFF_PRSNTA_R_N")
	)
	(via
		(at 436.155592 -5.05714)
		(size 0.508)
		(drill 0.254)
		(layers "F.Cu" "B.Cu")
		(net "OCP_SFF_PRSNTA_R_N")
	)
	(segment
		(start 435.145942 -7.916926)
		(end 435.145942 -5.922264)
		(width 0.10668)
		(layer "B.Cu")
		(net "OCP_SFF_PRSNTA_R_N")
	)
	(segment
		(start 435.145942 -5.922264)
		(end 436.011066 -5.05714)
		(width 0.10668)
		(layer "B.Cu")
		(net "OCP_SFF_PRSNTA_R_N")
	)
	(segment
		(start 436.011066 -5.05714)
		(end 436.155592 -5.05714)
		(width 0.10668)
		(layer "B.Cu")
		(net "OCP_SFF_PRSNTA_R_N")
	)
	(segment
		(start 418.286692 -57.047638)
		(end 420.222426 -57.047638)
		(width 0.10668)
		(layer "F.Cu")
		(net "OCP_SFF_PRSNT3_R_N")
	)
	(segment
		(start 455.296778 -102.598728)
		(end 456.339956 -102.598728)
		(width 0.10668)
		(layer "F.Cu")
		(net "OCP_SFF_PRSNT3_R_N")
	)
	(segment
		(start 456.339956 -102.598728)
		(end 456.737466 -102.996238)
		(width 0.10668)
		(layer "F.Cu")
		(net "OCP_SFF_PRSNT3_R_N")
	)
	(segment
		(start 391.246868 -11.26998)
		(end 391.246868 -12.37488)
		(width 0.10668)
		(layer "F.Cu")
		(net "OCP_SFF_PRSNT3_R_N")
	)
	(segment
		(start 454.119996 -102.598728)
		(end 455.296778 -102.598728)
		(width 0.10668)
		(layer "F.Cu")
		(net "OCP_SFF_PRSNT3_R_N")
	)
	(via
		(at 455.296778 -102.598728)
		(size 0.508)
		(drill 0.254)
		(layers "F.Cu" "B.Cu")
		(net "OCP_SFF_PRSNT3_R_N")
	)
	(via
		(at 391.246868 -12.37488)
		(size 0.508)
		(drill 0.254)
		(layers "F.Cu" "B.Cu")
		(net "OCP_SFF_PRSNT3_R_N")
	)
	(via
		(at 420.222426 -57.047638)
		(size 0.508)
		(drill 0.254)
		(layers "F.Cu" "B.Cu")
		(net "OCP_SFF_PRSNT3_R_N")
	)
	(segment
		(start 409.891738 -13.217906)
		(end 411.132528 -14.458696)
		(width 0.11684)
		(layer "In2.Cu")
		(net "OCP_SFF_PRSNT3_R_N")
	)
	(segment
		(start 391.246868 -12.37488)
		(end 392.089894 -13.217906)
		(width 0.11684)
		(layer "In2.Cu")
		(net "OCP_SFF_PRSNT3_R_N")
	)
	(segment
		(start 411.132528 -18.125948)
		(end 416.313112 -23.306532)
		(width 0.11684)
		(layer "In2.Cu")
		(net "OCP_SFF_PRSNT3_R_N")
	)
	(segment
		(start 414.424622 -58.862468)
		(end 418.89299 -58.862468)
		(width 0.11684)
		(layer "In2.Cu")
		(net "OCP_SFF_PRSNT3_R_N")
	)
	(segment
		(start 416.313112 -52.780946)
		(end 413.452818 -55.64124)
		(width 0.11684)
		(layer "In2.Cu")
		(net "OCP_SFF_PRSNT3_R_N")
	)
	(segment
		(start 420.222426 -57.533032)
		(end 420.222426 -57.047638)
		(width 0.11684)
		(layer "In2.Cu")
		(net "OCP_SFF_PRSNT3_R_N")
	)
	(segment
		(start 413.452818 -57.890664)
		(end 414.424622 -58.862468)
		(width 0.11684)
		(layer "In2.Cu")
		(net "OCP_SFF_PRSNT3_R_N")
	)
	(segment
		(start 416.313112 -23.306532)
		(end 416.313112 -52.780946)
		(width 0.11684)
		(layer "In2.Cu")
		(net "OCP_SFF_PRSNT3_R_N")
	)
	(segment
		(start 392.089894 -13.217906)
		(end 409.891738 -13.217906)
		(width 0.11684)
		(layer "In2.Cu")
		(net "OCP_SFF_PRSNT3_R_N")
	)
	(segment
		(start 418.89299 -58.862468)
		(end 420.222426 -57.533032)
		(width 0.11684)
		(layer "In2.Cu")
		(net "OCP_SFF_PRSNT3_R_N")
	)
	(segment
		(start 413.452818 -55.64124)
		(end 413.452818 -57.890664)
		(width 0.11684)
		(layer "In2.Cu")
		(net "OCP_SFF_PRSNT3_R_N")
	)
	(segment
		(start 411.132528 -14.458696)
		(end 411.132528 -18.125948)
		(width 0.11684)
		(layer "In2.Cu")
		(net "OCP_SFF_PRSNT3_R_N")
	)
	(segment
		(start 452.190866 -92.518992)
		(end 443.002924 -83.33105)
		(width 0.11684)
		(layer "In11.Cu")
		(net "OCP_SFF_PRSNT3_R_N")
	)
	(segment
		(start 425.216828 -83.33105)
		(end 419.706806 -77.821028)
		(width 0.11684)
		(layer "In11.Cu")
		(net "OCP_SFF_PRSNT3_R_N")
	)
	(segment
		(start 419.706806 -77.821028)
		(end 419.706806 -57.563258)
		(width 0.11684)
		(layer "In11.Cu")
		(net "OCP_SFF_PRSNT3_R_N")
	)
	(segment
		(start 419.706806 -57.563258)
		(end 420.222426 -57.047638)
		(width 0.11684)
		(layer "In11.Cu")
		(net "OCP_SFF_PRSNT3_R_N")
	)
	(segment
		(start 452.190866 -99.492816)
		(end 452.190866 -92.518992)
		(width 0.11684)
		(layer "In11.Cu")
		(net "OCP_SFF_PRSNT3_R_N")
	)
	(segment
		(start 443.002924 -83.33105)
		(end 425.216828 -83.33105)
		(width 0.11684)
		(layer "In11.Cu")
		(net "OCP_SFF_PRSNT3_R_N")
	)
	(segment
		(start 455.296778 -102.598728)
		(end 452.190866 -99.492816)
		(width 0.11684)
		(layer "In11.Cu")
		(net "OCP_SFF_PRSNT3_R_N")
	)
	(segment
		(start 433.59197 -4.023106)
		(end 433.625244 -3.989832)
		(width 0.10668)
		(layer "F.Cu")
		(net "OCP_SFF_PRSNT2_R_N")
	)
	(segment
		(start 455.2823 -104.29621)
		(end 454.166478 -104.29621)
		(width 0.10668)
		(layer "F.Cu")
		(net "OCP_SFF_PRSNT2_R_N")
	)
	(segment
		(start 418.286692 -56.347868)
		(end 419.105842 -56.347868)
		(width 0.10668)
		(layer "F.Cu")
		(net "OCP_SFF_PRSNT2_R_N")
	)
	(segment
		(start 433.59197 -7.052056)
		(end 433.59197 -4.023106)
		(width 0.10668)
		(layer "F.Cu")
		(net "OCP_SFF_PRSNT2_R_N")
	)
	(segment
		(start 456.737466 -104.29621)
		(end 455.2823 -104.29621)
		(width 0.10668)
		(layer "F.Cu")
		(net "OCP_SFF_PRSNT2_R_N")
	)
	(segment
		(start 433.766976 -8.320024)
		(end 433.766976 -7.227062)
		(width 0.10668)
		(layer "F.Cu")
		(net "OCP_SFF_PRSNT2_R_N")
	)
	(segment
		(start 433.766976 -7.227062)
		(end 433.59197 -7.052056)
		(width 0.10668)
		(layer "F.Cu")
		(net "OCP_SFF_PRSNT2_R_N")
	)
	(segment
		(start 454.166478 -104.29621)
		(end 454.119996 -104.249728)
		(width 0.10668)
		(layer "F.Cu")
		(net "OCP_SFF_PRSNT2_R_N")
	)
	(via
		(at 419.105842 -56.347868)
		(size 0.508)
		(drill 0.254)
		(layers "F.Cu" "B.Cu")
		(net "OCP_SFF_PRSNT2_R_N")
	)
	(via
		(at 433.625244 -3.989832)
		(size 0.508)
		(drill 0.254)
		(layers "F.Cu" "B.Cu")
		(net "OCP_SFF_PRSNT2_R_N")
	)
	(via
		(at 455.2823 -104.29621)
		(size 0.508)
		(drill 0.254)
		(layers "F.Cu" "B.Cu")
		(net "OCP_SFF_PRSNT2_R_N")
	)
	(segment
		(start 417.273232 -54.515258)
		(end 419.105842 -56.347868)
		(width 0.11684)
		(layer "In2.Cu")
		(net "OCP_SFF_PRSNT2_R_N")
	)
	(segment
		(start 421.092376 -15.91945)
		(end 420.461186 -16.55064)
		(width 0.11684)
		(layer "In2.Cu")
		(net "OCP_SFF_PRSNT2_R_N")
	)
	(segment
		(start 417.273232 -21.301964)
		(end 417.273232 -54.515258)
		(width 0.11684)
		(layer "In2.Cu")
		(net "OCP_SFF_PRSNT2_R_N")
	)
	(segment
		(start 421.092376 -7.52348)
		(end 421.092376 -15.91945)
		(width 0.11684)
		(layer "In2.Cu")
		(net "OCP_SFF_PRSNT2_R_N")
	)
	(segment
		(start 420.461186 -16.55064)
		(end 420.461186 -18.11401)
		(width 0.11684)
		(layer "In2.Cu")
		(net "OCP_SFF_PRSNT2_R_N")
	)
	(segment
		(start 420.461186 -18.11401)
		(end 417.273232 -21.301964)
		(width 0.11684)
		(layer "In2.Cu")
		(net "OCP_SFF_PRSNT2_R_N")
	)
	(segment
		(start 433.625244 -3.989832)
		(end 433.246022 -3.61061)
		(width 0.11684)
		(layer "In2.Cu")
		(net "OCP_SFF_PRSNT2_R_N")
	)
	(segment
		(start 425.005246 -3.61061)
		(end 421.092376 -7.52348)
		(width 0.11684)
		(layer "In2.Cu")
		(net "OCP_SFF_PRSNT2_R_N")
	)
	(segment
		(start 433.246022 -3.61061)
		(end 425.005246 -3.61061)
		(width 0.11684)
		(layer "In2.Cu")
		(net "OCP_SFF_PRSNT2_R_N")
	)
	(segment
		(start 451.870826 -100.884736)
		(end 451.870826 -92.65158)
		(width 0.11684)
		(layer "In11.Cu")
		(net "OCP_SFF_PRSNT2_R_N")
	)
	(segment
		(start 451.870826 -92.65158)
		(end 442.870336 -83.65109)
		(width 0.11684)
		(layer "In11.Cu")
		(net "OCP_SFF_PRSNT2_R_N")
	)
	(segment
		(start 418.641022 -77.207872)
		(end 418.641022 -56.812688)
		(width 0.11684)
		(layer "In11.Cu")
		(net "OCP_SFF_PRSNT2_R_N")
	)
	(segment
		(start 418.641022 -56.812688)
		(end 419.105842 -56.347868)
		(width 0.11684)
		(layer "In11.Cu")
		(net "OCP_SFF_PRSNT2_R_N")
	)
	(segment
		(start 442.870336 -83.65109)
		(end 425.08424 -83.65109)
		(width 0.11684)
		(layer "In11.Cu")
		(net "OCP_SFF_PRSNT2_R_N")
	)
	(segment
		(start 425.08424 -83.65109)
		(end 418.641022 -77.207872)
		(width 0.11684)
		(layer "In11.Cu")
		(net "OCP_SFF_PRSNT2_R_N")
	)
	(segment
		(start 455.2823 -104.29621)
		(end 451.870826 -100.884736)
		(width 0.11684)
		(layer "In11.Cu")
		(net "OCP_SFF_PRSNT2_R_N")
	)
	(segment
		(start 414.736788 -57.047638)
		(end 415.555938 -57.047638)
		(width 0.10668)
		(layer "F.Cu")
		(net "OCP_SFF_PRSNT23_R_N")
	)
	(via
		(at 415.555938 -57.047638)
		(size 0.508)
		(drill 0.254)
		(layers "F.Cu" "B.Cu")
		(net "OCP_SFF_PRSNT23_R_N")
	)
	(via
		(at 9.327388 -83.260438)
		(size 0.6604)
		(drill 0.3302)
		(layers "F.Cu" "B.Cu")
		(net "OCP_SFF_PRSNT23_R_N")
	)
	(via
		(at 178.685444 -87.758778)
		(size 0.508)
		(drill 0.254)
		(layers "F.Cu" "B.Cu")
		(net "OCP_SFF_PRSNT23_R_N")
	)
	(segment
		(start 8.382 -81.55305)
		(end 8.382 -82.31505)
		(width 0.10668)
		(layer "B.Cu")
		(net "OCP_SFF_PRSNT23_R_N")
	)
	(segment
		(start 178.685444 -87.758778)
		(end 177.49266 -86.565994)
		(width 0.10668)
		(layer "B.Cu")
		(net "OCP_SFF_PRSNT23_R_N")
	)
	(segment
		(start 133.69036 -83.15325)
		(end 9.434576 -83.15325)
		(width 0.10668)
		(layer "B.Cu")
		(net "OCP_SFF_PRSNT23_R_N")
	)
	(segment
		(start 9.434576 -83.15325)
		(end 9.327388 -83.260438)
		(width 0.10668)
		(layer "B.Cu")
		(net "OCP_SFF_PRSNT23_R_N")
	)
	(segment
		(start 136.607804 -86.070694)
		(end 133.69036 -83.15325)
		(width 0.10668)
		(layer "B.Cu")
		(net "OCP_SFF_PRSNT23_R_N")
	)
	(segment
		(start 177.49266 -86.565994)
		(end 170.885612 -86.565994)
		(width 0.10668)
		(layer "B.Cu")
		(net "OCP_SFF_PRSNT23_R_N")
	)
	(segment
		(start 170.390312 -86.070694)
		(end 136.607804 -86.070694)
		(width 0.10668)
		(layer "B.Cu")
		(net "OCP_SFF_PRSNT23_R_N")
	)
	(segment
		(start 170.885612 -86.565994)
		(end 170.390312 -86.070694)
		(width 0.10668)
		(layer "B.Cu")
		(net "OCP_SFF_PRSNT23_R_N")
	)
	(segment
		(start 8.382 -82.31505)
		(end 9.327388 -83.260438)
		(width 0.10668)
		(layer "B.Cu")
		(net "OCP_SFF_PRSNT23_R_N")
	)
	(segment
		(start 289.55873 -59.986418)
		(end 282.66136 -66.883788)
		(width 0.11684)
		(layer "In6.Cu")
		(net "OCP_SFF_PRSNT23_R_N")
	)
	(segment
		(start 272.638774 -85.838792)
		(end 253.845822 -85.838792)
		(width 0.11684)
		(layer "In6.Cu")
		(net "OCP_SFF_PRSNT23_R_N")
	)
	(segment
		(start 394.169646 -57.67832)
		(end 393.853924 -57.994042)
		(width 0.11684)
		(layer "In6.Cu")
		(net "OCP_SFF_PRSNT23_R_N")
	)
	(segment
		(start 282.66136 -75.816206)
		(end 272.638774 -85.838792)
		(width 0.11684)
		(layer "In6.Cu")
		(net "OCP_SFF_PRSNT23_R_N")
	)
	(segment
		(start 388.955534 -57.994042)
		(end 387.816598 -59.132978)
		(width 0.11684)
		(layer "In6.Cu")
		(net "OCP_SFF_PRSNT23_R_N")
	)
	(segment
		(start 309.338472 -59.132978)
		(end 308.485032 -59.986418)
		(width 0.11684)
		(layer "In6.Cu")
		(net "OCP_SFF_PRSNT23_R_N")
	)
	(segment
		(start 410.175202 -57.047638)
		(end 409.54452 -57.67832)
		(width 0.11684)
		(layer "In6.Cu")
		(net "OCP_SFF_PRSNT23_R_N")
	)
	(segment
		(start 180.065426 -86.378796)
		(end 178.685444 -87.758778)
		(width 0.11684)
		(layer "In6.Cu")
		(net "OCP_SFF_PRSNT23_R_N")
	)
	(segment
		(start 248.418858 -91.265756)
		(end 205.994 -91.265756)
		(width 0.11684)
		(layer "In6.Cu")
		(net "OCP_SFF_PRSNT23_R_N")
	)
	(segment
		(start 387.816598 -59.132978)
		(end 309.338472 -59.132978)
		(width 0.11684)
		(layer "In6.Cu")
		(net "OCP_SFF_PRSNT23_R_N")
	)
	(segment
		(start 195.776596 -87.507064)
		(end 194.648328 -86.378796)
		(width 0.11684)
		(layer "In6.Cu")
		(net "OCP_SFF_PRSNT23_R_N")
	)
	(segment
		(start 415.555938 -57.047638)
		(end 410.175202 -57.047638)
		(width 0.11684)
		(layer "In6.Cu")
		(net "OCP_SFF_PRSNT23_R_N")
	)
	(segment
		(start 393.853924 -57.994042)
		(end 388.955534 -57.994042)
		(width 0.11684)
		(layer "In6.Cu")
		(net "OCP_SFF_PRSNT23_R_N")
	)
	(segment
		(start 282.66136 -66.883788)
		(end 282.66136 -75.816206)
		(width 0.11684)
		(layer "In6.Cu")
		(net "OCP_SFF_PRSNT23_R_N")
	)
	(segment
		(start 409.54452 -57.67832)
		(end 394.169646 -57.67832)
		(width 0.11684)
		(layer "In6.Cu")
		(net "OCP_SFF_PRSNT23_R_N")
	)
	(segment
		(start 205.994 -91.265756)
		(end 202.235308 -87.507064)
		(width 0.11684)
		(layer "In6.Cu")
		(net "OCP_SFF_PRSNT23_R_N")
	)
	(segment
		(start 253.845822 -85.838792)
		(end 248.418858 -91.265756)
		(width 0.11684)
		(layer "In6.Cu")
		(net "OCP_SFF_PRSNT23_R_N")
	)
	(segment
		(start 308.485032 -59.986418)
		(end 289.55873 -59.986418)
		(width 0.11684)
		(layer "In6.Cu")
		(net "OCP_SFF_PRSNT23_R_N")
	)
	(segment
		(start 194.648328 -86.378796)
		(end 180.065426 -86.378796)
		(width 0.11684)
		(layer "In6.Cu")
		(net "OCP_SFF_PRSNT23_R_N")
	)
	(segment
		(start 202.235308 -87.507064)
		(end 195.776596 -87.507064)
		(width 0.11684)
		(layer "In6.Cu")
		(net "OCP_SFF_PRSNT23_R_N")
	)
	(segment
		(start 414.736788 -57.697878)
		(end 413.917638 -57.697878)
		(width 0.10668)
		(layer "F.Cu")
		(net "OCP_SFF_PRSNT1_R_N")
	)
	(segment
		(start 456.734672 -106.36885)
		(end 455.25309 -106.36885)
		(width 0.10668)
		(layer "F.Cu")
		(net "OCP_SFF_PRSNT1_R_N")
	)
	(segment
		(start 412.356808 -8.320024)
		(end 412.356808 -7.463536)
		(width 0.10668)
		(layer "F.Cu")
		(net "OCP_SFF_PRSNT1_R_N")
	)
	(segment
		(start 454.159874 -106.36885)
		(end 454.119996 -106.408728)
		(width 0.10668)
		(layer "F.Cu")
		(net "OCP_SFF_PRSNT1_R_N")
	)
	(segment
		(start 412.356808 -7.463536)
		(end 412.071566 -7.178294)
		(width 0.10668)
		(layer "F.Cu")
		(net "OCP_SFF_PRSNT1_R_N")
	)
	(segment
		(start 455.25309 -106.36885)
		(end 454.159874 -106.36885)
		(width 0.10668)
		(layer "F.Cu")
		(net "OCP_SFF_PRSNT1_R_N")
	)
	(via
		(at 412.071566 -7.178294)
		(size 0.508)
		(drill 0.254)
		(layers "F.Cu" "B.Cu")
		(net "OCP_SFF_PRSNT1_R_N")
	)
	(via
		(at 455.25309 -106.36885)
		(size 0.508)
		(drill 0.254)
		(layers "F.Cu" "B.Cu")
		(net "OCP_SFF_PRSNT1_R_N")
	)
	(via
		(at 413.917638 -57.697878)
		(size 0.508)
		(drill 0.254)
		(layers "F.Cu" "B.Cu")
		(net "OCP_SFF_PRSNT1_R_N")
	)
	(segment
		(start 414.43402 -18.228818)
		(end 413.736028 -18.92681)
		(width 0.11684)
		(layer "In2.Cu")
		(net "OCP_SFF_PRSNT1_R_N")
	)
	(segment
		(start 416.633152 -23.173944)
		(end 416.633152 -54.982364)
		(width 0.11684)
		(layer "In2.Cu")
		(net "OCP_SFF_PRSNT1_R_N")
	)
	(segment
		(start 416.633152 -54.982364)
		(end 413.917638 -57.697878)
		(width 0.11684)
		(layer "In2.Cu")
		(net "OCP_SFF_PRSNT1_R_N")
	)
	(segment
		(start 412.071566 -7.178294)
		(end 411.38729 -7.86257)
		(width 0.11684)
		(layer "In2.Cu")
		(net "OCP_SFF_PRSNT1_R_N")
	)
	(segment
		(start 414.43402 -15.389098)
		(end 414.43402 -18.228818)
		(width 0.11684)
		(layer "In2.Cu")
		(net "OCP_SFF_PRSNT1_R_N")
	)
	(segment
		(start 413.736028 -20.27682)
		(end 416.633152 -23.173944)
		(width 0.11684)
		(layer "In2.Cu")
		(net "OCP_SFF_PRSNT1_R_N")
	)
	(segment
		(start 413.736028 -18.92681)
		(end 413.736028 -20.27682)
		(width 0.11684)
		(layer "In2.Cu")
		(net "OCP_SFF_PRSNT1_R_N")
	)
	(segment
		(start 411.38729 -7.86257)
		(end 411.38729 -12.342368)
		(width 0.11684)
		(layer "In2.Cu")
		(net "OCP_SFF_PRSNT1_R_N")
	)
	(segment
		(start 411.38729 -12.342368)
		(end 414.43402 -15.389098)
		(width 0.11684)
		(layer "In2.Cu")
		(net "OCP_SFF_PRSNT1_R_N")
	)
	(segment
		(start 424.951652 -83.97113)
		(end 418.320982 -77.34046)
		(width 0.11684)
		(layer "In11.Cu")
		(net "OCP_SFF_PRSNT1_R_N")
	)
	(segment
		(start 418.320982 -60.505086)
		(end 415.513774 -57.697878)
		(width 0.11684)
		(layer "In11.Cu")
		(net "OCP_SFF_PRSNT1_R_N")
	)
	(segment
		(start 454.100184 -106.36885)
		(end 451.550786 -103.819452)
		(width 0.11684)
		(layer "In11.Cu")
		(net "OCP_SFF_PRSNT1_R_N")
	)
	(segment
		(start 451.550786 -92.784168)
		(end 442.737748 -83.97113)
		(width 0.11684)
		(layer "In11.Cu")
		(net "OCP_SFF_PRSNT1_R_N")
	)
	(segment
		(start 418.320982 -77.34046)
		(end 418.320982 -60.505086)
		(width 0.11684)
		(layer "In11.Cu")
		(net "OCP_SFF_PRSNT1_R_N")
	)
	(segment
		(start 455.25309 -106.36885)
		(end 454.100184 -106.36885)
		(width 0.11684)
		(layer "In11.Cu")
		(net "OCP_SFF_PRSNT1_R_N")
	)
	(segment
		(start 451.550786 -103.819452)
		(end 451.550786 -92.784168)
		(width 0.11684)
		(layer "In11.Cu")
		(net "OCP_SFF_PRSNT1_R_N")
	)
	(segment
		(start 442.737748 -83.97113)
		(end 424.951652 -83.97113)
		(width 0.11684)
		(layer "In11.Cu")
		(net "OCP_SFF_PRSNT1_R_N")
	)
	(segment
		(start 415.513774 -57.697878)
		(end 413.917638 -57.697878)
		(width 0.11684)
		(layer "In11.Cu")
		(net "OCP_SFF_PRSNT1_R_N")
	)
	(segment
		(start 456.343766 -108.059728)
		(end 456.734672 -107.668822)
		(width 0.10668)
		(layer "F.Cu")
		(net "OCP_SFF_PRSNT0_R_N")
	)
	(segment
		(start 454.119996 -108.059728)
		(end 455.22388 -108.059728)
		(width 0.10668)
		(layer "F.Cu")
		(net "OCP_SFF_PRSNT0_R_N")
	)
	(segment
		(start 414.736788 -58.397648)
		(end 415.555938 -58.397648)
		(width 0.10668)
		(layer "F.Cu")
		(net "OCP_SFF_PRSNT0_R_N")
	)
	(segment
		(start 455.22388 -108.059728)
		(end 456.343766 -108.059728)
		(width 0.10668)
		(layer "F.Cu")
		(net "OCP_SFF_PRSNT0_R_N")
	)
	(segment
		(start 412.356808 -12.308078)
		(end 412.290006 -12.37488)
		(width 0.10668)
		(layer "F.Cu")
		(net "OCP_SFF_PRSNT0_R_N")
	)
	(segment
		(start 412.356808 -11.26998)
		(end 412.356808 -12.308078)
		(width 0.10668)
		(layer "F.Cu")
		(net "OCP_SFF_PRSNT0_R_N")
	)
	(via
		(at 412.290006 -12.37488)
		(size 0.508)
		(drill 0.254)
		(layers "F.Cu" "B.Cu")
		(net "OCP_SFF_PRSNT0_R_N")
	)
	(via
		(at 455.22388 -108.059728)
		(size 0.508)
		(drill 0.254)
		(layers "F.Cu" "B.Cu")
		(net "OCP_SFF_PRSNT0_R_N")
	)
	(via
		(at 415.555938 -58.397648)
		(size 0.508)
		(drill 0.254)
		(layers "F.Cu" "B.Cu")
		(net "OCP_SFF_PRSNT0_R_N")
	)
	(segment
		(start 416.953192 -57.000394)
		(end 415.555938 -58.397648)
		(width 0.11684)
		(layer "In2.Cu")
		(net "OCP_SFF_PRSNT0_R_N")
	)
	(segment
		(start 416.953192 -23.041356)
		(end 416.953192 -57.000394)
		(width 0.11684)
		(layer "In2.Cu")
		(net "OCP_SFF_PRSNT0_R_N")
	)
	(segment
		(start 414.79978 -18.4785)
		(end 414.11271 -19.16557)
		(width 0.11684)
		(layer "In2.Cu")
		(net "OCP_SFF_PRSNT0_R_N")
	)
	(segment
		(start 414.11271 -20.200874)
		(end 416.953192 -23.041356)
		(width 0.11684)
		(layer "In2.Cu")
		(net "OCP_SFF_PRSNT0_R_N")
	)
	(segment
		(start 414.79978 -14.884654)
		(end 414.79978 -18.4785)
		(width 0.11684)
		(layer "In2.Cu")
		(net "OCP_SFF_PRSNT0_R_N")
	)
	(segment
		(start 412.290006 -12.37488)
		(end 414.79978 -14.884654)
		(width 0.11684)
		(layer "In2.Cu")
		(net "OCP_SFF_PRSNT0_R_N")
	)
	(segment
		(start 414.11271 -19.16557)
		(end 414.11271 -20.200874)
		(width 0.11684)
		(layer "In2.Cu")
		(net "OCP_SFF_PRSNT0_R_N")
	)
	(segment
		(start 424.899836 -84.371942)
		(end 417.878514 -77.35062)
		(width 0.11684)
		(layer "In11.Cu")
		(net "OCP_SFF_PRSNT0_R_N")
	)
	(segment
		(start 455.22388 -108.059728)
		(end 451.230746 -104.066594)
		(width 0.11684)
		(layer "In11.Cu")
		(net "OCP_SFF_PRSNT0_R_N")
	)
	(segment
		(start 442.685932 -84.371942)
		(end 424.899836 -84.371942)
		(width 0.11684)
		(layer "In11.Cu")
		(net "OCP_SFF_PRSNT0_R_N")
	)
	(segment
		(start 417.878514 -77.35062)
		(end 417.878514 -60.720224)
		(width 0.11684)
		(layer "In11.Cu")
		(net "OCP_SFF_PRSNT0_R_N")
	)
	(segment
		(start 417.878514 -60.720224)
		(end 415.555938 -58.397648)
		(width 0.11684)
		(layer "In11.Cu")
		(net "OCP_SFF_PRSNT0_R_N")
	)
	(segment
		(start 451.230746 -92.916756)
		(end 442.685932 -84.371942)
		(width 0.11684)
		(layer "In11.Cu")
		(net "OCP_SFF_PRSNT0_R_N")
	)
	(segment
		(start 451.230746 -104.066594)
		(end 451.230746 -92.916756)
		(width 0.11684)
		(layer "In11.Cu")
		(net "OCP_SFF_PRSNT0_R_N")
	)
	(segment
		(start 418.286692 -57.697878)
		(end 419.105842 -57.697878)
		(width 0.10668)
		(layer "F.Cu")
		(net "OCP_SFF_PRSNT01_R_N")
	)
	(via
		(at 11.934952 -82.439002)
		(size 0.6604)
		(drill 0.3302)
		(layers "F.Cu" "B.Cu")
		(net "OCP_SFF_PRSNT01_R_N")
	)
	(via
		(at 419.105842 -57.697878)
		(size 0.508)
		(drill 0.254)
		(layers "F.Cu" "B.Cu")
		(net "OCP_SFF_PRSNT01_R_N")
	)
	(via
		(at 179.359306 -87.781638)
		(size 0.508)
		(drill 0.254)
		(layers "F.Cu" "B.Cu")
		(net "OCP_SFF_PRSNT01_R_N")
	)
	(segment
		(start 177.694844 -86.117176)
		(end 170.828716 -86.117176)
		(width 0.10668)
		(layer "B.Cu")
		(net "OCP_SFF_PRSNT01_R_N")
	)
	(segment
		(start 136.858756 -85.621876)
		(end 133.941312 -82.704432)
		(width 0.10668)
		(layer "B.Cu")
		(net "OCP_SFF_PRSNT01_R_N")
	)
	(segment
		(start 12.200382 -82.704432)
		(end 11.934952 -82.439002)
		(width 0.10668)
		(layer "B.Cu")
		(net "OCP_SFF_PRSNT01_R_N")
	)
	(segment
		(start 170.333416 -85.621876)
		(end 136.858756 -85.621876)
		(width 0.10668)
		(layer "B.Cu")
		(net "OCP_SFF_PRSNT01_R_N")
	)
	(segment
		(start 133.941312 -82.704432)
		(end 12.200382 -82.704432)
		(width 0.10668)
		(layer "B.Cu")
		(net "OCP_SFF_PRSNT01_R_N")
	)
	(segment
		(start 179.359306 -87.781638)
		(end 177.694844 -86.117176)
		(width 0.10668)
		(layer "B.Cu")
		(net "OCP_SFF_PRSNT01_R_N")
	)
	(segment
		(start 11.934952 -82.439002)
		(end 11.049 -81.55305)
		(width 0.10668)
		(layer "B.Cu")
		(net "OCP_SFF_PRSNT01_R_N")
	)
	(segment
		(start 170.828716 -86.117176)
		(end 170.333416 -85.621876)
		(width 0.10668)
		(layer "B.Cu")
		(net "OCP_SFF_PRSNT01_R_N")
	)
	(segment
		(start 233.491532 -92.635578)
		(end 247.501664 -92.635578)
		(width 0.11684)
		(layer "In6.Cu")
		(net "OCP_SFF_PRSNT01_R_N")
	)
	(segment
		(start 202.057508 -87.94496)
		(end 205.886812 -91.774264)
		(width 0.11684)
		(layer "In6.Cu")
		(net "OCP_SFF_PRSNT01_R_N")
	)
	(segment
		(start 282.9814 -75.948794)
		(end 282.9814 -67.016376)
		(width 0.11684)
		(layer "In6.Cu")
		(net "OCP_SFF_PRSNT01_R_N")
	)
	(segment
		(start 390.103868 -58.88228)
		(end 417.92144 -58.88228)
		(width 0.11684)
		(layer "In6.Cu")
		(net "OCP_SFF_PRSNT01_R_N")
	)
	(segment
		(start 253.97841 -86.158832)
		(end 272.771362 -86.158832)
		(width 0.11684)
		(layer "In6.Cu")
		(net "OCP_SFF_PRSNT01_R_N")
	)
	(segment
		(start 205.886812 -91.774264)
		(end 232.630218 -91.774264)
		(width 0.11684)
		(layer "In6.Cu")
		(net "OCP_SFF_PRSNT01_R_N")
	)
	(segment
		(start 309.47106 -59.453018)
		(end 389.53313 -59.453018)
		(width 0.11684)
		(layer "In6.Cu")
		(net "OCP_SFF_PRSNT01_R_N")
	)
	(segment
		(start 389.53313 -59.453018)
		(end 390.103868 -58.88228)
		(width 0.11684)
		(layer "In6.Cu")
		(net "OCP_SFF_PRSNT01_R_N")
	)
	(segment
		(start 232.630218 -91.774264)
		(end 233.491532 -92.635578)
		(width 0.11684)
		(layer "In6.Cu")
		(net "OCP_SFF_PRSNT01_R_N")
	)
	(segment
		(start 282.9814 -67.016376)
		(end 289.691318 -60.306458)
		(width 0.11684)
		(layer "In6.Cu")
		(net "OCP_SFF_PRSNT01_R_N")
	)
	(segment
		(start 247.501664 -92.635578)
		(end 253.97841 -86.158832)
		(width 0.11684)
		(layer "In6.Cu")
		(net "OCP_SFF_PRSNT01_R_N")
	)
	(segment
		(start 194.474846 -87.94496)
		(end 202.057508 -87.94496)
		(width 0.11684)
		(layer "In6.Cu")
		(net "OCP_SFF_PRSNT01_R_N")
	)
	(segment
		(start 272.771362 -86.158832)
		(end 282.9814 -75.948794)
		(width 0.11684)
		(layer "In6.Cu")
		(net "OCP_SFF_PRSNT01_R_N")
	)
	(segment
		(start 180.442108 -86.698836)
		(end 193.228722 -86.698836)
		(width 0.11684)
		(layer "In6.Cu")
		(net "OCP_SFF_PRSNT01_R_N")
	)
	(segment
		(start 417.92144 -58.88228)
		(end 419.105842 -57.697878)
		(width 0.11684)
		(layer "In6.Cu")
		(net "OCP_SFF_PRSNT01_R_N")
	)
	(segment
		(start 193.228722 -86.698836)
		(end 194.474846 -87.94496)
		(width 0.11684)
		(layer "In6.Cu")
		(net "OCP_SFF_PRSNT01_R_N")
	)
	(segment
		(start 289.691318 -60.306458)
		(end 308.61762 -60.306458)
		(width 0.11684)
		(layer "In6.Cu")
		(net "OCP_SFF_PRSNT01_R_N")
	)
	(segment
		(start 308.61762 -60.306458)
		(end 309.47106 -59.453018)
		(width 0.11684)
		(layer "In6.Cu")
		(net "OCP_SFF_PRSNT01_R_N")
	)
	(segment
		(start 179.359306 -87.781638)
		(end 180.442108 -86.698836)
		(width 0.11684)
		(layer "In6.Cu")
		(net "OCP_SFF_PRSNT01_R_N")
	)
	(segment
		(start 152.884632 -96.262444)
		(end 151.339042 -96.262444)
		(width 0.10668)
		(layer "F.Cu")
		(net "OCP_SFF_NOT_PRSNT_RBT_ARB_IN")
	)
	(segment
		(start 151.339042 -96.262444)
		(end 150.430992 -97.170494)
		(width 0.10668)
		(layer "F.Cu")
		(net "OCP_SFF_NOT_PRSNT_RBT_ARB_IN")
	)
	(segment
		(start 152.884632 -99.005644)
		(end 150.430992 -99.005644)
		(width 0.10668)
		(layer "F.Cu")
		(net "OCP_SFF_NOT_PRSNT_RBT_ARB_IN")
	)
	(segment
		(start 150.430992 -97.170494)
		(end 150.430992 -99.005644)
		(width 0.10668)
		(layer "F.Cu")
		(net "OCP_SFF_NOT_PRSNT_RBT_ARB_IN")
	)
	(via
		(at 150.430992 -99.005644)
		(size 0.762)
		(drill 0.381)
		(layers "F.Cu" "B.Cu")
		(net "OCP_SFF_NOT_PRSNT_RBT_ARB_IN")
	)
	(segment
		(start 451.961758 -11.26998)
		(end 451.961758 -12.887452)
		(width 0.10668)
		(layer "F.Cu")
		(net "OCP_SFF_MAIN_PWR_EN_R")
	)
	(via
		(at 451.961758 -12.887452)
		(size 0.508)
		(drill 0.254)
		(layers "F.Cu" "B.Cu")
		(net "OCP_SFF_MAIN_PWR_EN_R")
	)
	(segment
		(start 451.961758 -12.887452)
		(end 453.143366 -11.705844)
		(width 0.10668)
		(layer "B.Cu")
		(net "OCP_SFF_MAIN_PWR_EN_R")
	)
	(segment
		(start 453.143366 -11.705844)
		(end 453.62241 -11.705844)
		(width 0.10668)
		(layer "B.Cu")
		(net "OCP_SFF_MAIN_PWR_EN_R")
	)
	(via
		(at 455.701146 -12.817094)
		(size 0.508)
		(drill 0.254)
		(layers "F.Cu" "B.Cu")
		(net "OCP_SFF_MAIN_PWR_EN")
	)
	(via
		(at 253.82728 -100.19792)
		(size 0.508)
		(drill 0.254)
		(layers "F.Cu" "B.Cu")
		(net "OCP_SFF_MAIN_PWR_EN")
	)
	(via
		(at 255.642872 -76.671678)
		(size 0.508)
		(drill 0.254)
		(layers "F.Cu" "B.Cu")
		(net "OCP_SFF_MAIN_PWR_EN")
	)
	(via
		(at 183.802528 -98.262948)
		(size 0.508)
		(drill 0.254)
		(layers "F.Cu" "B.Cu")
		(net "OCP_SFF_MAIN_PWR_EN")
	)
	(segment
		(start 455.084688 -11.845036)
		(end 454.945496 -11.705844)
		(width 0.10668)
		(layer "B.Cu")
		(net "OCP_SFF_MAIN_PWR_EN")
	)
	(segment
		(start 455.701146 -12.817094)
		(end 455.198988 -12.817094)
		(width 0.10668)
		(layer "B.Cu")
		(net "OCP_SFF_MAIN_PWR_EN")
	)
	(segment
		(start 184.042304 -99.894898)
		(end 183.769 -99.894898)
		(width 0.10668)
		(layer "B.Cu")
		(net "OCP_SFF_MAIN_PWR_EN")
	)
	(segment
		(start 184.26684 -98.72726)
		(end 184.26684 -99.670362)
		(width 0.10668)
		(layer "B.Cu")
		(net "OCP_SFF_MAIN_PWR_EN")
	)
	(segment
		(start 184.26684 -99.670362)
		(end 184.042304 -99.894898)
		(width 0.10668)
		(layer "B.Cu")
		(net "OCP_SFF_MAIN_PWR_EN")
	)
	(segment
		(start 183.802528 -98.262948)
		(end 184.26684 -98.72726)
		(width 0.10668)
		(layer "B.Cu")
		(net "OCP_SFF_MAIN_PWR_EN")
	)
	(segment
		(start 455.198988 -12.817094)
		(end 455.084688 -12.702794)
		(width 0.10668)
		(layer "B.Cu")
		(net "OCP_SFF_MAIN_PWR_EN")
	)
	(segment
		(start 455.084688 -12.702794)
		(end 455.084688 -11.845036)
		(width 0.10668)
		(layer "B.Cu")
		(net "OCP_SFF_MAIN_PWR_EN")
	)
	(segment
		(start 454.945496 -11.705844)
		(end 454.42251 -11.705844)
		(width 0.10668)
		(layer "B.Cu")
		(net "OCP_SFF_MAIN_PWR_EN")
	)
	(segment
		(start 256.106676 -77.135482)
		(end 255.642872 -76.671678)
		(width 0.11684)
		(layer "In4.Cu")
		(net "OCP_SFF_MAIN_PWR_EN")
	)
	(segment
		(start 255.009396 -92.112084)
		(end 256.106676 -91.014804)
		(width 0.11684)
		(layer "In4.Cu")
		(net "OCP_SFF_MAIN_PWR_EN")
	)
	(segment
		(start 256.106676 -91.014804)
		(end 256.106676 -77.135482)
		(width 0.11684)
		(layer "In4.Cu")
		(net "OCP_SFF_MAIN_PWR_EN")
	)
	(segment
		(start 254.160274 -100.19792)
		(end 255.009396 -99.348798)
		(width 0.11684)
		(layer "In4.Cu")
		(net "OCP_SFF_MAIN_PWR_EN")
	)
	(segment
		(start 253.82728 -100.19792)
		(end 254.160274 -100.19792)
		(width 0.11684)
		(layer "In4.Cu")
		(net "OCP_SFF_MAIN_PWR_EN")
	)
	(segment
		(start 255.009396 -99.348798)
		(end 255.009396 -92.112084)
		(width 0.11684)
		(layer "In4.Cu")
		(net "OCP_SFF_MAIN_PWR_EN")
	)
	(segment
		(start 184.066942 -98.262948)
		(end 184.543192 -97.786698)
		(width 0.11684)
		(layer "In6.Cu")
		(net "OCP_SFF_MAIN_PWR_EN")
	)
	(segment
		(start 220.644212 -99.920298)
		(end 221.466156 -100.742242)
		(width 0.11684)
		(layer "In6.Cu")
		(net "OCP_SFF_MAIN_PWR_EN")
	)
	(segment
		(start 253.282958 -100.742242)
		(end 253.82728 -100.19792)
		(width 0.11684)
		(layer "In6.Cu")
		(net "OCP_SFF_MAIN_PWR_EN")
	)
	(segment
		(start 184.543192 -97.786698)
		(end 197.982586 -97.786698)
		(width 0.11684)
		(layer "In6.Cu")
		(net "OCP_SFF_MAIN_PWR_EN")
	)
	(segment
		(start 210.22564 -100.75926)
		(end 211.995004 -100.75926)
		(width 0.11684)
		(layer "In6.Cu")
		(net "OCP_SFF_MAIN_PWR_EN")
	)
	(segment
		(start 215.000586 -99.920298)
		(end 220.644212 -99.920298)
		(width 0.11684)
		(layer "In6.Cu")
		(net "OCP_SFF_MAIN_PWR_EN")
	)
	(segment
		(start 211.995004 -100.75926)
		(end 212.29955 -100.454714)
		(width 0.11684)
		(layer "In6.Cu")
		(net "OCP_SFF_MAIN_PWR_EN")
	)
	(segment
		(start 212.29955 -100.454714)
		(end 214.46617 -100.454714)
		(width 0.11684)
		(layer "In6.Cu")
		(net "OCP_SFF_MAIN_PWR_EN")
	)
	(segment
		(start 209.891884 -101.093016)
		(end 210.22564 -100.75926)
		(width 0.11684)
		(layer "In6.Cu")
		(net "OCP_SFF_MAIN_PWR_EN")
	)
	(segment
		(start 197.982586 -97.786698)
		(end 201.288904 -101.093016)
		(width 0.11684)
		(layer "In6.Cu")
		(net "OCP_SFF_MAIN_PWR_EN")
	)
	(segment
		(start 221.466156 -100.742242)
		(end 253.282958 -100.742242)
		(width 0.11684)
		(layer "In6.Cu")
		(net "OCP_SFF_MAIN_PWR_EN")
	)
	(segment
		(start 183.802528 -98.262948)
		(end 184.066942 -98.262948)
		(width 0.11684)
		(layer "In6.Cu")
		(net "OCP_SFF_MAIN_PWR_EN")
	)
	(segment
		(start 201.288904 -101.093016)
		(end 209.891884 -101.093016)
		(width 0.11684)
		(layer "In6.Cu")
		(net "OCP_SFF_MAIN_PWR_EN")
	)
	(segment
		(start 214.46617 -100.454714)
		(end 215.000586 -99.920298)
		(width 0.11684)
		(layer "In6.Cu")
		(net "OCP_SFF_MAIN_PWR_EN")
	)
	(segment
		(start 451.752208 -8.868156)
		(end 455.701146 -12.817094)
		(width 0.11684)
		(layer "In15.Cu")
		(net "OCP_SFF_MAIN_PWR_EN")
	)
	(segment
		(start 324.653402 -19.242024)
		(end 327.874122 -16.021304)
		(width 0.11684)
		(layer "In15.Cu")
		(net "OCP_SFF_MAIN_PWR_EN")
	)
	(segment
		(start 283.61767 -64.47282)
		(end 283.61767 -50.264822)
		(width 0.11684)
		(layer "In15.Cu")
		(net "OCP_SFF_MAIN_PWR_EN")
	)
	(segment
		(start 357.716836 -18.940018)
		(end 375.483882 -18.940018)
		(width 0.11684)
		(layer "In15.Cu")
		(net "OCP_SFF_MAIN_PWR_EN")
	)
	(segment
		(start 276.140418 -71.950072)
		(end 283.61767 -64.47282)
		(width 0.11684)
		(layer "In15.Cu")
		(net "OCP_SFF_MAIN_PWR_EN")
	)
	(segment
		(start 423.401236 -9.440926)
		(end 423.974006 -8.868156)
		(width 0.11684)
		(layer "In15.Cu")
		(net "OCP_SFF_MAIN_PWR_EN")
	)
	(segment
		(start 327.874122 -16.021304)
		(end 354.798122 -16.021304)
		(width 0.11684)
		(layer "In15.Cu")
		(net "OCP_SFF_MAIN_PWR_EN")
	)
	(segment
		(start 324.653402 -24.179784)
		(end 324.653402 -19.242024)
		(width 0.11684)
		(layer "In15.Cu")
		(net "OCP_SFF_MAIN_PWR_EN")
	)
	(segment
		(start 283.61767 -50.264822)
		(end 304.72888 -29.153612)
		(width 0.11684)
		(layer "In15.Cu")
		(net "OCP_SFF_MAIN_PWR_EN")
	)
	(segment
		(start 319.679574 -29.153612)
		(end 324.653402 -24.179784)
		(width 0.11684)
		(layer "In15.Cu")
		(net "OCP_SFF_MAIN_PWR_EN")
	)
	(segment
		(start 262.034528 -71.950072)
		(end 276.140418 -71.950072)
		(width 0.11684)
		(layer "In15.Cu")
		(net "OCP_SFF_MAIN_PWR_EN")
	)
	(segment
		(start 255.642872 -76.671678)
		(end 255.66243 -76.65212)
		(width 0.11684)
		(layer "In15.Cu")
		(net "OCP_SFF_MAIN_PWR_EN")
	)
	(segment
		(start 421.002968 -16.021304)
		(end 423.401236 -13.623036)
		(width 0.11684)
		(layer "In15.Cu")
		(net "OCP_SFF_MAIN_PWR_EN")
	)
	(segment
		(start 257.33248 -76.65212)
		(end 262.034528 -71.950072)
		(width 0.11684)
		(layer "In15.Cu")
		(net "OCP_SFF_MAIN_PWR_EN")
	)
	(segment
		(start 423.974006 -8.868156)
		(end 451.752208 -8.868156)
		(width 0.11684)
		(layer "In15.Cu")
		(net "OCP_SFF_MAIN_PWR_EN")
	)
	(segment
		(start 375.483882 -18.940018)
		(end 378.402596 -16.021304)
		(width 0.11684)
		(layer "In15.Cu")
		(net "OCP_SFF_MAIN_PWR_EN")
	)
	(segment
		(start 354.798122 -16.021304)
		(end 357.716836 -18.940018)
		(width 0.11684)
		(layer "In15.Cu")
		(net "OCP_SFF_MAIN_PWR_EN")
	)
	(segment
		(start 255.66243 -76.65212)
		(end 257.33248 -76.65212)
		(width 0.11684)
		(layer "In15.Cu")
		(net "OCP_SFF_MAIN_PWR_EN")
	)
	(segment
		(start 423.401236 -13.623036)
		(end 423.401236 -9.440926)
		(width 0.11684)
		(layer "In15.Cu")
		(net "OCP_SFF_MAIN_PWR_EN")
	)
	(segment
		(start 378.402596 -16.021304)
		(end 421.002968 -16.021304)
		(width 0.11684)
		(layer "In15.Cu")
		(net "OCP_SFF_MAIN_PWR_EN")
	)
	(segment
		(start 304.72888 -29.153612)
		(end 319.679574 -29.153612)
		(width 0.11684)
		(layer "In15.Cu")
		(net "OCP_SFF_MAIN_PWR_EN")
	)
	(segment
		(start 436.005732 -16.599916)
		(end 436.005732 -17.237964)
		(width 0.10668)
		(layer "F.Cu")
		(net "OCP_SFF_ISO_BIF2_EN")
	)
	(via
		(at 436.005732 -17.237964)
		(size 0.508)
		(drill 0.254)
		(layers "F.Cu" "B.Cu")
		(net "OCP_SFF_ISO_BIF2_EN")
	)
	(segment
		(start 436.997348 -18.22958)
		(end 436.005732 -17.237964)
		(width 0.10668)
		(layer "B.Cu")
		(net "OCP_SFF_ISO_BIF2_EN")
	)
	(segment
		(start 436.997348 -18.67662)
		(end 436.997348 -18.22958)
		(width 0.10668)
		(layer "B.Cu")
		(net "OCP_SFF_ISO_BIF2_EN")
	)
	(segment
		(start 435.022244 -28.424632)
		(end 435.022244 -22.658832)
		(width 0.10668)
		(layer "F.Cu")
		(net "OCP_SFF_ISO_BIF1_EN")
	)
	(segment
		(start 436.100474 -21.580602)
		(end 436.100474 -20.02282)
		(width 0.10668)
		(layer "F.Cu")
		(net "OCP_SFF_ISO_BIF1_EN")
	)
	(segment
		(start 435.022244 -22.658832)
		(end 436.100474 -21.580602)
		(width 0.10668)
		(layer "F.Cu")
		(net "OCP_SFF_ISO_BIF1_EN")
	)
	(via
		(at 435.022244 -28.424632)
		(size 0.508)
		(drill 0.254)
		(layers "F.Cu" "B.Cu")
		(net "OCP_SFF_ISO_BIF1_EN")
	)
	(segment
		(start 435.050946 -27.286458)
		(end 435.050946 -28.39593)
		(width 0.10668)
		(layer "B.Cu")
		(net "OCP_SFF_ISO_BIF1_EN")
	)
	(segment
		(start 435.050946 -28.39593)
		(end 435.022244 -28.424632)
		(width 0.10668)
		(layer "B.Cu")
		(net "OCP_SFF_ISO_BIF1_EN")
	)
	(segment
		(start 437.221376 -17.224502)
		(end 437.298084 -17.30121)
		(width 0.10668)
		(layer "F.Cu")
		(net "OCP_SFF_ISO_BIF0_EN")
	)
	(segment
		(start 437.221376 -16.644874)
		(end 437.221376 -17.224502)
		(width 0.10668)
		(layer "F.Cu")
		(net "OCP_SFF_ISO_BIF0_EN")
	)
	(via
		(at 437.298084 -17.30121)
		(size 0.508)
		(drill 0.254)
		(layers "F.Cu" "B.Cu")
		(net "OCP_SFF_ISO_BIF0_EN")
	)
	(segment
		(start 438.013348 -18.016474)
		(end 437.298084 -17.30121)
		(width 0.10668)
		(layer "B.Cu")
		(net "OCP_SFF_ISO_BIF0_EN")
	)
	(segment
		(start 438.013348 -18.67662)
		(end 438.013348 -18.016474)
		(width 0.10668)
		(layer "B.Cu")
		(net "OCP_SFF_ISO_BIF0_EN")
	)
	(segment
		(start 450.36867 -4.880864)
		(end 449.81368 -4.325874)
		(width 0.10668)
		(layer "F.Cu")
		(net "OCP_SFF_ISO2_RBT_ARB_OUT")
	)
	(segment
		(start 450.161914 -8.320024)
		(end 450.161914 -6.226048)
		(width 0.10668)
		(layer "F.Cu")
		(net "OCP_SFF_ISO2_RBT_ARB_OUT")
	)
	(segment
		(start 450.161914 -6.226048)
		(end 450.36867 -6.019292)
		(width 0.10668)
		(layer "F.Cu")
		(net "OCP_SFF_ISO2_RBT_ARB_OUT")
	)
	(segment
		(start 450.36867 -6.019292)
		(end 450.36867 -4.880864)
		(width 0.10668)
		(layer "F.Cu")
		(net "OCP_SFF_ISO2_RBT_ARB_OUT")
	)
	(via
		(at 449.81368 -4.325874)
		(size 0.508)
		(drill 0.254)
		(layers "F.Cu" "B.Cu")
		(net "OCP_SFF_ISO2_RBT_ARB_OUT")
	)
	(via
		(at 209.059018 -69.39915)
		(size 0.508)
		(drill 0.254)
		(layers "F.Cu" "B.Cu")
		(net "OCP_SFF_ISO2_RBT_ARB_OUT")
	)
	(segment
		(start 207.91805 -69.530468)
		(end 208.9277 -69.530468)
		(width 0.10668)
		(layer "B.Cu")
		(net "OCP_SFF_ISO2_RBT_ARB_OUT")
	)
	(segment
		(start 208.9277 -69.530468)
		(end 209.059018 -69.39915)
		(width 0.10668)
		(layer "B.Cu")
		(net "OCP_SFF_ISO2_RBT_ARB_OUT")
	)
	(segment
		(start 421.527732 -7.011924)
		(end 425.096686 -3.44297)
		(width 0.11684)
		(layer "In15.Cu")
		(net "OCP_SFF_ISO2_RBT_ARB_OUT")
	)
	(segment
		(start 374.784874 -17.253458)
		(end 377.703588 -14.334744)
		(width 0.11684)
		(layer "In15.Cu")
		(net "OCP_SFF_ISO2_RBT_ARB_OUT")
	)
	(segment
		(start 233.81208 -73.130664)
		(end 256.71145 -73.130664)
		(width 0.11684)
		(layer "In15.Cu")
		(net "OCP_SFF_ISO2_RBT_ARB_OUT")
	)
	(segment
		(start 439.507376 -5.42925)
		(end 444.8937 -5.42925)
		(width 0.11684)
		(layer "In15.Cu")
		(net "OCP_SFF_ISO2_RBT_ARB_OUT")
	)
	(segment
		(start 444.8937 -5.42925)
		(end 446.734184 -3.588766)
		(width 0.11684)
		(layer "In15.Cu")
		(net "OCP_SFF_ISO2_RBT_ARB_OUT")
	)
	(segment
		(start 281.93111 -49.565814)
		(end 304.046636 -27.450288)
		(width 0.11684)
		(layer "In15.Cu")
		(net "OCP_SFF_ISO2_RBT_ARB_OUT")
	)
	(segment
		(start 256.71145 -73.130664)
		(end 259.595874 -70.24624)
		(width 0.11684)
		(layer "In15.Cu")
		(net "OCP_SFF_ISO2_RBT_ARB_OUT")
	)
	(segment
		(start 281.93111 -63.70574)
		(end 281.93111 -49.565814)
		(width 0.11684)
		(layer "In15.Cu")
		(net "OCP_SFF_ISO2_RBT_ARB_OUT")
	)
	(segment
		(start 355.49713 -14.334744)
		(end 358.415844 -17.253458)
		(width 0.11684)
		(layer "In15.Cu")
		(net "OCP_SFF_ISO2_RBT_ARB_OUT")
	)
	(segment
		(start 449.076572 -3.588766)
		(end 449.81368 -4.325874)
		(width 0.11684)
		(layer "In15.Cu")
		(net "OCP_SFF_ISO2_RBT_ARB_OUT")
	)
	(segment
		(start 358.415844 -17.253458)
		(end 374.784874 -17.253458)
		(width 0.11684)
		(layer "In15.Cu")
		(net "OCP_SFF_ISO2_RBT_ARB_OUT")
	)
	(segment
		(start 304.046636 -27.450288)
		(end 318.99733 -27.450288)
		(width 0.11684)
		(layer "In15.Cu")
		(net "OCP_SFF_ISO2_RBT_ARB_OUT")
	)
	(segment
		(start 421.527732 -13.088112)
		(end 421.527732 -7.011924)
		(width 0.11684)
		(layer "In15.Cu")
		(net "OCP_SFF_ISO2_RBT_ARB_OUT")
	)
	(segment
		(start 212.82533 -65.632838)
		(end 226.314254 -65.632838)
		(width 0.11684)
		(layer "In15.Cu")
		(net "OCP_SFF_ISO2_RBT_ARB_OUT")
	)
	(segment
		(start 420.2811 -14.334744)
		(end 421.527732 -13.088112)
		(width 0.11684)
		(layer "In15.Cu")
		(net "OCP_SFF_ISO2_RBT_ARB_OUT")
	)
	(segment
		(start 327.175114 -14.334744)
		(end 355.49713 -14.334744)
		(width 0.11684)
		(layer "In15.Cu")
		(net "OCP_SFF_ISO2_RBT_ARB_OUT")
	)
	(segment
		(start 446.734184 -3.588766)
		(end 449.076572 -3.588766)
		(width 0.11684)
		(layer "In15.Cu")
		(net "OCP_SFF_ISO2_RBT_ARB_OUT")
	)
	(segment
		(start 259.595874 -70.24624)
		(end 275.39061 -70.24624)
		(width 0.11684)
		(layer "In15.Cu")
		(net "OCP_SFF_ISO2_RBT_ARB_OUT")
	)
	(segment
		(start 209.059018 -69.39915)
		(end 212.82533 -65.632838)
		(width 0.11684)
		(layer "In15.Cu")
		(net "OCP_SFF_ISO2_RBT_ARB_OUT")
	)
	(segment
		(start 226.314254 -65.632838)
		(end 233.81208 -73.130664)
		(width 0.11684)
		(layer "In15.Cu")
		(net "OCP_SFF_ISO2_RBT_ARB_OUT")
	)
	(segment
		(start 425.096686 -3.44297)
		(end 437.521096 -3.44297)
		(width 0.11684)
		(layer "In15.Cu")
		(net "OCP_SFF_ISO2_RBT_ARB_OUT")
	)
	(segment
		(start 437.521096 -3.44297)
		(end 439.507376 -5.42925)
		(width 0.11684)
		(layer "In15.Cu")
		(net "OCP_SFF_ISO2_RBT_ARB_OUT")
	)
	(segment
		(start 322.113656 -24.333962)
		(end 322.113656 -19.396202)
		(width 0.11684)
		(layer "In15.Cu")
		(net "OCP_SFF_ISO2_RBT_ARB_OUT")
	)
	(segment
		(start 275.39061 -70.24624)
		(end 281.93111 -63.70574)
		(width 0.11684)
		(layer "In15.Cu")
		(net "OCP_SFF_ISO2_RBT_ARB_OUT")
	)
	(segment
		(start 318.99733 -27.450288)
		(end 322.113656 -24.333962)
		(width 0.11684)
		(layer "In15.Cu")
		(net "OCP_SFF_ISO2_RBT_ARB_OUT")
	)
	(segment
		(start 322.113656 -19.396202)
		(end 327.175114 -14.334744)
		(width 0.11684)
		(layer "In15.Cu")
		(net "OCP_SFF_ISO2_RBT_ARB_OUT")
	)
	(segment
		(start 377.703588 -14.334744)
		(end 420.2811 -14.334744)
		(width 0.11684)
		(layer "In15.Cu")
		(net "OCP_SFF_ISO2_RBT_ARB_OUT")
	)
	(segment
		(start 450.761862 -7.377176)
		(end 450.62394 -7.239254)
		(width 0.10668)
		(layer "F.Cu")
		(net "OCP_SFF_ISO1_RBT_ARB_IN")
	)
	(segment
		(start 450.761862 -8.320024)
		(end 450.761862 -7.377176)
		(width 0.10668)
		(layer "F.Cu")
		(net "OCP_SFF_ISO1_RBT_ARB_IN")
	)
	(segment
		(start 451.05066 -4.325874)
		(end 451.08368 -4.325874)
		(width 0.10668)
		(layer "F.Cu")
		(net "OCP_SFF_ISO1_RBT_ARB_IN")
	)
	(segment
		(start 450.62394 -4.752594)
		(end 451.05066 -4.325874)
		(width 0.10668)
		(layer "F.Cu")
		(net "OCP_SFF_ISO1_RBT_ARB_IN")
	)
	(segment
		(start 450.62394 -7.239254)
		(end 450.62394 -4.752594)
		(width 0.10668)
		(layer "F.Cu")
		(net "OCP_SFF_ISO1_RBT_ARB_IN")
	)
	(via
		(at 451.08368 -4.325874)
		(size 0.508)
		(drill 0.254)
		(layers "F.Cu" "B.Cu")
		(net "OCP_SFF_ISO1_RBT_ARB_IN")
	)
	(via
		(at 192.515998 -77.192632)
		(size 0.508)
		(drill 0.254)
		(layers "F.Cu" "B.Cu")
		(net "OCP_SFF_ISO1_RBT_ARB_IN")
	)
	(segment
		(start 194.304158 -77.192632)
		(end 192.515998 -77.192632)
		(width 0.10668)
		(layer "B.Cu")
		(net "OCP_SFF_ISO1_RBT_ARB_IN")
	)
	(segment
		(start 318.864742 -27.130248)
		(end 321.793616 -24.201374)
		(width 0.11684)
		(layer "In15.Cu")
		(net "OCP_SFF_ISO1_RBT_ARB_IN")
	)
	(segment
		(start 421.207692 -12.955524)
		(end 421.207692 -6.879336)
		(width 0.11684)
		(layer "In15.Cu")
		(net "OCP_SFF_ISO1_RBT_ARB_IN")
	)
	(segment
		(start 444.760858 -5.10921)
		(end 446.651126 -3.218942)
		(width 0.11684)
		(layer "In15.Cu")
		(net "OCP_SFF_ISO1_RBT_ARB_IN")
	)
	(segment
		(start 446.651126 -3.218942)
		(end 449.976748 -3.218942)
		(width 0.11684)
		(layer "In15.Cu")
		(net "OCP_SFF_ISO1_RBT_ARB_IN")
	)
	(segment
		(start 199.460358 -66.623184)
		(end 201.35723 -64.726312)
		(width 0.11684)
		(layer "In15.Cu")
		(net "OCP_SFF_ISO1_RBT_ARB_IN")
	)
	(segment
		(start 421.207692 -6.879336)
		(end 424.964098 -3.12293)
		(width 0.11684)
		(layer "In15.Cu")
		(net "OCP_SFF_ISO1_RBT_ARB_IN")
	)
	(segment
		(start 377.571 -14.014704)
		(end 420.148512 -14.014704)
		(width 0.11684)
		(layer "In15.Cu")
		(net "OCP_SFF_ISO1_RBT_ARB_IN")
	)
	(segment
		(start 256.578862 -72.810624)
		(end 259.463286 -69.9262)
		(width 0.11684)
		(layer "In15.Cu")
		(net "OCP_SFF_ISO1_RBT_ARB_IN")
	)
	(segment
		(start 201.35723 -64.726312)
		(end 225.860356 -64.726312)
		(width 0.11684)
		(layer "In15.Cu")
		(net "OCP_SFF_ISO1_RBT_ARB_IN")
	)
	(segment
		(start 374.652286 -16.933418)
		(end 377.571 -14.014704)
		(width 0.11684)
		(layer "In15.Cu")
		(net "OCP_SFF_ISO1_RBT_ARB_IN")
	)
	(segment
		(start 225.860356 -64.726312)
		(end 233.944668 -72.810624)
		(width 0.11684)
		(layer "In15.Cu")
		(net "OCP_SFF_ISO1_RBT_ARB_IN")
	)
	(segment
		(start 188.549026 -76.319888)
		(end 188.549026 -67.221862)
		(width 0.11684)
		(layer "In15.Cu")
		(net "OCP_SFF_ISO1_RBT_ARB_IN")
	)
	(segment
		(start 192.515998 -77.192632)
		(end 189.42177 -77.192632)
		(width 0.11684)
		(layer "In15.Cu")
		(net "OCP_SFF_ISO1_RBT_ARB_IN")
	)
	(segment
		(start 327.042526 -14.014704)
		(end 355.629718 -14.014704)
		(width 0.11684)
		(layer "In15.Cu")
		(net "OCP_SFF_ISO1_RBT_ARB_IN")
	)
	(segment
		(start 358.548432 -16.933418)
		(end 374.652286 -16.933418)
		(width 0.11684)
		(layer "In15.Cu")
		(net "OCP_SFF_ISO1_RBT_ARB_IN")
	)
	(segment
		(start 355.629718 -14.014704)
		(end 358.548432 -16.933418)
		(width 0.11684)
		(layer "In15.Cu")
		(net "OCP_SFF_ISO1_RBT_ARB_IN")
	)
	(segment
		(start 303.914048 -27.130248)
		(end 318.864742 -27.130248)
		(width 0.11684)
		(layer "In15.Cu")
		(net "OCP_SFF_ISO1_RBT_ARB_IN")
	)
	(segment
		(start 259.463286 -69.9262)
		(end 275.258022 -69.9262)
		(width 0.11684)
		(layer "In15.Cu")
		(net "OCP_SFF_ISO1_RBT_ARB_IN")
	)
	(segment
		(start 189.147704 -66.623184)
		(end 199.460358 -66.623184)
		(width 0.11684)
		(layer "In15.Cu")
		(net "OCP_SFF_ISO1_RBT_ARB_IN")
	)
	(segment
		(start 233.944668 -72.810624)
		(end 256.578862 -72.810624)
		(width 0.11684)
		(layer "In15.Cu")
		(net "OCP_SFF_ISO1_RBT_ARB_IN")
	)
	(segment
		(start 188.549026 -67.221862)
		(end 189.147704 -66.623184)
		(width 0.11684)
		(layer "In15.Cu")
		(net "OCP_SFF_ISO1_RBT_ARB_IN")
	)
	(segment
		(start 281.61107 -49.433226)
		(end 303.914048 -27.130248)
		(width 0.11684)
		(layer "In15.Cu")
		(net "OCP_SFF_ISO1_RBT_ARB_IN")
	)
	(segment
		(start 321.793616 -19.263614)
		(end 327.042526 -14.014704)
		(width 0.11684)
		(layer "In15.Cu")
		(net "OCP_SFF_ISO1_RBT_ARB_IN")
	)
	(segment
		(start 439.639964 -5.10921)
		(end 444.760858 -5.10921)
		(width 0.11684)
		(layer "In15.Cu")
		(net "OCP_SFF_ISO1_RBT_ARB_IN")
	)
	(segment
		(start 275.258022 -69.9262)
		(end 281.61107 -63.573152)
		(width 0.11684)
		(layer "In15.Cu")
		(net "OCP_SFF_ISO1_RBT_ARB_IN")
	)
	(segment
		(start 437.653684 -3.12293)
		(end 439.639964 -5.10921)
		(width 0.11684)
		(layer "In15.Cu")
		(net "OCP_SFF_ISO1_RBT_ARB_IN")
	)
	(segment
		(start 420.148512 -14.014704)
		(end 421.207692 -12.955524)
		(width 0.11684)
		(layer "In15.Cu")
		(net "OCP_SFF_ISO1_RBT_ARB_IN")
	)
	(segment
		(start 449.976748 -3.218942)
		(end 451.08368 -4.325874)
		(width 0.11684)
		(layer "In15.Cu")
		(net "OCP_SFF_ISO1_RBT_ARB_IN")
	)
	(segment
		(start 281.61107 -63.573152)
		(end 281.61107 -49.433226)
		(width 0.11684)
		(layer "In15.Cu")
		(net "OCP_SFF_ISO1_RBT_ARB_IN")
	)
	(segment
		(start 424.964098 -3.12293)
		(end 437.653684 -3.12293)
		(width 0.11684)
		(layer "In15.Cu")
		(net "OCP_SFF_ISO1_RBT_ARB_IN")
	)
	(segment
		(start 189.42177 -77.192632)
		(end 188.549026 -76.319888)
		(width 0.11684)
		(layer "In15.Cu")
		(net "OCP_SFF_ISO1_RBT_ARB_IN")
	)
	(segment
		(start 321.793616 -24.201374)
		(end 321.793616 -19.263614)
		(width 0.11684)
		(layer "In15.Cu")
		(net "OCP_SFF_ISO1_RBT_ARB_IN")
	)
	(segment
		(start 449.561966 -8.320024)
		(end 449.561966 -5.847588)
		(width 0.10668)
		(layer "F.Cu")
		(net "OCP_SFF_ID1")
	)
	(segment
		(start 449.561966 -5.847588)
		(end 449.81368 -5.595874)
		(width 0.10668)
		(layer "F.Cu")
		(net "OCP_SFF_ID1")
	)
	(via
		(at 449.81368 -5.595874)
		(size 0.508)
		(drill 0.254)
		(layers "F.Cu" "B.Cu")
		(net "OCP_SFF_ID1")
	)
	(segment
		(start 450.534278 -7.95655)
		(end 449.518278 -7.95655)
		(width 0.10668)
		(layer "B.Cu")
		(net "OCP_SFF_ID1")
	)
	(segment
		(start 449.479924 -5.92963)
		(end 449.81368 -5.595874)
		(width 0.10668)
		(layer "B.Cu")
		(net "OCP_SFF_ID1")
	)
	(segment
		(start 449.479924 -7.918196)
		(end 449.479924 -5.92963)
		(width 0.10668)
		(layer "B.Cu")
		(net "OCP_SFF_ID1")
	)
	(segment
		(start 449.518278 -7.95655)
		(end 449.479924 -7.918196)
		(width 0.10668)
		(layer "B.Cu")
		(net "OCP_SFF_ID1")
	)
	(segment
		(start 448.961764 -11.26998)
		(end 448.961764 -12.305792)
		(width 0.10668)
		(layer "F.Cu")
		(net "OCP_SFF_ID0")
	)
	(segment
		(start 448.961764 -12.305792)
		(end 448.885564 -12.381992)
		(width 0.10668)
		(layer "F.Cu")
		(net "OCP_SFF_ID0")
	)
	(via
		(at 448.885564 -12.381992)
		(size 0.508)
		(drill 0.254)
		(layers "F.Cu" "B.Cu")
		(net "OCP_SFF_ID0")
	)
	(segment
		(start 448.579748 -12.134596)
		(end 448.827144 -12.381992)
		(width 0.10668)
		(layer "B.Cu")
		(net "OCP_SFF_ID0")
	)
	(segment
		(start 447.563748 -10.967212)
		(end 448.579748 -10.967212)
		(width 0.10668)
		(layer "B.Cu")
		(net "OCP_SFF_ID0")
	)
	(segment
		(start 448.827144 -12.381992)
		(end 448.885564 -12.381992)
		(width 0.10668)
		(layer "B.Cu")
		(net "OCP_SFF_ID0")
	)
	(segment
		(start 448.579748 -10.967212)
		(end 448.579748 -12.134596)
		(width 0.10668)
		(layer "B.Cu")
		(net "OCP_SFF_ID0")
	)
	(segment
		(start 435.56682 -11.26998)
		(end 435.56682 -12.856972)
		(width 0.10668)
		(layer "F.Cu")
		(net "OCP_SFF_BIF2_R_N")
	)
	(segment
		(start 434.991764 -14.502892)
		(end 436.005732 -15.51686)
		(width 0.10668)
		(layer "F.Cu")
		(net "OCP_SFF_BIF2_R_N")
	)
	(segment
		(start 434.991764 -13.432028)
		(end 434.991764 -14.502892)
		(width 0.10668)
		(layer "F.Cu")
		(net "OCP_SFF_BIF2_R_N")
	)
	(segment
		(start 435.56682 -12.856972)
		(end 434.991764 -13.432028)
		(width 0.10668)
		(layer "F.Cu")
		(net "OCP_SFF_BIF2_R_N")
	)
	(segment
		(start 436.005732 -15.51686)
		(end 436.005732 -15.799816)
		(width 0.10668)
		(layer "F.Cu")
		(net "OCP_SFF_BIF2_R_N")
	)
	(via
		(at 434.991764 -14.502892)
		(size 0.762)
		(drill 0.381)
		(layers "F.Cu" "B.Cu")
		(net "OCP_SFF_BIF2_R_N")
	)
	(segment
		(start 436.166768 -13.645896)
		(end 436.166768 -11.26998)
		(width 0.10668)
		(layer "F.Cu")
		(net "OCP_SFF_BIF1_R_N")
	)
	(segment
		(start 436.55742 -18.765774)
		(end 436.55742 -14.798548)
		(width 0.10668)
		(layer "F.Cu")
		(net "OCP_SFF_BIF1_R_N")
	)
	(segment
		(start 436.55742 -14.798548)
		(end 436.261764 -14.502892)
		(width 0.10668)
		(layer "F.Cu")
		(net "OCP_SFF_BIF1_R_N")
	)
	(segment
		(start 436.261764 -13.740892)
		(end 436.166768 -13.645896)
		(width 0.10668)
		(layer "F.Cu")
		(net "OCP_SFF_BIF1_R_N")
	)
	(segment
		(start 436.261764 -14.502892)
		(end 436.261764 -13.740892)
		(width 0.10668)
		(layer "F.Cu")
		(net "OCP_SFF_BIF1_R_N")
	)
	(segment
		(start 436.100474 -19.22272)
		(end 436.55742 -18.765774)
		(width 0.10668)
		(layer "F.Cu")
		(net "OCP_SFF_BIF1_R_N")
	)
	(via
		(at 436.261764 -14.502892)
		(size 0.762)
		(drill 0.381)
		(layers "F.Cu" "B.Cu")
		(net "OCP_SFF_BIF1_R_N")
	)
	(segment
		(start 437.531764 -13.986764)
		(end 436.76697 -13.22197)
		(width 0.10668)
		(layer "F.Cu")
		(net "OCP_SFF_BIF0_R_N")
	)
	(segment
		(start 436.76697 -13.22197)
		(end 436.76697 -11.26998)
		(width 0.10668)
		(layer "F.Cu")
		(net "OCP_SFF_BIF0_R_N")
	)
	(segment
		(start 437.221376 -15.844774)
		(end 437.221376 -14.81328)
		(width 0.10668)
		(layer "F.Cu")
		(net "OCP_SFF_BIF0_R_N")
	)
	(segment
		(start 437.531764 -14.502892)
		(end 437.531764 -13.986764)
		(width 0.10668)
		(layer "F.Cu")
		(net "OCP_SFF_BIF0_R_N")
	)
	(segment
		(start 437.221376 -14.81328)
		(end 437.531764 -14.502892)
		(width 0.10668)
		(layer "F.Cu")
		(net "OCP_SFF_BIF0_R_N")
	)
	(via
		(at 437.531764 -14.502892)
		(size 0.762)
		(drill 0.381)
		(layers "F.Cu" "B.Cu")
		(net "OCP_SFF_BIF0_R_N")
	)
	(segment
		(start 457.253848 -99.164394)
		(end 456.017884 -99.164394)
		(width 0.10668)
		(layer "F.Cu")
		(net "OCP_SFF_AUX_PWR_EN_R1")
	)
	(segment
		(start 458.629766 -99.164394)
		(end 457.253848 -99.164394)
		(width 0.10668)
		(layer "F.Cu")
		(net "OCP_SFF_AUX_PWR_EN_R1")
	)
	(via
		(at 457.253848 -99.164394)
		(size 0.762)
		(drill 0.381)
		(layers "F.Cu" "B.Cu")
		(net "OCP_SFF_AUX_PWR_EN_R1")
	)
	(segment
		(start 433.340764 -14.502892)
		(end 434.637688 -15.799816)
		(width 0.10668)
		(layer "F.Cu")
		(net "OCP_SFF_AUX_PWR_EN_R")
	)
	(segment
		(start 433.766976 -14.07668)
		(end 433.340764 -14.502892)
		(width 0.10668)
		(layer "F.Cu")
		(net "OCP_SFF_AUX_PWR_EN_R")
	)
	(segment
		(start 434.637688 -15.799816)
		(end 434.796692 -15.799816)
		(width 0.10668)
		(layer "F.Cu")
		(net "OCP_SFF_AUX_PWR_EN_R")
	)
	(segment
		(start 433.766976 -11.26998)
		(end 433.766976 -14.07668)
		(width 0.10668)
		(layer "F.Cu")
		(net "OCP_SFF_AUX_PWR_EN_R")
	)
	(via
		(at 433.340764 -14.502892)
		(size 0.762)
		(drill 0.381)
		(layers "F.Cu" "B.Cu")
		(net "OCP_SFF_AUX_PWR_EN_R")
	)
	(segment
		(start 455.217784 -93.437964)
		(end 454.601834 -93.437964)
		(width 0.10668)
		(layer "F.Cu")
		(net "OCP_SFF_AUX_PWR_EN")
	)
	(segment
		(start 435.428644 -19.433032)
		(end 435.22138 -19.225768)
		(width 0.10668)
		(layer "F.Cu")
		(net "OCP_SFF_AUX_PWR_EN")
	)
	(segment
		(start 434.796692 -19.225768)
		(end 434.796692 -16.599916)
		(width 0.10668)
		(layer "F.Cu")
		(net "OCP_SFF_AUX_PWR_EN")
	)
	(segment
		(start 215.49995 -97.79)
		(end 215.49995 -96.774)
		(width 0.10668)
		(layer "F.Cu")
		(net "OCP_SFF_AUX_PWR_EN")
	)
	(segment
		(start 434.971444 -29.948632)
		(end 434.539644 -29.516832)
		(width 0.10668)
		(layer "F.Cu")
		(net "OCP_SFF_AUX_PWR_EN")
	)
	(segment
		(start 435.428644 -21.668232)
		(end 435.428644 -19.433032)
		(width 0.10668)
		(layer "F.Cu")
		(net "OCP_SFF_AUX_PWR_EN")
	)
	(segment
		(start 455.217784 -93.437964)
		(end 455.217784 -99.164394)
		(width 0.10668)
		(layer "F.Cu")
		(net "OCP_SFF_AUX_PWR_EN")
	)
	(segment
		(start 215.49995 -96.774)
		(end 215.49995 -96.034606)
		(width 0.10668)
		(layer "F.Cu")
		(net "OCP_SFF_AUX_PWR_EN")
	)
	(segment
		(start 435.22138 -19.225768)
		(end 434.796692 -19.225768)
		(width 0.10668)
		(layer "F.Cu")
		(net "OCP_SFF_AUX_PWR_EN")
	)
	(segment
		(start 434.539644 -22.557232)
		(end 435.428644 -21.668232)
		(width 0.10668)
		(layer "F.Cu")
		(net "OCP_SFF_AUX_PWR_EN")
	)
	(segment
		(start 434.539644 -29.516832)
		(end 434.539644 -22.557232)
		(width 0.10668)
		(layer "F.Cu")
		(net "OCP_SFF_AUX_PWR_EN")
	)
	(via
		(at 454.601834 -93.437964)
		(size 0.508)
		(drill 0.254)
		(layers "F.Cu" "B.Cu")
		(net "OCP_SFF_AUX_PWR_EN")
	)
	(via
		(at 215.49995 -96.034606)
		(size 0.508)
		(drill 0.254)
		(layers "F.Cu" "B.Cu")
		(net "OCP_SFF_AUX_PWR_EN")
	)
	(via
		(at 434.971444 -29.948632)
		(size 0.508)
		(drill 0.254)
		(layers "F.Cu" "B.Cu")
		(net "OCP_SFF_AUX_PWR_EN")
	)
	(via
		(at 213.933278 -88.995504)
		(size 0.508)
		(drill 0.254)
		(layers "F.Cu" "B.Cu")
		(net "OCP_SFF_AUX_PWR_EN")
	)
	(segment
		(start 437.80456 -80.36052)
		(end 436.898796 -79.454756)
		(width 0.11684)
		(layer "In2.Cu")
		(net "OCP_SFF_AUX_PWR_EN")
	)
	(segment
		(start 428.309786 -48.551592)
		(end 432.294538 -44.56684)
		(width 0.11684)
		(layer "In2.Cu")
		(net "OCP_SFF_AUX_PWR_EN")
	)
	(segment
		(start 441.52439 -80.36052)
		(end 437.80456 -80.36052)
		(width 0.11684)
		(layer "In2.Cu")
		(net "OCP_SFF_AUX_PWR_EN")
	)
	(segment
		(start 454.601834 -93.437964)
		(end 441.52439 -80.36052)
		(width 0.11684)
		(layer "In2.Cu")
		(net "OCP_SFF_AUX_PWR_EN")
	)
	(segment
		(start 428.309786 -54.375304)
		(end 428.309786 -48.551592)
		(width 0.11684)
		(layer "In2.Cu")
		(net "OCP_SFF_AUX_PWR_EN")
	)
	(segment
		(start 436.898796 -62.964314)
		(end 428.309786 -54.375304)
		(width 0.11684)
		(layer "In2.Cu")
		(net "OCP_SFF_AUX_PWR_EN")
	)
	(segment
		(start 432.294538 -32.625538)
		(end 434.971444 -29.948632)
		(width 0.11684)
		(layer "In2.Cu")
		(net "OCP_SFF_AUX_PWR_EN")
	)
	(segment
		(start 436.898796 -79.454756)
		(end 436.898796 -62.964314)
		(width 0.11684)
		(layer "In2.Cu")
		(net "OCP_SFF_AUX_PWR_EN")
	)
	(segment
		(start 432.294538 -44.56684)
		(end 432.294538 -32.625538)
		(width 0.11684)
		(layer "In2.Cu")
		(net "OCP_SFF_AUX_PWR_EN")
	)
	(segment
		(start 213.933278 -88.995504)
		(end 213.933278 -94.467934)
		(width 0.11684)
		(layer "In4.Cu")
		(net "OCP_SFF_AUX_PWR_EN")
	)
	(segment
		(start 213.933278 -94.467934)
		(end 215.49995 -96.034606)
		(width 0.11684)
		(layer "In4.Cu")
		(net "OCP_SFF_AUX_PWR_EN")
	)
	(segment
		(start 309.040022 -51.950874)
		(end 305.357022 -51.950874)
		(width 0.11684)
		(layer "In6.Cu")
		(net "OCP_SFF_AUX_PWR_EN")
	)
	(segment
		(start 304.616358 -51.21021)
		(end 290.957254 -51.21021)
		(width 0.11684)
		(layer "In6.Cu")
		(net "OCP_SFF_AUX_PWR_EN")
	)
	(segment
		(start 402.754592 -27.897328)
		(end 379.347222 -51.304698)
		(width 0.11684)
		(layer "In6.Cu")
		(net "OCP_SFF_AUX_PWR_EN")
	)
	(segment
		(start 290.957254 -51.21021)
		(end 277.769574 -64.39789)
		(width 0.11684)
		(layer "In6.Cu")
		(net "OCP_SFF_AUX_PWR_EN")
	)
	(segment
		(start 432.92014 -27.897328)
		(end 402.754592 -27.897328)
		(width 0.11684)
		(layer "In6.Cu")
		(net "OCP_SFF_AUX_PWR_EN")
	)
	(segment
		(start 305.357022 -51.950874)
		(end 304.616358 -51.21021)
		(width 0.11684)
		(layer "In6.Cu")
		(net "OCP_SFF_AUX_PWR_EN")
	)
	(segment
		(start 309.686198 -51.304698)
		(end 309.040022 -51.950874)
		(width 0.11684)
		(layer "In6.Cu")
		(net "OCP_SFF_AUX_PWR_EN")
	)
	(segment
		(start 241.108738 -88.995504)
		(end 213.933278 -88.995504)
		(width 0.11684)
		(layer "In6.Cu")
		(net "OCP_SFF_AUX_PWR_EN")
	)
	(segment
		(start 260.195822 -80.032606)
		(end 250.071636 -80.032606)
		(width 0.11684)
		(layer "In6.Cu")
		(net "OCP_SFF_AUX_PWR_EN")
	)
	(segment
		(start 277.769574 -64.39789)
		(end 277.769574 -67.415918)
		(width 0.11684)
		(layer "In6.Cu")
		(net "OCP_SFF_AUX_PWR_EN")
	)
	(segment
		(start 379.347222 -51.304698)
		(end 309.686198 -51.304698)
		(width 0.11684)
		(layer "In6.Cu")
		(net "OCP_SFF_AUX_PWR_EN")
	)
	(segment
		(start 277.769574 -67.415918)
		(end 274.922742 -70.26275)
		(width 0.11684)
		(layer "In6.Cu")
		(net "OCP_SFF_AUX_PWR_EN")
	)
	(segment
		(start 269.965678 -70.26275)
		(end 260.195822 -80.032606)
		(width 0.11684)
		(layer "In6.Cu")
		(net "OCP_SFF_AUX_PWR_EN")
	)
	(segment
		(start 250.071636 -80.032606)
		(end 241.108738 -88.995504)
		(width 0.11684)
		(layer "In6.Cu")
		(net "OCP_SFF_AUX_PWR_EN")
	)
	(segment
		(start 274.922742 -70.26275)
		(end 269.965678 -70.26275)
		(width 0.11684)
		(layer "In6.Cu")
		(net "OCP_SFF_AUX_PWR_EN")
	)
	(segment
		(start 434.971444 -29.948632)
		(end 432.92014 -27.897328)
		(width 0.11684)
		(layer "In6.Cu")
		(net "OCP_SFF_AUX_PWR_EN")
	)
	(segment
		(start 351.805494 -435.975252)
		(end 350.332294 -435.975252)
		(width 0.10668)
		(layer "F.Cu")
		(net "NC_U316_2Y")
	)
	(via
		(at 350.332294 -435.975252)
		(size 0.762)
		(drill 0.381)
		(layers "F.Cu" "B.Cu")
		(net "NC_U316_2Y")
	)
	(segment
		(start 118.723664 -436.731918)
		(end 117.602508 -435.610762)
		(width 0.10668)
		(layer "F.Cu")
		(net "NC_U257_2Y")
	)
	(segment
		(start 117.602508 -435.610762)
		(end 117.602508 -435.101492)
		(width 0.10668)
		(layer "F.Cu")
		(net "NC_U257_2Y")
	)
	(segment
		(start 118.723664 -436.893462)
		(end 118.723664 -436.731918)
		(width 0.10668)
		(layer "F.Cu")
		(net "NC_U257_2Y")
	)
	(segment
		(start 117.602508 -435.101492)
		(end 117.983 -434.721)
		(width 0.10668)
		(layer "F.Cu")
		(net "NC_U257_2Y")
	)
	(via
		(at 117.983 -434.721)
		(size 0.762)
		(drill 0.381)
		(layers "F.Cu" "B.Cu")
		(net "NC_U257_2Y")
	)
	(segment
		(start 92.8116 -36.891976)
		(end 93.473778 -36.229798)
		(width 0.10668)
		(layer "F.Cu")
		(net "NC_U219_NC1")
	)
	(segment
		(start 93.473778 -36.229798)
		(end 94.233746 -36.229798)
		(width 0.10668)
		(layer "F.Cu")
		(net "NC_U219_NC1")
	)
	(segment
		(start 92.8116 -37.31514)
		(end 92.8116 -36.891976)
		(width 0.10668)
		(layer "F.Cu")
		(net "NC_U219_NC1")
	)
	(via
		(at 92.8116 -37.31514)
		(size 0.762)
		(drill 0.381)
		(layers "F.Cu" "B.Cu")
		(net "NC_U219_NC1")
	)
	(segment
		(start 252.140212 -108.804964)
		(end 250.620784 -108.804964)
		(width 0.10668)
		(layer "F.Cu")
		(net "NC_U218_NC1")
	)
	(via
		(at 250.620784 -108.804964)
		(size 0.762)
		(drill 0.381)
		(layers "F.Cu" "B.Cu")
		(net "NC_U218_NC1")
	)
	(segment
		(start 161.268156 -32.523938)
		(end 161.268156 -30.80512)
		(width 0.10668)
		(layer "F.Cu")
		(net "NC_U157_NC1")
	)
	(via
		(at 161.268156 -30.80512)
		(size 0.762)
		(drill 0.381)
		(layers "F.Cu" "B.Cu")
		(net "NC_U157_NC1")
	)
	(segment
		(start 366.194848 -15.344902)
		(end 365.747554 -15.792196)
		(width 0.10668)
		(layer "F.Cu")
		(net "NC_U104_NC1")
	)
	(segment
		(start 367.124488 -15.344902)
		(end 366.194848 -15.344902)
		(width 0.10668)
		(layer "F.Cu")
		(net "NC_U104_NC1")
	)
	(via
		(at 365.747554 -15.792196)
		(size 0.762)
		(drill 0.381)
		(layers "F.Cu" "B.Cu")
		(net "NC_U104_NC1")
	)
	(segment
		(start 31.880048 -360.295952)
		(end 32.004 -360.172)
		(width 0.1778)
		(layer "F.Cu")
		(net "NC_PVDDCR_CPU1_P1_IMON8")
	)
	(segment
		(start 31.880048 -361.233974)
		(end 31.880048 -360.295952)
		(width 0.1778)
		(layer "F.Cu")
		(net "NC_PVDDCR_CPU1_P1_IMON8")
	)
	(via
		(at 32.004 -360.172)
		(size 0.508)
		(drill 0.254)
		(layers "F.Cu" "B.Cu")
		(net "NC_PVDDCR_CPU1_P1_IMON8")
	)
	(segment
		(start 31.623 -361.16895)
		(end 31.623 -360.553)
		(width 0.254)
		(layer "B.Cu")
		(net "NC_PVDDCR_CPU1_P1_IMON8")
	)
	(segment
		(start 31.623 -360.553)
		(end 32.004 -360.172)
		(width 0.254)
		(layer "B.Cu")
		(net "NC_PVDDCR_CPU1_P1_IMON8")
	)
	(segment
		(start 31.479998 -359.680002)
		(end 31.479998 -361.233974)
		(width 0.10668)
		(layer "F.Cu")
		(net "NC_PVDDCR_CPU1_P1_IMON7")
	)
	(segment
		(start 32.004 -359.156)
		(end 31.479998 -359.680002)
		(width 0.10668)
		(layer "F.Cu")
		(net "NC_PVDDCR_CPU1_P1_IMON7")
	)
	(via
		(at 32.004 -359.156)
		(size 0.508)
		(drill 0.254)
		(layers "F.Cu" "B.Cu")
		(net "NC_PVDDCR_CPU1_P1_IMON7")
	)
	(segment
		(start 33.02 -360.172)
		(end 32.004 -359.156)
		(width 0.10668)
		(layer "B.Cu")
		(net "NC_PVDDCR_CPU1_P1_IMON7")
	)
	(segment
		(start 33.02 -361.16895)
		(end 33.02 -360.172)
		(width 0.10668)
		(layer "B.Cu")
		(net "NC_PVDDCR_CPU1_P1_IMON7")
	)
	(segment
		(start 311.534048 -357.804974)
		(end 311.534048 -356.866952)
		(width 0.1778)
		(layer "F.Cu")
		(net "NC_PVDDCR_CPU1_P0_IMON8")
	)
	(segment
		(start 311.534048 -356.866952)
		(end 311.658 -356.743)
		(width 0.1778)
		(layer "F.Cu")
		(net "NC_PVDDCR_CPU1_P0_IMON8")
	)
	(via
		(at 311.658 -356.743)
		(size 0.508)
		(drill 0.254)
		(layers "F.Cu" "B.Cu")
		(net "NC_PVDDCR_CPU1_P0_IMON8")
	)
	(segment
		(start 311.277 -357.73995)
		(end 311.277 -357.124)
		(width 0.254)
		(layer "B.Cu")
		(net "NC_PVDDCR_CPU1_P0_IMON8")
	)
	(segment
		(start 311.277 -357.124)
		(end 311.658 -356.743)
		(width 0.254)
		(layer "B.Cu")
		(net "NC_PVDDCR_CPU1_P0_IMON8")
	)
	(segment
		(start 311.658 -355.9302)
		(end 311.133998 -356.454202)
		(width 0.1778)
		(layer "F.Cu")
		(net "NC_PVDDCR_CPU1_P0_IMON7")
	)
	(segment
		(start 311.133998 -356.454202)
		(end 311.133998 -357.804974)
		(width 0.1778)
		(layer "F.Cu")
		(net "NC_PVDDCR_CPU1_P0_IMON7")
	)
	(via
		(at 311.658 -355.9302)
		(size 0.508)
		(drill 0.254)
		(layers "F.Cu" "B.Cu")
		(net "NC_PVDDCR_CPU1_P0_IMON7")
	)
	(segment
		(start 312.166 -355.9302)
		(end 311.658 -355.9302)
		(width 0.254)
		(layer "B.Cu")
		(net "NC_PVDDCR_CPU1_P0_IMON7")
	)
	(segment
		(start 312.674 -356.4382)
		(end 312.166 -355.9302)
		(width 0.254)
		(layer "B.Cu")
		(net "NC_PVDDCR_CPU1_P0_IMON7")
	)
	(segment
		(start 312.674 -357.73995)
		(end 312.674 -356.4382)
		(width 0.254)
		(layer "B.Cu")
		(net "NC_PVDDCR_CPU1_P0_IMON7")
	)
	(via
		(at 98.062034 -149.133052)
		(size 0.6604)
		(drill 0.3302)
		(layers "F.Cu" "B.Cu")
		(net "NC_PVDDCR_CPU0_P1_IMON9")
	)
	(segment
		(start 97.470976 -147.633436)
		(end 97.470976 -148.07184)
		(width 0.1778)
		(layer "B.Cu")
		(net "NC_PVDDCR_CPU0_P1_IMON9")
	)
	(segment
		(start 98.918522 -149.98954)
		(end 98.918522 -150.298912)
		(width 0.254)
		(layer "B.Cu")
		(net "NC_PVDDCR_CPU0_P1_IMON9")
	)
	(segment
		(start 97.803462 -148.87448)
		(end 98.062034 -149.133052)
		(width 0.1778)
		(layer "B.Cu")
		(net "NC_PVDDCR_CPU0_P1_IMON9")
	)
	(segment
		(start 98.062034 -149.133052)
		(end 98.918522 -149.98954)
		(width 0.254)
		(layer "B.Cu")
		(net "NC_PVDDCR_CPU0_P1_IMON9")
	)
	(segment
		(start 97.470976 -148.07184)
		(end 97.803462 -148.87448)
		(width 0.1778)
		(layer "B.Cu")
		(net "NC_PVDDCR_CPU0_P1_IMON9")
	)
	(segment
		(start 97.3201 -148.706078)
		(end 97.070926 -148.104352)
		(width 0.1778)
		(layer "B.Cu")
		(net "NC_PVDDCR_CPU0_P1_IMON8")
	)
	(segment
		(start 97.44075 -149.311106)
		(end 97.3201 -148.706078)
		(width 0.254)
		(layer "B.Cu")
		(net "NC_PVDDCR_CPU0_P1_IMON8")
	)
	(segment
		(start 97.902522 -150.298912)
		(end 97.839022 -150.27275)
		(width 0.254)
		(layer "B.Cu")
		(net "NC_PVDDCR_CPU0_P1_IMON8")
	)
	(segment
		(start 97.070926 -148.104352)
		(end 97.070926 -147.633436)
		(width 0.1778)
		(layer "B.Cu")
		(net "NC_PVDDCR_CPU0_P1_IMON8")
	)
	(segment
		(start 97.839022 -150.27275)
		(end 97.44075 -149.311106)
		(width 0.254)
		(layer "B.Cu")
		(net "NC_PVDDCR_CPU0_P1_IMON8")
	)
	(segment
		(start 96.96577 -149.48789)
		(end 96.886522 -149.567138)
		(width 0.10668)
		(layer "B.Cu")
		(net "NC_PVDDCR_CPU0_P1_IMON7")
	)
	(segment
		(start 96.96577 -148.807678)
		(end 96.96577 -149.48789)
		(width 0.10668)
		(layer "B.Cu")
		(net "NC_PVDDCR_CPU0_P1_IMON7")
	)
	(segment
		(start 96.886522 -149.567138)
		(end 96.886522 -150.298912)
		(width 0.10668)
		(layer "B.Cu")
		(net "NC_PVDDCR_CPU0_P1_IMON7")
	)
	(segment
		(start 96.670876 -147.633436)
		(end 96.670876 -148.09597)
		(width 0.10668)
		(layer "B.Cu")
		(net "NC_PVDDCR_CPU0_P1_IMON7")
	)
	(segment
		(start 96.670876 -148.09597)
		(end 96.96577 -148.807678)
		(width 0.10668)
		(layer "B.Cu")
		(net "NC_PVDDCR_CPU0_P1_IMON7")
	)
	(segment
		(start 380.198376 -145.674588)
		(end 380.198376 -145.236184)
		(width 0.1778)
		(layer "B.Cu")
		(net "NC_PVDDCR_CPU0_P0_IMON9")
	)
	(segment
		(start 381.645922 -147.90166)
		(end 381.645922 -147.77974)
		(width 0.254)
		(layer "B.Cu")
		(net "NC_PVDDCR_CPU0_P0_IMON9")
	)
	(segment
		(start 380.663196 -146.797014)
		(end 380.198376 -145.674588)
		(width 0.1778)
		(layer "B.Cu")
		(net "NC_PVDDCR_CPU0_P0_IMON9")
	)
	(segment
		(start 381.645922 -147.77974)
		(end 380.663196 -146.797014)
		(width 0.254)
		(layer "B.Cu")
		(net "NC_PVDDCR_CPU0_P0_IMON9")
	)
	(segment
		(start 379.798326 -145.7071)
		(end 379.798326 -145.236184)
		(width 0.1778)
		(layer "B.Cu")
		(net "NC_PVDDCR_CPU0_P0_IMON8")
	)
	(segment
		(start 380.566422 -147.875498)
		(end 380.16815 -146.913854)
		(width 0.254)
		(layer "B.Cu")
		(net "NC_PVDDCR_CPU0_P0_IMON8")
	)
	(segment
		(start 380.16815 -146.913854)
		(end 380.0475 -146.308826)
		(width 0.254)
		(layer "B.Cu")
		(net "NC_PVDDCR_CPU0_P0_IMON8")
	)
	(segment
		(start 380.0475 -146.308826)
		(end 379.798326 -145.7071)
		(width 0.1778)
		(layer "B.Cu")
		(net "NC_PVDDCR_CPU0_P0_IMON8")
	)
	(segment
		(start 380.629922 -147.90166)
		(end 380.566422 -147.875498)
		(width 0.254)
		(layer "B.Cu")
		(net "NC_PVDDCR_CPU0_P0_IMON8")
	)
	(segment
		(start 379.673358 -146.362674)
		(end 379.673358 -147.842224)
		(width 0.10668)
		(layer "B.Cu")
		(net "NC_PVDDCR_CPU0_P0_IMON7")
	)
	(segment
		(start 379.398276 -145.236184)
		(end 379.398276 -145.698718)
		(width 0.10668)
		(layer "B.Cu")
		(net "NC_PVDDCR_CPU0_P0_IMON7")
	)
	(segment
		(start 379.673358 -147.842224)
		(end 379.613922 -147.90166)
		(width 0.10668)
		(layer "B.Cu")
		(net "NC_PVDDCR_CPU0_P0_IMON7")
	)
	(segment
		(start 379.398276 -145.698718)
		(end 379.673358 -146.362674)
		(width 0.10668)
		(layer "B.Cu")
		(net "NC_PVDDCR_CPU0_P0_IMON7")
	)
	(segment
		(start 164.028628 -346.153232)
		(end 164.028628 -346.03944)
		(width 0.1524)
		(layer "F.Cu")
		(net "NC_PVDD11_S3_P1_IMON8")
	)
	(segment
		(start 166.87546 -344.768932)
		(end 167.090344 -344.554048)
		(width 0.1524)
		(layer "F.Cu")
		(net "NC_PVDD11_S3_P1_IMON8")
	)
	(segment
		(start 164.028628 -346.03944)
		(end 164.18433 -345.883738)
		(width 0.1524)
		(layer "F.Cu")
		(net "NC_PVDD11_S3_P1_IMON8")
	)
	(segment
		(start 164.18433 -345.883738)
		(end 166.87546 -344.768932)
		(width 0.1524)
		(layer "F.Cu")
		(net "NC_PVDD11_S3_P1_IMON8")
	)
	(segment
		(start 165.771322 -344.85707)
		(end 166.074344 -344.554048)
		(width 0.1524)
		(layer "F.Cu")
		(net "NC_PVDD11_S3_P1_IMON7")
	)
	(segment
		(start 163.628578 -346.153232)
		(end 163.628578 -345.72829)
		(width 0.1524)
		(layer "F.Cu")
		(net "NC_PVDD11_S3_P1_IMON7")
	)
	(segment
		(start 163.76269 -345.594178)
		(end 163.991798 -345.594178)
		(width 0.1524)
		(layer "F.Cu")
		(net "NC_PVDD11_S3_P1_IMON7")
	)
	(segment
		(start 163.991798 -345.594178)
		(end 165.771322 -344.85707)
		(width 0.1524)
		(layer "F.Cu")
		(net "NC_PVDD11_S3_P1_IMON7")
	)
	(segment
		(start 163.628578 -345.72829)
		(end 163.76269 -345.594178)
		(width 0.1524)
		(layer "F.Cu")
		(net "NC_PVDD11_S3_P1_IMON7")
	)
	(segment
		(start 164.791644 -344.871548)
		(end 165.109144 -344.554048)
		(width 0.1524)
		(layer "F.Cu")
		(net "NC_PVDD11_S3_P1_IMON6")
	)
	(segment
		(start 163.228528 -345.3892)
		(end 163.31311 -345.304618)
		(width 0.1524)
		(layer "F.Cu")
		(net "NC_PVDD11_S3_P1_IMON6")
	)
	(segment
		(start 163.74618 -345.304618)
		(end 164.791644 -344.871548)
		(width 0.1524)
		(layer "F.Cu")
		(net "NC_PVDD11_S3_P1_IMON6")
	)
	(segment
		(start 163.31311 -345.304618)
		(end 163.74618 -345.304618)
		(width 0.1524)
		(layer "F.Cu")
		(net "NC_PVDD11_S3_P1_IMON6")
	)
	(segment
		(start 163.228528 -346.153232)
		(end 163.228528 -345.3892)
		(width 0.1524)
		(layer "F.Cu")
		(net "NC_PVDD11_S3_P1_IMON6")
	)
	(segment
		(start 162.828478 -345.299538)
		(end 163.120578 -345.007438)
		(width 0.1524)
		(layer "F.Cu")
		(net "NC_PVDD11_S3_P1_IMON5")
	)
	(segment
		(start 162.828478 -346.153232)
		(end 162.828478 -345.299538)
		(width 0.1524)
		(layer "F.Cu")
		(net "NC_PVDD11_S3_P1_IMON5")
	)
	(segment
		(start 163.120578 -345.007438)
		(end 163.690554 -345.007438)
		(width 0.1524)
		(layer "F.Cu")
		(net "NC_PVDD11_S3_P1_IMON5")
	)
	(segment
		(start 163.690554 -345.007438)
		(end 164.143944 -344.554048)
		(width 0.1524)
		(layer "F.Cu")
		(net "NC_PVDD11_S3_P1_IMON5")
	)
	(segment
		(start 162.428428 -345.304364)
		(end 163.178744 -344.554048)
		(width 0.1524)
		(layer "F.Cu")
		(net "NC_PVDD11_S3_P1_IMON4")
	)
	(segment
		(start 162.428428 -346.153232)
		(end 162.428428 -345.304364)
		(width 0.1524)
		(layer "F.Cu")
		(net "NC_PVDD11_S3_P1_IMON4")
	)
	(segment
		(start 162.162744 -344.930984)
		(end 162.028632 -345.065096)
		(width 0.1524)
		(layer "F.Cu")
		(net "NC_PVDD11_S3_P1_IMON3")
	)
	(segment
		(start 162.162744 -344.554048)
		(end 162.162744 -344.930984)
		(width 0.1524)
		(layer "F.Cu")
		(net "NC_PVDD11_S3_P1_IMON3")
	)
	(segment
		(start 162.028632 -345.065096)
		(end 162.028632 -346.153232)
		(width 0.1524)
		(layer "F.Cu")
		(net "NC_PVDD11_S3_P1_IMON3")
	)
	(segment
		(start 420.852854 -359.40111)
		(end 422.185084 -359.40111)
		(width 0.1778)
		(layer "F.Cu")
		(net "NC_PVDD11_S3_P0_IMON8")
	)
	(segment
		(start 420.71798 -359.535984)
		(end 420.852854 -359.40111)
		(width 0.1778)
		(layer "F.Cu")
		(net "NC_PVDD11_S3_P0_IMON8")
	)
	(segment
		(start 422.46677 -359.40111)
		(end 423.779696 -358.088184)
		(width 0.1778)
		(layer "F.Cu")
		(net "NC_PVDD11_S3_P0_IMON8")
	)
	(segment
		(start 420.71798 -359.687368)
		(end 420.71798 -359.535984)
		(width 0.1778)
		(layer "F.Cu")
		(net "NC_PVDD11_S3_P0_IMON8")
	)
	(segment
		(start 422.185084 -359.40111)
		(end 422.46677 -359.40111)
		(width 0.1778)
		(layer "F.Cu")
		(net "NC_PVDD11_S3_P0_IMON8")
	)
	(via
		(at 422.185084 -359.40111)
		(size 0.4064)
		(drill 0.2032)
		(layers "F.Cu" "B.Cu")
		(net "NC_PVDD11_S3_P0_IMON8")
	)
	(segment
		(start 421.83177 -359.02011)
		(end 420.624254 -359.02011)
		(width 0.1778)
		(layer "F.Cu")
		(net "NC_PVDD11_S3_P0_IMON7")
	)
	(segment
		(start 422.763696 -358.088184)
		(end 421.83177 -359.02011)
		(width 0.1778)
		(layer "F.Cu")
		(net "NC_PVDD11_S3_P0_IMON7")
	)
	(segment
		(start 420.31793 -359.326434)
		(end 420.31793 -359.687368)
		(width 0.1778)
		(layer "F.Cu")
		(net "NC_PVDD11_S3_P0_IMON7")
	)
	(segment
		(start 420.624254 -359.02011)
		(end 420.31793 -359.326434)
		(width 0.1778)
		(layer "F.Cu")
		(net "NC_PVDD11_S3_P0_IMON7")
	)
	(segment
		(start 421.798496 -358.088184)
		(end 421.22217 -358.66451)
		(width 0.1778)
		(layer "F.Cu")
		(net "NC_PVDD11_S3_P0_IMON6")
	)
	(segment
		(start 420.523924 -358.66451)
		(end 419.91788 -359.270554)
		(width 0.1778)
		(layer "F.Cu")
		(net "NC_PVDD11_S3_P0_IMON6")
	)
	(segment
		(start 419.91788 -359.270554)
		(end 419.91788 -359.687368)
		(width 0.1778)
		(layer "F.Cu")
		(net "NC_PVDD11_S3_P0_IMON6")
	)
	(segment
		(start 421.22217 -358.66451)
		(end 420.523924 -358.66451)
		(width 0.1778)
		(layer "F.Cu")
		(net "NC_PVDD11_S3_P0_IMON6")
	)
	(segment
		(start 420.141654 -358.56291)
		(end 420.014654 -358.56291)
		(width 0.1778)
		(layer "F.Cu")
		(net "NC_PVDD11_S3_P0_IMON5")
	)
	(segment
		(start 420.61638 -358.088184)
		(end 420.141654 -358.56291)
		(width 0.1778)
		(layer "F.Cu")
		(net "NC_PVDD11_S3_P0_IMON5")
	)
	(segment
		(start 419.51783 -359.059734)
		(end 419.51783 -359.687368)
		(width 0.1778)
		(layer "F.Cu")
		(net "NC_PVDD11_S3_P0_IMON5")
	)
	(segment
		(start 420.833296 -358.088184)
		(end 420.61638 -358.088184)
		(width 0.1778)
		(layer "F.Cu")
		(net "NC_PVDD11_S3_P0_IMON5")
	)
	(segment
		(start 420.014654 -358.56291)
		(end 419.51783 -359.059734)
		(width 0.1778)
		(layer "F.Cu")
		(net "NC_PVDD11_S3_P0_IMON5")
	)
	(segment
		(start 419.868096 -358.088184)
		(end 419.11778 -358.8385)
		(width 0.1778)
		(layer "F.Cu")
		(net "NC_PVDD11_S3_P0_IMON4")
	)
	(segment
		(start 419.11778 -358.8385)
		(end 419.11778 -359.687368)
		(width 0.1778)
		(layer "F.Cu")
		(net "NC_PVDD11_S3_P0_IMON4")
	)
	(segment
		(start 418.852096 -358.088184)
		(end 418.717984 -358.222296)
		(width 0.1778)
		(layer "F.Cu")
		(net "NC_PVDD11_S3_P0_IMON3")
	)
	(segment
		(start 418.717984 -358.222296)
		(end 418.717984 -359.687368)
		(width 0.1778)
		(layer "F.Cu")
		(net "NC_PVDD11_S3_P0_IMON3")
	)
	(segment
		(start 167.54856 -37.077904)
		(end 166.2176 -35.746944)
		(width 0.10668)
		(layer "F.Cu")
		(net "NC_M2_0_SUSCLK")
	)
	(segment
		(start 166.2176 -34.793174)
		(end 165.453314 -34.028888)
		(width 0.10668)
		(layer "F.Cu")
		(net "NC_M2_0_SUSCLK")
	)
	(segment
		(start 166.2176 -35.746944)
		(end 166.2176 -34.793174)
		(width 0.10668)
		(layer "F.Cu")
		(net "NC_M2_0_SUSCLK")
	)
	(segment
		(start 168.581832 -39.549832)
		(end 167.54856 -38.51656)
		(width 0.10668)
		(layer "F.Cu")
		(net "NC_M2_0_SUSCLK")
	)
	(segment
		(start 169.558208 -39.549832)
		(end 168.581832 -39.549832)
		(width 0.10668)
		(layer "F.Cu")
		(net "NC_M2_0_SUSCLK")
	)
	(segment
		(start 167.54856 -38.51656)
		(end 167.54856 -37.077904)
		(width 0.10668)
		(layer "F.Cu")
		(net "NC_M2_0_SUSCLK")
	)
	(via
		(at 165.453314 -34.028888)
		(size 0.762)
		(drill 0.381)
		(layers "F.Cu" "B.Cu")
		(net "NC_M2_0_SUSCLK")
	)
	(segment
		(start 169.558208 -48.550068)
		(end 168.3258 -48.550068)
		(width 0.10668)
		(layer "F.Cu")
		(net "NC_M2_0_NC9")
	)
	(segment
		(start 168.173654 -48.702214)
		(end 161.38906 -48.702214)
		(width 0.10668)
		(layer "F.Cu")
		(net "NC_M2_0_NC9")
	)
	(segment
		(start 158.215076 -48.600614)
		(end 157.803596 -49.012094)
		(width 0.10668)
		(layer "F.Cu")
		(net "NC_M2_0_NC9")
	)
	(segment
		(start 161.38906 -48.702214)
		(end 161.28746 -48.600614)
		(width 0.10668)
		(layer "F.Cu")
		(net "NC_M2_0_NC9")
	)
	(segment
		(start 161.28746 -48.600614)
		(end 158.215076 -48.600614)
		(width 0.10668)
		(layer "F.Cu")
		(net "NC_M2_0_NC9")
	)
	(segment
		(start 168.3258 -48.550068)
		(end 168.173654 -48.702214)
		(width 0.10668)
		(layer "F.Cu")
		(net "NC_M2_0_NC9")
	)
	(via
		(at 157.803596 -49.012094)
		(size 0.762)
		(drill 0.381)
		(layers "F.Cu" "B.Cu")
		(net "NC_M2_0_NC9")
	)
	(segment
		(start 168.3258 -49.04994)
		(end 168.201594 -48.925734)
		(width 0.10668)
		(layer "F.Cu")
		(net "NC_M2_0_NC8")
	)
	(segment
		(start 168.201594 -48.925734)
		(end 161.591244 -48.925734)
		(width 0.10668)
		(layer "F.Cu")
		(net "NC_M2_0_NC8")
	)
	(segment
		(start 161.591244 -48.925734)
		(end 160.869884 -49.647094)
		(width 0.10668)
		(layer "F.Cu")
		(net "NC_M2_0_NC8")
	)
	(segment
		(start 160.869884 -49.647094)
		(end 157.168596 -49.647094)
		(width 0.10668)
		(layer "F.Cu")
		(net "NC_M2_0_NC8")
	)
	(segment
		(start 157.168596 -49.647094)
		(end 156.533596 -49.012094)
		(width 0.10668)
		(layer "F.Cu")
		(net "NC_M2_0_NC8")
	)
	(segment
		(start 169.558208 -49.04994)
		(end 168.3258 -49.04994)
		(width 0.10668)
		(layer "F.Cu")
		(net "NC_M2_0_NC8")
	)
	(via
		(at 156.533596 -49.012094)
		(size 0.762)
		(drill 0.381)
		(layers "F.Cu" "B.Cu")
		(net "NC_M2_0_NC8")
	)
	(segment
		(start 161.79165 -49.149254)
		(end 160.65881 -50.282094)
		(width 0.10668)
		(layer "F.Cu")
		(net "NC_M2_0_NC7")
	)
	(segment
		(start 160.65881 -50.282094)
		(end 157.803596 -50.282094)
		(width 0.10668)
		(layer "F.Cu")
		(net "NC_M2_0_NC7")
	)
	(segment
		(start 168.3258 -49.550066)
		(end 167.924988 -49.149254)
		(width 0.10668)
		(layer "F.Cu")
		(net "NC_M2_0_NC7")
	)
	(segment
		(start 169.558208 -49.550066)
		(end 168.3258 -49.550066)
		(width 0.10668)
		(layer "F.Cu")
		(net "NC_M2_0_NC7")
	)
	(segment
		(start 167.924988 -49.149254)
		(end 161.79165 -49.149254)
		(width 0.10668)
		(layer "F.Cu")
		(net "NC_M2_0_NC7")
	)
	(via
		(at 157.803596 -50.282094)
		(size 0.762)
		(drill 0.381)
		(layers "F.Cu" "B.Cu")
		(net "NC_M2_0_NC7")
	)
	(segment
		(start 168.3258 -50.049938)
		(end 167.648636 -49.372774)
		(width 0.10668)
		(layer "F.Cu")
		(net "NC_M2_0_NC6")
	)
	(segment
		(start 160.46323 -50.9016)
		(end 157.153102 -50.9016)
		(width 0.10668)
		(layer "F.Cu")
		(net "NC_M2_0_NC6")
	)
	(segment
		(start 161.992056 -49.372774)
		(end 160.46323 -50.9016)
		(width 0.10668)
		(layer "F.Cu")
		(net "NC_M2_0_NC6")
	)
	(segment
		(start 167.648636 -49.372774)
		(end 161.992056 -49.372774)
		(width 0.10668)
		(layer "F.Cu")
		(net "NC_M2_0_NC6")
	)
	(segment
		(start 157.153102 -50.9016)
		(end 156.533596 -50.282094)
		(width 0.10668)
		(layer "F.Cu")
		(net "NC_M2_0_NC6")
	)
	(segment
		(start 169.558208 -50.049938)
		(end 168.3258 -50.049938)
		(width 0.10668)
		(layer "F.Cu")
		(net "NC_M2_0_NC6")
	)
	(via
		(at 156.533596 -50.282094)
		(size 0.762)
		(drill 0.381)
		(layers "F.Cu" "B.Cu")
		(net "NC_M2_0_NC6")
	)
	(segment
		(start 162.192462 -49.596294)
		(end 167.37203 -49.596294)
		(width 0.10668)
		(layer "F.Cu")
		(net "NC_M2_0_NC5")
	)
	(segment
		(start 167.37203 -49.596294)
		(end 168.3258 -50.550064)
		(width 0.10668)
		(layer "F.Cu")
		(net "NC_M2_0_NC5")
	)
	(segment
		(start 157.803596 -51.552094)
		(end 160.236662 -51.552094)
		(width 0.10668)
		(layer "F.Cu")
		(net "NC_M2_0_NC5")
	)
	(segment
		(start 168.3258 -50.550064)
		(end 169.558208 -50.550064)
		(width 0.10668)
		(layer "F.Cu")
		(net "NC_M2_0_NC5")
	)
	(segment
		(start 160.236662 -51.552094)
		(end 162.192462 -49.596294)
		(width 0.10668)
		(layer "F.Cu")
		(net "NC_M2_0_NC5")
	)
	(via
		(at 157.803596 -51.552094)
		(size 0.762)
		(drill 0.381)
		(layers "F.Cu" "B.Cu")
		(net "NC_M2_0_NC5")
	)
	(segment
		(start 167.095678 -49.819814)
		(end 168.3258 -51.049936)
		(width 0.10668)
		(layer "F.Cu")
		(net "NC_M2_0_NC4")
	)
	(segment
		(start 156.533596 -51.552094)
		(end 157.168596 -52.187094)
		(width 0.10668)
		(layer "F.Cu")
		(net "NC_M2_0_NC4")
	)
	(segment
		(start 160.025588 -52.187094)
		(end 162.392868 -49.819814)
		(width 0.10668)
		(layer "F.Cu")
		(net "NC_M2_0_NC4")
	)
	(segment
		(start 157.168596 -52.187094)
		(end 160.025588 -52.187094)
		(width 0.10668)
		(layer "F.Cu")
		(net "NC_M2_0_NC4")
	)
	(segment
		(start 168.3258 -51.049936)
		(end 169.558208 -51.049936)
		(width 0.10668)
		(layer "F.Cu")
		(net "NC_M2_0_NC4")
	)
	(segment
		(start 162.392868 -49.819814)
		(end 167.095678 -49.819814)
		(width 0.10668)
		(layer "F.Cu")
		(net "NC_M2_0_NC4")
	)
	(via
		(at 156.533596 -51.552094)
		(size 0.762)
		(drill 0.381)
		(layers "F.Cu" "B.Cu")
		(net "NC_M2_0_NC4")
	)
	(segment
		(start 159.814514 -52.822094)
		(end 162.593274 -50.043334)
		(width 0.10668)
		(layer "F.Cu")
		(net "NC_M2_0_NC3")
	)
	(segment
		(start 162.593274 -50.043334)
		(end 166.819072 -50.043334)
		(width 0.10668)
		(layer "F.Cu")
		(net "NC_M2_0_NC3")
	)
	(segment
		(start 157.803596 -52.822094)
		(end 159.814514 -52.822094)
		(width 0.10668)
		(layer "F.Cu")
		(net "NC_M2_0_NC3")
	)
	(segment
		(start 168.3258 -51.550062)
		(end 169.558208 -51.550062)
		(width 0.10668)
		(layer "F.Cu")
		(net "NC_M2_0_NC3")
	)
	(segment
		(start 166.819072 -50.043334)
		(end 168.3258 -51.550062)
		(width 0.10668)
		(layer "F.Cu")
		(net "NC_M2_0_NC3")
	)
	(via
		(at 157.803596 -52.822094)
		(size 0.762)
		(drill 0.381)
		(layers "F.Cu" "B.Cu")
		(net "NC_M2_0_NC3")
	)
	(segment
		(start 171.565062 -55.88889)
		(end 171.12996 -56.17972)
		(width 0.10668)
		(layer "F.Cu")
		(net "NC_M2_0_NC2")
	)
	(segment
		(start 169.558208 -54.550056)
		(end 170.501056 -54.550056)
		(width 0.10668)
		(layer "F.Cu")
		(net "NC_M2_0_NC2")
	)
	(segment
		(start 171.12996 -56.17972)
		(end 167.410384 -59.899296)
		(width 0.10668)
		(layer "F.Cu")
		(net "NC_M2_0_NC2")
	)
	(segment
		(start 167.410384 -59.899296)
		(end 167.410384 -66.171572)
		(width 0.10668)
		(layer "F.Cu")
		(net "NC_M2_0_NC2")
	)
	(segment
		(start 170.7896 -54.8386)
		(end 171.323 -54.8386)
		(width 0.10668)
		(layer "F.Cu")
		(net "NC_M2_0_NC2")
	)
	(segment
		(start 171.323 -54.8386)
		(end 171.744132 -55.259732)
		(width 0.10668)
		(layer "F.Cu")
		(net "NC_M2_0_NC2")
	)
	(segment
		(start 167.410384 -66.171572)
		(end 166.656512 -66.925444)
		(width 0.10668)
		(layer "F.Cu")
		(net "NC_M2_0_NC2")
	)
	(segment
		(start 170.501056 -54.550056)
		(end 170.7896 -54.8386)
		(width 0.10668)
		(layer "F.Cu")
		(net "NC_M2_0_NC2")
	)
	(segment
		(start 171.744132 -55.70982)
		(end 171.565062 -55.88889)
		(width 0.10668)
		(layer "F.Cu")
		(net "NC_M2_0_NC2")
	)
	(segment
		(start 171.744132 -55.259732)
		(end 171.744132 -55.70982)
		(width 0.10668)
		(layer "F.Cu")
		(net "NC_M2_0_NC2")
	)
	(via
		(at 166.656512 -66.925444)
		(size 0.762)
		(drill 0.381)
		(layers "F.Cu" "B.Cu")
		(net "NC_M2_0_NC2")
	)
	(segment
		(start 177.108358 -39.800022)
		(end 178.283362 -39.800022)
		(width 0.10668)
		(layer "F.Cu")
		(net "NC_M2_0_NC19")
	)
	(segment
		(start 179.380388 -41.405048)
		(end 180.542946 -41.405048)
		(width 0.10668)
		(layer "F.Cu")
		(net "NC_M2_0_NC19")
	)
	(segment
		(start 178.91506 -40.43172)
		(end 178.91506 -40.93972)
		(width 0.10668)
		(layer "F.Cu")
		(net "NC_M2_0_NC19")
	)
	(segment
		(start 178.91506 -40.93972)
		(end 179.380388 -41.405048)
		(width 0.10668)
		(layer "F.Cu")
		(net "NC_M2_0_NC19")
	)
	(segment
		(start 178.283362 -39.800022)
		(end 178.91506 -40.43172)
		(width 0.10668)
		(layer "F.Cu")
		(net "NC_M2_0_NC19")
	)
	(via
		(at 180.542946 -41.405048)
		(size 0.762)
		(drill 0.381)
		(layers "F.Cu" "B.Cu")
		(net "NC_M2_0_NC19")
	)
	(segment
		(start 167.012874 -40.327072)
		(end 168.735756 -42.049954)
		(width 0.10668)
		(layer "F.Cu")
		(net "NC_M2_0_NC18")
	)
	(segment
		(start 167.012874 -39.652448)
		(end 167.012874 -40.327072)
		(width 0.10668)
		(layer "F.Cu")
		(net "NC_M2_0_NC18")
	)
	(segment
		(start 168.735756 -42.049954)
		(end 169.558208 -42.049954)
		(width 0.10668)
		(layer "F.Cu")
		(net "NC_M2_0_NC18")
	)
	(segment
		(start 166.215314 -38.854888)
		(end 167.012874 -39.652448)
		(width 0.10668)
		(layer "F.Cu")
		(net "NC_M2_0_NC18")
	)
	(via
		(at 166.215314 -38.854888)
		(size 0.762)
		(drill 0.381)
		(layers "F.Cu" "B.Cu")
		(net "NC_M2_0_NC18")
	)
	(segment
		(start 168.482772 -42.549826)
		(end 169.558208 -42.549826)
		(width 0.10668)
		(layer "F.Cu")
		(net "NC_M2_0_NC17")
	)
	(segment
		(start 166.210234 -40.277288)
		(end 168.482772 -42.549826)
		(width 0.10668)
		(layer "F.Cu")
		(net "NC_M2_0_NC17")
	)
	(via
		(at 166.210234 -40.277288)
		(size 0.762)
		(drill 0.381)
		(layers "F.Cu" "B.Cu")
		(net "NC_M2_0_NC17")
	)
	(segment
		(start 172.085 -42.3672)
		(end 172.085 -43.7896)
		(width 0.10668)
		(layer "F.Cu")
		(net "NC_M2_0_NC16")
	)
	(segment
		(start 169.027856 -40.9448)
		(end 170.6626 -40.9448)
		(width 0.10668)
		(layer "F.Cu")
		(net "NC_M2_0_NC16")
	)
	(segment
		(start 166.878 -38.794944)
		(end 169.027856 -40.9448)
		(width 0.10668)
		(layer "F.Cu")
		(net "NC_M2_0_NC16")
	)
	(segment
		(start 170.6626 -40.9448)
		(end 172.085 -42.3672)
		(width 0.10668)
		(layer "F.Cu")
		(net "NC_M2_0_NC16")
	)
	(segment
		(start 171.324778 -44.549822)
		(end 169.558208 -44.549822)
		(width 0.10668)
		(layer "F.Cu")
		(net "NC_M2_0_NC16")
	)
	(segment
		(start 172.085 -43.7896)
		(end 171.324778 -44.549822)
		(width 0.10668)
		(layer "F.Cu")
		(net "NC_M2_0_NC16")
	)
	(segment
		(start 166.40683 -37.838888)
		(end 166.878 -38.310058)
		(width 0.10668)
		(layer "F.Cu")
		(net "NC_M2_0_NC16")
	)
	(segment
		(start 165.453314 -37.838888)
		(end 166.40683 -37.838888)
		(width 0.10668)
		(layer "F.Cu")
		(net "NC_M2_0_NC16")
	)
	(segment
		(start 166.878 -38.310058)
		(end 166.878 -38.794944)
		(width 0.10668)
		(layer "F.Cu")
		(net "NC_M2_0_NC16")
	)
	(via
		(at 165.453314 -37.838888)
		(size 0.762)
		(drill 0.381)
		(layers "F.Cu" "B.Cu")
		(net "NC_M2_0_NC16")
	)
	(segment
		(start 167.10152 -38.217094)
		(end 165.453314 -36.568888)
		(width 0.10668)
		(layer "F.Cu")
		(net "NC_M2_0_NC15")
	)
	(segment
		(start 171.140882 -45.049948)
		(end 172.30852 -43.88231)
		(width 0.10668)
		(layer "F.Cu")
		(net "NC_M2_0_NC15")
	)
	(segment
		(start 169.558208 -45.049948)
		(end 171.140882 -45.049948)
		(width 0.10668)
		(layer "F.Cu")
		(net "NC_M2_0_NC15")
	)
	(segment
		(start 172.30852 -43.88231)
		(end 172.30852 -42.27449)
		(width 0.10668)
		(layer "F.Cu")
		(net "NC_M2_0_NC15")
	)
	(segment
		(start 167.10152 -38.702234)
		(end 167.10152 -38.217094)
		(width 0.10668)
		(layer "F.Cu")
		(net "NC_M2_0_NC15")
	)
	(segment
		(start 170.75531 -40.72128)
		(end 169.120566 -40.72128)
		(width 0.10668)
		(layer "F.Cu")
		(net "NC_M2_0_NC15")
	)
	(segment
		(start 169.120566 -40.72128)
		(end 167.10152 -38.702234)
		(width 0.10668)
		(layer "F.Cu")
		(net "NC_M2_0_NC15")
	)
	(segment
		(start 172.30852 -42.27449)
		(end 170.75531 -40.72128)
		(width 0.10668)
		(layer "F.Cu")
		(net "NC_M2_0_NC15")
	)
	(via
		(at 165.453314 -36.568888)
		(size 0.762)
		(drill 0.381)
		(layers "F.Cu" "B.Cu")
		(net "NC_M2_0_NC15")
	)
	(segment
		(start 170.84802 -40.49776)
		(end 169.213276 -40.49776)
		(width 0.10668)
		(layer "F.Cu")
		(net "NC_M2_0_NC14")
	)
	(segment
		(start 170.957494 -45.54982)
		(end 172.53204 -43.975274)
		(width 0.10668)
		(layer "F.Cu")
		(net "NC_M2_0_NC14")
	)
	(segment
		(start 172.53204 -43.975274)
		(end 172.53204 -42.18178)
		(width 0.10668)
		(layer "F.Cu")
		(net "NC_M2_0_NC14")
	)
	(segment
		(start 167.32504 -37.170614)
		(end 165.453314 -35.298888)
		(width 0.10668)
		(layer "F.Cu")
		(net "NC_M2_0_NC14")
	)
	(segment
		(start 169.213276 -40.49776)
		(end 167.32504 -38.609524)
		(width 0.10668)
		(layer "F.Cu")
		(net "NC_M2_0_NC14")
	)
	(segment
		(start 169.558208 -45.54982)
		(end 170.957494 -45.54982)
		(width 0.10668)
		(layer "F.Cu")
		(net "NC_M2_0_NC14")
	)
	(segment
		(start 167.32504 -38.609524)
		(end 167.32504 -37.170614)
		(width 0.10668)
		(layer "F.Cu")
		(net "NC_M2_0_NC14")
	)
	(segment
		(start 172.53204 -42.18178)
		(end 170.84802 -40.49776)
		(width 0.10668)
		(layer "F.Cu")
		(net "NC_M2_0_NC14")
	)
	(via
		(at 165.453314 -35.298888)
		(size 0.762)
		(drill 0.381)
		(layers "F.Cu" "B.Cu")
		(net "NC_M2_0_NC14")
	)
	(segment
		(start 161.315908 -47.742094)
		(end 157.803596 -47.742094)
		(width 0.10668)
		(layer "F.Cu")
		(net "NC_M2_0_NC11")
	)
	(segment
		(start 168.400984 -47.549816)
		(end 167.695626 -48.255174)
		(width 0.10668)
		(layer "F.Cu")
		(net "NC_M2_0_NC11")
	)
	(segment
		(start 169.558208 -47.549816)
		(end 168.400984 -47.549816)
		(width 0.10668)
		(layer "F.Cu")
		(net "NC_M2_0_NC11")
	)
	(segment
		(start 161.828988 -48.255174)
		(end 161.315908 -47.742094)
		(width 0.10668)
		(layer "F.Cu")
		(net "NC_M2_0_NC11")
	)
	(segment
		(start 167.695626 -48.255174)
		(end 161.828988 -48.255174)
		(width 0.10668)
		(layer "F.Cu")
		(net "NC_M2_0_NC11")
	)
	(via
		(at 157.803596 -47.742094)
		(size 0.762)
		(drill 0.381)
		(layers "F.Cu" "B.Cu")
		(net "NC_M2_0_NC11")
	)
	(segment
		(start 157.168596 -48.377094)
		(end 156.533596 -47.742094)
		(width 0.10668)
		(layer "F.Cu")
		(net "NC_M2_0_NC10")
	)
	(segment
		(start 169.558208 -48.049942)
		(end 168.3258 -48.049942)
		(width 0.10668)
		(layer "F.Cu")
		(net "NC_M2_0_NC10")
	)
	(segment
		(start 168.3258 -48.049942)
		(end 167.897048 -48.478694)
		(width 0.10668)
		(layer "F.Cu")
		(net "NC_M2_0_NC10")
	)
	(segment
		(start 167.897048 -48.478694)
		(end 161.49574 -48.478694)
		(width 0.10668)
		(layer "F.Cu")
		(net "NC_M2_0_NC10")
	)
	(segment
		(start 161.39414 -48.377094)
		(end 157.168596 -48.377094)
		(width 0.10668)
		(layer "F.Cu")
		(net "NC_M2_0_NC10")
	)
	(segment
		(start 161.49574 -48.478694)
		(end 161.39414 -48.377094)
		(width 0.10668)
		(layer "F.Cu")
		(net "NC_M2_0_NC10")
	)
	(via
		(at 156.533596 -47.742094)
		(size 0.762)
		(drill 0.381)
		(layers "F.Cu" "B.Cu")
		(net "NC_M2_0_NC10")
	)
	(segment
		(start 167.093138 -64.277748)
		(end 166.704772 -64.666114)
		(width 0.10668)
		(layer "F.Cu")
		(net "NC_M2_0_NC1")
	)
	(segment
		(start 169.558208 -55.049928)
		(end 170.492928 -55.049928)
		(width 0.10668)
		(layer "F.Cu")
		(net "NC_M2_0_NC1")
	)
	(segment
		(start 170.7388 -56.23814)
		(end 167.093138 -59.883802)
		(width 0.10668)
		(layer "F.Cu")
		(net "NC_M2_0_NC1")
	)
	(segment
		(start 170.7388 -55.2958)
		(end 170.7388 -56.23814)
		(width 0.10668)
		(layer "F.Cu")
		(net "NC_M2_0_NC1")
	)
	(segment
		(start 170.492928 -55.049928)
		(end 170.7388 -55.2958)
		(width 0.10668)
		(layer "F.Cu")
		(net "NC_M2_0_NC1")
	)
	(segment
		(start 167.093138 -59.883802)
		(end 167.093138 -64.277748)
		(width 0.10668)
		(layer "F.Cu")
		(net "NC_M2_0_NC1")
	)
	(via
		(at 166.704772 -64.666114)
		(size 0.762)
		(drill 0.381)
		(layers "F.Cu" "B.Cu")
		(net "NC_M2_0_NC1")
	)
	(via
		(at 324.266814 -421.933116)
		(size 0.6604)
		(drill 0.3302)
		(layers "F.Cu" "B.Cu")
		(net "NC_J108_N6")
	)
	(segment
		(start 324.649592 -422.315894)
		(end 324.266814 -421.933116)
		(width 0.10668)
		(layer "B.Cu")
		(net "NC_J108_N6")
	)
	(segment
		(start 324.649592 -424.689778)
		(end 324.649592 -422.315894)
		(width 0.10668)
		(layer "B.Cu")
		(net "NC_J108_N6")
	)
	(via
		(at 320.998088 -421.933116)
		(size 0.6604)
		(drill 0.3302)
		(layers "F.Cu" "B.Cu")
		(net "NC_J108_N4")
	)
	(segment
		(start 320.6496 -422.281604)
		(end 320.998088 -421.933116)
		(width 0.10668)
		(layer "B.Cu")
		(net "NC_J108_N4")
	)
	(segment
		(start 320.6496 -424.689778)
		(end 320.6496 -422.281604)
		(width 0.10668)
		(layer "B.Cu")
		(net "NC_J108_N4")
	)
	(via
		(at 310.93918 -424.1927)
		(size 0.6604)
		(drill 0.3302)
		(layers "F.Cu" "B.Cu")
		(net "NC_J108_N2")
	)
	(segment
		(start 315.99632 -423.69994)
		(end 311.43194 -423.69994)
		(width 0.10668)
		(layer "B.Cu")
		(net "NC_J108_N2")
	)
	(segment
		(start 316.649608 -424.689778)
		(end 316.649608 -424.353228)
		(width 0.10668)
		(layer "B.Cu")
		(net "NC_J108_N2")
	)
	(segment
		(start 311.43194 -423.69994)
		(end 310.93918 -424.1927)
		(width 0.10668)
		(layer "B.Cu")
		(net "NC_J108_N2")
	)
	(segment
		(start 316.649608 -424.353228)
		(end 315.99632 -423.69994)
		(width 0.10668)
		(layer "B.Cu")
		(net "NC_J108_N2")
	)
	(via
		(at 342.383364 -421.93337)
		(size 0.6604)
		(drill 0.3302)
		(layers "F.Cu" "B.Cu")
		(net "NC_J107_N6")
	)
	(segment
		(start 341.649812 -422.666922)
		(end 342.383364 -421.93337)
		(width 0.10668)
		(layer "B.Cu")
		(net "NC_J107_N6")
	)
	(segment
		(start 341.649812 -424.689778)
		(end 341.649812 -422.666922)
		(width 0.10668)
		(layer "B.Cu")
		(net "NC_J107_N6")
	)
	(via
		(at 337.940142 -421.926766)
		(size 0.6604)
		(drill 0.3302)
		(layers "F.Cu" "B.Cu")
		(net "NC_J107_N4")
	)
	(segment
		(start 337.64982 -422.217088)
		(end 337.940142 -421.926766)
		(width 0.10668)
		(layer "B.Cu")
		(net "NC_J107_N4")
	)
	(segment
		(start 337.64982 -424.689778)
		(end 337.64982 -422.217088)
		(width 0.10668)
		(layer "B.Cu")
		(net "NC_J107_N4")
	)
	(via
		(at 339.606382 -421.926766)
		(size 0.6604)
		(drill 0.3302)
		(layers "F.Cu" "B.Cu")
		(net "NC_J107_A5")
	)
	(segment
		(start 339.606382 -421.926766)
		(end 338.83727 -422.695878)
		(width 0.10668)
		(layer "B.Cu")
		(net "NC_J107_A5")
	)
	(segment
		(start 338.83727 -422.695878)
		(end 338.83727 -439.677302)
		(width 0.10668)
		(layer "B.Cu")
		(net "NC_J107_A5")
	)
	(segment
		(start 338.83727 -439.677302)
		(end 339.649816 -440.489848)
		(width 0.10668)
		(layer "B.Cu")
		(net "NC_J107_A5")
	)
	(via
		(at 336.261456 -421.939466)
		(size 0.6604)
		(drill 0.3302)
		(layers "F.Cu" "B.Cu")
		(net "NC_J107_A3")
	)
	(segment
		(start 334.837278 -423.363644)
		(end 334.837278 -439.677302)
		(width 0.10668)
		(layer "B.Cu")
		(net "NC_J107_A3")
	)
	(segment
		(start 336.261456 -421.939466)
		(end 334.837278 -423.363644)
		(width 0.10668)
		(layer "B.Cu")
		(net "NC_J107_A3")
	)
	(segment
		(start 334.837278 -439.677302)
		(end 335.649824 -440.489848)
		(width 0.10668)
		(layer "B.Cu")
		(net "NC_J107_A3")
	)
	(via
		(at 330.254356 -422.373552)
		(size 0.6604)
		(drill 0.3302)
		(layers "F.Cu" "B.Cu")
		(net "NC_J107_A1")
	)
	(segment
		(start 330.837286 -422.956482)
		(end 330.837286 -439.677302)
		(width 0.10668)
		(layer "B.Cu")
		(net "NC_J107_A1")
	)
	(segment
		(start 330.837286 -439.677302)
		(end 331.649832 -440.489848)
		(width 0.10668)
		(layer "B.Cu")
		(net "NC_J107_A1")
	)
	(segment
		(start 330.254356 -422.373552)
		(end 330.837286 -422.956482)
		(width 0.10668)
		(layer "B.Cu")
		(net "NC_J107_A1")
	)
	(via
		(at 379.951996 -422.70934)
		(size 0.6604)
		(drill 0.3302)
		(layers "F.Cu" "B.Cu")
		(net "NC_J106_A5")
	)
	(segment
		(start 388.937246 -439.677302)
		(end 389.749792 -440.489848)
		(width 0.10668)
		(layer "B.Cu")
		(net "NC_J106_A5")
	)
	(segment
		(start 379.951996 -422.70934)
		(end 387.246114 -422.70934)
		(width 0.10668)
		(layer "B.Cu")
		(net "NC_J106_A5")
	)
	(segment
		(start 388.937246 -424.400472)
		(end 388.937246 -439.677302)
		(width 0.10668)
		(layer "B.Cu")
		(net "NC_J106_A5")
	)
	(segment
		(start 387.246114 -422.70934)
		(end 388.937246 -424.400472)
		(width 0.10668)
		(layer "B.Cu")
		(net "NC_J106_A5")
	)
	(segment
		(start 93.747844 -294.070278)
		(end 93.280992 -294.336216)
		(width 0.10668)
		(layer "F.Cu")
		(net "NC_CPU1_USB3_USB11_TXP")
	)
	(via
		(at 93.280992 -294.336216)
		(size 0.4064)
		(drill 0.2032)
		(layers "F.Cu" "B.Cu")
		(net "NC_CPU1_USB3_USB11_TXP")
	)
	(segment
		(start 93.277944 -294.880284)
		(end 92.811092 -295.146222)
		(width 0.10668)
		(layer "F.Cu")
		(net "NC_CPU1_USB3_USB11_TXN")
	)
	(via
		(at 92.811092 -295.146222)
		(size 0.4064)
		(drill 0.2032)
		(layers "F.Cu" "B.Cu")
		(net "NC_CPU1_USB3_USB11_TXN")
	)
	(segment
		(start 89.987882 -295.69029)
		(end 89.52103 -295.956228)
		(width 0.10668)
		(layer "F.Cu")
		(net "NC_CPU1_USB3_USB11_RXP")
	)
	(via
		(at 89.52103 -295.956228)
		(size 0.4064)
		(drill 0.2032)
		(layers "F.Cu" "B.Cu")
		(net "NC_CPU1_USB3_USB11_RXP")
	)
	(segment
		(start 89.517982 -294.880284)
		(end 89.05113 -295.146222)
		(width 0.10668)
		(layer "F.Cu")
		(net "NC_CPU1_USB3_USB11_RXN")
	)
	(via
		(at 89.05113 -295.146222)
		(size 0.4064)
		(drill 0.2032)
		(layers "F.Cu" "B.Cu")
		(net "NC_CPU1_USB3_USB11_RXN")
	)
	(segment
		(start 82.937858 -294.880284)
		(end 82.471006 -295.146222)
		(width 0.10668)
		(layer "F.Cu")
		(net "NC_CPU1_USB3_USB10_TXP")
	)
	(via
		(at 82.471006 -295.146222)
		(size 0.4064)
		(drill 0.2032)
		(layers "F.Cu" "B.Cu")
		(net "NC_CPU1_USB3_USB10_TXP")
	)
	(segment
		(start 83.408012 -295.69029)
		(end 82.940906 -295.956228)
		(width 0.10668)
		(layer "F.Cu")
		(net "NC_CPU1_USB3_USB10_TXN")
	)
	(via
		(at 82.940906 -295.956228)
		(size 0.4064)
		(drill 0.2032)
		(layers "F.Cu" "B.Cu")
		(net "NC_CPU1_USB3_USB10_TXN")
	)
	(segment
		(start 87.167974 -295.69029)
		(end 86.701122 -295.956228)
		(width 0.10668)
		(layer "F.Cu")
		(net "NC_CPU1_USB3_USB10_RXP")
	)
	(via
		(at 86.701122 -295.956228)
		(size 0.4064)
		(drill 0.2032)
		(layers "F.Cu" "B.Cu")
		(net "NC_CPU1_USB3_USB10_RXP")
	)
	(segment
		(start 86.69782 -294.880284)
		(end 86.230968 -295.146222)
		(width 0.10668)
		(layer "F.Cu")
		(net "NC_CPU1_USB3_USB10_RXN")
	)
	(via
		(at 86.230968 -295.146222)
		(size 0.4064)
		(drill 0.2032)
		(layers "F.Cu" "B.Cu")
		(net "NC_CPU1_USB3_USB10_RXN")
	)
	(segment
		(start 118.827804 -225.310446)
		(end 119.294656 -225.044508)
		(width 0.10668)
		(layer "F.Cu")
		(net "NC_CPU1_USB3_USB01_TXP")
	)
	(via
		(at 119.294656 -225.044508)
		(size 0.4064)
		(drill 0.2032)
		(layers "F.Cu" "B.Cu")
		(net "NC_CPU1_USB3_USB01_TXP")
	)
	(segment
		(start 119.767858 -225.310446)
		(end 120.23471 -225.044508)
		(width 0.10668)
		(layer "F.Cu")
		(net "NC_CPU1_USB3_USB01_TXN")
	)
	(via
		(at 120.23471 -225.044508)
		(size 0.4064)
		(drill 0.2032)
		(layers "F.Cu" "B.Cu")
		(net "NC_CPU1_USB3_USB01_TXN")
	)
	(segment
		(start 119.767858 -223.690434)
		(end 120.23471 -223.424496)
		(width 0.10668)
		(layer "F.Cu")
		(net "NC_CPU1_USB3_USB01_RXP")
	)
	(via
		(at 120.23471 -223.424496)
		(size 0.4064)
		(drill 0.2032)
		(layers "F.Cu" "B.Cu")
		(net "NC_CPU1_USB3_USB01_RXP")
	)
	(segment
		(start 120.707912 -223.690434)
		(end 121.174764 -223.424496)
		(width 0.10668)
		(layer "F.Cu")
		(net "NC_CPU1_USB3_USB01_RXN")
	)
	(via
		(at 121.174764 -223.424496)
		(size 0.4064)
		(drill 0.2032)
		(layers "F.Cu" "B.Cu")
		(net "NC_CPU1_USB3_USB01_RXN")
	)
	(segment
		(start 122.587766 -223.690434)
		(end 123.054618 -223.424496)
		(width 0.10668)
		(layer "F.Cu")
		(net "NC_CPU1_USB3_USB00_TXP")
	)
	(via
		(at 123.054618 -223.424496)
		(size 0.4064)
		(drill 0.2032)
		(layers "F.Cu" "B.Cu")
		(net "NC_CPU1_USB3_USB00_TXP")
	)
	(segment
		(start 123.52782 -223.690434)
		(end 123.994672 -223.424496)
		(width 0.10668)
		(layer "F.Cu")
		(net "NC_CPU1_USB3_USB00_TXN")
	)
	(via
		(at 123.994672 -223.424496)
		(size 0.4064)
		(drill 0.2032)
		(layers "F.Cu" "B.Cu")
		(net "NC_CPU1_USB3_USB00_TXN")
	)
	(segment
		(start 121.647966 -225.310446)
		(end 122.114818 -225.044508)
		(width 0.10668)
		(layer "F.Cu")
		(net "NC_CPU1_USB3_USB00_RXP")
	)
	(via
		(at 122.114818 -225.044508)
		(size 0.4064)
		(drill 0.2032)
		(layers "F.Cu" "B.Cu")
		(net "NC_CPU1_USB3_USB00_RXP")
	)
	(segment
		(start 122.587766 -225.310446)
		(end 123.054618 -225.044508)
		(width 0.10668)
		(layer "F.Cu")
		(net "NC_CPU1_USB3_USB00_RXN")
	)
	(via
		(at 123.054618 -225.044508)
		(size 0.4064)
		(drill 0.2032)
		(layers "F.Cu" "B.Cu")
		(net "NC_CPU1_USB3_USB00_RXN")
	)
	(segment
		(start 91.397836 -294.880284)
		(end 90.930984 -295.146222)
		(width 0.10668)
		(layer "F.Cu")
		(net "NC_CPU1_USB2_USB11_DP")
	)
	(via
		(at 90.930984 -295.146222)
		(size 0.4064)
		(drill 0.2032)
		(layers "F.Cu" "B.Cu")
		(net "NC_CPU1_USB2_USB11_DP")
	)
	(segment
		(start 91.86799 -295.69029)
		(end 91.401138 -295.956228)
		(width 0.10668)
		(layer "F.Cu")
		(net "NC_CPU1_USB2_USB11_DN")
	)
	(via
		(at 91.401138 -295.956228)
		(size 0.4064)
		(drill 0.2032)
		(layers "F.Cu" "B.Cu")
		(net "NC_CPU1_USB2_USB11_DN")
	)
	(segment
		(start 85.287866 -295.69029)
		(end 84.821014 -295.956228)
		(width 0.10668)
		(layer "F.Cu")
		(net "NC_CPU1_USB2_USB10_DP")
	)
	(via
		(at 84.821014 -295.956228)
		(size 0.4064)
		(drill 0.2032)
		(layers "F.Cu" "B.Cu")
		(net "NC_CPU1_USB2_USB10_DP")
	)
	(segment
		(start 84.817966 -294.880284)
		(end 84.351114 -295.146222)
		(width 0.10668)
		(layer "F.Cu")
		(net "NC_CPU1_USB2_USB10_DN")
	)
	(via
		(at 84.351114 -295.146222)
		(size 0.4064)
		(drill 0.2032)
		(layers "F.Cu" "B.Cu")
		(net "NC_CPU1_USB2_USB10_DN")
	)
	(segment
		(start 120.707912 -222.070422)
		(end 121.174764 -221.804484)
		(width 0.10668)
		(layer "F.Cu")
		(net "NC_CPU1_USB2_USB01_DP")
	)
	(via
		(at 121.174764 -221.804484)
		(size 0.4064)
		(drill 0.2032)
		(layers "F.Cu" "B.Cu")
		(net "NC_CPU1_USB2_USB01_DP")
	)
	(segment
		(start 119.767858 -222.070422)
		(end 120.23471 -221.804484)
		(width 0.10668)
		(layer "F.Cu")
		(net "NC_CPU1_USB2_USB01_DN")
	)
	(via
		(at 120.23471 -221.804484)
		(size 0.4064)
		(drill 0.2032)
		(layers "F.Cu" "B.Cu")
		(net "NC_CPU1_USB2_USB01_DN")
	)
	(segment
		(start 122.587766 -222.070422)
		(end 123.054618 -221.804484)
		(width 0.10668)
		(layer "F.Cu")
		(net "NC_CPU1_USB2_USB00_DP")
	)
	(via
		(at 123.054618 -221.804484)
		(size 0.4064)
		(drill 0.2032)
		(layers "F.Cu" "B.Cu")
		(net "NC_CPU1_USB2_USB00_DP")
	)
	(segment
		(start 123.52782 -222.070422)
		(end 123.994672 -221.804484)
		(width 0.10668)
		(layer "F.Cu")
		(net "NC_CPU1_USB2_USB00_DN")
	)
	(via
		(at 123.994672 -221.804484)
		(size 0.4064)
		(drill 0.2032)
		(layers "F.Cu" "B.Cu")
		(net "NC_CPU1_USB2_USB00_DN")
	)
	(segment
		(start 110.1979 -294.880284)
		(end 109.731048 -295.146222)
		(width 0.10668)
		(layer "F.Cu")
		(net "NC_CPU1_USB11_OC_N")
	)
	(via
		(at 109.731048 -295.146222)
		(size 0.4064)
		(drill 0.2032)
		(layers "F.Cu" "B.Cu")
		(net "NC_CPU1_USB11_OC_N")
	)
	(segment
		(start 110.6678 -294.070278)
		(end 110.200948 -294.336216)
		(width 0.10668)
		(layer "F.Cu")
		(net "NC_CPU1_USB10_OC_N")
	)
	(via
		(at 110.200948 -294.336216)
		(size 0.4064)
		(drill 0.2032)
		(layers "F.Cu" "B.Cu")
		(net "NC_CPU1_USB10_OC_N")
	)
	(segment
		(start 124.467874 -225.310446)
		(end 124.934726 -225.044508)
		(width 0.10668)
		(layer "F.Cu")
		(net "NC_CPU1_USB01_OC_N")
	)
	(via
		(at 124.934726 -225.044508)
		(size 0.4064)
		(drill 0.2032)
		(layers "F.Cu" "B.Cu")
		(net "NC_CPU1_USB01_OC_N")
	)
	(segment
		(start 125.407928 -225.310446)
		(end 125.87478 -225.044508)
		(width 0.10668)
		(layer "F.Cu")
		(net "NC_CPU1_USB00_OC_N")
	)
	(via
		(at 125.87478 -225.044508)
		(size 0.4064)
		(drill 0.2032)
		(layers "F.Cu" "B.Cu")
		(net "NC_CPU1_USB00_OC_N")
	)
	(segment
		(start 141.217904 -294.880284)
		(end 141.684756 -295.146222)
		(width 0.10668)
		(layer "F.Cu")
		(net "NC_CPU1_PWR_BTN_N")
	)
	(via
		(at 141.684756 -295.146222)
		(size 0.4064)
		(drill 0.2032)
		(layers "F.Cu" "B.Cu")
		(net "NC_CPU1_PWR_BTN_N")
	)
	(segment
		(start 117.41785 -224.50044)
		(end 117.884702 -224.234502)
		(width 0.10668)
		(layer "F.Cu")
		(net "NC_CPU1_AZ_SYNC")
	)
	(via
		(at 117.884702 -224.234502)
		(size 0.4064)
		(drill 0.2032)
		(layers "F.Cu" "B.Cu")
		(net "NC_CPU1_AZ_SYNC")
	)
	(segment
		(start 116.94795 -222.070422)
		(end 117.414802 -221.804484)
		(width 0.10668)
		(layer "F.Cu")
		(net "NC_CPU1_AZ_SDOUT")
	)
	(via
		(at 117.414802 -221.804484)
		(size 0.4064)
		(drill 0.2032)
		(layers "F.Cu" "B.Cu")
		(net "NC_CPU1_AZ_SDOUT")
	)
	(segment
		(start 116.007896 -222.070422)
		(end 116.474748 -221.804484)
		(width 0.10668)
		(layer "F.Cu")
		(net "NC_CPU1_AZ_SDIN2")
	)
	(via
		(at 116.474748 -221.804484)
		(size 0.4064)
		(drill 0.2032)
		(layers "F.Cu" "B.Cu")
		(net "NC_CPU1_AZ_SDIN2")
	)
	(segment
		(start 116.477796 -224.50044)
		(end 116.944648 -224.234502)
		(width 0.10668)
		(layer "F.Cu")
		(net "NC_CPU1_AZ_SDIN1")
	)
	(via
		(at 116.944648 -224.234502)
		(size 0.4064)
		(drill 0.2032)
		(layers "F.Cu" "B.Cu")
		(net "NC_CPU1_AZ_SDIN1")
	)
	(segment
		(start 116.007896 -223.690434)
		(end 116.474748 -223.424496)
		(width 0.10668)
		(layer "F.Cu")
		(net "NC_CPU1_AZ_SDIN0")
	)
	(via
		(at 116.474748 -223.424496)
		(size 0.4064)
		(drill 0.2032)
		(layers "F.Cu" "B.Cu")
		(net "NC_CPU1_AZ_SDIN0")
	)
	(segment
		(start 115.067842 -222.070422)
		(end 115.534694 -221.804484)
		(width 0.10668)
		(layer "F.Cu")
		(net "NC_CPU1_AZ_RST_N")
	)
	(via
		(at 115.534694 -221.804484)
		(size 0.4064)
		(drill 0.2032)
		(layers "F.Cu" "B.Cu")
		(net "NC_CPU1_AZ_RST_N")
	)
	(segment
		(start 116.94795 -223.690434)
		(end 117.414802 -223.424496)
		(width 0.10668)
		(layer "F.Cu")
		(net "NC_CPU1_AZ_BITCLK")
	)
	(via
		(at 117.414802 -223.424496)
		(size 0.4064)
		(drill 0.2032)
		(layers "F.Cu" "B.Cu")
		(net "NC_CPU1_AZ_BITCLK")
	)
	(segment
		(start 365.357918 -224.500186)
		(end 365.82477 -224.234248)
		(width 0.10668)
		(layer "F.Cu")
		(net "NC_CPU0_AZ_SYNC")
	)
	(via
		(at 365.82477 -224.234248)
		(size 0.4064)
		(drill 0.2032)
		(layers "F.Cu" "B.Cu")
		(net "NC_CPU0_AZ_SYNC")
	)
	(segment
		(start 364.888018 -222.070168)
		(end 365.35487 -221.80423)
		(width 0.10668)
		(layer "F.Cu")
		(net "NC_CPU0_AZ_SDOUT")
	)
	(via
		(at 365.35487 -221.80423)
		(size 0.4064)
		(drill 0.2032)
		(layers "F.Cu" "B.Cu")
		(net "NC_CPU0_AZ_SDOUT")
	)
	(segment
		(start 363.947964 -222.070168)
		(end 364.414816 -221.80423)
		(width 0.10668)
		(layer "F.Cu")
		(net "NC_CPU0_AZ_SDIN2")
	)
	(via
		(at 364.414816 -221.80423)
		(size 0.4064)
		(drill 0.2032)
		(layers "F.Cu" "B.Cu")
		(net "NC_CPU0_AZ_SDIN2")
	)
	(segment
		(start 364.417864 -224.500186)
		(end 364.884716 -224.234248)
		(width 0.10668)
		(layer "F.Cu")
		(net "NC_CPU0_AZ_SDIN1")
	)
	(via
		(at 364.884716 -224.234248)
		(size 0.4064)
		(drill 0.2032)
		(layers "F.Cu" "B.Cu")
		(net "NC_CPU0_AZ_SDIN1")
	)
	(segment
		(start 363.947964 -223.69018)
		(end 364.414816 -223.424242)
		(width 0.10668)
		(layer "F.Cu")
		(net "NC_CPU0_AZ_SDIN0")
	)
	(via
		(at 364.414816 -223.424242)
		(size 0.4064)
		(drill 0.2032)
		(layers "F.Cu" "B.Cu")
		(net "NC_CPU0_AZ_SDIN0")
	)
	(segment
		(start 363.00791 -222.070168)
		(end 363.474762 -221.80423)
		(width 0.10668)
		(layer "F.Cu")
		(net "NC_CPU0_AZ_RST_N")
	)
	(via
		(at 363.474762 -221.80423)
		(size 0.4064)
		(drill 0.2032)
		(layers "F.Cu" "B.Cu")
		(net "NC_CPU0_AZ_RST_N")
	)
	(segment
		(start 364.888018 -223.69018)
		(end 365.35487 -223.424242)
		(width 0.10668)
		(layer "F.Cu")
		(net "NC_CPU0_AZ_BITCLK")
	)
	(via
		(at 365.35487 -223.424242)
		(size 0.4064)
		(drill 0.2032)
		(layers "F.Cu" "B.Cu")
		(net "NC_CPU0_AZ_BITCLK")
	)
	(segment
		(start 74.461878 -8.320024)
		(end 74.461878 -6.496304)
		(width 0.10668)
		(layer "F.Cu")
		(net "NCSI_OCP_V3_2_TX_EN")
	)
	(segment
		(start 74.461878 -6.496304)
		(end 74.182224 -6.21665)
		(width 0.10668)
		(layer "F.Cu")
		(net "NCSI_OCP_V3_2_TX_EN")
	)
	(via
		(at 190.64224 -68.231766)
		(size 0.6604)
		(drill 0.3302)
		(layers "F.Cu" "B.Cu")
		(net "NCSI_OCP_V3_2_TX_EN")
	)
	(via
		(at 74.182224 -6.21665)
		(size 0.508)
		(drill 0.254)
		(layers "F.Cu" "B.Cu")
		(net "NCSI_OCP_V3_2_TX_EN")
	)
	(segment
		(start 108.471716 -39.641018)
		(end 104.11079 -35.280092)
		(width 0.10668)
		(layer "B.Cu")
		(net "NCSI_OCP_V3_2_TX_EN")
	)
	(segment
		(start 87.26932 -17.03324)
		(end 84.96046 -14.72438)
		(width 0.10668)
		(layer "B.Cu")
		(net "NCSI_OCP_V3_2_TX_EN")
	)
	(segment
		(start 191.76492 -64.063626)
		(end 190.38824 -64.063626)
		(width 0.10668)
		(layer "B.Cu")
		(net "NCSI_OCP_V3_2_TX_EN")
	)
	(segment
		(start 190.64224 -68.231766)
		(end 190.28156 -67.871086)
		(width 0.10668)
		(layer "B.Cu")
		(net "NCSI_OCP_V3_2_TX_EN")
	)
	(segment
		(start 79.825596 -10.515346)
		(end 78.10119 -8.79094)
		(width 0.10668)
		(layer "B.Cu")
		(net "NCSI_OCP_V3_2_TX_EN")
	)
	(segment
		(start 190.28156 -67.871086)
		(end 190.28156 -67.256406)
		(width 0.10668)
		(layer "B.Cu")
		(net "NCSI_OCP_V3_2_TX_EN")
	)
	(segment
		(start 82.17535 -14.72438)
		(end 79.825596 -12.374626)
		(width 0.10668)
		(layer "B.Cu")
		(net "NCSI_OCP_V3_2_TX_EN")
	)
	(segment
		(start 190.28156 -66.021966)
		(end 190.38824 -65.915286)
		(width 0.10668)
		(layer "B.Cu")
		(net "NCSI_OCP_V3_2_TX_EN")
	)
	(segment
		(start 190.38824 -66.532506)
		(end 190.28156 -66.425826)
		(width 0.10668)
		(layer "B.Cu")
		(net "NCSI_OCP_V3_2_TX_EN")
	)
	(segment
		(start 91.13012 -32.29864)
		(end 91.13012 -31.525972)
		(width 0.10668)
		(layer "B.Cu")
		(net "NCSI_OCP_V3_2_TX_EN")
	)
	(segment
		(start 147.009358 -47.74946)
		(end 135.861552 -47.74946)
		(width 0.10668)
		(layer "B.Cu")
		(net "NCSI_OCP_V3_2_TX_EN")
	)
	(segment
		(start 162.97656 -56.05145)
		(end 160.41751 -53.4924)
		(width 0.10668)
		(layer "B.Cu")
		(net "NCSI_OCP_V3_2_TX_EN")
	)
	(segment
		(start 73.67905 -6.21665)
		(end 74.182224 -6.21665)
		(width 0.10668)
		(layer "B.Cu")
		(net "NCSI_OCP_V3_2_TX_EN")
	)
	(segment
		(start 192.17894 -66.532506)
		(end 190.38824 -66.532506)
		(width 0.10668)
		(layer "B.Cu")
		(net "NCSI_OCP_V3_2_TX_EN")
	)
	(segment
		(start 173.84522 -58.447686)
		(end 173.059598 -59.233308)
		(width 0.10668)
		(layer "B.Cu")
		(net "NCSI_OCP_V3_2_TX_EN")
	)
	(segment
		(start 190.38824 -67.149726)
		(end 192.17894 -67.149726)
		(width 0.10668)
		(layer "B.Cu")
		(net "NCSI_OCP_V3_2_TX_EN")
	)
	(segment
		(start 190.38824 -64.063626)
		(end 190.28156 -63.956946)
		(width 0.10668)
		(layer "B.Cu")
		(net "NCSI_OCP_V3_2_TX_EN")
	)
	(segment
		(start 135.861552 -47.74946)
		(end 133.455156 -45.343064)
		(width 0.10668)
		(layer "B.Cu")
		(net "NCSI_OCP_V3_2_TX_EN")
	)
	(segment
		(start 190.28156 -67.256406)
		(end 190.38824 -67.149726)
		(width 0.10668)
		(layer "B.Cu")
		(net "NCSI_OCP_V3_2_TX_EN")
	)
	(segment
		(start 190.28156 -65.191386)
		(end 190.28156 -64.787526)
		(width 0.10668)
		(layer "B.Cu")
		(net "NCSI_OCP_V3_2_TX_EN")
	)
	(segment
		(start 170.892724 -59.233308)
		(end 167.710866 -56.05145)
		(width 0.10668)
		(layer "B.Cu")
		(net "NCSI_OCP_V3_2_TX_EN")
	)
	(segment
		(start 190.38824 -65.915286)
		(end 192.17894 -65.915286)
		(width 0.10668)
		(layer "B.Cu")
		(net "NCSI_OCP_V3_2_TX_EN")
	)
	(segment
		(start 190.28156 -63.956946)
		(end 190.28156 -62.74308)
		(width 0.10668)
		(layer "B.Cu")
		(net "NCSI_OCP_V3_2_TX_EN")
	)
	(segment
		(start 152.752298 -53.4924)
		(end 147.009358 -47.74946)
		(width 0.10668)
		(layer "B.Cu")
		(net "NCSI_OCP_V3_2_TX_EN")
	)
	(segment
		(start 124.516642 -44.538138)
		(end 119.619522 -39.641018)
		(width 0.10668)
		(layer "B.Cu")
		(net "NCSI_OCP_V3_2_TX_EN")
	)
	(segment
		(start 192.17894 -65.915286)
		(end 192.28562 -65.808606)
		(width 0.10668)
		(layer "B.Cu")
		(net "NCSI_OCP_V3_2_TX_EN")
	)
	(segment
		(start 92.5957 -33.76422)
		(end 91.13012 -32.29864)
		(width 0.10668)
		(layer "B.Cu")
		(net "NCSI_OCP_V3_2_TX_EN")
	)
	(segment
		(start 160.41751 -53.4924)
		(end 152.752298 -53.4924)
		(width 0.10668)
		(layer "B.Cu")
		(net "NCSI_OCP_V3_2_TX_EN")
	)
	(segment
		(start 191.8716 -64.574166)
		(end 191.8716 -64.170306)
		(width 0.10668)
		(layer "B.Cu")
		(net "NCSI_OCP_V3_2_TX_EN")
	)
	(segment
		(start 190.38824 -64.680846)
		(end 191.76492 -64.680846)
		(width 0.10668)
		(layer "B.Cu")
		(net "NCSI_OCP_V3_2_TX_EN")
	)
	(segment
		(start 73.697084 -8.79094)
		(end 73.217024 -8.31088)
		(width 0.10668)
		(layer "B.Cu")
		(net "NCSI_OCP_V3_2_TX_EN")
	)
	(segment
		(start 84.96046 -14.72438)
		(end 82.17535 -14.72438)
		(width 0.10668)
		(layer "B.Cu")
		(net "NCSI_OCP_V3_2_TX_EN")
	)
	(segment
		(start 190.28156 -64.787526)
		(end 190.38824 -64.680846)
		(width 0.10668)
		(layer "B.Cu")
		(net "NCSI_OCP_V3_2_TX_EN")
	)
	(segment
		(start 129.745994 -45.343064)
		(end 128.941068 -44.538138)
		(width 0.10668)
		(layer "B.Cu")
		(net "NCSI_OCP_V3_2_TX_EN")
	)
	(segment
		(start 87.26932 -27.665172)
		(end 87.26932 -17.03324)
		(width 0.10668)
		(layer "B.Cu")
		(net "NCSI_OCP_V3_2_TX_EN")
	)
	(segment
		(start 192.17894 -67.149726)
		(end 192.28562 -67.043046)
		(width 0.10668)
		(layer "B.Cu")
		(net "NCSI_OCP_V3_2_TX_EN")
	)
	(segment
		(start 104.11079 -35.280092)
		(end 100.451158 -33.76422)
		(width 0.10668)
		(layer "B.Cu")
		(net "NCSI_OCP_V3_2_TX_EN")
	)
	(segment
		(start 133.455156 -45.343064)
		(end 129.745994 -45.343064)
		(width 0.10668)
		(layer "B.Cu")
		(net "NCSI_OCP_V3_2_TX_EN")
	)
	(segment
		(start 78.10119 -8.79094)
		(end 73.697084 -8.79094)
		(width 0.10668)
		(layer "B.Cu")
		(net "NCSI_OCP_V3_2_TX_EN")
	)
	(segment
		(start 192.17894 -65.298066)
		(end 190.38824 -65.298066)
		(width 0.10668)
		(layer "B.Cu")
		(net "NCSI_OCP_V3_2_TX_EN")
	)
	(segment
		(start 190.38824 -65.298066)
		(end 190.28156 -65.191386)
		(width 0.10668)
		(layer "B.Cu")
		(net "NCSI_OCP_V3_2_TX_EN")
	)
	(segment
		(start 79.825596 -12.374626)
		(end 79.825596 -10.515346)
		(width 0.10668)
		(layer "B.Cu")
		(net "NCSI_OCP_V3_2_TX_EN")
	)
	(segment
		(start 190.28156 -66.425826)
		(end 190.28156 -66.021966)
		(width 0.10668)
		(layer "B.Cu")
		(net "NCSI_OCP_V3_2_TX_EN")
	)
	(segment
		(start 192.28562 -65.808606)
		(end 192.28562 -65.404746)
		(width 0.10668)
		(layer "B.Cu")
		(net "NCSI_OCP_V3_2_TX_EN")
	)
	(segment
		(start 128.941068 -44.538138)
		(end 124.516642 -44.538138)
		(width 0.10668)
		(layer "B.Cu")
		(net "NCSI_OCP_V3_2_TX_EN")
	)
	(segment
		(start 191.76492 -64.680846)
		(end 191.8716 -64.574166)
		(width 0.10668)
		(layer "B.Cu")
		(net "NCSI_OCP_V3_2_TX_EN")
	)
	(segment
		(start 192.28562 -65.404746)
		(end 192.17894 -65.298066)
		(width 0.10668)
		(layer "B.Cu")
		(net "NCSI_OCP_V3_2_TX_EN")
	)
	(segment
		(start 191.3636 -68.953126)
		(end 190.64224 -68.231766)
		(width 0.10668)
		(layer "B.Cu")
		(net "NCSI_OCP_V3_2_TX_EN")
	)
	(segment
		(start 189.555374 -62.016894)
		(end 180.938932 -58.447686)
		(width 0.10668)
		(layer "B.Cu")
		(net "NCSI_OCP_V3_2_TX_EN")
	)
	(segment
		(start 190.28156 -62.74308)
		(end 189.555374 -62.016894)
		(width 0.10668)
		(layer "B.Cu")
		(net "NCSI_OCP_V3_2_TX_EN")
	)
	(segment
		(start 73.217024 -6.678676)
		(end 73.67905 -6.21665)
		(width 0.10668)
		(layer "B.Cu")
		(net "NCSI_OCP_V3_2_TX_EN")
	)
	(segment
		(start 195.55333 -68.953126)
		(end 191.3636 -68.953126)
		(width 0.10668)
		(layer "B.Cu")
		(net "NCSI_OCP_V3_2_TX_EN")
	)
	(segment
		(start 167.710866 -56.05145)
		(end 162.97656 -56.05145)
		(width 0.10668)
		(layer "B.Cu")
		(net "NCSI_OCP_V3_2_TX_EN")
	)
	(segment
		(start 192.28562 -67.043046)
		(end 192.28562 -66.639186)
		(width 0.10668)
		(layer "B.Cu")
		(net "NCSI_OCP_V3_2_TX_EN")
	)
	(segment
		(start 191.8716 -64.170306)
		(end 191.76492 -64.063626)
		(width 0.10668)
		(layer "B.Cu")
		(net "NCSI_OCP_V3_2_TX_EN")
	)
	(segment
		(start 100.451158 -33.76422)
		(end 92.5957 -33.76422)
		(width 0.10668)
		(layer "B.Cu")
		(net "NCSI_OCP_V3_2_TX_EN")
	)
	(segment
		(start 180.938932 -58.447686)
		(end 173.84522 -58.447686)
		(width 0.10668)
		(layer "B.Cu")
		(net "NCSI_OCP_V3_2_TX_EN")
	)
	(segment
		(start 73.217024 -8.31088)
		(end 73.217024 -6.678676)
		(width 0.10668)
		(layer "B.Cu")
		(net "NCSI_OCP_V3_2_TX_EN")
	)
	(segment
		(start 173.059598 -59.233308)
		(end 170.892724 -59.233308)
		(width 0.10668)
		(layer "B.Cu")
		(net "NCSI_OCP_V3_2_TX_EN")
	)
	(segment
		(start 91.13012 -31.525972)
		(end 87.26932 -27.665172)
		(width 0.10668)
		(layer "B.Cu")
		(net "NCSI_OCP_V3_2_TX_EN")
	)
	(segment
		(start 192.28562 -66.639186)
		(end 192.17894 -66.532506)
		(width 0.10668)
		(layer "B.Cu")
		(net "NCSI_OCP_V3_2_TX_EN")
	)
	(segment
		(start 119.619522 -39.641018)
		(end 108.471716 -39.641018)
		(width 0.10668)
		(layer "B.Cu")
		(net "NCSI_OCP_V3_2_TX_EN")
	)
	(segment
		(start 73.86193 -8.320024)
		(end 73.86193 -7.20471)
		(width 0.10668)
		(layer "F.Cu")
		(net "NCSI_OCP_V3_2_TXD1")
	)
	(via
		(at 73.86193 -7.20471)
		(size 0.508)
		(drill 0.254)
		(layers "F.Cu" "B.Cu")
		(net "NCSI_OCP_V3_2_TXD1")
	)
	(segment
		(start 197.917054 -68.17106)
		(end 197.810374 -68.06438)
		(width 0.10668)
		(layer "B.Cu")
		(net "NCSI_OCP_V3_2_TXD1")
	)
	(segment
		(start 197.086474 -68.17106)
		(end 196.682614 -68.17106)
		(width 0.10668)
		(layer "B.Cu")
		(net "NCSI_OCP_V3_2_TXD1")
	)
	(segment
		(start 200.238614 -67.866768)
		(end 199.562974 -67.191128)
		(width 0.10668)
		(layer "B.Cu")
		(net "NCSI_OCP_V3_2_TXD1")
	)
	(segment
		(start 193.933318 -66.211196)
		(end 194.328542 -65.815972)
		(width 0.10668)
		(layer "B.Cu")
		(net "NCSI_OCP_V3_2_TXD1")
	)
	(segment
		(start 200.602596 -71.55307)
		(end 200.238614 -71.189088)
		(width 0.10668)
		(layer "B.Cu")
		(net "NCSI_OCP_V3_2_TXD1")
	)
	(segment
		(start 197.810374 -67.297808)
		(end 197.703694 -67.191128)
		(width 0.10668)
		(layer "B.Cu")
		(net "NCSI_OCP_V3_2_TXD1")
	)
	(segment
		(start 193.060066 -65.48882)
		(end 193.060066 -65.337944)
		(width 0.10668)
		(layer "B.Cu")
		(net "NCSI_OCP_V3_2_TXD1")
	)
	(segment
		(start 152.896062 -52.9463)
		(end 147.165822 -47.21606)
		(width 0.10668)
		(layer "B.Cu")
		(net "NCSI_OCP_V3_2_TXD1")
	)
	(segment
		(start 193.45529 -64.791844)
		(end 190.574422 -61.910976)
		(width 0.10668)
		(layer "B.Cu")
		(net "NCSI_OCP_V3_2_TXD1")
	)
	(segment
		(start 172.857414 -58.745628)
		(end 171.094908 -58.745628)
		(width 0.10668)
		(layer "B.Cu")
		(net "NCSI_OCP_V3_2_TXD1")
	)
	(segment
		(start 78.2574 -8.190738)
		(end 75.5142 -8.190738)
		(width 0.10668)
		(layer "B.Cu")
		(net "NCSI_OCP_V3_2_TXD1")
	)
	(segment
		(start 194.328542 -65.815972)
		(end 194.328542 -65.665096)
		(width 0.10668)
		(layer "B.Cu")
		(net "NCSI_OCP_V3_2_TXD1")
	)
	(segment
		(start 196.682614 -68.17106)
		(end 196.575934 -68.06438)
		(width 0.10668)
		(layer "B.Cu")
		(net "NCSI_OCP_V3_2_TXD1")
	)
	(segment
		(start 75.40752 -8.084058)
		(end 75.40752 -7.33933)
		(width 0.10668)
		(layer "B.Cu")
		(net "NCSI_OCP_V3_2_TXD1")
	)
	(segment
		(start 163.178998 -55.56377)
		(end 160.561528 -52.9463)
		(width 0.10668)
		(layer "B.Cu")
		(net "NCSI_OCP_V3_2_TXD1")
	)
	(segment
		(start 75.30084 -7.23265)
		(end 74.89698 -7.23265)
		(width 0.10668)
		(layer "B.Cu")
		(net "NCSI_OCP_V3_2_TXD1")
	)
	(segment
		(start 119.799354 -39.130732)
		(end 108.683298 -39.130732)
		(width 0.10668)
		(layer "B.Cu")
		(net "NCSI_OCP_V3_2_TXD1")
	)
	(segment
		(start 129.143252 -44.050458)
		(end 124.71908 -44.050458)
		(width 0.10668)
		(layer "B.Cu")
		(net "NCSI_OCP_V3_2_TXD1")
	)
	(segment
		(start 197.810374 -68.06438)
		(end 197.810374 -67.297808)
		(width 0.10668)
		(layer "B.Cu")
		(net "NCSI_OCP_V3_2_TXD1")
	)
	(segment
		(start 198.427594 -67.297808)
		(end 198.427594 -68.06438)
		(width 0.10668)
		(layer "B.Cu")
		(net "NCSI_OCP_V3_2_TXD1")
	)
	(segment
		(start 87.757 -25.884632)
		(end 87.757 -16.831056)
		(width 0.10668)
		(layer "B.Cu")
		(net "NCSI_OCP_V3_2_TXD1")
	)
	(segment
		(start 193.933318 -66.362072)
		(end 193.933318 -66.211196)
		(width 0.10668)
		(layer "B.Cu")
		(net "NCSI_OCP_V3_2_TXD1")
	)
	(segment
		(start 73.86193 -7.983728)
		(end 73.86193 -7.20471)
		(width 0.10668)
		(layer "B.Cu")
		(net "NCSI_OCP_V3_2_TXD1")
	)
	(segment
		(start 194.042792 -65.379346)
		(end 193.891916 -65.379346)
		(width 0.10668)
		(layer "B.Cu")
		(net "NCSI_OCP_V3_2_TXD1")
	)
	(segment
		(start 194.916044 -66.252598)
		(end 194.765168 -66.252598)
		(width 0.10668)
		(layer "B.Cu")
		(net "NCSI_OCP_V3_2_TXD1")
	)
	(segment
		(start 198.534274 -67.191128)
		(end 198.427594 -67.297808)
		(width 0.10668)
		(layer "B.Cu")
		(net "NCSI_OCP_V3_2_TXD1")
	)
	(segment
		(start 74.06894 -8.190738)
		(end 73.86193 -7.983728)
		(width 0.10668)
		(layer "B.Cu")
		(net "NCSI_OCP_V3_2_TXD1")
	)
	(segment
		(start 194.369944 -66.647822)
		(end 194.219068 -66.647822)
		(width 0.10668)
		(layer "B.Cu")
		(net "NCSI_OCP_V3_2_TXD1")
	)
	(segment
		(start 74.89698 -7.23265)
		(end 74.7903 -7.33933)
		(width 0.10668)
		(layer "B.Cu")
		(net "NCSI_OCP_V3_2_TXD1")
	)
	(segment
		(start 75.5142 -8.190738)
		(end 75.40752 -8.084058)
		(width 0.10668)
		(layer "B.Cu")
		(net "NCSI_OCP_V3_2_TXD1")
	)
	(segment
		(start 198.427594 -68.06438)
		(end 198.320914 -68.17106)
		(width 0.10668)
		(layer "B.Cu")
		(net "NCSI_OCP_V3_2_TXD1")
	)
	(segment
		(start 160.561528 -52.9463)
		(end 152.896062 -52.9463)
		(width 0.10668)
		(layer "B.Cu")
		(net "NCSI_OCP_V3_2_TXD1")
	)
	(segment
		(start 85.162644 -14.2367)
		(end 82.478626 -14.2367)
		(width 0.10668)
		(layer "B.Cu")
		(net "NCSI_OCP_V3_2_TXD1")
	)
	(segment
		(start 80.313276 -10.246614)
		(end 78.2574 -8.190738)
		(width 0.10668)
		(layer "B.Cu")
		(net "NCSI_OCP_V3_2_TXD1")
	)
	(segment
		(start 91.33078 -29.458412)
		(end 87.757 -25.884632)
		(width 0.10668)
		(layer "B.Cu")
		(net "NCSI_OCP_V3_2_TXD1")
	)
	(segment
		(start 194.219068 -66.647822)
		(end 193.933318 -66.362072)
		(width 0.10668)
		(layer "B.Cu")
		(net "NCSI_OCP_V3_2_TXD1")
	)
	(segment
		(start 196.469254 -67.191128)
		(end 195.854574 -67.191128)
		(width 0.10668)
		(layer "B.Cu")
		(net "NCSI_OCP_V3_2_TXD1")
	)
	(segment
		(start 194.328542 -65.665096)
		(end 194.042792 -65.379346)
		(width 0.10668)
		(layer "B.Cu")
		(net "NCSI_OCP_V3_2_TXD1")
	)
	(segment
		(start 195.854574 -67.191128)
		(end 194.916044 -66.252598)
		(width 0.10668)
		(layer "B.Cu")
		(net "NCSI_OCP_V3_2_TXD1")
	)
	(segment
		(start 133.65734 -44.855384)
		(end 129.948178 -44.855384)
		(width 0.10668)
		(layer "B.Cu")
		(net "NCSI_OCP_V3_2_TXD1")
	)
	(segment
		(start 108.683298 -39.130732)
		(end 104.441752 -34.889186)
		(width 0.10668)
		(layer "B.Cu")
		(net "NCSI_OCP_V3_2_TXD1")
	)
	(segment
		(start 194.765168 -66.252598)
		(end 194.369944 -66.647822)
		(width 0.10668)
		(layer "B.Cu")
		(net "NCSI_OCP_V3_2_TXD1")
	)
	(segment
		(start 80.313276 -12.07135)
		(end 80.313276 -10.246614)
		(width 0.10668)
		(layer "B.Cu")
		(net "NCSI_OCP_V3_2_TXD1")
	)
	(segment
		(start 129.948178 -44.855384)
		(end 129.143252 -44.050458)
		(width 0.10668)
		(layer "B.Cu")
		(net "NCSI_OCP_V3_2_TXD1")
	)
	(segment
		(start 197.703694 -67.191128)
		(end 197.299834 -67.191128)
		(width 0.10668)
		(layer "B.Cu")
		(net "NCSI_OCP_V3_2_TXD1")
	)
	(segment
		(start 173.643036 -57.960006)
		(end 172.857414 -58.745628)
		(width 0.10668)
		(layer "B.Cu")
		(net "NCSI_OCP_V3_2_TXD1")
	)
	(segment
		(start 197.299834 -67.191128)
		(end 197.193154 -67.297808)
		(width 0.10668)
		(layer "B.Cu")
		(net "NCSI_OCP_V3_2_TXD1")
	)
	(segment
		(start 74.68362 -8.190738)
		(end 74.06894 -8.190738)
		(width 0.10668)
		(layer "B.Cu")
		(net "NCSI_OCP_V3_2_TXD1")
	)
	(segment
		(start 74.7903 -8.084058)
		(end 74.68362 -8.190738)
		(width 0.10668)
		(layer "B.Cu")
		(net "NCSI_OCP_V3_2_TXD1")
	)
	(segment
		(start 196.575934 -68.06438)
		(end 196.575934 -67.297808)
		(width 0.10668)
		(layer "B.Cu")
		(net "NCSI_OCP_V3_2_TXD1")
	)
	(segment
		(start 136.018016 -47.21606)
		(end 133.65734 -44.855384)
		(width 0.10668)
		(layer "B.Cu")
		(net "NCSI_OCP_V3_2_TXD1")
	)
	(segment
		(start 74.7903 -7.33933)
		(end 74.7903 -8.084058)
		(width 0.10668)
		(layer "B.Cu")
		(net "NCSI_OCP_V3_2_TXD1")
	)
	(segment
		(start 147.165822 -47.21606)
		(end 136.018016 -47.21606)
		(width 0.10668)
		(layer "B.Cu")
		(net "NCSI_OCP_V3_2_TXD1")
	)
	(segment
		(start 124.71908 -44.050458)
		(end 119.799354 -39.130732)
		(width 0.10668)
		(layer "B.Cu")
		(net "NCSI_OCP_V3_2_TXD1")
	)
	(segment
		(start 196.575934 -67.297808)
		(end 196.469254 -67.191128)
		(width 0.10668)
		(layer "B.Cu")
		(net "NCSI_OCP_V3_2_TXD1")
	)
	(segment
		(start 200.238614 -71.189088)
		(end 200.238614 -67.866768)
		(width 0.10668)
		(layer "B.Cu")
		(net "NCSI_OCP_V3_2_TXD1")
	)
	(segment
		(start 193.496692 -65.77457)
		(end 193.345816 -65.77457)
		(width 0.10668)
		(layer "B.Cu")
		(net "NCSI_OCP_V3_2_TXD1")
	)
	(segment
		(start 190.574422 -61.910976)
		(end 181.036468 -57.960006)
		(width 0.10668)
		(layer "B.Cu")
		(net "NCSI_OCP_V3_2_TXD1")
	)
	(segment
		(start 201.39533 -71.55307)
		(end 200.602596 -71.55307)
		(width 0.10668)
		(layer "B.Cu")
		(net "NCSI_OCP_V3_2_TXD1")
	)
	(segment
		(start 87.757 -16.831056)
		(end 85.162644 -14.2367)
		(width 0.10668)
		(layer "B.Cu")
		(net "NCSI_OCP_V3_2_TXD1")
	)
	(segment
		(start 75.40752 -7.33933)
		(end 75.30084 -7.23265)
		(width 0.10668)
		(layer "B.Cu")
		(net "NCSI_OCP_V3_2_TXD1")
	)
	(segment
		(start 199.562974 -67.191128)
		(end 198.534274 -67.191128)
		(width 0.10668)
		(layer "B.Cu")
		(net "NCSI_OCP_V3_2_TXD1")
	)
	(segment
		(start 193.891916 -65.379346)
		(end 193.496692 -65.77457)
		(width 0.10668)
		(layer "B.Cu")
		(net "NCSI_OCP_V3_2_TXD1")
	)
	(segment
		(start 193.345816 -65.77457)
		(end 193.060066 -65.48882)
		(width 0.10668)
		(layer "B.Cu")
		(net "NCSI_OCP_V3_2_TXD1")
	)
	(segment
		(start 193.45529 -64.94272)
		(end 193.45529 -64.791844)
		(width 0.10668)
		(layer "B.Cu")
		(net "NCSI_OCP_V3_2_TXD1")
	)
	(segment
		(start 193.060066 -65.337944)
		(end 193.45529 -64.94272)
		(width 0.10668)
		(layer "B.Cu")
		(net "NCSI_OCP_V3_2_TXD1")
	)
	(segment
		(start 167.91305 -55.56377)
		(end 163.178998 -55.56377)
		(width 0.10668)
		(layer "B.Cu")
		(net "NCSI_OCP_V3_2_TXD1")
	)
	(segment
		(start 197.193154 -67.297808)
		(end 197.193154 -68.06438)
		(width 0.10668)
		(layer "B.Cu")
		(net "NCSI_OCP_V3_2_TXD1")
	)
	(segment
		(start 82.478626 -14.2367)
		(end 80.313276 -12.07135)
		(width 0.10668)
		(layer "B.Cu")
		(net "NCSI_OCP_V3_2_TXD1")
	)
	(segment
		(start 181.036468 -57.960006)
		(end 173.643036 -57.960006)
		(width 0.10668)
		(layer "B.Cu")
		(net "NCSI_OCP_V3_2_TXD1")
	)
	(segment
		(start 197.193154 -68.06438)
		(end 197.086474 -68.17106)
		(width 0.10668)
		(layer "B.Cu")
		(net "NCSI_OCP_V3_2_TXD1")
	)
	(segment
		(start 171.094908 -58.745628)
		(end 167.91305 -55.56377)
		(width 0.10668)
		(layer "B.Cu")
		(net "NCSI_OCP_V3_2_TXD1")
	)
	(segment
		(start 104.441752 -34.889186)
		(end 91.33078 -29.458412)
		(width 0.10668)
		(layer "B.Cu")
		(net "NCSI_OCP_V3_2_TXD1")
	)
	(segment
		(start 198.320914 -68.17106)
		(end 197.917054 -68.17106)
		(width 0.10668)
		(layer "B.Cu")
		(net "NCSI_OCP_V3_2_TXD1")
	)
	(segment
		(start 73.261982 -8.320024)
		(end 73.261982 -5.537708)
		(width 0.10668)
		(layer "F.Cu")
		(net "NCSI_OCP_V3_2_TXD0")
	)
	(segment
		(start 73.261982 -5.537708)
		(end 72.896984 -5.17271)
		(width 0.10668)
		(layer "F.Cu")
		(net "NCSI_OCP_V3_2_TXD0")
	)
	(via
		(at 72.896984 -5.17271)
		(size 0.508)
		(drill 0.254)
		(layers "F.Cu" "B.Cu")
		(net "NCSI_OCP_V3_2_TXD0")
	)
	(segment
		(start 88.24468 -16.628872)
		(end 85.364828 -13.74902)
		(width 0.10668)
		(layer "B.Cu")
		(net "NCSI_OCP_V3_2_TXD0")
	)
	(segment
		(start 190.902844 -61.462158)
		(end 181.270402 -57.472326)
		(width 0.10668)
		(layer "B.Cu")
		(net "NCSI_OCP_V3_2_TXD0")
	)
	(segment
		(start 202.78471 -69.603112)
		(end 203.185014 -69.202808)
		(width 0.10668)
		(layer "B.Cu")
		(net "NCSI_OCP_V3_2_TXD0")
	)
	(segment
		(start 125.117352 -43.562778)
		(end 120.155716 -38.601142)
		(width 0.10668)
		(layer "B.Cu")
		(net "NCSI_OCP_V3_2_TXD0")
	)
	(segment
		(start 72.896984 -3.962908)
		(end 72.896984 -5.17271)
		(width 0.10668)
		(layer "B.Cu")
		(net "NCSI_OCP_V3_2_TXD0")
	)
	(segment
		(start 120.155716 -38.601142)
		(end 108.902754 -38.601142)
		(width 0.10668)
		(layer "B.Cu")
		(net "NCSI_OCP_V3_2_TXD0")
	)
	(segment
		(start 78.064868 -4.920234)
		(end 76.245974 -3.10134)
		(width 0.10668)
		(layer "B.Cu")
		(net "NCSI_OCP_V3_2_TXD0")
	)
	(segment
		(start 80.815688 -11.718798)
		(end 80.815688 -9.815322)
		(width 0.10668)
		(layer "B.Cu")
		(net "NCSI_OCP_V3_2_TXD0")
	)
	(segment
		(start 172.65523 -58.257948)
		(end 171.297346 -58.257948)
		(width 0.10668)
		(layer "B.Cu")
		(net "NCSI_OCP_V3_2_TXD0")
	)
	(segment
		(start 203.185014 -68.707508)
		(end 201.119994 -66.642488)
		(width 0.10668)
		(layer "B.Cu")
		(net "NCSI_OCP_V3_2_TXD0")
	)
	(segment
		(start 129.345436 -43.562778)
		(end 125.117352 -43.562778)
		(width 0.10668)
		(layer "B.Cu")
		(net "NCSI_OCP_V3_2_TXD0")
	)
	(segment
		(start 181.270402 -57.472326)
		(end 173.440852 -57.472326)
		(width 0.10668)
		(layer "B.Cu")
		(net "NCSI_OCP_V3_2_TXD0")
	)
	(segment
		(start 151.752046 -51.11242)
		(end 147.368006 -46.72838)
		(width 0.10668)
		(layer "B.Cu")
		(net "NCSI_OCP_V3_2_TXD0")
	)
	(segment
		(start 171.297346 -58.257948)
		(end 168.115488 -55.07609)
		(width 0.10668)
		(layer "B.Cu")
		(net "NCSI_OCP_V3_2_TXD0")
	)
	(segment
		(start 80.815688 -9.815322)
		(end 78.064868 -7.064502)
		(width 0.10668)
		(layer "B.Cu")
		(net "NCSI_OCP_V3_2_TXD0")
	)
	(segment
		(start 201.119994 -66.642488)
		(end 196.083174 -66.642488)
		(width 0.10668)
		(layer "B.Cu")
		(net "NCSI_OCP_V3_2_TXD0")
	)
	(segment
		(start 108.902754 -38.601142)
		(end 104.818942 -34.51733)
		(width 0.10668)
		(layer "B.Cu")
		(net "NCSI_OCP_V3_2_TXD0")
	)
	(segment
		(start 91.607132 -29.0449)
		(end 88.24468 -25.682448)
		(width 0.10668)
		(layer "B.Cu")
		(net "NCSI_OCP_V3_2_TXD0")
	)
	(segment
		(start 85.364828 -13.74902)
		(end 82.84591 -13.74902)
		(width 0.10668)
		(layer "B.Cu")
		(net "NCSI_OCP_V3_2_TXD0")
	)
	(segment
		(start 82.84591 -13.74902)
		(end 80.815688 -11.718798)
		(width 0.10668)
		(layer "B.Cu")
		(net "NCSI_OCP_V3_2_TXD0")
	)
	(segment
		(start 196.083174 -66.642488)
		(end 190.902844 -61.462158)
		(width 0.10668)
		(layer "B.Cu")
		(net "NCSI_OCP_V3_2_TXD0")
	)
	(segment
		(start 203.185014 -69.202808)
		(end 203.185014 -68.707508)
		(width 0.10668)
		(layer "B.Cu")
		(net "NCSI_OCP_V3_2_TXD0")
	)
	(segment
		(start 130.150362 -44.367704)
		(end 129.345436 -43.562778)
		(width 0.10668)
		(layer "B.Cu")
		(net "NCSI_OCP_V3_2_TXD0")
	)
	(segment
		(start 73.758552 -3.10134)
		(end 72.896984 -3.962908)
		(width 0.10668)
		(layer "B.Cu")
		(net "NCSI_OCP_V3_2_TXD0")
	)
	(segment
		(start 163.381436 -55.07609)
		(end 159.417766 -51.11242)
		(width 0.10668)
		(layer "B.Cu")
		(net "NCSI_OCP_V3_2_TXD0")
	)
	(segment
		(start 147.368006 -46.72838)
		(end 136.2202 -46.72838)
		(width 0.10668)
		(layer "B.Cu")
		(net "NCSI_OCP_V3_2_TXD0")
	)
	(segment
		(start 78.064868 -7.064502)
		(end 78.064868 -4.920234)
		(width 0.10668)
		(layer "B.Cu")
		(net "NCSI_OCP_V3_2_TXD0")
	)
	(segment
		(start 201.39533 -69.603112)
		(end 202.78471 -69.603112)
		(width 0.10668)
		(layer "B.Cu")
		(net "NCSI_OCP_V3_2_TXD0")
	)
	(segment
		(start 104.818942 -34.51733)
		(end 91.607132 -29.0449)
		(width 0.10668)
		(layer "B.Cu")
		(net "NCSI_OCP_V3_2_TXD0")
	)
	(segment
		(start 159.417766 -51.11242)
		(end 151.752046 -51.11242)
		(width 0.10668)
		(layer "B.Cu")
		(net "NCSI_OCP_V3_2_TXD0")
	)
	(segment
		(start 88.24468 -25.682448)
		(end 88.24468 -16.628872)
		(width 0.10668)
		(layer "B.Cu")
		(net "NCSI_OCP_V3_2_TXD0")
	)
	(segment
		(start 173.440852 -57.472326)
		(end 172.65523 -58.257948)
		(width 0.10668)
		(layer "B.Cu")
		(net "NCSI_OCP_V3_2_TXD0")
	)
	(segment
		(start 76.245974 -3.10134)
		(end 73.758552 -3.10134)
		(width 0.10668)
		(layer "B.Cu")
		(net "NCSI_OCP_V3_2_TXD0")
	)
	(segment
		(start 168.115488 -55.07609)
		(end 163.381436 -55.07609)
		(width 0.10668)
		(layer "B.Cu")
		(net "NCSI_OCP_V3_2_TXD0")
	)
	(segment
		(start 133.859524 -44.367704)
		(end 130.150362 -44.367704)
		(width 0.10668)
		(layer "B.Cu")
		(net "NCSI_OCP_V3_2_TXD0")
	)
	(segment
		(start 136.2202 -46.72838)
		(end 133.859524 -44.367704)
		(width 0.10668)
		(layer "B.Cu")
		(net "NCSI_OCP_V3_2_TXD0")
	)
	(segment
		(start 73.86193 -14.011148)
		(end 73.86193 -11.26998)
		(width 0.10668)
		(layer "F.Cu")
		(net "NCSI_OCP_V3_2_RXD1")
	)
	(segment
		(start 74.010266 -14.159484)
		(end 73.86193 -14.011148)
		(width 0.10668)
		(layer "F.Cu")
		(net "NCSI_OCP_V3_2_RXD1")
	)
	(via
		(at 74.010266 -14.159484)
		(size 0.508)
		(drill 0.254)
		(layers "F.Cu" "B.Cu")
		(net "NCSI_OCP_V3_2_RXD1")
	)
	(via
		(at 205.142846 -74.237342)
		(size 0.6604)
		(drill 0.3302)
		(layers "F.Cu" "B.Cu")
		(net "NCSI_OCP_V3_2_RXD1")
	)
	(segment
		(start 212.216746 -77.913738)
		(end 210.313524 -77.913738)
		(width 0.10668)
		(layer "B.Cu")
		(net "NCSI_OCP_V3_2_RXD1")
	)
	(segment
		(start 96.00946 -34.73958)
		(end 100.256594 -34.73958)
		(width 0.10668)
		(layer "B.Cu")
		(net "NCSI_OCP_V3_2_RXD1")
	)
	(segment
		(start 128.5367 -45.513498)
		(end 129.341626 -46.318424)
		(width 0.10668)
		(layer "B.Cu")
		(net "NCSI_OCP_V3_2_RXD1")
	)
	(segment
		(start 86.194392 -17.675352)
		(end 86.194392 -28.110688)
		(width 0.10668)
		(layer "B.Cu")
		(net "NCSI_OCP_V3_2_RXD1")
	)
	(segment
		(start 207.20304 -74.803254)
		(end 205.708758 -74.803254)
		(width 0.10668)
		(layer "B.Cu")
		(net "NCSI_OCP_V3_2_RXD1")
	)
	(segment
		(start 74.010266 -14.159484)
		(end 74.010266 -14.4526)
		(width 0.10668)
		(layer "B.Cu")
		(net "NCSI_OCP_V3_2_RXD1")
	)
	(segment
		(start 74.010266 -14.4526)
		(end 74.718164 -15.160498)
		(width 0.10668)
		(layer "B.Cu")
		(net "NCSI_OCP_V3_2_RXD1")
	)
	(segment
		(start 204.916532 -74.011028)
		(end 205.142846 -74.237342)
		(width 0.10668)
		(layer "B.Cu")
		(net "NCSI_OCP_V3_2_RXD1")
	)
	(segment
		(start 174.24273 -59.429904)
		(end 180.761386 -59.429904)
		(width 0.10668)
		(layer "B.Cu")
		(net "NCSI_OCP_V3_2_RXD1")
	)
	(segment
		(start 210.313524 -77.913738)
		(end 207.20304 -74.803254)
		(width 0.10668)
		(layer "B.Cu")
		(net "NCSI_OCP_V3_2_RXD1")
	)
	(segment
		(start 185.728356 -61.487812)
		(end 188.45657 -64.216026)
		(width 0.10668)
		(layer "B.Cu")
		(net "NCSI_OCP_V3_2_RXD1")
	)
	(segment
		(start 108.875068 -41.55186)
		(end 120.150128 -41.55186)
		(width 0.10668)
		(layer "B.Cu")
		(net "NCSI_OCP_V3_2_RXD1")
	)
	(segment
		(start 74.882502 -15.22857)
		(end 75.753214 -15.22857)
		(width 0.10668)
		(layer "B.Cu")
		(net "NCSI_OCP_V3_2_RXD1")
	)
	(segment
		(start 120.150128 -41.55186)
		(end 124.111766 -45.513498)
		(width 0.10668)
		(layer "B.Cu")
		(net "NCSI_OCP_V3_2_RXD1")
	)
	(segment
		(start 86.194392 -28.110688)
		(end 89.963752 -31.880048)
		(width 0.10668)
		(layer "B.Cu")
		(net "NCSI_OCP_V3_2_RXD1")
	)
	(segment
		(start 124.111766 -45.513498)
		(end 128.5367 -45.513498)
		(width 0.10668)
		(layer "B.Cu")
		(net "NCSI_OCP_V3_2_RXD1")
	)
	(segment
		(start 81.567274 -15.799308)
		(end 84.318348 -15.799308)
		(width 0.10668)
		(layer "B.Cu")
		(net "NCSI_OCP_V3_2_RXD1")
	)
	(segment
		(start 180.761386 -59.429904)
		(end 185.728356 -61.487812)
		(width 0.10668)
		(layer "B.Cu")
		(net "NCSI_OCP_V3_2_RXD1")
	)
	(segment
		(start 89.963752 -31.880048)
		(end 89.963752 -34.712656)
		(width 0.10668)
		(layer "B.Cu")
		(net "NCSI_OCP_V3_2_RXD1")
	)
	(segment
		(start 152.39365 -54.51348)
		(end 160.058608 -54.51348)
		(width 0.10668)
		(layer "B.Cu")
		(net "NCSI_OCP_V3_2_RXD1")
	)
	(segment
		(start 94.756732 -35.992308)
		(end 96.00946 -34.73958)
		(width 0.10668)
		(layer "B.Cu")
		(net "NCSI_OCP_V3_2_RXD1")
	)
	(segment
		(start 167.403272 -57.123584)
		(end 170.488356 -60.208668)
		(width 0.10668)
		(layer "B.Cu")
		(net "NCSI_OCP_V3_2_RXD1")
	)
	(segment
		(start 138.28014 -51.789584)
		(end 149.669754 -51.789584)
		(width 0.10668)
		(layer "B.Cu")
		(net "NCSI_OCP_V3_2_RXD1")
	)
	(segment
		(start 84.318348 -15.799308)
		(end 86.194392 -17.675352)
		(width 0.10668)
		(layer "B.Cu")
		(net "NCSI_OCP_V3_2_RXD1")
	)
	(segment
		(start 190.592456 -74.011028)
		(end 204.916532 -74.011028)
		(width 0.10668)
		(layer "B.Cu")
		(net "NCSI_OCP_V3_2_RXD1")
	)
	(segment
		(start 188.45657 -71.875142)
		(end 190.592456 -74.011028)
		(width 0.10668)
		(layer "B.Cu")
		(net "NCSI_OCP_V3_2_RXD1")
	)
	(segment
		(start 103.3399 -36.016692)
		(end 108.875068 -41.55186)
		(width 0.10668)
		(layer "B.Cu")
		(net "NCSI_OCP_V3_2_RXD1")
	)
	(segment
		(start 162.668712 -57.123584)
		(end 167.403272 -57.123584)
		(width 0.10668)
		(layer "B.Cu")
		(net "NCSI_OCP_V3_2_RXD1")
	)
	(segment
		(start 149.669754 -51.789584)
		(end 152.39365 -54.51348)
		(width 0.10668)
		(layer "B.Cu")
		(net "NCSI_OCP_V3_2_RXD1")
	)
	(segment
		(start 89.963752 -34.712656)
		(end 91.243404 -35.992308)
		(width 0.10668)
		(layer "B.Cu")
		(net "NCSI_OCP_V3_2_RXD1")
	)
	(segment
		(start 75.753214 -15.22857)
		(end 76.549504 -14.43228)
		(width 0.10668)
		(layer "B.Cu")
		(net "NCSI_OCP_V3_2_RXD1")
	)
	(segment
		(start 205.708758 -74.803254)
		(end 205.142846 -74.237342)
		(width 0.10668)
		(layer "B.Cu")
		(net "NCSI_OCP_V3_2_RXD1")
	)
	(segment
		(start 76.549504 -14.43228)
		(end 80.200246 -14.43228)
		(width 0.10668)
		(layer "B.Cu")
		(net "NCSI_OCP_V3_2_RXD1")
	)
	(segment
		(start 132.80898 -46.318424)
		(end 138.28014 -51.789584)
		(width 0.10668)
		(layer "B.Cu")
		(net "NCSI_OCP_V3_2_RXD1")
	)
	(segment
		(start 80.200246 -14.43228)
		(end 81.567274 -15.799308)
		(width 0.10668)
		(layer "B.Cu")
		(net "NCSI_OCP_V3_2_RXD1")
	)
	(segment
		(start 173.463966 -60.208668)
		(end 174.24273 -59.429904)
		(width 0.10668)
		(layer "B.Cu")
		(net "NCSI_OCP_V3_2_RXD1")
	)
	(segment
		(start 100.256594 -34.73958)
		(end 103.3399 -36.016692)
		(width 0.10668)
		(layer "B.Cu")
		(net "NCSI_OCP_V3_2_RXD1")
	)
	(segment
		(start 74.718164 -15.160498)
		(end 74.882502 -15.22857)
		(width 0.10668)
		(layer "B.Cu")
		(net "NCSI_OCP_V3_2_RXD1")
	)
	(segment
		(start 170.488356 -60.208668)
		(end 173.463966 -60.208668)
		(width 0.10668)
		(layer "B.Cu")
		(net "NCSI_OCP_V3_2_RXD1")
	)
	(segment
		(start 91.243404 -35.992308)
		(end 94.756732 -35.992308)
		(width 0.10668)
		(layer "B.Cu")
		(net "NCSI_OCP_V3_2_RXD1")
	)
	(segment
		(start 160.058608 -54.51348)
		(end 162.668712 -57.123584)
		(width 0.10668)
		(layer "B.Cu")
		(net "NCSI_OCP_V3_2_RXD1")
	)
	(segment
		(start 129.341626 -46.318424)
		(end 132.80898 -46.318424)
		(width 0.10668)
		(layer "B.Cu")
		(net "NCSI_OCP_V3_2_RXD1")
	)
	(segment
		(start 188.45657 -64.216026)
		(end 188.45657 -71.875142)
		(width 0.10668)
		(layer "B.Cu")
		(net "NCSI_OCP_V3_2_RXD1")
	)
	(segment
		(start 73.261982 -13.829792)
		(end 73.148952 -13.942822)
		(width 0.10668)
		(layer "F.Cu")
		(net "NCSI_OCP_V3_2_RXD0")
	)
	(segment
		(start 73.261982 -11.26998)
		(end 73.261982 -13.829792)
		(width 0.10668)
		(layer "F.Cu")
		(net "NCSI_OCP_V3_2_RXD0")
	)
	(via
		(at 73.148952 -13.942822)
		(size 0.508)
		(drill 0.254)
		(layers "F.Cu" "B.Cu")
		(net "NCSI_OCP_V3_2_RXD0")
	)
	(segment
		(start 124.314204 -45.025818)
		(end 128.738884 -45.025818)
		(width 0.10668)
		(layer "B.Cu")
		(net "NCSI_OCP_V3_2_RXD0")
	)
	(segment
		(start 186.004708 -61.0743)
		(end 188.94425 -64.013842)
		(width 0.10668)
		(layer "B.Cu")
		(net "NCSI_OCP_V3_2_RXD0")
	)
	(segment
		(start 139.483846 -48.974756)
		(end 140.23467 -49.72558)
		(width 0.10668)
		(layer "B.Cu")
		(net "NCSI_OCP_V3_2_RXD0")
	)
	(segment
		(start 86.78164 -17.43202)
		(end 86.78164 -27.867356)
		(width 0.10668)
		(layer "B.Cu")
		(net "NCSI_OCP_V3_2_RXD0")
	)
	(segment
		(start 205.645258 -73.800208)
		(end 207.538574 -73.800208)
		(width 0.10668)
		(layer "B.Cu")
		(net "NCSI_OCP_V3_2_RXD0")
	)
	(segment
		(start 86.78164 -27.867356)
		(end 90.551 -31.636716)
		(width 0.10668)
		(layer "B.Cu")
		(net "NCSI_OCP_V3_2_RXD0")
	)
	(segment
		(start 74.498454 -13.711428)
		(end 74.498454 -14.240256)
		(width 0.10668)
		(layer "B.Cu")
		(net "NCSI_OCP_V3_2_RXD0")
	)
	(segment
		(start 205.345538 -73.500488)
		(end 205.645258 -73.800208)
		(width 0.10668)
		(layer "B.Cu")
		(net "NCSI_OCP_V3_2_RXD0")
	)
	(segment
		(start 129.54381 -45.830744)
		(end 133.011164 -45.830744)
		(width 0.10668)
		(layer "B.Cu")
		(net "NCSI_OCP_V3_2_RXD0")
	)
	(segment
		(start 207.538574 -73.800208)
		(end 209.702146 -75.96378)
		(width 0.10668)
		(layer "B.Cu")
		(net "NCSI_OCP_V3_2_RXD0")
	)
	(segment
		(start 95.66656 -34.2519)
		(end 100.35413 -34.2519)
		(width 0.10668)
		(layer "B.Cu")
		(net "NCSI_OCP_V3_2_RXD0")
	)
	(segment
		(start 174.047404 -58.935366)
		(end 180.841904 -58.935366)
		(width 0.10668)
		(layer "B.Cu")
		(net "NCSI_OCP_V3_2_RXD0")
	)
	(segment
		(start 94.5134 -35.40506)
		(end 95.66656 -34.2519)
		(width 0.10668)
		(layer "B.Cu")
		(net "NCSI_OCP_V3_2_RXD0")
	)
	(segment
		(start 73.148952 -13.942822)
		(end 73.589642 -13.502132)
		(width 0.10668)
		(layer "B.Cu")
		(net "NCSI_OCP_V3_2_RXD0")
	)
	(segment
		(start 81.797906 -15.21206)
		(end 84.56168 -15.21206)
		(width 0.10668)
		(layer "B.Cu")
		(net "NCSI_OCP_V3_2_RXD0")
	)
	(segment
		(start 188.94425 -64.013842)
		(end 188.94425 -71.672958)
		(width 0.10668)
		(layer "B.Cu")
		(net "NCSI_OCP_V3_2_RXD0")
	)
	(segment
		(start 74.498454 -14.240256)
		(end 74.988674 -14.730476)
		(width 0.10668)
		(layer "B.Cu")
		(net "NCSI_OCP_V3_2_RXD0")
	)
	(segment
		(start 152.572974 -54.00294)
		(end 160.238186 -54.00294)
		(width 0.10668)
		(layer "B.Cu")
		(net "NCSI_OCP_V3_2_RXD0")
	)
	(segment
		(start 190.77178 -73.500488)
		(end 205.345538 -73.500488)
		(width 0.10668)
		(layer "B.Cu")
		(net "NCSI_OCP_V3_2_RXD0")
	)
	(segment
		(start 173.261782 -59.720988)
		(end 174.047404 -58.935366)
		(width 0.10668)
		(layer "B.Cu")
		(net "NCSI_OCP_V3_2_RXD0")
	)
	(segment
		(start 91.34602 -35.40506)
		(end 94.5134 -35.40506)
		(width 0.10668)
		(layer "B.Cu")
		(net "NCSI_OCP_V3_2_RXD0")
	)
	(segment
		(start 128.738884 -45.025818)
		(end 129.54381 -45.830744)
		(width 0.10668)
		(layer "B.Cu")
		(net "NCSI_OCP_V3_2_RXD0")
	)
	(segment
		(start 133.011164 -45.830744)
		(end 136.155176 -48.974756)
		(width 0.10668)
		(layer "B.Cu")
		(net "NCSI_OCP_V3_2_RXD0")
	)
	(segment
		(start 75.561444 -14.730476)
		(end 76.38542 -13.9065)
		(width 0.10668)
		(layer "B.Cu")
		(net "NCSI_OCP_V3_2_RXD0")
	)
	(segment
		(start 90.551 -34.61004)
		(end 91.34602 -35.40506)
		(width 0.10668)
		(layer "B.Cu")
		(net "NCSI_OCP_V3_2_RXD0")
	)
	(segment
		(start 80.492346 -13.9065)
		(end 81.797906 -15.21206)
		(width 0.10668)
		(layer "B.Cu")
		(net "NCSI_OCP_V3_2_RXD0")
	)
	(segment
		(start 74.988674 -14.730476)
		(end 75.561444 -14.730476)
		(width 0.10668)
		(layer "B.Cu")
		(net "NCSI_OCP_V3_2_RXD0")
	)
	(segment
		(start 147.448524 -50.978816)
		(end 149.54885 -50.978816)
		(width 0.10668)
		(layer "B.Cu")
		(net "NCSI_OCP_V3_2_RXD0")
	)
	(segment
		(start 136.155176 -48.974756)
		(end 139.483846 -48.974756)
		(width 0.10668)
		(layer "B.Cu")
		(net "NCSI_OCP_V3_2_RXD0")
	)
	(segment
		(start 180.841904 -58.935366)
		(end 186.004708 -61.0743)
		(width 0.10668)
		(layer "B.Cu")
		(net "NCSI_OCP_V3_2_RXD0")
	)
	(segment
		(start 109.016292 -41.00322)
		(end 120.291606 -41.00322)
		(width 0.10668)
		(layer "B.Cu")
		(net "NCSI_OCP_V3_2_RXD0")
	)
	(segment
		(start 188.94425 -71.672958)
		(end 190.77178 -73.500488)
		(width 0.10668)
		(layer "B.Cu")
		(net "NCSI_OCP_V3_2_RXD0")
	)
	(segment
		(start 140.23467 -49.72558)
		(end 146.195288 -49.72558)
		(width 0.10668)
		(layer "B.Cu")
		(net "NCSI_OCP_V3_2_RXD0")
	)
	(segment
		(start 160.238186 -54.00294)
		(end 162.87115 -56.635904)
		(width 0.10668)
		(layer "B.Cu")
		(net "NCSI_OCP_V3_2_RXD0")
	)
	(segment
		(start 209.702146 -75.96378)
		(end 212.216746 -75.96378)
		(width 0.10668)
		(layer "B.Cu")
		(net "NCSI_OCP_V3_2_RXD0")
	)
	(segment
		(start 162.87115 -56.635904)
		(end 167.605456 -56.635904)
		(width 0.10668)
		(layer "B.Cu")
		(net "NCSI_OCP_V3_2_RXD0")
	)
	(segment
		(start 76.38542 -13.9065)
		(end 80.492346 -13.9065)
		(width 0.10668)
		(layer "B.Cu")
		(net "NCSI_OCP_V3_2_RXD0")
	)
	(segment
		(start 100.35413 -34.2519)
		(end 103.616252 -35.60318)
		(width 0.10668)
		(layer "B.Cu")
		(net "NCSI_OCP_V3_2_RXD0")
	)
	(segment
		(start 84.56168 -15.21206)
		(end 86.78164 -17.43202)
		(width 0.10668)
		(layer "B.Cu")
		(net "NCSI_OCP_V3_2_RXD0")
	)
	(segment
		(start 73.589642 -13.502132)
		(end 74.289158 -13.502132)
		(width 0.10668)
		(layer "B.Cu")
		(net "NCSI_OCP_V3_2_RXD0")
	)
	(segment
		(start 90.551 -31.636716)
		(end 90.551 -34.61004)
		(width 0.10668)
		(layer "B.Cu")
		(net "NCSI_OCP_V3_2_RXD0")
	)
	(segment
		(start 120.291606 -41.00322)
		(end 124.314204 -45.025818)
		(width 0.10668)
		(layer "B.Cu")
		(net "NCSI_OCP_V3_2_RXD0")
	)
	(segment
		(start 170.69054 -59.720988)
		(end 173.261782 -59.720988)
		(width 0.10668)
		(layer "B.Cu")
		(net "NCSI_OCP_V3_2_RXD0")
	)
	(segment
		(start 167.605456 -56.635904)
		(end 170.69054 -59.720988)
		(width 0.10668)
		(layer "B.Cu")
		(net "NCSI_OCP_V3_2_RXD0")
	)
	(segment
		(start 103.616252 -35.60318)
		(end 109.016292 -41.00322)
		(width 0.10668)
		(layer "B.Cu")
		(net "NCSI_OCP_V3_2_RXD0")
	)
	(segment
		(start 146.195288 -49.72558)
		(end 147.448524 -50.978816)
		(width 0.10668)
		(layer "B.Cu")
		(net "NCSI_OCP_V3_2_RXD0")
	)
	(segment
		(start 149.54885 -50.978816)
		(end 152.572974 -54.00294)
		(width 0.10668)
		(layer "B.Cu")
		(net "NCSI_OCP_V3_2_RXD0")
	)
	(segment
		(start 74.289158 -13.502132)
		(end 74.498454 -13.711428)
		(width 0.10668)
		(layer "B.Cu")
		(net "NCSI_OCP_V3_2_RXD0")
	)
	(segment
		(start 70.261988 -11.26998)
		(end 70.261988 -12.229846)
		(width 0.10668)
		(layer "F.Cu")
		(net "NCSI_OCP_V3_2_CRS_DV")
	)
	(segment
		(start 70.261988 -12.229846)
		(end 70.077584 -12.41425)
		(width 0.10668)
		(layer "F.Cu")
		(net "NCSI_OCP_V3_2_CRS_DV")
	)
	(via
		(at 70.077584 -12.41425)
		(size 0.508)
		(drill 0.254)
		(layers "F.Cu" "B.Cu")
		(net "NCSI_OCP_V3_2_CRS_DV")
	)
	(segment
		(start 173.66615 -60.696348)
		(end 170.286172 -60.696348)
		(width 0.10668)
		(layer "B.Cu")
		(net "NCSI_OCP_V3_2_CRS_DV")
	)
	(segment
		(start 110.35538 -44.22394)
		(end 108.5088 -42.37736)
		(width 0.10668)
		(layer "B.Cu")
		(net "NCSI_OCP_V3_2_CRS_DV")
	)
	(segment
		(start 159.30626 -55.06212)
		(end 152.252426 -55.06212)
		(width 0.10668)
		(layer "B.Cu")
		(net "NCSI_OCP_V3_2_CRS_DV")
	)
	(segment
		(start 206.374746 -75.313794)
		(end 205.30566 -75.313794)
		(width 0.10668)
		(layer "B.Cu")
		(net "NCSI_OCP_V3_2_CRS_DV")
	)
	(segment
		(start 70.077584 -12.52601)
		(end 70.077584 -12.41425)
		(width 0.10668)
		(layer "B.Cu")
		(net "NCSI_OCP_V3_2_CRS_DV")
	)
	(segment
		(start 89.397586 -35.889692)
		(end 89.397586 -32.114744)
		(width 0.10668)
		(layer "B.Cu")
		(net "NCSI_OCP_V3_2_CRS_DV")
	)
	(segment
		(start 174.444914 -59.917584)
		(end 173.66615 -60.696348)
		(width 0.10668)
		(layer "B.Cu")
		(net "NCSI_OCP_V3_2_CRS_DV")
	)
	(segment
		(start 74.210164 -15.71625)
		(end 73.21931 -14.725396)
		(width 0.10668)
		(layer "B.Cu")
		(net "NCSI_OCP_V3_2_CRS_DV")
	)
	(segment
		(start 180.664104 -59.917584)
		(end 174.444914 -59.917584)
		(width 0.10668)
		(layer "B.Cu")
		(net "NCSI_OCP_V3_2_CRS_DV")
	)
	(segment
		(start 76.78674 -14.93266)
		(end 76.00315 -15.71625)
		(width 0.10668)
		(layer "B.Cu")
		(net "NCSI_OCP_V3_2_CRS_DV")
	)
	(segment
		(start 132.606796 -46.806104)
		(end 129.139442 -46.806104)
		(width 0.10668)
		(layer "B.Cu")
		(net "NCSI_OCP_V3_2_CRS_DV")
	)
	(segment
		(start 90.066368 -36.558474)
		(end 89.397586 -35.889692)
		(width 0.10668)
		(layer "B.Cu")
		(net "NCSI_OCP_V3_2_CRS_DV")
	)
	(segment
		(start 128.334516 -46.001178)
		(end 123.909328 -46.001178)
		(width 0.10668)
		(layer "B.Cu")
		(net "NCSI_OCP_V3_2_CRS_DV")
	)
	(segment
		(start 149.503892 -52.313586)
		(end 138.114278 -52.313586)
		(width 0.10668)
		(layer "B.Cu")
		(net "NCSI_OCP_V3_2_CRS_DV")
	)
	(segment
		(start 81.257394 -16.365474)
		(end 79.82458 -14.93266)
		(width 0.10668)
		(layer "B.Cu")
		(net "NCSI_OCP_V3_2_CRS_DV")
	)
	(segment
		(start 94.991428 -36.558474)
		(end 90.066368 -36.558474)
		(width 0.10668)
		(layer "B.Cu")
		(net "NCSI_OCP_V3_2_CRS_DV")
	)
	(segment
		(start 108.5088 -42.37736)
		(end 108.5088 -41.87571)
		(width 0.10668)
		(layer "B.Cu")
		(net "NCSI_OCP_V3_2_CRS_DV")
	)
	(segment
		(start 152.252426 -55.06212)
		(end 149.503892 -52.313586)
		(width 0.10668)
		(layer "B.Cu")
		(net "NCSI_OCP_V3_2_CRS_DV")
	)
	(segment
		(start 73.21931 -14.725396)
		(end 72.27697 -14.725396)
		(width 0.10668)
		(layer "B.Cu")
		(net "NCSI_OCP_V3_2_CRS_DV")
	)
	(segment
		(start 89.397586 -32.114744)
		(end 85.628226 -28.345384)
		(width 0.10668)
		(layer "B.Cu")
		(net "NCSI_OCP_V3_2_CRS_DV")
	)
	(segment
		(start 95.357442 -36.19246)
		(end 94.991428 -36.558474)
		(width 0.10668)
		(layer "B.Cu")
		(net "NCSI_OCP_V3_2_CRS_DV")
	)
	(segment
		(start 185.452004 -61.901324)
		(end 184.10809 -61.344556)
		(width 0.10668)
		(layer "B.Cu")
		(net "NCSI_OCP_V3_2_CRS_DV")
	)
	(segment
		(start 169.716958 -60.127134)
		(end 164.371274 -60.127134)
		(width 0.10668)
		(layer "B.Cu")
		(net "NCSI_OCP_V3_2_CRS_DV")
	)
	(segment
		(start 190.428372 -74.536808)
		(end 187.96889 -72.077326)
		(width 0.10668)
		(layer "B.Cu")
		(net "NCSI_OCP_V3_2_CRS_DV")
	)
	(segment
		(start 187.96889 -64.41821)
		(end 185.452004 -61.901324)
		(width 0.10668)
		(layer "B.Cu")
		(net "NCSI_OCP_V3_2_CRS_DV")
	)
	(segment
		(start 122.13209 -44.22394)
		(end 110.35538 -44.22394)
		(width 0.10668)
		(layer "B.Cu")
		(net "NCSI_OCP_V3_2_CRS_DV")
	)
	(segment
		(start 164.371274 -60.127134)
		(end 159.30626 -55.06212)
		(width 0.10668)
		(layer "B.Cu")
		(net "NCSI_OCP_V3_2_CRS_DV")
	)
	(segment
		(start 84.083652 -16.365474)
		(end 81.257394 -16.365474)
		(width 0.10668)
		(layer "B.Cu")
		(net "NCSI_OCP_V3_2_CRS_DV")
	)
	(segment
		(start 205.30566 -75.313794)
		(end 204.528674 -74.536808)
		(width 0.10668)
		(layer "B.Cu")
		(net "NCSI_OCP_V3_2_CRS_DV")
	)
	(segment
		(start 85.628226 -17.910048)
		(end 84.083652 -16.365474)
		(width 0.10668)
		(layer "B.Cu")
		(net "NCSI_OCP_V3_2_CRS_DV")
	)
	(segment
		(start 85.628226 -28.345384)
		(end 85.628226 -17.910048)
		(width 0.10668)
		(layer "B.Cu")
		(net "NCSI_OCP_V3_2_CRS_DV")
	)
	(segment
		(start 204.528674 -74.536808)
		(end 190.428372 -74.536808)
		(width 0.10668)
		(layer "B.Cu")
		(net "NCSI_OCP_V3_2_CRS_DV")
	)
	(segment
		(start 103.06304 -36.42995)
		(end 102.489762 -36.19246)
		(width 0.10668)
		(layer "B.Cu")
		(net "NCSI_OCP_V3_2_CRS_DV")
	)
	(segment
		(start 138.114278 -52.313586)
		(end 132.606796 -46.806104)
		(width 0.10668)
		(layer "B.Cu")
		(net "NCSI_OCP_V3_2_CRS_DV")
	)
	(segment
		(start 187.96889 -72.077326)
		(end 187.96889 -64.41821)
		(width 0.10668)
		(layer "B.Cu")
		(net "NCSI_OCP_V3_2_CRS_DV")
	)
	(segment
		(start 123.909328 -46.001178)
		(end 122.13209 -44.22394)
		(width 0.10668)
		(layer "B.Cu")
		(net "NCSI_OCP_V3_2_CRS_DV")
	)
	(segment
		(start 108.5088 -41.87571)
		(end 103.06304 -36.42995)
		(width 0.10668)
		(layer "B.Cu")
		(net "NCSI_OCP_V3_2_CRS_DV")
	)
	(segment
		(start 72.27697 -14.725396)
		(end 70.077584 -12.52601)
		(width 0.10668)
		(layer "B.Cu")
		(net "NCSI_OCP_V3_2_CRS_DV")
	)
	(segment
		(start 170.286172 -60.696348)
		(end 169.716958 -60.127134)
		(width 0.10668)
		(layer "B.Cu")
		(net "NCSI_OCP_V3_2_CRS_DV")
	)
	(segment
		(start 184.10809 -61.344556)
		(end 180.664104 -59.917584)
		(width 0.10668)
		(layer "B.Cu")
		(net "NCSI_OCP_V3_2_CRS_DV")
	)
	(segment
		(start 76.00315 -15.71625)
		(end 74.210164 -15.71625)
		(width 0.10668)
		(layer "B.Cu")
		(net "NCSI_OCP_V3_2_CRS_DV")
	)
	(segment
		(start 79.82458 -14.93266)
		(end 76.78674 -14.93266)
		(width 0.10668)
		(layer "B.Cu")
		(net "NCSI_OCP_V3_2_CRS_DV")
	)
	(segment
		(start 129.139442 -46.806104)
		(end 128.334516 -46.001178)
		(width 0.10668)
		(layer "B.Cu")
		(net "NCSI_OCP_V3_2_CRS_DV")
	)
	(segment
		(start 102.489762 -36.19246)
		(end 95.357442 -36.19246)
		(width 0.10668)
		(layer "B.Cu")
		(net "NCSI_OCP_V3_2_CRS_DV")
	)
	(segment
		(start 449.074286 -7.523734)
		(end 449.074286 -6.12648)
		(width 0.10668)
		(layer "F.Cu")
		(net "NCSI_OCP_SFF_TX_EN")
	)
	(segment
		(start 448.961764 -7.636256)
		(end 449.074286 -7.523734)
		(width 0.10668)
		(layer "F.Cu")
		(net "NCSI_OCP_SFF_TX_EN")
	)
	(segment
		(start 448.961764 -8.320024)
		(end 448.961764 -7.636256)
		(width 0.10668)
		(layer "F.Cu")
		(net "NCSI_OCP_SFF_TX_EN")
	)
	(segment
		(start 449.074286 -6.12648)
		(end 448.54368 -5.595874)
		(width 0.10668)
		(layer "F.Cu")
		(net "NCSI_OCP_SFF_TX_EN")
	)
	(via
		(at 206.673704 -67.58051)
		(size 0.508)
		(drill 0.254)
		(layers "F.Cu" "B.Cu")
		(net "NCSI_OCP_SFF_TX_EN")
	)
	(via
		(at 448.54368 -5.595874)
		(size 0.508)
		(drill 0.254)
		(layers "F.Cu" "B.Cu")
		(net "NCSI_OCP_SFF_TX_EN")
	)
	(segment
		(start 207.91805 -67.58051)
		(end 206.673704 -67.58051)
		(width 0.10668)
		(layer "B.Cu")
		(net "NCSI_OCP_SFF_TX_EN")
	)
	(segment
		(start 213.510622 -67.803776)
		(end 217.931238 -67.803776)
		(width 0.11684)
		(layer "In6.Cu")
		(net "NCSI_OCP_SFF_TX_EN")
	)
	(segment
		(start 252.488446 -67.874896)
		(end 253.130304 -67.233038)
		(width 0.11684)
		(layer "In6.Cu")
		(net "NCSI_OCP_SFF_TX_EN")
	)
	(segment
		(start 328.025252 -21.198586)
		(end 332.49743 -21.198586)
		(width 0.11684)
		(layer "In6.Cu")
		(net "NCSI_OCP_SFF_TX_EN")
	)
	(segment
		(start 323.811392 -31.120842)
		(end 323.811392 -25.412446)
		(width 0.11684)
		(layer "In6.Cu")
		(net "NCSI_OCP_SFF_TX_EN")
	)
	(segment
		(start 227.836222 -67.874896)
		(end 252.488446 -67.874896)
		(width 0.11684)
		(layer "In6.Cu")
		(net "NCSI_OCP_SFF_TX_EN")
	)
	(segment
		(start 435.5338 -13.064744)
		(end 435.5338 -11.938)
		(width 0.11684)
		(layer "In6.Cu")
		(net "NCSI_OCP_SFF_TX_EN")
	)
	(segment
		(start 447.65341 -7.941818)
		(end 447.65341 -5.962396)
		(width 0.11684)
		(layer "In6.Cu")
		(net "NCSI_OCP_SFF_TX_EN")
	)
	(segment
		(start 350.744536 -17.530826)
		(end 373.735854 -17.530826)
		(width 0.11684)
		(layer "In6.Cu")
		(net "NCSI_OCP_SFF_TX_EN")
	)
	(segment
		(start 206.673704 -67.58051)
		(end 213.287356 -67.58051)
		(width 0.11684)
		(layer "In6.Cu")
		(net "NCSI_OCP_SFF_TX_EN")
	)
	(segment
		(start 217.931238 -67.803776)
		(end 218.667076 -67.067938)
		(width 0.11684)
		(layer "In6.Cu")
		(net "NCSI_OCP_SFF_TX_EN")
	)
	(segment
		(start 447.65341 -5.962396)
		(end 448.019932 -5.595874)
		(width 0.11684)
		(layer "In6.Cu")
		(net "NCSI_OCP_SFF_TX_EN")
	)
	(segment
		(start 213.287356 -67.58051)
		(end 213.510622 -67.803776)
		(width 0.11684)
		(layer "In6.Cu")
		(net "NCSI_OCP_SFF_TX_EN")
	)
	(segment
		(start 446.568322 -10.054844)
		(end 446.568322 -9.026906)
		(width 0.11684)
		(layer "In6.Cu")
		(net "NCSI_OCP_SFF_TX_EN")
	)
	(segment
		(start 434.61432 -13.984224)
		(end 435.5338 -13.064744)
		(width 0.11684)
		(layer "In6.Cu")
		(net "NCSI_OCP_SFF_TX_EN")
	)
	(segment
		(start 322.63715 -33.562036)
		(end 322.63715 -32.295084)
		(width 0.11684)
		(layer "In6.Cu")
		(net "NCSI_OCP_SFF_TX_EN")
	)
	(segment
		(start 446.14973 -10.473436)
		(end 446.568322 -10.054844)
		(width 0.11684)
		(layer "In6.Cu")
		(net "NCSI_OCP_SFF_TX_EN")
	)
	(segment
		(start 323.811392 -25.412446)
		(end 328.025252 -21.198586)
		(width 0.11684)
		(layer "In6.Cu")
		(net "NCSI_OCP_SFF_TX_EN")
	)
	(segment
		(start 218.667076 -67.067938)
		(end 227.029264 -67.067938)
		(width 0.11684)
		(layer "In6.Cu")
		(net "NCSI_OCP_SFF_TX_EN")
	)
	(segment
		(start 270.68399 -61.941964)
		(end 293.58844 -39.037514)
		(width 0.11684)
		(layer "In6.Cu")
		(net "NCSI_OCP_SFF_TX_EN")
	)
	(segment
		(start 253.130304 -67.233038)
		(end 259.951982 -67.233038)
		(width 0.11684)
		(layer "In6.Cu")
		(net "NCSI_OCP_SFF_TX_EN")
	)
	(segment
		(start 443.121796 -10.473436)
		(end 446.14973 -10.473436)
		(width 0.11684)
		(layer "In6.Cu")
		(net "NCSI_OCP_SFF_TX_EN")
	)
	(segment
		(start 435.5338 -11.938)
		(end 438.40908 -9.06272)
		(width 0.11684)
		(layer "In6.Cu")
		(net "NCSI_OCP_SFF_TX_EN")
	)
	(segment
		(start 259.951982 -67.233038)
		(end 265.243056 -61.941964)
		(width 0.11684)
		(layer "In6.Cu")
		(net "NCSI_OCP_SFF_TX_EN")
	)
	(segment
		(start 441.71108 -9.06272)
		(end 443.121796 -10.473436)
		(width 0.11684)
		(layer "In6.Cu")
		(net "NCSI_OCP_SFF_TX_EN")
	)
	(segment
		(start 265.243056 -61.941964)
		(end 270.68399 -61.941964)
		(width 0.11684)
		(layer "In6.Cu")
		(net "NCSI_OCP_SFF_TX_EN")
	)
	(segment
		(start 332.49743 -21.198586)
		(end 334.22971 -19.466306)
		(width 0.11684)
		(layer "In6.Cu")
		(net "NCSI_OCP_SFF_TX_EN")
	)
	(segment
		(start 377.282456 -13.984224)
		(end 434.61432 -13.984224)
		(width 0.11684)
		(layer "In6.Cu")
		(net "NCSI_OCP_SFF_TX_EN")
	)
	(segment
		(start 373.735854 -17.530826)
		(end 377.282456 -13.984224)
		(width 0.11684)
		(layer "In6.Cu")
		(net "NCSI_OCP_SFF_TX_EN")
	)
	(segment
		(start 446.568322 -9.026906)
		(end 447.65341 -7.941818)
		(width 0.11684)
		(layer "In6.Cu")
		(net "NCSI_OCP_SFF_TX_EN")
	)
	(segment
		(start 293.58844 -39.037514)
		(end 317.161672 -39.037514)
		(width 0.11684)
		(layer "In6.Cu")
		(net "NCSI_OCP_SFF_TX_EN")
	)
	(segment
		(start 438.40908 -9.06272)
		(end 441.71108 -9.06272)
		(width 0.11684)
		(layer "In6.Cu")
		(net "NCSI_OCP_SFF_TX_EN")
	)
	(segment
		(start 317.161672 -39.037514)
		(end 322.63715 -33.562036)
		(width 0.11684)
		(layer "In6.Cu")
		(net "NCSI_OCP_SFF_TX_EN")
	)
	(segment
		(start 227.029264 -67.067938)
		(end 227.836222 -67.874896)
		(width 0.11684)
		(layer "In6.Cu")
		(net "NCSI_OCP_SFF_TX_EN")
	)
	(segment
		(start 348.809056 -19.466306)
		(end 350.744536 -17.530826)
		(width 0.11684)
		(layer "In6.Cu")
		(net "NCSI_OCP_SFF_TX_EN")
	)
	(segment
		(start 322.63715 -32.295084)
		(end 323.811392 -31.120842)
		(width 0.11684)
		(layer "In6.Cu")
		(net "NCSI_OCP_SFF_TX_EN")
	)
	(segment
		(start 334.22971 -19.466306)
		(end 348.809056 -19.466306)
		(width 0.11684)
		(layer "In6.Cu")
		(net "NCSI_OCP_SFF_TX_EN")
	)
	(segment
		(start 448.019932 -5.595874)
		(end 448.54368 -5.595874)
		(width 0.11684)
		(layer "In6.Cu")
		(net "NCSI_OCP_SFF_TX_EN")
	)
	(segment
		(start 448.361816 -7.047738)
		(end 448.361816 -8.320024)
		(width 0.10668)
		(layer "F.Cu")
		(net "NCSI_OCP_SFF_TXD1")
	)
	(segment
		(start 448.55892 -6.865874)
		(end 448.54368 -6.865874)
		(width 0.10668)
		(layer "F.Cu")
		(net "NCSI_OCP_SFF_TXD1")
	)
	(segment
		(start 448.54368 -6.865874)
		(end 448.361816 -7.047738)
		(width 0.10668)
		(layer "F.Cu")
		(net "NCSI_OCP_SFF_TXD1")
	)
	(via
		(at 448.55892 -6.865874)
		(size 0.508)
		(drill 0.254)
		(layers "F.Cu" "B.Cu")
		(net "NCSI_OCP_SFF_TXD1")
	)
	(via
		(at 212.389974 -70.024244)
		(size 0.762)
		(drill 0.254)
		(layers "F.Cu" "B.Cu")
		(net "NCSI_OCP_SFF_TXD1")
	)
	(segment
		(start 213.76005 -70.180454)
		(end 212.546184 -70.180454)
		(width 0.10668)
		(layer "B.Cu")
		(net "NCSI_OCP_SFF_TXD1")
	)
	(segment
		(start 212.546184 -70.180454)
		(end 212.389974 -70.024244)
		(width 0.10668)
		(layer "B.Cu")
		(net "NCSI_OCP_SFF_TXD1")
	)
	(segment
		(start 444.208408 -14.830044)
		(end 444.487046 -14.551406)
		(width 0.11684)
		(layer "In6.Cu")
		(net "NCSI_OCP_SFF_TXD1")
	)
	(segment
		(start 444.487046 -14.551406)
		(end 444.487046 -14.386306)
		(width 0.11684)
		(layer "In6.Cu")
		(net "NCSI_OCP_SFF_TXD1")
	)
	(segment
		(start 324.654672 -25.76195)
		(end 328.374756 -22.041866)
		(width 0.11684)
		(layer "In6.Cu")
		(net "NCSI_OCP_SFF_TXD1")
	)
	(segment
		(start 437.394604 -15.079726)
		(end 441.925456 -15.079726)
		(width 0.11684)
		(layer "In6.Cu")
		(net "NCSI_OCP_SFF_TXD1")
	)
	(segment
		(start 324.654672 -31.55061)
		(end 324.654672 -25.76195)
		(width 0.11684)
		(layer "In6.Cu")
		(net "NCSI_OCP_SFF_TXD1")
	)
	(segment
		(start 441.925456 -15.079726)
		(end 443.026546 -13.978636)
		(width 0.11684)
		(layer "In6.Cu")
		(net "NCSI_OCP_SFF_TXD1")
	)
	(segment
		(start 293.937944 -39.880794)
		(end 317.61684 -39.880794)
		(width 0.11684)
		(layer "In6.Cu")
		(net "NCSI_OCP_SFF_TXD1")
	)
	(segment
		(start 323.48043 -32.724852)
		(end 324.654672 -31.55061)
		(width 0.11684)
		(layer "In6.Cu")
		(net "NCSI_OCP_SFF_TXD1")
	)
	(segment
		(start 446.661286 -11.610594)
		(end 448.55892 -9.71296)
		(width 0.11684)
		(layer "In6.Cu")
		(net "NCSI_OCP_SFF_TXD1")
	)
	(segment
		(start 443.191646 -13.978636)
		(end 444.043308 -14.830044)
		(width 0.11684)
		(layer "In6.Cu")
		(net "NCSI_OCP_SFF_TXD1")
	)
	(segment
		(start 334.579214 -20.309586)
		(end 349.304356 -20.309586)
		(width 0.11684)
		(layer "In6.Cu")
		(net "NCSI_OCP_SFF_TXD1")
	)
	(segment
		(start 251.60097 -69.42455)
		(end 251.94006 -69.08546)
		(width 0.11684)
		(layer "In6.Cu")
		(net "NCSI_OCP_SFF_TXD1")
	)
	(segment
		(start 235.984542 -69.950838)
		(end 243.241576 -69.950838)
		(width 0.11684)
		(layer "In6.Cu")
		(net "NCSI_OCP_SFF_TXD1")
	)
	(segment
		(start 448.55892 -9.71296)
		(end 448.55892 -6.865874)
		(width 0.11684)
		(layer "In6.Cu")
		(net "NCSI_OCP_SFF_TXD1")
	)
	(segment
		(start 323.48043 -34.017204)
		(end 323.48043 -32.724852)
		(width 0.11684)
		(layer "In6.Cu")
		(net "NCSI_OCP_SFF_TXD1")
	)
	(segment
		(start 332.846934 -22.041866)
		(end 334.579214 -20.309586)
		(width 0.11684)
		(layer "In6.Cu")
		(net "NCSI_OCP_SFF_TXD1")
	)
	(segment
		(start 253.870714 -69.733414)
		(end 258.64439 -69.733414)
		(width 0.11684)
		(layer "In6.Cu")
		(net "NCSI_OCP_SFF_TXD1")
	)
	(segment
		(start 251.94006 -69.08546)
		(end 253.22276 -69.08546)
		(width 0.11684)
		(layer "In6.Cu")
		(net "NCSI_OCP_SFF_TXD1")
	)
	(segment
		(start 443.914022 -13.09116)
		(end 444.079122 -13.09116)
		(width 0.11684)
		(layer "In6.Cu")
		(net "NCSI_OCP_SFF_TXD1")
	)
	(segment
		(start 445.275208 -14.287246)
		(end 445.440562 -14.287246)
		(width 0.11684)
		(layer "In6.Cu")
		(net "NCSI_OCP_SFF_TXD1")
	)
	(segment
		(start 243.241576 -69.950838)
		(end 243.767864 -69.42455)
		(width 0.11684)
		(layer "In6.Cu")
		(net "NCSI_OCP_SFF_TXD1")
	)
	(segment
		(start 445.7192 -13.843508)
		(end 444.52286 -12.647168)
		(width 0.11684)
		(layer "In6.Cu")
		(net "NCSI_OCP_SFF_TXD1")
	)
	(segment
		(start 445.440562 -14.287246)
		(end 445.7192 -14.008608)
		(width 0.11684)
		(layer "In6.Cu")
		(net "NCSI_OCP_SFF_TXD1")
	)
	(segment
		(start 235.54436 -69.510656)
		(end 235.984542 -69.950838)
		(width 0.11684)
		(layer "In6.Cu")
		(net "NCSI_OCP_SFF_TXD1")
	)
	(segment
		(start 443.635384 -13.369798)
		(end 443.914022 -13.09116)
		(width 0.11684)
		(layer "In6.Cu")
		(net "NCSI_OCP_SFF_TXD1")
	)
	(segment
		(start 377.63196 -14.827504)
		(end 437.142382 -14.827504)
		(width 0.11684)
		(layer "In6.Cu")
		(net "NCSI_OCP_SFF_TXD1")
	)
	(segment
		(start 444.043308 -14.830044)
		(end 444.208408 -14.830044)
		(width 0.11684)
		(layer "In6.Cu")
		(net "NCSI_OCP_SFF_TXD1")
	)
	(segment
		(start 443.026546 -13.978636)
		(end 443.191646 -13.978636)
		(width 0.11684)
		(layer "In6.Cu")
		(net "NCSI_OCP_SFF_TXD1")
	)
	(segment
		(start 437.142382 -14.827504)
		(end 437.394604 -15.079726)
		(width 0.11684)
		(layer "In6.Cu")
		(net "NCSI_OCP_SFF_TXD1")
	)
	(segment
		(start 253.22276 -69.08546)
		(end 253.870714 -69.733414)
		(width 0.11684)
		(layer "In6.Cu")
		(net "NCSI_OCP_SFF_TXD1")
	)
	(segment
		(start 212.512656 -70.024244)
		(end 213.11235 -69.42455)
		(width 0.11684)
		(layer "In6.Cu")
		(net "NCSI_OCP_SFF_TXD1")
	)
	(segment
		(start 271.033494 -62.785244)
		(end 293.937944 -39.880794)
		(width 0.11684)
		(layer "In6.Cu")
		(net "NCSI_OCP_SFF_TXD1")
	)
	(segment
		(start 443.635384 -13.534898)
		(end 443.635384 -13.369798)
		(width 0.11684)
		(layer "In6.Cu")
		(net "NCSI_OCP_SFF_TXD1")
	)
	(segment
		(start 317.61684 -39.880794)
		(end 323.48043 -34.017204)
		(width 0.11684)
		(layer "In6.Cu")
		(net "NCSI_OCP_SFF_TXD1")
	)
	(segment
		(start 213.11235 -69.42455)
		(end 217.892122 -69.42455)
		(width 0.11684)
		(layer "In6.Cu")
		(net "NCSI_OCP_SFF_TXD1")
	)
	(segment
		(start 226.546156 -69.510656)
		(end 235.54436 -69.510656)
		(width 0.11684)
		(layer "In6.Cu")
		(net "NCSI_OCP_SFF_TXD1")
	)
	(segment
		(start 225.788982 -70.26783)
		(end 226.546156 -69.510656)
		(width 0.11684)
		(layer "In6.Cu")
		(net "NCSI_OCP_SFF_TXD1")
	)
	(segment
		(start 444.52286 -12.647168)
		(end 444.52286 -12.482322)
		(width 0.11684)
		(layer "In6.Cu")
		(net "NCSI_OCP_SFF_TXD1")
	)
	(segment
		(start 212.389974 -70.024244)
		(end 212.512656 -70.024244)
		(width 0.11684)
		(layer "In6.Cu")
		(net "NCSI_OCP_SFF_TXD1")
	)
	(segment
		(start 328.374756 -22.041866)
		(end 332.846934 -22.041866)
		(width 0.11684)
		(layer "In6.Cu")
		(net "NCSI_OCP_SFF_TXD1")
	)
	(segment
		(start 222.423736 -70.26783)
		(end 225.788982 -70.26783)
		(width 0.11684)
		(layer "In6.Cu")
		(net "NCSI_OCP_SFF_TXD1")
	)
	(segment
		(start 351.239836 -18.374106)
		(end 374.085358 -18.374106)
		(width 0.11684)
		(layer "In6.Cu")
		(net "NCSI_OCP_SFF_TXD1")
	)
	(segment
		(start 258.64439 -69.733414)
		(end 265.59256 -62.785244)
		(width 0.11684)
		(layer "In6.Cu")
		(net "NCSI_OCP_SFF_TXD1")
	)
	(segment
		(start 444.487046 -14.386306)
		(end 443.635384 -13.534898)
		(width 0.11684)
		(layer "In6.Cu")
		(net "NCSI_OCP_SFF_TXD1")
	)
	(segment
		(start 265.59256 -62.785244)
		(end 271.033494 -62.785244)
		(width 0.11684)
		(layer "In6.Cu")
		(net "NCSI_OCP_SFF_TXD1")
	)
	(segment
		(start 374.085358 -18.374106)
		(end 377.63196 -14.827504)
		(width 0.11684)
		(layer "In6.Cu")
		(net "NCSI_OCP_SFF_TXD1")
	)
	(segment
		(start 243.767864 -69.42455)
		(end 251.60097 -69.42455)
		(width 0.11684)
		(layer "In6.Cu")
		(net "NCSI_OCP_SFF_TXD1")
	)
	(segment
		(start 444.52286 -12.482322)
		(end 445.394588 -11.610594)
		(width 0.11684)
		(layer "In6.Cu")
		(net "NCSI_OCP_SFF_TXD1")
	)
	(segment
		(start 445.7192 -14.008608)
		(end 445.7192 -13.843508)
		(width 0.11684)
		(layer "In6.Cu")
		(net "NCSI_OCP_SFF_TXD1")
	)
	(segment
		(start 220.838014 -68.682108)
		(end 222.423736 -70.26783)
		(width 0.11684)
		(layer "In6.Cu")
		(net "NCSI_OCP_SFF_TXD1")
	)
	(segment
		(start 444.079122 -13.09116)
		(end 445.275208 -14.287246)
		(width 0.11684)
		(layer "In6.Cu")
		(net "NCSI_OCP_SFF_TXD1")
	)
	(segment
		(start 218.634564 -68.682108)
		(end 220.838014 -68.682108)
		(width 0.11684)
		(layer "In6.Cu")
		(net "NCSI_OCP_SFF_TXD1")
	)
	(segment
		(start 445.394588 -11.610594)
		(end 446.661286 -11.610594)
		(width 0.11684)
		(layer "In6.Cu")
		(net "NCSI_OCP_SFF_TXD1")
	)
	(segment
		(start 349.304356 -20.309586)
		(end 351.239836 -18.374106)
		(width 0.11684)
		(layer "In6.Cu")
		(net "NCSI_OCP_SFF_TXD1")
	)
	(segment
		(start 217.892122 -69.42455)
		(end 218.634564 -68.682108)
		(width 0.11684)
		(layer "In6.Cu")
		(net "NCSI_OCP_SFF_TXD1")
	)
	(segment
		(start 447.761868 -5.107686)
		(end 448.54368 -4.325874)
		(width 0.10668)
		(layer "F.Cu")
		(net "NCSI_OCP_SFF_TXD0")
	)
	(segment
		(start 447.761868 -8.320024)
		(end 447.761868 -5.107686)
		(width 0.10668)
		(layer "F.Cu")
		(net "NCSI_OCP_SFF_TXD0")
	)
	(via
		(at 212.42147 -68.230496)
		(size 0.508)
		(drill 0.254)
		(layers "F.Cu" "B.Cu")
		(net "NCSI_OCP_SFF_TXD0")
	)
	(via
		(at 448.54368 -4.325874)
		(size 0.508)
		(drill 0.254)
		(layers "F.Cu" "B.Cu")
		(net "NCSI_OCP_SFF_TXD0")
	)
	(segment
		(start 213.76005 -68.230496)
		(end 212.42147 -68.230496)
		(width 0.10668)
		(layer "B.Cu")
		(net "NCSI_OCP_SFF_TXD0")
	)
	(segment
		(start 441.536328 -9.48436)
		(end 438.72404 -9.48436)
		(width 0.11684)
		(layer "In6.Cu")
		(net "NCSI_OCP_SFF_TXD0")
	)
	(segment
		(start 323.05879 -33.736788)
		(end 317.336424 -39.459154)
		(width 0.11684)
		(layer "In6.Cu")
		(net "NCSI_OCP_SFF_TXD0")
	)
	(segment
		(start 448.0941 -8.256524)
		(end 447.27368 -9.076944)
		(width 0.11684)
		(layer "In6.Cu")
		(net "NCSI_OCP_SFF_TXD0")
	)
	(segment
		(start 223.21139 -68.884038)
		(end 222.160846 -68.884038)
		(width 0.11684)
		(layer "In6.Cu")
		(net "NCSI_OCP_SFF_TXD0")
	)
	(segment
		(start 449.0085 -5.989066)
		(end 448.81165 -6.185916)
		(width 0.11684)
		(layer "In6.Cu")
		(net "NCSI_OCP_SFF_TXD0")
	)
	(segment
		(start 254.208534 -69.26326)
		(end 253.346966 -68.401692)
		(width 0.11684)
		(layer "In6.Cu")
		(net "NCSI_OCP_SFF_TXD0")
	)
	(segment
		(start 225.998532 -68.401692)
		(end 223.693736 -68.401692)
		(width 0.11684)
		(layer "In6.Cu")
		(net "NCSI_OCP_SFF_TXD0")
	)
	(segment
		(start 323.05879 -32.469836)
		(end 323.05879 -33.736788)
		(width 0.11684)
		(layer "In6.Cu")
		(net "NCSI_OCP_SFF_TXD0")
	)
	(segment
		(start 217.785188 -68.884038)
		(end 213.075012 -68.884038)
		(width 0.11684)
		(layer "In6.Cu")
		(net "NCSI_OCP_SFF_TXD0")
	)
	(segment
		(start 373.910606 -17.952466)
		(end 350.940878 -17.952466)
		(width 0.11684)
		(layer "In6.Cu")
		(net "NCSI_OCP_SFF_TXD0")
	)
	(segment
		(start 258.518152 -69.26326)
		(end 254.208534 -69.26326)
		(width 0.11684)
		(layer "In6.Cu")
		(net "NCSI_OCP_SFF_TXD0")
	)
	(segment
		(start 442.947044 -10.895076)
		(end 441.536328 -9.48436)
		(width 0.11684)
		(layer "In6.Cu")
		(net "NCSI_OCP_SFF_TXD0")
	)
	(segment
		(start 219.179648 -67.489578)
		(end 217.785188 -68.884038)
		(width 0.11684)
		(layer "In6.Cu")
		(net "NCSI_OCP_SFF_TXD0")
	)
	(segment
		(start 446.42913 -10.895076)
		(end 442.947044 -10.895076)
		(width 0.11684)
		(layer "In6.Cu")
		(net "NCSI_OCP_SFF_TXD0")
	)
	(segment
		(start 435.991 -13.203936)
		(end 434.789072 -14.405864)
		(width 0.11684)
		(layer "In6.Cu")
		(net "NCSI_OCP_SFF_TXD0")
	)
	(segment
		(start 328.200004 -21.620226)
		(end 324.233032 -25.587198)
		(width 0.11684)
		(layer "In6.Cu")
		(net "NCSI_OCP_SFF_TXD0")
	)
	(segment
		(start 226.65563 -69.05879)
		(end 225.998532 -68.401692)
		(width 0.11684)
		(layer "In6.Cu")
		(net "NCSI_OCP_SFF_TXD0")
	)
	(segment
		(start 213.075012 -68.884038)
		(end 212.42147 -68.230496)
		(width 0.11684)
		(layer "In6.Cu")
		(net "NCSI_OCP_SFF_TXD0")
	)
	(segment
		(start 448.0941 -6.46049)
		(end 448.0941 -8.256524)
		(width 0.11684)
		(layer "In6.Cu")
		(net "NCSI_OCP_SFF_TXD0")
	)
	(segment
		(start 317.336424 -39.459154)
		(end 293.763192 -39.459154)
		(width 0.11684)
		(layer "In6.Cu")
		(net "NCSI_OCP_SFF_TXD0")
	)
	(segment
		(start 234.66044 -69.05879)
		(end 226.65563 -69.05879)
		(width 0.11684)
		(layer "In6.Cu")
		(net "NCSI_OCP_SFF_TXD0")
	)
	(segment
		(start 222.160846 -68.884038)
		(end 220.766386 -67.489578)
		(width 0.11684)
		(layer "In6.Cu")
		(net "NCSI_OCP_SFF_TXD0")
	)
	(segment
		(start 220.766386 -67.489578)
		(end 219.179648 -67.489578)
		(width 0.11684)
		(layer "In6.Cu")
		(net "NCSI_OCP_SFF_TXD0")
	)
	(segment
		(start 253.346966 -68.401692)
		(end 235.317538 -68.401692)
		(width 0.11684)
		(layer "In6.Cu")
		(net "NCSI_OCP_SFF_TXD0")
	)
	(segment
		(start 434.789072 -14.405864)
		(end 377.457208 -14.405864)
		(width 0.11684)
		(layer "In6.Cu")
		(net "NCSI_OCP_SFF_TXD0")
	)
	(segment
		(start 448.368674 -6.185916)
		(end 448.0941 -6.46049)
		(width 0.11684)
		(layer "In6.Cu")
		(net "NCSI_OCP_SFF_TXD0")
	)
	(segment
		(start 448.54368 -4.325874)
		(end 449.0085 -5.447792)
		(width 0.11684)
		(layer "In6.Cu")
		(net "NCSI_OCP_SFF_TXD0")
	)
	(segment
		(start 265.417808 -62.363604)
		(end 258.518152 -69.26326)
		(width 0.11684)
		(layer "In6.Cu")
		(net "NCSI_OCP_SFF_TXD0")
	)
	(segment
		(start 448.81165 -6.185916)
		(end 448.368674 -6.185916)
		(width 0.11684)
		(layer "In6.Cu")
		(net "NCSI_OCP_SFF_TXD0")
	)
	(segment
		(start 350.940878 -17.952466)
		(end 349.005398 -19.887946)
		(width 0.11684)
		(layer "In6.Cu")
		(net "NCSI_OCP_SFF_TXD0")
	)
	(segment
		(start 435.991 -12.2174)
		(end 435.991 -13.203936)
		(width 0.11684)
		(layer "In6.Cu")
		(net "NCSI_OCP_SFF_TXD0")
	)
	(segment
		(start 293.763192 -39.459154)
		(end 270.858742 -62.363604)
		(width 0.11684)
		(layer "In6.Cu")
		(net "NCSI_OCP_SFF_TXD0")
	)
	(segment
		(start 447.27368 -9.076944)
		(end 447.27368 -10.050526)
		(width 0.11684)
		(layer "In6.Cu")
		(net "NCSI_OCP_SFF_TXD0")
	)
	(segment
		(start 235.317538 -68.401692)
		(end 234.66044 -69.05879)
		(width 0.11684)
		(layer "In6.Cu")
		(net "NCSI_OCP_SFF_TXD0")
	)
	(segment
		(start 334.404462 -19.887946)
		(end 332.672182 -21.620226)
		(width 0.11684)
		(layer "In6.Cu")
		(net "NCSI_OCP_SFF_TXD0")
	)
	(segment
		(start 223.693736 -68.401692)
		(end 223.21139 -68.884038)
		(width 0.11684)
		(layer "In6.Cu")
		(net "NCSI_OCP_SFF_TXD0")
	)
	(segment
		(start 377.457208 -14.405864)
		(end 373.910606 -17.952466)
		(width 0.11684)
		(layer "In6.Cu")
		(net "NCSI_OCP_SFF_TXD0")
	)
	(segment
		(start 447.27368 -10.050526)
		(end 446.42913 -10.895076)
		(width 0.11684)
		(layer "In6.Cu")
		(net "NCSI_OCP_SFF_TXD0")
	)
	(segment
		(start 324.233032 -31.295594)
		(end 323.05879 -32.469836)
		(width 0.11684)
		(layer "In6.Cu")
		(net "NCSI_OCP_SFF_TXD0")
	)
	(segment
		(start 332.672182 -21.620226)
		(end 328.200004 -21.620226)
		(width 0.11684)
		(layer "In6.Cu")
		(net "NCSI_OCP_SFF_TXD0")
	)
	(segment
		(start 449.0085 -5.447792)
		(end 449.0085 -5.989066)
		(width 0.11684)
		(layer "In6.Cu")
		(net "NCSI_OCP_SFF_TXD0")
	)
	(segment
		(start 270.858742 -62.363604)
		(end 265.417808 -62.363604)
		(width 0.11684)
		(layer "In6.Cu")
		(net "NCSI_OCP_SFF_TXD0")
	)
	(segment
		(start 324.233032 -25.587198)
		(end 324.233032 -31.295594)
		(width 0.11684)
		(layer "In6.Cu")
		(net "NCSI_OCP_SFF_TXD0")
	)
	(segment
		(start 438.72404 -9.48436)
		(end 435.991 -12.2174)
		(width 0.11684)
		(layer "In6.Cu")
		(net "NCSI_OCP_SFF_TXD0")
	)
	(segment
		(start 349.005398 -19.887946)
		(end 334.404462 -19.887946)
		(width 0.11684)
		(layer "In6.Cu")
		(net "NCSI_OCP_SFF_TXD0")
	)
	(segment
		(start 448.361816 -11.26998)
		(end 448.361816 -13.057124)
		(width 0.10668)
		(layer "F.Cu")
		(net "NCSI_OCP_SFF_RXD1")
	)
	(segment
		(start 448.443858 -13.139166)
		(end 448.443858 -13.637768)
		(width 0.10668)
		(layer "F.Cu")
		(net "NCSI_OCP_SFF_RXD1")
	)
	(segment
		(start 448.361816 -13.057124)
		(end 448.443858 -13.139166)
		(width 0.10668)
		(layer "F.Cu")
		(net "NCSI_OCP_SFF_RXD1")
	)
	(via
		(at 201.63917 -77.550264)
		(size 0.508)
		(drill 0.254)
		(layers "F.Cu" "B.Cu")
		(net "NCSI_OCP_SFF_RXD1")
	)
	(via
		(at 448.443858 -13.637768)
		(size 0.508)
		(drill 0.254)
		(layers "F.Cu" "B.Cu")
		(net "NCSI_OCP_SFF_RXD1")
	)
	(segment
		(start 201.346816 -77.842618)
		(end 201.63917 -77.550264)
		(width 0.10668)
		(layer "B.Cu")
		(net "NCSI_OCP_SFF_RXD1")
	)
	(segment
		(start 200.146158 -77.842618)
		(end 201.346816 -77.842618)
		(width 0.10668)
		(layer "B.Cu")
		(net "NCSI_OCP_SFF_RXD1")
	)
	(segment
		(start 316.641988 -42.448734)
		(end 292.562788 -42.448734)
		(width 0.11684)
		(layer "In6.Cu")
		(net "NCSI_OCP_SFF_RXD1")
	)
	(segment
		(start 436.406544 -15.71371)
		(end 377.999244 -15.71371)
		(width 0.11684)
		(layer "In6.Cu")
		(net "NCSI_OCP_SFF_RXD1")
	)
	(segment
		(start 203.124054 -77.507846)
		(end 201.681588 -77.507846)
		(width 0.11684)
		(layer "In6.Cu")
		(net "NCSI_OCP_SFF_RXD1")
	)
	(segment
		(start 219.766134 -76.671678)
		(end 216.78773 -76.671678)
		(width 0.11684)
		(layer "In6.Cu")
		(net "NCSI_OCP_SFF_RXD1")
	)
	(segment
		(start 442.58738 -15.983966)
		(end 442.2267 -16.344646)
		(width 0.11684)
		(layer "In6.Cu")
		(net "NCSI_OCP_SFF_RXD1")
	)
	(segment
		(start 255.93802 -70.576694)
		(end 254.821182 -71.693532)
		(width 0.11684)
		(layer "In6.Cu")
		(net "NCSI_OCP_SFF_RXD1")
	)
	(segment
		(start 292.562788 -42.448734)
		(end 271.382998 -63.628524)
		(width 0.11684)
		(layer "In6.Cu")
		(net "NCSI_OCP_SFF_RXD1")
	)
	(segment
		(start 271.382998 -63.628524)
		(end 266.009628 -63.628524)
		(width 0.11684)
		(layer "In6.Cu")
		(net "NCSI_OCP_SFF_RXD1")
	)
	(segment
		(start 324.32371 -33.181544)
		(end 324.32371 -34.366708)
		(width 0.11684)
		(layer "In6.Cu")
		(net "NCSI_OCP_SFF_RXD1")
	)
	(segment
		(start 351.858834 -19.260312)
		(end 349.960692 -21.158454)
		(width 0.11684)
		(layer "In6.Cu")
		(net "NCSI_OCP_SFF_RXD1")
	)
	(segment
		(start 448.443858 -13.637768)
		(end 448.64528 -13.83919)
		(width 0.11684)
		(layer "In6.Cu")
		(net "NCSI_OCP_SFF_RXD1")
	)
	(segment
		(start 377.999244 -15.71371)
		(end 374.452642 -19.260312)
		(width 0.11684)
		(layer "In6.Cu")
		(net "NCSI_OCP_SFF_RXD1")
	)
	(segment
		(start 216.317576 -76.201524)
		(end 210.151726 -76.201524)
		(width 0.11684)
		(layer "In6.Cu")
		(net "NCSI_OCP_SFF_RXD1")
	)
	(segment
		(start 341.050372 -22.210776)
		(end 339.99805 -21.158454)
		(width 0.11684)
		(layer "In6.Cu")
		(net "NCSI_OCP_SFF_RXD1")
	)
	(segment
		(start 325.664068 -31.841186)
		(end 324.32371 -33.181544)
		(width 0.11684)
		(layer "In6.Cu")
		(net "NCSI_OCP_SFF_RXD1")
	)
	(segment
		(start 448.64528 -14.81328)
		(end 447.474594 -15.983966)
		(width 0.11684)
		(layer "In6.Cu")
		(net "NCSI_OCP_SFF_RXD1")
	)
	(segment
		(start 334.931004 -21.158454)
		(end 331.347064 -24.742394)
		(width 0.11684)
		(layer "In6.Cu")
		(net "NCSI_OCP_SFF_RXD1")
	)
	(segment
		(start 447.474594 -15.983966)
		(end 442.58738 -15.983966)
		(width 0.11684)
		(layer "In6.Cu")
		(net "NCSI_OCP_SFF_RXD1")
	)
	(segment
		(start 326.874886 -24.742394)
		(end 325.664068 -25.953212)
		(width 0.11684)
		(layer "In6.Cu")
		(net "NCSI_OCP_SFF_RXD1")
	)
	(segment
		(start 438.099708 -17.406874)
		(end 436.406544 -15.71371)
		(width 0.11684)
		(layer "In6.Cu")
		(net "NCSI_OCP_SFF_RXD1")
	)
	(segment
		(start 345.153488 -22.210776)
		(end 341.050372 -22.210776)
		(width 0.11684)
		(layer "In6.Cu")
		(net "NCSI_OCP_SFF_RXD1")
	)
	(segment
		(start 318.639444 -40.050974)
		(end 318.639444 -40.451278)
		(width 0.11684)
		(layer "In6.Cu")
		(net "NCSI_OCP_SFF_RXD1")
	)
	(segment
		(start 229.04704 -71.693532)
		(end 224.983294 -75.757278)
		(width 0.11684)
		(layer "In6.Cu")
		(net "NCSI_OCP_SFF_RXD1")
	)
	(segment
		(start 439.36158 -17.406874)
		(end 438.099708 -17.406874)
		(width 0.11684)
		(layer "In6.Cu")
		(net "NCSI_OCP_SFF_RXD1")
	)
	(segment
		(start 220.680534 -75.757278)
		(end 219.766134 -76.671678)
		(width 0.11684)
		(layer "In6.Cu")
		(net "NCSI_OCP_SFF_RXD1")
	)
	(segment
		(start 254.821182 -71.693532)
		(end 229.04704 -71.693532)
		(width 0.11684)
		(layer "In6.Cu")
		(net "NCSI_OCP_SFF_RXD1")
	)
	(segment
		(start 349.960692 -21.158454)
		(end 346.20581 -21.158454)
		(width 0.11684)
		(layer "In6.Cu")
		(net "NCSI_OCP_SFF_RXD1")
	)
	(segment
		(start 318.639444 -40.451278)
		(end 316.641988 -42.448734)
		(width 0.11684)
		(layer "In6.Cu")
		(net "NCSI_OCP_SFF_RXD1")
	)
	(segment
		(start 210.151726 -76.201524)
		(end 209.89036 -75.940158)
		(width 0.11684)
		(layer "In6.Cu")
		(net "NCSI_OCP_SFF_RXD1")
	)
	(segment
		(start 203.411328 -77.220572)
		(end 203.124054 -77.507846)
		(width 0.11684)
		(layer "In6.Cu")
		(net "NCSI_OCP_SFF_RXD1")
	)
	(segment
		(start 374.452642 -19.260312)
		(end 351.858834 -19.260312)
		(width 0.11684)
		(layer "In6.Cu")
		(net "NCSI_OCP_SFF_RXD1")
	)
	(segment
		(start 201.681588 -77.507846)
		(end 201.63917 -77.550264)
		(width 0.11684)
		(layer "In6.Cu")
		(net "NCSI_OCP_SFF_RXD1")
	)
	(segment
		(start 339.99805 -21.158454)
		(end 334.931004 -21.158454)
		(width 0.11684)
		(layer "In6.Cu")
		(net "NCSI_OCP_SFF_RXD1")
	)
	(segment
		(start 346.20581 -21.158454)
		(end 345.153488 -22.210776)
		(width 0.11684)
		(layer "In6.Cu")
		(net "NCSI_OCP_SFF_RXD1")
	)
	(segment
		(start 324.32371 -34.366708)
		(end 318.639444 -40.050974)
		(width 0.11684)
		(layer "In6.Cu")
		(net "NCSI_OCP_SFF_RXD1")
	)
	(segment
		(start 442.2267 -16.344646)
		(end 440.423808 -16.344646)
		(width 0.11684)
		(layer "In6.Cu")
		(net "NCSI_OCP_SFF_RXD1")
	)
	(segment
		(start 266.009628 -63.628524)
		(end 259.061458 -70.576694)
		(width 0.11684)
		(layer "In6.Cu")
		(net "NCSI_OCP_SFF_RXD1")
	)
	(segment
		(start 203.411328 -76.6318)
		(end 203.411328 -77.220572)
		(width 0.11684)
		(layer "In6.Cu")
		(net "NCSI_OCP_SFF_RXD1")
	)
	(segment
		(start 209.89036 -75.940158)
		(end 204.10297 -75.940158)
		(width 0.11684)
		(layer "In6.Cu")
		(net "NCSI_OCP_SFF_RXD1")
	)
	(segment
		(start 331.347064 -24.742394)
		(end 326.874886 -24.742394)
		(width 0.11684)
		(layer "In6.Cu")
		(net "NCSI_OCP_SFF_RXD1")
	)
	(segment
		(start 216.78773 -76.671678)
		(end 216.317576 -76.201524)
		(width 0.11684)
		(layer "In6.Cu")
		(net "NCSI_OCP_SFF_RXD1")
	)
	(segment
		(start 448.64528 -13.83919)
		(end 448.64528 -14.81328)
		(width 0.11684)
		(layer "In6.Cu")
		(net "NCSI_OCP_SFF_RXD1")
	)
	(segment
		(start 204.10297 -75.940158)
		(end 203.411328 -76.6318)
		(width 0.11684)
		(layer "In6.Cu")
		(net "NCSI_OCP_SFF_RXD1")
	)
	(segment
		(start 440.423808 -16.344646)
		(end 439.36158 -17.406874)
		(width 0.11684)
		(layer "In6.Cu")
		(net "NCSI_OCP_SFF_RXD1")
	)
	(segment
		(start 224.983294 -75.757278)
		(end 220.680534 -75.757278)
		(width 0.11684)
		(layer "In6.Cu")
		(net "NCSI_OCP_SFF_RXD1")
	)
	(segment
		(start 325.664068 -25.953212)
		(end 325.664068 -31.841186)
		(width 0.11684)
		(layer "In6.Cu")
		(net "NCSI_OCP_SFF_RXD1")
	)
	(segment
		(start 259.061458 -70.576694)
		(end 255.93802 -70.576694)
		(width 0.11684)
		(layer "In6.Cu")
		(net "NCSI_OCP_SFF_RXD1")
	)
	(segment
		(start 447.761868 -11.26998)
		(end 447.761868 -12.96797)
		(width 0.10668)
		(layer "F.Cu")
		(net "NCSI_OCP_SFF_RXD0")
	)
	(segment
		(start 447.761868 -12.96797)
		(end 447.80454 -13.010642)
		(width 0.10668)
		(layer "F.Cu")
		(net "NCSI_OCP_SFF_RXD0")
	)
	(via
		(at 447.80454 -13.010642)
		(size 0.508)
		(drill 0.254)
		(layers "F.Cu" "B.Cu")
		(net "NCSI_OCP_SFF_RXD0")
	)
	(via
		(at 201.478134 -75.199748)
		(size 0.762)
		(drill 0.254)
		(layers "F.Cu" "B.Cu")
		(net "NCSI_OCP_SFF_RXD0")
	)
	(segment
		(start 200.146158 -75.89266)
		(end 200.785222 -75.89266)
		(width 0.10668)
		(layer "B.Cu")
		(net "NCSI_OCP_SFF_RXD0")
	)
	(segment
		(start 200.785222 -75.89266)
		(end 201.478134 -75.199748)
		(width 0.10668)
		(layer "B.Cu")
		(net "NCSI_OCP_SFF_RXD0")
	)
	(segment
		(start 304.44694 -41.429432)
		(end 303.329848 -40.31234)
		(width 0.11684)
		(layer "In6.Cu")
		(net "NCSI_OCP_SFF_RXD0")
	)
	(segment
		(start 240.591086 -70.688454)
		(end 240.154968 -71.124572)
		(width 0.11684)
		(layer "In6.Cu")
		(net "NCSI_OCP_SFF_RXD0")
	)
	(segment
		(start 294.10279 -40.31234)
		(end 271.208246 -63.206884)
		(width 0.11684)
		(layer "In6.Cu")
		(net "NCSI_OCP_SFF_RXD0")
	)
	(segment
		(start 318.217804 -40.230552)
		(end 317.018924 -41.429432)
		(width 0.11684)
		(layer "In6.Cu")
		(net "NCSI_OCP_SFF_RXD0")
	)
	(segment
		(start 439.165746 -16.942308)
		(end 438.247536 -16.942308)
		(width 0.11684)
		(layer "In6.Cu")
		(net "NCSI_OCP_SFF_RXD0")
	)
	(segment
		(start 318.217804 -39.876222)
		(end 318.217804 -40.230552)
		(width 0.11684)
		(layer "In6.Cu")
		(net "NCSI_OCP_SFF_RXD0")
	)
	(segment
		(start 317.018924 -41.429432)
		(end 304.44694 -41.429432)
		(width 0.11684)
		(layer "In6.Cu")
		(net "NCSI_OCP_SFF_RXD0")
	)
	(segment
		(start 325.0819 -31.735014)
		(end 323.90207 -32.914844)
		(width 0.11684)
		(layer "In6.Cu")
		(net "NCSI_OCP_SFF_RXD0")
	)
	(segment
		(start 442.323982 -15.437104)
		(end 442.089286 -15.6718)
		(width 0.11684)
		(layer "In6.Cu")
		(net "NCSI_OCP_SFF_RXD0")
	)
	(segment
		(start 325.0819 -25.938988)
		(end 325.0819 -31.735014)
		(width 0.11684)
		(layer "In6.Cu")
		(net "NCSI_OCP_SFF_RXD0")
	)
	(segment
		(start 328.551794 -22.469094)
		(end 325.0819 -25.938988)
		(width 0.11684)
		(layer "In6.Cu")
		(net "NCSI_OCP_SFF_RXD0")
	)
	(segment
		(start 323.90207 -32.914844)
		(end 323.90207 -34.191956)
		(width 0.11684)
		(layer "In6.Cu")
		(net "NCSI_OCP_SFF_RXD0")
	)
	(segment
		(start 323.90207 -34.191956)
		(end 318.217804 -39.876222)
		(width 0.11684)
		(layer "In6.Cu")
		(net "NCSI_OCP_SFF_RXD0")
	)
	(segment
		(start 227.960428 -71.124572)
		(end 224.554796 -74.530204)
		(width 0.11684)
		(layer "In6.Cu")
		(net "NCSI_OCP_SFF_RXD0")
	)
	(segment
		(start 438.247536 -16.942308)
		(end 436.554372 -15.249144)
		(width 0.11684)
		(layer "In6.Cu")
		(net "NCSI_OCP_SFF_RXD0")
	)
	(segment
		(start 377.806712 -15.249144)
		(end 374.26011 -18.795746)
		(width 0.11684)
		(layer "In6.Cu")
		(net "NCSI_OCP_SFF_RXD0")
	)
	(segment
		(start 436.554372 -15.249144)
		(end 377.806712 -15.249144)
		(width 0.11684)
		(layer "In6.Cu")
		(net "NCSI_OCP_SFF_RXD0")
	)
	(segment
		(start 214.753444 -74.046842)
		(end 202.63104 -74.046842)
		(width 0.11684)
		(layer "In6.Cu")
		(net "NCSI_OCP_SFF_RXD0")
	)
	(segment
		(start 258.85775 -70.155054)
		(end 254.99568 -70.155054)
		(width 0.11684)
		(layer "In6.Cu")
		(net "NCSI_OCP_SFF_RXD0")
	)
	(segment
		(start 351.59061 -18.795746)
		(end 349.649542 -20.736814)
		(width 0.11684)
		(layer "In6.Cu")
		(net "NCSI_OCP_SFF_RXD0")
	)
	(segment
		(start 447.496692 -13.770356)
		(end 447.496692 -14.905482)
		(width 0.11684)
		(layer "In6.Cu")
		(net "NCSI_OCP_SFF_RXD0")
	)
	(segment
		(start 447.80454 -13.010642)
		(end 447.80454 -13.462508)
		(width 0.11684)
		(layer "In6.Cu")
		(net "NCSI_OCP_SFF_RXD0")
	)
	(segment
		(start 442.089286 -15.6718)
		(end 440.436254 -15.6718)
		(width 0.11684)
		(layer "In6.Cu")
		(net "NCSI_OCP_SFF_RXD0")
	)
	(segment
		(start 447.80454 -13.462508)
		(end 447.496692 -13.770356)
		(width 0.11684)
		(layer "In6.Cu")
		(net "NCSI_OCP_SFF_RXD0")
	)
	(segment
		(start 334.756252 -20.736814)
		(end 333.023972 -22.469094)
		(width 0.11684)
		(layer "In6.Cu")
		(net "NCSI_OCP_SFF_RXD0")
	)
	(segment
		(start 446.96507 -15.437104)
		(end 442.323982 -15.437104)
		(width 0.11684)
		(layer "In6.Cu")
		(net "NCSI_OCP_SFF_RXD0")
	)
	(segment
		(start 440.436254 -15.6718)
		(end 439.165746 -16.942308)
		(width 0.11684)
		(layer "In6.Cu")
		(net "NCSI_OCP_SFF_RXD0")
	)
	(segment
		(start 224.554796 -74.530204)
		(end 215.236806 -74.530204)
		(width 0.11684)
		(layer "In6.Cu")
		(net "NCSI_OCP_SFF_RXD0")
	)
	(segment
		(start 333.023972 -22.469094)
		(end 328.551794 -22.469094)
		(width 0.11684)
		(layer "In6.Cu")
		(net "NCSI_OCP_SFF_RXD0")
	)
	(segment
		(start 202.63104 -74.046842)
		(end 201.478134 -75.199748)
		(width 0.11684)
		(layer "In6.Cu")
		(net "NCSI_OCP_SFF_RXD0")
	)
	(segment
		(start 447.496692 -14.905482)
		(end 446.96507 -15.437104)
		(width 0.11684)
		(layer "In6.Cu")
		(net "NCSI_OCP_SFF_RXD0")
	)
	(segment
		(start 254.46228 -70.688454)
		(end 240.591086 -70.688454)
		(width 0.11684)
		(layer "In6.Cu")
		(net "NCSI_OCP_SFF_RXD0")
	)
	(segment
		(start 215.236806 -74.530204)
		(end 214.753444 -74.046842)
		(width 0.11684)
		(layer "In6.Cu")
		(net "NCSI_OCP_SFF_RXD0")
	)
	(segment
		(start 303.329848 -40.31234)
		(end 294.10279 -40.31234)
		(width 0.11684)
		(layer "In6.Cu")
		(net "NCSI_OCP_SFF_RXD0")
	)
	(segment
		(start 271.208246 -63.206884)
		(end 265.80592 -63.206884)
		(width 0.11684)
		(layer "In6.Cu")
		(net "NCSI_OCP_SFF_RXD0")
	)
	(segment
		(start 240.154968 -71.124572)
		(end 227.960428 -71.124572)
		(width 0.11684)
		(layer "In6.Cu")
		(net "NCSI_OCP_SFF_RXD0")
	)
	(segment
		(start 265.80592 -63.206884)
		(end 258.85775 -70.155054)
		(width 0.11684)
		(layer "In6.Cu")
		(net "NCSI_OCP_SFF_RXD0")
	)
	(segment
		(start 374.26011 -18.795746)
		(end 351.59061 -18.795746)
		(width 0.11684)
		(layer "In6.Cu")
		(net "NCSI_OCP_SFF_RXD0")
	)
	(segment
		(start 254.99568 -70.155054)
		(end 254.46228 -70.688454)
		(width 0.11684)
		(layer "In6.Cu")
		(net "NCSI_OCP_SFF_RXD0")
	)
	(segment
		(start 349.649542 -20.736814)
		(end 334.756252 -20.736814)
		(width 0.11684)
		(layer "In6.Cu")
		(net "NCSI_OCP_SFF_RXD0")
	)
	(segment
		(start 444.761874 -11.26998)
		(end 444.761874 -9.922002)
		(width 0.10668)
		(layer "F.Cu")
		(net "NCSI_OCP_SFF_CRS_DV")
	)
	(via
		(at 195.52666 -75.242674)
		(size 0.508)
		(drill 0.254)
		(layers "F.Cu" "B.Cu")
		(net "NCSI_OCP_SFF_CRS_DV")
	)
	(via
		(at 444.761874 -9.922002)
		(size 0.508)
		(drill 0.254)
		(layers "F.Cu" "B.Cu")
		(net "NCSI_OCP_SFF_CRS_DV")
	)
	(segment
		(start 194.304158 -75.242674)
		(end 195.52666 -75.242674)
		(width 0.10668)
		(layer "B.Cu")
		(net "NCSI_OCP_SFF_CRS_DV")
	)
	(segment
		(start 327.8505 -20.776946)
		(end 332.322678 -20.776946)
		(width 0.11684)
		(layer "In6.Cu")
		(net "NCSI_OCP_SFF_CRS_DV")
	)
	(segment
		(start 434.216556 -13.562584)
		(end 435.0004 -12.77874)
		(width 0.11684)
		(layer "In6.Cu")
		(net "NCSI_OCP_SFF_CRS_DV")
	)
	(segment
		(start 195.85686 -74.032872)
		(end 196.577966 -74.032872)
		(width 0.11684)
		(layer "In6.Cu")
		(net "NCSI_OCP_SFF_CRS_DV")
	)
	(segment
		(start 377.107704 -13.562584)
		(end 434.216556 -13.562584)
		(width 0.11684)
		(layer "In6.Cu")
		(net "NCSI_OCP_SFF_CRS_DV")
	)
	(segment
		(start 220.152214 -65.913508)
		(end 220.458538 -66.219832)
		(width 0.11684)
		(layer "In6.Cu")
		(net "NCSI_OCP_SFF_CRS_DV")
	)
	(segment
		(start 323.389752 -25.237694)
		(end 327.8505 -20.776946)
		(width 0.11684)
		(layer "In6.Cu")
		(net "NCSI_OCP_SFF_CRS_DV")
	)
	(segment
		(start 253.46279 -66.418206)
		(end 253.855982 -66.811398)
		(width 0.11684)
		(layer "In6.Cu")
		(net "NCSI_OCP_SFF_CRS_DV")
	)
	(segment
		(start 207.160368 -65.913508)
		(end 220.152214 -65.913508)
		(width 0.11684)
		(layer "In6.Cu")
		(net "NCSI_OCP_SFF_CRS_DV")
	)
	(segment
		(start 442.231018 -8.5979)
		(end 443.55512 -9.922002)
		(width 0.11684)
		(layer "In6.Cu")
		(net "NCSI_OCP_SFF_CRS_DV")
	)
	(segment
		(start 205.99781 -68.206874)
		(end 205.99781 -67.076066)
		(width 0.11684)
		(layer "In6.Cu")
		(net "NCSI_OCP_SFF_CRS_DV")
	)
	(segment
		(start 316.98692 -38.615874)
		(end 317.84417 -37.758624)
		(width 0.11684)
		(layer "In6.Cu")
		(net "NCSI_OCP_SFF_CRS_DV")
	)
	(segment
		(start 332.322678 -20.776946)
		(end 334.054958 -19.044666)
		(width 0.11684)
		(layer "In6.Cu")
		(net "NCSI_OCP_SFF_CRS_DV")
	)
	(segment
		(start 247.195086 -66.219832)
		(end 247.73382 -66.758566)
		(width 0.11684)
		(layer "In6.Cu")
		(net "NCSI_OCP_SFF_CRS_DV")
	)
	(segment
		(start 201.019156 -69.591682)
		(end 204.613002 -69.591682)
		(width 0.11684)
		(layer "In6.Cu")
		(net "NCSI_OCP_SFF_CRS_DV")
	)
	(segment
		(start 348.510352 -19.044666)
		(end 350.445832 -17.109186)
		(width 0.11684)
		(layer "In6.Cu")
		(net "NCSI_OCP_SFF_CRS_DV")
	)
	(segment
		(start 247.73382 -66.758566)
		(end 251.350272 -66.758566)
		(width 0.11684)
		(layer "In6.Cu")
		(net "NCSI_OCP_SFF_CRS_DV")
	)
	(segment
		(start 204.613002 -69.591682)
		(end 205.99781 -68.206874)
		(width 0.11684)
		(layer "In6.Cu")
		(net "NCSI_OCP_SFF_CRS_DV")
	)
	(segment
		(start 205.99781 -67.076066)
		(end 207.160368 -65.913508)
		(width 0.11684)
		(layer "In6.Cu")
		(net "NCSI_OCP_SFF_CRS_DV")
	)
	(segment
		(start 196.577966 -74.032872)
		(end 201.019156 -69.591682)
		(width 0.11684)
		(layer "In6.Cu")
		(net "NCSI_OCP_SFF_CRS_DV")
	)
	(segment
		(start 265.068304 -61.520324)
		(end 270.509238 -61.520324)
		(width 0.11684)
		(layer "In6.Cu")
		(net "NCSI_OCP_SFF_CRS_DV")
	)
	(segment
		(start 321.252088 -31.461202)
		(end 322.734178 -31.461202)
		(width 0.11684)
		(layer "In6.Cu")
		(net "NCSI_OCP_SFF_CRS_DV")
	)
	(segment
		(start 251.350272 -66.758566)
		(end 251.690632 -66.418206)
		(width 0.11684)
		(layer "In6.Cu")
		(net "NCSI_OCP_SFF_CRS_DV")
	)
	(segment
		(start 270.509238 -61.520324)
		(end 293.413688 -38.615874)
		(width 0.11684)
		(layer "In6.Cu")
		(net "NCSI_OCP_SFF_CRS_DV")
	)
	(segment
		(start 195.52666 -75.242674)
		(end 195.52666 -74.363072)
		(width 0.11684)
		(layer "In6.Cu")
		(net "NCSI_OCP_SFF_CRS_DV")
	)
	(segment
		(start 253.855982 -66.811398)
		(end 259.77723 -66.811398)
		(width 0.11684)
		(layer "In6.Cu")
		(net "NCSI_OCP_SFF_CRS_DV")
	)
	(segment
		(start 220.458538 -66.219832)
		(end 247.195086 -66.219832)
		(width 0.11684)
		(layer "In6.Cu")
		(net "NCSI_OCP_SFF_CRS_DV")
	)
	(segment
		(start 435.0004 -11.811)
		(end 438.2135 -8.5979)
		(width 0.11684)
		(layer "In6.Cu")
		(net "NCSI_OCP_SFF_CRS_DV")
	)
	(segment
		(start 350.445832 -17.109186)
		(end 373.561102 -17.109186)
		(width 0.11684)
		(layer "In6.Cu")
		(net "NCSI_OCP_SFF_CRS_DV")
	)
	(segment
		(start 251.690632 -66.418206)
		(end 253.46279 -66.418206)
		(width 0.11684)
		(layer "In6.Cu")
		(net "NCSI_OCP_SFF_CRS_DV")
	)
	(segment
		(start 435.0004 -12.77874)
		(end 435.0004 -11.811)
		(width 0.11684)
		(layer "In6.Cu")
		(net "NCSI_OCP_SFF_CRS_DV")
	)
	(segment
		(start 443.55512 -9.922002)
		(end 444.761874 -9.922002)
		(width 0.11684)
		(layer "In6.Cu")
		(net "NCSI_OCP_SFF_CRS_DV")
	)
	(segment
		(start 195.52666 -74.363072)
		(end 195.85686 -74.032872)
		(width 0.11684)
		(layer "In6.Cu")
		(net "NCSI_OCP_SFF_CRS_DV")
	)
	(segment
		(start 293.413688 -38.615874)
		(end 316.98692 -38.615874)
		(width 0.11684)
		(layer "In6.Cu")
		(net "NCSI_OCP_SFF_CRS_DV")
	)
	(segment
		(start 323.389752 -30.805628)
		(end 323.389752 -25.237694)
		(width 0.11684)
		(layer "In6.Cu")
		(net "NCSI_OCP_SFF_CRS_DV")
	)
	(segment
		(start 259.77723 -66.811398)
		(end 265.068304 -61.520324)
		(width 0.11684)
		(layer "In6.Cu")
		(net "NCSI_OCP_SFF_CRS_DV")
	)
	(segment
		(start 322.734178 -31.461202)
		(end 323.389752 -30.805628)
		(width 0.11684)
		(layer "In6.Cu")
		(net "NCSI_OCP_SFF_CRS_DV")
	)
	(segment
		(start 317.84417 -37.758624)
		(end 317.84417 -34.86912)
		(width 0.11684)
		(layer "In6.Cu")
		(net "NCSI_OCP_SFF_CRS_DV")
	)
	(segment
		(start 334.054958 -19.044666)
		(end 348.510352 -19.044666)
		(width 0.11684)
		(layer "In6.Cu")
		(net "NCSI_OCP_SFF_CRS_DV")
	)
	(segment
		(start 317.84417 -34.86912)
		(end 321.252088 -31.461202)
		(width 0.11684)
		(layer "In6.Cu")
		(net "NCSI_OCP_SFF_CRS_DV")
	)
	(segment
		(start 373.561102 -17.109186)
		(end 377.107704 -13.562584)
		(width 0.11684)
		(layer "In6.Cu")
		(net "NCSI_OCP_SFF_CRS_DV")
	)
	(segment
		(start 438.2135 -8.5979)
		(end 442.231018 -8.5979)
		(width 0.11684)
		(layer "In6.Cu")
		(net "NCSI_OCP_SFF_CRS_DV")
	)
	(via
		(at 193.561208 -69.603112)
		(size 0.6604)
		(drill 0.3302)
		(layers "F.Cu" "B.Cu")
		(net "NCSI_BMC_TX_EN_R1")
	)
	(segment
		(start 193.561208 -69.603112)
		(end 192.552574 -69.603112)
		(width 0.10668)
		(layer "B.Cu")
		(net "NCSI_BMC_TX_EN_R1")
	)
	(segment
		(start 192.552574 -69.603112)
		(end 192.392808 -69.443346)
		(width 0.10668)
		(layer "B.Cu")
		(net "NCSI_BMC_TX_EN_R1")
	)
	(segment
		(start 195.55333 -69.603112)
		(end 193.561208 -69.603112)
		(width 0.10668)
		(layer "B.Cu")
		(net "NCSI_BMC_TX_EN_R1")
	)
	(via
		(at 206.0448 -68.230496)
		(size 0.6604)
		(drill 0.3302)
		(layers "F.Cu" "B.Cu")
		(net "NCSI_BMC_TX_EN_R")
	)
	(segment
		(start 207.91805 -68.230496)
		(end 206.0448 -68.230496)
		(width 0.10668)
		(layer "B.Cu")
		(net "NCSI_BMC_TX_EN_R")
	)
	(segment
		(start 206.0448 -68.230496)
		(end 206.044038 -68.229734)
		(width 0.10668)
		(layer "B.Cu")
		(net "NCSI_BMC_TX_EN_R")
	)
	(segment
		(start 206.044038 -68.229734)
		(end 204.838808 -68.229734)
		(width 0.10668)
		(layer "B.Cu")
		(net "NCSI_BMC_TX_EN_R")
	)
	(via
		(at 203.7842 -72.214994)
		(size 0.6604)
		(drill 0.3302)
		(layers "F.Cu" "B.Cu")
		(net "NCSI_BMC_TXD1_R1")
	)
	(segment
		(start 204.988922 -72.214994)
		(end 203.7842 -72.214994)
		(width 0.10668)
		(layer "B.Cu")
		(net "NCSI_BMC_TXD1_R1")
	)
	(segment
		(start 203.772262 -72.203056)
		(end 201.39533 -72.203056)
		(width 0.10668)
		(layer "B.Cu")
		(net "NCSI_BMC_TXD1_R1")
	)
	(segment
		(start 203.7842 -72.214994)
		(end 203.772262 -72.203056)
		(width 0.10668)
		(layer "B.Cu")
		(net "NCSI_BMC_TXD1_R1")
	)
	(via
		(at 215.800432 -71.724774)
		(size 0.6604)
		(drill 0.3302)
		(layers "F.Cu" "B.Cu")
		(net "NCSI_BMC_TXD1_R")
	)
	(segment
		(start 215.800432 -71.724774)
		(end 215.921336 -71.845678)
		(width 0.10668)
		(layer "B.Cu")
		(net "NCSI_BMC_TXD1_R")
	)
	(segment
		(start 215.921336 -71.845678)
		(end 215.921336 -73.050908)
		(width 0.10668)
		(layer "B.Cu")
		(net "NCSI_BMC_TXD1_R")
	)
	(segment
		(start 215.800432 -71.430134)
		(end 215.800432 -71.724774)
		(width 0.10668)
		(layer "B.Cu")
		(net "NCSI_BMC_TXD1_R")
	)
	(segment
		(start 213.76005 -70.83044)
		(end 215.200738 -70.83044)
		(width 0.10668)
		(layer "B.Cu")
		(net "NCSI_BMC_TXD1_R")
	)
	(segment
		(start 215.200738 -70.83044)
		(end 215.800432 -71.430134)
		(width 0.10668)
		(layer "B.Cu")
		(net "NCSI_BMC_TXD1_R")
	)
	(via
		(at 203.814934 -69.930518)
		(size 0.6604)
		(drill 0.3302)
		(layers "F.Cu" "B.Cu")
		(net "NCSI_BMC_TXD0_R1")
	)
	(segment
		(start 203.814934 -69.930518)
		(end 204.593444 -69.930518)
		(width 0.10668)
		(layer "B.Cu")
		(net "NCSI_BMC_TXD0_R1")
	)
	(segment
		(start 203.492354 -70.253098)
		(end 203.814934 -69.930518)
		(width 0.10668)
		(layer "B.Cu")
		(net "NCSI_BMC_TXD0_R1")
	)
	(segment
		(start 204.593444 -69.930518)
		(end 204.975206 -70.31228)
		(width 0.10668)
		(layer "B.Cu")
		(net "NCSI_BMC_TXD0_R1")
	)
	(segment
		(start 201.39533 -70.253098)
		(end 203.492354 -70.253098)
		(width 0.10668)
		(layer "B.Cu")
		(net "NCSI_BMC_TXD0_R1")
	)
	(via
		(at 215.983312 -69.483478)
		(size 0.6604)
		(drill 0.3302)
		(layers "F.Cu" "B.Cu")
		(net "NCSI_BMC_TXD0_R")
	)
	(segment
		(start 214.947754 -68.880482)
		(end 215.55075 -69.483478)
		(width 0.10668)
		(layer "B.Cu")
		(net "NCSI_BMC_TXD0_R")
	)
	(segment
		(start 213.76005 -68.880482)
		(end 214.947754 -68.880482)
		(width 0.10668)
		(layer "B.Cu")
		(net "NCSI_BMC_TXD0_R")
	)
	(segment
		(start 217.151712 -69.483478)
		(end 215.983312 -69.483478)
		(width 0.10668)
		(layer "B.Cu")
		(net "NCSI_BMC_TXD0_R")
	)
	(segment
		(start 215.55075 -69.483478)
		(end 215.983312 -69.483478)
		(width 0.10668)
		(layer "B.Cu")
		(net "NCSI_BMC_TXD0_R")
	)
	(via
		(at 214.004906 -78.563724)
		(size 0.6604)
		(drill 0.3302)
		(layers "F.Cu" "B.Cu")
		(net "NCSI_BMC_RXD1_R1")
	)
	(segment
		(start 212.216746 -78.563724)
		(end 214.004906 -78.563724)
		(width 0.10668)
		(layer "B.Cu")
		(net "NCSI_BMC_RXD1_R1")
	)
	(segment
		(start 214.004906 -78.563724)
		(end 215.737694 -78.563724)
		(width 0.10668)
		(layer "B.Cu")
		(net "NCSI_BMC_RXD1_R1")
	)
	(segment
		(start 215.737694 -78.563724)
		(end 215.85301 -78.448408)
		(width 0.10668)
		(layer "B.Cu")
		(net "NCSI_BMC_RXD1_R1")
	)
	(segment
		(start 200.435718 -78.42377)
		(end 200.504552 -78.492604)
		(width 0.10668)
		(layer "F.Cu")
		(net "NCSI_BMC_RXD1_R")
	)
	(segment
		(start 200.504552 -78.492604)
		(end 201.649838 -78.492604)
		(width 0.10668)
		(layer "F.Cu")
		(net "NCSI_BMC_RXD1_R")
	)
	(via
		(at 201.649838 -78.492604)
		(size 0.762)
		(drill 0.254)
		(layers "F.Cu" "B.Cu")
		(net "NCSI_BMC_RXD1_R")
	)
	(segment
		(start 201.649838 -78.492604)
		(end 200.146158 -78.492604)
		(width 0.10668)
		(layer "B.Cu")
		(net "NCSI_BMC_RXD1_R")
	)
	(via
		(at 214.004906 -76.613766)
		(size 0.6604)
		(drill 0.3302)
		(layers "F.Cu" "B.Cu")
		(net "NCSI_BMC_RXD0_R1")
	)
	(segment
		(start 214.004906 -76.613766)
		(end 215.790526 -76.613766)
		(width 0.10668)
		(layer "B.Cu")
		(net "NCSI_BMC_RXD0_R1")
	)
	(segment
		(start 215.790526 -76.613766)
		(end 215.812624 -76.591668)
		(width 0.10668)
		(layer "B.Cu")
		(net "NCSI_BMC_RXD0_R1")
	)
	(segment
		(start 212.216746 -76.613766)
		(end 214.004906 -76.613766)
		(width 0.10668)
		(layer "B.Cu")
		(net "NCSI_BMC_RXD0_R1")
	)
	(segment
		(start 200.924922 -76.598526)
		(end 201.690732 -76.598526)
		(width 0.10668)
		(layer "F.Cu")
		(net "NCSI_BMC_RXD0_R")
	)
	(segment
		(start 200.457308 -77.06614)
		(end 200.924922 -76.598526)
		(width 0.10668)
		(layer "F.Cu")
		(net "NCSI_BMC_RXD0_R")
	)
	(via
		(at 201.690732 -76.598526)
		(size 0.762)
		(drill 0.254)
		(layers "F.Cu" "B.Cu")
		(net "NCSI_BMC_RXD0_R")
	)
	(segment
		(start 200.146158 -76.542646)
		(end 201.634852 -76.542646)
		(width 0.10668)
		(layer "B.Cu")
		(net "NCSI_BMC_RXD0_R")
	)
	(segment
		(start 201.634852 -76.542646)
		(end 201.690732 -76.598526)
		(width 0.10668)
		(layer "B.Cu")
		(net "NCSI_BMC_RXD0_R")
	)
	(via
		(at 204.599286 -75.9079)
		(size 0.6604)
		(drill 0.3302)
		(layers "F.Cu" "B.Cu")
		(net "NCSI_BMC_CRS_DV_R1")
	)
	(segment
		(start 204.347318 -75.053952)
		(end 203.47305 -75.053952)
		(width 0.10668)
		(layer "B.Cu")
		(net "NCSI_BMC_CRS_DV_R1")
	)
	(segment
		(start 206.374746 -75.96378)
		(end 206.318866 -75.9079)
		(width 0.10668)
		(layer "B.Cu")
		(net "NCSI_BMC_CRS_DV_R1")
	)
	(segment
		(start 206.318866 -75.9079)
		(end 204.599286 -75.9079)
		(width 0.10668)
		(layer "B.Cu")
		(net "NCSI_BMC_CRS_DV_R1")
	)
	(segment
		(start 204.599286 -75.9079)
		(end 204.599286 -75.30592)
		(width 0.10668)
		(layer "B.Cu")
		(net "NCSI_BMC_CRS_DV_R1")
	)
	(segment
		(start 204.599286 -75.30592)
		(end 204.347318 -75.053952)
		(width 0.10668)
		(layer "B.Cu")
		(net "NCSI_BMC_CRS_DV_R1")
	)
	(segment
		(start 192.70472 -75.89266)
		(end 193.847466 -75.89266)
		(width 0.10668)
		(layer "F.Cu")
		(net "NCSI_BMC_CRS_DV_R")
	)
	(segment
		(start 192.66154 -75.84948)
		(end 192.70472 -75.89266)
		(width 0.10668)
		(layer "F.Cu")
		(net "NCSI_BMC_CRS_DV_R")
	)
	(segment
		(start 193.847466 -75.89266)
		(end 193.971672 -76.016866)
		(width 0.10668)
		(layer "F.Cu")
		(net "NCSI_BMC_CRS_DV_R")
	)
	(via
		(at 192.66154 -75.84948)
		(size 0.508)
		(drill 0.254)
		(layers "F.Cu" "B.Cu")
		(net "NCSI_BMC_CRS_DV_R")
	)
	(segment
		(start 194.304158 -75.89266)
		(end 192.70472 -75.89266)
		(width 0.10668)
		(layer "B.Cu")
		(net "NCSI_BMC_CRS_DV_R")
	)
	(segment
		(start 192.70472 -75.89266)
		(end 192.66154 -75.84948)
		(width 0.10668)
		(layer "B.Cu")
		(net "NCSI_BMC_CRS_DV_R")
	)
	(segment
		(start 139.337796 -267.340334)
		(end 139.804648 -267.606272)
		(width 0.10668)
		(layer "F.Cu")
		(net "M_L_CPU1_SB_RSP<0>")
	)
	(segment
		(start 145.69694 -267.874496)
		(end 145.750026 -267.82141)
		(width 0.0889)
		(layer "In11.Cu")
		(net "M_L_CPU1_SB_RSP<0>")
	)
	(segment
		(start 174.543974 -270.010382)
		(end 177.72634 -270.010382)
		(width 0.11684)
		(layer "In11.Cu")
		(net "M_L_CPU1_SB_RSP<0>")
	)
	(segment
		(start 147.649438 -266.570714)
		(end 147.948904 -266.570714)
		(width 0.0889)
		(layer "In11.Cu")
		(net "M_L_CPU1_SB_RSP<0>")
	)
	(segment
		(start 142.803372 -267.933678)
		(end 142.811754 -267.928852)
		(width 0.0889)
		(layer "In11.Cu")
		(net "M_L_CPU1_SB_RSP<0>")
	)
	(segment
		(start 145.803366 -267.692632)
		(end 145.803366 -266.96289)
		(width 0.0889)
		(layer "In11.Cu")
		(net "M_L_CPU1_SB_RSP<0>")
	)
	(segment
		(start 189.632082 -270.010382)
		(end 205.823058 -270.010382)
		(width 0.11684)
		(layer "In11.Cu")
		(net "M_L_CPU1_SB_RSP<0>")
	)
	(segment
		(start 185.270394 -270.010382)
		(end 186.120532 -270.86052)
		(width 0.11684)
		(layer "In11.Cu")
		(net "M_L_CPU1_SB_RSP<0>")
	)
	(segment
		(start 178.576478 -270.86052)
		(end 181.23789 -270.86052)
		(width 0.11684)
		(layer "In11.Cu")
		(net "M_L_CPU1_SB_RSP<0>")
	)
	(segment
		(start 144.317466 -267.928852)
		(end 144.331944 -267.937234)
		(width 0.0889)
		(layer "In11.Cu")
		(net "M_L_CPU1_SB_RSP<0>")
	)
	(segment
		(start 143.377666 -267.928852)
		(end 143.386048 -267.933678)
		(width 0.0889)
		(layer "In11.Cu")
		(net "M_L_CPU1_SB_RSP<0>")
	)
	(segment
		(start 181.23789 -270.86052)
		(end 182.088028 -270.010382)
		(width 0.11684)
		(layer "In11.Cu")
		(net "M_L_CPU1_SB_RSP<0>")
	)
	(segment
		(start 140.557758 -267.928852)
		(end 140.56614 -267.933678)
		(width 0.0889)
		(layer "In11.Cu")
		(net "M_L_CPU1_SB_RSP<0>")
	)
	(segment
		(start 144.307052 -267.922756)
		(end 144.317466 -267.928852)
		(width 0.0889)
		(layer "In11.Cu")
		(net "M_L_CPU1_SB_RSP<0>")
	)
	(segment
		(start 163.654994 -270.86052)
		(end 173.693836 -270.86052)
		(width 0.11684)
		(layer "In11.Cu")
		(net "M_L_CPU1_SB_RSP<0>")
	)
	(segment
		(start 145.803366 -266.96289)
		(end 146.59737 -266.168886)
		(width 0.0889)
		(layer "In11.Cu")
		(net "M_L_CPU1_SB_RSP<0>")
	)
	(segment
		(start 146.59737 -266.168886)
		(end 147.24761 -266.168886)
		(width 0.0889)
		(layer "In11.Cu")
		(net "M_L_CPU1_SB_RSP<0>")
	)
	(segment
		(start 186.120532 -270.86052)
		(end 188.781944 -270.86052)
		(width 0.11684)
		(layer "In11.Cu")
		(net "M_L_CPU1_SB_RSP<0>")
	)
	(segment
		(start 182.088028 -270.010382)
		(end 185.270394 -270.010382)
		(width 0.11684)
		(layer "In11.Cu")
		(net "M_L_CPU1_SB_RSP<0>")
	)
	(segment
		(start 159.365188 -266.570714)
		(end 163.654994 -270.86052)
		(width 0.11684)
		(layer "In11.Cu")
		(net "M_L_CPU1_SB_RSP<0>")
	)
	(segment
		(start 147.24761 -266.168886)
		(end 147.649438 -266.570714)
		(width 0.0889)
		(layer "In11.Cu")
		(net "M_L_CPU1_SB_RSP<0>")
	)
	(segment
		(start 188.781944 -270.86052)
		(end 189.632082 -270.010382)
		(width 0.11684)
		(layer "In11.Cu")
		(net "M_L_CPU1_SB_RSP<0>")
	)
	(segment
		(start 173.693836 -270.86052)
		(end 174.543974 -270.010382)
		(width 0.11684)
		(layer "In11.Cu")
		(net "M_L_CPU1_SB_RSP<0>")
	)
	(segment
		(start 147.948904 -266.570714)
		(end 159.365188 -266.570714)
		(width 0.11684)
		(layer "In11.Cu")
		(net "M_L_CPU1_SB_RSP<0>")
	)
	(segment
		(start 139.650724 -267.871702)
		(end 139.673076 -267.955014)
		(width 0.0889)
		(layer "In11.Cu")
		(net "M_L_CPU1_SB_RSP<0>")
	)
	(segment
		(start 139.804648 -267.606272)
		(end 139.650724 -267.871702)
		(width 0.0889)
		(layer "In11.Cu")
		(net "M_L_CPU1_SB_RSP<0>")
	)
	(segment
		(start 177.72634 -270.010382)
		(end 178.576478 -270.86052)
		(width 0.11684)
		(layer "In11.Cu")
		(net "M_L_CPU1_SB_RSP<0>")
	)
	(segment
		(start 205.823058 -270.010382)
		(end 206.248 -270.435324)
		(width 0.11684)
		(layer "In11.Cu")
		(net "M_L_CPU1_SB_RSP<0>")
	)
	(arc
		(start 143.386048 -267.933678)
		(mid 143.569556 -267.979172)
		(end 143.751808 -267.928852)
		(width 0.0889)
		(layer "In11.Cu")
		(net "M_L_CPU1_SB_RSP<0>")
	)
	(arc
		(start 143.751808 -267.928852)
		(mid 144.028621 -267.852709)
		(end 144.307052 -267.922756)
		(width 0.0889)
		(layer "In11.Cu")
		(net "M_L_CPU1_SB_RSP<0>")
	)
	(arc
		(start 145.750026 -267.82141)
		(mid 145.789505 -267.762326)
		(end 145.803366 -267.692632)
		(width 0.0889)
		(layer "In11.Cu")
		(net "M_L_CPU1_SB_RSP<0>")
	)
	(arc
		(start 141.497812 -267.928852)
		(mid 141.684756 -267.979107)
		(end 141.8717 -267.928852)
		(width 0.0889)
		(layer "In11.Cu")
		(net "M_L_CPU1_SB_RSP<0>")
	)
	(arc
		(start 144.331944 -267.937234)
		(mid 144.512852 -267.979256)
		(end 144.691608 -267.928852)
		(width 0.0889)
		(layer "In11.Cu")
		(net "M_L_CPU1_SB_RSP<0>")
	)
	(arc
		(start 139.673076 -267.955014)
		(mid 139.835408 -267.977832)
		(end 139.991846 -267.928852)
		(width 0.0889)
		(layer "In11.Cu")
		(net "M_L_CPU1_SB_RSP<0>")
	)
	(arc
		(start 145.444718 -267.979144)
		(mid 145.581233 -267.951896)
		(end 145.69694 -267.874496)
		(width 0.0889)
		(layer "In11.Cu")
		(net "M_L_CPU1_SB_RSP<0>")
	)
	(arc
		(start 140.9319 -267.928852)
		(mid 141.214856 -267.852675)
		(end 141.497812 -267.928852)
		(width 0.0889)
		(layer "In11.Cu")
		(net "M_L_CPU1_SB_RSP<0>")
	)
	(arc
		(start 140.56614 -267.933678)
		(mid 140.749648 -267.979172)
		(end 140.9319 -267.928852)
		(width 0.0889)
		(layer "In11.Cu")
		(net "M_L_CPU1_SB_RSP<0>")
	)
	(arc
		(start 139.991846 -267.928852)
		(mid 140.274802 -267.852675)
		(end 140.557758 -267.928852)
		(width 0.0889)
		(layer "In11.Cu")
		(net "M_L_CPU1_SB_RSP<0>")
	)
	(arc
		(start 142.437612 -267.928852)
		(mid 142.619863 -267.979202)
		(end 142.803372 -267.933678)
		(width 0.0889)
		(layer "In11.Cu")
		(net "M_L_CPU1_SB_RSP<0>")
	)
	(arc
		(start 145.24736 -267.922756)
		(mid 145.342084 -267.964784)
		(end 145.444718 -267.979144)
		(width 0.0889)
		(layer "In11.Cu")
		(net "M_L_CPU1_SB_RSP<0>")
	)
	(arc
		(start 141.8717 -267.928852)
		(mid 142.154656 -267.852675)
		(end 142.437612 -267.928852)
		(width 0.0889)
		(layer "In11.Cu")
		(net "M_L_CPU1_SB_RSP<0>")
	)
	(arc
		(start 144.691608 -267.928852)
		(mid 144.968675 -267.852581)
		(end 145.24736 -267.922756)
		(width 0.0889)
		(layer "In11.Cu")
		(net "M_L_CPU1_SB_RSP<0>")
	)
	(arc
		(start 142.811754 -267.928852)
		(mid 143.09471 -267.852675)
		(end 143.377666 -267.928852)
		(width 0.0889)
		(layer "In11.Cu")
		(net "M_L_CPU1_SB_RSP<0>")
	)
	(segment
		(start 137.927842 -264.910316)
		(end 138.394694 -265.176254)
		(width 0.10668)
		(layer "F.Cu")
		(net "M_L_CPU1_SB_PAR")
	)
	(segment
		(start 174.543974 -266.610338)
		(end 177.72634 -266.610338)
		(width 0.14478)
		(layer "In11.Cu")
		(net "M_L_CPU1_SB_PAR")
	)
	(segment
		(start 189.632082 -266.610338)
		(end 199.53097 -266.610338)
		(width 0.14478)
		(layer "In11.Cu")
		(net "M_L_CPU1_SB_PAR")
	)
	(segment
		(start 199.67575 -266.755118)
		(end 199.67575 -266.852146)
		(width 0.14478)
		(layer "In11.Cu")
		(net "M_L_CPU1_SB_PAR")
	)
	(segment
		(start 199.53097 -266.610338)
		(end 199.67575 -266.755118)
		(width 0.14478)
		(layer "In11.Cu")
		(net "M_L_CPU1_SB_PAR")
	)
	(segment
		(start 182.088028 -266.610338)
		(end 185.270394 -266.610338)
		(width 0.14478)
		(layer "In11.Cu")
		(net "M_L_CPU1_SB_PAR")
	)
	(segment
		(start 177.72634 -266.610338)
		(end 178.576478 -267.460476)
		(width 0.14478)
		(layer "In11.Cu")
		(net "M_L_CPU1_SB_PAR")
	)
	(segment
		(start 160.988502 -264.793984)
		(end 163.654994 -267.460476)
		(width 0.14478)
		(layer "In11.Cu")
		(net "M_L_CPU1_SB_PAR")
	)
	(segment
		(start 147.46097 -264.540746)
		(end 147.714208 -264.793984)
		(width 0.0889)
		(layer "In11.Cu")
		(net "M_L_CPU1_SB_PAR")
	)
	(segment
		(start 138.394694 -265.176254)
		(end 138.24077 -265.441684)
		(width 0.0889)
		(layer "In11.Cu")
		(net "M_L_CPU1_SB_PAR")
	)
	(segment
		(start 144.766538 -265.485118)
		(end 144.789906 -265.498834)
		(width 0.0889)
		(layer "In11.Cu")
		(net "M_L_CPU1_SB_PAR")
	)
	(segment
		(start 200.227184 -266.755118)
		(end 200.371964 -266.610338)
		(width 0.14478)
		(layer "In11.Cu")
		(net "M_L_CPU1_SB_PAR")
	)
	(segment
		(start 147.714208 -264.793984)
		(end 148.017484 -264.793984)
		(width 0.0889)
		(layer "In11.Cu")
		(net "M_L_CPU1_SB_PAR")
	)
	(segment
		(start 199.67575 -266.852146)
		(end 199.82053 -266.996926)
		(width 0.14478)
		(layer "In11.Cu")
		(net "M_L_CPU1_SB_PAR")
	)
	(segment
		(start 200.633838 -266.610338)
		(end 200.778618 -266.755118)
		(width 0.14478)
		(layer "In11.Cu")
		(net "M_L_CPU1_SB_PAR")
	)
	(segment
		(start 148.017484 -264.793984)
		(end 160.988502 -264.793984)
		(width 0.14478)
		(layer "In11.Cu")
		(net "M_L_CPU1_SB_PAR")
	)
	(segment
		(start 143.847566 -265.498834)
		(end 143.862044 -265.507216)
		(width 0.0889)
		(layer "In11.Cu")
		(net "M_L_CPU1_SB_PAR")
	)
	(segment
		(start 201.330052 -266.852146)
		(end 201.330052 -266.755118)
		(width 0.14478)
		(layer "In11.Cu")
		(net "M_L_CPU1_SB_PAR")
	)
	(segment
		(start 201.474832 -266.610338)
		(end 202.003152 -266.610338)
		(width 0.14478)
		(layer "In11.Cu")
		(net "M_L_CPU1_SB_PAR")
	)
	(segment
		(start 201.330052 -266.755118)
		(end 201.474832 -266.610338)
		(width 0.14478)
		(layer "In11.Cu")
		(net "M_L_CPU1_SB_PAR")
	)
	(segment
		(start 145.685256 -265.423142)
		(end 146.567652 -264.540746)
		(width 0.0889)
		(layer "In11.Cu")
		(net "M_L_CPU1_SB_PAR")
	)
	(segment
		(start 199.82053 -266.996926)
		(end 200.082404 -266.996926)
		(width 0.14478)
		(layer "In11.Cu")
		(net "M_L_CPU1_SB_PAR")
	)
	(segment
		(start 202.147932 -266.755118)
		(end 202.147932 -267.03528)
		(width 0.14478)
		(layer "In11.Cu")
		(net "M_L_CPU1_SB_PAR")
	)
	(segment
		(start 140.453364 -265.50366)
		(end 140.461746 -265.498834)
		(width 0.0889)
		(layer "In11.Cu")
		(net "M_L_CPU1_SB_PAR")
	)
	(segment
		(start 200.227184 -266.852146)
		(end 200.227184 -266.755118)
		(width 0.14478)
		(layer "In11.Cu")
		(net "M_L_CPU1_SB_PAR")
	)
	(segment
		(start 146.567652 -264.540746)
		(end 147.46097 -264.540746)
		(width 0.0889)
		(layer "In11.Cu")
		(net "M_L_CPU1_SB_PAR")
	)
	(segment
		(start 145.14322 -265.51001)
		(end 145.163286 -265.49858)
		(width 0.0889)
		(layer "In11.Cu")
		(net "M_L_CPU1_SB_PAR")
	)
	(segment
		(start 200.923398 -266.996926)
		(end 201.185272 -266.996926)
		(width 0.14478)
		(layer "In11.Cu")
		(net "M_L_CPU1_SB_PAR")
	)
	(segment
		(start 200.082404 -266.996926)
		(end 200.227184 -266.852146)
		(width 0.14478)
		(layer "In11.Cu")
		(net "M_L_CPU1_SB_PAR")
	)
	(segment
		(start 163.654994 -267.460476)
		(end 173.693836 -267.460476)
		(width 0.14478)
		(layer "In11.Cu")
		(net "M_L_CPU1_SB_PAR")
	)
	(segment
		(start 173.693836 -267.460476)
		(end 174.543974 -266.610338)
		(width 0.14478)
		(layer "In11.Cu")
		(net "M_L_CPU1_SB_PAR")
	)
	(segment
		(start 200.371964 -266.610338)
		(end 200.633838 -266.610338)
		(width 0.14478)
		(layer "In11.Cu")
		(net "M_L_CPU1_SB_PAR")
	)
	(segment
		(start 141.393418 -265.50366)
		(end 141.4018 -265.498834)
		(width 0.0889)
		(layer "In11.Cu")
		(net "M_L_CPU1_SB_PAR")
	)
	(segment
		(start 178.576478 -267.460476)
		(end 181.23789 -267.460476)
		(width 0.14478)
		(layer "In11.Cu")
		(net "M_L_CPU1_SB_PAR")
	)
	(segment
		(start 141.967712 -265.498834)
		(end 141.976094 -265.50366)
		(width 0.0889)
		(layer "In11.Cu")
		(net "M_L_CPU1_SB_PAR")
	)
	(segment
		(start 138.24077 -265.441684)
		(end 138.263122 -265.524996)
		(width 0.0889)
		(layer "In11.Cu")
		(net "M_L_CPU1_SB_PAR")
	)
	(segment
		(start 186.120532 -267.460476)
		(end 188.781944 -267.460476)
		(width 0.14478)
		(layer "In11.Cu")
		(net "M_L_CPU1_SB_PAR")
	)
	(segment
		(start 200.778618 -266.755118)
		(end 200.778618 -266.852146)
		(width 0.14478)
		(layer "In11.Cu")
		(net "M_L_CPU1_SB_PAR")
	)
	(segment
		(start 181.23789 -267.460476)
		(end 182.088028 -266.610338)
		(width 0.14478)
		(layer "In11.Cu")
		(net "M_L_CPU1_SB_PAR")
	)
	(segment
		(start 200.778618 -266.852146)
		(end 200.923398 -266.996926)
		(width 0.14478)
		(layer "In11.Cu")
		(net "M_L_CPU1_SB_PAR")
	)
	(segment
		(start 202.003152 -266.610338)
		(end 202.147932 -266.755118)
		(width 0.14478)
		(layer "In11.Cu")
		(net "M_L_CPU1_SB_PAR")
	)
	(segment
		(start 201.185272 -266.996926)
		(end 201.330052 -266.852146)
		(width 0.14478)
		(layer "In11.Cu")
		(net "M_L_CPU1_SB_PAR")
	)
	(segment
		(start 145.444464 -265.423142)
		(end 145.685256 -265.423142)
		(width 0.0889)
		(layer "In11.Cu")
		(net "M_L_CPU1_SB_PAR")
	)
	(segment
		(start 188.781944 -267.460476)
		(end 189.632082 -266.610338)
		(width 0.14478)
		(layer "In11.Cu")
		(net "M_L_CPU1_SB_PAR")
	)
	(segment
		(start 185.270394 -266.610338)
		(end 186.120532 -267.460476)
		(width 0.14478)
		(layer "In11.Cu")
		(net "M_L_CPU1_SB_PAR")
	)
	(arc
		(start 139.521692 -265.498834)
		(mid 139.804648 -265.422657)
		(end 140.087604 -265.498834)
		(width 0.0889)
		(layer "In11.Cu")
		(net "M_L_CPU1_SB_PAR")
	)
	(arc
		(start 140.087604 -265.498834)
		(mid 140.269855 -265.549184)
		(end 140.453364 -265.50366)
		(width 0.0889)
		(layer "In11.Cu")
		(net "M_L_CPU1_SB_PAR")
	)
	(arc
		(start 144.789906 -265.498834)
		(mid 144.965145 -265.548905)
		(end 145.14322 -265.51001)
		(width 0.0889)
		(layer "In11.Cu")
		(net "M_L_CPU1_SB_PAR")
	)
	(arc
		(start 141.027658 -265.498834)
		(mid 141.209909 -265.549184)
		(end 141.393418 -265.50366)
		(width 0.0889)
		(layer "In11.Cu")
		(net "M_L_CPU1_SB_PAR")
	)
	(arc
		(start 144.222724 -265.498834)
		(mid 144.492881 -265.422072)
		(end 144.766538 -265.485118)
		(width 0.0889)
		(layer "In11.Cu")
		(net "M_L_CPU1_SB_PAR")
	)
	(arc
		(start 140.461746 -265.498834)
		(mid 140.744702 -265.422657)
		(end 141.027658 -265.498834)
		(width 0.0889)
		(layer "In11.Cu")
		(net "M_L_CPU1_SB_PAR")
	)
	(arc
		(start 143.281654 -265.498834)
		(mid 143.56461 -265.422657)
		(end 143.847566 -265.498834)
		(width 0.0889)
		(layer "In11.Cu")
		(net "M_L_CPU1_SB_PAR")
	)
	(arc
		(start 138.263122 -265.524996)
		(mid 138.425454 -265.547814)
		(end 138.581892 -265.498834)
		(width 0.0889)
		(layer "In11.Cu")
		(net "M_L_CPU1_SB_PAR")
	)
	(arc
		(start 141.976094 -265.50366)
		(mid 142.159602 -265.549154)
		(end 142.341854 -265.498834)
		(width 0.0889)
		(layer "In11.Cu")
		(net "M_L_CPU1_SB_PAR")
	)
	(arc
		(start 142.907766 -265.498834)
		(mid 143.09471 -265.549089)
		(end 143.281654 -265.498834)
		(width 0.0889)
		(layer "In11.Cu")
		(net "M_L_CPU1_SB_PAR")
	)
	(arc
		(start 138.581892 -265.498834)
		(mid 138.864848 -265.422657)
		(end 139.147804 -265.498834)
		(width 0.0889)
		(layer "In11.Cu")
		(net "M_L_CPU1_SB_PAR")
	)
	(arc
		(start 142.341854 -265.498834)
		(mid 142.62481 -265.422657)
		(end 142.907766 -265.498834)
		(width 0.0889)
		(layer "In11.Cu")
		(net "M_L_CPU1_SB_PAR")
	)
	(arc
		(start 141.4018 -265.498834)
		(mid 141.684756 -265.422657)
		(end 141.967712 -265.498834)
		(width 0.0889)
		(layer "In11.Cu")
		(net "M_L_CPU1_SB_PAR")
	)
	(arc
		(start 143.862044 -265.507216)
		(mid 144.04346 -265.549473)
		(end 144.222724 -265.498834)
		(width 0.0889)
		(layer "In11.Cu")
		(net "M_L_CPU1_SB_PAR")
	)
	(arc
		(start 139.147804 -265.498834)
		(mid 139.334748 -265.549089)
		(end 139.521692 -265.498834)
		(width 0.0889)
		(layer "In11.Cu")
		(net "M_L_CPU1_SB_PAR")
	)
	(arc
		(start 145.163286 -265.49858)
		(mid 145.298919 -265.442405)
		(end 145.444464 -265.423142)
		(width 0.0889)
		(layer "In11.Cu")
		(net "M_L_CPU1_SB_PAR")
	)
	(segment
		(start 139.337796 -270.580358)
		(end 139.804648 -270.846296)
		(width 0.12954)
		(layer "F.Cu")
		(net "M_L_CPU1_SB_DQS_DP<9>")
	)
	(segment
		(start 147.895564 -269.252954)
		(end 147.919186 -269.252954)
		(width 0.09525)
		(layer "In11.Cu")
		(net "M_L_CPU1_SB_DQS_DP<9>")
	)
	(segment
		(start 140.556234 -271.171416)
		(end 140.564616 -271.176242)
		(width 0.09525)
		(layer "In11.Cu")
		(net "M_L_CPU1_SB_DQS_DP<9>")
	)
	(segment
		(start 146.714718 -269.216378)
		(end 147.457922 -269.216378)
		(width 0.09525)
		(layer "In11.Cu")
		(net "M_L_CPU1_SB_DQS_DP<9>")
	)
	(segment
		(start 204.68336 -275.809202)
		(end 204.81036 -275.682202)
		(width 0.16002)
		(layer "In11.Cu")
		(net "M_L_CPU1_SB_DQS_DP<9>")
	)
	(segment
		(start 189.512956 -275.164804)
		(end 189.924436 -275.164804)
		(width 0.16002)
		(layer "In11.Cu")
		(net "M_L_CPU1_SB_DQS_DP<9>")
	)
	(segment
		(start 203.347066 -276.003004)
		(end 203.761594 -276.003004)
		(width 0.16002)
		(layer "In11.Cu")
		(net "M_L_CPU1_SB_DQS_DP<9>")
	)
	(segment
		(start 177.100484 -274.81022)
		(end 177.950368 -275.660104)
		(width 0.16002)
		(layer "In11.Cu")
		(net "M_L_CPU1_SB_DQS_DP<9>")
	)
	(segment
		(start 200.306686 -275.38426)
		(end 202.728322 -275.38426)
		(width 0.16002)
		(layer "In11.Cu")
		(net "M_L_CPU1_SB_DQS_DP<9>")
	)
	(segment
		(start 174.424848 -275.164804)
		(end 174.836328 -275.164804)
		(width 0.16002)
		(layer "In11.Cu")
		(net "M_L_CPU1_SB_DQS_DP<9>")
	)
	(segment
		(start 180.422042 -275.987764)
		(end 181.145942 -275.987764)
		(width 0.16002)
		(layer "In11.Cu")
		(net "M_L_CPU1_SB_DQS_DP<9>")
	)
	(segment
		(start 143.376142 -271.171416)
		(end 143.384524 -271.176242)
		(width 0.09525)
		(layer "In11.Cu")
		(net "M_L_CPU1_SB_DQS_DP<9>")
	)
	(segment
		(start 205.29042 -275.682202)
		(end 205.41742 -275.809202)
		(width 0.16002)
		(layer "In11.Cu")
		(net "M_L_CPU1_SB_DQS_DP<9>")
	)
	(segment
		(start 182.734966 -274.81022)
		(end 184.644538 -274.81022)
		(width 0.16002)
		(layer "In11.Cu")
		(net "M_L_CPU1_SB_DQS_DP<9>")
	)
	(segment
		(start 202.728322 -275.38426)
		(end 203.347066 -276.003004)
		(width 0.16002)
		(layer "In11.Cu")
		(net "M_L_CPU1_SB_DQS_DP<9>")
	)
	(segment
		(start 196.23405 -275.987764)
		(end 197.05701 -275.164804)
		(width 0.16002)
		(layer "In11.Cu")
		(net "M_L_CPU1_SB_DQS_DP<9>")
	)
	(segment
		(start 164.472366 -275.987764)
		(end 166.057834 -275.987764)
		(width 0.16002)
		(layer "In11.Cu")
		(net "M_L_CPU1_SB_DQS_DP<9>")
	)
	(segment
		(start 177.950368 -275.660104)
		(end 180.094382 -275.660104)
		(width 0.16002)
		(layer "In11.Cu")
		(net "M_L_CPU1_SB_DQS_DP<9>")
	)
	(segment
		(start 166.880794 -275.164804)
		(end 172.055028 -275.164804)
		(width 0.16002)
		(layer "In11.Cu")
		(net "M_L_CPU1_SB_DQS_DP<9>")
	)
	(segment
		(start 181.145942 -275.987764)
		(end 181.968902 -275.164804)
		(width 0.16002)
		(layer "In11.Cu")
		(net "M_L_CPU1_SB_DQS_DP<9>")
	)
	(segment
		(start 195.51015 -275.987764)
		(end 196.23405 -275.987764)
		(width 0.16002)
		(layer "In11.Cu")
		(net "M_L_CPU1_SB_DQS_DP<9>")
	)
	(segment
		(start 197.05701 -275.164804)
		(end 197.46849 -275.164804)
		(width 0.16002)
		(layer "In11.Cu")
		(net "M_L_CPU1_SB_DQS_DP<9>")
	)
	(segment
		(start 147.457922 -269.216378)
		(end 147.55368 -269.312136)
		(width 0.09525)
		(layer "In11.Cu")
		(net "M_L_CPU1_SB_DQS_DP<9>")
	)
	(segment
		(start 203.761594 -276.003004)
		(end 203.955396 -275.809202)
		(width 0.16002)
		(layer "In11.Cu")
		(net "M_L_CPU1_SB_DQS_DP<9>")
	)
	(segment
		(start 144.693132 -271.171416)
		(end 144.726914 -271.151858)
		(width 0.09525)
		(layer "In11.Cu")
		(net "M_L_CPU1_SB_DQS_DP<9>")
	)
	(segment
		(start 157.737556 -269.252954)
		(end 164.472366 -275.987764)
		(width 0.16002)
		(layer "In11.Cu")
		(net "M_L_CPU1_SB_DQS_DP<9>")
	)
	(segment
		(start 142.804896 -271.176242)
		(end 142.813278 -271.171416)
		(width 0.09525)
		(layer "In11.Cu")
		(net "M_L_CPU1_SB_DQS_DP<9>")
	)
	(segment
		(start 145.645378 -270.285718)
		(end 146.714718 -269.216378)
		(width 0.09525)
		(layer "In11.Cu")
		(net "M_L_CPU1_SB_DQS_DP<9>")
	)
	(segment
		(start 195.18249 -275.660104)
		(end 195.51015 -275.987764)
		(width 0.16002)
		(layer "In11.Cu")
		(net "M_L_CPU1_SB_DQS_DP<9>")
	)
	(segment
		(start 139.804648 -270.846296)
		(end 139.650724 -271.111726)
		(width 0.09525)
		(layer "In11.Cu")
		(net "M_L_CPU1_SB_DQS_DP<9>")
	)
	(segment
		(start 175.190912 -274.81022)
		(end 177.100484 -274.81022)
		(width 0.16002)
		(layer "In11.Cu")
		(net "M_L_CPU1_SB_DQS_DP<9>")
	)
	(segment
		(start 205.41742 -275.809202)
		(end 205.974188 -275.809202)
		(width 0.16002)
		(layer "In11.Cu")
		(net "M_L_CPU1_SB_DQS_DP<9>")
	)
	(segment
		(start 205.974188 -275.809202)
		(end 206.248 -275.53539)
		(width 0.16002)
		(layer "In11.Cu")
		(net "M_L_CPU1_SB_DQS_DP<9>")
	)
	(segment
		(start 185.494422 -275.660104)
		(end 187.638436 -275.660104)
		(width 0.16002)
		(layer "In11.Cu")
		(net "M_L_CPU1_SB_DQS_DP<9>")
	)
	(segment
		(start 145.444718 -270.285718)
		(end 145.645378 -270.285718)
		(width 0.09525)
		(layer "In11.Cu")
		(net "M_L_CPU1_SB_DQS_DP<9>")
	)
	(segment
		(start 144.692624 -271.171416)
		(end 144.693132 -271.171416)
		(width 0.09525)
		(layer "In11.Cu")
		(net "M_L_CPU1_SB_DQS_DP<9>")
	)
	(segment
		(start 197.46849 -275.164804)
		(end 197.823074 -274.81022)
		(width 0.16002)
		(layer "In11.Cu")
		(net "M_L_CPU1_SB_DQS_DP<9>")
	)
	(segment
		(start 145.125186 -270.383508)
		(end 145.163286 -270.36141)
		(width 0.09525)
		(layer "In11.Cu")
		(net "M_L_CPU1_SB_DQS_DP<9>")
	)
	(segment
		(start 193.038476 -275.660104)
		(end 195.18249 -275.660104)
		(width 0.16002)
		(layer "In11.Cu")
		(net "M_L_CPU1_SB_DQS_DP<9>")
	)
	(segment
		(start 144.305528 -271.16532)
		(end 144.315942 -271.171416)
		(width 0.09525)
		(layer "In11.Cu")
		(net "M_L_CPU1_SB_DQS_DP<9>")
	)
	(segment
		(start 180.094382 -275.660104)
		(end 180.422042 -275.987764)
		(width 0.16002)
		(layer "In11.Cu")
		(net "M_L_CPU1_SB_DQS_DP<9>")
	)
	(segment
		(start 166.057834 -275.987764)
		(end 166.880794 -275.164804)
		(width 0.16002)
		(layer "In11.Cu")
		(net "M_L_CPU1_SB_DQS_DP<9>")
	)
	(segment
		(start 182.380382 -275.164804)
		(end 182.734966 -274.81022)
		(width 0.16002)
		(layer "In11.Cu")
		(net "M_L_CPU1_SB_DQS_DP<9>")
	)
	(segment
		(start 184.644538 -274.81022)
		(end 185.494422 -275.660104)
		(width 0.16002)
		(layer "In11.Cu")
		(net "M_L_CPU1_SB_DQS_DP<9>")
	)
	(segment
		(start 204.81036 -275.682202)
		(end 205.29042 -275.682202)
		(width 0.16002)
		(layer "In11.Cu")
		(net "M_L_CPU1_SB_DQS_DP<9>")
	)
	(segment
		(start 174.836328 -275.164804)
		(end 175.190912 -274.81022)
		(width 0.16002)
		(layer "In11.Cu")
		(net "M_L_CPU1_SB_DQS_DP<9>")
	)
	(segment
		(start 192.188592 -274.81022)
		(end 193.038476 -275.660104)
		(width 0.16002)
		(layer "In11.Cu")
		(net "M_L_CPU1_SB_DQS_DP<9>")
	)
	(segment
		(start 172.877988 -275.987764)
		(end 173.601888 -275.987764)
		(width 0.16002)
		(layer "In11.Cu")
		(net "M_L_CPU1_SB_DQS_DP<9>")
	)
	(segment
		(start 188.689996 -275.987764)
		(end 189.512956 -275.164804)
		(width 0.16002)
		(layer "In11.Cu")
		(net "M_L_CPU1_SB_DQS_DP<9>")
	)
	(segment
		(start 199.732646 -274.81022)
		(end 200.306686 -275.38426)
		(width 0.16002)
		(layer "In11.Cu")
		(net "M_L_CPU1_SB_DQS_DP<9>")
	)
	(segment
		(start 197.823074 -274.81022)
		(end 199.732646 -274.81022)
		(width 0.16002)
		(layer "In11.Cu")
		(net "M_L_CPU1_SB_DQS_DP<9>")
	)
	(segment
		(start 147.919186 -269.252954)
		(end 157.737556 -269.252954)
		(width 0.16002)
		(layer "In11.Cu")
		(net "M_L_CPU1_SB_DQS_DP<9>")
	)
	(segment
		(start 181.968902 -275.164804)
		(end 182.380382 -275.164804)
		(width 0.16002)
		(layer "In11.Cu")
		(net "M_L_CPU1_SB_DQS_DP<9>")
	)
	(segment
		(start 187.638436 -275.660104)
		(end 187.966096 -275.987764)
		(width 0.16002)
		(layer "In11.Cu")
		(net "M_L_CPU1_SB_DQS_DP<9>")
	)
	(segment
		(start 172.055028 -275.164804)
		(end 172.877988 -275.987764)
		(width 0.16002)
		(layer "In11.Cu")
		(net "M_L_CPU1_SB_DQS_DP<9>")
	)
	(segment
		(start 147.55368 -269.312136)
		(end 147.836382 -269.312136)
		(width 0.09525)
		(layer "In11.Cu")
		(net "M_L_CPU1_SB_DQS_DP<9>")
	)
	(segment
		(start 187.966096 -275.987764)
		(end 188.689996 -275.987764)
		(width 0.16002)
		(layer "In11.Cu")
		(net "M_L_CPU1_SB_DQS_DP<9>")
	)
	(segment
		(start 189.924436 -275.164804)
		(end 190.27902 -274.81022)
		(width 0.16002)
		(layer "In11.Cu")
		(net "M_L_CPU1_SB_DQS_DP<9>")
	)
	(segment
		(start 144.684242 -271.176242)
		(end 144.692624 -271.171416)
		(width 0.09525)
		(layer "In11.Cu")
		(net "M_L_CPU1_SB_DQS_DP<9>")
	)
	(segment
		(start 173.601888 -275.987764)
		(end 174.424848 -275.164804)
		(width 0.16002)
		(layer "In11.Cu")
		(net "M_L_CPU1_SB_DQS_DP<9>")
	)
	(segment
		(start 139.650724 -271.111726)
		(end 139.674092 -271.198594)
		(width 0.09525)
		(layer "In11.Cu")
		(net "M_L_CPU1_SB_DQS_DP<9>")
	)
	(segment
		(start 203.955396 -275.809202)
		(end 204.68336 -275.809202)
		(width 0.16002)
		(layer "In11.Cu")
		(net "M_L_CPU1_SB_DQS_DP<9>")
	)
	(segment
		(start 147.836382 -269.312136)
		(end 147.895564 -269.252954)
		(width 0.09525)
		(layer "In11.Cu")
		(net "M_L_CPU1_SB_DQS_DP<9>")
	)
	(segment
		(start 190.27902 -274.81022)
		(end 192.188592 -274.81022)
		(width 0.16002)
		(layer "In11.Cu")
		(net "M_L_CPU1_SB_DQS_DP<9>")
	)
	(arc
		(start 144.726914 -271.151858)
		(mid 144.841293 -271.017719)
		(end 144.882362 -270.846296)
		(width 0.09525)
		(layer "In11.Cu")
		(net "M_L_CPU1_SB_DQS_DP<9>")
	)
	(arc
		(start 139.99337 -271.171416)
		(mid 140.274802 -271.095661)
		(end 140.556234 -271.171416)
		(width 0.09525)
		(layer "In11.Cu")
		(net "M_L_CPU1_SB_DQS_DP<9>")
	)
	(arc
		(start 145.163286 -270.36141)
		(mid 145.298993 -270.304925)
		(end 145.444718 -270.285718)
		(width 0.09525)
		(layer "In11.Cu")
		(net "M_L_CPU1_SB_DQS_DP<9>")
	)
	(arc
		(start 144.882362 -270.846296)
		(mid 144.946759 -270.58499)
		(end 145.125186 -270.383508)
		(width 0.09525)
		(layer "In11.Cu")
		(net "M_L_CPU1_SB_DQS_DP<9>")
	)
	(arc
		(start 143.753332 -271.171416)
		(mid 144.028621 -271.095695)
		(end 144.305528 -271.16532)
		(width 0.09525)
		(layer "In11.Cu")
		(net "M_L_CPU1_SB_DQS_DP<9>")
	)
	(arc
		(start 139.674092 -271.198594)
		(mid 139.836774 -271.220726)
		(end 139.99337 -271.171416)
		(width 0.09525)
		(layer "In11.Cu")
		(net "M_L_CPU1_SB_DQS_DP<9>")
	)
	(arc
		(start 141.496288 -271.171416)
		(mid 141.684756 -271.222093)
		(end 141.873224 -271.171416)
		(width 0.09525)
		(layer "In11.Cu")
		(net "M_L_CPU1_SB_DQS_DP<9>")
	)
	(arc
		(start 142.813278 -271.171416)
		(mid 143.09471 -271.095661)
		(end 143.376142 -271.171416)
		(width 0.09525)
		(layer "In11.Cu")
		(net "M_L_CPU1_SB_DQS_DP<9>")
	)
	(arc
		(start 143.384524 -271.176242)
		(mid 143.569556 -271.222156)
		(end 143.753332 -271.171416)
		(width 0.09525)
		(layer "In11.Cu")
		(net "M_L_CPU1_SB_DQS_DP<9>")
	)
	(arc
		(start 140.933424 -271.171416)
		(mid 141.214856 -271.095661)
		(end 141.496288 -271.171416)
		(width 0.09525)
		(layer "In11.Cu")
		(net "M_L_CPU1_SB_DQS_DP<9>")
	)
	(arc
		(start 140.564616 -271.176242)
		(mid 140.749648 -271.222156)
		(end 140.933424 -271.171416)
		(width 0.09525)
		(layer "In11.Cu")
		(net "M_L_CPU1_SB_DQS_DP<9>")
	)
	(arc
		(start 141.873224 -271.171416)
		(mid 142.154656 -271.095661)
		(end 142.436088 -271.171416)
		(width 0.09525)
		(layer "In11.Cu")
		(net "M_L_CPU1_SB_DQS_DP<9>")
	)
	(arc
		(start 144.315942 -271.171416)
		(mid 144.499463 -271.22206)
		(end 144.684242 -271.176242)
		(width 0.09525)
		(layer "In11.Cu")
		(net "M_L_CPU1_SB_DQS_DP<9>")
	)
	(arc
		(start 142.436088 -271.171416)
		(mid 142.619863 -271.222188)
		(end 142.804896 -271.176242)
		(width 0.09525)
		(layer "In11.Cu")
		(net "M_L_CPU1_SB_DQS_DP<9>")
	)
	(segment
		(start 137.457942 -291.64026)
		(end 137.924794 -291.906198)
		(width 0.12954)
		(layer "F.Cu")
		(net "M_L_CPU1_SB_DQS_DP<8>")
	)
	(segment
		(start 166.99992 -314.13196)
		(end 168.02862 -314.13196)
		(width 0.16002)
		(layer "In11.Cu")
		(net "M_L_CPU1_SB_DQS_DP<8>")
	)
	(segment
		(start 197.748144 -314.13196)
		(end 198.126604 -314.51042)
		(width 0.16002)
		(layer "In11.Cu")
		(net "M_L_CPU1_SB_DQS_DP<8>")
	)
	(segment
		(start 144.990566 -292.269418)
		(end 144.990566 -292.269672)
		(width 0.09525)
		(layer "In11.Cu")
		(net "M_L_CPU1_SB_DQS_DP<8>")
	)
	(segment
		(start 180.613304 -314.9854)
		(end 181.234588 -314.9854)
		(width 0.16002)
		(layer "In11.Cu")
		(net "M_L_CPU1_SB_DQS_DP<8>")
	)
	(segment
		(start 177.81778 -314.51042)
		(end 178.667918 -315.360558)
		(width 0.16002)
		(layer "In11.Cu")
		(net "M_L_CPU1_SB_DQS_DP<8>")
	)
	(segment
		(start 169.74058 -314.251086)
		(end 170.840654 -314.251086)
		(width 0.16002)
		(layer "In11.Cu")
		(net "M_L_CPU1_SB_DQS_DP<8>")
	)
	(segment
		(start 201.87412 -314.361576)
		(end 202.147932 -314.635388)
		(width 0.16002)
		(layer "In11.Cu")
		(net "M_L_CPU1_SB_DQS_DP<8>")
	)
	(segment
		(start 146.079718 -293.99738)
		(end 146.134836 -294.029384)
		(width 0.09525)
		(layer "In11.Cu")
		(net "M_L_CPU1_SB_DQS_DP<8>")
	)
	(segment
		(start 193.756026 -315.360558)
		(end 195.326254 -315.360558)
		(width 0.16002)
		(layer "In11.Cu")
		(net "M_L_CPU1_SB_DQS_DP<8>")
	)
	(segment
		(start 188.778642 -314.9854)
		(end 189.632082 -314.13196)
		(width 0.16002)
		(layer "In11.Cu")
		(net "M_L_CPU1_SB_DQS_DP<8>")
	)
	(segment
		(start 199.437752 -314.51042)
		(end 199.586596 -314.361576)
		(width 0.16002)
		(layer "In11.Cu")
		(net "M_L_CPU1_SB_DQS_DP<8>")
	)
	(segment
		(start 147.255738 -296.379138)
		(end 147.255738 -296.40276)
		(width 0.09525)
		(layer "In11.Cu")
		(net "M_L_CPU1_SB_DQS_DP<8>")
	)
	(segment
		(start 175.115982 -314.13196)
		(end 175.494442 -314.51042)
		(width 0.16002)
		(layer "In11.Cu")
		(net "M_L_CPU1_SB_DQS_DP<8>")
	)
	(segment
		(start 137.924794 -291.906198)
		(end 138.078718 -291.640768)
		(width 0.09525)
		(layer "In11.Cu")
		(net "M_L_CPU1_SB_DQS_DP<8>")
	)
	(segment
		(start 168.307766 -314.945268)
		(end 168.644824 -315.282326)
		(width 0.16002)
		(layer "In11.Cu")
		(net "M_L_CPU1_SB_DQS_DP<8>")
	)
	(segment
		(start 147.31492 -296.319956)
		(end 147.255738 -296.379138)
		(width 0.09525)
		(layer "In11.Cu")
		(net "M_L_CPU1_SB_DQS_DP<8>")
	)
	(segment
		(start 161.769044 -314.9854)
		(end 166.14648 -314.9854)
		(width 0.16002)
		(layer "In11.Cu")
		(net "M_L_CPU1_SB_DQS_DP<8>")
	)
	(segment
		(start 181.234588 -314.9854)
		(end 182.088028 -314.13196)
		(width 0.16002)
		(layer "In11.Cu")
		(net "M_L_CPU1_SB_DQS_DP<8>")
	)
	(segment
		(start 197.176136 -314.13196)
		(end 197.748144 -314.13196)
		(width 0.16002)
		(layer "In11.Cu")
		(net "M_L_CPU1_SB_DQS_DP<8>")
	)
	(segment
		(start 171.08551 -314.495942)
		(end 171.08551 -314.919106)
		(width 0.16002)
		(layer "In11.Cu")
		(net "M_L_CPU1_SB_DQS_DP<8>")
	)
	(segment
		(start 178.667918 -315.360558)
		(end 180.238146 -315.360558)
		(width 0.16002)
		(layer "In11.Cu")
		(net "M_L_CPU1_SB_DQS_DP<8>")
	)
	(segment
		(start 147.255738 -296.40276)
		(end 147.255738 -300.472094)
		(width 0.16002)
		(layer "In11.Cu")
		(net "M_L_CPU1_SB_DQS_DP<8>")
	)
	(segment
		(start 171.08551 -314.919106)
		(end 171.526962 -315.360558)
		(width 0.16002)
		(layer "In11.Cu")
		(net "M_L_CPU1_SB_DQS_DP<8>")
	)
	(segment
		(start 174.543974 -314.13196)
		(end 175.115982 -314.13196)
		(width 0.16002)
		(layer "In11.Cu")
		(net "M_L_CPU1_SB_DQS_DP<8>")
	)
	(segment
		(start 168.02862 -314.13196)
		(end 168.307766 -314.411106)
		(width 0.16002)
		(layer "In11.Cu")
		(net "M_L_CPU1_SB_DQS_DP<8>")
	)
	(segment
		(start 195.326254 -315.360558)
		(end 195.701412 -314.9854)
		(width 0.16002)
		(layer "In11.Cu")
		(net "M_L_CPU1_SB_DQS_DP<8>")
	)
	(segment
		(start 145.822416 -293.440612)
		(end 145.822416 -293.52621)
		(width 0.09525)
		(layer "In11.Cu")
		(net "M_L_CPU1_SB_DQS_DP<8>")
	)
	(segment
		(start 185.361834 -314.51042)
		(end 186.211972 -315.360558)
		(width 0.16002)
		(layer "In11.Cu")
		(net "M_L_CPU1_SB_DQS_DP<8>")
	)
	(segment
		(start 168.307766 -314.411106)
		(end 168.307766 -314.945268)
		(width 0.16002)
		(layer "In11.Cu")
		(net "M_L_CPU1_SB_DQS_DP<8>")
	)
	(segment
		(start 138.078718 -291.640768)
		(end 138.179556 -291.614098)
		(width 0.09525)
		(layer "In11.Cu")
		(net "M_L_CPU1_SB_DQS_DP<8>")
	)
	(segment
		(start 171.526962 -315.360558)
		(end 172.694092 -315.360558)
		(width 0.16002)
		(layer "In11.Cu")
		(net "M_L_CPU1_SB_DQS_DP<8>")
	)
	(segment
		(start 144.034764 -291.65677)
		(end 144.58569 -291.65677)
		(width 0.09525)
		(layer "In11.Cu")
		(net "M_L_CPU1_SB_DQS_DP<8>")
	)
	(segment
		(start 190.58255 -314.51042)
		(end 192.905888 -314.51042)
		(width 0.16002)
		(layer "In11.Cu")
		(net "M_L_CPU1_SB_DQS_DP<8>")
	)
	(segment
		(start 169.58056 -314.411106)
		(end 169.74058 -314.251086)
		(width 0.16002)
		(layer "In11.Cu")
		(net "M_L_CPU1_SB_DQS_DP<8>")
	)
	(segment
		(start 146.068034 -293.990522)
		(end 146.079718 -293.99738)
		(width 0.09525)
		(layer "In11.Cu")
		(net "M_L_CPU1_SB_DQS_DP<8>")
	)
	(segment
		(start 146.65071 -294.88003)
		(end 147.31492 -295.54424)
		(width 0.09525)
		(layer "In11.Cu")
		(net "M_L_CPU1_SB_DQS_DP<8>")
	)
	(segment
		(start 189.632082 -314.13196)
		(end 190.20409 -314.13196)
		(width 0.16002)
		(layer "In11.Cu")
		(net "M_L_CPU1_SB_DQS_DP<8>")
	)
	(segment
		(start 170.840654 -314.251086)
		(end 171.08551 -314.495942)
		(width 0.16002)
		(layer "In11.Cu")
		(net "M_L_CPU1_SB_DQS_DP<8>")
	)
	(segment
		(start 166.14648 -314.9854)
		(end 166.99992 -314.13196)
		(width 0.16002)
		(layer "In11.Cu")
		(net "M_L_CPU1_SB_DQS_DP<8>")
	)
	(segment
		(start 173.06925 -314.9854)
		(end 173.690534 -314.9854)
		(width 0.16002)
		(layer "In11.Cu")
		(net "M_L_CPU1_SB_DQS_DP<8>")
	)
	(segment
		(start 139.044934 -291.576252)
		(end 139.053316 -291.581078)
		(width 0.09525)
		(layer "In11.Cu")
		(net "M_L_CPU1_SB_DQS_DP<8>")
	)
	(segment
		(start 196.322696 -314.9854)
		(end 197.176136 -314.13196)
		(width 0.16002)
		(layer "In11.Cu")
		(net "M_L_CPU1_SB_DQS_DP<8>")
	)
	(segment
		(start 147.255738 -300.472094)
		(end 161.769044 -314.9854)
		(width 0.16002)
		(layer "In11.Cu")
		(net "M_L_CPU1_SB_DQS_DP<8>")
	)
	(segment
		(start 183.038496 -314.51042)
		(end 185.361834 -314.51042)
		(width 0.16002)
		(layer "In11.Cu")
		(net "M_L_CPU1_SB_DQS_DP<8>")
	)
	(segment
		(start 142.804896 -291.576252)
		(end 142.813278 -291.581078)
		(width 0.09525)
		(layer "In11.Cu")
		(net "M_L_CPU1_SB_DQS_DP<8>")
	)
	(segment
		(start 182.088028 -314.13196)
		(end 182.660036 -314.13196)
		(width 0.16002)
		(layer "In11.Cu")
		(net "M_L_CPU1_SB_DQS_DP<8>")
	)
	(segment
		(start 173.690534 -314.9854)
		(end 174.543974 -314.13196)
		(width 0.16002)
		(layer "In11.Cu")
		(net "M_L_CPU1_SB_DQS_DP<8>")
	)
	(segment
		(start 168.644824 -315.282326)
		(end 169.243502 -315.282326)
		(width 0.16002)
		(layer "In11.Cu")
		(net "M_L_CPU1_SB_DQS_DP<8>")
	)
	(segment
		(start 169.243502 -315.282326)
		(end 169.58056 -314.945268)
		(width 0.16002)
		(layer "In11.Cu")
		(net "M_L_CPU1_SB_DQS_DP<8>")
	)
	(segment
		(start 147.31492 -295.54424)
		(end 147.31492 -296.319956)
		(width 0.09525)
		(layer "In11.Cu")
		(net "M_L_CPU1_SB_DQS_DP<8>")
	)
	(segment
		(start 192.905888 -314.51042)
		(end 193.756026 -315.360558)
		(width 0.16002)
		(layer "In11.Cu")
		(net "M_L_CPU1_SB_DQS_DP<8>")
	)
	(segment
		(start 143.376142 -291.581078)
		(end 143.384524 -291.576252)
		(width 0.09525)
		(layer "In11.Cu")
		(net "M_L_CPU1_SB_DQS_DP<8>")
	)
	(segment
		(start 190.20409 -314.13196)
		(end 190.58255 -314.51042)
		(width 0.16002)
		(layer "In11.Cu")
		(net "M_L_CPU1_SB_DQS_DP<8>")
	)
	(segment
		(start 199.586596 -314.361576)
		(end 201.87412 -314.361576)
		(width 0.16002)
		(layer "In11.Cu")
		(net "M_L_CPU1_SB_DQS_DP<8>")
	)
	(segment
		(start 175.494442 -314.51042)
		(end 177.81778 -314.51042)
		(width 0.16002)
		(layer "In11.Cu")
		(net "M_L_CPU1_SB_DQS_DP<8>")
	)
	(segment
		(start 139.61618 -291.581078)
		(end 139.624562 -291.576252)
		(width 0.09525)
		(layer "In11.Cu")
		(net "M_L_CPU1_SB_DQS_DP<8>")
	)
	(segment
		(start 172.694092 -315.360558)
		(end 173.06925 -314.9854)
		(width 0.16002)
		(layer "In11.Cu")
		(net "M_L_CPU1_SB_DQS_DP<8>")
	)
	(segment
		(start 180.238146 -315.360558)
		(end 180.613304 -314.9854)
		(width 0.16002)
		(layer "In11.Cu")
		(net "M_L_CPU1_SB_DQS_DP<8>")
	)
	(segment
		(start 195.701412 -314.9854)
		(end 196.322696 -314.9854)
		(width 0.16002)
		(layer "In11.Cu")
		(net "M_L_CPU1_SB_DQS_DP<8>")
	)
	(segment
		(start 198.126604 -314.51042)
		(end 199.437752 -314.51042)
		(width 0.16002)
		(layer "In11.Cu")
		(net "M_L_CPU1_SB_DQS_DP<8>")
	)
	(segment
		(start 188.157358 -314.9854)
		(end 188.778642 -314.9854)
		(width 0.16002)
		(layer "In11.Cu")
		(net "M_L_CPU1_SB_DQS_DP<8>")
	)
	(segment
		(start 169.58056 -314.945268)
		(end 169.58056 -314.411106)
		(width 0.16002)
		(layer "In11.Cu")
		(net "M_L_CPU1_SB_DQS_DP<8>")
	)
	(segment
		(start 186.211972 -315.360558)
		(end 187.7822 -315.360558)
		(width 0.16002)
		(layer "In11.Cu")
		(net "M_L_CPU1_SB_DQS_DP<8>")
	)
	(segment
		(start 187.7822 -315.360558)
		(end 188.157358 -314.9854)
		(width 0.16002)
		(layer "In11.Cu")
		(net "M_L_CPU1_SB_DQS_DP<8>")
	)
	(segment
		(start 144.990566 -292.269672)
		(end 145.58264 -292.861746)
		(width 0.09525)
		(layer "In11.Cu")
		(net "M_L_CPU1_SB_DQS_DP<8>")
	)
	(segment
		(start 182.660036 -314.13196)
		(end 183.038496 -314.51042)
		(width 0.16002)
		(layer "In11.Cu")
		(net "M_L_CPU1_SB_DQS_DP<8>")
	)
	(segment
		(start 146.53514 -294.799004)
		(end 146.57324 -294.821102)
		(width 0.09525)
		(layer "In11.Cu")
		(net "M_L_CPU1_SB_DQS_DP<8>")
	)
	(segment
		(start 140.556234 -291.581078)
		(end 140.564616 -291.576252)
		(width 0.09525)
		(layer "In11.Cu")
		(net "M_L_CPU1_SB_DQS_DP<8>")
	)
	(arc
		(start 141.873224 -291.581078)
		(mid 142.154656 -291.656833)
		(end 142.436088 -291.581078)
		(width 0.09525)
		(layer "In11.Cu")
		(net "M_L_CPU1_SB_DQS_DP<8>")
	)
	(arc
		(start 138.676126 -291.581078)
		(mid 138.859901 -291.530306)
		(end 139.044934 -291.576252)
		(width 0.09525)
		(layer "In11.Cu")
		(net "M_L_CPU1_SB_DQS_DP<8>")
	)
	(arc
		(start 139.624562 -291.576252)
		(mid 139.809594 -291.530338)
		(end 139.99337 -291.581078)
		(width 0.09525)
		(layer "In11.Cu")
		(net "M_L_CPU1_SB_DQS_DP<8>")
	)
	(arc
		(start 142.813278 -291.581078)
		(mid 143.09471 -291.656833)
		(end 143.376142 -291.581078)
		(width 0.09525)
		(layer "In11.Cu")
		(net "M_L_CPU1_SB_DQS_DP<8>")
	)
	(arc
		(start 140.564616 -291.576252)
		(mid 140.749648 -291.530338)
		(end 140.933424 -291.581078)
		(width 0.09525)
		(layer "In11.Cu")
		(net "M_L_CPU1_SB_DQS_DP<8>")
	)
	(arc
		(start 142.436088 -291.581078)
		(mid 142.619863 -291.530306)
		(end 142.804896 -291.576252)
		(width 0.09525)
		(layer "In11.Cu")
		(net "M_L_CPU1_SB_DQS_DP<8>")
	)
	(arc
		(start 144.58569 -291.65677)
		(mid 144.68328 -291.676182)
		(end 144.76603 -291.731446)
		(width 0.09525)
		(layer "In11.Cu")
		(net "M_L_CPU1_SB_DQS_DP<8>")
	)
	(arc
		(start 138.179556 -291.614098)
		(mid 138.189678 -291.618133)
		(end 138.199876 -291.621972)
		(width 0.09525)
		(layer "In11.Cu")
		(net "M_L_CPU1_SB_DQS_DP<8>")
	)
	(arc
		(start 146.134836 -294.029384)
		(mid 146.250634 -294.163778)
		(end 146.292316 -294.336216)
		(width 0.09525)
		(layer "In11.Cu")
		(net "M_L_CPU1_SB_DQS_DP<8>")
	)
	(arc
		(start 138.199876 -291.621972)
		(mid 138.442588 -291.654855)
		(end 138.676126 -291.581078)
		(width 0.09525)
		(layer "In11.Cu")
		(net "M_L_CPU1_SB_DQS_DP<8>")
	)
	(arc
		(start 145.822416 -293.52621)
		(mid 145.887663 -293.788813)
		(end 146.068034 -293.990522)
		(width 0.09525)
		(layer "In11.Cu")
		(net "M_L_CPU1_SB_DQS_DP<8>")
	)
	(arc
		(start 144.76603 -291.731446)
		(mid 144.808904 -291.795303)
		(end 144.82445 -291.870638)
		(width 0.09525)
		(layer "In11.Cu")
		(net "M_L_CPU1_SB_DQS_DP<8>")
	)
	(arc
		(start 139.99337 -291.581078)
		(mid 140.274802 -291.656833)
		(end 140.556234 -291.581078)
		(width 0.09525)
		(layer "In11.Cu")
		(net "M_L_CPU1_SB_DQS_DP<8>")
	)
	(arc
		(start 143.753332 -291.581078)
		(mid 143.889039 -291.637563)
		(end 144.034764 -291.65677)
		(width 0.09525)
		(layer "In11.Cu")
		(net "M_L_CPU1_SB_DQS_DP<8>")
	)
	(arc
		(start 139.053316 -291.581078)
		(mid 139.334748 -291.656833)
		(end 139.61618 -291.581078)
		(width 0.09525)
		(layer "In11.Cu")
		(net "M_L_CPU1_SB_DQS_DP<8>")
	)
	(arc
		(start 146.292316 -294.336216)
		(mid 146.356713 -294.597522)
		(end 146.53514 -294.799004)
		(width 0.09525)
		(layer "In11.Cu")
		(net "M_L_CPU1_SB_DQS_DP<8>")
	)
	(arc
		(start 146.612356 -294.84701)
		(mid 146.632094 -294.862869)
		(end 146.65071 -294.88003)
		(width 0.09525)
		(layer "In11.Cu")
		(net "M_L_CPU1_SB_DQS_DP<8>")
	)
	(arc
		(start 145.58264 -292.861746)
		(mid 145.760099 -293.127332)
		(end 145.822416 -293.440612)
		(width 0.09525)
		(layer "In11.Cu")
		(net "M_L_CPU1_SB_DQS_DP<8>")
	)
	(arc
		(start 141.496288 -291.581078)
		(mid 141.684756 -291.530401)
		(end 141.873224 -291.581078)
		(width 0.09525)
		(layer "In11.Cu")
		(net "M_L_CPU1_SB_DQS_DP<8>")
	)
	(arc
		(start 144.82445 -291.870638)
		(mid 144.868162 -292.086411)
		(end 144.990566 -292.269418)
		(width 0.09525)
		(layer "In11.Cu")
		(net "M_L_CPU1_SB_DQS_DP<8>")
	)
	(arc
		(start 146.57324 -294.821102)
		(mid 146.593199 -294.83345)
		(end 146.612356 -294.84701)
		(width 0.09525)
		(layer "In11.Cu")
		(net "M_L_CPU1_SB_DQS_DP<8>")
	)
	(arc
		(start 140.933424 -291.581078)
		(mid 141.214856 -291.656833)
		(end 141.496288 -291.581078)
		(width 0.09525)
		(layer "In11.Cu")
		(net "M_L_CPU1_SB_DQS_DP<8>")
	)
	(arc
		(start 143.384524 -291.576252)
		(mid 143.569556 -291.530338)
		(end 143.753332 -291.581078)
		(width 0.09525)
		(layer "In11.Cu")
		(net "M_L_CPU1_SB_DQS_DP<8>")
	)
	(segment
		(start 137.457942 -286.780478)
		(end 137.924794 -287.046162)
		(width 0.12954)
		(layer "F.Cu")
		(net "M_L_CPU1_SB_DQS_DP<7>")
	)
	(segment
		(start 166.99992 -304.781966)
		(end 167.571928 -304.781966)
		(width 0.16002)
		(layer "In11.Cu")
		(net "M_L_CPU1_SB_DQS_DP<7>")
	)
	(segment
		(start 199.586596 -305.011582)
		(end 201.87412 -305.011582)
		(width 0.16002)
		(layer "In11.Cu")
		(net "M_L_CPU1_SB_DQS_DP<7>")
	)
	(segment
		(start 157.174184 -300.72457)
		(end 157.252924 -300.646084)
		(width 0.16002)
		(layer "In11.Cu")
		(net "M_L_CPU1_SB_DQS_DP<7>")
	)
	(segment
		(start 154.731974 -297.89882)
		(end 154.97937 -298.146216)
		(width 0.16002)
		(layer "In11.Cu")
		(net "M_L_CPU1_SB_DQS_DP<7>")
	)
	(segment
		(start 180.613304 -305.635406)
		(end 181.234588 -305.635406)
		(width 0.16002)
		(layer "In11.Cu")
		(net "M_L_CPU1_SB_DQS_DP<7>")
	)
	(segment
		(start 158.547816 -302.098202)
		(end 158.626556 -302.019716)
		(width 0.16002)
		(layer "In11.Cu")
		(net "M_L_CPU1_SB_DQS_DP<7>")
	)
	(segment
		(start 154.42692 -297.977306)
		(end 154.50566 -297.89882)
		(width 0.16002)
		(layer "In11.Cu")
		(net "M_L_CPU1_SB_DQS_DP<7>")
	)
	(segment
		(start 158.071566 -302.098202)
		(end 158.547816 -302.098202)
		(width 0.16002)
		(layer "In11.Cu")
		(net "M_L_CPU1_SB_DQS_DP<7>")
	)
	(segment
		(start 170.39209 -305.160426)
		(end 171.242228 -306.010564)
		(width 0.16002)
		(layer "In11.Cu")
		(net "M_L_CPU1_SB_DQS_DP<7>")
	)
	(segment
		(start 166.14648 -305.635406)
		(end 166.99992 -304.781966)
		(width 0.16002)
		(layer "In11.Cu")
		(net "M_L_CPU1_SB_DQS_DP<7>")
	)
	(segment
		(start 140.556234 -286.721042)
		(end 140.564616 -286.716216)
		(width 0.09525)
		(layer "In11.Cu")
		(net "M_L_CPU1_SB_DQS_DP<7>")
	)
	(segment
		(start 157.252924 -300.646084)
		(end 157.479238 -300.646084)
		(width 0.16002)
		(layer "In11.Cu")
		(net "M_L_CPU1_SB_DQS_DP<7>")
	)
	(segment
		(start 192.905888 -305.160426)
		(end 193.756026 -306.010564)
		(width 0.16002)
		(layer "In11.Cu")
		(net "M_L_CPU1_SB_DQS_DP<7>")
	)
	(segment
		(start 157.647894 -301.198026)
		(end 157.647894 -301.67453)
		(width 0.16002)
		(layer "In11.Cu")
		(net "M_L_CPU1_SB_DQS_DP<7>")
	)
	(segment
		(start 180.238146 -306.010564)
		(end 180.613304 -305.635406)
		(width 0.16002)
		(layer "In11.Cu")
		(net "M_L_CPU1_SB_DQS_DP<7>")
	)
	(segment
		(start 153.95067 -297.977306)
		(end 154.42692 -297.977306)
		(width 0.16002)
		(layer "In11.Cu")
		(net "M_L_CPU1_SB_DQS_DP<7>")
	)
	(segment
		(start 156.697934 -300.72457)
		(end 157.174184 -300.72457)
		(width 0.16002)
		(layer "In11.Cu")
		(net "M_L_CPU1_SB_DQS_DP<7>")
	)
	(segment
		(start 154.90063 -298.450762)
		(end 154.90063 -298.927266)
		(width 0.16002)
		(layer "In11.Cu")
		(net "M_L_CPU1_SB_DQS_DP<7>")
	)
	(segment
		(start 152.88895 -296.915586)
		(end 153.95067 -297.977306)
		(width 0.16002)
		(layer "In11.Cu")
		(net "M_L_CPU1_SB_DQS_DP<7>")
	)
	(segment
		(start 157.726634 -300.89348)
		(end 157.726634 -301.119286)
		(width 0.16002)
		(layer "In11.Cu")
		(net "M_L_CPU1_SB_DQS_DP<7>")
	)
	(segment
		(start 146.024346 -286.628586)
		(end 146.578066 -287.182306)
		(width 0.09525)
		(layer "In11.Cu")
		(net "M_L_CPU1_SB_DQS_DP<7>")
	)
	(segment
		(start 159.100266 -302.267112)
		(end 159.100266 -302.492918)
		(width 0.16002)
		(layer "In11.Cu")
		(net "M_L_CPU1_SB_DQS_DP<7>")
	)
	(segment
		(start 156.274262 -299.824394)
		(end 156.274262 -300.300898)
		(width 0.16002)
		(layer "In11.Cu")
		(net "M_L_CPU1_SB_DQS_DP<7>")
	)
	(segment
		(start 175.494442 -305.160426)
		(end 177.81778 -305.160426)
		(width 0.16002)
		(layer "In11.Cu")
		(net "M_L_CPU1_SB_DQS_DP<7>")
	)
	(segment
		(start 138.078718 -286.780732)
		(end 138.179556 -286.754062)
		(width 0.09525)
		(layer "In11.Cu")
		(net "M_L_CPU1_SB_DQS_DP<7>")
	)
	(segment
		(start 139.044934 -286.716216)
		(end 139.053316 -286.721042)
		(width 0.09525)
		(layer "In11.Cu")
		(net "M_L_CPU1_SB_DQS_DP<7>")
	)
	(segment
		(start 197.748144 -304.781966)
		(end 198.126604 -305.160426)
		(width 0.16002)
		(layer "In11.Cu")
		(net "M_L_CPU1_SB_DQS_DP<7>")
	)
	(segment
		(start 195.701412 -305.635406)
		(end 196.322696 -305.635406)
		(width 0.16002)
		(layer "In11.Cu")
		(net "M_L_CPU1_SB_DQS_DP<7>")
	)
	(segment
		(start 144.320514 -286.718502)
		(end 144.324578 -286.716216)
		(width 0.09525)
		(layer "In11.Cu")
		(net "M_L_CPU1_SB_DQS_DP<7>")
	)
	(segment
		(start 154.97937 -298.146216)
		(end 154.97937 -298.372022)
		(width 0.16002)
		(layer "In11.Cu")
		(net "M_L_CPU1_SB_DQS_DP<7>")
	)
	(segment
		(start 182.088028 -304.781966)
		(end 182.660036 -304.781966)
		(width 0.16002)
		(layer "In11.Cu")
		(net "M_L_CPU1_SB_DQS_DP<7>")
	)
	(segment
		(start 161.60877 -305.635406)
		(end 166.14648 -305.635406)
		(width 0.16002)
		(layer "In11.Cu")
		(net "M_L_CPU1_SB_DQS_DP<7>")
	)
	(segment
		(start 190.20409 -304.781966)
		(end 190.58255 -305.160426)
		(width 0.16002)
		(layer "In11.Cu")
		(net "M_L_CPU1_SB_DQS_DP<7>")
	)
	(segment
		(start 147.56384 -287.679384)
		(end 147.580604 -287.696148)
		(width 0.09525)
		(layer "In11.Cu")
		(net "M_L_CPU1_SB_DQS_DP<7>")
	)
	(segment
		(start 197.176136 -304.781966)
		(end 197.748144 -304.781966)
		(width 0.16002)
		(layer "In11.Cu")
		(net "M_L_CPU1_SB_DQS_DP<7>")
	)
	(segment
		(start 155.800552 -299.350938)
		(end 155.879292 -299.272452)
		(width 0.16002)
		(layer "In11.Cu")
		(net "M_L_CPU1_SB_DQS_DP<7>")
	)
	(segment
		(start 193.756026 -306.010564)
		(end 195.326254 -306.010564)
		(width 0.16002)
		(layer "In11.Cu")
		(net "M_L_CPU1_SB_DQS_DP<7>")
	)
	(segment
		(start 144.667986 -286.628586)
		(end 146.024346 -286.628586)
		(width 0.09525)
		(layer "In11.Cu")
		(net "M_L_CPU1_SB_DQS_DP<7>")
	)
	(segment
		(start 154.50566 -297.89882)
		(end 154.731974 -297.89882)
		(width 0.16002)
		(layer "In11.Cu")
		(net "M_L_CPU1_SB_DQS_DP<7>")
	)
	(segment
		(start 156.105606 -299.272452)
		(end 156.353002 -299.519848)
		(width 0.16002)
		(layer "In11.Cu")
		(net "M_L_CPU1_SB_DQS_DP<7>")
	)
	(segment
		(start 154.90063 -298.927266)
		(end 155.324302 -299.350938)
		(width 0.16002)
		(layer "In11.Cu")
		(net "M_L_CPU1_SB_DQS_DP<7>")
	)
	(segment
		(start 198.126604 -305.160426)
		(end 199.437752 -305.160426)
		(width 0.16002)
		(layer "In11.Cu")
		(net "M_L_CPU1_SB_DQS_DP<7>")
	)
	(segment
		(start 173.690534 -305.635406)
		(end 174.543974 -304.781966)
		(width 0.16002)
		(layer "In11.Cu")
		(net "M_L_CPU1_SB_DQS_DP<7>")
	)
	(segment
		(start 157.726634 -301.119286)
		(end 157.647894 -301.198026)
		(width 0.16002)
		(layer "In11.Cu")
		(net "M_L_CPU1_SB_DQS_DP<7>")
	)
	(segment
		(start 190.58255 -305.160426)
		(end 192.905888 -305.160426)
		(width 0.16002)
		(layer "In11.Cu")
		(net "M_L_CPU1_SB_DQS_DP<7>")
	)
	(segment
		(start 139.61618 -286.721042)
		(end 139.624562 -286.716216)
		(width 0.09525)
		(layer "In11.Cu")
		(net "M_L_CPU1_SB_DQS_DP<7>")
	)
	(segment
		(start 188.157358 -305.635406)
		(end 188.778642 -305.635406)
		(width 0.16002)
		(layer "In11.Cu")
		(net "M_L_CPU1_SB_DQS_DP<7>")
	)
	(segment
		(start 156.353002 -299.745654)
		(end 156.274262 -299.824394)
		(width 0.16002)
		(layer "In11.Cu")
		(net "M_L_CPU1_SB_DQS_DP<7>")
	)
	(segment
		(start 155.879292 -299.272452)
		(end 156.105606 -299.272452)
		(width 0.16002)
		(layer "In11.Cu")
		(net "M_L_CPU1_SB_DQS_DP<7>")
	)
	(segment
		(start 181.234588 -305.635406)
		(end 182.088028 -304.781966)
		(width 0.16002)
		(layer "In11.Cu")
		(net "M_L_CPU1_SB_DQS_DP<7>")
	)
	(segment
		(start 178.667918 -306.010564)
		(end 180.238146 -306.010564)
		(width 0.16002)
		(layer "In11.Cu")
		(net "M_L_CPU1_SB_DQS_DP<7>")
	)
	(segment
		(start 167.571928 -304.781966)
		(end 167.950388 -305.160426)
		(width 0.16002)
		(layer "In11.Cu")
		(net "M_L_CPU1_SB_DQS_DP<7>")
	)
	(segment
		(start 158.626556 -302.019716)
		(end 158.85287 -302.019716)
		(width 0.16002)
		(layer "In11.Cu")
		(net "M_L_CPU1_SB_DQS_DP<7>")
	)
	(segment
		(start 186.211972 -306.010564)
		(end 187.7822 -306.010564)
		(width 0.16002)
		(layer "In11.Cu")
		(net "M_L_CPU1_SB_DQS_DP<7>")
	)
	(segment
		(start 159.021526 -302.571658)
		(end 159.021526 -303.048162)
		(width 0.16002)
		(layer "In11.Cu")
		(net "M_L_CPU1_SB_DQS_DP<7>")
	)
	(segment
		(start 154.97937 -298.372022)
		(end 154.90063 -298.450762)
		(width 0.16002)
		(layer "In11.Cu")
		(net "M_L_CPU1_SB_DQS_DP<7>")
	)
	(segment
		(start 195.326254 -306.010564)
		(end 195.701412 -305.635406)
		(width 0.16002)
		(layer "In11.Cu")
		(net "M_L_CPU1_SB_DQS_DP<7>")
	)
	(segment
		(start 155.324302 -299.350938)
		(end 155.800552 -299.350938)
		(width 0.16002)
		(layer "In11.Cu")
		(net "M_L_CPU1_SB_DQS_DP<7>")
	)
	(segment
		(start 177.81778 -305.160426)
		(end 178.667918 -306.010564)
		(width 0.16002)
		(layer "In11.Cu")
		(net "M_L_CPU1_SB_DQS_DP<7>")
	)
	(segment
		(start 175.115982 -304.781966)
		(end 175.494442 -305.160426)
		(width 0.16002)
		(layer "In11.Cu")
		(net "M_L_CPU1_SB_DQS_DP<7>")
	)
	(segment
		(start 156.274262 -300.300898)
		(end 156.697934 -300.72457)
		(width 0.16002)
		(layer "In11.Cu")
		(net "M_L_CPU1_SB_DQS_DP<7>")
	)
	(segment
		(start 174.543974 -304.781966)
		(end 175.115982 -304.781966)
		(width 0.16002)
		(layer "In11.Cu")
		(net "M_L_CPU1_SB_DQS_DP<7>")
	)
	(segment
		(start 167.950388 -305.160426)
		(end 170.39209 -305.160426)
		(width 0.16002)
		(layer "In11.Cu")
		(net "M_L_CPU1_SB_DQS_DP<7>")
	)
	(segment
		(start 156.353002 -299.519848)
		(end 156.353002 -299.745654)
		(width 0.16002)
		(layer "In11.Cu")
		(net "M_L_CPU1_SB_DQS_DP<7>")
	)
	(segment
		(start 183.038496 -305.160426)
		(end 185.361834 -305.160426)
		(width 0.16002)
		(layer "In11.Cu")
		(net "M_L_CPU1_SB_DQS_DP<7>")
	)
	(segment
		(start 196.322696 -305.635406)
		(end 197.176136 -304.781966)
		(width 0.16002)
		(layer "In11.Cu")
		(net "M_L_CPU1_SB_DQS_DP<7>")
	)
	(segment
		(start 171.242228 -306.010564)
		(end 172.694092 -306.010564)
		(width 0.16002)
		(layer "In11.Cu")
		(net "M_L_CPU1_SB_DQS_DP<7>")
	)
	(segment
		(start 182.660036 -304.781966)
		(end 183.038496 -305.160426)
		(width 0.16002)
		(layer "In11.Cu")
		(net "M_L_CPU1_SB_DQS_DP<7>")
	)
	(segment
		(start 143.376142 -286.721042)
		(end 143.384524 -286.716216)
		(width 0.09525)
		(layer "In11.Cu")
		(net "M_L_CPU1_SB_DQS_DP<7>")
	)
	(segment
		(start 185.361834 -305.160426)
		(end 186.211972 -306.010564)
		(width 0.16002)
		(layer "In11.Cu")
		(net "M_L_CPU1_SB_DQS_DP<7>")
	)
	(segment
		(start 199.437752 -305.160426)
		(end 199.586596 -305.011582)
		(width 0.16002)
		(layer "In11.Cu")
		(net "M_L_CPU1_SB_DQS_DP<7>")
	)
	(segment
		(start 147.580604 -287.696148)
		(end 152.88895 -293.005002)
		(width 0.16002)
		(layer "In11.Cu")
		(net "M_L_CPU1_SB_DQS_DP<7>")
	)
	(segment
		(start 172.694092 -306.010564)
		(end 173.06925 -305.635406)
		(width 0.16002)
		(layer "In11.Cu")
		(net "M_L_CPU1_SB_DQS_DP<7>")
	)
	(segment
		(start 157.479238 -300.646084)
		(end 157.726634 -300.89348)
		(width 0.16002)
		(layer "In11.Cu")
		(net "M_L_CPU1_SB_DQS_DP<7>")
	)
	(segment
		(start 188.778642 -305.635406)
		(end 189.632082 -304.781966)
		(width 0.16002)
		(layer "In11.Cu")
		(net "M_L_CPU1_SB_DQS_DP<7>")
	)
	(segment
		(start 137.924794 -287.046162)
		(end 138.078718 -286.780732)
		(width 0.09525)
		(layer "In11.Cu")
		(net "M_L_CPU1_SB_DQS_DP<7>")
	)
	(segment
		(start 147.151852 -287.182306)
		(end 147.564348 -287.596072)
		(width 0.09525)
		(layer "In11.Cu")
		(net "M_L_CPU1_SB_DQS_DP<7>")
	)
	(segment
		(start 159.100266 -302.492918)
		(end 159.021526 -302.571658)
		(width 0.16002)
		(layer "In11.Cu")
		(net "M_L_CPU1_SB_DQS_DP<7>")
	)
	(segment
		(start 158.85287 -302.019716)
		(end 159.100266 -302.267112)
		(width 0.16002)
		(layer "In11.Cu")
		(net "M_L_CPU1_SB_DQS_DP<7>")
	)
	(segment
		(start 152.88895 -293.005002)
		(end 152.88895 -296.915586)
		(width 0.16002)
		(layer "In11.Cu")
		(net "M_L_CPU1_SB_DQS_DP<7>")
	)
	(segment
		(start 187.7822 -306.010564)
		(end 188.157358 -305.635406)
		(width 0.16002)
		(layer "In11.Cu")
		(net "M_L_CPU1_SB_DQS_DP<7>")
	)
	(segment
		(start 159.021526 -303.048162)
		(end 161.60877 -305.635406)
		(width 0.16002)
		(layer "In11.Cu")
		(net "M_L_CPU1_SB_DQS_DP<7>")
	)
	(segment
		(start 142.804896 -286.716216)
		(end 142.813278 -286.721042)
		(width 0.09525)
		(layer "In11.Cu")
		(net "M_L_CPU1_SB_DQS_DP<7>")
	)
	(segment
		(start 189.632082 -304.781966)
		(end 190.20409 -304.781966)
		(width 0.16002)
		(layer "In11.Cu")
		(net "M_L_CPU1_SB_DQS_DP<7>")
	)
	(segment
		(start 157.647894 -301.67453)
		(end 158.071566 -302.098202)
		(width 0.16002)
		(layer "In11.Cu")
		(net "M_L_CPU1_SB_DQS_DP<7>")
	)
	(segment
		(start 173.06925 -305.635406)
		(end 173.690534 -305.635406)
		(width 0.16002)
		(layer "In11.Cu")
		(net "M_L_CPU1_SB_DQS_DP<7>")
	)
	(segment
		(start 144.316196 -286.721042)
		(end 144.320514 -286.718502)
		(width 0.09525)
		(layer "In11.Cu")
		(net "M_L_CPU1_SB_DQS_DP<7>")
	)
	(segment
		(start 147.564348 -287.596072)
		(end 147.56384 -287.679384)
		(width 0.09525)
		(layer "In11.Cu")
		(net "M_L_CPU1_SB_DQS_DP<7>")
	)
	(segment
		(start 201.87412 -305.011582)
		(end 202.147932 -305.285394)
		(width 0.16002)
		(layer "In11.Cu")
		(net "M_L_CPU1_SB_DQS_DP<7>")
	)
	(segment
		(start 146.578066 -287.182306)
		(end 147.151852 -287.182306)
		(width 0.09525)
		(layer "In11.Cu")
		(net "M_L_CPU1_SB_DQS_DP<7>")
	)
	(arc
		(start 139.99337 -286.721042)
		(mid 140.274802 -286.796831)
		(end 140.556234 -286.721042)
		(width 0.09525)
		(layer "In11.Cu")
		(net "M_L_CPU1_SB_DQS_DP<7>")
	)
	(arc
		(start 142.813278 -286.721042)
		(mid 143.09471 -286.796831)
		(end 143.376142 -286.721042)
		(width 0.09525)
		(layer "In11.Cu")
		(net "M_L_CPU1_SB_DQS_DP<7>")
	)
	(arc
		(start 143.384524 -286.716216)
		(mid 143.569556 -286.670302)
		(end 143.753332 -286.721042)
		(width 0.09525)
		(layer "In11.Cu")
		(net "M_L_CPU1_SB_DQS_DP<7>")
	)
	(arc
		(start 138.676126 -286.721042)
		(mid 138.859901 -286.67027)
		(end 139.044934 -286.716216)
		(width 0.09525)
		(layer "In11.Cu")
		(net "M_L_CPU1_SB_DQS_DP<7>")
	)
	(arc
		(start 141.873224 -286.721042)
		(mid 142.154656 -286.796831)
		(end 142.436088 -286.721042)
		(width 0.09525)
		(layer "In11.Cu")
		(net "M_L_CPU1_SB_DQS_DP<7>")
	)
	(arc
		(start 140.933424 -286.721042)
		(mid 141.214856 -286.796831)
		(end 141.496288 -286.721042)
		(width 0.09525)
		(layer "In11.Cu")
		(net "M_L_CPU1_SB_DQS_DP<7>")
	)
	(arc
		(start 143.753332 -286.721042)
		(mid 144.034764 -286.796831)
		(end 144.316196 -286.721042)
		(width 0.09525)
		(layer "In11.Cu")
		(net "M_L_CPU1_SB_DQS_DP<7>")
	)
	(arc
		(start 140.564616 -286.716216)
		(mid 140.749648 -286.670302)
		(end 140.933424 -286.721042)
		(width 0.09525)
		(layer "In11.Cu")
		(net "M_L_CPU1_SB_DQS_DP<7>")
	)
	(arc
		(start 142.436088 -286.721042)
		(mid 142.619863 -286.67027)
		(end 142.804896 -286.716216)
		(width 0.09525)
		(layer "In11.Cu")
		(net "M_L_CPU1_SB_DQS_DP<7>")
	)
	(arc
		(start 139.624562 -286.716216)
		(mid 139.809594 -286.670302)
		(end 139.99337 -286.721042)
		(width 0.09525)
		(layer "In11.Cu")
		(net "M_L_CPU1_SB_DQS_DP<7>")
	)
	(arc
		(start 141.496288 -286.721042)
		(mid 141.684756 -286.670365)
		(end 141.873224 -286.721042)
		(width 0.09525)
		(layer "In11.Cu")
		(net "M_L_CPU1_SB_DQS_DP<7>")
	)
	(arc
		(start 144.324578 -286.716216)
		(mid 144.490777 -286.650824)
		(end 144.667986 -286.628586)
		(width 0.09525)
		(layer "In11.Cu")
		(net "M_L_CPU1_SB_DQS_DP<7>")
	)
	(arc
		(start 139.053316 -286.721042)
		(mid 139.334748 -286.796831)
		(end 139.61618 -286.721042)
		(width 0.09525)
		(layer "In11.Cu")
		(net "M_L_CPU1_SB_DQS_DP<7>")
	)
	(arc
		(start 138.199876 -286.76219)
		(mid 138.442618 -286.794975)
		(end 138.676126 -286.721042)
		(width 0.09525)
		(layer "In11.Cu")
		(net "M_L_CPU1_SB_DQS_DP<7>")
	)
	(arc
		(start 138.179556 -286.754062)
		(mid 138.189677 -286.758224)
		(end 138.199876 -286.76219)
		(width 0.09525)
		(layer "In11.Cu")
		(net "M_L_CPU1_SB_DQS_DP<7>")
	)
	(segment
		(start 137.457942 -281.920442)
		(end 137.924794 -282.18638)
		(width 0.12954)
		(layer "F.Cu")
		(net "M_L_CPU1_SB_DQS_DP<6>")
	)
	(segment
		(start 162.183064 -294.41267)
		(end 162.183064 -294.638476)
		(width 0.16002)
		(layer "In11.Cu")
		(net "M_L_CPU1_SB_DQS_DP<6>")
	)
	(segment
		(start 147.895564 -282.120594)
		(end 147.919186 -282.120594)
		(width 0.09525)
		(layer "In11.Cu")
		(net "M_L_CPU1_SB_DQS_DP<6>")
	)
	(segment
		(start 197.748144 -295.431972)
		(end 198.126604 -295.810432)
		(width 0.16002)
		(layer "In11.Cu")
		(net "M_L_CPU1_SB_DQS_DP<6>")
	)
	(segment
		(start 173.690534 -296.285412)
		(end 174.543974 -295.431972)
		(width 0.16002)
		(layer "In11.Cu")
		(net "M_L_CPU1_SB_DQS_DP<6>")
	)
	(segment
		(start 199.437752 -295.810432)
		(end 199.586596 -295.661588)
		(width 0.16002)
		(layer "In11.Cu")
		(net "M_L_CPU1_SB_DQS_DP<6>")
	)
	(segment
		(start 146.275806 -282.061666)
		(end 147.836636 -282.061666)
		(width 0.09525)
		(layer "In11.Cu")
		(net "M_L_CPU1_SB_DQS_DP<6>")
	)
	(segment
		(start 159.508952 -293.141908)
		(end 159.985456 -293.141908)
		(width 0.16002)
		(layer "In11.Cu")
		(net "M_L_CPU1_SB_DQS_DP<6>")
	)
	(segment
		(start 185.361834 -295.810432)
		(end 186.211972 -296.66057)
		(width 0.16002)
		(layer "In11.Cu")
		(net "M_L_CPU1_SB_DQS_DP<6>")
	)
	(segment
		(start 160.562036 -292.791642)
		(end 160.809432 -293.039038)
		(width 0.16002)
		(layer "In11.Cu")
		(net "M_L_CPU1_SB_DQS_DP<6>")
	)
	(segment
		(start 158.50743 -292.140386)
		(end 159.508952 -293.141908)
		(width 0.16002)
		(layer "In11.Cu")
		(net "M_L_CPU1_SB_DQS_DP<6>")
	)
	(segment
		(start 182.660036 -295.431972)
		(end 183.038496 -295.810432)
		(width 0.16002)
		(layer "In11.Cu")
		(net "M_L_CPU1_SB_DQS_DP<6>")
	)
	(segment
		(start 161.832544 -295.4655)
		(end 162.652456 -296.285412)
		(width 0.16002)
		(layer "In11.Cu")
		(net "M_L_CPU1_SB_DQS_DP<6>")
	)
	(segment
		(start 199.586596 -295.661588)
		(end 201.87412 -295.661588)
		(width 0.16002)
		(layer "In11.Cu")
		(net "M_L_CPU1_SB_DQS_DP<6>")
	)
	(segment
		(start 160.809432 -293.039038)
		(end 160.809432 -293.264844)
		(width 0.16002)
		(layer "In11.Cu")
		(net "M_L_CPU1_SB_DQS_DP<6>")
	)
	(segment
		(start 172.694092 -296.66057)
		(end 173.06925 -296.285412)
		(width 0.16002)
		(layer "In11.Cu")
		(net "M_L_CPU1_SB_DQS_DP<6>")
	)
	(segment
		(start 181.234588 -296.285412)
		(end 182.088028 -295.431972)
		(width 0.16002)
		(layer "In11.Cu")
		(net "M_L_CPU1_SB_DQS_DP<6>")
	)
	(segment
		(start 196.322696 -296.285412)
		(end 197.176136 -295.431972)
		(width 0.16002)
		(layer "In11.Cu")
		(net "M_L_CPU1_SB_DQS_DP<6>")
	)
	(segment
		(start 186.211972 -296.66057)
		(end 187.7822 -296.66057)
		(width 0.16002)
		(layer "In11.Cu")
		(net "M_L_CPU1_SB_DQS_DP<6>")
	)
	(segment
		(start 170.847004 -296.120566)
		(end 171.387008 -296.66057)
		(width 0.16002)
		(layer "In11.Cu")
		(net "M_L_CPU1_SB_DQS_DP<6>")
	)
	(segment
		(start 173.06925 -296.285412)
		(end 173.690534 -296.285412)
		(width 0.16002)
		(layer "In11.Cu")
		(net "M_L_CPU1_SB_DQS_DP<6>")
	)
	(segment
		(start 142.804896 -281.856434)
		(end 142.813278 -281.86126)
		(width 0.09525)
		(layer "In11.Cu")
		(net "M_L_CPU1_SB_DQS_DP<6>")
	)
	(segment
		(start 178.667918 -296.66057)
		(end 180.238146 -296.66057)
		(width 0.16002)
		(layer "In11.Cu")
		(net "M_L_CPU1_SB_DQS_DP<6>")
	)
	(segment
		(start 147.919186 -282.120594)
		(end 149.950678 -282.120594)
		(width 0.16002)
		(layer "In11.Cu")
		(net "M_L_CPU1_SB_DQS_DP<6>")
	)
	(segment
		(start 147.836636 -282.061666)
		(end 147.895564 -282.120594)
		(width 0.09525)
		(layer "In11.Cu")
		(net "M_L_CPU1_SB_DQS_DP<6>")
	)
	(segment
		(start 201.87412 -295.661588)
		(end 202.147932 -295.9354)
		(width 0.16002)
		(layer "In11.Cu")
		(net "M_L_CPU1_SB_DQS_DP<6>")
	)
	(segment
		(start 188.157358 -296.285412)
		(end 188.778642 -296.285412)
		(width 0.16002)
		(layer "In11.Cu")
		(net "M_L_CPU1_SB_DQS_DP<6>")
	)
	(segment
		(start 160.458912 -294.091868)
		(end 160.882584 -294.51554)
		(width 0.16002)
		(layer "In11.Cu")
		(net "M_L_CPU1_SB_DQS_DP<6>")
	)
	(segment
		(start 146.024092 -281.809952)
		(end 146.275806 -282.061666)
		(width 0.09525)
		(layer "In11.Cu")
		(net "M_L_CPU1_SB_DQS_DP<6>")
	)
	(segment
		(start 161.935668 -294.165274)
		(end 162.183064 -294.41267)
		(width 0.16002)
		(layer "In11.Cu")
		(net "M_L_CPU1_SB_DQS_DP<6>")
	)
	(segment
		(start 143.376142 -281.86126)
		(end 143.384524 -281.856434)
		(width 0.09525)
		(layer "In11.Cu")
		(net "M_L_CPU1_SB_DQS_DP<6>")
	)
	(segment
		(start 175.115982 -295.431972)
		(end 175.494442 -295.810432)
		(width 0.16002)
		(layer "In11.Cu")
		(net "M_L_CPU1_SB_DQS_DP<6>")
	)
	(segment
		(start 160.882584 -294.51554)
		(end 161.359088 -294.51554)
		(width 0.16002)
		(layer "In11.Cu")
		(net "M_L_CPU1_SB_DQS_DP<6>")
	)
	(segment
		(start 137.924794 -282.18638)
		(end 138.078718 -281.92095)
		(width 0.09525)
		(layer "In11.Cu")
		(net "M_L_CPU1_SB_DQS_DP<6>")
	)
	(segment
		(start 161.359088 -294.51554)
		(end 161.709608 -294.165274)
		(width 0.16002)
		(layer "In11.Cu")
		(net "M_L_CPU1_SB_DQS_DP<6>")
	)
	(segment
		(start 180.613304 -296.285412)
		(end 181.234588 -296.285412)
		(width 0.16002)
		(layer "In11.Cu")
		(net "M_L_CPU1_SB_DQS_DP<6>")
	)
	(segment
		(start 159.985456 -293.141908)
		(end 160.335976 -292.791642)
		(width 0.16002)
		(layer "In11.Cu")
		(net "M_L_CPU1_SB_DQS_DP<6>")
	)
	(segment
		(start 139.61618 -281.86126)
		(end 139.624562 -281.856434)
		(width 0.09525)
		(layer "In11.Cu")
		(net "M_L_CPU1_SB_DQS_DP<6>")
	)
	(segment
		(start 187.7822 -296.66057)
		(end 188.157358 -296.285412)
		(width 0.16002)
		(layer "In11.Cu")
		(net "M_L_CPU1_SB_DQS_DP<6>")
	)
	(segment
		(start 162.183064 -294.638476)
		(end 161.832544 -294.988742)
		(width 0.16002)
		(layer "In11.Cu")
		(net "M_L_CPU1_SB_DQS_DP<6>")
	)
	(segment
		(start 182.088028 -295.431972)
		(end 182.660036 -295.431972)
		(width 0.16002)
		(layer "In11.Cu")
		(net "M_L_CPU1_SB_DQS_DP<6>")
	)
	(segment
		(start 166.99992 -295.431972)
		(end 167.571928 -295.431972)
		(width 0.16002)
		(layer "In11.Cu")
		(net "M_L_CPU1_SB_DQS_DP<6>")
	)
	(segment
		(start 139.044934 -281.856434)
		(end 139.053316 -281.86126)
		(width 0.09525)
		(layer "In11.Cu")
		(net "M_L_CPU1_SB_DQS_DP<6>")
	)
	(segment
		(start 175.494442 -295.810432)
		(end 177.81778 -295.810432)
		(width 0.16002)
		(layer "In11.Cu")
		(net "M_L_CPU1_SB_DQS_DP<6>")
	)
	(segment
		(start 192.905888 -295.810432)
		(end 193.756026 -296.66057)
		(width 0.16002)
		(layer "In11.Cu")
		(net "M_L_CPU1_SB_DQS_DP<6>")
	)
	(segment
		(start 144.504664 -281.809952)
		(end 146.024092 -281.809952)
		(width 0.09525)
		(layer "In11.Cu")
		(net "M_L_CPU1_SB_DQS_DP<6>")
	)
	(segment
		(start 189.632082 -295.431972)
		(end 190.20409 -295.431972)
		(width 0.16002)
		(layer "In11.Cu")
		(net "M_L_CPU1_SB_DQS_DP<6>")
	)
	(segment
		(start 190.20409 -295.431972)
		(end 190.58255 -295.810432)
		(width 0.16002)
		(layer "In11.Cu")
		(net "M_L_CPU1_SB_DQS_DP<6>")
	)
	(segment
		(start 193.756026 -296.66057)
		(end 195.326254 -296.66057)
		(width 0.16002)
		(layer "In11.Cu")
		(net "M_L_CPU1_SB_DQS_DP<6>")
	)
	(segment
		(start 171.387008 -296.66057)
		(end 172.694092 -296.66057)
		(width 0.16002)
		(layer "In11.Cu")
		(net "M_L_CPU1_SB_DQS_DP<6>")
	)
	(segment
		(start 161.709608 -294.165274)
		(end 161.935668 -294.165274)
		(width 0.16002)
		(layer "In11.Cu")
		(net "M_L_CPU1_SB_DQS_DP<6>")
	)
	(segment
		(start 149.950678 -282.120594)
		(end 158.50743 -290.677346)
		(width 0.16002)
		(layer "In11.Cu")
		(net "M_L_CPU1_SB_DQS_DP<6>")
	)
	(segment
		(start 188.778642 -296.285412)
		(end 189.632082 -295.431972)
		(width 0.16002)
		(layer "In11.Cu")
		(net "M_L_CPU1_SB_DQS_DP<6>")
	)
	(segment
		(start 190.58255 -295.810432)
		(end 192.905888 -295.810432)
		(width 0.16002)
		(layer "In11.Cu")
		(net "M_L_CPU1_SB_DQS_DP<6>")
	)
	(segment
		(start 140.556234 -281.86126)
		(end 140.564616 -281.856434)
		(width 0.09525)
		(layer "In11.Cu")
		(net "M_L_CPU1_SB_DQS_DP<6>")
	)
	(segment
		(start 138.078718 -281.92095)
		(end 138.179556 -281.89428)
		(width 0.09525)
		(layer "In11.Cu")
		(net "M_L_CPU1_SB_DQS_DP<6>")
	)
	(segment
		(start 183.038496 -295.810432)
		(end 185.361834 -295.810432)
		(width 0.16002)
		(layer "In11.Cu")
		(net "M_L_CPU1_SB_DQS_DP<6>")
	)
	(segment
		(start 195.326254 -296.66057)
		(end 195.701412 -296.285412)
		(width 0.16002)
		(layer "In11.Cu")
		(net "M_L_CPU1_SB_DQS_DP<6>")
	)
	(segment
		(start 174.543974 -295.431972)
		(end 175.115982 -295.431972)
		(width 0.16002)
		(layer "In11.Cu")
		(net "M_L_CPU1_SB_DQS_DP<6>")
	)
	(segment
		(start 162.652456 -296.285412)
		(end 166.14648 -296.285412)
		(width 0.16002)
		(layer "In11.Cu")
		(net "M_L_CPU1_SB_DQS_DP<6>")
	)
	(segment
		(start 166.14648 -296.285412)
		(end 166.99992 -295.431972)
		(width 0.16002)
		(layer "In11.Cu")
		(net "M_L_CPU1_SB_DQS_DP<6>")
	)
	(segment
		(start 197.176136 -295.431972)
		(end 197.748144 -295.431972)
		(width 0.16002)
		(layer "In11.Cu")
		(net "M_L_CPU1_SB_DQS_DP<6>")
	)
	(segment
		(start 161.832544 -294.988742)
		(end 161.832544 -295.4655)
		(width 0.16002)
		(layer "In11.Cu")
		(net "M_L_CPU1_SB_DQS_DP<6>")
	)
	(segment
		(start 160.335976 -292.791642)
		(end 160.562036 -292.791642)
		(width 0.16002)
		(layer "In11.Cu")
		(net "M_L_CPU1_SB_DQS_DP<6>")
	)
	(segment
		(start 167.571928 -295.431972)
		(end 168.260522 -296.120566)
		(width 0.16002)
		(layer "In11.Cu")
		(net "M_L_CPU1_SB_DQS_DP<6>")
	)
	(segment
		(start 168.260522 -296.120566)
		(end 170.847004 -296.120566)
		(width 0.16002)
		(layer "In11.Cu")
		(net "M_L_CPU1_SB_DQS_DP<6>")
	)
	(segment
		(start 158.50743 -290.677346)
		(end 158.50743 -292.140386)
		(width 0.16002)
		(layer "In11.Cu")
		(net "M_L_CPU1_SB_DQS_DP<6>")
	)
	(segment
		(start 195.701412 -296.285412)
		(end 196.322696 -296.285412)
		(width 0.16002)
		(layer "In11.Cu")
		(net "M_L_CPU1_SB_DQS_DP<6>")
	)
	(segment
		(start 198.126604 -295.810432)
		(end 199.437752 -295.810432)
		(width 0.16002)
		(layer "In11.Cu")
		(net "M_L_CPU1_SB_DQS_DP<6>")
	)
	(segment
		(start 160.458912 -293.61511)
		(end 160.458912 -294.091868)
		(width 0.16002)
		(layer "In11.Cu")
		(net "M_L_CPU1_SB_DQS_DP<6>")
	)
	(segment
		(start 177.81778 -295.810432)
		(end 178.667918 -296.66057)
		(width 0.16002)
		(layer "In11.Cu")
		(net "M_L_CPU1_SB_DQS_DP<6>")
	)
	(segment
		(start 180.238146 -296.66057)
		(end 180.613304 -296.285412)
		(width 0.16002)
		(layer "In11.Cu")
		(net "M_L_CPU1_SB_DQS_DP<6>")
	)
	(segment
		(start 160.809432 -293.264844)
		(end 160.458912 -293.61511)
		(width 0.16002)
		(layer "In11.Cu")
		(net "M_L_CPU1_SB_DQS_DP<6>")
	)
	(arc
		(start 142.813278 -281.86126)
		(mid 143.09471 -281.937015)
		(end 143.376142 -281.86126)
		(width 0.09525)
		(layer "In11.Cu")
		(net "M_L_CPU1_SB_DQS_DP<6>")
	)
	(arc
		(start 143.384524 -281.856434)
		(mid 143.569556 -281.81052)
		(end 143.753332 -281.86126)
		(width 0.09525)
		(layer "In11.Cu")
		(net "M_L_CPU1_SB_DQS_DP<6>")
	)
	(arc
		(start 140.933424 -281.86126)
		(mid 141.214856 -281.937015)
		(end 141.496288 -281.86126)
		(width 0.09525)
		(layer "In11.Cu")
		(net "M_L_CPU1_SB_DQS_DP<6>")
	)
	(arc
		(start 141.873224 -281.86126)
		(mid 142.154656 -281.937015)
		(end 142.436088 -281.86126)
		(width 0.09525)
		(layer "In11.Cu")
		(net "M_L_CPU1_SB_DQS_DP<6>")
	)
	(arc
		(start 143.753332 -281.86126)
		(mid 144.034764 -281.937015)
		(end 144.316196 -281.86126)
		(width 0.09525)
		(layer "In11.Cu")
		(net "M_L_CPU1_SB_DQS_DP<6>")
	)
	(arc
		(start 141.496288 -281.86126)
		(mid 141.684756 -281.810583)
		(end 141.873224 -281.86126)
		(width 0.09525)
		(layer "In11.Cu")
		(net "M_L_CPU1_SB_DQS_DP<6>")
	)
	(arc
		(start 142.436088 -281.86126)
		(mid 142.619863 -281.810488)
		(end 142.804896 -281.856434)
		(width 0.09525)
		(layer "In11.Cu")
		(net "M_L_CPU1_SB_DQS_DP<6>")
	)
	(arc
		(start 138.676126 -281.86126)
		(mid 138.859901 -281.810488)
		(end 139.044934 -281.856434)
		(width 0.09525)
		(layer "In11.Cu")
		(net "M_L_CPU1_SB_DQS_DP<6>")
	)
	(arc
		(start 139.053316 -281.86126)
		(mid 139.334748 -281.937015)
		(end 139.61618 -281.86126)
		(width 0.09525)
		(layer "In11.Cu")
		(net "M_L_CPU1_SB_DQS_DP<6>")
	)
	(arc
		(start 140.564616 -281.856434)
		(mid 140.749648 -281.81052)
		(end 140.933424 -281.86126)
		(width 0.09525)
		(layer "In11.Cu")
		(net "M_L_CPU1_SB_DQS_DP<6>")
	)
	(arc
		(start 138.199876 -281.902154)
		(mid 138.442588 -281.935037)
		(end 138.676126 -281.86126)
		(width 0.09525)
		(layer "In11.Cu")
		(net "M_L_CPU1_SB_DQS_DP<6>")
	)
	(arc
		(start 139.624562 -281.856434)
		(mid 139.809594 -281.81052)
		(end 139.99337 -281.86126)
		(width 0.09525)
		(layer "In11.Cu")
		(net "M_L_CPU1_SB_DQS_DP<6>")
	)
	(arc
		(start 144.316196 -281.86126)
		(mid 144.407044 -281.823166)
		(end 144.504664 -281.809952)
		(width 0.09525)
		(layer "In11.Cu")
		(net "M_L_CPU1_SB_DQS_DP<6>")
	)
	(arc
		(start 138.179556 -281.89428)
		(mid 138.189678 -281.898315)
		(end 138.199876 -281.902154)
		(width 0.09525)
		(layer "In11.Cu")
		(net "M_L_CPU1_SB_DQS_DP<6>")
	)
	(arc
		(start 139.99337 -281.86126)
		(mid 140.274802 -281.937015)
		(end 140.556234 -281.86126)
		(width 0.09525)
		(layer "In11.Cu")
		(net "M_L_CPU1_SB_DQS_DP<6>")
	)
	(segment
		(start 137.457942 -277.060406)
		(end 137.924794 -277.326344)
		(width 0.12954)
		(layer "F.Cu")
		(net "M_L_CPU1_SB_DQS_DP<5>")
	)
	(segment
		(start 174.543974 -286.081978)
		(end 175.115982 -286.081978)
		(width 0.16002)
		(layer "In11.Cu")
		(net "M_L_CPU1_SB_DQS_DP<5>")
	)
	(segment
		(start 147.143216 -275.782532)
		(end 147.420076 -276.059392)
		(width 0.09525)
		(layer "In11.Cu")
		(net "M_L_CPU1_SB_DQS_DP<5>")
	)
	(segment
		(start 147.008088 -275.782532)
		(end 147.143216 -275.782532)
		(width 0.09525)
		(layer "In11.Cu")
		(net "M_L_CPU1_SB_DQS_DP<5>")
	)
	(segment
		(start 143.376142 -277.001224)
		(end 143.384524 -276.996398)
		(width 0.09525)
		(layer "In11.Cu")
		(net "M_L_CPU1_SB_DQS_DP<5>")
	)
	(segment
		(start 139.61618 -277.001224)
		(end 139.624562 -276.996398)
		(width 0.09525)
		(layer "In11.Cu")
		(net "M_L_CPU1_SB_DQS_DP<5>")
	)
	(segment
		(start 201.87412 -286.311594)
		(end 202.147932 -286.585406)
		(width 0.16002)
		(layer "In11.Cu")
		(net "M_L_CPU1_SB_DQS_DP<5>")
	)
	(segment
		(start 137.924794 -277.326344)
		(end 138.078718 -277.060914)
		(width 0.09525)
		(layer "In11.Cu")
		(net "M_L_CPU1_SB_DQS_DP<5>")
	)
	(segment
		(start 164.675566 -286.161226)
		(end 164.675566 -286.59836)
		(width 0.16002)
		(layer "In11.Cu")
		(net "M_L_CPU1_SB_DQS_DP<5>")
	)
	(segment
		(start 145.444972 -276.949916)
		(end 145.840704 -276.949916)
		(width 0.09525)
		(layer "In11.Cu")
		(net "M_L_CPU1_SB_DQS_DP<5>")
	)
	(segment
		(start 195.326254 -287.310576)
		(end 195.701412 -286.935418)
		(width 0.16002)
		(layer "In11.Cu")
		(net "M_L_CPU1_SB_DQS_DP<5>")
	)
	(segment
		(start 167.88765 -285.645606)
		(end 168.04767 -285.485586)
		(width 0.16002)
		(layer "In11.Cu")
		(net "M_L_CPU1_SB_DQS_DP<5>")
	)
	(segment
		(start 139.044934 -276.996398)
		(end 139.053316 -277.001224)
		(width 0.09525)
		(layer "In11.Cu")
		(net "M_L_CPU1_SB_DQS_DP<5>")
	)
	(segment
		(start 147.420076 -276.059392)
		(end 147.836636 -276.059392)
		(width 0.09525)
		(layer "In11.Cu")
		(net "M_L_CPU1_SB_DQS_DP<5>")
	)
	(segment
		(start 147.895564 -276.11832)
		(end 147.919186 -276.11832)
		(width 0.09525)
		(layer "In11.Cu")
		(net "M_L_CPU1_SB_DQS_DP<5>")
	)
	(segment
		(start 168.555924 -285.645606)
		(end 168.555924 -285.798768)
		(width 0.16002)
		(layer "In11.Cu")
		(net "M_L_CPU1_SB_DQS_DP<5>")
	)
	(segment
		(start 138.078718 -277.060914)
		(end 138.179556 -277.034244)
		(width 0.09525)
		(layer "In11.Cu")
		(net "M_L_CPU1_SB_DQS_DP<5>")
	)
	(segment
		(start 165.012624 -286.935418)
		(end 166.14648 -286.935418)
		(width 0.16002)
		(layer "In11.Cu")
		(net "M_L_CPU1_SB_DQS_DP<5>")
	)
	(segment
		(start 197.176136 -286.081978)
		(end 197.748144 -286.081978)
		(width 0.16002)
		(layer "In11.Cu")
		(net "M_L_CPU1_SB_DQS_DP<5>")
	)
	(segment
		(start 145.840704 -276.949916)
		(end 147.008088 -275.782532)
		(width 0.09525)
		(layer "In11.Cu")
		(net "M_L_CPU1_SB_DQS_DP<5>")
	)
	(segment
		(start 187.7822 -287.310576)
		(end 188.157358 -286.935418)
		(width 0.16002)
		(layer "In11.Cu")
		(net "M_L_CPU1_SB_DQS_DP<5>")
	)
	(segment
		(start 164.675566 -286.59836)
		(end 165.012624 -286.935418)
		(width 0.16002)
		(layer "In11.Cu")
		(net "M_L_CPU1_SB_DQS_DP<5>")
	)
	(segment
		(start 167.88765 -285.798768)
		(end 167.88765 -285.645606)
		(width 0.16002)
		(layer "In11.Cu")
		(net "M_L_CPU1_SB_DQS_DP<5>")
	)
	(segment
		(start 192.905888 -286.460438)
		(end 193.756026 -287.310576)
		(width 0.16002)
		(layer "In11.Cu")
		(net "M_L_CPU1_SB_DQS_DP<5>")
	)
	(segment
		(start 193.756026 -287.310576)
		(end 195.326254 -287.310576)
		(width 0.16002)
		(layer "In11.Cu")
		(net "M_L_CPU1_SB_DQS_DP<5>")
	)
	(segment
		(start 180.238146 -287.310576)
		(end 180.613304 -286.935418)
		(width 0.16002)
		(layer "In11.Cu")
		(net "M_L_CPU1_SB_DQS_DP<5>")
	)
	(segment
		(start 188.157358 -286.935418)
		(end 188.778642 -286.935418)
		(width 0.16002)
		(layer "In11.Cu")
		(net "M_L_CPU1_SB_DQS_DP<5>")
	)
	(segment
		(start 163.670234 -286.935418)
		(end 164.007292 -286.59836)
		(width 0.16002)
		(layer "In11.Cu")
		(net "M_L_CPU1_SB_DQS_DP<5>")
	)
	(segment
		(start 199.586596 -286.311594)
		(end 201.87412 -286.311594)
		(width 0.16002)
		(layer "In11.Cu")
		(net "M_L_CPU1_SB_DQS_DP<5>")
	)
	(segment
		(start 173.690534 -286.935418)
		(end 174.543974 -286.081978)
		(width 0.16002)
		(layer "In11.Cu")
		(net "M_L_CPU1_SB_DQS_DP<5>")
	)
	(segment
		(start 168.892982 -286.135826)
		(end 169.426128 -286.135826)
		(width 0.16002)
		(layer "In11.Cu")
		(net "M_L_CPU1_SB_DQS_DP<5>")
	)
	(segment
		(start 143.753332 -277.001224)
		(end 143.763746 -277.00732)
		(width 0.09525)
		(layer "In11.Cu")
		(net "M_L_CPU1_SB_DQS_DP<5>")
	)
	(segment
		(start 152.355296 -276.11832)
		(end 163.172394 -286.935418)
		(width 0.16002)
		(layer "In11.Cu")
		(net "M_L_CPU1_SB_DQS_DP<5>")
	)
	(segment
		(start 180.613304 -286.935418)
		(end 181.234588 -286.935418)
		(width 0.16002)
		(layer "In11.Cu")
		(net "M_L_CPU1_SB_DQS_DP<5>")
	)
	(segment
		(start 182.088028 -286.081978)
		(end 182.660036 -286.081978)
		(width 0.16002)
		(layer "In11.Cu")
		(net "M_L_CPU1_SB_DQS_DP<5>")
	)
	(segment
		(start 170.508422 -286.460438)
		(end 171.35856 -287.310576)
		(width 0.16002)
		(layer "In11.Cu")
		(net "M_L_CPU1_SB_DQS_DP<5>")
	)
	(segment
		(start 142.804896 -276.996398)
		(end 142.813278 -277.001224)
		(width 0.09525)
		(layer "In11.Cu")
		(net "M_L_CPU1_SB_DQS_DP<5>")
	)
	(segment
		(start 172.694092 -287.310576)
		(end 173.06925 -286.935418)
		(width 0.16002)
		(layer "In11.Cu")
		(net "M_L_CPU1_SB_DQS_DP<5>")
	)
	(segment
		(start 190.58255 -286.460438)
		(end 192.905888 -286.460438)
		(width 0.16002)
		(layer "In11.Cu")
		(net "M_L_CPU1_SB_DQS_DP<5>")
	)
	(segment
		(start 175.115982 -286.081978)
		(end 175.494442 -286.460438)
		(width 0.16002)
		(layer "In11.Cu")
		(net "M_L_CPU1_SB_DQS_DP<5>")
	)
	(segment
		(start 175.494442 -286.460438)
		(end 177.81778 -286.460438)
		(width 0.16002)
		(layer "In11.Cu")
		(net "M_L_CPU1_SB_DQS_DP<5>")
	)
	(segment
		(start 140.556234 -277.001224)
		(end 140.564616 -276.996398)
		(width 0.09525)
		(layer "In11.Cu")
		(net "M_L_CPU1_SB_DQS_DP<5>")
	)
	(segment
		(start 169.75074 -286.460438)
		(end 170.508422 -286.460438)
		(width 0.16002)
		(layer "In11.Cu")
		(net "M_L_CPU1_SB_DQS_DP<5>")
	)
	(segment
		(start 171.35856 -287.310576)
		(end 172.694092 -287.310576)
		(width 0.16002)
		(layer "In11.Cu")
		(net "M_L_CPU1_SB_DQS_DP<5>")
	)
	(segment
		(start 195.701412 -286.935418)
		(end 196.322696 -286.935418)
		(width 0.16002)
		(layer "In11.Cu")
		(net "M_L_CPU1_SB_DQS_DP<5>")
	)
	(segment
		(start 186.211972 -287.310576)
		(end 187.7822 -287.310576)
		(width 0.16002)
		(layer "In11.Cu")
		(net "M_L_CPU1_SB_DQS_DP<5>")
	)
	(segment
		(start 166.946072 -286.135826)
		(end 167.550592 -286.135826)
		(width 0.16002)
		(layer "In11.Cu")
		(net "M_L_CPU1_SB_DQS_DP<5>")
	)
	(segment
		(start 164.167312 -286.001206)
		(end 164.515546 -286.001206)
		(width 0.16002)
		(layer "In11.Cu")
		(net "M_L_CPU1_SB_DQS_DP<5>")
	)
	(segment
		(start 183.038496 -286.460438)
		(end 185.361834 -286.460438)
		(width 0.16002)
		(layer "In11.Cu")
		(net "M_L_CPU1_SB_DQS_DP<5>")
	)
	(segment
		(start 166.14648 -286.935418)
		(end 166.946072 -286.135826)
		(width 0.16002)
		(layer "In11.Cu")
		(net "M_L_CPU1_SB_DQS_DP<5>")
	)
	(segment
		(start 188.778642 -286.935418)
		(end 189.632082 -286.081978)
		(width 0.16002)
		(layer "In11.Cu")
		(net "M_L_CPU1_SB_DQS_DP<5>")
	)
	(segment
		(start 164.007292 -286.59836)
		(end 164.007292 -286.161226)
		(width 0.16002)
		(layer "In11.Cu")
		(net "M_L_CPU1_SB_DQS_DP<5>")
	)
	(segment
		(start 181.234588 -286.935418)
		(end 182.088028 -286.081978)
		(width 0.16002)
		(layer "In11.Cu")
		(net "M_L_CPU1_SB_DQS_DP<5>")
	)
	(segment
		(start 189.632082 -286.081978)
		(end 190.20409 -286.081978)
		(width 0.16002)
		(layer "In11.Cu")
		(net "M_L_CPU1_SB_DQS_DP<5>")
	)
	(segment
		(start 198.126604 -286.460438)
		(end 199.437752 -286.460438)
		(width 0.16002)
		(layer "In11.Cu")
		(net "M_L_CPU1_SB_DQS_DP<5>")
	)
	(segment
		(start 199.437752 -286.460438)
		(end 199.586596 -286.311594)
		(width 0.16002)
		(layer "In11.Cu")
		(net "M_L_CPU1_SB_DQS_DP<5>")
	)
	(segment
		(start 145.24609 -277.00732)
		(end 145.256504 -277.001224)
		(width 0.09525)
		(layer "In11.Cu")
		(net "M_L_CPU1_SB_DQS_DP<5>")
	)
	(segment
		(start 185.361834 -286.460438)
		(end 186.211972 -287.310576)
		(width 0.16002)
		(layer "In11.Cu")
		(net "M_L_CPU1_SB_DQS_DP<5>")
	)
	(segment
		(start 163.172394 -286.935418)
		(end 163.670234 -286.935418)
		(width 0.16002)
		(layer "In11.Cu")
		(net "M_L_CPU1_SB_DQS_DP<5>")
	)
	(segment
		(start 173.06925 -286.935418)
		(end 173.690534 -286.935418)
		(width 0.16002)
		(layer "In11.Cu")
		(net "M_L_CPU1_SB_DQS_DP<5>")
	)
	(segment
		(start 178.667918 -287.310576)
		(end 180.238146 -287.310576)
		(width 0.16002)
		(layer "In11.Cu")
		(net "M_L_CPU1_SB_DQS_DP<5>")
	)
	(segment
		(start 168.395904 -285.485586)
		(end 168.555924 -285.645606)
		(width 0.16002)
		(layer "In11.Cu")
		(net "M_L_CPU1_SB_DQS_DP<5>")
	)
	(segment
		(start 164.515546 -286.001206)
		(end 164.675566 -286.161226)
		(width 0.16002)
		(layer "In11.Cu")
		(net "M_L_CPU1_SB_DQS_DP<5>")
	)
	(segment
		(start 177.81778 -286.460438)
		(end 178.667918 -287.310576)
		(width 0.16002)
		(layer "In11.Cu")
		(net "M_L_CPU1_SB_DQS_DP<5>")
	)
	(segment
		(start 197.748144 -286.081978)
		(end 198.126604 -286.460438)
		(width 0.16002)
		(layer "In11.Cu")
		(net "M_L_CPU1_SB_DQS_DP<5>")
	)
	(segment
		(start 147.919186 -276.11832)
		(end 152.355296 -276.11832)
		(width 0.16002)
		(layer "In11.Cu")
		(net "M_L_CPU1_SB_DQS_DP<5>")
	)
	(segment
		(start 182.660036 -286.081978)
		(end 183.038496 -286.460438)
		(width 0.16002)
		(layer "In11.Cu")
		(net "M_L_CPU1_SB_DQS_DP<5>")
	)
	(segment
		(start 164.007292 -286.161226)
		(end 164.167312 -286.001206)
		(width 0.16002)
		(layer "In11.Cu")
		(net "M_L_CPU1_SB_DQS_DP<5>")
	)
	(segment
		(start 168.04767 -285.485586)
		(end 168.395904 -285.485586)
		(width 0.16002)
		(layer "In11.Cu")
		(net "M_L_CPU1_SB_DQS_DP<5>")
	)
	(segment
		(start 190.20409 -286.081978)
		(end 190.58255 -286.460438)
		(width 0.16002)
		(layer "In11.Cu")
		(net "M_L_CPU1_SB_DQS_DP<5>")
	)
	(segment
		(start 196.322696 -286.935418)
		(end 197.176136 -286.081978)
		(width 0.16002)
		(layer "In11.Cu")
		(net "M_L_CPU1_SB_DQS_DP<5>")
	)
	(segment
		(start 147.836636 -276.059392)
		(end 147.895564 -276.11832)
		(width 0.09525)
		(layer "In11.Cu")
		(net "M_L_CPU1_SB_DQS_DP<5>")
	)
	(segment
		(start 167.550592 -286.135826)
		(end 167.88765 -285.798768)
		(width 0.16002)
		(layer "In11.Cu")
		(net "M_L_CPU1_SB_DQS_DP<5>")
	)
	(segment
		(start 169.426128 -286.135826)
		(end 169.75074 -286.460438)
		(width 0.16002)
		(layer "In11.Cu")
		(net "M_L_CPU1_SB_DQS_DP<5>")
	)
	(segment
		(start 168.555924 -285.798768)
		(end 168.892982 -286.135826)
		(width 0.16002)
		(layer "In11.Cu")
		(net "M_L_CPU1_SB_DQS_DP<5>")
	)
	(arc
		(start 138.676126 -277.001224)
		(mid 138.859901 -276.950452)
		(end 139.044934 -276.996398)
		(width 0.09525)
		(layer "In11.Cu")
		(net "M_L_CPU1_SB_DQS_DP<5>")
	)
	(arc
		(start 140.933424 -277.001224)
		(mid 141.214856 -277.076979)
		(end 141.496288 -277.001224)
		(width 0.09525)
		(layer "In11.Cu")
		(net "M_L_CPU1_SB_DQS_DP<5>")
	)
	(arc
		(start 140.564616 -276.996398)
		(mid 140.749648 -276.950484)
		(end 140.933424 -277.001224)
		(width 0.09525)
		(layer "In11.Cu")
		(net "M_L_CPU1_SB_DQS_DP<5>")
	)
	(arc
		(start 141.496288 -277.001224)
		(mid 141.684756 -276.950547)
		(end 141.873224 -277.001224)
		(width 0.09525)
		(layer "In11.Cu")
		(net "M_L_CPU1_SB_DQS_DP<5>")
	)
	(arc
		(start 143.763746 -277.00732)
		(mid 144.040908 -277.07712)
		(end 144.31645 -277.001224)
		(width 0.09525)
		(layer "In11.Cu")
		(net "M_L_CPU1_SB_DQS_DP<5>")
	)
	(arc
		(start 139.99337 -277.001224)
		(mid 140.274802 -277.076979)
		(end 140.556234 -277.001224)
		(width 0.09525)
		(layer "In11.Cu")
		(net "M_L_CPU1_SB_DQS_DP<5>")
	)
	(arc
		(start 144.31645 -277.001224)
		(mid 144.505172 -276.95042)
		(end 144.693894 -277.001224)
		(width 0.09525)
		(layer "In11.Cu")
		(net "M_L_CPU1_SB_DQS_DP<5>")
	)
	(arc
		(start 143.384524 -276.996398)
		(mid 143.569556 -276.950484)
		(end 143.753332 -277.001224)
		(width 0.09525)
		(layer "In11.Cu")
		(net "M_L_CPU1_SB_DQS_DP<5>")
	)
	(arc
		(start 144.693894 -277.001224)
		(mid 144.969183 -277.076945)
		(end 145.24609 -277.00732)
		(width 0.09525)
		(layer "In11.Cu")
		(net "M_L_CPU1_SB_DQS_DP<5>")
	)
	(arc
		(start 142.436088 -277.001224)
		(mid 142.619863 -276.950452)
		(end 142.804896 -276.996398)
		(width 0.09525)
		(layer "In11.Cu")
		(net "M_L_CPU1_SB_DQS_DP<5>")
	)
	(arc
		(start 138.199876 -277.042118)
		(mid 138.442588 -277.075001)
		(end 138.676126 -277.001224)
		(width 0.09525)
		(layer "In11.Cu")
		(net "M_L_CPU1_SB_DQS_DP<5>")
	)
	(arc
		(start 139.053316 -277.001224)
		(mid 139.334748 -277.076979)
		(end 139.61618 -277.001224)
		(width 0.09525)
		(layer "In11.Cu")
		(net "M_L_CPU1_SB_DQS_DP<5>")
	)
	(arc
		(start 145.256504 -277.001224)
		(mid 145.347343 -276.963079)
		(end 145.444972 -276.949916)
		(width 0.09525)
		(layer "In11.Cu")
		(net "M_L_CPU1_SB_DQS_DP<5>")
	)
	(arc
		(start 141.873224 -277.001224)
		(mid 142.154656 -277.076979)
		(end 142.436088 -277.001224)
		(width 0.09525)
		(layer "In11.Cu")
		(net "M_L_CPU1_SB_DQS_DP<5>")
	)
	(arc
		(start 138.179556 -277.034244)
		(mid 138.189678 -277.038279)
		(end 138.199876 -277.042118)
		(width 0.09525)
		(layer "In11.Cu")
		(net "M_L_CPU1_SB_DQS_DP<5>")
	)
	(arc
		(start 142.813278 -277.001224)
		(mid 143.09471 -277.076979)
		(end 143.376142 -277.001224)
		(width 0.09525)
		(layer "In11.Cu")
		(net "M_L_CPU1_SB_DQS_DP<5>")
	)
	(arc
		(start 139.624562 -276.996398)
		(mid 139.809594 -276.950484)
		(end 139.99337 -277.001224)
		(width 0.09525)
		(layer "In11.Cu")
		(net "M_L_CPU1_SB_DQS_DP<5>")
	)
	(segment
		(start 137.457942 -272.20037)
		(end 137.924794 -272.466308)
		(width 0.12954)
		(layer "F.Cu")
		(net "M_L_CPU1_SB_DQS_DP<4>")
	)
	(segment
		(start 166.99992 -276.731984)
		(end 167.937434 -276.731984)
		(width 0.16002)
		(layer "In11.Cu")
		(net "M_L_CPU1_SB_DQS_DP<4>")
	)
	(segment
		(start 187.7822 -277.960582)
		(end 188.157358 -277.585424)
		(width 0.16002)
		(layer "In11.Cu")
		(net "M_L_CPU1_SB_DQS_DP<4>")
	)
	(segment
		(start 140.556234 -272.141188)
		(end 140.564616 -272.136362)
		(width 0.09525)
		(layer "In11.Cu")
		(net "M_L_CPU1_SB_DQS_DP<4>")
	)
	(segment
		(start 142.804896 -272.136362)
		(end 142.813278 -272.141188)
		(width 0.09525)
		(layer "In11.Cu")
		(net "M_L_CPU1_SB_DQS_DP<4>")
	)
	(segment
		(start 195.701412 -277.585424)
		(end 196.322696 -277.585424)
		(width 0.16002)
		(layer "In11.Cu")
		(net "M_L_CPU1_SB_DQS_DP<4>")
	)
	(segment
		(start 190.20409 -276.731984)
		(end 190.58255 -277.110444)
		(width 0.16002)
		(layer "In11.Cu")
		(net "M_L_CPU1_SB_DQS_DP<4>")
	)
	(segment
		(start 161.671254 -274.9423)
		(end 161.671254 -275.52777)
		(width 0.16002)
		(layer "In11.Cu")
		(net "M_L_CPU1_SB_DQS_DP<4>")
	)
	(segment
		(start 192.905888 -277.110444)
		(end 193.756026 -277.960582)
		(width 0.16002)
		(layer "In11.Cu")
		(net "M_L_CPU1_SB_DQS_DP<4>")
	)
	(segment
		(start 143.376142 -272.141188)
		(end 143.384524 -272.136362)
		(width 0.09525)
		(layer "In11.Cu")
		(net "M_L_CPU1_SB_DQS_DP<4>")
	)
	(segment
		(start 181.234588 -277.585424)
		(end 182.088028 -276.731984)
		(width 0.16002)
		(layer "In11.Cu")
		(net "M_L_CPU1_SB_DQS_DP<4>")
	)
	(segment
		(start 160.297622 -273.568668)
		(end 160.297622 -274.154138)
		(width 0.16002)
		(layer "In11.Cu")
		(net "M_L_CPU1_SB_DQS_DP<4>")
	)
	(segment
		(start 188.157358 -277.585424)
		(end 188.778642 -277.585424)
		(width 0.16002)
		(layer "In11.Cu")
		(net "M_L_CPU1_SB_DQS_DP<4>")
	)
	(segment
		(start 185.361834 -277.110444)
		(end 186.211972 -277.960582)
		(width 0.16002)
		(layer "In11.Cu")
		(net "M_L_CPU1_SB_DQS_DP<4>")
	)
	(segment
		(start 138.078718 -272.200878)
		(end 138.179556 -272.174208)
		(width 0.09525)
		(layer "In11.Cu")
		(net "M_L_CPU1_SB_DQS_DP<4>")
	)
	(segment
		(start 147.895564 -270.446754)
		(end 147.919186 -270.446754)
		(width 0.09525)
		(layer "In11.Cu")
		(net "M_L_CPU1_SB_DQS_DP<4>")
	)
	(segment
		(start 147.263104 -270.592296)
		(end 147.467574 -270.387826)
		(width 0.09525)
		(layer "In11.Cu")
		(net "M_L_CPU1_SB_DQS_DP<4>")
	)
	(segment
		(start 172.694092 -277.960582)
		(end 173.06925 -277.585424)
		(width 0.16002)
		(layer "In11.Cu")
		(net "M_L_CPU1_SB_DQS_DP<4>")
	)
	(segment
		(start 169.530268 -276.731984)
		(end 170.114722 -276.731984)
		(width 0.16002)
		(layer "In11.Cu")
		(net "M_L_CPU1_SB_DQS_DP<4>")
	)
	(segment
		(start 186.211972 -277.960582)
		(end 187.7822 -277.960582)
		(width 0.16002)
		(layer "In11.Cu")
		(net "M_L_CPU1_SB_DQS_DP<4>")
	)
	(segment
		(start 197.748144 -276.731984)
		(end 198.126604 -277.110444)
		(width 0.16002)
		(layer "In11.Cu")
		(net "M_L_CPU1_SB_DQS_DP<4>")
	)
	(segment
		(start 147.467574 -270.387826)
		(end 147.836636 -270.387826)
		(width 0.09525)
		(layer "In11.Cu")
		(net "M_L_CPU1_SB_DQS_DP<4>")
	)
	(segment
		(start 198.126604 -277.110444)
		(end 199.437752 -277.110444)
		(width 0.16002)
		(layer "In11.Cu")
		(net "M_L_CPU1_SB_DQS_DP<4>")
	)
	(segment
		(start 190.58255 -277.110444)
		(end 192.905888 -277.110444)
		(width 0.16002)
		(layer "In11.Cu")
		(net "M_L_CPU1_SB_DQS_DP<4>")
	)
	(segment
		(start 173.690534 -277.585424)
		(end 174.543974 -276.731984)
		(width 0.16002)
		(layer "In11.Cu")
		(net "M_L_CPU1_SB_DQS_DP<4>")
	)
	(segment
		(start 159.991552 -273.262598)
		(end 160.297622 -273.568668)
		(width 0.16002)
		(layer "In11.Cu")
		(net "M_L_CPU1_SB_DQS_DP<4>")
	)
	(segment
		(start 174.543974 -276.731984)
		(end 175.115982 -276.731984)
		(width 0.16002)
		(layer "In11.Cu")
		(net "M_L_CPU1_SB_DQS_DP<4>")
	)
	(segment
		(start 201.87412 -276.9616)
		(end 202.147932 -277.235412)
		(width 0.16002)
		(layer "In11.Cu")
		(net "M_L_CPU1_SB_DQS_DP<4>")
	)
	(segment
		(start 178.667918 -277.960582)
		(end 180.238146 -277.960582)
		(width 0.16002)
		(layer "In11.Cu")
		(net "M_L_CPU1_SB_DQS_DP<4>")
	)
	(segment
		(start 168.434512 -277.418546)
		(end 169.03319 -277.418546)
		(width 0.16002)
		(layer "In11.Cu")
		(net "M_L_CPU1_SB_DQS_DP<4>")
	)
	(segment
		(start 180.238146 -277.960582)
		(end 180.613304 -277.585424)
		(width 0.16002)
		(layer "In11.Cu")
		(net "M_L_CPU1_SB_DQS_DP<4>")
	)
	(segment
		(start 188.778642 -277.585424)
		(end 189.632082 -276.731984)
		(width 0.16002)
		(layer "In11.Cu")
		(net "M_L_CPU1_SB_DQS_DP<4>")
	)
	(segment
		(start 159.406082 -273.262598)
		(end 159.991552 -273.262598)
		(width 0.16002)
		(layer "In11.Cu")
		(net "M_L_CPU1_SB_DQS_DP<4>")
	)
	(segment
		(start 182.088028 -276.731984)
		(end 182.660036 -276.731984)
		(width 0.16002)
		(layer "In11.Cu")
		(net "M_L_CPU1_SB_DQS_DP<4>")
	)
	(segment
		(start 197.176136 -276.731984)
		(end 197.748144 -276.731984)
		(width 0.16002)
		(layer "In11.Cu")
		(net "M_L_CPU1_SB_DQS_DP<4>")
	)
	(segment
		(start 147.919186 -270.446754)
		(end 156.590238 -270.446754)
		(width 0.16002)
		(layer "In11.Cu")
		(net "M_L_CPU1_SB_DQS_DP<4>")
	)
	(segment
		(start 163.044886 -276.315932)
		(end 163.044886 -276.901402)
		(width 0.16002)
		(layer "In11.Cu")
		(net "M_L_CPU1_SB_DQS_DP<4>")
	)
	(segment
		(start 163.044886 -276.901402)
		(end 163.728908 -277.585424)
		(width 0.16002)
		(layer "In11.Cu")
		(net "M_L_CPU1_SB_DQS_DP<4>")
	)
	(segment
		(start 147.836636 -270.387826)
		(end 147.895564 -270.446754)
		(width 0.09525)
		(layer "In11.Cu")
		(net "M_L_CPU1_SB_DQS_DP<4>")
	)
	(segment
		(start 168.097454 -276.892004)
		(end 168.097454 -277.081488)
		(width 0.16002)
		(layer "In11.Cu")
		(net "M_L_CPU1_SB_DQS_DP<4>")
	)
	(segment
		(start 145.840958 -271.243298)
		(end 146.491706 -270.592296)
		(width 0.09525)
		(layer "In11.Cu")
		(net "M_L_CPU1_SB_DQS_DP<4>")
	)
	(segment
		(start 171.34332 -277.960582)
		(end 172.694092 -277.960582)
		(width 0.16002)
		(layer "In11.Cu")
		(net "M_L_CPU1_SB_DQS_DP<4>")
	)
	(segment
		(start 163.728908 -277.585424)
		(end 166.14648 -277.585424)
		(width 0.16002)
		(layer "In11.Cu")
		(net "M_L_CPU1_SB_DQS_DP<4>")
	)
	(segment
		(start 139.044934 -272.136362)
		(end 139.053316 -272.141188)
		(width 0.09525)
		(layer "In11.Cu")
		(net "M_L_CPU1_SB_DQS_DP<4>")
	)
	(segment
		(start 156.590238 -270.446754)
		(end 159.406082 -273.262598)
		(width 0.16002)
		(layer "In11.Cu")
		(net "M_L_CPU1_SB_DQS_DP<4>")
	)
	(segment
		(start 196.322696 -277.585424)
		(end 197.176136 -276.731984)
		(width 0.16002)
		(layer "In11.Cu")
		(net "M_L_CPU1_SB_DQS_DP<4>")
	)
	(segment
		(start 162.738816 -276.009862)
		(end 163.044886 -276.315932)
		(width 0.16002)
		(layer "In11.Cu")
		(net "M_L_CPU1_SB_DQS_DP<4>")
	)
	(segment
		(start 180.613304 -277.585424)
		(end 181.234588 -277.585424)
		(width 0.16002)
		(layer "In11.Cu")
		(net "M_L_CPU1_SB_DQS_DP<4>")
	)
	(segment
		(start 139.61618 -272.141188)
		(end 139.624562 -272.136362)
		(width 0.09525)
		(layer "In11.Cu")
		(net "M_L_CPU1_SB_DQS_DP<4>")
	)
	(segment
		(start 169.370248 -277.081488)
		(end 169.370248 -276.892004)
		(width 0.16002)
		(layer "In11.Cu")
		(net "M_L_CPU1_SB_DQS_DP<4>")
	)
	(segment
		(start 160.297622 -274.154138)
		(end 160.779714 -274.63623)
		(width 0.16002)
		(layer "In11.Cu")
		(net "M_L_CPU1_SB_DQS_DP<4>")
	)
	(segment
		(start 199.586596 -276.9616)
		(end 201.87412 -276.9616)
		(width 0.16002)
		(layer "In11.Cu")
		(net "M_L_CPU1_SB_DQS_DP<4>")
	)
	(segment
		(start 166.14648 -277.585424)
		(end 166.99992 -276.731984)
		(width 0.16002)
		(layer "In11.Cu")
		(net "M_L_CPU1_SB_DQS_DP<4>")
	)
	(segment
		(start 193.756026 -277.960582)
		(end 195.326254 -277.960582)
		(width 0.16002)
		(layer "In11.Cu")
		(net "M_L_CPU1_SB_DQS_DP<4>")
	)
	(segment
		(start 162.153346 -276.009862)
		(end 162.738816 -276.009862)
		(width 0.16002)
		(layer "In11.Cu")
		(net "M_L_CPU1_SB_DQS_DP<4>")
	)
	(segment
		(start 169.03319 -277.418546)
		(end 169.370248 -277.081488)
		(width 0.16002)
		(layer "In11.Cu")
		(net "M_L_CPU1_SB_DQS_DP<4>")
	)
	(segment
		(start 167.937434 -276.731984)
		(end 168.097454 -276.892004)
		(width 0.16002)
		(layer "In11.Cu")
		(net "M_L_CPU1_SB_DQS_DP<4>")
	)
	(segment
		(start 137.924794 -272.466308)
		(end 138.078718 -272.200878)
		(width 0.09525)
		(layer "In11.Cu")
		(net "M_L_CPU1_SB_DQS_DP<4>")
	)
	(segment
		(start 168.097454 -277.081488)
		(end 168.434512 -277.418546)
		(width 0.16002)
		(layer "In11.Cu")
		(net "M_L_CPU1_SB_DQS_DP<4>")
	)
	(segment
		(start 170.114722 -276.731984)
		(end 171.34332 -277.960582)
		(width 0.16002)
		(layer "In11.Cu")
		(net "M_L_CPU1_SB_DQS_DP<4>")
	)
	(segment
		(start 175.115982 -276.731984)
		(end 175.494442 -277.110444)
		(width 0.16002)
		(layer "In11.Cu")
		(net "M_L_CPU1_SB_DQS_DP<4>")
	)
	(segment
		(start 189.632082 -276.731984)
		(end 190.20409 -276.731984)
		(width 0.16002)
		(layer "In11.Cu")
		(net "M_L_CPU1_SB_DQS_DP<4>")
	)
	(segment
		(start 183.038496 -277.110444)
		(end 185.361834 -277.110444)
		(width 0.16002)
		(layer "In11.Cu")
		(net "M_L_CPU1_SB_DQS_DP<4>")
	)
	(segment
		(start 195.326254 -277.960582)
		(end 195.701412 -277.585424)
		(width 0.16002)
		(layer "In11.Cu")
		(net "M_L_CPU1_SB_DQS_DP<4>")
	)
	(segment
		(start 199.437752 -277.110444)
		(end 199.586596 -276.9616)
		(width 0.16002)
		(layer "In11.Cu")
		(net "M_L_CPU1_SB_DQS_DP<4>")
	)
	(segment
		(start 175.494442 -277.110444)
		(end 177.81778 -277.110444)
		(width 0.16002)
		(layer "In11.Cu")
		(net "M_L_CPU1_SB_DQS_DP<4>")
	)
	(segment
		(start 160.779714 -274.63623)
		(end 161.365184 -274.63623)
		(width 0.16002)
		(layer "In11.Cu")
		(net "M_L_CPU1_SB_DQS_DP<4>")
	)
	(segment
		(start 173.06925 -277.585424)
		(end 173.690534 -277.585424)
		(width 0.16002)
		(layer "In11.Cu")
		(net "M_L_CPU1_SB_DQS_DP<4>")
	)
	(segment
		(start 161.365184 -274.63623)
		(end 161.671254 -274.9423)
		(width 0.16002)
		(layer "In11.Cu")
		(net "M_L_CPU1_SB_DQS_DP<4>")
	)
	(segment
		(start 145.693638 -271.349978)
		(end 145.72615 -271.331182)
		(width 0.09525)
		(layer "In11.Cu")
		(net "M_L_CPU1_SB_DQS_DP<4>")
	)
	(segment
		(start 161.671254 -275.52777)
		(end 162.153346 -276.009862)
		(width 0.16002)
		(layer "In11.Cu")
		(net "M_L_CPU1_SB_DQS_DP<4>")
	)
	(segment
		(start 182.660036 -276.731984)
		(end 183.038496 -277.110444)
		(width 0.16002)
		(layer "In11.Cu")
		(net "M_L_CPU1_SB_DQS_DP<4>")
	)
	(segment
		(start 169.370248 -276.892004)
		(end 169.530268 -276.731984)
		(width 0.16002)
		(layer "In11.Cu")
		(net "M_L_CPU1_SB_DQS_DP<4>")
	)
	(segment
		(start 145.25625 -272.141188)
		(end 145.291302 -272.120614)
		(width 0.09525)
		(layer "In11.Cu")
		(net "M_L_CPU1_SB_DQS_DP<4>")
	)
	(segment
		(start 146.491706 -270.592296)
		(end 147.263104 -270.592296)
		(width 0.09525)
		(layer "In11.Cu")
		(net "M_L_CPU1_SB_DQS_DP<4>")
	)
	(segment
		(start 144.316196 -272.141188)
		(end 144.324578 -272.136362)
		(width 0.09525)
		(layer "In11.Cu")
		(net "M_L_CPU1_SB_DQS_DP<4>")
	)
	(segment
		(start 177.81778 -277.110444)
		(end 178.667918 -277.960582)
		(width 0.16002)
		(layer "In11.Cu")
		(net "M_L_CPU1_SB_DQS_DP<4>")
	)
	(arc
		(start 141.873224 -272.141188)
		(mid 142.154656 -272.216943)
		(end 142.436088 -272.141188)
		(width 0.09525)
		(layer "In11.Cu")
		(net "M_L_CPU1_SB_DQS_DP<4>")
	)
	(arc
		(start 145.802096 -271.27835)
		(mid 145.821936 -271.261278)
		(end 145.840958 -271.243298)
		(width 0.09525)
		(layer "In11.Cu")
		(net "M_L_CPU1_SB_DQS_DP<4>")
	)
	(arc
		(start 144.693386 -272.141188)
		(mid 144.974818 -272.216943)
		(end 145.25625 -272.141188)
		(width 0.09525)
		(layer "In11.Cu")
		(net "M_L_CPU1_SB_DQS_DP<4>")
	)
	(arc
		(start 140.933424 -272.141188)
		(mid 141.214856 -272.216943)
		(end 141.496288 -272.141188)
		(width 0.09525)
		(layer "In11.Cu")
		(net "M_L_CPU1_SB_DQS_DP<4>")
	)
	(arc
		(start 145.72615 -271.331182)
		(mid 145.765213 -271.306333)
		(end 145.802096 -271.27835)
		(width 0.09525)
		(layer "In11.Cu")
		(net "M_L_CPU1_SB_DQS_DP<4>")
	)
	(arc
		(start 144.324578 -272.136362)
		(mid 144.50961 -272.090448)
		(end 144.693386 -272.141188)
		(width 0.09525)
		(layer "In11.Cu")
		(net "M_L_CPU1_SB_DQS_DP<4>")
	)
	(arc
		(start 143.384524 -272.136362)
		(mid 143.569556 -272.090448)
		(end 143.753332 -272.141188)
		(width 0.09525)
		(layer "In11.Cu")
		(net "M_L_CPU1_SB_DQS_DP<4>")
	)
	(arc
		(start 138.199876 -272.182082)
		(mid 138.442588 -272.214965)
		(end 138.676126 -272.141188)
		(width 0.09525)
		(layer "In11.Cu")
		(net "M_L_CPU1_SB_DQS_DP<4>")
	)
	(arc
		(start 141.496288 -272.141188)
		(mid 141.684756 -272.090511)
		(end 141.873224 -272.141188)
		(width 0.09525)
		(layer "In11.Cu")
		(net "M_L_CPU1_SB_DQS_DP<4>")
	)
	(arc
		(start 139.053316 -272.141188)
		(mid 139.334748 -272.216943)
		(end 139.61618 -272.141188)
		(width 0.09525)
		(layer "In11.Cu")
		(net "M_L_CPU1_SB_DQS_DP<4>")
	)
	(arc
		(start 138.179556 -272.174208)
		(mid 138.189678 -272.178243)
		(end 138.199876 -272.182082)
		(width 0.09525)
		(layer "In11.Cu")
		(net "M_L_CPU1_SB_DQS_DP<4>")
	)
	(arc
		(start 140.564616 -272.136362)
		(mid 140.749648 -272.090448)
		(end 140.933424 -272.141188)
		(width 0.09525)
		(layer "In11.Cu")
		(net "M_L_CPU1_SB_DQS_DP<4>")
	)
	(arc
		(start 145.291302 -272.120614)
		(mid 145.471693 -271.918915)
		(end 145.53692 -271.656302)
		(width 0.09525)
		(layer "In11.Cu")
		(net "M_L_CPU1_SB_DQS_DP<4>")
	)
	(arc
		(start 142.813278 -272.141188)
		(mid 143.09471 -272.216943)
		(end 143.376142 -272.141188)
		(width 0.09525)
		(layer "In11.Cu")
		(net "M_L_CPU1_SB_DQS_DP<4>")
	)
	(arc
		(start 143.753332 -272.141188)
		(mid 144.034764 -272.216943)
		(end 144.316196 -272.141188)
		(width 0.09525)
		(layer "In11.Cu")
		(net "M_L_CPU1_SB_DQS_DP<4>")
	)
	(arc
		(start 138.676126 -272.141188)
		(mid 138.859901 -272.090416)
		(end 139.044934 -272.136362)
		(width 0.09525)
		(layer "In11.Cu")
		(net "M_L_CPU1_SB_DQS_DP<4>")
	)
	(arc
		(start 142.436088 -272.141188)
		(mid 142.619863 -272.090416)
		(end 142.804896 -272.136362)
		(width 0.09525)
		(layer "In11.Cu")
		(net "M_L_CPU1_SB_DQS_DP<4>")
	)
	(arc
		(start 139.99337 -272.141188)
		(mid 140.274802 -272.216943)
		(end 140.556234 -272.141188)
		(width 0.09525)
		(layer "In11.Cu")
		(net "M_L_CPU1_SB_DQS_DP<4>")
	)
	(arc
		(start 139.624562 -272.136362)
		(mid 139.809594 -272.090448)
		(end 139.99337 -272.141188)
		(width 0.09525)
		(layer "In11.Cu")
		(net "M_L_CPU1_SB_DQS_DP<4>")
	)
	(arc
		(start 145.53692 -271.656302)
		(mid 145.578377 -271.484262)
		(end 145.693638 -271.349978)
		(width 0.09525)
		(layer "In11.Cu")
		(net "M_L_CPU1_SB_DQS_DP<4>")
	)
	(segment
		(start 139.337796 -290.020248)
		(end 139.804648 -290.286186)
		(width 0.12954)
		(layer "F.Cu")
		(net "M_L_CPU1_SB_DQS_DP<3>")
	)
	(segment
		(start 161.844736 -313.38774)
		(end 166.057834 -313.38774)
		(width 0.16002)
		(layer "In11.Cu")
		(net "M_L_CPU1_SB_DQS_DP<3>")
	)
	(segment
		(start 147.817586 -294.31234)
		(end 148.43887 -294.933624)
		(width 0.16002)
		(layer "In11.Cu")
		(net "M_L_CPU1_SB_DQS_DP<3>")
	)
	(segment
		(start 175.190912 -312.210196)
		(end 177.100484 -312.210196)
		(width 0.16002)
		(layer "In11.Cu")
		(net "M_L_CPU1_SB_DQS_DP<3>")
	)
	(segment
		(start 184.644538 -312.210196)
		(end 185.494422 -313.06008)
		(width 0.16002)
		(layer "In11.Cu")
		(net "M_L_CPU1_SB_DQS_DP<3>")
	)
	(segment
		(start 205.22692 -313.082178)
		(end 205.35392 -313.209178)
		(width 0.16002)
		(layer "In11.Cu")
		(net "M_L_CPU1_SB_DQS_DP<3>")
	)
	(segment
		(start 174.424848 -312.56478)
		(end 174.836328 -312.56478)
		(width 0.16002)
		(layer "In11.Cu")
		(net "M_L_CPU1_SB_DQS_DP<3>")
	)
	(segment
		(start 195.18249 -313.06008)
		(end 195.51015 -313.38774)
		(width 0.16002)
		(layer "In11.Cu")
		(net "M_L_CPU1_SB_DQS_DP<3>")
	)
	(segment
		(start 140.556234 -290.611306)
		(end 140.564616 -290.616132)
		(width 0.09525)
		(layer "In11.Cu")
		(net "M_L_CPU1_SB_DQS_DP<3>")
	)
	(segment
		(start 200.306686 -312.784236)
		(end 200.763886 -312.784236)
		(width 0.16002)
		(layer "In11.Cu")
		(net "M_L_CPU1_SB_DQS_DP<3>")
	)
	(segment
		(start 195.51015 -313.38774)
		(end 196.23405 -313.38774)
		(width 0.16002)
		(layer "In11.Cu")
		(net "M_L_CPU1_SB_DQS_DP<3>")
	)
	(segment
		(start 201.475086 -312.784236)
		(end 202.728322 -312.784236)
		(width 0.16002)
		(layer "In11.Cu")
		(net "M_L_CPU1_SB_DQS_DP<3>")
	)
	(segment
		(start 204.61986 -313.209178)
		(end 204.74686 -313.082178)
		(width 0.16002)
		(layer "In11.Cu")
		(net "M_L_CPU1_SB_DQS_DP<3>")
	)
	(segment
		(start 173.601888 -313.38774)
		(end 174.424848 -312.56478)
		(width 0.16002)
		(layer "In11.Cu")
		(net "M_L_CPU1_SB_DQS_DP<3>")
	)
	(segment
		(start 187.966096 -313.38774)
		(end 188.689996 -313.38774)
		(width 0.16002)
		(layer "In11.Cu")
		(net "M_L_CPU1_SB_DQS_DP<3>")
	)
	(segment
		(start 187.638436 -313.06008)
		(end 187.966096 -313.38774)
		(width 0.16002)
		(layer "In11.Cu")
		(net "M_L_CPU1_SB_DQS_DP<3>")
	)
	(segment
		(start 181.145942 -313.38774)
		(end 181.968902 -312.56478)
		(width 0.16002)
		(layer "In11.Cu")
		(net "M_L_CPU1_SB_DQS_DP<3>")
	)
	(segment
		(start 199.732646 -312.210196)
		(end 200.306686 -312.784236)
		(width 0.16002)
		(layer "In11.Cu")
		(net "M_L_CPU1_SB_DQS_DP<3>")
	)
	(segment
		(start 197.823074 -312.210196)
		(end 199.732646 -312.210196)
		(width 0.16002)
		(layer "In11.Cu")
		(net "M_L_CPU1_SB_DQS_DP<3>")
	)
	(segment
		(start 205.35392 -313.209178)
		(end 205.974188 -313.209178)
		(width 0.16002)
		(layer "In11.Cu")
		(net "M_L_CPU1_SB_DQS_DP<3>")
	)
	(segment
		(start 180.422042 -313.38774)
		(end 181.145942 -313.38774)
		(width 0.16002)
		(layer "In11.Cu")
		(net "M_L_CPU1_SB_DQS_DP<3>")
	)
	(segment
		(start 169.55643 -312.210196)
		(end 170.406314 -313.06008)
		(width 0.16002)
		(layer "In11.Cu")
		(net "M_L_CPU1_SB_DQS_DP<3>")
	)
	(segment
		(start 189.924436 -312.56478)
		(end 190.27902 -312.210196)
		(width 0.16002)
		(layer "In11.Cu")
		(net "M_L_CPU1_SB_DQS_DP<3>")
	)
	(segment
		(start 145.134584 -290.742116)
		(end 145.733008 -291.34054)
		(width 0.09525)
		(layer "In11.Cu")
		(net "M_L_CPU1_SB_DQS_DP<3>")
	)
	(segment
		(start 177.100484 -312.210196)
		(end 177.950368 -313.06008)
		(width 0.16002)
		(layer "In11.Cu")
		(net "M_L_CPU1_SB_DQS_DP<3>")
	)
	(segment
		(start 181.968902 -312.56478)
		(end 182.380382 -312.56478)
		(width 0.16002)
		(layer "In11.Cu")
		(net "M_L_CPU1_SB_DQS_DP<3>")
	)
	(segment
		(start 180.094382 -313.06008)
		(end 180.422042 -313.38774)
		(width 0.16002)
		(layer "In11.Cu")
		(net "M_L_CPU1_SB_DQS_DP<3>")
	)
	(segment
		(start 167.292274 -312.56478)
		(end 167.646858 -312.210196)
		(width 0.16002)
		(layer "In11.Cu")
		(net "M_L_CPU1_SB_DQS_DP<3>")
	)
	(segment
		(start 172.877988 -313.38774)
		(end 173.601888 -313.38774)
		(width 0.16002)
		(layer "In11.Cu")
		(net "M_L_CPU1_SB_DQS_DP<3>")
	)
	(segment
		(start 166.880794 -312.56478)
		(end 167.292274 -312.56478)
		(width 0.16002)
		(layer "In11.Cu")
		(net "M_L_CPU1_SB_DQS_DP<3>")
	)
	(segment
		(start 167.646858 -312.210196)
		(end 169.55643 -312.210196)
		(width 0.16002)
		(layer "In11.Cu")
		(net "M_L_CPU1_SB_DQS_DP<3>")
	)
	(segment
		(start 147.71751 -294.295576)
		(end 147.800822 -294.295576)
		(width 0.09525)
		(layer "In11.Cu")
		(net "M_L_CPU1_SB_DQS_DP<3>")
	)
	(segment
		(start 205.974188 -313.209178)
		(end 206.248 -312.935366)
		(width 0.16002)
		(layer "In11.Cu")
		(net "M_L_CPU1_SB_DQS_DP<3>")
	)
	(segment
		(start 166.057834 -313.38774)
		(end 166.880794 -312.56478)
		(width 0.16002)
		(layer "In11.Cu")
		(net "M_L_CPU1_SB_DQS_DP<3>")
	)
	(segment
		(start 148.43887 -294.933624)
		(end 148.43887 -299.981874)
		(width 0.16002)
		(layer "In11.Cu")
		(net "M_L_CPU1_SB_DQS_DP<3>")
	)
	(segment
		(start 197.05701 -312.56478)
		(end 197.46849 -312.56478)
		(width 0.16002)
		(layer "In11.Cu")
		(net "M_L_CPU1_SB_DQS_DP<3>")
	)
	(segment
		(start 201.348086 -312.657236)
		(end 201.475086 -312.784236)
		(width 0.16002)
		(layer "In11.Cu")
		(net "M_L_CPU1_SB_DQS_DP<3>")
	)
	(segment
		(start 145.974816 -291.702236)
		(end 146.576288 -293.154354)
		(width 0.09525)
		(layer "In11.Cu")
		(net "M_L_CPU1_SB_DQS_DP<3>")
	)
	(segment
		(start 174.836328 -312.56478)
		(end 175.190912 -312.210196)
		(width 0.16002)
		(layer "In11.Cu")
		(net "M_L_CPU1_SB_DQS_DP<3>")
	)
	(segment
		(start 182.380382 -312.56478)
		(end 182.734966 -312.210196)
		(width 0.16002)
		(layer "In11.Cu")
		(net "M_L_CPU1_SB_DQS_DP<3>")
	)
	(segment
		(start 188.689996 -313.38774)
		(end 189.512956 -312.56478)
		(width 0.16002)
		(layer "In11.Cu")
		(net "M_L_CPU1_SB_DQS_DP<3>")
	)
	(segment
		(start 147.800822 -294.295576)
		(end 147.817586 -294.31234)
		(width 0.09525)
		(layer "In11.Cu")
		(net "M_L_CPU1_SB_DQS_DP<3>")
	)
	(segment
		(start 200.890886 -312.657236)
		(end 201.348086 -312.657236)
		(width 0.16002)
		(layer "In11.Cu")
		(net "M_L_CPU1_SB_DQS_DP<3>")
	)
	(segment
		(start 142.804896 -290.616132)
		(end 142.813278 -290.611306)
		(width 0.09525)
		(layer "In11.Cu")
		(net "M_L_CPU1_SB_DQS_DP<3>")
	)
	(segment
		(start 139.650724 -290.551616)
		(end 139.674092 -290.638484)
		(width 0.09525)
		(layer "In11.Cu")
		(net "M_L_CPU1_SB_DQS_DP<3>")
	)
	(segment
		(start 200.763886 -312.784236)
		(end 200.890886 -312.657236)
		(width 0.16002)
		(layer "In11.Cu")
		(net "M_L_CPU1_SB_DQS_DP<3>")
	)
	(segment
		(start 190.27902 -312.210196)
		(end 192.188592 -312.210196)
		(width 0.16002)
		(layer "In11.Cu")
		(net "M_L_CPU1_SB_DQS_DP<3>")
	)
	(segment
		(start 193.038476 -313.06008)
		(end 195.18249 -313.06008)
		(width 0.16002)
		(layer "In11.Cu")
		(net "M_L_CPU1_SB_DQS_DP<3>")
	)
	(segment
		(start 146.576288 -293.154354)
		(end 147.71751 -294.295576)
		(width 0.09525)
		(layer "In11.Cu")
		(net "M_L_CPU1_SB_DQS_DP<3>")
	)
	(segment
		(start 182.734966 -312.210196)
		(end 184.644538 -312.210196)
		(width 0.16002)
		(layer "In11.Cu")
		(net "M_L_CPU1_SB_DQS_DP<3>")
	)
	(segment
		(start 185.494422 -313.06008)
		(end 187.638436 -313.06008)
		(width 0.16002)
		(layer "In11.Cu")
		(net "M_L_CPU1_SB_DQS_DP<3>")
	)
	(segment
		(start 148.43887 -299.981874)
		(end 161.844736 -313.38774)
		(width 0.16002)
		(layer "In11.Cu")
		(net "M_L_CPU1_SB_DQS_DP<3>")
	)
	(segment
		(start 203.955396 -313.209178)
		(end 204.61986 -313.209178)
		(width 0.16002)
		(layer "In11.Cu")
		(net "M_L_CPU1_SB_DQS_DP<3>")
	)
	(segment
		(start 139.804648 -290.286186)
		(end 139.650724 -290.551616)
		(width 0.09525)
		(layer "In11.Cu")
		(net "M_L_CPU1_SB_DQS_DP<3>")
	)
	(segment
		(start 202.728322 -312.784236)
		(end 203.347066 -313.40298)
		(width 0.16002)
		(layer "In11.Cu")
		(net "M_L_CPU1_SB_DQS_DP<3>")
	)
	(segment
		(start 197.46849 -312.56478)
		(end 197.823074 -312.210196)
		(width 0.16002)
		(layer "In11.Cu")
		(net "M_L_CPU1_SB_DQS_DP<3>")
	)
	(segment
		(start 170.406314 -313.06008)
		(end 172.550328 -313.06008)
		(width 0.16002)
		(layer "In11.Cu")
		(net "M_L_CPU1_SB_DQS_DP<3>")
	)
	(segment
		(start 203.761594 -313.40298)
		(end 203.955396 -313.209178)
		(width 0.16002)
		(layer "In11.Cu")
		(net "M_L_CPU1_SB_DQS_DP<3>")
	)
	(segment
		(start 172.550328 -313.06008)
		(end 172.877988 -313.38774)
		(width 0.16002)
		(layer "In11.Cu")
		(net "M_L_CPU1_SB_DQS_DP<3>")
	)
	(segment
		(start 189.512956 -312.56478)
		(end 189.924436 -312.56478)
		(width 0.16002)
		(layer "In11.Cu")
		(net "M_L_CPU1_SB_DQS_DP<3>")
	)
	(segment
		(start 203.347066 -313.40298)
		(end 203.761594 -313.40298)
		(width 0.16002)
		(layer "In11.Cu")
		(net "M_L_CPU1_SB_DQS_DP<3>")
	)
	(segment
		(start 144.03451 -290.535614)
		(end 144.635728 -290.535614)
		(width 0.09525)
		(layer "In11.Cu")
		(net "M_L_CPU1_SB_DQS_DP<3>")
	)
	(segment
		(start 143.376142 -290.611306)
		(end 143.384524 -290.616132)
		(width 0.09525)
		(layer "In11.Cu")
		(net "M_L_CPU1_SB_DQS_DP<3>")
	)
	(segment
		(start 192.188592 -312.210196)
		(end 193.038476 -313.06008)
		(width 0.16002)
		(layer "In11.Cu")
		(net "M_L_CPU1_SB_DQS_DP<3>")
	)
	(segment
		(start 196.23405 -313.38774)
		(end 197.05701 -312.56478)
		(width 0.16002)
		(layer "In11.Cu")
		(net "M_L_CPU1_SB_DQS_DP<3>")
	)
	(segment
		(start 177.950368 -313.06008)
		(end 180.094382 -313.06008)
		(width 0.16002)
		(layer "In11.Cu")
		(net "M_L_CPU1_SB_DQS_DP<3>")
	)
	(segment
		(start 204.74686 -313.082178)
		(end 205.22692 -313.082178)
		(width 0.16002)
		(layer "In11.Cu")
		(net "M_L_CPU1_SB_DQS_DP<3>")
	)
	(arc
		(start 142.813278 -290.611306)
		(mid 143.09471 -290.535551)
		(end 143.376142 -290.611306)
		(width 0.09525)
		(layer "In11.Cu")
		(net "M_L_CPU1_SB_DQS_DP<3>")
	)
	(arc
		(start 141.496288 -290.611306)
		(mid 141.684756 -290.661983)
		(end 141.873224 -290.611306)
		(width 0.09525)
		(layer "In11.Cu")
		(net "M_L_CPU1_SB_DQS_DP<3>")
	)
	(arc
		(start 140.933424 -290.611306)
		(mid 141.214856 -290.535551)
		(end 141.496288 -290.611306)
		(width 0.09525)
		(layer "In11.Cu")
		(net "M_L_CPU1_SB_DQS_DP<3>")
	)
	(arc
		(start 145.733008 -291.34054)
		(mid 145.871715 -291.509486)
		(end 145.974816 -291.702236)
		(width 0.09525)
		(layer "In11.Cu")
		(net "M_L_CPU1_SB_DQS_DP<3>")
	)
	(arc
		(start 141.873224 -290.611306)
		(mid 142.154656 -290.535551)
		(end 142.436088 -290.611306)
		(width 0.09525)
		(layer "In11.Cu")
		(net "M_L_CPU1_SB_DQS_DP<3>")
	)
	(arc
		(start 144.635728 -290.535614)
		(mid 144.905711 -290.589223)
		(end 145.134584 -290.742116)
		(width 0.09525)
		(layer "In11.Cu")
		(net "M_L_CPU1_SB_DQS_DP<3>")
	)
	(arc
		(start 142.436088 -290.611306)
		(mid 142.619863 -290.662078)
		(end 142.804896 -290.616132)
		(width 0.09525)
		(layer "In11.Cu")
		(net "M_L_CPU1_SB_DQS_DP<3>")
	)
	(arc
		(start 140.564616 -290.616132)
		(mid 140.749648 -290.662046)
		(end 140.933424 -290.611306)
		(width 0.09525)
		(layer "In11.Cu")
		(net "M_L_CPU1_SB_DQS_DP<3>")
	)
	(arc
		(start 143.384524 -290.616132)
		(mid 143.569556 -290.662046)
		(end 143.753332 -290.611306)
		(width 0.09525)
		(layer "In11.Cu")
		(net "M_L_CPU1_SB_DQS_DP<3>")
	)
	(arc
		(start 139.674092 -290.638484)
		(mid 139.836774 -290.660616)
		(end 139.99337 -290.611306)
		(width 0.09525)
		(layer "In11.Cu")
		(net "M_L_CPU1_SB_DQS_DP<3>")
	)
	(arc
		(start 139.99337 -290.611306)
		(mid 140.274802 -290.535551)
		(end 140.556234 -290.611306)
		(width 0.09525)
		(layer "In11.Cu")
		(net "M_L_CPU1_SB_DQS_DP<3>")
	)
	(arc
		(start 143.753332 -290.611306)
		(mid 143.888917 -290.554854)
		(end 144.03451 -290.535614)
		(width 0.09525)
		(layer "In11.Cu")
		(net "M_L_CPU1_SB_DQS_DP<3>")
	)
	(segment
		(start 139.337796 -285.160466)
		(end 139.804648 -285.426404)
		(width 0.12954)
		(layer "F.Cu")
		(net "M_L_CPU1_SB_DQS_DP<2>")
	)
	(segment
		(start 197.823074 -302.860202)
		(end 199.732646 -302.860202)
		(width 0.16002)
		(layer "In11.Cu")
		(net "M_L_CPU1_SB_DQS_DP<2>")
	)
	(segment
		(start 204.74686 -303.732184)
		(end 205.22692 -303.732184)
		(width 0.16002)
		(layer "In11.Cu")
		(net "M_L_CPU1_SB_DQS_DP<2>")
	)
	(segment
		(start 180.422042 -304.037746)
		(end 181.145942 -304.037746)
		(width 0.16002)
		(layer "In11.Cu")
		(net "M_L_CPU1_SB_DQS_DP<2>")
	)
	(segment
		(start 195.18249 -303.710086)
		(end 195.51015 -304.037746)
		(width 0.16002)
		(layer "In11.Cu")
		(net "M_L_CPU1_SB_DQS_DP<2>")
	)
	(segment
		(start 188.689996 -304.037746)
		(end 189.512956 -303.214786)
		(width 0.16002)
		(layer "In11.Cu")
		(net "M_L_CPU1_SB_DQS_DP<2>")
	)
	(segment
		(start 154.06243 -292.47084)
		(end 154.06243 -295.401492)
		(width 0.16002)
		(layer "In11.Cu")
		(net "M_L_CPU1_SB_DQS_DP<2>")
	)
	(segment
		(start 167.646858 -302.860202)
		(end 169.55643 -302.860202)
		(width 0.16002)
		(layer "In11.Cu")
		(net "M_L_CPU1_SB_DQS_DP<2>")
	)
	(segment
		(start 175.190912 -302.860202)
		(end 177.100484 -302.860202)
		(width 0.16002)
		(layer "In11.Cu")
		(net "M_L_CPU1_SB_DQS_DP<2>")
	)
	(segment
		(start 182.734966 -302.860202)
		(end 184.644538 -302.860202)
		(width 0.16002)
		(layer "In11.Cu")
		(net "M_L_CPU1_SB_DQS_DP<2>")
	)
	(segment
		(start 199.732646 -302.860202)
		(end 200.52665 -303.654206)
		(width 0.16002)
		(layer "In11.Cu")
		(net "M_L_CPU1_SB_DQS_DP<2>")
	)
	(segment
		(start 166.057834 -304.037746)
		(end 166.880794 -303.214786)
		(width 0.16002)
		(layer "In11.Cu")
		(net "M_L_CPU1_SB_DQS_DP<2>")
	)
	(segment
		(start 147.560284 -286.637476)
		(end 147.836636 -286.637476)
		(width 0.09525)
		(layer "In11.Cu")
		(net "M_L_CPU1_SB_DQS_DP<2>")
	)
	(segment
		(start 187.638436 -303.710086)
		(end 187.966096 -304.037746)
		(width 0.16002)
		(layer "In11.Cu")
		(net "M_L_CPU1_SB_DQS_DP<2>")
	)
	(segment
		(start 203.955396 -303.859184)
		(end 204.61986 -303.859184)
		(width 0.16002)
		(layer "In11.Cu")
		(net "M_L_CPU1_SB_DQS_DP<2>")
	)
	(segment
		(start 204.61986 -303.859184)
		(end 204.74686 -303.732184)
		(width 0.16002)
		(layer "In11.Cu")
		(net "M_L_CPU1_SB_DQS_DP<2>")
	)
	(segment
		(start 196.23405 -304.037746)
		(end 197.05701 -303.214786)
		(width 0.16002)
		(layer "In11.Cu")
		(net "M_L_CPU1_SB_DQS_DP<2>")
	)
	(segment
		(start 197.05701 -303.214786)
		(end 197.46849 -303.214786)
		(width 0.16002)
		(layer "In11.Cu")
		(net "M_L_CPU1_SB_DQS_DP<2>")
	)
	(segment
		(start 144.2974 -285.74111)
		(end 144.315434 -285.751524)
		(width 0.09525)
		(layer "In11.Cu")
		(net "M_L_CPU1_SB_DQS_DP<2>")
	)
	(segment
		(start 172.877988 -304.037746)
		(end 173.601888 -304.037746)
		(width 0.16002)
		(layer "In11.Cu")
		(net "M_L_CPU1_SB_DQS_DP<2>")
	)
	(segment
		(start 184.644538 -302.860202)
		(end 185.494422 -303.710086)
		(width 0.16002)
		(layer "In11.Cu")
		(net "M_L_CPU1_SB_DQS_DP<2>")
	)
	(segment
		(start 182.380382 -303.214786)
		(end 182.734966 -302.860202)
		(width 0.16002)
		(layer "In11.Cu")
		(net "M_L_CPU1_SB_DQS_DP<2>")
	)
	(segment
		(start 170.406314 -303.710086)
		(end 172.550328 -303.710086)
		(width 0.16002)
		(layer "In11.Cu")
		(net "M_L_CPU1_SB_DQS_DP<2>")
	)
	(segment
		(start 167.292274 -303.214786)
		(end 167.646858 -302.860202)
		(width 0.16002)
		(layer "In11.Cu")
		(net "M_L_CPU1_SB_DQS_DP<2>")
	)
	(segment
		(start 147.836636 -286.637476)
		(end 147.895564 -286.578548)
		(width 0.09525)
		(layer "In11.Cu")
		(net "M_L_CPU1_SB_DQS_DP<2>")
	)
	(segment
		(start 148.170138 -286.578548)
		(end 154.06243 -292.47084)
		(width 0.16002)
		(layer "In11.Cu")
		(net "M_L_CPU1_SB_DQS_DP<2>")
	)
	(segment
		(start 146.770344 -286.419036)
		(end 147.341844 -286.419036)
		(width 0.09525)
		(layer "In11.Cu")
		(net "M_L_CPU1_SB_DQS_DP<2>")
	)
	(segment
		(start 205.35392 -303.859184)
		(end 205.974188 -303.859184)
		(width 0.16002)
		(layer "In11.Cu")
		(net "M_L_CPU1_SB_DQS_DP<2>")
	)
	(segment
		(start 146.154648 -285.80334)
		(end 146.770344 -286.419036)
		(width 0.09525)
		(layer "In11.Cu")
		(net "M_L_CPU1_SB_DQS_DP<2>")
	)
	(segment
		(start 205.974188 -303.859184)
		(end 206.248 -303.585372)
		(width 0.16002)
		(layer "In11.Cu")
		(net "M_L_CPU1_SB_DQS_DP<2>")
	)
	(segment
		(start 174.424848 -303.214786)
		(end 174.836328 -303.214786)
		(width 0.16002)
		(layer "In11.Cu")
		(net "M_L_CPU1_SB_DQS_DP<2>")
	)
	(segment
		(start 169.55643 -302.860202)
		(end 170.406314 -303.710086)
		(width 0.16002)
		(layer "In11.Cu")
		(net "M_L_CPU1_SB_DQS_DP<2>")
	)
	(segment
		(start 205.22692 -303.732184)
		(end 205.35392 -303.859184)
		(width 0.16002)
		(layer "In11.Cu")
		(net "M_L_CPU1_SB_DQS_DP<2>")
	)
	(segment
		(start 177.950368 -303.710086)
		(end 180.094382 -303.710086)
		(width 0.16002)
		(layer "In11.Cu")
		(net "M_L_CPU1_SB_DQS_DP<2>")
	)
	(segment
		(start 203.761594 -304.052986)
		(end 203.955396 -303.859184)
		(width 0.16002)
		(layer "In11.Cu")
		(net "M_L_CPU1_SB_DQS_DP<2>")
	)
	(segment
		(start 162.698684 -304.037746)
		(end 166.057834 -304.037746)
		(width 0.16002)
		(layer "In11.Cu")
		(net "M_L_CPU1_SB_DQS_DP<2>")
	)
	(segment
		(start 145.444718 -285.80334)
		(end 146.154648 -285.80334)
		(width 0.09525)
		(layer "In11.Cu")
		(net "M_L_CPU1_SB_DQS_DP<2>")
	)
	(segment
		(start 154.06243 -295.401492)
		(end 162.698684 -304.037746)
		(width 0.16002)
		(layer "In11.Cu")
		(net "M_L_CPU1_SB_DQS_DP<2>")
	)
	(segment
		(start 195.51015 -304.037746)
		(end 196.23405 -304.037746)
		(width 0.16002)
		(layer "In11.Cu")
		(net "M_L_CPU1_SB_DQS_DP<2>")
	)
	(segment
		(start 172.550328 -303.710086)
		(end 172.877988 -304.037746)
		(width 0.16002)
		(layer "In11.Cu")
		(net "M_L_CPU1_SB_DQS_DP<2>")
	)
	(segment
		(start 147.919186 -286.578548)
		(end 148.170138 -286.578548)
		(width 0.16002)
		(layer "In11.Cu")
		(net "M_L_CPU1_SB_DQS_DP<2>")
	)
	(segment
		(start 192.188592 -302.860202)
		(end 193.038476 -303.710086)
		(width 0.16002)
		(layer "In11.Cu")
		(net "M_L_CPU1_SB_DQS_DP<2>")
	)
	(segment
		(start 173.601888 -304.037746)
		(end 174.424848 -303.214786)
		(width 0.16002)
		(layer "In11.Cu")
		(net "M_L_CPU1_SB_DQS_DP<2>")
	)
	(segment
		(start 197.46849 -303.214786)
		(end 197.823074 -302.860202)
		(width 0.16002)
		(layer "In11.Cu")
		(net "M_L_CPU1_SB_DQS_DP<2>")
	)
	(segment
		(start 174.836328 -303.214786)
		(end 175.190912 -302.860202)
		(width 0.16002)
		(layer "In11.Cu")
		(net "M_L_CPU1_SB_DQS_DP<2>")
	)
	(segment
		(start 181.968902 -303.214786)
		(end 182.380382 -303.214786)
		(width 0.16002)
		(layer "In11.Cu")
		(net "M_L_CPU1_SB_DQS_DP<2>")
	)
	(segment
		(start 139.650724 -285.691834)
		(end 139.674092 -285.778702)
		(width 0.09525)
		(layer "In11.Cu")
		(net "M_L_CPU1_SB_DQS_DP<2>")
	)
	(segment
		(start 142.804896 -285.75635)
		(end 142.813278 -285.751524)
		(width 0.09525)
		(layer "In11.Cu")
		(net "M_L_CPU1_SB_DQS_DP<2>")
	)
	(segment
		(start 187.966096 -304.037746)
		(end 188.689996 -304.037746)
		(width 0.16002)
		(layer "In11.Cu")
		(net "M_L_CPU1_SB_DQS_DP<2>")
	)
	(segment
		(start 177.100484 -302.860202)
		(end 177.950368 -303.710086)
		(width 0.16002)
		(layer "In11.Cu")
		(net "M_L_CPU1_SB_DQS_DP<2>")
	)
	(segment
		(start 166.880794 -303.214786)
		(end 167.292274 -303.214786)
		(width 0.16002)
		(layer "In11.Cu")
		(net "M_L_CPU1_SB_DQS_DP<2>")
	)
	(segment
		(start 143.376142 -285.751524)
		(end 143.384524 -285.75635)
		(width 0.09525)
		(layer "In11.Cu")
		(net "M_L_CPU1_SB_DQS_DP<2>")
	)
	(segment
		(start 181.145942 -304.037746)
		(end 181.968902 -303.214786)
		(width 0.16002)
		(layer "In11.Cu")
		(net "M_L_CPU1_SB_DQS_DP<2>")
	)
	(segment
		(start 144.692116 -285.751524)
		(end 144.71015 -285.74111)
		(width 0.09525)
		(layer "In11.Cu")
		(net "M_L_CPU1_SB_DQS_DP<2>")
	)
	(segment
		(start 193.038476 -303.710086)
		(end 195.18249 -303.710086)
		(width 0.16002)
		(layer "In11.Cu")
		(net "M_L_CPU1_SB_DQS_DP<2>")
	)
	(segment
		(start 185.494422 -303.710086)
		(end 187.638436 -303.710086)
		(width 0.16002)
		(layer "In11.Cu")
		(net "M_L_CPU1_SB_DQS_DP<2>")
	)
	(segment
		(start 203.347066 -304.052986)
		(end 203.761594 -304.052986)
		(width 0.16002)
		(layer "In11.Cu")
		(net "M_L_CPU1_SB_DQS_DP<2>")
	)
	(segment
		(start 189.512956 -303.214786)
		(end 189.924436 -303.214786)
		(width 0.16002)
		(layer "In11.Cu")
		(net "M_L_CPU1_SB_DQS_DP<2>")
	)
	(segment
		(start 140.556234 -285.751524)
		(end 140.564616 -285.75635)
		(width 0.09525)
		(layer "In11.Cu")
		(net "M_L_CPU1_SB_DQS_DP<2>")
	)
	(segment
		(start 190.27902 -302.860202)
		(end 192.188592 -302.860202)
		(width 0.16002)
		(layer "In11.Cu")
		(net "M_L_CPU1_SB_DQS_DP<2>")
	)
	(segment
		(start 189.924436 -303.214786)
		(end 190.27902 -302.860202)
		(width 0.16002)
		(layer "In11.Cu")
		(net "M_L_CPU1_SB_DQS_DP<2>")
	)
	(segment
		(start 139.804648 -285.426404)
		(end 139.650724 -285.691834)
		(width 0.09525)
		(layer "In11.Cu")
		(net "M_L_CPU1_SB_DQS_DP<2>")
	)
	(segment
		(start 147.895564 -286.578548)
		(end 147.919186 -286.578548)
		(width 0.09525)
		(layer "In11.Cu")
		(net "M_L_CPU1_SB_DQS_DP<2>")
	)
	(segment
		(start 180.094382 -303.710086)
		(end 180.422042 -304.037746)
		(width 0.16002)
		(layer "In11.Cu")
		(net "M_L_CPU1_SB_DQS_DP<2>")
	)
	(segment
		(start 202.948286 -303.654206)
		(end 203.347066 -304.052986)
		(width 0.16002)
		(layer "In11.Cu")
		(net "M_L_CPU1_SB_DQS_DP<2>")
	)
	(segment
		(start 147.341844 -286.419036)
		(end 147.560284 -286.637476)
		(width 0.09525)
		(layer "In11.Cu")
		(net "M_L_CPU1_SB_DQS_DP<2>")
	)
	(segment
		(start 200.52665 -303.654206)
		(end 202.948286 -303.654206)
		(width 0.16002)
		(layer "In11.Cu")
		(net "M_L_CPU1_SB_DQS_DP<2>")
	)
	(segment
		(start 144.315434 -285.751524)
		(end 144.323816 -285.75635)
		(width 0.09525)
		(layer "In11.Cu")
		(net "M_L_CPU1_SB_DQS_DP<2>")
	)
	(arc
		(start 142.436088 -285.751524)
		(mid 142.619863 -285.802296)
		(end 142.804896 -285.75635)
		(width 0.09525)
		(layer "In11.Cu")
		(net "M_L_CPU1_SB_DQS_DP<2>")
	)
	(arc
		(start 140.933424 -285.751524)
		(mid 141.214856 -285.675769)
		(end 141.496288 -285.751524)
		(width 0.09525)
		(layer "In11.Cu")
		(net "M_L_CPU1_SB_DQS_DP<2>")
	)
	(arc
		(start 139.99337 -285.751524)
		(mid 140.274802 -285.675769)
		(end 140.556234 -285.751524)
		(width 0.09525)
		(layer "In11.Cu")
		(net "M_L_CPU1_SB_DQS_DP<2>")
	)
	(arc
		(start 144.71015 -285.74111)
		(mid 144.984292 -285.675531)
		(end 145.255742 -285.751524)
		(width 0.09525)
		(layer "In11.Cu")
		(net "M_L_CPU1_SB_DQS_DP<2>")
	)
	(arc
		(start 145.255742 -285.751524)
		(mid 145.346802 -285.78992)
		(end 145.444718 -285.80334)
		(width 0.09525)
		(layer "In11.Cu")
		(net "M_L_CPU1_SB_DQS_DP<2>")
	)
	(arc
		(start 140.564616 -285.75635)
		(mid 140.749648 -285.802264)
		(end 140.933424 -285.751524)
		(width 0.09525)
		(layer "In11.Cu")
		(net "M_L_CPU1_SB_DQS_DP<2>")
	)
	(arc
		(start 139.674092 -285.778702)
		(mid 139.836774 -285.800834)
		(end 139.99337 -285.751524)
		(width 0.09525)
		(layer "In11.Cu")
		(net "M_L_CPU1_SB_DQS_DP<2>")
	)
	(arc
		(start 143.753332 -285.751524)
		(mid 144.02402 -285.675872)
		(end 144.2974 -285.74111)
		(width 0.09525)
		(layer "In11.Cu")
		(net "M_L_CPU1_SB_DQS_DP<2>")
	)
	(arc
		(start 143.384524 -285.75635)
		(mid 143.569556 -285.802264)
		(end 143.753332 -285.751524)
		(width 0.09525)
		(layer "In11.Cu")
		(net "M_L_CPU1_SB_DQS_DP<2>")
	)
	(arc
		(start 141.496288 -285.751524)
		(mid 141.684756 -285.802201)
		(end 141.873224 -285.751524)
		(width 0.09525)
		(layer "In11.Cu")
		(net "M_L_CPU1_SB_DQS_DP<2>")
	)
	(arc
		(start 144.323816 -285.75635)
		(mid 144.508594 -285.802143)
		(end 144.692116 -285.751524)
		(width 0.09525)
		(layer "In11.Cu")
		(net "M_L_CPU1_SB_DQS_DP<2>")
	)
	(arc
		(start 142.813278 -285.751524)
		(mid 143.09471 -285.675769)
		(end 143.376142 -285.751524)
		(width 0.09525)
		(layer "In11.Cu")
		(net "M_L_CPU1_SB_DQS_DP<2>")
	)
	(arc
		(start 141.873224 -285.751524)
		(mid 142.154656 -285.675769)
		(end 142.436088 -285.751524)
		(width 0.09525)
		(layer "In11.Cu")
		(net "M_L_CPU1_SB_DQS_DP<2>")
	)
	(segment
		(start 139.337796 -280.30043)
		(end 139.804648 -280.566368)
		(width 0.12954)
		(layer "F.Cu")
		(net "M_L_CPU1_SB_DQS_DP<1>")
	)
	(segment
		(start 140.556234 -280.891488)
		(end 140.564616 -280.896314)
		(width 0.09525)
		(layer "In11.Cu")
		(net "M_L_CPU1_SB_DQS_DP<1>")
	)
	(segment
		(start 172.877988 -294.687752)
		(end 173.601888 -294.687752)
		(width 0.16002)
		(layer "In11.Cu")
		(net "M_L_CPU1_SB_DQS_DP<1>")
	)
	(segment
		(start 177.100484 -293.510208)
		(end 177.950368 -294.360092)
		(width 0.16002)
		(layer "In11.Cu")
		(net "M_L_CPU1_SB_DQS_DP<1>")
	)
	(segment
		(start 144.692116 -280.891488)
		(end 144.71015 -280.881074)
		(width 0.09525)
		(layer "In11.Cu")
		(net "M_L_CPU1_SB_DQS_DP<1>")
	)
	(segment
		(start 144.2974 -280.881074)
		(end 144.315434 -280.891488)
		(width 0.09525)
		(layer "In11.Cu")
		(net "M_L_CPU1_SB_DQS_DP<1>")
	)
	(segment
		(start 187.966096 -294.687752)
		(end 188.689996 -294.687752)
		(width 0.16002)
		(layer "In11.Cu")
		(net "M_L_CPU1_SB_DQS_DP<1>")
	)
	(segment
		(start 205.974188 -294.50919)
		(end 206.248 -294.235378)
		(width 0.16002)
		(layer "In11.Cu")
		(net "M_L_CPU1_SB_DQS_DP<1>")
	)
	(segment
		(start 187.638436 -294.360092)
		(end 187.966096 -294.687752)
		(width 0.16002)
		(layer "In11.Cu")
		(net "M_L_CPU1_SB_DQS_DP<1>")
	)
	(segment
		(start 147.895564 -280.926794)
		(end 147.919186 -280.926794)
		(width 0.09525)
		(layer "In11.Cu")
		(net "M_L_CPU1_SB_DQS_DP<1>")
	)
	(segment
		(start 147.919186 -280.926794)
		(end 150.445216 -280.926794)
		(width 0.16002)
		(layer "In11.Cu")
		(net "M_L_CPU1_SB_DQS_DP<1>")
	)
	(segment
		(start 190.27902 -293.510208)
		(end 192.188592 -293.510208)
		(width 0.16002)
		(layer "In11.Cu")
		(net "M_L_CPU1_SB_DQS_DP<1>")
	)
	(segment
		(start 142.804896 -280.896314)
		(end 142.813278 -280.891488)
		(width 0.09525)
		(layer "In11.Cu")
		(net "M_L_CPU1_SB_DQS_DP<1>")
	)
	(segment
		(start 170.406314 -294.360092)
		(end 172.550328 -294.360092)
		(width 0.16002)
		(layer "In11.Cu")
		(net "M_L_CPU1_SB_DQS_DP<1>")
	)
	(segment
		(start 175.190912 -293.510208)
		(end 177.100484 -293.510208)
		(width 0.16002)
		(layer "In11.Cu")
		(net "M_L_CPU1_SB_DQS_DP<1>")
	)
	(segment
		(start 150.445216 -280.926794)
		(end 164.206174 -294.687752)
		(width 0.16002)
		(layer "In11.Cu")
		(net "M_L_CPU1_SB_DQS_DP<1>")
	)
	(segment
		(start 205.36408 -294.50919)
		(end 205.974188 -294.50919)
		(width 0.16002)
		(layer "In11.Cu")
		(net "M_L_CPU1_SB_DQS_DP<1>")
	)
	(segment
		(start 197.823074 -293.510208)
		(end 199.732646 -293.510208)
		(width 0.16002)
		(layer "In11.Cu")
		(net "M_L_CPU1_SB_DQS_DP<1>")
	)
	(segment
		(start 167.292274 -293.864792)
		(end 167.646858 -293.510208)
		(width 0.16002)
		(layer "In11.Cu")
		(net "M_L_CPU1_SB_DQS_DP<1>")
	)
	(segment
		(start 204.75702 -294.38219)
		(end 205.23708 -294.38219)
		(width 0.16002)
		(layer "In11.Cu")
		(net "M_L_CPU1_SB_DQS_DP<1>")
	)
	(segment
		(start 196.23405 -294.687752)
		(end 197.05701 -293.864792)
		(width 0.16002)
		(layer "In11.Cu")
		(net "M_L_CPU1_SB_DQS_DP<1>")
	)
	(segment
		(start 174.424848 -293.864792)
		(end 174.836328 -293.864792)
		(width 0.16002)
		(layer "In11.Cu")
		(net "M_L_CPU1_SB_DQS_DP<1>")
	)
	(segment
		(start 145.444718 -280.943304)
		(end 145.856452 -280.943304)
		(width 0.09525)
		(layer "In11.Cu")
		(net "M_L_CPU1_SB_DQS_DP<1>")
	)
	(segment
		(start 195.51015 -294.687752)
		(end 196.23405 -294.687752)
		(width 0.16002)
		(layer "In11.Cu")
		(net "M_L_CPU1_SB_DQS_DP<1>")
	)
	(segment
		(start 181.968902 -293.864792)
		(end 182.380382 -293.864792)
		(width 0.16002)
		(layer "In11.Cu")
		(net "M_L_CPU1_SB_DQS_DP<1>")
	)
	(segment
		(start 167.646858 -293.510208)
		(end 169.55643 -293.510208)
		(width 0.16002)
		(layer "In11.Cu")
		(net "M_L_CPU1_SB_DQS_DP<1>")
	)
	(segment
		(start 182.734966 -293.510208)
		(end 184.644538 -293.510208)
		(width 0.16002)
		(layer "In11.Cu")
		(net "M_L_CPU1_SB_DQS_DP<1>")
	)
	(segment
		(start 193.038476 -294.360092)
		(end 195.18249 -294.360092)
		(width 0.16002)
		(layer "In11.Cu")
		(net "M_L_CPU1_SB_DQS_DP<1>")
	)
	(segment
		(start 200.306686 -294.084248)
		(end 202.728322 -294.084248)
		(width 0.16002)
		(layer "In11.Cu")
		(net "M_L_CPU1_SB_DQS_DP<1>")
	)
	(segment
		(start 169.55643 -293.510208)
		(end 170.406314 -294.360092)
		(width 0.16002)
		(layer "In11.Cu")
		(net "M_L_CPU1_SB_DQS_DP<1>")
	)
	(segment
		(start 147.259548 -280.535126)
		(end 147.710398 -280.985976)
		(width 0.09525)
		(layer "In11.Cu")
		(net "M_L_CPU1_SB_DQS_DP<1>")
	)
	(segment
		(start 173.601888 -294.687752)
		(end 174.424848 -293.864792)
		(width 0.16002)
		(layer "In11.Cu")
		(net "M_L_CPU1_SB_DQS_DP<1>")
	)
	(segment
		(start 147.836382 -280.985976)
		(end 147.895564 -280.926794)
		(width 0.09525)
		(layer "In11.Cu")
		(net "M_L_CPU1_SB_DQS_DP<1>")
	)
	(segment
		(start 185.494422 -294.360092)
		(end 187.638436 -294.360092)
		(width 0.16002)
		(layer "In11.Cu")
		(net "M_L_CPU1_SB_DQS_DP<1>")
	)
	(segment
		(start 174.836328 -293.864792)
		(end 175.190912 -293.510208)
		(width 0.16002)
		(layer "In11.Cu")
		(net "M_L_CPU1_SB_DQS_DP<1>")
	)
	(segment
		(start 172.550328 -294.360092)
		(end 172.877988 -294.687752)
		(width 0.16002)
		(layer "In11.Cu")
		(net "M_L_CPU1_SB_DQS_DP<1>")
	)
	(segment
		(start 139.804648 -280.566368)
		(end 139.650724 -280.831798)
		(width 0.09525)
		(layer "In11.Cu")
		(net "M_L_CPU1_SB_DQS_DP<1>")
	)
	(segment
		(start 144.315434 -280.891488)
		(end 144.323816 -280.896314)
		(width 0.09525)
		(layer "In11.Cu")
		(net "M_L_CPU1_SB_DQS_DP<1>")
	)
	(segment
		(start 189.924436 -293.864792)
		(end 190.27902 -293.510208)
		(width 0.16002)
		(layer "In11.Cu")
		(net "M_L_CPU1_SB_DQS_DP<1>")
	)
	(segment
		(start 197.05701 -293.864792)
		(end 197.46849 -293.864792)
		(width 0.16002)
		(layer "In11.Cu")
		(net "M_L_CPU1_SB_DQS_DP<1>")
	)
	(segment
		(start 203.955396 -294.50919)
		(end 204.63002 -294.50919)
		(width 0.16002)
		(layer "In11.Cu")
		(net "M_L_CPU1_SB_DQS_DP<1>")
	)
	(segment
		(start 189.512956 -293.864792)
		(end 189.924436 -293.864792)
		(width 0.16002)
		(layer "In11.Cu")
		(net "M_L_CPU1_SB_DQS_DP<1>")
	)
	(segment
		(start 180.094382 -294.360092)
		(end 180.422042 -294.687752)
		(width 0.16002)
		(layer "In11.Cu")
		(net "M_L_CPU1_SB_DQS_DP<1>")
	)
	(segment
		(start 188.689996 -294.687752)
		(end 189.512956 -293.864792)
		(width 0.16002)
		(layer "In11.Cu")
		(net "M_L_CPU1_SB_DQS_DP<1>")
	)
	(segment
		(start 181.145942 -294.687752)
		(end 181.968902 -293.864792)
		(width 0.16002)
		(layer "In11.Cu")
		(net "M_L_CPU1_SB_DQS_DP<1>")
	)
	(segment
		(start 205.23708 -294.38219)
		(end 205.36408 -294.50919)
		(width 0.16002)
		(layer "In11.Cu")
		(net "M_L_CPU1_SB_DQS_DP<1>")
	)
	(segment
		(start 146.26463 -280.535126)
		(end 147.259548 -280.535126)
		(width 0.09525)
		(layer "In11.Cu")
		(net "M_L_CPU1_SB_DQS_DP<1>")
	)
	(segment
		(start 182.380382 -293.864792)
		(end 182.734966 -293.510208)
		(width 0.16002)
		(layer "In11.Cu")
		(net "M_L_CPU1_SB_DQS_DP<1>")
	)
	(segment
		(start 202.728322 -294.084248)
		(end 203.347066 -294.702992)
		(width 0.16002)
		(layer "In11.Cu")
		(net "M_L_CPU1_SB_DQS_DP<1>")
	)
	(segment
		(start 180.422042 -294.687752)
		(end 181.145942 -294.687752)
		(width 0.16002)
		(layer "In11.Cu")
		(net "M_L_CPU1_SB_DQS_DP<1>")
	)
	(segment
		(start 166.057834 -294.687752)
		(end 166.880794 -293.864792)
		(width 0.16002)
		(layer "In11.Cu")
		(net "M_L_CPU1_SB_DQS_DP<1>")
	)
	(segment
		(start 139.650724 -280.831798)
		(end 139.674092 -280.918666)
		(width 0.09525)
		(layer "In11.Cu")
		(net "M_L_CPU1_SB_DQS_DP<1>")
	)
	(segment
		(start 192.188592 -293.510208)
		(end 193.038476 -294.360092)
		(width 0.16002)
		(layer "In11.Cu")
		(net "M_L_CPU1_SB_DQS_DP<1>")
	)
	(segment
		(start 203.347066 -294.702992)
		(end 203.761594 -294.702992)
		(width 0.16002)
		(layer "In11.Cu")
		(net "M_L_CPU1_SB_DQS_DP<1>")
	)
	(segment
		(start 195.18249 -294.360092)
		(end 195.51015 -294.687752)
		(width 0.16002)
		(layer "In11.Cu")
		(net "M_L_CPU1_SB_DQS_DP<1>")
	)
	(segment
		(start 199.732646 -293.510208)
		(end 200.306686 -294.084248)
		(width 0.16002)
		(layer "In11.Cu")
		(net "M_L_CPU1_SB_DQS_DP<1>")
	)
	(segment
		(start 143.376142 -280.891488)
		(end 143.384524 -280.896314)
		(width 0.09525)
		(layer "In11.Cu")
		(net "M_L_CPU1_SB_DQS_DP<1>")
	)
	(segment
		(start 177.950368 -294.360092)
		(end 180.094382 -294.360092)
		(width 0.16002)
		(layer "In11.Cu")
		(net "M_L_CPU1_SB_DQS_DP<1>")
	)
	(segment
		(start 147.710398 -280.985976)
		(end 147.836382 -280.985976)
		(width 0.09525)
		(layer "In11.Cu")
		(net "M_L_CPU1_SB_DQS_DP<1>")
	)
	(segment
		(start 164.206174 -294.687752)
		(end 166.057834 -294.687752)
		(width 0.16002)
		(layer "In11.Cu")
		(net "M_L_CPU1_SB_DQS_DP<1>")
	)
	(segment
		(start 184.644538 -293.510208)
		(end 185.494422 -294.360092)
		(width 0.16002)
		(layer "In11.Cu")
		(net "M_L_CPU1_SB_DQS_DP<1>")
	)
	(segment
		(start 204.63002 -294.50919)
		(end 204.75702 -294.38219)
		(width 0.16002)
		(layer "In11.Cu")
		(net "M_L_CPU1_SB_DQS_DP<1>")
	)
	(segment
		(start 203.761594 -294.702992)
		(end 203.955396 -294.50919)
		(width 0.16002)
		(layer "In11.Cu")
		(net "M_L_CPU1_SB_DQS_DP<1>")
	)
	(segment
		(start 145.856452 -280.943304)
		(end 146.26463 -280.535126)
		(width 0.09525)
		(layer "In11.Cu")
		(net "M_L_CPU1_SB_DQS_DP<1>")
	)
	(segment
		(start 166.880794 -293.864792)
		(end 167.292274 -293.864792)
		(width 0.16002)
		(layer "In11.Cu")
		(net "M_L_CPU1_SB_DQS_DP<1>")
	)
	(segment
		(start 197.46849 -293.864792)
		(end 197.823074 -293.510208)
		(width 0.16002)
		(layer "In11.Cu")
		(net "M_L_CPU1_SB_DQS_DP<1>")
	)
	(arc
		(start 141.496288 -280.891488)
		(mid 141.684756 -280.942165)
		(end 141.873224 -280.891488)
		(width 0.09525)
		(layer "In11.Cu")
		(net "M_L_CPU1_SB_DQS_DP<1>")
	)
	(arc
		(start 140.933424 -280.891488)
		(mid 141.214856 -280.815733)
		(end 141.496288 -280.891488)
		(width 0.09525)
		(layer "In11.Cu")
		(net "M_L_CPU1_SB_DQS_DP<1>")
	)
	(arc
		(start 140.564616 -280.896314)
		(mid 140.749648 -280.942228)
		(end 140.933424 -280.891488)
		(width 0.09525)
		(layer "In11.Cu")
		(net "M_L_CPU1_SB_DQS_DP<1>")
	)
	(arc
		(start 144.71015 -280.881074)
		(mid 144.984292 -280.815495)
		(end 145.255742 -280.891488)
		(width 0.09525)
		(layer "In11.Cu")
		(net "M_L_CPU1_SB_DQS_DP<1>")
	)
	(arc
		(start 142.813278 -280.891488)
		(mid 143.09471 -280.815733)
		(end 143.376142 -280.891488)
		(width 0.09525)
		(layer "In11.Cu")
		(net "M_L_CPU1_SB_DQS_DP<1>")
	)
	(arc
		(start 143.753332 -280.891488)
		(mid 144.02402 -280.815836)
		(end 144.2974 -280.881074)
		(width 0.09525)
		(layer "In11.Cu")
		(net "M_L_CPU1_SB_DQS_DP<1>")
	)
	(arc
		(start 139.99337 -280.891488)
		(mid 140.274802 -280.815733)
		(end 140.556234 -280.891488)
		(width 0.09525)
		(layer "In11.Cu")
		(net "M_L_CPU1_SB_DQS_DP<1>")
	)
	(arc
		(start 145.255742 -280.891488)
		(mid 145.346802 -280.929884)
		(end 145.444718 -280.943304)
		(width 0.09525)
		(layer "In11.Cu")
		(net "M_L_CPU1_SB_DQS_DP<1>")
	)
	(arc
		(start 139.674092 -280.918666)
		(mid 139.836774 -280.940798)
		(end 139.99337 -280.891488)
		(width 0.09525)
		(layer "In11.Cu")
		(net "M_L_CPU1_SB_DQS_DP<1>")
	)
	(arc
		(start 142.436088 -280.891488)
		(mid 142.619863 -280.94226)
		(end 142.804896 -280.896314)
		(width 0.09525)
		(layer "In11.Cu")
		(net "M_L_CPU1_SB_DQS_DP<1>")
	)
	(arc
		(start 144.323816 -280.896314)
		(mid 144.508594 -280.942107)
		(end 144.692116 -280.891488)
		(width 0.09525)
		(layer "In11.Cu")
		(net "M_L_CPU1_SB_DQS_DP<1>")
	)
	(arc
		(start 143.384524 -280.896314)
		(mid 143.569556 -280.942228)
		(end 143.753332 -280.891488)
		(width 0.09525)
		(layer "In11.Cu")
		(net "M_L_CPU1_SB_DQS_DP<1>")
	)
	(arc
		(start 141.873224 -280.891488)
		(mid 142.154656 -280.815733)
		(end 142.436088 -280.891488)
		(width 0.09525)
		(layer "In11.Cu")
		(net "M_L_CPU1_SB_DQS_DP<1>")
	)
	(segment
		(start 139.337796 -275.440394)
		(end 139.804648 -275.706332)
		(width 0.12954)
		(layer "F.Cu")
		(net "M_L_CPU1_SB_DQS_DP<0>")
	)
	(segment
		(start 180.422042 -285.337758)
		(end 181.145942 -285.337758)
		(width 0.16002)
		(layer "In11.Cu")
		(net "M_L_CPU1_SB_DQS_DP<0>")
	)
	(segment
		(start 195.51015 -285.337758)
		(end 196.23405 -285.337758)
		(width 0.16002)
		(layer "In11.Cu")
		(net "M_L_CPU1_SB_DQS_DP<0>")
	)
	(segment
		(start 140.556234 -276.031452)
		(end 140.564616 -276.036278)
		(width 0.09525)
		(layer "In11.Cu")
		(net "M_L_CPU1_SB_DQS_DP<0>")
	)
	(segment
		(start 144.2974 -276.021038)
		(end 144.315434 -276.031452)
		(width 0.09525)
		(layer "In11.Cu")
		(net "M_L_CPU1_SB_DQS_DP<0>")
	)
	(segment
		(start 152.838658 -274.89785)
		(end 162.705542 -284.764734)
		(width 0.16002)
		(layer "In11.Cu")
		(net "M_L_CPU1_SB_DQS_DP<0>")
	)
	(segment
		(start 192.188592 -284.160214)
		(end 193.038476 -285.010098)
		(width 0.16002)
		(layer "In11.Cu")
		(net "M_L_CPU1_SB_DQS_DP<0>")
	)
	(segment
		(start 147.895564 -274.89785)
		(end 147.919186 -274.89785)
		(width 0.09525)
		(layer "In11.Cu")
		(net "M_L_CPU1_SB_DQS_DP<0>")
	)
	(segment
		(start 175.190912 -284.160214)
		(end 177.100484 -284.160214)
		(width 0.16002)
		(layer "In11.Cu")
		(net "M_L_CPU1_SB_DQS_DP<0>")
	)
	(segment
		(start 177.950368 -285.010098)
		(end 180.094382 -285.010098)
		(width 0.16002)
		(layer "In11.Cu")
		(net "M_L_CPU1_SB_DQS_DP<0>")
	)
	(segment
		(start 167.292274 -284.514798)
		(end 167.646858 -284.160214)
		(width 0.16002)
		(layer "In11.Cu")
		(net "M_L_CPU1_SB_DQS_DP<0>")
	)
	(segment
		(start 204.760068 -285.159196)
		(end 204.887068 -285.032196)
		(width 0.16002)
		(layer "In11.Cu")
		(net "M_L_CPU1_SB_DQS_DP<0>")
	)
	(segment
		(start 172.550328 -285.010098)
		(end 172.877988 -285.337758)
		(width 0.16002)
		(layer "In11.Cu")
		(net "M_L_CPU1_SB_DQS_DP<0>")
	)
	(segment
		(start 203.347066 -285.352998)
		(end 203.761594 -285.352998)
		(width 0.16002)
		(layer "In11.Cu")
		(net "M_L_CPU1_SB_DQS_DP<0>")
	)
	(segment
		(start 169.917618 -284.160214)
		(end 170.767502 -285.010098)
		(width 0.16002)
		(layer "In11.Cu")
		(net "M_L_CPU1_SB_DQS_DP<0>")
	)
	(segment
		(start 193.038476 -285.010098)
		(end 195.18249 -285.010098)
		(width 0.16002)
		(layer "In11.Cu")
		(net "M_L_CPU1_SB_DQS_DP<0>")
	)
	(segment
		(start 200.306686 -284.734254)
		(end 202.728322 -284.734254)
		(width 0.16002)
		(layer "In11.Cu")
		(net "M_L_CPU1_SB_DQS_DP<0>")
	)
	(segment
		(start 144.692116 -276.031452)
		(end 144.71015 -276.021038)
		(width 0.09525)
		(layer "In11.Cu")
		(net "M_L_CPU1_SB_DQS_DP<0>")
	)
	(segment
		(start 185.494422 -285.010098)
		(end 187.638436 -285.010098)
		(width 0.16002)
		(layer "In11.Cu")
		(net "M_L_CPU1_SB_DQS_DP<0>")
	)
	(segment
		(start 147.919186 -274.89785)
		(end 152.838658 -274.89785)
		(width 0.16002)
		(layer "In11.Cu")
		(net "M_L_CPU1_SB_DQS_DP<0>")
	)
	(segment
		(start 147.27301 -275.076666)
		(end 147.392898 -274.956778)
		(width 0.09525)
		(layer "In11.Cu")
		(net "M_L_CPU1_SB_DQS_DP<0>")
	)
	(segment
		(start 205.494128 -285.159196)
		(end 205.974188 -285.159196)
		(width 0.16002)
		(layer "In11.Cu")
		(net "M_L_CPU1_SB_DQS_DP<0>")
	)
	(segment
		(start 165.046406 -284.764734)
		(end 165.61943 -285.337758)
		(width 0.16002)
		(layer "In11.Cu")
		(net "M_L_CPU1_SB_DQS_DP<0>")
	)
	(segment
		(start 146.60626 -275.076666)
		(end 147.27301 -275.076666)
		(width 0.09525)
		(layer "In11.Cu")
		(net "M_L_CPU1_SB_DQS_DP<0>")
	)
	(segment
		(start 172.877988 -285.337758)
		(end 173.601888 -285.337758)
		(width 0.16002)
		(layer "In11.Cu")
		(net "M_L_CPU1_SB_DQS_DP<0>")
	)
	(segment
		(start 173.601888 -285.337758)
		(end 174.424848 -284.514798)
		(width 0.16002)
		(layer "In11.Cu")
		(net "M_L_CPU1_SB_DQS_DP<0>")
	)
	(segment
		(start 181.968902 -284.514798)
		(end 182.380382 -284.514798)
		(width 0.16002)
		(layer "In11.Cu")
		(net "M_L_CPU1_SB_DQS_DP<0>")
	)
	(segment
		(start 203.955396 -285.159196)
		(end 204.760068 -285.159196)
		(width 0.16002)
		(layer "In11.Cu")
		(net "M_L_CPU1_SB_DQS_DP<0>")
	)
	(segment
		(start 180.094382 -285.010098)
		(end 180.422042 -285.337758)
		(width 0.16002)
		(layer "In11.Cu")
		(net "M_L_CPU1_SB_DQS_DP<0>")
	)
	(segment
		(start 203.761594 -285.352998)
		(end 203.955396 -285.159196)
		(width 0.16002)
		(layer "In11.Cu")
		(net "M_L_CPU1_SB_DQS_DP<0>")
	)
	(segment
		(start 166.057834 -285.337758)
		(end 166.880794 -284.514798)
		(width 0.16002)
		(layer "In11.Cu")
		(net "M_L_CPU1_SB_DQS_DP<0>")
	)
	(segment
		(start 177.100484 -284.160214)
		(end 177.950368 -285.010098)
		(width 0.16002)
		(layer "In11.Cu")
		(net "M_L_CPU1_SB_DQS_DP<0>")
	)
	(segment
		(start 142.804896 -276.036278)
		(end 142.813278 -276.031452)
		(width 0.09525)
		(layer "In11.Cu")
		(net "M_L_CPU1_SB_DQS_DP<0>")
	)
	(segment
		(start 199.732646 -284.160214)
		(end 200.306686 -284.734254)
		(width 0.16002)
		(layer "In11.Cu")
		(net "M_L_CPU1_SB_DQS_DP<0>")
	)
	(segment
		(start 174.424848 -284.514798)
		(end 174.836328 -284.514798)
		(width 0.16002)
		(layer "In11.Cu")
		(net "M_L_CPU1_SB_DQS_DP<0>")
	)
	(segment
		(start 182.380382 -284.514798)
		(end 182.734966 -284.160214)
		(width 0.16002)
		(layer "In11.Cu")
		(net "M_L_CPU1_SB_DQS_DP<0>")
	)
	(segment
		(start 170.767502 -285.010098)
		(end 172.550328 -285.010098)
		(width 0.16002)
		(layer "In11.Cu")
		(net "M_L_CPU1_SB_DQS_DP<0>")
	)
	(segment
		(start 205.974188 -285.159196)
		(end 206.248 -284.885384)
		(width 0.16002)
		(layer "In11.Cu")
		(net "M_L_CPU1_SB_DQS_DP<0>")
	)
	(segment
		(start 166.880794 -284.514798)
		(end 167.292274 -284.514798)
		(width 0.16002)
		(layer "In11.Cu")
		(net "M_L_CPU1_SB_DQS_DP<0>")
	)
	(segment
		(start 187.966096 -285.337758)
		(end 188.689996 -285.337758)
		(width 0.16002)
		(layer "In11.Cu")
		(net "M_L_CPU1_SB_DQS_DP<0>")
	)
	(segment
		(start 165.61943 -285.337758)
		(end 166.057834 -285.337758)
		(width 0.16002)
		(layer "In11.Cu")
		(net "M_L_CPU1_SB_DQS_DP<0>")
	)
	(segment
		(start 195.18249 -285.010098)
		(end 195.51015 -285.337758)
		(width 0.16002)
		(layer "In11.Cu")
		(net "M_L_CPU1_SB_DQS_DP<0>")
	)
	(segment
		(start 190.27902 -284.160214)
		(end 192.188592 -284.160214)
		(width 0.16002)
		(layer "In11.Cu")
		(net "M_L_CPU1_SB_DQS_DP<0>")
	)
	(segment
		(start 197.05701 -284.514798)
		(end 197.46849 -284.514798)
		(width 0.16002)
		(layer "In11.Cu")
		(net "M_L_CPU1_SB_DQS_DP<0>")
	)
	(segment
		(start 189.512956 -284.514798)
		(end 189.924436 -284.514798)
		(width 0.16002)
		(layer "In11.Cu")
		(net "M_L_CPU1_SB_DQS_DP<0>")
	)
	(segment
		(start 145.710656 -275.97227)
		(end 146.60626 -275.076666)
		(width 0.09525)
		(layer "In11.Cu")
		(net "M_L_CPU1_SB_DQS_DP<0>")
	)
	(segment
		(start 202.728322 -284.734254)
		(end 203.347066 -285.352998)
		(width 0.16002)
		(layer "In11.Cu")
		(net "M_L_CPU1_SB_DQS_DP<0>")
	)
	(segment
		(start 196.23405 -285.337758)
		(end 197.05701 -284.514798)
		(width 0.16002)
		(layer "In11.Cu")
		(net "M_L_CPU1_SB_DQS_DP<0>")
	)
	(segment
		(start 197.823074 -284.160214)
		(end 199.732646 -284.160214)
		(width 0.16002)
		(layer "In11.Cu")
		(net "M_L_CPU1_SB_DQS_DP<0>")
	)
	(segment
		(start 187.638436 -285.010098)
		(end 187.966096 -285.337758)
		(width 0.16002)
		(layer "In11.Cu")
		(net "M_L_CPU1_SB_DQS_DP<0>")
	)
	(segment
		(start 205.367128 -285.032196)
		(end 205.494128 -285.159196)
		(width 0.16002)
		(layer "In11.Cu")
		(net "M_L_CPU1_SB_DQS_DP<0>")
	)
	(segment
		(start 174.836328 -284.514798)
		(end 175.190912 -284.160214)
		(width 0.16002)
		(layer "In11.Cu")
		(net "M_L_CPU1_SB_DQS_DP<0>")
	)
	(segment
		(start 181.145942 -285.337758)
		(end 181.968902 -284.514798)
		(width 0.16002)
		(layer "In11.Cu")
		(net "M_L_CPU1_SB_DQS_DP<0>")
	)
	(segment
		(start 144.315434 -276.031452)
		(end 144.323816 -276.036278)
		(width 0.09525)
		(layer "In11.Cu")
		(net "M_L_CPU1_SB_DQS_DP<0>")
	)
	(segment
		(start 188.689996 -285.337758)
		(end 189.512956 -284.514798)
		(width 0.16002)
		(layer "In11.Cu")
		(net "M_L_CPU1_SB_DQS_DP<0>")
	)
	(segment
		(start 143.376142 -276.031452)
		(end 143.384524 -276.036278)
		(width 0.09525)
		(layer "In11.Cu")
		(net "M_L_CPU1_SB_DQS_DP<0>")
	)
	(segment
		(start 147.392898 -274.956778)
		(end 147.836636 -274.956778)
		(width 0.09525)
		(layer "In11.Cu")
		(net "M_L_CPU1_SB_DQS_DP<0>")
	)
	(segment
		(start 162.705542 -284.764734)
		(end 165.046406 -284.764734)
		(width 0.16002)
		(layer "In11.Cu")
		(net "M_L_CPU1_SB_DQS_DP<0>")
	)
	(segment
		(start 139.804648 -275.706332)
		(end 139.650724 -275.971762)
		(width 0.09525)
		(layer "In11.Cu")
		(net "M_L_CPU1_SB_DQS_DP<0>")
	)
	(segment
		(start 182.734966 -284.160214)
		(end 184.644538 -284.160214)
		(width 0.16002)
		(layer "In11.Cu")
		(net "M_L_CPU1_SB_DQS_DP<0>")
	)
	(segment
		(start 184.644538 -284.160214)
		(end 185.494422 -285.010098)
		(width 0.16002)
		(layer "In11.Cu")
		(net "M_L_CPU1_SB_DQS_DP<0>")
	)
	(segment
		(start 189.924436 -284.514798)
		(end 190.27902 -284.160214)
		(width 0.16002)
		(layer "In11.Cu")
		(net "M_L_CPU1_SB_DQS_DP<0>")
	)
	(segment
		(start 147.836636 -274.956778)
		(end 147.895564 -274.89785)
		(width 0.09525)
		(layer "In11.Cu")
		(net "M_L_CPU1_SB_DQS_DP<0>")
	)
	(segment
		(start 139.650724 -275.971762)
		(end 139.674092 -276.05863)
		(width 0.09525)
		(layer "In11.Cu")
		(net "M_L_CPU1_SB_DQS_DP<0>")
	)
	(segment
		(start 167.646858 -284.160214)
		(end 169.917618 -284.160214)
		(width 0.16002)
		(layer "In11.Cu")
		(net "M_L_CPU1_SB_DQS_DP<0>")
	)
	(segment
		(start 197.46849 -284.514798)
		(end 197.823074 -284.160214)
		(width 0.16002)
		(layer "In11.Cu")
		(net "M_L_CPU1_SB_DQS_DP<0>")
	)
	(segment
		(start 204.887068 -285.032196)
		(end 205.367128 -285.032196)
		(width 0.16002)
		(layer "In11.Cu")
		(net "M_L_CPU1_SB_DQS_DP<0>")
	)
	(segment
		(start 145.615914 -276.041104)
		(end 145.632678 -276.031452)
		(width 0.09525)
		(layer "In11.Cu")
		(net "M_L_CPU1_SB_DQS_DP<0>")
	)
	(arc
		(start 145.632678 -276.031452)
		(mid 145.673608 -276.004418)
		(end 145.710656 -275.97227)
		(width 0.09525)
		(layer "In11.Cu")
		(net "M_L_CPU1_SB_DQS_DP<0>")
	)
	(arc
		(start 139.99337 -276.031452)
		(mid 140.274802 -275.955697)
		(end 140.556234 -276.031452)
		(width 0.09525)
		(layer "In11.Cu")
		(net "M_L_CPU1_SB_DQS_DP<0>")
	)
	(arc
		(start 140.933424 -276.031452)
		(mid 141.214856 -275.955697)
		(end 141.496288 -276.031452)
		(width 0.09525)
		(layer "In11.Cu")
		(net "M_L_CPU1_SB_DQS_DP<0>")
	)
	(arc
		(start 143.384524 -276.036278)
		(mid 143.569556 -276.082192)
		(end 143.753332 -276.031452)
		(width 0.09525)
		(layer "In11.Cu")
		(net "M_L_CPU1_SB_DQS_DP<0>")
	)
	(arc
		(start 139.674092 -276.05863)
		(mid 139.836774 -276.080762)
		(end 139.99337 -276.031452)
		(width 0.09525)
		(layer "In11.Cu")
		(net "M_L_CPU1_SB_DQS_DP<0>")
	)
	(arc
		(start 141.873224 -276.031452)
		(mid 142.154656 -275.955697)
		(end 142.436088 -276.031452)
		(width 0.09525)
		(layer "In11.Cu")
		(net "M_L_CPU1_SB_DQS_DP<0>")
	)
	(arc
		(start 141.496288 -276.031452)
		(mid 141.684756 -276.082129)
		(end 141.873224 -276.031452)
		(width 0.09525)
		(layer "In11.Cu")
		(net "M_L_CPU1_SB_DQS_DP<0>")
	)
	(arc
		(start 144.323816 -276.036278)
		(mid 144.508594 -276.082071)
		(end 144.692116 -276.031452)
		(width 0.09525)
		(layer "In11.Cu")
		(net "M_L_CPU1_SB_DQS_DP<0>")
	)
	(arc
		(start 144.71015 -276.021038)
		(mid 144.984292 -275.955459)
		(end 145.255742 -276.031452)
		(width 0.09525)
		(layer "In11.Cu")
		(net "M_L_CPU1_SB_DQS_DP<0>")
	)
	(arc
		(start 143.753332 -276.031452)
		(mid 144.02402 -275.9558)
		(end 144.2974 -276.021038)
		(width 0.09525)
		(layer "In11.Cu")
		(net "M_L_CPU1_SB_DQS_DP<0>")
	)
	(arc
		(start 142.436088 -276.031452)
		(mid 142.619863 -276.082224)
		(end 142.804896 -276.036278)
		(width 0.09525)
		(layer "In11.Cu")
		(net "M_L_CPU1_SB_DQS_DP<0>")
	)
	(arc
		(start 140.564616 -276.036278)
		(mid 140.749648 -276.082192)
		(end 140.933424 -276.031452)
		(width 0.09525)
		(layer "In11.Cu")
		(net "M_L_CPU1_SB_DQS_DP<0>")
	)
	(arc
		(start 142.813278 -276.031452)
		(mid 143.09471 -275.955697)
		(end 143.376142 -276.031452)
		(width 0.09525)
		(layer "In11.Cu")
		(net "M_L_CPU1_SB_DQS_DP<0>")
	)
	(arc
		(start 145.255742 -276.031452)
		(mid 145.434602 -276.082248)
		(end 145.615914 -276.041104)
		(width 0.09525)
		(layer "In11.Cu")
		(net "M_L_CPU1_SB_DQS_DP<0>")
	)
	(segment
		(start 138.867896 -271.390364)
		(end 139.334748 -271.656302)
		(width 0.12954)
		(layer "F.Cu")
		(net "M_L_CPU1_SB_DQS_DN<9>")
	)
	(segment
		(start 197.593712 -275.467064)
		(end 197.948296 -275.11248)
		(width 0.16002)
		(layer "In11.Cu")
		(net "M_L_CPU1_SB_DQS_DN<9>")
	)
	(segment
		(start 195.384928 -276.290024)
		(end 196.359272 -276.290024)
		(width 0.16002)
		(layer "In11.Cu")
		(net "M_L_CPU1_SB_DQS_DN<9>")
	)
	(segment
		(start 179.96916 -275.962364)
		(end 180.29682 -276.290024)
		(width 0.16002)
		(layer "In11.Cu")
		(net "M_L_CPU1_SB_DQS_DN<9>")
	)
	(segment
		(start 147.895564 -269.555214)
		(end 147.919186 -269.555214)
		(width 0.09525)
		(layer "In11.Cu")
		(net "M_L_CPU1_SB_DQS_DN<9>")
	)
	(segment
		(start 147.836636 -269.496286)
		(end 147.895564 -269.555214)
		(width 0.09525)
		(layer "In11.Cu")
		(net "M_L_CPU1_SB_DQS_DN<9>")
	)
	(segment
		(start 187.513214 -275.962364)
		(end 187.840874 -276.290024)
		(width 0.16002)
		(layer "In11.Cu")
		(net "M_L_CPU1_SB_DQS_DN<9>")
	)
	(segment
		(start 141.394942 -271.326356)
		(end 141.403324 -271.331182)
		(width 0.09525)
		(layer "In11.Cu")
		(net "M_L_CPU1_SB_DQS_DN<9>")
	)
	(segment
		(start 166.183056 -276.290024)
		(end 167.006016 -275.467064)
		(width 0.16002)
		(layer "In11.Cu")
		(net "M_L_CPU1_SB_DQS_DN<9>")
	)
	(segment
		(start 196.359272 -276.290024)
		(end 197.182232 -275.467064)
		(width 0.16002)
		(layer "In11.Cu")
		(net "M_L_CPU1_SB_DQS_DN<9>")
	)
	(segment
		(start 203.886816 -276.305264)
		(end 204.080618 -276.111462)
		(width 0.16002)
		(layer "In11.Cu")
		(net "M_L_CPU1_SB_DQS_DN<9>")
	)
	(segment
		(start 190.404242 -275.11248)
		(end 192.06337 -275.11248)
		(width 0.16002)
		(layer "In11.Cu")
		(net "M_L_CPU1_SB_DQS_DN<9>")
	)
	(segment
		(start 147.919186 -269.555214)
		(end 157.612334 -269.555214)
		(width 0.16002)
		(layer "In11.Cu")
		(net "M_L_CPU1_SB_DQS_DN<9>")
	)
	(segment
		(start 141.966188 -271.331182)
		(end 141.97457 -271.326356)
		(width 0.09525)
		(layer "In11.Cu")
		(net "M_L_CPU1_SB_DQS_DN<9>")
	)
	(segment
		(start 190.049658 -275.467064)
		(end 190.404242 -275.11248)
		(width 0.16002)
		(layer "In11.Cu")
		(net "M_L_CPU1_SB_DQS_DN<9>")
	)
	(segment
		(start 174.96155 -275.467064)
		(end 175.316134 -275.11248)
		(width 0.16002)
		(layer "In11.Cu")
		(net "M_L_CPU1_SB_DQS_DN<9>")
	)
	(segment
		(start 195.057268 -275.962364)
		(end 195.384928 -276.290024)
		(width 0.16002)
		(layer "In11.Cu")
		(net "M_L_CPU1_SB_DQS_DN<9>")
	)
	(segment
		(start 171.929806 -275.467064)
		(end 172.752766 -276.290024)
		(width 0.16002)
		(layer "In11.Cu")
		(net "M_L_CPU1_SB_DQS_DN<9>")
	)
	(segment
		(start 181.271164 -276.290024)
		(end 182.094124 -275.467064)
		(width 0.16002)
		(layer "In11.Cu")
		(net "M_L_CPU1_SB_DQS_DN<9>")
	)
	(segment
		(start 197.182232 -275.467064)
		(end 197.593712 -275.467064)
		(width 0.16002)
		(layer "In11.Cu")
		(net "M_L_CPU1_SB_DQS_DN<9>")
	)
	(segment
		(start 139.488672 -271.390872)
		(end 139.58951 -271.364202)
		(width 0.09525)
		(layer "In11.Cu")
		(net "M_L_CPU1_SB_DQS_DN<9>")
	)
	(segment
		(start 139.334748 -271.656302)
		(end 139.488672 -271.390872)
		(width 0.09525)
		(layer "In11.Cu")
		(net "M_L_CPU1_SB_DQS_DN<9>")
	)
	(segment
		(start 192.06337 -275.11248)
		(end 192.913254 -275.962364)
		(width 0.16002)
		(layer "In11.Cu")
		(net "M_L_CPU1_SB_DQS_DN<9>")
	)
	(segment
		(start 184.519316 -275.11248)
		(end 185.3692 -275.962364)
		(width 0.16002)
		(layer "In11.Cu")
		(net "M_L_CPU1_SB_DQS_DN<9>")
	)
	(segment
		(start 176.975262 -275.11248)
		(end 177.825146 -275.962364)
		(width 0.16002)
		(layer "In11.Cu")
		(net "M_L_CPU1_SB_DQS_DN<9>")
	)
	(segment
		(start 144.785842 -271.331182)
		(end 144.823942 -271.309084)
		(width 0.09525)
		(layer "In11.Cu")
		(net "M_L_CPU1_SB_DQS_DN<9>")
	)
	(segment
		(start 180.29682 -276.290024)
		(end 181.271164 -276.290024)
		(width 0.16002)
		(layer "In11.Cu")
		(net "M_L_CPU1_SB_DQS_DN<9>")
	)
	(segment
		(start 200.181464 -275.68652)
		(end 202.6031 -275.68652)
		(width 0.16002)
		(layer "In11.Cu")
		(net "M_L_CPU1_SB_DQS_DN<9>")
	)
	(segment
		(start 185.3692 -275.962364)
		(end 187.513214 -275.962364)
		(width 0.16002)
		(layer "In11.Cu")
		(net "M_L_CPU1_SB_DQS_DN<9>")
	)
	(segment
		(start 147.477226 -269.496286)
		(end 147.836636 -269.496286)
		(width 0.09525)
		(layer "In11.Cu")
		(net "M_L_CPU1_SB_DQS_DN<9>")
	)
	(segment
		(start 157.612334 -269.555214)
		(end 164.347144 -276.290024)
		(width 0.16002)
		(layer "In11.Cu")
		(net "M_L_CPU1_SB_DQS_DN<9>")
	)
	(segment
		(start 204.080618 -276.111462)
		(end 205.974188 -276.111462)
		(width 0.16002)
		(layer "In11.Cu")
		(net "M_L_CPU1_SB_DQS_DN<9>")
	)
	(segment
		(start 175.316134 -275.11248)
		(end 176.975262 -275.11248)
		(width 0.16002)
		(layer "In11.Cu")
		(net "M_L_CPU1_SB_DQS_DN<9>")
	)
	(segment
		(start 205.974188 -276.111462)
		(end 206.248 -276.385274)
		(width 0.16002)
		(layer "In11.Cu")
		(net "M_L_CPU1_SB_DQS_DN<9>")
	)
	(segment
		(start 188.815218 -276.290024)
		(end 189.638178 -275.467064)
		(width 0.16002)
		(layer "In11.Cu")
		(net "M_L_CPU1_SB_DQS_DN<9>")
	)
	(segment
		(start 182.505604 -275.467064)
		(end 182.860188 -275.11248)
		(width 0.16002)
		(layer "In11.Cu")
		(net "M_L_CPU1_SB_DQS_DN<9>")
	)
	(segment
		(start 146.791172 -269.400528)
		(end 147.381468 -269.400528)
		(width 0.09525)
		(layer "In11.Cu")
		(net "M_L_CPU1_SB_DQS_DN<9>")
	)
	(segment
		(start 174.55007 -275.467064)
		(end 174.96155 -275.467064)
		(width 0.16002)
		(layer "In11.Cu")
		(net "M_L_CPU1_SB_DQS_DN<9>")
	)
	(segment
		(start 197.948296 -275.11248)
		(end 199.607424 -275.11248)
		(width 0.16002)
		(layer "In11.Cu")
		(net "M_L_CPU1_SB_DQS_DN<9>")
	)
	(segment
		(start 199.607424 -275.11248)
		(end 200.181464 -275.68652)
		(width 0.16002)
		(layer "In11.Cu")
		(net "M_L_CPU1_SB_DQS_DN<9>")
	)
	(segment
		(start 145.222214 -270.540734)
		(end 145.255996 -270.521176)
		(width 0.09525)
		(layer "In11.Cu")
		(net "M_L_CPU1_SB_DQS_DN<9>")
	)
	(segment
		(start 173.72711 -276.290024)
		(end 174.55007 -275.467064)
		(width 0.16002)
		(layer "In11.Cu")
		(net "M_L_CPU1_SB_DQS_DN<9>")
	)
	(segment
		(start 182.094124 -275.467064)
		(end 182.505604 -275.467064)
		(width 0.16002)
		(layer "In11.Cu")
		(net "M_L_CPU1_SB_DQS_DN<9>")
	)
	(segment
		(start 202.6031 -275.68652)
		(end 203.221844 -276.305264)
		(width 0.16002)
		(layer "In11.Cu")
		(net "M_L_CPU1_SB_DQS_DN<9>")
	)
	(segment
		(start 203.221844 -276.305264)
		(end 203.886816 -276.305264)
		(width 0.16002)
		(layer "In11.Cu")
		(net "M_L_CPU1_SB_DQS_DN<9>")
	)
	(segment
		(start 177.825146 -275.962364)
		(end 179.96916 -275.962364)
		(width 0.16002)
		(layer "In11.Cu")
		(net "M_L_CPU1_SB_DQS_DN<9>")
	)
	(segment
		(start 145.444718 -270.469868)
		(end 145.721832 -270.469868)
		(width 0.09525)
		(layer "In11.Cu")
		(net "M_L_CPU1_SB_DQS_DN<9>")
	)
	(segment
		(start 147.381468 -269.400528)
		(end 147.477226 -269.496286)
		(width 0.09525)
		(layer "In11.Cu")
		(net "M_L_CPU1_SB_DQS_DN<9>")
	)
	(segment
		(start 144.77492 -271.337278)
		(end 144.785334 -271.331182)
		(width 0.09525)
		(layer "In11.Cu")
		(net "M_L_CPU1_SB_DQS_DN<9>")
	)
	(segment
		(start 187.840874 -276.290024)
		(end 188.815218 -276.290024)
		(width 0.16002)
		(layer "In11.Cu")
		(net "M_L_CPU1_SB_DQS_DN<9>")
	)
	(segment
		(start 189.638178 -275.467064)
		(end 190.049658 -275.467064)
		(width 0.16002)
		(layer "In11.Cu")
		(net "M_L_CPU1_SB_DQS_DN<9>")
	)
	(segment
		(start 172.752766 -276.290024)
		(end 173.72711 -276.290024)
		(width 0.16002)
		(layer "In11.Cu")
		(net "M_L_CPU1_SB_DQS_DN<9>")
	)
	(segment
		(start 192.913254 -275.962364)
		(end 195.057268 -275.962364)
		(width 0.16002)
		(layer "In11.Cu")
		(net "M_L_CPU1_SB_DQS_DN<9>")
	)
	(segment
		(start 167.006016 -275.467064)
		(end 171.929806 -275.467064)
		(width 0.16002)
		(layer "In11.Cu")
		(net "M_L_CPU1_SB_DQS_DN<9>")
	)
	(segment
		(start 144.785334 -271.331182)
		(end 144.785842 -271.331182)
		(width 0.09525)
		(layer "In11.Cu")
		(net "M_L_CPU1_SB_DQS_DN<9>")
	)
	(segment
		(start 144.21485 -271.326356)
		(end 144.223232 -271.331182)
		(width 0.09525)
		(layer "In11.Cu")
		(net "M_L_CPU1_SB_DQS_DN<9>")
	)
	(segment
		(start 182.860188 -275.11248)
		(end 184.519316 -275.11248)
		(width 0.16002)
		(layer "In11.Cu")
		(net "M_L_CPU1_SB_DQS_DN<9>")
	)
	(segment
		(start 145.721832 -270.469868)
		(end 146.791172 -269.400528)
		(width 0.09525)
		(layer "In11.Cu")
		(net "M_L_CPU1_SB_DQS_DN<9>")
	)
	(segment
		(start 164.347144 -276.290024)
		(end 166.183056 -276.290024)
		(width 0.16002)
		(layer "In11.Cu")
		(net "M_L_CPU1_SB_DQS_DN<9>")
	)
	(segment
		(start 140.454888 -271.326356)
		(end 140.46327 -271.331182)
		(width 0.09525)
		(layer "In11.Cu")
		(net "M_L_CPU1_SB_DQS_DN<9>")
	)
	(arc
		(start 144.823942 -271.309084)
		(mid 145.002392 -271.107614)
		(end 145.066766 -270.846296)
		(width 0.09525)
		(layer "In11.Cu")
		(net "M_L_CPU1_SB_DQS_DN<9>")
	)
	(arc
		(start 143.846042 -271.331182)
		(mid 144.029817 -271.28041)
		(end 144.21485 -271.326356)
		(width 0.09525)
		(layer "In11.Cu")
		(net "M_L_CPU1_SB_DQS_DN<9>")
	)
	(arc
		(start 139.58951 -271.364202)
		(mid 139.599632 -271.368237)
		(end 139.60983 -271.372076)
		(width 0.09525)
		(layer "In11.Cu")
		(net "M_L_CPU1_SB_DQS_DN<9>")
	)
	(arc
		(start 141.026134 -271.331182)
		(mid 141.209909 -271.28041)
		(end 141.394942 -271.326356)
		(width 0.09525)
		(layer "In11.Cu")
		(net "M_L_CPU1_SB_DQS_DN<9>")
	)
	(arc
		(start 143.283178 -271.331182)
		(mid 143.56461 -271.406937)
		(end 143.846042 -271.331182)
		(width 0.09525)
		(layer "In11.Cu")
		(net "M_L_CPU1_SB_DQS_DN<9>")
	)
	(arc
		(start 142.343378 -271.331182)
		(mid 142.62481 -271.406937)
		(end 142.906242 -271.331182)
		(width 0.09525)
		(layer "In11.Cu")
		(net "M_L_CPU1_SB_DQS_DN<9>")
	)
	(arc
		(start 142.906242 -271.331182)
		(mid 143.09471 -271.280505)
		(end 143.283178 -271.331182)
		(width 0.09525)
		(layer "In11.Cu")
		(net "M_L_CPU1_SB_DQS_DN<9>")
	)
	(arc
		(start 139.60983 -271.372076)
		(mid 139.852542 -271.404959)
		(end 140.08608 -271.331182)
		(width 0.09525)
		(layer "In11.Cu")
		(net "M_L_CPU1_SB_DQS_DN<9>")
	)
	(arc
		(start 145.066766 -270.846296)
		(mid 145.107868 -270.67489)
		(end 145.222214 -270.540734)
		(width 0.09525)
		(layer "In11.Cu")
		(net "M_L_CPU1_SB_DQS_DN<9>")
	)
	(arc
		(start 145.255996 -270.521176)
		(mid 145.346962 -270.483023)
		(end 145.444718 -270.469868)
		(width 0.09525)
		(layer "In11.Cu")
		(net "M_L_CPU1_SB_DQS_DN<9>")
	)
	(arc
		(start 140.08608 -271.331182)
		(mid 140.269855 -271.28041)
		(end 140.454888 -271.326356)
		(width 0.09525)
		(layer "In11.Cu")
		(net "M_L_CPU1_SB_DQS_DN<9>")
	)
	(arc
		(start 144.223232 -271.331182)
		(mid 144.498267 -271.406776)
		(end 144.77492 -271.337278)
		(width 0.09525)
		(layer "In11.Cu")
		(net "M_L_CPU1_SB_DQS_DN<9>")
	)
	(arc
		(start 140.46327 -271.331182)
		(mid 140.744702 -271.406937)
		(end 141.026134 -271.331182)
		(width 0.09525)
		(layer "In11.Cu")
		(net "M_L_CPU1_SB_DQS_DN<9>")
	)
	(arc
		(start 141.97457 -271.326356)
		(mid 142.159602 -271.280442)
		(end 142.343378 -271.331182)
		(width 0.09525)
		(layer "In11.Cu")
		(net "M_L_CPU1_SB_DQS_DN<9>")
	)
	(arc
		(start 141.403324 -271.331182)
		(mid 141.684756 -271.406937)
		(end 141.966188 -271.331182)
		(width 0.09525)
		(layer "In11.Cu")
		(net "M_L_CPU1_SB_DQS_DN<9>")
	)
	(segment
		(start 137.927842 -290.830254)
		(end 138.394694 -291.096192)
		(width 0.12954)
		(layer "F.Cu")
		(net "M_L_CPU1_SB_DQS_DN<8>")
	)
	(segment
		(start 164.26561 -314.55614)
		(end 164.39261 -314.68314)
		(width 0.16002)
		(layer "In11.Cu")
		(net "M_L_CPU1_SB_DQS_DN<8>")
	)
	(segment
		(start 192.53454 -314.20816)
		(end 193.03111 -314.20816)
		(width 0.16002)
		(layer "In11.Cu")
		(net "M_L_CPU1_SB_DQS_DN<8>")
	)
	(segment
		(start 168.153842 -313.8297)
		(end 168.610026 -314.285884)
		(width 0.16002)
		(layer "In11.Cu")
		(net "M_L_CPU1_SB_DQS_DN<8>")
	)
	(segment
		(start 169.11828 -314.980066)
		(end 169.2783 -314.820046)
		(width 0.16002)
		(layer "In11.Cu")
		(net "M_L_CPU1_SB_DQS_DN<8>")
	)
	(segment
		(start 141.394942 -291.426138)
		(end 141.403324 -291.421312)
		(width 0.09525)
		(layer "In11.Cu")
		(net "M_L_CPU1_SB_DQS_DN<8>")
	)
	(segment
		(start 145.120868 -292.139116)
		(end 145.289524 -292.308026)
		(width 0.09525)
		(layer "In11.Cu")
		(net "M_L_CPU1_SB_DQS_DN<8>")
	)
	(segment
		(start 169.615358 -313.948826)
		(end 170.965876 -313.948826)
		(width 0.16002)
		(layer "In11.Cu")
		(net "M_L_CPU1_SB_DQS_DN<8>")
	)
	(segment
		(start 177.943002 -314.20816)
		(end 178.79314 -315.058298)
		(width 0.16002)
		(layer "In11.Cu")
		(net "M_L_CPU1_SB_DQS_DN<8>")
	)
	(segment
		(start 147.27555 -295.244266)
		(end 147.49907 -295.467786)
		(width 0.09525)
		(layer "In11.Cu")
		(net "M_L_CPU1_SB_DQS_DN<8>")
	)
	(segment
		(start 195.201032 -315.058298)
		(end 195.57619 -314.68314)
		(width 0.16002)
		(layer "In11.Cu")
		(net "M_L_CPU1_SB_DQS_DN<8>")
	)
	(segment
		(start 181.962806 -313.8297)
		(end 182.785258 -313.8297)
		(width 0.16002)
		(layer "In11.Cu")
		(net "M_L_CPU1_SB_DQS_DN<8>")
	)
	(segment
		(start 168.610026 -314.820046)
		(end 168.770046 -314.980066)
		(width 0.16002)
		(layer "In11.Cu")
		(net "M_L_CPU1_SB_DQS_DN<8>")
	)
	(segment
		(start 166.021258 -314.68314)
		(end 166.874698 -313.8297)
		(width 0.16002)
		(layer "In11.Cu")
		(net "M_L_CPU1_SB_DQS_DN<8>")
	)
	(segment
		(start 191.80048 -314.20816)
		(end 191.92748 -314.08116)
		(width 0.16002)
		(layer "In11.Cu")
		(net "M_L_CPU1_SB_DQS_DN<8>")
	)
	(segment
		(start 169.2783 -314.285884)
		(end 169.615358 -313.948826)
		(width 0.16002)
		(layer "In11.Cu")
		(net "M_L_CPU1_SB_DQS_DN<8>")
	)
	(segment
		(start 145.289524 -292.308026)
		(end 145.712942 -292.731444)
		(width 0.09525)
		(layer "In11.Cu")
		(net "M_L_CPU1_SB_DQS_DN<8>")
	)
	(segment
		(start 183.163718 -314.20816)
		(end 185.487056 -314.20816)
		(width 0.16002)
		(layer "In11.Cu")
		(net "M_L_CPU1_SB_DQS_DN<8>")
	)
	(segment
		(start 201.02068 -313.932316)
		(end 201.14768 -314.059316)
		(width 0.16002)
		(layer "In11.Cu")
		(net "M_L_CPU1_SB_DQS_DN<8>")
	)
	(segment
		(start 190.707772 -314.20816)
		(end 191.80048 -314.20816)
		(width 0.16002)
		(layer "In11.Cu")
		(net "M_L_CPU1_SB_DQS_DN<8>")
	)
	(segment
		(start 201.14768 -314.059316)
		(end 201.873866 -314.059316)
		(width 0.16002)
		(layer "In11.Cu")
		(net "M_L_CPU1_SB_DQS_DN<8>")
	)
	(segment
		(start 200.41362 -314.059316)
		(end 200.54062 -313.932316)
		(width 0.16002)
		(layer "In11.Cu")
		(net "M_L_CPU1_SB_DQS_DN<8>")
	)
	(segment
		(start 199.461374 -314.059316)
		(end 200.41362 -314.059316)
		(width 0.16002)
		(layer "In11.Cu")
		(net "M_L_CPU1_SB_DQS_DN<8>")
	)
	(segment
		(start 188.032136 -314.68314)
		(end 188.65342 -314.68314)
		(width 0.16002)
		(layer "In11.Cu")
		(net "M_L_CPU1_SB_DQS_DN<8>")
	)
	(segment
		(start 146.006566 -293.440612)
		(end 146.006566 -293.525956)
		(width 0.09525)
		(layer "In11.Cu")
		(net "M_L_CPU1_SB_DQS_DN<8>")
	)
	(segment
		(start 192.40754 -314.08116)
		(end 192.53454 -314.20816)
		(width 0.16002)
		(layer "In11.Cu")
		(net "M_L_CPU1_SB_DQS_DN<8>")
	)
	(segment
		(start 166.874698 -313.8297)
		(end 168.153842 -313.8297)
		(width 0.16002)
		(layer "In11.Cu")
		(net "M_L_CPU1_SB_DQS_DN<8>")
	)
	(segment
		(start 173.565312 -314.68314)
		(end 174.418752 -313.8297)
		(width 0.16002)
		(layer "In11.Cu")
		(net "M_L_CPU1_SB_DQS_DN<8>")
	)
	(segment
		(start 178.79314 -315.058298)
		(end 180.112924 -315.058298)
		(width 0.16002)
		(layer "In11.Cu")
		(net "M_L_CPU1_SB_DQS_DN<8>")
	)
	(segment
		(start 147.557998 -296.40276)
		(end 147.557998 -300.346872)
		(width 0.16002)
		(layer "In11.Cu")
		(net "M_L_CPU1_SB_DQS_DN<8>")
	)
	(segment
		(start 146.163538 -293.832534)
		(end 146.19605 -293.85133)
		(width 0.09525)
		(layer "In11.Cu")
		(net "M_L_CPU1_SB_DQS_DN<8>")
	)
	(segment
		(start 182.785258 -313.8297)
		(end 183.163718 -314.20816)
		(width 0.16002)
		(layer "In11.Cu")
		(net "M_L_CPU1_SB_DQS_DN<8>")
	)
	(segment
		(start 193.881248 -315.058298)
		(end 195.201032 -315.058298)
		(width 0.16002)
		(layer "In11.Cu")
		(net "M_L_CPU1_SB_DQS_DN<8>")
	)
	(segment
		(start 187.656978 -315.058298)
		(end 188.032136 -314.68314)
		(width 0.16002)
		(layer "In11.Cu")
		(net "M_L_CPU1_SB_DQS_DN<8>")
	)
	(segment
		(start 163.80841 -314.55614)
		(end 164.26561 -314.55614)
		(width 0.16002)
		(layer "In11.Cu")
		(net "M_L_CPU1_SB_DQS_DN<8>")
	)
	(segment
		(start 180.112924 -315.058298)
		(end 180.488082 -314.68314)
		(width 0.16002)
		(layer "In11.Cu")
		(net "M_L_CPU1_SB_DQS_DN<8>")
	)
	(segment
		(start 147.49907 -295.467786)
		(end 147.49907 -296.32021)
		(width 0.09525)
		(layer "In11.Cu")
		(net "M_L_CPU1_SB_DQS_DN<8>")
	)
	(segment
		(start 186.337194 -315.058298)
		(end 187.656978 -315.058298)
		(width 0.16002)
		(layer "In11.Cu")
		(net "M_L_CPU1_SB_DQS_DN<8>")
	)
	(segment
		(start 168.770046 -314.980066)
		(end 169.11828 -314.980066)
		(width 0.16002)
		(layer "In11.Cu")
		(net "M_L_CPU1_SB_DQS_DN<8>")
	)
	(segment
		(start 146.780758 -294.74922)
		(end 147.27555 -295.244266)
		(width 0.09525)
		(layer "In11.Cu")
		(net "M_L_CPU1_SB_DQS_DN<8>")
	)
	(segment
		(start 175.241204 -313.8297)
		(end 175.619664 -314.20816)
		(width 0.16002)
		(layer "In11.Cu")
		(net "M_L_CPU1_SB_DQS_DN<8>")
	)
	(segment
		(start 138.394694 -291.096192)
		(end 138.24077 -291.361622)
		(width 0.09525)
		(layer "In11.Cu")
		(net "M_L_CPU1_SB_DQS_DN<8>")
	)
	(segment
		(start 144.03451 -291.47262)
		(end 144.58569 -291.47262)
		(width 0.09525)
		(layer "In11.Cu")
		(net "M_L_CPU1_SB_DQS_DN<8>")
	)
	(segment
		(start 146.006566 -293.525956)
		(end 146.00682 -293.52621)
		(width 0.09525)
		(layer "In11.Cu")
		(net "M_L_CPU1_SB_DQS_DN<8>")
	)
	(segment
		(start 147.49907 -296.32021)
		(end 147.557998 -296.379138)
		(width 0.09525)
		(layer "In11.Cu")
		(net "M_L_CPU1_SB_DQS_DN<8>")
	)
	(segment
		(start 195.57619 -314.68314)
		(end 196.197474 -314.68314)
		(width 0.16002)
		(layer "In11.Cu")
		(net "M_L_CPU1_SB_DQS_DN<8>")
	)
	(segment
		(start 171.38777 -314.37072)
		(end 171.38777 -314.793884)
		(width 0.16002)
		(layer "In11.Cu")
		(net "M_L_CPU1_SB_DQS_DN<8>")
	)
	(segment
		(start 169.2783 -314.820046)
		(end 169.2783 -314.285884)
		(width 0.16002)
		(layer "In11.Cu")
		(net "M_L_CPU1_SB_DQS_DN<8>")
	)
	(segment
		(start 199.31253 -314.20816)
		(end 199.461374 -314.059316)
		(width 0.16002)
		(layer "In11.Cu")
		(net "M_L_CPU1_SB_DQS_DN<8>")
	)
	(segment
		(start 172.56887 -315.058298)
		(end 172.944028 -314.68314)
		(width 0.16002)
		(layer "In11.Cu")
		(net "M_L_CPU1_SB_DQS_DN<8>")
	)
	(segment
		(start 175.619664 -314.20816)
		(end 177.943002 -314.20816)
		(width 0.16002)
		(layer "In11.Cu")
		(net "M_L_CPU1_SB_DQS_DN<8>")
	)
	(segment
		(start 197.050914 -313.8297)
		(end 197.873366 -313.8297)
		(width 0.16002)
		(layer "In11.Cu")
		(net "M_L_CPU1_SB_DQS_DN<8>")
	)
	(segment
		(start 171.38777 -314.793884)
		(end 171.652184 -315.058298)
		(width 0.16002)
		(layer "In11.Cu")
		(net "M_L_CPU1_SB_DQS_DN<8>")
	)
	(segment
		(start 146.634454 -294.643048)
		(end 146.66595 -294.661336)
		(width 0.09525)
		(layer "In11.Cu")
		(net "M_L_CPU1_SB_DQS_DN<8>")
	)
	(segment
		(start 181.109366 -314.68314)
		(end 181.962806 -313.8297)
		(width 0.16002)
		(layer "In11.Cu")
		(net "M_L_CPU1_SB_DQS_DN<8>")
	)
	(segment
		(start 188.65342 -314.68314)
		(end 189.50686 -313.8297)
		(width 0.16002)
		(layer "In11.Cu")
		(net "M_L_CPU1_SB_DQS_DN<8>")
	)
	(segment
		(start 141.966188 -291.421312)
		(end 141.97457 -291.426138)
		(width 0.09525)
		(layer "In11.Cu")
		(net "M_L_CPU1_SB_DQS_DN<8>")
	)
	(segment
		(start 191.92748 -314.08116)
		(end 192.40754 -314.08116)
		(width 0.16002)
		(layer "In11.Cu")
		(net "M_L_CPU1_SB_DQS_DN<8>")
	)
	(segment
		(start 201.873866 -314.059316)
		(end 202.147932 -313.78525)
		(width 0.16002)
		(layer "In11.Cu")
		(net "M_L_CPU1_SB_DQS_DN<8>")
	)
	(segment
		(start 164.39261 -314.68314)
		(end 166.021258 -314.68314)
		(width 0.16002)
		(layer "In11.Cu")
		(net "M_L_CPU1_SB_DQS_DN<8>")
	)
	(segment
		(start 180.488082 -314.68314)
		(end 181.109366 -314.68314)
		(width 0.16002)
		(layer "In11.Cu")
		(net "M_L_CPU1_SB_DQS_DN<8>")
	)
	(segment
		(start 196.197474 -314.68314)
		(end 197.050914 -313.8297)
		(width 0.16002)
		(layer "In11.Cu")
		(net "M_L_CPU1_SB_DQS_DN<8>")
	)
	(segment
		(start 193.03111 -314.20816)
		(end 193.881248 -315.058298)
		(width 0.16002)
		(layer "In11.Cu")
		(net "M_L_CPU1_SB_DQS_DN<8>")
	)
	(segment
		(start 161.894266 -314.68314)
		(end 163.68141 -314.68314)
		(width 0.16002)
		(layer "In11.Cu")
		(net "M_L_CPU1_SB_DQS_DN<8>")
	)
	(segment
		(start 185.487056 -314.20816)
		(end 186.337194 -315.058298)
		(width 0.16002)
		(layer "In11.Cu")
		(net "M_L_CPU1_SB_DQS_DN<8>")
	)
	(segment
		(start 171.652184 -315.058298)
		(end 172.56887 -315.058298)
		(width 0.16002)
		(layer "In11.Cu")
		(net "M_L_CPU1_SB_DQS_DN<8>")
	)
	(segment
		(start 147.557998 -296.379138)
		(end 147.557998 -296.40276)
		(width 0.09525)
		(layer "In11.Cu")
		(net "M_L_CPU1_SB_DQS_DN<8>")
	)
	(segment
		(start 170.965876 -313.948826)
		(end 171.38777 -314.37072)
		(width 0.16002)
		(layer "In11.Cu")
		(net "M_L_CPU1_SB_DQS_DN<8>")
	)
	(segment
		(start 198.251826 -314.20816)
		(end 199.31253 -314.20816)
		(width 0.16002)
		(layer "In11.Cu")
		(net "M_L_CPU1_SB_DQS_DN<8>")
	)
	(segment
		(start 189.50686 -313.8297)
		(end 190.329312 -313.8297)
		(width 0.16002)
		(layer "In11.Cu")
		(net "M_L_CPU1_SB_DQS_DN<8>")
	)
	(segment
		(start 147.557998 -300.346872)
		(end 161.894266 -314.68314)
		(width 0.16002)
		(layer "In11.Cu")
		(net "M_L_CPU1_SB_DQS_DN<8>")
	)
	(segment
		(start 163.68141 -314.68314)
		(end 163.80841 -314.55614)
		(width 0.16002)
		(layer "In11.Cu")
		(net "M_L_CPU1_SB_DQS_DN<8>")
	)
	(segment
		(start 138.24077 -291.361622)
		(end 138.264138 -291.44849)
		(width 0.09525)
		(layer "In11.Cu")
		(net "M_L_CPU1_SB_DQS_DN<8>")
	)
	(segment
		(start 197.873366 -313.8297)
		(end 198.251826 -314.20816)
		(width 0.16002)
		(layer "In11.Cu")
		(net "M_L_CPU1_SB_DQS_DN<8>")
	)
	(segment
		(start 146.19605 -293.85133)
		(end 146.23415 -293.873428)
		(width 0.09525)
		(layer "In11.Cu")
		(net "M_L_CPU1_SB_DQS_DN<8>")
	)
	(segment
		(start 140.454888 -291.426138)
		(end 140.46327 -291.421312)
		(width 0.09525)
		(layer "In11.Cu")
		(net "M_L_CPU1_SB_DQS_DN<8>")
	)
	(segment
		(start 190.329312 -313.8297)
		(end 190.707772 -314.20816)
		(width 0.16002)
		(layer "In11.Cu")
		(net "M_L_CPU1_SB_DQS_DN<8>")
	)
	(segment
		(start 168.610026 -314.285884)
		(end 168.610026 -314.820046)
		(width 0.16002)
		(layer "In11.Cu")
		(net "M_L_CPU1_SB_DQS_DN<8>")
	)
	(segment
		(start 172.944028 -314.68314)
		(end 173.565312 -314.68314)
		(width 0.16002)
		(layer "In11.Cu")
		(net "M_L_CPU1_SB_DQS_DN<8>")
	)
	(segment
		(start 200.54062 -313.932316)
		(end 201.02068 -313.932316)
		(width 0.16002)
		(layer "In11.Cu")
		(net "M_L_CPU1_SB_DQS_DN<8>")
	)
	(segment
		(start 174.418752 -313.8297)
		(end 175.241204 -313.8297)
		(width 0.16002)
		(layer "In11.Cu")
		(net "M_L_CPU1_SB_DQS_DN<8>")
	)
	(arc
		(start 145.712942 -292.731444)
		(mid 145.930264 -293.056828)
		(end 146.006566 -293.440612)
		(width 0.09525)
		(layer "In11.Cu")
		(net "M_L_CPU1_SB_DQS_DN<8>")
	)
	(arc
		(start 146.723354 -294.699436)
		(mid 146.7529 -294.723355)
		(end 146.780758 -294.74922)
		(width 0.09525)
		(layer "In11.Cu")
		(net "M_L_CPU1_SB_DQS_DN<8>")
	)
	(arc
		(start 138.583416 -291.421312)
		(mid 138.864848 -291.345557)
		(end 139.14628 -291.421312)
		(width 0.09525)
		(layer "In11.Cu")
		(net "M_L_CPU1_SB_DQS_DN<8>")
	)
	(arc
		(start 142.343378 -291.421312)
		(mid 142.62481 -291.345557)
		(end 142.906242 -291.421312)
		(width 0.09525)
		(layer "In11.Cu")
		(net "M_L_CPU1_SB_DQS_DN<8>")
	)
	(arc
		(start 140.46327 -291.421312)
		(mid 140.744702 -291.345557)
		(end 141.026134 -291.421312)
		(width 0.09525)
		(layer "In11.Cu")
		(net "M_L_CPU1_SB_DQS_DN<8>")
	)
	(arc
		(start 140.08608 -291.421312)
		(mid 140.269855 -291.472084)
		(end 140.454888 -291.426138)
		(width 0.09525)
		(layer "In11.Cu")
		(net "M_L_CPU1_SB_DQS_DN<8>")
	)
	(arc
		(start 144.58569 -291.47262)
		(mid 144.753805 -291.505967)
		(end 144.896332 -291.601144)
		(width 0.09525)
		(layer "In11.Cu")
		(net "M_L_CPU1_SB_DQS_DN<8>")
	)
	(arc
		(start 143.846042 -291.421312)
		(mid 143.936885 -291.459431)
		(end 144.03451 -291.47262)
		(width 0.09525)
		(layer "In11.Cu")
		(net "M_L_CPU1_SB_DQS_DN<8>")
	)
	(arc
		(start 141.97457 -291.426138)
		(mid 142.159602 -291.472052)
		(end 142.343378 -291.421312)
		(width 0.09525)
		(layer "In11.Cu")
		(net "M_L_CPU1_SB_DQS_DN<8>")
	)
	(arc
		(start 139.14628 -291.421312)
		(mid 139.334748 -291.471989)
		(end 139.523216 -291.421312)
		(width 0.09525)
		(layer "In11.Cu")
		(net "M_L_CPU1_SB_DQS_DN<8>")
	)
	(arc
		(start 139.523216 -291.421312)
		(mid 139.804648 -291.345557)
		(end 140.08608 -291.421312)
		(width 0.09525)
		(layer "In11.Cu")
		(net "M_L_CPU1_SB_DQS_DN<8>")
	)
	(arc
		(start 141.403324 -291.421312)
		(mid 141.684756 -291.345557)
		(end 141.966188 -291.421312)
		(width 0.09525)
		(layer "In11.Cu")
		(net "M_L_CPU1_SB_DQS_DN<8>")
	)
	(arc
		(start 146.23415 -293.873428)
		(mid 146.4126 -294.074898)
		(end 146.476974 -294.336216)
		(width 0.09525)
		(layer "In11.Cu")
		(net "M_L_CPU1_SB_DQS_DN<8>")
	)
	(arc
		(start 143.283178 -291.421312)
		(mid 143.56461 -291.345557)
		(end 143.846042 -291.421312)
		(width 0.09525)
		(layer "In11.Cu")
		(net "M_L_CPU1_SB_DQS_DN<8>")
	)
	(arc
		(start 138.264138 -291.44849)
		(mid 138.42682 -291.470622)
		(end 138.583416 -291.421312)
		(width 0.09525)
		(layer "In11.Cu")
		(net "M_L_CPU1_SB_DQS_DN<8>")
	)
	(arc
		(start 141.026134 -291.421312)
		(mid 141.209909 -291.472084)
		(end 141.394942 -291.426138)
		(width 0.09525)
		(layer "In11.Cu")
		(net "M_L_CPU1_SB_DQS_DN<8>")
	)
	(arc
		(start 146.476974 -294.336216)
		(mid 146.518639 -294.508663)
		(end 146.634454 -294.643048)
		(width 0.09525)
		(layer "In11.Cu")
		(net "M_L_CPU1_SB_DQS_DN<8>")
	)
	(arc
		(start 145.0086 -291.869876)
		(mid 145.03815 -292.015587)
		(end 145.120868 -292.139116)
		(width 0.09525)
		(layer "In11.Cu")
		(net "M_L_CPU1_SB_DQS_DN<8>")
	)
	(arc
		(start 146.66595 -294.661336)
		(mid 146.695239 -294.679501)
		(end 146.723354 -294.699436)
		(width 0.09525)
		(layer "In11.Cu")
		(net "M_L_CPU1_SB_DQS_DN<8>")
	)
	(arc
		(start 142.906242 -291.421312)
		(mid 143.09471 -291.471989)
		(end 143.283178 -291.421312)
		(width 0.09525)
		(layer "In11.Cu")
		(net "M_L_CPU1_SB_DQS_DN<8>")
	)
	(arc
		(start 144.896332 -291.601144)
		(mid 144.979006 -291.724432)
		(end 145.0086 -291.869876)
		(width 0.09525)
		(layer "In11.Cu")
		(net "M_L_CPU1_SB_DQS_DN<8>")
	)
	(arc
		(start 146.00682 -293.52621)
		(mid 146.048277 -293.69825)
		(end 146.163538 -293.832534)
		(width 0.09525)
		(layer "In11.Cu")
		(net "M_L_CPU1_SB_DQS_DN<8>")
	)
	(segment
		(start 137.927842 -285.970472)
		(end 138.394694 -286.23641)
		(width 0.12954)
		(layer "F.Cu")
		(net "M_L_CPU1_SB_DQS_DN<7>")
	)
	(segment
		(start 157.049216 -300.42231)
		(end 157.127956 -300.343824)
		(width 0.16002)
		(layer "In11.Cu")
		(net "M_L_CPU1_SB_DQS_DN<7>")
	)
	(segment
		(start 156.655262 -299.394626)
		(end 156.655262 -299.870876)
		(width 0.16002)
		(layer "In11.Cu")
		(net "M_L_CPU1_SB_DQS_DN<7>")
	)
	(segment
		(start 138.394694 -286.23641)
		(end 138.24077 -286.50184)
		(width 0.09525)
		(layer "In11.Cu")
		(net "M_L_CPU1_SB_DQS_DN<7>")
	)
	(segment
		(start 183.163718 -304.858166)
		(end 185.487056 -304.858166)
		(width 0.16002)
		(layer "In11.Cu")
		(net "M_L_CPU1_SB_DQS_DN<7>")
	)
	(segment
		(start 201.873866 -304.709322)
		(end 202.147932 -304.435256)
		(width 0.16002)
		(layer "In11.Cu")
		(net "M_L_CPU1_SB_DQS_DN<7>")
	)
	(segment
		(start 190.329312 -304.479706)
		(end 190.707772 -304.858166)
		(width 0.16002)
		(layer "In11.Cu")
		(net "M_L_CPU1_SB_DQS_DN<7>")
	)
	(segment
		(start 171.36745 -305.708304)
		(end 172.56887 -305.708304)
		(width 0.16002)
		(layer "In11.Cu")
		(net "M_L_CPU1_SB_DQS_DN<7>")
	)
	(segment
		(start 158.028894 -300.768258)
		(end 158.028894 -301.244508)
		(width 0.16002)
		(layer "In11.Cu")
		(net "M_L_CPU1_SB_DQS_DN<7>")
	)
	(segment
		(start 199.461374 -304.709322)
		(end 200.58634 -304.709322)
		(width 0.16002)
		(layer "In11.Cu")
		(net "M_L_CPU1_SB_DQS_DN<7>")
	)
	(segment
		(start 201.1934 -304.582322)
		(end 201.3204 -304.709322)
		(width 0.16002)
		(layer "In11.Cu")
		(net "M_L_CPU1_SB_DQS_DN<7>")
	)
	(segment
		(start 174.418752 -304.479706)
		(end 175.241204 -304.479706)
		(width 0.16002)
		(layer "In11.Cu")
		(net "M_L_CPU1_SB_DQS_DN<7>")
	)
	(segment
		(start 190.707772 -304.858166)
		(end 193.03111 -304.858166)
		(width 0.16002)
		(layer "In11.Cu")
		(net "M_L_CPU1_SB_DQS_DN<7>")
	)
	(segment
		(start 155.28163 -298.020994)
		(end 155.28163 -298.497244)
		(width 0.16002)
		(layer "In11.Cu")
		(net "M_L_CPU1_SB_DQS_DN<7>")
	)
	(segment
		(start 153.19121 -296.790364)
		(end 154.075892 -297.675046)
		(width 0.16002)
		(layer "In11.Cu")
		(net "M_L_CPU1_SB_DQS_DN<7>")
	)
	(segment
		(start 159.402526 -302.14189)
		(end 159.402526 -302.61814)
		(width 0.16002)
		(layer "In11.Cu")
		(net "M_L_CPU1_SB_DQS_DN<7>")
	)
	(segment
		(start 147.695158 -287.466024)
		(end 147.77847 -287.466278)
		(width 0.09525)
		(layer "In11.Cu")
		(net "M_L_CPU1_SB_DQS_DN<7>")
	)
	(segment
		(start 186.337194 -305.708304)
		(end 187.656978 -305.708304)
		(width 0.16002)
		(layer "In11.Cu")
		(net "M_L_CPU1_SB_DQS_DN<7>")
	)
	(segment
		(start 185.487056 -304.858166)
		(end 186.337194 -305.708304)
		(width 0.16002)
		(layer "In11.Cu")
		(net "M_L_CPU1_SB_DQS_DN<7>")
	)
	(segment
		(start 182.785258 -304.479706)
		(end 183.163718 -304.858166)
		(width 0.16002)
		(layer "In11.Cu")
		(net "M_L_CPU1_SB_DQS_DN<7>")
	)
	(segment
		(start 144.21485 -286.566356)
		(end 144.223232 -286.56153)
		(width 0.09525)
		(layer "In11.Cu")
		(net "M_L_CPU1_SB_DQS_DN<7>")
	)
	(segment
		(start 161.733992 -305.333146)
		(end 166.021258 -305.333146)
		(width 0.16002)
		(layer "In11.Cu")
		(net "M_L_CPU1_SB_DQS_DN<7>")
	)
	(segment
		(start 187.656978 -305.708304)
		(end 188.032136 -305.333146)
		(width 0.16002)
		(layer "In11.Cu")
		(net "M_L_CPU1_SB_DQS_DN<7>")
	)
	(segment
		(start 140.454888 -286.566356)
		(end 140.46327 -286.56153)
		(width 0.09525)
		(layer "In11.Cu")
		(net "M_L_CPU1_SB_DQS_DN<7>")
	)
	(segment
		(start 172.944028 -305.333146)
		(end 173.565312 -305.333146)
		(width 0.16002)
		(layer "In11.Cu")
		(net "M_L_CPU1_SB_DQS_DN<7>")
	)
	(segment
		(start 188.65342 -305.333146)
		(end 189.50686 -304.479706)
		(width 0.16002)
		(layer "In11.Cu")
		(net "M_L_CPU1_SB_DQS_DN<7>")
	)
	(segment
		(start 155.20289 -298.575984)
		(end 155.20289 -298.802044)
		(width 0.16002)
		(layer "In11.Cu")
		(net "M_L_CPU1_SB_DQS_DN<7>")
	)
	(segment
		(start 195.201032 -305.708304)
		(end 195.57619 -305.333146)
		(width 0.16002)
		(layer "In11.Cu")
		(net "M_L_CPU1_SB_DQS_DN<7>")
	)
	(segment
		(start 178.79314 -305.708304)
		(end 180.112924 -305.708304)
		(width 0.16002)
		(layer "In11.Cu")
		(net "M_L_CPU1_SB_DQS_DN<7>")
	)
	(segment
		(start 200.58634 -304.709322)
		(end 200.71334 -304.582322)
		(width 0.16002)
		(layer "In11.Cu")
		(net "M_L_CPU1_SB_DQS_DN<7>")
	)
	(segment
		(start 197.050914 -304.479706)
		(end 197.873366 -304.479706)
		(width 0.16002)
		(layer "In11.Cu")
		(net "M_L_CPU1_SB_DQS_DN<7>")
	)
	(segment
		(start 141.394942 -286.566356)
		(end 141.403324 -286.56153)
		(width 0.09525)
		(layer "In11.Cu")
		(net "M_L_CPU1_SB_DQS_DN<7>")
	)
	(segment
		(start 197.873366 -304.479706)
		(end 198.251826 -304.858166)
		(width 0.16002)
		(layer "In11.Cu")
		(net "M_L_CPU1_SB_DQS_DN<7>")
	)
	(segment
		(start 156.230828 -298.970192)
		(end 156.655262 -299.394626)
		(width 0.16002)
		(layer "In11.Cu")
		(net "M_L_CPU1_SB_DQS_DN<7>")
	)
	(segment
		(start 146.1008 -286.444436)
		(end 146.65452 -286.998156)
		(width 0.09525)
		(layer "In11.Cu")
		(net "M_L_CPU1_SB_DQS_DN<7>")
	)
	(segment
		(start 156.576522 -299.949616)
		(end 156.576522 -300.175676)
		(width 0.16002)
		(layer "In11.Cu")
		(net "M_L_CPU1_SB_DQS_DN<7>")
	)
	(segment
		(start 158.196788 -301.795942)
		(end 158.422848 -301.795942)
		(width 0.16002)
		(layer "In11.Cu")
		(net "M_L_CPU1_SB_DQS_DN<7>")
	)
	(segment
		(start 159.323786 -302.69688)
		(end 159.323786 -302.92294)
		(width 0.16002)
		(layer "In11.Cu")
		(net "M_L_CPU1_SB_DQS_DN<7>")
	)
	(segment
		(start 175.241204 -304.479706)
		(end 175.619664 -304.858166)
		(width 0.16002)
		(layer "In11.Cu")
		(net "M_L_CPU1_SB_DQS_DN<7>")
	)
	(segment
		(start 155.28163 -298.497244)
		(end 155.20289 -298.575984)
		(width 0.16002)
		(layer "In11.Cu")
		(net "M_L_CPU1_SB_DQS_DN<7>")
	)
	(segment
		(start 147.22856 -286.998156)
		(end 147.695158 -287.466024)
		(width 0.09525)
		(layer "In11.Cu")
		(net "M_L_CPU1_SB_DQS_DN<7>")
	)
	(segment
		(start 147.795234 -287.483042)
		(end 153.19121 -292.87978)
		(width 0.16002)
		(layer "In11.Cu")
		(net "M_L_CPU1_SB_DQS_DN<7>")
	)
	(segment
		(start 141.966188 -286.56153)
		(end 141.97457 -286.566356)
		(width 0.09525)
		(layer "In11.Cu")
		(net "M_L_CPU1_SB_DQS_DN<7>")
	)
	(segment
		(start 155.754324 -298.970192)
		(end 156.230828 -298.970192)
		(width 0.16002)
		(layer "In11.Cu")
		(net "M_L_CPU1_SB_DQS_DN<7>")
	)
	(segment
		(start 167.69715 -304.479706)
		(end 168.07561 -304.858166)
		(width 0.16002)
		(layer "In11.Cu")
		(net "M_L_CPU1_SB_DQS_DN<7>")
	)
	(segment
		(start 155.20289 -298.802044)
		(end 155.449524 -299.048678)
		(width 0.16002)
		(layer "In11.Cu")
		(net "M_L_CPU1_SB_DQS_DN<7>")
	)
	(segment
		(start 166.021258 -305.333146)
		(end 166.874698 -304.479706)
		(width 0.16002)
		(layer "In11.Cu")
		(net "M_L_CPU1_SB_DQS_DN<7>")
	)
	(segment
		(start 175.619664 -304.858166)
		(end 177.943002 -304.858166)
		(width 0.16002)
		(layer "In11.Cu")
		(net "M_L_CPU1_SB_DQS_DN<7>")
	)
	(segment
		(start 154.380692 -297.59656)
		(end 154.857196 -297.59656)
		(width 0.16002)
		(layer "In11.Cu")
		(net "M_L_CPU1_SB_DQS_DN<7>")
	)
	(segment
		(start 173.565312 -305.333146)
		(end 174.418752 -304.479706)
		(width 0.16002)
		(layer "In11.Cu")
		(net "M_L_CPU1_SB_DQS_DN<7>")
	)
	(segment
		(start 153.19121 -292.87978)
		(end 153.19121 -296.790364)
		(width 0.16002)
		(layer "In11.Cu")
		(net "M_L_CPU1_SB_DQS_DN<7>")
	)
	(segment
		(start 166.874698 -304.479706)
		(end 167.69715 -304.479706)
		(width 0.16002)
		(layer "In11.Cu")
		(net "M_L_CPU1_SB_DQS_DN<7>")
	)
	(segment
		(start 177.943002 -304.858166)
		(end 178.79314 -305.708304)
		(width 0.16002)
		(layer "In11.Cu")
		(net "M_L_CPU1_SB_DQS_DN<7>")
	)
	(segment
		(start 159.323786 -302.92294)
		(end 161.733992 -305.333146)
		(width 0.16002)
		(layer "In11.Cu")
		(net "M_L_CPU1_SB_DQS_DN<7>")
	)
	(segment
		(start 155.449524 -299.048678)
		(end 155.675584 -299.048678)
		(width 0.16002)
		(layer "In11.Cu")
		(net "M_L_CPU1_SB_DQS_DN<7>")
	)
	(segment
		(start 168.07561 -304.858166)
		(end 170.517312 -304.858166)
		(width 0.16002)
		(layer "In11.Cu")
		(net "M_L_CPU1_SB_DQS_DN<7>")
	)
	(segment
		(start 146.65452 -286.998156)
		(end 147.22856 -286.998156)
		(width 0.09525)
		(layer "In11.Cu")
		(net "M_L_CPU1_SB_DQS_DN<7>")
	)
	(segment
		(start 181.109366 -305.333146)
		(end 181.962806 -304.479706)
		(width 0.16002)
		(layer "In11.Cu")
		(net "M_L_CPU1_SB_DQS_DN<7>")
	)
	(segment
		(start 200.71334 -304.582322)
		(end 201.1934 -304.582322)
		(width 0.16002)
		(layer "In11.Cu")
		(net "M_L_CPU1_SB_DQS_DN<7>")
	)
	(segment
		(start 181.962806 -304.479706)
		(end 182.785258 -304.479706)
		(width 0.16002)
		(layer "In11.Cu")
		(net "M_L_CPU1_SB_DQS_DN<7>")
	)
	(segment
		(start 195.57619 -305.333146)
		(end 196.197474 -305.333146)
		(width 0.16002)
		(layer "In11.Cu")
		(net "M_L_CPU1_SB_DQS_DN<7>")
	)
	(segment
		(start 196.197474 -305.333146)
		(end 197.050914 -304.479706)
		(width 0.16002)
		(layer "In11.Cu")
		(net "M_L_CPU1_SB_DQS_DN<7>")
	)
	(segment
		(start 157.60446 -300.343824)
		(end 158.028894 -300.768258)
		(width 0.16002)
		(layer "In11.Cu")
		(net "M_L_CPU1_SB_DQS_DN<7>")
	)
	(segment
		(start 156.576522 -300.175676)
		(end 156.823156 -300.42231)
		(width 0.16002)
		(layer "In11.Cu")
		(net "M_L_CPU1_SB_DQS_DN<7>")
	)
	(segment
		(start 158.978092 -301.717456)
		(end 159.402526 -302.14189)
		(width 0.16002)
		(layer "In11.Cu")
		(net "M_L_CPU1_SB_DQS_DN<7>")
	)
	(segment
		(start 144.66824 -286.444436)
		(end 146.1008 -286.444436)
		(width 0.09525)
		(layer "In11.Cu")
		(net "M_L_CPU1_SB_DQS_DN<7>")
	)
	(segment
		(start 201.3204 -304.709322)
		(end 201.873866 -304.709322)
		(width 0.16002)
		(layer "In11.Cu")
		(net "M_L_CPU1_SB_DQS_DN<7>")
	)
	(segment
		(start 157.950154 -301.323248)
		(end 157.950154 -301.549308)
		(width 0.16002)
		(layer "In11.Cu")
		(net "M_L_CPU1_SB_DQS_DN<7>")
	)
	(segment
		(start 180.488082 -305.333146)
		(end 181.109366 -305.333146)
		(width 0.16002)
		(layer "In11.Cu")
		(net "M_L_CPU1_SB_DQS_DN<7>")
	)
	(segment
		(start 156.823156 -300.42231)
		(end 157.049216 -300.42231)
		(width 0.16002)
		(layer "In11.Cu")
		(net "M_L_CPU1_SB_DQS_DN<7>")
	)
	(segment
		(start 193.881248 -305.708304)
		(end 195.201032 -305.708304)
		(width 0.16002)
		(layer "In11.Cu")
		(net "M_L_CPU1_SB_DQS_DN<7>")
	)
	(segment
		(start 138.24077 -286.50184)
		(end 138.264138 -286.588708)
		(width 0.09525)
		(layer "In11.Cu")
		(net "M_L_CPU1_SB_DQS_DN<7>")
	)
	(segment
		(start 158.501588 -301.717456)
		(end 158.978092 -301.717456)
		(width 0.16002)
		(layer "In11.Cu")
		(net "M_L_CPU1_SB_DQS_DN<7>")
	)
	(segment
		(start 172.56887 -305.708304)
		(end 172.944028 -305.333146)
		(width 0.16002)
		(layer "In11.Cu")
		(net "M_L_CPU1_SB_DQS_DN<7>")
	)
	(segment
		(start 170.517312 -304.858166)
		(end 171.36745 -305.708304)
		(width 0.16002)
		(layer "In11.Cu")
		(net "M_L_CPU1_SB_DQS_DN<7>")
	)
	(segment
		(start 154.301952 -297.675046)
		(end 154.380692 -297.59656)
		(width 0.16002)
		(layer "In11.Cu")
		(net "M_L_CPU1_SB_DQS_DN<7>")
	)
	(segment
		(start 156.655262 -299.870876)
		(end 156.576522 -299.949616)
		(width 0.16002)
		(layer "In11.Cu")
		(net "M_L_CPU1_SB_DQS_DN<7>")
	)
	(segment
		(start 158.028894 -301.244508)
		(end 157.950154 -301.323248)
		(width 0.16002)
		(layer "In11.Cu")
		(net "M_L_CPU1_SB_DQS_DN<7>")
	)
	(segment
		(start 157.950154 -301.549308)
		(end 158.196788 -301.795942)
		(width 0.16002)
		(layer "In11.Cu")
		(net "M_L_CPU1_SB_DQS_DN<7>")
	)
	(segment
		(start 154.857196 -297.59656)
		(end 155.28163 -298.020994)
		(width 0.16002)
		(layer "In11.Cu")
		(net "M_L_CPU1_SB_DQS_DN<7>")
	)
	(segment
		(start 154.075892 -297.675046)
		(end 154.301952 -297.675046)
		(width 0.16002)
		(layer "In11.Cu")
		(net "M_L_CPU1_SB_DQS_DN<7>")
	)
	(segment
		(start 199.31253 -304.858166)
		(end 199.461374 -304.709322)
		(width 0.16002)
		(layer "In11.Cu")
		(net "M_L_CPU1_SB_DQS_DN<7>")
	)
	(segment
		(start 159.402526 -302.61814)
		(end 159.323786 -302.69688)
		(width 0.16002)
		(layer "In11.Cu")
		(net "M_L_CPU1_SB_DQS_DN<7>")
	)
	(segment
		(start 193.03111 -304.858166)
		(end 193.881248 -305.708304)
		(width 0.16002)
		(layer "In11.Cu")
		(net "M_L_CPU1_SB_DQS_DN<7>")
	)
	(segment
		(start 155.675584 -299.048678)
		(end 155.754324 -298.970192)
		(width 0.16002)
		(layer "In11.Cu")
		(net "M_L_CPU1_SB_DQS_DN<7>")
	)
	(segment
		(start 189.50686 -304.479706)
		(end 190.329312 -304.479706)
		(width 0.16002)
		(layer "In11.Cu")
		(net "M_L_CPU1_SB_DQS_DN<7>")
	)
	(segment
		(start 198.251826 -304.858166)
		(end 199.31253 -304.858166)
		(width 0.16002)
		(layer "In11.Cu")
		(net "M_L_CPU1_SB_DQS_DN<7>")
	)
	(segment
		(start 158.422848 -301.795942)
		(end 158.501588 -301.717456)
		(width 0.16002)
		(layer "In11.Cu")
		(net "M_L_CPU1_SB_DQS_DN<7>")
	)
	(segment
		(start 147.77847 -287.466278)
		(end 147.795234 -287.483042)
		(width 0.09525)
		(layer "In11.Cu")
		(net "M_L_CPU1_SB_DQS_DN<7>")
	)
	(segment
		(start 180.112924 -305.708304)
		(end 180.488082 -305.333146)
		(width 0.16002)
		(layer "In11.Cu")
		(net "M_L_CPU1_SB_DQS_DN<7>")
	)
	(segment
		(start 188.032136 -305.333146)
		(end 188.65342 -305.333146)
		(width 0.16002)
		(layer "In11.Cu")
		(net "M_L_CPU1_SB_DQS_DN<7>")
	)
	(segment
		(start 157.127956 -300.343824)
		(end 157.60446 -300.343824)
		(width 0.16002)
		(layer "In11.Cu")
		(net "M_L_CPU1_SB_DQS_DN<7>")
	)
	(arc
		(start 143.846042 -286.56153)
		(mid 144.029817 -286.612302)
		(end 144.21485 -286.566356)
		(width 0.09525)
		(layer "In11.Cu")
		(net "M_L_CPU1_SB_DQS_DN<7>")
	)
	(arc
		(start 140.08608 -286.56153)
		(mid 140.269855 -286.612302)
		(end 140.454888 -286.566356)
		(width 0.09525)
		(layer "In11.Cu")
		(net "M_L_CPU1_SB_DQS_DN<7>")
	)
	(arc
		(start 141.97457 -286.566356)
		(mid 142.159602 -286.61227)
		(end 142.343378 -286.56153)
		(width 0.09525)
		(layer "In11.Cu")
		(net "M_L_CPU1_SB_DQS_DN<7>")
	)
	(arc
		(start 142.906242 -286.56153)
		(mid 143.09471 -286.612207)
		(end 143.283178 -286.56153)
		(width 0.09525)
		(layer "In11.Cu")
		(net "M_L_CPU1_SB_DQS_DN<7>")
	)
	(arc
		(start 139.14628 -286.56153)
		(mid 139.334748 -286.612207)
		(end 139.523216 -286.56153)
		(width 0.09525)
		(layer "In11.Cu")
		(net "M_L_CPU1_SB_DQS_DN<7>")
	)
	(arc
		(start 140.46327 -286.56153)
		(mid 140.744702 -286.485741)
		(end 141.026134 -286.56153)
		(width 0.09525)
		(layer "In11.Cu")
		(net "M_L_CPU1_SB_DQS_DN<7>")
	)
	(arc
		(start 138.583416 -286.56153)
		(mid 138.864848 -286.485741)
		(end 139.14628 -286.56153)
		(width 0.09525)
		(layer "In11.Cu")
		(net "M_L_CPU1_SB_DQS_DN<7>")
	)
	(arc
		(start 138.264138 -286.588708)
		(mid 138.42682 -286.61084)
		(end 138.583416 -286.56153)
		(width 0.09525)
		(layer "In11.Cu")
		(net "M_L_CPU1_SB_DQS_DN<7>")
	)
	(arc
		(start 141.026134 -286.56153)
		(mid 141.209909 -286.612302)
		(end 141.394942 -286.566356)
		(width 0.09525)
		(layer "In11.Cu")
		(net "M_L_CPU1_SB_DQS_DN<7>")
	)
	(arc
		(start 144.23644 -286.554418)
		(mid 144.445432 -286.472306)
		(end 144.66824 -286.444436)
		(width 0.09525)
		(layer "In11.Cu")
		(net "M_L_CPU1_SB_DQS_DN<7>")
	)
	(arc
		(start 142.343378 -286.56153)
		(mid 142.62481 -286.485741)
		(end 142.906242 -286.56153)
		(width 0.09525)
		(layer "In11.Cu")
		(net "M_L_CPU1_SB_DQS_DN<7>")
	)
	(arc
		(start 143.283178 -286.56153)
		(mid 143.56461 -286.485741)
		(end 143.846042 -286.56153)
		(width 0.09525)
		(layer "In11.Cu")
		(net "M_L_CPU1_SB_DQS_DN<7>")
	)
	(arc
		(start 144.223232 -286.56153)
		(mid 144.229812 -286.557929)
		(end 144.23644 -286.554418)
		(width 0.09525)
		(layer "In11.Cu")
		(net "M_L_CPU1_SB_DQS_DN<7>")
	)
	(arc
		(start 141.403324 -286.56153)
		(mid 141.684756 -286.485741)
		(end 141.966188 -286.56153)
		(width 0.09525)
		(layer "In11.Cu")
		(net "M_L_CPU1_SB_DQS_DN<7>")
	)
	(arc
		(start 139.523216 -286.56153)
		(mid 139.804648 -286.485741)
		(end 140.08608 -286.56153)
		(width 0.09525)
		(layer "In11.Cu")
		(net "M_L_CPU1_SB_DQS_DN<7>")
	)
	(segment
		(start 137.927842 -281.110436)
		(end 138.394694 -281.376374)
		(width 0.12954)
		(layer "F.Cu")
		(net "M_L_CPU1_SB_DQS_DN<6>")
	)
	(segment
		(start 199.31253 -295.508172)
		(end 199.461374 -295.359328)
		(width 0.16002)
		(layer "In11.Cu")
		(net "M_L_CPU1_SB_DQS_DN<6>")
	)
	(segment
		(start 185.487056 -295.508172)
		(end 186.337194 -296.35831)
		(width 0.16002)
		(layer "In11.Cu")
		(net "M_L_CPU1_SB_DQS_DN<6>")
	)
	(segment
		(start 158.80969 -290.552124)
		(end 158.80969 -292.015164)
		(width 0.16002)
		(layer "In11.Cu")
		(net "M_L_CPU1_SB_DQS_DN<6>")
	)
	(segment
		(start 197.873366 -295.129712)
		(end 198.251826 -295.508172)
		(width 0.16002)
		(layer "In11.Cu")
		(net "M_L_CPU1_SB_DQS_DN<6>")
	)
	(segment
		(start 146.100546 -281.625802)
		(end 146.35226 -281.877516)
		(width 0.09525)
		(layer "In11.Cu")
		(net "M_L_CPU1_SB_DQS_DN<6>")
	)
	(segment
		(start 161.111692 -292.913816)
		(end 161.111692 -293.39032)
		(width 0.16002)
		(layer "In11.Cu")
		(net "M_L_CPU1_SB_DQS_DN<6>")
	)
	(segment
		(start 144.504664 -281.625802)
		(end 146.100546 -281.625802)
		(width 0.09525)
		(layer "In11.Cu")
		(net "M_L_CPU1_SB_DQS_DN<6>")
	)
	(segment
		(start 159.860234 -292.839648)
		(end 160.210754 -292.489382)
		(width 0.16002)
		(layer "In11.Cu")
		(net "M_L_CPU1_SB_DQS_DN<6>")
	)
	(segment
		(start 162.134804 -295.340278)
		(end 162.777678 -295.983152)
		(width 0.16002)
		(layer "In11.Cu")
		(net "M_L_CPU1_SB_DQS_DN<6>")
	)
	(segment
		(start 162.777678 -295.983152)
		(end 166.021258 -295.983152)
		(width 0.16002)
		(layer "In11.Cu")
		(net "M_L_CPU1_SB_DQS_DN<6>")
	)
	(segment
		(start 187.656978 -296.35831)
		(end 188.032136 -295.983152)
		(width 0.16002)
		(layer "In11.Cu")
		(net "M_L_CPU1_SB_DQS_DN<6>")
	)
	(segment
		(start 160.210754 -292.489382)
		(end 160.687258 -292.489382)
		(width 0.16002)
		(layer "In11.Cu")
		(net "M_L_CPU1_SB_DQS_DN<6>")
	)
	(segment
		(start 201.17562 -295.359328)
		(end 201.873866 -295.359328)
		(width 0.16002)
		(layer "In11.Cu")
		(net "M_L_CPU1_SB_DQS_DN<6>")
	)
	(segment
		(start 161.007806 -294.21328)
		(end 161.233866 -294.21328)
		(width 0.16002)
		(layer "In11.Cu")
		(net "M_L_CPU1_SB_DQS_DN<6>")
	)
	(segment
		(start 175.619664 -295.508172)
		(end 177.943002 -295.508172)
		(width 0.16002)
		(layer "In11.Cu")
		(net "M_L_CPU1_SB_DQS_DN<6>")
	)
	(segment
		(start 146.35226 -281.877516)
		(end 147.836382 -281.877516)
		(width 0.09525)
		(layer "In11.Cu")
		(net "M_L_CPU1_SB_DQS_DN<6>")
	)
	(segment
		(start 180.488082 -295.983152)
		(end 181.109366 -295.983152)
		(width 0.16002)
		(layer "In11.Cu")
		(net "M_L_CPU1_SB_DQS_DN<6>")
	)
	(segment
		(start 166.021258 -295.983152)
		(end 166.874698 -295.129712)
		(width 0.16002)
		(layer "In11.Cu")
		(net "M_L_CPU1_SB_DQS_DN<6>")
	)
	(segment
		(start 199.461374 -295.359328)
		(end 200.44156 -295.359328)
		(width 0.16002)
		(layer "In11.Cu")
		(net "M_L_CPU1_SB_DQS_DN<6>")
	)
	(segment
		(start 140.454888 -281.70632)
		(end 140.46327 -281.701494)
		(width 0.09525)
		(layer "In11.Cu")
		(net "M_L_CPU1_SB_DQS_DN<6>")
	)
	(segment
		(start 138.24077 -281.641804)
		(end 138.264138 -281.728672)
		(width 0.09525)
		(layer "In11.Cu")
		(net "M_L_CPU1_SB_DQS_DN<6>")
	)
	(segment
		(start 198.251826 -295.508172)
		(end 199.31253 -295.508172)
		(width 0.16002)
		(layer "In11.Cu")
		(net "M_L_CPU1_SB_DQS_DN<6>")
	)
	(segment
		(start 161.233866 -294.21328)
		(end 161.584386 -293.863014)
		(width 0.16002)
		(layer "In11.Cu")
		(net "M_L_CPU1_SB_DQS_DN<6>")
	)
	(segment
		(start 162.06089 -293.863014)
		(end 162.485324 -294.287448)
		(width 0.16002)
		(layer "In11.Cu")
		(net "M_L_CPU1_SB_DQS_DN<6>")
	)
	(segment
		(start 188.65342 -295.983152)
		(end 189.50686 -295.129712)
		(width 0.16002)
		(layer "In11.Cu")
		(net "M_L_CPU1_SB_DQS_DN<6>")
	)
	(segment
		(start 160.687258 -292.489382)
		(end 161.111692 -292.913816)
		(width 0.16002)
		(layer "In11.Cu")
		(net "M_L_CPU1_SB_DQS_DN<6>")
	)
	(segment
		(start 138.394694 -281.376374)
		(end 138.24077 -281.641804)
		(width 0.09525)
		(layer "In11.Cu")
		(net "M_L_CPU1_SB_DQS_DN<6>")
	)
	(segment
		(start 160.761172 -293.966646)
		(end 161.007806 -294.21328)
		(width 0.16002)
		(layer "In11.Cu")
		(net "M_L_CPU1_SB_DQS_DN<6>")
	)
	(segment
		(start 174.418752 -295.129712)
		(end 175.241204 -295.129712)
		(width 0.16002)
		(layer "In11.Cu")
		(net "M_L_CPU1_SB_DQS_DN<6>")
	)
	(segment
		(start 172.56887 -296.35831)
		(end 172.944028 -295.983152)
		(width 0.16002)
		(layer "In11.Cu")
		(net "M_L_CPU1_SB_DQS_DN<6>")
	)
	(segment
		(start 177.943002 -295.508172)
		(end 178.79314 -296.35831)
		(width 0.16002)
		(layer "In11.Cu")
		(net "M_L_CPU1_SB_DQS_DN<6>")
	)
	(segment
		(start 166.874698 -295.129712)
		(end 167.69715 -295.129712)
		(width 0.16002)
		(layer "In11.Cu")
		(net "M_L_CPU1_SB_DQS_DN<6>")
	)
	(segment
		(start 182.785258 -295.129712)
		(end 183.163718 -295.508172)
		(width 0.16002)
		(layer "In11.Cu")
		(net "M_L_CPU1_SB_DQS_DN<6>")
	)
	(segment
		(start 162.485324 -294.287448)
		(end 162.485324 -294.763952)
		(width 0.16002)
		(layer "In11.Cu")
		(net "M_L_CPU1_SB_DQS_DN<6>")
	)
	(segment
		(start 200.56856 -295.232328)
		(end 201.04862 -295.232328)
		(width 0.16002)
		(layer "In11.Cu")
		(net "M_L_CPU1_SB_DQS_DN<6>")
	)
	(segment
		(start 195.201032 -296.35831)
		(end 195.57619 -295.983152)
		(width 0.16002)
		(layer "In11.Cu")
		(net "M_L_CPU1_SB_DQS_DN<6>")
	)
	(segment
		(start 141.394942 -281.70632)
		(end 141.403324 -281.701494)
		(width 0.09525)
		(layer "In11.Cu")
		(net "M_L_CPU1_SB_DQS_DN<6>")
	)
	(segment
		(start 160.761172 -293.740586)
		(end 160.761172 -293.966646)
		(width 0.16002)
		(layer "In11.Cu")
		(net "M_L_CPU1_SB_DQS_DN<6>")
	)
	(segment
		(start 170.972226 -295.818306)
		(end 171.51223 -296.35831)
		(width 0.16002)
		(layer "In11.Cu")
		(net "M_L_CPU1_SB_DQS_DN<6>")
	)
	(segment
		(start 147.895564 -281.818334)
		(end 147.919186 -281.818334)
		(width 0.09525)
		(layer "In11.Cu")
		(net "M_L_CPU1_SB_DQS_DN<6>")
	)
	(segment
		(start 196.197474 -295.983152)
		(end 197.050914 -295.129712)
		(width 0.16002)
		(layer "In11.Cu")
		(net "M_L_CPU1_SB_DQS_DN<6>")
	)
	(segment
		(start 181.109366 -295.983152)
		(end 181.962806 -295.129712)
		(width 0.16002)
		(layer "In11.Cu")
		(net "M_L_CPU1_SB_DQS_DN<6>")
	)
	(segment
		(start 158.80969 -292.015164)
		(end 159.634174 -292.839648)
		(width 0.16002)
		(layer "In11.Cu")
		(net "M_L_CPU1_SB_DQS_DN<6>")
	)
	(segment
		(start 183.163718 -295.508172)
		(end 185.487056 -295.508172)
		(width 0.16002)
		(layer "In11.Cu")
		(net "M_L_CPU1_SB_DQS_DN<6>")
	)
	(segment
		(start 162.485324 -294.763952)
		(end 162.134804 -295.114218)
		(width 0.16002)
		(layer "In11.Cu")
		(net "M_L_CPU1_SB_DQS_DN<6>")
	)
	(segment
		(start 193.881248 -296.35831)
		(end 195.201032 -296.35831)
		(width 0.16002)
		(layer "In11.Cu")
		(net "M_L_CPU1_SB_DQS_DN<6>")
	)
	(segment
		(start 141.966188 -281.701494)
		(end 141.97457 -281.70632)
		(width 0.09525)
		(layer "In11.Cu")
		(net "M_L_CPU1_SB_DQS_DN<6>")
	)
	(segment
		(start 150.0759 -281.818334)
		(end 158.80969 -290.552124)
		(width 0.16002)
		(layer "In11.Cu")
		(net "M_L_CPU1_SB_DQS_DN<6>")
	)
	(segment
		(start 171.51223 -296.35831)
		(end 172.56887 -296.35831)
		(width 0.16002)
		(layer "In11.Cu")
		(net "M_L_CPU1_SB_DQS_DN<6>")
	)
	(segment
		(start 189.50686 -295.129712)
		(end 190.329312 -295.129712)
		(width 0.16002)
		(layer "In11.Cu")
		(net "M_L_CPU1_SB_DQS_DN<6>")
	)
	(segment
		(start 200.44156 -295.359328)
		(end 200.56856 -295.232328)
		(width 0.16002)
		(layer "In11.Cu")
		(net "M_L_CPU1_SB_DQS_DN<6>")
	)
	(segment
		(start 188.032136 -295.983152)
		(end 188.65342 -295.983152)
		(width 0.16002)
		(layer "In11.Cu")
		(net "M_L_CPU1_SB_DQS_DN<6>")
	)
	(segment
		(start 144.21485 -281.70632)
		(end 144.223232 -281.701494)
		(width 0.09525)
		(layer "In11.Cu")
		(net "M_L_CPU1_SB_DQS_DN<6>")
	)
	(segment
		(start 172.944028 -295.983152)
		(end 173.565312 -295.983152)
		(width 0.16002)
		(layer "In11.Cu")
		(net "M_L_CPU1_SB_DQS_DN<6>")
	)
	(segment
		(start 201.04862 -295.232328)
		(end 201.17562 -295.359328)
		(width 0.16002)
		(layer "In11.Cu")
		(net "M_L_CPU1_SB_DQS_DN<6>")
	)
	(segment
		(start 173.565312 -295.983152)
		(end 174.418752 -295.129712)
		(width 0.16002)
		(layer "In11.Cu")
		(net "M_L_CPU1_SB_DQS_DN<6>")
	)
	(segment
		(start 197.050914 -295.129712)
		(end 197.873366 -295.129712)
		(width 0.16002)
		(layer "In11.Cu")
		(net "M_L_CPU1_SB_DQS_DN<6>")
	)
	(segment
		(start 147.836382 -281.877516)
		(end 147.895564 -281.818334)
		(width 0.09525)
		(layer "In11.Cu")
		(net "M_L_CPU1_SB_DQS_DN<6>")
	)
	(segment
		(start 181.962806 -295.129712)
		(end 182.785258 -295.129712)
		(width 0.16002)
		(layer "In11.Cu")
		(net "M_L_CPU1_SB_DQS_DN<6>")
	)
	(segment
		(start 190.707772 -295.508172)
		(end 193.03111 -295.508172)
		(width 0.16002)
		(layer "In11.Cu")
		(net "M_L_CPU1_SB_DQS_DN<6>")
	)
	(segment
		(start 175.241204 -295.129712)
		(end 175.619664 -295.508172)
		(width 0.16002)
		(layer "In11.Cu")
		(net "M_L_CPU1_SB_DQS_DN<6>")
	)
	(segment
		(start 201.873866 -295.359328)
		(end 202.147932 -295.085262)
		(width 0.16002)
		(layer "In11.Cu")
		(net "M_L_CPU1_SB_DQS_DN<6>")
	)
	(segment
		(start 162.134804 -295.114218)
		(end 162.134804 -295.340278)
		(width 0.16002)
		(layer "In11.Cu")
		(net "M_L_CPU1_SB_DQS_DN<6>")
	)
	(segment
		(start 186.337194 -296.35831)
		(end 187.656978 -296.35831)
		(width 0.16002)
		(layer "In11.Cu")
		(net "M_L_CPU1_SB_DQS_DN<6>")
	)
	(segment
		(start 180.112924 -296.35831)
		(end 180.488082 -295.983152)
		(width 0.16002)
		(layer "In11.Cu")
		(net "M_L_CPU1_SB_DQS_DN<6>")
	)
	(segment
		(start 167.69715 -295.129712)
		(end 168.385744 -295.818306)
		(width 0.16002)
		(layer "In11.Cu")
		(net "M_L_CPU1_SB_DQS_DN<6>")
	)
	(segment
		(start 178.79314 -296.35831)
		(end 180.112924 -296.35831)
		(width 0.16002)
		(layer "In11.Cu")
		(net "M_L_CPU1_SB_DQS_DN<6>")
	)
	(segment
		(start 161.584386 -293.863014)
		(end 162.06089 -293.863014)
		(width 0.16002)
		(layer "In11.Cu")
		(net "M_L_CPU1_SB_DQS_DN<6>")
	)
	(segment
		(start 161.111692 -293.39032)
		(end 160.761172 -293.740586)
		(width 0.16002)
		(layer "In11.Cu")
		(net "M_L_CPU1_SB_DQS_DN<6>")
	)
	(segment
		(start 190.329312 -295.129712)
		(end 190.707772 -295.508172)
		(width 0.16002)
		(layer "In11.Cu")
		(net "M_L_CPU1_SB_DQS_DN<6>")
	)
	(segment
		(start 147.919186 -281.818334)
		(end 150.0759 -281.818334)
		(width 0.16002)
		(layer "In11.Cu")
		(net "M_L_CPU1_SB_DQS_DN<6>")
	)
	(segment
		(start 159.634174 -292.839648)
		(end 159.860234 -292.839648)
		(width 0.16002)
		(layer "In11.Cu")
		(net "M_L_CPU1_SB_DQS_DN<6>")
	)
	(segment
		(start 168.385744 -295.818306)
		(end 170.972226 -295.818306)
		(width 0.16002)
		(layer "In11.Cu")
		(net "M_L_CPU1_SB_DQS_DN<6>")
	)
	(segment
		(start 193.03111 -295.508172)
		(end 193.881248 -296.35831)
		(width 0.16002)
		(layer "In11.Cu")
		(net "M_L_CPU1_SB_DQS_DN<6>")
	)
	(segment
		(start 195.57619 -295.983152)
		(end 196.197474 -295.983152)
		(width 0.16002)
		(layer "In11.Cu")
		(net "M_L_CPU1_SB_DQS_DN<6>")
	)
	(arc
		(start 141.97457 -281.70632)
		(mid 142.159602 -281.752234)
		(end 142.343378 -281.701494)
		(width 0.09525)
		(layer "In11.Cu")
		(net "M_L_CPU1_SB_DQS_DN<6>")
	)
	(arc
		(start 141.403324 -281.701494)
		(mid 141.684756 -281.625739)
		(end 141.966188 -281.701494)
		(width 0.09525)
		(layer "In11.Cu")
		(net "M_L_CPU1_SB_DQS_DN<6>")
	)
	(arc
		(start 143.283178 -281.701494)
		(mid 143.56461 -281.625739)
		(end 143.846042 -281.701494)
		(width 0.09525)
		(layer "In11.Cu")
		(net "M_L_CPU1_SB_DQS_DN<6>")
	)
	(arc
		(start 138.264138 -281.728672)
		(mid 138.42682 -281.750804)
		(end 138.583416 -281.701494)
		(width 0.09525)
		(layer "In11.Cu")
		(net "M_L_CPU1_SB_DQS_DN<6>")
	)
	(arc
		(start 140.08608 -281.701494)
		(mid 140.269855 -281.752266)
		(end 140.454888 -281.70632)
		(width 0.09525)
		(layer "In11.Cu")
		(net "M_L_CPU1_SB_DQS_DN<6>")
	)
	(arc
		(start 142.343378 -281.701494)
		(mid 142.62481 -281.625739)
		(end 142.906242 -281.701494)
		(width 0.09525)
		(layer "In11.Cu")
		(net "M_L_CPU1_SB_DQS_DN<6>")
	)
	(arc
		(start 139.523216 -281.701494)
		(mid 139.804648 -281.625739)
		(end 140.08608 -281.701494)
		(width 0.09525)
		(layer "In11.Cu")
		(net "M_L_CPU1_SB_DQS_DN<6>")
	)
	(arc
		(start 138.583416 -281.701494)
		(mid 138.864848 -281.625739)
		(end 139.14628 -281.701494)
		(width 0.09525)
		(layer "In11.Cu")
		(net "M_L_CPU1_SB_DQS_DN<6>")
	)
	(arc
		(start 144.223232 -281.701494)
		(mid 144.358948 -281.645059)
		(end 144.504664 -281.625802)
		(width 0.09525)
		(layer "In11.Cu")
		(net "M_L_CPU1_SB_DQS_DN<6>")
	)
	(arc
		(start 140.46327 -281.701494)
		(mid 140.744702 -281.625739)
		(end 141.026134 -281.701494)
		(width 0.09525)
		(layer "In11.Cu")
		(net "M_L_CPU1_SB_DQS_DN<6>")
	)
	(arc
		(start 139.14628 -281.701494)
		(mid 139.334748 -281.752171)
		(end 139.523216 -281.701494)
		(width 0.09525)
		(layer "In11.Cu")
		(net "M_L_CPU1_SB_DQS_DN<6>")
	)
	(arc
		(start 143.846042 -281.701494)
		(mid 144.029817 -281.752266)
		(end 144.21485 -281.70632)
		(width 0.09525)
		(layer "In11.Cu")
		(net "M_L_CPU1_SB_DQS_DN<6>")
	)
	(arc
		(start 141.026134 -281.701494)
		(mid 141.209909 -281.752266)
		(end 141.394942 -281.70632)
		(width 0.09525)
		(layer "In11.Cu")
		(net "M_L_CPU1_SB_DQS_DN<6>")
	)
	(arc
		(start 142.906242 -281.701494)
		(mid 143.09471 -281.752171)
		(end 143.283178 -281.701494)
		(width 0.09525)
		(layer "In11.Cu")
		(net "M_L_CPU1_SB_DQS_DN<6>")
	)
	(segment
		(start 137.927842 -276.2504)
		(end 138.394694 -276.516338)
		(width 0.12954)
		(layer "F.Cu")
		(net "M_L_CPU1_SB_DQS_DN<5>")
	)
	(segment
		(start 181.109366 -286.633158)
		(end 181.962806 -285.779718)
		(width 0.16002)
		(layer "In11.Cu")
		(net "M_L_CPU1_SB_DQS_DN<5>")
	)
	(segment
		(start 174.418752 -285.779718)
		(end 175.241204 -285.779718)
		(width 0.16002)
		(layer "In11.Cu")
		(net "M_L_CPU1_SB_DQS_DN<5>")
	)
	(segment
		(start 193.881248 -287.008316)
		(end 195.201032 -287.008316)
		(width 0.16002)
		(layer "In11.Cu")
		(net "M_L_CPU1_SB_DQS_DN<5>")
	)
	(segment
		(start 169.875962 -286.158178)
		(end 170.633644 -286.158178)
		(width 0.16002)
		(layer "In11.Cu")
		(net "M_L_CPU1_SB_DQS_DN<5>")
	)
	(segment
		(start 172.56887 -287.008316)
		(end 172.944028 -286.633158)
		(width 0.16002)
		(layer "In11.Cu")
		(net "M_L_CPU1_SB_DQS_DN<5>")
	)
	(segment
		(start 164.04209 -285.698946)
		(end 164.640768 -285.698946)
		(width 0.16002)
		(layer "In11.Cu")
		(net "M_L_CPU1_SB_DQS_DN<5>")
	)
	(segment
		(start 188.032136 -286.633158)
		(end 188.65342 -286.633158)
		(width 0.16002)
		(layer "In11.Cu")
		(net "M_L_CPU1_SB_DQS_DN<5>")
	)
	(segment
		(start 195.57619 -286.633158)
		(end 196.197474 -286.633158)
		(width 0.16002)
		(layer "In11.Cu")
		(net "M_L_CPU1_SB_DQS_DN<5>")
	)
	(segment
		(start 200.3679 -286.009334)
		(end 200.4949 -285.882334)
		(width 0.16002)
		(layer "In11.Cu")
		(net "M_L_CPU1_SB_DQS_DN<5>")
	)
	(segment
		(start 163.705032 -286.036004)
		(end 164.04209 -285.698946)
		(width 0.16002)
		(layer "In11.Cu")
		(net "M_L_CPU1_SB_DQS_DN<5>")
	)
	(segment
		(start 141.966188 -276.841458)
		(end 141.97457 -276.846284)
		(width 0.09525)
		(layer "In11.Cu")
		(net "M_L_CPU1_SB_DQS_DN<5>")
	)
	(segment
		(start 181.962806 -285.779718)
		(end 182.785258 -285.779718)
		(width 0.16002)
		(layer "In11.Cu")
		(net "M_L_CPU1_SB_DQS_DN<5>")
	)
	(segment
		(start 175.619664 -286.158178)
		(end 177.943002 -286.158178)
		(width 0.16002)
		(layer "In11.Cu")
		(net "M_L_CPU1_SB_DQS_DN<5>")
	)
	(segment
		(start 167.58539 -285.520384)
		(end 167.922448 -285.183326)
		(width 0.16002)
		(layer "In11.Cu")
		(net "M_L_CPU1_SB_DQS_DN<5>")
	)
	(segment
		(start 164.977826 -286.473138)
		(end 165.137846 -286.633158)
		(width 0.16002)
		(layer "In11.Cu")
		(net "M_L_CPU1_SB_DQS_DN<5>")
	)
	(segment
		(start 190.329312 -285.779718)
		(end 190.707772 -286.158178)
		(width 0.16002)
		(layer "In11.Cu")
		(net "M_L_CPU1_SB_DQS_DN<5>")
	)
	(segment
		(start 183.163718 -286.158178)
		(end 185.487056 -286.158178)
		(width 0.16002)
		(layer "In11.Cu")
		(net "M_L_CPU1_SB_DQS_DN<5>")
	)
	(segment
		(start 147.49653 -275.875242)
		(end 147.836382 -275.875242)
		(width 0.09525)
		(layer "In11.Cu")
		(net "M_L_CPU1_SB_DQS_DN<5>")
	)
	(segment
		(start 163.705032 -286.473138)
		(end 163.705032 -286.036004)
		(width 0.16002)
		(layer "In11.Cu")
		(net "M_L_CPU1_SB_DQS_DN<5>")
	)
	(segment
		(start 188.65342 -286.633158)
		(end 189.50686 -285.779718)
		(width 0.16002)
		(layer "In11.Cu")
		(net "M_L_CPU1_SB_DQS_DN<5>")
	)
	(segment
		(start 145.151602 -276.848316)
		(end 145.16354 -276.841458)
		(width 0.09525)
		(layer "In11.Cu")
		(net "M_L_CPU1_SB_DQS_DN<5>")
	)
	(segment
		(start 168.858184 -285.520384)
		(end 168.858184 -285.673546)
		(width 0.16002)
		(layer "In11.Cu")
		(net "M_L_CPU1_SB_DQS_DN<5>")
	)
	(segment
		(start 196.197474 -286.633158)
		(end 197.050914 -285.779718)
		(width 0.16002)
		(layer "In11.Cu")
		(net "M_L_CPU1_SB_DQS_DN<5>")
	)
	(segment
		(start 169.55135 -285.833566)
		(end 169.875962 -286.158178)
		(width 0.16002)
		(layer "In11.Cu")
		(net "M_L_CPU1_SB_DQS_DN<5>")
	)
	(segment
		(start 167.922448 -285.183326)
		(end 168.521126 -285.183326)
		(width 0.16002)
		(layer "In11.Cu")
		(net "M_L_CPU1_SB_DQS_DN<5>")
	)
	(segment
		(start 193.03111 -286.158178)
		(end 193.881248 -287.008316)
		(width 0.16002)
		(layer "In11.Cu")
		(net "M_L_CPU1_SB_DQS_DN<5>")
	)
	(segment
		(start 138.24077 -276.781768)
		(end 138.264138 -276.868636)
		(width 0.09525)
		(layer "In11.Cu")
		(net "M_L_CPU1_SB_DQS_DN<5>")
	)
	(segment
		(start 146.931634 -275.598382)
		(end 147.21967 -275.598382)
		(width 0.09525)
		(layer "In11.Cu")
		(net "M_L_CPU1_SB_DQS_DN<5>")
	)
	(segment
		(start 141.394942 -276.846284)
		(end 141.403324 -276.841458)
		(width 0.09525)
		(layer "In11.Cu")
		(net "M_L_CPU1_SB_DQS_DN<5>")
	)
	(segment
		(start 200.97496 -285.882334)
		(end 201.10196 -286.009334)
		(width 0.16002)
		(layer "In11.Cu")
		(net "M_L_CPU1_SB_DQS_DN<5>")
	)
	(segment
		(start 199.31253 -286.158178)
		(end 199.461374 -286.009334)
		(width 0.16002)
		(layer "In11.Cu")
		(net "M_L_CPU1_SB_DQS_DN<5>")
	)
	(segment
		(start 169.018204 -285.833566)
		(end 169.55135 -285.833566)
		(width 0.16002)
		(layer "In11.Cu")
		(net "M_L_CPU1_SB_DQS_DN<5>")
	)
	(segment
		(start 173.565312 -286.633158)
		(end 174.418752 -285.779718)
		(width 0.16002)
		(layer "In11.Cu")
		(net "M_L_CPU1_SB_DQS_DN<5>")
	)
	(segment
		(start 197.050914 -285.779718)
		(end 197.873366 -285.779718)
		(width 0.16002)
		(layer "In11.Cu")
		(net "M_L_CPU1_SB_DQS_DN<5>")
	)
	(segment
		(start 147.895564 -275.81606)
		(end 147.919186 -275.81606)
		(width 0.09525)
		(layer "In11.Cu")
		(net "M_L_CPU1_SB_DQS_DN<5>")
	)
	(segment
		(start 144.77619 -276.835362)
		(end 144.786604 -276.841458)
		(width 0.09525)
		(layer "In11.Cu")
		(net "M_L_CPU1_SB_DQS_DN<5>")
	)
	(segment
		(start 200.4949 -285.882334)
		(end 200.97496 -285.882334)
		(width 0.16002)
		(layer "In11.Cu")
		(net "M_L_CPU1_SB_DQS_DN<5>")
	)
	(segment
		(start 167.58539 -285.673546)
		(end 167.58539 -285.520384)
		(width 0.16002)
		(layer "In11.Cu")
		(net "M_L_CPU1_SB_DQS_DN<5>")
	)
	(segment
		(start 140.454888 -276.846284)
		(end 140.46327 -276.841458)
		(width 0.09525)
		(layer "In11.Cu")
		(net "M_L_CPU1_SB_DQS_DN<5>")
	)
	(segment
		(start 180.488082 -286.633158)
		(end 181.109366 -286.633158)
		(width 0.16002)
		(layer "In11.Cu")
		(net "M_L_CPU1_SB_DQS_DN<5>")
	)
	(segment
		(start 180.112924 -287.008316)
		(end 180.488082 -286.633158)
		(width 0.16002)
		(layer "In11.Cu")
		(net "M_L_CPU1_SB_DQS_DN<5>")
	)
	(segment
		(start 138.394694 -276.516338)
		(end 138.24077 -276.781768)
		(width 0.09525)
		(layer "In11.Cu")
		(net "M_L_CPU1_SB_DQS_DN<5>")
	)
	(segment
		(start 182.785258 -285.779718)
		(end 183.163718 -286.158178)
		(width 0.16002)
		(layer "In11.Cu")
		(net "M_L_CPU1_SB_DQS_DN<5>")
	)
	(segment
		(start 171.483782 -287.008316)
		(end 172.56887 -287.008316)
		(width 0.16002)
		(layer "In11.Cu")
		(net "M_L_CPU1_SB_DQS_DN<5>")
	)
	(segment
		(start 201.10196 -286.009334)
		(end 201.873866 -286.009334)
		(width 0.16002)
		(layer "In11.Cu")
		(net "M_L_CPU1_SB_DQS_DN<5>")
	)
	(segment
		(start 175.241204 -285.779718)
		(end 175.619664 -286.158178)
		(width 0.16002)
		(layer "In11.Cu")
		(net "M_L_CPU1_SB_DQS_DN<5>")
	)
	(segment
		(start 164.640768 -285.698946)
		(end 164.977826 -286.036004)
		(width 0.16002)
		(layer "In11.Cu")
		(net "M_L_CPU1_SB_DQS_DN<5>")
	)
	(segment
		(start 147.21967 -275.598382)
		(end 147.49653 -275.875242)
		(width 0.09525)
		(layer "In11.Cu")
		(net "M_L_CPU1_SB_DQS_DN<5>")
	)
	(segment
		(start 168.858184 -285.673546)
		(end 169.018204 -285.833566)
		(width 0.16002)
		(layer "In11.Cu")
		(net "M_L_CPU1_SB_DQS_DN<5>")
	)
	(segment
		(start 197.873366 -285.779718)
		(end 198.251826 -286.158178)
		(width 0.16002)
		(layer "In11.Cu")
		(net "M_L_CPU1_SB_DQS_DN<5>")
	)
	(segment
		(start 152.480518 -275.81606)
		(end 163.297616 -286.633158)
		(width 0.16002)
		(layer "In11.Cu")
		(net "M_L_CPU1_SB_DQS_DN<5>")
	)
	(segment
		(start 167.42537 -285.833566)
		(end 167.58539 -285.673546)
		(width 0.16002)
		(layer "In11.Cu")
		(net "M_L_CPU1_SB_DQS_DN<5>")
	)
	(segment
		(start 189.50686 -285.779718)
		(end 190.329312 -285.779718)
		(width 0.16002)
		(layer "In11.Cu")
		(net "M_L_CPU1_SB_DQS_DN<5>")
	)
	(segment
		(start 145.76425 -276.765766)
		(end 146.931634 -275.598382)
		(width 0.09525)
		(layer "In11.Cu")
		(net "M_L_CPU1_SB_DQS_DN<5>")
	)
	(segment
		(start 164.977826 -286.036004)
		(end 164.977826 -286.473138)
		(width 0.16002)
		(layer "In11.Cu")
		(net "M_L_CPU1_SB_DQS_DN<5>")
	)
	(segment
		(start 170.633644 -286.158178)
		(end 171.483782 -287.008316)
		(width 0.16002)
		(layer "In11.Cu")
		(net "M_L_CPU1_SB_DQS_DN<5>")
	)
	(segment
		(start 178.79314 -287.008316)
		(end 180.112924 -287.008316)
		(width 0.16002)
		(layer "In11.Cu")
		(net "M_L_CPU1_SB_DQS_DN<5>")
	)
	(segment
		(start 147.919186 -275.81606)
		(end 152.480518 -275.81606)
		(width 0.16002)
		(layer "In11.Cu")
		(net "M_L_CPU1_SB_DQS_DN<5>")
	)
	(segment
		(start 177.943002 -286.158178)
		(end 178.79314 -287.008316)
		(width 0.16002)
		(layer "In11.Cu")
		(net "M_L_CPU1_SB_DQS_DN<5>")
	)
	(segment
		(start 186.337194 -287.008316)
		(end 187.656978 -287.008316)
		(width 0.16002)
		(layer "In11.Cu")
		(net "M_L_CPU1_SB_DQS_DN<5>")
	)
	(segment
		(start 198.251826 -286.158178)
		(end 199.31253 -286.158178)
		(width 0.16002)
		(layer "In11.Cu")
		(net "M_L_CPU1_SB_DQS_DN<5>")
	)
	(segment
		(start 185.487056 -286.158178)
		(end 186.337194 -287.008316)
		(width 0.16002)
		(layer "In11.Cu")
		(net "M_L_CPU1_SB_DQS_DN<5>")
	)
	(segment
		(start 163.297616 -286.633158)
		(end 163.545012 -286.633158)
		(width 0.16002)
		(layer "In11.Cu")
		(net "M_L_CPU1_SB_DQS_DN<5>")
	)
	(segment
		(start 190.707772 -286.158178)
		(end 193.03111 -286.158178)
		(width 0.16002)
		(layer "In11.Cu")
		(net "M_L_CPU1_SB_DQS_DN<5>")
	)
	(segment
		(start 166.021258 -286.633158)
		(end 166.82085 -285.833566)
		(width 0.16002)
		(layer "In11.Cu")
		(net "M_L_CPU1_SB_DQS_DN<5>")
	)
	(segment
		(start 165.137846 -286.633158)
		(end 166.021258 -286.633158)
		(width 0.16002)
		(layer "In11.Cu")
		(net "M_L_CPU1_SB_DQS_DN<5>")
	)
	(segment
		(start 166.82085 -285.833566)
		(end 167.42537 -285.833566)
		(width 0.16002)
		(layer "In11.Cu")
		(net "M_L_CPU1_SB_DQS_DN<5>")
	)
	(segment
		(start 187.656978 -287.008316)
		(end 188.032136 -286.633158)
		(width 0.16002)
		(layer "In11.Cu")
		(net "M_L_CPU1_SB_DQS_DN<5>")
	)
	(segment
		(start 147.836382 -275.875242)
		(end 147.895564 -275.81606)
		(width 0.09525)
		(layer "In11.Cu")
		(net "M_L_CPU1_SB_DQS_DN<5>")
	)
	(segment
		(start 201.873866 -286.009334)
		(end 202.147932 -285.735268)
		(width 0.16002)
		(layer "In11.Cu")
		(net "M_L_CPU1_SB_DQS_DN<5>")
	)
	(segment
		(start 145.444718 -276.765766)
		(end 145.76425 -276.765766)
		(width 0.09525)
		(layer "In11.Cu")
		(net "M_L_CPU1_SB_DQS_DN<5>")
	)
	(segment
		(start 163.545012 -286.633158)
		(end 163.705032 -286.473138)
		(width 0.16002)
		(layer "In11.Cu")
		(net "M_L_CPU1_SB_DQS_DN<5>")
	)
	(segment
		(start 168.521126 -285.183326)
		(end 168.858184 -285.520384)
		(width 0.16002)
		(layer "In11.Cu")
		(net "M_L_CPU1_SB_DQS_DN<5>")
	)
	(segment
		(start 172.944028 -286.633158)
		(end 173.565312 -286.633158)
		(width 0.16002)
		(layer "In11.Cu")
		(net "M_L_CPU1_SB_DQS_DN<5>")
	)
	(segment
		(start 195.201032 -287.008316)
		(end 195.57619 -286.633158)
		(width 0.16002)
		(layer "In11.Cu")
		(net "M_L_CPU1_SB_DQS_DN<5>")
	)
	(segment
		(start 199.461374 -286.009334)
		(end 200.3679 -286.009334)
		(width 0.16002)
		(layer "In11.Cu")
		(net "M_L_CPU1_SB_DQS_DN<5>")
	)
	(arc
		(start 140.08608 -276.841458)
		(mid 140.269855 -276.89223)
		(end 140.454888 -276.846284)
		(width 0.09525)
		(layer "In11.Cu")
		(net "M_L_CPU1_SB_DQS_DN<5>")
	)
	(arc
		(start 140.46327 -276.841458)
		(mid 140.744702 -276.765703)
		(end 141.026134 -276.841458)
		(width 0.09525)
		(layer "In11.Cu")
		(net "M_L_CPU1_SB_DQS_DN<5>")
	)
	(arc
		(start 138.583416 -276.841458)
		(mid 138.864848 -276.765703)
		(end 139.14628 -276.841458)
		(width 0.09525)
		(layer "In11.Cu")
		(net "M_L_CPU1_SB_DQS_DN<5>")
	)
	(arc
		(start 144.786604 -276.841458)
		(mid 144.96822 -276.892195)
		(end 145.151602 -276.848316)
		(width 0.09525)
		(layer "In11.Cu")
		(net "M_L_CPU1_SB_DQS_DN<5>")
	)
	(arc
		(start 144.223486 -276.841458)
		(mid 144.499029 -276.765609)
		(end 144.77619 -276.835362)
		(width 0.09525)
		(layer "In11.Cu")
		(net "M_L_CPU1_SB_DQS_DN<5>")
	)
	(arc
		(start 142.343378 -276.841458)
		(mid 142.62481 -276.765703)
		(end 142.906242 -276.841458)
		(width 0.09525)
		(layer "In11.Cu")
		(net "M_L_CPU1_SB_DQS_DN<5>")
	)
	(arc
		(start 141.97457 -276.846284)
		(mid 142.159602 -276.892198)
		(end 142.343378 -276.841458)
		(width 0.09525)
		(layer "In11.Cu")
		(net "M_L_CPU1_SB_DQS_DN<5>")
	)
	(arc
		(start 141.026134 -276.841458)
		(mid 141.209909 -276.89223)
		(end 141.394942 -276.846284)
		(width 0.09525)
		(layer "In11.Cu")
		(net "M_L_CPU1_SB_DQS_DN<5>")
	)
	(arc
		(start 145.16354 -276.841458)
		(mid 145.299132 -276.785067)
		(end 145.444718 -276.765766)
		(width 0.09525)
		(layer "In11.Cu")
		(net "M_L_CPU1_SB_DQS_DN<5>")
	)
	(arc
		(start 139.523216 -276.841458)
		(mid 139.804648 -276.765703)
		(end 140.08608 -276.841458)
		(width 0.09525)
		(layer "In11.Cu")
		(net "M_L_CPU1_SB_DQS_DN<5>")
	)
	(arc
		(start 141.403324 -276.841458)
		(mid 141.684756 -276.765703)
		(end 141.966188 -276.841458)
		(width 0.09525)
		(layer "In11.Cu")
		(net "M_L_CPU1_SB_DQS_DN<5>")
	)
	(arc
		(start 139.14628 -276.841458)
		(mid 139.334748 -276.892135)
		(end 139.523216 -276.841458)
		(width 0.09525)
		(layer "In11.Cu")
		(net "M_L_CPU1_SB_DQS_DN<5>")
	)
	(arc
		(start 138.264138 -276.868636)
		(mid 138.42682 -276.890768)
		(end 138.583416 -276.841458)
		(width 0.09525)
		(layer "In11.Cu")
		(net "M_L_CPU1_SB_DQS_DN<5>")
	)
	(arc
		(start 142.906242 -276.841458)
		(mid 143.09471 -276.892135)
		(end 143.283178 -276.841458)
		(width 0.09525)
		(layer "In11.Cu")
		(net "M_L_CPU1_SB_DQS_DN<5>")
	)
	(arc
		(start 143.283178 -276.841458)
		(mid 143.56461 -276.765703)
		(end 143.846042 -276.841458)
		(width 0.09525)
		(layer "In11.Cu")
		(net "M_L_CPU1_SB_DQS_DN<5>")
	)
	(arc
		(start 143.846042 -276.841458)
		(mid 144.034764 -276.892262)
		(end 144.223486 -276.841458)
		(width 0.09525)
		(layer "In11.Cu")
		(net "M_L_CPU1_SB_DQS_DN<5>")
	)
	(segment
		(start 137.927842 -271.390364)
		(end 138.394694 -271.656302)
		(width 0.12954)
		(layer "F.Cu")
		(net "M_L_CPU1_SB_DQS_DN<4>")
	)
	(segment
		(start 188.032136 -277.283164)
		(end 188.65342 -277.283164)
		(width 0.16002)
		(layer "In11.Cu")
		(net "M_L_CPU1_SB_DQS_DN<4>")
	)
	(segment
		(start 186.337194 -277.658322)
		(end 187.656978 -277.658322)
		(width 0.16002)
		(layer "In11.Cu")
		(net "M_L_CPU1_SB_DQS_DN<4>")
	)
	(segment
		(start 170.239944 -276.429724)
		(end 171.468542 -277.658322)
		(width 0.16002)
		(layer "In11.Cu")
		(net "M_L_CPU1_SB_DQS_DN<4>")
	)
	(segment
		(start 189.50686 -276.429724)
		(end 190.329312 -276.429724)
		(width 0.16002)
		(layer "In11.Cu")
		(net "M_L_CPU1_SB_DQS_DN<4>")
	)
	(segment
		(start 182.785258 -276.429724)
		(end 183.163718 -276.808184)
		(width 0.16002)
		(layer "In11.Cu")
		(net "M_L_CPU1_SB_DQS_DN<4>")
	)
	(segment
		(start 199.461374 -276.65934)
		(end 200.4314 -276.65934)
		(width 0.16002)
		(layer "In11.Cu")
		(net "M_L_CPU1_SB_DQS_DN<4>")
	)
	(segment
		(start 163.347146 -276.19071)
		(end 163.347146 -276.77618)
		(width 0.16002)
		(layer "In11.Cu")
		(net "M_L_CPU1_SB_DQS_DN<4>")
	)
	(segment
		(start 193.03111 -276.808184)
		(end 193.881248 -277.658322)
		(width 0.16002)
		(layer "In11.Cu")
		(net "M_L_CPU1_SB_DQS_DN<4>")
	)
	(segment
		(start 180.112924 -277.658322)
		(end 180.488082 -277.283164)
		(width 0.16002)
		(layer "In11.Cu")
		(net "M_L_CPU1_SB_DQS_DN<4>")
	)
	(segment
		(start 175.241204 -276.429724)
		(end 175.619664 -276.808184)
		(width 0.16002)
		(layer "In11.Cu")
		(net "M_L_CPU1_SB_DQS_DN<4>")
	)
	(segment
		(start 200.4314 -276.65934)
		(end 200.5584 -276.53234)
		(width 0.16002)
		(layer "In11.Cu")
		(net "M_L_CPU1_SB_DQS_DN<4>")
	)
	(segment
		(start 163.85413 -277.283164)
		(end 166.021258 -277.283164)
		(width 0.16002)
		(layer "In11.Cu")
		(net "M_L_CPU1_SB_DQS_DN<4>")
	)
	(segment
		(start 166.874698 -276.429724)
		(end 168.062656 -276.429724)
		(width 0.16002)
		(layer "In11.Cu")
		(net "M_L_CPU1_SB_DQS_DN<4>")
	)
	(segment
		(start 160.904936 -274.33397)
		(end 161.490406 -274.33397)
		(width 0.16002)
		(layer "In11.Cu")
		(net "M_L_CPU1_SB_DQS_DN<4>")
	)
	(segment
		(start 183.163718 -276.808184)
		(end 185.487056 -276.808184)
		(width 0.16002)
		(layer "In11.Cu")
		(net "M_L_CPU1_SB_DQS_DN<4>")
	)
	(segment
		(start 174.418752 -276.429724)
		(end 175.241204 -276.429724)
		(width 0.16002)
		(layer "In11.Cu")
		(net "M_L_CPU1_SB_DQS_DN<4>")
	)
	(segment
		(start 169.067988 -276.956266)
		(end 169.067988 -276.766782)
		(width 0.16002)
		(layer "In11.Cu")
		(net "M_L_CPU1_SB_DQS_DN<4>")
	)
	(segment
		(start 145.71091 -271.112488)
		(end 146.415252 -270.408146)
		(width 0.09525)
		(layer "In11.Cu")
		(net "M_L_CPU1_SB_DQS_DN<4>")
	)
	(segment
		(start 140.454888 -271.986248)
		(end 140.46327 -271.981422)
		(width 0.09525)
		(layer "In11.Cu")
		(net "M_L_CPU1_SB_DQS_DN<4>")
	)
	(segment
		(start 145.154904 -271.986248)
		(end 145.163286 -271.981422)
		(width 0.09525)
		(layer "In11.Cu")
		(net "M_L_CPU1_SB_DQS_DN<4>")
	)
	(segment
		(start 169.405046 -276.429724)
		(end 170.239944 -276.429724)
		(width 0.16002)
		(layer "In11.Cu")
		(net "M_L_CPU1_SB_DQS_DN<4>")
	)
	(segment
		(start 190.329312 -276.429724)
		(end 190.707772 -276.808184)
		(width 0.16002)
		(layer "In11.Cu")
		(net "M_L_CPU1_SB_DQS_DN<4>")
	)
	(segment
		(start 193.881248 -277.658322)
		(end 195.201032 -277.658322)
		(width 0.16002)
		(layer "In11.Cu")
		(net "M_L_CPU1_SB_DQS_DN<4>")
	)
	(segment
		(start 145.598134 -271.19199)
		(end 145.633186 -271.171416)
		(width 0.09525)
		(layer "In11.Cu")
		(net "M_L_CPU1_SB_DQS_DN<4>")
	)
	(segment
		(start 198.251826 -276.808184)
		(end 199.31253 -276.808184)
		(width 0.16002)
		(layer "In11.Cu")
		(net "M_L_CPU1_SB_DQS_DN<4>")
	)
	(segment
		(start 197.873366 -276.429724)
		(end 198.251826 -276.808184)
		(width 0.16002)
		(layer "In11.Cu")
		(net "M_L_CPU1_SB_DQS_DN<4>")
	)
	(segment
		(start 147.39112 -270.203676)
		(end 147.836382 -270.203676)
		(width 0.09525)
		(layer "In11.Cu")
		(net "M_L_CPU1_SB_DQS_DN<4>")
	)
	(segment
		(start 166.021258 -277.283164)
		(end 166.874698 -276.429724)
		(width 0.16002)
		(layer "In11.Cu")
		(net "M_L_CPU1_SB_DQS_DN<4>")
	)
	(segment
		(start 168.062656 -276.429724)
		(end 168.399714 -276.766782)
		(width 0.16002)
		(layer "In11.Cu")
		(net "M_L_CPU1_SB_DQS_DN<4>")
	)
	(segment
		(start 168.399714 -276.956266)
		(end 168.559734 -277.116286)
		(width 0.16002)
		(layer "In11.Cu")
		(net "M_L_CPU1_SB_DQS_DN<4>")
	)
	(segment
		(start 141.966188 -271.981422)
		(end 141.97457 -271.986248)
		(width 0.09525)
		(layer "In11.Cu")
		(net "M_L_CPU1_SB_DQS_DN<4>")
	)
	(segment
		(start 146.415252 -270.408146)
		(end 147.18665 -270.408146)
		(width 0.09525)
		(layer "In11.Cu")
		(net "M_L_CPU1_SB_DQS_DN<4>")
	)
	(segment
		(start 196.197474 -277.283164)
		(end 197.050914 -276.429724)
		(width 0.16002)
		(layer "In11.Cu")
		(net "M_L_CPU1_SB_DQS_DN<4>")
	)
	(segment
		(start 185.487056 -276.808184)
		(end 186.337194 -277.658322)
		(width 0.16002)
		(layer "In11.Cu")
		(net "M_L_CPU1_SB_DQS_DN<4>")
	)
	(segment
		(start 190.707772 -276.808184)
		(end 193.03111 -276.808184)
		(width 0.16002)
		(layer "In11.Cu")
		(net "M_L_CPU1_SB_DQS_DN<4>")
	)
	(segment
		(start 138.394694 -271.656302)
		(end 138.24077 -271.921732)
		(width 0.09525)
		(layer "In11.Cu")
		(net "M_L_CPU1_SB_DQS_DN<4>")
	)
	(segment
		(start 161.973514 -275.402548)
		(end 162.278568 -275.707602)
		(width 0.16002)
		(layer "In11.Cu")
		(net "M_L_CPU1_SB_DQS_DN<4>")
	)
	(segment
		(start 147.895564 -270.144494)
		(end 147.919186 -270.144494)
		(width 0.09525)
		(layer "In11.Cu")
		(net "M_L_CPU1_SB_DQS_DN<4>")
	)
	(segment
		(start 138.24077 -271.921732)
		(end 138.264138 -272.0086)
		(width 0.09525)
		(layer "In11.Cu")
		(net "M_L_CPU1_SB_DQS_DN<4>")
	)
	(segment
		(start 200.5584 -276.53234)
		(end 201.03846 -276.53234)
		(width 0.16002)
		(layer "In11.Cu")
		(net "M_L_CPU1_SB_DQS_DN<4>")
	)
	(segment
		(start 159.531304 -272.960338)
		(end 160.116774 -272.960338)
		(width 0.16002)
		(layer "In11.Cu")
		(net "M_L_CPU1_SB_DQS_DN<4>")
	)
	(segment
		(start 160.116774 -272.960338)
		(end 160.599882 -273.443446)
		(width 0.16002)
		(layer "In11.Cu")
		(net "M_L_CPU1_SB_DQS_DN<4>")
	)
	(segment
		(start 141.394942 -271.986248)
		(end 141.403324 -271.981422)
		(width 0.09525)
		(layer "In11.Cu")
		(net "M_L_CPU1_SB_DQS_DN<4>")
	)
	(segment
		(start 181.109366 -277.283164)
		(end 181.962806 -276.429724)
		(width 0.16002)
		(layer "In11.Cu")
		(net "M_L_CPU1_SB_DQS_DN<4>")
	)
	(segment
		(start 168.907968 -277.116286)
		(end 169.067988 -276.956266)
		(width 0.16002)
		(layer "In11.Cu")
		(net "M_L_CPU1_SB_DQS_DN<4>")
	)
	(segment
		(start 168.559734 -277.116286)
		(end 168.907968 -277.116286)
		(width 0.16002)
		(layer "In11.Cu")
		(net "M_L_CPU1_SB_DQS_DN<4>")
	)
	(segment
		(start 173.565312 -277.283164)
		(end 174.418752 -276.429724)
		(width 0.16002)
		(layer "In11.Cu")
		(net "M_L_CPU1_SB_DQS_DN<4>")
	)
	(segment
		(start 162.864038 -275.707602)
		(end 163.347146 -276.19071)
		(width 0.16002)
		(layer "In11.Cu")
		(net "M_L_CPU1_SB_DQS_DN<4>")
	)
	(segment
		(start 172.56887 -277.658322)
		(end 172.944028 -277.283164)
		(width 0.16002)
		(layer "In11.Cu")
		(net "M_L_CPU1_SB_DQS_DN<4>")
	)
	(segment
		(start 147.18665 -270.408146)
		(end 147.39112 -270.203676)
		(width 0.09525)
		(layer "In11.Cu")
		(net "M_L_CPU1_SB_DQS_DN<4>")
	)
	(segment
		(start 201.03846 -276.53234)
		(end 201.16546 -276.65934)
		(width 0.16002)
		(layer "In11.Cu")
		(net "M_L_CPU1_SB_DQS_DN<4>")
	)
	(segment
		(start 160.599882 -274.028916)
		(end 160.904936 -274.33397)
		(width 0.16002)
		(layer "In11.Cu")
		(net "M_L_CPU1_SB_DQS_DN<4>")
	)
	(segment
		(start 195.201032 -277.658322)
		(end 195.57619 -277.283164)
		(width 0.16002)
		(layer "In11.Cu")
		(net "M_L_CPU1_SB_DQS_DN<4>")
	)
	(segment
		(start 188.65342 -277.283164)
		(end 189.50686 -276.429724)
		(width 0.16002)
		(layer "In11.Cu")
		(net "M_L_CPU1_SB_DQS_DN<4>")
	)
	(segment
		(start 147.836382 -270.203676)
		(end 147.895564 -270.144494)
		(width 0.09525)
		(layer "In11.Cu")
		(net "M_L_CPU1_SB_DQS_DN<4>")
	)
	(segment
		(start 187.656978 -277.658322)
		(end 188.032136 -277.283164)
		(width 0.16002)
		(layer "In11.Cu")
		(net "M_L_CPU1_SB_DQS_DN<4>")
	)
	(segment
		(start 181.962806 -276.429724)
		(end 182.785258 -276.429724)
		(width 0.16002)
		(layer "In11.Cu")
		(net "M_L_CPU1_SB_DQS_DN<4>")
	)
	(segment
		(start 145.163286 -271.981422)
		(end 145.195798 -271.962626)
		(width 0.09525)
		(layer "In11.Cu")
		(net "M_L_CPU1_SB_DQS_DN<4>")
	)
	(segment
		(start 172.944028 -277.283164)
		(end 173.565312 -277.283164)
		(width 0.16002)
		(layer "In11.Cu")
		(net "M_L_CPU1_SB_DQS_DN<4>")
	)
	(segment
		(start 195.57619 -277.283164)
		(end 196.197474 -277.283164)
		(width 0.16002)
		(layer "In11.Cu")
		(net "M_L_CPU1_SB_DQS_DN<4>")
	)
	(segment
		(start 169.067988 -276.766782)
		(end 169.405046 -276.429724)
		(width 0.16002)
		(layer "In11.Cu")
		(net "M_L_CPU1_SB_DQS_DN<4>")
	)
	(segment
		(start 180.488082 -277.283164)
		(end 181.109366 -277.283164)
		(width 0.16002)
		(layer "In11.Cu")
		(net "M_L_CPU1_SB_DQS_DN<4>")
	)
	(segment
		(start 201.873866 -276.65934)
		(end 202.147932 -276.385274)
		(width 0.16002)
		(layer "In11.Cu")
		(net "M_L_CPU1_SB_DQS_DN<4>")
	)
	(segment
		(start 201.16546 -276.65934)
		(end 201.873866 -276.65934)
		(width 0.16002)
		(layer "In11.Cu")
		(net "M_L_CPU1_SB_DQS_DN<4>")
	)
	(segment
		(start 171.468542 -277.658322)
		(end 172.56887 -277.658322)
		(width 0.16002)
		(layer "In11.Cu")
		(net "M_L_CPU1_SB_DQS_DN<4>")
	)
	(segment
		(start 168.399714 -276.766782)
		(end 168.399714 -276.956266)
		(width 0.16002)
		(layer "In11.Cu")
		(net "M_L_CPU1_SB_DQS_DN<4>")
	)
	(segment
		(start 144.21485 -271.986248)
		(end 144.223232 -271.981422)
		(width 0.09525)
		(layer "In11.Cu")
		(net "M_L_CPU1_SB_DQS_DN<4>")
	)
	(segment
		(start 161.490406 -274.33397)
		(end 161.973514 -274.817078)
		(width 0.16002)
		(layer "In11.Cu")
		(net "M_L_CPU1_SB_DQS_DN<4>")
	)
	(segment
		(start 197.050914 -276.429724)
		(end 197.873366 -276.429724)
		(width 0.16002)
		(layer "In11.Cu")
		(net "M_L_CPU1_SB_DQS_DN<4>")
	)
	(segment
		(start 175.619664 -276.808184)
		(end 177.943002 -276.808184)
		(width 0.16002)
		(layer "In11.Cu")
		(net "M_L_CPU1_SB_DQS_DN<4>")
	)
	(segment
		(start 199.31253 -276.808184)
		(end 199.461374 -276.65934)
		(width 0.16002)
		(layer "In11.Cu")
		(net "M_L_CPU1_SB_DQS_DN<4>")
	)
	(segment
		(start 162.278568 -275.707602)
		(end 162.864038 -275.707602)
		(width 0.16002)
		(layer "In11.Cu")
		(net "M_L_CPU1_SB_DQS_DN<4>")
	)
	(segment
		(start 160.599882 -273.443446)
		(end 160.599882 -274.028916)
		(width 0.16002)
		(layer "In11.Cu")
		(net "M_L_CPU1_SB_DQS_DN<4>")
	)
	(segment
		(start 161.973514 -274.817078)
		(end 161.973514 -275.402548)
		(width 0.16002)
		(layer "In11.Cu")
		(net "M_L_CPU1_SB_DQS_DN<4>")
	)
	(segment
		(start 147.919186 -270.144494)
		(end 156.71546 -270.144494)
		(width 0.16002)
		(layer "In11.Cu")
		(net "M_L_CPU1_SB_DQS_DN<4>")
	)
	(segment
		(start 177.943002 -276.808184)
		(end 178.79314 -277.658322)
		(width 0.16002)
		(layer "In11.Cu")
		(net "M_L_CPU1_SB_DQS_DN<4>")
	)
	(segment
		(start 178.79314 -277.658322)
		(end 180.112924 -277.658322)
		(width 0.16002)
		(layer "In11.Cu")
		(net "M_L_CPU1_SB_DQS_DN<4>")
	)
	(segment
		(start 156.71546 -270.144494)
		(end 159.531304 -272.960338)
		(width 0.16002)
		(layer "In11.Cu")
		(net "M_L_CPU1_SB_DQS_DN<4>")
	)
	(segment
		(start 163.347146 -276.77618)
		(end 163.85413 -277.283164)
		(width 0.16002)
		(layer "In11.Cu")
		(net "M_L_CPU1_SB_DQS_DN<4>")
	)
	(arc
		(start 143.846042 -271.981422)
		(mid 144.029817 -272.032194)
		(end 144.21485 -271.986248)
		(width 0.09525)
		(layer "In11.Cu")
		(net "M_L_CPU1_SB_DQS_DN<4>")
	)
	(arc
		(start 143.283178 -271.981422)
		(mid 143.56461 -271.905667)
		(end 143.846042 -271.981422)
		(width 0.09525)
		(layer "In11.Cu")
		(net "M_L_CPU1_SB_DQS_DN<4>")
	)
	(arc
		(start 139.14628 -271.981422)
		(mid 139.334748 -272.032099)
		(end 139.523216 -271.981422)
		(width 0.09525)
		(layer "In11.Cu")
		(net "M_L_CPU1_SB_DQS_DN<4>")
	)
	(arc
		(start 142.906242 -271.981422)
		(mid 143.09471 -272.032099)
		(end 143.283178 -271.981422)
		(width 0.09525)
		(layer "In11.Cu")
		(net "M_L_CPU1_SB_DQS_DN<4>")
	)
	(arc
		(start 138.583416 -271.981422)
		(mid 138.864848 -271.905667)
		(end 139.14628 -271.981422)
		(width 0.09525)
		(layer "In11.Cu")
		(net "M_L_CPU1_SB_DQS_DN<4>")
	)
	(arc
		(start 141.97457 -271.986248)
		(mid 142.159602 -272.032162)
		(end 142.343378 -271.981422)
		(width 0.09525)
		(layer "In11.Cu")
		(net "M_L_CPU1_SB_DQS_DN<4>")
	)
	(arc
		(start 140.08608 -271.981422)
		(mid 140.269855 -272.032194)
		(end 140.454888 -271.986248)
		(width 0.09525)
		(layer "In11.Cu")
		(net "M_L_CPU1_SB_DQS_DN<4>")
	)
	(arc
		(start 141.403324 -271.981422)
		(mid 141.684756 -271.905667)
		(end 141.966188 -271.981422)
		(width 0.09525)
		(layer "In11.Cu")
		(net "M_L_CPU1_SB_DQS_DN<4>")
	)
	(arc
		(start 145.195798 -271.962626)
		(mid 145.311072 -271.828348)
		(end 145.352516 -271.656302)
		(width 0.09525)
		(layer "In11.Cu")
		(net "M_L_CPU1_SB_DQS_DN<4>")
	)
	(arc
		(start 144.223232 -271.981422)
		(mid 144.504664 -271.905667)
		(end 144.786096 -271.981422)
		(width 0.09525)
		(layer "In11.Cu")
		(net "M_L_CPU1_SB_DQS_DN<4>")
	)
	(arc
		(start 138.264138 -272.0086)
		(mid 138.42682 -272.030732)
		(end 138.583416 -271.981422)
		(width 0.09525)
		(layer "In11.Cu")
		(net "M_L_CPU1_SB_DQS_DN<4>")
	)
	(arc
		(start 140.46327 -271.981422)
		(mid 140.744702 -271.905667)
		(end 141.026134 -271.981422)
		(width 0.09525)
		(layer "In11.Cu")
		(net "M_L_CPU1_SB_DQS_DN<4>")
	)
	(arc
		(start 145.352516 -271.656302)
		(mid 145.417763 -271.393699)
		(end 145.598134 -271.19199)
		(width 0.09525)
		(layer "In11.Cu")
		(net "M_L_CPU1_SB_DQS_DN<4>")
	)
	(arc
		(start 145.633186 -271.171416)
		(mid 145.673967 -271.144483)
		(end 145.71091 -271.112488)
		(width 0.09525)
		(layer "In11.Cu")
		(net "M_L_CPU1_SB_DQS_DN<4>")
	)
	(arc
		(start 141.026134 -271.981422)
		(mid 141.209909 -272.032194)
		(end 141.394942 -271.986248)
		(width 0.09525)
		(layer "In11.Cu")
		(net "M_L_CPU1_SB_DQS_DN<4>")
	)
	(arc
		(start 144.786096 -271.981422)
		(mid 144.969871 -272.032194)
		(end 145.154904 -271.986248)
		(width 0.09525)
		(layer "In11.Cu")
		(net "M_L_CPU1_SB_DQS_DN<4>")
	)
	(arc
		(start 139.523216 -271.981422)
		(mid 139.804648 -271.905667)
		(end 140.08608 -271.981422)
		(width 0.09525)
		(layer "In11.Cu")
		(net "M_L_CPU1_SB_DQS_DN<4>")
	)
	(arc
		(start 142.343378 -271.981422)
		(mid 142.62481 -271.905667)
		(end 142.906242 -271.981422)
		(width 0.09525)
		(layer "In11.Cu")
		(net "M_L_CPU1_SB_DQS_DN<4>")
	)
	(segment
		(start 138.867896 -290.830254)
		(end 139.334748 -291.096192)
		(width 0.12954)
		(layer "F.Cu")
		(net "M_L_CPU1_SB_DQS_DN<3>")
	)
	(segment
		(start 197.948296 -312.512456)
		(end 199.607424 -312.512456)
		(width 0.16002)
		(layer "In11.Cu")
		(net "M_L_CPU1_SB_DQS_DN<3>")
	)
	(segment
		(start 148.13661 -300.107096)
		(end 161.719514 -313.69)
		(width 0.16002)
		(layer "In11.Cu")
		(net "M_L_CPU1_SB_DQS_DN<3>")
	)
	(segment
		(start 172.425106 -313.36234)
		(end 172.752766 -313.69)
		(width 0.16002)
		(layer "In11.Cu")
		(net "M_L_CPU1_SB_DQS_DN<3>")
	)
	(segment
		(start 196.359272 -313.69)
		(end 197.182232 -312.86704)
		(width 0.16002)
		(layer "In11.Cu")
		(net "M_L_CPU1_SB_DQS_DN<3>")
	)
	(segment
		(start 203.221844 -313.70524)
		(end 203.886816 -313.70524)
		(width 0.16002)
		(layer "In11.Cu")
		(net "M_L_CPU1_SB_DQS_DN<3>")
	)
	(segment
		(start 200.181464 -313.086496)
		(end 202.6031 -313.086496)
		(width 0.16002)
		(layer "In11.Cu")
		(net "M_L_CPU1_SB_DQS_DN<3>")
	)
	(segment
		(start 182.094124 -312.86704)
		(end 182.505604 -312.86704)
		(width 0.16002)
		(layer "In11.Cu")
		(net "M_L_CPU1_SB_DQS_DN<3>")
	)
	(segment
		(start 147.603718 -294.526208)
		(end 148.13661 -295.0591)
		(width 0.16002)
		(layer "In11.Cu")
		(net "M_L_CPU1_SB_DQS_DN<3>")
	)
	(segment
		(start 204.080618 -313.511438)
		(end 205.974188 -313.511438)
		(width 0.16002)
		(layer "In11.Cu")
		(net "M_L_CPU1_SB_DQS_DN<3>")
	)
	(segment
		(start 195.057268 -313.36234)
		(end 195.384928 -313.69)
		(width 0.16002)
		(layer "In11.Cu")
		(net "M_L_CPU1_SB_DQS_DN<3>")
	)
	(segment
		(start 147.586954 -294.425624)
		(end 147.586954 -294.509444)
		(width 0.09525)
		(layer "In11.Cu")
		(net "M_L_CPU1_SB_DQS_DN<3>")
	)
	(segment
		(start 177.825146 -313.36234)
		(end 179.96916 -313.36234)
		(width 0.16002)
		(layer "In11.Cu")
		(net "M_L_CPU1_SB_DQS_DN<3>")
	)
	(segment
		(start 182.860188 -312.512456)
		(end 184.519316 -312.512456)
		(width 0.16002)
		(layer "In11.Cu")
		(net "M_L_CPU1_SB_DQS_DN<3>")
	)
	(segment
		(start 174.96155 -312.86704)
		(end 175.316134 -312.512456)
		(width 0.16002)
		(layer "In11.Cu")
		(net "M_L_CPU1_SB_DQS_DN<3>")
	)
	(segment
		(start 147.586954 -294.509444)
		(end 147.603718 -294.526208)
		(width 0.09525)
		(layer "In11.Cu")
		(net "M_L_CPU1_SB_DQS_DN<3>")
	)
	(segment
		(start 140.454888 -290.766246)
		(end 140.46327 -290.771072)
		(width 0.09525)
		(layer "In11.Cu")
		(net "M_L_CPU1_SB_DQS_DN<3>")
	)
	(segment
		(start 144.034764 -290.719764)
		(end 144.635728 -290.719764)
		(width 0.09525)
		(layer "In11.Cu")
		(net "M_L_CPU1_SB_DQS_DN<3>")
	)
	(segment
		(start 184.519316 -312.512456)
		(end 185.3692 -313.36234)
		(width 0.16002)
		(layer "In11.Cu")
		(net "M_L_CPU1_SB_DQS_DN<3>")
	)
	(segment
		(start 166.183056 -313.69)
		(end 167.006016 -312.86704)
		(width 0.16002)
		(layer "In11.Cu")
		(net "M_L_CPU1_SB_DQS_DN<3>")
	)
	(segment
		(start 173.72711 -313.69)
		(end 174.55007 -312.86704)
		(width 0.16002)
		(layer "In11.Cu")
		(net "M_L_CPU1_SB_DQS_DN<3>")
	)
	(segment
		(start 185.3692 -313.36234)
		(end 187.513214 -313.36234)
		(width 0.16002)
		(layer "In11.Cu")
		(net "M_L_CPU1_SB_DQS_DN<3>")
	)
	(segment
		(start 199.607424 -312.512456)
		(end 200.181464 -313.086496)
		(width 0.16002)
		(layer "In11.Cu")
		(net "M_L_CPU1_SB_DQS_DN<3>")
	)
	(segment
		(start 187.840874 -313.69)
		(end 188.815218 -313.69)
		(width 0.16002)
		(layer "In11.Cu")
		(net "M_L_CPU1_SB_DQS_DN<3>")
	)
	(segment
		(start 172.752766 -313.69)
		(end 173.72711 -313.69)
		(width 0.16002)
		(layer "In11.Cu")
		(net "M_L_CPU1_SB_DQS_DN<3>")
	)
	(segment
		(start 176.975262 -312.512456)
		(end 177.825146 -313.36234)
		(width 0.16002)
		(layer "In11.Cu")
		(net "M_L_CPU1_SB_DQS_DN<3>")
	)
	(segment
		(start 182.505604 -312.86704)
		(end 182.860188 -312.512456)
		(width 0.16002)
		(layer "In11.Cu")
		(net "M_L_CPU1_SB_DQS_DN<3>")
	)
	(segment
		(start 180.29682 -313.69)
		(end 181.271164 -313.69)
		(width 0.16002)
		(layer "In11.Cu")
		(net "M_L_CPU1_SB_DQS_DN<3>")
	)
	(segment
		(start 188.815218 -313.69)
		(end 189.638178 -312.86704)
		(width 0.16002)
		(layer "In11.Cu")
		(net "M_L_CPU1_SB_DQS_DN<3>")
	)
	(segment
		(start 139.334748 -291.096192)
		(end 139.488672 -290.830762)
		(width 0.09525)
		(layer "In11.Cu")
		(net "M_L_CPU1_SB_DQS_DN<3>")
	)
	(segment
		(start 192.913254 -313.36234)
		(end 195.057268 -313.36234)
		(width 0.16002)
		(layer "In11.Cu")
		(net "M_L_CPU1_SB_DQS_DN<3>")
	)
	(segment
		(start 190.049658 -312.86704)
		(end 190.404242 -312.512456)
		(width 0.16002)
		(layer "In11.Cu")
		(net "M_L_CPU1_SB_DQS_DN<3>")
	)
	(segment
		(start 197.593712 -312.86704)
		(end 197.948296 -312.512456)
		(width 0.16002)
		(layer "In11.Cu")
		(net "M_L_CPU1_SB_DQS_DN<3>")
	)
	(segment
		(start 145.004282 -290.872418)
		(end 145.602706 -291.470842)
		(width 0.09525)
		(layer "In11.Cu")
		(net "M_L_CPU1_SB_DQS_DN<3>")
	)
	(segment
		(start 195.384928 -313.69)
		(end 196.359272 -313.69)
		(width 0.16002)
		(layer "In11.Cu")
		(net "M_L_CPU1_SB_DQS_DN<3>")
	)
	(segment
		(start 167.417496 -312.86704)
		(end 167.77208 -312.512456)
		(width 0.16002)
		(layer "In11.Cu")
		(net "M_L_CPU1_SB_DQS_DN<3>")
	)
	(segment
		(start 203.886816 -313.70524)
		(end 204.080618 -313.511438)
		(width 0.16002)
		(layer "In11.Cu")
		(net "M_L_CPU1_SB_DQS_DN<3>")
	)
	(segment
		(start 141.966188 -290.771072)
		(end 141.97457 -290.766246)
		(width 0.09525)
		(layer "In11.Cu")
		(net "M_L_CPU1_SB_DQS_DN<3>")
	)
	(segment
		(start 146.420078 -293.258748)
		(end 147.586954 -294.425624)
		(width 0.09525)
		(layer "In11.Cu")
		(net "M_L_CPU1_SB_DQS_DN<3>")
	)
	(segment
		(start 205.974188 -313.511438)
		(end 206.248 -313.78525)
		(width 0.16002)
		(layer "In11.Cu")
		(net "M_L_CPU1_SB_DQS_DN<3>")
	)
	(segment
		(start 187.513214 -313.36234)
		(end 187.840874 -313.69)
		(width 0.16002)
		(layer "In11.Cu")
		(net "M_L_CPU1_SB_DQS_DN<3>")
	)
	(segment
		(start 190.404242 -312.512456)
		(end 192.06337 -312.512456)
		(width 0.16002)
		(layer "In11.Cu")
		(net "M_L_CPU1_SB_DQS_DN<3>")
	)
	(segment
		(start 175.316134 -312.512456)
		(end 176.975262 -312.512456)
		(width 0.16002)
		(layer "In11.Cu")
		(net "M_L_CPU1_SB_DQS_DN<3>")
	)
	(segment
		(start 189.638178 -312.86704)
		(end 190.049658 -312.86704)
		(width 0.16002)
		(layer "In11.Cu")
		(net "M_L_CPU1_SB_DQS_DN<3>")
	)
	(segment
		(start 197.182232 -312.86704)
		(end 197.593712 -312.86704)
		(width 0.16002)
		(layer "In11.Cu")
		(net "M_L_CPU1_SB_DQS_DN<3>")
	)
	(segment
		(start 167.77208 -312.512456)
		(end 169.431208 -312.512456)
		(width 0.16002)
		(layer "In11.Cu")
		(net "M_L_CPU1_SB_DQS_DN<3>")
	)
	(segment
		(start 145.804636 -291.772848)
		(end 146.420078 -293.258748)
		(width 0.09525)
		(layer "In11.Cu")
		(net "M_L_CPU1_SB_DQS_DN<3>")
	)
	(segment
		(start 179.96916 -313.36234)
		(end 180.29682 -313.69)
		(width 0.16002)
		(layer "In11.Cu")
		(net "M_L_CPU1_SB_DQS_DN<3>")
	)
	(segment
		(start 139.488672 -290.830762)
		(end 139.58951 -290.804092)
		(width 0.09525)
		(layer "In11.Cu")
		(net "M_L_CPU1_SB_DQS_DN<3>")
	)
	(segment
		(start 169.431208 -312.512456)
		(end 170.281092 -313.36234)
		(width 0.16002)
		(layer "In11.Cu")
		(net "M_L_CPU1_SB_DQS_DN<3>")
	)
	(segment
		(start 181.271164 -313.69)
		(end 182.094124 -312.86704)
		(width 0.16002)
		(layer "In11.Cu")
		(net "M_L_CPU1_SB_DQS_DN<3>")
	)
	(segment
		(start 167.006016 -312.86704)
		(end 167.417496 -312.86704)
		(width 0.16002)
		(layer "In11.Cu")
		(net "M_L_CPU1_SB_DQS_DN<3>")
	)
	(segment
		(start 148.13661 -295.0591)
		(end 148.13661 -300.107096)
		(width 0.16002)
		(layer "In11.Cu")
		(net "M_L_CPU1_SB_DQS_DN<3>")
	)
	(segment
		(start 170.281092 -313.36234)
		(end 172.425106 -313.36234)
		(width 0.16002)
		(layer "In11.Cu")
		(net "M_L_CPU1_SB_DQS_DN<3>")
	)
	(segment
		(start 161.719514 -313.69)
		(end 166.183056 -313.69)
		(width 0.16002)
		(layer "In11.Cu")
		(net "M_L_CPU1_SB_DQS_DN<3>")
	)
	(segment
		(start 141.394942 -290.766246)
		(end 141.403324 -290.771072)
		(width 0.09525)
		(layer "In11.Cu")
		(net "M_L_CPU1_SB_DQS_DN<3>")
	)
	(segment
		(start 192.06337 -312.512456)
		(end 192.913254 -313.36234)
		(width 0.16002)
		(layer "In11.Cu")
		(net "M_L_CPU1_SB_DQS_DN<3>")
	)
	(segment
		(start 202.6031 -313.086496)
		(end 203.221844 -313.70524)
		(width 0.16002)
		(layer "In11.Cu")
		(net "M_L_CPU1_SB_DQS_DN<3>")
	)
	(segment
		(start 174.55007 -312.86704)
		(end 174.96155 -312.86704)
		(width 0.16002)
		(layer "In11.Cu")
		(net "M_L_CPU1_SB_DQS_DN<3>")
	)
	(arc
		(start 140.08608 -290.771072)
		(mid 140.269855 -290.7203)
		(end 140.454888 -290.766246)
		(width 0.09525)
		(layer "In11.Cu")
		(net "M_L_CPU1_SB_DQS_DN<3>")
	)
	(arc
		(start 143.846042 -290.771072)
		(mid 143.937008 -290.732919)
		(end 144.034764 -290.719764)
		(width 0.09525)
		(layer "In11.Cu")
		(net "M_L_CPU1_SB_DQS_DN<3>")
	)
	(arc
		(start 145.602706 -291.470842)
		(mid 145.718527 -291.61191)
		(end 145.804636 -291.772848)
		(width 0.09525)
		(layer "In11.Cu")
		(net "M_L_CPU1_SB_DQS_DN<3>")
	)
	(arc
		(start 141.97457 -290.766246)
		(mid 142.159602 -290.720332)
		(end 142.343378 -290.771072)
		(width 0.09525)
		(layer "In11.Cu")
		(net "M_L_CPU1_SB_DQS_DN<3>")
	)
	(arc
		(start 143.283178 -290.771072)
		(mid 143.56461 -290.846827)
		(end 143.846042 -290.771072)
		(width 0.09525)
		(layer "In11.Cu")
		(net "M_L_CPU1_SB_DQS_DN<3>")
	)
	(arc
		(start 144.635728 -290.719764)
		(mid 144.835186 -290.759439)
		(end 145.004282 -290.872418)
		(width 0.09525)
		(layer "In11.Cu")
		(net "M_L_CPU1_SB_DQS_DN<3>")
	)
	(arc
		(start 140.46327 -290.771072)
		(mid 140.744702 -290.846827)
		(end 141.026134 -290.771072)
		(width 0.09525)
		(layer "In11.Cu")
		(net "M_L_CPU1_SB_DQS_DN<3>")
	)
	(arc
		(start 139.58951 -290.804092)
		(mid 139.599632 -290.808127)
		(end 139.60983 -290.811966)
		(width 0.09525)
		(layer "In11.Cu")
		(net "M_L_CPU1_SB_DQS_DN<3>")
	)
	(arc
		(start 141.026134 -290.771072)
		(mid 141.209909 -290.7203)
		(end 141.394942 -290.766246)
		(width 0.09525)
		(layer "In11.Cu")
		(net "M_L_CPU1_SB_DQS_DN<3>")
	)
	(arc
		(start 139.60983 -290.811966)
		(mid 139.852542 -290.844849)
		(end 140.08608 -290.771072)
		(width 0.09525)
		(layer "In11.Cu")
		(net "M_L_CPU1_SB_DQS_DN<3>")
	)
	(arc
		(start 142.906242 -290.771072)
		(mid 143.09471 -290.720395)
		(end 143.283178 -290.771072)
		(width 0.09525)
		(layer "In11.Cu")
		(net "M_L_CPU1_SB_DQS_DN<3>")
	)
	(arc
		(start 142.343378 -290.771072)
		(mid 142.62481 -290.846827)
		(end 142.906242 -290.771072)
		(width 0.09525)
		(layer "In11.Cu")
		(net "M_L_CPU1_SB_DQS_DN<3>")
	)
	(arc
		(start 141.403324 -290.771072)
		(mid 141.684756 -290.846827)
		(end 141.966188 -290.771072)
		(width 0.09525)
		(layer "In11.Cu")
		(net "M_L_CPU1_SB_DQS_DN<3>")
	)
	(segment
		(start 138.867896 -285.970472)
		(end 139.334748 -286.23641)
		(width 0.12954)
		(layer "F.Cu")
		(net "M_L_CPU1_SB_DQS_DN<2>")
	)
	(segment
		(start 162.573462 -304.340006)
		(end 166.183056 -304.340006)
		(width 0.16002)
		(layer "In11.Cu")
		(net "M_L_CPU1_SB_DQS_DN<2>")
	)
	(segment
		(start 197.948296 -303.162462)
		(end 199.607424 -303.162462)
		(width 0.16002)
		(layer "In11.Cu")
		(net "M_L_CPU1_SB_DQS_DN<2>")
	)
	(segment
		(start 146.078194 -285.98749)
		(end 146.69389 -286.603186)
		(width 0.09525)
		(layer "In11.Cu")
		(net "M_L_CPU1_SB_DQS_DN<2>")
	)
	(segment
		(start 187.513214 -304.012346)
		(end 187.840874 -304.340006)
		(width 0.16002)
		(layer "In11.Cu")
		(net "M_L_CPU1_SB_DQS_DN<2>")
	)
	(segment
		(start 141.394942 -285.906464)
		(end 141.403324 -285.91129)
		(width 0.09525)
		(layer "In11.Cu")
		(net "M_L_CPU1_SB_DQS_DN<2>")
	)
	(segment
		(start 167.006016 -303.517046)
		(end 167.417496 -303.517046)
		(width 0.16002)
		(layer "In11.Cu")
		(net "M_L_CPU1_SB_DQS_DN<2>")
	)
	(segment
		(start 188.815218 -304.340006)
		(end 189.638178 -303.517046)
		(width 0.16002)
		(layer "In11.Cu")
		(net "M_L_CPU1_SB_DQS_DN<2>")
	)
	(segment
		(start 190.404242 -303.162462)
		(end 192.06337 -303.162462)
		(width 0.16002)
		(layer "In11.Cu")
		(net "M_L_CPU1_SB_DQS_DN<2>")
	)
	(segment
		(start 205.974188 -304.161444)
		(end 206.248 -304.435256)
		(width 0.16002)
		(layer "In11.Cu")
		(net "M_L_CPU1_SB_DQS_DN<2>")
	)
	(segment
		(start 185.3692 -304.012346)
		(end 187.513214 -304.012346)
		(width 0.16002)
		(layer "In11.Cu")
		(net "M_L_CPU1_SB_DQS_DN<2>")
	)
	(segment
		(start 189.638178 -303.517046)
		(end 190.049658 -303.517046)
		(width 0.16002)
		(layer "In11.Cu")
		(net "M_L_CPU1_SB_DQS_DN<2>")
	)
	(segment
		(start 195.384928 -304.340006)
		(end 196.359272 -304.340006)
		(width 0.16002)
		(layer "In11.Cu")
		(net "M_L_CPU1_SB_DQS_DN<2>")
	)
	(segment
		(start 182.860188 -303.162462)
		(end 184.519316 -303.162462)
		(width 0.16002)
		(layer "In11.Cu")
		(net "M_L_CPU1_SB_DQS_DN<2>")
	)
	(segment
		(start 187.840874 -304.340006)
		(end 188.815218 -304.340006)
		(width 0.16002)
		(layer "In11.Cu")
		(net "M_L_CPU1_SB_DQS_DN<2>")
	)
	(segment
		(start 170.281092 -304.012346)
		(end 172.425106 -304.012346)
		(width 0.16002)
		(layer "In11.Cu")
		(net "M_L_CPU1_SB_DQS_DN<2>")
	)
	(segment
		(start 195.057268 -304.012346)
		(end 195.384928 -304.340006)
		(width 0.16002)
		(layer "In11.Cu")
		(net "M_L_CPU1_SB_DQS_DN<2>")
	)
	(segment
		(start 175.316134 -303.162462)
		(end 176.975262 -303.162462)
		(width 0.16002)
		(layer "In11.Cu")
		(net "M_L_CPU1_SB_DQS_DN<2>")
	)
	(segment
		(start 139.488672 -285.97098)
		(end 139.58951 -285.94431)
		(width 0.09525)
		(layer "In11.Cu")
		(net "M_L_CPU1_SB_DQS_DN<2>")
	)
	(segment
		(start 140.454888 -285.906464)
		(end 140.46327 -285.91129)
		(width 0.09525)
		(layer "In11.Cu")
		(net "M_L_CPU1_SB_DQS_DN<2>")
	)
	(segment
		(start 202.823064 -303.956466)
		(end 203.221844 -304.355246)
		(width 0.16002)
		(layer "In11.Cu")
		(net "M_L_CPU1_SB_DQS_DN<2>")
	)
	(segment
		(start 192.913254 -304.012346)
		(end 195.057268 -304.012346)
		(width 0.16002)
		(layer "In11.Cu")
		(net "M_L_CPU1_SB_DQS_DN<2>")
	)
	(segment
		(start 174.96155 -303.517046)
		(end 175.316134 -303.162462)
		(width 0.16002)
		(layer "In11.Cu")
		(net "M_L_CPU1_SB_DQS_DN<2>")
	)
	(segment
		(start 200.401428 -303.956466)
		(end 202.823064 -303.956466)
		(width 0.16002)
		(layer "In11.Cu")
		(net "M_L_CPU1_SB_DQS_DN<2>")
	)
	(segment
		(start 147.26539 -286.603186)
		(end 147.48383 -286.821626)
		(width 0.09525)
		(layer "In11.Cu")
		(net "M_L_CPU1_SB_DQS_DN<2>")
	)
	(segment
		(start 174.55007 -303.517046)
		(end 174.96155 -303.517046)
		(width 0.16002)
		(layer "In11.Cu")
		(net "M_L_CPU1_SB_DQS_DN<2>")
	)
	(segment
		(start 141.966188 -285.91129)
		(end 141.97457 -285.906464)
		(width 0.09525)
		(layer "In11.Cu")
		(net "M_L_CPU1_SB_DQS_DN<2>")
	)
	(segment
		(start 139.334748 -286.23641)
		(end 139.488672 -285.97098)
		(width 0.09525)
		(layer "In11.Cu")
		(net "M_L_CPU1_SB_DQS_DN<2>")
	)
	(segment
		(start 184.519316 -303.162462)
		(end 185.3692 -304.012346)
		(width 0.16002)
		(layer "In11.Cu")
		(net "M_L_CPU1_SB_DQS_DN<2>")
	)
	(segment
		(start 177.825146 -304.012346)
		(end 179.96916 -304.012346)
		(width 0.16002)
		(layer "In11.Cu")
		(net "M_L_CPU1_SB_DQS_DN<2>")
	)
	(segment
		(start 179.96916 -304.012346)
		(end 180.29682 -304.340006)
		(width 0.16002)
		(layer "In11.Cu")
		(net "M_L_CPU1_SB_DQS_DN<2>")
	)
	(segment
		(start 147.836382 -286.821626)
		(end 147.895564 -286.880808)
		(width 0.09525)
		(layer "In11.Cu")
		(net "M_L_CPU1_SB_DQS_DN<2>")
	)
	(segment
		(start 147.919186 -286.880808)
		(end 148.044916 -286.880808)
		(width 0.16002)
		(layer "In11.Cu")
		(net "M_L_CPU1_SB_DQS_DN<2>")
	)
	(segment
		(start 196.359272 -304.340006)
		(end 197.182232 -303.517046)
		(width 0.16002)
		(layer "In11.Cu")
		(net "M_L_CPU1_SB_DQS_DN<2>")
	)
	(segment
		(start 181.271164 -304.340006)
		(end 182.094124 -303.517046)
		(width 0.16002)
		(layer "In11.Cu")
		(net "M_L_CPU1_SB_DQS_DN<2>")
	)
	(segment
		(start 146.69389 -286.603186)
		(end 147.26539 -286.603186)
		(width 0.09525)
		(layer "In11.Cu")
		(net "M_L_CPU1_SB_DQS_DN<2>")
	)
	(segment
		(start 167.417496 -303.517046)
		(end 167.77208 -303.162462)
		(width 0.16002)
		(layer "In11.Cu")
		(net "M_L_CPU1_SB_DQS_DN<2>")
	)
	(segment
		(start 147.48383 -286.821626)
		(end 147.836382 -286.821626)
		(width 0.09525)
		(layer "In11.Cu")
		(net "M_L_CPU1_SB_DQS_DN<2>")
	)
	(segment
		(start 192.06337 -303.162462)
		(end 192.913254 -304.012346)
		(width 0.16002)
		(layer "In11.Cu")
		(net "M_L_CPU1_SB_DQS_DN<2>")
	)
	(segment
		(start 172.752766 -304.340006)
		(end 173.72711 -304.340006)
		(width 0.16002)
		(layer "In11.Cu")
		(net "M_L_CPU1_SB_DQS_DN<2>")
	)
	(segment
		(start 169.431208 -303.162462)
		(end 170.281092 -304.012346)
		(width 0.16002)
		(layer "In11.Cu")
		(net "M_L_CPU1_SB_DQS_DN<2>")
	)
	(segment
		(start 197.593712 -303.517046)
		(end 197.948296 -303.162462)
		(width 0.16002)
		(layer "In11.Cu")
		(net "M_L_CPU1_SB_DQS_DN<2>")
	)
	(segment
		(start 145.444718 -285.98749)
		(end 146.078194 -285.98749)
		(width 0.09525)
		(layer "In11.Cu")
		(net "M_L_CPU1_SB_DQS_DN<2>")
	)
	(segment
		(start 173.72711 -304.340006)
		(end 174.55007 -303.517046)
		(width 0.16002)
		(layer "In11.Cu")
		(net "M_L_CPU1_SB_DQS_DN<2>")
	)
	(segment
		(start 144.78508 -285.91129)
		(end 144.797018 -285.904432)
		(width 0.09525)
		(layer "In11.Cu")
		(net "M_L_CPU1_SB_DQS_DN<2>")
	)
	(segment
		(start 199.607424 -303.162462)
		(end 200.401428 -303.956466)
		(width 0.16002)
		(layer "In11.Cu")
		(net "M_L_CPU1_SB_DQS_DN<2>")
	)
	(segment
		(start 190.049658 -303.517046)
		(end 190.404242 -303.162462)
		(width 0.16002)
		(layer "In11.Cu")
		(net "M_L_CPU1_SB_DQS_DN<2>")
	)
	(segment
		(start 153.76017 -292.596062)
		(end 153.76017 -295.526714)
		(width 0.16002)
		(layer "In11.Cu")
		(net "M_L_CPU1_SB_DQS_DN<2>")
	)
	(segment
		(start 167.77208 -303.162462)
		(end 169.431208 -303.162462)
		(width 0.16002)
		(layer "In11.Cu")
		(net "M_L_CPU1_SB_DQS_DN<2>")
	)
	(segment
		(start 172.425106 -304.012346)
		(end 172.752766 -304.340006)
		(width 0.16002)
		(layer "In11.Cu")
		(net "M_L_CPU1_SB_DQS_DN<2>")
	)
	(segment
		(start 182.094124 -303.517046)
		(end 182.505604 -303.517046)
		(width 0.16002)
		(layer "In11.Cu")
		(net "M_L_CPU1_SB_DQS_DN<2>")
	)
	(segment
		(start 176.975262 -303.162462)
		(end 177.825146 -304.012346)
		(width 0.16002)
		(layer "In11.Cu")
		(net "M_L_CPU1_SB_DQS_DN<2>")
	)
	(segment
		(start 153.76017 -295.526714)
		(end 162.573462 -304.340006)
		(width 0.16002)
		(layer "In11.Cu")
		(net "M_L_CPU1_SB_DQS_DN<2>")
	)
	(segment
		(start 204.080618 -304.161444)
		(end 205.974188 -304.161444)
		(width 0.16002)
		(layer "In11.Cu")
		(net "M_L_CPU1_SB_DQS_DN<2>")
	)
	(segment
		(start 166.183056 -304.340006)
		(end 167.006016 -303.517046)
		(width 0.16002)
		(layer "In11.Cu")
		(net "M_L_CPU1_SB_DQS_DN<2>")
	)
	(segment
		(start 203.886816 -304.355246)
		(end 204.080618 -304.161444)
		(width 0.16002)
		(layer "In11.Cu")
		(net "M_L_CPU1_SB_DQS_DN<2>")
	)
	(segment
		(start 203.221844 -304.355246)
		(end 203.886816 -304.355246)
		(width 0.16002)
		(layer "In11.Cu")
		(net "M_L_CPU1_SB_DQS_DN<2>")
	)
	(segment
		(start 147.895564 -286.880808)
		(end 147.919186 -286.880808)
		(width 0.09525)
		(layer "In11.Cu")
		(net "M_L_CPU1_SB_DQS_DN<2>")
	)
	(segment
		(start 182.505604 -303.517046)
		(end 182.860188 -303.162462)
		(width 0.16002)
		(layer "In11.Cu")
		(net "M_L_CPU1_SB_DQS_DN<2>")
	)
	(segment
		(start 144.21104 -285.904432)
		(end 144.222978 -285.91129)
		(width 0.09525)
		(layer "In11.Cu")
		(net "M_L_CPU1_SB_DQS_DN<2>")
	)
	(segment
		(start 197.182232 -303.517046)
		(end 197.593712 -303.517046)
		(width 0.16002)
		(layer "In11.Cu")
		(net "M_L_CPU1_SB_DQS_DN<2>")
	)
	(segment
		(start 180.29682 -304.340006)
		(end 181.271164 -304.340006)
		(width 0.16002)
		(layer "In11.Cu")
		(net "M_L_CPU1_SB_DQS_DN<2>")
	)
	(segment
		(start 148.044916 -286.880808)
		(end 153.76017 -292.596062)
		(width 0.16002)
		(layer "In11.Cu")
		(net "M_L_CPU1_SB_DQS_DN<2>")
	)
	(segment
		(start 144.222978 -285.91129)
		(end 144.241012 -285.921704)
		(width 0.09525)
		(layer "In11.Cu")
		(net "M_L_CPU1_SB_DQS_DN<2>")
	)
	(arc
		(start 140.46327 -285.91129)
		(mid 140.744702 -285.987045)
		(end 141.026134 -285.91129)
		(width 0.09525)
		(layer "In11.Cu")
		(net "M_L_CPU1_SB_DQS_DN<2>")
	)
	(arc
		(start 142.906242 -285.91129)
		(mid 143.09471 -285.860613)
		(end 143.283178 -285.91129)
		(width 0.09525)
		(layer "In11.Cu")
		(net "M_L_CPU1_SB_DQS_DN<2>")
	)
	(arc
		(start 145.162524 -285.91129)
		(mid 145.298576 -285.968059)
		(end 145.444718 -285.98749)
		(width 0.09525)
		(layer "In11.Cu")
		(net "M_L_CPU1_SB_DQS_DN<2>")
	)
	(arc
		(start 142.343378 -285.91129)
		(mid 142.62481 -285.987045)
		(end 142.906242 -285.91129)
		(width 0.09525)
		(layer "In11.Cu")
		(net "M_L_CPU1_SB_DQS_DN<2>")
	)
	(arc
		(start 140.08608 -285.91129)
		(mid 140.269855 -285.860518)
		(end 140.454888 -285.906464)
		(width 0.09525)
		(layer "In11.Cu")
		(net "M_L_CPU1_SB_DQS_DN<2>")
	)
	(arc
		(start 144.797018 -285.904432)
		(mid 144.980653 -285.860482)
		(end 145.162524 -285.91129)
		(width 0.09525)
		(layer "In11.Cu")
		(net "M_L_CPU1_SB_DQS_DN<2>")
	)
	(arc
		(start 139.60983 -285.952184)
		(mid 139.852542 -285.985067)
		(end 140.08608 -285.91129)
		(width 0.09525)
		(layer "In11.Cu")
		(net "M_L_CPU1_SB_DQS_DN<2>")
	)
	(arc
		(start 141.403324 -285.91129)
		(mid 141.684756 -285.987045)
		(end 141.966188 -285.91129)
		(width 0.09525)
		(layer "In11.Cu")
		(net "M_L_CPU1_SB_DQS_DN<2>")
	)
	(arc
		(start 139.58951 -285.94431)
		(mid 139.599632 -285.948345)
		(end 139.60983 -285.952184)
		(width 0.09525)
		(layer "In11.Cu")
		(net "M_L_CPU1_SB_DQS_DN<2>")
	)
	(arc
		(start 141.97457 -285.906464)
		(mid 142.159602 -285.86055)
		(end 142.343378 -285.91129)
		(width 0.09525)
		(layer "In11.Cu")
		(net "M_L_CPU1_SB_DQS_DN<2>")
	)
	(arc
		(start 144.241012 -285.921704)
		(mid 144.514392 -285.986925)
		(end 144.78508 -285.91129)
		(width 0.09525)
		(layer "In11.Cu")
		(net "M_L_CPU1_SB_DQS_DN<2>")
	)
	(arc
		(start 143.283178 -285.91129)
		(mid 143.56461 -285.987045)
		(end 143.846042 -285.91129)
		(width 0.09525)
		(layer "In11.Cu")
		(net "M_L_CPU1_SB_DQS_DN<2>")
	)
	(arc
		(start 141.026134 -285.91129)
		(mid 141.209909 -285.860518)
		(end 141.394942 -285.906464)
		(width 0.09525)
		(layer "In11.Cu")
		(net "M_L_CPU1_SB_DQS_DN<2>")
	)
	(arc
		(start 143.846042 -285.91129)
		(mid 144.027658 -285.860553)
		(end 144.21104 -285.904432)
		(width 0.09525)
		(layer "In11.Cu")
		(net "M_L_CPU1_SB_DQS_DN<2>")
	)
	(segment
		(start 138.867896 -281.110436)
		(end 139.334748 -281.376374)
		(width 0.12954)
		(layer "F.Cu")
		(net "M_L_CPU1_SB_DQS_DN<1>")
	)
	(segment
		(start 172.425106 -294.662352)
		(end 172.752766 -294.990012)
		(width 0.16002)
		(layer "In11.Cu")
		(net "M_L_CPU1_SB_DQS_DN<1>")
	)
	(segment
		(start 202.6031 -294.386508)
		(end 203.221844 -295.005252)
		(width 0.16002)
		(layer "In11.Cu")
		(net "M_L_CPU1_SB_DQS_DN<1>")
	)
	(segment
		(start 203.221844 -295.005252)
		(end 203.886816 -295.005252)
		(width 0.16002)
		(layer "In11.Cu")
		(net "M_L_CPU1_SB_DQS_DN<1>")
	)
	(segment
		(start 144.21104 -281.044396)
		(end 144.222978 -281.051254)
		(width 0.09525)
		(layer "In11.Cu")
		(net "M_L_CPU1_SB_DQS_DN<1>")
	)
	(segment
		(start 187.513214 -294.662352)
		(end 187.840874 -294.990012)
		(width 0.16002)
		(layer "In11.Cu")
		(net "M_L_CPU1_SB_DQS_DN<1>")
	)
	(segment
		(start 192.06337 -293.812468)
		(end 192.913254 -294.662352)
		(width 0.16002)
		(layer "In11.Cu")
		(net "M_L_CPU1_SB_DQS_DN<1>")
	)
	(segment
		(start 185.3692 -294.662352)
		(end 187.513214 -294.662352)
		(width 0.16002)
		(layer "In11.Cu")
		(net "M_L_CPU1_SB_DQS_DN<1>")
	)
	(segment
		(start 167.77208 -293.812468)
		(end 169.431208 -293.812468)
		(width 0.16002)
		(layer "In11.Cu")
		(net "M_L_CPU1_SB_DQS_DN<1>")
	)
	(segment
		(start 196.359272 -294.990012)
		(end 197.182232 -294.167052)
		(width 0.16002)
		(layer "In11.Cu")
		(net "M_L_CPU1_SB_DQS_DN<1>")
	)
	(segment
		(start 141.394942 -281.046428)
		(end 141.403324 -281.051254)
		(width 0.09525)
		(layer "In11.Cu")
		(net "M_L_CPU1_SB_DQS_DN<1>")
	)
	(segment
		(start 182.094124 -294.167052)
		(end 182.505604 -294.167052)
		(width 0.16002)
		(layer "In11.Cu")
		(net "M_L_CPU1_SB_DQS_DN<1>")
	)
	(segment
		(start 170.281092 -294.662352)
		(end 172.425106 -294.662352)
		(width 0.16002)
		(layer "In11.Cu")
		(net "M_L_CPU1_SB_DQS_DN<1>")
	)
	(segment
		(start 145.444718 -281.127454)
		(end 145.932906 -281.127454)
		(width 0.09525)
		(layer "In11.Cu")
		(net "M_L_CPU1_SB_DQS_DN<1>")
	)
	(segment
		(start 147.633944 -281.170126)
		(end 147.836636 -281.170126)
		(width 0.09525)
		(layer "In11.Cu")
		(net "M_L_CPU1_SB_DQS_DN<1>")
	)
	(segment
		(start 147.895564 -281.229054)
		(end 147.919186 -281.229054)
		(width 0.09525)
		(layer "In11.Cu")
		(net "M_L_CPU1_SB_DQS_DN<1>")
	)
	(segment
		(start 167.417496 -294.167052)
		(end 167.77208 -293.812468)
		(width 0.16002)
		(layer "In11.Cu")
		(net "M_L_CPU1_SB_DQS_DN<1>")
	)
	(segment
		(start 192.913254 -294.662352)
		(end 195.057268 -294.662352)
		(width 0.16002)
		(layer "In11.Cu")
		(net "M_L_CPU1_SB_DQS_DN<1>")
	)
	(segment
		(start 184.519316 -293.812468)
		(end 185.3692 -294.662352)
		(width 0.16002)
		(layer "In11.Cu")
		(net "M_L_CPU1_SB_DQS_DN<1>")
	)
	(segment
		(start 197.948296 -293.812468)
		(end 199.607424 -293.812468)
		(width 0.16002)
		(layer "In11.Cu")
		(net "M_L_CPU1_SB_DQS_DN<1>")
	)
	(segment
		(start 197.182232 -294.167052)
		(end 197.593712 -294.167052)
		(width 0.16002)
		(layer "In11.Cu")
		(net "M_L_CPU1_SB_DQS_DN<1>")
	)
	(segment
		(start 187.840874 -294.990012)
		(end 188.815218 -294.990012)
		(width 0.16002)
		(layer "In11.Cu")
		(net "M_L_CPU1_SB_DQS_DN<1>")
	)
	(segment
		(start 172.752766 -294.990012)
		(end 173.72711 -294.990012)
		(width 0.16002)
		(layer "In11.Cu")
		(net "M_L_CPU1_SB_DQS_DN<1>")
	)
	(segment
		(start 181.271164 -294.990012)
		(end 182.094124 -294.167052)
		(width 0.16002)
		(layer "In11.Cu")
		(net "M_L_CPU1_SB_DQS_DN<1>")
	)
	(segment
		(start 195.057268 -294.662352)
		(end 195.384928 -294.990012)
		(width 0.16002)
		(layer "In11.Cu")
		(net "M_L_CPU1_SB_DQS_DN<1>")
	)
	(segment
		(start 174.55007 -294.167052)
		(end 174.96155 -294.167052)
		(width 0.16002)
		(layer "In11.Cu")
		(net "M_L_CPU1_SB_DQS_DN<1>")
	)
	(segment
		(start 182.860188 -293.812468)
		(end 184.519316 -293.812468)
		(width 0.16002)
		(layer "In11.Cu")
		(net "M_L_CPU1_SB_DQS_DN<1>")
	)
	(segment
		(start 147.836636 -281.170126)
		(end 147.895564 -281.229054)
		(width 0.09525)
		(layer "In11.Cu")
		(net "M_L_CPU1_SB_DQS_DN<1>")
	)
	(segment
		(start 150.319994 -281.229054)
		(end 164.080952 -294.990012)
		(width 0.16002)
		(layer "In11.Cu")
		(net "M_L_CPU1_SB_DQS_DN<1>")
	)
	(segment
		(start 182.505604 -294.167052)
		(end 182.860188 -293.812468)
		(width 0.16002)
		(layer "In11.Cu")
		(net "M_L_CPU1_SB_DQS_DN<1>")
	)
	(segment
		(start 164.080952 -294.990012)
		(end 166.183056 -294.990012)
		(width 0.16002)
		(layer "In11.Cu")
		(net "M_L_CPU1_SB_DQS_DN<1>")
	)
	(segment
		(start 145.932906 -281.127454)
		(end 146.341084 -280.719276)
		(width 0.09525)
		(layer "In11.Cu")
		(net "M_L_CPU1_SB_DQS_DN<1>")
	)
	(segment
		(start 174.96155 -294.167052)
		(end 175.316134 -293.812468)
		(width 0.16002)
		(layer "In11.Cu")
		(net "M_L_CPU1_SB_DQS_DN<1>")
	)
	(segment
		(start 141.966188 -281.051254)
		(end 141.97457 -281.046428)
		(width 0.09525)
		(layer "In11.Cu")
		(net "M_L_CPU1_SB_DQS_DN<1>")
	)
	(segment
		(start 189.638178 -294.167052)
		(end 190.049658 -294.167052)
		(width 0.16002)
		(layer "In11.Cu")
		(net "M_L_CPU1_SB_DQS_DN<1>")
	)
	(segment
		(start 173.72711 -294.990012)
		(end 174.55007 -294.167052)
		(width 0.16002)
		(layer "In11.Cu")
		(net "M_L_CPU1_SB_DQS_DN<1>")
	)
	(segment
		(start 199.607424 -293.812468)
		(end 200.181464 -294.386508)
		(width 0.16002)
		(layer "In11.Cu")
		(net "M_L_CPU1_SB_DQS_DN<1>")
	)
	(segment
		(start 203.886816 -295.005252)
		(end 204.080618 -294.81145)
		(width 0.16002)
		(layer "In11.Cu")
		(net "M_L_CPU1_SB_DQS_DN<1>")
	)
	(segment
		(start 180.29682 -294.990012)
		(end 181.271164 -294.990012)
		(width 0.16002)
		(layer "In11.Cu")
		(net "M_L_CPU1_SB_DQS_DN<1>")
	)
	(segment
		(start 147.919186 -281.229054)
		(end 150.319994 -281.229054)
		(width 0.16002)
		(layer "In11.Cu")
		(net "M_L_CPU1_SB_DQS_DN<1>")
	)
	(segment
		(start 166.183056 -294.990012)
		(end 167.006016 -294.167052)
		(width 0.16002)
		(layer "In11.Cu")
		(net "M_L_CPU1_SB_DQS_DN<1>")
	)
	(segment
		(start 190.404242 -293.812468)
		(end 192.06337 -293.812468)
		(width 0.16002)
		(layer "In11.Cu")
		(net "M_L_CPU1_SB_DQS_DN<1>")
	)
	(segment
		(start 205.974188 -294.81145)
		(end 206.248 -295.085262)
		(width 0.16002)
		(layer "In11.Cu")
		(net "M_L_CPU1_SB_DQS_DN<1>")
	)
	(segment
		(start 144.78508 -281.051254)
		(end 144.797018 -281.044396)
		(width 0.09525)
		(layer "In11.Cu")
		(net "M_L_CPU1_SB_DQS_DN<1>")
	)
	(segment
		(start 179.96916 -294.662352)
		(end 180.29682 -294.990012)
		(width 0.16002)
		(layer "In11.Cu")
		(net "M_L_CPU1_SB_DQS_DN<1>")
	)
	(segment
		(start 140.454888 -281.046428)
		(end 140.46327 -281.051254)
		(width 0.09525)
		(layer "In11.Cu")
		(net "M_L_CPU1_SB_DQS_DN<1>")
	)
	(segment
		(start 204.080618 -294.81145)
		(end 205.974188 -294.81145)
		(width 0.16002)
		(layer "In11.Cu")
		(net "M_L_CPU1_SB_DQS_DN<1>")
	)
	(segment
		(start 167.006016 -294.167052)
		(end 167.417496 -294.167052)
		(width 0.16002)
		(layer "In11.Cu")
		(net "M_L_CPU1_SB_DQS_DN<1>")
	)
	(segment
		(start 177.825146 -294.662352)
		(end 179.96916 -294.662352)
		(width 0.16002)
		(layer "In11.Cu")
		(net "M_L_CPU1_SB_DQS_DN<1>")
	)
	(segment
		(start 144.222978 -281.051254)
		(end 144.241012 -281.061668)
		(width 0.09525)
		(layer "In11.Cu")
		(net "M_L_CPU1_SB_DQS_DN<1>")
	)
	(segment
		(start 197.593712 -294.167052)
		(end 197.948296 -293.812468)
		(width 0.16002)
		(layer "In11.Cu")
		(net "M_L_CPU1_SB_DQS_DN<1>")
	)
	(segment
		(start 190.049658 -294.167052)
		(end 190.404242 -293.812468)
		(width 0.16002)
		(layer "In11.Cu")
		(net "M_L_CPU1_SB_DQS_DN<1>")
	)
	(segment
		(start 139.488672 -281.110944)
		(end 139.58951 -281.084274)
		(width 0.09525)
		(layer "In11.Cu")
		(net "M_L_CPU1_SB_DQS_DN<1>")
	)
	(segment
		(start 139.334748 -281.376374)
		(end 139.488672 -281.110944)
		(width 0.09525)
		(layer "In11.Cu")
		(net "M_L_CPU1_SB_DQS_DN<1>")
	)
	(segment
		(start 188.815218 -294.990012)
		(end 189.638178 -294.167052)
		(width 0.16002)
		(layer "In11.Cu")
		(net "M_L_CPU1_SB_DQS_DN<1>")
	)
	(segment
		(start 176.975262 -293.812468)
		(end 177.825146 -294.662352)
		(width 0.16002)
		(layer "In11.Cu")
		(net "M_L_CPU1_SB_DQS_DN<1>")
	)
	(segment
		(start 200.181464 -294.386508)
		(end 202.6031 -294.386508)
		(width 0.16002)
		(layer "In11.Cu")
		(net "M_L_CPU1_SB_DQS_DN<1>")
	)
	(segment
		(start 175.316134 -293.812468)
		(end 176.975262 -293.812468)
		(width 0.16002)
		(layer "In11.Cu")
		(net "M_L_CPU1_SB_DQS_DN<1>")
	)
	(segment
		(start 169.431208 -293.812468)
		(end 170.281092 -294.662352)
		(width 0.16002)
		(layer "In11.Cu")
		(net "M_L_CPU1_SB_DQS_DN<1>")
	)
	(segment
		(start 146.341084 -280.719276)
		(end 147.183094 -280.719276)
		(width 0.09525)
		(layer "In11.Cu")
		(net "M_L_CPU1_SB_DQS_DN<1>")
	)
	(segment
		(start 195.384928 -294.990012)
		(end 196.359272 -294.990012)
		(width 0.16002)
		(layer "In11.Cu")
		(net "M_L_CPU1_SB_DQS_DN<1>")
	)
	(segment
		(start 147.183094 -280.719276)
		(end 147.633944 -281.170126)
		(width 0.09525)
		(layer "In11.Cu")
		(net "M_L_CPU1_SB_DQS_DN<1>")
	)
	(arc
		(start 142.906242 -281.051254)
		(mid 143.09471 -281.000577)
		(end 143.283178 -281.051254)
		(width 0.09525)
		(layer "In11.Cu")
		(net "M_L_CPU1_SB_DQS_DN<1>")
	)
	(arc
		(start 144.241012 -281.061668)
		(mid 144.514392 -281.126889)
		(end 144.78508 -281.051254)
		(width 0.09525)
		(layer "In11.Cu")
		(net "M_L_CPU1_SB_DQS_DN<1>")
	)
	(arc
		(start 139.60983 -281.092148)
		(mid 139.852542 -281.125031)
		(end 140.08608 -281.051254)
		(width 0.09525)
		(layer "In11.Cu")
		(net "M_L_CPU1_SB_DQS_DN<1>")
	)
	(arc
		(start 143.846042 -281.051254)
		(mid 144.027658 -281.000517)
		(end 144.21104 -281.044396)
		(width 0.09525)
		(layer "In11.Cu")
		(net "M_L_CPU1_SB_DQS_DN<1>")
	)
	(arc
		(start 142.343378 -281.051254)
		(mid 142.62481 -281.127009)
		(end 142.906242 -281.051254)
		(width 0.09525)
		(layer "In11.Cu")
		(net "M_L_CPU1_SB_DQS_DN<1>")
	)
	(arc
		(start 144.797018 -281.044396)
		(mid 144.980653 -281.000446)
		(end 145.162524 -281.051254)
		(width 0.09525)
		(layer "In11.Cu")
		(net "M_L_CPU1_SB_DQS_DN<1>")
	)
	(arc
		(start 145.162524 -281.051254)
		(mid 145.298576 -281.108023)
		(end 145.444718 -281.127454)
		(width 0.09525)
		(layer "In11.Cu")
		(net "M_L_CPU1_SB_DQS_DN<1>")
	)
	(arc
		(start 140.08608 -281.051254)
		(mid 140.269855 -281.000482)
		(end 140.454888 -281.046428)
		(width 0.09525)
		(layer "In11.Cu")
		(net "M_L_CPU1_SB_DQS_DN<1>")
	)
	(arc
		(start 141.97457 -281.046428)
		(mid 142.159602 -281.000514)
		(end 142.343378 -281.051254)
		(width 0.09525)
		(layer "In11.Cu")
		(net "M_L_CPU1_SB_DQS_DN<1>")
	)
	(arc
		(start 139.58951 -281.084274)
		(mid 139.599632 -281.088309)
		(end 139.60983 -281.092148)
		(width 0.09525)
		(layer "In11.Cu")
		(net "M_L_CPU1_SB_DQS_DN<1>")
	)
	(arc
		(start 143.283178 -281.051254)
		(mid 143.56461 -281.127009)
		(end 143.846042 -281.051254)
		(width 0.09525)
		(layer "In11.Cu")
		(net "M_L_CPU1_SB_DQS_DN<1>")
	)
	(arc
		(start 141.403324 -281.051254)
		(mid 141.684756 -281.127009)
		(end 141.966188 -281.051254)
		(width 0.09525)
		(layer "In11.Cu")
		(net "M_L_CPU1_SB_DQS_DN<1>")
	)
	(arc
		(start 140.46327 -281.051254)
		(mid 140.744702 -281.127009)
		(end 141.026134 -281.051254)
		(width 0.09525)
		(layer "In11.Cu")
		(net "M_L_CPU1_SB_DQS_DN<1>")
	)
	(arc
		(start 141.026134 -281.051254)
		(mid 141.209909 -281.000482)
		(end 141.394942 -281.046428)
		(width 0.09525)
		(layer "In11.Cu")
		(net "M_L_CPU1_SB_DQS_DN<1>")
	)
	(segment
		(start 138.867896 -276.2504)
		(end 139.334748 -276.516338)
		(width 0.12954)
		(layer "F.Cu")
		(net "M_L_CPU1_SB_DQS_DN<0>")
	)
	(segment
		(start 181.271164 -285.640018)
		(end 182.094124 -284.817058)
		(width 0.16002)
		(layer "In11.Cu")
		(net "M_L_CPU1_SB_DQS_DN<0>")
	)
	(segment
		(start 145.840958 -276.102572)
		(end 146.682714 -275.260816)
		(width 0.09525)
		(layer "In11.Cu")
		(net "M_L_CPU1_SB_DQS_DN<0>")
	)
	(segment
		(start 187.513214 -285.312358)
		(end 187.840874 -285.640018)
		(width 0.16002)
		(layer "In11.Cu")
		(net "M_L_CPU1_SB_DQS_DN<0>")
	)
	(segment
		(start 144.78508 -276.191218)
		(end 144.797018 -276.18436)
		(width 0.09525)
		(layer "In11.Cu")
		(net "M_L_CPU1_SB_DQS_DN<0>")
	)
	(segment
		(start 200.181464 -285.036514)
		(end 202.6031 -285.036514)
		(width 0.16002)
		(layer "In11.Cu")
		(net "M_L_CPU1_SB_DQS_DN<0>")
	)
	(segment
		(start 204.080618 -285.461456)
		(end 205.974188 -285.461456)
		(width 0.16002)
		(layer "In11.Cu")
		(net "M_L_CPU1_SB_DQS_DN<0>")
	)
	(segment
		(start 170.64228 -285.312358)
		(end 172.425106 -285.312358)
		(width 0.16002)
		(layer "In11.Cu")
		(net "M_L_CPU1_SB_DQS_DN<0>")
	)
	(segment
		(start 175.316134 -284.462474)
		(end 176.975262 -284.462474)
		(width 0.16002)
		(layer "In11.Cu")
		(net "M_L_CPU1_SB_DQS_DN<0>")
	)
	(segment
		(start 162.58032 -285.066994)
		(end 164.921184 -285.066994)
		(width 0.16002)
		(layer "In11.Cu")
		(net "M_L_CPU1_SB_DQS_DN<0>")
	)
	(segment
		(start 165.494208 -285.640018)
		(end 166.183056 -285.640018)
		(width 0.16002)
		(layer "In11.Cu")
		(net "M_L_CPU1_SB_DQS_DN<0>")
	)
	(segment
		(start 144.222978 -276.191218)
		(end 144.241012 -276.201632)
		(width 0.09525)
		(layer "In11.Cu")
		(net "M_L_CPU1_SB_DQS_DN<0>")
	)
	(segment
		(start 195.384928 -285.640018)
		(end 196.359272 -285.640018)
		(width 0.16002)
		(layer "In11.Cu")
		(net "M_L_CPU1_SB_DQS_DN<0>")
	)
	(segment
		(start 147.349464 -275.260816)
		(end 147.469352 -275.140928)
		(width 0.09525)
		(layer "In11.Cu")
		(net "M_L_CPU1_SB_DQS_DN<0>")
	)
	(segment
		(start 192.06337 -284.462474)
		(end 192.913254 -285.312358)
		(width 0.16002)
		(layer "In11.Cu")
		(net "M_L_CPU1_SB_DQS_DN<0>")
	)
	(segment
		(start 205.974188 -285.461456)
		(end 206.248 -285.735268)
		(width 0.16002)
		(layer "In11.Cu")
		(net "M_L_CPU1_SB_DQS_DN<0>")
	)
	(segment
		(start 167.417496 -284.817058)
		(end 167.77208 -284.462474)
		(width 0.16002)
		(layer "In11.Cu")
		(net "M_L_CPU1_SB_DQS_DN<0>")
	)
	(segment
		(start 167.77208 -284.462474)
		(end 169.792396 -284.462474)
		(width 0.16002)
		(layer "In11.Cu")
		(net "M_L_CPU1_SB_DQS_DN<0>")
	)
	(segment
		(start 177.825146 -285.312358)
		(end 179.96916 -285.312358)
		(width 0.16002)
		(layer "In11.Cu")
		(net "M_L_CPU1_SB_DQS_DN<0>")
	)
	(segment
		(start 190.049658 -284.817058)
		(end 190.404242 -284.462474)
		(width 0.16002)
		(layer "In11.Cu")
		(net "M_L_CPU1_SB_DQS_DN<0>")
	)
	(segment
		(start 144.21104 -276.18436)
		(end 144.222978 -276.191218)
		(width 0.09525)
		(layer "In11.Cu")
		(net "M_L_CPU1_SB_DQS_DN<0>")
	)
	(segment
		(start 197.182232 -284.817058)
		(end 197.593712 -284.817058)
		(width 0.16002)
		(layer "In11.Cu")
		(net "M_L_CPU1_SB_DQS_DN<0>")
	)
	(segment
		(start 180.29682 -285.640018)
		(end 181.271164 -285.640018)
		(width 0.16002)
		(layer "In11.Cu")
		(net "M_L_CPU1_SB_DQS_DN<0>")
	)
	(segment
		(start 182.860188 -284.462474)
		(end 184.519316 -284.462474)
		(width 0.16002)
		(layer "In11.Cu")
		(net "M_L_CPU1_SB_DQS_DN<0>")
	)
	(segment
		(start 189.638178 -284.817058)
		(end 190.049658 -284.817058)
		(width 0.16002)
		(layer "In11.Cu")
		(net "M_L_CPU1_SB_DQS_DN<0>")
	)
	(segment
		(start 199.607424 -284.462474)
		(end 200.181464 -285.036514)
		(width 0.16002)
		(layer "In11.Cu")
		(net "M_L_CPU1_SB_DQS_DN<0>")
	)
	(segment
		(start 196.359272 -285.640018)
		(end 197.182232 -284.817058)
		(width 0.16002)
		(layer "In11.Cu")
		(net "M_L_CPU1_SB_DQS_DN<0>")
	)
	(segment
		(start 172.425106 -285.312358)
		(end 172.752766 -285.640018)
		(width 0.16002)
		(layer "In11.Cu")
		(net "M_L_CPU1_SB_DQS_DN<0>")
	)
	(segment
		(start 169.792396 -284.462474)
		(end 170.64228 -285.312358)
		(width 0.16002)
		(layer "In11.Cu")
		(net "M_L_CPU1_SB_DQS_DN<0>")
	)
	(segment
		(start 173.72711 -285.640018)
		(end 174.55007 -284.817058)
		(width 0.16002)
		(layer "In11.Cu")
		(net "M_L_CPU1_SB_DQS_DN<0>")
	)
	(segment
		(start 140.454888 -276.186392)
		(end 140.46327 -276.191218)
		(width 0.09525)
		(layer "In11.Cu")
		(net "M_L_CPU1_SB_DQS_DN<0>")
	)
	(segment
		(start 174.55007 -284.817058)
		(end 174.96155 -284.817058)
		(width 0.16002)
		(layer "In11.Cu")
		(net "M_L_CPU1_SB_DQS_DN<0>")
	)
	(segment
		(start 202.6031 -285.036514)
		(end 203.221844 -285.655258)
		(width 0.16002)
		(layer "In11.Cu")
		(net "M_L_CPU1_SB_DQS_DN<0>")
	)
	(segment
		(start 195.057268 -285.312358)
		(end 195.384928 -285.640018)
		(width 0.16002)
		(layer "In11.Cu")
		(net "M_L_CPU1_SB_DQS_DN<0>")
	)
	(segment
		(start 164.921184 -285.066994)
		(end 165.494208 -285.640018)
		(width 0.16002)
		(layer "In11.Cu")
		(net "M_L_CPU1_SB_DQS_DN<0>")
	)
	(segment
		(start 197.593712 -284.817058)
		(end 197.948296 -284.462474)
		(width 0.16002)
		(layer "In11.Cu")
		(net "M_L_CPU1_SB_DQS_DN<0>")
	)
	(segment
		(start 192.913254 -285.312358)
		(end 195.057268 -285.312358)
		(width 0.16002)
		(layer "In11.Cu")
		(net "M_L_CPU1_SB_DQS_DN<0>")
	)
	(segment
		(start 174.96155 -284.817058)
		(end 175.316134 -284.462474)
		(width 0.16002)
		(layer "In11.Cu")
		(net "M_L_CPU1_SB_DQS_DN<0>")
	)
	(segment
		(start 152.713436 -275.20011)
		(end 162.58032 -285.066994)
		(width 0.16002)
		(layer "In11.Cu")
		(net "M_L_CPU1_SB_DQS_DN<0>")
	)
	(segment
		(start 203.221844 -285.655258)
		(end 203.886816 -285.655258)
		(width 0.16002)
		(layer "In11.Cu")
		(net "M_L_CPU1_SB_DQS_DN<0>")
	)
	(segment
		(start 139.488672 -276.250908)
		(end 139.58951 -276.224238)
		(width 0.09525)
		(layer "In11.Cu")
		(net "M_L_CPU1_SB_DQS_DN<0>")
	)
	(segment
		(start 167.006016 -284.817058)
		(end 167.417496 -284.817058)
		(width 0.16002)
		(layer "In11.Cu")
		(net "M_L_CPU1_SB_DQS_DN<0>")
	)
	(segment
		(start 147.895564 -275.20011)
		(end 147.919186 -275.20011)
		(width 0.09525)
		(layer "In11.Cu")
		(net "M_L_CPU1_SB_DQS_DN<0>")
	)
	(segment
		(start 145.699988 -276.20595)
		(end 145.725388 -276.191218)
		(width 0.09525)
		(layer "In11.Cu")
		(net "M_L_CPU1_SB_DQS_DN<0>")
	)
	(segment
		(start 203.886816 -285.655258)
		(end 204.080618 -285.461456)
		(width 0.16002)
		(layer "In11.Cu")
		(net "M_L_CPU1_SB_DQS_DN<0>")
	)
	(segment
		(start 197.948296 -284.462474)
		(end 199.607424 -284.462474)
		(width 0.16002)
		(layer "In11.Cu")
		(net "M_L_CPU1_SB_DQS_DN<0>")
	)
	(segment
		(start 179.96916 -285.312358)
		(end 180.29682 -285.640018)
		(width 0.16002)
		(layer "In11.Cu")
		(net "M_L_CPU1_SB_DQS_DN<0>")
	)
	(segment
		(start 176.975262 -284.462474)
		(end 177.825146 -285.312358)
		(width 0.16002)
		(layer "In11.Cu")
		(net "M_L_CPU1_SB_DQS_DN<0>")
	)
	(segment
		(start 185.3692 -285.312358)
		(end 187.513214 -285.312358)
		(width 0.16002)
		(layer "In11.Cu")
		(net "M_L_CPU1_SB_DQS_DN<0>")
	)
	(segment
		(start 182.505604 -284.817058)
		(end 182.860188 -284.462474)
		(width 0.16002)
		(layer "In11.Cu")
		(net "M_L_CPU1_SB_DQS_DN<0>")
	)
	(segment
		(start 182.094124 -284.817058)
		(end 182.505604 -284.817058)
		(width 0.16002)
		(layer "In11.Cu")
		(net "M_L_CPU1_SB_DQS_DN<0>")
	)
	(segment
		(start 146.682714 -275.260816)
		(end 147.349464 -275.260816)
		(width 0.09525)
		(layer "In11.Cu")
		(net "M_L_CPU1_SB_DQS_DN<0>")
	)
	(segment
		(start 188.815218 -285.640018)
		(end 189.638178 -284.817058)
		(width 0.16002)
		(layer "In11.Cu")
		(net "M_L_CPU1_SB_DQS_DN<0>")
	)
	(segment
		(start 184.519316 -284.462474)
		(end 185.3692 -285.312358)
		(width 0.16002)
		(layer "In11.Cu")
		(net "M_L_CPU1_SB_DQS_DN<0>")
	)
	(segment
		(start 141.394942 -276.186392)
		(end 141.403324 -276.191218)
		(width 0.09525)
		(layer "In11.Cu")
		(net "M_L_CPU1_SB_DQS_DN<0>")
	)
	(segment
		(start 190.404242 -284.462474)
		(end 192.06337 -284.462474)
		(width 0.16002)
		(layer "In11.Cu")
		(net "M_L_CPU1_SB_DQS_DN<0>")
	)
	(segment
		(start 147.469352 -275.140928)
		(end 147.836382 -275.140928)
		(width 0.09525)
		(layer "In11.Cu")
		(net "M_L_CPU1_SB_DQS_DN<0>")
	)
	(segment
		(start 139.334748 -276.516338)
		(end 139.488672 -276.250908)
		(width 0.09525)
		(layer "In11.Cu")
		(net "M_L_CPU1_SB_DQS_DN<0>")
	)
	(segment
		(start 147.836382 -275.140928)
		(end 147.895564 -275.20011)
		(width 0.09525)
		(layer "In11.Cu")
		(net "M_L_CPU1_SB_DQS_DN<0>")
	)
	(segment
		(start 187.840874 -285.640018)
		(end 188.815218 -285.640018)
		(width 0.16002)
		(layer "In11.Cu")
		(net "M_L_CPU1_SB_DQS_DN<0>")
	)
	(segment
		(start 172.752766 -285.640018)
		(end 173.72711 -285.640018)
		(width 0.16002)
		(layer "In11.Cu")
		(net "M_L_CPU1_SB_DQS_DN<0>")
	)
	(segment
		(start 141.966188 -276.191218)
		(end 141.97457 -276.186392)
		(width 0.09525)
		(layer "In11.Cu")
		(net "M_L_CPU1_SB_DQS_DN<0>")
	)
	(segment
		(start 147.919186 -275.20011)
		(end 152.713436 -275.20011)
		(width 0.16002)
		(layer "In11.Cu")
		(net "M_L_CPU1_SB_DQS_DN<0>")
	)
	(segment
		(start 166.183056 -285.640018)
		(end 167.006016 -284.817058)
		(width 0.16002)
		(layer "In11.Cu")
		(net "M_L_CPU1_SB_DQS_DN<0>")
	)
	(arc
		(start 140.46327 -276.191218)
		(mid 140.744702 -276.266973)
		(end 141.026134 -276.191218)
		(width 0.09525)
		(layer "In11.Cu")
		(net "M_L_CPU1_SB_DQS_DN<0>")
	)
	(arc
		(start 144.241012 -276.201632)
		(mid 144.514392 -276.266853)
		(end 144.78508 -276.191218)
		(width 0.09525)
		(layer "In11.Cu")
		(net "M_L_CPU1_SB_DQS_DN<0>")
	)
	(arc
		(start 145.162524 -276.191218)
		(mid 145.429373 -276.267146)
		(end 145.699988 -276.20595)
		(width 0.09525)
		(layer "In11.Cu")
		(net "M_L_CPU1_SB_DQS_DN<0>")
	)
	(arc
		(start 139.60983 -276.232112)
		(mid 139.852542 -276.264995)
		(end 140.08608 -276.191218)
		(width 0.09525)
		(layer "In11.Cu")
		(net "M_L_CPU1_SB_DQS_DN<0>")
	)
	(arc
		(start 141.403324 -276.191218)
		(mid 141.684756 -276.266973)
		(end 141.966188 -276.191218)
		(width 0.09525)
		(layer "In11.Cu")
		(net "M_L_CPU1_SB_DQS_DN<0>")
	)
	(arc
		(start 145.725388 -276.191218)
		(mid 145.78606 -276.15066)
		(end 145.840958 -276.102572)
		(width 0.09525)
		(layer "In11.Cu")
		(net "M_L_CPU1_SB_DQS_DN<0>")
	)
	(arc
		(start 141.026134 -276.191218)
		(mid 141.209909 -276.140446)
		(end 141.394942 -276.186392)
		(width 0.09525)
		(layer "In11.Cu")
		(net "M_L_CPU1_SB_DQS_DN<0>")
	)
	(arc
		(start 142.343378 -276.191218)
		(mid 142.62481 -276.266973)
		(end 142.906242 -276.191218)
		(width 0.09525)
		(layer "In11.Cu")
		(net "M_L_CPU1_SB_DQS_DN<0>")
	)
	(arc
		(start 140.08608 -276.191218)
		(mid 140.269855 -276.140446)
		(end 140.454888 -276.186392)
		(width 0.09525)
		(layer "In11.Cu")
		(net "M_L_CPU1_SB_DQS_DN<0>")
	)
	(arc
		(start 142.906242 -276.191218)
		(mid 143.09471 -276.140541)
		(end 143.283178 -276.191218)
		(width 0.09525)
		(layer "In11.Cu")
		(net "M_L_CPU1_SB_DQS_DN<0>")
	)
	(arc
		(start 141.97457 -276.186392)
		(mid 142.159602 -276.140478)
		(end 142.343378 -276.191218)
		(width 0.09525)
		(layer "In11.Cu")
		(net "M_L_CPU1_SB_DQS_DN<0>")
	)
	(arc
		(start 144.797018 -276.18436)
		(mid 144.980653 -276.14041)
		(end 145.162524 -276.191218)
		(width 0.09525)
		(layer "In11.Cu")
		(net "M_L_CPU1_SB_DQS_DN<0>")
	)
	(arc
		(start 143.846042 -276.191218)
		(mid 144.027658 -276.140481)
		(end 144.21104 -276.18436)
		(width 0.09525)
		(layer "In11.Cu")
		(net "M_L_CPU1_SB_DQS_DN<0>")
	)
	(arc
		(start 143.283178 -276.191218)
		(mid 143.56461 -276.266973)
		(end 143.846042 -276.191218)
		(width 0.09525)
		(layer "In11.Cu")
		(net "M_L_CPU1_SB_DQS_DN<0>")
	)
	(arc
		(start 139.58951 -276.224238)
		(mid 139.599632 -276.228273)
		(end 139.60983 -276.232112)
		(width 0.09525)
		(layer "In11.Cu")
		(net "M_L_CPU1_SB_DQS_DN<0>")
	)
	(segment
		(start 137.927842 -279.490424)
		(end 138.394694 -279.756362)
		(width 0.10668)
		(layer "F.Cu")
		(net "M_L_CPU1_SB_DQ<9>")
	)
	(segment
		(start 147.435062 -279.745694)
		(end 147.853908 -279.745694)
		(width 0.0889)
		(layer "In11.Cu")
		(net "M_L_CPU1_SB_DQ<9>")
	)
	(segment
		(start 163.942776 -292.960298)
		(end 166.194486 -292.960298)
		(width 0.14478)
		(layer "In11.Cu")
		(net "M_L_CPU1_SB_DQ<9>")
	)
	(segment
		(start 203.875132 -292.429946)
		(end 204.019912 -292.574726)
		(width 0.14478)
		(layer "In11.Cu")
		(net "M_L_CPU1_SB_DQ<9>")
	)
	(segment
		(start 150.728172 -279.745694)
		(end 163.942776 -292.960298)
		(width 0.14478)
		(layer "In11.Cu")
		(net "M_L_CPU1_SB_DQ<9>")
	)
	(segment
		(start 178.088036 -292.110414)
		(end 178.93792 -292.960298)
		(width 0.14478)
		(layer "In11.Cu")
		(net "M_L_CPU1_SB_DQ<9>")
	)
	(segment
		(start 195.87718 -292.960298)
		(end 196.727318 -292.11016)
		(width 0.14478)
		(layer "In11.Cu")
		(net "M_L_CPU1_SB_DQ<9>")
	)
	(segment
		(start 186.055254 -292.960298)
		(end 188.703204 -292.960298)
		(width 0.14478)
		(layer "In11.Cu")
		(net "M_L_CPU1_SB_DQ<9>")
	)
	(segment
		(start 182.180738 -292.110414)
		(end 185.20537 -292.110414)
		(width 0.14478)
		(layer "In11.Cu")
		(net "M_L_CPU1_SB_DQ<9>")
	)
	(segment
		(start 145.150332 -280.0858)
		(end 145.340578 -279.97404)
		(width 0.0889)
		(layer "In11.Cu")
		(net "M_L_CPU1_SB_DQ<9>")
	)
	(segment
		(start 144.777714 -280.072846)
		(end 144.788128 -280.078942)
		(width 0.0889)
		(layer "In11.Cu")
		(net "M_L_CPU1_SB_DQ<9>")
	)
	(segment
		(start 196.727318 -292.11016)
		(end 203.730352 -292.11016)
		(width 0.14478)
		(layer "In11.Cu")
		(net "M_L_CPU1_SB_DQ<9>")
	)
	(segment
		(start 145.537682 -279.920446)
		(end 147.26031 -279.920446)
		(width 0.0889)
		(layer "In11.Cu")
		(net "M_L_CPU1_SB_DQ<9>")
	)
	(segment
		(start 141.393418 -280.083768)
		(end 141.4018 -280.078942)
		(width 0.0889)
		(layer "In11.Cu")
		(net "M_L_CPU1_SB_DQ<9>")
	)
	(segment
		(start 173.592744 -292.960298)
		(end 174.442628 -292.110414)
		(width 0.14478)
		(layer "In11.Cu")
		(net "M_L_CPU1_SB_DQ<9>")
	)
	(segment
		(start 188.703204 -292.960298)
		(end 189.553088 -292.110414)
		(width 0.14478)
		(layer "In11.Cu")
		(net "M_L_CPU1_SB_DQ<9>")
	)
	(segment
		(start 167.044624 -292.11016)
		(end 170.117008 -292.11016)
		(width 0.14478)
		(layer "In11.Cu")
		(net "M_L_CPU1_SB_DQ<9>")
	)
	(segment
		(start 203.730352 -292.11016)
		(end 203.875132 -292.25494)
		(width 0.14478)
		(layer "In11.Cu")
		(net "M_L_CPU1_SB_DQ<9>")
	)
	(segment
		(start 203.875132 -292.25494)
		(end 203.875132 -292.429946)
		(width 0.14478)
		(layer "In11.Cu")
		(net "M_L_CPU1_SB_DQ<9>")
	)
	(segment
		(start 204.571346 -292.11016)
		(end 205.822804 -292.11016)
		(width 0.14478)
		(layer "In11.Cu")
		(net "M_L_CPU1_SB_DQ<9>")
	)
	(segment
		(start 166.194486 -292.960298)
		(end 167.044624 -292.11016)
		(width 0.14478)
		(layer "In11.Cu")
		(net "M_L_CPU1_SB_DQ<9>")
	)
	(segment
		(start 204.426566 -292.429946)
		(end 204.426566 -292.25494)
		(width 0.14478)
		(layer "In11.Cu")
		(net "M_L_CPU1_SB_DQ<9>")
	)
	(segment
		(start 185.20537 -292.110414)
		(end 186.055254 -292.960298)
		(width 0.14478)
		(layer "In11.Cu")
		(net "M_L_CPU1_SB_DQ<9>")
	)
	(segment
		(start 138.394694 -279.756362)
		(end 138.24077 -280.021792)
		(width 0.0889)
		(layer "In11.Cu")
		(net "M_L_CPU1_SB_DQ<9>")
	)
	(segment
		(start 204.019912 -292.574726)
		(end 204.281786 -292.574726)
		(width 0.14478)
		(layer "In11.Cu")
		(net "M_L_CPU1_SB_DQ<9>")
	)
	(segment
		(start 141.967712 -280.078942)
		(end 141.976094 -280.083768)
		(width 0.0889)
		(layer "In11.Cu")
		(net "M_L_CPU1_SB_DQ<9>")
	)
	(segment
		(start 205.822804 -292.11016)
		(end 206.248 -292.535356)
		(width 0.14478)
		(layer "In11.Cu")
		(net "M_L_CPU1_SB_DQ<9>")
	)
	(segment
		(start 192.749424 -292.110414)
		(end 193.599308 -292.960298)
		(width 0.14478)
		(layer "In11.Cu")
		(net "M_L_CPU1_SB_DQ<9>")
	)
	(segment
		(start 189.553088 -292.110414)
		(end 192.749424 -292.110414)
		(width 0.14478)
		(layer "In11.Cu")
		(net "M_L_CPU1_SB_DQ<9>")
	)
	(segment
		(start 204.426566 -292.25494)
		(end 204.571346 -292.11016)
		(width 0.14478)
		(layer "In11.Cu")
		(net "M_L_CPU1_SB_DQ<9>")
	)
	(segment
		(start 178.93792 -292.960298)
		(end 181.330854 -292.960298)
		(width 0.14478)
		(layer "In11.Cu")
		(net "M_L_CPU1_SB_DQ<9>")
	)
	(segment
		(start 193.599308 -292.960298)
		(end 195.87718 -292.960298)
		(width 0.14478)
		(layer "In11.Cu")
		(net "M_L_CPU1_SB_DQ<9>")
	)
	(segment
		(start 140.453364 -280.083768)
		(end 140.461746 -280.078942)
		(width 0.0889)
		(layer "In11.Cu")
		(net "M_L_CPU1_SB_DQ<9>")
	)
	(segment
		(start 147.26031 -279.920446)
		(end 147.435062 -279.745694)
		(width 0.0889)
		(layer "In11.Cu")
		(net "M_L_CPU1_SB_DQ<9>")
	)
	(segment
		(start 204.281786 -292.574726)
		(end 204.426566 -292.429946)
		(width 0.14478)
		(layer "In11.Cu")
		(net "M_L_CPU1_SB_DQ<9>")
	)
	(segment
		(start 147.853908 -279.745694)
		(end 150.728172 -279.745694)
		(width 0.14478)
		(layer "In11.Cu")
		(net "M_L_CPU1_SB_DQ<9>")
	)
	(segment
		(start 170.117008 -292.11016)
		(end 170.967146 -292.960298)
		(width 0.14478)
		(layer "In11.Cu")
		(net "M_L_CPU1_SB_DQ<9>")
	)
	(segment
		(start 170.967146 -292.960298)
		(end 173.592744 -292.960298)
		(width 0.14478)
		(layer "In11.Cu")
		(net "M_L_CPU1_SB_DQ<9>")
	)
	(segment
		(start 174.442628 -292.110414)
		(end 178.088036 -292.110414)
		(width 0.14478)
		(layer "In11.Cu")
		(net "M_L_CPU1_SB_DQ<9>")
	)
	(segment
		(start 181.330854 -292.960298)
		(end 182.180738 -292.110414)
		(width 0.14478)
		(layer "In11.Cu")
		(net "M_L_CPU1_SB_DQ<9>")
	)
	(segment
		(start 138.24077 -280.021792)
		(end 138.263122 -280.105104)
		(width 0.0889)
		(layer "In11.Cu")
		(net "M_L_CPU1_SB_DQ<9>")
	)
	(arc
		(start 141.027658 -280.078942)
		(mid 141.209909 -280.129292)
		(end 141.393418 -280.083768)
		(width 0.0889)
		(layer "In11.Cu")
		(net "M_L_CPU1_SB_DQ<9>")
	)
	(arc
		(start 141.976094 -280.083768)
		(mid 142.159602 -280.129262)
		(end 142.341854 -280.078942)
		(width 0.0889)
		(layer "In11.Cu")
		(net "M_L_CPU1_SB_DQ<9>")
	)
	(arc
		(start 138.581892 -280.078942)
		(mid 138.864848 -280.002765)
		(end 139.147804 -280.078942)
		(width 0.0889)
		(layer "In11.Cu")
		(net "M_L_CPU1_SB_DQ<9>")
	)
	(arc
		(start 142.907766 -280.078942)
		(mid 143.09471 -280.129197)
		(end 143.281654 -280.078942)
		(width 0.0889)
		(layer "In11.Cu")
		(net "M_L_CPU1_SB_DQ<9>")
	)
	(arc
		(start 144.788128 -280.078942)
		(mid 144.968333 -280.129259)
		(end 145.150332 -280.0858)
		(width 0.0889)
		(layer "In11.Cu")
		(net "M_L_CPU1_SB_DQ<9>")
	)
	(arc
		(start 143.847566 -280.078942)
		(mid 144.034764 -280.129324)
		(end 144.221962 -280.078942)
		(width 0.0889)
		(layer "In11.Cu")
		(net "M_L_CPU1_SB_DQ<9>")
	)
	(arc
		(start 140.461746 -280.078942)
		(mid 140.744702 -280.002765)
		(end 141.027658 -280.078942)
		(width 0.0889)
		(layer "In11.Cu")
		(net "M_L_CPU1_SB_DQ<9>")
	)
	(arc
		(start 140.087604 -280.078942)
		(mid 140.269855 -280.129292)
		(end 140.453364 -280.083768)
		(width 0.0889)
		(layer "In11.Cu")
		(net "M_L_CPU1_SB_DQ<9>")
	)
	(arc
		(start 143.281654 -280.078942)
		(mid 143.56461 -280.002765)
		(end 143.847566 -280.078942)
		(width 0.0889)
		(layer "In11.Cu")
		(net "M_L_CPU1_SB_DQ<9>")
	)
	(arc
		(start 139.521692 -280.078942)
		(mid 139.804648 -280.002765)
		(end 140.087604 -280.078942)
		(width 0.0889)
		(layer "In11.Cu")
		(net "M_L_CPU1_SB_DQ<9>")
	)
	(arc
		(start 144.221962 -280.078942)
		(mid 144.499029 -280.002671)
		(end 144.777714 -280.072846)
		(width 0.0889)
		(layer "In11.Cu")
		(net "M_L_CPU1_SB_DQ<9>")
	)
	(arc
		(start 141.4018 -280.078942)
		(mid 141.684756 -280.002765)
		(end 141.967712 -280.078942)
		(width 0.0889)
		(layer "In11.Cu")
		(net "M_L_CPU1_SB_DQ<9>")
	)
	(arc
		(start 139.147804 -280.078942)
		(mid 139.334748 -280.129197)
		(end 139.521692 -280.078942)
		(width 0.0889)
		(layer "In11.Cu")
		(net "M_L_CPU1_SB_DQ<9>")
	)
	(arc
		(start 142.341854 -280.078942)
		(mid 142.62481 -280.002765)
		(end 142.907766 -280.078942)
		(width 0.0889)
		(layer "In11.Cu")
		(net "M_L_CPU1_SB_DQ<9>")
	)
	(arc
		(start 145.340578 -279.97404)
		(mid 145.43555 -279.934072)
		(end 145.537682 -279.920446)
		(width 0.0889)
		(layer "In11.Cu")
		(net "M_L_CPU1_SB_DQ<9>")
	)
	(arc
		(start 138.263122 -280.105104)
		(mid 138.425454 -280.127922)
		(end 138.581892 -280.078942)
		(width 0.0889)
		(layer "In11.Cu")
		(net "M_L_CPU1_SB_DQ<9>")
	)
	(segment
		(start 139.337796 -278.680418)
		(end 139.804648 -278.946356)
		(width 0.10668)
		(layer "F.Cu")
		(net "M_L_CPU1_SB_DQ<8>")
	)
	(segment
		(start 163.52901 -291.260276)
		(end 166.242746 -291.260276)
		(width 0.14478)
		(layer "In11.Cu")
		(net "M_L_CPU1_SB_DQ<8>")
	)
	(segment
		(start 189.724792 -290.410392)
		(end 192.749424 -290.410392)
		(width 0.14478)
		(layer "In11.Cu")
		(net "M_L_CPU1_SB_DQ<8>")
	)
	(segment
		(start 203.121514 -290.57346)
		(end 203.121514 -291.166296)
		(width 0.14478)
		(layer "In11.Cu")
		(net "M_L_CPU1_SB_DQ<8>")
	)
	(segment
		(start 193.599308 -291.260276)
		(end 195.915788 -291.260276)
		(width 0.14478)
		(layer "In11.Cu")
		(net "M_L_CPU1_SB_DQ<8>")
	)
	(segment
		(start 139.650724 -279.211786)
		(end 139.673076 -279.295098)
		(width 0.0889)
		(layer "In11.Cu")
		(net "M_L_CPU1_SB_DQ<8>")
	)
	(segment
		(start 181.718966 -291.260276)
		(end 182.56885 -290.410392)
		(width 0.14478)
		(layer "In11.Cu")
		(net "M_L_CPU1_SB_DQ<8>")
	)
	(segment
		(start 144.30502 -279.261824)
		(end 144.316958 -279.268682)
		(width 0.0889)
		(layer "In11.Cu")
		(net "M_L_CPU1_SB_DQ<8>")
	)
	(segment
		(start 195.915788 -291.260276)
		(end 196.765672 -290.410392)
		(width 0.14478)
		(layer "In11.Cu")
		(net "M_L_CPU1_SB_DQ<8>")
	)
	(segment
		(start 204.234542 -290.57346)
		(end 204.234542 -291.166296)
		(width 0.14478)
		(layer "In11.Cu")
		(net "M_L_CPU1_SB_DQ<8>")
	)
	(segment
		(start 203.51496 -291.329364)
		(end 203.678028 -291.166296)
		(width 0.14478)
		(layer "In11.Cu")
		(net "M_L_CPU1_SB_DQ<8>")
	)
	(segment
		(start 188.874908 -291.260276)
		(end 189.724792 -290.410392)
		(width 0.14478)
		(layer "In11.Cu")
		(net "M_L_CPU1_SB_DQ<8>")
	)
	(segment
		(start 143.377666 -279.268936)
		(end 143.386048 -279.273762)
		(width 0.0889)
		(layer "In11.Cu")
		(net "M_L_CPU1_SB_DQ<8>")
	)
	(segment
		(start 204.791056 -290.57346)
		(end 204.954124 -290.410392)
		(width 0.14478)
		(layer "In11.Cu")
		(net "M_L_CPU1_SB_DQ<8>")
	)
	(segment
		(start 144.316958 -279.268682)
		(end 144.330674 -279.276556)
		(width 0.0889)
		(layer "In11.Cu")
		(net "M_L_CPU1_SB_DQ<8>")
	)
	(segment
		(start 182.56885 -290.410392)
		(end 185.20537 -290.410392)
		(width 0.14478)
		(layer "In11.Cu")
		(net "M_L_CPU1_SB_DQ<8>")
	)
	(segment
		(start 204.071474 -290.410392)
		(end 204.234542 -290.57346)
		(width 0.14478)
		(layer "In11.Cu")
		(net "M_L_CPU1_SB_DQ<8>")
	)
	(segment
		(start 177.75936 -290.410392)
		(end 178.609244 -291.260276)
		(width 0.14478)
		(layer "In11.Cu")
		(net "M_L_CPU1_SB_DQ<8>")
	)
	(segment
		(start 170.9674 -291.260276)
		(end 173.7868 -291.260276)
		(width 0.14478)
		(layer "In11.Cu")
		(net "M_L_CPU1_SB_DQ<8>")
	)
	(segment
		(start 142.803372 -279.273762)
		(end 142.811754 -279.268936)
		(width 0.0889)
		(layer "In11.Cu")
		(net "M_L_CPU1_SB_DQ<8>")
	)
	(segment
		(start 203.678028 -291.166296)
		(end 203.678028 -290.57346)
		(width 0.14478)
		(layer "In11.Cu")
		(net "M_L_CPU1_SB_DQ<8>")
	)
	(segment
		(start 204.234542 -291.166296)
		(end 204.39761 -291.329364)
		(width 0.14478)
		(layer "In11.Cu")
		(net "M_L_CPU1_SB_DQ<8>")
	)
	(segment
		(start 174.636684 -290.410392)
		(end 177.75936 -290.410392)
		(width 0.14478)
		(layer "In11.Cu")
		(net "M_L_CPU1_SB_DQ<8>")
	)
	(segment
		(start 166.242746 -291.260276)
		(end 167.092884 -290.410138)
		(width 0.14478)
		(layer "In11.Cu")
		(net "M_L_CPU1_SB_DQ<8>")
	)
	(segment
		(start 186.055254 -291.260276)
		(end 188.874908 -291.260276)
		(width 0.14478)
		(layer "In11.Cu")
		(net "M_L_CPU1_SB_DQ<8>")
	)
	(segment
		(start 173.7868 -291.260276)
		(end 174.636684 -290.410392)
		(width 0.14478)
		(layer "In11.Cu")
		(net "M_L_CPU1_SB_DQ<8>")
	)
	(segment
		(start 204.791056 -291.166296)
		(end 204.791056 -290.57346)
		(width 0.14478)
		(layer "In11.Cu")
		(net "M_L_CPU1_SB_DQ<8>")
	)
	(segment
		(start 148.006054 -278.61133)
		(end 150.880064 -278.61133)
		(width 0.14478)
		(layer "In11.Cu")
		(net "M_L_CPU1_SB_DQ<8>")
	)
	(segment
		(start 146.44624 -278.61133)
		(end 148.006054 -278.61133)
		(width 0.0889)
		(layer "In11.Cu")
		(net "M_L_CPU1_SB_DQ<8>")
	)
	(segment
		(start 203.841096 -290.410392)
		(end 204.071474 -290.410392)
		(width 0.14478)
		(layer "In11.Cu")
		(net "M_L_CPU1_SB_DQ<8>")
	)
	(segment
		(start 139.804648 -278.946356)
		(end 139.650724 -279.211786)
		(width 0.0889)
		(layer "In11.Cu")
		(net "M_L_CPU1_SB_DQ<8>")
	)
	(segment
		(start 144.690592 -279.268936)
		(end 144.708626 -279.258268)
		(width 0.0889)
		(layer "In11.Cu")
		(net "M_L_CPU1_SB_DQ<8>")
	)
	(segment
		(start 204.627988 -291.329364)
		(end 204.791056 -291.166296)
		(width 0.14478)
		(layer "In11.Cu")
		(net "M_L_CPU1_SB_DQ<8>")
	)
	(segment
		(start 203.121514 -291.166296)
		(end 203.284582 -291.329364)
		(width 0.14478)
		(layer "In11.Cu")
		(net "M_L_CPU1_SB_DQ<8>")
	)
	(segment
		(start 145.444718 -279.319736)
		(end 145.737834 -279.319736)
		(width 0.0889)
		(layer "In11.Cu")
		(net "M_L_CPU1_SB_DQ<8>")
	)
	(segment
		(start 167.092884 -290.410138)
		(end 170.117262 -290.410138)
		(width 0.14478)
		(layer "In11.Cu")
		(net "M_L_CPU1_SB_DQ<8>")
	)
	(segment
		(start 196.765672 -290.410392)
		(end 202.958446 -290.410392)
		(width 0.14478)
		(layer "In11.Cu")
		(net "M_L_CPU1_SB_DQ<8>")
	)
	(segment
		(start 185.20537 -290.410392)
		(end 186.055254 -291.260276)
		(width 0.14478)
		(layer "In11.Cu")
		(net "M_L_CPU1_SB_DQ<8>")
	)
	(segment
		(start 203.678028 -290.57346)
		(end 203.841096 -290.410392)
		(width 0.14478)
		(layer "In11.Cu")
		(net "M_L_CPU1_SB_DQ<8>")
	)
	(segment
		(start 140.557758 -279.268936)
		(end 140.56614 -279.273762)
		(width 0.0889)
		(layer "In11.Cu")
		(net "M_L_CPU1_SB_DQ<8>")
	)
	(segment
		(start 145.737834 -279.319736)
		(end 146.44624 -278.61133)
		(width 0.0889)
		(layer "In11.Cu")
		(net "M_L_CPU1_SB_DQ<8>")
	)
	(segment
		(start 202.958446 -290.410392)
		(end 203.121514 -290.57346)
		(width 0.14478)
		(layer "In11.Cu")
		(net "M_L_CPU1_SB_DQ<8>")
	)
	(segment
		(start 192.749424 -290.410392)
		(end 193.599308 -291.260276)
		(width 0.14478)
		(layer "In11.Cu")
		(net "M_L_CPU1_SB_DQ<8>")
	)
	(segment
		(start 150.880064 -278.61133)
		(end 163.52901 -291.260276)
		(width 0.14478)
		(layer "In11.Cu")
		(net "M_L_CPU1_SB_DQ<8>")
	)
	(segment
		(start 178.609244 -291.260276)
		(end 181.718966 -291.260276)
		(width 0.14478)
		(layer "In11.Cu")
		(net "M_L_CPU1_SB_DQ<8>")
	)
	(segment
		(start 204.954124 -290.410392)
		(end 205.823058 -290.410392)
		(width 0.14478)
		(layer "In11.Cu")
		(net "M_L_CPU1_SB_DQ<8>")
	)
	(segment
		(start 205.823058 -290.410392)
		(end 206.248 -290.835334)
		(width 0.14478)
		(layer "In11.Cu")
		(net "M_L_CPU1_SB_DQ<8>")
	)
	(segment
		(start 170.117262 -290.410138)
		(end 170.9674 -291.260276)
		(width 0.14478)
		(layer "In11.Cu")
		(net "M_L_CPU1_SB_DQ<8>")
	)
	(segment
		(start 203.284582 -291.329364)
		(end 203.51496 -291.329364)
		(width 0.14478)
		(layer "In11.Cu")
		(net "M_L_CPU1_SB_DQ<8>")
	)
	(segment
		(start 204.39761 -291.329364)
		(end 204.627988 -291.329364)
		(width 0.14478)
		(layer "In11.Cu")
		(net "M_L_CPU1_SB_DQ<8>")
	)
	(arc
		(start 141.8717 -279.268936)
		(mid 142.154656 -279.192759)
		(end 142.437612 -279.268936)
		(width 0.0889)
		(layer "In11.Cu")
		(net "M_L_CPU1_SB_DQ<8>")
	)
	(arc
		(start 143.751808 -279.268936)
		(mid 144.027486 -279.192806)
		(end 144.30502 -279.261824)
		(width 0.0889)
		(layer "In11.Cu")
		(net "M_L_CPU1_SB_DQ<8>")
	)
	(arc
		(start 141.497812 -279.268936)
		(mid 141.684756 -279.319191)
		(end 141.8717 -279.268936)
		(width 0.0889)
		(layer "In11.Cu")
		(net "M_L_CPU1_SB_DQ<8>")
	)
	(arc
		(start 139.991846 -279.268936)
		(mid 140.274802 -279.192759)
		(end 140.557758 -279.268936)
		(width 0.0889)
		(layer "In11.Cu")
		(net "M_L_CPU1_SB_DQ<8>")
	)
	(arc
		(start 140.56614 -279.273762)
		(mid 140.749648 -279.319256)
		(end 140.9319 -279.268936)
		(width 0.0889)
		(layer "In11.Cu")
		(net "M_L_CPU1_SB_DQ<8>")
	)
	(arc
		(start 144.708626 -279.258268)
		(mid 144.984321 -279.192425)
		(end 145.257266 -279.268936)
		(width 0.0889)
		(layer "In11.Cu")
		(net "M_L_CPU1_SB_DQ<8>")
	)
	(arc
		(start 140.9319 -279.268936)
		(mid 141.214856 -279.192759)
		(end 141.497812 -279.268936)
		(width 0.0889)
		(layer "In11.Cu")
		(net "M_L_CPU1_SB_DQ<8>")
	)
	(arc
		(start 142.437612 -279.268936)
		(mid 142.619863 -279.319286)
		(end 142.803372 -279.273762)
		(width 0.0889)
		(layer "In11.Cu")
		(net "M_L_CPU1_SB_DQ<8>")
	)
	(arc
		(start 143.386048 -279.273762)
		(mid 143.569556 -279.319256)
		(end 143.751808 -279.268936)
		(width 0.0889)
		(layer "In11.Cu")
		(net "M_L_CPU1_SB_DQ<8>")
	)
	(arc
		(start 142.811754 -279.268936)
		(mid 143.09471 -279.192759)
		(end 143.377666 -279.268936)
		(width 0.0889)
		(layer "In11.Cu")
		(net "M_L_CPU1_SB_DQ<8>")
	)
	(arc
		(start 145.257266 -279.268936)
		(mid 145.347629 -279.306746)
		(end 145.444718 -279.319736)
		(width 0.0889)
		(layer "In11.Cu")
		(net "M_L_CPU1_SB_DQ<8>")
	)
	(arc
		(start 144.330674 -279.276556)
		(mid 144.511604 -279.319034)
		(end 144.690592 -279.268936)
		(width 0.0889)
		(layer "In11.Cu")
		(net "M_L_CPU1_SB_DQ<8>")
	)
	(arc
		(start 139.673076 -279.295098)
		(mid 139.835408 -279.317916)
		(end 139.991846 -279.268936)
		(width 0.0889)
		(layer "In11.Cu")
		(net "M_L_CPU1_SB_DQ<8>")
	)
	(segment
		(start 137.457942 -278.680418)
		(end 137.924794 -278.946356)
		(width 0.10668)
		(layer "F.Cu")
		(net "M_L_CPU1_SB_DQ<7>")
	)
	(segment
		(start 159.280606 -286.224726)
		(end 159.474916 -286.419036)
		(width 0.14478)
		(layer "In11.Cu")
		(net "M_L_CPU1_SB_DQ<7>")
	)
	(segment
		(start 189.632082 -289.560508)
		(end 192.814448 -289.560508)
		(width 0.14478)
		(layer "In11.Cu")
		(net "M_L_CPU1_SB_DQ<7>")
	)
	(segment
		(start 154.19324 -280.906982)
		(end 154.361896 -280.906982)
		(width 0.14478)
		(layer "In11.Cu")
		(net "M_L_CPU1_SB_DQ<7>")
	)
	(segment
		(start 158.13024 -284.843982)
		(end 158.298896 -284.843982)
		(width 0.14478)
		(layer "In11.Cu")
		(net "M_L_CPU1_SB_DQ<7>")
	)
	(segment
		(start 158.492952 -285.038038)
		(end 158.493206 -285.26867)
		(width 0.14478)
		(layer "In11.Cu")
		(net "M_L_CPU1_SB_DQ<7>")
	)
	(segment
		(start 145.247614 -278.629872)
		(end 145.258028 -278.623776)
		(width 0.0889)
		(layer "In11.Cu")
		(net "M_L_CPU1_SB_DQ<7>")
	)
	(segment
		(start 161.642552 -288.187638)
		(end 161.642806 -288.41827)
		(width 0.14478)
		(layer "In11.Cu")
		(net "M_L_CPU1_SB_DQ<7>")
	)
	(segment
		(start 154.750516 -281.694636)
		(end 154.98064 -281.694382)
		(width 0.14478)
		(layer "In11.Cu")
		(net "M_L_CPU1_SB_DQ<7>")
	)
	(segment
		(start 200.807066 -289.271964)
		(end 201.075036 -289.271964)
		(width 0.14478)
		(layer "In11.Cu")
		(net "M_L_CPU1_SB_DQ<7>")
	)
	(segment
		(start 196.805296 -289.560508)
		(end 199.405494 -289.560508)
		(width 0.14478)
		(layer "In11.Cu")
		(net "M_L_CPU1_SB_DQ<7>")
	)
	(segment
		(start 158.493206 -285.26867)
		(end 158.493206 -285.437326)
		(width 0.14478)
		(layer "In11.Cu")
		(net "M_L_CPU1_SB_DQ<7>")
	)
	(segment
		(start 201.72299 -289.560508)
		(end 202.147932 -289.98545)
		(width 0.14478)
		(layer "In11.Cu")
		(net "M_L_CPU1_SB_DQ<7>")
	)
	(segment
		(start 139.04341 -278.61895)
		(end 139.051792 -278.623776)
		(width 0.0889)
		(layer "In11.Cu")
		(net "M_L_CPU1_SB_DQ<7>")
	)
	(segment
		(start 160.067752 -286.612838)
		(end 160.068006 -286.84347)
		(width 0.14478)
		(layer "In11.Cu")
		(net "M_L_CPU1_SB_DQ<7>")
	)
	(segment
		(start 155.343606 -282.287726)
		(end 155.537916 -282.482036)
		(width 0.14478)
		(layer "In11.Cu")
		(net "M_L_CPU1_SB_DQ<7>")
	)
	(segment
		(start 152.981406 -279.925526)
		(end 153.175716 -280.119836)
		(width 0.14478)
		(layer "In11.Cu")
		(net "M_L_CPU1_SB_DQ<7>")
	)
	(segment
		(start 153.768806 -280.712926)
		(end 153.963116 -280.907236)
		(width 0.14478)
		(layer "In11.Cu")
		(net "M_L_CPU1_SB_DQ<7>")
	)
	(segment
		(start 146.19859 -278.320246)
		(end 147.21967 -278.320246)
		(width 0.0889)
		(layer "In11.Cu")
		(net "M_L_CPU1_SB_DQ<7>")
	)
	(segment
		(start 154.98064 -281.694382)
		(end 155.149296 -281.694382)
		(width 0.14478)
		(layer "In11.Cu")
		(net "M_L_CPU1_SB_DQ<7>")
	)
	(segment
		(start 152.61844 -279.332182)
		(end 152.787096 -279.332182)
		(width 0.14478)
		(layer "In11.Cu")
		(net "M_L_CPU1_SB_DQ<7>")
	)
	(segment
		(start 137.924794 -278.946356)
		(end 138.078718 -278.680926)
		(width 0.0889)
		(layer "In11.Cu")
		(net "M_L_CPU1_SB_DQ<7>")
	)
	(segment
		(start 143.751808 -278.623776)
		(end 143.762222 -278.629872)
		(width 0.0889)
		(layer "In11.Cu")
		(net "M_L_CPU1_SB_DQ<7>")
	)
	(segment
		(start 153.768552 -280.313638)
		(end 153.768806 -280.54427)
		(width 0.14478)
		(layer "In11.Cu")
		(net "M_L_CPU1_SB_DQ<7>")
	)
	(segment
		(start 188.781944 -290.410646)
		(end 189.632082 -289.560508)
		(width 0.14478)
		(layer "In11.Cu")
		(net "M_L_CPU1_SB_DQ<7>")
	)
	(segment
		(start 159.086296 -285.631382)
		(end 159.280352 -285.825438)
		(width 0.14478)
		(layer "In11.Cu")
		(net "M_L_CPU1_SB_DQ<7>")
	)
	(segment
		(start 152.787096 -279.332182)
		(end 152.981152 -279.526238)
		(width 0.14478)
		(layer "In11.Cu")
		(net "M_L_CPU1_SB_DQ<7>")
	)
	(segment
		(start 142.803372 -278.61895)
		(end 142.811754 -278.623776)
		(width 0.0889)
		(layer "In11.Cu")
		(net "M_L_CPU1_SB_DQ<7>")
	)
	(segment
		(start 161.448496 -287.993582)
		(end 161.642552 -288.187638)
		(width 0.14478)
		(layer "In11.Cu")
		(net "M_L_CPU1_SB_DQ<7>")
	)
	(segment
		(start 199.694038 -289.271964)
		(end 199.962008 -289.271964)
		(width 0.14478)
		(layer "In11.Cu")
		(net "M_L_CPU1_SB_DQ<7>")
	)
	(segment
		(start 155.936696 -282.481782)
		(end 156.130752 -282.675838)
		(width 0.14478)
		(layer "In11.Cu")
		(net "M_L_CPU1_SB_DQ<7>")
	)
	(segment
		(start 185.270394 -289.560508)
		(end 186.120532 -290.410646)
		(width 0.14478)
		(layer "In11.Cu")
		(net "M_L_CPU1_SB_DQ<7>")
	)
	(segment
		(start 199.405494 -289.560508)
		(end 199.694038 -289.271964)
		(width 0.14478)
		(layer "In11.Cu")
		(net "M_L_CPU1_SB_DQ<7>")
	)
	(segment
		(start 156.55544 -283.269182)
		(end 156.724096 -283.269182)
		(width 0.14478)
		(layer "In11.Cu")
		(net "M_L_CPU1_SB_DQ<7>")
	)
	(segment
		(start 158.687516 -285.631636)
		(end 158.91764 -285.631382)
		(width 0.14478)
		(layer "In11.Cu")
		(net "M_L_CPU1_SB_DQ<7>")
	)
	(segment
		(start 147.977352 -278.05507)
		(end 151.11095 -278.05507)
		(width 0.14478)
		(layer "In11.Cu")
		(net "M_L_CPU1_SB_DQ<7>")
	)
	(segment
		(start 154.361896 -280.906982)
		(end 154.555952 -281.101038)
		(width 0.14478)
		(layer "In11.Cu")
		(net "M_L_CPU1_SB_DQ<7>")
	)
	(segment
		(start 201.36358 -289.560508)
		(end 201.72299 -289.560508)
		(width 0.14478)
		(layer "In11.Cu")
		(net "M_L_CPU1_SB_DQ<7>")
	)
	(segment
		(start 161.049716 -287.993836)
		(end 161.27984 -287.993582)
		(width 0.14478)
		(layer "In11.Cu")
		(net "M_L_CPU1_SB_DQ<7>")
	)
	(segment
		(start 161.642806 -288.41827)
		(end 161.642806 -288.586926)
		(width 0.14478)
		(layer "In11.Cu")
		(net "M_L_CPU1_SB_DQ<7>")
	)
	(segment
		(start 138.078718 -278.680926)
		(end 138.17473 -278.655526)
		(width 0.0889)
		(layer "In11.Cu")
		(net "M_L_CPU1_SB_DQ<7>")
	)
	(segment
		(start 153.768806 -280.54427)
		(end 153.768806 -280.712926)
		(width 0.14478)
		(layer "In11.Cu")
		(net "M_L_CPU1_SB_DQ<7>")
	)
	(segment
		(start 181.72303 -290.410646)
		(end 182.573168 -289.560508)
		(width 0.14478)
		(layer "In11.Cu")
		(net "M_L_CPU1_SB_DQ<7>")
	)
	(segment
		(start 155.149296 -281.694382)
		(end 155.343352 -281.888438)
		(width 0.14478)
		(layer "In11.Cu")
		(net "M_L_CPU1_SB_DQ<7>")
	)
	(segment
		(start 139.617704 -278.623776)
		(end 139.626086 -278.61895)
		(width 0.0889)
		(layer "In11.Cu")
		(net "M_L_CPU1_SB_DQ<7>")
	)
	(segment
		(start 177.72634 -289.560508)
		(end 178.576478 -290.410646)
		(width 0.14478)
		(layer "In11.Cu")
		(net "M_L_CPU1_SB_DQ<7>")
	)
	(segment
		(start 156.918152 -283.463238)
		(end 156.918406 -283.69387)
		(width 0.14478)
		(layer "In11.Cu")
		(net "M_L_CPU1_SB_DQ<7>")
	)
	(segment
		(start 161.27984 -287.993582)
		(end 161.448496 -287.993582)
		(width 0.14478)
		(layer "In11.Cu")
		(net "M_L_CPU1_SB_DQ<7>")
	)
	(segment
		(start 157.112716 -284.056836)
		(end 157.34284 -284.056582)
		(width 0.14478)
		(layer "In11.Cu")
		(net "M_L_CPU1_SB_DQ<7>")
	)
	(segment
		(start 145.945352 -278.573484)
		(end 146.19859 -278.320246)
		(width 0.0889)
		(layer "In11.Cu")
		(net "M_L_CPU1_SB_DQ<7>")
	)
	(segment
		(start 154.556206 -281.500326)
		(end 154.750516 -281.694636)
		(width 0.14478)
		(layer "In11.Cu")
		(net "M_L_CPU1_SB_DQ<7>")
	)
	(segment
		(start 182.573168 -289.560508)
		(end 185.270394 -289.560508)
		(width 0.14478)
		(layer "In11.Cu")
		(net "M_L_CPU1_SB_DQ<7>")
	)
	(segment
		(start 178.576478 -290.410646)
		(end 181.72303 -290.410646)
		(width 0.14478)
		(layer "In11.Cu")
		(net "M_L_CPU1_SB_DQ<7>")
	)
	(segment
		(start 155.343606 -282.11907)
		(end 155.343606 -282.287726)
		(width 0.14478)
		(layer "In11.Cu")
		(net "M_L_CPU1_SB_DQ<7>")
	)
	(segment
		(start 171.032678 -290.410646)
		(end 173.693836 -290.410646)
		(width 0.14478)
		(layer "In11.Cu")
		(net "M_L_CPU1_SB_DQ<7>")
	)
	(segment
		(start 153.40584 -280.119582)
		(end 153.574496 -280.119582)
		(width 0.14478)
		(layer "In11.Cu")
		(net "M_L_CPU1_SB_DQ<7>")
	)
	(segment
		(start 154.556206 -281.33167)
		(end 154.556206 -281.500326)
		(width 0.14478)
		(layer "In11.Cu")
		(net "M_L_CPU1_SB_DQ<7>")
	)
	(segment
		(start 152.981406 -279.75687)
		(end 152.981406 -279.925526)
		(width 0.14478)
		(layer "In11.Cu")
		(net "M_L_CPU1_SB_DQ<7>")
	)
	(segment
		(start 152.388316 -279.332436)
		(end 152.61844 -279.332182)
		(width 0.14478)
		(layer "In11.Cu")
		(net "M_L_CPU1_SB_DQ<7>")
	)
	(segment
		(start 153.963116 -280.907236)
		(end 154.19324 -280.906982)
		(width 0.14478)
		(layer "In11.Cu")
		(net "M_L_CPU1_SB_DQ<7>")
	)
	(segment
		(start 156.131006 -283.075126)
		(end 156.325316 -283.269436)
		(width 0.14478)
		(layer "In11.Cu")
		(net "M_L_CPU1_SB_DQ<7>")
	)
	(segment
		(start 167.000428 -289.560254)
		(end 170.182286 -289.560254)
		(width 0.14478)
		(layer "In11.Cu")
		(net "M_L_CPU1_SB_DQ<7>")
	)
	(segment
		(start 160.068006 -286.84347)
		(end 160.068006 -287.012126)
		(width 0.14478)
		(layer "In11.Cu")
		(net "M_L_CPU1_SB_DQ<7>")
	)
	(segment
		(start 157.34284 -284.056582)
		(end 157.511496 -284.056582)
		(width 0.14478)
		(layer "In11.Cu")
		(net "M_L_CPU1_SB_DQ<7>")
	)
	(segment
		(start 163.466272 -290.410392)
		(end 166.15029 -290.410392)
		(width 0.14478)
		(layer "In11.Cu")
		(net "M_L_CPU1_SB_DQ<7>")
	)
	(segment
		(start 199.962008 -289.271964)
		(end 200.250552 -289.560508)
		(width 0.14478)
		(layer "In11.Cu")
		(net "M_L_CPU1_SB_DQ<7>")
	)
	(segment
		(start 159.474916 -286.419036)
		(end 159.70504 -286.418782)
		(width 0.14478)
		(layer "In11.Cu")
		(net "M_L_CPU1_SB_DQ<7>")
	)
	(segment
		(start 201.075036 -289.271964)
		(end 201.36358 -289.560508)
		(width 0.14478)
		(layer "In11.Cu")
		(net "M_L_CPU1_SB_DQ<7>")
	)
	(segment
		(start 160.262316 -287.206436)
		(end 160.49244 -287.206182)
		(width 0.14478)
		(layer "In11.Cu")
		(net "M_L_CPU1_SB_DQ<7>")
	)
	(segment
		(start 145.444718 -278.573484)
		(end 145.945352 -278.573484)
		(width 0.0889)
		(layer "In11.Cu")
		(net "M_L_CPU1_SB_DQ<7>")
	)
	(segment
		(start 156.325316 -283.269436)
		(end 156.55544 -283.269182)
		(width 0.14478)
		(layer "In11.Cu")
		(net "M_L_CPU1_SB_DQ<7>")
	)
	(segment
		(start 157.705552 -284.250638)
		(end 157.705806 -284.48127)
		(width 0.14478)
		(layer "In11.Cu")
		(net "M_L_CPU1_SB_DQ<7>")
	)
	(segment
		(start 192.814448 -289.560508)
		(end 193.664332 -290.410392)
		(width 0.14478)
		(layer "In11.Cu")
		(net "M_L_CPU1_SB_DQ<7>")
	)
	(segment
		(start 156.918406 -283.69387)
		(end 156.918406 -283.862526)
		(width 0.14478)
		(layer "In11.Cu")
		(net "M_L_CPU1_SB_DQ<7>")
	)
	(segment
		(start 157.705806 -284.48127)
		(end 157.705806 -284.649926)
		(width 0.14478)
		(layer "In11.Cu")
		(net "M_L_CPU1_SB_DQ<7>")
	)
	(segment
		(start 151.11095 -278.05507)
		(end 152.388316 -279.332436)
		(width 0.14478)
		(layer "In11.Cu")
		(net "M_L_CPU1_SB_DQ<7>")
	)
	(segment
		(start 174.543974 -289.560508)
		(end 177.72634 -289.560508)
		(width 0.14478)
		(layer "In11.Cu")
		(net "M_L_CPU1_SB_DQ<7>")
	)
	(segment
		(start 170.182286 -289.560254)
		(end 171.032678 -290.410646)
		(width 0.14478)
		(layer "In11.Cu")
		(net "M_L_CPU1_SB_DQ<7>")
	)
	(segment
		(start 156.130752 -282.675838)
		(end 156.131006 -282.90647)
		(width 0.14478)
		(layer "In11.Cu")
		(net "M_L_CPU1_SB_DQ<7>")
	)
	(segment
		(start 160.855406 -287.799526)
		(end 161.049716 -287.993836)
		(width 0.14478)
		(layer "In11.Cu")
		(net "M_L_CPU1_SB_DQ<7>")
	)
	(segment
		(start 160.661096 -287.206182)
		(end 160.855152 -287.400238)
		(width 0.14478)
		(layer "In11.Cu")
		(net "M_L_CPU1_SB_DQ<7>")
	)
	(segment
		(start 153.175716 -280.119836)
		(end 153.40584 -280.119582)
		(width 0.14478)
		(layer "In11.Cu")
		(net "M_L_CPU1_SB_DQ<7>")
	)
	(segment
		(start 157.705806 -284.649926)
		(end 157.900116 -284.844236)
		(width 0.14478)
		(layer "In11.Cu")
		(net "M_L_CPU1_SB_DQ<7>")
	)
	(segment
		(start 147.484846 -278.05507)
		(end 147.977352 -278.05507)
		(width 0.0889)
		(layer "In11.Cu")
		(net "M_L_CPU1_SB_DQ<7>")
	)
	(segment
		(start 173.693836 -290.410646)
		(end 174.543974 -289.560508)
		(width 0.14478)
		(layer "In11.Cu")
		(net "M_L_CPU1_SB_DQ<7>")
	)
	(segment
		(start 153.574496 -280.119582)
		(end 153.768552 -280.313638)
		(width 0.14478)
		(layer "In11.Cu")
		(net "M_L_CPU1_SB_DQ<7>")
	)
	(segment
		(start 156.131006 -282.90647)
		(end 156.131006 -283.075126)
		(width 0.14478)
		(layer "In11.Cu")
		(net "M_L_CPU1_SB_DQ<7>")
	)
	(segment
		(start 160.068006 -287.012126)
		(end 160.262316 -287.206436)
		(width 0.14478)
		(layer "In11.Cu")
		(net "M_L_CPU1_SB_DQ<7>")
	)
	(segment
		(start 155.76804 -282.481782)
		(end 155.936696 -282.481782)
		(width 0.14478)
		(layer "In11.Cu")
		(net "M_L_CPU1_SB_DQ<7>")
	)
	(segment
		(start 140.557758 -278.623776)
		(end 140.56614 -278.61895)
		(width 0.0889)
		(layer "In11.Cu")
		(net "M_L_CPU1_SB_DQ<7>")
	)
	(segment
		(start 159.873696 -286.418782)
		(end 160.067752 -286.612838)
		(width 0.14478)
		(layer "In11.Cu")
		(net "M_L_CPU1_SB_DQ<7>")
	)
	(segment
		(start 157.511496 -284.056582)
		(end 157.705552 -284.250638)
		(width 0.14478)
		(layer "In11.Cu")
		(net "M_L_CPU1_SB_DQ<7>")
	)
	(segment
		(start 156.724096 -283.269182)
		(end 156.918152 -283.463238)
		(width 0.14478)
		(layer "In11.Cu")
		(net "M_L_CPU1_SB_DQ<7>")
	)
	(segment
		(start 200.250552 -289.560508)
		(end 200.518522 -289.560508)
		(width 0.14478)
		(layer "In11.Cu")
		(net "M_L_CPU1_SB_DQ<7>")
	)
	(segment
		(start 147.21967 -278.320246)
		(end 147.484846 -278.05507)
		(width 0.0889)
		(layer "In11.Cu")
		(net "M_L_CPU1_SB_DQ<7>")
	)
	(segment
		(start 160.855152 -287.400238)
		(end 160.855406 -287.63087)
		(width 0.14478)
		(layer "In11.Cu")
		(net "M_L_CPU1_SB_DQ<7>")
	)
	(segment
		(start 158.493206 -285.437326)
		(end 158.687516 -285.631636)
		(width 0.14478)
		(layer "In11.Cu")
		(net "M_L_CPU1_SB_DQ<7>")
	)
	(segment
		(start 200.518522 -289.560508)
		(end 200.807066 -289.271964)
		(width 0.14478)
		(layer "In11.Cu")
		(net "M_L_CPU1_SB_DQ<7>")
	)
	(segment
		(start 160.855406 -287.63087)
		(end 160.855406 -287.799526)
		(width 0.14478)
		(layer "In11.Cu")
		(net "M_L_CPU1_SB_DQ<7>")
	)
	(segment
		(start 186.120532 -290.410646)
		(end 188.781944 -290.410646)
		(width 0.14478)
		(layer "In11.Cu")
		(net "M_L_CPU1_SB_DQ<7>")
	)
	(segment
		(start 161.642806 -288.586926)
		(end 163.466272 -290.410392)
		(width 0.14478)
		(layer "In11.Cu")
		(net "M_L_CPU1_SB_DQ<7>")
	)
	(segment
		(start 159.280352 -285.825438)
		(end 159.280606 -286.05607)
		(width 0.14478)
		(layer "In11.Cu")
		(net "M_L_CPU1_SB_DQ<7>")
	)
	(segment
		(start 166.15029 -290.410392)
		(end 167.000428 -289.560254)
		(width 0.14478)
		(layer "In11.Cu")
		(net "M_L_CPU1_SB_DQ<7>")
	)
	(segment
		(start 152.981152 -279.526238)
		(end 152.981406 -279.75687)
		(width 0.14478)
		(layer "In11.Cu")
		(net "M_L_CPU1_SB_DQ<7>")
	)
	(segment
		(start 155.537916 -282.482036)
		(end 155.76804 -282.481782)
		(width 0.14478)
		(layer "In11.Cu")
		(net "M_L_CPU1_SB_DQ<7>")
	)
	(segment
		(start 155.343352 -281.888438)
		(end 155.343606 -282.11907)
		(width 0.14478)
		(layer "In11.Cu")
		(net "M_L_CPU1_SB_DQ<7>")
	)
	(segment
		(start 154.555952 -281.101038)
		(end 154.556206 -281.33167)
		(width 0.14478)
		(layer "In11.Cu")
		(net "M_L_CPU1_SB_DQ<7>")
	)
	(segment
		(start 157.900116 -284.844236)
		(end 158.13024 -284.843982)
		(width 0.14478)
		(layer "In11.Cu")
		(net "M_L_CPU1_SB_DQ<7>")
	)
	(segment
		(start 193.664332 -290.410392)
		(end 195.955412 -290.410392)
		(width 0.14478)
		(layer "In11.Cu")
		(net "M_L_CPU1_SB_DQ<7>")
	)
	(segment
		(start 158.91764 -285.631382)
		(end 159.086296 -285.631382)
		(width 0.14478)
		(layer "In11.Cu")
		(net "M_L_CPU1_SB_DQ<7>")
	)
	(segment
		(start 159.280606 -286.05607)
		(end 159.280606 -286.224726)
		(width 0.14478)
		(layer "In11.Cu")
		(net "M_L_CPU1_SB_DQ<7>")
	)
	(segment
		(start 160.49244 -287.206182)
		(end 160.661096 -287.206182)
		(width 0.14478)
		(layer "In11.Cu")
		(net "M_L_CPU1_SB_DQ<7>")
	)
	(segment
		(start 158.298896 -284.843982)
		(end 158.492952 -285.038038)
		(width 0.14478)
		(layer "In11.Cu")
		(net "M_L_CPU1_SB_DQ<7>")
	)
	(segment
		(start 159.70504 -286.418782)
		(end 159.873696 -286.418782)
		(width 0.14478)
		(layer "In11.Cu")
		(net "M_L_CPU1_SB_DQ<7>")
	)
	(segment
		(start 156.918406 -283.862526)
		(end 157.112716 -284.056836)
		(width 0.14478)
		(layer "In11.Cu")
		(net "M_L_CPU1_SB_DQ<7>")
	)
	(segment
		(start 195.955412 -290.410392)
		(end 196.805296 -289.560508)
		(width 0.14478)
		(layer "In11.Cu")
		(net "M_L_CPU1_SB_DQ<7>")
	)
	(segment
		(start 143.377666 -278.623776)
		(end 143.386048 -278.61895)
		(width 0.0889)
		(layer "In11.Cu")
		(net "M_L_CPU1_SB_DQ<7>")
	)
	(arc
		(start 139.626086 -278.61895)
		(mid 139.809594 -278.573456)
		(end 139.991846 -278.623776)
		(width 0.0889)
		(layer "In11.Cu")
		(net "M_L_CPU1_SB_DQ<7>")
	)
	(arc
		(start 144.317974 -278.623776)
		(mid 144.505172 -278.573394)
		(end 144.69237 -278.623776)
		(width 0.0889)
		(layer "In11.Cu")
		(net "M_L_CPU1_SB_DQ<7>")
	)
	(arc
		(start 141.497812 -278.623776)
		(mid 141.684756 -278.573521)
		(end 141.8717 -278.623776)
		(width 0.0889)
		(layer "In11.Cu")
		(net "M_L_CPU1_SB_DQ<7>")
	)
	(arc
		(start 140.56614 -278.61895)
		(mid 140.749648 -278.573456)
		(end 140.9319 -278.623776)
		(width 0.0889)
		(layer "In11.Cu")
		(net "M_L_CPU1_SB_DQ<7>")
	)
	(arc
		(start 144.69237 -278.623776)
		(mid 144.969183 -278.699919)
		(end 145.247614 -278.629872)
		(width 0.0889)
		(layer "In11.Cu")
		(net "M_L_CPU1_SB_DQ<7>")
	)
	(arc
		(start 145.258028 -278.623776)
		(mid 145.348059 -278.586337)
		(end 145.444718 -278.573484)
		(width 0.0889)
		(layer "In11.Cu")
		(net "M_L_CPU1_SB_DQ<7>")
	)
	(arc
		(start 138.67765 -278.623776)
		(mid 138.859901 -278.573426)
		(end 139.04341 -278.61895)
		(width 0.0889)
		(layer "In11.Cu")
		(net "M_L_CPU1_SB_DQ<7>")
	)
	(arc
		(start 138.17473 -278.655526)
		(mid 138.429938 -278.699003)
		(end 138.67765 -278.623776)
		(width 0.0889)
		(layer "In11.Cu")
		(net "M_L_CPU1_SB_DQ<7>")
	)
	(arc
		(start 142.811754 -278.623776)
		(mid 143.09471 -278.699953)
		(end 143.377666 -278.623776)
		(width 0.0889)
		(layer "In11.Cu")
		(net "M_L_CPU1_SB_DQ<7>")
	)
	(arc
		(start 139.991846 -278.623776)
		(mid 140.274802 -278.699953)
		(end 140.557758 -278.623776)
		(width 0.0889)
		(layer "In11.Cu")
		(net "M_L_CPU1_SB_DQ<7>")
	)
	(arc
		(start 140.9319 -278.623776)
		(mid 141.214856 -278.699953)
		(end 141.497812 -278.623776)
		(width 0.0889)
		(layer "In11.Cu")
		(net "M_L_CPU1_SB_DQ<7>")
	)
	(arc
		(start 143.762222 -278.629872)
		(mid 144.040908 -278.700092)
		(end 144.317974 -278.623776)
		(width 0.0889)
		(layer "In11.Cu")
		(net "M_L_CPU1_SB_DQ<7>")
	)
	(arc
		(start 141.8717 -278.623776)
		(mid 142.154656 -278.699953)
		(end 142.437612 -278.623776)
		(width 0.0889)
		(layer "In11.Cu")
		(net "M_L_CPU1_SB_DQ<7>")
	)
	(arc
		(start 142.437612 -278.623776)
		(mid 142.619863 -278.573426)
		(end 142.803372 -278.61895)
		(width 0.0889)
		(layer "In11.Cu")
		(net "M_L_CPU1_SB_DQ<7>")
	)
	(arc
		(start 143.386048 -278.61895)
		(mid 143.569556 -278.573456)
		(end 143.751808 -278.623776)
		(width 0.0889)
		(layer "In11.Cu")
		(net "M_L_CPU1_SB_DQ<7>")
	)
	(arc
		(start 139.051792 -278.623776)
		(mid 139.334748 -278.699953)
		(end 139.617704 -278.623776)
		(width 0.0889)
		(layer "In11.Cu")
		(net "M_L_CPU1_SB_DQ<7>")
	)
	(segment
		(start 138.867896 -277.870412)
		(end 139.334748 -278.13635)
		(width 0.10668)
		(layer "F.Cu")
		(net "M_L_CPU1_SB_DQ<6>")
	)
	(segment
		(start 200.687686 -287.987232)
		(end 200.814178 -288.113724)
		(width 0.14478)
		(layer "In11.Cu")
		(net "M_L_CPU1_SB_DQ<6>")
	)
	(segment
		(start 181.541674 -288.408364)
		(end 181.843934 -288.710624)
		(width 0.14478)
		(layer "In11.Cu")
		(net "M_L_CPU1_SB_DQ<6>")
	)
	(segment
		(start 146.550126 -277.14575)
		(end 147.998434 -277.14575)
		(width 0.0889)
		(layer "In11.Cu")
		(net "M_L_CPU1_SB_DQ<6>")
	)
	(segment
		(start 180.428646 -288.408364)
		(end 180.730906 -288.710624)
		(width 0.14478)
		(layer "In11.Cu")
		(net "M_L_CPU1_SB_DQ<6>")
	)
	(segment
		(start 188.781944 -288.710624)
		(end 189.632082 -287.860486)
		(width 0.14478)
		(layer "In11.Cu")
		(net "M_L_CPU1_SB_DQ<6>")
	)
	(segment
		(start 163.859718 -288.71037)
		(end 164.004498 -288.56559)
		(width 0.14478)
		(layer "In11.Cu")
		(net "M_L_CPU1_SB_DQ<6>")
	)
	(segment
		(start 173.239176 -288.433764)
		(end 173.516036 -288.710624)
		(width 0.14478)
		(layer "In11.Cu")
		(net "M_L_CPU1_SB_DQ<6>")
	)
	(segment
		(start 195.665852 -288.408364)
		(end 195.967858 -288.71037)
		(width 0.14478)
		(layer "In11.Cu")
		(net "M_L_CPU1_SB_DQ<6>")
	)
	(segment
		(start 177.027332 -288.154364)
		(end 177.847498 -288.154364)
		(width 0.14478)
		(layer "In11.Cu")
		(net "M_L_CPU1_SB_DQ<6>")
	)
	(segment
		(start 195.411344 -288.408364)
		(end 195.665852 -288.408364)
		(width 0.14478)
		(layer "In11.Cu")
		(net "M_L_CPU1_SB_DQ<6>")
	)
	(segment
		(start 169.334688 -287.860232)
		(end 170.182032 -287.860232)
		(width 0.14478)
		(layer "In11.Cu")
		(net "M_L_CPU1_SB_DQ<6>")
	)
	(segment
		(start 200.131172 -287.73374)
		(end 200.257664 -287.607248)
		(width 0.14478)
		(layer "In11.Cu")
		(net "M_L_CPU1_SB_DQ<6>")
	)
	(segment
		(start 151.935688 -277.14575)
		(end 163.500308 -288.71037)
		(width 0.14478)
		(layer "In11.Cu")
		(net "M_L_CPU1_SB_DQ<6>")
	)
	(segment
		(start 190.517526 -287.595564)
		(end 190.782448 -287.860486)
		(width 0.14478)
		(layer "In11.Cu")
		(net "M_L_CPU1_SB_DQ<6>")
	)
	(segment
		(start 190.782448 -287.860486)
		(end 191.726312 -287.860486)
		(width 0.14478)
		(layer "In11.Cu")
		(net "M_L_CPU1_SB_DQ<6>")
	)
	(segment
		(start 181.843934 -288.710624)
		(end 182.084218 -288.710624)
		(width 0.14478)
		(layer "In11.Cu")
		(net "M_L_CPU1_SB_DQ<6>")
	)
	(segment
		(start 174.831502 -287.860486)
		(end 175.07458 -288.103564)
		(width 0.14478)
		(layer "In11.Cu")
		(net "M_L_CPU1_SB_DQ<6>")
	)
	(segment
		(start 201.370692 -287.860486)
		(end 201.72299 -287.860486)
		(width 0.14478)
		(layer "In11.Cu")
		(net "M_L_CPU1_SB_DQ<6>")
	)
	(segment
		(start 145.444718 -277.890224)
		(end 145.805652 -277.890224)
		(width 0.0889)
		(layer "In11.Cu")
		(net "M_L_CPU1_SB_DQ<6>")
	)
	(segment
		(start 147.998434 -277.14575)
		(end 151.935688 -277.14575)
		(width 0.14478)
		(layer "In11.Cu")
		(net "M_L_CPU1_SB_DQ<6>")
	)
	(segment
		(start 195.109338 -288.71037)
		(end 195.411344 -288.408364)
		(width 0.14478)
		(layer "In11.Cu")
		(net "M_L_CPU1_SB_DQ<6>")
	)
	(segment
		(start 200.131172 -287.987232)
		(end 200.131172 -287.73374)
		(width 0.14478)
		(layer "In11.Cu")
		(net "M_L_CPU1_SB_DQ<6>")
	)
	(segment
		(start 173.516036 -288.710624)
		(end 173.693836 -288.710624)
		(width 0.14478)
		(layer "In11.Cu")
		(net "M_L_CPU1_SB_DQ<6>")
	)
	(segment
		(start 174.543974 -287.860486)
		(end 174.831502 -287.860486)
		(width 0.14478)
		(layer "In11.Cu")
		(net "M_L_CPU1_SB_DQ<6>")
	)
	(segment
		(start 171.032424 -288.710624)
		(end 172.682662 -288.710624)
		(width 0.14478)
		(layer "In11.Cu")
		(net "M_L_CPU1_SB_DQ<6>")
	)
	(segment
		(start 179.872132 -288.710624)
		(end 180.174392 -288.408364)
		(width 0.14478)
		(layer "In11.Cu")
		(net "M_L_CPU1_SB_DQ<6>")
	)
	(segment
		(start 199.448166 -287.860486)
		(end 199.574658 -287.986978)
		(width 0.14478)
		(layer "In11.Cu")
		(net "M_L_CPU1_SB_DQ<6>")
	)
	(segment
		(start 177.847498 -288.154364)
		(end 178.403758 -288.710624)
		(width 0.14478)
		(layer "In11.Cu")
		(net "M_L_CPU1_SB_DQ<6>")
	)
	(segment
		(start 197.567804 -287.544764)
		(end 197.808596 -287.544764)
		(width 0.14478)
		(layer "In11.Cu")
		(net "M_L_CPU1_SB_DQ<6>")
	)
	(segment
		(start 197.252082 -287.860486)
		(end 197.567804 -287.544764)
		(width 0.14478)
		(layer "In11.Cu")
		(net "M_L_CPU1_SB_DQ<6>")
	)
	(segment
		(start 173.693836 -288.710624)
		(end 174.543974 -287.860486)
		(width 0.14478)
		(layer "In11.Cu")
		(net "M_L_CPU1_SB_DQ<6>")
	)
	(segment
		(start 178.403758 -288.710624)
		(end 179.872132 -288.710624)
		(width 0.14478)
		(layer "In11.Cu")
		(net "M_L_CPU1_SB_DQ<6>")
	)
	(segment
		(start 139.488672 -277.87092)
		(end 139.584684 -277.84552)
		(width 0.0889)
		(layer "In11.Cu")
		(net "M_L_CPU1_SB_DQ<6>")
	)
	(segment
		(start 145.805652 -277.890224)
		(end 146.550126 -277.14575)
		(width 0.0889)
		(layer "In11.Cu")
		(net "M_L_CPU1_SB_DQ<6>")
	)
	(segment
		(start 187.468764 -288.710624)
		(end 187.745624 -288.433764)
		(width 0.14478)
		(layer "In11.Cu")
		(net "M_L_CPU1_SB_DQ<6>")
	)
	(segment
		(start 175.388016 -288.103564)
		(end 175.631094 -287.860486)
		(width 0.14478)
		(layer "In11.Cu")
		(net "M_L_CPU1_SB_DQ<6>")
	)
	(segment
		(start 195.967858 -288.71037)
		(end 196.20992 -288.71037)
		(width 0.14478)
		(layer "In11.Cu")
		(net "M_L_CPU1_SB_DQ<6>")
	)
	(segment
		(start 199.70115 -288.113724)
		(end 200.00468 -288.113724)
		(width 0.14478)
		(layer "In11.Cu")
		(net "M_L_CPU1_SB_DQ<6>")
	)
	(segment
		(start 164.004498 -288.56559)
		(end 164.004498 -288.170366)
		(width 0.14478)
		(layer "In11.Cu")
		(net "M_L_CPU1_SB_DQ<6>")
	)
	(segment
		(start 164.411152 -288.025586)
		(end 164.555932 -288.170366)
		(width 0.14478)
		(layer "In11.Cu")
		(net "M_L_CPU1_SB_DQ<6>")
	)
	(segment
		(start 189.961012 -287.860486)
		(end 190.225934 -287.595564)
		(width 0.14478)
		(layer "In11.Cu")
		(net "M_L_CPU1_SB_DQ<6>")
	)
	(segment
		(start 190.225934 -287.595564)
		(end 190.517526 -287.595564)
		(width 0.14478)
		(layer "In11.Cu")
		(net "M_L_CPU1_SB_DQ<6>")
	)
	(segment
		(start 186.120532 -288.710624)
		(end 187.468764 -288.710624)
		(width 0.14478)
		(layer "In11.Cu")
		(net "M_L_CPU1_SB_DQ<6>")
	)
	(segment
		(start 201.117708 -288.113724)
		(end 201.2442 -287.987232)
		(width 0.14478)
		(layer "In11.Cu")
		(net "M_L_CPU1_SB_DQ<6>")
	)
	(segment
		(start 163.500308 -288.71037)
		(end 163.859718 -288.71037)
		(width 0.14478)
		(layer "In11.Cu")
		(net "M_L_CPU1_SB_DQ<6>")
	)
	(segment
		(start 188.302138 -288.710624)
		(end 188.781944 -288.710624)
		(width 0.14478)
		(layer "In11.Cu")
		(net "M_L_CPU1_SB_DQ<6>")
	)
	(segment
		(start 167.956992 -287.595564)
		(end 168.22166 -287.860232)
		(width 0.14478)
		(layer "In11.Cu")
		(net "M_L_CPU1_SB_DQ<6>")
	)
	(segment
		(start 192.282826 -287.544764)
		(end 193.448432 -288.71037)
		(width 0.14478)
		(layer "In11.Cu")
		(net "M_L_CPU1_SB_DQ<6>")
	)
	(segment
		(start 188.025278 -288.433764)
		(end 188.302138 -288.710624)
		(width 0.14478)
		(layer "In11.Cu")
		(net "M_L_CPU1_SB_DQ<6>")
	)
	(segment
		(start 191.726312 -287.860486)
		(end 192.042034 -287.544764)
		(width 0.14478)
		(layer "In11.Cu")
		(net "M_L_CPU1_SB_DQ<6>")
	)
	(segment
		(start 144.786604 -277.81377)
		(end 144.798288 -277.806912)
		(width 0.0889)
		(layer "In11.Cu")
		(net "M_L_CPU1_SB_DQ<6>")
	)
	(segment
		(start 198.124318 -287.860486)
		(end 199.448166 -287.860486)
		(width 0.14478)
		(layer "In11.Cu")
		(net "M_L_CPU1_SB_DQ<6>")
	)
	(segment
		(start 175.07458 -288.103564)
		(end 175.388016 -288.103564)
		(width 0.14478)
		(layer "In11.Cu")
		(net "M_L_CPU1_SB_DQ<6>")
	)
	(segment
		(start 185.164222 -288.258504)
		(end 185.668412 -288.258504)
		(width 0.14478)
		(layer "In11.Cu")
		(net "M_L_CPU1_SB_DQ<6>")
	)
	(segment
		(start 166.149782 -288.71037)
		(end 166.99992 -287.860232)
		(width 0.14478)
		(layer "In11.Cu")
		(net "M_L_CPU1_SB_DQ<6>")
	)
	(segment
		(start 168.778174 -287.595564)
		(end 169.07002 -287.595564)
		(width 0.14478)
		(layer "In11.Cu")
		(net "M_L_CPU1_SB_DQ<6>")
	)
	(segment
		(start 199.574658 -287.986978)
		(end 199.574658 -287.987232)
		(width 0.14478)
		(layer "In11.Cu")
		(net "M_L_CPU1_SB_DQ<6>")
	)
	(segment
		(start 201.2442 -287.987232)
		(end 201.2442 -287.986978)
		(width 0.14478)
		(layer "In11.Cu")
		(net "M_L_CPU1_SB_DQ<6>")
	)
	(segment
		(start 200.00468 -288.113724)
		(end 200.131172 -287.987232)
		(width 0.14478)
		(layer "In11.Cu")
		(net "M_L_CPU1_SB_DQ<6>")
	)
	(segment
		(start 167.400478 -287.860232)
		(end 167.665146 -287.595564)
		(width 0.14478)
		(layer "In11.Cu")
		(net "M_L_CPU1_SB_DQ<6>")
	)
	(segment
		(start 182.934356 -287.860486)
		(end 183.970168 -287.860486)
		(width 0.14478)
		(layer "In11.Cu")
		(net "M_L_CPU1_SB_DQ<6>")
	)
	(segment
		(start 141.393418 -277.808944)
		(end 141.4018 -277.81377)
		(width 0.0889)
		(layer "In11.Cu")
		(net "M_L_CPU1_SB_DQ<6>")
	)
	(segment
		(start 189.632082 -287.860486)
		(end 189.961012 -287.860486)
		(width 0.14478)
		(layer "In11.Cu")
		(net "M_L_CPU1_SB_DQ<6>")
	)
	(segment
		(start 175.631094 -287.860486)
		(end 176.733454 -287.860486)
		(width 0.14478)
		(layer "In11.Cu")
		(net "M_L_CPU1_SB_DQ<6>")
	)
	(segment
		(start 201.72299 -287.860486)
		(end 202.147932 -288.285428)
		(width 0.14478)
		(layer "In11.Cu")
		(net "M_L_CPU1_SB_DQ<6>")
	)
	(segment
		(start 200.257664 -287.607248)
		(end 200.561194 -287.607248)
		(width 0.14478)
		(layer "In11.Cu")
		(net "M_L_CPU1_SB_DQ<6>")
	)
	(segment
		(start 182.084218 -288.710624)
		(end 182.934356 -287.860486)
		(width 0.14478)
		(layer "In11.Cu")
		(net "M_L_CPU1_SB_DQ<6>")
	)
	(segment
		(start 200.561194 -287.607248)
		(end 200.687686 -287.73374)
		(width 0.14478)
		(layer "In11.Cu")
		(net "M_L_CPU1_SB_DQ<6>")
	)
	(segment
		(start 141.967712 -277.81377)
		(end 141.976094 -277.808944)
		(width 0.0889)
		(layer "In11.Cu")
		(net "M_L_CPU1_SB_DQ<6>")
	)
	(segment
		(start 180.730906 -288.710624)
		(end 180.98516 -288.710624)
		(width 0.14478)
		(layer "In11.Cu")
		(net "M_L_CPU1_SB_DQ<6>")
	)
	(segment
		(start 140.453364 -277.808944)
		(end 140.461746 -277.81377)
		(width 0.0889)
		(layer "In11.Cu")
		(net "M_L_CPU1_SB_DQ<6>")
	)
	(segment
		(start 166.99992 -287.860232)
		(end 167.400478 -287.860232)
		(width 0.14478)
		(layer "In11.Cu")
		(net "M_L_CPU1_SB_DQ<6>")
	)
	(segment
		(start 184.526682 -287.620964)
		(end 185.164222 -288.258504)
		(width 0.14478)
		(layer "In11.Cu")
		(net "M_L_CPU1_SB_DQ<6>")
	)
	(segment
		(start 169.07002 -287.595564)
		(end 169.334688 -287.860232)
		(width 0.14478)
		(layer "In11.Cu")
		(net "M_L_CPU1_SB_DQ<6>")
	)
	(segment
		(start 168.22166 -287.860232)
		(end 168.513506 -287.860232)
		(width 0.14478)
		(layer "In11.Cu")
		(net "M_L_CPU1_SB_DQ<6>")
	)
	(segment
		(start 164.700712 -288.71037)
		(end 166.149782 -288.71037)
		(width 0.14478)
		(layer "In11.Cu")
		(net "M_L_CPU1_SB_DQ<6>")
	)
	(segment
		(start 144.205198 -277.804626)
		(end 144.221454 -277.814024)
		(width 0.0889)
		(layer "In11.Cu")
		(net "M_L_CPU1_SB_DQ<6>")
	)
	(segment
		(start 183.970168 -287.860486)
		(end 184.20969 -287.620964)
		(width 0.14478)
		(layer "In11.Cu")
		(net "M_L_CPU1_SB_DQ<6>")
	)
	(segment
		(start 164.555932 -288.56559)
		(end 164.700712 -288.71037)
		(width 0.14478)
		(layer "In11.Cu")
		(net "M_L_CPU1_SB_DQ<6>")
	)
	(segment
		(start 167.665146 -287.595564)
		(end 167.956992 -287.595564)
		(width 0.14478)
		(layer "In11.Cu")
		(net "M_L_CPU1_SB_DQ<6>")
	)
	(segment
		(start 199.574658 -287.987232)
		(end 199.70115 -288.113724)
		(width 0.14478)
		(layer "In11.Cu")
		(net "M_L_CPU1_SB_DQ<6>")
	)
	(segment
		(start 192.042034 -287.544764)
		(end 192.282826 -287.544764)
		(width 0.14478)
		(layer "In11.Cu")
		(net "M_L_CPU1_SB_DQ<6>")
	)
	(segment
		(start 185.668412 -288.258504)
		(end 186.120532 -288.710624)
		(width 0.14478)
		(layer "In11.Cu")
		(net "M_L_CPU1_SB_DQ<6>")
	)
	(segment
		(start 176.733454 -287.860486)
		(end 177.027332 -288.154364)
		(width 0.14478)
		(layer "In11.Cu")
		(net "M_L_CPU1_SB_DQ<6>")
	)
	(segment
		(start 164.555932 -288.170366)
		(end 164.555932 -288.56559)
		(width 0.14478)
		(layer "In11.Cu")
		(net "M_L_CPU1_SB_DQ<6>")
	)
	(segment
		(start 172.959522 -288.433764)
		(end 173.239176 -288.433764)
		(width 0.14478)
		(layer "In11.Cu")
		(net "M_L_CPU1_SB_DQ<6>")
	)
	(segment
		(start 197.059804 -287.860486)
		(end 197.252082 -287.860486)
		(width 0.14478)
		(layer "In11.Cu")
		(net "M_L_CPU1_SB_DQ<6>")
	)
	(segment
		(start 197.808596 -287.544764)
		(end 198.124318 -287.860486)
		(width 0.14478)
		(layer "In11.Cu")
		(net "M_L_CPU1_SB_DQ<6>")
	)
	(segment
		(start 181.28742 -288.408364)
		(end 181.541674 -288.408364)
		(width 0.14478)
		(layer "In11.Cu")
		(net "M_L_CPU1_SB_DQ<6>")
	)
	(segment
		(start 200.687686 -287.73374)
		(end 200.687686 -287.987232)
		(width 0.14478)
		(layer "In11.Cu")
		(net "M_L_CPU1_SB_DQ<6>")
	)
	(segment
		(start 139.334748 -278.13635)
		(end 139.488672 -277.87092)
		(width 0.0889)
		(layer "In11.Cu")
		(net "M_L_CPU1_SB_DQ<6>")
	)
	(segment
		(start 184.20969 -287.620964)
		(end 184.526682 -287.620964)
		(width 0.14478)
		(layer "In11.Cu")
		(net "M_L_CPU1_SB_DQ<6>")
	)
	(segment
		(start 164.004498 -288.170366)
		(end 164.149278 -288.025586)
		(width 0.14478)
		(layer "In11.Cu")
		(net "M_L_CPU1_SB_DQ<6>")
	)
	(segment
		(start 193.448432 -288.71037)
		(end 195.109338 -288.71037)
		(width 0.14478)
		(layer "In11.Cu")
		(net "M_L_CPU1_SB_DQ<6>")
	)
	(segment
		(start 144.221454 -277.814024)
		(end 144.233392 -277.820882)
		(width 0.0889)
		(layer "In11.Cu")
		(net "M_L_CPU1_SB_DQ<6>")
	)
	(segment
		(start 180.174392 -288.408364)
		(end 180.428646 -288.408364)
		(width 0.14478)
		(layer "In11.Cu")
		(net "M_L_CPU1_SB_DQ<6>")
	)
	(segment
		(start 196.20992 -288.71037)
		(end 197.059804 -287.860486)
		(width 0.14478)
		(layer "In11.Cu")
		(net "M_L_CPU1_SB_DQ<6>")
	)
	(segment
		(start 187.745624 -288.433764)
		(end 188.025278 -288.433764)
		(width 0.14478)
		(layer "In11.Cu")
		(net "M_L_CPU1_SB_DQ<6>")
	)
	(segment
		(start 168.513506 -287.860232)
		(end 168.778174 -287.595564)
		(width 0.14478)
		(layer "In11.Cu")
		(net "M_L_CPU1_SB_DQ<6>")
	)
	(segment
		(start 201.2442 -287.986978)
		(end 201.370692 -287.860486)
		(width 0.14478)
		(layer "In11.Cu")
		(net "M_L_CPU1_SB_DQ<6>")
	)
	(segment
		(start 164.149278 -288.025586)
		(end 164.411152 -288.025586)
		(width 0.14478)
		(layer "In11.Cu")
		(net "M_L_CPU1_SB_DQ<6>")
	)
	(segment
		(start 180.98516 -288.710624)
		(end 181.28742 -288.408364)
		(width 0.14478)
		(layer "In11.Cu")
		(net "M_L_CPU1_SB_DQ<6>")
	)
	(segment
		(start 170.182032 -287.860232)
		(end 171.032424 -288.710624)
		(width 0.14478)
		(layer "In11.Cu")
		(net "M_L_CPU1_SB_DQ<6>")
	)
	(segment
		(start 200.814178 -288.113724)
		(end 201.117708 -288.113724)
		(width 0.14478)
		(layer "In11.Cu")
		(net "M_L_CPU1_SB_DQ<6>")
	)
	(segment
		(start 172.682662 -288.710624)
		(end 172.959522 -288.433764)
		(width 0.14478)
		(layer "In11.Cu")
		(net "M_L_CPU1_SB_DQ<6>")
	)
	(arc
		(start 141.4018 -277.81377)
		(mid 141.684756 -277.889947)
		(end 141.967712 -277.81377)
		(width 0.0889)
		(layer "In11.Cu")
		(net "M_L_CPU1_SB_DQ<6>")
	)
	(arc
		(start 141.027658 -277.81377)
		(mid 141.209909 -277.76342)
		(end 141.393418 -277.808944)
		(width 0.0889)
		(layer "In11.Cu")
		(net "M_L_CPU1_SB_DQ<6>")
	)
	(arc
		(start 143.847566 -277.81377)
		(mid 144.025216 -277.76351)
		(end 144.205198 -277.804626)
		(width 0.0889)
		(layer "In11.Cu")
		(net "M_L_CPU1_SB_DQ<6>")
	)
	(arc
		(start 144.233392 -277.820882)
		(mid 144.510926 -277.889863)
		(end 144.786604 -277.81377)
		(width 0.0889)
		(layer "In11.Cu")
		(net "M_L_CPU1_SB_DQ<6>")
	)
	(arc
		(start 140.461746 -277.81377)
		(mid 140.744702 -277.889947)
		(end 141.027658 -277.81377)
		(width 0.0889)
		(layer "In11.Cu")
		(net "M_L_CPU1_SB_DQ<6>")
	)
	(arc
		(start 145.161 -277.81377)
		(mid 145.297793 -277.870792)
		(end 145.444718 -277.890224)
		(width 0.0889)
		(layer "In11.Cu")
		(net "M_L_CPU1_SB_DQ<6>")
	)
	(arc
		(start 144.798288 -277.806912)
		(mid 144.980543 -277.763259)
		(end 145.161 -277.81377)
		(width 0.0889)
		(layer "In11.Cu")
		(net "M_L_CPU1_SB_DQ<6>")
	)
	(arc
		(start 142.907766 -277.81377)
		(mid 143.09471 -277.763515)
		(end 143.281654 -277.81377)
		(width 0.0889)
		(layer "In11.Cu")
		(net "M_L_CPU1_SB_DQ<6>")
	)
	(arc
		(start 142.341854 -277.81377)
		(mid 142.62481 -277.889947)
		(end 142.907766 -277.81377)
		(width 0.0889)
		(layer "In11.Cu")
		(net "M_L_CPU1_SB_DQ<6>")
	)
	(arc
		(start 143.281654 -277.81377)
		(mid 143.56461 -277.889947)
		(end 143.847566 -277.81377)
		(width 0.0889)
		(layer "In11.Cu")
		(net "M_L_CPU1_SB_DQ<6>")
	)
	(arc
		(start 141.976094 -277.808944)
		(mid 142.159602 -277.76345)
		(end 142.341854 -277.81377)
		(width 0.0889)
		(layer "In11.Cu")
		(net "M_L_CPU1_SB_DQ<6>")
	)
	(arc
		(start 139.584684 -277.84552)
		(mid 139.839892 -277.888997)
		(end 140.087604 -277.81377)
		(width 0.0889)
		(layer "In11.Cu")
		(net "M_L_CPU1_SB_DQ<6>")
	)
	(arc
		(start 140.087604 -277.81377)
		(mid 140.269855 -277.76342)
		(end 140.453364 -277.808944)
		(width 0.0889)
		(layer "In11.Cu")
		(net "M_L_CPU1_SB_DQ<6>")
	)
	(segment
		(start 137.927842 -277.870412)
		(end 138.394694 -278.13635)
		(width 0.10668)
		(layer "F.Cu")
		(net "M_L_CPU1_SB_DQ<5>")
	)
	(segment
		(start 145.150332 -278.465788)
		(end 145.162016 -278.45893)
		(width 0.0889)
		(layer "In11.Cu")
		(net "M_L_CPU1_SB_DQ<5>")
	)
	(segment
		(start 167.093392 -288.710116)
		(end 170.117262 -288.710116)
		(width 0.14478)
		(layer "In11.Cu")
		(net "M_L_CPU1_SB_DQ<5>")
	)
	(segment
		(start 144.777714 -278.452834)
		(end 144.788128 -278.45893)
		(width 0.0889)
		(layer "In11.Cu")
		(net "M_L_CPU1_SB_DQ<5>")
	)
	(segment
		(start 140.453364 -278.463756)
		(end 140.461746 -278.45893)
		(width 0.0889)
		(layer "In11.Cu")
		(net "M_L_CPU1_SB_DQ<5>")
	)
	(segment
		(start 189.724792 -288.710624)
		(end 192.749424 -288.710624)
		(width 0.14478)
		(layer "In11.Cu")
		(net "M_L_CPU1_SB_DQ<5>")
	)
	(segment
		(start 188.874908 -289.560508)
		(end 189.724792 -288.710624)
		(width 0.14478)
		(layer "In11.Cu")
		(net "M_L_CPU1_SB_DQ<5>")
	)
	(segment
		(start 185.076338 -288.710624)
		(end 185.926222 -289.560508)
		(width 0.14478)
		(layer "In11.Cu")
		(net "M_L_CPU1_SB_DQ<5>")
	)
	(segment
		(start 170.967654 -289.560508)
		(end 173.7868 -289.560508)
		(width 0.14478)
		(layer "In11.Cu")
		(net "M_L_CPU1_SB_DQ<5>")
	)
	(segment
		(start 196.906134 -288.71037)
		(end 205.823058 -288.71037)
		(width 0.14478)
		(layer "In11.Cu")
		(net "M_L_CPU1_SB_DQ<5>")
	)
	(segment
		(start 173.7868 -289.560508)
		(end 174.636684 -288.710624)
		(width 0.14478)
		(layer "In11.Cu")
		(net "M_L_CPU1_SB_DQ<5>")
	)
	(segment
		(start 151.74722 -277.60041)
		(end 163.707064 -289.560254)
		(width 0.14478)
		(layer "In11.Cu")
		(net "M_L_CPU1_SB_DQ<5>")
	)
	(segment
		(start 182.749698 -288.710624)
		(end 185.076338 -288.710624)
		(width 0.14478)
		(layer "In11.Cu")
		(net "M_L_CPU1_SB_DQ<5>")
	)
	(segment
		(start 178.5112 -289.560508)
		(end 181.899814 -289.560508)
		(width 0.14478)
		(layer "In11.Cu")
		(net "M_L_CPU1_SB_DQ<5>")
	)
	(segment
		(start 177.661316 -288.710624)
		(end 178.5112 -289.560508)
		(width 0.14478)
		(layer "In11.Cu")
		(net "M_L_CPU1_SB_DQ<5>")
	)
	(segment
		(start 145.444718 -278.382984)
		(end 145.726658 -278.382984)
		(width 0.0889)
		(layer "In11.Cu")
		(net "M_L_CPU1_SB_DQ<5>")
	)
	(segment
		(start 147.37207 -277.441406)
		(end 147.531074 -277.60041)
		(width 0.0889)
		(layer "In11.Cu")
		(net "M_L_CPU1_SB_DQ<5>")
	)
	(segment
		(start 205.823058 -288.71037)
		(end 206.248 -289.135312)
		(width 0.14478)
		(layer "In11.Cu")
		(net "M_L_CPU1_SB_DQ<5>")
	)
	(segment
		(start 138.24077 -278.40178)
		(end 138.263122 -278.485092)
		(width 0.0889)
		(layer "In11.Cu")
		(net "M_L_CPU1_SB_DQ<5>")
	)
	(segment
		(start 163.707064 -289.560254)
		(end 166.243254 -289.560254)
		(width 0.14478)
		(layer "In11.Cu")
		(net "M_L_CPU1_SB_DQ<5>")
	)
	(segment
		(start 174.636684 -288.710624)
		(end 177.661316 -288.710624)
		(width 0.14478)
		(layer "In11.Cu")
		(net "M_L_CPU1_SB_DQ<5>")
	)
	(segment
		(start 145.726658 -278.382984)
		(end 146.668236 -277.441406)
		(width 0.0889)
		(layer "In11.Cu")
		(net "M_L_CPU1_SB_DQ<5>")
	)
	(segment
		(start 141.967712 -278.45893)
		(end 141.976094 -278.463756)
		(width 0.0889)
		(layer "In11.Cu")
		(net "M_L_CPU1_SB_DQ<5>")
	)
	(segment
		(start 192.749424 -288.710624)
		(end 193.599308 -289.560508)
		(width 0.14478)
		(layer "In11.Cu")
		(net "M_L_CPU1_SB_DQ<5>")
	)
	(segment
		(start 185.926222 -289.560508)
		(end 188.874908 -289.560508)
		(width 0.14478)
		(layer "In11.Cu")
		(net "M_L_CPU1_SB_DQ<5>")
	)
	(segment
		(start 147.920202 -277.60041)
		(end 151.74722 -277.60041)
		(width 0.14478)
		(layer "In11.Cu")
		(net "M_L_CPU1_SB_DQ<5>")
	)
	(segment
		(start 193.599308 -289.560508)
		(end 196.055996 -289.560508)
		(width 0.14478)
		(layer "In11.Cu")
		(net "M_L_CPU1_SB_DQ<5>")
	)
	(segment
		(start 147.531074 -277.60041)
		(end 147.920202 -277.60041)
		(width 0.0889)
		(layer "In11.Cu")
		(net "M_L_CPU1_SB_DQ<5>")
	)
	(segment
		(start 181.899814 -289.560508)
		(end 182.749698 -288.710624)
		(width 0.14478)
		(layer "In11.Cu")
		(net "M_L_CPU1_SB_DQ<5>")
	)
	(segment
		(start 138.394694 -278.13635)
		(end 138.24077 -278.40178)
		(width 0.0889)
		(layer "In11.Cu")
		(net "M_L_CPU1_SB_DQ<5>")
	)
	(segment
		(start 146.668236 -277.441406)
		(end 147.37207 -277.441406)
		(width 0.0889)
		(layer "In11.Cu")
		(net "M_L_CPU1_SB_DQ<5>")
	)
	(segment
		(start 196.055996 -289.560508)
		(end 196.906134 -288.71037)
		(width 0.14478)
		(layer "In11.Cu")
		(net "M_L_CPU1_SB_DQ<5>")
	)
	(segment
		(start 166.243254 -289.560254)
		(end 167.093392 -288.710116)
		(width 0.14478)
		(layer "In11.Cu")
		(net "M_L_CPU1_SB_DQ<5>")
	)
	(segment
		(start 170.117262 -288.710116)
		(end 170.967654 -289.560508)
		(width 0.14478)
		(layer "In11.Cu")
		(net "M_L_CPU1_SB_DQ<5>")
	)
	(segment
		(start 141.393418 -278.463756)
		(end 141.4018 -278.45893)
		(width 0.0889)
		(layer "In11.Cu")
		(net "M_L_CPU1_SB_DQ<5>")
	)
	(arc
		(start 143.281654 -278.45893)
		(mid 143.56461 -278.382753)
		(end 143.847566 -278.45893)
		(width 0.0889)
		(layer "In11.Cu")
		(net "M_L_CPU1_SB_DQ<5>")
	)
	(arc
		(start 141.027658 -278.45893)
		(mid 141.209909 -278.50928)
		(end 141.393418 -278.463756)
		(width 0.0889)
		(layer "In11.Cu")
		(net "M_L_CPU1_SB_DQ<5>")
	)
	(arc
		(start 138.581892 -278.45893)
		(mid 138.864848 -278.382753)
		(end 139.147804 -278.45893)
		(width 0.0889)
		(layer "In11.Cu")
		(net "M_L_CPU1_SB_DQ<5>")
	)
	(arc
		(start 144.788128 -278.45893)
		(mid 144.968333 -278.509247)
		(end 145.150332 -278.465788)
		(width 0.0889)
		(layer "In11.Cu")
		(net "M_L_CPU1_SB_DQ<5>")
	)
	(arc
		(start 140.087604 -278.45893)
		(mid 140.269855 -278.50928)
		(end 140.453364 -278.463756)
		(width 0.0889)
		(layer "In11.Cu")
		(net "M_L_CPU1_SB_DQ<5>")
	)
	(arc
		(start 143.847566 -278.45893)
		(mid 144.034764 -278.509312)
		(end 144.221962 -278.45893)
		(width 0.0889)
		(layer "In11.Cu")
		(net "M_L_CPU1_SB_DQ<5>")
	)
	(arc
		(start 142.341854 -278.45893)
		(mid 142.62481 -278.382753)
		(end 142.907766 -278.45893)
		(width 0.0889)
		(layer "In11.Cu")
		(net "M_L_CPU1_SB_DQ<5>")
	)
	(arc
		(start 139.147804 -278.45893)
		(mid 139.334748 -278.509185)
		(end 139.521692 -278.45893)
		(width 0.0889)
		(layer "In11.Cu")
		(net "M_L_CPU1_SB_DQ<5>")
	)
	(arc
		(start 144.221962 -278.45893)
		(mid 144.499029 -278.382659)
		(end 144.777714 -278.452834)
		(width 0.0889)
		(layer "In11.Cu")
		(net "M_L_CPU1_SB_DQ<5>")
	)
	(arc
		(start 139.521692 -278.45893)
		(mid 139.804648 -278.382753)
		(end 140.087604 -278.45893)
		(width 0.0889)
		(layer "In11.Cu")
		(net "M_L_CPU1_SB_DQ<5>")
	)
	(arc
		(start 138.263122 -278.485092)
		(mid 138.425454 -278.50791)
		(end 138.581892 -278.45893)
		(width 0.0889)
		(layer "In11.Cu")
		(net "M_L_CPU1_SB_DQ<5>")
	)
	(arc
		(start 140.461746 -278.45893)
		(mid 140.744702 -278.382753)
		(end 141.027658 -278.45893)
		(width 0.0889)
		(layer "In11.Cu")
		(net "M_L_CPU1_SB_DQ<5>")
	)
	(arc
		(start 141.976094 -278.463756)
		(mid 142.159602 -278.50925)
		(end 142.341854 -278.45893)
		(width 0.0889)
		(layer "In11.Cu")
		(net "M_L_CPU1_SB_DQ<5>")
	)
	(arc
		(start 141.4018 -278.45893)
		(mid 141.684756 -278.382753)
		(end 141.967712 -278.45893)
		(width 0.0889)
		(layer "In11.Cu")
		(net "M_L_CPU1_SB_DQ<5>")
	)
	(arc
		(start 142.907766 -278.45893)
		(mid 143.09471 -278.509185)
		(end 143.281654 -278.45893)
		(width 0.0889)
		(layer "In11.Cu")
		(net "M_L_CPU1_SB_DQ<5>")
	)
	(arc
		(start 145.162016 -278.45893)
		(mid 145.29835 -278.402287)
		(end 145.444718 -278.382984)
		(width 0.0889)
		(layer "In11.Cu")
		(net "M_L_CPU1_SB_DQ<5>")
	)
	(segment
		(start 139.337796 -277.060406)
		(end 139.804648 -277.326344)
		(width 0.10668)
		(layer "F.Cu")
		(net "M_L_CPU1_SB_DQ<4>")
	)
	(segment
		(start 205.39329 -287.010348)
		(end 205.823058 -287.010348)
		(width 0.14478)
		(layer "In11.Cu")
		(net "M_L_CPU1_SB_DQ<4>")
	)
	(segment
		(start 204.673708 -287.813496)
		(end 204.836776 -287.976564)
		(width 0.14478)
		(layer "In11.Cu")
		(net "M_L_CPU1_SB_DQ<4>")
	)
	(segment
		(start 145.617438 -277.699724)
		(end 146.626072 -276.69109)
		(width 0.0889)
		(layer "In11.Cu")
		(net "M_L_CPU1_SB_DQ<4>")
	)
	(segment
		(start 204.836776 -287.976564)
		(end 205.067154 -287.976564)
		(width 0.14478)
		(layer "In11.Cu")
		(net "M_L_CPU1_SB_DQ<4>")
	)
	(segment
		(start 197.095872 -287.019746)
		(end 204.520038 -287.019746)
		(width 0.14478)
		(layer "In11.Cu")
		(net "M_L_CPU1_SB_DQ<4>")
	)
	(segment
		(start 188.86551 -287.869884)
		(end 189.715394 -287.02)
		(width 0.14478)
		(layer "In11.Cu")
		(net "M_L_CPU1_SB_DQ<4>")
	)
	(segment
		(start 205.823058 -287.010348)
		(end 206.248 -287.43529)
		(width 0.14478)
		(layer "In11.Cu")
		(net "M_L_CPU1_SB_DQ<4>")
	)
	(segment
		(start 148.017484 -276.69109)
		(end 152.124156 -276.69109)
		(width 0.14478)
		(layer "In11.Cu")
		(net "M_L_CPU1_SB_DQ<4>")
	)
	(segment
		(start 145.444718 -277.699724)
		(end 145.617438 -277.699724)
		(width 0.0889)
		(layer "In11.Cu")
		(net "M_L_CPU1_SB_DQ<4>")
	)
	(segment
		(start 144.690592 -277.648924)
		(end 144.708626 -277.638256)
		(width 0.0889)
		(layer "In11.Cu")
		(net "M_L_CPU1_SB_DQ<4>")
	)
	(segment
		(start 166.971726 -287.131506)
		(end 170.23842 -287.131506)
		(width 0.14478)
		(layer "In11.Cu")
		(net "M_L_CPU1_SB_DQ<4>")
	)
	(segment
		(start 170.23842 -287.131506)
		(end 170.976798 -287.869884)
		(width 0.14478)
		(layer "In11.Cu")
		(net "M_L_CPU1_SB_DQ<4>")
	)
	(segment
		(start 170.976798 -287.869884)
		(end 173.777402 -287.869884)
		(width 0.14478)
		(layer "In11.Cu")
		(net "M_L_CPU1_SB_DQ<4>")
	)
	(segment
		(start 152.124156 -276.69109)
		(end 162.940492 -287.507426)
		(width 0.14478)
		(layer "In11.Cu")
		(net "M_L_CPU1_SB_DQ<4>")
	)
	(segment
		(start 139.804648 -277.326344)
		(end 139.650724 -277.591774)
		(width 0.0889)
		(layer "In11.Cu")
		(net "M_L_CPU1_SB_DQ<4>")
	)
	(segment
		(start 178.363118 -287.869884)
		(end 181.321456 -287.869884)
		(width 0.14478)
		(layer "In11.Cu")
		(net "M_L_CPU1_SB_DQ<4>")
	)
	(segment
		(start 205.067154 -287.976564)
		(end 205.230222 -287.813496)
		(width 0.14478)
		(layer "In11.Cu")
		(net "M_L_CPU1_SB_DQ<4>")
	)
	(segment
		(start 143.377666 -277.648924)
		(end 143.386048 -277.65375)
		(width 0.0889)
		(layer "In11.Cu")
		(net "M_L_CPU1_SB_DQ<4>")
	)
	(segment
		(start 165.48227 -287.860486)
		(end 166.242746 -287.860486)
		(width 0.14478)
		(layer "In11.Cu")
		(net "M_L_CPU1_SB_DQ<4>")
	)
	(segment
		(start 162.940492 -287.507426)
		(end 165.12921 -287.507426)
		(width 0.14478)
		(layer "In11.Cu")
		(net "M_L_CPU1_SB_DQ<4>")
	)
	(segment
		(start 192.530222 -287.02)
		(end 193.380106 -287.869884)
		(width 0.14478)
		(layer "In11.Cu")
		(net "M_L_CPU1_SB_DQ<4>")
	)
	(segment
		(start 193.380106 -287.869884)
		(end 196.245734 -287.869884)
		(width 0.14478)
		(layer "In11.Cu")
		(net "M_L_CPU1_SB_DQ<4>")
	)
	(segment
		(start 144.30502 -277.641812)
		(end 144.316958 -277.64867)
		(width 0.0889)
		(layer "In11.Cu")
		(net "M_L_CPU1_SB_DQ<4>")
	)
	(segment
		(start 166.242746 -287.860486)
		(end 166.971726 -287.131506)
		(width 0.14478)
		(layer "In11.Cu")
		(net "M_L_CPU1_SB_DQ<4>")
	)
	(segment
		(start 140.557758 -277.648924)
		(end 140.56614 -277.65375)
		(width 0.0889)
		(layer "In11.Cu")
		(net "M_L_CPU1_SB_DQ<4>")
	)
	(segment
		(start 205.230222 -287.173416)
		(end 205.39329 -287.010348)
		(width 0.14478)
		(layer "In11.Cu")
		(net "M_L_CPU1_SB_DQ<4>")
	)
	(segment
		(start 189.715394 -287.02)
		(end 192.530222 -287.02)
		(width 0.14478)
		(layer "In11.Cu")
		(net "M_L_CPU1_SB_DQ<4>")
	)
	(segment
		(start 204.673708 -287.173416)
		(end 204.673708 -287.813496)
		(width 0.14478)
		(layer "In11.Cu")
		(net "M_L_CPU1_SB_DQ<4>")
	)
	(segment
		(start 146.626072 -276.69109)
		(end 148.017484 -276.69109)
		(width 0.0889)
		(layer "In11.Cu")
		(net "M_L_CPU1_SB_DQ<4>")
	)
	(segment
		(start 177.513234 -287.02)
		(end 178.363118 -287.869884)
		(width 0.14478)
		(layer "In11.Cu")
		(net "M_L_CPU1_SB_DQ<4>")
	)
	(segment
		(start 204.520038 -287.019746)
		(end 204.673708 -287.173416)
		(width 0.14478)
		(layer "In11.Cu")
		(net "M_L_CPU1_SB_DQ<4>")
	)
	(segment
		(start 182.17134 -287.02)
		(end 185.062368 -287.02)
		(width 0.14478)
		(layer "In11.Cu")
		(net "M_L_CPU1_SB_DQ<4>")
	)
	(segment
		(start 185.912252 -287.869884)
		(end 188.86551 -287.869884)
		(width 0.14478)
		(layer "In11.Cu")
		(net "M_L_CPU1_SB_DQ<4>")
	)
	(segment
		(start 144.316958 -277.64867)
		(end 144.330674 -277.656544)
		(width 0.0889)
		(layer "In11.Cu")
		(net "M_L_CPU1_SB_DQ<4>")
	)
	(segment
		(start 173.777402 -287.869884)
		(end 174.627286 -287.02)
		(width 0.14478)
		(layer "In11.Cu")
		(net "M_L_CPU1_SB_DQ<4>")
	)
	(segment
		(start 174.627286 -287.02)
		(end 177.513234 -287.02)
		(width 0.14478)
		(layer "In11.Cu")
		(net "M_L_CPU1_SB_DQ<4>")
	)
	(segment
		(start 139.650724 -277.591774)
		(end 139.673076 -277.675086)
		(width 0.0889)
		(layer "In11.Cu")
		(net "M_L_CPU1_SB_DQ<4>")
	)
	(segment
		(start 185.062368 -287.02)
		(end 185.912252 -287.869884)
		(width 0.14478)
		(layer "In11.Cu")
		(net "M_L_CPU1_SB_DQ<4>")
	)
	(segment
		(start 181.321456 -287.869884)
		(end 182.17134 -287.02)
		(width 0.14478)
		(layer "In11.Cu")
		(net "M_L_CPU1_SB_DQ<4>")
	)
	(segment
		(start 196.245734 -287.869884)
		(end 197.095872 -287.019746)
		(width 0.14478)
		(layer "In11.Cu")
		(net "M_L_CPU1_SB_DQ<4>")
	)
	(segment
		(start 165.12921 -287.507426)
		(end 165.48227 -287.860486)
		(width 0.14478)
		(layer "In11.Cu")
		(net "M_L_CPU1_SB_DQ<4>")
	)
	(segment
		(start 205.230222 -287.813496)
		(end 205.230222 -287.173416)
		(width 0.14478)
		(layer "In11.Cu")
		(net "M_L_CPU1_SB_DQ<4>")
	)
	(segment
		(start 142.803372 -277.65375)
		(end 142.811754 -277.648924)
		(width 0.0889)
		(layer "In11.Cu")
		(net "M_L_CPU1_SB_DQ<4>")
	)
	(arc
		(start 142.437612 -277.648924)
		(mid 142.619863 -277.699274)
		(end 142.803372 -277.65375)
		(width 0.0889)
		(layer "In11.Cu")
		(net "M_L_CPU1_SB_DQ<4>")
	)
	(arc
		(start 141.497812 -277.648924)
		(mid 141.684756 -277.699179)
		(end 141.8717 -277.648924)
		(width 0.0889)
		(layer "In11.Cu")
		(net "M_L_CPU1_SB_DQ<4>")
	)
	(arc
		(start 144.708626 -277.638256)
		(mid 144.984321 -277.572413)
		(end 145.257266 -277.648924)
		(width 0.0889)
		(layer "In11.Cu")
		(net "M_L_CPU1_SB_DQ<4>")
	)
	(arc
		(start 140.9319 -277.648924)
		(mid 141.214856 -277.572747)
		(end 141.497812 -277.648924)
		(width 0.0889)
		(layer "In11.Cu")
		(net "M_L_CPU1_SB_DQ<4>")
	)
	(arc
		(start 143.751808 -277.648924)
		(mid 144.027486 -277.572794)
		(end 144.30502 -277.641812)
		(width 0.0889)
		(layer "In11.Cu")
		(net "M_L_CPU1_SB_DQ<4>")
	)
	(arc
		(start 139.991846 -277.648924)
		(mid 140.274802 -277.572747)
		(end 140.557758 -277.648924)
		(width 0.0889)
		(layer "In11.Cu")
		(net "M_L_CPU1_SB_DQ<4>")
	)
	(arc
		(start 143.386048 -277.65375)
		(mid 143.569556 -277.699244)
		(end 143.751808 -277.648924)
		(width 0.0889)
		(layer "In11.Cu")
		(net "M_L_CPU1_SB_DQ<4>")
	)
	(arc
		(start 141.8717 -277.648924)
		(mid 142.154656 -277.572747)
		(end 142.437612 -277.648924)
		(width 0.0889)
		(layer "In11.Cu")
		(net "M_L_CPU1_SB_DQ<4>")
	)
	(arc
		(start 142.811754 -277.648924)
		(mid 143.09471 -277.572747)
		(end 143.377666 -277.648924)
		(width 0.0889)
		(layer "In11.Cu")
		(net "M_L_CPU1_SB_DQ<4>")
	)
	(arc
		(start 145.257266 -277.648924)
		(mid 145.347629 -277.686734)
		(end 145.444718 -277.699724)
		(width 0.0889)
		(layer "In11.Cu")
		(net "M_L_CPU1_SB_DQ<4>")
	)
	(arc
		(start 139.673076 -277.675086)
		(mid 139.835408 -277.697904)
		(end 139.991846 -277.648924)
		(width 0.0889)
		(layer "In11.Cu")
		(net "M_L_CPU1_SB_DQ<4>")
	)
	(arc
		(start 144.330674 -277.656544)
		(mid 144.511604 -277.699022)
		(end 144.690592 -277.648924)
		(width 0.0889)
		(layer "In11.Cu")
		(net "M_L_CPU1_SB_DQ<4>")
	)
	(arc
		(start 140.56614 -277.65375)
		(mid 140.749648 -277.699244)
		(end 140.9319 -277.648924)
		(width 0.0889)
		(layer "In11.Cu")
		(net "M_L_CPU1_SB_DQ<4>")
	)
	(segment
		(start 137.457942 -275.440394)
		(end 137.924794 -275.706332)
		(width 0.10668)
		(layer "F.Cu")
		(net "M_L_CPU1_SB_DQ<3>")
	)
	(segment
		(start 173.605698 -284.451044)
		(end 174.455836 -283.600906)
		(width 0.14478)
		(layer "In11.Cu")
		(net "M_L_CPU1_SB_DQ<3>")
	)
	(segment
		(start 162.32124 -283.026104)
		(end 162.160204 -283.18714)
		(width 0.14478)
		(layer "In11.Cu")
		(net "M_L_CPU1_SB_DQ<3>")
	)
	(segment
		(start 159.173672 -280.43124)
		(end 159.404304 -280.43124)
		(width 0.14478)
		(layer "In11.Cu")
		(net "M_L_CPU1_SB_DQ<3>")
	)
	(segment
		(start 160.35274 -281.057604)
		(end 160.583372 -281.057604)
		(width 0.14478)
		(layer "In11.Cu")
		(net "M_L_CPU1_SB_DQ<3>")
	)
	(segment
		(start 201.280522 -283.600906)
		(end 201.713592 -283.600906)
		(width 0.14478)
		(layer "In11.Cu")
		(net "M_L_CPU1_SB_DQ<3>")
	)
	(segment
		(start 160.585404 -281.61234)
		(end 160.585404 -281.842972)
		(width 0.14478)
		(layer "In11.Cu")
		(net "M_L_CPU1_SB_DQ<3>")
	)
	(segment
		(start 201.135742 -283.745686)
		(end 201.280522 -283.600906)
		(width 0.14478)
		(layer "In11.Cu")
		(net "M_L_CPU1_SB_DQ<3>")
	)
	(segment
		(start 185.260996 -283.600906)
		(end 186.111134 -284.451044)
		(width 0.14478)
		(layer "In11.Cu")
		(net "M_L_CPU1_SB_DQ<3>")
	)
	(segment
		(start 145.444718 -275.33346)
		(end 145.769076 -275.33346)
		(width 0.0889)
		(layer "In11.Cu")
		(net "M_L_CPU1_SB_DQ<3>")
	)
	(segment
		(start 163.64839 -284.103826)
		(end 166.16807 -284.103826)
		(width 0.14478)
		(layer "In11.Cu")
		(net "M_L_CPU1_SB_DQ<3>")
	)
	(segment
		(start 160.74644 -281.220672)
		(end 160.74644 -281.451304)
		(width 0.14478)
		(layer "In11.Cu")
		(net "M_L_CPU1_SB_DQ<3>")
	)
	(segment
		(start 162.160204 -283.417772)
		(end 162.323272 -283.58084)
		(width 0.14478)
		(layer "In11.Cu")
		(net "M_L_CPU1_SB_DQ<3>")
	)
	(segment
		(start 162.964368 -283.419804)
		(end 163.64839 -284.103826)
		(width 0.14478)
		(layer "In11.Cu")
		(net "M_L_CPU1_SB_DQ<3>")
	)
	(segment
		(start 159.56534 -280.270204)
		(end 159.795972 -280.270204)
		(width 0.14478)
		(layer "In11.Cu")
		(net "M_L_CPU1_SB_DQ<3>")
	)
	(segment
		(start 159.798004 -281.055572)
		(end 159.961072 -281.21864)
		(width 0.14478)
		(layer "In11.Cu")
		(net "M_L_CPU1_SB_DQ<3>")
	)
	(segment
		(start 201.713592 -283.600906)
		(end 202.147932 -284.035246)
		(width 0.14478)
		(layer "In11.Cu")
		(net "M_L_CPU1_SB_DQ<3>")
	)
	(segment
		(start 161.535872 -282.79344)
		(end 161.766504 -282.79344)
		(width 0.14478)
		(layer "In11.Cu")
		(net "M_L_CPU1_SB_DQ<3>")
	)
	(segment
		(start 161.370772 -281.845004)
		(end 161.53384 -282.008072)
		(width 0.14478)
		(layer "In11.Cu")
		(net "M_L_CPU1_SB_DQ<3>")
	)
	(segment
		(start 143.751808 -275.383752)
		(end 143.762222 -275.389848)
		(width 0.0889)
		(layer "In11.Cu")
		(net "M_L_CPU1_SB_DQ<3>")
	)
	(segment
		(start 148.054568 -274.303744)
		(end 153.046176 -274.303744)
		(width 0.14478)
		(layer "In11.Cu")
		(net "M_L_CPU1_SB_DQ<3>")
	)
	(segment
		(start 166.67099 -283.600906)
		(end 170.172888 -283.600906)
		(width 0.14478)
		(layer "In11.Cu")
		(net "M_L_CPU1_SB_DQ<3>")
	)
	(segment
		(start 161.372804 -282.630372)
		(end 161.535872 -282.79344)
		(width 0.14478)
		(layer "In11.Cu")
		(net "M_L_CPU1_SB_DQ<3>")
	)
	(segment
		(start 161.372804 -282.39974)
		(end 161.372804 -282.630372)
		(width 0.14478)
		(layer "In11.Cu")
		(net "M_L_CPU1_SB_DQ<3>")
	)
	(segment
		(start 161.14014 -281.845004)
		(end 161.370772 -281.845004)
		(width 0.14478)
		(layer "In11.Cu")
		(net "M_L_CPU1_SB_DQ<3>")
	)
	(segment
		(start 161.766504 -282.79344)
		(end 161.92754 -282.632404)
		(width 0.14478)
		(layer "In11.Cu")
		(net "M_L_CPU1_SB_DQ<3>")
	)
	(segment
		(start 181.149752 -284.451044)
		(end 181.99989 -283.600906)
		(width 0.14478)
		(layer "In11.Cu")
		(net "M_L_CPU1_SB_DQ<3>")
	)
	(segment
		(start 162.158172 -282.632404)
		(end 162.32124 -282.795472)
		(width 0.14478)
		(layer "In11.Cu")
		(net "M_L_CPU1_SB_DQ<3>")
	)
	(segment
		(start 137.924794 -275.706332)
		(end 138.078718 -275.440902)
		(width 0.0889)
		(layer "In11.Cu")
		(net "M_L_CPU1_SB_DQ<3>")
	)
	(segment
		(start 186.111134 -284.451044)
		(end 188.696854 -284.451044)
		(width 0.14478)
		(layer "In11.Cu")
		(net "M_L_CPU1_SB_DQ<3>")
	)
	(segment
		(start 161.53384 -282.008072)
		(end 161.53384 -282.238704)
		(width 0.14478)
		(layer "In11.Cu")
		(net "M_L_CPU1_SB_DQ<3>")
	)
	(segment
		(start 166.16807 -284.103826)
		(end 166.67099 -283.600906)
		(width 0.14478)
		(layer "In11.Cu")
		(net "M_L_CPU1_SB_DQ<3>")
	)
	(segment
		(start 160.585404 -281.842972)
		(end 160.748472 -282.00604)
		(width 0.14478)
		(layer "In11.Cu")
		(net "M_L_CPU1_SB_DQ<3>")
	)
	(segment
		(start 160.74644 -281.451304)
		(end 160.585404 -281.61234)
		(width 0.14478)
		(layer "In11.Cu")
		(net "M_L_CPU1_SB_DQ<3>")
	)
	(segment
		(start 193.655188 -284.451044)
		(end 195.692014 -284.451044)
		(width 0.14478)
		(layer "In11.Cu")
		(net "M_L_CPU1_SB_DQ<3>")
	)
	(segment
		(start 200.584308 -284.030166)
		(end 200.729088 -284.174946)
		(width 0.14478)
		(layer "In11.Cu")
		(net "M_L_CPU1_SB_DQ<3>")
	)
	(segment
		(start 159.795972 -280.270204)
		(end 159.95904 -280.433272)
		(width 0.14478)
		(layer "In11.Cu")
		(net "M_L_CPU1_SB_DQ<3>")
	)
	(segment
		(start 160.191704 -281.21864)
		(end 160.35274 -281.057604)
		(width 0.14478)
		(layer "In11.Cu")
		(net "M_L_CPU1_SB_DQ<3>")
	)
	(segment
		(start 159.95904 -280.433272)
		(end 159.95904 -280.663904)
		(width 0.14478)
		(layer "In11.Cu")
		(net "M_L_CPU1_SB_DQ<3>")
	)
	(segment
		(start 196.542152 -283.600906)
		(end 200.439528 -283.600906)
		(width 0.14478)
		(layer "In11.Cu")
		(net "M_L_CPU1_SB_DQ<3>")
	)
	(segment
		(start 147.752308 -274.303744)
		(end 148.054568 -274.303744)
		(width 0.0889)
		(layer "In11.Cu")
		(net "M_L_CPU1_SB_DQ<3>")
	)
	(segment
		(start 139.617704 -275.383752)
		(end 139.626086 -275.378926)
		(width 0.0889)
		(layer "In11.Cu")
		(net "M_L_CPU1_SB_DQ<3>")
	)
	(segment
		(start 192.80505 -283.600906)
		(end 193.655188 -284.451044)
		(width 0.14478)
		(layer "In11.Cu")
		(net "M_L_CPU1_SB_DQ<3>")
	)
	(segment
		(start 146.92249 -274.180046)
		(end 147.62861 -274.180046)
		(width 0.0889)
		(layer "In11.Cu")
		(net "M_L_CPU1_SB_DQ<3>")
	)
	(segment
		(start 159.961072 -281.21864)
		(end 160.191704 -281.21864)
		(width 0.14478)
		(layer "In11.Cu")
		(net "M_L_CPU1_SB_DQ<3>")
	)
	(segment
		(start 142.803372 -275.378926)
		(end 142.811754 -275.383752)
		(width 0.0889)
		(layer "In11.Cu")
		(net "M_L_CPU1_SB_DQ<3>")
	)
	(segment
		(start 145.769076 -275.33346)
		(end 146.92249 -274.180046)
		(width 0.0889)
		(layer "In11.Cu")
		(net "M_L_CPU1_SB_DQ<3>")
	)
	(segment
		(start 162.160204 -283.18714)
		(end 162.160204 -283.417772)
		(width 0.14478)
		(layer "In11.Cu")
		(net "M_L_CPU1_SB_DQ<3>")
	)
	(segment
		(start 177.716942 -283.600906)
		(end 178.56708 -284.451044)
		(width 0.14478)
		(layer "In11.Cu")
		(net "M_L_CPU1_SB_DQ<3>")
	)
	(segment
		(start 145.247614 -275.389848)
		(end 145.258028 -275.383752)
		(width 0.0889)
		(layer "In11.Cu")
		(net "M_L_CPU1_SB_DQ<3>")
	)
	(segment
		(start 162.323272 -283.58084)
		(end 162.553904 -283.58084)
		(width 0.14478)
		(layer "In11.Cu")
		(net "M_L_CPU1_SB_DQ<3>")
	)
	(segment
		(start 195.692014 -284.451044)
		(end 196.542152 -283.600906)
		(width 0.14478)
		(layer "In11.Cu")
		(net "M_L_CPU1_SB_DQ<3>")
	)
	(segment
		(start 161.53384 -282.238704)
		(end 161.372804 -282.39974)
		(width 0.14478)
		(layer "In11.Cu")
		(net "M_L_CPU1_SB_DQ<3>")
	)
	(segment
		(start 201.135742 -284.030166)
		(end 201.135742 -283.745686)
		(width 0.14478)
		(layer "In11.Cu")
		(net "M_L_CPU1_SB_DQ<3>")
	)
	(segment
		(start 181.99989 -283.600906)
		(end 185.260996 -283.600906)
		(width 0.14478)
		(layer "In11.Cu")
		(net "M_L_CPU1_SB_DQ<3>")
	)
	(segment
		(start 200.729088 -284.174946)
		(end 200.990962 -284.174946)
		(width 0.14478)
		(layer "In11.Cu")
		(net "M_L_CPU1_SB_DQ<3>")
	)
	(segment
		(start 153.046176 -274.303744)
		(end 159.173672 -280.43124)
		(width 0.14478)
		(layer "In11.Cu")
		(net "M_L_CPU1_SB_DQ<3>")
	)
	(segment
		(start 159.95904 -280.663904)
		(end 159.798004 -280.82494)
		(width 0.14478)
		(layer "In11.Cu")
		(net "M_L_CPU1_SB_DQ<3>")
	)
	(segment
		(start 200.584308 -283.745686)
		(end 200.584308 -284.030166)
		(width 0.14478)
		(layer "In11.Cu")
		(net "M_L_CPU1_SB_DQ<3>")
	)
	(segment
		(start 189.546992 -283.600906)
		(end 192.80505 -283.600906)
		(width 0.14478)
		(layer "In11.Cu")
		(net "M_L_CPU1_SB_DQ<3>")
	)
	(segment
		(start 138.078718 -275.440902)
		(end 138.17473 -275.415502)
		(width 0.0889)
		(layer "In11.Cu")
		(net "M_L_CPU1_SB_DQ<3>")
	)
	(segment
		(start 200.439528 -283.600906)
		(end 200.584308 -283.745686)
		(width 0.14478)
		(layer "In11.Cu")
		(net "M_L_CPU1_SB_DQ<3>")
	)
	(segment
		(start 162.71494 -283.419804)
		(end 162.964368 -283.419804)
		(width 0.14478)
		(layer "In11.Cu")
		(net "M_L_CPU1_SB_DQ<3>")
	)
	(segment
		(start 188.696854 -284.451044)
		(end 189.546992 -283.600906)
		(width 0.14478)
		(layer "In11.Cu")
		(net "M_L_CPU1_SB_DQ<3>")
	)
	(segment
		(start 147.62861 -274.180046)
		(end 147.752308 -274.303744)
		(width 0.0889)
		(layer "In11.Cu")
		(net "M_L_CPU1_SB_DQ<3>")
	)
	(segment
		(start 160.583372 -281.057604)
		(end 160.74644 -281.220672)
		(width 0.14478)
		(layer "In11.Cu")
		(net "M_L_CPU1_SB_DQ<3>")
	)
	(segment
		(start 161.92754 -282.632404)
		(end 162.158172 -282.632404)
		(width 0.14478)
		(layer "In11.Cu")
		(net "M_L_CPU1_SB_DQ<3>")
	)
	(segment
		(start 140.557758 -275.383752)
		(end 140.56614 -275.378926)
		(width 0.0889)
		(layer "In11.Cu")
		(net "M_L_CPU1_SB_DQ<3>")
	)
	(segment
		(start 160.748472 -282.00604)
		(end 160.979104 -282.00604)
		(width 0.14478)
		(layer "In11.Cu")
		(net "M_L_CPU1_SB_DQ<3>")
	)
	(segment
		(start 143.377666 -275.383752)
		(end 143.386048 -275.378926)
		(width 0.0889)
		(layer "In11.Cu")
		(net "M_L_CPU1_SB_DQ<3>")
	)
	(segment
		(start 160.979104 -282.00604)
		(end 161.14014 -281.845004)
		(width 0.14478)
		(layer "In11.Cu")
		(net "M_L_CPU1_SB_DQ<3>")
	)
	(segment
		(start 174.455836 -283.600906)
		(end 177.716942 -283.600906)
		(width 0.14478)
		(layer "In11.Cu")
		(net "M_L_CPU1_SB_DQ<3>")
	)
	(segment
		(start 159.404304 -280.43124)
		(end 159.56534 -280.270204)
		(width 0.14478)
		(layer "In11.Cu")
		(net "M_L_CPU1_SB_DQ<3>")
	)
	(segment
		(start 162.32124 -282.795472)
		(end 162.32124 -283.026104)
		(width 0.14478)
		(layer "In11.Cu")
		(net "M_L_CPU1_SB_DQ<3>")
	)
	(segment
		(start 200.990962 -284.174946)
		(end 201.135742 -284.030166)
		(width 0.14478)
		(layer "In11.Cu")
		(net "M_L_CPU1_SB_DQ<3>")
	)
	(segment
		(start 171.023026 -284.451044)
		(end 173.605698 -284.451044)
		(width 0.14478)
		(layer "In11.Cu")
		(net "M_L_CPU1_SB_DQ<3>")
	)
	(segment
		(start 159.798004 -280.82494)
		(end 159.798004 -281.055572)
		(width 0.14478)
		(layer "In11.Cu")
		(net "M_L_CPU1_SB_DQ<3>")
	)
	(segment
		(start 139.04341 -275.378926)
		(end 139.051792 -275.383752)
		(width 0.0889)
		(layer "In11.Cu")
		(net "M_L_CPU1_SB_DQ<3>")
	)
	(segment
		(start 178.56708 -284.451044)
		(end 181.149752 -284.451044)
		(width 0.14478)
		(layer "In11.Cu")
		(net "M_L_CPU1_SB_DQ<3>")
	)
	(segment
		(start 162.553904 -283.58084)
		(end 162.71494 -283.419804)
		(width 0.14478)
		(layer "In11.Cu")
		(net "M_L_CPU1_SB_DQ<3>")
	)
	(segment
		(start 170.172888 -283.600906)
		(end 171.023026 -284.451044)
		(width 0.14478)
		(layer "In11.Cu")
		(net "M_L_CPU1_SB_DQ<3>")
	)
	(arc
		(start 141.8717 -275.383752)
		(mid 142.154656 -275.459929)
		(end 142.437612 -275.383752)
		(width 0.0889)
		(layer "In11.Cu")
		(net "M_L_CPU1_SB_DQ<3>")
	)
	(arc
		(start 142.437612 -275.383752)
		(mid 142.619863 -275.333402)
		(end 142.803372 -275.378926)
		(width 0.0889)
		(layer "In11.Cu")
		(net "M_L_CPU1_SB_DQ<3>")
	)
	(arc
		(start 139.626086 -275.378926)
		(mid 139.809594 -275.333432)
		(end 139.991846 -275.383752)
		(width 0.0889)
		(layer "In11.Cu")
		(net "M_L_CPU1_SB_DQ<3>")
	)
	(arc
		(start 138.17473 -275.415502)
		(mid 138.429938 -275.458979)
		(end 138.67765 -275.383752)
		(width 0.0889)
		(layer "In11.Cu")
		(net "M_L_CPU1_SB_DQ<3>")
	)
	(arc
		(start 140.56614 -275.378926)
		(mid 140.749648 -275.333432)
		(end 140.9319 -275.383752)
		(width 0.0889)
		(layer "In11.Cu")
		(net "M_L_CPU1_SB_DQ<3>")
	)
	(arc
		(start 143.762222 -275.389848)
		(mid 144.040908 -275.460068)
		(end 144.317974 -275.383752)
		(width 0.0889)
		(layer "In11.Cu")
		(net "M_L_CPU1_SB_DQ<3>")
	)
	(arc
		(start 138.67765 -275.383752)
		(mid 138.859901 -275.333402)
		(end 139.04341 -275.378926)
		(width 0.0889)
		(layer "In11.Cu")
		(net "M_L_CPU1_SB_DQ<3>")
	)
	(arc
		(start 140.9319 -275.383752)
		(mid 141.214856 -275.459929)
		(end 141.497812 -275.383752)
		(width 0.0889)
		(layer "In11.Cu")
		(net "M_L_CPU1_SB_DQ<3>")
	)
	(arc
		(start 139.991846 -275.383752)
		(mid 140.274802 -275.459929)
		(end 140.557758 -275.383752)
		(width 0.0889)
		(layer "In11.Cu")
		(net "M_L_CPU1_SB_DQ<3>")
	)
	(arc
		(start 141.497812 -275.383752)
		(mid 141.684756 -275.333497)
		(end 141.8717 -275.383752)
		(width 0.0889)
		(layer "In11.Cu")
		(net "M_L_CPU1_SB_DQ<3>")
	)
	(arc
		(start 139.051792 -275.383752)
		(mid 139.334748 -275.459929)
		(end 139.617704 -275.383752)
		(width 0.0889)
		(layer "In11.Cu")
		(net "M_L_CPU1_SB_DQ<3>")
	)
	(arc
		(start 144.69237 -275.383752)
		(mid 144.969183 -275.459895)
		(end 145.247614 -275.389848)
		(width 0.0889)
		(layer "In11.Cu")
		(net "M_L_CPU1_SB_DQ<3>")
	)
	(arc
		(start 142.811754 -275.383752)
		(mid 143.09471 -275.459929)
		(end 143.377666 -275.383752)
		(width 0.0889)
		(layer "In11.Cu")
		(net "M_L_CPU1_SB_DQ<3>")
	)
	(arc
		(start 145.258028 -275.383752)
		(mid 145.348059 -275.346313)
		(end 145.444718 -275.33346)
		(width 0.0889)
		(layer "In11.Cu")
		(net "M_L_CPU1_SB_DQ<3>")
	)
	(arc
		(start 144.317974 -275.383752)
		(mid 144.505172 -275.33337)
		(end 144.69237 -275.383752)
		(width 0.0889)
		(layer "In11.Cu")
		(net "M_L_CPU1_SB_DQ<3>")
	)
	(arc
		(start 143.386048 -275.378926)
		(mid 143.569556 -275.333432)
		(end 143.751808 -275.383752)
		(width 0.0889)
		(layer "In11.Cu")
		(net "M_L_CPU1_SB_DQ<3>")
	)
	(segment
		(start 139.337796 -293.260272)
		(end 139.804648 -293.52621)
		(width 0.10668)
		(layer "F.Cu")
		(net "M_L_CPU1_SB_DQ<31>")
	)
	(segment
		(start 145.122646 -295.610788)
		(end 145.161762 -295.633648)
		(width 0.0889)
		(layer "In11.Cu")
		(net "M_L_CPU1_SB_DQ<31>")
	)
	(segment
		(start 198.60387 -318.605154)
		(end 198.74865 -318.460374)
		(width 0.14478)
		(layer "In11.Cu")
		(net "M_L_CPU1_SB_DQ<31>")
	)
	(segment
		(start 197.501002 -318.605154)
		(end 197.645782 -318.460374)
		(width 0.14478)
		(layer "In11.Cu")
		(net "M_L_CPU1_SB_DQ<31>")
	)
	(segment
		(start 150.45817 -306.540408)
		(end 161.939986 -318.022224)
		(width 0.14478)
		(layer "In11.Cu")
		(net "M_L_CPU1_SB_DQ<31>")
	)
	(segment
		(start 196.398134 -318.605154)
		(end 196.542914 -318.460374)
		(width 0.14478)
		(layer "In11.Cu")
		(net "M_L_CPU1_SB_DQ<31>")
	)
	(segment
		(start 195.99148 -319.483486)
		(end 196.253354 -319.483486)
		(width 0.14478)
		(layer "In11.Cu")
		(net "M_L_CPU1_SB_DQ<31>")
	)
	(segment
		(start 144.691608 -294.823642)
		(end 144.724374 -294.842692)
		(width 0.0889)
		(layer "In11.Cu")
		(net "M_L_CPU1_SB_DQ<31>")
	)
	(segment
		(start 145.318988 -296.342308)
		(end 145.318988 -296.549572)
		(width 0.0889)
		(layer "In11.Cu")
		(net "M_L_CPU1_SB_DQ<31>")
	)
	(segment
		(start 198.45909 -319.483486)
		(end 198.60387 -319.338706)
		(width 0.14478)
		(layer "In11.Cu")
		(net "M_L_CPU1_SB_DQ<31>")
	)
	(segment
		(start 196.804788 -318.460374)
		(end 196.949568 -318.605154)
		(width 0.14478)
		(layer "In11.Cu")
		(net "M_L_CPU1_SB_DQ<31>")
	)
	(segment
		(start 199.851518 -318.460374)
		(end 201.72299 -318.460374)
		(width 0.14478)
		(layer "In11.Cu")
		(net "M_L_CPU1_SB_DQ<31>")
	)
	(segment
		(start 146.77009 -302.880268)
		(end 148.162772 -304.27295)
		(width 0.14478)
		(layer "In11.Cu")
		(net "M_L_CPU1_SB_DQ<31>")
	)
	(segment
		(start 145.349214 -295.956228)
		(end 145.349214 -296.312082)
		(width 0.0889)
		(layer "In11.Cu")
		(net "M_L_CPU1_SB_DQ<31>")
	)
	(segment
		(start 196.253354 -319.483486)
		(end 196.398134 -319.338706)
		(width 0.14478)
		(layer "In11.Cu")
		(net "M_L_CPU1_SB_DQ<31>")
	)
	(segment
		(start 148.162772 -304.27295)
		(end 148.162772 -305.101498)
		(width 0.14478)
		(layer "In11.Cu")
		(net "M_L_CPU1_SB_DQ<31>")
	)
	(segment
		(start 198.052436 -318.605154)
		(end 198.052436 -319.338706)
		(width 0.14478)
		(layer "In11.Cu")
		(net "M_L_CPU1_SB_DQ<31>")
	)
	(segment
		(start 142.803372 -293.198804)
		(end 142.811754 -293.20363)
		(width 0.0889)
		(layer "In11.Cu")
		(net "M_L_CPU1_SB_DQ<31>")
	)
	(segment
		(start 139.804648 -293.52621)
		(end 140.527278 -293.22141)
		(width 0.0889)
		(layer "In11.Cu")
		(net "M_L_CPU1_SB_DQ<31>")
	)
	(segment
		(start 199.155304 -319.338706)
		(end 199.300084 -319.483486)
		(width 0.14478)
		(layer "In11.Cu")
		(net "M_L_CPU1_SB_DQ<31>")
	)
	(segment
		(start 196.542914 -318.460374)
		(end 196.804788 -318.460374)
		(width 0.14478)
		(layer "In11.Cu")
		(net "M_L_CPU1_SB_DQ<31>")
	)
	(segment
		(start 145.941542 -302.880268)
		(end 146.77009 -302.880268)
		(width 0.14478)
		(layer "In11.Cu")
		(net "M_L_CPU1_SB_DQ<31>")
	)
	(segment
		(start 143.377666 -293.20363)
		(end 143.386048 -293.198804)
		(width 0.0889)
		(layer "In11.Cu")
		(net "M_L_CPU1_SB_DQ<31>")
	)
	(segment
		(start 199.706738 -319.338706)
		(end 199.706738 -318.605154)
		(width 0.14478)
		(layer "In11.Cu")
		(net "M_L_CPU1_SB_DQ<31>")
	)
	(segment
		(start 145.161762 -295.633648)
		(end 145.191226 -295.650666)
		(width 0.0889)
		(layer "In11.Cu")
		(net "M_L_CPU1_SB_DQ<31>")
	)
	(segment
		(start 162.997642 -318.460374)
		(end 195.70192 -318.460374)
		(width 0.14478)
		(layer "In11.Cu")
		(net "M_L_CPU1_SB_DQ<31>")
	)
	(segment
		(start 144.182592 -293.990776)
		(end 144.221708 -294.013636)
		(width 0.0889)
		(layer "In11.Cu")
		(net "M_L_CPU1_SB_DQ<31>")
	)
	(segment
		(start 199.706738 -318.605154)
		(end 199.851518 -318.460374)
		(width 0.14478)
		(layer "In11.Cu")
		(net "M_L_CPU1_SB_DQ<31>")
	)
	(segment
		(start 144.221708 -294.013636)
		(end 144.252188 -294.031416)
		(width 0.0889)
		(layer "In11.Cu")
		(net "M_L_CPU1_SB_DQ<31>")
	)
	(segment
		(start 145.349214 -296.312082)
		(end 145.318988 -296.342308)
		(width 0.0889)
		(layer "In11.Cu")
		(net "M_L_CPU1_SB_DQ<31>")
	)
	(segment
		(start 198.60387 -319.338706)
		(end 198.60387 -318.605154)
		(width 0.14478)
		(layer "In11.Cu")
		(net "M_L_CPU1_SB_DQ<31>")
	)
	(segment
		(start 197.356222 -319.483486)
		(end 197.501002 -319.338706)
		(width 0.14478)
		(layer "In11.Cu")
		(net "M_L_CPU1_SB_DQ<31>")
	)
	(segment
		(start 161.939986 -318.022224)
		(end 162.997642 -318.460374)
		(width 0.14478)
		(layer "In11.Cu")
		(net "M_L_CPU1_SB_DQ<31>")
	)
	(segment
		(start 195.8467 -319.338706)
		(end 195.99148 -319.483486)
		(width 0.14478)
		(layer "In11.Cu")
		(net "M_L_CPU1_SB_DQ<31>")
	)
	(segment
		(start 145.318988 -302.257714)
		(end 145.941542 -302.880268)
		(width 0.14478)
		(layer "In11.Cu")
		(net "M_L_CPU1_SB_DQ<31>")
	)
	(segment
		(start 195.8467 -318.605154)
		(end 195.8467 -319.338706)
		(width 0.14478)
		(layer "In11.Cu")
		(net "M_L_CPU1_SB_DQ<31>")
	)
	(segment
		(start 196.398134 -319.338706)
		(end 196.398134 -318.605154)
		(width 0.14478)
		(layer "In11.Cu")
		(net "M_L_CPU1_SB_DQ<31>")
	)
	(segment
		(start 196.949568 -319.338706)
		(end 197.094348 -319.483486)
		(width 0.14478)
		(layer "In11.Cu")
		(net "M_L_CPU1_SB_DQ<31>")
	)
	(segment
		(start 145.318988 -296.549572)
		(end 145.318988 -302.257714)
		(width 0.14478)
		(layer "In11.Cu")
		(net "M_L_CPU1_SB_DQ<31>")
	)
	(segment
		(start 140.527278 -293.22141)
		(end 140.557758 -293.20363)
		(width 0.0889)
		(layer "In11.Cu")
		(net "M_L_CPU1_SB_DQ<31>")
	)
	(segment
		(start 199.155304 -318.605154)
		(end 199.155304 -319.338706)
		(width 0.14478)
		(layer "In11.Cu")
		(net "M_L_CPU1_SB_DQ<31>")
	)
	(segment
		(start 144.652492 -294.800782)
		(end 144.691608 -294.823642)
		(width 0.0889)
		(layer "In11.Cu")
		(net "M_L_CPU1_SB_DQ<31>")
	)
	(segment
		(start 197.645782 -318.460374)
		(end 197.907656 -318.460374)
		(width 0.14478)
		(layer "In11.Cu")
		(net "M_L_CPU1_SB_DQ<31>")
	)
	(segment
		(start 199.300084 -319.483486)
		(end 199.561958 -319.483486)
		(width 0.14478)
		(layer "In11.Cu")
		(net "M_L_CPU1_SB_DQ<31>")
	)
	(segment
		(start 201.72299 -318.460374)
		(end 202.147932 -318.035432)
		(width 0.14478)
		(layer "In11.Cu")
		(net "M_L_CPU1_SB_DQ<31>")
	)
	(segment
		(start 198.197216 -319.483486)
		(end 198.45909 -319.483486)
		(width 0.14478)
		(layer "In11.Cu")
		(net "M_L_CPU1_SB_DQ<31>")
	)
	(segment
		(start 198.052436 -319.338706)
		(end 198.197216 -319.483486)
		(width 0.14478)
		(layer "In11.Cu")
		(net "M_L_CPU1_SB_DQ<31>")
	)
	(segment
		(start 199.010524 -318.460374)
		(end 199.155304 -318.605154)
		(width 0.14478)
		(layer "In11.Cu")
		(net "M_L_CPU1_SB_DQ<31>")
	)
	(segment
		(start 143.751808 -293.20363)
		(end 143.782288 -293.22141)
		(width 0.0889)
		(layer "In11.Cu")
		(net "M_L_CPU1_SB_DQ<31>")
	)
	(segment
		(start 195.70192 -318.460374)
		(end 195.8467 -318.605154)
		(width 0.14478)
		(layer "In11.Cu")
		(net "M_L_CPU1_SB_DQ<31>")
	)
	(segment
		(start 197.094348 -319.483486)
		(end 197.356222 -319.483486)
		(width 0.14478)
		(layer "In11.Cu")
		(net "M_L_CPU1_SB_DQ<31>")
	)
	(segment
		(start 149.601682 -306.540408)
		(end 150.45817 -306.540408)
		(width 0.14478)
		(layer "In11.Cu")
		(net "M_L_CPU1_SB_DQ<31>")
	)
	(segment
		(start 197.907656 -318.460374)
		(end 198.052436 -318.605154)
		(width 0.14478)
		(layer "In11.Cu")
		(net "M_L_CPU1_SB_DQ<31>")
	)
	(segment
		(start 140.557758 -293.20363)
		(end 140.56614 -293.198804)
		(width 0.0889)
		(layer "In11.Cu")
		(net "M_L_CPU1_SB_DQ<31>")
	)
	(segment
		(start 148.162772 -305.101498)
		(end 149.601682 -306.540408)
		(width 0.14478)
		(layer "In11.Cu")
		(net "M_L_CPU1_SB_DQ<31>")
	)
	(segment
		(start 197.501002 -319.338706)
		(end 197.501002 -318.605154)
		(width 0.14478)
		(layer "In11.Cu")
		(net "M_L_CPU1_SB_DQ<31>")
	)
	(segment
		(start 198.74865 -318.460374)
		(end 199.010524 -318.460374)
		(width 0.14478)
		(layer "In11.Cu")
		(net "M_L_CPU1_SB_DQ<31>")
	)
	(segment
		(start 199.561958 -319.483486)
		(end 199.706738 -319.338706)
		(width 0.14478)
		(layer "In11.Cu")
		(net "M_L_CPU1_SB_DQ<31>")
	)
	(segment
		(start 196.949568 -318.605154)
		(end 196.949568 -319.338706)
		(width 0.14478)
		(layer "In11.Cu")
		(net "M_L_CPU1_SB_DQ<31>")
	)
	(arc
		(start 145.191226 -295.650666)
		(mid 145.307407 -295.784225)
		(end 145.349214 -295.956228)
		(width 0.0889)
		(layer "In11.Cu")
		(net "M_L_CPU1_SB_DQ<31>")
	)
	(arc
		(start 144.879314 -295.146222)
		(mid 144.943829 -295.408441)
		(end 145.122646 -295.610788)
		(width 0.0889)
		(layer "In11.Cu")
		(net "M_L_CPU1_SB_DQ<31>")
	)
	(arc
		(start 144.252188 -294.031416)
		(mid 144.367615 -294.164792)
		(end 144.40916 -294.336216)
		(width 0.0889)
		(layer "In11.Cu")
		(net "M_L_CPU1_SB_DQ<31>")
	)
	(arc
		(start 140.9319 -293.20363)
		(mid 141.214856 -293.279807)
		(end 141.497812 -293.20363)
		(width 0.0889)
		(layer "In11.Cu")
		(net "M_L_CPU1_SB_DQ<31>")
	)
	(arc
		(start 144.40916 -294.336216)
		(mid 144.473675 -294.598435)
		(end 144.652492 -294.800782)
		(width 0.0889)
		(layer "In11.Cu")
		(net "M_L_CPU1_SB_DQ<31>")
	)
	(arc
		(start 143.93926 -293.52621)
		(mid 144.003775 -293.788429)
		(end 144.182592 -293.990776)
		(width 0.0889)
		(layer "In11.Cu")
		(net "M_L_CPU1_SB_DQ<31>")
	)
	(arc
		(start 141.497812 -293.20363)
		(mid 141.684756 -293.153375)
		(end 141.8717 -293.20363)
		(width 0.0889)
		(layer "In11.Cu")
		(net "M_L_CPU1_SB_DQ<31>")
	)
	(arc
		(start 141.8717 -293.20363)
		(mid 142.154656 -293.279807)
		(end 142.437612 -293.20363)
		(width 0.0889)
		(layer "In11.Cu")
		(net "M_L_CPU1_SB_DQ<31>")
	)
	(arc
		(start 143.782288 -293.22141)
		(mid 143.897715 -293.354786)
		(end 143.93926 -293.52621)
		(width 0.0889)
		(layer "In11.Cu")
		(net "M_L_CPU1_SB_DQ<31>")
	)
	(arc
		(start 140.56614 -293.198804)
		(mid 140.749648 -293.15331)
		(end 140.9319 -293.20363)
		(width 0.0889)
		(layer "In11.Cu")
		(net "M_L_CPU1_SB_DQ<31>")
	)
	(arc
		(start 144.724374 -294.842692)
		(mid 144.838303 -294.975839)
		(end 144.879314 -295.146222)
		(width 0.0889)
		(layer "In11.Cu")
		(net "M_L_CPU1_SB_DQ<31>")
	)
	(arc
		(start 142.437612 -293.20363)
		(mid 142.619863 -293.15328)
		(end 142.803372 -293.198804)
		(width 0.0889)
		(layer "In11.Cu")
		(net "M_L_CPU1_SB_DQ<31>")
	)
	(arc
		(start 142.811754 -293.20363)
		(mid 143.09471 -293.279807)
		(end 143.377666 -293.20363)
		(width 0.0889)
		(layer "In11.Cu")
		(net "M_L_CPU1_SB_DQ<31>")
	)
	(arc
		(start 143.386048 -293.198804)
		(mid 143.569556 -293.15331)
		(end 143.751808 -293.20363)
		(width 0.0889)
		(layer "In11.Cu")
		(net "M_L_CPU1_SB_DQ<31>")
	)
	(segment
		(start 138.867896 -292.450266)
		(end 139.334748 -292.716204)
		(width 0.10668)
		(layer "F.Cu")
		(net "M_L_CPU1_SB_DQ<30>")
	)
	(segment
		(start 141.967712 -292.393624)
		(end 141.976094 -292.388798)
		(width 0.0889)
		(layer "In11.Cu")
		(net "M_L_CPU1_SB_DQ<30>")
	)
	(segment
		(start 200.250806 -317.115698)
		(end 200.395586 -316.970918)
		(width 0.14478)
		(layer "In11.Cu")
		(net "M_L_CPU1_SB_DQ<30>")
	)
	(segment
		(start 197.896988 -316.514226)
		(end 197.896988 -316.615572)
		(width 0.14478)
		(layer "In11.Cu")
		(net "M_L_CPU1_SB_DQ<30>")
	)
	(segment
		(start 201.498454 -316.970918)
		(end 201.498454 -316.905132)
		(width 0.14478)
		(layer "In11.Cu")
		(net "M_L_CPU1_SB_DQ<30>")
	)
	(segment
		(start 197.345554 -316.514226)
		(end 197.490334 -316.369446)
		(width 0.14478)
		(layer "In11.Cu")
		(net "M_L_CPU1_SB_DQ<30>")
	)
	(segment
		(start 199.292718 -316.615572)
		(end 199.292718 -316.549786)
		(width 0.14478)
		(layer "In11.Cu")
		(net "M_L_CPU1_SB_DQ<30>")
	)
	(segment
		(start 141.393418 -292.388798)
		(end 141.4018 -292.393624)
		(width 0.0889)
		(layer "In11.Cu")
		(net "M_L_CPU1_SB_DQ<30>")
	)
	(segment
		(start 144.034764 -292.343078)
		(end 144.135348 -292.343078)
		(width 0.0889)
		(layer "In11.Cu")
		(net "M_L_CPU1_SB_DQ<30>")
	)
	(segment
		(start 201.353674 -317.115698)
		(end 201.498454 -316.970918)
		(width 0.14478)
		(layer "In11.Cu")
		(net "M_L_CPU1_SB_DQ<30>")
	)
	(segment
		(start 192.099692 -317.151258)
		(end 192.244472 -317.006478)
		(width 0.14478)
		(layer "In11.Cu")
		(net "M_L_CPU1_SB_DQ<30>")
	)
	(segment
		(start 146.228308 -300.922436)
		(end 162.066224 -316.760352)
		(width 0.14478)
		(layer "In11.Cu")
		(net "M_L_CPU1_SB_DQ<30>")
	)
	(segment
		(start 195.284598 -316.369446)
		(end 195.546472 -316.369446)
		(width 0.14478)
		(layer "In11.Cu")
		(net "M_L_CPU1_SB_DQ<30>")
	)
	(segment
		(start 196.242686 -317.006478)
		(end 196.242686 -316.514226)
		(width 0.14478)
		(layer "In11.Cu")
		(net "M_L_CPU1_SB_DQ<30>")
	)
	(segment
		(start 191.548258 -316.760352)
		(end 191.693038 -316.905132)
		(width 0.14478)
		(layer "In11.Cu")
		(net "M_L_CPU1_SB_DQ<30>")
	)
	(segment
		(start 191.837818 -317.151258)
		(end 192.099692 -317.151258)
		(width 0.14478)
		(layer "In11.Cu")
		(net "M_L_CPU1_SB_DQ<30>")
	)
	(segment
		(start 191.693038 -317.006478)
		(end 191.837818 -317.151258)
		(width 0.14478)
		(layer "In11.Cu")
		(net "M_L_CPU1_SB_DQ<30>")
	)
	(segment
		(start 144.652746 -293.18077)
		(end 144.691862 -293.20363)
		(width 0.0889)
		(layer "In11.Cu")
		(net "M_L_CPU1_SB_DQ<30>")
	)
	(segment
		(start 200.94702 -316.549786)
		(end 200.94702 -316.970918)
		(width 0.14478)
		(layer "In11.Cu")
		(net "M_L_CPU1_SB_DQ<30>")
	)
	(segment
		(start 140.453364 -292.388798)
		(end 140.461746 -292.393624)
		(width 0.0889)
		(layer "In11.Cu")
		(net "M_L_CPU1_SB_DQ<30>")
	)
	(segment
		(start 193.34734 -317.006478)
		(end 193.34734 -316.514226)
		(width 0.14478)
		(layer "In11.Cu")
		(net "M_L_CPU1_SB_DQ<30>")
	)
	(segment
		(start 200.540366 -316.405006)
		(end 200.80224 -316.405006)
		(width 0.14478)
		(layer "In11.Cu")
		(net "M_L_CPU1_SB_DQ<30>")
	)
	(segment
		(start 193.898774 -316.615572)
		(end 194.043554 -316.760352)
		(width 0.14478)
		(layer "In11.Cu")
		(net "M_L_CPU1_SB_DQ<30>")
	)
	(segment
		(start 195.139818 -316.514226)
		(end 195.284598 -316.369446)
		(width 0.14478)
		(layer "In11.Cu")
		(net "M_L_CPU1_SB_DQ<30>")
	)
	(segment
		(start 197.200774 -317.151258)
		(end 197.345554 -317.006478)
		(width 0.14478)
		(layer "In11.Cu")
		(net "M_L_CPU1_SB_DQ<30>")
	)
	(segment
		(start 195.691252 -316.514226)
		(end 195.691252 -317.006478)
		(width 0.14478)
		(layer "In11.Cu")
		(net "M_L_CPU1_SB_DQ<30>")
	)
	(segment
		(start 193.34734 -316.514226)
		(end 193.49212 -316.369446)
		(width 0.14478)
		(layer "In11.Cu")
		(net "M_L_CPU1_SB_DQ<30>")
	)
	(segment
		(start 199.844152 -316.970918)
		(end 199.988932 -317.115698)
		(width 0.14478)
		(layer "In11.Cu")
		(net "M_L_CPU1_SB_DQ<30>")
	)
	(segment
		(start 196.097906 -317.151258)
		(end 196.242686 -317.006478)
		(width 0.14478)
		(layer "In11.Cu")
		(net "M_L_CPU1_SB_DQ<30>")
	)
	(segment
		(start 191.693038 -316.905132)
		(end 191.693038 -317.006478)
		(width 0.14478)
		(layer "In11.Cu")
		(net "M_L_CPU1_SB_DQ<30>")
	)
	(segment
		(start 198.041768 -316.760352)
		(end 199.147938 -316.760352)
		(width 0.14478)
		(layer "In11.Cu")
		(net "M_L_CPU1_SB_DQ<30>")
	)
	(segment
		(start 144.691862 -293.20363)
		(end 144.722342 -293.22141)
		(width 0.0889)
		(layer "In11.Cu")
		(net "M_L_CPU1_SB_DQ<30>")
	)
	(segment
		(start 197.896988 -316.615572)
		(end 198.041768 -316.760352)
		(width 0.14478)
		(layer "In11.Cu")
		(net "M_L_CPU1_SB_DQ<30>")
	)
	(segment
		(start 145.161762 -294.013636)
		(end 145.192242 -294.031416)
		(width 0.0889)
		(layer "In11.Cu")
		(net "M_L_CPU1_SB_DQ<30>")
	)
	(segment
		(start 145.663412 -294.84193)
		(end 146.228308 -295.406826)
		(width 0.0889)
		(layer "In11.Cu")
		(net "M_L_CPU1_SB_DQ<30>")
	)
	(segment
		(start 145.592546 -294.800782)
		(end 145.631662 -294.823642)
		(width 0.0889)
		(layer "In11.Cu")
		(net "M_L_CPU1_SB_DQ<30>")
	)
	(segment
		(start 146.228308 -296.45102)
		(end 146.228308 -300.922436)
		(width 0.14478)
		(layer "In11.Cu")
		(net "M_L_CPU1_SB_DQ<30>")
	)
	(segment
		(start 192.244472 -317.006478)
		(end 192.244472 -316.514226)
		(width 0.14478)
		(layer "In11.Cu")
		(net "M_L_CPU1_SB_DQ<30>")
	)
	(segment
		(start 199.988932 -317.115698)
		(end 200.250806 -317.115698)
		(width 0.14478)
		(layer "In11.Cu")
		(net "M_L_CPU1_SB_DQ<30>")
	)
	(segment
		(start 162.066224 -316.760352)
		(end 191.548258 -316.760352)
		(width 0.14478)
		(layer "In11.Cu")
		(net "M_L_CPU1_SB_DQ<30>")
	)
	(segment
		(start 199.844152 -316.549786)
		(end 199.844152 -316.970918)
		(width 0.14478)
		(layer "In11.Cu")
		(net "M_L_CPU1_SB_DQ<30>")
	)
	(segment
		(start 194.043554 -316.760352)
		(end 194.995038 -316.760352)
		(width 0.14478)
		(layer "In11.Cu")
		(net "M_L_CPU1_SB_DQ<30>")
	)
	(segment
		(start 201.0918 -317.115698)
		(end 201.353674 -317.115698)
		(width 0.14478)
		(layer "In11.Cu")
		(net "M_L_CPU1_SB_DQ<30>")
	)
	(segment
		(start 199.147938 -316.760352)
		(end 199.292718 -316.615572)
		(width 0.14478)
		(layer "In11.Cu")
		(net "M_L_CPU1_SB_DQ<30>")
	)
	(segment
		(start 196.242686 -316.514226)
		(end 196.387466 -316.369446)
		(width 0.14478)
		(layer "In11.Cu")
		(net "M_L_CPU1_SB_DQ<30>")
	)
	(segment
		(start 193.898774 -316.514226)
		(end 193.898774 -316.615572)
		(width 0.14478)
		(layer "In11.Cu")
		(net "M_L_CPU1_SB_DQ<30>")
	)
	(segment
		(start 199.292718 -316.549786)
		(end 199.437498 -316.405006)
		(width 0.14478)
		(layer "In11.Cu")
		(net "M_L_CPU1_SB_DQ<30>")
	)
	(segment
		(start 192.389252 -316.369446)
		(end 192.651126 -316.369446)
		(width 0.14478)
		(layer "In11.Cu")
		(net "M_L_CPU1_SB_DQ<30>")
	)
	(segment
		(start 145.122646 -293.990776)
		(end 145.161762 -294.013636)
		(width 0.0889)
		(layer "In11.Cu")
		(net "M_L_CPU1_SB_DQ<30>")
	)
	(segment
		(start 192.795906 -316.514226)
		(end 192.795906 -317.006478)
		(width 0.14478)
		(layer "In11.Cu")
		(net "M_L_CPU1_SB_DQ<30>")
	)
	(segment
		(start 193.753994 -316.369446)
		(end 193.898774 -316.514226)
		(width 0.14478)
		(layer "In11.Cu")
		(net "M_L_CPU1_SB_DQ<30>")
	)
	(segment
		(start 192.651126 -316.369446)
		(end 192.795906 -316.514226)
		(width 0.14478)
		(layer "In11.Cu")
		(net "M_L_CPU1_SB_DQ<30>")
	)
	(segment
		(start 201.643234 -316.760352)
		(end 201.72299 -316.760352)
		(width 0.14478)
		(layer "In11.Cu")
		(net "M_L_CPU1_SB_DQ<30>")
	)
	(segment
		(start 201.498454 -316.905132)
		(end 201.643234 -316.760352)
		(width 0.14478)
		(layer "In11.Cu")
		(net "M_L_CPU1_SB_DQ<30>")
	)
	(segment
		(start 200.94702 -316.970918)
		(end 201.0918 -317.115698)
		(width 0.14478)
		(layer "In11.Cu")
		(net "M_L_CPU1_SB_DQ<30>")
	)
	(segment
		(start 196.387466 -316.369446)
		(end 196.64934 -316.369446)
		(width 0.14478)
		(layer "In11.Cu")
		(net "M_L_CPU1_SB_DQ<30>")
	)
	(segment
		(start 196.79412 -317.006478)
		(end 196.9389 -317.151258)
		(width 0.14478)
		(layer "In11.Cu")
		(net "M_L_CPU1_SB_DQ<30>")
	)
	(segment
		(start 196.9389 -317.151258)
		(end 197.200774 -317.151258)
		(width 0.14478)
		(layer "In11.Cu")
		(net "M_L_CPU1_SB_DQ<30>")
	)
	(segment
		(start 201.72299 -316.760352)
		(end 202.147932 -316.33541)
		(width 0.14478)
		(layer "In11.Cu")
		(net "M_L_CPU1_SB_DQ<30>")
	)
	(segment
		(start 192.940686 -317.151258)
		(end 193.20256 -317.151258)
		(width 0.14478)
		(layer "In11.Cu")
		(net "M_L_CPU1_SB_DQ<30>")
	)
	(segment
		(start 193.20256 -317.151258)
		(end 193.34734 -317.006478)
		(width 0.14478)
		(layer "In11.Cu")
		(net "M_L_CPU1_SB_DQ<30>")
	)
	(segment
		(start 199.699372 -316.405006)
		(end 199.844152 -316.549786)
		(width 0.14478)
		(layer "In11.Cu")
		(net "M_L_CPU1_SB_DQ<30>")
	)
	(segment
		(start 139.334748 -292.716204)
		(end 139.488672 -292.450774)
		(width 0.0889)
		(layer "In11.Cu")
		(net "M_L_CPU1_SB_DQ<30>")
	)
	(segment
		(start 200.395586 -316.970918)
		(end 200.395586 -316.549786)
		(width 0.14478)
		(layer "In11.Cu")
		(net "M_L_CPU1_SB_DQ<30>")
	)
	(segment
		(start 139.488672 -292.450774)
		(end 139.584684 -292.425374)
		(width 0.0889)
		(layer "In11.Cu")
		(net "M_L_CPU1_SB_DQ<30>")
	)
	(segment
		(start 192.244472 -316.514226)
		(end 192.389252 -316.369446)
		(width 0.14478)
		(layer "In11.Cu")
		(net "M_L_CPU1_SB_DQ<30>")
	)
	(segment
		(start 192.795906 -317.006478)
		(end 192.940686 -317.151258)
		(width 0.14478)
		(layer "In11.Cu")
		(net "M_L_CPU1_SB_DQ<30>")
	)
	(segment
		(start 145.631662 -294.823642)
		(end 145.663412 -294.84193)
		(width 0.0889)
		(layer "In11.Cu")
		(net "M_L_CPU1_SB_DQ<30>")
	)
	(segment
		(start 144.135348 -292.343078)
		(end 144.221962 -292.393624)
		(width 0.0889)
		(layer "In11.Cu")
		(net "M_L_CPU1_SB_DQ<30>")
	)
	(segment
		(start 200.395586 -316.549786)
		(end 200.540366 -316.405006)
		(width 0.14478)
		(layer "In11.Cu")
		(net "M_L_CPU1_SB_DQ<30>")
	)
	(segment
		(start 196.79412 -316.514226)
		(end 196.79412 -317.006478)
		(width 0.14478)
		(layer "In11.Cu")
		(net "M_L_CPU1_SB_DQ<30>")
	)
	(segment
		(start 197.490334 -316.369446)
		(end 197.752208 -316.369446)
		(width 0.14478)
		(layer "In11.Cu")
		(net "M_L_CPU1_SB_DQ<30>")
	)
	(segment
		(start 195.836032 -317.151258)
		(end 196.097906 -317.151258)
		(width 0.14478)
		(layer "In11.Cu")
		(net "M_L_CPU1_SB_DQ<30>")
	)
	(segment
		(start 200.80224 -316.405006)
		(end 200.94702 -316.549786)
		(width 0.14478)
		(layer "In11.Cu")
		(net "M_L_CPU1_SB_DQ<30>")
	)
	(segment
		(start 144.221962 -292.393624)
		(end 144.252442 -292.411404)
		(width 0.0889)
		(layer "In11.Cu")
		(net "M_L_CPU1_SB_DQ<30>")
	)
	(segment
		(start 197.345554 -317.006478)
		(end 197.345554 -316.514226)
		(width 0.14478)
		(layer "In11.Cu")
		(net "M_L_CPU1_SB_DQ<30>")
	)
	(segment
		(start 196.64934 -316.369446)
		(end 196.79412 -316.514226)
		(width 0.14478)
		(layer "In11.Cu")
		(net "M_L_CPU1_SB_DQ<30>")
	)
	(segment
		(start 195.139818 -316.615572)
		(end 195.139818 -316.514226)
		(width 0.14478)
		(layer "In11.Cu")
		(net "M_L_CPU1_SB_DQ<30>")
	)
	(segment
		(start 197.752208 -316.369446)
		(end 197.896988 -316.514226)
		(width 0.14478)
		(layer "In11.Cu")
		(net "M_L_CPU1_SB_DQ<30>")
	)
	(segment
		(start 199.437498 -316.405006)
		(end 199.699372 -316.405006)
		(width 0.14478)
		(layer "In11.Cu")
		(net "M_L_CPU1_SB_DQ<30>")
	)
	(segment
		(start 195.546472 -316.369446)
		(end 195.691252 -316.514226)
		(width 0.14478)
		(layer "In11.Cu")
		(net "M_L_CPU1_SB_DQ<30>")
	)
	(segment
		(start 194.995038 -316.760352)
		(end 195.139818 -316.615572)
		(width 0.14478)
		(layer "In11.Cu")
		(net "M_L_CPU1_SB_DQ<30>")
	)
	(segment
		(start 195.691252 -317.006478)
		(end 195.836032 -317.151258)
		(width 0.14478)
		(layer "In11.Cu")
		(net "M_L_CPU1_SB_DQ<30>")
	)
	(segment
		(start 146.228308 -295.406826)
		(end 146.228308 -296.45102)
		(width 0.0889)
		(layer "In11.Cu")
		(net "M_L_CPU1_SB_DQ<30>")
	)
	(segment
		(start 193.49212 -316.369446)
		(end 193.753994 -316.369446)
		(width 0.14478)
		(layer "In11.Cu")
		(net "M_L_CPU1_SB_DQ<30>")
	)
	(arc
		(start 142.341854 -292.393624)
		(mid 142.62481 -292.469801)
		(end 142.907766 -292.393624)
		(width 0.0889)
		(layer "In11.Cu")
		(net "M_L_CPU1_SB_DQ<30>")
	)
	(arc
		(start 145.192242 -294.031416)
		(mid 145.307669 -294.164792)
		(end 145.349214 -294.336216)
		(width 0.0889)
		(layer "In11.Cu")
		(net "M_L_CPU1_SB_DQ<30>")
	)
	(arc
		(start 141.976094 -292.388798)
		(mid 142.159602 -292.343304)
		(end 142.341854 -292.393624)
		(width 0.0889)
		(layer "In11.Cu")
		(net "M_L_CPU1_SB_DQ<30>")
	)
	(arc
		(start 140.461746 -292.393624)
		(mid 140.744702 -292.469801)
		(end 141.027658 -292.393624)
		(width 0.0889)
		(layer "In11.Cu")
		(net "M_L_CPU1_SB_DQ<30>")
	)
	(arc
		(start 145.349214 -294.336216)
		(mid 145.413729 -294.598435)
		(end 145.592546 -294.800782)
		(width 0.0889)
		(layer "In11.Cu")
		(net "M_L_CPU1_SB_DQ<30>")
	)
	(arc
		(start 139.584684 -292.425374)
		(mid 139.839892 -292.468851)
		(end 140.087604 -292.393624)
		(width 0.0889)
		(layer "In11.Cu")
		(net "M_L_CPU1_SB_DQ<30>")
	)
	(arc
		(start 144.252442 -292.411404)
		(mid 144.367869 -292.54478)
		(end 144.409414 -292.716204)
		(width 0.0889)
		(layer "In11.Cu")
		(net "M_L_CPU1_SB_DQ<30>")
	)
	(arc
		(start 141.4018 -292.393624)
		(mid 141.684756 -292.469801)
		(end 141.967712 -292.393624)
		(width 0.0889)
		(layer "In11.Cu")
		(net "M_L_CPU1_SB_DQ<30>")
	)
	(arc
		(start 143.847566 -292.393624)
		(mid 143.937826 -292.355996)
		(end 144.034764 -292.343078)
		(width 0.0889)
		(layer "In11.Cu")
		(net "M_L_CPU1_SB_DQ<30>")
	)
	(arc
		(start 144.409414 -292.716204)
		(mid 144.473929 -292.978423)
		(end 144.652746 -293.18077)
		(width 0.0889)
		(layer "In11.Cu")
		(net "M_L_CPU1_SB_DQ<30>")
	)
	(arc
		(start 144.722342 -293.22141)
		(mid 144.837769 -293.354786)
		(end 144.879314 -293.52621)
		(width 0.0889)
		(layer "In11.Cu")
		(net "M_L_CPU1_SB_DQ<30>")
	)
	(arc
		(start 144.879314 -293.52621)
		(mid 144.943829 -293.788429)
		(end 145.122646 -293.990776)
		(width 0.0889)
		(layer "In11.Cu")
		(net "M_L_CPU1_SB_DQ<30>")
	)
	(arc
		(start 141.027658 -292.393624)
		(mid 141.209909 -292.343274)
		(end 141.393418 -292.388798)
		(width 0.0889)
		(layer "In11.Cu")
		(net "M_L_CPU1_SB_DQ<30>")
	)
	(arc
		(start 142.907766 -292.393624)
		(mid 143.09471 -292.343369)
		(end 143.281654 -292.393624)
		(width 0.0889)
		(layer "In11.Cu")
		(net "M_L_CPU1_SB_DQ<30>")
	)
	(arc
		(start 140.087604 -292.393624)
		(mid 140.269855 -292.343274)
		(end 140.453364 -292.388798)
		(width 0.0889)
		(layer "In11.Cu")
		(net "M_L_CPU1_SB_DQ<30>")
	)
	(arc
		(start 143.281654 -292.393624)
		(mid 143.56461 -292.469801)
		(end 143.847566 -292.393624)
		(width 0.0889)
		(layer "In11.Cu")
		(net "M_L_CPU1_SB_DQ<30>")
	)
	(segment
		(start 138.867896 -274.630388)
		(end 139.334748 -274.896326)
		(width 0.10668)
		(layer "F.Cu")
		(net "M_L_CPU1_SB_DQ<2>")
	)
	(segment
		(start 141.967712 -274.573746)
		(end 141.976094 -274.56892)
		(width 0.0889)
		(layer "In11.Cu")
		(net "M_L_CPU1_SB_DQ<2>")
	)
	(segment
		(start 155.881832 -275.033994)
		(end 156.0449 -275.197062)
		(width 0.14478)
		(layer "In11.Cu")
		(net "M_L_CPU1_SB_DQ<2>")
	)
	(segment
		(start 159.1945 -278.346662)
		(end 159.1945 -278.577294)
		(width 0.14478)
		(layer "In11.Cu")
		(net "M_L_CPU1_SB_DQ<2>")
	)
	(segment
		(start 192.814448 -281.910282)
		(end 193.664586 -282.76042)
		(width 0.14478)
		(layer "In11.Cu")
		(net "M_L_CPU1_SB_DQ<2>")
	)
	(segment
		(start 157.837124 -277.57247)
		(end 158.0134 -277.396194)
		(width 0.14478)
		(layer "In11.Cu")
		(net "M_L_CPU1_SB_DQ<2>")
	)
	(segment
		(start 158.4071 -277.559262)
		(end 158.4071 -277.789894)
		(width 0.14478)
		(layer "In11.Cu")
		(net "M_L_CPU1_SB_DQ<2>")
	)
	(segment
		(start 155.868624 -275.60397)
		(end 155.868624 -275.834602)
		(width 0.14478)
		(layer "In11.Cu")
		(net "M_L_CPU1_SB_DQ<2>")
	)
	(segment
		(start 159.411924 -279.14727)
		(end 159.5882 -278.970994)
		(width 0.14478)
		(layer "In11.Cu")
		(net "M_L_CPU1_SB_DQ<2>")
	)
	(segment
		(start 154.687524 -274.42287)
		(end 154.8638 -274.246594)
		(width 0.14478)
		(layer "In11.Cu")
		(net "M_L_CPU1_SB_DQ<2>")
	)
	(segment
		(start 155.244292 -275.21027)
		(end 155.474924 -275.21027)
		(width 0.14478)
		(layer "In11.Cu")
		(net "M_L_CPU1_SB_DQ<2>")
	)
	(segment
		(start 157.456632 -276.608794)
		(end 157.6197 -276.771862)
		(width 0.14478)
		(layer "In11.Cu")
		(net "M_L_CPU1_SB_DQ<2>")
	)
	(segment
		(start 169.20337 -281.626564)
		(end 169.476166 -281.626564)
		(width 0.14478)
		(layer "In11.Cu")
		(net "M_L_CPU1_SB_DQ<2>")
	)
	(segment
		(start 159.5882 -278.970994)
		(end 159.818832 -278.970994)
		(width 0.14478)
		(layer "In11.Cu")
		(net "M_L_CPU1_SB_DQ<2>")
	)
	(segment
		(start 157.606492 -277.57247)
		(end 157.837124 -277.57247)
		(width 0.14478)
		(layer "In11.Cu")
		(net "M_L_CPU1_SB_DQ<2>")
	)
	(segment
		(start 170.182286 -281.910282)
		(end 171.032424 -282.76042)
		(width 0.14478)
		(layer "In11.Cu")
		(net "M_L_CPU1_SB_DQ<2>")
	)
	(segment
		(start 157.049724 -276.78507)
		(end 157.226 -276.608794)
		(width 0.14478)
		(layer "In11.Cu")
		(net "M_L_CPU1_SB_DQ<2>")
	)
	(segment
		(start 178.576478 -282.76042)
		(end 181.23789 -282.76042)
		(width 0.14478)
		(layer "In11.Cu")
		(net "M_L_CPU1_SB_DQ<2>")
	)
	(segment
		(start 154.293824 -274.02917)
		(end 154.293824 -274.259802)
		(width 0.14478)
		(layer "In11.Cu")
		(net "M_L_CPU1_SB_DQ<2>")
	)
	(segment
		(start 158.4071 -277.789894)
		(end 158.230824 -277.96617)
		(width 0.14478)
		(layer "In11.Cu")
		(net "M_L_CPU1_SB_DQ<2>")
	)
	(segment
		(start 173.693836 -282.76042)
		(end 174.543974 -281.910282)
		(width 0.14478)
		(layer "In11.Cu")
		(net "M_L_CPU1_SB_DQ<2>")
	)
	(segment
		(start 139.334748 -274.896326)
		(end 139.488672 -274.630896)
		(width 0.0889)
		(layer "In11.Cu")
		(net "M_L_CPU1_SB_DQ<2>")
	)
	(segment
		(start 182.088028 -281.910282)
		(end 185.270394 -281.910282)
		(width 0.14478)
		(layer "In11.Cu")
		(net "M_L_CPU1_SB_DQ<2>")
	)
	(segment
		(start 155.094432 -274.246594)
		(end 155.2575 -274.409662)
		(width 0.14478)
		(layer "In11.Cu")
		(net "M_L_CPU1_SB_DQ<2>")
	)
	(segment
		(start 144.221454 -274.574)
		(end 144.233392 -274.580858)
		(width 0.0889)
		(layer "In11.Cu")
		(net "M_L_CPU1_SB_DQ<2>")
	)
	(segment
		(start 158.8008 -278.183594)
		(end 159.031432 -278.183594)
		(width 0.14478)
		(layer "In11.Cu")
		(net "M_L_CPU1_SB_DQ<2>")
	)
	(segment
		(start 155.2575 -274.640294)
		(end 155.081224 -274.81657)
		(width 0.14478)
		(layer "In11.Cu")
		(net "M_L_CPU1_SB_DQ<2>")
	)
	(segment
		(start 158.393892 -278.35987)
		(end 158.624524 -278.35987)
		(width 0.14478)
		(layer "In11.Cu")
		(net "M_L_CPU1_SB_DQ<2>")
	)
	(segment
		(start 174.543974 -281.910282)
		(end 177.72634 -281.910282)
		(width 0.14478)
		(layer "In11.Cu")
		(net "M_L_CPU1_SB_DQ<2>")
	)
	(segment
		(start 201.72299 -281.910282)
		(end 202.147932 -282.335224)
		(width 0.14478)
		(layer "In11.Cu")
		(net "M_L_CPU1_SB_DQ<2>")
	)
	(segment
		(start 154.242262 -273.394424)
		(end 154.4701 -273.622262)
		(width 0.14478)
		(layer "In11.Cu")
		(net "M_L_CPU1_SB_DQ<2>")
	)
	(segment
		(start 156.0449 -275.197062)
		(end 156.0449 -275.427694)
		(width 0.14478)
		(layer "In11.Cu")
		(net "M_L_CPU1_SB_DQ<2>")
	)
	(segment
		(start 163.608258 -282.76042)
		(end 166.123874 -282.76042)
		(width 0.14478)
		(layer "In11.Cu")
		(net "M_L_CPU1_SB_DQ<2>")
	)
	(segment
		(start 156.656024 -276.39137)
		(end 156.656024 -276.622002)
		(width 0.14478)
		(layer "In11.Cu")
		(net "M_L_CPU1_SB_DQ<2>")
	)
	(segment
		(start 146.73707 -273.616166)
		(end 147.29841 -273.616166)
		(width 0.0889)
		(layer "In11.Cu")
		(net "M_L_CPU1_SB_DQ<2>")
	)
	(segment
		(start 166.123874 -282.76042)
		(end 166.974012 -281.910282)
		(width 0.14478)
		(layer "In11.Cu")
		(net "M_L_CPU1_SB_DQ<2>")
	)
	(segment
		(start 158.230824 -278.196802)
		(end 158.393892 -278.35987)
		(width 0.14478)
		(layer "In11.Cu")
		(net "M_L_CPU1_SB_DQ<2>")
	)
	(segment
		(start 154.4701 -273.852894)
		(end 154.293824 -274.02917)
		(width 0.14478)
		(layer "In11.Cu")
		(net "M_L_CPU1_SB_DQ<2>")
	)
	(segment
		(start 166.974012 -281.910282)
		(end 167.806624 -281.910282)
		(width 0.14478)
		(layer "In11.Cu")
		(net "M_L_CPU1_SB_DQ<2>")
	)
	(segment
		(start 193.664586 -282.76042)
		(end 195.662804 -282.76042)
		(width 0.14478)
		(layer "In11.Cu")
		(net "M_L_CPU1_SB_DQ<2>")
	)
	(segment
		(start 155.868624 -275.834602)
		(end 156.031692 -275.99767)
		(width 0.14478)
		(layer "In11.Cu")
		(net "M_L_CPU1_SB_DQ<2>")
	)
	(segment
		(start 155.081224 -274.81657)
		(end 155.081224 -275.047202)
		(width 0.14478)
		(layer "In11.Cu")
		(net "M_L_CPU1_SB_DQ<2>")
	)
	(segment
		(start 139.488672 -274.630896)
		(end 139.584684 -274.605496)
		(width 0.0889)
		(layer "In11.Cu")
		(net "M_L_CPU1_SB_DQ<2>")
	)
	(segment
		(start 195.662804 -282.76042)
		(end 196.512942 -281.910282)
		(width 0.14478)
		(layer "In11.Cu")
		(net "M_L_CPU1_SB_DQ<2>")
	)
	(segment
		(start 156.031692 -275.99767)
		(end 156.262324 -275.99767)
		(width 0.14478)
		(layer "In11.Cu")
		(net "M_L_CPU1_SB_DQ<2>")
	)
	(segment
		(start 169.759884 -281.910282)
		(end 170.182286 -281.910282)
		(width 0.14478)
		(layer "In11.Cu")
		(net "M_L_CPU1_SB_DQ<2>")
	)
	(segment
		(start 141.393418 -274.56892)
		(end 141.4018 -274.573746)
		(width 0.0889)
		(layer "In11.Cu")
		(net "M_L_CPU1_SB_DQ<2>")
	)
	(segment
		(start 154.8638 -274.246594)
		(end 155.094432 -274.246594)
		(width 0.14478)
		(layer "In11.Cu")
		(net "M_L_CPU1_SB_DQ<2>")
	)
	(segment
		(start 189.632082 -281.910282)
		(end 192.814448 -281.910282)
		(width 0.14478)
		(layer "In11.Cu")
		(net "M_L_CPU1_SB_DQ<2>")
	)
	(segment
		(start 159.1945 -278.577294)
		(end 159.018224 -278.75357)
		(width 0.14478)
		(layer "In11.Cu")
		(net "M_L_CPU1_SB_DQ<2>")
	)
	(segment
		(start 147.29841 -273.616166)
		(end 147.520152 -273.394424)
		(width 0.0889)
		(layer "In11.Cu")
		(net "M_L_CPU1_SB_DQ<2>")
	)
	(segment
		(start 171.032424 -282.76042)
		(end 173.693836 -282.76042)
		(width 0.14478)
		(layer "In11.Cu")
		(net "M_L_CPU1_SB_DQ<2>")
	)
	(segment
		(start 144.786604 -274.573746)
		(end 144.798288 -274.566888)
		(width 0.0889)
		(layer "In11.Cu")
		(net "M_L_CPU1_SB_DQ<2>")
	)
	(segment
		(start 158.624524 -278.35987)
		(end 158.8008 -278.183594)
		(width 0.14478)
		(layer "In11.Cu")
		(net "M_L_CPU1_SB_DQ<2>")
	)
	(segment
		(start 157.226 -276.608794)
		(end 157.456632 -276.608794)
		(width 0.14478)
		(layer "In11.Cu")
		(net "M_L_CPU1_SB_DQ<2>")
	)
	(segment
		(start 158.230824 -277.96617)
		(end 158.230824 -278.196802)
		(width 0.14478)
		(layer "In11.Cu")
		(net "M_L_CPU1_SB_DQ<2>")
	)
	(segment
		(start 181.23789 -282.76042)
		(end 182.088028 -281.910282)
		(width 0.14478)
		(layer "In11.Cu")
		(net "M_L_CPU1_SB_DQ<2>")
	)
	(segment
		(start 157.6197 -276.771862)
		(end 157.6197 -277.002494)
		(width 0.14478)
		(layer "In11.Cu")
		(net "M_L_CPU1_SB_DQ<2>")
	)
	(segment
		(start 177.72634 -281.910282)
		(end 178.576478 -282.76042)
		(width 0.14478)
		(layer "In11.Cu")
		(net "M_L_CPU1_SB_DQ<2>")
	)
	(segment
		(start 188.781944 -282.76042)
		(end 189.632082 -281.910282)
		(width 0.14478)
		(layer "In11.Cu")
		(net "M_L_CPU1_SB_DQ<2>")
	)
	(segment
		(start 140.453364 -274.56892)
		(end 140.461746 -274.573746)
		(width 0.0889)
		(layer "In11.Cu")
		(net "M_L_CPU1_SB_DQ<2>")
	)
	(segment
		(start 154.456892 -274.42287)
		(end 154.687524 -274.42287)
		(width 0.14478)
		(layer "In11.Cu")
		(net "M_L_CPU1_SB_DQ<2>")
	)
	(segment
		(start 145.444718 -274.6502)
		(end 145.703036 -274.6502)
		(width 0.0889)
		(layer "In11.Cu")
		(net "M_L_CPU1_SB_DQ<2>")
	)
	(segment
		(start 148.048218 -273.394424)
		(end 154.242262 -273.394424)
		(width 0.14478)
		(layer "In11.Cu")
		(net "M_L_CPU1_SB_DQ<2>")
	)
	(segment
		(start 154.4701 -273.622262)
		(end 154.4701 -273.852894)
		(width 0.14478)
		(layer "In11.Cu")
		(net "M_L_CPU1_SB_DQ<2>")
	)
	(segment
		(start 159.018224 -278.984202)
		(end 159.181292 -279.14727)
		(width 0.14478)
		(layer "In11.Cu")
		(net "M_L_CPU1_SB_DQ<2>")
	)
	(segment
		(start 158.0134 -277.396194)
		(end 158.244032 -277.396194)
		(width 0.14478)
		(layer "In11.Cu")
		(net "M_L_CPU1_SB_DQ<2>")
	)
	(segment
		(start 156.0449 -275.427694)
		(end 155.868624 -275.60397)
		(width 0.14478)
		(layer "In11.Cu")
		(net "M_L_CPU1_SB_DQ<2>")
	)
	(segment
		(start 156.262324 -275.99767)
		(end 156.4386 -275.821394)
		(width 0.14478)
		(layer "In11.Cu")
		(net "M_L_CPU1_SB_DQ<2>")
	)
	(segment
		(start 169.476166 -281.626564)
		(end 169.759884 -281.910282)
		(width 0.14478)
		(layer "In11.Cu")
		(net "M_L_CPU1_SB_DQ<2>")
	)
	(segment
		(start 159.031432 -278.183594)
		(end 159.1945 -278.346662)
		(width 0.14478)
		(layer "In11.Cu")
		(net "M_L_CPU1_SB_DQ<2>")
	)
	(segment
		(start 168.363138 -281.626564)
		(end 168.646856 -281.910282)
		(width 0.14478)
		(layer "In11.Cu")
		(net "M_L_CPU1_SB_DQ<2>")
	)
	(segment
		(start 158.244032 -277.396194)
		(end 158.4071 -277.559262)
		(width 0.14478)
		(layer "In11.Cu")
		(net "M_L_CPU1_SB_DQ<2>")
	)
	(segment
		(start 145.703036 -274.6502)
		(end 146.73707 -273.616166)
		(width 0.0889)
		(layer "In11.Cu")
		(net "M_L_CPU1_SB_DQ<2>")
	)
	(segment
		(start 159.818832 -278.970994)
		(end 163.608258 -282.76042)
		(width 0.14478)
		(layer "In11.Cu")
		(net "M_L_CPU1_SB_DQ<2>")
	)
	(segment
		(start 156.8323 -276.215094)
		(end 156.656024 -276.39137)
		(width 0.14478)
		(layer "In11.Cu")
		(net "M_L_CPU1_SB_DQ<2>")
	)
	(segment
		(start 156.4386 -275.821394)
		(end 156.669232 -275.821394)
		(width 0.14478)
		(layer "In11.Cu")
		(net "M_L_CPU1_SB_DQ<2>")
	)
	(segment
		(start 186.120532 -282.76042)
		(end 188.781944 -282.76042)
		(width 0.14478)
		(layer "In11.Cu")
		(net "M_L_CPU1_SB_DQ<2>")
	)
	(segment
		(start 168.090342 -281.626564)
		(end 168.363138 -281.626564)
		(width 0.14478)
		(layer "In11.Cu")
		(net "M_L_CPU1_SB_DQ<2>")
	)
	(segment
		(start 168.646856 -281.910282)
		(end 168.919652 -281.910282)
		(width 0.14478)
		(layer "In11.Cu")
		(net "M_L_CPU1_SB_DQ<2>")
	)
	(segment
		(start 157.6197 -277.002494)
		(end 157.443424 -277.17877)
		(width 0.14478)
		(layer "In11.Cu")
		(net "M_L_CPU1_SB_DQ<2>")
	)
	(segment
		(start 144.205198 -274.564602)
		(end 144.221454 -274.574)
		(width 0.0889)
		(layer "In11.Cu")
		(net "M_L_CPU1_SB_DQ<2>")
	)
	(segment
		(start 156.669232 -275.821394)
		(end 156.8323 -275.984462)
		(width 0.14478)
		(layer "In11.Cu")
		(net "M_L_CPU1_SB_DQ<2>")
	)
	(segment
		(start 157.443424 -277.17877)
		(end 157.443424 -277.409402)
		(width 0.14478)
		(layer "In11.Cu")
		(net "M_L_CPU1_SB_DQ<2>")
	)
	(segment
		(start 156.656024 -276.622002)
		(end 156.819092 -276.78507)
		(width 0.14478)
		(layer "In11.Cu")
		(net "M_L_CPU1_SB_DQ<2>")
	)
	(segment
		(start 155.6512 -275.033994)
		(end 155.881832 -275.033994)
		(width 0.14478)
		(layer "In11.Cu")
		(net "M_L_CPU1_SB_DQ<2>")
	)
	(segment
		(start 155.081224 -275.047202)
		(end 155.244292 -275.21027)
		(width 0.14478)
		(layer "In11.Cu")
		(net "M_L_CPU1_SB_DQ<2>")
	)
	(segment
		(start 156.819092 -276.78507)
		(end 157.049724 -276.78507)
		(width 0.14478)
		(layer "In11.Cu")
		(net "M_L_CPU1_SB_DQ<2>")
	)
	(segment
		(start 157.443424 -277.409402)
		(end 157.606492 -277.57247)
		(width 0.14478)
		(layer "In11.Cu")
		(net "M_L_CPU1_SB_DQ<2>")
	)
	(segment
		(start 159.018224 -278.75357)
		(end 159.018224 -278.984202)
		(width 0.14478)
		(layer "In11.Cu")
		(net "M_L_CPU1_SB_DQ<2>")
	)
	(segment
		(start 154.293824 -274.259802)
		(end 154.456892 -274.42287)
		(width 0.14478)
		(layer "In11.Cu")
		(net "M_L_CPU1_SB_DQ<2>")
	)
	(segment
		(start 155.474924 -275.21027)
		(end 155.6512 -275.033994)
		(width 0.14478)
		(layer "In11.Cu")
		(net "M_L_CPU1_SB_DQ<2>")
	)
	(segment
		(start 167.806624 -281.910282)
		(end 168.090342 -281.626564)
		(width 0.14478)
		(layer "In11.Cu")
		(net "M_L_CPU1_SB_DQ<2>")
	)
	(segment
		(start 168.919652 -281.910282)
		(end 169.20337 -281.626564)
		(width 0.14478)
		(layer "In11.Cu")
		(net "M_L_CPU1_SB_DQ<2>")
	)
	(segment
		(start 156.8323 -275.984462)
		(end 156.8323 -276.215094)
		(width 0.14478)
		(layer "In11.Cu")
		(net "M_L_CPU1_SB_DQ<2>")
	)
	(segment
		(start 196.512942 -281.910282)
		(end 201.72299 -281.910282)
		(width 0.14478)
		(layer "In11.Cu")
		(net "M_L_CPU1_SB_DQ<2>")
	)
	(segment
		(start 155.2575 -274.409662)
		(end 155.2575 -274.640294)
		(width 0.14478)
		(layer "In11.Cu")
		(net "M_L_CPU1_SB_DQ<2>")
	)
	(segment
		(start 147.520152 -273.394424)
		(end 148.048218 -273.394424)
		(width 0.0889)
		(layer "In11.Cu")
		(net "M_L_CPU1_SB_DQ<2>")
	)
	(segment
		(start 185.270394 -281.910282)
		(end 186.120532 -282.76042)
		(width 0.14478)
		(layer "In11.Cu")
		(net "M_L_CPU1_SB_DQ<2>")
	)
	(segment
		(start 159.181292 -279.14727)
		(end 159.411924 -279.14727)
		(width 0.14478)
		(layer "In11.Cu")
		(net "M_L_CPU1_SB_DQ<2>")
	)
	(arc
		(start 139.584684 -274.605496)
		(mid 139.839892 -274.648973)
		(end 140.087604 -274.573746)
		(width 0.0889)
		(layer "In11.Cu")
		(net "M_L_CPU1_SB_DQ<2>")
	)
	(arc
		(start 140.087604 -274.573746)
		(mid 140.269855 -274.523396)
		(end 140.453364 -274.56892)
		(width 0.0889)
		(layer "In11.Cu")
		(net "M_L_CPU1_SB_DQ<2>")
	)
	(arc
		(start 141.4018 -274.573746)
		(mid 141.684756 -274.649923)
		(end 141.967712 -274.573746)
		(width 0.0889)
		(layer "In11.Cu")
		(net "M_L_CPU1_SB_DQ<2>")
	)
	(arc
		(start 141.976094 -274.56892)
		(mid 142.159602 -274.523426)
		(end 142.341854 -274.573746)
		(width 0.0889)
		(layer "In11.Cu")
		(net "M_L_CPU1_SB_DQ<2>")
	)
	(arc
		(start 143.281654 -274.573746)
		(mid 143.56461 -274.649923)
		(end 143.847566 -274.573746)
		(width 0.0889)
		(layer "In11.Cu")
		(net "M_L_CPU1_SB_DQ<2>")
	)
	(arc
		(start 142.907766 -274.573746)
		(mid 143.09471 -274.523491)
		(end 143.281654 -274.573746)
		(width 0.0889)
		(layer "In11.Cu")
		(net "M_L_CPU1_SB_DQ<2>")
	)
	(arc
		(start 145.161 -274.573746)
		(mid 145.297793 -274.630768)
		(end 145.444718 -274.6502)
		(width 0.0889)
		(layer "In11.Cu")
		(net "M_L_CPU1_SB_DQ<2>")
	)
	(arc
		(start 142.341854 -274.573746)
		(mid 142.62481 -274.649923)
		(end 142.907766 -274.573746)
		(width 0.0889)
		(layer "In11.Cu")
		(net "M_L_CPU1_SB_DQ<2>")
	)
	(arc
		(start 144.798288 -274.566888)
		(mid 144.980543 -274.523235)
		(end 145.161 -274.573746)
		(width 0.0889)
		(layer "In11.Cu")
		(net "M_L_CPU1_SB_DQ<2>")
	)
	(arc
		(start 143.847566 -274.573746)
		(mid 144.025216 -274.523486)
		(end 144.205198 -274.564602)
		(width 0.0889)
		(layer "In11.Cu")
		(net "M_L_CPU1_SB_DQ<2>")
	)
	(arc
		(start 144.233392 -274.580858)
		(mid 144.510926 -274.649839)
		(end 144.786604 -274.573746)
		(width 0.0889)
		(layer "In11.Cu")
		(net "M_L_CPU1_SB_DQ<2>")
	)
	(arc
		(start 141.027658 -274.573746)
		(mid 141.209909 -274.523396)
		(end 141.393418 -274.56892)
		(width 0.0889)
		(layer "In11.Cu")
		(net "M_L_CPU1_SB_DQ<2>")
	)
	(arc
		(start 140.461746 -274.573746)
		(mid 140.744702 -274.649923)
		(end 141.027658 -274.573746)
		(width 0.0889)
		(layer "In11.Cu")
		(net "M_L_CPU1_SB_DQ<2>")
	)
	(segment
		(start 137.927842 -292.450266)
		(end 138.394694 -292.716204)
		(width 0.10668)
		(layer "F.Cu")
		(net "M_L_CPU1_SB_DQ<29>")
	)
	(segment
		(start 203.550266 -318.416686)
		(end 203.81214 -318.416686)
		(width 0.14478)
		(layer "In11.Cu")
		(net "M_L_CPU1_SB_DQ<29>")
	)
	(segment
		(start 144.317466 -293.84879)
		(end 144.356582 -293.87165)
		(width 0.0889)
		(layer "In11.Cu")
		(net "M_L_CPU1_SB_DQ<29>")
	)
	(segment
		(start 162.236912 -317.61049)
		(end 203.260706 -317.61049)
		(width 0.14478)
		(layer "In11.Cu")
		(net "M_L_CPU1_SB_DQ<29>")
	)
	(segment
		(start 145.415254 -295.602152)
		(end 145.773648 -295.960546)
		(width 0.0889)
		(layer "In11.Cu")
		(net "M_L_CPU1_SB_DQ<29>")
	)
	(segment
		(start 144.787366 -294.658796)
		(end 144.826482 -294.681656)
		(width 0.0889)
		(layer "In11.Cu")
		(net "M_L_CPU1_SB_DQ<29>")
	)
	(segment
		(start 203.95692 -317.75527)
		(end 204.1017 -317.61049)
		(width 0.14478)
		(layer "In11.Cu")
		(net "M_L_CPU1_SB_DQ<29>")
	)
	(segment
		(start 203.95692 -318.271906)
		(end 203.95692 -317.75527)
		(width 0.14478)
		(layer "In11.Cu")
		(net "M_L_CPU1_SB_DQ<29>")
	)
	(segment
		(start 140.453364 -293.04361)
		(end 140.461746 -293.038784)
		(width 0.0889)
		(layer "In11.Cu")
		(net "M_L_CPU1_SB_DQ<29>")
	)
	(segment
		(start 204.1017 -317.61049)
		(end 204.363574 -317.61049)
		(width 0.14478)
		(layer "In11.Cu")
		(net "M_L_CPU1_SB_DQ<29>")
	)
	(segment
		(start 138.394694 -292.716204)
		(end 139.117324 -293.021004)
		(width 0.0889)
		(layer "In11.Cu")
		(net "M_L_CPU1_SB_DQ<29>")
	)
	(segment
		(start 204.653134 -318.416686)
		(end 204.915008 -318.416686)
		(width 0.14478)
		(layer "In11.Cu")
		(net "M_L_CPU1_SB_DQ<29>")
	)
	(segment
		(start 144.756886 -294.641016)
		(end 144.787366 -294.658796)
		(width 0.0889)
		(layer "In11.Cu")
		(net "M_L_CPU1_SB_DQ<29>")
	)
	(segment
		(start 145.773648 -296.549572)
		(end 145.773648 -301.147226)
		(width 0.14478)
		(layer "In11.Cu")
		(net "M_L_CPU1_SB_DQ<29>")
	)
	(segment
		(start 144.286986 -293.83101)
		(end 144.317466 -293.84879)
		(width 0.0889)
		(layer "In11.Cu")
		(net "M_L_CPU1_SB_DQ<29>")
	)
	(segment
		(start 204.508354 -317.75527)
		(end 204.508354 -318.271906)
		(width 0.14478)
		(layer "In11.Cu")
		(net "M_L_CPU1_SB_DQ<29>")
	)
	(segment
		(start 203.405486 -318.271906)
		(end 203.550266 -318.416686)
		(width 0.14478)
		(layer "In11.Cu")
		(net "M_L_CPU1_SB_DQ<29>")
	)
	(segment
		(start 139.117324 -293.021004)
		(end 139.147804 -293.038784)
		(width 0.0889)
		(layer "In11.Cu")
		(net "M_L_CPU1_SB_DQ<29>")
	)
	(segment
		(start 145.223992 -295.449244)
		(end 145.294096 -295.489884)
		(width 0.0889)
		(layer "In11.Cu")
		(net "M_L_CPU1_SB_DQ<29>")
	)
	(segment
		(start 205.059788 -318.271906)
		(end 205.059788 -317.75527)
		(width 0.14478)
		(layer "In11.Cu")
		(net "M_L_CPU1_SB_DQ<29>")
	)
	(segment
		(start 204.915008 -318.416686)
		(end 205.059788 -318.271906)
		(width 0.14478)
		(layer "In11.Cu")
		(net "M_L_CPU1_SB_DQ<29>")
	)
	(segment
		(start 204.363574 -317.61049)
		(end 204.508354 -317.75527)
		(width 0.14478)
		(layer "In11.Cu")
		(net "M_L_CPU1_SB_DQ<29>")
	)
	(segment
		(start 203.405486 -317.75527)
		(end 203.405486 -318.271906)
		(width 0.14478)
		(layer "In11.Cu")
		(net "M_L_CPU1_SB_DQ<29>")
	)
	(segment
		(start 204.508354 -318.271906)
		(end 204.653134 -318.416686)
		(width 0.14478)
		(layer "In11.Cu")
		(net "M_L_CPU1_SB_DQ<29>")
	)
	(segment
		(start 141.393418 -293.04361)
		(end 141.4018 -293.038784)
		(width 0.0889)
		(layer "In11.Cu")
		(net "M_L_CPU1_SB_DQ<29>")
	)
	(segment
		(start 203.260706 -317.61049)
		(end 203.405486 -317.75527)
		(width 0.14478)
		(layer "In11.Cu")
		(net "M_L_CPU1_SB_DQ<29>")
	)
	(segment
		(start 141.967712 -293.038784)
		(end 141.976094 -293.04361)
		(width 0.0889)
		(layer "In11.Cu")
		(net "M_L_CPU1_SB_DQ<29>")
	)
	(segment
		(start 145.773648 -301.147226)
		(end 162.236912 -317.61049)
		(width 0.14478)
		(layer "In11.Cu")
		(net "M_L_CPU1_SB_DQ<29>")
	)
	(segment
		(start 143.847566 -293.038784)
		(end 143.886682 -293.061644)
		(width 0.0889)
		(layer "In11.Cu")
		(net "M_L_CPU1_SB_DQ<29>")
	)
	(segment
		(start 145.773648 -295.960546)
		(end 145.773648 -296.549572)
		(width 0.0889)
		(layer "In11.Cu")
		(net "M_L_CPU1_SB_DQ<29>")
	)
	(segment
		(start 205.059788 -317.75527)
		(end 205.204568 -317.61049)
		(width 0.14478)
		(layer "In11.Cu")
		(net "M_L_CPU1_SB_DQ<29>")
	)
	(segment
		(start 205.822804 -317.61049)
		(end 206.248 -317.185294)
		(width 0.14478)
		(layer "In11.Cu")
		(net "M_L_CPU1_SB_DQ<29>")
	)
	(segment
		(start 205.204568 -317.61049)
		(end 205.822804 -317.61049)
		(width 0.14478)
		(layer "In11.Cu")
		(net "M_L_CPU1_SB_DQ<29>")
	)
	(segment
		(start 203.81214 -318.416686)
		(end 203.95692 -318.271906)
		(width 0.14478)
		(layer "In11.Cu")
		(net "M_L_CPU1_SB_DQ<29>")
	)
	(arc
		(start 139.147804 -293.038784)
		(mid 139.334748 -293.089039)
		(end 139.521692 -293.038784)
		(width 0.0889)
		(layer "In11.Cu")
		(net "M_L_CPU1_SB_DQ<29>")
	)
	(arc
		(start 144.599914 -294.336216)
		(mid 144.641463 -294.507638)
		(end 144.756886 -294.641016)
		(width 0.0889)
		(layer "In11.Cu")
		(net "M_L_CPU1_SB_DQ<29>")
	)
	(arc
		(start 139.521692 -293.038784)
		(mid 139.804648 -292.962607)
		(end 140.087604 -293.038784)
		(width 0.0889)
		(layer "In11.Cu")
		(net "M_L_CPU1_SB_DQ<29>")
	)
	(arc
		(start 141.4018 -293.038784)
		(mid 141.684756 -292.962607)
		(end 141.967712 -293.038784)
		(width 0.0889)
		(layer "In11.Cu")
		(net "M_L_CPU1_SB_DQ<29>")
	)
	(arc
		(start 144.826482 -294.681656)
		(mid 145.005295 -294.884006)
		(end 145.069814 -295.146222)
		(width 0.0889)
		(layer "In11.Cu")
		(net "M_L_CPU1_SB_DQ<29>")
	)
	(arc
		(start 141.027658 -293.038784)
		(mid 141.209909 -293.089134)
		(end 141.393418 -293.04361)
		(width 0.0889)
		(layer "In11.Cu")
		(net "M_L_CPU1_SB_DQ<29>")
	)
	(arc
		(start 140.461746 -293.038784)
		(mid 140.744702 -292.962607)
		(end 141.027658 -293.038784)
		(width 0.0889)
		(layer "In11.Cu")
		(net "M_L_CPU1_SB_DQ<29>")
	)
	(arc
		(start 141.976094 -293.04361)
		(mid 142.159602 -293.089104)
		(end 142.341854 -293.038784)
		(width 0.0889)
		(layer "In11.Cu")
		(net "M_L_CPU1_SB_DQ<29>")
	)
	(arc
		(start 143.886682 -293.061644)
		(mid 144.065495 -293.263994)
		(end 144.130014 -293.52621)
		(width 0.0889)
		(layer "In11.Cu")
		(net "M_L_CPU1_SB_DQ<29>")
	)
	(arc
		(start 145.069814 -295.146222)
		(mid 145.110572 -295.31622)
		(end 145.223992 -295.449244)
		(width 0.0889)
		(layer "In11.Cu")
		(net "M_L_CPU1_SB_DQ<29>")
	)
	(arc
		(start 144.356582 -293.87165)
		(mid 144.535395 -294.074)
		(end 144.599914 -294.336216)
		(width 0.0889)
		(layer "In11.Cu")
		(net "M_L_CPU1_SB_DQ<29>")
	)
	(arc
		(start 144.130014 -293.52621)
		(mid 144.171563 -293.697632)
		(end 144.286986 -293.83101)
		(width 0.0889)
		(layer "In11.Cu")
		(net "M_L_CPU1_SB_DQ<29>")
	)
	(arc
		(start 140.087604 -293.038784)
		(mid 140.269855 -293.089134)
		(end 140.453364 -293.04361)
		(width 0.0889)
		(layer "In11.Cu")
		(net "M_L_CPU1_SB_DQ<29>")
	)
	(arc
		(start 143.281654 -293.038784)
		(mid 143.56461 -292.962607)
		(end 143.847566 -293.038784)
		(width 0.0889)
		(layer "In11.Cu")
		(net "M_L_CPU1_SB_DQ<29>")
	)
	(arc
		(start 142.907766 -293.038784)
		(mid 143.09471 -293.089039)
		(end 143.281654 -293.038784)
		(width 0.0889)
		(layer "In11.Cu")
		(net "M_L_CPU1_SB_DQ<29>")
	)
	(arc
		(start 145.294096 -295.489884)
		(mid 145.358798 -295.541569)
		(end 145.415254 -295.602152)
		(width 0.0889)
		(layer "In11.Cu")
		(net "M_L_CPU1_SB_DQ<29>")
	)
	(arc
		(start 142.341854 -293.038784)
		(mid 142.62481 -292.962607)
		(end 142.907766 -293.038784)
		(width 0.0889)
		(layer "In11.Cu")
		(net "M_L_CPU1_SB_DQ<29>")
	)
	(segment
		(start 139.337796 -291.64026)
		(end 139.804648 -291.906198)
		(width 0.10668)
		(layer "F.Cu")
		(net "M_L_CPU1_SB_DQ<28>")
	)
	(segment
		(start 144.75714 -293.021004)
		(end 144.78762 -293.038784)
		(width 0.0889)
		(layer "In11.Cu")
		(net "M_L_CPU1_SB_DQ<28>")
	)
	(segment
		(start 144.78762 -293.038784)
		(end 144.826736 -293.061644)
		(width 0.0889)
		(layer "In11.Cu")
		(net "M_L_CPU1_SB_DQ<28>")
	)
	(segment
		(start 205.086712 -316.859666)
		(end 205.086712 -316.064646)
		(width 0.14478)
		(layer "In11.Cu")
		(net "M_L_CPU1_SB_DQ<28>")
	)
	(segment
		(start 203.57719 -317.004446)
		(end 203.839064 -317.004446)
		(width 0.14478)
		(layer "In11.Cu")
		(net "M_L_CPU1_SB_DQ<28>")
	)
	(segment
		(start 204.680058 -317.004446)
		(end 204.941932 -317.004446)
		(width 0.14478)
		(layer "In11.Cu")
		(net "M_L_CPU1_SB_DQ<28>")
	)
	(segment
		(start 145.695924 -294.640508)
		(end 145.727674 -294.658796)
		(width 0.0889)
		(layer "In11.Cu")
		(net "M_L_CPU1_SB_DQ<28>")
	)
	(segment
		(start 146.682968 -296.468292)
		(end 146.682968 -300.733714)
		(width 0.14478)
		(layer "In11.Cu")
		(net "M_L_CPU1_SB_DQ<28>")
	)
	(segment
		(start 145.22704 -293.83101)
		(end 145.25752 -293.84879)
		(width 0.0889)
		(layer "In11.Cu")
		(net "M_L_CPU1_SB_DQ<28>")
	)
	(segment
		(start 205.086712 -316.064646)
		(end 205.231492 -315.919866)
		(width 0.14478)
		(layer "In11.Cu")
		(net "M_L_CPU1_SB_DQ<28>")
	)
	(segment
		(start 204.941932 -317.004446)
		(end 205.086712 -316.859666)
		(width 0.14478)
		(layer "In11.Cu")
		(net "M_L_CPU1_SB_DQ<28>")
	)
	(segment
		(start 144.31772 -292.228778)
		(end 144.356836 -292.251638)
		(width 0.0889)
		(layer "In11.Cu")
		(net "M_L_CPU1_SB_DQ<28>")
	)
	(segment
		(start 145.933668 -294.77843)
		(end 146.682968 -295.52773)
		(width 0.0889)
		(layer "In11.Cu")
		(net "M_L_CPU1_SB_DQ<28>")
	)
	(segment
		(start 205.231492 -315.919866)
		(end 205.813406 -315.919866)
		(width 0.14478)
		(layer "In11.Cu")
		(net "M_L_CPU1_SB_DQ<28>")
	)
	(segment
		(start 143.377666 -292.228778)
		(end 143.386048 -292.233604)
		(width 0.0889)
		(layer "In11.Cu")
		(net "M_L_CPU1_SB_DQ<28>")
	)
	(segment
		(start 203.43241 -316.064646)
		(end 203.43241 -316.859666)
		(width 0.14478)
		(layer "In11.Cu")
		(net "M_L_CPU1_SB_DQ<28>")
	)
	(segment
		(start 142.803372 -292.233604)
		(end 142.811754 -292.228778)
		(width 0.0889)
		(layer "In11.Cu")
		(net "M_L_CPU1_SB_DQ<28>")
	)
	(segment
		(start 146.682968 -300.733714)
		(end 161.86912 -315.919866)
		(width 0.14478)
		(layer "In11.Cu")
		(net "M_L_CPU1_SB_DQ<28>")
	)
	(segment
		(start 146.682968 -295.52773)
		(end 146.682968 -296.468292)
		(width 0.0889)
		(layer "In11.Cu")
		(net "M_L_CPU1_SB_DQ<28>")
	)
	(segment
		(start 139.650724 -292.171628)
		(end 139.673076 -292.25494)
		(width 0.0889)
		(layer "In11.Cu")
		(net "M_L_CPU1_SB_DQ<28>")
	)
	(segment
		(start 203.839064 -317.004446)
		(end 203.983844 -316.859666)
		(width 0.14478)
		(layer "In11.Cu")
		(net "M_L_CPU1_SB_DQ<28>")
	)
	(segment
		(start 204.128624 -315.919866)
		(end 204.390498 -315.919866)
		(width 0.14478)
		(layer "In11.Cu")
		(net "M_L_CPU1_SB_DQ<28>")
	)
	(segment
		(start 203.983844 -316.064646)
		(end 204.128624 -315.919866)
		(width 0.14478)
		(layer "In11.Cu")
		(net "M_L_CPU1_SB_DQ<28>")
	)
	(segment
		(start 203.983844 -316.859666)
		(end 203.983844 -316.064646)
		(width 0.14478)
		(layer "In11.Cu")
		(net "M_L_CPU1_SB_DQ<28>")
	)
	(segment
		(start 205.813406 -315.919866)
		(end 206.248 -315.485272)
		(width 0.14478)
		(layer "In11.Cu")
		(net "M_L_CPU1_SB_DQ<28>")
	)
	(segment
		(start 204.535278 -316.064646)
		(end 204.535278 -316.859666)
		(width 0.14478)
		(layer "In11.Cu")
		(net "M_L_CPU1_SB_DQ<28>")
	)
	(segment
		(start 140.557758 -292.228778)
		(end 140.56614 -292.233604)
		(width 0.0889)
		(layer "In11.Cu")
		(net "M_L_CPU1_SB_DQ<28>")
	)
	(segment
		(start 144.03451 -292.152578)
		(end 144.187418 -292.152578)
		(width 0.0889)
		(layer "In11.Cu")
		(net "M_L_CPU1_SB_DQ<28>")
	)
	(segment
		(start 203.43241 -316.859666)
		(end 203.57719 -317.004446)
		(width 0.14478)
		(layer "In11.Cu")
		(net "M_L_CPU1_SB_DQ<28>")
	)
	(segment
		(start 203.28763 -315.919866)
		(end 203.43241 -316.064646)
		(width 0.14478)
		(layer "In11.Cu")
		(net "M_L_CPU1_SB_DQ<28>")
	)
	(segment
		(start 204.390498 -315.919866)
		(end 204.535278 -316.064646)
		(width 0.14478)
		(layer "In11.Cu")
		(net "M_L_CPU1_SB_DQ<28>")
	)
	(segment
		(start 144.187418 -292.152578)
		(end 144.31772 -292.228778)
		(width 0.0889)
		(layer "In11.Cu")
		(net "M_L_CPU1_SB_DQ<28>")
	)
	(segment
		(start 145.25752 -293.84879)
		(end 145.296636 -293.87165)
		(width 0.0889)
		(layer "In11.Cu")
		(net "M_L_CPU1_SB_DQ<28>")
	)
	(segment
		(start 161.86912 -315.919866)
		(end 203.28763 -315.919866)
		(width 0.14478)
		(layer "In11.Cu")
		(net "M_L_CPU1_SB_DQ<28>")
	)
	(segment
		(start 139.804648 -291.906198)
		(end 139.650724 -292.171628)
		(width 0.0889)
		(layer "In11.Cu")
		(net "M_L_CPU1_SB_DQ<28>")
	)
	(segment
		(start 145.727674 -294.658796)
		(end 145.933668 -294.77843)
		(width 0.0889)
		(layer "In11.Cu")
		(net "M_L_CPU1_SB_DQ<28>")
	)
	(segment
		(start 204.535278 -316.859666)
		(end 204.680058 -317.004446)
		(width 0.14478)
		(layer "In11.Cu")
		(net "M_L_CPU1_SB_DQ<28>")
	)
	(arc
		(start 143.386048 -292.233604)
		(mid 143.569556 -292.279098)
		(end 143.751808 -292.228778)
		(width 0.0889)
		(layer "In11.Cu")
		(net "M_L_CPU1_SB_DQ<28>")
	)
	(arc
		(start 144.356836 -292.251638)
		(mid 144.535649 -292.453988)
		(end 144.600168 -292.716204)
		(width 0.0889)
		(layer "In11.Cu")
		(net "M_L_CPU1_SB_DQ<28>")
	)
	(arc
		(start 141.497812 -292.228778)
		(mid 141.684756 -292.279033)
		(end 141.8717 -292.228778)
		(width 0.0889)
		(layer "In11.Cu")
		(net "M_L_CPU1_SB_DQ<28>")
	)
	(arc
		(start 145.539968 -294.336216)
		(mid 145.581223 -294.507187)
		(end 145.695924 -294.640508)
		(width 0.0889)
		(layer "In11.Cu")
		(net "M_L_CPU1_SB_DQ<28>")
	)
	(arc
		(start 140.9319 -292.228778)
		(mid 141.214856 -292.152601)
		(end 141.497812 -292.228778)
		(width 0.0889)
		(layer "In11.Cu")
		(net "M_L_CPU1_SB_DQ<28>")
	)
	(arc
		(start 139.673076 -292.25494)
		(mid 139.835408 -292.277758)
		(end 139.991846 -292.228778)
		(width 0.0889)
		(layer "In11.Cu")
		(net "M_L_CPU1_SB_DQ<28>")
	)
	(arc
		(start 142.437612 -292.228778)
		(mid 142.619863 -292.279128)
		(end 142.803372 -292.233604)
		(width 0.0889)
		(layer "In11.Cu")
		(net "M_L_CPU1_SB_DQ<28>")
	)
	(arc
		(start 139.991846 -292.228778)
		(mid 140.274802 -292.152601)
		(end 140.557758 -292.228778)
		(width 0.0889)
		(layer "In11.Cu")
		(net "M_L_CPU1_SB_DQ<28>")
	)
	(arc
		(start 140.56614 -292.233604)
		(mid 140.749648 -292.279098)
		(end 140.9319 -292.228778)
		(width 0.0889)
		(layer "In11.Cu")
		(net "M_L_CPU1_SB_DQ<28>")
	)
	(arc
		(start 145.296636 -293.87165)
		(mid 145.475449 -294.074)
		(end 145.539968 -294.336216)
		(width 0.0889)
		(layer "In11.Cu")
		(net "M_L_CPU1_SB_DQ<28>")
	)
	(arc
		(start 143.751808 -292.228778)
		(mid 143.888126 -292.172011)
		(end 144.03451 -292.152578)
		(width 0.0889)
		(layer "In11.Cu")
		(net "M_L_CPU1_SB_DQ<28>")
	)
	(arc
		(start 145.070068 -293.52621)
		(mid 145.111617 -293.697632)
		(end 145.22704 -293.83101)
		(width 0.0889)
		(layer "In11.Cu")
		(net "M_L_CPU1_SB_DQ<28>")
	)
	(arc
		(start 142.811754 -292.228778)
		(mid 143.09471 -292.152601)
		(end 143.377666 -292.228778)
		(width 0.0889)
		(layer "In11.Cu")
		(net "M_L_CPU1_SB_DQ<28>")
	)
	(arc
		(start 144.600168 -292.716204)
		(mid 144.641717 -292.887626)
		(end 144.75714 -293.021004)
		(width 0.0889)
		(layer "In11.Cu")
		(net "M_L_CPU1_SB_DQ<28>")
	)
	(arc
		(start 141.8717 -292.228778)
		(mid 142.154656 -292.152601)
		(end 142.437612 -292.228778)
		(width 0.0889)
		(layer "In11.Cu")
		(net "M_L_CPU1_SB_DQ<28>")
	)
	(arc
		(start 144.826736 -293.061644)
		(mid 145.005549 -293.263994)
		(end 145.070068 -293.52621)
		(width 0.0889)
		(layer "In11.Cu")
		(net "M_L_CPU1_SB_DQ<28>")
	)
	(segment
		(start 137.457942 -290.020248)
		(end 137.924794 -290.286186)
		(width 0.10668)
		(layer "F.Cu")
		(net "M_L_CPU1_SB_DQ<27>")
	)
	(segment
		(start 149.022308 -299.763434)
		(end 159.085534 -309.82666)
		(width 0.14478)
		(layer "In11.Cu")
		(net "M_L_CPU1_SB_DQ<27>")
	)
	(segment
		(start 170.324272 -311.650888)
		(end 171.17441 -312.501026)
		(width 0.14478)
		(layer "In11.Cu")
		(net "M_L_CPU1_SB_DQ<27>")
	)
	(segment
		(start 160.007808 -309.691786)
		(end 160.007808 -309.922418)
		(width 0.14478)
		(layer "In11.Cu")
		(net "M_L_CPU1_SB_DQ<27>")
	)
	(segment
		(start 145.93189 -291.04971)
		(end 146.5072 -292.438836)
		(width 0.0889)
		(layer "In11.Cu")
		(net "M_L_CPU1_SB_DQ<27>")
	)
	(segment
		(start 143.751808 -289.963606)
		(end 143.762222 -289.969702)
		(width 0.0889)
		(layer "In11.Cu")
		(net "M_L_CPU1_SB_DQ<27>")
	)
	(segment
		(start 171.17441 -312.501026)
		(end 173.509178 -312.501026)
		(width 0.14478)
		(layer "In11.Cu")
		(net "M_L_CPU1_SB_DQ<27>")
	)
	(segment
		(start 161.582608 -311.497218)
		(end 161.284666 -311.79516)
		(width 0.14478)
		(layer "In11.Cu")
		(net "M_L_CPU1_SB_DQ<27>")
	)
	(segment
		(start 160.007808 -309.922418)
		(end 159.709866 -310.22036)
		(width 0.14478)
		(layer "In11.Cu")
		(net "M_L_CPU1_SB_DQ<27>")
	)
	(segment
		(start 159.709866 -310.450992)
		(end 159.872934 -310.61406)
		(width 0.14478)
		(layer "In11.Cu")
		(net "M_L_CPU1_SB_DQ<27>")
	)
	(segment
		(start 161.582608 -311.266586)
		(end 161.582608 -311.497218)
		(width 0.14478)
		(layer "In11.Cu")
		(net "M_L_CPU1_SB_DQ<27>")
	)
	(segment
		(start 145.599404 -289.91306)
		(end 145.93189 -290.245546)
		(width 0.0889)
		(layer "In11.Cu")
		(net "M_L_CPU1_SB_DQ<27>")
	)
	(segment
		(start 186.14898 -312.500772)
		(end 188.57976 -312.500772)
		(width 0.14478)
		(layer "In11.Cu")
		(net "M_L_CPU1_SB_DQ<27>")
	)
	(segment
		(start 143.377666 -289.963606)
		(end 143.386048 -289.95878)
		(width 0.0889)
		(layer "In11.Cu")
		(net "M_L_CPU1_SB_DQ<27>")
	)
	(segment
		(start 159.709866 -310.22036)
		(end 159.709866 -310.450992)
		(width 0.14478)
		(layer "In11.Cu")
		(net "M_L_CPU1_SB_DQ<27>")
	)
	(segment
		(start 159.614108 -309.528718)
		(end 159.84474 -309.528718)
		(width 0.14478)
		(layer "In11.Cu")
		(net "M_L_CPU1_SB_DQ<27>")
	)
	(segment
		(start 173.509178 -312.501026)
		(end 174.359316 -311.650888)
		(width 0.14478)
		(layer "In11.Cu")
		(net "M_L_CPU1_SB_DQ<27>")
	)
	(segment
		(start 181.035706 -312.500772)
		(end 181.88559 -311.650888)
		(width 0.14478)
		(layer "In11.Cu")
		(net "M_L_CPU1_SB_DQ<27>")
	)
	(segment
		(start 137.924794 -290.286186)
		(end 138.078718 -290.020756)
		(width 0.0889)
		(layer "In11.Cu")
		(net "M_L_CPU1_SB_DQ<27>")
	)
	(segment
		(start 159.316166 -309.82666)
		(end 159.614108 -309.528718)
		(width 0.14478)
		(layer "In11.Cu")
		(net "M_L_CPU1_SB_DQ<27>")
	)
	(segment
		(start 188.57976 -312.500772)
		(end 189.429644 -311.650888)
		(width 0.14478)
		(layer "In11.Cu")
		(net "M_L_CPU1_SB_DQ<27>")
	)
	(segment
		(start 159.085534 -309.82666)
		(end 159.316166 -309.82666)
		(width 0.14478)
		(layer "In11.Cu")
		(net "M_L_CPU1_SB_DQ<27>")
	)
	(segment
		(start 181.88559 -311.650888)
		(end 185.299096 -311.650888)
		(width 0.14478)
		(layer "In11.Cu")
		(net "M_L_CPU1_SB_DQ<27>")
	)
	(segment
		(start 185.299096 -311.650888)
		(end 186.14898 -312.500772)
		(width 0.14478)
		(layer "In11.Cu")
		(net "M_L_CPU1_SB_DQ<27>")
	)
	(segment
		(start 139.04341 -289.95878)
		(end 139.051792 -289.963606)
		(width 0.0889)
		(layer "In11.Cu")
		(net "M_L_CPU1_SB_DQ<27>")
	)
	(segment
		(start 160.401508 -310.316118)
		(end 160.63214 -310.316118)
		(width 0.14478)
		(layer "In11.Cu")
		(net "M_L_CPU1_SB_DQ<27>")
	)
	(segment
		(start 147.866608 -293.478204)
		(end 149.022308 -294.633904)
		(width 0.14478)
		(layer "In11.Cu")
		(net "M_L_CPU1_SB_DQ<27>")
	)
	(segment
		(start 146.94027 -292.871906)
		(end 147.26031 -292.871906)
		(width 0.0889)
		(layer "In11.Cu")
		(net "M_L_CPU1_SB_DQ<27>")
	)
	(segment
		(start 160.890966 -311.40146)
		(end 161.188908 -311.103518)
		(width 0.14478)
		(layer "In11.Cu")
		(net "M_L_CPU1_SB_DQ<27>")
	)
	(segment
		(start 160.795208 -310.709818)
		(end 160.497266 -311.00776)
		(width 0.14478)
		(layer "In11.Cu")
		(net "M_L_CPU1_SB_DQ<27>")
	)
	(segment
		(start 177.658522 -311.650888)
		(end 178.508406 -312.500772)
		(width 0.14478)
		(layer "In11.Cu")
		(net "M_L_CPU1_SB_DQ<27>")
	)
	(segment
		(start 159.84474 -309.528718)
		(end 160.007808 -309.691786)
		(width 0.14478)
		(layer "In11.Cu")
		(net "M_L_CPU1_SB_DQ<27>")
	)
	(segment
		(start 147.26031 -292.871906)
		(end 147.866608 -293.478204)
		(width 0.0889)
		(layer "In11.Cu")
		(net "M_L_CPU1_SB_DQ<27>")
	)
	(segment
		(start 159.872934 -310.61406)
		(end 160.103566 -310.61406)
		(width 0.14478)
		(layer "In11.Cu")
		(net "M_L_CPU1_SB_DQ<27>")
	)
	(segment
		(start 193.003678 -311.650888)
		(end 193.853308 -312.500518)
		(width 0.14478)
		(layer "In11.Cu")
		(net "M_L_CPU1_SB_DQ<27>")
	)
	(segment
		(start 196.184266 -312.500518)
		(end 197.033896 -311.650888)
		(width 0.14478)
		(layer "In11.Cu")
		(net "M_L_CPU1_SB_DQ<27>")
	)
	(segment
		(start 178.508406 -312.500772)
		(end 181.035706 -312.500772)
		(width 0.14478)
		(layer "In11.Cu")
		(net "M_L_CPU1_SB_DQ<27>")
	)
	(segment
		(start 201.713592 -311.650888)
		(end 202.147932 -312.085228)
		(width 0.14478)
		(layer "In11.Cu")
		(net "M_L_CPU1_SB_DQ<27>")
	)
	(segment
		(start 160.795208 -310.479186)
		(end 160.795208 -310.709818)
		(width 0.14478)
		(layer "In11.Cu")
		(net "M_L_CPU1_SB_DQ<27>")
	)
	(segment
		(start 160.660334 -311.40146)
		(end 160.890966 -311.40146)
		(width 0.14478)
		(layer "In11.Cu")
		(net "M_L_CPU1_SB_DQ<27>")
	)
	(segment
		(start 145.93189 -290.245546)
		(end 145.93189 -291.04971)
		(width 0.0889)
		(layer "In11.Cu")
		(net "M_L_CPU1_SB_DQ<27>")
	)
	(segment
		(start 146.5072 -292.438836)
		(end 146.94027 -292.871906)
		(width 0.0889)
		(layer "In11.Cu")
		(net "M_L_CPU1_SB_DQ<27>")
	)
	(segment
		(start 161.188908 -311.103518)
		(end 161.41954 -311.103518)
		(width 0.14478)
		(layer "In11.Cu")
		(net "M_L_CPU1_SB_DQ<27>")
	)
	(segment
		(start 161.284666 -312.025792)
		(end 161.769298 -312.510424)
		(width 0.14478)
		(layer "In11.Cu")
		(net "M_L_CPU1_SB_DQ<27>")
	)
	(segment
		(start 142.803372 -289.95878)
		(end 142.811754 -289.963606)
		(width 0.0889)
		(layer "In11.Cu")
		(net "M_L_CPU1_SB_DQ<27>")
	)
	(segment
		(start 160.497266 -311.00776)
		(end 160.497266 -311.238392)
		(width 0.14478)
		(layer "In11.Cu")
		(net "M_L_CPU1_SB_DQ<27>")
	)
	(segment
		(start 161.769298 -312.510424)
		(end 165.955726 -312.510424)
		(width 0.14478)
		(layer "In11.Cu")
		(net "M_L_CPU1_SB_DQ<27>")
	)
	(segment
		(start 160.103566 -310.61406)
		(end 160.401508 -310.316118)
		(width 0.14478)
		(layer "In11.Cu")
		(net "M_L_CPU1_SB_DQ<27>")
	)
	(segment
		(start 197.033896 -311.650888)
		(end 201.713592 -311.650888)
		(width 0.14478)
		(layer "In11.Cu")
		(net "M_L_CPU1_SB_DQ<27>")
	)
	(segment
		(start 161.284666 -311.79516)
		(end 161.284666 -312.025792)
		(width 0.14478)
		(layer "In11.Cu")
		(net "M_L_CPU1_SB_DQ<27>")
	)
	(segment
		(start 166.815262 -311.650888)
		(end 170.324272 -311.650888)
		(width 0.14478)
		(layer "In11.Cu")
		(net "M_L_CPU1_SB_DQ<27>")
	)
	(segment
		(start 189.429644 -311.650888)
		(end 193.003678 -311.650888)
		(width 0.14478)
		(layer "In11.Cu")
		(net "M_L_CPU1_SB_DQ<27>")
	)
	(segment
		(start 160.497266 -311.238392)
		(end 160.660334 -311.40146)
		(width 0.14478)
		(layer "In11.Cu")
		(net "M_L_CPU1_SB_DQ<27>")
	)
	(segment
		(start 144.504918 -289.91306)
		(end 145.599404 -289.91306)
		(width 0.0889)
		(layer "In11.Cu")
		(net "M_L_CPU1_SB_DQ<27>")
	)
	(segment
		(start 139.617704 -289.963606)
		(end 139.626086 -289.95878)
		(width 0.0889)
		(layer "In11.Cu")
		(net "M_L_CPU1_SB_DQ<27>")
	)
	(segment
		(start 193.853308 -312.500518)
		(end 196.184266 -312.500518)
		(width 0.14478)
		(layer "In11.Cu")
		(net "M_L_CPU1_SB_DQ<27>")
	)
	(segment
		(start 140.557758 -289.963606)
		(end 140.56614 -289.95878)
		(width 0.0889)
		(layer "In11.Cu")
		(net "M_L_CPU1_SB_DQ<27>")
	)
	(segment
		(start 138.078718 -290.020756)
		(end 138.17473 -289.995356)
		(width 0.0889)
		(layer "In11.Cu")
		(net "M_L_CPU1_SB_DQ<27>")
	)
	(segment
		(start 161.41954 -311.103518)
		(end 161.582608 -311.266586)
		(width 0.14478)
		(layer "In11.Cu")
		(net "M_L_CPU1_SB_DQ<27>")
	)
	(segment
		(start 165.955726 -312.510424)
		(end 166.815262 -311.650888)
		(width 0.14478)
		(layer "In11.Cu")
		(net "M_L_CPU1_SB_DQ<27>")
	)
	(segment
		(start 149.022308 -294.633904)
		(end 149.022308 -299.763434)
		(width 0.14478)
		(layer "In11.Cu")
		(net "M_L_CPU1_SB_DQ<27>")
	)
	(segment
		(start 160.63214 -310.316118)
		(end 160.795208 -310.479186)
		(width 0.14478)
		(layer "In11.Cu")
		(net "M_L_CPU1_SB_DQ<27>")
	)
	(segment
		(start 174.359316 -311.650888)
		(end 177.658522 -311.650888)
		(width 0.14478)
		(layer "In11.Cu")
		(net "M_L_CPU1_SB_DQ<27>")
	)
	(arc
		(start 142.811754 -289.963606)
		(mid 143.09471 -290.039783)
		(end 143.377666 -289.963606)
		(width 0.0889)
		(layer "In11.Cu")
		(net "M_L_CPU1_SB_DQ<27>")
	)
	(arc
		(start 139.626086 -289.95878)
		(mid 139.809594 -289.913286)
		(end 139.991846 -289.963606)
		(width 0.0889)
		(layer "In11.Cu")
		(net "M_L_CPU1_SB_DQ<27>")
	)
	(arc
		(start 143.386048 -289.95878)
		(mid 143.569556 -289.913286)
		(end 143.751808 -289.963606)
		(width 0.0889)
		(layer "In11.Cu")
		(net "M_L_CPU1_SB_DQ<27>")
	)
	(arc
		(start 141.8717 -289.963606)
		(mid 142.154656 -290.039783)
		(end 142.437612 -289.963606)
		(width 0.0889)
		(layer "In11.Cu")
		(net "M_L_CPU1_SB_DQ<27>")
	)
	(arc
		(start 139.051792 -289.963606)
		(mid 139.334748 -290.039783)
		(end 139.617704 -289.963606)
		(width 0.0889)
		(layer "In11.Cu")
		(net "M_L_CPU1_SB_DQ<27>")
	)
	(arc
		(start 138.17473 -289.995356)
		(mid 138.429938 -290.038833)
		(end 138.67765 -289.963606)
		(width 0.0889)
		(layer "In11.Cu")
		(net "M_L_CPU1_SB_DQ<27>")
	)
	(arc
		(start 144.317974 -289.963606)
		(mid 144.408092 -289.925931)
		(end 144.504918 -289.91306)
		(width 0.0889)
		(layer "In11.Cu")
		(net "M_L_CPU1_SB_DQ<27>")
	)
	(arc
		(start 142.437612 -289.963606)
		(mid 142.619863 -289.913256)
		(end 142.803372 -289.95878)
		(width 0.0889)
		(layer "In11.Cu")
		(net "M_L_CPU1_SB_DQ<27>")
	)
	(arc
		(start 143.762222 -289.969702)
		(mid 144.040908 -290.039922)
		(end 144.317974 -289.963606)
		(width 0.0889)
		(layer "In11.Cu")
		(net "M_L_CPU1_SB_DQ<27>")
	)
	(arc
		(start 138.67765 -289.963606)
		(mid 138.859901 -289.913256)
		(end 139.04341 -289.95878)
		(width 0.0889)
		(layer "In11.Cu")
		(net "M_L_CPU1_SB_DQ<27>")
	)
	(arc
		(start 140.9319 -289.963606)
		(mid 141.214856 -290.039783)
		(end 141.497812 -289.963606)
		(width 0.0889)
		(layer "In11.Cu")
		(net "M_L_CPU1_SB_DQ<27>")
	)
	(arc
		(start 139.991846 -289.963606)
		(mid 140.274802 -290.039783)
		(end 140.557758 -289.963606)
		(width 0.0889)
		(layer "In11.Cu")
		(net "M_L_CPU1_SB_DQ<27>")
	)
	(arc
		(start 140.56614 -289.95878)
		(mid 140.749648 -289.913286)
		(end 140.9319 -289.963606)
		(width 0.0889)
		(layer "In11.Cu")
		(net "M_L_CPU1_SB_DQ<27>")
	)
	(arc
		(start 141.497812 -289.963606)
		(mid 141.684756 -289.913351)
		(end 141.8717 -289.963606)
		(width 0.0889)
		(layer "In11.Cu")
		(net "M_L_CPU1_SB_DQ<27>")
	)
	(segment
		(start 138.867896 -289.210242)
		(end 139.334748 -289.47618)
		(width 0.10668)
		(layer "F.Cu")
		(net "M_L_CPU1_SB_DQ<26>")
	)
	(segment
		(start 159.047942 -308.271672)
		(end 159.375602 -307.944012)
		(width 0.14478)
		(layer "In11.Cu")
		(net "M_L_CPU1_SB_DQ<26>")
	)
	(segment
		(start 157.079442 -306.303172)
		(end 157.079442 -306.533804)
		(width 0.14478)
		(layer "In11.Cu")
		(net "M_L_CPU1_SB_DQ<26>")
	)
	(segment
		(start 156.685742 -305.909472)
		(end 157.013402 -305.581812)
		(width 0.14478)
		(layer "In11.Cu")
		(net "M_L_CPU1_SB_DQ<26>")
	)
	(segment
		(start 162.472624 -310.810402)
		(end 166.123874 -310.810402)
		(width 0.14478)
		(layer "In11.Cu")
		(net "M_L_CPU1_SB_DQ<26>")
	)
	(segment
		(start 144.205198 -289.144456)
		(end 144.221454 -289.153854)
		(width 0.0889)
		(layer "In11.Cu")
		(net "M_L_CPU1_SB_DQ<26>")
	)
	(segment
		(start 158.654242 -308.108604)
		(end 158.81731 -308.271672)
		(width 0.14478)
		(layer "In11.Cu")
		(net "M_L_CPU1_SB_DQ<26>")
	)
	(segment
		(start 159.606234 -307.944012)
		(end 162.472624 -310.810402)
		(width 0.14478)
		(layer "In11.Cu")
		(net "M_L_CPU1_SB_DQ<26>")
	)
	(segment
		(start 158.588202 -307.156612)
		(end 158.818834 -307.156612)
		(width 0.14478)
		(layer "In11.Cu")
		(net "M_L_CPU1_SB_DQ<26>")
	)
	(segment
		(start 155.66771 -305.122072)
		(end 155.898342 -305.122072)
		(width 0.14478)
		(layer "In11.Cu")
		(net "M_L_CPU1_SB_DQ<26>")
	)
	(segment
		(start 178.576478 -310.810402)
		(end 181.23789 -310.810402)
		(width 0.14478)
		(layer "In11.Cu")
		(net "M_L_CPU1_SB_DQ<26>")
	)
	(segment
		(start 140.453364 -289.148774)
		(end 140.461746 -289.1536)
		(width 0.0889)
		(layer "In11.Cu")
		(net "M_L_CPU1_SB_DQ<26>")
	)
	(segment
		(start 146.475704 -291.32149)
		(end 146.9263 -291.772086)
		(width 0.0889)
		(layer "In11.Cu")
		(net "M_L_CPU1_SB_DQ<26>")
	)
	(segment
		(start 157.866842 -307.090572)
		(end 157.866842 -307.321204)
		(width 0.14478)
		(layer "In11.Cu")
		(net "M_L_CPU1_SB_DQ<26>")
	)
	(segment
		(start 156.619702 -305.188112)
		(end 156.292042 -305.515772)
		(width 0.14478)
		(layer "In11.Cu")
		(net "M_L_CPU1_SB_DQ<26>")
	)
	(segment
		(start 158.981902 -307.550312)
		(end 158.654242 -307.877972)
		(width 0.14478)
		(layer "In11.Cu")
		(net "M_L_CPU1_SB_DQ<26>")
	)
	(segment
		(start 174.543974 -309.960264)
		(end 177.72634 -309.960264)
		(width 0.14478)
		(layer "In11.Cu")
		(net "M_L_CPU1_SB_DQ<26>")
	)
	(segment
		(start 197.0786 -309.960264)
		(end 199.363076 -309.960264)
		(width 0.14478)
		(layer "In11.Cu")
		(net "M_L_CPU1_SB_DQ<26>")
	)
	(segment
		(start 189.632082 -309.960264)
		(end 192.814448 -309.960264)
		(width 0.14478)
		(layer "In11.Cu")
		(net "M_L_CPU1_SB_DQ<26>")
	)
	(segment
		(start 166.974012 -309.960264)
		(end 170.33367 -309.960264)
		(width 0.14478)
		(layer "In11.Cu")
		(net "M_L_CPU1_SB_DQ<26>")
	)
	(segment
		(start 146.38909 -290.113466)
		(end 146.38909 -291.112448)
		(width 0.0889)
		(layer "In11.Cu")
		(net "M_L_CPU1_SB_DQ<26>")
	)
	(segment
		(start 173.693836 -310.810402)
		(end 174.543974 -309.960264)
		(width 0.14478)
		(layer "In11.Cu")
		(net "M_L_CPU1_SB_DQ<26>")
	)
	(segment
		(start 158.194502 -306.762912)
		(end 157.866842 -307.090572)
		(width 0.14478)
		(layer "In11.Cu")
		(net "M_L_CPU1_SB_DQ<26>")
	)
	(segment
		(start 147.915884 -292.240716)
		(end 149.931628 -294.25646)
		(width 0.14478)
		(layer "In11.Cu")
		(net "M_L_CPU1_SB_DQ<26>")
	)
	(segment
		(start 146.38909 -291.112448)
		(end 146.475704 -291.32149)
		(width 0.0889)
		(layer "In11.Cu")
		(net "M_L_CPU1_SB_DQ<26>")
	)
	(segment
		(start 157.407102 -305.74488)
		(end 157.407102 -305.975512)
		(width 0.14478)
		(layer "In11.Cu")
		(net "M_L_CPU1_SB_DQ<26>")
	)
	(segment
		(start 139.334748 -289.47618)
		(end 139.488672 -289.21075)
		(width 0.0889)
		(layer "In11.Cu")
		(net "M_L_CPU1_SB_DQ<26>")
	)
	(segment
		(start 158.194502 -306.53228)
		(end 158.194502 -306.762912)
		(width 0.14478)
		(layer "In11.Cu")
		(net "M_L_CPU1_SB_DQ<26>")
	)
	(segment
		(start 146.9263 -291.772086)
		(end 147.447254 -291.772086)
		(width 0.0889)
		(layer "In11.Cu")
		(net "M_L_CPU1_SB_DQ<26>")
	)
	(segment
		(start 158.260542 -307.484272)
		(end 158.588202 -307.156612)
		(width 0.14478)
		(layer "In11.Cu")
		(net "M_L_CPU1_SB_DQ<26>")
	)
	(segment
		(start 158.031434 -306.369212)
		(end 158.194502 -306.53228)
		(width 0.14478)
		(layer "In11.Cu")
		(net "M_L_CPU1_SB_DQ<26>")
	)
	(segment
		(start 200.23709 -309.960264)
		(end 200.476104 -309.960264)
		(width 0.14478)
		(layer "In11.Cu")
		(net "M_L_CPU1_SB_DQ<26>")
	)
	(segment
		(start 156.226002 -304.794412)
		(end 156.456634 -304.794412)
		(width 0.14478)
		(layer "In11.Cu")
		(net "M_L_CPU1_SB_DQ<26>")
	)
	(segment
		(start 156.619702 -304.95748)
		(end 156.619702 -305.188112)
		(width 0.14478)
		(layer "In11.Cu")
		(net "M_L_CPU1_SB_DQ<26>")
	)
	(segment
		(start 166.123874 -310.810402)
		(end 166.974012 -309.960264)
		(width 0.14478)
		(layer "In11.Cu")
		(net "M_L_CPU1_SB_DQ<26>")
	)
	(segment
		(start 170.33367 -309.960264)
		(end 171.183808 -310.810402)
		(width 0.14478)
		(layer "In11.Cu")
		(net "M_L_CPU1_SB_DQ<26>")
	)
	(segment
		(start 157.013402 -305.581812)
		(end 157.244034 -305.581812)
		(width 0.14478)
		(layer "In11.Cu")
		(net "M_L_CPU1_SB_DQ<26>")
	)
	(segment
		(start 157.24251 -306.696872)
		(end 157.473142 -306.696872)
		(width 0.14478)
		(layer "In11.Cu")
		(net "M_L_CPU1_SB_DQ<26>")
	)
	(segment
		(start 196.228716 -310.810148)
		(end 197.0786 -309.960264)
		(width 0.14478)
		(layer "In11.Cu")
		(net "M_L_CPU1_SB_DQ<26>")
	)
	(segment
		(start 200.793604 -309.642764)
		(end 201.032618 -309.642764)
		(width 0.14478)
		(layer "In11.Cu")
		(net "M_L_CPU1_SB_DQ<26>")
	)
	(segment
		(start 199.91959 -309.642764)
		(end 200.23709 -309.960264)
		(width 0.14478)
		(layer "In11.Cu")
		(net "M_L_CPU1_SB_DQ<26>")
	)
	(segment
		(start 144.503648 -289.229546)
		(end 145.50517 -289.229546)
		(width 0.0889)
		(layer "In11.Cu")
		(net "M_L_CPU1_SB_DQ<26>")
	)
	(segment
		(start 157.800802 -306.369212)
		(end 158.031434 -306.369212)
		(width 0.14478)
		(layer "In11.Cu")
		(net "M_L_CPU1_SB_DQ<26>")
	)
	(segment
		(start 181.23789 -310.810402)
		(end 182.088028 -309.960264)
		(width 0.14478)
		(layer "In11.Cu")
		(net "M_L_CPU1_SB_DQ<26>")
	)
	(segment
		(start 157.244034 -305.581812)
		(end 157.407102 -305.74488)
		(width 0.14478)
		(layer "In11.Cu")
		(net "M_L_CPU1_SB_DQ<26>")
	)
	(segment
		(start 158.654242 -307.877972)
		(end 158.654242 -308.108604)
		(width 0.14478)
		(layer "In11.Cu")
		(net "M_L_CPU1_SB_DQ<26>")
	)
	(segment
		(start 201.032618 -309.642764)
		(end 201.350118 -309.960264)
		(width 0.14478)
		(layer "In11.Cu")
		(net "M_L_CPU1_SB_DQ<26>")
	)
	(segment
		(start 201.350118 -309.960264)
		(end 201.72299 -309.960264)
		(width 0.14478)
		(layer "In11.Cu")
		(net "M_L_CPU1_SB_DQ<26>")
	)
	(segment
		(start 182.088028 -309.960264)
		(end 185.270394 -309.960264)
		(width 0.14478)
		(layer "In11.Cu")
		(net "M_L_CPU1_SB_DQ<26>")
	)
	(segment
		(start 199.680576 -309.642764)
		(end 199.91959 -309.642764)
		(width 0.14478)
		(layer "In11.Cu")
		(net "M_L_CPU1_SB_DQ<26>")
	)
	(segment
		(start 201.72299 -309.960264)
		(end 202.147932 -310.385206)
		(width 0.14478)
		(layer "In11.Cu")
		(net "M_L_CPU1_SB_DQ<26>")
	)
	(segment
		(start 158.818834 -307.156612)
		(end 158.981902 -307.31968)
		(width 0.14478)
		(layer "In11.Cu")
		(net "M_L_CPU1_SB_DQ<26>")
	)
	(segment
		(start 157.407102 -305.975512)
		(end 157.079442 -306.303172)
		(width 0.14478)
		(layer "In11.Cu")
		(net "M_L_CPU1_SB_DQ<26>")
	)
	(segment
		(start 185.270394 -309.960264)
		(end 186.120532 -310.810402)
		(width 0.14478)
		(layer "In11.Cu")
		(net "M_L_CPU1_SB_DQ<26>")
	)
	(segment
		(start 158.02991 -307.484272)
		(end 158.260542 -307.484272)
		(width 0.14478)
		(layer "In11.Cu")
		(net "M_L_CPU1_SB_DQ<26>")
	)
	(segment
		(start 193.664332 -310.810148)
		(end 196.228716 -310.810148)
		(width 0.14478)
		(layer "In11.Cu")
		(net "M_L_CPU1_SB_DQ<26>")
	)
	(segment
		(start 141.393418 -289.148774)
		(end 141.4018 -289.1536)
		(width 0.0889)
		(layer "In11.Cu")
		(net "M_L_CPU1_SB_DQ<26>")
	)
	(segment
		(start 158.81731 -308.271672)
		(end 159.047942 -308.271672)
		(width 0.14478)
		(layer "In11.Cu")
		(net "M_L_CPU1_SB_DQ<26>")
	)
	(segment
		(start 199.363076 -309.960264)
		(end 199.680576 -309.642764)
		(width 0.14478)
		(layer "In11.Cu")
		(net "M_L_CPU1_SB_DQ<26>")
	)
	(segment
		(start 188.781944 -310.810402)
		(end 189.632082 -309.960264)
		(width 0.14478)
		(layer "In11.Cu")
		(net "M_L_CPU1_SB_DQ<26>")
	)
	(segment
		(start 192.814448 -309.960264)
		(end 193.664332 -310.810148)
		(width 0.14478)
		(layer "In11.Cu")
		(net "M_L_CPU1_SB_DQ<26>")
	)
	(segment
		(start 159.375602 -307.944012)
		(end 159.606234 -307.944012)
		(width 0.14478)
		(layer "In11.Cu")
		(net "M_L_CPU1_SB_DQ<26>")
	)
	(segment
		(start 186.120532 -310.810402)
		(end 188.781944 -310.810402)
		(width 0.14478)
		(layer "In11.Cu")
		(net "M_L_CPU1_SB_DQ<26>")
	)
	(segment
		(start 155.898342 -305.122072)
		(end 156.226002 -304.794412)
		(width 0.14478)
		(layer "In11.Cu")
		(net "M_L_CPU1_SB_DQ<26>")
	)
	(segment
		(start 139.488672 -289.21075)
		(end 139.584684 -289.18535)
		(width 0.0889)
		(layer "In11.Cu")
		(net "M_L_CPU1_SB_DQ<26>")
	)
	(segment
		(start 158.981902 -307.31968)
		(end 158.981902 -307.550312)
		(width 0.14478)
		(layer "In11.Cu")
		(net "M_L_CPU1_SB_DQ<26>")
	)
	(segment
		(start 177.72634 -309.960264)
		(end 178.576478 -310.810402)
		(width 0.14478)
		(layer "In11.Cu")
		(net "M_L_CPU1_SB_DQ<26>")
	)
	(segment
		(start 156.456634 -304.794412)
		(end 156.619702 -304.95748)
		(width 0.14478)
		(layer "In11.Cu")
		(net "M_L_CPU1_SB_DQ<26>")
	)
	(segment
		(start 141.967712 -289.1536)
		(end 141.976094 -289.148774)
		(width 0.0889)
		(layer "In11.Cu")
		(net "M_L_CPU1_SB_DQ<26>")
	)
	(segment
		(start 156.45511 -305.909472)
		(end 156.685742 -305.909472)
		(width 0.14478)
		(layer "In11.Cu")
		(net "M_L_CPU1_SB_DQ<26>")
	)
	(segment
		(start 149.931628 -299.38599)
		(end 155.66771 -305.122072)
		(width 0.14478)
		(layer "In11.Cu")
		(net "M_L_CPU1_SB_DQ<26>")
	)
	(segment
		(start 156.292042 -305.515772)
		(end 156.292042 -305.746404)
		(width 0.14478)
		(layer "In11.Cu")
		(net "M_L_CPU1_SB_DQ<26>")
	)
	(segment
		(start 145.50517 -289.229546)
		(end 146.38909 -290.113466)
		(width 0.0889)
		(layer "In11.Cu")
		(net "M_L_CPU1_SB_DQ<26>")
	)
	(segment
		(start 157.473142 -306.696872)
		(end 157.800802 -306.369212)
		(width 0.14478)
		(layer "In11.Cu")
		(net "M_L_CPU1_SB_DQ<26>")
	)
	(segment
		(start 171.183808 -310.810402)
		(end 173.693836 -310.810402)
		(width 0.14478)
		(layer "In11.Cu")
		(net "M_L_CPU1_SB_DQ<26>")
	)
	(segment
		(start 149.931628 -294.25646)
		(end 149.931628 -299.38599)
		(width 0.14478)
		(layer "In11.Cu")
		(net "M_L_CPU1_SB_DQ<26>")
	)
	(segment
		(start 157.079442 -306.533804)
		(end 157.24251 -306.696872)
		(width 0.14478)
		(layer "In11.Cu")
		(net "M_L_CPU1_SB_DQ<26>")
	)
	(segment
		(start 156.292042 -305.746404)
		(end 156.45511 -305.909472)
		(width 0.14478)
		(layer "In11.Cu")
		(net "M_L_CPU1_SB_DQ<26>")
	)
	(segment
		(start 147.447254 -291.772086)
		(end 147.915884 -292.240716)
		(width 0.0889)
		(layer "In11.Cu")
		(net "M_L_CPU1_SB_DQ<26>")
	)
	(segment
		(start 200.476104 -309.960264)
		(end 200.793604 -309.642764)
		(width 0.14478)
		(layer "In11.Cu")
		(net "M_L_CPU1_SB_DQ<26>")
	)
	(segment
		(start 157.866842 -307.321204)
		(end 158.02991 -307.484272)
		(width 0.14478)
		(layer "In11.Cu")
		(net "M_L_CPU1_SB_DQ<26>")
	)
	(arc
		(start 141.4018 -289.1536)
		(mid 141.684756 -289.229777)
		(end 141.967712 -289.1536)
		(width 0.0889)
		(layer "In11.Cu")
		(net "M_L_CPU1_SB_DQ<26>")
	)
	(arc
		(start 141.027658 -289.1536)
		(mid 141.209909 -289.10325)
		(end 141.393418 -289.148774)
		(width 0.0889)
		(layer "In11.Cu")
		(net "M_L_CPU1_SB_DQ<26>")
	)
	(arc
		(start 141.976094 -289.148774)
		(mid 142.159602 -289.10328)
		(end 142.341854 -289.1536)
		(width 0.0889)
		(layer "In11.Cu")
		(net "M_L_CPU1_SB_DQ<26>")
	)
	(arc
		(start 144.221454 -289.153854)
		(mid 144.357563 -289.210295)
		(end 144.503648 -289.229546)
		(width 0.0889)
		(layer "In11.Cu")
		(net "M_L_CPU1_SB_DQ<26>")
	)
	(arc
		(start 140.461746 -289.1536)
		(mid 140.744702 -289.229777)
		(end 141.027658 -289.1536)
		(width 0.0889)
		(layer "In11.Cu")
		(net "M_L_CPU1_SB_DQ<26>")
	)
	(arc
		(start 143.847566 -289.1536)
		(mid 144.025216 -289.10334)
		(end 144.205198 -289.144456)
		(width 0.0889)
		(layer "In11.Cu")
		(net "M_L_CPU1_SB_DQ<26>")
	)
	(arc
		(start 140.087604 -289.1536)
		(mid 140.269855 -289.10325)
		(end 140.453364 -289.148774)
		(width 0.0889)
		(layer "In11.Cu")
		(net "M_L_CPU1_SB_DQ<26>")
	)
	(arc
		(start 142.907766 -289.1536)
		(mid 143.09471 -289.103345)
		(end 143.281654 -289.1536)
		(width 0.0889)
		(layer "In11.Cu")
		(net "M_L_CPU1_SB_DQ<26>")
	)
	(arc
		(start 142.341854 -289.1536)
		(mid 142.62481 -289.229777)
		(end 142.907766 -289.1536)
		(width 0.0889)
		(layer "In11.Cu")
		(net "M_L_CPU1_SB_DQ<26>")
	)
	(arc
		(start 143.281654 -289.1536)
		(mid 143.56461 -289.229777)
		(end 143.847566 -289.1536)
		(width 0.0889)
		(layer "In11.Cu")
		(net "M_L_CPU1_SB_DQ<26>")
	)
	(arc
		(start 139.584684 -289.18535)
		(mid 139.839892 -289.228827)
		(end 140.087604 -289.1536)
		(width 0.0889)
		(layer "In11.Cu")
		(net "M_L_CPU1_SB_DQ<26>")
	)
	(segment
		(start 137.927842 -289.210242)
		(end 138.394694 -289.47618)
		(width 0.10668)
		(layer "F.Cu")
		(net "M_L_CPU1_SB_DQ<25>")
	)
	(segment
		(start 170.33367 -310.810148)
		(end 171.183808 -311.660286)
		(width 0.14478)
		(layer "In11.Cu")
		(net "M_L_CPU1_SB_DQ<25>")
	)
	(segment
		(start 166.974012 -310.810148)
		(end 170.33367 -310.810148)
		(width 0.14478)
		(layer "In11.Cu")
		(net "M_L_CPU1_SB_DQ<25>")
	)
	(segment
		(start 173.580044 -311.660286)
		(end 174.429928 -310.810402)
		(width 0.14478)
		(layer "In11.Cu")
		(net "M_L_CPU1_SB_DQ<25>")
	)
	(segment
		(start 188.668152 -311.660286)
		(end 189.518036 -310.810402)
		(width 0.14478)
		(layer "In11.Cu")
		(net "M_L_CPU1_SB_DQ<25>")
	)
	(segment
		(start 189.518036 -310.810402)
		(end 192.848484 -310.810402)
		(width 0.14478)
		(layer "In11.Cu")
		(net "M_L_CPU1_SB_DQ<25>")
	)
	(segment
		(start 192.848484 -310.810402)
		(end 193.698114 -311.660032)
		(width 0.14478)
		(layer "In11.Cu")
		(net "M_L_CPU1_SB_DQ<25>")
	)
	(segment
		(start 146.457416 -291.775388)
		(end 146.741896 -292.059868)
		(width 0.0889)
		(layer "In11.Cu")
		(net "M_L_CPU1_SB_DQ<25>")
	)
	(segment
		(start 140.453364 -289.803586)
		(end 140.461746 -289.79876)
		(width 0.0889)
		(layer "In11.Cu")
		(net "M_L_CPU1_SB_DQ<25>")
	)
	(segment
		(start 162.679126 -311.660286)
		(end 166.123874 -311.660286)
		(width 0.14478)
		(layer "In11.Cu")
		(net "M_L_CPU1_SB_DQ<25>")
	)
	(segment
		(start 193.698114 -311.660032)
		(end 196.201538 -311.660032)
		(width 0.14478)
		(layer "In11.Cu")
		(net "M_L_CPU1_SB_DQ<25>")
	)
	(segment
		(start 178.61026 -311.660286)
		(end 181.124098 -311.660286)
		(width 0.14478)
		(layer "In11.Cu")
		(net "M_L_CPU1_SB_DQ<25>")
	)
	(segment
		(start 158.628588 -308.726332)
		(end 159.745172 -308.726332)
		(width 0.14478)
		(layer "In11.Cu")
		(net "M_L_CPU1_SB_DQ<25>")
	)
	(segment
		(start 147.49399 -292.373304)
		(end 147.49399 -292.462204)
		(width 0.0889)
		(layer "In11.Cu")
		(net "M_L_CPU1_SB_DQ<25>")
	)
	(segment
		(start 146.16811 -291.076888)
		(end 146.457416 -291.775388)
		(width 0.0889)
		(layer "In11.Cu")
		(net "M_L_CPU1_SB_DQ<25>")
	)
	(segment
		(start 144.504918 -289.72256)
		(end 145.724118 -289.72256)
		(width 0.0889)
		(layer "In11.Cu")
		(net "M_L_CPU1_SB_DQ<25>")
	)
	(segment
		(start 166.123874 -311.660286)
		(end 166.974012 -310.810148)
		(width 0.14478)
		(layer "In11.Cu")
		(net "M_L_CPU1_SB_DQ<25>")
	)
	(segment
		(start 205.822804 -310.810148)
		(end 206.248 -311.235344)
		(width 0.14478)
		(layer "In11.Cu")
		(net "M_L_CPU1_SB_DQ<25>")
	)
	(segment
		(start 147.180554 -292.059868)
		(end 147.49399 -292.373304)
		(width 0.0889)
		(layer "In11.Cu")
		(net "M_L_CPU1_SB_DQ<25>")
	)
	(segment
		(start 146.16811 -290.166552)
		(end 146.16811 -291.076888)
		(width 0.0889)
		(layer "In11.Cu")
		(net "M_L_CPU1_SB_DQ<25>")
	)
	(segment
		(start 138.24077 -289.74161)
		(end 138.263122 -289.824922)
		(width 0.0889)
		(layer "In11.Cu")
		(net "M_L_CPU1_SB_DQ<25>")
	)
	(segment
		(start 181.124098 -311.660286)
		(end 181.973982 -310.810402)
		(width 0.14478)
		(layer "In11.Cu")
		(net "M_L_CPU1_SB_DQ<25>")
	)
	(segment
		(start 145.724118 -289.72256)
		(end 146.16811 -290.166552)
		(width 0.0889)
		(layer "In11.Cu")
		(net "M_L_CPU1_SB_DQ<25>")
	)
	(segment
		(start 197.051422 -310.810148)
		(end 205.822804 -310.810148)
		(width 0.14478)
		(layer "In11.Cu")
		(net "M_L_CPU1_SB_DQ<25>")
	)
	(segment
		(start 146.741896 -292.059868)
		(end 147.180554 -292.059868)
		(width 0.0889)
		(layer "In11.Cu")
		(net "M_L_CPU1_SB_DQ<25>")
	)
	(segment
		(start 159.745172 -308.726332)
		(end 162.679126 -311.660286)
		(width 0.14478)
		(layer "In11.Cu")
		(net "M_L_CPU1_SB_DQ<25>")
	)
	(segment
		(start 141.967712 -289.79876)
		(end 141.976094 -289.803586)
		(width 0.0889)
		(layer "In11.Cu")
		(net "M_L_CPU1_SB_DQ<25>")
	)
	(segment
		(start 149.476968 -299.574712)
		(end 158.628588 -308.726332)
		(width 0.14478)
		(layer "In11.Cu")
		(net "M_L_CPU1_SB_DQ<25>")
	)
	(segment
		(start 174.429928 -310.810402)
		(end 177.760376 -310.810402)
		(width 0.14478)
		(layer "In11.Cu")
		(net "M_L_CPU1_SB_DQ<25>")
	)
	(segment
		(start 185.30443 -310.810402)
		(end 186.154314 -311.660286)
		(width 0.14478)
		(layer "In11.Cu")
		(net "M_L_CPU1_SB_DQ<25>")
	)
	(segment
		(start 177.760376 -310.810402)
		(end 178.61026 -311.660286)
		(width 0.14478)
		(layer "In11.Cu")
		(net "M_L_CPU1_SB_DQ<25>")
	)
	(segment
		(start 138.394694 -289.47618)
		(end 138.24077 -289.74161)
		(width 0.0889)
		(layer "In11.Cu")
		(net "M_L_CPU1_SB_DQ<25>")
	)
	(segment
		(start 147.49399 -292.462204)
		(end 147.883626 -292.85184)
		(width 0.0889)
		(layer "In11.Cu")
		(net "M_L_CPU1_SB_DQ<25>")
	)
	(segment
		(start 196.201538 -311.660032)
		(end 197.051422 -310.810148)
		(width 0.14478)
		(layer "In11.Cu")
		(net "M_L_CPU1_SB_DQ<25>")
	)
	(segment
		(start 181.973982 -310.810402)
		(end 185.30443 -310.810402)
		(width 0.14478)
		(layer "In11.Cu")
		(net "M_L_CPU1_SB_DQ<25>")
	)
	(segment
		(start 149.476968 -294.445182)
		(end 149.476968 -299.574712)
		(width 0.14478)
		(layer "In11.Cu")
		(net "M_L_CPU1_SB_DQ<25>")
	)
	(segment
		(start 147.883626 -292.85184)
		(end 149.476968 -294.445182)
		(width 0.14478)
		(layer "In11.Cu")
		(net "M_L_CPU1_SB_DQ<25>")
	)
	(segment
		(start 171.183808 -311.660286)
		(end 173.580044 -311.660286)
		(width 0.14478)
		(layer "In11.Cu")
		(net "M_L_CPU1_SB_DQ<25>")
	)
	(segment
		(start 141.393418 -289.803586)
		(end 141.4018 -289.79876)
		(width 0.0889)
		(layer "In11.Cu")
		(net "M_L_CPU1_SB_DQ<25>")
	)
	(segment
		(start 186.154314 -311.660286)
		(end 188.668152 -311.660286)
		(width 0.14478)
		(layer "In11.Cu")
		(net "M_L_CPU1_SB_DQ<25>")
	)
	(arc
		(start 143.281654 -289.79876)
		(mid 143.56461 -289.722583)
		(end 143.847566 -289.79876)
		(width 0.0889)
		(layer "In11.Cu")
		(net "M_L_CPU1_SB_DQ<25>")
	)
	(arc
		(start 138.263122 -289.824922)
		(mid 138.425454 -289.84774)
		(end 138.581892 -289.79876)
		(width 0.0889)
		(layer "In11.Cu")
		(net "M_L_CPU1_SB_DQ<25>")
	)
	(arc
		(start 141.027658 -289.79876)
		(mid 141.209909 -289.84911)
		(end 141.393418 -289.803586)
		(width 0.0889)
		(layer "In11.Cu")
		(net "M_L_CPU1_SB_DQ<25>")
	)
	(arc
		(start 139.521692 -289.79876)
		(mid 139.804648 -289.722583)
		(end 140.087604 -289.79876)
		(width 0.0889)
		(layer "In11.Cu")
		(net "M_L_CPU1_SB_DQ<25>")
	)
	(arc
		(start 141.976094 -289.803586)
		(mid 142.159602 -289.84908)
		(end 142.341854 -289.79876)
		(width 0.0889)
		(layer "In11.Cu")
		(net "M_L_CPU1_SB_DQ<25>")
	)
	(arc
		(start 142.907766 -289.79876)
		(mid 143.09471 -289.849015)
		(end 143.281654 -289.79876)
		(width 0.0889)
		(layer "In11.Cu")
		(net "M_L_CPU1_SB_DQ<25>")
	)
	(arc
		(start 144.221962 -289.79876)
		(mid 144.358383 -289.741881)
		(end 144.504918 -289.72256)
		(width 0.0889)
		(layer "In11.Cu")
		(net "M_L_CPU1_SB_DQ<25>")
	)
	(arc
		(start 140.087604 -289.79876)
		(mid 140.269855 -289.84911)
		(end 140.453364 -289.803586)
		(width 0.0889)
		(layer "In11.Cu")
		(net "M_L_CPU1_SB_DQ<25>")
	)
	(arc
		(start 139.147804 -289.79876)
		(mid 139.334748 -289.849015)
		(end 139.521692 -289.79876)
		(width 0.0889)
		(layer "In11.Cu")
		(net "M_L_CPU1_SB_DQ<25>")
	)
	(arc
		(start 143.847566 -289.79876)
		(mid 144.034764 -289.849142)
		(end 144.221962 -289.79876)
		(width 0.0889)
		(layer "In11.Cu")
		(net "M_L_CPU1_SB_DQ<25>")
	)
	(arc
		(start 138.581892 -289.79876)
		(mid 138.864848 -289.722583)
		(end 139.147804 -289.79876)
		(width 0.0889)
		(layer "In11.Cu")
		(net "M_L_CPU1_SB_DQ<25>")
	)
	(arc
		(start 141.4018 -289.79876)
		(mid 141.684756 -289.722583)
		(end 141.967712 -289.79876)
		(width 0.0889)
		(layer "In11.Cu")
		(net "M_L_CPU1_SB_DQ<25>")
	)
	(arc
		(start 142.341854 -289.79876)
		(mid 142.62481 -289.722583)
		(end 142.907766 -289.79876)
		(width 0.0889)
		(layer "In11.Cu")
		(net "M_L_CPU1_SB_DQ<25>")
	)
	(arc
		(start 140.461746 -289.79876)
		(mid 140.744702 -289.722583)
		(end 141.027658 -289.79876)
		(width 0.0889)
		(layer "In11.Cu")
		(net "M_L_CPU1_SB_DQ<25>")
	)
	(segment
		(start 139.337796 -288.400236)
		(end 139.804648 -288.666174)
		(width 0.10668)
		(layer "F.Cu")
		(net "M_L_CPU1_SB_DQ<24>")
	)
	(segment
		(start 186.055254 -309.960264)
		(end 188.874908 -309.960264)
		(width 0.14478)
		(layer "In11.Cu")
		(net "M_L_CPU1_SB_DQ<24>")
	)
	(segment
		(start 192.749424 -309.11038)
		(end 193.599308 -309.960264)
		(width 0.14478)
		(layer "In11.Cu")
		(net "M_L_CPU1_SB_DQ<24>")
	)
	(segment
		(start 142.803372 -288.99358)
		(end 142.811754 -288.988754)
		(width 0.0889)
		(layer "In11.Cu")
		(net "M_L_CPU1_SB_DQ<24>")
	)
	(segment
		(start 196.220334 -309.96001)
		(end 197.070218 -309.110126)
		(width 0.14478)
		(layer "In11.Cu")
		(net "M_L_CPU1_SB_DQ<24>")
	)
	(segment
		(start 203.641452 -309.972964)
		(end 203.80452 -309.809896)
		(width 0.14478)
		(layer "In11.Cu")
		(net "M_L_CPU1_SB_DQ<24>")
	)
	(segment
		(start 205.080616 -309.110126)
		(end 205.822804 -309.110126)
		(width 0.14478)
		(layer "In11.Cu")
		(net "M_L_CPU1_SB_DQ<24>")
	)
	(segment
		(start 177.661316 -309.11038)
		(end 178.5112 -309.960264)
		(width 0.14478)
		(layer "In11.Cu")
		(net "M_L_CPU1_SB_DQ<24>")
	)
	(segment
		(start 171.183808 -309.960264)
		(end 173.7868 -309.960264)
		(width 0.14478)
		(layer "In11.Cu")
		(net "M_L_CPU1_SB_DQ<24>")
	)
	(segment
		(start 188.874908 -309.960264)
		(end 189.724792 -309.11038)
		(width 0.14478)
		(layer "In11.Cu")
		(net "M_L_CPU1_SB_DQ<24>")
	)
	(segment
		(start 197.070218 -309.110126)
		(end 203.084938 -309.110126)
		(width 0.14478)
		(layer "In11.Cu")
		(net "M_L_CPU1_SB_DQ<24>")
	)
	(segment
		(start 204.917548 -309.273194)
		(end 205.080616 -309.110126)
		(width 0.14478)
		(layer "In11.Cu")
		(net "M_L_CPU1_SB_DQ<24>")
	)
	(segment
		(start 204.75448 -309.972964)
		(end 204.917548 -309.809896)
		(width 0.14478)
		(layer "In11.Cu")
		(net "M_L_CPU1_SB_DQ<24>")
	)
	(segment
		(start 166.974012 -309.110126)
		(end 170.33367 -309.110126)
		(width 0.14478)
		(layer "In11.Cu")
		(net "M_L_CPU1_SB_DQ<24>")
	)
	(segment
		(start 143.377666 -288.988754)
		(end 143.386048 -288.99358)
		(width 0.0889)
		(layer "In11.Cu")
		(net "M_L_CPU1_SB_DQ<24>")
	)
	(segment
		(start 193.599308 -309.960264)
		(end 193.599562 -309.96001)
		(width 0.14478)
		(layer "In11.Cu")
		(net "M_L_CPU1_SB_DQ<24>")
	)
	(segment
		(start 139.650724 -288.931604)
		(end 139.673076 -289.014916)
		(width 0.0889)
		(layer "In11.Cu")
		(net "M_L_CPU1_SB_DQ<24>")
	)
	(segment
		(start 144.503648 -289.039046)
		(end 145.644616 -289.039046)
		(width 0.0889)
		(layer "In11.Cu")
		(net "M_L_CPU1_SB_DQ<24>")
	)
	(segment
		(start 146.83359 -291.195506)
		(end 147.513802 -291.195506)
		(width 0.0889)
		(layer "In11.Cu")
		(net "M_L_CPU1_SB_DQ<24>")
	)
	(segment
		(start 170.33367 -309.110126)
		(end 171.183808 -309.960264)
		(width 0.14478)
		(layer "In11.Cu")
		(net "M_L_CPU1_SB_DQ<24>")
	)
	(segment
		(start 204.917548 -309.809896)
		(end 204.917548 -309.273194)
		(width 0.14478)
		(layer "In11.Cu")
		(net "M_L_CPU1_SB_DQ<24>")
	)
	(segment
		(start 205.822804 -309.110126)
		(end 206.248 -309.535322)
		(width 0.14478)
		(layer "In11.Cu")
		(net "M_L_CPU1_SB_DQ<24>")
	)
	(segment
		(start 203.084938 -309.110126)
		(end 203.248006 -309.273194)
		(width 0.14478)
		(layer "In11.Cu")
		(net "M_L_CPU1_SB_DQ<24>")
	)
	(segment
		(start 173.7868 -309.960264)
		(end 174.636684 -309.11038)
		(width 0.14478)
		(layer "In11.Cu")
		(net "M_L_CPU1_SB_DQ<24>")
	)
	(segment
		(start 185.20537 -309.11038)
		(end 186.055254 -309.960264)
		(width 0.14478)
		(layer "In11.Cu")
		(net "M_L_CPU1_SB_DQ<24>")
	)
	(segment
		(start 203.411074 -309.972964)
		(end 203.641452 -309.972964)
		(width 0.14478)
		(layer "In11.Cu")
		(net "M_L_CPU1_SB_DQ<24>")
	)
	(segment
		(start 150.386288 -299.197522)
		(end 155.456636 -304.26787)
		(width 0.14478)
		(layer "In11.Cu")
		(net "M_L_CPU1_SB_DQ<24>")
	)
	(segment
		(start 145.644616 -289.039046)
		(end 146.63547 -290.0299)
		(width 0.0889)
		(layer "In11.Cu")
		(net "M_L_CPU1_SB_DQ<24>")
	)
	(segment
		(start 162.412934 -309.960264)
		(end 166.123874 -309.960264)
		(width 0.14478)
		(layer "In11.Cu")
		(net "M_L_CPU1_SB_DQ<24>")
	)
	(segment
		(start 147.877276 -291.55898)
		(end 150.386288 -294.067992)
		(width 0.14478)
		(layer "In11.Cu")
		(net "M_L_CPU1_SB_DQ<24>")
	)
	(segment
		(start 147.513802 -291.195506)
		(end 147.877276 -291.55898)
		(width 0.0889)
		(layer "In11.Cu")
		(net "M_L_CPU1_SB_DQ<24>")
	)
	(segment
		(start 182.180738 -309.11038)
		(end 185.20537 -309.11038)
		(width 0.14478)
		(layer "In11.Cu")
		(net "M_L_CPU1_SB_DQ<24>")
	)
	(segment
		(start 144.30502 -288.981642)
		(end 144.316958 -288.9885)
		(width 0.0889)
		(layer "In11.Cu")
		(net "M_L_CPU1_SB_DQ<24>")
	)
	(segment
		(start 203.967588 -309.110126)
		(end 204.197966 -309.110126)
		(width 0.14478)
		(layer "In11.Cu")
		(net "M_L_CPU1_SB_DQ<24>")
	)
	(segment
		(start 150.386288 -294.067992)
		(end 150.386288 -299.197522)
		(width 0.14478)
		(layer "In11.Cu")
		(net "M_L_CPU1_SB_DQ<24>")
	)
	(segment
		(start 146.63547 -290.0299)
		(end 146.63547 -290.997386)
		(width 0.0889)
		(layer "In11.Cu")
		(net "M_L_CPU1_SB_DQ<24>")
	)
	(segment
		(start 203.248006 -309.809896)
		(end 203.411074 -309.972964)
		(width 0.14478)
		(layer "In11.Cu")
		(net "M_L_CPU1_SB_DQ<24>")
	)
	(segment
		(start 204.361034 -309.809896)
		(end 204.524102 -309.972964)
		(width 0.14478)
		(layer "In11.Cu")
		(net "M_L_CPU1_SB_DQ<24>")
	)
	(segment
		(start 193.599562 -309.96001)
		(end 196.220334 -309.96001)
		(width 0.14478)
		(layer "In11.Cu")
		(net "M_L_CPU1_SB_DQ<24>")
	)
	(segment
		(start 203.248006 -309.273194)
		(end 203.248006 -309.809896)
		(width 0.14478)
		(layer "In11.Cu")
		(net "M_L_CPU1_SB_DQ<24>")
	)
	(segment
		(start 174.636684 -309.11038)
		(end 177.661316 -309.11038)
		(width 0.14478)
		(layer "In11.Cu")
		(net "M_L_CPU1_SB_DQ<24>")
	)
	(segment
		(start 156.72054 -304.26787)
		(end 162.412934 -309.960264)
		(width 0.14478)
		(layer "In11.Cu")
		(net "M_L_CPU1_SB_DQ<24>")
	)
	(segment
		(start 139.804648 -288.666174)
		(end 139.650724 -288.931604)
		(width 0.0889)
		(layer "In11.Cu")
		(net "M_L_CPU1_SB_DQ<24>")
	)
	(segment
		(start 204.524102 -309.972964)
		(end 204.75448 -309.972964)
		(width 0.14478)
		(layer "In11.Cu")
		(net "M_L_CPU1_SB_DQ<24>")
	)
	(segment
		(start 166.123874 -309.960264)
		(end 166.974012 -309.110126)
		(width 0.14478)
		(layer "In11.Cu")
		(net "M_L_CPU1_SB_DQ<24>")
	)
	(segment
		(start 178.5112 -309.960264)
		(end 181.330854 -309.960264)
		(width 0.14478)
		(layer "In11.Cu")
		(net "M_L_CPU1_SB_DQ<24>")
	)
	(segment
		(start 155.456636 -304.26787)
		(end 156.72054 -304.26787)
		(width 0.14478)
		(layer "In11.Cu")
		(net "M_L_CPU1_SB_DQ<24>")
	)
	(segment
		(start 189.724792 -309.11038)
		(end 192.749424 -309.11038)
		(width 0.14478)
		(layer "In11.Cu")
		(net "M_L_CPU1_SB_DQ<24>")
	)
	(segment
		(start 146.63547 -290.997386)
		(end 146.83359 -291.195506)
		(width 0.0889)
		(layer "In11.Cu")
		(net "M_L_CPU1_SB_DQ<24>")
	)
	(segment
		(start 203.80452 -309.809896)
		(end 203.80452 -309.273194)
		(width 0.14478)
		(layer "In11.Cu")
		(net "M_L_CPU1_SB_DQ<24>")
	)
	(segment
		(start 181.330854 -309.960264)
		(end 182.180738 -309.11038)
		(width 0.14478)
		(layer "In11.Cu")
		(net "M_L_CPU1_SB_DQ<24>")
	)
	(segment
		(start 203.80452 -309.273194)
		(end 203.967588 -309.110126)
		(width 0.14478)
		(layer "In11.Cu")
		(net "M_L_CPU1_SB_DQ<24>")
	)
	(segment
		(start 140.557758 -288.988754)
		(end 140.56614 -288.99358)
		(width 0.0889)
		(layer "In11.Cu")
		(net "M_L_CPU1_SB_DQ<24>")
	)
	(segment
		(start 204.197966 -309.110126)
		(end 204.361034 -309.273194)
		(width 0.14478)
		(layer "In11.Cu")
		(net "M_L_CPU1_SB_DQ<24>")
	)
	(segment
		(start 204.361034 -309.273194)
		(end 204.361034 -309.809896)
		(width 0.14478)
		(layer "In11.Cu")
		(net "M_L_CPU1_SB_DQ<24>")
	)
	(arc
		(start 143.751808 -288.988754)
		(mid 144.027486 -288.912624)
		(end 144.30502 -288.981642)
		(width 0.0889)
		(layer "In11.Cu")
		(net "M_L_CPU1_SB_DQ<24>")
	)
	(arc
		(start 142.437612 -288.988754)
		(mid 142.619863 -289.039104)
		(end 142.803372 -288.99358)
		(width 0.0889)
		(layer "In11.Cu")
		(net "M_L_CPU1_SB_DQ<24>")
	)
	(arc
		(start 140.56614 -288.99358)
		(mid 140.749648 -289.039074)
		(end 140.9319 -288.988754)
		(width 0.0889)
		(layer "In11.Cu")
		(net "M_L_CPU1_SB_DQ<24>")
	)
	(arc
		(start 141.8717 -288.988754)
		(mid 142.154656 -288.912577)
		(end 142.437612 -288.988754)
		(width 0.0889)
		(layer "In11.Cu")
		(net "M_L_CPU1_SB_DQ<24>")
	)
	(arc
		(start 140.9319 -288.988754)
		(mid 141.214856 -288.912577)
		(end 141.497812 -288.988754)
		(width 0.0889)
		(layer "In11.Cu")
		(net "M_L_CPU1_SB_DQ<24>")
	)
	(arc
		(start 141.497812 -288.988754)
		(mid 141.684756 -289.039009)
		(end 141.8717 -288.988754)
		(width 0.0889)
		(layer "In11.Cu")
		(net "M_L_CPU1_SB_DQ<24>")
	)
	(arc
		(start 143.386048 -288.99358)
		(mid 143.569556 -289.039074)
		(end 143.751808 -288.988754)
		(width 0.0889)
		(layer "In11.Cu")
		(net "M_L_CPU1_SB_DQ<24>")
	)
	(arc
		(start 139.673076 -289.014916)
		(mid 139.835408 -289.037734)
		(end 139.991846 -288.988754)
		(width 0.0889)
		(layer "In11.Cu")
		(net "M_L_CPU1_SB_DQ<24>")
	)
	(arc
		(start 142.811754 -288.988754)
		(mid 143.09471 -288.912577)
		(end 143.377666 -288.988754)
		(width 0.0889)
		(layer "In11.Cu")
		(net "M_L_CPU1_SB_DQ<24>")
	)
	(arc
		(start 144.316958 -288.9885)
		(mid 144.406969 -289.026087)
		(end 144.503648 -289.039046)
		(width 0.0889)
		(layer "In11.Cu")
		(net "M_L_CPU1_SB_DQ<24>")
	)
	(arc
		(start 139.991846 -288.988754)
		(mid 140.274802 -288.912577)
		(end 140.557758 -288.988754)
		(width 0.0889)
		(layer "In11.Cu")
		(net "M_L_CPU1_SB_DQ<24>")
	)
	(segment
		(start 137.457942 -288.400236)
		(end 137.924794 -288.666174)
		(width 0.10668)
		(layer "F.Cu")
		(net "M_L_CPU1_SB_DQ<23>")
	)
	(segment
		(start 155.479496 -302.575214)
		(end 155.710128 -302.575214)
		(width 0.14478)
		(layer "In11.Cu")
		(net "M_L_CPU1_SB_DQ<23>")
	)
	(segment
		(start 139.04341 -288.339022)
		(end 139.051792 -288.343848)
		(width 0.0889)
		(layer "In11.Cu")
		(net "M_L_CPU1_SB_DQ<23>")
	)
	(segment
		(start 200.233788 -308.260496)
		(end 200.378568 -308.115716)
		(width 0.14478)
		(layer "In11.Cu")
		(net "M_L_CPU1_SB_DQ<23>")
	)
	(segment
		(start 156.266896 -303.362614)
		(end 156.60243 -303.362614)
		(width 0.14478)
		(layer "In11.Cu")
		(net "M_L_CPU1_SB_DQ<23>")
	)
	(segment
		(start 145.94713 -288.995866)
		(end 146.78279 -289.831526)
		(width 0.0889)
		(layer "In11.Cu")
		(net "M_L_CPU1_SB_DQ<23>")
	)
	(segment
		(start 154.899868 -302.923956)
		(end 155.1305 -302.92421)
		(width 0.14478)
		(layer "In11.Cu")
		(net "M_L_CPU1_SB_DQ<23>")
	)
	(segment
		(start 166.974012 -308.260242)
		(end 170.270932 -308.260242)
		(width 0.14478)
		(layer "In11.Cu")
		(net "M_L_CPU1_SB_DQ<23>")
	)
	(segment
		(start 155.710128 -302.575214)
		(end 155.87345 -302.738536)
		(width 0.14478)
		(layer "In11.Cu")
		(net "M_L_CPU1_SB_DQ<23>")
	)
	(segment
		(start 200.523348 -307.868066)
		(end 200.785222 -307.868066)
		(width 0.14478)
		(layer "In11.Cu")
		(net "M_L_CPU1_SB_DQ<23>")
	)
	(segment
		(start 189.632082 -308.260496)
		(end 192.814448 -308.260496)
		(width 0.14478)
		(layer "In11.Cu")
		(net "M_L_CPU1_SB_DQ<23>")
	)
	(segment
		(start 156.60243 -303.362614)
		(end 162.350196 -309.11038)
		(width 0.14478)
		(layer "In11.Cu")
		(net "M_L_CPU1_SB_DQ<23>")
	)
	(segment
		(start 147.839684 -290.733988)
		(end 150.942548 -293.836852)
		(width 0.14478)
		(layer "In11.Cu")
		(net "M_L_CPU1_SB_DQ<23>")
	)
	(segment
		(start 196.161152 -309.110126)
		(end 197.010782 -308.260496)
		(width 0.14478)
		(layer "In11.Cu")
		(net "M_L_CPU1_SB_DQ<23>")
	)
	(segment
		(start 150.942548 -293.836852)
		(end 150.942548 -298.966636)
		(width 0.14478)
		(layer "In11.Cu")
		(net "M_L_CPU1_SB_DQ<23>")
	)
	(segment
		(start 201.074782 -308.260496)
		(end 201.72299 -308.260496)
		(width 0.14478)
		(layer "In11.Cu")
		(net "M_L_CPU1_SB_DQ<23>")
	)
	(segment
		(start 170.270932 -308.260242)
		(end 171.121324 -309.110634)
		(width 0.14478)
		(layer "In11.Cu")
		(net "M_L_CPU1_SB_DQ<23>")
	)
	(segment
		(start 197.010782 -308.260496)
		(end 200.233788 -308.260496)
		(width 0.14478)
		(layer "In11.Cu")
		(net "M_L_CPU1_SB_DQ<23>")
	)
	(segment
		(start 143.377666 -288.343848)
		(end 143.386048 -288.339022)
		(width 0.0889)
		(layer "In11.Cu")
		(net "M_L_CPU1_SB_DQ<23>")
	)
	(segment
		(start 155.9179 -303.71161)
		(end 156.266896 -303.362614)
		(width 0.14478)
		(layer "In11.Cu")
		(net "M_L_CPU1_SB_DQ<23>")
	)
	(segment
		(start 138.078718 -288.400744)
		(end 138.174476 -288.375344)
		(width 0.0889)
		(layer "In11.Cu")
		(net "M_L_CPU1_SB_DQ<23>")
	)
	(segment
		(start 185.270394 -308.260496)
		(end 186.120532 -309.110634)
		(width 0.14478)
		(layer "In11.Cu")
		(net "M_L_CPU1_SB_DQ<23>")
	)
	(segment
		(start 201.72299 -308.260496)
		(end 202.147932 -308.685438)
		(width 0.14478)
		(layer "In11.Cu")
		(net "M_L_CPU1_SB_DQ<23>")
	)
	(segment
		(start 155.687268 -303.711356)
		(end 155.9179 -303.71161)
		(width 0.14478)
		(layer "In11.Cu")
		(net "M_L_CPU1_SB_DQ<23>")
	)
	(segment
		(start 137.924794 -288.666174)
		(end 138.078718 -288.400744)
		(width 0.0889)
		(layer "In11.Cu")
		(net "M_L_CPU1_SB_DQ<23>")
	)
	(segment
		(start 139.617704 -288.343848)
		(end 139.626086 -288.339022)
		(width 0.0889)
		(layer "In11.Cu")
		(net "M_L_CPU1_SB_DQ<23>")
	)
	(segment
		(start 177.72634 -308.260496)
		(end 178.576478 -309.110634)
		(width 0.14478)
		(layer "In11.Cu")
		(net "M_L_CPU1_SB_DQ<23>")
	)
	(segment
		(start 200.378568 -308.115716)
		(end 200.378568 -308.012846)
		(width 0.14478)
		(layer "In11.Cu")
		(net "M_L_CPU1_SB_DQ<23>")
	)
	(segment
		(start 146.937222 -289.831526)
		(end 147.839684 -290.733988)
		(width 0.0889)
		(layer "In11.Cu")
		(net "M_L_CPU1_SB_DQ<23>")
	)
	(segment
		(start 144.31772 -288.343848)
		(end 144.326102 -288.339022)
		(width 0.0889)
		(layer "In11.Cu")
		(net "M_L_CPU1_SB_DQ<23>")
	)
	(segment
		(start 142.803372 -288.339022)
		(end 142.811754 -288.343848)
		(width 0.0889)
		(layer "In11.Cu")
		(net "M_L_CPU1_SB_DQ<23>")
	)
	(segment
		(start 144.529302 -288.294318)
		(end 145.679922 -288.294318)
		(width 0.0889)
		(layer "In11.Cu")
		(net "M_L_CPU1_SB_DQ<23>")
	)
	(segment
		(start 173.693836 -309.110634)
		(end 174.543974 -308.260496)
		(width 0.14478)
		(layer "In11.Cu")
		(net "M_L_CPU1_SB_DQ<23>")
	)
	(segment
		(start 192.814448 -308.260496)
		(end 193.664078 -309.110126)
		(width 0.14478)
		(layer "In11.Cu")
		(net "M_L_CPU1_SB_DQ<23>")
	)
	(segment
		(start 140.557758 -288.343848)
		(end 140.56614 -288.339022)
		(width 0.0889)
		(layer "In11.Cu")
		(net "M_L_CPU1_SB_DQ<23>")
	)
	(segment
		(start 174.543974 -308.260496)
		(end 177.72634 -308.260496)
		(width 0.14478)
		(layer "In11.Cu")
		(net "M_L_CPU1_SB_DQ<23>")
	)
	(segment
		(start 181.23789 -309.110634)
		(end 182.088028 -308.260496)
		(width 0.14478)
		(layer "In11.Cu")
		(net "M_L_CPU1_SB_DQ<23>")
	)
	(segment
		(start 155.5242 -303.548288)
		(end 155.687268 -303.711356)
		(width 0.14478)
		(layer "In11.Cu")
		(net "M_L_CPU1_SB_DQ<23>")
	)
	(segment
		(start 171.121324 -309.110634)
		(end 173.693836 -309.110634)
		(width 0.14478)
		(layer "In11.Cu")
		(net "M_L_CPU1_SB_DQ<23>")
	)
	(segment
		(start 145.94713 -288.561526)
		(end 145.94713 -288.995866)
		(width 0.0889)
		(layer "In11.Cu")
		(net "M_L_CPU1_SB_DQ<23>")
	)
	(segment
		(start 146.78279 -289.831526)
		(end 146.937222 -289.831526)
		(width 0.0889)
		(layer "In11.Cu")
		(net "M_L_CPU1_SB_DQ<23>")
	)
	(segment
		(start 200.930002 -308.115716)
		(end 201.074782 -308.260496)
		(width 0.14478)
		(layer "In11.Cu")
		(net "M_L_CPU1_SB_DQ<23>")
	)
	(segment
		(start 200.930002 -308.012846)
		(end 200.930002 -308.115716)
		(width 0.14478)
		(layer "In11.Cu")
		(net "M_L_CPU1_SB_DQ<23>")
	)
	(segment
		(start 200.378568 -308.012846)
		(end 200.523348 -307.868066)
		(width 0.14478)
		(layer "In11.Cu")
		(net "M_L_CPU1_SB_DQ<23>")
	)
	(segment
		(start 182.088028 -308.260496)
		(end 185.270394 -308.260496)
		(width 0.14478)
		(layer "In11.Cu")
		(net "M_L_CPU1_SB_DQ<23>")
	)
	(segment
		(start 166.123874 -309.11038)
		(end 166.974012 -308.260242)
		(width 0.14478)
		(layer "In11.Cu")
		(net "M_L_CPU1_SB_DQ<23>")
	)
	(segment
		(start 193.664078 -309.110126)
		(end 196.161152 -309.110126)
		(width 0.14478)
		(layer "In11.Cu")
		(net "M_L_CPU1_SB_DQ<23>")
	)
	(segment
		(start 150.942548 -298.966636)
		(end 154.899868 -302.923956)
		(width 0.14478)
		(layer "In11.Cu")
		(net "M_L_CPU1_SB_DQ<23>")
	)
	(segment
		(start 162.350196 -309.11038)
		(end 166.123874 -309.11038)
		(width 0.14478)
		(layer "In11.Cu")
		(net "M_L_CPU1_SB_DQ<23>")
	)
	(segment
		(start 155.873196 -302.96866)
		(end 155.5242 -303.317656)
		(width 0.14478)
		(layer "In11.Cu")
		(net "M_L_CPU1_SB_DQ<23>")
	)
	(segment
		(start 155.87345 -302.738536)
		(end 155.873196 -302.96866)
		(width 0.14478)
		(layer "In11.Cu")
		(net "M_L_CPU1_SB_DQ<23>")
	)
	(segment
		(start 155.5242 -303.317656)
		(end 155.5242 -303.548288)
		(width 0.14478)
		(layer "In11.Cu")
		(net "M_L_CPU1_SB_DQ<23>")
	)
	(segment
		(start 145.679922 -288.294318)
		(end 145.94713 -288.561526)
		(width 0.0889)
		(layer "In11.Cu")
		(net "M_L_CPU1_SB_DQ<23>")
	)
	(segment
		(start 178.576478 -309.110634)
		(end 181.23789 -309.110634)
		(width 0.14478)
		(layer "In11.Cu")
		(net "M_L_CPU1_SB_DQ<23>")
	)
	(segment
		(start 200.785222 -307.868066)
		(end 200.930002 -308.012846)
		(width 0.14478)
		(layer "In11.Cu")
		(net "M_L_CPU1_SB_DQ<23>")
	)
	(segment
		(start 186.120532 -309.110634)
		(end 188.781944 -309.110634)
		(width 0.14478)
		(layer "In11.Cu")
		(net "M_L_CPU1_SB_DQ<23>")
	)
	(segment
		(start 188.781944 -309.110634)
		(end 189.632082 -308.260496)
		(width 0.14478)
		(layer "In11.Cu")
		(net "M_L_CPU1_SB_DQ<23>")
	)
	(segment
		(start 155.1305 -302.92421)
		(end 155.479496 -302.575214)
		(width 0.14478)
		(layer "In11.Cu")
		(net "M_L_CPU1_SB_DQ<23>")
	)
	(arc
		(start 140.56614 -288.339022)
		(mid 140.749648 -288.293497)
		(end 140.9319 -288.343848)
		(width 0.0889)
		(layer "In11.Cu")
		(net "M_L_CPU1_SB_DQ<23>")
	)
	(arc
		(start 139.626086 -288.339022)
		(mid 139.809594 -288.293497)
		(end 139.991846 -288.343848)
		(width 0.0889)
		(layer "In11.Cu")
		(net "M_L_CPU1_SB_DQ<23>")
	)
	(arc
		(start 143.386048 -288.339022)
		(mid 143.569556 -288.293497)
		(end 143.751808 -288.343848)
		(width 0.0889)
		(layer "In11.Cu")
		(net "M_L_CPU1_SB_DQ<23>")
	)
	(arc
		(start 141.497812 -288.343848)
		(mid 141.684756 -288.293559)
		(end 141.8717 -288.343848)
		(width 0.0889)
		(layer "In11.Cu")
		(net "M_L_CPU1_SB_DQ<23>")
	)
	(arc
		(start 138.67765 -288.343848)
		(mid 138.859901 -288.293464)
		(end 139.04341 -288.339022)
		(width 0.0889)
		(layer "In11.Cu")
		(net "M_L_CPU1_SB_DQ<23>")
	)
	(arc
		(start 138.174476 -288.375344)
		(mid 138.429798 -288.419044)
		(end 138.67765 -288.343848)
		(width 0.0889)
		(layer "In11.Cu")
		(net "M_L_CPU1_SB_DQ<23>")
	)
	(arc
		(start 142.437612 -288.343848)
		(mid 142.619863 -288.293464)
		(end 142.803372 -288.339022)
		(width 0.0889)
		(layer "In11.Cu")
		(net "M_L_CPU1_SB_DQ<23>")
	)
	(arc
		(start 142.811754 -288.343848)
		(mid 143.09471 -288.420025)
		(end 143.377666 -288.343848)
		(width 0.0889)
		(layer "In11.Cu")
		(net "M_L_CPU1_SB_DQ<23>")
	)
	(arc
		(start 141.8717 -288.343848)
		(mid 142.154656 -288.420025)
		(end 142.437612 -288.343848)
		(width 0.0889)
		(layer "In11.Cu")
		(net "M_L_CPU1_SB_DQ<23>")
	)
	(arc
		(start 139.051792 -288.343848)
		(mid 139.334748 -288.420025)
		(end 139.617704 -288.343848)
		(width 0.0889)
		(layer "In11.Cu")
		(net "M_L_CPU1_SB_DQ<23>")
	)
	(arc
		(start 140.9319 -288.343848)
		(mid 141.214856 -288.420025)
		(end 141.497812 -288.343848)
		(width 0.0889)
		(layer "In11.Cu")
		(net "M_L_CPU1_SB_DQ<23>")
	)
	(arc
		(start 139.991846 -288.343848)
		(mid 140.274802 -288.420025)
		(end 140.557758 -288.343848)
		(width 0.0889)
		(layer "In11.Cu")
		(net "M_L_CPU1_SB_DQ<23>")
	)
	(arc
		(start 143.751808 -288.343848)
		(mid 144.034764 -288.420025)
		(end 144.31772 -288.343848)
		(width 0.0889)
		(layer "In11.Cu")
		(net "M_L_CPU1_SB_DQ<23>")
	)
	(arc
		(start 144.326102 -288.339022)
		(mid 144.424518 -288.302183)
		(end 144.529302 -288.294318)
		(width 0.0889)
		(layer "In11.Cu")
		(net "M_L_CPU1_SB_DQ<23>")
	)
	(segment
		(start 138.867896 -287.590484)
		(end 139.334748 -287.856422)
		(width 0.10668)
		(layer "F.Cu")
		(net "M_L_CPU1_SB_DQ<22>")
	)
	(segment
		(start 152.384506 -297.85818)
		(end 152.384506 -298.088812)
		(width 0.14478)
		(layer "In11.Cu")
		(net "M_L_CPU1_SB_DQ<22>")
	)
	(segment
		(start 154.345386 -300.852332)
		(end 154.345386 -301.082964)
		(width 0.14478)
		(layer "In11.Cu")
		(net "M_L_CPU1_SB_DQ<22>")
	)
	(segment
		(start 167.955976 -306.56022)
		(end 170.205654 -306.56022)
		(width 0.14478)
		(layer "In11.Cu")
		(net "M_L_CPU1_SB_DQ<22>")
	)
	(segment
		(start 152.384506 -298.088812)
		(end 151.983186 -298.490132)
		(width 0.14478)
		(layer "In11.Cu")
		(net "M_L_CPU1_SB_DQ<22>")
	)
	(segment
		(start 161.936684 -307.410358)
		(end 165.903402 -307.410358)
		(width 0.14478)
		(layer "In11.Cu")
		(net "M_L_CPU1_SB_DQ<22>")
	)
	(segment
		(start 152.770586 -299.508164)
		(end 152.933654 -299.671232)
		(width 0.14478)
		(layer "In11.Cu")
		(net "M_L_CPU1_SB_DQ<22>")
	)
	(segment
		(start 146.000724 -287.610042)
		(end 147.749006 -289.358324)
		(width 0.0889)
		(layer "In11.Cu")
		(net "M_L_CPU1_SB_DQ<22>")
	)
	(segment
		(start 154.746706 -300.22038)
		(end 154.746706 -300.451012)
		(width 0.14478)
		(layer "In11.Cu")
		(net "M_L_CPU1_SB_DQ<22>")
	)
	(segment
		(start 170.205654 -306.56022)
		(end 171.056046 -307.410612)
		(width 0.14478)
		(layer "In11.Cu")
		(net "M_L_CPU1_SB_DQ<22>")
	)
	(segment
		(start 165.903402 -307.410358)
		(end 167.955976 -306.56022)
		(width 0.14478)
		(layer "In11.Cu")
		(net "M_L_CPU1_SB_DQ<22>")
	)
	(segment
		(start 155.371038 -300.844712)
		(end 161.936684 -307.410358)
		(width 0.14478)
		(layer "In11.Cu")
		(net "M_L_CPU1_SB_DQ<22>")
	)
	(segment
		(start 154.345386 -301.082964)
		(end 154.508454 -301.246032)
		(width 0.14478)
		(layer "In11.Cu")
		(net "M_L_CPU1_SB_DQ<22>")
	)
	(segment
		(start 201.72299 -306.560474)
		(end 202.147932 -306.985416)
		(width 0.14478)
		(layer "In11.Cu")
		(net "M_L_CPU1_SB_DQ<22>")
	)
	(segment
		(start 174.543974 -306.560474)
		(end 177.519076 -306.560474)
		(width 0.14478)
		(layer "In11.Cu")
		(net "M_L_CPU1_SB_DQ<22>")
	)
	(segment
		(start 152.933654 -299.671232)
		(end 153.164286 -299.671232)
		(width 0.14478)
		(layer "In11.Cu")
		(net "M_L_CPU1_SB_DQ<22>")
	)
	(segment
		(start 188.781944 -307.410612)
		(end 189.632082 -306.560474)
		(width 0.14478)
		(layer "In11.Cu")
		(net "M_L_CPU1_SB_DQ<22>")
	)
	(segment
		(start 153.959306 -299.43298)
		(end 153.959306 -299.663612)
		(width 0.14478)
		(layer "In11.Cu")
		(net "M_L_CPU1_SB_DQ<22>")
	)
	(segment
		(start 153.171906 -298.876212)
		(end 152.770586 -299.277532)
		(width 0.14478)
		(layer "In11.Cu")
		(net "M_L_CPU1_SB_DQ<22>")
	)
	(segment
		(start 141.393418 -287.529016)
		(end 141.4018 -287.533842)
		(width 0.0889)
		(layer "In11.Cu")
		(net "M_L_CPU1_SB_DQ<22>")
	)
	(segment
		(start 139.334748 -287.856422)
		(end 139.488672 -287.590992)
		(width 0.0889)
		(layer "In11.Cu")
		(net "M_L_CPU1_SB_DQ<22>")
	)
	(segment
		(start 153.557986 -300.295564)
		(end 153.721054 -300.458632)
		(width 0.14478)
		(layer "In11.Cu")
		(net "M_L_CPU1_SB_DQ<22>")
	)
	(segment
		(start 182.088028 -306.560474)
		(end 184.258458 -306.560474)
		(width 0.14478)
		(layer "In11.Cu")
		(net "M_L_CPU1_SB_DQ<22>")
	)
	(segment
		(start 144.504918 -287.610042)
		(end 146.000724 -287.610042)
		(width 0.0889)
		(layer "In11.Cu")
		(net "M_L_CPU1_SB_DQ<22>")
	)
	(segment
		(start 153.796238 -299.269912)
		(end 153.959306 -299.43298)
		(width 0.14478)
		(layer "In11.Cu")
		(net "M_L_CPU1_SB_DQ<22>")
	)
	(segment
		(start 153.557986 -300.064932)
		(end 153.557986 -300.295564)
		(width 0.14478)
		(layer "In11.Cu")
		(net "M_L_CPU1_SB_DQ<22>")
	)
	(segment
		(start 141.967712 -287.533842)
		(end 141.976094 -287.529016)
		(width 0.0889)
		(layer "In11.Cu")
		(net "M_L_CPU1_SB_DQ<22>")
	)
	(segment
		(start 139.488672 -287.590992)
		(end 139.584684 -287.565592)
		(width 0.0889)
		(layer "In11.Cu")
		(net "M_L_CPU1_SB_DQ<22>")
	)
	(segment
		(start 140.453364 -287.529016)
		(end 140.461746 -287.533842)
		(width 0.0889)
		(layer "In11.Cu")
		(net "M_L_CPU1_SB_DQ<22>")
	)
	(segment
		(start 151.983186 -298.490132)
		(end 151.983186 -298.720764)
		(width 0.14478)
		(layer "In11.Cu")
		(net "M_L_CPU1_SB_DQ<22>")
	)
	(segment
		(start 155.140406 -300.844712)
		(end 155.371038 -300.844712)
		(width 0.14478)
		(layer "In11.Cu")
		(net "M_L_CPU1_SB_DQ<22>")
	)
	(segment
		(start 153.959306 -299.663612)
		(end 153.557986 -300.064932)
		(width 0.14478)
		(layer "In11.Cu")
		(net "M_L_CPU1_SB_DQ<22>")
	)
	(segment
		(start 192.590928 -306.560474)
		(end 193.440558 -307.410104)
		(width 0.14478)
		(layer "In11.Cu")
		(net "M_L_CPU1_SB_DQ<22>")
	)
	(segment
		(start 154.746706 -300.451012)
		(end 154.345386 -300.852332)
		(width 0.14478)
		(layer "In11.Cu")
		(net "M_L_CPU1_SB_DQ<22>")
	)
	(segment
		(start 153.565606 -299.269912)
		(end 153.796238 -299.269912)
		(width 0.14478)
		(layer "In11.Cu")
		(net "M_L_CPU1_SB_DQ<22>")
	)
	(segment
		(start 178.369214 -307.410612)
		(end 181.23789 -307.410612)
		(width 0.14478)
		(layer "In11.Cu")
		(net "M_L_CPU1_SB_DQ<22>")
	)
	(segment
		(start 154.353006 -300.057312)
		(end 154.583638 -300.057312)
		(width 0.14478)
		(layer "In11.Cu")
		(net "M_L_CPU1_SB_DQ<22>")
	)
	(segment
		(start 151.851868 -297.325542)
		(end 152.384506 -297.85818)
		(width 0.14478)
		(layer "In11.Cu")
		(net "M_L_CPU1_SB_DQ<22>")
	)
	(segment
		(start 153.164286 -299.671232)
		(end 153.565606 -299.269912)
		(width 0.14478)
		(layer "In11.Cu")
		(net "M_L_CPU1_SB_DQ<22>")
	)
	(segment
		(start 184.258458 -306.560474)
		(end 186.311032 -307.410612)
		(width 0.14478)
		(layer "In11.Cu")
		(net "M_L_CPU1_SB_DQ<22>")
	)
	(segment
		(start 152.376886 -298.883832)
		(end 152.778206 -298.482512)
		(width 0.14478)
		(layer "In11.Cu")
		(net "M_L_CPU1_SB_DQ<22>")
	)
	(segment
		(start 151.851868 -293.461186)
		(end 151.851868 -297.325542)
		(width 0.14478)
		(layer "In11.Cu")
		(net "M_L_CPU1_SB_DQ<22>")
	)
	(segment
		(start 152.146254 -298.883832)
		(end 152.376886 -298.883832)
		(width 0.14478)
		(layer "In11.Cu")
		(net "M_L_CPU1_SB_DQ<22>")
	)
	(segment
		(start 189.632082 -306.560474)
		(end 192.590928 -306.560474)
		(width 0.14478)
		(layer "In11.Cu")
		(net "M_L_CPU1_SB_DQ<22>")
	)
	(segment
		(start 152.770586 -299.277532)
		(end 152.770586 -299.508164)
		(width 0.14478)
		(layer "In11.Cu")
		(net "M_L_CPU1_SB_DQ<22>")
	)
	(segment
		(start 186.311032 -307.410612)
		(end 188.781944 -307.410612)
		(width 0.14478)
		(layer "In11.Cu")
		(net "M_L_CPU1_SB_DQ<22>")
	)
	(segment
		(start 173.693836 -307.410612)
		(end 174.543974 -306.560474)
		(width 0.14478)
		(layer "In11.Cu")
		(net "M_L_CPU1_SB_DQ<22>")
	)
	(segment
		(start 154.508454 -301.246032)
		(end 154.739086 -301.246032)
		(width 0.14478)
		(layer "In11.Cu")
		(net "M_L_CPU1_SB_DQ<22>")
	)
	(segment
		(start 151.983186 -298.720764)
		(end 152.146254 -298.883832)
		(width 0.14478)
		(layer "In11.Cu")
		(net "M_L_CPU1_SB_DQ<22>")
	)
	(segment
		(start 181.23789 -307.410612)
		(end 182.088028 -306.560474)
		(width 0.14478)
		(layer "In11.Cu")
		(net "M_L_CPU1_SB_DQ<22>")
	)
	(segment
		(start 154.583638 -300.057312)
		(end 154.746706 -300.22038)
		(width 0.14478)
		(layer "In11.Cu")
		(net "M_L_CPU1_SB_DQ<22>")
	)
	(segment
		(start 193.440558 -307.410104)
		(end 196.33438 -307.410104)
		(width 0.14478)
		(layer "In11.Cu")
		(net "M_L_CPU1_SB_DQ<22>")
	)
	(segment
		(start 153.008838 -298.482512)
		(end 153.171906 -298.64558)
		(width 0.14478)
		(layer "In11.Cu")
		(net "M_L_CPU1_SB_DQ<22>")
	)
	(segment
		(start 177.519076 -306.560474)
		(end 178.369214 -307.410612)
		(width 0.14478)
		(layer "In11.Cu")
		(net "M_L_CPU1_SB_DQ<22>")
	)
	(segment
		(start 171.056046 -307.410612)
		(end 173.693836 -307.410612)
		(width 0.14478)
		(layer "In11.Cu")
		(net "M_L_CPU1_SB_DQ<22>")
	)
	(segment
		(start 197.18401 -306.560474)
		(end 201.72299 -306.560474)
		(width 0.14478)
		(layer "In11.Cu")
		(net "M_L_CPU1_SB_DQ<22>")
	)
	(segment
		(start 154.739086 -301.246032)
		(end 155.140406 -300.844712)
		(width 0.14478)
		(layer "In11.Cu")
		(net "M_L_CPU1_SB_DQ<22>")
	)
	(segment
		(start 196.33438 -307.410104)
		(end 197.18401 -306.560474)
		(width 0.14478)
		(layer "In11.Cu")
		(net "M_L_CPU1_SB_DQ<22>")
	)
	(segment
		(start 152.778206 -298.482512)
		(end 153.008838 -298.482512)
		(width 0.14478)
		(layer "In11.Cu")
		(net "M_L_CPU1_SB_DQ<22>")
	)
	(segment
		(start 153.171906 -298.64558)
		(end 153.171906 -298.876212)
		(width 0.14478)
		(layer "In11.Cu")
		(net "M_L_CPU1_SB_DQ<22>")
	)
	(segment
		(start 153.721054 -300.458632)
		(end 153.951686 -300.458632)
		(width 0.14478)
		(layer "In11.Cu")
		(net "M_L_CPU1_SB_DQ<22>")
	)
	(segment
		(start 153.951686 -300.458632)
		(end 154.353006 -300.057312)
		(width 0.14478)
		(layer "In11.Cu")
		(net "M_L_CPU1_SB_DQ<22>")
	)
	(segment
		(start 147.749006 -289.358324)
		(end 151.851868 -293.461186)
		(width 0.14478)
		(layer "In11.Cu")
		(net "M_L_CPU1_SB_DQ<22>")
	)
	(arc
		(start 139.584684 -287.565592)
		(mid 139.839892 -287.609049)
		(end 140.087604 -287.533842)
		(width 0.0889)
		(layer "In11.Cu")
		(net "M_L_CPU1_SB_DQ<22>")
	)
	(arc
		(start 142.907766 -287.533842)
		(mid 143.09471 -287.483587)
		(end 143.281654 -287.533842)
		(width 0.0889)
		(layer "In11.Cu")
		(net "M_L_CPU1_SB_DQ<22>")
	)
	(arc
		(start 140.087604 -287.533842)
		(mid 140.269855 -287.483492)
		(end 140.453364 -287.529016)
		(width 0.0889)
		(layer "In11.Cu")
		(net "M_L_CPU1_SB_DQ<22>")
	)
	(arc
		(start 141.4018 -287.533842)
		(mid 141.684756 -287.609985)
		(end 141.967712 -287.533842)
		(width 0.0889)
		(layer "In11.Cu")
		(net "M_L_CPU1_SB_DQ<22>")
	)
	(arc
		(start 141.027658 -287.533842)
		(mid 141.209909 -287.483492)
		(end 141.393418 -287.529016)
		(width 0.0889)
		(layer "In11.Cu")
		(net "M_L_CPU1_SB_DQ<22>")
	)
	(arc
		(start 143.281654 -287.533842)
		(mid 143.56461 -287.609985)
		(end 143.847566 -287.533842)
		(width 0.0889)
		(layer "In11.Cu")
		(net "M_L_CPU1_SB_DQ<22>")
	)
	(arc
		(start 144.221962 -287.533842)
		(mid 144.358404 -287.590652)
		(end 144.504918 -287.610042)
		(width 0.0889)
		(layer "In11.Cu")
		(net "M_L_CPU1_SB_DQ<22>")
	)
	(arc
		(start 141.976094 -287.529016)
		(mid 142.159602 -287.483522)
		(end 142.341854 -287.533842)
		(width 0.0889)
		(layer "In11.Cu")
		(net "M_L_CPU1_SB_DQ<22>")
	)
	(arc
		(start 140.461746 -287.533842)
		(mid 140.744702 -287.609985)
		(end 141.027658 -287.533842)
		(width 0.0889)
		(layer "In11.Cu")
		(net "M_L_CPU1_SB_DQ<22>")
	)
	(arc
		(start 143.847566 -287.533842)
		(mid 144.034764 -287.48346)
		(end 144.221962 -287.533842)
		(width 0.0889)
		(layer "In11.Cu")
		(net "M_L_CPU1_SB_DQ<22>")
	)
	(arc
		(start 142.341854 -287.533842)
		(mid 142.62481 -287.609985)
		(end 142.907766 -287.533842)
		(width 0.0889)
		(layer "In11.Cu")
		(net "M_L_CPU1_SB_DQ<22>")
	)
	(segment
		(start 137.927842 -287.590484)
		(end 138.394694 -287.856422)
		(width 0.10668)
		(layer "F.Cu")
		(net "M_L_CPU1_SB_DQ<21>")
	)
	(segment
		(start 195.749164 -308.260242)
		(end 197.800976 -307.410358)
		(width 0.14478)
		(layer "In11.Cu")
		(net "M_L_CPU1_SB_DQ<21>")
	)
	(segment
		(start 144.213326 -288.183574)
		(end 144.221708 -288.178748)
		(width 0.0889)
		(layer "In11.Cu")
		(net "M_L_CPU1_SB_DQ<21>")
	)
	(segment
		(start 146.13763 -288.413952)
		(end 146.13763 -288.863532)
		(width 0.0889)
		(layer "In11.Cu")
		(net "M_L_CPU1_SB_DQ<21>")
	)
	(segment
		(start 145.826226 -288.102548)
		(end 146.13763 -288.413952)
		(width 0.0889)
		(layer "In11.Cu")
		(net "M_L_CPU1_SB_DQ<21>")
	)
	(segment
		(start 144.509236 -288.102548)
		(end 145.826226 -288.102548)
		(width 0.0889)
		(layer "In11.Cu")
		(net "M_L_CPU1_SB_DQ<21>")
	)
	(segment
		(start 197.800976 -307.410358)
		(end 204.11186 -307.410358)
		(width 0.14478)
		(layer "In11.Cu")
		(net "M_L_CPU1_SB_DQ<21>")
	)
	(segment
		(start 174.636684 -307.410612)
		(end 177.661316 -307.410612)
		(width 0.14478)
		(layer "In11.Cu")
		(net "M_L_CPU1_SB_DQ<21>")
	)
	(segment
		(start 146.866864 -289.592766)
		(end 147.341336 -289.592766)
		(width 0.0889)
		(layer "In11.Cu")
		(net "M_L_CPU1_SB_DQ<21>")
	)
	(segment
		(start 162.824414 -308.260242)
		(end 165.485826 -308.260242)
		(width 0.14478)
		(layer "In11.Cu")
		(net "M_L_CPU1_SB_DQ<21>")
	)
	(segment
		(start 141.393418 -288.183574)
		(end 141.4018 -288.178748)
		(width 0.0889)
		(layer "In11.Cu")
		(net "M_L_CPU1_SB_DQ<21>")
	)
	(segment
		(start 177.661316 -307.410612)
		(end 178.5112 -308.260496)
		(width 0.14478)
		(layer "In11.Cu")
		(net "M_L_CPU1_SB_DQ<21>")
	)
	(segment
		(start 155.58389 -301.700692)
		(end 162.143694 -308.260496)
		(width 0.14478)
		(layer "In11.Cu")
		(net "M_L_CPU1_SB_DQ<21>")
	)
	(segment
		(start 151.397208 -293.648638)
		(end 151.397208 -298.777914)
		(width 0.14478)
		(layer "In11.Cu")
		(net "M_L_CPU1_SB_DQ<21>")
	)
	(segment
		(start 151.397208 -298.777914)
		(end 154.319986 -301.700692)
		(width 0.14478)
		(layer "In11.Cu")
		(net "M_L_CPU1_SB_DQ<21>")
	)
	(segment
		(start 170.914568 -308.260496)
		(end 173.7868 -308.260496)
		(width 0.14478)
		(layer "In11.Cu")
		(net "M_L_CPU1_SB_DQ<21>")
	)
	(segment
		(start 186.51855 -308.260496)
		(end 188.245242 -308.260496)
		(width 0.14478)
		(layer "In11.Cu")
		(net "M_L_CPU1_SB_DQ<21>")
	)
	(segment
		(start 188.245242 -308.260496)
		(end 190.297054 -307.410612)
		(width 0.14478)
		(layer "In11.Cu")
		(net "M_L_CPU1_SB_DQ<21>")
	)
	(segment
		(start 190.297054 -307.410612)
		(end 192.10782 -307.410612)
		(width 0.14478)
		(layer "In11.Cu")
		(net "M_L_CPU1_SB_DQ<21>")
	)
	(segment
		(start 141.967712 -288.178748)
		(end 141.976094 -288.183574)
		(width 0.0889)
		(layer "In11.Cu")
		(net "M_L_CPU1_SB_DQ<21>")
	)
	(segment
		(start 178.5112 -308.260496)
		(end 181.330854 -308.260496)
		(width 0.14478)
		(layer "In11.Cu")
		(net "M_L_CPU1_SB_DQ<21>")
	)
	(segment
		(start 167.5384 -307.410104)
		(end 170.064176 -307.410104)
		(width 0.14478)
		(layer "In11.Cu")
		(net "M_L_CPU1_SB_DQ<21>")
	)
	(segment
		(start 162.82416 -308.260496)
		(end 162.824414 -308.260242)
		(width 0.14478)
		(layer "In11.Cu")
		(net "M_L_CPU1_SB_DQ<21>")
	)
	(segment
		(start 138.394694 -287.856422)
		(end 138.24077 -288.121852)
		(width 0.0889)
		(layer "In11.Cu")
		(net "M_L_CPU1_SB_DQ<21>")
	)
	(segment
		(start 170.064176 -307.410104)
		(end 170.914568 -308.260496)
		(width 0.14478)
		(layer "In11.Cu")
		(net "M_L_CPU1_SB_DQ<21>")
	)
	(segment
		(start 147.898358 -290.149788)
		(end 151.397208 -293.648638)
		(width 0.14478)
		(layer "In11.Cu")
		(net "M_L_CPU1_SB_DQ<21>")
	)
	(segment
		(start 184.466738 -307.410612)
		(end 186.51855 -308.260496)
		(width 0.14478)
		(layer "In11.Cu")
		(net "M_L_CPU1_SB_DQ<21>")
	)
	(segment
		(start 140.453364 -288.183574)
		(end 140.461746 -288.178748)
		(width 0.0889)
		(layer "In11.Cu")
		(net "M_L_CPU1_SB_DQ<21>")
	)
	(segment
		(start 182.180738 -307.410612)
		(end 184.466738 -307.410612)
		(width 0.14478)
		(layer "In11.Cu")
		(net "M_L_CPU1_SB_DQ<21>")
	)
	(segment
		(start 146.13763 -288.863532)
		(end 146.866864 -289.592766)
		(width 0.0889)
		(layer "In11.Cu")
		(net "M_L_CPU1_SB_DQ<21>")
	)
	(segment
		(start 138.24077 -288.121852)
		(end 138.263122 -288.20491)
		(width 0.0889)
		(layer "In11.Cu")
		(net "M_L_CPU1_SB_DQ<21>")
	)
	(segment
		(start 147.341336 -289.592766)
		(end 147.898358 -290.149788)
		(width 0.0889)
		(layer "In11.Cu")
		(net "M_L_CPU1_SB_DQ<21>")
	)
	(segment
		(start 173.7868 -308.260496)
		(end 174.636684 -307.410612)
		(width 0.14478)
		(layer "In11.Cu")
		(net "M_L_CPU1_SB_DQ<21>")
	)
	(segment
		(start 165.485826 -308.260242)
		(end 167.5384 -307.410104)
		(width 0.14478)
		(layer "In11.Cu")
		(net "M_L_CPU1_SB_DQ<21>")
	)
	(segment
		(start 162.143694 -308.260496)
		(end 162.82416 -308.260496)
		(width 0.14478)
		(layer "In11.Cu")
		(net "M_L_CPU1_SB_DQ<21>")
	)
	(segment
		(start 204.11186 -307.410358)
		(end 206.248 -307.8353)
		(width 0.14478)
		(layer "In11.Cu")
		(net "M_L_CPU1_SB_DQ<21>")
	)
	(segment
		(start 181.330854 -308.260496)
		(end 182.180738 -307.410612)
		(width 0.14478)
		(layer "In11.Cu")
		(net "M_L_CPU1_SB_DQ<21>")
	)
	(segment
		(start 154.319986 -301.700692)
		(end 155.58389 -301.700692)
		(width 0.14478)
		(layer "In11.Cu")
		(net "M_L_CPU1_SB_DQ<21>")
	)
	(segment
		(start 194.159124 -308.260242)
		(end 195.749164 -308.260242)
		(width 0.14478)
		(layer "In11.Cu")
		(net "M_L_CPU1_SB_DQ<21>")
	)
	(segment
		(start 192.10782 -307.410612)
		(end 194.159124 -308.260242)
		(width 0.14478)
		(layer "In11.Cu")
		(net "M_L_CPU1_SB_DQ<21>")
	)
	(arc
		(start 140.461746 -288.178748)
		(mid 140.744702 -288.102571)
		(end 141.027658 -288.178748)
		(width 0.0889)
		(layer "In11.Cu")
		(net "M_L_CPU1_SB_DQ<21>")
	)
	(arc
		(start 143.281654 -288.178748)
		(mid 143.56461 -288.102571)
		(end 143.847566 -288.178748)
		(width 0.0889)
		(layer "In11.Cu")
		(net "M_L_CPU1_SB_DQ<21>")
	)
	(arc
		(start 141.976094 -288.183574)
		(mid 142.159602 -288.229099)
		(end 142.341854 -288.178748)
		(width 0.0889)
		(layer "In11.Cu")
		(net "M_L_CPU1_SB_DQ<21>")
	)
	(arc
		(start 141.027658 -288.178748)
		(mid 141.209909 -288.229132)
		(end 141.393418 -288.183574)
		(width 0.0889)
		(layer "In11.Cu")
		(net "M_L_CPU1_SB_DQ<21>")
	)
	(arc
		(start 140.087604 -288.178748)
		(mid 140.269855 -288.229132)
		(end 140.453364 -288.183574)
		(width 0.0889)
		(layer "In11.Cu")
		(net "M_L_CPU1_SB_DQ<21>")
	)
	(arc
		(start 143.847566 -288.178748)
		(mid 144.029817 -288.229132)
		(end 144.213326 -288.183574)
		(width 0.0889)
		(layer "In11.Cu")
		(net "M_L_CPU1_SB_DQ<21>")
	)
	(arc
		(start 139.147804 -288.178748)
		(mid 139.334748 -288.229037)
		(end 139.521692 -288.178748)
		(width 0.0889)
		(layer "In11.Cu")
		(net "M_L_CPU1_SB_DQ<21>")
	)
	(arc
		(start 139.521692 -288.178748)
		(mid 139.804648 -288.102571)
		(end 140.087604 -288.178748)
		(width 0.0889)
		(layer "In11.Cu")
		(net "M_L_CPU1_SB_DQ<21>")
	)
	(arc
		(start 138.263122 -288.20491)
		(mid 138.425454 -288.227744)
		(end 138.581892 -288.178748)
		(width 0.0889)
		(layer "In11.Cu")
		(net "M_L_CPU1_SB_DQ<21>")
	)
	(arc
		(start 142.907766 -288.178748)
		(mid 143.09471 -288.229037)
		(end 143.281654 -288.178748)
		(width 0.0889)
		(layer "In11.Cu")
		(net "M_L_CPU1_SB_DQ<21>")
	)
	(arc
		(start 138.581892 -288.178748)
		(mid 138.864848 -288.102571)
		(end 139.147804 -288.178748)
		(width 0.0889)
		(layer "In11.Cu")
		(net "M_L_CPU1_SB_DQ<21>")
	)
	(arc
		(start 144.221708 -288.178748)
		(mid 144.360357 -288.121359)
		(end 144.509236 -288.102548)
		(width 0.0889)
		(layer "In11.Cu")
		(net "M_L_CPU1_SB_DQ<21>")
	)
	(arc
		(start 141.4018 -288.178748)
		(mid 141.684756 -288.102571)
		(end 141.967712 -288.178748)
		(width 0.0889)
		(layer "In11.Cu")
		(net "M_L_CPU1_SB_DQ<21>")
	)
	(arc
		(start 142.341854 -288.178748)
		(mid 142.62481 -288.102571)
		(end 142.907766 -288.178748)
		(width 0.0889)
		(layer "In11.Cu")
		(net "M_L_CPU1_SB_DQ<21>")
	)
	(segment
		(start 139.337796 -286.780478)
		(end 139.804648 -287.046162)
		(width 0.10668)
		(layer "F.Cu")
		(net "M_L_CPU1_SB_DQ<20>")
	)
	(segment
		(start 139.804648 -287.046162)
		(end 139.650724 -287.311592)
		(width 0.0889)
		(layer "In11.Cu")
		(net "M_L_CPU1_SB_DQ<20>")
	)
	(segment
		(start 205.449932 -305.710336)
		(end 205.823058 -305.710336)
		(width 0.14478)
		(layer "In11.Cu")
		(net "M_L_CPU1_SB_DQ<20>")
	)
	(segment
		(start 197.196456 -305.719734)
		(end 204.57668 -305.719734)
		(width 0.14478)
		(layer "In11.Cu")
		(net "M_L_CPU1_SB_DQ<20>")
	)
	(segment
		(start 166.123874 -306.560474)
		(end 166.964614 -305.719734)
		(width 0.14478)
		(layer "In11.Cu")
		(net "M_L_CPU1_SB_DQ<20>")
	)
	(segment
		(start 205.286864 -306.584096)
		(end 205.286864 -305.873404)
		(width 0.14478)
		(layer "In11.Cu")
		(net "M_L_CPU1_SB_DQ<20>")
	)
	(segment
		(start 182.17134 -305.719988)
		(end 185.052716 -305.719988)
		(width 0.14478)
		(layer "In11.Cu")
		(net "M_L_CPU1_SB_DQ<20>")
	)
	(segment
		(start 188.86551 -306.569872)
		(end 189.715394 -305.719988)
		(width 0.14478)
		(layer "In11.Cu")
		(net "M_L_CPU1_SB_DQ<20>")
	)
	(segment
		(start 177.43805 -305.719988)
		(end 178.287934 -306.569872)
		(width 0.14478)
		(layer "In11.Cu")
		(net "M_L_CPU1_SB_DQ<20>")
	)
	(segment
		(start 170.976544 -306.569872)
		(end 173.777402 -306.569872)
		(width 0.14478)
		(layer "In11.Cu")
		(net "M_L_CPU1_SB_DQ<20>")
	)
	(segment
		(start 196.346318 -306.569872)
		(end 197.196456 -305.719734)
		(width 0.14478)
		(layer "In11.Cu")
		(net "M_L_CPU1_SB_DQ<20>")
	)
	(segment
		(start 170.126406 -305.719734)
		(end 170.976544 -306.569872)
		(width 0.14478)
		(layer "In11.Cu")
		(net "M_L_CPU1_SB_DQ<20>")
	)
	(segment
		(start 173.777402 -306.569872)
		(end 174.627286 -305.719988)
		(width 0.14478)
		(layer "In11.Cu")
		(net "M_L_CPU1_SB_DQ<20>")
	)
	(segment
		(start 147.901406 -288.86658)
		(end 152.306528 -293.271702)
		(width 0.14478)
		(layer "In11.Cu")
		(net "M_L_CPU1_SB_DQ<20>")
	)
	(segment
		(start 192.509902 -305.719988)
		(end 193.359786 -306.569872)
		(width 0.14478)
		(layer "In11.Cu")
		(net "M_L_CPU1_SB_DQ<20>")
	)
	(segment
		(start 189.715394 -305.719988)
		(end 192.509902 -305.719988)
		(width 0.14478)
		(layer "In11.Cu")
		(net "M_L_CPU1_SB_DQ<20>")
	)
	(segment
		(start 146.823684 -288.094166)
		(end 147.128992 -288.094166)
		(width 0.0889)
		(layer "In11.Cu")
		(net "M_L_CPU1_SB_DQ<20>")
	)
	(segment
		(start 204.73035 -305.873404)
		(end 204.73035 -306.584096)
		(width 0.14478)
		(layer "In11.Cu")
		(net "M_L_CPU1_SB_DQ<20>")
	)
	(segment
		(start 185.052716 -305.719988)
		(end 185.9026 -306.569872)
		(width 0.14478)
		(layer "In11.Cu")
		(net "M_L_CPU1_SB_DQ<20>")
	)
	(segment
		(start 152.306528 -293.271702)
		(end 152.306528 -297.13682)
		(width 0.14478)
		(layer "In11.Cu")
		(net "M_L_CPU1_SB_DQ<20>")
	)
	(segment
		(start 204.57668 -305.719734)
		(end 204.73035 -305.873404)
		(width 0.14478)
		(layer "In11.Cu")
		(net "M_L_CPU1_SB_DQ<20>")
	)
	(segment
		(start 193.359786 -306.569872)
		(end 196.346318 -306.569872)
		(width 0.14478)
		(layer "In11.Cu")
		(net "M_L_CPU1_SB_DQ<20>")
	)
	(segment
		(start 174.627286 -305.719988)
		(end 177.43805 -305.719988)
		(width 0.14478)
		(layer "In11.Cu")
		(net "M_L_CPU1_SB_DQ<20>")
	)
	(segment
		(start 205.823058 -305.710336)
		(end 206.248 -306.135278)
		(width 0.14478)
		(layer "In11.Cu")
		(net "M_L_CPU1_SB_DQ<20>")
	)
	(segment
		(start 143.377666 -287.368742)
		(end 143.386048 -287.373568)
		(width 0.0889)
		(layer "In11.Cu")
		(net "M_L_CPU1_SB_DQ<20>")
	)
	(segment
		(start 205.286864 -305.873404)
		(end 205.449932 -305.710336)
		(width 0.14478)
		(layer "In11.Cu")
		(net "M_L_CPU1_SB_DQ<20>")
	)
	(segment
		(start 139.650724 -287.311592)
		(end 139.673076 -287.394904)
		(width 0.0889)
		(layer "In11.Cu")
		(net "M_L_CPU1_SB_DQ<20>")
	)
	(segment
		(start 146.14906 -287.419542)
		(end 146.823684 -288.094166)
		(width 0.0889)
		(layer "In11.Cu")
		(net "M_L_CPU1_SB_DQ<20>")
	)
	(segment
		(start 185.9026 -306.569872)
		(end 188.86551 -306.569872)
		(width 0.14478)
		(layer "In11.Cu")
		(net "M_L_CPU1_SB_DQ<20>")
	)
	(segment
		(start 152.306528 -297.13682)
		(end 161.730182 -306.560474)
		(width 0.14478)
		(layer "In11.Cu")
		(net "M_L_CPU1_SB_DQ<20>")
	)
	(segment
		(start 204.73035 -306.584096)
		(end 204.893418 -306.747164)
		(width 0.14478)
		(layer "In11.Cu")
		(net "M_L_CPU1_SB_DQ<20>")
	)
	(segment
		(start 166.964614 -305.719734)
		(end 170.126406 -305.719734)
		(width 0.14478)
		(layer "In11.Cu")
		(net "M_L_CPU1_SB_DQ<20>")
	)
	(segment
		(start 147.128992 -288.094166)
		(end 147.901406 -288.86658)
		(width 0.0889)
		(layer "In11.Cu")
		(net "M_L_CPU1_SB_DQ<20>")
	)
	(segment
		(start 204.893418 -306.747164)
		(end 205.123796 -306.747164)
		(width 0.14478)
		(layer "In11.Cu")
		(net "M_L_CPU1_SB_DQ<20>")
	)
	(segment
		(start 161.730182 -306.560474)
		(end 166.123874 -306.560474)
		(width 0.14478)
		(layer "In11.Cu")
		(net "M_L_CPU1_SB_DQ<20>")
	)
	(segment
		(start 140.557758 -287.368742)
		(end 140.56614 -287.373568)
		(width 0.0889)
		(layer "In11.Cu")
		(net "M_L_CPU1_SB_DQ<20>")
	)
	(segment
		(start 205.123796 -306.747164)
		(end 205.286864 -306.584096)
		(width 0.14478)
		(layer "In11.Cu")
		(net "M_L_CPU1_SB_DQ<20>")
	)
	(segment
		(start 181.321456 -306.569872)
		(end 182.17134 -305.719988)
		(width 0.14478)
		(layer "In11.Cu")
		(net "M_L_CPU1_SB_DQ<20>")
	)
	(segment
		(start 144.505172 -287.419542)
		(end 146.14906 -287.419542)
		(width 0.0889)
		(layer "In11.Cu")
		(net "M_L_CPU1_SB_DQ<20>")
	)
	(segment
		(start 178.287934 -306.569872)
		(end 181.321456 -306.569872)
		(width 0.14478)
		(layer "In11.Cu")
		(net "M_L_CPU1_SB_DQ<20>")
	)
	(segment
		(start 142.803372 -287.373568)
		(end 142.811754 -287.368742)
		(width 0.0889)
		(layer "In11.Cu")
		(net "M_L_CPU1_SB_DQ<20>")
	)
	(arc
		(start 143.386048 -287.373568)
		(mid 143.569556 -287.419062)
		(end 143.751808 -287.368742)
		(width 0.0889)
		(layer "In11.Cu")
		(net "M_L_CPU1_SB_DQ<20>")
	)
	(arc
		(start 139.991846 -287.368742)
		(mid 140.274802 -287.292599)
		(end 140.557758 -287.368742)
		(width 0.0889)
		(layer "In11.Cu")
		(net "M_L_CPU1_SB_DQ<20>")
	)
	(arc
		(start 142.811754 -287.368742)
		(mid 143.09471 -287.292599)
		(end 143.377666 -287.368742)
		(width 0.0889)
		(layer "In11.Cu")
		(net "M_L_CPU1_SB_DQ<20>")
	)
	(arc
		(start 140.9319 -287.368742)
		(mid 141.214856 -287.292599)
		(end 141.497812 -287.368742)
		(width 0.0889)
		(layer "In11.Cu")
		(net "M_L_CPU1_SB_DQ<20>")
	)
	(arc
		(start 141.8717 -287.368742)
		(mid 142.154656 -287.292599)
		(end 142.437612 -287.368742)
		(width 0.0889)
		(layer "In11.Cu")
		(net "M_L_CPU1_SB_DQ<20>")
	)
	(arc
		(start 144.31772 -287.368742)
		(mid 144.408087 -287.406526)
		(end 144.505172 -287.419542)
		(width 0.0889)
		(layer "In11.Cu")
		(net "M_L_CPU1_SB_DQ<20>")
	)
	(arc
		(start 139.673076 -287.394904)
		(mid 139.835408 -287.417722)
		(end 139.991846 -287.368742)
		(width 0.0889)
		(layer "In11.Cu")
		(net "M_L_CPU1_SB_DQ<20>")
	)
	(arc
		(start 142.437612 -287.368742)
		(mid 142.619863 -287.419092)
		(end 142.803372 -287.373568)
		(width 0.0889)
		(layer "In11.Cu")
		(net "M_L_CPU1_SB_DQ<20>")
	)
	(arc
		(start 143.751808 -287.368742)
		(mid 144.034764 -287.292599)
		(end 144.31772 -287.368742)
		(width 0.0889)
		(layer "In11.Cu")
		(net "M_L_CPU1_SB_DQ<20>")
	)
	(arc
		(start 140.56614 -287.373568)
		(mid 140.749648 -287.419062)
		(end 140.9319 -287.368742)
		(width 0.0889)
		(layer "In11.Cu")
		(net "M_L_CPU1_SB_DQ<20>")
	)
	(arc
		(start 141.497812 -287.368742)
		(mid 141.684756 -287.418997)
		(end 141.8717 -287.368742)
		(width 0.0889)
		(layer "In11.Cu")
		(net "M_L_CPU1_SB_DQ<20>")
	)
	(segment
		(start 137.927842 -274.630388)
		(end 138.394694 -274.896326)
		(width 0.10668)
		(layer "F.Cu")
		(net "M_L_CPU1_SB_DQ<1>")
	)
	(segment
		(start 170.966892 -283.610304)
		(end 173.7868 -283.610304)
		(width 0.14478)
		(layer "In11.Cu")
		(net "M_L_CPU1_SB_DQ<1>")
	)
	(segment
		(start 141.393418 -275.223732)
		(end 141.4018 -275.218906)
		(width 0.0889)
		(layer "In11.Cu")
		(net "M_L_CPU1_SB_DQ<1>")
	)
	(segment
		(start 181.330854 -283.610304)
		(end 182.180738 -282.76042)
		(width 0.14478)
		(layer "In11.Cu")
		(net "M_L_CPU1_SB_DQ<1>")
	)
	(segment
		(start 138.24077 -275.161756)
		(end 138.263122 -275.245068)
		(width 0.0889)
		(layer "In11.Cu")
		(net "M_L_CPU1_SB_DQ<1>")
	)
	(segment
		(start 192.749424 -282.76042)
		(end 193.599308 -283.610304)
		(width 0.14478)
		(layer "In11.Cu")
		(net "M_L_CPU1_SB_DQ<1>")
	)
	(segment
		(start 189.724792 -282.76042)
		(end 192.749424 -282.76042)
		(width 0.14478)
		(layer "In11.Cu")
		(net "M_L_CPU1_SB_DQ<1>")
	)
	(segment
		(start 145.64741 -275.14296)
		(end 146.941286 -273.849084)
		(width 0.0889)
		(layer "In11.Cu")
		(net "M_L_CPU1_SB_DQ<1>")
	)
	(segment
		(start 153.234644 -273.849084)
		(end 158.98749 -279.60193)
		(width 0.14478)
		(layer "In11.Cu")
		(net "M_L_CPU1_SB_DQ<1>")
	)
	(segment
		(start 188.874908 -283.610304)
		(end 189.724792 -282.76042)
		(width 0.14478)
		(layer "In11.Cu")
		(net "M_L_CPU1_SB_DQ<1>")
	)
	(segment
		(start 144.777714 -275.21281)
		(end 144.788128 -275.218906)
		(width 0.0889)
		(layer "In11.Cu")
		(net "M_L_CPU1_SB_DQ<1>")
	)
	(segment
		(start 185.20537 -282.76042)
		(end 186.055254 -283.610304)
		(width 0.14478)
		(layer "In11.Cu")
		(net "M_L_CPU1_SB_DQ<1>")
	)
	(segment
		(start 145.150332 -275.225764)
		(end 145.162016 -275.218906)
		(width 0.0889)
		(layer "In11.Cu")
		(net "M_L_CPU1_SB_DQ<1>")
	)
	(segment
		(start 163.81476 -283.610304)
		(end 165.975538 -283.610304)
		(width 0.14478)
		(layer "In11.Cu")
		(net "M_L_CPU1_SB_DQ<1>")
	)
	(segment
		(start 158.98749 -279.60193)
		(end 159.806386 -279.60193)
		(width 0.14478)
		(layer "In11.Cu")
		(net "M_L_CPU1_SB_DQ<1>")
	)
	(segment
		(start 166.825676 -282.760166)
		(end 170.116754 -282.760166)
		(width 0.14478)
		(layer "In11.Cu")
		(net "M_L_CPU1_SB_DQ<1>")
	)
	(segment
		(start 177.661316 -282.76042)
		(end 178.5112 -283.610304)
		(width 0.14478)
		(layer "In11.Cu")
		(net "M_L_CPU1_SB_DQ<1>")
	)
	(segment
		(start 159.806386 -279.60193)
		(end 163.81476 -283.610304)
		(width 0.14478)
		(layer "In11.Cu")
		(net "M_L_CPU1_SB_DQ<1>")
	)
	(segment
		(start 148.060918 -273.849084)
		(end 153.234644 -273.849084)
		(width 0.14478)
		(layer "In11.Cu")
		(net "M_L_CPU1_SB_DQ<1>")
	)
	(segment
		(start 141.967712 -275.218906)
		(end 141.976094 -275.223732)
		(width 0.0889)
		(layer "In11.Cu")
		(net "M_L_CPU1_SB_DQ<1>")
	)
	(segment
		(start 186.055254 -283.610304)
		(end 188.874908 -283.610304)
		(width 0.14478)
		(layer "In11.Cu")
		(net "M_L_CPU1_SB_DQ<1>")
	)
	(segment
		(start 145.444718 -275.14296)
		(end 145.64741 -275.14296)
		(width 0.0889)
		(layer "In11.Cu")
		(net "M_L_CPU1_SB_DQ<1>")
	)
	(segment
		(start 195.631054 -283.610304)
		(end 196.480938 -282.76042)
		(width 0.14478)
		(layer "In11.Cu")
		(net "M_L_CPU1_SB_DQ<1>")
	)
	(segment
		(start 178.5112 -283.610304)
		(end 181.330854 -283.610304)
		(width 0.14478)
		(layer "In11.Cu")
		(net "M_L_CPU1_SB_DQ<1>")
	)
	(segment
		(start 205.823058 -282.76042)
		(end 206.248 -283.185362)
		(width 0.14478)
		(layer "In11.Cu")
		(net "M_L_CPU1_SB_DQ<1>")
	)
	(segment
		(start 196.480938 -282.76042)
		(end 205.823058 -282.76042)
		(width 0.14478)
		(layer "In11.Cu")
		(net "M_L_CPU1_SB_DQ<1>")
	)
	(segment
		(start 182.180738 -282.76042)
		(end 185.20537 -282.76042)
		(width 0.14478)
		(layer "In11.Cu")
		(net "M_L_CPU1_SB_DQ<1>")
	)
	(segment
		(start 174.636684 -282.76042)
		(end 177.661316 -282.76042)
		(width 0.14478)
		(layer "In11.Cu")
		(net "M_L_CPU1_SB_DQ<1>")
	)
	(segment
		(start 138.394694 -274.896326)
		(end 138.24077 -275.161756)
		(width 0.0889)
		(layer "In11.Cu")
		(net "M_L_CPU1_SB_DQ<1>")
	)
	(segment
		(start 140.453364 -275.223732)
		(end 140.461746 -275.218906)
		(width 0.0889)
		(layer "In11.Cu")
		(net "M_L_CPU1_SB_DQ<1>")
	)
	(segment
		(start 170.116754 -282.760166)
		(end 170.966892 -283.610304)
		(width 0.14478)
		(layer "In11.Cu")
		(net "M_L_CPU1_SB_DQ<1>")
	)
	(segment
		(start 146.941286 -273.849084)
		(end 148.060918 -273.849084)
		(width 0.0889)
		(layer "In11.Cu")
		(net "M_L_CPU1_SB_DQ<1>")
	)
	(segment
		(start 165.975538 -283.610304)
		(end 166.825676 -282.760166)
		(width 0.14478)
		(layer "In11.Cu")
		(net "M_L_CPU1_SB_DQ<1>")
	)
	(segment
		(start 173.7868 -283.610304)
		(end 174.636684 -282.76042)
		(width 0.14478)
		(layer "In11.Cu")
		(net "M_L_CPU1_SB_DQ<1>")
	)
	(segment
		(start 193.599308 -283.610304)
		(end 195.631054 -283.610304)
		(width 0.14478)
		(layer "In11.Cu")
		(net "M_L_CPU1_SB_DQ<1>")
	)
	(arc
		(start 143.281654 -275.218906)
		(mid 143.56461 -275.142729)
		(end 143.847566 -275.218906)
		(width 0.0889)
		(layer "In11.Cu")
		(net "M_L_CPU1_SB_DQ<1>")
	)
	(arc
		(start 144.221962 -275.218906)
		(mid 144.499029 -275.142635)
		(end 144.777714 -275.21281)
		(width 0.0889)
		(layer "In11.Cu")
		(net "M_L_CPU1_SB_DQ<1>")
	)
	(arc
		(start 142.907766 -275.218906)
		(mid 143.09471 -275.269161)
		(end 143.281654 -275.218906)
		(width 0.0889)
		(layer "In11.Cu")
		(net "M_L_CPU1_SB_DQ<1>")
	)
	(arc
		(start 141.4018 -275.218906)
		(mid 141.684756 -275.142729)
		(end 141.967712 -275.218906)
		(width 0.0889)
		(layer "In11.Cu")
		(net "M_L_CPU1_SB_DQ<1>")
	)
	(arc
		(start 145.162016 -275.218906)
		(mid 145.29835 -275.162263)
		(end 145.444718 -275.14296)
		(width 0.0889)
		(layer "In11.Cu")
		(net "M_L_CPU1_SB_DQ<1>")
	)
	(arc
		(start 138.263122 -275.245068)
		(mid 138.425454 -275.267886)
		(end 138.581892 -275.218906)
		(width 0.0889)
		(layer "In11.Cu")
		(net "M_L_CPU1_SB_DQ<1>")
	)
	(arc
		(start 141.976094 -275.223732)
		(mid 142.159602 -275.269226)
		(end 142.341854 -275.218906)
		(width 0.0889)
		(layer "In11.Cu")
		(net "M_L_CPU1_SB_DQ<1>")
	)
	(arc
		(start 140.461746 -275.218906)
		(mid 140.744702 -275.142729)
		(end 141.027658 -275.218906)
		(width 0.0889)
		(layer "In11.Cu")
		(net "M_L_CPU1_SB_DQ<1>")
	)
	(arc
		(start 142.341854 -275.218906)
		(mid 142.62481 -275.142729)
		(end 142.907766 -275.218906)
		(width 0.0889)
		(layer "In11.Cu")
		(net "M_L_CPU1_SB_DQ<1>")
	)
	(arc
		(start 138.581892 -275.218906)
		(mid 138.864848 -275.142729)
		(end 139.147804 -275.218906)
		(width 0.0889)
		(layer "In11.Cu")
		(net "M_L_CPU1_SB_DQ<1>")
	)
	(arc
		(start 144.788128 -275.218906)
		(mid 144.968333 -275.269223)
		(end 145.150332 -275.225764)
		(width 0.0889)
		(layer "In11.Cu")
		(net "M_L_CPU1_SB_DQ<1>")
	)
	(arc
		(start 141.027658 -275.218906)
		(mid 141.209909 -275.269256)
		(end 141.393418 -275.223732)
		(width 0.0889)
		(layer "In11.Cu")
		(net "M_L_CPU1_SB_DQ<1>")
	)
	(arc
		(start 139.147804 -275.218906)
		(mid 139.334748 -275.269161)
		(end 139.521692 -275.218906)
		(width 0.0889)
		(layer "In11.Cu")
		(net "M_L_CPU1_SB_DQ<1>")
	)
	(arc
		(start 143.847566 -275.218906)
		(mid 144.034764 -275.269288)
		(end 144.221962 -275.218906)
		(width 0.0889)
		(layer "In11.Cu")
		(net "M_L_CPU1_SB_DQ<1>")
	)
	(arc
		(start 140.087604 -275.218906)
		(mid 140.269855 -275.269256)
		(end 140.453364 -275.223732)
		(width 0.0889)
		(layer "In11.Cu")
		(net "M_L_CPU1_SB_DQ<1>")
	)
	(arc
		(start 139.521692 -275.218906)
		(mid 139.804648 -275.142729)
		(end 140.087604 -275.218906)
		(width 0.0889)
		(layer "In11.Cu")
		(net "M_L_CPU1_SB_DQ<1>")
	)
	(segment
		(start 137.457942 -285.160466)
		(end 137.924794 -285.426404)
		(width 0.10668)
		(layer "F.Cu")
		(net "M_L_CPU1_SB_DQ<19>")
	)
	(segment
		(start 174.420276 -302.300894)
		(end 177.716942 -302.300894)
		(width 0.14478)
		(layer "In11.Cu")
		(net "M_L_CPU1_SB_DQ<19>")
	)
	(segment
		(start 186.111134 -303.151032)
		(end 188.50483 -303.151032)
		(width 0.14478)
		(layer "In11.Cu")
		(net "M_L_CPU1_SB_DQ<19>")
	)
	(segment
		(start 190.032132 -302.156114)
		(end 190.032132 -302.066706)
		(width 0.14478)
		(layer "In11.Cu")
		(net "M_L_CPU1_SB_DQ<19>")
	)
	(segment
		(start 145.444718 -285.053786)
		(end 145.68297 -285.053786)
		(width 0.0889)
		(layer "In11.Cu")
		(net "M_L_CPU1_SB_DQ<19>")
	)
	(segment
		(start 191.605408 -302.300894)
		(end 191.750188 -302.156114)
		(width 0.14478)
		(layer "In11.Cu")
		(net "M_L_CPU1_SB_DQ<19>")
	)
	(segment
		(start 190.176912 -301.921926)
		(end 190.438786 -301.921926)
		(width 0.14478)
		(layer "In11.Cu")
		(net "M_L_CPU1_SB_DQ<19>")
	)
	(segment
		(start 164.857684 -303.290986)
		(end 164.857684 -302.909986)
		(width 0.14478)
		(layer "In11.Cu")
		(net "M_L_CPU1_SB_DQ<19>")
	)
	(segment
		(start 195.882514 -303.005998)
		(end 196.027294 -303.150778)
		(width 0.14478)
		(layer "In11.Cu")
		(net "M_L_CPU1_SB_DQ<19>")
	)
	(segment
		(start 145.236946 -285.116524)
		(end 145.258536 -285.104078)
		(width 0.0889)
		(layer "In11.Cu")
		(net "M_L_CPU1_SB_DQ<19>")
	)
	(segment
		(start 154.645868 -292.261798)
		(end 154.645868 -295.096438)
		(width 0.14478)
		(layer "In11.Cu")
		(net "M_L_CPU1_SB_DQ<19>")
	)
	(segment
		(start 190.728346 -302.300894)
		(end 191.605408 -302.300894)
		(width 0.14478)
		(layer "In11.Cu")
		(net "M_L_CPU1_SB_DQ<19>")
	)
	(segment
		(start 138.078718 -285.160974)
		(end 138.17473 -285.135574)
		(width 0.0889)
		(layer "In11.Cu")
		(net "M_L_CPU1_SB_DQ<19>")
	)
	(segment
		(start 166.47541 -302.765206)
		(end 166.939722 -302.300894)
		(width 0.14478)
		(layer "In11.Cu")
		(net "M_L_CPU1_SB_DQ<19>")
	)
	(segment
		(start 200.412858 -301.997364)
		(end 200.557638 -302.142144)
		(width 0.14478)
		(layer "In11.Cu")
		(net "M_L_CPU1_SB_DQ<19>")
	)
	(segment
		(start 164.712904 -303.435766)
		(end 164.857684 -303.290986)
		(width 0.14478)
		(layer "In11.Cu")
		(net "M_L_CPU1_SB_DQ<19>")
	)
	(segment
		(start 178.56708 -303.151032)
		(end 181.113684 -303.151032)
		(width 0.14478)
		(layer "In11.Cu")
		(net "M_L_CPU1_SB_DQ<19>")
	)
	(segment
		(start 147.15871 -285.483046)
		(end 147.653248 -285.977584)
		(width 0.0889)
		(layer "In11.Cu")
		(net "M_L_CPU1_SB_DQ<19>")
	)
	(segment
		(start 192.78219 -302.300894)
		(end 193.632074 -303.150778)
		(width 0.14478)
		(layer "In11.Cu")
		(net "M_L_CPU1_SB_DQ<19>")
	)
	(segment
		(start 201.410062 -301.997364)
		(end 202.147932 -302.735234)
		(width 0.14478)
		(layer "In11.Cu")
		(net "M_L_CPU1_SB_DQ<19>")
	)
	(segment
		(start 188.50483 -303.151032)
		(end 189.354968 -302.300894)
		(width 0.14478)
		(layer "In11.Cu")
		(net "M_L_CPU1_SB_DQ<19>")
	)
	(segment
		(start 195.737734 -302.760126)
		(end 195.882514 -302.904906)
		(width 0.14478)
		(layer "In11.Cu")
		(net "M_L_CPU1_SB_DQ<19>")
	)
	(segment
		(start 192.156842 -301.911766)
		(end 192.301622 -302.056546)
		(width 0.14478)
		(layer "In11.Cu")
		(net "M_L_CPU1_SB_DQ<19>")
	)
	(segment
		(start 166.939722 -302.300894)
		(end 170.173396 -302.300894)
		(width 0.14478)
		(layer "In11.Cu")
		(net "M_L_CPU1_SB_DQ<19>")
	)
	(segment
		(start 192.446402 -302.300894)
		(end 192.78219 -302.300894)
		(width 0.14478)
		(layer "In11.Cu")
		(net "M_L_CPU1_SB_DQ<19>")
	)
	(segment
		(start 163.203382 -303.290986)
		(end 163.348162 -303.435766)
		(width 0.14478)
		(layer "In11.Cu")
		(net "M_L_CPU1_SB_DQ<19>")
	)
	(segment
		(start 163.754816 -303.290986)
		(end 163.754816 -302.909986)
		(width 0.14478)
		(layer "In11.Cu")
		(net "M_L_CPU1_SB_DQ<19>")
	)
	(segment
		(start 170.173396 -302.300894)
		(end 171.023534 -303.151032)
		(width 0.14478)
		(layer "In11.Cu")
		(net "M_L_CPU1_SB_DQ<19>")
	)
	(segment
		(start 137.924794 -285.426404)
		(end 138.078718 -285.160974)
		(width 0.0889)
		(layer "In11.Cu")
		(net "M_L_CPU1_SB_DQ<19>")
	)
	(segment
		(start 142.803372 -285.098998)
		(end 142.811754 -285.103824)
		(width 0.0889)
		(layer "In11.Cu")
		(net "M_L_CPU1_SB_DQ<19>")
	)
	(segment
		(start 163.610036 -303.435766)
		(end 163.754816 -303.290986)
		(width 0.14478)
		(layer "In11.Cu")
		(net "M_L_CPU1_SB_DQ<19>")
	)
	(segment
		(start 191.894968 -301.911766)
		(end 192.156842 -301.911766)
		(width 0.14478)
		(layer "In11.Cu")
		(net "M_L_CPU1_SB_DQ<19>")
	)
	(segment
		(start 164.857684 -302.909986)
		(end 165.002464 -302.765206)
		(width 0.14478)
		(layer "In11.Cu")
		(net "M_L_CPU1_SB_DQ<19>")
	)
	(segment
		(start 189.354968 -302.300894)
		(end 189.887352 -302.300894)
		(width 0.14478)
		(layer "In11.Cu")
		(net "M_L_CPU1_SB_DQ<19>")
	)
	(segment
		(start 181.963822 -302.300894)
		(end 185.260996 -302.300894)
		(width 0.14478)
		(layer "In11.Cu")
		(net "M_L_CPU1_SB_DQ<19>")
	)
	(segment
		(start 201.253852 -301.997364)
		(end 201.410062 -301.997364)
		(width 0.14478)
		(layer "In11.Cu")
		(net "M_L_CPU1_SB_DQ<19>")
	)
	(segment
		(start 163.058602 -302.765206)
		(end 163.203382 -302.909986)
		(width 0.14478)
		(layer "In11.Cu")
		(net "M_L_CPU1_SB_DQ<19>")
	)
	(segment
		(start 171.023534 -303.151032)
		(end 173.570138 -303.151032)
		(width 0.14478)
		(layer "In11.Cu")
		(net "M_L_CPU1_SB_DQ<19>")
	)
	(segment
		(start 200.557638 -302.142144)
		(end 200.557638 -302.757586)
		(width 0.14478)
		(layer "In11.Cu")
		(net "M_L_CPU1_SB_DQ<19>")
	)
	(segment
		(start 195.1863 -303.150778)
		(end 195.33108 -303.005998)
		(width 0.14478)
		(layer "In11.Cu")
		(net "M_L_CPU1_SB_DQ<19>")
	)
	(segment
		(start 192.301622 -302.156114)
		(end 192.446402 -302.300894)
		(width 0.14478)
		(layer "In11.Cu")
		(net "M_L_CPU1_SB_DQ<19>")
	)
	(segment
		(start 139.617704 -285.103824)
		(end 139.626086 -285.098998)
		(width 0.0889)
		(layer "In11.Cu")
		(net "M_L_CPU1_SB_DQ<19>")
	)
	(segment
		(start 163.899596 -302.765206)
		(end 164.16147 -302.765206)
		(width 0.14478)
		(layer "In11.Cu")
		(net "M_L_CPU1_SB_DQ<19>")
	)
	(segment
		(start 196.027294 -303.150778)
		(end 196.234812 -303.150778)
		(width 0.14478)
		(layer "In11.Cu")
		(net "M_L_CPU1_SB_DQ<19>")
	)
	(segment
		(start 192.301622 -302.056546)
		(end 192.301622 -302.156114)
		(width 0.14478)
		(layer "In11.Cu")
		(net "M_L_CPU1_SB_DQ<19>")
	)
	(segment
		(start 191.750188 -302.056546)
		(end 191.894968 -301.911766)
		(width 0.14478)
		(layer "In11.Cu")
		(net "M_L_CPU1_SB_DQ<19>")
	)
	(segment
		(start 201.109072 -302.757586)
		(end 201.109072 -302.142144)
		(width 0.14478)
		(layer "In11.Cu")
		(net "M_L_CPU1_SB_DQ<19>")
	)
	(segment
		(start 143.751808 -285.103824)
		(end 143.775176 -285.11754)
		(width 0.0889)
		(layer "In11.Cu")
		(net "M_L_CPU1_SB_DQ<19>")
	)
	(segment
		(start 147.653248 -285.977584)
		(end 147.859496 -285.977584)
		(width 0.0889)
		(layer "In11.Cu")
		(net "M_L_CPU1_SB_DQ<19>")
	)
	(segment
		(start 189.887352 -302.300894)
		(end 190.032132 -302.156114)
		(width 0.14478)
		(layer "In11.Cu")
		(net "M_L_CPU1_SB_DQ<19>")
	)
	(segment
		(start 190.032132 -302.066706)
		(end 190.176912 -301.921926)
		(width 0.14478)
		(layer "In11.Cu")
		(net "M_L_CPU1_SB_DQ<19>")
	)
	(segment
		(start 195.882514 -302.904906)
		(end 195.882514 -303.005998)
		(width 0.14478)
		(layer "In11.Cu")
		(net "M_L_CPU1_SB_DQ<19>")
	)
	(segment
		(start 190.438786 -301.921926)
		(end 190.583566 -302.066706)
		(width 0.14478)
		(layer "In11.Cu")
		(net "M_L_CPU1_SB_DQ<19>")
	)
	(segment
		(start 201.109072 -302.142144)
		(end 201.253852 -301.997364)
		(width 0.14478)
		(layer "In11.Cu")
		(net "M_L_CPU1_SB_DQ<19>")
	)
	(segment
		(start 190.583566 -302.066706)
		(end 190.583566 -302.156114)
		(width 0.14478)
		(layer "In11.Cu")
		(net "M_L_CPU1_SB_DQ<19>")
	)
	(segment
		(start 165.002464 -302.765206)
		(end 166.47541 -302.765206)
		(width 0.14478)
		(layer "In11.Cu")
		(net "M_L_CPU1_SB_DQ<19>")
	)
	(segment
		(start 146.11223 -285.483046)
		(end 147.15871 -285.483046)
		(width 0.0889)
		(layer "In11.Cu")
		(net "M_L_CPU1_SB_DQ<19>")
	)
	(segment
		(start 143.377666 -285.103824)
		(end 143.386048 -285.098998)
		(width 0.0889)
		(layer "In11.Cu")
		(net "M_L_CPU1_SB_DQ<19>")
	)
	(segment
		(start 145.68297 -285.053786)
		(end 146.11223 -285.483046)
		(width 0.0889)
		(layer "In11.Cu")
		(net "M_L_CPU1_SB_DQ<19>")
	)
	(segment
		(start 193.632074 -303.150778)
		(end 195.1863 -303.150778)
		(width 0.14478)
		(layer "In11.Cu")
		(net "M_L_CPU1_SB_DQ<19>")
	)
	(segment
		(start 163.754816 -302.909986)
		(end 163.899596 -302.765206)
		(width 0.14478)
		(layer "In11.Cu")
		(net "M_L_CPU1_SB_DQ<19>")
	)
	(segment
		(start 148.361654 -285.977584)
		(end 154.645868 -292.261798)
		(width 0.14478)
		(layer "In11.Cu")
		(net "M_L_CPU1_SB_DQ<19>")
	)
	(segment
		(start 164.30625 -302.909986)
		(end 164.30625 -303.290986)
		(width 0.14478)
		(layer "In11.Cu")
		(net "M_L_CPU1_SB_DQ<19>")
	)
	(segment
		(start 139.04341 -285.098998)
		(end 139.051792 -285.103824)
		(width 0.0889)
		(layer "In11.Cu")
		(net "M_L_CPU1_SB_DQ<19>")
	)
	(segment
		(start 164.16147 -302.765206)
		(end 164.30625 -302.909986)
		(width 0.14478)
		(layer "In11.Cu")
		(net "M_L_CPU1_SB_DQ<19>")
	)
	(segment
		(start 185.260996 -302.300894)
		(end 186.111134 -303.151032)
		(width 0.14478)
		(layer "In11.Cu")
		(net "M_L_CPU1_SB_DQ<19>")
	)
	(segment
		(start 164.30625 -303.290986)
		(end 164.45103 -303.435766)
		(width 0.14478)
		(layer "In11.Cu")
		(net "M_L_CPU1_SB_DQ<19>")
	)
	(segment
		(start 200.702418 -302.902366)
		(end 200.964292 -302.902366)
		(width 0.14478)
		(layer "In11.Cu")
		(net "M_L_CPU1_SB_DQ<19>")
	)
	(segment
		(start 177.716942 -302.300894)
		(end 178.56708 -303.151032)
		(width 0.14478)
		(layer "In11.Cu")
		(net "M_L_CPU1_SB_DQ<19>")
	)
	(segment
		(start 163.348162 -303.435766)
		(end 163.610036 -303.435766)
		(width 0.14478)
		(layer "In11.Cu")
		(net "M_L_CPU1_SB_DQ<19>")
	)
	(segment
		(start 190.583566 -302.156114)
		(end 190.728346 -302.300894)
		(width 0.14478)
		(layer "In11.Cu")
		(net "M_L_CPU1_SB_DQ<19>")
	)
	(segment
		(start 173.570138 -303.151032)
		(end 174.420276 -302.300894)
		(width 0.14478)
		(layer "In11.Cu")
		(net "M_L_CPU1_SB_DQ<19>")
	)
	(segment
		(start 195.33108 -303.005998)
		(end 195.33108 -302.904906)
		(width 0.14478)
		(layer "In11.Cu")
		(net "M_L_CPU1_SB_DQ<19>")
	)
	(segment
		(start 162.314636 -302.765206)
		(end 163.058602 -302.765206)
		(width 0.14478)
		(layer "In11.Cu")
		(net "M_L_CPU1_SB_DQ<19>")
	)
	(segment
		(start 164.45103 -303.435766)
		(end 164.712904 -303.435766)
		(width 0.14478)
		(layer "In11.Cu")
		(net "M_L_CPU1_SB_DQ<19>")
	)
	(segment
		(start 200.964292 -302.902366)
		(end 201.109072 -302.757586)
		(width 0.14478)
		(layer "In11.Cu")
		(net "M_L_CPU1_SB_DQ<19>")
	)
	(segment
		(start 197.084696 -302.300894)
		(end 199.09663 -302.300894)
		(width 0.14478)
		(layer "In11.Cu")
		(net "M_L_CPU1_SB_DQ<19>")
	)
	(segment
		(start 147.859496 -285.977584)
		(end 148.361654 -285.977584)
		(width 0.14478)
		(layer "In11.Cu")
		(net "M_L_CPU1_SB_DQ<19>")
	)
	(segment
		(start 140.557758 -285.103824)
		(end 140.56614 -285.098998)
		(width 0.0889)
		(layer "In11.Cu")
		(net "M_L_CPU1_SB_DQ<19>")
	)
	(segment
		(start 191.750188 -302.156114)
		(end 191.750188 -302.056546)
		(width 0.14478)
		(layer "In11.Cu")
		(net "M_L_CPU1_SB_DQ<19>")
	)
	(segment
		(start 195.47586 -302.760126)
		(end 195.737734 -302.760126)
		(width 0.14478)
		(layer "In11.Cu")
		(net "M_L_CPU1_SB_DQ<19>")
	)
	(segment
		(start 195.33108 -302.904906)
		(end 195.47586 -302.760126)
		(width 0.14478)
		(layer "In11.Cu")
		(net "M_L_CPU1_SB_DQ<19>")
	)
	(segment
		(start 199.40016 -301.997364)
		(end 200.412858 -301.997364)
		(width 0.14478)
		(layer "In11.Cu")
		(net "M_L_CPU1_SB_DQ<19>")
	)
	(segment
		(start 181.113684 -303.151032)
		(end 181.963822 -302.300894)
		(width 0.14478)
		(layer "In11.Cu")
		(net "M_L_CPU1_SB_DQ<19>")
	)
	(segment
		(start 200.557638 -302.757586)
		(end 200.702418 -302.902366)
		(width 0.14478)
		(layer "In11.Cu")
		(net "M_L_CPU1_SB_DQ<19>")
	)
	(segment
		(start 163.203382 -302.909986)
		(end 163.203382 -303.290986)
		(width 0.14478)
		(layer "In11.Cu")
		(net "M_L_CPU1_SB_DQ<19>")
	)
	(segment
		(start 154.645868 -295.096438)
		(end 162.314636 -302.765206)
		(width 0.14478)
		(layer "In11.Cu")
		(net "M_L_CPU1_SB_DQ<19>")
	)
	(segment
		(start 144.67967 -285.095442)
		(end 144.694148 -285.103824)
		(width 0.0889)
		(layer "In11.Cu")
		(net "M_L_CPU1_SB_DQ<19>")
	)
	(segment
		(start 199.09663 -302.300894)
		(end 199.40016 -301.997364)
		(width 0.14478)
		(layer "In11.Cu")
		(net "M_L_CPU1_SB_DQ<19>")
	)
	(segment
		(start 196.234812 -303.150778)
		(end 197.084696 -302.300894)
		(width 0.14478)
		(layer "In11.Cu")
		(net "M_L_CPU1_SB_DQ<19>")
	)
	(arc
		(start 140.9319 -285.103824)
		(mid 141.214856 -285.180001)
		(end 141.497812 -285.103824)
		(width 0.0889)
		(layer "In11.Cu")
		(net "M_L_CPU1_SB_DQ<19>")
	)
	(arc
		(start 139.991846 -285.103824)
		(mid 140.274802 -285.180001)
		(end 140.557758 -285.103824)
		(width 0.0889)
		(layer "In11.Cu")
		(net "M_L_CPU1_SB_DQ<19>")
	)
	(arc
		(start 142.811754 -285.103824)
		(mid 143.09471 -285.180001)
		(end 143.377666 -285.103824)
		(width 0.0889)
		(layer "In11.Cu")
		(net "M_L_CPU1_SB_DQ<19>")
	)
	(arc
		(start 138.17473 -285.135574)
		(mid 138.429938 -285.179051)
		(end 138.67765 -285.103824)
		(width 0.0889)
		(layer "In11.Cu")
		(net "M_L_CPU1_SB_DQ<19>")
	)
	(arc
		(start 141.497812 -285.103824)
		(mid 141.684756 -285.053569)
		(end 141.8717 -285.103824)
		(width 0.0889)
		(layer "In11.Cu")
		(net "M_L_CPU1_SB_DQ<19>")
	)
	(arc
		(start 138.67765 -285.103824)
		(mid 138.859901 -285.053474)
		(end 139.04341 -285.098998)
		(width 0.0889)
		(layer "In11.Cu")
		(net "M_L_CPU1_SB_DQ<19>")
	)
	(arc
		(start 143.386048 -285.098998)
		(mid 143.569556 -285.053504)
		(end 143.751808 -285.103824)
		(width 0.0889)
		(layer "In11.Cu")
		(net "M_L_CPU1_SB_DQ<19>")
	)
	(arc
		(start 145.258536 -285.104078)
		(mid 145.348313 -285.066655)
		(end 145.444718 -285.053786)
		(width 0.0889)
		(layer "In11.Cu")
		(net "M_L_CPU1_SB_DQ<19>")
	)
	(arc
		(start 139.051792 -285.103824)
		(mid 139.334748 -285.180001)
		(end 139.617704 -285.103824)
		(width 0.0889)
		(layer "In11.Cu")
		(net "M_L_CPU1_SB_DQ<19>")
	)
	(arc
		(start 144.694148 -285.103824)
		(mid 144.963917 -285.179847)
		(end 145.236946 -285.116524)
		(width 0.0889)
		(layer "In11.Cu")
		(net "M_L_CPU1_SB_DQ<19>")
	)
	(arc
		(start 140.56614 -285.098998)
		(mid 140.749648 -285.053504)
		(end 140.9319 -285.103824)
		(width 0.0889)
		(layer "In11.Cu")
		(net "M_L_CPU1_SB_DQ<19>")
	)
	(arc
		(start 142.437612 -285.103824)
		(mid 142.619863 -285.053474)
		(end 142.803372 -285.098998)
		(width 0.0889)
		(layer "In11.Cu")
		(net "M_L_CPU1_SB_DQ<19>")
	)
	(arc
		(start 141.8717 -285.103824)
		(mid 142.154656 -285.180001)
		(end 142.437612 -285.103824)
		(width 0.0889)
		(layer "In11.Cu")
		(net "M_L_CPU1_SB_DQ<19>")
	)
	(arc
		(start 144.31899 -285.103824)
		(mid 144.498253 -285.05316)
		(end 144.67967 -285.095442)
		(width 0.0889)
		(layer "In11.Cu")
		(net "M_L_CPU1_SB_DQ<19>")
	)
	(arc
		(start 139.626086 -285.098998)
		(mid 139.809594 -285.053504)
		(end 139.991846 -285.103824)
		(width 0.0889)
		(layer "In11.Cu")
		(net "M_L_CPU1_SB_DQ<19>")
	)
	(arc
		(start 143.775176 -285.11754)
		(mid 144.04883 -285.180483)
		(end 144.31899 -285.103824)
		(width 0.0889)
		(layer "In11.Cu")
		(net "M_L_CPU1_SB_DQ<19>")
	)
	(segment
		(start 138.867896 -284.35046)
		(end 139.334748 -284.616398)
		(width 0.10668)
		(layer "F.Cu")
		(net "M_L_CPU1_SB_DQ<18>")
	)
	(segment
		(start 139.334748 -284.616398)
		(end 139.488672 -284.350968)
		(width 0.0889)
		(layer "In11.Cu")
		(net "M_L_CPU1_SB_DQ<18>")
	)
	(segment
		(start 196.373496 -301.460154)
		(end 197.22338 -300.61027)
		(width 0.14478)
		(layer "In11.Cu")
		(net "M_L_CPU1_SB_DQ<18>")
	)
	(segment
		(start 164.983414 -301.086266)
		(end 165.128194 -301.231046)
		(width 0.14478)
		(layer "In11.Cu")
		(net "M_L_CPU1_SB_DQ<18>")
	)
	(segment
		(start 183.12765 -300.46549)
		(end 183.27243 -300.61027)
		(width 0.14478)
		(layer "In11.Cu")
		(net "M_L_CPU1_SB_DQ<18>")
	)
	(segment
		(start 182.98287 -300.212506)
		(end 183.12765 -300.357286)
		(width 0.14478)
		(layer "In11.Cu")
		(net "M_L_CPU1_SB_DQ<18>")
	)
	(segment
		(start 164.57676 -301.286926)
		(end 164.57676 -301.231046)
		(width 0.14478)
		(layer "In11.Cu")
		(net "M_L_CPU1_SB_DQ<18>")
	)
	(segment
		(start 191.79667 -300.46549)
		(end 191.79667 -300.357286)
		(width 0.14478)
		(layer "In11.Cu")
		(net "M_L_CPU1_SB_DQ<18>")
	)
	(segment
		(start 184.859422 -300.46549)
		(end 185.004202 -300.61027)
		(width 0.14478)
		(layer "In11.Cu")
		(net "M_L_CPU1_SB_DQ<18>")
	)
	(segment
		(start 178.576478 -301.460408)
		(end 181.23789 -301.460408)
		(width 0.14478)
		(layer "In11.Cu")
		(net "M_L_CPU1_SB_DQ<18>")
	)
	(segment
		(start 199.492616 -301.002954)
		(end 199.637396 -300.858174)
		(width 0.14478)
		(layer "In11.Cu")
		(net "M_L_CPU1_SB_DQ<18>")
	)
	(segment
		(start 144.205198 -284.284674)
		(end 144.221454 -284.294072)
		(width 0.0889)
		(layer "In11.Cu")
		(net "M_L_CPU1_SB_DQ<18>")
	)
	(segment
		(start 145.444718 -284.370272)
		(end 146.162776 -284.370272)
		(width 0.0889)
		(layer "In11.Cu")
		(net "M_L_CPU1_SB_DQ<18>")
	)
	(segment
		(start 172.857668 -301.060866)
		(end 173.119542 -301.060866)
		(width 0.14478)
		(layer "In11.Cu")
		(net "M_L_CPU1_SB_DQ<18>")
	)
	(segment
		(start 164.025326 -301.231046)
		(end 164.025326 -301.286926)
		(width 0.14478)
		(layer "In11.Cu")
		(net "M_L_CPU1_SB_DQ<18>")
	)
	(segment
		(start 190.056008 -300.362366)
		(end 190.200788 -300.217586)
		(width 0.14478)
		(layer "In11.Cu")
		(net "M_L_CPU1_SB_DQ<18>")
	)
	(segment
		(start 171.032678 -301.460408)
		(end 172.568108 -301.460408)
		(width 0.14478)
		(layer "In11.Cu")
		(net "M_L_CPU1_SB_DQ<18>")
	)
	(segment
		(start 184.859422 -300.362366)
		(end 184.859422 -300.46549)
		(width 0.14478)
		(layer "In11.Cu")
		(net "M_L_CPU1_SB_DQ<18>")
	)
	(segment
		(start 191.79667 -300.357286)
		(end 191.94145 -300.212506)
		(width 0.14478)
		(layer "In11.Cu")
		(net "M_L_CPU1_SB_DQ<18>")
	)
	(segment
		(start 183.27243 -300.61027)
		(end 184.163208 -300.61027)
		(width 0.14478)
		(layer "In11.Cu")
		(net "M_L_CPU1_SB_DQ<18>")
	)
	(segment
		(start 168.00449 -300.46549)
		(end 168.00449 -300.369986)
		(width 0.14478)
		(layer "In11.Cu")
		(net "M_L_CPU1_SB_DQ<18>")
	)
	(segment
		(start 147.650708 -285.068264)
		(end 147.905216 -285.068264)
		(width 0.0889)
		(layer "In11.Cu")
		(net "M_L_CPU1_SB_DQ<18>")
	)
	(segment
		(start 146.162776 -284.370272)
		(end 146.74977 -284.957266)
		(width 0.0889)
		(layer "In11.Cu")
		(net "M_L_CPU1_SB_DQ<18>")
	)
	(segment
		(start 201.436478 -300.61027)
		(end 201.72299 -300.61027)
		(width 0.14478)
		(layer "In11.Cu")
		(net "M_L_CPU1_SB_DQ<18>")
	)
	(segment
		(start 168.555924 -300.369986)
		(end 168.555924 -300.46549)
		(width 0.14478)
		(layer "In11.Cu")
		(net "M_L_CPU1_SB_DQ<18>")
	)
	(segment
		(start 187.803028 -301.315628)
		(end 187.803028 -301.223426)
		(width 0.14478)
		(layer "In11.Cu")
		(net "M_L_CPU1_SB_DQ<18>")
	)
	(segment
		(start 189.911228 -300.61027)
		(end 190.056008 -300.46549)
		(width 0.14478)
		(layer "In11.Cu")
		(net "M_L_CPU1_SB_DQ<18>")
	)
	(segment
		(start 190.607442 -300.362366)
		(end 190.607442 -300.46549)
		(width 0.14478)
		(layer "In11.Cu")
		(net "M_L_CPU1_SB_DQ<18>")
	)
	(segment
		(start 165.128194 -301.231046)
		(end 165.128194 -301.286926)
		(width 0.14478)
		(layer "In11.Cu")
		(net "M_L_CPU1_SB_DQ<18>")
	)
	(segment
		(start 168.00449 -300.369986)
		(end 168.14927 -300.225206)
		(width 0.14478)
		(layer "In11.Cu")
		(net "M_L_CPU1_SB_DQ<18>")
	)
	(segment
		(start 193.664332 -301.460154)
		(end 196.373496 -301.460154)
		(width 0.14478)
		(layer "In11.Cu")
		(net "M_L_CPU1_SB_DQ<18>")
	)
	(segment
		(start 199.085962 -300.75505)
		(end 199.085962 -300.858174)
		(width 0.14478)
		(layer "In11.Cu")
		(net "M_L_CPU1_SB_DQ<18>")
	)
	(segment
		(start 184.452768 -300.217586)
		(end 184.714642 -300.217586)
		(width 0.14478)
		(layer "In11.Cu")
		(net "M_L_CPU1_SB_DQ<18>")
	)
	(segment
		(start 184.714642 -300.217586)
		(end 184.859422 -300.362366)
		(width 0.14478)
		(layer "In11.Cu")
		(net "M_L_CPU1_SB_DQ<18>")
	)
	(segment
		(start 169.658792 -300.369986)
		(end 169.658792 -300.46549)
		(width 0.14478)
		(layer "In11.Cu")
		(net "M_L_CPU1_SB_DQ<18>")
	)
	(segment
		(start 200.04405 -300.217586)
		(end 200.18883 -300.362366)
		(width 0.14478)
		(layer "In11.Cu")
		(net "M_L_CPU1_SB_DQ<18>")
	)
	(segment
		(start 141.967712 -284.293818)
		(end 141.976094 -284.288992)
		(width 0.0889)
		(layer "In11.Cu")
		(net "M_L_CPU1_SB_DQ<18>")
	)
	(segment
		(start 164.57676 -301.231046)
		(end 164.72154 -301.086266)
		(width 0.14478)
		(layer "In11.Cu")
		(net "M_L_CPU1_SB_DQ<18>")
	)
	(segment
		(start 200.18883 -300.362366)
		(end 200.18883 -300.858174)
		(width 0.14478)
		(layer "In11.Cu")
		(net "M_L_CPU1_SB_DQ<18>")
	)
	(segment
		(start 168.14927 -300.225206)
		(end 168.411144 -300.225206)
		(width 0.14478)
		(layer "In11.Cu")
		(net "M_L_CPU1_SB_DQ<18>")
	)
	(segment
		(start 148.73859 -285.068264)
		(end 155.555188 -291.884862)
		(width 0.14478)
		(layer "In11.Cu")
		(net "M_L_CPU1_SB_DQ<18>")
	)
	(segment
		(start 187.947808 -301.078646)
		(end 188.209682 -301.078646)
		(width 0.14478)
		(layer "In11.Cu")
		(net "M_L_CPU1_SB_DQ<18>")
	)
	(segment
		(start 188.209682 -301.078646)
		(end 188.354462 -301.223426)
		(width 0.14478)
		(layer "In11.Cu")
		(net "M_L_CPU1_SB_DQ<18>")
	)
	(segment
		(start 200.885044 -300.217586)
		(end 201.146918 -300.217586)
		(width 0.14478)
		(layer "In11.Cu")
		(net "M_L_CPU1_SB_DQ<18>")
	)
	(segment
		(start 182.576216 -300.357286)
		(end 182.720996 -300.212506)
		(width 0.14478)
		(layer "In11.Cu")
		(net "M_L_CPU1_SB_DQ<18>")
	)
	(segment
		(start 168.962578 -300.61027)
		(end 169.107358 -300.46549)
		(width 0.14478)
		(layer "In11.Cu")
		(net "M_L_CPU1_SB_DQ<18>")
	)
	(segment
		(start 197.22338 -300.61027)
		(end 198.941182 -300.61027)
		(width 0.14478)
		(layer "In11.Cu")
		(net "M_L_CPU1_SB_DQ<18>")
	)
	(segment
		(start 188.781944 -301.460408)
		(end 189.632082 -300.61027)
		(width 0.14478)
		(layer "In11.Cu")
		(net "M_L_CPU1_SB_DQ<18>")
	)
	(segment
		(start 188.354462 -301.315628)
		(end 188.499242 -301.460408)
		(width 0.14478)
		(layer "In11.Cu")
		(net "M_L_CPU1_SB_DQ<18>")
	)
	(segment
		(start 147.53971 -284.957266)
		(end 147.650708 -285.068264)
		(width 0.0889)
		(layer "In11.Cu")
		(net "M_L_CPU1_SB_DQ<18>")
	)
	(segment
		(start 173.693836 -301.460408)
		(end 174.543974 -300.61027)
		(width 0.14478)
		(layer "In11.Cu")
		(net "M_L_CPU1_SB_DQ<18>")
	)
	(segment
		(start 189.632082 -300.61027)
		(end 189.911228 -300.61027)
		(width 0.14478)
		(layer "In11.Cu")
		(net "M_L_CPU1_SB_DQ<18>")
	)
	(segment
		(start 162.922458 -301.286926)
		(end 163.067238 -301.431706)
		(width 0.14478)
		(layer "In11.Cu")
		(net "M_L_CPU1_SB_DQ<18>")
	)
	(segment
		(start 192.492884 -300.61027)
		(end 192.814448 -300.61027)
		(width 0.14478)
		(layer "In11.Cu")
		(net "M_L_CPU1_SB_DQ<18>")
	)
	(segment
		(start 185.004202 -300.61027)
		(end 185.270394 -300.61027)
		(width 0.14478)
		(layer "In11.Cu")
		(net "M_L_CPU1_SB_DQ<18>")
	)
	(segment
		(start 164.43198 -301.431706)
		(end 164.57676 -301.286926)
		(width 0.14478)
		(layer "In11.Cu")
		(net "M_L_CPU1_SB_DQ<18>")
	)
	(segment
		(start 200.740264 -300.362366)
		(end 200.885044 -300.217586)
		(width 0.14478)
		(layer "In11.Cu")
		(net "M_L_CPU1_SB_DQ<18>")
	)
	(segment
		(start 162.046158 -301.086266)
		(end 162.777678 -301.086266)
		(width 0.14478)
		(layer "In11.Cu")
		(net "M_L_CPU1_SB_DQ<18>")
	)
	(segment
		(start 187.803028 -301.223426)
		(end 187.947808 -301.078646)
		(width 0.14478)
		(layer "In11.Cu")
		(net "M_L_CPU1_SB_DQ<18>")
	)
	(segment
		(start 187.658248 -301.460408)
		(end 187.803028 -301.315628)
		(width 0.14478)
		(layer "In11.Cu")
		(net "M_L_CPU1_SB_DQ<18>")
	)
	(segment
		(start 169.252138 -300.225206)
		(end 169.514012 -300.225206)
		(width 0.14478)
		(layer "In11.Cu")
		(net "M_L_CPU1_SB_DQ<18>")
	)
	(segment
		(start 201.72299 -300.61027)
		(end 202.147932 -301.035212)
		(width 0.14478)
		(layer "In11.Cu")
		(net "M_L_CPU1_SB_DQ<18>")
	)
	(segment
		(start 199.637396 -300.858174)
		(end 199.637396 -300.362366)
		(width 0.14478)
		(layer "In11.Cu")
		(net "M_L_CPU1_SB_DQ<18>")
	)
	(segment
		(start 183.12765 -300.357286)
		(end 183.12765 -300.46549)
		(width 0.14478)
		(layer "In11.Cu")
		(net "M_L_CPU1_SB_DQ<18>")
	)
	(segment
		(start 139.488672 -284.350968)
		(end 139.584684 -284.325568)
		(width 0.0889)
		(layer "In11.Cu")
		(net "M_L_CPU1_SB_DQ<18>")
	)
	(segment
		(start 200.740264 -300.858174)
		(end 200.740264 -300.362366)
		(width 0.14478)
		(layer "In11.Cu")
		(net "M_L_CPU1_SB_DQ<18>")
	)
	(segment
		(start 200.18883 -300.858174)
		(end 200.33361 -301.002954)
		(width 0.14478)
		(layer "In11.Cu")
		(net "M_L_CPU1_SB_DQ<18>")
	)
	(segment
		(start 168.411144 -300.225206)
		(end 168.555924 -300.369986)
		(width 0.14478)
		(layer "In11.Cu")
		(net "M_L_CPU1_SB_DQ<18>")
	)
	(segment
		(start 141.393418 -284.288992)
		(end 141.4018 -284.293818)
		(width 0.0889)
		(layer "In11.Cu")
		(net "M_L_CPU1_SB_DQ<18>")
	)
	(segment
		(start 163.473892 -301.286926)
		(end 163.473892 -301.231046)
		(width 0.14478)
		(layer "In11.Cu")
		(net "M_L_CPU1_SB_DQ<18>")
	)
	(segment
		(start 163.067238 -301.431706)
		(end 163.329112 -301.431706)
		(width 0.14478)
		(layer "In11.Cu")
		(net "M_L_CPU1_SB_DQ<18>")
	)
	(segment
		(start 188.499242 -301.460408)
		(end 188.781944 -301.460408)
		(width 0.14478)
		(layer "In11.Cu")
		(net "M_L_CPU1_SB_DQ<18>")
	)
	(segment
		(start 190.607442 -300.46549)
		(end 190.752222 -300.61027)
		(width 0.14478)
		(layer "In11.Cu")
		(net "M_L_CPU1_SB_DQ<18>")
	)
	(segment
		(start 182.431436 -300.61027)
		(end 182.576216 -300.46549)
		(width 0.14478)
		(layer "In11.Cu")
		(net "M_L_CPU1_SB_DQ<18>")
	)
	(segment
		(start 192.814448 -300.61027)
		(end 193.664332 -301.460154)
		(width 0.14478)
		(layer "In11.Cu")
		(net "M_L_CPU1_SB_DQ<18>")
	)
	(segment
		(start 190.462662 -300.217586)
		(end 190.607442 -300.362366)
		(width 0.14478)
		(layer "In11.Cu")
		(net "M_L_CPU1_SB_DQ<18>")
	)
	(segment
		(start 200.33361 -301.002954)
		(end 200.595484 -301.002954)
		(width 0.14478)
		(layer "In11.Cu")
		(net "M_L_CPU1_SB_DQ<18>")
	)
	(segment
		(start 191.65189 -300.61027)
		(end 191.79667 -300.46549)
		(width 0.14478)
		(layer "In11.Cu")
		(net "M_L_CPU1_SB_DQ<18>")
	)
	(segment
		(start 144.786604 -284.293818)
		(end 144.798288 -284.28696)
		(width 0.0889)
		(layer "In11.Cu")
		(net "M_L_CPU1_SB_DQ<18>")
	)
	(segment
		(start 169.514012 -300.225206)
		(end 169.658792 -300.369986)
		(width 0.14478)
		(layer "In11.Cu")
		(net "M_L_CPU1_SB_DQ<18>")
	)
	(segment
		(start 166.99992 -300.61027)
		(end 167.85971 -300.61027)
		(width 0.14478)
		(layer "In11.Cu")
		(net "M_L_CPU1_SB_DQ<18>")
	)
	(segment
		(start 147.905216 -285.068264)
		(end 148.73859 -285.068264)
		(width 0.14478)
		(layer "In11.Cu")
		(net "M_L_CPU1_SB_DQ<18>")
	)
	(segment
		(start 140.453364 -284.288992)
		(end 140.461746 -284.293818)
		(width 0.0889)
		(layer "In11.Cu")
		(net "M_L_CPU1_SB_DQ<18>")
	)
	(segment
		(start 188.354462 -301.223426)
		(end 188.354462 -301.315628)
		(width 0.14478)
		(layer "In11.Cu")
		(net "M_L_CPU1_SB_DQ<18>")
	)
	(segment
		(start 173.264322 -301.315628)
		(end 173.409102 -301.460408)
		(width 0.14478)
		(layer "In11.Cu")
		(net "M_L_CPU1_SB_DQ<18>")
	)
	(segment
		(start 198.941182 -300.61027)
		(end 199.085962 -300.75505)
		(width 0.14478)
		(layer "In11.Cu")
		(net "M_L_CPU1_SB_DQ<18>")
	)
	(segment
		(start 200.595484 -301.002954)
		(end 200.740264 -300.858174)
		(width 0.14478)
		(layer "In11.Cu")
		(net "M_L_CPU1_SB_DQ<18>")
	)
	(segment
		(start 174.543974 -300.61027)
		(end 177.72634 -300.61027)
		(width 0.14478)
		(layer "In11.Cu")
		(net "M_L_CPU1_SB_DQ<18>")
	)
	(segment
		(start 165.679628 -301.286926)
		(end 165.679628 -301.231046)
		(width 0.14478)
		(layer "In11.Cu")
		(net "M_L_CPU1_SB_DQ<18>")
	)
	(segment
		(start 201.291698 -300.46549)
		(end 201.436478 -300.61027)
		(width 0.14478)
		(layer "In11.Cu")
		(net "M_L_CPU1_SB_DQ<18>")
	)
	(segment
		(start 164.170106 -301.431706)
		(end 164.43198 -301.431706)
		(width 0.14478)
		(layer "In11.Cu")
		(net "M_L_CPU1_SB_DQ<18>")
	)
	(segment
		(start 201.146918 -300.217586)
		(end 201.291698 -300.362366)
		(width 0.14478)
		(layer "In11.Cu")
		(net "M_L_CPU1_SB_DQ<18>")
	)
	(segment
		(start 191.94145 -300.212506)
		(end 192.203324 -300.212506)
		(width 0.14478)
		(layer "In11.Cu")
		(net "M_L_CPU1_SB_DQ<18>")
	)
	(segment
		(start 192.203324 -300.212506)
		(end 192.348104 -300.357286)
		(width 0.14478)
		(layer "In11.Cu")
		(net "M_L_CPU1_SB_DQ<18>")
	)
	(segment
		(start 165.679628 -301.231046)
		(end 165.824408 -301.086266)
		(width 0.14478)
		(layer "In11.Cu")
		(net "M_L_CPU1_SB_DQ<18>")
	)
	(segment
		(start 190.056008 -300.46549)
		(end 190.056008 -300.362366)
		(width 0.14478)
		(layer "In11.Cu")
		(net "M_L_CPU1_SB_DQ<18>")
	)
	(segment
		(start 163.880546 -301.086266)
		(end 164.025326 -301.231046)
		(width 0.14478)
		(layer "In11.Cu")
		(net "M_L_CPU1_SB_DQ<18>")
	)
	(segment
		(start 163.473892 -301.231046)
		(end 163.618672 -301.086266)
		(width 0.14478)
		(layer "In11.Cu")
		(net "M_L_CPU1_SB_DQ<18>")
	)
	(segment
		(start 165.824408 -301.086266)
		(end 166.523924 -301.086266)
		(width 0.14478)
		(layer "In11.Cu")
		(net "M_L_CPU1_SB_DQ<18>")
	)
	(segment
		(start 144.221454 -284.294072)
		(end 144.233392 -284.30093)
		(width 0.0889)
		(layer "In11.Cu")
		(net "M_L_CPU1_SB_DQ<18>")
	)
	(segment
		(start 165.534848 -301.431706)
		(end 165.679628 -301.286926)
		(width 0.14478)
		(layer "In11.Cu")
		(net "M_L_CPU1_SB_DQ<18>")
	)
	(segment
		(start 163.618672 -301.086266)
		(end 163.880546 -301.086266)
		(width 0.14478)
		(layer "In11.Cu")
		(net "M_L_CPU1_SB_DQ<18>")
	)
	(segment
		(start 165.128194 -301.286926)
		(end 165.272974 -301.431706)
		(width 0.14478)
		(layer "In11.Cu")
		(net "M_L_CPU1_SB_DQ<18>")
	)
	(segment
		(start 155.555188 -294.595296)
		(end 162.046158 -301.086266)
		(width 0.14478)
		(layer "In11.Cu")
		(net "M_L_CPU1_SB_DQ<18>")
	)
	(segment
		(start 182.720996 -300.212506)
		(end 182.98287 -300.212506)
		(width 0.14478)
		(layer "In11.Cu")
		(net "M_L_CPU1_SB_DQ<18>")
	)
	(segment
		(start 169.658792 -300.46549)
		(end 169.803572 -300.61027)
		(width 0.14478)
		(layer "In11.Cu")
		(net "M_L_CPU1_SB_DQ<18>")
	)
	(segment
		(start 164.025326 -301.286926)
		(end 164.170106 -301.431706)
		(width 0.14478)
		(layer "In11.Cu")
		(net "M_L_CPU1_SB_DQ<18>")
	)
	(segment
		(start 184.307988 -300.362366)
		(end 184.452768 -300.217586)
		(width 0.14478)
		(layer "In11.Cu")
		(net "M_L_CPU1_SB_DQ<18>")
	)
	(segment
		(start 173.119542 -301.060866)
		(end 173.264322 -301.205646)
		(width 0.14478)
		(layer "In11.Cu")
		(net "M_L_CPU1_SB_DQ<18>")
	)
	(segment
		(start 199.637396 -300.362366)
		(end 199.782176 -300.217586)
		(width 0.14478)
		(layer "In11.Cu")
		(net "M_L_CPU1_SB_DQ<18>")
	)
	(segment
		(start 186.120532 -301.460408)
		(end 187.658248 -301.460408)
		(width 0.14478)
		(layer "In11.Cu")
		(net "M_L_CPU1_SB_DQ<18>")
	)
	(segment
		(start 172.568108 -301.460408)
		(end 172.712888 -301.315628)
		(width 0.14478)
		(layer "In11.Cu")
		(net "M_L_CPU1_SB_DQ<18>")
	)
	(segment
		(start 163.329112 -301.431706)
		(end 163.473892 -301.286926)
		(width 0.14478)
		(layer "In11.Cu")
		(net "M_L_CPU1_SB_DQ<18>")
	)
	(segment
		(start 167.85971 -300.61027)
		(end 168.00449 -300.46549)
		(width 0.14478)
		(layer "In11.Cu")
		(net "M_L_CPU1_SB_DQ<18>")
	)
	(segment
		(start 173.264322 -301.205646)
		(end 173.264322 -301.315628)
		(width 0.14478)
		(layer "In11.Cu")
		(net "M_L_CPU1_SB_DQ<18>")
	)
	(segment
		(start 199.085962 -300.858174)
		(end 199.230742 -301.002954)
		(width 0.14478)
		(layer "In11.Cu")
		(net "M_L_CPU1_SB_DQ<18>")
	)
	(segment
		(start 146.74977 -284.957266)
		(end 147.53971 -284.957266)
		(width 0.0889)
		(layer "In11.Cu")
		(net "M_L_CPU1_SB_DQ<18>")
	)
	(segment
		(start 181.23789 -301.460408)
		(end 182.088028 -300.61027)
		(width 0.14478)
		(layer "In11.Cu")
		(net "M_L_CPU1_SB_DQ<18>")
	)
	(segment
		(start 190.200788 -300.217586)
		(end 190.462662 -300.217586)
		(width 0.14478)
		(layer "In11.Cu")
		(net "M_L_CPU1_SB_DQ<18>")
	)
	(segment
		(start 164.72154 -301.086266)
		(end 164.983414 -301.086266)
		(width 0.14478)
		(layer "In11.Cu")
		(net "M_L_CPU1_SB_DQ<18>")
	)
	(segment
		(start 182.576216 -300.46549)
		(end 182.576216 -300.357286)
		(width 0.14478)
		(layer "In11.Cu")
		(net "M_L_CPU1_SB_DQ<18>")
	)
	(segment
		(start 165.272974 -301.431706)
		(end 165.534848 -301.431706)
		(width 0.14478)
		(layer "In11.Cu")
		(net "M_L_CPU1_SB_DQ<18>")
	)
	(segment
		(start 190.752222 -300.61027)
		(end 191.65189 -300.61027)
		(width 0.14478)
		(layer "In11.Cu")
		(net "M_L_CPU1_SB_DQ<18>")
	)
	(segment
		(start 168.700704 -300.61027)
		(end 168.962578 -300.61027)
		(width 0.14478)
		(layer "In11.Cu")
		(net "M_L_CPU1_SB_DQ<18>")
	)
	(segment
		(start 177.72634 -300.61027)
		(end 178.576478 -301.460408)
		(width 0.14478)
		(layer "In11.Cu")
		(net "M_L_CPU1_SB_DQ<18>")
	)
	(segment
		(start 169.803572 -300.61027)
		(end 170.18254 -300.61027)
		(width 0.14478)
		(layer "In11.Cu")
		(net "M_L_CPU1_SB_DQ<18>")
	)
	(segment
		(start 192.348104 -300.46549)
		(end 192.492884 -300.61027)
		(width 0.14478)
		(layer "In11.Cu")
		(net "M_L_CPU1_SB_DQ<18>")
	)
	(segment
		(start 172.712888 -301.315628)
		(end 172.712888 -301.205646)
		(width 0.14478)
		(layer "In11.Cu")
		(net "M_L_CPU1_SB_DQ<18>")
	)
	(segment
		(start 201.291698 -300.362366)
		(end 201.291698 -300.46549)
		(width 0.14478)
		(layer "In11.Cu")
		(net "M_L_CPU1_SB_DQ<18>")
	)
	(segment
		(start 162.922458 -301.231046)
		(end 162.922458 -301.286926)
		(width 0.14478)
		(layer "In11.Cu")
		(net "M_L_CPU1_SB_DQ<18>")
	)
	(segment
		(start 184.307988 -300.46549)
		(end 184.307988 -300.362366)
		(width 0.14478)
		(layer "In11.Cu")
		(net "M_L_CPU1_SB_DQ<18>")
	)
	(segment
		(start 182.088028 -300.61027)
		(end 182.431436 -300.61027)
		(width 0.14478)
		(layer "In11.Cu")
		(net "M_L_CPU1_SB_DQ<18>")
	)
	(segment
		(start 166.523924 -301.086266)
		(end 166.99992 -300.61027)
		(width 0.14478)
		(layer "In11.Cu")
		(net "M_L_CPU1_SB_DQ<18>")
	)
	(segment
		(start 169.107358 -300.46549)
		(end 169.107358 -300.369986)
		(width 0.14478)
		(layer "In11.Cu")
		(net "M_L_CPU1_SB_DQ<18>")
	)
	(segment
		(start 199.782176 -300.217586)
		(end 200.04405 -300.217586)
		(width 0.14478)
		(layer "In11.Cu")
		(net "M_L_CPU1_SB_DQ<18>")
	)
	(segment
		(start 172.712888 -301.205646)
		(end 172.857668 -301.060866)
		(width 0.14478)
		(layer "In11.Cu")
		(net "M_L_CPU1_SB_DQ<18>")
	)
	(segment
		(start 173.409102 -301.460408)
		(end 173.693836 -301.460408)
		(width 0.14478)
		(layer "In11.Cu")
		(net "M_L_CPU1_SB_DQ<18>")
	)
	(segment
		(start 184.163208 -300.61027)
		(end 184.307988 -300.46549)
		(width 0.14478)
		(layer "In11.Cu")
		(net "M_L_CPU1_SB_DQ<18>")
	)
	(segment
		(start 170.18254 -300.61027)
		(end 171.032678 -301.460408)
		(width 0.14478)
		(layer "In11.Cu")
		(net "M_L_CPU1_SB_DQ<18>")
	)
	(segment
		(start 168.555924 -300.46549)
		(end 168.700704 -300.61027)
		(width 0.14478)
		(layer "In11.Cu")
		(net "M_L_CPU1_SB_DQ<18>")
	)
	(segment
		(start 192.348104 -300.357286)
		(end 192.348104 -300.46549)
		(width 0.14478)
		(layer "In11.Cu")
		(net "M_L_CPU1_SB_DQ<18>")
	)
	(segment
		(start 185.270394 -300.61027)
		(end 186.120532 -301.460408)
		(width 0.14478)
		(layer "In11.Cu")
		(net "M_L_CPU1_SB_DQ<18>")
	)
	(segment
		(start 199.230742 -301.002954)
		(end 199.492616 -301.002954)
		(width 0.14478)
		(layer "In11.Cu")
		(net "M_L_CPU1_SB_DQ<18>")
	)
	(segment
		(start 162.777678 -301.086266)
		(end 162.922458 -301.231046)
		(width 0.14478)
		(layer "In11.Cu")
		(net "M_L_CPU1_SB_DQ<18>")
	)
	(segment
		(start 155.555188 -291.884862)
		(end 155.555188 -294.595296)
		(width 0.14478)
		(layer "In11.Cu")
		(net "M_L_CPU1_SB_DQ<18>")
	)
	(segment
		(start 169.107358 -300.369986)
		(end 169.252138 -300.225206)
		(width 0.14478)
		(layer "In11.Cu")
		(net "M_L_CPU1_SB_DQ<18>")
	)
	(arc
		(start 140.087604 -284.293818)
		(mid 140.269855 -284.243468)
		(end 140.453364 -284.288992)
		(width 0.0889)
		(layer "In11.Cu")
		(net "M_L_CPU1_SB_DQ<18>")
	)
	(arc
		(start 144.798288 -284.28696)
		(mid 144.980543 -284.243307)
		(end 145.161 -284.293818)
		(width 0.0889)
		(layer "In11.Cu")
		(net "M_L_CPU1_SB_DQ<18>")
	)
	(arc
		(start 143.847566 -284.293818)
		(mid 144.025216 -284.243558)
		(end 144.205198 -284.284674)
		(width 0.0889)
		(layer "In11.Cu")
		(net "M_L_CPU1_SB_DQ<18>")
	)
	(arc
		(start 145.161 -284.293818)
		(mid 145.297793 -284.35084)
		(end 145.444718 -284.370272)
		(width 0.0889)
		(layer "In11.Cu")
		(net "M_L_CPU1_SB_DQ<18>")
	)
	(arc
		(start 142.907766 -284.293818)
		(mid 143.09471 -284.243563)
		(end 143.281654 -284.293818)
		(width 0.0889)
		(layer "In11.Cu")
		(net "M_L_CPU1_SB_DQ<18>")
	)
	(arc
		(start 143.281654 -284.293818)
		(mid 143.56461 -284.369995)
		(end 143.847566 -284.293818)
		(width 0.0889)
		(layer "In11.Cu")
		(net "M_L_CPU1_SB_DQ<18>")
	)
	(arc
		(start 141.4018 -284.293818)
		(mid 141.684756 -284.369995)
		(end 141.967712 -284.293818)
		(width 0.0889)
		(layer "In11.Cu")
		(net "M_L_CPU1_SB_DQ<18>")
	)
	(arc
		(start 140.461746 -284.293818)
		(mid 140.744702 -284.369995)
		(end 141.027658 -284.293818)
		(width 0.0889)
		(layer "In11.Cu")
		(net "M_L_CPU1_SB_DQ<18>")
	)
	(arc
		(start 139.584684 -284.325568)
		(mid 139.839892 -284.369045)
		(end 140.087604 -284.293818)
		(width 0.0889)
		(layer "In11.Cu")
		(net "M_L_CPU1_SB_DQ<18>")
	)
	(arc
		(start 141.976094 -284.288992)
		(mid 142.159602 -284.243498)
		(end 142.341854 -284.293818)
		(width 0.0889)
		(layer "In11.Cu")
		(net "M_L_CPU1_SB_DQ<18>")
	)
	(arc
		(start 141.027658 -284.293818)
		(mid 141.209909 -284.243468)
		(end 141.393418 -284.288992)
		(width 0.0889)
		(layer "In11.Cu")
		(net "M_L_CPU1_SB_DQ<18>")
	)
	(arc
		(start 144.233392 -284.30093)
		(mid 144.510926 -284.369911)
		(end 144.786604 -284.293818)
		(width 0.0889)
		(layer "In11.Cu")
		(net "M_L_CPU1_SB_DQ<18>")
	)
	(arc
		(start 142.341854 -284.293818)
		(mid 142.62481 -284.369995)
		(end 142.907766 -284.293818)
		(width 0.0889)
		(layer "In11.Cu")
		(net "M_L_CPU1_SB_DQ<18>")
	)
	(segment
		(start 137.927842 -284.35046)
		(end 138.394694 -284.616398)
		(width 0.10668)
		(layer "F.Cu")
		(net "M_L_CPU1_SB_DQ<17>")
	)
	(segment
		(start 147.34921 -285.231586)
		(end 147.640548 -285.522924)
		(width 0.0889)
		(layer "In11.Cu")
		(net "M_L_CPU1_SB_DQ<17>")
	)
	(segment
		(start 205.822804 -301.460154)
		(end 206.248 -301.88535)
		(width 0.14478)
		(layer "In11.Cu")
		(net "M_L_CPU1_SB_DQ<17>")
	)
	(segment
		(start 189.512448 -301.460408)
		(end 192.749424 -301.460408)
		(width 0.14478)
		(layer "In11.Cu")
		(net "M_L_CPU1_SB_DQ<17>")
	)
	(segment
		(start 193.599308 -302.310292)
		(end 193.599562 -302.310038)
		(width 0.14478)
		(layer "In11.Cu")
		(net "M_L_CPU1_SB_DQ<17>")
	)
	(segment
		(start 143.847566 -284.938978)
		(end 143.862044 -284.94736)
		(width 0.0889)
		(layer "In11.Cu")
		(net "M_L_CPU1_SB_DQ<17>")
	)
	(segment
		(start 155.100528 -294.82034)
		(end 162.59048 -302.310292)
		(width 0.14478)
		(layer "In11.Cu")
		(net "M_L_CPU1_SB_DQ<17>")
	)
	(segment
		(start 170.967146 -302.310292)
		(end 173.526704 -302.310292)
		(width 0.14478)
		(layer "In11.Cu")
		(net "M_L_CPU1_SB_DQ<17>")
	)
	(segment
		(start 167.092884 -301.460154)
		(end 170.117008 -301.460154)
		(width 0.14478)
		(layer "In11.Cu")
		(net "M_L_CPU1_SB_DQ<17>")
	)
	(segment
		(start 204.861922 -302.149764)
		(end 205.02499 -301.986696)
		(width 0.14478)
		(layer "In11.Cu")
		(net "M_L_CPU1_SB_DQ<17>")
	)
	(segment
		(start 205.02499 -301.623222)
		(end 205.188058 -301.460154)
		(width 0.14478)
		(layer "In11.Cu")
		(net "M_L_CPU1_SB_DQ<17>")
	)
	(segment
		(start 147.853908 -285.522924)
		(end 148.550122 -285.522924)
		(width 0.14478)
		(layer "In11.Cu")
		(net "M_L_CPU1_SB_DQ<17>")
	)
	(segment
		(start 140.453364 -284.943804)
		(end 140.461746 -284.938978)
		(width 0.0889)
		(layer "In11.Cu")
		(net "M_L_CPU1_SB_DQ<17>")
	)
	(segment
		(start 146.130264 -285.231586)
		(end 147.34921 -285.231586)
		(width 0.0889)
		(layer "In11.Cu")
		(net "M_L_CPU1_SB_DQ<17>")
	)
	(segment
		(start 204.468476 -301.623222)
		(end 204.468476 -301.986696)
		(width 0.14478)
		(layer "In11.Cu")
		(net "M_L_CPU1_SB_DQ<17>")
	)
	(segment
		(start 145.14322 -284.950154)
		(end 145.163286 -284.938724)
		(width 0.0889)
		(layer "In11.Cu")
		(net "M_L_CPU1_SB_DQ<17>")
	)
	(segment
		(start 204.305408 -301.460154)
		(end 204.468476 -301.623222)
		(width 0.14478)
		(layer "In11.Cu")
		(net "M_L_CPU1_SB_DQ<17>")
	)
	(segment
		(start 141.967712 -284.938978)
		(end 141.976094 -284.943804)
		(width 0.0889)
		(layer "In11.Cu")
		(net "M_L_CPU1_SB_DQ<17>")
	)
	(segment
		(start 170.117008 -301.460154)
		(end 170.967146 -302.310292)
		(width 0.14478)
		(layer "In11.Cu")
		(net "M_L_CPU1_SB_DQ<17>")
	)
	(segment
		(start 162.59048 -302.310292)
		(end 166.242746 -302.310292)
		(width 0.14478)
		(layer "In11.Cu")
		(net "M_L_CPU1_SB_DQ<17>")
	)
	(segment
		(start 177.661316 -301.460408)
		(end 178.5112 -302.310292)
		(width 0.14478)
		(layer "In11.Cu")
		(net "M_L_CPU1_SB_DQ<17>")
	)
	(segment
		(start 204.631544 -302.149764)
		(end 204.861922 -302.149764)
		(width 0.14478)
		(layer "In11.Cu")
		(net "M_L_CPU1_SB_DQ<17>")
	)
	(segment
		(start 197.21703 -301.460154)
		(end 204.305408 -301.460154)
		(width 0.14478)
		(layer "In11.Cu")
		(net "M_L_CPU1_SB_DQ<17>")
	)
	(segment
		(start 192.749424 -301.460408)
		(end 193.599308 -302.310292)
		(width 0.14478)
		(layer "In11.Cu")
		(net "M_L_CPU1_SB_DQ<17>")
	)
	(segment
		(start 138.24077 -284.881828)
		(end 138.263122 -284.96514)
		(width 0.0889)
		(layer "In11.Cu")
		(net "M_L_CPU1_SB_DQ<17>")
	)
	(segment
		(start 193.599562 -302.310038)
		(end 196.367146 -302.310038)
		(width 0.14478)
		(layer "In11.Cu")
		(net "M_L_CPU1_SB_DQ<17>")
	)
	(segment
		(start 204.468476 -301.986696)
		(end 204.631544 -302.149764)
		(width 0.14478)
		(layer "In11.Cu")
		(net "M_L_CPU1_SB_DQ<17>")
	)
	(segment
		(start 185.20537 -301.460408)
		(end 186.055254 -302.310292)
		(width 0.14478)
		(layer "In11.Cu")
		(net "M_L_CPU1_SB_DQ<17>")
	)
	(segment
		(start 205.02499 -301.986696)
		(end 205.02499 -301.623222)
		(width 0.14478)
		(layer "In11.Cu")
		(net "M_L_CPU1_SB_DQ<17>")
	)
	(segment
		(start 186.055254 -302.310292)
		(end 188.662564 -302.310292)
		(width 0.14478)
		(layer "In11.Cu")
		(net "M_L_CPU1_SB_DQ<17>")
	)
	(segment
		(start 155.100528 -292.07333)
		(end 155.100528 -294.82034)
		(width 0.14478)
		(layer "In11.Cu")
		(net "M_L_CPU1_SB_DQ<17>")
	)
	(segment
		(start 141.393418 -284.943804)
		(end 141.4018 -284.938978)
		(width 0.0889)
		(layer "In11.Cu")
		(net "M_L_CPU1_SB_DQ<17>")
	)
	(segment
		(start 166.242746 -302.310292)
		(end 167.092884 -301.460154)
		(width 0.14478)
		(layer "In11.Cu")
		(net "M_L_CPU1_SB_DQ<17>")
	)
	(segment
		(start 144.766538 -284.925262)
		(end 144.789906 -284.938978)
		(width 0.0889)
		(layer "In11.Cu")
		(net "M_L_CPU1_SB_DQ<17>")
	)
	(segment
		(start 181.11851 -302.310292)
		(end 181.968394 -301.460408)
		(width 0.14478)
		(layer "In11.Cu")
		(net "M_L_CPU1_SB_DQ<17>")
	)
	(segment
		(start 178.5112 -302.310292)
		(end 181.11851 -302.310292)
		(width 0.14478)
		(layer "In11.Cu")
		(net "M_L_CPU1_SB_DQ<17>")
	)
	(segment
		(start 181.968394 -301.460408)
		(end 185.20537 -301.460408)
		(width 0.14478)
		(layer "In11.Cu")
		(net "M_L_CPU1_SB_DQ<17>")
	)
	(segment
		(start 138.394694 -284.616398)
		(end 138.24077 -284.881828)
		(width 0.0889)
		(layer "In11.Cu")
		(net "M_L_CPU1_SB_DQ<17>")
	)
	(segment
		(start 174.376588 -301.460408)
		(end 177.661316 -301.460408)
		(width 0.14478)
		(layer "In11.Cu")
		(net "M_L_CPU1_SB_DQ<17>")
	)
	(segment
		(start 147.640548 -285.522924)
		(end 147.853908 -285.522924)
		(width 0.0889)
		(layer "In11.Cu")
		(net "M_L_CPU1_SB_DQ<17>")
	)
	(segment
		(start 205.188058 -301.460154)
		(end 205.822804 -301.460154)
		(width 0.14478)
		(layer "In11.Cu")
		(net "M_L_CPU1_SB_DQ<17>")
	)
	(segment
		(start 173.526704 -302.310292)
		(end 174.376588 -301.460408)
		(width 0.14478)
		(layer "In11.Cu")
		(net "M_L_CPU1_SB_DQ<17>")
	)
	(segment
		(start 188.662564 -302.310292)
		(end 189.512448 -301.460408)
		(width 0.14478)
		(layer "In11.Cu")
		(net "M_L_CPU1_SB_DQ<17>")
	)
	(segment
		(start 196.367146 -302.310038)
		(end 197.21703 -301.460154)
		(width 0.14478)
		(layer "In11.Cu")
		(net "M_L_CPU1_SB_DQ<17>")
	)
	(segment
		(start 145.444464 -284.863286)
		(end 145.761964 -284.863286)
		(width 0.0889)
		(layer "In11.Cu")
		(net "M_L_CPU1_SB_DQ<17>")
	)
	(segment
		(start 148.550122 -285.522924)
		(end 155.100528 -292.07333)
		(width 0.14478)
		(layer "In11.Cu")
		(net "M_L_CPU1_SB_DQ<17>")
	)
	(segment
		(start 145.761964 -284.863286)
		(end 146.130264 -285.231586)
		(width 0.0889)
		(layer "In11.Cu")
		(net "M_L_CPU1_SB_DQ<17>")
	)
	(arc
		(start 139.521692 -284.938978)
		(mid 139.804648 -284.862801)
		(end 140.087604 -284.938978)
		(width 0.0889)
		(layer "In11.Cu")
		(net "M_L_CPU1_SB_DQ<17>")
	)
	(arc
		(start 144.789906 -284.938978)
		(mid 144.965145 -284.989049)
		(end 145.14322 -284.950154)
		(width 0.0889)
		(layer "In11.Cu")
		(net "M_L_CPU1_SB_DQ<17>")
	)
	(arc
		(start 145.163286 -284.938724)
		(mid 145.298919 -284.882549)
		(end 145.444464 -284.863286)
		(width 0.0889)
		(layer "In11.Cu")
		(net "M_L_CPU1_SB_DQ<17>")
	)
	(arc
		(start 142.907766 -284.938978)
		(mid 143.09471 -284.989233)
		(end 143.281654 -284.938978)
		(width 0.0889)
		(layer "In11.Cu")
		(net "M_L_CPU1_SB_DQ<17>")
	)
	(arc
		(start 141.4018 -284.938978)
		(mid 141.684756 -284.862801)
		(end 141.967712 -284.938978)
		(width 0.0889)
		(layer "In11.Cu")
		(net "M_L_CPU1_SB_DQ<17>")
	)
	(arc
		(start 138.263122 -284.96514)
		(mid 138.425454 -284.987958)
		(end 138.581892 -284.938978)
		(width 0.0889)
		(layer "In11.Cu")
		(net "M_L_CPU1_SB_DQ<17>")
	)
	(arc
		(start 142.341854 -284.938978)
		(mid 142.62481 -284.862801)
		(end 142.907766 -284.938978)
		(width 0.0889)
		(layer "In11.Cu")
		(net "M_L_CPU1_SB_DQ<17>")
	)
	(arc
		(start 141.976094 -284.943804)
		(mid 142.159602 -284.989298)
		(end 142.341854 -284.938978)
		(width 0.0889)
		(layer "In11.Cu")
		(net "M_L_CPU1_SB_DQ<17>")
	)
	(arc
		(start 144.222724 -284.938978)
		(mid 144.492881 -284.862216)
		(end 144.766538 -284.925262)
		(width 0.0889)
		(layer "In11.Cu")
		(net "M_L_CPU1_SB_DQ<17>")
	)
	(arc
		(start 138.581892 -284.938978)
		(mid 138.864848 -284.862801)
		(end 139.147804 -284.938978)
		(width 0.0889)
		(layer "In11.Cu")
		(net "M_L_CPU1_SB_DQ<17>")
	)
	(arc
		(start 140.461746 -284.938978)
		(mid 140.744702 -284.862801)
		(end 141.027658 -284.938978)
		(width 0.0889)
		(layer "In11.Cu")
		(net "M_L_CPU1_SB_DQ<17>")
	)
	(arc
		(start 143.281654 -284.938978)
		(mid 143.56461 -284.862801)
		(end 143.847566 -284.938978)
		(width 0.0889)
		(layer "In11.Cu")
		(net "M_L_CPU1_SB_DQ<17>")
	)
	(arc
		(start 139.147804 -284.938978)
		(mid 139.334748 -284.989233)
		(end 139.521692 -284.938978)
		(width 0.0889)
		(layer "In11.Cu")
		(net "M_L_CPU1_SB_DQ<17>")
	)
	(arc
		(start 141.027658 -284.938978)
		(mid 141.209909 -284.989328)
		(end 141.393418 -284.943804)
		(width 0.0889)
		(layer "In11.Cu")
		(net "M_L_CPU1_SB_DQ<17>")
	)
	(arc
		(start 143.862044 -284.94736)
		(mid 144.04346 -284.989617)
		(end 144.222724 -284.938978)
		(width 0.0889)
		(layer "In11.Cu")
		(net "M_L_CPU1_SB_DQ<17>")
	)
	(arc
		(start 140.087604 -284.938978)
		(mid 140.269855 -284.989328)
		(end 140.453364 -284.943804)
		(width 0.0889)
		(layer "In11.Cu")
		(net "M_L_CPU1_SB_DQ<17>")
	)
	(segment
		(start 139.337796 -283.540454)
		(end 139.804648 -283.806392)
		(width 0.10668)
		(layer "F.Cu")
		(net "M_L_CPU1_SB_DQ<16>")
	)
	(segment
		(start 142.803372 -284.133798)
		(end 142.811754 -284.128972)
		(width 0.0889)
		(layer "In11.Cu")
		(net "M_L_CPU1_SB_DQ<16>")
	)
	(segment
		(start 204.300074 -299.9232)
		(end 204.300074 -300.640496)
		(width 0.14478)
		(layer "In11.Cu")
		(net "M_L_CPU1_SB_DQ<16>")
	)
	(segment
		(start 203.74356 -299.9232)
		(end 203.906628 -299.760132)
		(width 0.14478)
		(layer "In11.Cu")
		(net "M_L_CPU1_SB_DQ<16>")
	)
	(segment
		(start 205.019656 -299.760132)
		(end 205.822804 -299.760132)
		(width 0.14478)
		(layer "In11.Cu")
		(net "M_L_CPU1_SB_DQ<16>")
	)
	(segment
		(start 146.312636 -284.179772)
		(end 146.87169 -284.738826)
		(width 0.0889)
		(layer "In11.Cu")
		(net "M_L_CPU1_SB_DQ<16>")
	)
	(segment
		(start 204.137006 -299.760132)
		(end 204.300074 -299.9232)
		(width 0.14478)
		(layer "In11.Cu")
		(net "M_L_CPU1_SB_DQ<16>")
	)
	(segment
		(start 192.771776 -299.760386)
		(end 193.621406 -300.610016)
		(width 0.14478)
		(layer "In11.Cu")
		(net "M_L_CPU1_SB_DQ<16>")
	)
	(segment
		(start 188.874908 -300.61027)
		(end 189.724792 -299.760386)
		(width 0.14478)
		(layer "In11.Cu")
		(net "M_L_CPU1_SB_DQ<16>")
	)
	(segment
		(start 173.7868 -300.61027)
		(end 174.636684 -299.760386)
		(width 0.14478)
		(layer "In11.Cu")
		(net "M_L_CPU1_SB_DQ<16>")
	)
	(segment
		(start 196.449442 -300.610016)
		(end 197.299326 -299.760132)
		(width 0.14478)
		(layer "In11.Cu")
		(net "M_L_CPU1_SB_DQ<16>")
	)
	(segment
		(start 181.330854 -300.61027)
		(end 182.180738 -299.760386)
		(width 0.14478)
		(layer "In11.Cu")
		(net "M_L_CPU1_SB_DQ<16>")
	)
	(segment
		(start 203.187046 -300.640496)
		(end 203.350114 -300.803564)
		(width 0.14478)
		(layer "In11.Cu")
		(net "M_L_CPU1_SB_DQ<16>")
	)
	(segment
		(start 186.055254 -300.61027)
		(end 188.874908 -300.61027)
		(width 0.14478)
		(layer "In11.Cu")
		(net "M_L_CPU1_SB_DQ<16>")
	)
	(segment
		(start 185.20537 -299.760386)
		(end 186.055254 -300.61027)
		(width 0.14478)
		(layer "In11.Cu")
		(net "M_L_CPU1_SB_DQ<16>")
	)
	(segment
		(start 174.636684 -299.760386)
		(end 177.661316 -299.760386)
		(width 0.14478)
		(layer "In11.Cu")
		(net "M_L_CPU1_SB_DQ<16>")
	)
	(segment
		(start 204.69352 -300.803564)
		(end 204.856588 -300.640496)
		(width 0.14478)
		(layer "In11.Cu")
		(net "M_L_CPU1_SB_DQ<16>")
	)
	(segment
		(start 204.300074 -300.640496)
		(end 204.463142 -300.803564)
		(width 0.14478)
		(layer "In11.Cu")
		(net "M_L_CPU1_SB_DQ<16>")
	)
	(segment
		(start 139.650724 -284.071822)
		(end 139.673076 -284.155134)
		(width 0.0889)
		(layer "In11.Cu")
		(net "M_L_CPU1_SB_DQ<16>")
	)
	(segment
		(start 167.092884 -299.760132)
		(end 170.117008 -299.760132)
		(width 0.14478)
		(layer "In11.Cu")
		(net "M_L_CPU1_SB_DQ<16>")
	)
	(segment
		(start 139.804648 -283.806392)
		(end 139.650724 -284.071822)
		(width 0.0889)
		(layer "In11.Cu")
		(net "M_L_CPU1_SB_DQ<16>")
	)
	(segment
		(start 205.822804 -299.760132)
		(end 206.248 -300.185328)
		(width 0.14478)
		(layer "In11.Cu")
		(net "M_L_CPU1_SB_DQ<16>")
	)
	(segment
		(start 145.444718 -284.179772)
		(end 146.312636 -284.179772)
		(width 0.0889)
		(layer "In11.Cu")
		(net "M_L_CPU1_SB_DQ<16>")
	)
	(segment
		(start 162.21329 -300.61027)
		(end 166.242746 -300.61027)
		(width 0.14478)
		(layer "In11.Cu")
		(net "M_L_CPU1_SB_DQ<16>")
	)
	(segment
		(start 204.856588 -299.9232)
		(end 205.019656 -299.760132)
		(width 0.14478)
		(layer "In11.Cu")
		(net "M_L_CPU1_SB_DQ<16>")
	)
	(segment
		(start 140.557758 -284.128972)
		(end 140.56614 -284.133798)
		(width 0.0889)
		(layer "In11.Cu")
		(net "M_L_CPU1_SB_DQ<16>")
	)
	(segment
		(start 203.906628 -299.760132)
		(end 204.137006 -299.760132)
		(width 0.14478)
		(layer "In11.Cu")
		(net "M_L_CPU1_SB_DQ<16>")
	)
	(segment
		(start 203.187046 -299.9232)
		(end 203.187046 -300.640496)
		(width 0.14478)
		(layer "In11.Cu")
		(net "M_L_CPU1_SB_DQ<16>")
	)
	(segment
		(start 166.242746 -300.61027)
		(end 167.092884 -299.760132)
		(width 0.14478)
		(layer "In11.Cu")
		(net "M_L_CPU1_SB_DQ<16>")
	)
	(segment
		(start 178.5112 -300.61027)
		(end 181.330854 -300.61027)
		(width 0.14478)
		(layer "In11.Cu")
		(net "M_L_CPU1_SB_DQ<16>")
	)
	(segment
		(start 144.690592 -284.128972)
		(end 144.708626 -284.118304)
		(width 0.0889)
		(layer "In11.Cu")
		(net "M_L_CPU1_SB_DQ<16>")
	)
	(segment
		(start 156.009848 -291.696394)
		(end 156.009848 -294.406828)
		(width 0.14478)
		(layer "In11.Cu")
		(net "M_L_CPU1_SB_DQ<16>")
	)
	(segment
		(start 146.87169 -284.738826)
		(end 147.30095 -284.738826)
		(width 0.0889)
		(layer "In11.Cu")
		(net "M_L_CPU1_SB_DQ<16>")
	)
	(segment
		(start 189.724792 -299.760386)
		(end 192.771776 -299.760386)
		(width 0.14478)
		(layer "In11.Cu")
		(net "M_L_CPU1_SB_DQ<16>")
	)
	(segment
		(start 148.927058 -284.613604)
		(end 156.009848 -291.696394)
		(width 0.14478)
		(layer "In11.Cu")
		(net "M_L_CPU1_SB_DQ<16>")
	)
	(segment
		(start 203.580492 -300.803564)
		(end 203.74356 -300.640496)
		(width 0.14478)
		(layer "In11.Cu")
		(net "M_L_CPU1_SB_DQ<16>")
	)
	(segment
		(start 156.009848 -294.406828)
		(end 162.21329 -300.61027)
		(width 0.14478)
		(layer "In11.Cu")
		(net "M_L_CPU1_SB_DQ<16>")
	)
	(segment
		(start 144.30502 -284.12186)
		(end 144.316958 -284.128718)
		(width 0.0889)
		(layer "In11.Cu")
		(net "M_L_CPU1_SB_DQ<16>")
	)
	(segment
		(start 147.426172 -284.613604)
		(end 147.876768 -284.613604)
		(width 0.0889)
		(layer "In11.Cu")
		(net "M_L_CPU1_SB_DQ<16>")
	)
	(segment
		(start 197.299326 -299.760132)
		(end 203.023978 -299.760132)
		(width 0.14478)
		(layer "In11.Cu")
		(net "M_L_CPU1_SB_DQ<16>")
	)
	(segment
		(start 177.661316 -299.760386)
		(end 178.5112 -300.61027)
		(width 0.14478)
		(layer "In11.Cu")
		(net "M_L_CPU1_SB_DQ<16>")
	)
	(segment
		(start 204.463142 -300.803564)
		(end 204.69352 -300.803564)
		(width 0.14478)
		(layer "In11.Cu")
		(net "M_L_CPU1_SB_DQ<16>")
	)
	(segment
		(start 170.967146 -300.61027)
		(end 173.7868 -300.61027)
		(width 0.14478)
		(layer "In11.Cu")
		(net "M_L_CPU1_SB_DQ<16>")
	)
	(segment
		(start 147.876768 -284.613604)
		(end 148.927058 -284.613604)
		(width 0.14478)
		(layer "In11.Cu")
		(net "M_L_CPU1_SB_DQ<16>")
	)
	(segment
		(start 204.856588 -300.640496)
		(end 204.856588 -299.9232)
		(width 0.14478)
		(layer "In11.Cu")
		(net "M_L_CPU1_SB_DQ<16>")
	)
	(segment
		(start 193.621406 -300.610016)
		(end 196.449442 -300.610016)
		(width 0.14478)
		(layer "In11.Cu")
		(net "M_L_CPU1_SB_DQ<16>")
	)
	(segment
		(start 144.316958 -284.128718)
		(end 144.330674 -284.136592)
		(width 0.0889)
		(layer "In11.Cu")
		(net "M_L_CPU1_SB_DQ<16>")
	)
	(segment
		(start 203.023978 -299.760132)
		(end 203.187046 -299.9232)
		(width 0.14478)
		(layer "In11.Cu")
		(net "M_L_CPU1_SB_DQ<16>")
	)
	(segment
		(start 147.30095 -284.738826)
		(end 147.426172 -284.613604)
		(width 0.0889)
		(layer "In11.Cu")
		(net "M_L_CPU1_SB_DQ<16>")
	)
	(segment
		(start 203.350114 -300.803564)
		(end 203.580492 -300.803564)
		(width 0.14478)
		(layer "In11.Cu")
		(net "M_L_CPU1_SB_DQ<16>")
	)
	(segment
		(start 170.117008 -299.760132)
		(end 170.967146 -300.61027)
		(width 0.14478)
		(layer "In11.Cu")
		(net "M_L_CPU1_SB_DQ<16>")
	)
	(segment
		(start 143.377666 -284.128972)
		(end 143.386048 -284.133798)
		(width 0.0889)
		(layer "In11.Cu")
		(net "M_L_CPU1_SB_DQ<16>")
	)
	(segment
		(start 203.74356 -300.640496)
		(end 203.74356 -299.9232)
		(width 0.14478)
		(layer "In11.Cu")
		(net "M_L_CPU1_SB_DQ<16>")
	)
	(segment
		(start 182.180738 -299.760386)
		(end 185.20537 -299.760386)
		(width 0.14478)
		(layer "In11.Cu")
		(net "M_L_CPU1_SB_DQ<16>")
	)
	(arc
		(start 144.330674 -284.136592)
		(mid 144.511604 -284.17907)
		(end 144.690592 -284.128972)
		(width 0.0889)
		(layer "In11.Cu")
		(net "M_L_CPU1_SB_DQ<16>")
	)
	(arc
		(start 139.991846 -284.128972)
		(mid 140.274802 -284.052795)
		(end 140.557758 -284.128972)
		(width 0.0889)
		(layer "In11.Cu")
		(net "M_L_CPU1_SB_DQ<16>")
	)
	(arc
		(start 140.9319 -284.128972)
		(mid 141.214856 -284.052795)
		(end 141.497812 -284.128972)
		(width 0.0889)
		(layer "In11.Cu")
		(net "M_L_CPU1_SB_DQ<16>")
	)
	(arc
		(start 142.811754 -284.128972)
		(mid 143.09471 -284.052795)
		(end 143.377666 -284.128972)
		(width 0.0889)
		(layer "In11.Cu")
		(net "M_L_CPU1_SB_DQ<16>")
	)
	(arc
		(start 143.751808 -284.128972)
		(mid 144.027486 -284.052842)
		(end 144.30502 -284.12186)
		(width 0.0889)
		(layer "In11.Cu")
		(net "M_L_CPU1_SB_DQ<16>")
	)
	(arc
		(start 141.497812 -284.128972)
		(mid 141.684756 -284.179227)
		(end 141.8717 -284.128972)
		(width 0.0889)
		(layer "In11.Cu")
		(net "M_L_CPU1_SB_DQ<16>")
	)
	(arc
		(start 145.257266 -284.128972)
		(mid 145.347629 -284.166782)
		(end 145.444718 -284.179772)
		(width 0.0889)
		(layer "In11.Cu")
		(net "M_L_CPU1_SB_DQ<16>")
	)
	(arc
		(start 143.386048 -284.133798)
		(mid 143.569556 -284.179292)
		(end 143.751808 -284.128972)
		(width 0.0889)
		(layer "In11.Cu")
		(net "M_L_CPU1_SB_DQ<16>")
	)
	(arc
		(start 141.8717 -284.128972)
		(mid 142.154656 -284.052795)
		(end 142.437612 -284.128972)
		(width 0.0889)
		(layer "In11.Cu")
		(net "M_L_CPU1_SB_DQ<16>")
	)
	(arc
		(start 140.56614 -284.133798)
		(mid 140.749648 -284.179292)
		(end 140.9319 -284.128972)
		(width 0.0889)
		(layer "In11.Cu")
		(net "M_L_CPU1_SB_DQ<16>")
	)
	(arc
		(start 139.673076 -284.155134)
		(mid 139.835408 -284.177952)
		(end 139.991846 -284.128972)
		(width 0.0889)
		(layer "In11.Cu")
		(net "M_L_CPU1_SB_DQ<16>")
	)
	(arc
		(start 144.708626 -284.118304)
		(mid 144.984321 -284.052461)
		(end 145.257266 -284.128972)
		(width 0.0889)
		(layer "In11.Cu")
		(net "M_L_CPU1_SB_DQ<16>")
	)
	(arc
		(start 142.437612 -284.128972)
		(mid 142.619863 -284.179322)
		(end 142.803372 -284.133798)
		(width 0.0889)
		(layer "In11.Cu")
		(net "M_L_CPU1_SB_DQ<16>")
	)
	(segment
		(start 137.457942 -283.540454)
		(end 137.924794 -283.806392)
		(width 0.10668)
		(layer "F.Cu")
		(net "M_L_CPU1_SB_DQ<15>")
	)
	(segment
		(start 166.15029 -299.760386)
		(end 167.000428 -298.910248)
		(width 0.14478)
		(layer "In11.Cu")
		(net "M_L_CPU1_SB_DQ<15>")
	)
	(segment
		(start 160.650936 -298.0563)
		(end 160.834324 -297.872912)
		(width 0.14478)
		(layer "In11.Cu")
		(net "M_L_CPU1_SB_DQ<15>")
	)
	(segment
		(start 147.863814 -284.057344)
		(end 149.15769 -284.057344)
		(width 0.14478)
		(layer "In11.Cu")
		(net "M_L_CPU1_SB_DQ<15>")
	)
	(segment
		(start 197.266814 -298.910502)
		(end 199.277478 -298.910502)
		(width 0.14478)
		(layer "In11.Cu")
		(net "M_L_CPU1_SB_DQ<15>")
	)
	(segment
		(start 189.632082 -298.910502)
		(end 192.742058 -298.910502)
		(width 0.14478)
		(layer "In11.Cu")
		(net "M_L_CPU1_SB_DQ<15>")
	)
	(segment
		(start 178.576478 -299.76064)
		(end 181.23789 -299.76064)
		(width 0.14478)
		(layer "In11.Cu")
		(net "M_L_CPU1_SB_DQ<15>")
	)
	(segment
		(start 164.549074 -299.508164)
		(end 164.801296 -299.760386)
		(width 0.14478)
		(layer "In11.Cu")
		(net "M_L_CPU1_SB_DQ<15>")
	)
	(segment
		(start 188.781944 -299.76064)
		(end 189.632082 -298.910502)
		(width 0.14478)
		(layer "In11.Cu")
		(net "M_L_CPU1_SB_DQ<15>")
	)
	(segment
		(start 164.244782 -299.508164)
		(end 164.549074 -299.508164)
		(width 0.14478)
		(layer "In11.Cu")
		(net "M_L_CPU1_SB_DQ<15>")
	)
	(segment
		(start 161.04108 -298.651168)
		(end 161.2265 -298.836588)
		(width 0.14478)
		(layer "In11.Cu")
		(net "M_L_CPU1_SB_DQ<15>")
	)
	(segment
		(start 173.693836 -299.76064)
		(end 174.543974 -298.910502)
		(width 0.14478)
		(layer "In11.Cu")
		(net "M_L_CPU1_SB_DQ<15>")
	)
	(segment
		(start 140.557758 -283.483812)
		(end 140.56614 -283.478986)
		(width 0.0889)
		(layer "In11.Cu")
		(net "M_L_CPU1_SB_DQ<15>")
	)
	(segment
		(start 165.105588 -299.760386)
		(end 165.35781 -299.508164)
		(width 0.14478)
		(layer "In11.Cu")
		(net "M_L_CPU1_SB_DQ<15>")
	)
	(segment
		(start 145.236946 -283.496512)
		(end 145.258536 -283.484066)
		(width 0.0889)
		(layer "In11.Cu")
		(net "M_L_CPU1_SB_DQ<15>")
	)
	(segment
		(start 137.924794 -283.806392)
		(end 138.078718 -283.540962)
		(width 0.0889)
		(layer "In11.Cu")
		(net "M_L_CPU1_SB_DQ<15>")
	)
	(segment
		(start 165.662102 -299.508164)
		(end 165.914324 -299.760386)
		(width 0.14478)
		(layer "In11.Cu")
		(net "M_L_CPU1_SB_DQ<15>")
	)
	(segment
		(start 199.833992 -298.593764)
		(end 200.15073 -298.910502)
		(width 0.14478)
		(layer "In11.Cu")
		(net "M_L_CPU1_SB_DQ<15>")
	)
	(segment
		(start 160.446212 -298.0563)
		(end 160.650936 -298.0563)
		(width 0.14478)
		(layer "In11.Cu")
		(net "M_L_CPU1_SB_DQ<15>")
	)
	(segment
		(start 182.088028 -298.910502)
		(end 185.270394 -298.910502)
		(width 0.14478)
		(layer "In11.Cu")
		(net "M_L_CPU1_SB_DQ<15>")
	)
	(segment
		(start 161.039048 -297.872912)
		(end 161.224468 -298.058332)
		(width 0.14478)
		(layer "In11.Cu")
		(net "M_L_CPU1_SB_DQ<15>")
	)
	(segment
		(start 139.617704 -283.483812)
		(end 139.626086 -283.478986)
		(width 0.0889)
		(layer "In11.Cu")
		(net "M_L_CPU1_SB_DQ<15>")
	)
	(segment
		(start 145.444718 -283.433774)
		(end 146.33829 -283.433774)
		(width 0.0889)
		(layer "In11.Cu")
		(net "M_L_CPU1_SB_DQ<15>")
	)
	(segment
		(start 174.543974 -298.910502)
		(end 177.72634 -298.910502)
		(width 0.14478)
		(layer "In11.Cu")
		(net "M_L_CPU1_SB_DQ<15>")
	)
	(segment
		(start 164.801296 -299.760386)
		(end 165.105588 -299.760386)
		(width 0.14478)
		(layer "In11.Cu")
		(net "M_L_CPU1_SB_DQ<15>")
	)
	(segment
		(start 161.04108 -298.446444)
		(end 161.04108 -298.651168)
		(width 0.14478)
		(layer "In11.Cu")
		(net "M_L_CPU1_SB_DQ<15>")
	)
	(segment
		(start 200.15073 -298.910502)
		(end 200.390506 -298.910502)
		(width 0.14478)
		(layer "In11.Cu")
		(net "M_L_CPU1_SB_DQ<15>")
	)
	(segment
		(start 177.72634 -298.910502)
		(end 178.576478 -299.76064)
		(width 0.14478)
		(layer "In11.Cu")
		(net "M_L_CPU1_SB_DQ<15>")
	)
	(segment
		(start 171.032678 -299.76064)
		(end 173.693836 -299.76064)
		(width 0.14478)
		(layer "In11.Cu")
		(net "M_L_CPU1_SB_DQ<15>")
	)
	(segment
		(start 161.614612 -298.6532)
		(end 161.819336 -298.6532)
		(width 0.14478)
		(layer "In11.Cu")
		(net "M_L_CPU1_SB_DQ<15>")
	)
	(segment
		(start 165.35781 -299.508164)
		(end 165.662102 -299.508164)
		(width 0.14478)
		(layer "In11.Cu")
		(net "M_L_CPU1_SB_DQ<15>")
	)
	(segment
		(start 162.53206 -299.760386)
		(end 162.82416 -299.468286)
		(width 0.14478)
		(layer "In11.Cu")
		(net "M_L_CPU1_SB_DQ<15>")
	)
	(segment
		(start 185.270394 -298.910502)
		(end 186.120532 -299.76064)
		(width 0.14478)
		(layer "In11.Cu")
		(net "M_L_CPU1_SB_DQ<15>")
	)
	(segment
		(start 163.48837 -299.760386)
		(end 163.99256 -299.760386)
		(width 0.14478)
		(layer "In11.Cu")
		(net "M_L_CPU1_SB_DQ<15>")
	)
	(segment
		(start 199.594216 -298.593764)
		(end 199.833992 -298.593764)
		(width 0.14478)
		(layer "In11.Cu")
		(net "M_L_CPU1_SB_DQ<15>")
	)
	(segment
		(start 196.417184 -299.760132)
		(end 197.266814 -298.910502)
		(width 0.14478)
		(layer "In11.Cu")
		(net "M_L_CPU1_SB_DQ<15>")
	)
	(segment
		(start 138.078718 -283.540962)
		(end 138.17473 -283.515562)
		(width 0.0889)
		(layer "In11.Cu")
		(net "M_L_CPU1_SB_DQ<15>")
	)
	(segment
		(start 149.15769 -284.057344)
		(end 156.566108 -291.465762)
		(width 0.14478)
		(layer "In11.Cu")
		(net "M_L_CPU1_SB_DQ<15>")
	)
	(segment
		(start 161.224468 -298.058332)
		(end 161.224468 -298.263056)
		(width 0.14478)
		(layer "In11.Cu")
		(net "M_L_CPU1_SB_DQ<15>")
	)
	(segment
		(start 192.742058 -298.910502)
		(end 193.591688 -299.760132)
		(width 0.14478)
		(layer "In11.Cu")
		(net "M_L_CPU1_SB_DQ<15>")
	)
	(segment
		(start 147.579588 -284.057344)
		(end 147.863814 -284.057344)
		(width 0.0889)
		(layer "In11.Cu")
		(net "M_L_CPU1_SB_DQ<15>")
	)
	(segment
		(start 156.566108 -294.176196)
		(end 160.446212 -298.0563)
		(width 0.14478)
		(layer "In11.Cu")
		(net "M_L_CPU1_SB_DQ<15>")
	)
	(segment
		(start 161.2265 -298.836588)
		(end 161.431224 -298.836588)
		(width 0.14478)
		(layer "In11.Cu")
		(net "M_L_CPU1_SB_DQ<15>")
	)
	(segment
		(start 143.377666 -283.483812)
		(end 143.386048 -283.478986)
		(width 0.0889)
		(layer "In11.Cu")
		(net "M_L_CPU1_SB_DQ<15>")
	)
	(segment
		(start 170.182286 -298.910248)
		(end 171.032678 -299.76064)
		(width 0.14478)
		(layer "In11.Cu")
		(net "M_L_CPU1_SB_DQ<15>")
	)
	(segment
		(start 163.19627 -299.468286)
		(end 163.48837 -299.760386)
		(width 0.14478)
		(layer "In11.Cu")
		(net "M_L_CPU1_SB_DQ<15>")
	)
	(segment
		(start 162.004756 -298.83862)
		(end 162.004756 -299.043344)
		(width 0.14478)
		(layer "In11.Cu")
		(net "M_L_CPU1_SB_DQ<15>")
	)
	(segment
		(start 162.004756 -299.043344)
		(end 161.821368 -299.226732)
		(width 0.14478)
		(layer "In11.Cu")
		(net "M_L_CPU1_SB_DQ<15>")
	)
	(segment
		(start 161.224468 -298.263056)
		(end 161.04108 -298.446444)
		(width 0.14478)
		(layer "In11.Cu")
		(net "M_L_CPU1_SB_DQ<15>")
	)
	(segment
		(start 161.431224 -298.836588)
		(end 161.614612 -298.6532)
		(width 0.14478)
		(layer "In11.Cu")
		(net "M_L_CPU1_SB_DQ<15>")
	)
	(segment
		(start 139.04341 -283.478986)
		(end 139.051792 -283.483812)
		(width 0.0889)
		(layer "In11.Cu")
		(net "M_L_CPU1_SB_DQ<15>")
	)
	(segment
		(start 181.23789 -299.76064)
		(end 182.088028 -298.910502)
		(width 0.14478)
		(layer "In11.Cu")
		(net "M_L_CPU1_SB_DQ<15>")
	)
	(segment
		(start 161.821368 -299.226732)
		(end 161.821368 -299.431456)
		(width 0.14478)
		(layer "In11.Cu")
		(net "M_L_CPU1_SB_DQ<15>")
	)
	(segment
		(start 161.821368 -299.431456)
		(end 162.150298 -299.760386)
		(width 0.14478)
		(layer "In11.Cu")
		(net "M_L_CPU1_SB_DQ<15>")
	)
	(segment
		(start 201.72299 -298.910502)
		(end 202.147932 -299.335444)
		(width 0.14478)
		(layer "In11.Cu")
		(net "M_L_CPU1_SB_DQ<15>")
	)
	(segment
		(start 165.914324 -299.760386)
		(end 166.15029 -299.760386)
		(width 0.14478)
		(layer "In11.Cu")
		(net "M_L_CPU1_SB_DQ<15>")
	)
	(segment
		(start 146.33829 -283.433774)
		(end 146.632422 -283.727906)
		(width 0.0889)
		(layer "In11.Cu")
		(net "M_L_CPU1_SB_DQ<15>")
	)
	(segment
		(start 156.566108 -291.465762)
		(end 156.566108 -294.176196)
		(width 0.14478)
		(layer "In11.Cu")
		(net "M_L_CPU1_SB_DQ<15>")
	)
	(segment
		(start 161.819336 -298.6532)
		(end 162.004756 -298.83862)
		(width 0.14478)
		(layer "In11.Cu")
		(net "M_L_CPU1_SB_DQ<15>")
	)
	(segment
		(start 142.803372 -283.478986)
		(end 142.811754 -283.483812)
		(width 0.0889)
		(layer "In11.Cu")
		(net "M_L_CPU1_SB_DQ<15>")
	)
	(segment
		(start 143.751808 -283.483812)
		(end 143.775176 -283.497528)
		(width 0.0889)
		(layer "In11.Cu")
		(net "M_L_CPU1_SB_DQ<15>")
	)
	(segment
		(start 162.150298 -299.760386)
		(end 162.53206 -299.760386)
		(width 0.14478)
		(layer "In11.Cu")
		(net "M_L_CPU1_SB_DQ<15>")
	)
	(segment
		(start 193.591688 -299.760132)
		(end 196.417184 -299.760132)
		(width 0.14478)
		(layer "In11.Cu")
		(net "M_L_CPU1_SB_DQ<15>")
	)
	(segment
		(start 146.632422 -283.727906)
		(end 147.25015 -283.727906)
		(width 0.0889)
		(layer "In11.Cu")
		(net "M_L_CPU1_SB_DQ<15>")
	)
	(segment
		(start 186.120532 -299.76064)
		(end 188.781944 -299.76064)
		(width 0.14478)
		(layer "In11.Cu")
		(net "M_L_CPU1_SB_DQ<15>")
	)
	(segment
		(start 162.82416 -299.468286)
		(end 163.19627 -299.468286)
		(width 0.14478)
		(layer "In11.Cu")
		(net "M_L_CPU1_SB_DQ<15>")
	)
	(segment
		(start 200.707244 -298.593764)
		(end 200.94702 -298.593764)
		(width 0.14478)
		(layer "In11.Cu")
		(net "M_L_CPU1_SB_DQ<15>")
	)
	(segment
		(start 147.25015 -283.727906)
		(end 147.579588 -284.057344)
		(width 0.0889)
		(layer "In11.Cu")
		(net "M_L_CPU1_SB_DQ<15>")
	)
	(segment
		(start 167.000428 -298.910248)
		(end 170.182286 -298.910248)
		(width 0.14478)
		(layer "In11.Cu")
		(net "M_L_CPU1_SB_DQ<15>")
	)
	(segment
		(start 200.390506 -298.910502)
		(end 200.707244 -298.593764)
		(width 0.14478)
		(layer "In11.Cu")
		(net "M_L_CPU1_SB_DQ<15>")
	)
	(segment
		(start 163.99256 -299.760386)
		(end 164.244782 -299.508164)
		(width 0.14478)
		(layer "In11.Cu")
		(net "M_L_CPU1_SB_DQ<15>")
	)
	(segment
		(start 199.277478 -298.910502)
		(end 199.594216 -298.593764)
		(width 0.14478)
		(layer "In11.Cu")
		(net "M_L_CPU1_SB_DQ<15>")
	)
	(segment
		(start 201.263758 -298.910502)
		(end 201.72299 -298.910502)
		(width 0.14478)
		(layer "In11.Cu")
		(net "M_L_CPU1_SB_DQ<15>")
	)
	(segment
		(start 144.67967 -283.47543)
		(end 144.694148 -283.483812)
		(width 0.0889)
		(layer "In11.Cu")
		(net "M_L_CPU1_SB_DQ<15>")
	)
	(segment
		(start 200.94702 -298.593764)
		(end 201.263758 -298.910502)
		(width 0.14478)
		(layer "In11.Cu")
		(net "M_L_CPU1_SB_DQ<15>")
	)
	(segment
		(start 160.834324 -297.872912)
		(end 161.039048 -297.872912)
		(width 0.14478)
		(layer "In11.Cu")
		(net "M_L_CPU1_SB_DQ<15>")
	)
	(arc
		(start 139.051792 -283.483812)
		(mid 139.334748 -283.559989)
		(end 139.617704 -283.483812)
		(width 0.0889)
		(layer "In11.Cu")
		(net "M_L_CPU1_SB_DQ<15>")
	)
	(arc
		(start 142.437612 -283.483812)
		(mid 142.619863 -283.433462)
		(end 142.803372 -283.478986)
		(width 0.0889)
		(layer "In11.Cu")
		(net "M_L_CPU1_SB_DQ<15>")
	)
	(arc
		(start 144.31899 -283.483812)
		(mid 144.498253 -283.433148)
		(end 144.67967 -283.47543)
		(width 0.0889)
		(layer "In11.Cu")
		(net "M_L_CPU1_SB_DQ<15>")
	)
	(arc
		(start 141.497812 -283.483812)
		(mid 141.684756 -283.433557)
		(end 141.8717 -283.483812)
		(width 0.0889)
		(layer "In11.Cu")
		(net "M_L_CPU1_SB_DQ<15>")
	)
	(arc
		(start 139.991846 -283.483812)
		(mid 140.274802 -283.559989)
		(end 140.557758 -283.483812)
		(width 0.0889)
		(layer "In11.Cu")
		(net "M_L_CPU1_SB_DQ<15>")
	)
	(arc
		(start 140.9319 -283.483812)
		(mid 141.214856 -283.559989)
		(end 141.497812 -283.483812)
		(width 0.0889)
		(layer "In11.Cu")
		(net "M_L_CPU1_SB_DQ<15>")
	)
	(arc
		(start 138.67765 -283.483812)
		(mid 138.859901 -283.433462)
		(end 139.04341 -283.478986)
		(width 0.0889)
		(layer "In11.Cu")
		(net "M_L_CPU1_SB_DQ<15>")
	)
	(arc
		(start 140.56614 -283.478986)
		(mid 140.749648 -283.433492)
		(end 140.9319 -283.483812)
		(width 0.0889)
		(layer "In11.Cu")
		(net "M_L_CPU1_SB_DQ<15>")
	)
	(arc
		(start 144.694148 -283.483812)
		(mid 144.963917 -283.559835)
		(end 145.236946 -283.496512)
		(width 0.0889)
		(layer "In11.Cu")
		(net "M_L_CPU1_SB_DQ<15>")
	)
	(arc
		(start 145.258536 -283.484066)
		(mid 145.348313 -283.446643)
		(end 145.444718 -283.433774)
		(width 0.0889)
		(layer "In11.Cu")
		(net "M_L_CPU1_SB_DQ<15>")
	)
	(arc
		(start 138.17473 -283.515562)
		(mid 138.429938 -283.559039)
		(end 138.67765 -283.483812)
		(width 0.0889)
		(layer "In11.Cu")
		(net "M_L_CPU1_SB_DQ<15>")
	)
	(arc
		(start 141.8717 -283.483812)
		(mid 142.154656 -283.559989)
		(end 142.437612 -283.483812)
		(width 0.0889)
		(layer "In11.Cu")
		(net "M_L_CPU1_SB_DQ<15>")
	)
	(arc
		(start 143.775176 -283.497528)
		(mid 144.04883 -283.560471)
		(end 144.31899 -283.483812)
		(width 0.0889)
		(layer "In11.Cu")
		(net "M_L_CPU1_SB_DQ<15>")
	)
	(arc
		(start 139.626086 -283.478986)
		(mid 139.809594 -283.433492)
		(end 139.991846 -283.483812)
		(width 0.0889)
		(layer "In11.Cu")
		(net "M_L_CPU1_SB_DQ<15>")
	)
	(arc
		(start 143.386048 -283.478986)
		(mid 143.569556 -283.433492)
		(end 143.751808 -283.483812)
		(width 0.0889)
		(layer "In11.Cu")
		(net "M_L_CPU1_SB_DQ<15>")
	)
	(arc
		(start 142.811754 -283.483812)
		(mid 143.09471 -283.559989)
		(end 143.377666 -283.483812)
		(width 0.0889)
		(layer "In11.Cu")
		(net "M_L_CPU1_SB_DQ<15>")
	)
	(segment
		(start 138.867896 -282.730448)
		(end 139.334748 -282.996386)
		(width 0.10668)
		(layer "F.Cu")
		(net "M_L_CPU1_SB_DQ<14>")
	)
	(segment
		(start 146.860768 -283.148024)
		(end 147.795234 -283.148024)
		(width 0.0889)
		(layer "In11.Cu")
		(net "M_L_CPU1_SB_DQ<14>")
	)
	(segment
		(start 157.475428 -292.56101)
		(end 158.137606 -293.223188)
		(width 0.14478)
		(layer "In11.Cu")
		(net "M_L_CPU1_SB_DQ<14>")
	)
	(segment
		(start 140.453364 -282.66898)
		(end 140.461746 -282.673806)
		(width 0.0889)
		(layer "In11.Cu")
		(net "M_L_CPU1_SB_DQ<14>")
	)
	(segment
		(start 158.761938 -293.84752)
		(end 158.925006 -294.010588)
		(width 0.14478)
		(layer "In11.Cu")
		(net "M_L_CPU1_SB_DQ<14>")
	)
	(segment
		(start 182.088028 -297.21048)
		(end 185.004202 -297.21048)
		(width 0.14478)
		(layer "In11.Cu")
		(net "M_L_CPU1_SB_DQ<14>")
	)
	(segment
		(start 160.499806 -295.585388)
		(end 160.499806 -295.81602)
		(width 0.14478)
		(layer "In11.Cu")
		(net "M_L_CPU1_SB_DQ<14>")
	)
	(segment
		(start 139.488672 -282.730956)
		(end 139.584684 -282.705556)
		(width 0.0889)
		(layer "In11.Cu")
		(net "M_L_CPU1_SB_DQ<14>")
	)
	(segment
		(start 157.74924 -294.072818)
		(end 157.912308 -294.235886)
		(width 0.14478)
		(layer "In11.Cu")
		(net "M_L_CPU1_SB_DQ<14>")
	)
	(segment
		(start 201.72299 -297.21048)
		(end 202.147932 -297.635422)
		(width 0.14478)
		(layer "In11.Cu")
		(net "M_L_CPU1_SB_DQ<14>")
	)
	(segment
		(start 166.123874 -298.060364)
		(end 166.974012 -297.210226)
		(width 0.14478)
		(layer "In11.Cu")
		(net "M_L_CPU1_SB_DQ<14>")
	)
	(segment
		(start 170.181778 -297.210226)
		(end 171.03217 -298.060618)
		(width 0.14478)
		(layer "In11.Cu")
		(net "M_L_CPU1_SB_DQ<14>")
	)
	(segment
		(start 158.925006 -294.010588)
		(end 158.925006 -294.24122)
		(width 0.14478)
		(layer "In11.Cu")
		(net "M_L_CPU1_SB_DQ<14>")
	)
	(segment
		(start 159.32404 -295.416986)
		(end 159.32404 -295.647618)
		(width 0.14478)
		(layer "In11.Cu")
		(net "M_L_CPU1_SB_DQ<14>")
	)
	(segment
		(start 160.106106 -295.42232)
		(end 160.336738 -295.42232)
		(width 0.14478)
		(layer "In11.Cu")
		(net "M_L_CPU1_SB_DQ<14>")
	)
	(segment
		(start 147.795234 -283.148024)
		(end 149.534626 -283.148024)
		(width 0.14478)
		(layer "In11.Cu")
		(net "M_L_CPU1_SB_DQ<14>")
	)
	(segment
		(start 158.14294 -294.235886)
		(end 158.531306 -293.84752)
		(width 0.14478)
		(layer "In11.Cu")
		(net "M_L_CPU1_SB_DQ<14>")
	)
	(segment
		(start 157.912308 -294.235886)
		(end 158.14294 -294.235886)
		(width 0.14478)
		(layer "In11.Cu")
		(net "M_L_CPU1_SB_DQ<14>")
	)
	(segment
		(start 185.004202 -297.21048)
		(end 185.85434 -298.060618)
		(width 0.14478)
		(layer "In11.Cu")
		(net "M_L_CPU1_SB_DQ<14>")
	)
	(segment
		(start 159.71774 -295.810686)
		(end 160.106106 -295.42232)
		(width 0.14478)
		(layer "In11.Cu")
		(net "M_L_CPU1_SB_DQ<14>")
	)
	(segment
		(start 141.967712 -282.673806)
		(end 141.976094 -282.66898)
		(width 0.0889)
		(layer "In11.Cu")
		(net "M_L_CPU1_SB_DQ<14>")
	)
	(segment
		(start 161.124138 -296.20972)
		(end 162.974782 -298.060364)
		(width 0.14478)
		(layer "In11.Cu")
		(net "M_L_CPU1_SB_DQ<14>")
	)
	(segment
		(start 192.540128 -297.21048)
		(end 193.390012 -298.060364)
		(width 0.14478)
		(layer "In11.Cu")
		(net "M_L_CPU1_SB_DQ<14>")
	)
	(segment
		(start 181.23789 -298.060618)
		(end 182.088028 -297.21048)
		(width 0.14478)
		(layer "In11.Cu")
		(net "M_L_CPU1_SB_DQ<14>")
	)
	(segment
		(start 157.475428 -291.088826)
		(end 157.475428 -292.56101)
		(width 0.14478)
		(layer "In11.Cu")
		(net "M_L_CPU1_SB_DQ<14>")
	)
	(segment
		(start 158.531306 -293.84752)
		(end 158.761938 -293.84752)
		(width 0.14478)
		(layer "In11.Cu")
		(net "M_L_CPU1_SB_DQ<14>")
	)
	(segment
		(start 160.336738 -295.42232)
		(end 160.499806 -295.585388)
		(width 0.14478)
		(layer "In11.Cu")
		(net "M_L_CPU1_SB_DQ<14>")
	)
	(segment
		(start 160.893506 -296.20972)
		(end 161.124138 -296.20972)
		(width 0.14478)
		(layer "In11.Cu")
		(net "M_L_CPU1_SB_DQ<14>")
	)
	(segment
		(start 144.786604 -282.673806)
		(end 144.798288 -282.666948)
		(width 0.0889)
		(layer "In11.Cu")
		(net "M_L_CPU1_SB_DQ<14>")
	)
	(segment
		(start 185.85434 -298.060618)
		(end 188.781944 -298.060618)
		(width 0.14478)
		(layer "In11.Cu")
		(net "M_L_CPU1_SB_DQ<14>")
	)
	(segment
		(start 189.632082 -297.21048)
		(end 192.540128 -297.21048)
		(width 0.14478)
		(layer "In11.Cu")
		(net "M_L_CPU1_SB_DQ<14>")
	)
	(segment
		(start 158.137606 -293.223188)
		(end 158.137606 -293.45382)
		(width 0.14478)
		(layer "In11.Cu")
		(net "M_L_CPU1_SB_DQ<14>")
	)
	(segment
		(start 144.221454 -282.67406)
		(end 144.233392 -282.680918)
		(width 0.0889)
		(layer "In11.Cu")
		(net "M_L_CPU1_SB_DQ<14>")
	)
	(segment
		(start 173.693836 -298.060618)
		(end 174.543974 -297.21048)
		(width 0.14478)
		(layer "In11.Cu")
		(net "M_L_CPU1_SB_DQ<14>")
	)
	(segment
		(start 157.74924 -293.842186)
		(end 157.74924 -294.072818)
		(width 0.14478)
		(layer "In11.Cu")
		(net "M_L_CPU1_SB_DQ<14>")
	)
	(segment
		(start 197.290436 -297.21048)
		(end 201.72299 -297.21048)
		(width 0.14478)
		(layer "In11.Cu")
		(net "M_L_CPU1_SB_DQ<14>")
	)
	(segment
		(start 139.334748 -282.996386)
		(end 139.488672 -282.730956)
		(width 0.0889)
		(layer "In11.Cu")
		(net "M_L_CPU1_SB_DQ<14>")
	)
	(segment
		(start 160.11144 -296.435018)
		(end 160.274508 -296.598086)
		(width 0.14478)
		(layer "In11.Cu")
		(net "M_L_CPU1_SB_DQ<14>")
	)
	(segment
		(start 144.205198 -282.664662)
		(end 144.221454 -282.67406)
		(width 0.0889)
		(layer "In11.Cu")
		(net "M_L_CPU1_SB_DQ<14>")
	)
	(segment
		(start 158.699708 -295.023286)
		(end 158.93034 -295.023286)
		(width 0.14478)
		(layer "In11.Cu")
		(net "M_L_CPU1_SB_DQ<14>")
	)
	(segment
		(start 171.03217 -298.060618)
		(end 173.693836 -298.060618)
		(width 0.14478)
		(layer "In11.Cu")
		(net "M_L_CPU1_SB_DQ<14>")
	)
	(segment
		(start 160.499806 -295.81602)
		(end 160.11144 -296.204386)
		(width 0.14478)
		(layer "In11.Cu")
		(net "M_L_CPU1_SB_DQ<14>")
	)
	(segment
		(start 159.318706 -294.63492)
		(end 159.549338 -294.63492)
		(width 0.14478)
		(layer "In11.Cu")
		(net "M_L_CPU1_SB_DQ<14>")
	)
	(segment
		(start 159.549338 -294.63492)
		(end 159.712406 -294.797988)
		(width 0.14478)
		(layer "In11.Cu")
		(net "M_L_CPU1_SB_DQ<14>")
	)
	(segment
		(start 158.53664 -294.629586)
		(end 158.53664 -294.860218)
		(width 0.14478)
		(layer "In11.Cu")
		(net "M_L_CPU1_SB_DQ<14>")
	)
	(segment
		(start 160.11144 -296.204386)
		(end 160.11144 -296.435018)
		(width 0.14478)
		(layer "In11.Cu")
		(net "M_L_CPU1_SB_DQ<14>")
	)
	(segment
		(start 162.974782 -298.060364)
		(end 166.123874 -298.060364)
		(width 0.14478)
		(layer "In11.Cu")
		(net "M_L_CPU1_SB_DQ<14>")
	)
	(segment
		(start 196.440552 -298.060364)
		(end 197.290436 -297.21048)
		(width 0.14478)
		(layer "In11.Cu")
		(net "M_L_CPU1_SB_DQ<14>")
	)
	(segment
		(start 159.712406 -295.02862)
		(end 159.32404 -295.416986)
		(width 0.14478)
		(layer "In11.Cu")
		(net "M_L_CPU1_SB_DQ<14>")
	)
	(segment
		(start 158.925006 -294.24122)
		(end 158.53664 -294.629586)
		(width 0.14478)
		(layer "In11.Cu")
		(net "M_L_CPU1_SB_DQ<14>")
	)
	(segment
		(start 146.463004 -282.75026)
		(end 146.860768 -283.148024)
		(width 0.0889)
		(layer "In11.Cu")
		(net "M_L_CPU1_SB_DQ<14>")
	)
	(segment
		(start 188.781944 -298.060618)
		(end 189.632082 -297.21048)
		(width 0.14478)
		(layer "In11.Cu")
		(net "M_L_CPU1_SB_DQ<14>")
	)
	(segment
		(start 159.712406 -294.797988)
		(end 159.712406 -295.02862)
		(width 0.14478)
		(layer "In11.Cu")
		(net "M_L_CPU1_SB_DQ<14>")
	)
	(segment
		(start 174.543974 -297.21048)
		(end 177.526188 -297.21048)
		(width 0.14478)
		(layer "In11.Cu")
		(net "M_L_CPU1_SB_DQ<14>")
	)
	(segment
		(start 166.974012 -297.210226)
		(end 170.181778 -297.210226)
		(width 0.14478)
		(layer "In11.Cu")
		(net "M_L_CPU1_SB_DQ<14>")
	)
	(segment
		(start 177.526188 -297.21048)
		(end 178.376326 -298.060618)
		(width 0.14478)
		(layer "In11.Cu")
		(net "M_L_CPU1_SB_DQ<14>")
	)
	(segment
		(start 160.50514 -296.598086)
		(end 160.893506 -296.20972)
		(width 0.14478)
		(layer "In11.Cu")
		(net "M_L_CPU1_SB_DQ<14>")
	)
	(segment
		(start 141.393418 -282.66898)
		(end 141.4018 -282.673806)
		(width 0.0889)
		(layer "In11.Cu")
		(net "M_L_CPU1_SB_DQ<14>")
	)
	(segment
		(start 178.376326 -298.060618)
		(end 181.23789 -298.060618)
		(width 0.14478)
		(layer "In11.Cu")
		(net "M_L_CPU1_SB_DQ<14>")
	)
	(segment
		(start 159.487108 -295.810686)
		(end 159.71774 -295.810686)
		(width 0.14478)
		(layer "In11.Cu")
		(net "M_L_CPU1_SB_DQ<14>")
	)
	(segment
		(start 145.444718 -282.75026)
		(end 146.463004 -282.75026)
		(width 0.0889)
		(layer "In11.Cu")
		(net "M_L_CPU1_SB_DQ<14>")
	)
	(segment
		(start 158.137606 -293.45382)
		(end 157.74924 -293.842186)
		(width 0.14478)
		(layer "In11.Cu")
		(net "M_L_CPU1_SB_DQ<14>")
	)
	(segment
		(start 159.32404 -295.647618)
		(end 159.487108 -295.810686)
		(width 0.14478)
		(layer "In11.Cu")
		(net "M_L_CPU1_SB_DQ<14>")
	)
	(segment
		(start 160.274508 -296.598086)
		(end 160.50514 -296.598086)
		(width 0.14478)
		(layer "In11.Cu")
		(net "M_L_CPU1_SB_DQ<14>")
	)
	(segment
		(start 193.390012 -298.060364)
		(end 196.440552 -298.060364)
		(width 0.14478)
		(layer "In11.Cu")
		(net "M_L_CPU1_SB_DQ<14>")
	)
	(segment
		(start 158.53664 -294.860218)
		(end 158.699708 -295.023286)
		(width 0.14478)
		(layer "In11.Cu")
		(net "M_L_CPU1_SB_DQ<14>")
	)
	(segment
		(start 158.93034 -295.023286)
		(end 159.318706 -294.63492)
		(width 0.14478)
		(layer "In11.Cu")
		(net "M_L_CPU1_SB_DQ<14>")
	)
	(segment
		(start 149.534626 -283.148024)
		(end 157.475428 -291.088826)
		(width 0.14478)
		(layer "In11.Cu")
		(net "M_L_CPU1_SB_DQ<14>")
	)
	(arc
		(start 144.233392 -282.680918)
		(mid 144.510926 -282.749899)
		(end 144.786604 -282.673806)
		(width 0.0889)
		(layer "In11.Cu")
		(net "M_L_CPU1_SB_DQ<14>")
	)
	(arc
		(start 143.847566 -282.673806)
		(mid 144.025216 -282.623546)
		(end 144.205198 -282.664662)
		(width 0.0889)
		(layer "In11.Cu")
		(net "M_L_CPU1_SB_DQ<14>")
	)
	(arc
		(start 144.798288 -282.666948)
		(mid 144.980543 -282.623295)
		(end 145.161 -282.673806)
		(width 0.0889)
		(layer "In11.Cu")
		(net "M_L_CPU1_SB_DQ<14>")
	)
	(arc
		(start 145.161 -282.673806)
		(mid 145.297793 -282.730828)
		(end 145.444718 -282.75026)
		(width 0.0889)
		(layer "In11.Cu")
		(net "M_L_CPU1_SB_DQ<14>")
	)
	(arc
		(start 141.4018 -282.673806)
		(mid 141.684756 -282.749983)
		(end 141.967712 -282.673806)
		(width 0.0889)
		(layer "In11.Cu")
		(net "M_L_CPU1_SB_DQ<14>")
	)
	(arc
		(start 142.341854 -282.673806)
		(mid 142.62481 -282.749983)
		(end 142.907766 -282.673806)
		(width 0.0889)
		(layer "In11.Cu")
		(net "M_L_CPU1_SB_DQ<14>")
	)
	(arc
		(start 140.461746 -282.673806)
		(mid 140.744702 -282.749983)
		(end 141.027658 -282.673806)
		(width 0.0889)
		(layer "In11.Cu")
		(net "M_L_CPU1_SB_DQ<14>")
	)
	(arc
		(start 143.281654 -282.673806)
		(mid 143.56461 -282.749983)
		(end 143.847566 -282.673806)
		(width 0.0889)
		(layer "In11.Cu")
		(net "M_L_CPU1_SB_DQ<14>")
	)
	(arc
		(start 141.976094 -282.66898)
		(mid 142.159602 -282.623486)
		(end 142.341854 -282.673806)
		(width 0.0889)
		(layer "In11.Cu")
		(net "M_L_CPU1_SB_DQ<14>")
	)
	(arc
		(start 141.027658 -282.673806)
		(mid 141.209909 -282.623456)
		(end 141.393418 -282.66898)
		(width 0.0889)
		(layer "In11.Cu")
		(net "M_L_CPU1_SB_DQ<14>")
	)
	(arc
		(start 140.087604 -282.673806)
		(mid 140.269855 -282.623456)
		(end 140.453364 -282.66898)
		(width 0.0889)
		(layer "In11.Cu")
		(net "M_L_CPU1_SB_DQ<14>")
	)
	(arc
		(start 142.907766 -282.673806)
		(mid 143.09471 -282.623551)
		(end 143.281654 -282.673806)
		(width 0.0889)
		(layer "In11.Cu")
		(net "M_L_CPU1_SB_DQ<14>")
	)
	(arc
		(start 139.584684 -282.705556)
		(mid 139.839892 -282.749033)
		(end 140.087604 -282.673806)
		(width 0.0889)
		(layer "In11.Cu")
		(net "M_L_CPU1_SB_DQ<14>")
	)
	(segment
		(start 137.927842 -282.730448)
		(end 138.394694 -282.996386)
		(width 0.10668)
		(layer "F.Cu")
		(net "M_L_CPU1_SB_DQ<13>")
	)
	(segment
		(start 170.967146 -298.910502)
		(end 173.7868 -298.910502)
		(width 0.14478)
		(layer "In11.Cu")
		(net "M_L_CPU1_SB_DQ<13>")
	)
	(segment
		(start 147.582128 -283.602684)
		(end 147.898104 -283.602684)
		(width 0.0889)
		(layer "In11.Cu")
		(net "M_L_CPU1_SB_DQ<13>")
	)
	(segment
		(start 146.72945 -283.412946)
		(end 147.39239 -283.412946)
		(width 0.0889)
		(layer "In11.Cu")
		(net "M_L_CPU1_SB_DQ<13>")
	)
	(segment
		(start 146.559778 -283.243274)
		(end 146.72945 -283.412946)
		(width 0.0889)
		(layer "In11.Cu")
		(net "M_L_CPU1_SB_DQ<13>")
	)
	(segment
		(start 190.249048 -298.060618)
		(end 192.197228 -298.060618)
		(width 0.14478)
		(layer "In11.Cu")
		(net "M_L_CPU1_SB_DQ<13>")
	)
	(segment
		(start 167.86479 -298.06011)
		(end 170.116754 -298.06011)
		(width 0.14478)
		(layer "In11.Cu")
		(net "M_L_CPU1_SB_DQ<13>")
	)
	(segment
		(start 173.7868 -298.910502)
		(end 174.636684 -298.060618)
		(width 0.14478)
		(layer "In11.Cu")
		(net "M_L_CPU1_SB_DQ<13>")
	)
	(segment
		(start 192.197228 -298.060618)
		(end 194.248532 -298.910248)
		(width 0.14478)
		(layer "In11.Cu")
		(net "M_L_CPU1_SB_DQ<13>")
	)
	(segment
		(start 157.020768 -291.277294)
		(end 157.020768 -293.987728)
		(width 0.14478)
		(layer "In11.Cu")
		(net "M_L_CPU1_SB_DQ<13>")
	)
	(segment
		(start 145.444464 -283.243274)
		(end 146.559778 -283.243274)
		(width 0.0889)
		(layer "In11.Cu")
		(net "M_L_CPU1_SB_DQ<13>")
	)
	(segment
		(start 143.847566 -283.318966)
		(end 143.862044 -283.327348)
		(width 0.0889)
		(layer "In11.Cu")
		(net "M_L_CPU1_SB_DQ<13>")
	)
	(segment
		(start 141.393418 -283.323792)
		(end 141.4018 -283.318966)
		(width 0.0889)
		(layer "In11.Cu")
		(net "M_L_CPU1_SB_DQ<13>")
	)
	(segment
		(start 161.288476 -297.224958)
		(end 162.973766 -298.910248)
		(width 0.14478)
		(layer "In11.Cu")
		(net "M_L_CPU1_SB_DQ<13>")
	)
	(segment
		(start 177.661316 -298.060618)
		(end 178.5112 -298.910502)
		(width 0.14478)
		(layer "In11.Cu")
		(net "M_L_CPU1_SB_DQ<13>")
	)
	(segment
		(start 138.24077 -283.261816)
		(end 138.263122 -283.345128)
		(width 0.0889)
		(layer "In11.Cu")
		(net "M_L_CPU1_SB_DQ<13>")
	)
	(segment
		(start 138.394694 -282.996386)
		(end 138.24077 -283.261816)
		(width 0.0889)
		(layer "In11.Cu")
		(net "M_L_CPU1_SB_DQ<13>")
	)
	(segment
		(start 204.111606 -298.060364)
		(end 206.248 -298.485306)
		(width 0.14478)
		(layer "In11.Cu")
		(net "M_L_CPU1_SB_DQ<13>")
	)
	(segment
		(start 147.898104 -283.602684)
		(end 149.346158 -283.602684)
		(width 0.14478)
		(layer "In11.Cu")
		(net "M_L_CPU1_SB_DQ<13>")
	)
	(segment
		(start 170.116754 -298.06011)
		(end 170.967146 -298.910502)
		(width 0.14478)
		(layer "In11.Cu")
		(net "M_L_CPU1_SB_DQ<13>")
	)
	(segment
		(start 188.197236 -298.910502)
		(end 190.249048 -298.060618)
		(width 0.14478)
		(layer "In11.Cu")
		(net "M_L_CPU1_SB_DQ<13>")
	)
	(segment
		(start 178.5112 -298.910502)
		(end 180.748686 -298.910502)
		(width 0.14478)
		(layer "In11.Cu")
		(net "M_L_CPU1_SB_DQ<13>")
	)
	(segment
		(start 144.766538 -283.30525)
		(end 144.789906 -283.318966)
		(width 0.0889)
		(layer "In11.Cu")
		(net "M_L_CPU1_SB_DQ<13>")
	)
	(segment
		(start 197.885304 -298.060364)
		(end 204.111606 -298.060364)
		(width 0.14478)
		(layer "In11.Cu")
		(net "M_L_CPU1_SB_DQ<13>")
	)
	(segment
		(start 160.257998 -297.224958)
		(end 161.288476 -297.224958)
		(width 0.14478)
		(layer "In11.Cu")
		(net "M_L_CPU1_SB_DQ<13>")
	)
	(segment
		(start 140.453364 -283.323792)
		(end 140.461746 -283.318966)
		(width 0.0889)
		(layer "In11.Cu")
		(net "M_L_CPU1_SB_DQ<13>")
	)
	(segment
		(start 147.39239 -283.412946)
		(end 147.582128 -283.602684)
		(width 0.0889)
		(layer "In11.Cu")
		(net "M_L_CPU1_SB_DQ<13>")
	)
	(segment
		(start 157.020768 -293.987728)
		(end 160.257998 -297.224958)
		(width 0.14478)
		(layer "In11.Cu")
		(net "M_L_CPU1_SB_DQ<13>")
	)
	(segment
		(start 162.973766 -298.910248)
		(end 165.811708 -298.910248)
		(width 0.14478)
		(layer "In11.Cu")
		(net "M_L_CPU1_SB_DQ<13>")
	)
	(segment
		(start 195.833492 -298.910248)
		(end 197.885304 -298.060364)
		(width 0.14478)
		(layer "In11.Cu")
		(net "M_L_CPU1_SB_DQ<13>")
	)
	(segment
		(start 145.14322 -283.330142)
		(end 145.163286 -283.318712)
		(width 0.0889)
		(layer "In11.Cu")
		(net "M_L_CPU1_SB_DQ<13>")
	)
	(segment
		(start 194.248532 -298.910248)
		(end 195.833492 -298.910248)
		(width 0.14478)
		(layer "In11.Cu")
		(net "M_L_CPU1_SB_DQ<13>")
	)
	(segment
		(start 141.967712 -283.318966)
		(end 141.976094 -283.323792)
		(width 0.0889)
		(layer "In11.Cu")
		(net "M_L_CPU1_SB_DQ<13>")
	)
	(segment
		(start 186.559698 -298.910502)
		(end 188.197236 -298.910502)
		(width 0.14478)
		(layer "In11.Cu")
		(net "M_L_CPU1_SB_DQ<13>")
	)
	(segment
		(start 149.346158 -283.602684)
		(end 157.020768 -291.277294)
		(width 0.14478)
		(layer "In11.Cu")
		(net "M_L_CPU1_SB_DQ<13>")
	)
	(segment
		(start 184.507886 -298.060618)
		(end 186.559698 -298.910502)
		(width 0.14478)
		(layer "In11.Cu")
		(net "M_L_CPU1_SB_DQ<13>")
	)
	(segment
		(start 182.800498 -298.060618)
		(end 184.507886 -298.060618)
		(width 0.14478)
		(layer "In11.Cu")
		(net "M_L_CPU1_SB_DQ<13>")
	)
	(segment
		(start 165.811708 -298.910248)
		(end 167.86479 -298.06011)
		(width 0.14478)
		(layer "In11.Cu")
		(net "M_L_CPU1_SB_DQ<13>")
	)
	(segment
		(start 180.748686 -298.910502)
		(end 182.800498 -298.060618)
		(width 0.14478)
		(layer "In11.Cu")
		(net "M_L_CPU1_SB_DQ<13>")
	)
	(segment
		(start 174.636684 -298.060618)
		(end 177.661316 -298.060618)
		(width 0.14478)
		(layer "In11.Cu")
		(net "M_L_CPU1_SB_DQ<13>")
	)
	(arc
		(start 143.862044 -283.327348)
		(mid 144.04346 -283.369605)
		(end 144.222724 -283.318966)
		(width 0.0889)
		(layer "In11.Cu")
		(net "M_L_CPU1_SB_DQ<13>")
	)
	(arc
		(start 145.163286 -283.318712)
		(mid 145.298919 -283.262537)
		(end 145.444464 -283.243274)
		(width 0.0889)
		(layer "In11.Cu")
		(net "M_L_CPU1_SB_DQ<13>")
	)
	(arc
		(start 139.521692 -283.318966)
		(mid 139.804648 -283.242789)
		(end 140.087604 -283.318966)
		(width 0.0889)
		(layer "In11.Cu")
		(net "M_L_CPU1_SB_DQ<13>")
	)
	(arc
		(start 142.907766 -283.318966)
		(mid 143.09471 -283.369221)
		(end 143.281654 -283.318966)
		(width 0.0889)
		(layer "In11.Cu")
		(net "M_L_CPU1_SB_DQ<13>")
	)
	(arc
		(start 141.976094 -283.323792)
		(mid 142.159602 -283.369286)
		(end 142.341854 -283.318966)
		(width 0.0889)
		(layer "In11.Cu")
		(net "M_L_CPU1_SB_DQ<13>")
	)
	(arc
		(start 140.461746 -283.318966)
		(mid 140.744702 -283.242789)
		(end 141.027658 -283.318966)
		(width 0.0889)
		(layer "In11.Cu")
		(net "M_L_CPU1_SB_DQ<13>")
	)
	(arc
		(start 138.581892 -283.318966)
		(mid 138.864848 -283.242789)
		(end 139.147804 -283.318966)
		(width 0.0889)
		(layer "In11.Cu")
		(net "M_L_CPU1_SB_DQ<13>")
	)
	(arc
		(start 143.281654 -283.318966)
		(mid 143.56461 -283.242789)
		(end 143.847566 -283.318966)
		(width 0.0889)
		(layer "In11.Cu")
		(net "M_L_CPU1_SB_DQ<13>")
	)
	(arc
		(start 144.789906 -283.318966)
		(mid 144.965145 -283.369037)
		(end 145.14322 -283.330142)
		(width 0.0889)
		(layer "In11.Cu")
		(net "M_L_CPU1_SB_DQ<13>")
	)
	(arc
		(start 138.263122 -283.345128)
		(mid 138.425454 -283.367946)
		(end 138.581892 -283.318966)
		(width 0.0889)
		(layer "In11.Cu")
		(net "M_L_CPU1_SB_DQ<13>")
	)
	(arc
		(start 141.027658 -283.318966)
		(mid 141.209909 -283.369316)
		(end 141.393418 -283.323792)
		(width 0.0889)
		(layer "In11.Cu")
		(net "M_L_CPU1_SB_DQ<13>")
	)
	(arc
		(start 142.341854 -283.318966)
		(mid 142.62481 -283.242789)
		(end 142.907766 -283.318966)
		(width 0.0889)
		(layer "In11.Cu")
		(net "M_L_CPU1_SB_DQ<13>")
	)
	(arc
		(start 139.147804 -283.318966)
		(mid 139.334748 -283.369221)
		(end 139.521692 -283.318966)
		(width 0.0889)
		(layer "In11.Cu")
		(net "M_L_CPU1_SB_DQ<13>")
	)
	(arc
		(start 140.087604 -283.318966)
		(mid 140.269855 -283.369316)
		(end 140.453364 -283.323792)
		(width 0.0889)
		(layer "In11.Cu")
		(net "M_L_CPU1_SB_DQ<13>")
	)
	(arc
		(start 141.4018 -283.318966)
		(mid 141.684756 -283.242789)
		(end 141.967712 -283.318966)
		(width 0.0889)
		(layer "In11.Cu")
		(net "M_L_CPU1_SB_DQ<13>")
	)
	(arc
		(start 144.222724 -283.318966)
		(mid 144.492881 -283.242204)
		(end 144.766538 -283.30525)
		(width 0.0889)
		(layer "In11.Cu")
		(net "M_L_CPU1_SB_DQ<13>")
	)
	(segment
		(start 139.337796 -281.920442)
		(end 139.804648 -282.18638)
		(width 0.10668)
		(layer "F.Cu")
		(net "M_L_CPU1_SB_DQ<12>")
	)
	(segment
		(start 192.522602 -296.369994)
		(end 193.372486 -297.219878)
		(width 0.14478)
		(layer "In11.Cu")
		(net "M_L_CPU1_SB_DQ<12>")
	)
	(segment
		(start 143.377666 -282.50896)
		(end 143.386048 -282.513786)
		(width 0.0889)
		(layer "In11.Cu")
		(net "M_L_CPU1_SB_DQ<12>")
	)
	(segment
		(start 147.852384 -282.693364)
		(end 149.723094 -282.693364)
		(width 0.14478)
		(layer "In11.Cu")
		(net "M_L_CPU1_SB_DQ<12>")
	)
	(segment
		(start 205.110588 -297.033696)
		(end 205.110588 -296.52341)
		(width 0.14478)
		(layer "In11.Cu")
		(net "M_L_CPU1_SB_DQ<12>")
	)
	(segment
		(start 204.94752 -297.196764)
		(end 205.110588 -297.033696)
		(width 0.14478)
		(layer "In11.Cu")
		(net "M_L_CPU1_SB_DQ<12>")
	)
	(segment
		(start 185.8137 -297.219878)
		(end 188.86551 -297.219878)
		(width 0.14478)
		(layer "In11.Cu")
		(net "M_L_CPU1_SB_DQ<12>")
	)
	(segment
		(start 147.25269 -282.353766)
		(end 147.592288 -282.693364)
		(width 0.0889)
		(layer "In11.Cu")
		(net "M_L_CPU1_SB_DQ<12>")
	)
	(segment
		(start 139.650724 -282.45181)
		(end 139.673076 -282.535122)
		(width 0.0889)
		(layer "In11.Cu")
		(net "M_L_CPU1_SB_DQ<12>")
	)
	(segment
		(start 189.715394 -296.369994)
		(end 192.522602 -296.369994)
		(width 0.14478)
		(layer "In11.Cu")
		(net "M_L_CPU1_SB_DQ<12>")
	)
	(segment
		(start 157.930088 -290.900358)
		(end 157.930088 -292.372542)
		(width 0.14478)
		(layer "In11.Cu")
		(net "M_L_CPU1_SB_DQ<12>")
	)
	(segment
		(start 162.768026 -297.21048)
		(end 166.242746 -297.21048)
		(width 0.14478)
		(layer "In11.Cu")
		(net "M_L_CPU1_SB_DQ<12>")
	)
	(segment
		(start 170.448732 -296.692066)
		(end 170.976544 -297.219878)
		(width 0.14478)
		(layer "In11.Cu")
		(net "M_L_CPU1_SB_DQ<12>")
	)
	(segment
		(start 144.316958 -282.508706)
		(end 144.330674 -282.51658)
		(width 0.0889)
		(layer "In11.Cu")
		(net "M_L_CPU1_SB_DQ<12>")
	)
	(segment
		(start 204.554074 -296.52341)
		(end 204.554074 -297.033696)
		(width 0.14478)
		(layer "In11.Cu")
		(net "M_L_CPU1_SB_DQ<12>")
	)
	(segment
		(start 147.592288 -282.693364)
		(end 147.852384 -282.693364)
		(width 0.0889)
		(layer "In11.Cu")
		(net "M_L_CPU1_SB_DQ<12>")
	)
	(segment
		(start 193.372486 -297.219878)
		(end 196.402198 -297.219878)
		(width 0.14478)
		(layer "In11.Cu")
		(net "M_L_CPU1_SB_DQ<12>")
	)
	(segment
		(start 144.690592 -282.50896)
		(end 144.708626 -282.498292)
		(width 0.0889)
		(layer "In11.Cu")
		(net "M_L_CPU1_SB_DQ<12>")
	)
	(segment
		(start 174.627286 -296.369994)
		(end 177.470562 -296.369994)
		(width 0.14478)
		(layer "In11.Cu")
		(net "M_L_CPU1_SB_DQ<12>")
	)
	(segment
		(start 170.976544 -297.219878)
		(end 173.777402 -297.219878)
		(width 0.14478)
		(layer "In11.Cu")
		(net "M_L_CPU1_SB_DQ<12>")
	)
	(segment
		(start 188.86551 -297.219878)
		(end 189.715394 -296.369994)
		(width 0.14478)
		(layer "In11.Cu")
		(net "M_L_CPU1_SB_DQ<12>")
	)
	(segment
		(start 166.242746 -297.21048)
		(end 166.76116 -296.692066)
		(width 0.14478)
		(layer "In11.Cu")
		(net "M_L_CPU1_SB_DQ<12>")
	)
	(segment
		(start 149.723094 -282.693364)
		(end 157.930088 -290.900358)
		(width 0.14478)
		(layer "In11.Cu")
		(net "M_L_CPU1_SB_DQ<12>")
	)
	(segment
		(start 145.794476 -282.55976)
		(end 146.00047 -282.353766)
		(width 0.0889)
		(layer "In11.Cu")
		(net "M_L_CPU1_SB_DQ<12>")
	)
	(segment
		(start 184.963816 -296.369994)
		(end 185.8137 -297.219878)
		(width 0.14478)
		(layer "In11.Cu")
		(net "M_L_CPU1_SB_DQ<12>")
	)
	(segment
		(start 139.804648 -282.18638)
		(end 139.650724 -282.45181)
		(width 0.0889)
		(layer "In11.Cu")
		(net "M_L_CPU1_SB_DQ<12>")
	)
	(segment
		(start 173.777402 -297.219878)
		(end 174.627286 -296.369994)
		(width 0.14478)
		(layer "In11.Cu")
		(net "M_L_CPU1_SB_DQ<12>")
	)
	(segment
		(start 145.444718 -282.55976)
		(end 145.794476 -282.55976)
		(width 0.0889)
		(layer "In11.Cu")
		(net "M_L_CPU1_SB_DQ<12>")
	)
	(segment
		(start 205.110588 -296.52341)
		(end 205.273656 -296.360342)
		(width 0.14478)
		(layer "In11.Cu")
		(net "M_L_CPU1_SB_DQ<12>")
	)
	(segment
		(start 144.30502 -282.501848)
		(end 144.316958 -282.508706)
		(width 0.0889)
		(layer "In11.Cu")
		(net "M_L_CPU1_SB_DQ<12>")
	)
	(segment
		(start 181.321456 -297.219878)
		(end 182.17134 -296.369994)
		(width 0.14478)
		(layer "In11.Cu")
		(net "M_L_CPU1_SB_DQ<12>")
	)
	(segment
		(start 140.557758 -282.50896)
		(end 140.56614 -282.513786)
		(width 0.0889)
		(layer "In11.Cu")
		(net "M_L_CPU1_SB_DQ<12>")
	)
	(segment
		(start 178.320446 -297.219878)
		(end 181.321456 -297.219878)
		(width 0.14478)
		(layer "In11.Cu")
		(net "M_L_CPU1_SB_DQ<12>")
	)
	(segment
		(start 182.17134 -296.369994)
		(end 184.963816 -296.369994)
		(width 0.14478)
		(layer "In11.Cu")
		(net "M_L_CPU1_SB_DQ<12>")
	)
	(segment
		(start 204.554074 -297.033696)
		(end 204.717142 -297.196764)
		(width 0.14478)
		(layer "In11.Cu")
		(net "M_L_CPU1_SB_DQ<12>")
	)
	(segment
		(start 205.273656 -296.360342)
		(end 205.823058 -296.360342)
		(width 0.14478)
		(layer "In11.Cu")
		(net "M_L_CPU1_SB_DQ<12>")
	)
	(segment
		(start 177.470562 -296.369994)
		(end 178.320446 -297.219878)
		(width 0.14478)
		(layer "In11.Cu")
		(net "M_L_CPU1_SB_DQ<12>")
	)
	(segment
		(start 142.803372 -282.513786)
		(end 142.811754 -282.50896)
		(width 0.0889)
		(layer "In11.Cu")
		(net "M_L_CPU1_SB_DQ<12>")
	)
	(segment
		(start 197.252336 -296.36974)
		(end 204.400404 -296.36974)
		(width 0.14478)
		(layer "In11.Cu")
		(net "M_L_CPU1_SB_DQ<12>")
	)
	(segment
		(start 196.402198 -297.219878)
		(end 197.252336 -296.36974)
		(width 0.14478)
		(layer "In11.Cu")
		(net "M_L_CPU1_SB_DQ<12>")
	)
	(segment
		(start 146.00047 -282.353766)
		(end 147.25269 -282.353766)
		(width 0.0889)
		(layer "In11.Cu")
		(net "M_L_CPU1_SB_DQ<12>")
	)
	(segment
		(start 166.76116 -296.692066)
		(end 170.448732 -296.692066)
		(width 0.14478)
		(layer "In11.Cu")
		(net "M_L_CPU1_SB_DQ<12>")
	)
	(segment
		(start 157.930088 -292.372542)
		(end 162.768026 -297.21048)
		(width 0.14478)
		(layer "In11.Cu")
		(net "M_L_CPU1_SB_DQ<12>")
	)
	(segment
		(start 204.400404 -296.36974)
		(end 204.554074 -296.52341)
		(width 0.14478)
		(layer "In11.Cu")
		(net "M_L_CPU1_SB_DQ<12>")
	)
	(segment
		(start 204.717142 -297.196764)
		(end 204.94752 -297.196764)
		(width 0.14478)
		(layer "In11.Cu")
		(net "M_L_CPU1_SB_DQ<12>")
	)
	(segment
		(start 205.823058 -296.360342)
		(end 206.248 -296.785284)
		(width 0.14478)
		(layer "In11.Cu")
		(net "M_L_CPU1_SB_DQ<12>")
	)
	(arc
		(start 139.673076 -282.535122)
		(mid 139.835408 -282.55794)
		(end 139.991846 -282.50896)
		(width 0.0889)
		(layer "In11.Cu")
		(net "M_L_CPU1_SB_DQ<12>")
	)
	(arc
		(start 141.8717 -282.50896)
		(mid 142.154656 -282.432783)
		(end 142.437612 -282.50896)
		(width 0.0889)
		(layer "In11.Cu")
		(net "M_L_CPU1_SB_DQ<12>")
	)
	(arc
		(start 145.257266 -282.50896)
		(mid 145.347629 -282.54677)
		(end 145.444718 -282.55976)
		(width 0.0889)
		(layer "In11.Cu")
		(net "M_L_CPU1_SB_DQ<12>")
	)
	(arc
		(start 142.811754 -282.50896)
		(mid 143.09471 -282.432783)
		(end 143.377666 -282.50896)
		(width 0.0889)
		(layer "In11.Cu")
		(net "M_L_CPU1_SB_DQ<12>")
	)
	(arc
		(start 142.437612 -282.50896)
		(mid 142.619863 -282.55931)
		(end 142.803372 -282.513786)
		(width 0.0889)
		(layer "In11.Cu")
		(net "M_L_CPU1_SB_DQ<12>")
	)
	(arc
		(start 140.56614 -282.513786)
		(mid 140.749648 -282.55928)
		(end 140.9319 -282.50896)
		(width 0.0889)
		(layer "In11.Cu")
		(net "M_L_CPU1_SB_DQ<12>")
	)
	(arc
		(start 140.9319 -282.50896)
		(mid 141.214856 -282.432783)
		(end 141.497812 -282.50896)
		(width 0.0889)
		(layer "In11.Cu")
		(net "M_L_CPU1_SB_DQ<12>")
	)
	(arc
		(start 141.497812 -282.50896)
		(mid 141.684756 -282.559215)
		(end 141.8717 -282.50896)
		(width 0.0889)
		(layer "In11.Cu")
		(net "M_L_CPU1_SB_DQ<12>")
	)
	(arc
		(start 144.708626 -282.498292)
		(mid 144.984321 -282.432449)
		(end 145.257266 -282.50896)
		(width 0.0889)
		(layer "In11.Cu")
		(net "M_L_CPU1_SB_DQ<12>")
	)
	(arc
		(start 139.991846 -282.50896)
		(mid 140.274802 -282.432783)
		(end 140.557758 -282.50896)
		(width 0.0889)
		(layer "In11.Cu")
		(net "M_L_CPU1_SB_DQ<12>")
	)
	(arc
		(start 144.330674 -282.51658)
		(mid 144.511604 -282.559058)
		(end 144.690592 -282.50896)
		(width 0.0889)
		(layer "In11.Cu")
		(net "M_L_CPU1_SB_DQ<12>")
	)
	(arc
		(start 143.751808 -282.50896)
		(mid 144.027486 -282.43283)
		(end 144.30502 -282.501848)
		(width 0.0889)
		(layer "In11.Cu")
		(net "M_L_CPU1_SB_DQ<12>")
	)
	(arc
		(start 143.386048 -282.513786)
		(mid 143.569556 -282.55928)
		(end 143.751808 -282.50896)
		(width 0.0889)
		(layer "In11.Cu")
		(net "M_L_CPU1_SB_DQ<12>")
	)
	(segment
		(start 137.457942 -280.30043)
		(end 137.924794 -280.566368)
		(width 0.10668)
		(layer "F.Cu")
		(net "M_L_CPU1_SB_DQ<11>")
	)
	(segment
		(start 168.152826 -292.650164)
		(end 168.453562 -292.9509)
		(width 0.14478)
		(layer "In11.Cu")
		(net "M_L_CPU1_SB_DQ<11>")
	)
	(segment
		(start 163.853114 -293.513764)
		(end 164.244528 -293.513764)
		(width 0.14478)
		(layer "In11.Cu")
		(net "M_L_CPU1_SB_DQ<11>")
	)
	(segment
		(start 176.884584 -292.9509)
		(end 177.029364 -292.80612)
		(width 0.14478)
		(layer "In11.Cu")
		(net "M_L_CPU1_SB_DQ<11>")
	)
	(segment
		(start 177.436018 -292.569646)
		(end 177.580798 -292.714426)
		(width 0.14478)
		(layer "In11.Cu")
		(net "M_L_CPU1_SB_DQ<11>")
	)
	(segment
		(start 184.978548 -292.9509)
		(end 185.260996 -292.9509)
		(width 0.14478)
		(layer "In11.Cu")
		(net "M_L_CPU1_SB_DQ<11>")
	)
	(segment
		(start 167.60571 -292.9509)
		(end 167.906446 -292.650164)
		(width 0.14478)
		(layer "In11.Cu")
		(net "M_L_CPU1_SB_DQ<11>")
	)
	(segment
		(start 165.097714 -293.513764)
		(end 165.357556 -293.513764)
		(width 0.14478)
		(layer "In11.Cu")
		(net "M_L_CPU1_SB_DQ<11>")
	)
	(segment
		(start 201.635614 -293.38524)
		(end 202.147932 -293.38524)
		(width 0.14478)
		(layer "In11.Cu")
		(net "M_L_CPU1_SB_DQ<11>")
	)
	(segment
		(start 171.022772 -293.801038)
		(end 173.438058 -293.801038)
		(width 0.14478)
		(layer "In11.Cu")
		(net "M_L_CPU1_SB_DQ<11>")
	)
	(segment
		(start 200.453498 -293.38524)
		(end 200.79462 -293.38524)
		(width 0.14478)
		(layer "In11.Cu")
		(net "M_L_CPU1_SB_DQ<11>")
	)
	(segment
		(start 182.07101 -292.9509)
		(end 182.297324 -292.9509)
		(width 0.14478)
		(layer "In11.Cu")
		(net "M_L_CPU1_SB_DQ<11>")
	)
	(segment
		(start 174.966884 -292.719506)
		(end 175.111664 -292.574726)
		(width 0.14478)
		(layer "In11.Cu")
		(net "M_L_CPU1_SB_DQ<11>")
	)
	(segment
		(start 189.903862 -292.9509)
		(end 190.048642 -292.80612)
		(width 0.14478)
		(layer "In11.Cu")
		(net "M_L_CPU1_SB_DQ<11>")
	)
	(segment
		(start 192.297812 -292.719506)
		(end 192.297812 -292.80612)
		(width 0.14478)
		(layer "In11.Cu")
		(net "M_L_CPU1_SB_DQ<11>")
	)
	(segment
		(start 184.833768 -292.80612)
		(end 184.978548 -292.9509)
		(width 0.14478)
		(layer "In11.Cu")
		(net "M_L_CPU1_SB_DQ<11>")
	)
	(segment
		(start 175.111664 -292.574726)
		(end 175.373538 -292.574726)
		(width 0.14478)
		(layer "In11.Cu")
		(net "M_L_CPU1_SB_DQ<11>")
	)
	(segment
		(start 200.9394 -293.24046)
		(end 200.9394 -292.772846)
		(width 0.14478)
		(layer "In11.Cu")
		(net "M_L_CPU1_SB_DQ<11>")
	)
	(segment
		(start 174.966884 -292.80612)
		(end 174.966884 -292.719506)
		(width 0.14478)
		(layer "In11.Cu")
		(net "M_L_CPU1_SB_DQ<11>")
	)
	(segment
		(start 166.075106 -293.810436)
		(end 166.934642 -292.9509)
		(width 0.14478)
		(layer "In11.Cu")
		(net "M_L_CPU1_SB_DQ<11>")
	)
	(segment
		(start 164.5412 -293.810436)
		(end 164.801042 -293.810436)
		(width 0.14478)
		(layer "In11.Cu")
		(net "M_L_CPU1_SB_DQ<11>")
	)
	(segment
		(start 190.048642 -292.719506)
		(end 190.193422 -292.574726)
		(width 0.14478)
		(layer "In11.Cu")
		(net "M_L_CPU1_SB_DQ<11>")
	)
	(segment
		(start 181.615842 -293.406068)
		(end 182.07101 -292.9509)
		(width 0.14478)
		(layer "In11.Cu")
		(net "M_L_CPU1_SB_DQ<11>")
	)
	(segment
		(start 168.718738 -292.9509)
		(end 169.019474 -292.650164)
		(width 0.14478)
		(layer "In11.Cu")
		(net "M_L_CPU1_SB_DQ<11>")
	)
	(segment
		(start 169.265854 -292.650164)
		(end 169.56659 -292.9509)
		(width 0.14478)
		(layer "In11.Cu")
		(net "M_L_CPU1_SB_DQ<11>")
	)
	(segment
		(start 164.801042 -293.810436)
		(end 165.097714 -293.513764)
		(width 0.14478)
		(layer "In11.Cu")
		(net "M_L_CPU1_SB_DQ<11>")
	)
	(segment
		(start 192.297812 -292.80612)
		(end 192.442592 -292.9509)
		(width 0.14478)
		(layer "In11.Cu")
		(net "M_L_CPU1_SB_DQ<11>")
	)
	(segment
		(start 182.297324 -292.9509)
		(end 182.442104 -292.80612)
		(width 0.14478)
		(layer "In11.Cu")
		(net "M_L_CPU1_SB_DQ<11>")
	)
	(segment
		(start 178.039014 -292.9509)
		(end 178.889152 -293.801038)
		(width 0.14478)
		(layer "In11.Cu")
		(net "M_L_CPU1_SB_DQ<11>")
	)
	(segment
		(start 191.891158 -292.574726)
		(end 192.153032 -292.574726)
		(width 0.14478)
		(layer "In11.Cu")
		(net "M_L_CPU1_SB_DQ<11>")
	)
	(segment
		(start 192.153032 -292.574726)
		(end 192.297812 -292.719506)
		(width 0.14478)
		(layer "In11.Cu")
		(net "M_L_CPU1_SB_DQ<11>")
	)
	(segment
		(start 201.346054 -292.628066)
		(end 201.490834 -292.772846)
		(width 0.14478)
		(layer "In11.Cu")
		(net "M_L_CPU1_SB_DQ<11>")
	)
	(segment
		(start 200.019158 -292.9509)
		(end 200.453498 -293.38524)
		(width 0.14478)
		(layer "In11.Cu")
		(net "M_L_CPU1_SB_DQ<11>")
	)
	(segment
		(start 192.442592 -292.9509)
		(end 192.80505 -292.9509)
		(width 0.14478)
		(layer "In11.Cu")
		(net "M_L_CPU1_SB_DQ<11>")
	)
	(segment
		(start 173.438058 -293.801038)
		(end 174.288196 -292.9509)
		(width 0.14478)
		(layer "In11.Cu")
		(net "M_L_CPU1_SB_DQ<11>")
	)
	(segment
		(start 174.288196 -292.9509)
		(end 174.822104 -292.9509)
		(width 0.14478)
		(layer "In11.Cu")
		(net "M_L_CPU1_SB_DQ<11>")
	)
	(segment
		(start 190.455296 -292.574726)
		(end 190.600076 -292.719506)
		(width 0.14478)
		(layer "In11.Cu")
		(net "M_L_CPU1_SB_DQ<11>")
	)
	(segment
		(start 177.029364 -292.80612)
		(end 177.029364 -292.714426)
		(width 0.14478)
		(layer "In11.Cu")
		(net "M_L_CPU1_SB_DQ<11>")
	)
	(segment
		(start 184.282334 -292.80612)
		(end 184.282334 -292.719506)
		(width 0.14478)
		(layer "In11.Cu")
		(net "M_L_CPU1_SB_DQ<11>")
	)
	(segment
		(start 200.9394 -292.772846)
		(end 201.08418 -292.628066)
		(width 0.14478)
		(layer "In11.Cu")
		(net "M_L_CPU1_SB_DQ<11>")
	)
	(segment
		(start 143.377666 -280.243788)
		(end 143.386048 -280.238962)
		(width 0.0889)
		(layer "In11.Cu")
		(net "M_L_CPU1_SB_DQ<11>")
	)
	(segment
		(start 147.819618 -280.200354)
		(end 150.539704 -280.200354)
		(width 0.14478)
		(layer "In11.Cu")
		(net "M_L_CPU1_SB_DQ<11>")
	)
	(segment
		(start 175.518318 -292.719506)
		(end 175.518318 -292.80612)
		(width 0.14478)
		(layer "In11.Cu")
		(net "M_L_CPU1_SB_DQ<11>")
	)
	(segment
		(start 166.934642 -292.9509)
		(end 167.60571 -292.9509)
		(width 0.14478)
		(layer "In11.Cu")
		(net "M_L_CPU1_SB_DQ<11>")
	)
	(segment
		(start 174.822104 -292.9509)
		(end 174.966884 -292.80612)
		(width 0.14478)
		(layer "In11.Cu")
		(net "M_L_CPU1_SB_DQ<11>")
	)
	(segment
		(start 165.654228 -293.810436)
		(end 166.075106 -293.810436)
		(width 0.14478)
		(layer "In11.Cu")
		(net "M_L_CPU1_SB_DQ<11>")
	)
	(segment
		(start 190.600076 -292.80612)
		(end 190.744856 -292.9509)
		(width 0.14478)
		(layer "In11.Cu")
		(net "M_L_CPU1_SB_DQ<11>")
	)
	(segment
		(start 190.048642 -292.80612)
		(end 190.048642 -292.719506)
		(width 0.14478)
		(layer "In11.Cu")
		(net "M_L_CPU1_SB_DQ<11>")
	)
	(segment
		(start 184.427114 -292.574726)
		(end 184.688988 -292.574726)
		(width 0.14478)
		(layer "In11.Cu")
		(net "M_L_CPU1_SB_DQ<11>")
	)
	(segment
		(start 175.663098 -292.9509)
		(end 176.884584 -292.9509)
		(width 0.14478)
		(layer "In11.Cu")
		(net "M_L_CPU1_SB_DQ<11>")
	)
	(segment
		(start 197.134734 -292.9509)
		(end 197.401688 -292.683946)
		(width 0.14478)
		(layer "In11.Cu")
		(net "M_L_CPU1_SB_DQ<11>")
	)
	(segment
		(start 177.580798 -292.80612)
		(end 177.725578 -292.9509)
		(width 0.14478)
		(layer "In11.Cu")
		(net "M_L_CPU1_SB_DQ<11>")
	)
	(segment
		(start 165.357556 -293.513764)
		(end 165.654228 -293.810436)
		(width 0.14478)
		(layer "In11.Cu")
		(net "M_L_CPU1_SB_DQ<11>")
	)
	(segment
		(start 177.174144 -292.569646)
		(end 177.436018 -292.569646)
		(width 0.14478)
		(layer "In11.Cu")
		(net "M_L_CPU1_SB_DQ<11>")
	)
	(segment
		(start 177.725578 -292.9509)
		(end 178.039014 -292.9509)
		(width 0.14478)
		(layer "In11.Cu")
		(net "M_L_CPU1_SB_DQ<11>")
	)
	(segment
		(start 184.833768 -292.719506)
		(end 184.833768 -292.80612)
		(width 0.14478)
		(layer "In11.Cu")
		(net "M_L_CPU1_SB_DQ<11>")
	)
	(segment
		(start 169.56659 -292.9509)
		(end 170.172634 -292.9509)
		(width 0.14478)
		(layer "In11.Cu")
		(net "M_L_CPU1_SB_DQ<11>")
	)
	(segment
		(start 182.993538 -292.80612)
		(end 183.138318 -292.9509)
		(width 0.14478)
		(layer "In11.Cu")
		(net "M_L_CPU1_SB_DQ<11>")
	)
	(segment
		(start 191.746378 -292.80612)
		(end 191.746378 -292.719506)
		(width 0.14478)
		(layer "In11.Cu")
		(net "M_L_CPU1_SB_DQ<11>")
	)
	(segment
		(start 170.172634 -292.9509)
		(end 171.022772 -293.801038)
		(width 0.14478)
		(layer "In11.Cu")
		(net "M_L_CPU1_SB_DQ<11>")
	)
	(segment
		(start 182.586884 -292.569646)
		(end 182.848758 -292.569646)
		(width 0.14478)
		(layer "In11.Cu")
		(net "M_L_CPU1_SB_DQ<11>")
	)
	(segment
		(start 193.654934 -293.800784)
		(end 195.90258 -293.800784)
		(width 0.14478)
		(layer "In11.Cu")
		(net "M_L_CPU1_SB_DQ<11>")
	)
	(segment
		(start 197.401688 -292.683946)
		(end 197.686168 -292.683946)
		(width 0.14478)
		(layer "In11.Cu")
		(net "M_L_CPU1_SB_DQ<11>")
	)
	(segment
		(start 139.617704 -280.243788)
		(end 139.626086 -280.238962)
		(width 0.0889)
		(layer "In11.Cu")
		(net "M_L_CPU1_SB_DQ<11>")
	)
	(segment
		(start 182.442104 -292.714426)
		(end 182.586884 -292.569646)
		(width 0.14478)
		(layer "In11.Cu")
		(net "M_L_CPU1_SB_DQ<11>")
	)
	(segment
		(start 175.518318 -292.80612)
		(end 175.663098 -292.9509)
		(width 0.14478)
		(layer "In11.Cu")
		(net "M_L_CPU1_SB_DQ<11>")
	)
	(segment
		(start 177.580798 -292.714426)
		(end 177.580798 -292.80612)
		(width 0.14478)
		(layer "In11.Cu")
		(net "M_L_CPU1_SB_DQ<11>")
	)
	(segment
		(start 191.601598 -292.9509)
		(end 191.746378 -292.80612)
		(width 0.14478)
		(layer "In11.Cu")
		(net "M_L_CPU1_SB_DQ<11>")
	)
	(segment
		(start 182.848758 -292.569646)
		(end 182.993538 -292.714426)
		(width 0.14478)
		(layer "In11.Cu")
		(net "M_L_CPU1_SB_DQ<11>")
	)
	(segment
		(start 145.439892 -280.200354)
		(end 147.819618 -280.200354)
		(width 0.0889)
		(layer "In11.Cu")
		(net "M_L_CPU1_SB_DQ<11>")
	)
	(segment
		(start 188.670438 -293.801038)
		(end 189.520576 -292.9509)
		(width 0.14478)
		(layer "In11.Cu")
		(net "M_L_CPU1_SB_DQ<11>")
	)
	(segment
		(start 190.600076 -292.719506)
		(end 190.600076 -292.80612)
		(width 0.14478)
		(layer "In11.Cu")
		(net "M_L_CPU1_SB_DQ<11>")
	)
	(segment
		(start 139.04341 -280.238962)
		(end 139.051792 -280.243788)
		(width 0.0889)
		(layer "In11.Cu")
		(net "M_L_CPU1_SB_DQ<11>")
	)
	(segment
		(start 201.490834 -292.772846)
		(end 201.490834 -293.24046)
		(width 0.14478)
		(layer "In11.Cu")
		(net "M_L_CPU1_SB_DQ<11>")
	)
	(segment
		(start 197.686168 -292.683946)
		(end 197.953122 -292.9509)
		(width 0.14478)
		(layer "In11.Cu")
		(net "M_L_CPU1_SB_DQ<11>")
	)
	(segment
		(start 167.906446 -292.650164)
		(end 168.152826 -292.650164)
		(width 0.14478)
		(layer "In11.Cu")
		(net "M_L_CPU1_SB_DQ<11>")
	)
	(segment
		(start 184.282334 -292.719506)
		(end 184.427114 -292.574726)
		(width 0.14478)
		(layer "In11.Cu")
		(net "M_L_CPU1_SB_DQ<11>")
	)
	(segment
		(start 140.557758 -280.243788)
		(end 140.56614 -280.238962)
		(width 0.0889)
		(layer "In11.Cu")
		(net "M_L_CPU1_SB_DQ<11>")
	)
	(segment
		(start 184.688988 -292.574726)
		(end 184.833768 -292.719506)
		(width 0.14478)
		(layer "In11.Cu")
		(net "M_L_CPU1_SB_DQ<11>")
	)
	(segment
		(start 190.744856 -292.9509)
		(end 191.601598 -292.9509)
		(width 0.14478)
		(layer "In11.Cu")
		(net "M_L_CPU1_SB_DQ<11>")
	)
	(segment
		(start 201.490834 -293.24046)
		(end 201.635614 -293.38524)
		(width 0.14478)
		(layer "In11.Cu")
		(net "M_L_CPU1_SB_DQ<11>")
	)
	(segment
		(start 185.260996 -292.9509)
		(end 186.111134 -293.801038)
		(width 0.14478)
		(layer "In11.Cu")
		(net "M_L_CPU1_SB_DQ<11>")
	)
	(segment
		(start 195.90258 -293.800784)
		(end 196.752464 -292.9509)
		(width 0.14478)
		(layer "In11.Cu")
		(net "M_L_CPU1_SB_DQ<11>")
	)
	(segment
		(start 196.752464 -292.9509)
		(end 197.134734 -292.9509)
		(width 0.14478)
		(layer "In11.Cu")
		(net "M_L_CPU1_SB_DQ<11>")
	)
	(segment
		(start 178.889152 -293.801038)
		(end 180.662072 -293.801038)
		(width 0.14478)
		(layer "In11.Cu")
		(net "M_L_CPU1_SB_DQ<11>")
	)
	(segment
		(start 138.078718 -280.300938)
		(end 138.17473 -280.275538)
		(width 0.0889)
		(layer "In11.Cu")
		(net "M_L_CPU1_SB_DQ<11>")
	)
	(segment
		(start 191.746378 -292.719506)
		(end 191.891158 -292.574726)
		(width 0.14478)
		(layer "In11.Cu")
		(net "M_L_CPU1_SB_DQ<11>")
	)
	(segment
		(start 164.244528 -293.513764)
		(end 164.5412 -293.810436)
		(width 0.14478)
		(layer "In11.Cu")
		(net "M_L_CPU1_SB_DQ<11>")
	)
	(segment
		(start 189.520576 -292.9509)
		(end 189.903862 -292.9509)
		(width 0.14478)
		(layer "In11.Cu")
		(net "M_L_CPU1_SB_DQ<11>")
	)
	(segment
		(start 192.80505 -292.9509)
		(end 193.654934 -293.800784)
		(width 0.14478)
		(layer "In11.Cu")
		(net "M_L_CPU1_SB_DQ<11>")
	)
	(segment
		(start 182.442104 -292.80612)
		(end 182.442104 -292.714426)
		(width 0.14478)
		(layer "In11.Cu")
		(net "M_L_CPU1_SB_DQ<11>")
	)
	(segment
		(start 200.79462 -293.38524)
		(end 200.9394 -293.24046)
		(width 0.14478)
		(layer "In11.Cu")
		(net "M_L_CPU1_SB_DQ<11>")
	)
	(segment
		(start 184.137554 -292.9509)
		(end 184.282334 -292.80612)
		(width 0.14478)
		(layer "In11.Cu")
		(net "M_L_CPU1_SB_DQ<11>")
	)
	(segment
		(start 182.993538 -292.714426)
		(end 182.993538 -292.80612)
		(width 0.14478)
		(layer "In11.Cu")
		(net "M_L_CPU1_SB_DQ<11>")
	)
	(segment
		(start 169.019474 -292.650164)
		(end 169.265854 -292.650164)
		(width 0.14478)
		(layer "In11.Cu")
		(net "M_L_CPU1_SB_DQ<11>")
	)
	(segment
		(start 183.138318 -292.9509)
		(end 184.137554 -292.9509)
		(width 0.14478)
		(layer "In11.Cu")
		(net "M_L_CPU1_SB_DQ<11>")
	)
	(segment
		(start 168.453562 -292.9509)
		(end 168.718738 -292.9509)
		(width 0.14478)
		(layer "In11.Cu")
		(net "M_L_CPU1_SB_DQ<11>")
	)
	(segment
		(start 137.924794 -280.566368)
		(end 138.078718 -280.300938)
		(width 0.0889)
		(layer "In11.Cu")
		(net "M_L_CPU1_SB_DQ<11>")
	)
	(segment
		(start 142.803372 -280.238962)
		(end 142.811754 -280.243788)
		(width 0.0889)
		(layer "In11.Cu")
		(net "M_L_CPU1_SB_DQ<11>")
	)
	(segment
		(start 177.029364 -292.714426)
		(end 177.174144 -292.569646)
		(width 0.14478)
		(layer "In11.Cu")
		(net "M_L_CPU1_SB_DQ<11>")
	)
	(segment
		(start 180.662072 -293.801038)
		(end 181.615842 -293.406068)
		(width 0.14478)
		(layer "In11.Cu")
		(net "M_L_CPU1_SB_DQ<11>")
	)
	(segment
		(start 186.111134 -293.801038)
		(end 188.670438 -293.801038)
		(width 0.14478)
		(layer "In11.Cu")
		(net "M_L_CPU1_SB_DQ<11>")
	)
	(segment
		(start 175.373538 -292.574726)
		(end 175.518318 -292.719506)
		(width 0.14478)
		(layer "In11.Cu")
		(net "M_L_CPU1_SB_DQ<11>")
	)
	(segment
		(start 197.953122 -292.9509)
		(end 200.019158 -292.9509)
		(width 0.14478)
		(layer "In11.Cu")
		(net "M_L_CPU1_SB_DQ<11>")
	)
	(segment
		(start 201.08418 -292.628066)
		(end 201.346054 -292.628066)
		(width 0.14478)
		(layer "In11.Cu")
		(net "M_L_CPU1_SB_DQ<11>")
	)
	(segment
		(start 150.539704 -280.200354)
		(end 163.853114 -293.513764)
		(width 0.14478)
		(layer "In11.Cu")
		(net "M_L_CPU1_SB_DQ<11>")
	)
	(segment
		(start 190.193422 -292.574726)
		(end 190.455296 -292.574726)
		(width 0.14478)
		(layer "In11.Cu")
		(net "M_L_CPU1_SB_DQ<11>")
	)
	(segment
		(start 143.751808 -280.243788)
		(end 143.762222 -280.249884)
		(width 0.0889)
		(layer "In11.Cu")
		(net "M_L_CPU1_SB_DQ<11>")
	)
	(arc
		(start 145.247614 -280.249884)
		(mid 145.340615 -280.212939)
		(end 145.439892 -280.200354)
		(width 0.0889)
		(layer "In11.Cu")
		(net "M_L_CPU1_SB_DQ<11>")
	)
	(arc
		(start 142.437612 -280.243788)
		(mid 142.619863 -280.193438)
		(end 142.803372 -280.238962)
		(width 0.0889)
		(layer "In11.Cu")
		(net "M_L_CPU1_SB_DQ<11>")
	)
	(arc
		(start 140.56614 -280.238962)
		(mid 140.749648 -280.193468)
		(end 140.9319 -280.243788)
		(width 0.0889)
		(layer "In11.Cu")
		(net "M_L_CPU1_SB_DQ<11>")
	)
	(arc
		(start 140.9319 -280.243788)
		(mid 141.214856 -280.319965)
		(end 141.497812 -280.243788)
		(width 0.0889)
		(layer "In11.Cu")
		(net "M_L_CPU1_SB_DQ<11>")
	)
	(arc
		(start 143.386048 -280.238962)
		(mid 143.569556 -280.193468)
		(end 143.751808 -280.243788)
		(width 0.0889)
		(layer "In11.Cu")
		(net "M_L_CPU1_SB_DQ<11>")
	)
	(arc
		(start 138.17473 -280.275538)
		(mid 138.429938 -280.319015)
		(end 138.67765 -280.243788)
		(width 0.0889)
		(layer "In11.Cu")
		(net "M_L_CPU1_SB_DQ<11>")
	)
	(arc
		(start 141.8717 -280.243788)
		(mid 142.154656 -280.319965)
		(end 142.437612 -280.243788)
		(width 0.0889)
		(layer "In11.Cu")
		(net "M_L_CPU1_SB_DQ<11>")
	)
	(arc
		(start 139.626086 -280.238962)
		(mid 139.809594 -280.193468)
		(end 139.991846 -280.243788)
		(width 0.0889)
		(layer "In11.Cu")
		(net "M_L_CPU1_SB_DQ<11>")
	)
	(arc
		(start 142.811754 -280.243788)
		(mid 143.09471 -280.319965)
		(end 143.377666 -280.243788)
		(width 0.0889)
		(layer "In11.Cu")
		(net "M_L_CPU1_SB_DQ<11>")
	)
	(arc
		(start 144.69237 -280.243788)
		(mid 144.969183 -280.319931)
		(end 145.247614 -280.249884)
		(width 0.0889)
		(layer "In11.Cu")
		(net "M_L_CPU1_SB_DQ<11>")
	)
	(arc
		(start 141.497812 -280.243788)
		(mid 141.684756 -280.193533)
		(end 141.8717 -280.243788)
		(width 0.0889)
		(layer "In11.Cu")
		(net "M_L_CPU1_SB_DQ<11>")
	)
	(arc
		(start 139.991846 -280.243788)
		(mid 140.274802 -280.319965)
		(end 140.557758 -280.243788)
		(width 0.0889)
		(layer "In11.Cu")
		(net "M_L_CPU1_SB_DQ<11>")
	)
	(arc
		(start 138.67765 -280.243788)
		(mid 138.859901 -280.193438)
		(end 139.04341 -280.238962)
		(width 0.0889)
		(layer "In11.Cu")
		(net "M_L_CPU1_SB_DQ<11>")
	)
	(arc
		(start 139.051792 -280.243788)
		(mid 139.334748 -280.319965)
		(end 139.617704 -280.243788)
		(width 0.0889)
		(layer "In11.Cu")
		(net "M_L_CPU1_SB_DQ<11>")
	)
	(arc
		(start 143.762222 -280.249884)
		(mid 144.040908 -280.320104)
		(end 144.317974 -280.243788)
		(width 0.0889)
		(layer "In11.Cu")
		(net "M_L_CPU1_SB_DQ<11>")
	)
	(arc
		(start 144.317974 -280.243788)
		(mid 144.505172 -280.193406)
		(end 144.69237 -280.243788)
		(width 0.0889)
		(layer "In11.Cu")
		(net "M_L_CPU1_SB_DQ<11>")
	)
	(segment
		(start 138.867896 -279.490424)
		(end 139.334748 -279.756362)
		(width 0.10668)
		(layer "F.Cu")
		(net "M_L_CPU1_SB_DQ<10>")
	)
	(segment
		(start 172.643546 -292.110414)
		(end 172.916596 -291.837364)
		(width 0.14478)
		(layer "In11.Cu")
		(net "M_L_CPU1_SB_DQ<10>")
	)
	(segment
		(start 141.393418 -279.428956)
		(end 141.4018 -279.433782)
		(width 0.0889)
		(layer "In11.Cu")
		(net "M_L_CPU1_SB_DQ<10>")
	)
	(segment
		(start 166.149782 -292.110414)
		(end 166.99992 -291.260276)
		(width 0.14478)
		(layer "In11.Cu")
		(net "M_L_CPU1_SB_DQ<10>")
	)
	(segment
		(start 184.020714 -291.260276)
		(end 184.165494 -291.115496)
		(width 0.14478)
		(layer "In11.Cu")
		(net "M_L_CPU1_SB_DQ<10>")
	)
	(segment
		(start 184.165494 -291.005006)
		(end 184.310274 -290.860226)
		(width 0.14478)
		(layer "In11.Cu")
		(net "M_L_CPU1_SB_DQ<10>")
	)
	(segment
		(start 197.946518 -291.557964)
		(end 198.244206 -291.260276)
		(width 0.14478)
		(layer "In11.Cu")
		(net "M_L_CPU1_SB_DQ<10>")
	)
	(segment
		(start 177.226214 -290.867846)
		(end 177.370994 -291.012626)
		(width 0.14478)
		(layer "In11.Cu")
		(net "M_L_CPU1_SB_DQ<10>")
	)
	(segment
		(start 168.940226 -290.948364)
		(end 169.184828 -290.948364)
		(width 0.14478)
		(layer "In11.Cu")
		(net "M_L_CPU1_SB_DQ<10>")
	)
	(segment
		(start 190.18758 -290.865306)
		(end 190.449454 -290.865306)
		(width 0.14478)
		(layer "In11.Cu")
		(net "M_L_CPU1_SB_DQ<10>")
	)
	(segment
		(start 200.286874 -291.637466)
		(end 200.431654 -291.492686)
		(width 0.14478)
		(layer "In11.Cu")
		(net "M_L_CPU1_SB_DQ<10>")
	)
	(segment
		(start 190.449454 -290.865306)
		(end 190.594234 -291.010086)
		(width 0.14478)
		(layer "In11.Cu")
		(net "M_L_CPU1_SB_DQ<10>")
	)
	(segment
		(start 178.773582 -292.110414)
		(end 180.27396 -292.110414)
		(width 0.14478)
		(layer "In11.Cu")
		(net "M_L_CPU1_SB_DQ<10>")
	)
	(segment
		(start 186.120532 -292.110414)
		(end 187.570618 -292.110414)
		(width 0.14478)
		(layer "In11.Cu")
		(net "M_L_CPU1_SB_DQ<10>")
	)
	(segment
		(start 191.955674 -290.865306)
		(end 192.217548 -290.865306)
		(width 0.14478)
		(layer "In11.Cu")
		(net "M_L_CPU1_SB_DQ<10>")
	)
	(segment
		(start 173.693836 -292.110414)
		(end 174.543974 -291.260276)
		(width 0.14478)
		(layer "In11.Cu")
		(net "M_L_CPU1_SB_DQ<10>")
	)
	(segment
		(start 181.114954 -292.110414)
		(end 181.53761 -292.110414)
		(width 0.14478)
		(layer "In11.Cu")
		(net "M_L_CPU1_SB_DQ<10>")
	)
	(segment
		(start 175.666146 -291.260276)
		(end 176.67478 -291.260276)
		(width 0.14478)
		(layer "In11.Cu")
		(net "M_L_CPU1_SB_DQ<10>")
	)
	(segment
		(start 175.521366 -291.007546)
		(end 175.521366 -291.115496)
		(width 0.14478)
		(layer "In11.Cu")
		(net "M_L_CPU1_SB_DQ<10>")
	)
	(segment
		(start 200.025 -291.637466)
		(end 200.286874 -291.637466)
		(width 0.14478)
		(layer "In11.Cu")
		(net "M_L_CPU1_SB_DQ<10>")
	)
	(segment
		(start 177.515774 -291.260276)
		(end 177.923444 -291.260276)
		(width 0.14478)
		(layer "In11.Cu")
		(net "M_L_CPU1_SB_DQ<10>")
	)
	(segment
		(start 175.376586 -290.862766)
		(end 175.521366 -291.007546)
		(width 0.14478)
		(layer "In11.Cu")
		(net "M_L_CPU1_SB_DQ<10>")
	)
	(segment
		(start 189.632082 -291.260276)
		(end 189.89802 -291.260276)
		(width 0.14478)
		(layer "In11.Cu")
		(net "M_L_CPU1_SB_DQ<10>")
	)
	(segment
		(start 199.88022 -291.492686)
		(end 200.025 -291.637466)
		(width 0.14478)
		(layer "In11.Cu")
		(net "M_L_CPU1_SB_DQ<10>")
	)
	(segment
		(start 169.184828 -290.948364)
		(end 169.49674 -291.260276)
		(width 0.14478)
		(layer "In11.Cu")
		(net "M_L_CPU1_SB_DQ<10>")
	)
	(segment
		(start 174.543974 -291.260276)
		(end 174.825152 -291.260276)
		(width 0.14478)
		(layer "In11.Cu")
		(net "M_L_CPU1_SB_DQ<10>")
	)
	(segment
		(start 188.122052 -291.716206)
		(end 188.266832 -291.860986)
		(width 0.14478)
		(layer "In11.Cu")
		(net "M_L_CPU1_SB_DQ<10>")
	)
	(segment
		(start 167.827198 -290.948364)
		(end 168.0718 -290.948364)
		(width 0.14478)
		(layer "In11.Cu")
		(net "M_L_CPU1_SB_DQ<10>")
	)
	(segment
		(start 192.814448 -291.260276)
		(end 193.664332 -292.11016)
		(width 0.14478)
		(layer "In11.Cu")
		(net "M_L_CPU1_SB_DQ<10>")
	)
	(segment
		(start 198.244206 -291.260276)
		(end 199.184006 -291.260276)
		(width 0.14478)
		(layer "In11.Cu")
		(net "M_L_CPU1_SB_DQ<10>")
	)
	(segment
		(start 144.205198 -279.424638)
		(end 144.221454 -279.434036)
		(width 0.0889)
		(layer "In11.Cu")
		(net "M_L_CPU1_SB_DQ<10>")
	)
	(segment
		(start 201.127868 -291.260276)
		(end 201.72299 -291.260276)
		(width 0.14478)
		(layer "In11.Cu")
		(net "M_L_CPU1_SB_DQ<10>")
	)
	(segment
		(start 166.99992 -291.260276)
		(end 167.515286 -291.260276)
		(width 0.14478)
		(layer "In11.Cu")
		(net "M_L_CPU1_SB_DQ<10>")
	)
	(segment
		(start 189.89802 -291.260276)
		(end 190.0428 -291.115496)
		(width 0.14478)
		(layer "In11.Cu")
		(net "M_L_CPU1_SB_DQ<10>")
	)
	(segment
		(start 195.888864 -292.11016)
		(end 196.738748 -291.260276)
		(width 0.14478)
		(layer "In11.Cu")
		(net "M_L_CPU1_SB_DQ<10>")
	)
	(segment
		(start 165.001702 -292.110414)
		(end 165.325552 -291.786564)
		(width 0.14478)
		(layer "In11.Cu")
		(net "M_L_CPU1_SB_DQ<10>")
	)
	(segment
		(start 197.390004 -291.260276)
		(end 197.687692 -291.557964)
		(width 0.14478)
		(layer "In11.Cu")
		(net "M_L_CPU1_SB_DQ<10>")
	)
	(segment
		(start 168.383712 -291.260276)
		(end 168.628314 -291.260276)
		(width 0.14478)
		(layer "In11.Cu")
		(net "M_L_CPU1_SB_DQ<10>")
	)
	(segment
		(start 199.328786 -291.027866)
		(end 199.473566 -290.883086)
		(width 0.14478)
		(layer "In11.Cu")
		(net "M_L_CPU1_SB_DQ<10>")
	)
	(segment
		(start 165.882066 -292.110414)
		(end 166.149782 -292.110414)
		(width 0.14478)
		(layer "In11.Cu")
		(net "M_L_CPU1_SB_DQ<10>")
	)
	(segment
		(start 173.47311 -292.110414)
		(end 173.693836 -292.110414)
		(width 0.14478)
		(layer "In11.Cu")
		(net "M_L_CPU1_SB_DQ<10>")
	)
	(segment
		(start 168.628314 -291.260276)
		(end 168.940226 -290.948364)
		(width 0.14478)
		(layer "In11.Cu")
		(net "M_L_CPU1_SB_DQ<10>")
	)
	(segment
		(start 191.666114 -291.260276)
		(end 191.810894 -291.115496)
		(width 0.14478)
		(layer "In11.Cu")
		(net "M_L_CPU1_SB_DQ<10>")
	)
	(segment
		(start 199.73544 -290.883086)
		(end 199.88022 -291.027866)
		(width 0.14478)
		(layer "In11.Cu")
		(net "M_L_CPU1_SB_DQ<10>")
	)
	(segment
		(start 197.687692 -291.557964)
		(end 197.946518 -291.557964)
		(width 0.14478)
		(layer "In11.Cu")
		(net "M_L_CPU1_SB_DQ<10>")
	)
	(segment
		(start 191.810894 -291.115496)
		(end 191.810894 -291.010086)
		(width 0.14478)
		(layer "In11.Cu")
		(net "M_L_CPU1_SB_DQ<10>")
	)
	(segment
		(start 168.0718 -290.948364)
		(end 168.383712 -291.260276)
		(width 0.14478)
		(layer "In11.Cu")
		(net "M_L_CPU1_SB_DQ<10>")
	)
	(segment
		(start 175.521366 -291.115496)
		(end 175.666146 -291.260276)
		(width 0.14478)
		(layer "In11.Cu")
		(net "M_L_CPU1_SB_DQ<10>")
	)
	(segment
		(start 192.217548 -290.865306)
		(end 192.362328 -291.010086)
		(width 0.14478)
		(layer "In11.Cu")
		(net "M_L_CPU1_SB_DQ<10>")
	)
	(segment
		(start 196.738748 -291.260276)
		(end 197.390004 -291.260276)
		(width 0.14478)
		(layer "In11.Cu")
		(net "M_L_CPU1_SB_DQ<10>")
	)
	(segment
		(start 200.431654 -291.027866)
		(end 200.576434 -290.883086)
		(width 0.14478)
		(layer "In11.Cu")
		(net "M_L_CPU1_SB_DQ<10>")
	)
	(segment
		(start 176.81956 -291.115496)
		(end 176.81956 -291.012626)
		(width 0.14478)
		(layer "In11.Cu")
		(net "M_L_CPU1_SB_DQ<10>")
	)
	(segment
		(start 200.576434 -290.883086)
		(end 200.838308 -290.883086)
		(width 0.14478)
		(layer "In11.Cu")
		(net "M_L_CPU1_SB_DQ<10>")
	)
	(segment
		(start 187.570618 -292.110414)
		(end 187.715398 -291.965634)
		(width 0.14478)
		(layer "In11.Cu")
		(net "M_L_CPU1_SB_DQ<10>")
	)
	(segment
		(start 165.558216 -291.786564)
		(end 165.882066 -292.110414)
		(width 0.14478)
		(layer "In11.Cu")
		(net "M_L_CPU1_SB_DQ<10>")
	)
	(segment
		(start 180.970174 -291.855906)
		(end 180.970174 -291.965634)
		(width 0.14478)
		(layer "In11.Cu")
		(net "M_L_CPU1_SB_DQ<10>")
	)
	(segment
		(start 171.032678 -292.110414)
		(end 172.643546 -292.110414)
		(width 0.14478)
		(layer "In11.Cu")
		(net "M_L_CPU1_SB_DQ<10>")
	)
	(segment
		(start 180.970174 -291.965634)
		(end 181.114954 -292.110414)
		(width 0.14478)
		(layer "In11.Cu")
		(net "M_L_CPU1_SB_DQ<10>")
	)
	(segment
		(start 187.860178 -291.716206)
		(end 188.122052 -291.716206)
		(width 0.14478)
		(layer "In11.Cu")
		(net "M_L_CPU1_SB_DQ<10>")
	)
	(segment
		(start 173.20006 -291.837364)
		(end 173.47311 -292.110414)
		(width 0.14478)
		(layer "In11.Cu")
		(net "M_L_CPU1_SB_DQ<10>")
	)
	(segment
		(start 184.716928 -291.005006)
		(end 184.716928 -291.115496)
		(width 0.14478)
		(layer "In11.Cu")
		(net "M_L_CPU1_SB_DQ<10>")
	)
	(segment
		(start 199.184006 -291.260276)
		(end 199.328786 -291.115496)
		(width 0.14478)
		(layer "In11.Cu")
		(net "M_L_CPU1_SB_DQ<10>")
	)
	(segment
		(start 172.916596 -291.837364)
		(end 173.20006 -291.837364)
		(width 0.14478)
		(layer "In11.Cu")
		(net "M_L_CPU1_SB_DQ<10>")
	)
	(segment
		(start 184.716928 -291.115496)
		(end 184.861708 -291.260276)
		(width 0.14478)
		(layer "In11.Cu")
		(net "M_L_CPU1_SB_DQ<10>")
	)
	(segment
		(start 144.221454 -279.434036)
		(end 144.233392 -279.440894)
		(width 0.0889)
		(layer "In11.Cu")
		(net "M_L_CPU1_SB_DQ<10>")
	)
	(segment
		(start 176.81956 -291.012626)
		(end 176.96434 -290.867846)
		(width 0.14478)
		(layer "In11.Cu")
		(net "M_L_CPU1_SB_DQ<10>")
	)
	(segment
		(start 177.370994 -291.115496)
		(end 177.515774 -291.260276)
		(width 0.14478)
		(layer "In11.Cu")
		(net "M_L_CPU1_SB_DQ<10>")
	)
	(segment
		(start 177.370994 -291.012626)
		(end 177.370994 -291.115496)
		(width 0.14478)
		(layer "In11.Cu")
		(net "M_L_CPU1_SB_DQ<10>")
	)
	(segment
		(start 145.444718 -279.510236)
		(end 146.09572 -279.510236)
		(width 0.0889)
		(layer "In11.Cu")
		(net "M_L_CPU1_SB_DQ<10>")
	)
	(segment
		(start 180.41874 -291.855906)
		(end 180.56352 -291.711126)
		(width 0.14478)
		(layer "In11.Cu")
		(net "M_L_CPU1_SB_DQ<10>")
	)
	(segment
		(start 185.270394 -291.260276)
		(end 186.120532 -292.110414)
		(width 0.14478)
		(layer "In11.Cu")
		(net "M_L_CPU1_SB_DQ<10>")
	)
	(segment
		(start 146.09572 -279.510236)
		(end 146.539966 -279.06599)
		(width 0.0889)
		(layer "In11.Cu")
		(net "M_L_CPU1_SB_DQ<10>")
	)
	(segment
		(start 176.67478 -291.260276)
		(end 176.81956 -291.115496)
		(width 0.14478)
		(layer "In11.Cu")
		(net "M_L_CPU1_SB_DQ<10>")
	)
	(segment
		(start 200.431654 -291.492686)
		(end 200.431654 -291.027866)
		(width 0.14478)
		(layer "In11.Cu")
		(net "M_L_CPU1_SB_DQ<10>")
	)
	(segment
		(start 150.691596 -279.06599)
		(end 163.41217 -291.786564)
		(width 0.14478)
		(layer "In11.Cu")
		(net "M_L_CPU1_SB_DQ<10>")
	)
	(segment
		(start 146.539966 -279.06599)
		(end 147.937474 -279.06599)
		(width 0.0889)
		(layer "In11.Cu")
		(net "M_L_CPU1_SB_DQ<10>")
	)
	(segment
		(start 140.453364 -279.428956)
		(end 140.461746 -279.433782)
		(width 0.0889)
		(layer "In11.Cu")
		(net "M_L_CPU1_SB_DQ<10>")
	)
	(segment
		(start 167.515286 -291.260276)
		(end 167.827198 -290.948364)
		(width 0.14478)
		(layer "In11.Cu")
		(net "M_L_CPU1_SB_DQ<10>")
	)
	(segment
		(start 193.664332 -292.11016)
		(end 195.888864 -292.11016)
		(width 0.14478)
		(layer "In11.Cu")
		(net "M_L_CPU1_SB_DQ<10>")
	)
	(segment
		(start 180.56352 -291.711126)
		(end 180.825394 -291.711126)
		(width 0.14478)
		(layer "In11.Cu")
		(net "M_L_CPU1_SB_DQ<10>")
	)
	(segment
		(start 181.53761 -292.110414)
		(end 182.387748 -291.260276)
		(width 0.14478)
		(layer "In11.Cu")
		(net "M_L_CPU1_SB_DQ<10>")
	)
	(segment
		(start 141.967712 -279.433782)
		(end 141.976094 -279.428956)
		(width 0.0889)
		(layer "In11.Cu")
		(net "M_L_CPU1_SB_DQ<10>")
	)
	(segment
		(start 184.572148 -290.860226)
		(end 184.716928 -291.005006)
		(width 0.14478)
		(layer "In11.Cu")
		(net "M_L_CPU1_SB_DQ<10>")
	)
	(segment
		(start 187.715398 -291.965634)
		(end 187.715398 -291.860986)
		(width 0.14478)
		(layer "In11.Cu")
		(net "M_L_CPU1_SB_DQ<10>")
	)
	(segment
		(start 174.969932 -291.115496)
		(end 174.969932 -291.007546)
		(width 0.14478)
		(layer "In11.Cu")
		(net "M_L_CPU1_SB_DQ<10>")
	)
	(segment
		(start 190.0428 -291.010086)
		(end 190.18758 -290.865306)
		(width 0.14478)
		(layer "In11.Cu")
		(net "M_L_CPU1_SB_DQ<10>")
	)
	(segment
		(start 200.983088 -291.027866)
		(end 200.983088 -291.115496)
		(width 0.14478)
		(layer "In11.Cu")
		(net "M_L_CPU1_SB_DQ<10>")
	)
	(segment
		(start 164.445188 -291.786564)
		(end 164.769038 -292.110414)
		(width 0.14478)
		(layer "In11.Cu")
		(net "M_L_CPU1_SB_DQ<10>")
	)
	(segment
		(start 164.769038 -292.110414)
		(end 165.001702 -292.110414)
		(width 0.14478)
		(layer "In11.Cu")
		(net "M_L_CPU1_SB_DQ<10>")
	)
	(segment
		(start 192.362328 -291.115496)
		(end 192.507108 -291.260276)
		(width 0.14478)
		(layer "In11.Cu")
		(net "M_L_CPU1_SB_DQ<10>")
	)
	(segment
		(start 139.488672 -279.490932)
		(end 139.584684 -279.465532)
		(width 0.0889)
		(layer "In11.Cu")
		(net "M_L_CPU1_SB_DQ<10>")
	)
	(segment
		(start 170.18254 -291.260276)
		(end 171.032678 -292.110414)
		(width 0.14478)
		(layer "In11.Cu")
		(net "M_L_CPU1_SB_DQ<10>")
	)
	(segment
		(start 190.594234 -291.115496)
		(end 190.739014 -291.260276)
		(width 0.14478)
		(layer "In11.Cu")
		(net "M_L_CPU1_SB_DQ<10>")
	)
	(segment
		(start 184.861708 -291.260276)
		(end 185.270394 -291.260276)
		(width 0.14478)
		(layer "In11.Cu")
		(net "M_L_CPU1_SB_DQ<10>")
	)
	(segment
		(start 192.507108 -291.260276)
		(end 192.814448 -291.260276)
		(width 0.14478)
		(layer "In11.Cu")
		(net "M_L_CPU1_SB_DQ<10>")
	)
	(segment
		(start 192.362328 -291.010086)
		(end 192.362328 -291.115496)
		(width 0.14478)
		(layer "In11.Cu")
		(net "M_L_CPU1_SB_DQ<10>")
	)
	(segment
		(start 176.96434 -290.867846)
		(end 177.226214 -290.867846)
		(width 0.14478)
		(layer "In11.Cu")
		(net "M_L_CPU1_SB_DQ<10>")
	)
	(segment
		(start 199.88022 -291.027866)
		(end 199.88022 -291.492686)
		(width 0.14478)
		(layer "In11.Cu")
		(net "M_L_CPU1_SB_DQ<10>")
	)
	(segment
		(start 199.328786 -291.115496)
		(end 199.328786 -291.027866)
		(width 0.14478)
		(layer "In11.Cu")
		(net "M_L_CPU1_SB_DQ<10>")
	)
	(segment
		(start 174.969932 -291.007546)
		(end 175.114712 -290.862766)
		(width 0.14478)
		(layer "In11.Cu")
		(net "M_L_CPU1_SB_DQ<10>")
	)
	(segment
		(start 190.0428 -291.115496)
		(end 190.0428 -291.010086)
		(width 0.14478)
		(layer "In11.Cu")
		(net "M_L_CPU1_SB_DQ<10>")
	)
	(segment
		(start 169.49674 -291.260276)
		(end 170.18254 -291.260276)
		(width 0.14478)
		(layer "In11.Cu")
		(net "M_L_CPU1_SB_DQ<10>")
	)
	(segment
		(start 188.411612 -292.110414)
		(end 188.781944 -292.110414)
		(width 0.14478)
		(layer "In11.Cu")
		(net "M_L_CPU1_SB_DQ<10>")
	)
	(segment
		(start 165.325552 -291.786564)
		(end 165.558216 -291.786564)
		(width 0.14478)
		(layer "In11.Cu")
		(net "M_L_CPU1_SB_DQ<10>")
	)
	(segment
		(start 190.739014 -291.260276)
		(end 191.666114 -291.260276)
		(width 0.14478)
		(layer "In11.Cu")
		(net "M_L_CPU1_SB_DQ<10>")
	)
	(segment
		(start 180.825394 -291.711126)
		(end 180.970174 -291.855906)
		(width 0.14478)
		(layer "In11.Cu")
		(net "M_L_CPU1_SB_DQ<10>")
	)
	(segment
		(start 191.810894 -291.010086)
		(end 191.955674 -290.865306)
		(width 0.14478)
		(layer "In11.Cu")
		(net "M_L_CPU1_SB_DQ<10>")
	)
	(segment
		(start 180.27396 -292.110414)
		(end 180.41874 -291.965634)
		(width 0.14478)
		(layer "In11.Cu")
		(net "M_L_CPU1_SB_DQ<10>")
	)
	(segment
		(start 174.825152 -291.260276)
		(end 174.969932 -291.115496)
		(width 0.14478)
		(layer "In11.Cu")
		(net "M_L_CPU1_SB_DQ<10>")
	)
	(segment
		(start 200.838308 -290.883086)
		(end 200.983088 -291.027866)
		(width 0.14478)
		(layer "In11.Cu")
		(net "M_L_CPU1_SB_DQ<10>")
	)
	(segment
		(start 184.165494 -291.115496)
		(end 184.165494 -291.005006)
		(width 0.14478)
		(layer "In11.Cu")
		(net "M_L_CPU1_SB_DQ<10>")
	)
	(segment
		(start 184.310274 -290.860226)
		(end 184.572148 -290.860226)
		(width 0.14478)
		(layer "In11.Cu")
		(net "M_L_CPU1_SB_DQ<10>")
	)
	(segment
		(start 180.41874 -291.965634)
		(end 180.41874 -291.855906)
		(width 0.14478)
		(layer "In11.Cu")
		(net "M_L_CPU1_SB_DQ<10>")
	)
	(segment
		(start 201.72299 -291.260276)
		(end 202.147932 -291.685218)
		(width 0.14478)
		(layer "In11.Cu")
		(net "M_L_CPU1_SB_DQ<10>")
	)
	(segment
		(start 139.334748 -279.756362)
		(end 139.488672 -279.490932)
		(width 0.0889)
		(layer "In11.Cu")
		(net "M_L_CPU1_SB_DQ<10>")
	)
	(segment
		(start 190.594234 -291.010086)
		(end 190.594234 -291.115496)
		(width 0.14478)
		(layer "In11.Cu")
		(net "M_L_CPU1_SB_DQ<10>")
	)
	(segment
		(start 200.983088 -291.115496)
		(end 201.127868 -291.260276)
		(width 0.14478)
		(layer "In11.Cu")
		(net "M_L_CPU1_SB_DQ<10>")
	)
	(segment
		(start 147.937474 -279.06599)
		(end 150.691596 -279.06599)
		(width 0.14478)
		(layer "In11.Cu")
		(net "M_L_CPU1_SB_DQ<10>")
	)
	(segment
		(start 175.114712 -290.862766)
		(end 175.376586 -290.862766)
		(width 0.14478)
		(layer "In11.Cu")
		(net "M_L_CPU1_SB_DQ<10>")
	)
	(segment
		(start 188.781944 -292.110414)
		(end 189.632082 -291.260276)
		(width 0.14478)
		(layer "In11.Cu")
		(net "M_L_CPU1_SB_DQ<10>")
	)
	(segment
		(start 182.387748 -291.260276)
		(end 184.020714 -291.260276)
		(width 0.14478)
		(layer "In11.Cu")
		(net "M_L_CPU1_SB_DQ<10>")
	)
	(segment
		(start 187.715398 -291.860986)
		(end 187.860178 -291.716206)
		(width 0.14478)
		(layer "In11.Cu")
		(net "M_L_CPU1_SB_DQ<10>")
	)
	(segment
		(start 199.473566 -290.883086)
		(end 199.73544 -290.883086)
		(width 0.14478)
		(layer "In11.Cu")
		(net "M_L_CPU1_SB_DQ<10>")
	)
	(segment
		(start 188.266832 -291.860986)
		(end 188.266832 -291.965634)
		(width 0.14478)
		(layer "In11.Cu")
		(net "M_L_CPU1_SB_DQ<10>")
	)
	(segment
		(start 144.786604 -279.433782)
		(end 144.798288 -279.426924)
		(width 0.0889)
		(layer "In11.Cu")
		(net "M_L_CPU1_SB_DQ<10>")
	)
	(segment
		(start 188.266832 -291.965634)
		(end 188.411612 -292.110414)
		(width 0.14478)
		(layer "In11.Cu")
		(net "M_L_CPU1_SB_DQ<10>")
	)
	(segment
		(start 163.41217 -291.786564)
		(end 164.445188 -291.786564)
		(width 0.14478)
		(layer "In11.Cu")
		(net "M_L_CPU1_SB_DQ<10>")
	)
	(segment
		(start 177.923444 -291.260276)
		(end 178.773582 -292.110414)
		(width 0.14478)
		(layer "In11.Cu")
		(net "M_L_CPU1_SB_DQ<10>")
	)
	(arc
		(start 141.027658 -279.433782)
		(mid 141.209909 -279.383432)
		(end 141.393418 -279.428956)
		(width 0.0889)
		(layer "In11.Cu")
		(net "M_L_CPU1_SB_DQ<10>")
	)
	(arc
		(start 144.233392 -279.440894)
		(mid 144.510926 -279.509875)
		(end 144.786604 -279.433782)
		(width 0.0889)
		(layer "In11.Cu")
		(net "M_L_CPU1_SB_DQ<10>")
	)
	(arc
		(start 140.087604 -279.433782)
		(mid 140.269855 -279.383432)
		(end 140.453364 -279.428956)
		(width 0.0889)
		(layer "In11.Cu")
		(net "M_L_CPU1_SB_DQ<10>")
	)
	(arc
		(start 145.161 -279.433782)
		(mid 145.297793 -279.490804)
		(end 145.444718 -279.510236)
		(width 0.0889)
		(layer "In11.Cu")
		(net "M_L_CPU1_SB_DQ<10>")
	)
	(arc
		(start 142.907766 -279.433782)
		(mid 143.09471 -279.383527)
		(end 143.281654 -279.433782)
		(width 0.0889)
		(layer "In11.Cu")
		(net "M_L_CPU1_SB_DQ<10>")
	)
	(arc
		(start 142.341854 -279.433782)
		(mid 142.62481 -279.509959)
		(end 142.907766 -279.433782)
		(width 0.0889)
		(layer "In11.Cu")
		(net "M_L_CPU1_SB_DQ<10>")
	)
	(arc
		(start 141.976094 -279.428956)
		(mid 142.159602 -279.383462)
		(end 142.341854 -279.433782)
		(width 0.0889)
		(layer "In11.Cu")
		(net "M_L_CPU1_SB_DQ<10>")
	)
	(arc
		(start 143.847566 -279.433782)
		(mid 144.025216 -279.383522)
		(end 144.205198 -279.424638)
		(width 0.0889)
		(layer "In11.Cu")
		(net "M_L_CPU1_SB_DQ<10>")
	)
	(arc
		(start 141.4018 -279.433782)
		(mid 141.684756 -279.509959)
		(end 141.967712 -279.433782)
		(width 0.0889)
		(layer "In11.Cu")
		(net "M_L_CPU1_SB_DQ<10>")
	)
	(arc
		(start 139.584684 -279.465532)
		(mid 139.839892 -279.509009)
		(end 140.087604 -279.433782)
		(width 0.0889)
		(layer "In11.Cu")
		(net "M_L_CPU1_SB_DQ<10>")
	)
	(arc
		(start 140.461746 -279.433782)
		(mid 140.744702 -279.509959)
		(end 141.027658 -279.433782)
		(width 0.0889)
		(layer "In11.Cu")
		(net "M_L_CPU1_SB_DQ<10>")
	)
	(arc
		(start 143.281654 -279.433782)
		(mid 143.56461 -279.509959)
		(end 143.847566 -279.433782)
		(width 0.0889)
		(layer "In11.Cu")
		(net "M_L_CPU1_SB_DQ<10>")
	)
	(arc
		(start 144.798288 -279.426924)
		(mid 144.980543 -279.383271)
		(end 145.161 -279.433782)
		(width 0.0889)
		(layer "In11.Cu")
		(net "M_L_CPU1_SB_DQ<10>")
	)
	(segment
		(start 139.337796 -273.820382)
		(end 139.804648 -274.08632)
		(width 0.10668)
		(layer "F.Cu")
		(net "M_L_CPU1_SB_DQ<0>")
	)
	(segment
		(start 195.735448 -281.910282)
		(end 196.585332 -281.060398)
		(width 0.14478)
		(layer "In11.Cu")
		(net "M_L_CPU1_SB_DQ<0>")
	)
	(segment
		(start 154.430984 -272.939764)
		(end 163.401502 -281.910282)
		(width 0.14478)
		(layer "In11.Cu")
		(net "M_L_CPU1_SB_DQ<0>")
	)
	(segment
		(start 144.30502 -274.401788)
		(end 144.316958 -274.408646)
		(width 0.0889)
		(layer "In11.Cu")
		(net "M_L_CPU1_SB_DQ<0>")
	)
	(segment
		(start 188.874908 -281.910282)
		(end 189.724792 -281.060398)
		(width 0.14478)
		(layer "In11.Cu")
		(net "M_L_CPU1_SB_DQ<0>")
	)
	(segment
		(start 205.823058 -281.060398)
		(end 206.248 -281.48534)
		(width 0.14478)
		(layer "In11.Cu")
		(net "M_L_CPU1_SB_DQ<0>")
	)
	(segment
		(start 174.636684 -281.060398)
		(end 177.661316 -281.060398)
		(width 0.14478)
		(layer "In11.Cu")
		(net "M_L_CPU1_SB_DQ<0>")
	)
	(segment
		(start 173.7868 -281.910282)
		(end 174.636684 -281.060398)
		(width 0.14478)
		(layer "In11.Cu")
		(net "M_L_CPU1_SB_DQ<0>")
	)
	(segment
		(start 192.749424 -281.060398)
		(end 193.599308 -281.910282)
		(width 0.14478)
		(layer "In11.Cu")
		(net "M_L_CPU1_SB_DQ<0>")
	)
	(segment
		(start 139.804648 -274.08632)
		(end 139.650724 -274.35175)
		(width 0.0889)
		(layer "In11.Cu")
		(net "M_L_CPU1_SB_DQ<0>")
	)
	(segment
		(start 189.724792 -281.060398)
		(end 192.749424 -281.060398)
		(width 0.14478)
		(layer "In11.Cu")
		(net "M_L_CPU1_SB_DQ<0>")
	)
	(segment
		(start 196.585332 -281.060398)
		(end 204.215238 -281.060398)
		(width 0.14478)
		(layer "In11.Cu")
		(net "M_L_CPU1_SB_DQ<0>")
	)
	(segment
		(start 163.401502 -281.910282)
		(end 166.123874 -281.910282)
		(width 0.14478)
		(layer "In11.Cu")
		(net "M_L_CPU1_SB_DQ<0>")
	)
	(segment
		(start 204.215238 -281.060398)
		(end 204.378306 -281.223466)
		(width 0.14478)
		(layer "In11.Cu")
		(net "M_L_CPU1_SB_DQ<0>")
	)
	(segment
		(start 148.040344 -272.939764)
		(end 154.430984 -272.939764)
		(width 0.14478)
		(layer "In11.Cu")
		(net "M_L_CPU1_SB_DQ<0>")
	)
	(segment
		(start 143.377666 -274.4089)
		(end 143.386048 -274.413726)
		(width 0.0889)
		(layer "In11.Cu")
		(net "M_L_CPU1_SB_DQ<0>")
	)
	(segment
		(start 145.444718 -274.4597)
		(end 145.624042 -274.4597)
		(width 0.0889)
		(layer "In11.Cu")
		(net "M_L_CPU1_SB_DQ<0>")
	)
	(segment
		(start 142.803372 -274.413726)
		(end 142.811754 -274.4089)
		(width 0.0889)
		(layer "In11.Cu")
		(net "M_L_CPU1_SB_DQ<0>")
	)
	(segment
		(start 204.378306 -281.869896)
		(end 204.541374 -282.032964)
		(width 0.14478)
		(layer "In11.Cu")
		(net "M_L_CPU1_SB_DQ<0>")
	)
	(segment
		(start 185.20537 -281.060398)
		(end 186.055254 -281.910282)
		(width 0.14478)
		(layer "In11.Cu")
		(net "M_L_CPU1_SB_DQ<0>")
	)
	(segment
		(start 177.661316 -281.060398)
		(end 178.5112 -281.910282)
		(width 0.14478)
		(layer "In11.Cu")
		(net "M_L_CPU1_SB_DQ<0>")
	)
	(segment
		(start 178.5112 -281.910282)
		(end 181.330854 -281.910282)
		(width 0.14478)
		(layer "In11.Cu")
		(net "M_L_CPU1_SB_DQ<0>")
	)
	(segment
		(start 186.055254 -281.910282)
		(end 188.874908 -281.910282)
		(width 0.14478)
		(layer "In11.Cu")
		(net "M_L_CPU1_SB_DQ<0>")
	)
	(segment
		(start 193.599308 -281.910282)
		(end 195.735448 -281.910282)
		(width 0.14478)
		(layer "In11.Cu")
		(net "M_L_CPU1_SB_DQ<0>")
	)
	(segment
		(start 166.974012 -281.060144)
		(end 170.182286 -281.060144)
		(width 0.14478)
		(layer "In11.Cu")
		(net "M_L_CPU1_SB_DQ<0>")
	)
	(segment
		(start 166.123874 -281.910282)
		(end 166.974012 -281.060144)
		(width 0.14478)
		(layer "In11.Cu")
		(net "M_L_CPU1_SB_DQ<0>")
	)
	(segment
		(start 181.330854 -281.910282)
		(end 182.180738 -281.060398)
		(width 0.14478)
		(layer "In11.Cu")
		(net "M_L_CPU1_SB_DQ<0>")
	)
	(segment
		(start 144.316958 -274.408646)
		(end 144.330674 -274.41652)
		(width 0.0889)
		(layer "In11.Cu")
		(net "M_L_CPU1_SB_DQ<0>")
	)
	(segment
		(start 144.690592 -274.4089)
		(end 144.708626 -274.398232)
		(width 0.0889)
		(layer "In11.Cu")
		(net "M_L_CPU1_SB_DQ<0>")
	)
	(segment
		(start 147.18919 -273.397726)
		(end 147.647152 -272.939764)
		(width 0.0889)
		(layer "In11.Cu")
		(net "M_L_CPU1_SB_DQ<0>")
	)
	(segment
		(start 182.180738 -281.060398)
		(end 185.20537 -281.060398)
		(width 0.14478)
		(layer "In11.Cu")
		(net "M_L_CPU1_SB_DQ<0>")
	)
	(segment
		(start 146.686016 -273.397726)
		(end 147.18919 -273.397726)
		(width 0.0889)
		(layer "In11.Cu")
		(net "M_L_CPU1_SB_DQ<0>")
	)
	(segment
		(start 147.647152 -272.939764)
		(end 148.040344 -272.939764)
		(width 0.0889)
		(layer "In11.Cu")
		(net "M_L_CPU1_SB_DQ<0>")
	)
	(segment
		(start 145.624042 -274.4597)
		(end 146.686016 -273.397726)
		(width 0.0889)
		(layer "In11.Cu")
		(net "M_L_CPU1_SB_DQ<0>")
	)
	(segment
		(start 204.771752 -282.032964)
		(end 204.93482 -281.869896)
		(width 0.14478)
		(layer "In11.Cu")
		(net "M_L_CPU1_SB_DQ<0>")
	)
	(segment
		(start 204.93482 -281.869896)
		(end 204.93482 -281.223466)
		(width 0.14478)
		(layer "In11.Cu")
		(net "M_L_CPU1_SB_DQ<0>")
	)
	(segment
		(start 171.032424 -281.910282)
		(end 173.7868 -281.910282)
		(width 0.14478)
		(layer "In11.Cu")
		(net "M_L_CPU1_SB_DQ<0>")
	)
	(segment
		(start 140.557758 -274.4089)
		(end 140.56614 -274.413726)
		(width 0.0889)
		(layer "In11.Cu")
		(net "M_L_CPU1_SB_DQ<0>")
	)
	(segment
		(start 139.650724 -274.35175)
		(end 139.673076 -274.435062)
		(width 0.0889)
		(layer "In11.Cu")
		(net "M_L_CPU1_SB_DQ<0>")
	)
	(segment
		(start 204.378306 -281.223466)
		(end 204.378306 -281.869896)
		(width 0.14478)
		(layer "In11.Cu")
		(net "M_L_CPU1_SB_DQ<0>")
	)
	(segment
		(start 205.097888 -281.060398)
		(end 205.823058 -281.060398)
		(width 0.14478)
		(layer "In11.Cu")
		(net "M_L_CPU1_SB_DQ<0>")
	)
	(segment
		(start 204.93482 -281.223466)
		(end 205.097888 -281.060398)
		(width 0.14478)
		(layer "In11.Cu")
		(net "M_L_CPU1_SB_DQ<0>")
	)
	(segment
		(start 170.182286 -281.060144)
		(end 171.032424 -281.910282)
		(width 0.14478)
		(layer "In11.Cu")
		(net "M_L_CPU1_SB_DQ<0>")
	)
	(segment
		(start 204.541374 -282.032964)
		(end 204.771752 -282.032964)
		(width 0.14478)
		(layer "In11.Cu")
		(net "M_L_CPU1_SB_DQ<0>")
	)
	(arc
		(start 143.751808 -274.4089)
		(mid 144.027486 -274.33277)
		(end 144.30502 -274.401788)
		(width 0.0889)
		(layer "In11.Cu")
		(net "M_L_CPU1_SB_DQ<0>")
	)
	(arc
		(start 139.673076 -274.435062)
		(mid 139.835408 -274.45788)
		(end 139.991846 -274.4089)
		(width 0.0889)
		(layer "In11.Cu")
		(net "M_L_CPU1_SB_DQ<0>")
	)
	(arc
		(start 145.257266 -274.4089)
		(mid 145.347629 -274.44671)
		(end 145.444718 -274.4597)
		(width 0.0889)
		(layer "In11.Cu")
		(net "M_L_CPU1_SB_DQ<0>")
	)
	(arc
		(start 140.9319 -274.4089)
		(mid 141.214856 -274.332723)
		(end 141.497812 -274.4089)
		(width 0.0889)
		(layer "In11.Cu")
		(net "M_L_CPU1_SB_DQ<0>")
	)
	(arc
		(start 144.330674 -274.41652)
		(mid 144.511604 -274.458998)
		(end 144.690592 -274.4089)
		(width 0.0889)
		(layer "In11.Cu")
		(net "M_L_CPU1_SB_DQ<0>")
	)
	(arc
		(start 144.708626 -274.398232)
		(mid 144.984321 -274.332389)
		(end 145.257266 -274.4089)
		(width 0.0889)
		(layer "In11.Cu")
		(net "M_L_CPU1_SB_DQ<0>")
	)
	(arc
		(start 142.437612 -274.4089)
		(mid 142.619863 -274.45925)
		(end 142.803372 -274.413726)
		(width 0.0889)
		(layer "In11.Cu")
		(net "M_L_CPU1_SB_DQ<0>")
	)
	(arc
		(start 140.56614 -274.413726)
		(mid 140.749648 -274.45922)
		(end 140.9319 -274.4089)
		(width 0.0889)
		(layer "In11.Cu")
		(net "M_L_CPU1_SB_DQ<0>")
	)
	(arc
		(start 139.991846 -274.4089)
		(mid 140.274802 -274.332723)
		(end 140.557758 -274.4089)
		(width 0.0889)
		(layer "In11.Cu")
		(net "M_L_CPU1_SB_DQ<0>")
	)
	(arc
		(start 142.811754 -274.4089)
		(mid 143.09471 -274.332723)
		(end 143.377666 -274.4089)
		(width 0.0889)
		(layer "In11.Cu")
		(net "M_L_CPU1_SB_DQ<0>")
	)
	(arc
		(start 143.386048 -274.413726)
		(mid 143.569556 -274.45922)
		(end 143.751808 -274.4089)
		(width 0.0889)
		(layer "In11.Cu")
		(net "M_L_CPU1_SB_DQ<0>")
	)
	(arc
		(start 141.497812 -274.4089)
		(mid 141.684756 -274.459155)
		(end 141.8717 -274.4089)
		(width 0.0889)
		(layer "In11.Cu")
		(net "M_L_CPU1_SB_DQ<0>")
	)
	(arc
		(start 141.8717 -274.4089)
		(mid 142.154656 -274.332723)
		(end 142.437612 -274.4089)
		(width 0.0889)
		(layer "In11.Cu")
		(net "M_L_CPU1_SB_DQ<0>")
	)
	(segment
		(start 138.867896 -266.530328)
		(end 139.334748 -266.796266)
		(width 0.10668)
		(layer "F.Cu")
		(net "M_L_CPU1_SB_CS_N<1>")
	)
	(segment
		(start 163.654994 -269.160498)
		(end 173.693836 -269.160498)
		(width 0.14478)
		(layer "In11.Cu")
		(net "M_L_CPU1_SB_CS_N<1>")
	)
	(segment
		(start 201.72299 -268.31036)
		(end 202.147932 -268.735302)
		(width 0.14478)
		(layer "In11.Cu")
		(net "M_L_CPU1_SB_CS_N<1>")
	)
	(segment
		(start 178.576478 -269.160498)
		(end 181.23789 -269.160498)
		(width 0.14478)
		(layer "In11.Cu")
		(net "M_L_CPU1_SB_CS_N<1>")
	)
	(segment
		(start 173.693836 -269.160498)
		(end 174.543974 -268.31036)
		(width 0.14478)
		(layer "In11.Cu")
		(net "M_L_CPU1_SB_CS_N<1>")
	)
	(segment
		(start 177.72634 -268.31036)
		(end 178.576478 -269.160498)
		(width 0.14478)
		(layer "In11.Cu")
		(net "M_L_CPU1_SB_CS_N<1>")
	)
	(segment
		(start 140.453364 -266.46886)
		(end 140.461746 -266.473686)
		(width 0.0889)
		(layer "In11.Cu")
		(net "M_L_CPU1_SB_CS_N<1>")
	)
	(segment
		(start 160.1978 -265.703304)
		(end 163.654994 -269.160498)
		(width 0.14478)
		(layer "In11.Cu")
		(net "M_L_CPU1_SB_CS_N<1>")
	)
	(segment
		(start 199.437752 -268.16558)
		(end 199.437752 -268.089126)
		(width 0.14478)
		(layer "In11.Cu")
		(net "M_L_CPU1_SB_CS_N<1>")
	)
	(segment
		(start 199.844406 -267.944346)
		(end 199.989186 -268.089126)
		(width 0.14478)
		(layer "In11.Cu")
		(net "M_L_CPU1_SB_CS_N<1>")
	)
	(segment
		(start 147.602448 -265.703304)
		(end 147.965922 -265.703304)
		(width 0.0889)
		(layer "In11.Cu")
		(net "M_L_CPU1_SB_CS_N<1>")
	)
	(segment
		(start 188.781944 -269.160498)
		(end 189.632082 -268.31036)
		(width 0.14478)
		(layer "In11.Cu")
		(net "M_L_CPU1_SB_CS_N<1>")
	)
	(segment
		(start 144.881092 -266.434824)
		(end 145.14703 -266.366752)
		(width 0.0889)
		(layer "In11.Cu")
		(net "M_L_CPU1_SB_CS_N<1>")
	)
	(segment
		(start 174.543974 -268.31036)
		(end 177.72634 -268.31036)
		(width 0.14478)
		(layer "In11.Cu")
		(net "M_L_CPU1_SB_CS_N<1>")
	)
	(segment
		(start 199.989186 -268.531594)
		(end 200.133966 -268.676374)
		(width 0.14478)
		(layer "In11.Cu")
		(net "M_L_CPU1_SB_CS_N<1>")
	)
	(segment
		(start 200.947274 -267.944346)
		(end 201.092054 -268.089126)
		(width 0.14478)
		(layer "In11.Cu")
		(net "M_L_CPU1_SB_CS_N<1>")
	)
	(segment
		(start 144.205198 -266.464542)
		(end 144.221454 -266.47394)
		(width 0.0889)
		(layer "In11.Cu")
		(net "M_L_CPU1_SB_CS_N<1>")
	)
	(segment
		(start 147.965922 -265.703304)
		(end 160.1978 -265.703304)
		(width 0.14478)
		(layer "In11.Cu")
		(net "M_L_CPU1_SB_CS_N<1>")
	)
	(segment
		(start 200.39584 -268.676374)
		(end 200.54062 -268.531594)
		(width 0.14478)
		(layer "In11.Cu")
		(net "M_L_CPU1_SB_CS_N<1>")
	)
	(segment
		(start 182.088028 -268.31036)
		(end 185.270394 -268.31036)
		(width 0.14478)
		(layer "In11.Cu")
		(net "M_L_CPU1_SB_CS_N<1>")
	)
	(segment
		(start 146.35861 -265.582146)
		(end 147.48129 -265.582146)
		(width 0.0889)
		(layer "In11.Cu")
		(net "M_L_CPU1_SB_CS_N<1>")
	)
	(segment
		(start 181.23789 -269.160498)
		(end 182.088028 -268.31036)
		(width 0.14478)
		(layer "In11.Cu")
		(net "M_L_CPU1_SB_CS_N<1>")
	)
	(segment
		(start 145.14703 -266.366752)
		(end 145.574004 -266.366752)
		(width 0.0889)
		(layer "In11.Cu")
		(net "M_L_CPU1_SB_CS_N<1>")
	)
	(segment
		(start 145.574004 -266.366752)
		(end 146.35861 -265.582146)
		(width 0.0889)
		(layer "In11.Cu")
		(net "M_L_CPU1_SB_CS_N<1>")
	)
	(segment
		(start 144.786604 -266.473686)
		(end 144.798288 -266.466828)
		(width 0.0889)
		(layer "In11.Cu")
		(net "M_L_CPU1_SB_CS_N<1>")
	)
	(segment
		(start 199.292972 -268.31036)
		(end 199.437752 -268.16558)
		(width 0.14478)
		(layer "In11.Cu")
		(net "M_L_CPU1_SB_CS_N<1>")
	)
	(segment
		(start 185.270394 -268.31036)
		(end 186.120532 -269.160498)
		(width 0.14478)
		(layer "In11.Cu")
		(net "M_L_CPU1_SB_CS_N<1>")
	)
	(segment
		(start 139.334748 -266.796266)
		(end 139.488672 -266.530836)
		(width 0.0889)
		(layer "In11.Cu")
		(net "M_L_CPU1_SB_CS_N<1>")
	)
	(segment
		(start 201.092054 -268.16558)
		(end 201.236834 -268.31036)
		(width 0.14478)
		(layer "In11.Cu")
		(net "M_L_CPU1_SB_CS_N<1>")
	)
	(segment
		(start 144.221454 -266.47394)
		(end 144.233392 -266.480798)
		(width 0.0889)
		(layer "In11.Cu")
		(net "M_L_CPU1_SB_CS_N<1>")
	)
	(segment
		(start 141.967712 -266.473686)
		(end 141.976094 -266.46886)
		(width 0.0889)
		(layer "In11.Cu")
		(net "M_L_CPU1_SB_CS_N<1>")
	)
	(segment
		(start 189.632082 -268.31036)
		(end 199.292972 -268.31036)
		(width 0.14478)
		(layer "In11.Cu")
		(net "M_L_CPU1_SB_CS_N<1>")
	)
	(segment
		(start 186.120532 -269.160498)
		(end 188.781944 -269.160498)
		(width 0.14478)
		(layer "In11.Cu")
		(net "M_L_CPU1_SB_CS_N<1>")
	)
	(segment
		(start 201.236834 -268.31036)
		(end 201.72299 -268.31036)
		(width 0.14478)
		(layer "In11.Cu")
		(net "M_L_CPU1_SB_CS_N<1>")
	)
	(segment
		(start 200.54062 -268.531594)
		(end 200.54062 -268.089126)
		(width 0.14478)
		(layer "In11.Cu")
		(net "M_L_CPU1_SB_CS_N<1>")
	)
	(segment
		(start 141.393418 -266.46886)
		(end 141.4018 -266.473686)
		(width 0.0889)
		(layer "In11.Cu")
		(net "M_L_CPU1_SB_CS_N<1>")
	)
	(segment
		(start 199.437752 -268.089126)
		(end 199.582532 -267.944346)
		(width 0.14478)
		(layer "In11.Cu")
		(net "M_L_CPU1_SB_CS_N<1>")
	)
	(segment
		(start 147.48129 -265.582146)
		(end 147.602448 -265.703304)
		(width 0.0889)
		(layer "In11.Cu")
		(net "M_L_CPU1_SB_CS_N<1>")
	)
	(segment
		(start 139.488672 -266.530836)
		(end 139.584684 -266.505436)
		(width 0.0889)
		(layer "In11.Cu")
		(net "M_L_CPU1_SB_CS_N<1>")
	)
	(segment
		(start 199.989186 -268.089126)
		(end 199.989186 -268.531594)
		(width 0.14478)
		(layer "In11.Cu")
		(net "M_L_CPU1_SB_CS_N<1>")
	)
	(segment
		(start 200.54062 -268.089126)
		(end 200.6854 -267.944346)
		(width 0.14478)
		(layer "In11.Cu")
		(net "M_L_CPU1_SB_CS_N<1>")
	)
	(segment
		(start 200.6854 -267.944346)
		(end 200.947274 -267.944346)
		(width 0.14478)
		(layer "In11.Cu")
		(net "M_L_CPU1_SB_CS_N<1>")
	)
	(segment
		(start 200.133966 -268.676374)
		(end 200.39584 -268.676374)
		(width 0.14478)
		(layer "In11.Cu")
		(net "M_L_CPU1_SB_CS_N<1>")
	)
	(segment
		(start 199.582532 -267.944346)
		(end 199.844406 -267.944346)
		(width 0.14478)
		(layer "In11.Cu")
		(net "M_L_CPU1_SB_CS_N<1>")
	)
	(segment
		(start 201.092054 -268.089126)
		(end 201.092054 -268.16558)
		(width 0.14478)
		(layer "In11.Cu")
		(net "M_L_CPU1_SB_CS_N<1>")
	)
	(arc
		(start 143.847566 -266.473686)
		(mid 144.025216 -266.423426)
		(end 144.205198 -266.464542)
		(width 0.0889)
		(layer "In11.Cu")
		(net "M_L_CPU1_SB_CS_N<1>")
	)
	(arc
		(start 143.281654 -266.473686)
		(mid 143.56461 -266.549863)
		(end 143.847566 -266.473686)
		(width 0.0889)
		(layer "In11.Cu")
		(net "M_L_CPU1_SB_CS_N<1>")
	)
	(arc
		(start 139.584684 -266.505436)
		(mid 139.839892 -266.548913)
		(end 140.087604 -266.473686)
		(width 0.0889)
		(layer "In11.Cu")
		(net "M_L_CPU1_SB_CS_N<1>")
	)
	(arc
		(start 141.027658 -266.473686)
		(mid 141.209909 -266.423336)
		(end 141.393418 -266.46886)
		(width 0.0889)
		(layer "In11.Cu")
		(net "M_L_CPU1_SB_CS_N<1>")
	)
	(arc
		(start 144.798288 -266.466828)
		(mid 144.838731 -266.448344)
		(end 144.881092 -266.434824)
		(width 0.0889)
		(layer "In11.Cu")
		(net "M_L_CPU1_SB_CS_N<1>")
	)
	(arc
		(start 141.4018 -266.473686)
		(mid 141.684756 -266.549863)
		(end 141.967712 -266.473686)
		(width 0.0889)
		(layer "In11.Cu")
		(net "M_L_CPU1_SB_CS_N<1>")
	)
	(arc
		(start 144.233392 -266.480798)
		(mid 144.510926 -266.549779)
		(end 144.786604 -266.473686)
		(width 0.0889)
		(layer "In11.Cu")
		(net "M_L_CPU1_SB_CS_N<1>")
	)
	(arc
		(start 140.461746 -266.473686)
		(mid 140.744702 -266.549863)
		(end 141.027658 -266.473686)
		(width 0.0889)
		(layer "In11.Cu")
		(net "M_L_CPU1_SB_CS_N<1>")
	)
	(arc
		(start 141.976094 -266.46886)
		(mid 142.159602 -266.423366)
		(end 142.341854 -266.473686)
		(width 0.0889)
		(layer "In11.Cu")
		(net "M_L_CPU1_SB_CS_N<1>")
	)
	(arc
		(start 142.341854 -266.473686)
		(mid 142.62481 -266.549863)
		(end 142.907766 -266.473686)
		(width 0.0889)
		(layer "In11.Cu")
		(net "M_L_CPU1_SB_CS_N<1>")
	)
	(arc
		(start 142.907766 -266.473686)
		(mid 143.09471 -266.423431)
		(end 143.281654 -266.473686)
		(width 0.0889)
		(layer "In11.Cu")
		(net "M_L_CPU1_SB_CS_N<1>")
	)
	(arc
		(start 140.087604 -266.473686)
		(mid 140.269855 -266.423336)
		(end 140.453364 -266.46886)
		(width 0.0889)
		(layer "In11.Cu")
		(net "M_L_CPU1_SB_CS_N<1>")
	)
	(segment
		(start 137.457942 -265.720322)
		(end 137.924794 -265.98626)
		(width 0.10668)
		(layer "F.Cu")
		(net "M_L_CPU1_SB_CS_N<0>")
	)
	(segment
		(start 186.055254 -268.31036)
		(end 188.874908 -268.31036)
		(width 0.14478)
		(layer "In11.Cu")
		(net "M_L_CPU1_SB_CS_N<0>")
	)
	(segment
		(start 143.751808 -265.66368)
		(end 143.775176 -265.677396)
		(width 0.0889)
		(layer "In11.Cu")
		(net "M_L_CPU1_SB_CS_N<0>")
	)
	(segment
		(start 140.557758 -265.66368)
		(end 140.56614 -265.658854)
		(width 0.0889)
		(layer "In11.Cu")
		(net "M_L_CPU1_SB_CS_N<0>")
	)
	(segment
		(start 139.617704 -265.66368)
		(end 139.626086 -265.658854)
		(width 0.0889)
		(layer "In11.Cu")
		(net "M_L_CPU1_SB_CS_N<0>")
	)
	(segment
		(start 188.874908 -268.31036)
		(end 189.724792 -267.460476)
		(width 0.14478)
		(layer "In11.Cu")
		(net "M_L_CPU1_SB_CS_N<0>")
	)
	(segment
		(start 143.377666 -265.66368)
		(end 143.386048 -265.658854)
		(width 0.0889)
		(layer "In11.Cu")
		(net "M_L_CPU1_SB_CS_N<0>")
	)
	(segment
		(start 147.47621 -265.295126)
		(end 147.522692 -265.248644)
		(width 0.0889)
		(layer "In11.Cu")
		(net "M_L_CPU1_SB_CS_N<0>")
	)
	(segment
		(start 145.76425 -265.613642)
		(end 146.082766 -265.295126)
		(width 0.0889)
		(layer "In11.Cu")
		(net "M_L_CPU1_SB_CS_N<0>")
	)
	(segment
		(start 189.724792 -267.460476)
		(end 205.823058 -267.460476)
		(width 0.14478)
		(layer "In11.Cu")
		(net "M_L_CPU1_SB_CS_N<0>")
	)
	(segment
		(start 147.988782 -265.248644)
		(end 160.49117 -265.248644)
		(width 0.14478)
		(layer "In11.Cu")
		(net "M_L_CPU1_SB_CS_N<0>")
	)
	(segment
		(start 182.180738 -267.460476)
		(end 185.20537 -267.460476)
		(width 0.14478)
		(layer "In11.Cu")
		(net "M_L_CPU1_SB_CS_N<0>")
	)
	(segment
		(start 145.236946 -265.67638)
		(end 145.258536 -265.663934)
		(width 0.0889)
		(layer "In11.Cu")
		(net "M_L_CPU1_SB_CS_N<0>")
	)
	(segment
		(start 205.823058 -267.460476)
		(end 206.248 -267.885418)
		(width 0.14478)
		(layer "In11.Cu")
		(net "M_L_CPU1_SB_CS_N<0>")
	)
	(segment
		(start 160.49117 -265.248644)
		(end 163.552886 -268.31036)
		(width 0.14478)
		(layer "In11.Cu")
		(net "M_L_CPU1_SB_CS_N<0>")
	)
	(segment
		(start 145.444718 -265.613642)
		(end 145.76425 -265.613642)
		(width 0.0889)
		(layer "In11.Cu")
		(net "M_L_CPU1_SB_CS_N<0>")
	)
	(segment
		(start 139.04341 -265.658854)
		(end 139.051792 -265.66368)
		(width 0.0889)
		(layer "In11.Cu")
		(net "M_L_CPU1_SB_CS_N<0>")
	)
	(segment
		(start 138.078718 -265.72083)
		(end 138.17473 -265.69543)
		(width 0.0889)
		(layer "In11.Cu")
		(net "M_L_CPU1_SB_CS_N<0>")
	)
	(segment
		(start 181.330854 -268.31036)
		(end 182.180738 -267.460476)
		(width 0.14478)
		(layer "In11.Cu")
		(net "M_L_CPU1_SB_CS_N<0>")
	)
	(segment
		(start 147.522692 -265.248644)
		(end 147.988782 -265.248644)
		(width 0.0889)
		(layer "In11.Cu")
		(net "M_L_CPU1_SB_CS_N<0>")
	)
	(segment
		(start 178.5112 -268.31036)
		(end 181.330854 -268.31036)
		(width 0.14478)
		(layer "In11.Cu")
		(net "M_L_CPU1_SB_CS_N<0>")
	)
	(segment
		(start 173.7868 -268.31036)
		(end 174.636684 -267.460476)
		(width 0.14478)
		(layer "In11.Cu")
		(net "M_L_CPU1_SB_CS_N<0>")
	)
	(segment
		(start 146.082766 -265.295126)
		(end 147.47621 -265.295126)
		(width 0.0889)
		(layer "In11.Cu")
		(net "M_L_CPU1_SB_CS_N<0>")
	)
	(segment
		(start 137.924794 -265.98626)
		(end 138.078718 -265.72083)
		(width 0.0889)
		(layer "In11.Cu")
		(net "M_L_CPU1_SB_CS_N<0>")
	)
	(segment
		(start 142.803372 -265.658854)
		(end 142.811754 -265.66368)
		(width 0.0889)
		(layer "In11.Cu")
		(net "M_L_CPU1_SB_CS_N<0>")
	)
	(segment
		(start 144.67967 -265.655298)
		(end 144.694148 -265.66368)
		(width 0.0889)
		(layer "In11.Cu")
		(net "M_L_CPU1_SB_CS_N<0>")
	)
	(segment
		(start 177.661316 -267.460476)
		(end 178.5112 -268.31036)
		(width 0.14478)
		(layer "In11.Cu")
		(net "M_L_CPU1_SB_CS_N<0>")
	)
	(segment
		(start 185.20537 -267.460476)
		(end 186.055254 -268.31036)
		(width 0.14478)
		(layer "In11.Cu")
		(net "M_L_CPU1_SB_CS_N<0>")
	)
	(segment
		(start 174.636684 -267.460476)
		(end 177.661316 -267.460476)
		(width 0.14478)
		(layer "In11.Cu")
		(net "M_L_CPU1_SB_CS_N<0>")
	)
	(segment
		(start 163.552886 -268.31036)
		(end 173.7868 -268.31036)
		(width 0.14478)
		(layer "In11.Cu")
		(net "M_L_CPU1_SB_CS_N<0>")
	)
	(arc
		(start 145.258536 -265.663934)
		(mid 145.348313 -265.626511)
		(end 145.444718 -265.613642)
		(width 0.0889)
		(layer "In11.Cu")
		(net "M_L_CPU1_SB_CS_N<0>")
	)
	(arc
		(start 143.775176 -265.677396)
		(mid 144.04883 -265.740339)
		(end 144.31899 -265.66368)
		(width 0.0889)
		(layer "In11.Cu")
		(net "M_L_CPU1_SB_CS_N<0>")
	)
	(arc
		(start 141.497812 -265.66368)
		(mid 141.684756 -265.613425)
		(end 141.8717 -265.66368)
		(width 0.0889)
		(layer "In11.Cu")
		(net "M_L_CPU1_SB_CS_N<0>")
	)
	(arc
		(start 140.9319 -265.66368)
		(mid 141.214856 -265.739857)
		(end 141.497812 -265.66368)
		(width 0.0889)
		(layer "In11.Cu")
		(net "M_L_CPU1_SB_CS_N<0>")
	)
	(arc
		(start 144.694148 -265.66368)
		(mid 144.963917 -265.739703)
		(end 145.236946 -265.67638)
		(width 0.0889)
		(layer "In11.Cu")
		(net "M_L_CPU1_SB_CS_N<0>")
	)
	(arc
		(start 144.31899 -265.66368)
		(mid 144.498253 -265.613016)
		(end 144.67967 -265.655298)
		(width 0.0889)
		(layer "In11.Cu")
		(net "M_L_CPU1_SB_CS_N<0>")
	)
	(arc
		(start 139.626086 -265.658854)
		(mid 139.809594 -265.61336)
		(end 139.991846 -265.66368)
		(width 0.0889)
		(layer "In11.Cu")
		(net "M_L_CPU1_SB_CS_N<0>")
	)
	(arc
		(start 138.67765 -265.66368)
		(mid 138.859901 -265.61333)
		(end 139.04341 -265.658854)
		(width 0.0889)
		(layer "In11.Cu")
		(net "M_L_CPU1_SB_CS_N<0>")
	)
	(arc
		(start 142.437612 -265.66368)
		(mid 142.619863 -265.61333)
		(end 142.803372 -265.658854)
		(width 0.0889)
		(layer "In11.Cu")
		(net "M_L_CPU1_SB_CS_N<0>")
	)
	(arc
		(start 141.8717 -265.66368)
		(mid 142.154656 -265.739857)
		(end 142.437612 -265.66368)
		(width 0.0889)
		(layer "In11.Cu")
		(net "M_L_CPU1_SB_CS_N<0>")
	)
	(arc
		(start 143.386048 -265.658854)
		(mid 143.569556 -265.61336)
		(end 143.751808 -265.66368)
		(width 0.0889)
		(layer "In11.Cu")
		(net "M_L_CPU1_SB_CS_N<0>")
	)
	(arc
		(start 142.811754 -265.66368)
		(mid 143.09471 -265.739857)
		(end 143.377666 -265.66368)
		(width 0.0889)
		(layer "In11.Cu")
		(net "M_L_CPU1_SB_CS_N<0>")
	)
	(arc
		(start 140.56614 -265.658854)
		(mid 140.749648 -265.61336)
		(end 140.9319 -265.66368)
		(width 0.0889)
		(layer "In11.Cu")
		(net "M_L_CPU1_SB_CS_N<0>")
	)
	(arc
		(start 139.051792 -265.66368)
		(mid 139.334748 -265.739857)
		(end 139.617704 -265.66368)
		(width 0.0889)
		(layer "In11.Cu")
		(net "M_L_CPU1_SB_CS_N<0>")
	)
	(arc
		(start 139.991846 -265.66368)
		(mid 140.274802 -265.739857)
		(end 140.557758 -265.66368)
		(width 0.0889)
		(layer "In11.Cu")
		(net "M_L_CPU1_SB_CS_N<0>")
	)
	(arc
		(start 138.17473 -265.69543)
		(mid 138.429938 -265.738907)
		(end 138.67765 -265.66368)
		(width 0.0889)
		(layer "In11.Cu")
		(net "M_L_CPU1_SB_CS_N<0>")
	)
	(segment
		(start 137.457942 -270.580358)
		(end 137.924794 -270.846296)
		(width 0.10668)
		(layer "F.Cu")
		(net "M_L_CPU1_SB_CB<7>")
	)
	(segment
		(start 173.7868 -274.26031)
		(end 174.636684 -273.410426)
		(width 0.14478)
		(layer "In11.Cu")
		(net "M_L_CPU1_SB_CB<7>")
	)
	(segment
		(start 142.803372 -270.51889)
		(end 142.811754 -270.523716)
		(width 0.0889)
		(layer "In11.Cu")
		(net "M_L_CPU1_SB_CB<7>")
	)
	(segment
		(start 144.317974 -270.523716)
		(end 144.31772 -270.523716)
		(width 0.0889)
		(layer "In11.Cu")
		(net "M_L_CPU1_SB_CB<7>")
	)
	(segment
		(start 197.17131 -273.410172)
		(end 197.31609 -273.554952)
		(width 0.14478)
		(layer "In11.Cu")
		(net "M_L_CPU1_SB_CB<7>")
	)
	(segment
		(start 143.751808 -270.523716)
		(end 143.762222 -270.529812)
		(width 0.0889)
		(layer "In11.Cu")
		(net "M_L_CPU1_SB_CB<7>")
	)
	(segment
		(start 182.180738 -273.410426)
		(end 185.20537 -273.410426)
		(width 0.14478)
		(layer "In11.Cu")
		(net "M_L_CPU1_SB_CB<7>")
	)
	(segment
		(start 163.588446 -274.281646)
		(end 166.79037 -274.281646)
		(width 0.14478)
		(layer "In11.Cu")
		(net "M_L_CPU1_SB_CB<7>")
	)
	(segment
		(start 189.724792 -273.410426)
		(end 192.38341 -273.410426)
		(width 0.14478)
		(layer "In11.Cu")
		(net "M_L_CPU1_SB_CB<7>")
	)
	(segment
		(start 171.72559 -274.26031)
		(end 173.7868 -274.26031)
		(width 0.14478)
		(layer "In11.Cu")
		(net "M_L_CPU1_SB_CB<7>")
	)
	(segment
		(start 193.371978 -274.147026)
		(end 193.633852 -274.147026)
		(width 0.14478)
		(layer "In11.Cu")
		(net "M_L_CPU1_SB_CB<7>")
	)
	(segment
		(start 198.012304 -273.410172)
		(end 200.872852 -273.410172)
		(width 0.14478)
		(layer "In11.Cu")
		(net "M_L_CPU1_SB_CB<7>")
	)
	(segment
		(start 196.764656 -273.554952)
		(end 196.909436 -273.410172)
		(width 0.14478)
		(layer "In11.Cu")
		(net "M_L_CPU1_SB_CB<7>")
	)
	(segment
		(start 197.722744 -274.192746)
		(end 197.867524 -274.047966)
		(width 0.14478)
		(layer "In11.Cu")
		(net "M_L_CPU1_SB_CB<7>")
	)
	(segment
		(start 197.31609 -274.047966)
		(end 197.46087 -274.192746)
		(width 0.14478)
		(layer "In11.Cu")
		(net "M_L_CPU1_SB_CB<7>")
	)
	(segment
		(start 140.557758 -270.523716)
		(end 140.56614 -270.51889)
		(width 0.0889)
		(layer "In11.Cu")
		(net "M_L_CPU1_SB_CB<7>")
	)
	(segment
		(start 195.806568 -273.410172)
		(end 196.068442 -273.410172)
		(width 0.14478)
		(layer "In11.Cu")
		(net "M_L_CPU1_SB_CB<7>")
	)
	(segment
		(start 166.79037 -274.281646)
		(end 166.849298 -274.222718)
		(width 0.14478)
		(layer "In11.Cu")
		(net "M_L_CPU1_SB_CB<7>")
	)
	(segment
		(start 195.517008 -274.192746)
		(end 195.661788 -274.047966)
		(width 0.14478)
		(layer "In11.Cu")
		(net "M_L_CPU1_SB_CB<7>")
	)
	(segment
		(start 193.633852 -274.147026)
		(end 193.778632 -274.002246)
		(width 0.14478)
		(layer "In11.Cu")
		(net "M_L_CPU1_SB_CB<7>")
	)
	(segment
		(start 146.611848 -268.856206)
		(end 147.35429 -268.856206)
		(width 0.0889)
		(layer "In11.Cu")
		(net "M_L_CPU1_SB_CB<7>")
	)
	(segment
		(start 166.849298 -274.222718)
		(end 171.687998 -274.222718)
		(width 0.14478)
		(layer "In11.Cu")
		(net "M_L_CPU1_SB_CB<7>")
	)
	(segment
		(start 139.04341 -270.51889)
		(end 139.051792 -270.523716)
		(width 0.0889)
		(layer "In11.Cu")
		(net "M_L_CPU1_SB_CB<7>")
	)
	(segment
		(start 192.38341 -273.410426)
		(end 192.383664 -273.410172)
		(width 0.14478)
		(layer "In11.Cu")
		(net "M_L_CPU1_SB_CB<7>")
	)
	(segment
		(start 148.040344 -268.680184)
		(end 157.986984 -268.680184)
		(width 0.14478)
		(layer "In11.Cu")
		(net "M_L_CPU1_SB_CB<7>")
	)
	(segment
		(start 138.078718 -270.580866)
		(end 138.17473 -270.555466)
		(width 0.0889)
		(layer "In11.Cu")
		(net "M_L_CPU1_SB_CB<7>")
	)
	(segment
		(start 145.15338 -269.708884)
		(end 145.161762 -269.71371)
		(width 0.0889)
		(layer "In11.Cu")
		(net "M_L_CPU1_SB_CB<7>")
	)
	(segment
		(start 193.082418 -273.410172)
		(end 193.227198 -273.554952)
		(width 0.14478)
		(layer "In11.Cu")
		(net "M_L_CPU1_SB_CB<7>")
	)
	(segment
		(start 137.924794 -270.846296)
		(end 138.078718 -270.580866)
		(width 0.0889)
		(layer "In11.Cu")
		(net "M_L_CPU1_SB_CB<7>")
	)
	(segment
		(start 194.965574 -273.410172)
		(end 195.110354 -273.554952)
		(width 0.14478)
		(layer "In11.Cu")
		(net "M_L_CPU1_SB_CB<7>")
	)
	(segment
		(start 197.46087 -274.192746)
		(end 197.722744 -274.192746)
		(width 0.14478)
		(layer "In11.Cu")
		(net "M_L_CPU1_SB_CB<7>")
	)
	(segment
		(start 195.661788 -273.554952)
		(end 195.806568 -273.410172)
		(width 0.14478)
		(layer "In11.Cu")
		(net "M_L_CPU1_SB_CB<7>")
	)
	(segment
		(start 196.358002 -274.192746)
		(end 196.619876 -274.192746)
		(width 0.14478)
		(layer "In11.Cu")
		(net "M_L_CPU1_SB_CB<7>")
	)
	(segment
		(start 177.661316 -273.410426)
		(end 178.5112 -274.26031)
		(width 0.14478)
		(layer "In11.Cu")
		(net "M_L_CPU1_SB_CB<7>")
	)
	(segment
		(start 200.872852 -273.410172)
		(end 202.147932 -274.685252)
		(width 0.14478)
		(layer "In11.Cu")
		(net "M_L_CPU1_SB_CB<7>")
	)
	(segment
		(start 181.330854 -274.26031)
		(end 182.180738 -273.410426)
		(width 0.14478)
		(layer "In11.Cu")
		(net "M_L_CPU1_SB_CB<7>")
	)
	(segment
		(start 171.687998 -274.222718)
		(end 171.72559 -274.26031)
		(width 0.14478)
		(layer "In11.Cu")
		(net "M_L_CPU1_SB_CB<7>")
	)
	(segment
		(start 192.383664 -273.410172)
		(end 193.082418 -273.410172)
		(width 0.14478)
		(layer "In11.Cu")
		(net "M_L_CPU1_SB_CB<7>")
	)
	(segment
		(start 196.213222 -273.554952)
		(end 196.213222 -274.047966)
		(width 0.14478)
		(layer "In11.Cu")
		(net "M_L_CPU1_SB_CB<7>")
	)
	(segment
		(start 193.923412 -273.410172)
		(end 194.965574 -273.410172)
		(width 0.14478)
		(layer "In11.Cu")
		(net "M_L_CPU1_SB_CB<7>")
	)
	(segment
		(start 139.617704 -270.523716)
		(end 139.626086 -270.51889)
		(width 0.0889)
		(layer "In11.Cu")
		(net "M_L_CPU1_SB_CB<7>")
	)
	(segment
		(start 186.055254 -274.26031)
		(end 188.874908 -274.26031)
		(width 0.14478)
		(layer "In11.Cu")
		(net "M_L_CPU1_SB_CB<7>")
	)
	(segment
		(start 196.619876 -274.192746)
		(end 196.764656 -274.047966)
		(width 0.14478)
		(layer "In11.Cu")
		(net "M_L_CPU1_SB_CB<7>")
	)
	(segment
		(start 196.764656 -274.047966)
		(end 196.764656 -273.554952)
		(width 0.14478)
		(layer "In11.Cu")
		(net "M_L_CPU1_SB_CB<7>")
	)
	(segment
		(start 147.530312 -268.680184)
		(end 148.040344 -268.680184)
		(width 0.0889)
		(layer "In11.Cu")
		(net "M_L_CPU1_SB_CB<7>")
	)
	(segment
		(start 145.843244 -269.62481)
		(end 146.611848 -268.856206)
		(width 0.0889)
		(layer "In11.Cu")
		(net "M_L_CPU1_SB_CB<7>")
	)
	(segment
		(start 197.31609 -273.554952)
		(end 197.31609 -274.047966)
		(width 0.14478)
		(layer "In11.Cu")
		(net "M_L_CPU1_SB_CB<7>")
	)
	(segment
		(start 147.35429 -268.856206)
		(end 147.530312 -268.680184)
		(width 0.0889)
		(layer "In11.Cu")
		(net "M_L_CPU1_SB_CB<7>")
	)
	(segment
		(start 193.227198 -274.002246)
		(end 193.371978 -274.147026)
		(width 0.14478)
		(layer "In11.Cu")
		(net "M_L_CPU1_SB_CB<7>")
	)
	(segment
		(start 197.867524 -273.554952)
		(end 198.012304 -273.410172)
		(width 0.14478)
		(layer "In11.Cu")
		(net "M_L_CPU1_SB_CB<7>")
	)
	(segment
		(start 195.255134 -274.192746)
		(end 195.517008 -274.192746)
		(width 0.14478)
		(layer "In11.Cu")
		(net "M_L_CPU1_SB_CB<7>")
	)
	(segment
		(start 174.636684 -273.410426)
		(end 177.661316 -273.410426)
		(width 0.14478)
		(layer "In11.Cu")
		(net "M_L_CPU1_SB_CB<7>")
	)
	(segment
		(start 144.31772 -270.523716)
		(end 144.356836 -270.500856)
		(width 0.0889)
		(layer "In11.Cu")
		(net "M_L_CPU1_SB_CB<7>")
	)
	(segment
		(start 157.986984 -268.680184)
		(end 163.588446 -274.281646)
		(width 0.14478)
		(layer "In11.Cu")
		(net "M_L_CPU1_SB_CB<7>")
	)
	(segment
		(start 143.377666 -270.523716)
		(end 143.386048 -270.51889)
		(width 0.0889)
		(layer "In11.Cu")
		(net "M_L_CPU1_SB_CB<7>")
	)
	(segment
		(start 196.909436 -273.410172)
		(end 197.17131 -273.410172)
		(width 0.14478)
		(layer "In11.Cu")
		(net "M_L_CPU1_SB_CB<7>")
	)
	(segment
		(start 196.213222 -274.047966)
		(end 196.358002 -274.192746)
		(width 0.14478)
		(layer "In11.Cu")
		(net "M_L_CPU1_SB_CB<7>")
	)
	(segment
		(start 144.75714 -269.73149)
		(end 144.78762 -269.71371)
		(width 0.0889)
		(layer "In11.Cu")
		(net "M_L_CPU1_SB_CB<7>")
	)
	(segment
		(start 195.110354 -274.047966)
		(end 195.255134 -274.192746)
		(width 0.14478)
		(layer "In11.Cu")
		(net "M_L_CPU1_SB_CB<7>")
	)
	(segment
		(start 193.778632 -273.554952)
		(end 193.923412 -273.410172)
		(width 0.14478)
		(layer "In11.Cu")
		(net "M_L_CPU1_SB_CB<7>")
	)
	(segment
		(start 195.110354 -273.554952)
		(end 195.110354 -274.047966)
		(width 0.14478)
		(layer "In11.Cu")
		(net "M_L_CPU1_SB_CB<7>")
	)
	(segment
		(start 178.5112 -274.26031)
		(end 181.330854 -274.26031)
		(width 0.14478)
		(layer "In11.Cu")
		(net "M_L_CPU1_SB_CB<7>")
	)
	(segment
		(start 193.778632 -274.002246)
		(end 193.778632 -273.554952)
		(width 0.14478)
		(layer "In11.Cu")
		(net "M_L_CPU1_SB_CB<7>")
	)
	(segment
		(start 188.874908 -274.26031)
		(end 189.724792 -273.410426)
		(width 0.14478)
		(layer "In11.Cu")
		(net "M_L_CPU1_SB_CB<7>")
	)
	(segment
		(start 193.227198 -273.554952)
		(end 193.227198 -274.002246)
		(width 0.14478)
		(layer "In11.Cu")
		(net "M_L_CPU1_SB_CB<7>")
	)
	(segment
		(start 195.661788 -274.047966)
		(end 195.661788 -273.554952)
		(width 0.14478)
		(layer "In11.Cu")
		(net "M_L_CPU1_SB_CB<7>")
	)
	(segment
		(start 185.20537 -273.410426)
		(end 186.055254 -274.26031)
		(width 0.14478)
		(layer "In11.Cu")
		(net "M_L_CPU1_SB_CB<7>")
	)
	(segment
		(start 197.867524 -274.047966)
		(end 197.867524 -273.554952)
		(width 0.14478)
		(layer "In11.Cu")
		(net "M_L_CPU1_SB_CB<7>")
	)
	(segment
		(start 196.068442 -273.410172)
		(end 196.213222 -273.554952)
		(width 0.14478)
		(layer "In11.Cu")
		(net "M_L_CPU1_SB_CB<7>")
	)
	(arc
		(start 139.626086 -270.51889)
		(mid 139.809594 -270.473396)
		(end 139.991846 -270.523716)
		(width 0.0889)
		(layer "In11.Cu")
		(net "M_L_CPU1_SB_CB<7>")
	)
	(arc
		(start 143.386048 -270.51889)
		(mid 143.569556 -270.473396)
		(end 143.751808 -270.523716)
		(width 0.0889)
		(layer "In11.Cu")
		(net "M_L_CPU1_SB_CB<7>")
	)
	(arc
		(start 142.811754 -270.523716)
		(mid 143.09471 -270.599893)
		(end 143.377666 -270.523716)
		(width 0.0889)
		(layer "In11.Cu")
		(net "M_L_CPU1_SB_CB<7>")
	)
	(arc
		(start 140.9319 -270.523716)
		(mid 141.214856 -270.599893)
		(end 141.497812 -270.523716)
		(width 0.0889)
		(layer "In11.Cu")
		(net "M_L_CPU1_SB_CB<7>")
	)
	(arc
		(start 140.56614 -270.51889)
		(mid 140.749648 -270.473396)
		(end 140.9319 -270.523716)
		(width 0.0889)
		(layer "In11.Cu")
		(net "M_L_CPU1_SB_CB<7>")
	)
	(arc
		(start 138.67765 -270.523716)
		(mid 138.859901 -270.473366)
		(end 139.04341 -270.51889)
		(width 0.0889)
		(layer "In11.Cu")
		(net "M_L_CPU1_SB_CB<7>")
	)
	(arc
		(start 142.437612 -270.523716)
		(mid 142.619863 -270.473366)
		(end 142.803372 -270.51889)
		(width 0.0889)
		(layer "In11.Cu")
		(net "M_L_CPU1_SB_CB<7>")
	)
	(arc
		(start 139.051792 -270.523716)
		(mid 139.334748 -270.599893)
		(end 139.617704 -270.523716)
		(width 0.0889)
		(layer "In11.Cu")
		(net "M_L_CPU1_SB_CB<7>")
	)
	(arc
		(start 144.356836 -270.500856)
		(mid 144.535649 -270.298506)
		(end 144.600168 -270.03629)
		(width 0.0889)
		(layer "In11.Cu")
		(net "M_L_CPU1_SB_CB<7>")
	)
	(arc
		(start 144.78762 -269.71371)
		(mid 144.969871 -269.66336)
		(end 145.15338 -269.708884)
		(width 0.0889)
		(layer "In11.Cu")
		(net "M_L_CPU1_SB_CB<7>")
	)
	(arc
		(start 139.991846 -270.523716)
		(mid 140.274802 -270.599893)
		(end 140.557758 -270.523716)
		(width 0.0889)
		(layer "In11.Cu")
		(net "M_L_CPU1_SB_CB<7>")
	)
	(arc
		(start 145.161762 -269.71371)
		(mid 145.517622 -269.785152)
		(end 145.843244 -269.62481)
		(width 0.0889)
		(layer "In11.Cu")
		(net "M_L_CPU1_SB_CB<7>")
	)
	(arc
		(start 138.17473 -270.555466)
		(mid 138.429938 -270.598943)
		(end 138.67765 -270.523716)
		(width 0.0889)
		(layer "In11.Cu")
		(net "M_L_CPU1_SB_CB<7>")
	)
	(arc
		(start 144.600168 -270.03629)
		(mid 144.641717 -269.864868)
		(end 144.75714 -269.73149)
		(width 0.0889)
		(layer "In11.Cu")
		(net "M_L_CPU1_SB_CB<7>")
	)
	(arc
		(start 141.497812 -270.523716)
		(mid 141.684756 -270.473461)
		(end 141.8717 -270.523716)
		(width 0.0889)
		(layer "In11.Cu")
		(net "M_L_CPU1_SB_CB<7>")
	)
	(arc
		(start 141.8717 -270.523716)
		(mid 142.154656 -270.599893)
		(end 142.437612 -270.523716)
		(width 0.0889)
		(layer "In11.Cu")
		(net "M_L_CPU1_SB_CB<7>")
	)
	(arc
		(start 143.762222 -270.529812)
		(mid 144.040908 -270.600032)
		(end 144.317974 -270.523716)
		(width 0.0889)
		(layer "In11.Cu")
		(net "M_L_CPU1_SB_CB<7>")
	)
	(segment
		(start 138.867896 -269.770352)
		(end 139.334748 -270.03629)
		(width 0.10668)
		(layer "F.Cu")
		(net "M_L_CPU1_SB_CB<6>")
	)
	(segment
		(start 195.789042 -271.462246)
		(end 195.789042 -271.958562)
		(width 0.14478)
		(layer "In11.Cu")
		(net "M_L_CPU1_SB_CB<6>")
	)
	(segment
		(start 144.28597 -268.921992)
		(end 144.31772 -268.903704)
		(width 0.0889)
		(layer "In11.Cu")
		(net "M_L_CPU1_SB_CB<6>")
	)
	(segment
		(start 197.298564 -272.103342)
		(end 197.443344 -271.958562)
		(width 0.14478)
		(layer "In11.Cu")
		(net "M_L_CPU1_SB_CB<6>")
	)
	(segment
		(start 195.092828 -271.710404)
		(end 195.237608 -271.565624)
		(width 0.14478)
		(layer "In11.Cu")
		(net "M_L_CPU1_SB_CB<6>")
	)
	(segment
		(start 143.847566 -269.71371)
		(end 143.886682 -269.69085)
		(width 0.0889)
		(layer "In11.Cu")
		(net "M_L_CPU1_SB_CB<6>")
	)
	(segment
		(start 164.957252 -272.560288)
		(end 165.102032 -272.415508)
		(width 0.14478)
		(layer "In11.Cu")
		(net "M_L_CPU1_SB_CB<6>")
	)
	(segment
		(start 170.182032 -272.93951)
		(end 170.326812 -272.79473)
		(width 0.14478)
		(layer "In11.Cu")
		(net "M_L_CPU1_SB_CB<6>")
	)
	(segment
		(start 141.393418 -269.708884)
		(end 141.4018 -269.71371)
		(width 0.0889)
		(layer "In11.Cu")
		(net "M_L_CPU1_SB_CB<6>")
	)
	(segment
		(start 170.878246 -272.415508)
		(end 171.023026 -272.560288)
		(width 0.14478)
		(layer "In11.Cu")
		(net "M_L_CPU1_SB_CB<6>")
	)
	(segment
		(start 178.5112 -272.560288)
		(end 181.330854 -272.560288)
		(width 0.14478)
		(layer "In11.Cu")
		(net "M_L_CPU1_SB_CB<6>")
	)
	(segment
		(start 158.361888 -267.770864)
		(end 163.151312 -272.560288)
		(width 0.14478)
		(layer "In11.Cu")
		(net "M_L_CPU1_SB_CB<6>")
	)
	(segment
		(start 169.775378 -272.79473)
		(end 169.920158 -272.93951)
		(width 0.14478)
		(layer "In11.Cu")
		(net "M_L_CPU1_SB_CB<6>")
	)
	(segment
		(start 166.2049 -272.80489)
		(end 166.2049 -272.315686)
		(width 0.14478)
		(layer "In11.Cu")
		(net "M_L_CPU1_SB_CB<6>")
	)
	(segment
		(start 168.003982 -272.560288)
		(end 169.079164 -272.560288)
		(width 0.14478)
		(layer "In11.Cu")
		(net "M_L_CPU1_SB_CB<6>")
	)
	(segment
		(start 165.798246 -272.94967)
		(end 166.06012 -272.94967)
		(width 0.14478)
		(layer "In11.Cu")
		(net "M_L_CPU1_SB_CB<6>")
	)
	(segment
		(start 165.102032 -272.415508)
		(end 165.102032 -272.315686)
		(width 0.14478)
		(layer "In11.Cu")
		(net "M_L_CPU1_SB_CB<6>")
	)
	(segment
		(start 167.162988 -272.94967)
		(end 167.307768 -272.80489)
		(width 0.14478)
		(layer "In11.Cu")
		(net "M_L_CPU1_SB_CB<6>")
	)
	(segment
		(start 174.636684 -271.710404)
		(end 177.661316 -271.710404)
		(width 0.14478)
		(layer "In11.Cu")
		(net "M_L_CPU1_SB_CB<6>")
	)
	(segment
		(start 145.693638 -268.853158)
		(end 146.775932 -267.770864)
		(width 0.0889)
		(layer "In11.Cu")
		(net "M_L_CPU1_SB_CB<6>")
	)
	(segment
		(start 170.471592 -272.181066)
		(end 170.733466 -272.181066)
		(width 0.14478)
		(layer "In11.Cu")
		(net "M_L_CPU1_SB_CB<6>")
	)
	(segment
		(start 195.237608 -271.565624)
		(end 195.237608 -271.462246)
		(width 0.14478)
		(layer "In11.Cu")
		(net "M_L_CPU1_SB_CB<6>")
	)
	(segment
		(start 139.488672 -269.77086)
		(end 139.584684 -269.74546)
		(width 0.0889)
		(layer "In11.Cu")
		(net "M_L_CPU1_SB_CB<6>")
	)
	(segment
		(start 198.139558 -271.710404)
		(end 200.873106 -271.710404)
		(width 0.14478)
		(layer "In11.Cu")
		(net "M_L_CPU1_SB_CB<6>")
	)
	(segment
		(start 144.31772 -268.903704)
		(end 144.326102 -268.898878)
		(width 0.0889)
		(layer "In11.Cu")
		(net "M_L_CPU1_SB_CB<6>")
	)
	(segment
		(start 169.630598 -272.181066)
		(end 169.775378 -272.325846)
		(width 0.14478)
		(layer "In11.Cu")
		(net "M_L_CPU1_SB_CB<6>")
	)
	(segment
		(start 196.89191 -271.958562)
		(end 197.03669 -272.103342)
		(width 0.14478)
		(layer "In11.Cu")
		(net "M_L_CPU1_SB_CB<6>")
	)
	(segment
		(start 165.653466 -272.315686)
		(end 165.653466 -272.80489)
		(width 0.14478)
		(layer "In11.Cu")
		(net "M_L_CPU1_SB_CB<6>")
	)
	(segment
		(start 167.859202 -272.315686)
		(end 167.859202 -272.415508)
		(width 0.14478)
		(layer "In11.Cu")
		(net "M_L_CPU1_SB_CB<6>")
	)
	(segment
		(start 197.994778 -271.565624)
		(end 198.139558 -271.710404)
		(width 0.14478)
		(layer "In11.Cu")
		(net "M_L_CPU1_SB_CB<6>")
	)
	(segment
		(start 167.307768 -272.80489)
		(end 167.307768 -272.315686)
		(width 0.14478)
		(layer "In11.Cu")
		(net "M_L_CPU1_SB_CB<6>")
	)
	(segment
		(start 196.340476 -271.462246)
		(end 196.485256 -271.317466)
		(width 0.14478)
		(layer "In11.Cu")
		(net "M_L_CPU1_SB_CB<6>")
	)
	(segment
		(start 166.611554 -272.170906)
		(end 166.756334 -272.315686)
		(width 0.14478)
		(layer "In11.Cu")
		(net "M_L_CPU1_SB_CB<6>")
	)
	(segment
		(start 170.733466 -272.181066)
		(end 170.878246 -272.325846)
		(width 0.14478)
		(layer "In11.Cu")
		(net "M_L_CPU1_SB_CB<6>")
	)
	(segment
		(start 177.661316 -271.710404)
		(end 178.5112 -272.560288)
		(width 0.14478)
		(layer "In11.Cu")
		(net "M_L_CPU1_SB_CB<6>")
	)
	(segment
		(start 167.452548 -272.170906)
		(end 167.714422 -272.170906)
		(width 0.14478)
		(layer "In11.Cu")
		(net "M_L_CPU1_SB_CB<6>")
	)
	(segment
		(start 182.180738 -271.710404)
		(end 185.20537 -271.710404)
		(width 0.14478)
		(layer "In11.Cu")
		(net "M_L_CPU1_SB_CB<6>")
	)
	(segment
		(start 167.714422 -272.170906)
		(end 167.859202 -272.315686)
		(width 0.14478)
		(layer "In11.Cu")
		(net "M_L_CPU1_SB_CB<6>")
	)
	(segment
		(start 167.307768 -272.315686)
		(end 167.452548 -272.170906)
		(width 0.14478)
		(layer "In11.Cu")
		(net "M_L_CPU1_SB_CB<6>")
	)
	(segment
		(start 165.246812 -272.170906)
		(end 165.508686 -272.170906)
		(width 0.14478)
		(layer "In11.Cu")
		(net "M_L_CPU1_SB_CB<6>")
	)
	(segment
		(start 197.03669 -272.103342)
		(end 197.298564 -272.103342)
		(width 0.14478)
		(layer "In11.Cu")
		(net "M_L_CPU1_SB_CB<6>")
	)
	(segment
		(start 166.756334 -272.80489)
		(end 166.901114 -272.94967)
		(width 0.14478)
		(layer "In11.Cu")
		(net "M_L_CPU1_SB_CB<6>")
	)
	(segment
		(start 195.933822 -272.103342)
		(end 196.195696 -272.103342)
		(width 0.14478)
		(layer "In11.Cu")
		(net "M_L_CPU1_SB_CB<6>")
	)
	(segment
		(start 141.967712 -269.71371)
		(end 141.976094 -269.708884)
		(width 0.0889)
		(layer "In11.Cu")
		(net "M_L_CPU1_SB_CB<6>")
	)
	(segment
		(start 197.443344 -271.462246)
		(end 197.588124 -271.317466)
		(width 0.14478)
		(layer "In11.Cu")
		(net "M_L_CPU1_SB_CB<6>")
	)
	(segment
		(start 166.756334 -272.315686)
		(end 166.756334 -272.80489)
		(width 0.14478)
		(layer "In11.Cu")
		(net "M_L_CPU1_SB_CB<6>")
	)
	(segment
		(start 195.382388 -271.317466)
		(end 195.644262 -271.317466)
		(width 0.14478)
		(layer "In11.Cu")
		(net "M_L_CPU1_SB_CB<6>")
	)
	(segment
		(start 146.775932 -267.770864)
		(end 148.056854 -267.770864)
		(width 0.0889)
		(layer "In11.Cu")
		(net "M_L_CPU1_SB_CB<6>")
	)
	(segment
		(start 145.444718 -268.853158)
		(end 145.693638 -268.853158)
		(width 0.0889)
		(layer "In11.Cu")
		(net "M_L_CPU1_SB_CB<6>")
	)
	(segment
		(start 195.644262 -271.317466)
		(end 195.789042 -271.462246)
		(width 0.14478)
		(layer "In11.Cu")
		(net "M_L_CPU1_SB_CB<6>")
	)
	(segment
		(start 196.89191 -271.462246)
		(end 196.89191 -271.958562)
		(width 0.14478)
		(layer "In11.Cu")
		(net "M_L_CPU1_SB_CB<6>")
	)
	(segment
		(start 188.874908 -272.560288)
		(end 189.724792 -271.710404)
		(width 0.14478)
		(layer "In11.Cu")
		(net "M_L_CPU1_SB_CB<6>")
	)
	(segment
		(start 181.330854 -272.560288)
		(end 182.180738 -271.710404)
		(width 0.14478)
		(layer "In11.Cu")
		(net "M_L_CPU1_SB_CB<6>")
	)
	(segment
		(start 197.443344 -271.958562)
		(end 197.443344 -271.462246)
		(width 0.14478)
		(layer "In11.Cu")
		(net "M_L_CPU1_SB_CB<6>")
	)
	(segment
		(start 169.368724 -272.181066)
		(end 169.630598 -272.181066)
		(width 0.14478)
		(layer "In11.Cu")
		(net "M_L_CPU1_SB_CB<6>")
	)
	(segment
		(start 166.34968 -272.170906)
		(end 166.611554 -272.170906)
		(width 0.14478)
		(layer "In11.Cu")
		(net "M_L_CPU1_SB_CB<6>")
	)
	(segment
		(start 195.237608 -271.462246)
		(end 195.382388 -271.317466)
		(width 0.14478)
		(layer "In11.Cu")
		(net "M_L_CPU1_SB_CB<6>")
	)
	(segment
		(start 169.775378 -272.325846)
		(end 169.775378 -272.79473)
		(width 0.14478)
		(layer "In11.Cu")
		(net "M_L_CPU1_SB_CB<6>")
	)
	(segment
		(start 197.849998 -271.317466)
		(end 197.994778 -271.462246)
		(width 0.14478)
		(layer "In11.Cu")
		(net "M_L_CPU1_SB_CB<6>")
	)
	(segment
		(start 165.508686 -272.170906)
		(end 165.653466 -272.315686)
		(width 0.14478)
		(layer "In11.Cu")
		(net "M_L_CPU1_SB_CB<6>")
	)
	(segment
		(start 163.151312 -272.560288)
		(end 164.957252 -272.560288)
		(width 0.14478)
		(layer "In11.Cu")
		(net "M_L_CPU1_SB_CB<6>")
	)
	(segment
		(start 169.079164 -272.560288)
		(end 169.223944 -272.415508)
		(width 0.14478)
		(layer "In11.Cu")
		(net "M_L_CPU1_SB_CB<6>")
	)
	(segment
		(start 186.055254 -272.560288)
		(end 188.874908 -272.560288)
		(width 0.14478)
		(layer "In11.Cu")
		(net "M_L_CPU1_SB_CB<6>")
	)
	(segment
		(start 139.334748 -270.03629)
		(end 139.488672 -269.77086)
		(width 0.0889)
		(layer "In11.Cu")
		(net "M_L_CPU1_SB_CB<6>")
	)
	(segment
		(start 197.994778 -271.462246)
		(end 197.994778 -271.565624)
		(width 0.14478)
		(layer "In11.Cu")
		(net "M_L_CPU1_SB_CB<6>")
	)
	(segment
		(start 165.102032 -272.315686)
		(end 165.246812 -272.170906)
		(width 0.14478)
		(layer "In11.Cu")
		(net "M_L_CPU1_SB_CB<6>")
	)
	(segment
		(start 165.653466 -272.80489)
		(end 165.798246 -272.94967)
		(width 0.14478)
		(layer "In11.Cu")
		(net "M_L_CPU1_SB_CB<6>")
	)
	(segment
		(start 170.326812 -272.325846)
		(end 170.471592 -272.181066)
		(width 0.14478)
		(layer "In11.Cu")
		(net "M_L_CPU1_SB_CB<6>")
	)
	(segment
		(start 167.859202 -272.415508)
		(end 168.003982 -272.560288)
		(width 0.14478)
		(layer "In11.Cu")
		(net "M_L_CPU1_SB_CB<6>")
	)
	(segment
		(start 169.223944 -272.415508)
		(end 169.223944 -272.325846)
		(width 0.14478)
		(layer "In11.Cu")
		(net "M_L_CPU1_SB_CB<6>")
	)
	(segment
		(start 170.326812 -272.79473)
		(end 170.326812 -272.325846)
		(width 0.14478)
		(layer "In11.Cu")
		(net "M_L_CPU1_SB_CB<6>")
	)
	(segment
		(start 196.485256 -271.317466)
		(end 196.74713 -271.317466)
		(width 0.14478)
		(layer "In11.Cu")
		(net "M_L_CPU1_SB_CB<6>")
	)
	(segment
		(start 140.453364 -269.708884)
		(end 140.461746 -269.71371)
		(width 0.0889)
		(layer "In11.Cu")
		(net "M_L_CPU1_SB_CB<6>")
	)
	(segment
		(start 173.7868 -272.560288)
		(end 174.636684 -271.710404)
		(width 0.14478)
		(layer "In11.Cu")
		(net "M_L_CPU1_SB_CB<6>")
	)
	(segment
		(start 170.878246 -272.325846)
		(end 170.878246 -272.415508)
		(width 0.14478)
		(layer "In11.Cu")
		(net "M_L_CPU1_SB_CB<6>")
	)
	(segment
		(start 171.023026 -272.560288)
		(end 173.7868 -272.560288)
		(width 0.14478)
		(layer "In11.Cu")
		(net "M_L_CPU1_SB_CB<6>")
	)
	(segment
		(start 197.588124 -271.317466)
		(end 197.849998 -271.317466)
		(width 0.14478)
		(layer "In11.Cu")
		(net "M_L_CPU1_SB_CB<6>")
	)
	(segment
		(start 200.873106 -271.710404)
		(end 202.147932 -272.98523)
		(width 0.14478)
		(layer "In11.Cu")
		(net "M_L_CPU1_SB_CB<6>")
	)
	(segment
		(start 196.340476 -271.958562)
		(end 196.340476 -271.462246)
		(width 0.14478)
		(layer "In11.Cu")
		(net "M_L_CPU1_SB_CB<6>")
	)
	(segment
		(start 195.789042 -271.958562)
		(end 195.933822 -272.103342)
		(width 0.14478)
		(layer "In11.Cu")
		(net "M_L_CPU1_SB_CB<6>")
	)
	(segment
		(start 166.2049 -272.315686)
		(end 166.34968 -272.170906)
		(width 0.14478)
		(layer "In11.Cu")
		(net "M_L_CPU1_SB_CB<6>")
	)
	(segment
		(start 169.920158 -272.93951)
		(end 170.182032 -272.93951)
		(width 0.14478)
		(layer "In11.Cu")
		(net "M_L_CPU1_SB_CB<6>")
	)
	(segment
		(start 196.74713 -271.317466)
		(end 196.89191 -271.462246)
		(width 0.14478)
		(layer "In11.Cu")
		(net "M_L_CPU1_SB_CB<6>")
	)
	(segment
		(start 189.724792 -271.710404)
		(end 195.092828 -271.710404)
		(width 0.14478)
		(layer "In11.Cu")
		(net "M_L_CPU1_SB_CB<6>")
	)
	(segment
		(start 166.901114 -272.94967)
		(end 167.162988 -272.94967)
		(width 0.14478)
		(layer "In11.Cu")
		(net "M_L_CPU1_SB_CB<6>")
	)
	(segment
		(start 196.195696 -272.103342)
		(end 196.340476 -271.958562)
		(width 0.14478)
		(layer "In11.Cu")
		(net "M_L_CPU1_SB_CB<6>")
	)
	(segment
		(start 166.06012 -272.94967)
		(end 166.2049 -272.80489)
		(width 0.14478)
		(layer "In11.Cu")
		(net "M_L_CPU1_SB_CB<6>")
	)
	(segment
		(start 169.223944 -272.325846)
		(end 169.368724 -272.181066)
		(width 0.14478)
		(layer "In11.Cu")
		(net "M_L_CPU1_SB_CB<6>")
	)
	(segment
		(start 185.20537 -271.710404)
		(end 186.055254 -272.560288)
		(width 0.14478)
		(layer "In11.Cu")
		(net "M_L_CPU1_SB_CB<6>")
	)
	(segment
		(start 148.056854 -267.770864)
		(end 158.361888 -267.770864)
		(width 0.14478)
		(layer "In11.Cu")
		(net "M_L_CPU1_SB_CB<6>")
	)
	(arc
		(start 140.087604 -269.71371)
		(mid 140.269855 -269.66336)
		(end 140.453364 -269.708884)
		(width 0.0889)
		(layer "In11.Cu")
		(net "M_L_CPU1_SB_CB<6>")
	)
	(arc
		(start 143.886682 -269.69085)
		(mid 144.065495 -269.4885)
		(end 144.130014 -269.226284)
		(width 0.0889)
		(layer "In11.Cu")
		(net "M_L_CPU1_SB_CB<6>")
	)
	(arc
		(start 142.341854 -269.71371)
		(mid 142.62481 -269.789887)
		(end 142.907766 -269.71371)
		(width 0.0889)
		(layer "In11.Cu")
		(net "M_L_CPU1_SB_CB<6>")
	)
	(arc
		(start 141.976094 -269.708884)
		(mid 142.159602 -269.66339)
		(end 142.341854 -269.71371)
		(width 0.0889)
		(layer "In11.Cu")
		(net "M_L_CPU1_SB_CB<6>")
	)
	(arc
		(start 143.281654 -269.71371)
		(mid 143.56461 -269.789887)
		(end 143.847566 -269.71371)
		(width 0.0889)
		(layer "In11.Cu")
		(net "M_L_CPU1_SB_CB<6>")
	)
	(arc
		(start 139.584684 -269.74546)
		(mid 139.839892 -269.788937)
		(end 140.087604 -269.71371)
		(width 0.0889)
		(layer "In11.Cu")
		(net "M_L_CPU1_SB_CB<6>")
	)
	(arc
		(start 142.907766 -269.71371)
		(mid 143.09471 -269.663455)
		(end 143.281654 -269.71371)
		(width 0.0889)
		(layer "In11.Cu")
		(net "M_L_CPU1_SB_CB<6>")
	)
	(arc
		(start 144.691862 -268.903704)
		(mid 144.974818 -268.979881)
		(end 145.257774 -268.903704)
		(width 0.0889)
		(layer "In11.Cu")
		(net "M_L_CPU1_SB_CB<6>")
	)
	(arc
		(start 144.130014 -269.226284)
		(mid 144.171269 -269.055313)
		(end 144.28597 -268.921992)
		(width 0.0889)
		(layer "In11.Cu")
		(net "M_L_CPU1_SB_CB<6>")
	)
	(arc
		(start 145.257774 -268.903704)
		(mid 145.347907 -268.866084)
		(end 145.444718 -268.853158)
		(width 0.0889)
		(layer "In11.Cu")
		(net "M_L_CPU1_SB_CB<6>")
	)
	(arc
		(start 141.027658 -269.71371)
		(mid 141.209909 -269.66336)
		(end 141.393418 -269.708884)
		(width 0.0889)
		(layer "In11.Cu")
		(net "M_L_CPU1_SB_CB<6>")
	)
	(arc
		(start 140.461746 -269.71371)
		(mid 140.744702 -269.789887)
		(end 141.027658 -269.71371)
		(width 0.0889)
		(layer "In11.Cu")
		(net "M_L_CPU1_SB_CB<6>")
	)
	(arc
		(start 141.4018 -269.71371)
		(mid 141.684756 -269.789887)
		(end 141.967712 -269.71371)
		(width 0.0889)
		(layer "In11.Cu")
		(net "M_L_CPU1_SB_CB<6>")
	)
	(arc
		(start 144.326102 -268.898878)
		(mid 144.50961 -268.853384)
		(end 144.691862 -268.903704)
		(width 0.0889)
		(layer "In11.Cu")
		(net "M_L_CPU1_SB_CB<6>")
	)
	(segment
		(start 137.927842 -269.770352)
		(end 138.394694 -270.03629)
		(width 0.10668)
		(layer "F.Cu")
		(net "M_L_CPU1_SB_CB<5>")
	)
	(segment
		(start 144.221708 -270.35887)
		(end 144.253458 -270.340582)
		(width 0.0889)
		(layer "In11.Cu")
		(net "M_L_CPU1_SB_CB<5>")
	)
	(segment
		(start 147.598892 -268.225524)
		(end 148.040344 -268.225524)
		(width 0.0889)
		(layer "In11.Cu")
		(net "M_L_CPU1_SB_CB<5>")
	)
	(segment
		(start 144.652746 -269.571724)
		(end 144.691862 -269.548864)
		(width 0.0889)
		(layer "In11.Cu")
		(net "M_L_CPU1_SB_CB<5>")
	)
	(segment
		(start 177.72634 -272.560288)
		(end 178.576478 -273.410426)
		(width 0.14478)
		(layer "In11.Cu")
		(net "M_L_CPU1_SB_CB<5>")
	)
	(segment
		(start 146.614134 -268.584426)
		(end 147.23999 -268.584426)
		(width 0.0889)
		(layer "In11.Cu")
		(net "M_L_CPU1_SB_CB<5>")
	)
	(segment
		(start 141.393418 -270.363696)
		(end 141.4018 -270.35887)
		(width 0.0889)
		(layer "In11.Cu")
		(net "M_L_CPU1_SB_CB<5>")
	)
	(segment
		(start 178.576478 -273.410426)
		(end 181.23789 -273.410426)
		(width 0.14478)
		(layer "In11.Cu")
		(net "M_L_CPU1_SB_CB<5>")
	)
	(segment
		(start 204.74813 -273.410426)
		(end 205.823058 -273.410426)
		(width 0.14478)
		(layer "In11.Cu")
		(net "M_L_CPU1_SB_CB<5>")
	)
	(segment
		(start 201.929746 -273.410426)
		(end 203.907136 -273.410426)
		(width 0.14478)
		(layer "In11.Cu")
		(net "M_L_CPU1_SB_CB<5>")
	)
	(segment
		(start 204.051916 -273.928586)
		(end 204.196696 -274.073366)
		(width 0.14478)
		(layer "In11.Cu")
		(net "M_L_CPU1_SB_CB<5>")
	)
	(segment
		(start 201.079608 -272.560288)
		(end 201.929746 -273.410426)
		(width 0.14478)
		(layer "In11.Cu")
		(net "M_L_CPU1_SB_CB<5>")
	)
	(segment
		(start 138.24077 -270.30172)
		(end 138.263122 -270.385032)
		(width 0.0889)
		(layer "In11.Cu")
		(net "M_L_CPU1_SB_CB<5>")
	)
	(segment
		(start 140.453364 -270.363696)
		(end 140.461746 -270.35887)
		(width 0.0889)
		(layer "In11.Cu")
		(net "M_L_CPU1_SB_CB<5>")
	)
	(segment
		(start 182.088028 -272.560288)
		(end 185.270394 -272.560288)
		(width 0.14478)
		(layer "In11.Cu")
		(net "M_L_CPU1_SB_CB<5>")
	)
	(segment
		(start 144.221962 -270.35887)
		(end 144.221708 -270.35887)
		(width 0.0889)
		(layer "In11.Cu")
		(net "M_L_CPU1_SB_CB<5>")
	)
	(segment
		(start 145.257774 -269.548864)
		(end 145.266156 -269.55369)
		(width 0.0889)
		(layer "In11.Cu")
		(net "M_L_CPU1_SB_CB<5>")
	)
	(segment
		(start 158.175452 -268.225524)
		(end 163.360354 -273.410426)
		(width 0.14478)
		(layer "In11.Cu")
		(net "M_L_CPU1_SB_CB<5>")
	)
	(segment
		(start 204.60335 -273.555206)
		(end 204.74813 -273.410426)
		(width 0.14478)
		(layer "In11.Cu")
		(net "M_L_CPU1_SB_CB<5>")
	)
	(segment
		(start 204.45857 -274.073366)
		(end 204.60335 -273.928586)
		(width 0.14478)
		(layer "In11.Cu")
		(net "M_L_CPU1_SB_CB<5>")
	)
	(segment
		(start 181.23789 -273.410426)
		(end 182.088028 -272.560288)
		(width 0.14478)
		(layer "In11.Cu")
		(net "M_L_CPU1_SB_CB<5>")
	)
	(segment
		(start 163.360354 -273.410426)
		(end 173.693836 -273.410426)
		(width 0.14478)
		(layer "In11.Cu")
		(net "M_L_CPU1_SB_CB<5>")
	)
	(segment
		(start 185.270394 -272.560288)
		(end 186.120532 -273.410426)
		(width 0.14478)
		(layer "In11.Cu")
		(net "M_L_CPU1_SB_CB<5>")
	)
	(segment
		(start 189.632082 -272.560288)
		(end 201.079608 -272.560288)
		(width 0.14478)
		(layer "In11.Cu")
		(net "M_L_CPU1_SB_CB<5>")
	)
	(segment
		(start 174.543974 -272.560288)
		(end 177.72634 -272.560288)
		(width 0.14478)
		(layer "In11.Cu")
		(net "M_L_CPU1_SB_CB<5>")
	)
	(segment
		(start 203.907136 -273.410426)
		(end 204.051916 -273.555206)
		(width 0.14478)
		(layer "In11.Cu")
		(net "M_L_CPU1_SB_CB<5>")
	)
	(segment
		(start 173.693836 -273.410426)
		(end 174.543974 -272.560288)
		(width 0.14478)
		(layer "In11.Cu")
		(net "M_L_CPU1_SB_CB<5>")
	)
	(segment
		(start 204.196696 -274.073366)
		(end 204.45857 -274.073366)
		(width 0.14478)
		(layer "In11.Cu")
		(net "M_L_CPU1_SB_CB<5>")
	)
	(segment
		(start 186.120532 -273.410426)
		(end 188.781944 -273.410426)
		(width 0.14478)
		(layer "In11.Cu")
		(net "M_L_CPU1_SB_CB<5>")
	)
	(segment
		(start 188.781944 -273.410426)
		(end 189.632082 -272.560288)
		(width 0.14478)
		(layer "In11.Cu")
		(net "M_L_CPU1_SB_CB<5>")
	)
	(segment
		(start 147.23999 -268.584426)
		(end 147.598892 -268.225524)
		(width 0.0889)
		(layer "In11.Cu")
		(net "M_L_CPU1_SB_CB<5>")
	)
	(segment
		(start 138.394694 -270.03629)
		(end 138.24077 -270.30172)
		(width 0.0889)
		(layer "In11.Cu")
		(net "M_L_CPU1_SB_CB<5>")
	)
	(segment
		(start 204.60335 -273.928586)
		(end 204.60335 -273.555206)
		(width 0.14478)
		(layer "In11.Cu")
		(net "M_L_CPU1_SB_CB<5>")
	)
	(segment
		(start 205.823058 -273.410426)
		(end 206.248 -273.835368)
		(width 0.14478)
		(layer "In11.Cu")
		(net "M_L_CPU1_SB_CB<5>")
	)
	(segment
		(start 204.051916 -273.555206)
		(end 204.051916 -273.928586)
		(width 0.14478)
		(layer "In11.Cu")
		(net "M_L_CPU1_SB_CB<5>")
	)
	(segment
		(start 148.040344 -268.225524)
		(end 158.175452 -268.225524)
		(width 0.14478)
		(layer "In11.Cu")
		(net "M_L_CPU1_SB_CB<5>")
	)
	(segment
		(start 145.70837 -269.489936)
		(end 146.614134 -268.584426)
		(width 0.0889)
		(layer "In11.Cu")
		(net "M_L_CPU1_SB_CB<5>")
	)
	(segment
		(start 141.967712 -270.35887)
		(end 141.976094 -270.363696)
		(width 0.0889)
		(layer "In11.Cu")
		(net "M_L_CPU1_SB_CB<5>")
	)
	(arc
		(start 141.027658 -270.35887)
		(mid 141.209909 -270.40922)
		(end 141.393418 -270.363696)
		(width 0.0889)
		(layer "In11.Cu")
		(net "M_L_CPU1_SB_CB<5>")
	)
	(arc
		(start 142.341854 -270.35887)
		(mid 142.62481 -270.282693)
		(end 142.907766 -270.35887)
		(width 0.0889)
		(layer "In11.Cu")
		(net "M_L_CPU1_SB_CB<5>")
	)
	(arc
		(start 142.907766 -270.35887)
		(mid 143.09471 -270.409125)
		(end 143.281654 -270.35887)
		(width 0.0889)
		(layer "In11.Cu")
		(net "M_L_CPU1_SB_CB<5>")
	)
	(arc
		(start 139.147804 -270.35887)
		(mid 139.334748 -270.409125)
		(end 139.521692 -270.35887)
		(width 0.0889)
		(layer "In11.Cu")
		(net "M_L_CPU1_SB_CB<5>")
	)
	(arc
		(start 140.087604 -270.35887)
		(mid 140.269855 -270.40922)
		(end 140.453364 -270.363696)
		(width 0.0889)
		(layer "In11.Cu")
		(net "M_L_CPU1_SB_CB<5>")
	)
	(arc
		(start 138.263122 -270.385032)
		(mid 138.425454 -270.40785)
		(end 138.581892 -270.35887)
		(width 0.0889)
		(layer "In11.Cu")
		(net "M_L_CPU1_SB_CB<5>")
	)
	(arc
		(start 138.581892 -270.35887)
		(mid 138.864848 -270.282693)
		(end 139.147804 -270.35887)
		(width 0.0889)
		(layer "In11.Cu")
		(net "M_L_CPU1_SB_CB<5>")
	)
	(arc
		(start 139.521692 -270.35887)
		(mid 139.804648 -270.282693)
		(end 140.087604 -270.35887)
		(width 0.0889)
		(layer "In11.Cu")
		(net "M_L_CPU1_SB_CB<5>")
	)
	(arc
		(start 141.976094 -270.363696)
		(mid 142.159602 -270.40919)
		(end 142.341854 -270.35887)
		(width 0.0889)
		(layer "In11.Cu")
		(net "M_L_CPU1_SB_CB<5>")
	)
	(arc
		(start 140.461746 -270.35887)
		(mid 140.744702 -270.282693)
		(end 141.027658 -270.35887)
		(width 0.0889)
		(layer "In11.Cu")
		(net "M_L_CPU1_SB_CB<5>")
	)
	(arc
		(start 141.4018 -270.35887)
		(mid 141.684756 -270.282693)
		(end 141.967712 -270.35887)
		(width 0.0889)
		(layer "In11.Cu")
		(net "M_L_CPU1_SB_CB<5>")
	)
	(arc
		(start 143.281654 -270.35887)
		(mid 143.56461 -270.282693)
		(end 143.847566 -270.35887)
		(width 0.0889)
		(layer "In11.Cu")
		(net "M_L_CPU1_SB_CB<5>")
	)
	(arc
		(start 144.691862 -269.548864)
		(mid 144.974818 -269.472687)
		(end 145.257774 -269.548864)
		(width 0.0889)
		(layer "In11.Cu")
		(net "M_L_CPU1_SB_CB<5>")
	)
	(arc
		(start 144.409414 -270.03629)
		(mid 144.473929 -269.774071)
		(end 144.652746 -269.571724)
		(width 0.0889)
		(layer "In11.Cu")
		(net "M_L_CPU1_SB_CB<5>")
	)
	(arc
		(start 144.253458 -270.340582)
		(mid 144.368134 -270.207248)
		(end 144.409414 -270.03629)
		(width 0.0889)
		(layer "In11.Cu")
		(net "M_L_CPU1_SB_CB<5>")
	)
	(arc
		(start 143.847566 -270.35887)
		(mid 144.034764 -270.409252)
		(end 144.221962 -270.35887)
		(width 0.0889)
		(layer "In11.Cu")
		(net "M_L_CPU1_SB_CB<5>")
	)
	(arc
		(start 145.631916 -269.548864)
		(mid 145.672061 -269.521888)
		(end 145.70837 -269.489936)
		(width 0.0889)
		(layer "In11.Cu")
		(net "M_L_CPU1_SB_CB<5>")
	)
	(arc
		(start 145.266156 -269.55369)
		(mid 145.449664 -269.599184)
		(end 145.631916 -269.548864)
		(width 0.0889)
		(layer "In11.Cu")
		(net "M_L_CPU1_SB_CB<5>")
	)
	(segment
		(start 139.337796 -268.960346)
		(end 139.804648 -269.226284)
		(width 0.10668)
		(layer "F.Cu")
		(net "M_L_CPU1_SB_CB<4>")
	)
	(segment
		(start 162.164522 -270.715994)
		(end 162.207956 -270.67256)
		(width 0.14478)
		(layer "In11.Cu")
		(net "M_L_CPU1_SB_CB<4>")
	)
	(segment
		(start 204.177646 -271.528286)
		(end 204.322426 -271.383506)
		(width 0.14478)
		(layer "In11.Cu")
		(net "M_L_CPU1_SB_CB<4>")
	)
	(segment
		(start 188.996828 -271.71015)
		(end 189.846712 -270.860266)
		(width 0.14478)
		(layer "In11.Cu")
		(net "M_L_CPU1_SB_CB<4>")
	)
	(segment
		(start 159.476948 -267.941552)
		(end 159.433514 -267.984986)
		(width 0.14478)
		(layer "In11.Cu")
		(net "M_L_CPU1_SB_CB<4>")
	)
	(segment
		(start 203.626212 -270.860266)
		(end 203.770992 -271.005046)
		(width 0.14478)
		(layer "In11.Cu")
		(net "M_L_CPU1_SB_CB<4>")
	)
	(segment
		(start 204.322426 -271.005046)
		(end 204.467206 -270.860266)
		(width 0.14478)
		(layer "In11.Cu")
		(net "M_L_CPU1_SB_CB<4>")
	)
	(segment
		(start 140.557758 -269.548864)
		(end 140.56614 -269.55369)
		(width 0.0889)
		(layer "In11.Cu")
		(net "M_L_CPU1_SB_CB<4>")
	)
	(segment
		(start 146.874738 -267.316204)
		(end 148.034502 -267.316204)
		(width 0.0889)
		(layer "In11.Cu")
		(net "M_L_CPU1_SB_CB<4>")
	)
	(segment
		(start 160.213802 -268.765274)
		(end 160.213802 -268.969998)
		(width 0.14478)
		(layer "In11.Cu")
		(net "M_L_CPU1_SB_CB<4>")
	)
	(segment
		(start 160.257236 -268.517116)
		(end 160.257236 -268.72184)
		(width 0.14478)
		(layer "In11.Cu")
		(net "M_L_CPU1_SB_CB<4>")
	)
	(segment
		(start 148.034502 -267.316204)
		(end 159.056324 -267.316204)
		(width 0.14478)
		(layer "In11.Cu")
		(net "M_L_CPU1_SB_CB<4>")
	)
	(segment
		(start 144.182592 -268.761718)
		(end 144.221708 -268.738858)
		(width 0.0889)
		(layer "In11.Cu")
		(net "M_L_CPU1_SB_CB<4>")
	)
	(segment
		(start 162.554666 -271.310862)
		(end 162.954208 -271.710404)
		(width 0.14478)
		(layer "In11.Cu")
		(net "M_L_CPU1_SB_CB<4>")
	)
	(segment
		(start 161.17951 -269.935706)
		(end 161.384234 -269.935706)
		(width 0.14478)
		(layer "In11.Cu")
		(net "M_L_CPU1_SB_CB<4>")
	)
	(segment
		(start 177.508916 -270.860266)
		(end 178.3588 -271.71015)
		(width 0.14478)
		(layer "In11.Cu")
		(net "M_L_CPU1_SB_CB<4>")
	)
	(segment
		(start 145.528284 -268.662658)
		(end 146.874738 -267.316204)
		(width 0.0889)
		(layer "In11.Cu")
		(net "M_L_CPU1_SB_CB<4>")
	)
	(segment
		(start 181.445154 -271.71015)
		(end 182.295038 -270.860266)
		(width 0.14478)
		(layer "In11.Cu")
		(net "M_L_CPU1_SB_CB<4>")
	)
	(segment
		(start 185.904886 -271.71015)
		(end 188.996828 -271.71015)
		(width 0.14478)
		(layer "In11.Cu")
		(net "M_L_CPU1_SB_CB<4>")
	)
	(segment
		(start 142.803372 -269.55369)
		(end 142.811754 -269.548864)
		(width 0.0889)
		(layer "In11.Cu")
		(net "M_L_CPU1_SB_CB<4>")
	)
	(segment
		(start 204.467206 -270.860266)
		(end 204.97292 -270.860266)
		(width 0.14478)
		(layer "In11.Cu")
		(net "M_L_CPU1_SB_CB<4>")
	)
	(segment
		(start 160.257236 -268.72184)
		(end 160.213802 -268.765274)
		(width 0.14478)
		(layer "In11.Cu")
		(net "M_L_CPU1_SB_CB<4>")
	)
	(segment
		(start 204.97292 -270.860266)
		(end 206.248 -272.135346)
		(width 0.14478)
		(layer "In11.Cu")
		(net "M_L_CPU1_SB_CB<4>")
	)
	(segment
		(start 143.377666 -269.548864)
		(end 143.386048 -269.55369)
		(width 0.0889)
		(layer "In11.Cu")
		(net "M_L_CPU1_SB_CB<4>")
	)
	(segment
		(start 159.433514 -267.984986)
		(end 159.433514 -268.18971)
		(width 0.14478)
		(layer "In11.Cu")
		(net "M_L_CPU1_SB_CB<4>")
	)
	(segment
		(start 160.071816 -268.331696)
		(end 160.257236 -268.517116)
		(width 0.14478)
		(layer "In11.Cu")
		(net "M_L_CPU1_SB_CB<4>")
	)
	(segment
		(start 161.037524 -269.297404)
		(end 161.037524 -269.502128)
		(width 0.14478)
		(layer "In11.Cu")
		(net "M_L_CPU1_SB_CB<4>")
	)
	(segment
		(start 161.037524 -269.502128)
		(end 160.99409 -269.545562)
		(width 0.14478)
		(layer "In11.Cu")
		(net "M_L_CPU1_SB_CB<4>")
	)
	(segment
		(start 159.867092 -268.331696)
		(end 160.071816 -268.331696)
		(width 0.14478)
		(layer "In11.Cu")
		(net "M_L_CPU1_SB_CB<4>")
	)
	(segment
		(start 161.774378 -270.530574)
		(end 161.959798 -270.715994)
		(width 0.14478)
		(layer "In11.Cu")
		(net "M_L_CPU1_SB_CB<4>")
	)
	(segment
		(start 161.632392 -269.892272)
		(end 161.817812 -270.077692)
		(width 0.14478)
		(layer "In11.Cu")
		(net "M_L_CPU1_SB_CB<4>")
	)
	(segment
		(start 162.207956 -270.67256)
		(end 162.41268 -270.67256)
		(width 0.14478)
		(layer "In11.Cu")
		(net "M_L_CPU1_SB_CB<4>")
	)
	(segment
		(start 159.823658 -268.37513)
		(end 159.867092 -268.331696)
		(width 0.14478)
		(layer "In11.Cu")
		(net "M_L_CPU1_SB_CB<4>")
	)
	(segment
		(start 204.322426 -271.383506)
		(end 204.322426 -271.005046)
		(width 0.14478)
		(layer "In11.Cu")
		(net "M_L_CPU1_SB_CB<4>")
	)
	(segment
		(start 160.603946 -269.155418)
		(end 160.64738 -269.111984)
		(width 0.14478)
		(layer "In11.Cu")
		(net "M_L_CPU1_SB_CB<4>")
	)
	(segment
		(start 160.213802 -268.969998)
		(end 160.399222 -269.155418)
		(width 0.14478)
		(layer "In11.Cu")
		(net "M_L_CPU1_SB_CB<4>")
	)
	(segment
		(start 162.954208 -271.710404)
		(end 173.693582 -271.710404)
		(width 0.14478)
		(layer "In11.Cu")
		(net "M_L_CPU1_SB_CB<4>")
	)
	(segment
		(start 145.444464 -268.662658)
		(end 145.528284 -268.662658)
		(width 0.0889)
		(layer "In11.Cu")
		(net "M_L_CPU1_SB_CB<4>")
	)
	(segment
		(start 162.5981 -271.062704)
		(end 162.554666 -271.106138)
		(width 0.14478)
		(layer "In11.Cu")
		(net "M_L_CPU1_SB_CB<4>")
	)
	(segment
		(start 159.056324 -267.316204)
		(end 159.476948 -267.736828)
		(width 0.14478)
		(layer "In11.Cu")
		(net "M_L_CPU1_SB_CB<4>")
	)
	(segment
		(start 185.055002 -270.860266)
		(end 185.904886 -271.71015)
		(width 0.14478)
		(layer "In11.Cu")
		(net "M_L_CPU1_SB_CB<4>")
	)
	(segment
		(start 203.915772 -271.528286)
		(end 204.177646 -271.528286)
		(width 0.14478)
		(layer "In11.Cu")
		(net "M_L_CPU1_SB_CB<4>")
	)
	(segment
		(start 159.618934 -268.37513)
		(end 159.823658 -268.37513)
		(width 0.14478)
		(layer "In11.Cu")
		(net "M_L_CPU1_SB_CB<4>")
	)
	(segment
		(start 161.817812 -270.077692)
		(end 161.817812 -270.282416)
		(width 0.14478)
		(layer "In11.Cu")
		(net "M_L_CPU1_SB_CB<4>")
	)
	(segment
		(start 139.650724 -269.491714)
		(end 139.673076 -269.575026)
		(width 0.0889)
		(layer "In11.Cu")
		(net "M_L_CPU1_SB_CB<4>")
	)
	(segment
		(start 178.3588 -271.71015)
		(end 181.445154 -271.71015)
		(width 0.14478)
		(layer "In11.Cu")
		(net "M_L_CPU1_SB_CB<4>")
	)
	(segment
		(start 161.427668 -269.892272)
		(end 161.632392 -269.892272)
		(width 0.14478)
		(layer "In11.Cu")
		(net "M_L_CPU1_SB_CB<4>")
	)
	(segment
		(start 159.433514 -268.18971)
		(end 159.618934 -268.37513)
		(width 0.14478)
		(layer "In11.Cu")
		(net "M_L_CPU1_SB_CB<4>")
	)
	(segment
		(start 173.693836 -271.71015)
		(end 173.911768 -271.71015)
		(width 0.14478)
		(layer "In11.Cu")
		(net "M_L_CPU1_SB_CB<4>")
	)
	(segment
		(start 203.770992 -271.005046)
		(end 203.770992 -271.383506)
		(width 0.14478)
		(layer "In11.Cu")
		(net "M_L_CPU1_SB_CB<4>")
	)
	(segment
		(start 160.399222 -269.155418)
		(end 160.603946 -269.155418)
		(width 0.14478)
		(layer "In11.Cu")
		(net "M_L_CPU1_SB_CB<4>")
	)
	(segment
		(start 143.751808 -269.548864)
		(end 143.782288 -269.531084)
		(width 0.0889)
		(layer "In11.Cu")
		(net "M_L_CPU1_SB_CB<4>")
	)
	(segment
		(start 174.761652 -270.860266)
		(end 177.508916 -270.860266)
		(width 0.14478)
		(layer "In11.Cu")
		(net "M_L_CPU1_SB_CB<4>")
	)
	(segment
		(start 145.15338 -268.743684)
		(end 145.161762 -268.738858)
		(width 0.0889)
		(layer "In11.Cu")
		(net "M_L_CPU1_SB_CB<4>")
	)
	(segment
		(start 159.476948 -267.736828)
		(end 159.476948 -267.941552)
		(width 0.14478)
		(layer "In11.Cu")
		(net "M_L_CPU1_SB_CB<4>")
	)
	(segment
		(start 162.41268 -270.67256)
		(end 162.5981 -270.85798)
		(width 0.14478)
		(layer "In11.Cu")
		(net "M_L_CPU1_SB_CB<4>")
	)
	(segment
		(start 160.852104 -269.111984)
		(end 161.037524 -269.297404)
		(width 0.14478)
		(layer "In11.Cu")
		(net "M_L_CPU1_SB_CB<4>")
	)
	(segment
		(start 161.774378 -270.32585)
		(end 161.774378 -270.530574)
		(width 0.14478)
		(layer "In11.Cu")
		(net "M_L_CPU1_SB_CB<4>")
	)
	(segment
		(start 161.817812 -270.282416)
		(end 161.774378 -270.32585)
		(width 0.14478)
		(layer "In11.Cu")
		(net "M_L_CPU1_SB_CB<4>")
	)
	(segment
		(start 161.384234 -269.935706)
		(end 161.427668 -269.892272)
		(width 0.14478)
		(layer "In11.Cu")
		(net "M_L_CPU1_SB_CB<4>")
	)
	(segment
		(start 161.959798 -270.715994)
		(end 162.164522 -270.715994)
		(width 0.14478)
		(layer "In11.Cu")
		(net "M_L_CPU1_SB_CB<4>")
	)
	(segment
		(start 160.99409 -269.545562)
		(end 160.99409 -269.750286)
		(width 0.14478)
		(layer "In11.Cu")
		(net "M_L_CPU1_SB_CB<4>")
	)
	(segment
		(start 162.5981 -270.85798)
		(end 162.5981 -271.062704)
		(width 0.14478)
		(layer "In11.Cu")
		(net "M_L_CPU1_SB_CB<4>")
	)
	(segment
		(start 160.64738 -269.111984)
		(end 160.852104 -269.111984)
		(width 0.14478)
		(layer "In11.Cu")
		(net "M_L_CPU1_SB_CB<4>")
	)
	(segment
		(start 139.804648 -269.226284)
		(end 139.650724 -269.491714)
		(width 0.0889)
		(layer "In11.Cu")
		(net "M_L_CPU1_SB_CB<4>")
	)
	(segment
		(start 173.911768 -271.71015)
		(end 174.761652 -270.860266)
		(width 0.14478)
		(layer "In11.Cu")
		(net "M_L_CPU1_SB_CB<4>")
	)
	(segment
		(start 182.295038 -270.860266)
		(end 185.055002 -270.860266)
		(width 0.14478)
		(layer "In11.Cu")
		(net "M_L_CPU1_SB_CB<4>")
	)
	(segment
		(start 162.554666 -271.106138)
		(end 162.554666 -271.310862)
		(width 0.14478)
		(layer "In11.Cu")
		(net "M_L_CPU1_SB_CB<4>")
	)
	(segment
		(start 203.770992 -271.383506)
		(end 203.915772 -271.528286)
		(width 0.14478)
		(layer "In11.Cu")
		(net "M_L_CPU1_SB_CB<4>")
	)
	(segment
		(start 160.99409 -269.750286)
		(end 161.17951 -269.935706)
		(width 0.14478)
		(layer "In11.Cu")
		(net "M_L_CPU1_SB_CB<4>")
	)
	(segment
		(start 173.693582 -271.710404)
		(end 173.693836 -271.71015)
		(width 0.14478)
		(layer "In11.Cu")
		(net "M_L_CPU1_SB_CB<4>")
	)
	(segment
		(start 189.846712 -270.860266)
		(end 203.626212 -270.860266)
		(width 0.14478)
		(layer "In11.Cu")
		(net "M_L_CPU1_SB_CB<4>")
	)
	(arc
		(start 143.386048 -269.55369)
		(mid 143.569556 -269.599184)
		(end 143.751808 -269.548864)
		(width 0.0889)
		(layer "In11.Cu")
		(net "M_L_CPU1_SB_CB<4>")
	)
	(arc
		(start 140.9319 -269.548864)
		(mid 141.214856 -269.472687)
		(end 141.497812 -269.548864)
		(width 0.0889)
		(layer "In11.Cu")
		(net "M_L_CPU1_SB_CB<4>")
	)
	(arc
		(start 145.397474 -268.664436)
		(mid 145.420951 -268.66306)
		(end 145.444464 -268.662658)
		(width 0.0889)
		(layer "In11.Cu")
		(net "M_L_CPU1_SB_CB<4>")
	)
	(arc
		(start 139.991846 -269.548864)
		(mid 140.274802 -269.472687)
		(end 140.557758 -269.548864)
		(width 0.0889)
		(layer "In11.Cu")
		(net "M_L_CPU1_SB_CB<4>")
	)
	(arc
		(start 140.56614 -269.55369)
		(mid 140.749648 -269.599184)
		(end 140.9319 -269.548864)
		(width 0.0889)
		(layer "In11.Cu")
		(net "M_L_CPU1_SB_CB<4>")
	)
	(arc
		(start 143.93926 -269.226284)
		(mid 144.003775 -268.964065)
		(end 144.182592 -268.761718)
		(width 0.0889)
		(layer "In11.Cu")
		(net "M_L_CPU1_SB_CB<4>")
	)
	(arc
		(start 139.673076 -269.575026)
		(mid 139.835408 -269.597844)
		(end 139.991846 -269.548864)
		(width 0.0889)
		(layer "In11.Cu")
		(net "M_L_CPU1_SB_CB<4>")
	)
	(arc
		(start 141.497812 -269.548864)
		(mid 141.684756 -269.599119)
		(end 141.8717 -269.548864)
		(width 0.0889)
		(layer "In11.Cu")
		(net "M_L_CPU1_SB_CB<4>")
	)
	(arc
		(start 143.782288 -269.531084)
		(mid 143.897715 -269.397708)
		(end 143.93926 -269.226284)
		(width 0.0889)
		(layer "In11.Cu")
		(net "M_L_CPU1_SB_CB<4>")
	)
	(arc
		(start 144.78762 -268.738858)
		(mid 144.969871 -268.789208)
		(end 145.15338 -268.743684)
		(width 0.0889)
		(layer "In11.Cu")
		(net "M_L_CPU1_SB_CB<4>")
	)
	(arc
		(start 145.161762 -268.738858)
		(mid 145.275486 -268.688557)
		(end 145.397474 -268.664436)
		(width 0.0889)
		(layer "In11.Cu")
		(net "M_L_CPU1_SB_CB<4>")
	)
	(arc
		(start 142.437612 -269.548864)
		(mid 142.619863 -269.599214)
		(end 142.803372 -269.55369)
		(width 0.0889)
		(layer "In11.Cu")
		(net "M_L_CPU1_SB_CB<4>")
	)
	(arc
		(start 144.221708 -268.738858)
		(mid 144.504664 -268.662681)
		(end 144.78762 -268.738858)
		(width 0.0889)
		(layer "In11.Cu")
		(net "M_L_CPU1_SB_CB<4>")
	)
	(arc
		(start 142.811754 -269.548864)
		(mid 143.09471 -269.472687)
		(end 143.377666 -269.548864)
		(width 0.0889)
		(layer "In11.Cu")
		(net "M_L_CPU1_SB_CB<4>")
	)
	(arc
		(start 141.8717 -269.548864)
		(mid 142.154656 -269.472687)
		(end 142.437612 -269.548864)
		(width 0.0889)
		(layer "In11.Cu")
		(net "M_L_CPU1_SB_CB<4>")
	)
	(segment
		(start 137.457942 -273.820382)
		(end 137.924794 -274.08632)
		(width 0.10668)
		(layer "F.Cu")
		(net "M_L_CPU1_SB_CB<3>")
	)
	(segment
		(start 137.924794 -274.08632)
		(end 138.078718 -273.82089)
		(width 0.0889)
		(layer "In11.Cu")
		(net "M_L_CPU1_SB_CB<3>")
	)
	(segment
		(start 171.032424 -281.060398)
		(end 173.693836 -281.060398)
		(width 0.14478)
		(layer "In11.Cu")
		(net "M_L_CPU1_SB_CB<3>")
	)
	(segment
		(start 192.74917 -280.21026)
		(end 193.599308 -281.060398)
		(width 0.14478)
		(layer "In11.Cu")
		(net "M_L_CPU1_SB_CB<3>")
	)
	(segment
		(start 159.982916 -276.852634)
		(end 160.213548 -276.852634)
		(width 0.14478)
		(layer "In11.Cu")
		(net "M_L_CPU1_SB_CB<3>")
	)
	(segment
		(start 160.37687 -277.015956)
		(end 160.376616 -277.24608)
		(width 0.14478)
		(layer "In11.Cu")
		(net "M_L_CPU1_SB_CB<3>")
	)
	(segment
		(start 160.85312 -278.344376)
		(end 160.85312 -278.575008)
		(width 0.14478)
		(layer "In11.Cu")
		(net "M_L_CPU1_SB_CB<3>")
	)
	(segment
		(start 177.72634 -280.21026)
		(end 178.576478 -281.060398)
		(width 0.14478)
		(layer "In11.Cu")
		(net "M_L_CPU1_SB_CB<3>")
	)
	(segment
		(start 185.270394 -280.21026)
		(end 186.120532 -281.060398)
		(width 0.14478)
		(layer "In11.Cu")
		(net "M_L_CPU1_SB_CB<3>")
	)
	(segment
		(start 196.640704 -280.21026)
		(end 201.72299 -280.21026)
		(width 0.14478)
		(layer "In11.Cu")
		(net "M_L_CPU1_SB_CB<3>")
	)
	(segment
		(start 159.441388 -277.163276)
		(end 159.67202 -277.16353)
		(width 0.14478)
		(layer "In11.Cu")
		(net "M_L_CPU1_SB_CB<3>")
	)
	(segment
		(start 160.45942 -277.95093)
		(end 160.770316 -277.640034)
		(width 0.14478)
		(layer "In11.Cu")
		(net "M_L_CPU1_SB_CB<3>")
	)
	(segment
		(start 146.88947 -272.556986)
		(end 147.43557 -272.556986)
		(width 0.0889)
		(layer "In11.Cu")
		(net "M_L_CPU1_SB_CB<3>")
	)
	(segment
		(start 161.164016 -278.03348)
		(end 160.85312 -278.344376)
		(width 0.14478)
		(layer "In11.Cu")
		(net "M_L_CPU1_SB_CB<3>")
	)
	(segment
		(start 193.599308 -281.060398)
		(end 195.790566 -281.060398)
		(width 0.14478)
		(layer "In11.Cu")
		(net "M_L_CPU1_SB_CB<3>")
	)
	(segment
		(start 159.67202 -277.16353)
		(end 159.982916 -276.852634)
		(width 0.14478)
		(layer "In11.Cu")
		(net "M_L_CPU1_SB_CB<3>")
	)
	(segment
		(start 166.123874 -281.060398)
		(end 166.974012 -280.21026)
		(width 0.14478)
		(layer "In11.Cu")
		(net "M_L_CPU1_SB_CB<3>")
	)
	(segment
		(start 201.72299 -280.21026)
		(end 202.147932 -280.635202)
		(width 0.14478)
		(layer "In11.Cu")
		(net "M_L_CPU1_SB_CB<3>")
	)
	(segment
		(start 163.33851 -281.060398)
		(end 166.123874 -281.060398)
		(width 0.14478)
		(layer "In11.Cu")
		(net "M_L_CPU1_SB_CB<3>")
	)
	(segment
		(start 158.653988 -276.375876)
		(end 158.88462 -276.37613)
		(width 0.14478)
		(layer "In11.Cu")
		(net "M_L_CPU1_SB_CB<3>")
	)
	(segment
		(start 139.617704 -273.76374)
		(end 139.626086 -273.758914)
		(width 0.0889)
		(layer "In11.Cu")
		(net "M_L_CPU1_SB_CB<3>")
	)
	(segment
		(start 166.974012 -280.21026)
		(end 170.182286 -280.21026)
		(width 0.14478)
		(layer "In11.Cu")
		(net "M_L_CPU1_SB_CB<3>")
	)
	(segment
		(start 145.444718 -273.713448)
		(end 145.733008 -273.713448)
		(width 0.0889)
		(layer "In11.Cu")
		(net "M_L_CPU1_SB_CB<3>")
	)
	(segment
		(start 170.182286 -280.21026)
		(end 171.032424 -281.060398)
		(width 0.14478)
		(layer "In11.Cu")
		(net "M_L_CPU1_SB_CB<3>")
	)
	(segment
		(start 160.770316 -277.640034)
		(end 161.000948 -277.640034)
		(width 0.14478)
		(layer "In11.Cu")
		(net "M_L_CPU1_SB_CB<3>")
	)
	(segment
		(start 160.06572 -277.787608)
		(end 160.228788 -277.950676)
		(width 0.14478)
		(layer "In11.Cu")
		(net "M_L_CPU1_SB_CB<3>")
	)
	(segment
		(start 148.02612 -272.383504)
		(end 154.661616 -272.383504)
		(width 0.14478)
		(layer "In11.Cu")
		(net "M_L_CPU1_SB_CB<3>")
	)
	(segment
		(start 159.27832 -277.000208)
		(end 159.441388 -277.163276)
		(width 0.14478)
		(layer "In11.Cu")
		(net "M_L_CPU1_SB_CB<3>")
	)
	(segment
		(start 186.120532 -281.060398)
		(end 188.781944 -281.060398)
		(width 0.14478)
		(layer "In11.Cu")
		(net "M_L_CPU1_SB_CB<3>")
	)
	(segment
		(start 181.23789 -281.060398)
		(end 182.088028 -280.21026)
		(width 0.14478)
		(layer "In11.Cu")
		(net "M_L_CPU1_SB_CB<3>")
	)
	(segment
		(start 145.733008 -273.713448)
		(end 146.88947 -272.556986)
		(width 0.0889)
		(layer "In11.Cu")
		(net "M_L_CPU1_SB_CB<3>")
	)
	(segment
		(start 147.43557 -272.556986)
		(end 147.609052 -272.383504)
		(width 0.0889)
		(layer "In11.Cu")
		(net "M_L_CPU1_SB_CB<3>")
	)
	(segment
		(start 160.376616 -277.24608)
		(end 160.06572 -277.556976)
		(width 0.14478)
		(layer "In11.Cu")
		(net "M_L_CPU1_SB_CB<3>")
	)
	(segment
		(start 145.247614 -273.769836)
		(end 145.258028 -273.76374)
		(width 0.0889)
		(layer "In11.Cu")
		(net "M_L_CPU1_SB_CB<3>")
	)
	(segment
		(start 160.85312 -278.575008)
		(end 163.33851 -281.060398)
		(width 0.14478)
		(layer "In11.Cu")
		(net "M_L_CPU1_SB_CB<3>")
	)
	(segment
		(start 160.213548 -276.852634)
		(end 160.37687 -277.015956)
		(width 0.14478)
		(layer "In11.Cu")
		(net "M_L_CPU1_SB_CB<3>")
	)
	(segment
		(start 160.06572 -277.556976)
		(end 160.06572 -277.787608)
		(width 0.14478)
		(layer "In11.Cu")
		(net "M_L_CPU1_SB_CB<3>")
	)
	(segment
		(start 161.000948 -277.640034)
		(end 161.16427 -277.803356)
		(width 0.14478)
		(layer "In11.Cu")
		(net "M_L_CPU1_SB_CB<3>")
	)
	(segment
		(start 160.228788 -277.950676)
		(end 160.45942 -277.95093)
		(width 0.14478)
		(layer "In11.Cu")
		(net "M_L_CPU1_SB_CB<3>")
	)
	(segment
		(start 159.58947 -276.228556)
		(end 159.589216 -276.45868)
		(width 0.14478)
		(layer "In11.Cu")
		(net "M_L_CPU1_SB_CB<3>")
	)
	(segment
		(start 159.195516 -276.065234)
		(end 159.426148 -276.065234)
		(width 0.14478)
		(layer "In11.Cu")
		(net "M_L_CPU1_SB_CB<3>")
	)
	(segment
		(start 138.078718 -273.82089)
		(end 138.17473 -273.79549)
		(width 0.0889)
		(layer "In11.Cu")
		(net "M_L_CPU1_SB_CB<3>")
	)
	(segment
		(start 188.781944 -281.060398)
		(end 189.632082 -280.21026)
		(width 0.14478)
		(layer "In11.Cu")
		(net "M_L_CPU1_SB_CB<3>")
	)
	(segment
		(start 178.576478 -281.060398)
		(end 181.23789 -281.060398)
		(width 0.14478)
		(layer "In11.Cu")
		(net "M_L_CPU1_SB_CB<3>")
	)
	(segment
		(start 159.589216 -276.45868)
		(end 159.27832 -276.769576)
		(width 0.14478)
		(layer "In11.Cu")
		(net "M_L_CPU1_SB_CB<3>")
	)
	(segment
		(start 143.377666 -273.76374)
		(end 143.386048 -273.758914)
		(width 0.0889)
		(layer "In11.Cu")
		(net "M_L_CPU1_SB_CB<3>")
	)
	(segment
		(start 173.693836 -281.060398)
		(end 174.543974 -280.21026)
		(width 0.14478)
		(layer "In11.Cu")
		(net "M_L_CPU1_SB_CB<3>")
	)
	(segment
		(start 147.609052 -272.383504)
		(end 148.02612 -272.383504)
		(width 0.0889)
		(layer "In11.Cu")
		(net "M_L_CPU1_SB_CB<3>")
	)
	(segment
		(start 158.88462 -276.37613)
		(end 159.195516 -276.065234)
		(width 0.14478)
		(layer "In11.Cu")
		(net "M_L_CPU1_SB_CB<3>")
	)
	(segment
		(start 159.27832 -276.769576)
		(end 159.27832 -277.000208)
		(width 0.14478)
		(layer "In11.Cu")
		(net "M_L_CPU1_SB_CB<3>")
	)
	(segment
		(start 139.04341 -273.758914)
		(end 139.051792 -273.76374)
		(width 0.0889)
		(layer "In11.Cu")
		(net "M_L_CPU1_SB_CB<3>")
	)
	(segment
		(start 182.088028 -280.21026)
		(end 185.270394 -280.21026)
		(width 0.14478)
		(layer "In11.Cu")
		(net "M_L_CPU1_SB_CB<3>")
	)
	(segment
		(start 189.632082 -280.21026)
		(end 192.74917 -280.21026)
		(width 0.14478)
		(layer "In11.Cu")
		(net "M_L_CPU1_SB_CB<3>")
	)
	(segment
		(start 140.557758 -273.76374)
		(end 140.56614 -273.758914)
		(width 0.0889)
		(layer "In11.Cu")
		(net "M_L_CPU1_SB_CB<3>")
	)
	(segment
		(start 195.790566 -281.060398)
		(end 196.640704 -280.21026)
		(width 0.14478)
		(layer "In11.Cu")
		(net "M_L_CPU1_SB_CB<3>")
	)
	(segment
		(start 142.803372 -273.758914)
		(end 142.811754 -273.76374)
		(width 0.0889)
		(layer "In11.Cu")
		(net "M_L_CPU1_SB_CB<3>")
	)
	(segment
		(start 161.16427 -277.803356)
		(end 161.164016 -278.03348)
		(width 0.14478)
		(layer "In11.Cu")
		(net "M_L_CPU1_SB_CB<3>")
	)
	(segment
		(start 174.543974 -280.21026)
		(end 177.72634 -280.21026)
		(width 0.14478)
		(layer "In11.Cu")
		(net "M_L_CPU1_SB_CB<3>")
	)
	(segment
		(start 154.661616 -272.383504)
		(end 158.653988 -276.375876)
		(width 0.14478)
		(layer "In11.Cu")
		(net "M_L_CPU1_SB_CB<3>")
	)
	(segment
		(start 143.751808 -273.76374)
		(end 143.762222 -273.769836)
		(width 0.0889)
		(layer "In11.Cu")
		(net "M_L_CPU1_SB_CB<3>")
	)
	(segment
		(start 159.426148 -276.065234)
		(end 159.58947 -276.228556)
		(width 0.14478)
		(layer "In11.Cu")
		(net "M_L_CPU1_SB_CB<3>")
	)
	(arc
		(start 144.317974 -273.76374)
		(mid 144.505172 -273.713358)
		(end 144.69237 -273.76374)
		(width 0.0889)
		(layer "In11.Cu")
		(net "M_L_CPU1_SB_CB<3>")
	)
	(arc
		(start 141.8717 -273.76374)
		(mid 142.154656 -273.839917)
		(end 142.437612 -273.76374)
		(width 0.0889)
		(layer "In11.Cu")
		(net "M_L_CPU1_SB_CB<3>")
	)
	(arc
		(start 139.991846 -273.76374)
		(mid 140.274802 -273.839917)
		(end 140.557758 -273.76374)
		(width 0.0889)
		(layer "In11.Cu")
		(net "M_L_CPU1_SB_CB<3>")
	)
	(arc
		(start 138.67765 -273.76374)
		(mid 138.859901 -273.71339)
		(end 139.04341 -273.758914)
		(width 0.0889)
		(layer "In11.Cu")
		(net "M_L_CPU1_SB_CB<3>")
	)
	(arc
		(start 144.69237 -273.76374)
		(mid 144.969183 -273.839883)
		(end 145.247614 -273.769836)
		(width 0.0889)
		(layer "In11.Cu")
		(net "M_L_CPU1_SB_CB<3>")
	)
	(arc
		(start 143.386048 -273.758914)
		(mid 143.569556 -273.71342)
		(end 143.751808 -273.76374)
		(width 0.0889)
		(layer "In11.Cu")
		(net "M_L_CPU1_SB_CB<3>")
	)
	(arc
		(start 142.811754 -273.76374)
		(mid 143.09471 -273.839917)
		(end 143.377666 -273.76374)
		(width 0.0889)
		(layer "In11.Cu")
		(net "M_L_CPU1_SB_CB<3>")
	)
	(arc
		(start 145.258028 -273.76374)
		(mid 145.348059 -273.726301)
		(end 145.444718 -273.713448)
		(width 0.0889)
		(layer "In11.Cu")
		(net "M_L_CPU1_SB_CB<3>")
	)
	(arc
		(start 142.437612 -273.76374)
		(mid 142.619863 -273.71339)
		(end 142.803372 -273.758914)
		(width 0.0889)
		(layer "In11.Cu")
		(net "M_L_CPU1_SB_CB<3>")
	)
	(arc
		(start 138.17473 -273.79549)
		(mid 138.429938 -273.838967)
		(end 138.67765 -273.76374)
		(width 0.0889)
		(layer "In11.Cu")
		(net "M_L_CPU1_SB_CB<3>")
	)
	(arc
		(start 143.762222 -273.769836)
		(mid 144.040908 -273.840056)
		(end 144.317974 -273.76374)
		(width 0.0889)
		(layer "In11.Cu")
		(net "M_L_CPU1_SB_CB<3>")
	)
	(arc
		(start 139.626086 -273.758914)
		(mid 139.809594 -273.71342)
		(end 139.991846 -273.76374)
		(width 0.0889)
		(layer "In11.Cu")
		(net "M_L_CPU1_SB_CB<3>")
	)
	(arc
		(start 140.56614 -273.758914)
		(mid 140.749648 -273.71342)
		(end 140.9319 -273.76374)
		(width 0.0889)
		(layer "In11.Cu")
		(net "M_L_CPU1_SB_CB<3>")
	)
	(arc
		(start 141.497812 -273.76374)
		(mid 141.684756 -273.713485)
		(end 141.8717 -273.76374)
		(width 0.0889)
		(layer "In11.Cu")
		(net "M_L_CPU1_SB_CB<3>")
	)
	(arc
		(start 140.9319 -273.76374)
		(mid 141.214856 -273.839917)
		(end 141.497812 -273.76374)
		(width 0.0889)
		(layer "In11.Cu")
		(net "M_L_CPU1_SB_CB<3>")
	)
	(arc
		(start 139.051792 -273.76374)
		(mid 139.334748 -273.839917)
		(end 139.617704 -273.76374)
		(width 0.0889)
		(layer "In11.Cu")
		(net "M_L_CPU1_SB_CB<3>")
	)
	(segment
		(start 138.867896 -273.010376)
		(end 139.334748 -273.276314)
		(width 0.10668)
		(layer "F.Cu")
		(net "M_L_CPU1_SB_CB<2>")
	)
	(segment
		(start 157.452568 -272.981674)
		(end 157.6832 -272.981674)
		(width 0.14478)
		(layer "In11.Cu")
		(net "M_L_CPU1_SB_CB<2>")
	)
	(segment
		(start 171.032424 -279.360376)
		(end 173.693836 -279.360376)
		(width 0.14478)
		(layer "In11.Cu")
		(net "M_L_CPU1_SB_CB<2>")
	)
	(segment
		(start 177.504852 -278.510238)
		(end 178.35499 -279.360376)
		(width 0.14478)
		(layer "In11.Cu")
		(net "M_L_CPU1_SB_CB<2>")
	)
	(segment
		(start 157.508448 -273.943826)
		(end 157.671516 -274.106894)
		(width 0.14478)
		(layer "In11.Cu")
		(net "M_L_CPU1_SB_CB<2>")
	)
	(segment
		(start 158.295848 -274.731226)
		(end 158.458916 -274.894294)
		(width 0.14478)
		(layer "In11.Cu")
		(net "M_L_CPU1_SB_CB<2>")
	)
	(segment
		(start 144.786858 -272.953988)
		(end 144.805146 -272.943574)
		(width 0.0889)
		(layer "In11.Cu")
		(net "M_L_CPU1_SB_CB<2>")
	)
	(segment
		(start 147.535392 -271.474184)
		(end 147.89785 -271.474184)
		(width 0.0889)
		(layer "In11.Cu")
		(net "M_L_CPU1_SB_CB<2>")
	)
	(segment
		(start 156.235908 -271.624044)
		(end 156.235908 -271.836134)
		(width 0.14478)
		(layer "In11.Cu")
		(net "M_L_CPU1_SB_CB<2>")
	)
	(segment
		(start 170.182286 -278.510238)
		(end 171.032424 -279.360376)
		(width 0.14478)
		(layer "In11.Cu")
		(net "M_L_CPU1_SB_CB<2>")
	)
	(segment
		(start 157.6832 -272.981674)
		(end 157.846268 -273.144742)
		(width 0.14478)
		(layer "In11.Cu")
		(net "M_L_CPU1_SB_CB<2>")
	)
	(segment
		(start 157.508448 -273.713194)
		(end 157.508448 -273.943826)
		(width 0.14478)
		(layer "In11.Cu")
		(net "M_L_CPU1_SB_CB<2>")
	)
	(segment
		(start 156.721048 -272.925794)
		(end 156.721048 -273.156426)
		(width 0.14478)
		(layer "In11.Cu")
		(net "M_L_CPU1_SB_CB<2>")
	)
	(segment
		(start 140.453364 -272.948908)
		(end 140.461746 -272.953734)
		(width 0.0889)
		(layer "In11.Cu")
		(net "M_L_CPU1_SB_CB<2>")
	)
	(segment
		(start 156.8958 -272.194274)
		(end 157.058868 -272.357342)
		(width 0.14478)
		(layer "In11.Cu")
		(net "M_L_CPU1_SB_CB<2>")
	)
	(segment
		(start 156.096716 -272.532094)
		(end 156.327348 -272.532094)
		(width 0.14478)
		(layer "In11.Cu")
		(net "M_L_CPU1_SB_CB<2>")
	)
	(segment
		(start 144.77492 -272.960846)
		(end 144.786858 -272.953988)
		(width 0.0889)
		(layer "In11.Cu")
		(net "M_L_CPU1_SB_CB<2>")
	)
	(segment
		(start 147.89785 -271.474184)
		(end 156.086048 -271.474184)
		(width 0.14478)
		(layer "In11.Cu")
		(net "M_L_CPU1_SB_CB<2>")
	)
	(segment
		(start 196.045582 -279.360376)
		(end 196.89572 -278.510238)
		(width 0.14478)
		(layer "In11.Cu")
		(net "M_L_CPU1_SB_CB<2>")
	)
	(segment
		(start 155.933648 -272.138394)
		(end 155.933648 -272.369026)
		(width 0.14478)
		(layer "In11.Cu")
		(net "M_L_CPU1_SB_CB<2>")
	)
	(segment
		(start 144.213326 -272.948908)
		(end 144.221708 -272.953734)
		(width 0.0889)
		(layer "In11.Cu")
		(net "M_L_CPU1_SB_CB<2>")
	)
	(segment
		(start 158.4706 -273.769074)
		(end 158.633668 -273.932142)
		(width 0.14478)
		(layer "In11.Cu")
		(net "M_L_CPU1_SB_CB<2>")
	)
	(segment
		(start 139.488672 -273.010884)
		(end 139.584684 -272.985484)
		(width 0.0889)
		(layer "In11.Cu")
		(net "M_L_CPU1_SB_CB<2>")
	)
	(segment
		(start 147.126198 -271.883378)
		(end 147.535392 -271.474184)
		(width 0.0889)
		(layer "In11.Cu")
		(net "M_L_CPU1_SB_CB<2>")
	)
	(segment
		(start 141.967712 -272.953734)
		(end 141.976094 -272.948908)
		(width 0.0889)
		(layer "In11.Cu")
		(net "M_L_CPU1_SB_CB<2>")
	)
	(segment
		(start 145.843244 -272.864834)
		(end 146.8247 -271.883378)
		(width 0.0889)
		(layer "In11.Cu")
		(net "M_L_CPU1_SB_CB<2>")
	)
	(segment
		(start 164.061902 -279.360376)
		(end 166.123874 -279.360376)
		(width 0.14478)
		(layer "In11.Cu")
		(net "M_L_CPU1_SB_CB<2>")
	)
	(segment
		(start 185.899044 -279.360376)
		(end 188.781944 -279.360376)
		(width 0.14478)
		(layer "In11.Cu")
		(net "M_L_CPU1_SB_CB<2>")
	)
	(segment
		(start 158.633668 -273.932142)
		(end 158.633668 -274.162774)
		(width 0.14478)
		(layer "In11.Cu")
		(net "M_L_CPU1_SB_CB<2>")
	)
	(segment
		(start 156.235908 -271.836134)
		(end 155.933648 -272.138394)
		(width 0.14478)
		(layer "In11.Cu")
		(net "M_L_CPU1_SB_CB<2>")
	)
	(segment
		(start 157.902148 -274.106894)
		(end 158.239968 -273.769074)
		(width 0.14478)
		(layer "In11.Cu")
		(net "M_L_CPU1_SB_CB<2>")
	)
	(segment
		(start 157.671516 -274.106894)
		(end 157.902148 -274.106894)
		(width 0.14478)
		(layer "In11.Cu")
		(net "M_L_CPU1_SB_CB<2>")
	)
	(segment
		(start 158.239968 -273.769074)
		(end 158.4706 -273.769074)
		(width 0.14478)
		(layer "In11.Cu")
		(net "M_L_CPU1_SB_CB<2>")
	)
	(segment
		(start 156.327348 -272.532094)
		(end 156.665168 -272.194274)
		(width 0.14478)
		(layer "In11.Cu")
		(net "M_L_CPU1_SB_CB<2>")
	)
	(segment
		(start 158.458916 -274.894294)
		(end 158.689548 -274.894294)
		(width 0.14478)
		(layer "In11.Cu")
		(net "M_L_CPU1_SB_CB<2>")
	)
	(segment
		(start 174.543974 -278.510238)
		(end 177.504852 -278.510238)
		(width 0.14478)
		(layer "In11.Cu")
		(net "M_L_CPU1_SB_CB<2>")
	)
	(segment
		(start 146.8247 -271.883378)
		(end 147.126198 -271.883378)
		(width 0.0889)
		(layer "In11.Cu")
		(net "M_L_CPU1_SB_CB<2>")
	)
	(segment
		(start 156.721048 -273.156426)
		(end 156.884116 -273.319494)
		(width 0.14478)
		(layer "In11.Cu")
		(net "M_L_CPU1_SB_CB<2>")
	)
	(segment
		(start 156.086048 -271.474184)
		(end 156.235908 -271.624044)
		(width 0.14478)
		(layer "In11.Cu")
		(net "M_L_CPU1_SB_CB<2>")
	)
	(segment
		(start 181.23789 -279.360376)
		(end 182.088028 -278.510238)
		(width 0.14478)
		(layer "In11.Cu")
		(net "M_L_CPU1_SB_CB<2>")
	)
	(segment
		(start 178.35499 -279.360376)
		(end 181.23789 -279.360376)
		(width 0.14478)
		(layer "In11.Cu")
		(net "M_L_CPU1_SB_CB<2>")
	)
	(segment
		(start 201.722736 -278.510238)
		(end 202.147932 -278.935434)
		(width 0.14478)
		(layer "In11.Cu")
		(net "M_L_CPU1_SB_CB<2>")
	)
	(segment
		(start 182.088028 -278.510238)
		(end 185.048906 -278.510238)
		(width 0.14478)
		(layer "In11.Cu")
		(net "M_L_CPU1_SB_CB<2>")
	)
	(segment
		(start 157.058868 -272.357342)
		(end 157.058868 -272.587974)
		(width 0.14478)
		(layer "In11.Cu")
		(net "M_L_CPU1_SB_CB<2>")
	)
	(segment
		(start 156.884116 -273.319494)
		(end 157.114748 -273.319494)
		(width 0.14478)
		(layer "In11.Cu")
		(net "M_L_CPU1_SB_CB<2>")
	)
	(segment
		(start 157.846268 -273.144742)
		(end 157.846268 -273.375374)
		(width 0.14478)
		(layer "In11.Cu")
		(net "M_L_CPU1_SB_CB<2>")
	)
	(segment
		(start 158.689548 -274.894294)
		(end 159.027368 -274.556474)
		(width 0.14478)
		(layer "In11.Cu")
		(net "M_L_CPU1_SB_CB<2>")
	)
	(segment
		(start 158.295848 -274.500594)
		(end 158.295848 -274.731226)
		(width 0.14478)
		(layer "In11.Cu")
		(net "M_L_CPU1_SB_CB<2>")
	)
	(segment
		(start 193.392298 -279.360376)
		(end 196.045582 -279.360376)
		(width 0.14478)
		(layer "In11.Cu")
		(net "M_L_CPU1_SB_CB<2>")
	)
	(segment
		(start 196.89572 -278.510238)
		(end 201.722736 -278.510238)
		(width 0.14478)
		(layer "In11.Cu")
		(net "M_L_CPU1_SB_CB<2>")
	)
	(segment
		(start 157.114748 -273.319494)
		(end 157.452568 -272.981674)
		(width 0.14478)
		(layer "In11.Cu")
		(net "M_L_CPU1_SB_CB<2>")
	)
	(segment
		(start 159.027368 -274.556474)
		(end 159.258 -274.556474)
		(width 0.14478)
		(layer "In11.Cu")
		(net "M_L_CPU1_SB_CB<2>")
	)
	(segment
		(start 166.123874 -279.360376)
		(end 166.974012 -278.510238)
		(width 0.14478)
		(layer "In11.Cu")
		(net "M_L_CPU1_SB_CB<2>")
	)
	(segment
		(start 141.393418 -272.948908)
		(end 141.4018 -272.953734)
		(width 0.0889)
		(layer "In11.Cu")
		(net "M_L_CPU1_SB_CB<2>")
	)
	(segment
		(start 173.693836 -279.360376)
		(end 174.543974 -278.510238)
		(width 0.14478)
		(layer "In11.Cu")
		(net "M_L_CPU1_SB_CB<2>")
	)
	(segment
		(start 157.846268 -273.375374)
		(end 157.508448 -273.713194)
		(width 0.14478)
		(layer "In11.Cu")
		(net "M_L_CPU1_SB_CB<2>")
	)
	(segment
		(start 188.781944 -279.360376)
		(end 189.632082 -278.510238)
		(width 0.14478)
		(layer "In11.Cu")
		(net "M_L_CPU1_SB_CB<2>")
	)
	(segment
		(start 159.258 -274.556474)
		(end 164.061902 -279.360376)
		(width 0.14478)
		(layer "In11.Cu")
		(net "M_L_CPU1_SB_CB<2>")
	)
	(segment
		(start 145.705322 -272.966434)
		(end 145.726912 -272.953988)
		(width 0.0889)
		(layer "In11.Cu")
		(net "M_L_CPU1_SB_CB<2>")
	)
	(segment
		(start 157.058868 -272.587974)
		(end 156.721048 -272.925794)
		(width 0.14478)
		(layer "In11.Cu")
		(net "M_L_CPU1_SB_CB<2>")
	)
	(segment
		(start 189.632082 -278.510238)
		(end 192.54216 -278.510238)
		(width 0.14478)
		(layer "In11.Cu")
		(net "M_L_CPU1_SB_CB<2>")
	)
	(segment
		(start 192.54216 -278.510238)
		(end 193.392298 -279.360376)
		(width 0.14478)
		(layer "In11.Cu")
		(net "M_L_CPU1_SB_CB<2>")
	)
	(segment
		(start 158.633668 -274.162774)
		(end 158.295848 -274.500594)
		(width 0.14478)
		(layer "In11.Cu")
		(net "M_L_CPU1_SB_CB<2>")
	)
	(segment
		(start 139.334748 -273.276314)
		(end 139.488672 -273.010884)
		(width 0.0889)
		(layer "In11.Cu")
		(net "M_L_CPU1_SB_CB<2>")
	)
	(segment
		(start 155.933648 -272.369026)
		(end 156.096716 -272.532094)
		(width 0.14478)
		(layer "In11.Cu")
		(net "M_L_CPU1_SB_CB<2>")
	)
	(segment
		(start 156.665168 -272.194274)
		(end 156.8958 -272.194274)
		(width 0.14478)
		(layer "In11.Cu")
		(net "M_L_CPU1_SB_CB<2>")
	)
	(segment
		(start 185.048906 -278.510238)
		(end 185.899044 -279.360376)
		(width 0.14478)
		(layer "In11.Cu")
		(net "M_L_CPU1_SB_CB<2>")
	)
	(segment
		(start 166.974012 -278.510238)
		(end 170.182286 -278.510238)
		(width 0.14478)
		(layer "In11.Cu")
		(net "M_L_CPU1_SB_CB<2>")
	)
	(arc
		(start 144.805146 -272.943574)
		(mid 144.984375 -272.903421)
		(end 145.161 -272.953734)
		(width 0.0889)
		(layer "In11.Cu")
		(net "M_L_CPU1_SB_CB<2>")
	)
	(arc
		(start 142.341854 -272.953734)
		(mid 142.62481 -273.029911)
		(end 142.907766 -272.953734)
		(width 0.0889)
		(layer "In11.Cu")
		(net "M_L_CPU1_SB_CB<2>")
	)
	(arc
		(start 142.907766 -272.953734)
		(mid 143.09471 -272.903479)
		(end 143.281654 -272.953734)
		(width 0.0889)
		(layer "In11.Cu")
		(net "M_L_CPU1_SB_CB<2>")
	)
	(arc
		(start 143.847566 -272.953734)
		(mid 144.029817 -272.903384)
		(end 144.213326 -272.948908)
		(width 0.0889)
		(layer "In11.Cu")
		(net "M_L_CPU1_SB_CB<2>")
	)
	(arc
		(start 141.4018 -272.953734)
		(mid 141.684756 -273.029911)
		(end 141.967712 -272.953734)
		(width 0.0889)
		(layer "In11.Cu")
		(net "M_L_CPU1_SB_CB<2>")
	)
	(arc
		(start 144.221708 -272.953734)
		(mid 144.497386 -273.029864)
		(end 144.77492 -272.960846)
		(width 0.0889)
		(layer "In11.Cu")
		(net "M_L_CPU1_SB_CB<2>")
	)
	(arc
		(start 140.461746 -272.953734)
		(mid 140.744702 -273.029911)
		(end 141.027658 -272.953734)
		(width 0.0889)
		(layer "In11.Cu")
		(net "M_L_CPU1_SB_CB<2>")
	)
	(arc
		(start 143.281654 -272.953734)
		(mid 143.56461 -273.029911)
		(end 143.847566 -272.953734)
		(width 0.0889)
		(layer "In11.Cu")
		(net "M_L_CPU1_SB_CB<2>")
	)
	(arc
		(start 139.584684 -272.985484)
		(mid 139.839892 -273.028961)
		(end 140.087604 -272.953734)
		(width 0.0889)
		(layer "In11.Cu")
		(net "M_L_CPU1_SB_CB<2>")
	)
	(arc
		(start 145.161 -272.953734)
		(mid 145.431531 -273.03014)
		(end 145.705322 -272.966434)
		(width 0.0889)
		(layer "In11.Cu")
		(net "M_L_CPU1_SB_CB<2>")
	)
	(arc
		(start 141.027658 -272.953734)
		(mid 141.209909 -272.903384)
		(end 141.393418 -272.948908)
		(width 0.0889)
		(layer "In11.Cu")
		(net "M_L_CPU1_SB_CB<2>")
	)
	(arc
		(start 141.976094 -272.948908)
		(mid 142.159602 -272.903414)
		(end 142.341854 -272.953734)
		(width 0.0889)
		(layer "In11.Cu")
		(net "M_L_CPU1_SB_CB<2>")
	)
	(arc
		(start 145.726912 -272.953988)
		(mid 145.787984 -272.913204)
		(end 145.843244 -272.864834)
		(width 0.0889)
		(layer "In11.Cu")
		(net "M_L_CPU1_SB_CB<2>")
	)
	(arc
		(start 140.087604 -272.953734)
		(mid 140.269855 -272.903384)
		(end 140.453364 -272.948908)
		(width 0.0889)
		(layer "In11.Cu")
		(net "M_L_CPU1_SB_CB<2>")
	)
	(segment
		(start 137.927842 -273.010376)
		(end 138.394694 -273.276314)
		(width 0.10668)
		(layer "F.Cu")
		(net "M_L_CPU1_SB_CB<1>")
	)
	(segment
		(start 141.967712 -273.598894)
		(end 141.976094 -273.60372)
		(width 0.0889)
		(layer "In11.Cu")
		(net "M_L_CPU1_SB_CB<1>")
	)
	(segment
		(start 144.777714 -273.592798)
		(end 144.788128 -273.598894)
		(width 0.0889)
		(layer "In11.Cu")
		(net "M_L_CPU1_SB_CB<1>")
	)
	(segment
		(start 159.400494 -275.348954)
		(end 164.2618 -280.21026)
		(width 0.14478)
		(layer "In11.Cu")
		(net "M_L_CPU1_SB_CB<1>")
	)
	(segment
		(start 186.521598 -280.21026)
		(end 188.18987 -280.21026)
		(width 0.14478)
		(layer "In11.Cu")
		(net "M_L_CPU1_SB_CB<1>")
	)
	(segment
		(start 167.092884 -279.360122)
		(end 170.182286 -279.360122)
		(width 0.14478)
		(layer "In11.Cu")
		(net "M_L_CPU1_SB_CB<1>")
	)
	(segment
		(start 164.2618 -280.21026)
		(end 166.242746 -280.21026)
		(width 0.14478)
		(layer "In11.Cu")
		(net "M_L_CPU1_SB_CB<1>")
	)
	(segment
		(start 204.111606 -279.360376)
		(end 206.248 -279.785318)
		(width 0.14478)
		(layer "In11.Cu")
		(net "M_L_CPU1_SB_CB<1>")
	)
	(segment
		(start 194.225672 -280.21026)
		(end 195.336668 -280.21026)
		(width 0.14478)
		(layer "In11.Cu")
		(net "M_L_CPU1_SB_CB<1>")
	)
	(segment
		(start 147.30095 -272.242026)
		(end 147.614132 -271.928844)
		(width 0.0889)
		(layer "In11.Cu")
		(net "M_L_CPU1_SB_CB<1>")
	)
	(segment
		(start 178.5112 -280.21026)
		(end 181.16169 -280.21026)
		(width 0.14478)
		(layer "In11.Cu")
		(net "M_L_CPU1_SB_CB<1>")
	)
	(segment
		(start 170.182286 -279.360122)
		(end 171.032424 -280.21026)
		(width 0.14478)
		(layer "In11.Cu")
		(net "M_L_CPU1_SB_CB<1>")
	)
	(segment
		(start 171.032424 -280.21026)
		(end 173.7868 -280.21026)
		(width 0.14478)
		(layer "In11.Cu")
		(net "M_L_CPU1_SB_CB<1>")
	)
	(segment
		(start 188.18987 -280.21026)
		(end 190.241682 -279.360376)
		(width 0.14478)
		(layer "In11.Cu")
		(net "M_L_CPU1_SB_CB<1>")
	)
	(segment
		(start 145.444718 -273.522948)
		(end 145.618454 -273.522948)
		(width 0.0889)
		(layer "In11.Cu")
		(net "M_L_CPU1_SB_CB<1>")
	)
	(segment
		(start 154.850084 -271.928844)
		(end 158.270194 -275.348954)
		(width 0.14478)
		(layer "In11.Cu")
		(net "M_L_CPU1_SB_CB<1>")
	)
	(segment
		(start 140.453364 -273.60372)
		(end 140.461746 -273.598894)
		(width 0.0889)
		(layer "In11.Cu")
		(net "M_L_CPU1_SB_CB<1>")
	)
	(segment
		(start 141.393418 -273.60372)
		(end 141.4018 -273.598894)
		(width 0.0889)
		(layer "In11.Cu")
		(net "M_L_CPU1_SB_CB<1>")
	)
	(segment
		(start 190.241682 -279.360376)
		(end 192.17386 -279.360376)
		(width 0.14478)
		(layer "In11.Cu")
		(net "M_L_CPU1_SB_CB<1>")
	)
	(segment
		(start 145.618454 -273.522948)
		(end 146.899376 -272.242026)
		(width 0.0889)
		(layer "In11.Cu")
		(net "M_L_CPU1_SB_CB<1>")
	)
	(segment
		(start 138.24077 -273.541744)
		(end 138.263122 -273.625056)
		(width 0.0889)
		(layer "In11.Cu")
		(net "M_L_CPU1_SB_CB<1>")
	)
	(segment
		(start 181.16169 -280.21026)
		(end 182.011574 -279.360376)
		(width 0.14478)
		(layer "In11.Cu")
		(net "M_L_CPU1_SB_CB<1>")
	)
	(segment
		(start 138.394694 -273.276314)
		(end 138.24077 -273.541744)
		(width 0.0889)
		(layer "In11.Cu")
		(net "M_L_CPU1_SB_CB<1>")
	)
	(segment
		(start 184.469786 -279.360376)
		(end 186.521598 -280.21026)
		(width 0.14478)
		(layer "In11.Cu")
		(net "M_L_CPU1_SB_CB<1>")
	)
	(segment
		(start 145.150332 -273.605752)
		(end 145.162016 -273.598894)
		(width 0.0889)
		(layer "In11.Cu")
		(net "M_L_CPU1_SB_CB<1>")
	)
	(segment
		(start 182.011574 -279.360376)
		(end 184.469786 -279.360376)
		(width 0.14478)
		(layer "In11.Cu")
		(net "M_L_CPU1_SB_CB<1>")
	)
	(segment
		(start 195.336668 -280.21026)
		(end 197.38848 -279.360376)
		(width 0.14478)
		(layer "In11.Cu")
		(net "M_L_CPU1_SB_CB<1>")
	)
	(segment
		(start 146.899376 -272.242026)
		(end 147.30095 -272.242026)
		(width 0.0889)
		(layer "In11.Cu")
		(net "M_L_CPU1_SB_CB<1>")
	)
	(segment
		(start 192.17386 -279.360376)
		(end 194.225672 -280.21026)
		(width 0.14478)
		(layer "In11.Cu")
		(net "M_L_CPU1_SB_CB<1>")
	)
	(segment
		(start 177.661316 -279.360376)
		(end 178.5112 -280.21026)
		(width 0.14478)
		(layer "In11.Cu")
		(net "M_L_CPU1_SB_CB<1>")
	)
	(segment
		(start 166.242746 -280.21026)
		(end 167.092884 -279.360122)
		(width 0.14478)
		(layer "In11.Cu")
		(net "M_L_CPU1_SB_CB<1>")
	)
	(segment
		(start 173.7868 -280.21026)
		(end 174.636684 -279.360376)
		(width 0.14478)
		(layer "In11.Cu")
		(net "M_L_CPU1_SB_CB<1>")
	)
	(segment
		(start 147.614132 -271.928844)
		(end 147.99183 -271.928844)
		(width 0.0889)
		(layer "In11.Cu")
		(net "M_L_CPU1_SB_CB<1>")
	)
	(segment
		(start 174.636684 -279.360376)
		(end 177.661316 -279.360376)
		(width 0.14478)
		(layer "In11.Cu")
		(net "M_L_CPU1_SB_CB<1>")
	)
	(segment
		(start 197.38848 -279.360376)
		(end 204.111606 -279.360376)
		(width 0.14478)
		(layer "In11.Cu")
		(net "M_L_CPU1_SB_CB<1>")
	)
	(segment
		(start 158.270194 -275.348954)
		(end 159.400494 -275.348954)
		(width 0.14478)
		(layer "In11.Cu")
		(net "M_L_CPU1_SB_CB<1>")
	)
	(segment
		(start 147.99183 -271.928844)
		(end 154.850084 -271.928844)
		(width 0.14478)
		(layer "In11.Cu")
		(net "M_L_CPU1_SB_CB<1>")
	)
	(arc
		(start 143.281654 -273.598894)
		(mid 143.56461 -273.522717)
		(end 143.847566 -273.598894)
		(width 0.0889)
		(layer "In11.Cu")
		(net "M_L_CPU1_SB_CB<1>")
	)
	(arc
		(start 139.147804 -273.598894)
		(mid 139.334748 -273.649149)
		(end 139.521692 -273.598894)
		(width 0.0889)
		(layer "In11.Cu")
		(net "M_L_CPU1_SB_CB<1>")
	)
	(arc
		(start 138.263122 -273.625056)
		(mid 138.425454 -273.647874)
		(end 138.581892 -273.598894)
		(width 0.0889)
		(layer "In11.Cu")
		(net "M_L_CPU1_SB_CB<1>")
	)
	(arc
		(start 141.027658 -273.598894)
		(mid 141.209909 -273.649244)
		(end 141.393418 -273.60372)
		(width 0.0889)
		(layer "In11.Cu")
		(net "M_L_CPU1_SB_CB<1>")
	)
	(arc
		(start 140.087604 -273.598894)
		(mid 140.269855 -273.649244)
		(end 140.453364 -273.60372)
		(width 0.0889)
		(layer "In11.Cu")
		(net "M_L_CPU1_SB_CB<1>")
	)
	(arc
		(start 142.341854 -273.598894)
		(mid 142.62481 -273.522717)
		(end 142.907766 -273.598894)
		(width 0.0889)
		(layer "In11.Cu")
		(net "M_L_CPU1_SB_CB<1>")
	)
	(arc
		(start 140.461746 -273.598894)
		(mid 140.744702 -273.522717)
		(end 141.027658 -273.598894)
		(width 0.0889)
		(layer "In11.Cu")
		(net "M_L_CPU1_SB_CB<1>")
	)
	(arc
		(start 141.976094 -273.60372)
		(mid 142.159602 -273.649214)
		(end 142.341854 -273.598894)
		(width 0.0889)
		(layer "In11.Cu")
		(net "M_L_CPU1_SB_CB<1>")
	)
	(arc
		(start 141.4018 -273.598894)
		(mid 141.684756 -273.522717)
		(end 141.967712 -273.598894)
		(width 0.0889)
		(layer "In11.Cu")
		(net "M_L_CPU1_SB_CB<1>")
	)
	(arc
		(start 144.788128 -273.598894)
		(mid 144.968333 -273.649211)
		(end 145.150332 -273.605752)
		(width 0.0889)
		(layer "In11.Cu")
		(net "M_L_CPU1_SB_CB<1>")
	)
	(arc
		(start 144.221962 -273.598894)
		(mid 144.499029 -273.522623)
		(end 144.777714 -273.592798)
		(width 0.0889)
		(layer "In11.Cu")
		(net "M_L_CPU1_SB_CB<1>")
	)
	(arc
		(start 145.162016 -273.598894)
		(mid 145.29835 -273.542251)
		(end 145.444718 -273.522948)
		(width 0.0889)
		(layer "In11.Cu")
		(net "M_L_CPU1_SB_CB<1>")
	)
	(arc
		(start 138.581892 -273.598894)
		(mid 138.864848 -273.522717)
		(end 139.147804 -273.598894)
		(width 0.0889)
		(layer "In11.Cu")
		(net "M_L_CPU1_SB_CB<1>")
	)
	(arc
		(start 139.521692 -273.598894)
		(mid 139.804648 -273.522717)
		(end 140.087604 -273.598894)
		(width 0.0889)
		(layer "In11.Cu")
		(net "M_L_CPU1_SB_CB<1>")
	)
	(arc
		(start 142.907766 -273.598894)
		(mid 143.09471 -273.649149)
		(end 143.281654 -273.598894)
		(width 0.0889)
		(layer "In11.Cu")
		(net "M_L_CPU1_SB_CB<1>")
	)
	(arc
		(start 143.847566 -273.598894)
		(mid 144.034764 -273.649276)
		(end 144.221962 -273.598894)
		(width 0.0889)
		(layer "In11.Cu")
		(net "M_L_CPU1_SB_CB<1>")
	)
	(segment
		(start 139.337796 -272.20037)
		(end 139.804648 -272.466308)
		(width 0.10668)
		(layer "F.Cu")
		(net "M_L_CPU1_SB_CB<0>")
	)
	(segment
		(start 174.627286 -277.669752)
		(end 177.426874 -277.669752)
		(width 0.14478)
		(layer "In11.Cu")
		(net "M_L_CPU1_SB_CB<0>")
	)
	(segment
		(start 144.677638 -272.796508)
		(end 144.691354 -272.788634)
		(width 0.0889)
		(layer "In11.Cu")
		(net "M_L_CPU1_SB_CB<0>")
	)
	(segment
		(start 145.611088 -272.800064)
		(end 145.631154 -272.788634)
		(width 0.0889)
		(layer "In11.Cu")
		(net "M_L_CPU1_SB_CB<0>")
	)
	(segment
		(start 204.982064 -278.371046)
		(end 205.126844 -278.226266)
		(width 0.14478)
		(layer "In11.Cu")
		(net "M_L_CPU1_SB_CB<0>")
	)
	(segment
		(start 185.04408 -277.669752)
		(end 185.893964 -278.519636)
		(width 0.14478)
		(layer "In11.Cu")
		(net "M_L_CPU1_SB_CB<0>")
	)
	(segment
		(start 145.708624 -272.72996)
		(end 145.86077 -272.577814)
		(width 0.0889)
		(layer "In11.Cu")
		(net "M_L_CPU1_SB_CB<0>")
	)
	(segment
		(start 142.803372 -272.793714)
		(end 142.811754 -272.788888)
		(width 0.0889)
		(layer "In11.Cu")
		(net "M_L_CPU1_SB_CB<0>")
	)
	(segment
		(start 203.75499 -277.669498)
		(end 203.764388 -277.6601)
		(width 0.14478)
		(layer "In11.Cu")
		(net "M_L_CPU1_SB_CB<0>")
	)
	(segment
		(start 145.70837 -272.72996)
		(end 145.708624 -272.72996)
		(width 0.0889)
		(layer "In11.Cu")
		(net "M_L_CPU1_SB_CB<0>")
	)
	(segment
		(start 197.073266 -277.669498)
		(end 203.75499 -277.669498)
		(width 0.14478)
		(layer "In11.Cu")
		(net "M_L_CPU1_SB_CB<0>")
	)
	(segment
		(start 203.764388 -277.6601)
		(end 204.418184 -277.6601)
		(width 0.14478)
		(layer "In11.Cu")
		(net "M_L_CPU1_SB_CB<0>")
	)
	(segment
		(start 166.242746 -278.510492)
		(end 166.737792 -278.015446)
		(width 0.14478)
		(layer "In11.Cu")
		(net "M_L_CPU1_SB_CB<0>")
	)
	(segment
		(start 178.276758 -278.519636)
		(end 181.321456 -278.519636)
		(width 0.14478)
		(layer "In11.Cu")
		(net "M_L_CPU1_SB_CB<0>")
	)
	(segment
		(start 166.737792 -278.015446)
		(end 170.472354 -278.015446)
		(width 0.14478)
		(layer "In11.Cu")
		(net "M_L_CPU1_SB_CB<0>")
	)
	(segment
		(start 145.86077 -272.003012)
		(end 146.844258 -271.019524)
		(width 0.0889)
		(layer "In11.Cu")
		(net "M_L_CPU1_SB_CB<0>")
	)
	(segment
		(start 188.86551 -278.519636)
		(end 189.715394 -277.669752)
		(width 0.14478)
		(layer "In11.Cu")
		(net "M_L_CPU1_SB_CB<0>")
	)
	(segment
		(start 181.321456 -278.519636)
		(end 182.17134 -277.669752)
		(width 0.14478)
		(layer "In11.Cu")
		(net "M_L_CPU1_SB_CB<0>")
	)
	(segment
		(start 170.976798 -278.51989)
		(end 173.777148 -278.51989)
		(width 0.14478)
		(layer "In11.Cu")
		(net "M_L_CPU1_SB_CB<0>")
	)
	(segment
		(start 205.271624 -277.6601)
		(end 205.822804 -277.6601)
		(width 0.14478)
		(layer "In11.Cu")
		(net "M_L_CPU1_SB_CB<0>")
	)
	(segment
		(start 205.126844 -277.80488)
		(end 205.271624 -277.6601)
		(width 0.14478)
		(layer "In11.Cu")
		(net "M_L_CPU1_SB_CB<0>")
	)
	(segment
		(start 193.37401 -278.519636)
		(end 196.223128 -278.519636)
		(width 0.14478)
		(layer "In11.Cu")
		(net "M_L_CPU1_SB_CB<0>")
	)
	(segment
		(start 204.418184 -277.6601)
		(end 204.562964 -277.80488)
		(width 0.14478)
		(layer "In11.Cu")
		(net "M_L_CPU1_SB_CB<0>")
	)
	(segment
		(start 146.844258 -271.019524)
		(end 147.89785 -271.019524)
		(width 0.0889)
		(layer "In11.Cu")
		(net "M_L_CPU1_SB_CB<0>")
	)
	(segment
		(start 144.691354 -272.788634)
		(end 144.712944 -272.776188)
		(width 0.0889)
		(layer "In11.Cu")
		(net "M_L_CPU1_SB_CB<0>")
	)
	(segment
		(start 189.715394 -277.669752)
		(end 192.524126 -277.669752)
		(width 0.14478)
		(layer "In11.Cu")
		(net "M_L_CPU1_SB_CB<0>")
	)
	(segment
		(start 139.650724 -272.731738)
		(end 139.673076 -272.81505)
		(width 0.0889)
		(layer "In11.Cu")
		(net "M_L_CPU1_SB_CB<0>")
	)
	(segment
		(start 205.822804 -277.6601)
		(end 206.248 -278.085296)
		(width 0.14478)
		(layer "In11.Cu")
		(net "M_L_CPU1_SB_CB<0>")
	)
	(segment
		(start 173.777148 -278.51989)
		(end 174.627286 -277.669752)
		(width 0.14478)
		(layer "In11.Cu")
		(net "M_L_CPU1_SB_CB<0>")
	)
	(segment
		(start 147.89785 -271.019524)
		(end 156.364432 -271.019524)
		(width 0.14478)
		(layer "In11.Cu")
		(net "M_L_CPU1_SB_CB<0>")
	)
	(segment
		(start 185.893964 -278.519636)
		(end 188.86551 -278.519636)
		(width 0.14478)
		(layer "In11.Cu")
		(net "M_L_CPU1_SB_CB<0>")
	)
	(segment
		(start 170.472354 -278.015446)
		(end 170.976798 -278.51989)
		(width 0.14478)
		(layer "In11.Cu")
		(net "M_L_CPU1_SB_CB<0>")
	)
	(segment
		(start 204.562964 -278.226266)
		(end 204.707744 -278.371046)
		(width 0.14478)
		(layer "In11.Cu")
		(net "M_L_CPU1_SB_CB<0>")
	)
	(segment
		(start 192.524126 -277.669752)
		(end 193.37401 -278.519636)
		(width 0.14478)
		(layer "In11.Cu")
		(net "M_L_CPU1_SB_CB<0>")
	)
	(segment
		(start 204.707744 -278.371046)
		(end 204.982064 -278.371046)
		(width 0.14478)
		(layer "In11.Cu")
		(net "M_L_CPU1_SB_CB<0>")
	)
	(segment
		(start 196.223128 -278.519636)
		(end 197.073266 -277.669498)
		(width 0.14478)
		(layer "In11.Cu")
		(net "M_L_CPU1_SB_CB<0>")
	)
	(segment
		(start 156.364432 -271.019524)
		(end 163.8554 -278.510492)
		(width 0.14478)
		(layer "In11.Cu")
		(net "M_L_CPU1_SB_CB<0>")
	)
	(segment
		(start 163.8554 -278.510492)
		(end 166.242746 -278.510492)
		(width 0.14478)
		(layer "In11.Cu")
		(net "M_L_CPU1_SB_CB<0>")
	)
	(segment
		(start 145.86077 -272.577814)
		(end 145.86077 -272.003012)
		(width 0.0889)
		(layer "In11.Cu")
		(net "M_L_CPU1_SB_CB<0>")
	)
	(segment
		(start 177.426874 -277.669752)
		(end 178.276758 -278.519636)
		(width 0.14478)
		(layer "In11.Cu")
		(net "M_L_CPU1_SB_CB<0>")
	)
	(segment
		(start 140.557758 -272.788888)
		(end 140.56614 -272.793714)
		(width 0.0889)
		(layer "In11.Cu")
		(net "M_L_CPU1_SB_CB<0>")
	)
	(segment
		(start 205.126844 -278.226266)
		(end 205.126844 -277.80488)
		(width 0.14478)
		(layer "In11.Cu")
		(net "M_L_CPU1_SB_CB<0>")
	)
	(segment
		(start 143.377666 -272.788888)
		(end 143.386048 -272.793714)
		(width 0.0889)
		(layer "In11.Cu")
		(net "M_L_CPU1_SB_CB<0>")
	)
	(segment
		(start 182.17134 -277.669752)
		(end 185.04408 -277.669752)
		(width 0.14478)
		(layer "In11.Cu")
		(net "M_L_CPU1_SB_CB<0>")
	)
	(segment
		(start 204.562964 -277.80488)
		(end 204.562964 -278.226266)
		(width 0.14478)
		(layer "In11.Cu")
		(net "M_L_CPU1_SB_CB<0>")
	)
	(segment
		(start 139.804648 -272.466308)
		(end 139.650724 -272.731738)
		(width 0.0889)
		(layer "In11.Cu")
		(net "M_L_CPU1_SB_CB<0>")
	)
	(arc
		(start 144.31772 -272.788888)
		(mid 144.496707 -272.839058)
		(end 144.677638 -272.796508)
		(width 0.0889)
		(layer "In11.Cu")
		(net "M_L_CPU1_SB_CB<0>")
	)
	(arc
		(start 140.56614 -272.793714)
		(mid 140.749648 -272.839208)
		(end 140.9319 -272.788888)
		(width 0.0889)
		(layer "In11.Cu")
		(net "M_L_CPU1_SB_CB<0>")
	)
	(arc
		(start 143.751808 -272.788888)
		(mid 144.034764 -272.712711)
		(end 144.31772 -272.788888)
		(width 0.0889)
		(layer "In11.Cu")
		(net "M_L_CPU1_SB_CB<0>")
	)
	(arc
		(start 143.386048 -272.793714)
		(mid 143.569556 -272.839208)
		(end 143.751808 -272.788888)
		(width 0.0889)
		(layer "In11.Cu")
		(net "M_L_CPU1_SB_CB<0>")
	)
	(arc
		(start 142.437612 -272.788888)
		(mid 142.619863 -272.839238)
		(end 142.803372 -272.793714)
		(width 0.0889)
		(layer "In11.Cu")
		(net "M_L_CPU1_SB_CB<0>")
	)
	(arc
		(start 144.712944 -272.776188)
		(mid 144.986734 -272.712517)
		(end 145.257266 -272.788888)
		(width 0.0889)
		(layer "In11.Cu")
		(net "M_L_CPU1_SB_CB<0>")
	)
	(arc
		(start 140.9319 -272.788888)
		(mid 141.214856 -272.712711)
		(end 141.497812 -272.788888)
		(width 0.0889)
		(layer "In11.Cu")
		(net "M_L_CPU1_SB_CB<0>")
	)
	(arc
		(start 142.811754 -272.788888)
		(mid 143.09471 -272.712711)
		(end 143.377666 -272.788888)
		(width 0.0889)
		(layer "In11.Cu")
		(net "M_L_CPU1_SB_CB<0>")
	)
	(arc
		(start 145.257266 -272.788888)
		(mid 145.432758 -272.839087)
		(end 145.611088 -272.800064)
		(width 0.0889)
		(layer "In11.Cu")
		(net "M_L_CPU1_SB_CB<0>")
	)
	(arc
		(start 141.497812 -272.788888)
		(mid 141.684756 -272.839143)
		(end 141.8717 -272.788888)
		(width 0.0889)
		(layer "In11.Cu")
		(net "M_L_CPU1_SB_CB<0>")
	)
	(arc
		(start 145.631154 -272.788634)
		(mid 145.671684 -272.761825)
		(end 145.70837 -272.72996)
		(width 0.0889)
		(layer "In11.Cu")
		(net "M_L_CPU1_SB_CB<0>")
	)
	(arc
		(start 139.991846 -272.788888)
		(mid 140.274802 -272.712711)
		(end 140.557758 -272.788888)
		(width 0.0889)
		(layer "In11.Cu")
		(net "M_L_CPU1_SB_CB<0>")
	)
	(arc
		(start 139.673076 -272.81505)
		(mid 139.835408 -272.837868)
		(end 139.991846 -272.788888)
		(width 0.0889)
		(layer "In11.Cu")
		(net "M_L_CPU1_SB_CB<0>")
	)
	(arc
		(start 141.8717 -272.788888)
		(mid 142.154656 -272.712711)
		(end 142.437612 -272.788888)
		(width 0.0889)
		(layer "In11.Cu")
		(net "M_L_CPU1_SB_CB<0>")
	)
	(segment
		(start 139.337796 -264.10031)
		(end 139.804648 -264.366248)
		(width 0.10668)
		(layer "F.Cu")
		(net "M_L_CPU1_SB_CA<6>")
	)
	(segment
		(start 139.655804 -264.622534)
		(end 139.679172 -264.710418)
		(width 0.0889)
		(layer "In11.Cu")
		(net "M_L_CPU1_SB_CA<6>")
	)
	(segment
		(start 178.5112 -266.610338)
		(end 181.330854 -266.610338)
		(width 0.14478)
		(layer "In11.Cu")
		(net "M_L_CPU1_SB_CA<6>")
	)
	(segment
		(start 161.281872 -264.339324)
		(end 163.552886 -266.610338)
		(width 0.14478)
		(layer "In11.Cu")
		(net "M_L_CPU1_SB_CA<6>")
	)
	(segment
		(start 148.023072 -264.339324)
		(end 161.281872 -264.339324)
		(width 0.14478)
		(layer "In11.Cu")
		(net "M_L_CPU1_SB_CA<6>")
	)
	(segment
		(start 145.825718 -264.733278)
		(end 146.28495 -264.274046)
		(width 0.0889)
		(layer "In11.Cu")
		(net "M_L_CPU1_SB_CA<6>")
	)
	(segment
		(start 185.20537 -265.760454)
		(end 186.055254 -266.610338)
		(width 0.14478)
		(layer "In11.Cu")
		(net "M_L_CPU1_SB_CA<6>")
	)
	(segment
		(start 144.32026 -264.68324)
		(end 144.331944 -264.689844)
		(width 0.0889)
		(layer "In11.Cu")
		(net "M_L_CPU1_SB_CA<6>")
	)
	(segment
		(start 177.661316 -265.760454)
		(end 178.5112 -266.610338)
		(width 0.14478)
		(layer "In11.Cu")
		(net "M_L_CPU1_SB_CA<6>")
	)
	(segment
		(start 205.823058 -265.760454)
		(end 206.248 -266.185396)
		(width 0.14478)
		(layer "In11.Cu")
		(net "M_L_CPU1_SB_CA<6>")
	)
	(segment
		(start 139.804648 -264.366248)
		(end 139.655804 -264.622534)
		(width 0.0889)
		(layer "In11.Cu")
		(net "M_L_CPU1_SB_CA<6>")
	)
	(segment
		(start 145.444718 -264.733278)
		(end 145.825718 -264.733278)
		(width 0.0889)
		(layer "In11.Cu")
		(net "M_L_CPU1_SB_CA<6>")
	)
	(segment
		(start 144.301972 -264.672572)
		(end 144.32026 -264.68324)
		(width 0.0889)
		(layer "In11.Cu")
		(net "M_L_CPU1_SB_CA<6>")
	)
	(segment
		(start 147.721828 -264.339324)
		(end 148.023072 -264.339324)
		(width 0.0889)
		(layer "In11.Cu")
		(net "M_L_CPU1_SB_CA<6>")
	)
	(segment
		(start 163.552886 -266.610338)
		(end 173.7868 -266.610338)
		(width 0.14478)
		(layer "In11.Cu")
		(net "M_L_CPU1_SB_CA<6>")
	)
	(segment
		(start 181.330854 -266.610338)
		(end 182.180738 -265.760454)
		(width 0.14478)
		(layer "In11.Cu")
		(net "M_L_CPU1_SB_CA<6>")
	)
	(segment
		(start 174.636684 -265.760454)
		(end 177.661316 -265.760454)
		(width 0.14478)
		(layer "In11.Cu")
		(net "M_L_CPU1_SB_CA<6>")
	)
	(segment
		(start 141.490192 -264.677144)
		(end 141.50086 -264.68324)
		(width 0.0889)
		(layer "In11.Cu")
		(net "M_L_CPU1_SB_CA<6>")
	)
	(segment
		(start 146.28495 -264.274046)
		(end 147.65655 -264.274046)
		(width 0.0889)
		(layer "In11.Cu")
		(net "M_L_CPU1_SB_CA<6>")
	)
	(segment
		(start 189.724792 -265.760454)
		(end 205.823058 -265.760454)
		(width 0.14478)
		(layer "In11.Cu")
		(net "M_L_CPU1_SB_CA<6>")
	)
	(segment
		(start 147.65655 -264.274046)
		(end 147.721828 -264.339324)
		(width 0.0889)
		(layer "In11.Cu")
		(net "M_L_CPU1_SB_CA<6>")
	)
	(segment
		(start 188.874908 -266.610338)
		(end 189.724792 -265.760454)
		(width 0.14478)
		(layer "In11.Cu")
		(net "M_L_CPU1_SB_CA<6>")
	)
	(segment
		(start 186.055254 -266.610338)
		(end 188.874908 -266.610338)
		(width 0.14478)
		(layer "In11.Cu")
		(net "M_L_CPU1_SB_CA<6>")
	)
	(segment
		(start 173.7868 -266.610338)
		(end 174.636684 -265.760454)
		(width 0.14478)
		(layer "In11.Cu")
		(net "M_L_CPU1_SB_CA<6>")
	)
	(segment
		(start 182.180738 -265.760454)
		(end 185.20537 -265.760454)
		(width 0.14478)
		(layer "In11.Cu")
		(net "M_L_CPU1_SB_CA<6>")
	)
	(segment
		(start 140.550138 -264.677144)
		(end 140.560806 -264.68324)
		(width 0.0889)
		(layer "In11.Cu")
		(net "M_L_CPU1_SB_CA<6>")
	)
	(segment
		(start 141.868652 -264.68324)
		(end 141.87932 -264.677144)
		(width 0.0889)
		(layer "In11.Cu")
		(net "M_L_CPU1_SB_CA<6>")
	)
	(segment
		(start 144.687544 -264.68324)
		(end 144.705832 -264.672572)
		(width 0.0889)
		(layer "In11.Cu")
		(net "M_L_CPU1_SB_CA<6>")
	)
	(arc
		(start 140.560806 -264.68324)
		(mid 140.744702 -264.73272)
		(end 140.928598 -264.68324)
		(width 0.0889)
		(layer "In11.Cu")
		(net "M_L_CPU1_SB_CA<6>")
	)
	(arc
		(start 139.988544 -264.68324)
		(mid 140.268548 -264.606195)
		(end 140.550138 -264.677144)
		(width 0.0889)
		(layer "In11.Cu")
		(net "M_L_CPU1_SB_CA<6>")
	)
	(arc
		(start 140.928598 -264.68324)
		(mid 141.208602 -264.606195)
		(end 141.490192 -264.677144)
		(width 0.0889)
		(layer "In11.Cu")
		(net "M_L_CPU1_SB_CA<6>")
	)
	(arc
		(start 142.808706 -264.68324)
		(mid 143.09471 -264.606288)
		(end 143.380714 -264.68324)
		(width 0.0889)
		(layer "In11.Cu")
		(net "M_L_CPU1_SB_CA<6>")
	)
	(arc
		(start 145.260314 -264.68324)
		(mid 145.349201 -264.720472)
		(end 145.444718 -264.733278)
		(width 0.0889)
		(layer "In11.Cu")
		(net "M_L_CPU1_SB_CA<6>")
	)
	(arc
		(start 142.440914 -264.68324)
		(mid 142.62481 -264.73272)
		(end 142.808706 -264.68324)
		(width 0.0889)
		(layer "In11.Cu")
		(net "M_L_CPU1_SB_CA<6>")
	)
	(arc
		(start 144.705832 -264.672572)
		(mid 144.984465 -264.605949)
		(end 145.260314 -264.68324)
		(width 0.0889)
		(layer "In11.Cu")
		(net "M_L_CPU1_SB_CA<6>")
	)
	(arc
		(start 144.331944 -264.689844)
		(mid 144.510613 -264.732634)
		(end 144.687544 -264.68324)
		(width 0.0889)
		(layer "In11.Cu")
		(net "M_L_CPU1_SB_CA<6>")
	)
	(arc
		(start 143.748506 -264.68324)
		(mid 144.023848 -264.606265)
		(end 144.301972 -264.672572)
		(width 0.0889)
		(layer "In11.Cu")
		(net "M_L_CPU1_SB_CA<6>")
	)
	(arc
		(start 141.87932 -264.677144)
		(mid 142.160909 -264.60627)
		(end 142.440914 -264.68324)
		(width 0.0889)
		(layer "In11.Cu")
		(net "M_L_CPU1_SB_CA<6>")
	)
	(arc
		(start 141.50086 -264.68324)
		(mid 141.684756 -264.73272)
		(end 141.868652 -264.68324)
		(width 0.0889)
		(layer "In11.Cu")
		(net "M_L_CPU1_SB_CA<6>")
	)
	(arc
		(start 139.679172 -264.710418)
		(mid 139.836891 -264.731265)
		(end 139.988544 -264.68324)
		(width 0.0889)
		(layer "In11.Cu")
		(net "M_L_CPU1_SB_CA<6>")
	)
	(arc
		(start 143.380714 -264.68324)
		(mid 143.56461 -264.73272)
		(end 143.748506 -264.68324)
		(width 0.0889)
		(layer "In11.Cu")
		(net "M_L_CPU1_SB_CA<6>")
	)
	(segment
		(start 137.457942 -264.10031)
		(end 137.924794 -264.366248)
		(width 0.10668)
		(layer "F.Cu")
		(net "M_L_CPU1_SB_CA<5>")
	)
	(segment
		(start 200.531222 -264.685526)
		(end 200.676002 -264.540746)
		(width 0.14478)
		(layer "In11.Cu")
		(net "M_L_CPU1_SB_CA<5>")
	)
	(segment
		(start 143.377666 -264.043668)
		(end 143.386048 -264.038842)
		(width 0.0889)
		(layer "In11.Cu")
		(net "M_L_CPU1_SB_CA<5>")
	)
	(segment
		(start 201.082656 -264.685526)
		(end 201.082656 -264.765536)
		(width 0.14478)
		(layer "In11.Cu")
		(net "M_L_CPU1_SB_CA<5>")
	)
	(segment
		(start 181.23789 -265.760454)
		(end 182.088028 -264.910316)
		(width 0.14478)
		(layer "In11.Cu")
		(net "M_L_CPU1_SB_CA<5>")
	)
	(segment
		(start 148.006054 -263.884664)
		(end 161.779204 -263.884664)
		(width 0.14478)
		(layer "In11.Cu")
		(net "M_L_CPU1_SB_CA<5>")
	)
	(segment
		(start 185.270394 -264.910316)
		(end 186.120532 -265.760454)
		(width 0.14478)
		(layer "In11.Cu")
		(net "M_L_CPU1_SB_CA<5>")
	)
	(segment
		(start 145.444718 -263.99363)
		(end 147.332446 -263.99363)
		(width 0.0889)
		(layer "In11.Cu")
		(net "M_L_CPU1_SB_CA<5>")
	)
	(segment
		(start 200.676002 -264.540746)
		(end 200.937876 -264.540746)
		(width 0.14478)
		(layer "In11.Cu")
		(net "M_L_CPU1_SB_CA<5>")
	)
	(segment
		(start 138.078718 -264.100818)
		(end 138.17473 -264.075418)
		(width 0.0889)
		(layer "In11.Cu")
		(net "M_L_CPU1_SB_CA<5>")
	)
	(segment
		(start 145.236946 -264.056368)
		(end 145.258536 -264.043922)
		(width 0.0889)
		(layer "In11.Cu")
		(net "M_L_CPU1_SB_CA<5>")
	)
	(segment
		(start 201.72299 -264.910316)
		(end 202.147932 -265.335258)
		(width 0.14478)
		(layer "In11.Cu")
		(net "M_L_CPU1_SB_CA<5>")
	)
	(segment
		(start 140.557758 -264.043668)
		(end 140.56614 -264.038842)
		(width 0.0889)
		(layer "In11.Cu")
		(net "M_L_CPU1_SB_CA<5>")
	)
	(segment
		(start 186.120532 -265.760454)
		(end 188.781944 -265.760454)
		(width 0.14478)
		(layer "In11.Cu")
		(net "M_L_CPU1_SB_CA<5>")
	)
	(segment
		(start 199.428354 -264.685526)
		(end 199.573134 -264.540746)
		(width 0.14478)
		(layer "In11.Cu")
		(net "M_L_CPU1_SB_CA<5>")
	)
	(segment
		(start 163.654994 -265.760454)
		(end 173.693836 -265.760454)
		(width 0.14478)
		(layer "In11.Cu")
		(net "M_L_CPU1_SB_CA<5>")
	)
	(segment
		(start 147.441412 -263.884664)
		(end 148.006054 -263.884664)
		(width 0.0889)
		(layer "In11.Cu")
		(net "M_L_CPU1_SB_CA<5>")
	)
	(segment
		(start 199.835008 -264.540746)
		(end 199.979788 -264.685526)
		(width 0.14478)
		(layer "In11.Cu")
		(net "M_L_CPU1_SB_CA<5>")
	)
	(segment
		(start 188.781944 -265.760454)
		(end 189.632082 -264.910316)
		(width 0.14478)
		(layer "In11.Cu")
		(net "M_L_CPU1_SB_CA<5>")
	)
	(segment
		(start 174.543974 -264.910316)
		(end 177.72634 -264.910316)
		(width 0.14478)
		(layer "In11.Cu")
		(net "M_L_CPU1_SB_CA<5>")
	)
	(segment
		(start 200.124568 -265.279886)
		(end 200.386442 -265.279886)
		(width 0.14478)
		(layer "In11.Cu")
		(net "M_L_CPU1_SB_CA<5>")
	)
	(segment
		(start 173.693836 -265.760454)
		(end 174.543974 -264.910316)
		(width 0.14478)
		(layer "In11.Cu")
		(net "M_L_CPU1_SB_CA<5>")
	)
	(segment
		(start 182.088028 -264.910316)
		(end 185.270394 -264.910316)
		(width 0.14478)
		(layer "In11.Cu")
		(net "M_L_CPU1_SB_CA<5>")
	)
	(segment
		(start 139.04341 -264.038842)
		(end 139.051792 -264.043668)
		(width 0.0889)
		(layer "In11.Cu")
		(net "M_L_CPU1_SB_CA<5>")
	)
	(segment
		(start 178.576478 -265.760454)
		(end 181.23789 -265.760454)
		(width 0.14478)
		(layer "In11.Cu")
		(net "M_L_CPU1_SB_CA<5>")
	)
	(segment
		(start 177.72634 -264.910316)
		(end 178.576478 -265.760454)
		(width 0.14478)
		(layer "In11.Cu")
		(net "M_L_CPU1_SB_CA<5>")
	)
	(segment
		(start 147.332446 -263.99363)
		(end 147.441412 -263.884664)
		(width 0.0889)
		(layer "In11.Cu")
		(net "M_L_CPU1_SB_CA<5>")
	)
	(segment
		(start 199.979788 -264.685526)
		(end 199.979788 -265.135106)
		(width 0.14478)
		(layer "In11.Cu")
		(net "M_L_CPU1_SB_CA<5>")
	)
	(segment
		(start 200.386442 -265.279886)
		(end 200.531222 -265.135106)
		(width 0.14478)
		(layer "In11.Cu")
		(net "M_L_CPU1_SB_CA<5>")
	)
	(segment
		(start 201.227436 -264.910316)
		(end 201.72299 -264.910316)
		(width 0.14478)
		(layer "In11.Cu")
		(net "M_L_CPU1_SB_CA<5>")
	)
	(segment
		(start 189.632082 -264.910316)
		(end 199.283574 -264.910316)
		(width 0.14478)
		(layer "In11.Cu")
		(net "M_L_CPU1_SB_CA<5>")
	)
	(segment
		(start 199.573134 -264.540746)
		(end 199.835008 -264.540746)
		(width 0.14478)
		(layer "In11.Cu")
		(net "M_L_CPU1_SB_CA<5>")
	)
	(segment
		(start 200.937876 -264.540746)
		(end 201.082656 -264.685526)
		(width 0.14478)
		(layer "In11.Cu")
		(net "M_L_CPU1_SB_CA<5>")
	)
	(segment
		(start 139.617704 -264.043668)
		(end 139.626086 -264.038842)
		(width 0.0889)
		(layer "In11.Cu")
		(net "M_L_CPU1_SB_CA<5>")
	)
	(segment
		(start 161.779204 -263.884664)
		(end 163.654994 -265.760454)
		(width 0.14478)
		(layer "In11.Cu")
		(net "M_L_CPU1_SB_CA<5>")
	)
	(segment
		(start 137.924794 -264.366248)
		(end 138.078718 -264.100818)
		(width 0.0889)
		(layer "In11.Cu")
		(net "M_L_CPU1_SB_CA<5>")
	)
	(segment
		(start 200.531222 -265.135106)
		(end 200.531222 -264.685526)
		(width 0.14478)
		(layer "In11.Cu")
		(net "M_L_CPU1_SB_CA<5>")
	)
	(segment
		(start 199.979788 -265.135106)
		(end 200.124568 -265.279886)
		(width 0.14478)
		(layer "In11.Cu")
		(net "M_L_CPU1_SB_CA<5>")
	)
	(segment
		(start 144.67967 -264.035286)
		(end 144.694148 -264.043668)
		(width 0.0889)
		(layer "In11.Cu")
		(net "M_L_CPU1_SB_CA<5>")
	)
	(segment
		(start 142.803372 -264.038842)
		(end 142.811754 -264.043668)
		(width 0.0889)
		(layer "In11.Cu")
		(net "M_L_CPU1_SB_CA<5>")
	)
	(segment
		(start 199.283574 -264.910316)
		(end 199.428354 -264.765536)
		(width 0.14478)
		(layer "In11.Cu")
		(net "M_L_CPU1_SB_CA<5>")
	)
	(segment
		(start 199.428354 -264.765536)
		(end 199.428354 -264.685526)
		(width 0.14478)
		(layer "In11.Cu")
		(net "M_L_CPU1_SB_CA<5>")
	)
	(segment
		(start 201.082656 -264.765536)
		(end 201.227436 -264.910316)
		(width 0.14478)
		(layer "In11.Cu")
		(net "M_L_CPU1_SB_CA<5>")
	)
	(segment
		(start 143.751808 -264.043668)
		(end 143.775176 -264.057384)
		(width 0.0889)
		(layer "In11.Cu")
		(net "M_L_CPU1_SB_CA<5>")
	)
	(arc
		(start 142.437612 -264.043668)
		(mid 142.619863 -263.993318)
		(end 142.803372 -264.038842)
		(width 0.0889)
		(layer "In11.Cu")
		(net "M_L_CPU1_SB_CA<5>")
	)
	(arc
		(start 144.694148 -264.043668)
		(mid 144.963917 -264.119691)
		(end 145.236946 -264.056368)
		(width 0.0889)
		(layer "In11.Cu")
		(net "M_L_CPU1_SB_CA<5>")
	)
	(arc
		(start 142.811754 -264.043668)
		(mid 143.09471 -264.119845)
		(end 143.377666 -264.043668)
		(width 0.0889)
		(layer "In11.Cu")
		(net "M_L_CPU1_SB_CA<5>")
	)
	(arc
		(start 143.386048 -264.038842)
		(mid 143.569556 -263.993348)
		(end 143.751808 -264.043668)
		(width 0.0889)
		(layer "In11.Cu")
		(net "M_L_CPU1_SB_CA<5>")
	)
	(arc
		(start 140.56614 -264.038842)
		(mid 140.749648 -263.993348)
		(end 140.9319 -264.043668)
		(width 0.0889)
		(layer "In11.Cu")
		(net "M_L_CPU1_SB_CA<5>")
	)
	(arc
		(start 139.626086 -264.038842)
		(mid 139.809594 -263.993348)
		(end 139.991846 -264.043668)
		(width 0.0889)
		(layer "In11.Cu")
		(net "M_L_CPU1_SB_CA<5>")
	)
	(arc
		(start 143.775176 -264.057384)
		(mid 144.04883 -264.120327)
		(end 144.31899 -264.043668)
		(width 0.0889)
		(layer "In11.Cu")
		(net "M_L_CPU1_SB_CA<5>")
	)
	(arc
		(start 144.31899 -264.043668)
		(mid 144.498253 -263.993004)
		(end 144.67967 -264.035286)
		(width 0.0889)
		(layer "In11.Cu")
		(net "M_L_CPU1_SB_CA<5>")
	)
	(arc
		(start 138.17473 -264.075418)
		(mid 138.429938 -264.118895)
		(end 138.67765 -264.043668)
		(width 0.0889)
		(layer "In11.Cu")
		(net "M_L_CPU1_SB_CA<5>")
	)
	(arc
		(start 139.991846 -264.043668)
		(mid 140.274802 -264.119845)
		(end 140.557758 -264.043668)
		(width 0.0889)
		(layer "In11.Cu")
		(net "M_L_CPU1_SB_CA<5>")
	)
	(arc
		(start 145.258536 -264.043922)
		(mid 145.348313 -264.006499)
		(end 145.444718 -263.99363)
		(width 0.0889)
		(layer "In11.Cu")
		(net "M_L_CPU1_SB_CA<5>")
	)
	(arc
		(start 140.9319 -264.043668)
		(mid 141.214856 -264.119845)
		(end 141.497812 -264.043668)
		(width 0.0889)
		(layer "In11.Cu")
		(net "M_L_CPU1_SB_CA<5>")
	)
	(arc
		(start 139.051792 -264.043668)
		(mid 139.334748 -264.119845)
		(end 139.617704 -264.043668)
		(width 0.0889)
		(layer "In11.Cu")
		(net "M_L_CPU1_SB_CA<5>")
	)
	(arc
		(start 141.497812 -264.043668)
		(mid 141.684756 -263.993413)
		(end 141.8717 -264.043668)
		(width 0.0889)
		(layer "In11.Cu")
		(net "M_L_CPU1_SB_CA<5>")
	)
	(arc
		(start 138.67765 -264.043668)
		(mid 138.859901 -263.993318)
		(end 139.04341 -264.038842)
		(width 0.0889)
		(layer "In11.Cu")
		(net "M_L_CPU1_SB_CA<5>")
	)
	(arc
		(start 141.8717 -264.043668)
		(mid 142.154656 -264.119845)
		(end 142.437612 -264.043668)
		(width 0.0889)
		(layer "In11.Cu")
		(net "M_L_CPU1_SB_CA<5>")
	)
	(segment
		(start 137.927842 -263.290304)
		(end 138.394694 -263.556242)
		(width 0.10668)
		(layer "F.Cu")
		(net "M_L_CPU1_SB_CA<4>")
	)
	(segment
		(start 188.874908 -264.910316)
		(end 189.724792 -264.060432)
		(width 0.14478)
		(layer "In11.Cu")
		(net "M_L_CPU1_SB_CA<4>")
	)
	(segment
		(start 177.661316 -264.060432)
		(end 178.5112 -264.910316)
		(width 0.14478)
		(layer "In11.Cu")
		(net "M_L_CPU1_SB_CA<4>")
	)
	(segment
		(start 205.823058 -264.060432)
		(end 206.248 -264.485374)
		(width 0.14478)
		(layer "In11.Cu")
		(net "M_L_CPU1_SB_CA<4>")
	)
	(segment
		(start 174.636684 -264.060432)
		(end 177.661316 -264.060432)
		(width 0.14478)
		(layer "In11.Cu")
		(net "M_L_CPU1_SB_CA<4>")
	)
	(segment
		(start 189.724792 -264.060432)
		(end 205.823058 -264.060432)
		(width 0.14478)
		(layer "In11.Cu")
		(net "M_L_CPU1_SB_CA<4>")
	)
	(segment
		(start 147.167346 -263.80313)
		(end 147.540472 -263.430004)
		(width 0.0889)
		(layer "In11.Cu")
		(net "M_L_CPU1_SB_CA<4>")
	)
	(segment
		(start 181.330854 -264.910316)
		(end 182.180738 -264.060432)
		(width 0.14478)
		(layer "In11.Cu")
		(net "M_L_CPU1_SB_CA<4>")
	)
	(segment
		(start 144.766538 -263.865106)
		(end 144.789906 -263.878822)
		(width 0.0889)
		(layer "In11.Cu")
		(net "M_L_CPU1_SB_CA<4>")
	)
	(segment
		(start 147.540472 -263.430004)
		(end 148.045932 -263.430004)
		(width 0.0889)
		(layer "In11.Cu")
		(net "M_L_CPU1_SB_CA<4>")
	)
	(segment
		(start 138.24077 -263.821672)
		(end 138.263122 -263.904984)
		(width 0.0889)
		(layer "In11.Cu")
		(net "M_L_CPU1_SB_CA<4>")
	)
	(segment
		(start 186.055254 -264.910316)
		(end 188.874908 -264.910316)
		(width 0.14478)
		(layer "In11.Cu")
		(net "M_L_CPU1_SB_CA<4>")
	)
	(segment
		(start 140.453364 -263.883648)
		(end 140.461746 -263.878822)
		(width 0.0889)
		(layer "In11.Cu")
		(net "M_L_CPU1_SB_CA<4>")
	)
	(segment
		(start 178.5112 -264.910316)
		(end 181.330854 -264.910316)
		(width 0.14478)
		(layer "In11.Cu")
		(net "M_L_CPU1_SB_CA<4>")
	)
	(segment
		(start 148.045932 -263.430004)
		(end 162.072574 -263.430004)
		(width 0.14478)
		(layer "In11.Cu")
		(net "M_L_CPU1_SB_CA<4>")
	)
	(segment
		(start 182.180738 -264.060432)
		(end 185.20537 -264.060432)
		(width 0.14478)
		(layer "In11.Cu")
		(net "M_L_CPU1_SB_CA<4>")
	)
	(segment
		(start 138.394694 -263.556242)
		(end 138.24077 -263.821672)
		(width 0.0889)
		(layer "In11.Cu")
		(net "M_L_CPU1_SB_CA<4>")
	)
	(segment
		(start 162.072574 -263.430004)
		(end 163.552886 -264.910316)
		(width 0.14478)
		(layer "In11.Cu")
		(net "M_L_CPU1_SB_CA<4>")
	)
	(segment
		(start 143.847566 -263.878822)
		(end 143.862044 -263.887204)
		(width 0.0889)
		(layer "In11.Cu")
		(net "M_L_CPU1_SB_CA<4>")
	)
	(segment
		(start 163.552886 -264.910316)
		(end 173.7868 -264.910316)
		(width 0.14478)
		(layer "In11.Cu")
		(net "M_L_CPU1_SB_CA<4>")
	)
	(segment
		(start 141.393418 -263.883648)
		(end 141.4018 -263.878822)
		(width 0.0889)
		(layer "In11.Cu")
		(net "M_L_CPU1_SB_CA<4>")
	)
	(segment
		(start 141.967712 -263.878822)
		(end 141.976094 -263.883648)
		(width 0.0889)
		(layer "In11.Cu")
		(net "M_L_CPU1_SB_CA<4>")
	)
	(segment
		(start 145.14322 -263.889998)
		(end 145.163286 -263.878568)
		(width 0.0889)
		(layer "In11.Cu")
		(net "M_L_CPU1_SB_CA<4>")
	)
	(segment
		(start 145.444464 -263.80313)
		(end 147.167346 -263.80313)
		(width 0.0889)
		(layer "In11.Cu")
		(net "M_L_CPU1_SB_CA<4>")
	)
	(segment
		(start 173.7868 -264.910316)
		(end 174.636684 -264.060432)
		(width 0.14478)
		(layer "In11.Cu")
		(net "M_L_CPU1_SB_CA<4>")
	)
	(segment
		(start 185.20537 -264.060432)
		(end 186.055254 -264.910316)
		(width 0.14478)
		(layer "In11.Cu")
		(net "M_L_CPU1_SB_CA<4>")
	)
	(arc
		(start 139.521692 -263.878822)
		(mid 139.804648 -263.802645)
		(end 140.087604 -263.878822)
		(width 0.0889)
		(layer "In11.Cu")
		(net "M_L_CPU1_SB_CA<4>")
	)
	(arc
		(start 145.163286 -263.878568)
		(mid 145.298919 -263.822393)
		(end 145.444464 -263.80313)
		(width 0.0889)
		(layer "In11.Cu")
		(net "M_L_CPU1_SB_CA<4>")
	)
	(arc
		(start 143.862044 -263.887204)
		(mid 144.04346 -263.929461)
		(end 144.222724 -263.878822)
		(width 0.0889)
		(layer "In11.Cu")
		(net "M_L_CPU1_SB_CA<4>")
	)
	(arc
		(start 140.087604 -263.878822)
		(mid 140.269855 -263.929172)
		(end 140.453364 -263.883648)
		(width 0.0889)
		(layer "In11.Cu")
		(net "M_L_CPU1_SB_CA<4>")
	)
	(arc
		(start 139.147804 -263.878822)
		(mid 139.334748 -263.929077)
		(end 139.521692 -263.878822)
		(width 0.0889)
		(layer "In11.Cu")
		(net "M_L_CPU1_SB_CA<4>")
	)
	(arc
		(start 144.222724 -263.878822)
		(mid 144.492881 -263.80206)
		(end 144.766538 -263.865106)
		(width 0.0889)
		(layer "In11.Cu")
		(net "M_L_CPU1_SB_CA<4>")
	)
	(arc
		(start 141.976094 -263.883648)
		(mid 142.159602 -263.929142)
		(end 142.341854 -263.878822)
		(width 0.0889)
		(layer "In11.Cu")
		(net "M_L_CPU1_SB_CA<4>")
	)
	(arc
		(start 142.907766 -263.878822)
		(mid 143.09471 -263.929077)
		(end 143.281654 -263.878822)
		(width 0.0889)
		(layer "In11.Cu")
		(net "M_L_CPU1_SB_CA<4>")
	)
	(arc
		(start 138.263122 -263.904984)
		(mid 138.425454 -263.927802)
		(end 138.581892 -263.878822)
		(width 0.0889)
		(layer "In11.Cu")
		(net "M_L_CPU1_SB_CA<4>")
	)
	(arc
		(start 138.581892 -263.878822)
		(mid 138.864848 -263.802645)
		(end 139.147804 -263.878822)
		(width 0.0889)
		(layer "In11.Cu")
		(net "M_L_CPU1_SB_CA<4>")
	)
	(arc
		(start 142.341854 -263.878822)
		(mid 142.62481 -263.802645)
		(end 142.907766 -263.878822)
		(width 0.0889)
		(layer "In11.Cu")
		(net "M_L_CPU1_SB_CA<4>")
	)
	(arc
		(start 141.027658 -263.878822)
		(mid 141.209909 -263.929172)
		(end 141.393418 -263.883648)
		(width 0.0889)
		(layer "In11.Cu")
		(net "M_L_CPU1_SB_CA<4>")
	)
	(arc
		(start 141.4018 -263.878822)
		(mid 141.684756 -263.802645)
		(end 141.967712 -263.878822)
		(width 0.0889)
		(layer "In11.Cu")
		(net "M_L_CPU1_SB_CA<4>")
	)
	(arc
		(start 140.461746 -263.878822)
		(mid 140.744702 -263.802645)
		(end 141.027658 -263.878822)
		(width 0.0889)
		(layer "In11.Cu")
		(net "M_L_CPU1_SB_CA<4>")
	)
	(arc
		(start 143.281654 -263.878822)
		(mid 143.56461 -263.802645)
		(end 143.847566 -263.878822)
		(width 0.0889)
		(layer "In11.Cu")
		(net "M_L_CPU1_SB_CA<4>")
	)
	(arc
		(start 144.789906 -263.878822)
		(mid 144.965145 -263.928893)
		(end 145.14322 -263.889998)
		(width 0.0889)
		(layer "In11.Cu")
		(net "M_L_CPU1_SB_CA<4>")
	)
	(segment
		(start 138.867896 -263.290304)
		(end 139.334748 -263.556242)
		(width 0.10668)
		(layer "F.Cu")
		(net "M_L_CPU1_SB_CA<3>")
	)
	(segment
		(start 199.509126 -262.818626)
		(end 199.771 -262.818626)
		(width 0.14478)
		(layer "In11.Cu")
		(net "M_L_CPU1_SB_CA<3>")
	)
	(segment
		(start 195.417948 -263.210294)
		(end 195.562728 -263.355074)
		(width 0.14478)
		(layer "In11.Cu")
		(net "M_L_CPU1_SB_CA<3>")
	)
	(segment
		(start 162.569906 -262.975344)
		(end 163.654994 -264.060432)
		(width 0.14478)
		(layer "In11.Cu")
		(net "M_L_CPU1_SB_CA<3>")
	)
	(segment
		(start 201.163428 -263.210294)
		(end 201.72299 -263.210294)
		(width 0.14478)
		(layer "In11.Cu")
		(net "M_L_CPU1_SB_CA<3>")
	)
	(segment
		(start 200.611994 -262.818626)
		(end 200.873868 -262.818626)
		(width 0.14478)
		(layer "In11.Cu")
		(net "M_L_CPU1_SB_CA<3>")
	)
	(segment
		(start 195.562728 -263.355074)
		(end 195.562728 -263.434322)
		(width 0.14478)
		(layer "In11.Cu")
		(net "M_L_CPU1_SB_CA<3>")
	)
	(segment
		(start 196.810376 -263.579102)
		(end 197.07225 -263.579102)
		(width 0.14478)
		(layer "In11.Cu")
		(net "M_L_CPU1_SB_CA<3>")
	)
	(segment
		(start 173.693836 -264.060432)
		(end 174.543974 -263.210294)
		(width 0.14478)
		(layer "In11.Cu")
		(net "M_L_CPU1_SB_CA<3>")
	)
	(segment
		(start 199.771 -262.818626)
		(end 199.91578 -262.963406)
		(width 0.14478)
		(layer "In11.Cu")
		(net "M_L_CPU1_SB_CA<3>")
	)
	(segment
		(start 199.91578 -263.457182)
		(end 200.06056 -263.601962)
		(width 0.14478)
		(layer "In11.Cu")
		(net "M_L_CPU1_SB_CA<3>")
	)
	(segment
		(start 195.562728 -263.434322)
		(end 195.707508 -263.579102)
		(width 0.14478)
		(layer "In11.Cu")
		(net "M_L_CPU1_SB_CA<3>")
	)
	(segment
		(start 145.444718 -263.310116)
		(end 145.78076 -263.310116)
		(width 0.0889)
		(layer "In11.Cu")
		(net "M_L_CPU1_SB_CA<3>")
	)
	(segment
		(start 146.16557 -262.925306)
		(end 147.504912 -262.925306)
		(width 0.0889)
		(layer "In11.Cu")
		(net "M_L_CPU1_SB_CA<3>")
	)
	(segment
		(start 174.543974 -263.210294)
		(end 177.72634 -263.210294)
		(width 0.14478)
		(layer "In11.Cu")
		(net "M_L_CPU1_SB_CA<3>")
	)
	(segment
		(start 178.576478 -264.060432)
		(end 181.23789 -264.060432)
		(width 0.14478)
		(layer "In11.Cu")
		(net "M_L_CPU1_SB_CA<3>")
	)
	(segment
		(start 196.114162 -262.986266)
		(end 196.258942 -262.841486)
		(width 0.14478)
		(layer "In11.Cu")
		(net "M_L_CPU1_SB_CA<3>")
	)
	(segment
		(start 200.06056 -263.601962)
		(end 200.322434 -263.601962)
		(width 0.14478)
		(layer "In11.Cu")
		(net "M_L_CPU1_SB_CA<3>")
	)
	(segment
		(start 200.873868 -262.818626)
		(end 201.018648 -262.963406)
		(width 0.14478)
		(layer "In11.Cu")
		(net "M_L_CPU1_SB_CA<3>")
	)
	(segment
		(start 197.768464 -262.986266)
		(end 197.768464 -263.065514)
		(width 0.14478)
		(layer "In11.Cu")
		(net "M_L_CPU1_SB_CA<3>")
	)
	(segment
		(start 199.364346 -263.065514)
		(end 199.364346 -262.963406)
		(width 0.14478)
		(layer "In11.Cu")
		(net "M_L_CPU1_SB_CA<3>")
	)
	(segment
		(start 141.967712 -263.233662)
		(end 141.976094 -263.228836)
		(width 0.0889)
		(layer "In11.Cu")
		(net "M_L_CPU1_SB_CA<3>")
	)
	(segment
		(start 144.205198 -263.224518)
		(end 144.221454 -263.233916)
		(width 0.0889)
		(layer "In11.Cu")
		(net "M_L_CPU1_SB_CA<3>")
	)
	(segment
		(start 197.768464 -263.065514)
		(end 197.913244 -263.210294)
		(width 0.14478)
		(layer "In11.Cu")
		(net "M_L_CPU1_SB_CA<3>")
	)
	(segment
		(start 181.23789 -264.060432)
		(end 182.088028 -263.210294)
		(width 0.14478)
		(layer "In11.Cu")
		(net "M_L_CPU1_SB_CA<3>")
	)
	(segment
		(start 197.07225 -263.579102)
		(end 197.21703 -263.434322)
		(width 0.14478)
		(layer "In11.Cu")
		(net "M_L_CPU1_SB_CA<3>")
	)
	(segment
		(start 201.018648 -263.065514)
		(end 201.163428 -263.210294)
		(width 0.14478)
		(layer "In11.Cu")
		(net "M_L_CPU1_SB_CA<3>")
	)
	(segment
		(start 186.120532 -264.060432)
		(end 188.781944 -264.060432)
		(width 0.14478)
		(layer "In11.Cu")
		(net "M_L_CPU1_SB_CA<3>")
	)
	(segment
		(start 197.913244 -263.210294)
		(end 199.219566 -263.210294)
		(width 0.14478)
		(layer "In11.Cu")
		(net "M_L_CPU1_SB_CA<3>")
	)
	(segment
		(start 196.258942 -262.841486)
		(end 196.520816 -262.841486)
		(width 0.14478)
		(layer "In11.Cu")
		(net "M_L_CPU1_SB_CA<3>")
	)
	(segment
		(start 182.088028 -263.210294)
		(end 185.270394 -263.210294)
		(width 0.14478)
		(layer "In11.Cu")
		(net "M_L_CPU1_SB_CA<3>")
	)
	(segment
		(start 196.665596 -263.434322)
		(end 196.810376 -263.579102)
		(width 0.14478)
		(layer "In11.Cu")
		(net "M_L_CPU1_SB_CA<3>")
	)
	(segment
		(start 200.322434 -263.601962)
		(end 200.467214 -263.457182)
		(width 0.14478)
		(layer "In11.Cu")
		(net "M_L_CPU1_SB_CA<3>")
	)
	(segment
		(start 139.334748 -263.556242)
		(end 139.488672 -263.290812)
		(width 0.0889)
		(layer "In11.Cu")
		(net "M_L_CPU1_SB_CA<3>")
	)
	(segment
		(start 141.393418 -263.228836)
		(end 141.4018 -263.233662)
		(width 0.0889)
		(layer "In11.Cu")
		(net "M_L_CPU1_SB_CA<3>")
	)
	(segment
		(start 199.219566 -263.210294)
		(end 199.364346 -263.065514)
		(width 0.14478)
		(layer "In11.Cu")
		(net "M_L_CPU1_SB_CA<3>")
	)
	(segment
		(start 144.786604 -263.233662)
		(end 144.798288 -263.226804)
		(width 0.0889)
		(layer "In11.Cu")
		(net "M_L_CPU1_SB_CA<3>")
	)
	(segment
		(start 197.623684 -262.841486)
		(end 197.768464 -262.986266)
		(width 0.14478)
		(layer "In11.Cu")
		(net "M_L_CPU1_SB_CA<3>")
	)
	(segment
		(start 201.72299 -263.210294)
		(end 202.147932 -263.635236)
		(width 0.14478)
		(layer "In11.Cu")
		(net "M_L_CPU1_SB_CA<3>")
	)
	(segment
		(start 177.72634 -263.210294)
		(end 178.576478 -264.060432)
		(width 0.14478)
		(layer "In11.Cu")
		(net "M_L_CPU1_SB_CA<3>")
	)
	(segment
		(start 196.520816 -262.841486)
		(end 196.665596 -262.986266)
		(width 0.14478)
		(layer "In11.Cu")
		(net "M_L_CPU1_SB_CA<3>")
	)
	(segment
		(start 144.221454 -263.233916)
		(end 144.233392 -263.240774)
		(width 0.0889)
		(layer "In11.Cu")
		(net "M_L_CPU1_SB_CA<3>")
	)
	(segment
		(start 139.488672 -263.290812)
		(end 139.584684 -263.265412)
		(width 0.0889)
		(layer "In11.Cu")
		(net "M_L_CPU1_SB_CA<3>")
	)
	(segment
		(start 200.467214 -262.963406)
		(end 200.611994 -262.818626)
		(width 0.14478)
		(layer "In11.Cu")
		(net "M_L_CPU1_SB_CA<3>")
	)
	(segment
		(start 195.969382 -263.579102)
		(end 196.114162 -263.434322)
		(width 0.14478)
		(layer "In11.Cu")
		(net "M_L_CPU1_SB_CA<3>")
	)
	(segment
		(start 199.91578 -262.963406)
		(end 199.91578 -263.457182)
		(width 0.14478)
		(layer "In11.Cu")
		(net "M_L_CPU1_SB_CA<3>")
	)
	(segment
		(start 196.114162 -263.434322)
		(end 196.114162 -262.986266)
		(width 0.14478)
		(layer "In11.Cu")
		(net "M_L_CPU1_SB_CA<3>")
	)
	(segment
		(start 147.55495 -262.975344)
		(end 147.971764 -262.975344)
		(width 0.0889)
		(layer "In11.Cu")
		(net "M_L_CPU1_SB_CA<3>")
	)
	(segment
		(start 197.21703 -263.434322)
		(end 197.21703 -262.986266)
		(width 0.14478)
		(layer "In11.Cu")
		(net "M_L_CPU1_SB_CA<3>")
	)
	(segment
		(start 163.654994 -264.060432)
		(end 173.693836 -264.060432)
		(width 0.14478)
		(layer "In11.Cu")
		(net "M_L_CPU1_SB_CA<3>")
	)
	(segment
		(start 195.707508 -263.579102)
		(end 195.969382 -263.579102)
		(width 0.14478)
		(layer "In11.Cu")
		(net "M_L_CPU1_SB_CA<3>")
	)
	(segment
		(start 188.781944 -264.060432)
		(end 189.632082 -263.210294)
		(width 0.14478)
		(layer "In11.Cu")
		(net "M_L_CPU1_SB_CA<3>")
	)
	(segment
		(start 197.36181 -262.841486)
		(end 197.623684 -262.841486)
		(width 0.14478)
		(layer "In11.Cu")
		(net "M_L_CPU1_SB_CA<3>")
	)
	(segment
		(start 199.364346 -262.963406)
		(end 199.509126 -262.818626)
		(width 0.14478)
		(layer "In11.Cu")
		(net "M_L_CPU1_SB_CA<3>")
	)
	(segment
		(start 147.504912 -262.925306)
		(end 147.55495 -262.975344)
		(width 0.0889)
		(layer "In11.Cu")
		(net "M_L_CPU1_SB_CA<3>")
	)
	(segment
		(start 145.78076 -263.310116)
		(end 146.16557 -262.925306)
		(width 0.0889)
		(layer "In11.Cu")
		(net "M_L_CPU1_SB_CA<3>")
	)
	(segment
		(start 197.21703 -262.986266)
		(end 197.36181 -262.841486)
		(width 0.14478)
		(layer "In11.Cu")
		(net "M_L_CPU1_SB_CA<3>")
	)
	(segment
		(start 189.632082 -263.210294)
		(end 195.417948 -263.210294)
		(width 0.14478)
		(layer "In11.Cu")
		(net "M_L_CPU1_SB_CA<3>")
	)
	(segment
		(start 196.665596 -262.986266)
		(end 196.665596 -263.434322)
		(width 0.14478)
		(layer "In11.Cu")
		(net "M_L_CPU1_SB_CA<3>")
	)
	(segment
		(start 201.018648 -262.963406)
		(end 201.018648 -263.065514)
		(width 0.14478)
		(layer "In11.Cu")
		(net "M_L_CPU1_SB_CA<3>")
	)
	(segment
		(start 200.467214 -263.457182)
		(end 200.467214 -262.963406)
		(width 0.14478)
		(layer "In11.Cu")
		(net "M_L_CPU1_SB_CA<3>")
	)
	(segment
		(start 185.270394 -263.210294)
		(end 186.120532 -264.060432)
		(width 0.14478)
		(layer "In11.Cu")
		(net "M_L_CPU1_SB_CA<3>")
	)
	(segment
		(start 147.971764 -262.975344)
		(end 162.569906 -262.975344)
		(width 0.14478)
		(layer "In11.Cu")
		(net "M_L_CPU1_SB_CA<3>")
	)
	(segment
		(start 140.453364 -263.228836)
		(end 140.461746 -263.233662)
		(width 0.0889)
		(layer "In11.Cu")
		(net "M_L_CPU1_SB_CA<3>")
	)
	(arc
		(start 144.798288 -263.226804)
		(mid 144.980543 -263.183151)
		(end 145.161 -263.233662)
		(width 0.0889)
		(layer "In11.Cu")
		(net "M_L_CPU1_SB_CA<3>")
	)
	(arc
		(start 139.584684 -263.265412)
		(mid 139.839892 -263.308889)
		(end 140.087604 -263.233662)
		(width 0.0889)
		(layer "In11.Cu")
		(net "M_L_CPU1_SB_CA<3>")
	)
	(arc
		(start 140.087604 -263.233662)
		(mid 140.269855 -263.183312)
		(end 140.453364 -263.228836)
		(width 0.0889)
		(layer "In11.Cu")
		(net "M_L_CPU1_SB_CA<3>")
	)
	(arc
		(start 141.976094 -263.228836)
		(mid 142.159602 -263.183342)
		(end 142.341854 -263.233662)
		(width 0.0889)
		(layer "In11.Cu")
		(net "M_L_CPU1_SB_CA<3>")
	)
	(arc
		(start 142.907766 -263.233662)
		(mid 143.09471 -263.183407)
		(end 143.281654 -263.233662)
		(width 0.0889)
		(layer "In11.Cu")
		(net "M_L_CPU1_SB_CA<3>")
	)
	(arc
		(start 141.4018 -263.233662)
		(mid 141.684756 -263.309839)
		(end 141.967712 -263.233662)
		(width 0.0889)
		(layer "In11.Cu")
		(net "M_L_CPU1_SB_CA<3>")
	)
	(arc
		(start 143.847566 -263.233662)
		(mid 144.025216 -263.183402)
		(end 144.205198 -263.224518)
		(width 0.0889)
		(layer "In11.Cu")
		(net "M_L_CPU1_SB_CA<3>")
	)
	(arc
		(start 140.461746 -263.233662)
		(mid 140.744702 -263.309839)
		(end 141.027658 -263.233662)
		(width 0.0889)
		(layer "In11.Cu")
		(net "M_L_CPU1_SB_CA<3>")
	)
	(arc
		(start 143.281654 -263.233662)
		(mid 143.56461 -263.309839)
		(end 143.847566 -263.233662)
		(width 0.0889)
		(layer "In11.Cu")
		(net "M_L_CPU1_SB_CA<3>")
	)
	(arc
		(start 145.161 -263.233662)
		(mid 145.297793 -263.290684)
		(end 145.444718 -263.310116)
		(width 0.0889)
		(layer "In11.Cu")
		(net "M_L_CPU1_SB_CA<3>")
	)
	(arc
		(start 142.341854 -263.233662)
		(mid 142.62481 -263.309839)
		(end 142.907766 -263.233662)
		(width 0.0889)
		(layer "In11.Cu")
		(net "M_L_CPU1_SB_CA<3>")
	)
	(arc
		(start 144.233392 -263.240774)
		(mid 144.510926 -263.309755)
		(end 144.786604 -263.233662)
		(width 0.0889)
		(layer "In11.Cu")
		(net "M_L_CPU1_SB_CA<3>")
	)
	(arc
		(start 141.027658 -263.233662)
		(mid 141.209909 -263.183312)
		(end 141.393418 -263.228836)
		(width 0.0889)
		(layer "In11.Cu")
		(net "M_L_CPU1_SB_CA<3>")
	)
	(segment
		(start 139.337796 -262.480298)
		(end 139.804648 -262.746236)
		(width 0.10668)
		(layer "F.Cu")
		(net "M_L_CPU1_SB_CA<2>")
	)
	(segment
		(start 185.20537 -262.36041)
		(end 186.055254 -263.210294)
		(width 0.14478)
		(layer "In11.Cu")
		(net "M_L_CPU1_SB_CA<2>")
	)
	(segment
		(start 162.82416 -262.520684)
		(end 163.51377 -263.210294)
		(width 0.14478)
		(layer "In11.Cu")
		(net "M_L_CPU1_SB_CA<2>")
	)
	(segment
		(start 188.874908 -263.210294)
		(end 189.724792 -262.36041)
		(width 0.14478)
		(layer "In11.Cu")
		(net "M_L_CPU1_SB_CA<2>")
	)
	(segment
		(start 147.512532 -262.520684)
		(end 148.034502 -262.520684)
		(width 0.0889)
		(layer "In11.Cu")
		(net "M_L_CPU1_SB_CA<2>")
	)
	(segment
		(start 182.180738 -262.36041)
		(end 185.20537 -262.36041)
		(width 0.14478)
		(layer "In11.Cu")
		(net "M_L_CPU1_SB_CA<2>")
	)
	(segment
		(start 139.650724 -263.011666)
		(end 139.673076 -263.094978)
		(width 0.0889)
		(layer "In11.Cu")
		(net "M_L_CPU1_SB_CA<2>")
	)
	(segment
		(start 148.034502 -262.520684)
		(end 162.82416 -262.520684)
		(width 0.14478)
		(layer "In11.Cu")
		(net "M_L_CPU1_SB_CA<2>")
	)
	(segment
		(start 177.661316 -262.36041)
		(end 178.5112 -263.210294)
		(width 0.14478)
		(layer "In11.Cu")
		(net "M_L_CPU1_SB_CA<2>")
	)
	(segment
		(start 143.377666 -263.068816)
		(end 143.386048 -263.073642)
		(width 0.0889)
		(layer "In11.Cu")
		(net "M_L_CPU1_SB_CA<2>")
	)
	(segment
		(start 142.803372 -263.073642)
		(end 142.811754 -263.068816)
		(width 0.0889)
		(layer "In11.Cu")
		(net "M_L_CPU1_SB_CA<2>")
	)
	(segment
		(start 189.724792 -262.36041)
		(end 205.823058 -262.36041)
		(width 0.14478)
		(layer "In11.Cu")
		(net "M_L_CPU1_SB_CA<2>")
	)
	(segment
		(start 178.5112 -263.210294)
		(end 181.330854 -263.210294)
		(width 0.14478)
		(layer "In11.Cu")
		(net "M_L_CPU1_SB_CA<2>")
	)
	(segment
		(start 145.444718 -263.119616)
		(end 145.701766 -263.119616)
		(width 0.0889)
		(layer "In11.Cu")
		(net "M_L_CPU1_SB_CA<2>")
	)
	(segment
		(start 144.690592 -263.068816)
		(end 144.708626 -263.058148)
		(width 0.0889)
		(layer "In11.Cu")
		(net "M_L_CPU1_SB_CA<2>")
	)
	(segment
		(start 205.823058 -262.36041)
		(end 206.248 -262.785352)
		(width 0.14478)
		(layer "In11.Cu")
		(net "M_L_CPU1_SB_CA<2>")
	)
	(segment
		(start 147.29841 -262.734806)
		(end 147.512532 -262.520684)
		(width 0.0889)
		(layer "In11.Cu")
		(net "M_L_CPU1_SB_CA<2>")
	)
	(segment
		(start 186.055254 -263.210294)
		(end 188.874908 -263.210294)
		(width 0.14478)
		(layer "In11.Cu")
		(net "M_L_CPU1_SB_CA<2>")
	)
	(segment
		(start 144.30502 -263.061704)
		(end 144.316958 -263.068562)
		(width 0.0889)
		(layer "In11.Cu")
		(net "M_L_CPU1_SB_CA<2>")
	)
	(segment
		(start 174.636684 -262.36041)
		(end 177.661316 -262.36041)
		(width 0.14478)
		(layer "In11.Cu")
		(net "M_L_CPU1_SB_CA<2>")
	)
	(segment
		(start 146.086576 -262.734806)
		(end 147.29841 -262.734806)
		(width 0.0889)
		(layer "In11.Cu")
		(net "M_L_CPU1_SB_CA<2>")
	)
	(segment
		(start 144.316958 -263.068562)
		(end 144.330674 -263.076436)
		(width 0.0889)
		(layer "In11.Cu")
		(net "M_L_CPU1_SB_CA<2>")
	)
	(segment
		(start 181.330854 -263.210294)
		(end 182.180738 -262.36041)
		(width 0.14478)
		(layer "In11.Cu")
		(net "M_L_CPU1_SB_CA<2>")
	)
	(segment
		(start 173.7868 -263.210294)
		(end 174.636684 -262.36041)
		(width 0.14478)
		(layer "In11.Cu")
		(net "M_L_CPU1_SB_CA<2>")
	)
	(segment
		(start 140.557758 -263.068816)
		(end 140.56614 -263.073642)
		(width 0.0889)
		(layer "In11.Cu")
		(net "M_L_CPU1_SB_CA<2>")
	)
	(segment
		(start 145.701766 -263.119616)
		(end 146.086576 -262.734806)
		(width 0.0889)
		(layer "In11.Cu")
		(net "M_L_CPU1_SB_CA<2>")
	)
	(segment
		(start 163.51377 -263.210294)
		(end 173.7868 -263.210294)
		(width 0.14478)
		(layer "In11.Cu")
		(net "M_L_CPU1_SB_CA<2>")
	)
	(segment
		(start 139.804648 -262.746236)
		(end 139.650724 -263.011666)
		(width 0.0889)
		(layer "In11.Cu")
		(net "M_L_CPU1_SB_CA<2>")
	)
	(arc
		(start 144.330674 -263.076436)
		(mid 144.511604 -263.118914)
		(end 144.690592 -263.068816)
		(width 0.0889)
		(layer "In11.Cu")
		(net "M_L_CPU1_SB_CA<2>")
	)
	(arc
		(start 140.9319 -263.068816)
		(mid 141.214856 -262.992639)
		(end 141.497812 -263.068816)
		(width 0.0889)
		(layer "In11.Cu")
		(net "M_L_CPU1_SB_CA<2>")
	)
	(arc
		(start 139.991846 -263.068816)
		(mid 140.274802 -262.992639)
		(end 140.557758 -263.068816)
		(width 0.0889)
		(layer "In11.Cu")
		(net "M_L_CPU1_SB_CA<2>")
	)
	(arc
		(start 142.437612 -263.068816)
		(mid 142.619863 -263.119166)
		(end 142.803372 -263.073642)
		(width 0.0889)
		(layer "In11.Cu")
		(net "M_L_CPU1_SB_CA<2>")
	)
	(arc
		(start 145.257266 -263.068816)
		(mid 145.347629 -263.106626)
		(end 145.444718 -263.119616)
		(width 0.0889)
		(layer "In11.Cu")
		(net "M_L_CPU1_SB_CA<2>")
	)
	(arc
		(start 143.751808 -263.068816)
		(mid 144.027486 -262.992686)
		(end 144.30502 -263.061704)
		(width 0.0889)
		(layer "In11.Cu")
		(net "M_L_CPU1_SB_CA<2>")
	)
	(arc
		(start 143.386048 -263.073642)
		(mid 143.569556 -263.119136)
		(end 143.751808 -263.068816)
		(width 0.0889)
		(layer "In11.Cu")
		(net "M_L_CPU1_SB_CA<2>")
	)
	(arc
		(start 139.673076 -263.094978)
		(mid 139.835408 -263.117796)
		(end 139.991846 -263.068816)
		(width 0.0889)
		(layer "In11.Cu")
		(net "M_L_CPU1_SB_CA<2>")
	)
	(arc
		(start 141.497812 -263.068816)
		(mid 141.684756 -263.119071)
		(end 141.8717 -263.068816)
		(width 0.0889)
		(layer "In11.Cu")
		(net "M_L_CPU1_SB_CA<2>")
	)
	(arc
		(start 144.708626 -263.058148)
		(mid 144.984321 -262.992305)
		(end 145.257266 -263.068816)
		(width 0.0889)
		(layer "In11.Cu")
		(net "M_L_CPU1_SB_CA<2>")
	)
	(arc
		(start 142.811754 -263.068816)
		(mid 143.09471 -262.992639)
		(end 143.377666 -263.068816)
		(width 0.0889)
		(layer "In11.Cu")
		(net "M_L_CPU1_SB_CA<2>")
	)
	(arc
		(start 141.8717 -263.068816)
		(mid 142.154656 -262.992639)
		(end 142.437612 -263.068816)
		(width 0.0889)
		(layer "In11.Cu")
		(net "M_L_CPU1_SB_CA<2>")
	)
	(arc
		(start 140.56614 -263.073642)
		(mid 140.749648 -263.119136)
		(end 140.9319 -263.068816)
		(width 0.0889)
		(layer "In11.Cu")
		(net "M_L_CPU1_SB_CA<2>")
	)
	(segment
		(start 137.457942 -262.480298)
		(end 137.924794 -262.746236)
		(width 0.10668)
		(layer "F.Cu")
		(net "M_L_CPU1_SB_CA<1>")
	)
	(segment
		(start 199.939402 -261.256526)
		(end 199.939402 -261.764018)
		(width 0.14478)
		(layer "In11.Cu")
		(net "M_L_CPU1_SB_CA<1>")
	)
	(segment
		(start 181.23789 -262.36041)
		(end 182.088028 -261.510272)
		(width 0.14478)
		(layer "In11.Cu")
		(net "M_L_CPU1_SB_CA<1>")
	)
	(segment
		(start 201.04227 -261.256526)
		(end 201.04227 -261.365492)
		(width 0.14478)
		(layer "In11.Cu")
		(net "M_L_CPU1_SB_CA<1>")
	)
	(segment
		(start 201.04227 -261.365492)
		(end 201.18705 -261.510272)
		(width 0.14478)
		(layer "In11.Cu")
		(net "M_L_CPU1_SB_CA<1>")
	)
	(segment
		(start 177.72634 -261.510272)
		(end 178.576478 -262.36041)
		(width 0.14478)
		(layer "In11.Cu")
		(net "M_L_CPU1_SB_CA<1>")
	)
	(segment
		(start 145.444718 -262.373618)
		(end 147.207478 -262.373618)
		(width 0.0889)
		(layer "In11.Cu")
		(net "M_L_CPU1_SB_CA<1>")
	)
	(segment
		(start 201.72299 -261.510272)
		(end 202.147932 -261.935214)
		(width 0.14478)
		(layer "In11.Cu")
		(net "M_L_CPU1_SB_CA<1>")
	)
	(segment
		(start 199.532748 -261.111746)
		(end 199.794622 -261.111746)
		(width 0.14478)
		(layer "In11.Cu")
		(net "M_L_CPU1_SB_CA<1>")
	)
	(segment
		(start 178.576478 -262.36041)
		(end 181.23789 -262.36041)
		(width 0.14478)
		(layer "In11.Cu")
		(net "M_L_CPU1_SB_CA<1>")
	)
	(segment
		(start 200.346056 -261.908798)
		(end 200.490836 -261.764018)
		(width 0.14478)
		(layer "In11.Cu")
		(net "M_L_CPU1_SB_CA<1>")
	)
	(segment
		(start 200.490836 -261.256526)
		(end 200.635616 -261.111746)
		(width 0.14478)
		(layer "In11.Cu")
		(net "M_L_CPU1_SB_CA<1>")
	)
	(segment
		(start 200.084182 -261.908798)
		(end 200.346056 -261.908798)
		(width 0.14478)
		(layer "In11.Cu")
		(net "M_L_CPU1_SB_CA<1>")
	)
	(segment
		(start 143.377666 -262.423656)
		(end 143.386048 -262.41883)
		(width 0.0889)
		(layer "In11.Cu")
		(net "M_L_CPU1_SB_CA<1>")
	)
	(segment
		(start 199.387968 -261.365492)
		(end 199.387968 -261.256526)
		(width 0.14478)
		(layer "In11.Cu")
		(net "M_L_CPU1_SB_CA<1>")
	)
	(segment
		(start 143.751808 -262.423656)
		(end 143.775176 -262.437372)
		(width 0.0889)
		(layer "In11.Cu")
		(net "M_L_CPU1_SB_CA<1>")
	)
	(segment
		(start 188.781944 -262.36041)
		(end 189.632082 -261.510272)
		(width 0.14478)
		(layer "In11.Cu")
		(net "M_L_CPU1_SB_CA<1>")
	)
	(segment
		(start 138.078718 -262.480806)
		(end 138.17473 -262.455406)
		(width 0.0889)
		(layer "In11.Cu")
		(net "M_L_CPU1_SB_CA<1>")
	)
	(segment
		(start 199.243188 -261.510272)
		(end 199.387968 -261.365492)
		(width 0.14478)
		(layer "In11.Cu")
		(net "M_L_CPU1_SB_CA<1>")
	)
	(segment
		(start 148.030184 -262.066024)
		(end 163.895024 -262.066024)
		(width 0.14478)
		(layer "In11.Cu")
		(net "M_L_CPU1_SB_CA<1>")
	)
	(segment
		(start 147.207478 -262.373618)
		(end 147.515072 -262.066024)
		(width 0.0889)
		(layer "In11.Cu")
		(net "M_L_CPU1_SB_CA<1>")
	)
	(segment
		(start 145.236946 -262.436356)
		(end 145.258536 -262.42391)
		(width 0.0889)
		(layer "In11.Cu")
		(net "M_L_CPU1_SB_CA<1>")
	)
	(segment
		(start 139.04341 -262.41883)
		(end 139.051792 -262.423656)
		(width 0.0889)
		(layer "In11.Cu")
		(net "M_L_CPU1_SB_CA<1>")
	)
	(segment
		(start 186.120532 -262.36041)
		(end 188.781944 -262.36041)
		(width 0.14478)
		(layer "In11.Cu")
		(net "M_L_CPU1_SB_CA<1>")
	)
	(segment
		(start 200.490836 -261.764018)
		(end 200.490836 -261.256526)
		(width 0.14478)
		(layer "In11.Cu")
		(net "M_L_CPU1_SB_CA<1>")
	)
	(segment
		(start 200.635616 -261.111746)
		(end 200.89749 -261.111746)
		(width 0.14478)
		(layer "In11.Cu")
		(net "M_L_CPU1_SB_CA<1>")
	)
	(segment
		(start 182.088028 -261.510272)
		(end 185.270394 -261.510272)
		(width 0.14478)
		(layer "In11.Cu")
		(net "M_L_CPU1_SB_CA<1>")
	)
	(segment
		(start 201.18705 -261.510272)
		(end 201.72299 -261.510272)
		(width 0.14478)
		(layer "In11.Cu")
		(net "M_L_CPU1_SB_CA<1>")
	)
	(segment
		(start 137.924794 -262.746236)
		(end 138.078718 -262.480806)
		(width 0.0889)
		(layer "In11.Cu")
		(net "M_L_CPU1_SB_CA<1>")
	)
	(segment
		(start 139.617704 -262.423656)
		(end 139.626086 -262.41883)
		(width 0.0889)
		(layer "In11.Cu")
		(net "M_L_CPU1_SB_CA<1>")
	)
	(segment
		(start 200.89749 -261.111746)
		(end 201.04227 -261.256526)
		(width 0.14478)
		(layer "In11.Cu")
		(net "M_L_CPU1_SB_CA<1>")
	)
	(segment
		(start 199.939402 -261.764018)
		(end 200.084182 -261.908798)
		(width 0.14478)
		(layer "In11.Cu")
		(net "M_L_CPU1_SB_CA<1>")
	)
	(segment
		(start 199.387968 -261.256526)
		(end 199.532748 -261.111746)
		(width 0.14478)
		(layer "In11.Cu")
		(net "M_L_CPU1_SB_CA<1>")
	)
	(segment
		(start 174.543974 -261.510272)
		(end 177.72634 -261.510272)
		(width 0.14478)
		(layer "In11.Cu")
		(net "M_L_CPU1_SB_CA<1>")
	)
	(segment
		(start 185.270394 -261.510272)
		(end 186.120532 -262.36041)
		(width 0.14478)
		(layer "In11.Cu")
		(net "M_L_CPU1_SB_CA<1>")
	)
	(segment
		(start 164.18941 -262.36041)
		(end 173.693836 -262.36041)
		(width 0.14478)
		(layer "In11.Cu")
		(net "M_L_CPU1_SB_CA<1>")
	)
	(segment
		(start 199.794622 -261.111746)
		(end 199.939402 -261.256526)
		(width 0.14478)
		(layer "In11.Cu")
		(net "M_L_CPU1_SB_CA<1>")
	)
	(segment
		(start 189.632082 -261.510272)
		(end 199.243188 -261.510272)
		(width 0.14478)
		(layer "In11.Cu")
		(net "M_L_CPU1_SB_CA<1>")
	)
	(segment
		(start 173.693836 -262.36041)
		(end 174.543974 -261.510272)
		(width 0.14478)
		(layer "In11.Cu")
		(net "M_L_CPU1_SB_CA<1>")
	)
	(segment
		(start 144.67967 -262.415274)
		(end 144.694148 -262.423656)
		(width 0.0889)
		(layer "In11.Cu")
		(net "M_L_CPU1_SB_CA<1>")
	)
	(segment
		(start 163.895024 -262.066024)
		(end 164.18941 -262.36041)
		(width 0.14478)
		(layer "In11.Cu")
		(net "M_L_CPU1_SB_CA<1>")
	)
	(segment
		(start 147.515072 -262.066024)
		(end 148.030184 -262.066024)
		(width 0.0889)
		(layer "In11.Cu")
		(net "M_L_CPU1_SB_CA<1>")
	)
	(segment
		(start 142.803372 -262.41883)
		(end 142.811754 -262.423656)
		(width 0.0889)
		(layer "In11.Cu")
		(net "M_L_CPU1_SB_CA<1>")
	)
	(segment
		(start 140.557758 -262.423656)
		(end 140.56614 -262.41883)
		(width 0.0889)
		(layer "In11.Cu")
		(net "M_L_CPU1_SB_CA<1>")
	)
	(arc
		(start 145.258536 -262.42391)
		(mid 145.348313 -262.386487)
		(end 145.444718 -262.373618)
		(width 0.0889)
		(layer "In11.Cu")
		(net "M_L_CPU1_SB_CA<1>")
	)
	(arc
		(start 142.437612 -262.423656)
		(mid 142.619863 -262.373306)
		(end 142.803372 -262.41883)
		(width 0.0889)
		(layer "In11.Cu")
		(net "M_L_CPU1_SB_CA<1>")
	)
	(arc
		(start 140.9319 -262.423656)
		(mid 141.214856 -262.499833)
		(end 141.497812 -262.423656)
		(width 0.0889)
		(layer "In11.Cu")
		(net "M_L_CPU1_SB_CA<1>")
	)
	(arc
		(start 138.67765 -262.423656)
		(mid 138.859901 -262.373306)
		(end 139.04341 -262.41883)
		(width 0.0889)
		(layer "In11.Cu")
		(net "M_L_CPU1_SB_CA<1>")
	)
	(arc
		(start 140.56614 -262.41883)
		(mid 140.749648 -262.373336)
		(end 140.9319 -262.423656)
		(width 0.0889)
		(layer "In11.Cu")
		(net "M_L_CPU1_SB_CA<1>")
	)
	(arc
		(start 141.8717 -262.423656)
		(mid 142.154656 -262.499833)
		(end 142.437612 -262.423656)
		(width 0.0889)
		(layer "In11.Cu")
		(net "M_L_CPU1_SB_CA<1>")
	)
	(arc
		(start 144.694148 -262.423656)
		(mid 144.963917 -262.499679)
		(end 145.236946 -262.436356)
		(width 0.0889)
		(layer "In11.Cu")
		(net "M_L_CPU1_SB_CA<1>")
	)
	(arc
		(start 143.386048 -262.41883)
		(mid 143.569556 -262.373336)
		(end 143.751808 -262.423656)
		(width 0.0889)
		(layer "In11.Cu")
		(net "M_L_CPU1_SB_CA<1>")
	)
	(arc
		(start 142.811754 -262.423656)
		(mid 143.09471 -262.499833)
		(end 143.377666 -262.423656)
		(width 0.0889)
		(layer "In11.Cu")
		(net "M_L_CPU1_SB_CA<1>")
	)
	(arc
		(start 139.051792 -262.423656)
		(mid 139.334748 -262.499833)
		(end 139.617704 -262.423656)
		(width 0.0889)
		(layer "In11.Cu")
		(net "M_L_CPU1_SB_CA<1>")
	)
	(arc
		(start 143.775176 -262.437372)
		(mid 144.04883 -262.500315)
		(end 144.31899 -262.423656)
		(width 0.0889)
		(layer "In11.Cu")
		(net "M_L_CPU1_SB_CA<1>")
	)
	(arc
		(start 144.31899 -262.423656)
		(mid 144.498253 -262.372992)
		(end 144.67967 -262.415274)
		(width 0.0889)
		(layer "In11.Cu")
		(net "M_L_CPU1_SB_CA<1>")
	)
	(arc
		(start 138.17473 -262.455406)
		(mid 138.429938 -262.498883)
		(end 138.67765 -262.423656)
		(width 0.0889)
		(layer "In11.Cu")
		(net "M_L_CPU1_SB_CA<1>")
	)
	(arc
		(start 139.991846 -262.423656)
		(mid 140.274802 -262.499833)
		(end 140.557758 -262.423656)
		(width 0.0889)
		(layer "In11.Cu")
		(net "M_L_CPU1_SB_CA<1>")
	)
	(arc
		(start 139.626086 -262.41883)
		(mid 139.809594 -262.373336)
		(end 139.991846 -262.423656)
		(width 0.0889)
		(layer "In11.Cu")
		(net "M_L_CPU1_SB_CA<1>")
	)
	(arc
		(start 141.497812 -262.423656)
		(mid 141.684756 -262.373401)
		(end 141.8717 -262.423656)
		(width 0.0889)
		(layer "In11.Cu")
		(net "M_L_CPU1_SB_CA<1>")
	)
	(segment
		(start 137.927842 -261.670292)
		(end 138.394694 -261.93623)
		(width 0.10668)
		(layer "F.Cu")
		(net "M_L_CPU1_SB_CA<0>")
	)
	(segment
		(start 144.766538 -262.245094)
		(end 144.789906 -262.25881)
		(width 0.0889)
		(layer "In11.Cu")
		(net "M_L_CPU1_SB_CA<0>")
	)
	(segment
		(start 177.661316 -260.660388)
		(end 178.5112 -261.510272)
		(width 0.14478)
		(layer "In11.Cu")
		(net "M_L_CPU1_SB_CA<0>")
	)
	(segment
		(start 141.393418 -262.263636)
		(end 141.4018 -262.25881)
		(width 0.0889)
		(layer "In11.Cu")
		(net "M_L_CPU1_SB_CA<0>")
	)
	(segment
		(start 178.5112 -261.510272)
		(end 181.330854 -261.510272)
		(width 0.14478)
		(layer "In11.Cu")
		(net "M_L_CPU1_SB_CA<0>")
	)
	(segment
		(start 147.615148 -261.612888)
		(end 148.043138 -261.612888)
		(width 0.0889)
		(layer "In11.Cu")
		(net "M_L_CPU1_SB_CA<0>")
	)
	(segment
		(start 138.24077 -262.20166)
		(end 138.263122 -262.284972)
		(width 0.0889)
		(layer "In11.Cu")
		(net "M_L_CPU1_SB_CA<0>")
	)
	(segment
		(start 148.043138 -261.612888)
		(end 162.822636 -261.612888)
		(width 0.14478)
		(layer "In11.Cu")
		(net "M_L_CPU1_SB_CA<0>")
	)
	(segment
		(start 138.394694 -261.93623)
		(end 138.24077 -262.20166)
		(width 0.0889)
		(layer "In11.Cu")
		(net "M_L_CPU1_SB_CA<0>")
	)
	(segment
		(start 188.874908 -261.510272)
		(end 189.724792 -260.660388)
		(width 0.14478)
		(layer "In11.Cu")
		(net "M_L_CPU1_SB_CA<0>")
	)
	(segment
		(start 162.925252 -261.510272)
		(end 173.7868 -261.510272)
		(width 0.14478)
		(layer "In11.Cu")
		(net "M_L_CPU1_SB_CA<0>")
	)
	(segment
		(start 181.330854 -261.510272)
		(end 182.180738 -260.660388)
		(width 0.14478)
		(layer "In11.Cu")
		(net "M_L_CPU1_SB_CA<0>")
	)
	(segment
		(start 189.724792 -260.660388)
		(end 205.823058 -260.660388)
		(width 0.14478)
		(layer "In11.Cu")
		(net "M_L_CPU1_SB_CA<0>")
	)
	(segment
		(start 173.7868 -261.510272)
		(end 174.636684 -260.660388)
		(width 0.14478)
		(layer "In11.Cu")
		(net "M_L_CPU1_SB_CA<0>")
	)
	(segment
		(start 147.120864 -262.107172)
		(end 147.615148 -261.612888)
		(width 0.0889)
		(layer "In11.Cu")
		(net "M_L_CPU1_SB_CA<0>")
	)
	(segment
		(start 143.847566 -262.25881)
		(end 143.862044 -262.267192)
		(width 0.0889)
		(layer "In11.Cu")
		(net "M_L_CPU1_SB_CA<0>")
	)
	(segment
		(start 182.180738 -260.660388)
		(end 185.20537 -260.660388)
		(width 0.14478)
		(layer "In11.Cu")
		(net "M_L_CPU1_SB_CA<0>")
	)
	(segment
		(start 185.20537 -260.660388)
		(end 186.055254 -261.510272)
		(width 0.14478)
		(layer "In11.Cu")
		(net "M_L_CPU1_SB_CA<0>")
	)
	(segment
		(start 174.636684 -260.660388)
		(end 177.661316 -260.660388)
		(width 0.14478)
		(layer "In11.Cu")
		(net "M_L_CPU1_SB_CA<0>")
	)
	(segment
		(start 186.055254 -261.510272)
		(end 188.874908 -261.510272)
		(width 0.14478)
		(layer "In11.Cu")
		(net "M_L_CPU1_SB_CA<0>")
	)
	(segment
		(start 140.453364 -262.263636)
		(end 140.461746 -262.25881)
		(width 0.0889)
		(layer "In11.Cu")
		(net "M_L_CPU1_SB_CA<0>")
	)
	(segment
		(start 145.603976 -262.140446)
		(end 147.0406 -262.140446)
		(width 0.0889)
		(layer "In11.Cu")
		(net "M_L_CPU1_SB_CA<0>")
	)
	(segment
		(start 145.14322 -262.269986)
		(end 145.163286 -262.258556)
		(width 0.0889)
		(layer "In11.Cu")
		(net "M_L_CPU1_SB_CA<0>")
	)
	(segment
		(start 205.823058 -260.660388)
		(end 206.248 -261.08533)
		(width 0.14478)
		(layer "In11.Cu")
		(net "M_L_CPU1_SB_CA<0>")
	)
	(segment
		(start 162.822636 -261.612888)
		(end 162.925252 -261.510272)
		(width 0.14478)
		(layer "In11.Cu")
		(net "M_L_CPU1_SB_CA<0>")
	)
	(segment
		(start 141.967712 -262.25881)
		(end 141.976094 -262.263636)
		(width 0.0889)
		(layer "In11.Cu")
		(net "M_L_CPU1_SB_CA<0>")
	)
	(arc
		(start 141.976094 -262.263636)
		(mid 142.159602 -262.30913)
		(end 142.341854 -262.25881)
		(width 0.0889)
		(layer "In11.Cu")
		(net "M_L_CPU1_SB_CA<0>")
	)
	(arc
		(start 145.163286 -262.258556)
		(mid 145.375862 -262.170528)
		(end 145.603976 -262.140446)
		(width 0.0889)
		(layer "In11.Cu")
		(net "M_L_CPU1_SB_CA<0>")
	)
	(arc
		(start 143.281654 -262.25881)
		(mid 143.56461 -262.182633)
		(end 143.847566 -262.25881)
		(width 0.0889)
		(layer "In11.Cu")
		(net "M_L_CPU1_SB_CA<0>")
	)
	(arc
		(start 139.147804 -262.25881)
		(mid 139.334748 -262.309065)
		(end 139.521692 -262.25881)
		(width 0.0889)
		(layer "In11.Cu")
		(net "M_L_CPU1_SB_CA<0>")
	)
	(arc
		(start 144.789906 -262.25881)
		(mid 144.965145 -262.308881)
		(end 145.14322 -262.269986)
		(width 0.0889)
		(layer "In11.Cu")
		(net "M_L_CPU1_SB_CA<0>")
	)
	(arc
		(start 144.222724 -262.25881)
		(mid 144.492881 -262.182048)
		(end 144.766538 -262.245094)
		(width 0.0889)
		(layer "In11.Cu")
		(net "M_L_CPU1_SB_CA<0>")
	)
	(arc
		(start 139.521692 -262.25881)
		(mid 139.804648 -262.182633)
		(end 140.087604 -262.25881)
		(width 0.0889)
		(layer "In11.Cu")
		(net "M_L_CPU1_SB_CA<0>")
	)
	(arc
		(start 138.581892 -262.25881)
		(mid 138.864848 -262.182633)
		(end 139.147804 -262.25881)
		(width 0.0889)
		(layer "In11.Cu")
		(net "M_L_CPU1_SB_CA<0>")
	)
	(arc
		(start 140.087604 -262.25881)
		(mid 140.269855 -262.30916)
		(end 140.453364 -262.263636)
		(width 0.0889)
		(layer "In11.Cu")
		(net "M_L_CPU1_SB_CA<0>")
	)
	(arc
		(start 147.0406 -262.140446)
		(mid 147.084035 -262.131788)
		(end 147.120864 -262.107172)
		(width 0.0889)
		(layer "In11.Cu")
		(net "M_L_CPU1_SB_CA<0>")
	)
	(arc
		(start 142.341854 -262.25881)
		(mid 142.62481 -262.182633)
		(end 142.907766 -262.25881)
		(width 0.0889)
		(layer "In11.Cu")
		(net "M_L_CPU1_SB_CA<0>")
	)
	(arc
		(start 141.027658 -262.25881)
		(mid 141.209909 -262.30916)
		(end 141.393418 -262.263636)
		(width 0.0889)
		(layer "In11.Cu")
		(net "M_L_CPU1_SB_CA<0>")
	)
	(arc
		(start 141.4018 -262.25881)
		(mid 141.684756 -262.182633)
		(end 141.967712 -262.25881)
		(width 0.0889)
		(layer "In11.Cu")
		(net "M_L_CPU1_SB_CA<0>")
	)
	(arc
		(start 143.862044 -262.267192)
		(mid 144.04346 -262.309449)
		(end 144.222724 -262.25881)
		(width 0.0889)
		(layer "In11.Cu")
		(net "M_L_CPU1_SB_CA<0>")
	)
	(arc
		(start 142.907766 -262.25881)
		(mid 143.09471 -262.309065)
		(end 143.281654 -262.25881)
		(width 0.0889)
		(layer "In11.Cu")
		(net "M_L_CPU1_SB_CA<0>")
	)
	(arc
		(start 140.461746 -262.25881)
		(mid 140.744702 -262.182633)
		(end 141.027658 -262.25881)
		(width 0.0889)
		(layer "In11.Cu")
		(net "M_L_CPU1_SB_CA<0>")
	)
	(arc
		(start 138.263122 -262.284972)
		(mid 138.425454 -262.30779)
		(end 138.581892 -262.25881)
		(width 0.0889)
		(layer "In11.Cu")
		(net "M_L_CPU1_SB_CA<0>")
	)
	(segment
		(start 137.927842 -266.530328)
		(end 138.394694 -266.796266)
		(width 0.10668)
		(layer "F.Cu")
		(net "M_L_CPU1_SA_RSP<0>")
	)
	(segment
		(start 185.270394 -269.160498)
		(end 186.120532 -270.010636)
		(width 0.11684)
		(layer "In11.Cu")
		(net "M_L_CPU1_SA_RSP<0>")
	)
	(segment
		(start 141.967712 -267.118846)
		(end 141.976094 -267.123672)
		(width 0.0889)
		(layer "In11.Cu")
		(net "M_L_CPU1_SA_RSP<0>")
	)
	(segment
		(start 159.788352 -266.143994)
		(end 163.654994 -270.010636)
		(width 0.11684)
		(layer "In11.Cu")
		(net "M_L_CPU1_SA_RSP<0>")
	)
	(segment
		(start 141.393418 -267.123672)
		(end 141.4018 -267.118846)
		(width 0.0889)
		(layer "In11.Cu")
		(net "M_L_CPU1_SA_RSP<0>")
	)
	(segment
		(start 145.150332 -267.125704)
		(end 145.162016 -267.118846)
		(width 0.0889)
		(layer "In11.Cu")
		(net "M_L_CPU1_SA_RSP<0>")
	)
	(segment
		(start 186.120532 -270.010636)
		(end 188.31052 -270.010636)
		(width 0.11684)
		(layer "In11.Cu")
		(net "M_L_CPU1_SA_RSP<0>")
	)
	(segment
		(start 138.24077 -267.061696)
		(end 138.263122 -267.145008)
		(width 0.0889)
		(layer "In11.Cu")
		(net "M_L_CPU1_SA_RSP<0>")
	)
	(segment
		(start 181.23789 -270.010636)
		(end 182.088028 -269.160498)
		(width 0.11684)
		(layer "In11.Cu")
		(net "M_L_CPU1_SA_RSP<0>")
	)
	(segment
		(start 147.38985 -265.864086)
		(end 147.669758 -266.143994)
		(width 0.0889)
		(layer "In11.Cu")
		(net "M_L_CPU1_SA_RSP<0>")
	)
	(segment
		(start 178.576478 -270.010636)
		(end 181.23789 -270.010636)
		(width 0.11684)
		(layer "In11.Cu")
		(net "M_L_CPU1_SA_RSP<0>")
	)
	(segment
		(start 188.31052 -270.010636)
		(end 190.363094 -269.160498)
		(width 0.11684)
		(layer "In11.Cu")
		(net "M_L_CPU1_SA_RSP<0>")
	)
	(segment
		(start 173.693836 -270.010636)
		(end 174.543974 -269.160498)
		(width 0.11684)
		(layer "In11.Cu")
		(net "M_L_CPU1_SA_RSP<0>")
	)
	(segment
		(start 204.110844 -269.160498)
		(end 206.248 -269.58544)
		(width 0.11684)
		(layer "In11.Cu")
		(net "M_L_CPU1_SA_RSP<0>")
	)
	(segment
		(start 138.394694 -266.796266)
		(end 138.24077 -267.061696)
		(width 0.0889)
		(layer "In11.Cu")
		(net "M_L_CPU1_SA_RSP<0>")
	)
	(segment
		(start 147.669758 -266.143994)
		(end 148.000212 -266.143994)
		(width 0.0889)
		(layer "In11.Cu")
		(net "M_L_CPU1_SA_RSP<0>")
	)
	(segment
		(start 190.363094 -269.160498)
		(end 204.110844 -269.160498)
		(width 0.11684)
		(layer "In11.Cu")
		(net "M_L_CPU1_SA_RSP<0>")
	)
	(segment
		(start 174.543974 -269.160498)
		(end 177.72634 -269.160498)
		(width 0.11684)
		(layer "In11.Cu")
		(net "M_L_CPU1_SA_RSP<0>")
	)
	(segment
		(start 148.000212 -266.143994)
		(end 159.788352 -266.143994)
		(width 0.11684)
		(layer "In11.Cu")
		(net "M_L_CPU1_SA_RSP<0>")
	)
	(segment
		(start 146.416776 -265.864086)
		(end 147.38985 -265.864086)
		(width 0.0889)
		(layer "In11.Cu")
		(net "M_L_CPU1_SA_RSP<0>")
	)
	(segment
		(start 144.777714 -267.11275)
		(end 144.788128 -267.118846)
		(width 0.0889)
		(layer "In11.Cu")
		(net "M_L_CPU1_SA_RSP<0>")
	)
	(segment
		(start 182.088028 -269.160498)
		(end 185.270394 -269.160498)
		(width 0.11684)
		(layer "In11.Cu")
		(net "M_L_CPU1_SA_RSP<0>")
	)
	(segment
		(start 177.72634 -269.160498)
		(end 178.576478 -270.010636)
		(width 0.11684)
		(layer "In11.Cu")
		(net "M_L_CPU1_SA_RSP<0>")
	)
	(segment
		(start 145.162016 -267.118846)
		(end 146.416776 -265.864086)
		(width 0.0889)
		(layer "In11.Cu")
		(net "M_L_CPU1_SA_RSP<0>")
	)
	(segment
		(start 140.453364 -267.123672)
		(end 140.461746 -267.118846)
		(width 0.0889)
		(layer "In11.Cu")
		(net "M_L_CPU1_SA_RSP<0>")
	)
	(segment
		(start 163.654994 -270.010636)
		(end 173.693836 -270.010636)
		(width 0.11684)
		(layer "In11.Cu")
		(net "M_L_CPU1_SA_RSP<0>")
	)
	(arc
		(start 140.087604 -267.118846)
		(mid 140.269855 -267.169196)
		(end 140.453364 -267.123672)
		(width 0.0889)
		(layer "In11.Cu")
		(net "M_L_CPU1_SA_RSP<0>")
	)
	(arc
		(start 143.281654 -267.118846)
		(mid 143.56461 -267.042669)
		(end 143.847566 -267.118846)
		(width 0.0889)
		(layer "In11.Cu")
		(net "M_L_CPU1_SA_RSP<0>")
	)
	(arc
		(start 138.581892 -267.118846)
		(mid 138.864848 -267.042669)
		(end 139.147804 -267.118846)
		(width 0.0889)
		(layer "In11.Cu")
		(net "M_L_CPU1_SA_RSP<0>")
	)
	(arc
		(start 139.147804 -267.118846)
		(mid 139.334748 -267.169101)
		(end 139.521692 -267.118846)
		(width 0.0889)
		(layer "In11.Cu")
		(net "M_L_CPU1_SA_RSP<0>")
	)
	(arc
		(start 141.976094 -267.123672)
		(mid 142.159602 -267.169166)
		(end 142.341854 -267.118846)
		(width 0.0889)
		(layer "In11.Cu")
		(net "M_L_CPU1_SA_RSP<0>")
	)
	(arc
		(start 144.788128 -267.118846)
		(mid 144.968333 -267.169163)
		(end 145.150332 -267.125704)
		(width 0.0889)
		(layer "In11.Cu")
		(net "M_L_CPU1_SA_RSP<0>")
	)
	(arc
		(start 142.341854 -267.118846)
		(mid 142.62481 -267.042669)
		(end 142.907766 -267.118846)
		(width 0.0889)
		(layer "In11.Cu")
		(net "M_L_CPU1_SA_RSP<0>")
	)
	(arc
		(start 144.221962 -267.118846)
		(mid 144.499029 -267.042575)
		(end 144.777714 -267.11275)
		(width 0.0889)
		(layer "In11.Cu")
		(net "M_L_CPU1_SA_RSP<0>")
	)
	(arc
		(start 141.4018 -267.118846)
		(mid 141.684756 -267.042669)
		(end 141.967712 -267.118846)
		(width 0.0889)
		(layer "In11.Cu")
		(net "M_L_CPU1_SA_RSP<0>")
	)
	(arc
		(start 141.027658 -267.118846)
		(mid 141.209909 -267.169196)
		(end 141.393418 -267.123672)
		(width 0.0889)
		(layer "In11.Cu")
		(net "M_L_CPU1_SA_RSP<0>")
	)
	(arc
		(start 140.461746 -267.118846)
		(mid 140.744702 -267.042669)
		(end 141.027658 -267.118846)
		(width 0.0889)
		(layer "In11.Cu")
		(net "M_L_CPU1_SA_RSP<0>")
	)
	(arc
		(start 143.847566 -267.118846)
		(mid 144.034764 -267.169228)
		(end 144.221962 -267.118846)
		(width 0.0889)
		(layer "In11.Cu")
		(net "M_L_CPU1_SA_RSP<0>")
	)
	(arc
		(start 138.263122 -267.145008)
		(mid 138.425454 -267.167826)
		(end 138.581892 -267.118846)
		(width 0.0889)
		(layer "In11.Cu")
		(net "M_L_CPU1_SA_RSP<0>")
	)
	(arc
		(start 142.907766 -267.118846)
		(mid 143.09471 -267.169101)
		(end 143.281654 -267.118846)
		(width 0.0889)
		(layer "In11.Cu")
		(net "M_L_CPU1_SA_RSP<0>")
	)
	(arc
		(start 139.521692 -267.118846)
		(mid 139.804648 -267.042669)
		(end 140.087604 -267.118846)
		(width 0.0889)
		(layer "In11.Cu")
		(net "M_L_CPU1_SA_RSP<0>")
	)
	(segment
		(start 137.627868 -256.09042)
		(end 138.09472 -255.824482)
		(width 0.10668)
		(layer "F.Cu")
		(net "M_L_CPU1_SA_PAR")
	)
	(segment
		(start 200.69937 -253.010416)
		(end 203.170282 -253.010416)
		(width 0.14478)
		(layer "In11.Cu")
		(net "M_L_CPU1_SA_PAR")
	)
	(segment
		(start 141.667738 -255.501902)
		(end 141.67612 -255.497076)
		(width 0.0889)
		(layer "In11.Cu")
		(net "M_L_CPU1_SA_PAR")
	)
	(segment
		(start 147.819618 -256.551938)
		(end 150.986236 -256.551938)
		(width 0.14478)
		(layer "In11.Cu")
		(net "M_L_CPU1_SA_PAR")
	)
	(segment
		(start 158.903162 -255.572006)
		(end 198.96582 -255.572006)
		(width 0.14478)
		(layer "In11.Cu")
		(net "M_L_CPU1_SA_PAR")
	)
	(segment
		(start 140.15339 -255.497076)
		(end 140.161772 -255.501902)
		(width 0.0889)
		(layer "In11.Cu")
		(net "M_L_CPU1_SA_PAR")
	)
	(segment
		(start 199.843136 -254.69469)
		(end 199.843136 -253.86665)
		(width 0.14478)
		(layer "In11.Cu")
		(net "M_L_CPU1_SA_PAR")
	)
	(segment
		(start 203.170282 -253.010416)
		(end 206.248 -254.285242)
		(width 0.14478)
		(layer "In11.Cu")
		(net "M_L_CPU1_SA_PAR")
	)
	(segment
		(start 137.940796 -255.559052)
		(end 137.963148 -255.47574)
		(width 0.0889)
		(layer "In11.Cu")
		(net "M_L_CPU1_SA_PAR")
	)
	(segment
		(start 144.47774 -255.507998)
		(end 144.488154 -255.501902)
		(width 0.0889)
		(layer "In11.Cu")
		(net "M_L_CPU1_SA_PAR")
	)
	(segment
		(start 158.48457 -255.153414)
		(end 158.903162 -255.572006)
		(width 0.14478)
		(layer "In11.Cu")
		(net "M_L_CPU1_SA_PAR")
	)
	(segment
		(start 138.09472 -255.824482)
		(end 137.940796 -255.559052)
		(width 0.0889)
		(layer "In11.Cu")
		(net "M_L_CPU1_SA_PAR")
	)
	(segment
		(start 198.96582 -255.572006)
		(end 199.843136 -254.69469)
		(width 0.14478)
		(layer "In11.Cu")
		(net "M_L_CPU1_SA_PAR")
	)
	(segment
		(start 145.676112 -255.577848)
		(end 146.650202 -256.551938)
		(width 0.0889)
		(layer "In11.Cu")
		(net "M_L_CPU1_SA_PAR")
	)
	(segment
		(start 199.843136 -253.86665)
		(end 200.69937 -253.010416)
		(width 0.14478)
		(layer "In11.Cu")
		(net "M_L_CPU1_SA_PAR")
	)
	(segment
		(start 150.986236 -256.551938)
		(end 152.38476 -255.153414)
		(width 0.14478)
		(layer "In11.Cu")
		(net "M_L_CPU1_SA_PAR")
	)
	(segment
		(start 141.093444 -255.497076)
		(end 141.101826 -255.501902)
		(width 0.0889)
		(layer "In11.Cu")
		(net "M_L_CPU1_SA_PAR")
	)
	(segment
		(start 152.38476 -255.153414)
		(end 158.48457 -255.153414)
		(width 0.14478)
		(layer "In11.Cu")
		(net "M_L_CPU1_SA_PAR")
	)
	(segment
		(start 145.144744 -255.577848)
		(end 145.676112 -255.577848)
		(width 0.0889)
		(layer "In11.Cu")
		(net "M_L_CPU1_SA_PAR")
	)
	(segment
		(start 146.650202 -256.551938)
		(end 147.819618 -256.551938)
		(width 0.0889)
		(layer "In11.Cu")
		(net "M_L_CPU1_SA_PAR")
	)
	(arc
		(start 139.78763 -255.501902)
		(mid 139.969881 -255.451552)
		(end 140.15339 -255.497076)
		(width 0.0889)
		(layer "In11.Cu")
		(net "M_L_CPU1_SA_PAR")
	)
	(arc
		(start 142.98168 -255.501902)
		(mid 143.264636 -255.578079)
		(end 143.547592 -255.501902)
		(width 0.0889)
		(layer "In11.Cu")
		(net "M_L_CPU1_SA_PAR")
	)
	(arc
		(start 144.862042 -255.501902)
		(mid 144.998376 -255.558545)
		(end 145.144744 -255.577848)
		(width 0.0889)
		(layer "In11.Cu")
		(net "M_L_CPU1_SA_PAR")
	)
	(arc
		(start 137.963148 -255.47574)
		(mid 138.12548 -255.452922)
		(end 138.281918 -255.501902)
		(width 0.0889)
		(layer "In11.Cu")
		(net "M_L_CPU1_SA_PAR")
	)
	(arc
		(start 143.547592 -255.501902)
		(mid 143.73479 -255.45152)
		(end 143.921988 -255.501902)
		(width 0.0889)
		(layer "In11.Cu")
		(net "M_L_CPU1_SA_PAR")
	)
	(arc
		(start 140.161772 -255.501902)
		(mid 140.444728 -255.578079)
		(end 140.727684 -255.501902)
		(width 0.0889)
		(layer "In11.Cu")
		(net "M_L_CPU1_SA_PAR")
	)
	(arc
		(start 138.281918 -255.501902)
		(mid 138.564874 -255.578079)
		(end 138.84783 -255.501902)
		(width 0.0889)
		(layer "In11.Cu")
		(net "M_L_CPU1_SA_PAR")
	)
	(arc
		(start 144.488154 -255.501902)
		(mid 144.675098 -255.451647)
		(end 144.862042 -255.501902)
		(width 0.0889)
		(layer "In11.Cu")
		(net "M_L_CPU1_SA_PAR")
	)
	(arc
		(start 143.921988 -255.501902)
		(mid 144.199055 -255.578173)
		(end 144.47774 -255.507998)
		(width 0.0889)
		(layer "In11.Cu")
		(net "M_L_CPU1_SA_PAR")
	)
	(arc
		(start 138.84783 -255.501902)
		(mid 139.034774 -255.451647)
		(end 139.221718 -255.501902)
		(width 0.0889)
		(layer "In11.Cu")
		(net "M_L_CPU1_SA_PAR")
	)
	(arc
		(start 142.04188 -255.501902)
		(mid 142.324836 -255.578079)
		(end 142.607792 -255.501902)
		(width 0.0889)
		(layer "In11.Cu")
		(net "M_L_CPU1_SA_PAR")
	)
	(arc
		(start 141.101826 -255.501902)
		(mid 141.384782 -255.578079)
		(end 141.667738 -255.501902)
		(width 0.0889)
		(layer "In11.Cu")
		(net "M_L_CPU1_SA_PAR")
	)
	(arc
		(start 142.607792 -255.501902)
		(mid 142.794736 -255.451647)
		(end 142.98168 -255.501902)
		(width 0.0889)
		(layer "In11.Cu")
		(net "M_L_CPU1_SA_PAR")
	)
	(arc
		(start 140.727684 -255.501902)
		(mid 140.909935 -255.451552)
		(end 141.093444 -255.497076)
		(width 0.0889)
		(layer "In11.Cu")
		(net "M_L_CPU1_SA_PAR")
	)
	(arc
		(start 141.67612 -255.497076)
		(mid 141.859628 -255.451582)
		(end 142.04188 -255.501902)
		(width 0.0889)
		(layer "In11.Cu")
		(net "M_L_CPU1_SA_PAR")
	)
	(arc
		(start 139.221718 -255.501902)
		(mid 139.504674 -255.578079)
		(end 139.78763 -255.501902)
		(width 0.0889)
		(layer "In11.Cu")
		(net "M_L_CPU1_SA_PAR")
	)
	(segment
		(start 137.627868 -247.99036)
		(end 138.09472 -247.724422)
		(width 0.12954)
		(layer "F.Cu")
		(net "M_L_CPU1_SA_DQS_DP<9>")
	)
	(segment
		(start 197.748144 -239.332008)
		(end 198.126604 -239.710468)
		(width 0.16002)
		(layer "In11.Cu")
		(net "M_L_CPU1_SA_DQS_DP<9>")
	)
	(segment
		(start 182.660036 -239.332008)
		(end 183.179974 -239.851946)
		(width 0.16002)
		(layer "In11.Cu")
		(net "M_L_CPU1_SA_DQS_DP<9>")
	)
	(segment
		(start 147.919186 -248.116598)
		(end 148.187918 -248.116598)
		(width 0.16002)
		(layer "In11.Cu")
		(net "M_L_CPU1_SA_DQS_DP<9>")
	)
	(segment
		(start 187.7822 -240.560606)
		(end 188.157358 -240.185448)
		(width 0.16002)
		(layer "In11.Cu")
		(net "M_L_CPU1_SA_DQS_DP<9>")
	)
	(segment
		(start 170.395646 -239.501426)
		(end 170.555666 -239.661446)
		(width 0.16002)
		(layer "In11.Cu")
		(net "M_L_CPU1_SA_DQS_DP<9>")
	)
	(segment
		(start 199.586596 -239.561624)
		(end 200.30694 -239.561624)
		(width 0.16002)
		(layer "In11.Cu")
		(net "M_L_CPU1_SA_DQS_DP<9>")
	)
	(segment
		(start 195.326254 -240.560606)
		(end 195.701412 -240.185448)
		(width 0.16002)
		(layer "In11.Cu")
		(net "M_L_CPU1_SA_DQS_DP<9>")
	)
	(segment
		(start 188.157358 -240.185448)
		(end 188.778642 -240.185448)
		(width 0.16002)
		(layer "In11.Cu")
		(net "M_L_CPU1_SA_DQS_DP<9>")
	)
	(segment
		(start 201.87412 -239.561624)
		(end 202.147932 -239.835436)
		(width 0.16002)
		(layer "In11.Cu")
		(net "M_L_CPU1_SA_DQS_DP<9>")
	)
	(segment
		(start 141.094968 -247.394476)
		(end 141.10335 -247.399302)
		(width 0.09525)
		(layer "In11.Cu")
		(net "M_L_CPU1_SA_DQS_DP<9>")
	)
	(segment
		(start 175.494442 -239.710468)
		(end 177.81778 -239.710468)
		(width 0.16002)
		(layer "In11.Cu")
		(net "M_L_CPU1_SA_DQS_DP<9>")
	)
	(segment
		(start 141.666214 -247.399302)
		(end 141.674596 -247.394476)
		(width 0.09525)
		(layer "In11.Cu")
		(net "M_L_CPU1_SA_DQS_DP<9>")
	)
	(segment
		(start 189.632082 -239.332008)
		(end 190.20409 -239.332008)
		(width 0.16002)
		(layer "In11.Cu")
		(net "M_L_CPU1_SA_DQS_DP<9>")
	)
	(segment
		(start 200.30694 -239.561624)
		(end 200.43394 -239.688624)
		(width 0.16002)
		(layer "In11.Cu")
		(net "M_L_CPU1_SA_DQS_DP<9>")
	)
	(segment
		(start 174.543974 -239.332008)
		(end 175.115982 -239.332008)
		(width 0.16002)
		(layer "In11.Cu")
		(net "M_L_CPU1_SA_DQS_DP<9>")
	)
	(segment
		(start 186.103768 -240.223548)
		(end 186.440826 -240.560606)
		(width 0.16002)
		(layer "In11.Cu")
		(net "M_L_CPU1_SA_DQS_DP<9>")
	)
	(segment
		(start 185.595514 -239.470946)
		(end 185.943748 -239.470946)
		(width 0.16002)
		(layer "In11.Cu")
		(net "M_L_CPU1_SA_DQS_DP<9>")
	)
	(segment
		(start 184.361836 -240.560606)
		(end 185.098436 -240.560606)
		(width 0.16002)
		(layer "In11.Cu")
		(net "M_L_CPU1_SA_DQS_DP<9>")
	)
	(segment
		(start 173.690534 -240.185448)
		(end 174.543974 -239.332008)
		(width 0.16002)
		(layer "In11.Cu")
		(net "M_L_CPU1_SA_DQS_DP<9>")
	)
	(segment
		(start 143.546068 -247.399302)
		(end 143.560546 -247.39092)
		(width 0.09525)
		(layer "In11.Cu")
		(net "M_L_CPU1_SA_DQS_DP<9>")
	)
	(segment
		(start 172.694092 -240.560606)
		(end 173.06925 -240.185448)
		(width 0.16002)
		(layer "In11.Cu")
		(net "M_L_CPU1_SA_DQS_DP<9>")
	)
	(segment
		(start 170.892724 -240.560606)
		(end 172.694092 -240.560606)
		(width 0.16002)
		(layer "In11.Cu")
		(net "M_L_CPU1_SA_DQS_DP<9>")
	)
	(segment
		(start 137.940796 -247.458992)
		(end 137.964164 -247.372124)
		(width 0.09525)
		(layer "In11.Cu")
		(net "M_L_CPU1_SA_DQS_DP<9>")
	)
	(segment
		(start 177.81778 -239.710468)
		(end 178.667918 -240.560606)
		(width 0.16002)
		(layer "In11.Cu")
		(net "M_L_CPU1_SA_DQS_DP<9>")
	)
	(segment
		(start 188.778642 -240.185448)
		(end 189.632082 -239.332008)
		(width 0.16002)
		(layer "In11.Cu")
		(net "M_L_CPU1_SA_DQS_DP<9>")
	)
	(segment
		(start 169.887392 -239.661446)
		(end 170.047412 -239.501426)
		(width 0.16002)
		(layer "In11.Cu")
		(net "M_L_CPU1_SA_DQS_DP<9>")
	)
	(segment
		(start 199.437752 -239.710468)
		(end 199.586596 -239.561624)
		(width 0.16002)
		(layer "In11.Cu")
		(net "M_L_CPU1_SA_DQS_DP<9>")
	)
	(segment
		(start 140.154914 -247.394476)
		(end 140.163296 -247.399302)
		(width 0.09525)
		(layer "In11.Cu")
		(net "M_L_CPU1_SA_DQS_DP<9>")
	)
	(segment
		(start 148.187918 -248.116598)
		(end 149.12467 -247.179846)
		(width 0.16002)
		(layer "In11.Cu")
		(net "M_L_CPU1_SA_DQS_DP<9>")
	)
	(segment
		(start 164.233606 -241.41049)
		(end 166.933626 -241.41049)
		(width 0.16002)
		(layer "In11.Cu")
		(net "M_L_CPU1_SA_DQS_DP<9>")
	)
	(segment
		(start 185.943748 -239.470946)
		(end 186.103768 -239.630966)
		(width 0.16002)
		(layer "In11.Cu")
		(net "M_L_CPU1_SA_DQS_DP<9>")
	)
	(segment
		(start 190.20409 -239.332008)
		(end 190.58255 -239.710468)
		(width 0.16002)
		(layer "In11.Cu")
		(net "M_L_CPU1_SA_DQS_DP<9>")
	)
	(segment
		(start 185.435494 -239.630966)
		(end 185.595514 -239.470946)
		(width 0.16002)
		(layer "In11.Cu")
		(net "M_L_CPU1_SA_DQS_DP<9>")
	)
	(segment
		(start 166.933626 -241.41049)
		(end 167.78351 -240.560606)
		(width 0.16002)
		(layer "In11.Cu")
		(net "M_L_CPU1_SA_DQS_DP<9>")
	)
	(segment
		(start 190.58255 -239.710468)
		(end 192.905888 -239.710468)
		(width 0.16002)
		(layer "In11.Cu")
		(net "M_L_CPU1_SA_DQS_DP<9>")
	)
	(segment
		(start 167.78351 -240.560606)
		(end 169.550334 -240.560606)
		(width 0.16002)
		(layer "In11.Cu")
		(net "M_L_CPU1_SA_DQS_DP<9>")
	)
	(segment
		(start 180.613304 -240.185448)
		(end 181.234588 -240.185448)
		(width 0.16002)
		(layer "In11.Cu")
		(net "M_L_CPU1_SA_DQS_DP<9>")
	)
	(segment
		(start 144.848072 -247.38965)
		(end 144.864836 -247.399302)
		(width 0.09525)
		(layer "In11.Cu")
		(net "M_L_CPU1_SA_DQS_DP<9>")
	)
	(segment
		(start 170.555666 -239.661446)
		(end 170.555666 -240.223548)
		(width 0.16002)
		(layer "In11.Cu")
		(net "M_L_CPU1_SA_DQS_DP<9>")
	)
	(segment
		(start 195.701412 -240.185448)
		(end 196.322696 -240.185448)
		(width 0.16002)
		(layer "In11.Cu")
		(net "M_L_CPU1_SA_DQS_DP<9>")
	)
	(segment
		(start 158.46425 -247.179846)
		(end 164.233606 -241.41049)
		(width 0.16002)
		(layer "In11.Cu")
		(net "M_L_CPU1_SA_DQS_DP<9>")
	)
	(segment
		(start 180.238146 -240.560606)
		(end 180.613304 -240.185448)
		(width 0.16002)
		(layer "In11.Cu")
		(net "M_L_CPU1_SA_DQS_DP<9>")
	)
	(segment
		(start 183.179974 -239.851946)
		(end 183.653176 -239.851946)
		(width 0.16002)
		(layer "In11.Cu")
		(net "M_L_CPU1_SA_DQS_DP<9>")
	)
	(segment
		(start 178.667918 -240.560606)
		(end 180.238146 -240.560606)
		(width 0.16002)
		(layer "In11.Cu")
		(net "M_L_CPU1_SA_DQS_DP<9>")
	)
	(segment
		(start 144.46504 -247.412764)
		(end 144.488408 -247.399302)
		(width 0.09525)
		(layer "In11.Cu")
		(net "M_L_CPU1_SA_DQS_DP<9>")
	)
	(segment
		(start 147.48891 -248.05767)
		(end 147.836636 -248.05767)
		(width 0.09525)
		(layer "In11.Cu")
		(net "M_L_CPU1_SA_DQS_DP<9>")
	)
	(segment
		(start 145.144744 -247.474232)
		(end 146.905472 -247.474232)
		(width 0.09525)
		(layer "In11.Cu")
		(net "M_L_CPU1_SA_DQS_DP<9>")
	)
	(segment
		(start 186.440826 -240.560606)
		(end 187.7822 -240.560606)
		(width 0.16002)
		(layer "In11.Cu")
		(net "M_L_CPU1_SA_DQS_DP<9>")
	)
	(segment
		(start 192.905888 -239.710468)
		(end 193.756026 -240.560606)
		(width 0.16002)
		(layer "In11.Cu")
		(net "M_L_CPU1_SA_DQS_DP<9>")
	)
	(segment
		(start 169.550334 -240.560606)
		(end 169.887392 -240.223548)
		(width 0.16002)
		(layer "In11.Cu")
		(net "M_L_CPU1_SA_DQS_DP<9>")
	)
	(segment
		(start 201.041 -239.561624)
		(end 201.87412 -239.561624)
		(width 0.16002)
		(layer "In11.Cu")
		(net "M_L_CPU1_SA_DQS_DP<9>")
	)
	(segment
		(start 138.09472 -247.724422)
		(end 137.940796 -247.458992)
		(width 0.09525)
		(layer "In11.Cu")
		(net "M_L_CPU1_SA_DQS_DP<9>")
	)
	(segment
		(start 149.12467 -247.179846)
		(end 158.46425 -247.179846)
		(width 0.16002)
		(layer "In11.Cu")
		(net "M_L_CPU1_SA_DQS_DP<9>")
	)
	(segment
		(start 185.435494 -240.223548)
		(end 185.435494 -239.630966)
		(width 0.16002)
		(layer "In11.Cu")
		(net "M_L_CPU1_SA_DQS_DP<9>")
	)
	(segment
		(start 173.06925 -240.185448)
		(end 173.690534 -240.185448)
		(width 0.16002)
		(layer "In11.Cu")
		(net "M_L_CPU1_SA_DQS_DP<9>")
	)
	(segment
		(start 175.115982 -239.332008)
		(end 175.494442 -239.710468)
		(width 0.16002)
		(layer "In11.Cu")
		(net "M_L_CPU1_SA_DQS_DP<9>")
	)
	(segment
		(start 197.176136 -239.332008)
		(end 197.748144 -239.332008)
		(width 0.16002)
		(layer "In11.Cu")
		(net "M_L_CPU1_SA_DQS_DP<9>")
	)
	(segment
		(start 186.103768 -239.630966)
		(end 186.103768 -240.223548)
		(width 0.16002)
		(layer "In11.Cu")
		(net "M_L_CPU1_SA_DQS_DP<9>")
	)
	(segment
		(start 181.234588 -240.185448)
		(end 182.088028 -239.332008)
		(width 0.16002)
		(layer "In11.Cu")
		(net "M_L_CPU1_SA_DQS_DP<9>")
	)
	(segment
		(start 185.098436 -240.560606)
		(end 185.435494 -240.223548)
		(width 0.16002)
		(layer "In11.Cu")
		(net "M_L_CPU1_SA_DQS_DP<9>")
	)
	(segment
		(start 147.895564 -248.116598)
		(end 147.919186 -248.116598)
		(width 0.09525)
		(layer "In11.Cu")
		(net "M_L_CPU1_SA_DQS_DP<9>")
	)
	(segment
		(start 183.653176 -239.851946)
		(end 184.361836 -240.560606)
		(width 0.16002)
		(layer "In11.Cu")
		(net "M_L_CPU1_SA_DQS_DP<9>")
	)
	(segment
		(start 196.322696 -240.185448)
		(end 197.176136 -239.332008)
		(width 0.16002)
		(layer "In11.Cu")
		(net "M_L_CPU1_SA_DQS_DP<9>")
	)
	(segment
		(start 193.756026 -240.560606)
		(end 195.326254 -240.560606)
		(width 0.16002)
		(layer "In11.Cu")
		(net "M_L_CPU1_SA_DQS_DP<9>")
	)
	(segment
		(start 182.088028 -239.332008)
		(end 182.660036 -239.332008)
		(width 0.16002)
		(layer "In11.Cu")
		(net "M_L_CPU1_SA_DQS_DP<9>")
	)
	(segment
		(start 170.047412 -239.501426)
		(end 170.395646 -239.501426)
		(width 0.16002)
		(layer "In11.Cu")
		(net "M_L_CPU1_SA_DQS_DP<9>")
	)
	(segment
		(start 198.126604 -239.710468)
		(end 199.437752 -239.710468)
		(width 0.16002)
		(layer "In11.Cu")
		(net "M_L_CPU1_SA_DQS_DP<9>")
	)
	(segment
		(start 146.905472 -247.474232)
		(end 147.48891 -248.05767)
		(width 0.09525)
		(layer "In11.Cu")
		(net "M_L_CPU1_SA_DQS_DP<9>")
	)
	(segment
		(start 147.836636 -248.05767)
		(end 147.895564 -248.116598)
		(width 0.09525)
		(layer "In11.Cu")
		(net "M_L_CPU1_SA_DQS_DP<9>")
	)
	(segment
		(start 200.43394 -239.688624)
		(end 200.914 -239.688624)
		(width 0.16002)
		(layer "In11.Cu")
		(net "M_L_CPU1_SA_DQS_DP<9>")
	)
	(segment
		(start 200.914 -239.688624)
		(end 201.041 -239.561624)
		(width 0.16002)
		(layer "In11.Cu")
		(net "M_L_CPU1_SA_DQS_DP<9>")
	)
	(segment
		(start 169.887392 -240.223548)
		(end 169.887392 -239.661446)
		(width 0.16002)
		(layer "In11.Cu")
		(net "M_L_CPU1_SA_DQS_DP<9>")
	)
	(segment
		(start 170.555666 -240.223548)
		(end 170.892724 -240.560606)
		(width 0.16002)
		(layer "In11.Cu")
		(net "M_L_CPU1_SA_DQS_DP<9>")
	)
	(arc
		(start 140.163296 -247.399302)
		(mid 140.444728 -247.475057)
		(end 140.72616 -247.399302)
		(width 0.09525)
		(layer "In11.Cu")
		(net "M_L_CPU1_SA_DQS_DP<9>")
	)
	(arc
		(start 143.924274 -247.399302)
		(mid 144.192937 -247.47552)
		(end 144.46504 -247.412764)
		(width 0.09525)
		(layer "In11.Cu")
		(net "M_L_CPU1_SA_DQS_DP<9>")
	)
	(arc
		(start 143.560546 -247.39092)
		(mid 143.743486 -247.348245)
		(end 143.924274 -247.399302)
		(width 0.09525)
		(layer "In11.Cu")
		(net "M_L_CPU1_SA_DQS_DP<9>")
	)
	(arc
		(start 140.72616 -247.399302)
		(mid 140.909935 -247.34853)
		(end 141.094968 -247.394476)
		(width 0.09525)
		(layer "In11.Cu")
		(net "M_L_CPU1_SA_DQS_DP<9>")
	)
	(arc
		(start 138.283442 -247.399302)
		(mid 138.564874 -247.475057)
		(end 138.846306 -247.399302)
		(width 0.09525)
		(layer "In11.Cu")
		(net "M_L_CPU1_SA_DQS_DP<9>")
	)
	(arc
		(start 144.488408 -247.399302)
		(mid 144.667014 -247.348634)
		(end 144.848072 -247.38965)
		(width 0.09525)
		(layer "In11.Cu")
		(net "M_L_CPU1_SA_DQS_DP<9>")
	)
	(arc
		(start 142.043404 -247.399302)
		(mid 142.324836 -247.475057)
		(end 142.606268 -247.399302)
		(width 0.09525)
		(layer "In11.Cu")
		(net "M_L_CPU1_SA_DQS_DP<9>")
	)
	(arc
		(start 137.964164 -247.372124)
		(mid 138.126846 -247.349992)
		(end 138.283442 -247.399302)
		(width 0.09525)
		(layer "In11.Cu")
		(net "M_L_CPU1_SA_DQS_DP<9>")
	)
	(arc
		(start 141.674596 -247.394476)
		(mid 141.859628 -247.348562)
		(end 142.043404 -247.399302)
		(width 0.09525)
		(layer "In11.Cu")
		(net "M_L_CPU1_SA_DQS_DP<9>")
	)
	(arc
		(start 142.983204 -247.399302)
		(mid 143.264636 -247.475057)
		(end 143.546068 -247.399302)
		(width 0.09525)
		(layer "In11.Cu")
		(net "M_L_CPU1_SA_DQS_DP<9>")
	)
	(arc
		(start 141.10335 -247.399302)
		(mid 141.384782 -247.475057)
		(end 141.666214 -247.399302)
		(width 0.09525)
		(layer "In11.Cu")
		(net "M_L_CPU1_SA_DQS_DP<9>")
	)
	(arc
		(start 139.786106 -247.399302)
		(mid 139.969881 -247.34853)
		(end 140.154914 -247.394476)
		(width 0.09525)
		(layer "In11.Cu")
		(net "M_L_CPU1_SA_DQS_DP<9>")
	)
	(arc
		(start 138.846306 -247.399302)
		(mid 139.034774 -247.348625)
		(end 139.223242 -247.399302)
		(width 0.09525)
		(layer "In11.Cu")
		(net "M_L_CPU1_SA_DQS_DP<9>")
	)
	(arc
		(start 144.864836 -247.399302)
		(mid 144.999854 -247.455221)
		(end 145.144744 -247.474232)
		(width 0.09525)
		(layer "In11.Cu")
		(net "M_L_CPU1_SA_DQS_DP<9>")
	)
	(arc
		(start 142.606268 -247.399302)
		(mid 142.794736 -247.348625)
		(end 142.983204 -247.399302)
		(width 0.09525)
		(layer "In11.Cu")
		(net "M_L_CPU1_SA_DQS_DP<9>")
	)
	(arc
		(start 139.223242 -247.399302)
		(mid 139.504674 -247.475057)
		(end 139.786106 -247.399302)
		(width 0.09525)
		(layer "In11.Cu")
		(net "M_L_CPU1_SA_DQS_DP<9>")
	)
	(segment
		(start 137.627868 -243.130324)
		(end 138.09472 -242.864386)
		(width 0.12954)
		(layer "F.Cu")
		(net "M_L_CPU1_SA_DQS_DP<8>")
	)
	(segment
		(start 170.040554 -230.680006)
		(end 170.85945 -230.680006)
		(width 0.16002)
		(layer "In11.Cu")
		(net "M_L_CPU1_SA_DQS_DP<8>")
	)
	(segment
		(start 169.703496 -230.342948)
		(end 170.040554 -230.680006)
		(width 0.16002)
		(layer "In11.Cu")
		(net "M_L_CPU1_SA_DQS_DP<8>")
	)
	(segment
		(start 145.144744 -242.614958)
		(end 146.464782 -242.614958)
		(width 0.09525)
		(layer "In11.Cu")
		(net "M_L_CPU1_SA_DQS_DP<8>")
	)
	(segment
		(start 182.660036 -229.982014)
		(end 183.038496 -230.360474)
		(width 0.16002)
		(layer "In11.Cu")
		(net "M_L_CPU1_SA_DQS_DP<8>")
	)
	(segment
		(start 156.678884 -239.978692)
		(end 157.104588 -239.552988)
		(width 0.16002)
		(layer "In11.Cu")
		(net "M_L_CPU1_SA_DQS_DP<8>")
	)
	(segment
		(start 168.698164 -230.680006)
		(end 169.035222 -230.342948)
		(width 0.16002)
		(layer "In11.Cu")
		(net "M_L_CPU1_SA_DQS_DP<8>")
	)
	(segment
		(start 147.555204 -241.524536)
		(end 147.836636 -241.524536)
		(width 0.09525)
		(layer "In11.Cu")
		(net "M_L_CPU1_SA_DQS_DP<8>")
	)
	(segment
		(start 201.87412 -230.21163)
		(end 202.147932 -230.485442)
		(width 0.16002)
		(layer "In11.Cu")
		(net "M_L_CPU1_SA_DQS_DP<8>")
	)
	(segment
		(start 169.543476 -229.966266)
		(end 169.703496 -230.126286)
		(width 0.16002)
		(layer "In11.Cu")
		(net "M_L_CPU1_SA_DQS_DP<8>")
	)
	(segment
		(start 169.035222 -230.126286)
		(end 169.195242 -229.966266)
		(width 0.16002)
		(layer "In11.Cu")
		(net "M_L_CPU1_SA_DQS_DP<8>")
	)
	(segment
		(start 198.126604 -230.360474)
		(end 199.437752 -230.360474)
		(width 0.16002)
		(layer "In11.Cu")
		(net "M_L_CPU1_SA_DQS_DP<8>")
	)
	(segment
		(start 156.20238 -239.978692)
		(end 156.678884 -239.978692)
		(width 0.16002)
		(layer "In11.Cu")
		(net "M_L_CPU1_SA_DQS_DP<8>")
	)
	(segment
		(start 190.20409 -229.982014)
		(end 190.58255 -230.360474)
		(width 0.16002)
		(layer "In11.Cu")
		(net "M_L_CPU1_SA_DQS_DP<8>")
	)
	(segment
		(start 155.302458 -241.355118)
		(end 155.728162 -240.929414)
		(width 0.16002)
		(layer "In11.Cu")
		(net "M_L_CPU1_SA_DQS_DP<8>")
	)
	(segment
		(start 169.035222 -230.342948)
		(end 169.035222 -230.126286)
		(width 0.16002)
		(layer "In11.Cu")
		(net "M_L_CPU1_SA_DQS_DP<8>")
	)
	(segment
		(start 196.322696 -230.835454)
		(end 197.176136 -229.982014)
		(width 0.16002)
		(layer "In11.Cu")
		(net "M_L_CPU1_SA_DQS_DP<8>")
	)
	(segment
		(start 155.672282 -239.674654)
		(end 155.898342 -239.674654)
		(width 0.16002)
		(layer "In11.Cu")
		(net "M_L_CPU1_SA_DQS_DP<8>")
	)
	(segment
		(start 157.104588 -239.076484)
		(end 156.80055 -238.772446)
		(width 0.16002)
		(layer "In11.Cu")
		(net "M_L_CPU1_SA_DQS_DP<8>")
	)
	(segment
		(start 169.195242 -229.966266)
		(end 169.543476 -229.966266)
		(width 0.16002)
		(layer "In11.Cu")
		(net "M_L_CPU1_SA_DQS_DP<8>")
	)
	(segment
		(start 186.447176 -231.210612)
		(end 187.7822 -231.210612)
		(width 0.16002)
		(layer "In11.Cu")
		(net "M_L_CPU1_SA_DQS_DP<8>")
	)
	(segment
		(start 169.703496 -230.126286)
		(end 169.703496 -230.342948)
		(width 0.16002)
		(layer "In11.Cu")
		(net "M_L_CPU1_SA_DQS_DP<8>")
	)
	(segment
		(start 178.205892 -230.360474)
		(end 179.05603 -231.210612)
		(width 0.16002)
		(layer "In11.Cu")
		(net "M_L_CPU1_SA_DQS_DP<8>")
	)
	(segment
		(start 167.991536 -230.680006)
		(end 168.698164 -230.680006)
		(width 0.16002)
		(layer "In11.Cu")
		(net "M_L_CPU1_SA_DQS_DP<8>")
	)
	(segment
		(start 188.778642 -230.835454)
		(end 189.632082 -229.982014)
		(width 0.16002)
		(layer "In11.Cu")
		(net "M_L_CPU1_SA_DQS_DP<8>")
	)
	(segment
		(start 182.088028 -229.982014)
		(end 182.660036 -229.982014)
		(width 0.16002)
		(layer "In11.Cu")
		(net "M_L_CPU1_SA_DQS_DP<8>")
	)
	(segment
		(start 181.234588 -230.835454)
		(end 182.088028 -229.982014)
		(width 0.16002)
		(layer "In11.Cu")
		(net "M_L_CPU1_SA_DQS_DP<8>")
	)
	(segment
		(start 166.14648 -230.835454)
		(end 166.99992 -229.982014)
		(width 0.16002)
		(layer "In11.Cu")
		(net "M_L_CPU1_SA_DQS_DP<8>")
	)
	(segment
		(start 173.690534 -230.835454)
		(end 174.543974 -229.982014)
		(width 0.16002)
		(layer "In11.Cu")
		(net "M_L_CPU1_SA_DQS_DP<8>")
	)
	(segment
		(start 190.58255 -230.360474)
		(end 192.905888 -230.360474)
		(width 0.16002)
		(layer "In11.Cu")
		(net "M_L_CPU1_SA_DQS_DP<8>")
	)
	(segment
		(start 188.157358 -230.835454)
		(end 188.778642 -230.835454)
		(width 0.16002)
		(layer "In11.Cu")
		(net "M_L_CPU1_SA_DQS_DP<8>")
	)
	(segment
		(start 189.632082 -229.982014)
		(end 190.20409 -229.982014)
		(width 0.16002)
		(layer "In11.Cu")
		(net "M_L_CPU1_SA_DQS_DP<8>")
	)
	(segment
		(start 200.4949 -230.33863)
		(end 200.97496 -230.33863)
		(width 0.16002)
		(layer "In11.Cu")
		(net "M_L_CPU1_SA_DQS_DP<8>")
	)
	(segment
		(start 199.586596 -230.21163)
		(end 200.3679 -230.21163)
		(width 0.16002)
		(layer "In11.Cu")
		(net "M_L_CPU1_SA_DQS_DP<8>")
	)
	(segment
		(start 144.476216 -242.545362)
		(end 144.48663 -242.539266)
		(width 0.09525)
		(layer "In11.Cu")
		(net "M_L_CPU1_SA_DQS_DP<8>")
	)
	(segment
		(start 155.898342 -239.674654)
		(end 156.20238 -239.978692)
		(width 0.16002)
		(layer "In11.Cu")
		(net "M_L_CPU1_SA_DQS_DP<8>")
	)
	(segment
		(start 187.7822 -231.210612)
		(end 188.157358 -230.835454)
		(width 0.16002)
		(layer "In11.Cu")
		(net "M_L_CPU1_SA_DQS_DP<8>")
	)
	(segment
		(start 155.728162 -240.929414)
		(end 155.728162 -240.45291)
		(width 0.16002)
		(layer "In11.Cu")
		(net "M_L_CPU1_SA_DQS_DP<8>")
	)
	(segment
		(start 155.728162 -240.45291)
		(end 155.424124 -240.148872)
		(width 0.16002)
		(layer "In11.Cu")
		(net "M_L_CPU1_SA_DQS_DP<8>")
	)
	(segment
		(start 183.038496 -230.360474)
		(end 185.597038 -230.360474)
		(width 0.16002)
		(layer "In11.Cu")
		(net "M_L_CPU1_SA_DQS_DP<8>")
	)
	(segment
		(start 172.694092 -231.210612)
		(end 173.06925 -230.835454)
		(width 0.16002)
		(layer "In11.Cu")
		(net "M_L_CPU1_SA_DQS_DP<8>")
	)
	(segment
		(start 200.3679 -230.21163)
		(end 200.4949 -230.33863)
		(width 0.16002)
		(layer "In11.Cu")
		(net "M_L_CPU1_SA_DQS_DP<8>")
	)
	(segment
		(start 138.09472 -242.864386)
		(end 137.940796 -242.598956)
		(width 0.09525)
		(layer "In11.Cu")
		(net "M_L_CPU1_SA_DQS_DP<8>")
	)
	(segment
		(start 167.293544 -229.982014)
		(end 167.991536 -230.680006)
		(width 0.16002)
		(layer "In11.Cu")
		(net "M_L_CPU1_SA_DQS_DP<8>")
	)
	(segment
		(start 170.85945 -230.680006)
		(end 171.390056 -231.210612)
		(width 0.16002)
		(layer "In11.Cu")
		(net "M_L_CPU1_SA_DQS_DP<8>")
	)
	(segment
		(start 154.295856 -241.05108)
		(end 154.521916 -241.05108)
		(width 0.16002)
		(layer "In11.Cu")
		(net "M_L_CPU1_SA_DQS_DP<8>")
	)
	(segment
		(start 180.238146 -231.210612)
		(end 180.613304 -230.835454)
		(width 0.16002)
		(layer "In11.Cu")
		(net "M_L_CPU1_SA_DQS_DP<8>")
	)
	(segment
		(start 141.094968 -242.53444)
		(end 141.10335 -242.539266)
		(width 0.09525)
		(layer "In11.Cu")
		(net "M_L_CPU1_SA_DQS_DP<8>")
	)
	(segment
		(start 147.836636 -241.524536)
		(end 147.895564 -241.583464)
		(width 0.09525)
		(layer "In11.Cu")
		(net "M_L_CPU1_SA_DQS_DP<8>")
	)
	(segment
		(start 179.05603 -231.210612)
		(end 180.238146 -231.210612)
		(width 0.16002)
		(layer "In11.Cu")
		(net "M_L_CPU1_SA_DQS_DP<8>")
	)
	(segment
		(start 146.464782 -242.614958)
		(end 147.555204 -241.524536)
		(width 0.09525)
		(layer "In11.Cu")
		(net "M_L_CPU1_SA_DQS_DP<8>")
	)
	(segment
		(start 171.390056 -231.210612)
		(end 172.694092 -231.210612)
		(width 0.16002)
		(layer "In11.Cu")
		(net "M_L_CPU1_SA_DQS_DP<8>")
	)
	(segment
		(start 193.756026 -231.210612)
		(end 195.326254 -231.210612)
		(width 0.16002)
		(layer "In11.Cu")
		(net "M_L_CPU1_SA_DQS_DP<8>")
	)
	(segment
		(start 185.597038 -230.360474)
		(end 186.447176 -231.210612)
		(width 0.16002)
		(layer "In11.Cu")
		(net "M_L_CPU1_SA_DQS_DP<8>")
	)
	(segment
		(start 200.97496 -230.33863)
		(end 201.10196 -230.21163)
		(width 0.16002)
		(layer "In11.Cu")
		(net "M_L_CPU1_SA_DQS_DP<8>")
	)
	(segment
		(start 155.424124 -239.922812)
		(end 155.672282 -239.674654)
		(width 0.16002)
		(layer "In11.Cu")
		(net "M_L_CPU1_SA_DQS_DP<8>")
	)
	(segment
		(start 201.10196 -230.21163)
		(end 201.87412 -230.21163)
		(width 0.16002)
		(layer "In11.Cu")
		(net "M_L_CPU1_SA_DQS_DP<8>")
	)
	(segment
		(start 174.543974 -229.982014)
		(end 175.115982 -229.982014)
		(width 0.16002)
		(layer "In11.Cu")
		(net "M_L_CPU1_SA_DQS_DP<8>")
	)
	(segment
		(start 192.905888 -230.360474)
		(end 193.756026 -231.210612)
		(width 0.16002)
		(layer "In11.Cu")
		(net "M_L_CPU1_SA_DQS_DP<8>")
	)
	(segment
		(start 154.521916 -241.05108)
		(end 154.825954 -241.355118)
		(width 0.16002)
		(layer "In11.Cu")
		(net "M_L_CPU1_SA_DQS_DP<8>")
	)
	(segment
		(start 137.940796 -242.598956)
		(end 137.964164 -242.512088)
		(width 0.09525)
		(layer "In11.Cu")
		(net "M_L_CPU1_SA_DQS_DP<8>")
	)
	(segment
		(start 175.494442 -230.360474)
		(end 178.205892 -230.360474)
		(width 0.16002)
		(layer "In11.Cu")
		(net "M_L_CPU1_SA_DQS_DP<8>")
	)
	(segment
		(start 153.763472 -241.583464)
		(end 154.295856 -241.05108)
		(width 0.16002)
		(layer "In11.Cu")
		(net "M_L_CPU1_SA_DQS_DP<8>")
	)
	(segment
		(start 164.511482 -230.835454)
		(end 166.14648 -230.835454)
		(width 0.16002)
		(layer "In11.Cu")
		(net "M_L_CPU1_SA_DQS_DP<8>")
	)
	(segment
		(start 166.99992 -229.982014)
		(end 167.293544 -229.982014)
		(width 0.16002)
		(layer "In11.Cu")
		(net "M_L_CPU1_SA_DQS_DP<8>")
	)
	(segment
		(start 147.895564 -241.583464)
		(end 147.919186 -241.583464)
		(width 0.09525)
		(layer "In11.Cu")
		(net "M_L_CPU1_SA_DQS_DP<8>")
	)
	(segment
		(start 155.424124 -240.148872)
		(end 155.424124 -239.922812)
		(width 0.16002)
		(layer "In11.Cu")
		(net "M_L_CPU1_SA_DQS_DP<8>")
	)
	(segment
		(start 175.115982 -229.982014)
		(end 175.494442 -230.360474)
		(width 0.16002)
		(layer "In11.Cu")
		(net "M_L_CPU1_SA_DQS_DP<8>")
	)
	(segment
		(start 147.919186 -241.583464)
		(end 153.763472 -241.583464)
		(width 0.16002)
		(layer "In11.Cu")
		(net "M_L_CPU1_SA_DQS_DP<8>")
	)
	(segment
		(start 199.437752 -230.360474)
		(end 199.586596 -230.21163)
		(width 0.16002)
		(layer "In11.Cu")
		(net "M_L_CPU1_SA_DQS_DP<8>")
	)
	(segment
		(start 195.701412 -230.835454)
		(end 196.322696 -230.835454)
		(width 0.16002)
		(layer "In11.Cu")
		(net "M_L_CPU1_SA_DQS_DP<8>")
	)
	(segment
		(start 180.613304 -230.835454)
		(end 181.234588 -230.835454)
		(width 0.16002)
		(layer "In11.Cu")
		(net "M_L_CPU1_SA_DQS_DP<8>")
	)
	(segment
		(start 157.104588 -239.552988)
		(end 157.104588 -239.076484)
		(width 0.16002)
		(layer "In11.Cu")
		(net "M_L_CPU1_SA_DQS_DP<8>")
	)
	(segment
		(start 195.326254 -231.210612)
		(end 195.701412 -230.835454)
		(width 0.16002)
		(layer "In11.Cu")
		(net "M_L_CPU1_SA_DQS_DP<8>")
	)
	(segment
		(start 154.825954 -241.355118)
		(end 155.302458 -241.355118)
		(width 0.16002)
		(layer "In11.Cu")
		(net "M_L_CPU1_SA_DQS_DP<8>")
	)
	(segment
		(start 197.176136 -229.982014)
		(end 197.748144 -229.982014)
		(width 0.16002)
		(layer "In11.Cu")
		(net "M_L_CPU1_SA_DQS_DP<8>")
	)
	(segment
		(start 140.154914 -242.53444)
		(end 140.163296 -242.539266)
		(width 0.09525)
		(layer "In11.Cu")
		(net "M_L_CPU1_SA_DQS_DP<8>")
	)
	(segment
		(start 156.80055 -238.546386)
		(end 164.511482 -230.835454)
		(width 0.16002)
		(layer "In11.Cu")
		(net "M_L_CPU1_SA_DQS_DP<8>")
	)
	(segment
		(start 197.748144 -229.982014)
		(end 198.126604 -230.360474)
		(width 0.16002)
		(layer "In11.Cu")
		(net "M_L_CPU1_SA_DQS_DP<8>")
	)
	(segment
		(start 141.666214 -242.539266)
		(end 141.674596 -242.53444)
		(width 0.09525)
		(layer "In11.Cu")
		(net "M_L_CPU1_SA_DQS_DP<8>")
	)
	(segment
		(start 156.80055 -238.772446)
		(end 156.80055 -238.546386)
		(width 0.16002)
		(layer "In11.Cu")
		(net "M_L_CPU1_SA_DQS_DP<8>")
	)
	(segment
		(start 173.06925 -230.835454)
		(end 173.690534 -230.835454)
		(width 0.16002)
		(layer "In11.Cu")
		(net "M_L_CPU1_SA_DQS_DP<8>")
	)
	(arc
		(start 140.72616 -242.539266)
		(mid 140.909935 -242.488494)
		(end 141.094968 -242.53444)
		(width 0.09525)
		(layer "In11.Cu")
		(net "M_L_CPU1_SA_DQS_DP<8>")
	)
	(arc
		(start 139.223242 -242.539266)
		(mid 139.504674 -242.615021)
		(end 139.786106 -242.539266)
		(width 0.09525)
		(layer "In11.Cu")
		(net "M_L_CPU1_SA_DQS_DP<8>")
	)
	(arc
		(start 142.606268 -242.539266)
		(mid 142.794736 -242.488589)
		(end 142.983204 -242.539266)
		(width 0.09525)
		(layer "In11.Cu")
		(net "M_L_CPU1_SA_DQS_DP<8>")
	)
	(arc
		(start 144.48663 -242.539266)
		(mid 144.675098 -242.488589)
		(end 144.863566 -242.539266)
		(width 0.09525)
		(layer "In11.Cu")
		(net "M_L_CPU1_SA_DQS_DP<8>")
	)
	(arc
		(start 142.043404 -242.539266)
		(mid 142.324836 -242.615021)
		(end 142.606268 -242.539266)
		(width 0.09525)
		(layer "In11.Cu")
		(net "M_L_CPU1_SA_DQS_DP<8>")
	)
	(arc
		(start 143.546068 -242.539266)
		(mid 143.73479 -242.488462)
		(end 143.923512 -242.539266)
		(width 0.09525)
		(layer "In11.Cu")
		(net "M_L_CPU1_SA_DQS_DP<8>")
	)
	(arc
		(start 137.964164 -242.512088)
		(mid 138.126846 -242.489956)
		(end 138.283442 -242.539266)
		(width 0.09525)
		(layer "In11.Cu")
		(net "M_L_CPU1_SA_DQS_DP<8>")
	)
	(arc
		(start 142.983204 -242.539266)
		(mid 143.264636 -242.615021)
		(end 143.546068 -242.539266)
		(width 0.09525)
		(layer "In11.Cu")
		(net "M_L_CPU1_SA_DQS_DP<8>")
	)
	(arc
		(start 143.923512 -242.539266)
		(mid 144.199055 -242.615115)
		(end 144.476216 -242.545362)
		(width 0.09525)
		(layer "In11.Cu")
		(net "M_L_CPU1_SA_DQS_DP<8>")
	)
	(arc
		(start 139.786106 -242.539266)
		(mid 139.969881 -242.488494)
		(end 140.154914 -242.53444)
		(width 0.09525)
		(layer "In11.Cu")
		(net "M_L_CPU1_SA_DQS_DP<8>")
	)
	(arc
		(start 144.863566 -242.539266)
		(mid 144.999158 -242.595657)
		(end 145.144744 -242.614958)
		(width 0.09525)
		(layer "In11.Cu")
		(net "M_L_CPU1_SA_DQS_DP<8>")
	)
	(arc
		(start 138.283442 -242.539266)
		(mid 138.564874 -242.615021)
		(end 138.846306 -242.539266)
		(width 0.09525)
		(layer "In11.Cu")
		(net "M_L_CPU1_SA_DQS_DP<8>")
	)
	(arc
		(start 140.163296 -242.539266)
		(mid 140.444728 -242.615021)
		(end 140.72616 -242.539266)
		(width 0.09525)
		(layer "In11.Cu")
		(net "M_L_CPU1_SA_DQS_DP<8>")
	)
	(arc
		(start 138.846306 -242.539266)
		(mid 139.034774 -242.488589)
		(end 139.223242 -242.539266)
		(width 0.09525)
		(layer "In11.Cu")
		(net "M_L_CPU1_SA_DQS_DP<8>")
	)
	(arc
		(start 141.10335 -242.539266)
		(mid 141.384782 -242.615021)
		(end 141.666214 -242.539266)
		(width 0.09525)
		(layer "In11.Cu")
		(net "M_L_CPU1_SA_DQS_DP<8>")
	)
	(arc
		(start 141.674596 -242.53444)
		(mid 141.859628 -242.488526)
		(end 142.043404 -242.539266)
		(width 0.09525)
		(layer "In11.Cu")
		(net "M_L_CPU1_SA_DQS_DP<8>")
	)
	(segment
		(start 137.627868 -238.270288)
		(end 138.09472 -238.00435)
		(width 0.12954)
		(layer "F.Cu")
		(net "M_L_CPU1_SA_DQS_DP<7>")
	)
	(segment
		(start 138.09472 -238.00435)
		(end 137.940796 -237.73892)
		(width 0.09525)
		(layer "In11.Cu")
		(net "M_L_CPU1_SA_DQS_DP<7>")
	)
	(segment
		(start 180.238146 -221.860618)
		(end 180.613304 -221.48546)
		(width 0.16002)
		(layer "In11.Cu")
		(net "M_L_CPU1_SA_DQS_DP<7>")
	)
	(segment
		(start 141.666214 -237.67923)
		(end 141.674596 -237.674404)
		(width 0.09525)
		(layer "In11.Cu")
		(net "M_L_CPU1_SA_DQS_DP<7>")
	)
	(segment
		(start 182.660036 -220.63202)
		(end 183.038496 -221.01048)
		(width 0.16002)
		(layer "In11.Cu")
		(net "M_L_CPU1_SA_DQS_DP<7>")
	)
	(segment
		(start 144.864836 -237.67923)
		(end 144.900904 -237.700058)
		(width 0.09525)
		(layer "In11.Cu")
		(net "M_L_CPU1_SA_DQS_DP<7>")
	)
	(segment
		(start 164.295836 -221.48546)
		(end 166.14648 -221.48546)
		(width 0.16002)
		(layer "In11.Cu")
		(net "M_L_CPU1_SA_DQS_DP<7>")
	)
	(segment
		(start 149.8346 -235.946696)
		(end 157.71241 -228.068886)
		(width 0.16002)
		(layer "In11.Cu")
		(net "M_L_CPU1_SA_DQS_DP<7>")
	)
	(segment
		(start 169.301922 -220.878146)
		(end 170.394376 -220.878146)
		(width 0.16002)
		(layer "In11.Cu")
		(net "M_L_CPU1_SA_DQS_DP<7>")
	)
	(segment
		(start 188.778642 -221.48546)
		(end 189.632082 -220.63202)
		(width 0.16002)
		(layer "In11.Cu")
		(net "M_L_CPU1_SA_DQS_DP<7>")
	)
	(segment
		(start 159.662622 -226.695254)
		(end 160.150048 -226.207828)
		(width 0.16002)
		(layer "In11.Cu")
		(net "M_L_CPU1_SA_DQS_DP<7>")
	)
	(segment
		(start 161.52368 -224.257616)
		(end 161.833306 -223.94799)
		(width 0.16002)
		(layer "In11.Cu")
		(net "M_L_CPU1_SA_DQS_DP<7>")
	)
	(segment
		(start 143.546068 -237.67923)
		(end 143.560546 -237.670848)
		(width 0.09525)
		(layer "In11.Cu")
		(net "M_L_CPU1_SA_DQS_DP<7>")
	)
	(segment
		(start 190.20409 -220.63202)
		(end 190.58255 -221.01048)
		(width 0.16002)
		(layer "In11.Cu")
		(net "M_L_CPU1_SA_DQS_DP<7>")
	)
	(segment
		(start 145.541492 -237.591854)
		(end 145.68297 -237.450376)
		(width 0.09525)
		(layer "In11.Cu")
		(net "M_L_CPU1_SA_DQS_DP<7>")
	)
	(segment
		(start 141.094968 -237.674404)
		(end 141.10335 -237.67923)
		(width 0.09525)
		(layer "In11.Cu")
		(net "M_L_CPU1_SA_DQS_DP<7>")
	)
	(segment
		(start 189.632082 -220.63202)
		(end 190.20409 -220.63202)
		(width 0.16002)
		(layer "In11.Cu")
		(net "M_L_CPU1_SA_DQS_DP<7>")
	)
	(segment
		(start 144.848072 -237.669578)
		(end 144.864836 -237.67923)
		(width 0.09525)
		(layer "In11.Cu")
		(net "M_L_CPU1_SA_DQS_DP<7>")
	)
	(segment
		(start 158.776416 -227.00488)
		(end 159.086042 -226.695254)
		(width 0.16002)
		(layer "In11.Cu")
		(net "M_L_CPU1_SA_DQS_DP<7>")
	)
	(segment
		(start 146.724624 -237.450376)
		(end 147.36826 -236.80674)
		(width 0.09525)
		(layer "In11.Cu")
		(net "M_L_CPU1_SA_DQS_DP<7>")
	)
	(segment
		(start 181.234588 -221.48546)
		(end 182.088028 -220.63202)
		(width 0.16002)
		(layer "In11.Cu")
		(net "M_L_CPU1_SA_DQS_DP<7>")
	)
	(segment
		(start 196.322696 -221.48546)
		(end 197.176136 -220.63202)
		(width 0.16002)
		(layer "In11.Cu")
		(net "M_L_CPU1_SA_DQS_DP<7>")
	)
	(segment
		(start 160.150048 -225.631248)
		(end 160.459674 -225.321622)
		(width 0.16002)
		(layer "In11.Cu")
		(net "M_L_CPU1_SA_DQS_DP<7>")
	)
	(segment
		(start 144.46504 -237.692692)
		(end 144.488408 -237.67923)
		(width 0.09525)
		(layer "In11.Cu")
		(net "M_L_CPU1_SA_DQS_DP<7>")
	)
	(segment
		(start 160.459674 -225.321622)
		(end 161.036254 -225.321622)
		(width 0.16002)
		(layer "In11.Cu")
		(net "M_L_CPU1_SA_DQS_DP<7>")
	)
	(segment
		(start 200.9394 -220.988636)
		(end 201.0664 -220.861636)
		(width 0.16002)
		(layer "In11.Cu")
		(net "M_L_CPU1_SA_DQS_DP<7>")
	)
	(segment
		(start 172.694092 -221.860618)
		(end 173.06925 -221.48546)
		(width 0.16002)
		(layer "In11.Cu")
		(net "M_L_CPU1_SA_DQS_DP<7>")
	)
	(segment
		(start 162.897312 -223.460564)
		(end 162.897312 -222.883984)
		(width 0.16002)
		(layer "In11.Cu")
		(net "M_L_CPU1_SA_DQS_DP<7>")
	)
	(segment
		(start 201.874374 -220.861636)
		(end 202.147932 -221.135194)
		(width 0.16002)
		(layer "In11.Cu")
		(net "M_L_CPU1_SA_DQS_DP<7>")
	)
	(segment
		(start 197.748144 -220.63202)
		(end 198.126604 -221.01048)
		(width 0.16002)
		(layer "In11.Cu")
		(net "M_L_CPU1_SA_DQS_DP<7>")
	)
	(segment
		(start 180.613304 -221.48546)
		(end 181.234588 -221.48546)
		(width 0.16002)
		(layer "In11.Cu")
		(net "M_L_CPU1_SA_DQS_DP<7>")
	)
	(segment
		(start 168.425622 -220.001846)
		(end 169.301922 -220.878146)
		(width 0.16002)
		(layer "In11.Cu")
		(net "M_L_CPU1_SA_DQS_DP<7>")
	)
	(segment
		(start 159.086042 -226.695254)
		(end 159.662622 -226.695254)
		(width 0.16002)
		(layer "In11.Cu")
		(net "M_L_CPU1_SA_DQS_DP<7>")
	)
	(segment
		(start 195.701412 -221.48546)
		(end 196.322696 -221.48546)
		(width 0.16002)
		(layer "In11.Cu")
		(net "M_L_CPU1_SA_DQS_DP<7>")
	)
	(segment
		(start 158.776416 -227.58146)
		(end 158.776416 -227.00488)
		(width 0.16002)
		(layer "In11.Cu")
		(net "M_L_CPU1_SA_DQS_DP<7>")
	)
	(segment
		(start 147.36826 -236.80674)
		(end 147.36826 -236.18698)
		(width 0.09525)
		(layer "In11.Cu")
		(net "M_L_CPU1_SA_DQS_DP<7>")
	)
	(segment
		(start 171.376848 -221.860618)
		(end 172.694092 -221.860618)
		(width 0.16002)
		(layer "In11.Cu")
		(net "M_L_CPU1_SA_DQS_DP<7>")
	)
	(segment
		(start 183.038496 -221.01048)
		(end 185.609738 -221.01048)
		(width 0.16002)
		(layer "In11.Cu")
		(net "M_L_CPU1_SA_DQS_DP<7>")
	)
	(segment
		(start 200.45934 -220.988636)
		(end 200.9394 -220.988636)
		(width 0.16002)
		(layer "In11.Cu")
		(net "M_L_CPU1_SA_DQS_DP<7>")
	)
	(segment
		(start 199.437752 -221.01048)
		(end 199.586596 -220.861636)
		(width 0.16002)
		(layer "In11.Cu")
		(net "M_L_CPU1_SA_DQS_DP<7>")
	)
	(segment
		(start 185.609738 -221.01048)
		(end 186.459876 -221.860618)
		(width 0.16002)
		(layer "In11.Cu")
		(net "M_L_CPU1_SA_DQS_DP<7>")
	)
	(segment
		(start 147.81784 -235.887768)
		(end 147.876768 -235.946696)
		(width 0.09525)
		(layer "In11.Cu")
		(net "M_L_CPU1_SA_DQS_DP<7>")
	)
	(segment
		(start 195.326254 -221.860618)
		(end 195.701412 -221.48546)
		(width 0.16002)
		(layer "In11.Cu")
		(net "M_L_CPU1_SA_DQS_DP<7>")
	)
	(segment
		(start 193.756026 -221.860618)
		(end 195.326254 -221.860618)
		(width 0.16002)
		(layer "In11.Cu")
		(net "M_L_CPU1_SA_DQS_DP<7>")
	)
	(segment
		(start 162.897312 -222.883984)
		(end 164.295836 -221.48546)
		(width 0.16002)
		(layer "In11.Cu")
		(net "M_L_CPU1_SA_DQS_DP<7>")
	)
	(segment
		(start 200.33234 -220.861636)
		(end 200.45934 -220.988636)
		(width 0.16002)
		(layer "In11.Cu")
		(net "M_L_CPU1_SA_DQS_DP<7>")
	)
	(segment
		(start 199.586596 -220.861636)
		(end 200.33234 -220.861636)
		(width 0.16002)
		(layer "In11.Cu")
		(net "M_L_CPU1_SA_DQS_DP<7>")
	)
	(segment
		(start 160.150048 -226.207828)
		(end 160.150048 -225.631248)
		(width 0.16002)
		(layer "In11.Cu")
		(net "M_L_CPU1_SA_DQS_DP<7>")
	)
	(segment
		(start 182.088028 -220.63202)
		(end 182.660036 -220.63202)
		(width 0.16002)
		(layer "In11.Cu")
		(net "M_L_CPU1_SA_DQS_DP<7>")
	)
	(segment
		(start 147.667472 -235.887768)
		(end 147.81784 -235.887768)
		(width 0.09525)
		(layer "In11.Cu")
		(net "M_L_CPU1_SA_DQS_DP<7>")
	)
	(segment
		(start 175.115982 -220.63202)
		(end 175.494442 -221.01048)
		(width 0.16002)
		(layer "In11.Cu")
		(net "M_L_CPU1_SA_DQS_DP<7>")
	)
	(segment
		(start 174.543974 -220.63202)
		(end 175.115982 -220.63202)
		(width 0.16002)
		(layer "In11.Cu")
		(net "M_L_CPU1_SA_DQS_DP<7>")
	)
	(segment
		(start 192.905888 -221.01048)
		(end 193.756026 -221.860618)
		(width 0.16002)
		(layer "In11.Cu")
		(net "M_L_CPU1_SA_DQS_DP<7>")
	)
	(segment
		(start 198.126604 -221.01048)
		(end 199.437752 -221.01048)
		(width 0.16002)
		(layer "In11.Cu")
		(net "M_L_CPU1_SA_DQS_DP<7>")
	)
	(segment
		(start 173.06925 -221.48546)
		(end 173.690534 -221.48546)
		(width 0.16002)
		(layer "In11.Cu")
		(net "M_L_CPU1_SA_DQS_DP<7>")
	)
	(segment
		(start 161.833306 -223.94799)
		(end 162.409886 -223.94799)
		(width 0.16002)
		(layer "In11.Cu")
		(net "M_L_CPU1_SA_DQS_DP<7>")
	)
	(segment
		(start 187.7822 -221.860618)
		(end 188.157358 -221.48546)
		(width 0.16002)
		(layer "In11.Cu")
		(net "M_L_CPU1_SA_DQS_DP<7>")
	)
	(segment
		(start 147.36826 -236.18698)
		(end 147.667472 -235.887768)
		(width 0.09525)
		(layer "In11.Cu")
		(net "M_L_CPU1_SA_DQS_DP<7>")
	)
	(segment
		(start 197.176136 -220.63202)
		(end 197.748144 -220.63202)
		(width 0.16002)
		(layer "In11.Cu")
		(net "M_L_CPU1_SA_DQS_DP<7>")
	)
	(segment
		(start 188.157358 -221.48546)
		(end 188.778642 -221.48546)
		(width 0.16002)
		(layer "In11.Cu")
		(net "M_L_CPU1_SA_DQS_DP<7>")
	)
	(segment
		(start 157.71241 -228.068886)
		(end 158.28899 -228.068886)
		(width 0.16002)
		(layer "In11.Cu")
		(net "M_L_CPU1_SA_DQS_DP<7>")
	)
	(segment
		(start 179.047902 -221.860618)
		(end 180.238146 -221.860618)
		(width 0.16002)
		(layer "In11.Cu")
		(net "M_L_CPU1_SA_DQS_DP<7>")
	)
	(segment
		(start 178.197764 -221.01048)
		(end 179.047902 -221.860618)
		(width 0.16002)
		(layer "In11.Cu")
		(net "M_L_CPU1_SA_DQS_DP<7>")
	)
	(segment
		(start 140.154914 -237.674404)
		(end 140.163296 -237.67923)
		(width 0.09525)
		(layer "In11.Cu")
		(net "M_L_CPU1_SA_DQS_DP<7>")
	)
	(segment
		(start 190.58255 -221.01048)
		(end 192.905888 -221.01048)
		(width 0.16002)
		(layer "In11.Cu")
		(net "M_L_CPU1_SA_DQS_DP<7>")
	)
	(segment
		(start 147.90039 -235.946696)
		(end 149.8346 -235.946696)
		(width 0.16002)
		(layer "In11.Cu")
		(net "M_L_CPU1_SA_DQS_DP<7>")
	)
	(segment
		(start 137.940796 -237.73892)
		(end 137.964164 -237.652052)
		(width 0.09525)
		(layer "In11.Cu")
		(net "M_L_CPU1_SA_DQS_DP<7>")
	)
	(segment
		(start 170.394376 -220.878146)
		(end 171.376848 -221.860618)
		(width 0.16002)
		(layer "In11.Cu")
		(net "M_L_CPU1_SA_DQS_DP<7>")
	)
	(segment
		(start 167.500808 -220.63202)
		(end 168.130982 -220.001846)
		(width 0.16002)
		(layer "In11.Cu")
		(net "M_L_CPU1_SA_DQS_DP<7>")
	)
	(segment
		(start 166.14648 -221.48546)
		(end 166.99992 -220.63202)
		(width 0.16002)
		(layer "In11.Cu")
		(net "M_L_CPU1_SA_DQS_DP<7>")
	)
	(segment
		(start 147.876768 -235.946696)
		(end 147.90039 -235.946696)
		(width 0.09525)
		(layer "In11.Cu")
		(net "M_L_CPU1_SA_DQS_DP<7>")
	)
	(segment
		(start 158.28899 -228.068886)
		(end 158.776416 -227.58146)
		(width 0.16002)
		(layer "In11.Cu")
		(net "M_L_CPU1_SA_DQS_DP<7>")
	)
	(segment
		(start 175.494442 -221.01048)
		(end 178.197764 -221.01048)
		(width 0.16002)
		(layer "In11.Cu")
		(net "M_L_CPU1_SA_DQS_DP<7>")
	)
	(segment
		(start 145.68297 -237.450376)
		(end 146.724624 -237.450376)
		(width 0.09525)
		(layer "In11.Cu")
		(net "M_L_CPU1_SA_DQS_DP<7>")
	)
	(segment
		(start 162.409886 -223.94799)
		(end 162.897312 -223.460564)
		(width 0.16002)
		(layer "In11.Cu")
		(net "M_L_CPU1_SA_DQS_DP<7>")
	)
	(segment
		(start 168.130982 -220.001846)
		(end 168.425622 -220.001846)
		(width 0.16002)
		(layer "In11.Cu")
		(net "M_L_CPU1_SA_DQS_DP<7>")
	)
	(segment
		(start 166.99992 -220.63202)
		(end 167.500808 -220.63202)
		(width 0.16002)
		(layer "In11.Cu")
		(net "M_L_CPU1_SA_DQS_DP<7>")
	)
	(segment
		(start 161.52368 -224.834196)
		(end 161.52368 -224.257616)
		(width 0.16002)
		(layer "In11.Cu")
		(net "M_L_CPU1_SA_DQS_DP<7>")
	)
	(segment
		(start 201.0664 -220.861636)
		(end 201.874374 -220.861636)
		(width 0.16002)
		(layer "In11.Cu")
		(net "M_L_CPU1_SA_DQS_DP<7>")
	)
	(segment
		(start 186.459876 -221.860618)
		(end 187.7822 -221.860618)
		(width 0.16002)
		(layer "In11.Cu")
		(net "M_L_CPU1_SA_DQS_DP<7>")
	)
	(segment
		(start 173.690534 -221.48546)
		(end 174.543974 -220.63202)
		(width 0.16002)
		(layer "In11.Cu")
		(net "M_L_CPU1_SA_DQS_DP<7>")
	)
	(segment
		(start 161.036254 -225.321622)
		(end 161.52368 -224.834196)
		(width 0.16002)
		(layer "In11.Cu")
		(net "M_L_CPU1_SA_DQS_DP<7>")
	)
	(arc
		(start 144.488408 -237.67923)
		(mid 144.667014 -237.628562)
		(end 144.848072 -237.669578)
		(width 0.09525)
		(layer "In11.Cu")
		(net "M_L_CPU1_SA_DQS_DP<7>")
	)
	(arc
		(start 142.606268 -237.67923)
		(mid 142.794736 -237.628553)
		(end 142.983204 -237.67923)
		(width 0.09525)
		(layer "In11.Cu")
		(net "M_L_CPU1_SA_DQS_DP<7>")
	)
	(arc
		(start 145.4277 -237.67923)
		(mid 145.487404 -237.639198)
		(end 145.541492 -237.591854)
		(width 0.09525)
		(layer "In11.Cu")
		(net "M_L_CPU1_SA_DQS_DP<7>")
	)
	(arc
		(start 138.283442 -237.67923)
		(mid 138.564874 -237.754985)
		(end 138.846306 -237.67923)
		(width 0.09525)
		(layer "In11.Cu")
		(net "M_L_CPU1_SA_DQS_DP<7>")
	)
	(arc
		(start 140.72616 -237.67923)
		(mid 140.909935 -237.628458)
		(end 141.094968 -237.674404)
		(width 0.09525)
		(layer "In11.Cu")
		(net "M_L_CPU1_SA_DQS_DP<7>")
	)
	(arc
		(start 141.10335 -237.67923)
		(mid 141.384782 -237.754985)
		(end 141.666214 -237.67923)
		(width 0.09525)
		(layer "In11.Cu")
		(net "M_L_CPU1_SA_DQS_DP<7>")
	)
	(arc
		(start 142.983204 -237.67923)
		(mid 143.264636 -237.754985)
		(end 143.546068 -237.67923)
		(width 0.09525)
		(layer "In11.Cu")
		(net "M_L_CPU1_SA_DQS_DP<7>")
	)
	(arc
		(start 137.964164 -237.652052)
		(mid 138.126846 -237.62992)
		(end 138.283442 -237.67923)
		(width 0.09525)
		(layer "In11.Cu")
		(net "M_L_CPU1_SA_DQS_DP<7>")
	)
	(arc
		(start 143.924274 -237.67923)
		(mid 144.192937 -237.755448)
		(end 144.46504 -237.692692)
		(width 0.09525)
		(layer "In11.Cu")
		(net "M_L_CPU1_SA_DQS_DP<7>")
	)
	(arc
		(start 142.043404 -237.67923)
		(mid 142.324836 -237.754985)
		(end 142.606268 -237.67923)
		(width 0.09525)
		(layer "In11.Cu")
		(net "M_L_CPU1_SA_DQS_DP<7>")
	)
	(arc
		(start 141.674596 -237.674404)
		(mid 141.859628 -237.62849)
		(end 142.043404 -237.67923)
		(width 0.09525)
		(layer "In11.Cu")
		(net "M_L_CPU1_SA_DQS_DP<7>")
	)
	(arc
		(start 140.163296 -237.67923)
		(mid 140.444728 -237.754985)
		(end 140.72616 -237.67923)
		(width 0.09525)
		(layer "In11.Cu")
		(net "M_L_CPU1_SA_DQS_DP<7>")
	)
	(arc
		(start 139.223242 -237.67923)
		(mid 139.504674 -237.754985)
		(end 139.786106 -237.67923)
		(width 0.09525)
		(layer "In11.Cu")
		(net "M_L_CPU1_SA_DQS_DP<7>")
	)
	(arc
		(start 143.560546 -237.670848)
		(mid 143.743486 -237.628173)
		(end 143.924274 -237.67923)
		(width 0.09525)
		(layer "In11.Cu")
		(net "M_L_CPU1_SA_DQS_DP<7>")
	)
	(arc
		(start 144.900904 -237.700058)
		(mid 145.166902 -237.755337)
		(end 145.4277 -237.67923)
		(width 0.09525)
		(layer "In11.Cu")
		(net "M_L_CPU1_SA_DQS_DP<7>")
	)
	(arc
		(start 139.786106 -237.67923)
		(mid 139.969881 -237.628458)
		(end 140.154914 -237.674404)
		(width 0.09525)
		(layer "In11.Cu")
		(net "M_L_CPU1_SA_DQS_DP<7>")
	)
	(arc
		(start 138.846306 -237.67923)
		(mid 139.034774 -237.628553)
		(end 139.223242 -237.67923)
		(width 0.09525)
		(layer "In11.Cu")
		(net "M_L_CPU1_SA_DQS_DP<7>")
	)
	(segment
		(start 137.627868 -233.410252)
		(end 138.09472 -233.144314)
		(width 0.12954)
		(layer "F.Cu")
		(net "M_L_CPU1_SA_DQS_DP<6>")
	)
	(segment
		(start 154.288236 -221.920816)
		(end 154.76474 -221.920816)
		(width 0.16002)
		(layer "In11.Cu")
		(net "M_L_CPU1_SA_DQS_DP<6>")
	)
	(segment
		(start 156.562806 -219.646246)
		(end 156.39923 -219.48267)
		(width 0.16002)
		(layer "In11.Cu")
		(net "M_L_CPU1_SA_DQS_DP<6>")
	)
	(segment
		(start 188.778642 -212.135466)
		(end 189.632082 -211.282026)
		(width 0.16002)
		(layer "In11.Cu")
		(net "M_L_CPU1_SA_DQS_DP<6>")
	)
	(segment
		(start 169.72153 -211.520786)
		(end 170.48099 -211.520786)
		(width 0.16002)
		(layer "In11.Cu")
		(net "M_L_CPU1_SA_DQS_DP<6>")
	)
	(segment
		(start 198.126604 -211.660486)
		(end 199.437752 -211.660486)
		(width 0.16002)
		(layer "In11.Cu")
		(net "M_L_CPU1_SA_DQS_DP<6>")
	)
	(segment
		(start 200.91146 -211.638642)
		(end 201.03846 -211.511642)
		(width 0.16002)
		(layer "In11.Cu")
		(net "M_L_CPU1_SA_DQS_DP<6>")
	)
	(segment
		(start 173.690534 -212.135466)
		(end 174.543974 -211.282026)
		(width 0.16002)
		(layer "In11.Cu")
		(net "M_L_CPU1_SA_DQS_DP<6>")
	)
	(segment
		(start 155.661868 -220.547184)
		(end 156.138372 -220.547184)
		(width 0.16002)
		(layer "In11.Cu")
		(net "M_L_CPU1_SA_DQS_DP<6>")
	)
	(segment
		(start 157.772862 -218.109038)
		(end 157.772862 -217.882978)
		(width 0.16002)
		(layer "In11.Cu")
		(net "M_L_CPU1_SA_DQS_DP<6>")
	)
	(segment
		(start 157.772862 -217.882978)
		(end 163.520374 -212.135466)
		(width 0.16002)
		(layer "In11.Cu")
		(net "M_L_CPU1_SA_DQS_DP<6>")
	)
	(segment
		(start 157.512004 -219.173552)
		(end 157.936438 -218.749118)
		(width 0.16002)
		(layer "In11.Cu")
		(net "M_L_CPU1_SA_DQS_DP<6>")
	)
	(segment
		(start 155.498292 -220.383608)
		(end 155.661868 -220.547184)
		(width 0.16002)
		(layer "In11.Cu")
		(net "M_L_CPU1_SA_DQS_DP<6>")
	)
	(segment
		(start 157.936438 -218.272614)
		(end 157.772862 -218.109038)
		(width 0.16002)
		(layer "In11.Cu")
		(net "M_L_CPU1_SA_DQS_DP<6>")
	)
	(segment
		(start 157.936438 -218.749118)
		(end 157.936438 -218.272614)
		(width 0.16002)
		(layer "In11.Cu")
		(net "M_L_CPU1_SA_DQS_DP<6>")
	)
	(segment
		(start 182.088028 -211.282026)
		(end 182.660036 -211.282026)
		(width 0.16002)
		(layer "In11.Cu")
		(net "M_L_CPU1_SA_DQS_DP<6>")
	)
	(segment
		(start 174.543974 -211.282026)
		(end 175.115982 -211.282026)
		(width 0.16002)
		(layer "In11.Cu")
		(net "M_L_CPU1_SA_DQS_DP<6>")
	)
	(segment
		(start 156.562806 -220.12275)
		(end 156.562806 -219.646246)
		(width 0.16002)
		(layer "In11.Cu")
		(net "M_L_CPU1_SA_DQS_DP<6>")
	)
	(segment
		(start 199.586596 -211.511642)
		(end 200.3044 -211.511642)
		(width 0.16002)
		(layer "In11.Cu")
		(net "M_L_CPU1_SA_DQS_DP<6>")
	)
	(segment
		(start 147.603718 -230.115618)
		(end 147.68703 -230.115618)
		(width 0.09525)
		(layer "In11.Cu")
		(net "M_L_CPU1_SA_DQS_DP<6>")
	)
	(segment
		(start 144.46504 -232.832656)
		(end 144.488408 -232.819194)
		(width 0.09525)
		(layer "In11.Cu")
		(net "M_L_CPU1_SA_DQS_DP<6>")
	)
	(segment
		(start 182.660036 -211.282026)
		(end 183.038496 -211.660486)
		(width 0.16002)
		(layer "In11.Cu")
		(net "M_L_CPU1_SA_DQS_DP<6>")
	)
	(segment
		(start 189.632082 -211.282026)
		(end 190.20409 -211.282026)
		(width 0.16002)
		(layer "In11.Cu")
		(net "M_L_CPU1_SA_DQS_DP<6>")
	)
	(segment
		(start 179.042822 -212.510624)
		(end 180.238146 -212.510624)
		(width 0.16002)
		(layer "In11.Cu")
		(net "M_L_CPU1_SA_DQS_DP<6>")
	)
	(segment
		(start 181.234588 -212.135466)
		(end 182.088028 -211.282026)
		(width 0.16002)
		(layer "In11.Cu")
		(net "M_L_CPU1_SA_DQS_DP<6>")
	)
	(segment
		(start 155.189174 -221.019878)
		(end 155.025598 -220.856302)
		(width 0.16002)
		(layer "In11.Cu")
		(net "M_L_CPU1_SA_DQS_DP<6>")
	)
	(segment
		(start 144.864836 -232.819194)
		(end 144.900904 -232.840022)
		(width 0.09525)
		(layer "In11.Cu")
		(net "M_L_CPU1_SA_DQS_DP<6>")
	)
	(segment
		(start 180.238146 -212.510624)
		(end 180.613304 -212.135466)
		(width 0.16002)
		(layer "In11.Cu")
		(net "M_L_CPU1_SA_DQS_DP<6>")
	)
	(segment
		(start 186.464448 -212.510624)
		(end 187.7822 -212.510624)
		(width 0.16002)
		(layer "In11.Cu")
		(net "M_L_CPU1_SA_DQS_DP<6>")
	)
	(segment
		(start 141.094968 -232.814368)
		(end 141.10335 -232.819194)
		(width 0.09525)
		(layer "In11.Cu")
		(net "M_L_CPU1_SA_DQS_DP<6>")
	)
	(segment
		(start 146.2405 -231.478836)
		(end 147.603718 -230.115618)
		(width 0.09525)
		(layer "In11.Cu")
		(net "M_L_CPU1_SA_DQS_DP<6>")
	)
	(segment
		(start 155.025598 -220.856302)
		(end 155.025598 -220.630242)
		(width 0.16002)
		(layer "In11.Cu")
		(net "M_L_CPU1_SA_DQS_DP<6>")
	)
	(segment
		(start 140.154914 -232.814368)
		(end 140.163296 -232.819194)
		(width 0.09525)
		(layer "In11.Cu")
		(net "M_L_CPU1_SA_DQS_DP<6>")
	)
	(segment
		(start 156.645864 -219.009976)
		(end 156.871924 -219.009976)
		(width 0.16002)
		(layer "In11.Cu")
		(net "M_L_CPU1_SA_DQS_DP<6>")
	)
	(segment
		(start 154.12466 -221.75724)
		(end 154.288236 -221.920816)
		(width 0.16002)
		(layer "In11.Cu")
		(net "M_L_CPU1_SA_DQS_DP<6>")
	)
	(segment
		(start 144.848072 -232.809542)
		(end 144.864836 -232.819194)
		(width 0.09525)
		(layer "In11.Cu")
		(net "M_L_CPU1_SA_DQS_DP<6>")
	)
	(segment
		(start 166.99992 -211.282026)
		(end 167.571928 -211.282026)
		(width 0.16002)
		(layer "In11.Cu")
		(net "M_L_CPU1_SA_DQS_DP<6>")
	)
	(segment
		(start 166.14648 -212.135466)
		(end 166.99992 -211.282026)
		(width 0.16002)
		(layer "In11.Cu")
		(net "M_L_CPU1_SA_DQS_DP<6>")
	)
	(segment
		(start 147.703794 -230.098854)
		(end 147.70354 -230.098854)
		(width 0.16002)
		(layer "In11.Cu")
		(net "M_L_CPU1_SA_DQS_DP<6>")
	)
	(segment
		(start 138.09472 -233.144314)
		(end 137.940796 -232.878884)
		(width 0.09525)
		(layer "In11.Cu")
		(net "M_L_CPU1_SA_DQS_DP<6>")
	)
	(segment
		(start 201.03846 -211.511642)
		(end 201.874374 -211.511642)
		(width 0.16002)
		(layer "In11.Cu")
		(net "M_L_CPU1_SA_DQS_DP<6>")
	)
	(segment
		(start 173.06925 -212.135466)
		(end 173.690534 -212.135466)
		(width 0.16002)
		(layer "In11.Cu")
		(net "M_L_CPU1_SA_DQS_DP<6>")
	)
	(segment
		(start 188.157358 -212.135466)
		(end 188.778642 -212.135466)
		(width 0.16002)
		(layer "In11.Cu")
		(net "M_L_CPU1_SA_DQS_DP<6>")
	)
	(segment
		(start 155.189174 -221.496382)
		(end 155.189174 -221.019878)
		(width 0.16002)
		(layer "In11.Cu")
		(net "M_L_CPU1_SA_DQS_DP<6>")
	)
	(segment
		(start 167.810688 -211.520786)
		(end 169.01033 -211.520786)
		(width 0.16002)
		(layer "In11.Cu")
		(net "M_L_CPU1_SA_DQS_DP<6>")
	)
	(segment
		(start 145.541492 -232.731818)
		(end 145.9484 -232.324656)
		(width 0.09525)
		(layer "In11.Cu")
		(net "M_L_CPU1_SA_DQS_DP<6>")
	)
	(segment
		(start 153.8986 -221.75724)
		(end 154.12466 -221.75724)
		(width 0.16002)
		(layer "In11.Cu")
		(net "M_L_CPU1_SA_DQS_DP<6>")
	)
	(segment
		(start 197.748144 -211.282026)
		(end 198.126604 -211.660486)
		(width 0.16002)
		(layer "In11.Cu")
		(net "M_L_CPU1_SA_DQS_DP<6>")
	)
	(segment
		(start 170.48099 -211.520786)
		(end 171.470828 -212.510624)
		(width 0.16002)
		(layer "In11.Cu")
		(net "M_L_CPU1_SA_DQS_DP<6>")
	)
	(segment
		(start 154.76474 -221.920816)
		(end 155.189174 -221.496382)
		(width 0.16002)
		(layer "In11.Cu")
		(net "M_L_CPU1_SA_DQS_DP<6>")
	)
	(segment
		(start 156.39923 -219.48267)
		(end 156.39923 -219.25661)
		(width 0.16002)
		(layer "In11.Cu")
		(net "M_L_CPU1_SA_DQS_DP<6>")
	)
	(segment
		(start 153.22931 -224.572576)
		(end 153.22931 -222.42653)
		(width 0.16002)
		(layer "In11.Cu")
		(net "M_L_CPU1_SA_DQS_DP<6>")
	)
	(segment
		(start 175.115982 -211.282026)
		(end 175.494442 -211.660486)
		(width 0.16002)
		(layer "In11.Cu")
		(net "M_L_CPU1_SA_DQS_DP<6>")
	)
	(segment
		(start 157.0355 -219.173552)
		(end 157.512004 -219.173552)
		(width 0.16002)
		(layer "In11.Cu")
		(net "M_L_CPU1_SA_DQS_DP<6>")
	)
	(segment
		(start 155.025598 -220.630242)
		(end 155.272232 -220.383608)
		(width 0.16002)
		(layer "In11.Cu")
		(net "M_L_CPU1_SA_DQS_DP<6>")
	)
	(segment
		(start 171.470828 -212.510624)
		(end 172.694092 -212.510624)
		(width 0.16002)
		(layer "In11.Cu")
		(net "M_L_CPU1_SA_DQS_DP<6>")
	)
	(segment
		(start 156.138372 -220.547184)
		(end 156.562806 -220.12275)
		(width 0.16002)
		(layer "In11.Cu")
		(net "M_L_CPU1_SA_DQS_DP<6>")
	)
	(segment
		(start 199.437752 -211.660486)
		(end 199.586596 -211.511642)
		(width 0.16002)
		(layer "In11.Cu")
		(net "M_L_CPU1_SA_DQS_DP<6>")
	)
	(segment
		(start 195.326254 -212.510624)
		(end 195.701412 -212.135466)
		(width 0.16002)
		(layer "In11.Cu")
		(net "M_L_CPU1_SA_DQS_DP<6>")
	)
	(segment
		(start 146.2405 -232.032556)
		(end 146.2405 -231.478836)
		(width 0.09525)
		(layer "In11.Cu")
		(net "M_L_CPU1_SA_DQS_DP<6>")
	)
	(segment
		(start 192.905888 -211.660486)
		(end 193.756026 -212.510624)
		(width 0.16002)
		(layer "In11.Cu")
		(net "M_L_CPU1_SA_DQS_DP<6>")
	)
	(segment
		(start 183.038496 -211.660486)
		(end 185.61431 -211.660486)
		(width 0.16002)
		(layer "In11.Cu")
		(net "M_L_CPU1_SA_DQS_DP<6>")
	)
	(segment
		(start 193.756026 -212.510624)
		(end 195.326254 -212.510624)
		(width 0.16002)
		(layer "In11.Cu")
		(net "M_L_CPU1_SA_DQS_DP<6>")
	)
	(segment
		(start 167.571928 -211.282026)
		(end 167.810688 -211.520786)
		(width 0.16002)
		(layer "In11.Cu")
		(net "M_L_CPU1_SA_DQS_DP<6>")
	)
	(segment
		(start 153.22931 -222.42653)
		(end 153.8986 -221.75724)
		(width 0.16002)
		(layer "In11.Cu")
		(net "M_L_CPU1_SA_DQS_DP<6>")
	)
	(segment
		(start 163.520374 -212.135466)
		(end 166.14648 -212.135466)
		(width 0.16002)
		(layer "In11.Cu")
		(net "M_L_CPU1_SA_DQS_DP<6>")
	)
	(segment
		(start 143.546068 -232.819194)
		(end 143.560546 -232.810812)
		(width 0.09525)
		(layer "In11.Cu")
		(net "M_L_CPU1_SA_DQS_DP<6>")
	)
	(segment
		(start 201.874374 -211.511642)
		(end 202.147932 -211.7852)
		(width 0.16002)
		(layer "In11.Cu")
		(net "M_L_CPU1_SA_DQS_DP<6>")
	)
	(segment
		(start 190.20409 -211.282026)
		(end 190.58255 -211.660486)
		(width 0.16002)
		(layer "In11.Cu")
		(net "M_L_CPU1_SA_DQS_DP<6>")
	)
	(segment
		(start 156.871924 -219.009976)
		(end 157.0355 -219.173552)
		(width 0.16002)
		(layer "In11.Cu")
		(net "M_L_CPU1_SA_DQS_DP<6>")
	)
	(segment
		(start 187.7822 -212.510624)
		(end 188.157358 -212.135466)
		(width 0.16002)
		(layer "In11.Cu")
		(net "M_L_CPU1_SA_DQS_DP<6>")
	)
	(segment
		(start 169.13733 -211.647786)
		(end 169.59453 -211.647786)
		(width 0.16002)
		(layer "In11.Cu")
		(net "M_L_CPU1_SA_DQS_DP<6>")
	)
	(segment
		(start 147.68703 -230.115618)
		(end 147.703794 -230.098854)
		(width 0.09525)
		(layer "In11.Cu")
		(net "M_L_CPU1_SA_DQS_DP<6>")
	)
	(segment
		(start 180.613304 -212.135466)
		(end 181.234588 -212.135466)
		(width 0.16002)
		(layer "In11.Cu")
		(net "M_L_CPU1_SA_DQS_DP<6>")
	)
	(segment
		(start 169.59453 -211.647786)
		(end 169.72153 -211.520786)
		(width 0.16002)
		(layer "In11.Cu")
		(net "M_L_CPU1_SA_DQS_DP<6>")
	)
	(segment
		(start 141.666214 -232.819194)
		(end 141.674596 -232.814368)
		(width 0.09525)
		(layer "In11.Cu")
		(net "M_L_CPU1_SA_DQS_DP<6>")
	)
	(segment
		(start 195.701412 -212.135466)
		(end 196.322696 -212.135466)
		(width 0.16002)
		(layer "In11.Cu")
		(net "M_L_CPU1_SA_DQS_DP<6>")
	)
	(segment
		(start 156.39923 -219.25661)
		(end 156.645864 -219.009976)
		(width 0.16002)
		(layer "In11.Cu")
		(net "M_L_CPU1_SA_DQS_DP<6>")
	)
	(segment
		(start 145.9484 -232.324656)
		(end 146.2405 -232.032556)
		(width 0.09525)
		(layer "In11.Cu")
		(net "M_L_CPU1_SA_DQS_DP<6>")
	)
	(segment
		(start 190.58255 -211.660486)
		(end 192.905888 -211.660486)
		(width 0.16002)
		(layer "In11.Cu")
		(net "M_L_CPU1_SA_DQS_DP<6>")
	)
	(segment
		(start 200.4314 -211.638642)
		(end 200.91146 -211.638642)
		(width 0.16002)
		(layer "In11.Cu")
		(net "M_L_CPU1_SA_DQS_DP<6>")
	)
	(segment
		(start 169.01033 -211.520786)
		(end 169.13733 -211.647786)
		(width 0.16002)
		(layer "In11.Cu")
		(net "M_L_CPU1_SA_DQS_DP<6>")
	)
	(segment
		(start 155.272232 -220.383608)
		(end 155.498292 -220.383608)
		(width 0.16002)
		(layer "In11.Cu")
		(net "M_L_CPU1_SA_DQS_DP<6>")
	)
	(segment
		(start 185.61431 -211.660486)
		(end 186.464448 -212.510624)
		(width 0.16002)
		(layer "In11.Cu")
		(net "M_L_CPU1_SA_DQS_DP<6>")
	)
	(segment
		(start 175.494442 -211.660486)
		(end 178.192684 -211.660486)
		(width 0.16002)
		(layer "In11.Cu")
		(net "M_L_CPU1_SA_DQS_DP<6>")
	)
	(segment
		(start 197.176136 -211.282026)
		(end 197.748144 -211.282026)
		(width 0.16002)
		(layer "In11.Cu")
		(net "M_L_CPU1_SA_DQS_DP<6>")
	)
	(segment
		(start 147.70354 -230.098854)
		(end 153.22931 -224.572576)
		(width 0.16002)
		(layer "In11.Cu")
		(net "M_L_CPU1_SA_DQS_DP<6>")
	)
	(segment
		(start 200.3044 -211.511642)
		(end 200.4314 -211.638642)
		(width 0.16002)
		(layer "In11.Cu")
		(net "M_L_CPU1_SA_DQS_DP<6>")
	)
	(segment
		(start 172.694092 -212.510624)
		(end 173.06925 -212.135466)
		(width 0.16002)
		(layer "In11.Cu")
		(net "M_L_CPU1_SA_DQS_DP<6>")
	)
	(segment
		(start 178.192684 -211.660486)
		(end 179.042822 -212.510624)
		(width 0.16002)
		(layer "In11.Cu")
		(net "M_L_CPU1_SA_DQS_DP<6>")
	)
	(segment
		(start 137.940796 -232.878884)
		(end 137.964164 -232.792016)
		(width 0.09525)
		(layer "In11.Cu")
		(net "M_L_CPU1_SA_DQS_DP<6>")
	)
	(segment
		(start 196.322696 -212.135466)
		(end 197.176136 -211.282026)
		(width 0.16002)
		(layer "In11.Cu")
		(net "M_L_CPU1_SA_DQS_DP<6>")
	)
	(arc
		(start 142.606268 -232.819194)
		(mid 142.794736 -232.768517)
		(end 142.983204 -232.819194)
		(width 0.09525)
		(layer "In11.Cu")
		(net "M_L_CPU1_SA_DQS_DP<6>")
	)
	(arc
		(start 141.674596 -232.814368)
		(mid 141.859628 -232.768454)
		(end 142.043404 -232.819194)
		(width 0.09525)
		(layer "In11.Cu")
		(net "M_L_CPU1_SA_DQS_DP<6>")
	)
	(arc
		(start 144.900904 -232.840022)
		(mid 145.166902 -232.895301)
		(end 145.4277 -232.819194)
		(width 0.09525)
		(layer "In11.Cu")
		(net "M_L_CPU1_SA_DQS_DP<6>")
	)
	(arc
		(start 142.983204 -232.819194)
		(mid 143.264636 -232.894949)
		(end 143.546068 -232.819194)
		(width 0.09525)
		(layer "In11.Cu")
		(net "M_L_CPU1_SA_DQS_DP<6>")
	)
	(arc
		(start 138.283442 -232.819194)
		(mid 138.564874 -232.894949)
		(end 138.846306 -232.819194)
		(width 0.09525)
		(layer "In11.Cu")
		(net "M_L_CPU1_SA_DQS_DP<6>")
	)
	(arc
		(start 145.4277 -232.819194)
		(mid 145.487404 -232.779162)
		(end 145.541492 -232.731818)
		(width 0.09525)
		(layer "In11.Cu")
		(net "M_L_CPU1_SA_DQS_DP<6>")
	)
	(arc
		(start 141.10335 -232.819194)
		(mid 141.384782 -232.894949)
		(end 141.666214 -232.819194)
		(width 0.09525)
		(layer "In11.Cu")
		(net "M_L_CPU1_SA_DQS_DP<6>")
	)
	(arc
		(start 144.488408 -232.819194)
		(mid 144.667014 -232.768526)
		(end 144.848072 -232.809542)
		(width 0.09525)
		(layer "In11.Cu")
		(net "M_L_CPU1_SA_DQS_DP<6>")
	)
	(arc
		(start 140.163296 -232.819194)
		(mid 140.444728 -232.894949)
		(end 140.72616 -232.819194)
		(width 0.09525)
		(layer "In11.Cu")
		(net "M_L_CPU1_SA_DQS_DP<6>")
	)
	(arc
		(start 143.924274 -232.819194)
		(mid 144.192937 -232.895412)
		(end 144.46504 -232.832656)
		(width 0.09525)
		(layer "In11.Cu")
		(net "M_L_CPU1_SA_DQS_DP<6>")
	)
	(arc
		(start 143.560546 -232.810812)
		(mid 143.743486 -232.768137)
		(end 143.924274 -232.819194)
		(width 0.09525)
		(layer "In11.Cu")
		(net "M_L_CPU1_SA_DQS_DP<6>")
	)
	(arc
		(start 139.786106 -232.819194)
		(mid 139.969881 -232.768422)
		(end 140.154914 -232.814368)
		(width 0.09525)
		(layer "In11.Cu")
		(net "M_L_CPU1_SA_DQS_DP<6>")
	)
	(arc
		(start 137.964164 -232.792016)
		(mid 138.126846 -232.769884)
		(end 138.283442 -232.819194)
		(width 0.09525)
		(layer "In11.Cu")
		(net "M_L_CPU1_SA_DQS_DP<6>")
	)
	(arc
		(start 140.72616 -232.819194)
		(mid 140.909935 -232.768422)
		(end 141.094968 -232.814368)
		(width 0.09525)
		(layer "In11.Cu")
		(net "M_L_CPU1_SA_DQS_DP<6>")
	)
	(arc
		(start 142.043404 -232.819194)
		(mid 142.324836 -232.894949)
		(end 142.606268 -232.819194)
		(width 0.09525)
		(layer "In11.Cu")
		(net "M_L_CPU1_SA_DQS_DP<6>")
	)
	(arc
		(start 139.223242 -232.819194)
		(mid 139.504674 -232.894949)
		(end 139.786106 -232.819194)
		(width 0.09525)
		(layer "In11.Cu")
		(net "M_L_CPU1_SA_DQS_DP<6>")
	)
	(arc
		(start 138.846306 -232.819194)
		(mid 139.034774 -232.768517)
		(end 139.223242 -232.819194)
		(width 0.09525)
		(layer "In11.Cu")
		(net "M_L_CPU1_SA_DQS_DP<6>")
	)
	(segment
		(start 137.627868 -228.55047)
		(end 138.09472 -228.284532)
		(width 0.12954)
		(layer "F.Cu")
		(net "M_L_CPU1_SA_DQS_DP<5>")
	)
	(segment
		(start 144.956276 -225.529394)
		(end 144.99717 -225.505772)
		(width 0.09525)
		(layer "In11.Cu")
		(net "M_L_CPU1_SA_DQS_DP<5>")
	)
	(segment
		(start 153.928826 -212.180678)
		(end 153.685494 -211.9376)
		(width 0.16002)
		(layer "In11.Cu")
		(net "M_L_CPU1_SA_DQS_DP<5>")
	)
	(segment
		(start 144.48663 -226.3394)
		(end 144.521682 -226.318826)
		(width 0.09525)
		(layer "In11.Cu")
		(net "M_L_CPU1_SA_DQS_DP<5>")
	)
	(segment
		(start 182.660036 -201.932032)
		(end 183.038496 -202.310492)
		(width 0.16002)
		(layer "In11.Cu")
		(net "M_L_CPU1_SA_DQS_DP<5>")
	)
	(segment
		(start 153.685494 -211.9376)
		(end 153.685494 -211.71154)
		(width 0.16002)
		(layer "In11.Cu")
		(net "M_L_CPU1_SA_DQS_DP<5>")
	)
	(segment
		(start 201.874374 -202.161648)
		(end 202.147932 -202.435206)
		(width 0.16002)
		(layer "In11.Cu")
		(net "M_L_CPU1_SA_DQS_DP<5>")
	)
	(segment
		(start 199.373744 -202.310492)
		(end 199.522588 -202.161648)
		(width 0.16002)
		(layer "In11.Cu")
		(net "M_L_CPU1_SA_DQS_DP<5>")
	)
	(segment
		(start 169.40784 -202.094846)
		(end 170.336464 -202.094846)
		(width 0.16002)
		(layer "In11.Cu")
		(net "M_L_CPU1_SA_DQS_DP<5>")
	)
	(segment
		(start 198.126604 -202.310492)
		(end 199.373744 -202.310492)
		(width 0.16002)
		(layer "In11.Cu")
		(net "M_L_CPU1_SA_DQS_DP<5>")
	)
	(segment
		(start 141.666214 -227.959412)
		(end 141.674596 -227.954586)
		(width 0.09525)
		(layer "In11.Cu")
		(net "M_L_CPU1_SA_DQS_DP<5>")
	)
	(segment
		(start 187.7822 -203.16063)
		(end 188.157358 -202.785472)
		(width 0.16002)
		(layer "In11.Cu")
		(net "M_L_CPU1_SA_DQS_DP<5>")
	)
	(segment
		(start 154.158188 -211.464906)
		(end 154.40152 -211.707984)
		(width 0.16002)
		(layer "In11.Cu")
		(net "M_L_CPU1_SA_DQS_DP<5>")
	)
	(segment
		(start 154.40152 -211.707984)
		(end 154.878024 -211.707984)
		(width 0.16002)
		(layer "In11.Cu")
		(net "M_L_CPU1_SA_DQS_DP<5>")
	)
	(segment
		(start 166.99992 -201.932032)
		(end 167.571928 -201.932032)
		(width 0.16002)
		(layer "In11.Cu")
		(net "M_L_CPU1_SA_DQS_DP<5>")
	)
	(segment
		(start 185.593482 -202.310492)
		(end 186.44362 -203.16063)
		(width 0.16002)
		(layer "In11.Cu")
		(net "M_L_CPU1_SA_DQS_DP<5>")
	)
	(segment
		(start 153.027888 -213.081616)
		(end 153.504392 -213.081616)
		(width 0.16002)
		(layer "In11.Cu")
		(net "M_L_CPU1_SA_DQS_DP<5>")
	)
	(segment
		(start 167.571928 -201.932032)
		(end 167.734742 -202.094846)
		(width 0.16002)
		(layer "In11.Cu")
		(net "M_L_CPU1_SA_DQS_DP<5>")
	)
	(segment
		(start 182.088028 -201.932032)
		(end 182.660036 -201.932032)
		(width 0.16002)
		(layer "In11.Cu")
		(net "M_L_CPU1_SA_DQS_DP<5>")
	)
	(segment
		(start 154.878024 -211.707984)
		(end 155.302458 -211.28355)
		(width 0.16002)
		(layer "In11.Cu")
		(net "M_L_CPU1_SA_DQS_DP<5>")
	)
	(segment
		(start 153.928826 -212.657182)
		(end 153.928826 -212.180678)
		(width 0.16002)
		(layer "In11.Cu")
		(net "M_L_CPU1_SA_DQS_DP<5>")
	)
	(segment
		(start 181.234588 -202.785472)
		(end 182.088028 -201.932032)
		(width 0.16002)
		(layer "In11.Cu")
		(net "M_L_CPU1_SA_DQS_DP<5>")
	)
	(segment
		(start 178.171856 -202.310492)
		(end 179.021994 -203.16063)
		(width 0.16002)
		(layer "In11.Cu")
		(net "M_L_CPU1_SA_DQS_DP<5>")
	)
	(segment
		(start 200.4695 -202.288648)
		(end 200.94956 -202.288648)
		(width 0.16002)
		(layer "In11.Cu")
		(net "M_L_CPU1_SA_DQS_DP<5>")
	)
	(segment
		(start 143.98244 -227.168964)
		(end 144.016222 -227.149406)
		(width 0.09525)
		(layer "In11.Cu")
		(net "M_L_CPU1_SA_DQS_DP<5>")
	)
	(segment
		(start 173.690534 -202.785472)
		(end 174.543974 -201.932032)
		(width 0.16002)
		(layer "In11.Cu")
		(net "M_L_CPU1_SA_DQS_DP<5>")
	)
	(segment
		(start 147.290028 -221.474792)
		(end 147.348956 -221.415864)
		(width 0.09525)
		(layer "In11.Cu")
		(net "M_L_CPU1_SA_DQS_DP<5>")
	)
	(segment
		(start 168.80078 -202.221846)
		(end 169.28084 -202.221846)
		(width 0.16002)
		(layer "In11.Cu")
		(net "M_L_CPU1_SA_DQS_DP<5>")
	)
	(segment
		(start 153.932128 -211.464906)
		(end 154.158188 -211.464906)
		(width 0.16002)
		(layer "In11.Cu")
		(net "M_L_CPU1_SA_DQS_DP<5>")
	)
	(segment
		(start 197.748144 -201.932032)
		(end 198.126604 -202.310492)
		(width 0.16002)
		(layer "In11.Cu")
		(net "M_L_CPU1_SA_DQS_DP<5>")
	)
	(segment
		(start 200.94956 -202.288648)
		(end 201.07656 -202.161648)
		(width 0.16002)
		(layer "In11.Cu")
		(net "M_L_CPU1_SA_DQS_DP<5>")
	)
	(segment
		(start 190.20409 -201.932032)
		(end 190.58255 -202.310492)
		(width 0.16002)
		(layer "In11.Cu")
		(net "M_L_CPU1_SA_DQS_DP<5>")
	)
	(segment
		(start 146.242024 -223.212152)
		(end 147.06854 -222.385382)
		(width 0.09525)
		(layer "In11.Cu")
		(net "M_L_CPU1_SA_DQS_DP<5>")
	)
	(segment
		(start 174.543974 -201.932032)
		(end 175.115982 -201.932032)
		(width 0.16002)
		(layer "In11.Cu")
		(net "M_L_CPU1_SA_DQS_DP<5>")
	)
	(segment
		(start 186.44362 -203.16063)
		(end 187.7822 -203.16063)
		(width 0.16002)
		(layer "In11.Cu")
		(net "M_L_CPU1_SA_DQS_DP<5>")
	)
	(segment
		(start 195.701412 -202.785472)
		(end 196.322696 -202.785472)
		(width 0.16002)
		(layer "In11.Cu")
		(net "M_L_CPU1_SA_DQS_DP<5>")
	)
	(segment
		(start 145.393918 -224.738184)
		(end 145.42643 -224.719388)
		(width 0.09525)
		(layer "In11.Cu")
		(net "M_L_CPU1_SA_DQS_DP<5>")
	)
	(segment
		(start 147.348956 -221.415864)
		(end 147.348956 -221.392242)
		(width 0.09525)
		(layer "In11.Cu")
		(net "M_L_CPU1_SA_DQS_DP<5>")
	)
	(segment
		(start 167.734742 -202.094846)
		(end 168.67378 -202.094846)
		(width 0.16002)
		(layer "In11.Cu")
		(net "M_L_CPU1_SA_DQS_DP<5>")
	)
	(segment
		(start 153.685494 -211.71154)
		(end 153.932128 -211.464906)
		(width 0.16002)
		(layer "In11.Cu")
		(net "M_L_CPU1_SA_DQS_DP<5>")
	)
	(segment
		(start 175.494442 -202.310492)
		(end 178.171856 -202.310492)
		(width 0.16002)
		(layer "In11.Cu")
		(net "M_L_CPU1_SA_DQS_DP<5>")
	)
	(segment
		(start 190.58255 -202.310492)
		(end 192.905888 -202.310492)
		(width 0.16002)
		(layer "In11.Cu")
		(net "M_L_CPU1_SA_DQS_DP<5>")
	)
	(segment
		(start 166.14648 -202.785472)
		(end 166.99992 -201.932032)
		(width 0.16002)
		(layer "In11.Cu")
		(net "M_L_CPU1_SA_DQS_DP<5>")
	)
	(segment
		(start 141.094968 -227.954586)
		(end 141.10335 -227.959412)
		(width 0.09525)
		(layer "In11.Cu")
		(net "M_L_CPU1_SA_DQS_DP<5>")
	)
	(segment
		(start 168.67378 -202.094846)
		(end 168.80078 -202.221846)
		(width 0.16002)
		(layer "In11.Cu")
		(net "M_L_CPU1_SA_DQS_DP<5>")
	)
	(segment
		(start 199.522588 -202.161648)
		(end 200.3425 -202.161648)
		(width 0.16002)
		(layer "In11.Cu")
		(net "M_L_CPU1_SA_DQS_DP<5>")
	)
	(segment
		(start 169.28084 -202.221846)
		(end 169.40784 -202.094846)
		(width 0.16002)
		(layer "In11.Cu")
		(net "M_L_CPU1_SA_DQS_DP<5>")
	)
	(segment
		(start 147.06854 -222.385382)
		(end 147.290028 -222.163894)
		(width 0.09525)
		(layer "In11.Cu")
		(net "M_L_CPU1_SA_DQS_DP<5>")
	)
	(segment
		(start 192.905888 -202.310492)
		(end 193.756026 -203.16063)
		(width 0.16002)
		(layer "In11.Cu")
		(net "M_L_CPU1_SA_DQS_DP<5>")
	)
	(segment
		(start 183.038496 -202.310492)
		(end 185.593482 -202.310492)
		(width 0.16002)
		(layer "In11.Cu")
		(net "M_L_CPU1_SA_DQS_DP<5>")
	)
	(segment
		(start 155.059126 -210.563968)
		(end 155.059126 -210.337908)
		(width 0.16002)
		(layer "In11.Cu")
		(net "M_L_CPU1_SA_DQS_DP<5>")
	)
	(segment
		(start 201.07656 -202.161648)
		(end 201.874374 -202.161648)
		(width 0.16002)
		(layer "In11.Cu")
		(net "M_L_CPU1_SA_DQS_DP<5>")
	)
	(segment
		(start 138.09472 -228.284532)
		(end 137.940796 -228.019102)
		(width 0.09525)
		(layer "In11.Cu")
		(net "M_L_CPU1_SA_DQS_DP<5>")
	)
	(segment
		(start 155.302458 -210.807046)
		(end 155.059126 -210.563968)
		(width 0.16002)
		(layer "In11.Cu")
		(net "M_L_CPU1_SA_DQS_DP<5>")
	)
	(segment
		(start 155.302458 -211.28355)
		(end 155.302458 -210.807046)
		(width 0.16002)
		(layer "In11.Cu")
		(net "M_L_CPU1_SA_DQS_DP<5>")
	)
	(segment
		(start 193.756026 -203.16063)
		(end 195.326254 -203.16063)
		(width 0.16002)
		(layer "In11.Cu")
		(net "M_L_CPU1_SA_DQS_DP<5>")
	)
	(segment
		(start 196.322696 -202.785472)
		(end 197.176136 -201.932032)
		(width 0.16002)
		(layer "In11.Cu")
		(net "M_L_CPU1_SA_DQS_DP<5>")
	)
	(segment
		(start 145.896076 -223.909382)
		(end 145.934176 -223.887284)
		(width 0.09525)
		(layer "In11.Cu")
		(net "M_L_CPU1_SA_DQS_DP<5>")
	)
	(segment
		(start 179.021994 -203.16063)
		(end 180.238146 -203.16063)
		(width 0.16002)
		(layer "In11.Cu")
		(net "M_L_CPU1_SA_DQS_DP<5>")
	)
	(segment
		(start 146.177 -223.424496)
		(end 146.176492 -223.424496)
		(width 0.09525)
		(layer "In11.Cu")
		(net "M_L_CPU1_SA_DQS_DP<5>")
	)
	(segment
		(start 145.86458 -223.92767)
		(end 145.896076 -223.909382)
		(width 0.09525)
		(layer "In11.Cu")
		(net "M_L_CPU1_SA_DQS_DP<5>")
	)
	(segment
		(start 144.92605 -225.54692)
		(end 144.956276 -225.529394)
		(width 0.09525)
		(layer "In11.Cu")
		(net "M_L_CPU1_SA_DQS_DP<5>")
	)
	(segment
		(start 152.784556 -212.838538)
		(end 153.027888 -213.081616)
		(width 0.16002)
		(layer "In11.Cu")
		(net "M_L_CPU1_SA_DQS_DP<5>")
	)
	(segment
		(start 172.694092 -203.16063)
		(end 173.06925 -202.785472)
		(width 0.16002)
		(layer "In11.Cu")
		(net "M_L_CPU1_SA_DQS_DP<5>")
	)
	(segment
		(start 189.632082 -201.932032)
		(end 190.20409 -201.932032)
		(width 0.16002)
		(layer "In11.Cu")
		(net "M_L_CPU1_SA_DQS_DP<5>")
	)
	(segment
		(start 137.940796 -228.019102)
		(end 137.964164 -227.932234)
		(width 0.09525)
		(layer "In11.Cu")
		(net "M_L_CPU1_SA_DQS_DP<5>")
	)
	(segment
		(start 197.176136 -201.932032)
		(end 197.748144 -201.932032)
		(width 0.16002)
		(layer "In11.Cu")
		(net "M_L_CPU1_SA_DQS_DP<5>")
	)
	(segment
		(start 153.504392 -213.081616)
		(end 153.928826 -212.657182)
		(width 0.16002)
		(layer "In11.Cu")
		(net "M_L_CPU1_SA_DQS_DP<5>")
	)
	(segment
		(start 143.546068 -227.959412)
		(end 143.584168 -227.937314)
		(width 0.09525)
		(layer "In11.Cu")
		(net "M_L_CPU1_SA_DQS_DP<5>")
	)
	(segment
		(start 170.336464 -202.094846)
		(end 171.402248 -203.16063)
		(width 0.16002)
		(layer "In11.Cu")
		(net "M_L_CPU1_SA_DQS_DP<5>")
	)
	(segment
		(start 147.290028 -222.163894)
		(end 147.290028 -221.474792)
		(width 0.09525)
		(layer "In11.Cu")
		(net "M_L_CPU1_SA_DQS_DP<5>")
	)
	(segment
		(start 140.154914 -227.954586)
		(end 140.163296 -227.959412)
		(width 0.09525)
		(layer "In11.Cu")
		(net "M_L_CPU1_SA_DQS_DP<5>")
	)
	(segment
		(start 175.115982 -201.932032)
		(end 175.494442 -202.310492)
		(width 0.16002)
		(layer "In11.Cu")
		(net "M_L_CPU1_SA_DQS_DP<5>")
	)
	(segment
		(start 155.059126 -210.337908)
		(end 162.611562 -202.785472)
		(width 0.16002)
		(layer "In11.Cu")
		(net "M_L_CPU1_SA_DQS_DP<5>")
	)
	(segment
		(start 152.558496 -212.838538)
		(end 152.784556 -212.838538)
		(width 0.16002)
		(layer "In11.Cu")
		(net "M_L_CPU1_SA_DQS_DP<5>")
	)
	(segment
		(start 144.451832 -226.359466)
		(end 144.48663 -226.3394)
		(width 0.09525)
		(layer "In11.Cu")
		(net "M_L_CPU1_SA_DQS_DP<5>")
	)
	(segment
		(start 173.06925 -202.785472)
		(end 173.690534 -202.785472)
		(width 0.16002)
		(layer "In11.Cu")
		(net "M_L_CPU1_SA_DQS_DP<5>")
	)
	(segment
		(start 188.778642 -202.785472)
		(end 189.632082 -201.932032)
		(width 0.16002)
		(layer "In11.Cu")
		(net "M_L_CPU1_SA_DQS_DP<5>")
	)
	(segment
		(start 188.157358 -202.785472)
		(end 188.778642 -202.785472)
		(width 0.16002)
		(layer "In11.Cu")
		(net "M_L_CPU1_SA_DQS_DP<5>")
	)
	(segment
		(start 180.613304 -202.785472)
		(end 181.234588 -202.785472)
		(width 0.16002)
		(layer "In11.Cu")
		(net "M_L_CPU1_SA_DQS_DP<5>")
	)
	(segment
		(start 180.238146 -203.16063)
		(end 180.613304 -202.785472)
		(width 0.16002)
		(layer "In11.Cu")
		(net "M_L_CPU1_SA_DQS_DP<5>")
	)
	(segment
		(start 195.326254 -203.16063)
		(end 195.701412 -202.785472)
		(width 0.16002)
		(layer "In11.Cu")
		(net "M_L_CPU1_SA_DQS_DP<5>")
	)
	(segment
		(start 200.3425 -202.161648)
		(end 200.4695 -202.288648)
		(width 0.16002)
		(layer "In11.Cu")
		(net "M_L_CPU1_SA_DQS_DP<5>")
	)
	(segment
		(start 162.611562 -202.785472)
		(end 166.14648 -202.785472)
		(width 0.16002)
		(layer "In11.Cu")
		(net "M_L_CPU1_SA_DQS_DP<5>")
	)
	(segment
		(start 147.348956 -221.392242)
		(end 147.348956 -218.048078)
		(width 0.16002)
		(layer "In11.Cu")
		(net "M_L_CPU1_SA_DQS_DP<5>")
	)
	(segment
		(start 145.42643 -224.719388)
		(end 145.463006 -224.698052)
		(width 0.09525)
		(layer "In11.Cu")
		(net "M_L_CPU1_SA_DQS_DP<5>")
	)
	(segment
		(start 147.348956 -218.048078)
		(end 152.558496 -212.838538)
		(width 0.16002)
		(layer "In11.Cu")
		(net "M_L_CPU1_SA_DQS_DP<5>")
	)
	(segment
		(start 171.402248 -203.16063)
		(end 172.694092 -203.16063)
		(width 0.16002)
		(layer "In11.Cu")
		(net "M_L_CPU1_SA_DQS_DP<5>")
	)
	(segment
		(start 144.016222 -227.149406)
		(end 144.054322 -227.127308)
		(width 0.09525)
		(layer "In11.Cu")
		(net "M_L_CPU1_SA_DQS_DP<5>")
	)
	(arc
		(start 143.584168 -227.937314)
		(mid 143.762618 -227.735844)
		(end 143.826992 -227.474526)
		(width 0.09525)
		(layer "In11.Cu")
		(net "M_L_CPU1_SA_DQS_DP<5>")
	)
	(arc
		(start 145.7071 -224.234502)
		(mid 145.748765 -224.062055)
		(end 145.86458 -223.92767)
		(width 0.09525)
		(layer "In11.Cu")
		(net "M_L_CPU1_SA_DQS_DP<5>")
	)
	(arc
		(start 144.521682 -226.318826)
		(mid 144.702073 -226.117127)
		(end 144.7673 -225.854514)
		(width 0.09525)
		(layer "In11.Cu")
		(net "M_L_CPU1_SA_DQS_DP<5>")
	)
	(arc
		(start 142.983204 -227.959412)
		(mid 143.264636 -228.035167)
		(end 143.546068 -227.959412)
		(width 0.09525)
		(layer "In11.Cu")
		(net "M_L_CPU1_SA_DQS_DP<5>")
	)
	(arc
		(start 144.7673 -225.854514)
		(mid 144.809322 -225.681435)
		(end 144.92605 -225.54692)
		(width 0.09525)
		(layer "In11.Cu")
		(net "M_L_CPU1_SA_DQS_DP<5>")
	)
	(arc
		(start 140.72616 -227.959412)
		(mid 140.909935 -227.90864)
		(end 141.094968 -227.954586)
		(width 0.09525)
		(layer "In11.Cu")
		(net "M_L_CPU1_SA_DQS_DP<5>")
	)
	(arc
		(start 145.237454 -225.044508)
		(mid 145.278826 -224.872512)
		(end 145.393918 -224.738184)
		(width 0.09525)
		(layer "In11.Cu")
		(net "M_L_CPU1_SA_DQS_DP<5>")
	)
	(arc
		(start 137.964164 -227.932234)
		(mid 138.126846 -227.910102)
		(end 138.283442 -227.959412)
		(width 0.09525)
		(layer "In11.Cu")
		(net "M_L_CPU1_SA_DQS_DP<5>")
	)
	(arc
		(start 142.043404 -227.959412)
		(mid 142.324836 -228.035167)
		(end 142.606268 -227.959412)
		(width 0.09525)
		(layer "In11.Cu")
		(net "M_L_CPU1_SA_DQS_DP<5>")
	)
	(arc
		(start 145.934176 -223.887284)
		(mid 146.112626 -223.685814)
		(end 146.177 -223.424496)
		(width 0.09525)
		(layer "In11.Cu")
		(net "M_L_CPU1_SA_DQS_DP<5>")
	)
	(arc
		(start 140.163296 -227.959412)
		(mid 140.444728 -228.035167)
		(end 140.72616 -227.959412)
		(width 0.09525)
		(layer "In11.Cu")
		(net "M_L_CPU1_SA_DQS_DP<5>")
	)
	(arc
		(start 141.10335 -227.959412)
		(mid 141.384782 -228.035167)
		(end 141.666214 -227.959412)
		(width 0.09525)
		(layer "In11.Cu")
		(net "M_L_CPU1_SA_DQS_DP<5>")
	)
	(arc
		(start 146.176492 -223.424496)
		(mid 146.19333 -223.313412)
		(end 146.242024 -223.212152)
		(width 0.09525)
		(layer "In11.Cu")
		(net "M_L_CPU1_SA_DQS_DP<5>")
	)
	(arc
		(start 145.463006 -224.698052)
		(mid 145.642378 -224.496457)
		(end 145.7071 -224.234502)
		(width 0.09525)
		(layer "In11.Cu")
		(net "M_L_CPU1_SA_DQS_DP<5>")
	)
	(arc
		(start 138.283442 -227.959412)
		(mid 138.564874 -228.035167)
		(end 138.846306 -227.959412)
		(width 0.09525)
		(layer "In11.Cu")
		(net "M_L_CPU1_SA_DQS_DP<5>")
	)
	(arc
		(start 139.786106 -227.959412)
		(mid 139.969881 -227.90864)
		(end 140.154914 -227.954586)
		(width 0.09525)
		(layer "In11.Cu")
		(net "M_L_CPU1_SA_DQS_DP<5>")
	)
	(arc
		(start 141.674596 -227.954586)
		(mid 141.859628 -227.908672)
		(end 142.043404 -227.959412)
		(width 0.09525)
		(layer "In11.Cu")
		(net "M_L_CPU1_SA_DQS_DP<5>")
	)
	(arc
		(start 139.223242 -227.959412)
		(mid 139.504674 -228.035167)
		(end 139.786106 -227.959412)
		(width 0.09525)
		(layer "In11.Cu")
		(net "M_L_CPU1_SA_DQS_DP<5>")
	)
	(arc
		(start 144.054322 -227.127308)
		(mid 144.232772 -226.925838)
		(end 144.297146 -226.66452)
		(width 0.09525)
		(layer "In11.Cu")
		(net "M_L_CPU1_SA_DQS_DP<5>")
	)
	(arc
		(start 142.606268 -227.959412)
		(mid 142.794736 -227.908735)
		(end 142.983204 -227.959412)
		(width 0.09525)
		(layer "In11.Cu")
		(net "M_L_CPU1_SA_DQS_DP<5>")
	)
	(arc
		(start 144.99717 -225.505772)
		(mid 145.173786 -225.304558)
		(end 145.237454 -225.044508)
		(width 0.09525)
		(layer "In11.Cu")
		(net "M_L_CPU1_SA_DQS_DP<5>")
	)
	(arc
		(start 144.297146 -226.66452)
		(mid 144.338022 -226.493498)
		(end 144.451832 -226.359466)
		(width 0.09525)
		(layer "In11.Cu")
		(net "M_L_CPU1_SA_DQS_DP<5>")
	)
	(arc
		(start 138.846306 -227.959412)
		(mid 139.034774 -227.908735)
		(end 139.223242 -227.959412)
		(width 0.09525)
		(layer "In11.Cu")
		(net "M_L_CPU1_SA_DQS_DP<5>")
	)
	(arc
		(start 143.826992 -227.474526)
		(mid 143.868094 -227.30312)
		(end 143.98244 -227.168964)
		(width 0.09525)
		(layer "In11.Cu")
		(net "M_L_CPU1_SA_DQS_DP<5>")
	)
	(segment
		(start 138.567922 -246.370348)
		(end 139.034774 -246.10441)
		(width 0.12954)
		(layer "F.Cu")
		(net "M_L_CPU1_SA_DQS_DP<4>")
	)
	(segment
		(start 180.422042 -238.587788)
		(end 181.145942 -238.587788)
		(width 0.16002)
		(layer "In11.Cu")
		(net "M_L_CPU1_SA_DQS_DP<4>")
	)
	(segment
		(start 147.701 -246.677434)
		(end 147.724622 -246.677434)
		(width 0.09525)
		(layer "In11.Cu")
		(net "M_L_CPU1_SA_DQS_DP<4>")
	)
	(segment
		(start 180.094382 -238.260128)
		(end 180.422042 -238.587788)
		(width 0.16002)
		(layer "In11.Cu")
		(net "M_L_CPU1_SA_DQS_DP<4>")
	)
	(segment
		(start 187.638436 -238.260128)
		(end 187.966096 -238.587788)
		(width 0.16002)
		(layer "In11.Cu")
		(net "M_L_CPU1_SA_DQS_DP<4>")
	)
	(segment
		(start 199.732646 -237.410244)
		(end 200.306686 -237.984284)
		(width 0.16002)
		(layer "In11.Cu")
		(net "M_L_CPU1_SA_DQS_DP<4>")
	)
	(segment
		(start 203.761594 -238.603028)
		(end 203.955396 -238.409226)
		(width 0.16002)
		(layer "In11.Cu")
		(net "M_L_CPU1_SA_DQS_DP<4>")
	)
	(segment
		(start 147.641818 -246.736616)
		(end 147.701 -246.677434)
		(width 0.09525)
		(layer "In11.Cu")
		(net "M_L_CPU1_SA_DQS_DP<4>")
	)
	(segment
		(start 145.849594 -246.35333)
		(end 146.23288 -246.736616)
		(width 0.09525)
		(layer "In11.Cu")
		(net "M_L_CPU1_SA_DQS_DP<4>")
	)
	(segment
		(start 173.601888 -238.587788)
		(end 174.424848 -237.764828)
		(width 0.16002)
		(layer "In11.Cu")
		(net "M_L_CPU1_SA_DQS_DP<4>")
	)
	(segment
		(start 165.760908 -239.879886)
		(end 167.875966 -237.764828)
		(width 0.16002)
		(layer "In11.Cu")
		(net "M_L_CPU1_SA_DQS_DP<4>")
	)
	(segment
		(start 147.724622 -246.677434)
		(end 147.950936 -246.677434)
		(width 0.16002)
		(layer "In11.Cu")
		(net "M_L_CPU1_SA_DQS_DP<4>")
	)
	(segment
		(start 193.038476 -238.260128)
		(end 195.18249 -238.260128)
		(width 0.16002)
		(layer "In11.Cu")
		(net "M_L_CPU1_SA_DQS_DP<4>")
	)
	(segment
		(start 200.306686 -237.984284)
		(end 202.728322 -237.984284)
		(width 0.16002)
		(layer "In11.Cu")
		(net "M_L_CPU1_SA_DQS_DP<4>")
	)
	(segment
		(start 139.188698 -246.36984)
		(end 139.289536 -246.39651)
		(width 0.09525)
		(layer "In11.Cu")
		(net "M_L_CPU1_SA_DQS_DP<4>")
	)
	(segment
		(start 189.924436 -237.764828)
		(end 190.27902 -237.410244)
		(width 0.16002)
		(layer "In11.Cu")
		(net "M_L_CPU1_SA_DQS_DP<4>")
	)
	(segment
		(start 172.877988 -238.587788)
		(end 173.601888 -238.587788)
		(width 0.16002)
		(layer "In11.Cu")
		(net "M_L_CPU1_SA_DQS_DP<4>")
	)
	(segment
		(start 175.190912 -237.410244)
		(end 177.100484 -237.410244)
		(width 0.16002)
		(layer "In11.Cu")
		(net "M_L_CPU1_SA_DQS_DP<4>")
	)
	(segment
		(start 164.104574 -239.879886)
		(end 165.760908 -239.879886)
		(width 0.16002)
		(layer "In11.Cu")
		(net "M_L_CPU1_SA_DQS_DP<4>")
	)
	(segment
		(start 145.144744 -246.35333)
		(end 145.849594 -246.35333)
		(width 0.09525)
		(layer "In11.Cu")
		(net "M_L_CPU1_SA_DQS_DP<4>")
	)
	(segment
		(start 187.966096 -238.587788)
		(end 188.689996 -238.587788)
		(width 0.16002)
		(layer "In11.Cu")
		(net "M_L_CPU1_SA_DQS_DP<4>")
	)
	(segment
		(start 157.978094 -246.006366)
		(end 164.104574 -239.879886)
		(width 0.16002)
		(layer "In11.Cu")
		(net "M_L_CPU1_SA_DQS_DP<4>")
	)
	(segment
		(start 146.23288 -246.736616)
		(end 147.641818 -246.736616)
		(width 0.09525)
		(layer "In11.Cu")
		(net "M_L_CPU1_SA_DQS_DP<4>")
	)
	(segment
		(start 144.485106 -246.42953)
		(end 144.497044 -246.436388)
		(width 0.09525)
		(layer "In11.Cu")
		(net "M_L_CPU1_SA_DQS_DP<4>")
	)
	(segment
		(start 202.728322 -237.984284)
		(end 203.347066 -238.603028)
		(width 0.16002)
		(layer "In11.Cu")
		(net "M_L_CPU1_SA_DQS_DP<4>")
	)
	(segment
		(start 190.27902 -237.410244)
		(end 192.188592 -237.410244)
		(width 0.16002)
		(layer "In11.Cu")
		(net "M_L_CPU1_SA_DQS_DP<4>")
	)
	(segment
		(start 172.550328 -238.260128)
		(end 172.877988 -238.587788)
		(width 0.16002)
		(layer "In11.Cu")
		(net "M_L_CPU1_SA_DQS_DP<4>")
	)
	(segment
		(start 184.644538 -237.410244)
		(end 185.494422 -238.260128)
		(width 0.16002)
		(layer "In11.Cu")
		(net "M_L_CPU1_SA_DQS_DP<4>")
	)
	(segment
		(start 197.46849 -237.764828)
		(end 197.823074 -237.410244)
		(width 0.16002)
		(layer "In11.Cu")
		(net "M_L_CPU1_SA_DQS_DP<4>")
	)
	(segment
		(start 182.734966 -237.410244)
		(end 184.644538 -237.410244)
		(width 0.16002)
		(layer "In11.Cu")
		(net "M_L_CPU1_SA_DQS_DP<4>")
	)
	(segment
		(start 189.512956 -237.764828)
		(end 189.924436 -237.764828)
		(width 0.16002)
		(layer "In11.Cu")
		(net "M_L_CPU1_SA_DQS_DP<4>")
	)
	(segment
		(start 143.911066 -246.436388)
		(end 143.923004 -246.42953)
		(width 0.09525)
		(layer "In11.Cu")
		(net "M_L_CPU1_SA_DQS_DP<4>")
	)
	(segment
		(start 181.145942 -238.587788)
		(end 181.968902 -237.764828)
		(width 0.16002)
		(layer "In11.Cu")
		(net "M_L_CPU1_SA_DQS_DP<4>")
	)
	(segment
		(start 143.923004 -246.42953)
		(end 143.941038 -246.419116)
		(width 0.09525)
		(layer "In11.Cu")
		(net "M_L_CPU1_SA_DQS_DP<4>")
	)
	(segment
		(start 141.094968 -246.434356)
		(end 141.10335 -246.42953)
		(width 0.09525)
		(layer "In11.Cu")
		(net "M_L_CPU1_SA_DQS_DP<4>")
	)
	(segment
		(start 203.347066 -238.603028)
		(end 203.761594 -238.603028)
		(width 0.16002)
		(layer "In11.Cu")
		(net "M_L_CPU1_SA_DQS_DP<4>")
	)
	(segment
		(start 169.911014 -237.764828)
		(end 170.406314 -238.260128)
		(width 0.16002)
		(layer "In11.Cu")
		(net "M_L_CPU1_SA_DQS_DP<4>")
	)
	(segment
		(start 167.875966 -237.764828)
		(end 169.911014 -237.764828)
		(width 0.16002)
		(layer "In11.Cu")
		(net "M_L_CPU1_SA_DQS_DP<4>")
	)
	(segment
		(start 197.05701 -237.764828)
		(end 197.46849 -237.764828)
		(width 0.16002)
		(layer "In11.Cu")
		(net "M_L_CPU1_SA_DQS_DP<4>")
	)
	(segment
		(start 196.23405 -238.587788)
		(end 197.05701 -237.764828)
		(width 0.16002)
		(layer "In11.Cu")
		(net "M_L_CPU1_SA_DQS_DP<4>")
	)
	(segment
		(start 147.950936 -246.677434)
		(end 148.622004 -246.006366)
		(width 0.16002)
		(layer "In11.Cu")
		(net "M_L_CPU1_SA_DQS_DP<4>")
	)
	(segment
		(start 177.100484 -237.410244)
		(end 177.950368 -238.260128)
		(width 0.16002)
		(layer "In11.Cu")
		(net "M_L_CPU1_SA_DQS_DP<4>")
	)
	(segment
		(start 205.974188 -238.409226)
		(end 206.248 -238.135414)
		(width 0.16002)
		(layer "In11.Cu")
		(net "M_L_CPU1_SA_DQS_DP<4>")
	)
	(segment
		(start 182.380382 -237.764828)
		(end 182.734966 -237.410244)
		(width 0.16002)
		(layer "In11.Cu")
		(net "M_L_CPU1_SA_DQS_DP<4>")
	)
	(segment
		(start 188.689996 -238.587788)
		(end 189.512956 -237.764828)
		(width 0.16002)
		(layer "In11.Cu")
		(net "M_L_CPU1_SA_DQS_DP<4>")
	)
	(segment
		(start 192.188592 -237.410244)
		(end 193.038476 -238.260128)
		(width 0.16002)
		(layer "In11.Cu")
		(net "M_L_CPU1_SA_DQS_DP<4>")
	)
	(segment
		(start 197.823074 -237.410244)
		(end 199.732646 -237.410244)
		(width 0.16002)
		(layer "In11.Cu")
		(net "M_L_CPU1_SA_DQS_DP<4>")
	)
	(segment
		(start 174.424848 -237.764828)
		(end 174.836328 -237.764828)
		(width 0.16002)
		(layer "In11.Cu")
		(net "M_L_CPU1_SA_DQS_DP<4>")
	)
	(segment
		(start 141.666214 -246.42953)
		(end 141.674596 -246.434356)
		(width 0.09525)
		(layer "In11.Cu")
		(net "M_L_CPU1_SA_DQS_DP<4>")
	)
	(segment
		(start 177.950368 -238.260128)
		(end 180.094382 -238.260128)
		(width 0.16002)
		(layer "In11.Cu")
		(net "M_L_CPU1_SA_DQS_DP<4>")
	)
	(segment
		(start 195.18249 -238.260128)
		(end 195.51015 -238.587788)
		(width 0.16002)
		(layer "In11.Cu")
		(net "M_L_CPU1_SA_DQS_DP<4>")
	)
	(segment
		(start 140.154914 -246.434356)
		(end 140.163296 -246.42953)
		(width 0.09525)
		(layer "In11.Cu")
		(net "M_L_CPU1_SA_DQS_DP<4>")
	)
	(segment
		(start 148.622004 -246.006366)
		(end 157.978094 -246.006366)
		(width 0.16002)
		(layer "In11.Cu")
		(net "M_L_CPU1_SA_DQS_DP<4>")
	)
	(segment
		(start 174.836328 -237.764828)
		(end 175.190912 -237.410244)
		(width 0.16002)
		(layer "In11.Cu")
		(net "M_L_CPU1_SA_DQS_DP<4>")
	)
	(segment
		(start 195.51015 -238.587788)
		(end 196.23405 -238.587788)
		(width 0.16002)
		(layer "In11.Cu")
		(net "M_L_CPU1_SA_DQS_DP<4>")
	)
	(segment
		(start 203.955396 -238.409226)
		(end 205.974188 -238.409226)
		(width 0.16002)
		(layer "In11.Cu")
		(net "M_L_CPU1_SA_DQS_DP<4>")
	)
	(segment
		(start 185.494422 -238.260128)
		(end 187.638436 -238.260128)
		(width 0.16002)
		(layer "In11.Cu")
		(net "M_L_CPU1_SA_DQS_DP<4>")
	)
	(segment
		(start 139.034774 -246.10441)
		(end 139.188698 -246.36984)
		(width 0.09525)
		(layer "In11.Cu")
		(net "M_L_CPU1_SA_DQS_DP<4>")
	)
	(segment
		(start 170.406314 -238.260128)
		(end 172.550328 -238.260128)
		(width 0.16002)
		(layer "In11.Cu")
		(net "M_L_CPU1_SA_DQS_DP<4>")
	)
	(segment
		(start 181.968902 -237.764828)
		(end 182.380382 -237.764828)
		(width 0.16002)
		(layer "In11.Cu")
		(net "M_L_CPU1_SA_DQS_DP<4>")
	)
	(arc
		(start 142.043404 -246.42953)
		(mid 142.324836 -246.353775)
		(end 142.606268 -246.42953)
		(width 0.09525)
		(layer "In11.Cu")
		(net "M_L_CPU1_SA_DQS_DP<4>")
	)
	(arc
		(start 144.86255 -246.42953)
		(mid 144.998602 -246.372761)
		(end 145.144744 -246.35333)
		(width 0.09525)
		(layer "In11.Cu")
		(net "M_L_CPU1_SA_DQS_DP<4>")
	)
	(arc
		(start 143.546068 -246.42953)
		(mid 143.727684 -246.480267)
		(end 143.911066 -246.436388)
		(width 0.09525)
		(layer "In11.Cu")
		(net "M_L_CPU1_SA_DQS_DP<4>")
	)
	(arc
		(start 142.983204 -246.42953)
		(mid 143.264636 -246.353775)
		(end 143.546068 -246.42953)
		(width 0.09525)
		(layer "In11.Cu")
		(net "M_L_CPU1_SA_DQS_DP<4>")
	)
	(arc
		(start 139.289536 -246.39651)
		(mid 139.541677 -246.35494)
		(end 139.786106 -246.42953)
		(width 0.09525)
		(layer "In11.Cu")
		(net "M_L_CPU1_SA_DQS_DP<4>")
	)
	(arc
		(start 141.10335 -246.42953)
		(mid 141.384782 -246.353775)
		(end 141.666214 -246.42953)
		(width 0.09525)
		(layer "In11.Cu")
		(net "M_L_CPU1_SA_DQS_DP<4>")
	)
	(arc
		(start 140.163296 -246.42953)
		(mid 140.444728 -246.353775)
		(end 140.72616 -246.42953)
		(width 0.09525)
		(layer "In11.Cu")
		(net "M_L_CPU1_SA_DQS_DP<4>")
	)
	(arc
		(start 142.606268 -246.42953)
		(mid 142.794736 -246.480207)
		(end 142.983204 -246.42953)
		(width 0.09525)
		(layer "In11.Cu")
		(net "M_L_CPU1_SA_DQS_DP<4>")
	)
	(arc
		(start 144.497044 -246.436388)
		(mid 144.680679 -246.480338)
		(end 144.86255 -246.42953)
		(width 0.09525)
		(layer "In11.Cu")
		(net "M_L_CPU1_SA_DQS_DP<4>")
	)
	(arc
		(start 143.941038 -246.419116)
		(mid 144.214418 -246.353895)
		(end 144.485106 -246.42953)
		(width 0.09525)
		(layer "In11.Cu")
		(net "M_L_CPU1_SA_DQS_DP<4>")
	)
	(arc
		(start 141.674596 -246.434356)
		(mid 141.859628 -246.48027)
		(end 142.043404 -246.42953)
		(width 0.09525)
		(layer "In11.Cu")
		(net "M_L_CPU1_SA_DQS_DP<4>")
	)
	(arc
		(start 139.786106 -246.42953)
		(mid 139.969881 -246.480302)
		(end 140.154914 -246.434356)
		(width 0.09525)
		(layer "In11.Cu")
		(net "M_L_CPU1_SA_DQS_DP<4>")
	)
	(arc
		(start 140.72616 -246.42953)
		(mid 140.909935 -246.480302)
		(end 141.094968 -246.434356)
		(width 0.09525)
		(layer "In11.Cu")
		(net "M_L_CPU1_SA_DQS_DP<4>")
	)
	(segment
		(start 138.567922 -241.510312)
		(end 139.034774 -241.244374)
		(width 0.12954)
		(layer "F.Cu")
		(net "M_L_CPU1_SA_DQS_DP<3>")
	)
	(segment
		(start 140.154914 -241.57432)
		(end 140.163296 -241.569494)
		(width 0.09525)
		(layer "In11.Cu")
		(net "M_L_CPU1_SA_DQS_DP<3>")
	)
	(segment
		(start 200.306686 -228.63429)
		(end 202.728322 -228.63429)
		(width 0.16002)
		(layer "In11.Cu")
		(net "M_L_CPU1_SA_DQS_DP<3>")
	)
	(segment
		(start 139.188698 -241.509804)
		(end 139.289536 -241.536474)
		(width 0.09525)
		(layer "In11.Cu")
		(net "M_L_CPU1_SA_DQS_DP<3>")
	)
	(segment
		(start 193.038476 -228.910134)
		(end 195.18249 -228.910134)
		(width 0.16002)
		(layer "In11.Cu")
		(net "M_L_CPU1_SA_DQS_DP<3>")
	)
	(segment
		(start 173.601888 -229.237794)
		(end 174.424848 -228.414834)
		(width 0.16002)
		(layer "In11.Cu")
		(net "M_L_CPU1_SA_DQS_DP<3>")
	)
	(segment
		(start 143.911066 -241.576352)
		(end 143.923004 -241.569494)
		(width 0.09525)
		(layer "In11.Cu")
		(net "M_L_CPU1_SA_DQS_DP<3>")
	)
	(segment
		(start 205.974188 -229.059232)
		(end 206.248 -228.78542)
		(width 0.16002)
		(layer "In11.Cu")
		(net "M_L_CPU1_SA_DQS_DP<3>")
	)
	(segment
		(start 167.646858 -228.06025)
		(end 169.55643 -228.06025)
		(width 0.16002)
		(layer "In11.Cu")
		(net "M_L_CPU1_SA_DQS_DP<3>")
	)
	(segment
		(start 145.425414 -241.569494)
		(end 145.437352 -241.576352)
		(width 0.09525)
		(layer "In11.Cu")
		(net "M_L_CPU1_SA_DQS_DP<3>")
	)
	(segment
		(start 141.666214 -241.569494)
		(end 141.674596 -241.57432)
		(width 0.09525)
		(layer "In11.Cu")
		(net "M_L_CPU1_SA_DQS_DP<3>")
	)
	(segment
		(start 147.55622 -240.470436)
		(end 147.836382 -240.470436)
		(width 0.09525)
		(layer "In11.Cu")
		(net "M_L_CPU1_SA_DQS_DP<3>")
	)
	(segment
		(start 182.380382 -228.414834)
		(end 182.734966 -228.06025)
		(width 0.16002)
		(layer "In11.Cu")
		(net "M_L_CPU1_SA_DQS_DP<3>")
	)
	(segment
		(start 190.27902 -228.06025)
		(end 192.188592 -228.06025)
		(width 0.16002)
		(layer "In11.Cu")
		(net "M_L_CPU1_SA_DQS_DP<3>")
	)
	(segment
		(start 197.05701 -228.414834)
		(end 197.46849 -228.414834)
		(width 0.16002)
		(layer "In11.Cu")
		(net "M_L_CPU1_SA_DQS_DP<3>")
	)
	(segment
		(start 185.494422 -228.910134)
		(end 187.638436 -228.910134)
		(width 0.16002)
		(layer "In11.Cu")
		(net "M_L_CPU1_SA_DQS_DP<3>")
	)
	(segment
		(start 145.400014 -241.554762)
		(end 145.425414 -241.569494)
		(width 0.09525)
		(layer "In11.Cu")
		(net "M_L_CPU1_SA_DQS_DP<3>")
	)
	(segment
		(start 199.732646 -228.06025)
		(end 200.306686 -228.63429)
		(width 0.16002)
		(layer "In11.Cu")
		(net "M_L_CPU1_SA_DQS_DP<3>")
	)
	(segment
		(start 172.550328 -228.910134)
		(end 172.877988 -229.237794)
		(width 0.16002)
		(layer "In11.Cu")
		(net "M_L_CPU1_SA_DQS_DP<3>")
	)
	(segment
		(start 181.968902 -228.414834)
		(end 182.380382 -228.414834)
		(width 0.16002)
		(layer "In11.Cu")
		(net "M_L_CPU1_SA_DQS_DP<3>")
	)
	(segment
		(start 147.919186 -240.411254)
		(end 153.277824 -240.411254)
		(width 0.16002)
		(layer "In11.Cu")
		(net "M_L_CPU1_SA_DQS_DP<3>")
	)
	(segment
		(start 203.347066 -229.253034)
		(end 203.761594 -229.253034)
		(width 0.16002)
		(layer "In11.Cu")
		(net "M_L_CPU1_SA_DQS_DP<3>")
	)
	(segment
		(start 195.18249 -228.910134)
		(end 195.51015 -229.237794)
		(width 0.16002)
		(layer "In11.Cu")
		(net "M_L_CPU1_SA_DQS_DP<3>")
	)
	(segment
		(start 188.689996 -229.237794)
		(end 189.512956 -228.414834)
		(width 0.16002)
		(layer "In11.Cu")
		(net "M_L_CPU1_SA_DQS_DP<3>")
	)
	(segment
		(start 180.422042 -229.237794)
		(end 181.145942 -229.237794)
		(width 0.16002)
		(layer "In11.Cu")
		(net "M_L_CPU1_SA_DQS_DP<3>")
	)
	(segment
		(start 174.424848 -228.414834)
		(end 174.836328 -228.414834)
		(width 0.16002)
		(layer "In11.Cu")
		(net "M_L_CPU1_SA_DQS_DP<3>")
	)
	(segment
		(start 147.895564 -240.411254)
		(end 147.919186 -240.411254)
		(width 0.09525)
		(layer "In11.Cu")
		(net "M_L_CPU1_SA_DQS_DP<3>")
	)
	(segment
		(start 174.836328 -228.414834)
		(end 175.190912 -228.06025)
		(width 0.16002)
		(layer "In11.Cu")
		(net "M_L_CPU1_SA_DQS_DP<3>")
	)
	(segment
		(start 172.877988 -229.237794)
		(end 173.601888 -229.237794)
		(width 0.16002)
		(layer "In11.Cu")
		(net "M_L_CPU1_SA_DQS_DP<3>")
	)
	(segment
		(start 147.26285 -240.763806)
		(end 147.55622 -240.470436)
		(width 0.09525)
		(layer "In11.Cu")
		(net "M_L_CPU1_SA_DQS_DP<3>")
	)
	(segment
		(start 141.094968 -241.57432)
		(end 141.10335 -241.569494)
		(width 0.09525)
		(layer "In11.Cu")
		(net "M_L_CPU1_SA_DQS_DP<3>")
	)
	(segment
		(start 177.100484 -228.06025)
		(end 177.950368 -228.910134)
		(width 0.16002)
		(layer "In11.Cu")
		(net "M_L_CPU1_SA_DQS_DP<3>")
	)
	(segment
		(start 197.46849 -228.414834)
		(end 197.823074 -228.06025)
		(width 0.16002)
		(layer "In11.Cu")
		(net "M_L_CPU1_SA_DQS_DP<3>")
	)
	(segment
		(start 153.277824 -240.411254)
		(end 164.451284 -229.237794)
		(width 0.16002)
		(layer "In11.Cu")
		(net "M_L_CPU1_SA_DQS_DP<3>")
	)
	(segment
		(start 181.145942 -229.237794)
		(end 181.968902 -228.414834)
		(width 0.16002)
		(layer "In11.Cu")
		(net "M_L_CPU1_SA_DQS_DP<3>")
	)
	(segment
		(start 147.836382 -240.470436)
		(end 147.895564 -240.411254)
		(width 0.09525)
		(layer "In11.Cu")
		(net "M_L_CPU1_SA_DQS_DP<3>")
	)
	(segment
		(start 139.034774 -241.244374)
		(end 139.188698 -241.509804)
		(width 0.09525)
		(layer "In11.Cu")
		(net "M_L_CPU1_SA_DQS_DP<3>")
	)
	(segment
		(start 187.966096 -229.237794)
		(end 188.689996 -229.237794)
		(width 0.16002)
		(layer "In11.Cu")
		(net "M_L_CPU1_SA_DQS_DP<3>")
	)
	(segment
		(start 167.292274 -228.414834)
		(end 167.646858 -228.06025)
		(width 0.16002)
		(layer "In11.Cu")
		(net "M_L_CPU1_SA_DQS_DP<3>")
	)
	(segment
		(start 170.406314 -228.910134)
		(end 172.550328 -228.910134)
		(width 0.16002)
		(layer "In11.Cu")
		(net "M_L_CPU1_SA_DQS_DP<3>")
	)
	(segment
		(start 196.23405 -229.237794)
		(end 197.05701 -228.414834)
		(width 0.16002)
		(layer "In11.Cu")
		(net "M_L_CPU1_SA_DQS_DP<3>")
	)
	(segment
		(start 182.734966 -228.06025)
		(end 184.644538 -228.06025)
		(width 0.16002)
		(layer "In11.Cu")
		(net "M_L_CPU1_SA_DQS_DP<3>")
	)
	(segment
		(start 145.879566 -241.510566)
		(end 146.626326 -240.763806)
		(width 0.09525)
		(layer "In11.Cu")
		(net "M_L_CPU1_SA_DQS_DP<3>")
	)
	(segment
		(start 169.55643 -228.06025)
		(end 170.406314 -228.910134)
		(width 0.16002)
		(layer "In11.Cu")
		(net "M_L_CPU1_SA_DQS_DP<3>")
	)
	(segment
		(start 202.728322 -228.63429)
		(end 203.347066 -229.253034)
		(width 0.16002)
		(layer "In11.Cu")
		(net "M_L_CPU1_SA_DQS_DP<3>")
	)
	(segment
		(start 166.057834 -229.237794)
		(end 166.880794 -228.414834)
		(width 0.16002)
		(layer "In11.Cu")
		(net "M_L_CPU1_SA_DQS_DP<3>")
	)
	(segment
		(start 195.51015 -229.237794)
		(end 196.23405 -229.237794)
		(width 0.16002)
		(layer "In11.Cu")
		(net "M_L_CPU1_SA_DQS_DP<3>")
	)
	(segment
		(start 177.950368 -228.910134)
		(end 180.094382 -228.910134)
		(width 0.16002)
		(layer "In11.Cu")
		(net "M_L_CPU1_SA_DQS_DP<3>")
	)
	(segment
		(start 164.451284 -229.237794)
		(end 166.057834 -229.237794)
		(width 0.16002)
		(layer "In11.Cu")
		(net "M_L_CPU1_SA_DQS_DP<3>")
	)
	(segment
		(start 146.626326 -240.763806)
		(end 147.26285 -240.763806)
		(width 0.09525)
		(layer "In11.Cu")
		(net "M_L_CPU1_SA_DQS_DP<3>")
	)
	(segment
		(start 203.955396 -229.059232)
		(end 205.974188 -229.059232)
		(width 0.16002)
		(layer "In11.Cu")
		(net "M_L_CPU1_SA_DQS_DP<3>")
	)
	(segment
		(start 184.644538 -228.06025)
		(end 185.494422 -228.910134)
		(width 0.16002)
		(layer "In11.Cu")
		(net "M_L_CPU1_SA_DQS_DP<3>")
	)
	(segment
		(start 180.094382 -228.910134)
		(end 180.422042 -229.237794)
		(width 0.16002)
		(layer "In11.Cu")
		(net "M_L_CPU1_SA_DQS_DP<3>")
	)
	(segment
		(start 175.190912 -228.06025)
		(end 177.100484 -228.06025)
		(width 0.16002)
		(layer "In11.Cu")
		(net "M_L_CPU1_SA_DQS_DP<3>")
	)
	(segment
		(start 189.924436 -228.414834)
		(end 190.27902 -228.06025)
		(width 0.16002)
		(layer "In11.Cu")
		(net "M_L_CPU1_SA_DQS_DP<3>")
	)
	(segment
		(start 166.880794 -228.414834)
		(end 167.292274 -228.414834)
		(width 0.16002)
		(layer "In11.Cu")
		(net "M_L_CPU1_SA_DQS_DP<3>")
	)
	(segment
		(start 203.761594 -229.253034)
		(end 203.955396 -229.059232)
		(width 0.16002)
		(layer "In11.Cu")
		(net "M_L_CPU1_SA_DQS_DP<3>")
	)
	(segment
		(start 192.188592 -228.06025)
		(end 193.038476 -228.910134)
		(width 0.16002)
		(layer "In11.Cu")
		(net "M_L_CPU1_SA_DQS_DP<3>")
	)
	(segment
		(start 189.512956 -228.414834)
		(end 189.924436 -228.414834)
		(width 0.16002)
		(layer "In11.Cu")
		(net "M_L_CPU1_SA_DQS_DP<3>")
	)
	(segment
		(start 143.923004 -241.569494)
		(end 143.941038 -241.55908)
		(width 0.09525)
		(layer "In11.Cu")
		(net "M_L_CPU1_SA_DQS_DP<3>")
	)
	(segment
		(start 187.638436 -228.910134)
		(end 187.966096 -229.237794)
		(width 0.16002)
		(layer "In11.Cu")
		(net "M_L_CPU1_SA_DQS_DP<3>")
	)
	(segment
		(start 197.823074 -228.06025)
		(end 199.732646 -228.06025)
		(width 0.16002)
		(layer "In11.Cu")
		(net "M_L_CPU1_SA_DQS_DP<3>")
	)
	(segment
		(start 144.485106 -241.569494)
		(end 144.497044 -241.576352)
		(width 0.09525)
		(layer "In11.Cu")
		(net "M_L_CPU1_SA_DQS_DP<3>")
	)
	(arc
		(start 145.437352 -241.576352)
		(mid 145.620479 -241.620064)
		(end 145.801842 -241.569494)
		(width 0.09525)
		(layer "In11.Cu")
		(net "M_L_CPU1_SA_DQS_DP<3>")
	)
	(arc
		(start 142.043404 -241.569494)
		(mid 142.324836 -241.493739)
		(end 142.606268 -241.569494)
		(width 0.09525)
		(layer "In11.Cu")
		(net "M_L_CPU1_SA_DQS_DP<3>")
	)
	(arc
		(start 144.86255 -241.569494)
		(mid 145.129399 -241.493566)
		(end 145.400014 -241.554762)
		(width 0.09525)
		(layer "In11.Cu")
		(net "M_L_CPU1_SA_DQS_DP<3>")
	)
	(arc
		(start 141.10335 -241.569494)
		(mid 141.384782 -241.493739)
		(end 141.666214 -241.569494)
		(width 0.09525)
		(layer "In11.Cu")
		(net "M_L_CPU1_SA_DQS_DP<3>")
	)
	(arc
		(start 143.941038 -241.55908)
		(mid 144.214418 -241.493859)
		(end 144.485106 -241.569494)
		(width 0.09525)
		(layer "In11.Cu")
		(net "M_L_CPU1_SA_DQS_DP<3>")
	)
	(arc
		(start 139.289536 -241.536474)
		(mid 139.541677 -241.494904)
		(end 139.786106 -241.569494)
		(width 0.09525)
		(layer "In11.Cu")
		(net "M_L_CPU1_SA_DQS_DP<3>")
	)
	(arc
		(start 144.497044 -241.576352)
		(mid 144.680679 -241.620302)
		(end 144.86255 -241.569494)
		(width 0.09525)
		(layer "In11.Cu")
		(net "M_L_CPU1_SA_DQS_DP<3>")
	)
	(arc
		(start 142.606268 -241.569494)
		(mid 142.794736 -241.620171)
		(end 142.983204 -241.569494)
		(width 0.09525)
		(layer "In11.Cu")
		(net "M_L_CPU1_SA_DQS_DP<3>")
	)
	(arc
		(start 142.983204 -241.569494)
		(mid 143.264636 -241.493739)
		(end 143.546068 -241.569494)
		(width 0.09525)
		(layer "In11.Cu")
		(net "M_L_CPU1_SA_DQS_DP<3>")
	)
	(arc
		(start 145.801842 -241.569494)
		(mid 145.842623 -241.542561)
		(end 145.879566 -241.510566)
		(width 0.09525)
		(layer "In11.Cu")
		(net "M_L_CPU1_SA_DQS_DP<3>")
	)
	(arc
		(start 140.163296 -241.569494)
		(mid 140.444728 -241.493739)
		(end 140.72616 -241.569494)
		(width 0.09525)
		(layer "In11.Cu")
		(net "M_L_CPU1_SA_DQS_DP<3>")
	)
	(arc
		(start 140.72616 -241.569494)
		(mid 140.909935 -241.620266)
		(end 141.094968 -241.57432)
		(width 0.09525)
		(layer "In11.Cu")
		(net "M_L_CPU1_SA_DQS_DP<3>")
	)
	(arc
		(start 143.546068 -241.569494)
		(mid 143.727684 -241.620231)
		(end 143.911066 -241.576352)
		(width 0.09525)
		(layer "In11.Cu")
		(net "M_L_CPU1_SA_DQS_DP<3>")
	)
	(arc
		(start 141.674596 -241.57432)
		(mid 141.859628 -241.620234)
		(end 142.043404 -241.569494)
		(width 0.09525)
		(layer "In11.Cu")
		(net "M_L_CPU1_SA_DQS_DP<3>")
	)
	(arc
		(start 139.786106 -241.569494)
		(mid 139.969881 -241.620266)
		(end 140.154914 -241.57432)
		(width 0.09525)
		(layer "In11.Cu")
		(net "M_L_CPU1_SA_DQS_DP<3>")
	)
	(segment
		(start 138.567922 -236.650276)
		(end 139.034774 -236.384338)
		(width 0.12954)
		(layer "F.Cu")
		(net "M_L_CPU1_SA_DQS_DP<2>")
	)
	(segment
		(start 139.188698 -236.649768)
		(end 139.289536 -236.676438)
		(width 0.09525)
		(layer "In11.Cu")
		(net "M_L_CPU1_SA_DQS_DP<2>")
	)
	(segment
		(start 184.644538 -218.710256)
		(end 185.494422 -219.56014)
		(width 0.16002)
		(layer "In11.Cu")
		(net "M_L_CPU1_SA_DQS_DP<2>")
	)
	(segment
		(start 147.895564 -234.755436)
		(end 147.919186 -234.755436)
		(width 0.09525)
		(layer "In11.Cu")
		(net "M_L_CPU1_SA_DQS_DP<2>")
	)
	(segment
		(start 147.919186 -234.755436)
		(end 149.3139 -234.755436)
		(width 0.16002)
		(layer "In11.Cu")
		(net "M_L_CPU1_SA_DQS_DP<2>")
	)
	(segment
		(start 145.873978 -236.633258)
		(end 146.44751 -236.059726)
		(width 0.09525)
		(layer "In11.Cu")
		(net "M_L_CPU1_SA_DQS_DP<2>")
	)
	(segment
		(start 147.609814 -234.814618)
		(end 147.836382 -234.814618)
		(width 0.09525)
		(layer "In11.Cu")
		(net "M_L_CPU1_SA_DQS_DP<2>")
	)
	(segment
		(start 143.911066 -236.716316)
		(end 143.923004 -236.709458)
		(width 0.09525)
		(layer "In11.Cu")
		(net "M_L_CPU1_SA_DQS_DP<2>")
	)
	(segment
		(start 177.100484 -218.710256)
		(end 177.950368 -219.56014)
		(width 0.16002)
		(layer "In11.Cu")
		(net "M_L_CPU1_SA_DQS_DP<2>")
	)
	(segment
		(start 193.038476 -219.56014)
		(end 195.18249 -219.56014)
		(width 0.16002)
		(layer "In11.Cu")
		(net "M_L_CPU1_SA_DQS_DP<2>")
	)
	(segment
		(start 144.485106 -236.709458)
		(end 144.497044 -236.716316)
		(width 0.09525)
		(layer "In11.Cu")
		(net "M_L_CPU1_SA_DQS_DP<2>")
	)
	(segment
		(start 192.188592 -218.710256)
		(end 193.038476 -219.56014)
		(width 0.16002)
		(layer "In11.Cu")
		(net "M_L_CPU1_SA_DQS_DP<2>")
	)
	(segment
		(start 140.154914 -236.714284)
		(end 140.163296 -236.709458)
		(width 0.09525)
		(layer "In11.Cu")
		(net "M_L_CPU1_SA_DQS_DP<2>")
	)
	(segment
		(start 166.057834 -219.8878)
		(end 166.880794 -219.06484)
		(width 0.16002)
		(layer "In11.Cu")
		(net "M_L_CPU1_SA_DQS_DP<2>")
	)
	(segment
		(start 180.422042 -219.8878)
		(end 181.145942 -219.8878)
		(width 0.16002)
		(layer "In11.Cu")
		(net "M_L_CPU1_SA_DQS_DP<2>")
	)
	(segment
		(start 199.732646 -218.710256)
		(end 200.306686 -219.284296)
		(width 0.16002)
		(layer "In11.Cu")
		(net "M_L_CPU1_SA_DQS_DP<2>")
	)
	(segment
		(start 187.966096 -219.8878)
		(end 188.689996 -219.8878)
		(width 0.16002)
		(layer "In11.Cu")
		(net "M_L_CPU1_SA_DQS_DP<2>")
	)
	(segment
		(start 147.406868 -235.204508)
		(end 147.406868 -235.017564)
		(width 0.09525)
		(layer "In11.Cu")
		(net "M_L_CPU1_SA_DQS_DP<2>")
	)
	(segment
		(start 167.292274 -219.06484)
		(end 167.646858 -218.710256)
		(width 0.16002)
		(layer "In11.Cu")
		(net "M_L_CPU1_SA_DQS_DP<2>")
	)
	(segment
		(start 147.406868 -235.017564)
		(end 147.609814 -234.814618)
		(width 0.09525)
		(layer "In11.Cu")
		(net "M_L_CPU1_SA_DQS_DP<2>")
	)
	(segment
		(start 182.380382 -219.06484)
		(end 182.734966 -218.710256)
		(width 0.16002)
		(layer "In11.Cu")
		(net "M_L_CPU1_SA_DQS_DP<2>")
	)
	(segment
		(start 141.666214 -236.709458)
		(end 141.674596 -236.714284)
		(width 0.09525)
		(layer "In11.Cu")
		(net "M_L_CPU1_SA_DQS_DP<2>")
	)
	(segment
		(start 196.23405 -219.8878)
		(end 197.05701 -219.06484)
		(width 0.16002)
		(layer "In11.Cu")
		(net "M_L_CPU1_SA_DQS_DP<2>")
	)
	(segment
		(start 205.974188 -219.709238)
		(end 206.248 -219.435426)
		(width 0.16002)
		(layer "In11.Cu")
		(net "M_L_CPU1_SA_DQS_DP<2>")
	)
	(segment
		(start 143.923004 -236.709458)
		(end 143.941038 -236.699044)
		(width 0.09525)
		(layer "In11.Cu")
		(net "M_L_CPU1_SA_DQS_DP<2>")
	)
	(segment
		(start 190.27902 -218.710256)
		(end 192.188592 -218.710256)
		(width 0.16002)
		(layer "In11.Cu")
		(net "M_L_CPU1_SA_DQS_DP<2>")
	)
	(segment
		(start 189.512956 -219.06484)
		(end 189.924436 -219.06484)
		(width 0.16002)
		(layer "In11.Cu")
		(net "M_L_CPU1_SA_DQS_DP<2>")
	)
	(segment
		(start 174.424848 -219.06484)
		(end 174.836328 -219.06484)
		(width 0.16002)
		(layer "In11.Cu")
		(net "M_L_CPU1_SA_DQS_DP<2>")
	)
	(segment
		(start 172.877988 -219.8878)
		(end 173.601888 -219.8878)
		(width 0.16002)
		(layer "In11.Cu")
		(net "M_L_CPU1_SA_DQS_DP<2>")
	)
	(segment
		(start 197.823074 -218.710256)
		(end 199.732646 -218.710256)
		(width 0.16002)
		(layer "In11.Cu")
		(net "M_L_CPU1_SA_DQS_DP<2>")
	)
	(segment
		(start 197.46849 -219.06484)
		(end 197.823074 -218.710256)
		(width 0.16002)
		(layer "In11.Cu")
		(net "M_L_CPU1_SA_DQS_DP<2>")
	)
	(segment
		(start 185.494422 -219.56014)
		(end 187.638436 -219.56014)
		(width 0.16002)
		(layer "In11.Cu")
		(net "M_L_CPU1_SA_DQS_DP<2>")
	)
	(segment
		(start 203.761594 -219.90304)
		(end 203.955396 -219.709238)
		(width 0.16002)
		(layer "In11.Cu")
		(net "M_L_CPU1_SA_DQS_DP<2>")
	)
	(segment
		(start 197.05701 -219.06484)
		(end 197.46849 -219.06484)
		(width 0.16002)
		(layer "In11.Cu")
		(net "M_L_CPU1_SA_DQS_DP<2>")
	)
	(segment
		(start 139.034774 -236.384338)
		(end 139.188698 -236.649768)
		(width 0.09525)
		(layer "In11.Cu")
		(net "M_L_CPU1_SA_DQS_DP<2>")
	)
	(segment
		(start 141.094968 -236.714284)
		(end 141.10335 -236.709458)
		(width 0.09525)
		(layer "In11.Cu")
		(net "M_L_CPU1_SA_DQS_DP<2>")
	)
	(segment
		(start 202.728322 -219.284296)
		(end 203.347066 -219.90304)
		(width 0.16002)
		(layer "In11.Cu")
		(net "M_L_CPU1_SA_DQS_DP<2>")
	)
	(segment
		(start 180.094382 -219.56014)
		(end 180.422042 -219.8878)
		(width 0.16002)
		(layer "In11.Cu")
		(net "M_L_CPU1_SA_DQS_DP<2>")
	)
	(segment
		(start 187.638436 -219.56014)
		(end 187.966096 -219.8878)
		(width 0.16002)
		(layer "In11.Cu")
		(net "M_L_CPU1_SA_DQS_DP<2>")
	)
	(segment
		(start 200.306686 -219.284296)
		(end 202.728322 -219.284296)
		(width 0.16002)
		(layer "In11.Cu")
		(net "M_L_CPU1_SA_DQS_DP<2>")
	)
	(segment
		(start 172.550328 -219.56014)
		(end 172.877988 -219.8878)
		(width 0.16002)
		(layer "In11.Cu")
		(net "M_L_CPU1_SA_DQS_DP<2>")
	)
	(segment
		(start 169.55643 -218.710256)
		(end 170.406314 -219.56014)
		(width 0.16002)
		(layer "In11.Cu")
		(net "M_L_CPU1_SA_DQS_DP<2>")
	)
	(segment
		(start 146.62531 -235.986066)
		(end 147.406868 -235.204508)
		(width 0.09525)
		(layer "In11.Cu")
		(net "M_L_CPU1_SA_DQS_DP<2>")
	)
	(segment
		(start 146.44751 -236.059726)
		(end 146.62531 -235.986066)
		(width 0.09525)
		(layer "In11.Cu")
		(net "M_L_CPU1_SA_DQS_DP<2>")
	)
	(segment
		(start 174.836328 -219.06484)
		(end 175.190912 -218.710256)
		(width 0.16002)
		(layer "In11.Cu")
		(net "M_L_CPU1_SA_DQS_DP<2>")
	)
	(segment
		(start 177.950368 -219.56014)
		(end 180.094382 -219.56014)
		(width 0.16002)
		(layer "In11.Cu")
		(net "M_L_CPU1_SA_DQS_DP<2>")
	)
	(segment
		(start 181.968902 -219.06484)
		(end 182.380382 -219.06484)
		(width 0.16002)
		(layer "In11.Cu")
		(net "M_L_CPU1_SA_DQS_DP<2>")
	)
	(segment
		(start 189.924436 -219.06484)
		(end 190.27902 -218.710256)
		(width 0.16002)
		(layer "In11.Cu")
		(net "M_L_CPU1_SA_DQS_DP<2>")
	)
	(segment
		(start 173.601888 -219.8878)
		(end 174.424848 -219.06484)
		(width 0.16002)
		(layer "In11.Cu")
		(net "M_L_CPU1_SA_DQS_DP<2>")
	)
	(segment
		(start 188.689996 -219.8878)
		(end 189.512956 -219.06484)
		(width 0.16002)
		(layer "In11.Cu")
		(net "M_L_CPU1_SA_DQS_DP<2>")
	)
	(segment
		(start 195.51015 -219.8878)
		(end 196.23405 -219.8878)
		(width 0.16002)
		(layer "In11.Cu")
		(net "M_L_CPU1_SA_DQS_DP<2>")
	)
	(segment
		(start 170.406314 -219.56014)
		(end 172.550328 -219.56014)
		(width 0.16002)
		(layer "In11.Cu")
		(net "M_L_CPU1_SA_DQS_DP<2>")
	)
	(segment
		(start 147.836382 -234.814618)
		(end 147.895564 -234.755436)
		(width 0.09525)
		(layer "In11.Cu")
		(net "M_L_CPU1_SA_DQS_DP<2>")
	)
	(segment
		(start 182.734966 -218.710256)
		(end 184.644538 -218.710256)
		(width 0.16002)
		(layer "In11.Cu")
		(net "M_L_CPU1_SA_DQS_DP<2>")
	)
	(segment
		(start 203.955396 -219.709238)
		(end 205.974188 -219.709238)
		(width 0.16002)
		(layer "In11.Cu")
		(net "M_L_CPU1_SA_DQS_DP<2>")
	)
	(segment
		(start 167.646858 -218.710256)
		(end 169.55643 -218.710256)
		(width 0.16002)
		(layer "In11.Cu")
		(net "M_L_CPU1_SA_DQS_DP<2>")
	)
	(segment
		(start 203.347066 -219.90304)
		(end 203.761594 -219.90304)
		(width 0.16002)
		(layer "In11.Cu")
		(net "M_L_CPU1_SA_DQS_DP<2>")
	)
	(segment
		(start 164.181536 -219.8878)
		(end 166.057834 -219.8878)
		(width 0.16002)
		(layer "In11.Cu")
		(net "M_L_CPU1_SA_DQS_DP<2>")
	)
	(segment
		(start 181.145942 -219.8878)
		(end 181.968902 -219.06484)
		(width 0.16002)
		(layer "In11.Cu")
		(net "M_L_CPU1_SA_DQS_DP<2>")
	)
	(segment
		(start 195.18249 -219.56014)
		(end 195.51015 -219.8878)
		(width 0.16002)
		(layer "In11.Cu")
		(net "M_L_CPU1_SA_DQS_DP<2>")
	)
	(segment
		(start 166.880794 -219.06484)
		(end 167.292274 -219.06484)
		(width 0.16002)
		(layer "In11.Cu")
		(net "M_L_CPU1_SA_DQS_DP<2>")
	)
	(segment
		(start 175.190912 -218.710256)
		(end 177.100484 -218.710256)
		(width 0.16002)
		(layer "In11.Cu")
		(net "M_L_CPU1_SA_DQS_DP<2>")
	)
	(segment
		(start 145.144744 -236.633258)
		(end 145.873978 -236.633258)
		(width 0.09525)
		(layer "In11.Cu")
		(net "M_L_CPU1_SA_DQS_DP<2>")
	)
	(segment
		(start 149.3139 -234.755436)
		(end 164.181536 -219.8878)
		(width 0.16002)
		(layer "In11.Cu")
		(net "M_L_CPU1_SA_DQS_DP<2>")
	)
	(arc
		(start 141.674596 -236.714284)
		(mid 141.859628 -236.760198)
		(end 142.043404 -236.709458)
		(width 0.09525)
		(layer "In11.Cu")
		(net "M_L_CPU1_SA_DQS_DP<2>")
	)
	(arc
		(start 143.546068 -236.709458)
		(mid 143.727684 -236.760195)
		(end 143.911066 -236.716316)
		(width 0.09525)
		(layer "In11.Cu")
		(net "M_L_CPU1_SA_DQS_DP<2>")
	)
	(arc
		(start 144.86255 -236.709458)
		(mid 144.998602 -236.652689)
		(end 145.144744 -236.633258)
		(width 0.09525)
		(layer "In11.Cu")
		(net "M_L_CPU1_SA_DQS_DP<2>")
	)
	(arc
		(start 142.043404 -236.709458)
		(mid 142.324836 -236.633703)
		(end 142.606268 -236.709458)
		(width 0.09525)
		(layer "In11.Cu")
		(net "M_L_CPU1_SA_DQS_DP<2>")
	)
	(arc
		(start 139.289536 -236.676438)
		(mid 139.541677 -236.634868)
		(end 139.786106 -236.709458)
		(width 0.09525)
		(layer "In11.Cu")
		(net "M_L_CPU1_SA_DQS_DP<2>")
	)
	(arc
		(start 144.497044 -236.716316)
		(mid 144.680679 -236.760266)
		(end 144.86255 -236.709458)
		(width 0.09525)
		(layer "In11.Cu")
		(net "M_L_CPU1_SA_DQS_DP<2>")
	)
	(arc
		(start 142.606268 -236.709458)
		(mid 142.794736 -236.760135)
		(end 142.983204 -236.709458)
		(width 0.09525)
		(layer "In11.Cu")
		(net "M_L_CPU1_SA_DQS_DP<2>")
	)
	(arc
		(start 142.983204 -236.709458)
		(mid 143.264636 -236.633703)
		(end 143.546068 -236.709458)
		(width 0.09525)
		(layer "In11.Cu")
		(net "M_L_CPU1_SA_DQS_DP<2>")
	)
	(arc
		(start 141.10335 -236.709458)
		(mid 141.384782 -236.633703)
		(end 141.666214 -236.709458)
		(width 0.09525)
		(layer "In11.Cu")
		(net "M_L_CPU1_SA_DQS_DP<2>")
	)
	(arc
		(start 140.163296 -236.709458)
		(mid 140.444728 -236.633703)
		(end 140.72616 -236.709458)
		(width 0.09525)
		(layer "In11.Cu")
		(net "M_L_CPU1_SA_DQS_DP<2>")
	)
	(arc
		(start 143.941038 -236.699044)
		(mid 144.214418 -236.633823)
		(end 144.485106 -236.709458)
		(width 0.09525)
		(layer "In11.Cu")
		(net "M_L_CPU1_SA_DQS_DP<2>")
	)
	(arc
		(start 140.72616 -236.709458)
		(mid 140.909935 -236.76023)
		(end 141.094968 -236.714284)
		(width 0.09525)
		(layer "In11.Cu")
		(net "M_L_CPU1_SA_DQS_DP<2>")
	)
	(arc
		(start 139.786106 -236.709458)
		(mid 139.969881 -236.76023)
		(end 140.154914 -236.714284)
		(width 0.09525)
		(layer "In11.Cu")
		(net "M_L_CPU1_SA_DQS_DP<2>")
	)
	(segment
		(start 138.567922 -231.79024)
		(end 139.034774 -231.524302)
		(width 0.12954)
		(layer "F.Cu")
		(net "M_L_CPU1_SA_DQS_DP<1>")
	)
	(segment
		(start 140.154914 -231.854248)
		(end 140.163296 -231.849422)
		(width 0.09525)
		(layer "In11.Cu")
		(net "M_L_CPU1_SA_DQS_DP<1>")
	)
	(segment
		(start 193.038476 -210.210146)
		(end 195.18249 -210.210146)
		(width 0.16002)
		(layer "In11.Cu")
		(net "M_L_CPU1_SA_DQS_DP<1>")
	)
	(segment
		(start 147.26793 -228.86543)
		(end 147.26793 -228.78161)
		(width 0.09525)
		(layer "In11.Cu")
		(net "M_L_CPU1_SA_DQS_DP<1>")
	)
	(segment
		(start 200.306686 -209.934302)
		(end 202.728322 -209.934302)
		(width 0.16002)
		(layer "In11.Cu")
		(net "M_L_CPU1_SA_DQS_DP<1>")
	)
	(segment
		(start 197.46849 -209.714846)
		(end 197.823074 -209.360262)
		(width 0.16002)
		(layer "In11.Cu")
		(net "M_L_CPU1_SA_DQS_DP<1>")
	)
	(segment
		(start 174.424848 -209.714846)
		(end 174.836328 -209.714846)
		(width 0.16002)
		(layer "In11.Cu")
		(net "M_L_CPU1_SA_DQS_DP<1>")
	)
	(segment
		(start 172.877988 -210.537806)
		(end 173.601888 -210.537806)
		(width 0.16002)
		(layer "In11.Cu")
		(net "M_L_CPU1_SA_DQS_DP<1>")
	)
	(segment
		(start 177.100484 -209.360262)
		(end 177.950368 -210.210146)
		(width 0.16002)
		(layer "In11.Cu")
		(net "M_L_CPU1_SA_DQS_DP<1>")
	)
	(segment
		(start 187.638436 -210.210146)
		(end 187.966096 -210.537806)
		(width 0.16002)
		(layer "In11.Cu")
		(net "M_L_CPU1_SA_DQS_DP<1>")
	)
	(segment
		(start 166.880794 -209.714846)
		(end 167.292274 -209.714846)
		(width 0.16002)
		(layer "In11.Cu")
		(net "M_L_CPU1_SA_DQS_DP<1>")
	)
	(segment
		(start 180.422042 -210.537806)
		(end 181.145942 -210.537806)
		(width 0.16002)
		(layer "In11.Cu")
		(net "M_L_CPU1_SA_DQS_DP<1>")
	)
	(segment
		(start 203.347066 -210.553046)
		(end 203.761594 -210.553046)
		(width 0.16002)
		(layer "In11.Cu")
		(net "M_L_CPU1_SA_DQS_DP<1>")
	)
	(segment
		(start 189.924436 -209.714846)
		(end 190.27902 -209.360262)
		(width 0.16002)
		(layer "In11.Cu")
		(net "M_L_CPU1_SA_DQS_DP<1>")
	)
	(segment
		(start 144.941036 -231.79024)
		(end 146.15287 -230.578406)
		(width 0.09525)
		(layer "In11.Cu")
		(net "M_L_CPU1_SA_DQS_DP<1>")
	)
	(segment
		(start 185.494422 -210.210146)
		(end 187.638436 -210.210146)
		(width 0.16002)
		(layer "In11.Cu")
		(net "M_L_CPU1_SA_DQS_DP<1>")
	)
	(segment
		(start 146.15287 -230.578406)
		(end 146.15287 -229.98049)
		(width 0.09525)
		(layer "In11.Cu")
		(net "M_L_CPU1_SA_DQS_DP<1>")
	)
	(segment
		(start 187.966096 -210.537806)
		(end 188.689996 -210.537806)
		(width 0.16002)
		(layer "In11.Cu")
		(net "M_L_CPU1_SA_DQS_DP<1>")
	)
	(segment
		(start 196.23405 -210.537806)
		(end 197.05701 -209.714846)
		(width 0.16002)
		(layer "In11.Cu")
		(net "M_L_CPU1_SA_DQS_DP<1>")
	)
	(segment
		(start 202.728322 -209.934302)
		(end 203.347066 -210.553046)
		(width 0.16002)
		(layer "In11.Cu")
		(net "M_L_CPU1_SA_DQS_DP<1>")
	)
	(segment
		(start 188.689996 -210.537806)
		(end 189.512956 -209.714846)
		(width 0.16002)
		(layer "In11.Cu")
		(net "M_L_CPU1_SA_DQS_DP<1>")
	)
	(segment
		(start 146.15287 -229.98049)
		(end 147.26793 -228.86543)
		(width 0.09525)
		(layer "In11.Cu")
		(net "M_L_CPU1_SA_DQS_DP<1>")
	)
	(segment
		(start 172.550328 -210.210146)
		(end 172.877988 -210.537806)
		(width 0.16002)
		(layer "In11.Cu")
		(net "M_L_CPU1_SA_DQS_DP<1>")
	)
	(segment
		(start 144.855184 -231.854248)
		(end 144.863566 -231.849422)
		(width 0.09525)
		(layer "In11.Cu")
		(net "M_L_CPU1_SA_DQS_DP<1>")
	)
	(segment
		(start 173.601888 -210.537806)
		(end 174.424848 -209.714846)
		(width 0.16002)
		(layer "In11.Cu")
		(net "M_L_CPU1_SA_DQS_DP<1>")
	)
	(segment
		(start 141.094968 -231.854248)
		(end 141.10335 -231.849422)
		(width 0.09525)
		(layer "In11.Cu")
		(net "M_L_CPU1_SA_DQS_DP<1>")
	)
	(segment
		(start 180.094382 -210.210146)
		(end 180.422042 -210.537806)
		(width 0.16002)
		(layer "In11.Cu")
		(net "M_L_CPU1_SA_DQS_DP<1>")
	)
	(segment
		(start 182.380382 -209.714846)
		(end 182.734966 -209.360262)
		(width 0.16002)
		(layer "In11.Cu")
		(net "M_L_CPU1_SA_DQS_DP<1>")
	)
	(segment
		(start 205.974188 -210.359244)
		(end 206.248 -210.085432)
		(width 0.16002)
		(layer "In11.Cu")
		(net "M_L_CPU1_SA_DQS_DP<1>")
	)
	(segment
		(start 182.734966 -209.360262)
		(end 184.644538 -209.360262)
		(width 0.16002)
		(layer "In11.Cu")
		(net "M_L_CPU1_SA_DQS_DP<1>")
	)
	(segment
		(start 199.732646 -209.360262)
		(end 200.306686 -209.934302)
		(width 0.16002)
		(layer "In11.Cu")
		(net "M_L_CPU1_SA_DQS_DP<1>")
	)
	(segment
		(start 197.05701 -209.714846)
		(end 197.46849 -209.714846)
		(width 0.16002)
		(layer "In11.Cu")
		(net "M_L_CPU1_SA_DQS_DP<1>")
	)
	(segment
		(start 181.968902 -209.714846)
		(end 182.380382 -209.714846)
		(width 0.16002)
		(layer "In11.Cu")
		(net "M_L_CPU1_SA_DQS_DP<1>")
	)
	(segment
		(start 190.27902 -209.360262)
		(end 192.188592 -209.360262)
		(width 0.16002)
		(layer "In11.Cu")
		(net "M_L_CPU1_SA_DQS_DP<1>")
	)
	(segment
		(start 163.933124 -210.537806)
		(end 166.057834 -210.537806)
		(width 0.16002)
		(layer "In11.Cu")
		(net "M_L_CPU1_SA_DQS_DP<1>")
	)
	(segment
		(start 181.145942 -210.537806)
		(end 181.968902 -209.714846)
		(width 0.16002)
		(layer "In11.Cu")
		(net "M_L_CPU1_SA_DQS_DP<1>")
	)
	(segment
		(start 192.188592 -209.360262)
		(end 193.038476 -210.210146)
		(width 0.16002)
		(layer "In11.Cu")
		(net "M_L_CPU1_SA_DQS_DP<1>")
	)
	(segment
		(start 163.039298 -210.908138)
		(end 163.933124 -210.537806)
		(width 0.16002)
		(layer "In11.Cu")
		(net "M_L_CPU1_SA_DQS_DP<1>")
	)
	(segment
		(start 189.512956 -209.714846)
		(end 189.924436 -209.714846)
		(width 0.16002)
		(layer "In11.Cu")
		(net "M_L_CPU1_SA_DQS_DP<1>")
	)
	(segment
		(start 195.18249 -210.210146)
		(end 195.51015 -210.537806)
		(width 0.16002)
		(layer "In11.Cu")
		(net "M_L_CPU1_SA_DQS_DP<1>")
	)
	(segment
		(start 141.666214 -231.849422)
		(end 141.674596 -231.854248)
		(width 0.09525)
		(layer "In11.Cu")
		(net "M_L_CPU1_SA_DQS_DP<1>")
	)
	(segment
		(start 147.284694 -228.764846)
		(end 151.98217 -224.068132)
		(width 0.16002)
		(layer "In11.Cu")
		(net "M_L_CPU1_SA_DQS_DP<1>")
	)
	(segment
		(start 175.190912 -209.360262)
		(end 177.100484 -209.360262)
		(width 0.16002)
		(layer "In11.Cu")
		(net "M_L_CPU1_SA_DQS_DP<1>")
	)
	(segment
		(start 203.955396 -210.359244)
		(end 205.974188 -210.359244)
		(width 0.16002)
		(layer "In11.Cu")
		(net "M_L_CPU1_SA_DQS_DP<1>")
	)
	(segment
		(start 174.836328 -209.714846)
		(end 175.190912 -209.360262)
		(width 0.16002)
		(layer "In11.Cu")
		(net "M_L_CPU1_SA_DQS_DP<1>")
	)
	(segment
		(start 177.950368 -210.210146)
		(end 180.094382 -210.210146)
		(width 0.16002)
		(layer "In11.Cu")
		(net "M_L_CPU1_SA_DQS_DP<1>")
	)
	(segment
		(start 151.98217 -224.068132)
		(end 151.98217 -221.965266)
		(width 0.16002)
		(layer "In11.Cu")
		(net "M_L_CPU1_SA_DQS_DP<1>")
	)
	(segment
		(start 195.51015 -210.537806)
		(end 196.23405 -210.537806)
		(width 0.16002)
		(layer "In11.Cu")
		(net "M_L_CPU1_SA_DQS_DP<1>")
	)
	(segment
		(start 147.26793 -228.78161)
		(end 147.284694 -228.764846)
		(width 0.09525)
		(layer "In11.Cu")
		(net "M_L_CPU1_SA_DQS_DP<1>")
	)
	(segment
		(start 167.292274 -209.714846)
		(end 167.646858 -209.360262)
		(width 0.16002)
		(layer "In11.Cu")
		(net "M_L_CPU1_SA_DQS_DP<1>")
	)
	(segment
		(start 166.057834 -210.537806)
		(end 166.880794 -209.714846)
		(width 0.16002)
		(layer "In11.Cu")
		(net "M_L_CPU1_SA_DQS_DP<1>")
	)
	(segment
		(start 184.644538 -209.360262)
		(end 185.494422 -210.210146)
		(width 0.16002)
		(layer "In11.Cu")
		(net "M_L_CPU1_SA_DQS_DP<1>")
	)
	(segment
		(start 167.646858 -209.360262)
		(end 169.55643 -209.360262)
		(width 0.16002)
		(layer "In11.Cu")
		(net "M_L_CPU1_SA_DQS_DP<1>")
	)
	(segment
		(start 151.98217 -221.965266)
		(end 163.039298 -210.908138)
		(width 0.16002)
		(layer "In11.Cu")
		(net "M_L_CPU1_SA_DQS_DP<1>")
	)
	(segment
		(start 169.55643 -209.360262)
		(end 170.406314 -210.210146)
		(width 0.16002)
		(layer "In11.Cu")
		(net "M_L_CPU1_SA_DQS_DP<1>")
	)
	(segment
		(start 139.034774 -231.524302)
		(end 139.188698 -231.789732)
		(width 0.09525)
		(layer "In11.Cu")
		(net "M_L_CPU1_SA_DQS_DP<1>")
	)
	(segment
		(start 170.406314 -210.210146)
		(end 172.550328 -210.210146)
		(width 0.16002)
		(layer "In11.Cu")
		(net "M_L_CPU1_SA_DQS_DP<1>")
	)
	(segment
		(start 139.188698 -231.789732)
		(end 139.289536 -231.816402)
		(width 0.09525)
		(layer "In11.Cu")
		(net "M_L_CPU1_SA_DQS_DP<1>")
	)
	(segment
		(start 203.761594 -210.553046)
		(end 203.955396 -210.359244)
		(width 0.16002)
		(layer "In11.Cu")
		(net "M_L_CPU1_SA_DQS_DP<1>")
	)
	(segment
		(start 197.823074 -209.360262)
		(end 199.732646 -209.360262)
		(width 0.16002)
		(layer "In11.Cu")
		(net "M_L_CPU1_SA_DQS_DP<1>")
	)
	(arc
		(start 140.163296 -231.849422)
		(mid 140.444728 -231.773667)
		(end 140.72616 -231.849422)
		(width 0.09525)
		(layer "In11.Cu")
		(net "M_L_CPU1_SA_DQS_DP<1>")
	)
	(arc
		(start 142.043404 -231.849422)
		(mid 142.324836 -231.773667)
		(end 142.606268 -231.849422)
		(width 0.09525)
		(layer "In11.Cu")
		(net "M_L_CPU1_SA_DQS_DP<1>")
	)
	(arc
		(start 141.674596 -231.854248)
		(mid 141.859628 -231.900162)
		(end 142.043404 -231.849422)
		(width 0.09525)
		(layer "In11.Cu")
		(net "M_L_CPU1_SA_DQS_DP<1>")
	)
	(arc
		(start 143.546068 -231.849422)
		(mid 143.73479 -231.900226)
		(end 143.923512 -231.849422)
		(width 0.09525)
		(layer "In11.Cu")
		(net "M_L_CPU1_SA_DQS_DP<1>")
	)
	(arc
		(start 144.486376 -231.849422)
		(mid 144.670151 -231.900194)
		(end 144.855184 -231.854248)
		(width 0.09525)
		(layer "In11.Cu")
		(net "M_L_CPU1_SA_DQS_DP<1>")
	)
	(arc
		(start 139.786106 -231.849422)
		(mid 139.969881 -231.900194)
		(end 140.154914 -231.854248)
		(width 0.09525)
		(layer "In11.Cu")
		(net "M_L_CPU1_SA_DQS_DP<1>")
	)
	(arc
		(start 140.72616 -231.849422)
		(mid 140.909935 -231.900194)
		(end 141.094968 -231.854248)
		(width 0.09525)
		(layer "In11.Cu")
		(net "M_L_CPU1_SA_DQS_DP<1>")
	)
	(arc
		(start 141.10335 -231.849422)
		(mid 141.384782 -231.773667)
		(end 141.666214 -231.849422)
		(width 0.09525)
		(layer "In11.Cu")
		(net "M_L_CPU1_SA_DQS_DP<1>")
	)
	(arc
		(start 142.606268 -231.849422)
		(mid 142.794736 -231.900099)
		(end 142.983204 -231.849422)
		(width 0.09525)
		(layer "In11.Cu")
		(net "M_L_CPU1_SA_DQS_DP<1>")
	)
	(arc
		(start 142.983204 -231.849422)
		(mid 143.264636 -231.773667)
		(end 143.546068 -231.849422)
		(width 0.09525)
		(layer "In11.Cu")
		(net "M_L_CPU1_SA_DQS_DP<1>")
	)
	(arc
		(start 143.923512 -231.849422)
		(mid 144.204944 -231.773667)
		(end 144.486376 -231.849422)
		(width 0.09525)
		(layer "In11.Cu")
		(net "M_L_CPU1_SA_DQS_DP<1>")
	)
	(arc
		(start 139.289536 -231.816402)
		(mid 139.541677 -231.774832)
		(end 139.786106 -231.849422)
		(width 0.09525)
		(layer "In11.Cu")
		(net "M_L_CPU1_SA_DQS_DP<1>")
	)
	(arc
		(start 144.863566 -231.849422)
		(mid 144.904238 -231.822365)
		(end 144.941036 -231.79024)
		(width 0.09525)
		(layer "In11.Cu")
		(net "M_L_CPU1_SA_DQS_DP<1>")
	)
	(segment
		(start 138.567922 -226.930458)
		(end 139.034774 -226.66452)
		(width 0.12954)
		(layer "F.Cu")
		(net "M_L_CPU1_SA_DQS_DP<0>")
	)
	(segment
		(start 180.094382 -200.860152)
		(end 180.422042 -201.187812)
		(width 0.16002)
		(layer "In11.Cu")
		(net "M_L_CPU1_SA_DQS_DP<0>")
	)
	(segment
		(start 170.406314 -200.860152)
		(end 172.550328 -200.860152)
		(width 0.16002)
		(layer "In11.Cu")
		(net "M_L_CPU1_SA_DQS_DP<0>")
	)
	(segment
		(start 185.494422 -200.860152)
		(end 187.638436 -200.860152)
		(width 0.16002)
		(layer "In11.Cu")
		(net "M_L_CPU1_SA_DQS_DP<0>")
	)
	(segment
		(start 145.29689 -222.960946)
		(end 145.36928 -222.919036)
		(width 0.09525)
		(layer "In11.Cu")
		(net "M_L_CPU1_SA_DQS_DP<0>")
	)
	(segment
		(start 144.863312 -223.749616)
		(end 144.895824 -223.73082)
		(width 0.09525)
		(layer "In11.Cu")
		(net "M_L_CPU1_SA_DQS_DP<0>")
	)
	(segment
		(start 182.380382 -200.364852)
		(end 182.734966 -200.010268)
		(width 0.16002)
		(layer "In11.Cu")
		(net "M_L_CPU1_SA_DQS_DP<0>")
	)
	(segment
		(start 187.638436 -200.860152)
		(end 187.966096 -201.187812)
		(width 0.16002)
		(layer "In11.Cu")
		(net "M_L_CPU1_SA_DQS_DP<0>")
	)
	(segment
		(start 143.923258 -225.369628)
		(end 143.95577 -225.350832)
		(width 0.09525)
		(layer "In11.Cu")
		(net "M_L_CPU1_SA_DQS_DP<0>")
	)
	(segment
		(start 143.453358 -226.179634)
		(end 143.484854 -226.161346)
		(width 0.09525)
		(layer "In11.Cu")
		(net "M_L_CPU1_SA_DQS_DP<0>")
	)
	(segment
		(start 180.422042 -201.187812)
		(end 181.145942 -201.187812)
		(width 0.16002)
		(layer "In11.Cu")
		(net "M_L_CPU1_SA_DQS_DP<0>")
	)
	(segment
		(start 197.05701 -200.364852)
		(end 197.46849 -200.364852)
		(width 0.16002)
		(layer "In11.Cu")
		(net "M_L_CPU1_SA_DQS_DP<0>")
	)
	(segment
		(start 203.955396 -201.00925)
		(end 205.974188 -201.00925)
		(width 0.16002)
		(layer "In11.Cu")
		(net "M_L_CPU1_SA_DQS_DP<0>")
	)
	(segment
		(start 145.576798 -222.66021)
		(end 146.214084 -222.022924)
		(width 0.09525)
		(layer "In11.Cu")
		(net "M_L_CPU1_SA_DQS_DP<0>")
	)
	(segment
		(start 166.880794 -200.364852)
		(end 167.292274 -200.364852)
		(width 0.16002)
		(layer "In11.Cu")
		(net "M_L_CPU1_SA_DQS_DP<0>")
	)
	(segment
		(start 146.155156 -221.198186)
		(end 146.155156 -221.174564)
		(width 0.09525)
		(layer "In11.Cu")
		(net "M_L_CPU1_SA_DQS_DP<0>")
	)
	(segment
		(start 193.038476 -200.860152)
		(end 195.18249 -200.860152)
		(width 0.16002)
		(layer "In11.Cu")
		(net "M_L_CPU1_SA_DQS_DP<0>")
	)
	(segment
		(start 144.393158 -224.559622)
		(end 144.42694 -224.540064)
		(width 0.09525)
		(layer "In11.Cu")
		(net "M_L_CPU1_SA_DQS_DP<0>")
	)
	(segment
		(start 140.154914 -226.994466)
		(end 140.163296 -226.98964)
		(width 0.09525)
		(layer "In11.Cu")
		(net "M_L_CPU1_SA_DQS_DP<0>")
	)
	(segment
		(start 167.646858 -200.010268)
		(end 169.55643 -200.010268)
		(width 0.16002)
		(layer "In11.Cu")
		(net "M_L_CPU1_SA_DQS_DP<0>")
	)
	(segment
		(start 177.100484 -200.010268)
		(end 177.950368 -200.860152)
		(width 0.16002)
		(layer "In11.Cu")
		(net "M_L_CPU1_SA_DQS_DP<0>")
	)
	(segment
		(start 181.145942 -201.187812)
		(end 181.968902 -200.364852)
		(width 0.16002)
		(layer "In11.Cu")
		(net "M_L_CPU1_SA_DQS_DP<0>")
	)
	(segment
		(start 199.732646 -200.010268)
		(end 200.306686 -200.584308)
		(width 0.16002)
		(layer "In11.Cu")
		(net "M_L_CPU1_SA_DQS_DP<0>")
	)
	(segment
		(start 146.214084 -222.022924)
		(end 146.214084 -221.257114)
		(width 0.09525)
		(layer "In11.Cu")
		(net "M_L_CPU1_SA_DQS_DP<0>")
	)
	(segment
		(start 203.761594 -201.203052)
		(end 203.955396 -201.00925)
		(width 0.16002)
		(layer "In11.Cu")
		(net "M_L_CPU1_SA_DQS_DP<0>")
	)
	(segment
		(start 187.966096 -201.187812)
		(end 188.689996 -201.187812)
		(width 0.16002)
		(layer "In11.Cu")
		(net "M_L_CPU1_SA_DQS_DP<0>")
	)
	(segment
		(start 184.644538 -200.010268)
		(end 185.494422 -200.860152)
		(width 0.16002)
		(layer "In11.Cu")
		(net "M_L_CPU1_SA_DQS_DP<0>")
	)
	(segment
		(start 174.836328 -200.364852)
		(end 175.190912 -200.010268)
		(width 0.16002)
		(layer "In11.Cu")
		(net "M_L_CPU1_SA_DQS_DP<0>")
	)
	(segment
		(start 146.155156 -217.55354)
		(end 162.520884 -201.187812)
		(width 0.16002)
		(layer "In11.Cu")
		(net "M_L_CPU1_SA_DQS_DP<0>")
	)
	(segment
		(start 182.734966 -200.010268)
		(end 184.644538 -200.010268)
		(width 0.16002)
		(layer "In11.Cu")
		(net "M_L_CPU1_SA_DQS_DP<0>")
	)
	(segment
		(start 205.974188 -201.00925)
		(end 206.248 -200.735438)
		(width 0.16002)
		(layer "In11.Cu")
		(net "M_L_CPU1_SA_DQS_DP<0>")
	)
	(segment
		(start 189.924436 -200.364852)
		(end 190.27902 -200.010268)
		(width 0.16002)
		(layer "In11.Cu")
		(net "M_L_CPU1_SA_DQS_DP<0>")
	)
	(segment
		(start 197.823074 -200.010268)
		(end 199.732646 -200.010268)
		(width 0.16002)
		(layer "In11.Cu")
		(net "M_L_CPU1_SA_DQS_DP<0>")
	)
	(segment
		(start 190.27902 -200.010268)
		(end 192.188592 -200.010268)
		(width 0.16002)
		(layer "In11.Cu")
		(net "M_L_CPU1_SA_DQS_DP<0>")
	)
	(segment
		(start 173.601888 -201.187812)
		(end 174.424848 -200.364852)
		(width 0.16002)
		(layer "In11.Cu")
		(net "M_L_CPU1_SA_DQS_DP<0>")
	)
	(segment
		(start 141.094968 -226.994466)
		(end 141.10335 -226.98964)
		(width 0.09525)
		(layer "In11.Cu")
		(net "M_L_CPU1_SA_DQS_DP<0>")
	)
	(segment
		(start 141.666214 -226.98964)
		(end 141.674596 -226.994466)
		(width 0.09525)
		(layer "In11.Cu")
		(net "M_L_CPU1_SA_DQS_DP<0>")
	)
	(segment
		(start 181.968902 -200.364852)
		(end 182.380382 -200.364852)
		(width 0.16002)
		(layer "In11.Cu")
		(net "M_L_CPU1_SA_DQS_DP<0>")
	)
	(segment
		(start 162.520884 -201.187812)
		(end 166.057834 -201.187812)
		(width 0.16002)
		(layer "In11.Cu")
		(net "M_L_CPU1_SA_DQS_DP<0>")
	)
	(segment
		(start 169.55643 -200.010268)
		(end 170.406314 -200.860152)
		(width 0.16002)
		(layer "In11.Cu")
		(net "M_L_CPU1_SA_DQS_DP<0>")
	)
	(segment
		(start 143.886682 -225.390964)
		(end 143.923258 -225.369628)
		(width 0.09525)
		(layer "In11.Cu")
		(net "M_L_CPU1_SA_DQS_DP<0>")
	)
	(segment
		(start 166.057834 -201.187812)
		(end 166.880794 -200.364852)
		(width 0.16002)
		(layer "In11.Cu")
		(net "M_L_CPU1_SA_DQS_DP<0>")
	)
	(segment
		(start 196.23405 -201.187812)
		(end 197.05701 -200.364852)
		(width 0.16002)
		(layer "In11.Cu")
		(net "M_L_CPU1_SA_DQS_DP<0>")
	)
	(segment
		(start 146.155156 -221.174564)
		(end 146.155156 -217.55354)
		(width 0.16002)
		(layer "In11.Cu")
		(net "M_L_CPU1_SA_DQS_DP<0>")
	)
	(segment
		(start 174.424848 -200.364852)
		(end 174.836328 -200.364852)
		(width 0.16002)
		(layer "In11.Cu")
		(net "M_L_CPU1_SA_DQS_DP<0>")
	)
	(segment
		(start 203.347066 -201.203052)
		(end 203.761594 -201.203052)
		(width 0.16002)
		(layer "In11.Cu")
		(net "M_L_CPU1_SA_DQS_DP<0>")
	)
	(segment
		(start 175.190912 -200.010268)
		(end 177.100484 -200.010268)
		(width 0.16002)
		(layer "In11.Cu")
		(net "M_L_CPU1_SA_DQS_DP<0>")
	)
	(segment
		(start 172.550328 -200.860152)
		(end 172.877988 -201.187812)
		(width 0.16002)
		(layer "In11.Cu")
		(net "M_L_CPU1_SA_DQS_DP<0>")
	)
	(segment
		(start 188.689996 -201.187812)
		(end 189.512956 -200.364852)
		(width 0.16002)
		(layer "In11.Cu")
		(net "M_L_CPU1_SA_DQS_DP<0>")
	)
	(segment
		(start 195.18249 -200.860152)
		(end 195.51015 -201.187812)
		(width 0.16002)
		(layer "In11.Cu")
		(net "M_L_CPU1_SA_DQS_DP<0>")
	)
	(segment
		(start 144.356582 -224.580958)
		(end 144.393158 -224.559622)
		(width 0.09525)
		(layer "In11.Cu")
		(net "M_L_CPU1_SA_DQS_DP<0>")
	)
	(segment
		(start 189.512956 -200.364852)
		(end 189.924436 -200.364852)
		(width 0.16002)
		(layer "In11.Cu")
		(net "M_L_CPU1_SA_DQS_DP<0>")
	)
	(segment
		(start 139.188698 -226.92995)
		(end 139.289536 -226.95662)
		(width 0.09525)
		(layer "In11.Cu")
		(net "M_L_CPU1_SA_DQS_DP<0>")
	)
	(segment
		(start 177.950368 -200.860152)
		(end 180.094382 -200.860152)
		(width 0.16002)
		(layer "In11.Cu")
		(net "M_L_CPU1_SA_DQS_DP<0>")
	)
	(segment
		(start 202.728322 -200.584308)
		(end 203.347066 -201.203052)
		(width 0.16002)
		(layer "In11.Cu")
		(net "M_L_CPU1_SA_DQS_DP<0>")
	)
	(segment
		(start 192.188592 -200.010268)
		(end 193.038476 -200.860152)
		(width 0.16002)
		(layer "In11.Cu")
		(net "M_L_CPU1_SA_DQS_DP<0>")
	)
	(segment
		(start 195.51015 -201.187812)
		(end 196.23405 -201.187812)
		(width 0.16002)
		(layer "In11.Cu")
		(net "M_L_CPU1_SA_DQS_DP<0>")
	)
	(segment
		(start 172.877988 -201.187812)
		(end 173.601888 -201.187812)
		(width 0.16002)
		(layer "In11.Cu")
		(net "M_L_CPU1_SA_DQS_DP<0>")
	)
	(segment
		(start 200.306686 -200.584308)
		(end 202.728322 -200.584308)
		(width 0.16002)
		(layer "In11.Cu")
		(net "M_L_CPU1_SA_DQS_DP<0>")
	)
	(segment
		(start 197.46849 -200.364852)
		(end 197.823074 -200.010268)
		(width 0.16002)
		(layer "In11.Cu")
		(net "M_L_CPU1_SA_DQS_DP<0>")
	)
	(segment
		(start 143.415258 -226.201732)
		(end 143.453358 -226.179634)
		(width 0.09525)
		(layer "In11.Cu")
		(net "M_L_CPU1_SA_DQS_DP<0>")
	)
	(segment
		(start 146.214084 -221.257114)
		(end 146.155156 -221.198186)
		(width 0.09525)
		(layer "In11.Cu")
		(net "M_L_CPU1_SA_DQS_DP<0>")
	)
	(segment
		(start 167.292274 -200.364852)
		(end 167.646858 -200.010268)
		(width 0.16002)
		(layer "In11.Cu")
		(net "M_L_CPU1_SA_DQS_DP<0>")
	)
	(segment
		(start 139.034774 -226.66452)
		(end 139.188698 -226.92995)
		(width 0.09525)
		(layer "In11.Cu")
		(net "M_L_CPU1_SA_DQS_DP<0>")
	)
	(segment
		(start 142.983204 -226.98964)
		(end 143.015716 -226.970844)
		(width 0.09525)
		(layer "In11.Cu")
		(net "M_L_CPU1_SA_DQS_DP<0>")
	)
	(segment
		(start 144.825212 -223.771714)
		(end 144.863312 -223.749616)
		(width 0.09525)
		(layer "In11.Cu")
		(net "M_L_CPU1_SA_DQS_DP<0>")
	)
	(arc
		(start 145.052542 -223.424496)
		(mid 145.117371 -223.162494)
		(end 145.29689 -222.960946)
		(width 0.09525)
		(layer "In11.Cu")
		(net "M_L_CPU1_SA_DQS_DP<0>")
	)
	(arc
		(start 143.172434 -226.66452)
		(mid 143.236831 -226.403214)
		(end 143.415258 -226.201732)
		(width 0.09525)
		(layer "In11.Cu")
		(net "M_L_CPU1_SA_DQS_DP<0>")
	)
	(arc
		(start 140.163296 -226.98964)
		(mid 140.444728 -226.913885)
		(end 140.72616 -226.98964)
		(width 0.09525)
		(layer "In11.Cu")
		(net "M_L_CPU1_SA_DQS_DP<0>")
	)
	(arc
		(start 141.10335 -226.98964)
		(mid 141.384782 -226.913885)
		(end 141.666214 -226.98964)
		(width 0.09525)
		(layer "In11.Cu")
		(net "M_L_CPU1_SA_DQS_DP<0>")
	)
	(arc
		(start 139.786106 -226.98964)
		(mid 139.969881 -227.040412)
		(end 140.154914 -226.994466)
		(width 0.09525)
		(layer "In11.Cu")
		(net "M_L_CPU1_SA_DQS_DP<0>")
	)
	(arc
		(start 143.642334 -225.854514)
		(mid 143.707163 -225.592512)
		(end 143.886682 -225.390964)
		(width 0.09525)
		(layer "In11.Cu")
		(net "M_L_CPU1_SA_DQS_DP<0>")
	)
	(arc
		(start 143.95577 -225.350832)
		(mid 144.071044 -225.216554)
		(end 144.112488 -225.044508)
		(width 0.09525)
		(layer "In11.Cu")
		(net "M_L_CPU1_SA_DQS_DP<0>")
	)
	(arc
		(start 144.895824 -223.73082)
		(mid 145.011098 -223.596542)
		(end 145.052542 -223.424496)
		(width 0.09525)
		(layer "In11.Cu")
		(net "M_L_CPU1_SA_DQS_DP<0>")
	)
	(arc
		(start 144.112488 -225.044508)
		(mid 144.177248 -224.782573)
		(end 144.356582 -224.580958)
		(width 0.09525)
		(layer "In11.Cu")
		(net "M_L_CPU1_SA_DQS_DP<0>")
	)
	(arc
		(start 144.42694 -224.540064)
		(mid 144.541319 -224.405925)
		(end 144.582388 -224.234502)
		(width 0.09525)
		(layer "In11.Cu")
		(net "M_L_CPU1_SA_DQS_DP<0>")
	)
	(arc
		(start 139.289536 -226.95662)
		(mid 139.541677 -226.91505)
		(end 139.786106 -226.98964)
		(width 0.09525)
		(layer "In11.Cu")
		(net "M_L_CPU1_SA_DQS_DP<0>")
	)
	(arc
		(start 144.582388 -224.234502)
		(mid 144.646785 -223.973196)
		(end 144.825212 -223.771714)
		(width 0.09525)
		(layer "In11.Cu")
		(net "M_L_CPU1_SA_DQS_DP<0>")
	)
	(arc
		(start 142.606268 -226.98964)
		(mid 142.794736 -227.040317)
		(end 142.983204 -226.98964)
		(width 0.09525)
		(layer "In11.Cu")
		(net "M_L_CPU1_SA_DQS_DP<0>")
	)
	(arc
		(start 140.72616 -226.98964)
		(mid 140.909935 -227.040412)
		(end 141.094968 -226.994466)
		(width 0.09525)
		(layer "In11.Cu")
		(net "M_L_CPU1_SA_DQS_DP<0>")
	)
	(arc
		(start 145.4785 -222.792798)
		(mid 145.522772 -222.72289)
		(end 145.576798 -222.66021)
		(width 0.09525)
		(layer "In11.Cu")
		(net "M_L_CPU1_SA_DQS_DP<0>")
	)
	(arc
		(start 143.015716 -226.970844)
		(mid 143.13099 -226.836566)
		(end 143.172434 -226.66452)
		(width 0.09525)
		(layer "In11.Cu")
		(net "M_L_CPU1_SA_DQS_DP<0>")
	)
	(arc
		(start 142.043404 -226.98964)
		(mid 142.324836 -226.913885)
		(end 142.606268 -226.98964)
		(width 0.09525)
		(layer "In11.Cu")
		(net "M_L_CPU1_SA_DQS_DP<0>")
	)
	(arc
		(start 143.484854 -226.161346)
		(mid 143.600652 -226.026952)
		(end 143.642334 -225.854514)
		(width 0.09525)
		(layer "In11.Cu")
		(net "M_L_CPU1_SA_DQS_DP<0>")
	)
	(arc
		(start 141.674596 -226.994466)
		(mid 141.859628 -227.04038)
		(end 142.043404 -226.98964)
		(width 0.09525)
		(layer "In11.Cu")
		(net "M_L_CPU1_SA_DQS_DP<0>")
	)
	(arc
		(start 145.36928 -222.919036)
		(mid 145.43096 -222.862031)
		(end 145.4785 -222.792798)
		(width 0.09525)
		(layer "In11.Cu")
		(net "M_L_CPU1_SA_DQS_DP<0>")
	)
	(segment
		(start 137.157968 -247.180354)
		(end 137.62482 -246.914416)
		(width 0.12954)
		(layer "F.Cu")
		(net "M_L_CPU1_SA_DQS_DN<9>")
	)
	(segment
		(start 144.38122 -247.247918)
		(end 144.395698 -247.239536)
		(width 0.09525)
		(layer "In11.Cu")
		(net "M_L_CPU1_SA_DQS_DN<9>")
	)
	(segment
		(start 169.92219 -239.199166)
		(end 170.520868 -239.199166)
		(width 0.16002)
		(layer "In11.Cu")
		(net "M_L_CPU1_SA_DQS_DN<9>")
	)
	(segment
		(start 138.74496 -247.244362)
		(end 138.753342 -247.239536)
		(width 0.09525)
		(layer "In11.Cu")
		(net "M_L_CPU1_SA_DQS_DN<9>")
	)
	(segment
		(start 185.470292 -239.168686)
		(end 186.06897 -239.168686)
		(width 0.16002)
		(layer "In11.Cu")
		(net "M_L_CPU1_SA_DQS_DN<9>")
	)
	(segment
		(start 196.197474 -239.883188)
		(end 197.050914 -239.029748)
		(width 0.16002)
		(layer "In11.Cu")
		(net "M_L_CPU1_SA_DQS_DN<9>")
	)
	(segment
		(start 145.144744 -247.290082)
		(end 146.981926 -247.290082)
		(width 0.09525)
		(layer "In11.Cu")
		(net "M_L_CPU1_SA_DQS_DN<9>")
	)
	(segment
		(start 174.418752 -239.029748)
		(end 175.241204 -239.029748)
		(width 0.16002)
		(layer "In11.Cu")
		(net "M_L_CPU1_SA_DQS_DN<9>")
	)
	(segment
		(start 195.201032 -240.258346)
		(end 195.57619 -239.883188)
		(width 0.16002)
		(layer "In11.Cu")
		(net "M_L_CPU1_SA_DQS_DN<9>")
	)
	(segment
		(start 181.962806 -239.029748)
		(end 182.785258 -239.029748)
		(width 0.16002)
		(layer "In11.Cu")
		(net "M_L_CPU1_SA_DQS_DN<9>")
	)
	(segment
		(start 143.453358 -247.239536)
		(end 143.476726 -247.226074)
		(width 0.09525)
		(layer "In11.Cu")
		(net "M_L_CPU1_SA_DQS_DN<9>")
	)
	(segment
		(start 195.57619 -239.883188)
		(end 196.197474 -239.883188)
		(width 0.16002)
		(layer "In11.Cu")
		(net "M_L_CPU1_SA_DQS_DN<9>")
	)
	(segment
		(start 143.076168 -247.239536)
		(end 143.08455 -247.244362)
		(width 0.09525)
		(layer "In11.Cu")
		(net "M_L_CPU1_SA_DQS_DN<9>")
	)
	(segment
		(start 171.017946 -240.258346)
		(end 172.56887 -240.258346)
		(width 0.16002)
		(layer "In11.Cu")
		(net "M_L_CPU1_SA_DQS_DN<9>")
	)
	(segment
		(start 198.251826 -239.408208)
		(end 199.31253 -239.408208)
		(width 0.16002)
		(layer "In11.Cu")
		(net "M_L_CPU1_SA_DQS_DN<9>")
	)
	(segment
		(start 199.31253 -239.408208)
		(end 199.461374 -239.259364)
		(width 0.16002)
		(layer "In11.Cu")
		(net "M_L_CPU1_SA_DQS_DN<9>")
	)
	(segment
		(start 180.488082 -239.883188)
		(end 181.109366 -239.883188)
		(width 0.16002)
		(layer "In11.Cu")
		(net "M_L_CPU1_SA_DQS_DN<9>")
	)
	(segment
		(start 182.785258 -239.029748)
		(end 183.305196 -239.549686)
		(width 0.16002)
		(layer "In11.Cu")
		(net "M_L_CPU1_SA_DQS_DN<9>")
	)
	(segment
		(start 199.461374 -239.259364)
		(end 201.873866 -239.259364)
		(width 0.16002)
		(layer "In11.Cu")
		(net "M_L_CPU1_SA_DQS_DN<9>")
	)
	(segment
		(start 172.944028 -239.883188)
		(end 173.565312 -239.883188)
		(width 0.16002)
		(layer "In11.Cu")
		(net "M_L_CPU1_SA_DQS_DN<9>")
	)
	(segment
		(start 186.406028 -239.505744)
		(end 186.406028 -240.098326)
		(width 0.16002)
		(layer "In11.Cu")
		(net "M_L_CPU1_SA_DQS_DN<9>")
	)
	(segment
		(start 189.50686 -239.029748)
		(end 190.329312 -239.029748)
		(width 0.16002)
		(layer "In11.Cu")
		(net "M_L_CPU1_SA_DQS_DN<9>")
	)
	(segment
		(start 164.108384 -241.10823)
		(end 166.808404 -241.10823)
		(width 0.16002)
		(layer "In11.Cu")
		(net "M_L_CPU1_SA_DQS_DN<9>")
	)
	(segment
		(start 173.565312 -239.883188)
		(end 174.418752 -239.029748)
		(width 0.16002)
		(layer "In11.Cu")
		(net "M_L_CPU1_SA_DQS_DN<9>")
	)
	(segment
		(start 185.133234 -240.098326)
		(end 185.133234 -239.505744)
		(width 0.16002)
		(layer "In11.Cu")
		(net "M_L_CPU1_SA_DQS_DN<9>")
	)
	(segment
		(start 146.981926 -247.290082)
		(end 147.565364 -247.87352)
		(width 0.09525)
		(layer "In11.Cu")
		(net "M_L_CPU1_SA_DQS_DN<9>")
	)
	(segment
		(start 186.06897 -239.168686)
		(end 186.406028 -239.505744)
		(width 0.16002)
		(layer "In11.Cu")
		(net "M_L_CPU1_SA_DQS_DN<9>")
	)
	(segment
		(start 181.109366 -239.883188)
		(end 181.962806 -239.029748)
		(width 0.16002)
		(layer "In11.Cu")
		(net "M_L_CPU1_SA_DQS_DN<9>")
	)
	(segment
		(start 188.032136 -239.883188)
		(end 188.65342 -239.883188)
		(width 0.16002)
		(layer "In11.Cu")
		(net "M_L_CPU1_SA_DQS_DN<9>")
	)
	(segment
		(start 148.062696 -247.814338)
		(end 148.999448 -246.877586)
		(width 0.16002)
		(layer "In11.Cu")
		(net "M_L_CPU1_SA_DQS_DN<9>")
	)
	(segment
		(start 178.79314 -240.258346)
		(end 180.112924 -240.258346)
		(width 0.16002)
		(layer "In11.Cu")
		(net "M_L_CPU1_SA_DQS_DN<9>")
	)
	(segment
		(start 197.050914 -239.029748)
		(end 197.873366 -239.029748)
		(width 0.16002)
		(layer "In11.Cu")
		(net "M_L_CPU1_SA_DQS_DN<9>")
	)
	(segment
		(start 139.316206 -247.239536)
		(end 139.324588 -247.244362)
		(width 0.09525)
		(layer "In11.Cu")
		(net "M_L_CPU1_SA_DQS_DN<9>")
	)
	(segment
		(start 186.406028 -240.098326)
		(end 186.566048 -240.258346)
		(width 0.16002)
		(layer "In11.Cu")
		(net "M_L_CPU1_SA_DQS_DN<9>")
	)
	(segment
		(start 183.305196 -239.549686)
		(end 183.778398 -239.549686)
		(width 0.16002)
		(layer "In11.Cu")
		(net "M_L_CPU1_SA_DQS_DN<9>")
	)
	(segment
		(start 175.241204 -239.029748)
		(end 175.619664 -239.408208)
		(width 0.16002)
		(layer "In11.Cu")
		(net "M_L_CPU1_SA_DQS_DN<9>")
	)
	(segment
		(start 140.25626 -247.239536)
		(end 140.264642 -247.244362)
		(width 0.09525)
		(layer "In11.Cu")
		(net "M_L_CPU1_SA_DQS_DN<9>")
	)
	(segment
		(start 144.931638 -247.224804)
		(end 144.957038 -247.239536)
		(width 0.09525)
		(layer "In11.Cu")
		(net "M_L_CPU1_SA_DQS_DN<9>")
	)
	(segment
		(start 170.520868 -239.199166)
		(end 170.857926 -239.536224)
		(width 0.16002)
		(layer "In11.Cu")
		(net "M_L_CPU1_SA_DQS_DN<9>")
	)
	(segment
		(start 180.112924 -240.258346)
		(end 180.488082 -239.883188)
		(width 0.16002)
		(layer "In11.Cu")
		(net "M_L_CPU1_SA_DQS_DN<9>")
	)
	(segment
		(start 147.565364 -247.87352)
		(end 147.836382 -247.87352)
		(width 0.09525)
		(layer "In11.Cu")
		(net "M_L_CPU1_SA_DQS_DN<9>")
	)
	(segment
		(start 167.658288 -240.258346)
		(end 169.425112 -240.258346)
		(width 0.16002)
		(layer "In11.Cu")
		(net "M_L_CPU1_SA_DQS_DN<9>")
	)
	(segment
		(start 137.778744 -247.179846)
		(end 137.879582 -247.206516)
		(width 0.09525)
		(layer "In11.Cu")
		(net "M_L_CPU1_SA_DQS_DN<9>")
	)
	(segment
		(start 169.425112 -240.258346)
		(end 169.585132 -240.098326)
		(width 0.16002)
		(layer "In11.Cu")
		(net "M_L_CPU1_SA_DQS_DN<9>")
	)
	(segment
		(start 148.999448 -246.877586)
		(end 158.339028 -246.877586)
		(width 0.16002)
		(layer "In11.Cu")
		(net "M_L_CPU1_SA_DQS_DN<9>")
	)
	(segment
		(start 147.919186 -247.814338)
		(end 148.062696 -247.814338)
		(width 0.16002)
		(layer "In11.Cu")
		(net "M_L_CPU1_SA_DQS_DN<9>")
	)
	(segment
		(start 187.656978 -240.258346)
		(end 188.032136 -239.883188)
		(width 0.16002)
		(layer "In11.Cu")
		(net "M_L_CPU1_SA_DQS_DN<9>")
	)
	(segment
		(start 147.836382 -247.87352)
		(end 147.895564 -247.814338)
		(width 0.09525)
		(layer "In11.Cu")
		(net "M_L_CPU1_SA_DQS_DN<9>")
	)
	(segment
		(start 188.65342 -239.883188)
		(end 189.50686 -239.029748)
		(width 0.16002)
		(layer "In11.Cu")
		(net "M_L_CPU1_SA_DQS_DN<9>")
	)
	(segment
		(start 184.487058 -240.258346)
		(end 184.973214 -240.258346)
		(width 0.16002)
		(layer "In11.Cu")
		(net "M_L_CPU1_SA_DQS_DN<9>")
	)
	(segment
		(start 185.133234 -239.505744)
		(end 185.470292 -239.168686)
		(width 0.16002)
		(layer "In11.Cu")
		(net "M_L_CPU1_SA_DQS_DN<9>")
	)
	(segment
		(start 193.03111 -239.408208)
		(end 193.881248 -240.258346)
		(width 0.16002)
		(layer "In11.Cu")
		(net "M_L_CPU1_SA_DQS_DN<9>")
	)
	(segment
		(start 170.857926 -239.536224)
		(end 170.857926 -240.098326)
		(width 0.16002)
		(layer "In11.Cu")
		(net "M_L_CPU1_SA_DQS_DN<9>")
	)
	(segment
		(start 177.943002 -239.408208)
		(end 178.79314 -240.258346)
		(width 0.16002)
		(layer "In11.Cu")
		(net "M_L_CPU1_SA_DQS_DN<9>")
	)
	(segment
		(start 183.778398 -239.549686)
		(end 184.487058 -240.258346)
		(width 0.16002)
		(layer "In11.Cu")
		(net "M_L_CPU1_SA_DQS_DN<9>")
	)
	(segment
		(start 186.566048 -240.258346)
		(end 187.656978 -240.258346)
		(width 0.16002)
		(layer "In11.Cu")
		(net "M_L_CPU1_SA_DQS_DN<9>")
	)
	(segment
		(start 142.504922 -247.244362)
		(end 142.513304 -247.239536)
		(width 0.09525)
		(layer "In11.Cu")
		(net "M_L_CPU1_SA_DQS_DN<9>")
	)
	(segment
		(start 147.895564 -247.814338)
		(end 147.919186 -247.814338)
		(width 0.09525)
		(layer "In11.Cu")
		(net "M_L_CPU1_SA_DQS_DN<9>")
	)
	(segment
		(start 158.339028 -246.877586)
		(end 164.108384 -241.10823)
		(width 0.16002)
		(layer "In11.Cu")
		(net "M_L_CPU1_SA_DQS_DN<9>")
	)
	(segment
		(start 190.329312 -239.029748)
		(end 190.707772 -239.408208)
		(width 0.16002)
		(layer "In11.Cu")
		(net "M_L_CPU1_SA_DQS_DN<9>")
	)
	(segment
		(start 166.808404 -241.10823)
		(end 167.658288 -240.258346)
		(width 0.16002)
		(layer "In11.Cu")
		(net "M_L_CPU1_SA_DQS_DN<9>")
	)
	(segment
		(start 193.881248 -240.258346)
		(end 195.201032 -240.258346)
		(width 0.16002)
		(layer "In11.Cu")
		(net "M_L_CPU1_SA_DQS_DN<9>")
	)
	(segment
		(start 172.56887 -240.258346)
		(end 172.944028 -239.883188)
		(width 0.16002)
		(layer "In11.Cu")
		(net "M_L_CPU1_SA_DQS_DN<9>")
	)
	(segment
		(start 137.62482 -246.914416)
		(end 137.778744 -247.179846)
		(width 0.09525)
		(layer "In11.Cu")
		(net "M_L_CPU1_SA_DQS_DN<9>")
	)
	(segment
		(start 190.707772 -239.408208)
		(end 193.03111 -239.408208)
		(width 0.16002)
		(layer "In11.Cu")
		(net "M_L_CPU1_SA_DQS_DN<9>")
	)
	(segment
		(start 184.973214 -240.258346)
		(end 185.133234 -240.098326)
		(width 0.16002)
		(layer "In11.Cu")
		(net "M_L_CPU1_SA_DQS_DN<9>")
	)
	(segment
		(start 201.873866 -239.259364)
		(end 202.147932 -238.985298)
		(width 0.16002)
		(layer "In11.Cu")
		(net "M_L_CPU1_SA_DQS_DN<9>")
	)
	(segment
		(start 170.857926 -240.098326)
		(end 171.017946 -240.258346)
		(width 0.16002)
		(layer "In11.Cu")
		(net "M_L_CPU1_SA_DQS_DN<9>")
	)
	(segment
		(start 197.873366 -239.029748)
		(end 198.251826 -239.408208)
		(width 0.16002)
		(layer "In11.Cu")
		(net "M_L_CPU1_SA_DQS_DN<9>")
	)
	(segment
		(start 169.585132 -240.098326)
		(end 169.585132 -239.536224)
		(width 0.16002)
		(layer "In11.Cu")
		(net "M_L_CPU1_SA_DQS_DN<9>")
	)
	(segment
		(start 169.585132 -239.536224)
		(end 169.92219 -239.199166)
		(width 0.16002)
		(layer "In11.Cu")
		(net "M_L_CPU1_SA_DQS_DN<9>")
	)
	(segment
		(start 175.619664 -239.408208)
		(end 177.943002 -239.408208)
		(width 0.16002)
		(layer "In11.Cu")
		(net "M_L_CPU1_SA_DQS_DN<9>")
	)
	(arc
		(start 139.324588 -247.244362)
		(mid 139.50962 -247.290276)
		(end 139.693396 -247.239536)
		(width 0.09525)
		(layer "In11.Cu")
		(net "M_L_CPU1_SA_DQS_DN<9>")
	)
	(arc
		(start 142.513304 -247.239536)
		(mid 142.794736 -247.163781)
		(end 143.076168 -247.239536)
		(width 0.09525)
		(layer "In11.Cu")
		(net "M_L_CPU1_SA_DQS_DN<9>")
	)
	(arc
		(start 138.376152 -247.239536)
		(mid 138.559927 -247.290308)
		(end 138.74496 -247.244362)
		(width 0.09525)
		(layer "In11.Cu")
		(net "M_L_CPU1_SA_DQS_DN<9>")
	)
	(arc
		(start 139.693396 -247.239536)
		(mid 139.974828 -247.163781)
		(end 140.25626 -247.239536)
		(width 0.09525)
		(layer "In11.Cu")
		(net "M_L_CPU1_SA_DQS_DN<9>")
	)
	(arc
		(start 143.476726 -247.226074)
		(mid 143.748827 -247.163396)
		(end 144.017492 -247.239536)
		(width 0.09525)
		(layer "In11.Cu")
		(net "M_L_CPU1_SA_DQS_DN<9>")
	)
	(arc
		(start 140.63345 -247.239536)
		(mid 140.914882 -247.163781)
		(end 141.196314 -247.239536)
		(width 0.09525)
		(layer "In11.Cu")
		(net "M_L_CPU1_SA_DQS_DN<9>")
	)
	(arc
		(start 141.57325 -247.239536)
		(mid 141.854682 -247.163781)
		(end 142.136114 -247.239536)
		(width 0.09525)
		(layer "In11.Cu")
		(net "M_L_CPU1_SA_DQS_DN<9>")
	)
	(arc
		(start 138.753342 -247.239536)
		(mid 139.034774 -247.163781)
		(end 139.316206 -247.239536)
		(width 0.09525)
		(layer "In11.Cu")
		(net "M_L_CPU1_SA_DQS_DN<9>")
	)
	(arc
		(start 141.196314 -247.239536)
		(mid 141.384782 -247.290213)
		(end 141.57325 -247.239536)
		(width 0.09525)
		(layer "In11.Cu")
		(net "M_L_CPU1_SA_DQS_DN<9>")
	)
	(arc
		(start 143.08455 -247.244362)
		(mid 143.269582 -247.290276)
		(end 143.453358 -247.239536)
		(width 0.09525)
		(layer "In11.Cu")
		(net "M_L_CPU1_SA_DQS_DN<9>")
	)
	(arc
		(start 142.136114 -247.239536)
		(mid 142.319889 -247.290308)
		(end 142.504922 -247.244362)
		(width 0.09525)
		(layer "In11.Cu")
		(net "M_L_CPU1_SA_DQS_DN<9>")
	)
	(arc
		(start 137.879582 -247.206516)
		(mid 138.131723 -247.164946)
		(end 138.376152 -247.239536)
		(width 0.09525)
		(layer "In11.Cu")
		(net "M_L_CPU1_SA_DQS_DN<9>")
	)
	(arc
		(start 144.017492 -247.239536)
		(mid 144.198279 -247.290623)
		(end 144.38122 -247.247918)
		(width 0.09525)
		(layer "In11.Cu")
		(net "M_L_CPU1_SA_DQS_DN<9>")
	)
	(arc
		(start 144.395698 -247.239536)
		(mid 144.661785 -247.163991)
		(end 144.931638 -247.224804)
		(width 0.09525)
		(layer "In11.Cu")
		(net "M_L_CPU1_SA_DQS_DN<9>")
	)
	(arc
		(start 144.957038 -247.239536)
		(mid 145.047565 -247.277162)
		(end 145.144744 -247.290082)
		(width 0.09525)
		(layer "In11.Cu")
		(net "M_L_CPU1_SA_DQS_DN<9>")
	)
	(arc
		(start 140.264642 -247.244362)
		(mid 140.449674 -247.290276)
		(end 140.63345 -247.239536)
		(width 0.09525)
		(layer "In11.Cu")
		(net "M_L_CPU1_SA_DQS_DN<9>")
	)
	(segment
		(start 137.157968 -242.320318)
		(end 137.62482 -242.05438)
		(width 0.12954)
		(layer "F.Cu")
		(net "M_L_CPU1_SA_DQS_DN<8>")
	)
	(segment
		(start 186.572398 -230.908352)
		(end 187.656978 -230.908352)
		(width 0.16002)
		(layer "In11.Cu")
		(net "M_L_CPU1_SA_DQS_DN<8>")
	)
	(segment
		(start 143.076168 -242.3795)
		(end 143.08455 -242.384326)
		(width 0.09525)
		(layer "In11.Cu")
		(net "M_L_CPU1_SA_DQS_DN<8>")
	)
	(segment
		(start 189.50686 -229.679754)
		(end 190.329312 -229.679754)
		(width 0.16002)
		(layer "In11.Cu")
		(net "M_L_CPU1_SA_DQS_DN<8>")
	)
	(segment
		(start 144.385284 -242.384326)
		(end 144.393666 -242.3795)
		(width 0.09525)
		(layer "In11.Cu")
		(net "M_L_CPU1_SA_DQS_DN<8>")
	)
	(segment
		(start 172.56887 -230.908352)
		(end 172.944028 -230.533194)
		(width 0.16002)
		(layer "In11.Cu")
		(net "M_L_CPU1_SA_DQS_DN<8>")
	)
	(segment
		(start 167.418766 -229.679754)
		(end 168.116758 -230.377746)
		(width 0.16002)
		(layer "In11.Cu")
		(net "M_L_CPU1_SA_DQS_DN<8>")
	)
	(segment
		(start 147.895564 -241.281204)
		(end 147.919186 -241.281204)
		(width 0.09525)
		(layer "In11.Cu")
		(net "M_L_CPU1_SA_DQS_DN<8>")
	)
	(segment
		(start 181.962806 -229.679754)
		(end 182.785258 -229.679754)
		(width 0.16002)
		(layer "In11.Cu")
		(net "M_L_CPU1_SA_DQS_DN<8>")
	)
	(segment
		(start 201.873866 -229.90937)
		(end 202.147932 -229.635304)
		(width 0.16002)
		(layer "In11.Cu")
		(net "M_L_CPU1_SA_DQS_DN<8>")
	)
	(segment
		(start 175.619664 -230.058214)
		(end 178.331114 -230.058214)
		(width 0.16002)
		(layer "In11.Cu")
		(net "M_L_CPU1_SA_DQS_DN<8>")
	)
	(segment
		(start 169.668698 -229.664006)
		(end 170.005756 -230.001064)
		(width 0.16002)
		(layer "In11.Cu")
		(net "M_L_CPU1_SA_DQS_DN<8>")
	)
	(segment
		(start 145.144744 -242.430808)
		(end 146.388328 -242.430808)
		(width 0.09525)
		(layer "In11.Cu")
		(net "M_L_CPU1_SA_DQS_DN<8>")
	)
	(segment
		(start 193.03111 -230.058214)
		(end 193.881248 -230.908352)
		(width 0.16002)
		(layer "In11.Cu")
		(net "M_L_CPU1_SA_DQS_DN<8>")
	)
	(segment
		(start 197.873366 -229.679754)
		(end 198.251826 -230.058214)
		(width 0.16002)
		(layer "In11.Cu")
		(net "M_L_CPU1_SA_DQS_DN<8>")
	)
	(segment
		(start 137.62482 -242.05438)
		(end 137.778744 -242.31981)
		(width 0.09525)
		(layer "In11.Cu")
		(net "M_L_CPU1_SA_DQS_DN<8>")
	)
	(segment
		(start 156.802328 -239.201706)
		(end 156.49829 -238.897668)
		(width 0.16002)
		(layer "In11.Cu")
		(net "M_L_CPU1_SA_DQS_DN<8>")
	)
	(segment
		(start 156.49829 -238.421164)
		(end 164.38626 -230.533194)
		(width 0.16002)
		(layer "In11.Cu")
		(net "M_L_CPU1_SA_DQS_DN<8>")
	)
	(segment
		(start 155.121864 -240.274094)
		(end 155.121864 -239.79759)
		(width 0.16002)
		(layer "In11.Cu")
		(net "M_L_CPU1_SA_DQS_DN<8>")
	)
	(segment
		(start 170.005756 -230.001064)
		(end 170.005756 -230.217726)
		(width 0.16002)
		(layer "In11.Cu")
		(net "M_L_CPU1_SA_DQS_DN<8>")
	)
	(segment
		(start 155.177236 -241.052858)
		(end 155.425902 -240.804192)
		(width 0.16002)
		(layer "In11.Cu")
		(net "M_L_CPU1_SA_DQS_DN<8>")
	)
	(segment
		(start 169.07002 -229.664006)
		(end 169.668698 -229.664006)
		(width 0.16002)
		(layer "In11.Cu")
		(net "M_L_CPU1_SA_DQS_DN<8>")
	)
	(segment
		(start 156.023564 -239.372394)
		(end 156.327602 -239.676432)
		(width 0.16002)
		(layer "In11.Cu")
		(net "M_L_CPU1_SA_DQS_DN<8>")
	)
	(segment
		(start 154.170634 -240.74882)
		(end 154.647138 -240.74882)
		(width 0.16002)
		(layer "In11.Cu")
		(net "M_L_CPU1_SA_DQS_DN<8>")
	)
	(segment
		(start 193.881248 -230.908352)
		(end 195.201032 -230.908352)
		(width 0.16002)
		(layer "In11.Cu")
		(net "M_L_CPU1_SA_DQS_DN<8>")
	)
	(segment
		(start 144.945862 -242.373404)
		(end 144.956276 -242.3795)
		(width 0.09525)
		(layer "In11.Cu")
		(net "M_L_CPU1_SA_DQS_DN<8>")
	)
	(segment
		(start 140.25626 -242.3795)
		(end 140.264642 -242.384326)
		(width 0.09525)
		(layer "In11.Cu")
		(net "M_L_CPU1_SA_DQS_DN<8>")
	)
	(segment
		(start 197.050914 -229.679754)
		(end 197.873366 -229.679754)
		(width 0.16002)
		(layer "In11.Cu")
		(net "M_L_CPU1_SA_DQS_DN<8>")
	)
	(segment
		(start 188.032136 -230.533194)
		(end 188.65342 -230.533194)
		(width 0.16002)
		(layer "In11.Cu")
		(net "M_L_CPU1_SA_DQS_DN<8>")
	)
	(segment
		(start 137.778744 -242.31981)
		(end 137.879582 -242.34648)
		(width 0.09525)
		(layer "In11.Cu")
		(net "M_L_CPU1_SA_DQS_DN<8>")
	)
	(segment
		(start 187.656978 -230.908352)
		(end 188.032136 -230.533194)
		(width 0.16002)
		(layer "In11.Cu")
		(net "M_L_CPU1_SA_DQS_DN<8>")
	)
	(segment
		(start 172.944028 -230.533194)
		(end 173.565312 -230.533194)
		(width 0.16002)
		(layer "In11.Cu")
		(net "M_L_CPU1_SA_DQS_DN<8>")
	)
	(segment
		(start 168.732962 -230.217726)
		(end 168.732962 -230.001064)
		(width 0.16002)
		(layer "In11.Cu")
		(net "M_L_CPU1_SA_DQS_DN<8>")
	)
	(segment
		(start 155.425902 -240.578132)
		(end 155.121864 -240.274094)
		(width 0.16002)
		(layer "In11.Cu")
		(net "M_L_CPU1_SA_DQS_DN<8>")
	)
	(segment
		(start 155.54706 -239.372394)
		(end 156.023564 -239.372394)
		(width 0.16002)
		(layer "In11.Cu")
		(net "M_L_CPU1_SA_DQS_DN<8>")
	)
	(segment
		(start 138.74496 -242.384326)
		(end 138.753342 -242.3795)
		(width 0.09525)
		(layer "In11.Cu")
		(net "M_L_CPU1_SA_DQS_DN<8>")
	)
	(segment
		(start 143.453358 -242.3795)
		(end 143.463772 -242.373404)
		(width 0.09525)
		(layer "In11.Cu")
		(net "M_L_CPU1_SA_DQS_DN<8>")
	)
	(segment
		(start 154.647138 -240.74882)
		(end 154.951176 -241.052858)
		(width 0.16002)
		(layer "In11.Cu")
		(net "M_L_CPU1_SA_DQS_DN<8>")
	)
	(segment
		(start 199.31253 -230.058214)
		(end 199.461374 -229.90937)
		(width 0.16002)
		(layer "In11.Cu")
		(net "M_L_CPU1_SA_DQS_DN<8>")
	)
	(segment
		(start 147.919186 -241.281204)
		(end 153.63825 -241.281204)
		(width 0.16002)
		(layer "In11.Cu")
		(net "M_L_CPU1_SA_DQS_DN<8>")
	)
	(segment
		(start 195.57619 -230.533194)
		(end 196.197474 -230.533194)
		(width 0.16002)
		(layer "In11.Cu")
		(net "M_L_CPU1_SA_DQS_DN<8>")
	)
	(segment
		(start 181.109366 -230.533194)
		(end 181.962806 -229.679754)
		(width 0.16002)
		(layer "In11.Cu")
		(net "M_L_CPU1_SA_DQS_DN<8>")
	)
	(segment
		(start 190.329312 -229.679754)
		(end 190.707772 -230.058214)
		(width 0.16002)
		(layer "In11.Cu")
		(net "M_L_CPU1_SA_DQS_DN<8>")
	)
	(segment
		(start 190.707772 -230.058214)
		(end 193.03111 -230.058214)
		(width 0.16002)
		(layer "In11.Cu")
		(net "M_L_CPU1_SA_DQS_DN<8>")
	)
	(segment
		(start 147.836382 -241.340386)
		(end 147.895564 -241.281204)
		(width 0.09525)
		(layer "In11.Cu")
		(net "M_L_CPU1_SA_DQS_DN<8>")
	)
	(segment
		(start 153.63825 -241.281204)
		(end 154.170634 -240.74882)
		(width 0.16002)
		(layer "In11.Cu")
		(net "M_L_CPU1_SA_DQS_DN<8>")
	)
	(segment
		(start 198.251826 -230.058214)
		(end 199.31253 -230.058214)
		(width 0.16002)
		(layer "In11.Cu")
		(net "M_L_CPU1_SA_DQS_DN<8>")
	)
	(segment
		(start 166.874698 -229.679754)
		(end 167.418766 -229.679754)
		(width 0.16002)
		(layer "In11.Cu")
		(net "M_L_CPU1_SA_DQS_DN<8>")
	)
	(segment
		(start 146.388328 -242.430808)
		(end 147.47875 -241.340386)
		(width 0.09525)
		(layer "In11.Cu")
		(net "M_L_CPU1_SA_DQS_DN<8>")
	)
	(segment
		(start 199.461374 -229.90937)
		(end 201.873866 -229.90937)
		(width 0.16002)
		(layer "In11.Cu")
		(net "M_L_CPU1_SA_DQS_DN<8>")
	)
	(segment
		(start 170.165776 -230.377746)
		(end 170.984672 -230.377746)
		(width 0.16002)
		(layer "In11.Cu")
		(net "M_L_CPU1_SA_DQS_DN<8>")
	)
	(segment
		(start 179.181252 -230.908352)
		(end 180.112924 -230.908352)
		(width 0.16002)
		(layer "In11.Cu")
		(net "M_L_CPU1_SA_DQS_DN<8>")
	)
	(segment
		(start 180.112924 -230.908352)
		(end 180.488082 -230.533194)
		(width 0.16002)
		(layer "In11.Cu")
		(net "M_L_CPU1_SA_DQS_DN<8>")
	)
	(segment
		(start 168.116758 -230.377746)
		(end 168.572942 -230.377746)
		(width 0.16002)
		(layer "In11.Cu")
		(net "M_L_CPU1_SA_DQS_DN<8>")
	)
	(segment
		(start 170.984672 -230.377746)
		(end 171.515278 -230.908352)
		(width 0.16002)
		(layer "In11.Cu")
		(net "M_L_CPU1_SA_DQS_DN<8>")
	)
	(segment
		(start 196.197474 -230.533194)
		(end 197.050914 -229.679754)
		(width 0.16002)
		(layer "In11.Cu")
		(net "M_L_CPU1_SA_DQS_DN<8>")
	)
	(segment
		(start 195.201032 -230.908352)
		(end 195.57619 -230.533194)
		(width 0.16002)
		(layer "In11.Cu")
		(net "M_L_CPU1_SA_DQS_DN<8>")
	)
	(segment
		(start 147.47875 -241.340386)
		(end 147.836382 -241.340386)
		(width 0.09525)
		(layer "In11.Cu")
		(net "M_L_CPU1_SA_DQS_DN<8>")
	)
	(segment
		(start 156.49829 -238.897668)
		(end 156.49829 -238.421164)
		(width 0.16002)
		(layer "In11.Cu")
		(net "M_L_CPU1_SA_DQS_DN<8>")
	)
	(segment
		(start 183.163718 -230.058214)
		(end 185.72226 -230.058214)
		(width 0.16002)
		(layer "In11.Cu")
		(net "M_L_CPU1_SA_DQS_DN<8>")
	)
	(segment
		(start 173.565312 -230.533194)
		(end 174.418752 -229.679754)
		(width 0.16002)
		(layer "In11.Cu")
		(net "M_L_CPU1_SA_DQS_DN<8>")
	)
	(segment
		(start 168.572942 -230.377746)
		(end 168.732962 -230.217726)
		(width 0.16002)
		(layer "In11.Cu")
		(net "M_L_CPU1_SA_DQS_DN<8>")
	)
	(segment
		(start 171.515278 -230.908352)
		(end 172.56887 -230.908352)
		(width 0.16002)
		(layer "In11.Cu")
		(net "M_L_CPU1_SA_DQS_DN<8>")
	)
	(segment
		(start 174.418752 -229.679754)
		(end 175.241204 -229.679754)
		(width 0.16002)
		(layer "In11.Cu")
		(net "M_L_CPU1_SA_DQS_DN<8>")
	)
	(segment
		(start 188.65342 -230.533194)
		(end 189.50686 -229.679754)
		(width 0.16002)
		(layer "In11.Cu")
		(net "M_L_CPU1_SA_DQS_DN<8>")
	)
	(segment
		(start 155.425902 -240.804192)
		(end 155.425902 -240.578132)
		(width 0.16002)
		(layer "In11.Cu")
		(net "M_L_CPU1_SA_DQS_DN<8>")
	)
	(segment
		(start 156.802328 -239.427766)
		(end 156.802328 -239.201706)
		(width 0.16002)
		(layer "In11.Cu")
		(net "M_L_CPU1_SA_DQS_DN<8>")
	)
	(segment
		(start 155.121864 -239.79759)
		(end 155.54706 -239.372394)
		(width 0.16002)
		(layer "In11.Cu")
		(net "M_L_CPU1_SA_DQS_DN<8>")
	)
	(segment
		(start 175.241204 -229.679754)
		(end 175.619664 -230.058214)
		(width 0.16002)
		(layer "In11.Cu")
		(net "M_L_CPU1_SA_DQS_DN<8>")
	)
	(segment
		(start 139.316206 -242.3795)
		(end 139.324588 -242.384326)
		(width 0.09525)
		(layer "In11.Cu")
		(net "M_L_CPU1_SA_DQS_DN<8>")
	)
	(segment
		(start 154.951176 -241.052858)
		(end 155.177236 -241.052858)
		(width 0.16002)
		(layer "In11.Cu")
		(net "M_L_CPU1_SA_DQS_DN<8>")
	)
	(segment
		(start 156.327602 -239.676432)
		(end 156.553662 -239.676432)
		(width 0.16002)
		(layer "In11.Cu")
		(net "M_L_CPU1_SA_DQS_DN<8>")
	)
	(segment
		(start 164.38626 -230.533194)
		(end 166.021258 -230.533194)
		(width 0.16002)
		(layer "In11.Cu")
		(net "M_L_CPU1_SA_DQS_DN<8>")
	)
	(segment
		(start 168.732962 -230.001064)
		(end 169.07002 -229.664006)
		(width 0.16002)
		(layer "In11.Cu")
		(net "M_L_CPU1_SA_DQS_DN<8>")
	)
	(segment
		(start 178.331114 -230.058214)
		(end 179.181252 -230.908352)
		(width 0.16002)
		(layer "In11.Cu")
		(net "M_L_CPU1_SA_DQS_DN<8>")
	)
	(segment
		(start 156.553662 -239.676432)
		(end 156.802328 -239.427766)
		(width 0.16002)
		(layer "In11.Cu")
		(net "M_L_CPU1_SA_DQS_DN<8>")
	)
	(segment
		(start 180.488082 -230.533194)
		(end 181.109366 -230.533194)
		(width 0.16002)
		(layer "In11.Cu")
		(net "M_L_CPU1_SA_DQS_DN<8>")
	)
	(segment
		(start 182.785258 -229.679754)
		(end 183.163718 -230.058214)
		(width 0.16002)
		(layer "In11.Cu")
		(net "M_L_CPU1_SA_DQS_DN<8>")
	)
	(segment
		(start 166.021258 -230.533194)
		(end 166.874698 -229.679754)
		(width 0.16002)
		(layer "In11.Cu")
		(net "M_L_CPU1_SA_DQS_DN<8>")
	)
	(segment
		(start 170.005756 -230.217726)
		(end 170.165776 -230.377746)
		(width 0.16002)
		(layer "In11.Cu")
		(net "M_L_CPU1_SA_DQS_DN<8>")
	)
	(segment
		(start 185.72226 -230.058214)
		(end 186.572398 -230.908352)
		(width 0.16002)
		(layer "In11.Cu")
		(net "M_L_CPU1_SA_DQS_DN<8>")
	)
	(segment
		(start 142.504922 -242.384326)
		(end 142.513304 -242.3795)
		(width 0.09525)
		(layer "In11.Cu")
		(net "M_L_CPU1_SA_DQS_DN<8>")
	)
	(arc
		(start 138.376152 -242.3795)
		(mid 138.559927 -242.430272)
		(end 138.74496 -242.384326)
		(width 0.09525)
		(layer "In11.Cu")
		(net "M_L_CPU1_SA_DQS_DN<8>")
	)
	(arc
		(start 139.693396 -242.3795)
		(mid 139.974828 -242.303745)
		(end 140.25626 -242.3795)
		(width 0.09525)
		(layer "In11.Cu")
		(net "M_L_CPU1_SA_DQS_DN<8>")
	)
	(arc
		(start 143.08455 -242.384326)
		(mid 143.269582 -242.43024)
		(end 143.453358 -242.3795)
		(width 0.09525)
		(layer "In11.Cu")
		(net "M_L_CPU1_SA_DQS_DN<8>")
	)
	(arc
		(start 139.324588 -242.384326)
		(mid 139.50962 -242.43024)
		(end 139.693396 -242.3795)
		(width 0.09525)
		(layer "In11.Cu")
		(net "M_L_CPU1_SA_DQS_DN<8>")
	)
	(arc
		(start 142.513304 -242.3795)
		(mid 142.794736 -242.303745)
		(end 143.076168 -242.3795)
		(width 0.09525)
		(layer "In11.Cu")
		(net "M_L_CPU1_SA_DQS_DN<8>")
	)
	(arc
		(start 140.264642 -242.384326)
		(mid 140.449674 -242.43024)
		(end 140.63345 -242.3795)
		(width 0.09525)
		(layer "In11.Cu")
		(net "M_L_CPU1_SA_DQS_DN<8>")
	)
	(arc
		(start 137.879582 -242.34648)
		(mid 138.131723 -242.30491)
		(end 138.376152 -242.3795)
		(width 0.09525)
		(layer "In11.Cu")
		(net "M_L_CPU1_SA_DQS_DN<8>")
	)
	(arc
		(start 143.463772 -242.373404)
		(mid 143.740934 -242.303604)
		(end 144.016476 -242.3795)
		(width 0.09525)
		(layer "In11.Cu")
		(net "M_L_CPU1_SA_DQS_DN<8>")
	)
	(arc
		(start 140.63345 -242.3795)
		(mid 140.914882 -242.303745)
		(end 141.196314 -242.3795)
		(width 0.09525)
		(layer "In11.Cu")
		(net "M_L_CPU1_SA_DQS_DN<8>")
	)
	(arc
		(start 144.393666 -242.3795)
		(mid 144.668955 -242.303779)
		(end 144.945862 -242.373404)
		(width 0.09525)
		(layer "In11.Cu")
		(net "M_L_CPU1_SA_DQS_DN<8>")
	)
	(arc
		(start 144.016476 -242.3795)
		(mid 144.200251 -242.430272)
		(end 144.385284 -242.384326)
		(width 0.09525)
		(layer "In11.Cu")
		(net "M_L_CPU1_SA_DQS_DN<8>")
	)
	(arc
		(start 141.57325 -242.3795)
		(mid 141.854682 -242.303745)
		(end 142.136114 -242.3795)
		(width 0.09525)
		(layer "In11.Cu")
		(net "M_L_CPU1_SA_DQS_DN<8>")
	)
	(arc
		(start 141.196314 -242.3795)
		(mid 141.384782 -242.430177)
		(end 141.57325 -242.3795)
		(width 0.09525)
		(layer "In11.Cu")
		(net "M_L_CPU1_SA_DQS_DN<8>")
	)
	(arc
		(start 138.753342 -242.3795)
		(mid 139.034774 -242.303745)
		(end 139.316206 -242.3795)
		(width 0.09525)
		(layer "In11.Cu")
		(net "M_L_CPU1_SA_DQS_DN<8>")
	)
	(arc
		(start 142.136114 -242.3795)
		(mid 142.319889 -242.430272)
		(end 142.504922 -242.384326)
		(width 0.09525)
		(layer "In11.Cu")
		(net "M_L_CPU1_SA_DQS_DN<8>")
	)
	(arc
		(start 144.956276 -242.3795)
		(mid 145.047119 -242.417619)
		(end 145.144744 -242.430808)
		(width 0.09525)
		(layer "In11.Cu")
		(net "M_L_CPU1_SA_DQS_DN<8>")
	)
	(segment
		(start 137.157968 -237.460282)
		(end 137.62482 -237.194344)
		(width 0.12954)
		(layer "F.Cu")
		(net "M_L_CPU1_SA_DQS_DN<7>")
	)
	(segment
		(start 147.591018 -235.703618)
		(end 147.817586 -235.703618)
		(width 0.09525)
		(layer "In11.Cu")
		(net "M_L_CPU1_SA_DQS_DN<7>")
	)
	(segment
		(start 185.73496 -220.70822)
		(end 186.585098 -221.558358)
		(width 0.16002)
		(layer "In11.Cu")
		(net "M_L_CPU1_SA_DQS_DN<7>")
	)
	(segment
		(start 201.873866 -220.559376)
		(end 202.147932 -220.28531)
		(width 0.16002)
		(layer "In11.Cu")
		(net "M_L_CPU1_SA_DQS_DN<7>")
	)
	(segment
		(start 157.587188 -227.766626)
		(end 158.163768 -227.766626)
		(width 0.16002)
		(layer "In11.Cu")
		(net "M_L_CPU1_SA_DQS_DN<7>")
	)
	(segment
		(start 169.427144 -220.575886)
		(end 170.519598 -220.575886)
		(width 0.16002)
		(layer "In11.Cu")
		(net "M_L_CPU1_SA_DQS_DN<7>")
	)
	(segment
		(start 162.595052 -223.335342)
		(end 162.595052 -222.758762)
		(width 0.16002)
		(layer "In11.Cu")
		(net "M_L_CPU1_SA_DQS_DN<7>")
	)
	(segment
		(start 189.50686 -220.32976)
		(end 190.329312 -220.32976)
		(width 0.16002)
		(layer "In11.Cu")
		(net "M_L_CPU1_SA_DQS_DN<7>")
	)
	(segment
		(start 182.785258 -220.32976)
		(end 183.163718 -220.70822)
		(width 0.16002)
		(layer "In11.Cu")
		(net "M_L_CPU1_SA_DQS_DN<7>")
	)
	(segment
		(start 174.418752 -220.32976)
		(end 175.241204 -220.32976)
		(width 0.16002)
		(layer "In11.Cu")
		(net "M_L_CPU1_SA_DQS_DN<7>")
	)
	(segment
		(start 160.334452 -225.019362)
		(end 160.911032 -225.019362)
		(width 0.16002)
		(layer "In11.Cu")
		(net "M_L_CPU1_SA_DQS_DN<7>")
	)
	(segment
		(start 175.619664 -220.70822)
		(end 178.322986 -220.70822)
		(width 0.16002)
		(layer "In11.Cu")
		(net "M_L_CPU1_SA_DQS_DN<7>")
	)
	(segment
		(start 199.461374 -220.559376)
		(end 201.873866 -220.559376)
		(width 0.16002)
		(layer "In11.Cu")
		(net "M_L_CPU1_SA_DQS_DN<7>")
	)
	(segment
		(start 168.550844 -219.699586)
		(end 169.427144 -220.575886)
		(width 0.16002)
		(layer "In11.Cu")
		(net "M_L_CPU1_SA_DQS_DN<7>")
	)
	(segment
		(start 181.962806 -220.32976)
		(end 182.785258 -220.32976)
		(width 0.16002)
		(layer "In11.Cu")
		(net "M_L_CPU1_SA_DQS_DN<7>")
	)
	(segment
		(start 146.64817 -237.266226)
		(end 147.18411 -236.730286)
		(width 0.09525)
		(layer "In11.Cu")
		(net "M_L_CPU1_SA_DQS_DN<7>")
	)
	(segment
		(start 173.565312 -221.1832)
		(end 174.418752 -220.32976)
		(width 0.16002)
		(layer "In11.Cu")
		(net "M_L_CPU1_SA_DQS_DN<7>")
	)
	(segment
		(start 158.96082 -226.392994)
		(end 159.5374 -226.392994)
		(width 0.16002)
		(layer "In11.Cu")
		(net "M_L_CPU1_SA_DQS_DN<7>")
	)
	(segment
		(start 147.90039 -235.644436)
		(end 149.709378 -235.644436)
		(width 0.16002)
		(layer "In11.Cu")
		(net "M_L_CPU1_SA_DQS_DN<7>")
	)
	(segment
		(start 149.709378 -235.644436)
		(end 157.587188 -227.766626)
		(width 0.16002)
		(layer "In11.Cu")
		(net "M_L_CPU1_SA_DQS_DN<7>")
	)
	(segment
		(start 161.22142 -224.708974)
		(end 161.22142 -224.132394)
		(width 0.16002)
		(layer "In11.Cu")
		(net "M_L_CPU1_SA_DQS_DN<7>")
	)
	(segment
		(start 158.474156 -226.879658)
		(end 158.96082 -226.392994)
		(width 0.16002)
		(layer "In11.Cu")
		(net "M_L_CPU1_SA_DQS_DN<7>")
	)
	(segment
		(start 181.109366 -221.1832)
		(end 181.962806 -220.32976)
		(width 0.16002)
		(layer "In11.Cu")
		(net "M_L_CPU1_SA_DQS_DN<7>")
	)
	(segment
		(start 166.021258 -221.1832)
		(end 166.874698 -220.32976)
		(width 0.16002)
		(layer "In11.Cu")
		(net "M_L_CPU1_SA_DQS_DN<7>")
	)
	(segment
		(start 143.453358 -237.519464)
		(end 143.476726 -237.506002)
		(width 0.09525)
		(layer "In11.Cu")
		(net "M_L_CPU1_SA_DQS_DN<7>")
	)
	(segment
		(start 147.817586 -235.703618)
		(end 147.876768 -235.644436)
		(width 0.09525)
		(layer "In11.Cu")
		(net "M_L_CPU1_SA_DQS_DN<7>")
	)
	(segment
		(start 167.375586 -220.32976)
		(end 168.00576 -219.699586)
		(width 0.16002)
		(layer "In11.Cu")
		(net "M_L_CPU1_SA_DQS_DN<7>")
	)
	(segment
		(start 147.876768 -235.644436)
		(end 147.90039 -235.644436)
		(width 0.09525)
		(layer "In11.Cu")
		(net "M_L_CPU1_SA_DQS_DN<7>")
	)
	(segment
		(start 188.65342 -221.1832)
		(end 189.50686 -220.32976)
		(width 0.16002)
		(layer "In11.Cu")
		(net "M_L_CPU1_SA_DQS_DN<7>")
	)
	(segment
		(start 158.163768 -227.766626)
		(end 158.474156 -227.456238)
		(width 0.16002)
		(layer "In11.Cu")
		(net "M_L_CPU1_SA_DQS_DN<7>")
	)
	(segment
		(start 162.284664 -223.64573)
		(end 162.595052 -223.335342)
		(width 0.16002)
		(layer "In11.Cu")
		(net "M_L_CPU1_SA_DQS_DN<7>")
	)
	(segment
		(start 159.847788 -225.506026)
		(end 160.334452 -225.019362)
		(width 0.16002)
		(layer "In11.Cu")
		(net "M_L_CPU1_SA_DQS_DN<7>")
	)
	(segment
		(start 187.656978 -221.558358)
		(end 188.032136 -221.1832)
		(width 0.16002)
		(layer "In11.Cu")
		(net "M_L_CPU1_SA_DQS_DN<7>")
	)
	(segment
		(start 195.57619 -221.1832)
		(end 196.197474 -221.1832)
		(width 0.16002)
		(layer "In11.Cu")
		(net "M_L_CPU1_SA_DQS_DN<7>")
	)
	(segment
		(start 158.474156 -227.456238)
		(end 158.474156 -226.879658)
		(width 0.16002)
		(layer "In11.Cu")
		(net "M_L_CPU1_SA_DQS_DN<7>")
	)
	(segment
		(start 145.411444 -237.461044)
		(end 145.606262 -237.266226)
		(width 0.09525)
		(layer "In11.Cu")
		(net "M_L_CPU1_SA_DQS_DN<7>")
	)
	(segment
		(start 190.329312 -220.32976)
		(end 190.707772 -220.70822)
		(width 0.16002)
		(layer "In11.Cu")
		(net "M_L_CPU1_SA_DQS_DN<7>")
	)
	(segment
		(start 144.38122 -237.527846)
		(end 144.395698 -237.519464)
		(width 0.09525)
		(layer "In11.Cu")
		(net "M_L_CPU1_SA_DQS_DN<7>")
	)
	(segment
		(start 175.241204 -220.32976)
		(end 175.619664 -220.70822)
		(width 0.16002)
		(layer "In11.Cu")
		(net "M_L_CPU1_SA_DQS_DN<7>")
	)
	(segment
		(start 180.488082 -221.1832)
		(end 181.109366 -221.1832)
		(width 0.16002)
		(layer "In11.Cu")
		(net "M_L_CPU1_SA_DQS_DN<7>")
	)
	(segment
		(start 170.519598 -220.575886)
		(end 171.50207 -221.558358)
		(width 0.16002)
		(layer "In11.Cu")
		(net "M_L_CPU1_SA_DQS_DN<7>")
	)
	(segment
		(start 140.25626 -237.519464)
		(end 140.264642 -237.52429)
		(width 0.09525)
		(layer "In11.Cu")
		(net "M_L_CPU1_SA_DQS_DN<7>")
	)
	(segment
		(start 186.585098 -221.558358)
		(end 187.656978 -221.558358)
		(width 0.16002)
		(layer "In11.Cu")
		(net "M_L_CPU1_SA_DQS_DN<7>")
	)
	(segment
		(start 190.707772 -220.70822)
		(end 193.03111 -220.70822)
		(width 0.16002)
		(layer "In11.Cu")
		(net "M_L_CPU1_SA_DQS_DN<7>")
	)
	(segment
		(start 159.5374 -226.392994)
		(end 159.847788 -226.082606)
		(width 0.16002)
		(layer "In11.Cu")
		(net "M_L_CPU1_SA_DQS_DN<7>")
	)
	(segment
		(start 162.595052 -222.758762)
		(end 164.170614 -221.1832)
		(width 0.16002)
		(layer "In11.Cu")
		(net "M_L_CPU1_SA_DQS_DN<7>")
	)
	(segment
		(start 193.881248 -221.558358)
		(end 195.201032 -221.558358)
		(width 0.16002)
		(layer "In11.Cu")
		(net "M_L_CPU1_SA_DQS_DN<7>")
	)
	(segment
		(start 161.22142 -224.132394)
		(end 161.708084 -223.64573)
		(width 0.16002)
		(layer "In11.Cu")
		(net "M_L_CPU1_SA_DQS_DN<7>")
	)
	(segment
		(start 144.957038 -237.519464)
		(end 144.980914 -237.53318)
		(width 0.09525)
		(layer "In11.Cu")
		(net "M_L_CPU1_SA_DQS_DN<7>")
	)
	(segment
		(start 195.201032 -221.558358)
		(end 195.57619 -221.1832)
		(width 0.16002)
		(layer "In11.Cu")
		(net "M_L_CPU1_SA_DQS_DN<7>")
	)
	(segment
		(start 139.316206 -237.519464)
		(end 139.324588 -237.52429)
		(width 0.09525)
		(layer "In11.Cu")
		(net "M_L_CPU1_SA_DQS_DN<7>")
	)
	(segment
		(start 199.31253 -220.70822)
		(end 199.461374 -220.559376)
		(width 0.16002)
		(layer "In11.Cu")
		(net "M_L_CPU1_SA_DQS_DN<7>")
	)
	(segment
		(start 197.873366 -220.32976)
		(end 198.251826 -220.70822)
		(width 0.16002)
		(layer "In11.Cu")
		(net "M_L_CPU1_SA_DQS_DN<7>")
	)
	(segment
		(start 172.56887 -221.558358)
		(end 172.944028 -221.1832)
		(width 0.16002)
		(layer "In11.Cu")
		(net "M_L_CPU1_SA_DQS_DN<7>")
	)
	(segment
		(start 144.931638 -237.504732)
		(end 144.957038 -237.519464)
		(width 0.09525)
		(layer "In11.Cu")
		(net "M_L_CPU1_SA_DQS_DN<7>")
	)
	(segment
		(start 164.170614 -221.1832)
		(end 166.021258 -221.1832)
		(width 0.16002)
		(layer "In11.Cu")
		(net "M_L_CPU1_SA_DQS_DN<7>")
	)
	(segment
		(start 160.911032 -225.019362)
		(end 161.22142 -224.708974)
		(width 0.16002)
		(layer "In11.Cu")
		(net "M_L_CPU1_SA_DQS_DN<7>")
	)
	(segment
		(start 188.032136 -221.1832)
		(end 188.65342 -221.1832)
		(width 0.16002)
		(layer "In11.Cu")
		(net "M_L_CPU1_SA_DQS_DN<7>")
	)
	(segment
		(start 147.18411 -236.110526)
		(end 147.591018 -235.703618)
		(width 0.09525)
		(layer "In11.Cu")
		(net "M_L_CPU1_SA_DQS_DN<7>")
	)
	(segment
		(start 138.74496 -237.52429)
		(end 138.753342 -237.519464)
		(width 0.09525)
		(layer "In11.Cu")
		(net "M_L_CPU1_SA_DQS_DN<7>")
	)
	(segment
		(start 147.18411 -236.730286)
		(end 147.18411 -236.110526)
		(width 0.09525)
		(layer "In11.Cu")
		(net "M_L_CPU1_SA_DQS_DN<7>")
	)
	(segment
		(start 178.322986 -220.70822)
		(end 179.173124 -221.558358)
		(width 0.16002)
		(layer "In11.Cu")
		(net "M_L_CPU1_SA_DQS_DN<7>")
	)
	(segment
		(start 179.173124 -221.558358)
		(end 180.112924 -221.558358)
		(width 0.16002)
		(layer "In11.Cu")
		(net "M_L_CPU1_SA_DQS_DN<7>")
	)
	(segment
		(start 198.251826 -220.70822)
		(end 199.31253 -220.70822)
		(width 0.16002)
		(layer "In11.Cu")
		(net "M_L_CPU1_SA_DQS_DN<7>")
	)
	(segment
		(start 159.847788 -226.082606)
		(end 159.847788 -225.506026)
		(width 0.16002)
		(layer "In11.Cu")
		(net "M_L_CPU1_SA_DQS_DN<7>")
	)
	(segment
		(start 137.62482 -237.194344)
		(end 137.778744 -237.459774)
		(width 0.09525)
		(layer "In11.Cu")
		(net "M_L_CPU1_SA_DQS_DN<7>")
	)
	(segment
		(start 145.606262 -237.266226)
		(end 146.64817 -237.266226)
		(width 0.09525)
		(layer "In11.Cu")
		(net "M_L_CPU1_SA_DQS_DN<7>")
	)
	(segment
		(start 142.504922 -237.52429)
		(end 142.513304 -237.519464)
		(width 0.09525)
		(layer "In11.Cu")
		(net "M_L_CPU1_SA_DQS_DN<7>")
	)
	(segment
		(start 166.874698 -220.32976)
		(end 167.375586 -220.32976)
		(width 0.16002)
		(layer "In11.Cu")
		(net "M_L_CPU1_SA_DQS_DN<7>")
	)
	(segment
		(start 196.197474 -221.1832)
		(end 197.050914 -220.32976)
		(width 0.16002)
		(layer "In11.Cu")
		(net "M_L_CPU1_SA_DQS_DN<7>")
	)
	(segment
		(start 171.50207 -221.558358)
		(end 172.56887 -221.558358)
		(width 0.16002)
		(layer "In11.Cu")
		(net "M_L_CPU1_SA_DQS_DN<7>")
	)
	(segment
		(start 193.03111 -220.70822)
		(end 193.881248 -221.558358)
		(width 0.16002)
		(layer "In11.Cu")
		(net "M_L_CPU1_SA_DQS_DN<7>")
	)
	(segment
		(start 168.00576 -219.699586)
		(end 168.550844 -219.699586)
		(width 0.16002)
		(layer "In11.Cu")
		(net "M_L_CPU1_SA_DQS_DN<7>")
	)
	(segment
		(start 197.050914 -220.32976)
		(end 197.873366 -220.32976)
		(width 0.16002)
		(layer "In11.Cu")
		(net "M_L_CPU1_SA_DQS_DN<7>")
	)
	(segment
		(start 143.076168 -237.519464)
		(end 143.08455 -237.52429)
		(width 0.09525)
		(layer "In11.Cu")
		(net "M_L_CPU1_SA_DQS_DN<7>")
	)
	(segment
		(start 180.112924 -221.558358)
		(end 180.488082 -221.1832)
		(width 0.16002)
		(layer "In11.Cu")
		(net "M_L_CPU1_SA_DQS_DN<7>")
	)
	(segment
		(start 172.944028 -221.1832)
		(end 173.565312 -221.1832)
		(width 0.16002)
		(layer "In11.Cu")
		(net "M_L_CPU1_SA_DQS_DN<7>")
	)
	(segment
		(start 183.163718 -220.70822)
		(end 185.73496 -220.70822)
		(width 0.16002)
		(layer "In11.Cu")
		(net "M_L_CPU1_SA_DQS_DN<7>")
	)
	(segment
		(start 137.778744 -237.459774)
		(end 137.879582 -237.486444)
		(width 0.09525)
		(layer "In11.Cu")
		(net "M_L_CPU1_SA_DQS_DN<7>")
	)
	(segment
		(start 161.708084 -223.64573)
		(end 162.284664 -223.64573)
		(width 0.16002)
		(layer "In11.Cu")
		(net "M_L_CPU1_SA_DQS_DN<7>")
	)
	(arc
		(start 142.136114 -237.519464)
		(mid 142.319889 -237.570236)
		(end 142.504922 -237.52429)
		(width 0.09525)
		(layer "In11.Cu")
		(net "M_L_CPU1_SA_DQS_DN<7>")
	)
	(arc
		(start 142.513304 -237.519464)
		(mid 142.794736 -237.443709)
		(end 143.076168 -237.519464)
		(width 0.09525)
		(layer "In11.Cu")
		(net "M_L_CPU1_SA_DQS_DN<7>")
	)
	(arc
		(start 143.08455 -237.52429)
		(mid 143.269582 -237.570204)
		(end 143.453358 -237.519464)
		(width 0.09525)
		(layer "In11.Cu")
		(net "M_L_CPU1_SA_DQS_DN<7>")
	)
	(arc
		(start 139.324588 -237.52429)
		(mid 139.50962 -237.570204)
		(end 139.693396 -237.519464)
		(width 0.09525)
		(layer "In11.Cu")
		(net "M_L_CPU1_SA_DQS_DN<7>")
	)
	(arc
		(start 145.334482 -237.519464)
		(mid 145.374846 -237.492734)
		(end 145.411444 -237.461044)
		(width 0.09525)
		(layer "In11.Cu")
		(net "M_L_CPU1_SA_DQS_DN<7>")
	)
	(arc
		(start 138.376152 -237.519464)
		(mid 138.559927 -237.570236)
		(end 138.74496 -237.52429)
		(width 0.09525)
		(layer "In11.Cu")
		(net "M_L_CPU1_SA_DQS_DN<7>")
	)
	(arc
		(start 138.753342 -237.519464)
		(mid 139.034774 -237.443709)
		(end 139.316206 -237.519464)
		(width 0.09525)
		(layer "In11.Cu")
		(net "M_L_CPU1_SA_DQS_DN<7>")
	)
	(arc
		(start 140.264642 -237.52429)
		(mid 140.449674 -237.570204)
		(end 140.63345 -237.519464)
		(width 0.09525)
		(layer "In11.Cu")
		(net "M_L_CPU1_SA_DQS_DN<7>")
	)
	(arc
		(start 144.017492 -237.519464)
		(mid 144.198279 -237.570551)
		(end 144.38122 -237.527846)
		(width 0.09525)
		(layer "In11.Cu")
		(net "M_L_CPU1_SA_DQS_DN<7>")
	)
	(arc
		(start 139.693396 -237.519464)
		(mid 139.974828 -237.443709)
		(end 140.25626 -237.519464)
		(width 0.09525)
		(layer "In11.Cu")
		(net "M_L_CPU1_SA_DQS_DN<7>")
	)
	(arc
		(start 144.980914 -237.53318)
		(mid 145.1594 -237.570423)
		(end 145.334482 -237.519464)
		(width 0.09525)
		(layer "In11.Cu")
		(net "M_L_CPU1_SA_DQS_DN<7>")
	)
	(arc
		(start 144.395698 -237.519464)
		(mid 144.661785 -237.443919)
		(end 144.931638 -237.504732)
		(width 0.09525)
		(layer "In11.Cu")
		(net "M_L_CPU1_SA_DQS_DN<7>")
	)
	(arc
		(start 143.476726 -237.506002)
		(mid 143.748827 -237.443324)
		(end 144.017492 -237.519464)
		(width 0.09525)
		(layer "In11.Cu")
		(net "M_L_CPU1_SA_DQS_DN<7>")
	)
	(arc
		(start 140.63345 -237.519464)
		(mid 140.914882 -237.443709)
		(end 141.196314 -237.519464)
		(width 0.09525)
		(layer "In11.Cu")
		(net "M_L_CPU1_SA_DQS_DN<7>")
	)
	(arc
		(start 141.57325 -237.519464)
		(mid 141.854682 -237.443709)
		(end 142.136114 -237.519464)
		(width 0.09525)
		(layer "In11.Cu")
		(net "M_L_CPU1_SA_DQS_DN<7>")
	)
	(arc
		(start 141.196314 -237.519464)
		(mid 141.384782 -237.570141)
		(end 141.57325 -237.519464)
		(width 0.09525)
		(layer "In11.Cu")
		(net "M_L_CPU1_SA_DQS_DN<7>")
	)
	(arc
		(start 137.879582 -237.486444)
		(mid 138.131723 -237.444874)
		(end 138.376152 -237.519464)
		(width 0.09525)
		(layer "In11.Cu")
		(net "M_L_CPU1_SA_DQS_DN<7>")
	)
	(segment
		(start 137.157968 -232.600246)
		(end 137.62482 -232.334308)
		(width 0.12954)
		(layer "F.Cu")
		(net "M_L_CPU1_SA_DQS_DN<6>")
	)
	(segment
		(start 187.656978 -212.208364)
		(end 188.032136 -211.833206)
		(width 0.16002)
		(layer "In11.Cu")
		(net "M_L_CPU1_SA_DQS_DN<6>")
	)
	(segment
		(start 156.260546 -219.997528)
		(end 156.260546 -219.771468)
		(width 0.16002)
		(layer "In11.Cu")
		(net "M_L_CPU1_SA_DQS_DN<6>")
	)
	(segment
		(start 157.386782 -218.871292)
		(end 157.634178 -218.623896)
		(width 0.16002)
		(layer "In11.Cu")
		(net "M_L_CPU1_SA_DQS_DN<6>")
	)
	(segment
		(start 172.56887 -212.208364)
		(end 172.944028 -211.833206)
		(width 0.16002)
		(layer "In11.Cu")
		(net "M_L_CPU1_SA_DQS_DN<6>")
	)
	(segment
		(start 178.317906 -211.358226)
		(end 179.168044 -212.208364)
		(width 0.16002)
		(layer "In11.Cu")
		(net "M_L_CPU1_SA_DQS_DN<6>")
	)
	(segment
		(start 153.773378 -221.45498)
		(end 154.249882 -221.45498)
		(width 0.16002)
		(layer "In11.Cu")
		(net "M_L_CPU1_SA_DQS_DN<6>")
	)
	(segment
		(start 163.395152 -211.833206)
		(end 166.021258 -211.833206)
		(width 0.16002)
		(layer "In11.Cu")
		(net "M_L_CPU1_SA_DQS_DN<6>")
	)
	(segment
		(start 156.09697 -219.607892)
		(end 156.09697 -219.131388)
		(width 0.16002)
		(layer "In11.Cu")
		(net "M_L_CPU1_SA_DQS_DN<6>")
	)
	(segment
		(start 155.14701 -220.081348)
		(end 155.623514 -220.081348)
		(width 0.16002)
		(layer "In11.Cu")
		(net "M_L_CPU1_SA_DQS_DN<6>")
	)
	(segment
		(start 154.249882 -221.45498)
		(end 154.413458 -221.618556)
		(width 0.16002)
		(layer "In11.Cu")
		(net "M_L_CPU1_SA_DQS_DN<6>")
	)
	(segment
		(start 144.931638 -232.644696)
		(end 144.957038 -232.659428)
		(width 0.09525)
		(layer "In11.Cu")
		(net "M_L_CPU1_SA_DQS_DN<6>")
	)
	(segment
		(start 171.59605 -212.208364)
		(end 172.56887 -212.208364)
		(width 0.16002)
		(layer "In11.Cu")
		(net "M_L_CPU1_SA_DQS_DN<6>")
	)
	(segment
		(start 181.109366 -211.833206)
		(end 181.962806 -210.979766)
		(width 0.16002)
		(layer "In11.Cu")
		(net "M_L_CPU1_SA_DQS_DN<6>")
	)
	(segment
		(start 157.634178 -218.623896)
		(end 157.634178 -218.397836)
		(width 0.16002)
		(layer "In11.Cu")
		(net "M_L_CPU1_SA_DQS_DN<6>")
	)
	(segment
		(start 156.01315 -220.244924)
		(end 156.260546 -219.997528)
		(width 0.16002)
		(layer "In11.Cu")
		(net "M_L_CPU1_SA_DQS_DN<6>")
	)
	(segment
		(start 199.31253 -211.358226)
		(end 199.461374 -211.209382)
		(width 0.16002)
		(layer "In11.Cu")
		(net "M_L_CPU1_SA_DQS_DN<6>")
	)
	(segment
		(start 154.886914 -221.1451)
		(end 154.723338 -220.981524)
		(width 0.16002)
		(layer "In11.Cu")
		(net "M_L_CPU1_SA_DQS_DN<6>")
	)
	(segment
		(start 193.881248 -212.208364)
		(end 195.201032 -212.208364)
		(width 0.16002)
		(layer "In11.Cu")
		(net "M_L_CPU1_SA_DQS_DN<6>")
	)
	(segment
		(start 144.38122 -232.66781)
		(end 144.395698 -232.659428)
		(width 0.09525)
		(layer "In11.Cu")
		(net "M_L_CPU1_SA_DQS_DN<6>")
	)
	(segment
		(start 139.316206 -232.659428)
		(end 139.324588 -232.664254)
		(width 0.09525)
		(layer "In11.Cu")
		(net "M_L_CPU1_SA_DQS_DN<6>")
	)
	(segment
		(start 195.201032 -212.208364)
		(end 195.57619 -211.833206)
		(width 0.16002)
		(layer "In11.Cu")
		(net "M_L_CPU1_SA_DQS_DN<6>")
	)
	(segment
		(start 156.520642 -218.707716)
		(end 156.997146 -218.707716)
		(width 0.16002)
		(layer "In11.Cu")
		(net "M_L_CPU1_SA_DQS_DN<6>")
	)
	(segment
		(start 154.413458 -221.618556)
		(end 154.639518 -221.618556)
		(width 0.16002)
		(layer "In11.Cu")
		(net "M_L_CPU1_SA_DQS_DN<6>")
	)
	(segment
		(start 183.163718 -211.358226)
		(end 185.739532 -211.358226)
		(width 0.16002)
		(layer "In11.Cu")
		(net "M_L_CPU1_SA_DQS_DN<6>")
	)
	(segment
		(start 197.873366 -210.979766)
		(end 198.251826 -211.358226)
		(width 0.16002)
		(layer "In11.Cu")
		(net "M_L_CPU1_SA_DQS_DN<6>")
	)
	(segment
		(start 166.874698 -210.979766)
		(end 167.69715 -210.979766)
		(width 0.16002)
		(layer "In11.Cu")
		(net "M_L_CPU1_SA_DQS_DN<6>")
	)
	(segment
		(start 190.329312 -210.979766)
		(end 190.707772 -211.358226)
		(width 0.16002)
		(layer "In11.Cu")
		(net "M_L_CPU1_SA_DQS_DN<6>")
	)
	(segment
		(start 174.418752 -210.979766)
		(end 175.241204 -210.979766)
		(width 0.16002)
		(layer "In11.Cu")
		(net "M_L_CPU1_SA_DQS_DN<6>")
	)
	(segment
		(start 175.241204 -210.979766)
		(end 175.619664 -211.358226)
		(width 0.16002)
		(layer "In11.Cu")
		(net "M_L_CPU1_SA_DQS_DN<6>")
	)
	(segment
		(start 170.606212 -211.218526)
		(end 171.59605 -212.208364)
		(width 0.16002)
		(layer "In11.Cu")
		(net "M_L_CPU1_SA_DQS_DN<6>")
	)
	(segment
		(start 188.65342 -211.833206)
		(end 189.50686 -210.979766)
		(width 0.16002)
		(layer "In11.Cu")
		(net "M_L_CPU1_SA_DQS_DN<6>")
	)
	(segment
		(start 137.778744 -232.599738)
		(end 137.879582 -232.626408)
		(width 0.09525)
		(layer "In11.Cu")
		(net "M_L_CPU1_SA_DQS_DN<6>")
	)
	(segment
		(start 142.504922 -232.664254)
		(end 142.513304 -232.659428)
		(width 0.09525)
		(layer "In11.Cu")
		(net "M_L_CPU1_SA_DQS_DN<6>")
	)
	(segment
		(start 147.489926 -229.884986)
		(end 152.92705 -224.447354)
		(width 0.16002)
		(layer "In11.Cu")
		(net "M_L_CPU1_SA_DQS_DN<6>")
	)
	(segment
		(start 156.997146 -218.707716)
		(end 157.160722 -218.871292)
		(width 0.16002)
		(layer "In11.Cu")
		(net "M_L_CPU1_SA_DQS_DN<6>")
	)
	(segment
		(start 173.565312 -211.833206)
		(end 174.418752 -210.979766)
		(width 0.16002)
		(layer "In11.Cu")
		(net "M_L_CPU1_SA_DQS_DN<6>")
	)
	(segment
		(start 180.488082 -211.833206)
		(end 181.109366 -211.833206)
		(width 0.16002)
		(layer "In11.Cu")
		(net "M_L_CPU1_SA_DQS_DN<6>")
	)
	(segment
		(start 138.74496 -232.664254)
		(end 138.753342 -232.659428)
		(width 0.09525)
		(layer "In11.Cu")
		(net "M_L_CPU1_SA_DQS_DN<6>")
	)
	(segment
		(start 157.470602 -217.757756)
		(end 163.395152 -211.833206)
		(width 0.16002)
		(layer "In11.Cu")
		(net "M_L_CPU1_SA_DQS_DN<6>")
	)
	(segment
		(start 147.473162 -229.90175)
		(end 147.489926 -229.884986)
		(width 0.09525)
		(layer "In11.Cu")
		(net "M_L_CPU1_SA_DQS_DN<6>")
	)
	(segment
		(start 157.160722 -218.871292)
		(end 157.386782 -218.871292)
		(width 0.16002)
		(layer "In11.Cu")
		(net "M_L_CPU1_SA_DQS_DN<6>")
	)
	(segment
		(start 147.473162 -229.98557)
		(end 147.473162 -229.90175)
		(width 0.09525)
		(layer "In11.Cu")
		(net "M_L_CPU1_SA_DQS_DN<6>")
	)
	(segment
		(start 198.251826 -211.358226)
		(end 199.31253 -211.358226)
		(width 0.16002)
		(layer "In11.Cu")
		(net "M_L_CPU1_SA_DQS_DN<6>")
	)
	(segment
		(start 156.09697 -219.131388)
		(end 156.520642 -218.707716)
		(width 0.16002)
		(layer "In11.Cu")
		(net "M_L_CPU1_SA_DQS_DN<6>")
	)
	(segment
		(start 154.639518 -221.618556)
		(end 154.886914 -221.37116)
		(width 0.16002)
		(layer "In11.Cu")
		(net "M_L_CPU1_SA_DQS_DN<6>")
	)
	(segment
		(start 155.623514 -220.081348)
		(end 155.78709 -220.244924)
		(width 0.16002)
		(layer "In11.Cu")
		(net "M_L_CPU1_SA_DQS_DN<6>")
	)
	(segment
		(start 182.785258 -210.979766)
		(end 183.163718 -211.358226)
		(width 0.16002)
		(layer "In11.Cu")
		(net "M_L_CPU1_SA_DQS_DN<6>")
	)
	(segment
		(start 188.032136 -211.833206)
		(end 188.65342 -211.833206)
		(width 0.16002)
		(layer "In11.Cu")
		(net "M_L_CPU1_SA_DQS_DN<6>")
	)
	(segment
		(start 152.92705 -222.301308)
		(end 153.773378 -221.45498)
		(width 0.16002)
		(layer "In11.Cu")
		(net "M_L_CPU1_SA_DQS_DN<6>")
	)
	(segment
		(start 196.197474 -211.833206)
		(end 197.050914 -210.979766)
		(width 0.16002)
		(layer "In11.Cu")
		(net "M_L_CPU1_SA_DQS_DN<6>")
	)
	(segment
		(start 193.03111 -211.358226)
		(end 193.881248 -212.208364)
		(width 0.16002)
		(layer "In11.Cu")
		(net "M_L_CPU1_SA_DQS_DN<6>")
	)
	(segment
		(start 167.69715 -210.979766)
		(end 167.93591 -211.218526)
		(width 0.16002)
		(layer "In11.Cu")
		(net "M_L_CPU1_SA_DQS_DN<6>")
	)
	(segment
		(start 195.57619 -211.833206)
		(end 196.197474 -211.833206)
		(width 0.16002)
		(layer "In11.Cu")
		(net "M_L_CPU1_SA_DQS_DN<6>")
	)
	(segment
		(start 137.62482 -232.334308)
		(end 137.778744 -232.599738)
		(width 0.09525)
		(layer "In11.Cu")
		(net "M_L_CPU1_SA_DQS_DN<6>")
	)
	(segment
		(start 197.050914 -210.979766)
		(end 197.873366 -210.979766)
		(width 0.16002)
		(layer "In11.Cu")
		(net "M_L_CPU1_SA_DQS_DN<6>")
	)
	(segment
		(start 143.453358 -232.659428)
		(end 143.476726 -232.645966)
		(width 0.09525)
		(layer "In11.Cu")
		(net "M_L_CPU1_SA_DQS_DN<6>")
	)
	(segment
		(start 140.25626 -232.659428)
		(end 140.264642 -232.664254)
		(width 0.09525)
		(layer "In11.Cu")
		(net "M_L_CPU1_SA_DQS_DN<6>")
	)
	(segment
		(start 154.886914 -221.37116)
		(end 154.886914 -221.1451)
		(width 0.16002)
		(layer "In11.Cu")
		(net "M_L_CPU1_SA_DQS_DN<6>")
	)
	(segment
		(start 167.93591 -211.218526)
		(end 170.606212 -211.218526)
		(width 0.16002)
		(layer "In11.Cu")
		(net "M_L_CPU1_SA_DQS_DN<6>")
	)
	(segment
		(start 154.723338 -220.981524)
		(end 154.723338 -220.50502)
		(width 0.16002)
		(layer "In11.Cu")
		(net "M_L_CPU1_SA_DQS_DN<6>")
	)
	(segment
		(start 189.50686 -210.979766)
		(end 190.329312 -210.979766)
		(width 0.16002)
		(layer "In11.Cu")
		(net "M_L_CPU1_SA_DQS_DN<6>")
	)
	(segment
		(start 143.076168 -232.659428)
		(end 143.08455 -232.664254)
		(width 0.09525)
		(layer "In11.Cu")
		(net "M_L_CPU1_SA_DQS_DN<6>")
	)
	(segment
		(start 185.739532 -211.358226)
		(end 186.58967 -212.208364)
		(width 0.16002)
		(layer "In11.Cu")
		(net "M_L_CPU1_SA_DQS_DN<6>")
	)
	(segment
		(start 155.78709 -220.244924)
		(end 156.01315 -220.244924)
		(width 0.16002)
		(layer "In11.Cu")
		(net "M_L_CPU1_SA_DQS_DN<6>")
	)
	(segment
		(start 156.260546 -219.771468)
		(end 156.09697 -219.607892)
		(width 0.16002)
		(layer "In11.Cu")
		(net "M_L_CPU1_SA_DQS_DN<6>")
	)
	(segment
		(start 179.168044 -212.208364)
		(end 180.112924 -212.208364)
		(width 0.16002)
		(layer "In11.Cu")
		(net "M_L_CPU1_SA_DQS_DN<6>")
	)
	(segment
		(start 157.470602 -218.23426)
		(end 157.470602 -217.757756)
		(width 0.16002)
		(layer "In11.Cu")
		(net "M_L_CPU1_SA_DQS_DN<6>")
	)
	(segment
		(start 146.05635 -231.956102)
		(end 146.05635 -231.402382)
		(width 0.09525)
		(layer "In11.Cu")
		(net "M_L_CPU1_SA_DQS_DN<6>")
	)
	(segment
		(start 157.634178 -218.397836)
		(end 157.470602 -218.23426)
		(width 0.16002)
		(layer "In11.Cu")
		(net "M_L_CPU1_SA_DQS_DN<6>")
	)
	(segment
		(start 166.021258 -211.833206)
		(end 166.874698 -210.979766)
		(width 0.16002)
		(layer "In11.Cu")
		(net "M_L_CPU1_SA_DQS_DN<6>")
	)
	(segment
		(start 145.411444 -232.601008)
		(end 146.05635 -231.956102)
		(width 0.09525)
		(layer "In11.Cu")
		(net "M_L_CPU1_SA_DQS_DN<6>")
	)
	(segment
		(start 172.944028 -211.833206)
		(end 173.565312 -211.833206)
		(width 0.16002)
		(layer "In11.Cu")
		(net "M_L_CPU1_SA_DQS_DN<6>")
	)
	(segment
		(start 154.723338 -220.50502)
		(end 155.14701 -220.081348)
		(width 0.16002)
		(layer "In11.Cu")
		(net "M_L_CPU1_SA_DQS_DN<6>")
	)
	(segment
		(start 152.92705 -224.447354)
		(end 152.92705 -222.301308)
		(width 0.16002)
		(layer "In11.Cu")
		(net "M_L_CPU1_SA_DQS_DN<6>")
	)
	(segment
		(start 190.707772 -211.358226)
		(end 193.03111 -211.358226)
		(width 0.16002)
		(layer "In11.Cu")
		(net "M_L_CPU1_SA_DQS_DN<6>")
	)
	(segment
		(start 181.962806 -210.979766)
		(end 182.785258 -210.979766)
		(width 0.16002)
		(layer "In11.Cu")
		(net "M_L_CPU1_SA_DQS_DN<6>")
	)
	(segment
		(start 186.58967 -212.208364)
		(end 187.656978 -212.208364)
		(width 0.16002)
		(layer "In11.Cu")
		(net "M_L_CPU1_SA_DQS_DN<6>")
	)
	(segment
		(start 144.957038 -232.659428)
		(end 144.980914 -232.673144)
		(width 0.09525)
		(layer "In11.Cu")
		(net "M_L_CPU1_SA_DQS_DN<6>")
	)
	(segment
		(start 146.05635 -231.402382)
		(end 147.473162 -229.98557)
		(width 0.09525)
		(layer "In11.Cu")
		(net "M_L_CPU1_SA_DQS_DN<6>")
	)
	(segment
		(start 201.873866 -211.209382)
		(end 202.147932 -210.935316)
		(width 0.16002)
		(layer "In11.Cu")
		(net "M_L_CPU1_SA_DQS_DN<6>")
	)
	(segment
		(start 180.112924 -212.208364)
		(end 180.488082 -211.833206)
		(width 0.16002)
		(layer "In11.Cu")
		(net "M_L_CPU1_SA_DQS_DN<6>")
	)
	(segment
		(start 199.461374 -211.209382)
		(end 201.873866 -211.209382)
		(width 0.16002)
		(layer "In11.Cu")
		(net "M_L_CPU1_SA_DQS_DN<6>")
	)
	(segment
		(start 175.619664 -211.358226)
		(end 178.317906 -211.358226)
		(width 0.16002)
		(layer "In11.Cu")
		(net "M_L_CPU1_SA_DQS_DN<6>")
	)
	(arc
		(start 144.395698 -232.659428)
		(mid 144.661785 -232.583883)
		(end 144.931638 -232.644696)
		(width 0.09525)
		(layer "In11.Cu")
		(net "M_L_CPU1_SA_DQS_DN<6>")
	)
	(arc
		(start 144.017492 -232.659428)
		(mid 144.198279 -232.710515)
		(end 144.38122 -232.66781)
		(width 0.09525)
		(layer "In11.Cu")
		(net "M_L_CPU1_SA_DQS_DN<6>")
	)
	(arc
		(start 140.63345 -232.659428)
		(mid 140.914882 -232.583673)
		(end 141.196314 -232.659428)
		(width 0.09525)
		(layer "In11.Cu")
		(net "M_L_CPU1_SA_DQS_DN<6>")
	)
	(arc
		(start 137.879582 -232.626408)
		(mid 138.131723 -232.584838)
		(end 138.376152 -232.659428)
		(width 0.09525)
		(layer "In11.Cu")
		(net "M_L_CPU1_SA_DQS_DN<6>")
	)
	(arc
		(start 141.57325 -232.659428)
		(mid 141.854682 -232.583673)
		(end 142.136114 -232.659428)
		(width 0.09525)
		(layer "In11.Cu")
		(net "M_L_CPU1_SA_DQS_DN<6>")
	)
	(arc
		(start 139.324588 -232.664254)
		(mid 139.50962 -232.710168)
		(end 139.693396 -232.659428)
		(width 0.09525)
		(layer "In11.Cu")
		(net "M_L_CPU1_SA_DQS_DN<6>")
	)
	(arc
		(start 143.476726 -232.645966)
		(mid 143.748827 -232.583288)
		(end 144.017492 -232.659428)
		(width 0.09525)
		(layer "In11.Cu")
		(net "M_L_CPU1_SA_DQS_DN<6>")
	)
	(arc
		(start 142.136114 -232.659428)
		(mid 142.319889 -232.7102)
		(end 142.504922 -232.664254)
		(width 0.09525)
		(layer "In11.Cu")
		(net "M_L_CPU1_SA_DQS_DN<6>")
	)
	(arc
		(start 144.980914 -232.673144)
		(mid 145.1594 -232.710387)
		(end 145.334482 -232.659428)
		(width 0.09525)
		(layer "In11.Cu")
		(net "M_L_CPU1_SA_DQS_DN<6>")
	)
	(arc
		(start 139.693396 -232.659428)
		(mid 139.974828 -232.583673)
		(end 140.25626 -232.659428)
		(width 0.09525)
		(layer "In11.Cu")
		(net "M_L_CPU1_SA_DQS_DN<6>")
	)
	(arc
		(start 138.376152 -232.659428)
		(mid 138.559927 -232.7102)
		(end 138.74496 -232.664254)
		(width 0.09525)
		(layer "In11.Cu")
		(net "M_L_CPU1_SA_DQS_DN<6>")
	)
	(arc
		(start 140.264642 -232.664254)
		(mid 140.449674 -232.710168)
		(end 140.63345 -232.659428)
		(width 0.09525)
		(layer "In11.Cu")
		(net "M_L_CPU1_SA_DQS_DN<6>")
	)
	(arc
		(start 143.08455 -232.664254)
		(mid 143.269582 -232.710168)
		(end 143.453358 -232.659428)
		(width 0.09525)
		(layer "In11.Cu")
		(net "M_L_CPU1_SA_DQS_DN<6>")
	)
	(arc
		(start 141.196314 -232.659428)
		(mid 141.384782 -232.710105)
		(end 141.57325 -232.659428)
		(width 0.09525)
		(layer "In11.Cu")
		(net "M_L_CPU1_SA_DQS_DN<6>")
	)
	(arc
		(start 142.513304 -232.659428)
		(mid 142.794736 -232.583673)
		(end 143.076168 -232.659428)
		(width 0.09525)
		(layer "In11.Cu")
		(net "M_L_CPU1_SA_DQS_DN<6>")
	)
	(arc
		(start 138.753342 -232.659428)
		(mid 139.034774 -232.583673)
		(end 139.316206 -232.659428)
		(width 0.09525)
		(layer "In11.Cu")
		(net "M_L_CPU1_SA_DQS_DN<6>")
	)
	(arc
		(start 145.334482 -232.659428)
		(mid 145.374846 -232.632698)
		(end 145.411444 -232.601008)
		(width 0.09525)
		(layer "In11.Cu")
		(net "M_L_CPU1_SA_DQS_DN<6>")
	)
	(segment
		(start 137.157968 -227.740464)
		(end 137.62482 -227.474526)
		(width 0.12954)
		(layer "F.Cu")
		(net "M_L_CPU1_SA_DQS_DN<5>")
	)
	(segment
		(start 199.397366 -201.859388)
		(end 201.873866 -201.859388)
		(width 0.16002)
		(layer "In11.Cu")
		(net "M_L_CPU1_SA_DQS_DN<5>")
	)
	(segment
		(start 143.923512 -226.98964)
		(end 143.957294 -226.970082)
		(width 0.09525)
		(layer "In11.Cu")
		(net "M_L_CPU1_SA_DQS_DN<5>")
	)
	(segment
		(start 144.355566 -226.201732)
		(end 144.393666 -226.179634)
		(width 0.09525)
		(layer "In11.Cu")
		(net "M_L_CPU1_SA_DQS_DN<5>")
	)
	(segment
		(start 144.393666 -226.179634)
		(end 144.423892 -226.162108)
		(width 0.09525)
		(layer "In11.Cu")
		(net "M_L_CPU1_SA_DQS_DN<5>")
	)
	(segment
		(start 171.52747 -202.85837)
		(end 172.56887 -202.85837)
		(width 0.16002)
		(layer "In11.Cu")
		(net "M_L_CPU1_SA_DQS_DN<5>")
	)
	(segment
		(start 173.565312 -202.483212)
		(end 174.418752 -201.629772)
		(width 0.16002)
		(layer "In11.Cu")
		(net "M_L_CPU1_SA_DQS_DN<5>")
	)
	(segment
		(start 201.873866 -201.859388)
		(end 202.147932 -201.585322)
		(width 0.16002)
		(layer "In11.Cu")
		(net "M_L_CPU1_SA_DQS_DN<5>")
	)
	(segment
		(start 172.56887 -202.85837)
		(end 172.944028 -202.483212)
		(width 0.16002)
		(layer "In11.Cu")
		(net "M_L_CPU1_SA_DQS_DN<5>")
	)
	(segment
		(start 188.032136 -202.483212)
		(end 188.65342 -202.483212)
		(width 0.16002)
		(layer "In11.Cu")
		(net "M_L_CPU1_SA_DQS_DN<5>")
	)
	(segment
		(start 145.33372 -224.559622)
		(end 145.363946 -224.542096)
		(width 0.09525)
		(layer "In11.Cu")
		(net "M_L_CPU1_SA_DQS_DN<5>")
	)
	(segment
		(start 147.105878 -221.475046)
		(end 147.046696 -221.415864)
		(width 0.09525)
		(layer "In11.Cu")
		(net "M_L_CPU1_SA_DQS_DN<5>")
	)
	(segment
		(start 196.197474 -202.483212)
		(end 197.050914 -201.629772)
		(width 0.16002)
		(layer "In11.Cu")
		(net "M_L_CPU1_SA_DQS_DN<5>")
	)
	(segment
		(start 154.756866 -210.689444)
		(end 154.756866 -210.212686)
		(width 0.16002)
		(layer "In11.Cu")
		(net "M_L_CPU1_SA_DQS_DN<5>")
	)
	(segment
		(start 147.105878 -222.08744)
		(end 147.105878 -221.475046)
		(width 0.09525)
		(layer "In11.Cu")
		(net "M_L_CPU1_SA_DQS_DN<5>")
	)
	(segment
		(start 145.765266 -223.771714)
		(end 145.803366 -223.749616)
		(width 0.09525)
		(layer "In11.Cu")
		(net "M_L_CPU1_SA_DQS_DN<5>")
	)
	(segment
		(start 154.526742 -211.405724)
		(end 154.752802 -211.405724)
		(width 0.16002)
		(layer "In11.Cu")
		(net "M_L_CPU1_SA_DQS_DN<5>")
	)
	(segment
		(start 179.147216 -202.85837)
		(end 180.112924 -202.85837)
		(width 0.16002)
		(layer "In11.Cu")
		(net "M_L_CPU1_SA_DQS_DN<5>")
	)
	(segment
		(start 153.15311 -212.779356)
		(end 153.37917 -212.779356)
		(width 0.16002)
		(layer "In11.Cu")
		(net "M_L_CPU1_SA_DQS_DN<5>")
	)
	(segment
		(start 197.873366 -201.629772)
		(end 198.251826 -202.008232)
		(width 0.16002)
		(layer "In11.Cu")
		(net "M_L_CPU1_SA_DQS_DN<5>")
	)
	(segment
		(start 175.619664 -202.008232)
		(end 178.297078 -202.008232)
		(width 0.16002)
		(layer "In11.Cu")
		(net "M_L_CPU1_SA_DQS_DN<5>")
	)
	(segment
		(start 180.488082 -202.483212)
		(end 181.109366 -202.483212)
		(width 0.16002)
		(layer "In11.Cu")
		(net "M_L_CPU1_SA_DQS_DN<5>")
	)
	(segment
		(start 153.626566 -212.306154)
		(end 153.383234 -212.063076)
		(width 0.16002)
		(layer "In11.Cu")
		(net "M_L_CPU1_SA_DQS_DN<5>")
	)
	(segment
		(start 153.383234 -211.586318)
		(end 153.806906 -211.162646)
		(width 0.16002)
		(layer "In11.Cu")
		(net "M_L_CPU1_SA_DQS_DN<5>")
	)
	(segment
		(start 153.37917 -212.779356)
		(end 153.626566 -212.53196)
		(width 0.16002)
		(layer "In11.Cu")
		(net "M_L_CPU1_SA_DQS_DN<5>")
	)
	(segment
		(start 138.74496 -227.804472)
		(end 138.753342 -227.799646)
		(width 0.09525)
		(layer "In11.Cu")
		(net "M_L_CPU1_SA_DQS_DN<5>")
	)
	(segment
		(start 145.29435 -224.582482)
		(end 145.33372 -224.559622)
		(width 0.09525)
		(layer "In11.Cu")
		(net "M_L_CPU1_SA_DQS_DN<5>")
	)
	(segment
		(start 153.806906 -211.162646)
		(end 154.28341 -211.162646)
		(width 0.16002)
		(layer "In11.Cu")
		(net "M_L_CPU1_SA_DQS_DN<5>")
	)
	(segment
		(start 146.100546 -223.092772)
		(end 147.105878 -222.08744)
		(width 0.09525)
		(layer "In11.Cu")
		(net "M_L_CPU1_SA_DQS_DN<5>")
	)
	(segment
		(start 193.881248 -202.85837)
		(end 195.201032 -202.85837)
		(width 0.16002)
		(layer "In11.Cu")
		(net "M_L_CPU1_SA_DQS_DN<5>")
	)
	(segment
		(start 182.785258 -201.629772)
		(end 183.163718 -202.008232)
		(width 0.16002)
		(layer "In11.Cu")
		(net "M_L_CPU1_SA_DQS_DN<5>")
	)
	(segment
		(start 175.241204 -201.629772)
		(end 175.619664 -202.008232)
		(width 0.16002)
		(layer "In11.Cu")
		(net "M_L_CPU1_SA_DQS_DN<5>")
	)
	(segment
		(start 172.944028 -202.483212)
		(end 173.565312 -202.483212)
		(width 0.16002)
		(layer "In11.Cu")
		(net "M_L_CPU1_SA_DQS_DN<5>")
	)
	(segment
		(start 153.383234 -212.063076)
		(end 153.383234 -211.586318)
		(width 0.16002)
		(layer "In11.Cu")
		(net "M_L_CPU1_SA_DQS_DN<5>")
	)
	(segment
		(start 143.076168 -227.799646)
		(end 143.08455 -227.804472)
		(width 0.09525)
		(layer "In11.Cu")
		(net "M_L_CPU1_SA_DQS_DN<5>")
	)
	(segment
		(start 143.453358 -227.799646)
		(end 143.48714 -227.780088)
		(width 0.09525)
		(layer "In11.Cu")
		(net "M_L_CPU1_SA_DQS_DN<5>")
	)
	(segment
		(start 142.504922 -227.804472)
		(end 142.513304 -227.799646)
		(width 0.09525)
		(layer "In11.Cu")
		(net "M_L_CPU1_SA_DQS_DN<5>")
	)
	(segment
		(start 178.297078 -202.008232)
		(end 179.147216 -202.85837)
		(width 0.16002)
		(layer "In11.Cu")
		(net "M_L_CPU1_SA_DQS_DN<5>")
	)
	(segment
		(start 199.248522 -202.008232)
		(end 199.397366 -201.859388)
		(width 0.16002)
		(layer "In11.Cu")
		(net "M_L_CPU1_SA_DQS_DN<5>")
	)
	(segment
		(start 190.329312 -201.629772)
		(end 190.707772 -202.008232)
		(width 0.16002)
		(layer "In11.Cu")
		(net "M_L_CPU1_SA_DQS_DN<5>")
	)
	(segment
		(start 166.874698 -201.629772)
		(end 167.69715 -201.629772)
		(width 0.16002)
		(layer "In11.Cu")
		(net "M_L_CPU1_SA_DQS_DN<5>")
	)
	(segment
		(start 197.050914 -201.629772)
		(end 197.873366 -201.629772)
		(width 0.16002)
		(layer "In11.Cu")
		(net "M_L_CPU1_SA_DQS_DN<5>")
	)
	(segment
		(start 154.756866 -210.212686)
		(end 162.48634 -202.483212)
		(width 0.16002)
		(layer "In11.Cu")
		(net "M_L_CPU1_SA_DQS_DN<5>")
	)
	(segment
		(start 198.251826 -202.008232)
		(end 199.248522 -202.008232)
		(width 0.16002)
		(layer "In11.Cu")
		(net "M_L_CPU1_SA_DQS_DN<5>")
	)
	(segment
		(start 181.962806 -201.629772)
		(end 182.785258 -201.629772)
		(width 0.16002)
		(layer "In11.Cu")
		(net "M_L_CPU1_SA_DQS_DN<5>")
	)
	(segment
		(start 193.03111 -202.008232)
		(end 193.881248 -202.85837)
		(width 0.16002)
		(layer "In11.Cu")
		(net "M_L_CPU1_SA_DQS_DN<5>")
	)
	(segment
		(start 195.201032 -202.85837)
		(end 195.57619 -202.483212)
		(width 0.16002)
		(layer "In11.Cu")
		(net "M_L_CPU1_SA_DQS_DN<5>")
	)
	(segment
		(start 190.707772 -202.008232)
		(end 193.03111 -202.008232)
		(width 0.16002)
		(layer "In11.Cu")
		(net "M_L_CPU1_SA_DQS_DN<5>")
	)
	(segment
		(start 154.752802 -211.405724)
		(end 155.000198 -211.158328)
		(width 0.16002)
		(layer "In11.Cu")
		(net "M_L_CPU1_SA_DQS_DN<5>")
	)
	(segment
		(start 189.50686 -201.629772)
		(end 190.329312 -201.629772)
		(width 0.16002)
		(layer "In11.Cu")
		(net "M_L_CPU1_SA_DQS_DN<5>")
	)
	(segment
		(start 170.461686 -201.792586)
		(end 171.52747 -202.85837)
		(width 0.16002)
		(layer "In11.Cu")
		(net "M_L_CPU1_SA_DQS_DN<5>")
	)
	(segment
		(start 187.656978 -202.85837)
		(end 188.032136 -202.483212)
		(width 0.16002)
		(layer "In11.Cu")
		(net "M_L_CPU1_SA_DQS_DN<5>")
	)
	(segment
		(start 186.568842 -202.85837)
		(end 187.656978 -202.85837)
		(width 0.16002)
		(layer "In11.Cu")
		(net "M_L_CPU1_SA_DQS_DN<5>")
	)
	(segment
		(start 144.863312 -225.369628)
		(end 144.89811 -225.349562)
		(width 0.09525)
		(layer "In11.Cu")
		(net "M_L_CPU1_SA_DQS_DN<5>")
	)
	(segment
		(start 185.718704 -202.008232)
		(end 186.568842 -202.85837)
		(width 0.16002)
		(layer "In11.Cu")
		(net "M_L_CPU1_SA_DQS_DN<5>")
	)
	(segment
		(start 174.418752 -201.629772)
		(end 175.241204 -201.629772)
		(width 0.16002)
		(layer "In11.Cu")
		(net "M_L_CPU1_SA_DQS_DN<5>")
	)
	(segment
		(start 167.859964 -201.792586)
		(end 170.461686 -201.792586)
		(width 0.16002)
		(layer "In11.Cu")
		(net "M_L_CPU1_SA_DQS_DN<5>")
	)
	(segment
		(start 153.626566 -212.53196)
		(end 153.626566 -212.306154)
		(width 0.16002)
		(layer "In11.Cu")
		(net "M_L_CPU1_SA_DQS_DN<5>")
	)
	(segment
		(start 152.433274 -212.536278)
		(end 152.909778 -212.536278)
		(width 0.16002)
		(layer "In11.Cu")
		(net "M_L_CPU1_SA_DQS_DN<5>")
	)
	(segment
		(start 143.885412 -227.011738)
		(end 143.923512 -226.98964)
		(width 0.09525)
		(layer "In11.Cu")
		(net "M_L_CPU1_SA_DQS_DN<5>")
	)
	(segment
		(start 145.803366 -223.749616)
		(end 145.834862 -223.731328)
		(width 0.09525)
		(layer "In11.Cu")
		(net "M_L_CPU1_SA_DQS_DN<5>")
	)
	(segment
		(start 139.316206 -227.799646)
		(end 139.324588 -227.804472)
		(width 0.09525)
		(layer "In11.Cu")
		(net "M_L_CPU1_SA_DQS_DN<5>")
	)
	(segment
		(start 181.109366 -202.483212)
		(end 181.962806 -201.629772)
		(width 0.16002)
		(layer "In11.Cu")
		(net "M_L_CPU1_SA_DQS_DN<5>")
	)
	(segment
		(start 155.000198 -210.932522)
		(end 154.756866 -210.689444)
		(width 0.16002)
		(layer "In11.Cu")
		(net "M_L_CPU1_SA_DQS_DN<5>")
	)
	(segment
		(start 180.112924 -202.85837)
		(end 180.488082 -202.483212)
		(width 0.16002)
		(layer "In11.Cu")
		(net "M_L_CPU1_SA_DQS_DN<5>")
	)
	(segment
		(start 155.000198 -211.158328)
		(end 155.000198 -210.932522)
		(width 0.16002)
		(layer "In11.Cu")
		(net "M_L_CPU1_SA_DQS_DN<5>")
	)
	(segment
		(start 166.021258 -202.483212)
		(end 166.874698 -201.629772)
		(width 0.16002)
		(layer "In11.Cu")
		(net "M_L_CPU1_SA_DQS_DN<5>")
	)
	(segment
		(start 152.909778 -212.536278)
		(end 153.15311 -212.779356)
		(width 0.16002)
		(layer "In11.Cu")
		(net "M_L_CPU1_SA_DQS_DN<5>")
	)
	(segment
		(start 140.25626 -227.799646)
		(end 140.264642 -227.804472)
		(width 0.09525)
		(layer "In11.Cu")
		(net "M_L_CPU1_SA_DQS_DN<5>")
	)
	(segment
		(start 183.163718 -202.008232)
		(end 185.718704 -202.008232)
		(width 0.16002)
		(layer "In11.Cu")
		(net "M_L_CPU1_SA_DQS_DN<5>")
	)
	(segment
		(start 154.28341 -211.162646)
		(end 154.526742 -211.405724)
		(width 0.16002)
		(layer "In11.Cu")
		(net "M_L_CPU1_SA_DQS_DN<5>")
	)
	(segment
		(start 188.65342 -202.483212)
		(end 189.50686 -201.629772)
		(width 0.16002)
		(layer "In11.Cu")
		(net "M_L_CPU1_SA_DQS_DN<5>")
	)
	(segment
		(start 137.778744 -227.739956)
		(end 137.879582 -227.766626)
		(width 0.09525)
		(layer "In11.Cu")
		(net "M_L_CPU1_SA_DQS_DN<5>")
	)
	(segment
		(start 144.82826 -225.390202)
		(end 144.863312 -225.369628)
		(width 0.09525)
		(layer "In11.Cu")
		(net "M_L_CPU1_SA_DQS_DN<5>")
	)
	(segment
		(start 167.69715 -201.629772)
		(end 167.859964 -201.792586)
		(width 0.16002)
		(layer "In11.Cu")
		(net "M_L_CPU1_SA_DQS_DN<5>")
	)
	(segment
		(start 147.046696 -217.922856)
		(end 152.433274 -212.536278)
		(width 0.16002)
		(layer "In11.Cu")
		(net "M_L_CPU1_SA_DQS_DN<5>")
	)
	(segment
		(start 147.046696 -221.392242)
		(end 147.046696 -217.922856)
		(width 0.16002)
		(layer "In11.Cu")
		(net "M_L_CPU1_SA_DQS_DN<5>")
	)
	(segment
		(start 162.48634 -202.483212)
		(end 166.021258 -202.483212)
		(width 0.16002)
		(layer "In11.Cu")
		(net "M_L_CPU1_SA_DQS_DN<5>")
	)
	(segment
		(start 137.62482 -227.474526)
		(end 137.778744 -227.739956)
		(width 0.09525)
		(layer "In11.Cu")
		(net "M_L_CPU1_SA_DQS_DN<5>")
	)
	(segment
		(start 195.57619 -202.483212)
		(end 196.197474 -202.483212)
		(width 0.16002)
		(layer "In11.Cu")
		(net "M_L_CPU1_SA_DQS_DN<5>")
	)
	(segment
		(start 147.046696 -221.415864)
		(end 147.046696 -221.392242)
		(width 0.09525)
		(layer "In11.Cu")
		(net "M_L_CPU1_SA_DQS_DN<5>")
	)
	(arc
		(start 139.324588 -227.804472)
		(mid 139.50962 -227.850386)
		(end 139.693396 -227.799646)
		(width 0.09525)
		(layer "In11.Cu")
		(net "M_L_CPU1_SA_DQS_DN<5>")
	)
	(arc
		(start 144.89811 -225.349562)
		(mid 145.011895 -225.215518)
		(end 145.052796 -225.044508)
		(width 0.09525)
		(layer "In11.Cu")
		(net "M_L_CPU1_SA_DQS_DN<5>")
	)
	(arc
		(start 140.63345 -227.799646)
		(mid 140.914882 -227.723891)
		(end 141.196314 -227.799646)
		(width 0.09525)
		(layer "In11.Cu")
		(net "M_L_CPU1_SA_DQS_DN<5>")
	)
	(arc
		(start 137.879582 -227.766626)
		(mid 138.131723 -227.725056)
		(end 138.376152 -227.799646)
		(width 0.09525)
		(layer "In11.Cu")
		(net "M_L_CPU1_SA_DQS_DN<5>")
	)
	(arc
		(start 141.57325 -227.799646)
		(mid 141.854682 -227.723891)
		(end 142.136114 -227.799646)
		(width 0.09525)
		(layer "In11.Cu")
		(net "M_L_CPU1_SA_DQS_DN<5>")
	)
	(arc
		(start 144.423892 -226.162108)
		(mid 144.540593 -226.027579)
		(end 144.582642 -225.854514)
		(width 0.09525)
		(layer "In11.Cu")
		(net "M_L_CPU1_SA_DQS_DN<5>")
	)
	(arc
		(start 139.693396 -227.799646)
		(mid 139.974828 -227.723891)
		(end 140.25626 -227.799646)
		(width 0.09525)
		(layer "In11.Cu")
		(net "M_L_CPU1_SA_DQS_DN<5>")
	)
	(arc
		(start 141.196314 -227.799646)
		(mid 141.384782 -227.850323)
		(end 141.57325 -227.799646)
		(width 0.09525)
		(layer "In11.Cu")
		(net "M_L_CPU1_SA_DQS_DN<5>")
	)
	(arc
		(start 143.642588 -227.474526)
		(mid 143.706985 -227.21322)
		(end 143.885412 -227.011738)
		(width 0.09525)
		(layer "In11.Cu")
		(net "M_L_CPU1_SA_DQS_DN<5>")
	)
	(arc
		(start 144.582642 -225.854514)
		(mid 144.647889 -225.591911)
		(end 144.82826 -225.390202)
		(width 0.09525)
		(layer "In11.Cu")
		(net "M_L_CPU1_SA_DQS_DN<5>")
	)
	(arc
		(start 143.08455 -227.804472)
		(mid 143.269582 -227.850386)
		(end 143.453358 -227.799646)
		(width 0.09525)
		(layer "In11.Cu")
		(net "M_L_CPU1_SA_DQS_DN<5>")
	)
	(arc
		(start 144.112742 -226.66452)
		(mid 144.177139 -226.403214)
		(end 144.355566 -226.201732)
		(width 0.09525)
		(layer "In11.Cu")
		(net "M_L_CPU1_SA_DQS_DN<5>")
	)
	(arc
		(start 138.376152 -227.799646)
		(mid 138.559927 -227.850418)
		(end 138.74496 -227.804472)
		(width 0.09525)
		(layer "In11.Cu")
		(net "M_L_CPU1_SA_DQS_DN<5>")
	)
	(arc
		(start 145.992342 -223.424496)
		(mid 146.020076 -223.250033)
		(end 146.100546 -223.092772)
		(width 0.09525)
		(layer "In11.Cu")
		(net "M_L_CPU1_SA_DQS_DN<5>")
	)
	(arc
		(start 145.052796 -225.044508)
		(mid 145.116831 -224.783831)
		(end 145.29435 -224.582482)
		(width 0.09525)
		(layer "In11.Cu")
		(net "M_L_CPU1_SA_DQS_DN<5>")
	)
	(arc
		(start 143.957294 -226.970082)
		(mid 144.071673 -226.835943)
		(end 144.112742 -226.66452)
		(width 0.09525)
		(layer "In11.Cu")
		(net "M_L_CPU1_SA_DQS_DN<5>")
	)
	(arc
		(start 142.136114 -227.799646)
		(mid 142.319889 -227.850418)
		(end 142.504922 -227.804472)
		(width 0.09525)
		(layer "In11.Cu")
		(net "M_L_CPU1_SA_DQS_DN<5>")
	)
	(arc
		(start 145.834862 -223.731328)
		(mid 145.95066 -223.596934)
		(end 145.992342 -223.424496)
		(width 0.09525)
		(layer "In11.Cu")
		(net "M_L_CPU1_SA_DQS_DN<5>")
	)
	(arc
		(start 142.513304 -227.799646)
		(mid 142.794736 -227.723891)
		(end 143.076168 -227.799646)
		(width 0.09525)
		(layer "In11.Cu")
		(net "M_L_CPU1_SA_DQS_DN<5>")
	)
	(arc
		(start 143.48714 -227.780088)
		(mid 143.601519 -227.645949)
		(end 143.642588 -227.474526)
		(width 0.09525)
		(layer "In11.Cu")
		(net "M_L_CPU1_SA_DQS_DN<5>")
	)
	(arc
		(start 145.522442 -224.234502)
		(mid 145.586839 -223.973196)
		(end 145.765266 -223.771714)
		(width 0.09525)
		(layer "In11.Cu")
		(net "M_L_CPU1_SA_DQS_DN<5>")
	)
	(arc
		(start 138.753342 -227.799646)
		(mid 139.034774 -227.723891)
		(end 139.316206 -227.799646)
		(width 0.09525)
		(layer "In11.Cu")
		(net "M_L_CPU1_SA_DQS_DN<5>")
	)
	(arc
		(start 145.363946 -224.542096)
		(mid 145.480495 -224.407518)
		(end 145.522442 -224.234502)
		(width 0.09525)
		(layer "In11.Cu")
		(net "M_L_CPU1_SA_DQS_DN<5>")
	)
	(arc
		(start 140.264642 -227.804472)
		(mid 140.449674 -227.850386)
		(end 140.63345 -227.799646)
		(width 0.09525)
		(layer "In11.Cu")
		(net "M_L_CPU1_SA_DQS_DN<5>")
	)
	(segment
		(start 139.037822 -247.180354)
		(end 139.504674 -246.914416)
		(width 0.12954)
		(layer "F.Cu")
		(net "M_L_CPU1_SA_DQS_DN<4>")
	)
	(segment
		(start 139.504674 -246.914416)
		(end 139.35075 -246.648986)
		(width 0.09525)
		(layer "In11.Cu")
		(net "M_L_CPU1_SA_DQS_DN<4>")
	)
	(segment
		(start 200.181464 -238.286544)
		(end 202.6031 -238.286544)
		(width 0.16002)
		(layer "In11.Cu")
		(net "M_L_CPU1_SA_DQS_DN<4>")
	)
	(segment
		(start 145.144998 -246.53748)
		(end 145.77314 -246.53748)
		(width 0.09525)
		(layer "In11.Cu")
		(net "M_L_CPU1_SA_DQS_DN<4>")
	)
	(segment
		(start 144.01546 -246.589296)
		(end 144.023842 -246.58447)
		(width 0.09525)
		(layer "In11.Cu")
		(net "M_L_CPU1_SA_DQS_DN<4>")
	)
	(segment
		(start 202.6031 -238.286544)
		(end 203.221844 -238.905288)
		(width 0.16002)
		(layer "In11.Cu")
		(net "M_L_CPU1_SA_DQS_DN<4>")
	)
	(segment
		(start 187.840874 -238.890048)
		(end 188.815218 -238.890048)
		(width 0.16002)
		(layer "In11.Cu")
		(net "M_L_CPU1_SA_DQS_DN<4>")
	)
	(segment
		(start 146.156426 -246.920766)
		(end 147.642072 -246.920766)
		(width 0.09525)
		(layer "In11.Cu")
		(net "M_L_CPU1_SA_DQS_DN<4>")
	)
	(segment
		(start 169.785792 -238.067088)
		(end 170.281092 -238.562388)
		(width 0.16002)
		(layer "In11.Cu")
		(net "M_L_CPU1_SA_DQS_DN<4>")
	)
	(segment
		(start 190.049658 -238.067088)
		(end 190.404242 -237.712504)
		(width 0.16002)
		(layer "In11.Cu")
		(net "M_L_CPU1_SA_DQS_DN<4>")
	)
	(segment
		(start 181.271164 -238.890048)
		(end 182.094124 -238.067088)
		(width 0.16002)
		(layer "In11.Cu")
		(net "M_L_CPU1_SA_DQS_DN<4>")
	)
	(segment
		(start 173.72711 -238.890048)
		(end 174.55007 -238.067088)
		(width 0.16002)
		(layer "In11.Cu")
		(net "M_L_CPU1_SA_DQS_DN<4>")
	)
	(segment
		(start 182.094124 -238.067088)
		(end 182.505604 -238.067088)
		(width 0.16002)
		(layer "In11.Cu")
		(net "M_L_CPU1_SA_DQS_DN<4>")
	)
	(segment
		(start 172.752766 -238.890048)
		(end 173.72711 -238.890048)
		(width 0.16002)
		(layer "In11.Cu")
		(net "M_L_CPU1_SA_DQS_DN<4>")
	)
	(segment
		(start 192.913254 -238.562388)
		(end 195.057268 -238.562388)
		(width 0.16002)
		(layer "In11.Cu")
		(net "M_L_CPU1_SA_DQS_DN<4>")
	)
	(segment
		(start 147.701 -246.979694)
		(end 147.724622 -246.979694)
		(width 0.09525)
		(layer "In11.Cu")
		(net "M_L_CPU1_SA_DQS_DN<4>")
	)
	(segment
		(start 174.55007 -238.067088)
		(end 174.96155 -238.067088)
		(width 0.16002)
		(layer "In11.Cu")
		(net "M_L_CPU1_SA_DQS_DN<4>")
	)
	(segment
		(start 158.103316 -246.308626)
		(end 164.229796 -240.182146)
		(width 0.16002)
		(layer "In11.Cu")
		(net "M_L_CPU1_SA_DQS_DN<4>")
	)
	(segment
		(start 203.886816 -238.905288)
		(end 204.080618 -238.711486)
		(width 0.16002)
		(layer "In11.Cu")
		(net "M_L_CPU1_SA_DQS_DN<4>")
	)
	(segment
		(start 204.080618 -238.711486)
		(end 204.66558 -238.711486)
		(width 0.16002)
		(layer "In11.Cu")
		(net "M_L_CPU1_SA_DQS_DN<4>")
	)
	(segment
		(start 197.182232 -238.067088)
		(end 197.593712 -238.067088)
		(width 0.16002)
		(layer "In11.Cu")
		(net "M_L_CPU1_SA_DQS_DN<4>")
	)
	(segment
		(start 165.88613 -240.182146)
		(end 168.001188 -238.067088)
		(width 0.16002)
		(layer "In11.Cu")
		(net "M_L_CPU1_SA_DQS_DN<4>")
	)
	(segment
		(start 142.504922 -246.58447)
		(end 142.513304 -246.589296)
		(width 0.09525)
		(layer "In11.Cu")
		(net "M_L_CPU1_SA_DQS_DN<4>")
	)
	(segment
		(start 187.513214 -238.562388)
		(end 187.840874 -238.890048)
		(width 0.16002)
		(layer "In11.Cu")
		(net "M_L_CPU1_SA_DQS_DN<4>")
	)
	(segment
		(start 197.948296 -237.712504)
		(end 199.607424 -237.712504)
		(width 0.16002)
		(layer "In11.Cu")
		(net "M_L_CPU1_SA_DQS_DN<4>")
	)
	(segment
		(start 205.39964 -238.711486)
		(end 205.974188 -238.711486)
		(width 0.16002)
		(layer "In11.Cu")
		(net "M_L_CPU1_SA_DQS_DN<4>")
	)
	(segment
		(start 164.229796 -240.182146)
		(end 165.88613 -240.182146)
		(width 0.16002)
		(layer "In11.Cu")
		(net "M_L_CPU1_SA_DQS_DN<4>")
	)
	(segment
		(start 147.724622 -246.979694)
		(end 148.076158 -246.979694)
		(width 0.16002)
		(layer "In11.Cu")
		(net "M_L_CPU1_SA_DQS_DN<4>")
	)
	(segment
		(start 188.815218 -238.890048)
		(end 189.638178 -238.067088)
		(width 0.16002)
		(layer "In11.Cu")
		(net "M_L_CPU1_SA_DQS_DN<4>")
	)
	(segment
		(start 204.79258 -238.838486)
		(end 205.27264 -238.838486)
		(width 0.16002)
		(layer "In11.Cu")
		(net "M_L_CPU1_SA_DQS_DN<4>")
	)
	(segment
		(start 143.997426 -246.59971)
		(end 144.01546 -246.589296)
		(width 0.09525)
		(layer "In11.Cu")
		(net "M_L_CPU1_SA_DQS_DN<4>")
	)
	(segment
		(start 145.77314 -246.53748)
		(end 146.156426 -246.920766)
		(width 0.09525)
		(layer "In11.Cu")
		(net "M_L_CPU1_SA_DQS_DN<4>")
	)
	(segment
		(start 203.221844 -238.905288)
		(end 203.886816 -238.905288)
		(width 0.16002)
		(layer "In11.Cu")
		(net "M_L_CPU1_SA_DQS_DN<4>")
	)
	(segment
		(start 199.607424 -237.712504)
		(end 200.181464 -238.286544)
		(width 0.16002)
		(layer "In11.Cu")
		(net "M_L_CPU1_SA_DQS_DN<4>")
	)
	(segment
		(start 148.747226 -246.308626)
		(end 158.103316 -246.308626)
		(width 0.16002)
		(layer "In11.Cu")
		(net "M_L_CPU1_SA_DQS_DN<4>")
	)
	(segment
		(start 189.638178 -238.067088)
		(end 190.049658 -238.067088)
		(width 0.16002)
		(layer "In11.Cu")
		(net "M_L_CPU1_SA_DQS_DN<4>")
	)
	(segment
		(start 176.975262 -237.712504)
		(end 177.825146 -238.562388)
		(width 0.16002)
		(layer "In11.Cu")
		(net "M_L_CPU1_SA_DQS_DN<4>")
	)
	(segment
		(start 190.404242 -237.712504)
		(end 192.06337 -237.712504)
		(width 0.16002)
		(layer "In11.Cu")
		(net "M_L_CPU1_SA_DQS_DN<4>")
	)
	(segment
		(start 139.35075 -246.648986)
		(end 139.374118 -246.562118)
		(width 0.09525)
		(layer "In11.Cu")
		(net "M_L_CPU1_SA_DQS_DN<4>")
	)
	(segment
		(start 182.860188 -237.712504)
		(end 184.519316 -237.712504)
		(width 0.16002)
		(layer "In11.Cu")
		(net "M_L_CPU1_SA_DQS_DN<4>")
	)
	(segment
		(start 143.076168 -246.589296)
		(end 143.08455 -246.58447)
		(width 0.09525)
		(layer "In11.Cu")
		(net "M_L_CPU1_SA_DQS_DN<4>")
	)
	(segment
		(start 195.384928 -238.890048)
		(end 196.359272 -238.890048)
		(width 0.16002)
		(layer "In11.Cu")
		(net "M_L_CPU1_SA_DQS_DN<4>")
	)
	(segment
		(start 174.96155 -238.067088)
		(end 175.316134 -237.712504)
		(width 0.16002)
		(layer "In11.Cu")
		(net "M_L_CPU1_SA_DQS_DN<4>")
	)
	(segment
		(start 184.519316 -237.712504)
		(end 185.3692 -238.562388)
		(width 0.16002)
		(layer "In11.Cu")
		(net "M_L_CPU1_SA_DQS_DN<4>")
	)
	(segment
		(start 185.3692 -238.562388)
		(end 187.513214 -238.562388)
		(width 0.16002)
		(layer "In11.Cu")
		(net "M_L_CPU1_SA_DQS_DN<4>")
	)
	(segment
		(start 144.392142 -246.589296)
		(end 144.410176 -246.59971)
		(width 0.09525)
		(layer "In11.Cu")
		(net "M_L_CPU1_SA_DQS_DN<4>")
	)
	(segment
		(start 205.974188 -238.711486)
		(end 206.248 -238.985298)
		(width 0.16002)
		(layer "In11.Cu")
		(net "M_L_CPU1_SA_DQS_DN<4>")
	)
	(segment
		(start 148.076158 -246.979694)
		(end 148.747226 -246.308626)
		(width 0.16002)
		(layer "In11.Cu")
		(net "M_L_CPU1_SA_DQS_DN<4>")
	)
	(segment
		(start 204.66558 -238.711486)
		(end 204.79258 -238.838486)
		(width 0.16002)
		(layer "In11.Cu")
		(net "M_L_CPU1_SA_DQS_DN<4>")
	)
	(segment
		(start 147.642072 -246.920766)
		(end 147.701 -246.979694)
		(width 0.09525)
		(layer "In11.Cu")
		(net "M_L_CPU1_SA_DQS_DN<4>")
	)
	(segment
		(start 170.281092 -238.562388)
		(end 172.425106 -238.562388)
		(width 0.16002)
		(layer "In11.Cu")
		(net "M_L_CPU1_SA_DQS_DN<4>")
	)
	(segment
		(start 195.057268 -238.562388)
		(end 195.384928 -238.890048)
		(width 0.16002)
		(layer "In11.Cu")
		(net "M_L_CPU1_SA_DQS_DN<4>")
	)
	(segment
		(start 177.825146 -238.562388)
		(end 179.96916 -238.562388)
		(width 0.16002)
		(layer "In11.Cu")
		(net "M_L_CPU1_SA_DQS_DN<4>")
	)
	(segment
		(start 205.27264 -238.838486)
		(end 205.39964 -238.711486)
		(width 0.16002)
		(layer "In11.Cu")
		(net "M_L_CPU1_SA_DQS_DN<4>")
	)
	(segment
		(start 179.96916 -238.562388)
		(end 180.29682 -238.890048)
		(width 0.16002)
		(layer "In11.Cu")
		(net "M_L_CPU1_SA_DQS_DN<4>")
	)
	(segment
		(start 182.505604 -238.067088)
		(end 182.860188 -237.712504)
		(width 0.16002)
		(layer "In11.Cu")
		(net "M_L_CPU1_SA_DQS_DN<4>")
	)
	(segment
		(start 172.425106 -238.562388)
		(end 172.752766 -238.890048)
		(width 0.16002)
		(layer "In11.Cu")
		(net "M_L_CPU1_SA_DQS_DN<4>")
	)
	(segment
		(start 175.316134 -237.712504)
		(end 176.975262 -237.712504)
		(width 0.16002)
		(layer "In11.Cu")
		(net "M_L_CPU1_SA_DQS_DN<4>")
	)
	(segment
		(start 180.29682 -238.890048)
		(end 181.271164 -238.890048)
		(width 0.16002)
		(layer "In11.Cu")
		(net "M_L_CPU1_SA_DQS_DN<4>")
	)
	(segment
		(start 196.359272 -238.890048)
		(end 197.182232 -238.067088)
		(width 0.16002)
		(layer "In11.Cu")
		(net "M_L_CPU1_SA_DQS_DN<4>")
	)
	(segment
		(start 197.593712 -238.067088)
		(end 197.948296 -237.712504)
		(width 0.16002)
		(layer "In11.Cu")
		(net "M_L_CPU1_SA_DQS_DN<4>")
	)
	(segment
		(start 192.06337 -237.712504)
		(end 192.913254 -238.562388)
		(width 0.16002)
		(layer "In11.Cu")
		(net "M_L_CPU1_SA_DQS_DN<4>")
	)
	(segment
		(start 140.25626 -246.589296)
		(end 140.264642 -246.58447)
		(width 0.09525)
		(layer "In11.Cu")
		(net "M_L_CPU1_SA_DQS_DN<4>")
	)
	(segment
		(start 168.001188 -238.067088)
		(end 169.785792 -238.067088)
		(width 0.16002)
		(layer "In11.Cu")
		(net "M_L_CPU1_SA_DQS_DN<4>")
	)
	(arc
		(start 139.693396 -246.589296)
		(mid 139.974828 -246.665051)
		(end 140.25626 -246.589296)
		(width 0.09525)
		(layer "In11.Cu")
		(net "M_L_CPU1_SA_DQS_DN<4>")
	)
	(arc
		(start 140.264642 -246.58447)
		(mid 140.449674 -246.538556)
		(end 140.63345 -246.589296)
		(width 0.09525)
		(layer "In11.Cu")
		(net "M_L_CPU1_SA_DQS_DN<4>")
	)
	(arc
		(start 143.453358 -246.589296)
		(mid 143.724046 -246.664948)
		(end 143.997426 -246.59971)
		(width 0.09525)
		(layer "In11.Cu")
		(net "M_L_CPU1_SA_DQS_DN<4>")
	)
	(arc
		(start 142.136114 -246.589296)
		(mid 142.319889 -246.538524)
		(end 142.504922 -246.58447)
		(width 0.09525)
		(layer "In11.Cu")
		(net "M_L_CPU1_SA_DQS_DN<4>")
	)
	(arc
		(start 144.410176 -246.59971)
		(mid 144.684318 -246.665289)
		(end 144.955768 -246.589296)
		(width 0.09525)
		(layer "In11.Cu")
		(net "M_L_CPU1_SA_DQS_DN<4>")
	)
	(arc
		(start 140.63345 -246.589296)
		(mid 140.914882 -246.665051)
		(end 141.196314 -246.589296)
		(width 0.09525)
		(layer "In11.Cu")
		(net "M_L_CPU1_SA_DQS_DN<4>")
	)
	(arc
		(start 144.023842 -246.58447)
		(mid 144.20862 -246.538677)
		(end 144.392142 -246.589296)
		(width 0.09525)
		(layer "In11.Cu")
		(net "M_L_CPU1_SA_DQS_DN<4>")
	)
	(arc
		(start 141.196314 -246.589296)
		(mid 141.384782 -246.538619)
		(end 141.57325 -246.589296)
		(width 0.09525)
		(layer "In11.Cu")
		(net "M_L_CPU1_SA_DQS_DN<4>")
	)
	(arc
		(start 139.374118 -246.562118)
		(mid 139.5368 -246.539986)
		(end 139.693396 -246.589296)
		(width 0.09525)
		(layer "In11.Cu")
		(net "M_L_CPU1_SA_DQS_DN<4>")
	)
	(arc
		(start 141.57325 -246.589296)
		(mid 141.854682 -246.665051)
		(end 142.136114 -246.589296)
		(width 0.09525)
		(layer "In11.Cu")
		(net "M_L_CPU1_SA_DQS_DN<4>")
	)
	(arc
		(start 142.513304 -246.589296)
		(mid 142.794736 -246.665051)
		(end 143.076168 -246.589296)
		(width 0.09525)
		(layer "In11.Cu")
		(net "M_L_CPU1_SA_DQS_DN<4>")
	)
	(arc
		(start 143.08455 -246.58447)
		(mid 143.269582 -246.538556)
		(end 143.453358 -246.589296)
		(width 0.09525)
		(layer "In11.Cu")
		(net "M_L_CPU1_SA_DQS_DN<4>")
	)
	(arc
		(start 144.955768 -246.589296)
		(mid 145.046951 -246.550866)
		(end 145.144998 -246.53748)
		(width 0.09525)
		(layer "In11.Cu")
		(net "M_L_CPU1_SA_DQS_DN<4>")
	)
	(segment
		(start 139.037822 -242.320318)
		(end 139.504674 -242.05438)
		(width 0.12954)
		(layer "F.Cu")
		(net "M_L_CPU1_SA_DQS_DN<3>")
	)
	(segment
		(start 144.392142 -241.72926)
		(end 144.410176 -241.739674)
		(width 0.09525)
		(layer "In11.Cu")
		(net "M_L_CPU1_SA_DQS_DN<3>")
	)
	(segment
		(start 204.080618 -229.361492)
		(end 204.68336 -229.361492)
		(width 0.16002)
		(layer "In11.Cu")
		(net "M_L_CPU1_SA_DQS_DN<3>")
	)
	(segment
		(start 199.607424 -228.36251)
		(end 200.181464 -228.93655)
		(width 0.16002)
		(layer "In11.Cu")
		(net "M_L_CPU1_SA_DQS_DN<3>")
	)
	(segment
		(start 181.271164 -229.540054)
		(end 182.094124 -228.717094)
		(width 0.16002)
		(layer "In11.Cu")
		(net "M_L_CPU1_SA_DQS_DN<3>")
	)
	(segment
		(start 147.339304 -240.947956)
		(end 147.632674 -240.654586)
		(width 0.09525)
		(layer "In11.Cu")
		(net "M_L_CPU1_SA_DQS_DN<3>")
	)
	(segment
		(start 187.513214 -229.212394)
		(end 187.840874 -229.540054)
		(width 0.16002)
		(layer "In11.Cu")
		(net "M_L_CPU1_SA_DQS_DN<3>")
	)
	(segment
		(start 143.076168 -241.72926)
		(end 143.08455 -241.724434)
		(width 0.09525)
		(layer "In11.Cu")
		(net "M_L_CPU1_SA_DQS_DN<3>")
	)
	(segment
		(start 145.31594 -241.719608)
		(end 145.350738 -241.739674)
		(width 0.09525)
		(layer "In11.Cu")
		(net "M_L_CPU1_SA_DQS_DN<3>")
	)
	(segment
		(start 202.6031 -228.93655)
		(end 203.221844 -229.555294)
		(width 0.16002)
		(layer "In11.Cu")
		(net "M_L_CPU1_SA_DQS_DN<3>")
	)
	(segment
		(start 166.183056 -229.540054)
		(end 167.006016 -228.717094)
		(width 0.16002)
		(layer "In11.Cu")
		(net "M_L_CPU1_SA_DQS_DN<3>")
	)
	(segment
		(start 189.638178 -228.717094)
		(end 190.049658 -228.717094)
		(width 0.16002)
		(layer "In11.Cu")
		(net "M_L_CPU1_SA_DQS_DN<3>")
	)
	(segment
		(start 195.384928 -229.540054)
		(end 196.359272 -229.540054)
		(width 0.16002)
		(layer "In11.Cu")
		(net "M_L_CPU1_SA_DQS_DN<3>")
	)
	(segment
		(start 142.504922 -241.724434)
		(end 142.513304 -241.72926)
		(width 0.09525)
		(layer "In11.Cu")
		(net "M_L_CPU1_SA_DQS_DN<3>")
	)
	(segment
		(start 204.68336 -229.361492)
		(end 204.81036 -229.488492)
		(width 0.16002)
		(layer "In11.Cu")
		(net "M_L_CPU1_SA_DQS_DN<3>")
	)
	(segment
		(start 190.404242 -228.36251)
		(end 192.06337 -228.36251)
		(width 0.16002)
		(layer "In11.Cu")
		(net "M_L_CPU1_SA_DQS_DN<3>")
	)
	(segment
		(start 195.057268 -229.212394)
		(end 195.384928 -229.540054)
		(width 0.16002)
		(layer "In11.Cu")
		(net "M_L_CPU1_SA_DQS_DN<3>")
	)
	(segment
		(start 192.06337 -228.36251)
		(end 192.913254 -229.212394)
		(width 0.16002)
		(layer "In11.Cu")
		(net "M_L_CPU1_SA_DQS_DN<3>")
	)
	(segment
		(start 140.25626 -241.72926)
		(end 140.264642 -241.724434)
		(width 0.09525)
		(layer "In11.Cu")
		(net "M_L_CPU1_SA_DQS_DN<3>")
	)
	(segment
		(start 203.886816 -229.555294)
		(end 204.080618 -229.361492)
		(width 0.16002)
		(layer "In11.Cu")
		(net "M_L_CPU1_SA_DQS_DN<3>")
	)
	(segment
		(start 146.009868 -241.640868)
		(end 146.70278 -240.947956)
		(width 0.09525)
		(layer "In11.Cu")
		(net "M_L_CPU1_SA_DQS_DN<3>")
	)
	(segment
		(start 205.974188 -229.361492)
		(end 206.248 -229.635304)
		(width 0.16002)
		(layer "In11.Cu")
		(net "M_L_CPU1_SA_DQS_DN<3>")
	)
	(segment
		(start 167.417496 -228.717094)
		(end 167.77208 -228.36251)
		(width 0.16002)
		(layer "In11.Cu")
		(net "M_L_CPU1_SA_DQS_DN<3>")
	)
	(segment
		(start 200.181464 -228.93655)
		(end 202.6031 -228.93655)
		(width 0.16002)
		(layer "In11.Cu")
		(net "M_L_CPU1_SA_DQS_DN<3>")
	)
	(segment
		(start 172.752766 -229.540054)
		(end 173.72711 -229.540054)
		(width 0.16002)
		(layer "In11.Cu")
		(net "M_L_CPU1_SA_DQS_DN<3>")
	)
	(segment
		(start 175.316134 -228.36251)
		(end 176.975262 -228.36251)
		(width 0.16002)
		(layer "In11.Cu")
		(net "M_L_CPU1_SA_DQS_DN<3>")
	)
	(segment
		(start 170.281092 -229.212394)
		(end 172.425106 -229.212394)
		(width 0.16002)
		(layer "In11.Cu")
		(net "M_L_CPU1_SA_DQS_DN<3>")
	)
	(segment
		(start 147.895564 -240.713514)
		(end 147.919186 -240.713514)
		(width 0.09525)
		(layer "In11.Cu")
		(net "M_L_CPU1_SA_DQS_DN<3>")
	)
	(segment
		(start 184.519316 -228.36251)
		(end 185.3692 -229.212394)
		(width 0.16002)
		(layer "In11.Cu")
		(net "M_L_CPU1_SA_DQS_DN<3>")
	)
	(segment
		(start 143.997426 -241.739674)
		(end 144.01546 -241.72926)
		(width 0.09525)
		(layer "In11.Cu")
		(net "M_L_CPU1_SA_DQS_DN<3>")
	)
	(segment
		(start 190.049658 -228.717094)
		(end 190.404242 -228.36251)
		(width 0.16002)
		(layer "In11.Cu")
		(net "M_L_CPU1_SA_DQS_DN<3>")
	)
	(segment
		(start 205.29042 -229.488492)
		(end 205.41742 -229.361492)
		(width 0.16002)
		(layer "In11.Cu")
		(net "M_L_CPU1_SA_DQS_DN<3>")
	)
	(segment
		(start 192.913254 -229.212394)
		(end 195.057268 -229.212394)
		(width 0.16002)
		(layer "In11.Cu")
		(net "M_L_CPU1_SA_DQS_DN<3>")
	)
	(segment
		(start 173.72711 -229.540054)
		(end 174.55007 -228.717094)
		(width 0.16002)
		(layer "In11.Cu")
		(net "M_L_CPU1_SA_DQS_DN<3>")
	)
	(segment
		(start 176.975262 -228.36251)
		(end 177.825146 -229.212394)
		(width 0.16002)
		(layer "In11.Cu")
		(net "M_L_CPU1_SA_DQS_DN<3>")
	)
	(segment
		(start 182.860188 -228.36251)
		(end 184.519316 -228.36251)
		(width 0.16002)
		(layer "In11.Cu")
		(net "M_L_CPU1_SA_DQS_DN<3>")
	)
	(segment
		(start 153.403046 -240.713514)
		(end 164.576506 -229.540054)
		(width 0.16002)
		(layer "In11.Cu")
		(net "M_L_CPU1_SA_DQS_DN<3>")
	)
	(segment
		(start 197.593712 -228.717094)
		(end 197.948296 -228.36251)
		(width 0.16002)
		(layer "In11.Cu")
		(net "M_L_CPU1_SA_DQS_DN<3>")
	)
	(segment
		(start 196.359272 -229.540054)
		(end 197.182232 -228.717094)
		(width 0.16002)
		(layer "In11.Cu")
		(net "M_L_CPU1_SA_DQS_DN<3>")
	)
	(segment
		(start 146.70278 -240.947956)
		(end 147.339304 -240.947956)
		(width 0.09525)
		(layer "In11.Cu")
		(net "M_L_CPU1_SA_DQS_DN<3>")
	)
	(segment
		(start 147.632674 -240.654586)
		(end 147.836636 -240.654586)
		(width 0.09525)
		(layer "In11.Cu")
		(net "M_L_CPU1_SA_DQS_DN<3>")
	)
	(segment
		(start 185.3692 -229.212394)
		(end 187.513214 -229.212394)
		(width 0.16002)
		(layer "In11.Cu")
		(net "M_L_CPU1_SA_DQS_DN<3>")
	)
	(segment
		(start 177.825146 -229.212394)
		(end 179.96916 -229.212394)
		(width 0.16002)
		(layer "In11.Cu")
		(net "M_L_CPU1_SA_DQS_DN<3>")
	)
	(segment
		(start 139.504674 -242.05438)
		(end 139.35075 -241.78895)
		(width 0.09525)
		(layer "In11.Cu")
		(net "M_L_CPU1_SA_DQS_DN<3>")
	)
	(segment
		(start 180.29682 -229.540054)
		(end 181.271164 -229.540054)
		(width 0.16002)
		(layer "In11.Cu")
		(net "M_L_CPU1_SA_DQS_DN<3>")
	)
	(segment
		(start 147.836636 -240.654586)
		(end 147.895564 -240.713514)
		(width 0.09525)
		(layer "In11.Cu")
		(net "M_L_CPU1_SA_DQS_DN<3>")
	)
	(segment
		(start 197.182232 -228.717094)
		(end 197.593712 -228.717094)
		(width 0.16002)
		(layer "In11.Cu")
		(net "M_L_CPU1_SA_DQS_DN<3>")
	)
	(segment
		(start 144.01546 -241.72926)
		(end 144.023842 -241.724434)
		(width 0.09525)
		(layer "In11.Cu")
		(net "M_L_CPU1_SA_DQS_DN<3>")
	)
	(segment
		(start 204.81036 -229.488492)
		(end 205.29042 -229.488492)
		(width 0.16002)
		(layer "In11.Cu")
		(net "M_L_CPU1_SA_DQS_DN<3>")
	)
	(segment
		(start 203.221844 -229.555294)
		(end 203.886816 -229.555294)
		(width 0.16002)
		(layer "In11.Cu")
		(net "M_L_CPU1_SA_DQS_DN<3>")
	)
	(segment
		(start 187.840874 -229.540054)
		(end 188.815218 -229.540054)
		(width 0.16002)
		(layer "In11.Cu")
		(net "M_L_CPU1_SA_DQS_DN<3>")
	)
	(segment
		(start 147.919186 -240.713514)
		(end 153.403046 -240.713514)
		(width 0.16002)
		(layer "In11.Cu")
		(net "M_L_CPU1_SA_DQS_DN<3>")
	)
	(segment
		(start 174.96155 -228.717094)
		(end 175.316134 -228.36251)
		(width 0.16002)
		(layer "In11.Cu")
		(net "M_L_CPU1_SA_DQS_DN<3>")
	)
	(segment
		(start 172.425106 -229.212394)
		(end 172.752766 -229.540054)
		(width 0.16002)
		(layer "In11.Cu")
		(net "M_L_CPU1_SA_DQS_DN<3>")
	)
	(segment
		(start 169.431208 -228.36251)
		(end 170.281092 -229.212394)
		(width 0.16002)
		(layer "In11.Cu")
		(net "M_L_CPU1_SA_DQS_DN<3>")
	)
	(segment
		(start 182.505604 -228.717094)
		(end 182.860188 -228.36251)
		(width 0.16002)
		(layer "In11.Cu")
		(net "M_L_CPU1_SA_DQS_DN<3>")
	)
	(segment
		(start 174.55007 -228.717094)
		(end 174.96155 -228.717094)
		(width 0.16002)
		(layer "In11.Cu")
		(net "M_L_CPU1_SA_DQS_DN<3>")
	)
	(segment
		(start 139.35075 -241.78895)
		(end 139.374118 -241.702082)
		(width 0.09525)
		(layer "In11.Cu")
		(net "M_L_CPU1_SA_DQS_DN<3>")
	)
	(segment
		(start 197.948296 -228.36251)
		(end 199.607424 -228.36251)
		(width 0.16002)
		(layer "In11.Cu")
		(net "M_L_CPU1_SA_DQS_DN<3>")
	)
	(segment
		(start 205.41742 -229.361492)
		(end 205.974188 -229.361492)
		(width 0.16002)
		(layer "In11.Cu")
		(net "M_L_CPU1_SA_DQS_DN<3>")
	)
	(segment
		(start 182.094124 -228.717094)
		(end 182.505604 -228.717094)
		(width 0.16002)
		(layer "In11.Cu")
		(net "M_L_CPU1_SA_DQS_DN<3>")
	)
	(segment
		(start 179.96916 -229.212394)
		(end 180.29682 -229.540054)
		(width 0.16002)
		(layer "In11.Cu")
		(net "M_L_CPU1_SA_DQS_DN<3>")
	)
	(segment
		(start 188.815218 -229.540054)
		(end 189.638178 -228.717094)
		(width 0.16002)
		(layer "In11.Cu")
		(net "M_L_CPU1_SA_DQS_DN<3>")
	)
	(segment
		(start 164.576506 -229.540054)
		(end 166.183056 -229.540054)
		(width 0.16002)
		(layer "In11.Cu")
		(net "M_L_CPU1_SA_DQS_DN<3>")
	)
	(segment
		(start 167.006016 -228.717094)
		(end 167.417496 -228.717094)
		(width 0.16002)
		(layer "In11.Cu")
		(net "M_L_CPU1_SA_DQS_DN<3>")
	)
	(segment
		(start 167.77208 -228.36251)
		(end 169.431208 -228.36251)
		(width 0.16002)
		(layer "In11.Cu")
		(net "M_L_CPU1_SA_DQS_DN<3>")
	)
	(arc
		(start 144.955768 -241.72926)
		(mid 145.134628 -241.678464)
		(end 145.31594 -241.719608)
		(width 0.09525)
		(layer "In11.Cu")
		(net "M_L_CPU1_SA_DQS_DN<3>")
	)
	(arc
		(start 141.196314 -241.72926)
		(mid 141.384782 -241.678583)
		(end 141.57325 -241.72926)
		(width 0.09525)
		(layer "In11.Cu")
		(net "M_L_CPU1_SA_DQS_DN<3>")
	)
	(arc
		(start 139.693396 -241.72926)
		(mid 139.974828 -241.805015)
		(end 140.25626 -241.72926)
		(width 0.09525)
		(layer "In11.Cu")
		(net "M_L_CPU1_SA_DQS_DN<3>")
	)
	(arc
		(start 142.136114 -241.72926)
		(mid 142.319889 -241.678488)
		(end 142.504922 -241.724434)
		(width 0.09525)
		(layer "In11.Cu")
		(net "M_L_CPU1_SA_DQS_DN<3>")
	)
	(arc
		(start 143.453358 -241.72926)
		(mid 143.724046 -241.804912)
		(end 143.997426 -241.739674)
		(width 0.09525)
		(layer "In11.Cu")
		(net "M_L_CPU1_SA_DQS_DN<3>")
	)
	(arc
		(start 144.410176 -241.739674)
		(mid 144.684318 -241.805253)
		(end 144.955768 -241.72926)
		(width 0.09525)
		(layer "In11.Cu")
		(net "M_L_CPU1_SA_DQS_DN<3>")
	)
	(arc
		(start 143.08455 -241.724434)
		(mid 143.269582 -241.67852)
		(end 143.453358 -241.72926)
		(width 0.09525)
		(layer "In11.Cu")
		(net "M_L_CPU1_SA_DQS_DN<3>")
	)
	(arc
		(start 144.023842 -241.724434)
		(mid 144.20862 -241.678641)
		(end 144.392142 -241.72926)
		(width 0.09525)
		(layer "In11.Cu")
		(net "M_L_CPU1_SA_DQS_DN<3>")
	)
	(arc
		(start 140.63345 -241.72926)
		(mid 140.914882 -241.805015)
		(end 141.196314 -241.72926)
		(width 0.09525)
		(layer "In11.Cu")
		(net "M_L_CPU1_SA_DQS_DN<3>")
	)
	(arc
		(start 140.264642 -241.724434)
		(mid 140.449674 -241.67852)
		(end 140.63345 -241.72926)
		(width 0.09525)
		(layer "In11.Cu")
		(net "M_L_CPU1_SA_DQS_DN<3>")
	)
	(arc
		(start 141.57325 -241.72926)
		(mid 141.854682 -241.805015)
		(end 142.136114 -241.72926)
		(width 0.09525)
		(layer "In11.Cu")
		(net "M_L_CPU1_SA_DQS_DN<3>")
	)
	(arc
		(start 142.513304 -241.72926)
		(mid 142.794736 -241.805015)
		(end 143.076168 -241.72926)
		(width 0.09525)
		(layer "In11.Cu")
		(net "M_L_CPU1_SA_DQS_DN<3>")
	)
	(arc
		(start 145.350738 -241.739674)
		(mid 145.696554 -241.798793)
		(end 146.009868 -241.640868)
		(width 0.09525)
		(layer "In11.Cu")
		(net "M_L_CPU1_SA_DQS_DN<3>")
	)
	(arc
		(start 139.374118 -241.702082)
		(mid 139.5368 -241.67995)
		(end 139.693396 -241.72926)
		(width 0.09525)
		(layer "In11.Cu")
		(net "M_L_CPU1_SA_DQS_DN<3>")
	)
	(segment
		(start 139.037822 -237.460282)
		(end 139.504674 -237.194344)
		(width 0.12954)
		(layer "F.Cu")
		(net "M_L_CPU1_SA_DQS_DN<2>")
	)
	(segment
		(start 144.392142 -236.869224)
		(end 144.410176 -236.879638)
		(width 0.09525)
		(layer "In11.Cu")
		(net "M_L_CPU1_SA_DQS_DN<2>")
	)
	(segment
		(start 189.638178 -219.3671)
		(end 190.049658 -219.3671)
		(width 0.16002)
		(layer "In11.Cu")
		(net "M_L_CPU1_SA_DQS_DN<2>")
	)
	(segment
		(start 195.057268 -219.8624)
		(end 195.384928 -220.19006)
		(width 0.16002)
		(layer "In11.Cu")
		(net "M_L_CPU1_SA_DQS_DN<2>")
	)
	(segment
		(start 202.6031 -219.586556)
		(end 203.221844 -220.2053)
		(width 0.16002)
		(layer "In11.Cu")
		(net "M_L_CPU1_SA_DQS_DN<2>")
	)
	(segment
		(start 145.144744 -236.817408)
		(end 145.950432 -236.817408)
		(width 0.09525)
		(layer "In11.Cu")
		(net "M_L_CPU1_SA_DQS_DN<2>")
	)
	(segment
		(start 147.686268 -234.998768)
		(end 147.836636 -234.998768)
		(width 0.09525)
		(layer "In11.Cu")
		(net "M_L_CPU1_SA_DQS_DN<2>")
	)
	(segment
		(start 147.591018 -235.094018)
		(end 147.686268 -234.998768)
		(width 0.09525)
		(layer "In11.Cu")
		(net "M_L_CPU1_SA_DQS_DN<2>")
	)
	(segment
		(start 166.183056 -220.19006)
		(end 167.006016 -219.3671)
		(width 0.16002)
		(layer "In11.Cu")
		(net "M_L_CPU1_SA_DQS_DN<2>")
	)
	(segment
		(start 175.316134 -219.012516)
		(end 176.975262 -219.012516)
		(width 0.16002)
		(layer "In11.Cu")
		(net "M_L_CPU1_SA_DQS_DN<2>")
	)
	(segment
		(start 179.96916 -219.8624)
		(end 180.29682 -220.19006)
		(width 0.16002)
		(layer "In11.Cu")
		(net "M_L_CPU1_SA_DQS_DN<2>")
	)
	(segment
		(start 187.513214 -219.8624)
		(end 187.840874 -220.19006)
		(width 0.16002)
		(layer "In11.Cu")
		(net "M_L_CPU1_SA_DQS_DN<2>")
	)
	(segment
		(start 176.975262 -219.012516)
		(end 177.825146 -219.8624)
		(width 0.16002)
		(layer "In11.Cu")
		(net "M_L_CPU1_SA_DQS_DN<2>")
	)
	(segment
		(start 205.24724 -220.138498)
		(end 205.37424 -220.011498)
		(width 0.16002)
		(layer "In11.Cu")
		(net "M_L_CPU1_SA_DQS_DN<2>")
	)
	(segment
		(start 167.006016 -219.3671)
		(end 167.417496 -219.3671)
		(width 0.16002)
		(layer "In11.Cu")
		(net "M_L_CPU1_SA_DQS_DN<2>")
	)
	(segment
		(start 197.182232 -219.3671)
		(end 197.593712 -219.3671)
		(width 0.16002)
		(layer "In11.Cu")
		(net "M_L_CPU1_SA_DQS_DN<2>")
	)
	(segment
		(start 140.25626 -236.869224)
		(end 140.264642 -236.864398)
		(width 0.09525)
		(layer "In11.Cu")
		(net "M_L_CPU1_SA_DQS_DN<2>")
	)
	(segment
		(start 142.504922 -236.864398)
		(end 142.513304 -236.869224)
		(width 0.09525)
		(layer "In11.Cu")
		(net "M_L_CPU1_SA_DQS_DN<2>")
	)
	(segment
		(start 181.271164 -220.19006)
		(end 182.094124 -219.3671)
		(width 0.16002)
		(layer "In11.Cu")
		(net "M_L_CPU1_SA_DQS_DN<2>")
	)
	(segment
		(start 203.221844 -220.2053)
		(end 203.886816 -220.2053)
		(width 0.16002)
		(layer "In11.Cu")
		(net "M_L_CPU1_SA_DQS_DN<2>")
	)
	(segment
		(start 146.729704 -236.142276)
		(end 147.591018 -235.280962)
		(width 0.09525)
		(layer "In11.Cu")
		(net "M_L_CPU1_SA_DQS_DN<2>")
	)
	(segment
		(start 199.607424 -219.012516)
		(end 200.181464 -219.586556)
		(width 0.16002)
		(layer "In11.Cu")
		(net "M_L_CPU1_SA_DQS_DN<2>")
	)
	(segment
		(start 182.860188 -219.012516)
		(end 184.519316 -219.012516)
		(width 0.16002)
		(layer "In11.Cu")
		(net "M_L_CPU1_SA_DQS_DN<2>")
	)
	(segment
		(start 143.997426 -236.879638)
		(end 144.01546 -236.869224)
		(width 0.09525)
		(layer "In11.Cu")
		(net "M_L_CPU1_SA_DQS_DN<2>")
	)
	(segment
		(start 139.504674 -237.194344)
		(end 139.35075 -236.928914)
		(width 0.09525)
		(layer "In11.Cu")
		(net "M_L_CPU1_SA_DQS_DN<2>")
	)
	(segment
		(start 174.55007 -219.3671)
		(end 174.96155 -219.3671)
		(width 0.16002)
		(layer "In11.Cu")
		(net "M_L_CPU1_SA_DQS_DN<2>")
	)
	(segment
		(start 174.96155 -219.3671)
		(end 175.316134 -219.012516)
		(width 0.16002)
		(layer "In11.Cu")
		(net "M_L_CPU1_SA_DQS_DN<2>")
	)
	(segment
		(start 144.01546 -236.869224)
		(end 144.023842 -236.864398)
		(width 0.09525)
		(layer "In11.Cu")
		(net "M_L_CPU1_SA_DQS_DN<2>")
	)
	(segment
		(start 204.080618 -220.011498)
		(end 204.64018 -220.011498)
		(width 0.16002)
		(layer "In11.Cu")
		(net "M_L_CPU1_SA_DQS_DN<2>")
	)
	(segment
		(start 167.77208 -219.012516)
		(end 169.431208 -219.012516)
		(width 0.16002)
		(layer "In11.Cu")
		(net "M_L_CPU1_SA_DQS_DN<2>")
	)
	(segment
		(start 204.64018 -220.011498)
		(end 204.76718 -220.138498)
		(width 0.16002)
		(layer "In11.Cu")
		(net "M_L_CPU1_SA_DQS_DN<2>")
	)
	(segment
		(start 205.37424 -220.011498)
		(end 205.974188 -220.011498)
		(width 0.16002)
		(layer "In11.Cu")
		(net "M_L_CPU1_SA_DQS_DN<2>")
	)
	(segment
		(start 197.593712 -219.3671)
		(end 197.948296 -219.012516)
		(width 0.16002)
		(layer "In11.Cu")
		(net "M_L_CPU1_SA_DQS_DN<2>")
	)
	(segment
		(start 196.359272 -220.19006)
		(end 197.182232 -219.3671)
		(width 0.16002)
		(layer "In11.Cu")
		(net "M_L_CPU1_SA_DQS_DN<2>")
	)
	(segment
		(start 147.591018 -235.280962)
		(end 147.591018 -235.094018)
		(width 0.09525)
		(layer "In11.Cu")
		(net "M_L_CPU1_SA_DQS_DN<2>")
	)
	(segment
		(start 190.404242 -219.012516)
		(end 192.06337 -219.012516)
		(width 0.16002)
		(layer "In11.Cu")
		(net "M_L_CPU1_SA_DQS_DN<2>")
	)
	(segment
		(start 203.886816 -220.2053)
		(end 204.080618 -220.011498)
		(width 0.16002)
		(layer "In11.Cu")
		(net "M_L_CPU1_SA_DQS_DN<2>")
	)
	(segment
		(start 169.431208 -219.012516)
		(end 170.281092 -219.8624)
		(width 0.16002)
		(layer "In11.Cu")
		(net "M_L_CPU1_SA_DQS_DN<2>")
	)
	(segment
		(start 197.948296 -219.012516)
		(end 199.607424 -219.012516)
		(width 0.16002)
		(layer "In11.Cu")
		(net "M_L_CPU1_SA_DQS_DN<2>")
	)
	(segment
		(start 190.049658 -219.3671)
		(end 190.404242 -219.012516)
		(width 0.16002)
		(layer "In11.Cu")
		(net "M_L_CPU1_SA_DQS_DN<2>")
	)
	(segment
		(start 188.815218 -220.19006)
		(end 189.638178 -219.3671)
		(width 0.16002)
		(layer "In11.Cu")
		(net "M_L_CPU1_SA_DQS_DN<2>")
	)
	(segment
		(start 147.836636 -234.998768)
		(end 147.895564 -235.057696)
		(width 0.09525)
		(layer "In11.Cu")
		(net "M_L_CPU1_SA_DQS_DN<2>")
	)
	(segment
		(start 185.3692 -219.8624)
		(end 187.513214 -219.8624)
		(width 0.16002)
		(layer "In11.Cu")
		(net "M_L_CPU1_SA_DQS_DN<2>")
	)
	(segment
		(start 139.35075 -236.928914)
		(end 139.374118 -236.842046)
		(width 0.09525)
		(layer "In11.Cu")
		(net "M_L_CPU1_SA_DQS_DN<2>")
	)
	(segment
		(start 170.281092 -219.8624)
		(end 172.425106 -219.8624)
		(width 0.16002)
		(layer "In11.Cu")
		(net "M_L_CPU1_SA_DQS_DN<2>")
	)
	(segment
		(start 204.76718 -220.138498)
		(end 205.24724 -220.138498)
		(width 0.16002)
		(layer "In11.Cu")
		(net "M_L_CPU1_SA_DQS_DN<2>")
	)
	(segment
		(start 145.950432 -236.817408)
		(end 146.551904 -236.215936)
		(width 0.09525)
		(layer "In11.Cu")
		(net "M_L_CPU1_SA_DQS_DN<2>")
	)
	(segment
		(start 173.72711 -220.19006)
		(end 174.55007 -219.3671)
		(width 0.16002)
		(layer "In11.Cu")
		(net "M_L_CPU1_SA_DQS_DN<2>")
	)
	(segment
		(start 205.974188 -220.011498)
		(end 206.248 -220.28531)
		(width 0.16002)
		(layer "In11.Cu")
		(net "M_L_CPU1_SA_DQS_DN<2>")
	)
	(segment
		(start 195.384928 -220.19006)
		(end 196.359272 -220.19006)
		(width 0.16002)
		(layer "In11.Cu")
		(net "M_L_CPU1_SA_DQS_DN<2>")
	)
	(segment
		(start 172.425106 -219.8624)
		(end 172.752766 -220.19006)
		(width 0.16002)
		(layer "In11.Cu")
		(net "M_L_CPU1_SA_DQS_DN<2>")
	)
	(segment
		(start 172.752766 -220.19006)
		(end 173.72711 -220.19006)
		(width 0.16002)
		(layer "In11.Cu")
		(net "M_L_CPU1_SA_DQS_DN<2>")
	)
	(segment
		(start 192.913254 -219.8624)
		(end 195.057268 -219.8624)
		(width 0.16002)
		(layer "In11.Cu")
		(net "M_L_CPU1_SA_DQS_DN<2>")
	)
	(segment
		(start 164.306758 -220.19006)
		(end 166.183056 -220.19006)
		(width 0.16002)
		(layer "In11.Cu")
		(net "M_L_CPU1_SA_DQS_DN<2>")
	)
	(segment
		(start 149.439122 -235.057696)
		(end 164.306758 -220.19006)
		(width 0.16002)
		(layer "In11.Cu")
		(net "M_L_CPU1_SA_DQS_DN<2>")
	)
	(segment
		(start 187.840874 -220.19006)
		(end 188.815218 -220.19006)
		(width 0.16002)
		(layer "In11.Cu")
		(net "M_L_CPU1_SA_DQS_DN<2>")
	)
	(segment
		(start 182.094124 -219.3671)
		(end 182.505604 -219.3671)
		(width 0.16002)
		(layer "In11.Cu")
		(net "M_L_CPU1_SA_DQS_DN<2>")
	)
	(segment
		(start 147.919186 -235.057696)
		(end 149.439122 -235.057696)
		(width 0.16002)
		(layer "In11.Cu")
		(net "M_L_CPU1_SA_DQS_DN<2>")
	)
	(segment
		(start 184.519316 -219.012516)
		(end 185.3692 -219.8624)
		(width 0.16002)
		(layer "In11.Cu")
		(net "M_L_CPU1_SA_DQS_DN<2>")
	)
	(segment
		(start 143.076168 -236.869224)
		(end 143.08455 -236.864398)
		(width 0.09525)
		(layer "In11.Cu")
		(net "M_L_CPU1_SA_DQS_DN<2>")
	)
	(segment
		(start 177.825146 -219.8624)
		(end 179.96916 -219.8624)
		(width 0.16002)
		(layer "In11.Cu")
		(net "M_L_CPU1_SA_DQS_DN<2>")
	)
	(segment
		(start 147.895564 -235.057696)
		(end 147.919186 -235.057696)
		(width 0.09525)
		(layer "In11.Cu")
		(net "M_L_CPU1_SA_DQS_DN<2>")
	)
	(segment
		(start 200.181464 -219.586556)
		(end 202.6031 -219.586556)
		(width 0.16002)
		(layer "In11.Cu")
		(net "M_L_CPU1_SA_DQS_DN<2>")
	)
	(segment
		(start 180.29682 -220.19006)
		(end 181.271164 -220.19006)
		(width 0.16002)
		(layer "In11.Cu")
		(net "M_L_CPU1_SA_DQS_DN<2>")
	)
	(segment
		(start 146.551904 -236.215936)
		(end 146.729704 -236.142276)
		(width 0.09525)
		(layer "In11.Cu")
		(net "M_L_CPU1_SA_DQS_DN<2>")
	)
	(segment
		(start 167.417496 -219.3671)
		(end 167.77208 -219.012516)
		(width 0.16002)
		(layer "In11.Cu")
		(net "M_L_CPU1_SA_DQS_DN<2>")
	)
	(segment
		(start 192.06337 -219.012516)
		(end 192.913254 -219.8624)
		(width 0.16002)
		(layer "In11.Cu")
		(net "M_L_CPU1_SA_DQS_DN<2>")
	)
	(segment
		(start 182.505604 -219.3671)
		(end 182.860188 -219.012516)
		(width 0.16002)
		(layer "In11.Cu")
		(net "M_L_CPU1_SA_DQS_DN<2>")
	)
	(arc
		(start 139.374118 -236.842046)
		(mid 139.5368 -236.819914)
		(end 139.693396 -236.869224)
		(width 0.09525)
		(layer "In11.Cu")
		(net "M_L_CPU1_SA_DQS_DN<2>")
	)
	(arc
		(start 143.08455 -236.864398)
		(mid 143.269582 -236.818484)
		(end 143.453358 -236.869224)
		(width 0.09525)
		(layer "In11.Cu")
		(net "M_L_CPU1_SA_DQS_DN<2>")
	)
	(arc
		(start 140.63345 -236.869224)
		(mid 140.914882 -236.944979)
		(end 141.196314 -236.869224)
		(width 0.09525)
		(layer "In11.Cu")
		(net "M_L_CPU1_SA_DQS_DN<2>")
	)
	(arc
		(start 141.57325 -236.869224)
		(mid 141.854682 -236.944979)
		(end 142.136114 -236.869224)
		(width 0.09525)
		(layer "In11.Cu")
		(net "M_L_CPU1_SA_DQS_DN<2>")
	)
	(arc
		(start 142.513304 -236.869224)
		(mid 142.794736 -236.944979)
		(end 143.076168 -236.869224)
		(width 0.09525)
		(layer "In11.Cu")
		(net "M_L_CPU1_SA_DQS_DN<2>")
	)
	(arc
		(start 141.196314 -236.869224)
		(mid 141.384782 -236.818547)
		(end 141.57325 -236.869224)
		(width 0.09525)
		(layer "In11.Cu")
		(net "M_L_CPU1_SA_DQS_DN<2>")
	)
	(arc
		(start 143.453358 -236.869224)
		(mid 143.724046 -236.944876)
		(end 143.997426 -236.879638)
		(width 0.09525)
		(layer "In11.Cu")
		(net "M_L_CPU1_SA_DQS_DN<2>")
	)
	(arc
		(start 142.136114 -236.869224)
		(mid 142.319889 -236.818452)
		(end 142.504922 -236.864398)
		(width 0.09525)
		(layer "In11.Cu")
		(net "M_L_CPU1_SA_DQS_DN<2>")
	)
	(arc
		(start 139.693396 -236.869224)
		(mid 139.974828 -236.944979)
		(end 140.25626 -236.869224)
		(width 0.09525)
		(layer "In11.Cu")
		(net "M_L_CPU1_SA_DQS_DN<2>")
	)
	(arc
		(start 140.264642 -236.864398)
		(mid 140.449674 -236.818484)
		(end 140.63345 -236.869224)
		(width 0.09525)
		(layer "In11.Cu")
		(net "M_L_CPU1_SA_DQS_DN<2>")
	)
	(arc
		(start 144.410176 -236.879638)
		(mid 144.684318 -236.945217)
		(end 144.955768 -236.869224)
		(width 0.09525)
		(layer "In11.Cu")
		(net "M_L_CPU1_SA_DQS_DN<2>")
	)
	(arc
		(start 144.955768 -236.869224)
		(mid 145.046828 -236.830828)
		(end 145.144744 -236.817408)
		(width 0.09525)
		(layer "In11.Cu")
		(net "M_L_CPU1_SA_DQS_DN<2>")
	)
	(arc
		(start 144.023842 -236.864398)
		(mid 144.20862 -236.818605)
		(end 144.392142 -236.869224)
		(width 0.09525)
		(layer "In11.Cu")
		(net "M_L_CPU1_SA_DQS_DN<2>")
	)
	(segment
		(start 139.037822 -232.600246)
		(end 139.504674 -232.334308)
		(width 0.12954)
		(layer "F.Cu")
		(net "M_L_CPU1_SA_DQS_DN<1>")
	)
	(segment
		(start 166.183056 -210.840066)
		(end 167.006016 -210.017106)
		(width 0.16002)
		(layer "In11.Cu")
		(net "M_L_CPU1_SA_DQS_DN<1>")
	)
	(segment
		(start 203.886816 -210.855306)
		(end 204.080618 -210.661504)
		(width 0.16002)
		(layer "In11.Cu")
		(net "M_L_CPU1_SA_DQS_DN<1>")
	)
	(segment
		(start 170.281092 -210.512406)
		(end 172.425106 -210.512406)
		(width 0.16002)
		(layer "In11.Cu")
		(net "M_L_CPU1_SA_DQS_DN<1>")
	)
	(segment
		(start 184.519316 -209.662522)
		(end 185.3692 -210.512406)
		(width 0.16002)
		(layer "In11.Cu")
		(net "M_L_CPU1_SA_DQS_DN<1>")
	)
	(segment
		(start 142.504922 -232.004362)
		(end 142.513304 -232.009188)
		(width 0.09525)
		(layer "In11.Cu")
		(net "M_L_CPU1_SA_DQS_DN<1>")
	)
	(segment
		(start 145.071338 -231.920796)
		(end 146.209512 -230.782368)
		(width 0.09525)
		(layer "In11.Cu")
		(net "M_L_CPU1_SA_DQS_DN<1>")
	)
	(segment
		(start 140.25626 -232.009188)
		(end 140.264642 -232.004362)
		(width 0.09525)
		(layer "In11.Cu")
		(net "M_L_CPU1_SA_DQS_DN<1>")
	)
	(segment
		(start 163.210494 -211.164424)
		(end 163.993322 -210.840066)
		(width 0.16002)
		(layer "In11.Cu")
		(net "M_L_CPU1_SA_DQS_DN<1>")
	)
	(segment
		(start 168.262808 -209.662522)
		(end 168.389808 -209.789522)
		(width 0.16002)
		(layer "In11.Cu")
		(net "M_L_CPU1_SA_DQS_DN<1>")
	)
	(segment
		(start 187.840874 -210.840066)
		(end 188.815218 -210.840066)
		(width 0.16002)
		(layer "In11.Cu")
		(net "M_L_CPU1_SA_DQS_DN<1>")
	)
	(segment
		(start 173.72711 -210.840066)
		(end 174.55007 -210.017106)
		(width 0.16002)
		(layer "In11.Cu")
		(net "M_L_CPU1_SA_DQS_DN<1>")
	)
	(segment
		(start 205.22692 -210.788504)
		(end 205.35392 -210.661504)
		(width 0.16002)
		(layer "In11.Cu")
		(net "M_L_CPU1_SA_DQS_DN<1>")
	)
	(segment
		(start 169.431208 -209.662522)
		(end 170.281092 -210.512406)
		(width 0.16002)
		(layer "In11.Cu")
		(net "M_L_CPU1_SA_DQS_DN<1>")
	)
	(segment
		(start 190.049658 -210.017106)
		(end 190.404242 -209.662522)
		(width 0.16002)
		(layer "In11.Cu")
		(net "M_L_CPU1_SA_DQS_DN<1>")
	)
	(segment
		(start 185.3692 -210.512406)
		(end 187.513214 -210.512406)
		(width 0.16002)
		(layer "In11.Cu")
		(net "M_L_CPU1_SA_DQS_DN<1>")
	)
	(segment
		(start 203.221844 -210.855306)
		(end 203.886816 -210.855306)
		(width 0.16002)
		(layer "In11.Cu")
		(net "M_L_CPU1_SA_DQS_DN<1>")
	)
	(segment
		(start 205.974188 -210.661504)
		(end 206.248 -210.935316)
		(width 0.16002)
		(layer "In11.Cu")
		(net "M_L_CPU1_SA_DQS_DN<1>")
	)
	(segment
		(start 172.425106 -210.512406)
		(end 172.752766 -210.840066)
		(width 0.16002)
		(layer "In11.Cu")
		(net "M_L_CPU1_SA_DQS_DN<1>")
	)
	(segment
		(start 197.948296 -209.662522)
		(end 199.607424 -209.662522)
		(width 0.16002)
		(layer "In11.Cu")
		(net "M_L_CPU1_SA_DQS_DN<1>")
	)
	(segment
		(start 181.271164 -210.840066)
		(end 182.094124 -210.017106)
		(width 0.16002)
		(layer "In11.Cu")
		(net "M_L_CPU1_SA_DQS_DN<1>")
	)
	(segment
		(start 176.975262 -209.662522)
		(end 177.825146 -210.512406)
		(width 0.16002)
		(layer "In11.Cu")
		(net "M_L_CPU1_SA_DQS_DN<1>")
	)
	(segment
		(start 139.35075 -232.068878)
		(end 139.374118 -231.98201)
		(width 0.09525)
		(layer "In11.Cu")
		(net "M_L_CPU1_SA_DQS_DN<1>")
	)
	(segment
		(start 204.080618 -210.661504)
		(end 204.61986 -210.661504)
		(width 0.16002)
		(layer "In11.Cu")
		(net "M_L_CPU1_SA_DQS_DN<1>")
	)
	(segment
		(start 163.993322 -210.840066)
		(end 166.183056 -210.840066)
		(width 0.16002)
		(layer "In11.Cu")
		(net "M_L_CPU1_SA_DQS_DN<1>")
	)
	(segment
		(start 147.498562 -228.97846)
		(end 152.28443 -224.193354)
		(width 0.16002)
		(layer "In11.Cu")
		(net "M_L_CPU1_SA_DQS_DN<1>")
	)
	(segment
		(start 147.39874 -228.995224)
		(end 147.481798 -228.995224)
		(width 0.09525)
		(layer "In11.Cu")
		(net "M_L_CPU1_SA_DQS_DN<1>")
	)
	(segment
		(start 139.504674 -232.334308)
		(end 139.35075 -232.068878)
		(width 0.09525)
		(layer "In11.Cu")
		(net "M_L_CPU1_SA_DQS_DN<1>")
	)
	(segment
		(start 200.181464 -210.236562)
		(end 202.6031 -210.236562)
		(width 0.16002)
		(layer "In11.Cu")
		(net "M_L_CPU1_SA_DQS_DN<1>")
	)
	(segment
		(start 189.638178 -210.017106)
		(end 190.049658 -210.017106)
		(width 0.16002)
		(layer "In11.Cu")
		(net "M_L_CPU1_SA_DQS_DN<1>")
	)
	(segment
		(start 199.607424 -209.662522)
		(end 200.181464 -210.236562)
		(width 0.16002)
		(layer "In11.Cu")
		(net "M_L_CPU1_SA_DQS_DN<1>")
	)
	(segment
		(start 168.389808 -209.789522)
		(end 168.847008 -209.789522)
		(width 0.16002)
		(layer "In11.Cu")
		(net "M_L_CPU1_SA_DQS_DN<1>")
	)
	(segment
		(start 197.593712 -210.017106)
		(end 197.948296 -209.662522)
		(width 0.16002)
		(layer "In11.Cu")
		(net "M_L_CPU1_SA_DQS_DN<1>")
	)
	(segment
		(start 196.359272 -210.840066)
		(end 197.182232 -210.017106)
		(width 0.16002)
		(layer "In11.Cu")
		(net "M_L_CPU1_SA_DQS_DN<1>")
	)
	(segment
		(start 179.96916 -210.512406)
		(end 180.29682 -210.840066)
		(width 0.16002)
		(layer "In11.Cu")
		(net "M_L_CPU1_SA_DQS_DN<1>")
	)
	(segment
		(start 147.481798 -228.995224)
		(end 147.498562 -228.97846)
		(width 0.09525)
		(layer "In11.Cu")
		(net "M_L_CPU1_SA_DQS_DN<1>")
	)
	(segment
		(start 174.96155 -210.017106)
		(end 175.316134 -209.662522)
		(width 0.16002)
		(layer "In11.Cu")
		(net "M_L_CPU1_SA_DQS_DN<1>")
	)
	(segment
		(start 204.74686 -210.788504)
		(end 205.22692 -210.788504)
		(width 0.16002)
		(layer "In11.Cu")
		(net "M_L_CPU1_SA_DQS_DN<1>")
	)
	(segment
		(start 180.29682 -210.840066)
		(end 181.271164 -210.840066)
		(width 0.16002)
		(layer "In11.Cu")
		(net "M_L_CPU1_SA_DQS_DN<1>")
	)
	(segment
		(start 182.094124 -210.017106)
		(end 182.505604 -210.017106)
		(width 0.16002)
		(layer "In11.Cu")
		(net "M_L_CPU1_SA_DQS_DN<1>")
	)
	(segment
		(start 195.384928 -210.840066)
		(end 196.359272 -210.840066)
		(width 0.16002)
		(layer "In11.Cu")
		(net "M_L_CPU1_SA_DQS_DN<1>")
	)
	(segment
		(start 167.417496 -210.017106)
		(end 167.77208 -209.662522)
		(width 0.16002)
		(layer "In11.Cu")
		(net "M_L_CPU1_SA_DQS_DN<1>")
	)
	(segment
		(start 143.076168 -232.009188)
		(end 143.08455 -232.004362)
		(width 0.09525)
		(layer "In11.Cu")
		(net "M_L_CPU1_SA_DQS_DN<1>")
	)
	(segment
		(start 167.006016 -210.017106)
		(end 167.417496 -210.017106)
		(width 0.16002)
		(layer "In11.Cu")
		(net "M_L_CPU1_SA_DQS_DN<1>")
	)
	(segment
		(start 168.974008 -209.662522)
		(end 169.431208 -209.662522)
		(width 0.16002)
		(layer "In11.Cu")
		(net "M_L_CPU1_SA_DQS_DN<1>")
	)
	(segment
		(start 182.505604 -210.017106)
		(end 182.860188 -209.662522)
		(width 0.16002)
		(layer "In11.Cu")
		(net "M_L_CPU1_SA_DQS_DN<1>")
	)
	(segment
		(start 174.55007 -210.017106)
		(end 174.96155 -210.017106)
		(width 0.16002)
		(layer "In11.Cu")
		(net "M_L_CPU1_SA_DQS_DN<1>")
	)
	(segment
		(start 192.913254 -210.512406)
		(end 195.057268 -210.512406)
		(width 0.16002)
		(layer "In11.Cu")
		(net "M_L_CPU1_SA_DQS_DN<1>")
	)
	(segment
		(start 146.33702 -230.65486)
		(end 146.33702 -230.056944)
		(width 0.09525)
		(layer "In11.Cu")
		(net "M_L_CPU1_SA_DQS_DN<1>")
	)
	(segment
		(start 187.513214 -210.512406)
		(end 187.840874 -210.840066)
		(width 0.16002)
		(layer "In11.Cu")
		(net "M_L_CPU1_SA_DQS_DN<1>")
	)
	(segment
		(start 167.77208 -209.662522)
		(end 168.262808 -209.662522)
		(width 0.16002)
		(layer "In11.Cu")
		(net "M_L_CPU1_SA_DQS_DN<1>")
	)
	(segment
		(start 152.28443 -222.090488)
		(end 163.210494 -211.164424)
		(width 0.16002)
		(layer "In11.Cu")
		(net "M_L_CPU1_SA_DQS_DN<1>")
	)
	(segment
		(start 168.847008 -209.789522)
		(end 168.974008 -209.662522)
		(width 0.16002)
		(layer "In11.Cu")
		(net "M_L_CPU1_SA_DQS_DN<1>")
	)
	(segment
		(start 195.057268 -210.512406)
		(end 195.384928 -210.840066)
		(width 0.16002)
		(layer "In11.Cu")
		(net "M_L_CPU1_SA_DQS_DN<1>")
	)
	(segment
		(start 188.815218 -210.840066)
		(end 189.638178 -210.017106)
		(width 0.16002)
		(layer "In11.Cu")
		(net "M_L_CPU1_SA_DQS_DN<1>")
	)
	(segment
		(start 172.752766 -210.840066)
		(end 173.72711 -210.840066)
		(width 0.16002)
		(layer "In11.Cu")
		(net "M_L_CPU1_SA_DQS_DN<1>")
	)
	(segment
		(start 175.316134 -209.662522)
		(end 176.975262 -209.662522)
		(width 0.16002)
		(layer "In11.Cu")
		(net "M_L_CPU1_SA_DQS_DN<1>")
	)
	(segment
		(start 192.06337 -209.662522)
		(end 192.913254 -210.512406)
		(width 0.16002)
		(layer "In11.Cu")
		(net "M_L_CPU1_SA_DQS_DN<1>")
	)
	(segment
		(start 190.404242 -209.662522)
		(end 192.06337 -209.662522)
		(width 0.16002)
		(layer "In11.Cu")
		(net "M_L_CPU1_SA_DQS_DN<1>")
	)
	(segment
		(start 204.61986 -210.661504)
		(end 204.74686 -210.788504)
		(width 0.16002)
		(layer "In11.Cu")
		(net "M_L_CPU1_SA_DQS_DN<1>")
	)
	(segment
		(start 182.860188 -209.662522)
		(end 184.519316 -209.662522)
		(width 0.16002)
		(layer "In11.Cu")
		(net "M_L_CPU1_SA_DQS_DN<1>")
	)
	(segment
		(start 202.6031 -210.236562)
		(end 203.221844 -210.855306)
		(width 0.16002)
		(layer "In11.Cu")
		(net "M_L_CPU1_SA_DQS_DN<1>")
	)
	(segment
		(start 197.182232 -210.017106)
		(end 197.593712 -210.017106)
		(width 0.16002)
		(layer "In11.Cu")
		(net "M_L_CPU1_SA_DQS_DN<1>")
	)
	(segment
		(start 177.825146 -210.512406)
		(end 179.96916 -210.512406)
		(width 0.16002)
		(layer "In11.Cu")
		(net "M_L_CPU1_SA_DQS_DN<1>")
	)
	(segment
		(start 144.945862 -232.015284)
		(end 144.956276 -232.009188)
		(width 0.09525)
		(layer "In11.Cu")
		(net "M_L_CPU1_SA_DQS_DN<1>")
	)
	(segment
		(start 205.35392 -210.661504)
		(end 205.974188 -210.661504)
		(width 0.16002)
		(layer "In11.Cu")
		(net "M_L_CPU1_SA_DQS_DN<1>")
	)
	(segment
		(start 152.28443 -224.193354)
		(end 152.28443 -222.090488)
		(width 0.16002)
		(layer "In11.Cu")
		(net "M_L_CPU1_SA_DQS_DN<1>")
	)
	(segment
		(start 146.209512 -230.782368)
		(end 146.33702 -230.65486)
		(width 0.09525)
		(layer "In11.Cu")
		(net "M_L_CPU1_SA_DQS_DN<1>")
	)
	(segment
		(start 146.33702 -230.056944)
		(end 147.39874 -228.995224)
		(width 0.09525)
		(layer "In11.Cu")
		(net "M_L_CPU1_SA_DQS_DN<1>")
	)
	(arc
		(start 141.196314 -232.009188)
		(mid 141.384782 -231.958511)
		(end 141.57325 -232.009188)
		(width 0.09525)
		(layer "In11.Cu")
		(net "M_L_CPU1_SA_DQS_DN<1>")
	)
	(arc
		(start 139.693396 -232.009188)
		(mid 139.974828 -232.084943)
		(end 140.25626 -232.009188)
		(width 0.09525)
		(layer "In11.Cu")
		(net "M_L_CPU1_SA_DQS_DN<1>")
	)
	(arc
		(start 143.453358 -232.009188)
		(mid 143.73479 -232.084943)
		(end 144.016222 -232.009188)
		(width 0.09525)
		(layer "In11.Cu")
		(net "M_L_CPU1_SA_DQS_DN<1>")
	)
	(arc
		(start 142.136114 -232.009188)
		(mid 142.319889 -231.958416)
		(end 142.504922 -232.004362)
		(width 0.09525)
		(layer "In11.Cu")
		(net "M_L_CPU1_SA_DQS_DN<1>")
	)
	(arc
		(start 143.08455 -232.004362)
		(mid 143.269582 -231.958448)
		(end 143.453358 -232.009188)
		(width 0.09525)
		(layer "In11.Cu")
		(net "M_L_CPU1_SA_DQS_DN<1>")
	)
	(arc
		(start 140.63345 -232.009188)
		(mid 140.914882 -232.084943)
		(end 141.196314 -232.009188)
		(width 0.09525)
		(layer "In11.Cu")
		(net "M_L_CPU1_SA_DQS_DN<1>")
	)
	(arc
		(start 144.016222 -232.009188)
		(mid 144.204944 -231.958384)
		(end 144.393666 -232.009188)
		(width 0.09525)
		(layer "In11.Cu")
		(net "M_L_CPU1_SA_DQS_DN<1>")
	)
	(arc
		(start 141.57325 -232.009188)
		(mid 141.854682 -232.084943)
		(end 142.136114 -232.009188)
		(width 0.09525)
		(layer "In11.Cu")
		(net "M_L_CPU1_SA_DQS_DN<1>")
	)
	(arc
		(start 144.956276 -232.009188)
		(mid 145.013125 -231.971472)
		(end 145.064988 -231.927146)
		(width 0.09525)
		(layer "In11.Cu")
		(net "M_L_CPU1_SA_DQS_DN<1>")
	)
	(arc
		(start 139.374118 -231.98201)
		(mid 139.5368 -231.959878)
		(end 139.693396 -232.009188)
		(width 0.09525)
		(layer "In11.Cu")
		(net "M_L_CPU1_SA_DQS_DN<1>")
	)
	(arc
		(start 145.064988 -231.927146)
		(mid 145.068176 -231.923984)
		(end 145.071338 -231.920796)
		(width 0.09525)
		(layer "In11.Cu")
		(net "M_L_CPU1_SA_DQS_DN<1>")
	)
	(arc
		(start 140.264642 -232.004362)
		(mid 140.449674 -231.958448)
		(end 140.63345 -232.009188)
		(width 0.09525)
		(layer "In11.Cu")
		(net "M_L_CPU1_SA_DQS_DN<1>")
	)
	(arc
		(start 144.393666 -232.009188)
		(mid 144.668955 -232.084909)
		(end 144.945862 -232.015284)
		(width 0.09525)
		(layer "In11.Cu")
		(net "M_L_CPU1_SA_DQS_DN<1>")
	)
	(arc
		(start 142.513304 -232.009188)
		(mid 142.794736 -232.084943)
		(end 143.076168 -232.009188)
		(width 0.09525)
		(layer "In11.Cu")
		(net "M_L_CPU1_SA_DQS_DN<1>")
	)
	(segment
		(start 139.037822 -227.740464)
		(end 139.504674 -227.474526)
		(width 0.12954)
		(layer "F.Cu")
		(net "M_L_CPU1_SA_DQS_DN<0>")
	)
	(segment
		(start 143.514572 -226.357688)
		(end 143.546068 -226.3394)
		(width 0.09525)
		(layer "In11.Cu")
		(net "M_L_CPU1_SA_DQS_DN<0>")
	)
	(segment
		(start 167.006016 -200.667112)
		(end 167.417496 -200.667112)
		(width 0.16002)
		(layer "In11.Cu")
		(net "M_L_CPU1_SA_DQS_DN<0>")
	)
	(segment
		(start 199.607424 -200.312528)
		(end 200.181464 -200.886568)
		(width 0.16002)
		(layer "In11.Cu")
		(net "M_L_CPU1_SA_DQS_DN<0>")
	)
	(segment
		(start 170.281092 -201.162412)
		(end 172.425106 -201.162412)
		(width 0.16002)
		(layer "In11.Cu")
		(net "M_L_CPU1_SA_DQS_DN<0>")
	)
	(segment
		(start 201.75474 -200.886568)
		(end 202.6031 -200.886568)
		(width 0.16002)
		(layer "In11.Cu")
		(net "M_L_CPU1_SA_DQS_DN<0>")
	)
	(segment
		(start 197.948296 -200.312528)
		(end 199.607424 -200.312528)
		(width 0.16002)
		(layer "In11.Cu")
		(net "M_L_CPU1_SA_DQS_DN<0>")
	)
	(segment
		(start 205.974188 -201.31151)
		(end 206.248 -201.585322)
		(width 0.16002)
		(layer "In11.Cu")
		(net "M_L_CPU1_SA_DQS_DN<0>")
	)
	(segment
		(start 189.638178 -200.667112)
		(end 190.049658 -200.667112)
		(width 0.16002)
		(layer "In11.Cu")
		(net "M_L_CPU1_SA_DQS_DN<0>")
	)
	(segment
		(start 146.398234 -222.099378)
		(end 146.398234 -221.257368)
		(width 0.09525)
		(layer "In11.Cu")
		(net "M_L_CPU1_SA_DQS_DN<0>")
	)
	(segment
		(start 172.425106 -201.162412)
		(end 172.752766 -201.490072)
		(width 0.16002)
		(layer "In11.Cu")
		(net "M_L_CPU1_SA_DQS_DN<0>")
	)
	(segment
		(start 146.457416 -221.174564)
		(end 146.457416 -217.678762)
		(width 0.16002)
		(layer "In11.Cu")
		(net "M_L_CPU1_SA_DQS_DN<0>")
	)
	(segment
		(start 144.486122 -224.719388)
		(end 144.522698 -224.698052)
		(width 0.09525)
		(layer "In11.Cu")
		(net "M_L_CPU1_SA_DQS_DN<0>")
	)
	(segment
		(start 204.81036 -201.43851)
		(end 205.29042 -201.43851)
		(width 0.16002)
		(layer "In11.Cu")
		(net "M_L_CPU1_SA_DQS_DN<0>")
	)
	(segment
		(start 177.825146 -201.162412)
		(end 179.96916 -201.162412)
		(width 0.16002)
		(layer "In11.Cu")
		(net "M_L_CPU1_SA_DQS_DN<0>")
	)
	(segment
		(start 144.956276 -223.909382)
		(end 144.991328 -223.888808)
		(width 0.09525)
		(layer "In11.Cu")
		(net "M_L_CPU1_SA_DQS_DN<0>")
	)
	(segment
		(start 201.62774 -201.013568)
		(end 201.75474 -200.886568)
		(width 0.16002)
		(layer "In11.Cu")
		(net "M_L_CPU1_SA_DQS_DN<0>")
	)
	(segment
		(start 182.860188 -200.312528)
		(end 184.519316 -200.312528)
		(width 0.16002)
		(layer "In11.Cu")
		(net "M_L_CPU1_SA_DQS_DN<0>")
	)
	(segment
		(start 144.015968 -225.529394)
		(end 144.055338 -225.506534)
		(width 0.09525)
		(layer "In11.Cu")
		(net "M_L_CPU1_SA_DQS_DN<0>")
	)
	(segment
		(start 192.06337 -200.312528)
		(end 192.913254 -201.162412)
		(width 0.16002)
		(layer "In11.Cu")
		(net "M_L_CPU1_SA_DQS_DN<0>")
	)
	(segment
		(start 182.094124 -200.667112)
		(end 182.505604 -200.667112)
		(width 0.16002)
		(layer "In11.Cu")
		(net "M_L_CPU1_SA_DQS_DN<0>")
	)
	(segment
		(start 190.404242 -200.312528)
		(end 192.06337 -200.312528)
		(width 0.16002)
		(layer "In11.Cu")
		(net "M_L_CPU1_SA_DQS_DN<0>")
	)
	(segment
		(start 185.3692 -201.162412)
		(end 187.513214 -201.162412)
		(width 0.16002)
		(layer "In11.Cu")
		(net "M_L_CPU1_SA_DQS_DN<0>")
	)
	(segment
		(start 196.359272 -201.490072)
		(end 197.182232 -200.667112)
		(width 0.16002)
		(layer "In11.Cu")
		(net "M_L_CPU1_SA_DQS_DN<0>")
	)
	(segment
		(start 203.886816 -201.505312)
		(end 204.080618 -201.31151)
		(width 0.16002)
		(layer "In11.Cu")
		(net "M_L_CPU1_SA_DQS_DN<0>")
	)
	(segment
		(start 202.6031 -200.886568)
		(end 203.221844 -201.505312)
		(width 0.16002)
		(layer "In11.Cu")
		(net "M_L_CPU1_SA_DQS_DN<0>")
	)
	(segment
		(start 146.457416 -217.678762)
		(end 162.646106 -201.490072)
		(width 0.16002)
		(layer "In11.Cu")
		(net "M_L_CPU1_SA_DQS_DN<0>")
	)
	(segment
		(start 140.25626 -227.149406)
		(end 140.264642 -227.14458)
		(width 0.09525)
		(layer "In11.Cu")
		(net "M_L_CPU1_SA_DQS_DN<0>")
	)
	(segment
		(start 142.504922 -227.14458)
		(end 142.513304 -227.149406)
		(width 0.09525)
		(layer "In11.Cu")
		(net "M_L_CPU1_SA_DQS_DN<0>")
	)
	(segment
		(start 175.316134 -200.312528)
		(end 176.975262 -200.312528)
		(width 0.16002)
		(layer "In11.Cu")
		(net "M_L_CPU1_SA_DQS_DN<0>")
	)
	(segment
		(start 176.975262 -200.312528)
		(end 177.825146 -201.162412)
		(width 0.16002)
		(layer "In11.Cu")
		(net "M_L_CPU1_SA_DQS_DN<0>")
	)
	(segment
		(start 172.752766 -201.490072)
		(end 173.72711 -201.490072)
		(width 0.16002)
		(layer "In11.Cu")
		(net "M_L_CPU1_SA_DQS_DN<0>")
	)
	(segment
		(start 192.913254 -201.162412)
		(end 195.057268 -201.162412)
		(width 0.16002)
		(layer "In11.Cu")
		(net "M_L_CPU1_SA_DQS_DN<0>")
	)
	(segment
		(start 205.41742 -201.31151)
		(end 205.974188 -201.31151)
		(width 0.16002)
		(layer "In11.Cu")
		(net "M_L_CPU1_SA_DQS_DN<0>")
	)
	(segment
		(start 201.14768 -201.013568)
		(end 201.62774 -201.013568)
		(width 0.16002)
		(layer "In11.Cu")
		(net "M_L_CPU1_SA_DQS_DN<0>")
	)
	(segment
		(start 190.049658 -200.667112)
		(end 190.404242 -200.312528)
		(width 0.16002)
		(layer "In11.Cu")
		(net "M_L_CPU1_SA_DQS_DN<0>")
	)
	(segment
		(start 145.7071 -222.790512)
		(end 146.398234 -222.099378)
		(width 0.09525)
		(layer "In11.Cu")
		(net "M_L_CPU1_SA_DQS_DN<0>")
	)
	(segment
		(start 180.29682 -201.490072)
		(end 181.271164 -201.490072)
		(width 0.16002)
		(layer "In11.Cu")
		(net "M_L_CPU1_SA_DQS_DN<0>")
	)
	(segment
		(start 139.504674 -227.474526)
		(end 139.35075 -227.209096)
		(width 0.09525)
		(layer "In11.Cu")
		(net "M_L_CPU1_SA_DQS_DN<0>")
	)
	(segment
		(start 162.646106 -201.490072)
		(end 166.183056 -201.490072)
		(width 0.16002)
		(layer "In11.Cu")
		(net "M_L_CPU1_SA_DQS_DN<0>")
	)
	(segment
		(start 167.77208 -200.312528)
		(end 169.431208 -200.312528)
		(width 0.16002)
		(layer "In11.Cu")
		(net "M_L_CPU1_SA_DQS_DN<0>")
	)
	(segment
		(start 179.96916 -201.162412)
		(end 180.29682 -201.490072)
		(width 0.16002)
		(layer "In11.Cu")
		(net "M_L_CPU1_SA_DQS_DN<0>")
	)
	(segment
		(start 166.183056 -201.490072)
		(end 167.006016 -200.667112)
		(width 0.16002)
		(layer "In11.Cu")
		(net "M_L_CPU1_SA_DQS_DN<0>")
	)
	(segment
		(start 145.392648 -223.118934)
		(end 145.4658 -223.076516)
		(width 0.09525)
		(layer "In11.Cu")
		(net "M_L_CPU1_SA_DQS_DN<0>")
	)
	(segment
		(start 197.593712 -200.667112)
		(end 197.948296 -200.312528)
		(width 0.16002)
		(layer "In11.Cu")
		(net "M_L_CPU1_SA_DQS_DN<0>")
	)
	(segment
		(start 139.35075 -227.209096)
		(end 139.374118 -227.122228)
		(width 0.09525)
		(layer "In11.Cu")
		(net "M_L_CPU1_SA_DQS_DN<0>")
	)
	(segment
		(start 187.840874 -201.490072)
		(end 188.815218 -201.490072)
		(width 0.16002)
		(layer "In11.Cu")
		(net "M_L_CPU1_SA_DQS_DN<0>")
	)
	(segment
		(start 181.271164 -201.490072)
		(end 182.094124 -200.667112)
		(width 0.16002)
		(layer "In11.Cu")
		(net "M_L_CPU1_SA_DQS_DN<0>")
	)
	(segment
		(start 204.080618 -201.31151)
		(end 204.68336 -201.31151)
		(width 0.16002)
		(layer "In11.Cu")
		(net "M_L_CPU1_SA_DQS_DN<0>")
	)
	(segment
		(start 173.72711 -201.490072)
		(end 174.55007 -200.667112)
		(width 0.16002)
		(layer "In11.Cu")
		(net "M_L_CPU1_SA_DQS_DN<0>")
	)
	(segment
		(start 200.181464 -200.886568)
		(end 201.02068 -200.886568)
		(width 0.16002)
		(layer "In11.Cu")
		(net "M_L_CPU1_SA_DQS_DN<0>")
	)
	(segment
		(start 169.431208 -200.312528)
		(end 170.281092 -201.162412)
		(width 0.16002)
		(layer "In11.Cu")
		(net "M_L_CPU1_SA_DQS_DN<0>")
	)
	(segment
		(start 145.468848 -223.074484)
		(end 145.46961 -223.073976)
		(width 0.09525)
		(layer "In11.Cu")
		(net "M_L_CPU1_SA_DQS_DN<0>")
	)
	(segment
		(start 167.417496 -200.667112)
		(end 167.77208 -200.312528)
		(width 0.16002)
		(layer "In11.Cu")
		(net "M_L_CPU1_SA_DQS_DN<0>")
	)
	(segment
		(start 143.983456 -225.54819)
		(end 144.015968 -225.529394)
		(width 0.09525)
		(layer "In11.Cu")
		(net "M_L_CPU1_SA_DQS_DN<0>")
	)
	(segment
		(start 187.513214 -201.162412)
		(end 187.840874 -201.490072)
		(width 0.16002)
		(layer "In11.Cu")
		(net "M_L_CPU1_SA_DQS_DN<0>")
	)
	(segment
		(start 203.221844 -201.505312)
		(end 203.886816 -201.505312)
		(width 0.16002)
		(layer "In11.Cu")
		(net "M_L_CPU1_SA_DQS_DN<0>")
	)
	(segment
		(start 144.454626 -224.737676)
		(end 144.486122 -224.719388)
		(width 0.09525)
		(layer "In11.Cu")
		(net "M_L_CPU1_SA_DQS_DN<0>")
	)
	(segment
		(start 182.505604 -200.667112)
		(end 182.860188 -200.312528)
		(width 0.16002)
		(layer "In11.Cu")
		(net "M_L_CPU1_SA_DQS_DN<0>")
	)
	(segment
		(start 143.076168 -227.149406)
		(end 143.114268 -227.127308)
		(width 0.09525)
		(layer "In11.Cu")
		(net "M_L_CPU1_SA_DQS_DN<0>")
	)
	(segment
		(start 205.29042 -201.43851)
		(end 205.41742 -201.31151)
		(width 0.16002)
		(layer "In11.Cu")
		(net "M_L_CPU1_SA_DQS_DN<0>")
	)
	(segment
		(start 174.96155 -200.667112)
		(end 175.316134 -200.312528)
		(width 0.16002)
		(layer "In11.Cu")
		(net "M_L_CPU1_SA_DQS_DN<0>")
	)
	(segment
		(start 201.02068 -200.886568)
		(end 201.14768 -201.013568)
		(width 0.16002)
		(layer "In11.Cu")
		(net "M_L_CPU1_SA_DQS_DN<0>")
	)
	(segment
		(start 204.68336 -201.31151)
		(end 204.81036 -201.43851)
		(width 0.16002)
		(layer "In11.Cu")
		(net "M_L_CPU1_SA_DQS_DN<0>")
	)
	(segment
		(start 174.55007 -200.667112)
		(end 174.96155 -200.667112)
		(width 0.16002)
		(layer "In11.Cu")
		(net "M_L_CPU1_SA_DQS_DN<0>")
	)
	(segment
		(start 146.457416 -221.198186)
		(end 146.457416 -221.174564)
		(width 0.09525)
		(layer "In11.Cu")
		(net "M_L_CPU1_SA_DQS_DN<0>")
	)
	(segment
		(start 188.815218 -201.490072)
		(end 189.638178 -200.667112)
		(width 0.16002)
		(layer "In11.Cu")
		(net "M_L_CPU1_SA_DQS_DN<0>")
	)
	(segment
		(start 195.384928 -201.490072)
		(end 196.359272 -201.490072)
		(width 0.16002)
		(layer "In11.Cu")
		(net "M_L_CPU1_SA_DQS_DN<0>")
	)
	(segment
		(start 197.182232 -200.667112)
		(end 197.593712 -200.667112)
		(width 0.16002)
		(layer "In11.Cu")
		(net "M_L_CPU1_SA_DQS_DN<0>")
	)
	(segment
		(start 184.519316 -200.312528)
		(end 185.3692 -201.162412)
		(width 0.16002)
		(layer "In11.Cu")
		(net "M_L_CPU1_SA_DQS_DN<0>")
	)
	(segment
		(start 143.546068 -226.3394)
		(end 143.58112 -226.318826)
		(width 0.09525)
		(layer "In11.Cu")
		(net "M_L_CPU1_SA_DQS_DN<0>")
	)
	(segment
		(start 146.398234 -221.257368)
		(end 146.457416 -221.198186)
		(width 0.09525)
		(layer "In11.Cu")
		(net "M_L_CPU1_SA_DQS_DN<0>")
	)
	(segment
		(start 195.057268 -201.162412)
		(end 195.384928 -201.490072)
		(width 0.16002)
		(layer "In11.Cu")
		(net "M_L_CPU1_SA_DQS_DN<0>")
	)
	(segment
		(start 144.921478 -223.929448)
		(end 144.956276 -223.909382)
		(width 0.09525)
		(layer "In11.Cu")
		(net "M_L_CPU1_SA_DQS_DN<0>")
	)
	(arc
		(start 139.693396 -227.149406)
		(mid 139.974828 -227.225161)
		(end 140.25626 -227.149406)
		(width 0.09525)
		(layer "In11.Cu")
		(net "M_L_CPU1_SA_DQS_DN<0>")
	)
	(arc
		(start 141.196314 -227.149406)
		(mid 141.384782 -227.098729)
		(end 141.57325 -227.149406)
		(width 0.09525)
		(layer "In11.Cu")
		(net "M_L_CPU1_SA_DQS_DN<0>")
	)
	(arc
		(start 140.63345 -227.149406)
		(mid 140.914882 -227.225161)
		(end 141.196314 -227.149406)
		(width 0.09525)
		(layer "In11.Cu")
		(net "M_L_CPU1_SA_DQS_DN<0>")
	)
	(arc
		(start 145.4658 -223.076516)
		(mid 145.467326 -223.075502)
		(end 145.468848 -223.074484)
		(width 0.09525)
		(layer "In11.Cu")
		(net "M_L_CPU1_SA_DQS_DN<0>")
	)
	(arc
		(start 143.357092 -226.66452)
		(mid 143.398757 -226.492073)
		(end 143.514572 -226.357688)
		(width 0.09525)
		(layer "In11.Cu")
		(net "M_L_CPU1_SA_DQS_DN<0>")
	)
	(arc
		(start 143.114268 -227.127308)
		(mid 143.292718 -226.925838)
		(end 143.357092 -226.66452)
		(width 0.09525)
		(layer "In11.Cu")
		(net "M_L_CPU1_SA_DQS_DN<0>")
	)
	(arc
		(start 144.522698 -224.698052)
		(mid 144.70207 -224.496457)
		(end 144.766792 -224.234502)
		(width 0.09525)
		(layer "In11.Cu")
		(net "M_L_CPU1_SA_DQS_DN<0>")
	)
	(arc
		(start 140.264642 -227.14458)
		(mid 140.449674 -227.098666)
		(end 140.63345 -227.149406)
		(width 0.09525)
		(layer "In11.Cu")
		(net "M_L_CPU1_SA_DQS_DN<0>")
	)
	(arc
		(start 145.46961 -223.073976)
		(mid 145.56672 -222.986723)
		(end 145.64106 -222.879412)
		(width 0.09525)
		(layer "In11.Cu")
		(net "M_L_CPU1_SA_DQS_DN<0>")
	)
	(arc
		(start 143.826738 -225.854514)
		(mid 143.868195 -225.682474)
		(end 143.983456 -225.54819)
		(width 0.09525)
		(layer "In11.Cu")
		(net "M_L_CPU1_SA_DQS_DN<0>")
	)
	(arc
		(start 145.236946 -223.424496)
		(mid 145.278114 -223.253022)
		(end 145.392648 -223.118934)
		(width 0.09525)
		(layer "In11.Cu")
		(net "M_L_CPU1_SA_DQS_DN<0>")
	)
	(arc
		(start 145.64106 -222.879412)
		(mid 145.670815 -222.832537)
		(end 145.7071 -222.790512)
		(width 0.09525)
		(layer "In11.Cu")
		(net "M_L_CPU1_SA_DQS_DN<0>")
	)
	(arc
		(start 141.57325 -227.149406)
		(mid 141.854682 -227.225161)
		(end 142.136114 -227.149406)
		(width 0.09525)
		(layer "In11.Cu")
		(net "M_L_CPU1_SA_DQS_DN<0>")
	)
	(arc
		(start 142.513304 -227.149406)
		(mid 142.794736 -227.225161)
		(end 143.076168 -227.149406)
		(width 0.09525)
		(layer "In11.Cu")
		(net "M_L_CPU1_SA_DQS_DN<0>")
	)
	(arc
		(start 139.374118 -227.122228)
		(mid 139.5368 -227.100096)
		(end 139.693396 -227.149406)
		(width 0.09525)
		(layer "In11.Cu")
		(net "M_L_CPU1_SA_DQS_DN<0>")
	)
	(arc
		(start 142.136114 -227.149406)
		(mid 142.319889 -227.098634)
		(end 142.504922 -227.14458)
		(width 0.09525)
		(layer "In11.Cu")
		(net "M_L_CPU1_SA_DQS_DN<0>")
	)
	(arc
		(start 143.58112 -226.318826)
		(mid 143.761511 -226.117127)
		(end 143.826738 -225.854514)
		(width 0.09525)
		(layer "In11.Cu")
		(net "M_L_CPU1_SA_DQS_DN<0>")
	)
	(arc
		(start 144.055338 -225.506534)
		(mid 144.233024 -225.305242)
		(end 144.297146 -225.044508)
		(width 0.09525)
		(layer "In11.Cu")
		(net "M_L_CPU1_SA_DQS_DN<0>")
	)
	(arc
		(start 144.297146 -225.044508)
		(mid 144.338811 -224.872061)
		(end 144.454626 -224.737676)
		(width 0.09525)
		(layer "In11.Cu")
		(net "M_L_CPU1_SA_DQS_DN<0>")
	)
	(arc
		(start 144.991328 -223.888808)
		(mid 145.171719 -223.687109)
		(end 145.236946 -223.424496)
		(width 0.09525)
		(layer "In11.Cu")
		(net "M_L_CPU1_SA_DQS_DN<0>")
	)
	(arc
		(start 144.766792 -224.234502)
		(mid 144.807668 -224.06348)
		(end 144.921478 -223.929448)
		(width 0.09525)
		(layer "In11.Cu")
		(net "M_L_CPU1_SA_DQS_DN<0>")
	)
	(segment
		(start 137.157968 -230.980234)
		(end 137.62482 -230.71455)
		(width 0.10668)
		(layer "F.Cu")
		(net "M_L_CPU1_SA_DQ<9>")
	)
	(segment
		(start 150.947374 -221.552262)
		(end 160.098994 -212.400642)
		(width 0.14478)
		(layer "In11.Cu")
		(net "M_L_CPU1_SA_DQ<9>")
	)
	(segment
		(start 139.31773 -231.036876)
		(end 139.326112 -231.041702)
		(width 0.0889)
		(layer "In11.Cu")
		(net "M_L_CPU1_SA_DQ<9>")
	)
	(segment
		(start 190.095124 -207.960468)
		(end 193.010536 -207.960468)
		(width 0.14478)
		(layer "In11.Cu")
		(net "M_L_CPU1_SA_DQ<9>")
	)
	(segment
		(start 160.098994 -211.373974)
		(end 162.662616 -208.810352)
		(width 0.14478)
		(layer "In11.Cu")
		(net "M_L_CPU1_SA_DQ<9>")
	)
	(segment
		(start 171.117514 -208.810352)
		(end 173.031658 -208.810352)
		(width 0.14478)
		(layer "In11.Cu")
		(net "M_L_CPU1_SA_DQ<9>")
	)
	(segment
		(start 138.743436 -231.041702)
		(end 138.751818 -231.036876)
		(width 0.0889)
		(layer "In11.Cu")
		(net "M_L_CPU1_SA_DQ<9>")
	)
	(segment
		(start 175.08347 -207.960468)
		(end 177.114708 -207.960468)
		(width 0.14478)
		(layer "In11.Cu")
		(net "M_L_CPU1_SA_DQ<9>")
	)
	(segment
		(start 173.031658 -208.810352)
		(end 175.08347 -207.960468)
		(width 0.14478)
		(layer "In11.Cu")
		(net "M_L_CPU1_SA_DQ<9>")
	)
	(segment
		(start 145.96491 -228.343206)
		(end 146.41703 -227.891086)
		(width 0.0889)
		(layer "In11.Cu")
		(net "M_L_CPU1_SA_DQ<9>")
	)
	(segment
		(start 193.86042 -208.810352)
		(end 195.49618 -208.810352)
		(width 0.14478)
		(layer "In11.Cu")
		(net "M_L_CPU1_SA_DQ<9>")
	)
	(segment
		(start 197.548246 -207.960468)
		(end 204.110844 -207.960468)
		(width 0.14478)
		(layer "In11.Cu")
		(net "M_L_CPU1_SA_DQ<9>")
	)
	(segment
		(start 140.257784 -231.036876)
		(end 140.266166 -231.041702)
		(width 0.0889)
		(layer "In11.Cu")
		(net "M_L_CPU1_SA_DQ<9>")
	)
	(segment
		(start 182.402988 -207.960468)
		(end 184.648856 -207.960468)
		(width 0.14478)
		(layer "In11.Cu")
		(net "M_L_CPU1_SA_DQ<9>")
	)
	(segment
		(start 147.545298 -227.000054)
		(end 150.947374 -223.597978)
		(width 0.14478)
		(layer "In11.Cu")
		(net "M_L_CPU1_SA_DQ<9>")
	)
	(segment
		(start 177.114708 -207.960468)
		(end 179.16652 -208.810352)
		(width 0.14478)
		(layer "In11.Cu")
		(net "M_L_CPU1_SA_DQ<9>")
	)
	(segment
		(start 137.62482 -230.71455)
		(end 137.778744 -230.97998)
		(width 0.0889)
		(layer "In11.Cu")
		(net "M_L_CPU1_SA_DQ<9>")
	)
	(segment
		(start 184.648856 -207.960468)
		(end 186.700922 -208.810352)
		(width 0.14478)
		(layer "In11.Cu")
		(net "M_L_CPU1_SA_DQ<9>")
	)
	(segment
		(start 146.41703 -227.891086)
		(end 146.654266 -227.891086)
		(width 0.0889)
		(layer "In11.Cu")
		(net "M_L_CPU1_SA_DQ<9>")
	)
	(segment
		(start 179.16652 -208.810352)
		(end 180.351176 -208.810352)
		(width 0.14478)
		(layer "In11.Cu")
		(net "M_L_CPU1_SA_DQ<9>")
	)
	(segment
		(start 146.654266 -227.891086)
		(end 147.545298 -227.000054)
		(width 0.0889)
		(layer "In11.Cu")
		(net "M_L_CPU1_SA_DQ<9>")
	)
	(segment
		(start 143.451834 -231.036876)
		(end 143.462248 -231.03078)
		(width 0.0889)
		(layer "In11.Cu")
		(net "M_L_CPU1_SA_DQ<9>")
	)
	(segment
		(start 188.043312 -208.810352)
		(end 190.095124 -207.960468)
		(width 0.14478)
		(layer "In11.Cu")
		(net "M_L_CPU1_SA_DQ<9>")
	)
	(segment
		(start 162.662616 -208.810352)
		(end 165.91661 -208.810352)
		(width 0.14478)
		(layer "In11.Cu")
		(net "M_L_CPU1_SA_DQ<9>")
	)
	(segment
		(start 142.503398 -231.041702)
		(end 142.51178 -231.036876)
		(width 0.0889)
		(layer "In11.Cu")
		(net "M_L_CPU1_SA_DQ<9>")
	)
	(segment
		(start 180.351176 -208.810352)
		(end 182.402988 -207.960468)
		(width 0.14478)
		(layer "In11.Cu")
		(net "M_L_CPU1_SA_DQ<9>")
	)
	(segment
		(start 195.49618 -208.810352)
		(end 197.548246 -207.960468)
		(width 0.14478)
		(layer "In11.Cu")
		(net "M_L_CPU1_SA_DQ<9>")
	)
	(segment
		(start 193.010536 -207.960468)
		(end 193.86042 -208.810352)
		(width 0.14478)
		(layer "In11.Cu")
		(net "M_L_CPU1_SA_DQ<9>")
	)
	(segment
		(start 160.098994 -212.400642)
		(end 160.098994 -211.373974)
		(width 0.14478)
		(layer "In11.Cu")
		(net "M_L_CPU1_SA_DQ<9>")
	)
	(segment
		(start 166.766494 -207.960468)
		(end 170.26763 -207.960468)
		(width 0.14478)
		(layer "In11.Cu")
		(net "M_L_CPU1_SA_DQ<9>")
	)
	(segment
		(start 150.947374 -223.597978)
		(end 150.947374 -221.552262)
		(width 0.14478)
		(layer "In11.Cu")
		(net "M_L_CPU1_SA_DQ<9>")
	)
	(segment
		(start 143.73225 -230.960676)
		(end 144.34566 -230.960676)
		(width 0.0889)
		(layer "In11.Cu")
		(net "M_L_CPU1_SA_DQ<9>")
	)
	(segment
		(start 143.077692 -231.036876)
		(end 143.086074 -231.041702)
		(width 0.0889)
		(layer "In11.Cu")
		(net "M_L_CPU1_SA_DQ<9>")
	)
	(segment
		(start 145.96491 -229.341426)
		(end 145.96491 -228.343206)
		(width 0.0889)
		(layer "In11.Cu")
		(net "M_L_CPU1_SA_DQ<9>")
	)
	(segment
		(start 204.110844 -207.960468)
		(end 206.248 -208.38541)
		(width 0.14478)
		(layer "In11.Cu")
		(net "M_L_CPU1_SA_DQ<9>")
	)
	(segment
		(start 144.34566 -230.960676)
		(end 145.96491 -229.341426)
		(width 0.0889)
		(layer "In11.Cu")
		(net "M_L_CPU1_SA_DQ<9>")
	)
	(segment
		(start 165.91661 -208.810352)
		(end 166.766494 -207.960468)
		(width 0.14478)
		(layer "In11.Cu")
		(net "M_L_CPU1_SA_DQ<9>")
	)
	(segment
		(start 170.26763 -207.960468)
		(end 171.117514 -208.810352)
		(width 0.14478)
		(layer "In11.Cu")
		(net "M_L_CPU1_SA_DQ<9>")
	)
	(segment
		(start 137.778744 -230.97998)
		(end 137.874502 -231.00538)
		(width 0.0889)
		(layer "In11.Cu")
		(net "M_L_CPU1_SA_DQ<9>")
	)
	(segment
		(start 186.700922 -208.810352)
		(end 188.043312 -208.810352)
		(width 0.14478)
		(layer "In11.Cu")
		(net "M_L_CPU1_SA_DQ<9>")
	)
	(arc
		(start 138.751818 -231.036876)
		(mid 139.034774 -230.960699)
		(end 139.31773 -231.036876)
		(width 0.0889)
		(layer "In11.Cu")
		(net "M_L_CPU1_SA_DQ<9>")
	)
	(arc
		(start 140.266166 -231.041702)
		(mid 140.449674 -231.087227)
		(end 140.631926 -231.036876)
		(width 0.0889)
		(layer "In11.Cu")
		(net "M_L_CPU1_SA_DQ<9>")
	)
	(arc
		(start 139.691872 -231.036876)
		(mid 139.974828 -230.960699)
		(end 140.257784 -231.036876)
		(width 0.0889)
		(layer "In11.Cu")
		(net "M_L_CPU1_SA_DQ<9>")
	)
	(arc
		(start 143.086074 -231.041702)
		(mid 143.269582 -231.087227)
		(end 143.451834 -231.036876)
		(width 0.0889)
		(layer "In11.Cu")
		(net "M_L_CPU1_SA_DQ<9>")
	)
	(arc
		(start 142.51178 -231.036876)
		(mid 142.794736 -230.960699)
		(end 143.077692 -231.036876)
		(width 0.0889)
		(layer "In11.Cu")
		(net "M_L_CPU1_SA_DQ<9>")
	)
	(arc
		(start 143.462248 -231.03078)
		(mid 143.592842 -230.978749)
		(end 143.73225 -230.960676)
		(width 0.0889)
		(layer "In11.Cu")
		(net "M_L_CPU1_SA_DQ<9>")
	)
	(arc
		(start 138.377676 -231.036876)
		(mid 138.559927 -231.08726)
		(end 138.743436 -231.041702)
		(width 0.0889)
		(layer "In11.Cu")
		(net "M_L_CPU1_SA_DQ<9>")
	)
	(arc
		(start 139.326112 -231.041702)
		(mid 139.50962 -231.087227)
		(end 139.691872 -231.036876)
		(width 0.0889)
		(layer "In11.Cu")
		(net "M_L_CPU1_SA_DQ<9>")
	)
	(arc
		(start 137.874502 -231.00538)
		(mid 138.129824 -230.96168)
		(end 138.377676 -231.036876)
		(width 0.0889)
		(layer "In11.Cu")
		(net "M_L_CPU1_SA_DQ<9>")
	)
	(arc
		(start 141.197838 -231.036876)
		(mid 141.384782 -231.087165)
		(end 141.571726 -231.036876)
		(width 0.0889)
		(layer "In11.Cu")
		(net "M_L_CPU1_SA_DQ<9>")
	)
	(arc
		(start 142.137638 -231.036876)
		(mid 142.319889 -231.08726)
		(end 142.503398 -231.041702)
		(width 0.0889)
		(layer "In11.Cu")
		(net "M_L_CPU1_SA_DQ<9>")
	)
	(arc
		(start 140.631926 -231.036876)
		(mid 140.914882 -230.960699)
		(end 141.197838 -231.036876)
		(width 0.0889)
		(layer "In11.Cu")
		(net "M_L_CPU1_SA_DQ<9>")
	)
	(arc
		(start 141.571726 -231.036876)
		(mid 141.854682 -230.960699)
		(end 142.137638 -231.036876)
		(width 0.0889)
		(layer "In11.Cu")
		(net "M_L_CPU1_SA_DQ<9>")
	)
	(segment
		(start 138.567922 -230.170228)
		(end 139.034774 -229.90429)
		(width 0.10668)
		(layer "F.Cu")
		(net "M_L_CPU1_SA_DQ<8>")
	)
	(segment
		(start 185.250836 -206.260446)
		(end 186.10072 -207.11033)
		(width 0.14478)
		(layer "In11.Cu")
		(net "M_L_CPU1_SA_DQ<8>")
	)
	(segment
		(start 170.137836 -206.260446)
		(end 170.98772 -207.11033)
		(width 0.14478)
		(layer "In11.Cu")
		(net "M_L_CPU1_SA_DQ<8>")
	)
	(segment
		(start 145.51025 -229.239826)
		(end 145.51025 -228.206046)
		(width 0.0889)
		(layer "In11.Cu")
		(net "M_L_CPU1_SA_DQ<8>")
	)
	(segment
		(start 143.909796 -230.233728)
		(end 143.92148 -230.22687)
		(width 0.0889)
		(layer "In11.Cu")
		(net "M_L_CPU1_SA_DQ<8>")
	)
	(segment
		(start 173.59884 -207.11033)
		(end 174.448724 -206.260446)
		(width 0.14478)
		(layer "In11.Cu")
		(net "M_L_CPU1_SA_DQ<8>")
	)
	(segment
		(start 141.093444 -230.231696)
		(end 141.101826 -230.22687)
		(width 0.0889)
		(layer "In11.Cu")
		(net "M_L_CPU1_SA_DQ<8>")
	)
	(segment
		(start 146.41195 -226.268026)
		(end 146.990816 -226.268026)
		(width 0.0889)
		(layer "In11.Cu")
		(net "M_L_CPU1_SA_DQ<8>")
	)
	(segment
		(start 145.51025 -228.206046)
		(end 146.03857 -227.677726)
		(width 0.0889)
		(layer "In11.Cu")
		(net "M_L_CPU1_SA_DQ<8>")
	)
	(segment
		(start 146.03857 -227.677726)
		(end 146.03857 -226.641406)
		(width 0.0889)
		(layer "In11.Cu")
		(net "M_L_CPU1_SA_DQ<8>")
	)
	(segment
		(start 155.684474 -214.502238)
		(end 163.076382 -207.11033)
		(width 0.14478)
		(layer "In11.Cu")
		(net "M_L_CPU1_SA_DQ<8>")
	)
	(segment
		(start 146.990816 -226.268026)
		(end 147.794472 -225.46437)
		(width 0.0889)
		(layer "In11.Cu")
		(net "M_L_CPU1_SA_DQ<8>")
	)
	(segment
		(start 150.009606 -223.249236)
		(end 150.009606 -221.203774)
		(width 0.14478)
		(layer "In11.Cu")
		(net "M_L_CPU1_SA_DQ<8>")
	)
	(segment
		(start 180.997352 -207.11033)
		(end 181.847236 -206.260446)
		(width 0.14478)
		(layer "In11.Cu")
		(net "M_L_CPU1_SA_DQ<8>")
	)
	(segment
		(start 197.598792 -206.260446)
		(end 204.111606 -206.260446)
		(width 0.14478)
		(layer "In11.Cu")
		(net "M_L_CPU1_SA_DQ<8>")
	)
	(segment
		(start 145.15846 -229.591616)
		(end 145.51025 -229.239826)
		(width 0.0889)
		(layer "In11.Cu")
		(net "M_L_CPU1_SA_DQ<8>")
	)
	(segment
		(start 195.54698 -207.11033)
		(end 197.598792 -206.260446)
		(width 0.14478)
		(layer "In11.Cu")
		(net "M_L_CPU1_SA_DQ<8>")
	)
	(segment
		(start 165.820598 -207.11033)
		(end 166.670482 -206.260446)
		(width 0.14478)
		(layer "In11.Cu")
		(net "M_L_CPU1_SA_DQ<8>")
	)
	(segment
		(start 144.067022 -230.167942)
		(end 145.15846 -229.591616)
		(width 0.0889)
		(layer "In11.Cu")
		(net "M_L_CPU1_SA_DQ<8>")
	)
	(segment
		(start 166.670482 -206.260446)
		(end 170.137836 -206.260446)
		(width 0.14478)
		(layer "In11.Cu")
		(net "M_L_CPU1_SA_DQ<8>")
	)
	(segment
		(start 139.034774 -229.90429)
		(end 139.188698 -230.16972)
		(width 0.0889)
		(layer "In11.Cu")
		(net "M_L_CPU1_SA_DQ<8>")
	)
	(segment
		(start 139.188698 -230.16972)
		(end 139.28471 -230.19512)
		(width 0.0889)
		(layer "In11.Cu")
		(net "M_L_CPU1_SA_DQ<8>")
	)
	(segment
		(start 177.972466 -206.260446)
		(end 178.82235 -207.11033)
		(width 0.14478)
		(layer "In11.Cu")
		(net "M_L_CPU1_SA_DQ<8>")
	)
	(segment
		(start 140.15339 -230.231696)
		(end 140.161772 -230.22687)
		(width 0.0889)
		(layer "In11.Cu")
		(net "M_L_CPU1_SA_DQ<8>")
	)
	(segment
		(start 204.111606 -206.260446)
		(end 206.248 -206.685388)
		(width 0.14478)
		(layer "In11.Cu")
		(net "M_L_CPU1_SA_DQ<8>")
	)
	(segment
		(start 189.523116 -206.260446)
		(end 192.736216 -206.260446)
		(width 0.14478)
		(layer "In11.Cu")
		(net "M_L_CPU1_SA_DQ<8>")
	)
	(segment
		(start 181.847236 -206.260446)
		(end 185.250836 -206.260446)
		(width 0.14478)
		(layer "In11.Cu")
		(net "M_L_CPU1_SA_DQ<8>")
	)
	(segment
		(start 163.076382 -207.11033)
		(end 165.820598 -207.11033)
		(width 0.14478)
		(layer "In11.Cu")
		(net "M_L_CPU1_SA_DQ<8>")
	)
	(segment
		(start 146.03857 -226.641406)
		(end 146.41195 -226.268026)
		(width 0.0889)
		(layer "In11.Cu")
		(net "M_L_CPU1_SA_DQ<8>")
	)
	(segment
		(start 178.82235 -207.11033)
		(end 180.997352 -207.11033)
		(width 0.14478)
		(layer "In11.Cu")
		(net "M_L_CPU1_SA_DQ<8>")
	)
	(segment
		(start 193.5861 -207.11033)
		(end 195.54698 -207.11033)
		(width 0.14478)
		(layer "In11.Cu")
		(net "M_L_CPU1_SA_DQ<8>")
	)
	(segment
		(start 170.98772 -207.11033)
		(end 173.59884 -207.11033)
		(width 0.14478)
		(layer "In11.Cu")
		(net "M_L_CPU1_SA_DQ<8>")
	)
	(segment
		(start 150.009606 -221.203774)
		(end 155.684474 -215.528906)
		(width 0.14478)
		(layer "In11.Cu")
		(net "M_L_CPU1_SA_DQ<8>")
	)
	(segment
		(start 155.684474 -215.528906)
		(end 155.684474 -214.502238)
		(width 0.14478)
		(layer "In11.Cu")
		(net "M_L_CPU1_SA_DQ<8>")
	)
	(segment
		(start 192.736216 -206.260446)
		(end 193.5861 -207.11033)
		(width 0.14478)
		(layer "In11.Cu")
		(net "M_L_CPU1_SA_DQ<8>")
	)
	(segment
		(start 188.673232 -207.11033)
		(end 189.523116 -206.260446)
		(width 0.14478)
		(layer "In11.Cu")
		(net "M_L_CPU1_SA_DQ<8>")
	)
	(segment
		(start 147.794472 -225.46437)
		(end 150.009606 -223.249236)
		(width 0.14478)
		(layer "In11.Cu")
		(net "M_L_CPU1_SA_DQ<8>")
	)
	(segment
		(start 174.448724 -206.260446)
		(end 177.972466 -206.260446)
		(width 0.14478)
		(layer "In11.Cu")
		(net "M_L_CPU1_SA_DQ<8>")
	)
	(segment
		(start 141.667738 -230.22687)
		(end 141.67612 -230.231696)
		(width 0.0889)
		(layer "In11.Cu")
		(net "M_L_CPU1_SA_DQ<8>")
	)
	(segment
		(start 186.10072 -207.11033)
		(end 188.673232 -207.11033)
		(width 0.14478)
		(layer "In11.Cu")
		(net "M_L_CPU1_SA_DQ<8>")
	)
	(arc
		(start 141.101826 -230.22687)
		(mid 141.384782 -230.150727)
		(end 141.667738 -230.22687)
		(width 0.0889)
		(layer "In11.Cu")
		(net "M_L_CPU1_SA_DQ<8>")
	)
	(arc
		(start 142.98168 -230.22687)
		(mid 143.264636 -230.150727)
		(end 143.547592 -230.22687)
		(width 0.0889)
		(layer "In11.Cu")
		(net "M_L_CPU1_SA_DQ<8>")
	)
	(arc
		(start 140.727684 -230.22687)
		(mid 140.909935 -230.27722)
		(end 141.093444 -230.231696)
		(width 0.0889)
		(layer "In11.Cu")
		(net "M_L_CPU1_SA_DQ<8>")
	)
	(arc
		(start 142.607792 -230.22687)
		(mid 142.794736 -230.277125)
		(end 142.98168 -230.22687)
		(width 0.0889)
		(layer "In11.Cu")
		(net "M_L_CPU1_SA_DQ<8>")
	)
	(arc
		(start 139.28471 -230.19512)
		(mid 139.539918 -230.151663)
		(end 139.78763 -230.22687)
		(width 0.0889)
		(layer "In11.Cu")
		(net "M_L_CPU1_SA_DQ<8>")
	)
	(arc
		(start 143.92148 -230.22687)
		(mid 143.992192 -230.192321)
		(end 144.067022 -230.167942)
		(width 0.0889)
		(layer "In11.Cu")
		(net "M_L_CPU1_SA_DQ<8>")
	)
	(arc
		(start 139.78763 -230.22687)
		(mid 139.969881 -230.27722)
		(end 140.15339 -230.231696)
		(width 0.0889)
		(layer "In11.Cu")
		(net "M_L_CPU1_SA_DQ<8>")
	)
	(arc
		(start 143.547592 -230.22687)
		(mid 143.727797 -230.277187)
		(end 143.909796 -230.233728)
		(width 0.0889)
		(layer "In11.Cu")
		(net "M_L_CPU1_SA_DQ<8>")
	)
	(arc
		(start 140.161772 -230.22687)
		(mid 140.444728 -230.150727)
		(end 140.727684 -230.22687)
		(width 0.0889)
		(layer "In11.Cu")
		(net "M_L_CPU1_SA_DQ<8>")
	)
	(arc
		(start 142.04188 -230.22687)
		(mid 142.324836 -230.150727)
		(end 142.607792 -230.22687)
		(width 0.0889)
		(layer "In11.Cu")
		(net "M_L_CPU1_SA_DQ<8>")
	)
	(arc
		(start 141.67612 -230.231696)
		(mid 141.859628 -230.27719)
		(end 142.04188 -230.22687)
		(width 0.0889)
		(layer "In11.Cu")
		(net "M_L_CPU1_SA_DQ<8>")
	)
	(segment
		(start 137.627868 -230.170228)
		(end 138.09472 -229.90429)
		(width 0.10668)
		(layer "F.Cu")
		(net "M_L_CPU1_SA_DQ<7>")
	)
	(segment
		(start 152.341072 -217.23731)
		(end 152.649682 -217.54592)
		(width 0.14478)
		(layer "In11.Cu")
		(net "M_L_CPU1_SA_DQ<7>")
	)
	(segment
		(start 146.36115 -226.003866)
		(end 146.73961 -226.003866)
		(width 0.0889)
		(layer "In11.Cu")
		(net "M_L_CPU1_SA_DQ<7>")
	)
	(segment
		(start 145.83283 -226.532186)
		(end 146.36115 -226.003866)
		(width 0.0889)
		(layer "In11.Cu")
		(net "M_L_CPU1_SA_DQ<7>")
	)
	(segment
		(start 151.468582 -218.957652)
		(end 151.468582 -218.72702)
		(width 0.14478)
		(layer "In11.Cu")
		(net "M_L_CPU1_SA_DQ<7>")
	)
	(segment
		(start 170.464734 -205.410308)
		(end 171.314872 -206.260446)
		(width 0.14478)
		(layer "In11.Cu")
		(net "M_L_CPU1_SA_DQ<7>")
	)
	(segment
		(start 147.25523 -225.488246)
		(end 147.25523 -225.21672)
		(width 0.0889)
		(layer "In11.Cu")
		(net "M_L_CPU1_SA_DQ<7>")
	)
	(segment
		(start 147.84197 -224.62998)
		(end 149.443186 -223.028764)
		(width 0.14478)
		(layer "In11.Cu")
		(net "M_L_CPU1_SA_DQ<7>")
	)
	(segment
		(start 151.159972 -218.187778)
		(end 151.32304 -218.02471)
		(width 0.14478)
		(layer "In11.Cu")
		(net "M_L_CPU1_SA_DQ<7>")
	)
	(segment
		(start 163.13912 -206.260446)
		(end 165.591236 -206.260446)
		(width 0.14478)
		(layer "In11.Cu")
		(net "M_L_CPU1_SA_DQ<7>")
	)
	(segment
		(start 151.159972 -218.41841)
		(end 151.159972 -218.187778)
		(width 0.14478)
		(layer "In11.Cu")
		(net "M_L_CPU1_SA_DQ<7>")
	)
	(segment
		(start 178.82235 -206.260446)
		(end 180.906928 -206.260446)
		(width 0.14478)
		(layer "In11.Cu")
		(net "M_L_CPU1_SA_DQ<7>")
	)
	(segment
		(start 152.255982 -217.93962)
		(end 151.947372 -217.63101)
		(width 0.14478)
		(layer "In11.Cu")
		(net "M_L_CPU1_SA_DQ<7>")
	)
	(segment
		(start 137.940796 -229.63886)
		(end 137.963148 -229.555802)
		(width 0.0889)
		(layer "In11.Cu")
		(net "M_L_CPU1_SA_DQ<7>")
	)
	(segment
		(start 153.128472 -216.44991)
		(end 153.437082 -216.75852)
		(width 0.14478)
		(layer "In11.Cu")
		(net "M_L_CPU1_SA_DQ<7>")
	)
	(segment
		(start 171.314872 -206.260446)
		(end 173.494192 -206.260446)
		(width 0.14478)
		(layer "In11.Cu")
		(net "M_L_CPU1_SA_DQ<7>")
	)
	(segment
		(start 149.893782 -220.30182)
		(end 149.585172 -219.99321)
		(width 0.14478)
		(layer "In11.Cu")
		(net "M_L_CPU1_SA_DQ<7>")
	)
	(segment
		(start 149.978872 -219.59951)
		(end 150.287482 -219.90812)
		(width 0.14478)
		(layer "In11.Cu")
		(net "M_L_CPU1_SA_DQ<7>")
	)
	(segment
		(start 150.287482 -219.90812)
		(end 150.518114 -219.90812)
		(width 0.14478)
		(layer "In11.Cu")
		(net "M_L_CPU1_SA_DQ<7>")
	)
	(segment
		(start 147.25523 -225.21672)
		(end 147.84197 -224.62998)
		(width 0.0889)
		(layer "In11.Cu")
		(net "M_L_CPU1_SA_DQ<7>")
	)
	(segment
		(start 153.043382 -217.382852)
		(end 153.043382 -217.15222)
		(width 0.14478)
		(layer "In11.Cu")
		(net "M_L_CPU1_SA_DQ<7>")
	)
	(segment
		(start 152.734772 -216.612978)
		(end 152.89784 -216.44991)
		(width 0.14478)
		(layer "In11.Cu")
		(net "M_L_CPU1_SA_DQ<7>")
	)
	(segment
		(start 149.443186 -220.983048)
		(end 149.893782 -220.532452)
		(width 0.14478)
		(layer "In11.Cu")
		(net "M_L_CPU1_SA_DQ<7>")
	)
	(segment
		(start 143.73479 -229.531164)
		(end 144.101312 -229.531164)
		(width 0.0889)
		(layer "In11.Cu")
		(net "M_L_CPU1_SA_DQ<7>")
	)
	(segment
		(start 151.074882 -219.12072)
		(end 151.305514 -219.12072)
		(width 0.14478)
		(layer "In11.Cu")
		(net "M_L_CPU1_SA_DQ<7>")
	)
	(segment
		(start 153.043382 -217.15222)
		(end 152.734772 -216.84361)
		(width 0.14478)
		(layer "In11.Cu")
		(net "M_L_CPU1_SA_DQ<7>")
	)
	(segment
		(start 146.73961 -226.003866)
		(end 147.25523 -225.488246)
		(width 0.0889)
		(layer "In11.Cu")
		(net "M_L_CPU1_SA_DQ<7>")
	)
	(segment
		(start 150.53564 -218.81211)
		(end 150.766272 -218.81211)
		(width 0.14478)
		(layer "In11.Cu")
		(net "M_L_CPU1_SA_DQ<7>")
	)
	(segment
		(start 150.681182 -219.51442)
		(end 150.372572 -219.20581)
		(width 0.14478)
		(layer "In11.Cu")
		(net "M_L_CPU1_SA_DQ<7>")
	)
	(segment
		(start 189.523116 -205.410562)
		(end 192.695576 -205.410562)
		(width 0.14478)
		(layer "In11.Cu")
		(net "M_L_CPU1_SA_DQ<7>")
	)
	(segment
		(start 196.042788 -206.260446)
		(end 196.892672 -205.410562)
		(width 0.14478)
		(layer "In11.Cu")
		(net "M_L_CPU1_SA_DQ<7>")
	)
	(segment
		(start 153.667714 -216.75852)
		(end 155.128214 -215.29802)
		(width 0.14478)
		(layer "In11.Cu")
		(net "M_L_CPU1_SA_DQ<7>")
	)
	(segment
		(start 141.093444 -229.577138)
		(end 141.101826 -229.581964)
		(width 0.0889)
		(layer "In11.Cu")
		(net "M_L_CPU1_SA_DQ<7>")
	)
	(segment
		(start 151.468582 -218.72702)
		(end 151.159972 -218.41841)
		(width 0.14478)
		(layer "In11.Cu")
		(net "M_L_CPU1_SA_DQ<7>")
	)
	(segment
		(start 180.906928 -206.260446)
		(end 181.756812 -205.410562)
		(width 0.14478)
		(layer "In11.Cu")
		(net "M_L_CPU1_SA_DQ<7>")
	)
	(segment
		(start 149.443186 -223.028764)
		(end 149.443186 -220.983048)
		(width 0.14478)
		(layer "In11.Cu")
		(net "M_L_CPU1_SA_DQ<7>")
	)
	(segment
		(start 201.723244 -205.410562)
		(end 202.147932 -205.83525)
		(width 0.14478)
		(layer "In11.Cu")
		(net "M_L_CPU1_SA_DQ<7>")
	)
	(segment
		(start 165.591236 -206.260446)
		(end 166.441374 -205.410308)
		(width 0.14478)
		(layer "In11.Cu")
		(net "M_L_CPU1_SA_DQ<7>")
	)
	(segment
		(start 150.681182 -219.745052)
		(end 150.681182 -219.51442)
		(width 0.14478)
		(layer "In11.Cu")
		(net "M_L_CPU1_SA_DQ<7>")
	)
	(segment
		(start 150.766272 -218.81211)
		(end 151.074882 -219.12072)
		(width 0.14478)
		(layer "In11.Cu")
		(net "M_L_CPU1_SA_DQ<7>")
	)
	(segment
		(start 152.89784 -216.44991)
		(end 153.128472 -216.44991)
		(width 0.14478)
		(layer "In11.Cu")
		(net "M_L_CPU1_SA_DQ<7>")
	)
	(segment
		(start 153.437082 -216.75852)
		(end 153.667714 -216.75852)
		(width 0.14478)
		(layer "In11.Cu")
		(net "M_L_CPU1_SA_DQ<7>")
	)
	(segment
		(start 149.74824 -219.59951)
		(end 149.978872 -219.59951)
		(width 0.14478)
		(layer "In11.Cu")
		(net "M_L_CPU1_SA_DQ<7>")
	)
	(segment
		(start 155.128214 -214.271352)
		(end 163.13912 -206.260446)
		(width 0.14478)
		(layer "In11.Cu")
		(net "M_L_CPU1_SA_DQ<7>")
	)
	(segment
		(start 144.101312 -229.531164)
		(end 145.29435 -228.338126)
		(width 0.0889)
		(layer "In11.Cu")
		(net "M_L_CPU1_SA_DQ<7>")
	)
	(segment
		(start 193.54546 -206.260446)
		(end 196.042788 -206.260446)
		(width 0.14478)
		(layer "In11.Cu")
		(net "M_L_CPU1_SA_DQ<7>")
	)
	(segment
		(start 149.893782 -220.532452)
		(end 149.893782 -220.30182)
		(width 0.14478)
		(layer "In11.Cu")
		(net "M_L_CPU1_SA_DQ<7>")
	)
	(segment
		(start 152.092914 -218.33332)
		(end 152.255982 -218.170252)
		(width 0.14478)
		(layer "In11.Cu")
		(net "M_L_CPU1_SA_DQ<7>")
	)
	(segment
		(start 188.673232 -206.260446)
		(end 189.523116 -205.410562)
		(width 0.14478)
		(layer "In11.Cu")
		(net "M_L_CPU1_SA_DQ<7>")
	)
	(segment
		(start 166.441374 -205.410308)
		(end 170.464734 -205.410308)
		(width 0.14478)
		(layer "In11.Cu")
		(net "M_L_CPU1_SA_DQ<7>")
	)
	(segment
		(start 149.585172 -219.99321)
		(end 149.585172 -219.762578)
		(width 0.14478)
		(layer "In11.Cu")
		(net "M_L_CPU1_SA_DQ<7>")
	)
	(segment
		(start 177.972466 -205.410562)
		(end 178.82235 -206.260446)
		(width 0.14478)
		(layer "In11.Cu")
		(net "M_L_CPU1_SA_DQ<7>")
	)
	(segment
		(start 196.892672 -205.410562)
		(end 201.723244 -205.410562)
		(width 0.14478)
		(layer "In11.Cu")
		(net "M_L_CPU1_SA_DQ<7>")
	)
	(segment
		(start 141.667738 -229.581964)
		(end 141.67612 -229.577138)
		(width 0.0889)
		(layer "In11.Cu")
		(net "M_L_CPU1_SA_DQ<7>")
	)
	(segment
		(start 181.756812 -205.410562)
		(end 185.250836 -205.410562)
		(width 0.14478)
		(layer "In11.Cu")
		(net "M_L_CPU1_SA_DQ<7>")
	)
	(segment
		(start 140.15339 -229.577138)
		(end 140.161772 -229.581964)
		(width 0.0889)
		(layer "In11.Cu")
		(net "M_L_CPU1_SA_DQ<7>")
	)
	(segment
		(start 152.649682 -217.54592)
		(end 152.880314 -217.54592)
		(width 0.14478)
		(layer "In11.Cu")
		(net "M_L_CPU1_SA_DQ<7>")
	)
	(segment
		(start 152.255982 -218.170252)
		(end 152.255982 -217.93962)
		(width 0.14478)
		(layer "In11.Cu")
		(net "M_L_CPU1_SA_DQ<7>")
	)
	(segment
		(start 151.553672 -218.02471)
		(end 151.862282 -218.33332)
		(width 0.14478)
		(layer "In11.Cu")
		(net "M_L_CPU1_SA_DQ<7>")
	)
	(segment
		(start 173.494192 -206.260446)
		(end 174.344076 -205.410562)
		(width 0.14478)
		(layer "In11.Cu")
		(net "M_L_CPU1_SA_DQ<7>")
	)
	(segment
		(start 150.372572 -219.20581)
		(end 150.372572 -218.975178)
		(width 0.14478)
		(layer "In11.Cu")
		(net "M_L_CPU1_SA_DQ<7>")
	)
	(segment
		(start 150.518114 -219.90812)
		(end 150.681182 -219.745052)
		(width 0.14478)
		(layer "In11.Cu")
		(net "M_L_CPU1_SA_DQ<7>")
	)
	(segment
		(start 152.734772 -216.84361)
		(end 152.734772 -216.612978)
		(width 0.14478)
		(layer "In11.Cu")
		(net "M_L_CPU1_SA_DQ<7>")
	)
	(segment
		(start 152.880314 -217.54592)
		(end 153.043382 -217.382852)
		(width 0.14478)
		(layer "In11.Cu")
		(net "M_L_CPU1_SA_DQ<7>")
	)
	(segment
		(start 151.947372 -217.63101)
		(end 151.947372 -217.400378)
		(width 0.14478)
		(layer "In11.Cu")
		(net "M_L_CPU1_SA_DQ<7>")
	)
	(segment
		(start 145.83283 -227.609146)
		(end 145.83283 -226.532186)
		(width 0.0889)
		(layer "In11.Cu")
		(net "M_L_CPU1_SA_DQ<7>")
	)
	(segment
		(start 145.29435 -228.147626)
		(end 145.83283 -227.609146)
		(width 0.0889)
		(layer "In11.Cu")
		(net "M_L_CPU1_SA_DQ<7>")
	)
	(segment
		(start 151.947372 -217.400378)
		(end 152.11044 -217.23731)
		(width 0.14478)
		(layer "In11.Cu")
		(net "M_L_CPU1_SA_DQ<7>")
	)
	(segment
		(start 145.29435 -228.338126)
		(end 145.29435 -228.147626)
		(width 0.0889)
		(layer "In11.Cu")
		(net "M_L_CPU1_SA_DQ<7>")
	)
	(segment
		(start 155.128214 -215.29802)
		(end 155.128214 -214.271352)
		(width 0.14478)
		(layer "In11.Cu")
		(net "M_L_CPU1_SA_DQ<7>")
	)
	(segment
		(start 138.09472 -229.90429)
		(end 137.940796 -229.63886)
		(width 0.0889)
		(layer "In11.Cu")
		(net "M_L_CPU1_SA_DQ<7>")
	)
	(segment
		(start 151.32304 -218.02471)
		(end 151.553672 -218.02471)
		(width 0.14478)
		(layer "In11.Cu")
		(net "M_L_CPU1_SA_DQ<7>")
	)
	(segment
		(start 150.372572 -218.975178)
		(end 150.53564 -218.81211)
		(width 0.14478)
		(layer "In11.Cu")
		(net "M_L_CPU1_SA_DQ<7>")
	)
	(segment
		(start 186.10072 -206.260446)
		(end 188.673232 -206.260446)
		(width 0.14478)
		(layer "In11.Cu")
		(net "M_L_CPU1_SA_DQ<7>")
	)
	(segment
		(start 185.250836 -205.410562)
		(end 186.10072 -206.260446)
		(width 0.14478)
		(layer "In11.Cu")
		(net "M_L_CPU1_SA_DQ<7>")
	)
	(segment
		(start 151.862282 -218.33332)
		(end 152.092914 -218.33332)
		(width 0.14478)
		(layer "In11.Cu")
		(net "M_L_CPU1_SA_DQ<7>")
	)
	(segment
		(start 149.585172 -219.762578)
		(end 149.74824 -219.59951)
		(width 0.14478)
		(layer "In11.Cu")
		(net "M_L_CPU1_SA_DQ<7>")
	)
	(segment
		(start 174.344076 -205.410562)
		(end 177.972466 -205.410562)
		(width 0.14478)
		(layer "In11.Cu")
		(net "M_L_CPU1_SA_DQ<7>")
	)
	(segment
		(start 151.305514 -219.12072)
		(end 151.468582 -218.957652)
		(width 0.14478)
		(layer "In11.Cu")
		(net "M_L_CPU1_SA_DQ<7>")
	)
	(segment
		(start 152.11044 -217.23731)
		(end 152.341072 -217.23731)
		(width 0.14478)
		(layer "In11.Cu")
		(net "M_L_CPU1_SA_DQ<7>")
	)
	(segment
		(start 192.695576 -205.410562)
		(end 193.54546 -206.260446)
		(width 0.14478)
		(layer "In11.Cu")
		(net "M_L_CPU1_SA_DQ<7>")
	)
	(arc
		(start 137.963148 -229.555802)
		(mid 138.12548 -229.532968)
		(end 138.281918 -229.581964)
		(width 0.0889)
		(layer "In11.Cu")
		(net "M_L_CPU1_SA_DQ<7>")
	)
	(arc
		(start 140.727684 -229.581964)
		(mid 140.909935 -229.53158)
		(end 141.093444 -229.577138)
		(width 0.0889)
		(layer "In11.Cu")
		(net "M_L_CPU1_SA_DQ<7>")
	)
	(arc
		(start 142.607792 -229.581964)
		(mid 142.794736 -229.531675)
		(end 142.98168 -229.581964)
		(width 0.0889)
		(layer "In11.Cu")
		(net "M_L_CPU1_SA_DQ<7>")
	)
	(arc
		(start 139.78763 -229.581964)
		(mid 139.969881 -229.53158)
		(end 140.15339 -229.577138)
		(width 0.0889)
		(layer "In11.Cu")
		(net "M_L_CPU1_SA_DQ<7>")
	)
	(arc
		(start 138.281918 -229.581964)
		(mid 138.564874 -229.658141)
		(end 138.84783 -229.581964)
		(width 0.0889)
		(layer "In11.Cu")
		(net "M_L_CPU1_SA_DQ<7>")
	)
	(arc
		(start 138.84783 -229.581964)
		(mid 139.034774 -229.531675)
		(end 139.221718 -229.581964)
		(width 0.0889)
		(layer "In11.Cu")
		(net "M_L_CPU1_SA_DQ<7>")
	)
	(arc
		(start 142.04188 -229.581964)
		(mid 142.324836 -229.658141)
		(end 142.607792 -229.581964)
		(width 0.0889)
		(layer "In11.Cu")
		(net "M_L_CPU1_SA_DQ<7>")
	)
	(arc
		(start 140.161772 -229.581964)
		(mid 140.444728 -229.658141)
		(end 140.727684 -229.581964)
		(width 0.0889)
		(layer "In11.Cu")
		(net "M_L_CPU1_SA_DQ<7>")
	)
	(arc
		(start 143.547592 -229.581964)
		(mid 143.637828 -229.544162)
		(end 143.73479 -229.531164)
		(width 0.0889)
		(layer "In11.Cu")
		(net "M_L_CPU1_SA_DQ<7>")
	)
	(arc
		(start 139.221718 -229.581964)
		(mid 139.504674 -229.658141)
		(end 139.78763 -229.581964)
		(width 0.0889)
		(layer "In11.Cu")
		(net "M_L_CPU1_SA_DQ<7>")
	)
	(arc
		(start 141.67612 -229.577138)
		(mid 141.859628 -229.531613)
		(end 142.04188 -229.581964)
		(width 0.0889)
		(layer "In11.Cu")
		(net "M_L_CPU1_SA_DQ<7>")
	)
	(arc
		(start 141.101826 -229.581964)
		(mid 141.384782 -229.658141)
		(end 141.667738 -229.581964)
		(width 0.0889)
		(layer "In11.Cu")
		(net "M_L_CPU1_SA_DQ<7>")
	)
	(arc
		(start 142.98168 -229.581964)
		(mid 143.264636 -229.658141)
		(end 143.547592 -229.581964)
		(width 0.0889)
		(layer "In11.Cu")
		(net "M_L_CPU1_SA_DQ<7>")
	)
	(segment
		(start 139.037822 -229.360476)
		(end 139.504674 -229.094538)
		(width 0.10668)
		(layer "F.Cu")
		(net "M_L_CPU1_SA_DQ<6>")
	)
	(segment
		(start 189.523116 -203.71054)
		(end 192.59804 -203.71054)
		(width 0.14478)
		(layer "In11.Cu")
		(net "M_L_CPU1_SA_DQ<6>")
	)
	(segment
		(start 149.935184 -218.126056)
		(end 149.935438 -217.895424)
		(width 0.14478)
		(layer "In11.Cu")
		(net "M_L_CPU1_SA_DQ<6>")
	)
	(segment
		(start 152.297384 -215.763856)
		(end 152.297638 -215.533224)
		(width 0.14478)
		(layer "In11.Cu")
		(net "M_L_CPU1_SA_DQ<6>")
	)
	(segment
		(start 147.761706 -223.423988)
		(end 148.42363 -222.762064)
		(width 0.14478)
		(layer "In11.Cu")
		(net "M_L_CPU1_SA_DQ<6>")
	)
	(segment
		(start 151.302974 -215.556084)
		(end 151.533098 -215.556338)
		(width 0.14478)
		(layer "In11.Cu")
		(net "M_L_CPU1_SA_DQ<6>")
	)
	(segment
		(start 144.050512 -228.847904)
		(end 144.79397 -228.104446)
		(width 0.0889)
		(layer "In11.Cu")
		(net "M_L_CPU1_SA_DQ<6>")
	)
	(segment
		(start 149.541484 -218.289124)
		(end 149.772116 -218.289124)
		(width 0.14478)
		(layer "In11.Cu")
		(net "M_L_CPU1_SA_DQ<6>")
	)
	(segment
		(start 174.356268 -203.71054)
		(end 177.972466 -203.71054)
		(width 0.14478)
		(layer "In11.Cu")
		(net "M_L_CPU1_SA_DQ<6>")
	)
	(segment
		(start 150.515574 -216.343484)
		(end 150.745698 -216.343738)
		(width 0.14478)
		(layer "In11.Cu")
		(net "M_L_CPU1_SA_DQ<6>")
	)
	(segment
		(start 149.772116 -218.289124)
		(end 149.935184 -218.126056)
		(width 0.14478)
		(layer "In11.Cu")
		(net "M_L_CPU1_SA_DQ<6>")
	)
	(segment
		(start 149.147784 -218.913456)
		(end 149.148038 -218.682824)
		(width 0.14478)
		(layer "In11.Cu")
		(net "M_L_CPU1_SA_DQ<6>")
	)
	(segment
		(start 152.297638 -215.533224)
		(end 151.927052 -215.162638)
		(width 0.14478)
		(layer "In11.Cu")
		(net "M_L_CPU1_SA_DQ<6>")
	)
	(segment
		(start 181.915308 -203.71054)
		(end 185.250836 -203.71054)
		(width 0.14478)
		(layer "In11.Cu")
		(net "M_L_CPU1_SA_DQ<6>")
	)
	(segment
		(start 140.257784 -228.771958)
		(end 140.266166 -228.767132)
		(width 0.0889)
		(layer "In11.Cu")
		(net "M_L_CPU1_SA_DQ<6>")
	)
	(segment
		(start 151.903684 -215.926924)
		(end 152.134316 -215.926924)
		(width 0.14478)
		(layer "In11.Cu")
		(net "M_L_CPU1_SA_DQ<6>")
	)
	(segment
		(start 148.777452 -218.312238)
		(end 148.777452 -218.081606)
		(width 0.14478)
		(layer "In11.Cu")
		(net "M_L_CPU1_SA_DQ<6>")
	)
	(segment
		(start 150.352252 -216.737438)
		(end 150.352252 -216.506806)
		(width 0.14478)
		(layer "In11.Cu")
		(net "M_L_CPU1_SA_DQ<6>")
	)
	(segment
		(start 149.170898 -217.918538)
		(end 149.541484 -218.289124)
		(width 0.14478)
		(layer "In11.Cu")
		(net "M_L_CPU1_SA_DQ<6>")
	)
	(segment
		(start 151.533098 -215.556338)
		(end 151.903684 -215.926924)
		(width 0.14478)
		(layer "In11.Cu")
		(net "M_L_CPU1_SA_DQ<6>")
	)
	(segment
		(start 151.346916 -216.714324)
		(end 151.509984 -216.551256)
		(width 0.14478)
		(layer "In11.Cu")
		(net "M_L_CPU1_SA_DQ<6>")
	)
	(segment
		(start 150.352252 -216.506806)
		(end 150.515574 -216.343484)
		(width 0.14478)
		(layer "In11.Cu")
		(net "M_L_CPU1_SA_DQ<6>")
	)
	(segment
		(start 142.503398 -228.767132)
		(end 142.51178 -228.771958)
		(width 0.0889)
		(layer "In11.Cu")
		(net "M_L_CPU1_SA_DQ<6>")
	)
	(segment
		(start 149.564852 -217.524838)
		(end 149.564852 -217.294206)
		(width 0.14478)
		(layer "In11.Cu")
		(net "M_L_CPU1_SA_DQ<6>")
	)
	(segment
		(start 152.090374 -214.768684)
		(end 152.320498 -214.768938)
		(width 0.14478)
		(layer "In11.Cu")
		(net "M_L_CPU1_SA_DQ<6>")
	)
	(segment
		(start 173.506384 -204.560424)
		(end 174.356268 -203.71054)
		(width 0.14478)
		(layer "In11.Cu")
		(net "M_L_CPU1_SA_DQ<6>")
	)
	(segment
		(start 170.285918 -203.710286)
		(end 171.136056 -204.560424)
		(width 0.14478)
		(layer "In11.Cu")
		(net "M_L_CPU1_SA_DQ<6>")
	)
	(segment
		(start 166.79799 -203.710286)
		(end 170.285918 -203.710286)
		(width 0.14478)
		(layer "In11.Cu")
		(net "M_L_CPU1_SA_DQ<6>")
	)
	(segment
		(start 149.148038 -218.682824)
		(end 148.777452 -218.312238)
		(width 0.14478)
		(layer "In11.Cu")
		(net "M_L_CPU1_SA_DQ<6>")
	)
	(segment
		(start 150.722584 -217.338656)
		(end 150.722838 -217.108024)
		(width 0.14478)
		(layer "In11.Cu")
		(net "M_L_CPU1_SA_DQ<6>")
	)
	(segment
		(start 152.320498 -214.768938)
		(end 152.691084 -215.139524)
		(width 0.14478)
		(layer "In11.Cu")
		(net "M_L_CPU1_SA_DQ<6>")
	)
	(segment
		(start 192.59804 -203.71054)
		(end 193.447924 -204.560424)
		(width 0.14478)
		(layer "In11.Cu")
		(net "M_L_CPU1_SA_DQ<6>")
	)
	(segment
		(start 152.134316 -215.926924)
		(end 152.297384 -215.763856)
		(width 0.14478)
		(layer "In11.Cu")
		(net "M_L_CPU1_SA_DQ<6>")
	)
	(segment
		(start 178.82235 -204.560424)
		(end 181.065424 -204.560424)
		(width 0.14478)
		(layer "In11.Cu")
		(net "M_L_CPU1_SA_DQ<6>")
	)
	(segment
		(start 148.42363 -222.762064)
		(end 148.42363 -219.63761)
		(width 0.14478)
		(layer "In11.Cu")
		(net "M_L_CPU1_SA_DQ<6>")
	)
	(segment
		(start 152.691084 -215.139524)
		(end 152.921716 -215.139524)
		(width 0.14478)
		(layer "In11.Cu")
		(net "M_L_CPU1_SA_DQ<6>")
	)
	(segment
		(start 146.139154 -224.879662)
		(end 146.642328 -224.543366)
		(width 0.0889)
		(layer "In11.Cu")
		(net "M_L_CPU1_SA_DQ<6>")
	)
	(segment
		(start 148.42363 -219.63761)
		(end 149.147784 -218.913456)
		(width 0.14478)
		(layer "In11.Cu")
		(net "M_L_CPU1_SA_DQ<6>")
	)
	(segment
		(start 201.723244 -203.71054)
		(end 202.147932 -204.135228)
		(width 0.14478)
		(layer "In11.Cu")
		(net "M_L_CPU1_SA_DQ<6>")
	)
	(segment
		(start 163.500816 -204.560424)
		(end 165.947852 -204.560424)
		(width 0.14478)
		(layer "In11.Cu")
		(net "M_L_CPU1_SA_DQ<6>")
	)
	(segment
		(start 150.328884 -217.501724)
		(end 150.559516 -217.501724)
		(width 0.14478)
		(layer "In11.Cu")
		(net "M_L_CPU1_SA_DQ<6>")
	)
	(segment
		(start 143.077692 -228.771958)
		(end 143.086074 -228.767132)
		(width 0.0889)
		(layer "In11.Cu")
		(net "M_L_CPU1_SA_DQ<6>")
	)
	(segment
		(start 177.972466 -203.71054)
		(end 178.82235 -204.560424)
		(width 0.14478)
		(layer "In11.Cu")
		(net "M_L_CPU1_SA_DQ<6>")
	)
	(segment
		(start 151.509984 -216.551256)
		(end 151.510238 -216.320624)
		(width 0.14478)
		(layer "In11.Cu")
		(net "M_L_CPU1_SA_DQ<6>")
	)
	(segment
		(start 143.75003 -228.847904)
		(end 144.050512 -228.847904)
		(width 0.0889)
		(layer "In11.Cu")
		(net "M_L_CPU1_SA_DQ<6>")
	)
	(segment
		(start 148.777452 -218.081606)
		(end 148.940774 -217.918284)
		(width 0.14478)
		(layer "In11.Cu")
		(net "M_L_CPU1_SA_DQ<6>")
	)
	(segment
		(start 144.79397 -226.996244)
		(end 145.73377 -226.056444)
		(width 0.0889)
		(layer "In11.Cu")
		(net "M_L_CPU1_SA_DQ<6>")
	)
	(segment
		(start 151.510238 -216.320624)
		(end 151.139652 -215.950038)
		(width 0.14478)
		(layer "In11.Cu")
		(net "M_L_CPU1_SA_DQ<6>")
	)
	(segment
		(start 181.065424 -204.560424)
		(end 181.915308 -203.71054)
		(width 0.14478)
		(layer "In11.Cu")
		(net "M_L_CPU1_SA_DQ<6>")
	)
	(segment
		(start 171.136056 -204.560424)
		(end 173.506384 -204.560424)
		(width 0.14478)
		(layer "In11.Cu")
		(net "M_L_CPU1_SA_DQ<6>")
	)
	(segment
		(start 149.958298 -217.131138)
		(end 150.328884 -217.501724)
		(width 0.14478)
		(layer "In11.Cu")
		(net "M_L_CPU1_SA_DQ<6>")
	)
	(segment
		(start 149.935438 -217.895424)
		(end 149.564852 -217.524838)
		(width 0.14478)
		(layer "In11.Cu")
		(net "M_L_CPU1_SA_DQ<6>")
	)
	(segment
		(start 152.921716 -215.139524)
		(end 163.500816 -204.560424)
		(width 0.14478)
		(layer "In11.Cu")
		(net "M_L_CPU1_SA_DQ<6>")
	)
	(segment
		(start 146.642328 -224.543366)
		(end 147.761706 -223.423988)
		(width 0.0889)
		(layer "In11.Cu")
		(net "M_L_CPU1_SA_DQ<6>")
	)
	(segment
		(start 151.139652 -215.950038)
		(end 151.139652 -215.719406)
		(width 0.14478)
		(layer "In11.Cu")
		(net "M_L_CPU1_SA_DQ<6>")
	)
	(segment
		(start 188.673232 -204.560424)
		(end 189.523116 -203.71054)
		(width 0.14478)
		(layer "In11.Cu")
		(net "M_L_CPU1_SA_DQ<6>")
	)
	(segment
		(start 151.927052 -214.932006)
		(end 152.090374 -214.768684)
		(width 0.14478)
		(layer "In11.Cu")
		(net "M_L_CPU1_SA_DQ<6>")
	)
	(segment
		(start 151.927052 -215.162638)
		(end 151.927052 -214.932006)
		(width 0.14478)
		(layer "In11.Cu")
		(net "M_L_CPU1_SA_DQ<6>")
	)
	(segment
		(start 165.947852 -204.560424)
		(end 166.79799 -203.710286)
		(width 0.14478)
		(layer "In11.Cu")
		(net "M_L_CPU1_SA_DQ<6>")
	)
	(segment
		(start 150.745698 -216.343738)
		(end 151.116284 -216.714324)
		(width 0.14478)
		(layer "In11.Cu")
		(net "M_L_CPU1_SA_DQ<6>")
	)
	(segment
		(start 145.73377 -225.285046)
		(end 146.139154 -224.879662)
		(width 0.0889)
		(layer "In11.Cu")
		(net "M_L_CPU1_SA_DQ<6>")
	)
	(segment
		(start 193.447924 -204.560424)
		(end 196.262752 -204.560424)
		(width 0.14478)
		(layer "In11.Cu")
		(net "M_L_CPU1_SA_DQ<6>")
	)
	(segment
		(start 149.564852 -217.294206)
		(end 149.728174 -217.130884)
		(width 0.14478)
		(layer "In11.Cu")
		(net "M_L_CPU1_SA_DQ<6>")
	)
	(segment
		(start 151.116284 -216.714324)
		(end 151.346916 -216.714324)
		(width 0.14478)
		(layer "In11.Cu")
		(net "M_L_CPU1_SA_DQ<6>")
	)
	(segment
		(start 145.73377 -226.056444)
		(end 145.73377 -225.285046)
		(width 0.0889)
		(layer "In11.Cu")
		(net "M_L_CPU1_SA_DQ<6>")
	)
	(segment
		(start 144.79397 -228.104446)
		(end 144.79397 -226.996244)
		(width 0.0889)
		(layer "In11.Cu")
		(net "M_L_CPU1_SA_DQ<6>")
	)
	(segment
		(start 151.139652 -215.719406)
		(end 151.302974 -215.556084)
		(width 0.14478)
		(layer "In11.Cu")
		(net "M_L_CPU1_SA_DQ<6>")
	)
	(segment
		(start 186.10072 -204.560424)
		(end 188.673232 -204.560424)
		(width 0.14478)
		(layer "In11.Cu")
		(net "M_L_CPU1_SA_DQ<6>")
	)
	(segment
		(start 150.559516 -217.501724)
		(end 150.722584 -217.338656)
		(width 0.14478)
		(layer "In11.Cu")
		(net "M_L_CPU1_SA_DQ<6>")
	)
	(segment
		(start 139.35075 -228.829108)
		(end 139.373102 -228.745796)
		(width 0.0889)
		(layer "In11.Cu")
		(net "M_L_CPU1_SA_DQ<6>")
	)
	(segment
		(start 148.940774 -217.918284)
		(end 149.170898 -217.918538)
		(width 0.14478)
		(layer "In11.Cu")
		(net "M_L_CPU1_SA_DQ<6>")
	)
	(segment
		(start 197.112636 -203.71054)
		(end 201.723244 -203.71054)
		(width 0.14478)
		(layer "In11.Cu")
		(net "M_L_CPU1_SA_DQ<6>")
	)
	(segment
		(start 150.722838 -217.108024)
		(end 150.352252 -216.737438)
		(width 0.14478)
		(layer "In11.Cu")
		(net "M_L_CPU1_SA_DQ<6>")
	)
	(segment
		(start 196.262752 -204.560424)
		(end 197.112636 -203.71054)
		(width 0.14478)
		(layer "In11.Cu")
		(net "M_L_CPU1_SA_DQ<6>")
	)
	(segment
		(start 149.728174 -217.130884)
		(end 149.958298 -217.131138)
		(width 0.14478)
		(layer "In11.Cu")
		(net "M_L_CPU1_SA_DQ<6>")
	)
	(segment
		(start 185.250836 -203.71054)
		(end 186.10072 -204.560424)
		(width 0.14478)
		(layer "In11.Cu")
		(net "M_L_CPU1_SA_DQ<6>")
	)
	(segment
		(start 139.504674 -229.094538)
		(end 139.35075 -228.829108)
		(width 0.0889)
		(layer "In11.Cu")
		(net "M_L_CPU1_SA_DQ<6>")
	)
	(arc
		(start 139.691872 -228.771958)
		(mid 139.974828 -228.848135)
		(end 140.257784 -228.771958)
		(width 0.0889)
		(layer "In11.Cu")
		(net "M_L_CPU1_SA_DQ<6>")
	)
	(arc
		(start 143.451834 -228.771958)
		(mid 143.595647 -228.830689)
		(end 143.75003 -228.847904)
		(width 0.0889)
		(layer "In11.Cu")
		(net "M_L_CPU1_SA_DQ<6>")
	)
	(arc
		(start 140.631926 -228.771958)
		(mid 140.914882 -228.848135)
		(end 141.197838 -228.771958)
		(width 0.0889)
		(layer "In11.Cu")
		(net "M_L_CPU1_SA_DQ<6>")
	)
	(arc
		(start 139.373102 -228.745796)
		(mid 139.535434 -228.722978)
		(end 139.691872 -228.771958)
		(width 0.0889)
		(layer "In11.Cu")
		(net "M_L_CPU1_SA_DQ<6>")
	)
	(arc
		(start 142.137638 -228.771958)
		(mid 142.319889 -228.721608)
		(end 142.503398 -228.767132)
		(width 0.0889)
		(layer "In11.Cu")
		(net "M_L_CPU1_SA_DQ<6>")
	)
	(arc
		(start 140.266166 -228.767132)
		(mid 140.449674 -228.721638)
		(end 140.631926 -228.771958)
		(width 0.0889)
		(layer "In11.Cu")
		(net "M_L_CPU1_SA_DQ<6>")
	)
	(arc
		(start 142.51178 -228.771958)
		(mid 142.794736 -228.848135)
		(end 143.077692 -228.771958)
		(width 0.0889)
		(layer "In11.Cu")
		(net "M_L_CPU1_SA_DQ<6>")
	)
	(arc
		(start 141.197838 -228.771958)
		(mid 141.384782 -228.721703)
		(end 141.571726 -228.771958)
		(width 0.0889)
		(layer "In11.Cu")
		(net "M_L_CPU1_SA_DQ<6>")
	)
	(arc
		(start 141.571726 -228.771958)
		(mid 141.854682 -228.848135)
		(end 142.137638 -228.771958)
		(width 0.0889)
		(layer "In11.Cu")
		(net "M_L_CPU1_SA_DQ<6>")
	)
	(arc
		(start 143.086074 -228.767132)
		(mid 143.269582 -228.721638)
		(end 143.451834 -228.771958)
		(width 0.0889)
		(layer "In11.Cu")
		(net "M_L_CPU1_SA_DQ<6>")
	)
	(segment
		(start 137.157968 -229.360476)
		(end 137.62482 -229.094538)
		(width 0.10668)
		(layer "F.Cu")
		(net "M_L_CPU1_SA_DQ<5>")
	)
	(segment
		(start 204.090778 -204.560424)
		(end 204.253846 -204.723492)
		(width 0.14478)
		(layer "In11.Cu")
		(net "M_L_CPU1_SA_DQ<5>")
	)
	(segment
		(start 181.851808 -204.560424)
		(end 185.250836 -204.560424)
		(width 0.14478)
		(layer "In11.Cu")
		(net "M_L_CPU1_SA_DQ<5>")
	)
	(segment
		(start 142.503398 -229.42169)
		(end 142.51178 -229.416864)
		(width 0.0889)
		(layer "In11.Cu")
		(net "M_L_CPU1_SA_DQ<5>")
	)
	(segment
		(start 204.253846 -205.263496)
		(end 204.416914 -205.426564)
		(width 0.14478)
		(layer "In11.Cu")
		(net "M_L_CPU1_SA_DQ<5>")
	)
	(segment
		(start 145.00733 -228.134926)
		(end 145.574766 -227.56749)
		(width 0.0889)
		(layer "In11.Cu")
		(net "M_L_CPU1_SA_DQ<5>")
	)
	(segment
		(start 204.647292 -205.426564)
		(end 204.81036 -205.263496)
		(width 0.14478)
		(layer "In11.Cu")
		(net "M_L_CPU1_SA_DQ<5>")
	)
	(segment
		(start 138.743436 -229.42169)
		(end 138.751818 -229.416864)
		(width 0.0889)
		(layer "In11.Cu")
		(net "M_L_CPU1_SA_DQ<5>")
	)
	(segment
		(start 145.574766 -227.56749)
		(end 145.574766 -226.516438)
		(width 0.0889)
		(layer "In11.Cu")
		(net "M_L_CPU1_SA_DQ<5>")
	)
	(segment
		(start 185.250836 -204.560424)
		(end 186.10072 -205.410308)
		(width 0.14478)
		(layer "In11.Cu")
		(net "M_L_CPU1_SA_DQ<5>")
	)
	(segment
		(start 140.257784 -229.416864)
		(end 140.266166 -229.42169)
		(width 0.0889)
		(layer "In11.Cu")
		(net "M_L_CPU1_SA_DQ<5>")
	)
	(segment
		(start 146.651218 -225.677984)
		(end 146.96313 -225.366072)
		(width 0.0889)
		(layer "In11.Cu")
		(net "M_L_CPU1_SA_DQ<5>")
	)
	(segment
		(start 145.00733 -228.355652)
		(end 145.00733 -228.134926)
		(width 0.0889)
		(layer "In11.Cu")
		(net "M_L_CPU1_SA_DQ<5>")
	)
	(segment
		(start 148.941536 -222.88754)
		(end 148.941536 -219.762832)
		(width 0.14478)
		(layer "In11.Cu")
		(net "M_L_CPU1_SA_DQ<5>")
	)
	(segment
		(start 137.778744 -229.359968)
		(end 137.874502 -229.385368)
		(width 0.0889)
		(layer "In11.Cu")
		(net "M_L_CPU1_SA_DQ<5>")
	)
	(segment
		(start 166.595298 -204.560424)
		(end 170.391328 -204.560424)
		(width 0.14478)
		(layer "In11.Cu")
		(net "M_L_CPU1_SA_DQ<5>")
	)
	(segment
		(start 178.82235 -205.410308)
		(end 181.001924 -205.410308)
		(width 0.14478)
		(layer "In11.Cu")
		(net "M_L_CPU1_SA_DQ<5>")
	)
	(segment
		(start 204.253846 -204.723492)
		(end 204.253846 -205.263496)
		(width 0.14478)
		(layer "In11.Cu")
		(net "M_L_CPU1_SA_DQ<5>")
	)
	(segment
		(start 188.673232 -205.410308)
		(end 189.523116 -204.560424)
		(width 0.14478)
		(layer "In11.Cu")
		(net "M_L_CPU1_SA_DQ<5>")
	)
	(segment
		(start 196.123814 -205.409038)
		(end 196.972428 -204.560424)
		(width 0.14478)
		(layer "In11.Cu")
		(net "M_L_CPU1_SA_DQ<5>")
	)
	(segment
		(start 204.416914 -205.426564)
		(end 204.647292 -205.426564)
		(width 0.14478)
		(layer "In11.Cu")
		(net "M_L_CPU1_SA_DQ<5>")
	)
	(segment
		(start 205.823058 -204.560424)
		(end 206.248 -204.985366)
		(width 0.14478)
		(layer "In11.Cu")
		(net "M_L_CPU1_SA_DQ<5>")
	)
	(segment
		(start 146.41322 -225.677984)
		(end 146.651218 -225.677984)
		(width 0.0889)
		(layer "In11.Cu")
		(net "M_L_CPU1_SA_DQ<5>")
	)
	(segment
		(start 165.745414 -205.410308)
		(end 166.595298 -204.560424)
		(width 0.14478)
		(layer "In11.Cu")
		(net "M_L_CPU1_SA_DQ<5>")
	)
	(segment
		(start 174.369476 -204.560424)
		(end 177.972466 -204.560424)
		(width 0.14478)
		(layer "In11.Cu")
		(net "M_L_CPU1_SA_DQ<5>")
	)
	(segment
		(start 163.29406 -205.410308)
		(end 165.745414 -205.410308)
		(width 0.14478)
		(layer "In11.Cu")
		(net "M_L_CPU1_SA_DQ<5>")
	)
	(segment
		(start 148.941536 -219.762832)
		(end 163.29406 -205.410308)
		(width 0.14478)
		(layer "In11.Cu")
		(net "M_L_CPU1_SA_DQ<5>")
	)
	(segment
		(start 186.10072 -205.410308)
		(end 188.673232 -205.410308)
		(width 0.14478)
		(layer "In11.Cu")
		(net "M_L_CPU1_SA_DQ<5>")
	)
	(segment
		(start 139.31773 -229.416864)
		(end 139.326112 -229.42169)
		(width 0.0889)
		(layer "In11.Cu")
		(net "M_L_CPU1_SA_DQ<5>")
	)
	(segment
		(start 204.973428 -204.560424)
		(end 205.823058 -204.560424)
		(width 0.14478)
		(layer "In11.Cu")
		(net "M_L_CPU1_SA_DQ<5>")
	)
	(segment
		(start 173.519592 -205.410308)
		(end 174.369476 -204.560424)
		(width 0.14478)
		(layer "In11.Cu")
		(net "M_L_CPU1_SA_DQ<5>")
	)
	(segment
		(start 204.81036 -205.263496)
		(end 204.81036 -204.723492)
		(width 0.14478)
		(layer "In11.Cu")
		(net "M_L_CPU1_SA_DQ<5>")
	)
	(segment
		(start 147.791678 -224.037398)
		(end 148.941536 -222.88754)
		(width 0.14478)
		(layer "In11.Cu")
		(net "M_L_CPU1_SA_DQ<5>")
	)
	(segment
		(start 193.510662 -205.409038)
		(end 196.123814 -205.409038)
		(width 0.14478)
		(layer "In11.Cu")
		(net "M_L_CPU1_SA_DQ<5>")
	)
	(segment
		(start 145.574766 -226.516438)
		(end 146.41322 -225.677984)
		(width 0.0889)
		(layer "In11.Cu")
		(net "M_L_CPU1_SA_DQ<5>")
	)
	(segment
		(start 171.241212 -205.410308)
		(end 173.519592 -205.410308)
		(width 0.14478)
		(layer "In11.Cu")
		(net "M_L_CPU1_SA_DQ<5>")
	)
	(segment
		(start 181.001924 -205.410308)
		(end 181.851808 -204.560424)
		(width 0.14478)
		(layer "In11.Cu")
		(net "M_L_CPU1_SA_DQ<5>")
	)
	(segment
		(start 192.662048 -204.560424)
		(end 193.510662 -205.409038)
		(width 0.14478)
		(layer "In11.Cu")
		(net "M_L_CPU1_SA_DQ<5>")
	)
	(segment
		(start 137.62482 -229.094538)
		(end 137.778744 -229.359968)
		(width 0.0889)
		(layer "In11.Cu")
		(net "M_L_CPU1_SA_DQ<5>")
	)
	(segment
		(start 170.391328 -204.560424)
		(end 171.241212 -205.410308)
		(width 0.14478)
		(layer "In11.Cu")
		(net "M_L_CPU1_SA_DQ<5>")
	)
	(segment
		(start 204.81036 -204.723492)
		(end 204.973428 -204.560424)
		(width 0.14478)
		(layer "In11.Cu")
		(net "M_L_CPU1_SA_DQ<5>")
	)
	(segment
		(start 146.96313 -224.865946)
		(end 147.791678 -224.037398)
		(width 0.0889)
		(layer "In11.Cu")
		(net "M_L_CPU1_SA_DQ<5>")
	)
	(segment
		(start 144.022318 -229.340664)
		(end 145.00733 -228.355652)
		(width 0.0889)
		(layer "In11.Cu")
		(net "M_L_CPU1_SA_DQ<5>")
	)
	(segment
		(start 146.96313 -225.366072)
		(end 146.96313 -224.865946)
		(width 0.0889)
		(layer "In11.Cu")
		(net "M_L_CPU1_SA_DQ<5>")
	)
	(segment
		(start 143.734536 -229.340664)
		(end 144.022318 -229.340664)
		(width 0.0889)
		(layer "In11.Cu")
		(net "M_L_CPU1_SA_DQ<5>")
	)
	(segment
		(start 177.972466 -204.560424)
		(end 178.82235 -205.410308)
		(width 0.14478)
		(layer "In11.Cu")
		(net "M_L_CPU1_SA_DQ<5>")
	)
	(segment
		(start 189.523116 -204.560424)
		(end 192.662048 -204.560424)
		(width 0.14478)
		(layer "In11.Cu")
		(net "M_L_CPU1_SA_DQ<5>")
	)
	(segment
		(start 196.972428 -204.560424)
		(end 204.090778 -204.560424)
		(width 0.14478)
		(layer "In11.Cu")
		(net "M_L_CPU1_SA_DQ<5>")
	)
	(segment
		(start 143.077692 -229.416864)
		(end 143.086074 -229.42169)
		(width 0.0889)
		(layer "In11.Cu")
		(net "M_L_CPU1_SA_DQ<5>")
	)
	(arc
		(start 137.874502 -229.385368)
		(mid 138.129824 -229.341668)
		(end 138.377676 -229.416864)
		(width 0.0889)
		(layer "In11.Cu")
		(net "M_L_CPU1_SA_DQ<5>")
	)
	(arc
		(start 141.197838 -229.416864)
		(mid 141.384782 -229.467153)
		(end 141.571726 -229.416864)
		(width 0.0889)
		(layer "In11.Cu")
		(net "M_L_CPU1_SA_DQ<5>")
	)
	(arc
		(start 138.377676 -229.416864)
		(mid 138.559927 -229.467248)
		(end 138.743436 -229.42169)
		(width 0.0889)
		(layer "In11.Cu")
		(net "M_L_CPU1_SA_DQ<5>")
	)
	(arc
		(start 140.266166 -229.42169)
		(mid 140.449674 -229.467215)
		(end 140.631926 -229.416864)
		(width 0.0889)
		(layer "In11.Cu")
		(net "M_L_CPU1_SA_DQ<5>")
	)
	(arc
		(start 138.751818 -229.416864)
		(mid 139.034774 -229.340687)
		(end 139.31773 -229.416864)
		(width 0.0889)
		(layer "In11.Cu")
		(net "M_L_CPU1_SA_DQ<5>")
	)
	(arc
		(start 140.631926 -229.416864)
		(mid 140.914882 -229.340687)
		(end 141.197838 -229.416864)
		(width 0.0889)
		(layer "In11.Cu")
		(net "M_L_CPU1_SA_DQ<5>")
	)
	(arc
		(start 142.51178 -229.416864)
		(mid 142.794736 -229.340687)
		(end 143.077692 -229.416864)
		(width 0.0889)
		(layer "In11.Cu")
		(net "M_L_CPU1_SA_DQ<5>")
	)
	(arc
		(start 143.086074 -229.42169)
		(mid 143.269582 -229.467215)
		(end 143.451834 -229.416864)
		(width 0.0889)
		(layer "In11.Cu")
		(net "M_L_CPU1_SA_DQ<5>")
	)
	(arc
		(start 139.691872 -229.416864)
		(mid 139.974828 -229.340687)
		(end 140.257784 -229.416864)
		(width 0.0889)
		(layer "In11.Cu")
		(net "M_L_CPU1_SA_DQ<5>")
	)
	(arc
		(start 141.571726 -229.416864)
		(mid 141.854682 -229.340687)
		(end 142.137638 -229.416864)
		(width 0.0889)
		(layer "In11.Cu")
		(net "M_L_CPU1_SA_DQ<5>")
	)
	(arc
		(start 143.451834 -229.416864)
		(mid 143.588152 -229.360097)
		(end 143.734536 -229.340664)
		(width 0.0889)
		(layer "In11.Cu")
		(net "M_L_CPU1_SA_DQ<5>")
	)
	(arc
		(start 139.326112 -229.42169)
		(mid 139.50962 -229.467215)
		(end 139.691872 -229.416864)
		(width 0.0889)
		(layer "In11.Cu")
		(net "M_L_CPU1_SA_DQ<5>")
	)
	(arc
		(start 142.137638 -229.416864)
		(mid 142.319889 -229.467248)
		(end 142.503398 -229.42169)
		(width 0.0889)
		(layer "In11.Cu")
		(net "M_L_CPU1_SA_DQ<5>")
	)
	(segment
		(start 138.567922 -228.55047)
		(end 139.034774 -228.284532)
		(width 0.10668)
		(layer "F.Cu")
		(net "M_L_CPU1_SA_DQ<4>")
	)
	(segment
		(start 147.921726 -222.620586)
		(end 147.921726 -218.29395)
		(width 0.14478)
		(layer "In11.Cu")
		(net "M_L_CPU1_SA_DQ<4>")
	)
	(segment
		(start 140.15339 -228.611938)
		(end 140.161772 -228.607112)
		(width 0.0889)
		(layer "In11.Cu")
		(net "M_L_CPU1_SA_DQ<4>")
	)
	(segment
		(start 166.926006 -202.8698)
		(end 170.173904 -202.8698)
		(width 0.14478)
		(layer "In11.Cu")
		(net "M_L_CPU1_SA_DQ<4>")
	)
	(segment
		(start 205.823058 -202.860402)
		(end 206.248 -203.285344)
		(width 0.14478)
		(layer "In11.Cu")
		(net "M_L_CPU1_SA_DQ<4>")
	)
	(segment
		(start 163.707826 -203.710286)
		(end 166.08552 -203.710286)
		(width 0.14478)
		(layer "In11.Cu")
		(net "M_L_CPU1_SA_DQ<4>")
	)
	(segment
		(start 173.591982 -203.719684)
		(end 174.441866 -202.8698)
		(width 0.14478)
		(layer "In11.Cu")
		(net "M_L_CPU1_SA_DQ<4>")
	)
	(segment
		(start 205.246986 -202.860402)
		(end 205.823058 -202.860402)
		(width 0.14478)
		(layer "In11.Cu")
		(net "M_L_CPU1_SA_DQ<4>")
	)
	(segment
		(start 189.513718 -202.8698)
		(end 192.612518 -202.8698)
		(width 0.14478)
		(layer "In11.Cu")
		(net "M_L_CPU1_SA_DQ<4>")
	)
	(segment
		(start 185.260234 -202.8698)
		(end 186.110118 -203.719684)
		(width 0.14478)
		(layer "In11.Cu")
		(net "M_L_CPU1_SA_DQ<4>")
	)
	(segment
		(start 182.062374 -202.8698)
		(end 185.260234 -202.8698)
		(width 0.14478)
		(layer "In11.Cu")
		(net "M_L_CPU1_SA_DQ<4>")
	)
	(segment
		(start 197.198742 -202.8698)
		(end 204.373734 -202.8698)
		(width 0.14478)
		(layer "In11.Cu")
		(net "M_L_CPU1_SA_DQ<4>")
	)
	(segment
		(start 151.901652 -214.314024)
		(end 153.104088 -214.314024)
		(width 0.14478)
		(layer "In11.Cu")
		(net "M_L_CPU1_SA_DQ<4>")
	)
	(segment
		(start 145.53057 -225.173032)
		(end 145.879566 -224.824036)
		(width 0.0889)
		(layer "In11.Cu")
		(net "M_L_CPU1_SA_DQ<4>")
	)
	(segment
		(start 204.527404 -203.510896)
		(end 204.690472 -203.673964)
		(width 0.14478)
		(layer "In11.Cu")
		(net "M_L_CPU1_SA_DQ<4>")
	)
	(segment
		(start 144.585944 -227.943156)
		(end 144.585944 -226.916488)
		(width 0.0889)
		(layer "In11.Cu")
		(net "M_L_CPU1_SA_DQ<4>")
	)
	(segment
		(start 205.083918 -203.02347)
		(end 205.246986 -202.860402)
		(width 0.14478)
		(layer "In11.Cu")
		(net "M_L_CPU1_SA_DQ<4>")
	)
	(segment
		(start 177.905664 -202.8698)
		(end 178.755548 -203.719684)
		(width 0.14478)
		(layer "In11.Cu")
		(net "M_L_CPU1_SA_DQ<4>")
	)
	(segment
		(start 181.21249 -203.719684)
		(end 182.062374 -202.8698)
		(width 0.14478)
		(layer "In11.Cu")
		(net "M_L_CPU1_SA_DQ<4>")
	)
	(segment
		(start 205.083918 -203.510896)
		(end 205.083918 -203.02347)
		(width 0.14478)
		(layer "In11.Cu")
		(net "M_L_CPU1_SA_DQ<4>")
	)
	(segment
		(start 147.921726 -218.29395)
		(end 151.901652 -214.314024)
		(width 0.14478)
		(layer "In11.Cu")
		(net "M_L_CPU1_SA_DQ<4>")
	)
	(segment
		(start 141.093444 -228.611938)
		(end 141.101826 -228.607112)
		(width 0.0889)
		(layer "In11.Cu")
		(net "M_L_CPU1_SA_DQ<4>")
	)
	(segment
		(start 178.755548 -203.719684)
		(end 181.21249 -203.719684)
		(width 0.14478)
		(layer "In11.Cu")
		(net "M_L_CPU1_SA_DQ<4>")
	)
	(segment
		(start 186.110118 -203.719684)
		(end 188.663834 -203.719684)
		(width 0.14478)
		(layer "In11.Cu")
		(net "M_L_CPU1_SA_DQ<4>")
	)
	(segment
		(start 146.671284 -223.871028)
		(end 147.591272 -222.95104)
		(width 0.0889)
		(layer "In11.Cu")
		(net "M_L_CPU1_SA_DQ<4>")
	)
	(segment
		(start 141.667738 -228.607112)
		(end 141.67612 -228.611938)
		(width 0.0889)
		(layer "In11.Cu")
		(net "M_L_CPU1_SA_DQ<4>")
	)
	(segment
		(start 204.690472 -203.673964)
		(end 204.92085 -203.673964)
		(width 0.14478)
		(layer "In11.Cu")
		(net "M_L_CPU1_SA_DQ<4>")
	)
	(segment
		(start 174.441866 -202.8698)
		(end 177.905664 -202.8698)
		(width 0.14478)
		(layer "In11.Cu")
		(net "M_L_CPU1_SA_DQ<4>")
	)
	(segment
		(start 204.92085 -203.673964)
		(end 205.083918 -203.510896)
		(width 0.14478)
		(layer "In11.Cu")
		(net "M_L_CPU1_SA_DQ<4>")
	)
	(segment
		(start 146.428968 -224.456498)
		(end 146.671284 -223.871028)
		(width 0.0889)
		(layer "In11.Cu")
		(net "M_L_CPU1_SA_DQ<4>")
	)
	(segment
		(start 145.879566 -224.824036)
		(end 146.428968 -224.456498)
		(width 0.0889)
		(layer "In11.Cu")
		(net "M_L_CPU1_SA_DQ<4>")
	)
	(segment
		(start 188.663834 -203.719684)
		(end 189.513718 -202.8698)
		(width 0.14478)
		(layer "In11.Cu")
		(net "M_L_CPU1_SA_DQ<4>")
	)
	(segment
		(start 171.023788 -203.719684)
		(end 173.591982 -203.719684)
		(width 0.14478)
		(layer "In11.Cu")
		(net "M_L_CPU1_SA_DQ<4>")
	)
	(segment
		(start 170.173904 -202.8698)
		(end 171.023788 -203.719684)
		(width 0.14478)
		(layer "In11.Cu")
		(net "M_L_CPU1_SA_DQ<4>")
	)
	(segment
		(start 166.08552 -203.710286)
		(end 166.926006 -202.8698)
		(width 0.14478)
		(layer "In11.Cu")
		(net "M_L_CPU1_SA_DQ<4>")
	)
	(segment
		(start 192.612518 -202.8698)
		(end 193.462402 -203.719684)
		(width 0.14478)
		(layer "In11.Cu")
		(net "M_L_CPU1_SA_DQ<4>")
	)
	(segment
		(start 204.373734 -202.8698)
		(end 204.527404 -203.02347)
		(width 0.14478)
		(layer "In11.Cu")
		(net "M_L_CPU1_SA_DQ<4>")
	)
	(segment
		(start 139.034774 -228.284532)
		(end 139.188698 -228.549962)
		(width 0.0889)
		(layer "In11.Cu")
		(net "M_L_CPU1_SA_DQ<4>")
	)
	(segment
		(start 153.104088 -214.314024)
		(end 163.707826 -203.710286)
		(width 0.14478)
		(layer "In11.Cu")
		(net "M_L_CPU1_SA_DQ<4>")
	)
	(segment
		(start 196.348858 -203.719684)
		(end 197.198742 -202.8698)
		(width 0.14478)
		(layer "In11.Cu")
		(net "M_L_CPU1_SA_DQ<4>")
	)
	(segment
		(start 193.462402 -203.719684)
		(end 196.348858 -203.719684)
		(width 0.14478)
		(layer "In11.Cu")
		(net "M_L_CPU1_SA_DQ<4>")
	)
	(segment
		(start 147.591272 -222.95104)
		(end 147.921726 -222.620586)
		(width 0.14478)
		(layer "In11.Cu")
		(net "M_L_CPU1_SA_DQ<4>")
	)
	(segment
		(start 139.188698 -228.549962)
		(end 139.28471 -228.575362)
		(width 0.0889)
		(layer "In11.Cu")
		(net "M_L_CPU1_SA_DQ<4>")
	)
	(segment
		(start 144.585944 -226.916488)
		(end 145.53057 -225.971862)
		(width 0.0889)
		(layer "In11.Cu")
		(net "M_L_CPU1_SA_DQ<4>")
	)
	(segment
		(start 145.53057 -225.971862)
		(end 145.53057 -225.173032)
		(width 0.0889)
		(layer "In11.Cu")
		(net "M_L_CPU1_SA_DQ<4>")
	)
	(segment
		(start 143.921988 -228.607112)
		(end 144.585944 -227.943156)
		(width 0.0889)
		(layer "In11.Cu")
		(net "M_L_CPU1_SA_DQ<4>")
	)
	(segment
		(start 204.527404 -203.02347)
		(end 204.527404 -203.510896)
		(width 0.14478)
		(layer "In11.Cu")
		(net "M_L_CPU1_SA_DQ<4>")
	)
	(arc
		(start 143.547592 -228.607112)
		(mid 143.73479 -228.657494)
		(end 143.921988 -228.607112)
		(width 0.0889)
		(layer "In11.Cu")
		(net "M_L_CPU1_SA_DQ<4>")
	)
	(arc
		(start 142.607792 -228.607112)
		(mid 142.794736 -228.657367)
		(end 142.98168 -228.607112)
		(width 0.0889)
		(layer "In11.Cu")
		(net "M_L_CPU1_SA_DQ<4>")
	)
	(arc
		(start 140.727684 -228.607112)
		(mid 140.909935 -228.657462)
		(end 141.093444 -228.611938)
		(width 0.0889)
		(layer "In11.Cu")
		(net "M_L_CPU1_SA_DQ<4>")
	)
	(arc
		(start 141.101826 -228.607112)
		(mid 141.384782 -228.530935)
		(end 141.667738 -228.607112)
		(width 0.0889)
		(layer "In11.Cu")
		(net "M_L_CPU1_SA_DQ<4>")
	)
	(arc
		(start 142.04188 -228.607112)
		(mid 142.324836 -228.530935)
		(end 142.607792 -228.607112)
		(width 0.0889)
		(layer "In11.Cu")
		(net "M_L_CPU1_SA_DQ<4>")
	)
	(arc
		(start 140.161772 -228.607112)
		(mid 140.444728 -228.530935)
		(end 140.727684 -228.607112)
		(width 0.0889)
		(layer "In11.Cu")
		(net "M_L_CPU1_SA_DQ<4>")
	)
	(arc
		(start 141.67612 -228.611938)
		(mid 141.859628 -228.657432)
		(end 142.04188 -228.607112)
		(width 0.0889)
		(layer "In11.Cu")
		(net "M_L_CPU1_SA_DQ<4>")
	)
	(arc
		(start 139.28471 -228.575362)
		(mid 139.539918 -228.531885)
		(end 139.78763 -228.607112)
		(width 0.0889)
		(layer "In11.Cu")
		(net "M_L_CPU1_SA_DQ<4>")
	)
	(arc
		(start 139.78763 -228.607112)
		(mid 139.969881 -228.657462)
		(end 140.15339 -228.611938)
		(width 0.0889)
		(layer "In11.Cu")
		(net "M_L_CPU1_SA_DQ<4>")
	)
	(arc
		(start 142.98168 -228.607112)
		(mid 143.264636 -228.530935)
		(end 143.547592 -228.607112)
		(width 0.0889)
		(layer "In11.Cu")
		(net "M_L_CPU1_SA_DQ<4>")
	)
	(segment
		(start 137.627868 -226.930458)
		(end 138.09472 -226.66452)
		(width 0.10668)
		(layer "F.Cu")
		(net "M_L_CPU1_SA_DQ<3>")
	)
	(segment
		(start 170.340528 -199.45096)
		(end 171.190412 -200.300844)
		(width 0.14478)
		(layer "In11.Cu")
		(net "M_L_CPU1_SA_DQ<3>")
	)
	(segment
		(start 158.994348 -203.581508)
		(end 159.22498 -203.581508)
		(width 0.14478)
		(layer "In11.Cu")
		(net "M_L_CPU1_SA_DQ<3>")
	)
	(segment
		(start 160.412684 -201.850244)
		(end 160.569148 -202.006708)
		(width 0.14478)
		(layer "In11.Cu")
		(net "M_L_CPU1_SA_DQ<3>")
	)
	(segment
		(start 160.806384 -201.225912)
		(end 160.969452 -201.062844)
		(width 0.14478)
		(layer "In11.Cu")
		(net "M_L_CPU1_SA_DQ<3>")
	)
	(segment
		(start 145.0848 -222.217742)
		(end 145.582386 -221.720156)
		(width 0.0889)
		(layer "In11.Cu")
		(net "M_L_CPU1_SA_DQ<3>")
	)
	(segment
		(start 144.457166 -223.119696)
		(end 144.487646 -223.101916)
		(width 0.0889)
		(layer "In11.Cu")
		(net "M_L_CPU1_SA_DQ<3>")
	)
	(segment
		(start 161.200084 -201.062844)
		(end 161.356548 -201.219308)
		(width 0.14478)
		(layer "In11.Cu")
		(net "M_L_CPU1_SA_DQ<3>")
	)
	(segment
		(start 178.015646 -199.45096)
		(end 178.86553 -200.300844)
		(width 0.14478)
		(layer "In11.Cu")
		(net "M_L_CPU1_SA_DQ<3>")
	)
	(segment
		(start 160.969452 -201.062844)
		(end 161.200084 -201.062844)
		(width 0.14478)
		(layer "In11.Cu")
		(net "M_L_CPU1_SA_DQ<3>")
	)
	(segment
		(start 145.582386 -221.720156)
		(end 145.582386 -221.213426)
		(width 0.0889)
		(layer "In11.Cu")
		(net "M_L_CPU1_SA_DQ<3>")
	)
	(segment
		(start 137.940796 -226.39909)
		(end 137.963148 -226.315778)
		(width 0.0889)
		(layer "In11.Cu")
		(net "M_L_CPU1_SA_DQ<3>")
	)
	(segment
		(start 160.01238 -202.794108)
		(end 160.175448 -202.63104)
		(width 0.14478)
		(layer "In11.Cu")
		(net "M_L_CPU1_SA_DQ<3>")
	)
	(segment
		(start 144.017492 -223.911922)
		(end 144.057878 -223.8883)
		(width 0.0889)
		(layer "In11.Cu")
		(net "M_L_CPU1_SA_DQ<3>")
	)
	(segment
		(start 166.832788 -199.45096)
		(end 170.340528 -199.45096)
		(width 0.14478)
		(layer "In11.Cu")
		(net "M_L_CPU1_SA_DQ<3>")
	)
	(segment
		(start 158.600648 -203.975208)
		(end 158.444184 -203.818744)
		(width 0.14478)
		(layer "In11.Cu")
		(net "M_L_CPU1_SA_DQ<3>")
	)
	(segment
		(start 174.436278 -199.45096)
		(end 178.015646 -199.45096)
		(width 0.14478)
		(layer "In11.Cu")
		(net "M_L_CPU1_SA_DQ<3>")
	)
	(segment
		(start 159.394652 -202.637644)
		(end 159.625284 -202.637644)
		(width 0.14478)
		(layer "In11.Cu")
		(net "M_L_CPU1_SA_DQ<3>")
	)
	(segment
		(start 193.157602 -199.451214)
		(end 194.007486 -200.301098)
		(width 0.14478)
		(layer "In11.Cu")
		(net "M_L_CPU1_SA_DQ<3>")
	)
	(segment
		(start 159.388048 -203.187808)
		(end 159.231584 -203.031344)
		(width 0.14478)
		(layer "In11.Cu")
		(net "M_L_CPU1_SA_DQ<3>")
	)
	(segment
		(start 160.018984 -202.243944)
		(end 160.018984 -202.013312)
		(width 0.14478)
		(layer "In11.Cu")
		(net "M_L_CPU1_SA_DQ<3>")
	)
	(segment
		(start 160.806384 -201.456544)
		(end 160.806384 -201.225912)
		(width 0.14478)
		(layer "In11.Cu")
		(net "M_L_CPU1_SA_DQ<3>")
	)
	(segment
		(start 160.182052 -201.850244)
		(end 160.412684 -201.850244)
		(width 0.14478)
		(layer "In11.Cu")
		(net "M_L_CPU1_SA_DQ<3>")
	)
	(segment
		(start 145.582386 -217.324178)
		(end 157.813248 -205.093316)
		(width 0.14478)
		(layer "In11.Cu")
		(net "M_L_CPU1_SA_DQ<3>")
	)
	(segment
		(start 158.444184 -203.818744)
		(end 158.444184 -203.588112)
		(width 0.14478)
		(layer "In11.Cu")
		(net "M_L_CPU1_SA_DQ<3>")
	)
	(segment
		(start 160.175448 -202.400408)
		(end 160.018984 -202.243944)
		(width 0.14478)
		(layer "In11.Cu")
		(net "M_L_CPU1_SA_DQ<3>")
	)
	(segment
		(start 160.018984 -202.013312)
		(end 160.182052 -201.850244)
		(width 0.14478)
		(layer "In11.Cu")
		(net "M_L_CPU1_SA_DQ<3>")
	)
	(segment
		(start 141.093444 -226.337114)
		(end 141.101826 -226.34194)
		(width 0.0889)
		(layer "In11.Cu")
		(net "M_L_CPU1_SA_DQ<3>")
	)
	(segment
		(start 186.091322 -200.301098)
		(end 188.68263 -200.301098)
		(width 0.14478)
		(layer "In11.Cu")
		(net "M_L_CPU1_SA_DQ<3>")
	)
	(segment
		(start 194.007486 -200.301098)
		(end 195.996814 -200.301098)
		(width 0.14478)
		(layer "In11.Cu")
		(net "M_L_CPU1_SA_DQ<3>")
	)
	(segment
		(start 185.241438 -199.451214)
		(end 186.091322 -200.301098)
		(width 0.14478)
		(layer "In11.Cu")
		(net "M_L_CPU1_SA_DQ<3>")
	)
	(segment
		(start 144.92478 -222.31096)
		(end 145.0848 -222.217742)
		(width 0.0889)
		(layer "In11.Cu")
		(net "M_L_CPU1_SA_DQ<3>")
	)
	(segment
		(start 196.846698 -199.451214)
		(end 201.713846 -199.451214)
		(width 0.14478)
		(layer "In11.Cu")
		(net "M_L_CPU1_SA_DQ<3>")
	)
	(segment
		(start 160.569148 -202.006708)
		(end 160.79978 -202.006708)
		(width 0.14478)
		(layer "In11.Cu")
		(net "M_L_CPU1_SA_DQ<3>")
	)
	(segment
		(start 143.985742 -223.93021)
		(end 144.017492 -223.911922)
		(width 0.0889)
		(layer "In11.Cu")
		(net "M_L_CPU1_SA_DQ<3>")
	)
	(segment
		(start 159.231584 -202.800712)
		(end 159.394652 -202.637644)
		(width 0.14478)
		(layer "In11.Cu")
		(net "M_L_CPU1_SA_DQ<3>")
	)
	(segment
		(start 201.713846 -199.451214)
		(end 202.147932 -199.8853)
		(width 0.14478)
		(layer "In11.Cu")
		(net "M_L_CPU1_SA_DQ<3>")
	)
	(segment
		(start 138.09472 -226.66452)
		(end 137.940796 -226.39909)
		(width 0.0889)
		(layer "In11.Cu")
		(net "M_L_CPU1_SA_DQ<3>")
	)
	(segment
		(start 171.190412 -200.300844)
		(end 173.586394 -200.300844)
		(width 0.14478)
		(layer "In11.Cu")
		(net "M_L_CPU1_SA_DQ<3>")
	)
	(segment
		(start 158.050484 -204.212444)
		(end 158.206948 -204.368908)
		(width 0.14478)
		(layer "In11.Cu")
		(net "M_L_CPU1_SA_DQ<3>")
	)
	(segment
		(start 157.819852 -204.212444)
		(end 158.050484 -204.212444)
		(width 0.14478)
		(layer "In11.Cu")
		(net "M_L_CPU1_SA_DQ<3>")
	)
	(segment
		(start 159.625284 -202.637644)
		(end 159.781748 -202.794108)
		(width 0.14478)
		(layer "In11.Cu")
		(net "M_L_CPU1_SA_DQ<3>")
	)
	(segment
		(start 158.206948 -204.368908)
		(end 158.43758 -204.368908)
		(width 0.14478)
		(layer "In11.Cu")
		(net "M_L_CPU1_SA_DQ<3>")
	)
	(segment
		(start 160.175448 -202.63104)
		(end 160.175448 -202.400408)
		(width 0.14478)
		(layer "In11.Cu")
		(net "M_L_CPU1_SA_DQ<3>")
	)
	(segment
		(start 159.781748 -202.794108)
		(end 160.01238 -202.794108)
		(width 0.14478)
		(layer "In11.Cu")
		(net "M_L_CPU1_SA_DQ<3>")
	)
	(segment
		(start 160.79978 -202.006708)
		(end 160.962848 -201.84364)
		(width 0.14478)
		(layer "In11.Cu")
		(net "M_L_CPU1_SA_DQ<3>")
	)
	(segment
		(start 161.356548 -201.219308)
		(end 161.58718 -201.219308)
		(width 0.14478)
		(layer "In11.Cu")
		(net "M_L_CPU1_SA_DQ<3>")
	)
	(segment
		(start 178.86553 -200.300844)
		(end 181.0004 -200.300844)
		(width 0.14478)
		(layer "In11.Cu")
		(net "M_L_CPU1_SA_DQ<3>")
	)
	(segment
		(start 181.85003 -199.451214)
		(end 185.241438 -199.451214)
		(width 0.14478)
		(layer "In11.Cu")
		(net "M_L_CPU1_SA_DQ<3>")
	)
	(segment
		(start 158.444184 -203.588112)
		(end 158.607252 -203.425044)
		(width 0.14478)
		(layer "In11.Cu")
		(net "M_L_CPU1_SA_DQ<3>")
	)
	(segment
		(start 140.15339 -226.337114)
		(end 140.161772 -226.34194)
		(width 0.0889)
		(layer "In11.Cu")
		(net "M_L_CPU1_SA_DQ<3>")
	)
	(segment
		(start 157.656784 -204.606144)
		(end 157.656784 -204.375512)
		(width 0.14478)
		(layer "In11.Cu")
		(net "M_L_CPU1_SA_DQ<3>")
	)
	(segment
		(start 195.996814 -200.301098)
		(end 196.846698 -199.451214)
		(width 0.14478)
		(layer "In11.Cu")
		(net "M_L_CPU1_SA_DQ<3>")
	)
	(segment
		(start 165.973506 -200.310242)
		(end 166.832788 -199.45096)
		(width 0.14478)
		(layer "In11.Cu")
		(net "M_L_CPU1_SA_DQ<3>")
	)
	(segment
		(start 157.813248 -204.762608)
		(end 157.656784 -204.606144)
		(width 0.14478)
		(layer "In11.Cu")
		(net "M_L_CPU1_SA_DQ<3>")
	)
	(segment
		(start 158.43758 -204.368908)
		(end 158.600648 -204.20584)
		(width 0.14478)
		(layer "In11.Cu")
		(net "M_L_CPU1_SA_DQ<3>")
	)
	(segment
		(start 143.045942 -225.550222)
		(end 143.077692 -225.531934)
		(width 0.0889)
		(layer "In11.Cu")
		(net "M_L_CPU1_SA_DQ<3>")
	)
	(segment
		(start 160.962848 -201.84364)
		(end 160.962848 -201.613008)
		(width 0.14478)
		(layer "In11.Cu")
		(net "M_L_CPU1_SA_DQ<3>")
	)
	(segment
		(start 141.667738 -226.34194)
		(end 141.67612 -226.337114)
		(width 0.0889)
		(layer "In11.Cu")
		(net "M_L_CPU1_SA_DQ<3>")
	)
	(segment
		(start 160.962848 -201.613008)
		(end 160.806384 -201.456544)
		(width 0.14478)
		(layer "In11.Cu")
		(net "M_L_CPU1_SA_DQ<3>")
	)
	(segment
		(start 158.600648 -204.20584)
		(end 158.600648 -203.975208)
		(width 0.14478)
		(layer "In11.Cu")
		(net "M_L_CPU1_SA_DQ<3>")
	)
	(segment
		(start 145.582386 -221.213426)
		(end 145.582386 -217.324178)
		(width 0.14478)
		(layer "In11.Cu")
		(net "M_L_CPU1_SA_DQ<3>")
	)
	(segment
		(start 159.22498 -203.581508)
		(end 159.388048 -203.41844)
		(width 0.14478)
		(layer "In11.Cu")
		(net "M_L_CPU1_SA_DQ<3>")
	)
	(segment
		(start 157.813248 -205.093316)
		(end 157.813248 -204.762608)
		(width 0.14478)
		(layer "In11.Cu")
		(net "M_L_CPU1_SA_DQ<3>")
	)
	(segment
		(start 189.532514 -199.451214)
		(end 193.157602 -199.451214)
		(width 0.14478)
		(layer "In11.Cu")
		(net "M_L_CPU1_SA_DQ<3>")
	)
	(segment
		(start 181.0004 -200.300844)
		(end 181.85003 -199.451214)
		(width 0.14478)
		(layer "In11.Cu")
		(net "M_L_CPU1_SA_DQ<3>")
	)
	(segment
		(start 144.487646 -223.101916)
		(end 144.522444 -223.081596)
		(width 0.0889)
		(layer "In11.Cu")
		(net "M_L_CPU1_SA_DQ<3>")
	)
	(segment
		(start 188.68263 -200.301098)
		(end 189.532514 -199.451214)
		(width 0.14478)
		(layer "In11.Cu")
		(net "M_L_CPU1_SA_DQ<3>")
	)
	(segment
		(start 158.607252 -203.425044)
		(end 158.837884 -203.425044)
		(width 0.14478)
		(layer "In11.Cu")
		(net "M_L_CPU1_SA_DQ<3>")
	)
	(segment
		(start 173.586394 -200.300844)
		(end 174.436278 -199.45096)
		(width 0.14478)
		(layer "In11.Cu")
		(net "M_L_CPU1_SA_DQ<3>")
	)
	(segment
		(start 159.388048 -203.41844)
		(end 159.388048 -203.187808)
		(width 0.14478)
		(layer "In11.Cu")
		(net "M_L_CPU1_SA_DQ<3>")
	)
	(segment
		(start 158.837884 -203.425044)
		(end 158.994348 -203.581508)
		(width 0.14478)
		(layer "In11.Cu")
		(net "M_L_CPU1_SA_DQ<3>")
	)
	(segment
		(start 143.517112 -224.739708)
		(end 143.547592 -224.721928)
		(width 0.0889)
		(layer "In11.Cu")
		(net "M_L_CPU1_SA_DQ<3>")
	)
	(segment
		(start 143.547592 -224.721928)
		(end 143.583914 -224.700846)
		(width 0.0889)
		(layer "In11.Cu")
		(net "M_L_CPU1_SA_DQ<3>")
	)
	(segment
		(start 159.231584 -203.031344)
		(end 159.231584 -202.800712)
		(width 0.14478)
		(layer "In11.Cu")
		(net "M_L_CPU1_SA_DQ<3>")
	)
	(segment
		(start 142.607792 -226.34194)
		(end 142.644114 -226.320858)
		(width 0.0889)
		(layer "In11.Cu")
		(net "M_L_CPU1_SA_DQ<3>")
	)
	(segment
		(start 162.496246 -200.310242)
		(end 165.973506 -200.310242)
		(width 0.14478)
		(layer "In11.Cu")
		(net "M_L_CPU1_SA_DQ<3>")
	)
	(segment
		(start 157.656784 -204.375512)
		(end 157.819852 -204.212444)
		(width 0.14478)
		(layer "In11.Cu")
		(net "M_L_CPU1_SA_DQ<3>")
	)
	(segment
		(start 161.58718 -201.219308)
		(end 162.496246 -200.310242)
		(width 0.14478)
		(layer "In11.Cu")
		(net "M_L_CPU1_SA_DQ<3>")
	)
	(segment
		(start 143.077692 -225.531934)
		(end 143.116808 -225.509074)
		(width 0.0889)
		(layer "In11.Cu")
		(net "M_L_CPU1_SA_DQ<3>")
	)
	(arc
		(start 138.281918 -226.34194)
		(mid 138.564874 -226.418117)
		(end 138.84783 -226.34194)
		(width 0.0889)
		(layer "In11.Cu")
		(net "M_L_CPU1_SA_DQ<3>")
	)
	(arc
		(start 144.522444 -223.081596)
		(mid 144.704023 -222.878729)
		(end 144.769586 -222.61449)
		(width 0.0889)
		(layer "In11.Cu")
		(net "M_L_CPU1_SA_DQ<3>")
	)
	(arc
		(start 141.101826 -226.34194)
		(mid 141.384782 -226.418117)
		(end 141.667738 -226.34194)
		(width 0.0889)
		(layer "In11.Cu")
		(net "M_L_CPU1_SA_DQ<3>")
	)
	(arc
		(start 144.300194 -223.424496)
		(mid 144.341743 -223.253074)
		(end 144.457166 -223.119696)
		(width 0.0889)
		(layer "In11.Cu")
		(net "M_L_CPU1_SA_DQ<3>")
	)
	(arc
		(start 142.889986 -225.854514)
		(mid 142.931241 -225.683543)
		(end 143.045942 -225.550222)
		(width 0.0889)
		(layer "In11.Cu")
		(net "M_L_CPU1_SA_DQ<3>")
	)
	(arc
		(start 139.221718 -226.34194)
		(mid 139.504674 -226.418117)
		(end 139.78763 -226.34194)
		(width 0.0889)
		(layer "In11.Cu")
		(net "M_L_CPU1_SA_DQ<3>")
	)
	(arc
		(start 144.057878 -223.8883)
		(mid 144.235943 -223.686123)
		(end 144.300194 -223.424496)
		(width 0.0889)
		(layer "In11.Cu")
		(net "M_L_CPU1_SA_DQ<3>")
	)
	(arc
		(start 138.84783 -226.34194)
		(mid 139.034774 -226.291685)
		(end 139.221718 -226.34194)
		(width 0.0889)
		(layer "In11.Cu")
		(net "M_L_CPU1_SA_DQ<3>")
	)
	(arc
		(start 140.161772 -226.34194)
		(mid 140.444728 -226.418117)
		(end 140.727684 -226.34194)
		(width 0.0889)
		(layer "In11.Cu")
		(net "M_L_CPU1_SA_DQ<3>")
	)
	(arc
		(start 143.36014 -225.044508)
		(mid 143.401689 -224.873086)
		(end 143.517112 -224.739708)
		(width 0.0889)
		(layer "In11.Cu")
		(net "M_L_CPU1_SA_DQ<3>")
	)
	(arc
		(start 143.116808 -225.509074)
		(mid 143.295621 -225.306724)
		(end 143.36014 -225.044508)
		(width 0.0889)
		(layer "In11.Cu")
		(net "M_L_CPU1_SA_DQ<3>")
	)
	(arc
		(start 142.04188 -226.34194)
		(mid 142.324836 -226.418117)
		(end 142.607792 -226.34194)
		(width 0.0889)
		(layer "In11.Cu")
		(net "M_L_CPU1_SA_DQ<3>")
	)
	(arc
		(start 143.829786 -224.234502)
		(mid 143.871041 -224.063531)
		(end 143.985742 -223.93021)
		(width 0.0889)
		(layer "In11.Cu")
		(net "M_L_CPU1_SA_DQ<3>")
	)
	(arc
		(start 141.67612 -226.337114)
		(mid 141.859628 -226.29162)
		(end 142.04188 -226.34194)
		(width 0.0889)
		(layer "In11.Cu")
		(net "M_L_CPU1_SA_DQ<3>")
	)
	(arc
		(start 144.769586 -222.61449)
		(mid 144.810636 -222.44404)
		(end 144.92478 -222.31096)
		(width 0.0889)
		(layer "In11.Cu")
		(net "M_L_CPU1_SA_DQ<3>")
	)
	(arc
		(start 140.727684 -226.34194)
		(mid 140.909935 -226.29159)
		(end 141.093444 -226.337114)
		(width 0.0889)
		(layer "In11.Cu")
		(net "M_L_CPU1_SA_DQ<3>")
	)
	(arc
		(start 143.583914 -224.700846)
		(mid 143.764566 -224.498101)
		(end 143.829786 -224.234502)
		(width 0.0889)
		(layer "In11.Cu")
		(net "M_L_CPU1_SA_DQ<3>")
	)
	(arc
		(start 139.78763 -226.34194)
		(mid 139.969881 -226.29159)
		(end 140.15339 -226.337114)
		(width 0.0889)
		(layer "In11.Cu")
		(net "M_L_CPU1_SA_DQ<3>")
	)
	(arc
		(start 137.963148 -226.315778)
		(mid 138.12548 -226.29296)
		(end 138.281918 -226.34194)
		(width 0.0889)
		(layer "In11.Cu")
		(net "M_L_CPU1_SA_DQ<3>")
	)
	(arc
		(start 142.644114 -226.320858)
		(mid 142.824766 -226.118113)
		(end 142.889986 -225.854514)
		(width 0.0889)
		(layer "In11.Cu")
		(net "M_L_CPU1_SA_DQ<3>")
	)
	(segment
		(start 137.627868 -244.750336)
		(end 138.09472 -244.484398)
		(width 0.10668)
		(layer "F.Cu")
		(net "M_L_CPU1_SA_DQ<31>")
	)
	(segment
		(start 177.972466 -233.460544)
		(end 178.82235 -234.310428)
		(width 0.14478)
		(layer "In11.Cu")
		(net "M_L_CPU1_SA_DQ<31>")
	)
	(segment
		(start 161.187892 -237.511082)
		(end 161.188146 -237.306358)
		(width 0.14478)
		(layer "In11.Cu")
		(net "M_L_CPU1_SA_DQ<31>")
	)
	(segment
		(start 141.667738 -244.161818)
		(end 141.67612 -244.156992)
		(width 0.0889)
		(layer "In11.Cu")
		(net "M_L_CPU1_SA_DQ<31>")
	)
	(segment
		(start 192.695576 -233.460544)
		(end 193.54546 -234.310428)
		(width 0.14478)
		(layer "In11.Cu")
		(net "M_L_CPU1_SA_DQ<31>")
	)
	(segment
		(start 160.407858 -238.086646)
		(end 160.593278 -237.901226)
		(width 0.14478)
		(layer "In11.Cu")
		(net "M_L_CPU1_SA_DQ<31>")
	)
	(segment
		(start 196.892672 -233.460544)
		(end 199.147684 -233.460544)
		(width 0.14478)
		(layer "In11.Cu")
		(net "M_L_CPU1_SA_DQ<31>")
	)
	(segment
		(start 147.950682 -243.520214)
		(end 148.14423 -243.520214)
		(width 0.0889)
		(layer "In11.Cu")
		(net "M_L_CPU1_SA_DQ<31>")
	)
	(segment
		(start 160.688274 -238.776764)
		(end 160.688274 -238.57204)
		(width 0.14478)
		(layer "In11.Cu")
		(net "M_L_CPU1_SA_DQ<31>")
	)
	(segment
		(start 180.906928 -234.310428)
		(end 181.756812 -233.460544)
		(width 0.14478)
		(layer "In11.Cu")
		(net "M_L_CPU1_SA_DQ<31>")
	)
	(segment
		(start 164.191188 -234.310428)
		(end 165.591236 -234.310428)
		(width 0.14478)
		(layer "In11.Cu")
		(net "M_L_CPU1_SA_DQ<31>")
	)
	(segment
		(start 199.991218 -233.460544)
		(end 200.260712 -233.460544)
		(width 0.14478)
		(layer "In11.Cu")
		(net "M_L_CPU1_SA_DQ<31>")
	)
	(segment
		(start 160.798002 -237.901226)
		(end 161.078672 -238.181896)
		(width 0.14478)
		(layer "In11.Cu")
		(net "M_L_CPU1_SA_DQ<31>")
	)
	(segment
		(start 161.188146 -237.306358)
		(end 161.373566 -237.120938)
		(width 0.14478)
		(layer "In11.Cu")
		(net "M_L_CPU1_SA_DQ<31>")
	)
	(segment
		(start 163.93795 -234.563666)
		(end 164.191188 -234.310428)
		(width 0.14478)
		(layer "In11.Cu")
		(net "M_L_CPU1_SA_DQ<31>")
	)
	(segment
		(start 163.029138 -236.4359)
		(end 163.029138 -236.231176)
		(width 0.14478)
		(layer "In11.Cu")
		(net "M_L_CPU1_SA_DQ<31>")
	)
	(segment
		(start 188.673232 -234.310428)
		(end 189.523116 -233.460544)
		(width 0.14478)
		(layer "In11.Cu")
		(net "M_L_CPU1_SA_DQ<31>")
	)
	(segment
		(start 196.042788 -234.310428)
		(end 196.892672 -233.460544)
		(width 0.14478)
		(layer "In11.Cu")
		(net "M_L_CPU1_SA_DQ<31>")
	)
	(segment
		(start 162.843464 -236.621574)
		(end 163.029138 -236.4359)
		(width 0.14478)
		(layer "In11.Cu")
		(net "M_L_CPU1_SA_DQ<31>")
	)
	(segment
		(start 161.468562 -237.996476)
		(end 161.468562 -237.791752)
		(width 0.14478)
		(layer "In11.Cu")
		(net "M_L_CPU1_SA_DQ<31>")
	)
	(segment
		(start 147.233132 -244.237764)
		(end 147.950682 -243.520214)
		(width 0.0889)
		(layer "In11.Cu")
		(net "M_L_CPU1_SA_DQ<31>")
	)
	(segment
		(start 178.82235 -234.310428)
		(end 180.906928 -234.310428)
		(width 0.14478)
		(layer "In11.Cu")
		(net "M_L_CPU1_SA_DQ<31>")
	)
	(segment
		(start 200.260712 -233.460544)
		(end 200.547732 -233.747564)
		(width 0.14478)
		(layer "In11.Cu")
		(net "M_L_CPU1_SA_DQ<31>")
	)
	(segment
		(start 161.282888 -238.18215)
		(end 161.468562 -237.996476)
		(width 0.14478)
		(layer "In11.Cu")
		(net "M_L_CPU1_SA_DQ<31>")
	)
	(segment
		(start 163.623752 -235.841286)
		(end 163.93795 -235.527088)
		(width 0.14478)
		(layer "In11.Cu")
		(net "M_L_CPU1_SA_DQ<31>")
	)
	(segment
		(start 163.419536 -235.841032)
		(end 163.623752 -235.841286)
		(width 0.14478)
		(layer "In11.Cu")
		(net "M_L_CPU1_SA_DQ<31>")
	)
	(segment
		(start 148.14423 -243.520214)
		(end 155.944824 -243.520214)
		(width 0.14478)
		(layer "In11.Cu")
		(net "M_L_CPU1_SA_DQ<31>")
	)
	(segment
		(start 155.944824 -243.520214)
		(end 160.688274 -238.776764)
		(width 0.14478)
		(layer "In11.Cu")
		(net "M_L_CPU1_SA_DQ<31>")
	)
	(segment
		(start 161.373566 -237.120938)
		(end 161.57829 -237.120938)
		(width 0.14478)
		(layer "In11.Cu")
		(net "M_L_CPU1_SA_DQ<31>")
	)
	(segment
		(start 162.358578 -236.34065)
		(end 162.639248 -236.62132)
		(width 0.14478)
		(layer "In11.Cu")
		(net "M_L_CPU1_SA_DQ<31>")
	)
	(segment
		(start 162.639248 -236.62132)
		(end 162.843464 -236.621574)
		(width 0.14478)
		(layer "In11.Cu")
		(net "M_L_CPU1_SA_DQ<31>")
	)
	(segment
		(start 161.57829 -237.120938)
		(end 161.85896 -237.401608)
		(width 0.14478)
		(layer "In11.Cu")
		(net "M_L_CPU1_SA_DQ<31>")
	)
	(segment
		(start 199.704198 -233.747564)
		(end 199.991218 -233.460544)
		(width 0.14478)
		(layer "In11.Cu")
		(net "M_L_CPU1_SA_DQ<31>")
	)
	(segment
		(start 170.464734 -233.46029)
		(end 171.314872 -234.310428)
		(width 0.14478)
		(layer "In11.Cu")
		(net "M_L_CPU1_SA_DQ<31>")
	)
	(segment
		(start 193.54546 -234.310428)
		(end 196.042788 -234.310428)
		(width 0.14478)
		(layer "In11.Cu")
		(net "M_L_CPU1_SA_DQ<31>")
	)
	(segment
		(start 173.494192 -234.310428)
		(end 174.344076 -233.460544)
		(width 0.14478)
		(layer "In11.Cu")
		(net "M_L_CPU1_SA_DQ<31>")
	)
	(segment
		(start 160.593278 -237.901226)
		(end 160.798002 -237.901226)
		(width 0.14478)
		(layer "In11.Cu")
		(net "M_L_CPU1_SA_DQ<31>")
	)
	(segment
		(start 200.547732 -233.747564)
		(end 200.817226 -233.747564)
		(width 0.14478)
		(layer "In11.Cu")
		(net "M_L_CPU1_SA_DQ<31>")
	)
	(segment
		(start 186.10072 -234.310428)
		(end 188.673232 -234.310428)
		(width 0.14478)
		(layer "In11.Cu")
		(net "M_L_CPU1_SA_DQ<31>")
	)
	(segment
		(start 163.029138 -236.231176)
		(end 162.748468 -235.950506)
		(width 0.14478)
		(layer "In11.Cu")
		(net "M_L_CPU1_SA_DQ<31>")
	)
	(segment
		(start 181.756812 -233.460544)
		(end 185.250836 -233.460544)
		(width 0.14478)
		(layer "In11.Cu")
		(net "M_L_CPU1_SA_DQ<31>")
	)
	(segment
		(start 163.138866 -235.560362)
		(end 163.419536 -235.841032)
		(width 0.14478)
		(layer "In11.Cu")
		(net "M_L_CPU1_SA_DQ<31>")
	)
	(segment
		(start 144.47774 -244.167914)
		(end 144.488154 -244.161818)
		(width 0.0889)
		(layer "In11.Cu")
		(net "M_L_CPU1_SA_DQ<31>")
	)
	(segment
		(start 199.434704 -233.747564)
		(end 199.704198 -233.747564)
		(width 0.14478)
		(layer "In11.Cu")
		(net "M_L_CPU1_SA_DQ<31>")
	)
	(segment
		(start 163.93795 -235.527088)
		(end 163.93795 -234.563666)
		(width 0.14478)
		(layer "In11.Cu")
		(net "M_L_CPU1_SA_DQ<31>")
	)
	(segment
		(start 185.250836 -233.460544)
		(end 186.10072 -234.310428)
		(width 0.14478)
		(layer "In11.Cu")
		(net "M_L_CPU1_SA_DQ<31>")
	)
	(segment
		(start 162.748722 -235.745782)
		(end 162.934142 -235.560362)
		(width 0.14478)
		(layer "In11.Cu")
		(net "M_L_CPU1_SA_DQ<31>")
	)
	(segment
		(start 160.688274 -238.57204)
		(end 160.407604 -238.29137)
		(width 0.14478)
		(layer "In11.Cu")
		(net "M_L_CPU1_SA_DQ<31>")
	)
	(segment
		(start 162.934142 -235.560362)
		(end 163.138866 -235.560362)
		(width 0.14478)
		(layer "In11.Cu")
		(net "M_L_CPU1_SA_DQ<31>")
	)
	(segment
		(start 200.817226 -233.747564)
		(end 201.104246 -233.460544)
		(width 0.14478)
		(layer "In11.Cu")
		(net "M_L_CPU1_SA_DQ<31>")
	)
	(segment
		(start 162.24885 -237.011464)
		(end 161.96818 -236.730794)
		(width 0.14478)
		(layer "In11.Cu")
		(net "M_L_CPU1_SA_DQ<31>")
	)
	(segment
		(start 161.468562 -237.791752)
		(end 161.187892 -237.511082)
		(width 0.14478)
		(layer "In11.Cu")
		(net "M_L_CPU1_SA_DQ<31>")
	)
	(segment
		(start 161.078672 -238.181896)
		(end 161.282888 -238.18215)
		(width 0.14478)
		(layer "In11.Cu")
		(net "M_L_CPU1_SA_DQ<31>")
	)
	(segment
		(start 201.104246 -233.460544)
		(end 201.723244 -233.460544)
		(width 0.14478)
		(layer "In11.Cu")
		(net "M_L_CPU1_SA_DQ<31>")
	)
	(segment
		(start 174.344076 -233.460544)
		(end 177.972466 -233.460544)
		(width 0.14478)
		(layer "In11.Cu")
		(net "M_L_CPU1_SA_DQ<31>")
	)
	(segment
		(start 161.85896 -237.401608)
		(end 162.063176 -237.401862)
		(width 0.14478)
		(layer "In11.Cu")
		(net "M_L_CPU1_SA_DQ<31>")
	)
	(segment
		(start 162.748468 -235.950506)
		(end 162.748722 -235.745782)
		(width 0.14478)
		(layer "In11.Cu")
		(net "M_L_CPU1_SA_DQ<31>")
	)
	(segment
		(start 140.15339 -244.156992)
		(end 140.161772 -244.161818)
		(width 0.0889)
		(layer "In11.Cu")
		(net "M_L_CPU1_SA_DQ<31>")
	)
	(segment
		(start 165.591236 -234.310428)
		(end 166.441374 -233.46029)
		(width 0.14478)
		(layer "In11.Cu")
		(net "M_L_CPU1_SA_DQ<31>")
	)
	(segment
		(start 189.523116 -233.460544)
		(end 192.695576 -233.460544)
		(width 0.14478)
		(layer "In11.Cu")
		(net "M_L_CPU1_SA_DQ<31>")
	)
	(segment
		(start 162.153854 -236.34065)
		(end 162.358578 -236.34065)
		(width 0.14478)
		(layer "In11.Cu")
		(net "M_L_CPU1_SA_DQ<31>")
	)
	(segment
		(start 160.407604 -238.29137)
		(end 160.407858 -238.086646)
		(width 0.14478)
		(layer "In11.Cu")
		(net "M_L_CPU1_SA_DQ<31>")
	)
	(segment
		(start 145.144744 -244.237764)
		(end 147.233132 -244.237764)
		(width 0.0889)
		(layer "In11.Cu")
		(net "M_L_CPU1_SA_DQ<31>")
	)
	(segment
		(start 201.723244 -233.460544)
		(end 202.147932 -233.885232)
		(width 0.14478)
		(layer "In11.Cu")
		(net "M_L_CPU1_SA_DQ<31>")
	)
	(segment
		(start 199.147684 -233.460544)
		(end 199.434704 -233.747564)
		(width 0.14478)
		(layer "In11.Cu")
		(net "M_L_CPU1_SA_DQ<31>")
	)
	(segment
		(start 141.093444 -244.156992)
		(end 141.101826 -244.161818)
		(width 0.0889)
		(layer "In11.Cu")
		(net "M_L_CPU1_SA_DQ<31>")
	)
	(segment
		(start 138.09472 -244.484398)
		(end 137.940796 -244.218968)
		(width 0.0889)
		(layer "In11.Cu")
		(net "M_L_CPU1_SA_DQ<31>")
	)
	(segment
		(start 161.968434 -236.52607)
		(end 162.153854 -236.34065)
		(width 0.14478)
		(layer "In11.Cu")
		(net "M_L_CPU1_SA_DQ<31>")
	)
	(segment
		(start 166.441374 -233.46029)
		(end 170.464734 -233.46029)
		(width 0.14478)
		(layer "In11.Cu")
		(net "M_L_CPU1_SA_DQ<31>")
	)
	(segment
		(start 162.24885 -237.216188)
		(end 162.24885 -237.011464)
		(width 0.14478)
		(layer "In11.Cu")
		(net "M_L_CPU1_SA_DQ<31>")
	)
	(segment
		(start 161.96818 -236.730794)
		(end 161.968434 -236.52607)
		(width 0.14478)
		(layer "In11.Cu")
		(net "M_L_CPU1_SA_DQ<31>")
	)
	(segment
		(start 171.314872 -234.310428)
		(end 173.494192 -234.310428)
		(width 0.14478)
		(layer "In11.Cu")
		(net "M_L_CPU1_SA_DQ<31>")
	)
	(segment
		(start 137.940796 -244.218968)
		(end 137.963148 -244.135656)
		(width 0.0889)
		(layer "In11.Cu")
		(net "M_L_CPU1_SA_DQ<31>")
	)
	(segment
		(start 162.063176 -237.401862)
		(end 162.24885 -237.216188)
		(width 0.14478)
		(layer "In11.Cu")
		(net "M_L_CPU1_SA_DQ<31>")
	)
	(arc
		(start 144.862042 -244.161818)
		(mid 144.998376 -244.218461)
		(end 145.144744 -244.237764)
		(width 0.0889)
		(layer "In11.Cu")
		(net "M_L_CPU1_SA_DQ<31>")
	)
	(arc
		(start 139.78763 -244.161818)
		(mid 139.969881 -244.111468)
		(end 140.15339 -244.156992)
		(width 0.0889)
		(layer "In11.Cu")
		(net "M_L_CPU1_SA_DQ<31>")
	)
	(arc
		(start 144.488154 -244.161818)
		(mid 144.675098 -244.111563)
		(end 144.862042 -244.161818)
		(width 0.0889)
		(layer "In11.Cu")
		(net "M_L_CPU1_SA_DQ<31>")
	)
	(arc
		(start 140.727684 -244.161818)
		(mid 140.909935 -244.111468)
		(end 141.093444 -244.156992)
		(width 0.0889)
		(layer "In11.Cu")
		(net "M_L_CPU1_SA_DQ<31>")
	)
	(arc
		(start 139.221718 -244.161818)
		(mid 139.504674 -244.237995)
		(end 139.78763 -244.161818)
		(width 0.0889)
		(layer "In11.Cu")
		(net "M_L_CPU1_SA_DQ<31>")
	)
	(arc
		(start 142.607792 -244.161818)
		(mid 142.794736 -244.111563)
		(end 142.98168 -244.161818)
		(width 0.0889)
		(layer "In11.Cu")
		(net "M_L_CPU1_SA_DQ<31>")
	)
	(arc
		(start 140.161772 -244.161818)
		(mid 140.444728 -244.237995)
		(end 140.727684 -244.161818)
		(width 0.0889)
		(layer "In11.Cu")
		(net "M_L_CPU1_SA_DQ<31>")
	)
	(arc
		(start 142.04188 -244.161818)
		(mid 142.324836 -244.237995)
		(end 142.607792 -244.161818)
		(width 0.0889)
		(layer "In11.Cu")
		(net "M_L_CPU1_SA_DQ<31>")
	)
	(arc
		(start 143.921988 -244.161818)
		(mid 144.199055 -244.238089)
		(end 144.47774 -244.167914)
		(width 0.0889)
		(layer "In11.Cu")
		(net "M_L_CPU1_SA_DQ<31>")
	)
	(arc
		(start 138.281918 -244.161818)
		(mid 138.564874 -244.237995)
		(end 138.84783 -244.161818)
		(width 0.0889)
		(layer "In11.Cu")
		(net "M_L_CPU1_SA_DQ<31>")
	)
	(arc
		(start 142.98168 -244.161818)
		(mid 143.264636 -244.237995)
		(end 143.547592 -244.161818)
		(width 0.0889)
		(layer "In11.Cu")
		(net "M_L_CPU1_SA_DQ<31>")
	)
	(arc
		(start 143.547592 -244.161818)
		(mid 143.73479 -244.111436)
		(end 143.921988 -244.161818)
		(width 0.0889)
		(layer "In11.Cu")
		(net "M_L_CPU1_SA_DQ<31>")
	)
	(arc
		(start 141.101826 -244.161818)
		(mid 141.384782 -244.237995)
		(end 141.667738 -244.161818)
		(width 0.0889)
		(layer "In11.Cu")
		(net "M_L_CPU1_SA_DQ<31>")
	)
	(arc
		(start 138.84783 -244.161818)
		(mid 139.034774 -244.111563)
		(end 139.221718 -244.161818)
		(width 0.0889)
		(layer "In11.Cu")
		(net "M_L_CPU1_SA_DQ<31>")
	)
	(arc
		(start 141.67612 -244.156992)
		(mid 141.859628 -244.111498)
		(end 142.04188 -244.161818)
		(width 0.0889)
		(layer "In11.Cu")
		(net "M_L_CPU1_SA_DQ<31>")
	)
	(arc
		(start 137.963148 -244.135656)
		(mid 138.12548 -244.112838)
		(end 138.281918 -244.161818)
		(width 0.0889)
		(layer "In11.Cu")
		(net "M_L_CPU1_SA_DQ<31>")
	)
	(segment
		(start 139.037822 -243.94033)
		(end 139.504674 -243.674392)
		(width 0.10668)
		(layer "F.Cu")
		(net "M_L_CPU1_SA_DQ<30>")
	)
	(segment
		(start 182.434738 -231.520746)
		(end 182.579518 -231.375966)
		(width 0.14478)
		(layer "In11.Cu")
		(net "M_L_CPU1_SA_DQ<30>")
	)
	(segment
		(start 164.261546 -232.610406)
		(end 165.947852 -232.610406)
		(width 0.14478)
		(layer "In11.Cu")
		(net "M_L_CPU1_SA_DQ<30>")
	)
	(segment
		(start 200.09231 -231.977438)
		(end 200.23709 -232.122218)
		(width 0.14478)
		(layer "In11.Cu")
		(net "M_L_CPU1_SA_DQ<30>")
	)
	(segment
		(start 191.777366 -231.383586)
		(end 192.03924 -231.383586)
		(width 0.14478)
		(layer "In11.Cu")
		(net "M_L_CPU1_SA_DQ<30>")
	)
	(segment
		(start 184.037732 -231.760522)
		(end 184.182512 -231.615742)
		(width 0.14478)
		(layer "In11.Cu")
		(net "M_L_CPU1_SA_DQ<30>")
	)
	(segment
		(start 182.434738 -231.615742)
		(end 182.434738 -231.520746)
		(width 0.14478)
		(layer "In11.Cu")
		(net "M_L_CPU1_SA_DQ<30>")
	)
	(segment
		(start 184.878726 -231.760522)
		(end 185.250836 -231.760522)
		(width 0.14478)
		(layer "In11.Cu")
		(net "M_L_CPU1_SA_DQ<30>")
	)
	(segment
		(start 201.723244 -231.760522)
		(end 202.147932 -232.18521)
		(width 0.14478)
		(layer "In11.Cu")
		(net "M_L_CPU1_SA_DQ<30>")
	)
	(segment
		(start 188.673232 -232.610406)
		(end 189.523116 -231.760522)
		(width 0.14478)
		(layer "In11.Cu")
		(net "M_L_CPU1_SA_DQ<30>")
	)
	(segment
		(start 201.050398 -231.398826)
		(end 201.195178 -231.543606)
		(width 0.14478)
		(layer "In11.Cu")
		(net "M_L_CPU1_SA_DQ<30>")
	)
	(segment
		(start 169.266108 -231.905048)
		(end 169.266108 -232.000806)
		(width 0.14478)
		(layer "In11.Cu")
		(net "M_L_CPU1_SA_DQ<30>")
	)
	(segment
		(start 190.421006 -231.370886)
		(end 190.565786 -231.515666)
		(width 0.14478)
		(layer "In11.Cu")
		(net "M_L_CPU1_SA_DQ<30>")
	)
	(segment
		(start 183.130952 -231.760522)
		(end 184.037732 -231.760522)
		(width 0.14478)
		(layer "In11.Cu")
		(net "M_L_CPU1_SA_DQ<30>")
	)
	(segment
		(start 176.909222 -231.760522)
		(end 177.054002 -231.615742)
		(width 0.14478)
		(layer "In11.Cu")
		(net "M_L_CPU1_SA_DQ<30>")
	)
	(segment
		(start 182.986172 -231.615742)
		(end 183.130952 -231.760522)
		(width 0.14478)
		(layer "In11.Cu")
		(net "M_L_CPU1_SA_DQ<30>")
	)
	(segment
		(start 199.540876 -231.615742)
		(end 199.540876 -231.543606)
		(width 0.14478)
		(layer "In11.Cu")
		(net "M_L_CPU1_SA_DQ<30>")
	)
	(segment
		(start 199.396096 -231.760522)
		(end 199.540876 -231.615742)
		(width 0.14478)
		(layer "In11.Cu")
		(net "M_L_CPU1_SA_DQ<30>")
	)
	(segment
		(start 184.733946 -231.615742)
		(end 184.878726 -231.760522)
		(width 0.14478)
		(layer "In11.Cu")
		(net "M_L_CPU1_SA_DQ<30>")
	)
	(segment
		(start 191.632586 -231.615742)
		(end 191.632586 -231.528366)
		(width 0.14478)
		(layer "In11.Cu")
		(net "M_L_CPU1_SA_DQ<30>")
	)
	(segment
		(start 159.413956 -238.764572)
		(end 159.413956 -237.457996)
		(width 0.14478)
		(layer "In11.Cu")
		(net "M_L_CPU1_SA_DQ<30>")
	)
	(segment
		(start 184.182512 -231.515666)
		(end 184.327292 -231.370886)
		(width 0.14478)
		(layer "In11.Cu")
		(net "M_L_CPU1_SA_DQ<30>")
	)
	(segment
		(start 166.79799 -231.760268)
		(end 169.121328 -231.760268)
		(width 0.14478)
		(layer "In11.Cu")
		(net "M_L_CPU1_SA_DQ<30>")
	)
	(segment
		(start 169.817542 -231.905048)
		(end 169.962322 -231.760268)
		(width 0.14478)
		(layer "In11.Cu")
		(net "M_L_CPU1_SA_DQ<30>")
	)
	(segment
		(start 200.09231 -231.543606)
		(end 200.09231 -231.977438)
		(width 0.14478)
		(layer "In11.Cu")
		(net "M_L_CPU1_SA_DQ<30>")
	)
	(segment
		(start 177.605436 -231.533446)
		(end 177.605436 -231.615742)
		(width 0.14478)
		(layer "In11.Cu")
		(net "M_L_CPU1_SA_DQ<30>")
	)
	(segment
		(start 190.014352 -231.615742)
		(end 190.014352 -231.515666)
		(width 0.14478)
		(layer "In11.Cu")
		(net "M_L_CPU1_SA_DQ<30>")
	)
	(segment
		(start 181.065424 -232.610406)
		(end 181.915308 -231.760522)
		(width 0.14478)
		(layer "In11.Cu")
		(net "M_L_CPU1_SA_DQ<30>")
	)
	(segment
		(start 182.579518 -231.375966)
		(end 182.841392 -231.375966)
		(width 0.14478)
		(layer "In11.Cu")
		(net "M_L_CPU1_SA_DQ<30>")
	)
	(segment
		(start 169.672762 -232.145586)
		(end 169.817542 -232.000806)
		(width 0.14478)
		(layer "In11.Cu")
		(net "M_L_CPU1_SA_DQ<30>")
	)
	(segment
		(start 182.841392 -231.375966)
		(end 182.986172 -231.520746)
		(width 0.14478)
		(layer "In11.Cu")
		(net "M_L_CPU1_SA_DQ<30>")
	)
	(segment
		(start 144.005046 -243.358924)
		(end 144.016984 -243.352066)
		(width 0.0889)
		(layer "In11.Cu")
		(net "M_L_CPU1_SA_DQ<30>")
	)
	(segment
		(start 190.710566 -231.760522)
		(end 191.487806 -231.760522)
		(width 0.14478)
		(layer "In11.Cu")
		(net "M_L_CPU1_SA_DQ<30>")
	)
	(segment
		(start 147.42795 -243.275866)
		(end 147.42795 -242.892834)
		(width 0.0889)
		(layer "In11.Cu")
		(net "M_L_CPU1_SA_DQ<30>")
	)
	(segment
		(start 169.410888 -232.145586)
		(end 169.672762 -232.145586)
		(width 0.14478)
		(layer "In11.Cu")
		(net "M_L_CPU1_SA_DQ<30>")
	)
	(segment
		(start 155.567634 -242.610894)
		(end 159.413956 -238.764572)
		(width 0.14478)
		(layer "In11.Cu")
		(net "M_L_CPU1_SA_DQ<30>")
	)
	(segment
		(start 196.262752 -232.610406)
		(end 197.112636 -231.760522)
		(width 0.14478)
		(layer "In11.Cu")
		(net "M_L_CPU1_SA_DQ<30>")
	)
	(segment
		(start 200.23709 -232.122218)
		(end 200.498964 -232.122218)
		(width 0.14478)
		(layer "In11.Cu")
		(net "M_L_CPU1_SA_DQ<30>")
	)
	(segment
		(start 199.540876 -231.543606)
		(end 199.685656 -231.398826)
		(width 0.14478)
		(layer "In11.Cu")
		(net "M_L_CPU1_SA_DQ<30>")
	)
	(segment
		(start 146.31797 -243.783866)
		(end 146.91995 -243.783866)
		(width 0.0889)
		(layer "In11.Cu")
		(net "M_L_CPU1_SA_DQ<30>")
	)
	(segment
		(start 173.506384 -232.610406)
		(end 174.356268 -231.760522)
		(width 0.14478)
		(layer "In11.Cu")
		(net "M_L_CPU1_SA_DQ<30>")
	)
	(segment
		(start 174.995586 -231.381046)
		(end 175.25746 -231.381046)
		(width 0.14478)
		(layer "In11.Cu")
		(net "M_L_CPU1_SA_DQ<30>")
	)
	(segment
		(start 174.706026 -231.760522)
		(end 174.850806 -231.615742)
		(width 0.14478)
		(layer "In11.Cu")
		(net "M_L_CPU1_SA_DQ<30>")
	)
	(segment
		(start 169.266108 -232.000806)
		(end 169.410888 -232.145586)
		(width 0.14478)
		(layer "In11.Cu")
		(net "M_L_CPU1_SA_DQ<30>")
	)
	(segment
		(start 182.289958 -231.760522)
		(end 182.434738 -231.615742)
		(width 0.14478)
		(layer "In11.Cu")
		(net "M_L_CPU1_SA_DQ<30>")
	)
	(segment
		(start 143.077692 -243.351812)
		(end 143.086074 -243.346986)
		(width 0.0889)
		(layer "In11.Cu")
		(net "M_L_CPU1_SA_DQ<30>")
	)
	(segment
		(start 200.498964 -232.122218)
		(end 200.643744 -231.977438)
		(width 0.14478)
		(layer "In11.Cu")
		(net "M_L_CPU1_SA_DQ<30>")
	)
	(segment
		(start 147.42795 -242.892834)
		(end 147.70989 -242.610894)
		(width 0.0889)
		(layer "In11.Cu")
		(net "M_L_CPU1_SA_DQ<30>")
	)
	(segment
		(start 181.915308 -231.760522)
		(end 182.289958 -231.760522)
		(width 0.14478)
		(layer "In11.Cu")
		(net "M_L_CPU1_SA_DQ<30>")
	)
	(segment
		(start 184.327292 -231.370886)
		(end 184.589166 -231.370886)
		(width 0.14478)
		(layer "In11.Cu")
		(net "M_L_CPU1_SA_DQ<30>")
	)
	(segment
		(start 197.112636 -231.760522)
		(end 199.396096 -231.760522)
		(width 0.14478)
		(layer "In11.Cu")
		(net "M_L_CPU1_SA_DQ<30>")
	)
	(segment
		(start 145.835116 -243.301012)
		(end 146.31797 -243.783866)
		(width 0.0889)
		(layer "In11.Cu")
		(net "M_L_CPU1_SA_DQ<30>")
	)
	(segment
		(start 174.850806 -231.615742)
		(end 174.850806 -231.525826)
		(width 0.14478)
		(layer "In11.Cu")
		(net "M_L_CPU1_SA_DQ<30>")
	)
	(segment
		(start 191.632586 -231.528366)
		(end 191.777366 -231.383586)
		(width 0.14478)
		(layer "In11.Cu")
		(net "M_L_CPU1_SA_DQ<30>")
	)
	(segment
		(start 184.182512 -231.615742)
		(end 184.182512 -231.515666)
		(width 0.14478)
		(layer "In11.Cu")
		(net "M_L_CPU1_SA_DQ<30>")
	)
	(segment
		(start 201.339958 -231.760522)
		(end 201.723244 -231.760522)
		(width 0.14478)
		(layer "In11.Cu")
		(net "M_L_CPU1_SA_DQ<30>")
	)
	(segment
		(start 170.285918 -231.760268)
		(end 171.136056 -232.610406)
		(width 0.14478)
		(layer "In11.Cu")
		(net "M_L_CPU1_SA_DQ<30>")
	)
	(segment
		(start 140.257784 -243.351812)
		(end 140.266166 -243.346986)
		(width 0.0889)
		(layer "In11.Cu")
		(net "M_L_CPU1_SA_DQ<30>")
	)
	(segment
		(start 178.82235 -232.610406)
		(end 181.065424 -232.610406)
		(width 0.14478)
		(layer "In11.Cu")
		(net "M_L_CPU1_SA_DQ<30>")
	)
	(segment
		(start 192.18402 -231.615742)
		(end 192.3288 -231.760522)
		(width 0.14478)
		(layer "In11.Cu")
		(net "M_L_CPU1_SA_DQ<30>")
	)
	(segment
		(start 177.750216 -231.760522)
		(end 177.972466 -231.760522)
		(width 0.14478)
		(layer "In11.Cu")
		(net "M_L_CPU1_SA_DQ<30>")
	)
	(segment
		(start 191.487806 -231.760522)
		(end 191.632586 -231.615742)
		(width 0.14478)
		(layer "In11.Cu")
		(net "M_L_CPU1_SA_DQ<30>")
	)
	(segment
		(start 201.195178 -231.615742)
		(end 201.339958 -231.760522)
		(width 0.14478)
		(layer "In11.Cu")
		(net "M_L_CPU1_SA_DQ<30>")
	)
	(segment
		(start 199.685656 -231.398826)
		(end 199.94753 -231.398826)
		(width 0.14478)
		(layer "In11.Cu")
		(net "M_L_CPU1_SA_DQ<30>")
	)
	(segment
		(start 190.565786 -231.515666)
		(end 190.565786 -231.615742)
		(width 0.14478)
		(layer "In11.Cu")
		(net "M_L_CPU1_SA_DQ<30>")
	)
	(segment
		(start 192.03924 -231.383586)
		(end 192.18402 -231.528366)
		(width 0.14478)
		(layer "In11.Cu")
		(net "M_L_CPU1_SA_DQ<30>")
	)
	(segment
		(start 175.40224 -231.615742)
		(end 175.54702 -231.760522)
		(width 0.14478)
		(layer "In11.Cu")
		(net "M_L_CPU1_SA_DQ<30>")
	)
	(segment
		(start 199.94753 -231.398826)
		(end 200.09231 -231.543606)
		(width 0.14478)
		(layer "In11.Cu")
		(net "M_L_CPU1_SA_DQ<30>")
	)
	(segment
		(start 175.25746 -231.381046)
		(end 175.40224 -231.525826)
		(width 0.14478)
		(layer "In11.Cu")
		(net "M_L_CPU1_SA_DQ<30>")
	)
	(segment
		(start 177.198782 -231.388666)
		(end 177.460656 -231.388666)
		(width 0.14478)
		(layer "In11.Cu")
		(net "M_L_CPU1_SA_DQ<30>")
	)
	(segment
		(start 200.643744 -231.977438)
		(end 200.643744 -231.543606)
		(width 0.14478)
		(layer "In11.Cu")
		(net "M_L_CPU1_SA_DQ<30>")
	)
	(segment
		(start 171.136056 -232.610406)
		(end 173.506384 -232.610406)
		(width 0.14478)
		(layer "In11.Cu")
		(net "M_L_CPU1_SA_DQ<30>")
	)
	(segment
		(start 169.817542 -232.000806)
		(end 169.817542 -231.905048)
		(width 0.14478)
		(layer "In11.Cu")
		(net "M_L_CPU1_SA_DQ<30>")
	)
	(segment
		(start 200.788524 -231.398826)
		(end 201.050398 -231.398826)
		(width 0.14478)
		(layer "In11.Cu")
		(net "M_L_CPU1_SA_DQ<30>")
	)
	(segment
		(start 169.962322 -231.760268)
		(end 170.285918 -231.760268)
		(width 0.14478)
		(layer "In11.Cu")
		(net "M_L_CPU1_SA_DQ<30>")
	)
	(segment
		(start 165.947852 -232.610406)
		(end 166.79799 -231.760268)
		(width 0.14478)
		(layer "In11.Cu")
		(net "M_L_CPU1_SA_DQ<30>")
	)
	(segment
		(start 169.121328 -231.760268)
		(end 169.266108 -231.905048)
		(width 0.14478)
		(layer "In11.Cu")
		(net "M_L_CPU1_SA_DQ<30>")
	)
	(segment
		(start 200.643744 -231.543606)
		(end 200.788524 -231.398826)
		(width 0.14478)
		(layer "In11.Cu")
		(net "M_L_CPU1_SA_DQ<30>")
	)
	(segment
		(start 174.850806 -231.525826)
		(end 174.995586 -231.381046)
		(width 0.14478)
		(layer "In11.Cu")
		(net "M_L_CPU1_SA_DQ<30>")
	)
	(segment
		(start 190.014352 -231.515666)
		(end 190.159132 -231.370886)
		(width 0.14478)
		(layer "In11.Cu")
		(net "M_L_CPU1_SA_DQ<30>")
	)
	(segment
		(start 189.523116 -231.760522)
		(end 189.869572 -231.760522)
		(width 0.14478)
		(layer "In11.Cu")
		(net "M_L_CPU1_SA_DQ<30>")
	)
	(segment
		(start 142.503398 -243.346986)
		(end 142.51178 -243.351812)
		(width 0.0889)
		(layer "In11.Cu")
		(net "M_L_CPU1_SA_DQ<30>")
	)
	(segment
		(start 177.054002 -231.615742)
		(end 177.054002 -231.533446)
		(width 0.14478)
		(layer "In11.Cu")
		(net "M_L_CPU1_SA_DQ<30>")
	)
	(segment
		(start 192.18402 -231.528366)
		(end 192.18402 -231.615742)
		(width 0.14478)
		(layer "In11.Cu")
		(net "M_L_CPU1_SA_DQ<30>")
	)
	(segment
		(start 184.589166 -231.370886)
		(end 184.733946 -231.515666)
		(width 0.14478)
		(layer "In11.Cu")
		(net "M_L_CPU1_SA_DQ<30>")
	)
	(segment
		(start 148.022818 -242.610894)
		(end 155.567634 -242.610894)
		(width 0.14478)
		(layer "In11.Cu")
		(net "M_L_CPU1_SA_DQ<30>")
	)
	(segment
		(start 190.159132 -231.370886)
		(end 190.421006 -231.370886)
		(width 0.14478)
		(layer "In11.Cu")
		(net "M_L_CPU1_SA_DQ<30>")
	)
	(segment
		(start 139.504674 -243.674392)
		(end 139.35075 -243.408962)
		(width 0.0889)
		(layer "In11.Cu")
		(net "M_L_CPU1_SA_DQ<30>")
	)
	(segment
		(start 147.70989 -242.610894)
		(end 148.022818 -242.610894)
		(width 0.0889)
		(layer "In11.Cu")
		(net "M_L_CPU1_SA_DQ<30>")
	)
	(segment
		(start 145.144744 -243.301012)
		(end 145.835116 -243.301012)
		(width 0.0889)
		(layer "In11.Cu")
		(net "M_L_CPU1_SA_DQ<30>")
	)
	(segment
		(start 177.972466 -231.760522)
		(end 178.82235 -232.610406)
		(width 0.14478)
		(layer "In11.Cu")
		(net "M_L_CPU1_SA_DQ<30>")
	)
	(segment
		(start 144.390618 -243.351812)
		(end 144.408652 -243.36248)
		(width 0.0889)
		(layer "In11.Cu")
		(net "M_L_CPU1_SA_DQ<30>")
	)
	(segment
		(start 159.413956 -237.457996)
		(end 164.261546 -232.610406)
		(width 0.14478)
		(layer "In11.Cu")
		(net "M_L_CPU1_SA_DQ<30>")
	)
	(segment
		(start 192.3288 -231.760522)
		(end 192.59804 -231.760522)
		(width 0.14478)
		(layer "In11.Cu")
		(net "M_L_CPU1_SA_DQ<30>")
	)
	(segment
		(start 146.91995 -243.783866)
		(end 147.42795 -243.275866)
		(width 0.0889)
		(layer "In11.Cu")
		(net "M_L_CPU1_SA_DQ<30>")
	)
	(segment
		(start 186.10072 -232.610406)
		(end 188.673232 -232.610406)
		(width 0.14478)
		(layer "In11.Cu")
		(net "M_L_CPU1_SA_DQ<30>")
	)
	(segment
		(start 175.54702 -231.760522)
		(end 176.909222 -231.760522)
		(width 0.14478)
		(layer "In11.Cu")
		(net "M_L_CPU1_SA_DQ<30>")
	)
	(segment
		(start 175.40224 -231.525826)
		(end 175.40224 -231.615742)
		(width 0.14478)
		(layer "In11.Cu")
		(net "M_L_CPU1_SA_DQ<30>")
	)
	(segment
		(start 177.460656 -231.388666)
		(end 177.605436 -231.533446)
		(width 0.14478)
		(layer "In11.Cu")
		(net "M_L_CPU1_SA_DQ<30>")
	)
	(segment
		(start 139.35075 -243.408962)
		(end 139.373102 -243.32565)
		(width 0.0889)
		(layer "In11.Cu")
		(net "M_L_CPU1_SA_DQ<30>")
	)
	(segment
		(start 185.250836 -231.760522)
		(end 186.10072 -232.610406)
		(width 0.14478)
		(layer "In11.Cu")
		(net "M_L_CPU1_SA_DQ<30>")
	)
	(segment
		(start 193.447924 -232.610406)
		(end 196.262752 -232.610406)
		(width 0.14478)
		(layer "In11.Cu")
		(net "M_L_CPU1_SA_DQ<30>")
	)
	(segment
		(start 144.016984 -243.352066)
		(end 144.0307 -243.344192)
		(width 0.0889)
		(layer "In11.Cu")
		(net "M_L_CPU1_SA_DQ<30>")
	)
	(segment
		(start 192.59804 -231.760522)
		(end 193.447924 -232.610406)
		(width 0.14478)
		(layer "In11.Cu")
		(net "M_L_CPU1_SA_DQ<30>")
	)
	(segment
		(start 184.733946 -231.515666)
		(end 184.733946 -231.615742)
		(width 0.14478)
		(layer "In11.Cu")
		(net "M_L_CPU1_SA_DQ<30>")
	)
	(segment
		(start 190.565786 -231.615742)
		(end 190.710566 -231.760522)
		(width 0.14478)
		(layer "In11.Cu")
		(net "M_L_CPU1_SA_DQ<30>")
	)
	(segment
		(start 174.356268 -231.760522)
		(end 174.706026 -231.760522)
		(width 0.14478)
		(layer "In11.Cu")
		(net "M_L_CPU1_SA_DQ<30>")
	)
	(segment
		(start 189.869572 -231.760522)
		(end 190.014352 -231.615742)
		(width 0.14478)
		(layer "In11.Cu")
		(net "M_L_CPU1_SA_DQ<30>")
	)
	(segment
		(start 177.605436 -231.615742)
		(end 177.750216 -231.760522)
		(width 0.14478)
		(layer "In11.Cu")
		(net "M_L_CPU1_SA_DQ<30>")
	)
	(segment
		(start 177.054002 -231.533446)
		(end 177.198782 -231.388666)
		(width 0.14478)
		(layer "In11.Cu")
		(net "M_L_CPU1_SA_DQ<30>")
	)
	(segment
		(start 182.986172 -231.520746)
		(end 182.986172 -231.615742)
		(width 0.14478)
		(layer "In11.Cu")
		(net "M_L_CPU1_SA_DQ<30>")
	)
	(segment
		(start 201.195178 -231.543606)
		(end 201.195178 -231.615742)
		(width 0.14478)
		(layer "In11.Cu")
		(net "M_L_CPU1_SA_DQ<30>")
	)
	(arc
		(start 140.631926 -243.351812)
		(mid 140.914882 -243.427989)
		(end 141.197838 -243.351812)
		(width 0.0889)
		(layer "In11.Cu")
		(net "M_L_CPU1_SA_DQ<30>")
	)
	(arc
		(start 142.51178 -243.351812)
		(mid 142.794736 -243.427989)
		(end 143.077692 -243.351812)
		(width 0.0889)
		(layer "In11.Cu")
		(net "M_L_CPU1_SA_DQ<30>")
	)
	(arc
		(start 139.691872 -243.351812)
		(mid 139.974828 -243.427989)
		(end 140.257784 -243.351812)
		(width 0.0889)
		(layer "In11.Cu")
		(net "M_L_CPU1_SA_DQ<30>")
	)
	(arc
		(start 143.451834 -243.351812)
		(mid 143.727512 -243.427942)
		(end 144.005046 -243.358924)
		(width 0.0889)
		(layer "In11.Cu")
		(net "M_L_CPU1_SA_DQ<30>")
	)
	(arc
		(start 144.408652 -243.36248)
		(mid 144.684347 -243.428323)
		(end 144.957292 -243.351812)
		(width 0.0889)
		(layer "In11.Cu")
		(net "M_L_CPU1_SA_DQ<30>")
	)
	(arc
		(start 141.197838 -243.351812)
		(mid 141.384782 -243.301557)
		(end 141.571726 -243.351812)
		(width 0.0889)
		(layer "In11.Cu")
		(net "M_L_CPU1_SA_DQ<30>")
	)
	(arc
		(start 142.137638 -243.351812)
		(mid 142.319889 -243.301462)
		(end 142.503398 -243.346986)
		(width 0.0889)
		(layer "In11.Cu")
		(net "M_L_CPU1_SA_DQ<30>")
	)
	(arc
		(start 144.957292 -243.351812)
		(mid 145.047655 -243.314002)
		(end 145.144744 -243.301012)
		(width 0.0889)
		(layer "In11.Cu")
		(net "M_L_CPU1_SA_DQ<30>")
	)
	(arc
		(start 141.571726 -243.351812)
		(mid 141.854682 -243.427989)
		(end 142.137638 -243.351812)
		(width 0.0889)
		(layer "In11.Cu")
		(net "M_L_CPU1_SA_DQ<30>")
	)
	(arc
		(start 144.0307 -243.344192)
		(mid 144.21163 -243.301714)
		(end 144.390618 -243.351812)
		(width 0.0889)
		(layer "In11.Cu")
		(net "M_L_CPU1_SA_DQ<30>")
	)
	(arc
		(start 140.266166 -243.346986)
		(mid 140.449674 -243.301492)
		(end 140.631926 -243.351812)
		(width 0.0889)
		(layer "In11.Cu")
		(net "M_L_CPU1_SA_DQ<30>")
	)
	(arc
		(start 143.086074 -243.346986)
		(mid 143.269582 -243.301492)
		(end 143.451834 -243.351812)
		(width 0.0889)
		(layer "In11.Cu")
		(net "M_L_CPU1_SA_DQ<30>")
	)
	(arc
		(start 139.373102 -243.32565)
		(mid 139.535434 -243.302832)
		(end 139.691872 -243.351812)
		(width 0.0889)
		(layer "In11.Cu")
		(net "M_L_CPU1_SA_DQ<30>")
	)
	(segment
		(start 139.037822 -226.120452)
		(end 139.504674 -225.854514)
		(width 0.10668)
		(layer "F.Cu")
		(net "M_L_CPU1_SA_DQ<2>")
	)
	(segment
		(start 153.444956 -207.84439)
		(end 153.271474 -207.670908)
		(width 0.14478)
		(layer "In11.Cu")
		(net "M_L_CPU1_SA_DQ<2>")
	)
	(segment
		(start 153.281888 -208.23809)
		(end 153.444956 -208.075022)
		(width 0.14478)
		(layer "In11.Cu")
		(net "M_L_CPU1_SA_DQ<2>")
	)
	(segment
		(start 154.856688 -206.66329)
		(end 155.019756 -206.500222)
		(width 0.14478)
		(layer "In11.Cu")
		(net "M_L_CPU1_SA_DQ<2>")
	)
	(segment
		(start 152.647142 -208.064608)
		(end 152.877774 -208.064608)
		(width 0.14478)
		(layer "In11.Cu")
		(net "M_L_CPU1_SA_DQ<2>")
	)
	(segment
		(start 173.619668 -198.610474)
		(end 174.469552 -197.76059)
		(width 0.14478)
		(layer "In11.Cu")
		(net "M_L_CPU1_SA_DQ<2>")
	)
	(segment
		(start 180.987192 -198.610474)
		(end 181.837076 -197.76059)
		(width 0.14478)
		(layer "In11.Cu")
		(net "M_L_CPU1_SA_DQ<2>")
	)
	(segment
		(start 196.810884 -197.76059)
		(end 200.171558 -197.76059)
		(width 0.14478)
		(layer "In11.Cu")
		(net "M_L_CPU1_SA_DQ<2>")
	)
	(segment
		(start 153.444956 -208.075022)
		(end 153.444956 -207.84439)
		(width 0.14478)
		(layer "In11.Cu")
		(net "M_L_CPU1_SA_DQ<2>")
	)
	(segment
		(start 143.517112 -223.119696)
		(end 143.547592 -223.101916)
		(width 0.0889)
		(layer "In11.Cu")
		(net "M_L_CPU1_SA_DQ<2>")
	)
	(segment
		(start 201.723244 -197.76059)
		(end 202.147932 -198.185278)
		(width 0.14478)
		(layer "In11.Cu")
		(net "M_L_CPU1_SA_DQ<2>")
	)
	(segment
		(start 152.657556 -208.63179)
		(end 152.484074 -208.458308)
		(width 0.14478)
		(layer "In11.Cu")
		(net "M_L_CPU1_SA_DQ<2>")
	)
	(segment
		(start 154.058874 -206.883508)
		(end 154.058874 -206.652876)
		(width 0.14478)
		(layer "In11.Cu")
		(net "M_L_CPU1_SA_DQ<2>")
	)
	(segment
		(start 155.796742 -204.915008)
		(end 156.027374 -204.915008)
		(width 0.14478)
		(layer "In11.Cu")
		(net "M_L_CPU1_SA_DQ<2>")
	)
	(segment
		(start 200.867772 -197.90537)
		(end 201.012552 -197.76059)
		(width 0.14478)
		(layer "In11.Cu")
		(net "M_L_CPU1_SA_DQ<2>")
	)
	(segment
		(start 200.461118 -198.160386)
		(end 200.722992 -198.160386)
		(width 0.14478)
		(layer "In11.Cu")
		(net "M_L_CPU1_SA_DQ<2>")
	)
	(segment
		(start 154.058874 -206.652876)
		(end 154.221942 -206.489808)
		(width 0.14478)
		(layer "In11.Cu")
		(net "M_L_CPU1_SA_DQ<2>")
	)
	(segment
		(start 153.838656 -207.45069)
		(end 154.069288 -207.45069)
		(width 0.14478)
		(layer "In11.Cu")
		(net "M_L_CPU1_SA_DQ<2>")
	)
	(segment
		(start 155.413456 -205.87589)
		(end 155.644088 -205.87589)
		(width 0.14478)
		(layer "In11.Cu")
		(net "M_L_CPU1_SA_DQ<2>")
	)
	(segment
		(start 177.972466 -197.76059)
		(end 178.82235 -198.610474)
		(width 0.14478)
		(layer "In11.Cu")
		(net "M_L_CPU1_SA_DQ<2>")
	)
	(segment
		(start 181.837076 -197.76059)
		(end 185.250836 -197.76059)
		(width 0.14478)
		(layer "In11.Cu")
		(net "M_L_CPU1_SA_DQ<2>")
	)
	(segment
		(start 152.484074 -208.227676)
		(end 152.647142 -208.064608)
		(width 0.14478)
		(layer "In11.Cu")
		(net "M_L_CPU1_SA_DQ<2>")
	)
	(segment
		(start 155.807156 -205.712822)
		(end 155.807156 -205.48219)
		(width 0.14478)
		(layer "In11.Cu")
		(net "M_L_CPU1_SA_DQ<2>")
	)
	(segment
		(start 188.673232 -198.610474)
		(end 189.523116 -197.76059)
		(width 0.14478)
		(layer "In11.Cu")
		(net "M_L_CPU1_SA_DQ<2>")
	)
	(segment
		(start 154.232356 -207.287622)
		(end 154.232356 -207.05699)
		(width 0.14478)
		(layer "In11.Cu")
		(net "M_L_CPU1_SA_DQ<2>")
	)
	(segment
		(start 143.045942 -223.93021)
		(end 143.077692 -223.911922)
		(width 0.0889)
		(layer "In11.Cu")
		(net "M_L_CPU1_SA_DQ<2>")
	)
	(segment
		(start 142.137638 -225.531934)
		(end 142.176754 -225.509074)
		(width 0.0889)
		(layer "In11.Cu")
		(net "M_L_CPU1_SA_DQ<2>")
	)
	(segment
		(start 201.012552 -197.76059)
		(end 201.723244 -197.76059)
		(width 0.14478)
		(layer "In11.Cu")
		(net "M_L_CPU1_SA_DQ<2>")
	)
	(segment
		(start 156.431488 -205.08849)
		(end 156.594556 -204.925422)
		(width 0.14478)
		(layer "In11.Cu")
		(net "M_L_CPU1_SA_DQ<2>")
	)
	(segment
		(start 154.221942 -206.489808)
		(end 154.452574 -206.489808)
		(width 0.14478)
		(layer "In11.Cu")
		(net "M_L_CPU1_SA_DQ<2>")
	)
	(segment
		(start 139.35075 -225.589084)
		(end 139.373102 -225.505772)
		(width 0.0889)
		(layer "In11.Cu")
		(net "M_L_CPU1_SA_DQ<2>")
	)
	(segment
		(start 153.271474 -207.440276)
		(end 153.434542 -207.277208)
		(width 0.14478)
		(layer "In11.Cu")
		(net "M_L_CPU1_SA_DQ<2>")
	)
	(segment
		(start 200.316338 -198.015606)
		(end 200.461118 -198.160386)
		(width 0.14478)
		(layer "In11.Cu")
		(net "M_L_CPU1_SA_DQ<2>")
	)
	(segment
		(start 178.82235 -198.610474)
		(end 180.987192 -198.610474)
		(width 0.14478)
		(layer "In11.Cu")
		(net "M_L_CPU1_SA_DQ<2>")
	)
	(segment
		(start 154.069288 -207.45069)
		(end 154.232356 -207.287622)
		(width 0.14478)
		(layer "In11.Cu")
		(net "M_L_CPU1_SA_DQ<2>")
	)
	(segment
		(start 144.52092 -221.201488)
		(end 144.52092 -216.999058)
		(width 0.14478)
		(layer "In11.Cu")
		(net "M_L_CPU1_SA_DQ<2>")
	)
	(segment
		(start 200.867772 -198.015606)
		(end 200.867772 -197.90537)
		(width 0.14478)
		(layer "In11.Cu")
		(net "M_L_CPU1_SA_DQ<2>")
	)
	(segment
		(start 152.484074 -208.458308)
		(end 152.484074 -208.227676)
		(width 0.14478)
		(layer "In11.Cu")
		(net "M_L_CPU1_SA_DQ<2>")
	)
	(segment
		(start 155.807156 -205.48219)
		(end 155.633674 -205.308708)
		(width 0.14478)
		(layer "In11.Cu")
		(net "M_L_CPU1_SA_DQ<2>")
	)
	(segment
		(start 155.633674 -205.078076)
		(end 155.796742 -204.915008)
		(width 0.14478)
		(layer "In11.Cu")
		(net "M_L_CPU1_SA_DQ<2>")
	)
	(segment
		(start 156.200856 -205.08849)
		(end 156.431488 -205.08849)
		(width 0.14478)
		(layer "In11.Cu")
		(net "M_L_CPU1_SA_DQ<2>")
	)
	(segment
		(start 143.9291 -222.375984)
		(end 143.989298 -222.315786)
		(width 0.0889)
		(layer "In11.Cu")
		(net "M_L_CPU1_SA_DQ<2>")
	)
	(segment
		(start 186.10072 -198.610474)
		(end 188.673232 -198.610474)
		(width 0.14478)
		(layer "In11.Cu")
		(net "M_L_CPU1_SA_DQ<2>")
	)
	(segment
		(start 152.657556 -208.862422)
		(end 152.657556 -208.63179)
		(width 0.14478)
		(layer "In11.Cu")
		(net "M_L_CPU1_SA_DQ<2>")
	)
	(segment
		(start 144.300448 -221.610428)
		(end 144.52092 -221.389956)
		(width 0.0889)
		(layer "In11.Cu")
		(net "M_L_CPU1_SA_DQ<2>")
	)
	(segment
		(start 156.027374 -204.915008)
		(end 156.200856 -205.08849)
		(width 0.14478)
		(layer "In11.Cu")
		(net "M_L_CPU1_SA_DQ<2>")
	)
	(segment
		(start 156.594556 -204.69479)
		(end 156.421074 -204.521308)
		(width 0.14478)
		(layer "In11.Cu")
		(net "M_L_CPU1_SA_DQ<2>")
	)
	(segment
		(start 156.421074 -204.521308)
		(end 156.421074 -204.290676)
		(width 0.14478)
		(layer "In11.Cu")
		(net "M_L_CPU1_SA_DQ<2>")
	)
	(segment
		(start 166.005764 -198.610474)
		(end 166.855902 -197.760336)
		(width 0.14478)
		(layer "In11.Cu")
		(net "M_L_CPU1_SA_DQ<2>")
	)
	(segment
		(start 144.300448 -221.804484)
		(end 144.300448 -221.610428)
		(width 0.0889)
		(layer "In11.Cu")
		(net "M_L_CPU1_SA_DQ<2>")
	)
	(segment
		(start 154.846274 -205.865476)
		(end 155.009342 -205.702408)
		(width 0.14478)
		(layer "In11.Cu")
		(net "M_L_CPU1_SA_DQ<2>")
	)
	(segment
		(start 156.421074 -204.290676)
		(end 162.101276 -198.610474)
		(width 0.14478)
		(layer "In11.Cu")
		(net "M_L_CPU1_SA_DQ<2>")
	)
	(segment
		(start 170.828716 -197.760336)
		(end 171.678854 -198.610474)
		(width 0.14478)
		(layer "In11.Cu")
		(net "M_L_CPU1_SA_DQ<2>")
	)
	(segment
		(start 142.607792 -224.721928)
		(end 142.644114 -224.700846)
		(width 0.0889)
		(layer "In11.Cu")
		(net "M_L_CPU1_SA_DQ<2>")
	)
	(segment
		(start 144.52092 -216.999058)
		(end 152.657556 -208.862422)
		(width 0.14478)
		(layer "In11.Cu")
		(net "M_L_CPU1_SA_DQ<2>")
	)
	(segment
		(start 155.019756 -206.500222)
		(end 155.019756 -206.26959)
		(width 0.14478)
		(layer "In11.Cu")
		(net "M_L_CPU1_SA_DQ<2>")
	)
	(segment
		(start 143.077692 -223.911922)
		(end 143.116808 -223.889062)
		(width 0.0889)
		(layer "In11.Cu")
		(net "M_L_CPU1_SA_DQ<2>")
	)
	(segment
		(start 154.626056 -206.66329)
		(end 154.856688 -206.66329)
		(width 0.14478)
		(layer "In11.Cu")
		(net "M_L_CPU1_SA_DQ<2>")
	)
	(segment
		(start 153.051256 -208.23809)
		(end 153.281888 -208.23809)
		(width 0.14478)
		(layer "In11.Cu")
		(net "M_L_CPU1_SA_DQ<2>")
	)
	(segment
		(start 174.469552 -197.76059)
		(end 177.972466 -197.76059)
		(width 0.14478)
		(layer "In11.Cu")
		(net "M_L_CPU1_SA_DQ<2>")
	)
	(segment
		(start 140.257784 -225.531934)
		(end 140.266166 -225.527108)
		(width 0.0889)
		(layer "In11.Cu")
		(net "M_L_CPU1_SA_DQ<2>")
	)
	(segment
		(start 155.633674 -205.308708)
		(end 155.633674 -205.078076)
		(width 0.14478)
		(layer "In11.Cu")
		(net "M_L_CPU1_SA_DQ<2>")
	)
	(segment
		(start 143.547592 -223.101916)
		(end 143.589502 -223.077532)
		(width 0.0889)
		(layer "In11.Cu")
		(net "M_L_CPU1_SA_DQ<2>")
	)
	(segment
		(start 193.696336 -198.610474)
		(end 195.961 -198.610474)
		(width 0.14478)
		(layer "In11.Cu")
		(net "M_L_CPU1_SA_DQ<2>")
	)
	(segment
		(start 154.452574 -206.489808)
		(end 154.626056 -206.66329)
		(width 0.14478)
		(layer "In11.Cu")
		(net "M_L_CPU1_SA_DQ<2>")
	)
	(segment
		(start 162.101276 -198.610474)
		(end 166.005764 -198.610474)
		(width 0.14478)
		(layer "In11.Cu")
		(net "M_L_CPU1_SA_DQ<2>")
	)
	(segment
		(start 200.316338 -197.90537)
		(end 200.316338 -198.015606)
		(width 0.14478)
		(layer "In11.Cu")
		(net "M_L_CPU1_SA_DQ<2>")
	)
	(segment
		(start 185.250836 -197.76059)
		(end 186.10072 -198.610474)
		(width 0.14478)
		(layer "In11.Cu")
		(net "M_L_CPU1_SA_DQ<2>")
	)
	(segment
		(start 155.019756 -206.26959)
		(end 154.846274 -206.096108)
		(width 0.14478)
		(layer "In11.Cu")
		(net "M_L_CPU1_SA_DQ<2>")
	)
	(segment
		(start 144.52092 -221.389956)
		(end 144.52092 -221.201488)
		(width 0.0889)
		(layer "In11.Cu")
		(net "M_L_CPU1_SA_DQ<2>")
	)
	(segment
		(start 155.009342 -205.702408)
		(end 155.239974 -205.702408)
		(width 0.14478)
		(layer "In11.Cu")
		(net "M_L_CPU1_SA_DQ<2>")
	)
	(segment
		(start 189.523116 -197.76059)
		(end 192.846452 -197.76059)
		(width 0.14478)
		(layer "In11.Cu")
		(net "M_L_CPU1_SA_DQ<2>")
	)
	(segment
		(start 143.995902 -222.310452)
		(end 144.051782 -222.272606)
		(width 0.0889)
		(layer "In11.Cu")
		(net "M_L_CPU1_SA_DQ<2>")
	)
	(segment
		(start 154.846274 -206.096108)
		(end 154.846274 -205.865476)
		(width 0.14478)
		(layer "In11.Cu")
		(net "M_L_CPU1_SA_DQ<2>")
	)
	(segment
		(start 195.961 -198.610474)
		(end 196.810884 -197.76059)
		(width 0.14478)
		(layer "In11.Cu")
		(net "M_L_CPU1_SA_DQ<2>")
	)
	(segment
		(start 200.171558 -197.76059)
		(end 200.316338 -197.90537)
		(width 0.14478)
		(layer "In11.Cu")
		(net "M_L_CPU1_SA_DQ<2>")
	)
	(segment
		(start 139.504674 -225.854514)
		(end 139.35075 -225.589084)
		(width 0.0889)
		(layer "In11.Cu")
		(net "M_L_CPU1_SA_DQ<2>")
	)
	(segment
		(start 155.644088 -205.87589)
		(end 155.807156 -205.712822)
		(width 0.14478)
		(layer "In11.Cu")
		(net "M_L_CPU1_SA_DQ<2>")
	)
	(segment
		(start 192.846452 -197.76059)
		(end 193.696336 -198.610474)
		(width 0.14478)
		(layer "In11.Cu")
		(net "M_L_CPU1_SA_DQ<2>")
	)
	(segment
		(start 200.722992 -198.160386)
		(end 200.867772 -198.015606)
		(width 0.14478)
		(layer "In11.Cu")
		(net "M_L_CPU1_SA_DQ<2>")
	)
	(segment
		(start 154.232356 -207.05699)
		(end 154.058874 -206.883508)
		(width 0.14478)
		(layer "In11.Cu")
		(net "M_L_CPU1_SA_DQ<2>")
	)
	(segment
		(start 155.239974 -205.702408)
		(end 155.413456 -205.87589)
		(width 0.14478)
		(layer "In11.Cu")
		(net "M_L_CPU1_SA_DQ<2>")
	)
	(segment
		(start 142.576042 -224.740216)
		(end 142.607792 -224.721928)
		(width 0.0889)
		(layer "In11.Cu")
		(net "M_L_CPU1_SA_DQ<2>")
	)
	(segment
		(start 166.855902 -197.760336)
		(end 170.828716 -197.760336)
		(width 0.14478)
		(layer "In11.Cu")
		(net "M_L_CPU1_SA_DQ<2>")
	)
	(segment
		(start 152.877774 -208.064608)
		(end 153.051256 -208.23809)
		(width 0.14478)
		(layer "In11.Cu")
		(net "M_L_CPU1_SA_DQ<2>")
	)
	(segment
		(start 171.678854 -198.610474)
		(end 173.619668 -198.610474)
		(width 0.14478)
		(layer "In11.Cu")
		(net "M_L_CPU1_SA_DQ<2>")
	)
	(segment
		(start 153.434542 -207.277208)
		(end 153.665174 -207.277208)
		(width 0.14478)
		(layer "In11.Cu")
		(net "M_L_CPU1_SA_DQ<2>")
	)
	(segment
		(start 153.271474 -207.670908)
		(end 153.271474 -207.440276)
		(width 0.14478)
		(layer "In11.Cu")
		(net "M_L_CPU1_SA_DQ<2>")
	)
	(segment
		(start 153.665174 -207.277208)
		(end 153.838656 -207.45069)
		(width 0.14478)
		(layer "In11.Cu")
		(net "M_L_CPU1_SA_DQ<2>")
	)
	(segment
		(start 156.594556 -204.925422)
		(end 156.594556 -204.69479)
		(width 0.14478)
		(layer "In11.Cu")
		(net "M_L_CPU1_SA_DQ<2>")
	)
	(arc
		(start 142.176754 -225.509074)
		(mid 142.355567 -225.306724)
		(end 142.420086 -225.044508)
		(width 0.0889)
		(layer "In11.Cu")
		(net "M_L_CPU1_SA_DQ<2>")
	)
	(arc
		(start 143.36014 -223.424496)
		(mid 143.401689 -223.253074)
		(end 143.517112 -223.119696)
		(width 0.0889)
		(layer "In11.Cu")
		(net "M_L_CPU1_SA_DQ<2>")
	)
	(arc
		(start 143.589502 -223.077532)
		(mid 143.766484 -222.87544)
		(end 143.830294 -222.61449)
		(width 0.0889)
		(layer "In11.Cu")
		(net "M_L_CPU1_SA_DQ<2>")
	)
	(arc
		(start 142.420086 -225.044508)
		(mid 142.461341 -224.873537)
		(end 142.576042 -224.740216)
		(width 0.0889)
		(layer "In11.Cu")
		(net "M_L_CPU1_SA_DQ<2>")
	)
	(arc
		(start 142.644114 -224.700846)
		(mid 142.824766 -224.498101)
		(end 142.889986 -224.234502)
		(width 0.0889)
		(layer "In11.Cu")
		(net "M_L_CPU1_SA_DQ<2>")
	)
	(arc
		(start 141.197838 -225.531934)
		(mid 141.384782 -225.481679)
		(end 141.571726 -225.531934)
		(width 0.0889)
		(layer "In11.Cu")
		(net "M_L_CPU1_SA_DQ<2>")
	)
	(arc
		(start 141.571726 -225.531934)
		(mid 141.854682 -225.608111)
		(end 142.137638 -225.531934)
		(width 0.0889)
		(layer "In11.Cu")
		(net "M_L_CPU1_SA_DQ<2>")
	)
	(arc
		(start 143.116808 -223.889062)
		(mid 143.295621 -223.686712)
		(end 143.36014 -223.424496)
		(width 0.0889)
		(layer "In11.Cu")
		(net "M_L_CPU1_SA_DQ<2>")
	)
	(arc
		(start 143.830294 -222.61449)
		(mid 143.85597 -222.485406)
		(end 143.9291 -222.375984)
		(width 0.0889)
		(layer "In11.Cu")
		(net "M_L_CPU1_SA_DQ<2>")
	)
	(arc
		(start 139.691872 -225.531934)
		(mid 139.974828 -225.608111)
		(end 140.257784 -225.531934)
		(width 0.0889)
		(layer "In11.Cu")
		(net "M_L_CPU1_SA_DQ<2>")
	)
	(arc
		(start 143.989298 -222.315786)
		(mid 143.992467 -222.312954)
		(end 143.995902 -222.310452)
		(width 0.0889)
		(layer "In11.Cu")
		(net "M_L_CPU1_SA_DQ<2>")
	)
	(arc
		(start 139.373102 -225.505772)
		(mid 139.535434 -225.482954)
		(end 139.691872 -225.531934)
		(width 0.0889)
		(layer "In11.Cu")
		(net "M_L_CPU1_SA_DQ<2>")
	)
	(arc
		(start 144.051782 -222.272606)
		(mid 144.234444 -222.069525)
		(end 144.300448 -221.804484)
		(width 0.0889)
		(layer "In11.Cu")
		(net "M_L_CPU1_SA_DQ<2>")
	)
	(arc
		(start 142.889986 -224.234502)
		(mid 142.931241 -224.063531)
		(end 143.045942 -223.93021)
		(width 0.0889)
		(layer "In11.Cu")
		(net "M_L_CPU1_SA_DQ<2>")
	)
	(arc
		(start 140.266166 -225.527108)
		(mid 140.449674 -225.481614)
		(end 140.631926 -225.531934)
		(width 0.0889)
		(layer "In11.Cu")
		(net "M_L_CPU1_SA_DQ<2>")
	)
	(arc
		(start 140.631926 -225.531934)
		(mid 140.914882 -225.608111)
		(end 141.197838 -225.531934)
		(width 0.0889)
		(layer "In11.Cu")
		(net "M_L_CPU1_SA_DQ<2>")
	)
	(segment
		(start 137.157968 -243.94033)
		(end 137.62482 -243.674392)
		(width 0.10668)
		(layer "F.Cu")
		(net "M_L_CPU1_SA_DQ<29>")
	)
	(segment
		(start 138.743436 -244.001798)
		(end 138.751818 -243.996972)
		(width 0.0889)
		(layer "In11.Cu")
		(net "M_L_CPU1_SA_DQ<29>")
	)
	(segment
		(start 142.503398 -244.001798)
		(end 142.51178 -243.996972)
		(width 0.0889)
		(layer "In11.Cu")
		(net "M_L_CPU1_SA_DQ<29>")
	)
	(segment
		(start 137.62482 -243.674392)
		(end 137.778744 -243.939822)
		(width 0.0889)
		(layer "In11.Cu")
		(net "M_L_CPU1_SA_DQ<29>")
	)
	(segment
		(start 140.257784 -243.996972)
		(end 140.266166 -244.001798)
		(width 0.0889)
		(layer "In11.Cu")
		(net "M_L_CPU1_SA_DQ<29>")
	)
	(segment
		(start 181.001924 -233.46029)
		(end 181.851808 -232.610406)
		(width 0.14478)
		(layer "In11.Cu")
		(net "M_L_CPU1_SA_DQ<29>")
	)
	(segment
		(start 178.82235 -233.46029)
		(end 181.001924 -233.46029)
		(width 0.14478)
		(layer "In11.Cu")
		(net "M_L_CPU1_SA_DQ<29>")
	)
	(segment
		(start 147.64385 -243.209826)
		(end 147.788122 -243.065554)
		(width 0.0889)
		(layer "In11.Cu")
		(net "M_L_CPU1_SA_DQ<29>")
	)
	(segment
		(start 155.756356 -243.065554)
		(end 159.92983 -238.89208)
		(width 0.14478)
		(layer "In11.Cu")
		(net "M_L_CPU1_SA_DQ<29>")
	)
	(segment
		(start 147.083272 -244.047264)
		(end 147.64385 -243.486686)
		(width 0.0889)
		(layer "In11.Cu")
		(net "M_L_CPU1_SA_DQ<29>")
	)
	(segment
		(start 181.851808 -232.610406)
		(end 185.250836 -232.610406)
		(width 0.14478)
		(layer "In11.Cu")
		(net "M_L_CPU1_SA_DQ<29>")
	)
	(segment
		(start 170.391328 -232.610406)
		(end 171.241212 -233.46029)
		(width 0.14478)
		(layer "In11.Cu")
		(net "M_L_CPU1_SA_DQ<29>")
	)
	(segment
		(start 159.92983 -237.857538)
		(end 164.327078 -233.46029)
		(width 0.14478)
		(layer "In11.Cu")
		(net "M_L_CPU1_SA_DQ<29>")
	)
	(segment
		(start 143.077692 -243.996972)
		(end 143.086074 -244.001798)
		(width 0.0889)
		(layer "In11.Cu")
		(net "M_L_CPU1_SA_DQ<29>")
	)
	(segment
		(start 139.31773 -243.996972)
		(end 139.326112 -244.001798)
		(width 0.0889)
		(layer "In11.Cu")
		(net "M_L_CPU1_SA_DQ<29>")
	)
	(segment
		(start 188.673232 -233.46029)
		(end 189.523116 -232.610406)
		(width 0.14478)
		(layer "In11.Cu")
		(net "M_L_CPU1_SA_DQ<29>")
	)
	(segment
		(start 171.241212 -233.46029)
		(end 173.519592 -233.46029)
		(width 0.14478)
		(layer "In11.Cu")
		(net "M_L_CPU1_SA_DQ<29>")
	)
	(segment
		(start 174.369476 -232.610406)
		(end 177.972466 -232.610406)
		(width 0.14478)
		(layer "In11.Cu")
		(net "M_L_CPU1_SA_DQ<29>")
	)
	(segment
		(start 166.595298 -232.610406)
		(end 170.391328 -232.610406)
		(width 0.14478)
		(layer "In11.Cu")
		(net "M_L_CPU1_SA_DQ<29>")
	)
	(segment
		(start 192.662048 -232.610406)
		(end 193.510662 -233.45902)
		(width 0.14478)
		(layer "In11.Cu")
		(net "M_L_CPU1_SA_DQ<29>")
	)
	(segment
		(start 145.144744 -244.047264)
		(end 147.083272 -244.047264)
		(width 0.0889)
		(layer "In11.Cu")
		(net "M_L_CPU1_SA_DQ<29>")
	)
	(segment
		(start 147.788122 -243.065554)
		(end 148.02993 -243.065554)
		(width 0.0889)
		(layer "In11.Cu")
		(net "M_L_CPU1_SA_DQ<29>")
	)
	(segment
		(start 185.250836 -232.610406)
		(end 186.10072 -233.46029)
		(width 0.14478)
		(layer "In11.Cu")
		(net "M_L_CPU1_SA_DQ<29>")
	)
	(segment
		(start 189.523116 -232.610406)
		(end 192.662048 -232.610406)
		(width 0.14478)
		(layer "In11.Cu")
		(net "M_L_CPU1_SA_DQ<29>")
	)
	(segment
		(start 177.972466 -232.610406)
		(end 178.82235 -233.46029)
		(width 0.14478)
		(layer "In11.Cu")
		(net "M_L_CPU1_SA_DQ<29>")
	)
	(segment
		(start 193.510662 -233.45902)
		(end 195.5419 -233.45902)
		(width 0.14478)
		(layer "In11.Cu")
		(net "M_L_CPU1_SA_DQ<29>")
	)
	(segment
		(start 173.519592 -233.46029)
		(end 174.369476 -232.610406)
		(width 0.14478)
		(layer "In11.Cu")
		(net "M_L_CPU1_SA_DQ<29>")
	)
	(segment
		(start 143.451834 -243.996972)
		(end 143.462248 -243.990876)
		(width 0.0889)
		(layer "In11.Cu")
		(net "M_L_CPU1_SA_DQ<29>")
	)
	(segment
		(start 144.38376 -244.001798)
		(end 144.392142 -243.996972)
		(width 0.0889)
		(layer "In11.Cu")
		(net "M_L_CPU1_SA_DQ<29>")
	)
	(segment
		(start 144.947386 -243.990876)
		(end 144.9578 -243.996972)
		(width 0.0889)
		(layer "In11.Cu")
		(net "M_L_CPU1_SA_DQ<29>")
	)
	(segment
		(start 197.590664 -232.610406)
		(end 204.111606 -232.610406)
		(width 0.14478)
		(layer "In11.Cu")
		(net "M_L_CPU1_SA_DQ<29>")
	)
	(segment
		(start 195.5419 -233.45902)
		(end 197.590664 -232.610406)
		(width 0.14478)
		(layer "In11.Cu")
		(net "M_L_CPU1_SA_DQ<29>")
	)
	(segment
		(start 204.111606 -232.610406)
		(end 206.248 -233.035348)
		(width 0.14478)
		(layer "In11.Cu")
		(net "M_L_CPU1_SA_DQ<29>")
	)
	(segment
		(start 186.10072 -233.46029)
		(end 188.673232 -233.46029)
		(width 0.14478)
		(layer "In11.Cu")
		(net "M_L_CPU1_SA_DQ<29>")
	)
	(segment
		(start 148.02993 -243.065554)
		(end 155.756356 -243.065554)
		(width 0.14478)
		(layer "In11.Cu")
		(net "M_L_CPU1_SA_DQ<29>")
	)
	(segment
		(start 137.778744 -243.939822)
		(end 137.874756 -243.965222)
		(width 0.0889)
		(layer "In11.Cu")
		(net "M_L_CPU1_SA_DQ<29>")
	)
	(segment
		(start 147.64385 -243.486686)
		(end 147.64385 -243.209826)
		(width 0.0889)
		(layer "In11.Cu")
		(net "M_L_CPU1_SA_DQ<29>")
	)
	(segment
		(start 159.92983 -238.89208)
		(end 159.92983 -237.857538)
		(width 0.14478)
		(layer "In11.Cu")
		(net "M_L_CPU1_SA_DQ<29>")
	)
	(segment
		(start 165.745414 -233.46029)
		(end 166.595298 -232.610406)
		(width 0.14478)
		(layer "In11.Cu")
		(net "M_L_CPU1_SA_DQ<29>")
	)
	(segment
		(start 164.327078 -233.46029)
		(end 165.745414 -233.46029)
		(width 0.14478)
		(layer "In11.Cu")
		(net "M_L_CPU1_SA_DQ<29>")
	)
	(arc
		(start 144.9578 -243.996972)
		(mid 145.047949 -244.034469)
		(end 145.144744 -244.047264)
		(width 0.0889)
		(layer "In11.Cu")
		(net "M_L_CPU1_SA_DQ<29>")
	)
	(arc
		(start 142.51178 -243.996972)
		(mid 142.794736 -243.920795)
		(end 143.077692 -243.996972)
		(width 0.0889)
		(layer "In11.Cu")
		(net "M_L_CPU1_SA_DQ<29>")
	)
	(arc
		(start 142.137638 -243.996972)
		(mid 142.319889 -244.047322)
		(end 142.503398 -244.001798)
		(width 0.0889)
		(layer "In11.Cu")
		(net "M_L_CPU1_SA_DQ<29>")
	)
	(arc
		(start 141.197838 -243.996972)
		(mid 141.384782 -244.047227)
		(end 141.571726 -243.996972)
		(width 0.0889)
		(layer "In11.Cu")
		(net "M_L_CPU1_SA_DQ<29>")
	)
	(arc
		(start 141.571726 -243.996972)
		(mid 141.854682 -243.920795)
		(end 142.137638 -243.996972)
		(width 0.0889)
		(layer "In11.Cu")
		(net "M_L_CPU1_SA_DQ<29>")
	)
	(arc
		(start 138.377676 -243.996972)
		(mid 138.559927 -244.047322)
		(end 138.743436 -244.001798)
		(width 0.0889)
		(layer "In11.Cu")
		(net "M_L_CPU1_SA_DQ<29>")
	)
	(arc
		(start 144.018 -243.996972)
		(mid 144.200251 -244.047322)
		(end 144.38376 -244.001798)
		(width 0.0889)
		(layer "In11.Cu")
		(net "M_L_CPU1_SA_DQ<29>")
	)
	(arc
		(start 143.086074 -244.001798)
		(mid 143.269582 -244.047292)
		(end 143.451834 -243.996972)
		(width 0.0889)
		(layer "In11.Cu")
		(net "M_L_CPU1_SA_DQ<29>")
	)
	(arc
		(start 137.874756 -243.965222)
		(mid 138.129964 -243.921745)
		(end 138.377676 -243.996972)
		(width 0.0889)
		(layer "In11.Cu")
		(net "M_L_CPU1_SA_DQ<29>")
	)
	(arc
		(start 140.266166 -244.001798)
		(mid 140.449674 -244.047292)
		(end 140.631926 -243.996972)
		(width 0.0889)
		(layer "In11.Cu")
		(net "M_L_CPU1_SA_DQ<29>")
	)
	(arc
		(start 143.462248 -243.990876)
		(mid 143.740934 -243.920656)
		(end 144.018 -243.996972)
		(width 0.0889)
		(layer "In11.Cu")
		(net "M_L_CPU1_SA_DQ<29>")
	)
	(arc
		(start 144.392142 -243.996972)
		(mid 144.668955 -243.920829)
		(end 144.947386 -243.990876)
		(width 0.0889)
		(layer "In11.Cu")
		(net "M_L_CPU1_SA_DQ<29>")
	)
	(arc
		(start 139.691872 -243.996972)
		(mid 139.974828 -243.920795)
		(end 140.257784 -243.996972)
		(width 0.0889)
		(layer "In11.Cu")
		(net "M_L_CPU1_SA_DQ<29>")
	)
	(arc
		(start 139.326112 -244.001798)
		(mid 139.50962 -244.047292)
		(end 139.691872 -243.996972)
		(width 0.0889)
		(layer "In11.Cu")
		(net "M_L_CPU1_SA_DQ<29>")
	)
	(arc
		(start 140.631926 -243.996972)
		(mid 140.914882 -243.920795)
		(end 141.197838 -243.996972)
		(width 0.0889)
		(layer "In11.Cu")
		(net "M_L_CPU1_SA_DQ<29>")
	)
	(arc
		(start 138.751818 -243.996972)
		(mid 139.034774 -243.920795)
		(end 139.31773 -243.996972)
		(width 0.0889)
		(layer "In11.Cu")
		(net "M_L_CPU1_SA_DQ<29>")
	)
	(segment
		(start 138.567922 -243.130324)
		(end 139.034774 -242.864386)
		(width 0.10668)
		(layer "F.Cu")
		(net "M_L_CPU1_SA_DQ<28>")
	)
	(segment
		(start 147.78609 -242.156234)
		(end 155.339288 -242.156234)
		(width 0.14478)
		(layer "In11.Cu")
		(net "M_L_CPU1_SA_DQ<28>")
	)
	(segment
		(start 170.515788 -231.261666)
		(end 171.023788 -231.769666)
		(width 0.14478)
		(layer "In11.Cu")
		(net "M_L_CPU1_SA_DQ<28>")
	)
	(segment
		(start 204.78496 -231.528366)
		(end 204.92974 -231.383586)
		(width 0.14478)
		(layer "In11.Cu")
		(net "M_L_CPU1_SA_DQ<28>")
	)
	(segment
		(start 139.188698 -243.129816)
		(end 139.28471 -243.155216)
		(width 0.0889)
		(layer "In11.Cu")
		(net "M_L_CPU1_SA_DQ<28>")
	)
	(segment
		(start 141.667738 -243.186966)
		(end 141.67612 -243.191792)
		(width 0.0889)
		(layer "In11.Cu")
		(net "M_L_CPU1_SA_DQ<28>")
	)
	(segment
		(start 146.300444 -243.496846)
		(end 146.91995 -243.496846)
		(width 0.0889)
		(layer "In11.Cu")
		(net "M_L_CPU1_SA_DQ<28>")
	)
	(segment
		(start 139.034774 -242.864386)
		(end 139.188698 -243.129816)
		(width 0.0889)
		(layer "In11.Cu")
		(net "M_L_CPU1_SA_DQ<28>")
	)
	(segment
		(start 166.08552 -231.760268)
		(end 166.584122 -231.261666)
		(width 0.14478)
		(layer "In11.Cu")
		(net "M_L_CPU1_SA_DQ<28>")
	)
	(segment
		(start 186.110118 -231.769666)
		(end 188.663834 -231.769666)
		(width 0.14478)
		(layer "In11.Cu")
		(net "M_L_CPU1_SA_DQ<28>")
	)
	(segment
		(start 205.81366 -230.919782)
		(end 205.823058 -230.910384)
		(width 0.14478)
		(layer "In11.Cu")
		(net "M_L_CPU1_SA_DQ<28>")
	)
	(segment
		(start 204.523086 -231.528366)
		(end 204.78496 -231.528366)
		(width 0.14478)
		(layer "In11.Cu")
		(net "M_L_CPU1_SA_DQ<28>")
	)
	(segment
		(start 147.16887 -243.247926)
		(end 147.16887 -242.572286)
		(width 0.0889)
		(layer "In11.Cu")
		(net "M_L_CPU1_SA_DQ<28>")
	)
	(segment
		(start 144.48663 -243.186966)
		(end 144.498314 -243.193824)
		(width 0.0889)
		(layer "In11.Cu")
		(net "M_L_CPU1_SA_DQ<28>")
	)
	(segment
		(start 173.591982 -231.769666)
		(end 174.441866 -230.919782)
		(width 0.14478)
		(layer "In11.Cu")
		(net "M_L_CPU1_SA_DQ<28>")
	)
	(segment
		(start 145.91411 -243.110512)
		(end 146.300444 -243.496846)
		(width 0.0889)
		(layer "In11.Cu")
		(net "M_L_CPU1_SA_DQ<28>")
	)
	(segment
		(start 141.093444 -243.191792)
		(end 141.101826 -243.186966)
		(width 0.0889)
		(layer "In11.Cu")
		(net "M_L_CPU1_SA_DQ<28>")
	)
	(segment
		(start 205.823058 -230.910384)
		(end 206.248 -231.335326)
		(width 0.14478)
		(layer "In11.Cu")
		(net "M_L_CPU1_SA_DQ<28>")
	)
	(segment
		(start 147.16887 -242.572286)
		(end 147.584922 -242.156234)
		(width 0.0889)
		(layer "In11.Cu")
		(net "M_L_CPU1_SA_DQ<28>")
	)
	(segment
		(start 197.198742 -230.919782)
		(end 204.233526 -230.919782)
		(width 0.14478)
		(layer "In11.Cu")
		(net "M_L_CPU1_SA_DQ<28>")
	)
	(segment
		(start 192.612518 -230.919782)
		(end 193.462402 -231.769666)
		(width 0.14478)
		(layer "In11.Cu")
		(net "M_L_CPU1_SA_DQ<28>")
	)
	(segment
		(start 155.339288 -242.156234)
		(end 158.78937 -238.706152)
		(width 0.14478)
		(layer "In11.Cu")
		(net "M_L_CPU1_SA_DQ<28>")
	)
	(segment
		(start 158.78937 -237.4392)
		(end 164.468302 -231.760268)
		(width 0.14478)
		(layer "In11.Cu")
		(net "M_L_CPU1_SA_DQ<28>")
	)
	(segment
		(start 196.348858 -231.769666)
		(end 197.198742 -230.919782)
		(width 0.14478)
		(layer "In11.Cu")
		(net "M_L_CPU1_SA_DQ<28>")
	)
	(segment
		(start 143.905224 -243.19611)
		(end 143.92148 -243.186712)
		(width 0.0889)
		(layer "In11.Cu")
		(net "M_L_CPU1_SA_DQ<28>")
	)
	(segment
		(start 181.21249 -231.769666)
		(end 182.062374 -230.919782)
		(width 0.14478)
		(layer "In11.Cu")
		(net "M_L_CPU1_SA_DQ<28>")
	)
	(segment
		(start 193.462402 -231.769666)
		(end 196.348858 -231.769666)
		(width 0.14478)
		(layer "In11.Cu")
		(net "M_L_CPU1_SA_DQ<28>")
	)
	(segment
		(start 178.748436 -231.769666)
		(end 181.21249 -231.769666)
		(width 0.14478)
		(layer "In11.Cu")
		(net "M_L_CPU1_SA_DQ<28>")
	)
	(segment
		(start 146.91995 -243.496846)
		(end 147.16887 -243.247926)
		(width 0.0889)
		(layer "In11.Cu")
		(net "M_L_CPU1_SA_DQ<28>")
	)
	(segment
		(start 147.584922 -242.156234)
		(end 147.78609 -242.156234)
		(width 0.0889)
		(layer "In11.Cu")
		(net "M_L_CPU1_SA_DQ<28>")
	)
	(segment
		(start 177.898552 -230.919782)
		(end 178.748436 -231.769666)
		(width 0.14478)
		(layer "In11.Cu")
		(net "M_L_CPU1_SA_DQ<28>")
	)
	(segment
		(start 143.92148 -243.186712)
		(end 143.933418 -243.179854)
		(width 0.0889)
		(layer "In11.Cu")
		(net "M_L_CPU1_SA_DQ<28>")
	)
	(segment
		(start 171.023788 -231.769666)
		(end 173.591982 -231.769666)
		(width 0.14478)
		(layer "In11.Cu")
		(net "M_L_CPU1_SA_DQ<28>")
	)
	(segment
		(start 174.441866 -230.919782)
		(end 177.898552 -230.919782)
		(width 0.14478)
		(layer "In11.Cu")
		(net "M_L_CPU1_SA_DQ<28>")
	)
	(segment
		(start 158.78937 -238.706152)
		(end 158.78937 -237.4392)
		(width 0.14478)
		(layer "In11.Cu")
		(net "M_L_CPU1_SA_DQ<28>")
	)
	(segment
		(start 205.07452 -230.919782)
		(end 205.81366 -230.919782)
		(width 0.14478)
		(layer "In11.Cu")
		(net "M_L_CPU1_SA_DQ<28>")
	)
	(segment
		(start 164.468302 -231.760268)
		(end 166.08552 -231.760268)
		(width 0.14478)
		(layer "In11.Cu")
		(net "M_L_CPU1_SA_DQ<28>")
	)
	(segment
		(start 189.513718 -230.919782)
		(end 192.612518 -230.919782)
		(width 0.14478)
		(layer "In11.Cu")
		(net "M_L_CPU1_SA_DQ<28>")
	)
	(segment
		(start 204.378306 -231.383586)
		(end 204.523086 -231.528366)
		(width 0.14478)
		(layer "In11.Cu")
		(net "M_L_CPU1_SA_DQ<28>")
	)
	(segment
		(start 166.584122 -231.261666)
		(end 170.515788 -231.261666)
		(width 0.14478)
		(layer "In11.Cu")
		(net "M_L_CPU1_SA_DQ<28>")
	)
	(segment
		(start 185.260234 -230.919782)
		(end 186.110118 -231.769666)
		(width 0.14478)
		(layer "In11.Cu")
		(net "M_L_CPU1_SA_DQ<28>")
	)
	(segment
		(start 204.378306 -231.064562)
		(end 204.378306 -231.383586)
		(width 0.14478)
		(layer "In11.Cu")
		(net "M_L_CPU1_SA_DQ<28>")
	)
	(segment
		(start 188.663834 -231.769666)
		(end 189.513718 -230.919782)
		(width 0.14478)
		(layer "In11.Cu")
		(net "M_L_CPU1_SA_DQ<28>")
	)
	(segment
		(start 204.92974 -231.064562)
		(end 205.07452 -230.919782)
		(width 0.14478)
		(layer "In11.Cu")
		(net "M_L_CPU1_SA_DQ<28>")
	)
	(segment
		(start 145.144744 -243.110512)
		(end 145.91411 -243.110512)
		(width 0.0889)
		(layer "In11.Cu")
		(net "M_L_CPU1_SA_DQ<28>")
	)
	(segment
		(start 140.15339 -243.191792)
		(end 140.161772 -243.186966)
		(width 0.0889)
		(layer "In11.Cu")
		(net "M_L_CPU1_SA_DQ<28>")
	)
	(segment
		(start 204.92974 -231.383586)
		(end 204.92974 -231.064562)
		(width 0.14478)
		(layer "In11.Cu")
		(net "M_L_CPU1_SA_DQ<28>")
	)
	(segment
		(start 182.062374 -230.919782)
		(end 185.260234 -230.919782)
		(width 0.14478)
		(layer "In11.Cu")
		(net "M_L_CPU1_SA_DQ<28>")
	)
	(segment
		(start 204.233526 -230.919782)
		(end 204.378306 -231.064562)
		(width 0.14478)
		(layer "In11.Cu")
		(net "M_L_CPU1_SA_DQ<28>")
	)
	(arc
		(start 144.498314 -243.193824)
		(mid 144.680569 -243.237477)
		(end 144.861026 -243.186966)
		(width 0.0889)
		(layer "In11.Cu")
		(net "M_L_CPU1_SA_DQ<28>")
	)
	(arc
		(start 141.67612 -243.191792)
		(mid 141.859628 -243.237286)
		(end 142.04188 -243.186966)
		(width 0.0889)
		(layer "In11.Cu")
		(net "M_L_CPU1_SA_DQ<28>")
	)
	(arc
		(start 143.933418 -243.179854)
		(mid 144.210952 -243.110873)
		(end 144.48663 -243.186966)
		(width 0.0889)
		(layer "In11.Cu")
		(net "M_L_CPU1_SA_DQ<28>")
	)
	(arc
		(start 144.861026 -243.186966)
		(mid 144.997819 -243.129944)
		(end 145.144744 -243.110512)
		(width 0.0889)
		(layer "In11.Cu")
		(net "M_L_CPU1_SA_DQ<28>")
	)
	(arc
		(start 139.78763 -243.186966)
		(mid 139.969881 -243.237316)
		(end 140.15339 -243.191792)
		(width 0.0889)
		(layer "In11.Cu")
		(net "M_L_CPU1_SA_DQ<28>")
	)
	(arc
		(start 142.98168 -243.186966)
		(mid 143.264636 -243.110789)
		(end 143.547592 -243.186966)
		(width 0.0889)
		(layer "In11.Cu")
		(net "M_L_CPU1_SA_DQ<28>")
	)
	(arc
		(start 139.28471 -243.155216)
		(mid 139.539918 -243.111739)
		(end 139.78763 -243.186966)
		(width 0.0889)
		(layer "In11.Cu")
		(net "M_L_CPU1_SA_DQ<28>")
	)
	(arc
		(start 140.161772 -243.186966)
		(mid 140.444728 -243.110789)
		(end 140.727684 -243.186966)
		(width 0.0889)
		(layer "In11.Cu")
		(net "M_L_CPU1_SA_DQ<28>")
	)
	(arc
		(start 143.547592 -243.186966)
		(mid 143.725242 -243.237226)
		(end 143.905224 -243.19611)
		(width 0.0889)
		(layer "In11.Cu")
		(net "M_L_CPU1_SA_DQ<28>")
	)
	(arc
		(start 140.727684 -243.186966)
		(mid 140.909935 -243.237316)
		(end 141.093444 -243.191792)
		(width 0.0889)
		(layer "In11.Cu")
		(net "M_L_CPU1_SA_DQ<28>")
	)
	(arc
		(start 142.607792 -243.186966)
		(mid 142.794736 -243.237221)
		(end 142.98168 -243.186966)
		(width 0.0889)
		(layer "In11.Cu")
		(net "M_L_CPU1_SA_DQ<28>")
	)
	(arc
		(start 141.101826 -243.186966)
		(mid 141.384782 -243.110789)
		(end 141.667738 -243.186966)
		(width 0.0889)
		(layer "In11.Cu")
		(net "M_L_CPU1_SA_DQ<28>")
	)
	(arc
		(start 142.04188 -243.186966)
		(mid 142.324836 -243.110789)
		(end 142.607792 -243.186966)
		(width 0.0889)
		(layer "In11.Cu")
		(net "M_L_CPU1_SA_DQ<28>")
	)
	(segment
		(start 137.627868 -241.510312)
		(end 138.09472 -241.244374)
		(width 0.10668)
		(layer "F.Cu")
		(net "M_L_CPU1_SA_DQ<27>")
	)
	(segment
		(start 171.1325 -228.350826)
		(end 173.586394 -228.350826)
		(width 0.14478)
		(layer "In11.Cu")
		(net "M_L_CPU1_SA_DQ<27>")
	)
	(segment
		(start 189.532514 -227.501196)
		(end 193.157602 -227.501196)
		(width 0.14478)
		(layer "In11.Cu")
		(net "M_L_CPU1_SA_DQ<27>")
	)
	(segment
		(start 181.0004 -228.350826)
		(end 181.85003 -227.501196)
		(width 0.14478)
		(layer "In11.Cu")
		(net "M_L_CPU1_SA_DQ<27>")
	)
	(segment
		(start 156.578046 -236.298232)
		(end 156.578046 -236.0676)
		(width 0.14478)
		(layer "In11.Cu")
		(net "M_L_CPU1_SA_DQ<27>")
	)
	(segment
		(start 159.116014 -233.093768)
		(end 159.333946 -233.3117)
		(width 0.14478)
		(layer "In11.Cu")
		(net "M_L_CPU1_SA_DQ<27>")
	)
	(segment
		(start 194.007486 -228.35108)
		(end 195.996814 -228.35108)
		(width 0.14478)
		(layer "In11.Cu")
		(net "M_L_CPU1_SA_DQ<27>")
	)
	(segment
		(start 158.777178 -234.0991)
		(end 158.940246 -233.936032)
		(width 0.14478)
		(layer "In11.Cu")
		(net "M_L_CPU1_SA_DQ<27>")
	)
	(segment
		(start 158.152846 -234.4928)
		(end 157.934914 -234.274868)
		(width 0.14478)
		(layer "In11.Cu")
		(net "M_L_CPU1_SA_DQ<27>")
	)
	(segment
		(start 145.899378 -240.476786)
		(end 147.09267 -240.476786)
		(width 0.0889)
		(layer "In11.Cu")
		(net "M_L_CPU1_SA_DQ<27>")
	)
	(segment
		(start 156.971746 -235.6739)
		(end 157.202378 -235.6739)
		(width 0.14478)
		(layer "In11.Cu")
		(net "M_L_CPU1_SA_DQ<27>")
	)
	(segment
		(start 156.578046 -236.0676)
		(end 156.360114 -235.849668)
		(width 0.14478)
		(layer "In11.Cu")
		(net "M_L_CPU1_SA_DQ<27>")
	)
	(segment
		(start 157.202378 -235.6739)
		(end 157.365446 -235.510832)
		(width 0.14478)
		(layer "In11.Cu")
		(net "M_L_CPU1_SA_DQ<27>")
	)
	(segment
		(start 166.832788 -227.500942)
		(end 170.282616 -227.500942)
		(width 0.14478)
		(layer "In11.Cu")
		(net "M_L_CPU1_SA_DQ<27>")
	)
	(segment
		(start 138.09472 -241.244374)
		(end 137.940796 -240.978944)
		(width 0.0889)
		(layer "In11.Cu")
		(net "M_L_CPU1_SA_DQ<27>")
	)
	(segment
		(start 170.282616 -227.500942)
		(end 171.1325 -228.350826)
		(width 0.14478)
		(layer "In11.Cu")
		(net "M_L_CPU1_SA_DQ<27>")
	)
	(segment
		(start 141.667738 -240.921794)
		(end 141.67612 -240.916968)
		(width 0.0889)
		(layer "In11.Cu")
		(net "M_L_CPU1_SA_DQ<27>")
	)
	(segment
		(start 141.093444 -240.916968)
		(end 141.101826 -240.921794)
		(width 0.0889)
		(layer "In11.Cu")
		(net "M_L_CPU1_SA_DQ<27>")
	)
	(segment
		(start 143.913352 -240.916968)
		(end 143.921734 -240.921794)
		(width 0.0889)
		(layer "In11.Cu")
		(net "M_L_CPU1_SA_DQ<27>")
	)
	(segment
		(start 156.360114 -235.619036)
		(end 156.523182 -235.455968)
		(width 0.14478)
		(layer "In11.Cu")
		(net "M_L_CPU1_SA_DQ<27>")
	)
	(segment
		(start 173.586394 -228.350826)
		(end 174.436278 -227.500942)
		(width 0.14478)
		(layer "In11.Cu")
		(net "M_L_CPU1_SA_DQ<27>")
	)
	(segment
		(start 157.934914 -234.274868)
		(end 157.934914 -234.044236)
		(width 0.14478)
		(layer "In11.Cu")
		(net "M_L_CPU1_SA_DQ<27>")
	)
	(segment
		(start 157.147514 -235.062268)
		(end 157.147514 -234.831636)
		(width 0.14478)
		(layer "In11.Cu")
		(net "M_L_CPU1_SA_DQ<27>")
	)
	(segment
		(start 157.934914 -234.044236)
		(end 158.097982 -233.881168)
		(width 0.14478)
		(layer "In11.Cu")
		(net "M_L_CPU1_SA_DQ<27>")
	)
	(segment
		(start 158.722314 -233.487468)
		(end 158.722314 -233.256836)
		(width 0.14478)
		(layer "In11.Cu")
		(net "M_L_CPU1_SA_DQ<27>")
	)
	(segment
		(start 158.885382 -233.093768)
		(end 159.116014 -233.093768)
		(width 0.14478)
		(layer "In11.Cu")
		(net "M_L_CPU1_SA_DQ<27>")
	)
	(segment
		(start 158.097982 -233.881168)
		(end 158.328614 -233.881168)
		(width 0.14478)
		(layer "In11.Cu")
		(net "M_L_CPU1_SA_DQ<27>")
	)
	(segment
		(start 156.753814 -235.455968)
		(end 156.971746 -235.6739)
		(width 0.14478)
		(layer "In11.Cu")
		(net "M_L_CPU1_SA_DQ<27>")
	)
	(segment
		(start 159.564578 -233.3117)
		(end 164.516054 -228.360224)
		(width 0.14478)
		(layer "In11.Cu")
		(net "M_L_CPU1_SA_DQ<27>")
	)
	(segment
		(start 196.846698 -227.501196)
		(end 201.713846 -227.501196)
		(width 0.14478)
		(layer "In11.Cu")
		(net "M_L_CPU1_SA_DQ<27>")
	)
	(segment
		(start 140.15339 -240.916968)
		(end 140.161772 -240.921794)
		(width 0.0889)
		(layer "In11.Cu")
		(net "M_L_CPU1_SA_DQ<27>")
	)
	(segment
		(start 158.152846 -234.723432)
		(end 158.152846 -234.4928)
		(width 0.14478)
		(layer "In11.Cu")
		(net "M_L_CPU1_SA_DQ<27>")
	)
	(segment
		(start 148.010372 -239.816894)
		(end 153.059384 -239.816894)
		(width 0.14478)
		(layer "In11.Cu")
		(net "M_L_CPU1_SA_DQ<27>")
	)
	(segment
		(start 158.328614 -233.881168)
		(end 158.546546 -234.0991)
		(width 0.14478)
		(layer "In11.Cu")
		(net "M_L_CPU1_SA_DQ<27>")
	)
	(segment
		(start 156.360114 -235.849668)
		(end 156.360114 -235.619036)
		(width 0.14478)
		(layer "In11.Cu")
		(net "M_L_CPU1_SA_DQ<27>")
	)
	(segment
		(start 157.147514 -234.831636)
		(end 157.310582 -234.668568)
		(width 0.14478)
		(layer "In11.Cu")
		(net "M_L_CPU1_SA_DQ<27>")
	)
	(segment
		(start 144.853406 -240.916968)
		(end 144.861788 -240.921794)
		(width 0.0889)
		(layer "In11.Cu")
		(net "M_L_CPU1_SA_DQ<27>")
	)
	(segment
		(start 157.541214 -234.668568)
		(end 157.759146 -234.8865)
		(width 0.14478)
		(layer "In11.Cu")
		(net "M_L_CPU1_SA_DQ<27>")
	)
	(segment
		(start 157.365446 -235.2802)
		(end 157.147514 -235.062268)
		(width 0.14478)
		(layer "In11.Cu")
		(net "M_L_CPU1_SA_DQ<27>")
	)
	(segment
		(start 164.516054 -228.360224)
		(end 165.973506 -228.360224)
		(width 0.14478)
		(layer "In11.Cu")
		(net "M_L_CPU1_SA_DQ<27>")
	)
	(segment
		(start 158.722314 -233.256836)
		(end 158.885382 -233.093768)
		(width 0.14478)
		(layer "In11.Cu")
		(net "M_L_CPU1_SA_DQ<27>")
	)
	(segment
		(start 201.713846 -227.501196)
		(end 202.147932 -227.935282)
		(width 0.14478)
		(layer "In11.Cu")
		(net "M_L_CPU1_SA_DQ<27>")
	)
	(segment
		(start 158.546546 -234.0991)
		(end 158.777178 -234.0991)
		(width 0.14478)
		(layer "In11.Cu")
		(net "M_L_CPU1_SA_DQ<27>")
	)
	(segment
		(start 193.157602 -227.501196)
		(end 194.007486 -228.35108)
		(width 0.14478)
		(layer "In11.Cu")
		(net "M_L_CPU1_SA_DQ<27>")
	)
	(segment
		(start 181.85003 -227.501196)
		(end 185.241438 -227.501196)
		(width 0.14478)
		(layer "In11.Cu")
		(net "M_L_CPU1_SA_DQ<27>")
	)
	(segment
		(start 174.436278 -227.500942)
		(end 177.713894 -227.500942)
		(width 0.14478)
		(layer "In11.Cu")
		(net "M_L_CPU1_SA_DQ<27>")
	)
	(segment
		(start 157.365446 -235.510832)
		(end 157.365446 -235.2802)
		(width 0.14478)
		(layer "In11.Cu")
		(net "M_L_CPU1_SA_DQ<27>")
	)
	(segment
		(start 137.940796 -240.978944)
		(end 137.963148 -240.895632)
		(width 0.0889)
		(layer "In11.Cu")
		(net "M_L_CPU1_SA_DQ<27>")
	)
	(segment
		(start 157.989778 -234.8865)
		(end 158.152846 -234.723432)
		(width 0.14478)
		(layer "In11.Cu")
		(net "M_L_CPU1_SA_DQ<27>")
	)
	(segment
		(start 185.241438 -227.501196)
		(end 186.091322 -228.35108)
		(width 0.14478)
		(layer "In11.Cu")
		(net "M_L_CPU1_SA_DQ<27>")
	)
	(segment
		(start 188.68263 -228.35108)
		(end 189.532514 -227.501196)
		(width 0.14478)
		(layer "In11.Cu")
		(net "M_L_CPU1_SA_DQ<27>")
	)
	(segment
		(start 153.059384 -239.816894)
		(end 156.578046 -236.298232)
		(width 0.14478)
		(layer "In11.Cu")
		(net "M_L_CPU1_SA_DQ<27>")
	)
	(segment
		(start 159.333946 -233.3117)
		(end 159.564578 -233.3117)
		(width 0.14478)
		(layer "In11.Cu")
		(net "M_L_CPU1_SA_DQ<27>")
	)
	(segment
		(start 195.996814 -228.35108)
		(end 196.846698 -227.501196)
		(width 0.14478)
		(layer "In11.Cu")
		(net "M_L_CPU1_SA_DQ<27>")
	)
	(segment
		(start 178.563778 -228.350826)
		(end 181.0004 -228.350826)
		(width 0.14478)
		(layer "In11.Cu")
		(net "M_L_CPU1_SA_DQ<27>")
	)
	(segment
		(start 177.713894 -227.500942)
		(end 178.563778 -228.350826)
		(width 0.14478)
		(layer "In11.Cu")
		(net "M_L_CPU1_SA_DQ<27>")
	)
	(segment
		(start 157.310582 -234.668568)
		(end 157.541214 -234.668568)
		(width 0.14478)
		(layer "In11.Cu")
		(net "M_L_CPU1_SA_DQ<27>")
	)
	(segment
		(start 158.940246 -233.7054)
		(end 158.722314 -233.487468)
		(width 0.14478)
		(layer "In11.Cu")
		(net "M_L_CPU1_SA_DQ<27>")
	)
	(segment
		(start 147.09267 -240.476786)
		(end 147.752562 -239.816894)
		(width 0.0889)
		(layer "In11.Cu")
		(net "M_L_CPU1_SA_DQ<27>")
	)
	(segment
		(start 186.091322 -228.35108)
		(end 188.68263 -228.35108)
		(width 0.14478)
		(layer "In11.Cu")
		(net "M_L_CPU1_SA_DQ<27>")
	)
	(segment
		(start 157.759146 -234.8865)
		(end 157.989778 -234.8865)
		(width 0.14478)
		(layer "In11.Cu")
		(net "M_L_CPU1_SA_DQ<27>")
	)
	(segment
		(start 165.973506 -228.360224)
		(end 166.832788 -227.500942)
		(width 0.14478)
		(layer "In11.Cu")
		(net "M_L_CPU1_SA_DQ<27>")
	)
	(segment
		(start 158.940246 -233.936032)
		(end 158.940246 -233.7054)
		(width 0.14478)
		(layer "In11.Cu")
		(net "M_L_CPU1_SA_DQ<27>")
	)
	(segment
		(start 156.523182 -235.455968)
		(end 156.753814 -235.455968)
		(width 0.14478)
		(layer "In11.Cu")
		(net "M_L_CPU1_SA_DQ<27>")
	)
	(segment
		(start 147.752562 -239.816894)
		(end 148.010372 -239.816894)
		(width 0.0889)
		(layer "In11.Cu")
		(net "M_L_CPU1_SA_DQ<27>")
	)
	(segment
		(start 145.54327 -240.832894)
		(end 145.899378 -240.476786)
		(width 0.0889)
		(layer "In11.Cu")
		(net "M_L_CPU1_SA_DQ<27>")
	)
	(arc
		(start 142.607792 -240.921794)
		(mid 142.794736 -240.871539)
		(end 142.98168 -240.921794)
		(width 0.0889)
		(layer "In11.Cu")
		(net "M_L_CPU1_SA_DQ<27>")
	)
	(arc
		(start 141.101826 -240.921794)
		(mid 141.384782 -240.997971)
		(end 141.667738 -240.921794)
		(width 0.0889)
		(layer "In11.Cu")
		(net "M_L_CPU1_SA_DQ<27>")
	)
	(arc
		(start 139.221718 -240.921794)
		(mid 139.504674 -240.997971)
		(end 139.78763 -240.921794)
		(width 0.0889)
		(layer "In11.Cu")
		(net "M_L_CPU1_SA_DQ<27>")
	)
	(arc
		(start 139.78763 -240.921794)
		(mid 139.969881 -240.871444)
		(end 140.15339 -240.916968)
		(width 0.0889)
		(layer "In11.Cu")
		(net "M_L_CPU1_SA_DQ<27>")
	)
	(arc
		(start 138.84783 -240.921794)
		(mid 139.034774 -240.871539)
		(end 139.221718 -240.921794)
		(width 0.0889)
		(layer "In11.Cu")
		(net "M_L_CPU1_SA_DQ<27>")
	)
	(arc
		(start 144.861788 -240.921794)
		(mid 145.144744 -240.997971)
		(end 145.4277 -240.921794)
		(width 0.0889)
		(layer "In11.Cu")
		(net "M_L_CPU1_SA_DQ<27>")
	)
	(arc
		(start 143.921734 -240.921794)
		(mid 144.20469 -240.997971)
		(end 144.487646 -240.921794)
		(width 0.0889)
		(layer "In11.Cu")
		(net "M_L_CPU1_SA_DQ<27>")
	)
	(arc
		(start 145.4277 -240.921794)
		(mid 145.488373 -240.881098)
		(end 145.54327 -240.832894)
		(width 0.0889)
		(layer "In11.Cu")
		(net "M_L_CPU1_SA_DQ<27>")
	)
	(arc
		(start 140.161772 -240.921794)
		(mid 140.444728 -240.997971)
		(end 140.727684 -240.921794)
		(width 0.0889)
		(layer "In11.Cu")
		(net "M_L_CPU1_SA_DQ<27>")
	)
	(arc
		(start 142.04188 -240.921794)
		(mid 142.324836 -240.997971)
		(end 142.607792 -240.921794)
		(width 0.0889)
		(layer "In11.Cu")
		(net "M_L_CPU1_SA_DQ<27>")
	)
	(arc
		(start 142.98168 -240.921794)
		(mid 143.264636 -240.997971)
		(end 143.547592 -240.921794)
		(width 0.0889)
		(layer "In11.Cu")
		(net "M_L_CPU1_SA_DQ<27>")
	)
	(arc
		(start 138.281918 -240.921794)
		(mid 138.564874 -240.997971)
		(end 138.84783 -240.921794)
		(width 0.0889)
		(layer "In11.Cu")
		(net "M_L_CPU1_SA_DQ<27>")
	)
	(arc
		(start 144.487646 -240.921794)
		(mid 144.669897 -240.871444)
		(end 144.853406 -240.916968)
		(width 0.0889)
		(layer "In11.Cu")
		(net "M_L_CPU1_SA_DQ<27>")
	)
	(arc
		(start 143.547592 -240.921794)
		(mid 143.729843 -240.871444)
		(end 143.913352 -240.916968)
		(width 0.0889)
		(layer "In11.Cu")
		(net "M_L_CPU1_SA_DQ<27>")
	)
	(arc
		(start 140.727684 -240.921794)
		(mid 140.909935 -240.871444)
		(end 141.093444 -240.916968)
		(width 0.0889)
		(layer "In11.Cu")
		(net "M_L_CPU1_SA_DQ<27>")
	)
	(arc
		(start 137.963148 -240.895632)
		(mid 138.12548 -240.872814)
		(end 138.281918 -240.921794)
		(width 0.0889)
		(layer "In11.Cu")
		(net "M_L_CPU1_SA_DQ<27>")
	)
	(arc
		(start 141.67612 -240.916968)
		(mid 141.859628 -240.871474)
		(end 142.04188 -240.921794)
		(width 0.0889)
		(layer "In11.Cu")
		(net "M_L_CPU1_SA_DQ<27>")
	)
	(segment
		(start 139.037822 -240.700306)
		(end 139.504674 -240.434368)
		(width 0.10668)
		(layer "F.Cu")
		(net "M_L_CPU1_SA_DQ<26>")
	)
	(segment
		(start 201.0537 -226.049586)
		(end 201.0537 -225.955352)
		(width 0.14478)
		(layer "In11.Cu")
		(net "M_L_CPU1_SA_DQ<26>")
	)
	(segment
		(start 186.10072 -226.660456)
		(end 188.673232 -226.660456)
		(width 0.14478)
		(layer "In11.Cu")
		(net "M_L_CPU1_SA_DQ<26>")
	)
	(segment
		(start 147.990814 -238.907574)
		(end 152.68067 -238.907574)
		(width 0.14478)
		(layer "In11.Cu")
		(net "M_L_CPU1_SA_DQ<26>")
	)
	(segment
		(start 145.144744 -240.060988)
		(end 145.570448 -240.060988)
		(width 0.0889)
		(layer "In11.Cu")
		(net "M_L_CPU1_SA_DQ<26>")
	)
	(segment
		(start 152.989026 -237.899956)
		(end 153.22423 -238.13516)
		(width 0.14478)
		(layer "In11.Cu")
		(net "M_L_CPU1_SA_DQ<26>")
	)
	(segment
		(start 152.595326 -238.293656)
		(end 152.595326 -238.063024)
		(width 0.14478)
		(layer "In11.Cu")
		(net "M_L_CPU1_SA_DQ<26>")
	)
	(segment
		(start 167.579548 -225.810318)
		(end 167.922702 -225.467164)
		(width 0.14478)
		(layer "In11.Cu")
		(net "M_L_CPU1_SA_DQ<26>")
	)
	(segment
		(start 155.19273 -236.397292)
		(end 155.19273 -236.16666)
		(width 0.14478)
		(layer "In11.Cu")
		(net "M_L_CPU1_SA_DQ<26>")
	)
	(segment
		(start 164.25418 -226.660456)
		(end 166.005764 -226.660456)
		(width 0.14478)
		(layer "In11.Cu")
		(net "M_L_CPU1_SA_DQ<26>")
	)
	(segment
		(start 158.508446 -232.184448)
		(end 159.405574 -232.184448)
		(width 0.14478)
		(layer "In11.Cu")
		(net "M_L_CPU1_SA_DQ<26>")
	)
	(segment
		(start 155.029662 -236.56036)
		(end 155.19273 -236.397292)
		(width 0.14478)
		(layer "In11.Cu")
		(net "M_L_CPU1_SA_DQ<26>")
	)
	(segment
		(start 153.61793 -237.74146)
		(end 153.382726 -237.506256)
		(width 0.14478)
		(layer "In11.Cu")
		(net "M_L_CPU1_SA_DQ<26>")
	)
	(segment
		(start 201.0537 -225.955352)
		(end 201.19848 -225.810572)
		(width 0.14478)
		(layer "In11.Cu")
		(net "M_L_CPU1_SA_DQ<26>")
	)
	(segment
		(start 170.29176 -225.810318)
		(end 171.141898 -226.660456)
		(width 0.14478)
		(layer "In11.Cu")
		(net "M_L_CPU1_SA_DQ<26>")
	)
	(segment
		(start 154.965654 -235.939584)
		(end 154.965654 -235.72724)
		(width 0.14478)
		(layer "In11.Cu")
		(net "M_L_CPU1_SA_DQ<26>")
	)
	(segment
		(start 168.580816 -225.810318)
		(end 168.895776 -225.810318)
		(width 0.14478)
		(layer "In11.Cu")
		(net "M_L_CPU1_SA_DQ<26>")
	)
	(segment
		(start 144.016984 -240.112042)
		(end 144.0307 -240.104168)
		(width 0.0889)
		(layer "In11.Cu")
		(net "M_L_CPU1_SA_DQ<26>")
	)
	(segment
		(start 159.405574 -232.184448)
		(end 164.00907 -227.580952)
		(width 0.14478)
		(layer "In11.Cu")
		(net "M_L_CPU1_SA_DQ<26>")
	)
	(segment
		(start 185.250836 -225.810572)
		(end 186.10072 -226.660456)
		(width 0.14478)
		(layer "In11.Cu")
		(net "M_L_CPU1_SA_DQ<26>")
	)
	(segment
		(start 196.810884 -225.810572)
		(end 200.357486 -225.810572)
		(width 0.14478)
		(layer "In11.Cu")
		(net "M_L_CPU1_SA_DQ<26>")
	)
	(segment
		(start 171.141898 -226.660456)
		(end 173.619668 -226.660456)
		(width 0.14478)
		(layer "In11.Cu")
		(net "M_L_CPU1_SA_DQ<26>")
	)
	(segment
		(start 192.846452 -225.810572)
		(end 193.696336 -226.660456)
		(width 0.14478)
		(layer "In11.Cu")
		(net "M_L_CPU1_SA_DQ<26>")
	)
	(segment
		(start 154.333194 -236.325156)
		(end 154.563826 -236.325156)
		(width 0.14478)
		(layer "In11.Cu")
		(net "M_L_CPU1_SA_DQ<26>")
	)
	(segment
		(start 200.357486 -225.810572)
		(end 200.502266 -225.955352)
		(width 0.14478)
		(layer "In11.Cu")
		(net "M_L_CPU1_SA_DQ<26>")
	)
	(segment
		(start 144.005046 -240.1189)
		(end 144.016984 -240.112042)
		(width 0.0889)
		(layer "In11.Cu")
		(net "M_L_CPU1_SA_DQ<26>")
	)
	(segment
		(start 178.82235 -226.660456)
		(end 180.987192 -226.660456)
		(width 0.14478)
		(layer "In11.Cu")
		(net "M_L_CPU1_SA_DQ<26>")
	)
	(segment
		(start 154.170126 -236.718856)
		(end 154.170126 -236.488224)
		(width 0.14478)
		(layer "In11.Cu")
		(net "M_L_CPU1_SA_DQ<26>")
	)
	(segment
		(start 153.61793 -237.972092)
		(end 153.61793 -237.74146)
		(width 0.14478)
		(layer "In11.Cu")
		(net "M_L_CPU1_SA_DQ<26>")
	)
	(segment
		(start 168.895776 -225.810318)
		(end 169.23893 -225.467164)
		(width 0.14478)
		(layer "In11.Cu")
		(net "M_L_CPU1_SA_DQ<26>")
	)
	(segment
		(start 153.382726 -237.275624)
		(end 153.545794 -237.112556)
		(width 0.14478)
		(layer "In11.Cu")
		(net "M_L_CPU1_SA_DQ<26>")
	)
	(segment
		(start 200.502266 -225.955352)
		(end 200.502266 -226.049586)
		(width 0.14478)
		(layer "In11.Cu")
		(net "M_L_CPU1_SA_DQ<26>")
	)
	(segment
		(start 164.00907 -226.905566)
		(end 164.25418 -226.660456)
		(width 0.14478)
		(layer "In11.Cu")
		(net "M_L_CPU1_SA_DQ<26>")
	)
	(segment
		(start 152.83053 -238.52886)
		(end 152.595326 -238.293656)
		(width 0.14478)
		(layer "In11.Cu")
		(net "M_L_CPU1_SA_DQ<26>")
	)
	(segment
		(start 201.19848 -225.810572)
		(end 201.723244 -225.810572)
		(width 0.14478)
		(layer "In11.Cu")
		(net "M_L_CPU1_SA_DQ<26>")
	)
	(segment
		(start 201.723244 -225.810572)
		(end 202.147932 -226.23526)
		(width 0.14478)
		(layer "In11.Cu")
		(net "M_L_CPU1_SA_DQ<26>")
	)
	(segment
		(start 142.503398 -240.106962)
		(end 142.51178 -240.111788)
		(width 0.0889)
		(layer "In11.Cu")
		(net "M_L_CPU1_SA_DQ<26>")
	)
	(segment
		(start 180.987192 -226.660456)
		(end 181.837076 -225.810572)
		(width 0.14478)
		(layer "In11.Cu")
		(net "M_L_CPU1_SA_DQ<26>")
	)
	(segment
		(start 153.545794 -237.112556)
		(end 153.776426 -237.112556)
		(width 0.14478)
		(layer "In11.Cu")
		(net "M_L_CPU1_SA_DQ<26>")
	)
	(segment
		(start 139.504674 -240.434368)
		(end 139.35075 -240.168938)
		(width 0.0889)
		(layer "In11.Cu")
		(net "M_L_CPU1_SA_DQ<26>")
	)
	(segment
		(start 189.523116 -225.810572)
		(end 192.846452 -225.810572)
		(width 0.14478)
		(layer "In11.Cu")
		(net "M_L_CPU1_SA_DQ<26>")
	)
	(segment
		(start 154.79903 -236.56036)
		(end 155.029662 -236.56036)
		(width 0.14478)
		(layer "In11.Cu")
		(net "M_L_CPU1_SA_DQ<26>")
	)
	(segment
		(start 146.12747 -239.503966)
		(end 147.23491 -239.503966)
		(width 0.0889)
		(layer "In11.Cu")
		(net "M_L_CPU1_SA_DQ<26>")
	)
	(segment
		(start 169.897044 -225.810318)
		(end 170.29176 -225.810318)
		(width 0.14478)
		(layer "In11.Cu")
		(net "M_L_CPU1_SA_DQ<26>")
	)
	(segment
		(start 188.673232 -226.660456)
		(end 189.523116 -225.810572)
		(width 0.14478)
		(layer "In11.Cu")
		(net "M_L_CPU1_SA_DQ<26>")
	)
	(segment
		(start 200.502266 -226.049586)
		(end 200.647046 -226.194366)
		(width 0.14478)
		(layer "In11.Cu")
		(net "M_L_CPU1_SA_DQ<26>")
	)
	(segment
		(start 200.90892 -226.194366)
		(end 201.0537 -226.049586)
		(width 0.14478)
		(layer "In11.Cu")
		(net "M_L_CPU1_SA_DQ<26>")
	)
	(segment
		(start 144.390618 -240.111788)
		(end 144.408652 -240.122456)
		(width 0.0889)
		(layer "In11.Cu")
		(net "M_L_CPU1_SA_DQ<26>")
	)
	(segment
		(start 143.077692 -240.111788)
		(end 143.086074 -240.106962)
		(width 0.0889)
		(layer "In11.Cu")
		(net "M_L_CPU1_SA_DQ<26>")
	)
	(segment
		(start 169.23893 -225.467164)
		(end 169.55389 -225.467164)
		(width 0.14478)
		(layer "In11.Cu")
		(net "M_L_CPU1_SA_DQ<26>")
	)
	(segment
		(start 139.35075 -240.168938)
		(end 139.373102 -240.085626)
		(width 0.0889)
		(layer "In11.Cu")
		(net "M_L_CPU1_SA_DQ<26>")
	)
	(segment
		(start 154.01163 -237.34776)
		(end 154.242262 -237.34776)
		(width 0.14478)
		(layer "In11.Cu")
		(net "M_L_CPU1_SA_DQ<26>")
	)
	(segment
		(start 166.855902 -225.810318)
		(end 167.579548 -225.810318)
		(width 0.14478)
		(layer "In11.Cu")
		(net "M_L_CPU1_SA_DQ<26>")
	)
	(segment
		(start 195.961 -226.660456)
		(end 196.810884 -225.810572)
		(width 0.14478)
		(layer "In11.Cu")
		(net "M_L_CPU1_SA_DQ<26>")
	)
	(segment
		(start 140.257784 -240.111788)
		(end 140.266166 -240.106962)
		(width 0.0889)
		(layer "In11.Cu")
		(net "M_L_CPU1_SA_DQ<26>")
	)
	(segment
		(start 153.454862 -238.13516)
		(end 153.61793 -237.972092)
		(width 0.14478)
		(layer "In11.Cu")
		(net "M_L_CPU1_SA_DQ<26>")
	)
	(segment
		(start 168.237662 -225.467164)
		(end 168.580816 -225.810318)
		(width 0.14478)
		(layer "In11.Cu")
		(net "M_L_CPU1_SA_DQ<26>")
	)
	(segment
		(start 154.170126 -236.488224)
		(end 154.333194 -236.325156)
		(width 0.14478)
		(layer "In11.Cu")
		(net "M_L_CPU1_SA_DQ<26>")
	)
	(segment
		(start 177.972466 -225.810572)
		(end 178.82235 -226.660456)
		(width 0.14478)
		(layer "In11.Cu")
		(net "M_L_CPU1_SA_DQ<26>")
	)
	(segment
		(start 152.758394 -237.899956)
		(end 152.989026 -237.899956)
		(width 0.14478)
		(layer "In11.Cu")
		(net "M_L_CPU1_SA_DQ<26>")
	)
	(segment
		(start 145.570448 -240.060988)
		(end 146.12747 -239.503966)
		(width 0.0889)
		(layer "In11.Cu")
		(net "M_L_CPU1_SA_DQ<26>")
	)
	(segment
		(start 154.965654 -235.72724)
		(end 158.508446 -232.184448)
		(width 0.14478)
		(layer "In11.Cu")
		(net "M_L_CPU1_SA_DQ<26>")
	)
	(segment
		(start 169.55389 -225.467164)
		(end 169.897044 -225.810318)
		(width 0.14478)
		(layer "In11.Cu")
		(net "M_L_CPU1_SA_DQ<26>")
	)
	(segment
		(start 200.647046 -226.194366)
		(end 200.90892 -226.194366)
		(width 0.14478)
		(layer "In11.Cu")
		(net "M_L_CPU1_SA_DQ<26>")
	)
	(segment
		(start 164.00907 -227.580952)
		(end 164.00907 -226.905566)
		(width 0.14478)
		(layer "In11.Cu")
		(net "M_L_CPU1_SA_DQ<26>")
	)
	(segment
		(start 154.242262 -237.34776)
		(end 154.40533 -237.184692)
		(width 0.14478)
		(layer "In11.Cu")
		(net "M_L_CPU1_SA_DQ<26>")
	)
	(segment
		(start 153.776426 -237.112556)
		(end 154.01163 -237.34776)
		(width 0.14478)
		(layer "In11.Cu")
		(net "M_L_CPU1_SA_DQ<26>")
	)
	(segment
		(start 154.40533 -236.95406)
		(end 154.170126 -236.718856)
		(width 0.14478)
		(layer "In11.Cu")
		(net "M_L_CPU1_SA_DQ<26>")
	)
	(segment
		(start 153.382726 -237.506256)
		(end 153.382726 -237.275624)
		(width 0.14478)
		(layer "In11.Cu")
		(net "M_L_CPU1_SA_DQ<26>")
	)
	(segment
		(start 174.469552 -225.810572)
		(end 177.972466 -225.810572)
		(width 0.14478)
		(layer "In11.Cu")
		(net "M_L_CPU1_SA_DQ<26>")
	)
	(segment
		(start 193.696336 -226.660456)
		(end 195.961 -226.660456)
		(width 0.14478)
		(layer "In11.Cu")
		(net "M_L_CPU1_SA_DQ<26>")
	)
	(segment
		(start 181.837076 -225.810572)
		(end 185.250836 -225.810572)
		(width 0.14478)
		(layer "In11.Cu")
		(net "M_L_CPU1_SA_DQ<26>")
	)
	(segment
		(start 173.619668 -226.660456)
		(end 174.469552 -225.810572)
		(width 0.14478)
		(layer "In11.Cu")
		(net "M_L_CPU1_SA_DQ<26>")
	)
	(segment
		(start 155.19273 -236.16666)
		(end 154.965654 -235.939584)
		(width 0.14478)
		(layer "In11.Cu")
		(net "M_L_CPU1_SA_DQ<26>")
	)
	(segment
		(start 147.23491 -239.503966)
		(end 147.831302 -238.907574)
		(width 0.0889)
		(layer "In11.Cu")
		(net "M_L_CPU1_SA_DQ<26>")
	)
	(segment
		(start 152.83053 -238.757714)
		(end 152.83053 -238.52886)
		(width 0.14478)
		(layer "In11.Cu")
		(net "M_L_CPU1_SA_DQ<26>")
	)
	(segment
		(start 152.595326 -238.063024)
		(end 152.758394 -237.899956)
		(width 0.14478)
		(layer "In11.Cu")
		(net "M_L_CPU1_SA_DQ<26>")
	)
	(segment
		(start 154.563826 -236.325156)
		(end 154.79903 -236.56036)
		(width 0.14478)
		(layer "In11.Cu")
		(net "M_L_CPU1_SA_DQ<26>")
	)
	(segment
		(start 154.40533 -237.184692)
		(end 154.40533 -236.95406)
		(width 0.14478)
		(layer "In11.Cu")
		(net "M_L_CPU1_SA_DQ<26>")
	)
	(segment
		(start 167.922702 -225.467164)
		(end 168.237662 -225.467164)
		(width 0.14478)
		(layer "In11.Cu")
		(net "M_L_CPU1_SA_DQ<26>")
	)
	(segment
		(start 166.005764 -226.660456)
		(end 166.855902 -225.810318)
		(width 0.14478)
		(layer "In11.Cu")
		(net "M_L_CPU1_SA_DQ<26>")
	)
	(segment
		(start 147.831302 -238.907574)
		(end 147.990814 -238.907574)
		(width 0.0889)
		(layer "In11.Cu")
		(net "M_L_CPU1_SA_DQ<26>")
	)
	(segment
		(start 153.22423 -238.13516)
		(end 153.454862 -238.13516)
		(width 0.14478)
		(layer "In11.Cu")
		(net "M_L_CPU1_SA_DQ<26>")
	)
	(segment
		(start 152.68067 -238.907574)
		(end 152.83053 -238.757714)
		(width 0.14478)
		(layer "In11.Cu")
		(net "M_L_CPU1_SA_DQ<26>")
	)
	(arc
		(start 140.266166 -240.106962)
		(mid 140.449674 -240.061468)
		(end 140.631926 -240.111788)
		(width 0.0889)
		(layer "In11.Cu")
		(net "M_L_CPU1_SA_DQ<26>")
	)
	(arc
		(start 144.408652 -240.122456)
		(mid 144.684347 -240.188299)
		(end 144.957292 -240.111788)
		(width 0.0889)
		(layer "In11.Cu")
		(net "M_L_CPU1_SA_DQ<26>")
	)
	(arc
		(start 143.086074 -240.106962)
		(mid 143.269582 -240.061468)
		(end 143.451834 -240.111788)
		(width 0.0889)
		(layer "In11.Cu")
		(net "M_L_CPU1_SA_DQ<26>")
	)
	(arc
		(start 144.0307 -240.104168)
		(mid 144.21163 -240.06169)
		(end 144.390618 -240.111788)
		(width 0.0889)
		(layer "In11.Cu")
		(net "M_L_CPU1_SA_DQ<26>")
	)
	(arc
		(start 142.51178 -240.111788)
		(mid 142.794736 -240.187965)
		(end 143.077692 -240.111788)
		(width 0.0889)
		(layer "In11.Cu")
		(net "M_L_CPU1_SA_DQ<26>")
	)
	(arc
		(start 143.451834 -240.111788)
		(mid 143.727512 -240.187918)
		(end 144.005046 -240.1189)
		(width 0.0889)
		(layer "In11.Cu")
		(net "M_L_CPU1_SA_DQ<26>")
	)
	(arc
		(start 141.571726 -240.111788)
		(mid 141.854682 -240.187965)
		(end 142.137638 -240.111788)
		(width 0.0889)
		(layer "In11.Cu")
		(net "M_L_CPU1_SA_DQ<26>")
	)
	(arc
		(start 139.373102 -240.085626)
		(mid 139.535434 -240.062808)
		(end 139.691872 -240.111788)
		(width 0.0889)
		(layer "In11.Cu")
		(net "M_L_CPU1_SA_DQ<26>")
	)
	(arc
		(start 142.137638 -240.111788)
		(mid 142.319889 -240.061438)
		(end 142.503398 -240.106962)
		(width 0.0889)
		(layer "In11.Cu")
		(net "M_L_CPU1_SA_DQ<26>")
	)
	(arc
		(start 139.691872 -240.111788)
		(mid 139.974828 -240.187965)
		(end 140.257784 -240.111788)
		(width 0.0889)
		(layer "In11.Cu")
		(net "M_L_CPU1_SA_DQ<26>")
	)
	(arc
		(start 140.631926 -240.111788)
		(mid 140.914882 -240.187965)
		(end 141.197838 -240.111788)
		(width 0.0889)
		(layer "In11.Cu")
		(net "M_L_CPU1_SA_DQ<26>")
	)
	(arc
		(start 144.957292 -240.111788)
		(mid 145.047655 -240.073978)
		(end 145.144744 -240.060988)
		(width 0.0889)
		(layer "In11.Cu")
		(net "M_L_CPU1_SA_DQ<26>")
	)
	(arc
		(start 141.197838 -240.111788)
		(mid 141.384782 -240.061533)
		(end 141.571726 -240.111788)
		(width 0.0889)
		(layer "In11.Cu")
		(net "M_L_CPU1_SA_DQ<26>")
	)
	(segment
		(start 137.157968 -240.700306)
		(end 137.62482 -240.434368)
		(width 0.10668)
		(layer "F.Cu")
		(net "M_L_CPU1_SA_DQ<25>")
	)
	(segment
		(start 143.077692 -240.756948)
		(end 143.086074 -240.761774)
		(width 0.0889)
		(layer "In11.Cu")
		(net "M_L_CPU1_SA_DQ<25>")
	)
	(segment
		(start 204.111606 -226.660456)
		(end 206.248 -227.085398)
		(width 0.14478)
		(layer "In11.Cu")
		(net "M_L_CPU1_SA_DQ<25>")
	)
	(segment
		(start 195.533264 -227.51034)
		(end 197.585076 -226.660456)
		(width 0.14478)
		(layer "In11.Cu")
		(net "M_L_CPU1_SA_DQ<25>")
	)
	(segment
		(start 174.567596 -226.660456)
		(end 177.172874 -226.660456)
		(width 0.14478)
		(layer "In11.Cu")
		(net "M_L_CPU1_SA_DQ<25>")
	)
	(segment
		(start 182.43169 -226.660456)
		(end 184.646824 -226.660456)
		(width 0.14478)
		(layer "In11.Cu")
		(net "M_L_CPU1_SA_DQ<25>")
	)
	(segment
		(start 197.585076 -226.660456)
		(end 204.111606 -226.660456)
		(width 0.14478)
		(layer "In11.Cu")
		(net "M_L_CPU1_SA_DQ<25>")
	)
	(segment
		(start 138.743436 -240.761774)
		(end 138.751818 -240.756948)
		(width 0.0889)
		(layer "In11.Cu")
		(net "M_L_CPU1_SA_DQ<25>")
	)
	(segment
		(start 188.105796 -227.51034)
		(end 190.157608 -226.660456)
		(width 0.14478)
		(layer "In11.Cu")
		(net "M_L_CPU1_SA_DQ<25>")
	)
	(segment
		(start 186.698636 -227.51034)
		(end 188.105796 -227.51034)
		(width 0.14478)
		(layer "In11.Cu")
		(net "M_L_CPU1_SA_DQ<25>")
	)
	(segment
		(start 140.257784 -240.756948)
		(end 140.266166 -240.761774)
		(width 0.0889)
		(layer "In11.Cu")
		(net "M_L_CPU1_SA_DQ<25>")
	)
	(segment
		(start 155.64739 -236.58576)
		(end 155.64739 -235.688632)
		(width 0.14478)
		(layer "In11.Cu")
		(net "M_L_CPU1_SA_DQ<25>")
	)
	(segment
		(start 177.172874 -226.660456)
		(end 179.224686 -227.51034)
		(width 0.14478)
		(layer "In11.Cu")
		(net "M_L_CPU1_SA_DQ<25>")
	)
	(segment
		(start 194.374008 -227.51034)
		(end 195.533264 -227.51034)
		(width 0.14478)
		(layer "In11.Cu")
		(net "M_L_CPU1_SA_DQ<25>")
	)
	(segment
		(start 171.117514 -227.51034)
		(end 173.717712 -227.51034)
		(width 0.14478)
		(layer "In11.Cu")
		(net "M_L_CPU1_SA_DQ<25>")
	)
	(segment
		(start 139.31773 -240.756948)
		(end 139.326112 -240.761774)
		(width 0.0889)
		(layer "In11.Cu")
		(net "M_L_CPU1_SA_DQ<25>")
	)
	(segment
		(start 144.017746 -240.756948)
		(end 144.026128 -240.761774)
		(width 0.0889)
		(layer "In11.Cu")
		(net "M_L_CPU1_SA_DQ<25>")
	)
	(segment
		(start 145.408396 -240.69802)
		(end 145.820384 -240.286286)
		(width 0.0889)
		(layer "In11.Cu")
		(net "M_L_CPU1_SA_DQ<25>")
	)
	(segment
		(start 152.870916 -239.362234)
		(end 155.64739 -236.58576)
		(width 0.14478)
		(layer "In11.Cu")
		(net "M_L_CPU1_SA_DQ<25>")
	)
	(segment
		(start 137.778744 -240.699798)
		(end 137.874756 -240.725198)
		(width 0.0889)
		(layer "In11.Cu")
		(net "M_L_CPU1_SA_DQ<25>")
	)
	(segment
		(start 146.93773 -240.286286)
		(end 147.861782 -239.362234)
		(width 0.0889)
		(layer "In11.Cu")
		(net "M_L_CPU1_SA_DQ<25>")
	)
	(segment
		(start 170.26763 -226.660456)
		(end 171.117514 -227.51034)
		(width 0.14478)
		(layer "In11.Cu")
		(net "M_L_CPU1_SA_DQ<25>")
	)
	(segment
		(start 147.861782 -239.362234)
		(end 148.012404 -239.362234)
		(width 0.0889)
		(layer "In11.Cu")
		(net "M_L_CPU1_SA_DQ<25>")
	)
	(segment
		(start 144.9578 -240.756948)
		(end 144.966182 -240.761774)
		(width 0.0889)
		(layer "In11.Cu")
		(net "M_L_CPU1_SA_DQ<25>")
	)
	(segment
		(start 137.62482 -240.434368)
		(end 137.778744 -240.699798)
		(width 0.0889)
		(layer "In11.Cu")
		(net "M_L_CPU1_SA_DQ<25>")
	)
	(segment
		(start 158.696914 -232.639108)
		(end 159.594042 -232.639108)
		(width 0.14478)
		(layer "In11.Cu")
		(net "M_L_CPU1_SA_DQ<25>")
	)
	(segment
		(start 155.64739 -235.688632)
		(end 158.696914 -232.639108)
		(width 0.14478)
		(layer "In11.Cu")
		(net "M_L_CPU1_SA_DQ<25>")
	)
	(segment
		(start 145.820384 -240.286286)
		(end 146.93773 -240.286286)
		(width 0.0889)
		(layer "In11.Cu")
		(net "M_L_CPU1_SA_DQ<25>")
	)
	(segment
		(start 159.594042 -232.639108)
		(end 164.72281 -227.51034)
		(width 0.14478)
		(layer "In11.Cu")
		(net "M_L_CPU1_SA_DQ<25>")
	)
	(segment
		(start 142.503398 -240.761774)
		(end 142.51178 -240.756948)
		(width 0.0889)
		(layer "In11.Cu")
		(net "M_L_CPU1_SA_DQ<25>")
	)
	(segment
		(start 190.157608 -226.660456)
		(end 192.322196 -226.660456)
		(width 0.14478)
		(layer "In11.Cu")
		(net "M_L_CPU1_SA_DQ<25>")
	)
	(segment
		(start 184.646824 -226.660456)
		(end 186.698636 -227.51034)
		(width 0.14478)
		(layer "In11.Cu")
		(net "M_L_CPU1_SA_DQ<25>")
	)
	(segment
		(start 165.91661 -227.51034)
		(end 166.766494 -226.660456)
		(width 0.14478)
		(layer "In11.Cu")
		(net "M_L_CPU1_SA_DQ<25>")
	)
	(segment
		(start 192.322196 -226.660456)
		(end 194.374008 -227.51034)
		(width 0.14478)
		(layer "In11.Cu")
		(net "M_L_CPU1_SA_DQ<25>")
	)
	(segment
		(start 148.012404 -239.362234)
		(end 152.870916 -239.362234)
		(width 0.14478)
		(layer "In11.Cu")
		(net "M_L_CPU1_SA_DQ<25>")
	)
	(segment
		(start 173.717712 -227.51034)
		(end 174.567596 -226.660456)
		(width 0.14478)
		(layer "In11.Cu")
		(net "M_L_CPU1_SA_DQ<25>")
	)
	(segment
		(start 166.766494 -226.660456)
		(end 170.26763 -226.660456)
		(width 0.14478)
		(layer "In11.Cu")
		(net "M_L_CPU1_SA_DQ<25>")
	)
	(segment
		(start 179.224686 -227.51034)
		(end 180.379878 -227.51034)
		(width 0.14478)
		(layer "In11.Cu")
		(net "M_L_CPU1_SA_DQ<25>")
	)
	(segment
		(start 180.379878 -227.51034)
		(end 182.43169 -226.660456)
		(width 0.14478)
		(layer "In11.Cu")
		(net "M_L_CPU1_SA_DQ<25>")
	)
	(segment
		(start 164.72281 -227.51034)
		(end 165.91661 -227.51034)
		(width 0.14478)
		(layer "In11.Cu")
		(net "M_L_CPU1_SA_DQ<25>")
	)
	(arc
		(start 139.326112 -240.761774)
		(mid 139.50962 -240.807268)
		(end 139.691872 -240.756948)
		(width 0.0889)
		(layer "In11.Cu")
		(net "M_L_CPU1_SA_DQ<25>")
	)
	(arc
		(start 138.377676 -240.756948)
		(mid 138.559927 -240.807298)
		(end 138.743436 -240.761774)
		(width 0.0889)
		(layer "In11.Cu")
		(net "M_L_CPU1_SA_DQ<25>")
	)
	(arc
		(start 143.451834 -240.756948)
		(mid 143.73479 -240.680771)
		(end 144.017746 -240.756948)
		(width 0.0889)
		(layer "In11.Cu")
		(net "M_L_CPU1_SA_DQ<25>")
	)
	(arc
		(start 139.691872 -240.756948)
		(mid 139.974828 -240.680771)
		(end 140.257784 -240.756948)
		(width 0.0889)
		(layer "In11.Cu")
		(net "M_L_CPU1_SA_DQ<25>")
	)
	(arc
		(start 138.751818 -240.756948)
		(mid 139.034774 -240.680771)
		(end 139.31773 -240.756948)
		(width 0.0889)
		(layer "In11.Cu")
		(net "M_L_CPU1_SA_DQ<25>")
	)
	(arc
		(start 144.966182 -240.761774)
		(mid 145.14969 -240.807268)
		(end 145.331942 -240.756948)
		(width 0.0889)
		(layer "In11.Cu")
		(net "M_L_CPU1_SA_DQ<25>")
	)
	(arc
		(start 137.874756 -240.725198)
		(mid 138.129964 -240.681721)
		(end 138.377676 -240.756948)
		(width 0.0889)
		(layer "In11.Cu")
		(net "M_L_CPU1_SA_DQ<25>")
	)
	(arc
		(start 144.391888 -240.756948)
		(mid 144.674844 -240.680771)
		(end 144.9578 -240.756948)
		(width 0.0889)
		(layer "In11.Cu")
		(net "M_L_CPU1_SA_DQ<25>")
	)
	(arc
		(start 142.137638 -240.756948)
		(mid 142.319889 -240.807298)
		(end 142.503398 -240.761774)
		(width 0.0889)
		(layer "In11.Cu")
		(net "M_L_CPU1_SA_DQ<25>")
	)
	(arc
		(start 141.197838 -240.756948)
		(mid 141.384782 -240.807203)
		(end 141.571726 -240.756948)
		(width 0.0889)
		(layer "In11.Cu")
		(net "M_L_CPU1_SA_DQ<25>")
	)
	(arc
		(start 143.086074 -240.761774)
		(mid 143.269582 -240.807268)
		(end 143.451834 -240.756948)
		(width 0.0889)
		(layer "In11.Cu")
		(net "M_L_CPU1_SA_DQ<25>")
	)
	(arc
		(start 140.266166 -240.761774)
		(mid 140.449674 -240.807268)
		(end 140.631926 -240.756948)
		(width 0.0889)
		(layer "In11.Cu")
		(net "M_L_CPU1_SA_DQ<25>")
	)
	(arc
		(start 141.571726 -240.756948)
		(mid 141.854682 -240.680771)
		(end 142.137638 -240.756948)
		(width 0.0889)
		(layer "In11.Cu")
		(net "M_L_CPU1_SA_DQ<25>")
	)
	(arc
		(start 142.51178 -240.756948)
		(mid 142.794736 -240.680771)
		(end 143.077692 -240.756948)
		(width 0.0889)
		(layer "In11.Cu")
		(net "M_L_CPU1_SA_DQ<25>")
	)
	(arc
		(start 140.631926 -240.756948)
		(mid 140.914882 -240.680771)
		(end 141.197838 -240.756948)
		(width 0.0889)
		(layer "In11.Cu")
		(net "M_L_CPU1_SA_DQ<25>")
	)
	(arc
		(start 145.331942 -240.756948)
		(mid 145.372087 -240.729972)
		(end 145.408396 -240.69802)
		(width 0.0889)
		(layer "In11.Cu")
		(net "M_L_CPU1_SA_DQ<25>")
	)
	(arc
		(start 144.026128 -240.761774)
		(mid 144.209636 -240.807268)
		(end 144.391888 -240.756948)
		(width 0.0889)
		(layer "In11.Cu")
		(net "M_L_CPU1_SA_DQ<25>")
	)
	(segment
		(start 138.567922 -239.8903)
		(end 139.034774 -239.624362)
		(width 0.10668)
		(layer "F.Cu")
		(net "M_L_CPU1_SA_DQ<24>")
	)
	(segment
		(start 141.667738 -239.946942)
		(end 141.67612 -239.951768)
		(width 0.0889)
		(layer "In11.Cu")
		(net "M_L_CPU1_SA_DQ<24>")
	)
	(segment
		(start 159.217106 -231.729788)
		(end 163.55314 -227.393754)
		(width 0.14478)
		(layer "In11.Cu")
		(net "M_L_CPU1_SA_DQ<24>")
	)
	(segment
		(start 144.48663 -239.946942)
		(end 144.498314 -239.9538)
		(width 0.0889)
		(layer "In11.Cu")
		(net "M_L_CPU1_SA_DQ<24>")
	)
	(segment
		(start 139.188698 -239.889792)
		(end 139.28471 -239.915192)
		(width 0.0889)
		(layer "In11.Cu")
		(net "M_L_CPU1_SA_DQ<24>")
	)
	(segment
		(start 193.5861 -225.810318)
		(end 196.086984 -225.810318)
		(width 0.14478)
		(layer "In11.Cu")
		(net "M_L_CPU1_SA_DQ<24>")
	)
	(segment
		(start 177.972466 -224.960434)
		(end 178.82235 -225.810318)
		(width 0.14478)
		(layer "In11.Cu")
		(net "M_L_CPU1_SA_DQ<24>")
	)
	(segment
		(start 141.093444 -239.951768)
		(end 141.101826 -239.946942)
		(width 0.0889)
		(layer "In11.Cu")
		(net "M_L_CPU1_SA_DQ<24>")
	)
	(segment
		(start 164.438838 -225.810318)
		(end 165.820598 -225.810318)
		(width 0.14478)
		(layer "In11.Cu")
		(net "M_L_CPU1_SA_DQ<24>")
	)
	(segment
		(start 143.92148 -239.946688)
		(end 143.933418 -239.93983)
		(width 0.0889)
		(layer "In11.Cu")
		(net "M_L_CPU1_SA_DQ<24>")
	)
	(segment
		(start 151.562308 -238.452914)
		(end 158.285434 -231.729788)
		(width 0.14478)
		(layer "In11.Cu")
		(net "M_L_CPU1_SA_DQ<24>")
	)
	(segment
		(start 145.144744 -239.870488)
		(end 145.491454 -239.870488)
		(width 0.0889)
		(layer "In11.Cu")
		(net "M_L_CPU1_SA_DQ<24>")
	)
	(segment
		(start 147.10537 -239.247426)
		(end 147.899882 -238.452914)
		(width 0.0889)
		(layer "In11.Cu")
		(net "M_L_CPU1_SA_DQ<24>")
	)
	(segment
		(start 185.250836 -224.960434)
		(end 186.10072 -225.810318)
		(width 0.14478)
		(layer "In11.Cu")
		(net "M_L_CPU1_SA_DQ<24>")
	)
	(segment
		(start 145.491454 -239.870488)
		(end 146.114516 -239.247426)
		(width 0.0889)
		(layer "In11.Cu")
		(net "M_L_CPU1_SA_DQ<24>")
	)
	(segment
		(start 178.82235 -225.810318)
		(end 180.997352 -225.810318)
		(width 0.14478)
		(layer "In11.Cu")
		(net "M_L_CPU1_SA_DQ<24>")
	)
	(segment
		(start 163.55314 -227.393754)
		(end 163.55314 -226.696016)
		(width 0.14478)
		(layer "In11.Cu")
		(net "M_L_CPU1_SA_DQ<24>")
	)
	(segment
		(start 196.086984 -225.810318)
		(end 196.936868 -224.960434)
		(width 0.14478)
		(layer "In11.Cu")
		(net "M_L_CPU1_SA_DQ<24>")
	)
	(segment
		(start 188.673232 -225.810318)
		(end 189.523116 -224.960434)
		(width 0.14478)
		(layer "In11.Cu")
		(net "M_L_CPU1_SA_DQ<24>")
	)
	(segment
		(start 146.114516 -239.247426)
		(end 147.10537 -239.247426)
		(width 0.0889)
		(layer "In11.Cu")
		(net "M_L_CPU1_SA_DQ<24>")
	)
	(segment
		(start 189.523116 -224.960434)
		(end 192.736216 -224.960434)
		(width 0.14478)
		(layer "In11.Cu")
		(net "M_L_CPU1_SA_DQ<24>")
	)
	(segment
		(start 163.55314 -226.696016)
		(end 164.438838 -225.810318)
		(width 0.14478)
		(layer "In11.Cu")
		(net "M_L_CPU1_SA_DQ<24>")
	)
	(segment
		(start 192.736216 -224.960434)
		(end 193.5861 -225.810318)
		(width 0.14478)
		(layer "In11.Cu")
		(net "M_L_CPU1_SA_DQ<24>")
	)
	(segment
		(start 158.285434 -231.729788)
		(end 159.217106 -231.729788)
		(width 0.14478)
		(layer "In11.Cu")
		(net "M_L_CPU1_SA_DQ<24>")
	)
	(segment
		(start 174.448724 -224.960434)
		(end 177.972466 -224.960434)
		(width 0.14478)
		(layer "In11.Cu")
		(net "M_L_CPU1_SA_DQ<24>")
	)
	(segment
		(start 186.10072 -225.810318)
		(end 188.673232 -225.810318)
		(width 0.14478)
		(layer "In11.Cu")
		(net "M_L_CPU1_SA_DQ<24>")
	)
	(segment
		(start 170.98772 -225.810318)
		(end 173.59884 -225.810318)
		(width 0.14478)
		(layer "In11.Cu")
		(net "M_L_CPU1_SA_DQ<24>")
	)
	(segment
		(start 147.899882 -238.452914)
		(end 148.058886 -238.452914)
		(width 0.0889)
		(layer "In11.Cu")
		(net "M_L_CPU1_SA_DQ<24>")
	)
	(segment
		(start 165.820598 -225.810318)
		(end 166.670482 -224.960434)
		(width 0.14478)
		(layer "In11.Cu")
		(net "M_L_CPU1_SA_DQ<24>")
	)
	(segment
		(start 170.137836 -224.960434)
		(end 170.98772 -225.810318)
		(width 0.14478)
		(layer "In11.Cu")
		(net "M_L_CPU1_SA_DQ<24>")
	)
	(segment
		(start 173.59884 -225.810318)
		(end 174.448724 -224.960434)
		(width 0.14478)
		(layer "In11.Cu")
		(net "M_L_CPU1_SA_DQ<24>")
	)
	(segment
		(start 166.670482 -224.960434)
		(end 170.137836 -224.960434)
		(width 0.14478)
		(layer "In11.Cu")
		(net "M_L_CPU1_SA_DQ<24>")
	)
	(segment
		(start 139.034774 -239.624362)
		(end 139.188698 -239.889792)
		(width 0.0889)
		(layer "In11.Cu")
		(net "M_L_CPU1_SA_DQ<24>")
	)
	(segment
		(start 140.15339 -239.951768)
		(end 140.161772 -239.946942)
		(width 0.0889)
		(layer "In11.Cu")
		(net "M_L_CPU1_SA_DQ<24>")
	)
	(segment
		(start 196.936868 -224.960434)
		(end 205.823058 -224.960434)
		(width 0.14478)
		(layer "In11.Cu")
		(net "M_L_CPU1_SA_DQ<24>")
	)
	(segment
		(start 205.823058 -224.960434)
		(end 206.248 -225.385376)
		(width 0.14478)
		(layer "In11.Cu")
		(net "M_L_CPU1_SA_DQ<24>")
	)
	(segment
		(start 143.905224 -239.956086)
		(end 143.92148 -239.946688)
		(width 0.0889)
		(layer "In11.Cu")
		(net "M_L_CPU1_SA_DQ<24>")
	)
	(segment
		(start 180.997352 -225.810318)
		(end 181.847236 -224.960434)
		(width 0.14478)
		(layer "In11.Cu")
		(net "M_L_CPU1_SA_DQ<24>")
	)
	(segment
		(start 181.847236 -224.960434)
		(end 185.250836 -224.960434)
		(width 0.14478)
		(layer "In11.Cu")
		(net "M_L_CPU1_SA_DQ<24>")
	)
	(segment
		(start 148.058886 -238.452914)
		(end 151.562308 -238.452914)
		(width 0.14478)
		(layer "In11.Cu")
		(net "M_L_CPU1_SA_DQ<24>")
	)
	(arc
		(start 139.28471 -239.915192)
		(mid 139.539918 -239.871715)
		(end 139.78763 -239.946942)
		(width 0.0889)
		(layer "In11.Cu")
		(net "M_L_CPU1_SA_DQ<24>")
	)
	(arc
		(start 142.98168 -239.946942)
		(mid 143.264636 -239.870765)
		(end 143.547592 -239.946942)
		(width 0.0889)
		(layer "In11.Cu")
		(net "M_L_CPU1_SA_DQ<24>")
	)
	(arc
		(start 143.933418 -239.93983)
		(mid 144.210952 -239.870849)
		(end 144.48663 -239.946942)
		(width 0.0889)
		(layer "In11.Cu")
		(net "M_L_CPU1_SA_DQ<24>")
	)
	(arc
		(start 143.547592 -239.946942)
		(mid 143.725242 -239.997202)
		(end 143.905224 -239.956086)
		(width 0.0889)
		(layer "In11.Cu")
		(net "M_L_CPU1_SA_DQ<24>")
	)
	(arc
		(start 141.101826 -239.946942)
		(mid 141.384782 -239.870765)
		(end 141.667738 -239.946942)
		(width 0.0889)
		(layer "In11.Cu")
		(net "M_L_CPU1_SA_DQ<24>")
	)
	(arc
		(start 144.498314 -239.9538)
		(mid 144.680569 -239.997453)
		(end 144.861026 -239.946942)
		(width 0.0889)
		(layer "In11.Cu")
		(net "M_L_CPU1_SA_DQ<24>")
	)
	(arc
		(start 141.67612 -239.951768)
		(mid 141.859628 -239.997262)
		(end 142.04188 -239.946942)
		(width 0.0889)
		(layer "In11.Cu")
		(net "M_L_CPU1_SA_DQ<24>")
	)
	(arc
		(start 140.727684 -239.946942)
		(mid 140.909935 -239.997292)
		(end 141.093444 -239.951768)
		(width 0.0889)
		(layer "In11.Cu")
		(net "M_L_CPU1_SA_DQ<24>")
	)
	(arc
		(start 139.78763 -239.946942)
		(mid 139.969881 -239.997292)
		(end 140.15339 -239.951768)
		(width 0.0889)
		(layer "In11.Cu")
		(net "M_L_CPU1_SA_DQ<24>")
	)
	(arc
		(start 144.861026 -239.946942)
		(mid 144.997819 -239.88992)
		(end 145.144744 -239.870488)
		(width 0.0889)
		(layer "In11.Cu")
		(net "M_L_CPU1_SA_DQ<24>")
	)
	(arc
		(start 140.161772 -239.946942)
		(mid 140.444728 -239.870765)
		(end 140.727684 -239.946942)
		(width 0.0889)
		(layer "In11.Cu")
		(net "M_L_CPU1_SA_DQ<24>")
	)
	(arc
		(start 142.04188 -239.946942)
		(mid 142.324836 -239.870765)
		(end 142.607792 -239.946942)
		(width 0.0889)
		(layer "In11.Cu")
		(net "M_L_CPU1_SA_DQ<24>")
	)
	(arc
		(start 142.607792 -239.946942)
		(mid 142.794736 -239.997197)
		(end 142.98168 -239.946942)
		(width 0.0889)
		(layer "In11.Cu")
		(net "M_L_CPU1_SA_DQ<24>")
	)
	(segment
		(start 137.627868 -239.8903)
		(end 138.09472 -239.624362)
		(width 0.10668)
		(layer "F.Cu")
		(net "M_L_CPU1_SA_DQ<23>")
	)
	(segment
		(start 159.796226 -229.425754)
		(end 159.959294 -229.262686)
		(width 0.14478)
		(layer "In11.Cu")
		(net "M_L_CPU1_SA_DQ<23>")
	)
	(segment
		(start 161.198052 -228.695758)
		(end 161.428684 -228.695758)
		(width 0.14478)
		(layer "In11.Cu")
		(net "M_L_CPU1_SA_DQ<23>")
	)
	(segment
		(start 193.54546 -224.960434)
		(end 196.042788 -224.960434)
		(width 0.14478)
		(layer "In11.Cu")
		(net "M_L_CPU1_SA_DQ<23>")
	)
	(segment
		(start 167.443658 -223.790764)
		(end 167.76319 -224.110296)
		(width 0.14478)
		(layer "In11.Cu")
		(net "M_L_CPU1_SA_DQ<23>")
	)
	(segment
		(start 171.314872 -224.960434)
		(end 173.494192 -224.960434)
		(width 0.14478)
		(layer "In11.Cu")
		(net "M_L_CPU1_SA_DQ<23>")
	)
	(segment
		(start 162.216084 -227.908358)
		(end 162.379406 -227.745036)
		(width 0.14478)
		(layer "In11.Cu")
		(net "M_L_CPU1_SA_DQ<23>")
	)
	(segment
		(start 168.876218 -224.110296)
		(end 169.1132 -224.110296)
		(width 0.14478)
		(layer "In11.Cu")
		(net "M_L_CPU1_SA_DQ<23>")
	)
	(segment
		(start 159.229552 -230.664512)
		(end 159.008826 -230.443786)
		(width 0.14478)
		(layer "In11.Cu")
		(net "M_L_CPU1_SA_DQ<23>")
	)
	(segment
		(start 159.623252 -230.270558)
		(end 159.853884 -230.270558)
		(width 0.14478)
		(layer "In11.Cu")
		(net "M_L_CPU1_SA_DQ<23>")
	)
	(segment
		(start 137.940796 -239.358932)
		(end 137.963148 -239.27562)
		(width 0.0889)
		(layer "In11.Cu")
		(net "M_L_CPU1_SA_DQ<23>")
	)
	(segment
		(start 162.158426 -227.294186)
		(end 162.158426 -227.063554)
		(width 0.14478)
		(layer "In11.Cu")
		(net "M_L_CPU1_SA_DQ<23>")
	)
	(segment
		(start 162.158426 -227.063554)
		(end 164.261546 -224.960434)
		(width 0.14478)
		(layer "In11.Cu")
		(net "M_L_CPU1_SA_DQ<23>")
	)
	(segment
		(start 161.428684 -228.695758)
		(end 161.592006 -228.532436)
		(width 0.14478)
		(layer "In11.Cu")
		(net "M_L_CPU1_SA_DQ<23>")
	)
	(segment
		(start 185.250836 -224.11055)
		(end 186.10072 -224.960434)
		(width 0.14478)
		(layer "In11.Cu")
		(net "M_L_CPU1_SA_DQ<23>")
	)
	(segment
		(start 159.008826 -230.443786)
		(end 159.008826 -230.213154)
		(width 0.14478)
		(layer "In11.Cu")
		(net "M_L_CPU1_SA_DQ<23>")
	)
	(segment
		(start 144.862042 -239.301782)
		(end 144.876774 -239.310418)
		(width 0.0889)
		(layer "In11.Cu")
		(net "M_L_CPU1_SA_DQ<23>")
	)
	(segment
		(start 147.48383 -238.487966)
		(end 147.48383 -238.287306)
		(width 0.0889)
		(layer "In11.Cu")
		(net "M_L_CPU1_SA_DQ<23>")
	)
	(segment
		(start 138.09472 -239.624362)
		(end 137.940796 -239.358932)
		(width 0.0889)
		(layer "In11.Cu")
		(net "M_L_CPU1_SA_DQ<23>")
	)
	(segment
		(start 186.10072 -224.960434)
		(end 188.673232 -224.960434)
		(width 0.14478)
		(layer "In11.Cu")
		(net "M_L_CPU1_SA_DQ<23>")
	)
	(segment
		(start 165.591236 -224.960434)
		(end 166.441374 -224.110296)
		(width 0.14478)
		(layer "In11.Cu")
		(net "M_L_CPU1_SA_DQ<23>")
	)
	(segment
		(start 169.989246 -224.110296)
		(end 170.464734 -224.110296)
		(width 0.14478)
		(layer "In11.Cu")
		(net "M_L_CPU1_SA_DQ<23>")
	)
	(segment
		(start 160.410652 -229.483158)
		(end 160.641284 -229.483158)
		(width 0.14478)
		(layer "In11.Cu")
		(net "M_L_CPU1_SA_DQ<23>")
	)
	(segment
		(start 161.371026 -228.081586)
		(end 161.371026 -227.850954)
		(width 0.14478)
		(layer "In11.Cu")
		(net "M_L_CPU1_SA_DQ<23>")
	)
	(segment
		(start 167.206676 -223.790764)
		(end 167.443658 -223.790764)
		(width 0.14478)
		(layer "In11.Cu")
		(net "M_L_CPU1_SA_DQ<23>")
	)
	(segment
		(start 158.384494 -230.837486)
		(end 158.615126 -230.837232)
		(width 0.14478)
		(layer "In11.Cu")
		(net "M_L_CPU1_SA_DQ<23>")
	)
	(segment
		(start 159.229806 -230.894636)
		(end 159.229552 -230.664512)
		(width 0.14478)
		(layer "In11.Cu")
		(net "M_L_CPU1_SA_DQ<23>")
	)
	(segment
		(start 189.523116 -224.11055)
		(end 192.695576 -224.11055)
		(width 0.14478)
		(layer "In11.Cu")
		(net "M_L_CPU1_SA_DQ<23>")
	)
	(segment
		(start 145.54327 -239.212882)
		(end 145.793206 -238.962946)
		(width 0.0889)
		(layer "In11.Cu")
		(net "M_L_CPU1_SA_DQ<23>")
	)
	(segment
		(start 158.615126 -230.837232)
		(end 158.835852 -231.057958)
		(width 0.14478)
		(layer "In11.Cu")
		(net "M_L_CPU1_SA_DQ<23>")
	)
	(segment
		(start 147.874482 -237.896654)
		(end 148.03882 -237.896654)
		(width 0.0889)
		(layer "In11.Cu")
		(net "M_L_CPU1_SA_DQ<23>")
	)
	(segment
		(start 162.379406 -227.745036)
		(end 162.379152 -227.514912)
		(width 0.14478)
		(layer "In11.Cu")
		(net "M_L_CPU1_SA_DQ<23>")
	)
	(segment
		(start 151.325326 -237.896654)
		(end 158.384494 -230.837486)
		(width 0.14478)
		(layer "In11.Cu")
		(net "M_L_CPU1_SA_DQ<23>")
	)
	(segment
		(start 159.853884 -230.270558)
		(end 160.017206 -230.107236)
		(width 0.14478)
		(layer "In11.Cu")
		(net "M_L_CPU1_SA_DQ<23>")
	)
	(segment
		(start 160.641284 -229.483158)
		(end 160.804606 -229.319836)
		(width 0.14478)
		(layer "In11.Cu")
		(net "M_L_CPU1_SA_DQ<23>")
	)
	(segment
		(start 160.977326 -228.475032)
		(end 161.198052 -228.695758)
		(width 0.14478)
		(layer "In11.Cu")
		(net "M_L_CPU1_SA_DQ<23>")
	)
	(segment
		(start 169.669714 -223.790764)
		(end 169.989246 -224.110296)
		(width 0.14478)
		(layer "In11.Cu")
		(net "M_L_CPU1_SA_DQ<23>")
	)
	(segment
		(start 162.379152 -227.514912)
		(end 162.158426 -227.294186)
		(width 0.14478)
		(layer "In11.Cu")
		(net "M_L_CPU1_SA_DQ<23>")
	)
	(segment
		(start 161.592006 -228.532436)
		(end 161.591752 -228.302312)
		(width 0.14478)
		(layer "In11.Cu")
		(net "M_L_CPU1_SA_DQ<23>")
	)
	(segment
		(start 169.432732 -223.790764)
		(end 169.669714 -223.790764)
		(width 0.14478)
		(layer "In11.Cu")
		(net "M_L_CPU1_SA_DQ<23>")
	)
	(segment
		(start 169.1132 -224.110296)
		(end 169.432732 -223.790764)
		(width 0.14478)
		(layer "In11.Cu")
		(net "M_L_CPU1_SA_DQ<23>")
	)
	(segment
		(start 192.695576 -224.11055)
		(end 193.54546 -224.960434)
		(width 0.14478)
		(layer "In11.Cu")
		(net "M_L_CPU1_SA_DQ<23>")
	)
	(segment
		(start 168.000172 -224.110296)
		(end 168.319704 -223.790764)
		(width 0.14478)
		(layer "In11.Cu")
		(net "M_L_CPU1_SA_DQ<23>")
	)
	(segment
		(start 166.887144 -224.110296)
		(end 167.206676 -223.790764)
		(width 0.14478)
		(layer "In11.Cu")
		(net "M_L_CPU1_SA_DQ<23>")
	)
	(segment
		(start 181.756812 -224.11055)
		(end 185.250836 -224.11055)
		(width 0.14478)
		(layer "In11.Cu")
		(net "M_L_CPU1_SA_DQ<23>")
	)
	(segment
		(start 196.892672 -224.11055)
		(end 201.723244 -224.11055)
		(width 0.14478)
		(layer "In11.Cu")
		(net "M_L_CPU1_SA_DQ<23>")
	)
	(segment
		(start 188.673232 -224.960434)
		(end 189.523116 -224.11055)
		(width 0.14478)
		(layer "In11.Cu")
		(net "M_L_CPU1_SA_DQ<23>")
	)
	(segment
		(start 201.723244 -224.11055)
		(end 202.147932 -224.535238)
		(width 0.14478)
		(layer "In11.Cu")
		(net "M_L_CPU1_SA_DQ<23>")
	)
	(segment
		(start 159.008826 -230.213154)
		(end 159.171894 -230.050086)
		(width 0.14478)
		(layer "In11.Cu")
		(net "M_L_CPU1_SA_DQ<23>")
	)
	(segment
		(start 196.042788 -224.960434)
		(end 196.892672 -224.11055)
		(width 0.14478)
		(layer "In11.Cu")
		(net "M_L_CPU1_SA_DQ<23>")
	)
	(segment
		(start 161.985452 -227.908358)
		(end 162.216084 -227.908358)
		(width 0.14478)
		(layer "In11.Cu")
		(net "M_L_CPU1_SA_DQ<23>")
	)
	(segment
		(start 159.402526 -230.049832)
		(end 159.623252 -230.270558)
		(width 0.14478)
		(layer "In11.Cu")
		(net "M_L_CPU1_SA_DQ<23>")
	)
	(segment
		(start 148.03882 -237.896654)
		(end 151.325326 -237.896654)
		(width 0.14478)
		(layer "In11.Cu")
		(net "M_L_CPU1_SA_DQ<23>")
	)
	(segment
		(start 168.556686 -223.790764)
		(end 168.876218 -224.110296)
		(width 0.14478)
		(layer "In11.Cu")
		(net "M_L_CPU1_SA_DQ<23>")
	)
	(segment
		(start 160.189926 -229.262432)
		(end 160.410652 -229.483158)
		(width 0.14478)
		(layer "In11.Cu")
		(net "M_L_CPU1_SA_DQ<23>")
	)
	(segment
		(start 174.344076 -224.11055)
		(end 177.972466 -224.11055)
		(width 0.14478)
		(layer "In11.Cu")
		(net "M_L_CPU1_SA_DQ<23>")
	)
	(segment
		(start 147.48383 -238.287306)
		(end 147.874482 -237.896654)
		(width 0.0889)
		(layer "In11.Cu")
		(net "M_L_CPU1_SA_DQ<23>")
	)
	(segment
		(start 158.835852 -231.057958)
		(end 159.066484 -231.057958)
		(width 0.14478)
		(layer "In11.Cu")
		(net "M_L_CPU1_SA_DQ<23>")
	)
	(segment
		(start 160.804606 -229.319836)
		(end 160.804352 -229.089712)
		(width 0.14478)
		(layer "In11.Cu")
		(net "M_L_CPU1_SA_DQ<23>")
	)
	(segment
		(start 159.066484 -231.057958)
		(end 159.229806 -230.894636)
		(width 0.14478)
		(layer "In11.Cu")
		(net "M_L_CPU1_SA_DQ<23>")
	)
	(segment
		(start 166.441374 -224.110296)
		(end 166.887144 -224.110296)
		(width 0.14478)
		(layer "In11.Cu")
		(net "M_L_CPU1_SA_DQ<23>")
	)
	(segment
		(start 178.82235 -224.960434)
		(end 180.906928 -224.960434)
		(width 0.14478)
		(layer "In11.Cu")
		(net "M_L_CPU1_SA_DQ<23>")
	)
	(segment
		(start 159.796226 -229.656386)
		(end 159.796226 -229.425754)
		(width 0.14478)
		(layer "In11.Cu")
		(net "M_L_CPU1_SA_DQ<23>")
	)
	(segment
		(start 170.464734 -224.110296)
		(end 171.314872 -224.960434)
		(width 0.14478)
		(layer "In11.Cu")
		(net "M_L_CPU1_SA_DQ<23>")
	)
	(segment
		(start 160.583626 -228.868986)
		(end 160.583626 -228.638354)
		(width 0.14478)
		(layer "In11.Cu")
		(net "M_L_CPU1_SA_DQ<23>")
	)
	(segment
		(start 160.804352 -229.089712)
		(end 160.583626 -228.868986)
		(width 0.14478)
		(layer "In11.Cu")
		(net "M_L_CPU1_SA_DQ<23>")
	)
	(segment
		(start 177.972466 -224.11055)
		(end 178.82235 -224.960434)
		(width 0.14478)
		(layer "In11.Cu")
		(net "M_L_CPU1_SA_DQ<23>")
	)
	(segment
		(start 140.15339 -239.296956)
		(end 140.161772 -239.301782)
		(width 0.0889)
		(layer "In11.Cu")
		(net "M_L_CPU1_SA_DQ<23>")
	)
	(segment
		(start 160.017206 -230.107236)
		(end 160.016952 -229.877112)
		(width 0.14478)
		(layer "In11.Cu")
		(net "M_L_CPU1_SA_DQ<23>")
	)
	(segment
		(start 168.319704 -223.790764)
		(end 168.556686 -223.790764)
		(width 0.14478)
		(layer "In11.Cu")
		(net "M_L_CPU1_SA_DQ<23>")
	)
	(segment
		(start 145.793206 -238.962946)
		(end 147.00885 -238.962946)
		(width 0.0889)
		(layer "In11.Cu")
		(net "M_L_CPU1_SA_DQ<23>")
	)
	(segment
		(start 180.906928 -224.960434)
		(end 181.756812 -224.11055)
		(width 0.14478)
		(layer "In11.Cu")
		(net "M_L_CPU1_SA_DQ<23>")
	)
	(segment
		(start 159.171894 -230.050086)
		(end 159.402526 -230.049832)
		(width 0.14478)
		(layer "In11.Cu")
		(net "M_L_CPU1_SA_DQ<23>")
	)
	(segment
		(start 161.764726 -227.687632)
		(end 161.985452 -227.908358)
		(width 0.14478)
		(layer "In11.Cu")
		(net "M_L_CPU1_SA_DQ<23>")
	)
	(segment
		(start 147.00885 -238.962946)
		(end 147.48383 -238.487966)
		(width 0.0889)
		(layer "In11.Cu")
		(net "M_L_CPU1_SA_DQ<23>")
	)
	(segment
		(start 167.76319 -224.110296)
		(end 168.000172 -224.110296)
		(width 0.14478)
		(layer "In11.Cu")
		(net "M_L_CPU1_SA_DQ<23>")
	)
	(segment
		(start 161.534094 -227.687886)
		(end 161.764726 -227.687632)
		(width 0.14478)
		(layer "In11.Cu")
		(net "M_L_CPU1_SA_DQ<23>")
	)
	(segment
		(start 141.093444 -239.296956)
		(end 141.101826 -239.301782)
		(width 0.0889)
		(layer "In11.Cu")
		(net "M_L_CPU1_SA_DQ<23>")
	)
	(segment
		(start 160.746694 -228.475286)
		(end 160.977326 -228.475032)
		(width 0.14478)
		(layer "In11.Cu")
		(net "M_L_CPU1_SA_DQ<23>")
	)
	(segment
		(start 164.261546 -224.960434)
		(end 165.591236 -224.960434)
		(width 0.14478)
		(layer "In11.Cu")
		(net "M_L_CPU1_SA_DQ<23>")
	)
	(segment
		(start 141.667738 -239.301782)
		(end 141.67612 -239.296956)
		(width 0.0889)
		(layer "In11.Cu")
		(net "M_L_CPU1_SA_DQ<23>")
	)
	(segment
		(start 161.371026 -227.850954)
		(end 161.534094 -227.687886)
		(width 0.14478)
		(layer "In11.Cu")
		(net "M_L_CPU1_SA_DQ<23>")
	)
	(segment
		(start 173.494192 -224.960434)
		(end 174.344076 -224.11055)
		(width 0.14478)
		(layer "In11.Cu")
		(net "M_L_CPU1_SA_DQ<23>")
	)
	(segment
		(start 159.959294 -229.262686)
		(end 160.189926 -229.262432)
		(width 0.14478)
		(layer "In11.Cu")
		(net "M_L_CPU1_SA_DQ<23>")
	)
	(segment
		(start 161.591752 -228.302312)
		(end 161.371026 -228.081586)
		(width 0.14478)
		(layer "In11.Cu")
		(net "M_L_CPU1_SA_DQ<23>")
	)
	(segment
		(start 160.583626 -228.638354)
		(end 160.746694 -228.475286)
		(width 0.14478)
		(layer "In11.Cu")
		(net "M_L_CPU1_SA_DQ<23>")
	)
	(segment
		(start 144.47774 -239.307878)
		(end 144.488154 -239.301782)
		(width 0.0889)
		(layer "In11.Cu")
		(net "M_L_CPU1_SA_DQ<23>")
	)
	(segment
		(start 160.016952 -229.877112)
		(end 159.796226 -229.656386)
		(width 0.14478)
		(layer "In11.Cu")
		(net "M_L_CPU1_SA_DQ<23>")
	)
	(arc
		(start 142.607792 -239.301782)
		(mid 142.794736 -239.251527)
		(end 142.98168 -239.301782)
		(width 0.0889)
		(layer "In11.Cu")
		(net "M_L_CPU1_SA_DQ<23>")
	)
	(arc
		(start 141.67612 -239.296956)
		(mid 141.859628 -239.251462)
		(end 142.04188 -239.301782)
		(width 0.0889)
		(layer "In11.Cu")
		(net "M_L_CPU1_SA_DQ<23>")
	)
	(arc
		(start 143.547592 -239.301782)
		(mid 143.73479 -239.2514)
		(end 143.921988 -239.301782)
		(width 0.0889)
		(layer "In11.Cu")
		(net "M_L_CPU1_SA_DQ<23>")
	)
	(arc
		(start 144.876774 -239.310418)
		(mid 145.153503 -239.378101)
		(end 145.427954 -239.301782)
		(width 0.0889)
		(layer "In11.Cu")
		(net "M_L_CPU1_SA_DQ<23>")
	)
	(arc
		(start 139.78763 -239.301782)
		(mid 139.969881 -239.251432)
		(end 140.15339 -239.296956)
		(width 0.0889)
		(layer "In11.Cu")
		(net "M_L_CPU1_SA_DQ<23>")
	)
	(arc
		(start 142.98168 -239.301782)
		(mid 143.264636 -239.377959)
		(end 143.547592 -239.301782)
		(width 0.0889)
		(layer "In11.Cu")
		(net "M_L_CPU1_SA_DQ<23>")
	)
	(arc
		(start 138.281918 -239.301782)
		(mid 138.564874 -239.377959)
		(end 138.84783 -239.301782)
		(width 0.0889)
		(layer "In11.Cu")
		(net "M_L_CPU1_SA_DQ<23>")
	)
	(arc
		(start 145.427954 -239.301782)
		(mid 145.488489 -239.261065)
		(end 145.54327 -239.212882)
		(width 0.0889)
		(layer "In11.Cu")
		(net "M_L_CPU1_SA_DQ<23>")
	)
	(arc
		(start 143.921988 -239.301782)
		(mid 144.199055 -239.378053)
		(end 144.47774 -239.307878)
		(width 0.0889)
		(layer "In11.Cu")
		(net "M_L_CPU1_SA_DQ<23>")
	)
	(arc
		(start 137.963148 -239.27562)
		(mid 138.12548 -239.252802)
		(end 138.281918 -239.301782)
		(width 0.0889)
		(layer "In11.Cu")
		(net "M_L_CPU1_SA_DQ<23>")
	)
	(arc
		(start 141.101826 -239.301782)
		(mid 141.384782 -239.377959)
		(end 141.667738 -239.301782)
		(width 0.0889)
		(layer "In11.Cu")
		(net "M_L_CPU1_SA_DQ<23>")
	)
	(arc
		(start 139.221718 -239.301782)
		(mid 139.504674 -239.377959)
		(end 139.78763 -239.301782)
		(width 0.0889)
		(layer "In11.Cu")
		(net "M_L_CPU1_SA_DQ<23>")
	)
	(arc
		(start 140.161772 -239.301782)
		(mid 140.444728 -239.377959)
		(end 140.727684 -239.301782)
		(width 0.0889)
		(layer "In11.Cu")
		(net "M_L_CPU1_SA_DQ<23>")
	)
	(arc
		(start 140.727684 -239.301782)
		(mid 140.909935 -239.251432)
		(end 141.093444 -239.296956)
		(width 0.0889)
		(layer "In11.Cu")
		(net "M_L_CPU1_SA_DQ<23>")
	)
	(arc
		(start 144.488154 -239.301782)
		(mid 144.675098 -239.251527)
		(end 144.862042 -239.301782)
		(width 0.0889)
		(layer "In11.Cu")
		(net "M_L_CPU1_SA_DQ<23>")
	)
	(arc
		(start 138.84783 -239.301782)
		(mid 139.034774 -239.251527)
		(end 139.221718 -239.301782)
		(width 0.0889)
		(layer "In11.Cu")
		(net "M_L_CPU1_SA_DQ<23>")
	)
	(arc
		(start 142.04188 -239.301782)
		(mid 142.324836 -239.377959)
		(end 142.607792 -239.301782)
		(width 0.0889)
		(layer "In11.Cu")
		(net "M_L_CPU1_SA_DQ<23>")
	)
	(segment
		(start 139.037822 -239.080294)
		(end 139.504674 -238.814356)
		(width 0.10668)
		(layer "F.Cu")
		(net "M_L_CPU1_SA_DQ<22>")
	)
	(segment
		(start 151.413464 -236.037882)
		(end 151.517096 -236.141514)
		(width 0.14478)
		(layer "In11.Cu")
		(net "M_L_CPU1_SA_DQ<22>")
	)
	(segment
		(start 153.775664 -233.675682)
		(end 153.879296 -233.779314)
		(width 0.14478)
		(layer "In11.Cu")
		(net "M_L_CPU1_SA_DQ<22>")
	)
	(segment
		(start 152.757632 -234.463336)
		(end 152.988264 -234.463082)
		(width 0.14478)
		(layer "In11.Cu")
		(net "M_L_CPU1_SA_DQ<22>")
	)
	(segment
		(start 155.060396 -232.598468)
		(end 154.956764 -232.494836)
		(width 0.14478)
		(layer "In11.Cu")
		(net "M_L_CPU1_SA_DQ<22>")
	)
	(segment
		(start 185.250836 -222.410528)
		(end 186.10072 -223.260412)
		(width 0.14478)
		(layer "In11.Cu")
		(net "M_L_CPU1_SA_DQ<22>")
	)
	(segment
		(start 181.065424 -223.260412)
		(end 181.915308 -222.410528)
		(width 0.14478)
		(layer "In11.Cu")
		(net "M_L_CPU1_SA_DQ<22>")
	)
	(segment
		(start 200.695052 -222.028766)
		(end 200.839832 -222.173546)
		(width 0.14478)
		(layer "In11.Cu")
		(net "M_L_CPU1_SA_DQ<22>")
	)
	(segment
		(start 144.390618 -238.491776)
		(end 144.408652 -238.502444)
		(width 0.0889)
		(layer "In11.Cu")
		(net "M_L_CPU1_SA_DQ<22>")
	)
	(segment
		(start 146.48053 -237.888526)
		(end 147.03425 -237.888526)
		(width 0.0889)
		(layer "In11.Cu")
		(net "M_L_CPU1_SA_DQ<22>")
	)
	(segment
		(start 151.970232 -235.250736)
		(end 152.200864 -235.250482)
		(width 0.14478)
		(layer "In11.Cu")
		(net "M_L_CPU1_SA_DQ<22>")
	)
	(segment
		(start 144.005046 -238.498888)
		(end 144.016984 -238.49203)
		(width 0.0889)
		(layer "In11.Cu")
		(net "M_L_CPU1_SA_DQ<22>")
	)
	(segment
		(start 155.744164 -231.707436)
		(end 155.744164 -231.476804)
		(width 0.14478)
		(layer "In11.Cu")
		(net "M_L_CPU1_SA_DQ<22>")
	)
	(segment
		(start 165.947852 -223.260412)
		(end 166.79799 -222.410274)
		(width 0.14478)
		(layer "In11.Cu")
		(net "M_L_CPU1_SA_DQ<22>")
	)
	(segment
		(start 156.925264 -230.526082)
		(end 157.028896 -230.629714)
		(width 0.14478)
		(layer "In11.Cu")
		(net "M_L_CPU1_SA_DQ<22>")
	)
	(segment
		(start 154.109928 -233.779314)
		(end 154.27325 -233.615992)
		(width 0.14478)
		(layer "In11.Cu")
		(net "M_L_CPU1_SA_DQ<22>")
	)
	(segment
		(start 152.698196 -234.960668)
		(end 152.594564 -234.857036)
		(width 0.14478)
		(layer "In11.Cu")
		(net "M_L_CPU1_SA_DQ<22>")
	)
	(segment
		(start 189.523116 -222.410528)
		(end 192.59804 -222.410528)
		(width 0.14478)
		(layer "In11.Cu")
		(net "M_L_CPU1_SA_DQ<22>")
	)
	(segment
		(start 200.288398 -222.265748)
		(end 200.288398 -222.173546)
		(width 0.14478)
		(layer "In11.Cu")
		(net "M_L_CPU1_SA_DQ<22>")
	)
	(segment
		(start 155.454096 -232.204514)
		(end 155.684728 -232.204514)
		(width 0.14478)
		(layer "In11.Cu")
		(net "M_L_CPU1_SA_DQ<22>")
	)
	(segment
		(start 157.318964 -230.132636)
		(end 157.318964 -229.902004)
		(width 0.14478)
		(layer "In11.Cu")
		(net "M_L_CPU1_SA_DQ<22>")
	)
	(segment
		(start 153.485596 -234.173268)
		(end 153.381964 -234.069636)
		(width 0.14478)
		(layer "In11.Cu")
		(net "M_L_CPU1_SA_DQ<22>")
	)
	(segment
		(start 154.332432 -232.888536)
		(end 154.563064 -232.888282)
		(width 0.14478)
		(layer "In11.Cu")
		(net "M_L_CPU1_SA_DQ<22>")
	)
	(segment
		(start 192.59804 -222.410528)
		(end 193.447924 -223.260412)
		(width 0.14478)
		(layer "In11.Cu")
		(net "M_L_CPU1_SA_DQ<22>")
	)
	(segment
		(start 174.356268 -222.410528)
		(end 177.972466 -222.410528)
		(width 0.14478)
		(layer "In11.Cu")
		(net "M_L_CPU1_SA_DQ<22>")
	)
	(segment
		(start 151.019764 -236.431836)
		(end 151.019764 -236.201204)
		(width 0.14478)
		(layer "In11.Cu")
		(net "M_L_CPU1_SA_DQ<22>")
	)
	(segment
		(start 200.984612 -222.410528)
		(end 201.723244 -222.410528)
		(width 0.14478)
		(layer "In11.Cu")
		(net "M_L_CPU1_SA_DQ<22>")
	)
	(segment
		(start 152.594564 -234.857036)
		(end 152.594564 -234.626404)
		(width 0.14478)
		(layer "In11.Cu")
		(net "M_L_CPU1_SA_DQ<22>")
	)
	(segment
		(start 200.433178 -222.028766)
		(end 200.695052 -222.028766)
		(width 0.14478)
		(layer "In11.Cu")
		(net "M_L_CPU1_SA_DQ<22>")
	)
	(segment
		(start 200.839832 -222.173546)
		(end 200.839832 -222.265748)
		(width 0.14478)
		(layer "In11.Cu")
		(net "M_L_CPU1_SA_DQ<22>")
	)
	(segment
		(start 151.807164 -235.644436)
		(end 151.807164 -235.413804)
		(width 0.14478)
		(layer "In11.Cu")
		(net "M_L_CPU1_SA_DQ<22>")
	)
	(segment
		(start 170.285918 -222.410274)
		(end 171.136056 -223.260412)
		(width 0.14478)
		(layer "In11.Cu")
		(net "M_L_CPU1_SA_DQ<22>")
	)
	(segment
		(start 200.288398 -222.173546)
		(end 200.433178 -222.028766)
		(width 0.14478)
		(layer "In11.Cu")
		(net "M_L_CPU1_SA_DQ<22>")
	)
	(segment
		(start 151.517096 -236.141514)
		(end 151.747728 -236.141514)
		(width 0.14478)
		(layer "In11.Cu")
		(net "M_L_CPU1_SA_DQ<22>")
	)
	(segment
		(start 154.272996 -233.385868)
		(end 154.169364 -233.282236)
		(width 0.14478)
		(layer "In11.Cu")
		(net "M_L_CPU1_SA_DQ<22>")
	)
	(segment
		(start 142.503398 -238.48695)
		(end 142.51178 -238.491776)
		(width 0.0889)
		(layer "In11.Cu")
		(net "M_L_CPU1_SA_DQ<22>")
	)
	(segment
		(start 153.091896 -234.566714)
		(end 153.322528 -234.566714)
		(width 0.14478)
		(layer "In11.Cu")
		(net "M_L_CPU1_SA_DQ<22>")
	)
	(segment
		(start 154.956764 -232.494836)
		(end 154.956764 -232.264204)
		(width 0.14478)
		(layer "In11.Cu")
		(net "M_L_CPU1_SA_DQ<22>")
	)
	(segment
		(start 156.472128 -231.417114)
		(end 156.63545 -231.253792)
		(width 0.14478)
		(layer "In11.Cu")
		(net "M_L_CPU1_SA_DQ<22>")
	)
	(segment
		(start 155.84805 -232.041192)
		(end 155.847796 -231.811068)
		(width 0.14478)
		(layer "In11.Cu")
		(net "M_L_CPU1_SA_DQ<22>")
	)
	(segment
		(start 193.447924 -223.260412)
		(end 196.262752 -223.260412)
		(width 0.14478)
		(layer "In11.Cu")
		(net "M_L_CPU1_SA_DQ<22>")
	)
	(segment
		(start 152.535128 -235.354114)
		(end 152.69845 -235.190792)
		(width 0.14478)
		(layer "In11.Cu")
		(net "M_L_CPU1_SA_DQ<22>")
	)
	(segment
		(start 157.318964 -229.902004)
		(end 157.482032 -229.738936)
		(width 0.14478)
		(layer "In11.Cu")
		(net "M_L_CPU1_SA_DQ<22>")
	)
	(segment
		(start 156.63545 -231.253792)
		(end 156.635196 -231.023668)
		(width 0.14478)
		(layer "In11.Cu")
		(net "M_L_CPU1_SA_DQ<22>")
	)
	(segment
		(start 156.694632 -230.526336)
		(end 156.925264 -230.526082)
		(width 0.14478)
		(layer "In11.Cu")
		(net "M_L_CPU1_SA_DQ<22>")
	)
	(segment
		(start 157.422596 -230.236268)
		(end 157.318964 -230.132636)
		(width 0.14478)
		(layer "In11.Cu")
		(net "M_L_CPU1_SA_DQ<22>")
	)
	(segment
		(start 155.350464 -232.100882)
		(end 155.454096 -232.204514)
		(width 0.14478)
		(layer "In11.Cu")
		(net "M_L_CPU1_SA_DQ<22>")
	)
	(segment
		(start 152.304496 -235.354114)
		(end 152.535128 -235.354114)
		(width 0.14478)
		(layer "In11.Cu")
		(net "M_L_CPU1_SA_DQ<22>")
	)
	(segment
		(start 157.42285 -230.466392)
		(end 157.422596 -230.236268)
		(width 0.14478)
		(layer "In11.Cu")
		(net "M_L_CPU1_SA_DQ<22>")
	)
	(segment
		(start 155.847796 -231.811068)
		(end 155.744164 -231.707436)
		(width 0.14478)
		(layer "In11.Cu")
		(net "M_L_CPU1_SA_DQ<22>")
	)
	(segment
		(start 173.506384 -223.260412)
		(end 174.356268 -222.410528)
		(width 0.14478)
		(layer "In11.Cu")
		(net "M_L_CPU1_SA_DQ<22>")
	)
	(segment
		(start 177.972466 -222.410528)
		(end 178.82235 -223.260412)
		(width 0.14478)
		(layer "In11.Cu")
		(net "M_L_CPU1_SA_DQ<22>")
	)
	(segment
		(start 181.915308 -222.410528)
		(end 185.250836 -222.410528)
		(width 0.14478)
		(layer "In11.Cu")
		(net "M_L_CPU1_SA_DQ<22>")
	)
	(segment
		(start 155.907232 -231.313736)
		(end 156.137864 -231.313482)
		(width 0.14478)
		(layer "In11.Cu")
		(net "M_L_CPU1_SA_DQ<22>")
	)
	(segment
		(start 151.807164 -235.413804)
		(end 151.970232 -235.250736)
		(width 0.14478)
		(layer "In11.Cu")
		(net "M_L_CPU1_SA_DQ<22>")
	)
	(segment
		(start 155.744164 -231.476804)
		(end 155.907232 -231.313736)
		(width 0.14478)
		(layer "In11.Cu")
		(net "M_L_CPU1_SA_DQ<22>")
	)
	(segment
		(start 153.545032 -233.675936)
		(end 153.775664 -233.675682)
		(width 0.14478)
		(layer "In11.Cu")
		(net "M_L_CPU1_SA_DQ<22>")
	)
	(segment
		(start 171.136056 -223.260412)
		(end 173.506384 -223.260412)
		(width 0.14478)
		(layer "In11.Cu")
		(net "M_L_CPU1_SA_DQ<22>")
	)
	(segment
		(start 151.91105 -235.978192)
		(end 151.910796 -235.748068)
		(width 0.14478)
		(layer "In11.Cu")
		(net "M_L_CPU1_SA_DQ<22>")
	)
	(segment
		(start 156.531564 -230.689404)
		(end 156.694632 -230.526336)
		(width 0.14478)
		(layer "In11.Cu")
		(net "M_L_CPU1_SA_DQ<22>")
	)
	(segment
		(start 152.200864 -235.250482)
		(end 152.304496 -235.354114)
		(width 0.14478)
		(layer "In11.Cu")
		(net "M_L_CPU1_SA_DQ<22>")
	)
	(segment
		(start 153.381964 -234.069636)
		(end 153.381964 -233.839004)
		(width 0.14478)
		(layer "In11.Cu")
		(net "M_L_CPU1_SA_DQ<22>")
	)
	(segment
		(start 156.531564 -230.920036)
		(end 156.531564 -230.689404)
		(width 0.14478)
		(layer "In11.Cu")
		(net "M_L_CPU1_SA_DQ<22>")
	)
	(segment
		(start 151.747728 -236.141514)
		(end 151.91105 -235.978192)
		(width 0.14478)
		(layer "In11.Cu")
		(net "M_L_CPU1_SA_DQ<22>")
	)
	(segment
		(start 151.019764 -236.201204)
		(end 151.182832 -236.038136)
		(width 0.14478)
		(layer "In11.Cu")
		(net "M_L_CPU1_SA_DQ<22>")
	)
	(segment
		(start 200.143618 -222.410528)
		(end 200.288398 -222.265748)
		(width 0.14478)
		(layer "In11.Cu")
		(net "M_L_CPU1_SA_DQ<22>")
	)
	(segment
		(start 201.723244 -222.410528)
		(end 202.147932 -222.835216)
		(width 0.14478)
		(layer "In11.Cu")
		(net "M_L_CPU1_SA_DQ<22>")
	)
	(segment
		(start 145.92808 -238.440976)
		(end 146.48053 -237.888526)
		(width 0.0889)
		(layer "In11.Cu")
		(net "M_L_CPU1_SA_DQ<22>")
	)
	(segment
		(start 154.897328 -232.991914)
		(end 155.06065 -232.828592)
		(width 0.14478)
		(layer "In11.Cu")
		(net "M_L_CPU1_SA_DQ<22>")
	)
	(segment
		(start 157.712664 -229.738682)
		(end 157.816296 -229.842314)
		(width 0.14478)
		(layer "In11.Cu")
		(net "M_L_CPU1_SA_DQ<22>")
	)
	(segment
		(start 157.816296 -229.842314)
		(end 158.046928 -229.842314)
		(width 0.14478)
		(layer "In11.Cu")
		(net "M_L_CPU1_SA_DQ<22>")
	)
	(segment
		(start 186.10072 -223.260412)
		(end 188.673232 -223.260412)
		(width 0.14478)
		(layer "In11.Cu")
		(net "M_L_CPU1_SA_DQ<22>")
	)
	(segment
		(start 154.27325 -233.615992)
		(end 154.272996 -233.385868)
		(width 0.14478)
		(layer "In11.Cu")
		(net "M_L_CPU1_SA_DQ<22>")
	)
	(segment
		(start 143.077692 -238.491776)
		(end 143.086074 -238.48695)
		(width 0.0889)
		(layer "In11.Cu")
		(net "M_L_CPU1_SA_DQ<22>")
	)
	(segment
		(start 139.504674 -238.814356)
		(end 139.35075 -238.548926)
		(width 0.0889)
		(layer "In11.Cu")
		(net "M_L_CPU1_SA_DQ<22>")
	)
	(segment
		(start 156.241496 -231.417114)
		(end 156.472128 -231.417114)
		(width 0.14478)
		(layer "In11.Cu")
		(net "M_L_CPU1_SA_DQ<22>")
	)
	(segment
		(start 152.594564 -234.626404)
		(end 152.757632 -234.463336)
		(width 0.14478)
		(layer "In11.Cu")
		(net "M_L_CPU1_SA_DQ<22>")
	)
	(segment
		(start 196.262752 -223.260412)
		(end 197.112636 -222.410528)
		(width 0.14478)
		(layer "In11.Cu")
		(net "M_L_CPU1_SA_DQ<22>")
	)
	(segment
		(start 145.144744 -238.440976)
		(end 145.92808 -238.440976)
		(width 0.0889)
		(layer "In11.Cu")
		(net "M_L_CPU1_SA_DQ<22>")
	)
	(segment
		(start 152.69845 -235.190792)
		(end 152.698196 -234.960668)
		(width 0.14478)
		(layer "In11.Cu")
		(net "M_L_CPU1_SA_DQ<22>")
	)
	(segment
		(start 139.35075 -238.548926)
		(end 139.373102 -238.465614)
		(width 0.0889)
		(layer "In11.Cu")
		(net "M_L_CPU1_SA_DQ<22>")
	)
	(segment
		(start 154.563064 -232.888282)
		(end 154.666696 -232.991914)
		(width 0.14478)
		(layer "In11.Cu")
		(net "M_L_CPU1_SA_DQ<22>")
	)
	(segment
		(start 150.233634 -236.987334)
		(end 150.395432 -236.825536)
		(width 0.14478)
		(layer "In11.Cu")
		(net "M_L_CPU1_SA_DQ<22>")
	)
	(segment
		(start 166.79799 -222.410274)
		(end 170.285918 -222.410274)
		(width 0.14478)
		(layer "In11.Cu")
		(net "M_L_CPU1_SA_DQ<22>")
	)
	(segment
		(start 157.259528 -230.629714)
		(end 157.42285 -230.466392)
		(width 0.14478)
		(layer "In11.Cu")
		(net "M_L_CPU1_SA_DQ<22>")
	)
	(segment
		(start 163.978336 -223.910906)
		(end 163.978336 -223.405192)
		(width 0.14478)
		(layer "In11.Cu")
		(net "M_L_CPU1_SA_DQ<22>")
	)
	(segment
		(start 152.988264 -234.463082)
		(end 153.091896 -234.566714)
		(width 0.14478)
		(layer "In11.Cu")
		(net "M_L_CPU1_SA_DQ<22>")
	)
	(segment
		(start 154.956764 -232.264204)
		(end 155.119832 -232.101136)
		(width 0.14478)
		(layer "In11.Cu")
		(net "M_L_CPU1_SA_DQ<22>")
	)
	(segment
		(start 156.635196 -231.023668)
		(end 156.531564 -230.920036)
		(width 0.14478)
		(layer "In11.Cu")
		(net "M_L_CPU1_SA_DQ<22>")
	)
	(segment
		(start 151.123396 -236.535468)
		(end 151.019764 -236.431836)
		(width 0.14478)
		(layer "In11.Cu")
		(net "M_L_CPU1_SA_DQ<22>")
	)
	(segment
		(start 151.182832 -236.038136)
		(end 151.413464 -236.037882)
		(width 0.14478)
		(layer "In11.Cu")
		(net "M_L_CPU1_SA_DQ<22>")
	)
	(segment
		(start 155.119832 -232.101136)
		(end 155.350464 -232.100882)
		(width 0.14478)
		(layer "In11.Cu")
		(net "M_L_CPU1_SA_DQ<22>")
	)
	(segment
		(start 158.046928 -229.842314)
		(end 163.978336 -223.910906)
		(width 0.14478)
		(layer "In11.Cu")
		(net "M_L_CPU1_SA_DQ<22>")
	)
	(segment
		(start 157.028896 -230.629714)
		(end 157.259528 -230.629714)
		(width 0.14478)
		(layer "In11.Cu")
		(net "M_L_CPU1_SA_DQ<22>")
	)
	(segment
		(start 151.910796 -235.748068)
		(end 151.807164 -235.644436)
		(width 0.14478)
		(layer "In11.Cu")
		(net "M_L_CPU1_SA_DQ<22>")
	)
	(segment
		(start 197.112636 -222.410528)
		(end 200.143618 -222.410528)
		(width 0.14478)
		(layer "In11.Cu")
		(net "M_L_CPU1_SA_DQ<22>")
	)
	(segment
		(start 188.673232 -223.260412)
		(end 189.523116 -222.410528)
		(width 0.14478)
		(layer "In11.Cu")
		(net "M_L_CPU1_SA_DQ<22>")
	)
	(segment
		(start 150.960328 -236.928914)
		(end 151.12365 -236.765592)
		(width 0.14478)
		(layer "In11.Cu")
		(net "M_L_CPU1_SA_DQ<22>")
	)
	(segment
		(start 140.257784 -238.491776)
		(end 140.266166 -238.48695)
		(width 0.0889)
		(layer "In11.Cu")
		(net "M_L_CPU1_SA_DQ<22>")
	)
	(segment
		(start 147.935442 -236.987334)
		(end 148.146516 -236.987334)
		(width 0.0889)
		(layer "In11.Cu")
		(net "M_L_CPU1_SA_DQ<22>")
	)
	(segment
		(start 153.48585 -234.403392)
		(end 153.485596 -234.173268)
		(width 0.14478)
		(layer "In11.Cu")
		(net "M_L_CPU1_SA_DQ<22>")
	)
	(segment
		(start 147.03425 -237.888526)
		(end 147.935442 -236.987334)
		(width 0.0889)
		(layer "In11.Cu")
		(net "M_L_CPU1_SA_DQ<22>")
	)
	(segment
		(start 155.684728 -232.204514)
		(end 155.84805 -232.041192)
		(width 0.14478)
		(layer "In11.Cu")
		(net "M_L_CPU1_SA_DQ<22>")
	)
	(segment
		(start 164.123116 -223.260412)
		(end 165.947852 -223.260412)
		(width 0.14478)
		(layer "In11.Cu")
		(net "M_L_CPU1_SA_DQ<22>")
	)
	(segment
		(start 154.666696 -232.991914)
		(end 154.897328 -232.991914)
		(width 0.14478)
		(layer "In11.Cu")
		(net "M_L_CPU1_SA_DQ<22>")
	)
	(segment
		(start 154.169364 -233.282236)
		(end 154.169364 -233.051604)
		(width 0.14478)
		(layer "In11.Cu")
		(net "M_L_CPU1_SA_DQ<22>")
	)
	(segment
		(start 148.146516 -236.987334)
		(end 150.233634 -236.987334)
		(width 0.14478)
		(layer "In11.Cu")
		(net "M_L_CPU1_SA_DQ<22>")
	)
	(segment
		(start 150.395432 -236.825536)
		(end 150.626064 -236.825282)
		(width 0.14478)
		(layer "In11.Cu")
		(net "M_L_CPU1_SA_DQ<22>")
	)
	(segment
		(start 154.169364 -233.051604)
		(end 154.332432 -232.888536)
		(width 0.14478)
		(layer "In11.Cu")
		(net "M_L_CPU1_SA_DQ<22>")
	)
	(segment
		(start 155.06065 -232.828592)
		(end 155.060396 -232.598468)
		(width 0.14478)
		(layer "In11.Cu")
		(net "M_L_CPU1_SA_DQ<22>")
	)
	(segment
		(start 153.879296 -233.779314)
		(end 154.109928 -233.779314)
		(width 0.14478)
		(layer "In11.Cu")
		(net "M_L_CPU1_SA_DQ<22>")
	)
	(segment
		(start 151.12365 -236.765592)
		(end 151.123396 -236.535468)
		(width 0.14478)
		(layer "In11.Cu")
		(net "M_L_CPU1_SA_DQ<22>")
	)
	(segment
		(start 153.381964 -233.839004)
		(end 153.545032 -233.675936)
		(width 0.14478)
		(layer "In11.Cu")
		(net "M_L_CPU1_SA_DQ<22>")
	)
	(segment
		(start 157.482032 -229.738936)
		(end 157.712664 -229.738682)
		(width 0.14478)
		(layer "In11.Cu")
		(net "M_L_CPU1_SA_DQ<22>")
	)
	(segment
		(start 156.137864 -231.313482)
		(end 156.241496 -231.417114)
		(width 0.14478)
		(layer "In11.Cu")
		(net "M_L_CPU1_SA_DQ<22>")
	)
	(segment
		(start 200.839832 -222.265748)
		(end 200.984612 -222.410528)
		(width 0.14478)
		(layer "In11.Cu")
		(net "M_L_CPU1_SA_DQ<22>")
	)
	(segment
		(start 178.82235 -223.260412)
		(end 181.065424 -223.260412)
		(width 0.14478)
		(layer "In11.Cu")
		(net "M_L_CPU1_SA_DQ<22>")
	)
	(segment
		(start 150.729696 -236.928914)
		(end 150.960328 -236.928914)
		(width 0.14478)
		(layer "In11.Cu")
		(net "M_L_CPU1_SA_DQ<22>")
	)
	(segment
		(start 153.322528 -234.566714)
		(end 153.48585 -234.403392)
		(width 0.14478)
		(layer "In11.Cu")
		(net "M_L_CPU1_SA_DQ<22>")
	)
	(segment
		(start 163.978336 -223.405192)
		(end 164.123116 -223.260412)
		(width 0.14478)
		(layer "In11.Cu")
		(net "M_L_CPU1_SA_DQ<22>")
	)
	(segment
		(start 150.626064 -236.825282)
		(end 150.729696 -236.928914)
		(width 0.14478)
		(layer "In11.Cu")
		(net "M_L_CPU1_SA_DQ<22>")
	)
	(segment
		(start 144.016984 -238.49203)
		(end 144.0307 -238.484156)
		(width 0.0889)
		(layer "In11.Cu")
		(net "M_L_CPU1_SA_DQ<22>")
	)
	(arc
		(start 144.957292 -238.491776)
		(mid 145.047655 -238.453966)
		(end 145.144744 -238.440976)
		(width 0.0889)
		(layer "In11.Cu")
		(net "M_L_CPU1_SA_DQ<22>")
	)
	(arc
		(start 143.086074 -238.48695)
		(mid 143.269582 -238.441456)
		(end 143.451834 -238.491776)
		(width 0.0889)
		(layer "In11.Cu")
		(net "M_L_CPU1_SA_DQ<22>")
	)
	(arc
		(start 142.51178 -238.491776)
		(mid 142.794736 -238.567953)
		(end 143.077692 -238.491776)
		(width 0.0889)
		(layer "In11.Cu")
		(net "M_L_CPU1_SA_DQ<22>")
	)
	(arc
		(start 139.373102 -238.465614)
		(mid 139.535434 -238.442796)
		(end 139.691872 -238.491776)
		(width 0.0889)
		(layer "In11.Cu")
		(net "M_L_CPU1_SA_DQ<22>")
	)
	(arc
		(start 143.451834 -238.491776)
		(mid 143.727512 -238.567906)
		(end 144.005046 -238.498888)
		(width 0.0889)
		(layer "In11.Cu")
		(net "M_L_CPU1_SA_DQ<22>")
	)
	(arc
		(start 141.571726 -238.491776)
		(mid 141.854682 -238.567953)
		(end 142.137638 -238.491776)
		(width 0.0889)
		(layer "In11.Cu")
		(net "M_L_CPU1_SA_DQ<22>")
	)
	(arc
		(start 139.691872 -238.491776)
		(mid 139.974828 -238.567953)
		(end 140.257784 -238.491776)
		(width 0.0889)
		(layer "In11.Cu")
		(net "M_L_CPU1_SA_DQ<22>")
	)
	(arc
		(start 141.197838 -238.491776)
		(mid 141.384782 -238.441521)
		(end 141.571726 -238.491776)
		(width 0.0889)
		(layer "In11.Cu")
		(net "M_L_CPU1_SA_DQ<22>")
	)
	(arc
		(start 144.408652 -238.502444)
		(mid 144.684347 -238.568287)
		(end 144.957292 -238.491776)
		(width 0.0889)
		(layer "In11.Cu")
		(net "M_L_CPU1_SA_DQ<22>")
	)
	(arc
		(start 140.266166 -238.48695)
		(mid 140.449674 -238.441456)
		(end 140.631926 -238.491776)
		(width 0.0889)
		(layer "In11.Cu")
		(net "M_L_CPU1_SA_DQ<22>")
	)
	(arc
		(start 140.631926 -238.491776)
		(mid 140.914882 -238.567953)
		(end 141.197838 -238.491776)
		(width 0.0889)
		(layer "In11.Cu")
		(net "M_L_CPU1_SA_DQ<22>")
	)
	(arc
		(start 144.0307 -238.484156)
		(mid 144.21163 -238.441678)
		(end 144.390618 -238.491776)
		(width 0.0889)
		(layer "In11.Cu")
		(net "M_L_CPU1_SA_DQ<22>")
	)
	(arc
		(start 142.137638 -238.491776)
		(mid 142.319889 -238.441426)
		(end 142.503398 -238.48695)
		(width 0.0889)
		(layer "In11.Cu")
		(net "M_L_CPU1_SA_DQ<22>")
	)
	(segment
		(start 137.157968 -239.080294)
		(end 137.62482 -238.814356)
		(width 0.10668)
		(layer "F.Cu")
		(net "M_L_CPU1_SA_DQ<21>")
	)
	(segment
		(start 145.408396 -239.078262)
		(end 145.841212 -238.645446)
		(width 0.0889)
		(layer "In11.Cu")
		(net "M_L_CPU1_SA_DQ<21>")
	)
	(segment
		(start 166.595298 -223.260412)
		(end 170.391328 -223.260412)
		(width 0.14478)
		(layer "In11.Cu")
		(net "M_L_CPU1_SA_DQ<21>")
	)
	(segment
		(start 181.851808 -223.260412)
		(end 185.250836 -223.260412)
		(width 0.14478)
		(layer "In11.Cu")
		(net "M_L_CPU1_SA_DQ<21>")
	)
	(segment
		(start 193.510662 -224.109026)
		(end 196.123814 -224.109026)
		(width 0.14478)
		(layer "In11.Cu")
		(net "M_L_CPU1_SA_DQ<21>")
	)
	(segment
		(start 137.778744 -239.079786)
		(end 137.874756 -239.105186)
		(width 0.0889)
		(layer "In11.Cu")
		(net "M_L_CPU1_SA_DQ<21>")
	)
	(segment
		(start 170.391328 -223.260412)
		(end 171.241212 -224.110296)
		(width 0.14478)
		(layer "In11.Cu")
		(net "M_L_CPU1_SA_DQ<21>")
	)
	(segment
		(start 151.136858 -237.441994)
		(end 164.468556 -224.110296)
		(width 0.14478)
		(layer "In11.Cu")
		(net "M_L_CPU1_SA_DQ<21>")
	)
	(segment
		(start 178.82235 -224.110296)
		(end 181.001924 -224.110296)
		(width 0.14478)
		(layer "In11.Cu")
		(net "M_L_CPU1_SA_DQ<21>")
	)
	(segment
		(start 196.123814 -224.109026)
		(end 196.972428 -223.260412)
		(width 0.14478)
		(layer "In11.Cu")
		(net "M_L_CPU1_SA_DQ<21>")
	)
	(segment
		(start 138.743436 -239.141762)
		(end 138.751818 -239.136936)
		(width 0.0889)
		(layer "In11.Cu")
		(net "M_L_CPU1_SA_DQ<21>")
	)
	(segment
		(start 144.38376 -239.141762)
		(end 144.392142 -239.136936)
		(width 0.0889)
		(layer "In11.Cu")
		(net "M_L_CPU1_SA_DQ<21>")
	)
	(segment
		(start 147.25269 -238.096806)
		(end 147.907502 -237.441994)
		(width 0.0889)
		(layer "In11.Cu")
		(net "M_L_CPU1_SA_DQ<21>")
	)
	(segment
		(start 140.257784 -239.136936)
		(end 140.266166 -239.141762)
		(width 0.0889)
		(layer "In11.Cu")
		(net "M_L_CPU1_SA_DQ<21>")
	)
	(segment
		(start 186.10072 -224.110296)
		(end 188.673232 -224.110296)
		(width 0.14478)
		(layer "In11.Cu")
		(net "M_L_CPU1_SA_DQ<21>")
	)
	(segment
		(start 139.31773 -239.136936)
		(end 139.326112 -239.141762)
		(width 0.0889)
		(layer "In11.Cu")
		(net "M_L_CPU1_SA_DQ<21>")
	)
	(segment
		(start 189.523116 -223.260412)
		(end 192.662048 -223.260412)
		(width 0.14478)
		(layer "In11.Cu")
		(net "M_L_CPU1_SA_DQ<21>")
	)
	(segment
		(start 171.241212 -224.110296)
		(end 173.519592 -224.110296)
		(width 0.14478)
		(layer "In11.Cu")
		(net "M_L_CPU1_SA_DQ<21>")
	)
	(segment
		(start 173.519592 -224.110296)
		(end 174.369476 -223.260412)
		(width 0.14478)
		(layer "In11.Cu")
		(net "M_L_CPU1_SA_DQ<21>")
	)
	(segment
		(start 165.745414 -224.110296)
		(end 166.595298 -223.260412)
		(width 0.14478)
		(layer "In11.Cu")
		(net "M_L_CPU1_SA_DQ<21>")
	)
	(segment
		(start 147.907502 -237.441994)
		(end 148.085302 -237.441994)
		(width 0.0889)
		(layer "In11.Cu")
		(net "M_L_CPU1_SA_DQ<21>")
	)
	(segment
		(start 192.662048 -223.260412)
		(end 193.510662 -224.109026)
		(width 0.14478)
		(layer "In11.Cu")
		(net "M_L_CPU1_SA_DQ<21>")
	)
	(segment
		(start 145.841212 -238.645446)
		(end 146.92757 -238.645446)
		(width 0.0889)
		(layer "In11.Cu")
		(net "M_L_CPU1_SA_DQ<21>")
	)
	(segment
		(start 143.077692 -239.136936)
		(end 143.086074 -239.141762)
		(width 0.0889)
		(layer "In11.Cu")
		(net "M_L_CPU1_SA_DQ<21>")
	)
	(segment
		(start 148.085302 -237.441994)
		(end 151.136858 -237.441994)
		(width 0.14478)
		(layer "In11.Cu")
		(net "M_L_CPU1_SA_DQ<21>")
	)
	(segment
		(start 142.503398 -239.141762)
		(end 142.51178 -239.136936)
		(width 0.0889)
		(layer "In11.Cu")
		(net "M_L_CPU1_SA_DQ<21>")
	)
	(segment
		(start 177.972466 -223.260412)
		(end 178.82235 -224.110296)
		(width 0.14478)
		(layer "In11.Cu")
		(net "M_L_CPU1_SA_DQ<21>")
	)
	(segment
		(start 144.947386 -239.13084)
		(end 144.966182 -239.141762)
		(width 0.0889)
		(layer "In11.Cu")
		(net "M_L_CPU1_SA_DQ<21>")
	)
	(segment
		(start 185.250836 -223.260412)
		(end 186.10072 -224.110296)
		(width 0.14478)
		(layer "In11.Cu")
		(net "M_L_CPU1_SA_DQ<21>")
	)
	(segment
		(start 188.673232 -224.110296)
		(end 189.523116 -223.260412)
		(width 0.14478)
		(layer "In11.Cu")
		(net "M_L_CPU1_SA_DQ<21>")
	)
	(segment
		(start 174.369476 -223.260412)
		(end 177.972466 -223.260412)
		(width 0.14478)
		(layer "In11.Cu")
		(net "M_L_CPU1_SA_DQ<21>")
	)
	(segment
		(start 164.468556 -224.110296)
		(end 165.745414 -224.110296)
		(width 0.14478)
		(layer "In11.Cu")
		(net "M_L_CPU1_SA_DQ<21>")
	)
	(segment
		(start 137.62482 -238.814356)
		(end 137.778744 -239.079786)
		(width 0.0889)
		(layer "In11.Cu")
		(net "M_L_CPU1_SA_DQ<21>")
	)
	(segment
		(start 146.92757 -238.645446)
		(end 147.25269 -238.320326)
		(width 0.0889)
		(layer "In11.Cu")
		(net "M_L_CPU1_SA_DQ<21>")
	)
	(segment
		(start 196.972428 -223.260412)
		(end 205.823058 -223.260412)
		(width 0.14478)
		(layer "In11.Cu")
		(net "M_L_CPU1_SA_DQ<21>")
	)
	(segment
		(start 205.823058 -223.260412)
		(end 206.248 -223.685354)
		(width 0.14478)
		(layer "In11.Cu")
		(net "M_L_CPU1_SA_DQ<21>")
	)
	(segment
		(start 181.001924 -224.110296)
		(end 181.851808 -223.260412)
		(width 0.14478)
		(layer "In11.Cu")
		(net "M_L_CPU1_SA_DQ<21>")
	)
	(segment
		(start 143.451834 -239.136936)
		(end 143.462248 -239.13084)
		(width 0.0889)
		(layer "In11.Cu")
		(net "M_L_CPU1_SA_DQ<21>")
	)
	(segment
		(start 147.25269 -238.320326)
		(end 147.25269 -238.096806)
		(width 0.0889)
		(layer "In11.Cu")
		(net "M_L_CPU1_SA_DQ<21>")
	)
	(arc
		(start 137.874756 -239.105186)
		(mid 138.129964 -239.061709)
		(end 138.377676 -239.136936)
		(width 0.0889)
		(layer "In11.Cu")
		(net "M_L_CPU1_SA_DQ<21>")
	)
	(arc
		(start 144.018 -239.136936)
		(mid 144.200251 -239.187286)
		(end 144.38376 -239.141762)
		(width 0.0889)
		(layer "In11.Cu")
		(net "M_L_CPU1_SA_DQ<21>")
	)
	(arc
		(start 138.377676 -239.136936)
		(mid 138.559927 -239.187286)
		(end 138.743436 -239.141762)
		(width 0.0889)
		(layer "In11.Cu")
		(net "M_L_CPU1_SA_DQ<21>")
	)
	(arc
		(start 141.197838 -239.136936)
		(mid 141.384782 -239.187191)
		(end 141.571726 -239.136936)
		(width 0.0889)
		(layer "In11.Cu")
		(net "M_L_CPU1_SA_DQ<21>")
	)
	(arc
		(start 143.086074 -239.141762)
		(mid 143.269582 -239.187256)
		(end 143.451834 -239.136936)
		(width 0.0889)
		(layer "In11.Cu")
		(net "M_L_CPU1_SA_DQ<21>")
	)
	(arc
		(start 138.751818 -239.136936)
		(mid 139.034774 -239.060759)
		(end 139.31773 -239.136936)
		(width 0.0889)
		(layer "In11.Cu")
		(net "M_L_CPU1_SA_DQ<21>")
	)
	(arc
		(start 141.571726 -239.136936)
		(mid 141.854682 -239.060759)
		(end 142.137638 -239.136936)
		(width 0.0889)
		(layer "In11.Cu")
		(net "M_L_CPU1_SA_DQ<21>")
	)
	(arc
		(start 144.966182 -239.141762)
		(mid 145.197823 -239.183492)
		(end 145.408396 -239.078262)
		(width 0.0889)
		(layer "In11.Cu")
		(net "M_L_CPU1_SA_DQ<21>")
	)
	(arc
		(start 142.51178 -239.136936)
		(mid 142.794736 -239.060759)
		(end 143.077692 -239.136936)
		(width 0.0889)
		(layer "In11.Cu")
		(net "M_L_CPU1_SA_DQ<21>")
	)
	(arc
		(start 143.462248 -239.13084)
		(mid 143.740934 -239.06062)
		(end 144.018 -239.136936)
		(width 0.0889)
		(layer "In11.Cu")
		(net "M_L_CPU1_SA_DQ<21>")
	)
	(arc
		(start 142.137638 -239.136936)
		(mid 142.319889 -239.187286)
		(end 142.503398 -239.141762)
		(width 0.0889)
		(layer "In11.Cu")
		(net "M_L_CPU1_SA_DQ<21>")
	)
	(arc
		(start 140.266166 -239.141762)
		(mid 140.449674 -239.187256)
		(end 140.631926 -239.136936)
		(width 0.0889)
		(layer "In11.Cu")
		(net "M_L_CPU1_SA_DQ<21>")
	)
	(arc
		(start 139.691872 -239.136936)
		(mid 139.974828 -239.060759)
		(end 140.257784 -239.136936)
		(width 0.0889)
		(layer "In11.Cu")
		(net "M_L_CPU1_SA_DQ<21>")
	)
	(arc
		(start 144.392142 -239.136936)
		(mid 144.668955 -239.060793)
		(end 144.947386 -239.13084)
		(width 0.0889)
		(layer "In11.Cu")
		(net "M_L_CPU1_SA_DQ<21>")
	)
	(arc
		(start 140.631926 -239.136936)
		(mid 140.914882 -239.060759)
		(end 141.197838 -239.136936)
		(width 0.0889)
		(layer "In11.Cu")
		(net "M_L_CPU1_SA_DQ<21>")
	)
	(arc
		(start 139.326112 -239.141762)
		(mid 139.50962 -239.187256)
		(end 139.691872 -239.136936)
		(width 0.0889)
		(layer "In11.Cu")
		(net "M_L_CPU1_SA_DQ<21>")
	)
	(segment
		(start 138.567922 -238.270288)
		(end 139.034774 -238.00435)
		(width 0.10668)
		(layer "F.Cu")
		(net "M_L_CPU1_SA_DQ<20>")
	)
	(segment
		(start 174.441866 -221.569788)
		(end 177.870612 -221.569788)
		(width 0.14478)
		(layer "In11.Cu")
		(net "M_L_CPU1_SA_DQ<20>")
	)
	(segment
		(start 143.92148 -238.326676)
		(end 143.933418 -238.319818)
		(width 0.0889)
		(layer "In11.Cu")
		(net "M_L_CPU1_SA_DQ<20>")
	)
	(segment
		(start 181.21249 -222.419672)
		(end 182.062374 -221.569788)
		(width 0.14478)
		(layer "In11.Cu")
		(net "M_L_CPU1_SA_DQ<20>")
	)
	(segment
		(start 205.129892 -222.306896)
		(end 205.129892 -221.723458)
		(width 0.14478)
		(layer "In11.Cu")
		(net "M_L_CPU1_SA_DQ<20>")
	)
	(segment
		(start 197.198742 -221.569788)
		(end 204.419708 -221.569788)
		(width 0.14478)
		(layer "In11.Cu")
		(net "M_L_CPU1_SA_DQ<20>")
	)
	(segment
		(start 165.712648 -222.783146)
		(end 166.718488 -221.777306)
		(width 0.14478)
		(layer "In11.Cu")
		(net "M_L_CPU1_SA_DQ<20>")
	)
	(segment
		(start 182.062374 -221.569788)
		(end 185.260234 -221.569788)
		(width 0.14478)
		(layer "In11.Cu")
		(net "M_L_CPU1_SA_DQ<20>")
	)
	(segment
		(start 204.419708 -221.569788)
		(end 204.573378 -221.723458)
		(width 0.14478)
		(layer "In11.Cu")
		(net "M_L_CPU1_SA_DQ<20>")
	)
	(segment
		(start 157.876494 -228.701346)
		(end 158.48965 -228.701346)
		(width 0.14478)
		(layer "In11.Cu")
		(net "M_L_CPU1_SA_DQ<20>")
	)
	(segment
		(start 144.48663 -238.32693)
		(end 144.498314 -238.333788)
		(width 0.0889)
		(layer "In11.Cu")
		(net "M_L_CPU1_SA_DQ<20>")
	)
	(segment
		(start 147.963382 -236.532674)
		(end 148.107146 -236.532674)
		(width 0.0889)
		(layer "In11.Cu")
		(net "M_L_CPU1_SA_DQ<20>")
	)
	(segment
		(start 204.573378 -222.306896)
		(end 204.736446 -222.469964)
		(width 0.14478)
		(layer "In11.Cu")
		(net "M_L_CPU1_SA_DQ<20>")
	)
	(segment
		(start 141.093444 -238.331756)
		(end 141.101826 -238.32693)
		(width 0.0889)
		(layer "In11.Cu")
		(net "M_L_CPU1_SA_DQ<20>")
	)
	(segment
		(start 170.381422 -221.777306)
		(end 171.023788 -222.419672)
		(width 0.14478)
		(layer "In11.Cu")
		(net "M_L_CPU1_SA_DQ<20>")
	)
	(segment
		(start 163.52647 -223.05137)
		(end 163.794694 -222.783146)
		(width 0.14478)
		(layer "In11.Cu")
		(net "M_L_CPU1_SA_DQ<20>")
	)
	(segment
		(start 158.48965 -228.701346)
		(end 163.52647 -223.664526)
		(width 0.14478)
		(layer "In11.Cu")
		(net "M_L_CPU1_SA_DQ<20>")
	)
	(segment
		(start 177.870612 -221.569788)
		(end 178.720496 -222.419672)
		(width 0.14478)
		(layer "In11.Cu")
		(net "M_L_CPU1_SA_DQ<20>")
	)
	(segment
		(start 163.794694 -222.783146)
		(end 165.712648 -222.783146)
		(width 0.14478)
		(layer "In11.Cu")
		(net "M_L_CPU1_SA_DQ<20>")
	)
	(segment
		(start 204.966824 -222.469964)
		(end 205.129892 -222.306896)
		(width 0.14478)
		(layer "In11.Cu")
		(net "M_L_CPU1_SA_DQ<20>")
	)
	(segment
		(start 192.612518 -221.569788)
		(end 193.462402 -222.419672)
		(width 0.14478)
		(layer "In11.Cu")
		(net "M_L_CPU1_SA_DQ<20>")
	)
	(segment
		(start 204.736446 -222.469964)
		(end 204.966824 -222.469964)
		(width 0.14478)
		(layer "In11.Cu")
		(net "M_L_CPU1_SA_DQ<20>")
	)
	(segment
		(start 139.188698 -238.26978)
		(end 139.28471 -238.29518)
		(width 0.0889)
		(layer "In11.Cu")
		(net "M_L_CPU1_SA_DQ<20>")
	)
	(segment
		(start 141.667738 -238.32693)
		(end 141.67612 -238.331756)
		(width 0.0889)
		(layer "In11.Cu")
		(net "M_L_CPU1_SA_DQ<20>")
	)
	(segment
		(start 148.107146 -236.532674)
		(end 150.045166 -236.532674)
		(width 0.14478)
		(layer "In11.Cu")
		(net "M_L_CPU1_SA_DQ<20>")
	)
	(segment
		(start 146.80819 -237.687866)
		(end 147.963382 -236.532674)
		(width 0.0889)
		(layer "In11.Cu")
		(net "M_L_CPU1_SA_DQ<20>")
	)
	(segment
		(start 146.33321 -237.687866)
		(end 146.80819 -237.687866)
		(width 0.0889)
		(layer "In11.Cu")
		(net "M_L_CPU1_SA_DQ<20>")
	)
	(segment
		(start 193.462402 -222.419672)
		(end 196.348858 -222.419672)
		(width 0.14478)
		(layer "In11.Cu")
		(net "M_L_CPU1_SA_DQ<20>")
	)
	(segment
		(start 204.573378 -221.723458)
		(end 204.573378 -222.306896)
		(width 0.14478)
		(layer "In11.Cu")
		(net "M_L_CPU1_SA_DQ<20>")
	)
	(segment
		(start 173.591982 -222.419672)
		(end 174.441866 -221.569788)
		(width 0.14478)
		(layer "In11.Cu")
		(net "M_L_CPU1_SA_DQ<20>")
	)
	(segment
		(start 189.513718 -221.569788)
		(end 192.612518 -221.569788)
		(width 0.14478)
		(layer "In11.Cu")
		(net "M_L_CPU1_SA_DQ<20>")
	)
	(segment
		(start 205.823058 -221.56039)
		(end 206.248 -221.985332)
		(width 0.14478)
		(layer "In11.Cu")
		(net "M_L_CPU1_SA_DQ<20>")
	)
	(segment
		(start 185.260234 -221.569788)
		(end 186.110118 -222.419672)
		(width 0.14478)
		(layer "In11.Cu")
		(net "M_L_CPU1_SA_DQ<20>")
	)
	(segment
		(start 188.663834 -222.419672)
		(end 189.513718 -221.569788)
		(width 0.14478)
		(layer "In11.Cu")
		(net "M_L_CPU1_SA_DQ<20>")
	)
	(segment
		(start 186.110118 -222.419672)
		(end 188.663834 -222.419672)
		(width 0.14478)
		(layer "In11.Cu")
		(net "M_L_CPU1_SA_DQ<20>")
	)
	(segment
		(start 150.045166 -236.532674)
		(end 157.876494 -228.701346)
		(width 0.14478)
		(layer "In11.Cu")
		(net "M_L_CPU1_SA_DQ<20>")
	)
	(segment
		(start 205.129892 -221.723458)
		(end 205.29296 -221.56039)
		(width 0.14478)
		(layer "In11.Cu")
		(net "M_L_CPU1_SA_DQ<20>")
	)
	(segment
		(start 171.023788 -222.419672)
		(end 173.591982 -222.419672)
		(width 0.14478)
		(layer "In11.Cu")
		(net "M_L_CPU1_SA_DQ<20>")
	)
	(segment
		(start 145.7706 -238.250476)
		(end 146.33321 -237.687866)
		(width 0.0889)
		(layer "In11.Cu")
		(net "M_L_CPU1_SA_DQ<20>")
	)
	(segment
		(start 139.034774 -238.00435)
		(end 139.188698 -238.26978)
		(width 0.0889)
		(layer "In11.Cu")
		(net "M_L_CPU1_SA_DQ<20>")
	)
	(segment
		(start 143.905224 -238.336074)
		(end 143.92148 -238.326676)
		(width 0.0889)
		(layer "In11.Cu")
		(net "M_L_CPU1_SA_DQ<20>")
	)
	(segment
		(start 140.15339 -238.331756)
		(end 140.161772 -238.32693)
		(width 0.0889)
		(layer "In11.Cu")
		(net "M_L_CPU1_SA_DQ<20>")
	)
	(segment
		(start 145.144744 -238.250476)
		(end 145.7706 -238.250476)
		(width 0.0889)
		(layer "In11.Cu")
		(net "M_L_CPU1_SA_DQ<20>")
	)
	(segment
		(start 205.29296 -221.56039)
		(end 205.823058 -221.56039)
		(width 0.14478)
		(layer "In11.Cu")
		(net "M_L_CPU1_SA_DQ<20>")
	)
	(segment
		(start 178.720496 -222.419672)
		(end 181.21249 -222.419672)
		(width 0.14478)
		(layer "In11.Cu")
		(net "M_L_CPU1_SA_DQ<20>")
	)
	(segment
		(start 163.52647 -223.664526)
		(end 163.52647 -223.05137)
		(width 0.14478)
		(layer "In11.Cu")
		(net "M_L_CPU1_SA_DQ<20>")
	)
	(segment
		(start 166.718488 -221.777306)
		(end 170.381422 -221.777306)
		(width 0.14478)
		(layer "In11.Cu")
		(net "M_L_CPU1_SA_DQ<20>")
	)
	(segment
		(start 196.348858 -222.419672)
		(end 197.198742 -221.569788)
		(width 0.14478)
		(layer "In11.Cu")
		(net "M_L_CPU1_SA_DQ<20>")
	)
	(arc
		(start 140.727684 -238.32693)
		(mid 140.909935 -238.37728)
		(end 141.093444 -238.331756)
		(width 0.0889)
		(layer "In11.Cu")
		(net "M_L_CPU1_SA_DQ<20>")
	)
	(arc
		(start 139.78763 -238.32693)
		(mid 139.969881 -238.37728)
		(end 140.15339 -238.331756)
		(width 0.0889)
		(layer "In11.Cu")
		(net "M_L_CPU1_SA_DQ<20>")
	)
	(arc
		(start 141.67612 -238.331756)
		(mid 141.859628 -238.37725)
		(end 142.04188 -238.32693)
		(width 0.0889)
		(layer "In11.Cu")
		(net "M_L_CPU1_SA_DQ<20>")
	)
	(arc
		(start 142.607792 -238.32693)
		(mid 142.794736 -238.377185)
		(end 142.98168 -238.32693)
		(width 0.0889)
		(layer "In11.Cu")
		(net "M_L_CPU1_SA_DQ<20>")
	)
	(arc
		(start 143.547592 -238.32693)
		(mid 143.725242 -238.37719)
		(end 143.905224 -238.336074)
		(width 0.0889)
		(layer "In11.Cu")
		(net "M_L_CPU1_SA_DQ<20>")
	)
	(arc
		(start 140.161772 -238.32693)
		(mid 140.444728 -238.250753)
		(end 140.727684 -238.32693)
		(width 0.0889)
		(layer "In11.Cu")
		(net "M_L_CPU1_SA_DQ<20>")
	)
	(arc
		(start 144.498314 -238.333788)
		(mid 144.680569 -238.377441)
		(end 144.861026 -238.32693)
		(width 0.0889)
		(layer "In11.Cu")
		(net "M_L_CPU1_SA_DQ<20>")
	)
	(arc
		(start 139.28471 -238.29518)
		(mid 139.539918 -238.251703)
		(end 139.78763 -238.32693)
		(width 0.0889)
		(layer "In11.Cu")
		(net "M_L_CPU1_SA_DQ<20>")
	)
	(arc
		(start 141.101826 -238.32693)
		(mid 141.384782 -238.250753)
		(end 141.667738 -238.32693)
		(width 0.0889)
		(layer "In11.Cu")
		(net "M_L_CPU1_SA_DQ<20>")
	)
	(arc
		(start 144.861026 -238.32693)
		(mid 144.997819 -238.269908)
		(end 145.144744 -238.250476)
		(width 0.0889)
		(layer "In11.Cu")
		(net "M_L_CPU1_SA_DQ<20>")
	)
	(arc
		(start 142.98168 -238.32693)
		(mid 143.264636 -238.250753)
		(end 143.547592 -238.32693)
		(width 0.0889)
		(layer "In11.Cu")
		(net "M_L_CPU1_SA_DQ<20>")
	)
	(arc
		(start 143.933418 -238.319818)
		(mid 144.210952 -238.250837)
		(end 144.48663 -238.32693)
		(width 0.0889)
		(layer "In11.Cu")
		(net "M_L_CPU1_SA_DQ<20>")
	)
	(arc
		(start 142.04188 -238.32693)
		(mid 142.324836 -238.250753)
		(end 142.607792 -238.32693)
		(width 0.0889)
		(layer "In11.Cu")
		(net "M_L_CPU1_SA_DQ<20>")
	)
	(segment
		(start 137.157968 -226.120452)
		(end 137.62482 -225.854514)
		(width 0.10668)
		(layer "F.Cu")
		(net "M_L_CPU1_SA_DQ<1>")
	)
	(segment
		(start 143.921734 -223.747076)
		(end 143.953484 -223.728788)
		(width 0.0889)
		(layer "In11.Cu")
		(net "M_L_CPU1_SA_DQ<1>")
	)
	(segment
		(start 144.960594 -222.046292)
		(end 145.112232 -221.894654)
		(width 0.0889)
		(layer "In11.Cu")
		(net "M_L_CPU1_SA_DQ<1>")
	)
	(segment
		(start 192.969388 -198.610474)
		(end 193.819272 -199.460358)
		(width 0.14478)
		(layer "In11.Cu")
		(net "M_L_CPU1_SA_DQ<1>")
	)
	(segment
		(start 143.451834 -224.557082)
		(end 143.482314 -224.539302)
		(width 0.0889)
		(layer "In11.Cu")
		(net "M_L_CPU1_SA_DQ<1>")
	)
	(segment
		(start 193.819272 -199.460358)
		(end 196.049138 -199.460358)
		(width 0.14478)
		(layer "In11.Cu")
		(net "M_L_CPU1_SA_DQ<1>")
	)
	(segment
		(start 169.710862 -198.610474)
		(end 171.762674 -199.460358)
		(width 0.14478)
		(layer "In11.Cu")
		(net "M_L_CPU1_SA_DQ<1>")
	)
	(segment
		(start 161.894774 -199.460358)
		(end 165.422834 -199.460358)
		(width 0.14478)
		(layer "In11.Cu")
		(net "M_L_CPU1_SA_DQ<1>")
	)
	(segment
		(start 175.080168 -198.610474)
		(end 177.296318 -198.610474)
		(width 0.14478)
		(layer "In11.Cu")
		(net "M_L_CPU1_SA_DQ<1>")
	)
	(segment
		(start 138.743436 -226.18192)
		(end 138.751818 -226.177094)
		(width 0.0889)
		(layer "In11.Cu")
		(net "M_L_CPU1_SA_DQ<1>")
	)
	(segment
		(start 144.391634 -222.93707)
		(end 144.422114 -222.91929)
		(width 0.0889)
		(layer "In11.Cu")
		(net "M_L_CPU1_SA_DQ<1>")
	)
	(segment
		(start 145.112232 -221.153482)
		(end 145.112232 -217.151204)
		(width 0.14478)
		(layer "In11.Cu")
		(net "M_L_CPU1_SA_DQ<1>")
	)
	(segment
		(start 137.778744 -226.119944)
		(end 137.874756 -226.145344)
		(width 0.0889)
		(layer "In11.Cu")
		(net "M_L_CPU1_SA_DQ<1>")
	)
	(segment
		(start 142.98168 -225.367088)
		(end 143.01343 -225.3488)
		(width 0.0889)
		(layer "In11.Cu")
		(net "M_L_CPU1_SA_DQ<1>")
	)
	(segment
		(start 184.73039 -198.610474)
		(end 186.782202 -199.460358)
		(width 0.14478)
		(layer "In11.Cu")
		(net "M_L_CPU1_SA_DQ<1>")
	)
	(segment
		(start 182.492142 -198.610474)
		(end 184.73039 -198.610474)
		(width 0.14478)
		(layer "In11.Cu")
		(net "M_L_CPU1_SA_DQ<1>")
	)
	(segment
		(start 196.049138 -199.460358)
		(end 196.899022 -198.610474)
		(width 0.14478)
		(layer "In11.Cu")
		(net "M_L_CPU1_SA_DQ<1>")
	)
	(segment
		(start 205.823058 -198.610474)
		(end 206.248 -199.035416)
		(width 0.14478)
		(layer "In11.Cu")
		(net "M_L_CPU1_SA_DQ<1>")
	)
	(segment
		(start 157.049216 -205.21422)
		(end 157.049216 -204.305916)
		(width 0.14478)
		(layer "In11.Cu")
		(net "M_L_CPU1_SA_DQ<1>")
	)
	(segment
		(start 140.257784 -226.177094)
		(end 140.266166 -226.18192)
		(width 0.0889)
		(layer "In11.Cu")
		(net "M_L_CPU1_SA_DQ<1>")
	)
	(segment
		(start 144.823688 -222.148908)
		(end 144.892268 -222.109284)
		(width 0.0889)
		(layer "In11.Cu")
		(net "M_L_CPU1_SA_DQ<1>")
	)
	(segment
		(start 179.34813 -199.460358)
		(end 180.44033 -199.460358)
		(width 0.14478)
		(layer "In11.Cu")
		(net "M_L_CPU1_SA_DQ<1>")
	)
	(segment
		(start 188.126624 -199.460358)
		(end 190.178436 -198.610474)
		(width 0.14478)
		(layer "In11.Cu")
		(net "M_L_CPU1_SA_DQ<1>")
	)
	(segment
		(start 139.31773 -226.177094)
		(end 139.326112 -226.18192)
		(width 0.0889)
		(layer "In11.Cu")
		(net "M_L_CPU1_SA_DQ<1>")
	)
	(segment
		(start 142.945358 -225.38817)
		(end 142.98168 -225.367088)
		(width 0.0889)
		(layer "In11.Cu")
		(net "M_L_CPU1_SA_DQ<1>")
	)
	(segment
		(start 186.782202 -199.460358)
		(end 188.126624 -199.460358)
		(width 0.14478)
		(layer "In11.Cu")
		(net "M_L_CPU1_SA_DQ<1>")
	)
	(segment
		(start 171.762674 -199.460358)
		(end 173.028356 -199.460358)
		(width 0.14478)
		(layer "In11.Cu")
		(net "M_L_CPU1_SA_DQ<1>")
	)
	(segment
		(start 165.422834 -199.460358)
		(end 167.474646 -198.610474)
		(width 0.14478)
		(layer "In11.Cu")
		(net "M_L_CPU1_SA_DQ<1>")
	)
	(segment
		(start 145.112232 -221.894654)
		(end 145.112232 -221.153482)
		(width 0.0889)
		(layer "In11.Cu")
		(net "M_L_CPU1_SA_DQ<1>")
	)
	(segment
		(start 157.049216 -204.305916)
		(end 161.894774 -199.460358)
		(width 0.14478)
		(layer "In11.Cu")
		(net "M_L_CPU1_SA_DQ<1>")
	)
	(segment
		(start 190.178436 -198.610474)
		(end 192.969388 -198.610474)
		(width 0.14478)
		(layer "In11.Cu")
		(net "M_L_CPU1_SA_DQ<1>")
	)
	(segment
		(start 142.51178 -226.177094)
		(end 142.54353 -226.158806)
		(width 0.0889)
		(layer "In11.Cu")
		(net "M_L_CPU1_SA_DQ<1>")
	)
	(segment
		(start 145.112232 -217.151204)
		(end 157.049216 -205.21422)
		(width 0.14478)
		(layer "In11.Cu")
		(net "M_L_CPU1_SA_DQ<1>")
	)
	(segment
		(start 196.899022 -198.610474)
		(end 205.823058 -198.610474)
		(width 0.14478)
		(layer "In11.Cu")
		(net "M_L_CPU1_SA_DQ<1>")
	)
	(segment
		(start 142.503398 -226.18192)
		(end 142.51178 -226.177094)
		(width 0.0889)
		(layer "In11.Cu")
		(net "M_L_CPU1_SA_DQ<1>")
	)
	(segment
		(start 177.296318 -198.610474)
		(end 179.34813 -199.460358)
		(width 0.14478)
		(layer "In11.Cu")
		(net "M_L_CPU1_SA_DQ<1>")
	)
	(segment
		(start 143.412718 -224.579942)
		(end 143.451834 -224.557082)
		(width 0.0889)
		(layer "In11.Cu")
		(net "M_L_CPU1_SA_DQ<1>")
	)
	(segment
		(start 180.44033 -199.460358)
		(end 182.492142 -198.610474)
		(width 0.14478)
		(layer "In11.Cu")
		(net "M_L_CPU1_SA_DQ<1>")
	)
	(segment
		(start 173.028356 -199.460358)
		(end 175.080168 -198.610474)
		(width 0.14478)
		(layer "In11.Cu")
		(net "M_L_CPU1_SA_DQ<1>")
	)
	(segment
		(start 143.883888 -223.76892)
		(end 143.921734 -223.747076)
		(width 0.0889)
		(layer "In11.Cu")
		(net "M_L_CPU1_SA_DQ<1>")
	)
	(segment
		(start 137.62482 -225.854514)
		(end 137.778744 -226.119944)
		(width 0.0889)
		(layer "In11.Cu")
		(net "M_L_CPU1_SA_DQ<1>")
	)
	(segment
		(start 167.474646 -198.610474)
		(end 169.710862 -198.610474)
		(width 0.14478)
		(layer "In11.Cu")
		(net "M_L_CPU1_SA_DQ<1>")
	)
	(segment
		(start 144.354042 -222.958914)
		(end 144.391634 -222.93707)
		(width 0.0889)
		(layer "In11.Cu")
		(net "M_L_CPU1_SA_DQ<1>")
	)
	(arc
		(start 144.892268 -222.109284)
		(mid 144.928386 -222.07991)
		(end 144.960594 -222.046292)
		(width 0.0889)
		(layer "In11.Cu")
		(net "M_L_CPU1_SA_DQ<1>")
	)
	(arc
		(start 141.571726 -226.177094)
		(mid 141.854682 -226.100917)
		(end 142.137638 -226.177094)
		(width 0.0889)
		(layer "In11.Cu")
		(net "M_L_CPU1_SA_DQ<1>")
	)
	(arc
		(start 139.691872 -226.177094)
		(mid 139.974828 -226.100917)
		(end 140.257784 -226.177094)
		(width 0.0889)
		(layer "In11.Cu")
		(net "M_L_CPU1_SA_DQ<1>")
	)
	(arc
		(start 143.639286 -224.234502)
		(mid 143.704158 -223.971539)
		(end 143.883888 -223.76892)
		(width 0.0889)
		(layer "In11.Cu")
		(net "M_L_CPU1_SA_DQ<1>")
	)
	(arc
		(start 144.422114 -222.91929)
		(mid 144.537541 -222.785914)
		(end 144.579086 -222.61449)
		(width 0.0889)
		(layer "In11.Cu")
		(net "M_L_CPU1_SA_DQ<1>")
	)
	(arc
		(start 141.197838 -226.177094)
		(mid 141.384782 -226.227349)
		(end 141.571726 -226.177094)
		(width 0.0889)
		(layer "In11.Cu")
		(net "M_L_CPU1_SA_DQ<1>")
	)
	(arc
		(start 142.137638 -226.177094)
		(mid 142.319889 -226.227444)
		(end 142.503398 -226.18192)
		(width 0.0889)
		(layer "In11.Cu")
		(net "M_L_CPU1_SA_DQ<1>")
	)
	(arc
		(start 140.266166 -226.18192)
		(mid 140.449674 -226.227414)
		(end 140.631926 -226.177094)
		(width 0.0889)
		(layer "In11.Cu")
		(net "M_L_CPU1_SA_DQ<1>")
	)
	(arc
		(start 143.169386 -225.044508)
		(mid 143.233901 -224.782289)
		(end 143.412718 -224.579942)
		(width 0.0889)
		(layer "In11.Cu")
		(net "M_L_CPU1_SA_DQ<1>")
	)
	(arc
		(start 143.01343 -225.3488)
		(mid 143.128106 -225.215466)
		(end 143.169386 -225.044508)
		(width 0.0889)
		(layer "In11.Cu")
		(net "M_L_CPU1_SA_DQ<1>")
	)
	(arc
		(start 139.326112 -226.18192)
		(mid 139.50962 -226.227414)
		(end 139.691872 -226.177094)
		(width 0.0889)
		(layer "In11.Cu")
		(net "M_L_CPU1_SA_DQ<1>")
	)
	(arc
		(start 142.54353 -226.158806)
		(mid 142.658206 -226.025472)
		(end 142.699486 -225.854514)
		(width 0.0889)
		(layer "In11.Cu")
		(net "M_L_CPU1_SA_DQ<1>")
	)
	(arc
		(start 142.699486 -225.854514)
		(mid 142.764722 -225.590923)
		(end 142.945358 -225.38817)
		(width 0.0889)
		(layer "In11.Cu")
		(net "M_L_CPU1_SA_DQ<1>")
	)
	(arc
		(start 140.631926 -226.177094)
		(mid 140.914882 -226.100917)
		(end 141.197838 -226.177094)
		(width 0.0889)
		(layer "In11.Cu")
		(net "M_L_CPU1_SA_DQ<1>")
	)
	(arc
		(start 143.953484 -223.728788)
		(mid 144.06816 -223.595454)
		(end 144.10944 -223.424496)
		(width 0.0889)
		(layer "In11.Cu")
		(net "M_L_CPU1_SA_DQ<1>")
	)
	(arc
		(start 144.10944 -223.424496)
		(mid 144.174312 -223.161533)
		(end 144.354042 -222.958914)
		(width 0.0889)
		(layer "In11.Cu")
		(net "M_L_CPU1_SA_DQ<1>")
	)
	(arc
		(start 143.482314 -224.539302)
		(mid 143.597741 -224.405926)
		(end 143.639286 -224.234502)
		(width 0.0889)
		(layer "In11.Cu")
		(net "M_L_CPU1_SA_DQ<1>")
	)
	(arc
		(start 138.377676 -226.177094)
		(mid 138.559927 -226.227444)
		(end 138.743436 -226.18192)
		(width 0.0889)
		(layer "In11.Cu")
		(net "M_L_CPU1_SA_DQ<1>")
	)
	(arc
		(start 144.579086 -222.61449)
		(mid 144.643958 -222.351527)
		(end 144.823688 -222.148908)
		(width 0.0889)
		(layer "In11.Cu")
		(net "M_L_CPU1_SA_DQ<1>")
	)
	(arc
		(start 137.874756 -226.145344)
		(mid 138.129964 -226.101867)
		(end 138.377676 -226.177094)
		(width 0.0889)
		(layer "In11.Cu")
		(net "M_L_CPU1_SA_DQ<1>")
	)
	(arc
		(start 138.751818 -226.177094)
		(mid 139.034774 -226.100917)
		(end 139.31773 -226.177094)
		(width 0.0889)
		(layer "In11.Cu")
		(net "M_L_CPU1_SA_DQ<1>")
	)
	(segment
		(start 137.627868 -236.650276)
		(end 138.09472 -236.384338)
		(width 0.10668)
		(layer "F.Cu")
		(net "M_L_CPU1_SA_DQ<19>")
	)
	(segment
		(start 200.624186 -218.295982)
		(end 200.624186 -218.554046)
		(width 0.14478)
		(layer "In11.Cu")
		(net "M_L_CPU1_SA_DQ<19>")
	)
	(segment
		(start 141.093444 -236.056932)
		(end 141.101826 -236.061758)
		(width 0.0889)
		(layer "In11.Cu")
		(net "M_L_CPU1_SA_DQ<19>")
	)
	(segment
		(start 160.90392 -221.653862)
		(end 160.90392 -221.42323)
		(width 0.14478)
		(layer "In11.Cu")
		(net "M_L_CPU1_SA_DQ<19>")
	)
	(segment
		(start 161.29762 -221.260162)
		(end 161.537904 -221.500446)
		(width 0.14478)
		(layer "In11.Cu")
		(net "M_L_CPU1_SA_DQ<19>")
	)
	(segment
		(start 161.69132 -220.63583)
		(end 161.854388 -220.472762)
		(width 0.14478)
		(layer "In11.Cu")
		(net "M_L_CPU1_SA_DQ<19>")
	)
	(segment
		(start 201.3204 -218.151202)
		(end 201.713846 -218.151202)
		(width 0.14478)
		(layer "In11.Cu")
		(net "M_L_CPU1_SA_DQ<19>")
	)
	(segment
		(start 146.74469 -235.554266)
		(end 147.13077 -235.168186)
		(width 0.0889)
		(layer "In11.Cu")
		(net "M_L_CPU1_SA_DQ<19>")
	)
	(segment
		(start 181.85003 -218.151202)
		(end 185.241438 -218.151202)
		(width 0.14478)
		(layer "In11.Cu")
		(net "M_L_CPU1_SA_DQ<19>")
	)
	(segment
		(start 161.768536 -221.500446)
		(end 161.931604 -221.337378)
		(width 0.14478)
		(layer "In11.Cu")
		(net "M_L_CPU1_SA_DQ<19>")
	)
	(segment
		(start 195.996814 -219.001086)
		(end 196.846698 -218.151202)
		(width 0.14478)
		(layer "In11.Cu")
		(net "M_L_CPU1_SA_DQ<19>")
	)
	(segment
		(start 173.586394 -219.000832)
		(end 174.436278 -218.150948)
		(width 0.14478)
		(layer "In11.Cu")
		(net "M_L_CPU1_SA_DQ<19>")
	)
	(segment
		(start 166.832788 -218.150948)
		(end 170.282616 -218.150948)
		(width 0.14478)
		(layer "In11.Cu")
		(net "M_L_CPU1_SA_DQ<19>")
	)
	(segment
		(start 137.940796 -236.118908)
		(end 137.963148 -236.035596)
		(width 0.0889)
		(layer "In11.Cu")
		(net "M_L_CPU1_SA_DQ<19>")
	)
	(segment
		(start 161.854388 -220.472762)
		(end 162.08502 -220.472762)
		(width 0.14478)
		(layer "In11.Cu")
		(net "M_L_CPU1_SA_DQ<19>")
	)
	(segment
		(start 146.413982 -235.554266)
		(end 146.74469 -235.554266)
		(width 0.0889)
		(layer "In11.Cu")
		(net "M_L_CPU1_SA_DQ<19>")
	)
	(segment
		(start 201.713846 -218.151202)
		(end 202.147932 -218.585288)
		(width 0.14478)
		(layer "In11.Cu")
		(net "M_L_CPU1_SA_DQ<19>")
	)
	(segment
		(start 161.066988 -221.260162)
		(end 161.29762 -221.260162)
		(width 0.14478)
		(layer "In11.Cu")
		(net "M_L_CPU1_SA_DQ<19>")
	)
	(segment
		(start 161.931604 -221.337378)
		(end 161.931604 -221.106746)
		(width 0.14478)
		(layer "In11.Cu")
		(net "M_L_CPU1_SA_DQ<19>")
	)
	(segment
		(start 144.862042 -236.061758)
		(end 144.876774 -236.070394)
		(width 0.0889)
		(layer "In11.Cu")
		(net "M_L_CPU1_SA_DQ<19>")
	)
	(segment
		(start 200.624186 -218.554046)
		(end 200.768966 -218.698826)
		(width 0.14478)
		(layer "In11.Cu")
		(net "M_L_CPU1_SA_DQ<19>")
	)
	(segment
		(start 147.13077 -234.980226)
		(end 147.917662 -234.193334)
		(width 0.0889)
		(layer "In11.Cu")
		(net "M_L_CPU1_SA_DQ<19>")
	)
	(segment
		(start 178.563778 -219.000832)
		(end 181.0004 -219.000832)
		(width 0.14478)
		(layer "In11.Cu")
		(net "M_L_CPU1_SA_DQ<19>")
	)
	(segment
		(start 161.537904 -221.500446)
		(end 161.768536 -221.500446)
		(width 0.14478)
		(layer "In11.Cu")
		(net "M_L_CPU1_SA_DQ<19>")
	)
	(segment
		(start 162.719004 -220.319346)
		(end 162.47872 -220.079062)
		(width 0.14478)
		(layer "In11.Cu")
		(net "M_L_CPU1_SA_DQ<19>")
	)
	(segment
		(start 185.241438 -218.151202)
		(end 186.091322 -219.001086)
		(width 0.14478)
		(layer "In11.Cu")
		(net "M_L_CPU1_SA_DQ<19>")
	)
	(segment
		(start 174.436278 -218.150948)
		(end 177.713894 -218.150948)
		(width 0.14478)
		(layer "In11.Cu")
		(net "M_L_CPU1_SA_DQ<19>")
	)
	(segment
		(start 162.82416 -219.685362)
		(end 163.499292 -219.01023)
		(width 0.14478)
		(layer "In11.Cu")
		(net "M_L_CPU1_SA_DQ<19>")
	)
	(segment
		(start 138.09472 -236.384338)
		(end 137.940796 -236.118908)
		(width 0.0889)
		(layer "In11.Cu")
		(net "M_L_CPU1_SA_DQ<19>")
	)
	(segment
		(start 162.08502 -220.472762)
		(end 162.325304 -220.713046)
		(width 0.14478)
		(layer "In11.Cu")
		(net "M_L_CPU1_SA_DQ<19>")
	)
	(segment
		(start 201.17562 -218.295982)
		(end 201.3204 -218.151202)
		(width 0.14478)
		(layer "In11.Cu")
		(net "M_L_CPU1_SA_DQ<19>")
	)
	(segment
		(start 161.144204 -222.124778)
		(end 161.144204 -221.894146)
		(width 0.14478)
		(layer "In11.Cu")
		(net "M_L_CPU1_SA_DQ<19>")
	)
	(segment
		(start 145.95729 -236.010958)
		(end 146.413982 -235.554266)
		(width 0.0889)
		(layer "In11.Cu")
		(net "M_L_CPU1_SA_DQ<19>")
	)
	(segment
		(start 162.325304 -220.713046)
		(end 162.555936 -220.713046)
		(width 0.14478)
		(layer "In11.Cu")
		(net "M_L_CPU1_SA_DQ<19>")
	)
	(segment
		(start 144.47774 -236.067854)
		(end 144.488154 -236.061758)
		(width 0.0889)
		(layer "In11.Cu")
		(net "M_L_CPU1_SA_DQ<19>")
	)
	(segment
		(start 200.768966 -218.698826)
		(end 201.03084 -218.698826)
		(width 0.14478)
		(layer "In11.Cu")
		(net "M_L_CPU1_SA_DQ<19>")
	)
	(segment
		(start 161.931604 -221.106746)
		(end 161.69132 -220.866462)
		(width 0.14478)
		(layer "In11.Cu")
		(net "M_L_CPU1_SA_DQ<19>")
	)
	(segment
		(start 171.1325 -219.000832)
		(end 173.586394 -219.000832)
		(width 0.14478)
		(layer "In11.Cu")
		(net "M_L_CPU1_SA_DQ<19>")
	)
	(segment
		(start 188.68263 -219.001086)
		(end 189.532514 -218.151202)
		(width 0.14478)
		(layer "In11.Cu")
		(net "M_L_CPU1_SA_DQ<19>")
	)
	(segment
		(start 196.846698 -218.151202)
		(end 200.479406 -218.151202)
		(width 0.14478)
		(layer "In11.Cu")
		(net "M_L_CPU1_SA_DQ<19>")
	)
	(segment
		(start 201.03084 -218.698826)
		(end 201.17562 -218.554046)
		(width 0.14478)
		(layer "In11.Cu")
		(net "M_L_CPU1_SA_DQ<19>")
	)
	(segment
		(start 162.641788 -219.685362)
		(end 162.82416 -219.685362)
		(width 0.14478)
		(layer "In11.Cu")
		(net "M_L_CPU1_SA_DQ<19>")
	)
	(segment
		(start 148.414486 -234.193334)
		(end 149.075648 -234.193334)
		(width 0.14478)
		(layer "In11.Cu")
		(net "M_L_CPU1_SA_DQ<19>")
	)
	(segment
		(start 170.282616 -218.150948)
		(end 171.1325 -219.000832)
		(width 0.14478)
		(layer "In11.Cu")
		(net "M_L_CPU1_SA_DQ<19>")
	)
	(segment
		(start 200.479406 -218.151202)
		(end 200.624186 -218.295982)
		(width 0.14478)
		(layer "In11.Cu")
		(net "M_L_CPU1_SA_DQ<19>")
	)
	(segment
		(start 147.13077 -235.168186)
		(end 147.13077 -234.980226)
		(width 0.0889)
		(layer "In11.Cu")
		(net "M_L_CPU1_SA_DQ<19>")
	)
	(segment
		(start 140.15339 -236.056932)
		(end 140.161772 -236.061758)
		(width 0.0889)
		(layer "In11.Cu")
		(net "M_L_CPU1_SA_DQ<19>")
	)
	(segment
		(start 160.90392 -221.42323)
		(end 161.066988 -221.260162)
		(width 0.14478)
		(layer "In11.Cu")
		(net "M_L_CPU1_SA_DQ<19>")
	)
	(segment
		(start 186.091322 -219.001086)
		(end 188.68263 -219.001086)
		(width 0.14478)
		(layer "In11.Cu")
		(net "M_L_CPU1_SA_DQ<19>")
	)
	(segment
		(start 162.47872 -219.84843)
		(end 162.641788 -219.685362)
		(width 0.14478)
		(layer "In11.Cu")
		(net "M_L_CPU1_SA_DQ<19>")
	)
	(segment
		(start 145.615406 -236.010958)
		(end 145.95729 -236.010958)
		(width 0.0889)
		(layer "In11.Cu")
		(net "M_L_CPU1_SA_DQ<19>")
	)
	(segment
		(start 141.667738 -236.061758)
		(end 141.67612 -236.056932)
		(width 0.0889)
		(layer "In11.Cu")
		(net "M_L_CPU1_SA_DQ<19>")
	)
	(segment
		(start 147.917662 -234.193334)
		(end 148.414486 -234.193334)
		(width 0.0889)
		(layer "In11.Cu")
		(net "M_L_CPU1_SA_DQ<19>")
	)
	(segment
		(start 161.69132 -220.866462)
		(end 161.69132 -220.63583)
		(width 0.14478)
		(layer "In11.Cu")
		(net "M_L_CPU1_SA_DQ<19>")
	)
	(segment
		(start 161.144204 -221.894146)
		(end 160.90392 -221.653862)
		(width 0.14478)
		(layer "In11.Cu")
		(net "M_L_CPU1_SA_DQ<19>")
	)
	(segment
		(start 165.973506 -219.01023)
		(end 166.832788 -218.150948)
		(width 0.14478)
		(layer "In11.Cu")
		(net "M_L_CPU1_SA_DQ<19>")
	)
	(segment
		(start 149.075648 -234.193334)
		(end 161.144204 -222.124778)
		(width 0.14478)
		(layer "In11.Cu")
		(net "M_L_CPU1_SA_DQ<19>")
	)
	(segment
		(start 181.0004 -219.000832)
		(end 181.85003 -218.151202)
		(width 0.14478)
		(layer "In11.Cu")
		(net "M_L_CPU1_SA_DQ<19>")
	)
	(segment
		(start 177.713894 -218.150948)
		(end 178.563778 -219.000832)
		(width 0.14478)
		(layer "In11.Cu")
		(net "M_L_CPU1_SA_DQ<19>")
	)
	(segment
		(start 189.532514 -218.151202)
		(end 192.92443 -218.151202)
		(width 0.14478)
		(layer "In11.Cu")
		(net "M_L_CPU1_SA_DQ<19>")
	)
	(segment
		(start 192.92443 -218.151202)
		(end 193.774314 -219.001086)
		(width 0.14478)
		(layer "In11.Cu")
		(net "M_L_CPU1_SA_DQ<19>")
	)
	(segment
		(start 162.47872 -220.079062)
		(end 162.47872 -219.84843)
		(width 0.14478)
		(layer "In11.Cu")
		(net "M_L_CPU1_SA_DQ<19>")
	)
	(segment
		(start 201.17562 -218.554046)
		(end 201.17562 -218.295982)
		(width 0.14478)
		(layer "In11.Cu")
		(net "M_L_CPU1_SA_DQ<19>")
	)
	(segment
		(start 193.774314 -219.001086)
		(end 195.996814 -219.001086)
		(width 0.14478)
		(layer "In11.Cu")
		(net "M_L_CPU1_SA_DQ<19>")
	)
	(segment
		(start 162.555936 -220.713046)
		(end 162.719004 -220.549978)
		(width 0.14478)
		(layer "In11.Cu")
		(net "M_L_CPU1_SA_DQ<19>")
	)
	(segment
		(start 163.499292 -219.01023)
		(end 165.973506 -219.01023)
		(width 0.14478)
		(layer "In11.Cu")
		(net "M_L_CPU1_SA_DQ<19>")
	)
	(segment
		(start 162.719004 -220.549978)
		(end 162.719004 -220.319346)
		(width 0.14478)
		(layer "In11.Cu")
		(net "M_L_CPU1_SA_DQ<19>")
	)
	(arc
		(start 144.876774 -236.070394)
		(mid 145.153503 -236.138077)
		(end 145.427954 -236.061758)
		(width 0.0889)
		(layer "In11.Cu")
		(net "M_L_CPU1_SA_DQ<19>")
	)
	(arc
		(start 137.963148 -236.035596)
		(mid 138.12548 -236.012778)
		(end 138.281918 -236.061758)
		(width 0.0889)
		(layer "In11.Cu")
		(net "M_L_CPU1_SA_DQ<19>")
	)
	(arc
		(start 141.101826 -236.061758)
		(mid 141.384782 -236.137935)
		(end 141.667738 -236.061758)
		(width 0.0889)
		(layer "In11.Cu")
		(net "M_L_CPU1_SA_DQ<19>")
	)
	(arc
		(start 143.547592 -236.061758)
		(mid 143.73479 -236.011376)
		(end 143.921988 -236.061758)
		(width 0.0889)
		(layer "In11.Cu")
		(net "M_L_CPU1_SA_DQ<19>")
	)
	(arc
		(start 142.607792 -236.061758)
		(mid 142.794736 -236.011503)
		(end 142.98168 -236.061758)
		(width 0.0889)
		(layer "In11.Cu")
		(net "M_L_CPU1_SA_DQ<19>")
	)
	(arc
		(start 141.67612 -236.056932)
		(mid 141.859628 -236.011438)
		(end 142.04188 -236.061758)
		(width 0.0889)
		(layer "In11.Cu")
		(net "M_L_CPU1_SA_DQ<19>")
	)
	(arc
		(start 138.281918 -236.061758)
		(mid 138.564874 -236.137935)
		(end 138.84783 -236.061758)
		(width 0.0889)
		(layer "In11.Cu")
		(net "M_L_CPU1_SA_DQ<19>")
	)
	(arc
		(start 143.921988 -236.061758)
		(mid 144.199055 -236.138029)
		(end 144.47774 -236.067854)
		(width 0.0889)
		(layer "In11.Cu")
		(net "M_L_CPU1_SA_DQ<19>")
	)
	(arc
		(start 140.727684 -236.061758)
		(mid 140.909935 -236.011408)
		(end 141.093444 -236.056932)
		(width 0.0889)
		(layer "In11.Cu")
		(net "M_L_CPU1_SA_DQ<19>")
	)
	(arc
		(start 139.78763 -236.061758)
		(mid 139.969881 -236.011408)
		(end 140.15339 -236.056932)
		(width 0.0889)
		(layer "In11.Cu")
		(net "M_L_CPU1_SA_DQ<19>")
	)
	(arc
		(start 138.84783 -236.061758)
		(mid 139.034774 -236.011503)
		(end 139.221718 -236.061758)
		(width 0.0889)
		(layer "In11.Cu")
		(net "M_L_CPU1_SA_DQ<19>")
	)
	(arc
		(start 139.221718 -236.061758)
		(mid 139.504674 -236.137935)
		(end 139.78763 -236.061758)
		(width 0.0889)
		(layer "In11.Cu")
		(net "M_L_CPU1_SA_DQ<19>")
	)
	(arc
		(start 142.04188 -236.061758)
		(mid 142.324836 -236.137935)
		(end 142.607792 -236.061758)
		(width 0.0889)
		(layer "In11.Cu")
		(net "M_L_CPU1_SA_DQ<19>")
	)
	(arc
		(start 142.98168 -236.061758)
		(mid 143.264636 -236.137935)
		(end 143.547592 -236.061758)
		(width 0.0889)
		(layer "In11.Cu")
		(net "M_L_CPU1_SA_DQ<19>")
	)
	(arc
		(start 140.161772 -236.061758)
		(mid 140.444728 -236.137935)
		(end 140.727684 -236.061758)
		(width 0.0889)
		(layer "In11.Cu")
		(net "M_L_CPU1_SA_DQ<19>")
	)
	(arc
		(start 145.427954 -236.061758)
		(mid 145.518317 -236.023948)
		(end 145.615406 -236.010958)
		(width 0.0889)
		(layer "In11.Cu")
		(net "M_L_CPU1_SA_DQ<19>")
	)
	(arc
		(start 144.488154 -236.061758)
		(mid 144.675098 -236.011503)
		(end 144.862042 -236.061758)
		(width 0.0889)
		(layer "In11.Cu")
		(net "M_L_CPU1_SA_DQ<19>")
	)
	(segment
		(start 139.037822 -235.84027)
		(end 139.504674 -235.574332)
		(width 0.10668)
		(layer "F.Cu")
		(net "M_L_CPU1_SA_DQ<18>")
	)
	(segment
		(start 166.005764 -217.310462)
		(end 166.855902 -216.460324)
		(width 0.14478)
		(layer "In11.Cu")
		(net "M_L_CPU1_SA_DQ<18>")
	)
	(segment
		(start 147.882102 -233.284014)
		(end 148.400516 -233.284014)
		(width 0.0889)
		(layer "In11.Cu")
		(net "M_L_CPU1_SA_DQ<18>")
	)
	(segment
		(start 156.55036 -225.432366)
		(end 156.55036 -225.201734)
		(width 0.14478)
		(layer "In11.Cu")
		(net "M_L_CPU1_SA_DQ<18>")
	)
	(segment
		(start 158.91256 -223.070166)
		(end 158.91256 -222.839534)
		(width 0.14478)
		(layer "In11.Cu")
		(net "M_L_CPU1_SA_DQ<18>")
	)
	(segment
		(start 158.91256 -222.839534)
		(end 158.642304 -222.569278)
		(width 0.14478)
		(layer "In11.Cu")
		(net "M_L_CPU1_SA_DQ<18>")
	)
	(segment
		(start 186.10072 -217.310462)
		(end 188.673232 -217.310462)
		(width 0.14478)
		(layer "In11.Cu")
		(net "M_L_CPU1_SA_DQ<18>")
	)
	(segment
		(start 146.46275 -234.436666)
		(end 146.92757 -234.436666)
		(width 0.0889)
		(layer "In11.Cu")
		(net "M_L_CPU1_SA_DQ<18>")
	)
	(segment
		(start 146.0119 -235.162852)
		(end 146.10461 -235.070142)
		(width 0.0889)
		(layer "In11.Cu")
		(net "M_L_CPU1_SA_DQ<18>")
	)
	(segment
		(start 178.82235 -217.310462)
		(end 180.987192 -217.310462)
		(width 0.14478)
		(layer "In11.Cu")
		(net "M_L_CPU1_SA_DQ<18>")
	)
	(segment
		(start 156.673804 -224.537778)
		(end 156.94406 -224.808034)
		(width 0.14478)
		(layer "In11.Cu")
		(net "M_L_CPU1_SA_DQ<18>")
	)
	(segment
		(start 158.642304 -222.569278)
		(end 158.642304 -222.338646)
		(width 0.14478)
		(layer "In11.Cu")
		(net "M_L_CPU1_SA_DQ<18>")
	)
	(segment
		(start 157.230572 -223.750378)
		(end 157.461204 -223.750378)
		(width 0.14478)
		(layer "In11.Cu")
		(net "M_L_CPU1_SA_DQ<18>")
	)
	(segment
		(start 139.504674 -235.574332)
		(end 139.35075 -235.308902)
		(width 0.0889)
		(layer "In11.Cu")
		(net "M_L_CPU1_SA_DQ<18>")
	)
	(segment
		(start 189.523116 -216.460578)
		(end 192.846452 -216.460578)
		(width 0.14478)
		(layer "In11.Cu")
		(net "M_L_CPU1_SA_DQ<18>")
	)
	(segment
		(start 177.972466 -216.460578)
		(end 178.82235 -217.310462)
		(width 0.14478)
		(layer "In11.Cu")
		(net "M_L_CPU1_SA_DQ<18>")
	)
	(segment
		(start 195.961 -217.310462)
		(end 196.810884 -216.460578)
		(width 0.14478)
		(layer "In11.Cu")
		(net "M_L_CPU1_SA_DQ<18>")
	)
	(segment
		(start 157.854904 -223.126046)
		(end 158.017972 -222.962978)
		(width 0.14478)
		(layer "In11.Cu")
		(net "M_L_CPU1_SA_DQ<18>")
	)
	(segment
		(start 144.005046 -235.258864)
		(end 144.016984 -235.252006)
		(width 0.0889)
		(layer "In11.Cu")
		(net "M_L_CPU1_SA_DQ<18>")
	)
	(segment
		(start 146.10461 -235.070142)
		(end 146.10461 -234.794806)
		(width 0.0889)
		(layer "In11.Cu")
		(net "M_L_CPU1_SA_DQ<18>")
	)
	(segment
		(start 146.10461 -234.794806)
		(end 146.46275 -234.436666)
		(width 0.0889)
		(layer "In11.Cu")
		(net "M_L_CPU1_SA_DQ<18>")
	)
	(segment
		(start 159.036004 -222.175578)
		(end 159.30626 -222.445834)
		(width 0.14478)
		(layer "In11.Cu")
		(net "M_L_CPU1_SA_DQ<18>")
	)
	(segment
		(start 192.846452 -216.460578)
		(end 193.696336 -217.310462)
		(width 0.14478)
		(layer "In11.Cu")
		(net "M_L_CPU1_SA_DQ<18>")
	)
	(segment
		(start 157.854904 -223.356678)
		(end 157.854904 -223.126046)
		(width 0.14478)
		(layer "In11.Cu")
		(net "M_L_CPU1_SA_DQ<18>")
	)
	(segment
		(start 159.30626 -222.445834)
		(end 159.536892 -222.445834)
		(width 0.14478)
		(layer "In11.Cu")
		(net "M_L_CPU1_SA_DQ<18>")
	)
	(segment
		(start 157.33776 -224.644966)
		(end 157.33776 -224.414334)
		(width 0.14478)
		(layer "In11.Cu")
		(net "M_L_CPU1_SA_DQ<18>")
	)
	(segment
		(start 158.51886 -223.233234)
		(end 158.749492 -223.233234)
		(width 0.14478)
		(layer "In11.Cu")
		(net "M_L_CPU1_SA_DQ<18>")
	)
	(segment
		(start 147.62607 -233.540046)
		(end 147.882102 -233.284014)
		(width 0.0889)
		(layer "In11.Cu")
		(net "M_L_CPU1_SA_DQ<18>")
	)
	(segment
		(start 159.536892 -222.445834)
		(end 159.780986 -222.20174)
		(width 0.14478)
		(layer "In11.Cu")
		(net "M_L_CPU1_SA_DQ<18>")
	)
	(segment
		(start 196.810884 -216.460578)
		(end 201.723244 -216.460578)
		(width 0.14478)
		(layer "In11.Cu")
		(net "M_L_CPU1_SA_DQ<18>")
	)
	(segment
		(start 158.805372 -222.175578)
		(end 159.036004 -222.175578)
		(width 0.14478)
		(layer "In11.Cu")
		(net "M_L_CPU1_SA_DQ<18>")
	)
	(segment
		(start 157.33776 -224.414334)
		(end 157.067504 -224.144078)
		(width 0.14478)
		(layer "In11.Cu")
		(net "M_L_CPU1_SA_DQ<18>")
	)
	(segment
		(start 171.141898 -217.310462)
		(end 173.619668 -217.310462)
		(width 0.14478)
		(layer "In11.Cu")
		(net "M_L_CPU1_SA_DQ<18>")
	)
	(segment
		(start 158.642304 -222.338646)
		(end 158.805372 -222.175578)
		(width 0.14478)
		(layer "In11.Cu")
		(net "M_L_CPU1_SA_DQ<18>")
	)
	(segment
		(start 157.174692 -224.808034)
		(end 157.33776 -224.644966)
		(width 0.14478)
		(layer "In11.Cu")
		(net "M_L_CPU1_SA_DQ<18>")
	)
	(segment
		(start 157.067504 -223.913446)
		(end 157.230572 -223.750378)
		(width 0.14478)
		(layer "In11.Cu")
		(net "M_L_CPU1_SA_DQ<18>")
	)
	(segment
		(start 158.749492 -223.233234)
		(end 158.91256 -223.070166)
		(width 0.14478)
		(layer "In11.Cu")
		(net "M_L_CPU1_SA_DQ<18>")
	)
	(segment
		(start 156.280104 -224.700846)
		(end 156.443172 -224.537778)
		(width 0.14478)
		(layer "In11.Cu")
		(net "M_L_CPU1_SA_DQ<18>")
	)
	(segment
		(start 156.280104 -224.931478)
		(end 156.280104 -224.700846)
		(width 0.14478)
		(layer "In11.Cu")
		(net "M_L_CPU1_SA_DQ<18>")
	)
	(segment
		(start 139.35075 -235.308902)
		(end 139.373102 -235.22559)
		(width 0.0889)
		(layer "In11.Cu")
		(net "M_L_CPU1_SA_DQ<18>")
	)
	(segment
		(start 145.33118 -235.252006)
		(end 145.343118 -235.258864)
		(width 0.0889)
		(layer "In11.Cu")
		(net "M_L_CPU1_SA_DQ<18>")
	)
	(segment
		(start 146.92757 -234.436666)
		(end 147.62607 -233.738166)
		(width 0.0889)
		(layer "In11.Cu")
		(net "M_L_CPU1_SA_DQ<18>")
	)
	(segment
		(start 143.077692 -235.251752)
		(end 143.086074 -235.246926)
		(width 0.0889)
		(layer "In11.Cu")
		(net "M_L_CPU1_SA_DQ<18>")
	)
	(segment
		(start 148.400516 -233.284014)
		(end 148.698712 -233.284014)
		(width 0.14478)
		(layer "In11.Cu")
		(net "M_L_CPU1_SA_DQ<18>")
	)
	(segment
		(start 158.12516 -223.857566)
		(end 158.12516 -223.626934)
		(width 0.14478)
		(layer "In11.Cu")
		(net "M_L_CPU1_SA_DQ<18>")
	)
	(segment
		(start 157.461204 -223.750378)
		(end 157.73146 -224.020634)
		(width 0.14478)
		(layer "In11.Cu")
		(net "M_L_CPU1_SA_DQ<18>")
	)
	(segment
		(start 166.855902 -216.460324)
		(end 170.29176 -216.460324)
		(width 0.14478)
		(layer "In11.Cu")
		(net "M_L_CPU1_SA_DQ<18>")
	)
	(segment
		(start 157.73146 -224.020634)
		(end 157.962092 -224.020634)
		(width 0.14478)
		(layer "In11.Cu")
		(net "M_L_CPU1_SA_DQ<18>")
	)
	(segment
		(start 193.696336 -217.310462)
		(end 195.961 -217.310462)
		(width 0.14478)
		(layer "In11.Cu")
		(net "M_L_CPU1_SA_DQ<18>")
	)
	(segment
		(start 140.257784 -235.251752)
		(end 140.266166 -235.246926)
		(width 0.0889)
		(layer "In11.Cu")
		(net "M_L_CPU1_SA_DQ<18>")
	)
	(segment
		(start 148.698712 -233.284014)
		(end 156.55036 -225.432366)
		(width 0.14478)
		(layer "In11.Cu")
		(net "M_L_CPU1_SA_DQ<18>")
	)
	(segment
		(start 156.443172 -224.537778)
		(end 156.673804 -224.537778)
		(width 0.14478)
		(layer "In11.Cu")
		(net "M_L_CPU1_SA_DQ<18>")
	)
	(segment
		(start 157.067504 -224.144078)
		(end 157.067504 -223.913446)
		(width 0.14478)
		(layer "In11.Cu")
		(net "M_L_CPU1_SA_DQ<18>")
	)
	(segment
		(start 170.29176 -216.460324)
		(end 171.141898 -217.310462)
		(width 0.14478)
		(layer "In11.Cu")
		(net "M_L_CPU1_SA_DQ<18>")
	)
	(segment
		(start 173.619668 -217.310462)
		(end 174.469552 -216.460578)
		(width 0.14478)
		(layer "In11.Cu")
		(net "M_L_CPU1_SA_DQ<18>")
	)
	(segment
		(start 156.94406 -224.808034)
		(end 157.174692 -224.808034)
		(width 0.14478)
		(layer "In11.Cu")
		(net "M_L_CPU1_SA_DQ<18>")
	)
	(segment
		(start 159.780986 -222.20174)
		(end 159.780986 -221.174564)
		(width 0.14478)
		(layer "In11.Cu")
		(net "M_L_CPU1_SA_DQ<18>")
	)
	(segment
		(start 142.503398 -235.246926)
		(end 142.51178 -235.251752)
		(width 0.0889)
		(layer "In11.Cu")
		(net "M_L_CPU1_SA_DQ<18>")
	)
	(segment
		(start 159.780986 -221.174564)
		(end 163.645088 -217.310462)
		(width 0.14478)
		(layer "In11.Cu")
		(net "M_L_CPU1_SA_DQ<18>")
	)
	(segment
		(start 147.62607 -233.738166)
		(end 147.62607 -233.540046)
		(width 0.0889)
		(layer "In11.Cu")
		(net "M_L_CPU1_SA_DQ<18>")
	)
	(segment
		(start 157.962092 -224.020634)
		(end 158.12516 -223.857566)
		(width 0.14478)
		(layer "In11.Cu")
		(net "M_L_CPU1_SA_DQ<18>")
	)
	(segment
		(start 188.673232 -217.310462)
		(end 189.523116 -216.460578)
		(width 0.14478)
		(layer "In11.Cu")
		(net "M_L_CPU1_SA_DQ<18>")
	)
	(segment
		(start 158.12516 -223.626934)
		(end 157.854904 -223.356678)
		(width 0.14478)
		(layer "In11.Cu")
		(net "M_L_CPU1_SA_DQ<18>")
	)
	(segment
		(start 181.837076 -216.460578)
		(end 185.250836 -216.460578)
		(width 0.14478)
		(layer "In11.Cu")
		(net "M_L_CPU1_SA_DQ<18>")
	)
	(segment
		(start 144.390618 -235.251752)
		(end 144.408652 -235.26242)
		(width 0.0889)
		(layer "In11.Cu")
		(net "M_L_CPU1_SA_DQ<18>")
	)
	(segment
		(start 144.016984 -235.252006)
		(end 144.0307 -235.244132)
		(width 0.0889)
		(layer "In11.Cu")
		(net "M_L_CPU1_SA_DQ<18>")
	)
	(segment
		(start 185.250836 -216.460578)
		(end 186.10072 -217.310462)
		(width 0.14478)
		(layer "In11.Cu")
		(net "M_L_CPU1_SA_DQ<18>")
	)
	(segment
		(start 174.469552 -216.460578)
		(end 177.972466 -216.460578)
		(width 0.14478)
		(layer "In11.Cu")
		(net "M_L_CPU1_SA_DQ<18>")
	)
	(segment
		(start 158.248604 -222.962978)
		(end 158.51886 -223.233234)
		(width 0.14478)
		(layer "In11.Cu")
		(net "M_L_CPU1_SA_DQ<18>")
	)
	(segment
		(start 163.645088 -217.310462)
		(end 166.005764 -217.310462)
		(width 0.14478)
		(layer "In11.Cu")
		(net "M_L_CPU1_SA_DQ<18>")
	)
	(segment
		(start 156.55036 -225.201734)
		(end 156.280104 -224.931478)
		(width 0.14478)
		(layer "In11.Cu")
		(net "M_L_CPU1_SA_DQ<18>")
	)
	(segment
		(start 158.017972 -222.962978)
		(end 158.248604 -222.962978)
		(width 0.14478)
		(layer "In11.Cu")
		(net "M_L_CPU1_SA_DQ<18>")
	)
	(segment
		(start 180.987192 -217.310462)
		(end 181.837076 -216.460578)
		(width 0.14478)
		(layer "In11.Cu")
		(net "M_L_CPU1_SA_DQ<18>")
	)
	(segment
		(start 201.723244 -216.460578)
		(end 202.147932 -216.885266)
		(width 0.14478)
		(layer "In11.Cu")
		(net "M_L_CPU1_SA_DQ<18>")
	)
	(segment
		(start 145.311114 -235.240576)
		(end 145.33118 -235.252006)
		(width 0.0889)
		(layer "In11.Cu")
		(net "M_L_CPU1_SA_DQ<18>")
	)
	(arc
		(start 140.266166 -235.246926)
		(mid 140.449674 -235.201432)
		(end 140.631926 -235.251752)
		(width 0.0889)
		(layer "In11.Cu")
		(net "M_L_CPU1_SA_DQ<18>")
	)
	(arc
		(start 139.691872 -235.251752)
		(mid 139.974828 -235.327929)
		(end 140.257784 -235.251752)
		(width 0.0889)
		(layer "In11.Cu")
		(net "M_L_CPU1_SA_DQ<18>")
	)
	(arc
		(start 144.408652 -235.26242)
		(mid 144.684347 -235.328263)
		(end 144.957292 -235.251752)
		(width 0.0889)
		(layer "In11.Cu")
		(net "M_L_CPU1_SA_DQ<18>")
	)
	(arc
		(start 140.631926 -235.251752)
		(mid 140.914882 -235.327929)
		(end 141.197838 -235.251752)
		(width 0.0889)
		(layer "In11.Cu")
		(net "M_L_CPU1_SA_DQ<18>")
	)
	(arc
		(start 139.373102 -235.22559)
		(mid 139.535434 -235.202772)
		(end 139.691872 -235.251752)
		(width 0.0889)
		(layer "In11.Cu")
		(net "M_L_CPU1_SA_DQ<18>")
	)
	(arc
		(start 145.89633 -235.251752)
		(mid 145.957003 -235.211056)
		(end 146.0119 -235.162852)
		(width 0.0889)
		(layer "In11.Cu")
		(net "M_L_CPU1_SA_DQ<18>")
	)
	(arc
		(start 142.51178 -235.251752)
		(mid 142.794736 -235.327929)
		(end 143.077692 -235.251752)
		(width 0.0889)
		(layer "In11.Cu")
		(net "M_L_CPU1_SA_DQ<18>")
	)
	(arc
		(start 142.137638 -235.251752)
		(mid 142.319889 -235.201402)
		(end 142.503398 -235.246926)
		(width 0.0889)
		(layer "In11.Cu")
		(net "M_L_CPU1_SA_DQ<18>")
	)
	(arc
		(start 143.451834 -235.251752)
		(mid 143.727512 -235.327882)
		(end 144.005046 -235.258864)
		(width 0.0889)
		(layer "In11.Cu")
		(net "M_L_CPU1_SA_DQ<18>")
	)
	(arc
		(start 144.957292 -235.251752)
		(mid 145.132784 -235.201553)
		(end 145.311114 -235.240576)
		(width 0.0889)
		(layer "In11.Cu")
		(net "M_L_CPU1_SA_DQ<18>")
	)
	(arc
		(start 145.343118 -235.258864)
		(mid 145.620652 -235.327845)
		(end 145.89633 -235.251752)
		(width 0.0889)
		(layer "In11.Cu")
		(net "M_L_CPU1_SA_DQ<18>")
	)
	(arc
		(start 141.571726 -235.251752)
		(mid 141.854682 -235.327929)
		(end 142.137638 -235.251752)
		(width 0.0889)
		(layer "In11.Cu")
		(net "M_L_CPU1_SA_DQ<18>")
	)
	(arc
		(start 141.197838 -235.251752)
		(mid 141.384782 -235.201497)
		(end 141.571726 -235.251752)
		(width 0.0889)
		(layer "In11.Cu")
		(net "M_L_CPU1_SA_DQ<18>")
	)
	(arc
		(start 144.0307 -235.244132)
		(mid 144.21163 -235.201654)
		(end 144.390618 -235.251752)
		(width 0.0889)
		(layer "In11.Cu")
		(net "M_L_CPU1_SA_DQ<18>")
	)
	(arc
		(start 143.086074 -235.246926)
		(mid 143.269582 -235.201432)
		(end 143.451834 -235.251752)
		(width 0.0889)
		(layer "In11.Cu")
		(net "M_L_CPU1_SA_DQ<18>")
	)
	(segment
		(start 137.157968 -235.84027)
		(end 137.62482 -235.574332)
		(width 0.10668)
		(layer "F.Cu")
		(net "M_L_CPU1_SA_DQ<17>")
	)
	(segment
		(start 177.176938 -217.310462)
		(end 179.22875 -218.160346)
		(width 0.14478)
		(layer "In11.Cu")
		(net "M_L_CPU1_SA_DQ<17>")
	)
	(segment
		(start 194.407282 -218.160346)
		(end 195.555108 -218.160346)
		(width 0.14478)
		(layer "In11.Cu")
		(net "M_L_CPU1_SA_DQ<17>")
	)
	(segment
		(start 147.04695 -234.655106)
		(end 147.963382 -233.738674)
		(width 0.0889)
		(layer "In11.Cu")
		(net "M_L_CPU1_SA_DQ<17>")
	)
	(segment
		(start 182.637176 -217.310462)
		(end 184.56402 -217.310462)
		(width 0.14478)
		(layer "In11.Cu")
		(net "M_L_CPU1_SA_DQ<17>")
	)
	(segment
		(start 189.950598 -217.310462)
		(end 192.35547 -217.310462)
		(width 0.14478)
		(layer "In11.Cu")
		(net "M_L_CPU1_SA_DQ<17>")
	)
	(segment
		(start 147.963382 -233.738674)
		(end 148.387816 -233.738674)
		(width 0.0889)
		(layer "In11.Cu")
		(net "M_L_CPU1_SA_DQ<17>")
	)
	(segment
		(start 139.31773 -235.896912)
		(end 139.326112 -235.901738)
		(width 0.0889)
		(layer "In11.Cu")
		(net "M_L_CPU1_SA_DQ<17>")
	)
	(segment
		(start 143.077692 -235.896912)
		(end 143.086074 -235.901738)
		(width 0.0889)
		(layer "In11.Cu")
		(net "M_L_CPU1_SA_DQ<17>")
	)
	(segment
		(start 184.56402 -217.310462)
		(end 186.615832 -218.160346)
		(width 0.14478)
		(layer "In11.Cu")
		(net "M_L_CPU1_SA_DQ<17>")
	)
	(segment
		(start 146.60245 -234.655106)
		(end 147.04695 -234.655106)
		(width 0.0889)
		(layer "In11.Cu")
		(net "M_L_CPU1_SA_DQ<17>")
	)
	(segment
		(start 179.22875 -218.160346)
		(end 180.585364 -218.160346)
		(width 0.14478)
		(layer "In11.Cu")
		(net "M_L_CPU1_SA_DQ<17>")
	)
	(segment
		(start 171.117514 -218.160346)
		(end 173.717712 -218.160346)
		(width 0.14478)
		(layer "In11.Cu")
		(net "M_L_CPU1_SA_DQ<17>")
	)
	(segment
		(start 144.38376 -235.901738)
		(end 144.392142 -235.896912)
		(width 0.0889)
		(layer "In11.Cu")
		(net "M_L_CPU1_SA_DQ<17>")
	)
	(segment
		(start 138.743436 -235.901738)
		(end 138.751818 -235.896912)
		(width 0.0889)
		(layer "In11.Cu")
		(net "M_L_CPU1_SA_DQ<17>")
	)
	(segment
		(start 148.387816 -233.738674)
		(end 148.88718 -233.738674)
		(width 0.14478)
		(layer "In11.Cu")
		(net "M_L_CPU1_SA_DQ<17>")
	)
	(segment
		(start 173.717712 -218.160346)
		(end 174.567596 -217.310462)
		(width 0.14478)
		(layer "In11.Cu")
		(net "M_L_CPU1_SA_DQ<17>")
	)
	(segment
		(start 204.336142 -217.310462)
		(end 206.040482 -217.649552)
		(width 0.14478)
		(layer "In11.Cu")
		(net "M_L_CPU1_SA_DQ<17>")
	)
	(segment
		(start 145.777458 -235.820458)
		(end 146.38147 -235.216446)
		(width 0.0889)
		(layer "In11.Cu")
		(net "M_L_CPU1_SA_DQ<17>")
	)
	(segment
		(start 174.567596 -217.310462)
		(end 177.176938 -217.310462)
		(width 0.14478)
		(layer "In11.Cu")
		(net "M_L_CPU1_SA_DQ<17>")
	)
	(segment
		(start 165.91661 -218.160346)
		(end 166.766494 -217.310462)
		(width 0.14478)
		(layer "In11.Cu")
		(net "M_L_CPU1_SA_DQ<17>")
	)
	(segment
		(start 180.585364 -218.160346)
		(end 182.637176 -217.310462)
		(width 0.14478)
		(layer "In11.Cu")
		(net "M_L_CPU1_SA_DQ<17>")
	)
	(segment
		(start 166.766494 -217.310462)
		(end 170.26763 -217.310462)
		(width 0.14478)
		(layer "In11.Cu")
		(net "M_L_CPU1_SA_DQ<17>")
	)
	(segment
		(start 145.615152 -235.820458)
		(end 145.777458 -235.820458)
		(width 0.0889)
		(layer "In11.Cu")
		(net "M_L_CPU1_SA_DQ<17>")
	)
	(segment
		(start 137.778744 -235.839762)
		(end 137.874756 -235.865162)
		(width 0.0889)
		(layer "In11.Cu")
		(net "M_L_CPU1_SA_DQ<17>")
	)
	(segment
		(start 148.88718 -233.738674)
		(end 160.235646 -222.390208)
		(width 0.14478)
		(layer "In11.Cu")
		(net "M_L_CPU1_SA_DQ<17>")
	)
	(segment
		(start 144.9578 -235.896912)
		(end 144.966182 -235.901738)
		(width 0.0889)
		(layer "In11.Cu")
		(net "M_L_CPU1_SA_DQ<17>")
	)
	(segment
		(start 197.60692 -217.310462)
		(end 204.336142 -217.310462)
		(width 0.14478)
		(layer "In11.Cu")
		(net "M_L_CPU1_SA_DQ<17>")
	)
	(segment
		(start 187.898786 -218.160346)
		(end 189.950598 -217.310462)
		(width 0.14478)
		(layer "In11.Cu")
		(net "M_L_CPU1_SA_DQ<17>")
	)
	(segment
		(start 186.615832 -218.160346)
		(end 187.898786 -218.160346)
		(width 0.14478)
		(layer "In11.Cu")
		(net "M_L_CPU1_SA_DQ<17>")
	)
	(segment
		(start 146.38147 -234.876086)
		(end 146.60245 -234.655106)
		(width 0.0889)
		(layer "In11.Cu")
		(net "M_L_CPU1_SA_DQ<17>")
	)
	(segment
		(start 143.451834 -235.896912)
		(end 143.462248 -235.890816)
		(width 0.0889)
		(layer "In11.Cu")
		(net "M_L_CPU1_SA_DQ<17>")
	)
	(segment
		(start 160.235646 -222.390208)
		(end 160.235646 -221.363032)
		(width 0.14478)
		(layer "In11.Cu")
		(net "M_L_CPU1_SA_DQ<17>")
	)
	(segment
		(start 206.040482 -217.649552)
		(end 206.248 -217.735404)
		(width 0.14478)
		(layer "In11.Cu")
		(net "M_L_CPU1_SA_DQ<17>")
	)
	(segment
		(start 163.438332 -218.160346)
		(end 165.91661 -218.160346)
		(width 0.14478)
		(layer "In11.Cu")
		(net "M_L_CPU1_SA_DQ<17>")
	)
	(segment
		(start 137.62482 -235.574332)
		(end 137.778744 -235.839762)
		(width 0.0889)
		(layer "In11.Cu")
		(net "M_L_CPU1_SA_DQ<17>")
	)
	(segment
		(start 144.947386 -235.890816)
		(end 144.9578 -235.896912)
		(width 0.0889)
		(layer "In11.Cu")
		(net "M_L_CPU1_SA_DQ<17>")
	)
	(segment
		(start 146.38147 -235.216446)
		(end 146.38147 -234.876086)
		(width 0.0889)
		(layer "In11.Cu")
		(net "M_L_CPU1_SA_DQ<17>")
	)
	(segment
		(start 140.257784 -235.896912)
		(end 140.266166 -235.901738)
		(width 0.0889)
		(layer "In11.Cu")
		(net "M_L_CPU1_SA_DQ<17>")
	)
	(segment
		(start 192.35547 -217.310462)
		(end 194.407282 -218.160346)
		(width 0.14478)
		(layer "In11.Cu")
		(net "M_L_CPU1_SA_DQ<17>")
	)
	(segment
		(start 142.503398 -235.901738)
		(end 142.51178 -235.896912)
		(width 0.0889)
		(layer "In11.Cu")
		(net "M_L_CPU1_SA_DQ<17>")
	)
	(segment
		(start 170.26763 -217.310462)
		(end 171.117514 -218.160346)
		(width 0.14478)
		(layer "In11.Cu")
		(net "M_L_CPU1_SA_DQ<17>")
	)
	(segment
		(start 195.555108 -218.160346)
		(end 197.60692 -217.310462)
		(width 0.14478)
		(layer "In11.Cu")
		(net "M_L_CPU1_SA_DQ<17>")
	)
	(segment
		(start 160.235646 -221.363032)
		(end 163.438332 -218.160346)
		(width 0.14478)
		(layer "In11.Cu")
		(net "M_L_CPU1_SA_DQ<17>")
	)
	(arc
		(start 138.377676 -235.896912)
		(mid 138.559927 -235.947262)
		(end 138.743436 -235.901738)
		(width 0.0889)
		(layer "In11.Cu")
		(net "M_L_CPU1_SA_DQ<17>")
	)
	(arc
		(start 141.197838 -235.896912)
		(mid 141.384782 -235.947167)
		(end 141.571726 -235.896912)
		(width 0.0889)
		(layer "In11.Cu")
		(net "M_L_CPU1_SA_DQ<17>")
	)
	(arc
		(start 143.086074 -235.901738)
		(mid 143.269582 -235.947232)
		(end 143.451834 -235.896912)
		(width 0.0889)
		(layer "In11.Cu")
		(net "M_L_CPU1_SA_DQ<17>")
	)
	(arc
		(start 142.137638 -235.896912)
		(mid 142.319889 -235.947262)
		(end 142.503398 -235.901738)
		(width 0.0889)
		(layer "In11.Cu")
		(net "M_L_CPU1_SA_DQ<17>")
	)
	(arc
		(start 141.571726 -235.896912)
		(mid 141.854682 -235.820735)
		(end 142.137638 -235.896912)
		(width 0.0889)
		(layer "In11.Cu")
		(net "M_L_CPU1_SA_DQ<17>")
	)
	(arc
		(start 140.631926 -235.896912)
		(mid 140.914882 -235.820735)
		(end 141.197838 -235.896912)
		(width 0.0889)
		(layer "In11.Cu")
		(net "M_L_CPU1_SA_DQ<17>")
	)
	(arc
		(start 144.018 -235.896912)
		(mid 144.200251 -235.947262)
		(end 144.38376 -235.901738)
		(width 0.0889)
		(layer "In11.Cu")
		(net "M_L_CPU1_SA_DQ<17>")
	)
	(arc
		(start 145.331942 -235.896912)
		(mid 145.46849 -235.839956)
		(end 145.615152 -235.820458)
		(width 0.0889)
		(layer "In11.Cu")
		(net "M_L_CPU1_SA_DQ<17>")
	)
	(arc
		(start 142.51178 -235.896912)
		(mid 142.794736 -235.820735)
		(end 143.077692 -235.896912)
		(width 0.0889)
		(layer "In11.Cu")
		(net "M_L_CPU1_SA_DQ<17>")
	)
	(arc
		(start 144.392142 -235.896912)
		(mid 144.668955 -235.820769)
		(end 144.947386 -235.890816)
		(width 0.0889)
		(layer "In11.Cu")
		(net "M_L_CPU1_SA_DQ<17>")
	)
	(arc
		(start 138.751818 -235.896912)
		(mid 139.034774 -235.820735)
		(end 139.31773 -235.896912)
		(width 0.0889)
		(layer "In11.Cu")
		(net "M_L_CPU1_SA_DQ<17>")
	)
	(arc
		(start 140.266166 -235.901738)
		(mid 140.449674 -235.947232)
		(end 140.631926 -235.896912)
		(width 0.0889)
		(layer "In11.Cu")
		(net "M_L_CPU1_SA_DQ<17>")
	)
	(arc
		(start 139.691872 -235.896912)
		(mid 139.974828 -235.820735)
		(end 140.257784 -235.896912)
		(width 0.0889)
		(layer "In11.Cu")
		(net "M_L_CPU1_SA_DQ<17>")
	)
	(arc
		(start 137.874756 -235.865162)
		(mid 138.129964 -235.821685)
		(end 138.377676 -235.896912)
		(width 0.0889)
		(layer "In11.Cu")
		(net "M_L_CPU1_SA_DQ<17>")
	)
	(arc
		(start 139.326112 -235.901738)
		(mid 139.50962 -235.947232)
		(end 139.691872 -235.896912)
		(width 0.0889)
		(layer "In11.Cu")
		(net "M_L_CPU1_SA_DQ<17>")
	)
	(arc
		(start 144.966182 -235.901738)
		(mid 145.14969 -235.947232)
		(end 145.331942 -235.896912)
		(width 0.0889)
		(layer "In11.Cu")
		(net "M_L_CPU1_SA_DQ<17>")
	)
	(arc
		(start 143.462248 -235.890816)
		(mid 143.740934 -235.820596)
		(end 144.018 -235.896912)
		(width 0.0889)
		(layer "In11.Cu")
		(net "M_L_CPU1_SA_DQ<17>")
	)
	(segment
		(start 138.567922 -235.030264)
		(end 139.034774 -234.764326)
		(width 0.10668)
		(layer "F.Cu")
		(net "M_L_CPU1_SA_DQ<16>")
	)
	(segment
		(start 143.92148 -235.086652)
		(end 143.933418 -235.079794)
		(width 0.0889)
		(layer "In11.Cu")
		(net "M_L_CPU1_SA_DQ<16>")
	)
	(segment
		(start 147.95627 -232.849166)
		(end 148.490432 -232.849166)
		(width 0.0889)
		(layer "In11.Cu")
		(net "M_L_CPU1_SA_DQ<16>")
	)
	(segment
		(start 186.10072 -216.460324)
		(end 188.123576 -216.460324)
		(width 0.14478)
		(layer "In11.Cu")
		(net "M_L_CPU1_SA_DQ<16>")
	)
	(segment
		(start 182.453788 -215.61044)
		(end 185.250836 -215.61044)
		(width 0.14478)
		(layer "In11.Cu")
		(net "M_L_CPU1_SA_DQ<16>")
	)
	(segment
		(start 177.972466 -215.61044)
		(end 178.82235 -216.460324)
		(width 0.14478)
		(layer "In11.Cu")
		(net "M_L_CPU1_SA_DQ<16>")
	)
	(segment
		(start 145.405348 -235.074206)
		(end 145.443194 -235.09605)
		(width 0.0889)
		(layer "In11.Cu")
		(net "M_L_CPU1_SA_DQ<16>")
	)
	(segment
		(start 155.75026 -224.562162)
		(end 163.852098 -216.460324)
		(width 0.14478)
		(layer "In11.Cu")
		(net "M_L_CPU1_SA_DQ<16>")
	)
	(segment
		(start 148.57095 -232.768648)
		(end 155.75026 -225.589338)
		(width 0.14478)
		(layer "In11.Cu")
		(net "M_L_CPU1_SA_DQ<16>")
	)
	(segment
		(start 147.35429 -233.451146)
		(end 147.95627 -232.849166)
		(width 0.0889)
		(layer "In11.Cu")
		(net "M_L_CPU1_SA_DQ<16>")
	)
	(segment
		(start 141.093444 -235.091732)
		(end 141.101826 -235.086906)
		(width 0.0889)
		(layer "In11.Cu")
		(net "M_L_CPU1_SA_DQ<16>")
	)
	(segment
		(start 155.75026 -225.589338)
		(end 155.75026 -224.562162)
		(width 0.14478)
		(layer "In11.Cu")
		(net "M_L_CPU1_SA_DQ<16>")
	)
	(segment
		(start 178.82235 -216.460324)
		(end 180.401976 -216.460324)
		(width 0.14478)
		(layer "In11.Cu")
		(net "M_L_CPU1_SA_DQ<16>")
	)
	(segment
		(start 147.35429 -233.700066)
		(end 147.35429 -233.451146)
		(width 0.0889)
		(layer "In11.Cu")
		(net "M_L_CPU1_SA_DQ<16>")
	)
	(segment
		(start 170.98772 -216.460324)
		(end 173.59884 -216.460324)
		(width 0.14478)
		(layer "In11.Cu")
		(net "M_L_CPU1_SA_DQ<16>")
	)
	(segment
		(start 139.188698 -235.029756)
		(end 139.28471 -235.055156)
		(width 0.0889)
		(layer "In11.Cu")
		(net "M_L_CPU1_SA_DQ<16>")
	)
	(segment
		(start 180.401976 -216.460324)
		(end 182.453788 -215.61044)
		(width 0.14478)
		(layer "In11.Cu")
		(net "M_L_CPU1_SA_DQ<16>")
	)
	(segment
		(start 166.670482 -215.61044)
		(end 170.137836 -215.61044)
		(width 0.14478)
		(layer "In11.Cu")
		(net "M_L_CPU1_SA_DQ<16>")
	)
	(segment
		(start 192.736216 -215.61044)
		(end 193.5861 -216.460324)
		(width 0.14478)
		(layer "In11.Cu")
		(net "M_L_CPU1_SA_DQ<16>")
	)
	(segment
		(start 145.877026 -235.027978)
		(end 145.89125 -235.013754)
		(width 0.0889)
		(layer "In11.Cu")
		(net "M_L_CPU1_SA_DQ<16>")
	)
	(segment
		(start 140.15339 -235.091732)
		(end 140.161772 -235.086906)
		(width 0.0889)
		(layer "In11.Cu")
		(net "M_L_CPU1_SA_DQ<16>")
	)
	(segment
		(start 195.571872 -216.460324)
		(end 197.623684 -215.61044)
		(width 0.14478)
		(layer "In11.Cu")
		(net "M_L_CPU1_SA_DQ<16>")
	)
	(segment
		(start 141.667738 -235.086906)
		(end 141.67612 -235.091732)
		(width 0.0889)
		(layer "In11.Cu")
		(net "M_L_CPU1_SA_DQ<16>")
	)
	(segment
		(start 173.59884 -216.460324)
		(end 174.448724 -215.61044)
		(width 0.14478)
		(layer "In11.Cu")
		(net "M_L_CPU1_SA_DQ<16>")
	)
	(segment
		(start 139.034774 -234.764326)
		(end 139.188698 -235.029756)
		(width 0.0889)
		(layer "In11.Cu")
		(net "M_L_CPU1_SA_DQ<16>")
	)
	(segment
		(start 143.905224 -235.09605)
		(end 143.92148 -235.086652)
		(width 0.0889)
		(layer "In11.Cu")
		(net "M_L_CPU1_SA_DQ<16>")
	)
	(segment
		(start 165.820598 -216.460324)
		(end 166.670482 -215.61044)
		(width 0.14478)
		(layer "In11.Cu")
		(net "M_L_CPU1_SA_DQ<16>")
	)
	(segment
		(start 146.38909 -234.230926)
		(end 146.82343 -234.230926)
		(width 0.0889)
		(layer "In11.Cu")
		(net "M_L_CPU1_SA_DQ<16>")
	)
	(segment
		(start 146.82343 -234.230926)
		(end 147.35429 -233.700066)
		(width 0.0889)
		(layer "In11.Cu")
		(net "M_L_CPU1_SA_DQ<16>")
	)
	(segment
		(start 204.118718 -215.61044)
		(end 206.246222 -216.033604)
		(width 0.14478)
		(layer "In11.Cu")
		(net "M_L_CPU1_SA_DQ<16>")
	)
	(segment
		(start 144.48663 -235.086906)
		(end 144.498314 -235.093764)
		(width 0.0889)
		(layer "In11.Cu")
		(net "M_L_CPU1_SA_DQ<16>")
	)
	(segment
		(start 170.137836 -215.61044)
		(end 170.98772 -216.460324)
		(width 0.14478)
		(layer "In11.Cu")
		(net "M_L_CPU1_SA_DQ<16>")
	)
	(segment
		(start 163.852098 -216.460324)
		(end 165.820598 -216.460324)
		(width 0.14478)
		(layer "In11.Cu")
		(net "M_L_CPU1_SA_DQ<16>")
	)
	(segment
		(start 185.250836 -215.61044)
		(end 186.10072 -216.460324)
		(width 0.14478)
		(layer "In11.Cu")
		(net "M_L_CPU1_SA_DQ<16>")
	)
	(segment
		(start 206.246222 -216.033604)
		(end 206.248 -216.035382)
		(width 0.14478)
		(layer "In11.Cu")
		(net "M_L_CPU1_SA_DQ<16>")
	)
	(segment
		(start 188.123576 -216.460324)
		(end 190.175134 -215.61044)
		(width 0.14478)
		(layer "In11.Cu")
		(net "M_L_CPU1_SA_DQ<16>")
	)
	(segment
		(start 174.448724 -215.61044)
		(end 177.972466 -215.61044)
		(width 0.14478)
		(layer "In11.Cu")
		(net "M_L_CPU1_SA_DQ<16>")
	)
	(segment
		(start 197.623684 -215.61044)
		(end 204.118718 -215.61044)
		(width 0.14478)
		(layer "In11.Cu")
		(net "M_L_CPU1_SA_DQ<16>")
	)
	(segment
		(start 145.89125 -234.728766)
		(end 146.38909 -234.230926)
		(width 0.0889)
		(layer "In11.Cu")
		(net "M_L_CPU1_SA_DQ<16>")
	)
	(segment
		(start 148.490432 -232.849166)
		(end 148.57095 -232.768648)
		(width 0.0889)
		(layer "In11.Cu")
		(net "M_L_CPU1_SA_DQ<16>")
	)
	(segment
		(start 193.5861 -216.460324)
		(end 195.571872 -216.460324)
		(width 0.14478)
		(layer "In11.Cu")
		(net "M_L_CPU1_SA_DQ<16>")
	)
	(segment
		(start 145.89125 -235.013754)
		(end 145.89125 -234.728766)
		(width 0.0889)
		(layer "In11.Cu")
		(net "M_L_CPU1_SA_DQ<16>")
	)
	(segment
		(start 190.175134 -215.61044)
		(end 192.736216 -215.61044)
		(width 0.14478)
		(layer "In11.Cu")
		(net "M_L_CPU1_SA_DQ<16>")
	)
	(arc
		(start 144.861026 -235.086906)
		(mid 145.131557 -235.0105)
		(end 145.405348 -235.074206)
		(width 0.0889)
		(layer "In11.Cu")
		(net "M_L_CPU1_SA_DQ<16>")
	)
	(arc
		(start 143.933418 -235.079794)
		(mid 144.210952 -235.010813)
		(end 144.48663 -235.086906)
		(width 0.0889)
		(layer "In11.Cu")
		(net "M_L_CPU1_SA_DQ<16>")
	)
	(arc
		(start 139.28471 -235.055156)
		(mid 139.539918 -235.011679)
		(end 139.78763 -235.086906)
		(width 0.0889)
		(layer "In11.Cu")
		(net "M_L_CPU1_SA_DQ<16>")
	)
	(arc
		(start 142.98168 -235.086906)
		(mid 143.264636 -235.010729)
		(end 143.547592 -235.086906)
		(width 0.0889)
		(layer "In11.Cu")
		(net "M_L_CPU1_SA_DQ<16>")
	)
	(arc
		(start 142.607792 -235.086906)
		(mid 142.794736 -235.137161)
		(end 142.98168 -235.086906)
		(width 0.0889)
		(layer "In11.Cu")
		(net "M_L_CPU1_SA_DQ<16>")
	)
	(arc
		(start 141.67612 -235.091732)
		(mid 141.859628 -235.137226)
		(end 142.04188 -235.086906)
		(width 0.0889)
		(layer "In11.Cu")
		(net "M_L_CPU1_SA_DQ<16>")
	)
	(arc
		(start 144.498314 -235.093764)
		(mid 144.680569 -235.137417)
		(end 144.861026 -235.086906)
		(width 0.0889)
		(layer "In11.Cu")
		(net "M_L_CPU1_SA_DQ<16>")
	)
	(arc
		(start 141.101826 -235.086906)
		(mid 141.384782 -235.010729)
		(end 141.667738 -235.086906)
		(width 0.0889)
		(layer "In11.Cu")
		(net "M_L_CPU1_SA_DQ<16>")
	)
	(arc
		(start 143.547592 -235.086906)
		(mid 143.725242 -235.137166)
		(end 143.905224 -235.09605)
		(width 0.0889)
		(layer "In11.Cu")
		(net "M_L_CPU1_SA_DQ<16>")
	)
	(arc
		(start 145.443194 -235.09605)
		(mid 145.671188 -235.132646)
		(end 145.877026 -235.027978)
		(width 0.0889)
		(layer "In11.Cu")
		(net "M_L_CPU1_SA_DQ<16>")
	)
	(arc
		(start 142.04188 -235.086906)
		(mid 142.324836 -235.010729)
		(end 142.607792 -235.086906)
		(width 0.0889)
		(layer "In11.Cu")
		(net "M_L_CPU1_SA_DQ<16>")
	)
	(arc
		(start 140.727684 -235.086906)
		(mid 140.909935 -235.137256)
		(end 141.093444 -235.091732)
		(width 0.0889)
		(layer "In11.Cu")
		(net "M_L_CPU1_SA_DQ<16>")
	)
	(arc
		(start 139.78763 -235.086906)
		(mid 139.969881 -235.137256)
		(end 140.15339 -235.091732)
		(width 0.0889)
		(layer "In11.Cu")
		(net "M_L_CPU1_SA_DQ<16>")
	)
	(arc
		(start 140.161772 -235.086906)
		(mid 140.444728 -235.010729)
		(end 140.727684 -235.086906)
		(width 0.0889)
		(layer "In11.Cu")
		(net "M_L_CPU1_SA_DQ<16>")
	)
	(segment
		(start 137.627868 -235.030264)
		(end 138.09472 -234.764326)
		(width 0.10668)
		(layer "F.Cu")
		(net "M_L_CPU1_SA_DQ<15>")
	)
	(segment
		(start 167.840406 -214.760302)
		(end 168.080182 -214.760302)
		(width 0.14478)
		(layer "In11.Cu")
		(net "M_L_CPU1_SA_DQ<15>")
	)
	(segment
		(start 161.37763 -218.1479)
		(end 161.540698 -217.984832)
		(width 0.14478)
		(layer "In11.Cu")
		(net "M_L_CPU1_SA_DQ<15>")
	)
	(segment
		(start 138.09472 -234.764326)
		(end 137.940796 -234.498896)
		(width 0.0889)
		(layer "In11.Cu")
		(net "M_L_CPU1_SA_DQ<15>")
	)
	(segment
		(start 196.892672 -214.760556)
		(end 197.174358 -214.760556)
		(width 0.14478)
		(layer "In11.Cu")
		(net "M_L_CPU1_SA_DQ<15>")
	)
	(segment
		(start 167.283892 -214.443564)
		(end 167.523668 -214.443564)
		(width 0.14478)
		(layer "In11.Cu")
		(net "M_L_CPU1_SA_DQ<15>")
	)
	(segment
		(start 160.42894 -218.217242)
		(end 160.42894 -217.98661)
		(width 0.14478)
		(layer "In11.Cu")
		(net "M_L_CPU1_SA_DQ<15>")
	)
	(segment
		(start 162.166808 -216.248742)
		(end 162.39744 -216.248742)
		(width 0.14478)
		(layer "In11.Cu")
		(net "M_L_CPU1_SA_DQ<15>")
	)
	(segment
		(start 162.617404 -216.468706)
		(end 162.928554 -216.468706)
		(width 0.14478)
		(layer "In11.Cu")
		(net "M_L_CPU1_SA_DQ<15>")
	)
	(segment
		(start 146.83105 -233.933746)
		(end 147.16379 -233.601006)
		(width 0.0889)
		(layer "In11.Cu")
		(net "M_L_CPU1_SA_DQ<15>")
	)
	(segment
		(start 160.753298 -218.5416)
		(end 160.42894 -218.217242)
		(width 0.14478)
		(layer "In11.Cu")
		(net "M_L_CPU1_SA_DQ<15>")
	)
	(segment
		(start 169.749724 -214.443564)
		(end 170.066462 -214.760302)
		(width 0.14478)
		(layer "In11.Cu")
		(net "M_L_CPU1_SA_DQ<15>")
	)
	(segment
		(start 181.756812 -214.760556)
		(end 182.179214 -214.760556)
		(width 0.14478)
		(layer "In11.Cu")
		(net "M_L_CPU1_SA_DQ<15>")
	)
	(segment
		(start 199.154288 -214.760556)
		(end 199.44588 -214.468964)
		(width 0.14478)
		(layer "In11.Cu")
		(net "M_L_CPU1_SA_DQ<15>")
	)
	(segment
		(start 145.615406 -234.390946)
		(end 145.92427 -234.390946)
		(width 0.0889)
		(layer "In11.Cu")
		(net "M_L_CPU1_SA_DQ<15>")
	)
	(segment
		(start 161.146998 -218.1479)
		(end 161.37763 -218.1479)
		(width 0.14478)
		(layer "In11.Cu")
		(net "M_L_CPU1_SA_DQ<15>")
	)
	(segment
		(start 141.667738 -234.441746)
		(end 141.67612 -234.43692)
		(width 0.0889)
		(layer "In11.Cu")
		(net "M_L_CPU1_SA_DQ<15>")
	)
	(segment
		(start 160.592008 -217.823542)
		(end 160.82264 -217.823542)
		(width 0.14478)
		(layer "In11.Cu")
		(net "M_L_CPU1_SA_DQ<15>")
	)
	(segment
		(start 162.328098 -217.197432)
		(end 162.328098 -216.9668)
		(width 0.14478)
		(layer "In11.Cu")
		(net "M_L_CPU1_SA_DQ<15>")
	)
	(segment
		(start 171.314872 -215.61044)
		(end 173.494192 -215.61044)
		(width 0.14478)
		(layer "In11.Cu")
		(net "M_L_CPU1_SA_DQ<15>")
	)
	(segment
		(start 166.441374 -214.760302)
		(end 166.967154 -214.760302)
		(width 0.14478)
		(layer "In11.Cu")
		(net "M_L_CPU1_SA_DQ<15>")
	)
	(segment
		(start 163.78682 -215.61044)
		(end 165.591236 -215.61044)
		(width 0.14478)
		(layer "In11.Cu")
		(net "M_L_CPU1_SA_DQ<15>")
	)
	(segment
		(start 169.19321 -214.760302)
		(end 169.509948 -214.443564)
		(width 0.14478)
		(layer "In11.Cu")
		(net "M_L_CPU1_SA_DQ<15>")
	)
	(segment
		(start 170.066462 -214.760302)
		(end 170.464734 -214.760302)
		(width 0.14478)
		(layer "In11.Cu")
		(net "M_L_CPU1_SA_DQ<15>")
	)
	(segment
		(start 162.00374 -216.41181)
		(end 162.166808 -216.248742)
		(width 0.14478)
		(layer "In11.Cu")
		(net "M_L_CPU1_SA_DQ<15>")
	)
	(segment
		(start 188.673232 -215.61044)
		(end 189.523116 -214.760556)
		(width 0.14478)
		(layer "In11.Cu")
		(net "M_L_CPU1_SA_DQ<15>")
	)
	(segment
		(start 201.115422 -214.760556)
		(end 201.723244 -214.760556)
		(width 0.14478)
		(layer "In11.Cu")
		(net "M_L_CPU1_SA_DQ<15>")
	)
	(segment
		(start 197.996302 -214.760556)
		(end 199.154288 -214.760556)
		(width 0.14478)
		(layer "In11.Cu")
		(net "M_L_CPU1_SA_DQ<15>")
	)
	(segment
		(start 165.591236 -215.61044)
		(end 166.441374 -214.760302)
		(width 0.14478)
		(layer "In11.Cu")
		(net "M_L_CPU1_SA_DQ<15>")
	)
	(segment
		(start 161.21634 -217.19921)
		(end 161.379408 -217.036142)
		(width 0.14478)
		(layer "In11.Cu")
		(net "M_L_CPU1_SA_DQ<15>")
	)
	(segment
		(start 161.540698 -217.7542)
		(end 161.21634 -217.429842)
		(width 0.14478)
		(layer "In11.Cu")
		(net "M_L_CPU1_SA_DQ<15>")
	)
	(segment
		(start 166.967154 -214.760302)
		(end 167.283892 -214.443564)
		(width 0.14478)
		(layer "In11.Cu")
		(net "M_L_CPU1_SA_DQ<15>")
	)
	(segment
		(start 168.39692 -214.443564)
		(end 168.636696 -214.443564)
		(width 0.14478)
		(layer "In11.Cu")
		(net "M_L_CPU1_SA_DQ<15>")
	)
	(segment
		(start 199.44588 -214.468964)
		(end 199.710802 -214.468964)
		(width 0.14478)
		(layer "In11.Cu")
		(net "M_L_CPU1_SA_DQ<15>")
	)
	(segment
		(start 169.509948 -214.443564)
		(end 169.749724 -214.443564)
		(width 0.14478)
		(layer "In11.Cu")
		(net "M_L_CPU1_SA_DQ<15>")
	)
	(segment
		(start 185.250836 -214.760556)
		(end 186.10072 -215.61044)
		(width 0.14478)
		(layer "In11.Cu")
		(net "M_L_CPU1_SA_DQ<15>")
	)
	(segment
		(start 186.10072 -215.61044)
		(end 188.673232 -215.61044)
		(width 0.14478)
		(layer "In11.Cu")
		(net "M_L_CPU1_SA_DQ<15>")
	)
	(segment
		(start 200.267316 -214.760556)
		(end 200.558908 -214.468964)
		(width 0.14478)
		(layer "In11.Cu")
		(net "M_L_CPU1_SA_DQ<15>")
	)
	(segment
		(start 196.042788 -215.61044)
		(end 196.892672 -214.760556)
		(width 0.14478)
		(layer "In11.Cu")
		(net "M_L_CPU1_SA_DQ<15>")
	)
	(segment
		(start 197.725792 -214.490046)
		(end 197.996302 -214.760556)
		(width 0.14478)
		(layer "In11.Cu")
		(net "M_L_CPU1_SA_DQ<15>")
	)
	(segment
		(start 200.002394 -214.760556)
		(end 200.267316 -214.760556)
		(width 0.14478)
		(layer "In11.Cu")
		(net "M_L_CPU1_SA_DQ<15>")
	)
	(segment
		(start 200.82383 -214.468964)
		(end 201.115422 -214.760556)
		(width 0.14478)
		(layer "In11.Cu")
		(net "M_L_CPU1_SA_DQ<15>")
	)
	(segment
		(start 174.344076 -214.760556)
		(end 177.972466 -214.760556)
		(width 0.14478)
		(layer "In11.Cu")
		(net "M_L_CPU1_SA_DQ<15>")
	)
	(segment
		(start 146.38147 -233.933746)
		(end 146.83105 -233.933746)
		(width 0.0889)
		(layer "In11.Cu")
		(net "M_L_CPU1_SA_DQ<15>")
	)
	(segment
		(start 168.636696 -214.443564)
		(end 168.953434 -214.760302)
		(width 0.14478)
		(layer "In11.Cu")
		(net "M_L_CPU1_SA_DQ<15>")
	)
	(segment
		(start 197.174358 -214.760556)
		(end 197.444868 -214.490046)
		(width 0.14478)
		(layer "In11.Cu")
		(net "M_L_CPU1_SA_DQ<15>")
	)
	(segment
		(start 177.972466 -214.760556)
		(end 178.82235 -215.61044)
		(width 0.14478)
		(layer "In11.Cu")
		(net "M_L_CPU1_SA_DQ<15>")
	)
	(segment
		(start 148.380704 -232.172002)
		(end 155.194 -225.358706)
		(width 0.14478)
		(layer "In11.Cu")
		(net "M_L_CPU1_SA_DQ<15>")
	)
	(segment
		(start 161.934398 -217.3605)
		(end 162.16503 -217.3605)
		(width 0.14478)
		(layer "In11.Cu")
		(net "M_L_CPU1_SA_DQ<15>")
	)
	(segment
		(start 182.179214 -214.760556)
		(end 182.449724 -214.490046)
		(width 0.14478)
		(layer "In11.Cu")
		(net "M_L_CPU1_SA_DQ<15>")
	)
	(segment
		(start 193.54546 -215.61044)
		(end 196.042788 -215.61044)
		(width 0.14478)
		(layer "In11.Cu")
		(net "M_L_CPU1_SA_DQ<15>")
	)
	(segment
		(start 180.906928 -215.61044)
		(end 181.756812 -214.760556)
		(width 0.14478)
		(layer "In11.Cu")
		(net "M_L_CPU1_SA_DQ<15>")
	)
	(segment
		(start 192.695576 -214.760556)
		(end 193.54546 -215.61044)
		(width 0.14478)
		(layer "In11.Cu")
		(net "M_L_CPU1_SA_DQ<15>")
	)
	(segment
		(start 161.540698 -217.984832)
		(end 161.540698 -217.7542)
		(width 0.14478)
		(layer "In11.Cu")
		(net "M_L_CPU1_SA_DQ<15>")
	)
	(segment
		(start 147.88769 -232.341166)
		(end 148.21154 -232.341166)
		(width 0.0889)
		(layer "In11.Cu")
		(net "M_L_CPU1_SA_DQ<15>")
	)
	(segment
		(start 173.494192 -215.61044)
		(end 174.344076 -214.760556)
		(width 0.14478)
		(layer "In11.Cu")
		(net "M_L_CPU1_SA_DQ<15>")
	)
	(segment
		(start 201.723244 -214.760556)
		(end 202.147932 -215.185244)
		(width 0.14478)
		(layer "In11.Cu")
		(net "M_L_CPU1_SA_DQ<15>")
	)
	(segment
		(start 182.730648 -214.490046)
		(end 183.001158 -214.760556)
		(width 0.14478)
		(layer "In11.Cu")
		(net "M_L_CPU1_SA_DQ<15>")
	)
	(segment
		(start 155.194 -224.33153)
		(end 160.753298 -218.772232)
		(width 0.14478)
		(layer "In11.Cu")
		(net "M_L_CPU1_SA_DQ<15>")
	)
	(segment
		(start 199.710802 -214.468964)
		(end 200.002394 -214.760556)
		(width 0.14478)
		(layer "In11.Cu")
		(net "M_L_CPU1_SA_DQ<15>")
	)
	(segment
		(start 200.558908 -214.468964)
		(end 200.82383 -214.468964)
		(width 0.14478)
		(layer "In11.Cu")
		(net "M_L_CPU1_SA_DQ<15>")
	)
	(segment
		(start 197.444868 -214.490046)
		(end 197.725792 -214.490046)
		(width 0.14478)
		(layer "In11.Cu")
		(net "M_L_CPU1_SA_DQ<15>")
	)
	(segment
		(start 168.953434 -214.760302)
		(end 169.19321 -214.760302)
		(width 0.14478)
		(layer "In11.Cu")
		(net "M_L_CPU1_SA_DQ<15>")
	)
	(segment
		(start 161.379408 -217.036142)
		(end 161.61004 -217.036142)
		(width 0.14478)
		(layer "In11.Cu")
		(net "M_L_CPU1_SA_DQ<15>")
	)
	(segment
		(start 141.093444 -234.43692)
		(end 141.101826 -234.441746)
		(width 0.0889)
		(layer "In11.Cu")
		(net "M_L_CPU1_SA_DQ<15>")
	)
	(segment
		(start 168.080182 -214.760302)
		(end 168.39692 -214.443564)
		(width 0.14478)
		(layer "In11.Cu")
		(net "M_L_CPU1_SA_DQ<15>")
	)
	(segment
		(start 170.464734 -214.760302)
		(end 171.314872 -215.61044)
		(width 0.14478)
		(layer "In11.Cu")
		(net "M_L_CPU1_SA_DQ<15>")
	)
	(segment
		(start 178.82235 -215.61044)
		(end 180.906928 -215.61044)
		(width 0.14478)
		(layer "In11.Cu")
		(net "M_L_CPU1_SA_DQ<15>")
	)
	(segment
		(start 161.61004 -217.036142)
		(end 161.934398 -217.3605)
		(width 0.14478)
		(layer "In11.Cu")
		(net "M_L_CPU1_SA_DQ<15>")
	)
	(segment
		(start 189.523116 -214.760556)
		(end 192.695576 -214.760556)
		(width 0.14478)
		(layer "In11.Cu")
		(net "M_L_CPU1_SA_DQ<15>")
	)
	(segment
		(start 162.328098 -216.9668)
		(end 162.00374 -216.642442)
		(width 0.14478)
		(layer "In11.Cu")
		(net "M_L_CPU1_SA_DQ<15>")
	)
	(segment
		(start 160.82264 -217.823542)
		(end 161.146998 -218.1479)
		(width 0.14478)
		(layer "In11.Cu")
		(net "M_L_CPU1_SA_DQ<15>")
	)
	(segment
		(start 162.16503 -217.3605)
		(end 162.328098 -217.197432)
		(width 0.14478)
		(layer "In11.Cu")
		(net "M_L_CPU1_SA_DQ<15>")
	)
	(segment
		(start 140.15339 -234.43692)
		(end 140.161772 -234.441746)
		(width 0.0889)
		(layer "In11.Cu")
		(net "M_L_CPU1_SA_DQ<15>")
	)
	(segment
		(start 144.47774 -234.447842)
		(end 144.488154 -234.441746)
		(width 0.0889)
		(layer "In11.Cu")
		(net "M_L_CPU1_SA_DQ<15>")
	)
	(segment
		(start 183.001158 -214.760556)
		(end 185.250836 -214.760556)
		(width 0.14478)
		(layer "In11.Cu")
		(net "M_L_CPU1_SA_DQ<15>")
	)
	(segment
		(start 160.42894 -217.98661)
		(end 160.592008 -217.823542)
		(width 0.14478)
		(layer "In11.Cu")
		(net "M_L_CPU1_SA_DQ<15>")
	)
	(segment
		(start 161.21634 -217.429842)
		(end 161.21634 -217.19921)
		(width 0.14478)
		(layer "In11.Cu")
		(net "M_L_CPU1_SA_DQ<15>")
	)
	(segment
		(start 162.928554 -216.468706)
		(end 163.78682 -215.61044)
		(width 0.14478)
		(layer "In11.Cu")
		(net "M_L_CPU1_SA_DQ<15>")
	)
	(segment
		(start 182.449724 -214.490046)
		(end 182.730648 -214.490046)
		(width 0.14478)
		(layer "In11.Cu")
		(net "M_L_CPU1_SA_DQ<15>")
	)
	(segment
		(start 144.862042 -234.441746)
		(end 144.876774 -234.450382)
		(width 0.0889)
		(layer "In11.Cu")
		(net "M_L_CPU1_SA_DQ<15>")
	)
	(segment
		(start 167.523668 -214.443564)
		(end 167.840406 -214.760302)
		(width 0.14478)
		(layer "In11.Cu")
		(net "M_L_CPU1_SA_DQ<15>")
	)
	(segment
		(start 147.16379 -233.065066)
		(end 147.88769 -232.341166)
		(width 0.0889)
		(layer "In11.Cu")
		(net "M_L_CPU1_SA_DQ<15>")
	)
	(segment
		(start 148.21154 -232.341166)
		(end 148.380704 -232.172002)
		(width 0.0889)
		(layer "In11.Cu")
		(net "M_L_CPU1_SA_DQ<15>")
	)
	(segment
		(start 160.753298 -218.772232)
		(end 160.753298 -218.5416)
		(width 0.14478)
		(layer "In11.Cu")
		(net "M_L_CPU1_SA_DQ<15>")
	)
	(segment
		(start 162.00374 -216.642442)
		(end 162.00374 -216.41181)
		(width 0.14478)
		(layer "In11.Cu")
		(net "M_L_CPU1_SA_DQ<15>")
	)
	(segment
		(start 147.16379 -233.601006)
		(end 147.16379 -233.065066)
		(width 0.0889)
		(layer "In11.Cu")
		(net "M_L_CPU1_SA_DQ<15>")
	)
	(segment
		(start 162.39744 -216.248742)
		(end 162.617404 -216.468706)
		(width 0.14478)
		(layer "In11.Cu")
		(net "M_L_CPU1_SA_DQ<15>")
	)
	(segment
		(start 145.92427 -234.390946)
		(end 146.38147 -233.933746)
		(width 0.0889)
		(layer "In11.Cu")
		(net "M_L_CPU1_SA_DQ<15>")
	)
	(segment
		(start 137.940796 -234.498896)
		(end 137.963148 -234.415584)
		(width 0.0889)
		(layer "In11.Cu")
		(net "M_L_CPU1_SA_DQ<15>")
	)
	(segment
		(start 155.194 -225.358706)
		(end 155.194 -224.33153)
		(width 0.14478)
		(layer "In11.Cu")
		(net "M_L_CPU1_SA_DQ<15>")
	)
	(arc
		(start 138.281918 -234.441746)
		(mid 138.564874 -234.517923)
		(end 138.84783 -234.441746)
		(width 0.0889)
		(layer "In11.Cu")
		(net "M_L_CPU1_SA_DQ<15>")
	)
	(arc
		(start 143.547592 -234.441746)
		(mid 143.73479 -234.391364)
		(end 143.921988 -234.441746)
		(width 0.0889)
		(layer "In11.Cu")
		(net "M_L_CPU1_SA_DQ<15>")
	)
	(arc
		(start 139.221718 -234.441746)
		(mid 139.504674 -234.517923)
		(end 139.78763 -234.441746)
		(width 0.0889)
		(layer "In11.Cu")
		(net "M_L_CPU1_SA_DQ<15>")
	)
	(arc
		(start 140.727684 -234.441746)
		(mid 140.909935 -234.391396)
		(end 141.093444 -234.43692)
		(width 0.0889)
		(layer "In11.Cu")
		(net "M_L_CPU1_SA_DQ<15>")
	)
	(arc
		(start 139.78763 -234.441746)
		(mid 139.969881 -234.391396)
		(end 140.15339 -234.43692)
		(width 0.0889)
		(layer "In11.Cu")
		(net "M_L_CPU1_SA_DQ<15>")
	)
	(arc
		(start 141.67612 -234.43692)
		(mid 141.859628 -234.391426)
		(end 142.04188 -234.441746)
		(width 0.0889)
		(layer "In11.Cu")
		(net "M_L_CPU1_SA_DQ<15>")
	)
	(arc
		(start 144.488154 -234.441746)
		(mid 144.675098 -234.391491)
		(end 144.862042 -234.441746)
		(width 0.0889)
		(layer "In11.Cu")
		(net "M_L_CPU1_SA_DQ<15>")
	)
	(arc
		(start 145.427954 -234.441746)
		(mid 145.518317 -234.403936)
		(end 145.615406 -234.390946)
		(width 0.0889)
		(layer "In11.Cu")
		(net "M_L_CPU1_SA_DQ<15>")
	)
	(arc
		(start 142.607792 -234.441746)
		(mid 142.794736 -234.391491)
		(end 142.98168 -234.441746)
		(width 0.0889)
		(layer "In11.Cu")
		(net "M_L_CPU1_SA_DQ<15>")
	)
	(arc
		(start 143.921988 -234.441746)
		(mid 144.199055 -234.518017)
		(end 144.47774 -234.447842)
		(width 0.0889)
		(layer "In11.Cu")
		(net "M_L_CPU1_SA_DQ<15>")
	)
	(arc
		(start 140.161772 -234.441746)
		(mid 140.444728 -234.517923)
		(end 140.727684 -234.441746)
		(width 0.0889)
		(layer "In11.Cu")
		(net "M_L_CPU1_SA_DQ<15>")
	)
	(arc
		(start 141.101826 -234.441746)
		(mid 141.384782 -234.517923)
		(end 141.667738 -234.441746)
		(width 0.0889)
		(layer "In11.Cu")
		(net "M_L_CPU1_SA_DQ<15>")
	)
	(arc
		(start 142.04188 -234.441746)
		(mid 142.324836 -234.517923)
		(end 142.607792 -234.441746)
		(width 0.0889)
		(layer "In11.Cu")
		(net "M_L_CPU1_SA_DQ<15>")
	)
	(arc
		(start 144.876774 -234.450382)
		(mid 145.153503 -234.518065)
		(end 145.427954 -234.441746)
		(width 0.0889)
		(layer "In11.Cu")
		(net "M_L_CPU1_SA_DQ<15>")
	)
	(arc
		(start 142.98168 -234.441746)
		(mid 143.264636 -234.517923)
		(end 143.547592 -234.441746)
		(width 0.0889)
		(layer "In11.Cu")
		(net "M_L_CPU1_SA_DQ<15>")
	)
	(arc
		(start 138.84783 -234.441746)
		(mid 139.034774 -234.391491)
		(end 139.221718 -234.441746)
		(width 0.0889)
		(layer "In11.Cu")
		(net "M_L_CPU1_SA_DQ<15>")
	)
	(arc
		(start 137.963148 -234.415584)
		(mid 138.12548 -234.392766)
		(end 138.281918 -234.441746)
		(width 0.0889)
		(layer "In11.Cu")
		(net "M_L_CPU1_SA_DQ<15>")
	)
	(segment
		(start 139.037822 -234.220258)
		(end 139.504674 -233.95432)
		(width 0.10668)
		(layer "F.Cu")
		(net "M_L_CPU1_SA_DQ<14>")
	)
	(segment
		(start 190.44793 -212.823806)
		(end 190.44793 -212.915754)
		(width 0.14478)
		(layer "In11.Cu")
		(net "M_L_CPU1_SA_DQ<14>")
	)
	(segment
		(start 201.119232 -212.915754)
		(end 201.264012 -213.060534)
		(width 0.14478)
		(layer "In11.Cu")
		(net "M_L_CPU1_SA_DQ<14>")
	)
	(segment
		(start 200.161144 -213.414102)
		(end 200.423018 -213.414102)
		(width 0.14478)
		(layer "In11.Cu")
		(net "M_L_CPU1_SA_DQ<14>")
	)
	(segment
		(start 169.026078 -212.841586)
		(end 169.026078 -212.935566)
		(width 0.14478)
		(layer "In11.Cu")
		(net "M_L_CPU1_SA_DQ<14>")
	)
	(segment
		(start 167.77843 -212.696806)
		(end 167.92321 -212.841586)
		(width 0.14478)
		(layer "In11.Cu")
		(net "M_L_CPU1_SA_DQ<14>")
	)
	(segment
		(start 168.474644 -212.935566)
		(end 168.474644 -212.841586)
		(width 0.14478)
		(layer "In11.Cu")
		(net "M_L_CPU1_SA_DQ<14>")
	)
	(segment
		(start 163.185094 -213.910418)
		(end 163.522152 -213.910418)
		(width 0.14478)
		(layer "In11.Cu")
		(net "M_L_CPU1_SA_DQ<14>")
	)
	(segment
		(start 169.432732 -213.080346)
		(end 169.577512 -212.935566)
		(width 0.14478)
		(layer "In11.Cu")
		(net "M_L_CPU1_SA_DQ<14>")
	)
	(segment
		(start 163.522152 -213.910418)
		(end 163.666932 -213.765638)
		(width 0.14478)
		(layer "In11.Cu")
		(net "M_L_CPU1_SA_DQ<14>")
	)
	(segment
		(start 188.138816 -213.532466)
		(end 188.283596 -213.677246)
		(width 0.14478)
		(layer "In11.Cu")
		(net "M_L_CPU1_SA_DQ<14>")
	)
	(segment
		(start 197.909942 -213.296246)
		(end 197.909942 -213.205314)
		(width 0.14478)
		(layer "In11.Cu")
		(net "M_L_CPU1_SA_DQ<14>")
	)
	(segment
		(start 191.682624 -212.915754)
		(end 191.682624 -212.818726)
		(width 0.14478)
		(layer "In11.Cu")
		(net "M_L_CPU1_SA_DQ<14>")
	)
	(segment
		(start 192.089278 -212.673946)
		(end 192.234058 -212.818726)
		(width 0.14478)
		(layer "In11.Cu")
		(net "M_L_CPU1_SA_DQ<14>")
	)
	(segment
		(start 186.10072 -213.910418)
		(end 187.587382 -213.910418)
		(width 0.14478)
		(layer "In11.Cu")
		(net "M_L_CPU1_SA_DQ<14>")
	)
	(segment
		(start 169.577512 -212.935566)
		(end 169.577512 -212.841586)
		(width 0.14478)
		(layer "In11.Cu")
		(net "M_L_CPU1_SA_DQ<14>")
	)
	(segment
		(start 199.46493 -212.851746)
		(end 199.60971 -212.706966)
		(width 0.14478)
		(layer "In11.Cu")
		(net "M_L_CPU1_SA_DQ<14>")
	)
	(segment
		(start 199.32015 -213.060534)
		(end 199.46493 -212.915754)
		(width 0.14478)
		(layer "In11.Cu")
		(net "M_L_CPU1_SA_DQ<14>")
	)
	(segment
		(start 188.673232 -213.910418)
		(end 189.523116 -213.060534)
		(width 0.14478)
		(layer "In11.Cu")
		(net "M_L_CPU1_SA_DQ<14>")
	)
	(segment
		(start 170.097704 -212.696806)
		(end 171.311316 -213.910418)
		(width 0.14478)
		(layer "In11.Cu")
		(net "M_L_CPU1_SA_DQ<14>")
	)
	(segment
		(start 187.732162 -213.677246)
		(end 187.876942 -213.532466)
		(width 0.14478)
		(layer "In11.Cu")
		(net "M_L_CPU1_SA_DQ<14>")
	)
	(segment
		(start 164.7698 -213.765638)
		(end 164.7698 -213.593426)
		(width 0.14478)
		(layer "In11.Cu")
		(net "M_L_CPU1_SA_DQ<14>")
	)
	(segment
		(start 171.311316 -213.910418)
		(end 172.95368 -213.910418)
		(width 0.14478)
		(layer "In11.Cu")
		(net "M_L_CPU1_SA_DQ<14>")
	)
	(segment
		(start 199.46493 -212.915754)
		(end 199.46493 -212.851746)
		(width 0.14478)
		(layer "In11.Cu")
		(net "M_L_CPU1_SA_DQ<14>")
	)
	(segment
		(start 167.92321 -212.841586)
		(end 167.92321 -212.935566)
		(width 0.14478)
		(layer "In11.Cu")
		(net "M_L_CPU1_SA_DQ<14>")
	)
	(segment
		(start 164.363146 -213.910418)
		(end 164.62502 -213.910418)
		(width 0.14478)
		(layer "In11.Cu")
		(net "M_L_CPU1_SA_DQ<14>")
	)
	(segment
		(start 143.077692 -233.63174)
		(end 143.086074 -233.626914)
		(width 0.0889)
		(layer "In11.Cu")
		(net "M_L_CPU1_SA_DQ<14>")
	)
	(segment
		(start 163.666932 -213.765638)
		(end 163.666932 -213.593426)
		(width 0.14478)
		(layer "In11.Cu")
		(net "M_L_CPU1_SA_DQ<14>")
	)
	(segment
		(start 142.503398 -233.626914)
		(end 142.51178 -233.63174)
		(width 0.0889)
		(layer "In11.Cu")
		(net "M_L_CPU1_SA_DQ<14>")
	)
	(segment
		(start 144.016984 -233.631994)
		(end 144.0307 -233.62412)
		(width 0.0889)
		(layer "In11.Cu")
		(net "M_L_CPU1_SA_DQ<14>")
	)
	(segment
		(start 181.915308 -213.060534)
		(end 185.250836 -213.060534)
		(width 0.14478)
		(layer "In11.Cu")
		(net "M_L_CPU1_SA_DQ<14>")
	)
	(segment
		(start 189.896496 -212.823806)
		(end 190.041276 -212.679026)
		(width 0.14478)
		(layer "In11.Cu")
		(net "M_L_CPU1_SA_DQ<14>")
	)
	(segment
		(start 139.35075 -233.68889)
		(end 139.373102 -233.605578)
		(width 0.0889)
		(layer "In11.Cu")
		(net "M_L_CPU1_SA_DQ<14>")
	)
	(segment
		(start 196.262752 -213.910418)
		(end 197.112636 -213.060534)
		(width 0.14478)
		(layer "In11.Cu")
		(net "M_L_CPU1_SA_DQ<14>")
	)
	(segment
		(start 197.213728 -213.060534)
		(end 197.358508 -213.205314)
		(width 0.14478)
		(layer "In11.Cu")
		(net "M_L_CPU1_SA_DQ<14>")
	)
	(segment
		(start 164.218366 -213.765638)
		(end 164.363146 -213.910418)
		(width 0.14478)
		(layer "In11.Cu")
		(net "M_L_CPU1_SA_DQ<14>")
	)
	(segment
		(start 139.504674 -233.95432)
		(end 139.35075 -233.68889)
		(width 0.0889)
		(layer "In11.Cu")
		(net "M_L_CPU1_SA_DQ<14>")
	)
	(segment
		(start 201.264012 -213.060534)
		(end 201.723244 -213.060534)
		(width 0.14478)
		(layer "In11.Cu")
		(net "M_L_CPU1_SA_DQ<14>")
	)
	(segment
		(start 195.677536 -213.765638)
		(end 195.822316 -213.910418)
		(width 0.14478)
		(layer "In11.Cu")
		(net "M_L_CPU1_SA_DQ<14>")
	)
	(segment
		(start 188.283596 -213.765638)
		(end 188.428376 -213.910418)
		(width 0.14478)
		(layer "In11.Cu")
		(net "M_L_CPU1_SA_DQ<14>")
	)
	(segment
		(start 175.005492 -213.060534)
		(end 177.972466 -213.060534)
		(width 0.14478)
		(layer "In11.Cu")
		(net "M_L_CPU1_SA_DQ<14>")
	)
	(segment
		(start 192.59804 -213.060534)
		(end 193.447924 -213.910418)
		(width 0.14478)
		(layer "In11.Cu")
		(net "M_L_CPU1_SA_DQ<14>")
	)
	(segment
		(start 185.250836 -213.060534)
		(end 186.10072 -213.910418)
		(width 0.14478)
		(layer "In11.Cu")
		(net "M_L_CPU1_SA_DQ<14>")
	)
	(segment
		(start 194.981322 -213.910418)
		(end 195.126102 -213.765638)
		(width 0.14478)
		(layer "In11.Cu")
		(net "M_L_CPU1_SA_DQ<14>")
	)
	(segment
		(start 165.321234 -213.765638)
		(end 165.466014 -213.910418)
		(width 0.14478)
		(layer "In11.Cu")
		(net "M_L_CPU1_SA_DQ<14>")
	)
	(segment
		(start 189.896496 -212.915754)
		(end 189.896496 -212.823806)
		(width 0.14478)
		(layer "In11.Cu")
		(net "M_L_CPU1_SA_DQ<14>")
	)
	(segment
		(start 165.321234 -213.593426)
		(end 165.321234 -213.765638)
		(width 0.14478)
		(layer "In11.Cu")
		(net "M_L_CPU1_SA_DQ<14>")
	)
	(segment
		(start 190.30315 -212.679026)
		(end 190.44793 -212.823806)
		(width 0.14478)
		(layer "In11.Cu")
		(net "M_L_CPU1_SA_DQ<14>")
	)
	(segment
		(start 197.358508 -213.205314)
		(end 197.358508 -213.296246)
		(width 0.14478)
		(layer "In11.Cu")
		(net "M_L_CPU1_SA_DQ<14>")
	)
	(segment
		(start 193.447924 -213.910418)
		(end 194.981322 -213.910418)
		(width 0.14478)
		(layer "In11.Cu")
		(net "M_L_CPU1_SA_DQ<14>")
	)
	(segment
		(start 169.577512 -212.841586)
		(end 169.722292 -212.696806)
		(width 0.14478)
		(layer "In11.Cu")
		(net "M_L_CPU1_SA_DQ<14>")
	)
	(segment
		(start 159.425386 -217.670126)
		(end 163.185094 -213.910418)
		(width 0.14478)
		(layer "In11.Cu")
		(net "M_L_CPU1_SA_DQ<14>")
	)
	(segment
		(start 187.732162 -213.765638)
		(end 187.732162 -213.677246)
		(width 0.14478)
		(layer "In11.Cu")
		(net "M_L_CPU1_SA_DQ<14>")
	)
	(segment
		(start 147.885404 -231.381046)
		(end 154.28468 -224.98177)
		(width 0.14478)
		(layer "In11.Cu")
		(net "M_L_CPU1_SA_DQ<14>")
	)
	(segment
		(start 195.532756 -213.522306)
		(end 195.677536 -213.667086)
		(width 0.14478)
		(layer "In11.Cu")
		(net "M_L_CPU1_SA_DQ<14>")
	)
	(segment
		(start 168.474644 -212.841586)
		(end 168.619424 -212.696806)
		(width 0.14478)
		(layer "In11.Cu")
		(net "M_L_CPU1_SA_DQ<14>")
	)
	(segment
		(start 200.423018 -213.414102)
		(end 200.567798 -213.269322)
		(width 0.14478)
		(layer "In11.Cu")
		(net "M_L_CPU1_SA_DQ<14>")
	)
	(segment
		(start 164.91458 -213.448646)
		(end 165.176454 -213.448646)
		(width 0.14478)
		(layer "In11.Cu")
		(net "M_L_CPU1_SA_DQ<14>")
	)
	(segment
		(start 169.026078 -212.935566)
		(end 169.170858 -213.080346)
		(width 0.14478)
		(layer "In11.Cu")
		(net "M_L_CPU1_SA_DQ<14>")
	)
	(segment
		(start 146.53641 -232.73004)
		(end 146.629882 -232.73004)
		(width 0.0889)
		(layer "In11.Cu")
		(net "M_L_CPU1_SA_DQ<14>")
	)
	(segment
		(start 140.257784 -233.63174)
		(end 140.266166 -233.626914)
		(width 0.0889)
		(layer "In11.Cu")
		(net "M_L_CPU1_SA_DQ<14>")
	)
	(segment
		(start 147.47875 -231.881172)
		(end 147.47875 -231.7877)
		(width 0.0889)
		(layer "In11.Cu")
		(net "M_L_CPU1_SA_DQ<14>")
	)
	(segment
		(start 200.974452 -212.706966)
		(end 201.119232 -212.851746)
		(width 0.14478)
		(layer "In11.Cu")
		(net "M_L_CPU1_SA_DQ<14>")
	)
	(segment
		(start 197.765162 -213.441026)
		(end 197.909942 -213.296246)
		(width 0.14478)
		(layer "In11.Cu")
		(net "M_L_CPU1_SA_DQ<14>")
	)
	(segment
		(start 169.170858 -213.080346)
		(end 169.432732 -213.080346)
		(width 0.14478)
		(layer "In11.Cu")
		(net "M_L_CPU1_SA_DQ<14>")
	)
	(segment
		(start 168.329864 -213.080346)
		(end 168.474644 -212.935566)
		(width 0.14478)
		(layer "In11.Cu")
		(net "M_L_CPU1_SA_DQ<14>")
	)
	(segment
		(start 200.712578 -212.706966)
		(end 200.974452 -212.706966)
		(width 0.14478)
		(layer "In11.Cu")
		(net "M_L_CPU1_SA_DQ<14>")
	)
	(segment
		(start 181.065424 -213.910418)
		(end 181.915308 -213.060534)
		(width 0.14478)
		(layer "In11.Cu")
		(net "M_L_CPU1_SA_DQ<14>")
	)
	(segment
		(start 188.428376 -213.910418)
		(end 188.673232 -213.910418)
		(width 0.14478)
		(layer "In11.Cu")
		(net "M_L_CPU1_SA_DQ<14>")
	)
	(segment
		(start 154.28468 -223.887284)
		(end 159.425386 -218.746578)
		(width 0.14478)
		(layer "In11.Cu")
		(net "M_L_CPU1_SA_DQ<14>")
	)
	(segment
		(start 188.283596 -213.677246)
		(end 188.283596 -213.765638)
		(width 0.14478)
		(layer "In11.Cu")
		(net "M_L_CPU1_SA_DQ<14>")
	)
	(segment
		(start 200.567798 -213.269322)
		(end 200.567798 -212.851746)
		(width 0.14478)
		(layer "In11.Cu")
		(net "M_L_CPU1_SA_DQ<14>")
	)
	(segment
		(start 189.751716 -213.060534)
		(end 189.896496 -212.915754)
		(width 0.14478)
		(layer "In11.Cu")
		(net "M_L_CPU1_SA_DQ<14>")
	)
	(segment
		(start 146.629882 -232.73004)
		(end 147.47875 -231.881172)
		(width 0.0889)
		(layer "In11.Cu")
		(net "M_L_CPU1_SA_DQ<14>")
	)
	(segment
		(start 147.47875 -231.7877)
		(end 147.885404 -231.381046)
		(width 0.0889)
		(layer "In11.Cu")
		(net "M_L_CPU1_SA_DQ<14>")
	)
	(segment
		(start 164.7698 -213.593426)
		(end 164.91458 -213.448646)
		(width 0.14478)
		(layer "In11.Cu")
		(net "M_L_CPU1_SA_DQ<14>")
	)
	(segment
		(start 192.234058 -212.818726)
		(end 192.234058 -212.915754)
		(width 0.14478)
		(layer "In11.Cu")
		(net "M_L_CPU1_SA_DQ<14>")
	)
	(segment
		(start 199.871584 -212.706966)
		(end 200.016364 -212.851746)
		(width 0.14478)
		(layer "In11.Cu")
		(net "M_L_CPU1_SA_DQ<14>")
	)
	(segment
		(start 190.041276 -212.679026)
		(end 190.30315 -212.679026)
		(width 0.14478)
		(layer "In11.Cu")
		(net "M_L_CPU1_SA_DQ<14>")
	)
	(segment
		(start 195.270882 -213.522306)
		(end 195.532756 -213.522306)
		(width 0.14478)
		(layer "In11.Cu")
		(net "M_L_CPU1_SA_DQ<14>")
	)
	(segment
		(start 168.06799 -213.080346)
		(end 168.329864 -213.080346)
		(width 0.14478)
		(layer "In11.Cu")
		(net "M_L_CPU1_SA_DQ<14>")
	)
	(segment
		(start 197.503288 -213.441026)
		(end 197.765162 -213.441026)
		(width 0.14478)
		(layer "In11.Cu")
		(net "M_L_CPU1_SA_DQ<14>")
	)
	(segment
		(start 190.44793 -212.915754)
		(end 190.59271 -213.060534)
		(width 0.14478)
		(layer "In11.Cu")
		(net "M_L_CPU1_SA_DQ<14>")
	)
	(segment
		(start 191.682624 -212.818726)
		(end 191.827404 -212.673946)
		(width 0.14478)
		(layer "In11.Cu")
		(net "M_L_CPU1_SA_DQ<14>")
	)
	(segment
		(start 201.119232 -212.851746)
		(end 201.119232 -212.915754)
		(width 0.14478)
		(layer "In11.Cu")
		(net "M_L_CPU1_SA_DQ<14>")
	)
	(segment
		(start 164.62502 -213.910418)
		(end 164.7698 -213.765638)
		(width 0.14478)
		(layer "In11.Cu")
		(net "M_L_CPU1_SA_DQ<14>")
	)
	(segment
		(start 195.822316 -213.910418)
		(end 196.262752 -213.910418)
		(width 0.14478)
		(layer "In11.Cu")
		(net "M_L_CPU1_SA_DQ<14>")
	)
	(segment
		(start 190.59271 -213.060534)
		(end 191.537844 -213.060534)
		(width 0.14478)
		(layer "In11.Cu")
		(net "M_L_CPU1_SA_DQ<14>")
	)
	(segment
		(start 198.054722 -213.060534)
		(end 199.32015 -213.060534)
		(width 0.14478)
		(layer "In11.Cu")
		(net "M_L_CPU1_SA_DQ<14>")
	)
	(segment
		(start 165.466014 -213.910418)
		(end 165.954964 -213.910418)
		(width 0.14478)
		(layer "In11.Cu")
		(net "M_L_CPU1_SA_DQ<14>")
	)
	(segment
		(start 187.876942 -213.532466)
		(end 188.138816 -213.532466)
		(width 0.14478)
		(layer "In11.Cu")
		(net "M_L_CPU1_SA_DQ<14>")
	)
	(segment
		(start 189.523116 -213.060534)
		(end 189.751716 -213.060534)
		(width 0.14478)
		(layer "In11.Cu")
		(net "M_L_CPU1_SA_DQ<14>")
	)
	(segment
		(start 144.390618 -233.63174)
		(end 144.408652 -233.642408)
		(width 0.0889)
		(layer "In11.Cu")
		(net "M_L_CPU1_SA_DQ<14>")
	)
	(segment
		(start 144.005046 -233.638852)
		(end 144.016984 -233.631994)
		(width 0.0889)
		(layer "In11.Cu")
		(net "M_L_CPU1_SA_DQ<14>")
	)
	(segment
		(start 200.016364 -212.851746)
		(end 200.016364 -213.269322)
		(width 0.14478)
		(layer "In11.Cu")
		(net "M_L_CPU1_SA_DQ<14>")
	)
	(segment
		(start 197.112636 -213.060534)
		(end 197.213728 -213.060534)
		(width 0.14478)
		(layer "In11.Cu")
		(net "M_L_CPU1_SA_DQ<14>")
	)
	(segment
		(start 145.685002 -233.581448)
		(end 146.53641 -232.73004)
		(width 0.0889)
		(layer "In11.Cu")
		(net "M_L_CPU1_SA_DQ<14>")
	)
	(segment
		(start 165.176454 -213.448646)
		(end 165.321234 -213.593426)
		(width 0.14478)
		(layer "In11.Cu")
		(net "M_L_CPU1_SA_DQ<14>")
	)
	(segment
		(start 159.425386 -218.746578)
		(end 159.425386 -217.670126)
		(width 0.14478)
		(layer "In11.Cu")
		(net "M_L_CPU1_SA_DQ<14>")
	)
	(segment
		(start 195.126102 -213.667086)
		(end 195.270882 -213.522306)
		(width 0.14478)
		(layer "In11.Cu")
		(net "M_L_CPU1_SA_DQ<14>")
	)
	(segment
		(start 167.168576 -212.696806)
		(end 167.77843 -212.696806)
		(width 0.14478)
		(layer "In11.Cu")
		(net "M_L_CPU1_SA_DQ<14>")
	)
	(segment
		(start 192.378838 -213.060534)
		(end 192.59804 -213.060534)
		(width 0.14478)
		(layer "In11.Cu")
		(net "M_L_CPU1_SA_DQ<14>")
	)
	(segment
		(start 154.28468 -224.98177)
		(end 154.28468 -223.887284)
		(width 0.14478)
		(layer "In11.Cu")
		(net "M_L_CPU1_SA_DQ<14>")
	)
	(segment
		(start 164.073586 -213.448646)
		(end 164.218366 -213.593426)
		(width 0.14478)
		(layer "In11.Cu")
		(net "M_L_CPU1_SA_DQ<14>")
	)
	(segment
		(start 200.016364 -213.269322)
		(end 200.161144 -213.414102)
		(width 0.14478)
		(layer "In11.Cu")
		(net "M_L_CPU1_SA_DQ<14>")
	)
	(segment
		(start 169.722292 -212.696806)
		(end 170.097704 -212.696806)
		(width 0.14478)
		(layer "In11.Cu")
		(net "M_L_CPU1_SA_DQ<14>")
	)
	(segment
		(start 177.972466 -213.060534)
		(end 178.82235 -213.910418)
		(width 0.14478)
		(layer "In11.Cu")
		(net "M_L_CPU1_SA_DQ<14>")
	)
	(segment
		(start 168.881298 -212.696806)
		(end 169.026078 -212.841586)
		(width 0.14478)
		(layer "In11.Cu")
		(net "M_L_CPU1_SA_DQ<14>")
	)
	(segment
		(start 195.126102 -213.765638)
		(end 195.126102 -213.667086)
		(width 0.14478)
		(layer "In11.Cu")
		(net "M_L_CPU1_SA_DQ<14>")
	)
	(segment
		(start 165.954964 -213.910418)
		(end 167.168576 -212.696806)
		(width 0.14478)
		(layer "In11.Cu")
		(net "M_L_CPU1_SA_DQ<14>")
	)
	(segment
		(start 163.666932 -213.593426)
		(end 163.811712 -213.448646)
		(width 0.14478)
		(layer "In11.Cu")
		(net "M_L_CPU1_SA_DQ<14>")
	)
	(segment
		(start 200.567798 -212.851746)
		(end 200.712578 -212.706966)
		(width 0.14478)
		(layer "In11.Cu")
		(net "M_L_CPU1_SA_DQ<14>")
	)
	(segment
		(start 201.723244 -213.060534)
		(end 202.147932 -213.485222)
		(width 0.14478)
		(layer "In11.Cu")
		(net "M_L_CPU1_SA_DQ<14>")
	)
	(segment
		(start 167.92321 -212.935566)
		(end 168.06799 -213.080346)
		(width 0.14478)
		(layer "In11.Cu")
		(net "M_L_CPU1_SA_DQ<14>")
	)
	(segment
		(start 195.677536 -213.667086)
		(end 195.677536 -213.765638)
		(width 0.14478)
		(layer "In11.Cu")
		(net "M_L_CPU1_SA_DQ<14>")
	)
	(segment
		(start 164.218366 -213.593426)
		(end 164.218366 -213.765638)
		(width 0.14478)
		(layer "In11.Cu")
		(net "M_L_CPU1_SA_DQ<14>")
	)
	(segment
		(start 192.234058 -212.915754)
		(end 192.378838 -213.060534)
		(width 0.14478)
		(layer "In11.Cu")
		(net "M_L_CPU1_SA_DQ<14>")
	)
	(segment
		(start 145.142204 -233.581448)
		(end 145.685002 -233.581448)
		(width 0.0889)
		(layer "In11.Cu")
		(net "M_L_CPU1_SA_DQ<14>")
	)
	(segment
		(start 191.537844 -213.060534)
		(end 191.682624 -212.915754)
		(width 0.14478)
		(layer "In11.Cu")
		(net "M_L_CPU1_SA_DQ<14>")
	)
	(segment
		(start 168.619424 -212.696806)
		(end 168.881298 -212.696806)
		(width 0.14478)
		(layer "In11.Cu")
		(net "M_L_CPU1_SA_DQ<14>")
	)
	(segment
		(start 178.82235 -213.910418)
		(end 181.065424 -213.910418)
		(width 0.14478)
		(layer "In11.Cu")
		(net "M_L_CPU1_SA_DQ<14>")
	)
	(segment
		(start 172.95368 -213.910418)
		(end 175.005492 -213.060534)
		(width 0.14478)
		(layer "In11.Cu")
		(net "M_L_CPU1_SA_DQ<14>")
	)
	(segment
		(start 187.587382 -213.910418)
		(end 187.732162 -213.765638)
		(width 0.14478)
		(layer "In11.Cu")
		(net "M_L_CPU1_SA_DQ<14>")
	)
	(segment
		(start 163.811712 -213.448646)
		(end 164.073586 -213.448646)
		(width 0.14478)
		(layer "In11.Cu")
		(net "M_L_CPU1_SA_DQ<14>")
	)
	(segment
		(start 197.909942 -213.205314)
		(end 198.054722 -213.060534)
		(width 0.14478)
		(layer "In11.Cu")
		(net "M_L_CPU1_SA_DQ<14>")
	)
	(segment
		(start 199.60971 -212.706966)
		(end 199.871584 -212.706966)
		(width 0.14478)
		(layer "In11.Cu")
		(net "M_L_CPU1_SA_DQ<14>")
	)
	(segment
		(start 191.827404 -212.673946)
		(end 192.089278 -212.673946)
		(width 0.14478)
		(layer "In11.Cu")
		(net "M_L_CPU1_SA_DQ<14>")
	)
	(segment
		(start 197.358508 -213.296246)
		(end 197.503288 -213.441026)
		(width 0.14478)
		(layer "In11.Cu")
		(net "M_L_CPU1_SA_DQ<14>")
	)
	(arc
		(start 141.197838 -233.63174)
		(mid 141.384782 -233.581485)
		(end 141.571726 -233.63174)
		(width 0.0889)
		(layer "In11.Cu")
		(net "M_L_CPU1_SA_DQ<14>")
	)
	(arc
		(start 141.571726 -233.63174)
		(mid 141.854682 -233.707917)
		(end 142.137638 -233.63174)
		(width 0.0889)
		(layer "In11.Cu")
		(net "M_L_CPU1_SA_DQ<14>")
	)
	(arc
		(start 143.086074 -233.626914)
		(mid 143.269582 -233.58142)
		(end 143.451834 -233.63174)
		(width 0.0889)
		(layer "In11.Cu")
		(net "M_L_CPU1_SA_DQ<14>")
	)
	(arc
		(start 142.137638 -233.63174)
		(mid 142.319889 -233.58139)
		(end 142.503398 -233.626914)
		(width 0.0889)
		(layer "In11.Cu")
		(net "M_L_CPU1_SA_DQ<14>")
	)
	(arc
		(start 144.957292 -233.63174)
		(mid 145.046465 -233.594533)
		(end 145.142204 -233.581448)
		(width 0.0889)
		(layer "In11.Cu")
		(net "M_L_CPU1_SA_DQ<14>")
	)
	(arc
		(start 139.691872 -233.63174)
		(mid 139.974828 -233.707917)
		(end 140.257784 -233.63174)
		(width 0.0889)
		(layer "In11.Cu")
		(net "M_L_CPU1_SA_DQ<14>")
	)
	(arc
		(start 142.51178 -233.63174)
		(mid 142.794736 -233.707917)
		(end 143.077692 -233.63174)
		(width 0.0889)
		(layer "In11.Cu")
		(net "M_L_CPU1_SA_DQ<14>")
	)
	(arc
		(start 144.408652 -233.642408)
		(mid 144.684347 -233.708251)
		(end 144.957292 -233.63174)
		(width 0.0889)
		(layer "In11.Cu")
		(net "M_L_CPU1_SA_DQ<14>")
	)
	(arc
		(start 144.0307 -233.62412)
		(mid 144.21163 -233.581642)
		(end 144.390618 -233.63174)
		(width 0.0889)
		(layer "In11.Cu")
		(net "M_L_CPU1_SA_DQ<14>")
	)
	(arc
		(start 143.451834 -233.63174)
		(mid 143.727512 -233.70787)
		(end 144.005046 -233.638852)
		(width 0.0889)
		(layer "In11.Cu")
		(net "M_L_CPU1_SA_DQ<14>")
	)
	(arc
		(start 139.373102 -233.605578)
		(mid 139.535434 -233.58276)
		(end 139.691872 -233.63174)
		(width 0.0889)
		(layer "In11.Cu")
		(net "M_L_CPU1_SA_DQ<14>")
	)
	(arc
		(start 140.266166 -233.626914)
		(mid 140.449674 -233.58142)
		(end 140.631926 -233.63174)
		(width 0.0889)
		(layer "In11.Cu")
		(net "M_L_CPU1_SA_DQ<14>")
	)
	(arc
		(start 140.631926 -233.63174)
		(mid 140.914882 -233.707917)
		(end 141.197838 -233.63174)
		(width 0.0889)
		(layer "In11.Cu")
		(net "M_L_CPU1_SA_DQ<14>")
	)
	(segment
		(start 137.157968 -234.220258)
		(end 137.62482 -233.95432)
		(width 0.10668)
		(layer "F.Cu")
		(net "M_L_CPU1_SA_DQ<13>")
	)
	(segment
		(start 193.510662 -214.759032)
		(end 196.123814 -214.759032)
		(width 0.14478)
		(layer "In11.Cu")
		(net "M_L_CPU1_SA_DQ<13>")
	)
	(segment
		(start 144.947386 -234.270804)
		(end 144.9578 -234.2769)
		(width 0.0889)
		(layer "In11.Cu")
		(net "M_L_CPU1_SA_DQ<13>")
	)
	(segment
		(start 138.743436 -234.281726)
		(end 138.751818 -234.2769)
		(width 0.0889)
		(layer "In11.Cu")
		(net "M_L_CPU1_SA_DQ<13>")
	)
	(segment
		(start 204.827378 -214.073486)
		(end 204.990446 -213.910418)
		(width 0.14478)
		(layer "In11.Cu")
		(net "M_L_CPU1_SA_DQ<13>")
	)
	(segment
		(start 205.823058 -213.910418)
		(end 206.248 -214.33536)
		(width 0.14478)
		(layer "In11.Cu")
		(net "M_L_CPU1_SA_DQ<13>")
	)
	(segment
		(start 159.880046 -217.858594)
		(end 162.978338 -214.760302)
		(width 0.14478)
		(layer "In11.Cu")
		(net "M_L_CPU1_SA_DQ<13>")
	)
	(segment
		(start 171.241212 -214.760302)
		(end 173.519592 -214.760302)
		(width 0.14478)
		(layer "In11.Cu")
		(net "M_L_CPU1_SA_DQ<13>")
	)
	(segment
		(start 142.503398 -234.281726)
		(end 142.51178 -234.2769)
		(width 0.0889)
		(layer "In11.Cu")
		(net "M_L_CPU1_SA_DQ<13>")
	)
	(segment
		(start 204.66431 -214.494364)
		(end 204.827378 -214.331296)
		(width 0.14478)
		(layer "In11.Cu")
		(net "M_L_CPU1_SA_DQ<13>")
	)
	(segment
		(start 196.972428 -213.910418)
		(end 204.107796 -213.910418)
		(width 0.14478)
		(layer "In11.Cu")
		(net "M_L_CPU1_SA_DQ<13>")
	)
	(segment
		(start 166.595298 -213.910418)
		(end 170.391328 -213.910418)
		(width 0.14478)
		(layer "In11.Cu")
		(net "M_L_CPU1_SA_DQ<13>")
	)
	(segment
		(start 137.62482 -233.95432)
		(end 137.778744 -234.21975)
		(width 0.0889)
		(layer "In11.Cu")
		(net "M_L_CPU1_SA_DQ<13>")
	)
	(segment
		(start 154.73934 -224.142808)
		(end 159.880046 -219.002102)
		(width 0.14478)
		(layer "In11.Cu")
		(net "M_L_CPU1_SA_DQ<13>")
	)
	(segment
		(start 174.369476 -213.910418)
		(end 177.972466 -213.910418)
		(width 0.14478)
		(layer "In11.Cu")
		(net "M_L_CPU1_SA_DQ<13>")
	)
	(segment
		(start 181.851808 -213.910418)
		(end 185.250836 -213.910418)
		(width 0.14478)
		(layer "In11.Cu")
		(net "M_L_CPU1_SA_DQ<13>")
	)
	(segment
		(start 204.270864 -214.331296)
		(end 204.433932 -214.494364)
		(width 0.14478)
		(layer "In11.Cu")
		(net "M_L_CPU1_SA_DQ<13>")
	)
	(segment
		(start 196.123814 -214.759032)
		(end 196.972428 -213.910418)
		(width 0.14478)
		(layer "In11.Cu")
		(net "M_L_CPU1_SA_DQ<13>")
	)
	(segment
		(start 181.001924 -214.760302)
		(end 181.851808 -213.910418)
		(width 0.14478)
		(layer "In11.Cu")
		(net "M_L_CPU1_SA_DQ<13>")
	)
	(segment
		(start 139.31773 -234.2769)
		(end 139.326112 -234.281726)
		(width 0.0889)
		(layer "In11.Cu")
		(net "M_L_CPU1_SA_DQ<13>")
	)
	(segment
		(start 144.9578 -234.2769)
		(end 144.966182 -234.281726)
		(width 0.0889)
		(layer "In11.Cu")
		(net "M_L_CPU1_SA_DQ<13>")
	)
	(segment
		(start 189.523116 -213.910418)
		(end 192.662048 -213.910418)
		(width 0.14478)
		(layer "In11.Cu")
		(net "M_L_CPU1_SA_DQ<13>")
	)
	(segment
		(start 204.270864 -214.073486)
		(end 204.270864 -214.331296)
		(width 0.14478)
		(layer "In11.Cu")
		(net "M_L_CPU1_SA_DQ<13>")
	)
	(segment
		(start 143.077692 -234.2769)
		(end 143.086074 -234.281726)
		(width 0.0889)
		(layer "In11.Cu")
		(net "M_L_CPU1_SA_DQ<13>")
	)
	(segment
		(start 173.519592 -214.760302)
		(end 174.369476 -213.910418)
		(width 0.14478)
		(layer "In11.Cu")
		(net "M_L_CPU1_SA_DQ<13>")
	)
	(segment
		(start 204.107796 -213.910418)
		(end 204.270864 -214.073486)
		(width 0.14478)
		(layer "In11.Cu")
		(net "M_L_CPU1_SA_DQ<13>")
	)
	(segment
		(start 204.990446 -213.910418)
		(end 205.823058 -213.910418)
		(width 0.14478)
		(layer "In11.Cu")
		(net "M_L_CPU1_SA_DQ<13>")
	)
	(segment
		(start 204.827378 -214.331296)
		(end 204.827378 -214.073486)
		(width 0.14478)
		(layer "In11.Cu")
		(net "M_L_CPU1_SA_DQ<13>")
	)
	(segment
		(start 148.25472 -231.654858)
		(end 154.73934 -225.170238)
		(width 0.14478)
		(layer "In11.Cu")
		(net "M_L_CPU1_SA_DQ<13>")
	)
	(segment
		(start 144.38376 -234.281726)
		(end 144.392142 -234.2769)
		(width 0.0889)
		(layer "In11.Cu")
		(net "M_L_CPU1_SA_DQ<13>")
	)
	(segment
		(start 188.673232 -214.760302)
		(end 189.523116 -213.910418)
		(width 0.14478)
		(layer "In11.Cu")
		(net "M_L_CPU1_SA_DQ<13>")
	)
	(segment
		(start 147.73529 -231.906826)
		(end 148.002752 -231.906826)
		(width 0.0889)
		(layer "In11.Cu")
		(net "M_L_CPU1_SA_DQ<13>")
	)
	(segment
		(start 185.250836 -213.910418)
		(end 186.10072 -214.760302)
		(width 0.14478)
		(layer "In11.Cu")
		(net "M_L_CPU1_SA_DQ<13>")
	)
	(segment
		(start 148.002752 -231.906826)
		(end 148.25472 -231.654858)
		(width 0.0889)
		(layer "In11.Cu")
		(net "M_L_CPU1_SA_DQ<13>")
	)
	(segment
		(start 140.257784 -234.2769)
		(end 140.266166 -234.281726)
		(width 0.0889)
		(layer "In11.Cu")
		(net "M_L_CPU1_SA_DQ<13>")
	)
	(segment
		(start 154.73934 -225.170238)
		(end 154.73934 -224.142808)
		(width 0.14478)
		(layer "In11.Cu")
		(net "M_L_CPU1_SA_DQ<13>")
	)
	(segment
		(start 145.615152 -234.200446)
		(end 145.79727 -234.200446)
		(width 0.0889)
		(layer "In11.Cu")
		(net "M_L_CPU1_SA_DQ<13>")
	)
	(segment
		(start 178.82235 -214.760302)
		(end 181.001924 -214.760302)
		(width 0.14478)
		(layer "In11.Cu")
		(net "M_L_CPU1_SA_DQ<13>")
	)
	(segment
		(start 143.451834 -234.2769)
		(end 143.462248 -234.270804)
		(width 0.0889)
		(layer "In11.Cu")
		(net "M_L_CPU1_SA_DQ<13>")
	)
	(segment
		(start 146.36877 -233.628946)
		(end 146.36877 -233.273346)
		(width 0.0889)
		(layer "In11.Cu")
		(net "M_L_CPU1_SA_DQ<13>")
	)
	(segment
		(start 162.978338 -214.760302)
		(end 165.745414 -214.760302)
		(width 0.14478)
		(layer "In11.Cu")
		(net "M_L_CPU1_SA_DQ<13>")
	)
	(segment
		(start 186.10072 -214.760302)
		(end 188.673232 -214.760302)
		(width 0.14478)
		(layer "In11.Cu")
		(net "M_L_CPU1_SA_DQ<13>")
	)
	(segment
		(start 146.36877 -233.273346)
		(end 147.73529 -231.906826)
		(width 0.0889)
		(layer "In11.Cu")
		(net "M_L_CPU1_SA_DQ<13>")
	)
	(segment
		(start 159.880046 -219.002102)
		(end 159.880046 -217.858594)
		(width 0.14478)
		(layer "In11.Cu")
		(net "M_L_CPU1_SA_DQ<13>")
	)
	(segment
		(start 204.433932 -214.494364)
		(end 204.66431 -214.494364)
		(width 0.14478)
		(layer "In11.Cu")
		(net "M_L_CPU1_SA_DQ<13>")
	)
	(segment
		(start 165.745414 -214.760302)
		(end 166.595298 -213.910418)
		(width 0.14478)
		(layer "In11.Cu")
		(net "M_L_CPU1_SA_DQ<13>")
	)
	(segment
		(start 170.391328 -213.910418)
		(end 171.241212 -214.760302)
		(width 0.14478)
		(layer "In11.Cu")
		(net "M_L_CPU1_SA_DQ<13>")
	)
	(segment
		(start 145.79727 -234.200446)
		(end 146.36877 -233.628946)
		(width 0.0889)
		(layer "In11.Cu")
		(net "M_L_CPU1_SA_DQ<13>")
	)
	(segment
		(start 192.662048 -213.910418)
		(end 193.510662 -214.759032)
		(width 0.14478)
		(layer "In11.Cu")
		(net "M_L_CPU1_SA_DQ<13>")
	)
	(segment
		(start 137.778744 -234.21975)
		(end 137.874756 -234.24515)
		(width 0.0889)
		(layer "In11.Cu")
		(net "M_L_CPU1_SA_DQ<13>")
	)
	(segment
		(start 177.972466 -213.910418)
		(end 178.82235 -214.760302)
		(width 0.14478)
		(layer "In11.Cu")
		(net "M_L_CPU1_SA_DQ<13>")
	)
	(arc
		(start 140.631926 -234.2769)
		(mid 140.914882 -234.200723)
		(end 141.197838 -234.2769)
		(width 0.0889)
		(layer "In11.Cu")
		(net "M_L_CPU1_SA_DQ<13>")
	)
	(arc
		(start 141.571726 -234.2769)
		(mid 141.854682 -234.200723)
		(end 142.137638 -234.2769)
		(width 0.0889)
		(layer "In11.Cu")
		(net "M_L_CPU1_SA_DQ<13>")
	)
	(arc
		(start 143.462248 -234.270804)
		(mid 143.740934 -234.200584)
		(end 144.018 -234.2769)
		(width 0.0889)
		(layer "In11.Cu")
		(net "M_L_CPU1_SA_DQ<13>")
	)
	(arc
		(start 140.266166 -234.281726)
		(mid 140.449674 -234.32722)
		(end 140.631926 -234.2769)
		(width 0.0889)
		(layer "In11.Cu")
		(net "M_L_CPU1_SA_DQ<13>")
	)
	(arc
		(start 143.086074 -234.281726)
		(mid 143.269582 -234.32722)
		(end 143.451834 -234.2769)
		(width 0.0889)
		(layer "In11.Cu")
		(net "M_L_CPU1_SA_DQ<13>")
	)
	(arc
		(start 145.331942 -234.2769)
		(mid 145.46849 -234.219944)
		(end 145.615152 -234.200446)
		(width 0.0889)
		(layer "In11.Cu")
		(net "M_L_CPU1_SA_DQ<13>")
	)
	(arc
		(start 144.966182 -234.281726)
		(mid 145.14969 -234.32722)
		(end 145.331942 -234.2769)
		(width 0.0889)
		(layer "In11.Cu")
		(net "M_L_CPU1_SA_DQ<13>")
	)
	(arc
		(start 138.377676 -234.2769)
		(mid 138.559927 -234.32725)
		(end 138.743436 -234.281726)
		(width 0.0889)
		(layer "In11.Cu")
		(net "M_L_CPU1_SA_DQ<13>")
	)
	(arc
		(start 144.018 -234.2769)
		(mid 144.200251 -234.32725)
		(end 144.38376 -234.281726)
		(width 0.0889)
		(layer "In11.Cu")
		(net "M_L_CPU1_SA_DQ<13>")
	)
	(arc
		(start 139.326112 -234.281726)
		(mid 139.50962 -234.32722)
		(end 139.691872 -234.2769)
		(width 0.0889)
		(layer "In11.Cu")
		(net "M_L_CPU1_SA_DQ<13>")
	)
	(arc
		(start 137.874756 -234.24515)
		(mid 138.129964 -234.201673)
		(end 138.377676 -234.2769)
		(width 0.0889)
		(layer "In11.Cu")
		(net "M_L_CPU1_SA_DQ<13>")
	)
	(arc
		(start 138.751818 -234.2769)
		(mid 139.034774 -234.200723)
		(end 139.31773 -234.2769)
		(width 0.0889)
		(layer "In11.Cu")
		(net "M_L_CPU1_SA_DQ<13>")
	)
	(arc
		(start 142.51178 -234.2769)
		(mid 142.794736 -234.200723)
		(end 143.077692 -234.2769)
		(width 0.0889)
		(layer "In11.Cu")
		(net "M_L_CPU1_SA_DQ<13>")
	)
	(arc
		(start 142.137638 -234.2769)
		(mid 142.319889 -234.32725)
		(end 142.503398 -234.281726)
		(width 0.0889)
		(layer "In11.Cu")
		(net "M_L_CPU1_SA_DQ<13>")
	)
	(arc
		(start 139.691872 -234.2769)
		(mid 139.974828 -234.200723)
		(end 140.257784 -234.2769)
		(width 0.0889)
		(layer "In11.Cu")
		(net "M_L_CPU1_SA_DQ<13>")
	)
	(arc
		(start 141.197838 -234.2769)
		(mid 141.384782 -234.327155)
		(end 141.571726 -234.2769)
		(width 0.0889)
		(layer "In11.Cu")
		(net "M_L_CPU1_SA_DQ<13>")
	)
	(arc
		(start 144.392142 -234.2769)
		(mid 144.668955 -234.200757)
		(end 144.947386 -234.270804)
		(width 0.0889)
		(layer "In11.Cu")
		(net "M_L_CPU1_SA_DQ<13>")
	)
	(segment
		(start 138.567922 -233.410252)
		(end 139.034774 -233.144314)
		(width 0.10668)
		(layer "F.Cu")
		(net "M_L_CPU1_SA_DQ<12>")
	)
	(segment
		(start 165.441884 -213.06028)
		(end 166.08552 -213.06028)
		(width 0.14478)
		(layer "In11.Cu")
		(net "M_L_CPU1_SA_DQ<12>")
	)
	(segment
		(start 144.48663 -233.466894)
		(end 144.498314 -233.473752)
		(width 0.0889)
		(layer "In11.Cu")
		(net "M_L_CPU1_SA_DQ<12>")
	)
	(segment
		(start 204.618844 -213.010496)
		(end 204.781912 -213.173564)
		(width 0.14478)
		(layer "In11.Cu")
		(net "M_L_CPU1_SA_DQ<12>")
	)
	(segment
		(start 147.10283 -231.939846)
		(end 147.10283 -231.520746)
		(width 0.0889)
		(layer "In11.Cu")
		(net "M_L_CPU1_SA_DQ<12>")
	)
	(segment
		(start 165.10635 -212.724746)
		(end 165.441884 -213.06028)
		(width 0.14478)
		(layer "In11.Cu")
		(net "M_L_CPU1_SA_DQ<12>")
	)
	(segment
		(start 205.338426 -212.210396)
		(end 205.823058 -212.210396)
		(width 0.14478)
		(layer "In11.Cu")
		(net "M_L_CPU1_SA_DQ<12>")
	)
	(segment
		(start 204.618844 -212.373464)
		(end 204.618844 -213.010496)
		(width 0.14478)
		(layer "In11.Cu")
		(net "M_L_CPU1_SA_DQ<12>")
	)
	(segment
		(start 139.034774 -233.144314)
		(end 139.188698 -233.409744)
		(width 0.0889)
		(layer "In11.Cu")
		(net "M_L_CPU1_SA_DQ<12>")
	)
	(segment
		(start 166.08552 -213.06028)
		(end 166.926006 -212.219794)
		(width 0.14478)
		(layer "In11.Cu")
		(net "M_L_CPU1_SA_DQ<12>")
	)
	(segment
		(start 192.612518 -212.219794)
		(end 193.462402 -213.069678)
		(width 0.14478)
		(layer "In11.Cu")
		(net "M_L_CPU1_SA_DQ<12>")
	)
	(segment
		(start 139.188698 -233.409744)
		(end 139.28471 -233.435144)
		(width 0.0889)
		(layer "In11.Cu")
		(net "M_L_CPU1_SA_DQ<12>")
	)
	(segment
		(start 205.01229 -213.173564)
		(end 205.175358 -213.010496)
		(width 0.14478)
		(layer "In11.Cu")
		(net "M_L_CPU1_SA_DQ<12>")
	)
	(segment
		(start 141.093444 -233.47172)
		(end 141.101826 -233.466894)
		(width 0.0889)
		(layer "In11.Cu")
		(net "M_L_CPU1_SA_DQ<12>")
	)
	(segment
		(start 185.260234 -212.219794)
		(end 186.110118 -213.069678)
		(width 0.14478)
		(layer "In11.Cu")
		(net "M_L_CPU1_SA_DQ<12>")
	)
	(segment
		(start 147.10283 -231.520746)
		(end 147.862036 -230.76154)
		(width 0.0889)
		(layer "In11.Cu")
		(net "M_L_CPU1_SA_DQ<12>")
	)
	(segment
		(start 205.175358 -212.373464)
		(end 205.338426 -212.210396)
		(width 0.14478)
		(layer "In11.Cu")
		(net "M_L_CPU1_SA_DQ<12>")
	)
	(segment
		(start 147.862036 -230.76154)
		(end 153.83002 -224.793556)
		(width 0.14478)
		(layer "In11.Cu")
		(net "M_L_CPU1_SA_DQ<12>")
	)
	(segment
		(start 163.727384 -212.724746)
		(end 165.10635 -212.724746)
		(width 0.14478)
		(layer "In11.Cu")
		(net "M_L_CPU1_SA_DQ<12>")
	)
	(segment
		(start 196.348858 -213.069678)
		(end 197.198742 -212.219794)
		(width 0.14478)
		(layer "In11.Cu")
		(net "M_L_CPU1_SA_DQ<12>")
	)
	(segment
		(start 145.558002 -233.390694)
		(end 145.90649 -233.042206)
		(width 0.0889)
		(layer "In11.Cu")
		(net "M_L_CPU1_SA_DQ<12>")
	)
	(segment
		(start 186.110118 -213.069678)
		(end 188.663834 -213.069678)
		(width 0.14478)
		(layer "In11.Cu")
		(net "M_L_CPU1_SA_DQ<12>")
	)
	(segment
		(start 158.905194 -218.604592)
		(end 158.905194 -217.546936)
		(width 0.14478)
		(layer "In11.Cu")
		(net "M_L_CPU1_SA_DQ<12>")
	)
	(segment
		(start 158.905194 -217.546936)
		(end 163.727384 -212.724746)
		(width 0.14478)
		(layer "In11.Cu")
		(net "M_L_CPU1_SA_DQ<12>")
	)
	(segment
		(start 173.591982 -213.069678)
		(end 174.441866 -212.219794)
		(width 0.14478)
		(layer "In11.Cu")
		(net "M_L_CPU1_SA_DQ<12>")
	)
	(segment
		(start 140.15339 -233.47172)
		(end 140.161772 -233.466894)
		(width 0.0889)
		(layer "In11.Cu")
		(net "M_L_CPU1_SA_DQ<12>")
	)
	(segment
		(start 143.905224 -233.476038)
		(end 143.92148 -233.46664)
		(width 0.0889)
		(layer "In11.Cu")
		(net "M_L_CPU1_SA_DQ<12>")
	)
	(segment
		(start 178.765708 -213.069678)
		(end 181.21249 -213.069678)
		(width 0.14478)
		(layer "In11.Cu")
		(net "M_L_CPU1_SA_DQ<12>")
	)
	(segment
		(start 181.21249 -213.069678)
		(end 182.062374 -212.219794)
		(width 0.14478)
		(layer "In11.Cu")
		(net "M_L_CPU1_SA_DQ<12>")
	)
	(segment
		(start 177.915824 -212.219794)
		(end 178.765708 -213.069678)
		(width 0.14478)
		(layer "In11.Cu")
		(net "M_L_CPU1_SA_DQ<12>")
	)
	(segment
		(start 182.062374 -212.219794)
		(end 185.260234 -212.219794)
		(width 0.14478)
		(layer "In11.Cu")
		(net "M_L_CPU1_SA_DQ<12>")
	)
	(segment
		(start 146.72183 -232.320846)
		(end 147.10283 -231.939846)
		(width 0.0889)
		(layer "In11.Cu")
		(net "M_L_CPU1_SA_DQ<12>")
	)
	(segment
		(start 141.667738 -233.466894)
		(end 141.67612 -233.47172)
		(width 0.0889)
		(layer "In11.Cu")
		(net "M_L_CPU1_SA_DQ<12>")
	)
	(segment
		(start 193.462402 -213.069678)
		(end 196.348858 -213.069678)
		(width 0.14478)
		(layer "In11.Cu")
		(net "M_L_CPU1_SA_DQ<12>")
	)
	(segment
		(start 145.90649 -233.042206)
		(end 145.90649 -232.889806)
		(width 0.0889)
		(layer "In11.Cu")
		(net "M_L_CPU1_SA_DQ<12>")
	)
	(segment
		(start 197.198742 -212.219794)
		(end 204.465174 -212.219794)
		(width 0.14478)
		(layer "In11.Cu")
		(net "M_L_CPU1_SA_DQ<12>")
	)
	(segment
		(start 205.175358 -213.010496)
		(end 205.175358 -212.373464)
		(width 0.14478)
		(layer "In11.Cu")
		(net "M_L_CPU1_SA_DQ<12>")
	)
	(segment
		(start 171.199048 -213.069678)
		(end 173.591982 -213.069678)
		(width 0.14478)
		(layer "In11.Cu")
		(net "M_L_CPU1_SA_DQ<12>")
	)
	(segment
		(start 170.349164 -212.219794)
		(end 171.199048 -213.069678)
		(width 0.14478)
		(layer "In11.Cu")
		(net "M_L_CPU1_SA_DQ<12>")
	)
	(segment
		(start 166.926006 -212.219794)
		(end 170.349164 -212.219794)
		(width 0.14478)
		(layer "In11.Cu")
		(net "M_L_CPU1_SA_DQ<12>")
	)
	(segment
		(start 146.47545 -232.320846)
		(end 146.72183 -232.320846)
		(width 0.0889)
		(layer "In11.Cu")
		(net "M_L_CPU1_SA_DQ<12>")
	)
	(segment
		(start 204.781912 -213.173564)
		(end 205.01229 -213.173564)
		(width 0.14478)
		(layer "In11.Cu")
		(net "M_L_CPU1_SA_DQ<12>")
	)
	(segment
		(start 145.161762 -233.390694)
		(end 145.558002 -233.390694)
		(width 0.0889)
		(layer "In11.Cu")
		(net "M_L_CPU1_SA_DQ<12>")
	)
	(segment
		(start 188.663834 -213.069678)
		(end 189.513718 -212.219794)
		(width 0.14478)
		(layer "In11.Cu")
		(net "M_L_CPU1_SA_DQ<12>")
	)
	(segment
		(start 205.823058 -212.210396)
		(end 206.248 -212.635338)
		(width 0.14478)
		(layer "In11.Cu")
		(net "M_L_CPU1_SA_DQ<12>")
	)
	(segment
		(start 143.92148 -233.46664)
		(end 143.933418 -233.459782)
		(width 0.0889)
		(layer "In11.Cu")
		(net "M_L_CPU1_SA_DQ<12>")
	)
	(segment
		(start 153.83002 -223.679766)
		(end 158.905194 -218.604592)
		(width 0.14478)
		(layer "In11.Cu")
		(net "M_L_CPU1_SA_DQ<12>")
	)
	(segment
		(start 145.90649 -232.889806)
		(end 146.47545 -232.320846)
		(width 0.0889)
		(layer "In11.Cu")
		(net "M_L_CPU1_SA_DQ<12>")
	)
	(segment
		(start 174.441866 -212.219794)
		(end 177.915824 -212.219794)
		(width 0.14478)
		(layer "In11.Cu")
		(net "M_L_CPU1_SA_DQ<12>")
	)
	(segment
		(start 204.465174 -212.219794)
		(end 204.618844 -212.373464)
		(width 0.14478)
		(layer "In11.Cu")
		(net "M_L_CPU1_SA_DQ<12>")
	)
	(segment
		(start 153.83002 -224.793556)
		(end 153.83002 -223.679766)
		(width 0.14478)
		(layer "In11.Cu")
		(net "M_L_CPU1_SA_DQ<12>")
	)
	(segment
		(start 189.513718 -212.219794)
		(end 192.612518 -212.219794)
		(width 0.14478)
		(layer "In11.Cu")
		(net "M_L_CPU1_SA_DQ<12>")
	)
	(arc
		(start 144.861026 -233.466894)
		(mid 145.006052 -233.407721)
		(end 145.161762 -233.390694)
		(width 0.0889)
		(layer "In11.Cu")
		(net "M_L_CPU1_SA_DQ<12>")
	)
	(arc
		(start 143.547592 -233.466894)
		(mid 143.725242 -233.517154)
		(end 143.905224 -233.476038)
		(width 0.0889)
		(layer "In11.Cu")
		(net "M_L_CPU1_SA_DQ<12>")
	)
	(arc
		(start 140.161772 -233.466894)
		(mid 140.444728 -233.390717)
		(end 140.727684 -233.466894)
		(width 0.0889)
		(layer "In11.Cu")
		(net "M_L_CPU1_SA_DQ<12>")
	)
	(arc
		(start 142.98168 -233.466894)
		(mid 143.264636 -233.390717)
		(end 143.547592 -233.466894)
		(width 0.0889)
		(layer "In11.Cu")
		(net "M_L_CPU1_SA_DQ<12>")
	)
	(arc
		(start 144.498314 -233.473752)
		(mid 144.680569 -233.517405)
		(end 144.861026 -233.466894)
		(width 0.0889)
		(layer "In11.Cu")
		(net "M_L_CPU1_SA_DQ<12>")
	)
	(arc
		(start 143.933418 -233.459782)
		(mid 144.210952 -233.390801)
		(end 144.48663 -233.466894)
		(width 0.0889)
		(layer "In11.Cu")
		(net "M_L_CPU1_SA_DQ<12>")
	)
	(arc
		(start 141.101826 -233.466894)
		(mid 141.384782 -233.390717)
		(end 141.667738 -233.466894)
		(width 0.0889)
		(layer "In11.Cu")
		(net "M_L_CPU1_SA_DQ<12>")
	)
	(arc
		(start 139.78763 -233.466894)
		(mid 139.969881 -233.517244)
		(end 140.15339 -233.47172)
		(width 0.0889)
		(layer "In11.Cu")
		(net "M_L_CPU1_SA_DQ<12>")
	)
	(arc
		(start 140.727684 -233.466894)
		(mid 140.909935 -233.517244)
		(end 141.093444 -233.47172)
		(width 0.0889)
		(layer "In11.Cu")
		(net "M_L_CPU1_SA_DQ<12>")
	)
	(arc
		(start 141.67612 -233.47172)
		(mid 141.859628 -233.517214)
		(end 142.04188 -233.466894)
		(width 0.0889)
		(layer "In11.Cu")
		(net "M_L_CPU1_SA_DQ<12>")
	)
	(arc
		(start 139.28471 -233.435144)
		(mid 139.539918 -233.391667)
		(end 139.78763 -233.466894)
		(width 0.0889)
		(layer "In11.Cu")
		(net "M_L_CPU1_SA_DQ<12>")
	)
	(arc
		(start 142.04188 -233.466894)
		(mid 142.324836 -233.390717)
		(end 142.607792 -233.466894)
		(width 0.0889)
		(layer "In11.Cu")
		(net "M_L_CPU1_SA_DQ<12>")
	)
	(arc
		(start 142.607792 -233.466894)
		(mid 142.794736 -233.517149)
		(end 142.98168 -233.466894)
		(width 0.0889)
		(layer "In11.Cu")
		(net "M_L_CPU1_SA_DQ<12>")
	)
	(segment
		(start 137.627868 -231.79024)
		(end 138.09472 -231.524302)
		(width 0.10668)
		(layer "F.Cu")
		(net "M_L_CPU1_SA_DQ<11>")
	)
	(segment
		(start 174.436278 -208.800954)
		(end 177.713894 -208.800954)
		(width 0.14478)
		(layer "In11.Cu")
		(net "M_L_CPU1_SA_DQ<11>")
	)
	(segment
		(start 151.407622 -221.735396)
		(end 160.810956 -212.332062)
		(width 0.14478)
		(layer "In11.Cu")
		(net "M_L_CPU1_SA_DQ<11>")
	)
	(segment
		(start 151.407622 -223.780858)
		(end 151.407622 -221.735396)
		(width 0.14478)
		(layer "In11.Cu")
		(net "M_L_CPU1_SA_DQ<11>")
	)
	(segment
		(start 147.01901 -228.16947)
		(end 147.832318 -227.356162)
		(width 0.0889)
		(layer "In11.Cu")
		(net "M_L_CPU1_SA_DQ<11>")
	)
	(segment
		(start 161.341054 -211.056728)
		(end 161.341054 -210.826096)
		(width 0.14478)
		(layer "In11.Cu")
		(net "M_L_CPU1_SA_DQ<11>")
	)
	(segment
		(start 162.767772 -210.121246)
		(end 162.973004 -210.121246)
		(width 0.14478)
		(layer "In11.Cu")
		(net "M_L_CPU1_SA_DQ<11>")
	)
	(segment
		(start 161.734754 -210.663028)
		(end 161.992056 -210.92033)
		(width 0.14478)
		(layer "In11.Cu")
		(net "M_L_CPU1_SA_DQ<11>")
	)
	(segment
		(start 161.504122 -210.663028)
		(end 161.734754 -210.663028)
		(width 0.14478)
		(layer "In11.Cu")
		(net "M_L_CPU1_SA_DQ<11>")
	)
	(segment
		(start 200.69556 -208.945988)
		(end 200.69556 -209.176366)
		(width 0.14478)
		(layer "In11.Cu")
		(net "M_L_CPU1_SA_DQ<11>")
	)
	(segment
		(start 160.947354 -211.450428)
		(end 161.204656 -211.70773)
		(width 0.14478)
		(layer "In11.Cu")
		(net "M_L_CPU1_SA_DQ<11>")
	)
	(segment
		(start 201.713846 -208.801208)
		(end 202.147932 -209.235294)
		(width 0.14478)
		(layer "In11.Cu")
		(net "M_L_CPU1_SA_DQ<11>")
	)
	(segment
		(start 146.29257 -229.450646)
		(end 146.29257 -229.219506)
		(width 0.0889)
		(layer "In11.Cu")
		(net "M_L_CPU1_SA_DQ<11>")
	)
	(segment
		(start 141.093444 -231.19715)
		(end 141.101826 -231.201976)
		(width 0.0889)
		(layer "In11.Cu")
		(net "M_L_CPU1_SA_DQ<11>")
	)
	(segment
		(start 145.134076 -231.27462)
		(end 145.63217 -230.776526)
		(width 0.0889)
		(layer "In11.Cu")
		(net "M_L_CPU1_SA_DQ<11>")
	)
	(segment
		(start 162.222688 -210.92033)
		(end 162.385756 -210.757262)
		(width 0.14478)
		(layer "In11.Cu")
		(net "M_L_CPU1_SA_DQ<11>")
	)
	(segment
		(start 162.973004 -210.121246)
		(end 163.434014 -209.660236)
		(width 0.14478)
		(layer "In11.Cu")
		(net "M_L_CPU1_SA_DQ<11>")
	)
	(segment
		(start 201.391774 -208.801208)
		(end 201.713846 -208.801208)
		(width 0.14478)
		(layer "In11.Cu")
		(net "M_L_CPU1_SA_DQ<11>")
	)
	(segment
		(start 141.667738 -231.201976)
		(end 141.67612 -231.19715)
		(width 0.0889)
		(layer "In11.Cu")
		(net "M_L_CPU1_SA_DQ<11>")
	)
	(segment
		(start 162.128454 -210.038696)
		(end 162.291522 -209.875628)
		(width 0.14478)
		(layer "In11.Cu")
		(net "M_L_CPU1_SA_DQ<11>")
	)
	(segment
		(start 188.68263 -209.651092)
		(end 189.532514 -208.801208)
		(width 0.14478)
		(layer "In11.Cu")
		(net "M_L_CPU1_SA_DQ<11>")
	)
	(segment
		(start 196.846698 -208.801208)
		(end 200.55078 -208.801208)
		(width 0.14478)
		(layer "In11.Cu")
		(net "M_L_CPU1_SA_DQ<11>")
	)
	(segment
		(start 161.992056 -210.92033)
		(end 162.222688 -210.92033)
		(width 0.14478)
		(layer "In11.Cu")
		(net "M_L_CPU1_SA_DQ<11>")
	)
	(segment
		(start 137.940796 -231.258872)
		(end 137.963148 -231.175814)
		(width 0.0889)
		(layer "In11.Cu")
		(net "M_L_CPU1_SA_DQ<11>")
	)
	(segment
		(start 162.385756 -210.757262)
		(end 162.385756 -210.52663)
		(width 0.14478)
		(layer "In11.Cu")
		(net "M_L_CPU1_SA_DQ<11>")
	)
	(segment
		(start 144.270476 -231.27462)
		(end 145.134076 -231.27462)
		(width 0.0889)
		(layer "In11.Cu")
		(net "M_L_CPU1_SA_DQ<11>")
	)
	(segment
		(start 201.246994 -209.176366)
		(end 201.246994 -208.945988)
		(width 0.14478)
		(layer "In11.Cu")
		(net "M_L_CPU1_SA_DQ<11>")
	)
	(segment
		(start 161.598356 -211.544662)
		(end 161.598356 -211.31403)
		(width 0.14478)
		(layer "In11.Cu")
		(net "M_L_CPU1_SA_DQ<11>")
	)
	(segment
		(start 177.713894 -208.800954)
		(end 178.563778 -209.650838)
		(width 0.14478)
		(layer "In11.Cu")
		(net "M_L_CPU1_SA_DQ<11>")
	)
	(segment
		(start 147.01901 -228.493066)
		(end 147.01901 -228.16947)
		(width 0.0889)
		(layer "In11.Cu")
		(net "M_L_CPU1_SA_DQ<11>")
	)
	(segment
		(start 146.29257 -229.219506)
		(end 147.01901 -228.493066)
		(width 0.0889)
		(layer "In11.Cu")
		(net "M_L_CPU1_SA_DQ<11>")
	)
	(segment
		(start 181.85003 -208.801208)
		(end 185.28919 -208.801208)
		(width 0.14478)
		(layer "In11.Cu")
		(net "M_L_CPU1_SA_DQ<11>")
	)
	(segment
		(start 170.282616 -208.800954)
		(end 171.1325 -209.650838)
		(width 0.14478)
		(layer "In11.Cu")
		(net "M_L_CPU1_SA_DQ<11>")
	)
	(segment
		(start 201.246994 -208.945988)
		(end 201.391774 -208.801208)
		(width 0.14478)
		(layer "In11.Cu")
		(net "M_L_CPU1_SA_DQ<11>")
	)
	(segment
		(start 195.996814 -209.651092)
		(end 196.846698 -208.801208)
		(width 0.14478)
		(layer "In11.Cu")
		(net "M_L_CPU1_SA_DQ<11>")
	)
	(segment
		(start 162.385756 -210.52663)
		(end 162.128454 -210.269328)
		(width 0.14478)
		(layer "In11.Cu")
		(net "M_L_CPU1_SA_DQ<11>")
	)
	(segment
		(start 200.69556 -209.176366)
		(end 200.84034 -209.321146)
		(width 0.14478)
		(layer "In11.Cu")
		(net "M_L_CPU1_SA_DQ<11>")
	)
	(segment
		(start 147.832318 -227.356162)
		(end 151.407622 -223.780858)
		(width 0.14478)
		(layer "In11.Cu")
		(net "M_L_CPU1_SA_DQ<11>")
	)
	(segment
		(start 160.810956 -212.332062)
		(end 160.810956 -212.10143)
		(width 0.14478)
		(layer "In11.Cu")
		(net "M_L_CPU1_SA_DQ<11>")
	)
	(segment
		(start 140.15339 -231.19715)
		(end 140.161772 -231.201976)
		(width 0.0889)
		(layer "In11.Cu")
		(net "M_L_CPU1_SA_DQ<11>")
	)
	(segment
		(start 200.84034 -209.321146)
		(end 201.102214 -209.321146)
		(width 0.14478)
		(layer "In11.Cu")
		(net "M_L_CPU1_SA_DQ<11>")
	)
	(segment
		(start 161.435288 -211.70773)
		(end 161.598356 -211.544662)
		(width 0.14478)
		(layer "In11.Cu")
		(net "M_L_CPU1_SA_DQ<11>")
	)
	(segment
		(start 138.09472 -231.524302)
		(end 137.940796 -231.258872)
		(width 0.0889)
		(layer "In11.Cu")
		(net "M_L_CPU1_SA_DQ<11>")
	)
	(segment
		(start 161.204656 -211.70773)
		(end 161.435288 -211.70773)
		(width 0.14478)
		(layer "In11.Cu")
		(net "M_L_CPU1_SA_DQ<11>")
	)
	(segment
		(start 163.434014 -209.660236)
		(end 165.973506 -209.660236)
		(width 0.14478)
		(layer "In11.Cu")
		(net "M_L_CPU1_SA_DQ<11>")
	)
	(segment
		(start 200.55078 -208.801208)
		(end 200.69556 -208.945988)
		(width 0.14478)
		(layer "In11.Cu")
		(net "M_L_CPU1_SA_DQ<11>")
	)
	(segment
		(start 165.973506 -209.660236)
		(end 166.832788 -208.800954)
		(width 0.14478)
		(layer "In11.Cu")
		(net "M_L_CPU1_SA_DQ<11>")
	)
	(segment
		(start 162.291522 -209.875628)
		(end 162.522154 -209.875628)
		(width 0.14478)
		(layer "In11.Cu")
		(net "M_L_CPU1_SA_DQ<11>")
	)
	(segment
		(start 161.341054 -210.826096)
		(end 161.504122 -210.663028)
		(width 0.14478)
		(layer "In11.Cu")
		(net "M_L_CPU1_SA_DQ<11>")
	)
	(segment
		(start 162.128454 -210.269328)
		(end 162.128454 -210.038696)
		(width 0.14478)
		(layer "In11.Cu")
		(net "M_L_CPU1_SA_DQ<11>")
	)
	(segment
		(start 193.157602 -208.801208)
		(end 194.007486 -209.651092)
		(width 0.14478)
		(layer "In11.Cu")
		(net "M_L_CPU1_SA_DQ<11>")
	)
	(segment
		(start 162.522154 -209.875628)
		(end 162.767772 -210.121246)
		(width 0.14478)
		(layer "In11.Cu")
		(net "M_L_CPU1_SA_DQ<11>")
	)
	(segment
		(start 201.102214 -209.321146)
		(end 201.246994 -209.176366)
		(width 0.14478)
		(layer "In11.Cu")
		(net "M_L_CPU1_SA_DQ<11>")
	)
	(segment
		(start 161.598356 -211.31403)
		(end 161.341054 -211.056728)
		(width 0.14478)
		(layer "In11.Cu")
		(net "M_L_CPU1_SA_DQ<11>")
	)
	(segment
		(start 178.563778 -209.650838)
		(end 181.0004 -209.650838)
		(width 0.14478)
		(layer "In11.Cu")
		(net "M_L_CPU1_SA_DQ<11>")
	)
	(segment
		(start 189.532514 -208.801208)
		(end 193.157602 -208.801208)
		(width 0.14478)
		(layer "In11.Cu")
		(net "M_L_CPU1_SA_DQ<11>")
	)
	(segment
		(start 194.007486 -209.651092)
		(end 195.996814 -209.651092)
		(width 0.14478)
		(layer "In11.Cu")
		(net "M_L_CPU1_SA_DQ<11>")
	)
	(segment
		(start 186.139074 -209.651092)
		(end 188.68263 -209.651092)
		(width 0.14478)
		(layer "In11.Cu")
		(net "M_L_CPU1_SA_DQ<11>")
	)
	(segment
		(start 145.63217 -230.111046)
		(end 146.29257 -229.450646)
		(width 0.0889)
		(layer "In11.Cu")
		(net "M_L_CPU1_SA_DQ<11>")
	)
	(segment
		(start 160.553654 -211.613496)
		(end 160.716722 -211.450428)
		(width 0.14478)
		(layer "In11.Cu")
		(net "M_L_CPU1_SA_DQ<11>")
	)
	(segment
		(start 160.553654 -211.844128)
		(end 160.553654 -211.613496)
		(width 0.14478)
		(layer "In11.Cu")
		(net "M_L_CPU1_SA_DQ<11>")
	)
	(segment
		(start 171.1325 -209.650838)
		(end 173.586394 -209.650838)
		(width 0.14478)
		(layer "In11.Cu")
		(net "M_L_CPU1_SA_DQ<11>")
	)
	(segment
		(start 166.832788 -208.800954)
		(end 170.282616 -208.800954)
		(width 0.14478)
		(layer "In11.Cu")
		(net "M_L_CPU1_SA_DQ<11>")
	)
	(segment
		(start 160.716722 -211.450428)
		(end 160.947354 -211.450428)
		(width 0.14478)
		(layer "In11.Cu")
		(net "M_L_CPU1_SA_DQ<11>")
	)
	(segment
		(start 173.586394 -209.650838)
		(end 174.436278 -208.800954)
		(width 0.14478)
		(layer "In11.Cu")
		(net "M_L_CPU1_SA_DQ<11>")
	)
	(segment
		(start 145.63217 -230.776526)
		(end 145.63217 -230.111046)
		(width 0.0889)
		(layer "In11.Cu")
		(net "M_L_CPU1_SA_DQ<11>")
	)
	(segment
		(start 185.28919 -208.801208)
		(end 186.139074 -209.651092)
		(width 0.14478)
		(layer "In11.Cu")
		(net "M_L_CPU1_SA_DQ<11>")
	)
	(segment
		(start 160.810956 -212.10143)
		(end 160.553654 -211.844128)
		(width 0.14478)
		(layer "In11.Cu")
		(net "M_L_CPU1_SA_DQ<11>")
	)
	(segment
		(start 181.0004 -209.650838)
		(end 181.85003 -208.801208)
		(width 0.14478)
		(layer "In11.Cu")
		(net "M_L_CPU1_SA_DQ<11>")
	)
	(arc
		(start 140.727684 -231.201976)
		(mid 140.909935 -231.151592)
		(end 141.093444 -231.19715)
		(width 0.0889)
		(layer "In11.Cu")
		(net "M_L_CPU1_SA_DQ<11>")
	)
	(arc
		(start 143.547592 -231.201976)
		(mid 143.73479 -231.151559)
		(end 143.921988 -231.201976)
		(width 0.0889)
		(layer "In11.Cu")
		(net "M_L_CPU1_SA_DQ<11>")
	)
	(arc
		(start 139.221718 -231.201976)
		(mid 139.504674 -231.278153)
		(end 139.78763 -231.201976)
		(width 0.0889)
		(layer "In11.Cu")
		(net "M_L_CPU1_SA_DQ<11>")
	)
	(arc
		(start 141.101826 -231.201976)
		(mid 141.384782 -231.278153)
		(end 141.667738 -231.201976)
		(width 0.0889)
		(layer "In11.Cu")
		(net "M_L_CPU1_SA_DQ<11>")
	)
	(arc
		(start 142.04188 -231.201976)
		(mid 142.324836 -231.278153)
		(end 142.607792 -231.201976)
		(width 0.0889)
		(layer "In11.Cu")
		(net "M_L_CPU1_SA_DQ<11>")
	)
	(arc
		(start 138.84783 -231.201976)
		(mid 139.034774 -231.151687)
		(end 139.221718 -231.201976)
		(width 0.0889)
		(layer "In11.Cu")
		(net "M_L_CPU1_SA_DQ<11>")
	)
	(arc
		(start 140.161772 -231.201976)
		(mid 140.444728 -231.278153)
		(end 140.727684 -231.201976)
		(width 0.0889)
		(layer "In11.Cu")
		(net "M_L_CPU1_SA_DQ<11>")
	)
	(arc
		(start 139.78763 -231.201976)
		(mid 139.969881 -231.151592)
		(end 140.15339 -231.19715)
		(width 0.0889)
		(layer "In11.Cu")
		(net "M_L_CPU1_SA_DQ<11>")
	)
	(arc
		(start 142.607792 -231.201976)
		(mid 142.794736 -231.151687)
		(end 142.98168 -231.201976)
		(width 0.0889)
		(layer "In11.Cu")
		(net "M_L_CPU1_SA_DQ<11>")
	)
	(arc
		(start 138.281918 -231.201976)
		(mid 138.564874 -231.278153)
		(end 138.84783 -231.201976)
		(width 0.0889)
		(layer "In11.Cu")
		(net "M_L_CPU1_SA_DQ<11>")
	)
	(arc
		(start 143.921988 -231.201976)
		(mid 144.090348 -231.266535)
		(end 144.270476 -231.27462)
		(width 0.0889)
		(layer "In11.Cu")
		(net "M_L_CPU1_SA_DQ<11>")
	)
	(arc
		(start 142.98168 -231.201976)
		(mid 143.264636 -231.278153)
		(end 143.547592 -231.201976)
		(width 0.0889)
		(layer "In11.Cu")
		(net "M_L_CPU1_SA_DQ<11>")
	)
	(arc
		(start 141.67612 -231.19715)
		(mid 141.859628 -231.151625)
		(end 142.04188 -231.201976)
		(width 0.0889)
		(layer "In11.Cu")
		(net "M_L_CPU1_SA_DQ<11>")
	)
	(arc
		(start 137.963148 -231.175814)
		(mid 138.12548 -231.15298)
		(end 138.281918 -231.201976)
		(width 0.0889)
		(layer "In11.Cu")
		(net "M_L_CPU1_SA_DQ<11>")
	)
	(segment
		(start 139.037822 -230.980234)
		(end 139.504674 -230.71455)
		(width 0.10668)
		(layer "F.Cu")
		(net "M_L_CPU1_SA_DQ<10>")
	)
	(segment
		(start 146.47545 -227.672646)
		(end 147.26539 -226.882706)
		(width 0.0889)
		(layer "In11.Cu")
		(net "M_L_CPU1_SA_DQ<10>")
	)
	(segment
		(start 173.619668 -207.960468)
		(end 174.469552 -207.110584)
		(width 0.14478)
		(layer "In11.Cu")
		(net "M_L_CPU1_SA_DQ<10>")
	)
	(segment
		(start 142.503398 -230.387144)
		(end 142.51178 -230.39197)
		(width 0.0889)
		(layer "In11.Cu")
		(net "M_L_CPU1_SA_DQ<10>")
	)
	(segment
		(start 170.29176 -207.11033)
		(end 171.141898 -207.960468)
		(width 0.14478)
		(layer "In11.Cu")
		(net "M_L_CPU1_SA_DQ<10>")
	)
	(segment
		(start 150.464266 -223.437704)
		(end 150.464266 -221.392242)
		(width 0.14478)
		(layer "In11.Cu")
		(net "M_L_CPU1_SA_DQ<10>")
	)
	(segment
		(start 156.413708 -215.4428)
		(end 156.413708 -215.212168)
		(width 0.14478)
		(layer "In11.Cu")
		(net "M_L_CPU1_SA_DQ<10>")
	)
	(segment
		(start 192.846452 -207.110584)
		(end 193.696336 -207.960468)
		(width 0.14478)
		(layer "In11.Cu")
		(net "M_L_CPU1_SA_DQ<10>")
	)
	(segment
		(start 156.139134 -214.707724)
		(end 156.302456 -214.544402)
		(width 0.14478)
		(layer "In11.Cu")
		(net "M_L_CPU1_SA_DQ<10>")
	)
	(segment
		(start 157.201108 -214.6554)
		(end 157.201108 -214.424768)
		(width 0.14478)
		(layer "In11.Cu")
		(net "M_L_CPU1_SA_DQ<10>")
	)
	(segment
		(start 157.988508 -213.868)
		(end 157.988508 -213.637368)
		(width 0.14478)
		(layer "In11.Cu")
		(net "M_L_CPU1_SA_DQ<10>")
	)
	(segment
		(start 139.504674 -230.71455)
		(end 139.35075 -230.44912)
		(width 0.0889)
		(layer "In11.Cu")
		(net "M_L_CPU1_SA_DQ<10>")
	)
	(segment
		(start 156.139388 -214.937848)
		(end 156.139134 -214.707724)
		(width 0.14478)
		(layer "In11.Cu")
		(net "M_L_CPU1_SA_DQ<10>")
	)
	(segment
		(start 185.250836 -207.110584)
		(end 186.10072 -207.960468)
		(width 0.14478)
		(layer "In11.Cu")
		(net "M_L_CPU1_SA_DQ<10>")
	)
	(segment
		(start 139.35075 -230.44912)
		(end 139.373102 -230.365808)
		(width 0.0889)
		(layer "In11.Cu")
		(net "M_L_CPU1_SA_DQ<10>")
	)
	(segment
		(start 156.926534 -213.920324)
		(end 157.089856 -213.757002)
		(width 0.14478)
		(layer "In11.Cu")
		(net "M_L_CPU1_SA_DQ<10>")
	)
	(segment
		(start 156.302456 -214.544402)
		(end 156.533088 -214.544402)
		(width 0.14478)
		(layer "In11.Cu")
		(net "M_L_CPU1_SA_DQ<10>")
	)
	(segment
		(start 156.926788 -214.150448)
		(end 156.926534 -213.920324)
		(width 0.14478)
		(layer "In11.Cu")
		(net "M_L_CPU1_SA_DQ<10>")
	)
	(segment
		(start 157.82544 -214.031068)
		(end 157.988508 -213.868)
		(width 0.14478)
		(layer "In11.Cu")
		(net "M_L_CPU1_SA_DQ<10>")
	)
	(segment
		(start 145.72869 -228.269546)
		(end 146.32559 -227.672646)
		(width 0.0889)
		(layer "In11.Cu")
		(net "M_L_CPU1_SA_DQ<10>")
	)
	(segment
		(start 171.141898 -207.960468)
		(end 173.619668 -207.960468)
		(width 0.14478)
		(layer "In11.Cu")
		(net "M_L_CPU1_SA_DQ<10>")
	)
	(segment
		(start 143.077692 -230.39197)
		(end 143.086074 -230.387144)
		(width 0.0889)
		(layer "In11.Cu")
		(net "M_L_CPU1_SA_DQ<10>")
	)
	(segment
		(start 158.501334 -212.345524)
		(end 158.664656 -212.182202)
		(width 0.14478)
		(layer "In11.Cu")
		(net "M_L_CPU1_SA_DQ<10>")
	)
	(segment
		(start 178.82235 -207.960468)
		(end 180.987192 -207.960468)
		(width 0.14478)
		(layer "In11.Cu")
		(net "M_L_CPU1_SA_DQ<10>")
	)
	(segment
		(start 147.869656 -226.032314)
		(end 150.464266 -223.437704)
		(width 0.14478)
		(layer "In11.Cu")
		(net "M_L_CPU1_SA_DQ<10>")
	)
	(segment
		(start 140.257784 -230.39197)
		(end 140.266166 -230.387144)
		(width 0.0889)
		(layer "In11.Cu")
		(net "M_L_CPU1_SA_DQ<10>")
	)
	(segment
		(start 143.99895 -230.402384)
		(end 144.016984 -230.39197)
		(width 0.0889)
		(layer "In11.Cu")
		(net "M_L_CPU1_SA_DQ<10>")
	)
	(segment
		(start 201.723244 -207.110584)
		(end 202.147932 -207.535272)
		(width 0.14478)
		(layer "In11.Cu")
		(net "M_L_CPU1_SA_DQ<10>")
	)
	(segment
		(start 144.203674 -230.341678)
		(end 144.690338 -230.341678)
		(width 0.0889)
		(layer "In11.Cu")
		(net "M_L_CPU1_SA_DQ<10>")
	)
	(segment
		(start 158.775908 -212.849968)
		(end 158.501588 -212.575648)
		(width 0.14478)
		(layer "In11.Cu")
		(net "M_L_CPU1_SA_DQ<10>")
	)
	(segment
		(start 166.855902 -207.11033)
		(end 170.29176 -207.11033)
		(width 0.14478)
		(layer "In11.Cu")
		(net "M_L_CPU1_SA_DQ<10>")
	)
	(segment
		(start 156.413708 -215.212168)
		(end 156.139388 -214.937848)
		(width 0.14478)
		(layer "In11.Cu")
		(net "M_L_CPU1_SA_DQ<10>")
	)
	(segment
		(start 157.320488 -213.757002)
		(end 157.594808 -214.031322)
		(width 0.14478)
		(layer "In11.Cu")
		(net "M_L_CPU1_SA_DQ<10>")
	)
	(segment
		(start 186.10072 -207.960468)
		(end 188.673232 -207.960468)
		(width 0.14478)
		(layer "In11.Cu")
		(net "M_L_CPU1_SA_DQ<10>")
	)
	(segment
		(start 157.713934 -213.132924)
		(end 157.877256 -212.969602)
		(width 0.14478)
		(layer "In11.Cu")
		(net "M_L_CPU1_SA_DQ<10>")
	)
	(segment
		(start 158.775908 -213.0806)
		(end 158.775908 -212.849968)
		(width 0.14478)
		(layer "In11.Cu")
		(net "M_L_CPU1_SA_DQ<10>")
	)
	(segment
		(start 162.869372 -207.960468)
		(end 166.005764 -207.960468)
		(width 0.14478)
		(layer "In11.Cu")
		(net "M_L_CPU1_SA_DQ<10>")
	)
	(segment
		(start 147.26539 -226.63658)
		(end 147.869656 -226.032314)
		(width 0.0889)
		(layer "In11.Cu")
		(net "M_L_CPU1_SA_DQ<10>")
	)
	(segment
		(start 158.61284 -213.243668)
		(end 158.775908 -213.0806)
		(width 0.14478)
		(layer "In11.Cu")
		(net "M_L_CPU1_SA_DQ<10>")
	)
	(segment
		(start 146.32559 -227.672646)
		(end 146.47545 -227.672646)
		(width 0.0889)
		(layer "In11.Cu")
		(net "M_L_CPU1_SA_DQ<10>")
	)
	(segment
		(start 196.810884 -207.110584)
		(end 201.723244 -207.110584)
		(width 0.14478)
		(layer "In11.Cu")
		(net "M_L_CPU1_SA_DQ<10>")
	)
	(segment
		(start 158.664656 -212.182202)
		(end 158.895288 -212.182202)
		(width 0.14478)
		(layer "In11.Cu")
		(net "M_L_CPU1_SA_DQ<10>")
	)
	(segment
		(start 193.696336 -207.960468)
		(end 195.961 -207.960468)
		(width 0.14478)
		(layer "In11.Cu")
		(net "M_L_CPU1_SA_DQ<10>")
	)
	(segment
		(start 150.464266 -221.392242)
		(end 156.413708 -215.4428)
		(width 0.14478)
		(layer "In11.Cu")
		(net "M_L_CPU1_SA_DQ<10>")
	)
	(segment
		(start 189.523116 -207.110584)
		(end 192.846452 -207.110584)
		(width 0.14478)
		(layer "In11.Cu")
		(net "M_L_CPU1_SA_DQ<10>")
	)
	(segment
		(start 157.877256 -212.969602)
		(end 158.107888 -212.969602)
		(width 0.14478)
		(layer "In11.Cu")
		(net "M_L_CPU1_SA_DQ<10>")
	)
	(segment
		(start 144.690338 -230.341678)
		(end 145.72869 -229.303326)
		(width 0.0889)
		(layer "In11.Cu")
		(net "M_L_CPU1_SA_DQ<10>")
	)
	(segment
		(start 195.961 -207.960468)
		(end 196.810884 -207.110584)
		(width 0.14478)
		(layer "In11.Cu")
		(net "M_L_CPU1_SA_DQ<10>")
	)
	(segment
		(start 157.594808 -214.031322)
		(end 157.82544 -214.031068)
		(width 0.14478)
		(layer "In11.Cu")
		(net "M_L_CPU1_SA_DQ<10>")
	)
	(segment
		(start 166.005764 -207.960468)
		(end 166.855902 -207.11033)
		(width 0.14478)
		(layer "In11.Cu")
		(net "M_L_CPU1_SA_DQ<10>")
	)
	(segment
		(start 159.40024 -212.456268)
		(end 159.644334 -212.212174)
		(width 0.14478)
		(layer "In11.Cu")
		(net "M_L_CPU1_SA_DQ<10>")
	)
	(segment
		(start 159.169608 -212.456522)
		(end 159.40024 -212.456268)
		(width 0.14478)
		(layer "In11.Cu")
		(net "M_L_CPU1_SA_DQ<10>")
	)
	(segment
		(start 188.673232 -207.960468)
		(end 189.523116 -207.110584)
		(width 0.14478)
		(layer "In11.Cu")
		(net "M_L_CPU1_SA_DQ<10>")
	)
	(segment
		(start 147.26539 -226.882706)
		(end 147.26539 -226.63658)
		(width 0.0889)
		(layer "In11.Cu")
		(net "M_L_CPU1_SA_DQ<10>")
	)
	(segment
		(start 157.03804 -214.818468)
		(end 157.201108 -214.6554)
		(width 0.14478)
		(layer "In11.Cu")
		(net "M_L_CPU1_SA_DQ<10>")
	)
	(segment
		(start 156.533088 -214.544402)
		(end 156.807408 -214.818722)
		(width 0.14478)
		(layer "In11.Cu")
		(net "M_L_CPU1_SA_DQ<10>")
	)
	(segment
		(start 180.987192 -207.960468)
		(end 181.837076 -207.110584)
		(width 0.14478)
		(layer "In11.Cu")
		(net "M_L_CPU1_SA_DQ<10>")
	)
	(segment
		(start 159.644334 -212.212174)
		(end 159.644334 -211.185506)
		(width 0.14478)
		(layer "In11.Cu")
		(net "M_L_CPU1_SA_DQ<10>")
	)
	(segment
		(start 158.501588 -212.575648)
		(end 158.501334 -212.345524)
		(width 0.14478)
		(layer "In11.Cu")
		(net "M_L_CPU1_SA_DQ<10>")
	)
	(segment
		(start 156.807408 -214.818722)
		(end 157.03804 -214.818468)
		(width 0.14478)
		(layer "In11.Cu")
		(net "M_L_CPU1_SA_DQ<10>")
	)
	(segment
		(start 158.895288 -212.182202)
		(end 159.169608 -212.456522)
		(width 0.14478)
		(layer "In11.Cu")
		(net "M_L_CPU1_SA_DQ<10>")
	)
	(segment
		(start 177.972466 -207.110584)
		(end 178.82235 -207.960468)
		(width 0.14478)
		(layer "In11.Cu")
		(net "M_L_CPU1_SA_DQ<10>")
	)
	(segment
		(start 145.72869 -229.303326)
		(end 145.72869 -228.269546)
		(width 0.0889)
		(layer "In11.Cu")
		(net "M_L_CPU1_SA_DQ<10>")
	)
	(segment
		(start 157.089856 -213.757002)
		(end 157.320488 -213.757002)
		(width 0.14478)
		(layer "In11.Cu")
		(net "M_L_CPU1_SA_DQ<10>")
	)
	(segment
		(start 158.107888 -212.969602)
		(end 158.382208 -213.243922)
		(width 0.14478)
		(layer "In11.Cu")
		(net "M_L_CPU1_SA_DQ<10>")
	)
	(segment
		(start 157.201108 -214.424768)
		(end 156.926788 -214.150448)
		(width 0.14478)
		(layer "In11.Cu")
		(net "M_L_CPU1_SA_DQ<10>")
	)
	(segment
		(start 157.988508 -213.637368)
		(end 157.714188 -213.363048)
		(width 0.14478)
		(layer "In11.Cu")
		(net "M_L_CPU1_SA_DQ<10>")
	)
	(segment
		(start 157.714188 -213.363048)
		(end 157.713934 -213.132924)
		(width 0.14478)
		(layer "In11.Cu")
		(net "M_L_CPU1_SA_DQ<10>")
	)
	(segment
		(start 158.382208 -213.243922)
		(end 158.61284 -213.243668)
		(width 0.14478)
		(layer "In11.Cu")
		(net "M_L_CPU1_SA_DQ<10>")
	)
	(segment
		(start 181.837076 -207.110584)
		(end 185.250836 -207.110584)
		(width 0.14478)
		(layer "In11.Cu")
		(net "M_L_CPU1_SA_DQ<10>")
	)
	(segment
		(start 159.644334 -211.185506)
		(end 162.869372 -207.960468)
		(width 0.14478)
		(layer "In11.Cu")
		(net "M_L_CPU1_SA_DQ<10>")
	)
	(segment
		(start 174.469552 -207.110584)
		(end 177.972466 -207.110584)
		(width 0.14478)
		(layer "In11.Cu")
		(net "M_L_CPU1_SA_DQ<10>")
	)
	(arc
		(start 139.691872 -230.39197)
		(mid 139.974828 -230.468113)
		(end 140.257784 -230.39197)
		(width 0.0889)
		(layer "In11.Cu")
		(net "M_L_CPU1_SA_DQ<10>")
	)
	(arc
		(start 141.197838 -230.39197)
		(mid 141.384782 -230.341715)
		(end 141.571726 -230.39197)
		(width 0.0889)
		(layer "In11.Cu")
		(net "M_L_CPU1_SA_DQ<10>")
	)
	(arc
		(start 141.571726 -230.39197)
		(mid 141.854682 -230.468113)
		(end 142.137638 -230.39197)
		(width 0.0889)
		(layer "In11.Cu")
		(net "M_L_CPU1_SA_DQ<10>")
	)
	(arc
		(start 140.266166 -230.387144)
		(mid 140.449674 -230.34165)
		(end 140.631926 -230.39197)
		(width 0.0889)
		(layer "In11.Cu")
		(net "M_L_CPU1_SA_DQ<10>")
	)
	(arc
		(start 139.373102 -230.365808)
		(mid 139.535434 -230.34299)
		(end 139.691872 -230.39197)
		(width 0.0889)
		(layer "In11.Cu")
		(net "M_L_CPU1_SA_DQ<10>")
	)
	(arc
		(start 142.137638 -230.39197)
		(mid 142.319889 -230.34162)
		(end 142.503398 -230.387144)
		(width 0.0889)
		(layer "In11.Cu")
		(net "M_L_CPU1_SA_DQ<10>")
	)
	(arc
		(start 143.086074 -230.387144)
		(mid 143.269582 -230.34165)
		(end 143.451834 -230.39197)
		(width 0.0889)
		(layer "In11.Cu")
		(net "M_L_CPU1_SA_DQ<10>")
	)
	(arc
		(start 142.51178 -230.39197)
		(mid 142.794736 -230.468113)
		(end 143.077692 -230.39197)
		(width 0.0889)
		(layer "In11.Cu")
		(net "M_L_CPU1_SA_DQ<10>")
	)
	(arc
		(start 140.631926 -230.39197)
		(mid 140.914882 -230.468113)
		(end 141.197838 -230.39197)
		(width 0.0889)
		(layer "In11.Cu")
		(net "M_L_CPU1_SA_DQ<10>")
	)
	(arc
		(start 143.451834 -230.39197)
		(mid 143.724046 -230.46801)
		(end 143.99895 -230.402384)
		(width 0.0889)
		(layer "In11.Cu")
		(net "M_L_CPU1_SA_DQ<10>")
	)
	(arc
		(start 144.016984 -230.39197)
		(mid 144.107019 -230.354556)
		(end 144.203674 -230.341678)
		(width 0.0889)
		(layer "In11.Cu")
		(net "M_L_CPU1_SA_DQ<10>")
	)
	(segment
		(start 138.567922 -225.310446)
		(end 139.034774 -225.044508)
		(width 0.10668)
		(layer "F.Cu")
		(net "M_L_CPU1_SA_DQ<0>")
	)
	(segment
		(start 142.472664 -224.579942)
		(end 142.51178 -224.557082)
		(width 0.0889)
		(layer "In11.Cu")
		(net "M_L_CPU1_SA_DQ<0>")
	)
	(segment
		(start 193.5861 -197.760336)
		(end 196.086984 -197.760336)
		(width 0.14478)
		(layer "In11.Cu")
		(net "M_L_CPU1_SA_DQ<0>")
	)
	(segment
		(start 151.809196 -208.198974)
		(end 162.247834 -197.760336)
		(width 0.14478)
		(layer "In11.Cu")
		(net "M_L_CPU1_SA_DQ<0>")
	)
	(segment
		(start 196.936868 -196.910452)
		(end 205.823058 -196.910452)
		(width 0.14478)
		(layer "In11.Cu")
		(net "M_L_CPU1_SA_DQ<0>")
	)
	(segment
		(start 151.809196 -209.067654)
		(end 151.809196 -208.198974)
		(width 0.14478)
		(layer "In11.Cu")
		(net "M_L_CPU1_SA_DQ<0>")
	)
	(segment
		(start 186.10072 -197.760336)
		(end 188.673232 -197.760336)
		(width 0.14478)
		(layer "In11.Cu")
		(net "M_L_CPU1_SA_DQ<0>")
	)
	(segment
		(start 174.448724 -196.910452)
		(end 177.972466 -196.910452)
		(width 0.14478)
		(layer "In11.Cu")
		(net "M_L_CPU1_SA_DQ<0>")
	)
	(segment
		(start 185.250836 -196.910452)
		(end 186.10072 -197.760336)
		(width 0.14478)
		(layer "In11.Cu")
		(net "M_L_CPU1_SA_DQ<0>")
	)
	(segment
		(start 141.093444 -225.371914)
		(end 141.101826 -225.367088)
		(width 0.0889)
		(layer "In11.Cu")
		(net "M_L_CPU1_SA_DQ<0>")
	)
	(segment
		(start 205.823058 -196.910452)
		(end 206.248 -197.335394)
		(width 0.14478)
		(layer "In11.Cu")
		(net "M_L_CPU1_SA_DQ<0>")
	)
	(segment
		(start 171.722288 -197.760336)
		(end 173.59884 -197.760336)
		(width 0.14478)
		(layer "In11.Cu")
		(net "M_L_CPU1_SA_DQ<0>")
	)
	(segment
		(start 173.59884 -197.760336)
		(end 174.448724 -196.910452)
		(width 0.14478)
		(layer "In11.Cu")
		(net "M_L_CPU1_SA_DQ<0>")
	)
	(segment
		(start 178.82235 -197.760336)
		(end 180.997352 -197.760336)
		(width 0.14478)
		(layer "In11.Cu")
		(net "M_L_CPU1_SA_DQ<0>")
	)
	(segment
		(start 143.802608 -222.221044)
		(end 143.880586 -222.143066)
		(width 0.0889)
		(layer "In11.Cu")
		(net "M_L_CPU1_SA_DQ<0>")
	)
	(segment
		(start 177.972466 -196.910452)
		(end 178.82235 -197.760336)
		(width 0.14478)
		(layer "In11.Cu")
		(net "M_L_CPU1_SA_DQ<0>")
	)
	(segment
		(start 162.247834 -197.760336)
		(end 165.820598 -197.760336)
		(width 0.14478)
		(layer "In11.Cu")
		(net "M_L_CPU1_SA_DQ<0>")
	)
	(segment
		(start 142.945358 -223.768158)
		(end 142.98168 -223.747076)
		(width 0.0889)
		(layer "In11.Cu")
		(net "M_L_CPU1_SA_DQ<0>")
	)
	(segment
		(start 192.736216 -196.910452)
		(end 193.5861 -197.760336)
		(width 0.14478)
		(layer "In11.Cu")
		(net "M_L_CPU1_SA_DQ<0>")
	)
	(segment
		(start 196.086984 -197.760336)
		(end 196.936868 -196.910452)
		(width 0.14478)
		(layer "In11.Cu")
		(net "M_L_CPU1_SA_DQ<0>")
	)
	(segment
		(start 181.847236 -196.910452)
		(end 185.250836 -196.910452)
		(width 0.14478)
		(layer "In11.Cu")
		(net "M_L_CPU1_SA_DQ<0>")
	)
	(segment
		(start 142.04188 -225.367088)
		(end 142.07236 -225.349308)
		(width 0.0889)
		(layer "In11.Cu")
		(net "M_L_CPU1_SA_DQ<0>")
	)
	(segment
		(start 139.188698 -225.309938)
		(end 139.28471 -225.335338)
		(width 0.0889)
		(layer "In11.Cu")
		(net "M_L_CPU1_SA_DQ<0>")
	)
	(segment
		(start 144.06626 -221.156276)
		(end 144.06626 -216.81059)
		(width 0.14478)
		(layer "In11.Cu")
		(net "M_L_CPU1_SA_DQ<0>")
	)
	(segment
		(start 141.667738 -225.367088)
		(end 141.67612 -225.371914)
		(width 0.0889)
		(layer "In11.Cu")
		(net "M_L_CPU1_SA_DQ<0>")
	)
	(segment
		(start 142.51178 -224.557082)
		(end 142.54353 -224.538794)
		(width 0.0889)
		(layer "In11.Cu")
		(net "M_L_CPU1_SA_DQ<0>")
	)
	(segment
		(start 142.98168 -223.747076)
		(end 143.01343 -223.728788)
		(width 0.0889)
		(layer "In11.Cu")
		(net "M_L_CPU1_SA_DQ<0>")
	)
	(segment
		(start 139.034774 -225.044508)
		(end 139.188698 -225.309938)
		(width 0.0889)
		(layer "In11.Cu")
		(net "M_L_CPU1_SA_DQ<0>")
	)
	(segment
		(start 143.412718 -222.95993)
		(end 143.451834 -222.93707)
		(width 0.0889)
		(layer "In11.Cu")
		(net "M_L_CPU1_SA_DQ<0>")
	)
	(segment
		(start 144.10309 -221.804484)
		(end 144.10309 -221.543626)
		(width 0.0889)
		(layer "In11.Cu")
		(net "M_L_CPU1_SA_DQ<0>")
	)
	(segment
		(start 165.820598 -197.760336)
		(end 166.670482 -196.910452)
		(width 0.14478)
		(layer "In11.Cu")
		(net "M_L_CPU1_SA_DQ<0>")
	)
	(segment
		(start 144.06626 -221.506796)
		(end 144.06626 -221.156276)
		(width 0.0889)
		(layer "In11.Cu")
		(net "M_L_CPU1_SA_DQ<0>")
	)
	(segment
		(start 166.670482 -196.910452)
		(end 170.872404 -196.910452)
		(width 0.14478)
		(layer "In11.Cu")
		(net "M_L_CPU1_SA_DQ<0>")
	)
	(segment
		(start 180.997352 -197.760336)
		(end 181.847236 -196.910452)
		(width 0.14478)
		(layer "In11.Cu")
		(net "M_L_CPU1_SA_DQ<0>")
	)
	(segment
		(start 144.06626 -216.81059)
		(end 151.809196 -209.067654)
		(width 0.14478)
		(layer "In11.Cu")
		(net "M_L_CPU1_SA_DQ<0>")
	)
	(segment
		(start 170.872404 -196.910452)
		(end 171.722288 -197.760336)
		(width 0.14478)
		(layer "In11.Cu")
		(net "M_L_CPU1_SA_DQ<0>")
	)
	(segment
		(start 143.451834 -222.93707)
		(end 143.486886 -222.91675)
		(width 0.0889)
		(layer "In11.Cu")
		(net "M_L_CPU1_SA_DQ<0>")
	)
	(segment
		(start 189.523116 -196.910452)
		(end 192.736216 -196.910452)
		(width 0.14478)
		(layer "In11.Cu")
		(net "M_L_CPU1_SA_DQ<0>")
	)
	(segment
		(start 188.673232 -197.760336)
		(end 189.523116 -196.910452)
		(width 0.14478)
		(layer "In11.Cu")
		(net "M_L_CPU1_SA_DQ<0>")
	)
	(segment
		(start 140.15339 -225.371914)
		(end 140.161772 -225.367088)
		(width 0.0889)
		(layer "In11.Cu")
		(net "M_L_CPU1_SA_DQ<0>")
	)
	(segment
		(start 144.10309 -221.543626)
		(end 144.06626 -221.506796)
		(width 0.0889)
		(layer "In11.Cu")
		(net "M_L_CPU1_SA_DQ<0>")
	)
	(arc
		(start 139.78763 -225.367088)
		(mid 139.969881 -225.417438)
		(end 140.15339 -225.371914)
		(width 0.0889)
		(layer "In11.Cu")
		(net "M_L_CPU1_SA_DQ<0>")
	)
	(arc
		(start 141.101826 -225.367088)
		(mid 141.384782 -225.290911)
		(end 141.667738 -225.367088)
		(width 0.0889)
		(layer "In11.Cu")
		(net "M_L_CPU1_SA_DQ<0>")
	)
	(arc
		(start 141.67612 -225.371914)
		(mid 141.859628 -225.417408)
		(end 142.04188 -225.367088)
		(width 0.0889)
		(layer "In11.Cu")
		(net "M_L_CPU1_SA_DQ<0>")
	)
	(arc
		(start 143.639794 -222.61449)
		(mid 143.682054 -222.401565)
		(end 143.802608 -222.221044)
		(width 0.0889)
		(layer "In11.Cu")
		(net "M_L_CPU1_SA_DQ<0>")
	)
	(arc
		(start 139.28471 -225.335338)
		(mid 139.539918 -225.291861)
		(end 139.78763 -225.367088)
		(width 0.0889)
		(layer "In11.Cu")
		(net "M_L_CPU1_SA_DQ<0>")
	)
	(arc
		(start 143.880586 -222.143066)
		(mid 144.042507 -222.007067)
		(end 144.10309 -221.804484)
		(width 0.0889)
		(layer "In11.Cu")
		(net "M_L_CPU1_SA_DQ<0>")
	)
	(arc
		(start 142.07236 -225.349308)
		(mid 142.187787 -225.215932)
		(end 142.229332 -225.044508)
		(width 0.0889)
		(layer "In11.Cu")
		(net "M_L_CPU1_SA_DQ<0>")
	)
	(arc
		(start 143.486886 -222.91675)
		(mid 143.599404 -222.783862)
		(end 143.639794 -222.61449)
		(width 0.0889)
		(layer "In11.Cu")
		(net "M_L_CPU1_SA_DQ<0>")
	)
	(arc
		(start 142.54353 -224.538794)
		(mid 142.658206 -224.40546)
		(end 142.699486 -224.234502)
		(width 0.0889)
		(layer "In11.Cu")
		(net "M_L_CPU1_SA_DQ<0>")
	)
	(arc
		(start 142.229332 -225.044508)
		(mid 142.293847 -224.782289)
		(end 142.472664 -224.579942)
		(width 0.0889)
		(layer "In11.Cu")
		(net "M_L_CPU1_SA_DQ<0>")
	)
	(arc
		(start 140.161772 -225.367088)
		(mid 140.444728 -225.290911)
		(end 140.727684 -225.367088)
		(width 0.0889)
		(layer "In11.Cu")
		(net "M_L_CPU1_SA_DQ<0>")
	)
	(arc
		(start 143.169386 -223.424496)
		(mid 143.233901 -223.162277)
		(end 143.412718 -222.95993)
		(width 0.0889)
		(layer "In11.Cu")
		(net "M_L_CPU1_SA_DQ<0>")
	)
	(arc
		(start 142.699486 -224.234502)
		(mid 142.764722 -223.970911)
		(end 142.945358 -223.768158)
		(width 0.0889)
		(layer "In11.Cu")
		(net "M_L_CPU1_SA_DQ<0>")
	)
	(arc
		(start 143.01343 -223.728788)
		(mid 143.128106 -223.595454)
		(end 143.169386 -223.424496)
		(width 0.0889)
		(layer "In11.Cu")
		(net "M_L_CPU1_SA_DQ<0>")
	)
	(arc
		(start 140.727684 -225.367088)
		(mid 140.909935 -225.417438)
		(end 141.093444 -225.371914)
		(width 0.0889)
		(layer "In11.Cu")
		(net "M_L_CPU1_SA_DQ<0>")
	)
	(segment
		(start 137.157968 -252.04039)
		(end 137.62482 -251.774452)
		(width 0.10668)
		(layer "F.Cu")
		(net "M_L_CPU1_SA_CS_N<1>")
	)
	(segment
		(start 140.628624 -252.091444)
		(end 140.639292 -252.085348)
		(width 0.0889)
		(layer "In11.Cu")
		(net "M_L_CPU1_SA_CS_N<1>")
	)
	(segment
		(start 199.53351 -247.060466)
		(end 199.67829 -246.915686)
		(width 0.14478)
		(layer "In11.Cu")
		(net "M_L_CPU1_SA_CS_N<1>")
	)
	(segment
		(start 199.82307 -246.699786)
		(end 200.084944 -246.699786)
		(width 0.14478)
		(layer "In11.Cu")
		(net "M_L_CPU1_SA_CS_N<1>")
	)
	(segment
		(start 200.781158 -247.276366)
		(end 200.781158 -246.844566)
		(width 0.14478)
		(layer "In11.Cu")
		(net "M_L_CPU1_SA_CS_N<1>")
	)
	(segment
		(start 201.187812 -246.699786)
		(end 201.332592 -246.844566)
		(width 0.14478)
		(layer "In11.Cu")
		(net "M_L_CPU1_SA_CS_N<1>")
	)
	(segment
		(start 200.084944 -246.699786)
		(end 200.229724 -246.844566)
		(width 0.14478)
		(layer "In11.Cu")
		(net "M_L_CPU1_SA_CS_N<1>")
	)
	(segment
		(start 199.67829 -246.844566)
		(end 199.82307 -246.699786)
		(width 0.14478)
		(layer "In11.Cu")
		(net "M_L_CPU1_SA_CS_N<1>")
	)
	(segment
		(start 146.085052 -252.141228)
		(end 146.580352 -252.141228)
		(width 0.0889)
		(layer "In11.Cu")
		(net "M_L_CPU1_SA_CS_N<1>")
	)
	(segment
		(start 197.67296 -247.060466)
		(end 199.53351 -247.060466)
		(width 0.14478)
		(layer "In11.Cu")
		(net "M_L_CPU1_SA_CS_N<1>")
	)
	(segment
		(start 137.62482 -251.774452)
		(end 137.773664 -252.030738)
		(width 0.0889)
		(layer "In11.Cu")
		(net "M_L_CPU1_SA_CS_N<1>")
	)
	(segment
		(start 147.784312 -252.914658)
		(end 149.477476 -252.914658)
		(width 0.14478)
		(layer "In11.Cu")
		(net "M_L_CPU1_SA_CS_N<1>")
	)
	(segment
		(start 201.722736 -247.060466)
		(end 202.147932 -246.63527)
		(width 0.14478)
		(layer "In11.Cu")
		(net "M_L_CPU1_SA_CS_N<1>")
	)
	(segment
		(start 195.972938 -248.760488)
		(end 197.67296 -247.060466)
		(width 0.14478)
		(layer "In11.Cu")
		(net "M_L_CPU1_SA_CS_N<1>")
	)
	(segment
		(start 144.380966 -252.09627)
		(end 144.389094 -252.091444)
		(width 0.0889)
		(layer "In11.Cu")
		(net "M_L_CPU1_SA_CS_N<1>")
	)
	(segment
		(start 201.477372 -247.060466)
		(end 201.722736 -247.060466)
		(width 0.14478)
		(layer "In11.Cu")
		(net "M_L_CPU1_SA_CS_N<1>")
	)
	(segment
		(start 200.925938 -246.699786)
		(end 201.187812 -246.699786)
		(width 0.14478)
		(layer "In11.Cu")
		(net "M_L_CPU1_SA_CS_N<1>")
	)
	(segment
		(start 164.2618 -248.760488)
		(end 195.972938 -248.760488)
		(width 0.14478)
		(layer "In11.Cu")
		(net "M_L_CPU1_SA_CS_N<1>")
	)
	(segment
		(start 141.568678 -252.091444)
		(end 141.579346 -252.085348)
		(width 0.0889)
		(layer "In11.Cu")
		(net "M_L_CPU1_SA_CS_N<1>")
	)
	(segment
		(start 200.229724 -247.276366)
		(end 200.374504 -247.421146)
		(width 0.14478)
		(layer "In11.Cu")
		(net "M_L_CPU1_SA_CS_N<1>")
	)
	(segment
		(start 140.250164 -252.085348)
		(end 140.260832 -252.091444)
		(width 0.0889)
		(layer "In11.Cu")
		(net "M_L_CPU1_SA_CS_N<1>")
	)
	(segment
		(start 150.876 -251.516134)
		(end 161.506154 -251.516134)
		(width 0.14478)
		(layer "In11.Cu")
		(net "M_L_CPU1_SA_CS_N<1>")
	)
	(segment
		(start 199.67829 -246.915686)
		(end 199.67829 -246.844566)
		(width 0.14478)
		(layer "In11.Cu")
		(net "M_L_CPU1_SA_CS_N<1>")
	)
	(segment
		(start 137.773664 -252.030738)
		(end 137.876026 -252.057916)
		(width 0.0889)
		(layer "In11.Cu")
		(net "M_L_CPU1_SA_CS_N<1>")
	)
	(segment
		(start 200.374504 -247.421146)
		(end 200.636378 -247.421146)
		(width 0.14478)
		(layer "In11.Cu")
		(net "M_L_CPU1_SA_CS_N<1>")
	)
	(segment
		(start 200.229724 -246.844566)
		(end 200.229724 -247.276366)
		(width 0.14478)
		(layer "In11.Cu")
		(net "M_L_CPU1_SA_CS_N<1>")
	)
	(segment
		(start 144.961102 -252.091444)
		(end 144.972786 -252.098048)
		(width 0.0889)
		(layer "In11.Cu")
		(net "M_L_CPU1_SA_CS_N<1>")
	)
	(segment
		(start 149.477476 -252.914658)
		(end 150.876 -251.516134)
		(width 0.14478)
		(layer "In11.Cu")
		(net "M_L_CPU1_SA_CS_N<1>")
	)
	(segment
		(start 146.580352 -252.141228)
		(end 147.353782 -252.914658)
		(width 0.0889)
		(layer "In11.Cu")
		(net "M_L_CPU1_SA_CS_N<1>")
	)
	(segment
		(start 200.636378 -247.421146)
		(end 200.781158 -247.276366)
		(width 0.14478)
		(layer "In11.Cu")
		(net "M_L_CPU1_SA_CS_N<1>")
	)
	(segment
		(start 201.332592 -246.915686)
		(end 201.477372 -247.060466)
		(width 0.14478)
		(layer "In11.Cu")
		(net "M_L_CPU1_SA_CS_N<1>")
	)
	(segment
		(start 201.332592 -246.844566)
		(end 201.332592 -246.915686)
		(width 0.14478)
		(layer "In11.Cu")
		(net "M_L_CPU1_SA_CS_N<1>")
	)
	(segment
		(start 147.353782 -252.914658)
		(end 147.784312 -252.914658)
		(width 0.0889)
		(layer "In11.Cu")
		(net "M_L_CPU1_SA_CS_N<1>")
	)
	(segment
		(start 161.506154 -251.516134)
		(end 164.2618 -248.760488)
		(width 0.14478)
		(layer "In11.Cu")
		(net "M_L_CPU1_SA_CS_N<1>")
	)
	(segment
		(start 200.781158 -246.844566)
		(end 200.925938 -246.699786)
		(width 0.14478)
		(layer "In11.Cu")
		(net "M_L_CPU1_SA_CS_N<1>")
	)
	(arc
		(start 143.08074 -252.091444)
		(mid 143.264636 -252.140924)
		(end 143.448532 -252.091444)
		(width 0.0889)
		(layer "In11.Cu")
		(net "M_L_CPU1_SA_CS_N<1>")
	)
	(arc
		(start 139.320778 -252.091444)
		(mid 139.504674 -252.140924)
		(end 139.68857 -252.091444)
		(width 0.0889)
		(layer "In11.Cu")
		(net "M_L_CPU1_SA_CS_N<1>")
	)
	(arc
		(start 140.260832 -252.091444)
		(mid 140.444728 -252.140924)
		(end 140.628624 -252.091444)
		(width 0.0889)
		(layer "In11.Cu")
		(net "M_L_CPU1_SA_CS_N<1>")
	)
	(arc
		(start 141.200886 -252.091444)
		(mid 141.384782 -252.140924)
		(end 141.568678 -252.091444)
		(width 0.0889)
		(layer "In11.Cu")
		(net "M_L_CPU1_SA_CS_N<1>")
	)
	(arc
		(start 142.508732 -252.091444)
		(mid 142.794736 -252.014492)
		(end 143.08074 -252.091444)
		(width 0.0889)
		(layer "In11.Cu")
		(net "M_L_CPU1_SA_CS_N<1>")
	)
	(arc
		(start 139.68857 -252.091444)
		(mid 139.968574 -252.014399)
		(end 140.250164 -252.085348)
		(width 0.0889)
		(layer "In11.Cu")
		(net "M_L_CPU1_SA_CS_N<1>")
	)
	(arc
		(start 144.389094 -252.091444)
		(mid 144.675098 -252.014492)
		(end 144.961102 -252.091444)
		(width 0.0889)
		(layer "In11.Cu")
		(net "M_L_CPU1_SA_CS_N<1>")
	)
	(arc
		(start 141.579346 -252.085348)
		(mid 141.860935 -252.014474)
		(end 142.14094 -252.091444)
		(width 0.0889)
		(layer "In11.Cu")
		(net "M_L_CPU1_SA_CS_N<1>")
	)
	(arc
		(start 137.876026 -252.057916)
		(mid 138.132435 -252.015555)
		(end 138.380978 -252.091444)
		(width 0.0889)
		(layer "In11.Cu")
		(net "M_L_CPU1_SA_CS_N<1>")
	)
	(arc
		(start 142.14094 -252.091444)
		(mid 142.324836 -252.140924)
		(end 142.508732 -252.091444)
		(width 0.0889)
		(layer "In11.Cu")
		(net "M_L_CPU1_SA_CS_N<1>")
	)
	(arc
		(start 144.021048 -252.091444)
		(mid 144.200363 -252.14102)
		(end 144.380966 -252.09627)
		(width 0.0889)
		(layer "In11.Cu")
		(net "M_L_CPU1_SA_CS_N<1>")
	)
	(arc
		(start 145.90141 -252.091444)
		(mid 145.98995 -252.128428)
		(end 146.085052 -252.141228)
		(width 0.0889)
		(layer "In11.Cu")
		(net "M_L_CPU1_SA_CS_N<1>")
	)
	(arc
		(start 140.639292 -252.085348)
		(mid 140.920881 -252.014474)
		(end 141.200886 -252.091444)
		(width 0.0889)
		(layer "In11.Cu")
		(net "M_L_CPU1_SA_CS_N<1>")
	)
	(arc
		(start 138.380978 -252.091444)
		(mid 138.564874 -252.140924)
		(end 138.74877 -252.091444)
		(width 0.0889)
		(layer "In11.Cu")
		(net "M_L_CPU1_SA_CS_N<1>")
	)
	(arc
		(start 145.328894 -252.091444)
		(mid 145.615152 -252.014365)
		(end 145.90141 -252.091444)
		(width 0.0889)
		(layer "In11.Cu")
		(net "M_L_CPU1_SA_CS_N<1>")
	)
	(arc
		(start 143.448532 -252.091444)
		(mid 143.73479 -252.014365)
		(end 144.021048 -252.091444)
		(width 0.0889)
		(layer "In11.Cu")
		(net "M_L_CPU1_SA_CS_N<1>")
	)
	(arc
		(start 144.972786 -252.098048)
		(mid 145.151709 -252.140958)
		(end 145.328894 -252.091444)
		(width 0.0889)
		(layer "In11.Cu")
		(net "M_L_CPU1_SA_CS_N<1>")
	)
	(arc
		(start 138.74877 -252.091444)
		(mid 139.034774 -252.014492)
		(end 139.320778 -252.091444)
		(width 0.0889)
		(layer "In11.Cu")
		(net "M_L_CPU1_SA_CS_N<1>")
	)
	(segment
		(start 138.567922 -251.230384)
		(end 139.034774 -250.964446)
		(width 0.10668)
		(layer "F.Cu")
		(net "M_L_CPU1_SA_CS_N<0>")
	)
	(segment
		(start 142.600172 -251.275342)
		(end 142.61084 -251.281438)
		(width 0.0889)
		(layer "In11.Cu")
		(net "M_L_CPU1_SA_CS_N<0>")
	)
	(segment
		(start 143.918178 -251.281438)
		(end 143.941546 -251.267722)
		(width 0.0889)
		(layer "In11.Cu")
		(net "M_L_CPU1_SA_CS_N<0>")
	)
	(segment
		(start 139.034774 -250.964446)
		(end 139.183618 -251.220732)
		(width 0.0889)
		(layer "In11.Cu")
		(net "M_L_CPU1_SA_CS_N<0>")
	)
	(segment
		(start 145.613628 -251.330968)
		(end 146.166332 -251.330968)
		(width 0.0889)
		(layer "In11.Cu")
		(net "M_L_CPU1_SA_CS_N<0>")
	)
	(segment
		(start 140.158724 -251.281438)
		(end 140.169392 -251.275342)
		(width 0.0889)
		(layer "In11.Cu")
		(net "M_L_CPU1_SA_CS_N<0>")
	)
	(segment
		(start 149.288754 -252.459998)
		(end 150.687278 -251.061474)
		(width 0.14478)
		(layer "In11.Cu")
		(net "M_L_CPU1_SA_CS_N<0>")
	)
	(segment
		(start 147.295362 -252.459998)
		(end 147.818602 -252.459998)
		(width 0.0889)
		(layer "In11.Cu")
		(net "M_L_CPU1_SA_CS_N<0>")
	)
	(segment
		(start 205.823058 -246.210328)
		(end 206.248 -245.785386)
		(width 0.14478)
		(layer "In11.Cu")
		(net "M_L_CPU1_SA_CS_N<0>")
	)
	(segment
		(start 145.411698 -251.27077)
		(end 145.429986 -251.281438)
		(width 0.0889)
		(layer "In11.Cu")
		(net "M_L_CPU1_SA_CS_N<0>")
	)
	(segment
		(start 150.687278 -251.061474)
		(end 161.317686 -251.061474)
		(width 0.14478)
		(layer "In11.Cu")
		(net "M_L_CPU1_SA_CS_N<0>")
	)
	(segment
		(start 147.818602 -252.459998)
		(end 149.288754 -252.459998)
		(width 0.14478)
		(layer "In11.Cu")
		(net "M_L_CPU1_SA_CS_N<0>")
	)
	(segment
		(start 146.166332 -251.330968)
		(end 147.295362 -252.459998)
		(width 0.0889)
		(layer "In11.Cu")
		(net "M_L_CPU1_SA_CS_N<0>")
	)
	(segment
		(start 139.183618 -251.220732)
		(end 139.28598 -251.24791)
		(width 0.0889)
		(layer "In11.Cu")
		(net "M_L_CPU1_SA_CS_N<0>")
	)
	(segment
		(start 197.59803 -246.210328)
		(end 205.823058 -246.210328)
		(width 0.14478)
		(layer "In11.Cu")
		(net "M_L_CPU1_SA_CS_N<0>")
	)
	(segment
		(start 143.906494 -251.288042)
		(end 143.918178 -251.281438)
		(width 0.0889)
		(layer "In11.Cu")
		(net "M_L_CPU1_SA_CS_N<0>")
	)
	(segment
		(start 195.898008 -247.91035)
		(end 197.59803 -246.210328)
		(width 0.14478)
		(layer "In11.Cu")
		(net "M_L_CPU1_SA_CS_N<0>")
	)
	(segment
		(start 144.847056 -251.288296)
		(end 144.85874 -251.281438)
		(width 0.0889)
		(layer "In11.Cu")
		(net "M_L_CPU1_SA_CS_N<0>")
	)
	(segment
		(start 164.46881 -247.91035)
		(end 195.898008 -247.91035)
		(width 0.14478)
		(layer "In11.Cu")
		(net "M_L_CPU1_SA_CS_N<0>")
	)
	(segment
		(start 142.978632 -251.281438)
		(end 142.9893 -251.275342)
		(width 0.0889)
		(layer "In11.Cu")
		(net "M_L_CPU1_SA_CS_N<0>")
	)
	(segment
		(start 161.317686 -251.061474)
		(end 164.46881 -247.91035)
		(width 0.14478)
		(layer "In11.Cu")
		(net "M_L_CPU1_SA_CS_N<0>")
	)
	(arc
		(start 142.038578 -251.281438)
		(mid 142.318582 -251.204393)
		(end 142.600172 -251.275342)
		(width 0.0889)
		(layer "In11.Cu")
		(net "M_L_CPU1_SA_CS_N<0>")
	)
	(arc
		(start 142.9893 -251.275342)
		(mid 143.270889 -251.204468)
		(end 143.550894 -251.281438)
		(width 0.0889)
		(layer "In11.Cu")
		(net "M_L_CPU1_SA_CS_N<0>")
	)
	(arc
		(start 144.85874 -251.281438)
		(mid 145.133828 -251.204591)
		(end 145.411698 -251.27077)
		(width 0.0889)
		(layer "In11.Cu")
		(net "M_L_CPU1_SA_CS_N<0>")
	)
	(arc
		(start 144.49044 -251.281438)
		(mid 144.66785 -251.331106)
		(end 144.847056 -251.288296)
		(width 0.0889)
		(layer "In11.Cu")
		(net "M_L_CPU1_SA_CS_N<0>")
	)
	(arc
		(start 140.169392 -251.275342)
		(mid 140.450981 -251.204468)
		(end 140.730986 -251.281438)
		(width 0.0889)
		(layer "In11.Cu")
		(net "M_L_CPU1_SA_CS_N<0>")
	)
	(arc
		(start 145.429986 -251.281438)
		(mid 145.518537 -251.318324)
		(end 145.613628 -251.330968)
		(width 0.0889)
		(layer "In11.Cu")
		(net "M_L_CPU1_SA_CS_N<0>")
	)
	(arc
		(start 140.730986 -251.281438)
		(mid 140.914882 -251.330918)
		(end 141.098778 -251.281438)
		(width 0.0889)
		(layer "In11.Cu")
		(net "M_L_CPU1_SA_CS_N<0>")
	)
	(arc
		(start 143.941546 -251.267722)
		(mid 144.217741 -251.204234)
		(end 144.49044 -251.281438)
		(width 0.0889)
		(layer "In11.Cu")
		(net "M_L_CPU1_SA_CS_N<0>")
	)
	(arc
		(start 141.670786 -251.281438)
		(mid 141.854682 -251.330918)
		(end 142.038578 -251.281438)
		(width 0.0889)
		(layer "In11.Cu")
		(net "M_L_CPU1_SA_CS_N<0>")
	)
	(arc
		(start 139.28598 -251.24791)
		(mid 139.542389 -251.205549)
		(end 139.790932 -251.281438)
		(width 0.0889)
		(layer "In11.Cu")
		(net "M_L_CPU1_SA_CS_N<0>")
	)
	(arc
		(start 139.790932 -251.281438)
		(mid 139.974828 -251.330918)
		(end 140.158724 -251.281438)
		(width 0.0889)
		(layer "In11.Cu")
		(net "M_L_CPU1_SA_CS_N<0>")
	)
	(arc
		(start 141.098778 -251.281438)
		(mid 141.384782 -251.204486)
		(end 141.670786 -251.281438)
		(width 0.0889)
		(layer "In11.Cu")
		(net "M_L_CPU1_SA_CS_N<0>")
	)
	(arc
		(start 143.550894 -251.281438)
		(mid 143.727827 -251.330729)
		(end 143.906494 -251.288042)
		(width 0.0889)
		(layer "In11.Cu")
		(net "M_L_CPU1_SA_CS_N<0>")
	)
	(arc
		(start 142.61084 -251.281438)
		(mid 142.794736 -251.330918)
		(end 142.978632 -251.281438)
		(width 0.0889)
		(layer "In11.Cu")
		(net "M_L_CPU1_SA_CS_N<0>")
	)
	(segment
		(start 137.627868 -249.610372)
		(end 138.09472 -249.344434)
		(width 0.10668)
		(layer "F.Cu")
		(net "M_L_CPU1_SA_CB<7>")
	)
	(segment
		(start 162.42411 -246.251476)
		(end 162.79114 -246.618506)
		(width 0.14478)
		(layer "In11.Cu")
		(net "M_L_CPU1_SA_CB<7>")
	)
	(segment
		(start 160.47339 -247.997472)
		(end 160.65881 -247.812052)
		(width 0.14478)
		(layer "In11.Cu")
		(net "M_L_CPU1_SA_CB<7>")
	)
	(segment
		(start 141.667738 -249.021854)
		(end 141.67612 -249.017028)
		(width 0.0889)
		(layer "In11.Cu")
		(net "M_L_CPU1_SA_CB<7>")
	)
	(segment
		(start 160.470596 -249.143774)
		(end 160.84042 -248.77395)
		(width 0.14478)
		(layer "In11.Cu")
		(net "M_L_CPU1_SA_CB<7>")
	)
	(segment
		(start 138.09472 -249.344434)
		(end 137.940796 -249.079004)
		(width 0.0889)
		(layer "In11.Cu")
		(net "M_L_CPU1_SA_CB<7>")
	)
	(segment
		(start 162.033966 -246.64162)
		(end 162.033966 -246.436896)
		(width 0.14478)
		(layer "In11.Cu")
		(net "M_L_CPU1_SA_CB<7>")
	)
	(segment
		(start 137.940796 -249.079004)
		(end 137.963148 -248.995692)
		(width 0.0889)
		(layer "In11.Cu")
		(net "M_L_CPU1_SA_CB<7>")
	)
	(segment
		(start 161.620708 -247.993662)
		(end 161.620708 -247.788938)
		(width 0.14478)
		(layer "In11.Cu")
		(net "M_L_CPU1_SA_CB<7>")
	)
	(segment
		(start 193.451734 -244.59565)
		(end 193.637154 -244.41023)
		(width 0.14478)
		(layer "In11.Cu")
		(net "M_L_CPU1_SA_CB<7>")
	)
	(segment
		(start 162.79114 -246.618506)
		(end 162.995864 -246.618506)
		(width 0.14478)
		(layer "In11.Cu")
		(net "M_L_CPU1_SA_CB<7>")
	)
	(segment
		(start 162.400996 -247.213374)
		(end 162.400996 -247.00865)
		(width 0.14478)
		(layer "In11.Cu")
		(net "M_L_CPU1_SA_CB<7>")
	)
	(segment
		(start 193.45148 -244.800374)
		(end 193.451734 -244.59565)
		(width 0.14478)
		(layer "In11.Cu")
		(net "M_L_CPU1_SA_CB<7>")
	)
	(segment
		(start 161.643822 -247.031764)
		(end 162.010852 -247.398794)
		(width 0.14478)
		(layer "In11.Cu")
		(net "M_L_CPU1_SA_CB<7>")
	)
	(segment
		(start 193.841878 -244.41023)
		(end 194.02171 -244.590062)
		(width 0.14478)
		(layer "In11.Cu")
		(net "M_L_CPU1_SA_CB<7>")
	)
	(segment
		(start 162.814254 -245.656608)
		(end 162.999674 -245.471188)
		(width 0.14478)
		(layer "In11.Cu")
		(net "M_L_CPU1_SA_CB<7>")
	)
	(segment
		(start 144.843246 -249.010678)
		(end 144.863312 -249.022108)
		(width 0.0889)
		(layer "In11.Cu")
		(net "M_L_CPU1_SA_CB<7>")
	)
	(segment
		(start 162.215576 -247.398794)
		(end 162.400996 -247.213374)
		(width 0.14478)
		(layer "In11.Cu")
		(net "M_L_CPU1_SA_CB<7>")
	)
	(segment
		(start 160.863534 -247.812052)
		(end 161.230564 -248.179082)
		(width 0.14478)
		(layer "In11.Cu")
		(net "M_L_CPU1_SA_CB<7>")
	)
	(segment
		(start 193.631312 -245.18493)
		(end 193.631312 -244.980206)
		(width 0.14478)
		(layer "In11.Cu")
		(net "M_L_CPU1_SA_CB<7>")
	)
	(segment
		(start 162.033966 -246.436896)
		(end 162.219386 -246.251476)
		(width 0.14478)
		(layer "In11.Cu")
		(net "M_L_CPU1_SA_CB<7>")
	)
	(segment
		(start 193.455798 -245.360444)
		(end 193.631312 -245.18493)
		(width 0.14478)
		(layer "In11.Cu")
		(net "M_L_CPU1_SA_CB<7>")
	)
	(segment
		(start 144.466564 -249.03557)
		(end 144.489932 -249.021854)
		(width 0.0889)
		(layer "In11.Cu")
		(net "M_L_CPU1_SA_CB<7>")
	)
	(segment
		(start 162.010852 -247.398794)
		(end 162.215576 -247.398794)
		(width 0.14478)
		(layer "In11.Cu")
		(net "M_L_CPU1_SA_CB<7>")
	)
	(segment
		(start 161.439098 -247.031764)
		(end 161.643822 -247.031764)
		(width 0.14478)
		(layer "In11.Cu")
		(net "M_L_CPU1_SA_CB<7>")
	)
	(segment
		(start 145.144744 -249.097546)
		(end 145.59915 -249.097546)
		(width 0.0889)
		(layer "In11.Cu")
		(net "M_L_CPU1_SA_CB<7>")
	)
	(segment
		(start 162.814254 -245.861332)
		(end 162.814254 -245.656608)
		(width 0.14478)
		(layer "In11.Cu")
		(net "M_L_CPU1_SA_CB<7>")
	)
	(segment
		(start 162.995864 -246.618506)
		(end 163.181284 -246.433086)
		(width 0.14478)
		(layer "In11.Cu")
		(net "M_L_CPU1_SA_CB<7>")
	)
	(segment
		(start 192.892934 -245.215664)
		(end 193.037714 -245.360444)
		(width 0.14478)
		(layer "In11.Cu")
		(net "M_L_CPU1_SA_CB<7>")
	)
	(segment
		(start 192.48628 -244.650006)
		(end 192.748154 -244.650006)
		(width 0.14478)
		(layer "In11.Cu")
		(net "M_L_CPU1_SA_CB<7>")
	)
	(segment
		(start 164.253926 -245.360444)
		(end 192.19672 -245.360444)
		(width 0.14478)
		(layer "In11.Cu")
		(net "M_L_CPU1_SA_CB<7>")
	)
	(segment
		(start 160.84042 -248.569226)
		(end 160.47339 -248.202196)
		(width 0.14478)
		(layer "In11.Cu")
		(net "M_L_CPU1_SA_CB<7>")
	)
	(segment
		(start 192.3415 -244.794786)
		(end 192.48628 -244.650006)
		(width 0.14478)
		(layer "In11.Cu")
		(net "M_L_CPU1_SA_CB<7>")
	)
	(segment
		(start 162.999674 -245.471188)
		(end 163.204398 -245.471188)
		(width 0.14478)
		(layer "In11.Cu")
		(net "M_L_CPU1_SA_CB<7>")
	)
	(segment
		(start 161.253678 -247.217184)
		(end 161.439098 -247.031764)
		(width 0.14478)
		(layer "In11.Cu")
		(net "M_L_CPU1_SA_CB<7>")
	)
	(segment
		(start 161.230564 -248.179082)
		(end 161.435288 -248.179082)
		(width 0.14478)
		(layer "In11.Cu")
		(net "M_L_CPU1_SA_CB<7>")
	)
	(segment
		(start 163.776152 -245.838218)
		(end 164.253926 -245.360444)
		(width 0.14478)
		(layer "In11.Cu")
		(net "M_L_CPU1_SA_CB<7>")
	)
	(segment
		(start 162.219386 -246.251476)
		(end 162.42411 -246.251476)
		(width 0.14478)
		(layer "In11.Cu")
		(net "M_L_CPU1_SA_CB<7>")
	)
	(segment
		(start 194.02171 -244.590062)
		(end 194.225926 -244.590316)
		(width 0.14478)
		(layer "In11.Cu")
		(net "M_L_CPU1_SA_CB<7>")
	)
	(segment
		(start 160.65881 -247.812052)
		(end 160.863534 -247.812052)
		(width 0.14478)
		(layer "In11.Cu")
		(net "M_L_CPU1_SA_CB<7>")
	)
	(segment
		(start 192.3415 -245.215664)
		(end 192.3415 -244.794786)
		(width 0.14478)
		(layer "In11.Cu")
		(net "M_L_CPU1_SA_CB<7>")
	)
	(segment
		(start 163.181284 -246.228362)
		(end 162.814254 -245.861332)
		(width 0.14478)
		(layer "In11.Cu")
		(net "M_L_CPU1_SA_CB<7>")
	)
	(segment
		(start 162.400996 -247.00865)
		(end 162.033966 -246.64162)
		(width 0.14478)
		(layer "In11.Cu")
		(net "M_L_CPU1_SA_CB<7>")
	)
	(segment
		(start 143.547592 -249.021854)
		(end 143.56207 -249.013472)
		(width 0.0889)
		(layer "In11.Cu")
		(net "M_L_CPU1_SA_CB<7>")
	)
	(segment
		(start 160.84042 -248.77395)
		(end 160.84042 -248.569226)
		(width 0.14478)
		(layer "In11.Cu")
		(net "M_L_CPU1_SA_CB<7>")
	)
	(segment
		(start 163.571428 -245.838218)
		(end 163.776152 -245.838218)
		(width 0.14478)
		(layer "In11.Cu")
		(net "M_L_CPU1_SA_CB<7>")
	)
	(segment
		(start 160.47339 -248.202196)
		(end 160.47339 -247.997472)
		(width 0.14478)
		(layer "In11.Cu")
		(net "M_L_CPU1_SA_CB<7>")
	)
	(segment
		(start 193.631312 -244.980206)
		(end 193.45148 -244.800374)
		(width 0.14478)
		(layer "In11.Cu")
		(net "M_L_CPU1_SA_CB<7>")
	)
	(segment
		(start 161.435288 -248.179082)
		(end 161.620708 -247.993662)
		(width 0.14478)
		(layer "In11.Cu")
		(net "M_L_CPU1_SA_CB<7>")
	)
	(segment
		(start 145.59915 -249.097546)
		(end 146.554952 -250.053348)
		(width 0.0889)
		(layer "In11.Cu")
		(net "M_L_CPU1_SA_CB<7>")
	)
	(segment
		(start 140.15339 -249.017028)
		(end 140.161772 -249.021854)
		(width 0.0889)
		(layer "In11.Cu")
		(net "M_L_CPU1_SA_CB<7>")
	)
	(segment
		(start 197.016624 -243.660422)
		(end 201.722736 -243.660422)
		(width 0.14478)
		(layer "In11.Cu")
		(net "M_L_CPU1_SA_CB<7>")
	)
	(segment
		(start 192.892934 -244.794786)
		(end 192.892934 -245.215664)
		(width 0.14478)
		(layer "In11.Cu")
		(net "M_L_CPU1_SA_CB<7>")
	)
	(segment
		(start 192.19672 -245.360444)
		(end 192.3415 -245.215664)
		(width 0.14478)
		(layer "In11.Cu")
		(net "M_L_CPU1_SA_CB<7>")
	)
	(segment
		(start 161.253678 -247.421908)
		(end 161.253678 -247.217184)
		(width 0.14478)
		(layer "In11.Cu")
		(net "M_L_CPU1_SA_CB<7>")
	)
	(segment
		(start 196.16674 -244.510306)
		(end 197.016624 -243.660422)
		(width 0.14478)
		(layer "In11.Cu")
		(net "M_L_CPU1_SA_CB<7>")
	)
	(segment
		(start 163.204398 -245.471188)
		(end 163.571428 -245.838218)
		(width 0.14478)
		(layer "In11.Cu")
		(net "M_L_CPU1_SA_CB<7>")
	)
	(segment
		(start 161.620708 -247.788938)
		(end 161.253678 -247.421908)
		(width 0.14478)
		(layer "In11.Cu")
		(net "M_L_CPU1_SA_CB<7>")
	)
	(segment
		(start 148.983192 -250.053348)
		(end 149.892766 -249.143774)
		(width 0.14478)
		(layer "In11.Cu")
		(net "M_L_CPU1_SA_CB<7>")
	)
	(segment
		(start 141.093444 -249.017028)
		(end 141.101826 -249.021854)
		(width 0.0889)
		(layer "In11.Cu")
		(net "M_L_CPU1_SA_CB<7>")
	)
	(segment
		(start 146.554952 -250.053348)
		(end 147.807172 -250.053348)
		(width 0.0889)
		(layer "In11.Cu")
		(net "M_L_CPU1_SA_CB<7>")
	)
	(segment
		(start 193.637154 -244.41023)
		(end 193.841878 -244.41023)
		(width 0.14478)
		(layer "In11.Cu")
		(net "M_L_CPU1_SA_CB<7>")
	)
	(segment
		(start 201.722736 -243.660422)
		(end 202.147932 -243.235226)
		(width 0.14478)
		(layer "In11.Cu")
		(net "M_L_CPU1_SA_CB<7>")
	)
	(segment
		(start 193.037714 -245.360444)
		(end 193.455798 -245.360444)
		(width 0.14478)
		(layer "In11.Cu")
		(net "M_L_CPU1_SA_CB<7>")
	)
	(segment
		(start 194.305936 -244.510306)
		(end 196.16674 -244.510306)
		(width 0.14478)
		(layer "In11.Cu")
		(net "M_L_CPU1_SA_CB<7>")
	)
	(segment
		(start 194.225926 -244.590316)
		(end 194.305936 -244.510306)
		(width 0.14478)
		(layer "In11.Cu")
		(net "M_L_CPU1_SA_CB<7>")
	)
	(segment
		(start 163.181284 -246.433086)
		(end 163.181284 -246.228362)
		(width 0.14478)
		(layer "In11.Cu")
		(net "M_L_CPU1_SA_CB<7>")
	)
	(segment
		(start 192.748154 -244.650006)
		(end 192.892934 -244.794786)
		(width 0.14478)
		(layer "In11.Cu")
		(net "M_L_CPU1_SA_CB<7>")
	)
	(segment
		(start 147.807172 -250.053348)
		(end 148.983192 -250.053348)
		(width 0.14478)
		(layer "In11.Cu")
		(net "M_L_CPU1_SA_CB<7>")
	)
	(segment
		(start 149.892766 -249.143774)
		(end 160.470596 -249.143774)
		(width 0.14478)
		(layer "In11.Cu")
		(net "M_L_CPU1_SA_CB<7>")
	)
	(arc
		(start 138.281918 -249.021854)
		(mid 138.564874 -249.098031)
		(end 138.84783 -249.021854)
		(width 0.0889)
		(layer "In11.Cu")
		(net "M_L_CPU1_SA_CB<7>")
	)
	(arc
		(start 142.04188 -249.021854)
		(mid 142.324836 -249.098031)
		(end 142.607792 -249.021854)
		(width 0.0889)
		(layer "In11.Cu")
		(net "M_L_CPU1_SA_CB<7>")
	)
	(arc
		(start 138.84783 -249.021854)
		(mid 139.034774 -248.971599)
		(end 139.221718 -249.021854)
		(width 0.0889)
		(layer "In11.Cu")
		(net "M_L_CPU1_SA_CB<7>")
	)
	(arc
		(start 142.98168 -249.021854)
		(mid 143.264636 -249.098031)
		(end 143.547592 -249.021854)
		(width 0.0889)
		(layer "In11.Cu")
		(net "M_L_CPU1_SA_CB<7>")
	)
	(arc
		(start 143.92275 -249.021854)
		(mid 144.192907 -249.098616)
		(end 144.466564 -249.03557)
		(width 0.0889)
		(layer "In11.Cu")
		(net "M_L_CPU1_SA_CB<7>")
	)
	(arc
		(start 137.963148 -248.995692)
		(mid 138.12548 -248.972874)
		(end 138.281918 -249.021854)
		(width 0.0889)
		(layer "In11.Cu")
		(net "M_L_CPU1_SA_CB<7>")
	)
	(arc
		(start 142.607792 -249.021854)
		(mid 142.794736 -248.971599)
		(end 142.98168 -249.021854)
		(width 0.0889)
		(layer "In11.Cu")
		(net "M_L_CPU1_SA_CB<7>")
	)
	(arc
		(start 144.489932 -249.021854)
		(mid 144.665171 -248.971783)
		(end 144.843246 -249.010678)
		(width 0.0889)
		(layer "In11.Cu")
		(net "M_L_CPU1_SA_CB<7>")
	)
	(arc
		(start 140.161772 -249.021854)
		(mid 140.444728 -249.098031)
		(end 140.727684 -249.021854)
		(width 0.0889)
		(layer "In11.Cu")
		(net "M_L_CPU1_SA_CB<7>")
	)
	(arc
		(start 144.863312 -249.022108)
		(mid 144.999068 -249.078316)
		(end 145.144744 -249.097546)
		(width 0.0889)
		(layer "In11.Cu")
		(net "M_L_CPU1_SA_CB<7>")
	)
	(arc
		(start 139.221718 -249.021854)
		(mid 139.504674 -249.098031)
		(end 139.78763 -249.021854)
		(width 0.0889)
		(layer "In11.Cu")
		(net "M_L_CPU1_SA_CB<7>")
	)
	(arc
		(start 141.101826 -249.021854)
		(mid 141.384782 -249.098031)
		(end 141.667738 -249.021854)
		(width 0.0889)
		(layer "In11.Cu")
		(net "M_L_CPU1_SA_CB<7>")
	)
	(arc
		(start 140.727684 -249.021854)
		(mid 140.909935 -248.971504)
		(end 141.093444 -249.017028)
		(width 0.0889)
		(layer "In11.Cu")
		(net "M_L_CPU1_SA_CB<7>")
	)
	(arc
		(start 139.78763 -249.021854)
		(mid 139.969881 -248.971504)
		(end 140.15339 -249.017028)
		(width 0.0889)
		(layer "In11.Cu")
		(net "M_L_CPU1_SA_CB<7>")
	)
	(arc
		(start 141.67612 -249.017028)
		(mid 141.859628 -248.971534)
		(end 142.04188 -249.021854)
		(width 0.0889)
		(layer "In11.Cu")
		(net "M_L_CPU1_SA_CB<7>")
	)
	(arc
		(start 143.56207 -249.013472)
		(mid 143.743486 -248.971215)
		(end 143.92275 -249.021854)
		(width 0.0889)
		(layer "In11.Cu")
		(net "M_L_CPU1_SA_CB<7>")
	)
	(segment
		(start 139.037822 -248.800366)
		(end 139.504674 -248.534428)
		(width 0.10668)
		(layer "F.Cu")
		(net "M_L_CPU1_SA_CB<6>")
	)
	(segment
		(start 189.807342 -243.515642)
		(end 189.807342 -242.564666)
		(width 0.14478)
		(layer "In11.Cu")
		(net "M_L_CPU1_SA_CB<6>")
	)
	(segment
		(start 199.999346 -242.196874)
		(end 200.144126 -242.341654)
		(width 0.14478)
		(layer "In11.Cu")
		(net "M_L_CPU1_SA_CB<6>")
	)
	(segment
		(start 200.144126 -242.341654)
		(end 200.406 -242.341654)
		(width 0.14478)
		(layer "In11.Cu")
		(net "M_L_CPU1_SA_CB<6>")
	)
	(segment
		(start 199.447912 -241.81562)
		(end 199.447912 -241.723926)
		(width 0.14478)
		(layer "In11.Cu")
		(net "M_L_CPU1_SA_CB<6>")
	)
	(segment
		(start 201.722736 -241.9604)
		(end 202.147932 -241.535204)
		(width 0.14478)
		(layer "In11.Cu")
		(net "M_L_CPU1_SA_CB<6>")
	)
	(segment
		(start 200.55078 -242.196874)
		(end 200.55078 -241.723926)
		(width 0.14478)
		(layer "In11.Cu")
		(net "M_L_CPU1_SA_CB<6>")
	)
	(segment
		(start 140.257784 -248.211848)
		(end 140.266166 -248.207022)
		(width 0.0889)
		(layer "In11.Cu")
		(net "M_L_CPU1_SA_CB<6>")
	)
	(segment
		(start 145.638012 -248.161048)
		(end 146.14779 -248.670826)
		(width 0.0889)
		(layer "In11.Cu")
		(net "M_L_CPU1_SA_CB<6>")
	)
	(segment
		(start 189.400688 -243.660422)
		(end 189.662562 -243.660422)
		(width 0.14478)
		(layer "In11.Cu")
		(net "M_L_CPU1_SA_CB<6>")
	)
	(segment
		(start 199.447912 -241.723926)
		(end 199.592692 -241.579146)
		(width 0.14478)
		(layer "In11.Cu")
		(net "M_L_CPU1_SA_CB<6>")
	)
	(segment
		(start 200.406 -242.341654)
		(end 200.55078 -242.196874)
		(width 0.14478)
		(layer "In11.Cu")
		(net "M_L_CPU1_SA_CB<6>")
	)
	(segment
		(start 191.881506 -243.660422)
		(end 192.731644 -242.810284)
		(width 0.14478)
		(layer "In11.Cu")
		(net "M_L_CPU1_SA_CB<6>")
	)
	(segment
		(start 163.485322 -243.660422)
		(end 187.456826 -243.660422)
		(width 0.14478)
		(layer "In11.Cu")
		(net "M_L_CPU1_SA_CB<6>")
	)
	(segment
		(start 139.35075 -248.268998)
		(end 139.373102 -248.185686)
		(width 0.0889)
		(layer "In11.Cu")
		(net "M_L_CPU1_SA_CB<6>")
	)
	(segment
		(start 199.592692 -241.579146)
		(end 199.854566 -241.579146)
		(width 0.14478)
		(layer "In11.Cu")
		(net "M_L_CPU1_SA_CB<6>")
	)
	(segment
		(start 201.102214 -241.723926)
		(end 201.102214 -241.81562)
		(width 0.14478)
		(layer "In11.Cu")
		(net "M_L_CPU1_SA_CB<6>")
	)
	(segment
		(start 146.81327 -248.670826)
		(end 147.286472 -249.144028)
		(width 0.0889)
		(layer "In11.Cu")
		(net "M_L_CPU1_SA_CB<6>")
	)
	(segment
		(start 188.704474 -242.564666)
		(end 188.849254 -242.419886)
		(width 0.14478)
		(layer "In11.Cu")
		(net "M_L_CPU1_SA_CB<6>")
	)
	(segment
		(start 201.102214 -241.81562)
		(end 201.246994 -241.9604)
		(width 0.14478)
		(layer "In11.Cu")
		(net "M_L_CPU1_SA_CB<6>")
	)
	(segment
		(start 200.69556 -241.579146)
		(end 200.957434 -241.579146)
		(width 0.14478)
		(layer "In11.Cu")
		(net "M_L_CPU1_SA_CB<6>")
	)
	(segment
		(start 189.255908 -243.515642)
		(end 189.400688 -243.660422)
		(width 0.14478)
		(layer "In11.Cu")
		(net "M_L_CPU1_SA_CB<6>")
	)
	(segment
		(start 199.854566 -241.579146)
		(end 199.999346 -241.723926)
		(width 0.14478)
		(layer "In11.Cu")
		(net "M_L_CPU1_SA_CB<6>")
	)
	(segment
		(start 200.55078 -241.723926)
		(end 200.69556 -241.579146)
		(width 0.14478)
		(layer "In11.Cu")
		(net "M_L_CPU1_SA_CB<6>")
	)
	(segment
		(start 201.246994 -241.9604)
		(end 201.722736 -241.9604)
		(width 0.14478)
		(layer "In11.Cu")
		(net "M_L_CPU1_SA_CB<6>")
	)
	(segment
		(start 189.662562 -243.660422)
		(end 189.807342 -243.515642)
		(width 0.14478)
		(layer "In11.Cu")
		(net "M_L_CPU1_SA_CB<6>")
	)
	(segment
		(start 199.303132 -241.9604)
		(end 199.447912 -241.81562)
		(width 0.14478)
		(layer "In11.Cu")
		(net "M_L_CPU1_SA_CB<6>")
	)
	(segment
		(start 144.390618 -248.211848)
		(end 144.408652 -248.222516)
		(width 0.0889)
		(layer "In11.Cu")
		(net "M_L_CPU1_SA_CB<6>")
	)
	(segment
		(start 147.286472 -249.144028)
		(end 147.819618 -249.144028)
		(width 0.0889)
		(layer "In11.Cu")
		(net "M_L_CPU1_SA_CB<6>")
	)
	(segment
		(start 189.952122 -242.419886)
		(end 190.213996 -242.419886)
		(width 0.14478)
		(layer "In11.Cu")
		(net "M_L_CPU1_SA_CB<6>")
	)
	(segment
		(start 199.999346 -241.723926)
		(end 199.999346 -242.196874)
		(width 0.14478)
		(layer "In11.Cu")
		(net "M_L_CPU1_SA_CB<6>")
	)
	(segment
		(start 196.228716 -242.810284)
		(end 197.0786 -241.9604)
		(width 0.14478)
		(layer "In11.Cu")
		(net "M_L_CPU1_SA_CB<6>")
	)
	(segment
		(start 147.819618 -249.144028)
		(end 148.606256 -249.144028)
		(width 0.14478)
		(layer "In11.Cu")
		(net "M_L_CPU1_SA_CB<6>")
	)
	(segment
		(start 188.29782 -243.660422)
		(end 188.559694 -243.660422)
		(width 0.14478)
		(layer "In11.Cu")
		(net "M_L_CPU1_SA_CB<6>")
	)
	(segment
		(start 189.807342 -242.564666)
		(end 189.952122 -242.419886)
		(width 0.14478)
		(layer "In11.Cu")
		(net "M_L_CPU1_SA_CB<6>")
	)
	(segment
		(start 187.456826 -243.660422)
		(end 187.601606 -243.515642)
		(width 0.14478)
		(layer "In11.Cu")
		(net "M_L_CPU1_SA_CB<6>")
	)
	(segment
		(start 144.005046 -248.21896)
		(end 144.016984 -248.212102)
		(width 0.0889)
		(layer "In11.Cu")
		(net "M_L_CPU1_SA_CB<6>")
	)
	(segment
		(start 200.957434 -241.579146)
		(end 201.102214 -241.723926)
		(width 0.14478)
		(layer "In11.Cu")
		(net "M_L_CPU1_SA_CB<6>")
	)
	(segment
		(start 188.559694 -243.660422)
		(end 188.704474 -243.515642)
		(width 0.14478)
		(layer "In11.Cu")
		(net "M_L_CPU1_SA_CB<6>")
	)
	(segment
		(start 146.14779 -248.670826)
		(end 146.81327 -248.670826)
		(width 0.0889)
		(layer "In11.Cu")
		(net "M_L_CPU1_SA_CB<6>")
	)
	(segment
		(start 189.255908 -242.564666)
		(end 189.255908 -243.515642)
		(width 0.14478)
		(layer "In11.Cu")
		(net "M_L_CPU1_SA_CB<6>")
	)
	(segment
		(start 139.504674 -248.534428)
		(end 139.35075 -248.268998)
		(width 0.0889)
		(layer "In11.Cu")
		(net "M_L_CPU1_SA_CB<6>")
	)
	(segment
		(start 190.503556 -243.660422)
		(end 191.881506 -243.660422)
		(width 0.14478)
		(layer "In11.Cu")
		(net "M_L_CPU1_SA_CB<6>")
	)
	(segment
		(start 187.601606 -242.564666)
		(end 187.746386 -242.419886)
		(width 0.14478)
		(layer "In11.Cu")
		(net "M_L_CPU1_SA_CB<6>")
	)
	(segment
		(start 188.15304 -243.515642)
		(end 188.29782 -243.660422)
		(width 0.14478)
		(layer "In11.Cu")
		(net "M_L_CPU1_SA_CB<6>")
	)
	(segment
		(start 188.15304 -242.564666)
		(end 188.15304 -243.515642)
		(width 0.14478)
		(layer "In11.Cu")
		(net "M_L_CPU1_SA_CB<6>")
	)
	(segment
		(start 192.731644 -242.810284)
		(end 196.228716 -242.810284)
		(width 0.14478)
		(layer "In11.Cu")
		(net "M_L_CPU1_SA_CB<6>")
	)
	(segment
		(start 188.849254 -242.419886)
		(end 189.111128 -242.419886)
		(width 0.14478)
		(layer "In11.Cu")
		(net "M_L_CPU1_SA_CB<6>")
	)
	(segment
		(start 149.51583 -248.234454)
		(end 158.91129 -248.234454)
		(width 0.14478)
		(layer "In11.Cu")
		(net "M_L_CPU1_SA_CB<6>")
	)
	(segment
		(start 188.00826 -242.419886)
		(end 188.15304 -242.564666)
		(width 0.14478)
		(layer "In11.Cu")
		(net "M_L_CPU1_SA_CB<6>")
	)
	(segment
		(start 187.746386 -242.419886)
		(end 188.00826 -242.419886)
		(width 0.14478)
		(layer "In11.Cu")
		(net "M_L_CPU1_SA_CB<6>")
	)
	(segment
		(start 145.144744 -248.161048)
		(end 145.638012 -248.161048)
		(width 0.0889)
		(layer "In11.Cu")
		(net "M_L_CPU1_SA_CB<6>")
	)
	(segment
		(start 148.606256 -249.144028)
		(end 149.51583 -248.234454)
		(width 0.14478)
		(layer "In11.Cu")
		(net "M_L_CPU1_SA_CB<6>")
	)
	(segment
		(start 142.503398 -248.207022)
		(end 142.51178 -248.211848)
		(width 0.0889)
		(layer "In11.Cu")
		(net "M_L_CPU1_SA_CB<6>")
	)
	(segment
		(start 189.111128 -242.419886)
		(end 189.255908 -242.564666)
		(width 0.14478)
		(layer "In11.Cu")
		(net "M_L_CPU1_SA_CB<6>")
	)
	(segment
		(start 197.0786 -241.9604)
		(end 199.303132 -241.9604)
		(width 0.14478)
		(layer "In11.Cu")
		(net "M_L_CPU1_SA_CB<6>")
	)
	(segment
		(start 144.016984 -248.212102)
		(end 144.0307 -248.204228)
		(width 0.0889)
		(layer "In11.Cu")
		(net "M_L_CPU1_SA_CB<6>")
	)
	(segment
		(start 190.213996 -242.419886)
		(end 190.358776 -242.564666)
		(width 0.14478)
		(layer "In11.Cu")
		(net "M_L_CPU1_SA_CB<6>")
	)
	(segment
		(start 158.91129 -248.234454)
		(end 163.485322 -243.660422)
		(width 0.14478)
		(layer "In11.Cu")
		(net "M_L_CPU1_SA_CB<6>")
	)
	(segment
		(start 187.601606 -243.515642)
		(end 187.601606 -242.564666)
		(width 0.14478)
		(layer "In11.Cu")
		(net "M_L_CPU1_SA_CB<6>")
	)
	(segment
		(start 188.704474 -243.515642)
		(end 188.704474 -242.564666)
		(width 0.14478)
		(layer "In11.Cu")
		(net "M_L_CPU1_SA_CB<6>")
	)
	(segment
		(start 190.358776 -242.564666)
		(end 190.358776 -243.515642)
		(width 0.14478)
		(layer "In11.Cu")
		(net "M_L_CPU1_SA_CB<6>")
	)
	(segment
		(start 190.358776 -243.515642)
		(end 190.503556 -243.660422)
		(width 0.14478)
		(layer "In11.Cu")
		(net "M_L_CPU1_SA_CB<6>")
	)
	(segment
		(start 143.077692 -248.211848)
		(end 143.086074 -248.207022)
		(width 0.0889)
		(layer "In11.Cu")
		(net "M_L_CPU1_SA_CB<6>")
	)
	(arc
		(start 139.373102 -248.185686)
		(mid 139.535434 -248.162868)
		(end 139.691872 -248.211848)
		(width 0.0889)
		(layer "In11.Cu")
		(net "M_L_CPU1_SA_CB<6>")
	)
	(arc
		(start 139.691872 -248.211848)
		(mid 139.974828 -248.288025)
		(end 140.257784 -248.211848)
		(width 0.0889)
		(layer "In11.Cu")
		(net "M_L_CPU1_SA_CB<6>")
	)
	(arc
		(start 143.451834 -248.211848)
		(mid 143.727512 -248.287978)
		(end 144.005046 -248.21896)
		(width 0.0889)
		(layer "In11.Cu")
		(net "M_L_CPU1_SA_CB<6>")
	)
	(arc
		(start 140.631926 -248.211848)
		(mid 140.914882 -248.288025)
		(end 141.197838 -248.211848)
		(width 0.0889)
		(layer "In11.Cu")
		(net "M_L_CPU1_SA_CB<6>")
	)
	(arc
		(start 143.086074 -248.207022)
		(mid 143.269582 -248.161528)
		(end 143.451834 -248.211848)
		(width 0.0889)
		(layer "In11.Cu")
		(net "M_L_CPU1_SA_CB<6>")
	)
	(arc
		(start 140.266166 -248.207022)
		(mid 140.449674 -248.161528)
		(end 140.631926 -248.211848)
		(width 0.0889)
		(layer "In11.Cu")
		(net "M_L_CPU1_SA_CB<6>")
	)
	(arc
		(start 142.51178 -248.211848)
		(mid 142.794736 -248.288025)
		(end 143.077692 -248.211848)
		(width 0.0889)
		(layer "In11.Cu")
		(net "M_L_CPU1_SA_CB<6>")
	)
	(arc
		(start 142.137638 -248.211848)
		(mid 142.319889 -248.161498)
		(end 142.503398 -248.207022)
		(width 0.0889)
		(layer "In11.Cu")
		(net "M_L_CPU1_SA_CB<6>")
	)
	(arc
		(start 144.408652 -248.222516)
		(mid 144.684347 -248.288359)
		(end 144.957292 -248.211848)
		(width 0.0889)
		(layer "In11.Cu")
		(net "M_L_CPU1_SA_CB<6>")
	)
	(arc
		(start 144.957292 -248.211848)
		(mid 145.047655 -248.174038)
		(end 145.144744 -248.161048)
		(width 0.0889)
		(layer "In11.Cu")
		(net "M_L_CPU1_SA_CB<6>")
	)
	(arc
		(start 141.197838 -248.211848)
		(mid 141.384782 -248.161593)
		(end 141.571726 -248.211848)
		(width 0.0889)
		(layer "In11.Cu")
		(net "M_L_CPU1_SA_CB<6>")
	)
	(arc
		(start 141.571726 -248.211848)
		(mid 141.854682 -248.288025)
		(end 142.137638 -248.211848)
		(width 0.0889)
		(layer "In11.Cu")
		(net "M_L_CPU1_SA_CB<6>")
	)
	(arc
		(start 144.0307 -248.204228)
		(mid 144.21163 -248.16175)
		(end 144.390618 -248.211848)
		(width 0.0889)
		(layer "In11.Cu")
		(net "M_L_CPU1_SA_CB<6>")
	)
	(segment
		(start 137.157968 -248.800366)
		(end 137.62482 -248.534428)
		(width 0.10668)
		(layer "F.Cu")
		(net "M_L_CPU1_SA_CB<5>")
	)
	(segment
		(start 205.823058 -242.810284)
		(end 206.248 -242.385342)
		(width 0.14478)
		(layer "In11.Cu")
		(net "M_L_CPU1_SA_CB<5>")
	)
	(segment
		(start 163.27882 -244.510306)
		(end 191.940434 -244.510306)
		(width 0.14478)
		(layer "In11.Cu")
		(net "M_L_CPU1_SA_CB<5>")
	)
	(segment
		(start 204.472032 -242.076986)
		(end 204.616812 -241.932206)
		(width 0.14478)
		(layer "In11.Cu")
		(net "M_L_CPU1_SA_CB<5>")
	)
	(segment
		(start 203.224384 -242.810284)
		(end 203.369164 -242.665504)
		(width 0.14478)
		(layer "In11.Cu")
		(net "M_L_CPU1_SA_CB<5>")
	)
	(segment
		(start 192.790318 -243.660422)
		(end 196.290438 -243.660422)
		(width 0.14478)
		(layer "In11.Cu")
		(net "M_L_CPU1_SA_CB<5>")
	)
	(segment
		(start 144.936972 -248.844308)
		(end 144.958562 -248.856754)
		(width 0.0889)
		(layer "In11.Cu")
		(net "M_L_CPU1_SA_CB<5>")
	)
	(segment
		(start 138.743436 -248.861834)
		(end 138.751818 -248.857008)
		(width 0.0889)
		(layer "In11.Cu")
		(net "M_L_CPU1_SA_CB<5>")
	)
	(segment
		(start 147.370292 -249.598688)
		(end 147.864322 -249.598688)
		(width 0.0889)
		(layer "In11.Cu")
		(net "M_L_CPU1_SA_CB<5>")
	)
	(segment
		(start 205.023466 -242.076986)
		(end 205.023466 -242.665504)
		(width 0.14478)
		(layer "In11.Cu")
		(net "M_L_CPU1_SA_CB<5>")
	)
	(segment
		(start 146.67865 -248.907046)
		(end 147.370292 -249.598688)
		(width 0.0889)
		(layer "In11.Cu")
		(net "M_L_CPU1_SA_CB<5>")
	)
	(segment
		(start 204.878686 -241.932206)
		(end 205.023466 -242.076986)
		(width 0.14478)
		(layer "In11.Cu")
		(net "M_L_CPU1_SA_CB<5>")
	)
	(segment
		(start 203.920598 -242.665504)
		(end 204.065378 -242.810284)
		(width 0.14478)
		(layer "In11.Cu")
		(net "M_L_CPU1_SA_CB<5>")
	)
	(segment
		(start 204.327252 -242.810284)
		(end 204.472032 -242.665504)
		(width 0.14478)
		(layer "In11.Cu")
		(net "M_L_CPU1_SA_CB<5>")
	)
	(segment
		(start 203.513944 -241.932206)
		(end 203.775818 -241.932206)
		(width 0.14478)
		(layer "In11.Cu")
		(net "M_L_CPU1_SA_CB<5>")
	)
	(segment
		(start 197.140576 -242.810284)
		(end 203.224384 -242.810284)
		(width 0.14478)
		(layer "In11.Cu")
		(net "M_L_CPU1_SA_CB<5>")
	)
	(segment
		(start 145.144998 -248.907046)
		(end 146.67865 -248.907046)
		(width 0.0889)
		(layer "In11.Cu")
		(net "M_L_CPU1_SA_CB<5>")
	)
	(segment
		(start 203.369164 -242.665504)
		(end 203.369164 -242.076986)
		(width 0.14478)
		(layer "In11.Cu")
		(net "M_L_CPU1_SA_CB<5>")
	)
	(segment
		(start 204.472032 -242.665504)
		(end 204.472032 -242.076986)
		(width 0.14478)
		(layer "In11.Cu")
		(net "M_L_CPU1_SA_CB<5>")
	)
	(segment
		(start 203.920598 -242.076986)
		(end 203.920598 -242.665504)
		(width 0.14478)
		(layer "In11.Cu")
		(net "M_L_CPU1_SA_CB<5>")
	)
	(segment
		(start 149.704298 -248.689114)
		(end 159.100012 -248.689114)
		(width 0.14478)
		(layer "In11.Cu")
		(net "M_L_CPU1_SA_CB<5>")
	)
	(segment
		(start 205.168246 -242.810284)
		(end 205.823058 -242.810284)
		(width 0.14478)
		(layer "In11.Cu")
		(net "M_L_CPU1_SA_CB<5>")
	)
	(segment
		(start 205.023466 -242.665504)
		(end 205.168246 -242.810284)
		(width 0.14478)
		(layer "In11.Cu")
		(net "M_L_CPU1_SA_CB<5>")
	)
	(segment
		(start 137.62482 -248.534428)
		(end 137.778744 -248.799858)
		(width 0.0889)
		(layer "In11.Cu")
		(net "M_L_CPU1_SA_CB<5>")
	)
	(segment
		(start 204.616812 -241.932206)
		(end 204.878686 -241.932206)
		(width 0.14478)
		(layer "In11.Cu")
		(net "M_L_CPU1_SA_CB<5>")
	)
	(segment
		(start 203.369164 -242.076986)
		(end 203.513944 -241.932206)
		(width 0.14478)
		(layer "In11.Cu")
		(net "M_L_CPU1_SA_CB<5>")
	)
	(segment
		(start 159.100012 -248.689114)
		(end 163.27882 -244.510306)
		(width 0.14478)
		(layer "In11.Cu")
		(net "M_L_CPU1_SA_CB<5>")
	)
	(segment
		(start 142.503398 -248.861834)
		(end 142.51178 -248.857008)
		(width 0.0889)
		(layer "In11.Cu")
		(net "M_L_CPU1_SA_CB<5>")
	)
	(segment
		(start 148.794724 -249.598688)
		(end 149.704298 -248.689114)
		(width 0.14478)
		(layer "In11.Cu")
		(net "M_L_CPU1_SA_CB<5>")
	)
	(segment
		(start 196.290438 -243.660422)
		(end 197.140576 -242.810284)
		(width 0.14478)
		(layer "In11.Cu")
		(net "M_L_CPU1_SA_CB<5>")
	)
	(segment
		(start 143.077692 -248.857008)
		(end 143.086074 -248.861834)
		(width 0.0889)
		(layer "In11.Cu")
		(net "M_L_CPU1_SA_CB<5>")
	)
	(segment
		(start 147.864322 -249.598688)
		(end 148.794724 -249.598688)
		(width 0.14478)
		(layer "In11.Cu")
		(net "M_L_CPU1_SA_CB<5>")
	)
	(segment
		(start 204.065378 -242.810284)
		(end 204.327252 -242.810284)
		(width 0.14478)
		(layer "In11.Cu")
		(net "M_L_CPU1_SA_CB<5>")
	)
	(segment
		(start 140.257784 -248.857008)
		(end 140.266166 -248.861834)
		(width 0.0889)
		(layer "In11.Cu")
		(net "M_L_CPU1_SA_CB<5>")
	)
	(segment
		(start 203.775818 -241.932206)
		(end 203.920598 -242.076986)
		(width 0.14478)
		(layer "In11.Cu")
		(net "M_L_CPU1_SA_CB<5>")
	)
	(segment
		(start 137.778744 -248.799858)
		(end 137.874756 -248.825258)
		(width 0.0889)
		(layer "In11.Cu")
		(net "M_L_CPU1_SA_CB<5>")
	)
	(segment
		(start 144.379696 -248.86539)
		(end 144.394174 -248.857008)
		(width 0.0889)
		(layer "In11.Cu")
		(net "M_L_CPU1_SA_CB<5>")
	)
	(segment
		(start 139.31773 -248.857008)
		(end 139.326112 -248.861834)
		(width 0.0889)
		(layer "In11.Cu")
		(net "M_L_CPU1_SA_CB<5>")
	)
	(segment
		(start 143.451834 -248.857008)
		(end 143.475202 -248.843292)
		(width 0.0889)
		(layer "In11.Cu")
		(net "M_L_CPU1_SA_CB<5>")
	)
	(segment
		(start 191.940434 -244.510306)
		(end 192.790318 -243.660422)
		(width 0.14478)
		(layer "In11.Cu")
		(net "M_L_CPU1_SA_CB<5>")
	)
	(arc
		(start 144.394174 -248.857008)
		(mid 144.663943 -248.780985)
		(end 144.936972 -248.844308)
		(width 0.0889)
		(layer "In11.Cu")
		(net "M_L_CPU1_SA_CB<5>")
	)
	(arc
		(start 141.571726 -248.857008)
		(mid 141.854682 -248.780831)
		(end 142.137638 -248.857008)
		(width 0.0889)
		(layer "In11.Cu")
		(net "M_L_CPU1_SA_CB<5>")
	)
	(arc
		(start 143.475202 -248.843292)
		(mid 143.748856 -248.780349)
		(end 144.019016 -248.857008)
		(width 0.0889)
		(layer "In11.Cu")
		(net "M_L_CPU1_SA_CB<5>")
	)
	(arc
		(start 144.019016 -248.857008)
		(mid 144.198279 -248.907672)
		(end 144.379696 -248.86539)
		(width 0.0889)
		(layer "In11.Cu")
		(net "M_L_CPU1_SA_CB<5>")
	)
	(arc
		(start 140.631926 -248.857008)
		(mid 140.914882 -248.780831)
		(end 141.197838 -248.857008)
		(width 0.0889)
		(layer "In11.Cu")
		(net "M_L_CPU1_SA_CB<5>")
	)
	(arc
		(start 144.958562 -248.856754)
		(mid 145.048461 -248.894211)
		(end 145.144998 -248.907046)
		(width 0.0889)
		(layer "In11.Cu")
		(net "M_L_CPU1_SA_CB<5>")
	)
	(arc
		(start 138.751818 -248.857008)
		(mid 139.034774 -248.780831)
		(end 139.31773 -248.857008)
		(width 0.0889)
		(layer "In11.Cu")
		(net "M_L_CPU1_SA_CB<5>")
	)
	(arc
		(start 142.51178 -248.857008)
		(mid 142.794736 -248.780831)
		(end 143.077692 -248.857008)
		(width 0.0889)
		(layer "In11.Cu")
		(net "M_L_CPU1_SA_CB<5>")
	)
	(arc
		(start 139.691872 -248.857008)
		(mid 139.974828 -248.780831)
		(end 140.257784 -248.857008)
		(width 0.0889)
		(layer "In11.Cu")
		(net "M_L_CPU1_SA_CB<5>")
	)
	(arc
		(start 137.874756 -248.825258)
		(mid 138.129964 -248.781781)
		(end 138.377676 -248.857008)
		(width 0.0889)
		(layer "In11.Cu")
		(net "M_L_CPU1_SA_CB<5>")
	)
	(arc
		(start 140.266166 -248.861834)
		(mid 140.449674 -248.907328)
		(end 140.631926 -248.857008)
		(width 0.0889)
		(layer "In11.Cu")
		(net "M_L_CPU1_SA_CB<5>")
	)
	(arc
		(start 141.197838 -248.857008)
		(mid 141.384782 -248.907263)
		(end 141.571726 -248.857008)
		(width 0.0889)
		(layer "In11.Cu")
		(net "M_L_CPU1_SA_CB<5>")
	)
	(arc
		(start 142.137638 -248.857008)
		(mid 142.319889 -248.907358)
		(end 142.503398 -248.861834)
		(width 0.0889)
		(layer "In11.Cu")
		(net "M_L_CPU1_SA_CB<5>")
	)
	(arc
		(start 138.377676 -248.857008)
		(mid 138.559927 -248.907358)
		(end 138.743436 -248.861834)
		(width 0.0889)
		(layer "In11.Cu")
		(net "M_L_CPU1_SA_CB<5>")
	)
	(arc
		(start 143.086074 -248.861834)
		(mid 143.269582 -248.907328)
		(end 143.451834 -248.857008)
		(width 0.0889)
		(layer "In11.Cu")
		(net "M_L_CPU1_SA_CB<5>")
	)
	(arc
		(start 139.326112 -248.861834)
		(mid 139.50962 -248.907328)
		(end 139.691872 -248.857008)
		(width 0.0889)
		(layer "In11.Cu")
		(net "M_L_CPU1_SA_CB<5>")
	)
	(segment
		(start 138.567922 -247.99036)
		(end 139.034774 -247.724422)
		(width 0.10668)
		(layer "F.Cu")
		(net "M_L_CPU1_SA_CB<4>")
	)
	(segment
		(start 147.235672 -248.689368)
		(end 147.813776 -248.689368)
		(width 0.0889)
		(layer "In11.Cu")
		(net "M_L_CPU1_SA_CB<4>")
	)
	(segment
		(start 147.813776 -248.689368)
		(end 148.417534 -248.689368)
		(width 0.14478)
		(layer "In11.Cu")
		(net "M_L_CPU1_SA_CB<4>")
	)
	(segment
		(start 139.034774 -247.724422)
		(end 139.188698 -247.989852)
		(width 0.0889)
		(layer "In11.Cu")
		(net "M_L_CPU1_SA_CB<4>")
	)
	(segment
		(start 184.813448 -243.100606)
		(end 184.958228 -242.955826)
		(width 0.14478)
		(layer "In11.Cu")
		(net "M_L_CPU1_SA_CB<4>")
	)
	(segment
		(start 158.722568 -247.779794)
		(end 163.361116 -243.141246)
		(width 0.14478)
		(layer "In11.Cu")
		(net "M_L_CPU1_SA_CB<4>")
	)
	(segment
		(start 186.205876 -241.9604)
		(end 196.166486 -241.9604)
		(width 0.14478)
		(layer "In11.Cu")
		(net "M_L_CPU1_SA_CB<4>")
	)
	(segment
		(start 184.406794 -242.10518)
		(end 184.406794 -242.955826)
		(width 0.14478)
		(layer "In11.Cu")
		(net "M_L_CPU1_SA_CB<4>")
	)
	(segment
		(start 141.667738 -248.047002)
		(end 141.67612 -248.051828)
		(width 0.0889)
		(layer "In11.Cu")
		(net "M_L_CPU1_SA_CB<4>")
	)
	(segment
		(start 185.103008 -241.9604)
		(end 185.364882 -241.9604)
		(width 0.14478)
		(layer "In11.Cu")
		(net "M_L_CPU1_SA_CB<4>")
	)
	(segment
		(start 145.144744 -247.970548)
		(end 145.717006 -247.970548)
		(width 0.0889)
		(layer "In11.Cu")
		(net "M_L_CPU1_SA_CB<4>")
	)
	(segment
		(start 140.15339 -248.051828)
		(end 140.161772 -248.047002)
		(width 0.0889)
		(layer "In11.Cu")
		(net "M_L_CPU1_SA_CB<4>")
	)
	(segment
		(start 165.477444 -242.082066)
		(end 168.86047 -242.082066)
		(width 0.14478)
		(layer "In11.Cu")
		(net "M_L_CPU1_SA_CB<4>")
	)
	(segment
		(start 145.717006 -247.970548)
		(end 146.181064 -248.434606)
		(width 0.0889)
		(layer "In11.Cu")
		(net "M_L_CPU1_SA_CB<4>")
	)
	(segment
		(start 164.418264 -243.141246)
		(end 165.477444 -242.082066)
		(width 0.14478)
		(layer "In11.Cu")
		(net "M_L_CPU1_SA_CB<4>")
	)
	(segment
		(start 143.905224 -248.056146)
		(end 143.92148 -248.046748)
		(width 0.0889)
		(layer "In11.Cu")
		(net "M_L_CPU1_SA_CB<4>")
	)
	(segment
		(start 149.327108 -247.779794)
		(end 158.722568 -247.779794)
		(width 0.14478)
		(layer "In11.Cu")
		(net "M_L_CPU1_SA_CB<4>")
	)
	(segment
		(start 146.98091 -248.434606)
		(end 147.235672 -248.689368)
		(width 0.0889)
		(layer "In11.Cu")
		(net "M_L_CPU1_SA_CB<4>")
	)
	(segment
		(start 184.262014 -241.9604)
		(end 184.406794 -242.10518)
		(width 0.14478)
		(layer "In11.Cu")
		(net "M_L_CPU1_SA_CB<4>")
	)
	(segment
		(start 197.016624 -241.110262)
		(end 205.823058 -241.110262)
		(width 0.14478)
		(layer "In11.Cu")
		(net "M_L_CPU1_SA_CB<4>")
	)
	(segment
		(start 139.188698 -247.989852)
		(end 139.28471 -248.015252)
		(width 0.0889)
		(layer "In11.Cu")
		(net "M_L_CPU1_SA_CB<4>")
	)
	(segment
		(start 141.093444 -248.051828)
		(end 141.101826 -248.047002)
		(width 0.0889)
		(layer "In11.Cu")
		(net "M_L_CPU1_SA_CB<4>")
	)
	(segment
		(start 196.166486 -241.9604)
		(end 197.016624 -241.110262)
		(width 0.14478)
		(layer "In11.Cu")
		(net "M_L_CPU1_SA_CB<4>")
	)
	(segment
		(start 205.823058 -241.110262)
		(end 206.248 -240.68532)
		(width 0.14478)
		(layer "In11.Cu")
		(net "M_L_CPU1_SA_CB<4>")
	)
	(segment
		(start 185.916316 -243.100606)
		(end 186.061096 -242.955826)
		(width 0.14478)
		(layer "In11.Cu")
		(net "M_L_CPU1_SA_CB<4>")
	)
	(segment
		(start 185.654442 -243.100606)
		(end 185.916316 -243.100606)
		(width 0.14478)
		(layer "In11.Cu")
		(net "M_L_CPU1_SA_CB<4>")
	)
	(segment
		(start 184.958228 -242.955826)
		(end 184.958228 -242.10518)
		(width 0.14478)
		(layer "In11.Cu")
		(net "M_L_CPU1_SA_CB<4>")
	)
	(segment
		(start 144.48663 -248.047002)
		(end 144.498314 -248.05386)
		(width 0.0889)
		(layer "In11.Cu")
		(net "M_L_CPU1_SA_CB<4>")
	)
	(segment
		(start 148.417534 -248.689368)
		(end 149.327108 -247.779794)
		(width 0.14478)
		(layer "In11.Cu")
		(net "M_L_CPU1_SA_CB<4>")
	)
	(segment
		(start 184.958228 -242.10518)
		(end 185.103008 -241.9604)
		(width 0.14478)
		(layer "In11.Cu")
		(net "M_L_CPU1_SA_CB<4>")
	)
	(segment
		(start 143.92148 -248.046748)
		(end 143.933418 -248.03989)
		(width 0.0889)
		(layer "In11.Cu")
		(net "M_L_CPU1_SA_CB<4>")
	)
	(segment
		(start 184.551574 -243.100606)
		(end 184.813448 -243.100606)
		(width 0.14478)
		(layer "In11.Cu")
		(net "M_L_CPU1_SA_CB<4>")
	)
	(segment
		(start 163.361116 -243.141246)
		(end 164.418264 -243.141246)
		(width 0.14478)
		(layer "In11.Cu")
		(net "M_L_CPU1_SA_CB<4>")
	)
	(segment
		(start 184.406794 -242.955826)
		(end 184.551574 -243.100606)
		(width 0.14478)
		(layer "In11.Cu")
		(net "M_L_CPU1_SA_CB<4>")
	)
	(segment
		(start 168.982136 -241.9604)
		(end 184.262014 -241.9604)
		(width 0.14478)
		(layer "In11.Cu")
		(net "M_L_CPU1_SA_CB<4>")
	)
	(segment
		(start 146.181064 -248.434606)
		(end 146.98091 -248.434606)
		(width 0.0889)
		(layer "In11.Cu")
		(net "M_L_CPU1_SA_CB<4>")
	)
	(segment
		(start 186.061096 -242.10518)
		(end 186.205876 -241.9604)
		(width 0.14478)
		(layer "In11.Cu")
		(net "M_L_CPU1_SA_CB<4>")
	)
	(segment
		(start 185.364882 -241.9604)
		(end 185.509662 -242.10518)
		(width 0.14478)
		(layer "In11.Cu")
		(net "M_L_CPU1_SA_CB<4>")
	)
	(segment
		(start 185.509662 -242.10518)
		(end 185.509662 -242.955826)
		(width 0.14478)
		(layer "In11.Cu")
		(net "M_L_CPU1_SA_CB<4>")
	)
	(segment
		(start 186.061096 -242.955826)
		(end 186.061096 -242.10518)
		(width 0.14478)
		(layer "In11.Cu")
		(net "M_L_CPU1_SA_CB<4>")
	)
	(segment
		(start 185.509662 -242.955826)
		(end 185.654442 -243.100606)
		(width 0.14478)
		(layer "In11.Cu")
		(net "M_L_CPU1_SA_CB<4>")
	)
	(segment
		(start 168.86047 -242.082066)
		(end 168.982136 -241.9604)
		(width 0.14478)
		(layer "In11.Cu")
		(net "M_L_CPU1_SA_CB<4>")
	)
	(arc
		(start 142.98168 -248.047002)
		(mid 143.264636 -247.970825)
		(end 143.547592 -248.047002)
		(width 0.0889)
		(layer "In11.Cu")
		(net "M_L_CPU1_SA_CB<4>")
	)
	(arc
		(start 144.498314 -248.05386)
		(mid 144.680569 -248.097513)
		(end 144.861026 -248.047002)
		(width 0.0889)
		(layer "In11.Cu")
		(net "M_L_CPU1_SA_CB<4>")
	)
	(arc
		(start 143.933418 -248.03989)
		(mid 144.210952 -247.970909)
		(end 144.48663 -248.047002)
		(width 0.0889)
		(layer "In11.Cu")
		(net "M_L_CPU1_SA_CB<4>")
	)
	(arc
		(start 139.28471 -248.015252)
		(mid 139.539918 -247.971775)
		(end 139.78763 -248.047002)
		(width 0.0889)
		(layer "In11.Cu")
		(net "M_L_CPU1_SA_CB<4>")
	)
	(arc
		(start 140.727684 -248.047002)
		(mid 140.909935 -248.097352)
		(end 141.093444 -248.051828)
		(width 0.0889)
		(layer "In11.Cu")
		(net "M_L_CPU1_SA_CB<4>")
	)
	(arc
		(start 144.861026 -248.047002)
		(mid 144.997819 -247.98998)
		(end 145.144744 -247.970548)
		(width 0.0889)
		(layer "In11.Cu")
		(net "M_L_CPU1_SA_CB<4>")
	)
	(arc
		(start 142.607792 -248.047002)
		(mid 142.794736 -248.097257)
		(end 142.98168 -248.047002)
		(width 0.0889)
		(layer "In11.Cu")
		(net "M_L_CPU1_SA_CB<4>")
	)
	(arc
		(start 141.101826 -248.047002)
		(mid 141.384782 -247.970825)
		(end 141.667738 -248.047002)
		(width 0.0889)
		(layer "In11.Cu")
		(net "M_L_CPU1_SA_CB<4>")
	)
	(arc
		(start 142.04188 -248.047002)
		(mid 142.324836 -247.970825)
		(end 142.607792 -248.047002)
		(width 0.0889)
		(layer "In11.Cu")
		(net "M_L_CPU1_SA_CB<4>")
	)
	(arc
		(start 140.161772 -248.047002)
		(mid 140.444728 -247.970825)
		(end 140.727684 -248.047002)
		(width 0.0889)
		(layer "In11.Cu")
		(net "M_L_CPU1_SA_CB<4>")
	)
	(arc
		(start 141.67612 -248.051828)
		(mid 141.859628 -248.097322)
		(end 142.04188 -248.047002)
		(width 0.0889)
		(layer "In11.Cu")
		(net "M_L_CPU1_SA_CB<4>")
	)
	(arc
		(start 143.547592 -248.047002)
		(mid 143.725242 -248.097262)
		(end 143.905224 -248.056146)
		(width 0.0889)
		(layer "In11.Cu")
		(net "M_L_CPU1_SA_CB<4>")
	)
	(arc
		(start 139.78763 -248.047002)
		(mid 139.969881 -248.097352)
		(end 140.15339 -248.051828)
		(width 0.0889)
		(layer "In11.Cu")
		(net "M_L_CPU1_SA_CB<4>")
	)
	(segment
		(start 137.627868 -246.370348)
		(end 138.09472 -246.10441)
		(width 0.10668)
		(layer "F.Cu")
		(net "M_L_CPU1_SA_CB<3>")
	)
	(segment
		(start 158.34741 -244.845586)
		(end 158.34741 -244.640862)
		(width 0.14478)
		(layer "In11.Cu")
		(net "M_L_CPU1_SA_CB<3>")
	)
	(segment
		(start 174.436278 -236.850936)
		(end 177.713894 -236.850936)
		(width 0.14478)
		(layer "In11.Cu")
		(net "M_L_CPU1_SA_CB<3>")
	)
	(segment
		(start 160.486598 -242.098322)
		(end 160.486598 -241.893598)
		(width 0.14478)
		(layer "In11.Cu")
		(net "M_L_CPU1_SA_CB<3>")
	)
	(segment
		(start 148.28139 -245.440454)
		(end 157.752542 -245.440454)
		(width 0.14478)
		(layer "In11.Cu")
		(net "M_L_CPU1_SA_CB<3>")
	)
	(segment
		(start 189.532514 -236.85119)
		(end 193.157602 -236.85119)
		(width 0.14478)
		(layer "In11.Cu")
		(net "M_L_CPU1_SA_CB<3>")
	)
	(segment
		(start 160.672018 -241.708178)
		(end 160.876742 -241.708178)
		(width 0.14478)
		(layer "In11.Cu")
		(net "M_L_CPU1_SA_CB<3>")
	)
	(segment
		(start 159.517842 -243.47043)
		(end 159.722566 -243.47043)
		(width 0.14478)
		(layer "In11.Cu")
		(net "M_L_CPU1_SA_CB<3>")
	)
	(segment
		(start 141.667738 -245.78183)
		(end 141.67612 -245.777004)
		(width 0.0889)
		(layer "In11.Cu")
		(net "M_L_CPU1_SA_CB<3>")
	)
	(segment
		(start 144.843246 -245.770654)
		(end 144.863312 -245.782084)
		(width 0.0889)
		(layer "In11.Cu")
		(net "M_L_CPU1_SA_CB<3>")
	)
	(segment
		(start 158.145734 -244.439186)
		(end 158.145734 -244.234462)
		(width 0.14478)
		(layer "In11.Cu")
		(net "M_L_CPU1_SA_CB<3>")
	)
	(segment
		(start 195.996814 -237.701074)
		(end 196.846698 -236.85119)
		(width 0.14478)
		(layer "In11.Cu")
		(net "M_L_CPU1_SA_CB<3>")
	)
	(segment
		(start 185.241438 -236.85119)
		(end 186.091322 -237.701074)
		(width 0.14478)
		(layer "In11.Cu")
		(net "M_L_CPU1_SA_CB<3>")
	)
	(segment
		(start 181.85003 -236.85119)
		(end 185.241438 -236.85119)
		(width 0.14478)
		(layer "In11.Cu")
		(net "M_L_CPU1_SA_CB<3>")
	)
	(segment
		(start 143.547592 -245.78183)
		(end 143.56207 -245.773448)
		(width 0.0889)
		(layer "In11.Cu")
		(net "M_L_CPU1_SA_CB<3>")
	)
	(segment
		(start 137.940796 -245.83898)
		(end 137.963148 -245.755668)
		(width 0.0889)
		(layer "In11.Cu")
		(net "M_L_CPU1_SA_CB<3>")
	)
	(segment
		(start 171.1325 -237.70082)
		(end 173.586394 -237.70082)
		(width 0.14478)
		(layer "In11.Cu")
		(net "M_L_CPU1_SA_CB<3>")
	)
	(segment
		(start 188.68263 -237.701074)
		(end 189.532514 -236.85119)
		(width 0.14478)
		(layer "In11.Cu")
		(net "M_L_CPU1_SA_CB<3>")
	)
	(segment
		(start 160.876742 -241.708178)
		(end 161.078418 -241.909854)
		(width 0.14478)
		(layer "In11.Cu")
		(net "M_L_CPU1_SA_CB<3>")
	)
	(segment
		(start 147.59559 -245.937786)
		(end 148.092922 -245.440454)
		(width 0.0889)
		(layer "In11.Cu")
		(net "M_L_CPU1_SA_CB<3>")
	)
	(segment
		(start 158.331154 -244.049042)
		(end 158.535878 -244.049042)
		(width 0.14478)
		(layer "In11.Cu")
		(net "M_L_CPU1_SA_CB<3>")
	)
	(segment
		(start 170.292014 -236.860334)
		(end 171.1325 -237.70082)
		(width 0.14478)
		(layer "In11.Cu")
		(net "M_L_CPU1_SA_CB<3>")
	)
	(segment
		(start 138.09472 -246.10441)
		(end 137.940796 -245.83898)
		(width 0.0889)
		(layer "In11.Cu")
		(net "M_L_CPU1_SA_CB<3>")
	)
	(segment
		(start 148.092922 -245.440454)
		(end 148.28139 -245.440454)
		(width 0.0889)
		(layer "In11.Cu")
		(net "M_L_CPU1_SA_CB<3>")
	)
	(segment
		(start 159.111442 -243.268754)
		(end 159.316166 -243.268754)
		(width 0.14478)
		(layer "In11.Cu")
		(net "M_L_CPU1_SA_CB<3>")
	)
	(segment
		(start 159.907986 -243.28501)
		(end 159.907986 -243.080286)
		(width 0.14478)
		(layer "In11.Cu")
		(net "M_L_CPU1_SA_CB<3>")
	)
	(segment
		(start 186.091322 -237.701074)
		(end 188.68263 -237.701074)
		(width 0.14478)
		(layer "In11.Cu")
		(net "M_L_CPU1_SA_CB<3>")
	)
	(segment
		(start 158.535878 -244.049042)
		(end 158.737554 -244.250718)
		(width 0.14478)
		(layer "In11.Cu")
		(net "M_L_CPU1_SA_CB<3>")
	)
	(segment
		(start 161.266886 -241.318034)
		(end 161.266886 -241.11331)
		(width 0.14478)
		(layer "In11.Cu")
		(net "M_L_CPU1_SA_CB<3>")
	)
	(segment
		(start 196.846698 -236.85119)
		(end 201.713846 -236.85119)
		(width 0.14478)
		(layer "In11.Cu")
		(net "M_L_CPU1_SA_CB<3>")
	)
	(segment
		(start 173.586394 -237.70082)
		(end 174.436278 -236.850936)
		(width 0.14478)
		(layer "In11.Cu")
		(net "M_L_CPU1_SA_CB<3>")
	)
	(segment
		(start 162.06343 -241.129566)
		(end 165.482778 -237.710218)
		(width 0.14478)
		(layer "In11.Cu")
		(net "M_L_CPU1_SA_CB<3>")
	)
	(segment
		(start 158.942278 -244.250718)
		(end 159.127698 -244.065298)
		(width 0.14478)
		(layer "In11.Cu")
		(net "M_L_CPU1_SA_CB<3>")
	)
	(segment
		(start 161.65703 -240.92789)
		(end 161.858706 -241.129566)
		(width 0.14478)
		(layer "In11.Cu")
		(net "M_L_CPU1_SA_CB<3>")
	)
	(segment
		(start 193.157602 -236.85119)
		(end 194.007486 -237.701074)
		(width 0.14478)
		(layer "In11.Cu")
		(net "M_L_CPU1_SA_CB<3>")
	)
	(segment
		(start 194.007486 -237.701074)
		(end 195.996814 -237.701074)
		(width 0.14478)
		(layer "In11.Cu")
		(net "M_L_CPU1_SA_CB<3>")
	)
	(segment
		(start 165.973506 -237.710218)
		(end 166.82339 -236.860334)
		(width 0.14478)
		(layer "In11.Cu")
		(net "M_L_CPU1_SA_CB<3>")
	)
	(segment
		(start 144.466564 -245.795546)
		(end 144.489932 -245.78183)
		(width 0.0889)
		(layer "In11.Cu")
		(net "M_L_CPU1_SA_CB<3>")
	)
	(segment
		(start 160.688274 -242.504722)
		(end 160.688274 -242.299998)
		(width 0.14478)
		(layer "In11.Cu")
		(net "M_L_CPU1_SA_CB<3>")
	)
	(segment
		(start 159.127698 -244.065298)
		(end 159.127698 -243.860574)
		(width 0.14478)
		(layer "In11.Cu")
		(net "M_L_CPU1_SA_CB<3>")
	)
	(segment
		(start 181.0004 -237.70082)
		(end 181.85003 -236.85119)
		(width 0.14478)
		(layer "In11.Cu")
		(net "M_L_CPU1_SA_CB<3>")
	)
	(segment
		(start 146.34845 -245.937786)
		(end 147.59559 -245.937786)
		(width 0.0889)
		(layer "In11.Cu")
		(net "M_L_CPU1_SA_CB<3>")
	)
	(segment
		(start 159.722566 -243.47043)
		(end 159.907986 -243.28501)
		(width 0.14478)
		(layer "In11.Cu")
		(net "M_L_CPU1_SA_CB<3>")
	)
	(segment
		(start 201.713846 -236.85119)
		(end 202.147932 -237.285276)
		(width 0.14478)
		(layer "In11.Cu")
		(net "M_L_CPU1_SA_CB<3>")
	)
	(segment
		(start 140.15339 -245.777004)
		(end 140.161772 -245.78183)
		(width 0.0889)
		(layer "In11.Cu")
		(net "M_L_CPU1_SA_CB<3>")
	)
	(segment
		(start 159.127698 -243.860574)
		(end 158.926022 -243.658898)
		(width 0.14478)
		(layer "In11.Cu")
		(net "M_L_CPU1_SA_CB<3>")
	)
	(segment
		(start 158.926022 -243.658898)
		(end 158.926022 -243.454174)
		(width 0.14478)
		(layer "In11.Cu")
		(net "M_L_CPU1_SA_CB<3>")
	)
	(segment
		(start 177.713894 -236.850936)
		(end 178.563778 -237.70082)
		(width 0.14478)
		(layer "In11.Cu")
		(net "M_L_CPU1_SA_CB<3>")
	)
	(segment
		(start 161.468562 -241.724434)
		(end 161.468562 -241.51971)
		(width 0.14478)
		(layer "In11.Cu")
		(net "M_L_CPU1_SA_CB<3>")
	)
	(segment
		(start 160.096454 -242.488466)
		(end 160.29813 -242.690142)
		(width 0.14478)
		(layer "In11.Cu")
		(net "M_L_CPU1_SA_CB<3>")
	)
	(segment
		(start 165.482778 -237.710218)
		(end 165.973506 -237.710218)
		(width 0.14478)
		(layer "In11.Cu")
		(net "M_L_CPU1_SA_CB<3>")
	)
	(segment
		(start 159.316166 -243.268754)
		(end 159.517842 -243.47043)
		(width 0.14478)
		(layer "In11.Cu")
		(net "M_L_CPU1_SA_CB<3>")
	)
	(segment
		(start 157.752542 -245.440454)
		(end 158.34741 -244.845586)
		(width 0.14478)
		(layer "In11.Cu")
		(net "M_L_CPU1_SA_CB<3>")
	)
	(segment
		(start 161.283142 -241.909854)
		(end 161.468562 -241.724434)
		(width 0.14478)
		(layer "In11.Cu")
		(net "M_L_CPU1_SA_CB<3>")
	)
	(segment
		(start 146.268186 -245.857522)
		(end 146.34845 -245.937786)
		(width 0.0889)
		(layer "In11.Cu")
		(net "M_L_CPU1_SA_CB<3>")
	)
	(segment
		(start 160.502854 -242.690142)
		(end 160.688274 -242.504722)
		(width 0.14478)
		(layer "In11.Cu")
		(net "M_L_CPU1_SA_CB<3>")
	)
	(segment
		(start 161.858706 -241.129566)
		(end 162.06343 -241.129566)
		(width 0.14478)
		(layer "In11.Cu")
		(net "M_L_CPU1_SA_CB<3>")
	)
	(segment
		(start 161.452306 -240.92789)
		(end 161.65703 -240.92789)
		(width 0.14478)
		(layer "In11.Cu")
		(net "M_L_CPU1_SA_CB<3>")
	)
	(segment
		(start 160.29813 -242.690142)
		(end 160.502854 -242.690142)
		(width 0.14478)
		(layer "In11.Cu")
		(net "M_L_CPU1_SA_CB<3>")
	)
	(segment
		(start 161.078418 -241.909854)
		(end 161.283142 -241.909854)
		(width 0.14478)
		(layer "In11.Cu")
		(net "M_L_CPU1_SA_CB<3>")
	)
	(segment
		(start 178.563778 -237.70082)
		(end 181.0004 -237.70082)
		(width 0.14478)
		(layer "In11.Cu")
		(net "M_L_CPU1_SA_CB<3>")
	)
	(segment
		(start 166.82339 -236.860334)
		(end 170.292014 -236.860334)
		(width 0.14478)
		(layer "In11.Cu")
		(net "M_L_CPU1_SA_CB<3>")
	)
	(segment
		(start 160.688274 -242.299998)
		(end 160.486598 -242.098322)
		(width 0.14478)
		(layer "In11.Cu")
		(net "M_L_CPU1_SA_CB<3>")
	)
	(segment
		(start 158.737554 -244.250718)
		(end 158.942278 -244.250718)
		(width 0.14478)
		(layer "In11.Cu")
		(net "M_L_CPU1_SA_CB<3>")
	)
	(segment
		(start 158.145734 -244.234462)
		(end 158.331154 -244.049042)
		(width 0.14478)
		(layer "In11.Cu")
		(net "M_L_CPU1_SA_CB<3>")
	)
	(segment
		(start 161.266886 -241.11331)
		(end 161.452306 -240.92789)
		(width 0.14478)
		(layer "In11.Cu")
		(net "M_L_CPU1_SA_CB<3>")
	)
	(segment
		(start 141.093444 -245.777004)
		(end 141.101826 -245.78183)
		(width 0.0889)
		(layer "In11.Cu")
		(net "M_L_CPU1_SA_CB<3>")
	)
	(segment
		(start 158.34741 -244.640862)
		(end 158.145734 -244.439186)
		(width 0.14478)
		(layer "In11.Cu")
		(net "M_L_CPU1_SA_CB<3>")
	)
	(segment
		(start 161.468562 -241.51971)
		(end 161.266886 -241.318034)
		(width 0.14478)
		(layer "In11.Cu")
		(net "M_L_CPU1_SA_CB<3>")
	)
	(segment
		(start 158.926022 -243.454174)
		(end 159.111442 -243.268754)
		(width 0.14478)
		(layer "In11.Cu")
		(net "M_L_CPU1_SA_CB<3>")
	)
	(segment
		(start 159.70631 -242.673886)
		(end 159.89173 -242.488466)
		(width 0.14478)
		(layer "In11.Cu")
		(net "M_L_CPU1_SA_CB<3>")
	)
	(segment
		(start 145.144744 -245.857522)
		(end 146.268186 -245.857522)
		(width 0.0889)
		(layer "In11.Cu")
		(net "M_L_CPU1_SA_CB<3>")
	)
	(segment
		(start 159.70631 -242.87861)
		(end 159.70631 -242.673886)
		(width 0.14478)
		(layer "In11.Cu")
		(net "M_L_CPU1_SA_CB<3>")
	)
	(segment
		(start 160.486598 -241.893598)
		(end 160.672018 -241.708178)
		(width 0.14478)
		(layer "In11.Cu")
		(net "M_L_CPU1_SA_CB<3>")
	)
	(segment
		(start 159.89173 -242.488466)
		(end 160.096454 -242.488466)
		(width 0.14478)
		(layer "In11.Cu")
		(net "M_L_CPU1_SA_CB<3>")
	)
	(segment
		(start 159.907986 -243.080286)
		(end 159.70631 -242.87861)
		(width 0.14478)
		(layer "In11.Cu")
		(net "M_L_CPU1_SA_CB<3>")
	)
	(arc
		(start 139.78763 -245.78183)
		(mid 139.969881 -245.73148)
		(end 140.15339 -245.777004)
		(width 0.0889)
		(layer "In11.Cu")
		(net "M_L_CPU1_SA_CB<3>")
	)
	(arc
		(start 139.221718 -245.78183)
		(mid 139.504674 -245.858007)
		(end 139.78763 -245.78183)
		(width 0.0889)
		(layer "In11.Cu")
		(net "M_L_CPU1_SA_CB<3>")
	)
	(arc
		(start 144.863312 -245.782084)
		(mid 144.999068 -245.838292)
		(end 145.144744 -245.857522)
		(width 0.0889)
		(layer "In11.Cu")
		(net "M_L_CPU1_SA_CB<3>")
	)
	(arc
		(start 140.161772 -245.78183)
		(mid 140.444728 -245.858007)
		(end 140.727684 -245.78183)
		(width 0.0889)
		(layer "In11.Cu")
		(net "M_L_CPU1_SA_CB<3>")
	)
	(arc
		(start 141.67612 -245.777004)
		(mid 141.859628 -245.73151)
		(end 142.04188 -245.78183)
		(width 0.0889)
		(layer "In11.Cu")
		(net "M_L_CPU1_SA_CB<3>")
	)
	(arc
		(start 144.489932 -245.78183)
		(mid 144.665171 -245.731759)
		(end 144.843246 -245.770654)
		(width 0.0889)
		(layer "In11.Cu")
		(net "M_L_CPU1_SA_CB<3>")
	)
	(arc
		(start 142.04188 -245.78183)
		(mid 142.324836 -245.858007)
		(end 142.607792 -245.78183)
		(width 0.0889)
		(layer "In11.Cu")
		(net "M_L_CPU1_SA_CB<3>")
	)
	(arc
		(start 138.281918 -245.78183)
		(mid 138.564874 -245.858007)
		(end 138.84783 -245.78183)
		(width 0.0889)
		(layer "In11.Cu")
		(net "M_L_CPU1_SA_CB<3>")
	)
	(arc
		(start 143.92275 -245.78183)
		(mid 144.192907 -245.858592)
		(end 144.466564 -245.795546)
		(width 0.0889)
		(layer "In11.Cu")
		(net "M_L_CPU1_SA_CB<3>")
	)
	(arc
		(start 142.98168 -245.78183)
		(mid 143.264636 -245.858007)
		(end 143.547592 -245.78183)
		(width 0.0889)
		(layer "In11.Cu")
		(net "M_L_CPU1_SA_CB<3>")
	)
	(arc
		(start 138.84783 -245.78183)
		(mid 139.034774 -245.731575)
		(end 139.221718 -245.78183)
		(width 0.0889)
		(layer "In11.Cu")
		(net "M_L_CPU1_SA_CB<3>")
	)
	(arc
		(start 141.101826 -245.78183)
		(mid 141.384782 -245.858007)
		(end 141.667738 -245.78183)
		(width 0.0889)
		(layer "In11.Cu")
		(net "M_L_CPU1_SA_CB<3>")
	)
	(arc
		(start 137.963148 -245.755668)
		(mid 138.12548 -245.73285)
		(end 138.281918 -245.78183)
		(width 0.0889)
		(layer "In11.Cu")
		(net "M_L_CPU1_SA_CB<3>")
	)
	(arc
		(start 142.607792 -245.78183)
		(mid 142.794736 -245.731575)
		(end 142.98168 -245.78183)
		(width 0.0889)
		(layer "In11.Cu")
		(net "M_L_CPU1_SA_CB<3>")
	)
	(arc
		(start 140.727684 -245.78183)
		(mid 140.909935 -245.73148)
		(end 141.093444 -245.777004)
		(width 0.0889)
		(layer "In11.Cu")
		(net "M_L_CPU1_SA_CB<3>")
	)
	(arc
		(start 143.56207 -245.773448)
		(mid 143.743486 -245.731191)
		(end 143.92275 -245.78183)
		(width 0.0889)
		(layer "In11.Cu")
		(net "M_L_CPU1_SA_CB<3>")
	)
	(segment
		(start 139.037822 -245.560342)
		(end 139.504674 -245.294404)
		(width 0.10668)
		(layer "F.Cu")
		(net "M_L_CPU1_SA_CB<2>")
	)
	(segment
		(start 140.257784 -244.971824)
		(end 140.266166 -244.966998)
		(width 0.0889)
		(layer "In11.Cu")
		(net "M_L_CPU1_SA_CB<2>")
	)
	(segment
		(start 199.42556 -234.769406)
		(end 199.687434 -234.769406)
		(width 0.14478)
		(layer "In11.Cu")
		(net "M_L_CPU1_SA_CB<2>")
	)
	(segment
		(start 164.276278 -237.630462)
		(end 166.746428 -235.160312)
		(width 0.14478)
		(layer "In11.Cu")
		(net "M_L_CPU1_SA_CB<2>")
	)
	(segment
		(start 156.474414 -244.531134)
		(end 161.013648 -239.9919)
		(width 0.14478)
		(layer "In11.Cu")
		(net "M_L_CPU1_SA_CB<2>")
	)
	(segment
		(start 147.978622 -244.531134)
		(end 148.50745 -244.531134)
		(width 0.0889)
		(layer "In11.Cu")
		(net "M_L_CPU1_SA_CB<2>")
	)
	(segment
		(start 162.120834 -239.581182)
		(end 161.865056 -239.325404)
		(width 0.14478)
		(layer "In11.Cu")
		(net "M_L_CPU1_SA_CB<2>")
	)
	(segment
		(start 174.469552 -235.160566)
		(end 177.972466 -235.160566)
		(width 0.14478)
		(layer "In11.Cu")
		(net "M_L_CPU1_SA_CB<2>")
	)
	(segment
		(start 162.830764 -238.154972)
		(end 163.035488 -238.154972)
		(width 0.14478)
		(layer "In11.Cu")
		(net "M_L_CPU1_SA_CB<2>")
	)
	(segment
		(start 199.687434 -234.769406)
		(end 199.832214 -234.914186)
		(width 0.14478)
		(layer "In11.Cu")
		(net "M_L_CPU1_SA_CB<2>")
	)
	(segment
		(start 196.810884 -235.160566)
		(end 199.136 -235.160566)
		(width 0.14478)
		(layer "In11.Cu")
		(net "M_L_CPU1_SA_CB<2>")
	)
	(segment
		(start 163.425632 -237.560104)
		(end 163.611052 -237.374684)
		(width 0.14478)
		(layer "In11.Cu")
		(net "M_L_CPU1_SA_CB<2>")
	)
	(segment
		(start 163.611052 -237.374684)
		(end 163.815776 -237.374684)
		(width 0.14478)
		(layer "In11.Cu")
		(net "M_L_CPU1_SA_CB<2>")
	)
	(segment
		(start 173.619668 -236.01045)
		(end 174.469552 -235.160566)
		(width 0.14478)
		(layer "In11.Cu")
		(net "M_L_CPU1_SA_CB<2>")
	)
	(segment
		(start 162.901122 -238.800894)
		(end 162.645344 -238.545116)
		(width 0.14478)
		(layer "In11.Cu")
		(net "M_L_CPU1_SA_CB<2>")
	)
	(segment
		(start 163.035488 -238.154972)
		(end 163.291266 -238.41075)
		(width 0.14478)
		(layer "In11.Cu")
		(net "M_L_CPU1_SA_CB<2>")
	)
	(segment
		(start 188.673232 -236.01045)
		(end 189.523116 -235.160566)
		(width 0.14478)
		(layer "In11.Cu")
		(net "M_L_CPU1_SA_CB<2>")
	)
	(segment
		(start 139.504674 -245.294404)
		(end 139.35075 -245.028974)
		(width 0.0889)
		(layer "In11.Cu")
		(net "M_L_CPU1_SA_CB<2>")
	)
	(segment
		(start 162.510978 -239.191038)
		(end 162.715702 -239.191038)
		(width 0.14478)
		(layer "In11.Cu")
		(net "M_L_CPU1_SA_CB<2>")
	)
	(segment
		(start 177.972466 -235.160566)
		(end 178.82235 -236.01045)
		(width 0.14478)
		(layer "In11.Cu")
		(net "M_L_CPU1_SA_CB<2>")
	)
	(segment
		(start 144.016984 -244.972078)
		(end 144.0307 -244.964204)
		(width 0.0889)
		(layer "In11.Cu")
		(net "M_L_CPU1_SA_CB<2>")
	)
	(segment
		(start 162.715702 -239.191038)
		(end 162.901122 -239.005618)
		(width 0.14478)
		(layer "In11.Cu")
		(net "M_L_CPU1_SA_CB<2>")
	)
	(segment
		(start 199.832214 -235.406946)
		(end 199.976994 -235.551726)
		(width 0.14478)
		(layer "In11.Cu")
		(net "M_L_CPU1_SA_CB<2>")
	)
	(segment
		(start 199.28078 -234.914186)
		(end 199.42556 -234.769406)
		(width 0.14478)
		(layer "In11.Cu")
		(net "M_L_CPU1_SA_CB<2>")
	)
	(segment
		(start 200.935082 -235.015786)
		(end 201.079862 -235.160566)
		(width 0.14478)
		(layer "In11.Cu")
		(net "M_L_CPU1_SA_CB<2>")
	)
	(segment
		(start 145.144744 -244.921024)
		(end 145.999708 -244.921024)
		(width 0.0889)
		(layer "In11.Cu")
		(net "M_L_CPU1_SA_CB<2>")
	)
	(segment
		(start 142.503398 -244.966998)
		(end 142.51178 -244.971824)
		(width 0.0889)
		(layer "In11.Cu")
		(net "M_L_CPU1_SA_CB<2>")
	)
	(segment
		(start 178.82235 -236.01045)
		(end 180.987192 -236.01045)
		(width 0.14478)
		(layer "In11.Cu")
		(net "M_L_CPU1_SA_CB<2>")
	)
	(segment
		(start 162.050476 -238.93526)
		(end 162.2552 -238.93526)
		(width 0.14478)
		(layer "In11.Cu")
		(net "M_L_CPU1_SA_CB<2>")
	)
	(segment
		(start 163.68141 -238.22533)
		(end 163.68141 -238.020606)
		(width 0.14478)
		(layer "In11.Cu")
		(net "M_L_CPU1_SA_CB<2>")
	)
	(segment
		(start 200.935082 -234.914186)
		(end 200.935082 -235.015786)
		(width 0.14478)
		(layer "In11.Cu")
		(net "M_L_CPU1_SA_CB<2>")
	)
	(segment
		(start 164.071554 -237.630462)
		(end 164.276278 -237.630462)
		(width 0.14478)
		(layer "In11.Cu")
		(net "M_L_CPU1_SA_CB<2>")
	)
	(segment
		(start 180.987192 -236.01045)
		(end 181.837076 -235.160566)
		(width 0.14478)
		(layer "In11.Cu")
		(net "M_L_CPU1_SA_CB<2>")
	)
	(segment
		(start 199.136 -235.160566)
		(end 199.28078 -235.015786)
		(width 0.14478)
		(layer "In11.Cu")
		(net "M_L_CPU1_SA_CB<2>")
	)
	(segment
		(start 162.645344 -238.545116)
		(end 162.645344 -238.340392)
		(width 0.14478)
		(layer "In11.Cu")
		(net "M_L_CPU1_SA_CB<2>")
	)
	(segment
		(start 170.29176 -235.160312)
		(end 171.141898 -236.01045)
		(width 0.14478)
		(layer "In11.Cu")
		(net "M_L_CPU1_SA_CB<2>")
	)
	(segment
		(start 166.746428 -235.160312)
		(end 170.29176 -235.160312)
		(width 0.14478)
		(layer "In11.Cu")
		(net "M_L_CPU1_SA_CB<2>")
	)
	(segment
		(start 162.645344 -238.340392)
		(end 162.830764 -238.154972)
		(width 0.14478)
		(layer "In11.Cu")
		(net "M_L_CPU1_SA_CB<2>")
	)
	(segment
		(start 195.961 -236.01045)
		(end 196.810884 -235.160566)
		(width 0.14478)
		(layer "In11.Cu")
		(net "M_L_CPU1_SA_CB<2>")
	)
	(segment
		(start 201.723244 -235.160566)
		(end 202.147932 -235.585254)
		(width 0.14478)
		(layer "In11.Cu")
		(net "M_L_CPU1_SA_CB<2>")
	)
	(segment
		(start 192.846452 -235.160566)
		(end 193.696336 -236.01045)
		(width 0.14478)
		(layer "In11.Cu")
		(net "M_L_CPU1_SA_CB<2>")
	)
	(segment
		(start 193.696336 -236.01045)
		(end 195.961 -236.01045)
		(width 0.14478)
		(layer "In11.Cu")
		(net "M_L_CPU1_SA_CB<2>")
	)
	(segment
		(start 162.120834 -239.785906)
		(end 162.120834 -239.581182)
		(width 0.14478)
		(layer "In11.Cu")
		(net "M_L_CPU1_SA_CB<2>")
	)
	(segment
		(start 200.790302 -234.769406)
		(end 200.935082 -234.914186)
		(width 0.14478)
		(layer "In11.Cu")
		(net "M_L_CPU1_SA_CB<2>")
	)
	(segment
		(start 186.10072 -236.01045)
		(end 188.673232 -236.01045)
		(width 0.14478)
		(layer "In11.Cu")
		(net "M_L_CPU1_SA_CB<2>")
	)
	(segment
		(start 161.865056 -239.325404)
		(end 161.865056 -239.12068)
		(width 0.14478)
		(layer "In11.Cu")
		(net "M_L_CPU1_SA_CB<2>")
	)
	(segment
		(start 185.250836 -235.160566)
		(end 186.10072 -236.01045)
		(width 0.14478)
		(layer "In11.Cu")
		(net "M_L_CPU1_SA_CB<2>")
	)
	(segment
		(start 200.528428 -234.769406)
		(end 200.790302 -234.769406)
		(width 0.14478)
		(layer "In11.Cu")
		(net "M_L_CPU1_SA_CB<2>")
	)
	(segment
		(start 162.2552 -238.93526)
		(end 162.510978 -239.191038)
		(width 0.14478)
		(layer "In11.Cu")
		(net "M_L_CPU1_SA_CB<2>")
	)
	(segment
		(start 201.079862 -235.160566)
		(end 201.723244 -235.160566)
		(width 0.14478)
		(layer "In11.Cu")
		(net "M_L_CPU1_SA_CB<2>")
	)
	(segment
		(start 181.837076 -235.160566)
		(end 185.250836 -235.160566)
		(width 0.14478)
		(layer "In11.Cu")
		(net "M_L_CPU1_SA_CB<2>")
	)
	(segment
		(start 139.35075 -245.028974)
		(end 139.373102 -244.945662)
		(width 0.0889)
		(layer "In11.Cu")
		(net "M_L_CPU1_SA_CB<2>")
	)
	(segment
		(start 189.523116 -235.160566)
		(end 192.846452 -235.160566)
		(width 0.14478)
		(layer "In11.Cu")
		(net "M_L_CPU1_SA_CB<2>")
	)
	(segment
		(start 200.238868 -235.551726)
		(end 200.383648 -235.406946)
		(width 0.14478)
		(layer "In11.Cu")
		(net "M_L_CPU1_SA_CB<2>")
	)
	(segment
		(start 163.49599 -238.41075)
		(end 163.68141 -238.22533)
		(width 0.14478)
		(layer "In11.Cu")
		(net "M_L_CPU1_SA_CB<2>")
	)
	(segment
		(start 199.832214 -234.914186)
		(end 199.832214 -235.406946)
		(width 0.14478)
		(layer "In11.Cu")
		(net "M_L_CPU1_SA_CB<2>")
	)
	(segment
		(start 200.383648 -234.914186)
		(end 200.528428 -234.769406)
		(width 0.14478)
		(layer "In11.Cu")
		(net "M_L_CPU1_SA_CB<2>")
	)
	(segment
		(start 147.20443 -245.305326)
		(end 147.978622 -244.531134)
		(width 0.0889)
		(layer "In11.Cu")
		(net "M_L_CPU1_SA_CB<2>")
	)
	(segment
		(start 145.999708 -244.921024)
		(end 146.38401 -245.305326)
		(width 0.0889)
		(layer "In11.Cu")
		(net "M_L_CPU1_SA_CB<2>")
	)
	(segment
		(start 163.68141 -238.020606)
		(end 163.425632 -237.764828)
		(width 0.14478)
		(layer "In11.Cu")
		(net "M_L_CPU1_SA_CB<2>")
	)
	(segment
		(start 163.815776 -237.374684)
		(end 164.071554 -237.630462)
		(width 0.14478)
		(layer "In11.Cu")
		(net "M_L_CPU1_SA_CB<2>")
	)
	(segment
		(start 171.141898 -236.01045)
		(end 173.619668 -236.01045)
		(width 0.14478)
		(layer "In11.Cu")
		(net "M_L_CPU1_SA_CB<2>")
	)
	(segment
		(start 199.976994 -235.551726)
		(end 200.238868 -235.551726)
		(width 0.14478)
		(layer "In11.Cu")
		(net "M_L_CPU1_SA_CB<2>")
	)
	(segment
		(start 148.50745 -244.531134)
		(end 156.474414 -244.531134)
		(width 0.14478)
		(layer "In11.Cu")
		(net "M_L_CPU1_SA_CB<2>")
	)
	(segment
		(start 143.077692 -244.971824)
		(end 143.086074 -244.966998)
		(width 0.0889)
		(layer "In11.Cu")
		(net "M_L_CPU1_SA_CB<2>")
	)
	(segment
		(start 161.013648 -239.9919)
		(end 161.91484 -239.9919)
		(width 0.14478)
		(layer "In11.Cu")
		(net "M_L_CPU1_SA_CB<2>")
	)
	(segment
		(start 200.383648 -235.406946)
		(end 200.383648 -234.914186)
		(width 0.14478)
		(layer "In11.Cu")
		(net "M_L_CPU1_SA_CB<2>")
	)
	(segment
		(start 163.291266 -238.41075)
		(end 163.49599 -238.41075)
		(width 0.14478)
		(layer "In11.Cu")
		(net "M_L_CPU1_SA_CB<2>")
	)
	(segment
		(start 199.28078 -235.015786)
		(end 199.28078 -234.914186)
		(width 0.14478)
		(layer "In11.Cu")
		(net "M_L_CPU1_SA_CB<2>")
	)
	(segment
		(start 162.901122 -239.005618)
		(end 162.901122 -238.800894)
		(width 0.14478)
		(layer "In11.Cu")
		(net "M_L_CPU1_SA_CB<2>")
	)
	(segment
		(start 161.865056 -239.12068)
		(end 162.050476 -238.93526)
		(width 0.14478)
		(layer "In11.Cu")
		(net "M_L_CPU1_SA_CB<2>")
	)
	(segment
		(start 144.390618 -244.971824)
		(end 144.408652 -244.982492)
		(width 0.0889)
		(layer "In11.Cu")
		(net "M_L_CPU1_SA_CB<2>")
	)
	(segment
		(start 144.005046 -244.978936)
		(end 144.016984 -244.972078)
		(width 0.0889)
		(layer "In11.Cu")
		(net "M_L_CPU1_SA_CB<2>")
	)
	(segment
		(start 163.425632 -237.764828)
		(end 163.425632 -237.560104)
		(width 0.14478)
		(layer "In11.Cu")
		(net "M_L_CPU1_SA_CB<2>")
	)
	(segment
		(start 161.91484 -239.9919)
		(end 162.120834 -239.785906)
		(width 0.14478)
		(layer "In11.Cu")
		(net "M_L_CPU1_SA_CB<2>")
	)
	(segment
		(start 146.38401 -245.305326)
		(end 147.20443 -245.305326)
		(width 0.0889)
		(layer "In11.Cu")
		(net "M_L_CPU1_SA_CB<2>")
	)
	(arc
		(start 141.571726 -244.971824)
		(mid 141.854682 -245.048001)
		(end 142.137638 -244.971824)
		(width 0.0889)
		(layer "In11.Cu")
		(net "M_L_CPU1_SA_CB<2>")
	)
	(arc
		(start 143.086074 -244.966998)
		(mid 143.269582 -244.921504)
		(end 143.451834 -244.971824)
		(width 0.0889)
		(layer "In11.Cu")
		(net "M_L_CPU1_SA_CB<2>")
	)
	(arc
		(start 141.197838 -244.971824)
		(mid 141.384782 -244.921569)
		(end 141.571726 -244.971824)
		(width 0.0889)
		(layer "In11.Cu")
		(net "M_L_CPU1_SA_CB<2>")
	)
	(arc
		(start 142.137638 -244.971824)
		(mid 142.319889 -244.921474)
		(end 142.503398 -244.966998)
		(width 0.0889)
		(layer "In11.Cu")
		(net "M_L_CPU1_SA_CB<2>")
	)
	(arc
		(start 139.373102 -244.945662)
		(mid 139.535434 -244.922844)
		(end 139.691872 -244.971824)
		(width 0.0889)
		(layer "In11.Cu")
		(net "M_L_CPU1_SA_CB<2>")
	)
	(arc
		(start 139.691872 -244.971824)
		(mid 139.974828 -245.048001)
		(end 140.257784 -244.971824)
		(width 0.0889)
		(layer "In11.Cu")
		(net "M_L_CPU1_SA_CB<2>")
	)
	(arc
		(start 144.0307 -244.964204)
		(mid 144.21163 -244.921726)
		(end 144.390618 -244.971824)
		(width 0.0889)
		(layer "In11.Cu")
		(net "M_L_CPU1_SA_CB<2>")
	)
	(arc
		(start 144.957292 -244.971824)
		(mid 145.047655 -244.934014)
		(end 145.144744 -244.921024)
		(width 0.0889)
		(layer "In11.Cu")
		(net "M_L_CPU1_SA_CB<2>")
	)
	(arc
		(start 140.266166 -244.966998)
		(mid 140.449674 -244.921504)
		(end 140.631926 -244.971824)
		(width 0.0889)
		(layer "In11.Cu")
		(net "M_L_CPU1_SA_CB<2>")
	)
	(arc
		(start 140.631926 -244.971824)
		(mid 140.914882 -245.048001)
		(end 141.197838 -244.971824)
		(width 0.0889)
		(layer "In11.Cu")
		(net "M_L_CPU1_SA_CB<2>")
	)
	(arc
		(start 142.51178 -244.971824)
		(mid 142.794736 -245.048001)
		(end 143.077692 -244.971824)
		(width 0.0889)
		(layer "In11.Cu")
		(net "M_L_CPU1_SA_CB<2>")
	)
	(arc
		(start 143.451834 -244.971824)
		(mid 143.727512 -245.047954)
		(end 144.005046 -244.978936)
		(width 0.0889)
		(layer "In11.Cu")
		(net "M_L_CPU1_SA_CB<2>")
	)
	(arc
		(start 144.408652 -244.982492)
		(mid 144.684347 -245.048335)
		(end 144.957292 -244.971824)
		(width 0.0889)
		(layer "In11.Cu")
		(net "M_L_CPU1_SA_CB<2>")
	)
	(segment
		(start 137.157968 -245.560342)
		(end 137.62482 -245.294404)
		(width 0.10668)
		(layer "F.Cu")
		(net "M_L_CPU1_SA_CB<1>")
	)
	(segment
		(start 175.059086 -236.01045)
		(end 177.309526 -236.01045)
		(width 0.14478)
		(layer "In11.Cu")
		(net "M_L_CPU1_SA_CB<1>")
	)
	(segment
		(start 197.461632 -236.01045)
		(end 202.777852 -236.01045)
		(width 0.14478)
		(layer "In11.Cu")
		(net "M_L_CPU1_SA_CB<1>")
	)
	(segment
		(start 144.936972 -245.604284)
		(end 144.958562 -245.61673)
		(width 0.0889)
		(layer "In11.Cu")
		(net "M_L_CPU1_SA_CB<1>")
	)
	(segment
		(start 186.87542 -236.860334)
		(end 188.039756 -236.860334)
		(width 0.14478)
		(layer "In11.Cu")
		(net "M_L_CPU1_SA_CB<1>")
	)
	(segment
		(start 144.379696 -245.625366)
		(end 144.394174 -245.616984)
		(width 0.0889)
		(layer "In11.Cu")
		(net "M_L_CPU1_SA_CB<1>")
	)
	(segment
		(start 148.25091 -244.985794)
		(end 156.662882 -244.985794)
		(width 0.14478)
		(layer "In11.Cu")
		(net "M_L_CPU1_SA_CB<1>")
	)
	(segment
		(start 137.62482 -245.294404)
		(end 137.778744 -245.559834)
		(width 0.0889)
		(layer "In11.Cu")
		(net "M_L_CPU1_SA_CB<1>")
	)
	(segment
		(start 137.778744 -245.559834)
		(end 137.874756 -245.585234)
		(width 0.0889)
		(layer "In11.Cu")
		(net "M_L_CPU1_SA_CB<1>")
	)
	(segment
		(start 188.039756 -236.860334)
		(end 190.091568 -236.01045)
		(width 0.14478)
		(layer "In11.Cu")
		(net "M_L_CPU1_SA_CB<1>")
	)
	(segment
		(start 161.202116 -240.44656)
		(end 162.103308 -240.44656)
		(width 0.14478)
		(layer "In11.Cu")
		(net "M_L_CPU1_SA_CB<1>")
	)
	(segment
		(start 173.007274 -236.860334)
		(end 175.059086 -236.01045)
		(width 0.14478)
		(layer "In11.Cu")
		(net "M_L_CPU1_SA_CB<1>")
	)
	(segment
		(start 171.776898 -236.860334)
		(end 173.007274 -236.860334)
		(width 0.14478)
		(layer "In11.Cu")
		(net "M_L_CPU1_SA_CB<1>")
	)
	(segment
		(start 195.40982 -236.860334)
		(end 197.461632 -236.01045)
		(width 0.14478)
		(layer "In11.Cu")
		(net "M_L_CPU1_SA_CB<1>")
	)
	(segment
		(start 145.144998 -245.667022)
		(end 147.327874 -245.667022)
		(width 0.0889)
		(layer "In11.Cu")
		(net "M_L_CPU1_SA_CB<1>")
	)
	(segment
		(start 177.309526 -236.01045)
		(end 179.361338 -236.860334)
		(width 0.14478)
		(layer "In11.Cu")
		(net "M_L_CPU1_SA_CB<1>")
	)
	(segment
		(start 143.451834 -245.616984)
		(end 143.475202 -245.603268)
		(width 0.0889)
		(layer "In11.Cu")
		(net "M_L_CPU1_SA_CB<1>")
	)
	(segment
		(start 169.725086 -236.01045)
		(end 171.776898 -236.860334)
		(width 0.14478)
		(layer "In11.Cu")
		(net "M_L_CPU1_SA_CB<1>")
	)
	(segment
		(start 182.420768 -236.01045)
		(end 184.823608 -236.01045)
		(width 0.14478)
		(layer "In11.Cu")
		(net "M_L_CPU1_SA_CB<1>")
	)
	(segment
		(start 167.606726 -236.01045)
		(end 169.725086 -236.01045)
		(width 0.14478)
		(layer "In11.Cu")
		(net "M_L_CPU1_SA_CB<1>")
	)
	(segment
		(start 184.823608 -236.01045)
		(end 186.87542 -236.860334)
		(width 0.14478)
		(layer "In11.Cu")
		(net "M_L_CPU1_SA_CB<1>")
	)
	(segment
		(start 204.111606 -236.01045)
		(end 206.248 -236.435392)
		(width 0.14478)
		(layer "In11.Cu")
		(net "M_L_CPU1_SA_CB<1>")
	)
	(segment
		(start 203.067412 -236.565186)
		(end 203.329286 -236.565186)
		(width 0.14478)
		(layer "In11.Cu")
		(net "M_L_CPU1_SA_CB<1>")
	)
	(segment
		(start 203.474066 -236.420406)
		(end 203.474066 -236.15523)
		(width 0.14478)
		(layer "In11.Cu")
		(net "M_L_CPU1_SA_CB<1>")
	)
	(segment
		(start 138.743436 -245.62181)
		(end 138.751818 -245.616984)
		(width 0.0889)
		(layer "In11.Cu")
		(net "M_L_CPU1_SA_CB<1>")
	)
	(segment
		(start 148.009102 -244.985794)
		(end 148.25091 -244.985794)
		(width 0.0889)
		(layer "In11.Cu")
		(net "M_L_CPU1_SA_CB<1>")
	)
	(segment
		(start 139.31773 -245.616984)
		(end 139.326112 -245.62181)
		(width 0.0889)
		(layer "In11.Cu")
		(net "M_L_CPU1_SA_CB<1>")
	)
	(segment
		(start 202.777852 -236.01045)
		(end 202.922632 -236.15523)
		(width 0.14478)
		(layer "In11.Cu")
		(net "M_L_CPU1_SA_CB<1>")
	)
	(segment
		(start 190.091568 -236.01045)
		(end 192.403476 -236.01045)
		(width 0.14478)
		(layer "In11.Cu")
		(net "M_L_CPU1_SA_CB<1>")
	)
	(segment
		(start 162.103308 -240.44656)
		(end 165.784784 -236.765084)
		(width 0.14478)
		(layer "In11.Cu")
		(net "M_L_CPU1_SA_CB<1>")
	)
	(segment
		(start 179.361338 -236.860334)
		(end 180.368956 -236.860334)
		(width 0.14478)
		(layer "In11.Cu")
		(net "M_L_CPU1_SA_CB<1>")
	)
	(segment
		(start 147.327874 -245.667022)
		(end 148.009102 -244.985794)
		(width 0.0889)
		(layer "In11.Cu")
		(net "M_L_CPU1_SA_CB<1>")
	)
	(segment
		(start 203.618846 -236.01045)
		(end 204.111606 -236.01045)
		(width 0.14478)
		(layer "In11.Cu")
		(net "M_L_CPU1_SA_CB<1>")
	)
	(segment
		(start 140.257784 -245.616984)
		(end 140.266166 -245.62181)
		(width 0.0889)
		(layer "In11.Cu")
		(net "M_L_CPU1_SA_CB<1>")
	)
	(segment
		(start 203.329286 -236.565186)
		(end 203.474066 -236.420406)
		(width 0.14478)
		(layer "In11.Cu")
		(net "M_L_CPU1_SA_CB<1>")
	)
	(segment
		(start 194.455288 -236.860334)
		(end 195.40982 -236.860334)
		(width 0.14478)
		(layer "In11.Cu")
		(net "M_L_CPU1_SA_CB<1>")
	)
	(segment
		(start 180.368956 -236.860334)
		(end 182.420768 -236.01045)
		(width 0.14478)
		(layer "In11.Cu")
		(net "M_L_CPU1_SA_CB<1>")
	)
	(segment
		(start 202.922632 -236.420406)
		(end 203.067412 -236.565186)
		(width 0.14478)
		(layer "In11.Cu")
		(net "M_L_CPU1_SA_CB<1>")
	)
	(segment
		(start 203.474066 -236.15523)
		(end 203.618846 -236.01045)
		(width 0.14478)
		(layer "In11.Cu")
		(net "M_L_CPU1_SA_CB<1>")
	)
	(segment
		(start 202.922632 -236.15523)
		(end 202.922632 -236.420406)
		(width 0.14478)
		(layer "In11.Cu")
		(net "M_L_CPU1_SA_CB<1>")
	)
	(segment
		(start 143.077692 -245.616984)
		(end 143.086074 -245.62181)
		(width 0.0889)
		(layer "In11.Cu")
		(net "M_L_CPU1_SA_CB<1>")
	)
	(segment
		(start 142.503398 -245.62181)
		(end 142.51178 -245.616984)
		(width 0.0889)
		(layer "In11.Cu")
		(net "M_L_CPU1_SA_CB<1>")
	)
	(segment
		(start 165.784784 -236.765084)
		(end 167.606726 -236.01045)
		(width 0.14478)
		(layer "In11.Cu")
		(net "M_L_CPU1_SA_CB<1>")
	)
	(segment
		(start 156.662882 -244.985794)
		(end 161.202116 -240.44656)
		(width 0.14478)
		(layer "In11.Cu")
		(net "M_L_CPU1_SA_CB<1>")
	)
	(segment
		(start 192.403476 -236.01045)
		(end 194.455288 -236.860334)
		(width 0.14478)
		(layer "In11.Cu")
		(net "M_L_CPU1_SA_CB<1>")
	)
	(arc
		(start 139.326112 -245.62181)
		(mid 139.50962 -245.667304)
		(end 139.691872 -245.616984)
		(width 0.0889)
		(layer "In11.Cu")
		(net "M_L_CPU1_SA_CB<1>")
	)
	(arc
		(start 144.019016 -245.616984)
		(mid 144.198279 -245.667648)
		(end 144.379696 -245.625366)
		(width 0.0889)
		(layer "In11.Cu")
		(net "M_L_CPU1_SA_CB<1>")
	)
	(arc
		(start 144.958562 -245.61673)
		(mid 145.048461 -245.654187)
		(end 145.144998 -245.667022)
		(width 0.0889)
		(layer "In11.Cu")
		(net "M_L_CPU1_SA_CB<1>")
	)
	(arc
		(start 137.874756 -245.585234)
		(mid 138.129964 -245.541757)
		(end 138.377676 -245.616984)
		(width 0.0889)
		(layer "In11.Cu")
		(net "M_L_CPU1_SA_CB<1>")
	)
	(arc
		(start 141.197838 -245.616984)
		(mid 141.384782 -245.667239)
		(end 141.571726 -245.616984)
		(width 0.0889)
		(layer "In11.Cu")
		(net "M_L_CPU1_SA_CB<1>")
	)
	(arc
		(start 144.394174 -245.616984)
		(mid 144.663943 -245.540961)
		(end 144.936972 -245.604284)
		(width 0.0889)
		(layer "In11.Cu")
		(net "M_L_CPU1_SA_CB<1>")
	)
	(arc
		(start 142.137638 -245.616984)
		(mid 142.319889 -245.667334)
		(end 142.503398 -245.62181)
		(width 0.0889)
		(layer "In11.Cu")
		(net "M_L_CPU1_SA_CB<1>")
	)
	(arc
		(start 138.751818 -245.616984)
		(mid 139.034774 -245.540807)
		(end 139.31773 -245.616984)
		(width 0.0889)
		(layer "In11.Cu")
		(net "M_L_CPU1_SA_CB<1>")
	)
	(arc
		(start 141.571726 -245.616984)
		(mid 141.854682 -245.540807)
		(end 142.137638 -245.616984)
		(width 0.0889)
		(layer "In11.Cu")
		(net "M_L_CPU1_SA_CB<1>")
	)
	(arc
		(start 140.266166 -245.62181)
		(mid 140.449674 -245.667304)
		(end 140.631926 -245.616984)
		(width 0.0889)
		(layer "In11.Cu")
		(net "M_L_CPU1_SA_CB<1>")
	)
	(arc
		(start 142.51178 -245.616984)
		(mid 142.794736 -245.540807)
		(end 143.077692 -245.616984)
		(width 0.0889)
		(layer "In11.Cu")
		(net "M_L_CPU1_SA_CB<1>")
	)
	(arc
		(start 138.377676 -245.616984)
		(mid 138.559927 -245.667334)
		(end 138.743436 -245.62181)
		(width 0.0889)
		(layer "In11.Cu")
		(net "M_L_CPU1_SA_CB<1>")
	)
	(arc
		(start 143.086074 -245.62181)
		(mid 143.269582 -245.667304)
		(end 143.451834 -245.616984)
		(width 0.0889)
		(layer "In11.Cu")
		(net "M_L_CPU1_SA_CB<1>")
	)
	(arc
		(start 139.691872 -245.616984)
		(mid 139.974828 -245.540807)
		(end 140.257784 -245.616984)
		(width 0.0889)
		(layer "In11.Cu")
		(net "M_L_CPU1_SA_CB<1>")
	)
	(arc
		(start 143.475202 -245.603268)
		(mid 143.748856 -245.540325)
		(end 144.019016 -245.616984)
		(width 0.0889)
		(layer "In11.Cu")
		(net "M_L_CPU1_SA_CB<1>")
	)
	(arc
		(start 140.631926 -245.616984)
		(mid 140.914882 -245.540807)
		(end 141.197838 -245.616984)
		(width 0.0889)
		(layer "In11.Cu")
		(net "M_L_CPU1_SA_CB<1>")
	)
	(segment
		(start 138.567922 -244.750336)
		(end 139.034774 -244.484398)
		(width 0.10668)
		(layer "F.Cu")
		(net "M_L_CPU1_SA_CB<0>")
	)
	(segment
		(start 146.93519 -245.114826)
		(end 147.973542 -244.076474)
		(width 0.0889)
		(layer "In11.Cu")
		(net "M_L_CPU1_SA_CB<0>")
	)
	(segment
		(start 182.4609 -234.310428)
		(end 185.311796 -234.310428)
		(width 0.14478)
		(layer "In11.Cu")
		(net "M_L_CPU1_SA_CB<0>")
	)
	(segment
		(start 145.144744 -244.730524)
		(end 146.078702 -244.730524)
		(width 0.0889)
		(layer "In11.Cu")
		(net "M_L_CPU1_SA_CB<0>")
	)
	(segment
		(start 156.175456 -244.076474)
		(end 165.12667 -235.12526)
		(width 0.14478)
		(layer "In11.Cu")
		(net "M_L_CPU1_SA_CB<0>")
	)
	(segment
		(start 165.12667 -235.12526)
		(end 167.094154 -234.310428)
		(width 0.14478)
		(layer "In11.Cu")
		(net "M_L_CPU1_SA_CB<0>")
	)
	(segment
		(start 144.48663 -244.806978)
		(end 144.498314 -244.813836)
		(width 0.0889)
		(layer "In11.Cu")
		(net "M_L_CPU1_SA_CB<0>")
	)
	(segment
		(start 195.979796 -235.160312)
		(end 196.82968 -234.310428)
		(width 0.14478)
		(layer "In11.Cu")
		(net "M_L_CPU1_SA_CB<0>")
	)
	(segment
		(start 188.746384 -235.160312)
		(end 189.596268 -234.310428)
		(width 0.14478)
		(layer "In11.Cu")
		(net "M_L_CPU1_SA_CB<0>")
	)
	(segment
		(start 205.823058 -234.310428)
		(end 206.248 -234.73537)
		(width 0.14478)
		(layer "In11.Cu")
		(net "M_L_CPU1_SA_CB<0>")
	)
	(segment
		(start 203.585826 -234.865926)
		(end 203.585826 -234.455208)
		(width 0.14478)
		(layer "In11.Cu")
		(net "M_L_CPU1_SA_CB<0>")
	)
	(segment
		(start 140.15339 -244.811804)
		(end 140.161772 -244.806978)
		(width 0.0889)
		(layer "In11.Cu")
		(net "M_L_CPU1_SA_CB<0>")
	)
	(segment
		(start 175.201072 -234.310428)
		(end 177.317146 -234.310428)
		(width 0.14478)
		(layer "In11.Cu")
		(net "M_L_CPU1_SA_CB<0>")
	)
	(segment
		(start 148.40839 -244.076474)
		(end 156.175456 -244.076474)
		(width 0.14478)
		(layer "In11.Cu")
		(net "M_L_CPU1_SA_CB<0>")
	)
	(segment
		(start 139.034774 -244.484398)
		(end 139.188698 -244.749828)
		(width 0.0889)
		(layer "In11.Cu")
		(net "M_L_CPU1_SA_CB<0>")
	)
	(segment
		(start 146.463004 -245.114826)
		(end 146.93519 -245.114826)
		(width 0.0889)
		(layer "In11.Cu")
		(net "M_L_CPU1_SA_CB<0>")
	)
	(segment
		(start 203.034392 -234.455208)
		(end 203.034392 -234.865926)
		(width 0.14478)
		(layer "In11.Cu")
		(net "M_L_CPU1_SA_CB<0>")
	)
	(segment
		(start 177.317146 -234.310428)
		(end 179.368958 -235.160312)
		(width 0.14478)
		(layer "In11.Cu")
		(net "M_L_CPU1_SA_CB<0>")
	)
	(segment
		(start 180.409088 -235.160312)
		(end 182.4609 -234.310428)
		(width 0.14478)
		(layer "In11.Cu")
		(net "M_L_CPU1_SA_CB<0>")
	)
	(segment
		(start 192.728596 -234.310428)
		(end 193.57848 -235.160312)
		(width 0.14478)
		(layer "In11.Cu")
		(net "M_L_CPU1_SA_CB<0>")
	)
	(segment
		(start 203.179172 -235.010706)
		(end 203.441046 -235.010706)
		(width 0.14478)
		(layer "In11.Cu")
		(net "M_L_CPU1_SA_CB<0>")
	)
	(segment
		(start 193.57848 -235.160312)
		(end 195.979796 -235.160312)
		(width 0.14478)
		(layer "In11.Cu")
		(net "M_L_CPU1_SA_CB<0>")
	)
	(segment
		(start 173.14926 -235.160312)
		(end 175.201072 -234.310428)
		(width 0.14478)
		(layer "In11.Cu")
		(net "M_L_CPU1_SA_CB<0>")
	)
	(segment
		(start 139.188698 -244.749828)
		(end 139.28471 -244.775228)
		(width 0.0889)
		(layer "In11.Cu")
		(net "M_L_CPU1_SA_CB<0>")
	)
	(segment
		(start 202.889612 -234.310428)
		(end 203.034392 -234.455208)
		(width 0.14478)
		(layer "In11.Cu")
		(net "M_L_CPU1_SA_CB<0>")
	)
	(segment
		(start 147.973542 -244.076474)
		(end 148.40839 -244.076474)
		(width 0.0889)
		(layer "In11.Cu")
		(net "M_L_CPU1_SA_CB<0>")
	)
	(segment
		(start 143.92148 -244.806724)
		(end 143.933418 -244.799866)
		(width 0.0889)
		(layer "In11.Cu")
		(net "M_L_CPU1_SA_CB<0>")
	)
	(segment
		(start 203.730606 -234.310428)
		(end 205.823058 -234.310428)
		(width 0.14478)
		(layer "In11.Cu")
		(net "M_L_CPU1_SA_CB<0>")
	)
	(segment
		(start 189.596268 -234.310428)
		(end 192.728596 -234.310428)
		(width 0.14478)
		(layer "In11.Cu")
		(net "M_L_CPU1_SA_CB<0>")
	)
	(segment
		(start 169.43705 -234.310428)
		(end 171.488862 -235.160312)
		(width 0.14478)
		(layer "In11.Cu")
		(net "M_L_CPU1_SA_CB<0>")
	)
	(segment
		(start 141.667738 -244.806978)
		(end 141.67612 -244.811804)
		(width 0.0889)
		(layer "In11.Cu")
		(net "M_L_CPU1_SA_CB<0>")
	)
	(segment
		(start 146.078702 -244.730524)
		(end 146.463004 -245.114826)
		(width 0.0889)
		(layer "In11.Cu")
		(net "M_L_CPU1_SA_CB<0>")
	)
	(segment
		(start 203.441046 -235.010706)
		(end 203.585826 -234.865926)
		(width 0.14478)
		(layer "In11.Cu")
		(net "M_L_CPU1_SA_CB<0>")
	)
	(segment
		(start 185.311796 -234.310428)
		(end 186.16168 -235.160312)
		(width 0.14478)
		(layer "In11.Cu")
		(net "M_L_CPU1_SA_CB<0>")
	)
	(segment
		(start 141.093444 -244.811804)
		(end 141.101826 -244.806978)
		(width 0.0889)
		(layer "In11.Cu")
		(net "M_L_CPU1_SA_CB<0>")
	)
	(segment
		(start 203.034392 -234.865926)
		(end 203.179172 -235.010706)
		(width 0.14478)
		(layer "In11.Cu")
		(net "M_L_CPU1_SA_CB<0>")
	)
	(segment
		(start 186.16168 -235.160312)
		(end 188.746384 -235.160312)
		(width 0.14478)
		(layer "In11.Cu")
		(net "M_L_CPU1_SA_CB<0>")
	)
	(segment
		(start 171.488862 -235.160312)
		(end 173.14926 -235.160312)
		(width 0.14478)
		(layer "In11.Cu")
		(net "M_L_CPU1_SA_CB<0>")
	)
	(segment
		(start 143.905224 -244.816122)
		(end 143.92148 -244.806724)
		(width 0.0889)
		(layer "In11.Cu")
		(net "M_L_CPU1_SA_CB<0>")
	)
	(segment
		(start 179.368958 -235.160312)
		(end 180.409088 -235.160312)
		(width 0.14478)
		(layer "In11.Cu")
		(net "M_L_CPU1_SA_CB<0>")
	)
	(segment
		(start 203.585826 -234.455208)
		(end 203.730606 -234.310428)
		(width 0.14478)
		(layer "In11.Cu")
		(net "M_L_CPU1_SA_CB<0>")
	)
	(segment
		(start 167.094154 -234.310428)
		(end 169.43705 -234.310428)
		(width 0.14478)
		(layer "In11.Cu")
		(net "M_L_CPU1_SA_CB<0>")
	)
	(segment
		(start 196.82968 -234.310428)
		(end 202.889612 -234.310428)
		(width 0.14478)
		(layer "In11.Cu")
		(net "M_L_CPU1_SA_CB<0>")
	)
	(arc
		(start 140.727684 -244.806978)
		(mid 140.909935 -244.857328)
		(end 141.093444 -244.811804)
		(width 0.0889)
		(layer "In11.Cu")
		(net "M_L_CPU1_SA_CB<0>")
	)
	(arc
		(start 143.547592 -244.806978)
		(mid 143.725242 -244.857238)
		(end 143.905224 -244.816122)
		(width 0.0889)
		(layer "In11.Cu")
		(net "M_L_CPU1_SA_CB<0>")
	)
	(arc
		(start 143.933418 -244.799866)
		(mid 144.210952 -244.730885)
		(end 144.48663 -244.806978)
		(width 0.0889)
		(layer "In11.Cu")
		(net "M_L_CPU1_SA_CB<0>")
	)
	(arc
		(start 139.28471 -244.775228)
		(mid 139.539918 -244.731751)
		(end 139.78763 -244.806978)
		(width 0.0889)
		(layer "In11.Cu")
		(net "M_L_CPU1_SA_CB<0>")
	)
	(arc
		(start 140.161772 -244.806978)
		(mid 140.444728 -244.730801)
		(end 140.727684 -244.806978)
		(width 0.0889)
		(layer "In11.Cu")
		(net "M_L_CPU1_SA_CB<0>")
	)
	(arc
		(start 144.861026 -244.806978)
		(mid 144.997819 -244.749956)
		(end 145.144744 -244.730524)
		(width 0.0889)
		(layer "In11.Cu")
		(net "M_L_CPU1_SA_CB<0>")
	)
	(arc
		(start 142.04188 -244.806978)
		(mid 142.324836 -244.730801)
		(end 142.607792 -244.806978)
		(width 0.0889)
		(layer "In11.Cu")
		(net "M_L_CPU1_SA_CB<0>")
	)
	(arc
		(start 139.78763 -244.806978)
		(mid 139.969881 -244.857328)
		(end 140.15339 -244.811804)
		(width 0.0889)
		(layer "In11.Cu")
		(net "M_L_CPU1_SA_CB<0>")
	)
	(arc
		(start 142.607792 -244.806978)
		(mid 142.794736 -244.857233)
		(end 142.98168 -244.806978)
		(width 0.0889)
		(layer "In11.Cu")
		(net "M_L_CPU1_SA_CB<0>")
	)
	(arc
		(start 144.498314 -244.813836)
		(mid 144.680569 -244.857489)
		(end 144.861026 -244.806978)
		(width 0.0889)
		(layer "In11.Cu")
		(net "M_L_CPU1_SA_CB<0>")
	)
	(arc
		(start 141.67612 -244.811804)
		(mid 141.859628 -244.857298)
		(end 142.04188 -244.806978)
		(width 0.0889)
		(layer "In11.Cu")
		(net "M_L_CPU1_SA_CB<0>")
	)
	(arc
		(start 142.98168 -244.806978)
		(mid 143.264636 -244.730801)
		(end 143.547592 -244.806978)
		(width 0.0889)
		(layer "In11.Cu")
		(net "M_L_CPU1_SA_CB<0>")
	)
	(arc
		(start 141.101826 -244.806978)
		(mid 141.384782 -244.730801)
		(end 141.667738 -244.806978)
		(width 0.0889)
		(layer "In11.Cu")
		(net "M_L_CPU1_SA_CB<0>")
	)
	(segment
		(start 137.157968 -255.280414)
		(end 137.62482 -255.014476)
		(width 0.10668)
		(layer "F.Cu")
		(net "M_L_CPU1_SA_CA<6>")
	)
	(segment
		(start 147.267422 -256.097278)
		(end 147.808188 -256.097278)
		(width 0.0889)
		(layer "In11.Cu")
		(net "M_L_CPU1_SA_CA<6>")
	)
	(segment
		(start 140.257784 -255.337056)
		(end 140.266166 -255.341882)
		(width 0.0889)
		(layer "In11.Cu")
		(net "M_L_CPU1_SA_CA<6>")
	)
	(segment
		(start 138.743436 -255.341882)
		(end 138.751818 -255.337056)
		(width 0.0889)
		(layer "In11.Cu")
		(net "M_L_CPU1_SA_CA<6>")
	)
	(segment
		(start 144.38376 -255.341882)
		(end 144.392142 -255.337056)
		(width 0.0889)
		(layer "In11.Cu")
		(net "M_L_CPU1_SA_CA<6>")
	)
	(segment
		(start 137.62482 -255.014476)
		(end 137.778744 -255.279906)
		(width 0.0889)
		(layer "In11.Cu")
		(net "M_L_CPU1_SA_CA<6>")
	)
	(segment
		(start 201.974704 -252.160278)
		(end 202.333352 -252.160278)
		(width 0.0889)
		(layer "In11.Cu")
		(net "M_L_CPU1_SA_CA<6>")
	)
	(segment
		(start 137.778744 -255.279906)
		(end 137.874756 -255.305306)
		(width 0.0889)
		(layer "In11.Cu")
		(net "M_L_CPU1_SA_CA<6>")
	)
	(segment
		(start 142.503398 -255.341882)
		(end 142.51178 -255.337056)
		(width 0.0889)
		(layer "In11.Cu")
		(net "M_L_CPU1_SA_CA<6>")
	)
	(segment
		(start 162.82416 -254.698754)
		(end 162.835844 -254.710438)
		(width 0.14478)
		(layer "In11.Cu")
		(net "M_L_CPU1_SA_CA<6>")
	)
	(segment
		(start 199.91197 -253.010416)
		(end 200.521062 -252.401324)
		(width 0.14478)
		(layer "In11.Cu")
		(net "M_L_CPU1_SA_CA<6>")
	)
	(segment
		(start 198.48703 -253.010416)
		(end 199.91197 -253.010416)
		(width 0.14478)
		(layer "In11.Cu")
		(net "M_L_CPU1_SA_CA<6>")
	)
	(segment
		(start 147.808188 -256.097278)
		(end 150.797768 -256.097278)
		(width 0.14478)
		(layer "In11.Cu")
		(net "M_L_CPU1_SA_CA<6>")
	)
	(segment
		(start 201.727054 -252.401324)
		(end 201.91095 -252.217428)
		(width 0.14478)
		(layer "In11.Cu")
		(net "M_L_CPU1_SA_CA<6>")
	)
	(segment
		(start 143.451834 -255.337056)
		(end 143.462248 -255.33096)
		(width 0.0889)
		(layer "In11.Cu")
		(net "M_L_CPU1_SA_CA<6>")
	)
	(segment
		(start 146.557492 -255.387348)
		(end 147.267422 -256.097278)
		(width 0.0889)
		(layer "In11.Cu")
		(net "M_L_CPU1_SA_CA<6>")
	)
	(segment
		(start 205.823058 -252.160278)
		(end 206.248 -252.58522)
		(width 0.14478)
		(layer "In11.Cu")
		(net "M_L_CPU1_SA_CA<6>")
	)
	(segment
		(start 152.196292 -254.698754)
		(end 162.82416 -254.698754)
		(width 0.14478)
		(layer "In11.Cu")
		(net "M_L_CPU1_SA_CA<6>")
	)
	(segment
		(start 196.787008 -254.710438)
		(end 198.48703 -253.010416)
		(width 0.14478)
		(layer "In11.Cu")
		(net "M_L_CPU1_SA_CA<6>")
	)
	(segment
		(start 201.91095 -252.217428)
		(end 201.917554 -252.217428)
		(width 0.0889)
		(layer "In11.Cu")
		(net "M_L_CPU1_SA_CA<6>")
	)
	(segment
		(start 143.077692 -255.337056)
		(end 143.086074 -255.341882)
		(width 0.0889)
		(layer "In11.Cu")
		(net "M_L_CPU1_SA_CA<6>")
	)
	(segment
		(start 200.521062 -252.401324)
		(end 201.727054 -252.401324)
		(width 0.14478)
		(layer "In11.Cu")
		(net "M_L_CPU1_SA_CA<6>")
	)
	(segment
		(start 150.797768 -256.097278)
		(end 152.196292 -254.698754)
		(width 0.14478)
		(layer "In11.Cu")
		(net "M_L_CPU1_SA_CA<6>")
	)
	(segment
		(start 139.31773 -255.337056)
		(end 139.326112 -255.341882)
		(width 0.0889)
		(layer "In11.Cu")
		(net "M_L_CPU1_SA_CA<6>")
	)
	(segment
		(start 201.917554 -252.217428)
		(end 201.974704 -252.160278)
		(width 0.0889)
		(layer "In11.Cu")
		(net "M_L_CPU1_SA_CA<6>")
	)
	(segment
		(start 144.947386 -255.33096)
		(end 144.9578 -255.337056)
		(width 0.0889)
		(layer "In11.Cu")
		(net "M_L_CPU1_SA_CA<6>")
	)
	(segment
		(start 145.144744 -255.387348)
		(end 146.557492 -255.387348)
		(width 0.0889)
		(layer "In11.Cu")
		(net "M_L_CPU1_SA_CA<6>")
	)
	(segment
		(start 202.333352 -252.160278)
		(end 205.823058 -252.160278)
		(width 0.14478)
		(layer "In11.Cu")
		(net "M_L_CPU1_SA_CA<6>")
	)
	(segment
		(start 162.835844 -254.710438)
		(end 196.787008 -254.710438)
		(width 0.14478)
		(layer "In11.Cu")
		(net "M_L_CPU1_SA_CA<6>")
	)
	(arc
		(start 142.51178 -255.337056)
		(mid 142.794736 -255.260879)
		(end 143.077692 -255.337056)
		(width 0.0889)
		(layer "In11.Cu")
		(net "M_L_CPU1_SA_CA<6>")
	)
	(arc
		(start 138.751818 -255.337056)
		(mid 139.034774 -255.260879)
		(end 139.31773 -255.337056)
		(width 0.0889)
		(layer "In11.Cu")
		(net "M_L_CPU1_SA_CA<6>")
	)
	(arc
		(start 140.631926 -255.337056)
		(mid 140.914882 -255.260879)
		(end 141.197838 -255.337056)
		(width 0.0889)
		(layer "In11.Cu")
		(net "M_L_CPU1_SA_CA<6>")
	)
	(arc
		(start 142.137638 -255.337056)
		(mid 142.319889 -255.387406)
		(end 142.503398 -255.341882)
		(width 0.0889)
		(layer "In11.Cu")
		(net "M_L_CPU1_SA_CA<6>")
	)
	(arc
		(start 138.377676 -255.337056)
		(mid 138.559927 -255.387406)
		(end 138.743436 -255.341882)
		(width 0.0889)
		(layer "In11.Cu")
		(net "M_L_CPU1_SA_CA<6>")
	)
	(arc
		(start 140.266166 -255.341882)
		(mid 140.449674 -255.387376)
		(end 140.631926 -255.337056)
		(width 0.0889)
		(layer "In11.Cu")
		(net "M_L_CPU1_SA_CA<6>")
	)
	(arc
		(start 139.691872 -255.337056)
		(mid 139.974828 -255.260879)
		(end 140.257784 -255.337056)
		(width 0.0889)
		(layer "In11.Cu")
		(net "M_L_CPU1_SA_CA<6>")
	)
	(arc
		(start 144.9578 -255.337056)
		(mid 145.047949 -255.374553)
		(end 145.144744 -255.387348)
		(width 0.0889)
		(layer "In11.Cu")
		(net "M_L_CPU1_SA_CA<6>")
	)
	(arc
		(start 137.874756 -255.305306)
		(mid 138.129964 -255.261829)
		(end 138.377676 -255.337056)
		(width 0.0889)
		(layer "In11.Cu")
		(net "M_L_CPU1_SA_CA<6>")
	)
	(arc
		(start 144.392142 -255.337056)
		(mid 144.668955 -255.260913)
		(end 144.947386 -255.33096)
		(width 0.0889)
		(layer "In11.Cu")
		(net "M_L_CPU1_SA_CA<6>")
	)
	(arc
		(start 144.018 -255.337056)
		(mid 144.200251 -255.387406)
		(end 144.38376 -255.341882)
		(width 0.0889)
		(layer "In11.Cu")
		(net "M_L_CPU1_SA_CA<6>")
	)
	(arc
		(start 139.326112 -255.341882)
		(mid 139.50962 -255.387376)
		(end 139.691872 -255.337056)
		(width 0.0889)
		(layer "In11.Cu")
		(net "M_L_CPU1_SA_CA<6>")
	)
	(arc
		(start 141.197838 -255.337056)
		(mid 141.384782 -255.387311)
		(end 141.571726 -255.337056)
		(width 0.0889)
		(layer "In11.Cu")
		(net "M_L_CPU1_SA_CA<6>")
	)
	(arc
		(start 143.462248 -255.33096)
		(mid 143.740934 -255.26074)
		(end 144.018 -255.337056)
		(width 0.0889)
		(layer "In11.Cu")
		(net "M_L_CPU1_SA_CA<6>")
	)
	(arc
		(start 141.571726 -255.337056)
		(mid 141.854682 -255.260879)
		(end 142.137638 -255.337056)
		(width 0.0889)
		(layer "In11.Cu")
		(net "M_L_CPU1_SA_CA<6>")
	)
	(arc
		(start 143.086074 -255.341882)
		(mid 143.269582 -255.387376)
		(end 143.451834 -255.337056)
		(width 0.0889)
		(layer "In11.Cu")
		(net "M_L_CPU1_SA_CA<6>")
	)
	(segment
		(start 139.037822 -255.280414)
		(end 139.504674 -255.014476)
		(width 0.10668)
		(layer "F.Cu")
		(net "M_L_CPU1_SA_CA<5>")
	)
	(segment
		(start 147.295362 -255.642618)
		(end 147.808188 -255.642618)
		(width 0.0889)
		(layer "In11.Cu")
		(net "M_L_CPU1_SA_CA<5>")
	)
	(segment
		(start 198.05269 -252.321314)
		(end 198.257414 -252.321314)
		(width 0.14478)
		(layer "In11.Cu")
		(net "M_L_CPU1_SA_CA<5>")
	)
	(segment
		(start 193.556382 -253.481586)
		(end 193.701162 -253.626366)
		(width 0.14478)
		(layer "In11.Cu")
		(net "M_L_CPU1_SA_CA<5>")
	)
	(segment
		(start 146.33829 -255.056386)
		(end 146.70913 -255.056386)
		(width 0.0889)
		(layer "In11.Cu")
		(net "M_L_CPU1_SA_CA<5>")
	)
	(segment
		(start 164.071046 -254.244094)
		(end 164.072316 -254.245364)
		(width 0.14478)
		(layer "In11.Cu")
		(net "M_L_CPU1_SA_CA<5>")
	)
	(segment
		(start 144.005046 -254.699008)
		(end 144.016984 -254.69215)
		(width 0.0889)
		(layer "In11.Cu")
		(net "M_L_CPU1_SA_CA<5>")
	)
	(segment
		(start 197.662546 -252.916182)
		(end 197.662546 -252.711458)
		(width 0.14478)
		(layer "In11.Cu")
		(net "M_L_CPU1_SA_CA<5>")
	)
	(segment
		(start 164.072316 -254.245364)
		(end 164.302694 -254.245364)
		(width 0.14478)
		(layer "In11.Cu")
		(net "M_L_CPU1_SA_CA<5>")
	)
	(segment
		(start 196.834506 -252.86843)
		(end 197.03923 -252.86843)
		(width 0.14478)
		(layer "In11.Cu")
		(net "M_L_CPU1_SA_CA<5>")
	)
	(segment
		(start 147.808188 -255.642618)
		(end 150.609046 -255.642618)
		(width 0.14478)
		(layer "In11.Cu")
		(net "M_L_CPU1_SA_CA<5>")
	)
	(segment
		(start 145.144744 -254.641096)
		(end 145.923 -254.641096)
		(width 0.0889)
		(layer "In11.Cu")
		(net "M_L_CPU1_SA_CA<5>")
	)
	(segment
		(start 192.04686 -253.71552)
		(end 192.04686 -253.626366)
		(width 0.14478)
		(layer "In11.Cu")
		(net "M_L_CPU1_SA_CA<5>")
	)
	(segment
		(start 192.453514 -253.481586)
		(end 192.598294 -253.626366)
		(width 0.14478)
		(layer "In11.Cu")
		(net "M_L_CPU1_SA_CA<5>")
	)
	(segment
		(start 200.08342 -251.735336)
		(end 202.147932 -251.735336)
		(width 0.14478)
		(layer "In11.Cu")
		(net "M_L_CPU1_SA_CA<5>")
	)
	(segment
		(start 197.662546 -252.711458)
		(end 197.429374 -252.478286)
		(width 0.14478)
		(layer "In11.Cu")
		(net "M_L_CPU1_SA_CA<5>")
	)
	(segment
		(start 197.614794 -252.088142)
		(end 197.819518 -252.088142)
		(width 0.14478)
		(layer "In11.Cu")
		(net "M_L_CPU1_SA_CA<5>")
	)
	(segment
		(start 142.503398 -254.68707)
		(end 142.51178 -254.691896)
		(width 0.0889)
		(layer "In11.Cu")
		(net "M_L_CPU1_SA_CA<5>")
	)
	(segment
		(start 196.718428 -253.8603)
		(end 196.882258 -253.69647)
		(width 0.14478)
		(layer "In11.Cu")
		(net "M_L_CPU1_SA_CA<5>")
	)
	(segment
		(start 143.077692 -254.691896)
		(end 143.086074 -254.68707)
		(width 0.0889)
		(layer "In11.Cu")
		(net "M_L_CPU1_SA_CA<5>")
	)
	(segment
		(start 197.03923 -252.86843)
		(end 197.272402 -253.101602)
		(width 0.14478)
		(layer "In11.Cu")
		(net "M_L_CPU1_SA_CA<5>")
	)
	(segment
		(start 139.504674 -255.014476)
		(end 139.35075 -254.749046)
		(width 0.0889)
		(layer "In11.Cu")
		(net "M_L_CPU1_SA_CA<5>")
	)
	(segment
		(start 197.477126 -253.101602)
		(end 197.662546 -252.916182)
		(width 0.14478)
		(layer "In11.Cu")
		(net "M_L_CPU1_SA_CA<5>")
	)
	(segment
		(start 191.90208 -253.8603)
		(end 192.04686 -253.71552)
		(width 0.14478)
		(layer "In11.Cu")
		(net "M_L_CPU1_SA_CA<5>")
	)
	(segment
		(start 164.465762 -254.082296)
		(end 164.465762 -254.00508)
		(width 0.14478)
		(layer "In11.Cu")
		(net "M_L_CPU1_SA_CA<5>")
	)
	(segment
		(start 192.743074 -254.239014)
		(end 193.004948 -254.239014)
		(width 0.14478)
		(layer "In11.Cu")
		(net "M_L_CPU1_SA_CA<5>")
	)
	(segment
		(start 164.610542 -253.8603)
		(end 191.90208 -253.8603)
		(width 0.14478)
		(layer "In11.Cu")
		(net "M_L_CPU1_SA_CA<5>")
	)
	(segment
		(start 193.149728 -254.094234)
		(end 193.149728 -253.626366)
		(width 0.14478)
		(layer "In11.Cu")
		(net "M_L_CPU1_SA_CA<5>")
	)
	(segment
		(start 193.294508 -253.481586)
		(end 193.556382 -253.481586)
		(width 0.14478)
		(layer "In11.Cu")
		(net "M_L_CPU1_SA_CA<5>")
	)
	(segment
		(start 144.390618 -254.691896)
		(end 144.408652 -254.702564)
		(width 0.0889)
		(layer "In11.Cu")
		(net "M_L_CPU1_SA_CA<5>")
	)
	(segment
		(start 164.302694 -254.245364)
		(end 164.465762 -254.082296)
		(width 0.14478)
		(layer "In11.Cu")
		(net "M_L_CPU1_SA_CA<5>")
	)
	(segment
		(start 197.272402 -253.101602)
		(end 197.477126 -253.101602)
		(width 0.14478)
		(layer "In11.Cu")
		(net "M_L_CPU1_SA_CA<5>")
	)
	(segment
		(start 198.41845 -252.160278)
		(end 199.658478 -252.160278)
		(width 0.14478)
		(layer "In11.Cu")
		(net "M_L_CPU1_SA_CA<5>")
	)
	(segment
		(start 197.819518 -252.088142)
		(end 198.05269 -252.321314)
		(width 0.14478)
		(layer "In11.Cu")
		(net "M_L_CPU1_SA_CA<5>")
	)
	(segment
		(start 196.649086 -253.05385)
		(end 196.834506 -252.86843)
		(width 0.14478)
		(layer "In11.Cu")
		(net "M_L_CPU1_SA_CA<5>")
	)
	(segment
		(start 152.00757 -254.244094)
		(end 164.071046 -254.244094)
		(width 0.14478)
		(layer "In11.Cu")
		(net "M_L_CPU1_SA_CA<5>")
	)
	(segment
		(start 193.701162 -253.626366)
		(end 193.701162 -253.71552)
		(width 0.14478)
		(layer "In11.Cu")
		(net "M_L_CPU1_SA_CA<5>")
	)
	(segment
		(start 192.598294 -253.626366)
		(end 192.598294 -254.094234)
		(width 0.14478)
		(layer "In11.Cu")
		(net "M_L_CPU1_SA_CA<5>")
	)
	(segment
		(start 164.465762 -254.00508)
		(end 164.610542 -253.8603)
		(width 0.14478)
		(layer "In11.Cu")
		(net "M_L_CPU1_SA_CA<5>")
	)
	(segment
		(start 140.257784 -254.691896)
		(end 140.266166 -254.68707)
		(width 0.0889)
		(layer "In11.Cu")
		(net "M_L_CPU1_SA_CA<5>")
	)
	(segment
		(start 198.257414 -252.321314)
		(end 198.41845 -252.160278)
		(width 0.14478)
		(layer "In11.Cu")
		(net "M_L_CPU1_SA_CA<5>")
	)
	(segment
		(start 144.016984 -254.69215)
		(end 144.0307 -254.684276)
		(width 0.0889)
		(layer "In11.Cu")
		(net "M_L_CPU1_SA_CA<5>")
	)
	(segment
		(start 197.429374 -252.478286)
		(end 197.429374 -252.273562)
		(width 0.14478)
		(layer "In11.Cu")
		(net "M_L_CPU1_SA_CA<5>")
	)
	(segment
		(start 197.429374 -252.273562)
		(end 197.614794 -252.088142)
		(width 0.14478)
		(layer "In11.Cu")
		(net "M_L_CPU1_SA_CA<5>")
	)
	(segment
		(start 196.882258 -253.491746)
		(end 196.649086 -253.258574)
		(width 0.14478)
		(layer "In11.Cu")
		(net "M_L_CPU1_SA_CA<5>")
	)
	(segment
		(start 192.19164 -253.481586)
		(end 192.453514 -253.481586)
		(width 0.14478)
		(layer "In11.Cu")
		(net "M_L_CPU1_SA_CA<5>")
	)
	(segment
		(start 192.598294 -254.094234)
		(end 192.743074 -254.239014)
		(width 0.14478)
		(layer "In11.Cu")
		(net "M_L_CPU1_SA_CA<5>")
	)
	(segment
		(start 193.004948 -254.239014)
		(end 193.149728 -254.094234)
		(width 0.14478)
		(layer "In11.Cu")
		(net "M_L_CPU1_SA_CA<5>")
	)
	(segment
		(start 193.701162 -253.71552)
		(end 193.845942 -253.8603)
		(width 0.14478)
		(layer "In11.Cu")
		(net "M_L_CPU1_SA_CA<5>")
	)
	(segment
		(start 193.845942 -253.8603)
		(end 196.718428 -253.8603)
		(width 0.14478)
		(layer "In11.Cu")
		(net "M_L_CPU1_SA_CA<5>")
	)
	(segment
		(start 145.923 -254.641096)
		(end 146.33829 -255.056386)
		(width 0.0889)
		(layer "In11.Cu")
		(net "M_L_CPU1_SA_CA<5>")
	)
	(segment
		(start 196.649086 -253.258574)
		(end 196.649086 -253.05385)
		(width 0.14478)
		(layer "In11.Cu")
		(net "M_L_CPU1_SA_CA<5>")
	)
	(segment
		(start 139.35075 -254.749046)
		(end 139.373102 -254.665734)
		(width 0.0889)
		(layer "In11.Cu")
		(net "M_L_CPU1_SA_CA<5>")
	)
	(segment
		(start 192.04686 -253.626366)
		(end 192.19164 -253.481586)
		(width 0.14478)
		(layer "In11.Cu")
		(net "M_L_CPU1_SA_CA<5>")
	)
	(segment
		(start 199.658478 -252.160278)
		(end 200.08342 -251.735336)
		(width 0.14478)
		(layer "In11.Cu")
		(net "M_L_CPU1_SA_CA<5>")
	)
	(segment
		(start 196.882258 -253.69647)
		(end 196.882258 -253.491746)
		(width 0.14478)
		(layer "In11.Cu")
		(net "M_L_CPU1_SA_CA<5>")
	)
	(segment
		(start 146.70913 -255.056386)
		(end 147.295362 -255.642618)
		(width 0.0889)
		(layer "In11.Cu")
		(net "M_L_CPU1_SA_CA<5>")
	)
	(segment
		(start 193.149728 -253.626366)
		(end 193.294508 -253.481586)
		(width 0.14478)
		(layer "In11.Cu")
		(net "M_L_CPU1_SA_CA<5>")
	)
	(segment
		(start 150.609046 -255.642618)
		(end 152.00757 -254.244094)
		(width 0.14478)
		(layer "In11.Cu")
		(net "M_L_CPU1_SA_CA<5>")
	)
	(arc
		(start 144.408652 -254.702564)
		(mid 144.684347 -254.768407)
		(end 144.957292 -254.691896)
		(width 0.0889)
		(layer "In11.Cu")
		(net "M_L_CPU1_SA_CA<5>")
	)
	(arc
		(start 144.957292 -254.691896)
		(mid 145.047655 -254.654086)
		(end 145.144744 -254.641096)
		(width 0.0889)
		(layer "In11.Cu")
		(net "M_L_CPU1_SA_CA<5>")
	)
	(arc
		(start 139.691872 -254.691896)
		(mid 139.974828 -254.768073)
		(end 140.257784 -254.691896)
		(width 0.0889)
		(layer "In11.Cu")
		(net "M_L_CPU1_SA_CA<5>")
	)
	(arc
		(start 141.197838 -254.691896)
		(mid 141.384782 -254.641641)
		(end 141.571726 -254.691896)
		(width 0.0889)
		(layer "In11.Cu")
		(net "M_L_CPU1_SA_CA<5>")
	)
	(arc
		(start 144.0307 -254.684276)
		(mid 144.21163 -254.641798)
		(end 144.390618 -254.691896)
		(width 0.0889)
		(layer "In11.Cu")
		(net "M_L_CPU1_SA_CA<5>")
	)
	(arc
		(start 140.266166 -254.68707)
		(mid 140.449674 -254.641576)
		(end 140.631926 -254.691896)
		(width 0.0889)
		(layer "In11.Cu")
		(net "M_L_CPU1_SA_CA<5>")
	)
	(arc
		(start 143.451834 -254.691896)
		(mid 143.727512 -254.768026)
		(end 144.005046 -254.699008)
		(width 0.0889)
		(layer "In11.Cu")
		(net "M_L_CPU1_SA_CA<5>")
	)
	(arc
		(start 141.571726 -254.691896)
		(mid 141.854682 -254.768073)
		(end 142.137638 -254.691896)
		(width 0.0889)
		(layer "In11.Cu")
		(net "M_L_CPU1_SA_CA<5>")
	)
	(arc
		(start 143.086074 -254.68707)
		(mid 143.269582 -254.641576)
		(end 143.451834 -254.691896)
		(width 0.0889)
		(layer "In11.Cu")
		(net "M_L_CPU1_SA_CA<5>")
	)
	(arc
		(start 139.373102 -254.665734)
		(mid 139.535434 -254.642916)
		(end 139.691872 -254.691896)
		(width 0.0889)
		(layer "In11.Cu")
		(net "M_L_CPU1_SA_CA<5>")
	)
	(arc
		(start 142.51178 -254.691896)
		(mid 142.794736 -254.768073)
		(end 143.077692 -254.691896)
		(width 0.0889)
		(layer "In11.Cu")
		(net "M_L_CPU1_SA_CA<5>")
	)
	(arc
		(start 142.137638 -254.691896)
		(mid 142.319889 -254.641546)
		(end 142.503398 -254.68707)
		(width 0.0889)
		(layer "In11.Cu")
		(net "M_L_CPU1_SA_CA<5>")
	)
	(arc
		(start 140.631926 -254.691896)
		(mid 140.914882 -254.768073)
		(end 141.197838 -254.691896)
		(width 0.0889)
		(layer "In11.Cu")
		(net "M_L_CPU1_SA_CA<5>")
	)
	(segment
		(start 138.567922 -254.470408)
		(end 139.034774 -254.20447)
		(width 0.10668)
		(layer "F.Cu")
		(net "M_L_CPU1_SA_CA<4>")
	)
	(segment
		(start 195.927218 -253.010416)
		(end 197.62724 -251.310394)
		(width 0.14478)
		(layer "In11.Cu")
		(net "M_L_CPU1_SA_CA<4>")
	)
	(segment
		(start 205.822804 -251.310394)
		(end 206.248 -250.885198)
		(width 0.14478)
		(layer "In11.Cu")
		(net "M_L_CPU1_SA_CA<4>")
	)
	(segment
		(start 150.420324 -255.187958)
		(end 151.818848 -253.789434)
		(width 0.14478)
		(layer "In11.Cu")
		(net "M_L_CPU1_SA_CA<4>")
	)
	(segment
		(start 197.62724 -251.310394)
		(end 199.284082 -251.310394)
		(width 0.14478)
		(layer "In11.Cu")
		(net "M_L_CPU1_SA_CA<4>")
	)
	(segment
		(start 151.818848 -253.789434)
		(end 163.074096 -253.789434)
		(width 0.14478)
		(layer "In11.Cu")
		(net "M_L_CPU1_SA_CA<4>")
	)
	(segment
		(start 146.97329 -254.865886)
		(end 147.295362 -255.187958)
		(width 0.0889)
		(layer "In11.Cu")
		(net "M_L_CPU1_SA_CA<4>")
	)
	(segment
		(start 139.034774 -254.20447)
		(end 139.188698 -254.4699)
		(width 0.0889)
		(layer "In11.Cu")
		(net "M_L_CPU1_SA_CA<4>")
	)
	(segment
		(start 141.667738 -254.52705)
		(end 141.67612 -254.531876)
		(width 0.0889)
		(layer "In11.Cu")
		(net "M_L_CPU1_SA_CA<4>")
	)
	(segment
		(start 201.74331 -251.085604)
		(end 201.91095 -251.253244)
		(width 0.14478)
		(layer "In11.Cu")
		(net "M_L_CPU1_SA_CA<4>")
	)
	(segment
		(start 163.853114 -253.010416)
		(end 195.927218 -253.010416)
		(width 0.14478)
		(layer "In11.Cu")
		(net "M_L_CPU1_SA_CA<4>")
	)
	(segment
		(start 147.295362 -255.187958)
		(end 147.819618 -255.187958)
		(width 0.0889)
		(layer "In11.Cu")
		(net "M_L_CPU1_SA_CA<4>")
	)
	(segment
		(start 146.001994 -254.450596)
		(end 146.417284 -254.865886)
		(width 0.0889)
		(layer "In11.Cu")
		(net "M_L_CPU1_SA_CA<4>")
	)
	(segment
		(start 199.508872 -251.085604)
		(end 201.74331 -251.085604)
		(width 0.14478)
		(layer "In11.Cu")
		(net "M_L_CPU1_SA_CA<4>")
	)
	(segment
		(start 163.074096 -253.789434)
		(end 163.853114 -253.010416)
		(width 0.14478)
		(layer "In11.Cu")
		(net "M_L_CPU1_SA_CA<4>")
	)
	(segment
		(start 143.905224 -254.536194)
		(end 143.92148 -254.526796)
		(width 0.0889)
		(layer "In11.Cu")
		(net "M_L_CPU1_SA_CA<4>")
	)
	(segment
		(start 140.15339 -254.531876)
		(end 140.161772 -254.52705)
		(width 0.0889)
		(layer "In11.Cu")
		(net "M_L_CPU1_SA_CA<4>")
	)
	(segment
		(start 147.819618 -255.187958)
		(end 150.420324 -255.187958)
		(width 0.14478)
		(layer "In11.Cu")
		(net "M_L_CPU1_SA_CA<4>")
	)
	(segment
		(start 144.48663 -254.52705)
		(end 144.498314 -254.533908)
		(width 0.0889)
		(layer "In11.Cu")
		(net "M_L_CPU1_SA_CA<4>")
	)
	(segment
		(start 145.144744 -254.450596)
		(end 146.001994 -254.450596)
		(width 0.0889)
		(layer "In11.Cu")
		(net "M_L_CPU1_SA_CA<4>")
	)
	(segment
		(start 202.333352 -251.310394)
		(end 205.822804 -251.310394)
		(width 0.14478)
		(layer "In11.Cu")
		(net "M_L_CPU1_SA_CA<4>")
	)
	(segment
		(start 141.093444 -254.531876)
		(end 141.101826 -254.52705)
		(width 0.0889)
		(layer "In11.Cu")
		(net "M_L_CPU1_SA_CA<4>")
	)
	(segment
		(start 143.92148 -254.526796)
		(end 143.933418 -254.519938)
		(width 0.0889)
		(layer "In11.Cu")
		(net "M_L_CPU1_SA_CA<4>")
	)
	(segment
		(start 199.284082 -251.310394)
		(end 199.508872 -251.085604)
		(width 0.14478)
		(layer "In11.Cu")
		(net "M_L_CPU1_SA_CA<4>")
	)
	(segment
		(start 201.917554 -251.253244)
		(end 201.974704 -251.310394)
		(width 0.0889)
		(layer "In11.Cu")
		(net "M_L_CPU1_SA_CA<4>")
	)
	(segment
		(start 201.974704 -251.310394)
		(end 202.333352 -251.310394)
		(width 0.0889)
		(layer "In11.Cu")
		(net "M_L_CPU1_SA_CA<4>")
	)
	(segment
		(start 139.188698 -254.4699)
		(end 139.28471 -254.4953)
		(width 0.0889)
		(layer "In11.Cu")
		(net "M_L_CPU1_SA_CA<4>")
	)
	(segment
		(start 146.417284 -254.865886)
		(end 146.97329 -254.865886)
		(width 0.0889)
		(layer "In11.Cu")
		(net "M_L_CPU1_SA_CA<4>")
	)
	(segment
		(start 201.91095 -251.253244)
		(end 201.917554 -251.253244)
		(width 0.0889)
		(layer "In11.Cu")
		(net "M_L_CPU1_SA_CA<4>")
	)
	(arc
		(start 140.161772 -254.52705)
		(mid 140.444728 -254.450873)
		(end 140.727684 -254.52705)
		(width 0.0889)
		(layer "In11.Cu")
		(net "M_L_CPU1_SA_CA<4>")
	)
	(arc
		(start 140.727684 -254.52705)
		(mid 140.909935 -254.5774)
		(end 141.093444 -254.531876)
		(width 0.0889)
		(layer "In11.Cu")
		(net "M_L_CPU1_SA_CA<4>")
	)
	(arc
		(start 143.547592 -254.52705)
		(mid 143.725242 -254.57731)
		(end 143.905224 -254.536194)
		(width 0.0889)
		(layer "In11.Cu")
		(net "M_L_CPU1_SA_CA<4>")
	)
	(arc
		(start 144.498314 -254.533908)
		(mid 144.680569 -254.577561)
		(end 144.861026 -254.52705)
		(width 0.0889)
		(layer "In11.Cu")
		(net "M_L_CPU1_SA_CA<4>")
	)
	(arc
		(start 141.101826 -254.52705)
		(mid 141.384782 -254.450873)
		(end 141.667738 -254.52705)
		(width 0.0889)
		(layer "In11.Cu")
		(net "M_L_CPU1_SA_CA<4>")
	)
	(arc
		(start 144.861026 -254.52705)
		(mid 144.997819 -254.470028)
		(end 145.144744 -254.450596)
		(width 0.0889)
		(layer "In11.Cu")
		(net "M_L_CPU1_SA_CA<4>")
	)
	(arc
		(start 143.933418 -254.519938)
		(mid 144.210952 -254.450957)
		(end 144.48663 -254.52705)
		(width 0.0889)
		(layer "In11.Cu")
		(net "M_L_CPU1_SA_CA<4>")
	)
	(arc
		(start 141.67612 -254.531876)
		(mid 141.859628 -254.57737)
		(end 142.04188 -254.52705)
		(width 0.0889)
		(layer "In11.Cu")
		(net "M_L_CPU1_SA_CA<4>")
	)
	(arc
		(start 139.28471 -254.4953)
		(mid 139.539918 -254.451823)
		(end 139.78763 -254.52705)
		(width 0.0889)
		(layer "In11.Cu")
		(net "M_L_CPU1_SA_CA<4>")
	)
	(arc
		(start 142.98168 -254.52705)
		(mid 143.264636 -254.450873)
		(end 143.547592 -254.52705)
		(width 0.0889)
		(layer "In11.Cu")
		(net "M_L_CPU1_SA_CA<4>")
	)
	(arc
		(start 139.78763 -254.52705)
		(mid 139.969881 -254.5774)
		(end 140.15339 -254.531876)
		(width 0.0889)
		(layer "In11.Cu")
		(net "M_L_CPU1_SA_CA<4>")
	)
	(arc
		(start 142.607792 -254.52705)
		(mid 142.794736 -254.577305)
		(end 142.98168 -254.52705)
		(width 0.0889)
		(layer "In11.Cu")
		(net "M_L_CPU1_SA_CA<4>")
	)
	(arc
		(start 142.04188 -254.52705)
		(mid 142.324836 -254.450873)
		(end 142.607792 -254.52705)
		(width 0.0889)
		(layer "In11.Cu")
		(net "M_L_CPU1_SA_CA<4>")
	)
	(segment
		(start 137.627868 -254.470408)
		(end 138.09472 -254.20447)
		(width 0.10668)
		(layer "F.Cu")
		(net "M_L_CPU1_SA_CA<3>")
	)
	(segment
		(start 147.546822 -254.733298)
		(end 147.819618 -254.733298)
		(width 0.0889)
		(layer "In11.Cu")
		(net "M_L_CPU1_SA_CA<3>")
	)
	(segment
		(start 163.998656 -252.160278)
		(end 165.117018 -252.160278)
		(width 0.14478)
		(layer "In11.Cu")
		(net "M_L_CPU1_SA_CA<3>")
	)
	(segment
		(start 166.509446 -252.54077)
		(end 166.77132 -252.54077)
		(width 0.14478)
		(layer "In11.Cu")
		(net "M_L_CPU1_SA_CA<3>")
	)
	(segment
		(start 201.72299 -250.460256)
		(end 202.147932 -250.035314)
		(width 0.14478)
		(layer "In11.Cu")
		(net "M_L_CPU1_SA_CA<3>")
	)
	(segment
		(start 165.117018 -252.160278)
		(end 165.261798 -252.305058)
		(width 0.14478)
		(layer "In11.Cu")
		(net "M_L_CPU1_SA_CA<3>")
	)
	(segment
		(start 167.06088 -251.779786)
		(end 167.322754 -251.779786)
		(width 0.14478)
		(layer "In11.Cu")
		(net "M_L_CPU1_SA_CA<3>")
	)
	(segment
		(start 146.77136 -253.957836)
		(end 147.546822 -254.733298)
		(width 0.0889)
		(layer "In11.Cu")
		(net "M_L_CPU1_SA_CA<3>")
	)
	(segment
		(start 137.940796 -253.93904)
		(end 137.963148 -253.855728)
		(width 0.0889)
		(layer "In11.Cu")
		(net "M_L_CPU1_SA_CA<3>")
	)
	(segment
		(start 167.467534 -252.015498)
		(end 167.612314 -252.160278)
		(width 0.14478)
		(layer "In11.Cu")
		(net "M_L_CPU1_SA_CA<3>")
	)
	(segment
		(start 165.261798 -252.305058)
		(end 165.261798 -252.39599)
		(width 0.14478)
		(layer "In11.Cu")
		(net "M_L_CPU1_SA_CA<3>")
	)
	(segment
		(start 167.467534 -251.924566)
		(end 167.467534 -252.015498)
		(width 0.14478)
		(layer "In11.Cu")
		(net "M_L_CPU1_SA_CA<3>")
	)
	(segment
		(start 165.668452 -252.54077)
		(end 165.813232 -252.39599)
		(width 0.14478)
		(layer "In11.Cu")
		(net "M_L_CPU1_SA_CA<3>")
	)
	(segment
		(start 166.364666 -252.39599)
		(end 166.509446 -252.54077)
		(width 0.14478)
		(layer "In11.Cu")
		(net "M_L_CPU1_SA_CA<3>")
	)
	(segment
		(start 166.9161 -251.924566)
		(end 167.06088 -251.779786)
		(width 0.14478)
		(layer "In11.Cu")
		(net "M_L_CPU1_SA_CA<3>")
	)
	(segment
		(start 140.15339 -253.877064)
		(end 140.161772 -253.88189)
		(width 0.0889)
		(layer "In11.Cu")
		(net "M_L_CPU1_SA_CA<3>")
	)
	(segment
		(start 165.958012 -251.779786)
		(end 166.219886 -251.779786)
		(width 0.14478)
		(layer "In11.Cu")
		(net "M_L_CPU1_SA_CA<3>")
	)
	(segment
		(start 197.567296 -250.460256)
		(end 201.72299 -250.460256)
		(width 0.14478)
		(layer "In11.Cu")
		(net "M_L_CPU1_SA_CA<3>")
	)
	(segment
		(start 166.9161 -252.39599)
		(end 166.9161 -251.924566)
		(width 0.14478)
		(layer "In11.Cu")
		(net "M_L_CPU1_SA_CA<3>")
	)
	(segment
		(start 150.231856 -254.733298)
		(end 151.63038 -253.334774)
		(width 0.14478)
		(layer "In11.Cu")
		(net "M_L_CPU1_SA_CA<3>")
	)
	(segment
		(start 165.406578 -252.54077)
		(end 165.668452 -252.54077)
		(width 0.14478)
		(layer "In11.Cu")
		(net "M_L_CPU1_SA_CA<3>")
	)
	(segment
		(start 166.364666 -251.924566)
		(end 166.364666 -252.39599)
		(width 0.14478)
		(layer "In11.Cu")
		(net "M_L_CPU1_SA_CA<3>")
	)
	(segment
		(start 167.612314 -252.160278)
		(end 195.867274 -252.160278)
		(width 0.14478)
		(layer "In11.Cu")
		(net "M_L_CPU1_SA_CA<3>")
	)
	(segment
		(start 165.261798 -252.39599)
		(end 165.406578 -252.54077)
		(width 0.14478)
		(layer "In11.Cu")
		(net "M_L_CPU1_SA_CA<3>")
	)
	(segment
		(start 141.667738 -253.88189)
		(end 141.67612 -253.877064)
		(width 0.0889)
		(layer "In11.Cu")
		(net "M_L_CPU1_SA_CA<3>")
	)
	(segment
		(start 144.47774 -253.887986)
		(end 144.488154 -253.88189)
		(width 0.0889)
		(layer "In11.Cu")
		(net "M_L_CPU1_SA_CA<3>")
	)
	(segment
		(start 166.219886 -251.779786)
		(end 166.364666 -251.924566)
		(width 0.14478)
		(layer "In11.Cu")
		(net "M_L_CPU1_SA_CA<3>")
	)
	(segment
		(start 165.813232 -251.924566)
		(end 165.958012 -251.779786)
		(width 0.14478)
		(layer "In11.Cu")
		(net "M_L_CPU1_SA_CA<3>")
	)
	(segment
		(start 151.63038 -253.334774)
		(end 162.82416 -253.334774)
		(width 0.14478)
		(layer "In11.Cu")
		(net "M_L_CPU1_SA_CA<3>")
	)
	(segment
		(start 141.093444 -253.877064)
		(end 141.101826 -253.88189)
		(width 0.0889)
		(layer "In11.Cu")
		(net "M_L_CPU1_SA_CA<3>")
	)
	(segment
		(start 145.144744 -253.957836)
		(end 146.77136 -253.957836)
		(width 0.0889)
		(layer "In11.Cu")
		(net "M_L_CPU1_SA_CA<3>")
	)
	(segment
		(start 165.813232 -252.39599)
		(end 165.813232 -251.924566)
		(width 0.14478)
		(layer "In11.Cu")
		(net "M_L_CPU1_SA_CA<3>")
	)
	(segment
		(start 138.09472 -254.20447)
		(end 137.940796 -253.93904)
		(width 0.0889)
		(layer "In11.Cu")
		(net "M_L_CPU1_SA_CA<3>")
	)
	(segment
		(start 167.322754 -251.779786)
		(end 167.467534 -251.924566)
		(width 0.14478)
		(layer "In11.Cu")
		(net "M_L_CPU1_SA_CA<3>")
	)
	(segment
		(start 166.77132 -252.54077)
		(end 166.9161 -252.39599)
		(width 0.14478)
		(layer "In11.Cu")
		(net "M_L_CPU1_SA_CA<3>")
	)
	(segment
		(start 195.867274 -252.160278)
		(end 197.567296 -250.460256)
		(width 0.14478)
		(layer "In11.Cu")
		(net "M_L_CPU1_SA_CA<3>")
	)
	(segment
		(start 147.819618 -254.733298)
		(end 150.231856 -254.733298)
		(width 0.14478)
		(layer "In11.Cu")
		(net "M_L_CPU1_SA_CA<3>")
	)
	(segment
		(start 162.82416 -253.334774)
		(end 163.998656 -252.160278)
		(width 0.14478)
		(layer "In11.Cu")
		(net "M_L_CPU1_SA_CA<3>")
	)
	(arc
		(start 141.101826 -253.88189)
		(mid 141.384782 -253.958067)
		(end 141.667738 -253.88189)
		(width 0.0889)
		(layer "In11.Cu")
		(net "M_L_CPU1_SA_CA<3>")
	)
	(arc
		(start 138.84783 -253.88189)
		(mid 139.034774 -253.831635)
		(end 139.221718 -253.88189)
		(width 0.0889)
		(layer "In11.Cu")
		(net "M_L_CPU1_SA_CA<3>")
	)
	(arc
		(start 138.281918 -253.88189)
		(mid 138.564874 -253.958067)
		(end 138.84783 -253.88189)
		(width 0.0889)
		(layer "In11.Cu")
		(net "M_L_CPU1_SA_CA<3>")
	)
	(arc
		(start 140.727684 -253.88189)
		(mid 140.909935 -253.83154)
		(end 141.093444 -253.877064)
		(width 0.0889)
		(layer "In11.Cu")
		(net "M_L_CPU1_SA_CA<3>")
	)
	(arc
		(start 137.963148 -253.855728)
		(mid 138.12548 -253.83291)
		(end 138.281918 -253.88189)
		(width 0.0889)
		(layer "In11.Cu")
		(net "M_L_CPU1_SA_CA<3>")
	)
	(arc
		(start 142.04188 -253.88189)
		(mid 142.324836 -253.958067)
		(end 142.607792 -253.88189)
		(width 0.0889)
		(layer "In11.Cu")
		(net "M_L_CPU1_SA_CA<3>")
	)
	(arc
		(start 142.98168 -253.88189)
		(mid 143.264636 -253.958067)
		(end 143.547592 -253.88189)
		(width 0.0889)
		(layer "In11.Cu")
		(net "M_L_CPU1_SA_CA<3>")
	)
	(arc
		(start 140.161772 -253.88189)
		(mid 140.444728 -253.958067)
		(end 140.727684 -253.88189)
		(width 0.0889)
		(layer "In11.Cu")
		(net "M_L_CPU1_SA_CA<3>")
	)
	(arc
		(start 143.547592 -253.88189)
		(mid 143.73479 -253.831508)
		(end 143.921988 -253.88189)
		(width 0.0889)
		(layer "In11.Cu")
		(net "M_L_CPU1_SA_CA<3>")
	)
	(arc
		(start 142.607792 -253.88189)
		(mid 142.794736 -253.831635)
		(end 142.98168 -253.88189)
		(width 0.0889)
		(layer "In11.Cu")
		(net "M_L_CPU1_SA_CA<3>")
	)
	(arc
		(start 141.67612 -253.877064)
		(mid 141.859628 -253.83157)
		(end 142.04188 -253.88189)
		(width 0.0889)
		(layer "In11.Cu")
		(net "M_L_CPU1_SA_CA<3>")
	)
	(arc
		(start 143.921988 -253.88189)
		(mid 144.199055 -253.958161)
		(end 144.47774 -253.887986)
		(width 0.0889)
		(layer "In11.Cu")
		(net "M_L_CPU1_SA_CA<3>")
	)
	(arc
		(start 139.221718 -253.88189)
		(mid 139.504674 -253.958067)
		(end 139.78763 -253.88189)
		(width 0.0889)
		(layer "In11.Cu")
		(net "M_L_CPU1_SA_CA<3>")
	)
	(arc
		(start 139.78763 -253.88189)
		(mid 139.969881 -253.83154)
		(end 140.15339 -253.877064)
		(width 0.0889)
		(layer "In11.Cu")
		(net "M_L_CPU1_SA_CA<3>")
	)
	(arc
		(start 144.488154 -253.88189)
		(mid 144.675098 -253.831635)
		(end 144.862042 -253.88189)
		(width 0.0889)
		(layer "In11.Cu")
		(net "M_L_CPU1_SA_CA<3>")
	)
	(arc
		(start 144.862042 -253.88189)
		(mid 144.998376 -253.938533)
		(end 145.144744 -253.957836)
		(width 0.0889)
		(layer "In11.Cu")
		(net "M_L_CPU1_SA_CA<3>")
	)
	(segment
		(start 137.157968 -253.660402)
		(end 137.62482 -253.394464)
		(width 0.10668)
		(layer "F.Cu")
		(net "M_L_CPU1_SA_CA<2>")
	)
	(segment
		(start 144.38376 -253.72187)
		(end 144.392142 -253.717044)
		(width 0.0889)
		(layer "In11.Cu")
		(net "M_L_CPU1_SA_CA<2>")
	)
	(segment
		(start 205.823058 -249.610372)
		(end 206.248 -249.18543)
		(width 0.14478)
		(layer "In11.Cu")
		(net "M_L_CPU1_SA_CA<2>")
	)
	(segment
		(start 139.31773 -253.717044)
		(end 139.326112 -253.72187)
		(width 0.0889)
		(layer "In11.Cu")
		(net "M_L_CPU1_SA_CA<2>")
	)
	(segment
		(start 138.743436 -253.72187)
		(end 138.751818 -253.717044)
		(width 0.0889)
		(layer "In11.Cu")
		(net "M_L_CPU1_SA_CA<2>")
	)
	(segment
		(start 140.257784 -253.717044)
		(end 140.266166 -253.72187)
		(width 0.0889)
		(layer "In11.Cu")
		(net "M_L_CPU1_SA_CA<2>")
	)
	(segment
		(start 147.455382 -254.278638)
		(end 147.773644 -254.278638)
		(width 0.0889)
		(layer "In11.Cu")
		(net "M_L_CPU1_SA_CA<2>")
	)
	(segment
		(start 137.62482 -253.394464)
		(end 137.778744 -253.659894)
		(width 0.0889)
		(layer "In11.Cu")
		(net "M_L_CPU1_SA_CA<2>")
	)
	(segment
		(start 150.043134 -254.278638)
		(end 151.441658 -252.880114)
		(width 0.14478)
		(layer "In11.Cu")
		(net "M_L_CPU1_SA_CA<2>")
	)
	(segment
		(start 162.618928 -252.880114)
		(end 164.188648 -251.310394)
		(width 0.14478)
		(layer "In11.Cu")
		(net "M_L_CPU1_SA_CA<2>")
	)
	(segment
		(start 195.892166 -251.310394)
		(end 197.592188 -249.610372)
		(width 0.14478)
		(layer "In11.Cu")
		(net "M_L_CPU1_SA_CA<2>")
	)
	(segment
		(start 197.592188 -249.610372)
		(end 205.823058 -249.610372)
		(width 0.14478)
		(layer "In11.Cu")
		(net "M_L_CPU1_SA_CA<2>")
	)
	(segment
		(start 143.077692 -253.717044)
		(end 143.086074 -253.72187)
		(width 0.0889)
		(layer "In11.Cu")
		(net "M_L_CPU1_SA_CA<2>")
	)
	(segment
		(start 151.441658 -252.880114)
		(end 162.618928 -252.880114)
		(width 0.14478)
		(layer "In11.Cu")
		(net "M_L_CPU1_SA_CA<2>")
	)
	(segment
		(start 137.778744 -253.659894)
		(end 137.874756 -253.685294)
		(width 0.0889)
		(layer "In11.Cu")
		(net "M_L_CPU1_SA_CA<2>")
	)
	(segment
		(start 147.773644 -254.278638)
		(end 150.043134 -254.278638)
		(width 0.14478)
		(layer "In11.Cu")
		(net "M_L_CPU1_SA_CA<2>")
	)
	(segment
		(start 144.947386 -253.710948)
		(end 144.9578 -253.717044)
		(width 0.0889)
		(layer "In11.Cu")
		(net "M_L_CPU1_SA_CA<2>")
	)
	(segment
		(start 145.144744 -253.767336)
		(end 146.94408 -253.767336)
		(width 0.0889)
		(layer "In11.Cu")
		(net "M_L_CPU1_SA_CA<2>")
	)
	(segment
		(start 164.188648 -251.310394)
		(end 195.892166 -251.310394)
		(width 0.14478)
		(layer "In11.Cu")
		(net "M_L_CPU1_SA_CA<2>")
	)
	(segment
		(start 143.451834 -253.717044)
		(end 143.462248 -253.710948)
		(width 0.0889)
		(layer "In11.Cu")
		(net "M_L_CPU1_SA_CA<2>")
	)
	(segment
		(start 146.94408 -253.767336)
		(end 147.455382 -254.278638)
		(width 0.0889)
		(layer "In11.Cu")
		(net "M_L_CPU1_SA_CA<2>")
	)
	(segment
		(start 142.503398 -253.72187)
		(end 142.51178 -253.717044)
		(width 0.0889)
		(layer "In11.Cu")
		(net "M_L_CPU1_SA_CA<2>")
	)
	(arc
		(start 138.377676 -253.717044)
		(mid 138.559927 -253.767394)
		(end 138.743436 -253.72187)
		(width 0.0889)
		(layer "In11.Cu")
		(net "M_L_CPU1_SA_CA<2>")
	)
	(arc
		(start 139.691872 -253.717044)
		(mid 139.974828 -253.640867)
		(end 140.257784 -253.717044)
		(width 0.0889)
		(layer "In11.Cu")
		(net "M_L_CPU1_SA_CA<2>")
	)
	(arc
		(start 141.571726 -253.717044)
		(mid 141.854682 -253.640867)
		(end 142.137638 -253.717044)
		(width 0.0889)
		(layer "In11.Cu")
		(net "M_L_CPU1_SA_CA<2>")
	)
	(arc
		(start 143.462248 -253.710948)
		(mid 143.740934 -253.640728)
		(end 144.018 -253.717044)
		(width 0.0889)
		(layer "In11.Cu")
		(net "M_L_CPU1_SA_CA<2>")
	)
	(arc
		(start 144.018 -253.717044)
		(mid 144.200251 -253.767394)
		(end 144.38376 -253.72187)
		(width 0.0889)
		(layer "In11.Cu")
		(net "M_L_CPU1_SA_CA<2>")
	)
	(arc
		(start 139.326112 -253.72187)
		(mid 139.50962 -253.767364)
		(end 139.691872 -253.717044)
		(width 0.0889)
		(layer "In11.Cu")
		(net "M_L_CPU1_SA_CA<2>")
	)
	(arc
		(start 142.51178 -253.717044)
		(mid 142.794736 -253.640867)
		(end 143.077692 -253.717044)
		(width 0.0889)
		(layer "In11.Cu")
		(net "M_L_CPU1_SA_CA<2>")
	)
	(arc
		(start 140.631926 -253.717044)
		(mid 140.914882 -253.640867)
		(end 141.197838 -253.717044)
		(width 0.0889)
		(layer "In11.Cu")
		(net "M_L_CPU1_SA_CA<2>")
	)
	(arc
		(start 144.9578 -253.717044)
		(mid 145.047949 -253.754541)
		(end 145.144744 -253.767336)
		(width 0.0889)
		(layer "In11.Cu")
		(net "M_L_CPU1_SA_CA<2>")
	)
	(arc
		(start 138.751818 -253.717044)
		(mid 139.034774 -253.640867)
		(end 139.31773 -253.717044)
		(width 0.0889)
		(layer "In11.Cu")
		(net "M_L_CPU1_SA_CA<2>")
	)
	(arc
		(start 143.086074 -253.72187)
		(mid 143.269582 -253.767364)
		(end 143.451834 -253.717044)
		(width 0.0889)
		(layer "In11.Cu")
		(net "M_L_CPU1_SA_CA<2>")
	)
	(arc
		(start 137.874756 -253.685294)
		(mid 138.129964 -253.641817)
		(end 138.377676 -253.717044)
		(width 0.0889)
		(layer "In11.Cu")
		(net "M_L_CPU1_SA_CA<2>")
	)
	(arc
		(start 142.137638 -253.717044)
		(mid 142.319889 -253.767394)
		(end 142.503398 -253.72187)
		(width 0.0889)
		(layer "In11.Cu")
		(net "M_L_CPU1_SA_CA<2>")
	)
	(arc
		(start 141.197838 -253.717044)
		(mid 141.384782 -253.767299)
		(end 141.571726 -253.717044)
		(width 0.0889)
		(layer "In11.Cu")
		(net "M_L_CPU1_SA_CA<2>")
	)
	(arc
		(start 140.266166 -253.72187)
		(mid 140.449674 -253.767364)
		(end 140.631926 -253.717044)
		(width 0.0889)
		(layer "In11.Cu")
		(net "M_L_CPU1_SA_CA<2>")
	)
	(arc
		(start 144.392142 -253.717044)
		(mid 144.668955 -253.640901)
		(end 144.947386 -253.710948)
		(width 0.0889)
		(layer "In11.Cu")
		(net "M_L_CPU1_SA_CA<2>")
	)
	(segment
		(start 139.037822 -253.660402)
		(end 139.504674 -253.394464)
		(width 0.10668)
		(layer "F.Cu")
		(net "M_L_CPU1_SA_CA<1>")
	)
	(segment
		(start 144.016984 -253.072138)
		(end 144.0307 -253.064264)
		(width 0.0889)
		(layer "In11.Cu")
		(net "M_L_CPU1_SA_CA<1>")
	)
	(segment
		(start 144.005046 -253.078996)
		(end 144.016984 -253.072138)
		(width 0.0889)
		(layer "In11.Cu")
		(net "M_L_CPU1_SA_CA<1>")
	)
	(segment
		(start 192.057528 -250.315476)
		(end 192.057528 -250.220226)
		(width 0.14478)
		(layer "In11.Cu")
		(net "M_L_CPU1_SA_CA<1>")
	)
	(segment
		(start 147.384262 -253.823978)
		(end 147.790916 -253.823978)
		(width 0.0889)
		(layer "In11.Cu")
		(net "M_L_CPU1_SA_CA<1>")
	)
	(segment
		(start 200.43648 -249.15495)
		(end 200.58126 -249.01017)
		(width 0.14478)
		(layer "In11.Cu")
		(net "M_L_CPU1_SA_CA<1>")
	)
	(segment
		(start 201.722736 -248.760488)
		(end 202.147932 -248.335292)
		(width 0.14478)
		(layer "In11.Cu")
		(net "M_L_CPU1_SA_CA<1>")
	)
	(segment
		(start 201.132694 -248.510806)
		(end 201.132694 -248.615708)
		(width 0.14478)
		(layer "In11.Cu")
		(net "M_L_CPU1_SA_CA<1>")
	)
	(segment
		(start 199.478392 -248.615708)
		(end 199.478392 -248.510806)
		(width 0.14478)
		(layer "In11.Cu")
		(net "M_L_CPU1_SA_CA<1>")
	)
	(segment
		(start 193.015616 -250.845066)
		(end 193.160396 -250.700286)
		(width 0.14478)
		(layer "In11.Cu")
		(net "M_L_CPU1_SA_CA<1>")
	)
	(segment
		(start 192.608962 -250.220226)
		(end 192.608962 -250.700286)
		(width 0.14478)
		(layer "In11.Cu")
		(net "M_L_CPU1_SA_CA<1>")
	)
	(segment
		(start 201.132694 -248.615708)
		(end 201.277474 -248.760488)
		(width 0.14478)
		(layer "In11.Cu")
		(net "M_L_CPU1_SA_CA<1>")
	)
	(segment
		(start 146.29257 -253.415546)
		(end 146.97583 -253.415546)
		(width 0.0889)
		(layer "In11.Cu")
		(net "M_L_CPU1_SA_CA<1>")
	)
	(segment
		(start 192.202308 -250.075446)
		(end 192.464182 -250.075446)
		(width 0.14478)
		(layer "In11.Cu")
		(net "M_L_CPU1_SA_CA<1>")
	)
	(segment
		(start 193.85661 -250.460256)
		(end 195.964556 -250.460256)
		(width 0.14478)
		(layer "In11.Cu")
		(net "M_L_CPU1_SA_CA<1>")
	)
	(segment
		(start 199.885046 -248.366026)
		(end 200.029826 -248.510806)
		(width 0.14478)
		(layer "In11.Cu")
		(net "M_L_CPU1_SA_CA<1>")
	)
	(segment
		(start 192.753742 -250.845066)
		(end 193.015616 -250.845066)
		(width 0.14478)
		(layer "In11.Cu")
		(net "M_L_CPU1_SA_CA<1>")
	)
	(segment
		(start 199.478392 -248.510806)
		(end 199.623172 -248.366026)
		(width 0.14478)
		(layer "In11.Cu")
		(net "M_L_CPU1_SA_CA<1>")
	)
	(segment
		(start 145.898108 -253.021084)
		(end 146.29257 -253.415546)
		(width 0.0889)
		(layer "In11.Cu")
		(net "M_L_CPU1_SA_CA<1>")
	)
	(segment
		(start 162.296348 -252.425454)
		(end 164.261546 -250.460256)
		(width 0.14478)
		(layer "In11.Cu")
		(net "M_L_CPU1_SA_CA<1>")
	)
	(segment
		(start 195.964556 -250.460256)
		(end 197.664324 -248.760488)
		(width 0.14478)
		(layer "In11.Cu")
		(net "M_L_CPU1_SA_CA<1>")
	)
	(segment
		(start 201.277474 -248.760488)
		(end 201.722736 -248.760488)
		(width 0.14478)
		(layer "In11.Cu")
		(net "M_L_CPU1_SA_CA<1>")
	)
	(segment
		(start 193.160396 -250.220226)
		(end 193.305176 -250.075446)
		(width 0.14478)
		(layer "In11.Cu")
		(net "M_L_CPU1_SA_CA<1>")
	)
	(segment
		(start 164.261546 -250.460256)
		(end 191.912748 -250.460256)
		(width 0.14478)
		(layer "In11.Cu")
		(net "M_L_CPU1_SA_CA<1>")
	)
	(segment
		(start 145.144744 -253.021084)
		(end 145.898108 -253.021084)
		(width 0.0889)
		(layer "In11.Cu")
		(net "M_L_CPU1_SA_CA<1>")
	)
	(segment
		(start 191.912748 -250.460256)
		(end 192.057528 -250.315476)
		(width 0.14478)
		(layer "In11.Cu")
		(net "M_L_CPU1_SA_CA<1>")
	)
	(segment
		(start 200.029826 -248.510806)
		(end 200.029826 -249.01017)
		(width 0.14478)
		(layer "In11.Cu")
		(net "M_L_CPU1_SA_CA<1>")
	)
	(segment
		(start 200.174606 -249.15495)
		(end 200.43648 -249.15495)
		(width 0.14478)
		(layer "In11.Cu")
		(net "M_L_CPU1_SA_CA<1>")
	)
	(segment
		(start 199.623172 -248.366026)
		(end 199.885046 -248.366026)
		(width 0.14478)
		(layer "In11.Cu")
		(net "M_L_CPU1_SA_CA<1>")
	)
	(segment
		(start 143.077692 -253.071884)
		(end 143.086074 -253.067058)
		(width 0.0889)
		(layer "In11.Cu")
		(net "M_L_CPU1_SA_CA<1>")
	)
	(segment
		(start 149.854666 -253.823978)
		(end 151.25319 -252.425454)
		(width 0.14478)
		(layer "In11.Cu")
		(net "M_L_CPU1_SA_CA<1>")
	)
	(segment
		(start 141.563344 -253.067058)
		(end 141.571726 -253.071884)
		(width 0.0889)
		(layer "In11.Cu")
		(net "M_L_CPU1_SA_CA<1>")
	)
	(segment
		(start 197.664324 -248.760488)
		(end 199.333612 -248.760488)
		(width 0.14478)
		(layer "In11.Cu")
		(net "M_L_CPU1_SA_CA<1>")
	)
	(segment
		(start 147.790916 -253.823978)
		(end 149.854666 -253.823978)
		(width 0.14478)
		(layer "In11.Cu")
		(net "M_L_CPU1_SA_CA<1>")
	)
	(segment
		(start 200.029826 -249.01017)
		(end 200.174606 -249.15495)
		(width 0.14478)
		(layer "In11.Cu")
		(net "M_L_CPU1_SA_CA<1>")
	)
	(segment
		(start 139.504674 -253.394464)
		(end 139.35075 -253.129034)
		(width 0.0889)
		(layer "In11.Cu")
		(net "M_L_CPU1_SA_CA<1>")
	)
	(segment
		(start 193.160396 -250.700286)
		(end 193.160396 -250.220226)
		(width 0.14478)
		(layer "In11.Cu")
		(net "M_L_CPU1_SA_CA<1>")
	)
	(segment
		(start 192.057528 -250.220226)
		(end 192.202308 -250.075446)
		(width 0.14478)
		(layer "In11.Cu")
		(net "M_L_CPU1_SA_CA<1>")
	)
	(segment
		(start 192.608962 -250.700286)
		(end 192.753742 -250.845066)
		(width 0.14478)
		(layer "In11.Cu")
		(net "M_L_CPU1_SA_CA<1>")
	)
	(segment
		(start 200.72604 -248.366026)
		(end 200.987914 -248.366026)
		(width 0.14478)
		(layer "In11.Cu")
		(net "M_L_CPU1_SA_CA<1>")
	)
	(segment
		(start 199.333612 -248.760488)
		(end 199.478392 -248.615708)
		(width 0.14478)
		(layer "In11.Cu")
		(net "M_L_CPU1_SA_CA<1>")
	)
	(segment
		(start 146.97583 -253.415546)
		(end 147.384262 -253.823978)
		(width 0.0889)
		(layer "In11.Cu")
		(net "M_L_CPU1_SA_CA<1>")
	)
	(segment
		(start 192.464182 -250.075446)
		(end 192.608962 -250.220226)
		(width 0.14478)
		(layer "In11.Cu")
		(net "M_L_CPU1_SA_CA<1>")
	)
	(segment
		(start 200.58126 -248.510806)
		(end 200.72604 -248.366026)
		(width 0.14478)
		(layer "In11.Cu")
		(net "M_L_CPU1_SA_CA<1>")
	)
	(segment
		(start 193.71183 -250.220226)
		(end 193.71183 -250.315476)
		(width 0.14478)
		(layer "In11.Cu")
		(net "M_L_CPU1_SA_CA<1>")
	)
	(segment
		(start 193.71183 -250.315476)
		(end 193.85661 -250.460256)
		(width 0.14478)
		(layer "In11.Cu")
		(net "M_L_CPU1_SA_CA<1>")
	)
	(segment
		(start 200.58126 -249.01017)
		(end 200.58126 -248.510806)
		(width 0.14478)
		(layer "In11.Cu")
		(net "M_L_CPU1_SA_CA<1>")
	)
	(segment
		(start 139.35075 -253.129034)
		(end 139.373102 -253.045722)
		(width 0.0889)
		(layer "In11.Cu")
		(net "M_L_CPU1_SA_CA<1>")
	)
	(segment
		(start 200.987914 -248.366026)
		(end 201.132694 -248.510806)
		(width 0.14478)
		(layer "In11.Cu")
		(net "M_L_CPU1_SA_CA<1>")
	)
	(segment
		(start 142.503398 -253.067058)
		(end 142.51178 -253.071884)
		(width 0.0889)
		(layer "In11.Cu")
		(net "M_L_CPU1_SA_CA<1>")
	)
	(segment
		(start 193.56705 -250.075446)
		(end 193.71183 -250.220226)
		(width 0.14478)
		(layer "In11.Cu")
		(net "M_L_CPU1_SA_CA<1>")
	)
	(segment
		(start 151.25319 -252.425454)
		(end 162.296348 -252.425454)
		(width 0.14478)
		(layer "In11.Cu")
		(net "M_L_CPU1_SA_CA<1>")
	)
	(segment
		(start 144.390618 -253.071884)
		(end 144.408652 -253.082552)
		(width 0.0889)
		(layer "In11.Cu")
		(net "M_L_CPU1_SA_CA<1>")
	)
	(segment
		(start 193.305176 -250.075446)
		(end 193.56705 -250.075446)
		(width 0.14478)
		(layer "In11.Cu")
		(net "M_L_CPU1_SA_CA<1>")
	)
	(arc
		(start 142.137638 -253.071884)
		(mid 142.319889 -253.021534)
		(end 142.503398 -253.067058)
		(width 0.0889)
		(layer "In11.Cu")
		(net "M_L_CPU1_SA_CA<1>")
	)
	(arc
		(start 139.691872 -253.071884)
		(mid 139.974828 -253.148061)
		(end 140.257784 -253.071884)
		(width 0.0889)
		(layer "In11.Cu")
		(net "M_L_CPU1_SA_CA<1>")
	)
	(arc
		(start 143.086074 -253.067058)
		(mid 143.269582 -253.021564)
		(end 143.451834 -253.071884)
		(width 0.0889)
		(layer "In11.Cu")
		(net "M_L_CPU1_SA_CA<1>")
	)
	(arc
		(start 139.373102 -253.045722)
		(mid 139.535434 -253.022904)
		(end 139.691872 -253.071884)
		(width 0.0889)
		(layer "In11.Cu")
		(net "M_L_CPU1_SA_CA<1>")
	)
	(arc
		(start 142.51178 -253.071884)
		(mid 142.794736 -253.148061)
		(end 143.077692 -253.071884)
		(width 0.0889)
		(layer "In11.Cu")
		(net "M_L_CPU1_SA_CA<1>")
	)
	(arc
		(start 144.957292 -253.071884)
		(mid 145.047655 -253.034074)
		(end 145.144744 -253.021084)
		(width 0.0889)
		(layer "In11.Cu")
		(net "M_L_CPU1_SA_CA<1>")
	)
	(arc
		(start 144.0307 -253.064264)
		(mid 144.21163 -253.021786)
		(end 144.390618 -253.071884)
		(width 0.0889)
		(layer "In11.Cu")
		(net "M_L_CPU1_SA_CA<1>")
	)
	(arc
		(start 140.631672 -253.071884)
		(mid 140.914628 -253.148061)
		(end 141.197584 -253.071884)
		(width 0.0889)
		(layer "In11.Cu")
		(net "M_L_CPU1_SA_CA<1>")
	)
	(arc
		(start 140.257784 -253.071884)
		(mid 140.444728 -253.021629)
		(end 140.631672 -253.071884)
		(width 0.0889)
		(layer "In11.Cu")
		(net "M_L_CPU1_SA_CA<1>")
	)
	(arc
		(start 143.451834 -253.071884)
		(mid 143.727512 -253.148014)
		(end 144.005046 -253.078996)
		(width 0.0889)
		(layer "In11.Cu")
		(net "M_L_CPU1_SA_CA<1>")
	)
	(arc
		(start 141.197584 -253.071884)
		(mid 141.379835 -253.021534)
		(end 141.563344 -253.067058)
		(width 0.0889)
		(layer "In11.Cu")
		(net "M_L_CPU1_SA_CA<1>")
	)
	(arc
		(start 144.408652 -253.082552)
		(mid 144.684347 -253.148395)
		(end 144.957292 -253.071884)
		(width 0.0889)
		(layer "In11.Cu")
		(net "M_L_CPU1_SA_CA<1>")
	)
	(arc
		(start 141.571726 -253.071884)
		(mid 141.854682 -253.148061)
		(end 142.137638 -253.071884)
		(width 0.0889)
		(layer "In11.Cu")
		(net "M_L_CPU1_SA_CA<1>")
	)
	(segment
		(start 138.567922 -252.850396)
		(end 139.034774 -252.584458)
		(width 0.10668)
		(layer "F.Cu")
		(net "M_L_CPU1_SA_CA<0>")
	)
	(segment
		(start 145.144744 -252.830584)
		(end 145.977102 -252.830584)
		(width 0.0889)
		(layer "In11.Cu")
		(net "M_L_CPU1_SA_CA<0>")
	)
	(segment
		(start 162.10788 -251.970794)
		(end 164.468302 -249.610372)
		(width 0.14478)
		(layer "In11.Cu")
		(net "M_L_CPU1_SA_CA<0>")
	)
	(segment
		(start 147.779486 -253.369318)
		(end 149.666198 -253.369318)
		(width 0.14478)
		(layer "In11.Cu")
		(net "M_L_CPU1_SA_CA<0>")
	)
	(segment
		(start 205.823058 -247.91035)
		(end 206.248 -247.485408)
		(width 0.14478)
		(layer "In11.Cu")
		(net "M_L_CPU1_SA_CA<0>")
	)
	(segment
		(start 195.951602 -249.610372)
		(end 197.651624 -247.91035)
		(width 0.14478)
		(layer "In11.Cu")
		(net "M_L_CPU1_SA_CA<0>")
	)
	(segment
		(start 143.905224 -252.916182)
		(end 143.92148 -252.906784)
		(width 0.0889)
		(layer "In11.Cu")
		(net "M_L_CPU1_SA_CA<0>")
	)
	(segment
		(start 139.188698 -252.849888)
		(end 139.28471 -252.875288)
		(width 0.0889)
		(layer "In11.Cu")
		(net "M_L_CPU1_SA_CA<0>")
	)
	(segment
		(start 141.667738 -252.907038)
		(end 141.67612 -252.911864)
		(width 0.0889)
		(layer "In11.Cu")
		(net "M_L_CPU1_SA_CA<0>")
	)
	(segment
		(start 139.034774 -252.584458)
		(end 139.188698 -252.849888)
		(width 0.0889)
		(layer "In11.Cu")
		(net "M_L_CPU1_SA_CA<0>")
	)
	(segment
		(start 151.064722 -251.970794)
		(end 162.10788 -251.970794)
		(width 0.14478)
		(layer "In11.Cu")
		(net "M_L_CPU1_SA_CA<0>")
	)
	(segment
		(start 143.92148 -252.906784)
		(end 143.933418 -252.899926)
		(width 0.0889)
		(layer "In11.Cu")
		(net "M_L_CPU1_SA_CA<0>")
	)
	(segment
		(start 140.15339 -252.911864)
		(end 140.161772 -252.907038)
		(width 0.0889)
		(layer "In11.Cu")
		(net "M_L_CPU1_SA_CA<0>")
	)
	(segment
		(start 140.727684 -252.907038)
		(end 140.736066 -252.911864)
		(width 0.0889)
		(layer "In11.Cu")
		(net "M_L_CPU1_SA_CA<0>")
	)
	(segment
		(start 145.977102 -252.830584)
		(end 146.371564 -253.225046)
		(width 0.0889)
		(layer "In11.Cu")
		(net "M_L_CPU1_SA_CA<0>")
	)
	(segment
		(start 147.22221 -253.225046)
		(end 147.366482 -253.369318)
		(width 0.0889)
		(layer "In11.Cu")
		(net "M_L_CPU1_SA_CA<0>")
	)
	(segment
		(start 149.666198 -253.369318)
		(end 151.064722 -251.970794)
		(width 0.14478)
		(layer "In11.Cu")
		(net "M_L_CPU1_SA_CA<0>")
	)
	(segment
		(start 146.371564 -253.225046)
		(end 147.22221 -253.225046)
		(width 0.0889)
		(layer "In11.Cu")
		(net "M_L_CPU1_SA_CA<0>")
	)
	(segment
		(start 144.48663 -252.907038)
		(end 144.498314 -252.913896)
		(width 0.0889)
		(layer "In11.Cu")
		(net "M_L_CPU1_SA_CA<0>")
	)
	(segment
		(start 147.366482 -253.369318)
		(end 147.779486 -253.369318)
		(width 0.0889)
		(layer "In11.Cu")
		(net "M_L_CPU1_SA_CA<0>")
	)
	(segment
		(start 164.468302 -249.610372)
		(end 195.951602 -249.610372)
		(width 0.14478)
		(layer "In11.Cu")
		(net "M_L_CPU1_SA_CA<0>")
	)
	(segment
		(start 197.651624 -247.91035)
		(end 205.823058 -247.91035)
		(width 0.14478)
		(layer "In11.Cu")
		(net "M_L_CPU1_SA_CA<0>")
	)
	(arc
		(start 144.861026 -252.907038)
		(mid 144.997819 -252.850016)
		(end 145.144744 -252.830584)
		(width 0.0889)
		(layer "In11.Cu")
		(net "M_L_CPU1_SA_CA<0>")
	)
	(arc
		(start 142.04188 -252.907038)
		(mid 142.324836 -252.830861)
		(end 142.607792 -252.907038)
		(width 0.0889)
		(layer "In11.Cu")
		(net "M_L_CPU1_SA_CA<0>")
	)
	(arc
		(start 143.547592 -252.907038)
		(mid 143.725242 -252.957298)
		(end 143.905224 -252.916182)
		(width 0.0889)
		(layer "In11.Cu")
		(net "M_L_CPU1_SA_CA<0>")
	)
	(arc
		(start 140.161772 -252.907038)
		(mid 140.444728 -252.830861)
		(end 140.727684 -252.907038)
		(width 0.0889)
		(layer "In11.Cu")
		(net "M_L_CPU1_SA_CA<0>")
	)
	(arc
		(start 139.28471 -252.875288)
		(mid 139.539918 -252.831811)
		(end 139.78763 -252.907038)
		(width 0.0889)
		(layer "In11.Cu")
		(net "M_L_CPU1_SA_CA<0>")
	)
	(arc
		(start 143.933418 -252.899926)
		(mid 144.210952 -252.830945)
		(end 144.48663 -252.907038)
		(width 0.0889)
		(layer "In11.Cu")
		(net "M_L_CPU1_SA_CA<0>")
	)
	(arc
		(start 140.736066 -252.911864)
		(mid 140.919574 -252.957358)
		(end 141.101826 -252.907038)
		(width 0.0889)
		(layer "In11.Cu")
		(net "M_L_CPU1_SA_CA<0>")
	)
	(arc
		(start 141.67612 -252.911864)
		(mid 141.859628 -252.957358)
		(end 142.04188 -252.907038)
		(width 0.0889)
		(layer "In11.Cu")
		(net "M_L_CPU1_SA_CA<0>")
	)
	(arc
		(start 141.101826 -252.907038)
		(mid 141.384782 -252.830861)
		(end 141.667738 -252.907038)
		(width 0.0889)
		(layer "In11.Cu")
		(net "M_L_CPU1_SA_CA<0>")
	)
	(arc
		(start 142.607792 -252.907038)
		(mid 142.794736 -252.957293)
		(end 142.98168 -252.907038)
		(width 0.0889)
		(layer "In11.Cu")
		(net "M_L_CPU1_SA_CA<0>")
	)
	(arc
		(start 144.498314 -252.913896)
		(mid 144.680569 -252.957549)
		(end 144.861026 -252.907038)
		(width 0.0889)
		(layer "In11.Cu")
		(net "M_L_CPU1_SA_CA<0>")
	)
	(arc
		(start 139.78763 -252.907038)
		(mid 139.969881 -252.957388)
		(end 140.15339 -252.911864)
		(width 0.0889)
		(layer "In11.Cu")
		(net "M_L_CPU1_SA_CA<0>")
	)
	(arc
		(start 142.98168 -252.907038)
		(mid 143.264636 -252.830861)
		(end 143.547592 -252.907038)
		(width 0.0889)
		(layer "In11.Cu")
		(net "M_L_CPU1_SA_CA<0>")
	)
	(segment
		(start 137.627868 -251.230384)
		(end 138.09472 -250.964446)
		(width 0.10668)
		(layer "F.Cu")
		(net "M_L_CPU1_RESET_N")
	)
	(segment
		(start 197.350888 -245.360444)
		(end 201.722736 -245.360444)
		(width 0.11684)
		(layer "In11.Cu")
		(net "M_L_CPU1_RESET_N")
	)
	(segment
		(start 201.722736 -245.360444)
		(end 202.147932 -244.935248)
		(width 0.11684)
		(layer "In11.Cu")
		(net "M_L_CPU1_RESET_N")
	)
	(segment
		(start 160.98901 -250.315984)
		(end 164.244528 -247.060466)
		(width 0.11684)
		(layer "In11.Cu")
		(net "M_L_CPU1_RESET_N")
	)
	(segment
		(start 164.244528 -247.060466)
		(end 195.650866 -247.060466)
		(width 0.11684)
		(layer "In11.Cu")
		(net "M_L_CPU1_RESET_N")
	)
	(segment
		(start 141.093444 -250.63704)
		(end 141.101826 -250.641866)
		(width 0.0889)
		(layer "In11.Cu")
		(net "M_L_CPU1_RESET_N")
	)
	(segment
		(start 147.768818 -251.700538)
		(end 148.99386 -251.700538)
		(width 0.11684)
		(layer "In11.Cu")
		(net "M_L_CPU1_RESET_N")
	)
	(segment
		(start 138.09472 -250.964446)
		(end 137.940796 -250.699016)
		(width 0.0889)
		(layer "In11.Cu")
		(net "M_L_CPU1_RESET_N")
	)
	(segment
		(start 147.22729 -251.424186)
		(end 147.503642 -251.700538)
		(width 0.0889)
		(layer "In11.Cu")
		(net "M_L_CPU1_RESET_N")
	)
	(segment
		(start 144.853406 -250.63704)
		(end 144.861788 -250.641866)
		(width 0.0889)
		(layer "In11.Cu")
		(net "M_L_CPU1_RESET_N")
	)
	(segment
		(start 141.667738 -250.641866)
		(end 141.67612 -250.63704)
		(width 0.0889)
		(layer "In11.Cu")
		(net "M_L_CPU1_RESET_N")
	)
	(segment
		(start 146.81835 -250.718066)
		(end 147.22729 -251.127006)
		(width 0.0889)
		(layer "In11.Cu")
		(net "M_L_CPU1_RESET_N")
	)
	(segment
		(start 148.99386 -251.700538)
		(end 150.378414 -250.315984)
		(width 0.11684)
		(layer "In11.Cu")
		(net "M_L_CPU1_RESET_N")
	)
	(segment
		(start 195.650866 -247.060466)
		(end 197.350888 -245.360444)
		(width 0.11684)
		(layer "In11.Cu")
		(net "M_L_CPU1_RESET_N")
	)
	(segment
		(start 147.503642 -251.700538)
		(end 147.768818 -251.700538)
		(width 0.0889)
		(layer "In11.Cu")
		(net "M_L_CPU1_RESET_N")
	)
	(segment
		(start 145.144744 -250.718066)
		(end 146.81835 -250.718066)
		(width 0.0889)
		(layer "In11.Cu")
		(net "M_L_CPU1_RESET_N")
	)
	(segment
		(start 147.22729 -251.127006)
		(end 147.22729 -251.424186)
		(width 0.0889)
		(layer "In11.Cu")
		(net "M_L_CPU1_RESET_N")
	)
	(segment
		(start 143.913352 -250.63704)
		(end 143.921734 -250.641866)
		(width 0.0889)
		(layer "In11.Cu")
		(net "M_L_CPU1_RESET_N")
	)
	(segment
		(start 137.940796 -250.699016)
		(end 137.963148 -250.615704)
		(width 0.0889)
		(layer "In11.Cu")
		(net "M_L_CPU1_RESET_N")
	)
	(segment
		(start 140.15339 -250.63704)
		(end 140.161772 -250.641866)
		(width 0.0889)
		(layer "In11.Cu")
		(net "M_L_CPU1_RESET_N")
	)
	(segment
		(start 150.378414 -250.315984)
		(end 160.98901 -250.315984)
		(width 0.11684)
		(layer "In11.Cu")
		(net "M_L_CPU1_RESET_N")
	)
	(arc
		(start 140.727684 -250.641866)
		(mid 140.909935 -250.591516)
		(end 141.093444 -250.63704)
		(width 0.0889)
		(layer "In11.Cu")
		(net "M_L_CPU1_RESET_N")
	)
	(arc
		(start 138.84783 -250.641866)
		(mid 139.034774 -250.591611)
		(end 139.221718 -250.641866)
		(width 0.0889)
		(layer "In11.Cu")
		(net "M_L_CPU1_RESET_N")
	)
	(arc
		(start 139.221718 -250.641866)
		(mid 139.504674 -250.718043)
		(end 139.78763 -250.641866)
		(width 0.0889)
		(layer "In11.Cu")
		(net "M_L_CPU1_RESET_N")
	)
	(arc
		(start 140.161772 -250.641866)
		(mid 140.444728 -250.718043)
		(end 140.727684 -250.641866)
		(width 0.0889)
		(layer "In11.Cu")
		(net "M_L_CPU1_RESET_N")
	)
	(arc
		(start 144.487646 -250.641866)
		(mid 144.669897 -250.591516)
		(end 144.853406 -250.63704)
		(width 0.0889)
		(layer "In11.Cu")
		(net "M_L_CPU1_RESET_N")
	)
	(arc
		(start 139.78763 -250.641866)
		(mid 139.969881 -250.591516)
		(end 140.15339 -250.63704)
		(width 0.0889)
		(layer "In11.Cu")
		(net "M_L_CPU1_RESET_N")
	)
	(arc
		(start 143.921734 -250.641866)
		(mid 144.20469 -250.718043)
		(end 144.487646 -250.641866)
		(width 0.0889)
		(layer "In11.Cu")
		(net "M_L_CPU1_RESET_N")
	)
	(arc
		(start 142.98168 -250.641866)
		(mid 143.264636 -250.718043)
		(end 143.547592 -250.641866)
		(width 0.0889)
		(layer "In11.Cu")
		(net "M_L_CPU1_RESET_N")
	)
	(arc
		(start 144.861788 -250.641866)
		(mid 144.998224 -250.698691)
		(end 145.144744 -250.718066)
		(width 0.0889)
		(layer "In11.Cu")
		(net "M_L_CPU1_RESET_N")
	)
	(arc
		(start 143.547592 -250.641866)
		(mid 143.729843 -250.591516)
		(end 143.913352 -250.63704)
		(width 0.0889)
		(layer "In11.Cu")
		(net "M_L_CPU1_RESET_N")
	)
	(arc
		(start 137.963148 -250.615704)
		(mid 138.12548 -250.592886)
		(end 138.281918 -250.641866)
		(width 0.0889)
		(layer "In11.Cu")
		(net "M_L_CPU1_RESET_N")
	)
	(arc
		(start 141.101826 -250.641866)
		(mid 141.384782 -250.718043)
		(end 141.667738 -250.641866)
		(width 0.0889)
		(layer "In11.Cu")
		(net "M_L_CPU1_RESET_N")
	)
	(arc
		(start 142.607792 -250.641866)
		(mid 142.794736 -250.591611)
		(end 142.98168 -250.641866)
		(width 0.0889)
		(layer "In11.Cu")
		(net "M_L_CPU1_RESET_N")
	)
	(arc
		(start 142.04188 -250.641866)
		(mid 142.324836 -250.718043)
		(end 142.607792 -250.641866)
		(width 0.0889)
		(layer "In11.Cu")
		(net "M_L_CPU1_RESET_N")
	)
	(arc
		(start 141.67612 -250.63704)
		(mid 141.859628 -250.591546)
		(end 142.04188 -250.641866)
		(width 0.0889)
		(layer "In11.Cu")
		(net "M_L_CPU1_RESET_N")
	)
	(arc
		(start 138.281918 -250.641866)
		(mid 138.564874 -250.718043)
		(end 138.84783 -250.641866)
		(width 0.0889)
		(layer "In11.Cu")
		(net "M_L_CPU1_RESET_N")
	)
	(segment
		(start 138.567922 -256.09042)
		(end 139.034774 -255.824482)
		(width 0.14732)
		(layer "F.Cu")
		(net "M_L_CPU1_CLK_DP<0>")
	)
	(segment
		(start 152.658318 -255.813814)
		(end 158.210758 -255.813814)
		(width 0.16002)
		(layer "In11.Cu")
		(net "M_L_CPU1_CLK_DP<0>")
	)
	(segment
		(start 160.3121 -257.685286)
		(end 160.47212 -257.845306)
		(width 0.16002)
		(layer "In11.Cu")
		(net "M_L_CPU1_CLK_DP<0>")
	)
	(segment
		(start 144.467326 -256.139188)
		(end 144.48536 -256.149602)
		(width 0.09525)
		(layer "In11.Cu")
		(net "M_L_CPU1_CLK_DP<0>")
	)
	(segment
		(start 151.259794 -257.212338)
		(end 152.658318 -255.813814)
		(width 0.16002)
		(layer "In11.Cu")
		(net "M_L_CPU1_CLK_DP<0>")
	)
	(segment
		(start 158.210758 -255.813814)
		(end 158.75381 -256.356866)
		(width 0.16002)
		(layer "In11.Cu")
		(net "M_L_CPU1_CLK_DP<0>")
	)
	(segment
		(start 163.226242 -257.685286)
		(end 163.226242 -256.693924)
		(width 0.16002)
		(layer "In11.Cu")
		(net "M_L_CPU1_CLK_DP<0>")
	)
	(segment
		(start 147.729702 -257.271266)
		(end 147.78863 -257.212338)
		(width 0.09525)
		(layer "In11.Cu")
		(net "M_L_CPU1_CLK_DP<0>")
	)
	(segment
		(start 162.456368 -256.693924)
		(end 162.456368 -257.685286)
		(width 0.16002)
		(layer "In11.Cu")
		(net "M_L_CPU1_CLK_DP<0>")
	)
	(segment
		(start 146.574002 -257.271266)
		(end 147.729702 -257.271266)
		(width 0.09525)
		(layer "In11.Cu")
		(net "M_L_CPU1_CLK_DP<0>")
	)
	(segment
		(start 159.975042 -256.356866)
		(end 160.3121 -256.693924)
		(width 0.16002)
		(layer "In11.Cu")
		(net "M_L_CPU1_CLK_DP<0>")
	)
	(segment
		(start 139.188698 -256.089912)
		(end 139.289536 -256.116582)
		(width 0.09525)
		(layer "In11.Cu")
		(net "M_L_CPU1_CLK_DP<0>")
	)
	(segment
		(start 140.154914 -256.154428)
		(end 140.163296 -256.149602)
		(width 0.09525)
		(layer "In11.Cu")
		(net "M_L_CPU1_CLK_DP<0>")
	)
	(segment
		(start 162.11931 -256.356866)
		(end 162.456368 -256.693924)
		(width 0.16002)
		(layer "In11.Cu")
		(net "M_L_CPU1_CLK_DP<0>")
	)
	(segment
		(start 162.456368 -257.685286)
		(end 162.616388 -257.845306)
		(width 0.16002)
		(layer "In11.Cu")
		(net "M_L_CPU1_CLK_DP<0>")
	)
	(segment
		(start 161.419032 -256.356866)
		(end 162.11931 -256.356866)
		(width 0.16002)
		(layer "In11.Cu")
		(net "M_L_CPU1_CLK_DP<0>")
	)
	(segment
		(start 163.066222 -257.845306)
		(end 163.226242 -257.685286)
		(width 0.16002)
		(layer "In11.Cu")
		(net "M_L_CPU1_CLK_DP<0>")
	)
	(segment
		(start 160.47212 -257.845306)
		(end 160.921954 -257.845306)
		(width 0.16002)
		(layer "In11.Cu")
		(net "M_L_CPU1_CLK_DP<0>")
	)
	(segment
		(start 145.400014 -256.13487)
		(end 145.425414 -256.149602)
		(width 0.09525)
		(layer "In11.Cu")
		(net "M_L_CPU1_CLK_DP<0>")
	)
	(segment
		(start 201.875644 -253.707646)
		(end 202.147932 -253.435358)
		(width 0.16002)
		(layer "In11.Cu")
		(net "M_L_CPU1_CLK_DP<0>")
	)
	(segment
		(start 139.034774 -255.824482)
		(end 139.188698 -256.089912)
		(width 0.09525)
		(layer "In11.Cu")
		(net "M_L_CPU1_CLK_DP<0>")
	)
	(segment
		(start 160.921954 -257.845306)
		(end 161.081974 -257.685286)
		(width 0.16002)
		(layer "In11.Cu")
		(net "M_L_CPU1_CLK_DP<0>")
	)
	(segment
		(start 161.081974 -256.693924)
		(end 161.419032 -256.356866)
		(width 0.16002)
		(layer "In11.Cu")
		(net "M_L_CPU1_CLK_DP<0>")
	)
	(segment
		(start 145.540984 -256.238248)
		(end 146.574002 -257.271266)
		(width 0.09525)
		(layer "In11.Cu")
		(net "M_L_CPU1_CLK_DP<0>")
	)
	(segment
		(start 200.82383 -254.274066)
		(end 201.39025 -253.707646)
		(width 0.16002)
		(layer "In11.Cu")
		(net "M_L_CPU1_CLK_DP<0>")
	)
	(segment
		(start 158.75381 -256.356866)
		(end 159.975042 -256.356866)
		(width 0.16002)
		(layer "In11.Cu")
		(net "M_L_CPU1_CLK_DP<0>")
	)
	(segment
		(start 199.30999 -256.356866)
		(end 200.82383 -254.843026)
		(width 0.16002)
		(layer "In11.Cu")
		(net "M_L_CPU1_CLK_DP<0>")
	)
	(segment
		(start 163.226242 -256.693924)
		(end 163.5633 -256.356866)
		(width 0.16002)
		(layer "In11.Cu")
		(net "M_L_CPU1_CLK_DP<0>")
	)
	(segment
		(start 143.914876 -256.154428)
		(end 143.923258 -256.149602)
		(width 0.09525)
		(layer "In11.Cu")
		(net "M_L_CPU1_CLK_DP<0>")
	)
	(segment
		(start 144.48536 -256.149602)
		(end 144.499838 -256.157984)
		(width 0.09525)
		(layer "In11.Cu")
		(net "M_L_CPU1_CLK_DP<0>")
	)
	(segment
		(start 147.812252 -257.212338)
		(end 151.259794 -257.212338)
		(width 0.16002)
		(layer "In11.Cu")
		(net "M_L_CPU1_CLK_DP<0>")
	)
	(segment
		(start 147.78863 -257.212338)
		(end 147.812252 -257.212338)
		(width 0.09525)
		(layer "In11.Cu")
		(net "M_L_CPU1_CLK_DP<0>")
	)
	(segment
		(start 201.39025 -253.707646)
		(end 201.875644 -253.707646)
		(width 0.16002)
		(layer "In11.Cu")
		(net "M_L_CPU1_CLK_DP<0>")
	)
	(segment
		(start 162.616388 -257.845306)
		(end 163.066222 -257.845306)
		(width 0.16002)
		(layer "In11.Cu")
		(net "M_L_CPU1_CLK_DP<0>")
	)
	(segment
		(start 141.666214 -256.149602)
		(end 141.674596 -256.154428)
		(width 0.09525)
		(layer "In11.Cu")
		(net "M_L_CPU1_CLK_DP<0>")
	)
	(segment
		(start 200.82383 -254.843026)
		(end 200.82383 -254.274066)
		(width 0.16002)
		(layer "In11.Cu")
		(net "M_L_CPU1_CLK_DP<0>")
	)
	(segment
		(start 141.094968 -256.154428)
		(end 141.10335 -256.149602)
		(width 0.09525)
		(layer "In11.Cu")
		(net "M_L_CPU1_CLK_DP<0>")
	)
	(segment
		(start 161.081974 -257.685286)
		(end 161.081974 -256.693924)
		(width 0.16002)
		(layer "In11.Cu")
		(net "M_L_CPU1_CLK_DP<0>")
	)
	(segment
		(start 163.5633 -256.356866)
		(end 199.30999 -256.356866)
		(width 0.16002)
		(layer "In11.Cu")
		(net "M_L_CPU1_CLK_DP<0>")
	)
	(segment
		(start 160.3121 -256.693924)
		(end 160.3121 -257.685286)
		(width 0.16002)
		(layer "In11.Cu")
		(net "M_L_CPU1_CLK_DP<0>")
	)
	(arc
		(start 143.923258 -256.149602)
		(mid 144.193946 -256.07395)
		(end 144.467326 -256.139188)
		(width 0.09525)
		(layer "In11.Cu")
		(net "M_L_CPU1_CLK_DP<0>")
	)
	(arc
		(start 140.72616 -256.149602)
		(mid 140.909935 -256.200374)
		(end 141.094968 -256.154428)
		(width 0.09525)
		(layer "In11.Cu")
		(net "M_L_CPU1_CLK_DP<0>")
	)
	(arc
		(start 145.425414 -256.149602)
		(mid 145.486086 -256.19016)
		(end 145.540984 -256.238248)
		(width 0.09525)
		(layer "In11.Cu")
		(net "M_L_CPU1_CLK_DP<0>")
	)
	(arc
		(start 141.10335 -256.149602)
		(mid 141.384782 -256.073847)
		(end 141.666214 -256.149602)
		(width 0.09525)
		(layer "In11.Cu")
		(net "M_L_CPU1_CLK_DP<0>")
	)
	(arc
		(start 139.309856 -256.108708)
		(mid 139.552568 -256.075825)
		(end 139.786106 -256.149602)
		(width 0.09525)
		(layer "In11.Cu")
		(net "M_L_CPU1_CLK_DP<0>")
	)
	(arc
		(start 142.606268 -256.149602)
		(mid 142.794736 -256.200279)
		(end 142.983204 -256.149602)
		(width 0.09525)
		(layer "In11.Cu")
		(net "M_L_CPU1_CLK_DP<0>")
	)
	(arc
		(start 140.163296 -256.149602)
		(mid 140.444728 -256.073847)
		(end 140.72616 -256.149602)
		(width 0.09525)
		(layer "In11.Cu")
		(net "M_L_CPU1_CLK_DP<0>")
	)
	(arc
		(start 139.289536 -256.116582)
		(mid 139.299658 -256.112547)
		(end 139.309856 -256.108708)
		(width 0.09525)
		(layer "In11.Cu")
		(net "M_L_CPU1_CLK_DP<0>")
	)
	(arc
		(start 141.674596 -256.154428)
		(mid 141.859628 -256.200342)
		(end 142.043404 -256.149602)
		(width 0.09525)
		(layer "In11.Cu")
		(net "M_L_CPU1_CLK_DP<0>")
	)
	(arc
		(start 143.546068 -256.149602)
		(mid 143.729843 -256.200374)
		(end 143.914876 -256.154428)
		(width 0.09525)
		(layer "In11.Cu")
		(net "M_L_CPU1_CLK_DP<0>")
	)
	(arc
		(start 144.499838 -256.157984)
		(mid 144.68227 -256.200424)
		(end 144.86255 -256.149602)
		(width 0.09525)
		(layer "In11.Cu")
		(net "M_L_CPU1_CLK_DP<0>")
	)
	(arc
		(start 144.86255 -256.149602)
		(mid 145.129399 -256.073674)
		(end 145.400014 -256.13487)
		(width 0.09525)
		(layer "In11.Cu")
		(net "M_L_CPU1_CLK_DP<0>")
	)
	(arc
		(start 142.983204 -256.149602)
		(mid 143.264636 -256.073847)
		(end 143.546068 -256.149602)
		(width 0.09525)
		(layer "In11.Cu")
		(net "M_L_CPU1_CLK_DP<0>")
	)
	(arc
		(start 139.786106 -256.149602)
		(mid 139.969881 -256.200374)
		(end 140.154914 -256.154428)
		(width 0.09525)
		(layer "In11.Cu")
		(net "M_L_CPU1_CLK_DP<0>")
	)
	(arc
		(start 142.043404 -256.149602)
		(mid 142.324836 -256.073847)
		(end 142.606268 -256.149602)
		(width 0.09525)
		(layer "In11.Cu")
		(net "M_L_CPU1_CLK_DP<0>")
	)
	(segment
		(start 139.037822 -256.900426)
		(end 139.504674 -256.634488)
		(width 0.14732)
		(layer "F.Cu")
		(net "M_L_CPU1_CLK_DN<0>")
	)
	(segment
		(start 145.410682 -256.36855)
		(end 146.497548 -257.455416)
		(width 0.09525)
		(layer "In11.Cu")
		(net "M_L_CPU1_CLK_DN<0>")
	)
	(segment
		(start 201.12609 -254.968248)
		(end 201.12609 -254.399288)
		(width 0.16002)
		(layer "In11.Cu")
		(net "M_L_CPU1_CLK_DN<0>")
	)
	(segment
		(start 159.84982 -256.659126)
		(end 160.00984 -256.819146)
		(width 0.16002)
		(layer "In11.Cu")
		(net "M_L_CPU1_CLK_DN<0>")
	)
	(segment
		(start 151.385016 -257.514598)
		(end 152.78354 -256.116074)
		(width 0.16002)
		(layer "In11.Cu")
		(net "M_L_CPU1_CLK_DN<0>")
	)
	(segment
		(start 152.78354 -256.116074)
		(end 158.085536 -256.116074)
		(width 0.16002)
		(layer "In11.Cu")
		(net "M_L_CPU1_CLK_DN<0>")
	)
	(segment
		(start 139.504674 -256.634488)
		(end 139.35075 -256.369058)
		(width 0.09525)
		(layer "In11.Cu")
		(net "M_L_CPU1_CLK_DN<0>")
	)
	(segment
		(start 158.628588 -256.659126)
		(end 159.84982 -256.659126)
		(width 0.16002)
		(layer "In11.Cu")
		(net "M_L_CPU1_CLK_DN<0>")
	)
	(segment
		(start 147.729448 -257.455416)
		(end 147.78863 -257.514598)
		(width 0.09525)
		(layer "In11.Cu")
		(net "M_L_CPU1_CLK_DN<0>")
	)
	(segment
		(start 161.544254 -256.659126)
		(end 161.994088 -256.659126)
		(width 0.16002)
		(layer "In11.Cu")
		(net "M_L_CPU1_CLK_DN<0>")
	)
	(segment
		(start 146.497548 -257.455416)
		(end 147.729448 -257.455416)
		(width 0.09525)
		(layer "In11.Cu")
		(net "M_L_CPU1_CLK_DN<0>")
	)
	(segment
		(start 196.6087 -256.659126)
		(end 196.7357 -256.786126)
		(width 0.16002)
		(layer "In11.Cu")
		(net "M_L_CPU1_CLK_DN<0>")
	)
	(segment
		(start 196.7357 -256.786126)
		(end 197.21576 -256.786126)
		(width 0.16002)
		(layer "In11.Cu")
		(net "M_L_CPU1_CLK_DN<0>")
	)
	(segment
		(start 199.435212 -256.659126)
		(end 201.12609 -254.968248)
		(width 0.16002)
		(layer "In11.Cu")
		(net "M_L_CPU1_CLK_DN<0>")
	)
	(segment
		(start 161.384234 -256.819146)
		(end 161.544254 -256.659126)
		(width 0.16002)
		(layer "In11.Cu")
		(net "M_L_CPU1_CLK_DN<0>")
	)
	(segment
		(start 161.384234 -257.810508)
		(end 161.384234 -256.819146)
		(width 0.16002)
		(layer "In11.Cu")
		(net "M_L_CPU1_CLK_DN<0>")
	)
	(segment
		(start 197.21576 -256.786126)
		(end 197.34276 -256.659126)
		(width 0.16002)
		(layer "In11.Cu")
		(net "M_L_CPU1_CLK_DN<0>")
	)
	(segment
		(start 160.00984 -257.810508)
		(end 160.346898 -258.147566)
		(width 0.16002)
		(layer "In11.Cu")
		(net "M_L_CPU1_CLK_DN<0>")
	)
	(segment
		(start 162.491166 -258.147566)
		(end 163.191444 -258.147566)
		(width 0.16002)
		(layer "In11.Cu")
		(net "M_L_CPU1_CLK_DN<0>")
	)
	(segment
		(start 201.515472 -254.009906)
		(end 201.872596 -254.009906)
		(width 0.16002)
		(layer "In11.Cu")
		(net "M_L_CPU1_CLK_DN<0>")
	)
	(segment
		(start 147.812252 -257.514598)
		(end 151.385016 -257.514598)
		(width 0.16002)
		(layer "In11.Cu")
		(net "M_L_CPU1_CLK_DN<0>")
	)
	(segment
		(start 162.154108 -257.810508)
		(end 162.491166 -258.147566)
		(width 0.16002)
		(layer "In11.Cu")
		(net "M_L_CPU1_CLK_DN<0>")
	)
	(segment
		(start 139.35075 -256.369058)
		(end 139.374118 -256.28219)
		(width 0.09525)
		(layer "In11.Cu")
		(net "M_L_CPU1_CLK_DN<0>")
	)
	(segment
		(start 163.688522 -256.659126)
		(end 196.6087 -256.659126)
		(width 0.16002)
		(layer "In11.Cu")
		(net "M_L_CPU1_CLK_DN<0>")
	)
	(segment
		(start 162.154108 -256.819146)
		(end 162.154108 -257.810508)
		(width 0.16002)
		(layer "In11.Cu")
		(net "M_L_CPU1_CLK_DN<0>")
	)
	(segment
		(start 161.047176 -258.147566)
		(end 161.384234 -257.810508)
		(width 0.16002)
		(layer "In11.Cu")
		(net "M_L_CPU1_CLK_DN<0>")
	)
	(segment
		(start 163.191444 -258.147566)
		(end 163.528502 -257.810508)
		(width 0.16002)
		(layer "In11.Cu")
		(net "M_L_CPU1_CLK_DN<0>")
	)
	(segment
		(start 140.25626 -256.309368)
		(end 140.264642 -256.304542)
		(width 0.09525)
		(layer "In11.Cu")
		(net "M_L_CPU1_CLK_DN<0>")
	)
	(segment
		(start 163.528502 -257.810508)
		(end 163.528502 -256.819146)
		(width 0.16002)
		(layer "In11.Cu")
		(net "M_L_CPU1_CLK_DN<0>")
	)
	(segment
		(start 160.00984 -256.819146)
		(end 160.00984 -257.810508)
		(width 0.16002)
		(layer "In11.Cu")
		(net "M_L_CPU1_CLK_DN<0>")
	)
	(segment
		(start 143.076168 -256.309368)
		(end 143.08455 -256.304542)
		(width 0.09525)
		(layer "In11.Cu")
		(net "M_L_CPU1_CLK_DN<0>")
	)
	(segment
		(start 201.12609 -254.399288)
		(end 201.515472 -254.009906)
		(width 0.16002)
		(layer "In11.Cu")
		(net "M_L_CPU1_CLK_DN<0>")
	)
	(segment
		(start 145.31594 -256.299716)
		(end 145.332704 -256.309368)
		(width 0.09525)
		(layer "In11.Cu")
		(net "M_L_CPU1_CLK_DN<0>")
	)
	(segment
		(start 142.504922 -256.304542)
		(end 142.513304 -256.309368)
		(width 0.09525)
		(layer "In11.Cu")
		(net "M_L_CPU1_CLK_DN<0>")
	)
	(segment
		(start 197.34276 -256.659126)
		(end 199.435212 -256.659126)
		(width 0.16002)
		(layer "In11.Cu")
		(net "M_L_CPU1_CLK_DN<0>")
	)
	(segment
		(start 144.384522 -256.304542)
		(end 144.392904 -256.309368)
		(width 0.09525)
		(layer "In11.Cu")
		(net "M_L_CPU1_CLK_DN<0>")
	)
	(segment
		(start 144.392904 -256.309368)
		(end 144.418304 -256.3241)
		(width 0.09525)
		(layer "In11.Cu")
		(net "M_L_CPU1_CLK_DN<0>")
	)
	(segment
		(start 201.872596 -254.009906)
		(end 202.147932 -254.285242)
		(width 0.16002)
		(layer "In11.Cu")
		(net "M_L_CPU1_CLK_DN<0>")
	)
	(segment
		(start 147.78863 -257.514598)
		(end 147.812252 -257.514598)
		(width 0.09525)
		(layer "In11.Cu")
		(net "M_L_CPU1_CLK_DN<0>")
	)
	(segment
		(start 163.528502 -256.819146)
		(end 163.688522 -256.659126)
		(width 0.16002)
		(layer "In11.Cu")
		(net "M_L_CPU1_CLK_DN<0>")
	)
	(segment
		(start 161.994088 -256.659126)
		(end 162.154108 -256.819146)
		(width 0.16002)
		(layer "In11.Cu")
		(net "M_L_CPU1_CLK_DN<0>")
	)
	(segment
		(start 160.346898 -258.147566)
		(end 161.047176 -258.147566)
		(width 0.16002)
		(layer "In11.Cu")
		(net "M_L_CPU1_CLK_DN<0>")
	)
	(segment
		(start 158.085536 -256.116074)
		(end 158.628588 -256.659126)
		(width 0.16002)
		(layer "In11.Cu")
		(net "M_L_CPU1_CLK_DN<0>")
	)
	(arc
		(start 142.136114 -256.309368)
		(mid 142.319889 -256.258596)
		(end 142.504922 -256.304542)
		(width 0.09525)
		(layer "In11.Cu")
		(net "M_L_CPU1_CLK_DN<0>")
	)
	(arc
		(start 139.374118 -256.28219)
		(mid 139.5368 -256.260058)
		(end 139.693396 -256.309368)
		(width 0.09525)
		(layer "In11.Cu")
		(net "M_L_CPU1_CLK_DN<0>")
	)
	(arc
		(start 145.332704 -256.309368)
		(mid 145.373634 -256.336402)
		(end 145.410682 -256.36855)
		(width 0.09525)
		(layer "In11.Cu")
		(net "M_L_CPU1_CLK_DN<0>")
	)
	(arc
		(start 144.016222 -256.309368)
		(mid 144.199743 -256.258724)
		(end 144.384522 -256.304542)
		(width 0.09525)
		(layer "In11.Cu")
		(net "M_L_CPU1_CLK_DN<0>")
	)
	(arc
		(start 144.418304 -256.3241)
		(mid 144.68892 -256.385325)
		(end 144.955768 -256.309368)
		(width 0.09525)
		(layer "In11.Cu")
		(net "M_L_CPU1_CLK_DN<0>")
	)
	(arc
		(start 140.63345 -256.309368)
		(mid 140.914882 -256.385123)
		(end 141.196314 -256.309368)
		(width 0.09525)
		(layer "In11.Cu")
		(net "M_L_CPU1_CLK_DN<0>")
	)
	(arc
		(start 141.196314 -256.309368)
		(mid 141.384782 -256.258691)
		(end 141.57325 -256.309368)
		(width 0.09525)
		(layer "In11.Cu")
		(net "M_L_CPU1_CLK_DN<0>")
	)
	(arc
		(start 139.693396 -256.309368)
		(mid 139.974828 -256.385123)
		(end 140.25626 -256.309368)
		(width 0.09525)
		(layer "In11.Cu")
		(net "M_L_CPU1_CLK_DN<0>")
	)
	(arc
		(start 143.453358 -256.309368)
		(mid 143.73479 -256.385123)
		(end 144.016222 -256.309368)
		(width 0.09525)
		(layer "In11.Cu")
		(net "M_L_CPU1_CLK_DN<0>")
	)
	(arc
		(start 140.264642 -256.304542)
		(mid 140.449674 -256.258628)
		(end 140.63345 -256.309368)
		(width 0.09525)
		(layer "In11.Cu")
		(net "M_L_CPU1_CLK_DN<0>")
	)
	(arc
		(start 143.08455 -256.304542)
		(mid 143.269582 -256.258628)
		(end 143.453358 -256.309368)
		(width 0.09525)
		(layer "In11.Cu")
		(net "M_L_CPU1_CLK_DN<0>")
	)
	(arc
		(start 142.513304 -256.309368)
		(mid 142.794736 -256.385123)
		(end 143.076168 -256.309368)
		(width 0.09525)
		(layer "In11.Cu")
		(net "M_L_CPU1_CLK_DN<0>")
	)
	(arc
		(start 141.57325 -256.309368)
		(mid 141.854682 -256.385123)
		(end 142.136114 -256.309368)
		(width 0.09525)
		(layer "In11.Cu")
		(net "M_L_CPU1_CLK_DN<0>")
	)
	(arc
		(start 144.955768 -256.309368)
		(mid 145.134628 -256.258572)
		(end 145.31594 -256.299716)
		(width 0.09525)
		(layer "In11.Cu")
		(net "M_L_CPU1_CLK_DN<0>")
	)
	(segment
		(start 137.157968 -250.420378)
		(end 137.62482 -250.15444)
		(width 0.10668)
		(layer "F.Cu")
		(net "M_L_CPU1_ALERT_R_N")
	)
	(segment
		(start 147.652232 -251.252228)
		(end 147.893024 -251.252228)
		(width 0.0889)
		(layer "In11.Cu")
		(net "M_L_CPU1_ALERT_R_N")
	)
	(segment
		(start 148.838666 -251.252228)
		(end 150.20163 -249.889264)
		(width 0.11684)
		(layer "In11.Cu")
		(net "M_L_CPU1_ALERT_R_N")
	)
	(segment
		(start 147.893024 -251.252228)
		(end 148.838666 -251.252228)
		(width 0.11684)
		(layer "In11.Cu")
		(net "M_L_CPU1_ALERT_R_N")
	)
	(segment
		(start 145.144744 -250.527566)
		(end 146.92757 -250.527566)
		(width 0.0889)
		(layer "In11.Cu")
		(net "M_L_CPU1_ALERT_R_N")
	)
	(segment
		(start 137.778744 -250.41987)
		(end 137.874756 -250.44527)
		(width 0.0889)
		(layer "In11.Cu")
		(net "M_L_CPU1_ALERT_R_N")
	)
	(segment
		(start 137.62482 -250.15444)
		(end 137.778744 -250.41987)
		(width 0.0889)
		(layer "In11.Cu")
		(net "M_L_CPU1_ALERT_R_N")
	)
	(segment
		(start 160.787334 -249.889264)
		(end 164.46627 -246.210328)
		(width 0.11684)
		(layer "In11.Cu")
		(net "M_L_CPU1_ALERT_R_N")
	)
	(segment
		(start 204.426058 -244.510306)
		(end 204.851 -244.085364)
		(width 0.11684)
		(layer "In11.Cu")
		(net "M_L_CPU1_ALERT_R_N")
	)
	(segment
		(start 197.48754 -244.510306)
		(end 204.426058 -244.510306)
		(width 0.11684)
		(layer "In11.Cu")
		(net "M_L_CPU1_ALERT_R_N")
	)
	(segment
		(start 143.077692 -250.47702)
		(end 143.086074 -250.481846)
		(width 0.0889)
		(layer "In11.Cu")
		(net "M_L_CPU1_ALERT_R_N")
	)
	(segment
		(start 146.92757 -250.527566)
		(end 147.652232 -251.252228)
		(width 0.0889)
		(layer "In11.Cu")
		(net "M_L_CPU1_ALERT_R_N")
	)
	(segment
		(start 140.257784 -250.47702)
		(end 140.266166 -250.481846)
		(width 0.0889)
		(layer "In11.Cu")
		(net "M_L_CPU1_ALERT_R_N")
	)
	(segment
		(start 195.787518 -246.210328)
		(end 197.48754 -244.510306)
		(width 0.11684)
		(layer "In11.Cu")
		(net "M_L_CPU1_ALERT_R_N")
	)
	(segment
		(start 164.46627 -246.210328)
		(end 195.787518 -246.210328)
		(width 0.11684)
		(layer "In11.Cu")
		(net "M_L_CPU1_ALERT_R_N")
	)
	(segment
		(start 138.743436 -250.481846)
		(end 138.751818 -250.47702)
		(width 0.0889)
		(layer "In11.Cu")
		(net "M_L_CPU1_ALERT_R_N")
	)
	(segment
		(start 142.503398 -250.481846)
		(end 142.51178 -250.47702)
		(width 0.0889)
		(layer "In11.Cu")
		(net "M_L_CPU1_ALERT_R_N")
	)
	(segment
		(start 139.31773 -250.47702)
		(end 139.326112 -250.481846)
		(width 0.0889)
		(layer "In11.Cu")
		(net "M_L_CPU1_ALERT_R_N")
	)
	(segment
		(start 150.20163 -249.889264)
		(end 160.787334 -249.889264)
		(width 0.11684)
		(layer "In11.Cu")
		(net "M_L_CPU1_ALERT_R_N")
	)
	(segment
		(start 144.017746 -250.47702)
		(end 144.026128 -250.481846)
		(width 0.0889)
		(layer "In11.Cu")
		(net "M_L_CPU1_ALERT_R_N")
	)
	(arc
		(start 143.086074 -250.481846)
		(mid 143.269582 -250.52734)
		(end 143.451834 -250.47702)
		(width 0.0889)
		(layer "In11.Cu")
		(net "M_L_CPU1_ALERT_R_N")
	)
	(arc
		(start 138.377676 -250.47702)
		(mid 138.559927 -250.52737)
		(end 138.743436 -250.481846)
		(width 0.0889)
		(layer "In11.Cu")
		(net "M_L_CPU1_ALERT_R_N")
	)
	(arc
		(start 144.391888 -250.47702)
		(mid 144.674844 -250.400843)
		(end 144.9578 -250.47702)
		(width 0.0889)
		(layer "In11.Cu")
		(net "M_L_CPU1_ALERT_R_N")
	)
	(arc
		(start 144.9578 -250.47702)
		(mid 145.047933 -250.51464)
		(end 145.144744 -250.527566)
		(width 0.0889)
		(layer "In11.Cu")
		(net "M_L_CPU1_ALERT_R_N")
	)
	(arc
		(start 140.631926 -250.47702)
		(mid 140.914882 -250.400843)
		(end 141.197838 -250.47702)
		(width 0.0889)
		(layer "In11.Cu")
		(net "M_L_CPU1_ALERT_R_N")
	)
	(arc
		(start 142.137638 -250.47702)
		(mid 142.319889 -250.52737)
		(end 142.503398 -250.481846)
		(width 0.0889)
		(layer "In11.Cu")
		(net "M_L_CPU1_ALERT_R_N")
	)
	(arc
		(start 139.326112 -250.481846)
		(mid 139.50962 -250.52734)
		(end 139.691872 -250.47702)
		(width 0.0889)
		(layer "In11.Cu")
		(net "M_L_CPU1_ALERT_R_N")
	)
	(arc
		(start 142.51178 -250.47702)
		(mid 142.794736 -250.400843)
		(end 143.077692 -250.47702)
		(width 0.0889)
		(layer "In11.Cu")
		(net "M_L_CPU1_ALERT_R_N")
	)
	(arc
		(start 139.691872 -250.47702)
		(mid 139.974828 -250.400843)
		(end 140.257784 -250.47702)
		(width 0.0889)
		(layer "In11.Cu")
		(net "M_L_CPU1_ALERT_R_N")
	)
	(arc
		(start 141.197838 -250.47702)
		(mid 141.384782 -250.527275)
		(end 141.571726 -250.47702)
		(width 0.0889)
		(layer "In11.Cu")
		(net "M_L_CPU1_ALERT_R_N")
	)
	(arc
		(start 140.266166 -250.481846)
		(mid 140.449674 -250.52734)
		(end 140.631926 -250.47702)
		(width 0.0889)
		(layer "In11.Cu")
		(net "M_L_CPU1_ALERT_R_N")
	)
	(arc
		(start 143.451834 -250.47702)
		(mid 143.73479 -250.400843)
		(end 144.017746 -250.47702)
		(width 0.0889)
		(layer "In11.Cu")
		(net "M_L_CPU1_ALERT_R_N")
	)
	(arc
		(start 138.751818 -250.47702)
		(mid 139.034774 -250.400843)
		(end 139.31773 -250.47702)
		(width 0.0889)
		(layer "In11.Cu")
		(net "M_L_CPU1_ALERT_R_N")
	)
	(arc
		(start 137.874756 -250.44527)
		(mid 138.129964 -250.401793)
		(end 138.377676 -250.47702)
		(width 0.0889)
		(layer "In11.Cu")
		(net "M_L_CPU1_ALERT_R_N")
	)
	(arc
		(start 144.026128 -250.481846)
		(mid 144.209636 -250.52734)
		(end 144.391888 -250.47702)
		(width 0.0889)
		(layer "In11.Cu")
		(net "M_L_CPU1_ALERT_R_N")
	)
	(arc
		(start 141.571726 -250.47702)
		(mid 141.854682 -250.400843)
		(end 142.137638 -250.47702)
		(width 0.0889)
		(layer "In11.Cu")
		(net "M_L_CPU1_ALERT_R_N")
	)
	(via
		(at 206.248 -244.085364)
		(size 0.4826)
		(drill 0.254)
		(layers "F.Cu" "B.Cu")
		(net "M_L_CPU1_ALERT_N")
	)
	(segment
		(start 205.6511 -244.085364)
		(end 206.248 -244.085364)
		(width 0.10668)
		(layer "B.Cu")
		(net "M_L_CPU1_ALERT_N")
	)
	(segment
		(start 387.277864 -267.34008)
		(end 387.744716 -267.606018)
		(width 0.10668)
		(layer "F.Cu")
		(net "M_L_CPU0_SB_RSP<0>")
	)
	(segment
		(start 407.305256 -266.57046)
		(end 411.595062 -270.860266)
		(width 0.11684)
		(layer "In11.Cu")
		(net "M_L_CPU0_SB_RSP<0>")
	)
	(segment
		(start 395.589506 -266.57046)
		(end 395.888972 -266.57046)
		(width 0.0889)
		(layer "In11.Cu")
		(net "M_L_CPU0_SB_RSP<0>")
	)
	(segment
		(start 387.744716 -267.606018)
		(end 387.590792 -267.871448)
		(width 0.0889)
		(layer "In11.Cu")
		(net "M_L_CPU0_SB_RSP<0>")
	)
	(segment
		(start 390.74344 -267.933424)
		(end 390.751822 -267.928598)
		(width 0.0889)
		(layer "In11.Cu")
		(net "M_L_CPU0_SB_RSP<0>")
	)
	(segment
		(start 395.888972 -266.57046)
		(end 407.305256 -266.57046)
		(width 0.11684)
		(layer "In11.Cu")
		(net "M_L_CPU0_SB_RSP<0>")
	)
	(segment
		(start 436.722012 -270.860266)
		(end 437.57215 -270.010128)
		(width 0.11684)
		(layer "In11.Cu")
		(net "M_L_CPU0_SB_RSP<0>")
	)
	(segment
		(start 394.537438 -266.168632)
		(end 395.187678 -266.168632)
		(width 0.0889)
		(layer "In11.Cu")
		(net "M_L_CPU0_SB_RSP<0>")
	)
	(segment
		(start 391.317734 -267.928598)
		(end 391.326116 -267.933424)
		(width 0.0889)
		(layer "In11.Cu")
		(net "M_L_CPU0_SB_RSP<0>")
	)
	(segment
		(start 393.637008 -267.874242)
		(end 393.690094 -267.821156)
		(width 0.0889)
		(layer "In11.Cu")
		(net "M_L_CPU0_SB_RSP<0>")
	)
	(segment
		(start 387.590792 -267.871448)
		(end 387.613144 -267.95476)
		(width 0.0889)
		(layer "In11.Cu")
		(net "M_L_CPU0_SB_RSP<0>")
	)
	(segment
		(start 453.763126 -270.010128)
		(end 454.188068 -270.43507)
		(width 0.11684)
		(layer "In11.Cu")
		(net "M_L_CPU0_SB_RSP<0>")
	)
	(segment
		(start 426.516546 -270.860266)
		(end 429.177958 -270.860266)
		(width 0.11684)
		(layer "In11.Cu")
		(net "M_L_CPU0_SB_RSP<0>")
	)
	(segment
		(start 395.187678 -266.168632)
		(end 395.589506 -266.57046)
		(width 0.0889)
		(layer "In11.Cu")
		(net "M_L_CPU0_SB_RSP<0>")
	)
	(segment
		(start 393.743434 -266.962636)
		(end 394.537438 -266.168632)
		(width 0.0889)
		(layer "In11.Cu")
		(net "M_L_CPU0_SB_RSP<0>")
	)
	(segment
		(start 425.666408 -270.010128)
		(end 426.516546 -270.860266)
		(width 0.11684)
		(layer "In11.Cu")
		(net "M_L_CPU0_SB_RSP<0>")
	)
	(segment
		(start 392.257534 -267.928598)
		(end 392.272012 -267.93698)
		(width 0.0889)
		(layer "In11.Cu")
		(net "M_L_CPU0_SB_RSP<0>")
	)
	(segment
		(start 433.210462 -270.010128)
		(end 434.0606 -270.860266)
		(width 0.11684)
		(layer "In11.Cu")
		(net "M_L_CPU0_SB_RSP<0>")
	)
	(segment
		(start 437.57215 -270.010128)
		(end 453.763126 -270.010128)
		(width 0.11684)
		(layer "In11.Cu")
		(net "M_L_CPU0_SB_RSP<0>")
	)
	(segment
		(start 434.0606 -270.860266)
		(end 436.722012 -270.860266)
		(width 0.11684)
		(layer "In11.Cu")
		(net "M_L_CPU0_SB_RSP<0>")
	)
	(segment
		(start 393.743434 -267.692378)
		(end 393.743434 -266.962636)
		(width 0.0889)
		(layer "In11.Cu")
		(net "M_L_CPU0_SB_RSP<0>")
	)
	(segment
		(start 392.24712 -267.922502)
		(end 392.257534 -267.928598)
		(width 0.0889)
		(layer "In11.Cu")
		(net "M_L_CPU0_SB_RSP<0>")
	)
	(segment
		(start 429.177958 -270.860266)
		(end 430.028096 -270.010128)
		(width 0.11684)
		(layer "In11.Cu")
		(net "M_L_CPU0_SB_RSP<0>")
	)
	(segment
		(start 411.595062 -270.860266)
		(end 421.633904 -270.860266)
		(width 0.11684)
		(layer "In11.Cu")
		(net "M_L_CPU0_SB_RSP<0>")
	)
	(segment
		(start 421.633904 -270.860266)
		(end 422.484042 -270.010128)
		(width 0.11684)
		(layer "In11.Cu")
		(net "M_L_CPU0_SB_RSP<0>")
	)
	(segment
		(start 422.484042 -270.010128)
		(end 425.666408 -270.010128)
		(width 0.11684)
		(layer "In11.Cu")
		(net "M_L_CPU0_SB_RSP<0>")
	)
	(segment
		(start 388.497826 -267.928598)
		(end 388.506208 -267.933424)
		(width 0.0889)
		(layer "In11.Cu")
		(net "M_L_CPU0_SB_RSP<0>")
	)
	(segment
		(start 430.028096 -270.010128)
		(end 433.210462 -270.010128)
		(width 0.11684)
		(layer "In11.Cu")
		(net "M_L_CPU0_SB_RSP<0>")
	)
	(arc
		(start 393.690094 -267.821156)
		(mid 393.729573 -267.762072)
		(end 393.743434 -267.692378)
		(width 0.0889)
		(layer "In11.Cu")
		(net "M_L_CPU0_SB_RSP<0>")
	)
	(arc
		(start 392.272012 -267.93698)
		(mid 392.45292 -267.979002)
		(end 392.631676 -267.928598)
		(width 0.0889)
		(layer "In11.Cu")
		(net "M_L_CPU0_SB_RSP<0>")
	)
	(arc
		(start 388.506208 -267.933424)
		(mid 388.689716 -267.978918)
		(end 388.871968 -267.928598)
		(width 0.0889)
		(layer "In11.Cu")
		(net "M_L_CPU0_SB_RSP<0>")
	)
	(arc
		(start 393.187428 -267.922502)
		(mid 393.282152 -267.96453)
		(end 393.384786 -267.97889)
		(width 0.0889)
		(layer "In11.Cu")
		(net "M_L_CPU0_SB_RSP<0>")
	)
	(arc
		(start 393.384786 -267.97889)
		(mid 393.521301 -267.951642)
		(end 393.637008 -267.874242)
		(width 0.0889)
		(layer "In11.Cu")
		(net "M_L_CPU0_SB_RSP<0>")
	)
	(arc
		(start 389.43788 -267.928598)
		(mid 389.624824 -267.978853)
		(end 389.811768 -267.928598)
		(width 0.0889)
		(layer "In11.Cu")
		(net "M_L_CPU0_SB_RSP<0>")
	)
	(arc
		(start 390.751822 -267.928598)
		(mid 391.034778 -267.852421)
		(end 391.317734 -267.928598)
		(width 0.0889)
		(layer "In11.Cu")
		(net "M_L_CPU0_SB_RSP<0>")
	)
	(arc
		(start 389.811768 -267.928598)
		(mid 390.094724 -267.852421)
		(end 390.37768 -267.928598)
		(width 0.0889)
		(layer "In11.Cu")
		(net "M_L_CPU0_SB_RSP<0>")
	)
	(arc
		(start 391.326116 -267.933424)
		(mid 391.509624 -267.978918)
		(end 391.691876 -267.928598)
		(width 0.0889)
		(layer "In11.Cu")
		(net "M_L_CPU0_SB_RSP<0>")
	)
	(arc
		(start 387.931914 -267.928598)
		(mid 388.21487 -267.852421)
		(end 388.497826 -267.928598)
		(width 0.0889)
		(layer "In11.Cu")
		(net "M_L_CPU0_SB_RSP<0>")
	)
	(arc
		(start 390.37768 -267.928598)
		(mid 390.559931 -267.978948)
		(end 390.74344 -267.933424)
		(width 0.0889)
		(layer "In11.Cu")
		(net "M_L_CPU0_SB_RSP<0>")
	)
	(arc
		(start 387.613144 -267.95476)
		(mid 387.775476 -267.977578)
		(end 387.931914 -267.928598)
		(width 0.0889)
		(layer "In11.Cu")
		(net "M_L_CPU0_SB_RSP<0>")
	)
	(arc
		(start 388.871968 -267.928598)
		(mid 389.154924 -267.852421)
		(end 389.43788 -267.928598)
		(width 0.0889)
		(layer "In11.Cu")
		(net "M_L_CPU0_SB_RSP<0>")
	)
	(arc
		(start 391.691876 -267.928598)
		(mid 391.968689 -267.852455)
		(end 392.24712 -267.922502)
		(width 0.0889)
		(layer "In11.Cu")
		(net "M_L_CPU0_SB_RSP<0>")
	)
	(arc
		(start 392.631676 -267.928598)
		(mid 392.908743 -267.852327)
		(end 393.187428 -267.922502)
		(width 0.0889)
		(layer "In11.Cu")
		(net "M_L_CPU0_SB_RSP<0>")
	)
	(segment
		(start 385.86791 -264.910062)
		(end 386.334762 -265.176)
		(width 0.10668)
		(layer "F.Cu")
		(net "M_L_CPU0_SB_PAR")
	)
	(segment
		(start 393.625324 -265.422888)
		(end 393.384532 -265.422888)
		(width 0.0889)
		(layer "In11.Cu")
		(net "M_L_CPU0_SB_PAR")
	)
	(segment
		(start 437.57215 -266.610084)
		(end 436.722012 -267.460222)
		(width 0.14478)
		(layer "In11.Cu")
		(net "M_L_CPU0_SB_PAR")
	)
	(segment
		(start 448.312032 -266.610084)
		(end 448.167252 -266.754864)
		(width 0.14478)
		(layer "In11.Cu")
		(net "M_L_CPU0_SB_PAR")
	)
	(segment
		(start 421.633904 -267.460222)
		(end 411.595062 -267.460222)
		(width 0.14478)
		(layer "In11.Cu")
		(net "M_L_CPU0_SB_PAR")
	)
	(segment
		(start 449.27012 -266.754864)
		(end 449.27012 -266.851892)
		(width 0.14478)
		(layer "In11.Cu")
		(net "M_L_CPU0_SB_PAR")
	)
	(segment
		(start 386.180838 -265.44143)
		(end 386.334762 -265.176)
		(width 0.0889)
		(layer "In11.Cu")
		(net "M_L_CPU0_SB_PAR")
	)
	(segment
		(start 447.615818 -266.754864)
		(end 447.471038 -266.610084)
		(width 0.14478)
		(layer "In11.Cu")
		(net "M_L_CPU0_SB_PAR")
	)
	(segment
		(start 449.12534 -266.996672)
		(end 448.863466 -266.996672)
		(width 0.14478)
		(layer "In11.Cu")
		(net "M_L_CPU0_SB_PAR")
	)
	(segment
		(start 449.94322 -266.610084)
		(end 449.4149 -266.610084)
		(width 0.14478)
		(layer "In11.Cu")
		(net "M_L_CPU0_SB_PAR")
	)
	(segment
		(start 426.516546 -267.460222)
		(end 425.666408 -266.610084)
		(width 0.14478)
		(layer "In11.Cu")
		(net "M_L_CPU0_SB_PAR")
	)
	(segment
		(start 411.595062 -267.460222)
		(end 408.92857 -264.79373)
		(width 0.14478)
		(layer "In11.Cu")
		(net "M_L_CPU0_SB_PAR")
	)
	(segment
		(start 447.615818 -266.851892)
		(end 447.615818 -266.754864)
		(width 0.14478)
		(layer "In11.Cu")
		(net "M_L_CPU0_SB_PAR")
	)
	(segment
		(start 393.103354 -265.498326)
		(end 393.083288 -265.509756)
		(width 0.0889)
		(layer "In11.Cu")
		(net "M_L_CPU0_SB_PAR")
	)
	(segment
		(start 394.50772 -264.540492)
		(end 393.625324 -265.422888)
		(width 0.0889)
		(layer "In11.Cu")
		(net "M_L_CPU0_SB_PAR")
	)
	(segment
		(start 395.654276 -264.79373)
		(end 395.401038 -264.540492)
		(width 0.0889)
		(layer "In11.Cu")
		(net "M_L_CPU0_SB_PAR")
	)
	(segment
		(start 448.022472 -266.996672)
		(end 447.760598 -266.996672)
		(width 0.14478)
		(layer "In11.Cu")
		(net "M_L_CPU0_SB_PAR")
	)
	(segment
		(start 449.4149 -266.610084)
		(end 449.27012 -266.754864)
		(width 0.14478)
		(layer "In11.Cu")
		(net "M_L_CPU0_SB_PAR")
	)
	(segment
		(start 389.916162 -265.503406)
		(end 389.90778 -265.49858)
		(width 0.0889)
		(layer "In11.Cu")
		(net "M_L_CPU0_SB_PAR")
	)
	(segment
		(start 450.088 -267.035026)
		(end 450.088 -266.754864)
		(width 0.14478)
		(layer "In11.Cu")
		(net "M_L_CPU0_SB_PAR")
	)
	(segment
		(start 392.729974 -265.49858)
		(end 392.706606 -265.484864)
		(width 0.0889)
		(layer "In11.Cu")
		(net "M_L_CPU0_SB_PAR")
	)
	(segment
		(start 434.0606 -267.460222)
		(end 433.210462 -266.610084)
		(width 0.14478)
		(layer "In11.Cu")
		(net "M_L_CPU0_SB_PAR")
	)
	(segment
		(start 448.167252 -266.754864)
		(end 448.167252 -266.851892)
		(width 0.14478)
		(layer "In11.Cu")
		(net "M_L_CPU0_SB_PAR")
	)
	(segment
		(start 448.718686 -266.851892)
		(end 448.718686 -266.754864)
		(width 0.14478)
		(layer "In11.Cu")
		(net "M_L_CPU0_SB_PAR")
	)
	(segment
		(start 448.573906 -266.610084)
		(end 448.312032 -266.610084)
		(width 0.14478)
		(layer "In11.Cu")
		(net "M_L_CPU0_SB_PAR")
	)
	(segment
		(start 395.401038 -264.540492)
		(end 394.50772 -264.540492)
		(width 0.0889)
		(layer "In11.Cu")
		(net "M_L_CPU0_SB_PAR")
	)
	(segment
		(start 433.210462 -266.610084)
		(end 430.028096 -266.610084)
		(width 0.14478)
		(layer "In11.Cu")
		(net "M_L_CPU0_SB_PAR")
	)
	(segment
		(start 389.341868 -265.49858)
		(end 389.333486 -265.503406)
		(width 0.0889)
		(layer "In11.Cu")
		(net "M_L_CPU0_SB_PAR")
	)
	(segment
		(start 448.863466 -266.996672)
		(end 448.718686 -266.851892)
		(width 0.14478)
		(layer "In11.Cu")
		(net "M_L_CPU0_SB_PAR")
	)
	(segment
		(start 450.088 -266.754864)
		(end 449.94322 -266.610084)
		(width 0.14478)
		(layer "In11.Cu")
		(net "M_L_CPU0_SB_PAR")
	)
	(segment
		(start 430.028096 -266.610084)
		(end 429.177958 -267.460222)
		(width 0.14478)
		(layer "In11.Cu")
		(net "M_L_CPU0_SB_PAR")
	)
	(segment
		(start 386.20319 -265.524742)
		(end 386.180838 -265.44143)
		(width 0.0889)
		(layer "In11.Cu")
		(net "M_L_CPU0_SB_PAR")
	)
	(segment
		(start 388.401814 -265.49858)
		(end 388.393432 -265.503406)
		(width 0.0889)
		(layer "In11.Cu")
		(net "M_L_CPU0_SB_PAR")
	)
	(segment
		(start 422.484042 -266.610084)
		(end 421.633904 -267.460222)
		(width 0.14478)
		(layer "In11.Cu")
		(net "M_L_CPU0_SB_PAR")
	)
	(segment
		(start 408.92857 -264.79373)
		(end 395.957552 -264.79373)
		(width 0.14478)
		(layer "In11.Cu")
		(net "M_L_CPU0_SB_PAR")
	)
	(segment
		(start 425.666408 -266.610084)
		(end 422.484042 -266.610084)
		(width 0.14478)
		(layer "In11.Cu")
		(net "M_L_CPU0_SB_PAR")
	)
	(segment
		(start 436.722012 -267.460222)
		(end 434.0606 -267.460222)
		(width 0.14478)
		(layer "In11.Cu")
		(net "M_L_CPU0_SB_PAR")
	)
	(segment
		(start 391.802112 -265.506962)
		(end 391.787634 -265.49858)
		(width 0.0889)
		(layer "In11.Cu")
		(net "M_L_CPU0_SB_PAR")
	)
	(segment
		(start 449.27012 -266.851892)
		(end 449.12534 -266.996672)
		(width 0.14478)
		(layer "In11.Cu")
		(net "M_L_CPU0_SB_PAR")
	)
	(segment
		(start 429.177958 -267.460222)
		(end 426.516546 -267.460222)
		(width 0.14478)
		(layer "In11.Cu")
		(net "M_L_CPU0_SB_PAR")
	)
	(segment
		(start 447.760598 -266.996672)
		(end 447.615818 -266.851892)
		(width 0.14478)
		(layer "In11.Cu")
		(net "M_L_CPU0_SB_PAR")
	)
	(segment
		(start 395.957552 -264.79373)
		(end 395.654276 -264.79373)
		(width 0.0889)
		(layer "In11.Cu")
		(net "M_L_CPU0_SB_PAR")
	)
	(segment
		(start 448.718686 -266.754864)
		(end 448.573906 -266.610084)
		(width 0.14478)
		(layer "In11.Cu")
		(net "M_L_CPU0_SB_PAR")
	)
	(segment
		(start 448.167252 -266.851892)
		(end 448.022472 -266.996672)
		(width 0.14478)
		(layer "In11.Cu")
		(net "M_L_CPU0_SB_PAR")
	)
	(segment
		(start 447.471038 -266.610084)
		(end 437.57215 -266.610084)
		(width 0.14478)
		(layer "In11.Cu")
		(net "M_L_CPU0_SB_PAR")
	)
	(arc
		(start 392.162792 -265.49858)
		(mid 391.983529 -265.549244)
		(end 391.802112 -265.506962)
		(width 0.0889)
		(layer "In11.Cu")
		(net "M_L_CPU0_SB_PAR")
	)
	(arc
		(start 389.333486 -265.503406)
		(mid 389.149978 -265.5489)
		(end 388.967726 -265.49858)
		(width 0.0889)
		(layer "In11.Cu")
		(net "M_L_CPU0_SB_PAR")
	)
	(arc
		(start 388.967726 -265.49858)
		(mid 388.68477 -265.422403)
		(end 388.401814 -265.49858)
		(width 0.0889)
		(layer "In11.Cu")
		(net "M_L_CPU0_SB_PAR")
	)
	(arc
		(start 390.281922 -265.49858)
		(mid 390.099671 -265.54893)
		(end 389.916162 -265.503406)
		(width 0.0889)
		(layer "In11.Cu")
		(net "M_L_CPU0_SB_PAR")
	)
	(arc
		(start 391.221722 -265.49858)
		(mid 391.034778 -265.548835)
		(end 390.847834 -265.49858)
		(width 0.0889)
		(layer "In11.Cu")
		(net "M_L_CPU0_SB_PAR")
	)
	(arc
		(start 391.787634 -265.49858)
		(mid 391.504678 -265.422403)
		(end 391.221722 -265.49858)
		(width 0.0889)
		(layer "In11.Cu")
		(net "M_L_CPU0_SB_PAR")
	)
	(arc
		(start 389.90778 -265.49858)
		(mid 389.624824 -265.422403)
		(end 389.341868 -265.49858)
		(width 0.0889)
		(layer "In11.Cu")
		(net "M_L_CPU0_SB_PAR")
	)
	(arc
		(start 390.847834 -265.49858)
		(mid 390.564878 -265.422403)
		(end 390.281922 -265.49858)
		(width 0.0889)
		(layer "In11.Cu")
		(net "M_L_CPU0_SB_PAR")
	)
	(arc
		(start 388.393432 -265.503406)
		(mid 388.209924 -265.5489)
		(end 388.027672 -265.49858)
		(width 0.0889)
		(layer "In11.Cu")
		(net "M_L_CPU0_SB_PAR")
	)
	(arc
		(start 392.706606 -265.484864)
		(mid 392.432952 -265.421921)
		(end 392.162792 -265.49858)
		(width 0.0889)
		(layer "In11.Cu")
		(net "M_L_CPU0_SB_PAR")
	)
	(arc
		(start 388.027672 -265.49858)
		(mid 387.744716 -265.422403)
		(end 387.46176 -265.49858)
		(width 0.0889)
		(layer "In11.Cu")
		(net "M_L_CPU0_SB_PAR")
	)
	(arc
		(start 393.083288 -265.509756)
		(mid 392.90521 -265.54874)
		(end 392.729974 -265.49858)
		(width 0.0889)
		(layer "In11.Cu")
		(net "M_L_CPU0_SB_PAR")
	)
	(arc
		(start 387.087872 -265.49858)
		(mid 386.804916 -265.422403)
		(end 386.52196 -265.49858)
		(width 0.0889)
		(layer "In11.Cu")
		(net "M_L_CPU0_SB_PAR")
	)
	(arc
		(start 386.52196 -265.49858)
		(mid 386.365522 -265.547551)
		(end 386.20319 -265.524742)
		(width 0.0889)
		(layer "In11.Cu")
		(net "M_L_CPU0_SB_PAR")
	)
	(arc
		(start 387.46176 -265.49858)
		(mid 387.274816 -265.548835)
		(end 387.087872 -265.49858)
		(width 0.0889)
		(layer "In11.Cu")
		(net "M_L_CPU0_SB_PAR")
	)
	(arc
		(start 393.384532 -265.422888)
		(mid 393.238972 -265.442094)
		(end 393.103354 -265.498326)
		(width 0.0889)
		(layer "In11.Cu")
		(net "M_L_CPU0_SB_PAR")
	)
	(segment
		(start 387.277864 -270.580104)
		(end 387.744716 -270.846042)
		(width 0.12954)
		(layer "F.Cu")
		(net "M_L_CPU0_SB_DQS_DP<9>")
	)
	(segment
		(start 405.677624 -269.2527)
		(end 412.412434 -275.98751)
		(width 0.16002)
		(layer "In11.Cu")
		(net "M_L_CPU0_SB_DQS_DP<9>")
	)
	(segment
		(start 448.246754 -275.384006)
		(end 450.66839 -275.384006)
		(width 0.16002)
		(layer "In11.Cu")
		(net "M_L_CPU0_SB_DQS_DP<9>")
	)
	(segment
		(start 428.03445 -275.65985)
		(end 428.36211 -275.98751)
		(width 0.16002)
		(layer "In11.Cu")
		(net "M_L_CPU0_SB_DQS_DP<9>")
	)
	(segment
		(start 387.590792 -271.111472)
		(end 387.61416 -271.19834)
		(width 0.09525)
		(layer "In11.Cu")
		(net "M_L_CPU0_SB_DQS_DP<9>")
	)
	(segment
		(start 422.776396 -275.16455)
		(end 423.13098 -274.809966)
		(width 0.16002)
		(layer "In11.Cu")
		(net "M_L_CPU0_SB_DQS_DP<9>")
	)
	(segment
		(start 422.364916 -275.16455)
		(end 422.776396 -275.16455)
		(width 0.16002)
		(layer "In11.Cu")
		(net "M_L_CPU0_SB_DQS_DP<9>")
	)
	(segment
		(start 440.12866 -274.809966)
		(end 440.978544 -275.65985)
		(width 0.16002)
		(layer "In11.Cu")
		(net "M_L_CPU0_SB_DQS_DP<9>")
	)
	(segment
		(start 393.065254 -270.383254)
		(end 393.103354 -270.361156)
		(width 0.09525)
		(layer "In11.Cu")
		(net "M_L_CPU0_SB_DQS_DP<9>")
	)
	(segment
		(start 425.890436 -275.65985)
		(end 428.03445 -275.65985)
		(width 0.16002)
		(layer "In11.Cu")
		(net "M_L_CPU0_SB_DQS_DP<9>")
	)
	(segment
		(start 437.864504 -275.16455)
		(end 438.219088 -274.809966)
		(width 0.16002)
		(layer "In11.Cu")
		(net "M_L_CPU0_SB_DQS_DP<9>")
	)
	(segment
		(start 395.39799 -269.216124)
		(end 395.493748 -269.311882)
		(width 0.09525)
		(layer "In11.Cu")
		(net "M_L_CPU0_SB_DQS_DP<9>")
	)
	(segment
		(start 420.818056 -275.98751)
		(end 421.541956 -275.98751)
		(width 0.16002)
		(layer "In11.Cu")
		(net "M_L_CPU0_SB_DQS_DP<9>")
	)
	(segment
		(start 425.040552 -274.809966)
		(end 425.890436 -275.65985)
		(width 0.16002)
		(layer "In11.Cu")
		(net "M_L_CPU0_SB_DQS_DP<9>")
	)
	(segment
		(start 451.895464 -275.808948)
		(end 452.623428 -275.808948)
		(width 0.16002)
		(layer "In11.Cu")
		(net "M_L_CPU0_SB_DQS_DP<9>")
	)
	(segment
		(start 452.623428 -275.808948)
		(end 452.750428 -275.681948)
		(width 0.16002)
		(layer "In11.Cu")
		(net "M_L_CPU0_SB_DQS_DP<9>")
	)
	(segment
		(start 435.906164 -275.98751)
		(end 436.630064 -275.98751)
		(width 0.16002)
		(layer "In11.Cu")
		(net "M_L_CPU0_SB_DQS_DP<9>")
	)
	(segment
		(start 395.859254 -269.2527)
		(end 405.677624 -269.2527)
		(width 0.16002)
		(layer "In11.Cu")
		(net "M_L_CPU0_SB_DQS_DP<9>")
	)
	(segment
		(start 432.584606 -274.809966)
		(end 433.43449 -275.65985)
		(width 0.16002)
		(layer "In11.Cu")
		(net "M_L_CPU0_SB_DQS_DP<9>")
	)
	(segment
		(start 445.408558 -275.16455)
		(end 445.763142 -274.809966)
		(width 0.16002)
		(layer "In11.Cu")
		(net "M_L_CPU0_SB_DQS_DP<9>")
	)
	(segment
		(start 433.43449 -275.65985)
		(end 435.578504 -275.65985)
		(width 0.16002)
		(layer "In11.Cu")
		(net "M_L_CPU0_SB_DQS_DP<9>")
	)
	(segment
		(start 392.6332 -271.171162)
		(end 392.666982 -271.151604)
		(width 0.09525)
		(layer "In11.Cu")
		(net "M_L_CPU0_SB_DQS_DP<9>")
	)
	(segment
		(start 451.701662 -276.00275)
		(end 451.895464 -275.808948)
		(width 0.16002)
		(layer "In11.Cu")
		(net "M_L_CPU0_SB_DQS_DP<9>")
	)
	(segment
		(start 388.496302 -271.171162)
		(end 388.504684 -271.175988)
		(width 0.09525)
		(layer "In11.Cu")
		(net "M_L_CPU0_SB_DQS_DP<9>")
	)
	(segment
		(start 395.77645 -269.311882)
		(end 395.835632 -269.2527)
		(width 0.09525)
		(layer "In11.Cu")
		(net "M_L_CPU0_SB_DQS_DP<9>")
	)
	(segment
		(start 430.675034 -274.809966)
		(end 432.584606 -274.809966)
		(width 0.16002)
		(layer "In11.Cu")
		(net "M_L_CPU0_SB_DQS_DP<9>")
	)
	(segment
		(start 438.219088 -274.809966)
		(end 440.12866 -274.809966)
		(width 0.16002)
		(layer "In11.Cu")
		(net "M_L_CPU0_SB_DQS_DP<9>")
	)
	(segment
		(start 421.541956 -275.98751)
		(end 422.364916 -275.16455)
		(width 0.16002)
		(layer "In11.Cu")
		(net "M_L_CPU0_SB_DQS_DP<9>")
	)
	(segment
		(start 392.62431 -271.175988)
		(end 392.632692 -271.171162)
		(width 0.09525)
		(layer "In11.Cu")
		(net "M_L_CPU0_SB_DQS_DP<9>")
	)
	(segment
		(start 447.672714 -274.809966)
		(end 448.246754 -275.384006)
		(width 0.16002)
		(layer "In11.Cu")
		(net "M_L_CPU0_SB_DQS_DP<9>")
	)
	(segment
		(start 436.630064 -275.98751)
		(end 437.453024 -275.16455)
		(width 0.16002)
		(layer "In11.Cu")
		(net "M_L_CPU0_SB_DQS_DP<9>")
	)
	(segment
		(start 395.835632 -269.2527)
		(end 395.859254 -269.2527)
		(width 0.09525)
		(layer "In11.Cu")
		(net "M_L_CPU0_SB_DQS_DP<9>")
	)
	(segment
		(start 451.287134 -276.00275)
		(end 451.701662 -276.00275)
		(width 0.16002)
		(layer "In11.Cu")
		(net "M_L_CPU0_SB_DQS_DP<9>")
	)
	(segment
		(start 452.750428 -275.681948)
		(end 453.230488 -275.681948)
		(width 0.16002)
		(layer "In11.Cu")
		(net "M_L_CPU0_SB_DQS_DP<9>")
	)
	(segment
		(start 453.357488 -275.808948)
		(end 453.914256 -275.808948)
		(width 0.16002)
		(layer "In11.Cu")
		(net "M_L_CPU0_SB_DQS_DP<9>")
	)
	(segment
		(start 453.914256 -275.808948)
		(end 454.188068 -275.535136)
		(width 0.16002)
		(layer "In11.Cu")
		(net "M_L_CPU0_SB_DQS_DP<9>")
	)
	(segment
		(start 443.450218 -275.98751)
		(end 444.174118 -275.98751)
		(width 0.16002)
		(layer "In11.Cu")
		(net "M_L_CPU0_SB_DQS_DP<9>")
	)
	(segment
		(start 395.493748 -269.311882)
		(end 395.77645 -269.311882)
		(width 0.09525)
		(layer "In11.Cu")
		(net "M_L_CPU0_SB_DQS_DP<9>")
	)
	(segment
		(start 391.31621 -271.171162)
		(end 391.324592 -271.175988)
		(width 0.09525)
		(layer "In11.Cu")
		(net "M_L_CPU0_SB_DQS_DP<9>")
	)
	(segment
		(start 392.245596 -271.165066)
		(end 392.25601 -271.171162)
		(width 0.09525)
		(layer "In11.Cu")
		(net "M_L_CPU0_SB_DQS_DP<9>")
	)
	(segment
		(start 437.453024 -275.16455)
		(end 437.864504 -275.16455)
		(width 0.16002)
		(layer "In11.Cu")
		(net "M_L_CPU0_SB_DQS_DP<9>")
	)
	(segment
		(start 392.632692 -271.171162)
		(end 392.6332 -271.171162)
		(width 0.09525)
		(layer "In11.Cu")
		(net "M_L_CPU0_SB_DQS_DP<9>")
	)
	(segment
		(start 440.978544 -275.65985)
		(end 443.122558 -275.65985)
		(width 0.16002)
		(layer "In11.Cu")
		(net "M_L_CPU0_SB_DQS_DP<9>")
	)
	(segment
		(start 444.997078 -275.16455)
		(end 445.408558 -275.16455)
		(width 0.16002)
		(layer "In11.Cu")
		(net "M_L_CPU0_SB_DQS_DP<9>")
	)
	(segment
		(start 435.578504 -275.65985)
		(end 435.906164 -275.98751)
		(width 0.16002)
		(layer "In11.Cu")
		(net "M_L_CPU0_SB_DQS_DP<9>")
	)
	(segment
		(start 444.174118 -275.98751)
		(end 444.997078 -275.16455)
		(width 0.16002)
		(layer "In11.Cu")
		(net "M_L_CPU0_SB_DQS_DP<9>")
	)
	(segment
		(start 430.32045 -275.16455)
		(end 430.675034 -274.809966)
		(width 0.16002)
		(layer "In11.Cu")
		(net "M_L_CPU0_SB_DQS_DP<9>")
	)
	(segment
		(start 419.995096 -275.16455)
		(end 420.818056 -275.98751)
		(width 0.16002)
		(layer "In11.Cu")
		(net "M_L_CPU0_SB_DQS_DP<9>")
	)
	(segment
		(start 394.654786 -269.216124)
		(end 395.39799 -269.216124)
		(width 0.09525)
		(layer "In11.Cu")
		(net "M_L_CPU0_SB_DQS_DP<9>")
	)
	(segment
		(start 450.66839 -275.384006)
		(end 451.287134 -276.00275)
		(width 0.16002)
		(layer "In11.Cu")
		(net "M_L_CPU0_SB_DQS_DP<9>")
	)
	(segment
		(start 412.412434 -275.98751)
		(end 413.997902 -275.98751)
		(width 0.16002)
		(layer "In11.Cu")
		(net "M_L_CPU0_SB_DQS_DP<9>")
	)
	(segment
		(start 387.744716 -270.846042)
		(end 387.590792 -271.111472)
		(width 0.09525)
		(layer "In11.Cu")
		(net "M_L_CPU0_SB_DQS_DP<9>")
	)
	(segment
		(start 414.820862 -275.16455)
		(end 419.995096 -275.16455)
		(width 0.16002)
		(layer "In11.Cu")
		(net "M_L_CPU0_SB_DQS_DP<9>")
	)
	(segment
		(start 428.36211 -275.98751)
		(end 429.08601 -275.98751)
		(width 0.16002)
		(layer "In11.Cu")
		(net "M_L_CPU0_SB_DQS_DP<9>")
	)
	(segment
		(start 413.997902 -275.98751)
		(end 414.820862 -275.16455)
		(width 0.16002)
		(layer "In11.Cu")
		(net "M_L_CPU0_SB_DQS_DP<9>")
	)
	(segment
		(start 390.744964 -271.175988)
		(end 390.753346 -271.171162)
		(width 0.09525)
		(layer "In11.Cu")
		(net "M_L_CPU0_SB_DQS_DP<9>")
	)
	(segment
		(start 453.230488 -275.681948)
		(end 453.357488 -275.808948)
		(width 0.16002)
		(layer "In11.Cu")
		(net "M_L_CPU0_SB_DQS_DP<9>")
	)
	(segment
		(start 423.13098 -274.809966)
		(end 425.040552 -274.809966)
		(width 0.16002)
		(layer "In11.Cu")
		(net "M_L_CPU0_SB_DQS_DP<9>")
	)
	(segment
		(start 443.122558 -275.65985)
		(end 443.450218 -275.98751)
		(width 0.16002)
		(layer "In11.Cu")
		(net "M_L_CPU0_SB_DQS_DP<9>")
	)
	(segment
		(start 429.90897 -275.16455)
		(end 430.32045 -275.16455)
		(width 0.16002)
		(layer "In11.Cu")
		(net "M_L_CPU0_SB_DQS_DP<9>")
	)
	(segment
		(start 393.585446 -270.285464)
		(end 394.654786 -269.216124)
		(width 0.09525)
		(layer "In11.Cu")
		(net "M_L_CPU0_SB_DQS_DP<9>")
	)
	(segment
		(start 429.08601 -275.98751)
		(end 429.90897 -275.16455)
		(width 0.16002)
		(layer "In11.Cu")
		(net "M_L_CPU0_SB_DQS_DP<9>")
	)
	(segment
		(start 445.763142 -274.809966)
		(end 447.672714 -274.809966)
		(width 0.16002)
		(layer "In11.Cu")
		(net "M_L_CPU0_SB_DQS_DP<9>")
	)
	(segment
		(start 393.384786 -270.285464)
		(end 393.585446 -270.285464)
		(width 0.09525)
		(layer "In11.Cu")
		(net "M_L_CPU0_SB_DQS_DP<9>")
	)
	(arc
		(start 390.753346 -271.171162)
		(mid 391.034778 -271.095407)
		(end 391.31621 -271.171162)
		(width 0.09525)
		(layer "In11.Cu")
		(net "M_L_CPU0_SB_DQS_DP<9>")
	)
	(arc
		(start 392.25601 -271.171162)
		(mid 392.439531 -271.221806)
		(end 392.62431 -271.175988)
		(width 0.09525)
		(layer "In11.Cu")
		(net "M_L_CPU0_SB_DQS_DP<9>")
	)
	(arc
		(start 388.873492 -271.171162)
		(mid 389.154924 -271.095407)
		(end 389.436356 -271.171162)
		(width 0.09525)
		(layer "In11.Cu")
		(net "M_L_CPU0_SB_DQS_DP<9>")
	)
	(arc
		(start 389.436356 -271.171162)
		(mid 389.624824 -271.221839)
		(end 389.813292 -271.171162)
		(width 0.09525)
		(layer "In11.Cu")
		(net "M_L_CPU0_SB_DQS_DP<9>")
	)
	(arc
		(start 389.813292 -271.171162)
		(mid 390.094724 -271.095407)
		(end 390.376156 -271.171162)
		(width 0.09525)
		(layer "In11.Cu")
		(net "M_L_CPU0_SB_DQS_DP<9>")
	)
	(arc
		(start 390.376156 -271.171162)
		(mid 390.559931 -271.221934)
		(end 390.744964 -271.175988)
		(width 0.09525)
		(layer "In11.Cu")
		(net "M_L_CPU0_SB_DQS_DP<9>")
	)
	(arc
		(start 388.504684 -271.175988)
		(mid 388.689716 -271.221902)
		(end 388.873492 -271.171162)
		(width 0.09525)
		(layer "In11.Cu")
		(net "M_L_CPU0_SB_DQS_DP<9>")
	)
	(arc
		(start 391.6934 -271.171162)
		(mid 391.968689 -271.095441)
		(end 392.245596 -271.165066)
		(width 0.09525)
		(layer "In11.Cu")
		(net "M_L_CPU0_SB_DQS_DP<9>")
	)
	(arc
		(start 387.61416 -271.19834)
		(mid 387.776842 -271.220472)
		(end 387.933438 -271.171162)
		(width 0.09525)
		(layer "In11.Cu")
		(net "M_L_CPU0_SB_DQS_DP<9>")
	)
	(arc
		(start 392.666982 -271.151604)
		(mid 392.781361 -271.017465)
		(end 392.82243 -270.846042)
		(width 0.09525)
		(layer "In11.Cu")
		(net "M_L_CPU0_SB_DQS_DP<9>")
	)
	(arc
		(start 393.103354 -270.361156)
		(mid 393.239061 -270.304671)
		(end 393.384786 -270.285464)
		(width 0.09525)
		(layer "In11.Cu")
		(net "M_L_CPU0_SB_DQS_DP<9>")
	)
	(arc
		(start 391.324592 -271.175988)
		(mid 391.509624 -271.221902)
		(end 391.6934 -271.171162)
		(width 0.09525)
		(layer "In11.Cu")
		(net "M_L_CPU0_SB_DQS_DP<9>")
	)
	(arc
		(start 392.82243 -270.846042)
		(mid 392.886827 -270.584736)
		(end 393.065254 -270.383254)
		(width 0.09525)
		(layer "In11.Cu")
		(net "M_L_CPU0_SB_DQS_DP<9>")
	)
	(arc
		(start 387.933438 -271.171162)
		(mid 388.21487 -271.095407)
		(end 388.496302 -271.171162)
		(width 0.09525)
		(layer "In11.Cu")
		(net "M_L_CPU0_SB_DQS_DP<9>")
	)
	(segment
		(start 385.39801 -291.640006)
		(end 385.864862 -291.905944)
		(width 0.12954)
		(layer "F.Cu")
		(net "M_L_CPU0_SB_DQS_DP<8>")
	)
	(segment
		(start 394.475208 -294.79875)
		(end 394.513308 -294.820848)
		(width 0.09525)
		(layer "In11.Cu")
		(net "M_L_CPU0_SB_DQS_DP<8>")
	)
	(segment
		(start 433.301902 -314.510166)
		(end 434.15204 -315.360304)
		(width 0.16002)
		(layer "In11.Cu")
		(net "M_L_CPU0_SB_DQS_DP<8>")
	)
	(segment
		(start 409.709112 -314.985146)
		(end 414.086548 -314.985146)
		(width 0.16002)
		(layer "In11.Cu")
		(net "M_L_CPU0_SB_DQS_DP<8>")
	)
	(segment
		(start 421.630602 -314.985146)
		(end 422.484042 -314.131706)
		(width 0.16002)
		(layer "In11.Cu")
		(net "M_L_CPU0_SB_DQS_DP<8>")
	)
	(segment
		(start 437.57215 -314.131706)
		(end 438.144158 -314.131706)
		(width 0.16002)
		(layer "In11.Cu")
		(net "M_L_CPU0_SB_DQS_DP<8>")
	)
	(segment
		(start 429.174656 -314.985146)
		(end 430.028096 -314.131706)
		(width 0.16002)
		(layer "In11.Cu")
		(net "M_L_CPU0_SB_DQS_DP<8>")
	)
	(segment
		(start 438.522618 -314.510166)
		(end 440.845956 -314.510166)
		(width 0.16002)
		(layer "In11.Cu")
		(net "M_L_CPU0_SB_DQS_DP<8>")
	)
	(segment
		(start 417.520628 -314.410852)
		(end 417.680648 -314.250832)
		(width 0.16002)
		(layer "In11.Cu")
		(net "M_L_CPU0_SB_DQS_DP<8>")
	)
	(segment
		(start 435.722268 -315.360304)
		(end 436.097426 -314.985146)
		(width 0.16002)
		(layer "In11.Cu")
		(net "M_L_CPU0_SB_DQS_DP<8>")
	)
	(segment
		(start 417.680648 -314.250832)
		(end 418.780722 -314.250832)
		(width 0.16002)
		(layer "In11.Cu")
		(net "M_L_CPU0_SB_DQS_DP<8>")
	)
	(segment
		(start 423.43451 -314.510166)
		(end 425.757848 -314.510166)
		(width 0.16002)
		(layer "In11.Cu")
		(net "M_L_CPU0_SB_DQS_DP<8>")
	)
	(segment
		(start 390.744964 -291.575998)
		(end 390.753346 -291.580824)
		(width 0.09525)
		(layer "In11.Cu")
		(net "M_L_CPU0_SB_DQS_DP<8>")
	)
	(segment
		(start 395.195806 -296.378884)
		(end 395.195806 -296.402506)
		(width 0.09525)
		(layer "In11.Cu")
		(net "M_L_CPU0_SB_DQS_DP<8>")
	)
	(segment
		(start 416.247834 -314.410852)
		(end 416.247834 -314.945014)
		(width 0.16002)
		(layer "In11.Cu")
		(net "M_L_CPU0_SB_DQS_DP<8>")
	)
	(segment
		(start 428.553372 -314.985146)
		(end 429.174656 -314.985146)
		(width 0.16002)
		(layer "In11.Cu")
		(net "M_L_CPU0_SB_DQS_DP<8>")
	)
	(segment
		(start 386.985002 -291.575998)
		(end 386.993384 -291.580824)
		(width 0.09525)
		(layer "In11.Cu")
		(net "M_L_CPU0_SB_DQS_DP<8>")
	)
	(segment
		(start 438.144158 -314.131706)
		(end 438.522618 -314.510166)
		(width 0.16002)
		(layer "In11.Cu")
		(net "M_L_CPU0_SB_DQS_DP<8>")
	)
	(segment
		(start 414.086548 -314.985146)
		(end 414.939988 -314.131706)
		(width 0.16002)
		(layer "In11.Cu")
		(net "M_L_CPU0_SB_DQS_DP<8>")
	)
	(segment
		(start 445.116204 -314.131706)
		(end 445.688212 -314.131706)
		(width 0.16002)
		(layer "In11.Cu")
		(net "M_L_CPU0_SB_DQS_DP<8>")
	)
	(segment
		(start 445.688212 -314.131706)
		(end 446.066672 -314.510166)
		(width 0.16002)
		(layer "In11.Cu")
		(net "M_L_CPU0_SB_DQS_DP<8>")
	)
	(segment
		(start 416.584892 -315.282072)
		(end 417.18357 -315.282072)
		(width 0.16002)
		(layer "In11.Cu")
		(net "M_L_CPU0_SB_DQS_DP<8>")
	)
	(segment
		(start 394.590778 -294.879776)
		(end 395.254988 -295.543986)
		(width 0.09525)
		(layer "In11.Cu")
		(net "M_L_CPU0_SB_DQS_DP<8>")
	)
	(segment
		(start 417.18357 -315.282072)
		(end 417.520628 -314.945014)
		(width 0.16002)
		(layer "In11.Cu")
		(net "M_L_CPU0_SB_DQS_DP<8>")
	)
	(segment
		(start 385.864862 -291.905944)
		(end 386.018786 -291.640514)
		(width 0.09525)
		(layer "In11.Cu")
		(net "M_L_CPU0_SB_DQS_DP<8>")
	)
	(segment
		(start 391.31621 -291.580824)
		(end 391.324592 -291.575998)
		(width 0.09525)
		(layer "In11.Cu")
		(net "M_L_CPU0_SB_DQS_DP<8>")
	)
	(segment
		(start 430.028096 -314.131706)
		(end 430.600104 -314.131706)
		(width 0.16002)
		(layer "In11.Cu")
		(net "M_L_CPU0_SB_DQS_DP<8>")
	)
	(segment
		(start 421.009318 -314.985146)
		(end 421.630602 -314.985146)
		(width 0.16002)
		(layer "In11.Cu")
		(net "M_L_CPU0_SB_DQS_DP<8>")
	)
	(segment
		(start 430.600104 -314.131706)
		(end 430.978564 -314.510166)
		(width 0.16002)
		(layer "In11.Cu")
		(net "M_L_CPU0_SB_DQS_DP<8>")
	)
	(segment
		(start 436.097426 -314.985146)
		(end 436.71871 -314.985146)
		(width 0.16002)
		(layer "In11.Cu")
		(net "M_L_CPU0_SB_DQS_DP<8>")
	)
	(segment
		(start 393.762484 -293.440358)
		(end 393.762484 -293.525956)
		(width 0.09525)
		(layer "In11.Cu")
		(net "M_L_CPU0_SB_DQS_DP<8>")
	)
	(segment
		(start 449.814188 -314.361322)
		(end 450.088 -314.635134)
		(width 0.16002)
		(layer "In11.Cu")
		(net "M_L_CPU0_SB_DQS_DP<8>")
	)
	(segment
		(start 441.696094 -315.360304)
		(end 443.266322 -315.360304)
		(width 0.16002)
		(layer "In11.Cu")
		(net "M_L_CPU0_SB_DQS_DP<8>")
	)
	(segment
		(start 422.484042 -314.131706)
		(end 423.05605 -314.131706)
		(width 0.16002)
		(layer "In11.Cu")
		(net "M_L_CPU0_SB_DQS_DP<8>")
	)
	(segment
		(start 416.247834 -314.945014)
		(end 416.584892 -315.282072)
		(width 0.16002)
		(layer "In11.Cu")
		(net "M_L_CPU0_SB_DQS_DP<8>")
	)
	(segment
		(start 420.63416 -315.360304)
		(end 421.009318 -314.985146)
		(width 0.16002)
		(layer "In11.Cu")
		(net "M_L_CPU0_SB_DQS_DP<8>")
	)
	(segment
		(start 444.262764 -314.985146)
		(end 445.116204 -314.131706)
		(width 0.16002)
		(layer "In11.Cu")
		(net "M_L_CPU0_SB_DQS_DP<8>")
	)
	(segment
		(start 443.266322 -315.360304)
		(end 443.64148 -314.985146)
		(width 0.16002)
		(layer "In11.Cu")
		(net "M_L_CPU0_SB_DQS_DP<8>")
	)
	(segment
		(start 395.195806 -296.402506)
		(end 395.195806 -300.47184)
		(width 0.16002)
		(layer "In11.Cu")
		(net "M_L_CPU0_SB_DQS_DP<8>")
	)
	(segment
		(start 395.254988 -295.543986)
		(end 395.254988 -296.319702)
		(width 0.09525)
		(layer "In11.Cu")
		(net "M_L_CPU0_SB_DQS_DP<8>")
	)
	(segment
		(start 386.018786 -291.640514)
		(end 386.119624 -291.613844)
		(width 0.09525)
		(layer "In11.Cu")
		(net "M_L_CPU0_SB_DQS_DP<8>")
	)
	(segment
		(start 395.195806 -300.47184)
		(end 409.709112 -314.985146)
		(width 0.16002)
		(layer "In11.Cu")
		(net "M_L_CPU0_SB_DQS_DP<8>")
	)
	(segment
		(start 419.025578 -314.495688)
		(end 419.025578 -314.918852)
		(width 0.16002)
		(layer "In11.Cu")
		(net "M_L_CPU0_SB_DQS_DP<8>")
	)
	(segment
		(start 426.607986 -315.360304)
		(end 428.178214 -315.360304)
		(width 0.16002)
		(layer "In11.Cu")
		(net "M_L_CPU0_SB_DQS_DP<8>")
	)
	(segment
		(start 440.845956 -314.510166)
		(end 441.696094 -315.360304)
		(width 0.16002)
		(layer "In11.Cu")
		(net "M_L_CPU0_SB_DQS_DP<8>")
	)
	(segment
		(start 415.968688 -314.131706)
		(end 416.247834 -314.410852)
		(width 0.16002)
		(layer "In11.Cu")
		(net "M_L_CPU0_SB_DQS_DP<8>")
	)
	(segment
		(start 392.930634 -292.269164)
		(end 392.930634 -292.269418)
		(width 0.09525)
		(layer "In11.Cu")
		(net "M_L_CPU0_SB_DQS_DP<8>")
	)
	(segment
		(start 436.71871 -314.985146)
		(end 437.57215 -314.131706)
		(width 0.16002)
		(layer "In11.Cu")
		(net "M_L_CPU0_SB_DQS_DP<8>")
	)
	(segment
		(start 430.978564 -314.510166)
		(end 433.301902 -314.510166)
		(width 0.16002)
		(layer "In11.Cu")
		(net "M_L_CPU0_SB_DQS_DP<8>")
	)
	(segment
		(start 428.178214 -315.360304)
		(end 428.553372 -314.985146)
		(width 0.16002)
		(layer "In11.Cu")
		(net "M_L_CPU0_SB_DQS_DP<8>")
	)
	(segment
		(start 447.37782 -314.510166)
		(end 447.526664 -314.361322)
		(width 0.16002)
		(layer "In11.Cu")
		(net "M_L_CPU0_SB_DQS_DP<8>")
	)
	(segment
		(start 446.066672 -314.510166)
		(end 447.37782 -314.510166)
		(width 0.16002)
		(layer "In11.Cu")
		(net "M_L_CPU0_SB_DQS_DP<8>")
	)
	(segment
		(start 392.930634 -292.269418)
		(end 393.522708 -292.861492)
		(width 0.09525)
		(layer "In11.Cu")
		(net "M_L_CPU0_SB_DQS_DP<8>")
	)
	(segment
		(start 417.520628 -314.945014)
		(end 417.520628 -314.410852)
		(width 0.16002)
		(layer "In11.Cu")
		(net "M_L_CPU0_SB_DQS_DP<8>")
	)
	(segment
		(start 394.008102 -293.990268)
		(end 394.019786 -293.997126)
		(width 0.09525)
		(layer "In11.Cu")
		(net "M_L_CPU0_SB_DQS_DP<8>")
	)
	(segment
		(start 434.15204 -315.360304)
		(end 435.722268 -315.360304)
		(width 0.16002)
		(layer "In11.Cu")
		(net "M_L_CPU0_SB_DQS_DP<8>")
	)
	(segment
		(start 419.46703 -315.360304)
		(end 420.63416 -315.360304)
		(width 0.16002)
		(layer "In11.Cu")
		(net "M_L_CPU0_SB_DQS_DP<8>")
	)
	(segment
		(start 447.526664 -314.361322)
		(end 449.814188 -314.361322)
		(width 0.16002)
		(layer "In11.Cu")
		(net "M_L_CPU0_SB_DQS_DP<8>")
	)
	(segment
		(start 388.496302 -291.580824)
		(end 388.504684 -291.575998)
		(width 0.09525)
		(layer "In11.Cu")
		(net "M_L_CPU0_SB_DQS_DP<8>")
	)
	(segment
		(start 418.780722 -314.250832)
		(end 419.025578 -314.495688)
		(width 0.16002)
		(layer "In11.Cu")
		(net "M_L_CPU0_SB_DQS_DP<8>")
	)
	(segment
		(start 425.757848 -314.510166)
		(end 426.607986 -315.360304)
		(width 0.16002)
		(layer "In11.Cu")
		(net "M_L_CPU0_SB_DQS_DP<8>")
	)
	(segment
		(start 423.05605 -314.131706)
		(end 423.43451 -314.510166)
		(width 0.16002)
		(layer "In11.Cu")
		(net "M_L_CPU0_SB_DQS_DP<8>")
	)
	(segment
		(start 414.939988 -314.131706)
		(end 415.968688 -314.131706)
		(width 0.16002)
		(layer "In11.Cu")
		(net "M_L_CPU0_SB_DQS_DP<8>")
	)
	(segment
		(start 395.254988 -296.319702)
		(end 395.195806 -296.378884)
		(width 0.09525)
		(layer "In11.Cu")
		(net "M_L_CPU0_SB_DQS_DP<8>")
	)
	(segment
		(start 443.64148 -314.985146)
		(end 444.262764 -314.985146)
		(width 0.16002)
		(layer "In11.Cu")
		(net "M_L_CPU0_SB_DQS_DP<8>")
	)
	(segment
		(start 387.556248 -291.580824)
		(end 387.56463 -291.575998)
		(width 0.09525)
		(layer "In11.Cu")
		(net "M_L_CPU0_SB_DQS_DP<8>")
	)
	(segment
		(start 391.974832 -291.656516)
		(end 392.525758 -291.656516)
		(width 0.09525)
		(layer "In11.Cu")
		(net "M_L_CPU0_SB_DQS_DP<8>")
	)
	(segment
		(start 394.019786 -293.997126)
		(end 394.074904 -294.02913)
		(width 0.09525)
		(layer "In11.Cu")
		(net "M_L_CPU0_SB_DQS_DP<8>")
	)
	(segment
		(start 419.025578 -314.918852)
		(end 419.46703 -315.360304)
		(width 0.16002)
		(layer "In11.Cu")
		(net "M_L_CPU0_SB_DQS_DP<8>")
	)
	(arc
		(start 390.376156 -291.580824)
		(mid 390.559931 -291.530052)
		(end 390.744964 -291.575998)
		(width 0.09525)
		(layer "In11.Cu")
		(net "M_L_CPU0_SB_DQS_DP<8>")
	)
	(arc
		(start 386.616194 -291.580824)
		(mid 386.799969 -291.530052)
		(end 386.985002 -291.575998)
		(width 0.09525)
		(layer "In11.Cu")
		(net "M_L_CPU0_SB_DQS_DP<8>")
	)
	(arc
		(start 391.6934 -291.580824)
		(mid 391.829107 -291.637309)
		(end 391.974832 -291.656516)
		(width 0.09525)
		(layer "In11.Cu")
		(net "M_L_CPU0_SB_DQS_DP<8>")
	)
	(arc
		(start 390.753346 -291.580824)
		(mid 391.034778 -291.656579)
		(end 391.31621 -291.580824)
		(width 0.09525)
		(layer "In11.Cu")
		(net "M_L_CPU0_SB_DQS_DP<8>")
	)
	(arc
		(start 392.525758 -291.656516)
		(mid 392.623348 -291.675928)
		(end 392.706098 -291.731192)
		(width 0.09525)
		(layer "In11.Cu")
		(net "M_L_CPU0_SB_DQS_DP<8>")
	)
	(arc
		(start 394.513308 -294.820848)
		(mid 394.533267 -294.833196)
		(end 394.552424 -294.846756)
		(width 0.09525)
		(layer "In11.Cu")
		(net "M_L_CPU0_SB_DQS_DP<8>")
	)
	(arc
		(start 394.552424 -294.846756)
		(mid 394.572162 -294.862615)
		(end 394.590778 -294.879776)
		(width 0.09525)
		(layer "In11.Cu")
		(net "M_L_CPU0_SB_DQS_DP<8>")
	)
	(arc
		(start 386.119624 -291.613844)
		(mid 386.129746 -291.617879)
		(end 386.139944 -291.621718)
		(width 0.09525)
		(layer "In11.Cu")
		(net "M_L_CPU0_SB_DQS_DP<8>")
	)
	(arc
		(start 388.504684 -291.575998)
		(mid 388.689716 -291.530084)
		(end 388.873492 -291.580824)
		(width 0.09525)
		(layer "In11.Cu")
		(net "M_L_CPU0_SB_DQS_DP<8>")
	)
	(arc
		(start 389.813292 -291.580824)
		(mid 390.094724 -291.656579)
		(end 390.376156 -291.580824)
		(width 0.09525)
		(layer "In11.Cu")
		(net "M_L_CPU0_SB_DQS_DP<8>")
	)
	(arc
		(start 387.933438 -291.580824)
		(mid 388.21487 -291.656579)
		(end 388.496302 -291.580824)
		(width 0.09525)
		(layer "In11.Cu")
		(net "M_L_CPU0_SB_DQS_DP<8>")
	)
	(arc
		(start 392.764518 -291.870384)
		(mid 392.80823 -292.086157)
		(end 392.930634 -292.269164)
		(width 0.09525)
		(layer "In11.Cu")
		(net "M_L_CPU0_SB_DQS_DP<8>")
	)
	(arc
		(start 386.993384 -291.580824)
		(mid 387.274816 -291.656579)
		(end 387.556248 -291.580824)
		(width 0.09525)
		(layer "In11.Cu")
		(net "M_L_CPU0_SB_DQS_DP<8>")
	)
	(arc
		(start 389.436356 -291.580824)
		(mid 389.624824 -291.530147)
		(end 389.813292 -291.580824)
		(width 0.09525)
		(layer "In11.Cu")
		(net "M_L_CPU0_SB_DQS_DP<8>")
	)
	(arc
		(start 392.706098 -291.731192)
		(mid 392.748972 -291.795049)
		(end 392.764518 -291.870384)
		(width 0.09525)
		(layer "In11.Cu")
		(net "M_L_CPU0_SB_DQS_DP<8>")
	)
	(arc
		(start 388.873492 -291.580824)
		(mid 389.154924 -291.656579)
		(end 389.436356 -291.580824)
		(width 0.09525)
		(layer "In11.Cu")
		(net "M_L_CPU0_SB_DQS_DP<8>")
	)
	(arc
		(start 386.139944 -291.621718)
		(mid 386.382656 -291.654601)
		(end 386.616194 -291.580824)
		(width 0.09525)
		(layer "In11.Cu")
		(net "M_L_CPU0_SB_DQS_DP<8>")
	)
	(arc
		(start 394.232384 -294.335962)
		(mid 394.296781 -294.597268)
		(end 394.475208 -294.79875)
		(width 0.09525)
		(layer "In11.Cu")
		(net "M_L_CPU0_SB_DQS_DP<8>")
	)
	(arc
		(start 393.762484 -293.525956)
		(mid 393.827731 -293.788559)
		(end 394.008102 -293.990268)
		(width 0.09525)
		(layer "In11.Cu")
		(net "M_L_CPU0_SB_DQS_DP<8>")
	)
	(arc
		(start 394.074904 -294.02913)
		(mid 394.190702 -294.163524)
		(end 394.232384 -294.335962)
		(width 0.09525)
		(layer "In11.Cu")
		(net "M_L_CPU0_SB_DQS_DP<8>")
	)
	(arc
		(start 391.324592 -291.575998)
		(mid 391.509624 -291.530084)
		(end 391.6934 -291.580824)
		(width 0.09525)
		(layer "In11.Cu")
		(net "M_L_CPU0_SB_DQS_DP<8>")
	)
	(arc
		(start 393.522708 -292.861492)
		(mid 393.700167 -293.127078)
		(end 393.762484 -293.440358)
		(width 0.09525)
		(layer "In11.Cu")
		(net "M_L_CPU0_SB_DQS_DP<8>")
	)
	(arc
		(start 387.56463 -291.575998)
		(mid 387.749662 -291.530084)
		(end 387.933438 -291.580824)
		(width 0.09525)
		(layer "In11.Cu")
		(net "M_L_CPU0_SB_DQS_DP<8>")
	)
	(segment
		(start 385.39801 -286.780224)
		(end 385.864862 -287.045908)
		(width 0.12954)
		(layer "F.Cu")
		(net "M_L_CPU0_SB_DQS_DP<7>")
	)
	(segment
		(start 405.666702 -301.119032)
		(end 405.587962 -301.197772)
		(width 0.16002)
		(layer "In11.Cu")
		(net "M_L_CPU0_SB_DQS_DP<7>")
	)
	(segment
		(start 387.556248 -286.720788)
		(end 387.56463 -286.715962)
		(width 0.09525)
		(layer "In11.Cu")
		(net "M_L_CPU0_SB_DQS_DP<7>")
	)
	(segment
		(start 406.961594 -303.047908)
		(end 409.548838 -305.635152)
		(width 0.16002)
		(layer "In11.Cu")
		(net "M_L_CPU0_SB_DQS_DP<7>")
	)
	(segment
		(start 438.522618 -305.160172)
		(end 440.845956 -305.160172)
		(width 0.16002)
		(layer "In11.Cu")
		(net "M_L_CPU0_SB_DQS_DP<7>")
	)
	(segment
		(start 415.890456 -305.160172)
		(end 418.332158 -305.160172)
		(width 0.16002)
		(layer "In11.Cu")
		(net "M_L_CPU0_SB_DQS_DP<7>")
	)
	(segment
		(start 392.608054 -286.628332)
		(end 393.964414 -286.628332)
		(width 0.09525)
		(layer "In11.Cu")
		(net "M_L_CPU0_SB_DQS_DP<7>")
	)
	(segment
		(start 402.919438 -298.145962)
		(end 402.919438 -298.371768)
		(width 0.16002)
		(layer "In11.Cu")
		(net "M_L_CPU0_SB_DQS_DP<7>")
	)
	(segment
		(start 445.688212 -304.781712)
		(end 446.066672 -305.160172)
		(width 0.16002)
		(layer "In11.Cu")
		(net "M_L_CPU0_SB_DQS_DP<7>")
	)
	(segment
		(start 405.666702 -300.893226)
		(end 405.666702 -301.119032)
		(width 0.16002)
		(layer "In11.Cu")
		(net "M_L_CPU0_SB_DQS_DP<7>")
	)
	(segment
		(start 406.487884 -302.097948)
		(end 406.566624 -302.019462)
		(width 0.16002)
		(layer "In11.Cu")
		(net "M_L_CPU0_SB_DQS_DP<7>")
	)
	(segment
		(start 395.504416 -287.595818)
		(end 395.503908 -287.67913)
		(width 0.09525)
		(layer "In11.Cu")
		(net "M_L_CPU0_SB_DQS_DP<7>")
	)
	(segment
		(start 426.607986 -306.01031)
		(end 428.178214 -306.01031)
		(width 0.16002)
		(layer "In11.Cu")
		(net "M_L_CPU0_SB_DQS_DP<7>")
	)
	(segment
		(start 441.696094 -306.01031)
		(end 443.266322 -306.01031)
		(width 0.16002)
		(layer "In11.Cu")
		(net "M_L_CPU0_SB_DQS_DP<7>")
	)
	(segment
		(start 428.178214 -306.01031)
		(end 428.553372 -305.635152)
		(width 0.16002)
		(layer "In11.Cu")
		(net "M_L_CPU0_SB_DQS_DP<7>")
	)
	(segment
		(start 444.262764 -305.635152)
		(end 445.116204 -304.781712)
		(width 0.16002)
		(layer "In11.Cu")
		(net "M_L_CPU0_SB_DQS_DP<7>")
	)
	(segment
		(start 415.511996 -304.781712)
		(end 415.890456 -305.160172)
		(width 0.16002)
		(layer "In11.Cu")
		(net "M_L_CPU0_SB_DQS_DP<7>")
	)
	(segment
		(start 443.64148 -305.635152)
		(end 444.262764 -305.635152)
		(width 0.16002)
		(layer "In11.Cu")
		(net "M_L_CPU0_SB_DQS_DP<7>")
	)
	(segment
		(start 403.26437 -299.350684)
		(end 403.74062 -299.350684)
		(width 0.16002)
		(layer "In11.Cu")
		(net "M_L_CPU0_SB_DQS_DP<7>")
	)
	(segment
		(start 422.484042 -304.781712)
		(end 423.05605 -304.781712)
		(width 0.16002)
		(layer "In11.Cu")
		(net "M_L_CPU0_SB_DQS_DP<7>")
	)
	(segment
		(start 435.722268 -306.01031)
		(end 436.097426 -305.635152)
		(width 0.16002)
		(layer "In11.Cu")
		(net "M_L_CPU0_SB_DQS_DP<7>")
	)
	(segment
		(start 400.829018 -296.915332)
		(end 401.890738 -297.977052)
		(width 0.16002)
		(layer "In11.Cu")
		(net "M_L_CPU0_SB_DQS_DP<7>")
	)
	(segment
		(start 447.37782 -305.160172)
		(end 447.526664 -305.011328)
		(width 0.16002)
		(layer "In11.Cu")
		(net "M_L_CPU0_SB_DQS_DP<7>")
	)
	(segment
		(start 407.040334 -302.492664)
		(end 406.961594 -302.571404)
		(width 0.16002)
		(layer "In11.Cu")
		(net "M_L_CPU0_SB_DQS_DP<7>")
	)
	(segment
		(start 425.757848 -305.160172)
		(end 426.607986 -306.01031)
		(width 0.16002)
		(layer "In11.Cu")
		(net "M_L_CPU0_SB_DQS_DP<7>")
	)
	(segment
		(start 420.63416 -306.01031)
		(end 421.009318 -305.635152)
		(width 0.16002)
		(layer "In11.Cu")
		(net "M_L_CPU0_SB_DQS_DP<7>")
	)
	(segment
		(start 403.81936 -299.272198)
		(end 404.045674 -299.272198)
		(width 0.16002)
		(layer "In11.Cu")
		(net "M_L_CPU0_SB_DQS_DP<7>")
	)
	(segment
		(start 430.028096 -304.781712)
		(end 430.600104 -304.781712)
		(width 0.16002)
		(layer "In11.Cu")
		(net "M_L_CPU0_SB_DQS_DP<7>")
	)
	(segment
		(start 430.600104 -304.781712)
		(end 430.978564 -305.160172)
		(width 0.16002)
		(layer "In11.Cu")
		(net "M_L_CPU0_SB_DQS_DP<7>")
	)
	(segment
		(start 386.985002 -286.715962)
		(end 386.993384 -286.720788)
		(width 0.09525)
		(layer "In11.Cu")
		(net "M_L_CPU0_SB_DQS_DP<7>")
	)
	(segment
		(start 405.192992 -300.64583)
		(end 405.419306 -300.64583)
		(width 0.16002)
		(layer "In11.Cu")
		(net "M_L_CPU0_SB_DQS_DP<7>")
	)
	(segment
		(start 395.09192 -287.182052)
		(end 395.504416 -287.595818)
		(width 0.09525)
		(layer "In11.Cu")
		(net "M_L_CPU0_SB_DQS_DP<7>")
	)
	(segment
		(start 405.587962 -301.197772)
		(end 405.587962 -301.674276)
		(width 0.16002)
		(layer "In11.Cu")
		(net "M_L_CPU0_SB_DQS_DP<7>")
	)
	(segment
		(start 392.256264 -286.720788)
		(end 392.260582 -286.718248)
		(width 0.09525)
		(layer "In11.Cu")
		(net "M_L_CPU0_SB_DQS_DP<7>")
	)
	(segment
		(start 405.419306 -300.64583)
		(end 405.666702 -300.893226)
		(width 0.16002)
		(layer "In11.Cu")
		(net "M_L_CPU0_SB_DQS_DP<7>")
	)
	(segment
		(start 437.57215 -304.781712)
		(end 438.144158 -304.781712)
		(width 0.16002)
		(layer "In11.Cu")
		(net "M_L_CPU0_SB_DQS_DP<7>")
	)
	(segment
		(start 392.260582 -286.718248)
		(end 392.264646 -286.715962)
		(width 0.09525)
		(layer "In11.Cu")
		(net "M_L_CPU0_SB_DQS_DP<7>")
	)
	(segment
		(start 405.587962 -301.674276)
		(end 406.011634 -302.097948)
		(width 0.16002)
		(layer "In11.Cu")
		(net "M_L_CPU0_SB_DQS_DP<7>")
	)
	(segment
		(start 394.518134 -287.182052)
		(end 395.09192 -287.182052)
		(width 0.09525)
		(layer "In11.Cu")
		(net "M_L_CPU0_SB_DQS_DP<7>")
	)
	(segment
		(start 438.144158 -304.781712)
		(end 438.522618 -305.160172)
		(width 0.16002)
		(layer "In11.Cu")
		(net "M_L_CPU0_SB_DQS_DP<7>")
	)
	(segment
		(start 405.114252 -300.724316)
		(end 405.192992 -300.64583)
		(width 0.16002)
		(layer "In11.Cu")
		(net "M_L_CPU0_SB_DQS_DP<7>")
	)
	(segment
		(start 429.174656 -305.635152)
		(end 430.028096 -304.781712)
		(width 0.16002)
		(layer "In11.Cu")
		(net "M_L_CPU0_SB_DQS_DP<7>")
	)
	(segment
		(start 414.086548 -305.635152)
		(end 414.939988 -304.781712)
		(width 0.16002)
		(layer "In11.Cu")
		(net "M_L_CPU0_SB_DQS_DP<7>")
	)
	(segment
		(start 406.961594 -302.571404)
		(end 406.961594 -303.047908)
		(width 0.16002)
		(layer "In11.Cu")
		(net "M_L_CPU0_SB_DQS_DP<7>")
	)
	(segment
		(start 385.864862 -287.045908)
		(end 386.018786 -286.780478)
		(width 0.09525)
		(layer "In11.Cu")
		(net "M_L_CPU0_SB_DQS_DP<7>")
	)
	(segment
		(start 402.672042 -297.898566)
		(end 402.919438 -298.145962)
		(width 0.16002)
		(layer "In11.Cu")
		(net "M_L_CPU0_SB_DQS_DP<7>")
	)
	(segment
		(start 395.520672 -287.695894)
		(end 400.829018 -293.004748)
		(width 0.16002)
		(layer "In11.Cu")
		(net "M_L_CPU0_SB_DQS_DP<7>")
	)
	(segment
		(start 404.29307 -299.519594)
		(end 404.29307 -299.7454)
		(width 0.16002)
		(layer "In11.Cu")
		(net "M_L_CPU0_SB_DQS_DP<7>")
	)
	(segment
		(start 388.496302 -286.720788)
		(end 388.504684 -286.715962)
		(width 0.09525)
		(layer "In11.Cu")
		(net "M_L_CPU0_SB_DQS_DP<7>")
	)
	(segment
		(start 436.71871 -305.635152)
		(end 437.57215 -304.781712)
		(width 0.16002)
		(layer "In11.Cu")
		(net "M_L_CPU0_SB_DQS_DP<7>")
	)
	(segment
		(start 447.526664 -305.011328)
		(end 449.814188 -305.011328)
		(width 0.16002)
		(layer "In11.Cu")
		(net "M_L_CPU0_SB_DQS_DP<7>")
	)
	(segment
		(start 395.503908 -287.67913)
		(end 395.520672 -287.695894)
		(width 0.09525)
		(layer "In11.Cu")
		(net "M_L_CPU0_SB_DQS_DP<7>")
	)
	(segment
		(start 406.566624 -302.019462)
		(end 406.792938 -302.019462)
		(width 0.16002)
		(layer "In11.Cu")
		(net "M_L_CPU0_SB_DQS_DP<7>")
	)
	(segment
		(start 428.553372 -305.635152)
		(end 429.174656 -305.635152)
		(width 0.16002)
		(layer "In11.Cu")
		(net "M_L_CPU0_SB_DQS_DP<7>")
	)
	(segment
		(start 409.548838 -305.635152)
		(end 414.086548 -305.635152)
		(width 0.16002)
		(layer "In11.Cu")
		(net "M_L_CPU0_SB_DQS_DP<7>")
	)
	(segment
		(start 433.301902 -305.160172)
		(end 434.15204 -306.01031)
		(width 0.16002)
		(layer "In11.Cu")
		(net "M_L_CPU0_SB_DQS_DP<7>")
	)
	(segment
		(start 393.964414 -286.628332)
		(end 394.518134 -287.182052)
		(width 0.09525)
		(layer "In11.Cu")
		(net "M_L_CPU0_SB_DQS_DP<7>")
	)
	(segment
		(start 423.43451 -305.160172)
		(end 425.757848 -305.160172)
		(width 0.16002)
		(layer "In11.Cu")
		(net "M_L_CPU0_SB_DQS_DP<7>")
	)
	(segment
		(start 404.21433 -300.300644)
		(end 404.638002 -300.724316)
		(width 0.16002)
		(layer "In11.Cu")
		(net "M_L_CPU0_SB_DQS_DP<7>")
	)
	(segment
		(start 402.445728 -297.898566)
		(end 402.672042 -297.898566)
		(width 0.16002)
		(layer "In11.Cu")
		(net "M_L_CPU0_SB_DQS_DP<7>")
	)
	(segment
		(start 407.040334 -302.266858)
		(end 407.040334 -302.492664)
		(width 0.16002)
		(layer "In11.Cu")
		(net "M_L_CPU0_SB_DQS_DP<7>")
	)
	(segment
		(start 402.919438 -298.371768)
		(end 402.840698 -298.450508)
		(width 0.16002)
		(layer "In11.Cu")
		(net "M_L_CPU0_SB_DQS_DP<7>")
	)
	(segment
		(start 404.29307 -299.7454)
		(end 404.21433 -299.82414)
		(width 0.16002)
		(layer "In11.Cu")
		(net "M_L_CPU0_SB_DQS_DP<7>")
	)
	(segment
		(start 403.74062 -299.350684)
		(end 403.81936 -299.272198)
		(width 0.16002)
		(layer "In11.Cu")
		(net "M_L_CPU0_SB_DQS_DP<7>")
	)
	(segment
		(start 404.045674 -299.272198)
		(end 404.29307 -299.519594)
		(width 0.16002)
		(layer "In11.Cu")
		(net "M_L_CPU0_SB_DQS_DP<7>")
	)
	(segment
		(start 421.009318 -305.635152)
		(end 421.630602 -305.635152)
		(width 0.16002)
		(layer "In11.Cu")
		(net "M_L_CPU0_SB_DQS_DP<7>")
	)
	(segment
		(start 402.840698 -298.450508)
		(end 402.840698 -298.927012)
		(width 0.16002)
		(layer "In11.Cu")
		(net "M_L_CPU0_SB_DQS_DP<7>")
	)
	(segment
		(start 391.31621 -286.720788)
		(end 391.324592 -286.715962)
		(width 0.09525)
		(layer "In11.Cu")
		(net "M_L_CPU0_SB_DQS_DP<7>")
	)
	(segment
		(start 404.638002 -300.724316)
		(end 405.114252 -300.724316)
		(width 0.16002)
		(layer "In11.Cu")
		(net "M_L_CPU0_SB_DQS_DP<7>")
	)
	(segment
		(start 421.630602 -305.635152)
		(end 422.484042 -304.781712)
		(width 0.16002)
		(layer "In11.Cu")
		(net "M_L_CPU0_SB_DQS_DP<7>")
	)
	(segment
		(start 443.266322 -306.01031)
		(end 443.64148 -305.635152)
		(width 0.16002)
		(layer "In11.Cu")
		(net "M_L_CPU0_SB_DQS_DP<7>")
	)
	(segment
		(start 419.182296 -306.01031)
		(end 420.63416 -306.01031)
		(width 0.16002)
		(layer "In11.Cu")
		(net "M_L_CPU0_SB_DQS_DP<7>")
	)
	(segment
		(start 434.15204 -306.01031)
		(end 435.722268 -306.01031)
		(width 0.16002)
		(layer "In11.Cu")
		(net "M_L_CPU0_SB_DQS_DP<7>")
	)
	(segment
		(start 401.890738 -297.977052)
		(end 402.366988 -297.977052)
		(width 0.16002)
		(layer "In11.Cu")
		(net "M_L_CPU0_SB_DQS_DP<7>")
	)
	(segment
		(start 404.21433 -299.82414)
		(end 404.21433 -300.300644)
		(width 0.16002)
		(layer "In11.Cu")
		(net "M_L_CPU0_SB_DQS_DP<7>")
	)
	(segment
		(start 390.744964 -286.715962)
		(end 390.753346 -286.720788)
		(width 0.09525)
		(layer "In11.Cu")
		(net "M_L_CPU0_SB_DQS_DP<7>")
	)
	(segment
		(start 446.066672 -305.160172)
		(end 447.37782 -305.160172)
		(width 0.16002)
		(layer "In11.Cu")
		(net "M_L_CPU0_SB_DQS_DP<7>")
	)
	(segment
		(start 449.814188 -305.011328)
		(end 450.088 -305.28514)
		(width 0.16002)
		(layer "In11.Cu")
		(net "M_L_CPU0_SB_DQS_DP<7>")
	)
	(segment
		(start 436.097426 -305.635152)
		(end 436.71871 -305.635152)
		(width 0.16002)
		(layer "In11.Cu")
		(net "M_L_CPU0_SB_DQS_DP<7>")
	)
	(segment
		(start 423.05605 -304.781712)
		(end 423.43451 -305.160172)
		(width 0.16002)
		(layer "In11.Cu")
		(net "M_L_CPU0_SB_DQS_DP<7>")
	)
	(segment
		(start 414.939988 -304.781712)
		(end 415.511996 -304.781712)
		(width 0.16002)
		(layer "In11.Cu")
		(net "M_L_CPU0_SB_DQS_DP<7>")
	)
	(segment
		(start 386.018786 -286.780478)
		(end 386.119624 -286.753808)
		(width 0.09525)
		(layer "In11.Cu")
		(net "M_L_CPU0_SB_DQS_DP<7>")
	)
	(segment
		(start 400.829018 -293.004748)
		(end 400.829018 -296.915332)
		(width 0.16002)
		(layer "In11.Cu")
		(net "M_L_CPU0_SB_DQS_DP<7>")
	)
	(segment
		(start 402.840698 -298.927012)
		(end 403.26437 -299.350684)
		(width 0.16002)
		(layer "In11.Cu")
		(net "M_L_CPU0_SB_DQS_DP<7>")
	)
	(segment
		(start 430.978564 -305.160172)
		(end 433.301902 -305.160172)
		(width 0.16002)
		(layer "In11.Cu")
		(net "M_L_CPU0_SB_DQS_DP<7>")
	)
	(segment
		(start 418.332158 -305.160172)
		(end 419.182296 -306.01031)
		(width 0.16002)
		(layer "In11.Cu")
		(net "M_L_CPU0_SB_DQS_DP<7>")
	)
	(segment
		(start 406.011634 -302.097948)
		(end 406.487884 -302.097948)
		(width 0.16002)
		(layer "In11.Cu")
		(net "M_L_CPU0_SB_DQS_DP<7>")
	)
	(segment
		(start 406.792938 -302.019462)
		(end 407.040334 -302.266858)
		(width 0.16002)
		(layer "In11.Cu")
		(net "M_L_CPU0_SB_DQS_DP<7>")
	)
	(segment
		(start 402.366988 -297.977052)
		(end 402.445728 -297.898566)
		(width 0.16002)
		(layer "In11.Cu")
		(net "M_L_CPU0_SB_DQS_DP<7>")
	)
	(segment
		(start 445.116204 -304.781712)
		(end 445.688212 -304.781712)
		(width 0.16002)
		(layer "In11.Cu")
		(net "M_L_CPU0_SB_DQS_DP<7>")
	)
	(segment
		(start 440.845956 -305.160172)
		(end 441.696094 -306.01031)
		(width 0.16002)
		(layer "In11.Cu")
		(net "M_L_CPU0_SB_DQS_DP<7>")
	)
	(arc
		(start 386.119624 -286.753808)
		(mid 386.129745 -286.75797)
		(end 386.139944 -286.761936)
		(width 0.09525)
		(layer "In11.Cu")
		(net "M_L_CPU0_SB_DQS_DP<7>")
	)
	(arc
		(start 391.6934 -286.720788)
		(mid 391.974832 -286.796577)
		(end 392.256264 -286.720788)
		(width 0.09525)
		(layer "In11.Cu")
		(net "M_L_CPU0_SB_DQS_DP<7>")
	)
	(arc
		(start 392.264646 -286.715962)
		(mid 392.430845 -286.65057)
		(end 392.608054 -286.628332)
		(width 0.09525)
		(layer "In11.Cu")
		(net "M_L_CPU0_SB_DQS_DP<7>")
	)
	(arc
		(start 390.753346 -286.720788)
		(mid 391.034778 -286.796577)
		(end 391.31621 -286.720788)
		(width 0.09525)
		(layer "In11.Cu")
		(net "M_L_CPU0_SB_DQS_DP<7>")
	)
	(arc
		(start 389.813292 -286.720788)
		(mid 390.094724 -286.796577)
		(end 390.376156 -286.720788)
		(width 0.09525)
		(layer "In11.Cu")
		(net "M_L_CPU0_SB_DQS_DP<7>")
	)
	(arc
		(start 387.933438 -286.720788)
		(mid 388.21487 -286.796577)
		(end 388.496302 -286.720788)
		(width 0.09525)
		(layer "In11.Cu")
		(net "M_L_CPU0_SB_DQS_DP<7>")
	)
	(arc
		(start 389.436356 -286.720788)
		(mid 389.624824 -286.670111)
		(end 389.813292 -286.720788)
		(width 0.09525)
		(layer "In11.Cu")
		(net "M_L_CPU0_SB_DQS_DP<7>")
	)
	(arc
		(start 386.616194 -286.720788)
		(mid 386.799969 -286.670016)
		(end 386.985002 -286.715962)
		(width 0.09525)
		(layer "In11.Cu")
		(net "M_L_CPU0_SB_DQS_DP<7>")
	)
	(arc
		(start 391.324592 -286.715962)
		(mid 391.509624 -286.670048)
		(end 391.6934 -286.720788)
		(width 0.09525)
		(layer "In11.Cu")
		(net "M_L_CPU0_SB_DQS_DP<7>")
	)
	(arc
		(start 386.139944 -286.761936)
		(mid 386.382686 -286.794721)
		(end 386.616194 -286.720788)
		(width 0.09525)
		(layer "In11.Cu")
		(net "M_L_CPU0_SB_DQS_DP<7>")
	)
	(arc
		(start 390.376156 -286.720788)
		(mid 390.559931 -286.670016)
		(end 390.744964 -286.715962)
		(width 0.09525)
		(layer "In11.Cu")
		(net "M_L_CPU0_SB_DQS_DP<7>")
	)
	(arc
		(start 386.993384 -286.720788)
		(mid 387.274816 -286.796577)
		(end 387.556248 -286.720788)
		(width 0.09525)
		(layer "In11.Cu")
		(net "M_L_CPU0_SB_DQS_DP<7>")
	)
	(arc
		(start 387.56463 -286.715962)
		(mid 387.749662 -286.670048)
		(end 387.933438 -286.720788)
		(width 0.09525)
		(layer "In11.Cu")
		(net "M_L_CPU0_SB_DQS_DP<7>")
	)
	(arc
		(start 388.873492 -286.720788)
		(mid 389.154924 -286.796577)
		(end 389.436356 -286.720788)
		(width 0.09525)
		(layer "In11.Cu")
		(net "M_L_CPU0_SB_DQS_DP<7>")
	)
	(arc
		(start 388.504684 -286.715962)
		(mid 388.689716 -286.670048)
		(end 388.873492 -286.720788)
		(width 0.09525)
		(layer "In11.Cu")
		(net "M_L_CPU0_SB_DQS_DP<7>")
	)
	(segment
		(start 385.39801 -281.920188)
		(end 385.864862 -282.186126)
		(width 0.12954)
		(layer "F.Cu")
		(net "M_L_CPU0_SB_DQS_DP<6>")
	)
	(segment
		(start 434.15204 -296.660316)
		(end 435.722268 -296.660316)
		(width 0.16002)
		(layer "In11.Cu")
		(net "M_L_CPU0_SB_DQS_DP<6>")
	)
	(segment
		(start 395.835632 -282.12034)
		(end 395.859254 -282.12034)
		(width 0.09525)
		(layer "In11.Cu")
		(net "M_L_CPU0_SB_DQS_DP<6>")
	)
	(segment
		(start 446.066672 -295.810178)
		(end 447.37782 -295.810178)
		(width 0.16002)
		(layer "In11.Cu")
		(net "M_L_CPU0_SB_DQS_DP<6>")
	)
	(segment
		(start 397.890746 -282.12034)
		(end 406.447498 -290.677092)
		(width 0.16002)
		(layer "In11.Cu")
		(net "M_L_CPU0_SB_DQS_DP<6>")
	)
	(segment
		(start 433.301902 -295.810178)
		(end 434.15204 -296.660316)
		(width 0.16002)
		(layer "In11.Cu")
		(net "M_L_CPU0_SB_DQS_DP<6>")
	)
	(segment
		(start 387.556248 -281.861006)
		(end 387.56463 -281.85618)
		(width 0.09525)
		(layer "In11.Cu")
		(net "M_L_CPU0_SB_DQS_DP<6>")
	)
	(segment
		(start 421.009318 -296.285158)
		(end 421.630602 -296.285158)
		(width 0.16002)
		(layer "In11.Cu")
		(net "M_L_CPU0_SB_DQS_DP<6>")
	)
	(segment
		(start 393.96416 -281.809698)
		(end 394.215874 -282.061412)
		(width 0.09525)
		(layer "In11.Cu")
		(net "M_L_CPU0_SB_DQS_DP<6>")
	)
	(segment
		(start 437.57215 -295.431718)
		(end 438.144158 -295.431718)
		(width 0.16002)
		(layer "In11.Cu")
		(net "M_L_CPU0_SB_DQS_DP<6>")
	)
	(segment
		(start 408.7495 -293.038784)
		(end 408.7495 -293.26459)
		(width 0.16002)
		(layer "In11.Cu")
		(net "M_L_CPU0_SB_DQS_DP<6>")
	)
	(segment
		(start 421.630602 -296.285158)
		(end 422.484042 -295.431718)
		(width 0.16002)
		(layer "In11.Cu")
		(net "M_L_CPU0_SB_DQS_DP<6>")
	)
	(segment
		(start 408.502104 -292.791388)
		(end 408.7495 -293.038784)
		(width 0.16002)
		(layer "In11.Cu")
		(net "M_L_CPU0_SB_DQS_DP<6>")
	)
	(segment
		(start 388.496302 -281.861006)
		(end 388.504684 -281.85618)
		(width 0.09525)
		(layer "In11.Cu")
		(net "M_L_CPU0_SB_DQS_DP<6>")
	)
	(segment
		(start 440.845956 -295.810178)
		(end 441.696094 -296.660316)
		(width 0.16002)
		(layer "In11.Cu")
		(net "M_L_CPU0_SB_DQS_DP<6>")
	)
	(segment
		(start 443.266322 -296.660316)
		(end 443.64148 -296.285158)
		(width 0.16002)
		(layer "In11.Cu")
		(net "M_L_CPU0_SB_DQS_DP<6>")
	)
	(segment
		(start 445.688212 -295.431718)
		(end 446.066672 -295.810178)
		(width 0.16002)
		(layer "In11.Cu")
		(net "M_L_CPU0_SB_DQS_DP<6>")
	)
	(segment
		(start 390.744964 -281.85618)
		(end 390.753346 -281.861006)
		(width 0.09525)
		(layer "In11.Cu")
		(net "M_L_CPU0_SB_DQS_DP<6>")
	)
	(segment
		(start 444.262764 -296.285158)
		(end 445.116204 -295.431718)
		(width 0.16002)
		(layer "In11.Cu")
		(net "M_L_CPU0_SB_DQS_DP<6>")
	)
	(segment
		(start 436.71871 -296.285158)
		(end 437.57215 -295.431718)
		(width 0.16002)
		(layer "In11.Cu")
		(net "M_L_CPU0_SB_DQS_DP<6>")
	)
	(segment
		(start 447.37782 -295.810178)
		(end 447.526664 -295.661334)
		(width 0.16002)
		(layer "In11.Cu")
		(net "M_L_CPU0_SB_DQS_DP<6>")
	)
	(segment
		(start 386.985002 -281.85618)
		(end 386.993384 -281.861006)
		(width 0.09525)
		(layer "In11.Cu")
		(net "M_L_CPU0_SB_DQS_DP<6>")
	)
	(segment
		(start 409.649676 -294.16502)
		(end 409.875736 -294.16502)
		(width 0.16002)
		(layer "In11.Cu")
		(net "M_L_CPU0_SB_DQS_DP<6>")
	)
	(segment
		(start 428.178214 -296.660316)
		(end 428.553372 -296.285158)
		(width 0.16002)
		(layer "In11.Cu")
		(net "M_L_CPU0_SB_DQS_DP<6>")
	)
	(segment
		(start 435.722268 -296.660316)
		(end 436.097426 -296.285158)
		(width 0.16002)
		(layer "In11.Cu")
		(net "M_L_CPU0_SB_DQS_DP<6>")
	)
	(segment
		(start 409.875736 -294.16502)
		(end 410.123132 -294.412416)
		(width 0.16002)
		(layer "In11.Cu")
		(net "M_L_CPU0_SB_DQS_DP<6>")
	)
	(segment
		(start 418.787072 -296.120312)
		(end 419.327076 -296.660316)
		(width 0.16002)
		(layer "In11.Cu")
		(net "M_L_CPU0_SB_DQS_DP<6>")
	)
	(segment
		(start 409.772612 -295.465246)
		(end 410.592524 -296.285158)
		(width 0.16002)
		(layer "In11.Cu")
		(net "M_L_CPU0_SB_DQS_DP<6>")
	)
	(segment
		(start 443.64148 -296.285158)
		(end 444.262764 -296.285158)
		(width 0.16002)
		(layer "In11.Cu")
		(net "M_L_CPU0_SB_DQS_DP<6>")
	)
	(segment
		(start 422.484042 -295.431718)
		(end 423.05605 -295.431718)
		(width 0.16002)
		(layer "In11.Cu")
		(net "M_L_CPU0_SB_DQS_DP<6>")
	)
	(segment
		(start 425.757848 -295.810178)
		(end 426.607986 -296.660316)
		(width 0.16002)
		(layer "In11.Cu")
		(net "M_L_CPU0_SB_DQS_DP<6>")
	)
	(segment
		(start 429.174656 -296.285158)
		(end 430.028096 -295.431718)
		(width 0.16002)
		(layer "In11.Cu")
		(net "M_L_CPU0_SB_DQS_DP<6>")
	)
	(segment
		(start 414.086548 -296.285158)
		(end 414.939988 -295.431718)
		(width 0.16002)
		(layer "In11.Cu")
		(net "M_L_CPU0_SB_DQS_DP<6>")
	)
	(segment
		(start 406.447498 -290.677092)
		(end 406.447498 -292.140132)
		(width 0.16002)
		(layer "In11.Cu")
		(net "M_L_CPU0_SB_DQS_DP<6>")
	)
	(segment
		(start 408.39898 -294.091614)
		(end 408.822652 -294.515286)
		(width 0.16002)
		(layer "In11.Cu")
		(net "M_L_CPU0_SB_DQS_DP<6>")
	)
	(segment
		(start 430.600104 -295.431718)
		(end 430.978564 -295.810178)
		(width 0.16002)
		(layer "In11.Cu")
		(net "M_L_CPU0_SB_DQS_DP<6>")
	)
	(segment
		(start 409.772612 -294.988488)
		(end 409.772612 -295.465246)
		(width 0.16002)
		(layer "In11.Cu")
		(net "M_L_CPU0_SB_DQS_DP<6>")
	)
	(segment
		(start 408.7495 -293.26459)
		(end 408.39898 -293.614856)
		(width 0.16002)
		(layer "In11.Cu")
		(net "M_L_CPU0_SB_DQS_DP<6>")
	)
	(segment
		(start 394.215874 -282.061412)
		(end 395.776704 -282.061412)
		(width 0.09525)
		(layer "In11.Cu")
		(net "M_L_CPU0_SB_DQS_DP<6>")
	)
	(segment
		(start 385.864862 -282.186126)
		(end 386.018786 -281.920696)
		(width 0.09525)
		(layer "In11.Cu")
		(net "M_L_CPU0_SB_DQS_DP<6>")
	)
	(segment
		(start 447.526664 -295.661334)
		(end 449.814188 -295.661334)
		(width 0.16002)
		(layer "In11.Cu")
		(net "M_L_CPU0_SB_DQS_DP<6>")
	)
	(segment
		(start 423.43451 -295.810178)
		(end 425.757848 -295.810178)
		(width 0.16002)
		(layer "In11.Cu")
		(net "M_L_CPU0_SB_DQS_DP<6>")
	)
	(segment
		(start 438.144158 -295.431718)
		(end 438.522618 -295.810178)
		(width 0.16002)
		(layer "In11.Cu")
		(net "M_L_CPU0_SB_DQS_DP<6>")
	)
	(segment
		(start 426.607986 -296.660316)
		(end 428.178214 -296.660316)
		(width 0.16002)
		(layer "In11.Cu")
		(net "M_L_CPU0_SB_DQS_DP<6>")
	)
	(segment
		(start 420.63416 -296.660316)
		(end 421.009318 -296.285158)
		(width 0.16002)
		(layer "In11.Cu")
		(net "M_L_CPU0_SB_DQS_DP<6>")
	)
	(segment
		(start 408.39898 -293.614856)
		(end 408.39898 -294.091614)
		(width 0.16002)
		(layer "In11.Cu")
		(net "M_L_CPU0_SB_DQS_DP<6>")
	)
	(segment
		(start 423.05605 -295.431718)
		(end 423.43451 -295.810178)
		(width 0.16002)
		(layer "In11.Cu")
		(net "M_L_CPU0_SB_DQS_DP<6>")
	)
	(segment
		(start 410.123132 -294.638222)
		(end 409.772612 -294.988488)
		(width 0.16002)
		(layer "In11.Cu")
		(net "M_L_CPU0_SB_DQS_DP<6>")
	)
	(segment
		(start 438.522618 -295.810178)
		(end 440.845956 -295.810178)
		(width 0.16002)
		(layer "In11.Cu")
		(net "M_L_CPU0_SB_DQS_DP<6>")
	)
	(segment
		(start 407.44902 -293.141654)
		(end 407.925524 -293.141654)
		(width 0.16002)
		(layer "In11.Cu")
		(net "M_L_CPU0_SB_DQS_DP<6>")
	)
	(segment
		(start 386.018786 -281.920696)
		(end 386.119624 -281.894026)
		(width 0.09525)
		(layer "In11.Cu")
		(net "M_L_CPU0_SB_DQS_DP<6>")
	)
	(segment
		(start 430.978564 -295.810178)
		(end 433.301902 -295.810178)
		(width 0.16002)
		(layer "In11.Cu")
		(net "M_L_CPU0_SB_DQS_DP<6>")
	)
	(segment
		(start 395.776704 -282.061412)
		(end 395.835632 -282.12034)
		(width 0.09525)
		(layer "In11.Cu")
		(net "M_L_CPU0_SB_DQS_DP<6>")
	)
	(segment
		(start 416.20059 -296.120312)
		(end 418.787072 -296.120312)
		(width 0.16002)
		(layer "In11.Cu")
		(net "M_L_CPU0_SB_DQS_DP<6>")
	)
	(segment
		(start 409.299156 -294.515286)
		(end 409.649676 -294.16502)
		(width 0.16002)
		(layer "In11.Cu")
		(net "M_L_CPU0_SB_DQS_DP<6>")
	)
	(segment
		(start 436.097426 -296.285158)
		(end 436.71871 -296.285158)
		(width 0.16002)
		(layer "In11.Cu")
		(net "M_L_CPU0_SB_DQS_DP<6>")
	)
	(segment
		(start 391.31621 -281.861006)
		(end 391.324592 -281.85618)
		(width 0.09525)
		(layer "In11.Cu")
		(net "M_L_CPU0_SB_DQS_DP<6>")
	)
	(segment
		(start 428.553372 -296.285158)
		(end 429.174656 -296.285158)
		(width 0.16002)
		(layer "In11.Cu")
		(net "M_L_CPU0_SB_DQS_DP<6>")
	)
	(segment
		(start 430.028096 -295.431718)
		(end 430.600104 -295.431718)
		(width 0.16002)
		(layer "In11.Cu")
		(net "M_L_CPU0_SB_DQS_DP<6>")
	)
	(segment
		(start 419.327076 -296.660316)
		(end 420.63416 -296.660316)
		(width 0.16002)
		(layer "In11.Cu")
		(net "M_L_CPU0_SB_DQS_DP<6>")
	)
	(segment
		(start 415.511996 -295.431718)
		(end 416.20059 -296.120312)
		(width 0.16002)
		(layer "In11.Cu")
		(net "M_L_CPU0_SB_DQS_DP<6>")
	)
	(segment
		(start 410.123132 -294.412416)
		(end 410.123132 -294.638222)
		(width 0.16002)
		(layer "In11.Cu")
		(net "M_L_CPU0_SB_DQS_DP<6>")
	)
	(segment
		(start 408.822652 -294.515286)
		(end 409.299156 -294.515286)
		(width 0.16002)
		(layer "In11.Cu")
		(net "M_L_CPU0_SB_DQS_DP<6>")
	)
	(segment
		(start 441.696094 -296.660316)
		(end 443.266322 -296.660316)
		(width 0.16002)
		(layer "In11.Cu")
		(net "M_L_CPU0_SB_DQS_DP<6>")
	)
	(segment
		(start 392.444732 -281.809698)
		(end 393.96416 -281.809698)
		(width 0.09525)
		(layer "In11.Cu")
		(net "M_L_CPU0_SB_DQS_DP<6>")
	)
	(segment
		(start 445.116204 -295.431718)
		(end 445.688212 -295.431718)
		(width 0.16002)
		(layer "In11.Cu")
		(net "M_L_CPU0_SB_DQS_DP<6>")
	)
	(segment
		(start 410.592524 -296.285158)
		(end 414.086548 -296.285158)
		(width 0.16002)
		(layer "In11.Cu")
		(net "M_L_CPU0_SB_DQS_DP<6>")
	)
	(segment
		(start 395.859254 -282.12034)
		(end 397.890746 -282.12034)
		(width 0.16002)
		(layer "In11.Cu")
		(net "M_L_CPU0_SB_DQS_DP<6>")
	)
	(segment
		(start 407.925524 -293.141654)
		(end 408.276044 -292.791388)
		(width 0.16002)
		(layer "In11.Cu")
		(net "M_L_CPU0_SB_DQS_DP<6>")
	)
	(segment
		(start 406.447498 -292.140132)
		(end 407.44902 -293.141654)
		(width 0.16002)
		(layer "In11.Cu")
		(net "M_L_CPU0_SB_DQS_DP<6>")
	)
	(segment
		(start 449.814188 -295.661334)
		(end 450.088 -295.935146)
		(width 0.16002)
		(layer "In11.Cu")
		(net "M_L_CPU0_SB_DQS_DP<6>")
	)
	(segment
		(start 408.276044 -292.791388)
		(end 408.502104 -292.791388)
		(width 0.16002)
		(layer "In11.Cu")
		(net "M_L_CPU0_SB_DQS_DP<6>")
	)
	(segment
		(start 414.939988 -295.431718)
		(end 415.511996 -295.431718)
		(width 0.16002)
		(layer "In11.Cu")
		(net "M_L_CPU0_SB_DQS_DP<6>")
	)
	(arc
		(start 389.813292 -281.861006)
		(mid 390.094724 -281.936761)
		(end 390.376156 -281.861006)
		(width 0.09525)
		(layer "In11.Cu")
		(net "M_L_CPU0_SB_DQS_DP<6>")
	)
	(arc
		(start 388.504684 -281.85618)
		(mid 388.689716 -281.810266)
		(end 388.873492 -281.861006)
		(width 0.09525)
		(layer "In11.Cu")
		(net "M_L_CPU0_SB_DQS_DP<6>")
	)
	(arc
		(start 386.993384 -281.861006)
		(mid 387.274816 -281.936761)
		(end 387.556248 -281.861006)
		(width 0.09525)
		(layer "In11.Cu")
		(net "M_L_CPU0_SB_DQS_DP<6>")
	)
	(arc
		(start 389.436356 -281.861006)
		(mid 389.624824 -281.810329)
		(end 389.813292 -281.861006)
		(width 0.09525)
		(layer "In11.Cu")
		(net "M_L_CPU0_SB_DQS_DP<6>")
	)
	(arc
		(start 390.376156 -281.861006)
		(mid 390.559931 -281.810234)
		(end 390.744964 -281.85618)
		(width 0.09525)
		(layer "In11.Cu")
		(net "M_L_CPU0_SB_DQS_DP<6>")
	)
	(arc
		(start 386.119624 -281.894026)
		(mid 386.129746 -281.898061)
		(end 386.139944 -281.9019)
		(width 0.09525)
		(layer "In11.Cu")
		(net "M_L_CPU0_SB_DQS_DP<6>")
	)
	(arc
		(start 392.256264 -281.861006)
		(mid 392.347112 -281.822912)
		(end 392.444732 -281.809698)
		(width 0.09525)
		(layer "In11.Cu")
		(net "M_L_CPU0_SB_DQS_DP<6>")
	)
	(arc
		(start 387.933438 -281.861006)
		(mid 388.21487 -281.936761)
		(end 388.496302 -281.861006)
		(width 0.09525)
		(layer "In11.Cu")
		(net "M_L_CPU0_SB_DQS_DP<6>")
	)
	(arc
		(start 386.139944 -281.9019)
		(mid 386.382656 -281.934783)
		(end 386.616194 -281.861006)
		(width 0.09525)
		(layer "In11.Cu")
		(net "M_L_CPU0_SB_DQS_DP<6>")
	)
	(arc
		(start 388.873492 -281.861006)
		(mid 389.154924 -281.936761)
		(end 389.436356 -281.861006)
		(width 0.09525)
		(layer "In11.Cu")
		(net "M_L_CPU0_SB_DQS_DP<6>")
	)
	(arc
		(start 386.616194 -281.861006)
		(mid 386.799969 -281.810234)
		(end 386.985002 -281.85618)
		(width 0.09525)
		(layer "In11.Cu")
		(net "M_L_CPU0_SB_DQS_DP<6>")
	)
	(arc
		(start 391.324592 -281.85618)
		(mid 391.509624 -281.810266)
		(end 391.6934 -281.861006)
		(width 0.09525)
		(layer "In11.Cu")
		(net "M_L_CPU0_SB_DQS_DP<6>")
	)
	(arc
		(start 390.753346 -281.861006)
		(mid 391.034778 -281.936761)
		(end 391.31621 -281.861006)
		(width 0.09525)
		(layer "In11.Cu")
		(net "M_L_CPU0_SB_DQS_DP<6>")
	)
	(arc
		(start 391.6934 -281.861006)
		(mid 391.974832 -281.936761)
		(end 392.256264 -281.861006)
		(width 0.09525)
		(layer "In11.Cu")
		(net "M_L_CPU0_SB_DQS_DP<6>")
	)
	(arc
		(start 387.56463 -281.85618)
		(mid 387.749662 -281.810266)
		(end 387.933438 -281.861006)
		(width 0.09525)
		(layer "In11.Cu")
		(net "M_L_CPU0_SB_DQS_DP<6>")
	)
	(segment
		(start 385.39801 -277.060152)
		(end 385.864862 -277.32609)
		(width 0.12954)
		(layer "F.Cu")
		(net "M_L_CPU0_SB_DQS_DP<5>")
	)
	(segment
		(start 417.690808 -286.460184)
		(end 418.44849 -286.460184)
		(width 0.16002)
		(layer "In11.Cu")
		(net "M_L_CPU0_SB_DQS_DP<5>")
	)
	(segment
		(start 391.6934 -277.00097)
		(end 391.703814 -277.007066)
		(width 0.09525)
		(layer "In11.Cu")
		(net "M_L_CPU0_SB_DQS_DP<5>")
	)
	(segment
		(start 412.615634 -286.160972)
		(end 412.615634 -286.598106)
		(width 0.16002)
		(layer "In11.Cu")
		(net "M_L_CPU0_SB_DQS_DP<5>")
	)
	(segment
		(start 412.10738 -286.000952)
		(end 412.455614 -286.000952)
		(width 0.16002)
		(layer "In11.Cu")
		(net "M_L_CPU0_SB_DQS_DP<5>")
	)
	(segment
		(start 415.987738 -285.485332)
		(end 416.335972 -285.485332)
		(width 0.16002)
		(layer "In11.Cu")
		(net "M_L_CPU0_SB_DQS_DP<5>")
	)
	(segment
		(start 411.94736 -286.598106)
		(end 411.94736 -286.160972)
		(width 0.16002)
		(layer "In11.Cu")
		(net "M_L_CPU0_SB_DQS_DP<5>")
	)
	(segment
		(start 411.112462 -286.935164)
		(end 411.610302 -286.935164)
		(width 0.16002)
		(layer "In11.Cu")
		(net "M_L_CPU0_SB_DQS_DP<5>")
	)
	(segment
		(start 443.64148 -286.935164)
		(end 444.262764 -286.935164)
		(width 0.16002)
		(layer "In11.Cu")
		(net "M_L_CPU0_SB_DQS_DP<5>")
	)
	(segment
		(start 411.94736 -286.160972)
		(end 412.10738 -286.000952)
		(width 0.16002)
		(layer "In11.Cu")
		(net "M_L_CPU0_SB_DQS_DP<5>")
	)
	(segment
		(start 385.864862 -277.32609)
		(end 386.018786 -277.06066)
		(width 0.09525)
		(layer "In11.Cu")
		(net "M_L_CPU0_SB_DQS_DP<5>")
	)
	(segment
		(start 422.484042 -286.081724)
		(end 423.05605 -286.081724)
		(width 0.16002)
		(layer "In11.Cu")
		(net "M_L_CPU0_SB_DQS_DP<5>")
	)
	(segment
		(start 438.144158 -286.081724)
		(end 438.522618 -286.460184)
		(width 0.16002)
		(layer "In11.Cu")
		(net "M_L_CPU0_SB_DQS_DP<5>")
	)
	(segment
		(start 386.018786 -277.06066)
		(end 386.119624 -277.03399)
		(width 0.09525)
		(layer "In11.Cu")
		(net "M_L_CPU0_SB_DQS_DP<5>")
	)
	(segment
		(start 393.780772 -276.949662)
		(end 394.948156 -275.782278)
		(width 0.09525)
		(layer "In11.Cu")
		(net "M_L_CPU0_SB_DQS_DP<5>")
	)
	(segment
		(start 416.495992 -285.798514)
		(end 416.83305 -286.135572)
		(width 0.16002)
		(layer "In11.Cu")
		(net "M_L_CPU0_SB_DQS_DP<5>")
	)
	(segment
		(start 445.116204 -286.081724)
		(end 445.688212 -286.081724)
		(width 0.16002)
		(layer "In11.Cu")
		(net "M_L_CPU0_SB_DQS_DP<5>")
	)
	(segment
		(start 393.38504 -276.949662)
		(end 393.780772 -276.949662)
		(width 0.09525)
		(layer "In11.Cu")
		(net "M_L_CPU0_SB_DQS_DP<5>")
	)
	(segment
		(start 433.301902 -286.460184)
		(end 434.15204 -287.310322)
		(width 0.16002)
		(layer "In11.Cu")
		(net "M_L_CPU0_SB_DQS_DP<5>")
	)
	(segment
		(start 412.615634 -286.598106)
		(end 412.952692 -286.935164)
		(width 0.16002)
		(layer "In11.Cu")
		(net "M_L_CPU0_SB_DQS_DP<5>")
	)
	(segment
		(start 391.31621 -277.00097)
		(end 391.324592 -276.996144)
		(width 0.09525)
		(layer "In11.Cu")
		(net "M_L_CPU0_SB_DQS_DP<5>")
	)
	(segment
		(start 395.083284 -275.782278)
		(end 395.360144 -276.059138)
		(width 0.09525)
		(layer "In11.Cu")
		(net "M_L_CPU0_SB_DQS_DP<5>")
	)
	(segment
		(start 438.522618 -286.460184)
		(end 440.845956 -286.460184)
		(width 0.16002)
		(layer "In11.Cu")
		(net "M_L_CPU0_SB_DQS_DP<5>")
	)
	(segment
		(start 395.859254 -276.118066)
		(end 400.295364 -276.118066)
		(width 0.16002)
		(layer "In11.Cu")
		(net "M_L_CPU0_SB_DQS_DP<5>")
	)
	(segment
		(start 415.827718 -285.645352)
		(end 415.987738 -285.485332)
		(width 0.16002)
		(layer "In11.Cu")
		(net "M_L_CPU0_SB_DQS_DP<5>")
	)
	(segment
		(start 421.009318 -286.935164)
		(end 421.630602 -286.935164)
		(width 0.16002)
		(layer "In11.Cu")
		(net "M_L_CPU0_SB_DQS_DP<5>")
	)
	(segment
		(start 415.49066 -286.135572)
		(end 415.827718 -285.798514)
		(width 0.16002)
		(layer "In11.Cu")
		(net "M_L_CPU0_SB_DQS_DP<5>")
	)
	(segment
		(start 436.71871 -286.935164)
		(end 437.57215 -286.081724)
		(width 0.16002)
		(layer "In11.Cu")
		(net "M_L_CPU0_SB_DQS_DP<5>")
	)
	(segment
		(start 418.44849 -286.460184)
		(end 419.298628 -287.310322)
		(width 0.16002)
		(layer "In11.Cu")
		(net "M_L_CPU0_SB_DQS_DP<5>")
	)
	(segment
		(start 440.845956 -286.460184)
		(end 441.696094 -287.310322)
		(width 0.16002)
		(layer "In11.Cu")
		(net "M_L_CPU0_SB_DQS_DP<5>")
	)
	(segment
		(start 434.15204 -287.310322)
		(end 435.722268 -287.310322)
		(width 0.16002)
		(layer "In11.Cu")
		(net "M_L_CPU0_SB_DQS_DP<5>")
	)
	(segment
		(start 426.607986 -287.310322)
		(end 428.178214 -287.310322)
		(width 0.16002)
		(layer "In11.Cu")
		(net "M_L_CPU0_SB_DQS_DP<5>")
	)
	(segment
		(start 446.066672 -286.460184)
		(end 447.37782 -286.460184)
		(width 0.16002)
		(layer "In11.Cu")
		(net "M_L_CPU0_SB_DQS_DP<5>")
	)
	(segment
		(start 387.556248 -277.00097)
		(end 387.56463 -276.996144)
		(width 0.09525)
		(layer "In11.Cu")
		(net "M_L_CPU0_SB_DQS_DP<5>")
	)
	(segment
		(start 436.097426 -286.935164)
		(end 436.71871 -286.935164)
		(width 0.16002)
		(layer "In11.Cu")
		(net "M_L_CPU0_SB_DQS_DP<5>")
	)
	(segment
		(start 395.776704 -276.059138)
		(end 395.835632 -276.118066)
		(width 0.09525)
		(layer "In11.Cu")
		(net "M_L_CPU0_SB_DQS_DP<5>")
	)
	(segment
		(start 430.028096 -286.081724)
		(end 430.600104 -286.081724)
		(width 0.16002)
		(layer "In11.Cu")
		(net "M_L_CPU0_SB_DQS_DP<5>")
	)
	(segment
		(start 411.610302 -286.935164)
		(end 411.94736 -286.598106)
		(width 0.16002)
		(layer "In11.Cu")
		(net "M_L_CPU0_SB_DQS_DP<5>")
	)
	(segment
		(start 423.43451 -286.460184)
		(end 425.757848 -286.460184)
		(width 0.16002)
		(layer "In11.Cu")
		(net "M_L_CPU0_SB_DQS_DP<5>")
	)
	(segment
		(start 416.83305 -286.135572)
		(end 417.366196 -286.135572)
		(width 0.16002)
		(layer "In11.Cu")
		(net "M_L_CPU0_SB_DQS_DP<5>")
	)
	(segment
		(start 395.835632 -276.118066)
		(end 395.859254 -276.118066)
		(width 0.09525)
		(layer "In11.Cu")
		(net "M_L_CPU0_SB_DQS_DP<5>")
	)
	(segment
		(start 419.298628 -287.310322)
		(end 420.63416 -287.310322)
		(width 0.16002)
		(layer "In11.Cu")
		(net "M_L_CPU0_SB_DQS_DP<5>")
	)
	(segment
		(start 393.186158 -277.007066)
		(end 393.196572 -277.00097)
		(width 0.09525)
		(layer "In11.Cu")
		(net "M_L_CPU0_SB_DQS_DP<5>")
	)
	(segment
		(start 441.696094 -287.310322)
		(end 443.266322 -287.310322)
		(width 0.16002)
		(layer "In11.Cu")
		(net "M_L_CPU0_SB_DQS_DP<5>")
	)
	(segment
		(start 416.495992 -285.645352)
		(end 416.495992 -285.798514)
		(width 0.16002)
		(layer "In11.Cu")
		(net "M_L_CPU0_SB_DQS_DP<5>")
	)
	(segment
		(start 435.722268 -287.310322)
		(end 436.097426 -286.935164)
		(width 0.16002)
		(layer "In11.Cu")
		(net "M_L_CPU0_SB_DQS_DP<5>")
	)
	(segment
		(start 420.63416 -287.310322)
		(end 421.009318 -286.935164)
		(width 0.16002)
		(layer "In11.Cu")
		(net "M_L_CPU0_SB_DQS_DP<5>")
	)
	(segment
		(start 417.366196 -286.135572)
		(end 417.690808 -286.460184)
		(width 0.16002)
		(layer "In11.Cu")
		(net "M_L_CPU0_SB_DQS_DP<5>")
	)
	(segment
		(start 395.360144 -276.059138)
		(end 395.776704 -276.059138)
		(width 0.09525)
		(layer "In11.Cu")
		(net "M_L_CPU0_SB_DQS_DP<5>")
	)
	(segment
		(start 423.05605 -286.081724)
		(end 423.43451 -286.460184)
		(width 0.16002)
		(layer "In11.Cu")
		(net "M_L_CPU0_SB_DQS_DP<5>")
	)
	(segment
		(start 445.688212 -286.081724)
		(end 446.066672 -286.460184)
		(width 0.16002)
		(layer "In11.Cu")
		(net "M_L_CPU0_SB_DQS_DP<5>")
	)
	(segment
		(start 437.57215 -286.081724)
		(end 438.144158 -286.081724)
		(width 0.16002)
		(layer "In11.Cu")
		(net "M_L_CPU0_SB_DQS_DP<5>")
	)
	(segment
		(start 394.948156 -275.782278)
		(end 395.083284 -275.782278)
		(width 0.09525)
		(layer "In11.Cu")
		(net "M_L_CPU0_SB_DQS_DP<5>")
	)
	(segment
		(start 415.827718 -285.798514)
		(end 415.827718 -285.645352)
		(width 0.16002)
		(layer "In11.Cu")
		(net "M_L_CPU0_SB_DQS_DP<5>")
	)
	(segment
		(start 429.174656 -286.935164)
		(end 430.028096 -286.081724)
		(width 0.16002)
		(layer "In11.Cu")
		(net "M_L_CPU0_SB_DQS_DP<5>")
	)
	(segment
		(start 449.814188 -286.31134)
		(end 450.088 -286.585152)
		(width 0.16002)
		(layer "In11.Cu")
		(net "M_L_CPU0_SB_DQS_DP<5>")
	)
	(segment
		(start 425.757848 -286.460184)
		(end 426.607986 -287.310322)
		(width 0.16002)
		(layer "In11.Cu")
		(net "M_L_CPU0_SB_DQS_DP<5>")
	)
	(segment
		(start 414.086548 -286.935164)
		(end 414.88614 -286.135572)
		(width 0.16002)
		(layer "In11.Cu")
		(net "M_L_CPU0_SB_DQS_DP<5>")
	)
	(segment
		(start 443.266322 -287.310322)
		(end 443.64148 -286.935164)
		(width 0.16002)
		(layer "In11.Cu")
		(net "M_L_CPU0_SB_DQS_DP<5>")
	)
	(segment
		(start 416.335972 -285.485332)
		(end 416.495992 -285.645352)
		(width 0.16002)
		(layer "In11.Cu")
		(net "M_L_CPU0_SB_DQS_DP<5>")
	)
	(segment
		(start 428.553372 -286.935164)
		(end 429.174656 -286.935164)
		(width 0.16002)
		(layer "In11.Cu")
		(net "M_L_CPU0_SB_DQS_DP<5>")
	)
	(segment
		(start 412.455614 -286.000952)
		(end 412.615634 -286.160972)
		(width 0.16002)
		(layer "In11.Cu")
		(net "M_L_CPU0_SB_DQS_DP<5>")
	)
	(segment
		(start 447.526664 -286.31134)
		(end 449.814188 -286.31134)
		(width 0.16002)
		(layer "In11.Cu")
		(net "M_L_CPU0_SB_DQS_DP<5>")
	)
	(segment
		(start 428.178214 -287.310322)
		(end 428.553372 -286.935164)
		(width 0.16002)
		(layer "In11.Cu")
		(net "M_L_CPU0_SB_DQS_DP<5>")
	)
	(segment
		(start 430.600104 -286.081724)
		(end 430.978564 -286.460184)
		(width 0.16002)
		(layer "In11.Cu")
		(net "M_L_CPU0_SB_DQS_DP<5>")
	)
	(segment
		(start 414.88614 -286.135572)
		(end 415.49066 -286.135572)
		(width 0.16002)
		(layer "In11.Cu")
		(net "M_L_CPU0_SB_DQS_DP<5>")
	)
	(segment
		(start 386.985002 -276.996144)
		(end 386.993384 -277.00097)
		(width 0.09525)
		(layer "In11.Cu")
		(net "M_L_CPU0_SB_DQS_DP<5>")
	)
	(segment
		(start 430.978564 -286.460184)
		(end 433.301902 -286.460184)
		(width 0.16002)
		(layer "In11.Cu")
		(net "M_L_CPU0_SB_DQS_DP<5>")
	)
	(segment
		(start 390.744964 -276.996144)
		(end 390.753346 -277.00097)
		(width 0.09525)
		(layer "In11.Cu")
		(net "M_L_CPU0_SB_DQS_DP<5>")
	)
	(segment
		(start 444.262764 -286.935164)
		(end 445.116204 -286.081724)
		(width 0.16002)
		(layer "In11.Cu")
		(net "M_L_CPU0_SB_DQS_DP<5>")
	)
	(segment
		(start 400.295364 -276.118066)
		(end 411.112462 -286.935164)
		(width 0.16002)
		(layer "In11.Cu")
		(net "M_L_CPU0_SB_DQS_DP<5>")
	)
	(segment
		(start 412.952692 -286.935164)
		(end 414.086548 -286.935164)
		(width 0.16002)
		(layer "In11.Cu")
		(net "M_L_CPU0_SB_DQS_DP<5>")
	)
	(segment
		(start 388.496302 -277.00097)
		(end 388.504684 -276.996144)
		(width 0.09525)
		(layer "In11.Cu")
		(net "M_L_CPU0_SB_DQS_DP<5>")
	)
	(segment
		(start 421.630602 -286.935164)
		(end 422.484042 -286.081724)
		(width 0.16002)
		(layer "In11.Cu")
		(net "M_L_CPU0_SB_DQS_DP<5>")
	)
	(segment
		(start 447.37782 -286.460184)
		(end 447.526664 -286.31134)
		(width 0.16002)
		(layer "In11.Cu")
		(net "M_L_CPU0_SB_DQS_DP<5>")
	)
	(arc
		(start 390.753346 -277.00097)
		(mid 391.034778 -277.076725)
		(end 391.31621 -277.00097)
		(width 0.09525)
		(layer "In11.Cu")
		(net "M_L_CPU0_SB_DQS_DP<5>")
	)
	(arc
		(start 386.139944 -277.041864)
		(mid 386.382656 -277.074747)
		(end 386.616194 -277.00097)
		(width 0.09525)
		(layer "In11.Cu")
		(net "M_L_CPU0_SB_DQS_DP<5>")
	)
	(arc
		(start 386.616194 -277.00097)
		(mid 386.799969 -276.950198)
		(end 386.985002 -276.996144)
		(width 0.09525)
		(layer "In11.Cu")
		(net "M_L_CPU0_SB_DQS_DP<5>")
	)
	(arc
		(start 392.256518 -277.00097)
		(mid 392.44524 -276.950166)
		(end 392.633962 -277.00097)
		(width 0.09525)
		(layer "In11.Cu")
		(net "M_L_CPU0_SB_DQS_DP<5>")
	)
	(arc
		(start 389.436356 -277.00097)
		(mid 389.624824 -276.950293)
		(end 389.813292 -277.00097)
		(width 0.09525)
		(layer "In11.Cu")
		(net "M_L_CPU0_SB_DQS_DP<5>")
	)
	(arc
		(start 389.813292 -277.00097)
		(mid 390.094724 -277.076725)
		(end 390.376156 -277.00097)
		(width 0.09525)
		(layer "In11.Cu")
		(net "M_L_CPU0_SB_DQS_DP<5>")
	)
	(arc
		(start 386.119624 -277.03399)
		(mid 386.129746 -277.038025)
		(end 386.139944 -277.041864)
		(width 0.09525)
		(layer "In11.Cu")
		(net "M_L_CPU0_SB_DQS_DP<5>")
	)
	(arc
		(start 390.376156 -277.00097)
		(mid 390.559931 -276.950198)
		(end 390.744964 -276.996144)
		(width 0.09525)
		(layer "In11.Cu")
		(net "M_L_CPU0_SB_DQS_DP<5>")
	)
	(arc
		(start 392.633962 -277.00097)
		(mid 392.909251 -277.076691)
		(end 393.186158 -277.007066)
		(width 0.09525)
		(layer "In11.Cu")
		(net "M_L_CPU0_SB_DQS_DP<5>")
	)
	(arc
		(start 386.993384 -277.00097)
		(mid 387.274816 -277.076725)
		(end 387.556248 -277.00097)
		(width 0.09525)
		(layer "In11.Cu")
		(net "M_L_CPU0_SB_DQS_DP<5>")
	)
	(arc
		(start 387.933438 -277.00097)
		(mid 388.21487 -277.076725)
		(end 388.496302 -277.00097)
		(width 0.09525)
		(layer "In11.Cu")
		(net "M_L_CPU0_SB_DQS_DP<5>")
	)
	(arc
		(start 387.56463 -276.996144)
		(mid 387.749662 -276.95023)
		(end 387.933438 -277.00097)
		(width 0.09525)
		(layer "In11.Cu")
		(net "M_L_CPU0_SB_DQS_DP<5>")
	)
	(arc
		(start 388.873492 -277.00097)
		(mid 389.154924 -277.076725)
		(end 389.436356 -277.00097)
		(width 0.09525)
		(layer "In11.Cu")
		(net "M_L_CPU0_SB_DQS_DP<5>")
	)
	(arc
		(start 393.196572 -277.00097)
		(mid 393.287411 -276.962825)
		(end 393.38504 -276.949662)
		(width 0.09525)
		(layer "In11.Cu")
		(net "M_L_CPU0_SB_DQS_DP<5>")
	)
	(arc
		(start 391.703814 -277.007066)
		(mid 391.980976 -277.076866)
		(end 392.256518 -277.00097)
		(width 0.09525)
		(layer "In11.Cu")
		(net "M_L_CPU0_SB_DQS_DP<5>")
	)
	(arc
		(start 388.504684 -276.996144)
		(mid 388.689716 -276.95023)
		(end 388.873492 -277.00097)
		(width 0.09525)
		(layer "In11.Cu")
		(net "M_L_CPU0_SB_DQS_DP<5>")
	)
	(arc
		(start 391.324592 -276.996144)
		(mid 391.509624 -276.95023)
		(end 391.6934 -277.00097)
		(width 0.09525)
		(layer "In11.Cu")
		(net "M_L_CPU0_SB_DQS_DP<5>")
	)
	(segment
		(start 385.39801 -272.200116)
		(end 385.864862 -272.466054)
		(width 0.12954)
		(layer "F.Cu")
		(net "M_L_CPU0_SB_DQS_DP<4>")
	)
	(segment
		(start 430.600104 -276.73173)
		(end 430.978564 -277.11019)
		(width 0.16002)
		(layer "In11.Cu")
		(net "M_L_CPU0_SB_DQS_DP<4>")
	)
	(segment
		(start 407.34615 -273.262344)
		(end 407.93162 -273.262344)
		(width 0.16002)
		(layer "In11.Cu")
		(net "M_L_CPU0_SB_DQS_DP<4>")
	)
	(segment
		(start 392.256264 -272.140934)
		(end 392.264646 -272.136108)
		(width 0.09525)
		(layer "In11.Cu")
		(net "M_L_CPU0_SB_DQS_DP<4>")
	)
	(segment
		(start 425.757848 -277.11019)
		(end 426.607986 -277.960328)
		(width 0.16002)
		(layer "In11.Cu")
		(net "M_L_CPU0_SB_DQS_DP<4>")
	)
	(segment
		(start 421.009318 -277.58517)
		(end 421.630602 -277.58517)
		(width 0.16002)
		(layer "In11.Cu")
		(net "M_L_CPU0_SB_DQS_DP<4>")
	)
	(segment
		(start 393.196318 -272.140934)
		(end 393.23137 -272.12036)
		(width 0.09525)
		(layer "In11.Cu")
		(net "M_L_CPU0_SB_DQS_DP<4>")
	)
	(segment
		(start 390.744964 -272.136108)
		(end 390.753346 -272.140934)
		(width 0.09525)
		(layer "In11.Cu")
		(net "M_L_CPU0_SB_DQS_DP<4>")
	)
	(segment
		(start 415.877502 -276.73173)
		(end 416.037522 -276.89175)
		(width 0.16002)
		(layer "In11.Cu")
		(net "M_L_CPU0_SB_DQS_DP<4>")
	)
	(segment
		(start 393.633706 -271.349724)
		(end 393.666218 -271.330928)
		(width 0.09525)
		(layer "In11.Cu")
		(net "M_L_CPU0_SB_DQS_DP<4>")
	)
	(segment
		(start 416.037522 -277.081234)
		(end 416.37458 -277.418292)
		(width 0.16002)
		(layer "In11.Cu")
		(net "M_L_CPU0_SB_DQS_DP<4>")
	)
	(segment
		(start 423.43451 -277.11019)
		(end 425.757848 -277.11019)
		(width 0.16002)
		(layer "In11.Cu")
		(net "M_L_CPU0_SB_DQS_DP<4>")
	)
	(segment
		(start 408.23769 -274.153884)
		(end 408.719782 -274.635976)
		(width 0.16002)
		(layer "In11.Cu")
		(net "M_L_CPU0_SB_DQS_DP<4>")
	)
	(segment
		(start 416.973258 -277.418292)
		(end 417.310316 -277.081234)
		(width 0.16002)
		(layer "In11.Cu")
		(net "M_L_CPU0_SB_DQS_DP<4>")
	)
	(segment
		(start 388.496302 -272.140934)
		(end 388.504684 -272.136108)
		(width 0.09525)
		(layer "In11.Cu")
		(net "M_L_CPU0_SB_DQS_DP<4>")
	)
	(segment
		(start 437.57215 -276.73173)
		(end 438.144158 -276.73173)
		(width 0.16002)
		(layer "In11.Cu")
		(net "M_L_CPU0_SB_DQS_DP<4>")
	)
	(segment
		(start 395.203172 -270.592042)
		(end 395.407642 -270.387572)
		(width 0.09525)
		(layer "In11.Cu")
		(net "M_L_CPU0_SB_DQS_DP<4>")
	)
	(segment
		(start 410.984954 -276.901148)
		(end 411.668976 -277.58517)
		(width 0.16002)
		(layer "In11.Cu")
		(net "M_L_CPU0_SB_DQS_DP<4>")
	)
	(segment
		(start 436.71871 -277.58517)
		(end 437.57215 -276.73173)
		(width 0.16002)
		(layer "In11.Cu")
		(net "M_L_CPU0_SB_DQS_DP<4>")
	)
	(segment
		(start 408.23769 -273.568414)
		(end 408.23769 -274.153884)
		(width 0.16002)
		(layer "In11.Cu")
		(net "M_L_CPU0_SB_DQS_DP<4>")
	)
	(segment
		(start 421.630602 -277.58517)
		(end 422.484042 -276.73173)
		(width 0.16002)
		(layer "In11.Cu")
		(net "M_L_CPU0_SB_DQS_DP<4>")
	)
	(segment
		(start 447.37782 -277.11019)
		(end 447.526664 -276.961346)
		(width 0.16002)
		(layer "In11.Cu")
		(net "M_L_CPU0_SB_DQS_DP<4>")
	)
	(segment
		(start 410.984954 -276.315678)
		(end 410.984954 -276.901148)
		(width 0.16002)
		(layer "In11.Cu")
		(net "M_L_CPU0_SB_DQS_DP<4>")
	)
	(segment
		(start 393.781026 -271.243044)
		(end 394.431774 -270.592042)
		(width 0.09525)
		(layer "In11.Cu")
		(net "M_L_CPU0_SB_DQS_DP<4>")
	)
	(segment
		(start 426.607986 -277.960328)
		(end 428.178214 -277.960328)
		(width 0.16002)
		(layer "In11.Cu")
		(net "M_L_CPU0_SB_DQS_DP<4>")
	)
	(segment
		(start 429.174656 -277.58517)
		(end 430.028096 -276.73173)
		(width 0.16002)
		(layer "In11.Cu")
		(net "M_L_CPU0_SB_DQS_DP<4>")
	)
	(segment
		(start 434.15204 -277.960328)
		(end 435.722268 -277.960328)
		(width 0.16002)
		(layer "In11.Cu")
		(net "M_L_CPU0_SB_DQS_DP<4>")
	)
	(segment
		(start 446.066672 -277.11019)
		(end 447.37782 -277.11019)
		(width 0.16002)
		(layer "In11.Cu")
		(net "M_L_CPU0_SB_DQS_DP<4>")
	)
	(segment
		(start 410.093414 -276.009608)
		(end 410.678884 -276.009608)
		(width 0.16002)
		(layer "In11.Cu")
		(net "M_L_CPU0_SB_DQS_DP<4>")
	)
	(segment
		(start 410.678884 -276.009608)
		(end 410.984954 -276.315678)
		(width 0.16002)
		(layer "In11.Cu")
		(net "M_L_CPU0_SB_DQS_DP<4>")
	)
	(segment
		(start 438.522618 -277.11019)
		(end 440.845956 -277.11019)
		(width 0.16002)
		(layer "In11.Cu")
		(net "M_L_CPU0_SB_DQS_DP<4>")
	)
	(segment
		(start 391.31621 -272.140934)
		(end 391.324592 -272.136108)
		(width 0.09525)
		(layer "In11.Cu")
		(net "M_L_CPU0_SB_DQS_DP<4>")
	)
	(segment
		(start 409.611322 -275.527516)
		(end 410.093414 -276.009608)
		(width 0.16002)
		(layer "In11.Cu")
		(net "M_L_CPU0_SB_DQS_DP<4>")
	)
	(segment
		(start 395.835632 -270.4465)
		(end 395.859254 -270.4465)
		(width 0.09525)
		(layer "In11.Cu")
		(net "M_L_CPU0_SB_DQS_DP<4>")
	)
	(segment
		(start 395.407642 -270.387572)
		(end 395.776704 -270.387572)
		(width 0.09525)
		(layer "In11.Cu")
		(net "M_L_CPU0_SB_DQS_DP<4>")
	)
	(segment
		(start 418.05479 -276.73173)
		(end 419.283388 -277.960328)
		(width 0.16002)
		(layer "In11.Cu")
		(net "M_L_CPU0_SB_DQS_DP<4>")
	)
	(segment
		(start 430.028096 -276.73173)
		(end 430.600104 -276.73173)
		(width 0.16002)
		(layer "In11.Cu")
		(net "M_L_CPU0_SB_DQS_DP<4>")
	)
	(segment
		(start 428.178214 -277.960328)
		(end 428.553372 -277.58517)
		(width 0.16002)
		(layer "In11.Cu")
		(net "M_L_CPU0_SB_DQS_DP<4>")
	)
	(segment
		(start 428.553372 -277.58517)
		(end 429.174656 -277.58517)
		(width 0.16002)
		(layer "In11.Cu")
		(net "M_L_CPU0_SB_DQS_DP<4>")
	)
	(segment
		(start 409.305252 -274.635976)
		(end 409.611322 -274.942046)
		(width 0.16002)
		(layer "In11.Cu")
		(net "M_L_CPU0_SB_DQS_DP<4>")
	)
	(segment
		(start 407.93162 -273.262344)
		(end 408.23769 -273.568414)
		(width 0.16002)
		(layer "In11.Cu")
		(net "M_L_CPU0_SB_DQS_DP<4>")
	)
	(segment
		(start 440.845956 -277.11019)
		(end 441.696094 -277.960328)
		(width 0.16002)
		(layer "In11.Cu")
		(net "M_L_CPU0_SB_DQS_DP<4>")
	)
	(segment
		(start 444.262764 -277.58517)
		(end 445.116204 -276.73173)
		(width 0.16002)
		(layer "In11.Cu")
		(net "M_L_CPU0_SB_DQS_DP<4>")
	)
	(segment
		(start 408.719782 -274.635976)
		(end 409.305252 -274.635976)
		(width 0.16002)
		(layer "In11.Cu")
		(net "M_L_CPU0_SB_DQS_DP<4>")
	)
	(segment
		(start 414.086548 -277.58517)
		(end 414.939988 -276.73173)
		(width 0.16002)
		(layer "In11.Cu")
		(net "M_L_CPU0_SB_DQS_DP<4>")
	)
	(segment
		(start 423.05605 -276.73173)
		(end 423.43451 -277.11019)
		(width 0.16002)
		(layer "In11.Cu")
		(net "M_L_CPU0_SB_DQS_DP<4>")
	)
	(segment
		(start 419.283388 -277.960328)
		(end 420.63416 -277.960328)
		(width 0.16002)
		(layer "In11.Cu")
		(net "M_L_CPU0_SB_DQS_DP<4>")
	)
	(segment
		(start 385.864862 -272.466054)
		(end 386.018786 -272.200624)
		(width 0.09525)
		(layer "In11.Cu")
		(net "M_L_CPU0_SB_DQS_DP<4>")
	)
	(segment
		(start 447.526664 -276.961346)
		(end 449.814188 -276.961346)
		(width 0.16002)
		(layer "In11.Cu")
		(net "M_L_CPU0_SB_DQS_DP<4>")
	)
	(segment
		(start 443.266322 -277.960328)
		(end 443.64148 -277.58517)
		(width 0.16002)
		(layer "In11.Cu")
		(net "M_L_CPU0_SB_DQS_DP<4>")
	)
	(segment
		(start 420.63416 -277.960328)
		(end 421.009318 -277.58517)
		(width 0.16002)
		(layer "In11.Cu")
		(net "M_L_CPU0_SB_DQS_DP<4>")
	)
	(segment
		(start 449.814188 -276.961346)
		(end 450.088 -277.235158)
		(width 0.16002)
		(layer "In11.Cu")
		(net "M_L_CPU0_SB_DQS_DP<4>")
	)
	(segment
		(start 430.978564 -277.11019)
		(end 433.301902 -277.11019)
		(width 0.16002)
		(layer "In11.Cu")
		(net "M_L_CPU0_SB_DQS_DP<4>")
	)
	(segment
		(start 386.985002 -272.136108)
		(end 386.993384 -272.140934)
		(width 0.09525)
		(layer "In11.Cu")
		(net "M_L_CPU0_SB_DQS_DP<4>")
	)
	(segment
		(start 404.530306 -270.4465)
		(end 407.34615 -273.262344)
		(width 0.16002)
		(layer "In11.Cu")
		(net "M_L_CPU0_SB_DQS_DP<4>")
	)
	(segment
		(start 445.688212 -276.73173)
		(end 446.066672 -277.11019)
		(width 0.16002)
		(layer "In11.Cu")
		(net "M_L_CPU0_SB_DQS_DP<4>")
	)
	(segment
		(start 411.668976 -277.58517)
		(end 414.086548 -277.58517)
		(width 0.16002)
		(layer "In11.Cu")
		(net "M_L_CPU0_SB_DQS_DP<4>")
	)
	(segment
		(start 438.144158 -276.73173)
		(end 438.522618 -277.11019)
		(width 0.16002)
		(layer "In11.Cu")
		(net "M_L_CPU0_SB_DQS_DP<4>")
	)
	(segment
		(start 436.097426 -277.58517)
		(end 436.71871 -277.58517)
		(width 0.16002)
		(layer "In11.Cu")
		(net "M_L_CPU0_SB_DQS_DP<4>")
	)
	(segment
		(start 386.018786 -272.200624)
		(end 386.119624 -272.173954)
		(width 0.09525)
		(layer "In11.Cu")
		(net "M_L_CPU0_SB_DQS_DP<4>")
	)
	(segment
		(start 395.776704 -270.387572)
		(end 395.835632 -270.4465)
		(width 0.09525)
		(layer "In11.Cu")
		(net "M_L_CPU0_SB_DQS_DP<4>")
	)
	(segment
		(start 416.37458 -277.418292)
		(end 416.973258 -277.418292)
		(width 0.16002)
		(layer "In11.Cu")
		(net "M_L_CPU0_SB_DQS_DP<4>")
	)
	(segment
		(start 422.484042 -276.73173)
		(end 423.05605 -276.73173)
		(width 0.16002)
		(layer "In11.Cu")
		(net "M_L_CPU0_SB_DQS_DP<4>")
	)
	(segment
		(start 441.696094 -277.960328)
		(end 443.266322 -277.960328)
		(width 0.16002)
		(layer "In11.Cu")
		(net "M_L_CPU0_SB_DQS_DP<4>")
	)
	(segment
		(start 395.859254 -270.4465)
		(end 404.530306 -270.4465)
		(width 0.16002)
		(layer "In11.Cu")
		(net "M_L_CPU0_SB_DQS_DP<4>")
	)
	(segment
		(start 414.939988 -276.73173)
		(end 415.877502 -276.73173)
		(width 0.16002)
		(layer "In11.Cu")
		(net "M_L_CPU0_SB_DQS_DP<4>")
	)
	(segment
		(start 394.431774 -270.592042)
		(end 395.203172 -270.592042)
		(width 0.09525)
		(layer "In11.Cu")
		(net "M_L_CPU0_SB_DQS_DP<4>")
	)
	(segment
		(start 435.722268 -277.960328)
		(end 436.097426 -277.58517)
		(width 0.16002)
		(layer "In11.Cu")
		(net "M_L_CPU0_SB_DQS_DP<4>")
	)
	(segment
		(start 433.301902 -277.11019)
		(end 434.15204 -277.960328)
		(width 0.16002)
		(layer "In11.Cu")
		(net "M_L_CPU0_SB_DQS_DP<4>")
	)
	(segment
		(start 387.556248 -272.140934)
		(end 387.56463 -272.136108)
		(width 0.09525)
		(layer "In11.Cu")
		(net "M_L_CPU0_SB_DQS_DP<4>")
	)
	(segment
		(start 443.64148 -277.58517)
		(end 444.262764 -277.58517)
		(width 0.16002)
		(layer "In11.Cu")
		(net "M_L_CPU0_SB_DQS_DP<4>")
	)
	(segment
		(start 409.611322 -274.942046)
		(end 409.611322 -275.527516)
		(width 0.16002)
		(layer "In11.Cu")
		(net "M_L_CPU0_SB_DQS_DP<4>")
	)
	(segment
		(start 417.310316 -277.081234)
		(end 417.310316 -276.89175)
		(width 0.16002)
		(layer "In11.Cu")
		(net "M_L_CPU0_SB_DQS_DP<4>")
	)
	(segment
		(start 416.037522 -276.89175)
		(end 416.037522 -277.081234)
		(width 0.16002)
		(layer "In11.Cu")
		(net "M_L_CPU0_SB_DQS_DP<4>")
	)
	(segment
		(start 445.116204 -276.73173)
		(end 445.688212 -276.73173)
		(width 0.16002)
		(layer "In11.Cu")
		(net "M_L_CPU0_SB_DQS_DP<4>")
	)
	(segment
		(start 417.470336 -276.73173)
		(end 418.05479 -276.73173)
		(width 0.16002)
		(layer "In11.Cu")
		(net "M_L_CPU0_SB_DQS_DP<4>")
	)
	(segment
		(start 417.310316 -276.89175)
		(end 417.470336 -276.73173)
		(width 0.16002)
		(layer "In11.Cu")
		(net "M_L_CPU0_SB_DQS_DP<4>")
	)
	(arc
		(start 393.742164 -271.278096)
		(mid 393.762004 -271.261024)
		(end 393.781026 -271.243044)
		(width 0.09525)
		(layer "In11.Cu")
		(net "M_L_CPU0_SB_DQS_DP<4>")
	)
	(arc
		(start 391.6934 -272.140934)
		(mid 391.974832 -272.216689)
		(end 392.256264 -272.140934)
		(width 0.09525)
		(layer "In11.Cu")
		(net "M_L_CPU0_SB_DQS_DP<4>")
	)
	(arc
		(start 388.873492 -272.140934)
		(mid 389.154924 -272.216689)
		(end 389.436356 -272.140934)
		(width 0.09525)
		(layer "In11.Cu")
		(net "M_L_CPU0_SB_DQS_DP<4>")
	)
	(arc
		(start 392.264646 -272.136108)
		(mid 392.449678 -272.090194)
		(end 392.633454 -272.140934)
		(width 0.09525)
		(layer "In11.Cu")
		(net "M_L_CPU0_SB_DQS_DP<4>")
	)
	(arc
		(start 391.324592 -272.136108)
		(mid 391.509624 -272.090194)
		(end 391.6934 -272.140934)
		(width 0.09525)
		(layer "In11.Cu")
		(net "M_L_CPU0_SB_DQS_DP<4>")
	)
	(arc
		(start 389.436356 -272.140934)
		(mid 389.624824 -272.090257)
		(end 389.813292 -272.140934)
		(width 0.09525)
		(layer "In11.Cu")
		(net "M_L_CPU0_SB_DQS_DP<4>")
	)
	(arc
		(start 386.993384 -272.140934)
		(mid 387.274816 -272.216689)
		(end 387.556248 -272.140934)
		(width 0.09525)
		(layer "In11.Cu")
		(net "M_L_CPU0_SB_DQS_DP<4>")
	)
	(arc
		(start 386.139944 -272.181828)
		(mid 386.382656 -272.214711)
		(end 386.616194 -272.140934)
		(width 0.09525)
		(layer "In11.Cu")
		(net "M_L_CPU0_SB_DQS_DP<4>")
	)
	(arc
		(start 393.23137 -272.12036)
		(mid 393.411761 -271.918661)
		(end 393.476988 -271.656048)
		(width 0.09525)
		(layer "In11.Cu")
		(net "M_L_CPU0_SB_DQS_DP<4>")
	)
	(arc
		(start 392.633454 -272.140934)
		(mid 392.914886 -272.216689)
		(end 393.196318 -272.140934)
		(width 0.09525)
		(layer "In11.Cu")
		(net "M_L_CPU0_SB_DQS_DP<4>")
	)
	(arc
		(start 389.813292 -272.140934)
		(mid 390.094724 -272.216689)
		(end 390.376156 -272.140934)
		(width 0.09525)
		(layer "In11.Cu")
		(net "M_L_CPU0_SB_DQS_DP<4>")
	)
	(arc
		(start 393.476988 -271.656048)
		(mid 393.518445 -271.484008)
		(end 393.633706 -271.349724)
		(width 0.09525)
		(layer "In11.Cu")
		(net "M_L_CPU0_SB_DQS_DP<4>")
	)
	(arc
		(start 390.376156 -272.140934)
		(mid 390.559931 -272.090162)
		(end 390.744964 -272.136108)
		(width 0.09525)
		(layer "In11.Cu")
		(net "M_L_CPU0_SB_DQS_DP<4>")
	)
	(arc
		(start 393.666218 -271.330928)
		(mid 393.705281 -271.306079)
		(end 393.742164 -271.278096)
		(width 0.09525)
		(layer "In11.Cu")
		(net "M_L_CPU0_SB_DQS_DP<4>")
	)
	(arc
		(start 387.56463 -272.136108)
		(mid 387.749662 -272.090194)
		(end 387.933438 -272.140934)
		(width 0.09525)
		(layer "In11.Cu")
		(net "M_L_CPU0_SB_DQS_DP<4>")
	)
	(arc
		(start 387.933438 -272.140934)
		(mid 388.21487 -272.216689)
		(end 388.496302 -272.140934)
		(width 0.09525)
		(layer "In11.Cu")
		(net "M_L_CPU0_SB_DQS_DP<4>")
	)
	(arc
		(start 390.753346 -272.140934)
		(mid 391.034778 -272.216689)
		(end 391.31621 -272.140934)
		(width 0.09525)
		(layer "In11.Cu")
		(net "M_L_CPU0_SB_DQS_DP<4>")
	)
	(arc
		(start 386.119624 -272.173954)
		(mid 386.129746 -272.177989)
		(end 386.139944 -272.181828)
		(width 0.09525)
		(layer "In11.Cu")
		(net "M_L_CPU0_SB_DQS_DP<4>")
	)
	(arc
		(start 386.616194 -272.140934)
		(mid 386.799969 -272.090162)
		(end 386.985002 -272.136108)
		(width 0.09525)
		(layer "In11.Cu")
		(net "M_L_CPU0_SB_DQS_DP<4>")
	)
	(arc
		(start 388.504684 -272.136108)
		(mid 388.689716 -272.090194)
		(end 388.873492 -272.140934)
		(width 0.09525)
		(layer "In11.Cu")
		(net "M_L_CPU0_SB_DQS_DP<4>")
	)
	(segment
		(start 387.277864 -290.019994)
		(end 387.744716 -290.285932)
		(width 0.12954)
		(layer "F.Cu")
		(net "M_L_CPU0_SB_DQS_DP<3>")
	)
	(segment
		(start 432.584606 -312.209942)
		(end 433.43449 -313.059826)
		(width 0.16002)
		(layer "In11.Cu")
		(net "M_L_CPU0_SB_DQS_DP<3>")
	)
	(segment
		(start 396.378938 -294.93337)
		(end 396.378938 -299.98162)
		(width 0.16002)
		(layer "In11.Cu")
		(net "M_L_CPU0_SB_DQS_DP<3>")
	)
	(segment
		(start 409.784804 -313.387486)
		(end 413.997902 -313.387486)
		(width 0.16002)
		(layer "In11.Cu")
		(net "M_L_CPU0_SB_DQS_DP<3>")
	)
	(segment
		(start 417.496498 -312.209942)
		(end 418.346382 -313.059826)
		(width 0.16002)
		(layer "In11.Cu")
		(net "M_L_CPU0_SB_DQS_DP<3>")
	)
	(segment
		(start 387.590792 -290.551362)
		(end 387.61416 -290.63823)
		(width 0.09525)
		(layer "In11.Cu")
		(net "M_L_CPU0_SB_DQS_DP<3>")
	)
	(segment
		(start 444.174118 -313.387486)
		(end 444.997078 -312.564526)
		(width 0.16002)
		(layer "In11.Cu")
		(net "M_L_CPU0_SB_DQS_DP<3>")
	)
	(segment
		(start 451.701662 -313.402726)
		(end 451.895464 -313.208924)
		(width 0.16002)
		(layer "In11.Cu")
		(net "M_L_CPU0_SB_DQS_DP<3>")
	)
	(segment
		(start 396.378938 -299.98162)
		(end 409.784804 -313.387486)
		(width 0.16002)
		(layer "In11.Cu")
		(net "M_L_CPU0_SB_DQS_DP<3>")
	)
	(segment
		(start 448.703954 -312.783982)
		(end 448.830954 -312.656982)
		(width 0.16002)
		(layer "In11.Cu")
		(net "M_L_CPU0_SB_DQS_DP<3>")
	)
	(segment
		(start 395.74089 -294.295322)
		(end 395.757654 -294.312086)
		(width 0.09525)
		(layer "In11.Cu")
		(net "M_L_CPU0_SB_DQS_DP<3>")
	)
	(segment
		(start 391.31621 -290.611052)
		(end 391.324592 -290.615878)
		(width 0.09525)
		(layer "In11.Cu")
		(net "M_L_CPU0_SB_DQS_DP<3>")
	)
	(segment
		(start 418.346382 -313.059826)
		(end 420.490396 -313.059826)
		(width 0.16002)
		(layer "In11.Cu")
		(net "M_L_CPU0_SB_DQS_DP<3>")
	)
	(segment
		(start 421.541956 -313.387486)
		(end 422.364916 -312.564526)
		(width 0.16002)
		(layer "In11.Cu")
		(net "M_L_CPU0_SB_DQS_DP<3>")
	)
	(segment
		(start 430.675034 -312.209942)
		(end 432.584606 -312.209942)
		(width 0.16002)
		(layer "In11.Cu")
		(net "M_L_CPU0_SB_DQS_DP<3>")
	)
	(segment
		(start 447.672714 -312.209942)
		(end 448.246754 -312.783982)
		(width 0.16002)
		(layer "In11.Cu")
		(net "M_L_CPU0_SB_DQS_DP<3>")
	)
	(segment
		(start 444.997078 -312.564526)
		(end 445.408558 -312.564526)
		(width 0.16002)
		(layer "In11.Cu")
		(net "M_L_CPU0_SB_DQS_DP<3>")
	)
	(segment
		(start 423.13098 -312.209942)
		(end 425.040552 -312.209942)
		(width 0.16002)
		(layer "In11.Cu")
		(net "M_L_CPU0_SB_DQS_DP<3>")
	)
	(segment
		(start 388.496302 -290.611052)
		(end 388.504684 -290.615878)
		(width 0.09525)
		(layer "In11.Cu")
		(net "M_L_CPU0_SB_DQS_DP<3>")
	)
	(segment
		(start 422.776396 -312.564526)
		(end 423.13098 -312.209942)
		(width 0.16002)
		(layer "In11.Cu")
		(net "M_L_CPU0_SB_DQS_DP<3>")
	)
	(segment
		(start 450.66839 -312.783982)
		(end 451.287134 -313.402726)
		(width 0.16002)
		(layer "In11.Cu")
		(net "M_L_CPU0_SB_DQS_DP<3>")
	)
	(segment
		(start 452.559928 -313.208924)
		(end 452.686928 -313.081924)
		(width 0.16002)
		(layer "In11.Cu")
		(net "M_L_CPU0_SB_DQS_DP<3>")
	)
	(segment
		(start 429.08601 -313.387486)
		(end 429.90897 -312.564526)
		(width 0.16002)
		(layer "In11.Cu")
		(net "M_L_CPU0_SB_DQS_DP<3>")
	)
	(segment
		(start 428.36211 -313.387486)
		(end 429.08601 -313.387486)
		(width 0.16002)
		(layer "In11.Cu")
		(net "M_L_CPU0_SB_DQS_DP<3>")
	)
	(segment
		(start 425.890436 -313.059826)
		(end 428.03445 -313.059826)
		(width 0.16002)
		(layer "In11.Cu")
		(net "M_L_CPU0_SB_DQS_DP<3>")
	)
	(segment
		(start 393.914884 -291.701982)
		(end 394.516356 -293.1541)
		(width 0.09525)
		(layer "In11.Cu")
		(net "M_L_CPU0_SB_DQS_DP<3>")
	)
	(segment
		(start 420.490396 -313.059826)
		(end 420.818056 -313.387486)
		(width 0.16002)
		(layer "In11.Cu")
		(net "M_L_CPU0_SB_DQS_DP<3>")
	)
	(segment
		(start 445.408558 -312.564526)
		(end 445.763142 -312.209942)
		(width 0.16002)
		(layer "In11.Cu")
		(net "M_L_CPU0_SB_DQS_DP<3>")
	)
	(segment
		(start 436.630064 -313.387486)
		(end 437.453024 -312.564526)
		(width 0.16002)
		(layer "In11.Cu")
		(net "M_L_CPU0_SB_DQS_DP<3>")
	)
	(segment
		(start 429.90897 -312.564526)
		(end 430.32045 -312.564526)
		(width 0.16002)
		(layer "In11.Cu")
		(net "M_L_CPU0_SB_DQS_DP<3>")
	)
	(segment
		(start 448.246754 -312.783982)
		(end 448.703954 -312.783982)
		(width 0.16002)
		(layer "In11.Cu")
		(net "M_L_CPU0_SB_DQS_DP<3>")
	)
	(segment
		(start 437.864504 -312.564526)
		(end 438.219088 -312.209942)
		(width 0.16002)
		(layer "In11.Cu")
		(net "M_L_CPU0_SB_DQS_DP<3>")
	)
	(segment
		(start 413.997902 -313.387486)
		(end 414.820862 -312.564526)
		(width 0.16002)
		(layer "In11.Cu")
		(net "M_L_CPU0_SB_DQS_DP<3>")
	)
	(segment
		(start 438.219088 -312.209942)
		(end 440.12866 -312.209942)
		(width 0.16002)
		(layer "In11.Cu")
		(net "M_L_CPU0_SB_DQS_DP<3>")
	)
	(segment
		(start 414.820862 -312.564526)
		(end 415.232342 -312.564526)
		(width 0.16002)
		(layer "In11.Cu")
		(net "M_L_CPU0_SB_DQS_DP<3>")
	)
	(segment
		(start 425.040552 -312.209942)
		(end 425.890436 -313.059826)
		(width 0.16002)
		(layer "In11.Cu")
		(net "M_L_CPU0_SB_DQS_DP<3>")
	)
	(segment
		(start 437.453024 -312.564526)
		(end 437.864504 -312.564526)
		(width 0.16002)
		(layer "In11.Cu")
		(net "M_L_CPU0_SB_DQS_DP<3>")
	)
	(segment
		(start 445.763142 -312.209942)
		(end 447.672714 -312.209942)
		(width 0.16002)
		(layer "In11.Cu")
		(net "M_L_CPU0_SB_DQS_DP<3>")
	)
	(segment
		(start 393.074652 -290.741862)
		(end 393.673076 -291.340286)
		(width 0.09525)
		(layer "In11.Cu")
		(net "M_L_CPU0_SB_DQS_DP<3>")
	)
	(segment
		(start 395.757654 -294.312086)
		(end 396.378938 -294.93337)
		(width 0.16002)
		(layer "In11.Cu")
		(net "M_L_CPU0_SB_DQS_DP<3>")
	)
	(segment
		(start 433.43449 -313.059826)
		(end 435.578504 -313.059826)
		(width 0.16002)
		(layer "In11.Cu")
		(net "M_L_CPU0_SB_DQS_DP<3>")
	)
	(segment
		(start 451.895464 -313.208924)
		(end 452.559928 -313.208924)
		(width 0.16002)
		(layer "In11.Cu")
		(net "M_L_CPU0_SB_DQS_DP<3>")
	)
	(segment
		(start 428.03445 -313.059826)
		(end 428.36211 -313.387486)
		(width 0.16002)
		(layer "In11.Cu")
		(net "M_L_CPU0_SB_DQS_DP<3>")
	)
	(segment
		(start 453.293988 -313.208924)
		(end 453.914256 -313.208924)
		(width 0.16002)
		(layer "In11.Cu")
		(net "M_L_CPU0_SB_DQS_DP<3>")
	)
	(segment
		(start 415.586926 -312.209942)
		(end 417.496498 -312.209942)
		(width 0.16002)
		(layer "In11.Cu")
		(net "M_L_CPU0_SB_DQS_DP<3>")
	)
	(segment
		(start 453.166988 -313.081924)
		(end 453.293988 -313.208924)
		(width 0.16002)
		(layer "In11.Cu")
		(net "M_L_CPU0_SB_DQS_DP<3>")
	)
	(segment
		(start 415.232342 -312.564526)
		(end 415.586926 -312.209942)
		(width 0.16002)
		(layer "In11.Cu")
		(net "M_L_CPU0_SB_DQS_DP<3>")
	)
	(segment
		(start 449.415154 -312.783982)
		(end 450.66839 -312.783982)
		(width 0.16002)
		(layer "In11.Cu")
		(net "M_L_CPU0_SB_DQS_DP<3>")
	)
	(segment
		(start 443.122558 -313.059826)
		(end 443.450218 -313.387486)
		(width 0.16002)
		(layer "In11.Cu")
		(net "M_L_CPU0_SB_DQS_DP<3>")
	)
	(segment
		(start 451.287134 -313.402726)
		(end 451.701662 -313.402726)
		(width 0.16002)
		(layer "In11.Cu")
		(net "M_L_CPU0_SB_DQS_DP<3>")
	)
	(segment
		(start 449.288154 -312.656982)
		(end 449.415154 -312.783982)
		(width 0.16002)
		(layer "In11.Cu")
		(net "M_L_CPU0_SB_DQS_DP<3>")
	)
	(segment
		(start 448.830954 -312.656982)
		(end 449.288154 -312.656982)
		(width 0.16002)
		(layer "In11.Cu")
		(net "M_L_CPU0_SB_DQS_DP<3>")
	)
	(segment
		(start 420.818056 -313.387486)
		(end 421.541956 -313.387486)
		(width 0.16002)
		(layer "In11.Cu")
		(net "M_L_CPU0_SB_DQS_DP<3>")
	)
	(segment
		(start 440.12866 -312.209942)
		(end 440.978544 -313.059826)
		(width 0.16002)
		(layer "In11.Cu")
		(net "M_L_CPU0_SB_DQS_DP<3>")
	)
	(segment
		(start 430.32045 -312.564526)
		(end 430.675034 -312.209942)
		(width 0.16002)
		(layer "In11.Cu")
		(net "M_L_CPU0_SB_DQS_DP<3>")
	)
	(segment
		(start 443.450218 -313.387486)
		(end 444.174118 -313.387486)
		(width 0.16002)
		(layer "In11.Cu")
		(net "M_L_CPU0_SB_DQS_DP<3>")
	)
	(segment
		(start 394.516356 -293.1541)
		(end 395.657578 -294.295322)
		(width 0.09525)
		(layer "In11.Cu")
		(net "M_L_CPU0_SB_DQS_DP<3>")
	)
	(segment
		(start 435.578504 -313.059826)
		(end 435.906164 -313.387486)
		(width 0.16002)
		(layer "In11.Cu")
		(net "M_L_CPU0_SB_DQS_DP<3>")
	)
	(segment
		(start 453.914256 -313.208924)
		(end 454.188068 -312.935112)
		(width 0.16002)
		(layer "In11.Cu")
		(net "M_L_CPU0_SB_DQS_DP<3>")
	)
	(segment
		(start 387.744716 -290.285932)
		(end 387.590792 -290.551362)
		(width 0.09525)
		(layer "In11.Cu")
		(net "M_L_CPU0_SB_DQS_DP<3>")
	)
	(segment
		(start 395.657578 -294.295322)
		(end 395.74089 -294.295322)
		(width 0.09525)
		(layer "In11.Cu")
		(net "M_L_CPU0_SB_DQS_DP<3>")
	)
	(segment
		(start 422.364916 -312.564526)
		(end 422.776396 -312.564526)
		(width 0.16002)
		(layer "In11.Cu")
		(net "M_L_CPU0_SB_DQS_DP<3>")
	)
	(segment
		(start 435.906164 -313.387486)
		(end 436.630064 -313.387486)
		(width 0.16002)
		(layer "In11.Cu")
		(net "M_L_CPU0_SB_DQS_DP<3>")
	)
	(segment
		(start 390.744964 -290.615878)
		(end 390.753346 -290.611052)
		(width 0.09525)
		(layer "In11.Cu")
		(net "M_L_CPU0_SB_DQS_DP<3>")
	)
	(segment
		(start 391.974578 -290.53536)
		(end 392.575796 -290.53536)
		(width 0.09525)
		(layer "In11.Cu")
		(net "M_L_CPU0_SB_DQS_DP<3>")
	)
	(segment
		(start 440.978544 -313.059826)
		(end 443.122558 -313.059826)
		(width 0.16002)
		(layer "In11.Cu")
		(net "M_L_CPU0_SB_DQS_DP<3>")
	)
	(segment
		(start 452.686928 -313.081924)
		(end 453.166988 -313.081924)
		(width 0.16002)
		(layer "In11.Cu")
		(net "M_L_CPU0_SB_DQS_DP<3>")
	)
	(arc
		(start 391.324592 -290.615878)
		(mid 391.509624 -290.661792)
		(end 391.6934 -290.611052)
		(width 0.09525)
		(layer "In11.Cu")
		(net "M_L_CPU0_SB_DQS_DP<3>")
	)
	(arc
		(start 392.575796 -290.53536)
		(mid 392.845779 -290.588969)
		(end 393.074652 -290.741862)
		(width 0.09525)
		(layer "In11.Cu")
		(net "M_L_CPU0_SB_DQS_DP<3>")
	)
	(arc
		(start 389.436356 -290.611052)
		(mid 389.624824 -290.661729)
		(end 389.813292 -290.611052)
		(width 0.09525)
		(layer "In11.Cu")
		(net "M_L_CPU0_SB_DQS_DP<3>")
	)
	(arc
		(start 388.504684 -290.615878)
		(mid 388.689716 -290.661792)
		(end 388.873492 -290.611052)
		(width 0.09525)
		(layer "In11.Cu")
		(net "M_L_CPU0_SB_DQS_DP<3>")
	)
	(arc
		(start 389.813292 -290.611052)
		(mid 390.094724 -290.535297)
		(end 390.376156 -290.611052)
		(width 0.09525)
		(layer "In11.Cu")
		(net "M_L_CPU0_SB_DQS_DP<3>")
	)
	(arc
		(start 390.376156 -290.611052)
		(mid 390.559931 -290.661824)
		(end 390.744964 -290.615878)
		(width 0.09525)
		(layer "In11.Cu")
		(net "M_L_CPU0_SB_DQS_DP<3>")
	)
	(arc
		(start 387.933438 -290.611052)
		(mid 388.21487 -290.535297)
		(end 388.496302 -290.611052)
		(width 0.09525)
		(layer "In11.Cu")
		(net "M_L_CPU0_SB_DQS_DP<3>")
	)
	(arc
		(start 391.6934 -290.611052)
		(mid 391.828985 -290.5546)
		(end 391.974578 -290.53536)
		(width 0.09525)
		(layer "In11.Cu")
		(net "M_L_CPU0_SB_DQS_DP<3>")
	)
	(arc
		(start 387.61416 -290.63823)
		(mid 387.776842 -290.660362)
		(end 387.933438 -290.611052)
		(width 0.09525)
		(layer "In11.Cu")
		(net "M_L_CPU0_SB_DQS_DP<3>")
	)
	(arc
		(start 390.753346 -290.611052)
		(mid 391.034778 -290.535297)
		(end 391.31621 -290.611052)
		(width 0.09525)
		(layer "In11.Cu")
		(net "M_L_CPU0_SB_DQS_DP<3>")
	)
	(arc
		(start 393.673076 -291.340286)
		(mid 393.811783 -291.509232)
		(end 393.914884 -291.701982)
		(width 0.09525)
		(layer "In11.Cu")
		(net "M_L_CPU0_SB_DQS_DP<3>")
	)
	(arc
		(start 388.873492 -290.611052)
		(mid 389.154924 -290.535297)
		(end 389.436356 -290.611052)
		(width 0.09525)
		(layer "In11.Cu")
		(net "M_L_CPU0_SB_DQS_DP<3>")
	)
	(segment
		(start 387.277864 -285.160212)
		(end 387.744716 -285.42615)
		(width 0.12954)
		(layer "F.Cu")
		(net "M_L_CPU0_SB_DQS_DP<2>")
	)
	(segment
		(start 420.490396 -303.709832)
		(end 420.818056 -304.037492)
		(width 0.16002)
		(layer "In11.Cu")
		(net "M_L_CPU0_SB_DQS_DP<2>")
	)
	(segment
		(start 392.255502 -285.75127)
		(end 392.263884 -285.756096)
		(width 0.09525)
		(layer "In11.Cu")
		(net "M_L_CPU0_SB_DQS_DP<2>")
	)
	(segment
		(start 453.914256 -303.85893)
		(end 454.188068 -303.585118)
		(width 0.16002)
		(layer "In11.Cu")
		(net "M_L_CPU0_SB_DQS_DP<2>")
	)
	(segment
		(start 445.408558 -303.214532)
		(end 445.763142 -302.859948)
		(width 0.16002)
		(layer "In11.Cu")
		(net "M_L_CPU0_SB_DQS_DP<2>")
	)
	(segment
		(start 422.776396 -303.214532)
		(end 423.13098 -302.859948)
		(width 0.16002)
		(layer "In11.Cu")
		(net "M_L_CPU0_SB_DQS_DP<2>")
	)
	(segment
		(start 443.450218 -304.037492)
		(end 444.174118 -304.037492)
		(width 0.16002)
		(layer "In11.Cu")
		(net "M_L_CPU0_SB_DQS_DP<2>")
	)
	(segment
		(start 420.818056 -304.037492)
		(end 421.541956 -304.037492)
		(width 0.16002)
		(layer "In11.Cu")
		(net "M_L_CPU0_SB_DQS_DP<2>")
	)
	(segment
		(start 410.638752 -304.037492)
		(end 413.997902 -304.037492)
		(width 0.16002)
		(layer "In11.Cu")
		(net "M_L_CPU0_SB_DQS_DP<2>")
	)
	(segment
		(start 394.710412 -286.418782)
		(end 395.281912 -286.418782)
		(width 0.09525)
		(layer "In11.Cu")
		(net "M_L_CPU0_SB_DQS_DP<2>")
	)
	(segment
		(start 436.630064 -304.037492)
		(end 437.453024 -303.214532)
		(width 0.16002)
		(layer "In11.Cu")
		(net "M_L_CPU0_SB_DQS_DP<2>")
	)
	(segment
		(start 415.232342 -303.214532)
		(end 415.586926 -302.859948)
		(width 0.16002)
		(layer "In11.Cu")
		(net "M_L_CPU0_SB_DQS_DP<2>")
	)
	(segment
		(start 393.384786 -285.803086)
		(end 394.094716 -285.803086)
		(width 0.09525)
		(layer "In11.Cu")
		(net "M_L_CPU0_SB_DQS_DP<2>")
	)
	(segment
		(start 447.672714 -302.859948)
		(end 448.466718 -303.653952)
		(width 0.16002)
		(layer "In11.Cu")
		(net "M_L_CPU0_SB_DQS_DP<2>")
	)
	(segment
		(start 448.466718 -303.653952)
		(end 450.888354 -303.653952)
		(width 0.16002)
		(layer "In11.Cu")
		(net "M_L_CPU0_SB_DQS_DP<2>")
	)
	(segment
		(start 428.03445 -303.709832)
		(end 428.36211 -304.037492)
		(width 0.16002)
		(layer "In11.Cu")
		(net "M_L_CPU0_SB_DQS_DP<2>")
	)
	(segment
		(start 422.364916 -303.214532)
		(end 422.776396 -303.214532)
		(width 0.16002)
		(layer "In11.Cu")
		(net "M_L_CPU0_SB_DQS_DP<2>")
	)
	(segment
		(start 451.701662 -304.052732)
		(end 451.895464 -303.85893)
		(width 0.16002)
		(layer "In11.Cu")
		(net "M_L_CPU0_SB_DQS_DP<2>")
	)
	(segment
		(start 391.31621 -285.75127)
		(end 391.324592 -285.756096)
		(width 0.09525)
		(layer "In11.Cu")
		(net "M_L_CPU0_SB_DQS_DP<2>")
	)
	(segment
		(start 414.820862 -303.214532)
		(end 415.232342 -303.214532)
		(width 0.16002)
		(layer "In11.Cu")
		(net "M_L_CPU0_SB_DQS_DP<2>")
	)
	(segment
		(start 390.744964 -285.756096)
		(end 390.753346 -285.75127)
		(width 0.09525)
		(layer "In11.Cu")
		(net "M_L_CPU0_SB_DQS_DP<2>")
	)
	(segment
		(start 429.08601 -304.037492)
		(end 429.90897 -303.214532)
		(width 0.16002)
		(layer "In11.Cu")
		(net "M_L_CPU0_SB_DQS_DP<2>")
	)
	(segment
		(start 395.776704 -286.637222)
		(end 395.835632 -286.578294)
		(width 0.09525)
		(layer "In11.Cu")
		(net "M_L_CPU0_SB_DQS_DP<2>")
	)
	(segment
		(start 440.12866 -302.859948)
		(end 440.978544 -303.709832)
		(width 0.16002)
		(layer "In11.Cu")
		(net "M_L_CPU0_SB_DQS_DP<2>")
	)
	(segment
		(start 437.864504 -303.214532)
		(end 438.219088 -302.859948)
		(width 0.16002)
		(layer "In11.Cu")
		(net "M_L_CPU0_SB_DQS_DP<2>")
	)
	(segment
		(start 435.906164 -304.037492)
		(end 436.630064 -304.037492)
		(width 0.16002)
		(layer "In11.Cu")
		(net "M_L_CPU0_SB_DQS_DP<2>")
	)
	(segment
		(start 402.002498 -295.401238)
		(end 410.638752 -304.037492)
		(width 0.16002)
		(layer "In11.Cu")
		(net "M_L_CPU0_SB_DQS_DP<2>")
	)
	(segment
		(start 450.888354 -303.653952)
		(end 451.287134 -304.052732)
		(width 0.16002)
		(layer "In11.Cu")
		(net "M_L_CPU0_SB_DQS_DP<2>")
	)
	(segment
		(start 423.13098 -302.859948)
		(end 425.040552 -302.859948)
		(width 0.16002)
		(layer "In11.Cu")
		(net "M_L_CPU0_SB_DQS_DP<2>")
	)
	(segment
		(start 433.43449 -303.709832)
		(end 435.578504 -303.709832)
		(width 0.16002)
		(layer "In11.Cu")
		(net "M_L_CPU0_SB_DQS_DP<2>")
	)
	(segment
		(start 432.584606 -302.859948)
		(end 433.43449 -303.709832)
		(width 0.16002)
		(layer "In11.Cu")
		(net "M_L_CPU0_SB_DQS_DP<2>")
	)
	(segment
		(start 429.90897 -303.214532)
		(end 430.32045 -303.214532)
		(width 0.16002)
		(layer "In11.Cu")
		(net "M_L_CPU0_SB_DQS_DP<2>")
	)
	(segment
		(start 444.997078 -303.214532)
		(end 445.408558 -303.214532)
		(width 0.16002)
		(layer "In11.Cu")
		(net "M_L_CPU0_SB_DQS_DP<2>")
	)
	(segment
		(start 428.36211 -304.037492)
		(end 429.08601 -304.037492)
		(width 0.16002)
		(layer "In11.Cu")
		(net "M_L_CPU0_SB_DQS_DP<2>")
	)
	(segment
		(start 453.293988 -303.85893)
		(end 453.914256 -303.85893)
		(width 0.16002)
		(layer "In11.Cu")
		(net "M_L_CPU0_SB_DQS_DP<2>")
	)
	(segment
		(start 395.859254 -286.578294)
		(end 396.110206 -286.578294)
		(width 0.16002)
		(layer "In11.Cu")
		(net "M_L_CPU0_SB_DQS_DP<2>")
	)
	(segment
		(start 418.346382 -303.709832)
		(end 420.490396 -303.709832)
		(width 0.16002)
		(layer "In11.Cu")
		(net "M_L_CPU0_SB_DQS_DP<2>")
	)
	(segment
		(start 395.835632 -286.578294)
		(end 395.859254 -286.578294)
		(width 0.09525)
		(layer "In11.Cu")
		(net "M_L_CPU0_SB_DQS_DP<2>")
	)
	(segment
		(start 388.496302 -285.75127)
		(end 388.504684 -285.756096)
		(width 0.09525)
		(layer "In11.Cu")
		(net "M_L_CPU0_SB_DQS_DP<2>")
	)
	(segment
		(start 417.496498 -302.859948)
		(end 418.346382 -303.709832)
		(width 0.16002)
		(layer "In11.Cu")
		(net "M_L_CPU0_SB_DQS_DP<2>")
	)
	(segment
		(start 443.122558 -303.709832)
		(end 443.450218 -304.037492)
		(width 0.16002)
		(layer "In11.Cu")
		(net "M_L_CPU0_SB_DQS_DP<2>")
	)
	(segment
		(start 444.174118 -304.037492)
		(end 444.997078 -303.214532)
		(width 0.16002)
		(layer "In11.Cu")
		(net "M_L_CPU0_SB_DQS_DP<2>")
	)
	(segment
		(start 402.002498 -292.470586)
		(end 402.002498 -295.401238)
		(width 0.16002)
		(layer "In11.Cu")
		(net "M_L_CPU0_SB_DQS_DP<2>")
	)
	(segment
		(start 395.500352 -286.637222)
		(end 395.776704 -286.637222)
		(width 0.09525)
		(layer "In11.Cu")
		(net "M_L_CPU0_SB_DQS_DP<2>")
	)
	(segment
		(start 437.453024 -303.214532)
		(end 437.864504 -303.214532)
		(width 0.16002)
		(layer "In11.Cu")
		(net "M_L_CPU0_SB_DQS_DP<2>")
	)
	(segment
		(start 453.166988 -303.73193)
		(end 453.293988 -303.85893)
		(width 0.16002)
		(layer "In11.Cu")
		(net "M_L_CPU0_SB_DQS_DP<2>")
	)
	(segment
		(start 451.287134 -304.052732)
		(end 451.701662 -304.052732)
		(width 0.16002)
		(layer "In11.Cu")
		(net "M_L_CPU0_SB_DQS_DP<2>")
	)
	(segment
		(start 438.219088 -302.859948)
		(end 440.12866 -302.859948)
		(width 0.16002)
		(layer "In11.Cu")
		(net "M_L_CPU0_SB_DQS_DP<2>")
	)
	(segment
		(start 392.632184 -285.75127)
		(end 392.650218 -285.740856)
		(width 0.09525)
		(layer "In11.Cu")
		(net "M_L_CPU0_SB_DQS_DP<2>")
	)
	(segment
		(start 435.578504 -303.709832)
		(end 435.906164 -304.037492)
		(width 0.16002)
		(layer "In11.Cu")
		(net "M_L_CPU0_SB_DQS_DP<2>")
	)
	(segment
		(start 387.744716 -285.42615)
		(end 387.590792 -285.69158)
		(width 0.09525)
		(layer "In11.Cu")
		(net "M_L_CPU0_SB_DQS_DP<2>")
	)
	(segment
		(start 395.281912 -286.418782)
		(end 395.500352 -286.637222)
		(width 0.09525)
		(layer "In11.Cu")
		(net "M_L_CPU0_SB_DQS_DP<2>")
	)
	(segment
		(start 421.541956 -304.037492)
		(end 422.364916 -303.214532)
		(width 0.16002)
		(layer "In11.Cu")
		(net "M_L_CPU0_SB_DQS_DP<2>")
	)
	(segment
		(start 387.590792 -285.69158)
		(end 387.61416 -285.778448)
		(width 0.09525)
		(layer "In11.Cu")
		(net "M_L_CPU0_SB_DQS_DP<2>")
	)
	(segment
		(start 425.890436 -303.709832)
		(end 428.03445 -303.709832)
		(width 0.16002)
		(layer "In11.Cu")
		(net "M_L_CPU0_SB_DQS_DP<2>")
	)
	(segment
		(start 452.559928 -303.85893)
		(end 452.686928 -303.73193)
		(width 0.16002)
		(layer "In11.Cu")
		(net "M_L_CPU0_SB_DQS_DP<2>")
	)
	(segment
		(start 430.32045 -303.214532)
		(end 430.675034 -302.859948)
		(width 0.16002)
		(layer "In11.Cu")
		(net "M_L_CPU0_SB_DQS_DP<2>")
	)
	(segment
		(start 392.237468 -285.740856)
		(end 392.255502 -285.75127)
		(width 0.09525)
		(layer "In11.Cu")
		(net "M_L_CPU0_SB_DQS_DP<2>")
	)
	(segment
		(start 413.997902 -304.037492)
		(end 414.820862 -303.214532)
		(width 0.16002)
		(layer "In11.Cu")
		(net "M_L_CPU0_SB_DQS_DP<2>")
	)
	(segment
		(start 396.110206 -286.578294)
		(end 402.002498 -292.470586)
		(width 0.16002)
		(layer "In11.Cu")
		(net "M_L_CPU0_SB_DQS_DP<2>")
	)
	(segment
		(start 451.895464 -303.85893)
		(end 452.559928 -303.85893)
		(width 0.16002)
		(layer "In11.Cu")
		(net "M_L_CPU0_SB_DQS_DP<2>")
	)
	(segment
		(start 425.040552 -302.859948)
		(end 425.890436 -303.709832)
		(width 0.16002)
		(layer "In11.Cu")
		(net "M_L_CPU0_SB_DQS_DP<2>")
	)
	(segment
		(start 440.978544 -303.709832)
		(end 443.122558 -303.709832)
		(width 0.16002)
		(layer "In11.Cu")
		(net "M_L_CPU0_SB_DQS_DP<2>")
	)
	(segment
		(start 445.763142 -302.859948)
		(end 447.672714 -302.859948)
		(width 0.16002)
		(layer "In11.Cu")
		(net "M_L_CPU0_SB_DQS_DP<2>")
	)
	(segment
		(start 430.675034 -302.859948)
		(end 432.584606 -302.859948)
		(width 0.16002)
		(layer "In11.Cu")
		(net "M_L_CPU0_SB_DQS_DP<2>")
	)
	(segment
		(start 394.094716 -285.803086)
		(end 394.710412 -286.418782)
		(width 0.09525)
		(layer "In11.Cu")
		(net "M_L_CPU0_SB_DQS_DP<2>")
	)
	(segment
		(start 415.586926 -302.859948)
		(end 417.496498 -302.859948)
		(width 0.16002)
		(layer "In11.Cu")
		(net "M_L_CPU0_SB_DQS_DP<2>")
	)
	(segment
		(start 452.686928 -303.73193)
		(end 453.166988 -303.73193)
		(width 0.16002)
		(layer "In11.Cu")
		(net "M_L_CPU0_SB_DQS_DP<2>")
	)
	(arc
		(start 393.19581 -285.75127)
		(mid 393.28687 -285.789666)
		(end 393.384786 -285.803086)
		(width 0.09525)
		(layer "In11.Cu")
		(net "M_L_CPU0_SB_DQS_DP<2>")
	)
	(arc
		(start 390.376156 -285.75127)
		(mid 390.559931 -285.802042)
		(end 390.744964 -285.756096)
		(width 0.09525)
		(layer "In11.Cu")
		(net "M_L_CPU0_SB_DQS_DP<2>")
	)
	(arc
		(start 390.753346 -285.75127)
		(mid 391.034778 -285.675515)
		(end 391.31621 -285.75127)
		(width 0.09525)
		(layer "In11.Cu")
		(net "M_L_CPU0_SB_DQS_DP<2>")
	)
	(arc
		(start 391.324592 -285.756096)
		(mid 391.509624 -285.80201)
		(end 391.6934 -285.75127)
		(width 0.09525)
		(layer "In11.Cu")
		(net "M_L_CPU0_SB_DQS_DP<2>")
	)
	(arc
		(start 388.504684 -285.756096)
		(mid 388.689716 -285.80201)
		(end 388.873492 -285.75127)
		(width 0.09525)
		(layer "In11.Cu")
		(net "M_L_CPU0_SB_DQS_DP<2>")
	)
	(arc
		(start 388.873492 -285.75127)
		(mid 389.154924 -285.675515)
		(end 389.436356 -285.75127)
		(width 0.09525)
		(layer "In11.Cu")
		(net "M_L_CPU0_SB_DQS_DP<2>")
	)
	(arc
		(start 387.933438 -285.75127)
		(mid 388.21487 -285.675515)
		(end 388.496302 -285.75127)
		(width 0.09525)
		(layer "In11.Cu")
		(net "M_L_CPU0_SB_DQS_DP<2>")
	)
	(arc
		(start 391.6934 -285.75127)
		(mid 391.964088 -285.675618)
		(end 392.237468 -285.740856)
		(width 0.09525)
		(layer "In11.Cu")
		(net "M_L_CPU0_SB_DQS_DP<2>")
	)
	(arc
		(start 389.813292 -285.75127)
		(mid 390.094724 -285.675515)
		(end 390.376156 -285.75127)
		(width 0.09525)
		(layer "In11.Cu")
		(net "M_L_CPU0_SB_DQS_DP<2>")
	)
	(arc
		(start 392.263884 -285.756096)
		(mid 392.448662 -285.801889)
		(end 392.632184 -285.75127)
		(width 0.09525)
		(layer "In11.Cu")
		(net "M_L_CPU0_SB_DQS_DP<2>")
	)
	(arc
		(start 392.650218 -285.740856)
		(mid 392.92436 -285.675277)
		(end 393.19581 -285.75127)
		(width 0.09525)
		(layer "In11.Cu")
		(net "M_L_CPU0_SB_DQS_DP<2>")
	)
	(arc
		(start 387.61416 -285.778448)
		(mid 387.776842 -285.80058)
		(end 387.933438 -285.75127)
		(width 0.09525)
		(layer "In11.Cu")
		(net "M_L_CPU0_SB_DQS_DP<2>")
	)
	(arc
		(start 389.436356 -285.75127)
		(mid 389.624824 -285.801947)
		(end 389.813292 -285.75127)
		(width 0.09525)
		(layer "In11.Cu")
		(net "M_L_CPU0_SB_DQS_DP<2>")
	)
	(segment
		(start 387.277864 -280.300176)
		(end 387.744716 -280.566114)
		(width 0.12954)
		(layer "F.Cu")
		(net "M_L_CPU0_SB_DQS_DP<1>")
	)
	(segment
		(start 387.590792 -280.831544)
		(end 387.61416 -280.918412)
		(width 0.09525)
		(layer "In11.Cu")
		(net "M_L_CPU0_SB_DQS_DP<1>")
	)
	(segment
		(start 428.03445 -294.359838)
		(end 428.36211 -294.687498)
		(width 0.16002)
		(layer "In11.Cu")
		(net "M_L_CPU0_SB_DQS_DP<1>")
	)
	(segment
		(start 391.31621 -280.891234)
		(end 391.324592 -280.89606)
		(width 0.09525)
		(layer "In11.Cu")
		(net "M_L_CPU0_SB_DQS_DP<1>")
	)
	(segment
		(start 395.77645 -280.985722)
		(end 395.835632 -280.92654)
		(width 0.09525)
		(layer "In11.Cu")
		(net "M_L_CPU0_SB_DQS_DP<1>")
	)
	(segment
		(start 429.90897 -293.864538)
		(end 430.32045 -293.864538)
		(width 0.16002)
		(layer "In11.Cu")
		(net "M_L_CPU0_SB_DQS_DP<1>")
	)
	(segment
		(start 430.32045 -293.864538)
		(end 430.675034 -293.509954)
		(width 0.16002)
		(layer "In11.Cu")
		(net "M_L_CPU0_SB_DQS_DP<1>")
	)
	(segment
		(start 395.650466 -280.985722)
		(end 395.77645 -280.985722)
		(width 0.09525)
		(layer "In11.Cu")
		(net "M_L_CPU0_SB_DQS_DP<1>")
	)
	(segment
		(start 435.578504 -294.359838)
		(end 435.906164 -294.687498)
		(width 0.16002)
		(layer "In11.Cu")
		(net "M_L_CPU0_SB_DQS_DP<1>")
	)
	(segment
		(start 420.490396 -294.359838)
		(end 420.818056 -294.687498)
		(width 0.16002)
		(layer "In11.Cu")
		(net "M_L_CPU0_SB_DQS_DP<1>")
	)
	(segment
		(start 412.146242 -294.687498)
		(end 413.997902 -294.687498)
		(width 0.16002)
		(layer "In11.Cu")
		(net "M_L_CPU0_SB_DQS_DP<1>")
	)
	(segment
		(start 395.835632 -280.92654)
		(end 395.859254 -280.92654)
		(width 0.09525)
		(layer "In11.Cu")
		(net "M_L_CPU0_SB_DQS_DP<1>")
	)
	(segment
		(start 447.672714 -293.509954)
		(end 448.246754 -294.083994)
		(width 0.16002)
		(layer "In11.Cu")
		(net "M_L_CPU0_SB_DQS_DP<1>")
	)
	(segment
		(start 414.820862 -293.864538)
		(end 415.232342 -293.864538)
		(width 0.16002)
		(layer "In11.Cu")
		(net "M_L_CPU0_SB_DQS_DP<1>")
	)
	(segment
		(start 451.701662 -294.702738)
		(end 451.895464 -294.508936)
		(width 0.16002)
		(layer "In11.Cu")
		(net "M_L_CPU0_SB_DQS_DP<1>")
	)
	(segment
		(start 451.287134 -294.702738)
		(end 451.701662 -294.702738)
		(width 0.16002)
		(layer "In11.Cu")
		(net "M_L_CPU0_SB_DQS_DP<1>")
	)
	(segment
		(start 417.496498 -293.509954)
		(end 418.346382 -294.359838)
		(width 0.16002)
		(layer "In11.Cu")
		(net "M_L_CPU0_SB_DQS_DP<1>")
	)
	(segment
		(start 437.864504 -293.864538)
		(end 438.219088 -293.509954)
		(width 0.16002)
		(layer "In11.Cu")
		(net "M_L_CPU0_SB_DQS_DP<1>")
	)
	(segment
		(start 452.697088 -294.381936)
		(end 453.177148 -294.381936)
		(width 0.16002)
		(layer "In11.Cu")
		(net "M_L_CPU0_SB_DQS_DP<1>")
	)
	(segment
		(start 392.237468 -280.88082)
		(end 392.255502 -280.891234)
		(width 0.09525)
		(layer "In11.Cu")
		(net "M_L_CPU0_SB_DQS_DP<1>")
	)
	(segment
		(start 395.199616 -280.534872)
		(end 395.650466 -280.985722)
		(width 0.09525)
		(layer "In11.Cu")
		(net "M_L_CPU0_SB_DQS_DP<1>")
	)
	(segment
		(start 430.675034 -293.509954)
		(end 432.584606 -293.509954)
		(width 0.16002)
		(layer "In11.Cu")
		(net "M_L_CPU0_SB_DQS_DP<1>")
	)
	(segment
		(start 390.744964 -280.89606)
		(end 390.753346 -280.891234)
		(width 0.09525)
		(layer "In11.Cu")
		(net "M_L_CPU0_SB_DQS_DP<1>")
	)
	(segment
		(start 433.43449 -294.359838)
		(end 435.578504 -294.359838)
		(width 0.16002)
		(layer "In11.Cu")
		(net "M_L_CPU0_SB_DQS_DP<1>")
	)
	(segment
		(start 422.364916 -293.864538)
		(end 422.776396 -293.864538)
		(width 0.16002)
		(layer "In11.Cu")
		(net "M_L_CPU0_SB_DQS_DP<1>")
	)
	(segment
		(start 435.906164 -294.687498)
		(end 436.630064 -294.687498)
		(width 0.16002)
		(layer "In11.Cu")
		(net "M_L_CPU0_SB_DQS_DP<1>")
	)
	(segment
		(start 444.174118 -294.687498)
		(end 444.997078 -293.864538)
		(width 0.16002)
		(layer "In11.Cu")
		(net "M_L_CPU0_SB_DQS_DP<1>")
	)
	(segment
		(start 444.997078 -293.864538)
		(end 445.408558 -293.864538)
		(width 0.16002)
		(layer "In11.Cu")
		(net "M_L_CPU0_SB_DQS_DP<1>")
	)
	(segment
		(start 451.895464 -294.508936)
		(end 452.570088 -294.508936)
		(width 0.16002)
		(layer "In11.Cu")
		(net "M_L_CPU0_SB_DQS_DP<1>")
	)
	(segment
		(start 440.978544 -294.359838)
		(end 443.122558 -294.359838)
		(width 0.16002)
		(layer "In11.Cu")
		(net "M_L_CPU0_SB_DQS_DP<1>")
	)
	(segment
		(start 387.744716 -280.566114)
		(end 387.590792 -280.831544)
		(width 0.09525)
		(layer "In11.Cu")
		(net "M_L_CPU0_SB_DQS_DP<1>")
	)
	(segment
		(start 448.246754 -294.083994)
		(end 450.66839 -294.083994)
		(width 0.16002)
		(layer "In11.Cu")
		(net "M_L_CPU0_SB_DQS_DP<1>")
	)
	(segment
		(start 453.914256 -294.508936)
		(end 454.188068 -294.235124)
		(width 0.16002)
		(layer "In11.Cu")
		(net "M_L_CPU0_SB_DQS_DP<1>")
	)
	(segment
		(start 438.219088 -293.509954)
		(end 440.12866 -293.509954)
		(width 0.16002)
		(layer "In11.Cu")
		(net "M_L_CPU0_SB_DQS_DP<1>")
	)
	(segment
		(start 421.541956 -294.687498)
		(end 422.364916 -293.864538)
		(width 0.16002)
		(layer "In11.Cu")
		(net "M_L_CPU0_SB_DQS_DP<1>")
	)
	(segment
		(start 425.040552 -293.509954)
		(end 425.890436 -294.359838)
		(width 0.16002)
		(layer "In11.Cu")
		(net "M_L_CPU0_SB_DQS_DP<1>")
	)
	(segment
		(start 415.586926 -293.509954)
		(end 417.496498 -293.509954)
		(width 0.16002)
		(layer "In11.Cu")
		(net "M_L_CPU0_SB_DQS_DP<1>")
	)
	(segment
		(start 422.776396 -293.864538)
		(end 423.13098 -293.509954)
		(width 0.16002)
		(layer "In11.Cu")
		(net "M_L_CPU0_SB_DQS_DP<1>")
	)
	(segment
		(start 393.384786 -280.94305)
		(end 393.79652 -280.94305)
		(width 0.09525)
		(layer "In11.Cu")
		(net "M_L_CPU0_SB_DQS_DP<1>")
	)
	(segment
		(start 394.204698 -280.534872)
		(end 395.199616 -280.534872)
		(width 0.09525)
		(layer "In11.Cu")
		(net "M_L_CPU0_SB_DQS_DP<1>")
	)
	(segment
		(start 425.890436 -294.359838)
		(end 428.03445 -294.359838)
		(width 0.16002)
		(layer "In11.Cu")
		(net "M_L_CPU0_SB_DQS_DP<1>")
	)
	(segment
		(start 413.997902 -294.687498)
		(end 414.820862 -293.864538)
		(width 0.16002)
		(layer "In11.Cu")
		(net "M_L_CPU0_SB_DQS_DP<1>")
	)
	(segment
		(start 429.08601 -294.687498)
		(end 429.90897 -293.864538)
		(width 0.16002)
		(layer "In11.Cu")
		(net "M_L_CPU0_SB_DQS_DP<1>")
	)
	(segment
		(start 395.859254 -280.92654)
		(end 398.385284 -280.92654)
		(width 0.16002)
		(layer "In11.Cu")
		(net "M_L_CPU0_SB_DQS_DP<1>")
	)
	(segment
		(start 445.408558 -293.864538)
		(end 445.763142 -293.509954)
		(width 0.16002)
		(layer "In11.Cu")
		(net "M_L_CPU0_SB_DQS_DP<1>")
	)
	(segment
		(start 450.66839 -294.083994)
		(end 451.287134 -294.702738)
		(width 0.16002)
		(layer "In11.Cu")
		(net "M_L_CPU0_SB_DQS_DP<1>")
	)
	(segment
		(start 436.630064 -294.687498)
		(end 437.453024 -293.864538)
		(width 0.16002)
		(layer "In11.Cu")
		(net "M_L_CPU0_SB_DQS_DP<1>")
	)
	(segment
		(start 393.79652 -280.94305)
		(end 394.204698 -280.534872)
		(width 0.09525)
		(layer "In11.Cu")
		(net "M_L_CPU0_SB_DQS_DP<1>")
	)
	(segment
		(start 415.232342 -293.864538)
		(end 415.586926 -293.509954)
		(width 0.16002)
		(layer "In11.Cu")
		(net "M_L_CPU0_SB_DQS_DP<1>")
	)
	(segment
		(start 452.570088 -294.508936)
		(end 452.697088 -294.381936)
		(width 0.16002)
		(layer "In11.Cu")
		(net "M_L_CPU0_SB_DQS_DP<1>")
	)
	(segment
		(start 423.13098 -293.509954)
		(end 425.040552 -293.509954)
		(width 0.16002)
		(layer "In11.Cu")
		(net "M_L_CPU0_SB_DQS_DP<1>")
	)
	(segment
		(start 440.12866 -293.509954)
		(end 440.978544 -294.359838)
		(width 0.16002)
		(layer "In11.Cu")
		(net "M_L_CPU0_SB_DQS_DP<1>")
	)
	(segment
		(start 437.453024 -293.864538)
		(end 437.864504 -293.864538)
		(width 0.16002)
		(layer "In11.Cu")
		(net "M_L_CPU0_SB_DQS_DP<1>")
	)
	(segment
		(start 388.496302 -280.891234)
		(end 388.504684 -280.89606)
		(width 0.09525)
		(layer "In11.Cu")
		(net "M_L_CPU0_SB_DQS_DP<1>")
	)
	(segment
		(start 453.177148 -294.381936)
		(end 453.304148 -294.508936)
		(width 0.16002)
		(layer "In11.Cu")
		(net "M_L_CPU0_SB_DQS_DP<1>")
	)
	(segment
		(start 418.346382 -294.359838)
		(end 420.490396 -294.359838)
		(width 0.16002)
		(layer "In11.Cu")
		(net "M_L_CPU0_SB_DQS_DP<1>")
	)
	(segment
		(start 392.632184 -280.891234)
		(end 392.650218 -280.88082)
		(width 0.09525)
		(layer "In11.Cu")
		(net "M_L_CPU0_SB_DQS_DP<1>")
	)
	(segment
		(start 443.450218 -294.687498)
		(end 444.174118 -294.687498)
		(width 0.16002)
		(layer "In11.Cu")
		(net "M_L_CPU0_SB_DQS_DP<1>")
	)
	(segment
		(start 420.818056 -294.687498)
		(end 421.541956 -294.687498)
		(width 0.16002)
		(layer "In11.Cu")
		(net "M_L_CPU0_SB_DQS_DP<1>")
	)
	(segment
		(start 443.122558 -294.359838)
		(end 443.450218 -294.687498)
		(width 0.16002)
		(layer "In11.Cu")
		(net "M_L_CPU0_SB_DQS_DP<1>")
	)
	(segment
		(start 445.763142 -293.509954)
		(end 447.672714 -293.509954)
		(width 0.16002)
		(layer "In11.Cu")
		(net "M_L_CPU0_SB_DQS_DP<1>")
	)
	(segment
		(start 453.304148 -294.508936)
		(end 453.914256 -294.508936)
		(width 0.16002)
		(layer "In11.Cu")
		(net "M_L_CPU0_SB_DQS_DP<1>")
	)
	(segment
		(start 398.385284 -280.92654)
		(end 412.146242 -294.687498)
		(width 0.16002)
		(layer "In11.Cu")
		(net "M_L_CPU0_SB_DQS_DP<1>")
	)
	(segment
		(start 432.584606 -293.509954)
		(end 433.43449 -294.359838)
		(width 0.16002)
		(layer "In11.Cu")
		(net "M_L_CPU0_SB_DQS_DP<1>")
	)
	(segment
		(start 428.36211 -294.687498)
		(end 429.08601 -294.687498)
		(width 0.16002)
		(layer "In11.Cu")
		(net "M_L_CPU0_SB_DQS_DP<1>")
	)
	(segment
		(start 392.255502 -280.891234)
		(end 392.263884 -280.89606)
		(width 0.09525)
		(layer "In11.Cu")
		(net "M_L_CPU0_SB_DQS_DP<1>")
	)
	(arc
		(start 390.753346 -280.891234)
		(mid 391.034778 -280.815479)
		(end 391.31621 -280.891234)
		(width 0.09525)
		(layer "In11.Cu")
		(net "M_L_CPU0_SB_DQS_DP<1>")
	)
	(arc
		(start 392.263884 -280.89606)
		(mid 392.448662 -280.941853)
		(end 392.632184 -280.891234)
		(width 0.09525)
		(layer "In11.Cu")
		(net "M_L_CPU0_SB_DQS_DP<1>")
	)
	(arc
		(start 387.933438 -280.891234)
		(mid 388.21487 -280.815479)
		(end 388.496302 -280.891234)
		(width 0.09525)
		(layer "In11.Cu")
		(net "M_L_CPU0_SB_DQS_DP<1>")
	)
	(arc
		(start 390.376156 -280.891234)
		(mid 390.559931 -280.942006)
		(end 390.744964 -280.89606)
		(width 0.09525)
		(layer "In11.Cu")
		(net "M_L_CPU0_SB_DQS_DP<1>")
	)
	(arc
		(start 393.19581 -280.891234)
		(mid 393.28687 -280.92963)
		(end 393.384786 -280.94305)
		(width 0.09525)
		(layer "In11.Cu")
		(net "M_L_CPU0_SB_DQS_DP<1>")
	)
	(arc
		(start 389.436356 -280.891234)
		(mid 389.624824 -280.941911)
		(end 389.813292 -280.891234)
		(width 0.09525)
		(layer "In11.Cu")
		(net "M_L_CPU0_SB_DQS_DP<1>")
	)
	(arc
		(start 388.504684 -280.89606)
		(mid 388.689716 -280.941974)
		(end 388.873492 -280.891234)
		(width 0.09525)
		(layer "In11.Cu")
		(net "M_L_CPU0_SB_DQS_DP<1>")
	)
	(arc
		(start 391.324592 -280.89606)
		(mid 391.509624 -280.941974)
		(end 391.6934 -280.891234)
		(width 0.09525)
		(layer "In11.Cu")
		(net "M_L_CPU0_SB_DQS_DP<1>")
	)
	(arc
		(start 388.873492 -280.891234)
		(mid 389.154924 -280.815479)
		(end 389.436356 -280.891234)
		(width 0.09525)
		(layer "In11.Cu")
		(net "M_L_CPU0_SB_DQS_DP<1>")
	)
	(arc
		(start 391.6934 -280.891234)
		(mid 391.964088 -280.815582)
		(end 392.237468 -280.88082)
		(width 0.09525)
		(layer "In11.Cu")
		(net "M_L_CPU0_SB_DQS_DP<1>")
	)
	(arc
		(start 387.61416 -280.918412)
		(mid 387.776842 -280.940544)
		(end 387.933438 -280.891234)
		(width 0.09525)
		(layer "In11.Cu")
		(net "M_L_CPU0_SB_DQS_DP<1>")
	)
	(arc
		(start 392.650218 -280.88082)
		(mid 392.92436 -280.815241)
		(end 393.19581 -280.891234)
		(width 0.09525)
		(layer "In11.Cu")
		(net "M_L_CPU0_SB_DQS_DP<1>")
	)
	(arc
		(start 389.813292 -280.891234)
		(mid 390.094724 -280.815479)
		(end 390.376156 -280.891234)
		(width 0.09525)
		(layer "In11.Cu")
		(net "M_L_CPU0_SB_DQS_DP<1>")
	)
	(segment
		(start 387.277864 -275.44014)
		(end 387.744716 -275.706078)
		(width 0.12954)
		(layer "F.Cu")
		(net "M_L_CPU0_SB_DQS_DP<0>")
	)
	(segment
		(start 444.174118 -285.337504)
		(end 444.997078 -284.514544)
		(width 0.16002)
		(layer "In11.Cu")
		(net "M_L_CPU0_SB_DQS_DP<0>")
	)
	(segment
		(start 437.453024 -284.514544)
		(end 437.864504 -284.514544)
		(width 0.16002)
		(layer "In11.Cu")
		(net "M_L_CPU0_SB_DQS_DP<0>")
	)
	(segment
		(start 452.700136 -285.158942)
		(end 452.827136 -285.031942)
		(width 0.16002)
		(layer "In11.Cu")
		(net "M_L_CPU0_SB_DQS_DP<0>")
	)
	(segment
		(start 417.857686 -284.15996)
		(end 418.70757 -285.009844)
		(width 0.16002)
		(layer "In11.Cu")
		(net "M_L_CPU0_SB_DQS_DP<0>")
	)
	(segment
		(start 395.332966 -274.956524)
		(end 395.776704 -274.956524)
		(width 0.09525)
		(layer "In11.Cu")
		(net "M_L_CPU0_SB_DQS_DP<0>")
	)
	(segment
		(start 428.36211 -285.337504)
		(end 429.08601 -285.337504)
		(width 0.16002)
		(layer "In11.Cu")
		(net "M_L_CPU0_SB_DQS_DP<0>")
	)
	(segment
		(start 420.490396 -285.009844)
		(end 420.818056 -285.337504)
		(width 0.16002)
		(layer "In11.Cu")
		(net "M_L_CPU0_SB_DQS_DP<0>")
	)
	(segment
		(start 395.859254 -274.897596)
		(end 400.778726 -274.897596)
		(width 0.16002)
		(layer "In11.Cu")
		(net "M_L_CPU0_SB_DQS_DP<0>")
	)
	(segment
		(start 390.744964 -276.036024)
		(end 390.753346 -276.031198)
		(width 0.09525)
		(layer "In11.Cu")
		(net "M_L_CPU0_SB_DQS_DP<0>")
	)
	(segment
		(start 435.578504 -285.009844)
		(end 435.906164 -285.337504)
		(width 0.16002)
		(layer "In11.Cu")
		(net "M_L_CPU0_SB_DQS_DP<0>")
	)
	(segment
		(start 453.914256 -285.158942)
		(end 454.188068 -284.88513)
		(width 0.16002)
		(layer "In11.Cu")
		(net "M_L_CPU0_SB_DQS_DP<0>")
	)
	(segment
		(start 430.675034 -284.15996)
		(end 432.584606 -284.15996)
		(width 0.16002)
		(layer "In11.Cu")
		(net "M_L_CPU0_SB_DQS_DP<0>")
	)
	(segment
		(start 412.986474 -284.76448)
		(end 413.559498 -285.337504)
		(width 0.16002)
		(layer "In11.Cu")
		(net "M_L_CPU0_SB_DQS_DP<0>")
	)
	(segment
		(start 400.778726 -274.897596)
		(end 410.64561 -284.76448)
		(width 0.16002)
		(layer "In11.Cu")
		(net "M_L_CPU0_SB_DQS_DP<0>")
	)
	(segment
		(start 395.776704 -274.956524)
		(end 395.835632 -274.897596)
		(width 0.09525)
		(layer "In11.Cu")
		(net "M_L_CPU0_SB_DQS_DP<0>")
	)
	(segment
		(start 425.040552 -284.15996)
		(end 425.890436 -285.009844)
		(width 0.16002)
		(layer "In11.Cu")
		(net "M_L_CPU0_SB_DQS_DP<0>")
	)
	(segment
		(start 450.66839 -284.734)
		(end 451.287134 -285.352744)
		(width 0.16002)
		(layer "In11.Cu")
		(net "M_L_CPU0_SB_DQS_DP<0>")
	)
	(segment
		(start 428.03445 -285.009844)
		(end 428.36211 -285.337504)
		(width 0.16002)
		(layer "In11.Cu")
		(net "M_L_CPU0_SB_DQS_DP<0>")
	)
	(segment
		(start 438.219088 -284.15996)
		(end 440.12866 -284.15996)
		(width 0.16002)
		(layer "In11.Cu")
		(net "M_L_CPU0_SB_DQS_DP<0>")
	)
	(segment
		(start 388.496302 -276.031198)
		(end 388.504684 -276.036024)
		(width 0.09525)
		(layer "In11.Cu")
		(net "M_L_CPU0_SB_DQS_DP<0>")
	)
	(segment
		(start 415.586926 -284.15996)
		(end 417.857686 -284.15996)
		(width 0.16002)
		(layer "In11.Cu")
		(net "M_L_CPU0_SB_DQS_DP<0>")
	)
	(segment
		(start 436.630064 -285.337504)
		(end 437.453024 -284.514544)
		(width 0.16002)
		(layer "In11.Cu")
		(net "M_L_CPU0_SB_DQS_DP<0>")
	)
	(segment
		(start 445.408558 -284.514544)
		(end 445.763142 -284.15996)
		(width 0.16002)
		(layer "In11.Cu")
		(net "M_L_CPU0_SB_DQS_DP<0>")
	)
	(segment
		(start 393.555982 -276.04085)
		(end 393.572746 -276.031198)
		(width 0.09525)
		(layer "In11.Cu")
		(net "M_L_CPU0_SB_DQS_DP<0>")
	)
	(segment
		(start 387.590792 -275.971508)
		(end 387.61416 -276.058376)
		(width 0.09525)
		(layer "In11.Cu")
		(net "M_L_CPU0_SB_DQS_DP<0>")
	)
	(segment
		(start 420.818056 -285.337504)
		(end 421.541956 -285.337504)
		(width 0.16002)
		(layer "In11.Cu")
		(net "M_L_CPU0_SB_DQS_DP<0>")
	)
	(segment
		(start 429.08601 -285.337504)
		(end 429.90897 -284.514544)
		(width 0.16002)
		(layer "In11.Cu")
		(net "M_L_CPU0_SB_DQS_DP<0>")
	)
	(segment
		(start 447.672714 -284.15996)
		(end 448.246754 -284.734)
		(width 0.16002)
		(layer "In11.Cu")
		(net "M_L_CPU0_SB_DQS_DP<0>")
	)
	(segment
		(start 430.32045 -284.514544)
		(end 430.675034 -284.15996)
		(width 0.16002)
		(layer "In11.Cu")
		(net "M_L_CPU0_SB_DQS_DP<0>")
	)
	(segment
		(start 448.246754 -284.734)
		(end 450.66839 -284.734)
		(width 0.16002)
		(layer "In11.Cu")
		(net "M_L_CPU0_SB_DQS_DP<0>")
	)
	(segment
		(start 413.559498 -285.337504)
		(end 413.997902 -285.337504)
		(width 0.16002)
		(layer "In11.Cu")
		(net "M_L_CPU0_SB_DQS_DP<0>")
	)
	(segment
		(start 423.13098 -284.15996)
		(end 425.040552 -284.15996)
		(width 0.16002)
		(layer "In11.Cu")
		(net "M_L_CPU0_SB_DQS_DP<0>")
	)
	(segment
		(start 452.827136 -285.031942)
		(end 453.307196 -285.031942)
		(width 0.16002)
		(layer "In11.Cu")
		(net "M_L_CPU0_SB_DQS_DP<0>")
	)
	(segment
		(start 422.364916 -284.514544)
		(end 422.776396 -284.514544)
		(width 0.16002)
		(layer "In11.Cu")
		(net "M_L_CPU0_SB_DQS_DP<0>")
	)
	(segment
		(start 440.12866 -284.15996)
		(end 440.978544 -285.009844)
		(width 0.16002)
		(layer "In11.Cu")
		(net "M_L_CPU0_SB_DQS_DP<0>")
	)
	(segment
		(start 422.776396 -284.514544)
		(end 423.13098 -284.15996)
		(width 0.16002)
		(layer "In11.Cu")
		(net "M_L_CPU0_SB_DQS_DP<0>")
	)
	(segment
		(start 415.232342 -284.514544)
		(end 415.586926 -284.15996)
		(width 0.16002)
		(layer "In11.Cu")
		(net "M_L_CPU0_SB_DQS_DP<0>")
	)
	(segment
		(start 418.70757 -285.009844)
		(end 420.490396 -285.009844)
		(width 0.16002)
		(layer "In11.Cu")
		(net "M_L_CPU0_SB_DQS_DP<0>")
	)
	(segment
		(start 435.906164 -285.337504)
		(end 436.630064 -285.337504)
		(width 0.16002)
		(layer "In11.Cu")
		(net "M_L_CPU0_SB_DQS_DP<0>")
	)
	(segment
		(start 432.584606 -284.15996)
		(end 433.43449 -285.009844)
		(width 0.16002)
		(layer "In11.Cu")
		(net "M_L_CPU0_SB_DQS_DP<0>")
	)
	(segment
		(start 391.31621 -276.031198)
		(end 391.324592 -276.036024)
		(width 0.09525)
		(layer "In11.Cu")
		(net "M_L_CPU0_SB_DQS_DP<0>")
	)
	(segment
		(start 437.864504 -284.514544)
		(end 438.219088 -284.15996)
		(width 0.16002)
		(layer "In11.Cu")
		(net "M_L_CPU0_SB_DQS_DP<0>")
	)
	(segment
		(start 451.701662 -285.352744)
		(end 451.895464 -285.158942)
		(width 0.16002)
		(layer "In11.Cu")
		(net "M_L_CPU0_SB_DQS_DP<0>")
	)
	(segment
		(start 410.64561 -284.76448)
		(end 412.986474 -284.76448)
		(width 0.16002)
		(layer "In11.Cu")
		(net "M_L_CPU0_SB_DQS_DP<0>")
	)
	(segment
		(start 387.744716 -275.706078)
		(end 387.590792 -275.971508)
		(width 0.09525)
		(layer "In11.Cu")
		(net "M_L_CPU0_SB_DQS_DP<0>")
	)
	(segment
		(start 453.307196 -285.031942)
		(end 453.434196 -285.158942)
		(width 0.16002)
		(layer "In11.Cu")
		(net "M_L_CPU0_SB_DQS_DP<0>")
	)
	(segment
		(start 392.255502 -276.031198)
		(end 392.263884 -276.036024)
		(width 0.09525)
		(layer "In11.Cu")
		(net "M_L_CPU0_SB_DQS_DP<0>")
	)
	(segment
		(start 451.895464 -285.158942)
		(end 452.700136 -285.158942)
		(width 0.16002)
		(layer "In11.Cu")
		(net "M_L_CPU0_SB_DQS_DP<0>")
	)
	(segment
		(start 395.835632 -274.897596)
		(end 395.859254 -274.897596)
		(width 0.09525)
		(layer "In11.Cu")
		(net "M_L_CPU0_SB_DQS_DP<0>")
	)
	(segment
		(start 451.287134 -285.352744)
		(end 451.701662 -285.352744)
		(width 0.16002)
		(layer "In11.Cu")
		(net "M_L_CPU0_SB_DQS_DP<0>")
	)
	(segment
		(start 444.997078 -284.514544)
		(end 445.408558 -284.514544)
		(width 0.16002)
		(layer "In11.Cu")
		(net "M_L_CPU0_SB_DQS_DP<0>")
	)
	(segment
		(start 443.122558 -285.009844)
		(end 443.450218 -285.337504)
		(width 0.16002)
		(layer "In11.Cu")
		(net "M_L_CPU0_SB_DQS_DP<0>")
	)
	(segment
		(start 414.820862 -284.514544)
		(end 415.232342 -284.514544)
		(width 0.16002)
		(layer "In11.Cu")
		(net "M_L_CPU0_SB_DQS_DP<0>")
	)
	(segment
		(start 445.763142 -284.15996)
		(end 447.672714 -284.15996)
		(width 0.16002)
		(layer "In11.Cu")
		(net "M_L_CPU0_SB_DQS_DP<0>")
	)
	(segment
		(start 453.434196 -285.158942)
		(end 453.914256 -285.158942)
		(width 0.16002)
		(layer "In11.Cu")
		(net "M_L_CPU0_SB_DQS_DP<0>")
	)
	(segment
		(start 421.541956 -285.337504)
		(end 422.364916 -284.514544)
		(width 0.16002)
		(layer "In11.Cu")
		(net "M_L_CPU0_SB_DQS_DP<0>")
	)
	(segment
		(start 395.213078 -275.076412)
		(end 395.332966 -274.956524)
		(width 0.09525)
		(layer "In11.Cu")
		(net "M_L_CPU0_SB_DQS_DP<0>")
	)
	(segment
		(start 440.978544 -285.009844)
		(end 443.122558 -285.009844)
		(width 0.16002)
		(layer "In11.Cu")
		(net "M_L_CPU0_SB_DQS_DP<0>")
	)
	(segment
		(start 429.90897 -284.514544)
		(end 430.32045 -284.514544)
		(width 0.16002)
		(layer "In11.Cu")
		(net "M_L_CPU0_SB_DQS_DP<0>")
	)
	(segment
		(start 392.237468 -276.020784)
		(end 392.255502 -276.031198)
		(width 0.09525)
		(layer "In11.Cu")
		(net "M_L_CPU0_SB_DQS_DP<0>")
	)
	(segment
		(start 394.546328 -275.076412)
		(end 395.213078 -275.076412)
		(width 0.09525)
		(layer "In11.Cu")
		(net "M_L_CPU0_SB_DQS_DP<0>")
	)
	(segment
		(start 443.450218 -285.337504)
		(end 444.174118 -285.337504)
		(width 0.16002)
		(layer "In11.Cu")
		(net "M_L_CPU0_SB_DQS_DP<0>")
	)
	(segment
		(start 433.43449 -285.009844)
		(end 435.578504 -285.009844)
		(width 0.16002)
		(layer "In11.Cu")
		(net "M_L_CPU0_SB_DQS_DP<0>")
	)
	(segment
		(start 393.650724 -275.972016)
		(end 394.546328 -275.076412)
		(width 0.09525)
		(layer "In11.Cu")
		(net "M_L_CPU0_SB_DQS_DP<0>")
	)
	(segment
		(start 425.890436 -285.009844)
		(end 428.03445 -285.009844)
		(width 0.16002)
		(layer "In11.Cu")
		(net "M_L_CPU0_SB_DQS_DP<0>")
	)
	(segment
		(start 413.997902 -285.337504)
		(end 414.820862 -284.514544)
		(width 0.16002)
		(layer "In11.Cu")
		(net "M_L_CPU0_SB_DQS_DP<0>")
	)
	(segment
		(start 392.632184 -276.031198)
		(end 392.650218 -276.020784)
		(width 0.09525)
		(layer "In11.Cu")
		(net "M_L_CPU0_SB_DQS_DP<0>")
	)
	(arc
		(start 393.19581 -276.031198)
		(mid 393.37467 -276.081994)
		(end 393.555982 -276.04085)
		(width 0.09525)
		(layer "In11.Cu")
		(net "M_L_CPU0_SB_DQS_DP<0>")
	)
	(arc
		(start 387.933438 -276.031198)
		(mid 388.21487 -275.955443)
		(end 388.496302 -276.031198)
		(width 0.09525)
		(layer "In11.Cu")
		(net "M_L_CPU0_SB_DQS_DP<0>")
	)
	(arc
		(start 391.324592 -276.036024)
		(mid 391.509624 -276.081938)
		(end 391.6934 -276.031198)
		(width 0.09525)
		(layer "In11.Cu")
		(net "M_L_CPU0_SB_DQS_DP<0>")
	)
	(arc
		(start 387.61416 -276.058376)
		(mid 387.776842 -276.080508)
		(end 387.933438 -276.031198)
		(width 0.09525)
		(layer "In11.Cu")
		(net "M_L_CPU0_SB_DQS_DP<0>")
	)
	(arc
		(start 392.650218 -276.020784)
		(mid 392.92436 -275.955205)
		(end 393.19581 -276.031198)
		(width 0.09525)
		(layer "In11.Cu")
		(net "M_L_CPU0_SB_DQS_DP<0>")
	)
	(arc
		(start 389.436356 -276.031198)
		(mid 389.624824 -276.081875)
		(end 389.813292 -276.031198)
		(width 0.09525)
		(layer "In11.Cu")
		(net "M_L_CPU0_SB_DQS_DP<0>")
	)
	(arc
		(start 390.753346 -276.031198)
		(mid 391.034778 -275.955443)
		(end 391.31621 -276.031198)
		(width 0.09525)
		(layer "In11.Cu")
		(net "M_L_CPU0_SB_DQS_DP<0>")
	)
	(arc
		(start 391.6934 -276.031198)
		(mid 391.964088 -275.955546)
		(end 392.237468 -276.020784)
		(width 0.09525)
		(layer "In11.Cu")
		(net "M_L_CPU0_SB_DQS_DP<0>")
	)
	(arc
		(start 390.376156 -276.031198)
		(mid 390.559931 -276.08197)
		(end 390.744964 -276.036024)
		(width 0.09525)
		(layer "In11.Cu")
		(net "M_L_CPU0_SB_DQS_DP<0>")
	)
	(arc
		(start 389.813292 -276.031198)
		(mid 390.094724 -275.955443)
		(end 390.376156 -276.031198)
		(width 0.09525)
		(layer "In11.Cu")
		(net "M_L_CPU0_SB_DQS_DP<0>")
	)
	(arc
		(start 388.504684 -276.036024)
		(mid 388.689716 -276.081938)
		(end 388.873492 -276.031198)
		(width 0.09525)
		(layer "In11.Cu")
		(net "M_L_CPU0_SB_DQS_DP<0>")
	)
	(arc
		(start 392.263884 -276.036024)
		(mid 392.448662 -276.081817)
		(end 392.632184 -276.031198)
		(width 0.09525)
		(layer "In11.Cu")
		(net "M_L_CPU0_SB_DQS_DP<0>")
	)
	(arc
		(start 388.873492 -276.031198)
		(mid 389.154924 -275.955443)
		(end 389.436356 -276.031198)
		(width 0.09525)
		(layer "In11.Cu")
		(net "M_L_CPU0_SB_DQS_DP<0>")
	)
	(arc
		(start 393.572746 -276.031198)
		(mid 393.613676 -276.004164)
		(end 393.650724 -275.972016)
		(width 0.09525)
		(layer "In11.Cu")
		(net "M_L_CPU0_SB_DQS_DP<0>")
	)
	(segment
		(start 386.807964 -271.39011)
		(end 387.274816 -271.656048)
		(width 0.12954)
		(layer "F.Cu")
		(net "M_L_CPU0_SB_DQS_DN<9>")
	)
	(segment
		(start 451.161912 -276.30501)
		(end 451.826884 -276.30501)
		(width 0.16002)
		(layer "In11.Cu")
		(net "M_L_CPU0_SB_DQS_DN<9>")
	)
	(segment
		(start 442.997336 -275.96211)
		(end 443.324996 -276.28977)
		(width 0.16002)
		(layer "In11.Cu")
		(net "M_L_CPU0_SB_DQS_DN<9>")
	)
	(segment
		(start 422.490138 -275.46681)
		(end 422.901618 -275.46681)
		(width 0.16002)
		(layer "In11.Cu")
		(net "M_L_CPU0_SB_DQS_DN<9>")
	)
	(segment
		(start 424.91533 -275.112226)
		(end 425.765214 -275.96211)
		(width 0.16002)
		(layer "In11.Cu")
		(net "M_L_CPU0_SB_DQS_DN<9>")
	)
	(segment
		(start 389.33501 -271.326102)
		(end 389.343392 -271.330928)
		(width 0.09525)
		(layer "In11.Cu")
		(net "M_L_CPU0_SB_DQS_DN<9>")
	)
	(segment
		(start 448.121532 -275.686266)
		(end 450.543168 -275.686266)
		(width 0.16002)
		(layer "In11.Cu")
		(net "M_L_CPU0_SB_DQS_DN<9>")
	)
	(segment
		(start 444.29934 -276.28977)
		(end 445.1223 -275.46681)
		(width 0.16002)
		(layer "In11.Cu")
		(net "M_L_CPU0_SB_DQS_DN<9>")
	)
	(segment
		(start 395.859254 -269.55496)
		(end 405.552402 -269.55496)
		(width 0.16002)
		(layer "In11.Cu")
		(net "M_L_CPU0_SB_DQS_DN<9>")
	)
	(segment
		(start 435.780942 -276.28977)
		(end 436.755286 -276.28977)
		(width 0.16002)
		(layer "In11.Cu")
		(net "M_L_CPU0_SB_DQS_DN<9>")
	)
	(segment
		(start 392.714988 -271.337024)
		(end 392.725402 -271.330928)
		(width 0.09525)
		(layer "In11.Cu")
		(net "M_L_CPU0_SB_DQS_DN<9>")
	)
	(segment
		(start 437.989726 -275.46681)
		(end 438.34431 -275.112226)
		(width 0.16002)
		(layer "In11.Cu")
		(net "M_L_CPU0_SB_DQS_DN<9>")
	)
	(segment
		(start 388.394956 -271.326102)
		(end 388.403338 -271.330928)
		(width 0.09525)
		(layer "In11.Cu")
		(net "M_L_CPU0_SB_DQS_DN<9>")
	)
	(segment
		(start 432.459384 -275.112226)
		(end 433.309268 -275.96211)
		(width 0.16002)
		(layer "In11.Cu")
		(net "M_L_CPU0_SB_DQS_DN<9>")
	)
	(segment
		(start 428.236888 -276.28977)
		(end 429.211232 -276.28977)
		(width 0.16002)
		(layer "In11.Cu")
		(net "M_L_CPU0_SB_DQS_DN<9>")
	)
	(segment
		(start 450.543168 -275.686266)
		(end 451.161912 -276.30501)
		(width 0.16002)
		(layer "In11.Cu")
		(net "M_L_CPU0_SB_DQS_DN<9>")
	)
	(segment
		(start 433.309268 -275.96211)
		(end 435.453282 -275.96211)
		(width 0.16002)
		(layer "In11.Cu")
		(net "M_L_CPU0_SB_DQS_DN<9>")
	)
	(segment
		(start 420.692834 -276.28977)
		(end 421.667178 -276.28977)
		(width 0.16002)
		(layer "In11.Cu")
		(net "M_L_CPU0_SB_DQS_DN<9>")
	)
	(segment
		(start 436.755286 -276.28977)
		(end 437.578246 -275.46681)
		(width 0.16002)
		(layer "In11.Cu")
		(net "M_L_CPU0_SB_DQS_DN<9>")
	)
	(segment
		(start 447.547492 -275.112226)
		(end 448.121532 -275.686266)
		(width 0.16002)
		(layer "In11.Cu")
		(net "M_L_CPU0_SB_DQS_DN<9>")
	)
	(segment
		(start 395.321536 -269.400274)
		(end 395.417294 -269.496032)
		(width 0.09525)
		(layer "In11.Cu")
		(net "M_L_CPU0_SB_DQS_DN<9>")
	)
	(segment
		(start 387.42874 -271.390618)
		(end 387.529578 -271.363948)
		(width 0.09525)
		(layer "In11.Cu")
		(net "M_L_CPU0_SB_DQS_DN<9>")
	)
	(segment
		(start 392.154918 -271.326102)
		(end 392.1633 -271.330928)
		(width 0.09525)
		(layer "In11.Cu")
		(net "M_L_CPU0_SB_DQS_DN<9>")
	)
	(segment
		(start 394.73124 -269.400274)
		(end 395.321536 -269.400274)
		(width 0.09525)
		(layer "In11.Cu")
		(net "M_L_CPU0_SB_DQS_DN<9>")
	)
	(segment
		(start 427.909228 -275.96211)
		(end 428.236888 -276.28977)
		(width 0.16002)
		(layer "In11.Cu")
		(net "M_L_CPU0_SB_DQS_DN<9>")
	)
	(segment
		(start 451.826884 -276.30501)
		(end 452.020686 -276.111208)
		(width 0.16002)
		(layer "In11.Cu")
		(net "M_L_CPU0_SB_DQS_DN<9>")
	)
	(segment
		(start 412.287212 -276.28977)
		(end 414.123124 -276.28977)
		(width 0.16002)
		(layer "In11.Cu")
		(net "M_L_CPU0_SB_DQS_DN<9>")
	)
	(segment
		(start 387.274816 -271.656048)
		(end 387.42874 -271.390618)
		(width 0.09525)
		(layer "In11.Cu")
		(net "M_L_CPU0_SB_DQS_DN<9>")
	)
	(segment
		(start 453.914256 -276.111208)
		(end 454.188068 -276.38502)
		(width 0.16002)
		(layer "In11.Cu")
		(net "M_L_CPU0_SB_DQS_DN<9>")
	)
	(segment
		(start 440.853322 -275.96211)
		(end 442.997336 -275.96211)
		(width 0.16002)
		(layer "In11.Cu")
		(net "M_L_CPU0_SB_DQS_DN<9>")
	)
	(segment
		(start 422.901618 -275.46681)
		(end 423.256202 -275.112226)
		(width 0.16002)
		(layer "In11.Cu")
		(net "M_L_CPU0_SB_DQS_DN<9>")
	)
	(segment
		(start 414.946084 -275.46681)
		(end 419.869874 -275.46681)
		(width 0.16002)
		(layer "In11.Cu")
		(net "M_L_CPU0_SB_DQS_DN<9>")
	)
	(segment
		(start 395.776704 -269.496032)
		(end 395.835632 -269.55496)
		(width 0.09525)
		(layer "In11.Cu")
		(net "M_L_CPU0_SB_DQS_DN<9>")
	)
	(segment
		(start 438.34431 -275.112226)
		(end 440.003438 -275.112226)
		(width 0.16002)
		(layer "In11.Cu")
		(net "M_L_CPU0_SB_DQS_DN<9>")
	)
	(segment
		(start 419.869874 -275.46681)
		(end 420.692834 -276.28977)
		(width 0.16002)
		(layer "In11.Cu")
		(net "M_L_CPU0_SB_DQS_DN<9>")
	)
	(segment
		(start 393.6619 -270.469614)
		(end 394.73124 -269.400274)
		(width 0.09525)
		(layer "In11.Cu")
		(net "M_L_CPU0_SB_DQS_DN<9>")
	)
	(segment
		(start 437.578246 -275.46681)
		(end 437.989726 -275.46681)
		(width 0.16002)
		(layer "In11.Cu")
		(net "M_L_CPU0_SB_DQS_DN<9>")
	)
	(segment
		(start 414.123124 -276.28977)
		(end 414.946084 -275.46681)
		(width 0.16002)
		(layer "In11.Cu")
		(net "M_L_CPU0_SB_DQS_DN<9>")
	)
	(segment
		(start 435.453282 -275.96211)
		(end 435.780942 -276.28977)
		(width 0.16002)
		(layer "In11.Cu")
		(net "M_L_CPU0_SB_DQS_DN<9>")
	)
	(segment
		(start 425.765214 -275.96211)
		(end 427.909228 -275.96211)
		(width 0.16002)
		(layer "In11.Cu")
		(net "M_L_CPU0_SB_DQS_DN<9>")
	)
	(segment
		(start 395.417294 -269.496032)
		(end 395.776704 -269.496032)
		(width 0.09525)
		(layer "In11.Cu")
		(net "M_L_CPU0_SB_DQS_DN<9>")
	)
	(segment
		(start 395.835632 -269.55496)
		(end 395.859254 -269.55496)
		(width 0.09525)
		(layer "In11.Cu")
		(net "M_L_CPU0_SB_DQS_DN<9>")
	)
	(segment
		(start 445.53378 -275.46681)
		(end 445.888364 -275.112226)
		(width 0.16002)
		(layer "In11.Cu")
		(net "M_L_CPU0_SB_DQS_DN<9>")
	)
	(segment
		(start 405.552402 -269.55496)
		(end 412.287212 -276.28977)
		(width 0.16002)
		(layer "In11.Cu")
		(net "M_L_CPU0_SB_DQS_DN<9>")
	)
	(segment
		(start 392.725402 -271.330928)
		(end 392.72591 -271.330928)
		(width 0.09525)
		(layer "In11.Cu")
		(net "M_L_CPU0_SB_DQS_DN<9>")
	)
	(segment
		(start 429.211232 -276.28977)
		(end 430.034192 -275.46681)
		(width 0.16002)
		(layer "In11.Cu")
		(net "M_L_CPU0_SB_DQS_DN<9>")
	)
	(segment
		(start 421.667178 -276.28977)
		(end 422.490138 -275.46681)
		(width 0.16002)
		(layer "In11.Cu")
		(net "M_L_CPU0_SB_DQS_DN<9>")
	)
	(segment
		(start 393.162282 -270.54048)
		(end 393.196064 -270.520922)
		(width 0.09525)
		(layer "In11.Cu")
		(net "M_L_CPU0_SB_DQS_DN<9>")
	)
	(segment
		(start 430.034192 -275.46681)
		(end 430.445672 -275.46681)
		(width 0.16002)
		(layer "In11.Cu")
		(net "M_L_CPU0_SB_DQS_DN<9>")
	)
	(segment
		(start 443.324996 -276.28977)
		(end 444.29934 -276.28977)
		(width 0.16002)
		(layer "In11.Cu")
		(net "M_L_CPU0_SB_DQS_DN<9>")
	)
	(segment
		(start 392.72591 -271.330928)
		(end 392.76401 -271.30883)
		(width 0.09525)
		(layer "In11.Cu")
		(net "M_L_CPU0_SB_DQS_DN<9>")
	)
	(segment
		(start 430.445672 -275.46681)
		(end 430.800256 -275.112226)
		(width 0.16002)
		(layer "In11.Cu")
		(net "M_L_CPU0_SB_DQS_DN<9>")
	)
	(segment
		(start 393.384786 -270.469614)
		(end 393.6619 -270.469614)
		(width 0.09525)
		(layer "In11.Cu")
		(net "M_L_CPU0_SB_DQS_DN<9>")
	)
	(segment
		(start 423.256202 -275.112226)
		(end 424.91533 -275.112226)
		(width 0.16002)
		(layer "In11.Cu")
		(net "M_L_CPU0_SB_DQS_DN<9>")
	)
	(segment
		(start 430.800256 -275.112226)
		(end 432.459384 -275.112226)
		(width 0.16002)
		(layer "In11.Cu")
		(net "M_L_CPU0_SB_DQS_DN<9>")
	)
	(segment
		(start 452.020686 -276.111208)
		(end 453.914256 -276.111208)
		(width 0.16002)
		(layer "In11.Cu")
		(net "M_L_CPU0_SB_DQS_DN<9>")
	)
	(segment
		(start 445.888364 -275.112226)
		(end 447.547492 -275.112226)
		(width 0.16002)
		(layer "In11.Cu")
		(net "M_L_CPU0_SB_DQS_DN<9>")
	)
	(segment
		(start 440.003438 -275.112226)
		(end 440.853322 -275.96211)
		(width 0.16002)
		(layer "In11.Cu")
		(net "M_L_CPU0_SB_DQS_DN<9>")
	)
	(segment
		(start 389.906256 -271.330928)
		(end 389.914638 -271.326102)
		(width 0.09525)
		(layer "In11.Cu")
		(net "M_L_CPU0_SB_DQS_DN<9>")
	)
	(segment
		(start 445.1223 -275.46681)
		(end 445.53378 -275.46681)
		(width 0.16002)
		(layer "In11.Cu")
		(net "M_L_CPU0_SB_DQS_DN<9>")
	)
	(arc
		(start 391.223246 -271.330928)
		(mid 391.504678 -271.406683)
		(end 391.78611 -271.330928)
		(width 0.09525)
		(layer "In11.Cu")
		(net "M_L_CPU0_SB_DQS_DN<9>")
	)
	(arc
		(start 390.84631 -271.330928)
		(mid 391.034778 -271.280251)
		(end 391.223246 -271.330928)
		(width 0.09525)
		(layer "In11.Cu")
		(net "M_L_CPU0_SB_DQS_DN<9>")
	)
	(arc
		(start 388.026148 -271.330928)
		(mid 388.209923 -271.280156)
		(end 388.394956 -271.326102)
		(width 0.09525)
		(layer "In11.Cu")
		(net "M_L_CPU0_SB_DQS_DN<9>")
	)
	(arc
		(start 391.78611 -271.330928)
		(mid 391.969885 -271.280156)
		(end 392.154918 -271.326102)
		(width 0.09525)
		(layer "In11.Cu")
		(net "M_L_CPU0_SB_DQS_DN<9>")
	)
	(arc
		(start 390.283446 -271.330928)
		(mid 390.564878 -271.406683)
		(end 390.84631 -271.330928)
		(width 0.09525)
		(layer "In11.Cu")
		(net "M_L_CPU0_SB_DQS_DN<9>")
	)
	(arc
		(start 392.76401 -271.30883)
		(mid 392.94246 -271.10736)
		(end 393.006834 -270.846042)
		(width 0.09525)
		(layer "In11.Cu")
		(net "M_L_CPU0_SB_DQS_DN<9>")
	)
	(arc
		(start 388.403338 -271.330928)
		(mid 388.68477 -271.406683)
		(end 388.966202 -271.330928)
		(width 0.09525)
		(layer "In11.Cu")
		(net "M_L_CPU0_SB_DQS_DN<9>")
	)
	(arc
		(start 393.006834 -270.846042)
		(mid 393.047936 -270.674636)
		(end 393.162282 -270.54048)
		(width 0.09525)
		(layer "In11.Cu")
		(net "M_L_CPU0_SB_DQS_DN<9>")
	)
	(arc
		(start 387.549898 -271.371822)
		(mid 387.79261 -271.404705)
		(end 388.026148 -271.330928)
		(width 0.09525)
		(layer "In11.Cu")
		(net "M_L_CPU0_SB_DQS_DN<9>")
	)
	(arc
		(start 389.914638 -271.326102)
		(mid 390.09967 -271.280188)
		(end 390.283446 -271.330928)
		(width 0.09525)
		(layer "In11.Cu")
		(net "M_L_CPU0_SB_DQS_DN<9>")
	)
	(arc
		(start 392.1633 -271.330928)
		(mid 392.438335 -271.406522)
		(end 392.714988 -271.337024)
		(width 0.09525)
		(layer "In11.Cu")
		(net "M_L_CPU0_SB_DQS_DN<9>")
	)
	(arc
		(start 388.966202 -271.330928)
		(mid 389.149977 -271.280156)
		(end 389.33501 -271.326102)
		(width 0.09525)
		(layer "In11.Cu")
		(net "M_L_CPU0_SB_DQS_DN<9>")
	)
	(arc
		(start 393.196064 -270.520922)
		(mid 393.28703 -270.482769)
		(end 393.384786 -270.469614)
		(width 0.09525)
		(layer "In11.Cu")
		(net "M_L_CPU0_SB_DQS_DN<9>")
	)
	(arc
		(start 387.529578 -271.363948)
		(mid 387.5397 -271.367983)
		(end 387.549898 -271.371822)
		(width 0.09525)
		(layer "In11.Cu")
		(net "M_L_CPU0_SB_DQS_DN<9>")
	)
	(arc
		(start 389.343392 -271.330928)
		(mid 389.624824 -271.406683)
		(end 389.906256 -271.330928)
		(width 0.09525)
		(layer "In11.Cu")
		(net "M_L_CPU0_SB_DQS_DN<9>")
	)
	(segment
		(start 385.86791 -290.83)
		(end 386.334762 -291.095938)
		(width 0.12954)
		(layer "F.Cu")
		(net "M_L_CPU0_SB_DQS_DN<8>")
	)
	(segment
		(start 394.574522 -294.642794)
		(end 394.606018 -294.661082)
		(width 0.09525)
		(layer "In11.Cu")
		(net "M_L_CPU0_SB_DQS_DN<8>")
	)
	(segment
		(start 431.103786 -314.207906)
		(end 433.427124 -314.207906)
		(width 0.16002)
		(layer "In11.Cu")
		(net "M_L_CPU0_SB_DQS_DN<8>")
	)
	(segment
		(start 386.180838 -291.361368)
		(end 386.204206 -291.448236)
		(width 0.09525)
		(layer "In11.Cu")
		(net "M_L_CPU0_SB_DQS_DN<8>")
	)
	(segment
		(start 435.597046 -315.058044)
		(end 435.972204 -314.682886)
		(width 0.16002)
		(layer "In11.Cu")
		(net "M_L_CPU0_SB_DQS_DN<8>")
	)
	(segment
		(start 440.347608 -314.080906)
		(end 440.474608 -314.207906)
		(width 0.16002)
		(layer "In11.Cu")
		(net "M_L_CPU0_SB_DQS_DN<8>")
	)
	(segment
		(start 428.42815 -314.682886)
		(end 429.049434 -314.682886)
		(width 0.16002)
		(layer "In11.Cu")
		(net "M_L_CPU0_SB_DQS_DN<8>")
	)
	(segment
		(start 389.33501 -291.425884)
		(end 389.343392 -291.421058)
		(width 0.09525)
		(layer "In11.Cu")
		(net "M_L_CPU0_SB_DQS_DN<8>")
	)
	(segment
		(start 395.439138 -295.467532)
		(end 395.439138 -296.319956)
		(width 0.09525)
		(layer "In11.Cu")
		(net "M_L_CPU0_SB_DQS_DN<8>")
	)
	(segment
		(start 446.191894 -314.207906)
		(end 447.252598 -314.207906)
		(width 0.16002)
		(layer "In11.Cu")
		(net "M_L_CPU0_SB_DQS_DN<8>")
	)
	(segment
		(start 447.252598 -314.207906)
		(end 447.401442 -314.059062)
		(width 0.16002)
		(layer "In11.Cu")
		(net "M_L_CPU0_SB_DQS_DN<8>")
	)
	(segment
		(start 391.974578 -291.472366)
		(end 392.525758 -291.472366)
		(width 0.09525)
		(layer "In11.Cu")
		(net "M_L_CPU0_SB_DQS_DN<8>")
	)
	(segment
		(start 429.902874 -313.829446)
		(end 430.725326 -313.829446)
		(width 0.16002)
		(layer "In11.Cu")
		(net "M_L_CPU0_SB_DQS_DN<8>")
	)
	(segment
		(start 411.621478 -314.682886)
		(end 411.748478 -314.555886)
		(width 0.16002)
		(layer "In11.Cu")
		(net "M_L_CPU0_SB_DQS_DN<8>")
	)
	(segment
		(start 411.748478 -314.555886)
		(end 412.205678 -314.555886)
		(width 0.16002)
		(layer "In11.Cu")
		(net "M_L_CPU0_SB_DQS_DN<8>")
	)
	(segment
		(start 419.327838 -314.79363)
		(end 419.592252 -315.058044)
		(width 0.16002)
		(layer "In11.Cu")
		(net "M_L_CPU0_SB_DQS_DN<8>")
	)
	(segment
		(start 416.09391 -313.829446)
		(end 416.550094 -314.28563)
		(width 0.16002)
		(layer "In11.Cu")
		(net "M_L_CPU0_SB_DQS_DN<8>")
	)
	(segment
		(start 389.906256 -291.421058)
		(end 389.914638 -291.425884)
		(width 0.09525)
		(layer "In11.Cu")
		(net "M_L_CPU0_SB_DQS_DN<8>")
	)
	(segment
		(start 429.049434 -314.682886)
		(end 429.902874 -313.829446)
		(width 0.16002)
		(layer "In11.Cu")
		(net "M_L_CPU0_SB_DQS_DN<8>")
	)
	(segment
		(start 449.087748 -314.059062)
		(end 449.813934 -314.059062)
		(width 0.16002)
		(layer "In11.Cu")
		(net "M_L_CPU0_SB_DQS_DN<8>")
	)
	(segment
		(start 393.229592 -292.307772)
		(end 393.65301 -292.73119)
		(width 0.09525)
		(layer "In11.Cu")
		(net "M_L_CPU0_SB_DQS_DN<8>")
	)
	(segment
		(start 449.813934 -314.059062)
		(end 450.088 -313.784996)
		(width 0.16002)
		(layer "In11.Cu")
		(net "M_L_CPU0_SB_DQS_DN<8>")
	)
	(segment
		(start 423.559732 -314.207906)
		(end 425.88307 -314.207906)
		(width 0.16002)
		(layer "In11.Cu")
		(net "M_L_CPU0_SB_DQS_DN<8>")
	)
	(segment
		(start 436.593488 -314.682886)
		(end 437.446928 -313.829446)
		(width 0.16002)
		(layer "In11.Cu")
		(net "M_L_CPU0_SB_DQS_DN<8>")
	)
	(segment
		(start 426.733208 -315.058044)
		(end 428.052992 -315.058044)
		(width 0.16002)
		(layer "In11.Cu")
		(net "M_L_CPU0_SB_DQS_DN<8>")
	)
	(segment
		(start 416.550094 -314.28563)
		(end 416.550094 -314.819792)
		(width 0.16002)
		(layer "In11.Cu")
		(net "M_L_CPU0_SB_DQS_DN<8>")
	)
	(segment
		(start 437.446928 -313.829446)
		(end 438.26938 -313.829446)
		(width 0.16002)
		(layer "In11.Cu")
		(net "M_L_CPU0_SB_DQS_DN<8>")
	)
	(segment
		(start 445.813434 -313.829446)
		(end 446.191894 -314.207906)
		(width 0.16002)
		(layer "In11.Cu")
		(net "M_L_CPU0_SB_DQS_DN<8>")
	)
	(segment
		(start 434.277262 -315.058044)
		(end 435.597046 -315.058044)
		(width 0.16002)
		(layer "In11.Cu")
		(net "M_L_CPU0_SB_DQS_DN<8>")
	)
	(segment
		(start 423.181272 -313.829446)
		(end 423.559732 -314.207906)
		(width 0.16002)
		(layer "In11.Cu")
		(net "M_L_CPU0_SB_DQS_DN<8>")
	)
	(segment
		(start 409.834334 -314.682886)
		(end 411.621478 -314.682886)
		(width 0.16002)
		(layer "In11.Cu")
		(net "M_L_CPU0_SB_DQS_DN<8>")
	)
	(segment
		(start 443.516258 -314.682886)
		(end 444.137542 -314.682886)
		(width 0.16002)
		(layer "In11.Cu")
		(net "M_L_CPU0_SB_DQS_DN<8>")
	)
	(segment
		(start 430.725326 -313.829446)
		(end 431.103786 -314.207906)
		(width 0.16002)
		(layer "In11.Cu")
		(net "M_L_CPU0_SB_DQS_DN<8>")
	)
	(segment
		(start 393.946634 -293.440358)
		(end 393.946634 -293.525702)
		(width 0.09525)
		(layer "In11.Cu")
		(net "M_L_CPU0_SB_DQS_DN<8>")
	)
	(segment
		(start 425.88307 -314.207906)
		(end 426.733208 -315.058044)
		(width 0.16002)
		(layer "In11.Cu")
		(net "M_L_CPU0_SB_DQS_DN<8>")
	)
	(segment
		(start 448.480688 -313.932062)
		(end 448.960748 -313.932062)
		(width 0.16002)
		(layer "In11.Cu")
		(net "M_L_CPU0_SB_DQS_DN<8>")
	)
	(segment
		(start 419.592252 -315.058044)
		(end 420.508938 -315.058044)
		(width 0.16002)
		(layer "In11.Cu")
		(net "M_L_CPU0_SB_DQS_DN<8>")
	)
	(segment
		(start 417.555426 -313.948572)
		(end 418.905944 -313.948572)
		(width 0.16002)
		(layer "In11.Cu")
		(net "M_L_CPU0_SB_DQS_DN<8>")
	)
	(segment
		(start 441.821316 -315.058044)
		(end 443.1411 -315.058044)
		(width 0.16002)
		(layer "In11.Cu")
		(net "M_L_CPU0_SB_DQS_DN<8>")
	)
	(segment
		(start 428.052992 -315.058044)
		(end 428.42815 -314.682886)
		(width 0.16002)
		(layer "In11.Cu")
		(net "M_L_CPU0_SB_DQS_DN<8>")
	)
	(segment
		(start 417.058348 -314.979812)
		(end 417.218368 -314.819792)
		(width 0.16002)
		(layer "In11.Cu")
		(net "M_L_CPU0_SB_DQS_DN<8>")
	)
	(segment
		(start 435.972204 -314.682886)
		(end 436.593488 -314.682886)
		(width 0.16002)
		(layer "In11.Cu")
		(net "M_L_CPU0_SB_DQS_DN<8>")
	)
	(segment
		(start 438.64784 -314.207906)
		(end 439.740548 -314.207906)
		(width 0.16002)
		(layer "In11.Cu")
		(net "M_L_CPU0_SB_DQS_DN<8>")
	)
	(segment
		(start 440.971178 -314.207906)
		(end 441.821316 -315.058044)
		(width 0.16002)
		(layer "In11.Cu")
		(net "M_L_CPU0_SB_DQS_DN<8>")
	)
	(segment
		(start 393.946634 -293.525702)
		(end 393.946888 -293.525956)
		(width 0.09525)
		(layer "In11.Cu")
		(net "M_L_CPU0_SB_DQS_DN<8>")
	)
	(segment
		(start 443.1411 -315.058044)
		(end 443.516258 -314.682886)
		(width 0.16002)
		(layer "In11.Cu")
		(net "M_L_CPU0_SB_DQS_DN<8>")
	)
	(segment
		(start 419.327838 -314.370466)
		(end 419.327838 -314.79363)
		(width 0.16002)
		(layer "In11.Cu")
		(net "M_L_CPU0_SB_DQS_DN<8>")
	)
	(segment
		(start 448.960748 -313.932062)
		(end 449.087748 -314.059062)
		(width 0.16002)
		(layer "In11.Cu")
		(net "M_L_CPU0_SB_DQS_DN<8>")
	)
	(segment
		(start 416.710114 -314.979812)
		(end 417.058348 -314.979812)
		(width 0.16002)
		(layer "In11.Cu")
		(net "M_L_CPU0_SB_DQS_DN<8>")
	)
	(segment
		(start 440.474608 -314.207906)
		(end 440.971178 -314.207906)
		(width 0.16002)
		(layer "In11.Cu")
		(net "M_L_CPU0_SB_DQS_DN<8>")
	)
	(segment
		(start 439.740548 -314.207906)
		(end 439.867548 -314.080906)
		(width 0.16002)
		(layer "In11.Cu")
		(net "M_L_CPU0_SB_DQS_DN<8>")
	)
	(segment
		(start 395.498066 -300.346618)
		(end 409.834334 -314.682886)
		(width 0.16002)
		(layer "In11.Cu")
		(net "M_L_CPU0_SB_DQS_DN<8>")
	)
	(segment
		(start 386.334762 -291.095938)
		(end 386.180838 -291.361368)
		(width 0.09525)
		(layer "In11.Cu")
		(net "M_L_CPU0_SB_DQS_DN<8>")
	)
	(segment
		(start 420.508938 -315.058044)
		(end 420.884096 -314.682886)
		(width 0.16002)
		(layer "In11.Cu")
		(net "M_L_CPU0_SB_DQS_DN<8>")
	)
	(segment
		(start 412.332678 -314.682886)
		(end 413.961326 -314.682886)
		(width 0.16002)
		(layer "In11.Cu")
		(net "M_L_CPU0_SB_DQS_DN<8>")
	)
	(segment
		(start 395.439138 -296.319956)
		(end 395.498066 -296.378884)
		(width 0.09525)
		(layer "In11.Cu")
		(net "M_L_CPU0_SB_DQS_DN<8>")
	)
	(segment
		(start 438.26938 -313.829446)
		(end 438.64784 -314.207906)
		(width 0.16002)
		(layer "In11.Cu")
		(net "M_L_CPU0_SB_DQS_DN<8>")
	)
	(segment
		(start 422.35882 -313.829446)
		(end 423.181272 -313.829446)
		(width 0.16002)
		(layer "In11.Cu")
		(net "M_L_CPU0_SB_DQS_DN<8>")
	)
	(segment
		(start 417.218368 -314.28563)
		(end 417.555426 -313.948572)
		(width 0.16002)
		(layer "In11.Cu")
		(net "M_L_CPU0_SB_DQS_DN<8>")
	)
	(segment
		(start 395.498066 -296.378884)
		(end 395.498066 -296.402506)
		(width 0.09525)
		(layer "In11.Cu")
		(net "M_L_CPU0_SB_DQS_DN<8>")
	)
	(segment
		(start 444.990982 -313.829446)
		(end 445.813434 -313.829446)
		(width 0.16002)
		(layer "In11.Cu")
		(net "M_L_CPU0_SB_DQS_DN<8>")
	)
	(segment
		(start 388.394956 -291.425884)
		(end 388.403338 -291.421058)
		(width 0.09525)
		(layer "In11.Cu")
		(net "M_L_CPU0_SB_DQS_DN<8>")
	)
	(segment
		(start 413.961326 -314.682886)
		(end 414.814766 -313.829446)
		(width 0.16002)
		(layer "In11.Cu")
		(net "M_L_CPU0_SB_DQS_DN<8>")
	)
	(segment
		(start 444.137542 -314.682886)
		(end 444.990982 -313.829446)
		(width 0.16002)
		(layer "In11.Cu")
		(net "M_L_CPU0_SB_DQS_DN<8>")
	)
	(segment
		(start 395.215618 -295.244012)
		(end 395.439138 -295.467532)
		(width 0.09525)
		(layer "In11.Cu")
		(net "M_L_CPU0_SB_DQS_DN<8>")
	)
	(segment
		(start 433.427124 -314.207906)
		(end 434.277262 -315.058044)
		(width 0.16002)
		(layer "In11.Cu")
		(net "M_L_CPU0_SB_DQS_DN<8>")
	)
	(segment
		(start 393.060936 -292.138862)
		(end 393.229592 -292.307772)
		(width 0.09525)
		(layer "In11.Cu")
		(net "M_L_CPU0_SB_DQS_DN<8>")
	)
	(segment
		(start 417.218368 -314.819792)
		(end 417.218368 -314.28563)
		(width 0.16002)
		(layer "In11.Cu")
		(net "M_L_CPU0_SB_DQS_DN<8>")
	)
	(segment
		(start 414.814766 -313.829446)
		(end 416.09391 -313.829446)
		(width 0.16002)
		(layer "In11.Cu")
		(net "M_L_CPU0_SB_DQS_DN<8>")
	)
	(segment
		(start 421.50538 -314.682886)
		(end 422.35882 -313.829446)
		(width 0.16002)
		(layer "In11.Cu")
		(net "M_L_CPU0_SB_DQS_DN<8>")
	)
	(segment
		(start 416.550094 -314.819792)
		(end 416.710114 -314.979812)
		(width 0.16002)
		(layer "In11.Cu")
		(net "M_L_CPU0_SB_DQS_DN<8>")
	)
	(segment
		(start 394.103606 -293.83228)
		(end 394.136118 -293.851076)
		(width 0.09525)
		(layer "In11.Cu")
		(net "M_L_CPU0_SB_DQS_DN<8>")
	)
	(segment
		(start 448.353688 -314.059062)
		(end 448.480688 -313.932062)
		(width 0.16002)
		(layer "In11.Cu")
		(net "M_L_CPU0_SB_DQS_DN<8>")
	)
	(segment
		(start 412.205678 -314.555886)
		(end 412.332678 -314.682886)
		(width 0.16002)
		(layer "In11.Cu")
		(net "M_L_CPU0_SB_DQS_DN<8>")
	)
	(segment
		(start 394.136118 -293.851076)
		(end 394.174218 -293.873174)
		(width 0.09525)
		(layer "In11.Cu")
		(net "M_L_CPU0_SB_DQS_DN<8>")
	)
	(segment
		(start 395.498066 -296.402506)
		(end 395.498066 -300.346618)
		(width 0.16002)
		(layer "In11.Cu")
		(net "M_L_CPU0_SB_DQS_DN<8>")
	)
	(segment
		(start 420.884096 -314.682886)
		(end 421.50538 -314.682886)
		(width 0.16002)
		(layer "In11.Cu")
		(net "M_L_CPU0_SB_DQS_DN<8>")
	)
	(segment
		(start 394.720826 -294.748966)
		(end 395.215618 -295.244012)
		(width 0.09525)
		(layer "In11.Cu")
		(net "M_L_CPU0_SB_DQS_DN<8>")
	)
	(segment
		(start 418.905944 -313.948572)
		(end 419.327838 -314.370466)
		(width 0.16002)
		(layer "In11.Cu")
		(net "M_L_CPU0_SB_DQS_DN<8>")
	)
	(segment
		(start 447.401442 -314.059062)
		(end 448.353688 -314.059062)
		(width 0.16002)
		(layer "In11.Cu")
		(net "M_L_CPU0_SB_DQS_DN<8>")
	)
	(segment
		(start 439.867548 -314.080906)
		(end 440.347608 -314.080906)
		(width 0.16002)
		(layer "In11.Cu")
		(net "M_L_CPU0_SB_DQS_DN<8>")
	)
	(arc
		(start 389.914638 -291.425884)
		(mid 390.09967 -291.471798)
		(end 390.283446 -291.421058)
		(width 0.09525)
		(layer "In11.Cu")
		(net "M_L_CPU0_SB_DQS_DN<8>")
	)
	(arc
		(start 393.946888 -293.525956)
		(mid 393.988345 -293.697996)
		(end 394.103606 -293.83228)
		(width 0.09525)
		(layer "In11.Cu")
		(net "M_L_CPU0_SB_DQS_DN<8>")
	)
	(arc
		(start 387.463284 -291.421058)
		(mid 387.744716 -291.345303)
		(end 388.026148 -291.421058)
		(width 0.09525)
		(layer "In11.Cu")
		(net "M_L_CPU0_SB_DQS_DN<8>")
	)
	(arc
		(start 392.525758 -291.472366)
		(mid 392.693873 -291.505713)
		(end 392.8364 -291.60089)
		(width 0.09525)
		(layer "In11.Cu")
		(net "M_L_CPU0_SB_DQS_DN<8>")
	)
	(arc
		(start 392.948668 -291.869622)
		(mid 392.978218 -292.015333)
		(end 393.060936 -292.138862)
		(width 0.09525)
		(layer "In11.Cu")
		(net "M_L_CPU0_SB_DQS_DN<8>")
	)
	(arc
		(start 386.523484 -291.421058)
		(mid 386.804916 -291.345303)
		(end 387.086348 -291.421058)
		(width 0.09525)
		(layer "In11.Cu")
		(net "M_L_CPU0_SB_DQS_DN<8>")
	)
	(arc
		(start 389.343392 -291.421058)
		(mid 389.624824 -291.345303)
		(end 389.906256 -291.421058)
		(width 0.09525)
		(layer "In11.Cu")
		(net "M_L_CPU0_SB_DQS_DN<8>")
	)
	(arc
		(start 388.966202 -291.421058)
		(mid 389.149977 -291.47183)
		(end 389.33501 -291.425884)
		(width 0.09525)
		(layer "In11.Cu")
		(net "M_L_CPU0_SB_DQS_DN<8>")
	)
	(arc
		(start 391.78611 -291.421058)
		(mid 391.876953 -291.459177)
		(end 391.974578 -291.472366)
		(width 0.09525)
		(layer "In11.Cu")
		(net "M_L_CPU0_SB_DQS_DN<8>")
	)
	(arc
		(start 390.283446 -291.421058)
		(mid 390.564878 -291.345303)
		(end 390.84631 -291.421058)
		(width 0.09525)
		(layer "In11.Cu")
		(net "M_L_CPU0_SB_DQS_DN<8>")
	)
	(arc
		(start 392.8364 -291.60089)
		(mid 392.919074 -291.724178)
		(end 392.948668 -291.869622)
		(width 0.09525)
		(layer "In11.Cu")
		(net "M_L_CPU0_SB_DQS_DN<8>")
	)
	(arc
		(start 394.606018 -294.661082)
		(mid 394.635307 -294.679247)
		(end 394.663422 -294.699182)
		(width 0.09525)
		(layer "In11.Cu")
		(net "M_L_CPU0_SB_DQS_DN<8>")
	)
	(arc
		(start 394.663422 -294.699182)
		(mid 394.692968 -294.723101)
		(end 394.720826 -294.748966)
		(width 0.09525)
		(layer "In11.Cu")
		(net "M_L_CPU0_SB_DQS_DN<8>")
	)
	(arc
		(start 394.417042 -294.335962)
		(mid 394.458707 -294.508409)
		(end 394.574522 -294.642794)
		(width 0.09525)
		(layer "In11.Cu")
		(net "M_L_CPU0_SB_DQS_DN<8>")
	)
	(arc
		(start 391.223246 -291.421058)
		(mid 391.504678 -291.345303)
		(end 391.78611 -291.421058)
		(width 0.09525)
		(layer "In11.Cu")
		(net "M_L_CPU0_SB_DQS_DN<8>")
	)
	(arc
		(start 390.84631 -291.421058)
		(mid 391.034778 -291.471735)
		(end 391.223246 -291.421058)
		(width 0.09525)
		(layer "In11.Cu")
		(net "M_L_CPU0_SB_DQS_DN<8>")
	)
	(arc
		(start 388.403338 -291.421058)
		(mid 388.68477 -291.345303)
		(end 388.966202 -291.421058)
		(width 0.09525)
		(layer "In11.Cu")
		(net "M_L_CPU0_SB_DQS_DN<8>")
	)
	(arc
		(start 387.086348 -291.421058)
		(mid 387.274816 -291.471735)
		(end 387.463284 -291.421058)
		(width 0.09525)
		(layer "In11.Cu")
		(net "M_L_CPU0_SB_DQS_DN<8>")
	)
	(arc
		(start 394.174218 -293.873174)
		(mid 394.352668 -294.074644)
		(end 394.417042 -294.335962)
		(width 0.09525)
		(layer "In11.Cu")
		(net "M_L_CPU0_SB_DQS_DN<8>")
	)
	(arc
		(start 393.65301 -292.73119)
		(mid 393.870332 -293.056574)
		(end 393.946634 -293.440358)
		(width 0.09525)
		(layer "In11.Cu")
		(net "M_L_CPU0_SB_DQS_DN<8>")
	)
	(arc
		(start 388.026148 -291.421058)
		(mid 388.209923 -291.47183)
		(end 388.394956 -291.425884)
		(width 0.09525)
		(layer "In11.Cu")
		(net "M_L_CPU0_SB_DQS_DN<8>")
	)
	(arc
		(start 386.204206 -291.448236)
		(mid 386.366888 -291.470368)
		(end 386.523484 -291.421058)
		(width 0.09525)
		(layer "In11.Cu")
		(net "M_L_CPU0_SB_DQS_DN<8>")
	)
	(segment
		(start 385.86791 -285.970218)
		(end 386.334762 -286.236156)
		(width 0.12954)
		(layer "F.Cu")
		(net "M_L_CPU0_SB_DQS_DN<7>")
	)
	(segment
		(start 448.653408 -304.582068)
		(end 449.133468 -304.582068)
		(width 0.16002)
		(layer "In11.Cu")
		(net "M_L_CPU0_SB_DQS_DN<7>")
	)
	(segment
		(start 388.394956 -286.566102)
		(end 388.403338 -286.561276)
		(width 0.09525)
		(layer "In11.Cu")
		(net "M_L_CPU0_SB_DQS_DN<7>")
	)
	(segment
		(start 445.813434 -304.479452)
		(end 446.191894 -304.857912)
		(width 0.16002)
		(layer "In11.Cu")
		(net "M_L_CPU0_SB_DQS_DN<7>")
	)
	(segment
		(start 443.1411 -305.70805)
		(end 443.516258 -305.332892)
		(width 0.16002)
		(layer "In11.Cu")
		(net "M_L_CPU0_SB_DQS_DN<7>")
	)
	(segment
		(start 409.67406 -305.332892)
		(end 413.961326 -305.332892)
		(width 0.16002)
		(layer "In11.Cu")
		(net "M_L_CPU0_SB_DQS_DN<7>")
	)
	(segment
		(start 402.32076 -297.596306)
		(end 402.797264 -297.596306)
		(width 0.16002)
		(layer "In11.Cu")
		(net "M_L_CPU0_SB_DQS_DN<7>")
	)
	(segment
		(start 416.015678 -304.857912)
		(end 418.45738 -304.857912)
		(width 0.16002)
		(layer "In11.Cu")
		(net "M_L_CPU0_SB_DQS_DN<7>")
	)
	(segment
		(start 405.890222 -301.549054)
		(end 406.136856 -301.795688)
		(width 0.16002)
		(layer "In11.Cu")
		(net "M_L_CPU0_SB_DQS_DN<7>")
	)
	(segment
		(start 440.971178 -304.857912)
		(end 441.821316 -305.70805)
		(width 0.16002)
		(layer "In11.Cu")
		(net "M_L_CPU0_SB_DQS_DN<7>")
	)
	(segment
		(start 429.902874 -304.479452)
		(end 430.725326 -304.479452)
		(width 0.16002)
		(layer "In11.Cu")
		(net "M_L_CPU0_SB_DQS_DN<7>")
	)
	(segment
		(start 407.342594 -302.617886)
		(end 407.263854 -302.696626)
		(width 0.16002)
		(layer "In11.Cu")
		(net "M_L_CPU0_SB_DQS_DN<7>")
	)
	(segment
		(start 403.221698 -298.49699)
		(end 403.142958 -298.57573)
		(width 0.16002)
		(layer "In11.Cu")
		(net "M_L_CPU0_SB_DQS_DN<7>")
	)
	(segment
		(start 413.961326 -305.332892)
		(end 414.814766 -304.479452)
		(width 0.16002)
		(layer "In11.Cu")
		(net "M_L_CPU0_SB_DQS_DN<7>")
	)
	(segment
		(start 402.01596 -297.674792)
		(end 402.24202 -297.674792)
		(width 0.16002)
		(layer "In11.Cu")
		(net "M_L_CPU0_SB_DQS_DN<7>")
	)
	(segment
		(start 405.544528 -300.34357)
		(end 405.968962 -300.768004)
		(width 0.16002)
		(layer "In11.Cu")
		(net "M_L_CPU0_SB_DQS_DN<7>")
	)
	(segment
		(start 447.401442 -304.709068)
		(end 448.526408 -304.709068)
		(width 0.16002)
		(layer "In11.Cu")
		(net "M_L_CPU0_SB_DQS_DN<7>")
	)
	(segment
		(start 403.694392 -298.969938)
		(end 404.170896 -298.969938)
		(width 0.16002)
		(layer "In11.Cu")
		(net "M_L_CPU0_SB_DQS_DN<7>")
	)
	(segment
		(start 423.181272 -304.479452)
		(end 423.559732 -304.857912)
		(width 0.16002)
		(layer "In11.Cu")
		(net "M_L_CPU0_SB_DQS_DN<7>")
	)
	(segment
		(start 402.24202 -297.674792)
		(end 402.32076 -297.596306)
		(width 0.16002)
		(layer "In11.Cu")
		(net "M_L_CPU0_SB_DQS_DN<7>")
	)
	(segment
		(start 420.508938 -305.70805)
		(end 420.884096 -305.332892)
		(width 0.16002)
		(layer "In11.Cu")
		(net "M_L_CPU0_SB_DQS_DN<7>")
	)
	(segment
		(start 405.968962 -301.244254)
		(end 405.890222 -301.322994)
		(width 0.16002)
		(layer "In11.Cu")
		(net "M_L_CPU0_SB_DQS_DN<7>")
	)
	(segment
		(start 404.51659 -300.175422)
		(end 404.763224 -300.422056)
		(width 0.16002)
		(layer "In11.Cu")
		(net "M_L_CPU0_SB_DQS_DN<7>")
	)
	(segment
		(start 449.813934 -304.709068)
		(end 450.088 -304.435002)
		(width 0.16002)
		(layer "In11.Cu")
		(net "M_L_CPU0_SB_DQS_DN<7>")
	)
	(segment
		(start 404.989284 -300.422056)
		(end 405.068024 -300.34357)
		(width 0.16002)
		(layer "In11.Cu")
		(net "M_L_CPU0_SB_DQS_DN<7>")
	)
	(segment
		(start 395.718538 -287.466024)
		(end 395.735302 -287.482788)
		(width 0.09525)
		(layer "In11.Cu")
		(net "M_L_CPU0_SB_DQS_DN<7>")
	)
	(segment
		(start 402.797264 -297.596306)
		(end 403.221698 -298.02074)
		(width 0.16002)
		(layer "In11.Cu")
		(net "M_L_CPU0_SB_DQS_DN<7>")
	)
	(segment
		(start 435.597046 -305.70805)
		(end 435.972204 -305.332892)
		(width 0.16002)
		(layer "In11.Cu")
		(net "M_L_CPU0_SB_DQS_DN<7>")
	)
	(segment
		(start 425.88307 -304.857912)
		(end 426.733208 -305.70805)
		(width 0.16002)
		(layer "In11.Cu")
		(net "M_L_CPU0_SB_DQS_DN<7>")
	)
	(segment
		(start 447.252598 -304.857912)
		(end 447.401442 -304.709068)
		(width 0.16002)
		(layer "In11.Cu")
		(net "M_L_CPU0_SB_DQS_DN<7>")
	)
	(segment
		(start 444.137542 -305.332892)
		(end 444.990982 -304.479452)
		(width 0.16002)
		(layer "In11.Cu")
		(net "M_L_CPU0_SB_DQS_DN<7>")
	)
	(segment
		(start 444.990982 -304.479452)
		(end 445.813434 -304.479452)
		(width 0.16002)
		(layer "In11.Cu")
		(net "M_L_CPU0_SB_DQS_DN<7>")
	)
	(segment
		(start 403.142958 -298.80179)
		(end 403.389592 -299.048424)
		(width 0.16002)
		(layer "In11.Cu")
		(net "M_L_CPU0_SB_DQS_DN<7>")
	)
	(segment
		(start 433.427124 -304.857912)
		(end 434.277262 -305.70805)
		(width 0.16002)
		(layer "In11.Cu")
		(net "M_L_CPU0_SB_DQS_DN<7>")
	)
	(segment
		(start 436.593488 -305.332892)
		(end 437.446928 -304.479452)
		(width 0.16002)
		(layer "In11.Cu")
		(net "M_L_CPU0_SB_DQS_DN<7>")
	)
	(segment
		(start 438.26938 -304.479452)
		(end 438.64784 -304.857912)
		(width 0.16002)
		(layer "In11.Cu")
		(net "M_L_CPU0_SB_DQS_DN<7>")
	)
	(segment
		(start 426.733208 -305.70805)
		(end 428.052992 -305.70805)
		(width 0.16002)
		(layer "In11.Cu")
		(net "M_L_CPU0_SB_DQS_DN<7>")
	)
	(segment
		(start 386.180838 -286.501586)
		(end 386.204206 -286.588454)
		(width 0.09525)
		(layer "In11.Cu")
		(net "M_L_CPU0_SB_DQS_DN<7>")
	)
	(segment
		(start 438.64784 -304.857912)
		(end 440.971178 -304.857912)
		(width 0.16002)
		(layer "In11.Cu")
		(net "M_L_CPU0_SB_DQS_DN<7>")
	)
	(segment
		(start 406.91816 -301.717202)
		(end 407.342594 -302.141636)
		(width 0.16002)
		(layer "In11.Cu")
		(net "M_L_CPU0_SB_DQS_DN<7>")
	)
	(segment
		(start 414.814766 -304.479452)
		(end 415.637218 -304.479452)
		(width 0.16002)
		(layer "In11.Cu")
		(net "M_L_CPU0_SB_DQS_DN<7>")
	)
	(segment
		(start 448.526408 -304.709068)
		(end 448.653408 -304.582068)
		(width 0.16002)
		(layer "In11.Cu")
		(net "M_L_CPU0_SB_DQS_DN<7>")
	)
	(segment
		(start 405.968962 -300.768004)
		(end 405.968962 -301.244254)
		(width 0.16002)
		(layer "In11.Cu")
		(net "M_L_CPU0_SB_DQS_DN<7>")
	)
	(segment
		(start 404.59533 -299.870622)
		(end 404.51659 -299.949362)
		(width 0.16002)
		(layer "In11.Cu")
		(net "M_L_CPU0_SB_DQS_DN<7>")
	)
	(segment
		(start 404.51659 -299.949362)
		(end 404.51659 -300.175422)
		(width 0.16002)
		(layer "In11.Cu")
		(net "M_L_CPU0_SB_DQS_DN<7>")
	)
	(segment
		(start 441.821316 -305.70805)
		(end 443.1411 -305.70805)
		(width 0.16002)
		(layer "In11.Cu")
		(net "M_L_CPU0_SB_DQS_DN<7>")
	)
	(segment
		(start 392.154918 -286.566102)
		(end 392.1633 -286.561276)
		(width 0.09525)
		(layer "In11.Cu")
		(net "M_L_CPU0_SB_DQS_DN<7>")
	)
	(segment
		(start 406.362916 -301.795688)
		(end 406.441656 -301.717202)
		(width 0.16002)
		(layer "In11.Cu")
		(net "M_L_CPU0_SB_DQS_DN<7>")
	)
	(segment
		(start 429.049434 -305.332892)
		(end 429.902874 -304.479452)
		(width 0.16002)
		(layer "In11.Cu")
		(net "M_L_CPU0_SB_DQS_DN<7>")
	)
	(segment
		(start 405.890222 -301.322994)
		(end 405.890222 -301.549054)
		(width 0.16002)
		(layer "In11.Cu")
		(net "M_L_CPU0_SB_DQS_DN<7>")
	)
	(segment
		(start 420.884096 -305.332892)
		(end 421.50538 -305.332892)
		(width 0.16002)
		(layer "In11.Cu")
		(net "M_L_CPU0_SB_DQS_DN<7>")
	)
	(segment
		(start 434.277262 -305.70805)
		(end 435.597046 -305.70805)
		(width 0.16002)
		(layer "In11.Cu")
		(net "M_L_CPU0_SB_DQS_DN<7>")
	)
	(segment
		(start 449.260468 -304.709068)
		(end 449.813934 -304.709068)
		(width 0.16002)
		(layer "In11.Cu")
		(net "M_L_CPU0_SB_DQS_DN<7>")
	)
	(segment
		(start 404.170896 -298.969938)
		(end 404.59533 -299.394372)
		(width 0.16002)
		(layer "In11.Cu")
		(net "M_L_CPU0_SB_DQS_DN<7>")
	)
	(segment
		(start 406.441656 -301.717202)
		(end 406.91816 -301.717202)
		(width 0.16002)
		(layer "In11.Cu")
		(net "M_L_CPU0_SB_DQS_DN<7>")
	)
	(segment
		(start 394.594588 -286.997902)
		(end 395.168628 -286.997902)
		(width 0.09525)
		(layer "In11.Cu")
		(net "M_L_CPU0_SB_DQS_DN<7>")
	)
	(segment
		(start 389.906256 -286.561276)
		(end 389.914638 -286.566102)
		(width 0.09525)
		(layer "In11.Cu")
		(net "M_L_CPU0_SB_DQS_DN<7>")
	)
	(segment
		(start 421.50538 -305.332892)
		(end 422.35882 -304.479452)
		(width 0.16002)
		(layer "In11.Cu")
		(net "M_L_CPU0_SB_DQS_DN<7>")
	)
	(segment
		(start 418.45738 -304.857912)
		(end 419.307518 -305.70805)
		(width 0.16002)
		(layer "In11.Cu")
		(net "M_L_CPU0_SB_DQS_DN<7>")
	)
	(segment
		(start 403.142958 -298.57573)
		(end 403.142958 -298.80179)
		(width 0.16002)
		(layer "In11.Cu")
		(net "M_L_CPU0_SB_DQS_DN<7>")
	)
	(segment
		(start 401.131278 -296.79011)
		(end 402.01596 -297.674792)
		(width 0.16002)
		(layer "In11.Cu")
		(net "M_L_CPU0_SB_DQS_DN<7>")
	)
	(segment
		(start 435.972204 -305.332892)
		(end 436.593488 -305.332892)
		(width 0.16002)
		(layer "In11.Cu")
		(net "M_L_CPU0_SB_DQS_DN<7>")
	)
	(segment
		(start 446.191894 -304.857912)
		(end 447.252598 -304.857912)
		(width 0.16002)
		(layer "In11.Cu")
		(net "M_L_CPU0_SB_DQS_DN<7>")
	)
	(segment
		(start 437.446928 -304.479452)
		(end 438.26938 -304.479452)
		(width 0.16002)
		(layer "In11.Cu")
		(net "M_L_CPU0_SB_DQS_DN<7>")
	)
	(segment
		(start 406.136856 -301.795688)
		(end 406.362916 -301.795688)
		(width 0.16002)
		(layer "In11.Cu")
		(net "M_L_CPU0_SB_DQS_DN<7>")
	)
	(segment
		(start 423.559732 -304.857912)
		(end 425.88307 -304.857912)
		(width 0.16002)
		(layer "In11.Cu")
		(net "M_L_CPU0_SB_DQS_DN<7>")
	)
	(segment
		(start 386.334762 -286.236156)
		(end 386.180838 -286.501586)
		(width 0.09525)
		(layer "In11.Cu")
		(net "M_L_CPU0_SB_DQS_DN<7>")
	)
	(segment
		(start 449.133468 -304.582068)
		(end 449.260468 -304.709068)
		(width 0.16002)
		(layer "In11.Cu")
		(net "M_L_CPU0_SB_DQS_DN<7>")
	)
	(segment
		(start 395.168628 -286.997902)
		(end 395.635226 -287.46577)
		(width 0.09525)
		(layer "In11.Cu")
		(net "M_L_CPU0_SB_DQS_DN<7>")
	)
	(segment
		(start 405.068024 -300.34357)
		(end 405.544528 -300.34357)
		(width 0.16002)
		(layer "In11.Cu")
		(net "M_L_CPU0_SB_DQS_DN<7>")
	)
	(segment
		(start 395.635226 -287.46577)
		(end 395.718538 -287.466024)
		(width 0.09525)
		(layer "In11.Cu")
		(net "M_L_CPU0_SB_DQS_DN<7>")
	)
	(segment
		(start 428.42815 -305.332892)
		(end 429.049434 -305.332892)
		(width 0.16002)
		(layer "In11.Cu")
		(net "M_L_CPU0_SB_DQS_DN<7>")
	)
	(segment
		(start 422.35882 -304.479452)
		(end 423.181272 -304.479452)
		(width 0.16002)
		(layer "In11.Cu")
		(net "M_L_CPU0_SB_DQS_DN<7>")
	)
	(segment
		(start 403.221698 -298.02074)
		(end 403.221698 -298.49699)
		(width 0.16002)
		(layer "In11.Cu")
		(net "M_L_CPU0_SB_DQS_DN<7>")
	)
	(segment
		(start 407.263854 -302.696626)
		(end 407.263854 -302.922686)
		(width 0.16002)
		(layer "In11.Cu")
		(net "M_L_CPU0_SB_DQS_DN<7>")
	)
	(segment
		(start 392.608308 -286.444182)
		(end 394.040868 -286.444182)
		(width 0.09525)
		(layer "In11.Cu")
		(net "M_L_CPU0_SB_DQS_DN<7>")
	)
	(segment
		(start 404.763224 -300.422056)
		(end 404.989284 -300.422056)
		(width 0.16002)
		(layer "In11.Cu")
		(net "M_L_CPU0_SB_DQS_DN<7>")
	)
	(segment
		(start 401.131278 -292.879526)
		(end 401.131278 -296.79011)
		(width 0.16002)
		(layer "In11.Cu")
		(net "M_L_CPU0_SB_DQS_DN<7>")
	)
	(segment
		(start 403.615652 -299.048424)
		(end 403.694392 -298.969938)
		(width 0.16002)
		(layer "In11.Cu")
		(net "M_L_CPU0_SB_DQS_DN<7>")
	)
	(segment
		(start 407.342594 -302.141636)
		(end 407.342594 -302.617886)
		(width 0.16002)
		(layer "In11.Cu")
		(net "M_L_CPU0_SB_DQS_DN<7>")
	)
	(segment
		(start 394.040868 -286.444182)
		(end 394.594588 -286.997902)
		(width 0.09525)
		(layer "In11.Cu")
		(net "M_L_CPU0_SB_DQS_DN<7>")
	)
	(segment
		(start 389.33501 -286.566102)
		(end 389.343392 -286.561276)
		(width 0.09525)
		(layer "In11.Cu")
		(net "M_L_CPU0_SB_DQS_DN<7>")
	)
	(segment
		(start 395.735302 -287.482788)
		(end 401.131278 -292.879526)
		(width 0.16002)
		(layer "In11.Cu")
		(net "M_L_CPU0_SB_DQS_DN<7>")
	)
	(segment
		(start 415.637218 -304.479452)
		(end 416.015678 -304.857912)
		(width 0.16002)
		(layer "In11.Cu")
		(net "M_L_CPU0_SB_DQS_DN<7>")
	)
	(segment
		(start 404.59533 -299.394372)
		(end 404.59533 -299.870622)
		(width 0.16002)
		(layer "In11.Cu")
		(net "M_L_CPU0_SB_DQS_DN<7>")
	)
	(segment
		(start 430.725326 -304.479452)
		(end 431.103786 -304.857912)
		(width 0.16002)
		(layer "In11.Cu")
		(net "M_L_CPU0_SB_DQS_DN<7>")
	)
	(segment
		(start 428.052992 -305.70805)
		(end 428.42815 -305.332892)
		(width 0.16002)
		(layer "In11.Cu")
		(net "M_L_CPU0_SB_DQS_DN<7>")
	)
	(segment
		(start 443.516258 -305.332892)
		(end 444.137542 -305.332892)
		(width 0.16002)
		(layer "In11.Cu")
		(net "M_L_CPU0_SB_DQS_DN<7>")
	)
	(segment
		(start 407.263854 -302.922686)
		(end 409.67406 -305.332892)
		(width 0.16002)
		(layer "In11.Cu")
		(net "M_L_CPU0_SB_DQS_DN<7>")
	)
	(segment
		(start 403.389592 -299.048424)
		(end 403.615652 -299.048424)
		(width 0.16002)
		(layer "In11.Cu")
		(net "M_L_CPU0_SB_DQS_DN<7>")
	)
	(segment
		(start 431.103786 -304.857912)
		(end 433.427124 -304.857912)
		(width 0.16002)
		(layer "In11.Cu")
		(net "M_L_CPU0_SB_DQS_DN<7>")
	)
	(segment
		(start 419.307518 -305.70805)
		(end 420.508938 -305.70805)
		(width 0.16002)
		(layer "In11.Cu")
		(net "M_L_CPU0_SB_DQS_DN<7>")
	)
	(arc
		(start 392.1633 -286.561276)
		(mid 392.16988 -286.557675)
		(end 392.176508 -286.554164)
		(width 0.09525)
		(layer "In11.Cu")
		(net "M_L_CPU0_SB_DQS_DN<7>")
	)
	(arc
		(start 387.086348 -286.561276)
		(mid 387.274816 -286.611953)
		(end 387.463284 -286.561276)
		(width 0.09525)
		(layer "In11.Cu")
		(net "M_L_CPU0_SB_DQS_DN<7>")
	)
	(arc
		(start 392.176508 -286.554164)
		(mid 392.3855 -286.472052)
		(end 392.608308 -286.444182)
		(width 0.09525)
		(layer "In11.Cu")
		(net "M_L_CPU0_SB_DQS_DN<7>")
	)
	(arc
		(start 386.523484 -286.561276)
		(mid 386.804916 -286.485487)
		(end 387.086348 -286.561276)
		(width 0.09525)
		(layer "In11.Cu")
		(net "M_L_CPU0_SB_DQS_DN<7>")
	)
	(arc
		(start 390.283446 -286.561276)
		(mid 390.564878 -286.485487)
		(end 390.84631 -286.561276)
		(width 0.09525)
		(layer "In11.Cu")
		(net "M_L_CPU0_SB_DQS_DN<7>")
	)
	(arc
		(start 390.84631 -286.561276)
		(mid 391.034778 -286.611953)
		(end 391.223246 -286.561276)
		(width 0.09525)
		(layer "In11.Cu")
		(net "M_L_CPU0_SB_DQS_DN<7>")
	)
	(arc
		(start 386.204206 -286.588454)
		(mid 386.366888 -286.610586)
		(end 386.523484 -286.561276)
		(width 0.09525)
		(layer "In11.Cu")
		(net "M_L_CPU0_SB_DQS_DN<7>")
	)
	(arc
		(start 388.026148 -286.561276)
		(mid 388.209923 -286.612048)
		(end 388.394956 -286.566102)
		(width 0.09525)
		(layer "In11.Cu")
		(net "M_L_CPU0_SB_DQS_DN<7>")
	)
	(arc
		(start 391.223246 -286.561276)
		(mid 391.504678 -286.485487)
		(end 391.78611 -286.561276)
		(width 0.09525)
		(layer "In11.Cu")
		(net "M_L_CPU0_SB_DQS_DN<7>")
	)
	(arc
		(start 389.914638 -286.566102)
		(mid 390.09967 -286.612016)
		(end 390.283446 -286.561276)
		(width 0.09525)
		(layer "In11.Cu")
		(net "M_L_CPU0_SB_DQS_DN<7>")
	)
	(arc
		(start 391.78611 -286.561276)
		(mid 391.969885 -286.612048)
		(end 392.154918 -286.566102)
		(width 0.09525)
		(layer "In11.Cu")
		(net "M_L_CPU0_SB_DQS_DN<7>")
	)
	(arc
		(start 387.463284 -286.561276)
		(mid 387.744716 -286.485487)
		(end 388.026148 -286.561276)
		(width 0.09525)
		(layer "In11.Cu")
		(net "M_L_CPU0_SB_DQS_DN<7>")
	)
	(arc
		(start 388.403338 -286.561276)
		(mid 388.68477 -286.485487)
		(end 388.966202 -286.561276)
		(width 0.09525)
		(layer "In11.Cu")
		(net "M_L_CPU0_SB_DQS_DN<7>")
	)
	(arc
		(start 389.343392 -286.561276)
		(mid 389.624824 -286.485487)
		(end 389.906256 -286.561276)
		(width 0.09525)
		(layer "In11.Cu")
		(net "M_L_CPU0_SB_DQS_DN<7>")
	)
	(arc
		(start 388.966202 -286.561276)
		(mid 389.149977 -286.612048)
		(end 389.33501 -286.566102)
		(width 0.09525)
		(layer "In11.Cu")
		(net "M_L_CPU0_SB_DQS_DN<7>")
	)
	(segment
		(start 385.86791 -281.110182)
		(end 386.334762 -281.37612)
		(width 0.12954)
		(layer "F.Cu")
		(net "M_L_CPU0_SB_DQS_DN<6>")
	)
	(segment
		(start 448.508628 -295.232074)
		(end 448.988688 -295.232074)
		(width 0.16002)
		(layer "In11.Cu")
		(net "M_L_CPU0_SB_DQS_DN<6>")
	)
	(segment
		(start 410.425392 -294.287194)
		(end 410.425392 -294.763698)
		(width 0.16002)
		(layer "In11.Cu")
		(net "M_L_CPU0_SB_DQS_DN<6>")
	)
	(segment
		(start 408.947874 -294.213026)
		(end 409.173934 -294.213026)
		(width 0.16002)
		(layer "In11.Cu")
		(net "M_L_CPU0_SB_DQS_DN<6>")
	)
	(segment
		(start 409.05176 -293.390066)
		(end 408.70124 -293.740332)
		(width 0.16002)
		(layer "In11.Cu")
		(net "M_L_CPU0_SB_DQS_DN<6>")
	)
	(segment
		(start 446.191894 -295.507918)
		(end 447.252598 -295.507918)
		(width 0.16002)
		(layer "In11.Cu")
		(net "M_L_CPU0_SB_DQS_DN<6>")
	)
	(segment
		(start 437.446928 -295.129458)
		(end 438.26938 -295.129458)
		(width 0.16002)
		(layer "In11.Cu")
		(net "M_L_CPU0_SB_DQS_DN<6>")
	)
	(segment
		(start 389.906256 -281.70124)
		(end 389.914638 -281.706066)
		(width 0.09525)
		(layer "In11.Cu")
		(net "M_L_CPU0_SB_DQS_DN<6>")
	)
	(segment
		(start 386.180838 -281.64155)
		(end 386.204206 -281.728418)
		(width 0.09525)
		(layer "In11.Cu")
		(net "M_L_CPU0_SB_DQS_DN<6>")
	)
	(segment
		(start 410.425392 -294.763698)
		(end 410.074872 -295.113964)
		(width 0.16002)
		(layer "In11.Cu")
		(net "M_L_CPU0_SB_DQS_DN<6>")
	)
	(segment
		(start 392.154918 -281.706066)
		(end 392.1633 -281.70124)
		(width 0.09525)
		(layer "In11.Cu")
		(net "M_L_CPU0_SB_DQS_DN<6>")
	)
	(segment
		(start 445.813434 -295.129458)
		(end 446.191894 -295.507918)
		(width 0.16002)
		(layer "In11.Cu")
		(net "M_L_CPU0_SB_DQS_DN<6>")
	)
	(segment
		(start 448.381628 -295.359074)
		(end 448.508628 -295.232074)
		(width 0.16002)
		(layer "In11.Cu")
		(net "M_L_CPU0_SB_DQS_DN<6>")
	)
	(segment
		(start 408.627326 -292.489128)
		(end 409.05176 -292.913562)
		(width 0.16002)
		(layer "In11.Cu")
		(net "M_L_CPU0_SB_DQS_DN<6>")
	)
	(segment
		(start 430.725326 -295.129458)
		(end 431.103786 -295.507918)
		(width 0.16002)
		(layer "In11.Cu")
		(net "M_L_CPU0_SB_DQS_DN<6>")
	)
	(segment
		(start 448.988688 -295.232074)
		(end 449.115688 -295.359074)
		(width 0.16002)
		(layer "In11.Cu")
		(net "M_L_CPU0_SB_DQS_DN<6>")
	)
	(segment
		(start 433.427124 -295.507918)
		(end 434.277262 -296.358056)
		(width 0.16002)
		(layer "In11.Cu")
		(net "M_L_CPU0_SB_DQS_DN<6>")
	)
	(segment
		(start 429.902874 -295.129458)
		(end 430.725326 -295.129458)
		(width 0.16002)
		(layer "In11.Cu")
		(net "M_L_CPU0_SB_DQS_DN<6>")
	)
	(segment
		(start 435.972204 -295.982898)
		(end 436.593488 -295.982898)
		(width 0.16002)
		(layer "In11.Cu")
		(net "M_L_CPU0_SB_DQS_DN<6>")
	)
	(segment
		(start 395.835632 -281.81808)
		(end 395.859254 -281.81808)
		(width 0.09525)
		(layer "In11.Cu")
		(net "M_L_CPU0_SB_DQS_DN<6>")
	)
	(segment
		(start 398.015968 -281.81808)
		(end 406.749758 -290.55187)
		(width 0.16002)
		(layer "In11.Cu")
		(net "M_L_CPU0_SB_DQS_DN<6>")
	)
	(segment
		(start 449.813934 -295.359074)
		(end 450.088 -295.085008)
		(width 0.16002)
		(layer "In11.Cu")
		(net "M_L_CPU0_SB_DQS_DN<6>")
	)
	(segment
		(start 434.277262 -296.358056)
		(end 435.597046 -296.358056)
		(width 0.16002)
		(layer "In11.Cu")
		(net "M_L_CPU0_SB_DQS_DN<6>")
	)
	(segment
		(start 394.040614 -281.625548)
		(end 394.292328 -281.877262)
		(width 0.09525)
		(layer "In11.Cu")
		(net "M_L_CPU0_SB_DQS_DN<6>")
	)
	(segment
		(start 447.401442 -295.359074)
		(end 448.381628 -295.359074)
		(width 0.16002)
		(layer "In11.Cu")
		(net "M_L_CPU0_SB_DQS_DN<6>")
	)
	(segment
		(start 392.444732 -281.625548)
		(end 394.040614 -281.625548)
		(width 0.09525)
		(layer "In11.Cu")
		(net "M_L_CPU0_SB_DQS_DN<6>")
	)
	(segment
		(start 441.821316 -296.358056)
		(end 443.1411 -296.358056)
		(width 0.16002)
		(layer "In11.Cu")
		(net "M_L_CPU0_SB_DQS_DN<6>")
	)
	(segment
		(start 435.597046 -296.358056)
		(end 435.972204 -295.982898)
		(width 0.16002)
		(layer "In11.Cu")
		(net "M_L_CPU0_SB_DQS_DN<6>")
	)
	(segment
		(start 444.137542 -295.982898)
		(end 444.990982 -295.129458)
		(width 0.16002)
		(layer "In11.Cu")
		(net "M_L_CPU0_SB_DQS_DN<6>")
	)
	(segment
		(start 407.574242 -292.839394)
		(end 407.800302 -292.839394)
		(width 0.16002)
		(layer "In11.Cu")
		(net "M_L_CPU0_SB_DQS_DN<6>")
	)
	(segment
		(start 418.912294 -295.818052)
		(end 419.452298 -296.358056)
		(width 0.16002)
		(layer "In11.Cu")
		(net "M_L_CPU0_SB_DQS_DN<6>")
	)
	(segment
		(start 428.052992 -296.358056)
		(end 428.42815 -295.982898)
		(width 0.16002)
		(layer "In11.Cu")
		(net "M_L_CPU0_SB_DQS_DN<6>")
	)
	(segment
		(start 444.990982 -295.129458)
		(end 445.813434 -295.129458)
		(width 0.16002)
		(layer "In11.Cu")
		(net "M_L_CPU0_SB_DQS_DN<6>")
	)
	(segment
		(start 443.516258 -295.982898)
		(end 444.137542 -295.982898)
		(width 0.16002)
		(layer "In11.Cu")
		(net "M_L_CPU0_SB_DQS_DN<6>")
	)
	(segment
		(start 449.115688 -295.359074)
		(end 449.813934 -295.359074)
		(width 0.16002)
		(layer "In11.Cu")
		(net "M_L_CPU0_SB_DQS_DN<6>")
	)
	(segment
		(start 416.325812 -295.818052)
		(end 418.912294 -295.818052)
		(width 0.16002)
		(layer "In11.Cu")
		(net "M_L_CPU0_SB_DQS_DN<6>")
	)
	(segment
		(start 406.749758 -290.55187)
		(end 406.749758 -292.01491)
		(width 0.16002)
		(layer "In11.Cu")
		(net "M_L_CPU0_SB_DQS_DN<6>")
	)
	(segment
		(start 422.35882 -295.129458)
		(end 423.181272 -295.129458)
		(width 0.16002)
		(layer "In11.Cu")
		(net "M_L_CPU0_SB_DQS_DN<6>")
	)
	(segment
		(start 429.049434 -295.982898)
		(end 429.902874 -295.129458)
		(width 0.16002)
		(layer "In11.Cu")
		(net "M_L_CPU0_SB_DQS_DN<6>")
	)
	(segment
		(start 408.70124 -293.740332)
		(end 408.70124 -293.966392)
		(width 0.16002)
		(layer "In11.Cu")
		(net "M_L_CPU0_SB_DQS_DN<6>")
	)
	(segment
		(start 407.800302 -292.839394)
		(end 408.150822 -292.489128)
		(width 0.16002)
		(layer "In11.Cu")
		(net "M_L_CPU0_SB_DQS_DN<6>")
	)
	(segment
		(start 415.637218 -295.129458)
		(end 416.325812 -295.818052)
		(width 0.16002)
		(layer "In11.Cu")
		(net "M_L_CPU0_SB_DQS_DN<6>")
	)
	(segment
		(start 421.50538 -295.982898)
		(end 422.35882 -295.129458)
		(width 0.16002)
		(layer "In11.Cu")
		(net "M_L_CPU0_SB_DQS_DN<6>")
	)
	(segment
		(start 408.70124 -293.966392)
		(end 408.947874 -294.213026)
		(width 0.16002)
		(layer "In11.Cu")
		(net "M_L_CPU0_SB_DQS_DN<6>")
	)
	(segment
		(start 419.452298 -296.358056)
		(end 420.508938 -296.358056)
		(width 0.16002)
		(layer "In11.Cu")
		(net "M_L_CPU0_SB_DQS_DN<6>")
	)
	(segment
		(start 409.524454 -293.86276)
		(end 410.000958 -293.86276)
		(width 0.16002)
		(layer "In11.Cu")
		(net "M_L_CPU0_SB_DQS_DN<6>")
	)
	(segment
		(start 410.074872 -295.113964)
		(end 410.074872 -295.340024)
		(width 0.16002)
		(layer "In11.Cu")
		(net "M_L_CPU0_SB_DQS_DN<6>")
	)
	(segment
		(start 386.334762 -281.37612)
		(end 386.180838 -281.64155)
		(width 0.09525)
		(layer "In11.Cu")
		(net "M_L_CPU0_SB_DQS_DN<6>")
	)
	(segment
		(start 447.252598 -295.507918)
		(end 447.401442 -295.359074)
		(width 0.16002)
		(layer "In11.Cu")
		(net "M_L_CPU0_SB_DQS_DN<6>")
	)
	(segment
		(start 420.508938 -296.358056)
		(end 420.884096 -295.982898)
		(width 0.16002)
		(layer "In11.Cu")
		(net "M_L_CPU0_SB_DQS_DN<6>")
	)
	(segment
		(start 423.181272 -295.129458)
		(end 423.559732 -295.507918)
		(width 0.16002)
		(layer "In11.Cu")
		(net "M_L_CPU0_SB_DQS_DN<6>")
	)
	(segment
		(start 420.884096 -295.982898)
		(end 421.50538 -295.982898)
		(width 0.16002)
		(layer "In11.Cu")
		(net "M_L_CPU0_SB_DQS_DN<6>")
	)
	(segment
		(start 413.961326 -295.982898)
		(end 414.814766 -295.129458)
		(width 0.16002)
		(layer "In11.Cu")
		(net "M_L_CPU0_SB_DQS_DN<6>")
	)
	(segment
		(start 440.971178 -295.507918)
		(end 441.821316 -296.358056)
		(width 0.16002)
		(layer "In11.Cu")
		(net "M_L_CPU0_SB_DQS_DN<6>")
	)
	(segment
		(start 436.593488 -295.982898)
		(end 437.446928 -295.129458)
		(width 0.16002)
		(layer "In11.Cu")
		(net "M_L_CPU0_SB_DQS_DN<6>")
	)
	(segment
		(start 388.394956 -281.706066)
		(end 388.403338 -281.70124)
		(width 0.09525)
		(layer "In11.Cu")
		(net "M_L_CPU0_SB_DQS_DN<6>")
	)
	(segment
		(start 409.05176 -292.913562)
		(end 409.05176 -293.390066)
		(width 0.16002)
		(layer "In11.Cu")
		(net "M_L_CPU0_SB_DQS_DN<6>")
	)
	(segment
		(start 428.42815 -295.982898)
		(end 429.049434 -295.982898)
		(width 0.16002)
		(layer "In11.Cu")
		(net "M_L_CPU0_SB_DQS_DN<6>")
	)
	(segment
		(start 408.150822 -292.489128)
		(end 408.627326 -292.489128)
		(width 0.16002)
		(layer "In11.Cu")
		(net "M_L_CPU0_SB_DQS_DN<6>")
	)
	(segment
		(start 425.88307 -295.507918)
		(end 426.733208 -296.358056)
		(width 0.16002)
		(layer "In11.Cu")
		(net "M_L_CPU0_SB_DQS_DN<6>")
	)
	(segment
		(start 414.814766 -295.129458)
		(end 415.637218 -295.129458)
		(width 0.16002)
		(layer "In11.Cu")
		(net "M_L_CPU0_SB_DQS_DN<6>")
	)
	(segment
		(start 395.77645 -281.877262)
		(end 395.835632 -281.81808)
		(width 0.09525)
		(layer "In11.Cu")
		(net "M_L_CPU0_SB_DQS_DN<6>")
	)
	(segment
		(start 431.103786 -295.507918)
		(end 433.427124 -295.507918)
		(width 0.16002)
		(layer "In11.Cu")
		(net "M_L_CPU0_SB_DQS_DN<6>")
	)
	(segment
		(start 394.292328 -281.877262)
		(end 395.77645 -281.877262)
		(width 0.09525)
		(layer "In11.Cu")
		(net "M_L_CPU0_SB_DQS_DN<6>")
	)
	(segment
		(start 395.859254 -281.81808)
		(end 398.015968 -281.81808)
		(width 0.16002)
		(layer "In11.Cu")
		(net "M_L_CPU0_SB_DQS_DN<6>")
	)
	(segment
		(start 423.559732 -295.507918)
		(end 425.88307 -295.507918)
		(width 0.16002)
		(layer "In11.Cu")
		(net "M_L_CPU0_SB_DQS_DN<6>")
	)
	(segment
		(start 438.26938 -295.129458)
		(end 438.64784 -295.507918)
		(width 0.16002)
		(layer "In11.Cu")
		(net "M_L_CPU0_SB_DQS_DN<6>")
	)
	(segment
		(start 438.64784 -295.507918)
		(end 440.971178 -295.507918)
		(width 0.16002)
		(layer "In11.Cu")
		(net "M_L_CPU0_SB_DQS_DN<6>")
	)
	(segment
		(start 443.1411 -296.358056)
		(end 443.516258 -295.982898)
		(width 0.16002)
		(layer "In11.Cu")
		(net "M_L_CPU0_SB_DQS_DN<6>")
	)
	(segment
		(start 406.749758 -292.01491)
		(end 407.574242 -292.839394)
		(width 0.16002)
		(layer "In11.Cu")
		(net "M_L_CPU0_SB_DQS_DN<6>")
	)
	(segment
		(start 409.173934 -294.213026)
		(end 409.524454 -293.86276)
		(width 0.16002)
		(layer "In11.Cu")
		(net "M_L_CPU0_SB_DQS_DN<6>")
	)
	(segment
		(start 389.33501 -281.706066)
		(end 389.343392 -281.70124)
		(width 0.09525)
		(layer "In11.Cu")
		(net "M_L_CPU0_SB_DQS_DN<6>")
	)
	(segment
		(start 410.074872 -295.340024)
		(end 410.717746 -295.982898)
		(width 0.16002)
		(layer "In11.Cu")
		(net "M_L_CPU0_SB_DQS_DN<6>")
	)
	(segment
		(start 410.717746 -295.982898)
		(end 413.961326 -295.982898)
		(width 0.16002)
		(layer "In11.Cu")
		(net "M_L_CPU0_SB_DQS_DN<6>")
	)
	(segment
		(start 410.000958 -293.86276)
		(end 410.425392 -294.287194)
		(width 0.16002)
		(layer "In11.Cu")
		(net "M_L_CPU0_SB_DQS_DN<6>")
	)
	(segment
		(start 426.733208 -296.358056)
		(end 428.052992 -296.358056)
		(width 0.16002)
		(layer "In11.Cu")
		(net "M_L_CPU0_SB_DQS_DN<6>")
	)
	(arc
		(start 386.204206 -281.728418)
		(mid 386.366888 -281.75055)
		(end 386.523484 -281.70124)
		(width 0.09525)
		(layer "In11.Cu")
		(net "M_L_CPU0_SB_DQS_DN<6>")
	)
	(arc
		(start 389.343392 -281.70124)
		(mid 389.624824 -281.625485)
		(end 389.906256 -281.70124)
		(width 0.09525)
		(layer "In11.Cu")
		(net "M_L_CPU0_SB_DQS_DN<6>")
	)
	(arc
		(start 392.1633 -281.70124)
		(mid 392.299016 -281.644805)
		(end 392.444732 -281.625548)
		(width 0.09525)
		(layer "In11.Cu")
		(net "M_L_CPU0_SB_DQS_DN<6>")
	)
	(arc
		(start 391.223246 -281.70124)
		(mid 391.504678 -281.625485)
		(end 391.78611 -281.70124)
		(width 0.09525)
		(layer "In11.Cu")
		(net "M_L_CPU0_SB_DQS_DN<6>")
	)
	(arc
		(start 388.966202 -281.70124)
		(mid 389.149977 -281.752012)
		(end 389.33501 -281.706066)
		(width 0.09525)
		(layer "In11.Cu")
		(net "M_L_CPU0_SB_DQS_DN<6>")
	)
	(arc
		(start 389.914638 -281.706066)
		(mid 390.09967 -281.75198)
		(end 390.283446 -281.70124)
		(width 0.09525)
		(layer "In11.Cu")
		(net "M_L_CPU0_SB_DQS_DN<6>")
	)
	(arc
		(start 391.78611 -281.70124)
		(mid 391.969885 -281.752012)
		(end 392.154918 -281.706066)
		(width 0.09525)
		(layer "In11.Cu")
		(net "M_L_CPU0_SB_DQS_DN<6>")
	)
	(arc
		(start 386.523484 -281.70124)
		(mid 386.804916 -281.625485)
		(end 387.086348 -281.70124)
		(width 0.09525)
		(layer "In11.Cu")
		(net "M_L_CPU0_SB_DQS_DN<6>")
	)
	(arc
		(start 390.283446 -281.70124)
		(mid 390.564878 -281.625485)
		(end 390.84631 -281.70124)
		(width 0.09525)
		(layer "In11.Cu")
		(net "M_L_CPU0_SB_DQS_DN<6>")
	)
	(arc
		(start 387.463284 -281.70124)
		(mid 387.744716 -281.625485)
		(end 388.026148 -281.70124)
		(width 0.09525)
		(layer "In11.Cu")
		(net "M_L_CPU0_SB_DQS_DN<6>")
	)
	(arc
		(start 388.403338 -281.70124)
		(mid 388.68477 -281.625485)
		(end 388.966202 -281.70124)
		(width 0.09525)
		(layer "In11.Cu")
		(net "M_L_CPU0_SB_DQS_DN<6>")
	)
	(arc
		(start 388.026148 -281.70124)
		(mid 388.209923 -281.752012)
		(end 388.394956 -281.706066)
		(width 0.09525)
		(layer "In11.Cu")
		(net "M_L_CPU0_SB_DQS_DN<6>")
	)
	(arc
		(start 390.84631 -281.70124)
		(mid 391.034778 -281.751917)
		(end 391.223246 -281.70124)
		(width 0.09525)
		(layer "In11.Cu")
		(net "M_L_CPU0_SB_DQS_DN<6>")
	)
	(arc
		(start 387.086348 -281.70124)
		(mid 387.274816 -281.751917)
		(end 387.463284 -281.70124)
		(width 0.09525)
		(layer "In11.Cu")
		(net "M_L_CPU0_SB_DQS_DN<6>")
	)
	(segment
		(start 385.86791 -276.250146)
		(end 386.334762 -276.516084)
		(width 0.12954)
		(layer "F.Cu")
		(net "M_L_CPU0_SB_DQS_DN<5>")
	)
	(segment
		(start 420.508938 -287.008062)
		(end 420.884096 -286.632904)
		(width 0.16002)
		(layer "In11.Cu")
		(net "M_L_CPU0_SB_DQS_DN<5>")
	)
	(segment
		(start 417.81603 -286.157924)
		(end 418.573712 -286.157924)
		(width 0.16002)
		(layer "In11.Cu")
		(net "M_L_CPU0_SB_DQS_DN<5>")
	)
	(segment
		(start 444.990982 -285.779464)
		(end 445.813434 -285.779464)
		(width 0.16002)
		(layer "In11.Cu")
		(net "M_L_CPU0_SB_DQS_DN<5>")
	)
	(segment
		(start 430.725326 -285.779464)
		(end 431.103786 -286.157924)
		(width 0.16002)
		(layer "In11.Cu")
		(net "M_L_CPU0_SB_DQS_DN<5>")
	)
	(segment
		(start 433.427124 -286.157924)
		(end 434.277262 -287.008062)
		(width 0.16002)
		(layer "In11.Cu")
		(net "M_L_CPU0_SB_DQS_DN<5>")
	)
	(segment
		(start 411.982158 -285.698692)
		(end 412.580836 -285.698692)
		(width 0.16002)
		(layer "In11.Cu")
		(net "M_L_CPU0_SB_DQS_DN<5>")
	)
	(segment
		(start 395.77645 -275.874988)
		(end 395.835632 -275.815806)
		(width 0.09525)
		(layer "In11.Cu")
		(net "M_L_CPU0_SB_DQS_DN<5>")
	)
	(segment
		(start 386.334762 -276.516084)
		(end 386.180838 -276.781514)
		(width 0.09525)
		(layer "In11.Cu")
		(net "M_L_CPU0_SB_DQS_DN<5>")
	)
	(segment
		(start 436.593488 -286.632904)
		(end 437.446928 -285.779464)
		(width 0.16002)
		(layer "In11.Cu")
		(net "M_L_CPU0_SB_DQS_DN<5>")
	)
	(segment
		(start 428.42815 -286.632904)
		(end 429.049434 -286.632904)
		(width 0.16002)
		(layer "In11.Cu")
		(net "M_L_CPU0_SB_DQS_DN<5>")
	)
	(segment
		(start 422.35882 -285.779464)
		(end 423.181272 -285.779464)
		(width 0.16002)
		(layer "In11.Cu")
		(net "M_L_CPU0_SB_DQS_DN<5>")
	)
	(segment
		(start 386.180838 -276.781514)
		(end 386.204206 -276.868382)
		(width 0.09525)
		(layer "In11.Cu")
		(net "M_L_CPU0_SB_DQS_DN<5>")
	)
	(segment
		(start 448.434968 -285.88208)
		(end 448.915028 -285.88208)
		(width 0.16002)
		(layer "In11.Cu")
		(net "M_L_CPU0_SB_DQS_DN<5>")
	)
	(segment
		(start 429.049434 -286.632904)
		(end 429.902874 -285.779464)
		(width 0.16002)
		(layer "In11.Cu")
		(net "M_L_CPU0_SB_DQS_DN<5>")
	)
	(segment
		(start 444.137542 -286.632904)
		(end 444.990982 -285.779464)
		(width 0.16002)
		(layer "In11.Cu")
		(net "M_L_CPU0_SB_DQS_DN<5>")
	)
	(segment
		(start 392.716258 -276.835108)
		(end 392.726672 -276.841204)
		(width 0.09525)
		(layer "In11.Cu")
		(net "M_L_CPU0_SB_DQS_DN<5>")
	)
	(segment
		(start 438.26938 -285.779464)
		(end 438.64784 -286.157924)
		(width 0.16002)
		(layer "In11.Cu")
		(net "M_L_CPU0_SB_DQS_DN<5>")
	)
	(segment
		(start 447.401442 -286.00908)
		(end 448.307968 -286.00908)
		(width 0.16002)
		(layer "In11.Cu")
		(net "M_L_CPU0_SB_DQS_DN<5>")
	)
	(segment
		(start 416.798252 -285.673292)
		(end 416.958272 -285.833312)
		(width 0.16002)
		(layer "In11.Cu")
		(net "M_L_CPU0_SB_DQS_DN<5>")
	)
	(segment
		(start 413.961326 -286.632904)
		(end 414.760918 -285.833312)
		(width 0.16002)
		(layer "In11.Cu")
		(net "M_L_CPU0_SB_DQS_DN<5>")
	)
	(segment
		(start 395.835632 -275.815806)
		(end 395.859254 -275.815806)
		(width 0.09525)
		(layer "In11.Cu")
		(net "M_L_CPU0_SB_DQS_DN<5>")
	)
	(segment
		(start 413.077914 -286.632904)
		(end 413.961326 -286.632904)
		(width 0.16002)
		(layer "In11.Cu")
		(net "M_L_CPU0_SB_DQS_DN<5>")
	)
	(segment
		(start 438.64784 -286.157924)
		(end 440.971178 -286.157924)
		(width 0.16002)
		(layer "In11.Cu")
		(net "M_L_CPU0_SB_DQS_DN<5>")
	)
	(segment
		(start 412.580836 -285.698692)
		(end 412.917894 -286.03575)
		(width 0.16002)
		(layer "In11.Cu")
		(net "M_L_CPU0_SB_DQS_DN<5>")
	)
	(segment
		(start 400.420586 -275.815806)
		(end 411.237684 -286.632904)
		(width 0.16002)
		(layer "In11.Cu")
		(net "M_L_CPU0_SB_DQS_DN<5>")
	)
	(segment
		(start 412.917894 -286.472884)
		(end 413.077914 -286.632904)
		(width 0.16002)
		(layer "In11.Cu")
		(net "M_L_CPU0_SB_DQS_DN<5>")
	)
	(segment
		(start 449.813934 -286.00908)
		(end 450.088 -285.735014)
		(width 0.16002)
		(layer "In11.Cu")
		(net "M_L_CPU0_SB_DQS_DN<5>")
	)
	(segment
		(start 443.516258 -286.632904)
		(end 444.137542 -286.632904)
		(width 0.16002)
		(layer "In11.Cu")
		(net "M_L_CPU0_SB_DQS_DN<5>")
	)
	(segment
		(start 423.559732 -286.157924)
		(end 425.88307 -286.157924)
		(width 0.16002)
		(layer "In11.Cu")
		(net "M_L_CPU0_SB_DQS_DN<5>")
	)
	(segment
		(start 421.50538 -286.632904)
		(end 422.35882 -285.779464)
		(width 0.16002)
		(layer "In11.Cu")
		(net "M_L_CPU0_SB_DQS_DN<5>")
	)
	(segment
		(start 412.917894 -286.03575)
		(end 412.917894 -286.472884)
		(width 0.16002)
		(layer "In11.Cu")
		(net "M_L_CPU0_SB_DQS_DN<5>")
	)
	(segment
		(start 389.33501 -276.84603)
		(end 389.343392 -276.841204)
		(width 0.09525)
		(layer "In11.Cu")
		(net "M_L_CPU0_SB_DQS_DN<5>")
	)
	(segment
		(start 416.958272 -285.833312)
		(end 417.491418 -285.833312)
		(width 0.16002)
		(layer "In11.Cu")
		(net "M_L_CPU0_SB_DQS_DN<5>")
	)
	(segment
		(start 418.573712 -286.157924)
		(end 419.42385 -287.008062)
		(width 0.16002)
		(layer "In11.Cu")
		(net "M_L_CPU0_SB_DQS_DN<5>")
	)
	(segment
		(start 441.821316 -287.008062)
		(end 443.1411 -287.008062)
		(width 0.16002)
		(layer "In11.Cu")
		(net "M_L_CPU0_SB_DQS_DN<5>")
	)
	(segment
		(start 411.48508 -286.632904)
		(end 411.6451 -286.472884)
		(width 0.16002)
		(layer "In11.Cu")
		(net "M_L_CPU0_SB_DQS_DN<5>")
	)
	(segment
		(start 426.733208 -287.008062)
		(end 428.052992 -287.008062)
		(width 0.16002)
		(layer "In11.Cu")
		(net "M_L_CPU0_SB_DQS_DN<5>")
	)
	(segment
		(start 395.436598 -275.874988)
		(end 395.77645 -275.874988)
		(width 0.09525)
		(layer "In11.Cu")
		(net "M_L_CPU0_SB_DQS_DN<5>")
	)
	(segment
		(start 388.394956 -276.84603)
		(end 388.403338 -276.841204)
		(width 0.09525)
		(layer "In11.Cu")
		(net "M_L_CPU0_SB_DQS_DN<5>")
	)
	(segment
		(start 389.906256 -276.841204)
		(end 389.914638 -276.84603)
		(width 0.09525)
		(layer "In11.Cu")
		(net "M_L_CPU0_SB_DQS_DN<5>")
	)
	(segment
		(start 411.6451 -286.03575)
		(end 411.982158 -285.698692)
		(width 0.16002)
		(layer "In11.Cu")
		(net "M_L_CPU0_SB_DQS_DN<5>")
	)
	(segment
		(start 416.798252 -285.52013)
		(end 416.798252 -285.673292)
		(width 0.16002)
		(layer "In11.Cu")
		(net "M_L_CPU0_SB_DQS_DN<5>")
	)
	(segment
		(start 416.461194 -285.183072)
		(end 416.798252 -285.52013)
		(width 0.16002)
		(layer "In11.Cu")
		(net "M_L_CPU0_SB_DQS_DN<5>")
	)
	(segment
		(start 425.88307 -286.157924)
		(end 426.733208 -287.008062)
		(width 0.16002)
		(layer "In11.Cu")
		(net "M_L_CPU0_SB_DQS_DN<5>")
	)
	(segment
		(start 428.052992 -287.008062)
		(end 428.42815 -286.632904)
		(width 0.16002)
		(layer "In11.Cu")
		(net "M_L_CPU0_SB_DQS_DN<5>")
	)
	(segment
		(start 431.103786 -286.157924)
		(end 433.427124 -286.157924)
		(width 0.16002)
		(layer "In11.Cu")
		(net "M_L_CPU0_SB_DQS_DN<5>")
	)
	(segment
		(start 415.525458 -285.673292)
		(end 415.525458 -285.52013)
		(width 0.16002)
		(layer "In11.Cu")
		(net "M_L_CPU0_SB_DQS_DN<5>")
	)
	(segment
		(start 415.862516 -285.183072)
		(end 416.461194 -285.183072)
		(width 0.16002)
		(layer "In11.Cu")
		(net "M_L_CPU0_SB_DQS_DN<5>")
	)
	(segment
		(start 395.159738 -275.598128)
		(end 395.436598 -275.874988)
		(width 0.09525)
		(layer "In11.Cu")
		(net "M_L_CPU0_SB_DQS_DN<5>")
	)
	(segment
		(start 445.813434 -285.779464)
		(end 446.191894 -286.157924)
		(width 0.16002)
		(layer "In11.Cu")
		(net "M_L_CPU0_SB_DQS_DN<5>")
	)
	(segment
		(start 394.871702 -275.598128)
		(end 395.159738 -275.598128)
		(width 0.09525)
		(layer "In11.Cu")
		(net "M_L_CPU0_SB_DQS_DN<5>")
	)
	(segment
		(start 437.446928 -285.779464)
		(end 438.26938 -285.779464)
		(width 0.16002)
		(layer "In11.Cu")
		(net "M_L_CPU0_SB_DQS_DN<5>")
	)
	(segment
		(start 446.191894 -286.157924)
		(end 447.252598 -286.157924)
		(width 0.16002)
		(layer "In11.Cu")
		(net "M_L_CPU0_SB_DQS_DN<5>")
	)
	(segment
		(start 395.859254 -275.815806)
		(end 400.420586 -275.815806)
		(width 0.16002)
		(layer "In11.Cu")
		(net "M_L_CPU0_SB_DQS_DN<5>")
	)
	(segment
		(start 435.597046 -287.008062)
		(end 435.972204 -286.632904)
		(width 0.16002)
		(layer "In11.Cu")
		(net "M_L_CPU0_SB_DQS_DN<5>")
	)
	(segment
		(start 419.42385 -287.008062)
		(end 420.508938 -287.008062)
		(width 0.16002)
		(layer "In11.Cu")
		(net "M_L_CPU0_SB_DQS_DN<5>")
	)
	(segment
		(start 411.6451 -286.472884)
		(end 411.6451 -286.03575)
		(width 0.16002)
		(layer "In11.Cu")
		(net "M_L_CPU0_SB_DQS_DN<5>")
	)
	(segment
		(start 443.1411 -287.008062)
		(end 443.516258 -286.632904)
		(width 0.16002)
		(layer "In11.Cu")
		(net "M_L_CPU0_SB_DQS_DN<5>")
	)
	(segment
		(start 415.365438 -285.833312)
		(end 415.525458 -285.673292)
		(width 0.16002)
		(layer "In11.Cu")
		(net "M_L_CPU0_SB_DQS_DN<5>")
	)
	(segment
		(start 393.384786 -276.765512)
		(end 393.704318 -276.765512)
		(width 0.09525)
		(layer "In11.Cu")
		(net "M_L_CPU0_SB_DQS_DN<5>")
	)
	(segment
		(start 393.09167 -276.848062)
		(end 393.103608 -276.841204)
		(width 0.09525)
		(layer "In11.Cu")
		(net "M_L_CPU0_SB_DQS_DN<5>")
	)
	(segment
		(start 420.884096 -286.632904)
		(end 421.50538 -286.632904)
		(width 0.16002)
		(layer "In11.Cu")
		(net "M_L_CPU0_SB_DQS_DN<5>")
	)
	(segment
		(start 414.760918 -285.833312)
		(end 415.365438 -285.833312)
		(width 0.16002)
		(layer "In11.Cu")
		(net "M_L_CPU0_SB_DQS_DN<5>")
	)
	(segment
		(start 449.042028 -286.00908)
		(end 449.813934 -286.00908)
		(width 0.16002)
		(layer "In11.Cu")
		(net "M_L_CPU0_SB_DQS_DN<5>")
	)
	(segment
		(start 393.704318 -276.765512)
		(end 394.871702 -275.598128)
		(width 0.09525)
		(layer "In11.Cu")
		(net "M_L_CPU0_SB_DQS_DN<5>")
	)
	(segment
		(start 447.252598 -286.157924)
		(end 447.401442 -286.00908)
		(width 0.16002)
		(layer "In11.Cu")
		(net "M_L_CPU0_SB_DQS_DN<5>")
	)
	(segment
		(start 435.972204 -286.632904)
		(end 436.593488 -286.632904)
		(width 0.16002)
		(layer "In11.Cu")
		(net "M_L_CPU0_SB_DQS_DN<5>")
	)
	(segment
		(start 423.181272 -285.779464)
		(end 423.559732 -286.157924)
		(width 0.16002)
		(layer "In11.Cu")
		(net "M_L_CPU0_SB_DQS_DN<5>")
	)
	(segment
		(start 448.307968 -286.00908)
		(end 448.434968 -285.88208)
		(width 0.16002)
		(layer "In11.Cu")
		(net "M_L_CPU0_SB_DQS_DN<5>")
	)
	(segment
		(start 411.237684 -286.632904)
		(end 411.48508 -286.632904)
		(width 0.16002)
		(layer "In11.Cu")
		(net "M_L_CPU0_SB_DQS_DN<5>")
	)
	(segment
		(start 417.491418 -285.833312)
		(end 417.81603 -286.157924)
		(width 0.16002)
		(layer "In11.Cu")
		(net "M_L_CPU0_SB_DQS_DN<5>")
	)
	(segment
		(start 429.902874 -285.779464)
		(end 430.725326 -285.779464)
		(width 0.16002)
		(layer "In11.Cu")
		(net "M_L_CPU0_SB_DQS_DN<5>")
	)
	(segment
		(start 434.277262 -287.008062)
		(end 435.597046 -287.008062)
		(width 0.16002)
		(layer "In11.Cu")
		(net "M_L_CPU0_SB_DQS_DN<5>")
	)
	(segment
		(start 448.915028 -285.88208)
		(end 449.042028 -286.00908)
		(width 0.16002)
		(layer "In11.Cu")
		(net "M_L_CPU0_SB_DQS_DN<5>")
	)
	(segment
		(start 415.525458 -285.52013)
		(end 415.862516 -285.183072)
		(width 0.16002)
		(layer "In11.Cu")
		(net "M_L_CPU0_SB_DQS_DN<5>")
	)
	(segment
		(start 440.971178 -286.157924)
		(end 441.821316 -287.008062)
		(width 0.16002)
		(layer "In11.Cu")
		(net "M_L_CPU0_SB_DQS_DN<5>")
	)
	(arc
		(start 391.223246 -276.841204)
		(mid 391.504678 -276.765449)
		(end 391.78611 -276.841204)
		(width 0.09525)
		(layer "In11.Cu")
		(net "M_L_CPU0_SB_DQS_DN<5>")
	)
	(arc
		(start 387.086348 -276.841204)
		(mid 387.274816 -276.891881)
		(end 387.463284 -276.841204)
		(width 0.09525)
		(layer "In11.Cu")
		(net "M_L_CPU0_SB_DQS_DN<5>")
	)
	(arc
		(start 390.283446 -276.841204)
		(mid 390.564878 -276.765449)
		(end 390.84631 -276.841204)
		(width 0.09525)
		(layer "In11.Cu")
		(net "M_L_CPU0_SB_DQS_DN<5>")
	)
	(arc
		(start 387.463284 -276.841204)
		(mid 387.744716 -276.765449)
		(end 388.026148 -276.841204)
		(width 0.09525)
		(layer "In11.Cu")
		(net "M_L_CPU0_SB_DQS_DN<5>")
	)
	(arc
		(start 388.966202 -276.841204)
		(mid 389.149977 -276.891976)
		(end 389.33501 -276.84603)
		(width 0.09525)
		(layer "In11.Cu")
		(net "M_L_CPU0_SB_DQS_DN<5>")
	)
	(arc
		(start 390.84631 -276.841204)
		(mid 391.034778 -276.891881)
		(end 391.223246 -276.841204)
		(width 0.09525)
		(layer "In11.Cu")
		(net "M_L_CPU0_SB_DQS_DN<5>")
	)
	(arc
		(start 389.343392 -276.841204)
		(mid 389.624824 -276.765449)
		(end 389.906256 -276.841204)
		(width 0.09525)
		(layer "In11.Cu")
		(net "M_L_CPU0_SB_DQS_DN<5>")
	)
	(arc
		(start 391.78611 -276.841204)
		(mid 391.974832 -276.892008)
		(end 392.163554 -276.841204)
		(width 0.09525)
		(layer "In11.Cu")
		(net "M_L_CPU0_SB_DQS_DN<5>")
	)
	(arc
		(start 393.103608 -276.841204)
		(mid 393.2392 -276.784813)
		(end 393.384786 -276.765512)
		(width 0.09525)
		(layer "In11.Cu")
		(net "M_L_CPU0_SB_DQS_DN<5>")
	)
	(arc
		(start 388.403338 -276.841204)
		(mid 388.68477 -276.765449)
		(end 388.966202 -276.841204)
		(width 0.09525)
		(layer "In11.Cu")
		(net "M_L_CPU0_SB_DQS_DN<5>")
	)
	(arc
		(start 392.163554 -276.841204)
		(mid 392.439097 -276.765355)
		(end 392.716258 -276.835108)
		(width 0.09525)
		(layer "In11.Cu")
		(net "M_L_CPU0_SB_DQS_DN<5>")
	)
	(arc
		(start 389.914638 -276.84603)
		(mid 390.09967 -276.891944)
		(end 390.283446 -276.841204)
		(width 0.09525)
		(layer "In11.Cu")
		(net "M_L_CPU0_SB_DQS_DN<5>")
	)
	(arc
		(start 392.726672 -276.841204)
		(mid 392.908288 -276.891941)
		(end 393.09167 -276.848062)
		(width 0.09525)
		(layer "In11.Cu")
		(net "M_L_CPU0_SB_DQS_DN<5>")
	)
	(arc
		(start 386.204206 -276.868382)
		(mid 386.366888 -276.890514)
		(end 386.523484 -276.841204)
		(width 0.09525)
		(layer "In11.Cu")
		(net "M_L_CPU0_SB_DQS_DN<5>")
	)
	(arc
		(start 388.026148 -276.841204)
		(mid 388.209923 -276.891976)
		(end 388.394956 -276.84603)
		(width 0.09525)
		(layer "In11.Cu")
		(net "M_L_CPU0_SB_DQS_DN<5>")
	)
	(arc
		(start 386.523484 -276.841204)
		(mid 386.804916 -276.765449)
		(end 387.086348 -276.841204)
		(width 0.09525)
		(layer "In11.Cu")
		(net "M_L_CPU0_SB_DQS_DN<5>")
	)
	(segment
		(start 385.86791 -271.39011)
		(end 386.334762 -271.656048)
		(width 0.12954)
		(layer "F.Cu")
		(net "M_L_CPU0_SB_DQS_DN<4>")
	)
	(segment
		(start 395.331188 -270.203422)
		(end 395.77645 -270.203422)
		(width 0.09525)
		(layer "In11.Cu")
		(net "M_L_CPU0_SB_DQS_DN<4>")
	)
	(segment
		(start 444.990982 -276.42947)
		(end 445.813434 -276.42947)
		(width 0.16002)
		(layer "In11.Cu")
		(net "M_L_CPU0_SB_DQS_DN<4>")
	)
	(segment
		(start 388.394956 -271.985994)
		(end 388.403338 -271.981168)
		(width 0.09525)
		(layer "In11.Cu")
		(net "M_L_CPU0_SB_DQS_DN<4>")
	)
	(segment
		(start 425.88307 -276.80793)
		(end 426.733208 -277.658068)
		(width 0.16002)
		(layer "In11.Cu")
		(net "M_L_CPU0_SB_DQS_DN<4>")
	)
	(segment
		(start 393.650978 -271.112234)
		(end 394.35532 -270.407892)
		(width 0.09525)
		(layer "In11.Cu")
		(net "M_L_CPU0_SB_DQS_DN<4>")
	)
	(segment
		(start 433.427124 -276.80793)
		(end 434.277262 -277.658068)
		(width 0.16002)
		(layer "In11.Cu")
		(net "M_L_CPU0_SB_DQS_DN<4>")
	)
	(segment
		(start 393.538202 -271.191736)
		(end 393.573254 -271.171162)
		(width 0.09525)
		(layer "In11.Cu")
		(net "M_L_CPU0_SB_DQS_DN<4>")
	)
	(segment
		(start 395.126718 -270.407892)
		(end 395.331188 -270.203422)
		(width 0.09525)
		(layer "In11.Cu")
		(net "M_L_CPU0_SB_DQS_DN<4>")
	)
	(segment
		(start 443.1411 -277.658068)
		(end 443.516258 -277.28291)
		(width 0.16002)
		(layer "In11.Cu")
		(net "M_L_CPU0_SB_DQS_DN<4>")
	)
	(segment
		(start 426.733208 -277.658068)
		(end 428.052992 -277.658068)
		(width 0.16002)
		(layer "In11.Cu")
		(net "M_L_CPU0_SB_DQS_DN<4>")
	)
	(segment
		(start 408.056842 -272.960084)
		(end 408.53995 -273.443192)
		(width 0.16002)
		(layer "In11.Cu")
		(net "M_L_CPU0_SB_DQS_DN<4>")
	)
	(segment
		(start 410.804106 -275.707348)
		(end 411.287214 -276.190456)
		(width 0.16002)
		(layer "In11.Cu")
		(net "M_L_CPU0_SB_DQS_DN<4>")
	)
	(segment
		(start 422.35882 -276.42947)
		(end 423.181272 -276.42947)
		(width 0.16002)
		(layer "In11.Cu")
		(net "M_L_CPU0_SB_DQS_DN<4>")
	)
	(segment
		(start 429.902874 -276.42947)
		(end 430.725326 -276.42947)
		(width 0.16002)
		(layer "In11.Cu")
		(net "M_L_CPU0_SB_DQS_DN<4>")
	)
	(segment
		(start 408.845004 -274.333716)
		(end 409.430474 -274.333716)
		(width 0.16002)
		(layer "In11.Cu")
		(net "M_L_CPU0_SB_DQS_DN<4>")
	)
	(segment
		(start 437.446928 -276.42947)
		(end 438.26938 -276.42947)
		(width 0.16002)
		(layer "In11.Cu")
		(net "M_L_CPU0_SB_DQS_DN<4>")
	)
	(segment
		(start 416.339782 -276.766528)
		(end 416.339782 -276.956012)
		(width 0.16002)
		(layer "In11.Cu")
		(net "M_L_CPU0_SB_DQS_DN<4>")
	)
	(segment
		(start 440.971178 -276.80793)
		(end 441.821316 -277.658068)
		(width 0.16002)
		(layer "In11.Cu")
		(net "M_L_CPU0_SB_DQS_DN<4>")
	)
	(segment
		(start 436.593488 -277.28291)
		(end 437.446928 -276.42947)
		(width 0.16002)
		(layer "In11.Cu")
		(net "M_L_CPU0_SB_DQS_DN<4>")
	)
	(segment
		(start 438.26938 -276.42947)
		(end 438.64784 -276.80793)
		(width 0.16002)
		(layer "In11.Cu")
		(net "M_L_CPU0_SB_DQS_DN<4>")
	)
	(segment
		(start 429.049434 -277.28291)
		(end 429.902874 -276.42947)
		(width 0.16002)
		(layer "In11.Cu")
		(net "M_L_CPU0_SB_DQS_DN<4>")
	)
	(segment
		(start 438.64784 -276.80793)
		(end 440.971178 -276.80793)
		(width 0.16002)
		(layer "In11.Cu")
		(net "M_L_CPU0_SB_DQS_DN<4>")
	)
	(segment
		(start 392.154918 -271.985994)
		(end 392.1633 -271.981168)
		(width 0.09525)
		(layer "In11.Cu")
		(net "M_L_CPU0_SB_DQS_DN<4>")
	)
	(segment
		(start 395.859254 -270.14424)
		(end 404.655528 -270.14424)
		(width 0.16002)
		(layer "In11.Cu")
		(net "M_L_CPU0_SB_DQS_DN<4>")
	)
	(segment
		(start 418.180012 -276.42947)
		(end 419.40861 -277.658068)
		(width 0.16002)
		(layer "In11.Cu")
		(net "M_L_CPU0_SB_DQS_DN<4>")
	)
	(segment
		(start 395.835632 -270.14424)
		(end 395.859254 -270.14424)
		(width 0.09525)
		(layer "In11.Cu")
		(net "M_L_CPU0_SB_DQS_DN<4>")
	)
	(segment
		(start 428.42815 -277.28291)
		(end 429.049434 -277.28291)
		(width 0.16002)
		(layer "In11.Cu")
		(net "M_L_CPU0_SB_DQS_DN<4>")
	)
	(segment
		(start 408.53995 -274.028662)
		(end 408.845004 -274.333716)
		(width 0.16002)
		(layer "In11.Cu")
		(net "M_L_CPU0_SB_DQS_DN<4>")
	)
	(segment
		(start 420.884096 -277.28291)
		(end 421.50538 -277.28291)
		(width 0.16002)
		(layer "In11.Cu")
		(net "M_L_CPU0_SB_DQS_DN<4>")
	)
	(segment
		(start 386.180838 -271.921478)
		(end 386.204206 -272.008346)
		(width 0.09525)
		(layer "In11.Cu")
		(net "M_L_CPU0_SB_DQS_DN<4>")
	)
	(segment
		(start 421.50538 -277.28291)
		(end 422.35882 -276.42947)
		(width 0.16002)
		(layer "In11.Cu")
		(net "M_L_CPU0_SB_DQS_DN<4>")
	)
	(segment
		(start 389.906256 -271.981168)
		(end 389.914638 -271.985994)
		(width 0.09525)
		(layer "In11.Cu")
		(net "M_L_CPU0_SB_DQS_DN<4>")
	)
	(segment
		(start 447.252598 -276.80793)
		(end 447.401442 -276.659086)
		(width 0.16002)
		(layer "In11.Cu")
		(net "M_L_CPU0_SB_DQS_DN<4>")
	)
	(segment
		(start 395.77645 -270.203422)
		(end 395.835632 -270.14424)
		(width 0.09525)
		(layer "In11.Cu")
		(net "M_L_CPU0_SB_DQS_DN<4>")
	)
	(segment
		(start 386.334762 -271.656048)
		(end 386.180838 -271.921478)
		(width 0.09525)
		(layer "In11.Cu")
		(net "M_L_CPU0_SB_DQS_DN<4>")
	)
	(segment
		(start 447.401442 -276.659086)
		(end 448.371468 -276.659086)
		(width 0.16002)
		(layer "In11.Cu")
		(net "M_L_CPU0_SB_DQS_DN<4>")
	)
	(segment
		(start 408.53995 -273.443192)
		(end 408.53995 -274.028662)
		(width 0.16002)
		(layer "In11.Cu")
		(net "M_L_CPU0_SB_DQS_DN<4>")
	)
	(segment
		(start 394.35532 -270.407892)
		(end 395.126718 -270.407892)
		(width 0.09525)
		(layer "In11.Cu")
		(net "M_L_CPU0_SB_DQS_DN<4>")
	)
	(segment
		(start 434.277262 -277.658068)
		(end 435.597046 -277.658068)
		(width 0.16002)
		(layer "In11.Cu")
		(net "M_L_CPU0_SB_DQS_DN<4>")
	)
	(segment
		(start 411.287214 -276.190456)
		(end 411.287214 -276.775926)
		(width 0.16002)
		(layer "In11.Cu")
		(net "M_L_CPU0_SB_DQS_DN<4>")
	)
	(segment
		(start 411.794198 -277.28291)
		(end 413.961326 -277.28291)
		(width 0.16002)
		(layer "In11.Cu")
		(net "M_L_CPU0_SB_DQS_DN<4>")
	)
	(segment
		(start 423.559732 -276.80793)
		(end 425.88307 -276.80793)
		(width 0.16002)
		(layer "In11.Cu")
		(net "M_L_CPU0_SB_DQS_DN<4>")
	)
	(segment
		(start 416.002724 -276.42947)
		(end 416.339782 -276.766528)
		(width 0.16002)
		(layer "In11.Cu")
		(net "M_L_CPU0_SB_DQS_DN<4>")
	)
	(segment
		(start 445.813434 -276.42947)
		(end 446.191894 -276.80793)
		(width 0.16002)
		(layer "In11.Cu")
		(net "M_L_CPU0_SB_DQS_DN<4>")
	)
	(segment
		(start 411.287214 -276.775926)
		(end 411.794198 -277.28291)
		(width 0.16002)
		(layer "In11.Cu")
		(net "M_L_CPU0_SB_DQS_DN<4>")
	)
	(segment
		(start 410.218636 -275.707348)
		(end 410.804106 -275.707348)
		(width 0.16002)
		(layer "In11.Cu")
		(net "M_L_CPU0_SB_DQS_DN<4>")
	)
	(segment
		(start 420.508938 -277.658068)
		(end 420.884096 -277.28291)
		(width 0.16002)
		(layer "In11.Cu")
		(net "M_L_CPU0_SB_DQS_DN<4>")
	)
	(segment
		(start 417.008056 -276.766528)
		(end 417.345114 -276.42947)
		(width 0.16002)
		(layer "In11.Cu")
		(net "M_L_CPU0_SB_DQS_DN<4>")
	)
	(segment
		(start 449.813934 -276.659086)
		(end 450.088 -276.38502)
		(width 0.16002)
		(layer "In11.Cu")
		(net "M_L_CPU0_SB_DQS_DN<4>")
	)
	(segment
		(start 416.499802 -277.116032)
		(end 416.848036 -277.116032)
		(width 0.16002)
		(layer "In11.Cu")
		(net "M_L_CPU0_SB_DQS_DN<4>")
	)
	(segment
		(start 428.052992 -277.658068)
		(end 428.42815 -277.28291)
		(width 0.16002)
		(layer "In11.Cu")
		(net "M_L_CPU0_SB_DQS_DN<4>")
	)
	(segment
		(start 417.008056 -276.956012)
		(end 417.008056 -276.766528)
		(width 0.16002)
		(layer "In11.Cu")
		(net "M_L_CPU0_SB_DQS_DN<4>")
	)
	(segment
		(start 430.725326 -276.42947)
		(end 431.103786 -276.80793)
		(width 0.16002)
		(layer "In11.Cu")
		(net "M_L_CPU0_SB_DQS_DN<4>")
	)
	(segment
		(start 446.191894 -276.80793)
		(end 447.252598 -276.80793)
		(width 0.16002)
		(layer "In11.Cu")
		(net "M_L_CPU0_SB_DQS_DN<4>")
	)
	(segment
		(start 404.655528 -270.14424)
		(end 407.471372 -272.960084)
		(width 0.16002)
		(layer "In11.Cu")
		(net "M_L_CPU0_SB_DQS_DN<4>")
	)
	(segment
		(start 443.516258 -277.28291)
		(end 444.137542 -277.28291)
		(width 0.16002)
		(layer "In11.Cu")
		(net "M_L_CPU0_SB_DQS_DN<4>")
	)
	(segment
		(start 409.913582 -275.402294)
		(end 410.218636 -275.707348)
		(width 0.16002)
		(layer "In11.Cu")
		(net "M_L_CPU0_SB_DQS_DN<4>")
	)
	(segment
		(start 419.40861 -277.658068)
		(end 420.508938 -277.658068)
		(width 0.16002)
		(layer "In11.Cu")
		(net "M_L_CPU0_SB_DQS_DN<4>")
	)
	(segment
		(start 423.181272 -276.42947)
		(end 423.559732 -276.80793)
		(width 0.16002)
		(layer "In11.Cu")
		(net "M_L_CPU0_SB_DQS_DN<4>")
	)
	(segment
		(start 409.913582 -274.816824)
		(end 409.913582 -275.402294)
		(width 0.16002)
		(layer "In11.Cu")
		(net "M_L_CPU0_SB_DQS_DN<4>")
	)
	(segment
		(start 416.339782 -276.956012)
		(end 416.499802 -277.116032)
		(width 0.16002)
		(layer "In11.Cu")
		(net "M_L_CPU0_SB_DQS_DN<4>")
	)
	(segment
		(start 407.471372 -272.960084)
		(end 408.056842 -272.960084)
		(width 0.16002)
		(layer "In11.Cu")
		(net "M_L_CPU0_SB_DQS_DN<4>")
	)
	(segment
		(start 393.094972 -271.985994)
		(end 393.103354 -271.981168)
		(width 0.09525)
		(layer "In11.Cu")
		(net "M_L_CPU0_SB_DQS_DN<4>")
	)
	(segment
		(start 444.137542 -277.28291)
		(end 444.990982 -276.42947)
		(width 0.16002)
		(layer "In11.Cu")
		(net "M_L_CPU0_SB_DQS_DN<4>")
	)
	(segment
		(start 413.961326 -277.28291)
		(end 414.814766 -276.42947)
		(width 0.16002)
		(layer "In11.Cu")
		(net "M_L_CPU0_SB_DQS_DN<4>")
	)
	(segment
		(start 414.814766 -276.42947)
		(end 416.002724 -276.42947)
		(width 0.16002)
		(layer "In11.Cu")
		(net "M_L_CPU0_SB_DQS_DN<4>")
	)
	(segment
		(start 389.33501 -271.985994)
		(end 389.343392 -271.981168)
		(width 0.09525)
		(layer "In11.Cu")
		(net "M_L_CPU0_SB_DQS_DN<4>")
	)
	(segment
		(start 416.848036 -277.116032)
		(end 417.008056 -276.956012)
		(width 0.16002)
		(layer "In11.Cu")
		(net "M_L_CPU0_SB_DQS_DN<4>")
	)
	(segment
		(start 431.103786 -276.80793)
		(end 433.427124 -276.80793)
		(width 0.16002)
		(layer "In11.Cu")
		(net "M_L_CPU0_SB_DQS_DN<4>")
	)
	(segment
		(start 448.371468 -276.659086)
		(end 448.498468 -276.532086)
		(width 0.16002)
		(layer "In11.Cu")
		(net "M_L_CPU0_SB_DQS_DN<4>")
	)
	(segment
		(start 448.498468 -276.532086)
		(end 448.978528 -276.532086)
		(width 0.16002)
		(layer "In11.Cu")
		(net "M_L_CPU0_SB_DQS_DN<4>")
	)
	(segment
		(start 435.597046 -277.658068)
		(end 435.972204 -277.28291)
		(width 0.16002)
		(layer "In11.Cu")
		(net "M_L_CPU0_SB_DQS_DN<4>")
	)
	(segment
		(start 448.978528 -276.532086)
		(end 449.105528 -276.659086)
		(width 0.16002)
		(layer "In11.Cu")
		(net "M_L_CPU0_SB_DQS_DN<4>")
	)
	(segment
		(start 441.821316 -277.658068)
		(end 443.1411 -277.658068)
		(width 0.16002)
		(layer "In11.Cu")
		(net "M_L_CPU0_SB_DQS_DN<4>")
	)
	(segment
		(start 417.345114 -276.42947)
		(end 418.180012 -276.42947)
		(width 0.16002)
		(layer "In11.Cu")
		(net "M_L_CPU0_SB_DQS_DN<4>")
	)
	(segment
		(start 435.972204 -277.28291)
		(end 436.593488 -277.28291)
		(width 0.16002)
		(layer "In11.Cu")
		(net "M_L_CPU0_SB_DQS_DN<4>")
	)
	(segment
		(start 409.430474 -274.333716)
		(end 409.913582 -274.816824)
		(width 0.16002)
		(layer "In11.Cu")
		(net "M_L_CPU0_SB_DQS_DN<4>")
	)
	(segment
		(start 449.105528 -276.659086)
		(end 449.813934 -276.659086)
		(width 0.16002)
		(layer "In11.Cu")
		(net "M_L_CPU0_SB_DQS_DN<4>")
	)
	(segment
		(start 393.103354 -271.981168)
		(end 393.135866 -271.962372)
		(width 0.09525)
		(layer "In11.Cu")
		(net "M_L_CPU0_SB_DQS_DN<4>")
	)
	(arc
		(start 388.026148 -271.981168)
		(mid 388.209923 -272.03194)
		(end 388.394956 -271.985994)
		(width 0.09525)
		(layer "In11.Cu")
		(net "M_L_CPU0_SB_DQS_DN<4>")
	)
	(arc
		(start 392.726164 -271.981168)
		(mid 392.909939 -272.03194)
		(end 393.094972 -271.985994)
		(width 0.09525)
		(layer "In11.Cu")
		(net "M_L_CPU0_SB_DQS_DN<4>")
	)
	(arc
		(start 388.403338 -271.981168)
		(mid 388.68477 -271.905413)
		(end 388.966202 -271.981168)
		(width 0.09525)
		(layer "In11.Cu")
		(net "M_L_CPU0_SB_DQS_DN<4>")
	)
	(arc
		(start 389.914638 -271.985994)
		(mid 390.09967 -272.031908)
		(end 390.283446 -271.981168)
		(width 0.09525)
		(layer "In11.Cu")
		(net "M_L_CPU0_SB_DQS_DN<4>")
	)
	(arc
		(start 387.463284 -271.981168)
		(mid 387.744716 -271.905413)
		(end 388.026148 -271.981168)
		(width 0.09525)
		(layer "In11.Cu")
		(net "M_L_CPU0_SB_DQS_DN<4>")
	)
	(arc
		(start 391.78611 -271.981168)
		(mid 391.969885 -272.03194)
		(end 392.154918 -271.985994)
		(width 0.09525)
		(layer "In11.Cu")
		(net "M_L_CPU0_SB_DQS_DN<4>")
	)
	(arc
		(start 386.523484 -271.981168)
		(mid 386.804916 -271.905413)
		(end 387.086348 -271.981168)
		(width 0.09525)
		(layer "In11.Cu")
		(net "M_L_CPU0_SB_DQS_DN<4>")
	)
	(arc
		(start 393.135866 -271.962372)
		(mid 393.25114 -271.828094)
		(end 393.292584 -271.656048)
		(width 0.09525)
		(layer "In11.Cu")
		(net "M_L_CPU0_SB_DQS_DN<4>")
	)
	(arc
		(start 390.84631 -271.981168)
		(mid 391.034778 -272.031845)
		(end 391.223246 -271.981168)
		(width 0.09525)
		(layer "In11.Cu")
		(net "M_L_CPU0_SB_DQS_DN<4>")
	)
	(arc
		(start 388.966202 -271.981168)
		(mid 389.149977 -272.03194)
		(end 389.33501 -271.985994)
		(width 0.09525)
		(layer "In11.Cu")
		(net "M_L_CPU0_SB_DQS_DN<4>")
	)
	(arc
		(start 393.573254 -271.171162)
		(mid 393.614035 -271.144229)
		(end 393.650978 -271.112234)
		(width 0.09525)
		(layer "In11.Cu")
		(net "M_L_CPU0_SB_DQS_DN<4>")
	)
	(arc
		(start 390.283446 -271.981168)
		(mid 390.564878 -271.905413)
		(end 390.84631 -271.981168)
		(width 0.09525)
		(layer "In11.Cu")
		(net "M_L_CPU0_SB_DQS_DN<4>")
	)
	(arc
		(start 391.223246 -271.981168)
		(mid 391.504678 -271.905413)
		(end 391.78611 -271.981168)
		(width 0.09525)
		(layer "In11.Cu")
		(net "M_L_CPU0_SB_DQS_DN<4>")
	)
	(arc
		(start 389.343392 -271.981168)
		(mid 389.624824 -271.905413)
		(end 389.906256 -271.981168)
		(width 0.09525)
		(layer "In11.Cu")
		(net "M_L_CPU0_SB_DQS_DN<4>")
	)
	(arc
		(start 392.1633 -271.981168)
		(mid 392.444732 -271.905413)
		(end 392.726164 -271.981168)
		(width 0.09525)
		(layer "In11.Cu")
		(net "M_L_CPU0_SB_DQS_DN<4>")
	)
	(arc
		(start 387.086348 -271.981168)
		(mid 387.274816 -272.031845)
		(end 387.463284 -271.981168)
		(width 0.09525)
		(layer "In11.Cu")
		(net "M_L_CPU0_SB_DQS_DN<4>")
	)
	(arc
		(start 386.204206 -272.008346)
		(mid 386.366888 -272.030478)
		(end 386.523484 -271.981168)
		(width 0.09525)
		(layer "In11.Cu")
		(net "M_L_CPU0_SB_DQS_DN<4>")
	)
	(arc
		(start 393.292584 -271.656048)
		(mid 393.357831 -271.393445)
		(end 393.538202 -271.191736)
		(width 0.09525)
		(layer "In11.Cu")
		(net "M_L_CPU0_SB_DQS_DN<4>")
	)
	(segment
		(start 386.807964 -290.83)
		(end 387.274816 -291.095938)
		(width 0.12954)
		(layer "F.Cu")
		(net "M_L_CPU0_SB_DQS_DN<3>")
	)
	(segment
		(start 396.076678 -295.058846)
		(end 396.076678 -300.106842)
		(width 0.16002)
		(layer "In11.Cu")
		(net "M_L_CPU0_SB_DQS_DN<3>")
	)
	(segment
		(start 445.1223 -312.866786)
		(end 445.53378 -312.866786)
		(width 0.16002)
		(layer "In11.Cu")
		(net "M_L_CPU0_SB_DQS_DN<3>")
	)
	(segment
		(start 435.780942 -313.689746)
		(end 436.755286 -313.689746)
		(width 0.16002)
		(layer "In11.Cu")
		(net "M_L_CPU0_SB_DQS_DN<3>")
	)
	(segment
		(start 392.94435 -290.872164)
		(end 393.542774 -291.470588)
		(width 0.09525)
		(layer "In11.Cu")
		(net "M_L_CPU0_SB_DQS_DN<3>")
	)
	(segment
		(start 429.211232 -313.689746)
		(end 430.034192 -312.866786)
		(width 0.16002)
		(layer "In11.Cu")
		(net "M_L_CPU0_SB_DQS_DN<3>")
	)
	(segment
		(start 427.909228 -313.362086)
		(end 428.236888 -313.689746)
		(width 0.16002)
		(layer "In11.Cu")
		(net "M_L_CPU0_SB_DQS_DN<3>")
	)
	(segment
		(start 437.989726 -312.866786)
		(end 438.34431 -312.512202)
		(width 0.16002)
		(layer "In11.Cu")
		(net "M_L_CPU0_SB_DQS_DN<3>")
	)
	(segment
		(start 437.578246 -312.866786)
		(end 437.989726 -312.866786)
		(width 0.16002)
		(layer "In11.Cu")
		(net "M_L_CPU0_SB_DQS_DN<3>")
	)
	(segment
		(start 423.256202 -312.512202)
		(end 424.91533 -312.512202)
		(width 0.16002)
		(layer "In11.Cu")
		(net "M_L_CPU0_SB_DQS_DN<3>")
	)
	(segment
		(start 395.527022 -294.42537)
		(end 395.527022 -294.50919)
		(width 0.09525)
		(layer "In11.Cu")
		(net "M_L_CPU0_SB_DQS_DN<3>")
	)
	(segment
		(start 451.826884 -313.704986)
		(end 452.020686 -313.511184)
		(width 0.16002)
		(layer "In11.Cu")
		(net "M_L_CPU0_SB_DQS_DN<3>")
	)
	(segment
		(start 396.076678 -300.106842)
		(end 409.659582 -313.689746)
		(width 0.16002)
		(layer "In11.Cu")
		(net "M_L_CPU0_SB_DQS_DN<3>")
	)
	(segment
		(start 433.309268 -313.362086)
		(end 435.453282 -313.362086)
		(width 0.16002)
		(layer "In11.Cu")
		(net "M_L_CPU0_SB_DQS_DN<3>")
	)
	(segment
		(start 452.020686 -313.511184)
		(end 453.914256 -313.511184)
		(width 0.16002)
		(layer "In11.Cu")
		(net "M_L_CPU0_SB_DQS_DN<3>")
	)
	(segment
		(start 430.445672 -312.866786)
		(end 430.800256 -312.512202)
		(width 0.16002)
		(layer "In11.Cu")
		(net "M_L_CPU0_SB_DQS_DN<3>")
	)
	(segment
		(start 425.765214 -313.362086)
		(end 427.909228 -313.362086)
		(width 0.16002)
		(layer "In11.Cu")
		(net "M_L_CPU0_SB_DQS_DN<3>")
	)
	(segment
		(start 430.800256 -312.512202)
		(end 432.459384 -312.512202)
		(width 0.16002)
		(layer "In11.Cu")
		(net "M_L_CPU0_SB_DQS_DN<3>")
	)
	(segment
		(start 424.91533 -312.512202)
		(end 425.765214 -313.362086)
		(width 0.16002)
		(layer "In11.Cu")
		(net "M_L_CPU0_SB_DQS_DN<3>")
	)
	(segment
		(start 432.459384 -312.512202)
		(end 433.309268 -313.362086)
		(width 0.16002)
		(layer "In11.Cu")
		(net "M_L_CPU0_SB_DQS_DN<3>")
	)
	(segment
		(start 417.371276 -312.512202)
		(end 418.22116 -313.362086)
		(width 0.16002)
		(layer "In11.Cu")
		(net "M_L_CPU0_SB_DQS_DN<3>")
	)
	(segment
		(start 448.121532 -313.086242)
		(end 450.543168 -313.086242)
		(width 0.16002)
		(layer "In11.Cu")
		(net "M_L_CPU0_SB_DQS_DN<3>")
	)
	(segment
		(start 415.712148 -312.512202)
		(end 417.371276 -312.512202)
		(width 0.16002)
		(layer "In11.Cu")
		(net "M_L_CPU0_SB_DQS_DN<3>")
	)
	(segment
		(start 393.744704 -291.772594)
		(end 394.360146 -293.258494)
		(width 0.09525)
		(layer "In11.Cu")
		(net "M_L_CPU0_SB_DQS_DN<3>")
	)
	(segment
		(start 421.667178 -313.689746)
		(end 422.490138 -312.866786)
		(width 0.16002)
		(layer "In11.Cu")
		(net "M_L_CPU0_SB_DQS_DN<3>")
	)
	(segment
		(start 428.236888 -313.689746)
		(end 429.211232 -313.689746)
		(width 0.16002)
		(layer "In11.Cu")
		(net "M_L_CPU0_SB_DQS_DN<3>")
	)
	(segment
		(start 420.692834 -313.689746)
		(end 421.667178 -313.689746)
		(width 0.16002)
		(layer "In11.Cu")
		(net "M_L_CPU0_SB_DQS_DN<3>")
	)
	(segment
		(start 388.394956 -290.765992)
		(end 388.403338 -290.770818)
		(width 0.09525)
		(layer "In11.Cu")
		(net "M_L_CPU0_SB_DQS_DN<3>")
	)
	(segment
		(start 409.659582 -313.689746)
		(end 414.123124 -313.689746)
		(width 0.16002)
		(layer "In11.Cu")
		(net "M_L_CPU0_SB_DQS_DN<3>")
	)
	(segment
		(start 447.547492 -312.512202)
		(end 448.121532 -313.086242)
		(width 0.16002)
		(layer "In11.Cu")
		(net "M_L_CPU0_SB_DQS_DN<3>")
	)
	(segment
		(start 395.543786 -294.525954)
		(end 396.076678 -295.058846)
		(width 0.16002)
		(layer "In11.Cu")
		(net "M_L_CPU0_SB_DQS_DN<3>")
	)
	(segment
		(start 395.527022 -294.50919)
		(end 395.543786 -294.525954)
		(width 0.09525)
		(layer "In11.Cu")
		(net "M_L_CPU0_SB_DQS_DN<3>")
	)
	(segment
		(start 414.946084 -312.866786)
		(end 415.357564 -312.866786)
		(width 0.16002)
		(layer "In11.Cu")
		(net "M_L_CPU0_SB_DQS_DN<3>")
	)
	(segment
		(start 440.853322 -313.362086)
		(end 442.997336 -313.362086)
		(width 0.16002)
		(layer "In11.Cu")
		(net "M_L_CPU0_SB_DQS_DN<3>")
	)
	(segment
		(start 387.42874 -290.830508)
		(end 387.529578 -290.803838)
		(width 0.09525)
		(layer "In11.Cu")
		(net "M_L_CPU0_SB_DQS_DN<3>")
	)
	(segment
		(start 445.53378 -312.866786)
		(end 445.888364 -312.512202)
		(width 0.16002)
		(layer "In11.Cu")
		(net "M_L_CPU0_SB_DQS_DN<3>")
	)
	(segment
		(start 394.360146 -293.258494)
		(end 395.527022 -294.42537)
		(width 0.09525)
		(layer "In11.Cu")
		(net "M_L_CPU0_SB_DQS_DN<3>")
	)
	(segment
		(start 443.324996 -313.689746)
		(end 444.29934 -313.689746)
		(width 0.16002)
		(layer "In11.Cu")
		(net "M_L_CPU0_SB_DQS_DN<3>")
	)
	(segment
		(start 418.22116 -313.362086)
		(end 420.365174 -313.362086)
		(width 0.16002)
		(layer "In11.Cu")
		(net "M_L_CPU0_SB_DQS_DN<3>")
	)
	(segment
		(start 414.123124 -313.689746)
		(end 414.946084 -312.866786)
		(width 0.16002)
		(layer "In11.Cu")
		(net "M_L_CPU0_SB_DQS_DN<3>")
	)
	(segment
		(start 450.543168 -313.086242)
		(end 451.161912 -313.704986)
		(width 0.16002)
		(layer "In11.Cu")
		(net "M_L_CPU0_SB_DQS_DN<3>")
	)
	(segment
		(start 387.274816 -291.095938)
		(end 387.42874 -290.830508)
		(width 0.09525)
		(layer "In11.Cu")
		(net "M_L_CPU0_SB_DQS_DN<3>")
	)
	(segment
		(start 451.161912 -313.704986)
		(end 451.826884 -313.704986)
		(width 0.16002)
		(layer "In11.Cu")
		(net "M_L_CPU0_SB_DQS_DN<3>")
	)
	(segment
		(start 438.34431 -312.512202)
		(end 440.003438 -312.512202)
		(width 0.16002)
		(layer "In11.Cu")
		(net "M_L_CPU0_SB_DQS_DN<3>")
	)
	(segment
		(start 420.365174 -313.362086)
		(end 420.692834 -313.689746)
		(width 0.16002)
		(layer "In11.Cu")
		(net "M_L_CPU0_SB_DQS_DN<3>")
	)
	(segment
		(start 389.906256 -290.770818)
		(end 389.914638 -290.765992)
		(width 0.09525)
		(layer "In11.Cu")
		(net "M_L_CPU0_SB_DQS_DN<3>")
	)
	(segment
		(start 415.357564 -312.866786)
		(end 415.712148 -312.512202)
		(width 0.16002)
		(layer "In11.Cu")
		(net "M_L_CPU0_SB_DQS_DN<3>")
	)
	(segment
		(start 453.914256 -313.511184)
		(end 454.188068 -313.784996)
		(width 0.16002)
		(layer "In11.Cu")
		(net "M_L_CPU0_SB_DQS_DN<3>")
	)
	(segment
		(start 442.997336 -313.362086)
		(end 443.324996 -313.689746)
		(width 0.16002)
		(layer "In11.Cu")
		(net "M_L_CPU0_SB_DQS_DN<3>")
	)
	(segment
		(start 391.974832 -290.71951)
		(end 392.575796 -290.71951)
		(width 0.09525)
		(layer "In11.Cu")
		(net "M_L_CPU0_SB_DQS_DN<3>")
	)
	(segment
		(start 436.755286 -313.689746)
		(end 437.578246 -312.866786)
		(width 0.16002)
		(layer "In11.Cu")
		(net "M_L_CPU0_SB_DQS_DN<3>")
	)
	(segment
		(start 435.453282 -313.362086)
		(end 435.780942 -313.689746)
		(width 0.16002)
		(layer "In11.Cu")
		(net "M_L_CPU0_SB_DQS_DN<3>")
	)
	(segment
		(start 444.29934 -313.689746)
		(end 445.1223 -312.866786)
		(width 0.16002)
		(layer "In11.Cu")
		(net "M_L_CPU0_SB_DQS_DN<3>")
	)
	(segment
		(start 389.33501 -290.765992)
		(end 389.343392 -290.770818)
		(width 0.09525)
		(layer "In11.Cu")
		(net "M_L_CPU0_SB_DQS_DN<3>")
	)
	(segment
		(start 445.888364 -312.512202)
		(end 447.547492 -312.512202)
		(width 0.16002)
		(layer "In11.Cu")
		(net "M_L_CPU0_SB_DQS_DN<3>")
	)
	(segment
		(start 422.901618 -312.866786)
		(end 423.256202 -312.512202)
		(width 0.16002)
		(layer "In11.Cu")
		(net "M_L_CPU0_SB_DQS_DN<3>")
	)
	(segment
		(start 430.034192 -312.866786)
		(end 430.445672 -312.866786)
		(width 0.16002)
		(layer "In11.Cu")
		(net "M_L_CPU0_SB_DQS_DN<3>")
	)
	(segment
		(start 422.490138 -312.866786)
		(end 422.901618 -312.866786)
		(width 0.16002)
		(layer "In11.Cu")
		(net "M_L_CPU0_SB_DQS_DN<3>")
	)
	(segment
		(start 440.003438 -312.512202)
		(end 440.853322 -313.362086)
		(width 0.16002)
		(layer "In11.Cu")
		(net "M_L_CPU0_SB_DQS_DN<3>")
	)
	(arc
		(start 387.549898 -290.811712)
		(mid 387.79261 -290.844595)
		(end 388.026148 -290.770818)
		(width 0.09525)
		(layer "In11.Cu")
		(net "M_L_CPU0_SB_DQS_DN<3>")
	)
	(arc
		(start 388.026148 -290.770818)
		(mid 388.209923 -290.720046)
		(end 388.394956 -290.765992)
		(width 0.09525)
		(layer "In11.Cu")
		(net "M_L_CPU0_SB_DQS_DN<3>")
	)
	(arc
		(start 388.403338 -290.770818)
		(mid 388.68477 -290.846573)
		(end 388.966202 -290.770818)
		(width 0.09525)
		(layer "In11.Cu")
		(net "M_L_CPU0_SB_DQS_DN<3>")
	)
	(arc
		(start 391.78611 -290.770818)
		(mid 391.877076 -290.732665)
		(end 391.974832 -290.71951)
		(width 0.09525)
		(layer "In11.Cu")
		(net "M_L_CPU0_SB_DQS_DN<3>")
	)
	(arc
		(start 388.966202 -290.770818)
		(mid 389.149977 -290.720046)
		(end 389.33501 -290.765992)
		(width 0.09525)
		(layer "In11.Cu")
		(net "M_L_CPU0_SB_DQS_DN<3>")
	)
	(arc
		(start 390.283446 -290.770818)
		(mid 390.564878 -290.846573)
		(end 390.84631 -290.770818)
		(width 0.09525)
		(layer "In11.Cu")
		(net "M_L_CPU0_SB_DQS_DN<3>")
	)
	(arc
		(start 392.575796 -290.71951)
		(mid 392.775254 -290.759185)
		(end 392.94435 -290.872164)
		(width 0.09525)
		(layer "In11.Cu")
		(net "M_L_CPU0_SB_DQS_DN<3>")
	)
	(arc
		(start 389.343392 -290.770818)
		(mid 389.624824 -290.846573)
		(end 389.906256 -290.770818)
		(width 0.09525)
		(layer "In11.Cu")
		(net "M_L_CPU0_SB_DQS_DN<3>")
	)
	(arc
		(start 391.223246 -290.770818)
		(mid 391.504678 -290.846573)
		(end 391.78611 -290.770818)
		(width 0.09525)
		(layer "In11.Cu")
		(net "M_L_CPU0_SB_DQS_DN<3>")
	)
	(arc
		(start 387.529578 -290.803838)
		(mid 387.5397 -290.807873)
		(end 387.549898 -290.811712)
		(width 0.09525)
		(layer "In11.Cu")
		(net "M_L_CPU0_SB_DQS_DN<3>")
	)
	(arc
		(start 389.914638 -290.765992)
		(mid 390.09967 -290.720078)
		(end 390.283446 -290.770818)
		(width 0.09525)
		(layer "In11.Cu")
		(net "M_L_CPU0_SB_DQS_DN<3>")
	)
	(arc
		(start 393.542774 -291.470588)
		(mid 393.658595 -291.611656)
		(end 393.744704 -291.772594)
		(width 0.09525)
		(layer "In11.Cu")
		(net "M_L_CPU0_SB_DQS_DN<3>")
	)
	(arc
		(start 390.84631 -290.770818)
		(mid 391.034778 -290.720141)
		(end 391.223246 -290.770818)
		(width 0.09525)
		(layer "In11.Cu")
		(net "M_L_CPU0_SB_DQS_DN<3>")
	)
	(segment
		(start 386.807964 -285.970218)
		(end 387.274816 -286.236156)
		(width 0.12954)
		(layer "F.Cu")
		(net "M_L_CPU0_SB_DQS_DN<2>")
	)
	(segment
		(start 435.780942 -304.339752)
		(end 436.755286 -304.339752)
		(width 0.16002)
		(layer "In11.Cu")
		(net "M_L_CPU0_SB_DQS_DN<2>")
	)
	(segment
		(start 425.765214 -304.012092)
		(end 427.909228 -304.012092)
		(width 0.16002)
		(layer "In11.Cu")
		(net "M_L_CPU0_SB_DQS_DN<2>")
	)
	(segment
		(start 445.53378 -303.516792)
		(end 445.888364 -303.162208)
		(width 0.16002)
		(layer "In11.Cu")
		(net "M_L_CPU0_SB_DQS_DN<2>")
	)
	(segment
		(start 418.22116 -304.012092)
		(end 420.365174 -304.012092)
		(width 0.16002)
		(layer "In11.Cu")
		(net "M_L_CPU0_SB_DQS_DN<2>")
	)
	(segment
		(start 387.274816 -286.236156)
		(end 387.42874 -285.970726)
		(width 0.09525)
		(layer "In11.Cu")
		(net "M_L_CPU0_SB_DQS_DN<2>")
	)
	(segment
		(start 428.236888 -304.339752)
		(end 429.211232 -304.339752)
		(width 0.16002)
		(layer "In11.Cu")
		(net "M_L_CPU0_SB_DQS_DN<2>")
	)
	(segment
		(start 451.161912 -304.354992)
		(end 451.826884 -304.354992)
		(width 0.16002)
		(layer "In11.Cu")
		(net "M_L_CPU0_SB_DQS_DN<2>")
	)
	(segment
		(start 395.859254 -286.880554)
		(end 395.984984 -286.880554)
		(width 0.16002)
		(layer "In11.Cu")
		(net "M_L_CPU0_SB_DQS_DN<2>")
	)
	(segment
		(start 395.423898 -286.821372)
		(end 395.77645 -286.821372)
		(width 0.09525)
		(layer "In11.Cu")
		(net "M_L_CPU0_SB_DQS_DN<2>")
	)
	(segment
		(start 437.578246 -303.516792)
		(end 437.989726 -303.516792)
		(width 0.16002)
		(layer "In11.Cu")
		(net "M_L_CPU0_SB_DQS_DN<2>")
	)
	(segment
		(start 430.445672 -303.516792)
		(end 430.800256 -303.162208)
		(width 0.16002)
		(layer "In11.Cu")
		(net "M_L_CPU0_SB_DQS_DN<2>")
	)
	(segment
		(start 395.77645 -286.821372)
		(end 395.835632 -286.880554)
		(width 0.09525)
		(layer "In11.Cu")
		(net "M_L_CPU0_SB_DQS_DN<2>")
	)
	(segment
		(start 420.692834 -304.339752)
		(end 421.667178 -304.339752)
		(width 0.16002)
		(layer "In11.Cu")
		(net "M_L_CPU0_SB_DQS_DN<2>")
	)
	(segment
		(start 392.725148 -285.911036)
		(end 392.737086 -285.904178)
		(width 0.09525)
		(layer "In11.Cu")
		(net "M_L_CPU0_SB_DQS_DN<2>")
	)
	(segment
		(start 452.020686 -304.16119)
		(end 453.914256 -304.16119)
		(width 0.16002)
		(layer "In11.Cu")
		(net "M_L_CPU0_SB_DQS_DN<2>")
	)
	(segment
		(start 444.29934 -304.339752)
		(end 445.1223 -303.516792)
		(width 0.16002)
		(layer "In11.Cu")
		(net "M_L_CPU0_SB_DQS_DN<2>")
	)
	(segment
		(start 445.1223 -303.516792)
		(end 445.53378 -303.516792)
		(width 0.16002)
		(layer "In11.Cu")
		(net "M_L_CPU0_SB_DQS_DN<2>")
	)
	(segment
		(start 451.826884 -304.354992)
		(end 452.020686 -304.16119)
		(width 0.16002)
		(layer "In11.Cu")
		(net "M_L_CPU0_SB_DQS_DN<2>")
	)
	(segment
		(start 410.51353 -304.339752)
		(end 414.123124 -304.339752)
		(width 0.16002)
		(layer "In11.Cu")
		(net "M_L_CPU0_SB_DQS_DN<2>")
	)
	(segment
		(start 443.324996 -304.339752)
		(end 444.29934 -304.339752)
		(width 0.16002)
		(layer "In11.Cu")
		(net "M_L_CPU0_SB_DQS_DN<2>")
	)
	(segment
		(start 437.989726 -303.516792)
		(end 438.34431 -303.162208)
		(width 0.16002)
		(layer "In11.Cu")
		(net "M_L_CPU0_SB_DQS_DN<2>")
	)
	(segment
		(start 447.547492 -303.162208)
		(end 448.341496 -303.956212)
		(width 0.16002)
		(layer "In11.Cu")
		(net "M_L_CPU0_SB_DQS_DN<2>")
	)
	(segment
		(start 395.835632 -286.880554)
		(end 395.859254 -286.880554)
		(width 0.09525)
		(layer "In11.Cu")
		(net "M_L_CPU0_SB_DQS_DN<2>")
	)
	(segment
		(start 435.453282 -304.012092)
		(end 435.780942 -304.339752)
		(width 0.16002)
		(layer "In11.Cu")
		(net "M_L_CPU0_SB_DQS_DN<2>")
	)
	(segment
		(start 395.205458 -286.602932)
		(end 395.423898 -286.821372)
		(width 0.09525)
		(layer "In11.Cu")
		(net "M_L_CPU0_SB_DQS_DN<2>")
	)
	(segment
		(start 392.163046 -285.911036)
		(end 392.18108 -285.92145)
		(width 0.09525)
		(layer "In11.Cu")
		(net "M_L_CPU0_SB_DQS_DN<2>")
	)
	(segment
		(start 414.123124 -304.339752)
		(end 414.946084 -303.516792)
		(width 0.16002)
		(layer "In11.Cu")
		(net "M_L_CPU0_SB_DQS_DN<2>")
	)
	(segment
		(start 401.700238 -295.52646)
		(end 410.51353 -304.339752)
		(width 0.16002)
		(layer "In11.Cu")
		(net "M_L_CPU0_SB_DQS_DN<2>")
	)
	(segment
		(start 450.763132 -303.956212)
		(end 451.161912 -304.354992)
		(width 0.16002)
		(layer "In11.Cu")
		(net "M_L_CPU0_SB_DQS_DN<2>")
	)
	(segment
		(start 388.394956 -285.90621)
		(end 388.403338 -285.911036)
		(width 0.09525)
		(layer "In11.Cu")
		(net "M_L_CPU0_SB_DQS_DN<2>")
	)
	(segment
		(start 427.909228 -304.012092)
		(end 428.236888 -304.339752)
		(width 0.16002)
		(layer "In11.Cu")
		(net "M_L_CPU0_SB_DQS_DN<2>")
	)
	(segment
		(start 433.309268 -304.012092)
		(end 435.453282 -304.012092)
		(width 0.16002)
		(layer "In11.Cu")
		(net "M_L_CPU0_SB_DQS_DN<2>")
	)
	(segment
		(start 393.384786 -285.987236)
		(end 394.018262 -285.987236)
		(width 0.09525)
		(layer "In11.Cu")
		(net "M_L_CPU0_SB_DQS_DN<2>")
	)
	(segment
		(start 420.365174 -304.012092)
		(end 420.692834 -304.339752)
		(width 0.16002)
		(layer "In11.Cu")
		(net "M_L_CPU0_SB_DQS_DN<2>")
	)
	(segment
		(start 395.984984 -286.880554)
		(end 401.700238 -292.595808)
		(width 0.16002)
		(layer "In11.Cu")
		(net "M_L_CPU0_SB_DQS_DN<2>")
	)
	(segment
		(start 414.946084 -303.516792)
		(end 415.357564 -303.516792)
		(width 0.16002)
		(layer "In11.Cu")
		(net "M_L_CPU0_SB_DQS_DN<2>")
	)
	(segment
		(start 430.034192 -303.516792)
		(end 430.445672 -303.516792)
		(width 0.16002)
		(layer "In11.Cu")
		(net "M_L_CPU0_SB_DQS_DN<2>")
	)
	(segment
		(start 424.91533 -303.162208)
		(end 425.765214 -304.012092)
		(width 0.16002)
		(layer "In11.Cu")
		(net "M_L_CPU0_SB_DQS_DN<2>")
	)
	(segment
		(start 440.003438 -303.162208)
		(end 440.853322 -304.012092)
		(width 0.16002)
		(layer "In11.Cu")
		(net "M_L_CPU0_SB_DQS_DN<2>")
	)
	(segment
		(start 442.997336 -304.012092)
		(end 443.324996 -304.339752)
		(width 0.16002)
		(layer "In11.Cu")
		(net "M_L_CPU0_SB_DQS_DN<2>")
	)
	(segment
		(start 387.42874 -285.970726)
		(end 387.529578 -285.944056)
		(width 0.09525)
		(layer "In11.Cu")
		(net "M_L_CPU0_SB_DQS_DN<2>")
	)
	(segment
		(start 440.853322 -304.012092)
		(end 442.997336 -304.012092)
		(width 0.16002)
		(layer "In11.Cu")
		(net "M_L_CPU0_SB_DQS_DN<2>")
	)
	(segment
		(start 389.906256 -285.911036)
		(end 389.914638 -285.90621)
		(width 0.09525)
		(layer "In11.Cu")
		(net "M_L_CPU0_SB_DQS_DN<2>")
	)
	(segment
		(start 430.800256 -303.162208)
		(end 432.459384 -303.162208)
		(width 0.16002)
		(layer "In11.Cu")
		(net "M_L_CPU0_SB_DQS_DN<2>")
	)
	(segment
		(start 453.914256 -304.16119)
		(end 454.188068 -304.435002)
		(width 0.16002)
		(layer "In11.Cu")
		(net "M_L_CPU0_SB_DQS_DN<2>")
	)
	(segment
		(start 436.755286 -304.339752)
		(end 437.578246 -303.516792)
		(width 0.16002)
		(layer "In11.Cu")
		(net "M_L_CPU0_SB_DQS_DN<2>")
	)
	(segment
		(start 392.151108 -285.904178)
		(end 392.163046 -285.911036)
		(width 0.09525)
		(layer "In11.Cu")
		(net "M_L_CPU0_SB_DQS_DN<2>")
	)
	(segment
		(start 422.901618 -303.516792)
		(end 423.256202 -303.162208)
		(width 0.16002)
		(layer "In11.Cu")
		(net "M_L_CPU0_SB_DQS_DN<2>")
	)
	(segment
		(start 394.633958 -286.602932)
		(end 395.205458 -286.602932)
		(width 0.09525)
		(layer "In11.Cu")
		(net "M_L_CPU0_SB_DQS_DN<2>")
	)
	(segment
		(start 415.712148 -303.162208)
		(end 417.371276 -303.162208)
		(width 0.16002)
		(layer "In11.Cu")
		(net "M_L_CPU0_SB_DQS_DN<2>")
	)
	(segment
		(start 417.371276 -303.162208)
		(end 418.22116 -304.012092)
		(width 0.16002)
		(layer "In11.Cu")
		(net "M_L_CPU0_SB_DQS_DN<2>")
	)
	(segment
		(start 445.888364 -303.162208)
		(end 447.547492 -303.162208)
		(width 0.16002)
		(layer "In11.Cu")
		(net "M_L_CPU0_SB_DQS_DN<2>")
	)
	(segment
		(start 394.018262 -285.987236)
		(end 394.633958 -286.602932)
		(width 0.09525)
		(layer "In11.Cu")
		(net "M_L_CPU0_SB_DQS_DN<2>")
	)
	(segment
		(start 415.357564 -303.516792)
		(end 415.712148 -303.162208)
		(width 0.16002)
		(layer "In11.Cu")
		(net "M_L_CPU0_SB_DQS_DN<2>")
	)
	(segment
		(start 432.459384 -303.162208)
		(end 433.309268 -304.012092)
		(width 0.16002)
		(layer "In11.Cu")
		(net "M_L_CPU0_SB_DQS_DN<2>")
	)
	(segment
		(start 429.211232 -304.339752)
		(end 430.034192 -303.516792)
		(width 0.16002)
		(layer "In11.Cu")
		(net "M_L_CPU0_SB_DQS_DN<2>")
	)
	(segment
		(start 401.700238 -292.595808)
		(end 401.700238 -295.52646)
		(width 0.16002)
		(layer "In11.Cu")
		(net "M_L_CPU0_SB_DQS_DN<2>")
	)
	(segment
		(start 422.490138 -303.516792)
		(end 422.901618 -303.516792)
		(width 0.16002)
		(layer "In11.Cu")
		(net "M_L_CPU0_SB_DQS_DN<2>")
	)
	(segment
		(start 423.256202 -303.162208)
		(end 424.91533 -303.162208)
		(width 0.16002)
		(layer "In11.Cu")
		(net "M_L_CPU0_SB_DQS_DN<2>")
	)
	(segment
		(start 448.341496 -303.956212)
		(end 450.763132 -303.956212)
		(width 0.16002)
		(layer "In11.Cu")
		(net "M_L_CPU0_SB_DQS_DN<2>")
	)
	(segment
		(start 438.34431 -303.162208)
		(end 440.003438 -303.162208)
		(width 0.16002)
		(layer "In11.Cu")
		(net "M_L_CPU0_SB_DQS_DN<2>")
	)
	(segment
		(start 389.33501 -285.90621)
		(end 389.343392 -285.911036)
		(width 0.09525)
		(layer "In11.Cu")
		(net "M_L_CPU0_SB_DQS_DN<2>")
	)
	(segment
		(start 421.667178 -304.339752)
		(end 422.490138 -303.516792)
		(width 0.16002)
		(layer "In11.Cu")
		(net "M_L_CPU0_SB_DQS_DN<2>")
	)
	(arc
		(start 388.026148 -285.911036)
		(mid 388.209923 -285.860264)
		(end 388.394956 -285.90621)
		(width 0.09525)
		(layer "In11.Cu")
		(net "M_L_CPU0_SB_DQS_DN<2>")
	)
	(arc
		(start 388.403338 -285.911036)
		(mid 388.68477 -285.986791)
		(end 388.966202 -285.911036)
		(width 0.09525)
		(layer "In11.Cu")
		(net "M_L_CPU0_SB_DQS_DN<2>")
	)
	(arc
		(start 389.343392 -285.911036)
		(mid 389.624824 -285.986791)
		(end 389.906256 -285.911036)
		(width 0.09525)
		(layer "In11.Cu")
		(net "M_L_CPU0_SB_DQS_DN<2>")
	)
	(arc
		(start 391.78611 -285.911036)
		(mid 391.967726 -285.860299)
		(end 392.151108 -285.904178)
		(width 0.09525)
		(layer "In11.Cu")
		(net "M_L_CPU0_SB_DQS_DN<2>")
	)
	(arc
		(start 393.102592 -285.911036)
		(mid 393.238644 -285.967805)
		(end 393.384786 -285.987236)
		(width 0.09525)
		(layer "In11.Cu")
		(net "M_L_CPU0_SB_DQS_DN<2>")
	)
	(arc
		(start 389.914638 -285.90621)
		(mid 390.09967 -285.860296)
		(end 390.283446 -285.911036)
		(width 0.09525)
		(layer "In11.Cu")
		(net "M_L_CPU0_SB_DQS_DN<2>")
	)
	(arc
		(start 388.966202 -285.911036)
		(mid 389.149977 -285.860264)
		(end 389.33501 -285.90621)
		(width 0.09525)
		(layer "In11.Cu")
		(net "M_L_CPU0_SB_DQS_DN<2>")
	)
	(arc
		(start 387.529578 -285.944056)
		(mid 387.5397 -285.948091)
		(end 387.549898 -285.95193)
		(width 0.09525)
		(layer "In11.Cu")
		(net "M_L_CPU0_SB_DQS_DN<2>")
	)
	(arc
		(start 390.283446 -285.911036)
		(mid 390.564878 -285.986791)
		(end 390.84631 -285.911036)
		(width 0.09525)
		(layer "In11.Cu")
		(net "M_L_CPU0_SB_DQS_DN<2>")
	)
	(arc
		(start 392.18108 -285.92145)
		(mid 392.45446 -285.986671)
		(end 392.725148 -285.911036)
		(width 0.09525)
		(layer "In11.Cu")
		(net "M_L_CPU0_SB_DQS_DN<2>")
	)
	(arc
		(start 391.223246 -285.911036)
		(mid 391.504678 -285.986791)
		(end 391.78611 -285.911036)
		(width 0.09525)
		(layer "In11.Cu")
		(net "M_L_CPU0_SB_DQS_DN<2>")
	)
	(arc
		(start 392.737086 -285.904178)
		(mid 392.920721 -285.860228)
		(end 393.102592 -285.911036)
		(width 0.09525)
		(layer "In11.Cu")
		(net "M_L_CPU0_SB_DQS_DN<2>")
	)
	(arc
		(start 387.549898 -285.95193)
		(mid 387.79261 -285.984813)
		(end 388.026148 -285.911036)
		(width 0.09525)
		(layer "In11.Cu")
		(net "M_L_CPU0_SB_DQS_DN<2>")
	)
	(arc
		(start 390.84631 -285.911036)
		(mid 391.034778 -285.860359)
		(end 391.223246 -285.911036)
		(width 0.09525)
		(layer "In11.Cu")
		(net "M_L_CPU0_SB_DQS_DN<2>")
	)
	(segment
		(start 386.807964 -281.110182)
		(end 387.274816 -281.37612)
		(width 0.12954)
		(layer "F.Cu")
		(net "M_L_CPU0_SB_DQS_DN<1>")
	)
	(segment
		(start 435.453282 -294.662098)
		(end 435.780942 -294.989758)
		(width 0.16002)
		(layer "In11.Cu")
		(net "M_L_CPU0_SB_DQS_DN<1>")
	)
	(segment
		(start 415.357564 -294.166798)
		(end 415.712148 -293.812214)
		(width 0.16002)
		(layer "In11.Cu")
		(net "M_L_CPU0_SB_DQS_DN<1>")
	)
	(segment
		(start 395.123162 -280.719022)
		(end 395.574012 -281.169872)
		(width 0.09525)
		(layer "In11.Cu")
		(net "M_L_CPU0_SB_DQS_DN<1>")
	)
	(segment
		(start 398.260062 -281.2288)
		(end 412.02102 -294.989758)
		(width 0.16002)
		(layer "In11.Cu")
		(net "M_L_CPU0_SB_DQS_DN<1>")
	)
	(segment
		(start 393.384786 -281.1272)
		(end 393.872974 -281.1272)
		(width 0.09525)
		(layer "In11.Cu")
		(net "M_L_CPU0_SB_DQS_DN<1>")
	)
	(segment
		(start 452.020686 -294.811196)
		(end 453.914256 -294.811196)
		(width 0.16002)
		(layer "In11.Cu")
		(net "M_L_CPU0_SB_DQS_DN<1>")
	)
	(segment
		(start 430.445672 -294.166798)
		(end 430.800256 -293.812214)
		(width 0.16002)
		(layer "In11.Cu")
		(net "M_L_CPU0_SB_DQS_DN<1>")
	)
	(segment
		(start 433.309268 -294.662098)
		(end 435.453282 -294.662098)
		(width 0.16002)
		(layer "In11.Cu")
		(net "M_L_CPU0_SB_DQS_DN<1>")
	)
	(segment
		(start 444.29934 -294.989758)
		(end 445.1223 -294.166798)
		(width 0.16002)
		(layer "In11.Cu")
		(net "M_L_CPU0_SB_DQS_DN<1>")
	)
	(segment
		(start 387.274816 -281.37612)
		(end 387.42874 -281.11069)
		(width 0.09525)
		(layer "In11.Cu")
		(net "M_L_CPU0_SB_DQS_DN<1>")
	)
	(segment
		(start 415.712148 -293.812214)
		(end 417.371276 -293.812214)
		(width 0.16002)
		(layer "In11.Cu")
		(net "M_L_CPU0_SB_DQS_DN<1>")
	)
	(segment
		(start 438.34431 -293.812214)
		(end 440.003438 -293.812214)
		(width 0.16002)
		(layer "In11.Cu")
		(net "M_L_CPU0_SB_DQS_DN<1>")
	)
	(segment
		(start 448.121532 -294.386254)
		(end 450.543168 -294.386254)
		(width 0.16002)
		(layer "In11.Cu")
		(net "M_L_CPU0_SB_DQS_DN<1>")
	)
	(segment
		(start 429.211232 -294.989758)
		(end 430.034192 -294.166798)
		(width 0.16002)
		(layer "In11.Cu")
		(net "M_L_CPU0_SB_DQS_DN<1>")
	)
	(segment
		(start 450.543168 -294.386254)
		(end 451.161912 -295.004998)
		(width 0.16002)
		(layer "In11.Cu")
		(net "M_L_CPU0_SB_DQS_DN<1>")
	)
	(segment
		(start 451.826884 -295.004998)
		(end 452.020686 -294.811196)
		(width 0.16002)
		(layer "In11.Cu")
		(net "M_L_CPU0_SB_DQS_DN<1>")
	)
	(segment
		(start 418.22116 -294.662098)
		(end 420.365174 -294.662098)
		(width 0.16002)
		(layer "In11.Cu")
		(net "M_L_CPU0_SB_DQS_DN<1>")
	)
	(segment
		(start 437.989726 -294.166798)
		(end 438.34431 -293.812214)
		(width 0.16002)
		(layer "In11.Cu")
		(net "M_L_CPU0_SB_DQS_DN<1>")
	)
	(segment
		(start 437.578246 -294.166798)
		(end 437.989726 -294.166798)
		(width 0.16002)
		(layer "In11.Cu")
		(net "M_L_CPU0_SB_DQS_DN<1>")
	)
	(segment
		(start 442.997336 -294.662098)
		(end 443.324996 -294.989758)
		(width 0.16002)
		(layer "In11.Cu")
		(net "M_L_CPU0_SB_DQS_DN<1>")
	)
	(segment
		(start 395.776704 -281.169872)
		(end 395.835632 -281.2288)
		(width 0.09525)
		(layer "In11.Cu")
		(net "M_L_CPU0_SB_DQS_DN<1>")
	)
	(segment
		(start 395.574012 -281.169872)
		(end 395.776704 -281.169872)
		(width 0.09525)
		(layer "In11.Cu")
		(net "M_L_CPU0_SB_DQS_DN<1>")
	)
	(segment
		(start 392.725148 -281.051)
		(end 392.737086 -281.044142)
		(width 0.09525)
		(layer "In11.Cu")
		(net "M_L_CPU0_SB_DQS_DN<1>")
	)
	(segment
		(start 430.800256 -293.812214)
		(end 432.459384 -293.812214)
		(width 0.16002)
		(layer "In11.Cu")
		(net "M_L_CPU0_SB_DQS_DN<1>")
	)
	(segment
		(start 421.667178 -294.989758)
		(end 422.490138 -294.166798)
		(width 0.16002)
		(layer "In11.Cu")
		(net "M_L_CPU0_SB_DQS_DN<1>")
	)
	(segment
		(start 428.236888 -294.989758)
		(end 429.211232 -294.989758)
		(width 0.16002)
		(layer "In11.Cu")
		(net "M_L_CPU0_SB_DQS_DN<1>")
	)
	(segment
		(start 412.02102 -294.989758)
		(end 414.123124 -294.989758)
		(width 0.16002)
		(layer "In11.Cu")
		(net "M_L_CPU0_SB_DQS_DN<1>")
	)
	(segment
		(start 420.692834 -294.989758)
		(end 421.667178 -294.989758)
		(width 0.16002)
		(layer "In11.Cu")
		(net "M_L_CPU0_SB_DQS_DN<1>")
	)
	(segment
		(start 445.888364 -293.812214)
		(end 447.547492 -293.812214)
		(width 0.16002)
		(layer "In11.Cu")
		(net "M_L_CPU0_SB_DQS_DN<1>")
	)
	(segment
		(start 423.256202 -293.812214)
		(end 424.91533 -293.812214)
		(width 0.16002)
		(layer "In11.Cu")
		(net "M_L_CPU0_SB_DQS_DN<1>")
	)
	(segment
		(start 388.394956 -281.046174)
		(end 388.403338 -281.051)
		(width 0.09525)
		(layer "In11.Cu")
		(net "M_L_CPU0_SB_DQS_DN<1>")
	)
	(segment
		(start 447.547492 -293.812214)
		(end 448.121532 -294.386254)
		(width 0.16002)
		(layer "In11.Cu")
		(net "M_L_CPU0_SB_DQS_DN<1>")
	)
	(segment
		(start 420.365174 -294.662098)
		(end 420.692834 -294.989758)
		(width 0.16002)
		(layer "In11.Cu")
		(net "M_L_CPU0_SB_DQS_DN<1>")
	)
	(segment
		(start 395.859254 -281.2288)
		(end 398.260062 -281.2288)
		(width 0.16002)
		(layer "In11.Cu")
		(net "M_L_CPU0_SB_DQS_DN<1>")
	)
	(segment
		(start 445.1223 -294.166798)
		(end 445.53378 -294.166798)
		(width 0.16002)
		(layer "In11.Cu")
		(net "M_L_CPU0_SB_DQS_DN<1>")
	)
	(segment
		(start 387.42874 -281.11069)
		(end 387.529578 -281.08402)
		(width 0.09525)
		(layer "In11.Cu")
		(net "M_L_CPU0_SB_DQS_DN<1>")
	)
	(segment
		(start 395.835632 -281.2288)
		(end 395.859254 -281.2288)
		(width 0.09525)
		(layer "In11.Cu")
		(net "M_L_CPU0_SB_DQS_DN<1>")
	)
	(segment
		(start 435.780942 -294.989758)
		(end 436.755286 -294.989758)
		(width 0.16002)
		(layer "In11.Cu")
		(net "M_L_CPU0_SB_DQS_DN<1>")
	)
	(segment
		(start 440.003438 -293.812214)
		(end 440.853322 -294.662098)
		(width 0.16002)
		(layer "In11.Cu")
		(net "M_L_CPU0_SB_DQS_DN<1>")
	)
	(segment
		(start 425.765214 -294.662098)
		(end 427.909228 -294.662098)
		(width 0.16002)
		(layer "In11.Cu")
		(net "M_L_CPU0_SB_DQS_DN<1>")
	)
	(segment
		(start 393.872974 -281.1272)
		(end 394.281152 -280.719022)
		(width 0.09525)
		(layer "In11.Cu")
		(net "M_L_CPU0_SB_DQS_DN<1>")
	)
	(segment
		(start 389.906256 -281.051)
		(end 389.914638 -281.046174)
		(width 0.09525)
		(layer "In11.Cu")
		(net "M_L_CPU0_SB_DQS_DN<1>")
	)
	(segment
		(start 414.123124 -294.989758)
		(end 414.946084 -294.166798)
		(width 0.16002)
		(layer "In11.Cu")
		(net "M_L_CPU0_SB_DQS_DN<1>")
	)
	(segment
		(start 440.853322 -294.662098)
		(end 442.997336 -294.662098)
		(width 0.16002)
		(layer "In11.Cu")
		(net "M_L_CPU0_SB_DQS_DN<1>")
	)
	(segment
		(start 392.163046 -281.051)
		(end 392.18108 -281.061414)
		(width 0.09525)
		(layer "In11.Cu")
		(net "M_L_CPU0_SB_DQS_DN<1>")
	)
	(segment
		(start 424.91533 -293.812214)
		(end 425.765214 -294.662098)
		(width 0.16002)
		(layer "In11.Cu")
		(net "M_L_CPU0_SB_DQS_DN<1>")
	)
	(segment
		(start 422.490138 -294.166798)
		(end 422.901618 -294.166798)
		(width 0.16002)
		(layer "In11.Cu")
		(net "M_L_CPU0_SB_DQS_DN<1>")
	)
	(segment
		(start 417.371276 -293.812214)
		(end 418.22116 -294.662098)
		(width 0.16002)
		(layer "In11.Cu")
		(net "M_L_CPU0_SB_DQS_DN<1>")
	)
	(segment
		(start 432.459384 -293.812214)
		(end 433.309268 -294.662098)
		(width 0.16002)
		(layer "In11.Cu")
		(net "M_L_CPU0_SB_DQS_DN<1>")
	)
	(segment
		(start 427.909228 -294.662098)
		(end 428.236888 -294.989758)
		(width 0.16002)
		(layer "In11.Cu")
		(net "M_L_CPU0_SB_DQS_DN<1>")
	)
	(segment
		(start 430.034192 -294.166798)
		(end 430.445672 -294.166798)
		(width 0.16002)
		(layer "In11.Cu")
		(net "M_L_CPU0_SB_DQS_DN<1>")
	)
	(segment
		(start 392.151108 -281.044142)
		(end 392.163046 -281.051)
		(width 0.09525)
		(layer "In11.Cu")
		(net "M_L_CPU0_SB_DQS_DN<1>")
	)
	(segment
		(start 394.281152 -280.719022)
		(end 395.123162 -280.719022)
		(width 0.09525)
		(layer "In11.Cu")
		(net "M_L_CPU0_SB_DQS_DN<1>")
	)
	(segment
		(start 436.755286 -294.989758)
		(end 437.578246 -294.166798)
		(width 0.16002)
		(layer "In11.Cu")
		(net "M_L_CPU0_SB_DQS_DN<1>")
	)
	(segment
		(start 451.161912 -295.004998)
		(end 451.826884 -295.004998)
		(width 0.16002)
		(layer "In11.Cu")
		(net "M_L_CPU0_SB_DQS_DN<1>")
	)
	(segment
		(start 445.53378 -294.166798)
		(end 445.888364 -293.812214)
		(width 0.16002)
		(layer "In11.Cu")
		(net "M_L_CPU0_SB_DQS_DN<1>")
	)
	(segment
		(start 443.324996 -294.989758)
		(end 444.29934 -294.989758)
		(width 0.16002)
		(layer "In11.Cu")
		(net "M_L_CPU0_SB_DQS_DN<1>")
	)
	(segment
		(start 414.946084 -294.166798)
		(end 415.357564 -294.166798)
		(width 0.16002)
		(layer "In11.Cu")
		(net "M_L_CPU0_SB_DQS_DN<1>")
	)
	(segment
		(start 389.33501 -281.046174)
		(end 389.343392 -281.051)
		(width 0.09525)
		(layer "In11.Cu")
		(net "M_L_CPU0_SB_DQS_DN<1>")
	)
	(segment
		(start 422.901618 -294.166798)
		(end 423.256202 -293.812214)
		(width 0.16002)
		(layer "In11.Cu")
		(net "M_L_CPU0_SB_DQS_DN<1>")
	)
	(segment
		(start 453.914256 -294.811196)
		(end 454.188068 -295.085008)
		(width 0.16002)
		(layer "In11.Cu")
		(net "M_L_CPU0_SB_DQS_DN<1>")
	)
	(arc
		(start 389.343392 -281.051)
		(mid 389.624824 -281.126755)
		(end 389.906256 -281.051)
		(width 0.09525)
		(layer "In11.Cu")
		(net "M_L_CPU0_SB_DQS_DN<1>")
	)
	(arc
		(start 391.223246 -281.051)
		(mid 391.504678 -281.126755)
		(end 391.78611 -281.051)
		(width 0.09525)
		(layer "In11.Cu")
		(net "M_L_CPU0_SB_DQS_DN<1>")
	)
	(arc
		(start 391.78611 -281.051)
		(mid 391.967726 -281.000263)
		(end 392.151108 -281.044142)
		(width 0.09525)
		(layer "In11.Cu")
		(net "M_L_CPU0_SB_DQS_DN<1>")
	)
	(arc
		(start 388.966202 -281.051)
		(mid 389.149977 -281.000228)
		(end 389.33501 -281.046174)
		(width 0.09525)
		(layer "In11.Cu")
		(net "M_L_CPU0_SB_DQS_DN<1>")
	)
	(arc
		(start 392.18108 -281.061414)
		(mid 392.45446 -281.126635)
		(end 392.725148 -281.051)
		(width 0.09525)
		(layer "In11.Cu")
		(net "M_L_CPU0_SB_DQS_DN<1>")
	)
	(arc
		(start 390.84631 -281.051)
		(mid 391.034778 -281.000323)
		(end 391.223246 -281.051)
		(width 0.09525)
		(layer "In11.Cu")
		(net "M_L_CPU0_SB_DQS_DN<1>")
	)
	(arc
		(start 393.102592 -281.051)
		(mid 393.238644 -281.107769)
		(end 393.384786 -281.1272)
		(width 0.09525)
		(layer "In11.Cu")
		(net "M_L_CPU0_SB_DQS_DN<1>")
	)
	(arc
		(start 387.529578 -281.08402)
		(mid 387.5397 -281.088055)
		(end 387.549898 -281.091894)
		(width 0.09525)
		(layer "In11.Cu")
		(net "M_L_CPU0_SB_DQS_DN<1>")
	)
	(arc
		(start 387.549898 -281.091894)
		(mid 387.79261 -281.124777)
		(end 388.026148 -281.051)
		(width 0.09525)
		(layer "In11.Cu")
		(net "M_L_CPU0_SB_DQS_DN<1>")
	)
	(arc
		(start 389.914638 -281.046174)
		(mid 390.09967 -281.00026)
		(end 390.283446 -281.051)
		(width 0.09525)
		(layer "In11.Cu")
		(net "M_L_CPU0_SB_DQS_DN<1>")
	)
	(arc
		(start 388.026148 -281.051)
		(mid 388.209923 -281.000228)
		(end 388.394956 -281.046174)
		(width 0.09525)
		(layer "In11.Cu")
		(net "M_L_CPU0_SB_DQS_DN<1>")
	)
	(arc
		(start 390.283446 -281.051)
		(mid 390.564878 -281.126755)
		(end 390.84631 -281.051)
		(width 0.09525)
		(layer "In11.Cu")
		(net "M_L_CPU0_SB_DQS_DN<1>")
	)
	(arc
		(start 388.403338 -281.051)
		(mid 388.68477 -281.126755)
		(end 388.966202 -281.051)
		(width 0.09525)
		(layer "In11.Cu")
		(net "M_L_CPU0_SB_DQS_DN<1>")
	)
	(arc
		(start 392.737086 -281.044142)
		(mid 392.920721 -281.000192)
		(end 393.102592 -281.051)
		(width 0.09525)
		(layer "In11.Cu")
		(net "M_L_CPU0_SB_DQS_DN<1>")
	)
	(segment
		(start 386.807964 -276.250146)
		(end 387.274816 -276.516084)
		(width 0.12954)
		(layer "F.Cu")
		(net "M_L_CPU0_SB_DQS_DN<0>")
	)
	(segment
		(start 392.725148 -276.190964)
		(end 392.737086 -276.184106)
		(width 0.09525)
		(layer "In11.Cu")
		(net "M_L_CPU0_SB_DQS_DN<0>")
	)
	(segment
		(start 417.732464 -284.46222)
		(end 418.582348 -285.312104)
		(width 0.16002)
		(layer "In11.Cu")
		(net "M_L_CPU0_SB_DQS_DN<0>")
	)
	(segment
		(start 440.853322 -285.312104)
		(end 442.997336 -285.312104)
		(width 0.16002)
		(layer "In11.Cu")
		(net "M_L_CPU0_SB_DQS_DN<0>")
	)
	(segment
		(start 425.765214 -285.312104)
		(end 427.909228 -285.312104)
		(width 0.16002)
		(layer "In11.Cu")
		(net "M_L_CPU0_SB_DQS_DN<0>")
	)
	(segment
		(start 437.578246 -284.816804)
		(end 437.989726 -284.816804)
		(width 0.16002)
		(layer "In11.Cu")
		(net "M_L_CPU0_SB_DQS_DN<0>")
	)
	(segment
		(start 423.256202 -284.46222)
		(end 424.91533 -284.46222)
		(width 0.16002)
		(layer "In11.Cu")
		(net "M_L_CPU0_SB_DQS_DN<0>")
	)
	(segment
		(start 387.42874 -276.250654)
		(end 387.529578 -276.223984)
		(width 0.09525)
		(layer "In11.Cu")
		(net "M_L_CPU0_SB_DQS_DN<0>")
	)
	(segment
		(start 395.859254 -275.199856)
		(end 400.653504 -275.199856)
		(width 0.16002)
		(layer "In11.Cu")
		(net "M_L_CPU0_SB_DQS_DN<0>")
	)
	(segment
		(start 395.40942 -275.140674)
		(end 395.77645 -275.140674)
		(width 0.09525)
		(layer "In11.Cu")
		(net "M_L_CPU0_SB_DQS_DN<0>")
	)
	(segment
		(start 445.888364 -284.46222)
		(end 447.547492 -284.46222)
		(width 0.16002)
		(layer "In11.Cu")
		(net "M_L_CPU0_SB_DQS_DN<0>")
	)
	(segment
		(start 453.914256 -285.461202)
		(end 454.188068 -285.735014)
		(width 0.16002)
		(layer "In11.Cu")
		(net "M_L_CPU0_SB_DQS_DN<0>")
	)
	(segment
		(start 452.020686 -285.461202)
		(end 453.914256 -285.461202)
		(width 0.16002)
		(layer "In11.Cu")
		(net "M_L_CPU0_SB_DQS_DN<0>")
	)
	(segment
		(start 430.034192 -284.816804)
		(end 430.445672 -284.816804)
		(width 0.16002)
		(layer "In11.Cu")
		(net "M_L_CPU0_SB_DQS_DN<0>")
	)
	(segment
		(start 410.520388 -285.06674)
		(end 412.861252 -285.06674)
		(width 0.16002)
		(layer "In11.Cu")
		(net "M_L_CPU0_SB_DQS_DN<0>")
	)
	(segment
		(start 392.163046 -276.190964)
		(end 392.18108 -276.201378)
		(width 0.09525)
		(layer "In11.Cu")
		(net "M_L_CPU0_SB_DQS_DN<0>")
	)
	(segment
		(start 393.781026 -276.102318)
		(end 394.622782 -275.260562)
		(width 0.09525)
		(layer "In11.Cu")
		(net "M_L_CPU0_SB_DQS_DN<0>")
	)
	(segment
		(start 389.906256 -276.190964)
		(end 389.914638 -276.186138)
		(width 0.09525)
		(layer "In11.Cu")
		(net "M_L_CPU0_SB_DQS_DN<0>")
	)
	(segment
		(start 430.445672 -284.816804)
		(end 430.800256 -284.46222)
		(width 0.16002)
		(layer "In11.Cu")
		(net "M_L_CPU0_SB_DQS_DN<0>")
	)
	(segment
		(start 430.800256 -284.46222)
		(end 432.459384 -284.46222)
		(width 0.16002)
		(layer "In11.Cu")
		(net "M_L_CPU0_SB_DQS_DN<0>")
	)
	(segment
		(start 450.543168 -285.03626)
		(end 451.161912 -285.655004)
		(width 0.16002)
		(layer "In11.Cu")
		(net "M_L_CPU0_SB_DQS_DN<0>")
	)
	(segment
		(start 413.434276 -285.639764)
		(end 414.123124 -285.639764)
		(width 0.16002)
		(layer "In11.Cu")
		(net "M_L_CPU0_SB_DQS_DN<0>")
	)
	(segment
		(start 447.547492 -284.46222)
		(end 448.121532 -285.03626)
		(width 0.16002)
		(layer "In11.Cu")
		(net "M_L_CPU0_SB_DQS_DN<0>")
	)
	(segment
		(start 448.121532 -285.03626)
		(end 450.543168 -285.03626)
		(width 0.16002)
		(layer "In11.Cu")
		(net "M_L_CPU0_SB_DQS_DN<0>")
	)
	(segment
		(start 389.33501 -276.186138)
		(end 389.343392 -276.190964)
		(width 0.09525)
		(layer "In11.Cu")
		(net "M_L_CPU0_SB_DQS_DN<0>")
	)
	(segment
		(start 392.151108 -276.184106)
		(end 392.163046 -276.190964)
		(width 0.09525)
		(layer "In11.Cu")
		(net "M_L_CPU0_SB_DQS_DN<0>")
	)
	(segment
		(start 418.582348 -285.312104)
		(end 420.365174 -285.312104)
		(width 0.16002)
		(layer "In11.Cu")
		(net "M_L_CPU0_SB_DQS_DN<0>")
	)
	(segment
		(start 395.835632 -275.199856)
		(end 395.859254 -275.199856)
		(width 0.09525)
		(layer "In11.Cu")
		(net "M_L_CPU0_SB_DQS_DN<0>")
	)
	(segment
		(start 435.780942 -285.639764)
		(end 436.755286 -285.639764)
		(width 0.16002)
		(layer "In11.Cu")
		(net "M_L_CPU0_SB_DQS_DN<0>")
	)
	(segment
		(start 395.289532 -275.260562)
		(end 395.40942 -275.140674)
		(width 0.09525)
		(layer "In11.Cu")
		(net "M_L_CPU0_SB_DQS_DN<0>")
	)
	(segment
		(start 387.274816 -276.516084)
		(end 387.42874 -276.250654)
		(width 0.09525)
		(layer "In11.Cu")
		(net "M_L_CPU0_SB_DQS_DN<0>")
	)
	(segment
		(start 412.861252 -285.06674)
		(end 413.434276 -285.639764)
		(width 0.16002)
		(layer "In11.Cu")
		(net "M_L_CPU0_SB_DQS_DN<0>")
	)
	(segment
		(start 432.459384 -284.46222)
		(end 433.309268 -285.312104)
		(width 0.16002)
		(layer "In11.Cu")
		(net "M_L_CPU0_SB_DQS_DN<0>")
	)
	(segment
		(start 394.622782 -275.260562)
		(end 395.289532 -275.260562)
		(width 0.09525)
		(layer "In11.Cu")
		(net "M_L_CPU0_SB_DQS_DN<0>")
	)
	(segment
		(start 429.211232 -285.639764)
		(end 430.034192 -284.816804)
		(width 0.16002)
		(layer "In11.Cu")
		(net "M_L_CPU0_SB_DQS_DN<0>")
	)
	(segment
		(start 433.309268 -285.312104)
		(end 435.453282 -285.312104)
		(width 0.16002)
		(layer "In11.Cu")
		(net "M_L_CPU0_SB_DQS_DN<0>")
	)
	(segment
		(start 415.357564 -284.816804)
		(end 415.712148 -284.46222)
		(width 0.16002)
		(layer "In11.Cu")
		(net "M_L_CPU0_SB_DQS_DN<0>")
	)
	(segment
		(start 437.989726 -284.816804)
		(end 438.34431 -284.46222)
		(width 0.16002)
		(layer "In11.Cu")
		(net "M_L_CPU0_SB_DQS_DN<0>")
	)
	(segment
		(start 420.365174 -285.312104)
		(end 420.692834 -285.639764)
		(width 0.16002)
		(layer "In11.Cu")
		(net "M_L_CPU0_SB_DQS_DN<0>")
	)
	(segment
		(start 435.453282 -285.312104)
		(end 435.780942 -285.639764)
		(width 0.16002)
		(layer "In11.Cu")
		(net "M_L_CPU0_SB_DQS_DN<0>")
	)
	(segment
		(start 388.394956 -276.186138)
		(end 388.403338 -276.190964)
		(width 0.09525)
		(layer "In11.Cu")
		(net "M_L_CPU0_SB_DQS_DN<0>")
	)
	(segment
		(start 445.53378 -284.816804)
		(end 445.888364 -284.46222)
		(width 0.16002)
		(layer "In11.Cu")
		(net "M_L_CPU0_SB_DQS_DN<0>")
	)
	(segment
		(start 400.653504 -275.199856)
		(end 410.520388 -285.06674)
		(width 0.16002)
		(layer "In11.Cu")
		(net "M_L_CPU0_SB_DQS_DN<0>")
	)
	(segment
		(start 438.34431 -284.46222)
		(end 440.003438 -284.46222)
		(width 0.16002)
		(layer "In11.Cu")
		(net "M_L_CPU0_SB_DQS_DN<0>")
	)
	(segment
		(start 451.161912 -285.655004)
		(end 451.826884 -285.655004)
		(width 0.16002)
		(layer "In11.Cu")
		(net "M_L_CPU0_SB_DQS_DN<0>")
	)
	(segment
		(start 393.640056 -276.205696)
		(end 393.665456 -276.190964)
		(width 0.09525)
		(layer "In11.Cu")
		(net "M_L_CPU0_SB_DQS_DN<0>")
	)
	(segment
		(start 422.490138 -284.816804)
		(end 422.901618 -284.816804)
		(width 0.16002)
		(layer "In11.Cu")
		(net "M_L_CPU0_SB_DQS_DN<0>")
	)
	(segment
		(start 445.1223 -284.816804)
		(end 445.53378 -284.816804)
		(width 0.16002)
		(layer "In11.Cu")
		(net "M_L_CPU0_SB_DQS_DN<0>")
	)
	(segment
		(start 443.324996 -285.639764)
		(end 444.29934 -285.639764)
		(width 0.16002)
		(layer "In11.Cu")
		(net "M_L_CPU0_SB_DQS_DN<0>")
	)
	(segment
		(start 442.997336 -285.312104)
		(end 443.324996 -285.639764)
		(width 0.16002)
		(layer "In11.Cu")
		(net "M_L_CPU0_SB_DQS_DN<0>")
	)
	(segment
		(start 451.826884 -285.655004)
		(end 452.020686 -285.461202)
		(width 0.16002)
		(layer "In11.Cu")
		(net "M_L_CPU0_SB_DQS_DN<0>")
	)
	(segment
		(start 427.909228 -285.312104)
		(end 428.236888 -285.639764)
		(width 0.16002)
		(layer "In11.Cu")
		(net "M_L_CPU0_SB_DQS_DN<0>")
	)
	(segment
		(start 444.29934 -285.639764)
		(end 445.1223 -284.816804)
		(width 0.16002)
		(layer "In11.Cu")
		(net "M_L_CPU0_SB_DQS_DN<0>")
	)
	(segment
		(start 395.77645 -275.140674)
		(end 395.835632 -275.199856)
		(width 0.09525)
		(layer "In11.Cu")
		(net "M_L_CPU0_SB_DQS_DN<0>")
	)
	(segment
		(start 424.91533 -284.46222)
		(end 425.765214 -285.312104)
		(width 0.16002)
		(layer "In11.Cu")
		(net "M_L_CPU0_SB_DQS_DN<0>")
	)
	(segment
		(start 421.667178 -285.639764)
		(end 422.490138 -284.816804)
		(width 0.16002)
		(layer "In11.Cu")
		(net "M_L_CPU0_SB_DQS_DN<0>")
	)
	(segment
		(start 415.712148 -284.46222)
		(end 417.732464 -284.46222)
		(width 0.16002)
		(layer "In11.Cu")
		(net "M_L_CPU0_SB_DQS_DN<0>")
	)
	(segment
		(start 440.003438 -284.46222)
		(end 440.853322 -285.312104)
		(width 0.16002)
		(layer "In11.Cu")
		(net "M_L_CPU0_SB_DQS_DN<0>")
	)
	(segment
		(start 420.692834 -285.639764)
		(end 421.667178 -285.639764)
		(width 0.16002)
		(layer "In11.Cu")
		(net "M_L_CPU0_SB_DQS_DN<0>")
	)
	(segment
		(start 414.123124 -285.639764)
		(end 414.946084 -284.816804)
		(width 0.16002)
		(layer "In11.Cu")
		(net "M_L_CPU0_SB_DQS_DN<0>")
	)
	(segment
		(start 428.236888 -285.639764)
		(end 429.211232 -285.639764)
		(width 0.16002)
		(layer "In11.Cu")
		(net "M_L_CPU0_SB_DQS_DN<0>")
	)
	(segment
		(start 436.755286 -285.639764)
		(end 437.578246 -284.816804)
		(width 0.16002)
		(layer "In11.Cu")
		(net "M_L_CPU0_SB_DQS_DN<0>")
	)
	(segment
		(start 414.946084 -284.816804)
		(end 415.357564 -284.816804)
		(width 0.16002)
		(layer "In11.Cu")
		(net "M_L_CPU0_SB_DQS_DN<0>")
	)
	(segment
		(start 422.901618 -284.816804)
		(end 423.256202 -284.46222)
		(width 0.16002)
		(layer "In11.Cu")
		(net "M_L_CPU0_SB_DQS_DN<0>")
	)
	(arc
		(start 388.966202 -276.190964)
		(mid 389.149977 -276.140192)
		(end 389.33501 -276.186138)
		(width 0.09525)
		(layer "In11.Cu")
		(net "M_L_CPU0_SB_DQS_DN<0>")
	)
	(arc
		(start 387.529578 -276.223984)
		(mid 387.5397 -276.228019)
		(end 387.549898 -276.231858)
		(width 0.09525)
		(layer "In11.Cu")
		(net "M_L_CPU0_SB_DQS_DN<0>")
	)
	(arc
		(start 393.102592 -276.190964)
		(mid 393.369441 -276.266892)
		(end 393.640056 -276.205696)
		(width 0.09525)
		(layer "In11.Cu")
		(net "M_L_CPU0_SB_DQS_DN<0>")
	)
	(arc
		(start 389.343392 -276.190964)
		(mid 389.624824 -276.266719)
		(end 389.906256 -276.190964)
		(width 0.09525)
		(layer "In11.Cu")
		(net "M_L_CPU0_SB_DQS_DN<0>")
	)
	(arc
		(start 388.403338 -276.190964)
		(mid 388.68477 -276.266719)
		(end 388.966202 -276.190964)
		(width 0.09525)
		(layer "In11.Cu")
		(net "M_L_CPU0_SB_DQS_DN<0>")
	)
	(arc
		(start 388.026148 -276.190964)
		(mid 388.209923 -276.140192)
		(end 388.394956 -276.186138)
		(width 0.09525)
		(layer "In11.Cu")
		(net "M_L_CPU0_SB_DQS_DN<0>")
	)
	(arc
		(start 391.78611 -276.190964)
		(mid 391.967726 -276.140227)
		(end 392.151108 -276.184106)
		(width 0.09525)
		(layer "In11.Cu")
		(net "M_L_CPU0_SB_DQS_DN<0>")
	)
	(arc
		(start 387.549898 -276.231858)
		(mid 387.79261 -276.264741)
		(end 388.026148 -276.190964)
		(width 0.09525)
		(layer "In11.Cu")
		(net "M_L_CPU0_SB_DQS_DN<0>")
	)
	(arc
		(start 389.914638 -276.186138)
		(mid 390.09967 -276.140224)
		(end 390.283446 -276.190964)
		(width 0.09525)
		(layer "In11.Cu")
		(net "M_L_CPU0_SB_DQS_DN<0>")
	)
	(arc
		(start 390.84631 -276.190964)
		(mid 391.034778 -276.140287)
		(end 391.223246 -276.190964)
		(width 0.09525)
		(layer "In11.Cu")
		(net "M_L_CPU0_SB_DQS_DN<0>")
	)
	(arc
		(start 391.223246 -276.190964)
		(mid 391.504678 -276.266719)
		(end 391.78611 -276.190964)
		(width 0.09525)
		(layer "In11.Cu")
		(net "M_L_CPU0_SB_DQS_DN<0>")
	)
	(arc
		(start 390.283446 -276.190964)
		(mid 390.564878 -276.266719)
		(end 390.84631 -276.190964)
		(width 0.09525)
		(layer "In11.Cu")
		(net "M_L_CPU0_SB_DQS_DN<0>")
	)
	(arc
		(start 393.665456 -276.190964)
		(mid 393.726128 -276.150406)
		(end 393.781026 -276.102318)
		(width 0.09525)
		(layer "In11.Cu")
		(net "M_L_CPU0_SB_DQS_DN<0>")
	)
	(arc
		(start 392.737086 -276.184106)
		(mid 392.920721 -276.140156)
		(end 393.102592 -276.190964)
		(width 0.09525)
		(layer "In11.Cu")
		(net "M_L_CPU0_SB_DQS_DN<0>")
	)
	(arc
		(start 392.18108 -276.201378)
		(mid 392.45446 -276.266599)
		(end 392.725148 -276.190964)
		(width 0.09525)
		(layer "In11.Cu")
		(net "M_L_CPU0_SB_DQS_DN<0>")
	)
	(segment
		(start 385.86791 -279.49017)
		(end 386.334762 -279.756108)
		(width 0.10668)
		(layer "F.Cu")
		(net "M_L_CPU0_SB_DQ<9>")
	)
	(segment
		(start 395.37513 -279.74544)
		(end 395.793976 -279.74544)
		(width 0.0889)
		(layer "In11.Cu")
		(net "M_L_CPU0_SB_DQ<9>")
	)
	(segment
		(start 389.90778 -280.078688)
		(end 389.916162 -280.083514)
		(width 0.0889)
		(layer "In11.Cu")
		(net "M_L_CPU0_SB_DQ<9>")
	)
	(segment
		(start 452.366634 -292.429692)
		(end 452.366634 -292.254686)
		(width 0.14478)
		(layer "In11.Cu")
		(net "M_L_CPU0_SB_DQ<9>")
	)
	(segment
		(start 426.877988 -292.960044)
		(end 429.270922 -292.960044)
		(width 0.14478)
		(layer "In11.Cu")
		(net "M_L_CPU0_SB_DQ<9>")
	)
	(segment
		(start 393.0904 -280.085546)
		(end 393.280646 -279.973786)
		(width 0.0889)
		(layer "In11.Cu")
		(net "M_L_CPU0_SB_DQ<9>")
	)
	(segment
		(start 395.200378 -279.920192)
		(end 395.37513 -279.74544)
		(width 0.0889)
		(layer "In11.Cu")
		(net "M_L_CPU0_SB_DQ<9>")
	)
	(segment
		(start 418.057076 -292.109906)
		(end 418.907214 -292.960044)
		(width 0.14478)
		(layer "In11.Cu")
		(net "M_L_CPU0_SB_DQ<9>")
	)
	(segment
		(start 421.532812 -292.960044)
		(end 422.382696 -292.11016)
		(width 0.14478)
		(layer "In11.Cu")
		(net "M_L_CPU0_SB_DQ<9>")
	)
	(segment
		(start 451.67042 -292.109906)
		(end 451.8152 -292.254686)
		(width 0.14478)
		(layer "In11.Cu")
		(net "M_L_CPU0_SB_DQ<9>")
	)
	(segment
		(start 440.689492 -292.11016)
		(end 441.539376 -292.960044)
		(width 0.14478)
		(layer "In11.Cu")
		(net "M_L_CPU0_SB_DQ<9>")
	)
	(segment
		(start 429.270922 -292.960044)
		(end 430.120806 -292.11016)
		(width 0.14478)
		(layer "In11.Cu")
		(net "M_L_CPU0_SB_DQ<9>")
	)
	(segment
		(start 433.145438 -292.11016)
		(end 433.995322 -292.960044)
		(width 0.14478)
		(layer "In11.Cu")
		(net "M_L_CPU0_SB_DQ<9>")
	)
	(segment
		(start 452.366634 -292.254686)
		(end 452.511414 -292.109906)
		(width 0.14478)
		(layer "In11.Cu")
		(net "M_L_CPU0_SB_DQ<9>")
	)
	(segment
		(start 388.393432 -280.083514)
		(end 388.401814 -280.078688)
		(width 0.0889)
		(layer "In11.Cu")
		(net "M_L_CPU0_SB_DQ<9>")
	)
	(segment
		(start 430.120806 -292.11016)
		(end 433.145438 -292.11016)
		(width 0.14478)
		(layer "In11.Cu")
		(net "M_L_CPU0_SB_DQ<9>")
	)
	(segment
		(start 426.028104 -292.11016)
		(end 426.877988 -292.960044)
		(width 0.14478)
		(layer "In11.Cu")
		(net "M_L_CPU0_SB_DQ<9>")
	)
	(segment
		(start 398.66824 -279.74544)
		(end 411.882844 -292.960044)
		(width 0.14478)
		(layer "In11.Cu")
		(net "M_L_CPU0_SB_DQ<9>")
	)
	(segment
		(start 443.817248 -292.960044)
		(end 444.667386 -292.109906)
		(width 0.14478)
		(layer "In11.Cu")
		(net "M_L_CPU0_SB_DQ<9>")
	)
	(segment
		(start 444.667386 -292.109906)
		(end 451.67042 -292.109906)
		(width 0.14478)
		(layer "In11.Cu")
		(net "M_L_CPU0_SB_DQ<9>")
	)
	(segment
		(start 414.984692 -292.109906)
		(end 418.057076 -292.109906)
		(width 0.14478)
		(layer "In11.Cu")
		(net "M_L_CPU0_SB_DQ<9>")
	)
	(segment
		(start 389.333486 -280.083514)
		(end 389.341868 -280.078688)
		(width 0.0889)
		(layer "In11.Cu")
		(net "M_L_CPU0_SB_DQ<9>")
	)
	(segment
		(start 414.134554 -292.960044)
		(end 414.984692 -292.109906)
		(width 0.14478)
		(layer "In11.Cu")
		(net "M_L_CPU0_SB_DQ<9>")
	)
	(segment
		(start 451.8152 -292.254686)
		(end 451.8152 -292.429692)
		(width 0.14478)
		(layer "In11.Cu")
		(net "M_L_CPU0_SB_DQ<9>")
	)
	(segment
		(start 452.221854 -292.574472)
		(end 452.366634 -292.429692)
		(width 0.14478)
		(layer "In11.Cu")
		(net "M_L_CPU0_SB_DQ<9>")
	)
	(segment
		(start 433.995322 -292.960044)
		(end 436.643272 -292.960044)
		(width 0.14478)
		(layer "In11.Cu")
		(net "M_L_CPU0_SB_DQ<9>")
	)
	(segment
		(start 451.8152 -292.429692)
		(end 451.95998 -292.574472)
		(width 0.14478)
		(layer "In11.Cu")
		(net "M_L_CPU0_SB_DQ<9>")
	)
	(segment
		(start 418.907214 -292.960044)
		(end 421.532812 -292.960044)
		(width 0.14478)
		(layer "In11.Cu")
		(net "M_L_CPU0_SB_DQ<9>")
	)
	(segment
		(start 386.180838 -280.021538)
		(end 386.20319 -280.10485)
		(width 0.0889)
		(layer "In11.Cu")
		(net "M_L_CPU0_SB_DQ<9>")
	)
	(segment
		(start 392.717782 -280.072592)
		(end 392.728196 -280.078688)
		(width 0.0889)
		(layer "In11.Cu")
		(net "M_L_CPU0_SB_DQ<9>")
	)
	(segment
		(start 441.539376 -292.960044)
		(end 443.817248 -292.960044)
		(width 0.14478)
		(layer "In11.Cu")
		(net "M_L_CPU0_SB_DQ<9>")
	)
	(segment
		(start 453.762872 -292.109906)
		(end 454.188068 -292.535102)
		(width 0.14478)
		(layer "In11.Cu")
		(net "M_L_CPU0_SB_DQ<9>")
	)
	(segment
		(start 451.95998 -292.574472)
		(end 452.221854 -292.574472)
		(width 0.14478)
		(layer "In11.Cu")
		(net "M_L_CPU0_SB_DQ<9>")
	)
	(segment
		(start 395.793976 -279.74544)
		(end 398.66824 -279.74544)
		(width 0.14478)
		(layer "In11.Cu")
		(net "M_L_CPU0_SB_DQ<9>")
	)
	(segment
		(start 436.643272 -292.960044)
		(end 437.493156 -292.11016)
		(width 0.14478)
		(layer "In11.Cu")
		(net "M_L_CPU0_SB_DQ<9>")
	)
	(segment
		(start 386.334762 -279.756108)
		(end 386.180838 -280.021538)
		(width 0.0889)
		(layer "In11.Cu")
		(net "M_L_CPU0_SB_DQ<9>")
	)
	(segment
		(start 422.382696 -292.11016)
		(end 426.028104 -292.11016)
		(width 0.14478)
		(layer "In11.Cu")
		(net "M_L_CPU0_SB_DQ<9>")
	)
	(segment
		(start 452.511414 -292.109906)
		(end 453.762872 -292.109906)
		(width 0.14478)
		(layer "In11.Cu")
		(net "M_L_CPU0_SB_DQ<9>")
	)
	(segment
		(start 437.493156 -292.11016)
		(end 440.689492 -292.11016)
		(width 0.14478)
		(layer "In11.Cu")
		(net "M_L_CPU0_SB_DQ<9>")
	)
	(segment
		(start 411.882844 -292.960044)
		(end 414.134554 -292.960044)
		(width 0.14478)
		(layer "In11.Cu")
		(net "M_L_CPU0_SB_DQ<9>")
	)
	(segment
		(start 393.47775 -279.920192)
		(end 395.200378 -279.920192)
		(width 0.0889)
		(layer "In11.Cu")
		(net "M_L_CPU0_SB_DQ<9>")
	)
	(arc
		(start 387.087872 -280.078688)
		(mid 387.274816 -280.128943)
		(end 387.46176 -280.078688)
		(width 0.0889)
		(layer "In11.Cu")
		(net "M_L_CPU0_SB_DQ<9>")
	)
	(arc
		(start 391.221722 -280.078688)
		(mid 391.504678 -280.002511)
		(end 391.787634 -280.078688)
		(width 0.0889)
		(layer "In11.Cu")
		(net "M_L_CPU0_SB_DQ<9>")
	)
	(arc
		(start 391.787634 -280.078688)
		(mid 391.974832 -280.12907)
		(end 392.16203 -280.078688)
		(width 0.0889)
		(layer "In11.Cu")
		(net "M_L_CPU0_SB_DQ<9>")
	)
	(arc
		(start 387.46176 -280.078688)
		(mid 387.744716 -280.002511)
		(end 388.027672 -280.078688)
		(width 0.0889)
		(layer "In11.Cu")
		(net "M_L_CPU0_SB_DQ<9>")
	)
	(arc
		(start 388.027672 -280.078688)
		(mid 388.209923 -280.129038)
		(end 388.393432 -280.083514)
		(width 0.0889)
		(layer "In11.Cu")
		(net "M_L_CPU0_SB_DQ<9>")
	)
	(arc
		(start 392.16203 -280.078688)
		(mid 392.439097 -280.002417)
		(end 392.717782 -280.072592)
		(width 0.0889)
		(layer "In11.Cu")
		(net "M_L_CPU0_SB_DQ<9>")
	)
	(arc
		(start 386.20319 -280.10485)
		(mid 386.365522 -280.127668)
		(end 386.52196 -280.078688)
		(width 0.0889)
		(layer "In11.Cu")
		(net "M_L_CPU0_SB_DQ<9>")
	)
	(arc
		(start 388.967726 -280.078688)
		(mid 389.149977 -280.129038)
		(end 389.333486 -280.083514)
		(width 0.0889)
		(layer "In11.Cu")
		(net "M_L_CPU0_SB_DQ<9>")
	)
	(arc
		(start 389.916162 -280.083514)
		(mid 390.09967 -280.129008)
		(end 390.281922 -280.078688)
		(width 0.0889)
		(layer "In11.Cu")
		(net "M_L_CPU0_SB_DQ<9>")
	)
	(arc
		(start 390.847834 -280.078688)
		(mid 391.034778 -280.128943)
		(end 391.221722 -280.078688)
		(width 0.0889)
		(layer "In11.Cu")
		(net "M_L_CPU0_SB_DQ<9>")
	)
	(arc
		(start 386.52196 -280.078688)
		(mid 386.804916 -280.002511)
		(end 387.087872 -280.078688)
		(width 0.0889)
		(layer "In11.Cu")
		(net "M_L_CPU0_SB_DQ<9>")
	)
	(arc
		(start 393.280646 -279.973786)
		(mid 393.375618 -279.933818)
		(end 393.47775 -279.920192)
		(width 0.0889)
		(layer "In11.Cu")
		(net "M_L_CPU0_SB_DQ<9>")
	)
	(arc
		(start 389.341868 -280.078688)
		(mid 389.624824 -280.002511)
		(end 389.90778 -280.078688)
		(width 0.0889)
		(layer "In11.Cu")
		(net "M_L_CPU0_SB_DQ<9>")
	)
	(arc
		(start 388.401814 -280.078688)
		(mid 388.68477 -280.002511)
		(end 388.967726 -280.078688)
		(width 0.0889)
		(layer "In11.Cu")
		(net "M_L_CPU0_SB_DQ<9>")
	)
	(arc
		(start 392.728196 -280.078688)
		(mid 392.908401 -280.129005)
		(end 393.0904 -280.085546)
		(width 0.0889)
		(layer "In11.Cu")
		(net "M_L_CPU0_SB_DQ<9>")
	)
	(arc
		(start 390.281922 -280.078688)
		(mid 390.564878 -280.002511)
		(end 390.847834 -280.078688)
		(width 0.0889)
		(layer "In11.Cu")
		(net "M_L_CPU0_SB_DQ<9>")
	)
	(segment
		(start 387.277864 -278.680164)
		(end 387.744716 -278.946102)
		(width 0.10668)
		(layer "F.Cu")
		(net "M_L_CPU0_SB_DQ<8>")
	)
	(segment
		(start 444.70574 -290.410138)
		(end 450.898514 -290.410138)
		(width 0.14478)
		(layer "In11.Cu")
		(net "M_L_CPU0_SB_DQ<8>")
	)
	(segment
		(start 452.337678 -291.32911)
		(end 452.568056 -291.32911)
		(width 0.14478)
		(layer "In11.Cu")
		(net "M_L_CPU0_SB_DQ<8>")
	)
	(segment
		(start 414.182814 -291.260022)
		(end 415.032952 -290.409884)
		(width 0.14478)
		(layer "In11.Cu")
		(net "M_L_CPU0_SB_DQ<8>")
	)
	(segment
		(start 392.257026 -279.268428)
		(end 392.270742 -279.276302)
		(width 0.0889)
		(layer "In11.Cu")
		(net "M_L_CPU0_SB_DQ<8>")
	)
	(segment
		(start 387.744716 -278.946102)
		(end 387.590792 -279.211532)
		(width 0.0889)
		(layer "In11.Cu")
		(net "M_L_CPU0_SB_DQ<8>")
	)
	(segment
		(start 393.384786 -279.319482)
		(end 393.677902 -279.319482)
		(width 0.0889)
		(layer "In11.Cu")
		(net "M_L_CPU0_SB_DQ<8>")
	)
	(segment
		(start 451.061582 -290.573206)
		(end 451.061582 -291.166042)
		(width 0.14478)
		(layer "In11.Cu")
		(net "M_L_CPU0_SB_DQ<8>")
	)
	(segment
		(start 443.855856 -291.260022)
		(end 444.70574 -290.410138)
		(width 0.14478)
		(layer "In11.Cu")
		(net "M_L_CPU0_SB_DQ<8>")
	)
	(segment
		(start 411.469078 -291.260022)
		(end 414.182814 -291.260022)
		(width 0.14478)
		(layer "In11.Cu")
		(net "M_L_CPU0_SB_DQ<8>")
	)
	(segment
		(start 421.726868 -291.260022)
		(end 422.576752 -290.410138)
		(width 0.14478)
		(layer "In11.Cu")
		(net "M_L_CPU0_SB_DQ<8>")
	)
	(segment
		(start 430.508918 -290.410138)
		(end 433.145438 -290.410138)
		(width 0.14478)
		(layer "In11.Cu")
		(net "M_L_CPU0_SB_DQ<8>")
	)
	(segment
		(start 450.898514 -290.410138)
		(end 451.061582 -290.573206)
		(width 0.14478)
		(layer "In11.Cu")
		(net "M_L_CPU0_SB_DQ<8>")
	)
	(segment
		(start 452.731124 -290.573206)
		(end 452.894192 -290.410138)
		(width 0.14478)
		(layer "In11.Cu")
		(net "M_L_CPU0_SB_DQ<8>")
	)
	(segment
		(start 398.820132 -278.611076)
		(end 411.469078 -291.260022)
		(width 0.14478)
		(layer "In11.Cu")
		(net "M_L_CPU0_SB_DQ<8>")
	)
	(segment
		(start 395.946122 -278.611076)
		(end 398.820132 -278.611076)
		(width 0.14478)
		(layer "In11.Cu")
		(net "M_L_CPU0_SB_DQ<8>")
	)
	(segment
		(start 418.907468 -291.260022)
		(end 421.726868 -291.260022)
		(width 0.14478)
		(layer "In11.Cu")
		(net "M_L_CPU0_SB_DQ<8>")
	)
	(segment
		(start 392.63066 -279.268682)
		(end 392.648694 -279.258014)
		(width 0.0889)
		(layer "In11.Cu")
		(net "M_L_CPU0_SB_DQ<8>")
	)
	(segment
		(start 394.386308 -278.611076)
		(end 395.946122 -278.611076)
		(width 0.0889)
		(layer "In11.Cu")
		(net "M_L_CPU0_SB_DQ<8>")
	)
	(segment
		(start 433.995322 -291.260022)
		(end 436.814976 -291.260022)
		(width 0.14478)
		(layer "In11.Cu")
		(net "M_L_CPU0_SB_DQ<8>")
	)
	(segment
		(start 418.05733 -290.409884)
		(end 418.907468 -291.260022)
		(width 0.14478)
		(layer "In11.Cu")
		(net "M_L_CPU0_SB_DQ<8>")
	)
	(segment
		(start 422.576752 -290.410138)
		(end 425.699428 -290.410138)
		(width 0.14478)
		(layer "In11.Cu")
		(net "M_L_CPU0_SB_DQ<8>")
	)
	(segment
		(start 392.245088 -279.26157)
		(end 392.257026 -279.268428)
		(width 0.0889)
		(layer "In11.Cu")
		(net "M_L_CPU0_SB_DQ<8>")
	)
	(segment
		(start 451.618096 -291.166042)
		(end 451.618096 -290.573206)
		(width 0.14478)
		(layer "In11.Cu")
		(net "M_L_CPU0_SB_DQ<8>")
	)
	(segment
		(start 451.618096 -290.573206)
		(end 451.781164 -290.410138)
		(width 0.14478)
		(layer "In11.Cu")
		(net "M_L_CPU0_SB_DQ<8>")
	)
	(segment
		(start 391.317734 -279.268682)
		(end 391.326116 -279.273508)
		(width 0.0889)
		(layer "In11.Cu")
		(net "M_L_CPU0_SB_DQ<8>")
	)
	(segment
		(start 390.74344 -279.273508)
		(end 390.751822 -279.268682)
		(width 0.0889)
		(layer "In11.Cu")
		(net "M_L_CPU0_SB_DQ<8>")
	)
	(segment
		(start 451.455028 -291.32911)
		(end 451.618096 -291.166042)
		(width 0.14478)
		(layer "In11.Cu")
		(net "M_L_CPU0_SB_DQ<8>")
	)
	(segment
		(start 451.22465 -291.32911)
		(end 451.455028 -291.32911)
		(width 0.14478)
		(layer "In11.Cu")
		(net "M_L_CPU0_SB_DQ<8>")
	)
	(segment
		(start 452.17461 -291.166042)
		(end 452.337678 -291.32911)
		(width 0.14478)
		(layer "In11.Cu")
		(net "M_L_CPU0_SB_DQ<8>")
	)
	(segment
		(start 436.814976 -291.260022)
		(end 437.66486 -290.410138)
		(width 0.14478)
		(layer "In11.Cu")
		(net "M_L_CPU0_SB_DQ<8>")
	)
	(segment
		(start 453.763126 -290.410138)
		(end 454.188068 -290.83508)
		(width 0.14478)
		(layer "In11.Cu")
		(net "M_L_CPU0_SB_DQ<8>")
	)
	(segment
		(start 393.677902 -279.319482)
		(end 394.386308 -278.611076)
		(width 0.0889)
		(layer "In11.Cu")
		(net "M_L_CPU0_SB_DQ<8>")
	)
	(segment
		(start 429.659034 -291.260022)
		(end 430.508918 -290.410138)
		(width 0.14478)
		(layer "In11.Cu")
		(net "M_L_CPU0_SB_DQ<8>")
	)
	(segment
		(start 452.568056 -291.32911)
		(end 452.731124 -291.166042)
		(width 0.14478)
		(layer "In11.Cu")
		(net "M_L_CPU0_SB_DQ<8>")
	)
	(segment
		(start 451.061582 -291.166042)
		(end 451.22465 -291.32911)
		(width 0.14478)
		(layer "In11.Cu")
		(net "M_L_CPU0_SB_DQ<8>")
	)
	(segment
		(start 425.699428 -290.410138)
		(end 426.549312 -291.260022)
		(width 0.14478)
		(layer "In11.Cu")
		(net "M_L_CPU0_SB_DQ<8>")
	)
	(segment
		(start 452.731124 -291.166042)
		(end 452.731124 -290.573206)
		(width 0.14478)
		(layer "In11.Cu")
		(net "M_L_CPU0_SB_DQ<8>")
	)
	(segment
		(start 433.145438 -290.410138)
		(end 433.995322 -291.260022)
		(width 0.14478)
		(layer "In11.Cu")
		(net "M_L_CPU0_SB_DQ<8>")
	)
	(segment
		(start 437.66486 -290.410138)
		(end 440.689492 -290.410138)
		(width 0.14478)
		(layer "In11.Cu")
		(net "M_L_CPU0_SB_DQ<8>")
	)
	(segment
		(start 452.894192 -290.410138)
		(end 453.763126 -290.410138)
		(width 0.14478)
		(layer "In11.Cu")
		(net "M_L_CPU0_SB_DQ<8>")
	)
	(segment
		(start 441.539376 -291.260022)
		(end 443.855856 -291.260022)
		(width 0.14478)
		(layer "In11.Cu")
		(net "M_L_CPU0_SB_DQ<8>")
	)
	(segment
		(start 440.689492 -290.410138)
		(end 441.539376 -291.260022)
		(width 0.14478)
		(layer "In11.Cu")
		(net "M_L_CPU0_SB_DQ<8>")
	)
	(segment
		(start 415.032952 -290.409884)
		(end 418.05733 -290.409884)
		(width 0.14478)
		(layer "In11.Cu")
		(net "M_L_CPU0_SB_DQ<8>")
	)
	(segment
		(start 388.497826 -279.268682)
		(end 388.506208 -279.273508)
		(width 0.0889)
		(layer "In11.Cu")
		(net "M_L_CPU0_SB_DQ<8>")
	)
	(segment
		(start 387.590792 -279.211532)
		(end 387.613144 -279.294844)
		(width 0.0889)
		(layer "In11.Cu")
		(net "M_L_CPU0_SB_DQ<8>")
	)
	(segment
		(start 452.17461 -290.573206)
		(end 452.17461 -291.166042)
		(width 0.14478)
		(layer "In11.Cu")
		(net "M_L_CPU0_SB_DQ<8>")
	)
	(segment
		(start 426.549312 -291.260022)
		(end 429.659034 -291.260022)
		(width 0.14478)
		(layer "In11.Cu")
		(net "M_L_CPU0_SB_DQ<8>")
	)
	(segment
		(start 451.781164 -290.410138)
		(end 452.011542 -290.410138)
		(width 0.14478)
		(layer "In11.Cu")
		(net "M_L_CPU0_SB_DQ<8>")
	)
	(segment
		(start 452.011542 -290.410138)
		(end 452.17461 -290.573206)
		(width 0.14478)
		(layer "In11.Cu")
		(net "M_L_CPU0_SB_DQ<8>")
	)
	(arc
		(start 387.613144 -279.294844)
		(mid 387.775476 -279.317662)
		(end 387.931914 -279.268682)
		(width 0.0889)
		(layer "In11.Cu")
		(net "M_L_CPU0_SB_DQ<8>")
	)
	(arc
		(start 388.871968 -279.268682)
		(mid 389.154924 -279.192505)
		(end 389.43788 -279.268682)
		(width 0.0889)
		(layer "In11.Cu")
		(net "M_L_CPU0_SB_DQ<8>")
	)
	(arc
		(start 388.506208 -279.273508)
		(mid 388.689716 -279.319002)
		(end 388.871968 -279.268682)
		(width 0.0889)
		(layer "In11.Cu")
		(net "M_L_CPU0_SB_DQ<8>")
	)
	(arc
		(start 391.326116 -279.273508)
		(mid 391.509624 -279.319002)
		(end 391.691876 -279.268682)
		(width 0.0889)
		(layer "In11.Cu")
		(net "M_L_CPU0_SB_DQ<8>")
	)
	(arc
		(start 393.197334 -279.268682)
		(mid 393.287697 -279.306492)
		(end 393.384786 -279.319482)
		(width 0.0889)
		(layer "In11.Cu")
		(net "M_L_CPU0_SB_DQ<8>")
	)
	(arc
		(start 389.811768 -279.268682)
		(mid 390.094724 -279.192505)
		(end 390.37768 -279.268682)
		(width 0.0889)
		(layer "In11.Cu")
		(net "M_L_CPU0_SB_DQ<8>")
	)
	(arc
		(start 392.270742 -279.276302)
		(mid 392.451672 -279.31878)
		(end 392.63066 -279.268682)
		(width 0.0889)
		(layer "In11.Cu")
		(net "M_L_CPU0_SB_DQ<8>")
	)
	(arc
		(start 391.691876 -279.268682)
		(mid 391.967554 -279.192552)
		(end 392.245088 -279.26157)
		(width 0.0889)
		(layer "In11.Cu")
		(net "M_L_CPU0_SB_DQ<8>")
	)
	(arc
		(start 390.37768 -279.268682)
		(mid 390.559931 -279.319032)
		(end 390.74344 -279.273508)
		(width 0.0889)
		(layer "In11.Cu")
		(net "M_L_CPU0_SB_DQ<8>")
	)
	(arc
		(start 392.648694 -279.258014)
		(mid 392.924389 -279.192171)
		(end 393.197334 -279.268682)
		(width 0.0889)
		(layer "In11.Cu")
		(net "M_L_CPU0_SB_DQ<8>")
	)
	(arc
		(start 387.931914 -279.268682)
		(mid 388.21487 -279.192505)
		(end 388.497826 -279.268682)
		(width 0.0889)
		(layer "In11.Cu")
		(net "M_L_CPU0_SB_DQ<8>")
	)
	(arc
		(start 389.43788 -279.268682)
		(mid 389.624824 -279.318937)
		(end 389.811768 -279.268682)
		(width 0.0889)
		(layer "In11.Cu")
		(net "M_L_CPU0_SB_DQ<8>")
	)
	(arc
		(start 390.751822 -279.268682)
		(mid 391.034778 -279.192505)
		(end 391.317734 -279.268682)
		(width 0.0889)
		(layer "In11.Cu")
		(net "M_L_CPU0_SB_DQ<8>")
	)
	(segment
		(start 385.39801 -278.680164)
		(end 385.864862 -278.946102)
		(width 0.10668)
		(layer "F.Cu")
		(net "M_L_CPU0_SB_DQ<7>")
	)
	(segment
		(start 402.920708 -281.694128)
		(end 403.089364 -281.694128)
		(width 0.14478)
		(layer "In11.Cu")
		(net "M_L_CPU0_SB_DQ<7>")
	)
	(segment
		(start 403.477984 -282.481782)
		(end 403.708108 -282.481528)
		(width 0.14478)
		(layer "In11.Cu")
		(net "M_L_CPU0_SB_DQ<7>")
	)
	(segment
		(start 407.645108 -286.418528)
		(end 407.813764 -286.418528)
		(width 0.14478)
		(layer "In11.Cu")
		(net "M_L_CPU0_SB_DQ<7>")
	)
	(segment
		(start 385.864862 -278.946102)
		(end 386.018786 -278.680672)
		(width 0.0889)
		(layer "In11.Cu")
		(net "M_L_CPU0_SB_DQ<7>")
	)
	(segment
		(start 434.0606 -290.410392)
		(end 436.722012 -290.410392)
		(width 0.14478)
		(layer "In11.Cu")
		(net "M_L_CPU0_SB_DQ<7>")
	)
	(segment
		(start 408.795474 -287.799272)
		(end 408.989784 -287.993582)
		(width 0.14478)
		(layer "In11.Cu")
		(net "M_L_CPU0_SB_DQ<7>")
	)
	(segment
		(start 402.133308 -280.906728)
		(end 402.301964 -280.906728)
		(width 0.14478)
		(layer "In11.Cu")
		(net "M_L_CPU0_SB_DQ<7>")
	)
	(segment
		(start 408.008074 -287.011872)
		(end 408.202384 -287.206182)
		(width 0.14478)
		(layer "In11.Cu")
		(net "M_L_CPU0_SB_DQ<7>")
	)
	(segment
		(start 401.514564 -280.119328)
		(end 401.70862 -280.313384)
		(width 0.14478)
		(layer "In11.Cu")
		(net "M_L_CPU0_SB_DQ<7>")
	)
	(segment
		(start 407.220674 -286.224472)
		(end 407.414984 -286.418782)
		(width 0.14478)
		(layer "In11.Cu")
		(net "M_L_CPU0_SB_DQ<7>")
	)
	(segment
		(start 402.496274 -281.500072)
		(end 402.690584 -281.694382)
		(width 0.14478)
		(layer "In11.Cu")
		(net "M_L_CPU0_SB_DQ<7>")
	)
	(segment
		(start 448.45859 -289.560254)
		(end 448.747134 -289.27171)
		(width 0.14478)
		(layer "In11.Cu")
		(net "M_L_CPU0_SB_DQ<7>")
	)
	(segment
		(start 394.138658 -278.319992)
		(end 395.159738 -278.319992)
		(width 0.0889)
		(layer "In11.Cu")
		(net "M_L_CPU0_SB_DQ<7>")
	)
	(segment
		(start 433.210462 -289.560254)
		(end 434.0606 -290.410392)
		(width 0.14478)
		(layer "In11.Cu")
		(net "M_L_CPU0_SB_DQ<7>")
	)
	(segment
		(start 414.090358 -290.410138)
		(end 414.940496 -289.56)
		(width 0.14478)
		(layer "In11.Cu")
		(net "M_L_CPU0_SB_DQ<7>")
	)
	(segment
		(start 429.663098 -290.410392)
		(end 430.513236 -289.560254)
		(width 0.14478)
		(layer "In11.Cu")
		(net "M_L_CPU0_SB_DQ<7>")
	)
	(segment
		(start 441.6044 -290.410138)
		(end 443.89548 -290.410138)
		(width 0.14478)
		(layer "In11.Cu")
		(net "M_L_CPU0_SB_DQ<7>")
	)
	(segment
		(start 407.22042 -285.825184)
		(end 407.220674 -286.055816)
		(width 0.14478)
		(layer "In11.Cu")
		(net "M_L_CPU0_SB_DQ<7>")
	)
	(segment
		(start 444.745364 -289.560254)
		(end 447.345562 -289.560254)
		(width 0.14478)
		(layer "In11.Cu")
		(net "M_L_CPU0_SB_DQ<7>")
	)
	(segment
		(start 400.921474 -279.756616)
		(end 400.921474 -279.925272)
		(width 0.14478)
		(layer "In11.Cu")
		(net "M_L_CPU0_SB_DQ<7>")
	)
	(segment
		(start 408.00782 -286.612584)
		(end 408.008074 -286.843216)
		(width 0.14478)
		(layer "In11.Cu")
		(net "M_L_CPU0_SB_DQ<7>")
	)
	(segment
		(start 403.876764 -282.481528)
		(end 404.07082 -282.675584)
		(width 0.14478)
		(layer "In11.Cu")
		(net "M_L_CPU0_SB_DQ<7>")
	)
	(segment
		(start 407.414984 -286.418782)
		(end 407.645108 -286.418528)
		(width 0.14478)
		(layer "In11.Cu")
		(net "M_L_CPU0_SB_DQ<7>")
	)
	(segment
		(start 406.627584 -285.631382)
		(end 406.857708 -285.631128)
		(width 0.14478)
		(layer "In11.Cu")
		(net "M_L_CPU0_SB_DQ<7>")
	)
	(segment
		(start 425.666408 -289.560254)
		(end 426.516546 -290.410392)
		(width 0.14478)
		(layer "In11.Cu")
		(net "M_L_CPU0_SB_DQ<7>")
	)
	(segment
		(start 449.663058 -289.560254)
		(end 450.088 -289.985196)
		(width 0.14478)
		(layer "In11.Cu")
		(net "M_L_CPU0_SB_DQ<7>")
	)
	(segment
		(start 405.282908 -284.056328)
		(end 405.451564 -284.056328)
		(width 0.14478)
		(layer "In11.Cu")
		(net "M_L_CPU0_SB_DQ<7>")
	)
	(segment
		(start 393.88542 -278.57323)
		(end 394.138658 -278.319992)
		(width 0.0889)
		(layer "In11.Cu")
		(net "M_L_CPU0_SB_DQ<7>")
	)
	(segment
		(start 418.972746 -290.410392)
		(end 421.633904 -290.410392)
		(width 0.14478)
		(layer "In11.Cu")
		(net "M_L_CPU0_SB_DQ<7>")
	)
	(segment
		(start 409.388564 -287.993328)
		(end 409.58262 -288.187384)
		(width 0.14478)
		(layer "In11.Cu")
		(net "M_L_CPU0_SB_DQ<7>")
	)
	(segment
		(start 390.74344 -278.618696)
		(end 390.751822 -278.623522)
		(width 0.0889)
		(layer "In11.Cu")
		(net "M_L_CPU0_SB_DQ<7>")
	)
	(segment
		(start 393.384786 -278.57323)
		(end 393.88542 -278.57323)
		(width 0.0889)
		(layer "In11.Cu")
		(net "M_L_CPU0_SB_DQ<7>")
	)
	(segment
		(start 403.708108 -282.481528)
		(end 403.876764 -282.481528)
		(width 0.14478)
		(layer "In11.Cu")
		(net "M_L_CPU0_SB_DQ<7>")
	)
	(segment
		(start 403.28342 -281.888184)
		(end 403.283674 -282.118816)
		(width 0.14478)
		(layer "In11.Cu")
		(net "M_L_CPU0_SB_DQ<7>")
	)
	(segment
		(start 405.052784 -284.056582)
		(end 405.282908 -284.056328)
		(width 0.14478)
		(layer "In11.Cu")
		(net "M_L_CPU0_SB_DQ<7>")
	)
	(segment
		(start 406.238964 -284.843728)
		(end 406.43302 -285.037784)
		(width 0.14478)
		(layer "In11.Cu")
		(net "M_L_CPU0_SB_DQ<7>")
	)
	(segment
		(start 388.497826 -278.623522)
		(end 388.506208 -278.618696)
		(width 0.0889)
		(layer "In11.Cu")
		(net "M_L_CPU0_SB_DQ<7>")
	)
	(segment
		(start 405.645874 -284.649672)
		(end 405.840184 -284.843982)
		(width 0.14478)
		(layer "In11.Cu")
		(net "M_L_CPU0_SB_DQ<7>")
	)
	(segment
		(start 405.840184 -284.843982)
		(end 406.070308 -284.843728)
		(width 0.14478)
		(layer "In11.Cu")
		(net "M_L_CPU0_SB_DQ<7>")
	)
	(segment
		(start 400.558508 -279.331928)
		(end 400.727164 -279.331928)
		(width 0.14478)
		(layer "In11.Cu")
		(net "M_L_CPU0_SB_DQ<7>")
	)
	(segment
		(start 400.727164 -279.331928)
		(end 400.92122 -279.525984)
		(width 0.14478)
		(layer "In11.Cu")
		(net "M_L_CPU0_SB_DQ<7>")
	)
	(segment
		(start 404.07082 -282.675584)
		(end 404.071074 -282.906216)
		(width 0.14478)
		(layer "In11.Cu")
		(net "M_L_CPU0_SB_DQ<7>")
	)
	(segment
		(start 447.902076 -289.27171)
		(end 448.19062 -289.560254)
		(width 0.14478)
		(layer "In11.Cu")
		(net "M_L_CPU0_SB_DQ<7>")
	)
	(segment
		(start 404.858474 -283.862272)
		(end 405.052784 -284.056582)
		(width 0.14478)
		(layer "In11.Cu")
		(net "M_L_CPU0_SB_DQ<7>")
	)
	(segment
		(start 447.634106 -289.27171)
		(end 447.902076 -289.27171)
		(width 0.14478)
		(layer "In11.Cu")
		(net "M_L_CPU0_SB_DQ<7>")
	)
	(segment
		(start 408.601164 -287.205928)
		(end 408.79522 -287.399984)
		(width 0.14478)
		(layer "In11.Cu")
		(net "M_L_CPU0_SB_DQ<7>")
	)
	(segment
		(start 409.58262 -288.187384)
		(end 409.582874 -288.418016)
		(width 0.14478)
		(layer "In11.Cu")
		(net "M_L_CPU0_SB_DQ<7>")
	)
	(segment
		(start 409.219908 -287.993328)
		(end 409.388564 -287.993328)
		(width 0.14478)
		(layer "In11.Cu")
		(net "M_L_CPU0_SB_DQ<7>")
	)
	(segment
		(start 399.051018 -278.054816)
		(end 400.328384 -279.332182)
		(width 0.14478)
		(layer "In11.Cu")
		(net "M_L_CPU0_SB_DQ<7>")
	)
	(segment
		(start 387.557772 -278.623522)
		(end 387.566154 -278.618696)
		(width 0.0889)
		(layer "In11.Cu")
		(net "M_L_CPU0_SB_DQ<7>")
	)
	(segment
		(start 404.495508 -283.268928)
		(end 404.664164 -283.268928)
		(width 0.14478)
		(layer "In11.Cu")
		(net "M_L_CPU0_SB_DQ<7>")
	)
	(segment
		(start 436.722012 -290.410392)
		(end 437.57215 -289.560254)
		(width 0.14478)
		(layer "In11.Cu")
		(net "M_L_CPU0_SB_DQ<7>")
	)
	(segment
		(start 406.857708 -285.631128)
		(end 407.026364 -285.631128)
		(width 0.14478)
		(layer "In11.Cu")
		(net "M_L_CPU0_SB_DQ<7>")
	)
	(segment
		(start 418.122354 -289.56)
		(end 418.972746 -290.410392)
		(width 0.14478)
		(layer "In11.Cu")
		(net "M_L_CPU0_SB_DQ<7>")
	)
	(segment
		(start 391.691876 -278.623522)
		(end 391.70229 -278.629618)
		(width 0.0889)
		(layer "In11.Cu")
		(net "M_L_CPU0_SB_DQ<7>")
	)
	(segment
		(start 403.089364 -281.694128)
		(end 403.28342 -281.888184)
		(width 0.14478)
		(layer "In11.Cu")
		(net "M_L_CPU0_SB_DQ<7>")
	)
	(segment
		(start 408.79522 -287.399984)
		(end 408.795474 -287.630616)
		(width 0.14478)
		(layer "In11.Cu")
		(net "M_L_CPU0_SB_DQ<7>")
	)
	(segment
		(start 404.071074 -283.074872)
		(end 404.265384 -283.269182)
		(width 0.14478)
		(layer "In11.Cu")
		(net "M_L_CPU0_SB_DQ<7>")
	)
	(segment
		(start 401.708874 -280.544016)
		(end 401.708874 -280.712672)
		(width 0.14478)
		(layer "In11.Cu")
		(net "M_L_CPU0_SB_DQ<7>")
	)
	(segment
		(start 422.484042 -289.560254)
		(end 425.666408 -289.560254)
		(width 0.14478)
		(layer "In11.Cu")
		(net "M_L_CPU0_SB_DQ<7>")
	)
	(segment
		(start 395.159738 -278.319992)
		(end 395.424914 -278.054816)
		(width 0.0889)
		(layer "In11.Cu")
		(net "M_L_CPU0_SB_DQ<7>")
	)
	(segment
		(start 448.19062 -289.560254)
		(end 448.45859 -289.560254)
		(width 0.14478)
		(layer "In11.Cu")
		(net "M_L_CPU0_SB_DQ<7>")
	)
	(segment
		(start 449.015104 -289.27171)
		(end 449.303648 -289.560254)
		(width 0.14478)
		(layer "In11.Cu")
		(net "M_L_CPU0_SB_DQ<7>")
	)
	(segment
		(start 386.983478 -278.618696)
		(end 386.99186 -278.623522)
		(width 0.0889)
		(layer "In11.Cu")
		(net "M_L_CPU0_SB_DQ<7>")
	)
	(segment
		(start 402.301964 -280.906728)
		(end 402.49602 -281.100784)
		(width 0.14478)
		(layer "In11.Cu")
		(net "M_L_CPU0_SB_DQ<7>")
	)
	(segment
		(start 414.940496 -289.56)
		(end 418.122354 -289.56)
		(width 0.14478)
		(layer "In11.Cu")
		(net "M_L_CPU0_SB_DQ<7>")
	)
	(segment
		(start 447.345562 -289.560254)
		(end 447.634106 -289.27171)
		(width 0.14478)
		(layer "In11.Cu")
		(net "M_L_CPU0_SB_DQ<7>")
	)
	(segment
		(start 409.582874 -288.586672)
		(end 411.40634 -290.410138)
		(width 0.14478)
		(layer "In11.Cu")
		(net "M_L_CPU0_SB_DQ<7>")
	)
	(segment
		(start 403.283674 -282.118816)
		(end 403.283674 -282.287472)
		(width 0.14478)
		(layer "In11.Cu")
		(net "M_L_CPU0_SB_DQ<7>")
	)
	(segment
		(start 404.265384 -283.269182)
		(end 404.495508 -283.268928)
		(width 0.14478)
		(layer "In11.Cu")
		(net "M_L_CPU0_SB_DQ<7>")
	)
	(segment
		(start 391.317734 -278.623522)
		(end 391.326116 -278.618696)
		(width 0.0889)
		(layer "In11.Cu")
		(net "M_L_CPU0_SB_DQ<7>")
	)
	(segment
		(start 402.690584 -281.694382)
		(end 402.920708 -281.694128)
		(width 0.14478)
		(layer "In11.Cu")
		(net "M_L_CPU0_SB_DQ<7>")
	)
	(segment
		(start 408.202384 -287.206182)
		(end 408.432508 -287.205928)
		(width 0.14478)
		(layer "In11.Cu")
		(net "M_L_CPU0_SB_DQ<7>")
	)
	(segment
		(start 430.513236 -289.560254)
		(end 433.210462 -289.560254)
		(width 0.14478)
		(layer "In11.Cu")
		(net "M_L_CPU0_SB_DQ<7>")
	)
	(segment
		(start 440.754516 -289.560254)
		(end 441.6044 -290.410138)
		(width 0.14478)
		(layer "In11.Cu")
		(net "M_L_CPU0_SB_DQ<7>")
	)
	(segment
		(start 407.220674 -286.055816)
		(end 407.220674 -286.224472)
		(width 0.14478)
		(layer "In11.Cu")
		(net "M_L_CPU0_SB_DQ<7>")
	)
	(segment
		(start 407.026364 -285.631128)
		(end 407.22042 -285.825184)
		(width 0.14478)
		(layer "In11.Cu")
		(net "M_L_CPU0_SB_DQ<7>")
	)
	(segment
		(start 403.283674 -282.287472)
		(end 403.477984 -282.481782)
		(width 0.14478)
		(layer "In11.Cu")
		(net "M_L_CPU0_SB_DQ<7>")
	)
	(segment
		(start 401.115784 -280.119582)
		(end 401.345908 -280.119328)
		(width 0.14478)
		(layer "In11.Cu")
		(net "M_L_CPU0_SB_DQ<7>")
	)
	(segment
		(start 408.989784 -287.993582)
		(end 409.219908 -287.993328)
		(width 0.14478)
		(layer "In11.Cu")
		(net "M_L_CPU0_SB_DQ<7>")
	)
	(segment
		(start 408.008074 -286.843216)
		(end 408.008074 -287.011872)
		(width 0.14478)
		(layer "In11.Cu")
		(net "M_L_CPU0_SB_DQ<7>")
	)
	(segment
		(start 404.071074 -282.906216)
		(end 404.071074 -283.074872)
		(width 0.14478)
		(layer "In11.Cu")
		(net "M_L_CPU0_SB_DQ<7>")
	)
	(segment
		(start 404.85822 -283.462984)
		(end 404.858474 -283.693616)
		(width 0.14478)
		(layer "In11.Cu")
		(net "M_L_CPU0_SB_DQ<7>")
	)
	(segment
		(start 408.795474 -287.630616)
		(end 408.795474 -287.799272)
		(width 0.14478)
		(layer "In11.Cu")
		(net "M_L_CPU0_SB_DQ<7>")
	)
	(segment
		(start 402.496274 -281.331416)
		(end 402.496274 -281.500072)
		(width 0.14478)
		(layer "In11.Cu")
		(net "M_L_CPU0_SB_DQ<7>")
	)
	(segment
		(start 386.018786 -278.680672)
		(end 386.114798 -278.655272)
		(width 0.0889)
		(layer "In11.Cu")
		(net "M_L_CPU0_SB_DQ<7>")
	)
	(segment
		(start 449.303648 -289.560254)
		(end 449.663058 -289.560254)
		(width 0.14478)
		(layer "In11.Cu")
		(net "M_L_CPU0_SB_DQ<7>")
	)
	(segment
		(start 406.433274 -285.437072)
		(end 406.627584 -285.631382)
		(width 0.14478)
		(layer "In11.Cu")
		(net "M_L_CPU0_SB_DQ<7>")
	)
	(segment
		(start 405.64562 -284.250384)
		(end 405.645874 -284.481016)
		(width 0.14478)
		(layer "In11.Cu")
		(net "M_L_CPU0_SB_DQ<7>")
	)
	(segment
		(start 407.813764 -286.418528)
		(end 408.00782 -286.612584)
		(width 0.14478)
		(layer "In11.Cu")
		(net "M_L_CPU0_SB_DQ<7>")
	)
	(segment
		(start 404.664164 -283.268928)
		(end 404.85822 -283.462984)
		(width 0.14478)
		(layer "In11.Cu")
		(net "M_L_CPU0_SB_DQ<7>")
	)
	(segment
		(start 406.433274 -285.268416)
		(end 406.433274 -285.437072)
		(width 0.14478)
		(layer "In11.Cu")
		(net "M_L_CPU0_SB_DQ<7>")
	)
	(segment
		(start 426.516546 -290.410392)
		(end 429.663098 -290.410392)
		(width 0.14478)
		(layer "In11.Cu")
		(net "M_L_CPU0_SB_DQ<7>")
	)
	(segment
		(start 411.40634 -290.410138)
		(end 414.090358 -290.410138)
		(width 0.14478)
		(layer "In11.Cu")
		(net "M_L_CPU0_SB_DQ<7>")
	)
	(segment
		(start 443.89548 -290.410138)
		(end 444.745364 -289.560254)
		(width 0.14478)
		(layer "In11.Cu")
		(net "M_L_CPU0_SB_DQ<7>")
	)
	(segment
		(start 395.91742 -278.054816)
		(end 399.051018 -278.054816)
		(width 0.14478)
		(layer "In11.Cu")
		(net "M_L_CPU0_SB_DQ<7>")
	)
	(segment
		(start 408.432508 -287.205928)
		(end 408.601164 -287.205928)
		(width 0.14478)
		(layer "In11.Cu")
		(net "M_L_CPU0_SB_DQ<7>")
	)
	(segment
		(start 402.49602 -281.100784)
		(end 402.496274 -281.331416)
		(width 0.14478)
		(layer "In11.Cu")
		(net "M_L_CPU0_SB_DQ<7>")
	)
	(segment
		(start 405.645874 -284.481016)
		(end 405.645874 -284.649672)
		(width 0.14478)
		(layer "In11.Cu")
		(net "M_L_CPU0_SB_DQ<7>")
	)
	(segment
		(start 400.328384 -279.332182)
		(end 400.558508 -279.331928)
		(width 0.14478)
		(layer "In11.Cu")
		(net "M_L_CPU0_SB_DQ<7>")
	)
	(segment
		(start 404.858474 -283.693616)
		(end 404.858474 -283.862272)
		(width 0.14478)
		(layer "In11.Cu")
		(net "M_L_CPU0_SB_DQ<7>")
	)
	(segment
		(start 400.921474 -279.925272)
		(end 401.115784 -280.119582)
		(width 0.14478)
		(layer "In11.Cu")
		(net "M_L_CPU0_SB_DQ<7>")
	)
	(segment
		(start 437.57215 -289.560254)
		(end 440.754516 -289.560254)
		(width 0.14478)
		(layer "In11.Cu")
		(net "M_L_CPU0_SB_DQ<7>")
	)
	(segment
		(start 406.43302 -285.037784)
		(end 406.433274 -285.268416)
		(width 0.14478)
		(layer "In11.Cu")
		(net "M_L_CPU0_SB_DQ<7>")
	)
	(segment
		(start 406.070308 -284.843728)
		(end 406.238964 -284.843728)
		(width 0.14478)
		(layer "In11.Cu")
		(net "M_L_CPU0_SB_DQ<7>")
	)
	(segment
		(start 395.424914 -278.054816)
		(end 395.91742 -278.054816)
		(width 0.0889)
		(layer "In11.Cu")
		(net "M_L_CPU0_SB_DQ<7>")
	)
	(segment
		(start 401.903184 -280.906982)
		(end 402.133308 -280.906728)
		(width 0.14478)
		(layer "In11.Cu")
		(net "M_L_CPU0_SB_DQ<7>")
	)
	(segment
		(start 401.70862 -280.313384)
		(end 401.708874 -280.544016)
		(width 0.14478)
		(layer "In11.Cu")
		(net "M_L_CPU0_SB_DQ<7>")
	)
	(segment
		(start 400.92122 -279.525984)
		(end 400.921474 -279.756616)
		(width 0.14478)
		(layer "In11.Cu")
		(net "M_L_CPU0_SB_DQ<7>")
	)
	(segment
		(start 401.345908 -280.119328)
		(end 401.514564 -280.119328)
		(width 0.14478)
		(layer "In11.Cu")
		(net "M_L_CPU0_SB_DQ<7>")
	)
	(segment
		(start 393.187682 -278.629618)
		(end 393.198096 -278.623522)
		(width 0.0889)
		(layer "In11.Cu")
		(net "M_L_CPU0_SB_DQ<7>")
	)
	(segment
		(start 401.708874 -280.712672)
		(end 401.903184 -280.906982)
		(width 0.14478)
		(layer "In11.Cu")
		(net "M_L_CPU0_SB_DQ<7>")
	)
	(segment
		(start 448.747134 -289.27171)
		(end 449.015104 -289.27171)
		(width 0.14478)
		(layer "In11.Cu")
		(net "M_L_CPU0_SB_DQ<7>")
	)
	(segment
		(start 421.633904 -290.410392)
		(end 422.484042 -289.560254)
		(width 0.14478)
		(layer "In11.Cu")
		(net "M_L_CPU0_SB_DQ<7>")
	)
	(segment
		(start 409.582874 -288.418016)
		(end 409.582874 -288.586672)
		(width 0.14478)
		(layer "In11.Cu")
		(net "M_L_CPU0_SB_DQ<7>")
	)
	(segment
		(start 405.451564 -284.056328)
		(end 405.64562 -284.250384)
		(width 0.14478)
		(layer "In11.Cu")
		(net "M_L_CPU0_SB_DQ<7>")
	)
	(arc
		(start 389.43788 -278.623522)
		(mid 389.624824 -278.573267)
		(end 389.811768 -278.623522)
		(width 0.0889)
		(layer "In11.Cu")
		(net "M_L_CPU0_SB_DQ<7>")
	)
	(arc
		(start 387.566154 -278.618696)
		(mid 387.749662 -278.573202)
		(end 387.931914 -278.623522)
		(width 0.0889)
		(layer "In11.Cu")
		(net "M_L_CPU0_SB_DQ<7>")
	)
	(arc
		(start 389.811768 -278.623522)
		(mid 390.094724 -278.699699)
		(end 390.37768 -278.623522)
		(width 0.0889)
		(layer "In11.Cu")
		(net "M_L_CPU0_SB_DQ<7>")
	)
	(arc
		(start 390.751822 -278.623522)
		(mid 391.034778 -278.699699)
		(end 391.317734 -278.623522)
		(width 0.0889)
		(layer "In11.Cu")
		(net "M_L_CPU0_SB_DQ<7>")
	)
	(arc
		(start 392.258042 -278.623522)
		(mid 392.44524 -278.57314)
		(end 392.632438 -278.623522)
		(width 0.0889)
		(layer "In11.Cu")
		(net "M_L_CPU0_SB_DQ<7>")
	)
	(arc
		(start 390.37768 -278.623522)
		(mid 390.559931 -278.573172)
		(end 390.74344 -278.618696)
		(width 0.0889)
		(layer "In11.Cu")
		(net "M_L_CPU0_SB_DQ<7>")
	)
	(arc
		(start 387.931914 -278.623522)
		(mid 388.21487 -278.699699)
		(end 388.497826 -278.623522)
		(width 0.0889)
		(layer "In11.Cu")
		(net "M_L_CPU0_SB_DQ<7>")
	)
	(arc
		(start 386.99186 -278.623522)
		(mid 387.274816 -278.699699)
		(end 387.557772 -278.623522)
		(width 0.0889)
		(layer "In11.Cu")
		(net "M_L_CPU0_SB_DQ<7>")
	)
	(arc
		(start 393.198096 -278.623522)
		(mid 393.288127 -278.586083)
		(end 393.384786 -278.57323)
		(width 0.0889)
		(layer "In11.Cu")
		(net "M_L_CPU0_SB_DQ<7>")
	)
	(arc
		(start 388.506208 -278.618696)
		(mid 388.689716 -278.573202)
		(end 388.871968 -278.623522)
		(width 0.0889)
		(layer "In11.Cu")
		(net "M_L_CPU0_SB_DQ<7>")
	)
	(arc
		(start 386.617718 -278.623522)
		(mid 386.799969 -278.573172)
		(end 386.983478 -278.618696)
		(width 0.0889)
		(layer "In11.Cu")
		(net "M_L_CPU0_SB_DQ<7>")
	)
	(arc
		(start 388.871968 -278.623522)
		(mid 389.154924 -278.699699)
		(end 389.43788 -278.623522)
		(width 0.0889)
		(layer "In11.Cu")
		(net "M_L_CPU0_SB_DQ<7>")
	)
	(arc
		(start 392.632438 -278.623522)
		(mid 392.909251 -278.699665)
		(end 393.187682 -278.629618)
		(width 0.0889)
		(layer "In11.Cu")
		(net "M_L_CPU0_SB_DQ<7>")
	)
	(arc
		(start 391.326116 -278.618696)
		(mid 391.509624 -278.573202)
		(end 391.691876 -278.623522)
		(width 0.0889)
		(layer "In11.Cu")
		(net "M_L_CPU0_SB_DQ<7>")
	)
	(arc
		(start 391.70229 -278.629618)
		(mid 391.980976 -278.699838)
		(end 392.258042 -278.623522)
		(width 0.0889)
		(layer "In11.Cu")
		(net "M_L_CPU0_SB_DQ<7>")
	)
	(arc
		(start 386.114798 -278.655272)
		(mid 386.370006 -278.698749)
		(end 386.617718 -278.623522)
		(width 0.0889)
		(layer "In11.Cu")
		(net "M_L_CPU0_SB_DQ<7>")
	)
	(segment
		(start 386.807964 -277.870158)
		(end 387.274816 -278.136096)
		(width 0.10668)
		(layer "F.Cu")
		(net "M_L_CPU0_SB_DQ<6>")
	)
	(segment
		(start 443.907926 -288.710116)
		(end 444.149988 -288.710116)
		(width 0.14478)
		(layer "In11.Cu")
		(net "M_L_CPU0_SB_DQ<6>")
	)
	(segment
		(start 415.89706 -287.59531)
		(end 416.161728 -287.859978)
		(width 0.14478)
		(layer "In11.Cu")
		(net "M_L_CPU0_SB_DQ<6>")
	)
	(segment
		(start 444.999872 -287.860232)
		(end 445.19215 -287.860232)
		(width 0.14478)
		(layer "In11.Cu")
		(net "M_L_CPU0_SB_DQ<6>")
	)
	(segment
		(start 415.340546 -287.859978)
		(end 415.605214 -287.59531)
		(width 0.14478)
		(layer "In11.Cu")
		(net "M_L_CPU0_SB_DQ<6>")
	)
	(segment
		(start 447.514726 -287.986978)
		(end 447.641218 -288.11347)
		(width 0.14478)
		(layer "In11.Cu")
		(net "M_L_CPU0_SB_DQ<6>")
	)
	(segment
		(start 392.726672 -277.813516)
		(end 392.738356 -277.806658)
		(width 0.0889)
		(layer "In11.Cu")
		(net "M_L_CPU0_SB_DQ<6>")
	)
	(segment
		(start 437.57215 -287.860232)
		(end 437.90108 -287.860232)
		(width 0.14478)
		(layer "In11.Cu")
		(net "M_L_CPU0_SB_DQ<6>")
	)
	(segment
		(start 440.222894 -287.54451)
		(end 441.3885 -288.710116)
		(width 0.14478)
		(layer "In11.Cu")
		(net "M_L_CPU0_SB_DQ<6>")
	)
	(segment
		(start 441.3885 -288.710116)
		(end 443.049406 -288.710116)
		(width 0.14478)
		(layer "In11.Cu")
		(net "M_L_CPU0_SB_DQ<6>")
	)
	(segment
		(start 418.1221 -287.859978)
		(end 418.972492 -288.71037)
		(width 0.14478)
		(layer "In11.Cu")
		(net "M_L_CPU0_SB_DQ<6>")
	)
	(segment
		(start 392.145266 -277.804372)
		(end 392.161522 -277.81377)
		(width 0.0889)
		(layer "In11.Cu")
		(net "M_L_CPU0_SB_DQ<6>")
	)
	(segment
		(start 443.351412 -288.40811)
		(end 443.60592 -288.40811)
		(width 0.14478)
		(layer "In11.Cu")
		(net "M_L_CPU0_SB_DQ<6>")
	)
	(segment
		(start 422.77157 -287.860232)
		(end 423.014648 -288.10331)
		(width 0.14478)
		(layer "In11.Cu")
		(net "M_L_CPU0_SB_DQ<6>")
	)
	(segment
		(start 435.408832 -288.71037)
		(end 435.685692 -288.43351)
		(width 0.14478)
		(layer "In11.Cu")
		(net "M_L_CPU0_SB_DQ<6>")
	)
	(segment
		(start 428.11446 -288.40811)
		(end 428.368714 -288.40811)
		(width 0.14478)
		(layer "In11.Cu")
		(net "M_L_CPU0_SB_DQ<6>")
	)
	(segment
		(start 448.754246 -288.11347)
		(end 449.057776 -288.11347)
		(width 0.14478)
		(layer "In11.Cu")
		(net "M_L_CPU0_SB_DQ<6>")
	)
	(segment
		(start 447.514726 -287.986724)
		(end 447.514726 -287.986978)
		(width 0.14478)
		(layer "In11.Cu")
		(net "M_L_CPU0_SB_DQ<6>")
	)
	(segment
		(start 449.184268 -287.986724)
		(end 449.31076 -287.860232)
		(width 0.14478)
		(layer "In11.Cu")
		(net "M_L_CPU0_SB_DQ<6>")
	)
	(segment
		(start 430.024286 -288.71037)
		(end 430.874424 -287.860232)
		(width 0.14478)
		(layer "In11.Cu")
		(net "M_L_CPU0_SB_DQ<6>")
	)
	(segment
		(start 423.014648 -288.10331)
		(end 423.328084 -288.10331)
		(width 0.14478)
		(layer "In11.Cu")
		(net "M_L_CPU0_SB_DQ<6>")
	)
	(segment
		(start 411.799786 -288.710116)
		(end 411.944566 -288.565336)
		(width 0.14478)
		(layer "In11.Cu")
		(net "M_L_CPU0_SB_DQ<6>")
	)
	(segment
		(start 431.910236 -287.860232)
		(end 432.149758 -287.62071)
		(width 0.14478)
		(layer "In11.Cu")
		(net "M_L_CPU0_SB_DQ<6>")
	)
	(segment
		(start 436.722012 -288.71037)
		(end 437.57215 -287.860232)
		(width 0.14478)
		(layer "In11.Cu")
		(net "M_L_CPU0_SB_DQ<6>")
	)
	(segment
		(start 412.496 -288.565336)
		(end 412.64078 -288.710116)
		(width 0.14478)
		(layer "In11.Cu")
		(net "M_L_CPU0_SB_DQ<6>")
	)
	(segment
		(start 420.89959 -288.43351)
		(end 421.179244 -288.43351)
		(width 0.14478)
		(layer "In11.Cu")
		(net "M_L_CPU0_SB_DQ<6>")
	)
	(segment
		(start 445.507872 -287.54451)
		(end 445.748664 -287.54451)
		(width 0.14478)
		(layer "In11.Cu")
		(net "M_L_CPU0_SB_DQ<6>")
	)
	(segment
		(start 448.07124 -287.733486)
		(end 448.197732 -287.606994)
		(width 0.14478)
		(layer "In11.Cu")
		(net "M_L_CPU0_SB_DQ<6>")
	)
	(segment
		(start 423.571162 -287.860232)
		(end 424.673522 -287.860232)
		(width 0.14478)
		(layer "In11.Cu")
		(net "M_L_CPU0_SB_DQ<6>")
	)
	(segment
		(start 439.982102 -287.54451)
		(end 440.222894 -287.54451)
		(width 0.14478)
		(layer "In11.Cu")
		(net "M_L_CPU0_SB_DQ<6>")
	)
	(segment
		(start 430.874424 -287.860232)
		(end 431.910236 -287.860232)
		(width 0.14478)
		(layer "In11.Cu")
		(net "M_L_CPU0_SB_DQ<6>")
	)
	(segment
		(start 389.333486 -277.80869)
		(end 389.341868 -277.813516)
		(width 0.0889)
		(layer "In11.Cu")
		(net "M_L_CPU0_SB_DQ<6>")
	)
	(segment
		(start 447.641218 -288.11347)
		(end 447.944748 -288.11347)
		(width 0.14478)
		(layer "In11.Cu")
		(net "M_L_CPU0_SB_DQ<6>")
	)
	(segment
		(start 417.274756 -287.859978)
		(end 418.1221 -287.859978)
		(width 0.14478)
		(layer "In11.Cu")
		(net "M_L_CPU0_SB_DQ<6>")
	)
	(segment
		(start 446.064386 -287.860232)
		(end 447.388234 -287.860232)
		(width 0.14478)
		(layer "In11.Cu")
		(net "M_L_CPU0_SB_DQ<6>")
	)
	(segment
		(start 418.972492 -288.71037)
		(end 420.62273 -288.71037)
		(width 0.14478)
		(layer "In11.Cu")
		(net "M_L_CPU0_SB_DQ<6>")
	)
	(segment
		(start 399.875756 -277.145496)
		(end 411.440376 -288.710116)
		(width 0.14478)
		(layer "In11.Cu")
		(net "M_L_CPU0_SB_DQ<6>")
	)
	(segment
		(start 449.184268 -287.986978)
		(end 449.184268 -287.986724)
		(width 0.14478)
		(layer "In11.Cu")
		(net "M_L_CPU0_SB_DQ<6>")
	)
	(segment
		(start 411.440376 -288.710116)
		(end 411.799786 -288.710116)
		(width 0.14478)
		(layer "In11.Cu")
		(net "M_L_CPU0_SB_DQ<6>")
	)
	(segment
		(start 427.8122 -288.71037)
		(end 428.11446 -288.40811)
		(width 0.14478)
		(layer "In11.Cu")
		(net "M_L_CPU0_SB_DQ<6>")
	)
	(segment
		(start 438.457594 -287.59531)
		(end 438.722516 -287.860232)
		(width 0.14478)
		(layer "In11.Cu")
		(net "M_L_CPU0_SB_DQ<6>")
	)
	(segment
		(start 443.60592 -288.40811)
		(end 443.907926 -288.710116)
		(width 0.14478)
		(layer "In11.Cu")
		(net "M_L_CPU0_SB_DQ<6>")
	)
	(segment
		(start 435.685692 -288.43351)
		(end 435.965346 -288.43351)
		(width 0.14478)
		(layer "In11.Cu")
		(net "M_L_CPU0_SB_DQ<6>")
	)
	(segment
		(start 412.64078 -288.710116)
		(end 414.08985 -288.710116)
		(width 0.14478)
		(layer "In11.Cu")
		(net "M_L_CPU0_SB_DQ<6>")
	)
	(segment
		(start 422.484042 -287.860232)
		(end 422.77157 -287.860232)
		(width 0.14478)
		(layer "In11.Cu")
		(net "M_L_CPU0_SB_DQ<6>")
	)
	(segment
		(start 445.748664 -287.54451)
		(end 446.064386 -287.860232)
		(width 0.14478)
		(layer "In11.Cu")
		(net "M_L_CPU0_SB_DQ<6>")
	)
	(segment
		(start 448.501262 -287.606994)
		(end 448.627754 -287.733486)
		(width 0.14478)
		(layer "In11.Cu")
		(net "M_L_CPU0_SB_DQ<6>")
	)
	(segment
		(start 412.35122 -288.025332)
		(end 412.496 -288.170112)
		(width 0.14478)
		(layer "In11.Cu")
		(net "M_L_CPU0_SB_DQ<6>")
	)
	(segment
		(start 421.456104 -288.71037)
		(end 421.633904 -288.71037)
		(width 0.14478)
		(layer "In11.Cu")
		(net "M_L_CPU0_SB_DQ<6>")
	)
	(segment
		(start 395.938502 -277.145496)
		(end 399.875756 -277.145496)
		(width 0.14478)
		(layer "In11.Cu")
		(net "M_L_CPU0_SB_DQ<6>")
	)
	(segment
		(start 435.965346 -288.43351)
		(end 436.242206 -288.71037)
		(width 0.14478)
		(layer "In11.Cu")
		(net "M_L_CPU0_SB_DQ<6>")
	)
	(segment
		(start 432.46675 -287.62071)
		(end 433.10429 -288.25825)
		(width 0.14478)
		(layer "In11.Cu")
		(net "M_L_CPU0_SB_DQ<6>")
	)
	(segment
		(start 436.242206 -288.71037)
		(end 436.722012 -288.71037)
		(width 0.14478)
		(layer "In11.Cu")
		(net "M_L_CPU0_SB_DQ<6>")
	)
	(segment
		(start 412.496 -288.170112)
		(end 412.496 -288.565336)
		(width 0.14478)
		(layer "In11.Cu")
		(net "M_L_CPU0_SB_DQ<6>")
	)
	(segment
		(start 445.19215 -287.860232)
		(end 445.507872 -287.54451)
		(width 0.14478)
		(layer "In11.Cu")
		(net "M_L_CPU0_SB_DQ<6>")
	)
	(segment
		(start 414.939988 -287.859978)
		(end 415.340546 -287.859978)
		(width 0.14478)
		(layer "In11.Cu")
		(net "M_L_CPU0_SB_DQ<6>")
	)
	(segment
		(start 447.388234 -287.860232)
		(end 447.514726 -287.986724)
		(width 0.14478)
		(layer "In11.Cu")
		(net "M_L_CPU0_SB_DQ<6>")
	)
	(segment
		(start 448.197732 -287.606994)
		(end 448.501262 -287.606994)
		(width 0.14478)
		(layer "In11.Cu")
		(net "M_L_CPU0_SB_DQ<6>")
	)
	(segment
		(start 428.670974 -288.71037)
		(end 428.925228 -288.71037)
		(width 0.14478)
		(layer "In11.Cu")
		(net "M_L_CPU0_SB_DQ<6>")
	)
	(segment
		(start 387.274816 -278.136096)
		(end 387.42874 -277.870666)
		(width 0.0889)
		(layer "In11.Cu")
		(net "M_L_CPU0_SB_DQ<6>")
	)
	(segment
		(start 433.10429 -288.25825)
		(end 433.60848 -288.25825)
		(width 0.14478)
		(layer "In11.Cu")
		(net "M_L_CPU0_SB_DQ<6>")
	)
	(segment
		(start 392.161522 -277.81377)
		(end 392.17346 -277.820628)
		(width 0.0889)
		(layer "In11.Cu")
		(net "M_L_CPU0_SB_DQ<6>")
	)
	(segment
		(start 424.673522 -287.860232)
		(end 424.9674 -288.15411)
		(width 0.14478)
		(layer "In11.Cu")
		(net "M_L_CPU0_SB_DQ<6>")
	)
	(segment
		(start 449.31076 -287.860232)
		(end 449.663058 -287.860232)
		(width 0.14478)
		(layer "In11.Cu")
		(net "M_L_CPU0_SB_DQ<6>")
	)
	(segment
		(start 437.90108 -287.860232)
		(end 438.166002 -287.59531)
		(width 0.14478)
		(layer "In11.Cu")
		(net "M_L_CPU0_SB_DQ<6>")
	)
	(segment
		(start 428.925228 -288.71037)
		(end 429.227488 -288.40811)
		(width 0.14478)
		(layer "In11.Cu")
		(net "M_L_CPU0_SB_DQ<6>")
	)
	(segment
		(start 429.784002 -288.71037)
		(end 430.024286 -288.71037)
		(width 0.14478)
		(layer "In11.Cu")
		(net "M_L_CPU0_SB_DQ<6>")
	)
	(segment
		(start 388.393432 -277.80869)
		(end 388.401814 -277.813516)
		(width 0.0889)
		(layer "In11.Cu")
		(net "M_L_CPU0_SB_DQ<6>")
	)
	(segment
		(start 426.343826 -288.71037)
		(end 427.8122 -288.71037)
		(width 0.14478)
		(layer "In11.Cu")
		(net "M_L_CPU0_SB_DQ<6>")
	)
	(segment
		(start 411.944566 -288.170112)
		(end 412.089346 -288.025332)
		(width 0.14478)
		(layer "In11.Cu")
		(net "M_L_CPU0_SB_DQ<6>")
	)
	(segment
		(start 449.057776 -288.11347)
		(end 449.184268 -287.986978)
		(width 0.14478)
		(layer "In11.Cu")
		(net "M_L_CPU0_SB_DQ<6>")
	)
	(segment
		(start 432.149758 -287.62071)
		(end 432.46675 -287.62071)
		(width 0.14478)
		(layer "In11.Cu")
		(net "M_L_CPU0_SB_DQ<6>")
	)
	(segment
		(start 443.049406 -288.710116)
		(end 443.351412 -288.40811)
		(width 0.14478)
		(layer "In11.Cu")
		(net "M_L_CPU0_SB_DQ<6>")
	)
	(segment
		(start 387.42874 -277.870666)
		(end 387.524752 -277.845266)
		(width 0.0889)
		(layer "In11.Cu")
		(net "M_L_CPU0_SB_DQ<6>")
	)
	(segment
		(start 434.0606 -288.71037)
		(end 435.408832 -288.71037)
		(width 0.14478)
		(layer "In11.Cu")
		(net "M_L_CPU0_SB_DQ<6>")
	)
	(segment
		(start 424.9674 -288.15411)
		(end 425.787566 -288.15411)
		(width 0.14478)
		(layer "In11.Cu")
		(net "M_L_CPU0_SB_DQ<6>")
	)
	(segment
		(start 449.663058 -287.860232)
		(end 450.088 -288.285174)
		(width 0.14478)
		(layer "In11.Cu")
		(net "M_L_CPU0_SB_DQ<6>")
	)
	(segment
		(start 439.66638 -287.860232)
		(end 439.982102 -287.54451)
		(width 0.14478)
		(layer "In11.Cu")
		(net "M_L_CPU0_SB_DQ<6>")
	)
	(segment
		(start 416.161728 -287.859978)
		(end 416.453574 -287.859978)
		(width 0.14478)
		(layer "In11.Cu")
		(net "M_L_CPU0_SB_DQ<6>")
	)
	(segment
		(start 411.944566 -288.565336)
		(end 411.944566 -288.170112)
		(width 0.14478)
		(layer "In11.Cu")
		(net "M_L_CPU0_SB_DQ<6>")
	)
	(segment
		(start 417.010088 -287.59531)
		(end 417.274756 -287.859978)
		(width 0.14478)
		(layer "In11.Cu")
		(net "M_L_CPU0_SB_DQ<6>")
	)
	(segment
		(start 416.718242 -287.59531)
		(end 417.010088 -287.59531)
		(width 0.14478)
		(layer "In11.Cu")
		(net "M_L_CPU0_SB_DQ<6>")
	)
	(segment
		(start 423.328084 -288.10331)
		(end 423.571162 -287.860232)
		(width 0.14478)
		(layer "In11.Cu")
		(net "M_L_CPU0_SB_DQ<6>")
	)
	(segment
		(start 444.149988 -288.710116)
		(end 444.999872 -287.860232)
		(width 0.14478)
		(layer "In11.Cu")
		(net "M_L_CPU0_SB_DQ<6>")
	)
	(segment
		(start 438.722516 -287.860232)
		(end 439.66638 -287.860232)
		(width 0.14478)
		(layer "In11.Cu")
		(net "M_L_CPU0_SB_DQ<6>")
	)
	(segment
		(start 425.787566 -288.15411)
		(end 426.343826 -288.71037)
		(width 0.14478)
		(layer "In11.Cu")
		(net "M_L_CPU0_SB_DQ<6>")
	)
	(segment
		(start 448.07124 -287.986978)
		(end 448.07124 -287.733486)
		(width 0.14478)
		(layer "In11.Cu")
		(net "M_L_CPU0_SB_DQ<6>")
	)
	(segment
		(start 429.481742 -288.40811)
		(end 429.784002 -288.71037)
		(width 0.14478)
		(layer "In11.Cu")
		(net "M_L_CPU0_SB_DQ<6>")
	)
	(segment
		(start 412.089346 -288.025332)
		(end 412.35122 -288.025332)
		(width 0.14478)
		(layer "In11.Cu")
		(net "M_L_CPU0_SB_DQ<6>")
	)
	(segment
		(start 416.453574 -287.859978)
		(end 416.718242 -287.59531)
		(width 0.14478)
		(layer "In11.Cu")
		(net "M_L_CPU0_SB_DQ<6>")
	)
	(segment
		(start 428.368714 -288.40811)
		(end 428.670974 -288.71037)
		(width 0.14478)
		(layer "In11.Cu")
		(net "M_L_CPU0_SB_DQ<6>")
	)
	(segment
		(start 421.179244 -288.43351)
		(end 421.456104 -288.71037)
		(width 0.14478)
		(layer "In11.Cu")
		(net "M_L_CPU0_SB_DQ<6>")
	)
	(segment
		(start 447.944748 -288.11347)
		(end 448.07124 -287.986978)
		(width 0.14478)
		(layer "In11.Cu")
		(net "M_L_CPU0_SB_DQ<6>")
	)
	(segment
		(start 448.627754 -287.733486)
		(end 448.627754 -287.986978)
		(width 0.14478)
		(layer "In11.Cu")
		(net "M_L_CPU0_SB_DQ<6>")
	)
	(segment
		(start 414.08985 -288.710116)
		(end 414.939988 -287.859978)
		(width 0.14478)
		(layer "In11.Cu")
		(net "M_L_CPU0_SB_DQ<6>")
	)
	(segment
		(start 420.62273 -288.71037)
		(end 420.89959 -288.43351)
		(width 0.14478)
		(layer "In11.Cu")
		(net "M_L_CPU0_SB_DQ<6>")
	)
	(segment
		(start 448.627754 -287.986978)
		(end 448.754246 -288.11347)
		(width 0.14478)
		(layer "In11.Cu")
		(net "M_L_CPU0_SB_DQ<6>")
	)
	(segment
		(start 389.90778 -277.813516)
		(end 389.916162 -277.80869)
		(width 0.0889)
		(layer "In11.Cu")
		(net "M_L_CPU0_SB_DQ<6>")
	)
	(segment
		(start 429.227488 -288.40811)
		(end 429.481742 -288.40811)
		(width 0.14478)
		(layer "In11.Cu")
		(net "M_L_CPU0_SB_DQ<6>")
	)
	(segment
		(start 393.384786 -277.88997)
		(end 393.74572 -277.88997)
		(width 0.0889)
		(layer "In11.Cu")
		(net "M_L_CPU0_SB_DQ<6>")
	)
	(segment
		(start 433.60848 -288.25825)
		(end 434.0606 -288.71037)
		(width 0.14478)
		(layer "In11.Cu")
		(net "M_L_CPU0_SB_DQ<6>")
	)
	(segment
		(start 438.166002 -287.59531)
		(end 438.457594 -287.59531)
		(width 0.14478)
		(layer "In11.Cu")
		(net "M_L_CPU0_SB_DQ<6>")
	)
	(segment
		(start 393.74572 -277.88997)
		(end 394.490194 -277.145496)
		(width 0.0889)
		(layer "In11.Cu")
		(net "M_L_CPU0_SB_DQ<6>")
	)
	(segment
		(start 415.605214 -287.59531)
		(end 415.89706 -287.59531)
		(width 0.14478)
		(layer "In11.Cu")
		(net "M_L_CPU0_SB_DQ<6>")
	)
	(segment
		(start 421.633904 -288.71037)
		(end 422.484042 -287.860232)
		(width 0.14478)
		(layer "In11.Cu")
		(net "M_L_CPU0_SB_DQ<6>")
	)
	(segment
		(start 394.490194 -277.145496)
		(end 395.938502 -277.145496)
		(width 0.0889)
		(layer "In11.Cu")
		(net "M_L_CPU0_SB_DQ<6>")
	)
	(arc
		(start 387.524752 -277.845266)
		(mid 387.77996 -277.888743)
		(end 388.027672 -277.813516)
		(width 0.0889)
		(layer "In11.Cu")
		(net "M_L_CPU0_SB_DQ<6>")
	)
	(arc
		(start 388.967726 -277.813516)
		(mid 389.149977 -277.763166)
		(end 389.333486 -277.80869)
		(width 0.0889)
		(layer "In11.Cu")
		(net "M_L_CPU0_SB_DQ<6>")
	)
	(arc
		(start 392.738356 -277.806658)
		(mid 392.920611 -277.763005)
		(end 393.101068 -277.813516)
		(width 0.0889)
		(layer "In11.Cu")
		(net "M_L_CPU0_SB_DQ<6>")
	)
	(arc
		(start 391.221722 -277.813516)
		(mid 391.504678 -277.889693)
		(end 391.787634 -277.813516)
		(width 0.0889)
		(layer "In11.Cu")
		(net "M_L_CPU0_SB_DQ<6>")
	)
	(arc
		(start 390.847834 -277.813516)
		(mid 391.034778 -277.763261)
		(end 391.221722 -277.813516)
		(width 0.0889)
		(layer "In11.Cu")
		(net "M_L_CPU0_SB_DQ<6>")
	)
	(arc
		(start 389.916162 -277.80869)
		(mid 390.09967 -277.763196)
		(end 390.281922 -277.813516)
		(width 0.0889)
		(layer "In11.Cu")
		(net "M_L_CPU0_SB_DQ<6>")
	)
	(arc
		(start 390.281922 -277.813516)
		(mid 390.564878 -277.889693)
		(end 390.847834 -277.813516)
		(width 0.0889)
		(layer "In11.Cu")
		(net "M_L_CPU0_SB_DQ<6>")
	)
	(arc
		(start 393.101068 -277.813516)
		(mid 393.237861 -277.870538)
		(end 393.384786 -277.88997)
		(width 0.0889)
		(layer "In11.Cu")
		(net "M_L_CPU0_SB_DQ<6>")
	)
	(arc
		(start 392.17346 -277.820628)
		(mid 392.450994 -277.889609)
		(end 392.726672 -277.813516)
		(width 0.0889)
		(layer "In11.Cu")
		(net "M_L_CPU0_SB_DQ<6>")
	)
	(arc
		(start 389.341868 -277.813516)
		(mid 389.624824 -277.889693)
		(end 389.90778 -277.813516)
		(width 0.0889)
		(layer "In11.Cu")
		(net "M_L_CPU0_SB_DQ<6>")
	)
	(arc
		(start 391.787634 -277.813516)
		(mid 391.965284 -277.763256)
		(end 392.145266 -277.804372)
		(width 0.0889)
		(layer "In11.Cu")
		(net "M_L_CPU0_SB_DQ<6>")
	)
	(arc
		(start 388.401814 -277.813516)
		(mid 388.68477 -277.889693)
		(end 388.967726 -277.813516)
		(width 0.0889)
		(layer "In11.Cu")
		(net "M_L_CPU0_SB_DQ<6>")
	)
	(arc
		(start 388.027672 -277.813516)
		(mid 388.209923 -277.763166)
		(end 388.393432 -277.80869)
		(width 0.0889)
		(layer "In11.Cu")
		(net "M_L_CPU0_SB_DQ<6>")
	)
	(segment
		(start 385.86791 -277.870158)
		(end 386.334762 -278.136096)
		(width 0.10668)
		(layer "F.Cu")
		(net "M_L_CPU0_SB_DQ<5>")
	)
	(segment
		(start 393.0904 -278.465534)
		(end 393.102084 -278.458676)
		(width 0.0889)
		(layer "In11.Cu")
		(net "M_L_CPU0_SB_DQ<5>")
	)
	(segment
		(start 389.333486 -278.463502)
		(end 389.341868 -278.458676)
		(width 0.0889)
		(layer "In11.Cu")
		(net "M_L_CPU0_SB_DQ<5>")
	)
	(segment
		(start 426.451268 -289.560254)
		(end 429.839882 -289.560254)
		(width 0.14478)
		(layer "In11.Cu")
		(net "M_L_CPU0_SB_DQ<5>")
	)
	(segment
		(start 430.689766 -288.71037)
		(end 433.016406 -288.71037)
		(width 0.14478)
		(layer "In11.Cu")
		(net "M_L_CPU0_SB_DQ<5>")
	)
	(segment
		(start 395.312138 -277.441152)
		(end 395.471142 -277.600156)
		(width 0.0889)
		(layer "In11.Cu")
		(net "M_L_CPU0_SB_DQ<5>")
	)
	(segment
		(start 453.763126 -288.710116)
		(end 454.188068 -289.135058)
		(width 0.14478)
		(layer "In11.Cu")
		(net "M_L_CPU0_SB_DQ<5>")
	)
	(segment
		(start 444.846202 -288.710116)
		(end 453.763126 -288.710116)
		(width 0.14478)
		(layer "In11.Cu")
		(net "M_L_CPU0_SB_DQ<5>")
	)
	(segment
		(start 418.05733 -288.709862)
		(end 418.907722 -289.560254)
		(width 0.14478)
		(layer "In11.Cu")
		(net "M_L_CPU0_SB_DQ<5>")
	)
	(segment
		(start 418.907722 -289.560254)
		(end 421.726868 -289.560254)
		(width 0.14478)
		(layer "In11.Cu")
		(net "M_L_CPU0_SB_DQ<5>")
	)
	(segment
		(start 386.334762 -278.136096)
		(end 386.180838 -278.401526)
		(width 0.0889)
		(layer "In11.Cu")
		(net "M_L_CPU0_SB_DQ<5>")
	)
	(segment
		(start 415.03346 -288.709862)
		(end 418.05733 -288.709862)
		(width 0.14478)
		(layer "In11.Cu")
		(net "M_L_CPU0_SB_DQ<5>")
	)
	(segment
		(start 394.608304 -277.441152)
		(end 395.312138 -277.441152)
		(width 0.0889)
		(layer "In11.Cu")
		(net "M_L_CPU0_SB_DQ<5>")
	)
	(segment
		(start 443.996064 -289.560254)
		(end 444.846202 -288.710116)
		(width 0.14478)
		(layer "In11.Cu")
		(net "M_L_CPU0_SB_DQ<5>")
	)
	(segment
		(start 399.687288 -277.600156)
		(end 411.647132 -289.56)
		(width 0.14478)
		(layer "In11.Cu")
		(net "M_L_CPU0_SB_DQ<5>")
	)
	(segment
		(start 433.016406 -288.71037)
		(end 433.86629 -289.560254)
		(width 0.14478)
		(layer "In11.Cu")
		(net "M_L_CPU0_SB_DQ<5>")
	)
	(segment
		(start 393.666726 -278.38273)
		(end 394.608304 -277.441152)
		(width 0.0889)
		(layer "In11.Cu")
		(net "M_L_CPU0_SB_DQ<5>")
	)
	(segment
		(start 392.717782 -278.45258)
		(end 392.728196 -278.458676)
		(width 0.0889)
		(layer "In11.Cu")
		(net "M_L_CPU0_SB_DQ<5>")
	)
	(segment
		(start 395.86027 -277.600156)
		(end 399.687288 -277.600156)
		(width 0.14478)
		(layer "In11.Cu")
		(net "M_L_CPU0_SB_DQ<5>")
	)
	(segment
		(start 436.814976 -289.560254)
		(end 437.66486 -288.71037)
		(width 0.14478)
		(layer "In11.Cu")
		(net "M_L_CPU0_SB_DQ<5>")
	)
	(segment
		(start 422.576752 -288.71037)
		(end 425.601384 -288.71037)
		(width 0.14478)
		(layer "In11.Cu")
		(net "M_L_CPU0_SB_DQ<5>")
	)
	(segment
		(start 411.647132 -289.56)
		(end 414.183322 -289.56)
		(width 0.14478)
		(layer "In11.Cu")
		(net "M_L_CPU0_SB_DQ<5>")
	)
	(segment
		(start 393.384786 -278.38273)
		(end 393.666726 -278.38273)
		(width 0.0889)
		(layer "In11.Cu")
		(net "M_L_CPU0_SB_DQ<5>")
	)
	(segment
		(start 388.393432 -278.463502)
		(end 388.401814 -278.458676)
		(width 0.0889)
		(layer "In11.Cu")
		(net "M_L_CPU0_SB_DQ<5>")
	)
	(segment
		(start 414.183322 -289.56)
		(end 415.03346 -288.709862)
		(width 0.14478)
		(layer "In11.Cu")
		(net "M_L_CPU0_SB_DQ<5>")
	)
	(segment
		(start 433.86629 -289.560254)
		(end 436.814976 -289.560254)
		(width 0.14478)
		(layer "In11.Cu")
		(net "M_L_CPU0_SB_DQ<5>")
	)
	(segment
		(start 441.539376 -289.560254)
		(end 443.996064 -289.560254)
		(width 0.14478)
		(layer "In11.Cu")
		(net "M_L_CPU0_SB_DQ<5>")
	)
	(segment
		(start 429.839882 -289.560254)
		(end 430.689766 -288.71037)
		(width 0.14478)
		(layer "In11.Cu")
		(net "M_L_CPU0_SB_DQ<5>")
	)
	(segment
		(start 395.471142 -277.600156)
		(end 395.86027 -277.600156)
		(width 0.0889)
		(layer "In11.Cu")
		(net "M_L_CPU0_SB_DQ<5>")
	)
	(segment
		(start 389.90778 -278.458676)
		(end 389.916162 -278.463502)
		(width 0.0889)
		(layer "In11.Cu")
		(net "M_L_CPU0_SB_DQ<5>")
	)
	(segment
		(start 437.66486 -288.71037)
		(end 440.689492 -288.71037)
		(width 0.14478)
		(layer "In11.Cu")
		(net "M_L_CPU0_SB_DQ<5>")
	)
	(segment
		(start 386.180838 -278.401526)
		(end 386.20319 -278.484838)
		(width 0.0889)
		(layer "In11.Cu")
		(net "M_L_CPU0_SB_DQ<5>")
	)
	(segment
		(start 440.689492 -288.71037)
		(end 441.539376 -289.560254)
		(width 0.14478)
		(layer "In11.Cu")
		(net "M_L_CPU0_SB_DQ<5>")
	)
	(segment
		(start 425.601384 -288.71037)
		(end 426.451268 -289.560254)
		(width 0.14478)
		(layer "In11.Cu")
		(net "M_L_CPU0_SB_DQ<5>")
	)
	(segment
		(start 421.726868 -289.560254)
		(end 422.576752 -288.71037)
		(width 0.14478)
		(layer "In11.Cu")
		(net "M_L_CPU0_SB_DQ<5>")
	)
	(arc
		(start 388.027672 -278.458676)
		(mid 388.209923 -278.509026)
		(end 388.393432 -278.463502)
		(width 0.0889)
		(layer "In11.Cu")
		(net "M_L_CPU0_SB_DQ<5>")
	)
	(arc
		(start 388.401814 -278.458676)
		(mid 388.68477 -278.382499)
		(end 388.967726 -278.458676)
		(width 0.0889)
		(layer "In11.Cu")
		(net "M_L_CPU0_SB_DQ<5>")
	)
	(arc
		(start 387.087872 -278.458676)
		(mid 387.274816 -278.508931)
		(end 387.46176 -278.458676)
		(width 0.0889)
		(layer "In11.Cu")
		(net "M_L_CPU0_SB_DQ<5>")
	)
	(arc
		(start 389.916162 -278.463502)
		(mid 390.09967 -278.508996)
		(end 390.281922 -278.458676)
		(width 0.0889)
		(layer "In11.Cu")
		(net "M_L_CPU0_SB_DQ<5>")
	)
	(arc
		(start 388.967726 -278.458676)
		(mid 389.149977 -278.509026)
		(end 389.333486 -278.463502)
		(width 0.0889)
		(layer "In11.Cu")
		(net "M_L_CPU0_SB_DQ<5>")
	)
	(arc
		(start 390.847834 -278.458676)
		(mid 391.034778 -278.508931)
		(end 391.221722 -278.458676)
		(width 0.0889)
		(layer "In11.Cu")
		(net "M_L_CPU0_SB_DQ<5>")
	)
	(arc
		(start 392.728196 -278.458676)
		(mid 392.908401 -278.508993)
		(end 393.0904 -278.465534)
		(width 0.0889)
		(layer "In11.Cu")
		(net "M_L_CPU0_SB_DQ<5>")
	)
	(arc
		(start 390.281922 -278.458676)
		(mid 390.564878 -278.382499)
		(end 390.847834 -278.458676)
		(width 0.0889)
		(layer "In11.Cu")
		(net "M_L_CPU0_SB_DQ<5>")
	)
	(arc
		(start 386.20319 -278.484838)
		(mid 386.365522 -278.507656)
		(end 386.52196 -278.458676)
		(width 0.0889)
		(layer "In11.Cu")
		(net "M_L_CPU0_SB_DQ<5>")
	)
	(arc
		(start 387.46176 -278.458676)
		(mid 387.744716 -278.382499)
		(end 388.027672 -278.458676)
		(width 0.0889)
		(layer "In11.Cu")
		(net "M_L_CPU0_SB_DQ<5>")
	)
	(arc
		(start 389.341868 -278.458676)
		(mid 389.624824 -278.382499)
		(end 389.90778 -278.458676)
		(width 0.0889)
		(layer "In11.Cu")
		(net "M_L_CPU0_SB_DQ<5>")
	)
	(arc
		(start 393.102084 -278.458676)
		(mid 393.238418 -278.402033)
		(end 393.384786 -278.38273)
		(width 0.0889)
		(layer "In11.Cu")
		(net "M_L_CPU0_SB_DQ<5>")
	)
	(arc
		(start 392.16203 -278.458676)
		(mid 392.439097 -278.382405)
		(end 392.717782 -278.45258)
		(width 0.0889)
		(layer "In11.Cu")
		(net "M_L_CPU0_SB_DQ<5>")
	)
	(arc
		(start 386.52196 -278.458676)
		(mid 386.804916 -278.382499)
		(end 387.087872 -278.458676)
		(width 0.0889)
		(layer "In11.Cu")
		(net "M_L_CPU0_SB_DQ<5>")
	)
	(arc
		(start 391.787634 -278.458676)
		(mid 391.974832 -278.509058)
		(end 392.16203 -278.458676)
		(width 0.0889)
		(layer "In11.Cu")
		(net "M_L_CPU0_SB_DQ<5>")
	)
	(arc
		(start 391.221722 -278.458676)
		(mid 391.504678 -278.382499)
		(end 391.787634 -278.458676)
		(width 0.0889)
		(layer "In11.Cu")
		(net "M_L_CPU0_SB_DQ<5>")
	)
	(segment
		(start 387.277864 -277.060152)
		(end 387.744716 -277.32609)
		(width 0.10668)
		(layer "F.Cu")
		(net "M_L_CPU0_SB_DQ<4>")
	)
	(segment
		(start 444.185802 -287.86963)
		(end 445.03594 -287.019492)
		(width 0.14478)
		(layer "In11.Cu")
		(net "M_L_CPU0_SB_DQ<4>")
	)
	(segment
		(start 453.763126 -287.010094)
		(end 454.188068 -287.435036)
		(width 0.14478)
		(layer "In11.Cu")
		(net "M_L_CPU0_SB_DQ<4>")
	)
	(segment
		(start 400.064224 -276.690836)
		(end 410.88056 -287.507172)
		(width 0.14478)
		(layer "In11.Cu")
		(net "M_L_CPU0_SB_DQ<4>")
	)
	(segment
		(start 392.257026 -277.648416)
		(end 392.270742 -277.65629)
		(width 0.0889)
		(layer "In11.Cu")
		(net "M_L_CPU0_SB_DQ<4>")
	)
	(segment
		(start 429.261524 -287.86963)
		(end 430.111408 -287.019746)
		(width 0.14478)
		(layer "In11.Cu")
		(net "M_L_CPU0_SB_DQ<4>")
	)
	(segment
		(start 390.74344 -277.653496)
		(end 390.751822 -277.64867)
		(width 0.0889)
		(layer "In11.Cu")
		(net "M_L_CPU0_SB_DQ<4>")
	)
	(segment
		(start 441.320174 -287.86963)
		(end 444.185802 -287.86963)
		(width 0.14478)
		(layer "In11.Cu")
		(net "M_L_CPU0_SB_DQ<4>")
	)
	(segment
		(start 391.317734 -277.64867)
		(end 391.326116 -277.653496)
		(width 0.0889)
		(layer "In11.Cu")
		(net "M_L_CPU0_SB_DQ<4>")
	)
	(segment
		(start 387.744716 -277.32609)
		(end 387.590792 -277.59152)
		(width 0.0889)
		(layer "In11.Cu")
		(net "M_L_CPU0_SB_DQ<4>")
	)
	(segment
		(start 388.497826 -277.64867)
		(end 388.506208 -277.653496)
		(width 0.0889)
		(layer "In11.Cu")
		(net "M_L_CPU0_SB_DQ<4>")
	)
	(segment
		(start 410.88056 -287.507172)
		(end 413.069278 -287.507172)
		(width 0.14478)
		(layer "In11.Cu")
		(net "M_L_CPU0_SB_DQ<4>")
	)
	(segment
		(start 433.002436 -287.019746)
		(end 433.85232 -287.86963)
		(width 0.14478)
		(layer "In11.Cu")
		(net "M_L_CPU0_SB_DQ<4>")
	)
	(segment
		(start 436.805578 -287.86963)
		(end 437.655462 -287.019746)
		(width 0.14478)
		(layer "In11.Cu")
		(net "M_L_CPU0_SB_DQ<4>")
	)
	(segment
		(start 445.03594 -287.019492)
		(end 452.460106 -287.019492)
		(width 0.14478)
		(layer "In11.Cu")
		(net "M_L_CPU0_SB_DQ<4>")
	)
	(segment
		(start 387.590792 -277.59152)
		(end 387.613144 -277.674832)
		(width 0.0889)
		(layer "In11.Cu")
		(net "M_L_CPU0_SB_DQ<4>")
	)
	(segment
		(start 453.333358 -287.010094)
		(end 453.763126 -287.010094)
		(width 0.14478)
		(layer "In11.Cu")
		(net "M_L_CPU0_SB_DQ<4>")
	)
	(segment
		(start 414.182814 -287.860232)
		(end 414.911794 -287.131252)
		(width 0.14478)
		(layer "In11.Cu")
		(net "M_L_CPU0_SB_DQ<4>")
	)
	(segment
		(start 413.069278 -287.507172)
		(end 413.422338 -287.860232)
		(width 0.14478)
		(layer "In11.Cu")
		(net "M_L_CPU0_SB_DQ<4>")
	)
	(segment
		(start 418.178488 -287.131252)
		(end 418.916866 -287.86963)
		(width 0.14478)
		(layer "In11.Cu")
		(net "M_L_CPU0_SB_DQ<4>")
	)
	(segment
		(start 433.85232 -287.86963)
		(end 436.805578 -287.86963)
		(width 0.14478)
		(layer "In11.Cu")
		(net "M_L_CPU0_SB_DQ<4>")
	)
	(segment
		(start 452.613776 -287.173162)
		(end 452.613776 -287.813242)
		(width 0.14478)
		(layer "In11.Cu")
		(net "M_L_CPU0_SB_DQ<4>")
	)
	(segment
		(start 392.245088 -277.641558)
		(end 392.257026 -277.648416)
		(width 0.0889)
		(layer "In11.Cu")
		(net "M_L_CPU0_SB_DQ<4>")
	)
	(segment
		(start 394.56614 -276.690836)
		(end 395.957552 -276.690836)
		(width 0.0889)
		(layer "In11.Cu")
		(net "M_L_CPU0_SB_DQ<4>")
	)
	(segment
		(start 453.17029 -287.813242)
		(end 453.17029 -287.173162)
		(width 0.14478)
		(layer "In11.Cu")
		(net "M_L_CPU0_SB_DQ<4>")
	)
	(segment
		(start 395.957552 -276.690836)
		(end 400.064224 -276.690836)
		(width 0.14478)
		(layer "In11.Cu")
		(net "M_L_CPU0_SB_DQ<4>")
	)
	(segment
		(start 421.71747 -287.86963)
		(end 422.567354 -287.019746)
		(width 0.14478)
		(layer "In11.Cu")
		(net "M_L_CPU0_SB_DQ<4>")
	)
	(segment
		(start 425.453302 -287.019746)
		(end 426.303186 -287.86963)
		(width 0.14478)
		(layer "In11.Cu")
		(net "M_L_CPU0_SB_DQ<4>")
	)
	(segment
		(start 393.557506 -277.69947)
		(end 394.56614 -276.690836)
		(width 0.0889)
		(layer "In11.Cu")
		(net "M_L_CPU0_SB_DQ<4>")
	)
	(segment
		(start 418.916866 -287.86963)
		(end 421.71747 -287.86963)
		(width 0.14478)
		(layer "In11.Cu")
		(net "M_L_CPU0_SB_DQ<4>")
	)
	(segment
		(start 453.007222 -287.97631)
		(end 453.17029 -287.813242)
		(width 0.14478)
		(layer "In11.Cu")
		(net "M_L_CPU0_SB_DQ<4>")
	)
	(segment
		(start 452.776844 -287.97631)
		(end 453.007222 -287.97631)
		(width 0.14478)
		(layer "In11.Cu")
		(net "M_L_CPU0_SB_DQ<4>")
	)
	(segment
		(start 413.422338 -287.860232)
		(end 414.182814 -287.860232)
		(width 0.14478)
		(layer "In11.Cu")
		(net "M_L_CPU0_SB_DQ<4>")
	)
	(segment
		(start 437.655462 -287.019746)
		(end 440.47029 -287.019746)
		(width 0.14478)
		(layer "In11.Cu")
		(net "M_L_CPU0_SB_DQ<4>")
	)
	(segment
		(start 422.567354 -287.019746)
		(end 425.453302 -287.019746)
		(width 0.14478)
		(layer "In11.Cu")
		(net "M_L_CPU0_SB_DQ<4>")
	)
	(segment
		(start 440.47029 -287.019746)
		(end 441.320174 -287.86963)
		(width 0.14478)
		(layer "In11.Cu")
		(net "M_L_CPU0_SB_DQ<4>")
	)
	(segment
		(start 392.63066 -277.64867)
		(end 392.648694 -277.638002)
		(width 0.0889)
		(layer "In11.Cu")
		(net "M_L_CPU0_SB_DQ<4>")
	)
	(segment
		(start 452.460106 -287.019492)
		(end 452.613776 -287.173162)
		(width 0.14478)
		(layer "In11.Cu")
		(net "M_L_CPU0_SB_DQ<4>")
	)
	(segment
		(start 453.17029 -287.173162)
		(end 453.333358 -287.010094)
		(width 0.14478)
		(layer "In11.Cu")
		(net "M_L_CPU0_SB_DQ<4>")
	)
	(segment
		(start 393.384786 -277.69947)
		(end 393.557506 -277.69947)
		(width 0.0889)
		(layer "In11.Cu")
		(net "M_L_CPU0_SB_DQ<4>")
	)
	(segment
		(start 452.613776 -287.813242)
		(end 452.776844 -287.97631)
		(width 0.14478)
		(layer "In11.Cu")
		(net "M_L_CPU0_SB_DQ<4>")
	)
	(segment
		(start 426.303186 -287.86963)
		(end 429.261524 -287.86963)
		(width 0.14478)
		(layer "In11.Cu")
		(net "M_L_CPU0_SB_DQ<4>")
	)
	(segment
		(start 414.911794 -287.131252)
		(end 418.178488 -287.131252)
		(width 0.14478)
		(layer "In11.Cu")
		(net "M_L_CPU0_SB_DQ<4>")
	)
	(segment
		(start 430.111408 -287.019746)
		(end 433.002436 -287.019746)
		(width 0.14478)
		(layer "In11.Cu")
		(net "M_L_CPU0_SB_DQ<4>")
	)
	(arc
		(start 392.648694 -277.638002)
		(mid 392.924389 -277.572159)
		(end 393.197334 -277.64867)
		(width 0.0889)
		(layer "In11.Cu")
		(net "M_L_CPU0_SB_DQ<4>")
	)
	(arc
		(start 387.613144 -277.674832)
		(mid 387.775476 -277.69765)
		(end 387.931914 -277.64867)
		(width 0.0889)
		(layer "In11.Cu")
		(net "M_L_CPU0_SB_DQ<4>")
	)
	(arc
		(start 388.871968 -277.64867)
		(mid 389.154924 -277.572493)
		(end 389.43788 -277.64867)
		(width 0.0889)
		(layer "In11.Cu")
		(net "M_L_CPU0_SB_DQ<4>")
	)
	(arc
		(start 390.37768 -277.64867)
		(mid 390.559931 -277.69902)
		(end 390.74344 -277.653496)
		(width 0.0889)
		(layer "In11.Cu")
		(net "M_L_CPU0_SB_DQ<4>")
	)
	(arc
		(start 393.197334 -277.64867)
		(mid 393.287697 -277.68648)
		(end 393.384786 -277.69947)
		(width 0.0889)
		(layer "In11.Cu")
		(net "M_L_CPU0_SB_DQ<4>")
	)
	(arc
		(start 389.43788 -277.64867)
		(mid 389.624824 -277.698925)
		(end 389.811768 -277.64867)
		(width 0.0889)
		(layer "In11.Cu")
		(net "M_L_CPU0_SB_DQ<4>")
	)
	(arc
		(start 388.506208 -277.653496)
		(mid 388.689716 -277.69899)
		(end 388.871968 -277.64867)
		(width 0.0889)
		(layer "In11.Cu")
		(net "M_L_CPU0_SB_DQ<4>")
	)
	(arc
		(start 391.326116 -277.653496)
		(mid 391.509624 -277.69899)
		(end 391.691876 -277.64867)
		(width 0.0889)
		(layer "In11.Cu")
		(net "M_L_CPU0_SB_DQ<4>")
	)
	(arc
		(start 389.811768 -277.64867)
		(mid 390.094724 -277.572493)
		(end 390.37768 -277.64867)
		(width 0.0889)
		(layer "In11.Cu")
		(net "M_L_CPU0_SB_DQ<4>")
	)
	(arc
		(start 391.691876 -277.64867)
		(mid 391.967554 -277.57254)
		(end 392.245088 -277.641558)
		(width 0.0889)
		(layer "In11.Cu")
		(net "M_L_CPU0_SB_DQ<4>")
	)
	(arc
		(start 390.751822 -277.64867)
		(mid 391.034778 -277.572493)
		(end 391.317734 -277.64867)
		(width 0.0889)
		(layer "In11.Cu")
		(net "M_L_CPU0_SB_DQ<4>")
	)
	(arc
		(start 387.931914 -277.64867)
		(mid 388.21487 -277.572493)
		(end 388.497826 -277.64867)
		(width 0.0889)
		(layer "In11.Cu")
		(net "M_L_CPU0_SB_DQ<4>")
	)
	(arc
		(start 392.270742 -277.65629)
		(mid 392.451672 -277.698768)
		(end 392.63066 -277.64867)
		(width 0.0889)
		(layer "In11.Cu")
		(net "M_L_CPU0_SB_DQ<4>")
	)
	(segment
		(start 385.39801 -275.44014)
		(end 385.864862 -275.706078)
		(width 0.10668)
		(layer "F.Cu")
		(net "M_L_CPU0_SB_DQ<3>")
	)
	(segment
		(start 418.963094 -284.45079)
		(end 418.112956 -283.600652)
		(width 0.14478)
		(layer "In11.Cu")
		(net "M_L_CPU0_SB_DQ<3>")
	)
	(segment
		(start 429.08982 -284.45079)
		(end 426.507148 -284.45079)
		(width 0.14478)
		(layer "In11.Cu")
		(net "M_L_CPU0_SB_DQ<3>")
	)
	(segment
		(start 390.751822 -275.383498)
		(end 390.74344 -275.378672)
		(width 0.0889)
		(layer "In11.Cu")
		(net "M_L_CPU0_SB_DQ<3>")
	)
	(segment
		(start 433.201064 -283.600652)
		(end 429.939958 -283.600652)
		(width 0.14478)
		(layer "In11.Cu")
		(net "M_L_CPU0_SB_DQ<3>")
	)
	(segment
		(start 409.867608 -282.63215)
		(end 409.706572 -282.793186)
		(width 0.14478)
		(layer "In11.Cu")
		(net "M_L_CPU0_SB_DQ<3>")
	)
	(segment
		(start 409.312872 -282.399486)
		(end 409.473908 -282.23845)
		(width 0.14478)
		(layer "In11.Cu")
		(net "M_L_CPU0_SB_DQ<3>")
	)
	(segment
		(start 408.525472 -281.842718)
		(end 408.525472 -281.612086)
		(width 0.14478)
		(layer "In11.Cu")
		(net "M_L_CPU0_SB_DQ<3>")
	)
	(segment
		(start 407.505408 -280.26995)
		(end 407.344372 -280.430986)
		(width 0.14478)
		(layer "In11.Cu")
		(net "M_L_CPU0_SB_DQ<3>")
	)
	(segment
		(start 407.90114 -281.218386)
		(end 407.738072 -281.055318)
		(width 0.14478)
		(layer "In11.Cu")
		(net "M_L_CPU0_SB_DQ<3>")
	)
	(segment
		(start 388.506208 -275.378672)
		(end 388.497826 -275.383498)
		(width 0.0889)
		(layer "In11.Cu")
		(net "M_L_CPU0_SB_DQ<3>")
	)
	(segment
		(start 410.493972 -283.580586)
		(end 410.26334 -283.580586)
		(width 0.14478)
		(layer "In11.Cu")
		(net "M_L_CPU0_SB_DQ<3>")
	)
	(segment
		(start 391.326116 -275.378672)
		(end 391.317734 -275.383498)
		(width 0.0889)
		(layer "In11.Cu")
		(net "M_L_CPU0_SB_DQ<3>")
	)
	(segment
		(start 407.899108 -280.433018)
		(end 407.73604 -280.26995)
		(width 0.14478)
		(layer "In11.Cu")
		(net "M_L_CPU0_SB_DQ<3>")
	)
	(segment
		(start 387.566154 -275.378672)
		(end 387.557772 -275.383498)
		(width 0.0889)
		(layer "In11.Cu")
		(net "M_L_CPU0_SB_DQ<3>")
	)
	(segment
		(start 414.611058 -283.600652)
		(end 414.108138 -284.103572)
		(width 0.14478)
		(layer "In11.Cu")
		(net "M_L_CPU0_SB_DQ<3>")
	)
	(segment
		(start 449.65366 -283.600652)
		(end 449.22059 -283.600652)
		(width 0.14478)
		(layer "In11.Cu")
		(net "M_L_CPU0_SB_DQ<3>")
	)
	(segment
		(start 421.545766 -284.45079)
		(end 418.963094 -284.45079)
		(width 0.14478)
		(layer "In11.Cu")
		(net "M_L_CPU0_SB_DQ<3>")
	)
	(segment
		(start 410.26334 -283.580586)
		(end 410.100272 -283.417518)
		(width 0.14478)
		(layer "In11.Cu")
		(net "M_L_CPU0_SB_DQ<3>")
	)
	(segment
		(start 410.261308 -282.795218)
		(end 410.09824 -282.63215)
		(width 0.14478)
		(layer "In11.Cu")
		(net "M_L_CPU0_SB_DQ<3>")
	)
	(segment
		(start 450.088 -284.034992)
		(end 449.65366 -283.600652)
		(width 0.14478)
		(layer "In11.Cu")
		(net "M_L_CPU0_SB_DQ<3>")
	)
	(segment
		(start 411.588458 -284.103572)
		(end 410.904436 -283.41955)
		(width 0.14478)
		(layer "In11.Cu")
		(net "M_L_CPU0_SB_DQ<3>")
	)
	(segment
		(start 386.114798 -275.415248)
		(end 386.018786 -275.440648)
		(width 0.0889)
		(layer "In11.Cu")
		(net "M_L_CPU0_SB_DQ<3>")
	)
	(segment
		(start 408.525472 -281.612086)
		(end 408.686508 -281.45105)
		(width 0.14478)
		(layer "In11.Cu")
		(net "M_L_CPU0_SB_DQ<3>")
	)
	(segment
		(start 426.507148 -284.45079)
		(end 425.65701 -283.600652)
		(width 0.14478)
		(layer "In11.Cu")
		(net "M_L_CPU0_SB_DQ<3>")
	)
	(segment
		(start 410.100272 -283.186886)
		(end 410.261308 -283.02585)
		(width 0.14478)
		(layer "In11.Cu")
		(net "M_L_CPU0_SB_DQ<3>")
	)
	(segment
		(start 407.738072 -280.824686)
		(end 407.899108 -280.66365)
		(width 0.14478)
		(layer "In11.Cu")
		(net "M_L_CPU0_SB_DQ<3>")
	)
	(segment
		(start 443.632082 -284.45079)
		(end 441.595256 -284.45079)
		(width 0.14478)
		(layer "In11.Cu")
		(net "M_L_CPU0_SB_DQ<3>")
	)
	(segment
		(start 440.745118 -283.600652)
		(end 437.48706 -283.600652)
		(width 0.14478)
		(layer "In11.Cu")
		(net "M_L_CPU0_SB_DQ<3>")
	)
	(segment
		(start 408.292808 -281.05735)
		(end 408.131772 -281.218386)
		(width 0.14478)
		(layer "In11.Cu")
		(net "M_L_CPU0_SB_DQ<3>")
	)
	(segment
		(start 414.108138 -284.103572)
		(end 411.588458 -284.103572)
		(width 0.14478)
		(layer "In11.Cu")
		(net "M_L_CPU0_SB_DQ<3>")
	)
	(segment
		(start 410.100272 -283.417518)
		(end 410.100272 -283.186886)
		(width 0.14478)
		(layer "In11.Cu")
		(net "M_L_CPU0_SB_DQ<3>")
	)
	(segment
		(start 449.07581 -283.745432)
		(end 449.07581 -284.029912)
		(width 0.14478)
		(layer "In11.Cu")
		(net "M_L_CPU0_SB_DQ<3>")
	)
	(segment
		(start 407.344372 -280.430986)
		(end 407.11374 -280.430986)
		(width 0.14478)
		(layer "In11.Cu")
		(net "M_L_CPU0_SB_DQ<3>")
	)
	(segment
		(start 408.686508 -281.45105)
		(end 408.686508 -281.220418)
		(width 0.14478)
		(layer "In11.Cu")
		(net "M_L_CPU0_SB_DQ<3>")
	)
	(segment
		(start 395.568678 -274.179792)
		(end 394.862558 -274.179792)
		(width 0.0889)
		(layer "In11.Cu")
		(net "M_L_CPU0_SB_DQ<3>")
	)
	(segment
		(start 422.395904 -283.600652)
		(end 421.545766 -284.45079)
		(width 0.14478)
		(layer "In11.Cu")
		(net "M_L_CPU0_SB_DQ<3>")
	)
	(segment
		(start 448.524376 -284.029912)
		(end 448.524376 -283.745432)
		(width 0.14478)
		(layer "In11.Cu")
		(net "M_L_CPU0_SB_DQ<3>")
	)
	(segment
		(start 448.379596 -283.600652)
		(end 444.48222 -283.600652)
		(width 0.14478)
		(layer "In11.Cu")
		(net "M_L_CPU0_SB_DQ<3>")
	)
	(segment
		(start 436.636922 -284.45079)
		(end 434.051202 -284.45079)
		(width 0.14478)
		(layer "In11.Cu")
		(net "M_L_CPU0_SB_DQ<3>")
	)
	(segment
		(start 434.051202 -284.45079)
		(end 433.201064 -283.600652)
		(width 0.14478)
		(layer "In11.Cu")
		(net "M_L_CPU0_SB_DQ<3>")
	)
	(segment
		(start 393.198096 -275.383498)
		(end 393.187682 -275.389594)
		(width 0.0889)
		(layer "In11.Cu")
		(net "M_L_CPU0_SB_DQ<3>")
	)
	(segment
		(start 448.93103 -284.174692)
		(end 448.669156 -284.174692)
		(width 0.14478)
		(layer "In11.Cu")
		(net "M_L_CPU0_SB_DQ<3>")
	)
	(segment
		(start 409.473908 -282.007818)
		(end 409.31084 -281.84475)
		(width 0.14478)
		(layer "In11.Cu")
		(net "M_L_CPU0_SB_DQ<3>")
	)
	(segment
		(start 393.709144 -275.333206)
		(end 393.384786 -275.333206)
		(width 0.0889)
		(layer "In11.Cu")
		(net "M_L_CPU0_SB_DQ<3>")
	)
	(segment
		(start 408.919172 -282.005786)
		(end 408.68854 -282.005786)
		(width 0.14478)
		(layer "In11.Cu")
		(net "M_L_CPU0_SB_DQ<3>")
	)
	(segment
		(start 409.31084 -281.84475)
		(end 409.080208 -281.84475)
		(width 0.14478)
		(layer "In11.Cu")
		(net "M_L_CPU0_SB_DQ<3>")
	)
	(segment
		(start 386.018786 -275.440648)
		(end 385.864862 -275.706078)
		(width 0.0889)
		(layer "In11.Cu")
		(net "M_L_CPU0_SB_DQ<3>")
	)
	(segment
		(start 407.73604 -280.26995)
		(end 407.505408 -280.26995)
		(width 0.14478)
		(layer "In11.Cu")
		(net "M_L_CPU0_SB_DQ<3>")
	)
	(segment
		(start 418.112956 -283.600652)
		(end 414.611058 -283.600652)
		(width 0.14478)
		(layer "In11.Cu")
		(net "M_L_CPU0_SB_DQ<3>")
	)
	(segment
		(start 408.131772 -281.218386)
		(end 407.90114 -281.218386)
		(width 0.14478)
		(layer "In11.Cu")
		(net "M_L_CPU0_SB_DQ<3>")
	)
	(segment
		(start 408.52344 -281.05735)
		(end 408.292808 -281.05735)
		(width 0.14478)
		(layer "In11.Cu")
		(net "M_L_CPU0_SB_DQ<3>")
	)
	(segment
		(start 441.595256 -284.45079)
		(end 440.745118 -283.600652)
		(width 0.14478)
		(layer "In11.Cu")
		(net "M_L_CPU0_SB_DQ<3>")
	)
	(segment
		(start 395.994636 -274.30349)
		(end 395.692376 -274.30349)
		(width 0.0889)
		(layer "In11.Cu")
		(net "M_L_CPU0_SB_DQ<3>")
	)
	(segment
		(start 429.939958 -283.600652)
		(end 429.08982 -284.45079)
		(width 0.14478)
		(layer "In11.Cu")
		(net "M_L_CPU0_SB_DQ<3>")
	)
	(segment
		(start 386.99186 -275.383498)
		(end 386.983478 -275.378672)
		(width 0.0889)
		(layer "In11.Cu")
		(net "M_L_CPU0_SB_DQ<3>")
	)
	(segment
		(start 437.48706 -283.600652)
		(end 436.636922 -284.45079)
		(width 0.14478)
		(layer "In11.Cu")
		(net "M_L_CPU0_SB_DQ<3>")
	)
	(segment
		(start 448.524376 -283.745432)
		(end 448.379596 -283.600652)
		(width 0.14478)
		(layer "In11.Cu")
		(net "M_L_CPU0_SB_DQ<3>")
	)
	(segment
		(start 391.70229 -275.389594)
		(end 391.691876 -275.383498)
		(width 0.0889)
		(layer "In11.Cu")
		(net "M_L_CPU0_SB_DQ<3>")
	)
	(segment
		(start 449.22059 -283.600652)
		(end 449.07581 -283.745432)
		(width 0.14478)
		(layer "In11.Cu")
		(net "M_L_CPU0_SB_DQ<3>")
	)
	(segment
		(start 449.07581 -284.029912)
		(end 448.93103 -284.174692)
		(width 0.14478)
		(layer "In11.Cu")
		(net "M_L_CPU0_SB_DQ<3>")
	)
	(segment
		(start 400.986244 -274.30349)
		(end 395.994636 -274.30349)
		(width 0.14478)
		(layer "In11.Cu")
		(net "M_L_CPU0_SB_DQ<3>")
	)
	(segment
		(start 410.09824 -282.63215)
		(end 409.867608 -282.63215)
		(width 0.14478)
		(layer "In11.Cu")
		(net "M_L_CPU0_SB_DQ<3>")
	)
	(segment
		(start 409.473908 -282.23845)
		(end 409.473908 -282.007818)
		(width 0.14478)
		(layer "In11.Cu")
		(net "M_L_CPU0_SB_DQ<3>")
	)
	(segment
		(start 448.669156 -284.174692)
		(end 448.524376 -284.029912)
		(width 0.14478)
		(layer "In11.Cu")
		(net "M_L_CPU0_SB_DQ<3>")
	)
	(segment
		(start 410.904436 -283.41955)
		(end 410.655008 -283.41955)
		(width 0.14478)
		(layer "In11.Cu")
		(net "M_L_CPU0_SB_DQ<3>")
	)
	(segment
		(start 395.692376 -274.30349)
		(end 395.568678 -274.179792)
		(width 0.0889)
		(layer "In11.Cu")
		(net "M_L_CPU0_SB_DQ<3>")
	)
	(segment
		(start 409.706572 -282.793186)
		(end 409.47594 -282.793186)
		(width 0.14478)
		(layer "In11.Cu")
		(net "M_L_CPU0_SB_DQ<3>")
	)
	(segment
		(start 444.48222 -283.600652)
		(end 443.632082 -284.45079)
		(width 0.14478)
		(layer "In11.Cu")
		(net "M_L_CPU0_SB_DQ<3>")
	)
	(segment
		(start 409.47594 -282.793186)
		(end 409.312872 -282.630118)
		(width 0.14478)
		(layer "In11.Cu")
		(net "M_L_CPU0_SB_DQ<3>")
	)
	(segment
		(start 394.862558 -274.179792)
		(end 393.709144 -275.333206)
		(width 0.0889)
		(layer "In11.Cu")
		(net "M_L_CPU0_SB_DQ<3>")
	)
	(segment
		(start 408.68854 -282.005786)
		(end 408.525472 -281.842718)
		(width 0.14478)
		(layer "In11.Cu")
		(net "M_L_CPU0_SB_DQ<3>")
	)
	(segment
		(start 407.738072 -281.055318)
		(end 407.738072 -280.824686)
		(width 0.14478)
		(layer "In11.Cu")
		(net "M_L_CPU0_SB_DQ<3>")
	)
	(segment
		(start 410.261308 -283.02585)
		(end 410.261308 -282.795218)
		(width 0.14478)
		(layer "In11.Cu")
		(net "M_L_CPU0_SB_DQ<3>")
	)
	(segment
		(start 407.11374 -280.430986)
		(end 400.986244 -274.30349)
		(width 0.14478)
		(layer "In11.Cu")
		(net "M_L_CPU0_SB_DQ<3>")
	)
	(segment
		(start 410.655008 -283.41955)
		(end 410.493972 -283.580586)
		(width 0.14478)
		(layer "In11.Cu")
		(net "M_L_CPU0_SB_DQ<3>")
	)
	(segment
		(start 409.312872 -282.630118)
		(end 409.312872 -282.399486)
		(width 0.14478)
		(layer "In11.Cu")
		(net "M_L_CPU0_SB_DQ<3>")
	)
	(segment
		(start 409.080208 -281.84475)
		(end 408.919172 -282.005786)
		(width 0.14478)
		(layer "In11.Cu")
		(net "M_L_CPU0_SB_DQ<3>")
	)
	(segment
		(start 407.899108 -280.66365)
		(end 407.899108 -280.433018)
		(width 0.14478)
		(layer "In11.Cu")
		(net "M_L_CPU0_SB_DQ<3>")
	)
	(segment
		(start 425.65701 -283.600652)
		(end 422.395904 -283.600652)
		(width 0.14478)
		(layer "In11.Cu")
		(net "M_L_CPU0_SB_DQ<3>")
	)
	(segment
		(start 408.686508 -281.220418)
		(end 408.52344 -281.05735)
		(width 0.14478)
		(layer "In11.Cu")
		(net "M_L_CPU0_SB_DQ<3>")
	)
	(arc
		(start 386.617718 -275.383498)
		(mid 386.370005 -275.458718)
		(end 386.114798 -275.415248)
		(width 0.0889)
		(layer "In11.Cu")
		(net "M_L_CPU0_SB_DQ<3>")
	)
	(arc
		(start 387.557772 -275.383498)
		(mid 387.274816 -275.459675)
		(end 386.99186 -275.383498)
		(width 0.0889)
		(layer "In11.Cu")
		(net "M_L_CPU0_SB_DQ<3>")
	)
	(arc
		(start 392.632438 -275.383498)
		(mid 392.44524 -275.333116)
		(end 392.258042 -275.383498)
		(width 0.0889)
		(layer "In11.Cu")
		(net "M_L_CPU0_SB_DQ<3>")
	)
	(arc
		(start 386.983478 -275.378672)
		(mid 386.79997 -275.333178)
		(end 386.617718 -275.383498)
		(width 0.0889)
		(layer "In11.Cu")
		(net "M_L_CPU0_SB_DQ<3>")
	)
	(arc
		(start 393.187682 -275.389594)
		(mid 392.90925 -275.459692)
		(end 392.632438 -275.383498)
		(width 0.0889)
		(layer "In11.Cu")
		(net "M_L_CPU0_SB_DQ<3>")
	)
	(arc
		(start 389.811768 -275.383498)
		(mid 389.624824 -275.333243)
		(end 389.43788 -275.383498)
		(width 0.0889)
		(layer "In11.Cu")
		(net "M_L_CPU0_SB_DQ<3>")
	)
	(arc
		(start 387.931914 -275.383498)
		(mid 387.749663 -275.333148)
		(end 387.566154 -275.378672)
		(width 0.0889)
		(layer "In11.Cu")
		(net "M_L_CPU0_SB_DQ<3>")
	)
	(arc
		(start 393.384786 -275.333206)
		(mid 393.288117 -275.346023)
		(end 393.198096 -275.383498)
		(width 0.0889)
		(layer "In11.Cu")
		(net "M_L_CPU0_SB_DQ<3>")
	)
	(arc
		(start 392.258042 -275.383498)
		(mid 391.980975 -275.459769)
		(end 391.70229 -275.389594)
		(width 0.0889)
		(layer "In11.Cu")
		(net "M_L_CPU0_SB_DQ<3>")
	)
	(arc
		(start 388.497826 -275.383498)
		(mid 388.21487 -275.459675)
		(end 387.931914 -275.383498)
		(width 0.0889)
		(layer "In11.Cu")
		(net "M_L_CPU0_SB_DQ<3>")
	)
	(arc
		(start 390.37768 -275.383498)
		(mid 390.094724 -275.459675)
		(end 389.811768 -275.383498)
		(width 0.0889)
		(layer "In11.Cu")
		(net "M_L_CPU0_SB_DQ<3>")
	)
	(arc
		(start 391.691876 -275.383498)
		(mid 391.509625 -275.333148)
		(end 391.326116 -275.378672)
		(width 0.0889)
		(layer "In11.Cu")
		(net "M_L_CPU0_SB_DQ<3>")
	)
	(arc
		(start 389.43788 -275.383498)
		(mid 389.154924 -275.459675)
		(end 388.871968 -275.383498)
		(width 0.0889)
		(layer "In11.Cu")
		(net "M_L_CPU0_SB_DQ<3>")
	)
	(arc
		(start 388.871968 -275.383498)
		(mid 388.689717 -275.333148)
		(end 388.506208 -275.378672)
		(width 0.0889)
		(layer "In11.Cu")
		(net "M_L_CPU0_SB_DQ<3>")
	)
	(arc
		(start 391.317734 -275.383498)
		(mid 391.034778 -275.459675)
		(end 390.751822 -275.383498)
		(width 0.0889)
		(layer "In11.Cu")
		(net "M_L_CPU0_SB_DQ<3>")
	)
	(arc
		(start 390.74344 -275.378672)
		(mid 390.559932 -275.333178)
		(end 390.37768 -275.383498)
		(width 0.0889)
		(layer "In11.Cu")
		(net "M_L_CPU0_SB_DQ<3>")
	)
	(segment
		(start 387.277864 -293.260018)
		(end 387.744716 -293.525956)
		(width 0.10668)
		(layer "F.Cu")
		(net "M_L_CPU0_SB_DQ<31>")
	)
	(segment
		(start 396.10284 -304.272696)
		(end 396.10284 -305.101244)
		(width 0.14478)
		(layer "In11.Cu")
		(net "M_L_CPU0_SB_DQ<31>")
	)
	(segment
		(start 444.193422 -319.483232)
		(end 444.338202 -319.338452)
		(width 0.14478)
		(layer "In11.Cu")
		(net "M_L_CPU0_SB_DQ<31>")
	)
	(segment
		(start 446.543938 -318.6049)
		(end 446.688718 -318.46012)
		(width 0.14478)
		(layer "In11.Cu")
		(net "M_L_CPU0_SB_DQ<31>")
	)
	(segment
		(start 447.240152 -319.483232)
		(end 447.502026 -319.483232)
		(width 0.14478)
		(layer "In11.Cu")
		(net "M_L_CPU0_SB_DQ<31>")
	)
	(segment
		(start 392.59256 -294.800528)
		(end 392.631676 -294.823388)
		(width 0.0889)
		(layer "In11.Cu")
		(net "M_L_CPU0_SB_DQ<31>")
	)
	(segment
		(start 446.399158 -319.483232)
		(end 446.543938 -319.338452)
		(width 0.14478)
		(layer "In11.Cu")
		(net "M_L_CPU0_SB_DQ<31>")
	)
	(segment
		(start 393.259056 -296.342054)
		(end 393.259056 -296.549318)
		(width 0.0889)
		(layer "In11.Cu")
		(net "M_L_CPU0_SB_DQ<31>")
	)
	(segment
		(start 447.646806 -318.6049)
		(end 447.791586 -318.46012)
		(width 0.14478)
		(layer "In11.Cu")
		(net "M_L_CPU0_SB_DQ<31>")
	)
	(segment
		(start 444.338202 -319.338452)
		(end 444.338202 -318.6049)
		(width 0.14478)
		(layer "In11.Cu")
		(net "M_L_CPU0_SB_DQ<31>")
	)
	(segment
		(start 393.88161 -302.880014)
		(end 394.710158 -302.880014)
		(width 0.14478)
		(layer "In11.Cu")
		(net "M_L_CPU0_SB_DQ<31>")
	)
	(segment
		(start 444.482982 -318.46012)
		(end 444.744856 -318.46012)
		(width 0.14478)
		(layer "In11.Cu")
		(net "M_L_CPU0_SB_DQ<31>")
	)
	(segment
		(start 445.992504 -318.6049)
		(end 445.992504 -319.338452)
		(width 0.14478)
		(layer "In11.Cu")
		(net "M_L_CPU0_SB_DQ<31>")
	)
	(segment
		(start 392.161776 -294.013382)
		(end 392.192256 -294.031162)
		(width 0.0889)
		(layer "In11.Cu")
		(net "M_L_CPU0_SB_DQ<31>")
	)
	(segment
		(start 445.44107 -319.338452)
		(end 445.44107 -318.6049)
		(width 0.14478)
		(layer "In11.Cu")
		(net "M_L_CPU0_SB_DQ<31>")
	)
	(segment
		(start 446.137284 -319.483232)
		(end 446.399158 -319.483232)
		(width 0.14478)
		(layer "In11.Cu")
		(net "M_L_CPU0_SB_DQ<31>")
	)
	(segment
		(start 445.29629 -319.483232)
		(end 445.44107 -319.338452)
		(width 0.14478)
		(layer "In11.Cu")
		(net "M_L_CPU0_SB_DQ<31>")
	)
	(segment
		(start 387.744716 -293.525956)
		(end 388.467346 -293.221156)
		(width 0.0889)
		(layer "In11.Cu")
		(net "M_L_CPU0_SB_DQ<31>")
	)
	(segment
		(start 396.10284 -305.101244)
		(end 397.54175 -306.540154)
		(width 0.14478)
		(layer "In11.Cu")
		(net "M_L_CPU0_SB_DQ<31>")
	)
	(segment
		(start 445.58585 -318.46012)
		(end 445.847724 -318.46012)
		(width 0.14478)
		(layer "In11.Cu")
		(net "M_L_CPU0_SB_DQ<31>")
	)
	(segment
		(start 446.950592 -318.46012)
		(end 447.095372 -318.6049)
		(width 0.14478)
		(layer "In11.Cu")
		(net "M_L_CPU0_SB_DQ<31>")
	)
	(segment
		(start 393.062714 -295.610534)
		(end 393.10183 -295.633394)
		(width 0.0889)
		(layer "In11.Cu")
		(net "M_L_CPU0_SB_DQ<31>")
	)
	(segment
		(start 443.641988 -318.46012)
		(end 443.786768 -318.6049)
		(width 0.14478)
		(layer "In11.Cu")
		(net "M_L_CPU0_SB_DQ<31>")
	)
	(segment
		(start 449.663058 -318.46012)
		(end 450.088 -318.035178)
		(width 0.14478)
		(layer "In11.Cu")
		(net "M_L_CPU0_SB_DQ<31>")
	)
	(segment
		(start 393.289282 -296.311828)
		(end 393.259056 -296.342054)
		(width 0.0889)
		(layer "In11.Cu")
		(net "M_L_CPU0_SB_DQ<31>")
	)
	(segment
		(start 446.688718 -318.46012)
		(end 446.950592 -318.46012)
		(width 0.14478)
		(layer "In11.Cu")
		(net "M_L_CPU0_SB_DQ<31>")
	)
	(segment
		(start 445.034416 -319.483232)
		(end 445.29629 -319.483232)
		(width 0.14478)
		(layer "In11.Cu")
		(net "M_L_CPU0_SB_DQ<31>")
	)
	(segment
		(start 388.497826 -293.203376)
		(end 388.506208 -293.19855)
		(width 0.0889)
		(layer "In11.Cu")
		(net "M_L_CPU0_SB_DQ<31>")
	)
	(segment
		(start 393.289282 -295.955974)
		(end 393.289282 -296.311828)
		(width 0.0889)
		(layer "In11.Cu")
		(net "M_L_CPU0_SB_DQ<31>")
	)
	(segment
		(start 445.44107 -318.6049)
		(end 445.58585 -318.46012)
		(width 0.14478)
		(layer "In11.Cu")
		(net "M_L_CPU0_SB_DQ<31>")
	)
	(segment
		(start 447.095372 -319.338452)
		(end 447.240152 -319.483232)
		(width 0.14478)
		(layer "In11.Cu")
		(net "M_L_CPU0_SB_DQ<31>")
	)
	(segment
		(start 444.338202 -318.6049)
		(end 444.482982 -318.46012)
		(width 0.14478)
		(layer "In11.Cu")
		(net "M_L_CPU0_SB_DQ<31>")
	)
	(segment
		(start 393.259056 -302.25746)
		(end 393.88161 -302.880014)
		(width 0.14478)
		(layer "In11.Cu")
		(net "M_L_CPU0_SB_DQ<31>")
	)
	(segment
		(start 393.10183 -295.633394)
		(end 393.131294 -295.650412)
		(width 0.0889)
		(layer "In11.Cu")
		(net "M_L_CPU0_SB_DQ<31>")
	)
	(segment
		(start 444.889636 -319.338452)
		(end 445.034416 -319.483232)
		(width 0.14478)
		(layer "In11.Cu")
		(net "M_L_CPU0_SB_DQ<31>")
	)
	(segment
		(start 443.786768 -319.338452)
		(end 443.931548 -319.483232)
		(width 0.14478)
		(layer "In11.Cu")
		(net "M_L_CPU0_SB_DQ<31>")
	)
	(segment
		(start 392.631676 -294.823388)
		(end 392.664442 -294.842438)
		(width 0.0889)
		(layer "In11.Cu")
		(net "M_L_CPU0_SB_DQ<31>")
	)
	(segment
		(start 446.543938 -319.338452)
		(end 446.543938 -318.6049)
		(width 0.14478)
		(layer "In11.Cu")
		(net "M_L_CPU0_SB_DQ<31>")
	)
	(segment
		(start 445.992504 -319.338452)
		(end 446.137284 -319.483232)
		(width 0.14478)
		(layer "In11.Cu")
		(net "M_L_CPU0_SB_DQ<31>")
	)
	(segment
		(start 398.398238 -306.540154)
		(end 409.880054 -318.02197)
		(width 0.14478)
		(layer "In11.Cu")
		(net "M_L_CPU0_SB_DQ<31>")
	)
	(segment
		(start 391.317734 -293.203376)
		(end 391.326116 -293.19855)
		(width 0.0889)
		(layer "In11.Cu")
		(net "M_L_CPU0_SB_DQ<31>")
	)
	(segment
		(start 447.502026 -319.483232)
		(end 447.646806 -319.338452)
		(width 0.14478)
		(layer "In11.Cu")
		(net "M_L_CPU0_SB_DQ<31>")
	)
	(segment
		(start 392.12266 -293.990522)
		(end 392.161776 -294.013382)
		(width 0.0889)
		(layer "In11.Cu")
		(net "M_L_CPU0_SB_DQ<31>")
	)
	(segment
		(start 445.847724 -318.46012)
		(end 445.992504 -318.6049)
		(width 0.14478)
		(layer "In11.Cu")
		(net "M_L_CPU0_SB_DQ<31>")
	)
	(segment
		(start 443.931548 -319.483232)
		(end 444.193422 -319.483232)
		(width 0.14478)
		(layer "In11.Cu")
		(net "M_L_CPU0_SB_DQ<31>")
	)
	(segment
		(start 390.74344 -293.19855)
		(end 390.751822 -293.203376)
		(width 0.0889)
		(layer "In11.Cu")
		(net "M_L_CPU0_SB_DQ<31>")
	)
	(segment
		(start 444.889636 -318.6049)
		(end 444.889636 -319.338452)
		(width 0.14478)
		(layer "In11.Cu")
		(net "M_L_CPU0_SB_DQ<31>")
	)
	(segment
		(start 444.744856 -318.46012)
		(end 444.889636 -318.6049)
		(width 0.14478)
		(layer "In11.Cu")
		(net "M_L_CPU0_SB_DQ<31>")
	)
	(segment
		(start 388.467346 -293.221156)
		(end 388.497826 -293.203376)
		(width 0.0889)
		(layer "In11.Cu")
		(net "M_L_CPU0_SB_DQ<31>")
	)
	(segment
		(start 397.54175 -306.540154)
		(end 398.398238 -306.540154)
		(width 0.14478)
		(layer "In11.Cu")
		(net "M_L_CPU0_SB_DQ<31>")
	)
	(segment
		(start 447.095372 -318.6049)
		(end 447.095372 -319.338452)
		(width 0.14478)
		(layer "In11.Cu")
		(net "M_L_CPU0_SB_DQ<31>")
	)
	(segment
		(start 410.93771 -318.46012)
		(end 443.641988 -318.46012)
		(width 0.14478)
		(layer "In11.Cu")
		(net "M_L_CPU0_SB_DQ<31>")
	)
	(segment
		(start 394.710158 -302.880014)
		(end 396.10284 -304.272696)
		(width 0.14478)
		(layer "In11.Cu")
		(net "M_L_CPU0_SB_DQ<31>")
	)
	(segment
		(start 447.791586 -318.46012)
		(end 449.663058 -318.46012)
		(width 0.14478)
		(layer "In11.Cu")
		(net "M_L_CPU0_SB_DQ<31>")
	)
	(segment
		(start 391.691876 -293.203376)
		(end 391.722356 -293.221156)
		(width 0.0889)
		(layer "In11.Cu")
		(net "M_L_CPU0_SB_DQ<31>")
	)
	(segment
		(start 447.646806 -319.338452)
		(end 447.646806 -318.6049)
		(width 0.14478)
		(layer "In11.Cu")
		(net "M_L_CPU0_SB_DQ<31>")
	)
	(segment
		(start 443.786768 -318.6049)
		(end 443.786768 -319.338452)
		(width 0.14478)
		(layer "In11.Cu")
		(net "M_L_CPU0_SB_DQ<31>")
	)
	(segment
		(start 393.259056 -296.549318)
		(end 393.259056 -302.25746)
		(width 0.14478)
		(layer "In11.Cu")
		(net "M_L_CPU0_SB_DQ<31>")
	)
	(segment
		(start 409.880054 -318.02197)
		(end 410.93771 -318.46012)
		(width 0.14478)
		(layer "In11.Cu")
		(net "M_L_CPU0_SB_DQ<31>")
	)
	(arc
		(start 391.722356 -293.221156)
		(mid 391.837783 -293.354532)
		(end 391.879328 -293.525956)
		(width 0.0889)
		(layer "In11.Cu")
		(net "M_L_CPU0_SB_DQ<31>")
	)
	(arc
		(start 392.192256 -294.031162)
		(mid 392.307683 -294.164538)
		(end 392.349228 -294.335962)
		(width 0.0889)
		(layer "In11.Cu")
		(net "M_L_CPU0_SB_DQ<31>")
	)
	(arc
		(start 392.664442 -294.842438)
		(mid 392.778371 -294.975585)
		(end 392.819382 -295.145968)
		(width 0.0889)
		(layer "In11.Cu")
		(net "M_L_CPU0_SB_DQ<31>")
	)
	(arc
		(start 389.43788 -293.203376)
		(mid 389.624824 -293.153121)
		(end 389.811768 -293.203376)
		(width 0.0889)
		(layer "In11.Cu")
		(net "M_L_CPU0_SB_DQ<31>")
	)
	(arc
		(start 389.811768 -293.203376)
		(mid 390.094724 -293.279553)
		(end 390.37768 -293.203376)
		(width 0.0889)
		(layer "In11.Cu")
		(net "M_L_CPU0_SB_DQ<31>")
	)
	(arc
		(start 390.751822 -293.203376)
		(mid 391.034778 -293.279553)
		(end 391.317734 -293.203376)
		(width 0.0889)
		(layer "In11.Cu")
		(net "M_L_CPU0_SB_DQ<31>")
	)
	(arc
		(start 390.37768 -293.203376)
		(mid 390.559931 -293.153026)
		(end 390.74344 -293.19855)
		(width 0.0889)
		(layer "In11.Cu")
		(net "M_L_CPU0_SB_DQ<31>")
	)
	(arc
		(start 392.819382 -295.145968)
		(mid 392.883897 -295.408187)
		(end 393.062714 -295.610534)
		(width 0.0889)
		(layer "In11.Cu")
		(net "M_L_CPU0_SB_DQ<31>")
	)
	(arc
		(start 391.879328 -293.525956)
		(mid 391.943843 -293.788175)
		(end 392.12266 -293.990522)
		(width 0.0889)
		(layer "In11.Cu")
		(net "M_L_CPU0_SB_DQ<31>")
	)
	(arc
		(start 388.871968 -293.203376)
		(mid 389.154924 -293.279553)
		(end 389.43788 -293.203376)
		(width 0.0889)
		(layer "In11.Cu")
		(net "M_L_CPU0_SB_DQ<31>")
	)
	(arc
		(start 391.326116 -293.19855)
		(mid 391.509624 -293.153056)
		(end 391.691876 -293.203376)
		(width 0.0889)
		(layer "In11.Cu")
		(net "M_L_CPU0_SB_DQ<31>")
	)
	(arc
		(start 392.349228 -294.335962)
		(mid 392.413743 -294.598181)
		(end 392.59256 -294.800528)
		(width 0.0889)
		(layer "In11.Cu")
		(net "M_L_CPU0_SB_DQ<31>")
	)
	(arc
		(start 393.131294 -295.650412)
		(mid 393.247475 -295.783971)
		(end 393.289282 -295.955974)
		(width 0.0889)
		(layer "In11.Cu")
		(net "M_L_CPU0_SB_DQ<31>")
	)
	(arc
		(start 388.506208 -293.19855)
		(mid 388.689716 -293.153056)
		(end 388.871968 -293.203376)
		(width 0.0889)
		(layer "In11.Cu")
		(net "M_L_CPU0_SB_DQ<31>")
	)
	(segment
		(start 386.807964 -292.450012)
		(end 387.274816 -292.71595)
		(width 0.10668)
		(layer "F.Cu")
		(net "M_L_CPU0_SB_DQ<30>")
	)
	(segment
		(start 448.887088 -316.970664)
		(end 449.031868 -317.115444)
		(width 0.14478)
		(layer "In11.Cu")
		(net "M_L_CPU0_SB_DQ<30>")
	)
	(segment
		(start 394.168376 -296.450766)
		(end 394.168376 -300.922182)
		(width 0.14478)
		(layer "In11.Cu")
		(net "M_L_CPU0_SB_DQ<30>")
	)
	(segment
		(start 447.088006 -316.760098)
		(end 447.232786 -316.615318)
		(width 0.14478)
		(layer "In11.Cu")
		(net "M_L_CPU0_SB_DQ<30>")
	)
	(segment
		(start 392.592814 -293.180516)
		(end 392.63193 -293.203376)
		(width 0.0889)
		(layer "In11.Cu")
		(net "M_L_CPU0_SB_DQ<30>")
	)
	(segment
		(start 448.335654 -316.970664)
		(end 448.335654 -316.549532)
		(width 0.14478)
		(layer "In11.Cu")
		(net "M_L_CPU0_SB_DQ<30>")
	)
	(segment
		(start 394.168376 -300.922182)
		(end 410.006292 -316.760098)
		(width 0.14478)
		(layer "In11.Cu")
		(net "M_L_CPU0_SB_DQ<30>")
	)
	(segment
		(start 444.734188 -317.006224)
		(end 444.878968 -317.151004)
		(width 0.14478)
		(layer "In11.Cu")
		(net "M_L_CPU0_SB_DQ<30>")
	)
	(segment
		(start 447.78422 -316.970664)
		(end 447.929 -317.115444)
		(width 0.14478)
		(layer "In11.Cu")
		(net "M_L_CPU0_SB_DQ<30>")
	)
	(segment
		(start 449.663058 -316.760098)
		(end 450.088 -316.335156)
		(width 0.14478)
		(layer "In11.Cu")
		(net "M_L_CPU0_SB_DQ<30>")
	)
	(segment
		(start 444.589408 -316.369192)
		(end 444.734188 -316.513972)
		(width 0.14478)
		(layer "In11.Cu")
		(net "M_L_CPU0_SB_DQ<30>")
	)
	(segment
		(start 444.327534 -316.369192)
		(end 444.589408 -316.369192)
		(width 0.14478)
		(layer "In11.Cu")
		(net "M_L_CPU0_SB_DQ<30>")
	)
	(segment
		(start 448.480434 -316.404752)
		(end 448.742308 -316.404752)
		(width 0.14478)
		(layer "In11.Cu")
		(net "M_L_CPU0_SB_DQ<30>")
	)
	(segment
		(start 441.838842 -316.615318)
		(end 441.983622 -316.760098)
		(width 0.14478)
		(layer "In11.Cu")
		(net "M_L_CPU0_SB_DQ<30>")
	)
	(segment
		(start 391.974832 -292.342824)
		(end 392.075416 -292.342824)
		(width 0.0889)
		(layer "In11.Cu")
		(net "M_L_CPU0_SB_DQ<30>")
	)
	(segment
		(start 445.837056 -316.615318)
		(end 445.981836 -316.760098)
		(width 0.14478)
		(layer "In11.Cu")
		(net "M_L_CPU0_SB_DQ<30>")
	)
	(segment
		(start 441.432188 -316.369192)
		(end 441.694062 -316.369192)
		(width 0.14478)
		(layer "In11.Cu")
		(net "M_L_CPU0_SB_DQ<30>")
	)
	(segment
		(start 444.878968 -317.151004)
		(end 445.140842 -317.151004)
		(width 0.14478)
		(layer "In11.Cu")
		(net "M_L_CPU0_SB_DQ<30>")
	)
	(segment
		(start 445.981836 -316.760098)
		(end 447.088006 -316.760098)
		(width 0.14478)
		(layer "In11.Cu")
		(net "M_L_CPU0_SB_DQ<30>")
	)
	(segment
		(start 439.488326 -316.760098)
		(end 439.633106 -316.904878)
		(width 0.14478)
		(layer "In11.Cu")
		(net "M_L_CPU0_SB_DQ<30>")
	)
	(segment
		(start 389.333486 -292.388544)
		(end 389.341868 -292.39337)
		(width 0.0889)
		(layer "In11.Cu")
		(net "M_L_CPU0_SB_DQ<30>")
	)
	(segment
		(start 441.983622 -316.760098)
		(end 442.935106 -316.760098)
		(width 0.14478)
		(layer "In11.Cu")
		(net "M_L_CPU0_SB_DQ<30>")
	)
	(segment
		(start 441.694062 -316.369192)
		(end 441.838842 -316.513972)
		(width 0.14478)
		(layer "In11.Cu")
		(net "M_L_CPU0_SB_DQ<30>")
	)
	(segment
		(start 387.274816 -292.71595)
		(end 387.42874 -292.45052)
		(width 0.0889)
		(layer "In11.Cu")
		(net "M_L_CPU0_SB_DQ<30>")
	)
	(segment
		(start 439.633106 -316.904878)
		(end 439.633106 -317.006224)
		(width 0.14478)
		(layer "In11.Cu")
		(net "M_L_CPU0_SB_DQ<30>")
	)
	(segment
		(start 394.168376 -295.406572)
		(end 394.168376 -296.450766)
		(width 0.0889)
		(layer "In11.Cu")
		(net "M_L_CPU0_SB_DQ<30>")
	)
	(segment
		(start 447.377566 -316.404752)
		(end 447.63944 -316.404752)
		(width 0.14478)
		(layer "In11.Cu")
		(net "M_L_CPU0_SB_DQ<30>")
	)
	(segment
		(start 447.63944 -316.404752)
		(end 447.78422 -316.549532)
		(width 0.14478)
		(layer "In11.Cu")
		(net "M_L_CPU0_SB_DQ<30>")
	)
	(segment
		(start 440.18454 -317.006224)
		(end 440.18454 -316.513972)
		(width 0.14478)
		(layer "In11.Cu")
		(net "M_L_CPU0_SB_DQ<30>")
	)
	(segment
		(start 443.7761 -317.151004)
		(end 444.037974 -317.151004)
		(width 0.14478)
		(layer "In11.Cu")
		(net "M_L_CPU0_SB_DQ<30>")
	)
	(segment
		(start 447.232786 -316.615318)
		(end 447.232786 -316.549532)
		(width 0.14478)
		(layer "In11.Cu")
		(net "M_L_CPU0_SB_DQ<30>")
	)
	(segment
		(start 445.692276 -316.369192)
		(end 445.837056 -316.513972)
		(width 0.14478)
		(layer "In11.Cu")
		(net "M_L_CPU0_SB_DQ<30>")
	)
	(segment
		(start 448.190874 -317.115444)
		(end 448.335654 -316.970664)
		(width 0.14478)
		(layer "In11.Cu")
		(net "M_L_CPU0_SB_DQ<30>")
	)
	(segment
		(start 393.60348 -294.841676)
		(end 394.168376 -295.406572)
		(width 0.0889)
		(layer "In11.Cu")
		(net "M_L_CPU0_SB_DQ<30>")
	)
	(segment
		(start 449.583302 -316.760098)
		(end 449.663058 -316.760098)
		(width 0.14478)
		(layer "In11.Cu")
		(net "M_L_CPU0_SB_DQ<30>")
	)
	(segment
		(start 393.062714 -293.990522)
		(end 393.10183 -294.013382)
		(width 0.0889)
		(layer "In11.Cu")
		(net "M_L_CPU0_SB_DQ<30>")
	)
	(segment
		(start 443.079886 -316.513972)
		(end 443.224666 -316.369192)
		(width 0.14478)
		(layer "In11.Cu")
		(net "M_L_CPU0_SB_DQ<30>")
	)
	(segment
		(start 444.182754 -316.513972)
		(end 444.327534 -316.369192)
		(width 0.14478)
		(layer "In11.Cu")
		(net "M_L_CPU0_SB_DQ<30>")
	)
	(segment
		(start 445.285622 -317.006224)
		(end 445.285622 -316.513972)
		(width 0.14478)
		(layer "In11.Cu")
		(net "M_L_CPU0_SB_DQ<30>")
	)
	(segment
		(start 440.32932 -316.369192)
		(end 440.591194 -316.369192)
		(width 0.14478)
		(layer "In11.Cu")
		(net "M_L_CPU0_SB_DQ<30>")
	)
	(segment
		(start 392.63193 -293.203376)
		(end 392.66241 -293.221156)
		(width 0.0889)
		(layer "In11.Cu")
		(net "M_L_CPU0_SB_DQ<30>")
	)
	(segment
		(start 440.591194 -316.369192)
		(end 440.735974 -316.513972)
		(width 0.14478)
		(layer "In11.Cu")
		(net "M_L_CPU0_SB_DQ<30>")
	)
	(segment
		(start 442.935106 -316.760098)
		(end 443.079886 -316.615318)
		(width 0.14478)
		(layer "In11.Cu")
		(net "M_L_CPU0_SB_DQ<30>")
	)
	(segment
		(start 389.90778 -292.39337)
		(end 389.916162 -292.388544)
		(width 0.0889)
		(layer "In11.Cu")
		(net "M_L_CPU0_SB_DQ<30>")
	)
	(segment
		(start 444.734188 -316.513972)
		(end 444.734188 -317.006224)
		(width 0.14478)
		(layer "In11.Cu")
		(net "M_L_CPU0_SB_DQ<30>")
	)
	(segment
		(start 448.742308 -316.404752)
		(end 448.887088 -316.549532)
		(width 0.14478)
		(layer "In11.Cu")
		(net "M_L_CPU0_SB_DQ<30>")
	)
	(segment
		(start 440.880754 -317.151004)
		(end 441.142628 -317.151004)
		(width 0.14478)
		(layer "In11.Cu")
		(net "M_L_CPU0_SB_DQ<30>")
	)
	(segment
		(start 393.10183 -294.013382)
		(end 393.13231 -294.031162)
		(width 0.0889)
		(layer "In11.Cu")
		(net "M_L_CPU0_SB_DQ<30>")
	)
	(segment
		(start 393.532614 -294.800528)
		(end 393.57173 -294.823388)
		(width 0.0889)
		(layer "In11.Cu")
		(net "M_L_CPU0_SB_DQ<30>")
	)
	(segment
		(start 445.430402 -316.369192)
		(end 445.692276 -316.369192)
		(width 0.14478)
		(layer "In11.Cu")
		(net "M_L_CPU0_SB_DQ<30>")
	)
	(segment
		(start 393.57173 -294.823388)
		(end 393.60348 -294.841676)
		(width 0.0889)
		(layer "In11.Cu")
		(net "M_L_CPU0_SB_DQ<30>")
	)
	(segment
		(start 410.006292 -316.760098)
		(end 439.488326 -316.760098)
		(width 0.14478)
		(layer "In11.Cu")
		(net "M_L_CPU0_SB_DQ<30>")
	)
	(segment
		(start 445.837056 -316.513972)
		(end 445.837056 -316.615318)
		(width 0.14478)
		(layer "In11.Cu")
		(net "M_L_CPU0_SB_DQ<30>")
	)
	(segment
		(start 388.393432 -292.388544)
		(end 388.401814 -292.39337)
		(width 0.0889)
		(layer "In11.Cu")
		(net "M_L_CPU0_SB_DQ<30>")
	)
	(segment
		(start 448.335654 -316.549532)
		(end 448.480434 -316.404752)
		(width 0.14478)
		(layer "In11.Cu")
		(net "M_L_CPU0_SB_DQ<30>")
	)
	(segment
		(start 441.838842 -316.513972)
		(end 441.838842 -316.615318)
		(width 0.14478)
		(layer "In11.Cu")
		(net "M_L_CPU0_SB_DQ<30>")
	)
	(segment
		(start 443.224666 -316.369192)
		(end 443.48654 -316.369192)
		(width 0.14478)
		(layer "In11.Cu")
		(net "M_L_CPU0_SB_DQ<30>")
	)
	(segment
		(start 392.16203 -292.39337)
		(end 392.19251 -292.41115)
		(width 0.0889)
		(layer "In11.Cu")
		(net "M_L_CPU0_SB_DQ<30>")
	)
	(segment
		(start 448.887088 -316.549532)
		(end 448.887088 -316.970664)
		(width 0.14478)
		(layer "In11.Cu")
		(net "M_L_CPU0_SB_DQ<30>")
	)
	(segment
		(start 440.735974 -316.513972)
		(end 440.735974 -317.006224)
		(width 0.14478)
		(layer "In11.Cu")
		(net "M_L_CPU0_SB_DQ<30>")
	)
	(segment
		(start 392.075416 -292.342824)
		(end 392.16203 -292.39337)
		(width 0.0889)
		(layer "In11.Cu")
		(net "M_L_CPU0_SB_DQ<30>")
	)
	(segment
		(start 449.293742 -317.115444)
		(end 449.438522 -316.970664)
		(width 0.14478)
		(layer "In11.Cu")
		(net "M_L_CPU0_SB_DQ<30>")
	)
	(segment
		(start 441.287408 -317.006224)
		(end 441.287408 -316.513972)
		(width 0.14478)
		(layer "In11.Cu")
		(net "M_L_CPU0_SB_DQ<30>")
	)
	(segment
		(start 439.777886 -317.151004)
		(end 440.03976 -317.151004)
		(width 0.14478)
		(layer "In11.Cu")
		(net "M_L_CPU0_SB_DQ<30>")
	)
	(segment
		(start 443.63132 -317.006224)
		(end 443.7761 -317.151004)
		(width 0.14478)
		(layer "In11.Cu")
		(net "M_L_CPU0_SB_DQ<30>")
	)
	(segment
		(start 387.42874 -292.45052)
		(end 387.524752 -292.42512)
		(width 0.0889)
		(layer "In11.Cu")
		(net "M_L_CPU0_SB_DQ<30>")
	)
	(segment
		(start 445.140842 -317.151004)
		(end 445.285622 -317.006224)
		(width 0.14478)
		(layer "In11.Cu")
		(net "M_L_CPU0_SB_DQ<30>")
	)
	(segment
		(start 440.03976 -317.151004)
		(end 440.18454 -317.006224)
		(width 0.14478)
		(layer "In11.Cu")
		(net "M_L_CPU0_SB_DQ<30>")
	)
	(segment
		(start 445.285622 -316.513972)
		(end 445.430402 -316.369192)
		(width 0.14478)
		(layer "In11.Cu")
		(net "M_L_CPU0_SB_DQ<30>")
	)
	(segment
		(start 443.48654 -316.369192)
		(end 443.63132 -316.513972)
		(width 0.14478)
		(layer "In11.Cu")
		(net "M_L_CPU0_SB_DQ<30>")
	)
	(segment
		(start 449.438522 -316.904878)
		(end 449.583302 -316.760098)
		(width 0.14478)
		(layer "In11.Cu")
		(net "M_L_CPU0_SB_DQ<30>")
	)
	(segment
		(start 447.78422 -316.549532)
		(end 447.78422 -316.970664)
		(width 0.14478)
		(layer "In11.Cu")
		(net "M_L_CPU0_SB_DQ<30>")
	)
	(segment
		(start 449.438522 -316.970664)
		(end 449.438522 -316.904878)
		(width 0.14478)
		(layer "In11.Cu")
		(net "M_L_CPU0_SB_DQ<30>")
	)
	(segment
		(start 441.142628 -317.151004)
		(end 441.287408 -317.006224)
		(width 0.14478)
		(layer "In11.Cu")
		(net "M_L_CPU0_SB_DQ<30>")
	)
	(segment
		(start 447.929 -317.115444)
		(end 448.190874 -317.115444)
		(width 0.14478)
		(layer "In11.Cu")
		(net "M_L_CPU0_SB_DQ<30>")
	)
	(segment
		(start 441.287408 -316.513972)
		(end 441.432188 -316.369192)
		(width 0.14478)
		(layer "In11.Cu")
		(net "M_L_CPU0_SB_DQ<30>")
	)
	(segment
		(start 440.18454 -316.513972)
		(end 440.32932 -316.369192)
		(width 0.14478)
		(layer "In11.Cu")
		(net "M_L_CPU0_SB_DQ<30>")
	)
	(segment
		(start 444.182754 -317.006224)
		(end 444.182754 -316.513972)
		(width 0.14478)
		(layer "In11.Cu")
		(net "M_L_CPU0_SB_DQ<30>")
	)
	(segment
		(start 449.031868 -317.115444)
		(end 449.293742 -317.115444)
		(width 0.14478)
		(layer "In11.Cu")
		(net "M_L_CPU0_SB_DQ<30>")
	)
	(segment
		(start 440.735974 -317.006224)
		(end 440.880754 -317.151004)
		(width 0.14478)
		(layer "In11.Cu")
		(net "M_L_CPU0_SB_DQ<30>")
	)
	(segment
		(start 443.079886 -316.615318)
		(end 443.079886 -316.513972)
		(width 0.14478)
		(layer "In11.Cu")
		(net "M_L_CPU0_SB_DQ<30>")
	)
	(segment
		(start 444.037974 -317.151004)
		(end 444.182754 -317.006224)
		(width 0.14478)
		(layer "In11.Cu")
		(net "M_L_CPU0_SB_DQ<30>")
	)
	(segment
		(start 439.633106 -317.006224)
		(end 439.777886 -317.151004)
		(width 0.14478)
		(layer "In11.Cu")
		(net "M_L_CPU0_SB_DQ<30>")
	)
	(segment
		(start 447.232786 -316.549532)
		(end 447.377566 -316.404752)
		(width 0.14478)
		(layer "In11.Cu")
		(net "M_L_CPU0_SB_DQ<30>")
	)
	(segment
		(start 443.63132 -316.513972)
		(end 443.63132 -317.006224)
		(width 0.14478)
		(layer "In11.Cu")
		(net "M_L_CPU0_SB_DQ<30>")
	)
	(arc
		(start 393.289282 -294.335962)
		(mid 393.353797 -294.598181)
		(end 393.532614 -294.800528)
		(width 0.0889)
		(layer "In11.Cu")
		(net "M_L_CPU0_SB_DQ<30>")
	)
	(arc
		(start 392.66241 -293.221156)
		(mid 392.777837 -293.354532)
		(end 392.819382 -293.525956)
		(width 0.0889)
		(layer "In11.Cu")
		(net "M_L_CPU0_SB_DQ<30>")
	)
	(arc
		(start 388.967726 -292.39337)
		(mid 389.149977 -292.34302)
		(end 389.333486 -292.388544)
		(width 0.0889)
		(layer "In11.Cu")
		(net "M_L_CPU0_SB_DQ<30>")
	)
	(arc
		(start 392.19251 -292.41115)
		(mid 392.307937 -292.544526)
		(end 392.349482 -292.71595)
		(width 0.0889)
		(layer "In11.Cu")
		(net "M_L_CPU0_SB_DQ<30>")
	)
	(arc
		(start 387.524752 -292.42512)
		(mid 387.77996 -292.468597)
		(end 388.027672 -292.39337)
		(width 0.0889)
		(layer "In11.Cu")
		(net "M_L_CPU0_SB_DQ<30>")
	)
	(arc
		(start 388.401814 -292.39337)
		(mid 388.68477 -292.469547)
		(end 388.967726 -292.39337)
		(width 0.0889)
		(layer "In11.Cu")
		(net "M_L_CPU0_SB_DQ<30>")
	)
	(arc
		(start 389.916162 -292.388544)
		(mid 390.09967 -292.34305)
		(end 390.281922 -292.39337)
		(width 0.0889)
		(layer "In11.Cu")
		(net "M_L_CPU0_SB_DQ<30>")
	)
	(arc
		(start 391.787634 -292.39337)
		(mid 391.877894 -292.355742)
		(end 391.974832 -292.342824)
		(width 0.0889)
		(layer "In11.Cu")
		(net "M_L_CPU0_SB_DQ<30>")
	)
	(arc
		(start 390.281922 -292.39337)
		(mid 390.564878 -292.469547)
		(end 390.847834 -292.39337)
		(width 0.0889)
		(layer "In11.Cu")
		(net "M_L_CPU0_SB_DQ<30>")
	)
	(arc
		(start 393.13231 -294.031162)
		(mid 393.247737 -294.164538)
		(end 393.289282 -294.335962)
		(width 0.0889)
		(layer "In11.Cu")
		(net "M_L_CPU0_SB_DQ<30>")
	)
	(arc
		(start 392.349482 -292.71595)
		(mid 392.413997 -292.978169)
		(end 392.592814 -293.180516)
		(width 0.0889)
		(layer "In11.Cu")
		(net "M_L_CPU0_SB_DQ<30>")
	)
	(arc
		(start 392.819382 -293.525956)
		(mid 392.883897 -293.788175)
		(end 393.062714 -293.990522)
		(width 0.0889)
		(layer "In11.Cu")
		(net "M_L_CPU0_SB_DQ<30>")
	)
	(arc
		(start 391.221722 -292.39337)
		(mid 391.504678 -292.469547)
		(end 391.787634 -292.39337)
		(width 0.0889)
		(layer "In11.Cu")
		(net "M_L_CPU0_SB_DQ<30>")
	)
	(arc
		(start 388.027672 -292.39337)
		(mid 388.209923 -292.34302)
		(end 388.393432 -292.388544)
		(width 0.0889)
		(layer "In11.Cu")
		(net "M_L_CPU0_SB_DQ<30>")
	)
	(arc
		(start 389.341868 -292.39337)
		(mid 389.624824 -292.469547)
		(end 389.90778 -292.39337)
		(width 0.0889)
		(layer "In11.Cu")
		(net "M_L_CPU0_SB_DQ<30>")
	)
	(arc
		(start 390.847834 -292.39337)
		(mid 391.034778 -292.343115)
		(end 391.221722 -292.39337)
		(width 0.0889)
		(layer "In11.Cu")
		(net "M_L_CPU0_SB_DQ<30>")
	)
	(segment
		(start 386.807964 -274.630134)
		(end 387.274816 -274.896072)
		(width 0.10668)
		(layer "F.Cu")
		(net "M_L_CPU0_SB_DQ<2>")
	)
	(segment
		(start 403.414992 -275.210016)
		(end 403.591268 -275.03374)
		(width 0.14478)
		(layer "In11.Cu")
		(net "M_L_CPU0_SB_DQ<2>")
	)
	(segment
		(start 422.484042 -281.910028)
		(end 425.666408 -281.910028)
		(width 0.14478)
		(layer "In11.Cu")
		(net "M_L_CPU0_SB_DQ<2>")
	)
	(segment
		(start 406.1841 -277.39594)
		(end 406.347168 -277.559008)
		(width 0.14478)
		(layer "In11.Cu")
		(net "M_L_CPU0_SB_DQ<2>")
	)
	(segment
		(start 418.972492 -282.760166)
		(end 421.633904 -282.760166)
		(width 0.14478)
		(layer "In11.Cu")
		(net "M_L_CPU0_SB_DQ<2>")
	)
	(segment
		(start 404.75916 -276.784816)
		(end 404.989792 -276.784816)
		(width 0.14478)
		(layer "In11.Cu")
		(net "M_L_CPU0_SB_DQ<2>")
	)
	(segment
		(start 388.393432 -274.568666)
		(end 388.401814 -274.573492)
		(width 0.0889)
		(layer "In11.Cu")
		(net "M_L_CPU0_SB_DQ<2>")
	)
	(segment
		(start 403.97176 -275.997416)
		(end 404.202392 -275.997416)
		(width 0.14478)
		(layer "In11.Cu")
		(net "M_L_CPU0_SB_DQ<2>")
	)
	(segment
		(start 392.145266 -274.564348)
		(end 392.161522 -274.573746)
		(width 0.0889)
		(layer "In11.Cu")
		(net "M_L_CPU0_SB_DQ<2>")
	)
	(segment
		(start 449.663058 -281.910028)
		(end 450.088 -282.33497)
		(width 0.14478)
		(layer "In11.Cu")
		(net "M_L_CPU0_SB_DQ<2>")
	)
	(segment
		(start 406.958292 -278.983948)
		(end 407.12136 -279.147016)
		(width 0.14478)
		(layer "In11.Cu")
		(net "M_L_CPU0_SB_DQ<2>")
	)
	(segment
		(start 414.91408 -281.910028)
		(end 415.746692 -281.910028)
		(width 0.14478)
		(layer "In11.Cu")
		(net "M_L_CPU0_SB_DQ<2>")
	)
	(segment
		(start 402.627592 -274.422616)
		(end 402.803868 -274.24634)
		(width 0.14478)
		(layer "In11.Cu")
		(net "M_L_CPU0_SB_DQ<2>")
	)
	(segment
		(start 405.166068 -276.60854)
		(end 405.3967 -276.60854)
		(width 0.14478)
		(layer "In11.Cu")
		(net "M_L_CPU0_SB_DQ<2>")
	)
	(segment
		(start 389.90778 -274.573492)
		(end 389.916162 -274.568666)
		(width 0.0889)
		(layer "In11.Cu")
		(net "M_L_CPU0_SB_DQ<2>")
	)
	(segment
		(start 404.989792 -276.784816)
		(end 405.166068 -276.60854)
		(width 0.14478)
		(layer "In11.Cu")
		(net "M_L_CPU0_SB_DQ<2>")
	)
	(segment
		(start 436.722012 -282.760166)
		(end 437.57215 -281.910028)
		(width 0.14478)
		(layer "In11.Cu")
		(net "M_L_CPU0_SB_DQ<2>")
	)
	(segment
		(start 406.33396 -278.359616)
		(end 406.564592 -278.359616)
		(width 0.14478)
		(layer "In11.Cu")
		(net "M_L_CPU0_SB_DQ<2>")
	)
	(segment
		(start 406.170892 -278.196548)
		(end 406.33396 -278.359616)
		(width 0.14478)
		(layer "In11.Cu")
		(net "M_L_CPU0_SB_DQ<2>")
	)
	(segment
		(start 402.410168 -273.622008)
		(end 402.410168 -273.85264)
		(width 0.14478)
		(layer "In11.Cu")
		(net "M_L_CPU0_SB_DQ<2>")
	)
	(segment
		(start 407.134568 -278.346408)
		(end 407.134568 -278.57704)
		(width 0.14478)
		(layer "In11.Cu")
		(net "M_L_CPU0_SB_DQ<2>")
	)
	(segment
		(start 405.383492 -277.178516)
		(end 405.383492 -277.409148)
		(width 0.14478)
		(layer "In11.Cu")
		(net "M_L_CPU0_SB_DQ<2>")
	)
	(segment
		(start 404.6093 -275.82114)
		(end 404.772368 -275.984208)
		(width 0.14478)
		(layer "In11.Cu")
		(net "M_L_CPU0_SB_DQ<2>")
	)
	(segment
		(start 403.8219 -275.03374)
		(end 403.984968 -275.196808)
		(width 0.14478)
		(layer "In11.Cu")
		(net "M_L_CPU0_SB_DQ<2>")
	)
	(segment
		(start 402.18233 -273.39417)
		(end 402.410168 -273.622008)
		(width 0.14478)
		(layer "In11.Cu")
		(net "M_L_CPU0_SB_DQ<2>")
	)
	(segment
		(start 406.958292 -278.753316)
		(end 406.958292 -278.983948)
		(width 0.14478)
		(layer "In11.Cu")
		(net "M_L_CPU0_SB_DQ<2>")
	)
	(segment
		(start 406.9715 -278.18334)
		(end 407.134568 -278.346408)
		(width 0.14478)
		(layer "In11.Cu")
		(net "M_L_CPU0_SB_DQ<2>")
	)
	(segment
		(start 407.12136 -279.147016)
		(end 407.351992 -279.147016)
		(width 0.14478)
		(layer "In11.Cu")
		(net "M_L_CPU0_SB_DQ<2>")
	)
	(segment
		(start 404.378668 -275.82114)
		(end 404.6093 -275.82114)
		(width 0.14478)
		(layer "In11.Cu")
		(net "M_L_CPU0_SB_DQ<2>")
	)
	(segment
		(start 402.39696 -274.422616)
		(end 402.627592 -274.422616)
		(width 0.14478)
		(layer "In11.Cu")
		(net "M_L_CPU0_SB_DQ<2>")
	)
	(segment
		(start 405.777192 -277.572216)
		(end 405.953468 -277.39594)
		(width 0.14478)
		(layer "In11.Cu")
		(net "M_L_CPU0_SB_DQ<2>")
	)
	(segment
		(start 418.122354 -281.910028)
		(end 418.972492 -282.760166)
		(width 0.14478)
		(layer "In11.Cu")
		(net "M_L_CPU0_SB_DQ<2>")
	)
	(segment
		(start 404.596092 -276.621748)
		(end 404.75916 -276.784816)
		(width 0.14478)
		(layer "In11.Cu")
		(net "M_L_CPU0_SB_DQ<2>")
	)
	(segment
		(start 405.559768 -277.00224)
		(end 405.383492 -277.178516)
		(width 0.14478)
		(layer "In11.Cu")
		(net "M_L_CPU0_SB_DQ<2>")
	)
	(segment
		(start 402.233892 -274.259548)
		(end 402.39696 -274.422616)
		(width 0.14478)
		(layer "In11.Cu")
		(net "M_L_CPU0_SB_DQ<2>")
	)
	(segment
		(start 403.984968 -275.196808)
		(end 403.984968 -275.42744)
		(width 0.14478)
		(layer "In11.Cu")
		(net "M_L_CPU0_SB_DQ<2>")
	)
	(segment
		(start 405.953468 -277.39594)
		(end 406.1841 -277.39594)
		(width 0.14478)
		(layer "In11.Cu")
		(net "M_L_CPU0_SB_DQ<2>")
	)
	(segment
		(start 437.57215 -281.910028)
		(end 440.754516 -281.910028)
		(width 0.14478)
		(layer "In11.Cu")
		(net "M_L_CPU0_SB_DQ<2>")
	)
	(segment
		(start 403.18436 -275.210016)
		(end 403.414992 -275.210016)
		(width 0.14478)
		(layer "In11.Cu")
		(net "M_L_CPU0_SB_DQ<2>")
	)
	(segment
		(start 406.170892 -277.965916)
		(end 406.170892 -278.196548)
		(width 0.14478)
		(layer "In11.Cu")
		(net "M_L_CPU0_SB_DQ<2>")
	)
	(segment
		(start 405.3967 -276.60854)
		(end 405.559768 -276.771608)
		(width 0.14478)
		(layer "In11.Cu")
		(net "M_L_CPU0_SB_DQ<2>")
	)
	(segment
		(start 429.177958 -282.760166)
		(end 430.028096 -281.910028)
		(width 0.14478)
		(layer "In11.Cu")
		(net "M_L_CPU0_SB_DQ<2>")
	)
	(segment
		(start 406.347168 -277.78964)
		(end 406.170892 -277.965916)
		(width 0.14478)
		(layer "In11.Cu")
		(net "M_L_CPU0_SB_DQ<2>")
	)
	(segment
		(start 406.564592 -278.359616)
		(end 406.740868 -278.18334)
		(width 0.14478)
		(layer "In11.Cu")
		(net "M_L_CPU0_SB_DQ<2>")
	)
	(segment
		(start 421.633904 -282.760166)
		(end 422.484042 -281.910028)
		(width 0.14478)
		(layer "In11.Cu")
		(net "M_L_CPU0_SB_DQ<2>")
	)
	(segment
		(start 403.808692 -275.603716)
		(end 403.808692 -275.834348)
		(width 0.14478)
		(layer "In11.Cu")
		(net "M_L_CPU0_SB_DQ<2>")
	)
	(segment
		(start 403.021292 -275.046948)
		(end 403.18436 -275.210016)
		(width 0.14478)
		(layer "In11.Cu")
		(net "M_L_CPU0_SB_DQ<2>")
	)
	(segment
		(start 387.274816 -274.896072)
		(end 387.42874 -274.630642)
		(width 0.0889)
		(layer "In11.Cu")
		(net "M_L_CPU0_SB_DQ<2>")
	)
	(segment
		(start 430.028096 -281.910028)
		(end 433.210462 -281.910028)
		(width 0.14478)
		(layer "In11.Cu")
		(net "M_L_CPU0_SB_DQ<2>")
	)
	(segment
		(start 407.134568 -278.57704)
		(end 406.958292 -278.753316)
		(width 0.14478)
		(layer "In11.Cu")
		(net "M_L_CPU0_SB_DQ<2>")
	)
	(segment
		(start 395.46022 -273.39417)
		(end 395.988286 -273.39417)
		(width 0.0889)
		(layer "In11.Cu")
		(net "M_L_CPU0_SB_DQ<2>")
	)
	(segment
		(start 440.754516 -281.910028)
		(end 441.604654 -282.760166)
		(width 0.14478)
		(layer "In11.Cu")
		(net "M_L_CPU0_SB_DQ<2>")
	)
	(segment
		(start 444.45301 -281.910028)
		(end 449.663058 -281.910028)
		(width 0.14478)
		(layer "In11.Cu")
		(net "M_L_CPU0_SB_DQ<2>")
	)
	(segment
		(start 417.143438 -281.62631)
		(end 417.416234 -281.62631)
		(width 0.14478)
		(layer "In11.Cu")
		(net "M_L_CPU0_SB_DQ<2>")
	)
	(segment
		(start 403.808692 -275.834348)
		(end 403.97176 -275.997416)
		(width 0.14478)
		(layer "In11.Cu")
		(net "M_L_CPU0_SB_DQ<2>")
	)
	(segment
		(start 392.726672 -274.573492)
		(end 392.738356 -274.566634)
		(width 0.0889)
		(layer "In11.Cu")
		(net "M_L_CPU0_SB_DQ<2>")
	)
	(segment
		(start 402.233892 -274.028916)
		(end 402.233892 -274.259548)
		(width 0.14478)
		(layer "In11.Cu")
		(net "M_L_CPU0_SB_DQ<2>")
	)
	(segment
		(start 393.643104 -274.649946)
		(end 394.677138 -273.615912)
		(width 0.0889)
		(layer "In11.Cu")
		(net "M_L_CPU0_SB_DQ<2>")
	)
	(segment
		(start 425.666408 -281.910028)
		(end 426.516546 -282.760166)
		(width 0.14478)
		(layer "In11.Cu")
		(net "M_L_CPU0_SB_DQ<2>")
	)
	(segment
		(start 433.210462 -281.910028)
		(end 434.0606 -282.760166)
		(width 0.14478)
		(layer "In11.Cu")
		(net "M_L_CPU0_SB_DQ<2>")
	)
	(segment
		(start 416.586924 -281.910028)
		(end 416.85972 -281.910028)
		(width 0.14478)
		(layer "In11.Cu")
		(net "M_L_CPU0_SB_DQ<2>")
	)
	(segment
		(start 414.063942 -282.760166)
		(end 414.91408 -281.910028)
		(width 0.14478)
		(layer "In11.Cu")
		(net "M_L_CPU0_SB_DQ<2>")
	)
	(segment
		(start 434.0606 -282.760166)
		(end 436.722012 -282.760166)
		(width 0.14478)
		(layer "In11.Cu")
		(net "M_L_CPU0_SB_DQ<2>")
	)
	(segment
		(start 393.384786 -274.649946)
		(end 393.643104 -274.649946)
		(width 0.0889)
		(layer "In11.Cu")
		(net "M_L_CPU0_SB_DQ<2>")
	)
	(segment
		(start 403.197568 -274.409408)
		(end 403.197568 -274.64004)
		(width 0.14478)
		(layer "In11.Cu")
		(net "M_L_CPU0_SB_DQ<2>")
	)
	(segment
		(start 406.347168 -277.559008)
		(end 406.347168 -277.78964)
		(width 0.14478)
		(layer "In11.Cu")
		(net "M_L_CPU0_SB_DQ<2>")
	)
	(segment
		(start 416.303206 -281.62631)
		(end 416.586924 -281.910028)
		(width 0.14478)
		(layer "In11.Cu")
		(net "M_L_CPU0_SB_DQ<2>")
	)
	(segment
		(start 403.0345 -274.24634)
		(end 403.197568 -274.409408)
		(width 0.14478)
		(layer "In11.Cu")
		(net "M_L_CPU0_SB_DQ<2>")
	)
	(segment
		(start 403.591268 -275.03374)
		(end 403.8219 -275.03374)
		(width 0.14478)
		(layer "In11.Cu")
		(net "M_L_CPU0_SB_DQ<2>")
	)
	(segment
		(start 407.528268 -278.97074)
		(end 407.7589 -278.97074)
		(width 0.14478)
		(layer "In11.Cu")
		(net "M_L_CPU0_SB_DQ<2>")
	)
	(segment
		(start 417.416234 -281.62631)
		(end 417.699952 -281.910028)
		(width 0.14478)
		(layer "In11.Cu")
		(net "M_L_CPU0_SB_DQ<2>")
	)
	(segment
		(start 407.7589 -278.97074)
		(end 411.548326 -282.760166)
		(width 0.14478)
		(layer "In11.Cu")
		(net "M_L_CPU0_SB_DQ<2>")
	)
	(segment
		(start 416.03041 -281.62631)
		(end 416.303206 -281.62631)
		(width 0.14478)
		(layer "In11.Cu")
		(net "M_L_CPU0_SB_DQ<2>")
	)
	(segment
		(start 426.516546 -282.760166)
		(end 429.177958 -282.760166)
		(width 0.14478)
		(layer "In11.Cu")
		(net "M_L_CPU0_SB_DQ<2>")
	)
	(segment
		(start 395.988286 -273.39417)
		(end 402.18233 -273.39417)
		(width 0.14478)
		(layer "In11.Cu")
		(net "M_L_CPU0_SB_DQ<2>")
	)
	(segment
		(start 403.984968 -275.42744)
		(end 403.808692 -275.603716)
		(width 0.14478)
		(layer "In11.Cu")
		(net "M_L_CPU0_SB_DQ<2>")
	)
	(segment
		(start 404.202392 -275.997416)
		(end 404.378668 -275.82114)
		(width 0.14478)
		(layer "In11.Cu")
		(net "M_L_CPU0_SB_DQ<2>")
	)
	(segment
		(start 405.559768 -276.771608)
		(end 405.559768 -277.00224)
		(width 0.14478)
		(layer "In11.Cu")
		(net "M_L_CPU0_SB_DQ<2>")
	)
	(segment
		(start 395.238478 -273.615912)
		(end 395.46022 -273.39417)
		(width 0.0889)
		(layer "In11.Cu")
		(net "M_L_CPU0_SB_DQ<2>")
	)
	(segment
		(start 411.548326 -282.760166)
		(end 414.063942 -282.760166)
		(width 0.14478)
		(layer "In11.Cu")
		(net "M_L_CPU0_SB_DQ<2>")
	)
	(segment
		(start 403.021292 -274.816316)
		(end 403.021292 -275.046948)
		(width 0.14478)
		(layer "In11.Cu")
		(net "M_L_CPU0_SB_DQ<2>")
	)
	(segment
		(start 392.161522 -274.573746)
		(end 392.17346 -274.580604)
		(width 0.0889)
		(layer "In11.Cu")
		(net "M_L_CPU0_SB_DQ<2>")
	)
	(segment
		(start 394.677138 -273.615912)
		(end 395.238478 -273.615912)
		(width 0.0889)
		(layer "In11.Cu")
		(net "M_L_CPU0_SB_DQ<2>")
	)
	(segment
		(start 387.42874 -274.630642)
		(end 387.524752 -274.605242)
		(width 0.0889)
		(layer "In11.Cu")
		(net "M_L_CPU0_SB_DQ<2>")
	)
	(segment
		(start 416.85972 -281.910028)
		(end 417.143438 -281.62631)
		(width 0.14478)
		(layer "In11.Cu")
		(net "M_L_CPU0_SB_DQ<2>")
	)
	(segment
		(start 441.604654 -282.760166)
		(end 443.602872 -282.760166)
		(width 0.14478)
		(layer "In11.Cu")
		(net "M_L_CPU0_SB_DQ<2>")
	)
	(segment
		(start 403.197568 -274.64004)
		(end 403.021292 -274.816316)
		(width 0.14478)
		(layer "In11.Cu")
		(net "M_L_CPU0_SB_DQ<2>")
	)
	(segment
		(start 406.740868 -278.18334)
		(end 406.9715 -278.18334)
		(width 0.14478)
		(layer "In11.Cu")
		(net "M_L_CPU0_SB_DQ<2>")
	)
	(segment
		(start 415.746692 -281.910028)
		(end 416.03041 -281.62631)
		(width 0.14478)
		(layer "In11.Cu")
		(net "M_L_CPU0_SB_DQ<2>")
	)
	(segment
		(start 417.699952 -281.910028)
		(end 418.122354 -281.910028)
		(width 0.14478)
		(layer "In11.Cu")
		(net "M_L_CPU0_SB_DQ<2>")
	)
	(segment
		(start 405.54656 -277.572216)
		(end 405.777192 -277.572216)
		(width 0.14478)
		(layer "In11.Cu")
		(net "M_L_CPU0_SB_DQ<2>")
	)
	(segment
		(start 402.803868 -274.24634)
		(end 403.0345 -274.24634)
		(width 0.14478)
		(layer "In11.Cu")
		(net "M_L_CPU0_SB_DQ<2>")
	)
	(segment
		(start 404.596092 -276.391116)
		(end 404.596092 -276.621748)
		(width 0.14478)
		(layer "In11.Cu")
		(net "M_L_CPU0_SB_DQ<2>")
	)
	(segment
		(start 407.351992 -279.147016)
		(end 407.528268 -278.97074)
		(width 0.14478)
		(layer "In11.Cu")
		(net "M_L_CPU0_SB_DQ<2>")
	)
	(segment
		(start 404.772368 -275.984208)
		(end 404.772368 -276.21484)
		(width 0.14478)
		(layer "In11.Cu")
		(net "M_L_CPU0_SB_DQ<2>")
	)
	(segment
		(start 405.383492 -277.409148)
		(end 405.54656 -277.572216)
		(width 0.14478)
		(layer "In11.Cu")
		(net "M_L_CPU0_SB_DQ<2>")
	)
	(segment
		(start 404.772368 -276.21484)
		(end 404.596092 -276.391116)
		(width 0.14478)
		(layer "In11.Cu")
		(net "M_L_CPU0_SB_DQ<2>")
	)
	(segment
		(start 402.410168 -273.85264)
		(end 402.233892 -274.028916)
		(width 0.14478)
		(layer "In11.Cu")
		(net "M_L_CPU0_SB_DQ<2>")
	)
	(segment
		(start 389.333486 -274.568666)
		(end 389.341868 -274.573492)
		(width 0.0889)
		(layer "In11.Cu")
		(net "M_L_CPU0_SB_DQ<2>")
	)
	(segment
		(start 443.602872 -282.760166)
		(end 444.45301 -281.910028)
		(width 0.14478)
		(layer "In11.Cu")
		(net "M_L_CPU0_SB_DQ<2>")
	)
	(arc
		(start 392.738356 -274.566634)
		(mid 392.920611 -274.522981)
		(end 393.101068 -274.573492)
		(width 0.0889)
		(layer "In11.Cu")
		(net "M_L_CPU0_SB_DQ<2>")
	)
	(arc
		(start 390.847834 -274.573492)
		(mid 391.034778 -274.523237)
		(end 391.221722 -274.573492)
		(width 0.0889)
		(layer "In11.Cu")
		(net "M_L_CPU0_SB_DQ<2>")
	)
	(arc
		(start 388.027672 -274.573492)
		(mid 388.209923 -274.523142)
		(end 388.393432 -274.568666)
		(width 0.0889)
		(layer "In11.Cu")
		(net "M_L_CPU0_SB_DQ<2>")
	)
	(arc
		(start 391.221722 -274.573492)
		(mid 391.504678 -274.649669)
		(end 391.787634 -274.573492)
		(width 0.0889)
		(layer "In11.Cu")
		(net "M_L_CPU0_SB_DQ<2>")
	)
	(arc
		(start 391.787634 -274.573492)
		(mid 391.965284 -274.523232)
		(end 392.145266 -274.564348)
		(width 0.0889)
		(layer "In11.Cu")
		(net "M_L_CPU0_SB_DQ<2>")
	)
	(arc
		(start 393.101068 -274.573492)
		(mid 393.237861 -274.630514)
		(end 393.384786 -274.649946)
		(width 0.0889)
		(layer "In11.Cu")
		(net "M_L_CPU0_SB_DQ<2>")
	)
	(arc
		(start 389.916162 -274.568666)
		(mid 390.09967 -274.523172)
		(end 390.281922 -274.573492)
		(width 0.0889)
		(layer "In11.Cu")
		(net "M_L_CPU0_SB_DQ<2>")
	)
	(arc
		(start 388.401814 -274.573492)
		(mid 388.68477 -274.649669)
		(end 388.967726 -274.573492)
		(width 0.0889)
		(layer "In11.Cu")
		(net "M_L_CPU0_SB_DQ<2>")
	)
	(arc
		(start 388.967726 -274.573492)
		(mid 389.149977 -274.523142)
		(end 389.333486 -274.568666)
		(width 0.0889)
		(layer "In11.Cu")
		(net "M_L_CPU0_SB_DQ<2>")
	)
	(arc
		(start 392.17346 -274.580604)
		(mid 392.450994 -274.649585)
		(end 392.726672 -274.573492)
		(width 0.0889)
		(layer "In11.Cu")
		(net "M_L_CPU0_SB_DQ<2>")
	)
	(arc
		(start 387.524752 -274.605242)
		(mid 387.77996 -274.648719)
		(end 388.027672 -274.573492)
		(width 0.0889)
		(layer "In11.Cu")
		(net "M_L_CPU0_SB_DQ<2>")
	)
	(arc
		(start 389.341868 -274.573492)
		(mid 389.624824 -274.649669)
		(end 389.90778 -274.573492)
		(width 0.0889)
		(layer "In11.Cu")
		(net "M_L_CPU0_SB_DQ<2>")
	)
	(arc
		(start 390.281922 -274.573492)
		(mid 390.564878 -274.649669)
		(end 390.847834 -274.573492)
		(width 0.0889)
		(layer "In11.Cu")
		(net "M_L_CPU0_SB_DQ<2>")
	)
	(segment
		(start 385.86791 -292.450012)
		(end 386.334762 -292.71595)
		(width 0.10668)
		(layer "F.Cu")
		(net "M_L_CPU0_SB_DQ<29>")
	)
	(segment
		(start 451.345554 -317.755016)
		(end 451.345554 -318.271652)
		(width 0.14478)
		(layer "In11.Cu")
		(net "M_L_CPU0_SB_DQ<29>")
	)
	(segment
		(start 452.855076 -318.416432)
		(end 452.999856 -318.271652)
		(width 0.14478)
		(layer "In11.Cu")
		(net "M_L_CPU0_SB_DQ<29>")
	)
	(segment
		(start 387.057392 -293.02075)
		(end 387.087872 -293.03853)
		(width 0.0889)
		(layer "In11.Cu")
		(net "M_L_CPU0_SB_DQ<29>")
	)
	(segment
		(start 392.727434 -294.658542)
		(end 392.76655 -294.681402)
		(width 0.0889)
		(layer "In11.Cu")
		(net "M_L_CPU0_SB_DQ<29>")
	)
	(segment
		(start 452.448422 -317.755016)
		(end 452.448422 -318.271652)
		(width 0.14478)
		(layer "In11.Cu")
		(net "M_L_CPU0_SB_DQ<29>")
	)
	(segment
		(start 451.896988 -317.755016)
		(end 452.041768 -317.610236)
		(width 0.14478)
		(layer "In11.Cu")
		(net "M_L_CPU0_SB_DQ<29>")
	)
	(segment
		(start 452.593202 -318.416432)
		(end 452.855076 -318.416432)
		(width 0.14478)
		(layer "In11.Cu")
		(net "M_L_CPU0_SB_DQ<29>")
	)
	(segment
		(start 393.713716 -295.960292)
		(end 393.713716 -296.549318)
		(width 0.0889)
		(layer "In11.Cu")
		(net "M_L_CPU0_SB_DQ<29>")
	)
	(segment
		(start 451.345554 -318.271652)
		(end 451.490334 -318.416432)
		(width 0.14478)
		(layer "In11.Cu")
		(net "M_L_CPU0_SB_DQ<29>")
	)
	(segment
		(start 451.896988 -318.271652)
		(end 451.896988 -317.755016)
		(width 0.14478)
		(layer "In11.Cu")
		(net "M_L_CPU0_SB_DQ<29>")
	)
	(segment
		(start 451.752208 -318.416432)
		(end 451.896988 -318.271652)
		(width 0.14478)
		(layer "In11.Cu")
		(net "M_L_CPU0_SB_DQ<29>")
	)
	(segment
		(start 389.333486 -293.043356)
		(end 389.341868 -293.03853)
		(width 0.0889)
		(layer "In11.Cu")
		(net "M_L_CPU0_SB_DQ<29>")
	)
	(segment
		(start 393.713716 -301.146972)
		(end 410.17698 -317.610236)
		(width 0.14478)
		(layer "In11.Cu")
		(net "M_L_CPU0_SB_DQ<29>")
	)
	(segment
		(start 391.787634 -293.03853)
		(end 391.82675 -293.06139)
		(width 0.0889)
		(layer "In11.Cu")
		(net "M_L_CPU0_SB_DQ<29>")
	)
	(segment
		(start 393.355322 -295.601898)
		(end 393.713716 -295.960292)
		(width 0.0889)
		(layer "In11.Cu")
		(net "M_L_CPU0_SB_DQ<29>")
	)
	(segment
		(start 452.041768 -317.610236)
		(end 452.303642 -317.610236)
		(width 0.14478)
		(layer "In11.Cu")
		(net "M_L_CPU0_SB_DQ<29>")
	)
	(segment
		(start 451.490334 -318.416432)
		(end 451.752208 -318.416432)
		(width 0.14478)
		(layer "In11.Cu")
		(net "M_L_CPU0_SB_DQ<29>")
	)
	(segment
		(start 392.696954 -294.640762)
		(end 392.727434 -294.658542)
		(width 0.0889)
		(layer "In11.Cu")
		(net "M_L_CPU0_SB_DQ<29>")
	)
	(segment
		(start 389.90778 -293.03853)
		(end 389.916162 -293.043356)
		(width 0.0889)
		(layer "In11.Cu")
		(net "M_L_CPU0_SB_DQ<29>")
	)
	(segment
		(start 393.713716 -296.549318)
		(end 393.713716 -301.146972)
		(width 0.14478)
		(layer "In11.Cu")
		(net "M_L_CPU0_SB_DQ<29>")
	)
	(segment
		(start 388.393432 -293.043356)
		(end 388.401814 -293.03853)
		(width 0.0889)
		(layer "In11.Cu")
		(net "M_L_CPU0_SB_DQ<29>")
	)
	(segment
		(start 410.17698 -317.610236)
		(end 451.200774 -317.610236)
		(width 0.14478)
		(layer "In11.Cu")
		(net "M_L_CPU0_SB_DQ<29>")
	)
	(segment
		(start 453.762872 -317.610236)
		(end 454.188068 -317.18504)
		(width 0.14478)
		(layer "In11.Cu")
		(net "M_L_CPU0_SB_DQ<29>")
	)
	(segment
		(start 452.303642 -317.610236)
		(end 452.448422 -317.755016)
		(width 0.14478)
		(layer "In11.Cu")
		(net "M_L_CPU0_SB_DQ<29>")
	)
	(segment
		(start 452.999856 -318.271652)
		(end 452.999856 -317.755016)
		(width 0.14478)
		(layer "In11.Cu")
		(net "M_L_CPU0_SB_DQ<29>")
	)
	(segment
		(start 452.999856 -317.755016)
		(end 453.144636 -317.610236)
		(width 0.14478)
		(layer "In11.Cu")
		(net "M_L_CPU0_SB_DQ<29>")
	)
	(segment
		(start 451.200774 -317.610236)
		(end 451.345554 -317.755016)
		(width 0.14478)
		(layer "In11.Cu")
		(net "M_L_CPU0_SB_DQ<29>")
	)
	(segment
		(start 453.144636 -317.610236)
		(end 453.762872 -317.610236)
		(width 0.14478)
		(layer "In11.Cu")
		(net "M_L_CPU0_SB_DQ<29>")
	)
	(segment
		(start 392.257534 -293.848536)
		(end 392.29665 -293.871396)
		(width 0.0889)
		(layer "In11.Cu")
		(net "M_L_CPU0_SB_DQ<29>")
	)
	(segment
		(start 386.334762 -292.71595)
		(end 387.057392 -293.02075)
		(width 0.0889)
		(layer "In11.Cu")
		(net "M_L_CPU0_SB_DQ<29>")
	)
	(segment
		(start 452.448422 -318.271652)
		(end 452.593202 -318.416432)
		(width 0.14478)
		(layer "In11.Cu")
		(net "M_L_CPU0_SB_DQ<29>")
	)
	(segment
		(start 392.227054 -293.830756)
		(end 392.257534 -293.848536)
		(width 0.0889)
		(layer "In11.Cu")
		(net "M_L_CPU0_SB_DQ<29>")
	)
	(segment
		(start 393.16406 -295.44899)
		(end 393.234164 -295.48963)
		(width 0.0889)
		(layer "In11.Cu")
		(net "M_L_CPU0_SB_DQ<29>")
	)
	(arc
		(start 393.234164 -295.48963)
		(mid 393.298866 -295.541315)
		(end 393.355322 -295.601898)
		(width 0.0889)
		(layer "In11.Cu")
		(net "M_L_CPU0_SB_DQ<29>")
	)
	(arc
		(start 390.281922 -293.03853)
		(mid 390.564878 -292.962353)
		(end 390.847834 -293.03853)
		(width 0.0889)
		(layer "In11.Cu")
		(net "M_L_CPU0_SB_DQ<29>")
	)
	(arc
		(start 391.82675 -293.06139)
		(mid 392.005563 -293.26374)
		(end 392.070082 -293.525956)
		(width 0.0889)
		(layer "In11.Cu")
		(net "M_L_CPU0_SB_DQ<29>")
	)
	(arc
		(start 388.401814 -293.03853)
		(mid 388.68477 -292.962353)
		(end 388.967726 -293.03853)
		(width 0.0889)
		(layer "In11.Cu")
		(net "M_L_CPU0_SB_DQ<29>")
	)
	(arc
		(start 392.29665 -293.871396)
		(mid 392.475463 -294.073746)
		(end 392.539982 -294.335962)
		(width 0.0889)
		(layer "In11.Cu")
		(net "M_L_CPU0_SB_DQ<29>")
	)
	(arc
		(start 389.916162 -293.043356)
		(mid 390.09967 -293.08885)
		(end 390.281922 -293.03853)
		(width 0.0889)
		(layer "In11.Cu")
		(net "M_L_CPU0_SB_DQ<29>")
	)
	(arc
		(start 392.539982 -294.335962)
		(mid 392.581531 -294.507384)
		(end 392.696954 -294.640762)
		(width 0.0889)
		(layer "In11.Cu")
		(net "M_L_CPU0_SB_DQ<29>")
	)
	(arc
		(start 392.76655 -294.681402)
		(mid 392.945363 -294.883752)
		(end 393.009882 -295.145968)
		(width 0.0889)
		(layer "In11.Cu")
		(net "M_L_CPU0_SB_DQ<29>")
	)
	(arc
		(start 388.027672 -293.03853)
		(mid 388.209923 -293.08888)
		(end 388.393432 -293.043356)
		(width 0.0889)
		(layer "In11.Cu")
		(net "M_L_CPU0_SB_DQ<29>")
	)
	(arc
		(start 393.009882 -295.145968)
		(mid 393.05064 -295.315966)
		(end 393.16406 -295.44899)
		(width 0.0889)
		(layer "In11.Cu")
		(net "M_L_CPU0_SB_DQ<29>")
	)
	(arc
		(start 389.341868 -293.03853)
		(mid 389.624824 -292.962353)
		(end 389.90778 -293.03853)
		(width 0.0889)
		(layer "In11.Cu")
		(net "M_L_CPU0_SB_DQ<29>")
	)
	(arc
		(start 392.070082 -293.525956)
		(mid 392.111631 -293.697378)
		(end 392.227054 -293.830756)
		(width 0.0889)
		(layer "In11.Cu")
		(net "M_L_CPU0_SB_DQ<29>")
	)
	(arc
		(start 391.221722 -293.03853)
		(mid 391.504678 -292.962353)
		(end 391.787634 -293.03853)
		(width 0.0889)
		(layer "In11.Cu")
		(net "M_L_CPU0_SB_DQ<29>")
	)
	(arc
		(start 390.847834 -293.03853)
		(mid 391.034778 -293.088785)
		(end 391.221722 -293.03853)
		(width 0.0889)
		(layer "In11.Cu")
		(net "M_L_CPU0_SB_DQ<29>")
	)
	(arc
		(start 387.087872 -293.03853)
		(mid 387.274816 -293.088785)
		(end 387.46176 -293.03853)
		(width 0.0889)
		(layer "In11.Cu")
		(net "M_L_CPU0_SB_DQ<29>")
	)
	(arc
		(start 388.967726 -293.03853)
		(mid 389.149977 -293.08888)
		(end 389.333486 -293.043356)
		(width 0.0889)
		(layer "In11.Cu")
		(net "M_L_CPU0_SB_DQ<29>")
	)
	(arc
		(start 387.46176 -293.03853)
		(mid 387.744716 -292.962353)
		(end 388.027672 -293.03853)
		(width 0.0889)
		(layer "In11.Cu")
		(net "M_L_CPU0_SB_DQ<29>")
	)
	(segment
		(start 387.277864 -291.640006)
		(end 387.744716 -291.905944)
		(width 0.10668)
		(layer "F.Cu")
		(net "M_L_CPU0_SB_DQ<28>")
	)
	(segment
		(start 392.127486 -292.152324)
		(end 392.257788 -292.228524)
		(width 0.0889)
		(layer "In11.Cu")
		(net "M_L_CPU0_SB_DQ<28>")
	)
	(segment
		(start 451.372478 -316.064392)
		(end 451.372478 -316.859412)
		(width 0.14478)
		(layer "In11.Cu")
		(net "M_L_CPU0_SB_DQ<28>")
	)
	(segment
		(start 452.882 -317.004192)
		(end 453.02678 -316.859412)
		(width 0.14478)
		(layer "In11.Cu")
		(net "M_L_CPU0_SB_DQ<28>")
	)
	(segment
		(start 451.372478 -316.859412)
		(end 451.517258 -317.004192)
		(width 0.14478)
		(layer "In11.Cu")
		(net "M_L_CPU0_SB_DQ<28>")
	)
	(segment
		(start 452.475346 -316.859412)
		(end 452.620126 -317.004192)
		(width 0.14478)
		(layer "In11.Cu")
		(net "M_L_CPU0_SB_DQ<28>")
	)
	(segment
		(start 394.623036 -300.73346)
		(end 409.809188 -315.919612)
		(width 0.14478)
		(layer "In11.Cu")
		(net "M_L_CPU0_SB_DQ<28>")
	)
	(segment
		(start 451.923912 -316.859412)
		(end 451.923912 -316.064392)
		(width 0.14478)
		(layer "In11.Cu")
		(net "M_L_CPU0_SB_DQ<28>")
	)
	(segment
		(start 453.17156 -315.919612)
		(end 453.753474 -315.919612)
		(width 0.14478)
		(layer "In11.Cu")
		(net "M_L_CPU0_SB_DQ<28>")
	)
	(segment
		(start 392.697208 -293.02075)
		(end 392.727688 -293.03853)
		(width 0.0889)
		(layer "In11.Cu")
		(net "M_L_CPU0_SB_DQ<28>")
	)
	(segment
		(start 393.197588 -293.848536)
		(end 393.236704 -293.871396)
		(width 0.0889)
		(layer "In11.Cu")
		(net "M_L_CPU0_SB_DQ<28>")
	)
	(segment
		(start 393.667742 -294.658542)
		(end 393.873736 -294.778176)
		(width 0.0889)
		(layer "In11.Cu")
		(net "M_L_CPU0_SB_DQ<28>")
	)
	(segment
		(start 451.923912 -316.064392)
		(end 452.068692 -315.919612)
		(width 0.14478)
		(layer "In11.Cu")
		(net "M_L_CPU0_SB_DQ<28>")
	)
	(segment
		(start 387.590792 -292.171374)
		(end 387.613144 -292.254686)
		(width 0.0889)
		(layer "In11.Cu")
		(net "M_L_CPU0_SB_DQ<28>")
	)
	(segment
		(start 390.74344 -292.23335)
		(end 390.751822 -292.228524)
		(width 0.0889)
		(layer "In11.Cu")
		(net "M_L_CPU0_SB_DQ<28>")
	)
	(segment
		(start 394.623036 -296.468038)
		(end 394.623036 -300.73346)
		(width 0.14478)
		(layer "In11.Cu")
		(net "M_L_CPU0_SB_DQ<28>")
	)
	(segment
		(start 392.727688 -293.03853)
		(end 392.766804 -293.06139)
		(width 0.0889)
		(layer "In11.Cu")
		(net "M_L_CPU0_SB_DQ<28>")
	)
	(segment
		(start 387.744716 -291.905944)
		(end 387.590792 -292.171374)
		(width 0.0889)
		(layer "In11.Cu")
		(net "M_L_CPU0_SB_DQ<28>")
	)
	(segment
		(start 453.02678 -316.064392)
		(end 453.17156 -315.919612)
		(width 0.14478)
		(layer "In11.Cu")
		(net "M_L_CPU0_SB_DQ<28>")
	)
	(segment
		(start 452.620126 -317.004192)
		(end 452.882 -317.004192)
		(width 0.14478)
		(layer "In11.Cu")
		(net "M_L_CPU0_SB_DQ<28>")
	)
	(segment
		(start 451.779132 -317.004192)
		(end 451.923912 -316.859412)
		(width 0.14478)
		(layer "In11.Cu")
		(net "M_L_CPU0_SB_DQ<28>")
	)
	(segment
		(start 453.02678 -316.859412)
		(end 453.02678 -316.064392)
		(width 0.14478)
		(layer "In11.Cu")
		(net "M_L_CPU0_SB_DQ<28>")
	)
	(segment
		(start 394.623036 -295.527476)
		(end 394.623036 -296.468038)
		(width 0.0889)
		(layer "In11.Cu")
		(net "M_L_CPU0_SB_DQ<28>")
	)
	(segment
		(start 388.497826 -292.228524)
		(end 388.506208 -292.23335)
		(width 0.0889)
		(layer "In11.Cu")
		(net "M_L_CPU0_SB_DQ<28>")
	)
	(segment
		(start 452.068692 -315.919612)
		(end 452.330566 -315.919612)
		(width 0.14478)
		(layer "In11.Cu")
		(net "M_L_CPU0_SB_DQ<28>")
	)
	(segment
		(start 452.475346 -316.064392)
		(end 452.475346 -316.859412)
		(width 0.14478)
		(layer "In11.Cu")
		(net "M_L_CPU0_SB_DQ<28>")
	)
	(segment
		(start 453.753474 -315.919612)
		(end 454.188068 -315.485018)
		(width 0.14478)
		(layer "In11.Cu")
		(net "M_L_CPU0_SB_DQ<28>")
	)
	(segment
		(start 392.257788 -292.228524)
		(end 392.296904 -292.251384)
		(width 0.0889)
		(layer "In11.Cu")
		(net "M_L_CPU0_SB_DQ<28>")
	)
	(segment
		(start 391.974578 -292.152324)
		(end 392.127486 -292.152324)
		(width 0.0889)
		(layer "In11.Cu")
		(net "M_L_CPU0_SB_DQ<28>")
	)
	(segment
		(start 391.317734 -292.228524)
		(end 391.326116 -292.23335)
		(width 0.0889)
		(layer "In11.Cu")
		(net "M_L_CPU0_SB_DQ<28>")
	)
	(segment
		(start 452.330566 -315.919612)
		(end 452.475346 -316.064392)
		(width 0.14478)
		(layer "In11.Cu")
		(net "M_L_CPU0_SB_DQ<28>")
	)
	(segment
		(start 393.873736 -294.778176)
		(end 394.623036 -295.527476)
		(width 0.0889)
		(layer "In11.Cu")
		(net "M_L_CPU0_SB_DQ<28>")
	)
	(segment
		(start 393.635992 -294.640254)
		(end 393.667742 -294.658542)
		(width 0.0889)
		(layer "In11.Cu")
		(net "M_L_CPU0_SB_DQ<28>")
	)
	(segment
		(start 451.227698 -315.919612)
		(end 451.372478 -316.064392)
		(width 0.14478)
		(layer "In11.Cu")
		(net "M_L_CPU0_SB_DQ<28>")
	)
	(segment
		(start 409.809188 -315.919612)
		(end 451.227698 -315.919612)
		(width 0.14478)
		(layer "In11.Cu")
		(net "M_L_CPU0_SB_DQ<28>")
	)
	(segment
		(start 393.167108 -293.830756)
		(end 393.197588 -293.848536)
		(width 0.0889)
		(layer "In11.Cu")
		(net "M_L_CPU0_SB_DQ<28>")
	)
	(segment
		(start 451.517258 -317.004192)
		(end 451.779132 -317.004192)
		(width 0.14478)
		(layer "In11.Cu")
		(net "M_L_CPU0_SB_DQ<28>")
	)
	(arc
		(start 390.751822 -292.228524)
		(mid 391.034778 -292.152347)
		(end 391.317734 -292.228524)
		(width 0.0889)
		(layer "In11.Cu")
		(net "M_L_CPU0_SB_DQ<28>")
	)
	(arc
		(start 393.010136 -293.525956)
		(mid 393.051685 -293.697378)
		(end 393.167108 -293.830756)
		(width 0.0889)
		(layer "In11.Cu")
		(net "M_L_CPU0_SB_DQ<28>")
	)
	(arc
		(start 387.931914 -292.228524)
		(mid 388.21487 -292.152347)
		(end 388.497826 -292.228524)
		(width 0.0889)
		(layer "In11.Cu")
		(net "M_L_CPU0_SB_DQ<28>")
	)
	(arc
		(start 389.811768 -292.228524)
		(mid 390.094724 -292.152347)
		(end 390.37768 -292.228524)
		(width 0.0889)
		(layer "In11.Cu")
		(net "M_L_CPU0_SB_DQ<28>")
	)
	(arc
		(start 391.691876 -292.228524)
		(mid 391.828194 -292.171757)
		(end 391.974578 -292.152324)
		(width 0.0889)
		(layer "In11.Cu")
		(net "M_L_CPU0_SB_DQ<28>")
	)
	(arc
		(start 393.480036 -294.335962)
		(mid 393.521291 -294.506933)
		(end 393.635992 -294.640254)
		(width 0.0889)
		(layer "In11.Cu")
		(net "M_L_CPU0_SB_DQ<28>")
	)
	(arc
		(start 391.326116 -292.23335)
		(mid 391.509624 -292.278844)
		(end 391.691876 -292.228524)
		(width 0.0889)
		(layer "In11.Cu")
		(net "M_L_CPU0_SB_DQ<28>")
	)
	(arc
		(start 392.296904 -292.251384)
		(mid 392.475717 -292.453734)
		(end 392.540236 -292.71595)
		(width 0.0889)
		(layer "In11.Cu")
		(net "M_L_CPU0_SB_DQ<28>")
	)
	(arc
		(start 388.871968 -292.228524)
		(mid 389.154924 -292.152347)
		(end 389.43788 -292.228524)
		(width 0.0889)
		(layer "In11.Cu")
		(net "M_L_CPU0_SB_DQ<28>")
	)
	(arc
		(start 389.43788 -292.228524)
		(mid 389.624824 -292.278779)
		(end 389.811768 -292.228524)
		(width 0.0889)
		(layer "In11.Cu")
		(net "M_L_CPU0_SB_DQ<28>")
	)
	(arc
		(start 393.236704 -293.871396)
		(mid 393.415517 -294.073746)
		(end 393.480036 -294.335962)
		(width 0.0889)
		(layer "In11.Cu")
		(net "M_L_CPU0_SB_DQ<28>")
	)
	(arc
		(start 387.613144 -292.254686)
		(mid 387.775476 -292.277504)
		(end 387.931914 -292.228524)
		(width 0.0889)
		(layer "In11.Cu")
		(net "M_L_CPU0_SB_DQ<28>")
	)
	(arc
		(start 390.37768 -292.228524)
		(mid 390.559931 -292.278874)
		(end 390.74344 -292.23335)
		(width 0.0889)
		(layer "In11.Cu")
		(net "M_L_CPU0_SB_DQ<28>")
	)
	(arc
		(start 392.540236 -292.71595)
		(mid 392.581785 -292.887372)
		(end 392.697208 -293.02075)
		(width 0.0889)
		(layer "In11.Cu")
		(net "M_L_CPU0_SB_DQ<28>")
	)
	(arc
		(start 388.506208 -292.23335)
		(mid 388.689716 -292.278844)
		(end 388.871968 -292.228524)
		(width 0.0889)
		(layer "In11.Cu")
		(net "M_L_CPU0_SB_DQ<28>")
	)
	(arc
		(start 392.766804 -293.06139)
		(mid 392.945617 -293.26374)
		(end 393.010136 -293.525956)
		(width 0.0889)
		(layer "In11.Cu")
		(net "M_L_CPU0_SB_DQ<28>")
	)
	(segment
		(start 385.39801 -290.019994)
		(end 385.864862 -290.285932)
		(width 0.10668)
		(layer "F.Cu")
		(net "M_L_CPU0_SB_DQ<27>")
	)
	(segment
		(start 396.962376 -299.76318)
		(end 407.025602 -309.826406)
		(width 0.14478)
		(layer "In11.Cu")
		(net "M_L_CPU0_SB_DQ<27>")
	)
	(segment
		(start 408.735276 -310.478932)
		(end 408.735276 -310.709564)
		(width 0.14478)
		(layer "In11.Cu")
		(net "M_L_CPU0_SB_DQ<27>")
	)
	(segment
		(start 407.813002 -310.613806)
		(end 408.043634 -310.613806)
		(width 0.14478)
		(layer "In11.Cu")
		(net "M_L_CPU0_SB_DQ<27>")
	)
	(segment
		(start 393.871958 -291.049456)
		(end 394.447268 -292.438582)
		(width 0.0889)
		(layer "In11.Cu")
		(net "M_L_CPU0_SB_DQ<27>")
	)
	(segment
		(start 440.943746 -311.650634)
		(end 441.793376 -312.500264)
		(width 0.14478)
		(layer "In11.Cu")
		(net "M_L_CPU0_SB_DQ<27>")
	)
	(segment
		(start 395.200378 -292.871652)
		(end 395.806676 -293.47795)
		(width 0.0889)
		(layer "In11.Cu")
		(net "M_L_CPU0_SB_DQ<27>")
	)
	(segment
		(start 409.224734 -312.025538)
		(end 409.709366 -312.51017)
		(width 0.14478)
		(layer "In11.Cu")
		(net "M_L_CPU0_SB_DQ<27>")
	)
	(segment
		(start 407.784808 -309.528464)
		(end 407.947876 -309.691532)
		(width 0.14478)
		(layer "In11.Cu")
		(net "M_L_CPU0_SB_DQ<27>")
	)
	(segment
		(start 408.735276 -310.709564)
		(end 408.437334 -311.007506)
		(width 0.14478)
		(layer "In11.Cu")
		(net "M_L_CPU0_SB_DQ<27>")
	)
	(segment
		(start 437.369712 -311.650634)
		(end 440.943746 -311.650634)
		(width 0.14478)
		(layer "In11.Cu")
		(net "M_L_CPU0_SB_DQ<27>")
	)
	(segment
		(start 395.806676 -293.47795)
		(end 396.962376 -294.63365)
		(width 0.14478)
		(layer "In11.Cu")
		(net "M_L_CPU0_SB_DQ<27>")
	)
	(segment
		(start 408.831034 -311.401206)
		(end 409.128976 -311.103264)
		(width 0.14478)
		(layer "In11.Cu")
		(net "M_L_CPU0_SB_DQ<27>")
	)
	(segment
		(start 449.65366 -311.650634)
		(end 450.088 -312.084974)
		(width 0.14478)
		(layer "In11.Cu")
		(net "M_L_CPU0_SB_DQ<27>")
	)
	(segment
		(start 414.75533 -311.650634)
		(end 418.26434 -311.650634)
		(width 0.14478)
		(layer "In11.Cu")
		(net "M_L_CPU0_SB_DQ<27>")
	)
	(segment
		(start 409.709366 -312.51017)
		(end 413.895794 -312.51017)
		(width 0.14478)
		(layer "In11.Cu")
		(net "M_L_CPU0_SB_DQ<27>")
	)
	(segment
		(start 421.449246 -312.500772)
		(end 422.299384 -311.650634)
		(width 0.14478)
		(layer "In11.Cu")
		(net "M_L_CPU0_SB_DQ<27>")
	)
	(segment
		(start 394.880338 -292.871652)
		(end 395.200378 -292.871652)
		(width 0.0889)
		(layer "In11.Cu")
		(net "M_L_CPU0_SB_DQ<27>")
	)
	(segment
		(start 393.871958 -290.245292)
		(end 393.871958 -291.049456)
		(width 0.0889)
		(layer "In11.Cu")
		(net "M_L_CPU0_SB_DQ<27>")
	)
	(segment
		(start 390.74344 -289.958526)
		(end 390.751822 -289.963352)
		(width 0.0889)
		(layer "In11.Cu")
		(net "M_L_CPU0_SB_DQ<27>")
	)
	(segment
		(start 408.341576 -310.315864)
		(end 408.572208 -310.315864)
		(width 0.14478)
		(layer "In11.Cu")
		(net "M_L_CPU0_SB_DQ<27>")
	)
	(segment
		(start 409.522676 -311.496964)
		(end 409.224734 -311.794906)
		(width 0.14478)
		(layer "In11.Cu")
		(net "M_L_CPU0_SB_DQ<27>")
	)
	(segment
		(start 409.522676 -311.266332)
		(end 409.522676 -311.496964)
		(width 0.14478)
		(layer "In11.Cu")
		(net "M_L_CPU0_SB_DQ<27>")
	)
	(segment
		(start 413.895794 -312.51017)
		(end 414.75533 -311.650634)
		(width 0.14478)
		(layer "In11.Cu")
		(net "M_L_CPU0_SB_DQ<27>")
	)
	(segment
		(start 436.519828 -312.500518)
		(end 437.369712 -311.650634)
		(width 0.14478)
		(layer "In11.Cu")
		(net "M_L_CPU0_SB_DQ<27>")
	)
	(segment
		(start 418.26434 -311.650634)
		(end 419.114478 -312.500772)
		(width 0.14478)
		(layer "In11.Cu")
		(net "M_L_CPU0_SB_DQ<27>")
	)
	(segment
		(start 407.025602 -309.826406)
		(end 407.256234 -309.826406)
		(width 0.14478)
		(layer "In11.Cu")
		(net "M_L_CPU0_SB_DQ<27>")
	)
	(segment
		(start 393.539472 -289.912806)
		(end 393.871958 -290.245292)
		(width 0.0889)
		(layer "In11.Cu")
		(net "M_L_CPU0_SB_DQ<27>")
	)
	(segment
		(start 407.256234 -309.826406)
		(end 407.554176 -309.528464)
		(width 0.14478)
		(layer "In11.Cu")
		(net "M_L_CPU0_SB_DQ<27>")
	)
	(segment
		(start 391.691876 -289.963352)
		(end 391.70229 -289.969448)
		(width 0.0889)
		(layer "In11.Cu")
		(net "M_L_CPU0_SB_DQ<27>")
	)
	(segment
		(start 419.114478 -312.500772)
		(end 421.449246 -312.500772)
		(width 0.14478)
		(layer "In11.Cu")
		(net "M_L_CPU0_SB_DQ<27>")
	)
	(segment
		(start 407.554176 -309.528464)
		(end 407.784808 -309.528464)
		(width 0.14478)
		(layer "In11.Cu")
		(net "M_L_CPU0_SB_DQ<27>")
	)
	(segment
		(start 409.359608 -311.103264)
		(end 409.522676 -311.266332)
		(width 0.14478)
		(layer "In11.Cu")
		(net "M_L_CPU0_SB_DQ<27>")
	)
	(segment
		(start 388.497826 -289.963352)
		(end 388.506208 -289.958526)
		(width 0.0889)
		(layer "In11.Cu")
		(net "M_L_CPU0_SB_DQ<27>")
	)
	(segment
		(start 407.947876 -309.691532)
		(end 407.947876 -309.922164)
		(width 0.14478)
		(layer "In11.Cu")
		(net "M_L_CPU0_SB_DQ<27>")
	)
	(segment
		(start 387.557772 -289.963352)
		(end 387.566154 -289.958526)
		(width 0.0889)
		(layer "In11.Cu")
		(net "M_L_CPU0_SB_DQ<27>")
	)
	(segment
		(start 409.128976 -311.103264)
		(end 409.359608 -311.103264)
		(width 0.14478)
		(layer "In11.Cu")
		(net "M_L_CPU0_SB_DQ<27>")
	)
	(segment
		(start 429.825658 -311.650634)
		(end 433.239164 -311.650634)
		(width 0.14478)
		(layer "In11.Cu")
		(net "M_L_CPU0_SB_DQ<27>")
	)
	(segment
		(start 428.975774 -312.500518)
		(end 429.825658 -311.650634)
		(width 0.14478)
		(layer "In11.Cu")
		(net "M_L_CPU0_SB_DQ<27>")
	)
	(segment
		(start 407.649934 -310.450738)
		(end 407.813002 -310.613806)
		(width 0.14478)
		(layer "In11.Cu")
		(net "M_L_CPU0_SB_DQ<27>")
	)
	(segment
		(start 444.973964 -311.650634)
		(end 449.65366 -311.650634)
		(width 0.14478)
		(layer "In11.Cu")
		(net "M_L_CPU0_SB_DQ<27>")
	)
	(segment
		(start 426.448474 -312.500518)
		(end 428.975774 -312.500518)
		(width 0.14478)
		(layer "In11.Cu")
		(net "M_L_CPU0_SB_DQ<27>")
	)
	(segment
		(start 391.317734 -289.963352)
		(end 391.326116 -289.958526)
		(width 0.0889)
		(layer "In11.Cu")
		(net "M_L_CPU0_SB_DQ<27>")
	)
	(segment
		(start 396.962376 -294.63365)
		(end 396.962376 -299.76318)
		(width 0.14478)
		(layer "In11.Cu")
		(net "M_L_CPU0_SB_DQ<27>")
	)
	(segment
		(start 408.600402 -311.401206)
		(end 408.831034 -311.401206)
		(width 0.14478)
		(layer "In11.Cu")
		(net "M_L_CPU0_SB_DQ<27>")
	)
	(segment
		(start 408.043634 -310.613806)
		(end 408.341576 -310.315864)
		(width 0.14478)
		(layer "In11.Cu")
		(net "M_L_CPU0_SB_DQ<27>")
	)
	(segment
		(start 408.572208 -310.315864)
		(end 408.735276 -310.478932)
		(width 0.14478)
		(layer "In11.Cu")
		(net "M_L_CPU0_SB_DQ<27>")
	)
	(segment
		(start 425.59859 -311.650634)
		(end 426.448474 -312.500518)
		(width 0.14478)
		(layer "In11.Cu")
		(net "M_L_CPU0_SB_DQ<27>")
	)
	(segment
		(start 394.447268 -292.438582)
		(end 394.880338 -292.871652)
		(width 0.0889)
		(layer "In11.Cu")
		(net "M_L_CPU0_SB_DQ<27>")
	)
	(segment
		(start 441.793376 -312.500264)
		(end 444.124334 -312.500264)
		(width 0.14478)
		(layer "In11.Cu")
		(net "M_L_CPU0_SB_DQ<27>")
	)
	(segment
		(start 385.864862 -290.285932)
		(end 386.018786 -290.020502)
		(width 0.0889)
		(layer "In11.Cu")
		(net "M_L_CPU0_SB_DQ<27>")
	)
	(segment
		(start 433.239164 -311.650634)
		(end 434.089048 -312.500518)
		(width 0.14478)
		(layer "In11.Cu")
		(net "M_L_CPU0_SB_DQ<27>")
	)
	(segment
		(start 422.299384 -311.650634)
		(end 425.59859 -311.650634)
		(width 0.14478)
		(layer "In11.Cu")
		(net "M_L_CPU0_SB_DQ<27>")
	)
	(segment
		(start 392.444986 -289.912806)
		(end 393.539472 -289.912806)
		(width 0.0889)
		(layer "In11.Cu")
		(net "M_L_CPU0_SB_DQ<27>")
	)
	(segment
		(start 409.224734 -311.794906)
		(end 409.224734 -312.025538)
		(width 0.14478)
		(layer "In11.Cu")
		(net "M_L_CPU0_SB_DQ<27>")
	)
	(segment
		(start 408.437334 -311.238138)
		(end 408.600402 -311.401206)
		(width 0.14478)
		(layer "In11.Cu")
		(net "M_L_CPU0_SB_DQ<27>")
	)
	(segment
		(start 386.983478 -289.958526)
		(end 386.99186 -289.963352)
		(width 0.0889)
		(layer "In11.Cu")
		(net "M_L_CPU0_SB_DQ<27>")
	)
	(segment
		(start 444.124334 -312.500264)
		(end 444.973964 -311.650634)
		(width 0.14478)
		(layer "In11.Cu")
		(net "M_L_CPU0_SB_DQ<27>")
	)
	(segment
		(start 407.649934 -310.220106)
		(end 407.649934 -310.450738)
		(width 0.14478)
		(layer "In11.Cu")
		(net "M_L_CPU0_SB_DQ<27>")
	)
	(segment
		(start 386.018786 -290.020502)
		(end 386.114798 -289.995102)
		(width 0.0889)
		(layer "In11.Cu")
		(net "M_L_CPU0_SB_DQ<27>")
	)
	(segment
		(start 434.089048 -312.500518)
		(end 436.519828 -312.500518)
		(width 0.14478)
		(layer "In11.Cu")
		(net "M_L_CPU0_SB_DQ<27>")
	)
	(segment
		(start 407.947876 -309.922164)
		(end 407.649934 -310.220106)
		(width 0.14478)
		(layer "In11.Cu")
		(net "M_L_CPU0_SB_DQ<27>")
	)
	(segment
		(start 408.437334 -311.007506)
		(end 408.437334 -311.238138)
		(width 0.14478)
		(layer "In11.Cu")
		(net "M_L_CPU0_SB_DQ<27>")
	)
	(arc
		(start 387.566154 -289.958526)
		(mid 387.749662 -289.913032)
		(end 387.931914 -289.963352)
		(width 0.0889)
		(layer "In11.Cu")
		(net "M_L_CPU0_SB_DQ<27>")
	)
	(arc
		(start 389.811768 -289.963352)
		(mid 390.094724 -290.039529)
		(end 390.37768 -289.963352)
		(width 0.0889)
		(layer "In11.Cu")
		(net "M_L_CPU0_SB_DQ<27>")
	)
	(arc
		(start 390.751822 -289.963352)
		(mid 391.034778 -290.039529)
		(end 391.317734 -289.963352)
		(width 0.0889)
		(layer "In11.Cu")
		(net "M_L_CPU0_SB_DQ<27>")
	)
	(arc
		(start 388.506208 -289.958526)
		(mid 388.689716 -289.913032)
		(end 388.871968 -289.963352)
		(width 0.0889)
		(layer "In11.Cu")
		(net "M_L_CPU0_SB_DQ<27>")
	)
	(arc
		(start 387.931914 -289.963352)
		(mid 388.21487 -290.039529)
		(end 388.497826 -289.963352)
		(width 0.0889)
		(layer "In11.Cu")
		(net "M_L_CPU0_SB_DQ<27>")
	)
	(arc
		(start 391.326116 -289.958526)
		(mid 391.509624 -289.913032)
		(end 391.691876 -289.963352)
		(width 0.0889)
		(layer "In11.Cu")
		(net "M_L_CPU0_SB_DQ<27>")
	)
	(arc
		(start 391.70229 -289.969448)
		(mid 391.980976 -290.039668)
		(end 392.258042 -289.963352)
		(width 0.0889)
		(layer "In11.Cu")
		(net "M_L_CPU0_SB_DQ<27>")
	)
	(arc
		(start 386.114798 -289.995102)
		(mid 386.370006 -290.038579)
		(end 386.617718 -289.963352)
		(width 0.0889)
		(layer "In11.Cu")
		(net "M_L_CPU0_SB_DQ<27>")
	)
	(arc
		(start 386.99186 -289.963352)
		(mid 387.274816 -290.039529)
		(end 387.557772 -289.963352)
		(width 0.0889)
		(layer "In11.Cu")
		(net "M_L_CPU0_SB_DQ<27>")
	)
	(arc
		(start 386.617718 -289.963352)
		(mid 386.799969 -289.913002)
		(end 386.983478 -289.958526)
		(width 0.0889)
		(layer "In11.Cu")
		(net "M_L_CPU0_SB_DQ<27>")
	)
	(arc
		(start 392.258042 -289.963352)
		(mid 392.34816 -289.925677)
		(end 392.444986 -289.912806)
		(width 0.0889)
		(layer "In11.Cu")
		(net "M_L_CPU0_SB_DQ<27>")
	)
	(arc
		(start 389.43788 -289.963352)
		(mid 389.624824 -289.913097)
		(end 389.811768 -289.963352)
		(width 0.0889)
		(layer "In11.Cu")
		(net "M_L_CPU0_SB_DQ<27>")
	)
	(arc
		(start 390.37768 -289.963352)
		(mid 390.559931 -289.913002)
		(end 390.74344 -289.958526)
		(width 0.0889)
		(layer "In11.Cu")
		(net "M_L_CPU0_SB_DQ<27>")
	)
	(arc
		(start 388.871968 -289.963352)
		(mid 389.154924 -290.039529)
		(end 389.43788 -289.963352)
		(width 0.0889)
		(layer "In11.Cu")
		(net "M_L_CPU0_SB_DQ<27>")
	)
	(segment
		(start 386.807964 -289.209988)
		(end 387.274816 -289.475926)
		(width 0.10668)
		(layer "F.Cu")
		(net "M_L_CPU0_SB_DQ<26>")
	)
	(segment
		(start 426.516546 -310.810148)
		(end 429.177958 -310.810148)
		(width 0.14478)
		(layer "In11.Cu")
		(net "M_L_CPU0_SB_DQ<26>")
	)
	(segment
		(start 394.866368 -291.771832)
		(end 395.387322 -291.771832)
		(width 0.0889)
		(layer "In11.Cu")
		(net "M_L_CPU0_SB_DQ<26>")
	)
	(segment
		(start 395.387322 -291.771832)
		(end 395.855952 -292.240462)
		(width 0.0889)
		(layer "In11.Cu")
		(net "M_L_CPU0_SB_DQ<26>")
	)
	(segment
		(start 436.722012 -310.810148)
		(end 437.57215 -309.96001)
		(width 0.14478)
		(layer "In11.Cu")
		(net "M_L_CPU0_SB_DQ<26>")
	)
	(segment
		(start 404.16607 -304.794158)
		(end 404.396702 -304.794158)
		(width 0.14478)
		(layer "In11.Cu")
		(net "M_L_CPU0_SB_DQ<26>")
	)
	(segment
		(start 405.969978 -307.484018)
		(end 406.20061 -307.484018)
		(width 0.14478)
		(layer "In11.Cu")
		(net "M_L_CPU0_SB_DQ<26>")
	)
	(segment
		(start 393.445238 -289.229292)
		(end 394.329158 -290.113212)
		(width 0.0889)
		(layer "In11.Cu")
		(net "M_L_CPU0_SB_DQ<26>")
	)
	(segment
		(start 444.168784 -310.809894)
		(end 445.018668 -309.96001)
		(width 0.14478)
		(layer "In11.Cu")
		(net "M_L_CPU0_SB_DQ<26>")
	)
	(segment
		(start 404.396702 -304.794158)
		(end 404.55977 -304.957226)
		(width 0.14478)
		(layer "In11.Cu")
		(net "M_L_CPU0_SB_DQ<26>")
	)
	(segment
		(start 404.395178 -305.909218)
		(end 404.62581 -305.909218)
		(width 0.14478)
		(layer "In11.Cu")
		(net "M_L_CPU0_SB_DQ<26>")
	)
	(segment
		(start 414.91408 -309.96001)
		(end 418.273738 -309.96001)
		(width 0.14478)
		(layer "In11.Cu")
		(net "M_L_CPU0_SB_DQ<26>")
	)
	(segment
		(start 405.182578 -306.696618)
		(end 405.41321 -306.696618)
		(width 0.14478)
		(layer "In11.Cu")
		(net "M_L_CPU0_SB_DQ<26>")
	)
	(segment
		(start 421.633904 -310.810148)
		(end 422.484042 -309.96001)
		(width 0.14478)
		(layer "In11.Cu")
		(net "M_L_CPU0_SB_DQ<26>")
	)
	(segment
		(start 406.92197 -307.550058)
		(end 406.59431 -307.877718)
		(width 0.14478)
		(layer "In11.Cu")
		(net "M_L_CPU0_SB_DQ<26>")
	)
	(segment
		(start 404.62581 -305.909218)
		(end 404.95347 -305.581558)
		(width 0.14478)
		(layer "In11.Cu")
		(net "M_L_CPU0_SB_DQ<26>")
	)
	(segment
		(start 448.733672 -309.64251)
		(end 448.972686 -309.64251)
		(width 0.14478)
		(layer "In11.Cu")
		(net "M_L_CPU0_SB_DQ<26>")
	)
	(segment
		(start 448.972686 -309.64251)
		(end 449.290186 -309.96001)
		(width 0.14478)
		(layer "In11.Cu")
		(net "M_L_CPU0_SB_DQ<26>")
	)
	(segment
		(start 392.443716 -289.229292)
		(end 393.445238 -289.229292)
		(width 0.0889)
		(layer "In11.Cu")
		(net "M_L_CPU0_SB_DQ<26>")
	)
	(segment
		(start 448.416172 -309.96001)
		(end 448.733672 -309.64251)
		(width 0.14478)
		(layer "In11.Cu")
		(net "M_L_CPU0_SB_DQ<26>")
	)
	(segment
		(start 440.754516 -309.96001)
		(end 441.6044 -310.809894)
		(width 0.14478)
		(layer "In11.Cu")
		(net "M_L_CPU0_SB_DQ<26>")
	)
	(segment
		(start 394.329158 -291.112194)
		(end 394.415772 -291.321236)
		(width 0.0889)
		(layer "In11.Cu")
		(net "M_L_CPU0_SB_DQ<26>")
	)
	(segment
		(start 406.92197 -307.319426)
		(end 406.92197 -307.550058)
		(width 0.14478)
		(layer "In11.Cu")
		(net "M_L_CPU0_SB_DQ<26>")
	)
	(segment
		(start 405.80691 -307.090318)
		(end 405.80691 -307.32095)
		(width 0.14478)
		(layer "In11.Cu")
		(net "M_L_CPU0_SB_DQ<26>")
	)
	(segment
		(start 392.145266 -289.144202)
		(end 392.161522 -289.1536)
		(width 0.0889)
		(layer "In11.Cu")
		(net "M_L_CPU0_SB_DQ<26>")
	)
	(segment
		(start 449.663058 -309.96001)
		(end 450.088 -310.384952)
		(width 0.14478)
		(layer "In11.Cu")
		(net "M_L_CPU0_SB_DQ<26>")
	)
	(segment
		(start 447.859658 -309.64251)
		(end 448.177158 -309.96001)
		(width 0.14478)
		(layer "In11.Cu")
		(net "M_L_CPU0_SB_DQ<26>")
	)
	(segment
		(start 406.758902 -307.156358)
		(end 406.92197 -307.319426)
		(width 0.14478)
		(layer "In11.Cu")
		(net "M_L_CPU0_SB_DQ<26>")
	)
	(segment
		(start 403.607778 -305.121818)
		(end 403.83841 -305.121818)
		(width 0.14478)
		(layer "In11.Cu")
		(net "M_L_CPU0_SB_DQ<26>")
	)
	(segment
		(start 434.0606 -310.810148)
		(end 436.722012 -310.810148)
		(width 0.14478)
		(layer "In11.Cu")
		(net "M_L_CPU0_SB_DQ<26>")
	)
	(segment
		(start 448.177158 -309.96001)
		(end 448.416172 -309.96001)
		(width 0.14478)
		(layer "In11.Cu")
		(net "M_L_CPU0_SB_DQ<26>")
	)
	(segment
		(start 406.59431 -308.10835)
		(end 406.757378 -308.271418)
		(width 0.14478)
		(layer "In11.Cu")
		(net "M_L_CPU0_SB_DQ<26>")
	)
	(segment
		(start 405.34717 -305.975258)
		(end 405.01951 -306.302918)
		(width 0.14478)
		(layer "In11.Cu")
		(net "M_L_CPU0_SB_DQ<26>")
	)
	(segment
		(start 406.757378 -308.271418)
		(end 406.98801 -308.271418)
		(width 0.14478)
		(layer "In11.Cu")
		(net "M_L_CPU0_SB_DQ<26>")
	)
	(segment
		(start 449.290186 -309.96001)
		(end 449.663058 -309.96001)
		(width 0.14478)
		(layer "In11.Cu")
		(net "M_L_CPU0_SB_DQ<26>")
	)
	(segment
		(start 406.20061 -307.484018)
		(end 406.52827 -307.156358)
		(width 0.14478)
		(layer "In11.Cu")
		(net "M_L_CPU0_SB_DQ<26>")
	)
	(segment
		(start 433.210462 -309.96001)
		(end 434.0606 -310.810148)
		(width 0.14478)
		(layer "In11.Cu")
		(net "M_L_CPU0_SB_DQ<26>")
	)
	(segment
		(start 394.415772 -291.321236)
		(end 394.866368 -291.771832)
		(width 0.0889)
		(layer "In11.Cu")
		(net "M_L_CPU0_SB_DQ<26>")
	)
	(segment
		(start 407.31567 -307.943758)
		(end 407.546302 -307.943758)
		(width 0.14478)
		(layer "In11.Cu")
		(net "M_L_CPU0_SB_DQ<26>")
	)
	(segment
		(start 445.018668 -309.96001)
		(end 447.303144 -309.96001)
		(width 0.14478)
		(layer "In11.Cu")
		(net "M_L_CPU0_SB_DQ<26>")
	)
	(segment
		(start 404.23211 -305.74615)
		(end 404.395178 -305.909218)
		(width 0.14478)
		(layer "In11.Cu")
		(net "M_L_CPU0_SB_DQ<26>")
	)
	(segment
		(start 447.303144 -309.96001)
		(end 447.620644 -309.64251)
		(width 0.14478)
		(layer "In11.Cu")
		(net "M_L_CPU0_SB_DQ<26>")
	)
	(segment
		(start 405.41321 -306.696618)
		(end 405.74087 -306.368958)
		(width 0.14478)
		(layer "In11.Cu")
		(net "M_L_CPU0_SB_DQ<26>")
	)
	(segment
		(start 403.83841 -305.121818)
		(end 404.16607 -304.794158)
		(width 0.14478)
		(layer "In11.Cu")
		(net "M_L_CPU0_SB_DQ<26>")
	)
	(segment
		(start 405.971502 -306.368958)
		(end 406.13457 -306.532026)
		(width 0.14478)
		(layer "In11.Cu")
		(net "M_L_CPU0_SB_DQ<26>")
	)
	(segment
		(start 404.55977 -305.187858)
		(end 404.23211 -305.515518)
		(width 0.14478)
		(layer "In11.Cu")
		(net "M_L_CPU0_SB_DQ<26>")
	)
	(segment
		(start 387.274816 -289.475926)
		(end 387.42874 -289.210496)
		(width 0.0889)
		(layer "In11.Cu")
		(net "M_L_CPU0_SB_DQ<26>")
	)
	(segment
		(start 437.57215 -309.96001)
		(end 440.754516 -309.96001)
		(width 0.14478)
		(layer "In11.Cu")
		(net "M_L_CPU0_SB_DQ<26>")
	)
	(segment
		(start 405.74087 -306.368958)
		(end 405.971502 -306.368958)
		(width 0.14478)
		(layer "In11.Cu")
		(net "M_L_CPU0_SB_DQ<26>")
	)
	(segment
		(start 414.063942 -310.810148)
		(end 414.91408 -309.96001)
		(width 0.14478)
		(layer "In11.Cu")
		(net "M_L_CPU0_SB_DQ<26>")
	)
	(segment
		(start 429.177958 -310.810148)
		(end 430.028096 -309.96001)
		(width 0.14478)
		(layer "In11.Cu")
		(net "M_L_CPU0_SB_DQ<26>")
	)
	(segment
		(start 405.01951 -306.302918)
		(end 405.01951 -306.53355)
		(width 0.14478)
		(layer "In11.Cu")
		(net "M_L_CPU0_SB_DQ<26>")
	)
	(segment
		(start 395.855952 -292.240462)
		(end 397.871696 -294.256206)
		(width 0.14478)
		(layer "In11.Cu")
		(net "M_L_CPU0_SB_DQ<26>")
	)
	(segment
		(start 406.59431 -307.877718)
		(end 406.59431 -308.10835)
		(width 0.14478)
		(layer "In11.Cu")
		(net "M_L_CPU0_SB_DQ<26>")
	)
	(segment
		(start 418.273738 -309.96001)
		(end 419.123876 -310.810148)
		(width 0.14478)
		(layer "In11.Cu")
		(net "M_L_CPU0_SB_DQ<26>")
	)
	(segment
		(start 419.123876 -310.810148)
		(end 421.633904 -310.810148)
		(width 0.14478)
		(layer "In11.Cu")
		(net "M_L_CPU0_SB_DQ<26>")
	)
	(segment
		(start 406.52827 -307.156358)
		(end 406.758902 -307.156358)
		(width 0.14478)
		(layer "In11.Cu")
		(net "M_L_CPU0_SB_DQ<26>")
	)
	(segment
		(start 397.871696 -299.385736)
		(end 403.607778 -305.121818)
		(width 0.14478)
		(layer "In11.Cu")
		(net "M_L_CPU0_SB_DQ<26>")
	)
	(segment
		(start 389.333486 -289.14852)
		(end 389.341868 -289.153346)
		(width 0.0889)
		(layer "In11.Cu")
		(net "M_L_CPU0_SB_DQ<26>")
	)
	(segment
		(start 405.34717 -305.744626)
		(end 405.34717 -305.975258)
		(width 0.14478)
		(layer "In11.Cu")
		(net "M_L_CPU0_SB_DQ<26>")
	)
	(segment
		(start 389.90778 -289.153346)
		(end 389.916162 -289.14852)
		(width 0.0889)
		(layer "In11.Cu")
		(net "M_L_CPU0_SB_DQ<26>")
	)
	(segment
		(start 388.393432 -289.14852)
		(end 388.401814 -289.153346)
		(width 0.0889)
		(layer "In11.Cu")
		(net "M_L_CPU0_SB_DQ<26>")
	)
	(segment
		(start 404.95347 -305.581558)
		(end 405.184102 -305.581558)
		(width 0.14478)
		(layer "In11.Cu")
		(net "M_L_CPU0_SB_DQ<26>")
	)
	(segment
		(start 430.028096 -309.96001)
		(end 433.210462 -309.96001)
		(width 0.14478)
		(layer "In11.Cu")
		(net "M_L_CPU0_SB_DQ<26>")
	)
	(segment
		(start 406.13457 -306.762658)
		(end 405.80691 -307.090318)
		(width 0.14478)
		(layer "In11.Cu")
		(net "M_L_CPU0_SB_DQ<26>")
	)
	(segment
		(start 406.13457 -306.532026)
		(end 406.13457 -306.762658)
		(width 0.14478)
		(layer "In11.Cu")
		(net "M_L_CPU0_SB_DQ<26>")
	)
	(segment
		(start 410.412692 -310.810148)
		(end 414.063942 -310.810148)
		(width 0.14478)
		(layer "In11.Cu")
		(net "M_L_CPU0_SB_DQ<26>")
	)
	(segment
		(start 405.184102 -305.581558)
		(end 405.34717 -305.744626)
		(width 0.14478)
		(layer "In11.Cu")
		(net "M_L_CPU0_SB_DQ<26>")
	)
	(segment
		(start 406.98801 -308.271418)
		(end 407.31567 -307.943758)
		(width 0.14478)
		(layer "In11.Cu")
		(net "M_L_CPU0_SB_DQ<26>")
	)
	(segment
		(start 394.329158 -290.113212)
		(end 394.329158 -291.112194)
		(width 0.0889)
		(layer "In11.Cu")
		(net "M_L_CPU0_SB_DQ<26>")
	)
	(segment
		(start 387.42874 -289.210496)
		(end 387.524752 -289.185096)
		(width 0.0889)
		(layer "In11.Cu")
		(net "M_L_CPU0_SB_DQ<26>")
	)
	(segment
		(start 407.546302 -307.943758)
		(end 410.412692 -310.810148)
		(width 0.14478)
		(layer "In11.Cu")
		(net "M_L_CPU0_SB_DQ<26>")
	)
	(segment
		(start 441.6044 -310.809894)
		(end 444.168784 -310.809894)
		(width 0.14478)
		(layer "In11.Cu")
		(net "M_L_CPU0_SB_DQ<26>")
	)
	(segment
		(start 405.01951 -306.53355)
		(end 405.182578 -306.696618)
		(width 0.14478)
		(layer "In11.Cu")
		(net "M_L_CPU0_SB_DQ<26>")
	)
	(segment
		(start 404.23211 -305.515518)
		(end 404.23211 -305.74615)
		(width 0.14478)
		(layer "In11.Cu")
		(net "M_L_CPU0_SB_DQ<26>")
	)
	(segment
		(start 404.55977 -304.957226)
		(end 404.55977 -305.187858)
		(width 0.14478)
		(layer "In11.Cu")
		(net "M_L_CPU0_SB_DQ<26>")
	)
	(segment
		(start 405.80691 -307.32095)
		(end 405.969978 -307.484018)
		(width 0.14478)
		(layer "In11.Cu")
		(net "M_L_CPU0_SB_DQ<26>")
	)
	(segment
		(start 447.620644 -309.64251)
		(end 447.859658 -309.64251)
		(width 0.14478)
		(layer "In11.Cu")
		(net "M_L_CPU0_SB_DQ<26>")
	)
	(segment
		(start 425.666408 -309.96001)
		(end 426.516546 -310.810148)
		(width 0.14478)
		(layer "In11.Cu")
		(net "M_L_CPU0_SB_DQ<26>")
	)
	(segment
		(start 422.484042 -309.96001)
		(end 425.666408 -309.96001)
		(width 0.14478)
		(layer "In11.Cu")
		(net "M_L_CPU0_SB_DQ<26>")
	)
	(segment
		(start 397.871696 -294.256206)
		(end 397.871696 -299.385736)
		(width 0.14478)
		(layer "In11.Cu")
		(net "M_L_CPU0_SB_DQ<26>")
	)
	(arc
		(start 389.341868 -289.153346)
		(mid 389.624824 -289.229523)
		(end 389.90778 -289.153346)
		(width 0.0889)
		(layer "In11.Cu")
		(net "M_L_CPU0_SB_DQ<26>")
	)
	(arc
		(start 387.524752 -289.185096)
		(mid 387.77996 -289.228573)
		(end 388.027672 -289.153346)
		(width 0.0889)
		(layer "In11.Cu")
		(net "M_L_CPU0_SB_DQ<26>")
	)
	(arc
		(start 391.221722 -289.153346)
		(mid 391.504678 -289.229523)
		(end 391.787634 -289.153346)
		(width 0.0889)
		(layer "In11.Cu")
		(net "M_L_CPU0_SB_DQ<26>")
	)
	(arc
		(start 392.161522 -289.1536)
		(mid 392.297631 -289.210041)
		(end 392.443716 -289.229292)
		(width 0.0889)
		(layer "In11.Cu")
		(net "M_L_CPU0_SB_DQ<26>")
	)
	(arc
		(start 388.967726 -289.153346)
		(mid 389.149977 -289.102996)
		(end 389.333486 -289.14852)
		(width 0.0889)
		(layer "In11.Cu")
		(net "M_L_CPU0_SB_DQ<26>")
	)
	(arc
		(start 391.787634 -289.153346)
		(mid 391.965284 -289.103086)
		(end 392.145266 -289.144202)
		(width 0.0889)
		(layer "In11.Cu")
		(net "M_L_CPU0_SB_DQ<26>")
	)
	(arc
		(start 390.281922 -289.153346)
		(mid 390.564878 -289.229523)
		(end 390.847834 -289.153346)
		(width 0.0889)
		(layer "In11.Cu")
		(net "M_L_CPU0_SB_DQ<26>")
	)
	(arc
		(start 390.847834 -289.153346)
		(mid 391.034778 -289.103091)
		(end 391.221722 -289.153346)
		(width 0.0889)
		(layer "In11.Cu")
		(net "M_L_CPU0_SB_DQ<26>")
	)
	(arc
		(start 388.027672 -289.153346)
		(mid 388.209923 -289.102996)
		(end 388.393432 -289.14852)
		(width 0.0889)
		(layer "In11.Cu")
		(net "M_L_CPU0_SB_DQ<26>")
	)
	(arc
		(start 389.916162 -289.14852)
		(mid 390.09967 -289.103026)
		(end 390.281922 -289.153346)
		(width 0.0889)
		(layer "In11.Cu")
		(net "M_L_CPU0_SB_DQ<26>")
	)
	(arc
		(start 388.401814 -289.153346)
		(mid 388.68477 -289.229523)
		(end 388.967726 -289.153346)
		(width 0.0889)
		(layer "In11.Cu")
		(net "M_L_CPU0_SB_DQ<26>")
	)
	(segment
		(start 385.86791 -289.209988)
		(end 386.334762 -289.475926)
		(width 0.10668)
		(layer "F.Cu")
		(net "M_L_CPU0_SB_DQ<25>")
	)
	(segment
		(start 418.273738 -310.809894)
		(end 419.123876 -311.660032)
		(width 0.14478)
		(layer "In11.Cu")
		(net "M_L_CPU0_SB_DQ<25>")
	)
	(segment
		(start 425.700444 -310.810148)
		(end 426.550328 -311.660032)
		(width 0.14478)
		(layer "In11.Cu")
		(net "M_L_CPU0_SB_DQ<25>")
	)
	(segment
		(start 444.99149 -310.809894)
		(end 453.762872 -310.809894)
		(width 0.14478)
		(layer "In11.Cu")
		(net "M_L_CPU0_SB_DQ<25>")
	)
	(segment
		(start 407.68524 -308.726078)
		(end 410.619194 -311.660032)
		(width 0.14478)
		(layer "In11.Cu")
		(net "M_L_CPU0_SB_DQ<25>")
	)
	(segment
		(start 440.788552 -310.810148)
		(end 441.638182 -311.659778)
		(width 0.14478)
		(layer "In11.Cu")
		(net "M_L_CPU0_SB_DQ<25>")
	)
	(segment
		(start 429.064166 -311.660032)
		(end 429.91405 -310.810148)
		(width 0.14478)
		(layer "In11.Cu")
		(net "M_L_CPU0_SB_DQ<25>")
	)
	(segment
		(start 389.90778 -289.798506)
		(end 389.916162 -289.803332)
		(width 0.0889)
		(layer "In11.Cu")
		(net "M_L_CPU0_SB_DQ<25>")
	)
	(segment
		(start 414.91408 -310.809894)
		(end 418.273738 -310.809894)
		(width 0.14478)
		(layer "In11.Cu")
		(net "M_L_CPU0_SB_DQ<25>")
	)
	(segment
		(start 392.444986 -289.722306)
		(end 393.664186 -289.722306)
		(width 0.0889)
		(layer "In11.Cu")
		(net "M_L_CPU0_SB_DQ<25>")
	)
	(segment
		(start 441.638182 -311.659778)
		(end 444.141606 -311.659778)
		(width 0.14478)
		(layer "In11.Cu")
		(net "M_L_CPU0_SB_DQ<25>")
	)
	(segment
		(start 393.664186 -289.722306)
		(end 394.108178 -290.166298)
		(width 0.0889)
		(layer "In11.Cu")
		(net "M_L_CPU0_SB_DQ<25>")
	)
	(segment
		(start 386.180838 -289.741356)
		(end 386.20319 -289.824668)
		(width 0.0889)
		(layer "In11.Cu")
		(net "M_L_CPU0_SB_DQ<25>")
	)
	(segment
		(start 426.550328 -311.660032)
		(end 429.064166 -311.660032)
		(width 0.14478)
		(layer "In11.Cu")
		(net "M_L_CPU0_SB_DQ<25>")
	)
	(segment
		(start 395.823694 -292.851586)
		(end 397.417036 -294.444928)
		(width 0.14478)
		(layer "In11.Cu")
		(net "M_L_CPU0_SB_DQ<25>")
	)
	(segment
		(start 436.60822 -311.660032)
		(end 437.458104 -310.810148)
		(width 0.14478)
		(layer "In11.Cu")
		(net "M_L_CPU0_SB_DQ<25>")
	)
	(segment
		(start 437.458104 -310.810148)
		(end 440.788552 -310.810148)
		(width 0.14478)
		(layer "In11.Cu")
		(net "M_L_CPU0_SB_DQ<25>")
	)
	(segment
		(start 394.681964 -292.059614)
		(end 395.120622 -292.059614)
		(width 0.0889)
		(layer "In11.Cu")
		(net "M_L_CPU0_SB_DQ<25>")
	)
	(segment
		(start 395.120622 -292.059614)
		(end 395.434058 -292.37305)
		(width 0.0889)
		(layer "In11.Cu")
		(net "M_L_CPU0_SB_DQ<25>")
	)
	(segment
		(start 395.434058 -292.46195)
		(end 395.823694 -292.851586)
		(width 0.0889)
		(layer "In11.Cu")
		(net "M_L_CPU0_SB_DQ<25>")
	)
	(segment
		(start 421.520112 -311.660032)
		(end 422.369996 -310.810148)
		(width 0.14478)
		(layer "In11.Cu")
		(net "M_L_CPU0_SB_DQ<25>")
	)
	(segment
		(start 389.333486 -289.803332)
		(end 389.341868 -289.798506)
		(width 0.0889)
		(layer "In11.Cu")
		(net "M_L_CPU0_SB_DQ<25>")
	)
	(segment
		(start 394.108178 -291.076634)
		(end 394.397484 -291.775134)
		(width 0.0889)
		(layer "In11.Cu")
		(net "M_L_CPU0_SB_DQ<25>")
	)
	(segment
		(start 433.244498 -310.810148)
		(end 434.094382 -311.660032)
		(width 0.14478)
		(layer "In11.Cu")
		(net "M_L_CPU0_SB_DQ<25>")
	)
	(segment
		(start 419.123876 -311.660032)
		(end 421.520112 -311.660032)
		(width 0.14478)
		(layer "In11.Cu")
		(net "M_L_CPU0_SB_DQ<25>")
	)
	(segment
		(start 388.393432 -289.803332)
		(end 388.401814 -289.798506)
		(width 0.0889)
		(layer "In11.Cu")
		(net "M_L_CPU0_SB_DQ<25>")
	)
	(segment
		(start 444.141606 -311.659778)
		(end 444.99149 -310.809894)
		(width 0.14478)
		(layer "In11.Cu")
		(net "M_L_CPU0_SB_DQ<25>")
	)
	(segment
		(start 386.334762 -289.475926)
		(end 386.180838 -289.741356)
		(width 0.0889)
		(layer "In11.Cu")
		(net "M_L_CPU0_SB_DQ<25>")
	)
	(segment
		(start 397.417036 -299.574458)
		(end 406.568656 -308.726078)
		(width 0.14478)
		(layer "In11.Cu")
		(net "M_L_CPU0_SB_DQ<25>")
	)
	(segment
		(start 422.369996 -310.810148)
		(end 425.700444 -310.810148)
		(width 0.14478)
		(layer "In11.Cu")
		(net "M_L_CPU0_SB_DQ<25>")
	)
	(segment
		(start 394.397484 -291.775134)
		(end 394.681964 -292.059614)
		(width 0.0889)
		(layer "In11.Cu")
		(net "M_L_CPU0_SB_DQ<25>")
	)
	(segment
		(start 410.619194 -311.660032)
		(end 414.063942 -311.660032)
		(width 0.14478)
		(layer "In11.Cu")
		(net "M_L_CPU0_SB_DQ<25>")
	)
	(segment
		(start 453.762872 -310.809894)
		(end 454.188068 -311.23509)
		(width 0.14478)
		(layer "In11.Cu")
		(net "M_L_CPU0_SB_DQ<25>")
	)
	(segment
		(start 397.417036 -294.444928)
		(end 397.417036 -299.574458)
		(width 0.14478)
		(layer "In11.Cu")
		(net "M_L_CPU0_SB_DQ<25>")
	)
	(segment
		(start 406.568656 -308.726078)
		(end 407.68524 -308.726078)
		(width 0.14478)
		(layer "In11.Cu")
		(net "M_L_CPU0_SB_DQ<25>")
	)
	(segment
		(start 414.063942 -311.660032)
		(end 414.91408 -310.809894)
		(width 0.14478)
		(layer "In11.Cu")
		(net "M_L_CPU0_SB_DQ<25>")
	)
	(segment
		(start 434.094382 -311.660032)
		(end 436.60822 -311.660032)
		(width 0.14478)
		(layer "In11.Cu")
		(net "M_L_CPU0_SB_DQ<25>")
	)
	(segment
		(start 394.108178 -290.166298)
		(end 394.108178 -291.076634)
		(width 0.0889)
		(layer "In11.Cu")
		(net "M_L_CPU0_SB_DQ<25>")
	)
	(segment
		(start 429.91405 -310.810148)
		(end 433.244498 -310.810148)
		(width 0.14478)
		(layer "In11.Cu")
		(net "M_L_CPU0_SB_DQ<25>")
	)
	(segment
		(start 395.434058 -292.37305)
		(end 395.434058 -292.46195)
		(width 0.0889)
		(layer "In11.Cu")
		(net "M_L_CPU0_SB_DQ<25>")
	)
	(arc
		(start 390.847834 -289.798506)
		(mid 391.034778 -289.848761)
		(end 391.221722 -289.798506)
		(width 0.0889)
		(layer "In11.Cu")
		(net "M_L_CPU0_SB_DQ<25>")
	)
	(arc
		(start 386.20319 -289.824668)
		(mid 386.365522 -289.847486)
		(end 386.52196 -289.798506)
		(width 0.0889)
		(layer "In11.Cu")
		(net "M_L_CPU0_SB_DQ<25>")
	)
	(arc
		(start 386.52196 -289.798506)
		(mid 386.804916 -289.722329)
		(end 387.087872 -289.798506)
		(width 0.0889)
		(layer "In11.Cu")
		(net "M_L_CPU0_SB_DQ<25>")
	)
	(arc
		(start 388.027672 -289.798506)
		(mid 388.209923 -289.848856)
		(end 388.393432 -289.803332)
		(width 0.0889)
		(layer "In11.Cu")
		(net "M_L_CPU0_SB_DQ<25>")
	)
	(arc
		(start 391.787634 -289.798506)
		(mid 391.974832 -289.848888)
		(end 392.16203 -289.798506)
		(width 0.0889)
		(layer "In11.Cu")
		(net "M_L_CPU0_SB_DQ<25>")
	)
	(arc
		(start 389.916162 -289.803332)
		(mid 390.09967 -289.848826)
		(end 390.281922 -289.798506)
		(width 0.0889)
		(layer "In11.Cu")
		(net "M_L_CPU0_SB_DQ<25>")
	)
	(arc
		(start 390.281922 -289.798506)
		(mid 390.564878 -289.722329)
		(end 390.847834 -289.798506)
		(width 0.0889)
		(layer "In11.Cu")
		(net "M_L_CPU0_SB_DQ<25>")
	)
	(arc
		(start 387.087872 -289.798506)
		(mid 387.274816 -289.848761)
		(end 387.46176 -289.798506)
		(width 0.0889)
		(layer "In11.Cu")
		(net "M_L_CPU0_SB_DQ<25>")
	)
	(arc
		(start 388.401814 -289.798506)
		(mid 388.68477 -289.722329)
		(end 388.967726 -289.798506)
		(width 0.0889)
		(layer "In11.Cu")
		(net "M_L_CPU0_SB_DQ<25>")
	)
	(arc
		(start 387.46176 -289.798506)
		(mid 387.744716 -289.722329)
		(end 388.027672 -289.798506)
		(width 0.0889)
		(layer "In11.Cu")
		(net "M_L_CPU0_SB_DQ<25>")
	)
	(arc
		(start 389.341868 -289.798506)
		(mid 389.624824 -289.722329)
		(end 389.90778 -289.798506)
		(width 0.0889)
		(layer "In11.Cu")
		(net "M_L_CPU0_SB_DQ<25>")
	)
	(arc
		(start 392.16203 -289.798506)
		(mid 392.298451 -289.741627)
		(end 392.444986 -289.722306)
		(width 0.0889)
		(layer "In11.Cu")
		(net "M_L_CPU0_SB_DQ<25>")
	)
	(arc
		(start 388.967726 -289.798506)
		(mid 389.149977 -289.848856)
		(end 389.333486 -289.803332)
		(width 0.0889)
		(layer "In11.Cu")
		(net "M_L_CPU0_SB_DQ<25>")
	)
	(arc
		(start 391.221722 -289.798506)
		(mid 391.504678 -289.722329)
		(end 391.787634 -289.798506)
		(width 0.0889)
		(layer "In11.Cu")
		(net "M_L_CPU0_SB_DQ<25>")
	)
	(segment
		(start 387.277864 -288.399982)
		(end 387.744716 -288.66592)
		(width 0.10668)
		(layer "F.Cu")
		(net "M_L_CPU0_SB_DQ<24>")
	)
	(segment
		(start 436.814976 -309.96001)
		(end 433.995322 -309.96001)
		(width 0.14478)
		(layer "In11.Cu")
		(net "M_L_CPU0_SB_DQ<24>")
	)
	(segment
		(start 437.66486 -309.110126)
		(end 436.814976 -309.96001)
		(width 0.14478)
		(layer "In11.Cu")
		(net "M_L_CPU0_SB_DQ<24>")
	)
	(segment
		(start 394.575538 -290.029646)
		(end 393.584684 -289.038792)
		(width 0.0889)
		(layer "In11.Cu")
		(net "M_L_CPU0_SB_DQ<24>")
	)
	(segment
		(start 388.506208 -288.993326)
		(end 388.497826 -288.9885)
		(width 0.0889)
		(layer "In11.Cu")
		(net "M_L_CPU0_SB_DQ<24>")
	)
	(segment
		(start 390.751822 -288.9885)
		(end 390.74344 -288.993326)
		(width 0.0889)
		(layer "In11.Cu")
		(net "M_L_CPU0_SB_DQ<24>")
	)
	(segment
		(start 451.58152 -309.97271)
		(end 451.351142 -309.97271)
		(width 0.14478)
		(layer "In11.Cu")
		(net "M_L_CPU0_SB_DQ<24>")
	)
	(segment
		(start 441.53963 -309.959756)
		(end 441.539376 -309.96001)
		(width 0.14478)
		(layer "In11.Cu")
		(net "M_L_CPU0_SB_DQ<24>")
	)
	(segment
		(start 454.188068 -309.535068)
		(end 453.762872 -309.109872)
		(width 0.14478)
		(layer "In11.Cu")
		(net "M_L_CPU0_SB_DQ<24>")
	)
	(segment
		(start 395.817344 -291.558726)
		(end 395.45387 -291.195252)
		(width 0.0889)
		(layer "In11.Cu")
		(net "M_L_CPU0_SB_DQ<24>")
	)
	(segment
		(start 444.160402 -309.959756)
		(end 441.53963 -309.959756)
		(width 0.14478)
		(layer "In11.Cu")
		(net "M_L_CPU0_SB_DQ<24>")
	)
	(segment
		(start 440.689492 -309.110126)
		(end 437.66486 -309.110126)
		(width 0.14478)
		(layer "In11.Cu")
		(net "M_L_CPU0_SB_DQ<24>")
	)
	(segment
		(start 430.120806 -309.110126)
		(end 429.270922 -309.96001)
		(width 0.14478)
		(layer "In11.Cu")
		(net "M_L_CPU0_SB_DQ<24>")
	)
	(segment
		(start 391.326116 -288.993326)
		(end 391.317734 -288.9885)
		(width 0.0889)
		(layer "In11.Cu")
		(net "M_L_CPU0_SB_DQ<24>")
	)
	(segment
		(start 452.301102 -309.809642)
		(end 452.301102 -309.27294)
		(width 0.14478)
		(layer "In11.Cu")
		(net "M_L_CPU0_SB_DQ<24>")
	)
	(segment
		(start 422.576752 -309.110126)
		(end 421.726868 -309.96001)
		(width 0.14478)
		(layer "In11.Cu")
		(net "M_L_CPU0_SB_DQ<24>")
	)
	(segment
		(start 421.726868 -309.96001)
		(end 419.123876 -309.96001)
		(width 0.14478)
		(layer "In11.Cu")
		(net "M_L_CPU0_SB_DQ<24>")
	)
	(segment
		(start 419.123876 -309.96001)
		(end 418.273738 -309.109872)
		(width 0.14478)
		(layer "In11.Cu")
		(net "M_L_CPU0_SB_DQ<24>")
	)
	(segment
		(start 387.613144 -289.014662)
		(end 387.590792 -288.93135)
		(width 0.0889)
		(layer "In11.Cu")
		(net "M_L_CPU0_SB_DQ<24>")
	)
	(segment
		(start 452.694548 -309.97271)
		(end 452.46417 -309.97271)
		(width 0.14478)
		(layer "In11.Cu")
		(net "M_L_CPU0_SB_DQ<24>")
	)
	(segment
		(start 441.539376 -309.96001)
		(end 440.689492 -309.110126)
		(width 0.14478)
		(layer "In11.Cu")
		(net "M_L_CPU0_SB_DQ<24>")
	)
	(segment
		(start 451.025006 -309.109872)
		(end 445.010286 -309.109872)
		(width 0.14478)
		(layer "In11.Cu")
		(net "M_L_CPU0_SB_DQ<24>")
	)
	(segment
		(start 453.020684 -309.109872)
		(end 452.857616 -309.27294)
		(width 0.14478)
		(layer "In11.Cu")
		(net "M_L_CPU0_SB_DQ<24>")
	)
	(segment
		(start 395.45387 -291.195252)
		(end 394.773658 -291.195252)
		(width 0.0889)
		(layer "In11.Cu")
		(net "M_L_CPU0_SB_DQ<24>")
	)
	(segment
		(start 414.91408 -309.109872)
		(end 414.063942 -309.96001)
		(width 0.14478)
		(layer "In11.Cu")
		(net "M_L_CPU0_SB_DQ<24>")
	)
	(segment
		(start 452.138034 -309.109872)
		(end 451.907656 -309.109872)
		(width 0.14478)
		(layer "In11.Cu")
		(net "M_L_CPU0_SB_DQ<24>")
	)
	(segment
		(start 452.857616 -309.27294)
		(end 452.857616 -309.809642)
		(width 0.14478)
		(layer "In11.Cu")
		(net "M_L_CPU0_SB_DQ<24>")
	)
	(segment
		(start 451.188074 -309.809642)
		(end 451.188074 -309.27294)
		(width 0.14478)
		(layer "In11.Cu")
		(net "M_L_CPU0_SB_DQ<24>")
	)
	(segment
		(start 410.353002 -309.96001)
		(end 404.660608 -304.267616)
		(width 0.14478)
		(layer "In11.Cu")
		(net "M_L_CPU0_SB_DQ<24>")
	)
	(segment
		(start 429.270922 -309.96001)
		(end 426.451268 -309.96001)
		(width 0.14478)
		(layer "In11.Cu")
		(net "M_L_CPU0_SB_DQ<24>")
	)
	(segment
		(start 452.301102 -309.27294)
		(end 452.138034 -309.109872)
		(width 0.14478)
		(layer "In11.Cu")
		(net "M_L_CPU0_SB_DQ<24>")
	)
	(segment
		(start 451.188074 -309.27294)
		(end 451.025006 -309.109872)
		(width 0.14478)
		(layer "In11.Cu")
		(net "M_L_CPU0_SB_DQ<24>")
	)
	(segment
		(start 452.857616 -309.809642)
		(end 452.694548 -309.97271)
		(width 0.14478)
		(layer "In11.Cu")
		(net "M_L_CPU0_SB_DQ<24>")
	)
	(segment
		(start 425.601384 -309.110126)
		(end 422.576752 -309.110126)
		(width 0.14478)
		(layer "In11.Cu")
		(net "M_L_CPU0_SB_DQ<24>")
	)
	(segment
		(start 433.995322 -309.96001)
		(end 433.145438 -309.110126)
		(width 0.14478)
		(layer "In11.Cu")
		(net "M_L_CPU0_SB_DQ<24>")
	)
	(segment
		(start 445.010286 -309.109872)
		(end 444.160402 -309.959756)
		(width 0.14478)
		(layer "In11.Cu")
		(net "M_L_CPU0_SB_DQ<24>")
	)
	(segment
		(start 451.744588 -309.809642)
		(end 451.58152 -309.97271)
		(width 0.14478)
		(layer "In11.Cu")
		(net "M_L_CPU0_SB_DQ<24>")
	)
	(segment
		(start 387.590792 -288.93135)
		(end 387.744716 -288.66592)
		(width 0.0889)
		(layer "In11.Cu")
		(net "M_L_CPU0_SB_DQ<24>")
	)
	(segment
		(start 418.273738 -309.109872)
		(end 414.91408 -309.109872)
		(width 0.14478)
		(layer "In11.Cu")
		(net "M_L_CPU0_SB_DQ<24>")
	)
	(segment
		(start 394.575538 -290.997132)
		(end 394.575538 -290.029646)
		(width 0.0889)
		(layer "In11.Cu")
		(net "M_L_CPU0_SB_DQ<24>")
	)
	(segment
		(start 404.660608 -304.267616)
		(end 403.396704 -304.267616)
		(width 0.14478)
		(layer "In11.Cu")
		(net "M_L_CPU0_SB_DQ<24>")
	)
	(segment
		(start 398.326356 -299.197268)
		(end 398.326356 -294.067738)
		(width 0.14478)
		(layer "In11.Cu")
		(net "M_L_CPU0_SB_DQ<24>")
	)
	(segment
		(start 393.584684 -289.038792)
		(end 392.443716 -289.038792)
		(width 0.0889)
		(layer "In11.Cu")
		(net "M_L_CPU0_SB_DQ<24>")
	)
	(segment
		(start 451.744588 -309.27294)
		(end 451.744588 -309.809642)
		(width 0.14478)
		(layer "In11.Cu")
		(net "M_L_CPU0_SB_DQ<24>")
	)
	(segment
		(start 398.326356 -294.067738)
		(end 395.817344 -291.558726)
		(width 0.14478)
		(layer "In11.Cu")
		(net "M_L_CPU0_SB_DQ<24>")
	)
	(segment
		(start 433.145438 -309.110126)
		(end 430.120806 -309.110126)
		(width 0.14478)
		(layer "In11.Cu")
		(net "M_L_CPU0_SB_DQ<24>")
	)
	(segment
		(start 452.46417 -309.97271)
		(end 452.301102 -309.809642)
		(width 0.14478)
		(layer "In11.Cu")
		(net "M_L_CPU0_SB_DQ<24>")
	)
	(segment
		(start 426.451268 -309.96001)
		(end 425.601384 -309.110126)
		(width 0.14478)
		(layer "In11.Cu")
		(net "M_L_CPU0_SB_DQ<24>")
	)
	(segment
		(start 392.257026 -288.988246)
		(end 392.245088 -288.981388)
		(width 0.0889)
		(layer "In11.Cu")
		(net "M_L_CPU0_SB_DQ<24>")
	)
	(segment
		(start 403.396704 -304.267616)
		(end 398.326356 -299.197268)
		(width 0.14478)
		(layer "In11.Cu")
		(net "M_L_CPU0_SB_DQ<24>")
	)
	(segment
		(start 453.762872 -309.109872)
		(end 453.020684 -309.109872)
		(width 0.14478)
		(layer "In11.Cu")
		(net "M_L_CPU0_SB_DQ<24>")
	)
	(segment
		(start 451.907656 -309.109872)
		(end 451.744588 -309.27294)
		(width 0.14478)
		(layer "In11.Cu")
		(net "M_L_CPU0_SB_DQ<24>")
	)
	(segment
		(start 414.063942 -309.96001)
		(end 410.353002 -309.96001)
		(width 0.14478)
		(layer "In11.Cu")
		(net "M_L_CPU0_SB_DQ<24>")
	)
	(segment
		(start 394.773658 -291.195252)
		(end 394.575538 -290.997132)
		(width 0.0889)
		(layer "In11.Cu")
		(net "M_L_CPU0_SB_DQ<24>")
	)
	(segment
		(start 451.351142 -309.97271)
		(end 451.188074 -309.809642)
		(width 0.14478)
		(layer "In11.Cu")
		(net "M_L_CPU0_SB_DQ<24>")
	)
	(arc
		(start 392.443716 -289.038792)
		(mid 392.347036 -289.025836)
		(end 392.257026 -288.988246)
		(width 0.0889)
		(layer "In11.Cu")
		(net "M_L_CPU0_SB_DQ<24>")
	)
	(arc
		(start 388.871968 -288.9885)
		(mid 388.689717 -289.03885)
		(end 388.506208 -288.993326)
		(width 0.0889)
		(layer "In11.Cu")
		(net "M_L_CPU0_SB_DQ<24>")
	)
	(arc
		(start 391.317734 -288.9885)
		(mid 391.034778 -288.912323)
		(end 390.751822 -288.9885)
		(width 0.0889)
		(layer "In11.Cu")
		(net "M_L_CPU0_SB_DQ<24>")
	)
	(arc
		(start 390.37768 -288.9885)
		(mid 390.094724 -288.912323)
		(end 389.811768 -288.9885)
		(width 0.0889)
		(layer "In11.Cu")
		(net "M_L_CPU0_SB_DQ<24>")
	)
	(arc
		(start 390.74344 -288.993326)
		(mid 390.559932 -289.03882)
		(end 390.37768 -288.9885)
		(width 0.0889)
		(layer "In11.Cu")
		(net "M_L_CPU0_SB_DQ<24>")
	)
	(arc
		(start 388.497826 -288.9885)
		(mid 388.21487 -288.912323)
		(end 387.931914 -288.9885)
		(width 0.0889)
		(layer "In11.Cu")
		(net "M_L_CPU0_SB_DQ<24>")
	)
	(arc
		(start 389.811768 -288.9885)
		(mid 389.624824 -289.038755)
		(end 389.43788 -288.9885)
		(width 0.0889)
		(layer "In11.Cu")
		(net "M_L_CPU0_SB_DQ<24>")
	)
	(arc
		(start 387.931914 -288.9885)
		(mid 387.775476 -289.037471)
		(end 387.613144 -289.014662)
		(width 0.0889)
		(layer "In11.Cu")
		(net "M_L_CPU0_SB_DQ<24>")
	)
	(arc
		(start 389.43788 -288.9885)
		(mid 389.154924 -288.912323)
		(end 388.871968 -288.9885)
		(width 0.0889)
		(layer "In11.Cu")
		(net "M_L_CPU0_SB_DQ<24>")
	)
	(arc
		(start 391.691876 -288.9885)
		(mid 391.509625 -289.03885)
		(end 391.326116 -288.993326)
		(width 0.0889)
		(layer "In11.Cu")
		(net "M_L_CPU0_SB_DQ<24>")
	)
	(arc
		(start 392.245088 -288.981388)
		(mid 391.967554 -288.912407)
		(end 391.691876 -288.9885)
		(width 0.0889)
		(layer "In11.Cu")
		(net "M_L_CPU0_SB_DQ<24>")
	)
	(segment
		(start 385.39801 -288.399982)
		(end 385.864862 -288.66592)
		(width 0.10668)
		(layer "F.Cu")
		(net "M_L_CPU0_SB_DQ<23>")
	)
	(segment
		(start 393.887198 -288.561272)
		(end 393.887198 -288.995612)
		(width 0.0889)
		(layer "In11.Cu")
		(net "M_L_CPU0_SB_DQ<23>")
	)
	(segment
		(start 386.018786 -288.40049)
		(end 386.114544 -288.37509)
		(width 0.0889)
		(layer "In11.Cu")
		(net "M_L_CPU0_SB_DQ<23>")
	)
	(segment
		(start 393.887198 -288.995612)
		(end 394.722858 -289.831272)
		(width 0.0889)
		(layer "In11.Cu")
		(net "M_L_CPU0_SB_DQ<23>")
	)
	(segment
		(start 403.419564 -302.57496)
		(end 403.650196 -302.57496)
		(width 0.14478)
		(layer "In11.Cu")
		(net "M_L_CPU0_SB_DQ<23>")
	)
	(segment
		(start 448.87007 -308.115462)
		(end 449.01485 -308.260242)
		(width 0.14478)
		(layer "In11.Cu")
		(net "M_L_CPU0_SB_DQ<23>")
	)
	(segment
		(start 448.173856 -308.260242)
		(end 448.318636 -308.115462)
		(width 0.14478)
		(layer "In11.Cu")
		(net "M_L_CPU0_SB_DQ<23>")
	)
	(segment
		(start 444.10122 -309.109872)
		(end 444.95085 -308.260242)
		(width 0.14478)
		(layer "In11.Cu")
		(net "M_L_CPU0_SB_DQ<23>")
	)
	(segment
		(start 403.813518 -302.738282)
		(end 403.813264 -302.968406)
		(width 0.14478)
		(layer "In11.Cu")
		(net "M_L_CPU0_SB_DQ<23>")
	)
	(segment
		(start 448.87007 -308.012592)
		(end 448.87007 -308.115462)
		(width 0.14478)
		(layer "In11.Cu")
		(net "M_L_CPU0_SB_DQ<23>")
	)
	(segment
		(start 441.604146 -309.109872)
		(end 444.10122 -309.109872)
		(width 0.14478)
		(layer "In11.Cu")
		(net "M_L_CPU0_SB_DQ<23>")
	)
	(segment
		(start 419.061392 -309.11038)
		(end 421.633904 -309.11038)
		(width 0.14478)
		(layer "In11.Cu")
		(net "M_L_CPU0_SB_DQ<23>")
	)
	(segment
		(start 403.857968 -303.711356)
		(end 404.206964 -303.36236)
		(width 0.14478)
		(layer "In11.Cu")
		(net "M_L_CPU0_SB_DQ<23>")
	)
	(segment
		(start 403.813264 -302.968406)
		(end 403.464268 -303.317402)
		(width 0.14478)
		(layer "In11.Cu")
		(net "M_L_CPU0_SB_DQ<23>")
	)
	(segment
		(start 426.516546 -309.11038)
		(end 429.177958 -309.11038)
		(width 0.14478)
		(layer "In11.Cu")
		(net "M_L_CPU0_SB_DQ<23>")
	)
	(segment
		(start 449.01485 -308.260242)
		(end 449.663058 -308.260242)
		(width 0.14478)
		(layer "In11.Cu")
		(net "M_L_CPU0_SB_DQ<23>")
	)
	(segment
		(start 410.290264 -309.110126)
		(end 414.063942 -309.110126)
		(width 0.14478)
		(layer "In11.Cu")
		(net "M_L_CPU0_SB_DQ<23>")
	)
	(segment
		(start 430.028096 -308.260242)
		(end 433.210462 -308.260242)
		(width 0.14478)
		(layer "In11.Cu")
		(net "M_L_CPU0_SB_DQ<23>")
	)
	(segment
		(start 433.210462 -308.260242)
		(end 434.0606 -309.11038)
		(width 0.14478)
		(layer "In11.Cu")
		(net "M_L_CPU0_SB_DQ<23>")
	)
	(segment
		(start 390.74344 -288.338768)
		(end 390.751822 -288.343594)
		(width 0.0889)
		(layer "In11.Cu")
		(net "M_L_CPU0_SB_DQ<23>")
	)
	(segment
		(start 448.318636 -308.012592)
		(end 448.463416 -307.867812)
		(width 0.14478)
		(layer "In11.Cu")
		(net "M_L_CPU0_SB_DQ<23>")
	)
	(segment
		(start 394.722858 -289.831272)
		(end 394.87729 -289.831272)
		(width 0.0889)
		(layer "In11.Cu")
		(net "M_L_CPU0_SB_DQ<23>")
	)
	(segment
		(start 414.063942 -309.110126)
		(end 414.91408 -308.259988)
		(width 0.14478)
		(layer "In11.Cu")
		(net "M_L_CPU0_SB_DQ<23>")
	)
	(segment
		(start 402.839936 -302.923702)
		(end 403.070568 -302.923956)
		(width 0.14478)
		(layer "In11.Cu")
		(net "M_L_CPU0_SB_DQ<23>")
	)
	(segment
		(start 404.542498 -303.36236)
		(end 410.290264 -309.110126)
		(width 0.14478)
		(layer "In11.Cu")
		(net "M_L_CPU0_SB_DQ<23>")
	)
	(segment
		(start 388.497826 -288.343594)
		(end 388.506208 -288.338768)
		(width 0.0889)
		(layer "In11.Cu")
		(net "M_L_CPU0_SB_DQ<23>")
	)
	(segment
		(start 425.666408 -308.260242)
		(end 426.516546 -309.11038)
		(width 0.14478)
		(layer "In11.Cu")
		(net "M_L_CPU0_SB_DQ<23>")
	)
	(segment
		(start 403.464268 -303.317402)
		(end 403.464268 -303.548034)
		(width 0.14478)
		(layer "In11.Cu")
		(net "M_L_CPU0_SB_DQ<23>")
	)
	(segment
		(start 436.722012 -309.11038)
		(end 437.57215 -308.260242)
		(width 0.14478)
		(layer "In11.Cu")
		(net "M_L_CPU0_SB_DQ<23>")
	)
	(segment
		(start 448.72529 -307.867812)
		(end 448.87007 -308.012592)
		(width 0.14478)
		(layer "In11.Cu")
		(net "M_L_CPU0_SB_DQ<23>")
	)
	(segment
		(start 429.177958 -309.11038)
		(end 430.028096 -308.260242)
		(width 0.14478)
		(layer "In11.Cu")
		(net "M_L_CPU0_SB_DQ<23>")
	)
	(segment
		(start 403.464268 -303.548034)
		(end 403.627336 -303.711102)
		(width 0.14478)
		(layer "In11.Cu")
		(net "M_L_CPU0_SB_DQ<23>")
	)
	(segment
		(start 393.61999 -288.294064)
		(end 393.887198 -288.561272)
		(width 0.0889)
		(layer "In11.Cu")
		(net "M_L_CPU0_SB_DQ<23>")
	)
	(segment
		(start 403.627336 -303.711102)
		(end 403.857968 -303.711356)
		(width 0.14478)
		(layer "In11.Cu")
		(net "M_L_CPU0_SB_DQ<23>")
	)
	(segment
		(start 394.87729 -289.831272)
		(end 395.779752 -290.733734)
		(width 0.0889)
		(layer "In11.Cu")
		(net "M_L_CPU0_SB_DQ<23>")
	)
	(segment
		(start 403.070568 -302.923956)
		(end 403.419564 -302.57496)
		(width 0.14478)
		(layer "In11.Cu")
		(net "M_L_CPU0_SB_DQ<23>")
	)
	(segment
		(start 398.882616 -293.836598)
		(end 398.882616 -298.966382)
		(width 0.14478)
		(layer "In11.Cu")
		(net "M_L_CPU0_SB_DQ<23>")
	)
	(segment
		(start 437.57215 -308.260242)
		(end 440.754516 -308.260242)
		(width 0.14478)
		(layer "In11.Cu")
		(net "M_L_CPU0_SB_DQ<23>")
	)
	(segment
		(start 392.46937 -288.294064)
		(end 393.61999 -288.294064)
		(width 0.0889)
		(layer "In11.Cu")
		(net "M_L_CPU0_SB_DQ<23>")
	)
	(segment
		(start 391.317734 -288.343594)
		(end 391.326116 -288.338768)
		(width 0.0889)
		(layer "In11.Cu")
		(net "M_L_CPU0_SB_DQ<23>")
	)
	(segment
		(start 403.650196 -302.57496)
		(end 403.813518 -302.738282)
		(width 0.14478)
		(layer "In11.Cu")
		(net "M_L_CPU0_SB_DQ<23>")
	)
	(segment
		(start 421.633904 -309.11038)
		(end 422.484042 -308.260242)
		(width 0.14478)
		(layer "In11.Cu")
		(net "M_L_CPU0_SB_DQ<23>")
	)
	(segment
		(start 414.91408 -308.259988)
		(end 418.211 -308.259988)
		(width 0.14478)
		(layer "In11.Cu")
		(net "M_L_CPU0_SB_DQ<23>")
	)
	(segment
		(start 398.882616 -298.966382)
		(end 402.839936 -302.923702)
		(width 0.14478)
		(layer "In11.Cu")
		(net "M_L_CPU0_SB_DQ<23>")
	)
	(segment
		(start 386.983478 -288.338768)
		(end 386.99186 -288.343594)
		(width 0.0889)
		(layer "In11.Cu")
		(net "M_L_CPU0_SB_DQ<23>")
	)
	(segment
		(start 392.257788 -288.343594)
		(end 392.26617 -288.338768)
		(width 0.0889)
		(layer "In11.Cu")
		(net "M_L_CPU0_SB_DQ<23>")
	)
	(segment
		(start 422.484042 -308.260242)
		(end 425.666408 -308.260242)
		(width 0.14478)
		(layer "In11.Cu")
		(net "M_L_CPU0_SB_DQ<23>")
	)
	(segment
		(start 444.95085 -308.260242)
		(end 448.173856 -308.260242)
		(width 0.14478)
		(layer "In11.Cu")
		(net "M_L_CPU0_SB_DQ<23>")
	)
	(segment
		(start 434.0606 -309.11038)
		(end 436.722012 -309.11038)
		(width 0.14478)
		(layer "In11.Cu")
		(net "M_L_CPU0_SB_DQ<23>")
	)
	(segment
		(start 387.557772 -288.343594)
		(end 387.566154 -288.338768)
		(width 0.0889)
		(layer "In11.Cu")
		(net "M_L_CPU0_SB_DQ<23>")
	)
	(segment
		(start 448.318636 -308.115462)
		(end 448.318636 -308.012592)
		(width 0.14478)
		(layer "In11.Cu")
		(net "M_L_CPU0_SB_DQ<23>")
	)
	(segment
		(start 395.779752 -290.733734)
		(end 398.882616 -293.836598)
		(width 0.14478)
		(layer "In11.Cu")
		(net "M_L_CPU0_SB_DQ<23>")
	)
	(segment
		(start 385.864862 -288.66592)
		(end 386.018786 -288.40049)
		(width 0.0889)
		(layer "In11.Cu")
		(net "M_L_CPU0_SB_DQ<23>")
	)
	(segment
		(start 448.463416 -307.867812)
		(end 448.72529 -307.867812)
		(width 0.14478)
		(layer "In11.Cu")
		(net "M_L_CPU0_SB_DQ<23>")
	)
	(segment
		(start 418.211 -308.259988)
		(end 419.061392 -309.11038)
		(width 0.14478)
		(layer "In11.Cu")
		(net "M_L_CPU0_SB_DQ<23>")
	)
	(segment
		(start 449.663058 -308.260242)
		(end 450.088 -308.685184)
		(width 0.14478)
		(layer "In11.Cu")
		(net "M_L_CPU0_SB_DQ<23>")
	)
	(segment
		(start 440.754516 -308.260242)
		(end 441.604146 -309.109872)
		(width 0.14478)
		(layer "In11.Cu")
		(net "M_L_CPU0_SB_DQ<23>")
	)
	(segment
		(start 404.206964 -303.36236)
		(end 404.542498 -303.36236)
		(width 0.14478)
		(layer "In11.Cu")
		(net "M_L_CPU0_SB_DQ<23>")
	)
	(arc
		(start 386.99186 -288.343594)
		(mid 387.274816 -288.419771)
		(end 387.557772 -288.343594)
		(width 0.0889)
		(layer "In11.Cu")
		(net "M_L_CPU0_SB_DQ<23>")
	)
	(arc
		(start 387.931914 -288.343594)
		(mid 388.21487 -288.419771)
		(end 388.497826 -288.343594)
		(width 0.0889)
		(layer "In11.Cu")
		(net "M_L_CPU0_SB_DQ<23>")
	)
	(arc
		(start 389.811768 -288.343594)
		(mid 390.094724 -288.419771)
		(end 390.37768 -288.343594)
		(width 0.0889)
		(layer "In11.Cu")
		(net "M_L_CPU0_SB_DQ<23>")
	)
	(arc
		(start 386.617718 -288.343594)
		(mid 386.799969 -288.29321)
		(end 386.983478 -288.338768)
		(width 0.0889)
		(layer "In11.Cu")
		(net "M_L_CPU0_SB_DQ<23>")
	)
	(arc
		(start 391.691876 -288.343594)
		(mid 391.974832 -288.419771)
		(end 392.257788 -288.343594)
		(width 0.0889)
		(layer "In11.Cu")
		(net "M_L_CPU0_SB_DQ<23>")
	)
	(arc
		(start 386.114544 -288.37509)
		(mid 386.369866 -288.41879)
		(end 386.617718 -288.343594)
		(width 0.0889)
		(layer "In11.Cu")
		(net "M_L_CPU0_SB_DQ<23>")
	)
	(arc
		(start 387.566154 -288.338768)
		(mid 387.749662 -288.293243)
		(end 387.931914 -288.343594)
		(width 0.0889)
		(layer "In11.Cu")
		(net "M_L_CPU0_SB_DQ<23>")
	)
	(arc
		(start 388.871968 -288.343594)
		(mid 389.154924 -288.419771)
		(end 389.43788 -288.343594)
		(width 0.0889)
		(layer "In11.Cu")
		(net "M_L_CPU0_SB_DQ<23>")
	)
	(arc
		(start 389.43788 -288.343594)
		(mid 389.624824 -288.293305)
		(end 389.811768 -288.343594)
		(width 0.0889)
		(layer "In11.Cu")
		(net "M_L_CPU0_SB_DQ<23>")
	)
	(arc
		(start 390.751822 -288.343594)
		(mid 391.034778 -288.419771)
		(end 391.317734 -288.343594)
		(width 0.0889)
		(layer "In11.Cu")
		(net "M_L_CPU0_SB_DQ<23>")
	)
	(arc
		(start 390.37768 -288.343594)
		(mid 390.559931 -288.29321)
		(end 390.74344 -288.338768)
		(width 0.0889)
		(layer "In11.Cu")
		(net "M_L_CPU0_SB_DQ<23>")
	)
	(arc
		(start 391.326116 -288.338768)
		(mid 391.509624 -288.293243)
		(end 391.691876 -288.343594)
		(width 0.0889)
		(layer "In11.Cu")
		(net "M_L_CPU0_SB_DQ<23>")
	)
	(arc
		(start 392.26617 -288.338768)
		(mid 392.364586 -288.301929)
		(end 392.46937 -288.294064)
		(width 0.0889)
		(layer "In11.Cu")
		(net "M_L_CPU0_SB_DQ<23>")
	)
	(arc
		(start 388.506208 -288.338768)
		(mid 388.689716 -288.293243)
		(end 388.871968 -288.343594)
		(width 0.0889)
		(layer "In11.Cu")
		(net "M_L_CPU0_SB_DQ<23>")
	)
	(segment
		(start 386.807964 -287.59023)
		(end 387.274816 -287.856168)
		(width 0.10668)
		(layer "F.Cu")
		(net "M_L_CPU0_SB_DQ<22>")
	)
	(segment
		(start 425.459144 -306.56022)
		(end 426.309282 -307.410358)
		(width 0.14478)
		(layer "In11.Cu")
		(net "M_L_CPU0_SB_DQ<22>")
	)
	(segment
		(start 401.899374 -299.432726)
		(end 401.899374 -299.663358)
		(width 0.14478)
		(layer "In11.Cu")
		(net "M_L_CPU0_SB_DQ<22>")
	)
	(segment
		(start 403.311106 -300.844458)
		(end 409.876752 -307.410104)
		(width 0.14478)
		(layer "In11.Cu")
		(net "M_L_CPU0_SB_DQ<22>")
	)
	(segment
		(start 403.080474 -300.844458)
		(end 403.311106 -300.844458)
		(width 0.14478)
		(layer "In11.Cu")
		(net "M_L_CPU0_SB_DQ<22>")
	)
	(segment
		(start 402.285454 -300.852078)
		(end 402.285454 -301.08271)
		(width 0.14478)
		(layer "In11.Cu")
		(net "M_L_CPU0_SB_DQ<22>")
	)
	(segment
		(start 401.111974 -298.875958)
		(end 400.710654 -299.277278)
		(width 0.14478)
		(layer "In11.Cu")
		(net "M_L_CPU0_SB_DQ<22>")
	)
	(segment
		(start 393.940792 -287.609788)
		(end 395.689074 -289.35807)
		(width 0.0889)
		(layer "In11.Cu")
		(net "M_L_CPU0_SB_DQ<22>")
	)
	(segment
		(start 421.633904 -307.410358)
		(end 422.484042 -306.56022)
		(width 0.14478)
		(layer "In11.Cu")
		(net "M_L_CPU0_SB_DQ<22>")
	)
	(segment
		(start 401.891754 -300.458378)
		(end 402.293074 -300.057058)
		(width 0.14478)
		(layer "In11.Cu")
		(net "M_L_CPU0_SB_DQ<22>")
	)
	(segment
		(start 440.530996 -306.56022)
		(end 441.380626 -307.40985)
		(width 0.14478)
		(layer "In11.Cu")
		(net "M_L_CPU0_SB_DQ<22>")
	)
	(segment
		(start 395.689074 -289.35807)
		(end 399.791936 -293.460932)
		(width 0.14478)
		(layer "In11.Cu")
		(net "M_L_CPU0_SB_DQ<22>")
	)
	(segment
		(start 387.274816 -287.856168)
		(end 387.42874 -287.590738)
		(width 0.0889)
		(layer "In11.Cu")
		(net "M_L_CPU0_SB_DQ<22>")
	)
	(segment
		(start 400.086322 -298.883578)
		(end 400.316954 -298.883578)
		(width 0.14478)
		(layer "In11.Cu")
		(net "M_L_CPU0_SB_DQ<22>")
	)
	(segment
		(start 413.84347 -307.410104)
		(end 415.896044 -306.559966)
		(width 0.14478)
		(layer "In11.Cu")
		(net "M_L_CPU0_SB_DQ<22>")
	)
	(segment
		(start 422.484042 -306.56022)
		(end 425.459144 -306.56022)
		(width 0.14478)
		(layer "In11.Cu")
		(net "M_L_CPU0_SB_DQ<22>")
	)
	(segment
		(start 400.718274 -298.482258)
		(end 400.948906 -298.482258)
		(width 0.14478)
		(layer "In11.Cu")
		(net "M_L_CPU0_SB_DQ<22>")
	)
	(segment
		(start 399.791936 -293.460932)
		(end 399.791936 -297.325288)
		(width 0.14478)
		(layer "In11.Cu")
		(net "M_L_CPU0_SB_DQ<22>")
	)
	(segment
		(start 415.896044 -306.559966)
		(end 418.145722 -306.559966)
		(width 0.14478)
		(layer "In11.Cu")
		(net "M_L_CPU0_SB_DQ<22>")
	)
	(segment
		(start 430.028096 -306.56022)
		(end 432.198526 -306.56022)
		(width 0.14478)
		(layer "In11.Cu")
		(net "M_L_CPU0_SB_DQ<22>")
	)
	(segment
		(start 418.996114 -307.410358)
		(end 421.633904 -307.410358)
		(width 0.14478)
		(layer "In11.Cu")
		(net "M_L_CPU0_SB_DQ<22>")
	)
	(segment
		(start 401.498054 -300.29531)
		(end 401.661122 -300.458378)
		(width 0.14478)
		(layer "In11.Cu")
		(net "M_L_CPU0_SB_DQ<22>")
	)
	(segment
		(start 441.380626 -307.40985)
		(end 444.274448 -307.40985)
		(width 0.14478)
		(layer "In11.Cu")
		(net "M_L_CPU0_SB_DQ<22>")
	)
	(segment
		(start 388.393432 -287.528762)
		(end 388.401814 -287.533588)
		(width 0.0889)
		(layer "In11.Cu")
		(net "M_L_CPU0_SB_DQ<22>")
	)
	(segment
		(start 399.923254 -298.72051)
		(end 400.086322 -298.883578)
		(width 0.14478)
		(layer "In11.Cu")
		(net "M_L_CPU0_SB_DQ<22>")
	)
	(segment
		(start 402.285454 -301.08271)
		(end 402.448522 -301.245778)
		(width 0.14478)
		(layer "In11.Cu")
		(net "M_L_CPU0_SB_DQ<22>")
	)
	(segment
		(start 437.57215 -306.56022)
		(end 440.530996 -306.56022)
		(width 0.14478)
		(layer "In11.Cu")
		(net "M_L_CPU0_SB_DQ<22>")
	)
	(segment
		(start 400.316954 -298.883578)
		(end 400.718274 -298.482258)
		(width 0.14478)
		(layer "In11.Cu")
		(net "M_L_CPU0_SB_DQ<22>")
	)
	(segment
		(start 426.309282 -307.410358)
		(end 429.177958 -307.410358)
		(width 0.14478)
		(layer "In11.Cu")
		(net "M_L_CPU0_SB_DQ<22>")
	)
	(segment
		(start 400.324574 -298.088558)
		(end 399.923254 -298.489878)
		(width 0.14478)
		(layer "In11.Cu")
		(net "M_L_CPU0_SB_DQ<22>")
	)
	(segment
		(start 392.444986 -287.609788)
		(end 393.940792 -287.609788)
		(width 0.0889)
		(layer "In11.Cu")
		(net "M_L_CPU0_SB_DQ<22>")
	)
	(segment
		(start 449.663058 -306.56022)
		(end 450.088 -306.985162)
		(width 0.14478)
		(layer "In11.Cu")
		(net "M_L_CPU0_SB_DQ<22>")
	)
	(segment
		(start 400.710654 -299.50791)
		(end 400.873722 -299.670978)
		(width 0.14478)
		(layer "In11.Cu")
		(net "M_L_CPU0_SB_DQ<22>")
	)
	(segment
		(start 389.333486 -287.528762)
		(end 389.341868 -287.533588)
		(width 0.0889)
		(layer "In11.Cu")
		(net "M_L_CPU0_SB_DQ<22>")
	)
	(segment
		(start 400.948906 -298.482258)
		(end 401.111974 -298.645326)
		(width 0.14478)
		(layer "In11.Cu")
		(net "M_L_CPU0_SB_DQ<22>")
	)
	(segment
		(start 401.111974 -298.645326)
		(end 401.111974 -298.875958)
		(width 0.14478)
		(layer "In11.Cu")
		(net "M_L_CPU0_SB_DQ<22>")
	)
	(segment
		(start 434.2511 -307.410358)
		(end 436.722012 -307.410358)
		(width 0.14478)
		(layer "In11.Cu")
		(net "M_L_CPU0_SB_DQ<22>")
	)
	(segment
		(start 401.899374 -299.663358)
		(end 401.498054 -300.064678)
		(width 0.14478)
		(layer "In11.Cu")
		(net "M_L_CPU0_SB_DQ<22>")
	)
	(segment
		(start 409.876752 -307.410104)
		(end 413.84347 -307.410104)
		(width 0.14478)
		(layer "In11.Cu")
		(net "M_L_CPU0_SB_DQ<22>")
	)
	(segment
		(start 429.177958 -307.410358)
		(end 430.028096 -306.56022)
		(width 0.14478)
		(layer "In11.Cu")
		(net "M_L_CPU0_SB_DQ<22>")
	)
	(segment
		(start 401.104354 -299.670978)
		(end 401.505674 -299.269658)
		(width 0.14478)
		(layer "In11.Cu")
		(net "M_L_CPU0_SB_DQ<22>")
	)
	(segment
		(start 432.198526 -306.56022)
		(end 434.2511 -307.410358)
		(width 0.14478)
		(layer "In11.Cu")
		(net "M_L_CPU0_SB_DQ<22>")
	)
	(segment
		(start 400.710654 -299.277278)
		(end 400.710654 -299.50791)
		(width 0.14478)
		(layer "In11.Cu")
		(net "M_L_CPU0_SB_DQ<22>")
	)
	(segment
		(start 389.90778 -287.533588)
		(end 389.916162 -287.528762)
		(width 0.0889)
		(layer "In11.Cu")
		(net "M_L_CPU0_SB_DQ<22>")
	)
	(segment
		(start 444.274448 -307.40985)
		(end 445.124078 -306.56022)
		(width 0.14478)
		(layer "In11.Cu")
		(net "M_L_CPU0_SB_DQ<22>")
	)
	(segment
		(start 400.324574 -297.857926)
		(end 400.324574 -298.088558)
		(width 0.14478)
		(layer "In11.Cu")
		(net "M_L_CPU0_SB_DQ<22>")
	)
	(segment
		(start 399.923254 -298.489878)
		(end 399.923254 -298.72051)
		(width 0.14478)
		(layer "In11.Cu")
		(net "M_L_CPU0_SB_DQ<22>")
	)
	(segment
		(start 418.145722 -306.559966)
		(end 418.996114 -307.410358)
		(width 0.14478)
		(layer "In11.Cu")
		(net "M_L_CPU0_SB_DQ<22>")
	)
	(segment
		(start 387.42874 -287.590738)
		(end 387.524752 -287.565338)
		(width 0.0889)
		(layer "In11.Cu")
		(net "M_L_CPU0_SB_DQ<22>")
	)
	(segment
		(start 402.293074 -300.057058)
		(end 402.523706 -300.057058)
		(width 0.14478)
		(layer "In11.Cu")
		(net "M_L_CPU0_SB_DQ<22>")
	)
	(segment
		(start 402.448522 -301.245778)
		(end 402.679154 -301.245778)
		(width 0.14478)
		(layer "In11.Cu")
		(net "M_L_CPU0_SB_DQ<22>")
	)
	(segment
		(start 401.505674 -299.269658)
		(end 401.736306 -299.269658)
		(width 0.14478)
		(layer "In11.Cu")
		(net "M_L_CPU0_SB_DQ<22>")
	)
	(segment
		(start 402.523706 -300.057058)
		(end 402.686774 -300.220126)
		(width 0.14478)
		(layer "In11.Cu")
		(net "M_L_CPU0_SB_DQ<22>")
	)
	(segment
		(start 401.498054 -300.064678)
		(end 401.498054 -300.29531)
		(width 0.14478)
		(layer "In11.Cu")
		(net "M_L_CPU0_SB_DQ<22>")
	)
	(segment
		(start 399.791936 -297.325288)
		(end 400.324574 -297.857926)
		(width 0.14478)
		(layer "In11.Cu")
		(net "M_L_CPU0_SB_DQ<22>")
	)
	(segment
		(start 401.661122 -300.458378)
		(end 401.891754 -300.458378)
		(width 0.14478)
		(layer "In11.Cu")
		(net "M_L_CPU0_SB_DQ<22>")
	)
	(segment
		(start 400.873722 -299.670978)
		(end 401.104354 -299.670978)
		(width 0.14478)
		(layer "In11.Cu")
		(net "M_L_CPU0_SB_DQ<22>")
	)
	(segment
		(start 436.722012 -307.410358)
		(end 437.57215 -306.56022)
		(width 0.14478)
		(layer "In11.Cu")
		(net "M_L_CPU0_SB_DQ<22>")
	)
	(segment
		(start 402.686774 -300.220126)
		(end 402.686774 -300.450758)
		(width 0.14478)
		(layer "In11.Cu")
		(net "M_L_CPU0_SB_DQ<22>")
	)
	(segment
		(start 401.736306 -299.269658)
		(end 401.899374 -299.432726)
		(width 0.14478)
		(layer "In11.Cu")
		(net "M_L_CPU0_SB_DQ<22>")
	)
	(segment
		(start 445.124078 -306.56022)
		(end 449.663058 -306.56022)
		(width 0.14478)
		(layer "In11.Cu")
		(net "M_L_CPU0_SB_DQ<22>")
	)
	(segment
		(start 402.679154 -301.245778)
		(end 403.080474 -300.844458)
		(width 0.14478)
		(layer "In11.Cu")
		(net "M_L_CPU0_SB_DQ<22>")
	)
	(segment
		(start 402.686774 -300.450758)
		(end 402.285454 -300.852078)
		(width 0.14478)
		(layer "In11.Cu")
		(net "M_L_CPU0_SB_DQ<22>")
	)
	(arc
		(start 391.787634 -287.533588)
		(mid 391.974832 -287.483206)
		(end 392.16203 -287.533588)
		(width 0.0889)
		(layer "In11.Cu")
		(net "M_L_CPU0_SB_DQ<22>")
	)
	(arc
		(start 387.524752 -287.565338)
		(mid 387.77996 -287.608795)
		(end 388.027672 -287.533588)
		(width 0.0889)
		(layer "In11.Cu")
		(net "M_L_CPU0_SB_DQ<22>")
	)
	(arc
		(start 388.401814 -287.533588)
		(mid 388.68477 -287.609731)
		(end 388.967726 -287.533588)
		(width 0.0889)
		(layer "In11.Cu")
		(net "M_L_CPU0_SB_DQ<22>")
	)
	(arc
		(start 392.16203 -287.533588)
		(mid 392.298472 -287.590398)
		(end 392.444986 -287.609788)
		(width 0.0889)
		(layer "In11.Cu")
		(net "M_L_CPU0_SB_DQ<22>")
	)
	(arc
		(start 390.281922 -287.533588)
		(mid 390.564878 -287.609731)
		(end 390.847834 -287.533588)
		(width 0.0889)
		(layer "In11.Cu")
		(net "M_L_CPU0_SB_DQ<22>")
	)
	(arc
		(start 388.027672 -287.533588)
		(mid 388.209923 -287.483238)
		(end 388.393432 -287.528762)
		(width 0.0889)
		(layer "In11.Cu")
		(net "M_L_CPU0_SB_DQ<22>")
	)
	(arc
		(start 389.341868 -287.533588)
		(mid 389.624824 -287.609731)
		(end 389.90778 -287.533588)
		(width 0.0889)
		(layer "In11.Cu")
		(net "M_L_CPU0_SB_DQ<22>")
	)
	(arc
		(start 389.916162 -287.528762)
		(mid 390.09967 -287.483268)
		(end 390.281922 -287.533588)
		(width 0.0889)
		(layer "In11.Cu")
		(net "M_L_CPU0_SB_DQ<22>")
	)
	(arc
		(start 390.847834 -287.533588)
		(mid 391.034778 -287.483333)
		(end 391.221722 -287.533588)
		(width 0.0889)
		(layer "In11.Cu")
		(net "M_L_CPU0_SB_DQ<22>")
	)
	(arc
		(start 391.221722 -287.533588)
		(mid 391.504678 -287.609731)
		(end 391.787634 -287.533588)
		(width 0.0889)
		(layer "In11.Cu")
		(net "M_L_CPU0_SB_DQ<22>")
	)
	(arc
		(start 388.967726 -287.533588)
		(mid 389.149977 -287.483238)
		(end 389.333486 -287.528762)
		(width 0.0889)
		(layer "In11.Cu")
		(net "M_L_CPU0_SB_DQ<22>")
	)
	(segment
		(start 385.86791 -287.59023)
		(end 386.334762 -287.856168)
		(width 0.10668)
		(layer "F.Cu")
		(net "M_L_CPU0_SB_DQ<21>")
	)
	(segment
		(start 386.180838 -288.121598)
		(end 386.20319 -288.204656)
		(width 0.0889)
		(layer "In11.Cu")
		(net "M_L_CPU0_SB_DQ<21>")
	)
	(segment
		(start 399.337276 -298.77766)
		(end 402.260054 -301.700438)
		(width 0.14478)
		(layer "In11.Cu")
		(net "M_L_CPU0_SB_DQ<21>")
	)
	(segment
		(start 393.766294 -288.102294)
		(end 394.077698 -288.413698)
		(width 0.0889)
		(layer "In11.Cu")
		(net "M_L_CPU0_SB_DQ<21>")
	)
	(segment
		(start 426.451268 -308.260242)
		(end 429.270922 -308.260242)
		(width 0.14478)
		(layer "In11.Cu")
		(net "M_L_CPU0_SB_DQ<21>")
	)
	(segment
		(start 386.334762 -287.856168)
		(end 386.180838 -288.121598)
		(width 0.0889)
		(layer "In11.Cu")
		(net "M_L_CPU0_SB_DQ<21>")
	)
	(segment
		(start 388.393432 -288.18332)
		(end 388.401814 -288.178494)
		(width 0.0889)
		(layer "In11.Cu")
		(net "M_L_CPU0_SB_DQ<21>")
	)
	(segment
		(start 415.478468 -307.40985)
		(end 418.004244 -307.40985)
		(width 0.14478)
		(layer "In11.Cu")
		(net "M_L_CPU0_SB_DQ<21>")
	)
	(segment
		(start 425.601384 -307.410358)
		(end 426.451268 -308.260242)
		(width 0.14478)
		(layer "In11.Cu")
		(net "M_L_CPU0_SB_DQ<21>")
	)
	(segment
		(start 394.806932 -289.592512)
		(end 395.281404 -289.592512)
		(width 0.0889)
		(layer "In11.Cu")
		(net "M_L_CPU0_SB_DQ<21>")
	)
	(segment
		(start 434.458618 -308.260242)
		(end 436.18531 -308.260242)
		(width 0.14478)
		(layer "In11.Cu")
		(net "M_L_CPU0_SB_DQ<21>")
	)
	(segment
		(start 432.406806 -307.410358)
		(end 434.458618 -308.260242)
		(width 0.14478)
		(layer "In11.Cu")
		(net "M_L_CPU0_SB_DQ<21>")
	)
	(segment
		(start 389.333486 -288.18332)
		(end 389.341868 -288.178494)
		(width 0.0889)
		(layer "In11.Cu")
		(net "M_L_CPU0_SB_DQ<21>")
	)
	(segment
		(start 394.077698 -288.863278)
		(end 394.806932 -289.592512)
		(width 0.0889)
		(layer "In11.Cu")
		(net "M_L_CPU0_SB_DQ<21>")
	)
	(segment
		(start 392.153394 -288.18332)
		(end 392.161776 -288.178494)
		(width 0.0889)
		(layer "In11.Cu")
		(net "M_L_CPU0_SB_DQ<21>")
	)
	(segment
		(start 395.838426 -290.149534)
		(end 399.337276 -293.648384)
		(width 0.14478)
		(layer "In11.Cu")
		(net "M_L_CPU0_SB_DQ<21>")
	)
	(segment
		(start 418.004244 -307.40985)
		(end 418.854636 -308.260242)
		(width 0.14478)
		(layer "In11.Cu")
		(net "M_L_CPU0_SB_DQ<21>")
	)
	(segment
		(start 402.260054 -301.700438)
		(end 403.523958 -301.700438)
		(width 0.14478)
		(layer "In11.Cu")
		(net "M_L_CPU0_SB_DQ<21>")
	)
	(segment
		(start 421.726868 -308.260242)
		(end 422.576752 -307.410358)
		(width 0.14478)
		(layer "In11.Cu")
		(net "M_L_CPU0_SB_DQ<21>")
	)
	(segment
		(start 410.764482 -308.259988)
		(end 413.425894 -308.259988)
		(width 0.14478)
		(layer "In11.Cu")
		(net "M_L_CPU0_SB_DQ<21>")
	)
	(segment
		(start 418.854636 -308.260242)
		(end 421.726868 -308.260242)
		(width 0.14478)
		(layer "In11.Cu")
		(net "M_L_CPU0_SB_DQ<21>")
	)
	(segment
		(start 399.337276 -293.648384)
		(end 399.337276 -298.77766)
		(width 0.14478)
		(layer "In11.Cu")
		(net "M_L_CPU0_SB_DQ<21>")
	)
	(segment
		(start 389.90778 -288.178494)
		(end 389.916162 -288.18332)
		(width 0.0889)
		(layer "In11.Cu")
		(net "M_L_CPU0_SB_DQ<21>")
	)
	(segment
		(start 410.764228 -308.260242)
		(end 410.764482 -308.259988)
		(width 0.14478)
		(layer "In11.Cu")
		(net "M_L_CPU0_SB_DQ<21>")
	)
	(segment
		(start 452.051928 -307.410104)
		(end 454.188068 -307.835046)
		(width 0.14478)
		(layer "In11.Cu")
		(net "M_L_CPU0_SB_DQ<21>")
	)
	(segment
		(start 440.047888 -307.410358)
		(end 442.099192 -308.259988)
		(width 0.14478)
		(layer "In11.Cu")
		(net "M_L_CPU0_SB_DQ<21>")
	)
	(segment
		(start 442.099192 -308.259988)
		(end 443.689232 -308.259988)
		(width 0.14478)
		(layer "In11.Cu")
		(net "M_L_CPU0_SB_DQ<21>")
	)
	(segment
		(start 445.741044 -307.410104)
		(end 452.051928 -307.410104)
		(width 0.14478)
		(layer "In11.Cu")
		(net "M_L_CPU0_SB_DQ<21>")
	)
	(segment
		(start 443.689232 -308.259988)
		(end 445.741044 -307.410104)
		(width 0.14478)
		(layer "In11.Cu")
		(net "M_L_CPU0_SB_DQ<21>")
	)
	(segment
		(start 394.077698 -288.413698)
		(end 394.077698 -288.863278)
		(width 0.0889)
		(layer "In11.Cu")
		(net "M_L_CPU0_SB_DQ<21>")
	)
	(segment
		(start 413.425894 -308.259988)
		(end 415.478468 -307.40985)
		(width 0.14478)
		(layer "In11.Cu")
		(net "M_L_CPU0_SB_DQ<21>")
	)
	(segment
		(start 403.523958 -301.700438)
		(end 410.083762 -308.260242)
		(width 0.14478)
		(layer "In11.Cu")
		(net "M_L_CPU0_SB_DQ<21>")
	)
	(segment
		(start 430.120806 -307.410358)
		(end 432.406806 -307.410358)
		(width 0.14478)
		(layer "In11.Cu")
		(net "M_L_CPU0_SB_DQ<21>")
	)
	(segment
		(start 438.237122 -307.410358)
		(end 440.047888 -307.410358)
		(width 0.14478)
		(layer "In11.Cu")
		(net "M_L_CPU0_SB_DQ<21>")
	)
	(segment
		(start 436.18531 -308.260242)
		(end 438.237122 -307.410358)
		(width 0.14478)
		(layer "In11.Cu")
		(net "M_L_CPU0_SB_DQ<21>")
	)
	(segment
		(start 392.449304 -288.102294)
		(end 393.766294 -288.102294)
		(width 0.0889)
		(layer "In11.Cu")
		(net "M_L_CPU0_SB_DQ<21>")
	)
	(segment
		(start 395.281404 -289.592512)
		(end 395.838426 -290.149534)
		(width 0.0889)
		(layer "In11.Cu")
		(net "M_L_CPU0_SB_DQ<21>")
	)
	(segment
		(start 422.576752 -307.410358)
		(end 425.601384 -307.410358)
		(width 0.14478)
		(layer "In11.Cu")
		(net "M_L_CPU0_SB_DQ<21>")
	)
	(segment
		(start 410.083762 -308.260242)
		(end 410.764228 -308.260242)
		(width 0.14478)
		(layer "In11.Cu")
		(net "M_L_CPU0_SB_DQ<21>")
	)
	(segment
		(start 429.270922 -308.260242)
		(end 430.120806 -307.410358)
		(width 0.14478)
		(layer "In11.Cu")
		(net "M_L_CPU0_SB_DQ<21>")
	)
	(arc
		(start 387.46176 -288.178494)
		(mid 387.744716 -288.102317)
		(end 388.027672 -288.178494)
		(width 0.0889)
		(layer "In11.Cu")
		(net "M_L_CPU0_SB_DQ<21>")
	)
	(arc
		(start 390.847834 -288.178494)
		(mid 391.034778 -288.228783)
		(end 391.221722 -288.178494)
		(width 0.0889)
		(layer "In11.Cu")
		(net "M_L_CPU0_SB_DQ<21>")
	)
	(arc
		(start 390.281922 -288.178494)
		(mid 390.564878 -288.102317)
		(end 390.847834 -288.178494)
		(width 0.0889)
		(layer "In11.Cu")
		(net "M_L_CPU0_SB_DQ<21>")
	)
	(arc
		(start 392.161776 -288.178494)
		(mid 392.300425 -288.121105)
		(end 392.449304 -288.102294)
		(width 0.0889)
		(layer "In11.Cu")
		(net "M_L_CPU0_SB_DQ<21>")
	)
	(arc
		(start 387.087872 -288.178494)
		(mid 387.274816 -288.228783)
		(end 387.46176 -288.178494)
		(width 0.0889)
		(layer "In11.Cu")
		(net "M_L_CPU0_SB_DQ<21>")
	)
	(arc
		(start 386.20319 -288.204656)
		(mid 386.365522 -288.22749)
		(end 386.52196 -288.178494)
		(width 0.0889)
		(layer "In11.Cu")
		(net "M_L_CPU0_SB_DQ<21>")
	)
	(arc
		(start 388.027672 -288.178494)
		(mid 388.209923 -288.228878)
		(end 388.393432 -288.18332)
		(width 0.0889)
		(layer "In11.Cu")
		(net "M_L_CPU0_SB_DQ<21>")
	)
	(arc
		(start 386.52196 -288.178494)
		(mid 386.804916 -288.102317)
		(end 387.087872 -288.178494)
		(width 0.0889)
		(layer "In11.Cu")
		(net "M_L_CPU0_SB_DQ<21>")
	)
	(arc
		(start 389.341868 -288.178494)
		(mid 389.624824 -288.102317)
		(end 389.90778 -288.178494)
		(width 0.0889)
		(layer "In11.Cu")
		(net "M_L_CPU0_SB_DQ<21>")
	)
	(arc
		(start 391.221722 -288.178494)
		(mid 391.504678 -288.102317)
		(end 391.787634 -288.178494)
		(width 0.0889)
		(layer "In11.Cu")
		(net "M_L_CPU0_SB_DQ<21>")
	)
	(arc
		(start 388.401814 -288.178494)
		(mid 388.68477 -288.102317)
		(end 388.967726 -288.178494)
		(width 0.0889)
		(layer "In11.Cu")
		(net "M_L_CPU0_SB_DQ<21>")
	)
	(arc
		(start 391.787634 -288.178494)
		(mid 391.969885 -288.228878)
		(end 392.153394 -288.18332)
		(width 0.0889)
		(layer "In11.Cu")
		(net "M_L_CPU0_SB_DQ<21>")
	)
	(arc
		(start 389.916162 -288.18332)
		(mid 390.09967 -288.228845)
		(end 390.281922 -288.178494)
		(width 0.0889)
		(layer "In11.Cu")
		(net "M_L_CPU0_SB_DQ<21>")
	)
	(arc
		(start 388.967726 -288.178494)
		(mid 389.149977 -288.228878)
		(end 389.333486 -288.18332)
		(width 0.0889)
		(layer "In11.Cu")
		(net "M_L_CPU0_SB_DQ<21>")
	)
	(segment
		(start 387.277864 -286.780224)
		(end 387.744716 -287.045908)
		(width 0.10668)
		(layer "F.Cu")
		(net "M_L_CPU0_SB_DQ<20>")
	)
	(segment
		(start 390.74344 -287.373314)
		(end 390.751822 -287.368488)
		(width 0.0889)
		(layer "In11.Cu")
		(net "M_L_CPU0_SB_DQ<20>")
	)
	(segment
		(start 394.763752 -288.093912)
		(end 395.06906 -288.093912)
		(width 0.0889)
		(layer "In11.Cu")
		(net "M_L_CPU0_SB_DQ<20>")
	)
	(segment
		(start 422.567354 -305.719734)
		(end 425.378118 -305.719734)
		(width 0.14478)
		(layer "In11.Cu")
		(net "M_L_CPU0_SB_DQ<20>")
	)
	(segment
		(start 395.841474 -288.866326)
		(end 400.246596 -293.271448)
		(width 0.14478)
		(layer "In11.Cu")
		(net "M_L_CPU0_SB_DQ<20>")
	)
	(segment
		(start 418.066474 -305.71948)
		(end 418.916612 -306.569618)
		(width 0.14478)
		(layer "In11.Cu")
		(net "M_L_CPU0_SB_DQ<20>")
	)
	(segment
		(start 395.06906 -288.093912)
		(end 395.841474 -288.866326)
		(width 0.0889)
		(layer "In11.Cu")
		(net "M_L_CPU0_SB_DQ<20>")
	)
	(segment
		(start 387.744716 -287.045908)
		(end 387.590792 -287.311338)
		(width 0.0889)
		(layer "In11.Cu")
		(net "M_L_CPU0_SB_DQ<20>")
	)
	(segment
		(start 429.261524 -306.569618)
		(end 430.111408 -305.719734)
		(width 0.14478)
		(layer "In11.Cu")
		(net "M_L_CPU0_SB_DQ<20>")
	)
	(segment
		(start 453.39 -305.710082)
		(end 453.763126 -305.710082)
		(width 0.14478)
		(layer "In11.Cu")
		(net "M_L_CPU0_SB_DQ<20>")
	)
	(segment
		(start 453.226932 -305.87315)
		(end 453.39 -305.710082)
		(width 0.14478)
		(layer "In11.Cu")
		(net "M_L_CPU0_SB_DQ<20>")
	)
	(segment
		(start 430.111408 -305.719734)
		(end 432.992784 -305.719734)
		(width 0.14478)
		(layer "In11.Cu")
		(net "M_L_CPU0_SB_DQ<20>")
	)
	(segment
		(start 433.842668 -306.569618)
		(end 436.805578 -306.569618)
		(width 0.14478)
		(layer "In11.Cu")
		(net "M_L_CPU0_SB_DQ<20>")
	)
	(segment
		(start 432.992784 -305.719734)
		(end 433.842668 -306.569618)
		(width 0.14478)
		(layer "In11.Cu")
		(net "M_L_CPU0_SB_DQ<20>")
	)
	(segment
		(start 387.590792 -287.311338)
		(end 387.613144 -287.39465)
		(width 0.0889)
		(layer "In11.Cu")
		(net "M_L_CPU0_SB_DQ<20>")
	)
	(segment
		(start 391.317734 -287.368488)
		(end 391.326116 -287.373314)
		(width 0.0889)
		(layer "In11.Cu")
		(net "M_L_CPU0_SB_DQ<20>")
	)
	(segment
		(start 436.805578 -306.569618)
		(end 437.655462 -305.719734)
		(width 0.14478)
		(layer "In11.Cu")
		(net "M_L_CPU0_SB_DQ<20>")
	)
	(segment
		(start 437.655462 -305.719734)
		(end 440.44997 -305.719734)
		(width 0.14478)
		(layer "In11.Cu")
		(net "M_L_CPU0_SB_DQ<20>")
	)
	(segment
		(start 441.299854 -306.569618)
		(end 444.286386 -306.569618)
		(width 0.14478)
		(layer "In11.Cu")
		(net "M_L_CPU0_SB_DQ<20>")
	)
	(segment
		(start 452.833486 -306.74691)
		(end 453.063864 -306.74691)
		(width 0.14478)
		(layer "In11.Cu")
		(net "M_L_CPU0_SB_DQ<20>")
	)
	(segment
		(start 426.228002 -306.569618)
		(end 429.261524 -306.569618)
		(width 0.14478)
		(layer "In11.Cu")
		(net "M_L_CPU0_SB_DQ<20>")
	)
	(segment
		(start 414.904682 -305.71948)
		(end 418.066474 -305.71948)
		(width 0.14478)
		(layer "In11.Cu")
		(net "M_L_CPU0_SB_DQ<20>")
	)
	(segment
		(start 452.670418 -306.583842)
		(end 452.833486 -306.74691)
		(width 0.14478)
		(layer "In11.Cu")
		(net "M_L_CPU0_SB_DQ<20>")
	)
	(segment
		(start 452.516748 -305.71948)
		(end 452.670418 -305.87315)
		(width 0.14478)
		(layer "In11.Cu")
		(net "M_L_CPU0_SB_DQ<20>")
	)
	(segment
		(start 453.763126 -305.710082)
		(end 454.188068 -306.135024)
		(width 0.14478)
		(layer "In11.Cu")
		(net "M_L_CPU0_SB_DQ<20>")
	)
	(segment
		(start 414.063942 -306.56022)
		(end 414.904682 -305.71948)
		(width 0.14478)
		(layer "In11.Cu")
		(net "M_L_CPU0_SB_DQ<20>")
	)
	(segment
		(start 444.286386 -306.569618)
		(end 445.136524 -305.71948)
		(width 0.14478)
		(layer "In11.Cu")
		(net "M_L_CPU0_SB_DQ<20>")
	)
	(segment
		(start 400.246596 -293.271448)
		(end 400.246596 -297.136566)
		(width 0.14478)
		(layer "In11.Cu")
		(net "M_L_CPU0_SB_DQ<20>")
	)
	(segment
		(start 388.497826 -287.368488)
		(end 388.506208 -287.373314)
		(width 0.0889)
		(layer "In11.Cu")
		(net "M_L_CPU0_SB_DQ<20>")
	)
	(segment
		(start 409.67025 -306.56022)
		(end 414.063942 -306.56022)
		(width 0.14478)
		(layer "In11.Cu")
		(net "M_L_CPU0_SB_DQ<20>")
	)
	(segment
		(start 392.44524 -287.419288)
		(end 394.089128 -287.419288)
		(width 0.0889)
		(layer "In11.Cu")
		(net "M_L_CPU0_SB_DQ<20>")
	)
	(segment
		(start 400.246596 -297.136566)
		(end 409.67025 -306.56022)
		(width 0.14478)
		(layer "In11.Cu")
		(net "M_L_CPU0_SB_DQ<20>")
	)
	(segment
		(start 440.44997 -305.719734)
		(end 441.299854 -306.569618)
		(width 0.14478)
		(layer "In11.Cu")
		(net "M_L_CPU0_SB_DQ<20>")
	)
	(segment
		(start 421.71747 -306.569618)
		(end 422.567354 -305.719734)
		(width 0.14478)
		(layer "In11.Cu")
		(net "M_L_CPU0_SB_DQ<20>")
	)
	(segment
		(start 453.226932 -306.583842)
		(end 453.226932 -305.87315)
		(width 0.14478)
		(layer "In11.Cu")
		(net "M_L_CPU0_SB_DQ<20>")
	)
	(segment
		(start 418.916612 -306.569618)
		(end 421.71747 -306.569618)
		(width 0.14478)
		(layer "In11.Cu")
		(net "M_L_CPU0_SB_DQ<20>")
	)
	(segment
		(start 425.378118 -305.719734)
		(end 426.228002 -306.569618)
		(width 0.14478)
		(layer "In11.Cu")
		(net "M_L_CPU0_SB_DQ<20>")
	)
	(segment
		(start 394.089128 -287.419288)
		(end 394.763752 -288.093912)
		(width 0.0889)
		(layer "In11.Cu")
		(net "M_L_CPU0_SB_DQ<20>")
	)
	(segment
		(start 452.670418 -305.87315)
		(end 452.670418 -306.583842)
		(width 0.14478)
		(layer "In11.Cu")
		(net "M_L_CPU0_SB_DQ<20>")
	)
	(segment
		(start 445.136524 -305.71948)
		(end 452.516748 -305.71948)
		(width 0.14478)
		(layer "In11.Cu")
		(net "M_L_CPU0_SB_DQ<20>")
	)
	(segment
		(start 453.063864 -306.74691)
		(end 453.226932 -306.583842)
		(width 0.14478)
		(layer "In11.Cu")
		(net "M_L_CPU0_SB_DQ<20>")
	)
	(arc
		(start 390.751822 -287.368488)
		(mid 391.034778 -287.292345)
		(end 391.317734 -287.368488)
		(width 0.0889)
		(layer "In11.Cu")
		(net "M_L_CPU0_SB_DQ<20>")
	)
	(arc
		(start 388.871968 -287.368488)
		(mid 389.154924 -287.292345)
		(end 389.43788 -287.368488)
		(width 0.0889)
		(layer "In11.Cu")
		(net "M_L_CPU0_SB_DQ<20>")
	)
	(arc
		(start 389.43788 -287.368488)
		(mid 389.624824 -287.418743)
		(end 389.811768 -287.368488)
		(width 0.0889)
		(layer "In11.Cu")
		(net "M_L_CPU0_SB_DQ<20>")
	)
	(arc
		(start 387.931914 -287.368488)
		(mid 388.21487 -287.292345)
		(end 388.497826 -287.368488)
		(width 0.0889)
		(layer "In11.Cu")
		(net "M_L_CPU0_SB_DQ<20>")
	)
	(arc
		(start 391.691876 -287.368488)
		(mid 391.974832 -287.292345)
		(end 392.257788 -287.368488)
		(width 0.0889)
		(layer "In11.Cu")
		(net "M_L_CPU0_SB_DQ<20>")
	)
	(arc
		(start 387.613144 -287.39465)
		(mid 387.775476 -287.417468)
		(end 387.931914 -287.368488)
		(width 0.0889)
		(layer "In11.Cu")
		(net "M_L_CPU0_SB_DQ<20>")
	)
	(arc
		(start 389.811768 -287.368488)
		(mid 390.094724 -287.292345)
		(end 390.37768 -287.368488)
		(width 0.0889)
		(layer "In11.Cu")
		(net "M_L_CPU0_SB_DQ<20>")
	)
	(arc
		(start 388.506208 -287.373314)
		(mid 388.689716 -287.418808)
		(end 388.871968 -287.368488)
		(width 0.0889)
		(layer "In11.Cu")
		(net "M_L_CPU0_SB_DQ<20>")
	)
	(arc
		(start 390.37768 -287.368488)
		(mid 390.559931 -287.418838)
		(end 390.74344 -287.373314)
		(width 0.0889)
		(layer "In11.Cu")
		(net "M_L_CPU0_SB_DQ<20>")
	)
	(arc
		(start 392.257788 -287.368488)
		(mid 392.348155 -287.406272)
		(end 392.44524 -287.419288)
		(width 0.0889)
		(layer "In11.Cu")
		(net "M_L_CPU0_SB_DQ<20>")
	)
	(arc
		(start 391.326116 -287.373314)
		(mid 391.509624 -287.418808)
		(end 391.691876 -287.368488)
		(width 0.0889)
		(layer "In11.Cu")
		(net "M_L_CPU0_SB_DQ<20>")
	)
	(segment
		(start 385.86791 -274.630134)
		(end 386.334762 -274.896072)
		(width 0.10668)
		(layer "F.Cu")
		(net "M_L_CPU0_SB_DQ<1>")
	)
	(segment
		(start 437.66486 -282.760166)
		(end 440.689492 -282.760166)
		(width 0.14478)
		(layer "In11.Cu")
		(net "M_L_CPU0_SB_DQ<1>")
	)
	(segment
		(start 421.726868 -283.61005)
		(end 422.576752 -282.760166)
		(width 0.14478)
		(layer "In11.Cu")
		(net "M_L_CPU0_SB_DQ<1>")
	)
	(segment
		(start 426.451268 -283.61005)
		(end 429.270922 -283.61005)
		(width 0.14478)
		(layer "In11.Cu")
		(net "M_L_CPU0_SB_DQ<1>")
	)
	(segment
		(start 394.881354 -273.84883)
		(end 396.000986 -273.84883)
		(width 0.0889)
		(layer "In11.Cu")
		(net "M_L_CPU0_SB_DQ<1>")
	)
	(segment
		(start 440.689492 -282.760166)
		(end 441.539376 -283.61005)
		(width 0.14478)
		(layer "In11.Cu")
		(net "M_L_CPU0_SB_DQ<1>")
	)
	(segment
		(start 453.763126 -282.760166)
		(end 454.188068 -283.185108)
		(width 0.14478)
		(layer "In11.Cu")
		(net "M_L_CPU0_SB_DQ<1>")
	)
	(segment
		(start 393.0904 -275.22551)
		(end 393.102084 -275.218652)
		(width 0.0889)
		(layer "In11.Cu")
		(net "M_L_CPU0_SB_DQ<1>")
	)
	(segment
		(start 407.746454 -279.601676)
		(end 411.754828 -283.61005)
		(width 0.14478)
		(layer "In11.Cu")
		(net "M_L_CPU0_SB_DQ<1>")
	)
	(segment
		(start 388.393432 -275.223478)
		(end 388.401814 -275.218652)
		(width 0.0889)
		(layer "In11.Cu")
		(net "M_L_CPU0_SB_DQ<1>")
	)
	(segment
		(start 413.915606 -283.61005)
		(end 414.765744 -282.759912)
		(width 0.14478)
		(layer "In11.Cu")
		(net "M_L_CPU0_SB_DQ<1>")
	)
	(segment
		(start 430.120806 -282.760166)
		(end 433.145438 -282.760166)
		(width 0.14478)
		(layer "In11.Cu")
		(net "M_L_CPU0_SB_DQ<1>")
	)
	(segment
		(start 389.333486 -275.223478)
		(end 389.341868 -275.218652)
		(width 0.0889)
		(layer "In11.Cu")
		(net "M_L_CPU0_SB_DQ<1>")
	)
	(segment
		(start 436.814976 -283.61005)
		(end 437.66486 -282.760166)
		(width 0.14478)
		(layer "In11.Cu")
		(net "M_L_CPU0_SB_DQ<1>")
	)
	(segment
		(start 433.145438 -282.760166)
		(end 433.995322 -283.61005)
		(width 0.14478)
		(layer "In11.Cu")
		(net "M_L_CPU0_SB_DQ<1>")
	)
	(segment
		(start 418.056822 -282.759912)
		(end 418.90696 -283.61005)
		(width 0.14478)
		(layer "In11.Cu")
		(net "M_L_CPU0_SB_DQ<1>")
	)
	(segment
		(start 386.180838 -275.161502)
		(end 386.20319 -275.244814)
		(width 0.0889)
		(layer "In11.Cu")
		(net "M_L_CPU0_SB_DQ<1>")
	)
	(segment
		(start 444.421006 -282.760166)
		(end 453.763126 -282.760166)
		(width 0.14478)
		(layer "In11.Cu")
		(net "M_L_CPU0_SB_DQ<1>")
	)
	(segment
		(start 406.927558 -279.601676)
		(end 407.746454 -279.601676)
		(width 0.14478)
		(layer "In11.Cu")
		(net "M_L_CPU0_SB_DQ<1>")
	)
	(segment
		(start 443.571122 -283.61005)
		(end 444.421006 -282.760166)
		(width 0.14478)
		(layer "In11.Cu")
		(net "M_L_CPU0_SB_DQ<1>")
	)
	(segment
		(start 411.754828 -283.61005)
		(end 413.915606 -283.61005)
		(width 0.14478)
		(layer "In11.Cu")
		(net "M_L_CPU0_SB_DQ<1>")
	)
	(segment
		(start 396.000986 -273.84883)
		(end 401.174712 -273.84883)
		(width 0.14478)
		(layer "In11.Cu")
		(net "M_L_CPU0_SB_DQ<1>")
	)
	(segment
		(start 422.576752 -282.760166)
		(end 425.601384 -282.760166)
		(width 0.14478)
		(layer "In11.Cu")
		(net "M_L_CPU0_SB_DQ<1>")
	)
	(segment
		(start 393.587478 -275.142706)
		(end 394.881354 -273.84883)
		(width 0.0889)
		(layer "In11.Cu")
		(net "M_L_CPU0_SB_DQ<1>")
	)
	(segment
		(start 433.995322 -283.61005)
		(end 436.814976 -283.61005)
		(width 0.14478)
		(layer "In11.Cu")
		(net "M_L_CPU0_SB_DQ<1>")
	)
	(segment
		(start 401.174712 -273.84883)
		(end 406.927558 -279.601676)
		(width 0.14478)
		(layer "In11.Cu")
		(net "M_L_CPU0_SB_DQ<1>")
	)
	(segment
		(start 392.717782 -275.212556)
		(end 392.728196 -275.218652)
		(width 0.0889)
		(layer "In11.Cu")
		(net "M_L_CPU0_SB_DQ<1>")
	)
	(segment
		(start 386.334762 -274.896072)
		(end 386.180838 -275.161502)
		(width 0.0889)
		(layer "In11.Cu")
		(net "M_L_CPU0_SB_DQ<1>")
	)
	(segment
		(start 429.270922 -283.61005)
		(end 430.120806 -282.760166)
		(width 0.14478)
		(layer "In11.Cu")
		(net "M_L_CPU0_SB_DQ<1>")
	)
	(segment
		(start 441.539376 -283.61005)
		(end 443.571122 -283.61005)
		(width 0.14478)
		(layer "In11.Cu")
		(net "M_L_CPU0_SB_DQ<1>")
	)
	(segment
		(start 418.90696 -283.61005)
		(end 421.726868 -283.61005)
		(width 0.14478)
		(layer "In11.Cu")
		(net "M_L_CPU0_SB_DQ<1>")
	)
	(segment
		(start 393.384786 -275.142706)
		(end 393.587478 -275.142706)
		(width 0.0889)
		(layer "In11.Cu")
		(net "M_L_CPU0_SB_DQ<1>")
	)
	(segment
		(start 414.765744 -282.759912)
		(end 418.056822 -282.759912)
		(width 0.14478)
		(layer "In11.Cu")
		(net "M_L_CPU0_SB_DQ<1>")
	)
	(segment
		(start 425.601384 -282.760166)
		(end 426.451268 -283.61005)
		(width 0.14478)
		(layer "In11.Cu")
		(net "M_L_CPU0_SB_DQ<1>")
	)
	(segment
		(start 389.90778 -275.218652)
		(end 389.916162 -275.223478)
		(width 0.0889)
		(layer "In11.Cu")
		(net "M_L_CPU0_SB_DQ<1>")
	)
	(arc
		(start 386.20319 -275.244814)
		(mid 386.365522 -275.267632)
		(end 386.52196 -275.218652)
		(width 0.0889)
		(layer "In11.Cu")
		(net "M_L_CPU0_SB_DQ<1>")
	)
	(arc
		(start 390.281922 -275.218652)
		(mid 390.564878 -275.142475)
		(end 390.847834 -275.218652)
		(width 0.0889)
		(layer "In11.Cu")
		(net "M_L_CPU0_SB_DQ<1>")
	)
	(arc
		(start 388.967726 -275.218652)
		(mid 389.149977 -275.269002)
		(end 389.333486 -275.223478)
		(width 0.0889)
		(layer "In11.Cu")
		(net "M_L_CPU0_SB_DQ<1>")
	)
	(arc
		(start 388.027672 -275.218652)
		(mid 388.209923 -275.269002)
		(end 388.393432 -275.223478)
		(width 0.0889)
		(layer "In11.Cu")
		(net "M_L_CPU0_SB_DQ<1>")
	)
	(arc
		(start 393.102084 -275.218652)
		(mid 393.238418 -275.162009)
		(end 393.384786 -275.142706)
		(width 0.0889)
		(layer "In11.Cu")
		(net "M_L_CPU0_SB_DQ<1>")
	)
	(arc
		(start 389.916162 -275.223478)
		(mid 390.09967 -275.268972)
		(end 390.281922 -275.218652)
		(width 0.0889)
		(layer "In11.Cu")
		(net "M_L_CPU0_SB_DQ<1>")
	)
	(arc
		(start 392.16203 -275.218652)
		(mid 392.439097 -275.142381)
		(end 392.717782 -275.212556)
		(width 0.0889)
		(layer "In11.Cu")
		(net "M_L_CPU0_SB_DQ<1>")
	)
	(arc
		(start 389.341868 -275.218652)
		(mid 389.624824 -275.142475)
		(end 389.90778 -275.218652)
		(width 0.0889)
		(layer "In11.Cu")
		(net "M_L_CPU0_SB_DQ<1>")
	)
	(arc
		(start 392.728196 -275.218652)
		(mid 392.908401 -275.268969)
		(end 393.0904 -275.22551)
		(width 0.0889)
		(layer "In11.Cu")
		(net "M_L_CPU0_SB_DQ<1>")
	)
	(arc
		(start 386.52196 -275.218652)
		(mid 386.804916 -275.142475)
		(end 387.087872 -275.218652)
		(width 0.0889)
		(layer "In11.Cu")
		(net "M_L_CPU0_SB_DQ<1>")
	)
	(arc
		(start 387.087872 -275.218652)
		(mid 387.274816 -275.268907)
		(end 387.46176 -275.218652)
		(width 0.0889)
		(layer "In11.Cu")
		(net "M_L_CPU0_SB_DQ<1>")
	)
	(arc
		(start 390.847834 -275.218652)
		(mid 391.034778 -275.268907)
		(end 391.221722 -275.218652)
		(width 0.0889)
		(layer "In11.Cu")
		(net "M_L_CPU0_SB_DQ<1>")
	)
	(arc
		(start 391.221722 -275.218652)
		(mid 391.504678 -275.142475)
		(end 391.787634 -275.218652)
		(width 0.0889)
		(layer "In11.Cu")
		(net "M_L_CPU0_SB_DQ<1>")
	)
	(arc
		(start 387.46176 -275.218652)
		(mid 387.744716 -275.142475)
		(end 388.027672 -275.218652)
		(width 0.0889)
		(layer "In11.Cu")
		(net "M_L_CPU0_SB_DQ<1>")
	)
	(arc
		(start 388.401814 -275.218652)
		(mid 388.68477 -275.142475)
		(end 388.967726 -275.218652)
		(width 0.0889)
		(layer "In11.Cu")
		(net "M_L_CPU0_SB_DQ<1>")
	)
	(arc
		(start 391.787634 -275.218652)
		(mid 391.974832 -275.269034)
		(end 392.16203 -275.218652)
		(width 0.0889)
		(layer "In11.Cu")
		(net "M_L_CPU0_SB_DQ<1>")
	)
	(segment
		(start 385.39801 -285.160212)
		(end 385.864862 -285.42615)
		(width 0.10668)
		(layer "F.Cu")
		(net "M_L_CPU0_SB_DQ<19>")
	)
	(segment
		(start 437.82742 -302.30064)
		(end 437.295036 -302.30064)
		(width 0.14478)
		(layer "In11.Cu")
		(net "M_L_CPU0_SB_DQ<19>")
	)
	(segment
		(start 411.14345 -302.909732)
		(end 410.99867 -302.764952)
		(width 0.14478)
		(layer "In11.Cu")
		(net "M_L_CPU0_SB_DQ<19>")
	)
	(segment
		(start 443.126368 -303.150524)
		(end 441.572142 -303.150524)
		(width 0.14478)
		(layer "In11.Cu")
		(net "M_L_CPU0_SB_DQ<19>")
	)
	(segment
		(start 396.301722 -285.97733)
		(end 395.799564 -285.97733)
		(width 0.14478)
		(layer "In11.Cu")
		(net "M_L_CPU0_SB_DQ<19>")
	)
	(segment
		(start 395.593316 -285.97733)
		(end 395.098778 -285.482792)
		(width 0.0889)
		(layer "In11.Cu")
		(net "M_L_CPU0_SB_DQ<19>")
	)
	(segment
		(start 410.254704 -302.764952)
		(end 402.585936 -295.096184)
		(width 0.14478)
		(layer "In11.Cu")
		(net "M_L_CPU0_SB_DQ<19>")
	)
	(segment
		(start 429.90389 -302.30064)
		(end 429.053752 -303.150778)
		(width 0.14478)
		(layer "In11.Cu")
		(net "M_L_CPU0_SB_DQ<19>")
	)
	(segment
		(start 395.098778 -285.482792)
		(end 394.052298 -285.482792)
		(width 0.0889)
		(layer "In11.Cu")
		(net "M_L_CPU0_SB_DQ<19>")
	)
	(segment
		(start 425.65701 -302.30064)
		(end 422.360344 -302.30064)
		(width 0.14478)
		(layer "In11.Cu")
		(net "M_L_CPU0_SB_DQ<19>")
	)
	(segment
		(start 393.623038 -285.053532)
		(end 393.384786 -285.053532)
		(width 0.0889)
		(layer "In11.Cu")
		(net "M_L_CPU0_SB_DQ<19>")
	)
	(segment
		(start 411.550104 -303.435512)
		(end 411.28823 -303.435512)
		(width 0.14478)
		(layer "In11.Cu")
		(net "M_L_CPU0_SB_DQ<19>")
	)
	(segment
		(start 449.04914 -302.757332)
		(end 448.90436 -302.902112)
		(width 0.14478)
		(layer "In11.Cu")
		(net "M_L_CPU0_SB_DQ<19>")
	)
	(segment
		(start 412.652972 -303.435512)
		(end 412.391098 -303.435512)
		(width 0.14478)
		(layer "In11.Cu")
		(net "M_L_CPU0_SB_DQ<19>")
	)
	(segment
		(start 439.545476 -302.30064)
		(end 438.668414 -302.30064)
		(width 0.14478)
		(layer "In11.Cu")
		(net "M_L_CPU0_SB_DQ<19>")
	)
	(segment
		(start 440.24169 -302.056292)
		(end 440.09691 -301.911512)
		(width 0.14478)
		(layer "In11.Cu")
		(net "M_L_CPU0_SB_DQ<19>")
	)
	(segment
		(start 433.201064 -302.30064)
		(end 429.90389 -302.30064)
		(width 0.14478)
		(layer "In11.Cu")
		(net "M_L_CPU0_SB_DQ<19>")
	)
	(segment
		(start 411.694884 -302.909732)
		(end 411.694884 -303.290732)
		(width 0.14478)
		(layer "In11.Cu")
		(net "M_L_CPU0_SB_DQ<19>")
	)
	(segment
		(start 437.295036 -302.30064)
		(end 436.444898 -303.150778)
		(width 0.14478)
		(layer "In11.Cu")
		(net "M_L_CPU0_SB_DQ<19>")
	)
	(segment
		(start 441.572142 -303.150524)
		(end 440.722258 -302.30064)
		(width 0.14478)
		(layer "In11.Cu")
		(net "M_L_CPU0_SB_DQ<19>")
	)
	(segment
		(start 443.822582 -303.005744)
		(end 443.822582 -302.904652)
		(width 0.14478)
		(layer "In11.Cu")
		(net "M_L_CPU0_SB_DQ<19>")
	)
	(segment
		(start 444.17488 -303.150524)
		(end 443.967362 -303.150524)
		(width 0.14478)
		(layer "In11.Cu")
		(net "M_L_CPU0_SB_DQ<19>")
	)
	(segment
		(start 448.352926 -301.99711)
		(end 447.340228 -301.99711)
		(width 0.14478)
		(layer "In11.Cu")
		(net "M_L_CPU0_SB_DQ<19>")
	)
	(segment
		(start 448.90436 -302.902112)
		(end 448.642486 -302.902112)
		(width 0.14478)
		(layer "In11.Cu")
		(net "M_L_CPU0_SB_DQ<19>")
	)
	(segment
		(start 448.642486 -302.902112)
		(end 448.497706 -302.757332)
		(width 0.14478)
		(layer "In11.Cu")
		(net "M_L_CPU0_SB_DQ<19>")
	)
	(segment
		(start 448.497706 -302.14189)
		(end 448.352926 -301.99711)
		(width 0.14478)
		(layer "In11.Cu")
		(net "M_L_CPU0_SB_DQ<19>")
	)
	(segment
		(start 412.797752 -303.290732)
		(end 412.652972 -303.435512)
		(width 0.14478)
		(layer "In11.Cu")
		(net "M_L_CPU0_SB_DQ<19>")
	)
	(segment
		(start 386.114798 -285.13532)
		(end 386.018786 -285.16072)
		(width 0.0889)
		(layer "In11.Cu")
		(net "M_L_CPU0_SB_DQ<19>")
	)
	(segment
		(start 418.113464 -302.30064)
		(end 414.87979 -302.30064)
		(width 0.14478)
		(layer "In11.Cu")
		(net "M_L_CPU0_SB_DQ<19>")
	)
	(segment
		(start 412.246318 -302.909732)
		(end 412.101538 -302.764952)
		(width 0.14478)
		(layer "In11.Cu")
		(net "M_L_CPU0_SB_DQ<19>")
	)
	(segment
		(start 395.799564 -285.97733)
		(end 395.593316 -285.97733)
		(width 0.0889)
		(layer "In11.Cu")
		(net "M_L_CPU0_SB_DQ<19>")
	)
	(segment
		(start 392.634216 -285.10357)
		(end 392.619738 -285.095188)
		(width 0.0889)
		(layer "In11.Cu")
		(net "M_L_CPU0_SB_DQ<19>")
	)
	(segment
		(start 438.668414 -302.30064)
		(end 438.523634 -302.15586)
		(width 0.14478)
		(layer "In11.Cu")
		(net "M_L_CPU0_SB_DQ<19>")
	)
	(segment
		(start 449.35013 -301.99711)
		(end 449.19392 -301.99711)
		(width 0.14478)
		(layer "In11.Cu")
		(net "M_L_CPU0_SB_DQ<19>")
	)
	(segment
		(start 414.87979 -302.30064)
		(end 414.415478 -302.764952)
		(width 0.14478)
		(layer "In11.Cu")
		(net "M_L_CPU0_SB_DQ<19>")
	)
	(segment
		(start 439.835036 -301.911512)
		(end 439.690256 -302.056292)
		(width 0.14478)
		(layer "In11.Cu")
		(net "M_L_CPU0_SB_DQ<19>")
	)
	(segment
		(start 447.340228 -301.99711)
		(end 447.036698 -302.30064)
		(width 0.14478)
		(layer "In11.Cu")
		(net "M_L_CPU0_SB_DQ<19>")
	)
	(segment
		(start 450.088 -302.73498)
		(end 449.35013 -301.99711)
		(width 0.14478)
		(layer "In11.Cu")
		(net "M_L_CPU0_SB_DQ<19>")
	)
	(segment
		(start 386.99186 -285.10357)
		(end 386.983478 -285.098744)
		(width 0.0889)
		(layer "In11.Cu")
		(net "M_L_CPU0_SB_DQ<19>")
	)
	(segment
		(start 388.506208 -285.098744)
		(end 388.497826 -285.10357)
		(width 0.0889)
		(layer "In11.Cu")
		(net "M_L_CPU0_SB_DQ<19>")
	)
	(segment
		(start 391.326116 -285.098744)
		(end 391.317734 -285.10357)
		(width 0.0889)
		(layer "In11.Cu")
		(net "M_L_CPU0_SB_DQ<19>")
	)
	(segment
		(start 443.415928 -302.759872)
		(end 443.271148 -302.904652)
		(width 0.14478)
		(layer "In11.Cu")
		(net "M_L_CPU0_SB_DQ<19>")
	)
	(segment
		(start 410.99867 -302.764952)
		(end 410.254704 -302.764952)
		(width 0.14478)
		(layer "In11.Cu")
		(net "M_L_CPU0_SB_DQ<19>")
	)
	(segment
		(start 421.510206 -303.150778)
		(end 418.963602 -303.150778)
		(width 0.14478)
		(layer "In11.Cu")
		(net "M_L_CPU0_SB_DQ<19>")
	)
	(segment
		(start 440.09691 -301.911512)
		(end 439.835036 -301.911512)
		(width 0.14478)
		(layer "In11.Cu")
		(net "M_L_CPU0_SB_DQ<19>")
	)
	(segment
		(start 437.9722 -302.15586)
		(end 437.82742 -302.30064)
		(width 0.14478)
		(layer "In11.Cu")
		(net "M_L_CPU0_SB_DQ<19>")
	)
	(segment
		(start 391.715244 -285.117286)
		(end 391.691876 -285.10357)
		(width 0.0889)
		(layer "In11.Cu")
		(net "M_L_CPU0_SB_DQ<19>")
	)
	(segment
		(start 426.507148 -303.150778)
		(end 425.65701 -302.30064)
		(width 0.14478)
		(layer "In11.Cu")
		(net "M_L_CPU0_SB_DQ<19>")
	)
	(segment
		(start 418.963602 -303.150778)
		(end 418.113464 -302.30064)
		(width 0.14478)
		(layer "In11.Cu")
		(net "M_L_CPU0_SB_DQ<19>")
	)
	(segment
		(start 422.360344 -302.30064)
		(end 421.510206 -303.150778)
		(width 0.14478)
		(layer "In11.Cu")
		(net "M_L_CPU0_SB_DQ<19>")
	)
	(segment
		(start 436.444898 -303.150778)
		(end 434.051202 -303.150778)
		(width 0.14478)
		(layer "In11.Cu")
		(net "M_L_CPU0_SB_DQ<19>")
	)
	(segment
		(start 440.722258 -302.30064)
		(end 440.38647 -302.30064)
		(width 0.14478)
		(layer "In11.Cu")
		(net "M_L_CPU0_SB_DQ<19>")
	)
	(segment
		(start 438.11698 -301.921672)
		(end 437.9722 -302.066452)
		(width 0.14478)
		(layer "In11.Cu")
		(net "M_L_CPU0_SB_DQ<19>")
	)
	(segment
		(start 449.04914 -302.14189)
		(end 449.04914 -302.757332)
		(width 0.14478)
		(layer "In11.Cu")
		(net "M_L_CPU0_SB_DQ<19>")
	)
	(segment
		(start 394.052298 -285.482792)
		(end 393.623038 -285.053532)
		(width 0.0889)
		(layer "In11.Cu")
		(net "M_L_CPU0_SB_DQ<19>")
	)
	(segment
		(start 390.751822 -285.10357)
		(end 390.74344 -285.098744)
		(width 0.0889)
		(layer "In11.Cu")
		(net "M_L_CPU0_SB_DQ<19>")
	)
	(segment
		(start 386.018786 -285.16072)
		(end 385.864862 -285.42615)
		(width 0.0889)
		(layer "In11.Cu")
		(net "M_L_CPU0_SB_DQ<19>")
	)
	(segment
		(start 440.24169 -302.15586)
		(end 440.24169 -302.056292)
		(width 0.14478)
		(layer "In11.Cu")
		(net "M_L_CPU0_SB_DQ<19>")
	)
	(segment
		(start 443.271148 -303.005744)
		(end 443.126368 -303.150524)
		(width 0.14478)
		(layer "In11.Cu")
		(net "M_L_CPU0_SB_DQ<19>")
	)
	(segment
		(start 414.415478 -302.764952)
		(end 412.942532 -302.764952)
		(width 0.14478)
		(layer "In11.Cu")
		(net "M_L_CPU0_SB_DQ<19>")
	)
	(segment
		(start 411.694884 -303.290732)
		(end 411.550104 -303.435512)
		(width 0.14478)
		(layer "In11.Cu")
		(net "M_L_CPU0_SB_DQ<19>")
	)
	(segment
		(start 439.690256 -302.056292)
		(end 439.690256 -302.15586)
		(width 0.14478)
		(layer "In11.Cu")
		(net "M_L_CPU0_SB_DQ<19>")
	)
	(segment
		(start 434.051202 -303.150778)
		(end 433.201064 -302.30064)
		(width 0.14478)
		(layer "In11.Cu")
		(net "M_L_CPU0_SB_DQ<19>")
	)
	(segment
		(start 412.101538 -302.764952)
		(end 411.839664 -302.764952)
		(width 0.14478)
		(layer "In11.Cu")
		(net "M_L_CPU0_SB_DQ<19>")
	)
	(segment
		(start 443.967362 -303.150524)
		(end 443.822582 -303.005744)
		(width 0.14478)
		(layer "In11.Cu")
		(net "M_L_CPU0_SB_DQ<19>")
	)
	(segment
		(start 412.391098 -303.435512)
		(end 412.246318 -303.290732)
		(width 0.14478)
		(layer "In11.Cu")
		(net "M_L_CPU0_SB_DQ<19>")
	)
	(segment
		(start 387.566154 -285.098744)
		(end 387.557772 -285.10357)
		(width 0.0889)
		(layer "In11.Cu")
		(net "M_L_CPU0_SB_DQ<19>")
	)
	(segment
		(start 411.839664 -302.764952)
		(end 411.694884 -302.909732)
		(width 0.14478)
		(layer "In11.Cu")
		(net "M_L_CPU0_SB_DQ<19>")
	)
	(segment
		(start 447.036698 -302.30064)
		(end 445.024764 -302.30064)
		(width 0.14478)
		(layer "In11.Cu")
		(net "M_L_CPU0_SB_DQ<19>")
	)
	(segment
		(start 445.024764 -302.30064)
		(end 444.17488 -303.150524)
		(width 0.14478)
		(layer "In11.Cu")
		(net "M_L_CPU0_SB_DQ<19>")
	)
	(segment
		(start 412.246318 -303.290732)
		(end 412.246318 -302.909732)
		(width 0.14478)
		(layer "In11.Cu")
		(net "M_L_CPU0_SB_DQ<19>")
	)
	(segment
		(start 443.677802 -302.759872)
		(end 443.415928 -302.759872)
		(width 0.14478)
		(layer "In11.Cu")
		(net "M_L_CPU0_SB_DQ<19>")
	)
	(segment
		(start 437.9722 -302.066452)
		(end 437.9722 -302.15586)
		(width 0.14478)
		(layer "In11.Cu")
		(net "M_L_CPU0_SB_DQ<19>")
	)
	(segment
		(start 438.523634 -302.066452)
		(end 438.378854 -301.921672)
		(width 0.14478)
		(layer "In11.Cu")
		(net "M_L_CPU0_SB_DQ<19>")
	)
	(segment
		(start 439.690256 -302.15586)
		(end 439.545476 -302.30064)
		(width 0.14478)
		(layer "In11.Cu")
		(net "M_L_CPU0_SB_DQ<19>")
	)
	(segment
		(start 448.497706 -302.757332)
		(end 448.497706 -302.14189)
		(width 0.14478)
		(layer "In11.Cu")
		(net "M_L_CPU0_SB_DQ<19>")
	)
	(segment
		(start 402.585936 -295.096184)
		(end 402.585936 -292.261544)
		(width 0.14478)
		(layer "In11.Cu")
		(net "M_L_CPU0_SB_DQ<19>")
	)
	(segment
		(start 438.378854 -301.921672)
		(end 438.11698 -301.921672)
		(width 0.14478)
		(layer "In11.Cu")
		(net "M_L_CPU0_SB_DQ<19>")
	)
	(segment
		(start 393.198604 -285.103824)
		(end 393.177014 -285.11627)
		(width 0.0889)
		(layer "In11.Cu")
		(net "M_L_CPU0_SB_DQ<19>")
	)
	(segment
		(start 412.797752 -302.909732)
		(end 412.797752 -303.290732)
		(width 0.14478)
		(layer "In11.Cu")
		(net "M_L_CPU0_SB_DQ<19>")
	)
	(segment
		(start 443.271148 -302.904652)
		(end 443.271148 -303.005744)
		(width 0.14478)
		(layer "In11.Cu")
		(net "M_L_CPU0_SB_DQ<19>")
	)
	(segment
		(start 429.053752 -303.150778)
		(end 426.507148 -303.150778)
		(width 0.14478)
		(layer "In11.Cu")
		(net "M_L_CPU0_SB_DQ<19>")
	)
	(segment
		(start 443.822582 -302.904652)
		(end 443.677802 -302.759872)
		(width 0.14478)
		(layer "In11.Cu")
		(net "M_L_CPU0_SB_DQ<19>")
	)
	(segment
		(start 402.585936 -292.261544)
		(end 396.301722 -285.97733)
		(width 0.14478)
		(layer "In11.Cu")
		(net "M_L_CPU0_SB_DQ<19>")
	)
	(segment
		(start 412.942532 -302.764952)
		(end 412.797752 -302.909732)
		(width 0.14478)
		(layer "In11.Cu")
		(net "M_L_CPU0_SB_DQ<19>")
	)
	(segment
		(start 438.523634 -302.15586)
		(end 438.523634 -302.066452)
		(width 0.14478)
		(layer "In11.Cu")
		(net "M_L_CPU0_SB_DQ<19>")
	)
	(segment
		(start 411.14345 -303.290732)
		(end 411.14345 -302.909732)
		(width 0.14478)
		(layer "In11.Cu")
		(net "M_L_CPU0_SB_DQ<19>")
	)
	(segment
		(start 411.28823 -303.435512)
		(end 411.14345 -303.290732)
		(width 0.14478)
		(layer "In11.Cu")
		(net "M_L_CPU0_SB_DQ<19>")
	)
	(segment
		(start 440.38647 -302.30064)
		(end 440.24169 -302.15586)
		(width 0.14478)
		(layer "In11.Cu")
		(net "M_L_CPU0_SB_DQ<19>")
	)
	(segment
		(start 449.19392 -301.99711)
		(end 449.04914 -302.14189)
		(width 0.14478)
		(layer "In11.Cu")
		(net "M_L_CPU0_SB_DQ<19>")
	)
	(arc
		(start 387.557772 -285.10357)
		(mid 387.274816 -285.179747)
		(end 386.99186 -285.10357)
		(width 0.0889)
		(layer "In11.Cu")
		(net "M_L_CPU0_SB_DQ<19>")
	)
	(arc
		(start 391.691876 -285.10357)
		(mid 391.509625 -285.05322)
		(end 391.326116 -285.098744)
		(width 0.0889)
		(layer "In11.Cu")
		(net "M_L_CPU0_SB_DQ<19>")
	)
	(arc
		(start 387.931914 -285.10357)
		(mid 387.749663 -285.05322)
		(end 387.566154 -285.098744)
		(width 0.0889)
		(layer "In11.Cu")
		(net "M_L_CPU0_SB_DQ<19>")
	)
	(arc
		(start 386.983478 -285.098744)
		(mid 386.79997 -285.05325)
		(end 386.617718 -285.10357)
		(width 0.0889)
		(layer "In11.Cu")
		(net "M_L_CPU0_SB_DQ<19>")
	)
	(arc
		(start 390.37768 -285.10357)
		(mid 390.094724 -285.179747)
		(end 389.811768 -285.10357)
		(width 0.0889)
		(layer "In11.Cu")
		(net "M_L_CPU0_SB_DQ<19>")
	)
	(arc
		(start 389.811768 -285.10357)
		(mid 389.624824 -285.053315)
		(end 389.43788 -285.10357)
		(width 0.0889)
		(layer "In11.Cu")
		(net "M_L_CPU0_SB_DQ<19>")
	)
	(arc
		(start 390.74344 -285.098744)
		(mid 390.559932 -285.05325)
		(end 390.37768 -285.10357)
		(width 0.0889)
		(layer "In11.Cu")
		(net "M_L_CPU0_SB_DQ<19>")
	)
	(arc
		(start 392.619738 -285.095188)
		(mid 392.438322 -285.052931)
		(end 392.259058 -285.10357)
		(width 0.0889)
		(layer "In11.Cu")
		(net "M_L_CPU0_SB_DQ<19>")
	)
	(arc
		(start 389.43788 -285.10357)
		(mid 389.154924 -285.179747)
		(end 388.871968 -285.10357)
		(width 0.0889)
		(layer "In11.Cu")
		(net "M_L_CPU0_SB_DQ<19>")
	)
	(arc
		(start 388.871968 -285.10357)
		(mid 388.689717 -285.05322)
		(end 388.506208 -285.098744)
		(width 0.0889)
		(layer "In11.Cu")
		(net "M_L_CPU0_SB_DQ<19>")
	)
	(arc
		(start 393.384786 -285.053532)
		(mid 393.288389 -285.06643)
		(end 393.198604 -285.103824)
		(width 0.0889)
		(layer "In11.Cu")
		(net "M_L_CPU0_SB_DQ<19>")
	)
	(arc
		(start 393.177014 -285.11627)
		(mid 392.903985 -285.179589)
		(end 392.634216 -285.10357)
		(width 0.0889)
		(layer "In11.Cu")
		(net "M_L_CPU0_SB_DQ<19>")
	)
	(arc
		(start 386.617718 -285.10357)
		(mid 386.370005 -285.17879)
		(end 386.114798 -285.13532)
		(width 0.0889)
		(layer "In11.Cu")
		(net "M_L_CPU0_SB_DQ<19>")
	)
	(arc
		(start 388.497826 -285.10357)
		(mid 388.21487 -285.179747)
		(end 387.931914 -285.10357)
		(width 0.0889)
		(layer "In11.Cu")
		(net "M_L_CPU0_SB_DQ<19>")
	)
	(arc
		(start 392.259058 -285.10357)
		(mid 391.988901 -285.180332)
		(end 391.715244 -285.117286)
		(width 0.0889)
		(layer "In11.Cu")
		(net "M_L_CPU0_SB_DQ<19>")
	)
	(arc
		(start 391.317734 -285.10357)
		(mid 391.034778 -285.179747)
		(end 390.751822 -285.10357)
		(width 0.0889)
		(layer "In11.Cu")
		(net "M_L_CPU0_SB_DQ<19>")
	)
	(segment
		(start 386.807964 -284.350206)
		(end 387.274816 -284.616144)
		(width 0.10668)
		(layer "F.Cu")
		(net "M_L_CPU0_SB_DQ<18>")
	)
	(segment
		(start 414.463992 -301.086012)
		(end 414.939988 -300.610016)
		(width 0.14478)
		(layer "In11.Cu")
		(net "M_L_CPU0_SB_DQ<18>")
	)
	(segment
		(start 410.717746 -301.086012)
		(end 410.862526 -301.230792)
		(width 0.14478)
		(layer "In11.Cu")
		(net "M_L_CPU0_SB_DQ<18>")
	)
	(segment
		(start 433.210462 -300.610016)
		(end 434.0606 -301.460154)
		(width 0.14478)
		(layer "In11.Cu")
		(net "M_L_CPU0_SB_DQ<18>")
	)
	(segment
		(start 420.652956 -301.315374)
		(end 420.652956 -301.205392)
		(width 0.14478)
		(layer "In11.Cu")
		(net "M_L_CPU0_SB_DQ<18>")
	)
	(segment
		(start 439.736738 -300.357032)
		(end 439.881518 -300.212252)
		(width 0.14478)
		(layer "In11.Cu")
		(net "M_L_CPU0_SB_DQ<18>")
	)
	(segment
		(start 389.333486 -284.288738)
		(end 389.341868 -284.293564)
		(width 0.0889)
		(layer "In11.Cu")
		(net "M_L_CPU0_SB_DQ<18>")
	)
	(segment
		(start 396.678658 -285.06801)
		(end 403.495256 -291.884608)
		(width 0.14478)
		(layer "In11.Cu")
		(net "M_L_CPU0_SB_DQ<18>")
	)
	(segment
		(start 414.939988 -300.610016)
		(end 415.799778 -300.610016)
		(width 0.14478)
		(layer "In11.Cu")
		(net "M_L_CPU0_SB_DQ<18>")
	)
	(segment
		(start 440.288172 -300.357032)
		(end 440.288172 -300.465236)
		(width 0.14478)
		(layer "In11.Cu")
		(net "M_L_CPU0_SB_DQ<18>")
	)
	(segment
		(start 448.535552 -301.0027)
		(end 448.680332 -300.85792)
		(width 0.14478)
		(layer "In11.Cu")
		(net "M_L_CPU0_SB_DQ<18>")
	)
	(segment
		(start 417.74364 -300.610016)
		(end 418.122608 -300.610016)
		(width 0.14478)
		(layer "In11.Cu")
		(net "M_L_CPU0_SB_DQ<18>")
	)
	(segment
		(start 413.213042 -301.431452)
		(end 413.474916 -301.431452)
		(width 0.14478)
		(layer "In11.Cu")
		(net "M_L_CPU0_SB_DQ<18>")
	)
	(segment
		(start 435.598316 -301.460154)
		(end 435.743096 -301.315374)
		(width 0.14478)
		(layer "In11.Cu")
		(net "M_L_CPU0_SB_DQ<18>")
	)
	(segment
		(start 449.086986 -300.217332)
		(end 449.231766 -300.362112)
		(width 0.14478)
		(layer "In11.Cu")
		(net "M_L_CPU0_SB_DQ<18>")
	)
	(segment
		(start 411.007306 -301.431452)
		(end 411.26918 -301.431452)
		(width 0.14478)
		(layer "In11.Cu")
		(net "M_L_CPU0_SB_DQ<18>")
	)
	(segment
		(start 431.067718 -300.465236)
		(end 431.212498 -300.610016)
		(width 0.14478)
		(layer "In11.Cu")
		(net "M_L_CPU0_SB_DQ<18>")
	)
	(segment
		(start 421.34917 -301.460154)
		(end 421.633904 -301.460154)
		(width 0.14478)
		(layer "In11.Cu")
		(net "M_L_CPU0_SB_DQ<18>")
	)
	(segment
		(start 432.65471 -300.217332)
		(end 432.79949 -300.362112)
		(width 0.14478)
		(layer "In11.Cu")
		(net "M_L_CPU0_SB_DQ<18>")
	)
	(segment
		(start 444.313564 -301.4599)
		(end 445.163448 -300.610016)
		(width 0.14478)
		(layer "In11.Cu")
		(net "M_L_CPU0_SB_DQ<18>")
	)
	(segment
		(start 416.902646 -300.610016)
		(end 417.047426 -300.465236)
		(width 0.14478)
		(layer "In11.Cu")
		(net "M_L_CPU0_SB_DQ<18>")
	)
	(segment
		(start 430.516284 -300.357032)
		(end 430.661064 -300.212252)
		(width 0.14478)
		(layer "In11.Cu")
		(net "M_L_CPU0_SB_DQ<18>")
	)
	(segment
		(start 387.274816 -284.616144)
		(end 387.42874 -284.350714)
		(width 0.0889)
		(layer "In11.Cu")
		(net "M_L_CPU0_SB_DQ<18>")
	)
	(segment
		(start 438.40273 -300.217332)
		(end 438.54751 -300.362112)
		(width 0.14478)
		(layer "In11.Cu")
		(net "M_L_CPU0_SB_DQ<18>")
	)
	(segment
		(start 392.161522 -284.293818)
		(end 392.17346 -284.300676)
		(width 0.0889)
		(layer "In11.Cu")
		(net "M_L_CPU0_SB_DQ<18>")
	)
	(segment
		(start 449.663058 -300.610016)
		(end 450.088 -301.034958)
		(width 0.14478)
		(layer "In11.Cu")
		(net "M_L_CPU0_SB_DQ<18>")
	)
	(segment
		(start 388.393432 -284.288738)
		(end 388.401814 -284.293564)
		(width 0.0889)
		(layer "In11.Cu")
		(net "M_L_CPU0_SB_DQ<18>")
	)
	(segment
		(start 392.145266 -284.28442)
		(end 392.161522 -284.293818)
		(width 0.0889)
		(layer "In11.Cu")
		(net "M_L_CPU0_SB_DQ<18>")
	)
	(segment
		(start 418.122608 -300.610016)
		(end 418.972746 -301.460154)
		(width 0.14478)
		(layer "In11.Cu")
		(net "M_L_CPU0_SB_DQ<18>")
	)
	(segment
		(start 437.996076 -300.362112)
		(end 438.140856 -300.217332)
		(width 0.14478)
		(layer "In11.Cu")
		(net "M_L_CPU0_SB_DQ<18>")
	)
	(segment
		(start 430.028096 -300.610016)
		(end 430.371504 -300.610016)
		(width 0.14478)
		(layer "In11.Cu")
		(net "M_L_CPU0_SB_DQ<18>")
	)
	(segment
		(start 403.495256 -294.595042)
		(end 409.986226 -301.086012)
		(width 0.14478)
		(layer "In11.Cu")
		(net "M_L_CPU0_SB_DQ<18>")
	)
	(segment
		(start 393.384786 -284.370018)
		(end 394.102844 -284.370018)
		(width 0.0889)
		(layer "In11.Cu")
		(net "M_L_CPU0_SB_DQ<18>")
	)
	(segment
		(start 430.516284 -300.465236)
		(end 430.516284 -300.357032)
		(width 0.14478)
		(layer "In11.Cu")
		(net "M_L_CPU0_SB_DQ<18>")
	)
	(segment
		(start 409.986226 -301.086012)
		(end 410.717746 -301.086012)
		(width 0.14478)
		(layer "In11.Cu")
		(net "M_L_CPU0_SB_DQ<18>")
	)
	(segment
		(start 431.067718 -300.357032)
		(end 431.067718 -300.465236)
		(width 0.14478)
		(layer "In11.Cu")
		(net "M_L_CPU0_SB_DQ<18>")
	)
	(segment
		(start 415.799778 -300.610016)
		(end 415.944558 -300.465236)
		(width 0.14478)
		(layer "In11.Cu")
		(net "M_L_CPU0_SB_DQ<18>")
	)
	(segment
		(start 417.59886 -300.369732)
		(end 417.59886 -300.465236)
		(width 0.14478)
		(layer "In11.Cu")
		(net "M_L_CPU0_SB_DQ<18>")
	)
	(segment
		(start 437.57215 -300.610016)
		(end 437.851296 -300.610016)
		(width 0.14478)
		(layer "In11.Cu")
		(net "M_L_CPU0_SB_DQ<18>")
	)
	(segment
		(start 411.55874 -301.086012)
		(end 411.820614 -301.086012)
		(width 0.14478)
		(layer "In11.Cu")
		(net "M_L_CPU0_SB_DQ<18>")
	)
	(segment
		(start 411.41396 -301.230792)
		(end 411.55874 -301.086012)
		(width 0.14478)
		(layer "In11.Cu")
		(net "M_L_CPU0_SB_DQ<18>")
	)
	(segment
		(start 395.590776 -285.06801)
		(end 395.845284 -285.06801)
		(width 0.0889)
		(layer "In11.Cu")
		(net "M_L_CPU0_SB_DQ<18>")
	)
	(segment
		(start 412.372048 -301.431452)
		(end 412.516828 -301.286672)
		(width 0.14478)
		(layer "In11.Cu")
		(net "M_L_CPU0_SB_DQ<18>")
	)
	(segment
		(start 426.516546 -301.460154)
		(end 429.177958 -301.460154)
		(width 0.14478)
		(layer "In11.Cu")
		(net "M_L_CPU0_SB_DQ<18>")
	)
	(segment
		(start 394.102844 -284.370018)
		(end 394.689838 -284.957012)
		(width 0.0889)
		(layer "In11.Cu")
		(net "M_L_CPU0_SB_DQ<18>")
	)
	(segment
		(start 435.743096 -301.223172)
		(end 435.887876 -301.078392)
		(width 0.14478)
		(layer "In11.Cu")
		(net "M_L_CPU0_SB_DQ<18>")
	)
	(segment
		(start 448.680332 -300.362112)
		(end 448.825112 -300.217332)
		(width 0.14478)
		(layer "In11.Cu")
		(net "M_L_CPU0_SB_DQ<18>")
	)
	(segment
		(start 417.047426 -300.369732)
		(end 417.192206 -300.224952)
		(width 0.14478)
		(layer "In11.Cu")
		(net "M_L_CPU0_SB_DQ<18>")
	)
	(segment
		(start 435.743096 -301.315374)
		(end 435.743096 -301.223172)
		(width 0.14478)
		(layer "In11.Cu")
		(net "M_L_CPU0_SB_DQ<18>")
	)
	(segment
		(start 413.619696 -301.230792)
		(end 413.764476 -301.086012)
		(width 0.14478)
		(layer "In11.Cu")
		(net "M_L_CPU0_SB_DQ<18>")
	)
	(segment
		(start 449.231766 -300.465236)
		(end 449.376546 -300.610016)
		(width 0.14478)
		(layer "In11.Cu")
		(net "M_L_CPU0_SB_DQ<18>")
	)
	(segment
		(start 421.633904 -301.460154)
		(end 422.484042 -300.610016)
		(width 0.14478)
		(layer "In11.Cu")
		(net "M_L_CPU0_SB_DQ<18>")
	)
	(segment
		(start 447.02603 -300.85792)
		(end 447.17081 -301.0027)
		(width 0.14478)
		(layer "In11.Cu")
		(net "M_L_CPU0_SB_DQ<18>")
	)
	(segment
		(start 432.248056 -300.362112)
		(end 432.392836 -300.217332)
		(width 0.14478)
		(layer "In11.Cu")
		(net "M_L_CPU0_SB_DQ<18>")
	)
	(segment
		(start 413.764476 -301.086012)
		(end 414.463992 -301.086012)
		(width 0.14478)
		(layer "In11.Cu")
		(net "M_L_CPU0_SB_DQ<18>")
	)
	(segment
		(start 447.02603 -300.754796)
		(end 447.02603 -300.85792)
		(width 0.14478)
		(layer "In11.Cu")
		(net "M_L_CPU0_SB_DQ<18>")
	)
	(segment
		(start 412.516828 -301.230792)
		(end 412.661608 -301.086012)
		(width 0.14478)
		(layer "In11.Cu")
		(net "M_L_CPU0_SB_DQ<18>")
	)
	(segment
		(start 412.923482 -301.086012)
		(end 413.068262 -301.230792)
		(width 0.14478)
		(layer "In11.Cu")
		(net "M_L_CPU0_SB_DQ<18>")
	)
	(segment
		(start 422.484042 -300.610016)
		(end 425.666408 -300.610016)
		(width 0.14478)
		(layer "In11.Cu")
		(net "M_L_CPU0_SB_DQ<18>")
	)
	(segment
		(start 416.089338 -300.224952)
		(end 416.351212 -300.224952)
		(width 0.14478)
		(layer "In11.Cu")
		(net "M_L_CPU0_SB_DQ<18>")
	)
	(segment
		(start 446.88125 -300.610016)
		(end 447.02603 -300.754796)
		(width 0.14478)
		(layer "In11.Cu")
		(net "M_L_CPU0_SB_DQ<18>")
	)
	(segment
		(start 445.163448 -300.610016)
		(end 446.88125 -300.610016)
		(width 0.14478)
		(layer "In11.Cu")
		(net "M_L_CPU0_SB_DQ<18>")
	)
	(segment
		(start 438.54751 -300.465236)
		(end 438.69229 -300.610016)
		(width 0.14478)
		(layer "In11.Cu")
		(net "M_L_CPU0_SB_DQ<18>")
	)
	(segment
		(start 411.820614 -301.086012)
		(end 411.965394 -301.230792)
		(width 0.14478)
		(layer "In11.Cu")
		(net "M_L_CPU0_SB_DQ<18>")
	)
	(segment
		(start 430.922938 -300.212252)
		(end 431.067718 -300.357032)
		(width 0.14478)
		(layer "In11.Cu")
		(net "M_L_CPU0_SB_DQ<18>")
	)
	(segment
		(start 420.797736 -301.060612)
		(end 421.05961 -301.060612)
		(width 0.14478)
		(layer "In11.Cu")
		(net "M_L_CPU0_SB_DQ<18>")
	)
	(segment
		(start 441.6044 -301.4599)
		(end 444.313564 -301.4599)
		(width 0.14478)
		(layer "In11.Cu")
		(net "M_L_CPU0_SB_DQ<18>")
	)
	(segment
		(start 447.17081 -301.0027)
		(end 447.432684 -301.0027)
		(width 0.14478)
		(layer "In11.Cu")
		(net "M_L_CPU0_SB_DQ<18>")
	)
	(segment
		(start 432.79949 -300.465236)
		(end 432.94427 -300.610016)
		(width 0.14478)
		(layer "In11.Cu")
		(net "M_L_CPU0_SB_DQ<18>")
	)
	(segment
		(start 411.41396 -301.286672)
		(end 411.41396 -301.230792)
		(width 0.14478)
		(layer "In11.Cu")
		(net "M_L_CPU0_SB_DQ<18>")
	)
	(segment
		(start 416.351212 -300.224952)
		(end 416.495992 -300.369732)
		(width 0.14478)
		(layer "In11.Cu")
		(net "M_L_CPU0_SB_DQ<18>")
	)
	(segment
		(start 447.722244 -300.217332)
		(end 447.984118 -300.217332)
		(width 0.14478)
		(layer "In11.Cu")
		(net "M_L_CPU0_SB_DQ<18>")
	)
	(segment
		(start 448.825112 -300.217332)
		(end 449.086986 -300.217332)
		(width 0.14478)
		(layer "In11.Cu")
		(net "M_L_CPU0_SB_DQ<18>")
	)
	(segment
		(start 431.212498 -300.610016)
		(end 432.103276 -300.610016)
		(width 0.14478)
		(layer "In11.Cu")
		(net "M_L_CPU0_SB_DQ<18>")
	)
	(segment
		(start 440.143392 -300.212252)
		(end 440.288172 -300.357032)
		(width 0.14478)
		(layer "In11.Cu")
		(net "M_L_CPU0_SB_DQ<18>")
	)
	(segment
		(start 418.972746 -301.460154)
		(end 420.508176 -301.460154)
		(width 0.14478)
		(layer "In11.Cu")
		(net "M_L_CPU0_SB_DQ<18>")
	)
	(segment
		(start 439.881518 -300.212252)
		(end 440.143392 -300.212252)
		(width 0.14478)
		(layer "In11.Cu")
		(net "M_L_CPU0_SB_DQ<18>")
	)
	(segment
		(start 447.577464 -300.85792)
		(end 447.577464 -300.362112)
		(width 0.14478)
		(layer "In11.Cu")
		(net "M_L_CPU0_SB_DQ<18>")
	)
	(segment
		(start 417.59886 -300.465236)
		(end 417.74364 -300.610016)
		(width 0.14478)
		(layer "In11.Cu")
		(net "M_L_CPU0_SB_DQ<18>")
	)
	(segment
		(start 437.996076 -300.465236)
		(end 437.996076 -300.362112)
		(width 0.14478)
		(layer "In11.Cu")
		(net "M_L_CPU0_SB_DQ<18>")
	)
	(segment
		(start 411.965394 -301.230792)
		(end 411.965394 -301.286672)
		(width 0.14478)
		(layer "In11.Cu")
		(net "M_L_CPU0_SB_DQ<18>")
	)
	(segment
		(start 425.666408 -300.610016)
		(end 426.516546 -301.460154)
		(width 0.14478)
		(layer "In11.Cu")
		(net "M_L_CPU0_SB_DQ<18>")
	)
	(segment
		(start 395.845284 -285.06801)
		(end 396.678658 -285.06801)
		(width 0.14478)
		(layer "In11.Cu")
		(net "M_L_CPU0_SB_DQ<18>")
	)
	(segment
		(start 432.79949 -300.362112)
		(end 432.79949 -300.465236)
		(width 0.14478)
		(layer "In11.Cu")
		(net "M_L_CPU0_SB_DQ<18>")
	)
	(segment
		(start 392.726672 -284.293564)
		(end 392.738356 -284.286706)
		(width 0.0889)
		(layer "In11.Cu")
		(net "M_L_CPU0_SB_DQ<18>")
	)
	(segment
		(start 435.887876 -301.078392)
		(end 436.14975 -301.078392)
		(width 0.14478)
		(layer "In11.Cu")
		(net "M_L_CPU0_SB_DQ<18>")
	)
	(segment
		(start 429.177958 -301.460154)
		(end 430.028096 -300.610016)
		(width 0.14478)
		(layer "In11.Cu")
		(net "M_L_CPU0_SB_DQ<18>")
	)
	(segment
		(start 421.05961 -301.060612)
		(end 421.20439 -301.205392)
		(width 0.14478)
		(layer "In11.Cu")
		(net "M_L_CPU0_SB_DQ<18>")
	)
	(segment
		(start 421.20439 -301.205392)
		(end 421.20439 -301.315374)
		(width 0.14478)
		(layer "In11.Cu")
		(net "M_L_CPU0_SB_DQ<18>")
	)
	(segment
		(start 411.26918 -301.431452)
		(end 411.41396 -301.286672)
		(width 0.14478)
		(layer "In11.Cu")
		(net "M_L_CPU0_SB_DQ<18>")
	)
	(segment
		(start 411.965394 -301.286672)
		(end 412.110174 -301.431452)
		(width 0.14478)
		(layer "In11.Cu")
		(net "M_L_CPU0_SB_DQ<18>")
	)
	(segment
		(start 434.0606 -301.460154)
		(end 435.598316 -301.460154)
		(width 0.14478)
		(layer "In11.Cu")
		(net "M_L_CPU0_SB_DQ<18>")
	)
	(segment
		(start 436.29453 -301.315374)
		(end 436.43931 -301.460154)
		(width 0.14478)
		(layer "In11.Cu")
		(net "M_L_CPU0_SB_DQ<18>")
	)
	(segment
		(start 432.103276 -300.610016)
		(end 432.248056 -300.465236)
		(width 0.14478)
		(layer "In11.Cu")
		(net "M_L_CPU0_SB_DQ<18>")
	)
	(segment
		(start 410.862526 -301.286672)
		(end 411.007306 -301.431452)
		(width 0.14478)
		(layer "In11.Cu")
		(net "M_L_CPU0_SB_DQ<18>")
	)
	(segment
		(start 417.192206 -300.224952)
		(end 417.45408 -300.224952)
		(width 0.14478)
		(layer "In11.Cu")
		(net "M_L_CPU0_SB_DQ<18>")
	)
	(segment
		(start 432.248056 -300.465236)
		(end 432.248056 -300.362112)
		(width 0.14478)
		(layer "In11.Cu")
		(net "M_L_CPU0_SB_DQ<18>")
	)
	(segment
		(start 415.944558 -300.465236)
		(end 415.944558 -300.369732)
		(width 0.14478)
		(layer "In11.Cu")
		(net "M_L_CPU0_SB_DQ<18>")
	)
	(segment
		(start 449.376546 -300.610016)
		(end 449.663058 -300.610016)
		(width 0.14478)
		(layer "In11.Cu")
		(net "M_L_CPU0_SB_DQ<18>")
	)
	(segment
		(start 440.288172 -300.465236)
		(end 440.432952 -300.610016)
		(width 0.14478)
		(layer "In11.Cu")
		(net "M_L_CPU0_SB_DQ<18>")
	)
	(segment
		(start 395.479778 -284.957012)
		(end 395.590776 -285.06801)
		(width 0.0889)
		(layer "In11.Cu")
		(net "M_L_CPU0_SB_DQ<18>")
	)
	(segment
		(start 394.689838 -284.957012)
		(end 395.479778 -284.957012)
		(width 0.0889)
		(layer "In11.Cu")
		(net "M_L_CPU0_SB_DQ<18>")
	)
	(segment
		(start 439.736738 -300.465236)
		(end 439.736738 -300.357032)
		(width 0.14478)
		(layer "In11.Cu")
		(net "M_L_CPU0_SB_DQ<18>")
	)
	(segment
		(start 436.29453 -301.223172)
		(end 436.29453 -301.315374)
		(width 0.14478)
		(layer "In11.Cu")
		(net "M_L_CPU0_SB_DQ<18>")
	)
	(segment
		(start 413.068262 -301.286672)
		(end 413.213042 -301.431452)
		(width 0.14478)
		(layer "In11.Cu")
		(net "M_L_CPU0_SB_DQ<18>")
	)
	(segment
		(start 430.371504 -300.610016)
		(end 430.516284 -300.465236)
		(width 0.14478)
		(layer "In11.Cu")
		(net "M_L_CPU0_SB_DQ<18>")
	)
	(segment
		(start 430.661064 -300.212252)
		(end 430.922938 -300.212252)
		(width 0.14478)
		(layer "In11.Cu")
		(net "M_L_CPU0_SB_DQ<18>")
	)
	(segment
		(start 410.862526 -301.230792)
		(end 410.862526 -301.286672)
		(width 0.14478)
		(layer "In11.Cu")
		(net "M_L_CPU0_SB_DQ<18>")
	)
	(segment
		(start 412.661608 -301.086012)
		(end 412.923482 -301.086012)
		(width 0.14478)
		(layer "In11.Cu")
		(net "M_L_CPU0_SB_DQ<18>")
	)
	(segment
		(start 420.508176 -301.460154)
		(end 420.652956 -301.315374)
		(width 0.14478)
		(layer "In11.Cu")
		(net "M_L_CPU0_SB_DQ<18>")
	)
	(segment
		(start 438.69229 -300.610016)
		(end 439.591958 -300.610016)
		(width 0.14478)
		(layer "In11.Cu")
		(net "M_L_CPU0_SB_DQ<18>")
	)
	(segment
		(start 421.20439 -301.315374)
		(end 421.34917 -301.460154)
		(width 0.14478)
		(layer "In11.Cu")
		(net "M_L_CPU0_SB_DQ<18>")
	)
	(segment
		(start 448.680332 -300.85792)
		(end 448.680332 -300.362112)
		(width 0.14478)
		(layer "In11.Cu")
		(net "M_L_CPU0_SB_DQ<18>")
	)
	(segment
		(start 447.432684 -301.0027)
		(end 447.577464 -300.85792)
		(width 0.14478)
		(layer "In11.Cu")
		(net "M_L_CPU0_SB_DQ<18>")
	)
	(segment
		(start 387.42874 -284.350714)
		(end 387.524752 -284.325314)
		(width 0.0889)
		(layer "In11.Cu")
		(net "M_L_CPU0_SB_DQ<18>")
	)
	(segment
		(start 440.432952 -300.610016)
		(end 440.754516 -300.610016)
		(width 0.14478)
		(layer "In11.Cu")
		(net "M_L_CPU0_SB_DQ<18>")
	)
	(segment
		(start 412.110174 -301.431452)
		(end 412.372048 -301.431452)
		(width 0.14478)
		(layer "In11.Cu")
		(net "M_L_CPU0_SB_DQ<18>")
	)
	(segment
		(start 417.047426 -300.465236)
		(end 417.047426 -300.369732)
		(width 0.14478)
		(layer "In11.Cu")
		(net "M_L_CPU0_SB_DQ<18>")
	)
	(segment
		(start 436.43931 -301.460154)
		(end 436.722012 -301.460154)
		(width 0.14478)
		(layer "In11.Cu")
		(net "M_L_CPU0_SB_DQ<18>")
	)
	(segment
		(start 413.068262 -301.230792)
		(end 413.068262 -301.286672)
		(width 0.14478)
		(layer "In11.Cu")
		(net "M_L_CPU0_SB_DQ<18>")
	)
	(segment
		(start 437.851296 -300.610016)
		(end 437.996076 -300.465236)
		(width 0.14478)
		(layer "In11.Cu")
		(net "M_L_CPU0_SB_DQ<18>")
	)
	(segment
		(start 416.495992 -300.369732)
		(end 416.495992 -300.465236)
		(width 0.14478)
		(layer "In11.Cu")
		(net "M_L_CPU0_SB_DQ<18>")
	)
	(segment
		(start 448.128898 -300.362112)
		(end 448.128898 -300.85792)
		(width 0.14478)
		(layer "In11.Cu")
		(net "M_L_CPU0_SB_DQ<18>")
	)
	(segment
		(start 432.94427 -300.610016)
		(end 433.210462 -300.610016)
		(width 0.14478)
		(layer "In11.Cu")
		(net "M_L_CPU0_SB_DQ<18>")
	)
	(segment
		(start 436.722012 -301.460154)
		(end 437.57215 -300.610016)
		(width 0.14478)
		(layer "In11.Cu")
		(net "M_L_CPU0_SB_DQ<18>")
	)
	(segment
		(start 447.577464 -300.362112)
		(end 447.722244 -300.217332)
		(width 0.14478)
		(layer "In11.Cu")
		(net "M_L_CPU0_SB_DQ<18>")
	)
	(segment
		(start 415.944558 -300.369732)
		(end 416.089338 -300.224952)
		(width 0.14478)
		(layer "In11.Cu")
		(net "M_L_CPU0_SB_DQ<18>")
	)
	(segment
		(start 416.495992 -300.465236)
		(end 416.640772 -300.610016)
		(width 0.14478)
		(layer "In11.Cu")
		(net "M_L_CPU0_SB_DQ<18>")
	)
	(segment
		(start 420.652956 -301.205392)
		(end 420.797736 -301.060612)
		(width 0.14478)
		(layer "In11.Cu")
		(net "M_L_CPU0_SB_DQ<18>")
	)
	(segment
		(start 440.754516 -300.610016)
		(end 441.6044 -301.4599)
		(width 0.14478)
		(layer "In11.Cu")
		(net "M_L_CPU0_SB_DQ<18>")
	)
	(segment
		(start 448.273678 -301.0027)
		(end 448.535552 -301.0027)
		(width 0.14478)
		(layer "In11.Cu")
		(net "M_L_CPU0_SB_DQ<18>")
	)
	(segment
		(start 403.495256 -291.884608)
		(end 403.495256 -294.595042)
		(width 0.14478)
		(layer "In11.Cu")
		(net "M_L_CPU0_SB_DQ<18>")
	)
	(segment
		(start 413.474916 -301.431452)
		(end 413.619696 -301.286672)
		(width 0.14478)
		(layer "In11.Cu")
		(net "M_L_CPU0_SB_DQ<18>")
	)
	(segment
		(start 417.45408 -300.224952)
		(end 417.59886 -300.369732)
		(width 0.14478)
		(layer "In11.Cu")
		(net "M_L_CPU0_SB_DQ<18>")
	)
	(segment
		(start 438.54751 -300.362112)
		(end 438.54751 -300.465236)
		(width 0.14478)
		(layer "In11.Cu")
		(net "M_L_CPU0_SB_DQ<18>")
	)
	(segment
		(start 438.140856 -300.217332)
		(end 438.40273 -300.217332)
		(width 0.14478)
		(layer "In11.Cu")
		(net "M_L_CPU0_SB_DQ<18>")
	)
	(segment
		(start 412.516828 -301.286672)
		(end 412.516828 -301.230792)
		(width 0.14478)
		(layer "In11.Cu")
		(net "M_L_CPU0_SB_DQ<18>")
	)
	(segment
		(start 447.984118 -300.217332)
		(end 448.128898 -300.362112)
		(width 0.14478)
		(layer "In11.Cu")
		(net "M_L_CPU0_SB_DQ<18>")
	)
	(segment
		(start 436.14975 -301.078392)
		(end 436.29453 -301.223172)
		(width 0.14478)
		(layer "In11.Cu")
		(net "M_L_CPU0_SB_DQ<18>")
	)
	(segment
		(start 416.640772 -300.610016)
		(end 416.902646 -300.610016)
		(width 0.14478)
		(layer "In11.Cu")
		(net "M_L_CPU0_SB_DQ<18>")
	)
	(segment
		(start 389.90778 -284.293564)
		(end 389.916162 -284.288738)
		(width 0.0889)
		(layer "In11.Cu")
		(net "M_L_CPU0_SB_DQ<18>")
	)
	(segment
		(start 439.591958 -300.610016)
		(end 439.736738 -300.465236)
		(width 0.14478)
		(layer "In11.Cu")
		(net "M_L_CPU0_SB_DQ<18>")
	)
	(segment
		(start 449.231766 -300.362112)
		(end 449.231766 -300.465236)
		(width 0.14478)
		(layer "In11.Cu")
		(net "M_L_CPU0_SB_DQ<18>")
	)
	(segment
		(start 432.392836 -300.217332)
		(end 432.65471 -300.217332)
		(width 0.14478)
		(layer "In11.Cu")
		(net "M_L_CPU0_SB_DQ<18>")
	)
	(segment
		(start 448.128898 -300.85792)
		(end 448.273678 -301.0027)
		(width 0.14478)
		(layer "In11.Cu")
		(net "M_L_CPU0_SB_DQ<18>")
	)
	(segment
		(start 413.619696 -301.286672)
		(end 413.619696 -301.230792)
		(width 0.14478)
		(layer "In11.Cu")
		(net "M_L_CPU0_SB_DQ<18>")
	)
	(arc
		(start 387.524752 -284.325314)
		(mid 387.77996 -284.368791)
		(end 388.027672 -284.293564)
		(width 0.0889)
		(layer "In11.Cu")
		(net "M_L_CPU0_SB_DQ<18>")
	)
	(arc
		(start 389.341868 -284.293564)
		(mid 389.624824 -284.369741)
		(end 389.90778 -284.293564)
		(width 0.0889)
		(layer "In11.Cu")
		(net "M_L_CPU0_SB_DQ<18>")
	)
	(arc
		(start 388.401814 -284.293564)
		(mid 388.68477 -284.369741)
		(end 388.967726 -284.293564)
		(width 0.0889)
		(layer "In11.Cu")
		(net "M_L_CPU0_SB_DQ<18>")
	)
	(arc
		(start 391.221722 -284.293564)
		(mid 391.504678 -284.369741)
		(end 391.787634 -284.293564)
		(width 0.0889)
		(layer "In11.Cu")
		(net "M_L_CPU0_SB_DQ<18>")
	)
	(arc
		(start 392.738356 -284.286706)
		(mid 392.920611 -284.243053)
		(end 393.101068 -284.293564)
		(width 0.0889)
		(layer "In11.Cu")
		(net "M_L_CPU0_SB_DQ<18>")
	)
	(arc
		(start 388.027672 -284.293564)
		(mid 388.209923 -284.243214)
		(end 388.393432 -284.288738)
		(width 0.0889)
		(layer "In11.Cu")
		(net "M_L_CPU0_SB_DQ<18>")
	)
	(arc
		(start 388.967726 -284.293564)
		(mid 389.149977 -284.243214)
		(end 389.333486 -284.288738)
		(width 0.0889)
		(layer "In11.Cu")
		(net "M_L_CPU0_SB_DQ<18>")
	)
	(arc
		(start 389.916162 -284.288738)
		(mid 390.09967 -284.243244)
		(end 390.281922 -284.293564)
		(width 0.0889)
		(layer "In11.Cu")
		(net "M_L_CPU0_SB_DQ<18>")
	)
	(arc
		(start 390.847834 -284.293564)
		(mid 391.034778 -284.243309)
		(end 391.221722 -284.293564)
		(width 0.0889)
		(layer "In11.Cu")
		(net "M_L_CPU0_SB_DQ<18>")
	)
	(arc
		(start 391.787634 -284.293564)
		(mid 391.965284 -284.243304)
		(end 392.145266 -284.28442)
		(width 0.0889)
		(layer "In11.Cu")
		(net "M_L_CPU0_SB_DQ<18>")
	)
	(arc
		(start 390.281922 -284.293564)
		(mid 390.564878 -284.369741)
		(end 390.847834 -284.293564)
		(width 0.0889)
		(layer "In11.Cu")
		(net "M_L_CPU0_SB_DQ<18>")
	)
	(arc
		(start 392.17346 -284.300676)
		(mid 392.450994 -284.369657)
		(end 392.726672 -284.293564)
		(width 0.0889)
		(layer "In11.Cu")
		(net "M_L_CPU0_SB_DQ<18>")
	)
	(arc
		(start 393.101068 -284.293564)
		(mid 393.237861 -284.350586)
		(end 393.384786 -284.370018)
		(width 0.0889)
		(layer "In11.Cu")
		(net "M_L_CPU0_SB_DQ<18>")
	)
	(segment
		(start 385.86791 -284.350206)
		(end 386.334762 -284.616144)
		(width 0.10668)
		(layer "F.Cu")
		(net "M_L_CPU0_SB_DQ<17>")
	)
	(segment
		(start 452.80199 -302.14951)
		(end 452.965058 -301.986442)
		(width 0.14478)
		(layer "In11.Cu")
		(net "M_L_CPU0_SB_DQ<17>")
	)
	(segment
		(start 452.408544 -301.986442)
		(end 452.571612 -302.14951)
		(width 0.14478)
		(layer "In11.Cu")
		(net "M_L_CPU0_SB_DQ<17>")
	)
	(segment
		(start 444.307214 -302.309784)
		(end 445.157098 -301.4599)
		(width 0.14478)
		(layer "In11.Cu")
		(net "M_L_CPU0_SB_DQ<17>")
	)
	(segment
		(start 386.334762 -284.616144)
		(end 386.180838 -284.881574)
		(width 0.0889)
		(layer "In11.Cu")
		(net "M_L_CPU0_SB_DQ<17>")
	)
	(segment
		(start 396.49019 -285.52267)
		(end 403.040596 -292.073076)
		(width 0.14478)
		(layer "In11.Cu")
		(net "M_L_CPU0_SB_DQ<17>")
	)
	(segment
		(start 394.070332 -285.231332)
		(end 395.289278 -285.231332)
		(width 0.0889)
		(layer "In11.Cu")
		(net "M_L_CPU0_SB_DQ<17>")
	)
	(segment
		(start 415.032952 -301.4599)
		(end 418.057076 -301.4599)
		(width 0.14478)
		(layer "In11.Cu")
		(net "M_L_CPU0_SB_DQ<17>")
	)
	(segment
		(start 433.995322 -302.310038)
		(end 436.602632 -302.310038)
		(width 0.14478)
		(layer "In11.Cu")
		(net "M_L_CPU0_SB_DQ<17>")
	)
	(segment
		(start 426.451268 -302.310038)
		(end 429.058578 -302.310038)
		(width 0.14478)
		(layer "In11.Cu")
		(net "M_L_CPU0_SB_DQ<17>")
	)
	(segment
		(start 388.393432 -284.94355)
		(end 388.401814 -284.938724)
		(width 0.0889)
		(layer "In11.Cu")
		(net "M_L_CPU0_SB_DQ<17>")
	)
	(segment
		(start 441.53963 -302.309784)
		(end 444.307214 -302.309784)
		(width 0.14478)
		(layer "In11.Cu")
		(net "M_L_CPU0_SB_DQ<17>")
	)
	(segment
		(start 393.384532 -284.863032)
		(end 393.702032 -284.863032)
		(width 0.0889)
		(layer "In11.Cu")
		(net "M_L_CPU0_SB_DQ<17>")
	)
	(segment
		(start 433.145438 -301.460154)
		(end 433.995322 -302.310038)
		(width 0.14478)
		(layer "In11.Cu")
		(net "M_L_CPU0_SB_DQ<17>")
	)
	(segment
		(start 393.702032 -284.863032)
		(end 394.070332 -285.231332)
		(width 0.0889)
		(layer "In11.Cu")
		(net "M_L_CPU0_SB_DQ<17>")
	)
	(segment
		(start 452.245476 -301.4599)
		(end 452.408544 -301.622968)
		(width 0.14478)
		(layer "In11.Cu")
		(net "M_L_CPU0_SB_DQ<17>")
	)
	(segment
		(start 452.965058 -301.622968)
		(end 453.128126 -301.4599)
		(width 0.14478)
		(layer "In11.Cu")
		(net "M_L_CPU0_SB_DQ<17>")
	)
	(segment
		(start 453.128126 -301.4599)
		(end 453.762872 -301.4599)
		(width 0.14478)
		(layer "In11.Cu")
		(net "M_L_CPU0_SB_DQ<17>")
	)
	(segment
		(start 436.602632 -302.310038)
		(end 437.452516 -301.460154)
		(width 0.14478)
		(layer "In11.Cu")
		(net "M_L_CPU0_SB_DQ<17>")
	)
	(segment
		(start 421.466772 -302.310038)
		(end 422.316656 -301.460154)
		(width 0.14478)
		(layer "In11.Cu")
		(net "M_L_CPU0_SB_DQ<17>")
	)
	(segment
		(start 410.530548 -302.310038)
		(end 414.182814 -302.310038)
		(width 0.14478)
		(layer "In11.Cu")
		(net "M_L_CPU0_SB_DQ<17>")
	)
	(segment
		(start 395.793976 -285.52267)
		(end 396.49019 -285.52267)
		(width 0.14478)
		(layer "In11.Cu")
		(net "M_L_CPU0_SB_DQ<17>")
	)
	(segment
		(start 418.907214 -302.310038)
		(end 421.466772 -302.310038)
		(width 0.14478)
		(layer "In11.Cu")
		(net "M_L_CPU0_SB_DQ<17>")
	)
	(segment
		(start 429.908462 -301.460154)
		(end 433.145438 -301.460154)
		(width 0.14478)
		(layer "In11.Cu")
		(net "M_L_CPU0_SB_DQ<17>")
	)
	(segment
		(start 389.90778 -284.938724)
		(end 389.916162 -284.94355)
		(width 0.0889)
		(layer "In11.Cu")
		(net "M_L_CPU0_SB_DQ<17>")
	)
	(segment
		(start 391.787634 -284.938724)
		(end 391.802112 -284.947106)
		(width 0.0889)
		(layer "In11.Cu")
		(net "M_L_CPU0_SB_DQ<17>")
	)
	(segment
		(start 425.601384 -301.460154)
		(end 426.451268 -302.310038)
		(width 0.14478)
		(layer "In11.Cu")
		(net "M_L_CPU0_SB_DQ<17>")
	)
	(segment
		(start 453.762872 -301.4599)
		(end 454.188068 -301.885096)
		(width 0.14478)
		(layer "In11.Cu")
		(net "M_L_CPU0_SB_DQ<17>")
	)
	(segment
		(start 389.333486 -284.94355)
		(end 389.341868 -284.938724)
		(width 0.0889)
		(layer "In11.Cu")
		(net "M_L_CPU0_SB_DQ<17>")
	)
	(segment
		(start 395.580616 -285.52267)
		(end 395.793976 -285.52267)
		(width 0.0889)
		(layer "In11.Cu")
		(net "M_L_CPU0_SB_DQ<17>")
	)
	(segment
		(start 395.289278 -285.231332)
		(end 395.580616 -285.52267)
		(width 0.0889)
		(layer "In11.Cu")
		(net "M_L_CPU0_SB_DQ<17>")
	)
	(segment
		(start 403.040596 -294.820086)
		(end 410.530548 -302.310038)
		(width 0.14478)
		(layer "In11.Cu")
		(net "M_L_CPU0_SB_DQ<17>")
	)
	(segment
		(start 452.965058 -301.986442)
		(end 452.965058 -301.622968)
		(width 0.14478)
		(layer "In11.Cu")
		(net "M_L_CPU0_SB_DQ<17>")
	)
	(segment
		(start 392.706606 -284.925008)
		(end 392.729974 -284.938724)
		(width 0.0889)
		(layer "In11.Cu")
		(net "M_L_CPU0_SB_DQ<17>")
	)
	(segment
		(start 452.571612 -302.14951)
		(end 452.80199 -302.14951)
		(width 0.14478)
		(layer "In11.Cu")
		(net "M_L_CPU0_SB_DQ<17>")
	)
	(segment
		(start 422.316656 -301.460154)
		(end 425.601384 -301.460154)
		(width 0.14478)
		(layer "In11.Cu")
		(net "M_L_CPU0_SB_DQ<17>")
	)
	(segment
		(start 440.689492 -301.460154)
		(end 441.539376 -302.310038)
		(width 0.14478)
		(layer "In11.Cu")
		(net "M_L_CPU0_SB_DQ<17>")
	)
	(segment
		(start 429.058578 -302.310038)
		(end 429.908462 -301.460154)
		(width 0.14478)
		(layer "In11.Cu")
		(net "M_L_CPU0_SB_DQ<17>")
	)
	(segment
		(start 386.180838 -284.881574)
		(end 386.20319 -284.964886)
		(width 0.0889)
		(layer "In11.Cu")
		(net "M_L_CPU0_SB_DQ<17>")
	)
	(segment
		(start 452.408544 -301.622968)
		(end 452.408544 -301.986442)
		(width 0.14478)
		(layer "In11.Cu")
		(net "M_L_CPU0_SB_DQ<17>")
	)
	(segment
		(start 437.452516 -301.460154)
		(end 440.689492 -301.460154)
		(width 0.14478)
		(layer "In11.Cu")
		(net "M_L_CPU0_SB_DQ<17>")
	)
	(segment
		(start 393.083288 -284.9499)
		(end 393.103354 -284.93847)
		(width 0.0889)
		(layer "In11.Cu")
		(net "M_L_CPU0_SB_DQ<17>")
	)
	(segment
		(start 403.040596 -292.073076)
		(end 403.040596 -294.820086)
		(width 0.14478)
		(layer "In11.Cu")
		(net "M_L_CPU0_SB_DQ<17>")
	)
	(segment
		(start 414.182814 -302.310038)
		(end 415.032952 -301.4599)
		(width 0.14478)
		(layer "In11.Cu")
		(net "M_L_CPU0_SB_DQ<17>")
	)
	(segment
		(start 441.539376 -302.310038)
		(end 441.53963 -302.309784)
		(width 0.14478)
		(layer "In11.Cu")
		(net "M_L_CPU0_SB_DQ<17>")
	)
	(segment
		(start 445.157098 -301.4599)
		(end 452.245476 -301.4599)
		(width 0.14478)
		(layer "In11.Cu")
		(net "M_L_CPU0_SB_DQ<17>")
	)
	(segment
		(start 418.057076 -301.4599)
		(end 418.907214 -302.310038)
		(width 0.14478)
		(layer "In11.Cu")
		(net "M_L_CPU0_SB_DQ<17>")
	)
	(arc
		(start 392.162792 -284.938724)
		(mid 392.432949 -284.861962)
		(end 392.706606 -284.925008)
		(width 0.0889)
		(layer "In11.Cu")
		(net "M_L_CPU0_SB_DQ<17>")
	)
	(arc
		(start 387.46176 -284.938724)
		(mid 387.744716 -284.862547)
		(end 388.027672 -284.938724)
		(width 0.0889)
		(layer "In11.Cu")
		(net "M_L_CPU0_SB_DQ<17>")
	)
	(arc
		(start 390.847834 -284.938724)
		(mid 391.034778 -284.988979)
		(end 391.221722 -284.938724)
		(width 0.0889)
		(layer "In11.Cu")
		(net "M_L_CPU0_SB_DQ<17>")
	)
	(arc
		(start 390.281922 -284.938724)
		(mid 390.564878 -284.862547)
		(end 390.847834 -284.938724)
		(width 0.0889)
		(layer "In11.Cu")
		(net "M_L_CPU0_SB_DQ<17>")
	)
	(arc
		(start 391.221722 -284.938724)
		(mid 391.504678 -284.862547)
		(end 391.787634 -284.938724)
		(width 0.0889)
		(layer "In11.Cu")
		(net "M_L_CPU0_SB_DQ<17>")
	)
	(arc
		(start 391.802112 -284.947106)
		(mid 391.983528 -284.989363)
		(end 392.162792 -284.938724)
		(width 0.0889)
		(layer "In11.Cu")
		(net "M_L_CPU0_SB_DQ<17>")
	)
	(arc
		(start 389.341868 -284.938724)
		(mid 389.624824 -284.862547)
		(end 389.90778 -284.938724)
		(width 0.0889)
		(layer "In11.Cu")
		(net "M_L_CPU0_SB_DQ<17>")
	)
	(arc
		(start 389.916162 -284.94355)
		(mid 390.09967 -284.989044)
		(end 390.281922 -284.938724)
		(width 0.0889)
		(layer "In11.Cu")
		(net "M_L_CPU0_SB_DQ<17>")
	)
	(arc
		(start 392.729974 -284.938724)
		(mid 392.905213 -284.988795)
		(end 393.083288 -284.9499)
		(width 0.0889)
		(layer "In11.Cu")
		(net "M_L_CPU0_SB_DQ<17>")
	)
	(arc
		(start 386.52196 -284.938724)
		(mid 386.804916 -284.862547)
		(end 387.087872 -284.938724)
		(width 0.0889)
		(layer "In11.Cu")
		(net "M_L_CPU0_SB_DQ<17>")
	)
	(arc
		(start 386.20319 -284.964886)
		(mid 386.365522 -284.987704)
		(end 386.52196 -284.938724)
		(width 0.0889)
		(layer "In11.Cu")
		(net "M_L_CPU0_SB_DQ<17>")
	)
	(arc
		(start 387.087872 -284.938724)
		(mid 387.274816 -284.988979)
		(end 387.46176 -284.938724)
		(width 0.0889)
		(layer "In11.Cu")
		(net "M_L_CPU0_SB_DQ<17>")
	)
	(arc
		(start 388.027672 -284.938724)
		(mid 388.209923 -284.989074)
		(end 388.393432 -284.94355)
		(width 0.0889)
		(layer "In11.Cu")
		(net "M_L_CPU0_SB_DQ<17>")
	)
	(arc
		(start 388.401814 -284.938724)
		(mid 388.68477 -284.862547)
		(end 388.967726 -284.938724)
		(width 0.0889)
		(layer "In11.Cu")
		(net "M_L_CPU0_SB_DQ<17>")
	)
	(arc
		(start 388.967726 -284.938724)
		(mid 389.149977 -284.989074)
		(end 389.333486 -284.94355)
		(width 0.0889)
		(layer "In11.Cu")
		(net "M_L_CPU0_SB_DQ<17>")
	)
	(arc
		(start 393.103354 -284.93847)
		(mid 393.238987 -284.882295)
		(end 393.384532 -284.863032)
		(width 0.0889)
		(layer "In11.Cu")
		(net "M_L_CPU0_SB_DQ<17>")
	)
	(segment
		(start 387.277864 -283.5402)
		(end 387.744716 -283.806138)
		(width 0.10668)
		(layer "F.Cu")
		(net "M_L_CPU0_SB_DQ<16>")
	)
	(segment
		(start 445.239394 -299.759878)
		(end 450.964046 -299.759878)
		(width 0.14478)
		(layer "In11.Cu")
		(net "M_L_CPU0_SB_DQ<16>")
	)
	(segment
		(start 426.451268 -300.610016)
		(end 429.270922 -300.610016)
		(width 0.14478)
		(layer "In11.Cu")
		(net "M_L_CPU0_SB_DQ<16>")
	)
	(segment
		(start 440.711844 -299.760132)
		(end 441.561474 -300.609762)
		(width 0.14478)
		(layer "In11.Cu")
		(net "M_L_CPU0_SB_DQ<16>")
	)
	(segment
		(start 390.74344 -284.133544)
		(end 390.751822 -284.128718)
		(width 0.0889)
		(layer "In11.Cu")
		(net "M_L_CPU0_SB_DQ<16>")
	)
	(segment
		(start 430.120806 -299.760132)
		(end 433.145438 -299.760132)
		(width 0.14478)
		(layer "In11.Cu")
		(net "M_L_CPU0_SB_DQ<16>")
	)
	(segment
		(start 414.182814 -300.610016)
		(end 415.032952 -299.759878)
		(width 0.14478)
		(layer "In11.Cu")
		(net "M_L_CPU0_SB_DQ<16>")
	)
	(segment
		(start 394.811758 -284.738572)
		(end 395.241018 -284.738572)
		(width 0.0889)
		(layer "In11.Cu")
		(net "M_L_CPU0_SB_DQ<16>")
	)
	(segment
		(start 395.241018 -284.738572)
		(end 395.36624 -284.61335)
		(width 0.0889)
		(layer "In11.Cu")
		(net "M_L_CPU0_SB_DQ<16>")
	)
	(segment
		(start 387.744716 -283.806138)
		(end 387.590792 -284.071568)
		(width 0.0889)
		(layer "In11.Cu")
		(net "M_L_CPU0_SB_DQ<16>")
	)
	(segment
		(start 429.270922 -300.610016)
		(end 430.120806 -299.760132)
		(width 0.14478)
		(layer "In11.Cu")
		(net "M_L_CPU0_SB_DQ<16>")
	)
	(segment
		(start 452.077074 -299.759878)
		(end 452.240142 -299.922946)
		(width 0.14478)
		(layer "In11.Cu")
		(net "M_L_CPU0_SB_DQ<16>")
	)
	(segment
		(start 403.949916 -294.406574)
		(end 410.153358 -300.610016)
		(width 0.14478)
		(layer "In11.Cu")
		(net "M_L_CPU0_SB_DQ<16>")
	)
	(segment
		(start 452.40321 -300.80331)
		(end 452.633588 -300.80331)
		(width 0.14478)
		(layer "In11.Cu")
		(net "M_L_CPU0_SB_DQ<16>")
	)
	(segment
		(start 418.057076 -299.759878)
		(end 418.907214 -300.610016)
		(width 0.14478)
		(layer "In11.Cu")
		(net "M_L_CPU0_SB_DQ<16>")
	)
	(segment
		(start 452.240142 -300.640242)
		(end 452.40321 -300.80331)
		(width 0.14478)
		(layer "In11.Cu")
		(net "M_L_CPU0_SB_DQ<16>")
	)
	(segment
		(start 437.66486 -299.760132)
		(end 440.711844 -299.760132)
		(width 0.14478)
		(layer "In11.Cu")
		(net "M_L_CPU0_SB_DQ<16>")
	)
	(segment
		(start 450.964046 -299.759878)
		(end 451.127114 -299.922946)
		(width 0.14478)
		(layer "In11.Cu")
		(net "M_L_CPU0_SB_DQ<16>")
	)
	(segment
		(start 425.601384 -299.760132)
		(end 426.451268 -300.610016)
		(width 0.14478)
		(layer "In11.Cu")
		(net "M_L_CPU0_SB_DQ<16>")
	)
	(segment
		(start 451.290182 -300.80331)
		(end 451.52056 -300.80331)
		(width 0.14478)
		(layer "In11.Cu")
		(net "M_L_CPU0_SB_DQ<16>")
	)
	(segment
		(start 452.796656 -299.922946)
		(end 452.959724 -299.759878)
		(width 0.14478)
		(layer "In11.Cu")
		(net "M_L_CPU0_SB_DQ<16>")
	)
	(segment
		(start 451.127114 -299.922946)
		(end 451.127114 -300.640242)
		(width 0.14478)
		(layer "In11.Cu")
		(net "M_L_CPU0_SB_DQ<16>")
	)
	(segment
		(start 422.576752 -299.760132)
		(end 425.601384 -299.760132)
		(width 0.14478)
		(layer "In11.Cu")
		(net "M_L_CPU0_SB_DQ<16>")
	)
	(segment
		(start 451.127114 -300.640242)
		(end 451.290182 -300.80331)
		(width 0.14478)
		(layer "In11.Cu")
		(net "M_L_CPU0_SB_DQ<16>")
	)
	(segment
		(start 451.52056 -300.80331)
		(end 451.683628 -300.640242)
		(width 0.14478)
		(layer "In11.Cu")
		(net "M_L_CPU0_SB_DQ<16>")
	)
	(segment
		(start 433.145438 -299.760132)
		(end 433.995322 -300.610016)
		(width 0.14478)
		(layer "In11.Cu")
		(net "M_L_CPU0_SB_DQ<16>")
	)
	(segment
		(start 393.384786 -284.179518)
		(end 394.252704 -284.179518)
		(width 0.0889)
		(layer "In11.Cu")
		(net "M_L_CPU0_SB_DQ<16>")
	)
	(segment
		(start 453.762872 -299.759878)
		(end 454.188068 -300.185074)
		(width 0.14478)
		(layer "In11.Cu")
		(net "M_L_CPU0_SB_DQ<16>")
	)
	(segment
		(start 418.907214 -300.610016)
		(end 421.726868 -300.610016)
		(width 0.14478)
		(layer "In11.Cu")
		(net "M_L_CPU0_SB_DQ<16>")
	)
	(segment
		(start 452.959724 -299.759878)
		(end 453.762872 -299.759878)
		(width 0.14478)
		(layer "In11.Cu")
		(net "M_L_CPU0_SB_DQ<16>")
	)
	(segment
		(start 403.949916 -291.69614)
		(end 403.949916 -294.406574)
		(width 0.14478)
		(layer "In11.Cu")
		(net "M_L_CPU0_SB_DQ<16>")
	)
	(segment
		(start 392.63066 -284.128718)
		(end 392.648694 -284.11805)
		(width 0.0889)
		(layer "In11.Cu")
		(net "M_L_CPU0_SB_DQ<16>")
	)
	(segment
		(start 395.816836 -284.61335)
		(end 396.867126 -284.61335)
		(width 0.14478)
		(layer "In11.Cu")
		(net "M_L_CPU0_SB_DQ<16>")
	)
	(segment
		(start 395.36624 -284.61335)
		(end 395.816836 -284.61335)
		(width 0.0889)
		(layer "In11.Cu")
		(net "M_L_CPU0_SB_DQ<16>")
	)
	(segment
		(start 421.726868 -300.610016)
		(end 422.576752 -299.760132)
		(width 0.14478)
		(layer "In11.Cu")
		(net "M_L_CPU0_SB_DQ<16>")
	)
	(segment
		(start 452.796656 -300.640242)
		(end 452.796656 -299.922946)
		(width 0.14478)
		(layer "In11.Cu")
		(net "M_L_CPU0_SB_DQ<16>")
	)
	(segment
		(start 410.153358 -300.610016)
		(end 414.182814 -300.610016)
		(width 0.14478)
		(layer "In11.Cu")
		(net "M_L_CPU0_SB_DQ<16>")
	)
	(segment
		(start 451.683628 -299.922946)
		(end 451.846696 -299.759878)
		(width 0.14478)
		(layer "In11.Cu")
		(net "M_L_CPU0_SB_DQ<16>")
	)
	(segment
		(start 433.995322 -300.610016)
		(end 436.814976 -300.610016)
		(width 0.14478)
		(layer "In11.Cu")
		(net "M_L_CPU0_SB_DQ<16>")
	)
	(segment
		(start 436.814976 -300.610016)
		(end 437.66486 -299.760132)
		(width 0.14478)
		(layer "In11.Cu")
		(net "M_L_CPU0_SB_DQ<16>")
	)
	(segment
		(start 391.317734 -284.128718)
		(end 391.326116 -284.133544)
		(width 0.0889)
		(layer "In11.Cu")
		(net "M_L_CPU0_SB_DQ<16>")
	)
	(segment
		(start 444.38951 -300.609762)
		(end 445.239394 -299.759878)
		(width 0.14478)
		(layer "In11.Cu")
		(net "M_L_CPU0_SB_DQ<16>")
	)
	(segment
		(start 415.032952 -299.759878)
		(end 418.057076 -299.759878)
		(width 0.14478)
		(layer "In11.Cu")
		(net "M_L_CPU0_SB_DQ<16>")
	)
	(segment
		(start 392.257026 -284.128464)
		(end 392.270742 -284.136338)
		(width 0.0889)
		(layer "In11.Cu")
		(net "M_L_CPU0_SB_DQ<16>")
	)
	(segment
		(start 388.497826 -284.128718)
		(end 388.506208 -284.133544)
		(width 0.0889)
		(layer "In11.Cu")
		(net "M_L_CPU0_SB_DQ<16>")
	)
	(segment
		(start 394.252704 -284.179518)
		(end 394.811758 -284.738572)
		(width 0.0889)
		(layer "In11.Cu")
		(net "M_L_CPU0_SB_DQ<16>")
	)
	(segment
		(start 452.633588 -300.80331)
		(end 452.796656 -300.640242)
		(width 0.14478)
		(layer "In11.Cu")
		(net "M_L_CPU0_SB_DQ<16>")
	)
	(segment
		(start 441.561474 -300.609762)
		(end 444.38951 -300.609762)
		(width 0.14478)
		(layer "In11.Cu")
		(net "M_L_CPU0_SB_DQ<16>")
	)
	(segment
		(start 451.846696 -299.759878)
		(end 452.077074 -299.759878)
		(width 0.14478)
		(layer "In11.Cu")
		(net "M_L_CPU0_SB_DQ<16>")
	)
	(segment
		(start 392.245088 -284.121606)
		(end 392.257026 -284.128464)
		(width 0.0889)
		(layer "In11.Cu")
		(net "M_L_CPU0_SB_DQ<16>")
	)
	(segment
		(start 387.590792 -284.071568)
		(end 387.613144 -284.15488)
		(width 0.0889)
		(layer "In11.Cu")
		(net "M_L_CPU0_SB_DQ<16>")
	)
	(segment
		(start 452.240142 -299.922946)
		(end 452.240142 -300.640242)
		(width 0.14478)
		(layer "In11.Cu")
		(net "M_L_CPU0_SB_DQ<16>")
	)
	(segment
		(start 451.683628 -300.640242)
		(end 451.683628 -299.922946)
		(width 0.14478)
		(layer "In11.Cu")
		(net "M_L_CPU0_SB_DQ<16>")
	)
	(segment
		(start 396.867126 -284.61335)
		(end 403.949916 -291.69614)
		(width 0.14478)
		(layer "In11.Cu")
		(net "M_L_CPU0_SB_DQ<16>")
	)
	(arc
		(start 390.751822 -284.128718)
		(mid 391.034778 -284.052541)
		(end 391.317734 -284.128718)
		(width 0.0889)
		(layer "In11.Cu")
		(net "M_L_CPU0_SB_DQ<16>")
	)
	(arc
		(start 389.43788 -284.128718)
		(mid 389.624824 -284.178973)
		(end 389.811768 -284.128718)
		(width 0.0889)
		(layer "In11.Cu")
		(net "M_L_CPU0_SB_DQ<16>")
	)
	(arc
		(start 391.691876 -284.128718)
		(mid 391.967554 -284.052588)
		(end 392.245088 -284.121606)
		(width 0.0889)
		(layer "In11.Cu")
		(net "M_L_CPU0_SB_DQ<16>")
	)
	(arc
		(start 393.197334 -284.128718)
		(mid 393.287697 -284.166528)
		(end 393.384786 -284.179518)
		(width 0.0889)
		(layer "In11.Cu")
		(net "M_L_CPU0_SB_DQ<16>")
	)
	(arc
		(start 392.648694 -284.11805)
		(mid 392.924389 -284.052207)
		(end 393.197334 -284.128718)
		(width 0.0889)
		(layer "In11.Cu")
		(net "M_L_CPU0_SB_DQ<16>")
	)
	(arc
		(start 392.270742 -284.136338)
		(mid 392.451672 -284.178816)
		(end 392.63066 -284.128718)
		(width 0.0889)
		(layer "In11.Cu")
		(net "M_L_CPU0_SB_DQ<16>")
	)
	(arc
		(start 387.613144 -284.15488)
		(mid 387.775476 -284.177698)
		(end 387.931914 -284.128718)
		(width 0.0889)
		(layer "In11.Cu")
		(net "M_L_CPU0_SB_DQ<16>")
	)
	(arc
		(start 388.506208 -284.133544)
		(mid 388.689716 -284.179038)
		(end 388.871968 -284.128718)
		(width 0.0889)
		(layer "In11.Cu")
		(net "M_L_CPU0_SB_DQ<16>")
	)
	(arc
		(start 389.811768 -284.128718)
		(mid 390.094724 -284.052541)
		(end 390.37768 -284.128718)
		(width 0.0889)
		(layer "In11.Cu")
		(net "M_L_CPU0_SB_DQ<16>")
	)
	(arc
		(start 390.37768 -284.128718)
		(mid 390.559931 -284.179068)
		(end 390.74344 -284.133544)
		(width 0.0889)
		(layer "In11.Cu")
		(net "M_L_CPU0_SB_DQ<16>")
	)
	(arc
		(start 388.871968 -284.128718)
		(mid 389.154924 -284.052541)
		(end 389.43788 -284.128718)
		(width 0.0889)
		(layer "In11.Cu")
		(net "M_L_CPU0_SB_DQ<16>")
	)
	(arc
		(start 387.931914 -284.128718)
		(mid 388.21487 -284.052541)
		(end 388.497826 -284.128718)
		(width 0.0889)
		(layer "In11.Cu")
		(net "M_L_CPU0_SB_DQ<16>")
	)
	(arc
		(start 391.326116 -284.133544)
		(mid 391.509624 -284.179038)
		(end 391.691876 -284.128718)
		(width 0.0889)
		(layer "In11.Cu")
		(net "M_L_CPU0_SB_DQ<16>")
	)
	(segment
		(start 385.39801 -283.5402)
		(end 385.864862 -283.806138)
		(width 0.10668)
		(layer "F.Cu")
		(net "M_L_CPU0_SB_DQ<15>")
	)
	(segment
		(start 434.0606 -299.760386)
		(end 436.722012 -299.760386)
		(width 0.14478)
		(layer "In11.Cu")
		(net "M_L_CPU0_SB_DQ<15>")
	)
	(segment
		(start 413.297878 -299.50791)
		(end 413.60217 -299.50791)
		(width 0.14478)
		(layer "In11.Cu")
		(net "M_L_CPU0_SB_DQ<15>")
	)
	(segment
		(start 393.177014 -283.496258)
		(end 393.198604 -283.483812)
		(width 0.0889)
		(layer "In11.Cu")
		(net "M_L_CPU0_SB_DQ<15>")
	)
	(segment
		(start 395.519656 -284.05709)
		(end 395.803882 -284.05709)
		(width 0.0889)
		(layer "In11.Cu")
		(net "M_L_CPU0_SB_DQ<15>")
	)
	(segment
		(start 448.887088 -298.59351)
		(end 449.203826 -298.910248)
		(width 0.14478)
		(layer "In11.Cu")
		(net "M_L_CPU0_SB_DQ<15>")
	)
	(segment
		(start 409.944824 -298.838366)
		(end 409.944824 -299.04309)
		(width 0.14478)
		(layer "In11.Cu")
		(net "M_L_CPU0_SB_DQ<15>")
	)
	(segment
		(start 409.944824 -299.04309)
		(end 409.761436 -299.226478)
		(width 0.14478)
		(layer "In11.Cu")
		(net "M_L_CPU0_SB_DQ<15>")
	)
	(segment
		(start 440.682126 -298.910248)
		(end 441.531756 -299.759878)
		(width 0.14478)
		(layer "In11.Cu")
		(net "M_L_CPU0_SB_DQ<15>")
	)
	(segment
		(start 404.506176 -291.465508)
		(end 404.506176 -294.175942)
		(width 0.14478)
		(layer "In11.Cu")
		(net "M_L_CPU0_SB_DQ<15>")
	)
	(segment
		(start 412.741364 -299.760132)
		(end 413.045656 -299.760132)
		(width 0.14478)
		(layer "In11.Cu")
		(net "M_L_CPU0_SB_DQ<15>")
	)
	(segment
		(start 386.983478 -283.478732)
		(end 386.99186 -283.483558)
		(width 0.0889)
		(layer "In11.Cu")
		(net "M_L_CPU0_SB_DQ<15>")
	)
	(segment
		(start 404.506176 -294.175942)
		(end 408.38628 -298.056046)
		(width 0.14478)
		(layer "In11.Cu")
		(net "M_L_CPU0_SB_DQ<15>")
	)
	(segment
		(start 409.164536 -298.262802)
		(end 408.981148 -298.44619)
		(width 0.14478)
		(layer "In11.Cu")
		(net "M_L_CPU0_SB_DQ<15>")
	)
	(segment
		(start 430.028096 -298.910248)
		(end 433.210462 -298.910248)
		(width 0.14478)
		(layer "In11.Cu")
		(net "M_L_CPU0_SB_DQ<15>")
	)
	(segment
		(start 422.484042 -298.910248)
		(end 425.666408 -298.910248)
		(width 0.14478)
		(layer "In11.Cu")
		(net "M_L_CPU0_SB_DQ<15>")
	)
	(segment
		(start 437.57215 -298.910248)
		(end 440.682126 -298.910248)
		(width 0.14478)
		(layer "In11.Cu")
		(net "M_L_CPU0_SB_DQ<15>")
	)
	(segment
		(start 426.516546 -299.760386)
		(end 429.177958 -299.760386)
		(width 0.14478)
		(layer "In11.Cu")
		(net "M_L_CPU0_SB_DQ<15>")
	)
	(segment
		(start 449.203826 -298.910248)
		(end 449.663058 -298.910248)
		(width 0.14478)
		(layer "In11.Cu")
		(net "M_L_CPU0_SB_DQ<15>")
	)
	(segment
		(start 444.357252 -299.759878)
		(end 445.206882 -298.910248)
		(width 0.14478)
		(layer "In11.Cu")
		(net "M_L_CPU0_SB_DQ<15>")
	)
	(segment
		(start 409.55468 -298.652946)
		(end 409.759404 -298.652946)
		(width 0.14478)
		(layer "In11.Cu")
		(net "M_L_CPU0_SB_DQ<15>")
	)
	(segment
		(start 414.090358 -299.760132)
		(end 414.940496 -298.909994)
		(width 0.14478)
		(layer "In11.Cu")
		(net "M_L_CPU0_SB_DQ<15>")
	)
	(segment
		(start 408.38628 -298.056046)
		(end 408.591004 -298.056046)
		(width 0.14478)
		(layer "In11.Cu")
		(net "M_L_CPU0_SB_DQ<15>")
	)
	(segment
		(start 409.371292 -298.836334)
		(end 409.55468 -298.652946)
		(width 0.14478)
		(layer "In11.Cu")
		(net "M_L_CPU0_SB_DQ<15>")
	)
	(segment
		(start 425.666408 -298.910248)
		(end 426.516546 -299.760386)
		(width 0.14478)
		(layer "In11.Cu")
		(net "M_L_CPU0_SB_DQ<15>")
	)
	(segment
		(start 388.497826 -283.483558)
		(end 388.506208 -283.478732)
		(width 0.0889)
		(layer "In11.Cu")
		(net "M_L_CPU0_SB_DQ<15>")
	)
	(segment
		(start 447.217546 -298.910248)
		(end 447.534284 -298.59351)
		(width 0.14478)
		(layer "In11.Cu")
		(net "M_L_CPU0_SB_DQ<15>")
	)
	(segment
		(start 445.206882 -298.910248)
		(end 447.217546 -298.910248)
		(width 0.14478)
		(layer "In11.Cu")
		(net "M_L_CPU0_SB_DQ<15>")
	)
	(segment
		(start 395.803882 -284.05709)
		(end 397.097758 -284.05709)
		(width 0.14478)
		(layer "In11.Cu")
		(net "M_L_CPU0_SB_DQ<15>")
	)
	(segment
		(start 413.60217 -299.50791)
		(end 413.854392 -299.760132)
		(width 0.14478)
		(layer "In11.Cu")
		(net "M_L_CPU0_SB_DQ<15>")
	)
	(segment
		(start 418.972746 -299.760386)
		(end 421.633904 -299.760386)
		(width 0.14478)
		(layer "In11.Cu")
		(net "M_L_CPU0_SB_DQ<15>")
	)
	(segment
		(start 414.940496 -298.909994)
		(end 418.122354 -298.909994)
		(width 0.14478)
		(layer "In11.Cu")
		(net "M_L_CPU0_SB_DQ<15>")
	)
	(segment
		(start 395.190218 -283.727652)
		(end 395.519656 -284.05709)
		(width 0.0889)
		(layer "In11.Cu")
		(net "M_L_CPU0_SB_DQ<15>")
	)
	(segment
		(start 418.122354 -298.909994)
		(end 418.972746 -299.760386)
		(width 0.14478)
		(layer "In11.Cu")
		(net "M_L_CPU0_SB_DQ<15>")
	)
	(segment
		(start 410.472128 -299.760132)
		(end 410.764228 -299.468032)
		(width 0.14478)
		(layer "In11.Cu")
		(net "M_L_CPU0_SB_DQ<15>")
	)
	(segment
		(start 392.619738 -283.475176)
		(end 392.634216 -283.483558)
		(width 0.0889)
		(layer "In11.Cu")
		(net "M_L_CPU0_SB_DQ<15>")
	)
	(segment
		(start 409.759404 -298.652946)
		(end 409.944824 -298.838366)
		(width 0.14478)
		(layer "In11.Cu")
		(net "M_L_CPU0_SB_DQ<15>")
	)
	(segment
		(start 409.761436 -299.431202)
		(end 410.090366 -299.760132)
		(width 0.14478)
		(layer "In11.Cu")
		(net "M_L_CPU0_SB_DQ<15>")
	)
	(segment
		(start 393.384786 -283.43352)
		(end 394.278358 -283.43352)
		(width 0.0889)
		(layer "In11.Cu")
		(net "M_L_CPU0_SB_DQ<15>")
	)
	(segment
		(start 411.932628 -299.760132)
		(end 412.18485 -299.50791)
		(width 0.14478)
		(layer "In11.Cu")
		(net "M_L_CPU0_SB_DQ<15>")
	)
	(segment
		(start 448.330574 -298.910248)
		(end 448.647312 -298.59351)
		(width 0.14478)
		(layer "In11.Cu")
		(net "M_L_CPU0_SB_DQ<15>")
	)
	(segment
		(start 408.981148 -298.650914)
		(end 409.166568 -298.836334)
		(width 0.14478)
		(layer "In11.Cu")
		(net "M_L_CPU0_SB_DQ<15>")
	)
	(segment
		(start 410.090366 -299.760132)
		(end 410.472128 -299.760132)
		(width 0.14478)
		(layer "In11.Cu")
		(net "M_L_CPU0_SB_DQ<15>")
	)
	(segment
		(start 447.77406 -298.59351)
		(end 448.090798 -298.910248)
		(width 0.14478)
		(layer "In11.Cu")
		(net "M_L_CPU0_SB_DQ<15>")
	)
	(segment
		(start 448.090798 -298.910248)
		(end 448.330574 -298.910248)
		(width 0.14478)
		(layer "In11.Cu")
		(net "M_L_CPU0_SB_DQ<15>")
	)
	(segment
		(start 436.722012 -299.760386)
		(end 437.57215 -298.910248)
		(width 0.14478)
		(layer "In11.Cu")
		(net "M_L_CPU0_SB_DQ<15>")
	)
	(segment
		(start 387.557772 -283.483558)
		(end 387.566154 -283.478732)
		(width 0.0889)
		(layer "In11.Cu")
		(net "M_L_CPU0_SB_DQ<15>")
	)
	(segment
		(start 410.764228 -299.468032)
		(end 411.136338 -299.468032)
		(width 0.14478)
		(layer "In11.Cu")
		(net "M_L_CPU0_SB_DQ<15>")
	)
	(segment
		(start 411.428438 -299.760132)
		(end 411.932628 -299.760132)
		(width 0.14478)
		(layer "In11.Cu")
		(net "M_L_CPU0_SB_DQ<15>")
	)
	(segment
		(start 397.097758 -284.05709)
		(end 404.506176 -291.465508)
		(width 0.14478)
		(layer "In11.Cu")
		(net "M_L_CPU0_SB_DQ<15>")
	)
	(segment
		(start 421.633904 -299.760386)
		(end 422.484042 -298.910248)
		(width 0.14478)
		(layer "In11.Cu")
		(net "M_L_CPU0_SB_DQ<15>")
	)
	(segment
		(start 447.534284 -298.59351)
		(end 447.77406 -298.59351)
		(width 0.14478)
		(layer "In11.Cu")
		(net "M_L_CPU0_SB_DQ<15>")
	)
	(segment
		(start 386.018786 -283.540708)
		(end 386.114798 -283.515308)
		(width 0.0889)
		(layer "In11.Cu")
		(net "M_L_CPU0_SB_DQ<15>")
	)
	(segment
		(start 449.663058 -298.910248)
		(end 450.088 -299.33519)
		(width 0.14478)
		(layer "In11.Cu")
		(net "M_L_CPU0_SB_DQ<15>")
	)
	(segment
		(start 391.317734 -283.483558)
		(end 391.326116 -283.478732)
		(width 0.0889)
		(layer "In11.Cu")
		(net "M_L_CPU0_SB_DQ<15>")
	)
	(segment
		(start 448.647312 -298.59351)
		(end 448.887088 -298.59351)
		(width 0.14478)
		(layer "In11.Cu")
		(net "M_L_CPU0_SB_DQ<15>")
	)
	(segment
		(start 441.531756 -299.759878)
		(end 444.357252 -299.759878)
		(width 0.14478)
		(layer "In11.Cu")
		(net "M_L_CPU0_SB_DQ<15>")
	)
	(segment
		(start 390.74344 -283.478732)
		(end 390.751822 -283.483558)
		(width 0.0889)
		(layer "In11.Cu")
		(net "M_L_CPU0_SB_DQ<15>")
	)
	(segment
		(start 412.489142 -299.50791)
		(end 412.741364 -299.760132)
		(width 0.14478)
		(layer "In11.Cu")
		(net "M_L_CPU0_SB_DQ<15>")
	)
	(segment
		(start 394.57249 -283.727652)
		(end 395.190218 -283.727652)
		(width 0.0889)
		(layer "In11.Cu")
		(net "M_L_CPU0_SB_DQ<15>")
	)
	(segment
		(start 385.864862 -283.806138)
		(end 386.018786 -283.540708)
		(width 0.0889)
		(layer "In11.Cu")
		(net "M_L_CPU0_SB_DQ<15>")
	)
	(segment
		(start 408.774392 -297.872658)
		(end 408.979116 -297.872658)
		(width 0.14478)
		(layer "In11.Cu")
		(net "M_L_CPU0_SB_DQ<15>")
	)
	(segment
		(start 408.981148 -298.44619)
		(end 408.981148 -298.650914)
		(width 0.14478)
		(layer "In11.Cu")
		(net "M_L_CPU0_SB_DQ<15>")
	)
	(segment
		(start 391.691876 -283.483558)
		(end 391.715244 -283.497274)
		(width 0.0889)
		(layer "In11.Cu")
		(net "M_L_CPU0_SB_DQ<15>")
	)
	(segment
		(start 412.18485 -299.50791)
		(end 412.489142 -299.50791)
		(width 0.14478)
		(layer "In11.Cu")
		(net "M_L_CPU0_SB_DQ<15>")
	)
	(segment
		(start 408.591004 -298.056046)
		(end 408.774392 -297.872658)
		(width 0.14478)
		(layer "In11.Cu")
		(net "M_L_CPU0_SB_DQ<15>")
	)
	(segment
		(start 413.045656 -299.760132)
		(end 413.297878 -299.50791)
		(width 0.14478)
		(layer "In11.Cu")
		(net "M_L_CPU0_SB_DQ<15>")
	)
	(segment
		(start 411.136338 -299.468032)
		(end 411.428438 -299.760132)
		(width 0.14478)
		(layer "In11.Cu")
		(net "M_L_CPU0_SB_DQ<15>")
	)
	(segment
		(start 408.979116 -297.872658)
		(end 409.164536 -298.058078)
		(width 0.14478)
		(layer "In11.Cu")
		(net "M_L_CPU0_SB_DQ<15>")
	)
	(segment
		(start 409.166568 -298.836334)
		(end 409.371292 -298.836334)
		(width 0.14478)
		(layer "In11.Cu")
		(net "M_L_CPU0_SB_DQ<15>")
	)
	(segment
		(start 433.210462 -298.910248)
		(end 434.0606 -299.760386)
		(width 0.14478)
		(layer "In11.Cu")
		(net "M_L_CPU0_SB_DQ<15>")
	)
	(segment
		(start 394.278358 -283.43352)
		(end 394.57249 -283.727652)
		(width 0.0889)
		(layer "In11.Cu")
		(net "M_L_CPU0_SB_DQ<15>")
	)
	(segment
		(start 409.761436 -299.226478)
		(end 409.761436 -299.431202)
		(width 0.14478)
		(layer "In11.Cu")
		(net "M_L_CPU0_SB_DQ<15>")
	)
	(segment
		(start 429.177958 -299.760386)
		(end 430.028096 -298.910248)
		(width 0.14478)
		(layer "In11.Cu")
		(net "M_L_CPU0_SB_DQ<15>")
	)
	(segment
		(start 409.164536 -298.058078)
		(end 409.164536 -298.262802)
		(width 0.14478)
		(layer "In11.Cu")
		(net "M_L_CPU0_SB_DQ<15>")
	)
	(segment
		(start 413.854392 -299.760132)
		(end 414.090358 -299.760132)
		(width 0.14478)
		(layer "In11.Cu")
		(net "M_L_CPU0_SB_DQ<15>")
	)
	(arc
		(start 387.931914 -283.483558)
		(mid 388.21487 -283.559735)
		(end 388.497826 -283.483558)
		(width 0.0889)
		(layer "In11.Cu")
		(net "M_L_CPU0_SB_DQ<15>")
	)
	(arc
		(start 389.811768 -283.483558)
		(mid 390.094724 -283.559735)
		(end 390.37768 -283.483558)
		(width 0.0889)
		(layer "In11.Cu")
		(net "M_L_CPU0_SB_DQ<15>")
	)
	(arc
		(start 391.715244 -283.497274)
		(mid 391.988898 -283.560217)
		(end 392.259058 -283.483558)
		(width 0.0889)
		(layer "In11.Cu")
		(net "M_L_CPU0_SB_DQ<15>")
	)
	(arc
		(start 388.871968 -283.483558)
		(mid 389.154924 -283.559735)
		(end 389.43788 -283.483558)
		(width 0.0889)
		(layer "In11.Cu")
		(net "M_L_CPU0_SB_DQ<15>")
	)
	(arc
		(start 390.37768 -283.483558)
		(mid 390.559931 -283.433208)
		(end 390.74344 -283.478732)
		(width 0.0889)
		(layer "In11.Cu")
		(net "M_L_CPU0_SB_DQ<15>")
	)
	(arc
		(start 386.617718 -283.483558)
		(mid 386.799969 -283.433208)
		(end 386.983478 -283.478732)
		(width 0.0889)
		(layer "In11.Cu")
		(net "M_L_CPU0_SB_DQ<15>")
	)
	(arc
		(start 387.566154 -283.478732)
		(mid 387.749662 -283.433238)
		(end 387.931914 -283.483558)
		(width 0.0889)
		(layer "In11.Cu")
		(net "M_L_CPU0_SB_DQ<15>")
	)
	(arc
		(start 390.751822 -283.483558)
		(mid 391.034778 -283.559735)
		(end 391.317734 -283.483558)
		(width 0.0889)
		(layer "In11.Cu")
		(net "M_L_CPU0_SB_DQ<15>")
	)
	(arc
		(start 389.43788 -283.483558)
		(mid 389.624824 -283.433303)
		(end 389.811768 -283.483558)
		(width 0.0889)
		(layer "In11.Cu")
		(net "M_L_CPU0_SB_DQ<15>")
	)
	(arc
		(start 392.259058 -283.483558)
		(mid 392.438321 -283.432894)
		(end 392.619738 -283.475176)
		(width 0.0889)
		(layer "In11.Cu")
		(net "M_L_CPU0_SB_DQ<15>")
	)
	(arc
		(start 386.114798 -283.515308)
		(mid 386.370006 -283.558785)
		(end 386.617718 -283.483558)
		(width 0.0889)
		(layer "In11.Cu")
		(net "M_L_CPU0_SB_DQ<15>")
	)
	(arc
		(start 391.326116 -283.478732)
		(mid 391.509624 -283.433238)
		(end 391.691876 -283.483558)
		(width 0.0889)
		(layer "In11.Cu")
		(net "M_L_CPU0_SB_DQ<15>")
	)
	(arc
		(start 388.506208 -283.478732)
		(mid 388.689716 -283.433238)
		(end 388.871968 -283.483558)
		(width 0.0889)
		(layer "In11.Cu")
		(net "M_L_CPU0_SB_DQ<15>")
	)
	(arc
		(start 392.634216 -283.483558)
		(mid 392.903985 -283.559581)
		(end 393.177014 -283.496258)
		(width 0.0889)
		(layer "In11.Cu")
		(net "M_L_CPU0_SB_DQ<15>")
	)
	(arc
		(start 386.99186 -283.483558)
		(mid 387.274816 -283.559735)
		(end 387.557772 -283.483558)
		(width 0.0889)
		(layer "In11.Cu")
		(net "M_L_CPU0_SB_DQ<15>")
	)
	(arc
		(start 393.198604 -283.483812)
		(mid 393.288381 -283.446389)
		(end 393.384786 -283.43352)
		(width 0.0889)
		(layer "In11.Cu")
		(net "M_L_CPU0_SB_DQ<15>")
	)
	(segment
		(start 386.807964 -282.730194)
		(end 387.274816 -282.996132)
		(width 0.10668)
		(layer "F.Cu")
		(net "M_L_CPU0_SB_DQ<14>")
	)
	(segment
		(start 410.91485 -298.06011)
		(end 414.063942 -298.06011)
		(width 0.14478)
		(layer "In11.Cu")
		(net "M_L_CPU0_SB_DQ<14>")
	)
	(segment
		(start 405.852376 -294.235632)
		(end 406.083008 -294.235632)
		(width 0.14478)
		(layer "In11.Cu")
		(net "M_L_CPU0_SB_DQ<14>")
	)
	(segment
		(start 407.258774 -294.634666)
		(end 407.489406 -294.634666)
		(width 0.14478)
		(layer "In11.Cu")
		(net "M_L_CPU0_SB_DQ<14>")
	)
	(segment
		(start 408.276806 -295.422066)
		(end 408.439874 -295.585134)
		(width 0.14478)
		(layer "In11.Cu")
		(net "M_L_CPU0_SB_DQ<14>")
	)
	(segment
		(start 395.735302 -283.14777)
		(end 397.474694 -283.14777)
		(width 0.14478)
		(layer "In11.Cu")
		(net "M_L_CPU0_SB_DQ<14>")
	)
	(segment
		(start 407.427176 -295.810432)
		(end 407.657808 -295.810432)
		(width 0.14478)
		(layer "In11.Cu")
		(net "M_L_CPU0_SB_DQ<14>")
	)
	(segment
		(start 405.689308 -294.072564)
		(end 405.852376 -294.235632)
		(width 0.14478)
		(layer "In11.Cu")
		(net "M_L_CPU0_SB_DQ<14>")
	)
	(segment
		(start 387.274816 -282.996132)
		(end 387.42874 -282.730702)
		(width 0.0889)
		(layer "In11.Cu")
		(net "M_L_CPU0_SB_DQ<14>")
	)
	(segment
		(start 418.972238 -298.060364)
		(end 421.633904 -298.060364)
		(width 0.14478)
		(layer "In11.Cu")
		(net "M_L_CPU0_SB_DQ<14>")
	)
	(segment
		(start 394.403072 -282.750006)
		(end 394.800836 -283.14777)
		(width 0.0889)
		(layer "In11.Cu")
		(net "M_L_CPU0_SB_DQ<14>")
	)
	(segment
		(start 406.476708 -294.629332)
		(end 406.476708 -294.859964)
		(width 0.14478)
		(layer "In11.Cu")
		(net "M_L_CPU0_SB_DQ<14>")
	)
	(segment
		(start 389.90778 -282.673552)
		(end 389.916162 -282.668726)
		(width 0.0889)
		(layer "In11.Cu")
		(net "M_L_CPU0_SB_DQ<14>")
	)
	(segment
		(start 406.476708 -294.859964)
		(end 406.639776 -295.023032)
		(width 0.14478)
		(layer "In11.Cu")
		(net "M_L_CPU0_SB_DQ<14>")
	)
	(segment
		(start 408.439874 -295.815766)
		(end 408.051508 -296.204132)
		(width 0.14478)
		(layer "In11.Cu")
		(net "M_L_CPU0_SB_DQ<14>")
	)
	(segment
		(start 407.264108 -295.647364)
		(end 407.427176 -295.810432)
		(width 0.14478)
		(layer "In11.Cu")
		(net "M_L_CPU0_SB_DQ<14>")
	)
	(segment
		(start 449.663058 -297.210226)
		(end 450.088 -297.635168)
		(width 0.14478)
		(layer "In11.Cu")
		(net "M_L_CPU0_SB_DQ<14>")
	)
	(segment
		(start 408.046174 -295.422066)
		(end 408.276806 -295.422066)
		(width 0.14478)
		(layer "In11.Cu")
		(net "M_L_CPU0_SB_DQ<14>")
	)
	(segment
		(start 433.794408 -298.060364)
		(end 436.722012 -298.060364)
		(width 0.14478)
		(layer "In11.Cu")
		(net "M_L_CPU0_SB_DQ<14>")
	)
	(segment
		(start 421.633904 -298.060364)
		(end 422.484042 -297.210226)
		(width 0.14478)
		(layer "In11.Cu")
		(net "M_L_CPU0_SB_DQ<14>")
	)
	(segment
		(start 407.652474 -295.028366)
		(end 407.264108 -295.416732)
		(width 0.14478)
		(layer "In11.Cu")
		(net "M_L_CPU0_SB_DQ<14>")
	)
	(segment
		(start 414.063942 -298.06011)
		(end 414.91408 -297.209972)
		(width 0.14478)
		(layer "In11.Cu")
		(net "M_L_CPU0_SB_DQ<14>")
	)
	(segment
		(start 408.445208 -296.597832)
		(end 408.833574 -296.209466)
		(width 0.14478)
		(layer "In11.Cu")
		(net "M_L_CPU0_SB_DQ<14>")
	)
	(segment
		(start 429.177958 -298.060364)
		(end 430.028096 -297.210226)
		(width 0.14478)
		(layer "In11.Cu")
		(net "M_L_CPU0_SB_DQ<14>")
	)
	(segment
		(start 406.870408 -295.023032)
		(end 407.258774 -294.634666)
		(width 0.14478)
		(layer "In11.Cu")
		(net "M_L_CPU0_SB_DQ<14>")
	)
	(segment
		(start 389.333486 -282.668726)
		(end 389.341868 -282.673552)
		(width 0.0889)
		(layer "In11.Cu")
		(net "M_L_CPU0_SB_DQ<14>")
	)
	(segment
		(start 392.726672 -282.673552)
		(end 392.738356 -282.666694)
		(width 0.0889)
		(layer "In11.Cu")
		(net "M_L_CPU0_SB_DQ<14>")
	)
	(segment
		(start 432.94427 -297.210226)
		(end 433.794408 -298.060364)
		(width 0.14478)
		(layer "In11.Cu")
		(net "M_L_CPU0_SB_DQ<14>")
	)
	(segment
		(start 436.722012 -298.060364)
		(end 437.57215 -297.210226)
		(width 0.14478)
		(layer "In11.Cu")
		(net "M_L_CPU0_SB_DQ<14>")
	)
	(segment
		(start 406.077674 -293.222934)
		(end 406.077674 -293.453566)
		(width 0.14478)
		(layer "In11.Cu")
		(net "M_L_CPU0_SB_DQ<14>")
	)
	(segment
		(start 406.865074 -294.010334)
		(end 406.865074 -294.240966)
		(width 0.14478)
		(layer "In11.Cu")
		(net "M_L_CPU0_SB_DQ<14>")
	)
	(segment
		(start 388.393432 -282.668726)
		(end 388.401814 -282.673552)
		(width 0.0889)
		(layer "In11.Cu")
		(net "M_L_CPU0_SB_DQ<14>")
	)
	(segment
		(start 445.230504 -297.210226)
		(end 449.663058 -297.210226)
		(width 0.14478)
		(layer "In11.Cu")
		(net "M_L_CPU0_SB_DQ<14>")
	)
	(segment
		(start 425.466256 -297.210226)
		(end 426.316394 -298.060364)
		(width 0.14478)
		(layer "In11.Cu")
		(net "M_L_CPU0_SB_DQ<14>")
	)
	(segment
		(start 394.800836 -283.14777)
		(end 395.735302 -283.14777)
		(width 0.0889)
		(layer "In11.Cu")
		(net "M_L_CPU0_SB_DQ<14>")
	)
	(segment
		(start 407.264108 -295.416732)
		(end 407.264108 -295.647364)
		(width 0.14478)
		(layer "In11.Cu")
		(net "M_L_CPU0_SB_DQ<14>")
	)
	(segment
		(start 426.316394 -298.060364)
		(end 429.177958 -298.060364)
		(width 0.14478)
		(layer "In11.Cu")
		(net "M_L_CPU0_SB_DQ<14>")
	)
	(segment
		(start 444.38062 -298.06011)
		(end 445.230504 -297.210226)
		(width 0.14478)
		(layer "In11.Cu")
		(net "M_L_CPU0_SB_DQ<14>")
	)
	(segment
		(start 406.702006 -293.847266)
		(end 406.865074 -294.010334)
		(width 0.14478)
		(layer "In11.Cu")
		(net "M_L_CPU0_SB_DQ<14>")
	)
	(segment
		(start 406.639776 -295.023032)
		(end 406.870408 -295.023032)
		(width 0.14478)
		(layer "In11.Cu")
		(net "M_L_CPU0_SB_DQ<14>")
	)
	(segment
		(start 392.161522 -282.673806)
		(end 392.17346 -282.680664)
		(width 0.0889)
		(layer "In11.Cu")
		(net "M_L_CPU0_SB_DQ<14>")
	)
	(segment
		(start 441.33008 -298.06011)
		(end 444.38062 -298.06011)
		(width 0.14478)
		(layer "In11.Cu")
		(net "M_L_CPU0_SB_DQ<14>")
	)
	(segment
		(start 408.051508 -296.434764)
		(end 408.214576 -296.597832)
		(width 0.14478)
		(layer "In11.Cu")
		(net "M_L_CPU0_SB_DQ<14>")
	)
	(segment
		(start 405.415496 -291.088572)
		(end 405.415496 -292.560756)
		(width 0.14478)
		(layer "In11.Cu")
		(net "M_L_CPU0_SB_DQ<14>")
	)
	(segment
		(start 440.480196 -297.210226)
		(end 441.33008 -298.06011)
		(width 0.14478)
		(layer "In11.Cu")
		(net "M_L_CPU0_SB_DQ<14>")
	)
	(segment
		(start 422.484042 -297.210226)
		(end 425.466256 -297.210226)
		(width 0.14478)
		(layer "In11.Cu")
		(net "M_L_CPU0_SB_DQ<14>")
	)
	(segment
		(start 392.145266 -282.664408)
		(end 392.161522 -282.673806)
		(width 0.0889)
		(layer "In11.Cu")
		(net "M_L_CPU0_SB_DQ<14>")
	)
	(segment
		(start 393.384786 -282.750006)
		(end 394.403072 -282.750006)
		(width 0.0889)
		(layer "In11.Cu")
		(net "M_L_CPU0_SB_DQ<14>")
	)
	(segment
		(start 406.077674 -293.453566)
		(end 405.689308 -293.841932)
		(width 0.14478)
		(layer "In11.Cu")
		(net "M_L_CPU0_SB_DQ<14>")
	)
	(segment
		(start 409.064206 -296.209466)
		(end 410.91485 -298.06011)
		(width 0.14478)
		(layer "In11.Cu")
		(net "M_L_CPU0_SB_DQ<14>")
	)
	(segment
		(start 397.474694 -283.14777)
		(end 405.415496 -291.088572)
		(width 0.14478)
		(layer "In11.Cu")
		(net "M_L_CPU0_SB_DQ<14>")
	)
	(segment
		(start 408.214576 -296.597832)
		(end 408.445208 -296.597832)
		(width 0.14478)
		(layer "In11.Cu")
		(net "M_L_CPU0_SB_DQ<14>")
	)
	(segment
		(start 406.083008 -294.235632)
		(end 406.471374 -293.847266)
		(width 0.14478)
		(layer "In11.Cu")
		(net "M_L_CPU0_SB_DQ<14>")
	)
	(segment
		(start 418.121846 -297.209972)
		(end 418.972238 -298.060364)
		(width 0.14478)
		(layer "In11.Cu")
		(net "M_L_CPU0_SB_DQ<14>")
	)
	(segment
		(start 414.91408 -297.209972)
		(end 418.121846 -297.209972)
		(width 0.14478)
		(layer "In11.Cu")
		(net "M_L_CPU0_SB_DQ<14>")
	)
	(segment
		(start 408.439874 -295.585134)
		(end 408.439874 -295.815766)
		(width 0.14478)
		(layer "In11.Cu")
		(net "M_L_CPU0_SB_DQ<14>")
	)
	(segment
		(start 407.652474 -294.797734)
		(end 407.652474 -295.028366)
		(width 0.14478)
		(layer "In11.Cu")
		(net "M_L_CPU0_SB_DQ<14>")
	)
	(segment
		(start 387.42874 -282.730702)
		(end 387.524752 -282.705302)
		(width 0.0889)
		(layer "In11.Cu")
		(net "M_L_CPU0_SB_DQ<14>")
	)
	(segment
		(start 407.489406 -294.634666)
		(end 407.652474 -294.797734)
		(width 0.14478)
		(layer "In11.Cu")
		(net "M_L_CPU0_SB_DQ<14>")
	)
	(segment
		(start 407.657808 -295.810432)
		(end 408.046174 -295.422066)
		(width 0.14478)
		(layer "In11.Cu")
		(net "M_L_CPU0_SB_DQ<14>")
	)
	(segment
		(start 430.028096 -297.210226)
		(end 432.94427 -297.210226)
		(width 0.14478)
		(layer "In11.Cu")
		(net "M_L_CPU0_SB_DQ<14>")
	)
	(segment
		(start 405.689308 -293.841932)
		(end 405.689308 -294.072564)
		(width 0.14478)
		(layer "In11.Cu")
		(net "M_L_CPU0_SB_DQ<14>")
	)
	(segment
		(start 406.865074 -294.240966)
		(end 406.476708 -294.629332)
		(width 0.14478)
		(layer "In11.Cu")
		(net "M_L_CPU0_SB_DQ<14>")
	)
	(segment
		(start 437.57215 -297.210226)
		(end 440.480196 -297.210226)
		(width 0.14478)
		(layer "In11.Cu")
		(net "M_L_CPU0_SB_DQ<14>")
	)
	(segment
		(start 408.833574 -296.209466)
		(end 409.064206 -296.209466)
		(width 0.14478)
		(layer "In11.Cu")
		(net "M_L_CPU0_SB_DQ<14>")
	)
	(segment
		(start 405.415496 -292.560756)
		(end 406.077674 -293.222934)
		(width 0.14478)
		(layer "In11.Cu")
		(net "M_L_CPU0_SB_DQ<14>")
	)
	(segment
		(start 408.051508 -296.204132)
		(end 408.051508 -296.434764)
		(width 0.14478)
		(layer "In11.Cu")
		(net "M_L_CPU0_SB_DQ<14>")
	)
	(segment
		(start 406.471374 -293.847266)
		(end 406.702006 -293.847266)
		(width 0.14478)
		(layer "In11.Cu")
		(net "M_L_CPU0_SB_DQ<14>")
	)
	(arc
		(start 387.524752 -282.705302)
		(mid 387.77996 -282.748779)
		(end 388.027672 -282.673552)
		(width 0.0889)
		(layer "In11.Cu")
		(net "M_L_CPU0_SB_DQ<14>")
	)
	(arc
		(start 392.17346 -282.680664)
		(mid 392.450994 -282.749645)
		(end 392.726672 -282.673552)
		(width 0.0889)
		(layer "In11.Cu")
		(net "M_L_CPU0_SB_DQ<14>")
	)
	(arc
		(start 388.967726 -282.673552)
		(mid 389.149977 -282.623202)
		(end 389.333486 -282.668726)
		(width 0.0889)
		(layer "In11.Cu")
		(net "M_L_CPU0_SB_DQ<14>")
	)
	(arc
		(start 393.101068 -282.673552)
		(mid 393.237861 -282.730574)
		(end 393.384786 -282.750006)
		(width 0.0889)
		(layer "In11.Cu")
		(net "M_L_CPU0_SB_DQ<14>")
	)
	(arc
		(start 389.341868 -282.673552)
		(mid 389.624824 -282.749729)
		(end 389.90778 -282.673552)
		(width 0.0889)
		(layer "In11.Cu")
		(net "M_L_CPU0_SB_DQ<14>")
	)
	(arc
		(start 389.916162 -282.668726)
		(mid 390.09967 -282.623232)
		(end 390.281922 -282.673552)
		(width 0.0889)
		(layer "In11.Cu")
		(net "M_L_CPU0_SB_DQ<14>")
	)
	(arc
		(start 390.281922 -282.673552)
		(mid 390.564878 -282.749729)
		(end 390.847834 -282.673552)
		(width 0.0889)
		(layer "In11.Cu")
		(net "M_L_CPU0_SB_DQ<14>")
	)
	(arc
		(start 388.027672 -282.673552)
		(mid 388.209923 -282.623202)
		(end 388.393432 -282.668726)
		(width 0.0889)
		(layer "In11.Cu")
		(net "M_L_CPU0_SB_DQ<14>")
	)
	(arc
		(start 388.401814 -282.673552)
		(mid 388.68477 -282.749729)
		(end 388.967726 -282.673552)
		(width 0.0889)
		(layer "In11.Cu")
		(net "M_L_CPU0_SB_DQ<14>")
	)
	(arc
		(start 392.738356 -282.666694)
		(mid 392.920611 -282.623041)
		(end 393.101068 -282.673552)
		(width 0.0889)
		(layer "In11.Cu")
		(net "M_L_CPU0_SB_DQ<14>")
	)
	(arc
		(start 390.847834 -282.673552)
		(mid 391.034778 -282.623297)
		(end 391.221722 -282.673552)
		(width 0.0889)
		(layer "In11.Cu")
		(net "M_L_CPU0_SB_DQ<14>")
	)
	(arc
		(start 391.221722 -282.673552)
		(mid 391.504678 -282.749729)
		(end 391.787634 -282.673552)
		(width 0.0889)
		(layer "In11.Cu")
		(net "M_L_CPU0_SB_DQ<14>")
	)
	(arc
		(start 391.787634 -282.673552)
		(mid 391.965284 -282.623292)
		(end 392.145266 -282.664408)
		(width 0.0889)
		(layer "In11.Cu")
		(net "M_L_CPU0_SB_DQ<14>")
	)
	(segment
		(start 385.86791 -282.730194)
		(end 386.334762 -282.996132)
		(width 0.10668)
		(layer "F.Cu")
		(net "M_L_CPU0_SB_DQ<13>")
	)
	(segment
		(start 395.838172 -283.60243)
		(end 397.286226 -283.60243)
		(width 0.14478)
		(layer "In11.Cu")
		(net "M_L_CPU0_SB_DQ<13>")
	)
	(segment
		(start 389.333486 -283.323538)
		(end 389.341868 -283.318712)
		(width 0.0889)
		(layer "In11.Cu")
		(net "M_L_CPU0_SB_DQ<13>")
	)
	(segment
		(start 392.706606 -283.304996)
		(end 392.729974 -283.318712)
		(width 0.0889)
		(layer "In11.Cu")
		(net "M_L_CPU0_SB_DQ<13>")
	)
	(segment
		(start 393.384532 -283.24302)
		(end 394.499846 -283.24302)
		(width 0.0889)
		(layer "In11.Cu")
		(net "M_L_CPU0_SB_DQ<13>")
	)
	(segment
		(start 418.907214 -298.910248)
		(end 421.726868 -298.910248)
		(width 0.14478)
		(layer "In11.Cu")
		(net "M_L_CPU0_SB_DQ<13>")
	)
	(segment
		(start 438.189116 -298.060364)
		(end 440.137296 -298.060364)
		(width 0.14478)
		(layer "In11.Cu")
		(net "M_L_CPU0_SB_DQ<13>")
	)
	(segment
		(start 428.688754 -298.910248)
		(end 430.740566 -298.060364)
		(width 0.14478)
		(layer "In11.Cu")
		(net "M_L_CPU0_SB_DQ<13>")
	)
	(segment
		(start 386.180838 -283.261562)
		(end 386.20319 -283.344874)
		(width 0.0889)
		(layer "In11.Cu")
		(net "M_L_CPU0_SB_DQ<13>")
	)
	(segment
		(start 432.447954 -298.060364)
		(end 434.499766 -298.910248)
		(width 0.14478)
		(layer "In11.Cu")
		(net "M_L_CPU0_SB_DQ<13>")
	)
	(segment
		(start 410.913834 -298.909994)
		(end 413.751776 -298.909994)
		(width 0.14478)
		(layer "In11.Cu")
		(net "M_L_CPU0_SB_DQ<13>")
	)
	(segment
		(start 386.334762 -282.996132)
		(end 386.180838 -283.261562)
		(width 0.0889)
		(layer "In11.Cu")
		(net "M_L_CPU0_SB_DQ<13>")
	)
	(segment
		(start 430.740566 -298.060364)
		(end 432.447954 -298.060364)
		(width 0.14478)
		(layer "In11.Cu")
		(net "M_L_CPU0_SB_DQ<13>")
	)
	(segment
		(start 404.960836 -291.27704)
		(end 404.960836 -293.987474)
		(width 0.14478)
		(layer "In11.Cu")
		(net "M_L_CPU0_SB_DQ<13>")
	)
	(segment
		(start 415.804858 -298.059856)
		(end 418.056822 -298.059856)
		(width 0.14478)
		(layer "In11.Cu")
		(net "M_L_CPU0_SB_DQ<13>")
	)
	(segment
		(start 445.825372 -298.06011)
		(end 452.051674 -298.06011)
		(width 0.14478)
		(layer "In11.Cu")
		(net "M_L_CPU0_SB_DQ<13>")
	)
	(segment
		(start 418.056822 -298.059856)
		(end 418.907214 -298.910248)
		(width 0.14478)
		(layer "In11.Cu")
		(net "M_L_CPU0_SB_DQ<13>")
	)
	(segment
		(start 408.198066 -297.224704)
		(end 409.228544 -297.224704)
		(width 0.14478)
		(layer "In11.Cu")
		(net "M_L_CPU0_SB_DQ<13>")
	)
	(segment
		(start 413.751776 -298.909994)
		(end 415.804858 -298.059856)
		(width 0.14478)
		(layer "In11.Cu")
		(net "M_L_CPU0_SB_DQ<13>")
	)
	(segment
		(start 389.90778 -283.318712)
		(end 389.916162 -283.323538)
		(width 0.0889)
		(layer "In11.Cu")
		(net "M_L_CPU0_SB_DQ<13>")
	)
	(segment
		(start 436.137304 -298.910248)
		(end 438.189116 -298.060364)
		(width 0.14478)
		(layer "In11.Cu")
		(net "M_L_CPU0_SB_DQ<13>")
	)
	(segment
		(start 397.286226 -283.60243)
		(end 404.960836 -291.27704)
		(width 0.14478)
		(layer "In11.Cu")
		(net "M_L_CPU0_SB_DQ<13>")
	)
	(segment
		(start 395.332458 -283.412692)
		(end 395.522196 -283.60243)
		(width 0.0889)
		(layer "In11.Cu")
		(net "M_L_CPU0_SB_DQ<13>")
	)
	(segment
		(start 425.601384 -298.060364)
		(end 426.451268 -298.910248)
		(width 0.14478)
		(layer "In11.Cu")
		(net "M_L_CPU0_SB_DQ<13>")
	)
	(segment
		(start 421.726868 -298.910248)
		(end 422.576752 -298.060364)
		(width 0.14478)
		(layer "In11.Cu")
		(net "M_L_CPU0_SB_DQ<13>")
	)
	(segment
		(start 442.1886 -298.909994)
		(end 443.77356 -298.909994)
		(width 0.14478)
		(layer "In11.Cu")
		(net "M_L_CPU0_SB_DQ<13>")
	)
	(segment
		(start 409.228544 -297.224704)
		(end 410.913834 -298.909994)
		(width 0.14478)
		(layer "In11.Cu")
		(net "M_L_CPU0_SB_DQ<13>")
	)
	(segment
		(start 388.393432 -283.323538)
		(end 388.401814 -283.318712)
		(width 0.0889)
		(layer "In11.Cu")
		(net "M_L_CPU0_SB_DQ<13>")
	)
	(segment
		(start 452.051674 -298.06011)
		(end 454.188068 -298.485052)
		(width 0.14478)
		(layer "In11.Cu")
		(net "M_L_CPU0_SB_DQ<13>")
	)
	(segment
		(start 395.522196 -283.60243)
		(end 395.838172 -283.60243)
		(width 0.0889)
		(layer "In11.Cu")
		(net "M_L_CPU0_SB_DQ<13>")
	)
	(segment
		(start 404.960836 -293.987474)
		(end 408.198066 -297.224704)
		(width 0.14478)
		(layer "In11.Cu")
		(net "M_L_CPU0_SB_DQ<13>")
	)
	(segment
		(start 393.083288 -283.329888)
		(end 393.103354 -283.318458)
		(width 0.0889)
		(layer "In11.Cu")
		(net "M_L_CPU0_SB_DQ<13>")
	)
	(segment
		(start 391.787634 -283.318712)
		(end 391.802112 -283.327094)
		(width 0.0889)
		(layer "In11.Cu")
		(net "M_L_CPU0_SB_DQ<13>")
	)
	(segment
		(start 443.77356 -298.909994)
		(end 445.825372 -298.06011)
		(width 0.14478)
		(layer "In11.Cu")
		(net "M_L_CPU0_SB_DQ<13>")
	)
	(segment
		(start 440.137296 -298.060364)
		(end 442.1886 -298.909994)
		(width 0.14478)
		(layer "In11.Cu")
		(net "M_L_CPU0_SB_DQ<13>")
	)
	(segment
		(start 394.669518 -283.412692)
		(end 395.332458 -283.412692)
		(width 0.0889)
		(layer "In11.Cu")
		(net "M_L_CPU0_SB_DQ<13>")
	)
	(segment
		(start 394.499846 -283.24302)
		(end 394.669518 -283.412692)
		(width 0.0889)
		(layer "In11.Cu")
		(net "M_L_CPU0_SB_DQ<13>")
	)
	(segment
		(start 422.576752 -298.060364)
		(end 425.601384 -298.060364)
		(width 0.14478)
		(layer "In11.Cu")
		(net "M_L_CPU0_SB_DQ<13>")
	)
	(segment
		(start 434.499766 -298.910248)
		(end 436.137304 -298.910248)
		(width 0.14478)
		(layer "In11.Cu")
		(net "M_L_CPU0_SB_DQ<13>")
	)
	(segment
		(start 426.451268 -298.910248)
		(end 428.688754 -298.910248)
		(width 0.14478)
		(layer "In11.Cu")
		(net "M_L_CPU0_SB_DQ<13>")
	)
	(arc
		(start 390.281922 -283.318712)
		(mid 390.564878 -283.242535)
		(end 390.847834 -283.318712)
		(width 0.0889)
		(layer "In11.Cu")
		(net "M_L_CPU0_SB_DQ<13>")
	)
	(arc
		(start 390.847834 -283.318712)
		(mid 391.034778 -283.368967)
		(end 391.221722 -283.318712)
		(width 0.0889)
		(layer "In11.Cu")
		(net "M_L_CPU0_SB_DQ<13>")
	)
	(arc
		(start 392.729974 -283.318712)
		(mid 392.905213 -283.368783)
		(end 393.083288 -283.329888)
		(width 0.0889)
		(layer "In11.Cu")
		(net "M_L_CPU0_SB_DQ<13>")
	)
	(arc
		(start 386.20319 -283.344874)
		(mid 386.365522 -283.367692)
		(end 386.52196 -283.318712)
		(width 0.0889)
		(layer "In11.Cu")
		(net "M_L_CPU0_SB_DQ<13>")
	)
	(arc
		(start 389.916162 -283.323538)
		(mid 390.09967 -283.369032)
		(end 390.281922 -283.318712)
		(width 0.0889)
		(layer "In11.Cu")
		(net "M_L_CPU0_SB_DQ<13>")
	)
	(arc
		(start 389.341868 -283.318712)
		(mid 389.624824 -283.242535)
		(end 389.90778 -283.318712)
		(width 0.0889)
		(layer "In11.Cu")
		(net "M_L_CPU0_SB_DQ<13>")
	)
	(arc
		(start 388.401814 -283.318712)
		(mid 388.68477 -283.242535)
		(end 388.967726 -283.318712)
		(width 0.0889)
		(layer "In11.Cu")
		(net "M_L_CPU0_SB_DQ<13>")
	)
	(arc
		(start 393.103354 -283.318458)
		(mid 393.238987 -283.262283)
		(end 393.384532 -283.24302)
		(width 0.0889)
		(layer "In11.Cu")
		(net "M_L_CPU0_SB_DQ<13>")
	)
	(arc
		(start 388.967726 -283.318712)
		(mid 389.149977 -283.369062)
		(end 389.333486 -283.323538)
		(width 0.0889)
		(layer "In11.Cu")
		(net "M_L_CPU0_SB_DQ<13>")
	)
	(arc
		(start 391.221722 -283.318712)
		(mid 391.504678 -283.242535)
		(end 391.787634 -283.318712)
		(width 0.0889)
		(layer "In11.Cu")
		(net "M_L_CPU0_SB_DQ<13>")
	)
	(arc
		(start 391.802112 -283.327094)
		(mid 391.983528 -283.369351)
		(end 392.162792 -283.318712)
		(width 0.0889)
		(layer "In11.Cu")
		(net "M_L_CPU0_SB_DQ<13>")
	)
	(arc
		(start 386.52196 -283.318712)
		(mid 386.804916 -283.242535)
		(end 387.087872 -283.318712)
		(width 0.0889)
		(layer "In11.Cu")
		(net "M_L_CPU0_SB_DQ<13>")
	)
	(arc
		(start 388.027672 -283.318712)
		(mid 388.209923 -283.369062)
		(end 388.393432 -283.323538)
		(width 0.0889)
		(layer "In11.Cu")
		(net "M_L_CPU0_SB_DQ<13>")
	)
	(arc
		(start 387.46176 -283.318712)
		(mid 387.744716 -283.242535)
		(end 388.027672 -283.318712)
		(width 0.0889)
		(layer "In11.Cu")
		(net "M_L_CPU0_SB_DQ<13>")
	)
	(arc
		(start 387.087872 -283.318712)
		(mid 387.274816 -283.368967)
		(end 387.46176 -283.318712)
		(width 0.0889)
		(layer "In11.Cu")
		(net "M_L_CPU0_SB_DQ<13>")
	)
	(arc
		(start 392.162792 -283.318712)
		(mid 392.432949 -283.24195)
		(end 392.706606 -283.304996)
		(width 0.0889)
		(layer "In11.Cu")
		(net "M_L_CPU0_SB_DQ<13>")
	)
	(segment
		(start 387.277864 -281.920188)
		(end 387.744716 -282.186126)
		(width 0.10668)
		(layer "F.Cu")
		(net "M_L_CPU0_SB_DQ<12>")
	)
	(segment
		(start 452.494142 -297.033442)
		(end 452.65721 -297.19651)
		(width 0.14478)
		(layer "In11.Cu")
		(net "M_L_CPU0_SB_DQ<12>")
	)
	(segment
		(start 414.701228 -296.691812)
		(end 418.3888 -296.691812)
		(width 0.14478)
		(layer "In11.Cu")
		(net "M_L_CPU0_SB_DQ<12>")
	)
	(segment
		(start 387.590792 -282.451556)
		(end 387.613144 -282.534868)
		(width 0.0889)
		(layer "In11.Cu")
		(net "M_L_CPU0_SB_DQ<12>")
	)
	(segment
		(start 437.655462 -296.36974)
		(end 440.46267 -296.36974)
		(width 0.14478)
		(layer "In11.Cu")
		(net "M_L_CPU0_SB_DQ<12>")
	)
	(segment
		(start 429.261524 -297.219624)
		(end 430.111408 -296.36974)
		(width 0.14478)
		(layer "In11.Cu")
		(net "M_L_CPU0_SB_DQ<12>")
	)
	(segment
		(start 392.257026 -282.508452)
		(end 392.270742 -282.516326)
		(width 0.0889)
		(layer "In11.Cu")
		(net "M_L_CPU0_SB_DQ<12>")
	)
	(segment
		(start 390.74344 -282.513532)
		(end 390.751822 -282.508706)
		(width 0.0889)
		(layer "In11.Cu")
		(net "M_L_CPU0_SB_DQ<12>")
	)
	(segment
		(start 410.708094 -297.210226)
		(end 414.182814 -297.210226)
		(width 0.14478)
		(layer "In11.Cu")
		(net "M_L_CPU0_SB_DQ<12>")
	)
	(segment
		(start 452.65721 -297.19651)
		(end 452.887588 -297.19651)
		(width 0.14478)
		(layer "In11.Cu")
		(net "M_L_CPU0_SB_DQ<12>")
	)
	(segment
		(start 392.245088 -282.501594)
		(end 392.257026 -282.508452)
		(width 0.0889)
		(layer "In11.Cu")
		(net "M_L_CPU0_SB_DQ<12>")
	)
	(segment
		(start 393.734544 -282.559506)
		(end 393.940538 -282.353512)
		(width 0.0889)
		(layer "In11.Cu")
		(net "M_L_CPU0_SB_DQ<12>")
	)
	(segment
		(start 393.940538 -282.353512)
		(end 395.192758 -282.353512)
		(width 0.0889)
		(layer "In11.Cu")
		(net "M_L_CPU0_SB_DQ<12>")
	)
	(segment
		(start 453.213724 -296.360088)
		(end 453.763126 -296.360088)
		(width 0.14478)
		(layer "In11.Cu")
		(net "M_L_CPU0_SB_DQ<12>")
	)
	(segment
		(start 432.903884 -296.36974)
		(end 433.753768 -297.219624)
		(width 0.14478)
		(layer "In11.Cu")
		(net "M_L_CPU0_SB_DQ<12>")
	)
	(segment
		(start 418.3888 -296.691812)
		(end 418.916612 -297.219624)
		(width 0.14478)
		(layer "In11.Cu")
		(net "M_L_CPU0_SB_DQ<12>")
	)
	(segment
		(start 440.46267 -296.36974)
		(end 441.312554 -297.219624)
		(width 0.14478)
		(layer "In11.Cu")
		(net "M_L_CPU0_SB_DQ<12>")
	)
	(segment
		(start 395.792452 -282.69311)
		(end 397.663162 -282.69311)
		(width 0.14478)
		(layer "In11.Cu")
		(net "M_L_CPU0_SB_DQ<12>")
	)
	(segment
		(start 444.342266 -297.219624)
		(end 445.192404 -296.369486)
		(width 0.14478)
		(layer "In11.Cu")
		(net "M_L_CPU0_SB_DQ<12>")
	)
	(segment
		(start 422.567354 -296.36974)
		(end 425.41063 -296.36974)
		(width 0.14478)
		(layer "In11.Cu")
		(net "M_L_CPU0_SB_DQ<12>")
	)
	(segment
		(start 388.497826 -282.508706)
		(end 388.506208 -282.513532)
		(width 0.0889)
		(layer "In11.Cu")
		(net "M_L_CPU0_SB_DQ<12>")
	)
	(segment
		(start 418.916612 -297.219624)
		(end 421.71747 -297.219624)
		(width 0.14478)
		(layer "In11.Cu")
		(net "M_L_CPU0_SB_DQ<12>")
	)
	(segment
		(start 426.260514 -297.219624)
		(end 429.261524 -297.219624)
		(width 0.14478)
		(layer "In11.Cu")
		(net "M_L_CPU0_SB_DQ<12>")
	)
	(segment
		(start 391.317734 -282.508706)
		(end 391.326116 -282.513532)
		(width 0.0889)
		(layer "In11.Cu")
		(net "M_L_CPU0_SB_DQ<12>")
	)
	(segment
		(start 453.050656 -296.523156)
		(end 453.213724 -296.360088)
		(width 0.14478)
		(layer "In11.Cu")
		(net "M_L_CPU0_SB_DQ<12>")
	)
	(segment
		(start 392.63066 -282.508706)
		(end 392.648694 -282.498038)
		(width 0.0889)
		(layer "In11.Cu")
		(net "M_L_CPU0_SB_DQ<12>")
	)
	(segment
		(start 425.41063 -296.36974)
		(end 426.260514 -297.219624)
		(width 0.14478)
		(layer "In11.Cu")
		(net "M_L_CPU0_SB_DQ<12>")
	)
	(segment
		(start 452.887588 -297.19651)
		(end 453.050656 -297.033442)
		(width 0.14478)
		(layer "In11.Cu")
		(net "M_L_CPU0_SB_DQ<12>")
	)
	(segment
		(start 452.494142 -296.523156)
		(end 452.494142 -297.033442)
		(width 0.14478)
		(layer "In11.Cu")
		(net "M_L_CPU0_SB_DQ<12>")
	)
	(segment
		(start 387.744716 -282.186126)
		(end 387.590792 -282.451556)
		(width 0.0889)
		(layer "In11.Cu")
		(net "M_L_CPU0_SB_DQ<12>")
	)
	(segment
		(start 441.312554 -297.219624)
		(end 444.342266 -297.219624)
		(width 0.14478)
		(layer "In11.Cu")
		(net "M_L_CPU0_SB_DQ<12>")
	)
	(segment
		(start 453.050656 -297.033442)
		(end 453.050656 -296.523156)
		(width 0.14478)
		(layer "In11.Cu")
		(net "M_L_CPU0_SB_DQ<12>")
	)
	(segment
		(start 393.384786 -282.559506)
		(end 393.734544 -282.559506)
		(width 0.0889)
		(layer "In11.Cu")
		(net "M_L_CPU0_SB_DQ<12>")
	)
	(segment
		(start 414.182814 -297.210226)
		(end 414.701228 -296.691812)
		(width 0.14478)
		(layer "In11.Cu")
		(net "M_L_CPU0_SB_DQ<12>")
	)
	(segment
		(start 405.870156 -292.372288)
		(end 410.708094 -297.210226)
		(width 0.14478)
		(layer "In11.Cu")
		(net "M_L_CPU0_SB_DQ<12>")
	)
	(segment
		(start 433.753768 -297.219624)
		(end 436.805578 -297.219624)
		(width 0.14478)
		(layer "In11.Cu")
		(net "M_L_CPU0_SB_DQ<12>")
	)
	(segment
		(start 452.340472 -296.369486)
		(end 452.494142 -296.523156)
		(width 0.14478)
		(layer "In11.Cu")
		(net "M_L_CPU0_SB_DQ<12>")
	)
	(segment
		(start 445.192404 -296.369486)
		(end 452.340472 -296.369486)
		(width 0.14478)
		(layer "In11.Cu")
		(net "M_L_CPU0_SB_DQ<12>")
	)
	(segment
		(start 395.532356 -282.69311)
		(end 395.792452 -282.69311)
		(width 0.0889)
		(layer "In11.Cu")
		(net "M_L_CPU0_SB_DQ<12>")
	)
	(segment
		(start 430.111408 -296.36974)
		(end 432.903884 -296.36974)
		(width 0.14478)
		(layer "In11.Cu")
		(net "M_L_CPU0_SB_DQ<12>")
	)
	(segment
		(start 421.71747 -297.219624)
		(end 422.567354 -296.36974)
		(width 0.14478)
		(layer "In11.Cu")
		(net "M_L_CPU0_SB_DQ<12>")
	)
	(segment
		(start 453.763126 -296.360088)
		(end 454.188068 -296.78503)
		(width 0.14478)
		(layer "In11.Cu")
		(net "M_L_CPU0_SB_DQ<12>")
	)
	(segment
		(start 436.805578 -297.219624)
		(end 437.655462 -296.36974)
		(width 0.14478)
		(layer "In11.Cu")
		(net "M_L_CPU0_SB_DQ<12>")
	)
	(segment
		(start 395.192758 -282.353512)
		(end 395.532356 -282.69311)
		(width 0.0889)
		(layer "In11.Cu")
		(net "M_L_CPU0_SB_DQ<12>")
	)
	(segment
		(start 405.870156 -290.900104)
		(end 405.870156 -292.372288)
		(width 0.14478)
		(layer "In11.Cu")
		(net "M_L_CPU0_SB_DQ<12>")
	)
	(segment
		(start 397.663162 -282.69311)
		(end 405.870156 -290.900104)
		(width 0.14478)
		(layer "In11.Cu")
		(net "M_L_CPU0_SB_DQ<12>")
	)
	(arc
		(start 388.871968 -282.508706)
		(mid 389.154924 -282.432529)
		(end 389.43788 -282.508706)
		(width 0.0889)
		(layer "In11.Cu")
		(net "M_L_CPU0_SB_DQ<12>")
	)
	(arc
		(start 393.197334 -282.508706)
		(mid 393.287697 -282.546516)
		(end 393.384786 -282.559506)
		(width 0.0889)
		(layer "In11.Cu")
		(net "M_L_CPU0_SB_DQ<12>")
	)
	(arc
		(start 392.648694 -282.498038)
		(mid 392.924389 -282.432195)
		(end 393.197334 -282.508706)
		(width 0.0889)
		(layer "In11.Cu")
		(net "M_L_CPU0_SB_DQ<12>")
	)
	(arc
		(start 391.691876 -282.508706)
		(mid 391.967554 -282.432576)
		(end 392.245088 -282.501594)
		(width 0.0889)
		(layer "In11.Cu")
		(net "M_L_CPU0_SB_DQ<12>")
	)
	(arc
		(start 389.43788 -282.508706)
		(mid 389.624824 -282.558961)
		(end 389.811768 -282.508706)
		(width 0.0889)
		(layer "In11.Cu")
		(net "M_L_CPU0_SB_DQ<12>")
	)
	(arc
		(start 389.811768 -282.508706)
		(mid 390.094724 -282.432529)
		(end 390.37768 -282.508706)
		(width 0.0889)
		(layer "In11.Cu")
		(net "M_L_CPU0_SB_DQ<12>")
	)
	(arc
		(start 390.751822 -282.508706)
		(mid 391.034778 -282.432529)
		(end 391.317734 -282.508706)
		(width 0.0889)
		(layer "In11.Cu")
		(net "M_L_CPU0_SB_DQ<12>")
	)
	(arc
		(start 387.613144 -282.534868)
		(mid 387.775476 -282.557686)
		(end 387.931914 -282.508706)
		(width 0.0889)
		(layer "In11.Cu")
		(net "M_L_CPU0_SB_DQ<12>")
	)
	(arc
		(start 392.270742 -282.516326)
		(mid 392.451672 -282.558804)
		(end 392.63066 -282.508706)
		(width 0.0889)
		(layer "In11.Cu")
		(net "M_L_CPU0_SB_DQ<12>")
	)
	(arc
		(start 387.931914 -282.508706)
		(mid 388.21487 -282.432529)
		(end 388.497826 -282.508706)
		(width 0.0889)
		(layer "In11.Cu")
		(net "M_L_CPU0_SB_DQ<12>")
	)
	(arc
		(start 390.37768 -282.508706)
		(mid 390.559931 -282.559056)
		(end 390.74344 -282.513532)
		(width 0.0889)
		(layer "In11.Cu")
		(net "M_L_CPU0_SB_DQ<12>")
	)
	(arc
		(start 388.506208 -282.513532)
		(mid 388.689716 -282.559026)
		(end 388.871968 -282.508706)
		(width 0.0889)
		(layer "In11.Cu")
		(net "M_L_CPU0_SB_DQ<12>")
	)
	(arc
		(start 391.326116 -282.513532)
		(mid 391.509624 -282.559026)
		(end 391.691876 -282.508706)
		(width 0.0889)
		(layer "In11.Cu")
		(net "M_L_CPU0_SB_DQ<12>")
	)
	(segment
		(start 385.39801 -280.300176)
		(end 385.864862 -280.566114)
		(width 0.10668)
		(layer "F.Cu")
		(net "M_L_CPU0_SB_DQ<11>")
	)
	(segment
		(start 432.077622 -292.950646)
		(end 432.222402 -292.805866)
		(width 0.14478)
		(layer "In11.Cu")
		(net "M_L_CPU0_SB_DQ<11>")
	)
	(segment
		(start 449.430902 -292.772592)
		(end 449.430902 -293.240206)
		(width 0.14478)
		(layer "In11.Cu")
		(net "M_L_CPU0_SB_DQ<11>")
	)
	(segment
		(start 449.430902 -293.240206)
		(end 449.575682 -293.384986)
		(width 0.14478)
		(layer "In11.Cu")
		(net "M_L_CPU0_SB_DQ<11>")
	)
	(segment
		(start 432.773836 -292.805866)
		(end 432.918616 -292.950646)
		(width 0.14478)
		(layer "In11.Cu")
		(net "M_L_CPU0_SB_DQ<11>")
	)
	(segment
		(start 448.393566 -293.384986)
		(end 448.734688 -293.384986)
		(width 0.14478)
		(layer "In11.Cu")
		(net "M_L_CPU0_SB_DQ<11>")
	)
	(segment
		(start 449.575682 -293.384986)
		(end 450.088 -293.384986)
		(width 0.14478)
		(layer "In11.Cu")
		(net "M_L_CPU0_SB_DQ<11>")
	)
	(segment
		(start 421.378126 -293.800784)
		(end 422.228264 -292.950646)
		(width 0.14478)
		(layer "In11.Cu")
		(net "M_L_CPU0_SB_DQ<11>")
	)
	(segment
		(start 416.092894 -292.64991)
		(end 416.39363 -292.950646)
		(width 0.14478)
		(layer "In11.Cu")
		(net "M_L_CPU0_SB_DQ<11>")
	)
	(segment
		(start 425.114212 -292.569392)
		(end 425.376086 -292.569392)
		(width 0.14478)
		(layer "In11.Cu")
		(net "M_L_CPU0_SB_DQ<11>")
	)
	(segment
		(start 430.788826 -292.569392)
		(end 430.933606 -292.714172)
		(width 0.14478)
		(layer "In11.Cu")
		(net "M_L_CPU0_SB_DQ<11>")
	)
	(segment
		(start 386.983478 -280.238708)
		(end 386.99186 -280.243534)
		(width 0.0889)
		(layer "In11.Cu")
		(net "M_L_CPU0_SB_DQ<11>")
	)
	(segment
		(start 424.824652 -292.950646)
		(end 424.969432 -292.805866)
		(width 0.14478)
		(layer "In11.Cu")
		(net "M_L_CPU0_SB_DQ<11>")
	)
	(segment
		(start 443.842648 -293.80053)
		(end 444.692532 -292.950646)
		(width 0.14478)
		(layer "In11.Cu")
		(net "M_L_CPU0_SB_DQ<11>")
	)
	(segment
		(start 414.87471 -292.950646)
		(end 415.545778 -292.950646)
		(width 0.14478)
		(layer "In11.Cu")
		(net "M_L_CPU0_SB_DQ<11>")
	)
	(segment
		(start 438.540144 -292.719252)
		(end 438.540144 -292.805866)
		(width 0.14478)
		(layer "In11.Cu")
		(net "M_L_CPU0_SB_DQ<11>")
	)
	(segment
		(start 412.74111 -293.810182)
		(end 413.037782 -293.51351)
		(width 0.14478)
		(layer "In11.Cu")
		(net "M_L_CPU0_SB_DQ<11>")
	)
	(segment
		(start 414.015174 -293.810182)
		(end 414.87471 -292.950646)
		(width 0.14478)
		(layer "In11.Cu")
		(net "M_L_CPU0_SB_DQ<11>")
	)
	(segment
		(start 390.74344 -280.238708)
		(end 390.751822 -280.243534)
		(width 0.0889)
		(layer "In11.Cu")
		(net "M_L_CPU0_SB_DQ<11>")
	)
	(segment
		(start 425.520866 -292.805866)
		(end 425.665646 -292.950646)
		(width 0.14478)
		(layer "In11.Cu")
		(net "M_L_CPU0_SB_DQ<11>")
	)
	(segment
		(start 388.497826 -280.243534)
		(end 388.506208 -280.238708)
		(width 0.0889)
		(layer "In11.Cu")
		(net "M_L_CPU0_SB_DQ<11>")
	)
	(segment
		(start 437.98871 -292.719252)
		(end 438.13349 -292.574472)
		(width 0.14478)
		(layer "In11.Cu")
		(net "M_L_CPU0_SB_DQ<11>")
	)
	(segment
		(start 422.228264 -292.950646)
		(end 422.762172 -292.950646)
		(width 0.14478)
		(layer "In11.Cu")
		(net "M_L_CPU0_SB_DQ<11>")
	)
	(segment
		(start 411.793182 -293.51351)
		(end 412.184596 -293.51351)
		(width 0.14478)
		(layer "In11.Cu")
		(net "M_L_CPU0_SB_DQ<11>")
	)
	(segment
		(start 386.018786 -280.300684)
		(end 386.114798 -280.275284)
		(width 0.0889)
		(layer "In11.Cu")
		(net "M_L_CPU0_SB_DQ<11>")
	)
	(segment
		(start 413.297624 -293.51351)
		(end 413.594296 -293.810182)
		(width 0.14478)
		(layer "In11.Cu")
		(net "M_L_CPU0_SB_DQ<11>")
	)
	(segment
		(start 424.969432 -292.805866)
		(end 424.969432 -292.714172)
		(width 0.14478)
		(layer "In11.Cu")
		(net "M_L_CPU0_SB_DQ<11>")
	)
	(segment
		(start 391.691876 -280.243534)
		(end 391.70229 -280.24963)
		(width 0.0889)
		(layer "In11.Cu")
		(net "M_L_CPU0_SB_DQ<11>")
	)
	(segment
		(start 387.557772 -280.243534)
		(end 387.566154 -280.238708)
		(width 0.0889)
		(layer "In11.Cu")
		(net "M_L_CPU0_SB_DQ<11>")
	)
	(segment
		(start 425.520866 -292.714172)
		(end 425.520866 -292.805866)
		(width 0.14478)
		(layer "In11.Cu")
		(net "M_L_CPU0_SB_DQ<11>")
	)
	(segment
		(start 430.011078 -292.950646)
		(end 430.237392 -292.950646)
		(width 0.14478)
		(layer "In11.Cu")
		(net "M_L_CPU0_SB_DQ<11>")
	)
	(segment
		(start 416.658806 -292.950646)
		(end 416.959542 -292.64991)
		(width 0.14478)
		(layer "In11.Cu")
		(net "M_L_CPU0_SB_DQ<11>")
	)
	(segment
		(start 430.933606 -292.805866)
		(end 431.078386 -292.950646)
		(width 0.14478)
		(layer "In11.Cu")
		(net "M_L_CPU0_SB_DQ<11>")
	)
	(segment
		(start 433.201064 -292.950646)
		(end 434.051202 -293.800784)
		(width 0.14478)
		(layer "In11.Cu")
		(net "M_L_CPU0_SB_DQ<11>")
	)
	(segment
		(start 449.286122 -292.627812)
		(end 449.430902 -292.772592)
		(width 0.14478)
		(layer "In11.Cu")
		(net "M_L_CPU0_SB_DQ<11>")
	)
	(segment
		(start 448.734688 -293.384986)
		(end 448.879468 -293.240206)
		(width 0.14478)
		(layer "In11.Cu")
		(net "M_L_CPU0_SB_DQ<11>")
	)
	(segment
		(start 448.879468 -293.240206)
		(end 448.879468 -292.772592)
		(width 0.14478)
		(layer "In11.Cu")
		(net "M_L_CPU0_SB_DQ<11>")
	)
	(segment
		(start 423.603166 -292.950646)
		(end 424.824652 -292.950646)
		(width 0.14478)
		(layer "In11.Cu")
		(net "M_L_CPU0_SB_DQ<11>")
	)
	(segment
		(start 426.82922 -293.800784)
		(end 428.60214 -293.800784)
		(width 0.14478)
		(layer "In11.Cu")
		(net "M_L_CPU0_SB_DQ<11>")
	)
	(segment
		(start 432.222402 -292.719252)
		(end 432.367182 -292.574472)
		(width 0.14478)
		(layer "In11.Cu")
		(net "M_L_CPU0_SB_DQ<11>")
	)
	(segment
		(start 425.979082 -292.950646)
		(end 426.82922 -293.800784)
		(width 0.14478)
		(layer "In11.Cu")
		(net "M_L_CPU0_SB_DQ<11>")
	)
	(segment
		(start 423.313606 -292.574472)
		(end 423.458386 -292.719252)
		(width 0.14478)
		(layer "In11.Cu")
		(net "M_L_CPU0_SB_DQ<11>")
	)
	(segment
		(start 398.479772 -280.2001)
		(end 411.793182 -293.51351)
		(width 0.14478)
		(layer "In11.Cu")
		(net "M_L_CPU0_SB_DQ<11>")
	)
	(segment
		(start 440.23788 -292.719252)
		(end 440.23788 -292.805866)
		(width 0.14478)
		(layer "In11.Cu")
		(net "M_L_CPU0_SB_DQ<11>")
	)
	(segment
		(start 422.906952 -292.805866)
		(end 422.906952 -292.719252)
		(width 0.14478)
		(layer "In11.Cu")
		(net "M_L_CPU0_SB_DQ<11>")
	)
	(segment
		(start 430.526952 -292.569392)
		(end 430.788826 -292.569392)
		(width 0.14478)
		(layer "In11.Cu")
		(net "M_L_CPU0_SB_DQ<11>")
	)
	(segment
		(start 417.205922 -292.64991)
		(end 417.506658 -292.950646)
		(width 0.14478)
		(layer "In11.Cu")
		(net "M_L_CPU0_SB_DQ<11>")
	)
	(segment
		(start 439.686446 -292.805866)
		(end 439.686446 -292.719252)
		(width 0.14478)
		(layer "In11.Cu")
		(net "M_L_CPU0_SB_DQ<11>")
	)
	(segment
		(start 438.13349 -292.574472)
		(end 438.395364 -292.574472)
		(width 0.14478)
		(layer "In11.Cu")
		(net "M_L_CPU0_SB_DQ<11>")
	)
	(segment
		(start 440.0931 -292.574472)
		(end 440.23788 -292.719252)
		(width 0.14478)
		(layer "In11.Cu")
		(net "M_L_CPU0_SB_DQ<11>")
	)
	(segment
		(start 437.84393 -292.950646)
		(end 437.98871 -292.805866)
		(width 0.14478)
		(layer "In11.Cu")
		(net "M_L_CPU0_SB_DQ<11>")
	)
	(segment
		(start 448.879468 -292.772592)
		(end 449.024248 -292.627812)
		(width 0.14478)
		(layer "In11.Cu")
		(net "M_L_CPU0_SB_DQ<11>")
	)
	(segment
		(start 432.918616 -292.950646)
		(end 433.201064 -292.950646)
		(width 0.14478)
		(layer "In11.Cu")
		(net "M_L_CPU0_SB_DQ<11>")
	)
	(segment
		(start 415.846514 -292.64991)
		(end 416.092894 -292.64991)
		(width 0.14478)
		(layer "In11.Cu")
		(net "M_L_CPU0_SB_DQ<11>")
	)
	(segment
		(start 440.23788 -292.805866)
		(end 440.38266 -292.950646)
		(width 0.14478)
		(layer "In11.Cu")
		(net "M_L_CPU0_SB_DQ<11>")
	)
	(segment
		(start 445.341756 -292.683692)
		(end 445.626236 -292.683692)
		(width 0.14478)
		(layer "In11.Cu")
		(net "M_L_CPU0_SB_DQ<11>")
	)
	(segment
		(start 417.506658 -292.950646)
		(end 418.112702 -292.950646)
		(width 0.14478)
		(layer "In11.Cu")
		(net "M_L_CPU0_SB_DQ<11>")
	)
	(segment
		(start 423.458386 -292.719252)
		(end 423.458386 -292.805866)
		(width 0.14478)
		(layer "In11.Cu")
		(net "M_L_CPU0_SB_DQ<11>")
	)
	(segment
		(start 413.037782 -293.51351)
		(end 413.297624 -293.51351)
		(width 0.14478)
		(layer "In11.Cu")
		(net "M_L_CPU0_SB_DQ<11>")
	)
	(segment
		(start 438.395364 -292.574472)
		(end 438.540144 -292.719252)
		(width 0.14478)
		(layer "In11.Cu")
		(net "M_L_CPU0_SB_DQ<11>")
	)
	(segment
		(start 449.024248 -292.627812)
		(end 449.286122 -292.627812)
		(width 0.14478)
		(layer "In11.Cu")
		(net "M_L_CPU0_SB_DQ<11>")
	)
	(segment
		(start 418.96284 -293.800784)
		(end 421.378126 -293.800784)
		(width 0.14478)
		(layer "In11.Cu")
		(net "M_L_CPU0_SB_DQ<11>")
	)
	(segment
		(start 412.481268 -293.810182)
		(end 412.74111 -293.810182)
		(width 0.14478)
		(layer "In11.Cu")
		(net "M_L_CPU0_SB_DQ<11>")
	)
	(segment
		(start 439.541666 -292.950646)
		(end 439.686446 -292.805866)
		(width 0.14478)
		(layer "In11.Cu")
		(net "M_L_CPU0_SB_DQ<11>")
	)
	(segment
		(start 444.692532 -292.950646)
		(end 445.074802 -292.950646)
		(width 0.14478)
		(layer "In11.Cu")
		(net "M_L_CPU0_SB_DQ<11>")
	)
	(segment
		(start 438.684924 -292.950646)
		(end 439.541666 -292.950646)
		(width 0.14478)
		(layer "In11.Cu")
		(net "M_L_CPU0_SB_DQ<11>")
	)
	(segment
		(start 432.222402 -292.805866)
		(end 432.222402 -292.719252)
		(width 0.14478)
		(layer "In11.Cu")
		(net "M_L_CPU0_SB_DQ<11>")
	)
	(segment
		(start 424.969432 -292.714172)
		(end 425.114212 -292.569392)
		(width 0.14478)
		(layer "In11.Cu")
		(net "M_L_CPU0_SB_DQ<11>")
	)
	(segment
		(start 385.864862 -280.566114)
		(end 386.018786 -280.300684)
		(width 0.0889)
		(layer "In11.Cu")
		(net "M_L_CPU0_SB_DQ<11>")
	)
	(segment
		(start 439.686446 -292.719252)
		(end 439.831226 -292.574472)
		(width 0.14478)
		(layer "In11.Cu")
		(net "M_L_CPU0_SB_DQ<11>")
	)
	(segment
		(start 425.376086 -292.569392)
		(end 425.520866 -292.714172)
		(width 0.14478)
		(layer "In11.Cu")
		(net "M_L_CPU0_SB_DQ<11>")
	)
	(segment
		(start 434.051202 -293.800784)
		(end 436.610506 -293.800784)
		(width 0.14478)
		(layer "In11.Cu")
		(net "M_L_CPU0_SB_DQ<11>")
	)
	(segment
		(start 428.60214 -293.800784)
		(end 429.55591 -293.405814)
		(width 0.14478)
		(layer "In11.Cu")
		(net "M_L_CPU0_SB_DQ<11>")
	)
	(segment
		(start 413.594296 -293.810182)
		(end 414.015174 -293.810182)
		(width 0.14478)
		(layer "In11.Cu")
		(net "M_L_CPU0_SB_DQ<11>")
	)
	(segment
		(start 432.367182 -292.574472)
		(end 432.629056 -292.574472)
		(width 0.14478)
		(layer "In11.Cu")
		(net "M_L_CPU0_SB_DQ<11>")
	)
	(segment
		(start 436.610506 -293.800784)
		(end 437.460644 -292.950646)
		(width 0.14478)
		(layer "In11.Cu")
		(net "M_L_CPU0_SB_DQ<11>")
	)
	(segment
		(start 431.078386 -292.950646)
		(end 432.077622 -292.950646)
		(width 0.14478)
		(layer "In11.Cu")
		(net "M_L_CPU0_SB_DQ<11>")
	)
	(segment
		(start 445.89319 -292.950646)
		(end 447.959226 -292.950646)
		(width 0.14478)
		(layer "In11.Cu")
		(net "M_L_CPU0_SB_DQ<11>")
	)
	(segment
		(start 425.665646 -292.950646)
		(end 425.979082 -292.950646)
		(width 0.14478)
		(layer "In11.Cu")
		(net "M_L_CPU0_SB_DQ<11>")
	)
	(segment
		(start 430.382172 -292.714172)
		(end 430.526952 -292.569392)
		(width 0.14478)
		(layer "In11.Cu")
		(net "M_L_CPU0_SB_DQ<11>")
	)
	(segment
		(start 430.933606 -292.714172)
		(end 430.933606 -292.805866)
		(width 0.14478)
		(layer "In11.Cu")
		(net "M_L_CPU0_SB_DQ<11>")
	)
	(segment
		(start 416.959542 -292.64991)
		(end 417.205922 -292.64991)
		(width 0.14478)
		(layer "In11.Cu")
		(net "M_L_CPU0_SB_DQ<11>")
	)
	(segment
		(start 432.773836 -292.719252)
		(end 432.773836 -292.805866)
		(width 0.14478)
		(layer "In11.Cu")
		(net "M_L_CPU0_SB_DQ<11>")
	)
	(segment
		(start 437.460644 -292.950646)
		(end 437.84393 -292.950646)
		(width 0.14478)
		(layer "In11.Cu")
		(net "M_L_CPU0_SB_DQ<11>")
	)
	(segment
		(start 445.074802 -292.950646)
		(end 445.341756 -292.683692)
		(width 0.14478)
		(layer "In11.Cu")
		(net "M_L_CPU0_SB_DQ<11>")
	)
	(segment
		(start 391.317734 -280.243534)
		(end 391.326116 -280.238708)
		(width 0.0889)
		(layer "In11.Cu")
		(net "M_L_CPU0_SB_DQ<11>")
	)
	(segment
		(start 439.831226 -292.574472)
		(end 440.0931 -292.574472)
		(width 0.14478)
		(layer "In11.Cu")
		(net "M_L_CPU0_SB_DQ<11>")
	)
	(segment
		(start 440.38266 -292.950646)
		(end 440.745118 -292.950646)
		(width 0.14478)
		(layer "In11.Cu")
		(net "M_L_CPU0_SB_DQ<11>")
	)
	(segment
		(start 416.39363 -292.950646)
		(end 416.658806 -292.950646)
		(width 0.14478)
		(layer "In11.Cu")
		(net "M_L_CPU0_SB_DQ<11>")
	)
	(segment
		(start 393.37996 -280.2001)
		(end 395.759686 -280.2001)
		(width 0.0889)
		(layer "In11.Cu")
		(net "M_L_CPU0_SB_DQ<11>")
	)
	(segment
		(start 441.595002 -293.80053)
		(end 443.842648 -293.80053)
		(width 0.14478)
		(layer "In11.Cu")
		(net "M_L_CPU0_SB_DQ<11>")
	)
	(segment
		(start 423.051732 -292.574472)
		(end 423.313606 -292.574472)
		(width 0.14478)
		(layer "In11.Cu")
		(net "M_L_CPU0_SB_DQ<11>")
	)
	(segment
		(start 422.906952 -292.719252)
		(end 423.051732 -292.574472)
		(width 0.14478)
		(layer "In11.Cu")
		(net "M_L_CPU0_SB_DQ<11>")
	)
	(segment
		(start 415.545778 -292.950646)
		(end 415.846514 -292.64991)
		(width 0.14478)
		(layer "In11.Cu")
		(net "M_L_CPU0_SB_DQ<11>")
	)
	(segment
		(start 423.458386 -292.805866)
		(end 423.603166 -292.950646)
		(width 0.14478)
		(layer "In11.Cu")
		(net "M_L_CPU0_SB_DQ<11>")
	)
	(segment
		(start 422.762172 -292.950646)
		(end 422.906952 -292.805866)
		(width 0.14478)
		(layer "In11.Cu")
		(net "M_L_CPU0_SB_DQ<11>")
	)
	(segment
		(start 430.382172 -292.805866)
		(end 430.382172 -292.714172)
		(width 0.14478)
		(layer "In11.Cu")
		(net "M_L_CPU0_SB_DQ<11>")
	)
	(segment
		(start 440.745118 -292.950646)
		(end 441.595002 -293.80053)
		(width 0.14478)
		(layer "In11.Cu")
		(net "M_L_CPU0_SB_DQ<11>")
	)
	(segment
		(start 445.626236 -292.683692)
		(end 445.89319 -292.950646)
		(width 0.14478)
		(layer "In11.Cu")
		(net "M_L_CPU0_SB_DQ<11>")
	)
	(segment
		(start 395.759686 -280.2001)
		(end 398.479772 -280.2001)
		(width 0.14478)
		(layer "In11.Cu")
		(net "M_L_CPU0_SB_DQ<11>")
	)
	(segment
		(start 438.540144 -292.805866)
		(end 438.684924 -292.950646)
		(width 0.14478)
		(layer "In11.Cu")
		(net "M_L_CPU0_SB_DQ<11>")
	)
	(segment
		(start 418.112702 -292.950646)
		(end 418.96284 -293.800784)
		(width 0.14478)
		(layer "In11.Cu")
		(net "M_L_CPU0_SB_DQ<11>")
	)
	(segment
		(start 412.184596 -293.51351)
		(end 412.481268 -293.810182)
		(width 0.14478)
		(layer "In11.Cu")
		(net "M_L_CPU0_SB_DQ<11>")
	)
	(segment
		(start 432.629056 -292.574472)
		(end 432.773836 -292.719252)
		(width 0.14478)
		(layer "In11.Cu")
		(net "M_L_CPU0_SB_DQ<11>")
	)
	(segment
		(start 430.237392 -292.950646)
		(end 430.382172 -292.805866)
		(width 0.14478)
		(layer "In11.Cu")
		(net "M_L_CPU0_SB_DQ<11>")
	)
	(segment
		(start 437.98871 -292.805866)
		(end 437.98871 -292.719252)
		(width 0.14478)
		(layer "In11.Cu")
		(net "M_L_CPU0_SB_DQ<11>")
	)
	(segment
		(start 429.55591 -293.405814)
		(end 430.011078 -292.950646)
		(width 0.14478)
		(layer "In11.Cu")
		(net "M_L_CPU0_SB_DQ<11>")
	)
	(segment
		(start 447.959226 -292.950646)
		(end 448.393566 -293.384986)
		(width 0.14478)
		(layer "In11.Cu")
		(net "M_L_CPU0_SB_DQ<11>")
	)
	(arc
		(start 389.43788 -280.243534)
		(mid 389.624824 -280.193279)
		(end 389.811768 -280.243534)
		(width 0.0889)
		(layer "In11.Cu")
		(net "M_L_CPU0_SB_DQ<11>")
	)
	(arc
		(start 391.326116 -280.238708)
		(mid 391.509624 -280.193214)
		(end 391.691876 -280.243534)
		(width 0.0889)
		(layer "In11.Cu")
		(net "M_L_CPU0_SB_DQ<11>")
	)
	(arc
		(start 388.871968 -280.243534)
		(mid 389.154924 -280.319711)
		(end 389.43788 -280.243534)
		(width 0.0889)
		(layer "In11.Cu")
		(net "M_L_CPU0_SB_DQ<11>")
	)
	(arc
		(start 392.258042 -280.243534)
		(mid 392.44524 -280.193152)
		(end 392.632438 -280.243534)
		(width 0.0889)
		(layer "In11.Cu")
		(net "M_L_CPU0_SB_DQ<11>")
	)
	(arc
		(start 389.811768 -280.243534)
		(mid 390.094724 -280.319711)
		(end 390.37768 -280.243534)
		(width 0.0889)
		(layer "In11.Cu")
		(net "M_L_CPU0_SB_DQ<11>")
	)
	(arc
		(start 393.187682 -280.24963)
		(mid 393.280683 -280.212685)
		(end 393.37996 -280.2001)
		(width 0.0889)
		(layer "In11.Cu")
		(net "M_L_CPU0_SB_DQ<11>")
	)
	(arc
		(start 387.566154 -280.238708)
		(mid 387.749662 -280.193214)
		(end 387.931914 -280.243534)
		(width 0.0889)
		(layer "In11.Cu")
		(net "M_L_CPU0_SB_DQ<11>")
	)
	(arc
		(start 386.114798 -280.275284)
		(mid 386.370006 -280.318761)
		(end 386.617718 -280.243534)
		(width 0.0889)
		(layer "In11.Cu")
		(net "M_L_CPU0_SB_DQ<11>")
	)
	(arc
		(start 390.751822 -280.243534)
		(mid 391.034778 -280.319711)
		(end 391.317734 -280.243534)
		(width 0.0889)
		(layer "In11.Cu")
		(net "M_L_CPU0_SB_DQ<11>")
	)
	(arc
		(start 386.617718 -280.243534)
		(mid 386.799969 -280.193184)
		(end 386.983478 -280.238708)
		(width 0.0889)
		(layer "In11.Cu")
		(net "M_L_CPU0_SB_DQ<11>")
	)
	(arc
		(start 388.506208 -280.238708)
		(mid 388.689716 -280.193214)
		(end 388.871968 -280.243534)
		(width 0.0889)
		(layer "In11.Cu")
		(net "M_L_CPU0_SB_DQ<11>")
	)
	(arc
		(start 387.931914 -280.243534)
		(mid 388.21487 -280.319711)
		(end 388.497826 -280.243534)
		(width 0.0889)
		(layer "In11.Cu")
		(net "M_L_CPU0_SB_DQ<11>")
	)
	(arc
		(start 390.37768 -280.243534)
		(mid 390.559931 -280.193184)
		(end 390.74344 -280.238708)
		(width 0.0889)
		(layer "In11.Cu")
		(net "M_L_CPU0_SB_DQ<11>")
	)
	(arc
		(start 386.99186 -280.243534)
		(mid 387.274816 -280.319711)
		(end 387.557772 -280.243534)
		(width 0.0889)
		(layer "In11.Cu")
		(net "M_L_CPU0_SB_DQ<11>")
	)
	(arc
		(start 391.70229 -280.24963)
		(mid 391.980976 -280.31985)
		(end 392.258042 -280.243534)
		(width 0.0889)
		(layer "In11.Cu")
		(net "M_L_CPU0_SB_DQ<11>")
	)
	(arc
		(start 392.632438 -280.243534)
		(mid 392.909251 -280.319677)
		(end 393.187682 -280.24963)
		(width 0.0889)
		(layer "In11.Cu")
		(net "M_L_CPU0_SB_DQ<11>")
	)
	(segment
		(start 386.807964 -279.49017)
		(end 387.274816 -279.756108)
		(width 0.10668)
		(layer "F.Cu")
		(net "M_L_CPU0_SB_DQ<10>")
	)
	(segment
		(start 428.910242 -291.96538)
		(end 429.055022 -292.11016)
		(width 0.14478)
		(layer "In11.Cu")
		(net "M_L_CPU0_SB_DQ<10>")
	)
	(segment
		(start 437.838088 -291.260022)
		(end 437.982868 -291.115242)
		(width 0.14478)
		(layer "In11.Cu")
		(net "M_L_CPU0_SB_DQ<10>")
	)
	(segment
		(start 440.447176 -291.260022)
		(end 440.754516 -291.260022)
		(width 0.14478)
		(layer "In11.Cu")
		(net "M_L_CPU0_SB_DQ<10>")
	)
	(segment
		(start 413.26562 -291.78631)
		(end 413.498284 -291.78631)
		(width 0.14478)
		(layer "In11.Cu")
		(net "M_L_CPU0_SB_DQ<10>")
	)
	(segment
		(start 394.480034 -279.065736)
		(end 395.877542 -279.065736)
		(width 0.0889)
		(layer "In11.Cu")
		(net "M_L_CPU0_SB_DQ<10>")
	)
	(segment
		(start 423.461434 -291.007292)
		(end 423.461434 -291.115242)
		(width 0.14478)
		(layer "In11.Cu")
		(net "M_L_CPU0_SB_DQ<10>")
	)
	(segment
		(start 429.477678 -292.11016)
		(end 430.327816 -291.260022)
		(width 0.14478)
		(layer "In11.Cu")
		(net "M_L_CPU0_SB_DQ<10>")
	)
	(segment
		(start 416.880294 -290.94811)
		(end 417.124896 -290.94811)
		(width 0.14478)
		(layer "In11.Cu")
		(net "M_L_CPU0_SB_DQ<10>")
	)
	(segment
		(start 422.91 -291.115242)
		(end 422.91 -291.007292)
		(width 0.14478)
		(layer "In11.Cu")
		(net "M_L_CPU0_SB_DQ<10>")
	)
	(segment
		(start 387.42874 -279.490678)
		(end 387.524752 -279.465278)
		(width 0.0889)
		(layer "In11.Cu")
		(net "M_L_CPU0_SB_DQ<10>")
	)
	(segment
		(start 424.614848 -291.260022)
		(end 424.759628 -291.115242)
		(width 0.14478)
		(layer "In11.Cu")
		(net "M_L_CPU0_SB_DQ<10>")
	)
	(segment
		(start 415.767266 -290.94811)
		(end 416.011868 -290.94811)
		(width 0.14478)
		(layer "In11.Cu")
		(net "M_L_CPU0_SB_DQ<10>")
	)
	(segment
		(start 436.2069 -291.860732)
		(end 436.2069 -291.96538)
		(width 0.14478)
		(layer "In11.Cu")
		(net "M_L_CPU0_SB_DQ<10>")
	)
	(segment
		(start 438.389522 -290.865052)
		(end 438.534302 -291.009832)
		(width 0.14478)
		(layer "In11.Cu")
		(net "M_L_CPU0_SB_DQ<10>")
	)
	(segment
		(start 428.358808 -291.96538)
		(end 428.358808 -291.855652)
		(width 0.14478)
		(layer "In11.Cu")
		(net "M_L_CPU0_SB_DQ<10>")
	)
	(segment
		(start 436.06212 -291.715952)
		(end 436.2069 -291.860732)
		(width 0.14478)
		(layer "In11.Cu")
		(net "M_L_CPU0_SB_DQ<10>")
	)
	(segment
		(start 428.214028 -292.11016)
		(end 428.358808 -291.96538)
		(width 0.14478)
		(layer "In11.Cu")
		(net "M_L_CPU0_SB_DQ<10>")
	)
	(segment
		(start 388.393432 -279.428702)
		(end 388.401814 -279.433528)
		(width 0.0889)
		(layer "In11.Cu")
		(net "M_L_CPU0_SB_DQ<10>")
	)
	(segment
		(start 395.877542 -279.065736)
		(end 398.631664 -279.065736)
		(width 0.14478)
		(layer "In11.Cu")
		(net "M_L_CPU0_SB_DQ<10>")
	)
	(segment
		(start 432.656996 -291.115242)
		(end 432.801776 -291.260022)
		(width 0.14478)
		(layer "In11.Cu")
		(net "M_L_CPU0_SB_DQ<10>")
	)
	(segment
		(start 436.722012 -292.11016)
		(end 437.57215 -291.260022)
		(width 0.14478)
		(layer "In11.Cu")
		(net "M_L_CPU0_SB_DQ<10>")
	)
	(segment
		(start 432.105562 -291.004752)
		(end 432.250342 -290.859972)
		(width 0.14478)
		(layer "In11.Cu")
		(net "M_L_CPU0_SB_DQ<10>")
	)
	(segment
		(start 412.709106 -292.11016)
		(end 412.94177 -292.11016)
		(width 0.14478)
		(layer "In11.Cu")
		(net "M_L_CPU0_SB_DQ<10>")
	)
	(segment
		(start 425.311062 -291.012372)
		(end 425.311062 -291.115242)
		(width 0.14478)
		(layer "In11.Cu")
		(net "M_L_CPU0_SB_DQ<10>")
	)
	(segment
		(start 413.498284 -291.78631)
		(end 413.822134 -292.11016)
		(width 0.14478)
		(layer "In11.Cu")
		(net "M_L_CPU0_SB_DQ<10>")
	)
	(segment
		(start 423.05478 -290.862512)
		(end 423.316654 -290.862512)
		(width 0.14478)
		(layer "In11.Cu")
		(net "M_L_CPU0_SB_DQ<10>")
	)
	(segment
		(start 421.140128 -291.83711)
		(end 421.413178 -292.11016)
		(width 0.14478)
		(layer "In11.Cu")
		(net "M_L_CPU0_SB_DQ<10>")
	)
	(segment
		(start 432.512216 -290.859972)
		(end 432.656996 -291.004752)
		(width 0.14478)
		(layer "In11.Cu")
		(net "M_L_CPU0_SB_DQ<10>")
	)
	(segment
		(start 440.302396 -291.009832)
		(end 440.302396 -291.115242)
		(width 0.14478)
		(layer "In11.Cu")
		(net "M_L_CPU0_SB_DQ<10>")
	)
	(segment
		(start 447.413634 -290.882832)
		(end 447.675508 -290.882832)
		(width 0.14478)
		(layer "In11.Cu")
		(net "M_L_CPU0_SB_DQ<10>")
	)
	(segment
		(start 432.105562 -291.115242)
		(end 432.105562 -291.004752)
		(width 0.14478)
		(layer "In11.Cu")
		(net "M_L_CPU0_SB_DQ<10>")
	)
	(segment
		(start 392.145266 -279.424384)
		(end 392.161522 -279.433782)
		(width 0.0889)
		(layer "In11.Cu")
		(net "M_L_CPU0_SB_DQ<10>")
	)
	(segment
		(start 440.302396 -291.115242)
		(end 440.447176 -291.260022)
		(width 0.14478)
		(layer "In11.Cu")
		(net "M_L_CPU0_SB_DQ<10>")
	)
	(segment
		(start 424.759628 -291.012372)
		(end 424.904408 -290.867592)
		(width 0.14478)
		(layer "In11.Cu")
		(net "M_L_CPU0_SB_DQ<10>")
	)
	(segment
		(start 416.32378 -291.260022)
		(end 416.568382 -291.260022)
		(width 0.14478)
		(layer "In11.Cu")
		(net "M_L_CPU0_SB_DQ<10>")
	)
	(segment
		(start 438.679082 -291.260022)
		(end 439.606182 -291.260022)
		(width 0.14478)
		(layer "In11.Cu")
		(net "M_L_CPU0_SB_DQ<10>")
	)
	(segment
		(start 445.886586 -291.55771)
		(end 446.184274 -291.260022)
		(width 0.14478)
		(layer "In11.Cu")
		(net "M_L_CPU0_SB_DQ<10>")
	)
	(segment
		(start 423.316654 -290.862512)
		(end 423.461434 -291.007292)
		(width 0.14478)
		(layer "In11.Cu")
		(net "M_L_CPU0_SB_DQ<10>")
	)
	(segment
		(start 425.455842 -291.260022)
		(end 425.863512 -291.260022)
		(width 0.14478)
		(layer "In11.Cu")
		(net "M_L_CPU0_SB_DQ<10>")
	)
	(segment
		(start 445.62776 -291.55771)
		(end 445.886586 -291.55771)
		(width 0.14478)
		(layer "In11.Cu")
		(net "M_L_CPU0_SB_DQ<10>")
	)
	(segment
		(start 447.965068 -291.637212)
		(end 448.226942 -291.637212)
		(width 0.14478)
		(layer "In11.Cu")
		(net "M_L_CPU0_SB_DQ<10>")
	)
	(segment
		(start 436.35168 -292.11016)
		(end 436.722012 -292.11016)
		(width 0.14478)
		(layer "In11.Cu")
		(net "M_L_CPU0_SB_DQ<10>")
	)
	(segment
		(start 448.778376 -290.882832)
		(end 448.923156 -291.027612)
		(width 0.14478)
		(layer "In11.Cu")
		(net "M_L_CPU0_SB_DQ<10>")
	)
	(segment
		(start 447.124074 -291.260022)
		(end 447.268854 -291.115242)
		(width 0.14478)
		(layer "In11.Cu")
		(net "M_L_CPU0_SB_DQ<10>")
	)
	(segment
		(start 422.484042 -291.260022)
		(end 422.76522 -291.260022)
		(width 0.14478)
		(layer "In11.Cu")
		(net "M_L_CPU0_SB_DQ<10>")
	)
	(segment
		(start 438.534302 -291.009832)
		(end 438.534302 -291.115242)
		(width 0.14478)
		(layer "In11.Cu")
		(net "M_L_CPU0_SB_DQ<10>")
	)
	(segment
		(start 411.352238 -291.78631)
		(end 412.385256 -291.78631)
		(width 0.14478)
		(layer "In11.Cu")
		(net "M_L_CPU0_SB_DQ<10>")
	)
	(segment
		(start 432.801776 -291.260022)
		(end 433.210462 -291.260022)
		(width 0.14478)
		(layer "In11.Cu")
		(net "M_L_CPU0_SB_DQ<10>")
	)
	(segment
		(start 434.0606 -292.11016)
		(end 435.510686 -292.11016)
		(width 0.14478)
		(layer "In11.Cu")
		(net "M_L_CPU0_SB_DQ<10>")
	)
	(segment
		(start 387.274816 -279.756108)
		(end 387.42874 -279.490678)
		(width 0.0889)
		(layer "In11.Cu")
		(net "M_L_CPU0_SB_DQ<10>")
	)
	(segment
		(start 420.583614 -292.11016)
		(end 420.856664 -291.83711)
		(width 0.14478)
		(layer "In11.Cu")
		(net "M_L_CPU0_SB_DQ<10>")
	)
	(segment
		(start 392.726672 -279.433528)
		(end 392.738356 -279.42667)
		(width 0.0889)
		(layer "In11.Cu")
		(net "M_L_CPU0_SB_DQ<10>")
	)
	(segment
		(start 425.311062 -291.115242)
		(end 425.455842 -291.260022)
		(width 0.14478)
		(layer "In11.Cu")
		(net "M_L_CPU0_SB_DQ<10>")
	)
	(segment
		(start 414.08985 -292.11016)
		(end 414.939988 -291.260022)
		(width 0.14478)
		(layer "In11.Cu")
		(net "M_L_CPU0_SB_DQ<10>")
	)
	(segment
		(start 433.210462 -291.260022)
		(end 434.0606 -292.11016)
		(width 0.14478)
		(layer "In11.Cu")
		(net "M_L_CPU0_SB_DQ<10>")
	)
	(segment
		(start 394.035788 -279.509982)
		(end 394.480034 -279.065736)
		(width 0.0889)
		(layer "In11.Cu")
		(net "M_L_CPU0_SB_DQ<10>")
	)
	(segment
		(start 432.250342 -290.859972)
		(end 432.512216 -290.859972)
		(width 0.14478)
		(layer "In11.Cu")
		(net "M_L_CPU0_SB_DQ<10>")
	)
	(segment
		(start 448.923156 -291.115242)
		(end 449.067936 -291.260022)
		(width 0.14478)
		(layer "In11.Cu")
		(net "M_L_CPU0_SB_DQ<10>")
	)
	(segment
		(start 412.385256 -291.78631)
		(end 412.709106 -292.11016)
		(width 0.14478)
		(layer "In11.Cu")
		(net "M_L_CPU0_SB_DQ<10>")
	)
	(segment
		(start 449.663058 -291.260022)
		(end 450.088 -291.684964)
		(width 0.14478)
		(layer "In11.Cu")
		(net "M_L_CPU0_SB_DQ<10>")
	)
	(segment
		(start 428.910242 -291.855652)
		(end 428.910242 -291.96538)
		(width 0.14478)
		(layer "In11.Cu")
		(net "M_L_CPU0_SB_DQ<10>")
	)
	(segment
		(start 423.606214 -291.260022)
		(end 424.614848 -291.260022)
		(width 0.14478)
		(layer "In11.Cu")
		(net "M_L_CPU0_SB_DQ<10>")
	)
	(segment
		(start 435.655466 -291.860732)
		(end 435.800246 -291.715952)
		(width 0.14478)
		(layer "In11.Cu")
		(net "M_L_CPU0_SB_DQ<10>")
	)
	(segment
		(start 437.982868 -291.115242)
		(end 437.982868 -291.009832)
		(width 0.14478)
		(layer "In11.Cu")
		(net "M_L_CPU0_SB_DQ<10>")
	)
	(segment
		(start 412.94177 -292.11016)
		(end 413.26562 -291.78631)
		(width 0.14478)
		(layer "In11.Cu")
		(net "M_L_CPU0_SB_DQ<10>")
	)
	(segment
		(start 413.822134 -292.11016)
		(end 414.08985 -292.11016)
		(width 0.14478)
		(layer "In11.Cu")
		(net "M_L_CPU0_SB_DQ<10>")
	)
	(segment
		(start 448.226942 -291.637212)
		(end 448.371722 -291.492432)
		(width 0.14478)
		(layer "In11.Cu")
		(net "M_L_CPU0_SB_DQ<10>")
	)
	(segment
		(start 423.461434 -291.115242)
		(end 423.606214 -291.260022)
		(width 0.14478)
		(layer "In11.Cu")
		(net "M_L_CPU0_SB_DQ<10>")
	)
	(segment
		(start 448.371722 -291.027612)
		(end 448.516502 -290.882832)
		(width 0.14478)
		(layer "In11.Cu")
		(net "M_L_CPU0_SB_DQ<10>")
	)
	(segment
		(start 414.939988 -291.260022)
		(end 415.455354 -291.260022)
		(width 0.14478)
		(layer "In11.Cu")
		(net "M_L_CPU0_SB_DQ<10>")
	)
	(segment
		(start 422.76522 -291.260022)
		(end 422.91 -291.115242)
		(width 0.14478)
		(layer "In11.Cu")
		(net "M_L_CPU0_SB_DQ<10>")
	)
	(segment
		(start 444.678816 -291.260022)
		(end 445.330072 -291.260022)
		(width 0.14478)
		(layer "In11.Cu")
		(net "M_L_CPU0_SB_DQ<10>")
	)
	(segment
		(start 393.384786 -279.509982)
		(end 394.035788 -279.509982)
		(width 0.0889)
		(layer "In11.Cu")
		(net "M_L_CPU0_SB_DQ<10>")
	)
	(segment
		(start 416.568382 -291.260022)
		(end 416.880294 -290.94811)
		(width 0.14478)
		(layer "In11.Cu")
		(net "M_L_CPU0_SB_DQ<10>")
	)
	(segment
		(start 448.371722 -291.492432)
		(end 448.371722 -291.027612)
		(width 0.14478)
		(layer "In11.Cu")
		(net "M_L_CPU0_SB_DQ<10>")
	)
	(segment
		(start 438.127648 -290.865052)
		(end 438.389522 -290.865052)
		(width 0.14478)
		(layer "In11.Cu")
		(net "M_L_CPU0_SB_DQ<10>")
	)
	(segment
		(start 431.960782 -291.260022)
		(end 432.105562 -291.115242)
		(width 0.14478)
		(layer "In11.Cu")
		(net "M_L_CPU0_SB_DQ<10>")
	)
	(segment
		(start 425.166282 -290.867592)
		(end 425.311062 -291.012372)
		(width 0.14478)
		(layer "In11.Cu")
		(net "M_L_CPU0_SB_DQ<10>")
	)
	(segment
		(start 421.633904 -292.11016)
		(end 422.484042 -291.260022)
		(width 0.14478)
		(layer "In11.Cu")
		(net "M_L_CPU0_SB_DQ<10>")
	)
	(segment
		(start 448.923156 -291.027612)
		(end 448.923156 -291.115242)
		(width 0.14478)
		(layer "In11.Cu")
		(net "M_L_CPU0_SB_DQ<10>")
	)
	(segment
		(start 447.820288 -291.492432)
		(end 447.965068 -291.637212)
		(width 0.14478)
		(layer "In11.Cu")
		(net "M_L_CPU0_SB_DQ<10>")
	)
	(segment
		(start 429.055022 -292.11016)
		(end 429.477678 -292.11016)
		(width 0.14478)
		(layer "In11.Cu")
		(net "M_L_CPU0_SB_DQ<10>")
	)
	(segment
		(start 425.863512 -291.260022)
		(end 426.71365 -292.11016)
		(width 0.14478)
		(layer "In11.Cu")
		(net "M_L_CPU0_SB_DQ<10>")
	)
	(segment
		(start 439.750962 -291.115242)
		(end 439.750962 -291.009832)
		(width 0.14478)
		(layer "In11.Cu")
		(net "M_L_CPU0_SB_DQ<10>")
	)
	(segment
		(start 415.455354 -291.260022)
		(end 415.767266 -290.94811)
		(width 0.14478)
		(layer "In11.Cu")
		(net "M_L_CPU0_SB_DQ<10>")
	)
	(segment
		(start 447.675508 -290.882832)
		(end 447.820288 -291.027612)
		(width 0.14478)
		(layer "In11.Cu")
		(net "M_L_CPU0_SB_DQ<10>")
	)
	(segment
		(start 428.358808 -291.855652)
		(end 428.503588 -291.710872)
		(width 0.14478)
		(layer "In11.Cu")
		(net "M_L_CPU0_SB_DQ<10>")
	)
	(segment
		(start 428.503588 -291.710872)
		(end 428.765462 -291.710872)
		(width 0.14478)
		(layer "In11.Cu")
		(net "M_L_CPU0_SB_DQ<10>")
	)
	(segment
		(start 440.754516 -291.260022)
		(end 441.6044 -292.109906)
		(width 0.14478)
		(layer "In11.Cu")
		(net "M_L_CPU0_SB_DQ<10>")
	)
	(segment
		(start 435.510686 -292.11016)
		(end 435.655466 -291.96538)
		(width 0.14478)
		(layer "In11.Cu")
		(net "M_L_CPU0_SB_DQ<10>")
	)
	(segment
		(start 430.327816 -291.260022)
		(end 431.960782 -291.260022)
		(width 0.14478)
		(layer "In11.Cu")
		(net "M_L_CPU0_SB_DQ<10>")
	)
	(segment
		(start 437.982868 -291.009832)
		(end 438.127648 -290.865052)
		(width 0.14478)
		(layer "In11.Cu")
		(net "M_L_CPU0_SB_DQ<10>")
	)
	(segment
		(start 441.6044 -292.109906)
		(end 443.828932 -292.109906)
		(width 0.14478)
		(layer "In11.Cu")
		(net "M_L_CPU0_SB_DQ<10>")
	)
	(segment
		(start 398.631664 -279.065736)
		(end 411.352238 -291.78631)
		(width 0.14478)
		(layer "In11.Cu")
		(net "M_L_CPU0_SB_DQ<10>")
	)
	(segment
		(start 421.413178 -292.11016)
		(end 421.633904 -292.11016)
		(width 0.14478)
		(layer "In11.Cu")
		(net "M_L_CPU0_SB_DQ<10>")
	)
	(segment
		(start 417.436808 -291.260022)
		(end 418.122608 -291.260022)
		(width 0.14478)
		(layer "In11.Cu")
		(net "M_L_CPU0_SB_DQ<10>")
	)
	(segment
		(start 422.91 -291.007292)
		(end 423.05478 -290.862512)
		(width 0.14478)
		(layer "In11.Cu")
		(net "M_L_CPU0_SB_DQ<10>")
	)
	(segment
		(start 424.904408 -290.867592)
		(end 425.166282 -290.867592)
		(width 0.14478)
		(layer "In11.Cu")
		(net "M_L_CPU0_SB_DQ<10>")
	)
	(segment
		(start 439.750962 -291.009832)
		(end 439.895742 -290.865052)
		(width 0.14478)
		(layer "In11.Cu")
		(net "M_L_CPU0_SB_DQ<10>")
	)
	(segment
		(start 392.161522 -279.433782)
		(end 392.17346 -279.44064)
		(width 0.0889)
		(layer "In11.Cu")
		(net "M_L_CPU0_SB_DQ<10>")
	)
	(segment
		(start 418.972746 -292.11016)
		(end 420.583614 -292.11016)
		(width 0.14478)
		(layer "In11.Cu")
		(net "M_L_CPU0_SB_DQ<10>")
	)
	(segment
		(start 389.90778 -279.433528)
		(end 389.916162 -279.428702)
		(width 0.0889)
		(layer "In11.Cu")
		(net "M_L_CPU0_SB_DQ<10>")
	)
	(segment
		(start 440.157616 -290.865052)
		(end 440.302396 -291.009832)
		(width 0.14478)
		(layer "In11.Cu")
		(net "M_L_CPU0_SB_DQ<10>")
	)
	(segment
		(start 447.820288 -291.027612)
		(end 447.820288 -291.492432)
		(width 0.14478)
		(layer "In11.Cu")
		(net "M_L_CPU0_SB_DQ<10>")
	)
	(segment
		(start 443.828932 -292.109906)
		(end 444.678816 -291.260022)
		(width 0.14478)
		(layer "In11.Cu")
		(net "M_L_CPU0_SB_DQ<10>")
	)
	(segment
		(start 428.765462 -291.710872)
		(end 428.910242 -291.855652)
		(width 0.14478)
		(layer "In11.Cu")
		(net "M_L_CPU0_SB_DQ<10>")
	)
	(segment
		(start 447.268854 -291.027612)
		(end 447.413634 -290.882832)
		(width 0.14478)
		(layer "In11.Cu")
		(net "M_L_CPU0_SB_DQ<10>")
	)
	(segment
		(start 417.124896 -290.94811)
		(end 417.436808 -291.260022)
		(width 0.14478)
		(layer "In11.Cu")
		(net "M_L_CPU0_SB_DQ<10>")
	)
	(segment
		(start 435.655466 -291.96538)
		(end 435.655466 -291.860732)
		(width 0.14478)
		(layer "In11.Cu")
		(net "M_L_CPU0_SB_DQ<10>")
	)
	(segment
		(start 449.067936 -291.260022)
		(end 449.663058 -291.260022)
		(width 0.14478)
		(layer "In11.Cu")
		(net "M_L_CPU0_SB_DQ<10>")
	)
	(segment
		(start 446.184274 -291.260022)
		(end 447.124074 -291.260022)
		(width 0.14478)
		(layer "In11.Cu")
		(net "M_L_CPU0_SB_DQ<10>")
	)
	(segment
		(start 416.011868 -290.94811)
		(end 416.32378 -291.260022)
		(width 0.14478)
		(layer "In11.Cu")
		(net "M_L_CPU0_SB_DQ<10>")
	)
	(segment
		(start 447.268854 -291.115242)
		(end 447.268854 -291.027612)
		(width 0.14478)
		(layer "In11.Cu")
		(net "M_L_CPU0_SB_DQ<10>")
	)
	(segment
		(start 436.2069 -291.96538)
		(end 436.35168 -292.11016)
		(width 0.14478)
		(layer "In11.Cu")
		(net "M_L_CPU0_SB_DQ<10>")
	)
	(segment
		(start 448.516502 -290.882832)
		(end 448.778376 -290.882832)
		(width 0.14478)
		(layer "In11.Cu")
		(net "M_L_CPU0_SB_DQ<10>")
	)
	(segment
		(start 389.333486 -279.428702)
		(end 389.341868 -279.433528)
		(width 0.0889)
		(layer "In11.Cu")
		(net "M_L_CPU0_SB_DQ<10>")
	)
	(segment
		(start 445.330072 -291.260022)
		(end 445.62776 -291.55771)
		(width 0.14478)
		(layer "In11.Cu")
		(net "M_L_CPU0_SB_DQ<10>")
	)
	(segment
		(start 418.122608 -291.260022)
		(end 418.972746 -292.11016)
		(width 0.14478)
		(layer "In11.Cu")
		(net "M_L_CPU0_SB_DQ<10>")
	)
	(segment
		(start 420.856664 -291.83711)
		(end 421.140128 -291.83711)
		(width 0.14478)
		(layer "In11.Cu")
		(net "M_L_CPU0_SB_DQ<10>")
	)
	(segment
		(start 437.57215 -291.260022)
		(end 437.838088 -291.260022)
		(width 0.14478)
		(layer "In11.Cu")
		(net "M_L_CPU0_SB_DQ<10>")
	)
	(segment
		(start 439.606182 -291.260022)
		(end 439.750962 -291.115242)
		(width 0.14478)
		(layer "In11.Cu")
		(net "M_L_CPU0_SB_DQ<10>")
	)
	(segment
		(start 426.71365 -292.11016)
		(end 428.214028 -292.11016)
		(width 0.14478)
		(layer "In11.Cu")
		(net "M_L_CPU0_SB_DQ<10>")
	)
	(segment
		(start 432.656996 -291.004752)
		(end 432.656996 -291.115242)
		(width 0.14478)
		(layer "In11.Cu")
		(net "M_L_CPU0_SB_DQ<10>")
	)
	(segment
		(start 439.895742 -290.865052)
		(end 440.157616 -290.865052)
		(width 0.14478)
		(layer "In11.Cu")
		(net "M_L_CPU0_SB_DQ<10>")
	)
	(segment
		(start 424.759628 -291.115242)
		(end 424.759628 -291.012372)
		(width 0.14478)
		(layer "In11.Cu")
		(net "M_L_CPU0_SB_DQ<10>")
	)
	(segment
		(start 438.534302 -291.115242)
		(end 438.679082 -291.260022)
		(width 0.14478)
		(layer "In11.Cu")
		(net "M_L_CPU0_SB_DQ<10>")
	)
	(segment
		(start 435.800246 -291.715952)
		(end 436.06212 -291.715952)
		(width 0.14478)
		(layer "In11.Cu")
		(net "M_L_CPU0_SB_DQ<10>")
	)
	(arc
		(start 390.847834 -279.433528)
		(mid 391.034778 -279.383273)
		(end 391.221722 -279.433528)
		(width 0.0889)
		(layer "In11.Cu")
		(net "M_L_CPU0_SB_DQ<10>")
	)
	(arc
		(start 388.401814 -279.433528)
		(mid 388.68477 -279.509705)
		(end 388.967726 -279.433528)
		(width 0.0889)
		(layer "In11.Cu")
		(net "M_L_CPU0_SB_DQ<10>")
	)
	(arc
		(start 389.341868 -279.433528)
		(mid 389.624824 -279.509705)
		(end 389.90778 -279.433528)
		(width 0.0889)
		(layer "In11.Cu")
		(net "M_L_CPU0_SB_DQ<10>")
	)
	(arc
		(start 388.027672 -279.433528)
		(mid 388.209923 -279.383178)
		(end 388.393432 -279.428702)
		(width 0.0889)
		(layer "In11.Cu")
		(net "M_L_CPU0_SB_DQ<10>")
	)
	(arc
		(start 388.967726 -279.433528)
		(mid 389.149977 -279.383178)
		(end 389.333486 -279.428702)
		(width 0.0889)
		(layer "In11.Cu")
		(net "M_L_CPU0_SB_DQ<10>")
	)
	(arc
		(start 391.221722 -279.433528)
		(mid 391.504678 -279.509705)
		(end 391.787634 -279.433528)
		(width 0.0889)
		(layer "In11.Cu")
		(net "M_L_CPU0_SB_DQ<10>")
	)
	(arc
		(start 391.787634 -279.433528)
		(mid 391.965284 -279.383268)
		(end 392.145266 -279.424384)
		(width 0.0889)
		(layer "In11.Cu")
		(net "M_L_CPU0_SB_DQ<10>")
	)
	(arc
		(start 389.916162 -279.428702)
		(mid 390.09967 -279.383208)
		(end 390.281922 -279.433528)
		(width 0.0889)
		(layer "In11.Cu")
		(net "M_L_CPU0_SB_DQ<10>")
	)
	(arc
		(start 390.281922 -279.433528)
		(mid 390.564878 -279.509705)
		(end 390.847834 -279.433528)
		(width 0.0889)
		(layer "In11.Cu")
		(net "M_L_CPU0_SB_DQ<10>")
	)
	(arc
		(start 392.738356 -279.42667)
		(mid 392.920611 -279.383017)
		(end 393.101068 -279.433528)
		(width 0.0889)
		(layer "In11.Cu")
		(net "M_L_CPU0_SB_DQ<10>")
	)
	(arc
		(start 387.524752 -279.465278)
		(mid 387.77996 -279.508755)
		(end 388.027672 -279.433528)
		(width 0.0889)
		(layer "In11.Cu")
		(net "M_L_CPU0_SB_DQ<10>")
	)
	(arc
		(start 392.17346 -279.44064)
		(mid 392.450994 -279.509621)
		(end 392.726672 -279.433528)
		(width 0.0889)
		(layer "In11.Cu")
		(net "M_L_CPU0_SB_DQ<10>")
	)
	(arc
		(start 393.101068 -279.433528)
		(mid 393.237861 -279.49055)
		(end 393.384786 -279.509982)
		(width 0.0889)
		(layer "In11.Cu")
		(net "M_L_CPU0_SB_DQ<10>")
	)
	(segment
		(start 387.277864 -273.820128)
		(end 387.744716 -274.086066)
		(width 0.10668)
		(layer "F.Cu")
		(net "M_L_CPU0_SB_DQ<0>")
	)
	(segment
		(start 452.318374 -281.869642)
		(end 452.481442 -282.03271)
		(width 0.14478)
		(layer "In11.Cu")
		(net "M_L_CPU0_SB_DQ<0>")
	)
	(segment
		(start 421.726868 -281.910028)
		(end 422.576752 -281.060144)
		(width 0.14478)
		(layer "In11.Cu")
		(net "M_L_CPU0_SB_DQ<0>")
	)
	(segment
		(start 402.371052 -272.93951)
		(end 411.34157 -281.910028)
		(width 0.14478)
		(layer "In11.Cu")
		(net "M_L_CPU0_SB_DQ<0>")
	)
	(segment
		(start 418.122354 -281.05989)
		(end 418.972492 -281.910028)
		(width 0.14478)
		(layer "In11.Cu")
		(net "M_L_CPU0_SB_DQ<0>")
	)
	(segment
		(start 414.063942 -281.910028)
		(end 414.91408 -281.05989)
		(width 0.14478)
		(layer "In11.Cu")
		(net "M_L_CPU0_SB_DQ<0>")
	)
	(segment
		(start 437.66486 -281.060144)
		(end 440.689492 -281.060144)
		(width 0.14478)
		(layer "In11.Cu")
		(net "M_L_CPU0_SB_DQ<0>")
	)
	(segment
		(start 388.497826 -274.408646)
		(end 388.506208 -274.413472)
		(width 0.0889)
		(layer "In11.Cu")
		(net "M_L_CPU0_SB_DQ<0>")
	)
	(segment
		(start 394.626084 -273.397472)
		(end 395.129258 -273.397472)
		(width 0.0889)
		(layer "In11.Cu")
		(net "M_L_CPU0_SB_DQ<0>")
	)
	(segment
		(start 392.257026 -274.408392)
		(end 392.270742 -274.416266)
		(width 0.0889)
		(layer "In11.Cu")
		(net "M_L_CPU0_SB_DQ<0>")
	)
	(segment
		(start 411.34157 -281.910028)
		(end 414.063942 -281.910028)
		(width 0.14478)
		(layer "In11.Cu")
		(net "M_L_CPU0_SB_DQ<0>")
	)
	(segment
		(start 392.245088 -274.401534)
		(end 392.257026 -274.408392)
		(width 0.0889)
		(layer "In11.Cu")
		(net "M_L_CPU0_SB_DQ<0>")
	)
	(segment
		(start 452.71182 -282.03271)
		(end 452.874888 -281.869642)
		(width 0.14478)
		(layer "In11.Cu")
		(net "M_L_CPU0_SB_DQ<0>")
	)
	(segment
		(start 430.120806 -281.060144)
		(end 433.145438 -281.060144)
		(width 0.14478)
		(layer "In11.Cu")
		(net "M_L_CPU0_SB_DQ<0>")
	)
	(segment
		(start 426.451268 -281.910028)
		(end 429.270922 -281.910028)
		(width 0.14478)
		(layer "In11.Cu")
		(net "M_L_CPU0_SB_DQ<0>")
	)
	(segment
		(start 453.037956 -281.060144)
		(end 453.763126 -281.060144)
		(width 0.14478)
		(layer "In11.Cu")
		(net "M_L_CPU0_SB_DQ<0>")
	)
	(segment
		(start 452.318374 -281.223212)
		(end 452.318374 -281.869642)
		(width 0.14478)
		(layer "In11.Cu")
		(net "M_L_CPU0_SB_DQ<0>")
	)
	(segment
		(start 395.129258 -273.397472)
		(end 395.58722 -272.93951)
		(width 0.0889)
		(layer "In11.Cu")
		(net "M_L_CPU0_SB_DQ<0>")
	)
	(segment
		(start 429.270922 -281.910028)
		(end 430.120806 -281.060144)
		(width 0.14478)
		(layer "In11.Cu")
		(net "M_L_CPU0_SB_DQ<0>")
	)
	(segment
		(start 418.972492 -281.910028)
		(end 421.726868 -281.910028)
		(width 0.14478)
		(layer "In11.Cu")
		(net "M_L_CPU0_SB_DQ<0>")
	)
	(segment
		(start 452.155306 -281.060144)
		(end 452.318374 -281.223212)
		(width 0.14478)
		(layer "In11.Cu")
		(net "M_L_CPU0_SB_DQ<0>")
	)
	(segment
		(start 433.995322 -281.910028)
		(end 436.814976 -281.910028)
		(width 0.14478)
		(layer "In11.Cu")
		(net "M_L_CPU0_SB_DQ<0>")
	)
	(segment
		(start 441.539376 -281.910028)
		(end 443.675516 -281.910028)
		(width 0.14478)
		(layer "In11.Cu")
		(net "M_L_CPU0_SB_DQ<0>")
	)
	(segment
		(start 393.56411 -274.459446)
		(end 394.626084 -273.397472)
		(width 0.0889)
		(layer "In11.Cu")
		(net "M_L_CPU0_SB_DQ<0>")
	)
	(segment
		(start 387.744716 -274.086066)
		(end 387.590792 -274.351496)
		(width 0.0889)
		(layer "In11.Cu")
		(net "M_L_CPU0_SB_DQ<0>")
	)
	(segment
		(start 395.58722 -272.93951)
		(end 395.980412 -272.93951)
		(width 0.0889)
		(layer "In11.Cu")
		(net "M_L_CPU0_SB_DQ<0>")
	)
	(segment
		(start 444.5254 -281.060144)
		(end 452.155306 -281.060144)
		(width 0.14478)
		(layer "In11.Cu")
		(net "M_L_CPU0_SB_DQ<0>")
	)
	(segment
		(start 452.874888 -281.223212)
		(end 453.037956 -281.060144)
		(width 0.14478)
		(layer "In11.Cu")
		(net "M_L_CPU0_SB_DQ<0>")
	)
	(segment
		(start 452.481442 -282.03271)
		(end 452.71182 -282.03271)
		(width 0.14478)
		(layer "In11.Cu")
		(net "M_L_CPU0_SB_DQ<0>")
	)
	(segment
		(start 433.145438 -281.060144)
		(end 433.995322 -281.910028)
		(width 0.14478)
		(layer "In11.Cu")
		(net "M_L_CPU0_SB_DQ<0>")
	)
	(segment
		(start 452.874888 -281.869642)
		(end 452.874888 -281.223212)
		(width 0.14478)
		(layer "In11.Cu")
		(net "M_L_CPU0_SB_DQ<0>")
	)
	(segment
		(start 414.91408 -281.05989)
		(end 418.122354 -281.05989)
		(width 0.14478)
		(layer "In11.Cu")
		(net "M_L_CPU0_SB_DQ<0>")
	)
	(segment
		(start 391.317734 -274.408646)
		(end 391.326116 -274.413472)
		(width 0.0889)
		(layer "In11.Cu")
		(net "M_L_CPU0_SB_DQ<0>")
	)
	(segment
		(start 390.74344 -274.413472)
		(end 390.751822 -274.408646)
		(width 0.0889)
		(layer "In11.Cu")
		(net "M_L_CPU0_SB_DQ<0>")
	)
	(segment
		(start 393.384786 -274.459446)
		(end 393.56411 -274.459446)
		(width 0.0889)
		(layer "In11.Cu")
		(net "M_L_CPU0_SB_DQ<0>")
	)
	(segment
		(start 440.689492 -281.060144)
		(end 441.539376 -281.910028)
		(width 0.14478)
		(layer "In11.Cu")
		(net "M_L_CPU0_SB_DQ<0>")
	)
	(segment
		(start 422.576752 -281.060144)
		(end 425.601384 -281.060144)
		(width 0.14478)
		(layer "In11.Cu")
		(net "M_L_CPU0_SB_DQ<0>")
	)
	(segment
		(start 443.675516 -281.910028)
		(end 444.5254 -281.060144)
		(width 0.14478)
		(layer "In11.Cu")
		(net "M_L_CPU0_SB_DQ<0>")
	)
	(segment
		(start 387.590792 -274.351496)
		(end 387.613144 -274.434808)
		(width 0.0889)
		(layer "In11.Cu")
		(net "M_L_CPU0_SB_DQ<0>")
	)
	(segment
		(start 453.763126 -281.060144)
		(end 454.188068 -281.485086)
		(width 0.14478)
		(layer "In11.Cu")
		(net "M_L_CPU0_SB_DQ<0>")
	)
	(segment
		(start 425.601384 -281.060144)
		(end 426.451268 -281.910028)
		(width 0.14478)
		(layer "In11.Cu")
		(net "M_L_CPU0_SB_DQ<0>")
	)
	(segment
		(start 392.63066 -274.408646)
		(end 392.648694 -274.397978)
		(width 0.0889)
		(layer "In11.Cu")
		(net "M_L_CPU0_SB_DQ<0>")
	)
	(segment
		(start 436.814976 -281.910028)
		(end 437.66486 -281.060144)
		(width 0.14478)
		(layer "In11.Cu")
		(net "M_L_CPU0_SB_DQ<0>")
	)
	(segment
		(start 395.980412 -272.93951)
		(end 402.371052 -272.93951)
		(width 0.14478)
		(layer "In11.Cu")
		(net "M_L_CPU0_SB_DQ<0>")
	)
	(arc
		(start 387.931914 -274.408646)
		(mid 388.21487 -274.332469)
		(end 388.497826 -274.408646)
		(width 0.0889)
		(layer "In11.Cu")
		(net "M_L_CPU0_SB_DQ<0>")
	)
	(arc
		(start 387.613144 -274.434808)
		(mid 387.775476 -274.457626)
		(end 387.931914 -274.408646)
		(width 0.0889)
		(layer "In11.Cu")
		(net "M_L_CPU0_SB_DQ<0>")
	)
	(arc
		(start 389.811768 -274.408646)
		(mid 390.094724 -274.332469)
		(end 390.37768 -274.408646)
		(width 0.0889)
		(layer "In11.Cu")
		(net "M_L_CPU0_SB_DQ<0>")
	)
	(arc
		(start 389.43788 -274.408646)
		(mid 389.624824 -274.458901)
		(end 389.811768 -274.408646)
		(width 0.0889)
		(layer "In11.Cu")
		(net "M_L_CPU0_SB_DQ<0>")
	)
	(arc
		(start 391.326116 -274.413472)
		(mid 391.509624 -274.458966)
		(end 391.691876 -274.408646)
		(width 0.0889)
		(layer "In11.Cu")
		(net "M_L_CPU0_SB_DQ<0>")
	)
	(arc
		(start 392.270742 -274.416266)
		(mid 392.451672 -274.458744)
		(end 392.63066 -274.408646)
		(width 0.0889)
		(layer "In11.Cu")
		(net "M_L_CPU0_SB_DQ<0>")
	)
	(arc
		(start 388.871968 -274.408646)
		(mid 389.154924 -274.332469)
		(end 389.43788 -274.408646)
		(width 0.0889)
		(layer "In11.Cu")
		(net "M_L_CPU0_SB_DQ<0>")
	)
	(arc
		(start 391.691876 -274.408646)
		(mid 391.967554 -274.332516)
		(end 392.245088 -274.401534)
		(width 0.0889)
		(layer "In11.Cu")
		(net "M_L_CPU0_SB_DQ<0>")
	)
	(arc
		(start 388.506208 -274.413472)
		(mid 388.689716 -274.458966)
		(end 388.871968 -274.408646)
		(width 0.0889)
		(layer "In11.Cu")
		(net "M_L_CPU0_SB_DQ<0>")
	)
	(arc
		(start 390.37768 -274.408646)
		(mid 390.559931 -274.458996)
		(end 390.74344 -274.413472)
		(width 0.0889)
		(layer "In11.Cu")
		(net "M_L_CPU0_SB_DQ<0>")
	)
	(arc
		(start 390.751822 -274.408646)
		(mid 391.034778 -274.332469)
		(end 391.317734 -274.408646)
		(width 0.0889)
		(layer "In11.Cu")
		(net "M_L_CPU0_SB_DQ<0>")
	)
	(arc
		(start 392.648694 -274.397978)
		(mid 392.924389 -274.332135)
		(end 393.197334 -274.408646)
		(width 0.0889)
		(layer "In11.Cu")
		(net "M_L_CPU0_SB_DQ<0>")
	)
	(arc
		(start 393.197334 -274.408646)
		(mid 393.287697 -274.446456)
		(end 393.384786 -274.459446)
		(width 0.0889)
		(layer "In11.Cu")
		(net "M_L_CPU0_SB_DQ<0>")
	)
	(segment
		(start 386.807964 -266.530074)
		(end 387.274816 -266.796012)
		(width 0.10668)
		(layer "F.Cu")
		(net "M_L_CPU0_SB_CS_N<1>")
	)
	(segment
		(start 448.480688 -268.088872)
		(end 448.625468 -267.944092)
		(width 0.14478)
		(layer "In11.Cu")
		(net "M_L_CPU0_SB_CS_N<1>")
	)
	(segment
		(start 392.161522 -266.473686)
		(end 392.17346 -266.480544)
		(width 0.0889)
		(layer "In11.Cu")
		(net "M_L_CPU0_SB_CS_N<1>")
	)
	(segment
		(start 387.274816 -266.796012)
		(end 387.42874 -266.530582)
		(width 0.0889)
		(layer "In11.Cu")
		(net "M_L_CPU0_SB_CS_N<1>")
	)
	(segment
		(start 395.90599 -265.70305)
		(end 408.137868 -265.70305)
		(width 0.14478)
		(layer "In11.Cu")
		(net "M_L_CPU0_SB_CS_N<1>")
	)
	(segment
		(start 449.176902 -268.310106)
		(end 449.663058 -268.310106)
		(width 0.14478)
		(layer "In11.Cu")
		(net "M_L_CPU0_SB_CS_N<1>")
	)
	(segment
		(start 447.929254 -268.53134)
		(end 448.074034 -268.67612)
		(width 0.14478)
		(layer "In11.Cu")
		(net "M_L_CPU0_SB_CS_N<1>")
	)
	(segment
		(start 430.028096 -268.310106)
		(end 433.210462 -268.310106)
		(width 0.14478)
		(layer "In11.Cu")
		(net "M_L_CPU0_SB_CS_N<1>")
	)
	(segment
		(start 426.516546 -269.160244)
		(end 429.177958 -269.160244)
		(width 0.14478)
		(layer "In11.Cu")
		(net "M_L_CPU0_SB_CS_N<1>")
	)
	(segment
		(start 448.335908 -268.67612)
		(end 448.480688 -268.53134)
		(width 0.14478)
		(layer "In11.Cu")
		(net "M_L_CPU0_SB_CS_N<1>")
	)
	(segment
		(start 447.37782 -268.165326)
		(end 447.37782 -268.088872)
		(width 0.14478)
		(layer "In11.Cu")
		(net "M_L_CPU0_SB_CS_N<1>")
	)
	(segment
		(start 421.633904 -269.160244)
		(end 422.484042 -268.310106)
		(width 0.14478)
		(layer "In11.Cu")
		(net "M_L_CPU0_SB_CS_N<1>")
	)
	(segment
		(start 408.137868 -265.70305)
		(end 411.595062 -269.160244)
		(width 0.14478)
		(layer "In11.Cu")
		(net "M_L_CPU0_SB_CS_N<1>")
	)
	(segment
		(start 448.074034 -268.67612)
		(end 448.335908 -268.67612)
		(width 0.14478)
		(layer "In11.Cu")
		(net "M_L_CPU0_SB_CS_N<1>")
	)
	(segment
		(start 387.42874 -266.530582)
		(end 387.524752 -266.505182)
		(width 0.0889)
		(layer "In11.Cu")
		(net "M_L_CPU0_SB_CS_N<1>")
	)
	(segment
		(start 388.393432 -266.468606)
		(end 388.401814 -266.473432)
		(width 0.0889)
		(layer "In11.Cu")
		(net "M_L_CPU0_SB_CS_N<1>")
	)
	(segment
		(start 448.480688 -268.53134)
		(end 448.480688 -268.088872)
		(width 0.14478)
		(layer "In11.Cu")
		(net "M_L_CPU0_SB_CS_N<1>")
	)
	(segment
		(start 389.333486 -266.468606)
		(end 389.341868 -266.473432)
		(width 0.0889)
		(layer "In11.Cu")
		(net "M_L_CPU0_SB_CS_N<1>")
	)
	(segment
		(start 392.145266 -266.464288)
		(end 392.161522 -266.473686)
		(width 0.0889)
		(layer "In11.Cu")
		(net "M_L_CPU0_SB_CS_N<1>")
	)
	(segment
		(start 422.484042 -268.310106)
		(end 425.666408 -268.310106)
		(width 0.14478)
		(layer "In11.Cu")
		(net "M_L_CPU0_SB_CS_N<1>")
	)
	(segment
		(start 449.663058 -268.310106)
		(end 450.088 -268.735048)
		(width 0.14478)
		(layer "In11.Cu")
		(net "M_L_CPU0_SB_CS_N<1>")
	)
	(segment
		(start 436.722012 -269.160244)
		(end 437.57215 -268.310106)
		(width 0.14478)
		(layer "In11.Cu")
		(net "M_L_CPU0_SB_CS_N<1>")
	)
	(segment
		(start 448.625468 -267.944092)
		(end 448.887342 -267.944092)
		(width 0.14478)
		(layer "In11.Cu")
		(net "M_L_CPU0_SB_CS_N<1>")
	)
	(segment
		(start 449.032122 -268.088872)
		(end 449.032122 -268.165326)
		(width 0.14478)
		(layer "In11.Cu")
		(net "M_L_CPU0_SB_CS_N<1>")
	)
	(segment
		(start 448.887342 -267.944092)
		(end 449.032122 -268.088872)
		(width 0.14478)
		(layer "In11.Cu")
		(net "M_L_CPU0_SB_CS_N<1>")
	)
	(segment
		(start 449.032122 -268.165326)
		(end 449.176902 -268.310106)
		(width 0.14478)
		(layer "In11.Cu")
		(net "M_L_CPU0_SB_CS_N<1>")
	)
	(segment
		(start 429.177958 -269.160244)
		(end 430.028096 -268.310106)
		(width 0.14478)
		(layer "In11.Cu")
		(net "M_L_CPU0_SB_CS_N<1>")
	)
	(segment
		(start 434.0606 -269.160244)
		(end 436.722012 -269.160244)
		(width 0.14478)
		(layer "In11.Cu")
		(net "M_L_CPU0_SB_CS_N<1>")
	)
	(segment
		(start 392.82116 -266.43457)
		(end 393.087098 -266.366498)
		(width 0.0889)
		(layer "In11.Cu")
		(net "M_L_CPU0_SB_CS_N<1>")
	)
	(segment
		(start 394.298678 -265.581892)
		(end 395.421358 -265.581892)
		(width 0.0889)
		(layer "In11.Cu")
		(net "M_L_CPU0_SB_CS_N<1>")
	)
	(segment
		(start 447.5226 -267.944092)
		(end 447.784474 -267.944092)
		(width 0.14478)
		(layer "In11.Cu")
		(net "M_L_CPU0_SB_CS_N<1>")
	)
	(segment
		(start 395.421358 -265.581892)
		(end 395.542516 -265.70305)
		(width 0.0889)
		(layer "In11.Cu")
		(net "M_L_CPU0_SB_CS_N<1>")
	)
	(segment
		(start 389.90778 -266.473432)
		(end 389.916162 -266.468606)
		(width 0.0889)
		(layer "In11.Cu")
		(net "M_L_CPU0_SB_CS_N<1>")
	)
	(segment
		(start 433.210462 -268.310106)
		(end 434.0606 -269.160244)
		(width 0.14478)
		(layer "In11.Cu")
		(net "M_L_CPU0_SB_CS_N<1>")
	)
	(segment
		(start 437.57215 -268.310106)
		(end 447.23304 -268.310106)
		(width 0.14478)
		(layer "In11.Cu")
		(net "M_L_CPU0_SB_CS_N<1>")
	)
	(segment
		(start 447.929254 -268.088872)
		(end 447.929254 -268.53134)
		(width 0.14478)
		(layer "In11.Cu")
		(net "M_L_CPU0_SB_CS_N<1>")
	)
	(segment
		(start 411.595062 -269.160244)
		(end 421.633904 -269.160244)
		(width 0.14478)
		(layer "In11.Cu")
		(net "M_L_CPU0_SB_CS_N<1>")
	)
	(segment
		(start 447.23304 -268.310106)
		(end 447.37782 -268.165326)
		(width 0.14478)
		(layer "In11.Cu")
		(net "M_L_CPU0_SB_CS_N<1>")
	)
	(segment
		(start 393.514072 -266.366498)
		(end 394.298678 -265.581892)
		(width 0.0889)
		(layer "In11.Cu")
		(net "M_L_CPU0_SB_CS_N<1>")
	)
	(segment
		(start 447.37782 -268.088872)
		(end 447.5226 -267.944092)
		(width 0.14478)
		(layer "In11.Cu")
		(net "M_L_CPU0_SB_CS_N<1>")
	)
	(segment
		(start 392.726672 -266.473432)
		(end 392.738356 -266.466574)
		(width 0.0889)
		(layer "In11.Cu")
		(net "M_L_CPU0_SB_CS_N<1>")
	)
	(segment
		(start 425.666408 -268.310106)
		(end 426.516546 -269.160244)
		(width 0.14478)
		(layer "In11.Cu")
		(net "M_L_CPU0_SB_CS_N<1>")
	)
	(segment
		(start 393.087098 -266.366498)
		(end 393.514072 -266.366498)
		(width 0.0889)
		(layer "In11.Cu")
		(net "M_L_CPU0_SB_CS_N<1>")
	)
	(segment
		(start 447.784474 -267.944092)
		(end 447.929254 -268.088872)
		(width 0.14478)
		(layer "In11.Cu")
		(net "M_L_CPU0_SB_CS_N<1>")
	)
	(segment
		(start 395.542516 -265.70305)
		(end 395.90599 -265.70305)
		(width 0.0889)
		(layer "In11.Cu")
		(net "M_L_CPU0_SB_CS_N<1>")
	)
	(arc
		(start 389.916162 -266.468606)
		(mid 390.09967 -266.423112)
		(end 390.281922 -266.473432)
		(width 0.0889)
		(layer "In11.Cu")
		(net "M_L_CPU0_SB_CS_N<1>")
	)
	(arc
		(start 391.221722 -266.473432)
		(mid 391.504678 -266.549609)
		(end 391.787634 -266.473432)
		(width 0.0889)
		(layer "In11.Cu")
		(net "M_L_CPU0_SB_CS_N<1>")
	)
	(arc
		(start 390.281922 -266.473432)
		(mid 390.564878 -266.549609)
		(end 390.847834 -266.473432)
		(width 0.0889)
		(layer "In11.Cu")
		(net "M_L_CPU0_SB_CS_N<1>")
	)
	(arc
		(start 387.524752 -266.505182)
		(mid 387.77996 -266.548659)
		(end 388.027672 -266.473432)
		(width 0.0889)
		(layer "In11.Cu")
		(net "M_L_CPU0_SB_CS_N<1>")
	)
	(arc
		(start 390.847834 -266.473432)
		(mid 391.034778 -266.423177)
		(end 391.221722 -266.473432)
		(width 0.0889)
		(layer "In11.Cu")
		(net "M_L_CPU0_SB_CS_N<1>")
	)
	(arc
		(start 388.027672 -266.473432)
		(mid 388.209923 -266.423082)
		(end 388.393432 -266.468606)
		(width 0.0889)
		(layer "In11.Cu")
		(net "M_L_CPU0_SB_CS_N<1>")
	)
	(arc
		(start 388.401814 -266.473432)
		(mid 388.68477 -266.549609)
		(end 388.967726 -266.473432)
		(width 0.0889)
		(layer "In11.Cu")
		(net "M_L_CPU0_SB_CS_N<1>")
	)
	(arc
		(start 392.738356 -266.466574)
		(mid 392.778799 -266.44809)
		(end 392.82116 -266.43457)
		(width 0.0889)
		(layer "In11.Cu")
		(net "M_L_CPU0_SB_CS_N<1>")
	)
	(arc
		(start 388.967726 -266.473432)
		(mid 389.149977 -266.423082)
		(end 389.333486 -266.468606)
		(width 0.0889)
		(layer "In11.Cu")
		(net "M_L_CPU0_SB_CS_N<1>")
	)
	(arc
		(start 392.17346 -266.480544)
		(mid 392.450994 -266.549525)
		(end 392.726672 -266.473432)
		(width 0.0889)
		(layer "In11.Cu")
		(net "M_L_CPU0_SB_CS_N<1>")
	)
	(arc
		(start 391.787634 -266.473432)
		(mid 391.965284 -266.423172)
		(end 392.145266 -266.464288)
		(width 0.0889)
		(layer "In11.Cu")
		(net "M_L_CPU0_SB_CS_N<1>")
	)
	(arc
		(start 389.341868 -266.473432)
		(mid 389.624824 -266.549609)
		(end 389.90778 -266.473432)
		(width 0.0889)
		(layer "In11.Cu")
		(net "M_L_CPU0_SB_CS_N<1>")
	)
	(segment
		(start 385.39801 -265.720068)
		(end 385.864862 -265.986006)
		(width 0.10668)
		(layer "F.Cu")
		(net "M_L_CPU0_SB_CS_N<0>")
	)
	(segment
		(start 386.114798 -265.695176)
		(end 386.018786 -265.720576)
		(width 0.0889)
		(layer "In11.Cu")
		(net "M_L_CPU0_SB_CS_N<0>")
	)
	(segment
		(start 429.270922 -268.310106)
		(end 426.451268 -268.310106)
		(width 0.14478)
		(layer "In11.Cu")
		(net "M_L_CPU0_SB_CS_N<0>")
	)
	(segment
		(start 395.46276 -265.24839)
		(end 395.416278 -265.294872)
		(width 0.0889)
		(layer "In11.Cu")
		(net "M_L_CPU0_SB_CS_N<0>")
	)
	(segment
		(start 391.326116 -265.6586)
		(end 391.317734 -265.663426)
		(width 0.0889)
		(layer "In11.Cu")
		(net "M_L_CPU0_SB_CS_N<0>")
	)
	(segment
		(start 437.66486 -267.460222)
		(end 436.814976 -268.310106)
		(width 0.14478)
		(layer "In11.Cu")
		(net "M_L_CPU0_SB_CS_N<0>")
	)
	(segment
		(start 411.492954 -268.310106)
		(end 408.431238 -265.24839)
		(width 0.14478)
		(layer "In11.Cu")
		(net "M_L_CPU0_SB_CS_N<0>")
	)
	(segment
		(start 421.726868 -268.310106)
		(end 411.492954 -268.310106)
		(width 0.14478)
		(layer "In11.Cu")
		(net "M_L_CPU0_SB_CS_N<0>")
	)
	(segment
		(start 422.576752 -267.460222)
		(end 421.726868 -268.310106)
		(width 0.14478)
		(layer "In11.Cu")
		(net "M_L_CPU0_SB_CS_N<0>")
	)
	(segment
		(start 395.92885 -265.24839)
		(end 395.46276 -265.24839)
		(width 0.0889)
		(layer "In11.Cu")
		(net "M_L_CPU0_SB_CS_N<0>")
	)
	(segment
		(start 392.634216 -265.663426)
		(end 392.619738 -265.655044)
		(width 0.0889)
		(layer "In11.Cu")
		(net "M_L_CPU0_SB_CS_N<0>")
	)
	(segment
		(start 408.431238 -265.24839)
		(end 395.92885 -265.24839)
		(width 0.14478)
		(layer "In11.Cu")
		(net "M_L_CPU0_SB_CS_N<0>")
	)
	(segment
		(start 433.995322 -268.310106)
		(end 433.145438 -267.460222)
		(width 0.14478)
		(layer "In11.Cu")
		(net "M_L_CPU0_SB_CS_N<0>")
	)
	(segment
		(start 425.601384 -267.460222)
		(end 422.576752 -267.460222)
		(width 0.14478)
		(layer "In11.Cu")
		(net "M_L_CPU0_SB_CS_N<0>")
	)
	(segment
		(start 426.451268 -268.310106)
		(end 425.601384 -267.460222)
		(width 0.14478)
		(layer "In11.Cu")
		(net "M_L_CPU0_SB_CS_N<0>")
	)
	(segment
		(start 390.751822 -265.663426)
		(end 390.74344 -265.6586)
		(width 0.0889)
		(layer "In11.Cu")
		(net "M_L_CPU0_SB_CS_N<0>")
	)
	(segment
		(start 395.416278 -265.294872)
		(end 394.022834 -265.294872)
		(width 0.0889)
		(layer "In11.Cu")
		(net "M_L_CPU0_SB_CS_N<0>")
	)
	(segment
		(start 433.145438 -267.460222)
		(end 430.120806 -267.460222)
		(width 0.14478)
		(layer "In11.Cu")
		(net "M_L_CPU0_SB_CS_N<0>")
	)
	(segment
		(start 386.99186 -265.663426)
		(end 386.983478 -265.6586)
		(width 0.0889)
		(layer "In11.Cu")
		(net "M_L_CPU0_SB_CS_N<0>")
	)
	(segment
		(start 454.188068 -267.885164)
		(end 453.763126 -267.460222)
		(width 0.14478)
		(layer "In11.Cu")
		(net "M_L_CPU0_SB_CS_N<0>")
	)
	(segment
		(start 393.198604 -265.66368)
		(end 393.177014 -265.676126)
		(width 0.0889)
		(layer "In11.Cu")
		(net "M_L_CPU0_SB_CS_N<0>")
	)
	(segment
		(start 453.763126 -267.460222)
		(end 437.66486 -267.460222)
		(width 0.14478)
		(layer "In11.Cu")
		(net "M_L_CPU0_SB_CS_N<0>")
	)
	(segment
		(start 386.018786 -265.720576)
		(end 385.864862 -265.986006)
		(width 0.0889)
		(layer "In11.Cu")
		(net "M_L_CPU0_SB_CS_N<0>")
	)
	(segment
		(start 391.715244 -265.677142)
		(end 391.691876 -265.663426)
		(width 0.0889)
		(layer "In11.Cu")
		(net "M_L_CPU0_SB_CS_N<0>")
	)
	(segment
		(start 394.022834 -265.294872)
		(end 393.704318 -265.613388)
		(width 0.0889)
		(layer "In11.Cu")
		(net "M_L_CPU0_SB_CS_N<0>")
	)
	(segment
		(start 388.506208 -265.6586)
		(end 388.497826 -265.663426)
		(width 0.0889)
		(layer "In11.Cu")
		(net "M_L_CPU0_SB_CS_N<0>")
	)
	(segment
		(start 387.566154 -265.6586)
		(end 387.557772 -265.663426)
		(width 0.0889)
		(layer "In11.Cu")
		(net "M_L_CPU0_SB_CS_N<0>")
	)
	(segment
		(start 436.814976 -268.310106)
		(end 433.995322 -268.310106)
		(width 0.14478)
		(layer "In11.Cu")
		(net "M_L_CPU0_SB_CS_N<0>")
	)
	(segment
		(start 393.704318 -265.613388)
		(end 393.384786 -265.613388)
		(width 0.0889)
		(layer "In11.Cu")
		(net "M_L_CPU0_SB_CS_N<0>")
	)
	(segment
		(start 430.120806 -267.460222)
		(end 429.270922 -268.310106)
		(width 0.14478)
		(layer "In11.Cu")
		(net "M_L_CPU0_SB_CS_N<0>")
	)
	(arc
		(start 393.177014 -265.676126)
		(mid 392.903985 -265.739445)
		(end 392.634216 -265.663426)
		(width 0.0889)
		(layer "In11.Cu")
		(net "M_L_CPU0_SB_CS_N<0>")
	)
	(arc
		(start 386.983478 -265.6586)
		(mid 386.79997 -265.613106)
		(end 386.617718 -265.663426)
		(width 0.0889)
		(layer "In11.Cu")
		(net "M_L_CPU0_SB_CS_N<0>")
	)
	(arc
		(start 387.931914 -265.663426)
		(mid 387.749663 -265.613076)
		(end 387.566154 -265.6586)
		(width 0.0889)
		(layer "In11.Cu")
		(net "M_L_CPU0_SB_CS_N<0>")
	)
	(arc
		(start 391.317734 -265.663426)
		(mid 391.034778 -265.739603)
		(end 390.751822 -265.663426)
		(width 0.0889)
		(layer "In11.Cu")
		(net "M_L_CPU0_SB_CS_N<0>")
	)
	(arc
		(start 388.871968 -265.663426)
		(mid 388.689717 -265.613076)
		(end 388.506208 -265.6586)
		(width 0.0889)
		(layer "In11.Cu")
		(net "M_L_CPU0_SB_CS_N<0>")
	)
	(arc
		(start 389.43788 -265.663426)
		(mid 389.154924 -265.739603)
		(end 388.871968 -265.663426)
		(width 0.0889)
		(layer "In11.Cu")
		(net "M_L_CPU0_SB_CS_N<0>")
	)
	(arc
		(start 392.259058 -265.663426)
		(mid 391.988901 -265.740188)
		(end 391.715244 -265.677142)
		(width 0.0889)
		(layer "In11.Cu")
		(net "M_L_CPU0_SB_CS_N<0>")
	)
	(arc
		(start 387.557772 -265.663426)
		(mid 387.274816 -265.739603)
		(end 386.99186 -265.663426)
		(width 0.0889)
		(layer "In11.Cu")
		(net "M_L_CPU0_SB_CS_N<0>")
	)
	(arc
		(start 389.811768 -265.663426)
		(mid 389.624824 -265.613171)
		(end 389.43788 -265.663426)
		(width 0.0889)
		(layer "In11.Cu")
		(net "M_L_CPU0_SB_CS_N<0>")
	)
	(arc
		(start 386.617718 -265.663426)
		(mid 386.370005 -265.738646)
		(end 386.114798 -265.695176)
		(width 0.0889)
		(layer "In11.Cu")
		(net "M_L_CPU0_SB_CS_N<0>")
	)
	(arc
		(start 392.619738 -265.655044)
		(mid 392.438322 -265.612787)
		(end 392.259058 -265.663426)
		(width 0.0889)
		(layer "In11.Cu")
		(net "M_L_CPU0_SB_CS_N<0>")
	)
	(arc
		(start 393.384786 -265.613388)
		(mid 393.288389 -265.626286)
		(end 393.198604 -265.66368)
		(width 0.0889)
		(layer "In11.Cu")
		(net "M_L_CPU0_SB_CS_N<0>")
	)
	(arc
		(start 388.497826 -265.663426)
		(mid 388.21487 -265.739603)
		(end 387.931914 -265.663426)
		(width 0.0889)
		(layer "In11.Cu")
		(net "M_L_CPU0_SB_CS_N<0>")
	)
	(arc
		(start 390.37768 -265.663426)
		(mid 390.094724 -265.739603)
		(end 389.811768 -265.663426)
		(width 0.0889)
		(layer "In11.Cu")
		(net "M_L_CPU0_SB_CS_N<0>")
	)
	(arc
		(start 391.691876 -265.663426)
		(mid 391.509625 -265.613076)
		(end 391.326116 -265.6586)
		(width 0.0889)
		(layer "In11.Cu")
		(net "M_L_CPU0_SB_CS_N<0>")
	)
	(arc
		(start 390.74344 -265.6586)
		(mid 390.559932 -265.613106)
		(end 390.37768 -265.663426)
		(width 0.0889)
		(layer "In11.Cu")
		(net "M_L_CPU0_SB_CS_N<0>")
	)
	(segment
		(start 385.39801 -270.580104)
		(end 385.864862 -270.846042)
		(width 0.10668)
		(layer "F.Cu")
		(net "M_L_CPU0_SB_CB<7>")
	)
	(segment
		(start 419.628066 -274.222464)
		(end 414.789366 -274.222464)
		(width 0.14478)
		(layer "In11.Cu")
		(net "M_L_CPU0_SB_CB<7>")
	)
	(segment
		(start 421.726868 -274.260056)
		(end 419.665658 -274.260056)
		(width 0.14478)
		(layer "In11.Cu")
		(net "M_L_CPU0_SB_CB<7>")
	)
	(segment
		(start 444.15329 -273.554698)
		(end 444.00851 -273.409918)
		(width 0.14478)
		(layer "In11.Cu")
		(net "M_L_CPU0_SB_CB<7>")
	)
	(segment
		(start 443.601856 -274.047712)
		(end 443.457076 -274.192492)
		(width 0.14478)
		(layer "In11.Cu")
		(net "M_L_CPU0_SB_CB<7>")
	)
	(segment
		(start 392.296904 -270.500602)
		(end 392.257788 -270.523462)
		(width 0.0889)
		(layer "In11.Cu")
		(net "M_L_CPU0_SB_CB<7>")
	)
	(segment
		(start 422.576752 -273.410172)
		(end 421.726868 -274.260056)
		(width 0.14478)
		(layer "In11.Cu")
		(net "M_L_CPU0_SB_CB<7>")
	)
	(segment
		(start 445.400938 -274.192492)
		(end 445.256158 -274.047712)
		(width 0.14478)
		(layer "In11.Cu")
		(net "M_L_CPU0_SB_CB<7>")
	)
	(segment
		(start 388.506208 -270.518636)
		(end 388.497826 -270.523462)
		(width 0.0889)
		(layer "In11.Cu")
		(net "M_L_CPU0_SB_CB<7>")
	)
	(segment
		(start 394.551916 -268.855952)
		(end 393.783312 -269.624556)
		(width 0.0889)
		(layer "In11.Cu")
		(net "M_L_CPU0_SB_CB<7>")
	)
	(segment
		(start 441.022486 -273.409918)
		(end 440.323732 -273.409918)
		(width 0.14478)
		(layer "In11.Cu")
		(net "M_L_CPU0_SB_CB<7>")
	)
	(segment
		(start 425.601384 -273.410172)
		(end 422.576752 -273.410172)
		(width 0.14478)
		(layer "In11.Cu")
		(net "M_L_CPU0_SB_CB<7>")
	)
	(segment
		(start 386.114798 -270.555212)
		(end 386.018786 -270.580612)
		(width 0.0889)
		(layer "In11.Cu")
		(net "M_L_CPU0_SB_CB<7>")
	)
	(segment
		(start 445.256158 -274.047712)
		(end 445.256158 -273.554698)
		(width 0.14478)
		(layer "In11.Cu")
		(net "M_L_CPU0_SB_CB<7>")
	)
	(segment
		(start 445.662812 -274.192492)
		(end 445.400938 -274.192492)
		(width 0.14478)
		(layer "In11.Cu")
		(net "M_L_CPU0_SB_CB<7>")
	)
	(segment
		(start 443.746636 -273.409918)
		(end 443.601856 -273.554698)
		(width 0.14478)
		(layer "In11.Cu")
		(net "M_L_CPU0_SB_CB<7>")
	)
	(segment
		(start 392.257788 -270.523462)
		(end 392.258042 -270.523462)
		(width 0.0889)
		(layer "In11.Cu")
		(net "M_L_CPU0_SB_CB<7>")
	)
	(segment
		(start 433.995322 -274.260056)
		(end 433.145438 -273.410172)
		(width 0.14478)
		(layer "In11.Cu")
		(net "M_L_CPU0_SB_CB<7>")
	)
	(segment
		(start 393.10183 -269.713456)
		(end 393.093448 -269.70863)
		(width 0.0889)
		(layer "In11.Cu")
		(net "M_L_CPU0_SB_CB<7>")
	)
	(segment
		(start 419.665658 -274.260056)
		(end 419.628066 -274.222464)
		(width 0.14478)
		(layer "In11.Cu")
		(net "M_L_CPU0_SB_CB<7>")
	)
	(segment
		(start 440.323478 -273.410172)
		(end 437.66486 -273.410172)
		(width 0.14478)
		(layer "In11.Cu")
		(net "M_L_CPU0_SB_CB<7>")
	)
	(segment
		(start 392.727688 -269.713456)
		(end 392.697208 -269.731236)
		(width 0.0889)
		(layer "In11.Cu")
		(net "M_L_CPU0_SB_CB<7>")
	)
	(segment
		(start 441.167266 -274.001992)
		(end 441.167266 -273.554698)
		(width 0.14478)
		(layer "In11.Cu")
		(net "M_L_CPU0_SB_CB<7>")
	)
	(segment
		(start 444.00851 -273.409918)
		(end 443.746636 -273.409918)
		(width 0.14478)
		(layer "In11.Cu")
		(net "M_L_CPU0_SB_CB<7>")
	)
	(segment
		(start 445.807592 -274.047712)
		(end 445.662812 -274.192492)
		(width 0.14478)
		(layer "In11.Cu")
		(net "M_L_CPU0_SB_CB<7>")
	)
	(segment
		(start 395.47038 -268.67993)
		(end 395.294358 -268.855952)
		(width 0.0889)
		(layer "In11.Cu")
		(net "M_L_CPU0_SB_CB<7>")
	)
	(segment
		(start 426.451268 -274.260056)
		(end 425.601384 -273.410172)
		(width 0.14478)
		(layer "In11.Cu")
		(net "M_L_CPU0_SB_CB<7>")
	)
	(segment
		(start 441.57392 -274.146772)
		(end 441.312046 -274.146772)
		(width 0.14478)
		(layer "In11.Cu")
		(net "M_L_CPU0_SB_CB<7>")
	)
	(segment
		(start 441.312046 -274.146772)
		(end 441.167266 -274.001992)
		(width 0.14478)
		(layer "In11.Cu")
		(net "M_L_CPU0_SB_CB<7>")
	)
	(segment
		(start 443.050422 -274.047712)
		(end 443.050422 -273.554698)
		(width 0.14478)
		(layer "In11.Cu")
		(net "M_L_CPU0_SB_CB<7>")
	)
	(segment
		(start 444.29807 -274.192492)
		(end 444.15329 -274.047712)
		(width 0.14478)
		(layer "In11.Cu")
		(net "M_L_CPU0_SB_CB<7>")
	)
	(segment
		(start 444.559944 -274.192492)
		(end 444.29807 -274.192492)
		(width 0.14478)
		(layer "In11.Cu")
		(net "M_L_CPU0_SB_CB<7>")
	)
	(segment
		(start 387.566154 -270.518636)
		(end 387.557772 -270.523462)
		(width 0.0889)
		(layer "In11.Cu")
		(net "M_L_CPU0_SB_CB<7>")
	)
	(segment
		(start 441.86348 -273.409918)
		(end 441.7187 -273.554698)
		(width 0.14478)
		(layer "In11.Cu")
		(net "M_L_CPU0_SB_CB<7>")
	)
	(segment
		(start 386.99186 -270.523462)
		(end 386.983478 -270.518636)
		(width 0.0889)
		(layer "In11.Cu")
		(net "M_L_CPU0_SB_CB<7>")
	)
	(segment
		(start 440.323732 -273.409918)
		(end 440.323478 -273.410172)
		(width 0.14478)
		(layer "In11.Cu")
		(net "M_L_CPU0_SB_CB<7>")
	)
	(segment
		(start 430.120806 -273.410172)
		(end 429.270922 -274.260056)
		(width 0.14478)
		(layer "In11.Cu")
		(net "M_L_CPU0_SB_CB<7>")
	)
	(segment
		(start 414.789366 -274.222464)
		(end 414.730438 -274.281392)
		(width 0.14478)
		(layer "In11.Cu")
		(net "M_L_CPU0_SB_CB<7>")
	)
	(segment
		(start 448.81292 -273.409918)
		(end 445.952372 -273.409918)
		(width 0.14478)
		(layer "In11.Cu")
		(net "M_L_CPU0_SB_CB<7>")
	)
	(segment
		(start 391.70229 -270.529558)
		(end 391.691876 -270.523462)
		(width 0.0889)
		(layer "In11.Cu")
		(net "M_L_CPU0_SB_CB<7>")
	)
	(segment
		(start 444.704724 -274.047712)
		(end 444.559944 -274.192492)
		(width 0.14478)
		(layer "In11.Cu")
		(net "M_L_CPU0_SB_CB<7>")
	)
	(segment
		(start 433.145438 -273.410172)
		(end 430.120806 -273.410172)
		(width 0.14478)
		(layer "In11.Cu")
		(net "M_L_CPU0_SB_CB<7>")
	)
	(segment
		(start 443.195202 -274.192492)
		(end 443.050422 -274.047712)
		(width 0.14478)
		(layer "In11.Cu")
		(net "M_L_CPU0_SB_CB<7>")
	)
	(segment
		(start 441.167266 -273.554698)
		(end 441.022486 -273.409918)
		(width 0.14478)
		(layer "In11.Cu")
		(net "M_L_CPU0_SB_CB<7>")
	)
	(segment
		(start 443.601856 -273.554698)
		(end 443.601856 -274.047712)
		(width 0.14478)
		(layer "In11.Cu")
		(net "M_L_CPU0_SB_CB<7>")
	)
	(segment
		(start 386.018786 -270.580612)
		(end 385.864862 -270.846042)
		(width 0.0889)
		(layer "In11.Cu")
		(net "M_L_CPU0_SB_CB<7>")
	)
	(segment
		(start 395.294358 -268.855952)
		(end 394.551916 -268.855952)
		(width 0.0889)
		(layer "In11.Cu")
		(net "M_L_CPU0_SB_CB<7>")
	)
	(segment
		(start 395.980412 -268.67993)
		(end 395.47038 -268.67993)
		(width 0.0889)
		(layer "In11.Cu")
		(net "M_L_CPU0_SB_CB<7>")
	)
	(segment
		(start 437.66486 -273.410172)
		(end 436.814976 -274.260056)
		(width 0.14478)
		(layer "In11.Cu")
		(net "M_L_CPU0_SB_CB<7>")
	)
	(segment
		(start 442.905642 -273.409918)
		(end 441.86348 -273.409918)
		(width 0.14478)
		(layer "In11.Cu")
		(net "M_L_CPU0_SB_CB<7>")
	)
	(segment
		(start 411.528514 -274.281392)
		(end 405.927052 -268.67993)
		(width 0.14478)
		(layer "In11.Cu")
		(net "M_L_CPU0_SB_CB<7>")
	)
	(segment
		(start 443.050422 -273.554698)
		(end 442.905642 -273.409918)
		(width 0.14478)
		(layer "In11.Cu")
		(net "M_L_CPU0_SB_CB<7>")
	)
	(segment
		(start 390.751822 -270.523462)
		(end 390.74344 -270.518636)
		(width 0.0889)
		(layer "In11.Cu")
		(net "M_L_CPU0_SB_CB<7>")
	)
	(segment
		(start 405.927052 -268.67993)
		(end 395.980412 -268.67993)
		(width 0.14478)
		(layer "In11.Cu")
		(net "M_L_CPU0_SB_CB<7>")
	)
	(segment
		(start 391.326116 -270.518636)
		(end 391.317734 -270.523462)
		(width 0.0889)
		(layer "In11.Cu")
		(net "M_L_CPU0_SB_CB<7>")
	)
	(segment
		(start 436.814976 -274.260056)
		(end 433.995322 -274.260056)
		(width 0.14478)
		(layer "In11.Cu")
		(net "M_L_CPU0_SB_CB<7>")
	)
	(segment
		(start 450.088 -274.684998)
		(end 448.81292 -273.409918)
		(width 0.14478)
		(layer "In11.Cu")
		(net "M_L_CPU0_SB_CB<7>")
	)
	(segment
		(start 429.270922 -274.260056)
		(end 426.451268 -274.260056)
		(width 0.14478)
		(layer "In11.Cu")
		(net "M_L_CPU0_SB_CB<7>")
	)
	(segment
		(start 444.849504 -273.409918)
		(end 444.704724 -273.554698)
		(width 0.14478)
		(layer "In11.Cu")
		(net "M_L_CPU0_SB_CB<7>")
	)
	(segment
		(start 445.256158 -273.554698)
		(end 445.111378 -273.409918)
		(width 0.14478)
		(layer "In11.Cu")
		(net "M_L_CPU0_SB_CB<7>")
	)
	(segment
		(start 445.952372 -273.409918)
		(end 445.807592 -273.554698)
		(width 0.14478)
		(layer "In11.Cu")
		(net "M_L_CPU0_SB_CB<7>")
	)
	(segment
		(start 444.704724 -273.554698)
		(end 444.704724 -274.047712)
		(width 0.14478)
		(layer "In11.Cu")
		(net "M_L_CPU0_SB_CB<7>")
	)
	(segment
		(start 441.7187 -274.001992)
		(end 441.57392 -274.146772)
		(width 0.14478)
		(layer "In11.Cu")
		(net "M_L_CPU0_SB_CB<7>")
	)
	(segment
		(start 445.807592 -273.554698)
		(end 445.807592 -274.047712)
		(width 0.14478)
		(layer "In11.Cu")
		(net "M_L_CPU0_SB_CB<7>")
	)
	(segment
		(start 441.7187 -273.554698)
		(end 441.7187 -274.001992)
		(width 0.14478)
		(layer "In11.Cu")
		(net "M_L_CPU0_SB_CB<7>")
	)
	(segment
		(start 443.457076 -274.192492)
		(end 443.195202 -274.192492)
		(width 0.14478)
		(layer "In11.Cu")
		(net "M_L_CPU0_SB_CB<7>")
	)
	(segment
		(start 445.111378 -273.409918)
		(end 444.849504 -273.409918)
		(width 0.14478)
		(layer "In11.Cu")
		(net "M_L_CPU0_SB_CB<7>")
	)
	(segment
		(start 444.15329 -274.047712)
		(end 444.15329 -273.554698)
		(width 0.14478)
		(layer "In11.Cu")
		(net "M_L_CPU0_SB_CB<7>")
	)
	(segment
		(start 414.730438 -274.281392)
		(end 411.528514 -274.281392)
		(width 0.14478)
		(layer "In11.Cu")
		(net "M_L_CPU0_SB_CB<7>")
	)
	(arc
		(start 386.617718 -270.523462)
		(mid 386.370005 -270.598682)
		(end 386.114798 -270.555212)
		(width 0.0889)
		(layer "In11.Cu")
		(net "M_L_CPU0_SB_CB<7>")
	)
	(arc
		(start 388.497826 -270.523462)
		(mid 388.21487 -270.599639)
		(end 387.931914 -270.523462)
		(width 0.0889)
		(layer "In11.Cu")
		(net "M_L_CPU0_SB_CB<7>")
	)
	(arc
		(start 389.811768 -270.523462)
		(mid 389.624824 -270.473207)
		(end 389.43788 -270.523462)
		(width 0.0889)
		(layer "In11.Cu")
		(net "M_L_CPU0_SB_CB<7>")
	)
	(arc
		(start 392.697208 -269.731236)
		(mid 392.581781 -269.864612)
		(end 392.540236 -270.036036)
		(width 0.0889)
		(layer "In11.Cu")
		(net "M_L_CPU0_SB_CB<7>")
	)
	(arc
		(start 387.557772 -270.523462)
		(mid 387.274816 -270.599639)
		(end 386.99186 -270.523462)
		(width 0.0889)
		(layer "In11.Cu")
		(net "M_L_CPU0_SB_CB<7>")
	)
	(arc
		(start 389.43788 -270.523462)
		(mid 389.154924 -270.599639)
		(end 388.871968 -270.523462)
		(width 0.0889)
		(layer "In11.Cu")
		(net "M_L_CPU0_SB_CB<7>")
	)
	(arc
		(start 387.931914 -270.523462)
		(mid 387.749663 -270.473112)
		(end 387.566154 -270.518636)
		(width 0.0889)
		(layer "In11.Cu")
		(net "M_L_CPU0_SB_CB<7>")
	)
	(arc
		(start 393.093448 -269.70863)
		(mid 392.90994 -269.663136)
		(end 392.727688 -269.713456)
		(width 0.0889)
		(layer "In11.Cu")
		(net "M_L_CPU0_SB_CB<7>")
	)
	(arc
		(start 392.540236 -270.036036)
		(mid 392.475721 -270.298255)
		(end 392.296904 -270.500602)
		(width 0.0889)
		(layer "In11.Cu")
		(net "M_L_CPU0_SB_CB<7>")
	)
	(arc
		(start 388.871968 -270.523462)
		(mid 388.689717 -270.473112)
		(end 388.506208 -270.518636)
		(width 0.0889)
		(layer "In11.Cu")
		(net "M_L_CPU0_SB_CB<7>")
	)
	(arc
		(start 390.37768 -270.523462)
		(mid 390.094724 -270.599639)
		(end 389.811768 -270.523462)
		(width 0.0889)
		(layer "In11.Cu")
		(net "M_L_CPU0_SB_CB<7>")
	)
	(arc
		(start 392.258042 -270.523462)
		(mid 391.980975 -270.599733)
		(end 391.70229 -270.529558)
		(width 0.0889)
		(layer "In11.Cu")
		(net "M_L_CPU0_SB_CB<7>")
	)
	(arc
		(start 390.74344 -270.518636)
		(mid 390.559932 -270.473142)
		(end 390.37768 -270.523462)
		(width 0.0889)
		(layer "In11.Cu")
		(net "M_L_CPU0_SB_CB<7>")
	)
	(arc
		(start 393.783312 -269.624556)
		(mid 393.457689 -269.784896)
		(end 393.10183 -269.713456)
		(width 0.0889)
		(layer "In11.Cu")
		(net "M_L_CPU0_SB_CB<7>")
	)
	(arc
		(start 386.983478 -270.518636)
		(mid 386.79997 -270.473142)
		(end 386.617718 -270.523462)
		(width 0.0889)
		(layer "In11.Cu")
		(net "M_L_CPU0_SB_CB<7>")
	)
	(arc
		(start 391.691876 -270.523462)
		(mid 391.509625 -270.473112)
		(end 391.326116 -270.518636)
		(width 0.0889)
		(layer "In11.Cu")
		(net "M_L_CPU0_SB_CB<7>")
	)
	(arc
		(start 391.317734 -270.523462)
		(mid 391.034778 -270.599639)
		(end 390.751822 -270.523462)
		(width 0.0889)
		(layer "In11.Cu")
		(net "M_L_CPU0_SB_CB<7>")
	)
	(segment
		(start 386.807964 -269.770098)
		(end 387.274816 -270.036036)
		(width 0.10668)
		(layer "F.Cu")
		(net "M_L_CPU0_SB_CB<6>")
	)
	(segment
		(start 413.738314 -272.949416)
		(end 413.593534 -272.804636)
		(width 0.14478)
		(layer "In11.Cu")
		(net "M_L_CPU0_SB_CB<6>")
	)
	(segment
		(start 415.247836 -272.315432)
		(end 415.247836 -272.804636)
		(width 0.14478)
		(layer "In11.Cu")
		(net "M_L_CPU0_SB_CB<6>")
	)
	(segment
		(start 417.164012 -272.415254)
		(end 417.019232 -272.560034)
		(width 0.14478)
		(layer "In11.Cu")
		(net "M_L_CPU0_SB_CB<6>")
	)
	(segment
		(start 443.032896 -271.71015)
		(end 437.66486 -271.71015)
		(width 0.14478)
		(layer "In11.Cu")
		(net "M_L_CPU0_SB_CB<6>")
	)
	(segment
		(start 426.451268 -272.560034)
		(end 425.601384 -271.71015)
		(width 0.14478)
		(layer "In11.Cu")
		(net "M_L_CPU0_SB_CB<6>")
	)
	(segment
		(start 413.593534 -272.315432)
		(end 413.448754 -272.170652)
		(width 0.14478)
		(layer "In11.Cu")
		(net "M_L_CPU0_SB_CB<6>")
	)
	(segment
		(start 445.383412 -271.461992)
		(end 445.383412 -271.958308)
		(width 0.14478)
		(layer "In11.Cu")
		(net "M_L_CPU0_SB_CB<6>")
	)
	(segment
		(start 415.94405 -272.560034)
		(end 415.79927 -272.415254)
		(width 0.14478)
		(layer "In11.Cu")
		(net "M_L_CPU0_SB_CB<6>")
	)
	(segment
		(start 443.177676 -271.56537)
		(end 443.032896 -271.71015)
		(width 0.14478)
		(layer "In11.Cu")
		(net "M_L_CPU0_SB_CB<6>")
	)
	(segment
		(start 417.570666 -272.180812)
		(end 417.308792 -272.180812)
		(width 0.14478)
		(layer "In11.Cu")
		(net "M_L_CPU0_SB_CB<6>")
	)
	(segment
		(start 417.308792 -272.180812)
		(end 417.164012 -272.325592)
		(width 0.14478)
		(layer "In11.Cu")
		(net "M_L_CPU0_SB_CB<6>")
	)
	(segment
		(start 444.831978 -271.461992)
		(end 444.687198 -271.317212)
		(width 0.14478)
		(layer "In11.Cu")
		(net "M_L_CPU0_SB_CB<6>")
	)
	(segment
		(start 394.716 -267.77061)
		(end 393.633706 -268.852904)
		(width 0.0889)
		(layer "In11.Cu")
		(net "M_L_CPU0_SB_CB<6>")
	)
	(segment
		(start 414.144968 -272.315432)
		(end 414.144968 -272.804636)
		(width 0.14478)
		(layer "In11.Cu")
		(net "M_L_CPU0_SB_CB<6>")
	)
	(segment
		(start 445.934846 -271.461992)
		(end 445.790066 -271.317212)
		(width 0.14478)
		(layer "In11.Cu")
		(net "M_L_CPU0_SB_CB<6>")
	)
	(segment
		(start 443.72911 -271.461992)
		(end 443.58433 -271.317212)
		(width 0.14478)
		(layer "In11.Cu")
		(net "M_L_CPU0_SB_CB<6>")
	)
	(segment
		(start 436.814976 -272.560034)
		(end 433.995322 -272.560034)
		(width 0.14478)
		(layer "In11.Cu")
		(net "M_L_CPU0_SB_CB<6>")
	)
	(segment
		(start 392.26617 -268.898624)
		(end 392.257788 -268.90345)
		(width 0.0889)
		(layer "In11.Cu")
		(net "M_L_CPU0_SB_CB<6>")
	)
	(segment
		(start 418.26688 -272.794476)
		(end 418.1221 -272.939256)
		(width 0.14478)
		(layer "In11.Cu")
		(net "M_L_CPU0_SB_CB<6>")
	)
	(segment
		(start 414.000188 -272.949416)
		(end 413.738314 -272.949416)
		(width 0.14478)
		(layer "In11.Cu")
		(net "M_L_CPU0_SB_CB<6>")
	)
	(segment
		(start 418.1221 -272.939256)
		(end 417.860226 -272.939256)
		(width 0.14478)
		(layer "In11.Cu")
		(net "M_L_CPU0_SB_CB<6>")
	)
	(segment
		(start 418.26688 -272.325592)
		(end 418.26688 -272.794476)
		(width 0.14478)
		(layer "In11.Cu")
		(net "M_L_CPU0_SB_CB<6>")
	)
	(segment
		(start 443.58433 -271.317212)
		(end 443.322456 -271.317212)
		(width 0.14478)
		(layer "In11.Cu")
		(net "M_L_CPU0_SB_CB<6>")
	)
	(segment
		(start 412.89732 -272.560034)
		(end 411.09138 -272.560034)
		(width 0.14478)
		(layer "In11.Cu")
		(net "M_L_CPU0_SB_CB<6>")
	)
	(segment
		(start 444.831978 -271.958308)
		(end 444.831978 -271.461992)
		(width 0.14478)
		(layer "In11.Cu")
		(net "M_L_CPU0_SB_CB<6>")
	)
	(segment
		(start 418.673534 -272.180812)
		(end 418.41166 -272.180812)
		(width 0.14478)
		(layer "In11.Cu")
		(net "M_L_CPU0_SB_CB<6>")
	)
	(segment
		(start 417.715446 -272.325592)
		(end 417.570666 -272.180812)
		(width 0.14478)
		(layer "In11.Cu")
		(net "M_L_CPU0_SB_CB<6>")
	)
	(segment
		(start 444.425324 -271.317212)
		(end 444.280544 -271.461992)
		(width 0.14478)
		(layer "In11.Cu")
		(net "M_L_CPU0_SB_CB<6>")
	)
	(segment
		(start 450.088 -272.984976)
		(end 448.813174 -271.71015)
		(width 0.14478)
		(layer "In11.Cu")
		(net "M_L_CPU0_SB_CB<6>")
	)
	(segment
		(start 445.238632 -272.103088)
		(end 444.976758 -272.103088)
		(width 0.14478)
		(layer "In11.Cu")
		(net "M_L_CPU0_SB_CB<6>")
	)
	(segment
		(start 387.42874 -269.770606)
		(end 387.274816 -270.036036)
		(width 0.0889)
		(layer "In11.Cu")
		(net "M_L_CPU0_SB_CB<6>")
	)
	(segment
		(start 443.72911 -271.958308)
		(end 443.72911 -271.461992)
		(width 0.14478)
		(layer "In11.Cu")
		(net "M_L_CPU0_SB_CB<6>")
	)
	(segment
		(start 446.079626 -271.71015)
		(end 445.934846 -271.56537)
		(width 0.14478)
		(layer "In11.Cu")
		(net "M_L_CPU0_SB_CB<6>")
	)
	(segment
		(start 411.09138 -272.560034)
		(end 406.301956 -267.77061)
		(width 0.14478)
		(layer "In11.Cu")
		(net "M_L_CPU0_SB_CB<6>")
	)
	(segment
		(start 414.841182 -272.949416)
		(end 414.696402 -272.804636)
		(width 0.14478)
		(layer "In11.Cu")
		(net "M_L_CPU0_SB_CB<6>")
	)
	(segment
		(start 413.593534 -272.804636)
		(end 413.593534 -272.315432)
		(width 0.14478)
		(layer "In11.Cu")
		(net "M_L_CPU0_SB_CB<6>")
	)
	(segment
		(start 387.524752 -269.745206)
		(end 387.42874 -269.770606)
		(width 0.0889)
		(layer "In11.Cu")
		(net "M_L_CPU0_SB_CB<6>")
	)
	(segment
		(start 418.818314 -272.325592)
		(end 418.673534 -272.180812)
		(width 0.14478)
		(layer "In11.Cu")
		(net "M_L_CPU0_SB_CB<6>")
	)
	(segment
		(start 414.289748 -272.170652)
		(end 414.144968 -272.315432)
		(width 0.14478)
		(layer "In11.Cu")
		(net "M_L_CPU0_SB_CB<6>")
	)
	(segment
		(start 392.257788 -268.90345)
		(end 392.226038 -268.921738)
		(width 0.0889)
		(layer "In11.Cu")
		(net "M_L_CPU0_SB_CB<6>")
	)
	(segment
		(start 445.383412 -271.958308)
		(end 445.238632 -272.103088)
		(width 0.14478)
		(layer "In11.Cu")
		(net "M_L_CPU0_SB_CB<6>")
	)
	(segment
		(start 443.177676 -271.461992)
		(end 443.177676 -271.56537)
		(width 0.14478)
		(layer "In11.Cu")
		(net "M_L_CPU0_SB_CB<6>")
	)
	(segment
		(start 413.0421 -272.315432)
		(end 413.0421 -272.415254)
		(width 0.14478)
		(layer "In11.Cu")
		(net "M_L_CPU0_SB_CB<6>")
	)
	(segment
		(start 425.601384 -271.71015)
		(end 422.576752 -271.71015)
		(width 0.14478)
		(layer "In11.Cu")
		(net "M_L_CPU0_SB_CB<6>")
	)
	(segment
		(start 389.916162 -269.70863)
		(end 389.90778 -269.713456)
		(width 0.0889)
		(layer "In11.Cu")
		(net "M_L_CPU0_SB_CB<6>")
	)
	(segment
		(start 421.726868 -272.560034)
		(end 418.963094 -272.560034)
		(width 0.14478)
		(layer "In11.Cu")
		(net "M_L_CPU0_SB_CB<6>")
	)
	(segment
		(start 433.145438 -271.71015)
		(end 430.120806 -271.71015)
		(width 0.14478)
		(layer "In11.Cu")
		(net "M_L_CPU0_SB_CB<6>")
	)
	(segment
		(start 430.120806 -271.71015)
		(end 429.270922 -272.560034)
		(width 0.14478)
		(layer "In11.Cu")
		(net "M_L_CPU0_SB_CB<6>")
	)
	(segment
		(start 415.65449 -272.170652)
		(end 415.392616 -272.170652)
		(width 0.14478)
		(layer "In11.Cu")
		(net "M_L_CPU0_SB_CB<6>")
	)
	(segment
		(start 388.401814 -269.713456)
		(end 388.393432 -269.70863)
		(width 0.0889)
		(layer "In11.Cu")
		(net "M_L_CPU0_SB_CB<6>")
	)
	(segment
		(start 413.18688 -272.170652)
		(end 413.0421 -272.315432)
		(width 0.14478)
		(layer "In11.Cu")
		(net "M_L_CPU0_SB_CB<6>")
	)
	(segment
		(start 444.280544 -271.958308)
		(end 444.135764 -272.103088)
		(width 0.14478)
		(layer "In11.Cu")
		(net "M_L_CPU0_SB_CB<6>")
	)
	(segment
		(start 406.301956 -267.77061)
		(end 395.996922 -267.77061)
		(width 0.14478)
		(layer "In11.Cu")
		(net "M_L_CPU0_SB_CB<6>")
	)
	(segment
		(start 445.790066 -271.317212)
		(end 445.528192 -271.317212)
		(width 0.14478)
		(layer "In11.Cu")
		(net "M_L_CPU0_SB_CB<6>")
	)
	(segment
		(start 417.715446 -272.794476)
		(end 417.715446 -272.325592)
		(width 0.14478)
		(layer "In11.Cu")
		(net "M_L_CPU0_SB_CB<6>")
	)
	(segment
		(start 414.696402 -272.804636)
		(end 414.696402 -272.315432)
		(width 0.14478)
		(layer "In11.Cu")
		(net "M_L_CPU0_SB_CB<6>")
	)
	(segment
		(start 417.019232 -272.560034)
		(end 415.94405 -272.560034)
		(width 0.14478)
		(layer "In11.Cu")
		(net "M_L_CPU0_SB_CB<6>")
	)
	(segment
		(start 413.0421 -272.415254)
		(end 412.89732 -272.560034)
		(width 0.14478)
		(layer "In11.Cu")
		(net "M_L_CPU0_SB_CB<6>")
	)
	(segment
		(start 448.813174 -271.71015)
		(end 446.079626 -271.71015)
		(width 0.14478)
		(layer "In11.Cu")
		(net "M_L_CPU0_SB_CB<6>")
	)
	(segment
		(start 415.392616 -272.170652)
		(end 415.247836 -272.315432)
		(width 0.14478)
		(layer "In11.Cu")
		(net "M_L_CPU0_SB_CB<6>")
	)
	(segment
		(start 444.976758 -272.103088)
		(end 444.831978 -271.958308)
		(width 0.14478)
		(layer "In11.Cu")
		(net "M_L_CPU0_SB_CB<6>")
	)
	(segment
		(start 414.144968 -272.804636)
		(end 414.000188 -272.949416)
		(width 0.14478)
		(layer "In11.Cu")
		(net "M_L_CPU0_SB_CB<6>")
	)
	(segment
		(start 415.247836 -272.804636)
		(end 415.103056 -272.949416)
		(width 0.14478)
		(layer "In11.Cu")
		(net "M_L_CPU0_SB_CB<6>")
	)
	(segment
		(start 443.322456 -271.317212)
		(end 443.177676 -271.461992)
		(width 0.14478)
		(layer "In11.Cu")
		(net "M_L_CPU0_SB_CB<6>")
	)
	(segment
		(start 415.103056 -272.949416)
		(end 414.841182 -272.949416)
		(width 0.14478)
		(layer "In11.Cu")
		(net "M_L_CPU0_SB_CB<6>")
	)
	(segment
		(start 445.934846 -271.56537)
		(end 445.934846 -271.461992)
		(width 0.14478)
		(layer "In11.Cu")
		(net "M_L_CPU0_SB_CB<6>")
	)
	(segment
		(start 444.135764 -272.103088)
		(end 443.87389 -272.103088)
		(width 0.14478)
		(layer "In11.Cu")
		(net "M_L_CPU0_SB_CB<6>")
	)
	(segment
		(start 393.633706 -268.852904)
		(end 393.384786 -268.852904)
		(width 0.0889)
		(layer "In11.Cu")
		(net "M_L_CPU0_SB_CB<6>")
	)
	(segment
		(start 413.448754 -272.170652)
		(end 413.18688 -272.170652)
		(width 0.14478)
		(layer "In11.Cu")
		(net "M_L_CPU0_SB_CB<6>")
	)
	(segment
		(start 422.576752 -271.71015)
		(end 421.726868 -272.560034)
		(width 0.14478)
		(layer "In11.Cu")
		(net "M_L_CPU0_SB_CB<6>")
	)
	(segment
		(start 414.696402 -272.315432)
		(end 414.551622 -272.170652)
		(width 0.14478)
		(layer "In11.Cu")
		(net "M_L_CPU0_SB_CB<6>")
	)
	(segment
		(start 429.270922 -272.560034)
		(end 426.451268 -272.560034)
		(width 0.14478)
		(layer "In11.Cu")
		(net "M_L_CPU0_SB_CB<6>")
	)
	(segment
		(start 444.280544 -271.461992)
		(end 444.280544 -271.958308)
		(width 0.14478)
		(layer "In11.Cu")
		(net "M_L_CPU0_SB_CB<6>")
	)
	(segment
		(start 418.963094 -272.560034)
		(end 418.818314 -272.415254)
		(width 0.14478)
		(layer "In11.Cu")
		(net "M_L_CPU0_SB_CB<6>")
	)
	(segment
		(start 433.995322 -272.560034)
		(end 433.145438 -271.71015)
		(width 0.14478)
		(layer "In11.Cu")
		(net "M_L_CPU0_SB_CB<6>")
	)
	(segment
		(start 415.79927 -272.315432)
		(end 415.65449 -272.170652)
		(width 0.14478)
		(layer "In11.Cu")
		(net "M_L_CPU0_SB_CB<6>")
	)
	(segment
		(start 391.82675 -269.690596)
		(end 391.787634 -269.713456)
		(width 0.0889)
		(layer "In11.Cu")
		(net "M_L_CPU0_SB_CB<6>")
	)
	(segment
		(start 418.818314 -272.415254)
		(end 418.818314 -272.325592)
		(width 0.14478)
		(layer "In11.Cu")
		(net "M_L_CPU0_SB_CB<6>")
	)
	(segment
		(start 417.860226 -272.939256)
		(end 417.715446 -272.794476)
		(width 0.14478)
		(layer "In11.Cu")
		(net "M_L_CPU0_SB_CB<6>")
	)
	(segment
		(start 414.551622 -272.170652)
		(end 414.289748 -272.170652)
		(width 0.14478)
		(layer "In11.Cu")
		(net "M_L_CPU0_SB_CB<6>")
	)
	(segment
		(start 395.996922 -267.77061)
		(end 394.716 -267.77061)
		(width 0.0889)
		(layer "In11.Cu")
		(net "M_L_CPU0_SB_CB<6>")
	)
	(segment
		(start 437.66486 -271.71015)
		(end 436.814976 -272.560034)
		(width 0.14478)
		(layer "In11.Cu")
		(net "M_L_CPU0_SB_CB<6>")
	)
	(segment
		(start 418.41166 -272.180812)
		(end 418.26688 -272.325592)
		(width 0.14478)
		(layer "In11.Cu")
		(net "M_L_CPU0_SB_CB<6>")
	)
	(segment
		(start 445.528192 -271.317212)
		(end 445.383412 -271.461992)
		(width 0.14478)
		(layer "In11.Cu")
		(net "M_L_CPU0_SB_CB<6>")
	)
	(segment
		(start 444.687198 -271.317212)
		(end 444.425324 -271.317212)
		(width 0.14478)
		(layer "In11.Cu")
		(net "M_L_CPU0_SB_CB<6>")
	)
	(segment
		(start 417.164012 -272.325592)
		(end 417.164012 -272.415254)
		(width 0.14478)
		(layer "In11.Cu")
		(net "M_L_CPU0_SB_CB<6>")
	)
	(segment
		(start 389.341868 -269.713456)
		(end 389.333486 -269.70863)
		(width 0.0889)
		(layer "In11.Cu")
		(net "M_L_CPU0_SB_CB<6>")
	)
	(segment
		(start 415.79927 -272.415254)
		(end 415.79927 -272.315432)
		(width 0.14478)
		(layer "In11.Cu")
		(net "M_L_CPU0_SB_CB<6>")
	)
	(segment
		(start 443.87389 -272.103088)
		(end 443.72911 -271.958308)
		(width 0.14478)
		(layer "In11.Cu")
		(net "M_L_CPU0_SB_CB<6>")
	)
	(arc
		(start 390.281922 -269.713456)
		(mid 390.099671 -269.663106)
		(end 389.916162 -269.70863)
		(width 0.0889)
		(layer "In11.Cu")
		(net "M_L_CPU0_SB_CB<6>")
	)
	(arc
		(start 393.197842 -268.90345)
		(mid 392.914886 -268.979627)
		(end 392.63193 -268.90345)
		(width 0.0889)
		(layer "In11.Cu")
		(net "M_L_CPU0_SB_CB<6>")
	)
	(arc
		(start 388.393432 -269.70863)
		(mid 388.209924 -269.663136)
		(end 388.027672 -269.713456)
		(width 0.0889)
		(layer "In11.Cu")
		(net "M_L_CPU0_SB_CB<6>")
	)
	(arc
		(start 392.226038 -268.921738)
		(mid 392.111362 -269.055072)
		(end 392.070082 -269.22603)
		(width 0.0889)
		(layer "In11.Cu")
		(net "M_L_CPU0_SB_CB<6>")
	)
	(arc
		(start 389.333486 -269.70863)
		(mid 389.149978 -269.663136)
		(end 388.967726 -269.713456)
		(width 0.0889)
		(layer "In11.Cu")
		(net "M_L_CPU0_SB_CB<6>")
	)
	(arc
		(start 391.787634 -269.713456)
		(mid 391.504678 -269.789633)
		(end 391.221722 -269.713456)
		(width 0.0889)
		(layer "In11.Cu")
		(net "M_L_CPU0_SB_CB<6>")
	)
	(arc
		(start 391.221722 -269.713456)
		(mid 391.034778 -269.663201)
		(end 390.847834 -269.713456)
		(width 0.0889)
		(layer "In11.Cu")
		(net "M_L_CPU0_SB_CB<6>")
	)
	(arc
		(start 388.967726 -269.713456)
		(mid 388.68477 -269.789633)
		(end 388.401814 -269.713456)
		(width 0.0889)
		(layer "In11.Cu")
		(net "M_L_CPU0_SB_CB<6>")
	)
	(arc
		(start 388.027672 -269.713456)
		(mid 387.779959 -269.788676)
		(end 387.524752 -269.745206)
		(width 0.0889)
		(layer "In11.Cu")
		(net "M_L_CPU0_SB_CB<6>")
	)
	(arc
		(start 392.63193 -268.90345)
		(mid 392.449679 -268.8531)
		(end 392.26617 -268.898624)
		(width 0.0889)
		(layer "In11.Cu")
		(net "M_L_CPU0_SB_CB<6>")
	)
	(arc
		(start 390.847834 -269.713456)
		(mid 390.564878 -269.789633)
		(end 390.281922 -269.713456)
		(width 0.0889)
		(layer "In11.Cu")
		(net "M_L_CPU0_SB_CB<6>")
	)
	(arc
		(start 392.070082 -269.22603)
		(mid 392.005567 -269.488249)
		(end 391.82675 -269.690596)
		(width 0.0889)
		(layer "In11.Cu")
		(net "M_L_CPU0_SB_CB<6>")
	)
	(arc
		(start 389.90778 -269.713456)
		(mid 389.624824 -269.789633)
		(end 389.341868 -269.713456)
		(width 0.0889)
		(layer "In11.Cu")
		(net "M_L_CPU0_SB_CB<6>")
	)
	(arc
		(start 393.384786 -268.852904)
		(mid 393.287975 -268.865828)
		(end 393.197842 -268.90345)
		(width 0.0889)
		(layer "In11.Cu")
		(net "M_L_CPU0_SB_CB<6>")
	)
	(segment
		(start 385.86791 -269.770098)
		(end 386.334762 -270.036036)
		(width 0.10668)
		(layer "F.Cu")
		(net "M_L_CPU0_SB_CB<5>")
	)
	(segment
		(start 425.666408 -272.560034)
		(end 422.484042 -272.560034)
		(width 0.14478)
		(layer "In11.Cu")
		(net "M_L_CPU0_SB_CB<5>")
	)
	(segment
		(start 395.980412 -268.22527)
		(end 395.53896 -268.22527)
		(width 0.0889)
		(layer "In11.Cu")
		(net "M_L_CPU0_SB_CB<5>")
	)
	(segment
		(start 429.177958 -273.410172)
		(end 426.516546 -273.410172)
		(width 0.14478)
		(layer "In11.Cu")
		(net "M_L_CPU0_SB_CB<5>")
	)
	(segment
		(start 449.869814 -273.410172)
		(end 449.019676 -272.560034)
		(width 0.14478)
		(layer "In11.Cu")
		(net "M_L_CPU0_SB_CB<5>")
	)
	(segment
		(start 392.161776 -270.358616)
		(end 392.16203 -270.358616)
		(width 0.0889)
		(layer "In11.Cu")
		(net "M_L_CPU0_SB_CB<5>")
	)
	(segment
		(start 452.398638 -274.073112)
		(end 452.136764 -274.073112)
		(width 0.14478)
		(layer "In11.Cu")
		(net "M_L_CPU0_SB_CB<5>")
	)
	(segment
		(start 388.401814 -270.358616)
		(end 388.393432 -270.363442)
		(width 0.0889)
		(layer "In11.Cu")
		(net "M_L_CPU0_SB_CB<5>")
	)
	(segment
		(start 430.028096 -272.560034)
		(end 429.177958 -273.410172)
		(width 0.14478)
		(layer "In11.Cu")
		(net "M_L_CPU0_SB_CB<5>")
	)
	(segment
		(start 386.20319 -270.384778)
		(end 386.180838 -270.301466)
		(width 0.0889)
		(layer "In11.Cu")
		(net "M_L_CPU0_SB_CB<5>")
	)
	(segment
		(start 406.11552 -268.22527)
		(end 395.980412 -268.22527)
		(width 0.14478)
		(layer "In11.Cu")
		(net "M_L_CPU0_SB_CB<5>")
	)
	(segment
		(start 386.180838 -270.301466)
		(end 386.334762 -270.036036)
		(width 0.0889)
		(layer "In11.Cu")
		(net "M_L_CPU0_SB_CB<5>")
	)
	(segment
		(start 437.57215 -272.560034)
		(end 436.722012 -273.410172)
		(width 0.14478)
		(layer "In11.Cu")
		(net "M_L_CPU0_SB_CB<5>")
	)
	(segment
		(start 449.019676 -272.560034)
		(end 437.57215 -272.560034)
		(width 0.14478)
		(layer "In11.Cu")
		(net "M_L_CPU0_SB_CB<5>")
	)
	(segment
		(start 452.688198 -273.410172)
		(end 452.543418 -273.554952)
		(width 0.14478)
		(layer "In11.Cu")
		(net "M_L_CPU0_SB_CB<5>")
	)
	(segment
		(start 395.53896 -268.22527)
		(end 395.180058 -268.584172)
		(width 0.0889)
		(layer "In11.Cu")
		(net "M_L_CPU0_SB_CB<5>")
	)
	(segment
		(start 452.543418 -273.554952)
		(end 452.543418 -273.928332)
		(width 0.14478)
		(layer "In11.Cu")
		(net "M_L_CPU0_SB_CB<5>")
	)
	(segment
		(start 426.516546 -273.410172)
		(end 425.666408 -272.560034)
		(width 0.14478)
		(layer "In11.Cu")
		(net "M_L_CPU0_SB_CB<5>")
	)
	(segment
		(start 422.484042 -272.560034)
		(end 421.633904 -273.410172)
		(width 0.14478)
		(layer "In11.Cu")
		(net "M_L_CPU0_SB_CB<5>")
	)
	(segment
		(start 454.188068 -273.835114)
		(end 453.763126 -273.410172)
		(width 0.14478)
		(layer "In11.Cu")
		(net "M_L_CPU0_SB_CB<5>")
	)
	(segment
		(start 452.136764 -274.073112)
		(end 451.991984 -273.928332)
		(width 0.14478)
		(layer "In11.Cu")
		(net "M_L_CPU0_SB_CB<5>")
	)
	(segment
		(start 411.300422 -273.410172)
		(end 406.11552 -268.22527)
		(width 0.14478)
		(layer "In11.Cu")
		(net "M_L_CPU0_SB_CB<5>")
	)
	(segment
		(start 434.0606 -273.410172)
		(end 433.210462 -272.560034)
		(width 0.14478)
		(layer "In11.Cu")
		(net "M_L_CPU0_SB_CB<5>")
	)
	(segment
		(start 452.543418 -273.928332)
		(end 452.398638 -274.073112)
		(width 0.14478)
		(layer "In11.Cu")
		(net "M_L_CPU0_SB_CB<5>")
	)
	(segment
		(start 392.63193 -269.54861)
		(end 392.592814 -269.57147)
		(width 0.0889)
		(layer "In11.Cu")
		(net "M_L_CPU0_SB_CB<5>")
	)
	(segment
		(start 451.991984 -273.554952)
		(end 451.847204 -273.410172)
		(width 0.14478)
		(layer "In11.Cu")
		(net "M_L_CPU0_SB_CB<5>")
	)
	(segment
		(start 436.722012 -273.410172)
		(end 434.0606 -273.410172)
		(width 0.14478)
		(layer "In11.Cu")
		(net "M_L_CPU0_SB_CB<5>")
	)
	(segment
		(start 389.916162 -270.363442)
		(end 389.90778 -270.358616)
		(width 0.0889)
		(layer "In11.Cu")
		(net "M_L_CPU0_SB_CB<5>")
	)
	(segment
		(start 394.554202 -268.584172)
		(end 393.648438 -269.489682)
		(width 0.0889)
		(layer "In11.Cu")
		(net "M_L_CPU0_SB_CB<5>")
	)
	(segment
		(start 433.210462 -272.560034)
		(end 430.028096 -272.560034)
		(width 0.14478)
		(layer "In11.Cu")
		(net "M_L_CPU0_SB_CB<5>")
	)
	(segment
		(start 451.847204 -273.410172)
		(end 449.869814 -273.410172)
		(width 0.14478)
		(layer "In11.Cu")
		(net "M_L_CPU0_SB_CB<5>")
	)
	(segment
		(start 395.180058 -268.584172)
		(end 394.554202 -268.584172)
		(width 0.0889)
		(layer "In11.Cu")
		(net "M_L_CPU0_SB_CB<5>")
	)
	(segment
		(start 453.763126 -273.410172)
		(end 452.688198 -273.410172)
		(width 0.14478)
		(layer "In11.Cu")
		(net "M_L_CPU0_SB_CB<5>")
	)
	(segment
		(start 392.193526 -270.340328)
		(end 392.161776 -270.358616)
		(width 0.0889)
		(layer "In11.Cu")
		(net "M_L_CPU0_SB_CB<5>")
	)
	(segment
		(start 421.633904 -273.410172)
		(end 411.300422 -273.410172)
		(width 0.14478)
		(layer "In11.Cu")
		(net "M_L_CPU0_SB_CB<5>")
	)
	(segment
		(start 393.206224 -269.553436)
		(end 393.197842 -269.54861)
		(width 0.0889)
		(layer "In11.Cu")
		(net "M_L_CPU0_SB_CB<5>")
	)
	(segment
		(start 451.991984 -273.928332)
		(end 451.991984 -273.554952)
		(width 0.14478)
		(layer "In11.Cu")
		(net "M_L_CPU0_SB_CB<5>")
	)
	(segment
		(start 389.341868 -270.358616)
		(end 389.333486 -270.363442)
		(width 0.0889)
		(layer "In11.Cu")
		(net "M_L_CPU0_SB_CB<5>")
	)
	(arc
		(start 391.787634 -270.358616)
		(mid 391.504678 -270.282439)
		(end 391.221722 -270.358616)
		(width 0.0889)
		(layer "In11.Cu")
		(net "M_L_CPU0_SB_CB<5>")
	)
	(arc
		(start 392.349482 -270.036036)
		(mid 392.308227 -270.207007)
		(end 392.193526 -270.340328)
		(width 0.0889)
		(layer "In11.Cu")
		(net "M_L_CPU0_SB_CB<5>")
	)
	(arc
		(start 390.281922 -270.358616)
		(mid 390.099671 -270.408966)
		(end 389.916162 -270.363442)
		(width 0.0889)
		(layer "In11.Cu")
		(net "M_L_CPU0_SB_CB<5>")
	)
	(arc
		(start 389.90778 -270.358616)
		(mid 389.624824 -270.282439)
		(end 389.341868 -270.358616)
		(width 0.0889)
		(layer "In11.Cu")
		(net "M_L_CPU0_SB_CB<5>")
	)
	(arc
		(start 393.197842 -269.54861)
		(mid 392.914886 -269.472433)
		(end 392.63193 -269.54861)
		(width 0.0889)
		(layer "In11.Cu")
		(net "M_L_CPU0_SB_CB<5>")
	)
	(arc
		(start 390.847834 -270.358616)
		(mid 390.564878 -270.282439)
		(end 390.281922 -270.358616)
		(width 0.0889)
		(layer "In11.Cu")
		(net "M_L_CPU0_SB_CB<5>")
	)
	(arc
		(start 388.027672 -270.358616)
		(mid 387.744716 -270.282439)
		(end 387.46176 -270.358616)
		(width 0.0889)
		(layer "In11.Cu")
		(net "M_L_CPU0_SB_CB<5>")
	)
	(arc
		(start 387.087872 -270.358616)
		(mid 386.804916 -270.282439)
		(end 386.52196 -270.358616)
		(width 0.0889)
		(layer "In11.Cu")
		(net "M_L_CPU0_SB_CB<5>")
	)
	(arc
		(start 387.46176 -270.358616)
		(mid 387.274816 -270.408871)
		(end 387.087872 -270.358616)
		(width 0.0889)
		(layer "In11.Cu")
		(net "M_L_CPU0_SB_CB<5>")
	)
	(arc
		(start 388.393432 -270.363442)
		(mid 388.209924 -270.408936)
		(end 388.027672 -270.358616)
		(width 0.0889)
		(layer "In11.Cu")
		(net "M_L_CPU0_SB_CB<5>")
	)
	(arc
		(start 389.333486 -270.363442)
		(mid 389.149978 -270.408936)
		(end 388.967726 -270.358616)
		(width 0.0889)
		(layer "In11.Cu")
		(net "M_L_CPU0_SB_CB<5>")
	)
	(arc
		(start 386.52196 -270.358616)
		(mid 386.365522 -270.407587)
		(end 386.20319 -270.384778)
		(width 0.0889)
		(layer "In11.Cu")
		(net "M_L_CPU0_SB_CB<5>")
	)
	(arc
		(start 392.592814 -269.57147)
		(mid 392.414001 -269.77382)
		(end 392.349482 -270.036036)
		(width 0.0889)
		(layer "In11.Cu")
		(net "M_L_CPU0_SB_CB<5>")
	)
	(arc
		(start 392.16203 -270.358616)
		(mid 391.974832 -270.408998)
		(end 391.787634 -270.358616)
		(width 0.0889)
		(layer "In11.Cu")
		(net "M_L_CPU0_SB_CB<5>")
	)
	(arc
		(start 388.967726 -270.358616)
		(mid 388.68477 -270.282439)
		(end 388.401814 -270.358616)
		(width 0.0889)
		(layer "In11.Cu")
		(net "M_L_CPU0_SB_CB<5>")
	)
	(arc
		(start 393.648438 -269.489682)
		(mid 393.612123 -269.521626)
		(end 393.571984 -269.54861)
		(width 0.0889)
		(layer "In11.Cu")
		(net "M_L_CPU0_SB_CB<5>")
	)
	(arc
		(start 391.221722 -270.358616)
		(mid 391.034778 -270.408871)
		(end 390.847834 -270.358616)
		(width 0.0889)
		(layer "In11.Cu")
		(net "M_L_CPU0_SB_CB<5>")
	)
	(arc
		(start 393.571984 -269.54861)
		(mid 393.389733 -269.59896)
		(end 393.206224 -269.553436)
		(width 0.0889)
		(layer "In11.Cu")
		(net "M_L_CPU0_SB_CB<5>")
	)
	(segment
		(start 387.277864 -268.960092)
		(end 387.744716 -269.22603)
		(width 0.10668)
		(layer "F.Cu")
		(net "M_L_CPU0_SB_CB<4>")
	)
	(segment
		(start 409.714446 -270.53032)
		(end 409.714446 -270.325596)
		(width 0.14478)
		(layer "In11.Cu")
		(net "M_L_CPU0_SB_CB<4>")
	)
	(segment
		(start 421.851836 -271.709896)
		(end 421.633904 -271.709896)
		(width 0.14478)
		(layer "In11.Cu")
		(net "M_L_CPU0_SB_CB<4>")
	)
	(segment
		(start 409.714446 -270.325596)
		(end 409.75788 -270.282162)
		(width 0.14478)
		(layer "In11.Cu")
		(net "M_L_CPU0_SB_CB<4>")
	)
	(segment
		(start 407.417016 -267.736574)
		(end 406.996392 -267.31595)
		(width 0.14478)
		(layer "In11.Cu")
		(net "M_L_CPU0_SB_CB<4>")
	)
	(segment
		(start 408.011884 -268.331442)
		(end 407.80716 -268.331442)
		(width 0.14478)
		(layer "In11.Cu")
		(net "M_L_CPU0_SB_CB<4>")
	)
	(segment
		(start 410.148024 -270.672306)
		(end 410.10459 -270.71574)
		(width 0.14478)
		(layer "In11.Cu")
		(net "M_L_CPU0_SB_CB<4>")
	)
	(segment
		(start 406.996392 -267.31595)
		(end 395.97457 -267.31595)
		(width 0.14478)
		(layer "In11.Cu")
		(net "M_L_CPU0_SB_CB<4>")
	)
	(segment
		(start 409.75788 -270.077438)
		(end 409.57246 -269.892018)
		(width 0.14478)
		(layer "In11.Cu")
		(net "M_L_CPU0_SB_CB<4>")
	)
	(segment
		(start 407.763726 -268.374876)
		(end 407.559002 -268.374876)
		(width 0.14478)
		(layer "In11.Cu")
		(net "M_L_CPU0_SB_CB<4>")
	)
	(segment
		(start 391.722356 -269.53083)
		(end 391.691876 -269.54861)
		(width 0.0889)
		(layer "In11.Cu")
		(net "M_L_CPU0_SB_CB<4>")
	)
	(segment
		(start 408.197304 -268.516862)
		(end 408.011884 -268.331442)
		(width 0.14478)
		(layer "In11.Cu")
		(net "M_L_CPU0_SB_CB<4>")
	)
	(segment
		(start 408.934158 -269.750032)
		(end 408.934158 -269.545308)
		(width 0.14478)
		(layer "In11.Cu")
		(net "M_L_CPU0_SB_CB<4>")
	)
	(segment
		(start 451.56628 -270.860012)
		(end 437.78678 -270.860012)
		(width 0.14478)
		(layer "In11.Cu")
		(net "M_L_CPU0_SB_CB<4>")
	)
	(segment
		(start 408.33929 -269.155164)
		(end 408.15387 -268.969744)
		(width 0.14478)
		(layer "In11.Cu")
		(net "M_L_CPU0_SB_CB<4>")
	)
	(segment
		(start 422.70172 -270.860012)
		(end 421.851836 -271.709896)
		(width 0.14478)
		(layer "In11.Cu")
		(net "M_L_CPU0_SB_CB<4>")
	)
	(segment
		(start 408.544014 -269.155164)
		(end 408.33929 -269.155164)
		(width 0.14478)
		(layer "In11.Cu")
		(net "M_L_CPU0_SB_CB<4>")
	)
	(segment
		(start 408.792172 -269.11173)
		(end 408.587448 -269.11173)
		(width 0.14478)
		(layer "In11.Cu")
		(net "M_L_CPU0_SB_CB<4>")
	)
	(segment
		(start 409.75788 -270.282162)
		(end 409.75788 -270.077438)
		(width 0.14478)
		(layer "In11.Cu")
		(net "M_L_CPU0_SB_CB<4>")
	)
	(segment
		(start 390.751822 -269.54861)
		(end 390.74344 -269.553436)
		(width 0.0889)
		(layer "In11.Cu")
		(net "M_L_CPU0_SB_CB<4>")
	)
	(segment
		(start 407.559002 -268.374876)
		(end 407.373582 -268.189456)
		(width 0.14478)
		(layer "In11.Cu")
		(net "M_L_CPU0_SB_CB<4>")
	)
	(segment
		(start 452.262494 -271.383252)
		(end 452.117714 -271.528032)
		(width 0.14478)
		(layer "In11.Cu")
		(net "M_L_CPU0_SB_CB<4>")
	)
	(segment
		(start 421.63365 -271.71015)
		(end 410.894276 -271.71015)
		(width 0.14478)
		(layer "In11.Cu")
		(net "M_L_CPU0_SB_CB<4>")
	)
	(segment
		(start 395.97457 -267.31595)
		(end 394.814806 -267.31595)
		(width 0.0889)
		(layer "In11.Cu")
		(net "M_L_CPU0_SB_CB<4>")
	)
	(segment
		(start 387.613144 -269.574772)
		(end 387.590792 -269.49146)
		(width 0.0889)
		(layer "In11.Cu")
		(net "M_L_CPU0_SB_CB<4>")
	)
	(segment
		(start 451.71106 -271.004792)
		(end 451.56628 -270.860012)
		(width 0.14478)
		(layer "In11.Cu")
		(net "M_L_CPU0_SB_CB<4>")
	)
	(segment
		(start 408.977592 -269.501874)
		(end 408.977592 -269.29715)
		(width 0.14478)
		(layer "In11.Cu")
		(net "M_L_CPU0_SB_CB<4>")
	)
	(segment
		(start 393.10183 -268.738604)
		(end 393.093448 -268.74343)
		(width 0.0889)
		(layer "In11.Cu")
		(net "M_L_CPU0_SB_CB<4>")
	)
	(segment
		(start 410.894276 -271.71015)
		(end 410.494734 -271.310608)
		(width 0.14478)
		(layer "In11.Cu")
		(net "M_L_CPU0_SB_CB<4>")
	)
	(segment
		(start 407.373582 -268.189456)
		(end 407.373582 -267.984732)
		(width 0.14478)
		(layer "In11.Cu")
		(net "M_L_CPU0_SB_CB<4>")
	)
	(segment
		(start 451.85584 -271.528032)
		(end 451.71106 -271.383252)
		(width 0.14478)
		(layer "In11.Cu")
		(net "M_L_CPU0_SB_CB<4>")
	)
	(segment
		(start 421.633904 -271.709896)
		(end 421.63365 -271.71015)
		(width 0.14478)
		(layer "In11.Cu")
		(net "M_L_CPU0_SB_CB<4>")
	)
	(segment
		(start 429.385222 -271.709896)
		(end 426.298868 -271.709896)
		(width 0.14478)
		(layer "In11.Cu")
		(net "M_L_CPU0_SB_CB<4>")
	)
	(segment
		(start 432.99507 -270.860012)
		(end 430.235106 -270.860012)
		(width 0.14478)
		(layer "In11.Cu")
		(net "M_L_CPU0_SB_CB<4>")
	)
	(segment
		(start 408.15387 -268.969744)
		(end 408.15387 -268.76502)
		(width 0.14478)
		(layer "In11.Cu")
		(net "M_L_CPU0_SB_CB<4>")
	)
	(segment
		(start 454.188068 -272.135092)
		(end 452.912988 -270.860012)
		(width 0.14478)
		(layer "In11.Cu")
		(net "M_L_CPU0_SB_CB<4>")
	)
	(segment
		(start 393.468352 -268.662404)
		(end 393.384532 -268.662404)
		(width 0.0889)
		(layer "In11.Cu")
		(net "M_L_CPU0_SB_CB<4>")
	)
	(segment
		(start 407.417016 -267.941298)
		(end 407.417016 -267.736574)
		(width 0.14478)
		(layer "In11.Cu")
		(net "M_L_CPU0_SB_CB<4>")
	)
	(segment
		(start 410.494734 -271.105884)
		(end 410.538168 -271.06245)
		(width 0.14478)
		(layer "In11.Cu")
		(net "M_L_CPU0_SB_CB<4>")
	)
	(segment
		(start 408.934158 -269.545308)
		(end 408.977592 -269.501874)
		(width 0.14478)
		(layer "In11.Cu")
		(net "M_L_CPU0_SB_CB<4>")
	)
	(segment
		(start 452.407274 -270.860012)
		(end 452.262494 -271.004792)
		(width 0.14478)
		(layer "In11.Cu")
		(net "M_L_CPU0_SB_CB<4>")
	)
	(segment
		(start 410.352748 -270.672306)
		(end 410.148024 -270.672306)
		(width 0.14478)
		(layer "In11.Cu")
		(net "M_L_CPU0_SB_CB<4>")
	)
	(segment
		(start 394.814806 -267.31595)
		(end 393.468352 -268.662404)
		(width 0.0889)
		(layer "In11.Cu")
		(net "M_L_CPU0_SB_CB<4>")
	)
	(segment
		(start 409.119578 -269.935452)
		(end 408.934158 -269.750032)
		(width 0.14478)
		(layer "In11.Cu")
		(net "M_L_CPU0_SB_CB<4>")
	)
	(segment
		(start 407.373582 -267.984732)
		(end 407.417016 -267.941298)
		(width 0.14478)
		(layer "In11.Cu")
		(net "M_L_CPU0_SB_CB<4>")
	)
	(segment
		(start 410.538168 -270.857726)
		(end 410.352748 -270.672306)
		(width 0.14478)
		(layer "In11.Cu")
		(net "M_L_CPU0_SB_CB<4>")
	)
	(segment
		(start 408.15387 -268.76502)
		(end 408.197304 -268.721586)
		(width 0.14478)
		(layer "In11.Cu")
		(net "M_L_CPU0_SB_CB<4>")
	)
	(segment
		(start 392.161776 -268.738604)
		(end 392.12266 -268.761464)
		(width 0.0889)
		(layer "In11.Cu")
		(net "M_L_CPU0_SB_CB<4>")
	)
	(segment
		(start 407.80716 -268.331442)
		(end 407.763726 -268.374876)
		(width 0.14478)
		(layer "In11.Cu")
		(net "M_L_CPU0_SB_CB<4>")
	)
	(segment
		(start 452.262494 -271.004792)
		(end 452.262494 -271.383252)
		(width 0.14478)
		(layer "In11.Cu")
		(net "M_L_CPU0_SB_CB<4>")
	)
	(segment
		(start 410.10459 -270.71574)
		(end 409.899866 -270.71574)
		(width 0.14478)
		(layer "In11.Cu")
		(net "M_L_CPU0_SB_CB<4>")
	)
	(segment
		(start 408.587448 -269.11173)
		(end 408.544014 -269.155164)
		(width 0.14478)
		(layer "In11.Cu")
		(net "M_L_CPU0_SB_CB<4>")
	)
	(segment
		(start 410.538168 -271.06245)
		(end 410.538168 -270.857726)
		(width 0.14478)
		(layer "In11.Cu")
		(net "M_L_CPU0_SB_CB<4>")
	)
	(segment
		(start 387.590792 -269.49146)
		(end 387.744716 -269.22603)
		(width 0.0889)
		(layer "In11.Cu")
		(net "M_L_CPU0_SB_CB<4>")
	)
	(segment
		(start 433.844954 -271.709896)
		(end 432.99507 -270.860012)
		(width 0.14478)
		(layer "In11.Cu")
		(net "M_L_CPU0_SB_CB<4>")
	)
	(segment
		(start 408.197304 -268.721586)
		(end 408.197304 -268.516862)
		(width 0.14478)
		(layer "In11.Cu")
		(net "M_L_CPU0_SB_CB<4>")
	)
	(segment
		(start 436.936896 -271.709896)
		(end 433.844954 -271.709896)
		(width 0.14478)
		(layer "In11.Cu")
		(net "M_L_CPU0_SB_CB<4>")
	)
	(segment
		(start 452.117714 -271.528032)
		(end 451.85584 -271.528032)
		(width 0.14478)
		(layer "In11.Cu")
		(net "M_L_CPU0_SB_CB<4>")
	)
	(segment
		(start 451.71106 -271.383252)
		(end 451.71106 -271.004792)
		(width 0.14478)
		(layer "In11.Cu")
		(net "M_L_CPU0_SB_CB<4>")
	)
	(segment
		(start 452.912988 -270.860012)
		(end 452.407274 -270.860012)
		(width 0.14478)
		(layer "In11.Cu")
		(net "M_L_CPU0_SB_CB<4>")
	)
	(segment
		(start 430.235106 -270.860012)
		(end 429.385222 -271.709896)
		(width 0.14478)
		(layer "In11.Cu")
		(net "M_L_CPU0_SB_CB<4>")
	)
	(segment
		(start 391.326116 -269.553436)
		(end 391.317734 -269.54861)
		(width 0.0889)
		(layer "In11.Cu")
		(net "M_L_CPU0_SB_CB<4>")
	)
	(segment
		(start 426.298868 -271.709896)
		(end 425.448984 -270.860012)
		(width 0.14478)
		(layer "In11.Cu")
		(net "M_L_CPU0_SB_CB<4>")
	)
	(segment
		(start 409.324302 -269.935452)
		(end 409.119578 -269.935452)
		(width 0.14478)
		(layer "In11.Cu")
		(net "M_L_CPU0_SB_CB<4>")
	)
	(segment
		(start 409.57246 -269.892018)
		(end 409.367736 -269.892018)
		(width 0.14478)
		(layer "In11.Cu")
		(net "M_L_CPU0_SB_CB<4>")
	)
	(segment
		(start 409.899866 -270.71574)
		(end 409.714446 -270.53032)
		(width 0.14478)
		(layer "In11.Cu")
		(net "M_L_CPU0_SB_CB<4>")
	)
	(segment
		(start 408.977592 -269.29715)
		(end 408.792172 -269.11173)
		(width 0.14478)
		(layer "In11.Cu")
		(net "M_L_CPU0_SB_CB<4>")
	)
	(segment
		(start 425.448984 -270.860012)
		(end 422.70172 -270.860012)
		(width 0.14478)
		(layer "In11.Cu")
		(net "M_L_CPU0_SB_CB<4>")
	)
	(segment
		(start 410.494734 -271.310608)
		(end 410.494734 -271.105884)
		(width 0.14478)
		(layer "In11.Cu")
		(net "M_L_CPU0_SB_CB<4>")
	)
	(segment
		(start 409.367736 -269.892018)
		(end 409.324302 -269.935452)
		(width 0.14478)
		(layer "In11.Cu")
		(net "M_L_CPU0_SB_CB<4>")
	)
	(segment
		(start 437.78678 -270.860012)
		(end 436.936896 -271.709896)
		(width 0.14478)
		(layer "In11.Cu")
		(net "M_L_CPU0_SB_CB<4>")
	)
	(segment
		(start 388.506208 -269.553436)
		(end 388.497826 -269.54861)
		(width 0.0889)
		(layer "In11.Cu")
		(net "M_L_CPU0_SB_CB<4>")
	)
	(arc
		(start 389.811768 -269.54861)
		(mid 389.624824 -269.598865)
		(end 389.43788 -269.54861)
		(width 0.0889)
		(layer "In11.Cu")
		(net "M_L_CPU0_SB_CB<4>")
	)
	(arc
		(start 393.093448 -268.74343)
		(mid 392.90994 -268.788924)
		(end 392.727688 -268.738604)
		(width 0.0889)
		(layer "In11.Cu")
		(net "M_L_CPU0_SB_CB<4>")
	)
	(arc
		(start 390.37768 -269.54861)
		(mid 390.094724 -269.472433)
		(end 389.811768 -269.54861)
		(width 0.0889)
		(layer "In11.Cu")
		(net "M_L_CPU0_SB_CB<4>")
	)
	(arc
		(start 391.317734 -269.54861)
		(mid 391.034778 -269.472433)
		(end 390.751822 -269.54861)
		(width 0.0889)
		(layer "In11.Cu")
		(net "M_L_CPU0_SB_CB<4>")
	)
	(arc
		(start 388.497826 -269.54861)
		(mid 388.21487 -269.472433)
		(end 387.931914 -269.54861)
		(width 0.0889)
		(layer "In11.Cu")
		(net "M_L_CPU0_SB_CB<4>")
	)
	(arc
		(start 387.931914 -269.54861)
		(mid 387.775476 -269.597581)
		(end 387.613144 -269.574772)
		(width 0.0889)
		(layer "In11.Cu")
		(net "M_L_CPU0_SB_CB<4>")
	)
	(arc
		(start 392.727688 -268.738604)
		(mid 392.444732 -268.662427)
		(end 392.161776 -268.738604)
		(width 0.0889)
		(layer "In11.Cu")
		(net "M_L_CPU0_SB_CB<4>")
	)
	(arc
		(start 391.879328 -269.22603)
		(mid 391.837779 -269.397452)
		(end 391.722356 -269.53083)
		(width 0.0889)
		(layer "In11.Cu")
		(net "M_L_CPU0_SB_CB<4>")
	)
	(arc
		(start 391.691876 -269.54861)
		(mid 391.509625 -269.59896)
		(end 391.326116 -269.553436)
		(width 0.0889)
		(layer "In11.Cu")
		(net "M_L_CPU0_SB_CB<4>")
	)
	(arc
		(start 393.384532 -268.662404)
		(mid 393.361018 -268.662799)
		(end 393.337542 -268.664182)
		(width 0.0889)
		(layer "In11.Cu")
		(net "M_L_CPU0_SB_CB<4>")
	)
	(arc
		(start 392.12266 -268.761464)
		(mid 391.943847 -268.963814)
		(end 391.879328 -269.22603)
		(width 0.0889)
		(layer "In11.Cu")
		(net "M_L_CPU0_SB_CB<4>")
	)
	(arc
		(start 389.43788 -269.54861)
		(mid 389.154924 -269.472433)
		(end 388.871968 -269.54861)
		(width 0.0889)
		(layer "In11.Cu")
		(net "M_L_CPU0_SB_CB<4>")
	)
	(arc
		(start 388.871968 -269.54861)
		(mid 388.689717 -269.59896)
		(end 388.506208 -269.553436)
		(width 0.0889)
		(layer "In11.Cu")
		(net "M_L_CPU0_SB_CB<4>")
	)
	(arc
		(start 393.337542 -268.664182)
		(mid 393.21556 -268.688321)
		(end 393.10183 -268.738604)
		(width 0.0889)
		(layer "In11.Cu")
		(net "M_L_CPU0_SB_CB<4>")
	)
	(arc
		(start 390.74344 -269.553436)
		(mid 390.559932 -269.59893)
		(end 390.37768 -269.54861)
		(width 0.0889)
		(layer "In11.Cu")
		(net "M_L_CPU0_SB_CB<4>")
	)
	(segment
		(start 385.39801 -273.820128)
		(end 385.864862 -274.086066)
		(width 0.10668)
		(layer "F.Cu")
		(net "M_L_CPU0_SB_CB<3>")
	)
	(segment
		(start 414.063942 -281.060144)
		(end 411.278578 -281.060144)
		(width 0.14478)
		(layer "In11.Cu")
		(net "M_L_CPU0_SB_CB<3>")
	)
	(segment
		(start 437.57215 -280.210006)
		(end 436.722012 -281.060144)
		(width 0.14478)
		(layer "In11.Cu")
		(net "M_L_CPU0_SB_CB<3>")
	)
	(segment
		(start 408.316684 -277.245826)
		(end 408.316938 -277.015702)
		(width 0.14478)
		(layer "In11.Cu")
		(net "M_L_CPU0_SB_CB<3>")
	)
	(segment
		(start 418.972492 -281.060144)
		(end 418.122354 -280.210006)
		(width 0.14478)
		(layer "In11.Cu")
		(net "M_L_CPU0_SB_CB<3>")
	)
	(segment
		(start 406.594056 -276.375622)
		(end 402.601684 -272.38325)
		(width 0.14478)
		(layer "In11.Cu")
		(net "M_L_CPU0_SB_CB<3>")
	)
	(segment
		(start 391.326116 -273.75866)
		(end 391.317734 -273.763486)
		(width 0.0889)
		(layer "In11.Cu")
		(net "M_L_CPU0_SB_CB<3>")
	)
	(segment
		(start 418.122354 -280.210006)
		(end 414.91408 -280.210006)
		(width 0.14478)
		(layer "In11.Cu")
		(net "M_L_CPU0_SB_CB<3>")
	)
	(segment
		(start 407.381456 -277.163022)
		(end 407.218388 -276.999954)
		(width 0.14478)
		(layer "In11.Cu")
		(net "M_L_CPU0_SB_CB<3>")
	)
	(segment
		(start 391.70229 -273.769582)
		(end 391.691876 -273.763486)
		(width 0.0889)
		(layer "In11.Cu")
		(net "M_L_CPU0_SB_CB<3>")
	)
	(segment
		(start 407.366216 -276.06498)
		(end 407.135584 -276.06498)
		(width 0.14478)
		(layer "In11.Cu")
		(net "M_L_CPU0_SB_CB<3>")
	)
	(segment
		(start 395.966188 -272.38325)
		(end 395.54912 -272.38325)
		(width 0.0889)
		(layer "In11.Cu")
		(net "M_L_CPU0_SB_CB<3>")
	)
	(segment
		(start 407.612088 -277.163276)
		(end 407.381456 -277.163022)
		(width 0.14478)
		(layer "In11.Cu")
		(net "M_L_CPU0_SB_CB<3>")
	)
	(segment
		(start 430.028096 -280.210006)
		(end 429.177958 -281.060144)
		(width 0.14478)
		(layer "In11.Cu")
		(net "M_L_CPU0_SB_CB<3>")
	)
	(segment
		(start 386.018786 -273.820636)
		(end 385.864862 -274.086066)
		(width 0.0889)
		(layer "In11.Cu")
		(net "M_L_CPU0_SB_CB<3>")
	)
	(segment
		(start 440.689238 -280.210006)
		(end 437.57215 -280.210006)
		(width 0.14478)
		(layer "In11.Cu")
		(net "M_L_CPU0_SB_CB<3>")
	)
	(segment
		(start 434.0606 -281.060144)
		(end 433.210462 -280.210006)
		(width 0.14478)
		(layer "In11.Cu")
		(net "M_L_CPU0_SB_CB<3>")
	)
	(segment
		(start 388.506208 -273.75866)
		(end 388.497826 -273.763486)
		(width 0.0889)
		(layer "In11.Cu")
		(net "M_L_CPU0_SB_CB<3>")
	)
	(segment
		(start 429.177958 -281.060144)
		(end 426.516546 -281.060144)
		(width 0.14478)
		(layer "In11.Cu")
		(net "M_L_CPU0_SB_CB<3>")
	)
	(segment
		(start 387.566154 -273.75866)
		(end 387.557772 -273.763486)
		(width 0.0889)
		(layer "In11.Cu")
		(net "M_L_CPU0_SB_CB<3>")
	)
	(segment
		(start 395.375638 -272.556732)
		(end 394.829538 -272.556732)
		(width 0.0889)
		(layer "In11.Cu")
		(net "M_L_CPU0_SB_CB<3>")
	)
	(segment
		(start 422.484042 -280.210006)
		(end 421.633904 -281.060144)
		(width 0.14478)
		(layer "In11.Cu")
		(net "M_L_CPU0_SB_CB<3>")
	)
	(segment
		(start 408.399488 -277.950676)
		(end 408.168856 -277.950422)
		(width 0.14478)
		(layer "In11.Cu")
		(net "M_L_CPU0_SB_CB<3>")
	)
	(segment
		(start 433.210462 -280.210006)
		(end 430.028096 -280.210006)
		(width 0.14478)
		(layer "In11.Cu")
		(net "M_L_CPU0_SB_CB<3>")
	)
	(segment
		(start 443.730634 -281.060144)
		(end 441.539376 -281.060144)
		(width 0.14478)
		(layer "In11.Cu")
		(net "M_L_CPU0_SB_CB<3>")
	)
	(segment
		(start 406.824688 -276.375876)
		(end 406.594056 -276.375622)
		(width 0.14478)
		(layer "In11.Cu")
		(net "M_L_CPU0_SB_CB<3>")
	)
	(segment
		(start 414.91408 -280.210006)
		(end 414.063942 -281.060144)
		(width 0.14478)
		(layer "In11.Cu")
		(net "M_L_CPU0_SB_CB<3>")
	)
	(segment
		(start 393.198096 -273.763486)
		(end 393.187682 -273.769582)
		(width 0.0889)
		(layer "In11.Cu")
		(net "M_L_CPU0_SB_CB<3>")
	)
	(segment
		(start 408.005788 -277.556722)
		(end 408.316684 -277.245826)
		(width 0.14478)
		(layer "In11.Cu")
		(net "M_L_CPU0_SB_CB<3>")
	)
	(segment
		(start 386.114798 -273.795236)
		(end 386.018786 -273.820636)
		(width 0.0889)
		(layer "In11.Cu")
		(net "M_L_CPU0_SB_CB<3>")
	)
	(segment
		(start 394.829538 -272.556732)
		(end 393.673076 -273.713194)
		(width 0.0889)
		(layer "In11.Cu")
		(net "M_L_CPU0_SB_CB<3>")
	)
	(segment
		(start 441.539376 -281.060144)
		(end 440.689238 -280.210006)
		(width 0.14478)
		(layer "In11.Cu")
		(net "M_L_CPU0_SB_CB<3>")
	)
	(segment
		(start 409.104084 -278.033226)
		(end 409.104338 -277.803102)
		(width 0.14478)
		(layer "In11.Cu")
		(net "M_L_CPU0_SB_CB<3>")
	)
	(segment
		(start 408.793188 -278.574754)
		(end 408.793188 -278.344122)
		(width 0.14478)
		(layer "In11.Cu")
		(net "M_L_CPU0_SB_CB<3>")
	)
	(segment
		(start 426.516546 -281.060144)
		(end 425.666408 -280.210006)
		(width 0.14478)
		(layer "In11.Cu")
		(net "M_L_CPU0_SB_CB<3>")
	)
	(segment
		(start 407.218388 -276.999954)
		(end 407.218388 -276.769322)
		(width 0.14478)
		(layer "In11.Cu")
		(net "M_L_CPU0_SB_CB<3>")
	)
	(segment
		(start 407.135584 -276.06498)
		(end 406.824688 -276.375876)
		(width 0.14478)
		(layer "In11.Cu")
		(net "M_L_CPU0_SB_CB<3>")
	)
	(segment
		(start 408.168856 -277.950422)
		(end 408.005788 -277.787354)
		(width 0.14478)
		(layer "In11.Cu")
		(net "M_L_CPU0_SB_CB<3>")
	)
	(segment
		(start 395.54912 -272.38325)
		(end 395.375638 -272.556732)
		(width 0.0889)
		(layer "In11.Cu")
		(net "M_L_CPU0_SB_CB<3>")
	)
	(segment
		(start 408.005788 -277.787354)
		(end 408.005788 -277.556722)
		(width 0.14478)
		(layer "In11.Cu")
		(net "M_L_CPU0_SB_CB<3>")
	)
	(segment
		(start 408.153616 -276.85238)
		(end 407.922984 -276.85238)
		(width 0.14478)
		(layer "In11.Cu")
		(net "M_L_CPU0_SB_CB<3>")
	)
	(segment
		(start 390.751822 -273.763486)
		(end 390.74344 -273.75866)
		(width 0.0889)
		(layer "In11.Cu")
		(net "M_L_CPU0_SB_CB<3>")
	)
	(segment
		(start 411.278578 -281.060144)
		(end 408.793188 -278.574754)
		(width 0.14478)
		(layer "In11.Cu")
		(net "M_L_CPU0_SB_CB<3>")
	)
	(segment
		(start 408.793188 -278.344122)
		(end 409.104084 -278.033226)
		(width 0.14478)
		(layer "In11.Cu")
		(net "M_L_CPU0_SB_CB<3>")
	)
	(segment
		(start 407.529538 -276.228302)
		(end 407.366216 -276.06498)
		(width 0.14478)
		(layer "In11.Cu")
		(net "M_L_CPU0_SB_CB<3>")
	)
	(segment
		(start 407.218388 -276.769322)
		(end 407.529284 -276.458426)
		(width 0.14478)
		(layer "In11.Cu")
		(net "M_L_CPU0_SB_CB<3>")
	)
	(segment
		(start 407.529284 -276.458426)
		(end 407.529538 -276.228302)
		(width 0.14478)
		(layer "In11.Cu")
		(net "M_L_CPU0_SB_CB<3>")
	)
	(segment
		(start 449.663058 -280.210006)
		(end 444.580772 -280.210006)
		(width 0.14478)
		(layer "In11.Cu")
		(net "M_L_CPU0_SB_CB<3>")
	)
	(segment
		(start 409.104338 -277.803102)
		(end 408.941016 -277.63978)
		(width 0.14478)
		(layer "In11.Cu")
		(net "M_L_CPU0_SB_CB<3>")
	)
	(segment
		(start 386.99186 -273.763486)
		(end 386.983478 -273.75866)
		(width 0.0889)
		(layer "In11.Cu")
		(net "M_L_CPU0_SB_CB<3>")
	)
	(segment
		(start 421.633904 -281.060144)
		(end 418.972492 -281.060144)
		(width 0.14478)
		(layer "In11.Cu")
		(net "M_L_CPU0_SB_CB<3>")
	)
	(segment
		(start 436.722012 -281.060144)
		(end 434.0606 -281.060144)
		(width 0.14478)
		(layer "In11.Cu")
		(net "M_L_CPU0_SB_CB<3>")
	)
	(segment
		(start 393.673076 -273.713194)
		(end 393.384786 -273.713194)
		(width 0.0889)
		(layer "In11.Cu")
		(net "M_L_CPU0_SB_CB<3>")
	)
	(segment
		(start 450.088 -280.634948)
		(end 449.663058 -280.210006)
		(width 0.14478)
		(layer "In11.Cu")
		(net "M_L_CPU0_SB_CB<3>")
	)
	(segment
		(start 408.710384 -277.63978)
		(end 408.399488 -277.950676)
		(width 0.14478)
		(layer "In11.Cu")
		(net "M_L_CPU0_SB_CB<3>")
	)
	(segment
		(start 402.601684 -272.38325)
		(end 395.966188 -272.38325)
		(width 0.14478)
		(layer "In11.Cu")
		(net "M_L_CPU0_SB_CB<3>")
	)
	(segment
		(start 408.941016 -277.63978)
		(end 408.710384 -277.63978)
		(width 0.14478)
		(layer "In11.Cu")
		(net "M_L_CPU0_SB_CB<3>")
	)
	(segment
		(start 444.580772 -280.210006)
		(end 443.730634 -281.060144)
		(width 0.14478)
		(layer "In11.Cu")
		(net "M_L_CPU0_SB_CB<3>")
	)
	(segment
		(start 425.666408 -280.210006)
		(end 422.484042 -280.210006)
		(width 0.14478)
		(layer "In11.Cu")
		(net "M_L_CPU0_SB_CB<3>")
	)
	(segment
		(start 407.922984 -276.85238)
		(end 407.612088 -277.163276)
		(width 0.14478)
		(layer "In11.Cu")
		(net "M_L_CPU0_SB_CB<3>")
	)
	(segment
		(start 408.316938 -277.015702)
		(end 408.153616 -276.85238)
		(width 0.14478)
		(layer "In11.Cu")
		(net "M_L_CPU0_SB_CB<3>")
	)
	(arc
		(start 386.983478 -273.75866)
		(mid 386.79997 -273.713166)
		(end 386.617718 -273.763486)
		(width 0.0889)
		(layer "In11.Cu")
		(net "M_L_CPU0_SB_CB<3>")
	)
	(arc
		(start 393.384786 -273.713194)
		(mid 393.288117 -273.726011)
		(end 393.198096 -273.763486)
		(width 0.0889)
		(layer "In11.Cu")
		(net "M_L_CPU0_SB_CB<3>")
	)
	(arc
		(start 387.931914 -273.763486)
		(mid 387.749663 -273.713136)
		(end 387.566154 -273.75866)
		(width 0.0889)
		(layer "In11.Cu")
		(net "M_L_CPU0_SB_CB<3>")
	)
	(arc
		(start 388.497826 -273.763486)
		(mid 388.21487 -273.839663)
		(end 387.931914 -273.763486)
		(width 0.0889)
		(layer "In11.Cu")
		(net "M_L_CPU0_SB_CB<3>")
	)
	(arc
		(start 390.37768 -273.763486)
		(mid 390.094724 -273.839663)
		(end 389.811768 -273.763486)
		(width 0.0889)
		(layer "In11.Cu")
		(net "M_L_CPU0_SB_CB<3>")
	)
	(arc
		(start 392.632438 -273.763486)
		(mid 392.44524 -273.713104)
		(end 392.258042 -273.763486)
		(width 0.0889)
		(layer "In11.Cu")
		(net "M_L_CPU0_SB_CB<3>")
	)
	(arc
		(start 392.258042 -273.763486)
		(mid 391.980975 -273.839757)
		(end 391.70229 -273.769582)
		(width 0.0889)
		(layer "In11.Cu")
		(net "M_L_CPU0_SB_CB<3>")
	)
	(arc
		(start 389.811768 -273.763486)
		(mid 389.624824 -273.713231)
		(end 389.43788 -273.763486)
		(width 0.0889)
		(layer "In11.Cu")
		(net "M_L_CPU0_SB_CB<3>")
	)
	(arc
		(start 388.871968 -273.763486)
		(mid 388.689717 -273.713136)
		(end 388.506208 -273.75866)
		(width 0.0889)
		(layer "In11.Cu")
		(net "M_L_CPU0_SB_CB<3>")
	)
	(arc
		(start 389.43788 -273.763486)
		(mid 389.154924 -273.839663)
		(end 388.871968 -273.763486)
		(width 0.0889)
		(layer "In11.Cu")
		(net "M_L_CPU0_SB_CB<3>")
	)
	(arc
		(start 387.557772 -273.763486)
		(mid 387.274816 -273.839663)
		(end 386.99186 -273.763486)
		(width 0.0889)
		(layer "In11.Cu")
		(net "M_L_CPU0_SB_CB<3>")
	)
	(arc
		(start 391.691876 -273.763486)
		(mid 391.509625 -273.713136)
		(end 391.326116 -273.75866)
		(width 0.0889)
		(layer "In11.Cu")
		(net "M_L_CPU0_SB_CB<3>")
	)
	(arc
		(start 386.617718 -273.763486)
		(mid 386.370005 -273.838706)
		(end 386.114798 -273.795236)
		(width 0.0889)
		(layer "In11.Cu")
		(net "M_L_CPU0_SB_CB<3>")
	)
	(arc
		(start 390.74344 -273.75866)
		(mid 390.559932 -273.713166)
		(end 390.37768 -273.763486)
		(width 0.0889)
		(layer "In11.Cu")
		(net "M_L_CPU0_SB_CB<3>")
	)
	(arc
		(start 391.317734 -273.763486)
		(mid 391.034778 -273.839663)
		(end 390.751822 -273.763486)
		(width 0.0889)
		(layer "In11.Cu")
		(net "M_L_CPU0_SB_CB<3>")
	)
	(arc
		(start 393.187682 -273.769582)
		(mid 392.90925 -273.83968)
		(end 392.632438 -273.763486)
		(width 0.0889)
		(layer "In11.Cu")
		(net "M_L_CPU0_SB_CB<3>")
	)
	(segment
		(start 386.807964 -273.010122)
		(end 387.274816 -273.27606)
		(width 0.10668)
		(layer "F.Cu")
		(net "M_L_CPU0_SB_CB<2>")
	)
	(segment
		(start 405.842216 -274.10664)
		(end 405.611584 -274.10664)
		(width 0.14478)
		(layer "In11.Cu")
		(net "M_L_CPU0_SB_CB<2>")
	)
	(segment
		(start 404.661116 -272.92554)
		(end 404.998936 -272.58772)
		(width 0.14478)
		(layer "In11.Cu")
		(net "M_L_CPU0_SB_CB<2>")
	)
	(segment
		(start 433.839112 -279.360122)
		(end 432.988974 -278.509984)
		(width 0.14478)
		(layer "In11.Cu")
		(net "M_L_CPU0_SB_CB<2>")
	)
	(segment
		(start 405.786336 -273.37512)
		(end 405.786336 -273.144488)
		(width 0.14478)
		(layer "In11.Cu")
		(net "M_L_CPU0_SB_CB<2>")
	)
	(segment
		(start 429.177958 -279.360122)
		(end 426.295058 -279.360122)
		(width 0.14478)
		(layer "In11.Cu")
		(net "M_L_CPU0_SB_CB<2>")
	)
	(segment
		(start 443.98565 -279.360122)
		(end 441.332366 -279.360122)
		(width 0.14478)
		(layer "In11.Cu")
		(net "M_L_CPU0_SB_CB<2>")
	)
	(segment
		(start 441.332366 -279.360122)
		(end 440.482228 -278.509984)
		(width 0.14478)
		(layer "In11.Cu")
		(net "M_L_CPU0_SB_CB<2>")
	)
	(segment
		(start 406.573736 -273.931888)
		(end 406.410668 -273.76882)
		(width 0.14478)
		(layer "In11.Cu")
		(net "M_L_CPU0_SB_CB<2>")
	)
	(segment
		(start 404.026116 -271.47393)
		(end 395.837918 -271.47393)
		(width 0.14478)
		(layer "In11.Cu")
		(net "M_L_CPU0_SB_CB<2>")
	)
	(segment
		(start 405.786336 -273.144488)
		(end 405.623268 -272.98142)
		(width 0.14478)
		(layer "In11.Cu")
		(net "M_L_CPU0_SB_CB<2>")
	)
	(segment
		(start 404.661116 -273.156172)
		(end 404.661116 -272.92554)
		(width 0.14478)
		(layer "In11.Cu")
		(net "M_L_CPU0_SB_CB<2>")
	)
	(segment
		(start 412.00197 -279.360122)
		(end 407.198068 -274.55622)
		(width 0.14478)
		(layer "In11.Cu")
		(net "M_L_CPU0_SB_CB<2>")
	)
	(segment
		(start 437.57215 -278.509984)
		(end 436.722012 -279.360122)
		(width 0.14478)
		(layer "In11.Cu")
		(net "M_L_CPU0_SB_CB<2>")
	)
	(segment
		(start 404.998936 -272.58772)
		(end 404.998936 -272.357088)
		(width 0.14478)
		(layer "In11.Cu")
		(net "M_L_CPU0_SB_CB<2>")
	)
	(segment
		(start 425.44492 -278.509984)
		(end 422.484042 -278.509984)
		(width 0.14478)
		(layer "In11.Cu")
		(net "M_L_CPU0_SB_CB<2>")
	)
	(segment
		(start 406.967436 -274.55622)
		(end 406.629616 -274.89404)
		(width 0.14478)
		(layer "In11.Cu")
		(net "M_L_CPU0_SB_CB<2>")
	)
	(segment
		(start 404.605236 -272.19402)
		(end 404.267416 -272.53184)
		(width 0.14478)
		(layer "In11.Cu")
		(net "M_L_CPU0_SB_CB<2>")
	)
	(segment
		(start 387.42874 -273.01063)
		(end 387.274816 -273.27606)
		(width 0.0889)
		(layer "In11.Cu")
		(net "M_L_CPU0_SB_CB<2>")
	)
	(segment
		(start 404.835868 -272.19402)
		(end 404.605236 -272.19402)
		(width 0.14478)
		(layer "In11.Cu")
		(net "M_L_CPU0_SB_CB<2>")
	)
	(segment
		(start 405.448516 -273.943572)
		(end 405.448516 -273.71294)
		(width 0.14478)
		(layer "In11.Cu")
		(net "M_L_CPU0_SB_CB<2>")
	)
	(segment
		(start 394.764768 -271.883124)
		(end 393.783312 -272.86458)
		(width 0.0889)
		(layer "In11.Cu")
		(net "M_L_CPU0_SB_CB<2>")
	)
	(segment
		(start 432.988974 -278.509984)
		(end 430.028096 -278.509984)
		(width 0.14478)
		(layer "In11.Cu")
		(net "M_L_CPU0_SB_CB<2>")
	)
	(segment
		(start 406.573736 -274.16252)
		(end 406.573736 -273.931888)
		(width 0.14478)
		(layer "In11.Cu")
		(net "M_L_CPU0_SB_CB<2>")
	)
	(segment
		(start 387.524752 -272.98523)
		(end 387.42874 -273.01063)
		(width 0.0889)
		(layer "In11.Cu")
		(net "M_L_CPU0_SB_CB<2>")
	)
	(segment
		(start 403.873716 -272.368772)
		(end 403.873716 -272.13814)
		(width 0.14478)
		(layer "In11.Cu")
		(net "M_L_CPU0_SB_CB<2>")
	)
	(segment
		(start 430.028096 -278.509984)
		(end 429.177958 -279.360122)
		(width 0.14478)
		(layer "In11.Cu")
		(net "M_L_CPU0_SB_CB<2>")
	)
	(segment
		(start 395.837918 -271.47393)
		(end 395.47546 -271.47393)
		(width 0.0889)
		(layer "In11.Cu")
		(net "M_L_CPU0_SB_CB<2>")
	)
	(segment
		(start 403.873716 -272.13814)
		(end 404.175976 -271.83588)
		(width 0.14478)
		(layer "In11.Cu")
		(net "M_L_CPU0_SB_CB<2>")
	)
	(segment
		(start 392.726926 -272.953734)
		(end 392.714988 -272.960592)
		(width 0.0889)
		(layer "In11.Cu")
		(net "M_L_CPU0_SB_CB<2>")
	)
	(segment
		(start 404.175976 -271.62379)
		(end 404.026116 -271.47393)
		(width 0.14478)
		(layer "In11.Cu")
		(net "M_L_CPU0_SB_CB<2>")
	)
	(segment
		(start 406.180036 -273.76882)
		(end 405.842216 -274.10664)
		(width 0.14478)
		(layer "In11.Cu")
		(net "M_L_CPU0_SB_CB<2>")
	)
	(segment
		(start 426.295058 -279.360122)
		(end 425.44492 -278.509984)
		(width 0.14478)
		(layer "In11.Cu")
		(net "M_L_CPU0_SB_CB<2>")
	)
	(segment
		(start 404.175976 -271.83588)
		(end 404.175976 -271.62379)
		(width 0.14478)
		(layer "In11.Cu")
		(net "M_L_CPU0_SB_CB<2>")
	)
	(segment
		(start 407.198068 -274.55622)
		(end 406.967436 -274.55622)
		(width 0.14478)
		(layer "In11.Cu")
		(net "M_L_CPU0_SB_CB<2>")
	)
	(segment
		(start 444.835788 -278.509984)
		(end 443.98565 -279.360122)
		(width 0.14478)
		(layer "In11.Cu")
		(net "M_L_CPU0_SB_CB<2>")
	)
	(segment
		(start 392.161776 -272.95348)
		(end 392.153394 -272.948654)
		(width 0.0889)
		(layer "In11.Cu")
		(net "M_L_CPU0_SB_CB<2>")
	)
	(segment
		(start 404.998936 -272.357088)
		(end 404.835868 -272.19402)
		(width 0.14478)
		(layer "In11.Cu")
		(net "M_L_CPU0_SB_CB<2>")
	)
	(segment
		(start 404.267416 -272.53184)
		(end 404.036784 -272.53184)
		(width 0.14478)
		(layer "In11.Cu")
		(net "M_L_CPU0_SB_CB<2>")
	)
	(segment
		(start 389.916162 -272.948654)
		(end 389.90778 -272.95348)
		(width 0.0889)
		(layer "In11.Cu")
		(net "M_L_CPU0_SB_CB<2>")
	)
	(segment
		(start 404.824184 -273.31924)
		(end 404.661116 -273.156172)
		(width 0.14478)
		(layer "In11.Cu")
		(net "M_L_CPU0_SB_CB<2>")
	)
	(segment
		(start 405.611584 -274.10664)
		(end 405.448516 -273.943572)
		(width 0.14478)
		(layer "In11.Cu")
		(net "M_L_CPU0_SB_CB<2>")
	)
	(segment
		(start 414.063942 -279.360122)
		(end 412.00197 -279.360122)
		(width 0.14478)
		(layer "In11.Cu")
		(net "M_L_CPU0_SB_CB<2>")
	)
	(segment
		(start 414.91408 -278.509984)
		(end 414.063942 -279.360122)
		(width 0.14478)
		(layer "In11.Cu")
		(net "M_L_CPU0_SB_CB<2>")
	)
	(segment
		(start 406.410668 -273.76882)
		(end 406.180036 -273.76882)
		(width 0.14478)
		(layer "In11.Cu")
		(net "M_L_CPU0_SB_CB<2>")
	)
	(segment
		(start 421.633904 -279.360122)
		(end 418.972492 -279.360122)
		(width 0.14478)
		(layer "In11.Cu")
		(net "M_L_CPU0_SB_CB<2>")
	)
	(segment
		(start 418.972492 -279.360122)
		(end 418.122354 -278.509984)
		(width 0.14478)
		(layer "In11.Cu")
		(net "M_L_CPU0_SB_CB<2>")
	)
	(segment
		(start 392.745214 -272.94332)
		(end 392.726926 -272.953734)
		(width 0.0889)
		(layer "In11.Cu")
		(net "M_L_CPU0_SB_CB<2>")
	)
	(segment
		(start 436.722012 -279.360122)
		(end 433.839112 -279.360122)
		(width 0.14478)
		(layer "In11.Cu")
		(net "M_L_CPU0_SB_CB<2>")
	)
	(segment
		(start 450.088 -278.93518)
		(end 449.662804 -278.509984)
		(width 0.14478)
		(layer "In11.Cu")
		(net "M_L_CPU0_SB_CB<2>")
	)
	(segment
		(start 440.482228 -278.509984)
		(end 437.57215 -278.509984)
		(width 0.14478)
		(layer "In11.Cu")
		(net "M_L_CPU0_SB_CB<2>")
	)
	(segment
		(start 422.484042 -278.509984)
		(end 421.633904 -279.360122)
		(width 0.14478)
		(layer "In11.Cu")
		(net "M_L_CPU0_SB_CB<2>")
	)
	(segment
		(start 393.66698 -272.953734)
		(end 393.64539 -272.96618)
		(width 0.0889)
		(layer "In11.Cu")
		(net "M_L_CPU0_SB_CB<2>")
	)
	(segment
		(start 395.066266 -271.883124)
		(end 394.764768 -271.883124)
		(width 0.0889)
		(layer "In11.Cu")
		(net "M_L_CPU0_SB_CB<2>")
	)
	(segment
		(start 404.036784 -272.53184)
		(end 403.873716 -272.368772)
		(width 0.14478)
		(layer "In11.Cu")
		(net "M_L_CPU0_SB_CB<2>")
	)
	(segment
		(start 405.448516 -273.71294)
		(end 405.786336 -273.37512)
		(width 0.14478)
		(layer "In11.Cu")
		(net "M_L_CPU0_SB_CB<2>")
	)
	(segment
		(start 395.47546 -271.47393)
		(end 395.066266 -271.883124)
		(width 0.0889)
		(layer "In11.Cu")
		(net "M_L_CPU0_SB_CB<2>")
	)
	(segment
		(start 405.054816 -273.31924)
		(end 404.824184 -273.31924)
		(width 0.14478)
		(layer "In11.Cu")
		(net "M_L_CPU0_SB_CB<2>")
	)
	(segment
		(start 406.629616 -274.89404)
		(end 406.398984 -274.89404)
		(width 0.14478)
		(layer "In11.Cu")
		(net "M_L_CPU0_SB_CB<2>")
	)
	(segment
		(start 406.398984 -274.89404)
		(end 406.235916 -274.730972)
		(width 0.14478)
		(layer "In11.Cu")
		(net "M_L_CPU0_SB_CB<2>")
	)
	(segment
		(start 389.341868 -272.95348)
		(end 389.333486 -272.948654)
		(width 0.0889)
		(layer "In11.Cu")
		(net "M_L_CPU0_SB_CB<2>")
	)
	(segment
		(start 405.623268 -272.98142)
		(end 405.392636 -272.98142)
		(width 0.14478)
		(layer "In11.Cu")
		(net "M_L_CPU0_SB_CB<2>")
	)
	(segment
		(start 406.235916 -274.730972)
		(end 406.235916 -274.50034)
		(width 0.14478)
		(layer "In11.Cu")
		(net "M_L_CPU0_SB_CB<2>")
	)
	(segment
		(start 449.662804 -278.509984)
		(end 444.835788 -278.509984)
		(width 0.14478)
		(layer "In11.Cu")
		(net "M_L_CPU0_SB_CB<2>")
	)
	(segment
		(start 388.401814 -272.95348)
		(end 388.393432 -272.948654)
		(width 0.0889)
		(layer "In11.Cu")
		(net "M_L_CPU0_SB_CB<2>")
	)
	(segment
		(start 406.235916 -274.50034)
		(end 406.573736 -274.16252)
		(width 0.14478)
		(layer "In11.Cu")
		(net "M_L_CPU0_SB_CB<2>")
	)
	(segment
		(start 418.122354 -278.509984)
		(end 414.91408 -278.509984)
		(width 0.14478)
		(layer "In11.Cu")
		(net "M_L_CPU0_SB_CB<2>")
	)
	(segment
		(start 405.392636 -272.98142)
		(end 405.054816 -273.31924)
		(width 0.14478)
		(layer "In11.Cu")
		(net "M_L_CPU0_SB_CB<2>")
	)
	(arc
		(start 388.027672 -272.95348)
		(mid 387.779959 -273.0287)
		(end 387.524752 -272.98523)
		(width 0.0889)
		(layer "In11.Cu")
		(net "M_L_CPU0_SB_CB<2>")
	)
	(arc
		(start 393.64539 -272.96618)
		(mid 393.3716 -273.029851)
		(end 393.101068 -272.95348)
		(width 0.0889)
		(layer "In11.Cu")
		(net "M_L_CPU0_SB_CB<2>")
	)
	(arc
		(start 393.101068 -272.95348)
		(mid 392.92444 -272.903247)
		(end 392.745214 -272.94332)
		(width 0.0889)
		(layer "In11.Cu")
		(net "M_L_CPU0_SB_CB<2>")
	)
	(arc
		(start 391.221722 -272.95348)
		(mid 391.034778 -272.903225)
		(end 390.847834 -272.95348)
		(width 0.0889)
		(layer "In11.Cu")
		(net "M_L_CPU0_SB_CB<2>")
	)
	(arc
		(start 392.714988 -272.960592)
		(mid 392.437454 -273.029573)
		(end 392.161776 -272.95348)
		(width 0.0889)
		(layer "In11.Cu")
		(net "M_L_CPU0_SB_CB<2>")
	)
	(arc
		(start 389.333486 -272.948654)
		(mid 389.149978 -272.90316)
		(end 388.967726 -272.95348)
		(width 0.0889)
		(layer "In11.Cu")
		(net "M_L_CPU0_SB_CB<2>")
	)
	(arc
		(start 388.967726 -272.95348)
		(mid 388.68477 -273.029657)
		(end 388.401814 -272.95348)
		(width 0.0889)
		(layer "In11.Cu")
		(net "M_L_CPU0_SB_CB<2>")
	)
	(arc
		(start 389.90778 -272.95348)
		(mid 389.624824 -273.029657)
		(end 389.341868 -272.95348)
		(width 0.0889)
		(layer "In11.Cu")
		(net "M_L_CPU0_SB_CB<2>")
	)
	(arc
		(start 390.847834 -272.95348)
		(mid 390.564878 -273.029657)
		(end 390.281922 -272.95348)
		(width 0.0889)
		(layer "In11.Cu")
		(net "M_L_CPU0_SB_CB<2>")
	)
	(arc
		(start 391.787634 -272.95348)
		(mid 391.504678 -273.029657)
		(end 391.221722 -272.95348)
		(width 0.0889)
		(layer "In11.Cu")
		(net "M_L_CPU0_SB_CB<2>")
	)
	(arc
		(start 388.393432 -272.948654)
		(mid 388.209924 -272.90316)
		(end 388.027672 -272.95348)
		(width 0.0889)
		(layer "In11.Cu")
		(net "M_L_CPU0_SB_CB<2>")
	)
	(arc
		(start 390.281922 -272.95348)
		(mid 390.099671 -272.90313)
		(end 389.916162 -272.948654)
		(width 0.0889)
		(layer "In11.Cu")
		(net "M_L_CPU0_SB_CB<2>")
	)
	(arc
		(start 392.153394 -272.948654)
		(mid 391.969886 -272.90316)
		(end 391.787634 -272.95348)
		(width 0.0889)
		(layer "In11.Cu")
		(net "M_L_CPU0_SB_CB<2>")
	)
	(arc
		(start 393.783312 -272.86458)
		(mid 393.728062 -272.912962)
		(end 393.66698 -272.953734)
		(width 0.0889)
		(layer "In11.Cu")
		(net "M_L_CPU0_SB_CB<2>")
	)
	(segment
		(start 385.86791 -273.010122)
		(end 386.334762 -273.27606)
		(width 0.10668)
		(layer "F.Cu")
		(net "M_L_CPU0_SB_CB<1>")
	)
	(segment
		(start 394.839444 -272.241772)
		(end 393.558522 -273.522694)
		(width 0.0889)
		(layer "In11.Cu")
		(net "M_L_CPU0_SB_CB<1>")
	)
	(segment
		(start 395.241018 -272.241772)
		(end 394.839444 -272.241772)
		(width 0.0889)
		(layer "In11.Cu")
		(net "M_L_CPU0_SB_CB<1>")
	)
	(segment
		(start 412.201868 -280.210006)
		(end 407.340562 -275.3487)
		(width 0.14478)
		(layer "In11.Cu")
		(net "M_L_CPU0_SB_CB<1>")
	)
	(segment
		(start 443.276736 -280.210006)
		(end 442.16574 -280.210006)
		(width 0.14478)
		(layer "In11.Cu")
		(net "M_L_CPU0_SB_CB<1>")
	)
	(segment
		(start 393.102084 -273.59864)
		(end 393.0904 -273.605498)
		(width 0.0889)
		(layer "In11.Cu")
		(net "M_L_CPU0_SB_CB<1>")
	)
	(segment
		(start 454.188068 -279.785064)
		(end 452.051674 -279.360122)
		(width 0.14478)
		(layer "In11.Cu")
		(net "M_L_CPU0_SB_CB<1>")
	)
	(segment
		(start 407.340562 -275.3487)
		(end 406.210262 -275.3487)
		(width 0.14478)
		(layer "In11.Cu")
		(net "M_L_CPU0_SB_CB<1>")
	)
	(segment
		(start 425.601384 -279.360122)
		(end 422.576752 -279.360122)
		(width 0.14478)
		(layer "In11.Cu")
		(net "M_L_CPU0_SB_CB<1>")
	)
	(segment
		(start 429.101758 -280.210006)
		(end 426.451268 -280.210006)
		(width 0.14478)
		(layer "In11.Cu")
		(net "M_L_CPU0_SB_CB<1>")
	)
	(segment
		(start 452.051674 -279.360122)
		(end 445.328548 -279.360122)
		(width 0.14478)
		(layer "In11.Cu")
		(net "M_L_CPU0_SB_CB<1>")
	)
	(segment
		(start 418.972492 -280.210006)
		(end 418.122354 -279.359868)
		(width 0.14478)
		(layer "In11.Cu")
		(net "M_L_CPU0_SB_CB<1>")
	)
	(segment
		(start 445.328548 -279.360122)
		(end 443.276736 -280.210006)
		(width 0.14478)
		(layer "In11.Cu")
		(net "M_L_CPU0_SB_CB<1>")
	)
	(segment
		(start 436.129938 -280.210006)
		(end 434.461666 -280.210006)
		(width 0.14478)
		(layer "In11.Cu")
		(net "M_L_CPU0_SB_CB<1>")
	)
	(segment
		(start 418.122354 -279.359868)
		(end 415.032952 -279.359868)
		(width 0.14478)
		(layer "In11.Cu")
		(net "M_L_CPU0_SB_CB<1>")
	)
	(segment
		(start 421.726868 -280.210006)
		(end 418.972492 -280.210006)
		(width 0.14478)
		(layer "In11.Cu")
		(net "M_L_CPU0_SB_CB<1>")
	)
	(segment
		(start 415.032952 -279.359868)
		(end 414.182814 -280.210006)
		(width 0.14478)
		(layer "In11.Cu")
		(net "M_L_CPU0_SB_CB<1>")
	)
	(segment
		(start 442.16574 -280.210006)
		(end 440.113928 -279.360122)
		(width 0.14478)
		(layer "In11.Cu")
		(net "M_L_CPU0_SB_CB<1>")
	)
	(segment
		(start 388.401814 -273.59864)
		(end 388.393432 -273.603466)
		(width 0.0889)
		(layer "In11.Cu")
		(net "M_L_CPU0_SB_CB<1>")
	)
	(segment
		(start 392.728196 -273.59864)
		(end 392.717782 -273.592544)
		(width 0.0889)
		(layer "In11.Cu")
		(net "M_L_CPU0_SB_CB<1>")
	)
	(segment
		(start 395.931898 -271.92859)
		(end 395.5542 -271.92859)
		(width 0.0889)
		(layer "In11.Cu")
		(net "M_L_CPU0_SB_CB<1>")
	)
	(segment
		(start 432.409854 -279.360122)
		(end 429.951642 -279.360122)
		(width 0.14478)
		(layer "In11.Cu")
		(net "M_L_CPU0_SB_CB<1>")
	)
	(segment
		(start 422.576752 -279.360122)
		(end 421.726868 -280.210006)
		(width 0.14478)
		(layer "In11.Cu")
		(net "M_L_CPU0_SB_CB<1>")
	)
	(segment
		(start 389.916162 -273.603466)
		(end 389.90778 -273.59864)
		(width 0.0889)
		(layer "In11.Cu")
		(net "M_L_CPU0_SB_CB<1>")
	)
	(segment
		(start 406.210262 -275.3487)
		(end 402.790152 -271.92859)
		(width 0.14478)
		(layer "In11.Cu")
		(net "M_L_CPU0_SB_CB<1>")
	)
	(segment
		(start 434.461666 -280.210006)
		(end 432.409854 -279.360122)
		(width 0.14478)
		(layer "In11.Cu")
		(net "M_L_CPU0_SB_CB<1>")
	)
	(segment
		(start 395.5542 -271.92859)
		(end 395.241018 -272.241772)
		(width 0.0889)
		(layer "In11.Cu")
		(net "M_L_CPU0_SB_CB<1>")
	)
	(segment
		(start 389.341868 -273.59864)
		(end 389.333486 -273.603466)
		(width 0.0889)
		(layer "In11.Cu")
		(net "M_L_CPU0_SB_CB<1>")
	)
	(segment
		(start 386.20319 -273.624802)
		(end 386.180838 -273.54149)
		(width 0.0889)
		(layer "In11.Cu")
		(net "M_L_CPU0_SB_CB<1>")
	)
	(segment
		(start 402.790152 -271.92859)
		(end 395.931898 -271.92859)
		(width 0.14478)
		(layer "In11.Cu")
		(net "M_L_CPU0_SB_CB<1>")
	)
	(segment
		(start 440.113928 -279.360122)
		(end 438.18175 -279.360122)
		(width 0.14478)
		(layer "In11.Cu")
		(net "M_L_CPU0_SB_CB<1>")
	)
	(segment
		(start 429.951642 -279.360122)
		(end 429.101758 -280.210006)
		(width 0.14478)
		(layer "In11.Cu")
		(net "M_L_CPU0_SB_CB<1>")
	)
	(segment
		(start 414.182814 -280.210006)
		(end 412.201868 -280.210006)
		(width 0.14478)
		(layer "In11.Cu")
		(net "M_L_CPU0_SB_CB<1>")
	)
	(segment
		(start 426.451268 -280.210006)
		(end 425.601384 -279.360122)
		(width 0.14478)
		(layer "In11.Cu")
		(net "M_L_CPU0_SB_CB<1>")
	)
	(segment
		(start 386.180838 -273.54149)
		(end 386.334762 -273.27606)
		(width 0.0889)
		(layer "In11.Cu")
		(net "M_L_CPU0_SB_CB<1>")
	)
	(segment
		(start 438.18175 -279.360122)
		(end 436.129938 -280.210006)
		(width 0.14478)
		(layer "In11.Cu")
		(net "M_L_CPU0_SB_CB<1>")
	)
	(segment
		(start 393.558522 -273.522694)
		(end 393.384786 -273.522694)
		(width 0.0889)
		(layer "In11.Cu")
		(net "M_L_CPU0_SB_CB<1>")
	)
	(arc
		(start 393.384786 -273.522694)
		(mid 393.238411 -273.541973)
		(end 393.102084 -273.59864)
		(width 0.0889)
		(layer "In11.Cu")
		(net "M_L_CPU0_SB_CB<1>")
	)
	(arc
		(start 389.333486 -273.603466)
		(mid 389.149978 -273.64896)
		(end 388.967726 -273.59864)
		(width 0.0889)
		(layer "In11.Cu")
		(net "M_L_CPU0_SB_CB<1>")
	)
	(arc
		(start 389.90778 -273.59864)
		(mid 389.624824 -273.522463)
		(end 389.341868 -273.59864)
		(width 0.0889)
		(layer "In11.Cu")
		(net "M_L_CPU0_SB_CB<1>")
	)
	(arc
		(start 392.16203 -273.59864)
		(mid 391.974832 -273.649022)
		(end 391.787634 -273.59864)
		(width 0.0889)
		(layer "In11.Cu")
		(net "M_L_CPU0_SB_CB<1>")
	)
	(arc
		(start 391.787634 -273.59864)
		(mid 391.504678 -273.522463)
		(end 391.221722 -273.59864)
		(width 0.0889)
		(layer "In11.Cu")
		(net "M_L_CPU0_SB_CB<1>")
	)
	(arc
		(start 386.52196 -273.59864)
		(mid 386.365522 -273.647611)
		(end 386.20319 -273.624802)
		(width 0.0889)
		(layer "In11.Cu")
		(net "M_L_CPU0_SB_CB<1>")
	)
	(arc
		(start 390.281922 -273.59864)
		(mid 390.099671 -273.64899)
		(end 389.916162 -273.603466)
		(width 0.0889)
		(layer "In11.Cu")
		(net "M_L_CPU0_SB_CB<1>")
	)
	(arc
		(start 391.221722 -273.59864)
		(mid 391.034778 -273.648895)
		(end 390.847834 -273.59864)
		(width 0.0889)
		(layer "In11.Cu")
		(net "M_L_CPU0_SB_CB<1>")
	)
	(arc
		(start 390.847834 -273.59864)
		(mid 390.564878 -273.522463)
		(end 390.281922 -273.59864)
		(width 0.0889)
		(layer "In11.Cu")
		(net "M_L_CPU0_SB_CB<1>")
	)
	(arc
		(start 388.393432 -273.603466)
		(mid 388.209924 -273.64896)
		(end 388.027672 -273.59864)
		(width 0.0889)
		(layer "In11.Cu")
		(net "M_L_CPU0_SB_CB<1>")
	)
	(arc
		(start 392.717782 -273.592544)
		(mid 392.439096 -273.522324)
		(end 392.16203 -273.59864)
		(width 0.0889)
		(layer "In11.Cu")
		(net "M_L_CPU0_SB_CB<1>")
	)
	(arc
		(start 388.027672 -273.59864)
		(mid 387.744716 -273.522463)
		(end 387.46176 -273.59864)
		(width 0.0889)
		(layer "In11.Cu")
		(net "M_L_CPU0_SB_CB<1>")
	)
	(arc
		(start 387.46176 -273.59864)
		(mid 387.274816 -273.648895)
		(end 387.087872 -273.59864)
		(width 0.0889)
		(layer "In11.Cu")
		(net "M_L_CPU0_SB_CB<1>")
	)
	(arc
		(start 393.0904 -273.605498)
		(mid 392.908399 -273.649031)
		(end 392.728196 -273.59864)
		(width 0.0889)
		(layer "In11.Cu")
		(net "M_L_CPU0_SB_CB<1>")
	)
	(arc
		(start 387.087872 -273.59864)
		(mid 386.804916 -273.522463)
		(end 386.52196 -273.59864)
		(width 0.0889)
		(layer "In11.Cu")
		(net "M_L_CPU0_SB_CB<1>")
	)
	(arc
		(start 388.967726 -273.59864)
		(mid 388.68477 -273.522463)
		(end 388.401814 -273.59864)
		(width 0.0889)
		(layer "In11.Cu")
		(net "M_L_CPU0_SB_CB<1>")
	)
	(segment
		(start 387.277864 -272.200116)
		(end 387.744716 -272.466054)
		(width 0.10668)
		(layer "F.Cu")
		(net "M_L_CPU0_SB_CB<0>")
	)
	(segment
		(start 393.571222 -272.78838)
		(end 393.551156 -272.79981)
		(width 0.0889)
		(layer "In11.Cu")
		(net "M_L_CPU0_SB_CB<0>")
	)
	(segment
		(start 395.837918 -271.01927)
		(end 394.784326 -271.01927)
		(width 0.0889)
		(layer "In11.Cu")
		(net "M_L_CPU0_SB_CB<0>")
	)
	(segment
		(start 432.984148 -277.669498)
		(end 430.111408 -277.669498)
		(width 0.14478)
		(layer "In11.Cu")
		(net "M_L_CPU0_SB_CB<0>")
	)
	(segment
		(start 387.590792 -272.731484)
		(end 387.744716 -272.466054)
		(width 0.0889)
		(layer "In11.Cu")
		(net "M_L_CPU0_SB_CB<0>")
	)
	(segment
		(start 452.503032 -278.226012)
		(end 452.503032 -277.804626)
		(width 0.14478)
		(layer "In11.Cu")
		(net "M_L_CPU0_SB_CB<0>")
	)
	(segment
		(start 392.631422 -272.78838)
		(end 392.617706 -272.796254)
		(width 0.0889)
		(layer "In11.Cu")
		(net "M_L_CPU0_SB_CB<0>")
	)
	(segment
		(start 453.066912 -278.226012)
		(end 452.922132 -278.370792)
		(width 0.14478)
		(layer "In11.Cu")
		(net "M_L_CPU0_SB_CB<0>")
	)
	(segment
		(start 393.800838 -272.57756)
		(end 393.648692 -272.729706)
		(width 0.0889)
		(layer "In11.Cu")
		(net "M_L_CPU0_SB_CB<0>")
	)
	(segment
		(start 390.751822 -272.788634)
		(end 390.74344 -272.79346)
		(width 0.0889)
		(layer "In11.Cu")
		(net "M_L_CPU0_SB_CB<0>")
	)
	(segment
		(start 452.922132 -278.370792)
		(end 452.647812 -278.370792)
		(width 0.14478)
		(layer "In11.Cu")
		(net "M_L_CPU0_SB_CB<0>")
	)
	(segment
		(start 393.800838 -272.002758)
		(end 393.800838 -272.57756)
		(width 0.0889)
		(layer "In11.Cu")
		(net "M_L_CPU0_SB_CB<0>")
	)
	(segment
		(start 418.916866 -278.519636)
		(end 418.412422 -278.015192)
		(width 0.14478)
		(layer "In11.Cu")
		(net "M_L_CPU0_SB_CB<0>")
	)
	(segment
		(start 421.717216 -278.519636)
		(end 418.916866 -278.519636)
		(width 0.14478)
		(layer "In11.Cu")
		(net "M_L_CPU0_SB_CB<0>")
	)
	(segment
		(start 452.358252 -277.659846)
		(end 451.704456 -277.659846)
		(width 0.14478)
		(layer "In11.Cu")
		(net "M_L_CPU0_SB_CB<0>")
	)
	(segment
		(start 440.464194 -277.669498)
		(end 437.655462 -277.669498)
		(width 0.14478)
		(layer "In11.Cu")
		(net "M_L_CPU0_SB_CB<0>")
	)
	(segment
		(start 414.182814 -278.510238)
		(end 411.795468 -278.510238)
		(width 0.14478)
		(layer "In11.Cu")
		(net "M_L_CPU0_SB_CB<0>")
	)
	(segment
		(start 388.506208 -272.79346)
		(end 388.497826 -272.788634)
		(width 0.0889)
		(layer "In11.Cu")
		(net "M_L_CPU0_SB_CB<0>")
	)
	(segment
		(start 418.412422 -278.015192)
		(end 414.67786 -278.015192)
		(width 0.14478)
		(layer "In11.Cu")
		(net "M_L_CPU0_SB_CB<0>")
	)
	(segment
		(start 429.261524 -278.519382)
		(end 426.216826 -278.519382)
		(width 0.14478)
		(layer "In11.Cu")
		(net "M_L_CPU0_SB_CB<0>")
	)
	(segment
		(start 451.695058 -277.669244)
		(end 445.013334 -277.669244)
		(width 0.14478)
		(layer "In11.Cu")
		(net "M_L_CPU0_SB_CB<0>")
	)
	(segment
		(start 422.567354 -277.669498)
		(end 421.717216 -278.519636)
		(width 0.14478)
		(layer "In11.Cu")
		(net "M_L_CPU0_SB_CB<0>")
	)
	(segment
		(start 437.655462 -277.669498)
		(end 436.805578 -278.519382)
		(width 0.14478)
		(layer "In11.Cu")
		(net "M_L_CPU0_SB_CB<0>")
	)
	(segment
		(start 394.784326 -271.01927)
		(end 393.800838 -272.002758)
		(width 0.0889)
		(layer "In11.Cu")
		(net "M_L_CPU0_SB_CB<0>")
	)
	(segment
		(start 392.653012 -272.775934)
		(end 392.631422 -272.78838)
		(width 0.0889)
		(layer "In11.Cu")
		(net "M_L_CPU0_SB_CB<0>")
	)
	(segment
		(start 453.066912 -277.804626)
		(end 453.066912 -278.226012)
		(width 0.14478)
		(layer "In11.Cu")
		(net "M_L_CPU0_SB_CB<0>")
	)
	(segment
		(start 454.188068 -278.085042)
		(end 453.762872 -277.659846)
		(width 0.14478)
		(layer "In11.Cu")
		(net "M_L_CPU0_SB_CB<0>")
	)
	(segment
		(start 414.67786 -278.015192)
		(end 414.182814 -278.510238)
		(width 0.14478)
		(layer "In11.Cu")
		(net "M_L_CPU0_SB_CB<0>")
	)
	(segment
		(start 391.326116 -272.79346)
		(end 391.317734 -272.788634)
		(width 0.0889)
		(layer "In11.Cu")
		(net "M_L_CPU0_SB_CB<0>")
	)
	(segment
		(start 411.795468 -278.510238)
		(end 404.3045 -271.01927)
		(width 0.14478)
		(layer "In11.Cu")
		(net "M_L_CPU0_SB_CB<0>")
	)
	(segment
		(start 430.111408 -277.669498)
		(end 429.261524 -278.519382)
		(width 0.14478)
		(layer "In11.Cu")
		(net "M_L_CPU0_SB_CB<0>")
	)
	(segment
		(start 393.648692 -272.729706)
		(end 393.648438 -272.729706)
		(width 0.0889)
		(layer "In11.Cu")
		(net "M_L_CPU0_SB_CB<0>")
	)
	(segment
		(start 426.216826 -278.519382)
		(end 425.366942 -277.669498)
		(width 0.14478)
		(layer "In11.Cu")
		(net "M_L_CPU0_SB_CB<0>")
	)
	(segment
		(start 453.762872 -277.659846)
		(end 453.211692 -277.659846)
		(width 0.14478)
		(layer "In11.Cu")
		(net "M_L_CPU0_SB_CB<0>")
	)
	(segment
		(start 445.013334 -277.669244)
		(end 444.163196 -278.519382)
		(width 0.14478)
		(layer "In11.Cu")
		(net "M_L_CPU0_SB_CB<0>")
	)
	(segment
		(start 387.613144 -272.814796)
		(end 387.590792 -272.731484)
		(width 0.0889)
		(layer "In11.Cu")
		(net "M_L_CPU0_SB_CB<0>")
	)
	(segment
		(start 441.314078 -278.519382)
		(end 440.464194 -277.669498)
		(width 0.14478)
		(layer "In11.Cu")
		(net "M_L_CPU0_SB_CB<0>")
	)
	(segment
		(start 451.704456 -277.659846)
		(end 451.695058 -277.669244)
		(width 0.14478)
		(layer "In11.Cu")
		(net "M_L_CPU0_SB_CB<0>")
	)
	(segment
		(start 452.503032 -277.804626)
		(end 452.358252 -277.659846)
		(width 0.14478)
		(layer "In11.Cu")
		(net "M_L_CPU0_SB_CB<0>")
	)
	(segment
		(start 444.163196 -278.519382)
		(end 441.314078 -278.519382)
		(width 0.14478)
		(layer "In11.Cu")
		(net "M_L_CPU0_SB_CB<0>")
	)
	(segment
		(start 452.647812 -278.370792)
		(end 452.503032 -278.226012)
		(width 0.14478)
		(layer "In11.Cu")
		(net "M_L_CPU0_SB_CB<0>")
	)
	(segment
		(start 404.3045 -271.01927)
		(end 395.837918 -271.01927)
		(width 0.14478)
		(layer "In11.Cu")
		(net "M_L_CPU0_SB_CB<0>")
	)
	(segment
		(start 436.805578 -278.519382)
		(end 433.834032 -278.519382)
		(width 0.14478)
		(layer "In11.Cu")
		(net "M_L_CPU0_SB_CB<0>")
	)
	(segment
		(start 433.834032 -278.519382)
		(end 432.984148 -277.669498)
		(width 0.14478)
		(layer "In11.Cu")
		(net "M_L_CPU0_SB_CB<0>")
	)
	(segment
		(start 453.211692 -277.659846)
		(end 453.066912 -277.804626)
		(width 0.14478)
		(layer "In11.Cu")
		(net "M_L_CPU0_SB_CB<0>")
	)
	(segment
		(start 425.366942 -277.669498)
		(end 422.567354 -277.669498)
		(width 0.14478)
		(layer "In11.Cu")
		(net "M_L_CPU0_SB_CB<0>")
	)
	(arc
		(start 388.497826 -272.788634)
		(mid 388.21487 -272.712457)
		(end 387.931914 -272.788634)
		(width 0.0889)
		(layer "In11.Cu")
		(net "M_L_CPU0_SB_CB<0>")
	)
	(arc
		(start 393.197334 -272.788634)
		(mid 392.926803 -272.712228)
		(end 392.653012 -272.775934)
		(width 0.0889)
		(layer "In11.Cu")
		(net "M_L_CPU0_SB_CB<0>")
	)
	(arc
		(start 388.871968 -272.788634)
		(mid 388.689717 -272.838984)
		(end 388.506208 -272.79346)
		(width 0.0889)
		(layer "In11.Cu")
		(net "M_L_CPU0_SB_CB<0>")
	)
	(arc
		(start 389.43788 -272.788634)
		(mid 389.154924 -272.712457)
		(end 388.871968 -272.788634)
		(width 0.0889)
		(layer "In11.Cu")
		(net "M_L_CPU0_SB_CB<0>")
	)
	(arc
		(start 390.74344 -272.79346)
		(mid 390.559932 -272.838954)
		(end 390.37768 -272.788634)
		(width 0.0889)
		(layer "In11.Cu")
		(net "M_L_CPU0_SB_CB<0>")
	)
	(arc
		(start 389.811768 -272.788634)
		(mid 389.624824 -272.838889)
		(end 389.43788 -272.788634)
		(width 0.0889)
		(layer "In11.Cu")
		(net "M_L_CPU0_SB_CB<0>")
	)
	(arc
		(start 387.931914 -272.788634)
		(mid 387.775476 -272.837605)
		(end 387.613144 -272.814796)
		(width 0.0889)
		(layer "In11.Cu")
		(net "M_L_CPU0_SB_CB<0>")
	)
	(arc
		(start 392.617706 -272.796254)
		(mid 392.436776 -272.838732)
		(end 392.257788 -272.788634)
		(width 0.0889)
		(layer "In11.Cu")
		(net "M_L_CPU0_SB_CB<0>")
	)
	(arc
		(start 393.551156 -272.79981)
		(mid 393.372824 -272.838907)
		(end 393.197334 -272.788634)
		(width 0.0889)
		(layer "In11.Cu")
		(net "M_L_CPU0_SB_CB<0>")
	)
	(arc
		(start 391.317734 -272.788634)
		(mid 391.034778 -272.712457)
		(end 390.751822 -272.788634)
		(width 0.0889)
		(layer "In11.Cu")
		(net "M_L_CPU0_SB_CB<0>")
	)
	(arc
		(start 391.691876 -272.788634)
		(mid 391.509625 -272.838984)
		(end 391.326116 -272.79346)
		(width 0.0889)
		(layer "In11.Cu")
		(net "M_L_CPU0_SB_CB<0>")
	)
	(arc
		(start 392.257788 -272.788634)
		(mid 391.974832 -272.712457)
		(end 391.691876 -272.788634)
		(width 0.0889)
		(layer "In11.Cu")
		(net "M_L_CPU0_SB_CB<0>")
	)
	(arc
		(start 390.37768 -272.788634)
		(mid 390.094724 -272.712457)
		(end 389.811768 -272.788634)
		(width 0.0889)
		(layer "In11.Cu")
		(net "M_L_CPU0_SB_CB<0>")
	)
	(arc
		(start 393.648438 -272.729706)
		(mid 393.611742 -272.761559)
		(end 393.571222 -272.78838)
		(width 0.0889)
		(layer "In11.Cu")
		(net "M_L_CPU0_SB_CB<0>")
	)
	(segment
		(start 387.277864 -264.100056)
		(end 387.744716 -264.365994)
		(width 0.10668)
		(layer "F.Cu")
		(net "M_L_CPU0_SB_CA<6>")
	)
	(segment
		(start 394.225018 -264.273792)
		(end 395.596618 -264.273792)
		(width 0.0889)
		(layer "In11.Cu")
		(net "M_L_CPU0_SB_CA<6>")
	)
	(segment
		(start 430.120806 -265.7602)
		(end 433.145438 -265.7602)
		(width 0.14478)
		(layer "In11.Cu")
		(net "M_L_CPU0_SB_CA<6>")
	)
	(segment
		(start 395.661896 -264.33907)
		(end 395.96314 -264.33907)
		(width 0.0889)
		(layer "In11.Cu")
		(net "M_L_CPU0_SB_CA<6>")
	)
	(segment
		(start 392.24204 -264.672318)
		(end 392.260328 -264.682986)
		(width 0.0889)
		(layer "In11.Cu")
		(net "M_L_CPU0_SB_CA<6>")
	)
	(segment
		(start 422.576752 -265.7602)
		(end 425.601384 -265.7602)
		(width 0.14478)
		(layer "In11.Cu")
		(net "M_L_CPU0_SB_CA<6>")
	)
	(segment
		(start 433.995322 -266.610084)
		(end 436.814976 -266.610084)
		(width 0.14478)
		(layer "In11.Cu")
		(net "M_L_CPU0_SB_CA<6>")
	)
	(segment
		(start 425.601384 -265.7602)
		(end 426.451268 -266.610084)
		(width 0.14478)
		(layer "In11.Cu")
		(net "M_L_CPU0_SB_CA<6>")
	)
	(segment
		(start 393.765786 -264.733024)
		(end 394.225018 -264.273792)
		(width 0.0889)
		(layer "In11.Cu")
		(net "M_L_CPU0_SB_CA<6>")
	)
	(segment
		(start 453.763126 -265.7602)
		(end 454.188068 -266.185142)
		(width 0.14478)
		(layer "In11.Cu")
		(net "M_L_CPU0_SB_CA<6>")
	)
	(segment
		(start 421.726868 -266.610084)
		(end 422.576752 -265.7602)
		(width 0.14478)
		(layer "In11.Cu")
		(net "M_L_CPU0_SB_CA<6>")
	)
	(segment
		(start 392.260328 -264.682986)
		(end 392.272012 -264.68959)
		(width 0.0889)
		(layer "In11.Cu")
		(net "M_L_CPU0_SB_CA<6>")
	)
	(segment
		(start 393.384786 -264.733024)
		(end 393.765786 -264.733024)
		(width 0.0889)
		(layer "In11.Cu")
		(net "M_L_CPU0_SB_CA<6>")
	)
	(segment
		(start 433.145438 -265.7602)
		(end 433.995322 -266.610084)
		(width 0.14478)
		(layer "In11.Cu")
		(net "M_L_CPU0_SB_CA<6>")
	)
	(segment
		(start 388.490206 -264.67689)
		(end 388.500874 -264.682986)
		(width 0.0889)
		(layer "In11.Cu")
		(net "M_L_CPU0_SB_CA<6>")
	)
	(segment
		(start 395.96314 -264.33907)
		(end 409.22194 -264.33907)
		(width 0.14478)
		(layer "In11.Cu")
		(net "M_L_CPU0_SB_CA<6>")
	)
	(segment
		(start 389.80872 -264.682986)
		(end 389.819388 -264.67689)
		(width 0.0889)
		(layer "In11.Cu")
		(net "M_L_CPU0_SB_CA<6>")
	)
	(segment
		(start 426.451268 -266.610084)
		(end 429.270922 -266.610084)
		(width 0.14478)
		(layer "In11.Cu")
		(net "M_L_CPU0_SB_CA<6>")
	)
	(segment
		(start 429.270922 -266.610084)
		(end 430.120806 -265.7602)
		(width 0.14478)
		(layer "In11.Cu")
		(net "M_L_CPU0_SB_CA<6>")
	)
	(segment
		(start 387.595872 -264.62228)
		(end 387.61924 -264.710164)
		(width 0.0889)
		(layer "In11.Cu")
		(net "M_L_CPU0_SB_CA<6>")
	)
	(segment
		(start 436.814976 -266.610084)
		(end 437.66486 -265.7602)
		(width 0.14478)
		(layer "In11.Cu")
		(net "M_L_CPU0_SB_CA<6>")
	)
	(segment
		(start 395.596618 -264.273792)
		(end 395.661896 -264.33907)
		(width 0.0889)
		(layer "In11.Cu")
		(net "M_L_CPU0_SB_CA<6>")
	)
	(segment
		(start 409.22194 -264.33907)
		(end 411.492954 -266.610084)
		(width 0.14478)
		(layer "In11.Cu")
		(net "M_L_CPU0_SB_CA<6>")
	)
	(segment
		(start 387.744716 -264.365994)
		(end 387.595872 -264.62228)
		(width 0.0889)
		(layer "In11.Cu")
		(net "M_L_CPU0_SB_CA<6>")
	)
	(segment
		(start 389.43026 -264.67689)
		(end 389.440928 -264.682986)
		(width 0.0889)
		(layer "In11.Cu")
		(net "M_L_CPU0_SB_CA<6>")
	)
	(segment
		(start 392.627612 -264.682986)
		(end 392.6459 -264.672318)
		(width 0.0889)
		(layer "In11.Cu")
		(net "M_L_CPU0_SB_CA<6>")
	)
	(segment
		(start 437.66486 -265.7602)
		(end 453.763126 -265.7602)
		(width 0.14478)
		(layer "In11.Cu")
		(net "M_L_CPU0_SB_CA<6>")
	)
	(segment
		(start 411.492954 -266.610084)
		(end 421.726868 -266.610084)
		(width 0.14478)
		(layer "In11.Cu")
		(net "M_L_CPU0_SB_CA<6>")
	)
	(arc
		(start 392.272012 -264.68959)
		(mid 392.450681 -264.73238)
		(end 392.627612 -264.682986)
		(width 0.0889)
		(layer "In11.Cu")
		(net "M_L_CPU0_SB_CA<6>")
	)
	(arc
		(start 388.868666 -264.682986)
		(mid 389.14867 -264.605941)
		(end 389.43026 -264.67689)
		(width 0.0889)
		(layer "In11.Cu")
		(net "M_L_CPU0_SB_CA<6>")
	)
	(arc
		(start 393.200382 -264.682986)
		(mid 393.289269 -264.720218)
		(end 393.384786 -264.733024)
		(width 0.0889)
		(layer "In11.Cu")
		(net "M_L_CPU0_SB_CA<6>")
	)
	(arc
		(start 387.928612 -264.682986)
		(mid 388.208616 -264.605941)
		(end 388.490206 -264.67689)
		(width 0.0889)
		(layer "In11.Cu")
		(net "M_L_CPU0_SB_CA<6>")
	)
	(arc
		(start 387.61924 -264.710164)
		(mid 387.776959 -264.731011)
		(end 387.928612 -264.682986)
		(width 0.0889)
		(layer "In11.Cu")
		(net "M_L_CPU0_SB_CA<6>")
	)
	(arc
		(start 390.380982 -264.682986)
		(mid 390.564878 -264.732466)
		(end 390.748774 -264.682986)
		(width 0.0889)
		(layer "In11.Cu")
		(net "M_L_CPU0_SB_CA<6>")
	)
	(arc
		(start 388.500874 -264.682986)
		(mid 388.68477 -264.732466)
		(end 388.868666 -264.682986)
		(width 0.0889)
		(layer "In11.Cu")
		(net "M_L_CPU0_SB_CA<6>")
	)
	(arc
		(start 389.440928 -264.682986)
		(mid 389.624824 -264.732466)
		(end 389.80872 -264.682986)
		(width 0.0889)
		(layer "In11.Cu")
		(net "M_L_CPU0_SB_CA<6>")
	)
	(arc
		(start 392.6459 -264.672318)
		(mid 392.924533 -264.605695)
		(end 393.200382 -264.682986)
		(width 0.0889)
		(layer "In11.Cu")
		(net "M_L_CPU0_SB_CA<6>")
	)
	(arc
		(start 391.688574 -264.682986)
		(mid 391.963916 -264.606011)
		(end 392.24204 -264.672318)
		(width 0.0889)
		(layer "In11.Cu")
		(net "M_L_CPU0_SB_CA<6>")
	)
	(arc
		(start 389.819388 -264.67689)
		(mid 390.100977 -264.606016)
		(end 390.380982 -264.682986)
		(width 0.0889)
		(layer "In11.Cu")
		(net "M_L_CPU0_SB_CA<6>")
	)
	(arc
		(start 391.320782 -264.682986)
		(mid 391.504678 -264.732466)
		(end 391.688574 -264.682986)
		(width 0.0889)
		(layer "In11.Cu")
		(net "M_L_CPU0_SB_CA<6>")
	)
	(arc
		(start 390.748774 -264.682986)
		(mid 391.034778 -264.606034)
		(end 391.320782 -264.682986)
		(width 0.0889)
		(layer "In11.Cu")
		(net "M_L_CPU0_SB_CA<6>")
	)
	(segment
		(start 385.39801 -264.100056)
		(end 385.864862 -264.365994)
		(width 0.10668)
		(layer "F.Cu")
		(net "M_L_CPU0_SB_CA<5>")
	)
	(segment
		(start 447.368422 -264.765282)
		(end 447.368422 -264.685272)
		(width 0.14478)
		(layer "In11.Cu")
		(net "M_L_CPU0_SB_CA<5>")
	)
	(segment
		(start 448.877944 -264.540492)
		(end 449.022724 -264.685272)
		(width 0.14478)
		(layer "In11.Cu")
		(net "M_L_CPU0_SB_CA<5>")
	)
	(segment
		(start 411.595062 -265.7602)
		(end 421.633904 -265.7602)
		(width 0.14478)
		(layer "In11.Cu")
		(net "M_L_CPU0_SB_CA<5>")
	)
	(segment
		(start 393.177014 -264.056114)
		(end 393.198604 -264.043668)
		(width 0.0889)
		(layer "In11.Cu")
		(net "M_L_CPU0_SB_CA<5>")
	)
	(segment
		(start 447.513202 -264.540492)
		(end 447.775076 -264.540492)
		(width 0.14478)
		(layer "In11.Cu")
		(net "M_L_CPU0_SB_CA<5>")
	)
	(segment
		(start 449.022724 -264.685272)
		(end 449.022724 -264.765282)
		(width 0.14478)
		(layer "In11.Cu")
		(net "M_L_CPU0_SB_CA<5>")
	)
	(segment
		(start 386.018786 -264.100564)
		(end 386.114798 -264.075164)
		(width 0.0889)
		(layer "In11.Cu")
		(net "M_L_CPU0_SB_CA<5>")
	)
	(segment
		(start 429.177958 -265.7602)
		(end 430.028096 -264.910062)
		(width 0.14478)
		(layer "In11.Cu")
		(net "M_L_CPU0_SB_CA<5>")
	)
	(segment
		(start 448.47129 -264.685272)
		(end 448.61607 -264.540492)
		(width 0.14478)
		(layer "In11.Cu")
		(net "M_L_CPU0_SB_CA<5>")
	)
	(segment
		(start 436.722012 -265.7602)
		(end 437.57215 -264.910062)
		(width 0.14478)
		(layer "In11.Cu")
		(net "M_L_CPU0_SB_CA<5>")
	)
	(segment
		(start 391.691876 -264.043414)
		(end 391.715244 -264.05713)
		(width 0.0889)
		(layer "In11.Cu")
		(net "M_L_CPU0_SB_CA<5>")
	)
	(segment
		(start 395.38148 -263.88441)
		(end 395.946122 -263.88441)
		(width 0.0889)
		(layer "In11.Cu")
		(net "M_L_CPU0_SB_CA<5>")
	)
	(segment
		(start 392.619738 -264.035032)
		(end 392.634216 -264.043414)
		(width 0.0889)
		(layer "In11.Cu")
		(net "M_L_CPU0_SB_CA<5>")
	)
	(segment
		(start 448.064636 -265.279632)
		(end 448.32651 -265.279632)
		(width 0.14478)
		(layer "In11.Cu")
		(net "M_L_CPU0_SB_CA<5>")
	)
	(segment
		(start 447.775076 -264.540492)
		(end 447.919856 -264.685272)
		(width 0.14478)
		(layer "In11.Cu")
		(net "M_L_CPU0_SB_CA<5>")
	)
	(segment
		(start 387.557772 -264.043414)
		(end 387.566154 -264.038588)
		(width 0.0889)
		(layer "In11.Cu")
		(net "M_L_CPU0_SB_CA<5>")
	)
	(segment
		(start 447.919856 -265.134852)
		(end 448.064636 -265.279632)
		(width 0.14478)
		(layer "In11.Cu")
		(net "M_L_CPU0_SB_CA<5>")
	)
	(segment
		(start 426.516546 -265.7602)
		(end 429.177958 -265.7602)
		(width 0.14478)
		(layer "In11.Cu")
		(net "M_L_CPU0_SB_CA<5>")
	)
	(segment
		(start 448.47129 -265.134852)
		(end 448.47129 -264.685272)
		(width 0.14478)
		(layer "In11.Cu")
		(net "M_L_CPU0_SB_CA<5>")
	)
	(segment
		(start 448.61607 -264.540492)
		(end 448.877944 -264.540492)
		(width 0.14478)
		(layer "In11.Cu")
		(net "M_L_CPU0_SB_CA<5>")
	)
	(segment
		(start 385.864862 -264.365994)
		(end 386.018786 -264.100564)
		(width 0.0889)
		(layer "In11.Cu")
		(net "M_L_CPU0_SB_CA<5>")
	)
	(segment
		(start 391.317734 -264.043414)
		(end 391.326116 -264.038588)
		(width 0.0889)
		(layer "In11.Cu")
		(net "M_L_CPU0_SB_CA<5>")
	)
	(segment
		(start 447.919856 -264.685272)
		(end 447.919856 -265.134852)
		(width 0.14478)
		(layer "In11.Cu")
		(net "M_L_CPU0_SB_CA<5>")
	)
	(segment
		(start 386.983478 -264.038588)
		(end 386.99186 -264.043414)
		(width 0.0889)
		(layer "In11.Cu")
		(net "M_L_CPU0_SB_CA<5>")
	)
	(segment
		(start 434.0606 -265.7602)
		(end 436.722012 -265.7602)
		(width 0.14478)
		(layer "In11.Cu")
		(net "M_L_CPU0_SB_CA<5>")
	)
	(segment
		(start 449.167504 -264.910062)
		(end 449.663058 -264.910062)
		(width 0.14478)
		(layer "In11.Cu")
		(net "M_L_CPU0_SB_CA<5>")
	)
	(segment
		(start 421.633904 -265.7602)
		(end 422.484042 -264.910062)
		(width 0.14478)
		(layer "In11.Cu")
		(net "M_L_CPU0_SB_CA<5>")
	)
	(segment
		(start 449.663058 -264.910062)
		(end 450.088 -265.335004)
		(width 0.14478)
		(layer "In11.Cu")
		(net "M_L_CPU0_SB_CA<5>")
	)
	(segment
		(start 433.210462 -264.910062)
		(end 434.0606 -265.7602)
		(width 0.14478)
		(layer "In11.Cu")
		(net "M_L_CPU0_SB_CA<5>")
	)
	(segment
		(start 448.32651 -265.279632)
		(end 448.47129 -265.134852)
		(width 0.14478)
		(layer "In11.Cu")
		(net "M_L_CPU0_SB_CA<5>")
	)
	(segment
		(start 422.484042 -264.910062)
		(end 425.666408 -264.910062)
		(width 0.14478)
		(layer "In11.Cu")
		(net "M_L_CPU0_SB_CA<5>")
	)
	(segment
		(start 395.272514 -263.993376)
		(end 395.38148 -263.88441)
		(width 0.0889)
		(layer "In11.Cu")
		(net "M_L_CPU0_SB_CA<5>")
	)
	(segment
		(start 437.57215 -264.910062)
		(end 447.223642 -264.910062)
		(width 0.14478)
		(layer "In11.Cu")
		(net "M_L_CPU0_SB_CA<5>")
	)
	(segment
		(start 388.497826 -264.043414)
		(end 388.506208 -264.038588)
		(width 0.0889)
		(layer "In11.Cu")
		(net "M_L_CPU0_SB_CA<5>")
	)
	(segment
		(start 390.74344 -264.038588)
		(end 390.751822 -264.043414)
		(width 0.0889)
		(layer "In11.Cu")
		(net "M_L_CPU0_SB_CA<5>")
	)
	(segment
		(start 449.022724 -264.765282)
		(end 449.167504 -264.910062)
		(width 0.14478)
		(layer "In11.Cu")
		(net "M_L_CPU0_SB_CA<5>")
	)
	(segment
		(start 409.719272 -263.88441)
		(end 411.595062 -265.7602)
		(width 0.14478)
		(layer "In11.Cu")
		(net "M_L_CPU0_SB_CA<5>")
	)
	(segment
		(start 395.946122 -263.88441)
		(end 409.719272 -263.88441)
		(width 0.14478)
		(layer "In11.Cu")
		(net "M_L_CPU0_SB_CA<5>")
	)
	(segment
		(start 447.368422 -264.685272)
		(end 447.513202 -264.540492)
		(width 0.14478)
		(layer "In11.Cu")
		(net "M_L_CPU0_SB_CA<5>")
	)
	(segment
		(start 430.028096 -264.910062)
		(end 433.210462 -264.910062)
		(width 0.14478)
		(layer "In11.Cu")
		(net "M_L_CPU0_SB_CA<5>")
	)
	(segment
		(start 447.223642 -264.910062)
		(end 447.368422 -264.765282)
		(width 0.14478)
		(layer "In11.Cu")
		(net "M_L_CPU0_SB_CA<5>")
	)
	(segment
		(start 425.666408 -264.910062)
		(end 426.516546 -265.7602)
		(width 0.14478)
		(layer "In11.Cu")
		(net "M_L_CPU0_SB_CA<5>")
	)
	(segment
		(start 393.384786 -263.993376)
		(end 395.272514 -263.993376)
		(width 0.0889)
		(layer "In11.Cu")
		(net "M_L_CPU0_SB_CA<5>")
	)
	(arc
		(start 388.506208 -264.038588)
		(mid 388.689716 -263.993094)
		(end 388.871968 -264.043414)
		(width 0.0889)
		(layer "In11.Cu")
		(net "M_L_CPU0_SB_CA<5>")
	)
	(arc
		(start 387.566154 -264.038588)
		(mid 387.749662 -263.993094)
		(end 387.931914 -264.043414)
		(width 0.0889)
		(layer "In11.Cu")
		(net "M_L_CPU0_SB_CA<5>")
	)
	(arc
		(start 391.326116 -264.038588)
		(mid 391.509624 -263.993094)
		(end 391.691876 -264.043414)
		(width 0.0889)
		(layer "In11.Cu")
		(net "M_L_CPU0_SB_CA<5>")
	)
	(arc
		(start 392.259058 -264.043414)
		(mid 392.438321 -263.99275)
		(end 392.619738 -264.035032)
		(width 0.0889)
		(layer "In11.Cu")
		(net "M_L_CPU0_SB_CA<5>")
	)
	(arc
		(start 387.931914 -264.043414)
		(mid 388.21487 -264.119591)
		(end 388.497826 -264.043414)
		(width 0.0889)
		(layer "In11.Cu")
		(net "M_L_CPU0_SB_CA<5>")
	)
	(arc
		(start 392.634216 -264.043414)
		(mid 392.903985 -264.119437)
		(end 393.177014 -264.056114)
		(width 0.0889)
		(layer "In11.Cu")
		(net "M_L_CPU0_SB_CA<5>")
	)
	(arc
		(start 386.114798 -264.075164)
		(mid 386.370006 -264.118641)
		(end 386.617718 -264.043414)
		(width 0.0889)
		(layer "In11.Cu")
		(net "M_L_CPU0_SB_CA<5>")
	)
	(arc
		(start 389.811768 -264.043414)
		(mid 390.094724 -264.119591)
		(end 390.37768 -264.043414)
		(width 0.0889)
		(layer "In11.Cu")
		(net "M_L_CPU0_SB_CA<5>")
	)
	(arc
		(start 391.715244 -264.05713)
		(mid 391.988898 -264.120073)
		(end 392.259058 -264.043414)
		(width 0.0889)
		(layer "In11.Cu")
		(net "M_L_CPU0_SB_CA<5>")
	)
	(arc
		(start 386.617718 -264.043414)
		(mid 386.799969 -263.993064)
		(end 386.983478 -264.038588)
		(width 0.0889)
		(layer "In11.Cu")
		(net "M_L_CPU0_SB_CA<5>")
	)
	(arc
		(start 390.37768 -264.043414)
		(mid 390.559931 -263.993064)
		(end 390.74344 -264.038588)
		(width 0.0889)
		(layer "In11.Cu")
		(net "M_L_CPU0_SB_CA<5>")
	)
	(arc
		(start 393.198604 -264.043668)
		(mid 393.288381 -264.006245)
		(end 393.384786 -263.993376)
		(width 0.0889)
		(layer "In11.Cu")
		(net "M_L_CPU0_SB_CA<5>")
	)
	(arc
		(start 390.751822 -264.043414)
		(mid 391.034778 -264.119591)
		(end 391.317734 -264.043414)
		(width 0.0889)
		(layer "In11.Cu")
		(net "M_L_CPU0_SB_CA<5>")
	)
	(arc
		(start 389.43788 -264.043414)
		(mid 389.624824 -263.993159)
		(end 389.811768 -264.043414)
		(width 0.0889)
		(layer "In11.Cu")
		(net "M_L_CPU0_SB_CA<5>")
	)
	(arc
		(start 388.871968 -264.043414)
		(mid 389.154924 -264.119591)
		(end 389.43788 -264.043414)
		(width 0.0889)
		(layer "In11.Cu")
		(net "M_L_CPU0_SB_CA<5>")
	)
	(arc
		(start 386.99186 -264.043414)
		(mid 387.274816 -264.119591)
		(end 387.557772 -264.043414)
		(width 0.0889)
		(layer "In11.Cu")
		(net "M_L_CPU0_SB_CA<5>")
	)
	(segment
		(start 385.86791 -263.29005)
		(end 386.334762 -263.555988)
		(width 0.10668)
		(layer "F.Cu")
		(net "M_L_CPU0_SB_CA<4>")
	)
	(segment
		(start 389.333486 -263.883394)
		(end 389.341868 -263.878568)
		(width 0.0889)
		(layer "In11.Cu")
		(net "M_L_CPU0_SB_CA<4>")
	)
	(segment
		(start 429.270922 -264.910062)
		(end 430.120806 -264.060178)
		(width 0.14478)
		(layer "In11.Cu")
		(net "M_L_CPU0_SB_CA<4>")
	)
	(segment
		(start 386.334762 -263.555988)
		(end 386.180838 -263.821418)
		(width 0.0889)
		(layer "In11.Cu")
		(net "M_L_CPU0_SB_CA<4>")
	)
	(segment
		(start 433.145438 -264.060178)
		(end 433.995322 -264.910062)
		(width 0.14478)
		(layer "In11.Cu")
		(net "M_L_CPU0_SB_CA<4>")
	)
	(segment
		(start 426.451268 -264.910062)
		(end 429.270922 -264.910062)
		(width 0.14478)
		(layer "In11.Cu")
		(net "M_L_CPU0_SB_CA<4>")
	)
	(segment
		(start 389.90778 -263.878568)
		(end 389.916162 -263.883394)
		(width 0.0889)
		(layer "In11.Cu")
		(net "M_L_CPU0_SB_CA<4>")
	)
	(segment
		(start 453.763126 -264.060178)
		(end 454.188068 -264.48512)
		(width 0.14478)
		(layer "In11.Cu")
		(net "M_L_CPU0_SB_CA<4>")
	)
	(segment
		(start 386.180838 -263.821418)
		(end 386.20319 -263.90473)
		(width 0.0889)
		(layer "In11.Cu")
		(net "M_L_CPU0_SB_CA<4>")
	)
	(segment
		(start 393.384532 -263.802876)
		(end 395.107414 -263.802876)
		(width 0.0889)
		(layer "In11.Cu")
		(net "M_L_CPU0_SB_CA<4>")
	)
	(segment
		(start 395.48054 -263.42975)
		(end 395.986 -263.42975)
		(width 0.0889)
		(layer "In11.Cu")
		(net "M_L_CPU0_SB_CA<4>")
	)
	(segment
		(start 433.995322 -264.910062)
		(end 436.814976 -264.910062)
		(width 0.14478)
		(layer "In11.Cu")
		(net "M_L_CPU0_SB_CA<4>")
	)
	(segment
		(start 422.576752 -264.060178)
		(end 425.601384 -264.060178)
		(width 0.14478)
		(layer "In11.Cu")
		(net "M_L_CPU0_SB_CA<4>")
	)
	(segment
		(start 395.986 -263.42975)
		(end 410.012642 -263.42975)
		(width 0.14478)
		(layer "In11.Cu")
		(net "M_L_CPU0_SB_CA<4>")
	)
	(segment
		(start 388.393432 -263.883394)
		(end 388.401814 -263.878568)
		(width 0.0889)
		(layer "In11.Cu")
		(net "M_L_CPU0_SB_CA<4>")
	)
	(segment
		(start 421.726868 -264.910062)
		(end 422.576752 -264.060178)
		(width 0.14478)
		(layer "In11.Cu")
		(net "M_L_CPU0_SB_CA<4>")
	)
	(segment
		(start 393.083288 -263.889744)
		(end 393.103354 -263.878314)
		(width 0.0889)
		(layer "In11.Cu")
		(net "M_L_CPU0_SB_CA<4>")
	)
	(segment
		(start 430.120806 -264.060178)
		(end 433.145438 -264.060178)
		(width 0.14478)
		(layer "In11.Cu")
		(net "M_L_CPU0_SB_CA<4>")
	)
	(segment
		(start 395.107414 -263.802876)
		(end 395.48054 -263.42975)
		(width 0.0889)
		(layer "In11.Cu")
		(net "M_L_CPU0_SB_CA<4>")
	)
	(segment
		(start 437.66486 -264.060178)
		(end 453.763126 -264.060178)
		(width 0.14478)
		(layer "In11.Cu")
		(net "M_L_CPU0_SB_CA<4>")
	)
	(segment
		(start 392.706606 -263.864852)
		(end 392.729974 -263.878568)
		(width 0.0889)
		(layer "In11.Cu")
		(net "M_L_CPU0_SB_CA<4>")
	)
	(segment
		(start 436.814976 -264.910062)
		(end 437.66486 -264.060178)
		(width 0.14478)
		(layer "In11.Cu")
		(net "M_L_CPU0_SB_CA<4>")
	)
	(segment
		(start 391.787634 -263.878568)
		(end 391.802112 -263.88695)
		(width 0.0889)
		(layer "In11.Cu")
		(net "M_L_CPU0_SB_CA<4>")
	)
	(segment
		(start 410.012642 -263.42975)
		(end 411.492954 -264.910062)
		(width 0.14478)
		(layer "In11.Cu")
		(net "M_L_CPU0_SB_CA<4>")
	)
	(segment
		(start 411.492954 -264.910062)
		(end 421.726868 -264.910062)
		(width 0.14478)
		(layer "In11.Cu")
		(net "M_L_CPU0_SB_CA<4>")
	)
	(segment
		(start 425.601384 -264.060178)
		(end 426.451268 -264.910062)
		(width 0.14478)
		(layer "In11.Cu")
		(net "M_L_CPU0_SB_CA<4>")
	)
	(arc
		(start 390.281922 -263.878568)
		(mid 390.564878 -263.802391)
		(end 390.847834 -263.878568)
		(width 0.0889)
		(layer "In11.Cu")
		(net "M_L_CPU0_SB_CA<4>")
	)
	(arc
		(start 389.341868 -263.878568)
		(mid 389.624824 -263.802391)
		(end 389.90778 -263.878568)
		(width 0.0889)
		(layer "In11.Cu")
		(net "M_L_CPU0_SB_CA<4>")
	)
	(arc
		(start 391.802112 -263.88695)
		(mid 391.983528 -263.929207)
		(end 392.162792 -263.878568)
		(width 0.0889)
		(layer "In11.Cu")
		(net "M_L_CPU0_SB_CA<4>")
	)
	(arc
		(start 390.847834 -263.878568)
		(mid 391.034778 -263.928823)
		(end 391.221722 -263.878568)
		(width 0.0889)
		(layer "In11.Cu")
		(net "M_L_CPU0_SB_CA<4>")
	)
	(arc
		(start 391.221722 -263.878568)
		(mid 391.504678 -263.802391)
		(end 391.787634 -263.878568)
		(width 0.0889)
		(layer "In11.Cu")
		(net "M_L_CPU0_SB_CA<4>")
	)
	(arc
		(start 392.162792 -263.878568)
		(mid 392.432949 -263.801806)
		(end 392.706606 -263.864852)
		(width 0.0889)
		(layer "In11.Cu")
		(net "M_L_CPU0_SB_CA<4>")
	)
	(arc
		(start 393.103354 -263.878314)
		(mid 393.238987 -263.822139)
		(end 393.384532 -263.802876)
		(width 0.0889)
		(layer "In11.Cu")
		(net "M_L_CPU0_SB_CA<4>")
	)
	(arc
		(start 389.916162 -263.883394)
		(mid 390.09967 -263.928888)
		(end 390.281922 -263.878568)
		(width 0.0889)
		(layer "In11.Cu")
		(net "M_L_CPU0_SB_CA<4>")
	)
	(arc
		(start 388.401814 -263.878568)
		(mid 388.68477 -263.802391)
		(end 388.967726 -263.878568)
		(width 0.0889)
		(layer "In11.Cu")
		(net "M_L_CPU0_SB_CA<4>")
	)
	(arc
		(start 388.967726 -263.878568)
		(mid 389.149977 -263.928918)
		(end 389.333486 -263.883394)
		(width 0.0889)
		(layer "In11.Cu")
		(net "M_L_CPU0_SB_CA<4>")
	)
	(arc
		(start 387.087872 -263.878568)
		(mid 387.274816 -263.928823)
		(end 387.46176 -263.878568)
		(width 0.0889)
		(layer "In11.Cu")
		(net "M_L_CPU0_SB_CA<4>")
	)
	(arc
		(start 388.027672 -263.878568)
		(mid 388.209923 -263.928918)
		(end 388.393432 -263.883394)
		(width 0.0889)
		(layer "In11.Cu")
		(net "M_L_CPU0_SB_CA<4>")
	)
	(arc
		(start 386.52196 -263.878568)
		(mid 386.804916 -263.802391)
		(end 387.087872 -263.878568)
		(width 0.0889)
		(layer "In11.Cu")
		(net "M_L_CPU0_SB_CA<4>")
	)
	(arc
		(start 387.46176 -263.878568)
		(mid 387.744716 -263.802391)
		(end 388.027672 -263.878568)
		(width 0.0889)
		(layer "In11.Cu")
		(net "M_L_CPU0_SB_CA<4>")
	)
	(arc
		(start 386.20319 -263.90473)
		(mid 386.365522 -263.927548)
		(end 386.52196 -263.878568)
		(width 0.0889)
		(layer "In11.Cu")
		(net "M_L_CPU0_SB_CA<4>")
	)
	(arc
		(start 392.729974 -263.878568)
		(mid 392.905213 -263.928639)
		(end 393.083288 -263.889744)
		(width 0.0889)
		(layer "In11.Cu")
		(net "M_L_CPU0_SB_CA<4>")
	)
	(segment
		(start 386.807964 -263.29005)
		(end 387.274816 -263.555988)
		(width 0.10668)
		(layer "F.Cu")
		(net "M_L_CPU0_SB_CA<3>")
	)
	(segment
		(start 411.595062 -264.060178)
		(end 410.509974 -262.97509)
		(width 0.14478)
		(layer "In11.Cu")
		(net "M_L_CPU0_SB_CA<3>")
	)
	(segment
		(start 447.449194 -262.818372)
		(end 447.304414 -262.963152)
		(width 0.14478)
		(layer "In11.Cu")
		(net "M_L_CPU0_SB_CA<3>")
	)
	(segment
		(start 429.177958 -264.060178)
		(end 426.516546 -264.060178)
		(width 0.14478)
		(layer "In11.Cu")
		(net "M_L_CPU0_SB_CA<3>")
	)
	(segment
		(start 445.563752 -262.841232)
		(end 445.301878 -262.841232)
		(width 0.14478)
		(layer "In11.Cu")
		(net "M_L_CPU0_SB_CA<3>")
	)
	(segment
		(start 445.708532 -263.06526)
		(end 445.708532 -262.986012)
		(width 0.14478)
		(layer "In11.Cu")
		(net "M_L_CPU0_SB_CA<3>")
	)
	(segment
		(start 394.105638 -262.925052)
		(end 393.720828 -263.309862)
		(width 0.0889)
		(layer "In11.Cu")
		(net "M_L_CPU0_SB_CA<3>")
	)
	(segment
		(start 389.341868 -263.233408)
		(end 389.333486 -263.228582)
		(width 0.0889)
		(layer "In11.Cu")
		(net "M_L_CPU0_SB_CA<3>")
	)
	(segment
		(start 444.460884 -262.841232)
		(end 444.19901 -262.841232)
		(width 0.14478)
		(layer "In11.Cu")
		(net "M_L_CPU0_SB_CA<3>")
	)
	(segment
		(start 447.304414 -263.06526)
		(end 447.159634 -263.21004)
		(width 0.14478)
		(layer "In11.Cu")
		(net "M_L_CPU0_SB_CA<3>")
	)
	(segment
		(start 448.000628 -263.601708)
		(end 447.855848 -263.456928)
		(width 0.14478)
		(layer "In11.Cu")
		(net "M_L_CPU0_SB_CA<3>")
	)
	(segment
		(start 422.484042 -263.21004)
		(end 421.633904 -264.060178)
		(width 0.14478)
		(layer "In11.Cu")
		(net "M_L_CPU0_SB_CA<3>")
	)
	(segment
		(start 448.407282 -263.456928)
		(end 448.262502 -263.601708)
		(width 0.14478)
		(layer "In11.Cu")
		(net "M_L_CPU0_SB_CA<3>")
	)
	(segment
		(start 450.088 -263.634982)
		(end 449.663058 -263.21004)
		(width 0.14478)
		(layer "In11.Cu")
		(net "M_L_CPU0_SB_CA<3>")
	)
	(segment
		(start 436.722012 -264.060178)
		(end 434.0606 -264.060178)
		(width 0.14478)
		(layer "In11.Cu")
		(net "M_L_CPU0_SB_CA<3>")
	)
	(segment
		(start 430.028096 -263.21004)
		(end 429.177958 -264.060178)
		(width 0.14478)
		(layer "In11.Cu")
		(net "M_L_CPU0_SB_CA<3>")
	)
	(segment
		(start 444.05423 -262.986012)
		(end 444.05423 -263.434068)
		(width 0.14478)
		(layer "In11.Cu")
		(net "M_L_CPU0_SB_CA<3>")
	)
	(segment
		(start 388.401814 -263.233408)
		(end 388.393432 -263.228582)
		(width 0.0889)
		(layer "In11.Cu")
		(net "M_L_CPU0_SB_CA<3>")
	)
	(segment
		(start 387.524752 -263.265158)
		(end 387.42874 -263.290558)
		(width 0.0889)
		(layer "In11.Cu")
		(net "M_L_CPU0_SB_CA<3>")
	)
	(segment
		(start 447.855848 -262.963152)
		(end 447.711068 -262.818372)
		(width 0.14478)
		(layer "In11.Cu")
		(net "M_L_CPU0_SB_CA<3>")
	)
	(segment
		(start 434.0606 -264.060178)
		(end 433.210462 -263.21004)
		(width 0.14478)
		(layer "In11.Cu")
		(net "M_L_CPU0_SB_CA<3>")
	)
	(segment
		(start 392.161522 -263.233662)
		(end 392.145266 -263.224264)
		(width 0.0889)
		(layer "In11.Cu")
		(net "M_L_CPU0_SB_CA<3>")
	)
	(segment
		(start 448.958716 -263.06526)
		(end 448.958716 -262.963152)
		(width 0.14478)
		(layer "In11.Cu")
		(net "M_L_CPU0_SB_CA<3>")
	)
	(segment
		(start 449.663058 -263.21004)
		(end 449.103496 -263.21004)
		(width 0.14478)
		(layer "In11.Cu")
		(net "M_L_CPU0_SB_CA<3>")
	)
	(segment
		(start 445.157098 -262.986012)
		(end 445.157098 -263.434068)
		(width 0.14478)
		(layer "In11.Cu")
		(net "M_L_CPU0_SB_CA<3>")
	)
	(segment
		(start 444.750444 -263.578848)
		(end 444.605664 -263.434068)
		(width 0.14478)
		(layer "In11.Cu")
		(net "M_L_CPU0_SB_CA<3>")
	)
	(segment
		(start 395.44498 -262.925052)
		(end 394.105638 -262.925052)
		(width 0.0889)
		(layer "In11.Cu")
		(net "M_L_CPU0_SB_CA<3>")
	)
	(segment
		(start 448.407282 -262.963152)
		(end 448.407282 -263.456928)
		(width 0.14478)
		(layer "In11.Cu")
		(net "M_L_CPU0_SB_CA<3>")
	)
	(segment
		(start 425.666408 -263.21004)
		(end 422.484042 -263.21004)
		(width 0.14478)
		(layer "In11.Cu")
		(net "M_L_CPU0_SB_CA<3>")
	)
	(segment
		(start 444.605664 -262.986012)
		(end 444.460884 -262.841232)
		(width 0.14478)
		(layer "In11.Cu")
		(net "M_L_CPU0_SB_CA<3>")
	)
	(segment
		(start 444.605664 -263.434068)
		(end 444.605664 -262.986012)
		(width 0.14478)
		(layer "In11.Cu")
		(net "M_L_CPU0_SB_CA<3>")
	)
	(segment
		(start 410.509974 -262.97509)
		(end 395.911832 -262.97509)
		(width 0.14478)
		(layer "In11.Cu")
		(net "M_L_CPU0_SB_CA<3>")
	)
	(segment
		(start 445.012318 -263.578848)
		(end 444.750444 -263.578848)
		(width 0.14478)
		(layer "In11.Cu")
		(net "M_L_CPU0_SB_CA<3>")
	)
	(segment
		(start 421.633904 -264.060178)
		(end 411.595062 -264.060178)
		(width 0.14478)
		(layer "In11.Cu")
		(net "M_L_CPU0_SB_CA<3>")
	)
	(segment
		(start 444.05423 -263.434068)
		(end 443.90945 -263.578848)
		(width 0.14478)
		(layer "In11.Cu")
		(net "M_L_CPU0_SB_CA<3>")
	)
	(segment
		(start 433.210462 -263.21004)
		(end 430.028096 -263.21004)
		(width 0.14478)
		(layer "In11.Cu")
		(net "M_L_CPU0_SB_CA<3>")
	)
	(segment
		(start 447.711068 -262.818372)
		(end 447.449194 -262.818372)
		(width 0.14478)
		(layer "In11.Cu")
		(net "M_L_CPU0_SB_CA<3>")
	)
	(segment
		(start 448.813936 -262.818372)
		(end 448.552062 -262.818372)
		(width 0.14478)
		(layer "In11.Cu")
		(net "M_L_CPU0_SB_CA<3>")
	)
	(segment
		(start 443.502796 -263.35482)
		(end 443.358016 -263.21004)
		(width 0.14478)
		(layer "In11.Cu")
		(net "M_L_CPU0_SB_CA<3>")
	)
	(segment
		(start 443.502796 -263.434068)
		(end 443.502796 -263.35482)
		(width 0.14478)
		(layer "In11.Cu")
		(net "M_L_CPU0_SB_CA<3>")
	)
	(segment
		(start 445.708532 -262.986012)
		(end 445.563752 -262.841232)
		(width 0.14478)
		(layer "In11.Cu")
		(net "M_L_CPU0_SB_CA<3>")
	)
	(segment
		(start 448.262502 -263.601708)
		(end 448.000628 -263.601708)
		(width 0.14478)
		(layer "In11.Cu")
		(net "M_L_CPU0_SB_CA<3>")
	)
	(segment
		(start 393.720828 -263.309862)
		(end 393.384786 -263.309862)
		(width 0.0889)
		(layer "In11.Cu")
		(net "M_L_CPU0_SB_CA<3>")
	)
	(segment
		(start 444.19901 -262.841232)
		(end 444.05423 -262.986012)
		(width 0.14478)
		(layer "In11.Cu")
		(net "M_L_CPU0_SB_CA<3>")
	)
	(segment
		(start 389.916162 -263.228582)
		(end 389.90778 -263.233408)
		(width 0.0889)
		(layer "In11.Cu")
		(net "M_L_CPU0_SB_CA<3>")
	)
	(segment
		(start 447.159634 -263.21004)
		(end 445.853312 -263.21004)
		(width 0.14478)
		(layer "In11.Cu")
		(net "M_L_CPU0_SB_CA<3>")
	)
	(segment
		(start 395.495018 -262.97509)
		(end 395.44498 -262.925052)
		(width 0.0889)
		(layer "In11.Cu")
		(net "M_L_CPU0_SB_CA<3>")
	)
	(segment
		(start 443.647576 -263.578848)
		(end 443.502796 -263.434068)
		(width 0.14478)
		(layer "In11.Cu")
		(net "M_L_CPU0_SB_CA<3>")
	)
	(segment
		(start 449.103496 -263.21004)
		(end 448.958716 -263.06526)
		(width 0.14478)
		(layer "In11.Cu")
		(net "M_L_CPU0_SB_CA<3>")
	)
	(segment
		(start 443.90945 -263.578848)
		(end 443.647576 -263.578848)
		(width 0.14478)
		(layer "In11.Cu")
		(net "M_L_CPU0_SB_CA<3>")
	)
	(segment
		(start 437.57215 -263.21004)
		(end 436.722012 -264.060178)
		(width 0.14478)
		(layer "In11.Cu")
		(net "M_L_CPU0_SB_CA<3>")
	)
	(segment
		(start 447.855848 -263.456928)
		(end 447.855848 -262.963152)
		(width 0.14478)
		(layer "In11.Cu")
		(net "M_L_CPU0_SB_CA<3>")
	)
	(segment
		(start 387.42874 -263.290558)
		(end 387.274816 -263.555988)
		(width 0.0889)
		(layer "In11.Cu")
		(net "M_L_CPU0_SB_CA<3>")
	)
	(segment
		(start 392.17346 -263.24052)
		(end 392.161522 -263.233662)
		(width 0.0889)
		(layer "In11.Cu")
		(net "M_L_CPU0_SB_CA<3>")
	)
	(segment
		(start 395.911832 -262.97509)
		(end 395.495018 -262.97509)
		(width 0.0889)
		(layer "In11.Cu")
		(net "M_L_CPU0_SB_CA<3>")
	)
	(segment
		(start 445.301878 -262.841232)
		(end 445.157098 -262.986012)
		(width 0.14478)
		(layer "In11.Cu")
		(net "M_L_CPU0_SB_CA<3>")
	)
	(segment
		(start 426.516546 -264.060178)
		(end 425.666408 -263.21004)
		(width 0.14478)
		(layer "In11.Cu")
		(net "M_L_CPU0_SB_CA<3>")
	)
	(segment
		(start 445.157098 -263.434068)
		(end 445.012318 -263.578848)
		(width 0.14478)
		(layer "In11.Cu")
		(net "M_L_CPU0_SB_CA<3>")
	)
	(segment
		(start 443.358016 -263.21004)
		(end 437.57215 -263.21004)
		(width 0.14478)
		(layer "In11.Cu")
		(net "M_L_CPU0_SB_CA<3>")
	)
	(segment
		(start 448.958716 -262.963152)
		(end 448.813936 -262.818372)
		(width 0.14478)
		(layer "In11.Cu")
		(net "M_L_CPU0_SB_CA<3>")
	)
	(segment
		(start 445.853312 -263.21004)
		(end 445.708532 -263.06526)
		(width 0.14478)
		(layer "In11.Cu")
		(net "M_L_CPU0_SB_CA<3>")
	)
	(segment
		(start 392.738356 -263.22655)
		(end 392.726672 -263.233408)
		(width 0.0889)
		(layer "In11.Cu")
		(net "M_L_CPU0_SB_CA<3>")
	)
	(segment
		(start 448.552062 -262.818372)
		(end 448.407282 -262.963152)
		(width 0.14478)
		(layer "In11.Cu")
		(net "M_L_CPU0_SB_CA<3>")
	)
	(segment
		(start 447.304414 -262.963152)
		(end 447.304414 -263.06526)
		(width 0.14478)
		(layer "In11.Cu")
		(net "M_L_CPU0_SB_CA<3>")
	)
	(arc
		(start 392.145266 -263.224264)
		(mid 391.965284 -263.183164)
		(end 391.787634 -263.233408)
		(width 0.0889)
		(layer "In11.Cu")
		(net "M_L_CPU0_SB_CA<3>")
	)
	(arc
		(start 391.221722 -263.233408)
		(mid 391.034778 -263.183153)
		(end 390.847834 -263.233408)
		(width 0.0889)
		(layer "In11.Cu")
		(net "M_L_CPU0_SB_CA<3>")
	)
	(arc
		(start 388.967726 -263.233408)
		(mid 388.68477 -263.309585)
		(end 388.401814 -263.233408)
		(width 0.0889)
		(layer "In11.Cu")
		(net "M_L_CPU0_SB_CA<3>")
	)
	(arc
		(start 389.333486 -263.228582)
		(mid 389.149978 -263.183088)
		(end 388.967726 -263.233408)
		(width 0.0889)
		(layer "In11.Cu")
		(net "M_L_CPU0_SB_CA<3>")
	)
	(arc
		(start 390.847834 -263.233408)
		(mid 390.564878 -263.309585)
		(end 390.281922 -263.233408)
		(width 0.0889)
		(layer "In11.Cu")
		(net "M_L_CPU0_SB_CA<3>")
	)
	(arc
		(start 393.384786 -263.309862)
		(mid 393.237855 -263.290451)
		(end 393.101068 -263.233408)
		(width 0.0889)
		(layer "In11.Cu")
		(net "M_L_CPU0_SB_CA<3>")
	)
	(arc
		(start 391.787634 -263.233408)
		(mid 391.504678 -263.309585)
		(end 391.221722 -263.233408)
		(width 0.0889)
		(layer "In11.Cu")
		(net "M_L_CPU0_SB_CA<3>")
	)
	(arc
		(start 390.281922 -263.233408)
		(mid 390.099671 -263.183058)
		(end 389.916162 -263.228582)
		(width 0.0889)
		(layer "In11.Cu")
		(net "M_L_CPU0_SB_CA<3>")
	)
	(arc
		(start 392.726672 -263.233408)
		(mid 392.450994 -263.309538)
		(end 392.17346 -263.24052)
		(width 0.0889)
		(layer "In11.Cu")
		(net "M_L_CPU0_SB_CA<3>")
	)
	(arc
		(start 389.90778 -263.233408)
		(mid 389.624824 -263.309585)
		(end 389.341868 -263.233408)
		(width 0.0889)
		(layer "In11.Cu")
		(net "M_L_CPU0_SB_CA<3>")
	)
	(arc
		(start 393.101068 -263.233408)
		(mid 392.92061 -263.182964)
		(end 392.738356 -263.22655)
		(width 0.0889)
		(layer "In11.Cu")
		(net "M_L_CPU0_SB_CA<3>")
	)
	(arc
		(start 388.027672 -263.233408)
		(mid 387.779959 -263.308628)
		(end 387.524752 -263.265158)
		(width 0.0889)
		(layer "In11.Cu")
		(net "M_L_CPU0_SB_CA<3>")
	)
	(arc
		(start 388.393432 -263.228582)
		(mid 388.209924 -263.183088)
		(end 388.027672 -263.233408)
		(width 0.0889)
		(layer "In11.Cu")
		(net "M_L_CPU0_SB_CA<3>")
	)
	(segment
		(start 387.277864 -262.480044)
		(end 387.744716 -262.745982)
		(width 0.10668)
		(layer "F.Cu")
		(net "M_L_CPU0_SB_CA<2>")
	)
	(segment
		(start 426.451268 -263.21004)
		(end 425.601384 -262.360156)
		(width 0.14478)
		(layer "In11.Cu")
		(net "M_L_CPU0_SB_CA<2>")
	)
	(segment
		(start 395.4526 -262.52043)
		(end 395.238478 -262.734552)
		(width 0.0889)
		(layer "In11.Cu")
		(net "M_L_CPU0_SB_CA<2>")
	)
	(segment
		(start 395.238478 -262.734552)
		(end 394.026644 -262.734552)
		(width 0.0889)
		(layer "In11.Cu")
		(net "M_L_CPU0_SB_CA<2>")
	)
	(segment
		(start 387.590792 -263.011412)
		(end 387.744716 -262.745982)
		(width 0.0889)
		(layer "In11.Cu")
		(net "M_L_CPU0_SB_CA<2>")
	)
	(segment
		(start 394.026644 -262.734552)
		(end 393.641834 -263.119362)
		(width 0.0889)
		(layer "In11.Cu")
		(net "M_L_CPU0_SB_CA<2>")
	)
	(segment
		(start 421.726868 -263.21004)
		(end 411.453838 -263.21004)
		(width 0.14478)
		(layer "In11.Cu")
		(net "M_L_CPU0_SB_CA<2>")
	)
	(segment
		(start 429.270922 -263.21004)
		(end 426.451268 -263.21004)
		(width 0.14478)
		(layer "In11.Cu")
		(net "M_L_CPU0_SB_CA<2>")
	)
	(segment
		(start 392.648694 -263.057894)
		(end 392.63066 -263.068562)
		(width 0.0889)
		(layer "In11.Cu")
		(net "M_L_CPU0_SB_CA<2>")
	)
	(segment
		(start 433.145438 -262.360156)
		(end 430.120806 -262.360156)
		(width 0.14478)
		(layer "In11.Cu")
		(net "M_L_CPU0_SB_CA<2>")
	)
	(segment
		(start 437.66486 -262.360156)
		(end 436.814976 -263.21004)
		(width 0.14478)
		(layer "In11.Cu")
		(net "M_L_CPU0_SB_CA<2>")
	)
	(segment
		(start 387.613144 -263.094724)
		(end 387.590792 -263.011412)
		(width 0.0889)
		(layer "In11.Cu")
		(net "M_L_CPU0_SB_CA<2>")
	)
	(segment
		(start 422.576752 -262.360156)
		(end 421.726868 -263.21004)
		(width 0.14478)
		(layer "In11.Cu")
		(net "M_L_CPU0_SB_CA<2>")
	)
	(segment
		(start 433.995322 -263.21004)
		(end 433.145438 -262.360156)
		(width 0.14478)
		(layer "In11.Cu")
		(net "M_L_CPU0_SB_CA<2>")
	)
	(segment
		(start 425.601384 -262.360156)
		(end 422.576752 -262.360156)
		(width 0.14478)
		(layer "In11.Cu")
		(net "M_L_CPU0_SB_CA<2>")
	)
	(segment
		(start 411.453838 -263.21004)
		(end 410.764228 -262.52043)
		(width 0.14478)
		(layer "In11.Cu")
		(net "M_L_CPU0_SB_CA<2>")
	)
	(segment
		(start 395.97457 -262.52043)
		(end 395.4526 -262.52043)
		(width 0.0889)
		(layer "In11.Cu")
		(net "M_L_CPU0_SB_CA<2>")
	)
	(segment
		(start 410.764228 -262.52043)
		(end 395.97457 -262.52043)
		(width 0.14478)
		(layer "In11.Cu")
		(net "M_L_CPU0_SB_CA<2>")
	)
	(segment
		(start 430.120806 -262.360156)
		(end 429.270922 -263.21004)
		(width 0.14478)
		(layer "In11.Cu")
		(net "M_L_CPU0_SB_CA<2>")
	)
	(segment
		(start 393.641834 -263.119362)
		(end 393.384786 -263.119362)
		(width 0.0889)
		(layer "In11.Cu")
		(net "M_L_CPU0_SB_CA<2>")
	)
	(segment
		(start 453.763126 -262.360156)
		(end 437.66486 -262.360156)
		(width 0.14478)
		(layer "In11.Cu")
		(net "M_L_CPU0_SB_CA<2>")
	)
	(segment
		(start 390.751822 -263.068562)
		(end 390.74344 -263.073388)
		(width 0.0889)
		(layer "In11.Cu")
		(net "M_L_CPU0_SB_CA<2>")
	)
	(segment
		(start 392.270742 -263.076182)
		(end 392.257026 -263.068308)
		(width 0.0889)
		(layer "In11.Cu")
		(net "M_L_CPU0_SB_CA<2>")
	)
	(segment
		(start 436.814976 -263.21004)
		(end 433.995322 -263.21004)
		(width 0.14478)
		(layer "In11.Cu")
		(net "M_L_CPU0_SB_CA<2>")
	)
	(segment
		(start 454.188068 -262.785098)
		(end 453.763126 -262.360156)
		(width 0.14478)
		(layer "In11.Cu")
		(net "M_L_CPU0_SB_CA<2>")
	)
	(segment
		(start 388.506208 -263.073388)
		(end 388.497826 -263.068562)
		(width 0.0889)
		(layer "In11.Cu")
		(net "M_L_CPU0_SB_CA<2>")
	)
	(segment
		(start 391.326116 -263.073388)
		(end 391.317734 -263.068562)
		(width 0.0889)
		(layer "In11.Cu")
		(net "M_L_CPU0_SB_CA<2>")
	)
	(segment
		(start 392.257026 -263.068308)
		(end 392.245088 -263.06145)
		(width 0.0889)
		(layer "In11.Cu")
		(net "M_L_CPU0_SB_CA<2>")
	)
	(arc
		(start 390.74344 -263.073388)
		(mid 390.559932 -263.118882)
		(end 390.37768 -263.068562)
		(width 0.0889)
		(layer "In11.Cu")
		(net "M_L_CPU0_SB_CA<2>")
	)
	(arc
		(start 392.245088 -263.06145)
		(mid 391.967554 -262.992469)
		(end 391.691876 -263.068562)
		(width 0.0889)
		(layer "In11.Cu")
		(net "M_L_CPU0_SB_CA<2>")
	)
	(arc
		(start 388.871968 -263.068562)
		(mid 388.689717 -263.118912)
		(end 388.506208 -263.073388)
		(width 0.0889)
		(layer "In11.Cu")
		(net "M_L_CPU0_SB_CA<2>")
	)
	(arc
		(start 392.63066 -263.068562)
		(mid 392.451673 -263.118732)
		(end 392.270742 -263.076182)
		(width 0.0889)
		(layer "In11.Cu")
		(net "M_L_CPU0_SB_CA<2>")
	)
	(arc
		(start 393.197334 -263.068562)
		(mid 392.92439 -262.991982)
		(end 392.648694 -263.057894)
		(width 0.0889)
		(layer "In11.Cu")
		(net "M_L_CPU0_SB_CA<2>")
	)
	(arc
		(start 389.43788 -263.068562)
		(mid 389.154924 -262.992385)
		(end 388.871968 -263.068562)
		(width 0.0889)
		(layer "In11.Cu")
		(net "M_L_CPU0_SB_CA<2>")
	)
	(arc
		(start 387.931914 -263.068562)
		(mid 387.775476 -263.117533)
		(end 387.613144 -263.094724)
		(width 0.0889)
		(layer "In11.Cu")
		(net "M_L_CPU0_SB_CA<2>")
	)
	(arc
		(start 391.317734 -263.068562)
		(mid 391.034778 -262.992385)
		(end 390.751822 -263.068562)
		(width 0.0889)
		(layer "In11.Cu")
		(net "M_L_CPU0_SB_CA<2>")
	)
	(arc
		(start 389.811768 -263.068562)
		(mid 389.624824 -263.118817)
		(end 389.43788 -263.068562)
		(width 0.0889)
		(layer "In11.Cu")
		(net "M_L_CPU0_SB_CA<2>")
	)
	(arc
		(start 391.691876 -263.068562)
		(mid 391.509625 -263.118912)
		(end 391.326116 -263.073388)
		(width 0.0889)
		(layer "In11.Cu")
		(net "M_L_CPU0_SB_CA<2>")
	)
	(arc
		(start 388.497826 -263.068562)
		(mid 388.21487 -262.992385)
		(end 387.931914 -263.068562)
		(width 0.0889)
		(layer "In11.Cu")
		(net "M_L_CPU0_SB_CA<2>")
	)
	(arc
		(start 393.384786 -263.119362)
		(mid 393.287697 -263.106372)
		(end 393.197334 -263.068562)
		(width 0.0889)
		(layer "In11.Cu")
		(net "M_L_CPU0_SB_CA<2>")
	)
	(arc
		(start 390.37768 -263.068562)
		(mid 390.094724 -262.992385)
		(end 389.811768 -263.068562)
		(width 0.0889)
		(layer "In11.Cu")
		(net "M_L_CPU0_SB_CA<2>")
	)
	(segment
		(start 385.39801 -262.480044)
		(end 385.864862 -262.745982)
		(width 0.10668)
		(layer "F.Cu")
		(net "M_L_CPU0_SB_CA<1>")
	)
	(segment
		(start 448.430904 -261.256272)
		(end 448.575684 -261.111492)
		(width 0.14478)
		(layer "In11.Cu")
		(net "M_L_CPU0_SB_CA<1>")
	)
	(segment
		(start 448.286124 -261.908544)
		(end 448.430904 -261.763764)
		(width 0.14478)
		(layer "In11.Cu")
		(net "M_L_CPU0_SB_CA<1>")
	)
	(segment
		(start 434.0606 -262.360156)
		(end 436.722012 -262.360156)
		(width 0.14478)
		(layer "In11.Cu")
		(net "M_L_CPU0_SB_CA<1>")
	)
	(segment
		(start 433.210462 -261.510018)
		(end 434.0606 -262.360156)
		(width 0.14478)
		(layer "In11.Cu")
		(net "M_L_CPU0_SB_CA<1>")
	)
	(segment
		(start 447.472816 -261.111492)
		(end 447.73469 -261.111492)
		(width 0.14478)
		(layer "In11.Cu")
		(net "M_L_CPU0_SB_CA<1>")
	)
	(segment
		(start 426.516546 -262.360156)
		(end 429.177958 -262.360156)
		(width 0.14478)
		(layer "In11.Cu")
		(net "M_L_CPU0_SB_CA<1>")
	)
	(segment
		(start 447.73469 -261.111492)
		(end 447.87947 -261.256272)
		(width 0.14478)
		(layer "In11.Cu")
		(net "M_L_CPU0_SB_CA<1>")
	)
	(segment
		(start 449.127118 -261.510018)
		(end 449.663058 -261.510018)
		(width 0.14478)
		(layer "In11.Cu")
		(net "M_L_CPU0_SB_CA<1>")
	)
	(segment
		(start 392.619738 -262.41502)
		(end 392.634216 -262.423402)
		(width 0.0889)
		(layer "In11.Cu")
		(net "M_L_CPU0_SB_CA<1>")
	)
	(segment
		(start 449.663058 -261.510018)
		(end 450.088 -261.93496)
		(width 0.14478)
		(layer "In11.Cu")
		(net "M_L_CPU0_SB_CA<1>")
	)
	(segment
		(start 448.837558 -261.111492)
		(end 448.982338 -261.256272)
		(width 0.14478)
		(layer "In11.Cu")
		(net "M_L_CPU0_SB_CA<1>")
	)
	(segment
		(start 390.74344 -262.418576)
		(end 390.751822 -262.423402)
		(width 0.0889)
		(layer "In11.Cu")
		(net "M_L_CPU0_SB_CA<1>")
	)
	(segment
		(start 385.864862 -262.745982)
		(end 386.018786 -262.480552)
		(width 0.0889)
		(layer "In11.Cu")
		(net "M_L_CPU0_SB_CA<1>")
	)
	(segment
		(start 391.691876 -262.423402)
		(end 391.715244 -262.437118)
		(width 0.0889)
		(layer "In11.Cu")
		(net "M_L_CPU0_SB_CA<1>")
	)
	(segment
		(start 386.983478 -262.418576)
		(end 386.99186 -262.423402)
		(width 0.0889)
		(layer "In11.Cu")
		(net "M_L_CPU0_SB_CA<1>")
	)
	(segment
		(start 447.87947 -261.256272)
		(end 447.87947 -261.763764)
		(width 0.14478)
		(layer "In11.Cu")
		(net "M_L_CPU0_SB_CA<1>")
	)
	(segment
		(start 421.633904 -262.360156)
		(end 422.484042 -261.510018)
		(width 0.14478)
		(layer "In11.Cu")
		(net "M_L_CPU0_SB_CA<1>")
	)
	(segment
		(start 387.557772 -262.423402)
		(end 387.566154 -262.418576)
		(width 0.0889)
		(layer "In11.Cu")
		(net "M_L_CPU0_SB_CA<1>")
	)
	(segment
		(start 447.328036 -261.365238)
		(end 447.328036 -261.256272)
		(width 0.14478)
		(layer "In11.Cu")
		(net "M_L_CPU0_SB_CA<1>")
	)
	(segment
		(start 395.147546 -262.373364)
		(end 395.45514 -262.06577)
		(width 0.0889)
		(layer "In11.Cu")
		(net "M_L_CPU0_SB_CA<1>")
	)
	(segment
		(start 412.129478 -262.360156)
		(end 421.633904 -262.360156)
		(width 0.14478)
		(layer "In11.Cu")
		(net "M_L_CPU0_SB_CA<1>")
	)
	(segment
		(start 436.722012 -262.360156)
		(end 437.57215 -261.510018)
		(width 0.14478)
		(layer "In11.Cu")
		(net "M_L_CPU0_SB_CA<1>")
	)
	(segment
		(start 388.497826 -262.423402)
		(end 388.506208 -262.418576)
		(width 0.0889)
		(layer "In11.Cu")
		(net "M_L_CPU0_SB_CA<1>")
	)
	(segment
		(start 448.575684 -261.111492)
		(end 448.837558 -261.111492)
		(width 0.14478)
		(layer "In11.Cu")
		(net "M_L_CPU0_SB_CA<1>")
	)
	(segment
		(start 411.835092 -262.06577)
		(end 412.129478 -262.360156)
		(width 0.14478)
		(layer "In11.Cu")
		(net "M_L_CPU0_SB_CA<1>")
	)
	(segment
		(start 447.87947 -261.763764)
		(end 448.02425 -261.908544)
		(width 0.14478)
		(layer "In11.Cu")
		(net "M_L_CPU0_SB_CA<1>")
	)
	(segment
		(start 437.57215 -261.510018)
		(end 447.183256 -261.510018)
		(width 0.14478)
		(layer "In11.Cu")
		(net "M_L_CPU0_SB_CA<1>")
	)
	(segment
		(start 430.028096 -261.510018)
		(end 433.210462 -261.510018)
		(width 0.14478)
		(layer "In11.Cu")
		(net "M_L_CPU0_SB_CA<1>")
	)
	(segment
		(start 391.317734 -262.423402)
		(end 391.326116 -262.418576)
		(width 0.0889)
		(layer "In11.Cu")
		(net "M_L_CPU0_SB_CA<1>")
	)
	(segment
		(start 429.177958 -262.360156)
		(end 430.028096 -261.510018)
		(width 0.14478)
		(layer "In11.Cu")
		(net "M_L_CPU0_SB_CA<1>")
	)
	(segment
		(start 393.384786 -262.373364)
		(end 395.147546 -262.373364)
		(width 0.0889)
		(layer "In11.Cu")
		(net "M_L_CPU0_SB_CA<1>")
	)
	(segment
		(start 422.484042 -261.510018)
		(end 425.666408 -261.510018)
		(width 0.14478)
		(layer "In11.Cu")
		(net "M_L_CPU0_SB_CA<1>")
	)
	(segment
		(start 448.02425 -261.908544)
		(end 448.286124 -261.908544)
		(width 0.14478)
		(layer "In11.Cu")
		(net "M_L_CPU0_SB_CA<1>")
	)
	(segment
		(start 448.430904 -261.763764)
		(end 448.430904 -261.256272)
		(width 0.14478)
		(layer "In11.Cu")
		(net "M_L_CPU0_SB_CA<1>")
	)
	(segment
		(start 448.982338 -261.256272)
		(end 448.982338 -261.365238)
		(width 0.14478)
		(layer "In11.Cu")
		(net "M_L_CPU0_SB_CA<1>")
	)
	(segment
		(start 425.666408 -261.510018)
		(end 426.516546 -262.360156)
		(width 0.14478)
		(layer "In11.Cu")
		(net "M_L_CPU0_SB_CA<1>")
	)
	(segment
		(start 386.018786 -262.480552)
		(end 386.114798 -262.455152)
		(width 0.0889)
		(layer "In11.Cu")
		(net "M_L_CPU0_SB_CA<1>")
	)
	(segment
		(start 448.982338 -261.365238)
		(end 449.127118 -261.510018)
		(width 0.14478)
		(layer "In11.Cu")
		(net "M_L_CPU0_SB_CA<1>")
	)
	(segment
		(start 395.45514 -262.06577)
		(end 395.970252 -262.06577)
		(width 0.0889)
		(layer "In11.Cu")
		(net "M_L_CPU0_SB_CA<1>")
	)
	(segment
		(start 447.183256 -261.510018)
		(end 447.328036 -261.365238)
		(width 0.14478)
		(layer "In11.Cu")
		(net "M_L_CPU0_SB_CA<1>")
	)
	(segment
		(start 393.177014 -262.436102)
		(end 393.198604 -262.423656)
		(width 0.0889)
		(layer "In11.Cu")
		(net "M_L_CPU0_SB_CA<1>")
	)
	(segment
		(start 395.970252 -262.06577)
		(end 411.835092 -262.06577)
		(width 0.14478)
		(layer "In11.Cu")
		(net "M_L_CPU0_SB_CA<1>")
	)
	(segment
		(start 447.328036 -261.256272)
		(end 447.472816 -261.111492)
		(width 0.14478)
		(layer "In11.Cu")
		(net "M_L_CPU0_SB_CA<1>")
	)
	(arc
		(start 389.43788 -262.423402)
		(mid 389.624824 -262.373147)
		(end 389.811768 -262.423402)
		(width 0.0889)
		(layer "In11.Cu")
		(net "M_L_CPU0_SB_CA<1>")
	)
	(arc
		(start 386.114798 -262.455152)
		(mid 386.370006 -262.498629)
		(end 386.617718 -262.423402)
		(width 0.0889)
		(layer "In11.Cu")
		(net "M_L_CPU0_SB_CA<1>")
	)
	(arc
		(start 389.811768 -262.423402)
		(mid 390.094724 -262.499579)
		(end 390.37768 -262.423402)
		(width 0.0889)
		(layer "In11.Cu")
		(net "M_L_CPU0_SB_CA<1>")
	)
	(arc
		(start 387.566154 -262.418576)
		(mid 387.749662 -262.373082)
		(end 387.931914 -262.423402)
		(width 0.0889)
		(layer "In11.Cu")
		(net "M_L_CPU0_SB_CA<1>")
	)
	(arc
		(start 392.634216 -262.423402)
		(mid 392.903985 -262.499425)
		(end 393.177014 -262.436102)
		(width 0.0889)
		(layer "In11.Cu")
		(net "M_L_CPU0_SB_CA<1>")
	)
	(arc
		(start 392.259058 -262.423402)
		(mid 392.438321 -262.372738)
		(end 392.619738 -262.41502)
		(width 0.0889)
		(layer "In11.Cu")
		(net "M_L_CPU0_SB_CA<1>")
	)
	(arc
		(start 390.37768 -262.423402)
		(mid 390.559931 -262.373052)
		(end 390.74344 -262.418576)
		(width 0.0889)
		(layer "In11.Cu")
		(net "M_L_CPU0_SB_CA<1>")
	)
	(arc
		(start 393.198604 -262.423656)
		(mid 393.288381 -262.386233)
		(end 393.384786 -262.373364)
		(width 0.0889)
		(layer "In11.Cu")
		(net "M_L_CPU0_SB_CA<1>")
	)
	(arc
		(start 391.715244 -262.437118)
		(mid 391.988898 -262.500061)
		(end 392.259058 -262.423402)
		(width 0.0889)
		(layer "In11.Cu")
		(net "M_L_CPU0_SB_CA<1>")
	)
	(arc
		(start 386.617718 -262.423402)
		(mid 386.799969 -262.373052)
		(end 386.983478 -262.418576)
		(width 0.0889)
		(layer "In11.Cu")
		(net "M_L_CPU0_SB_CA<1>")
	)
	(arc
		(start 386.99186 -262.423402)
		(mid 387.274816 -262.499579)
		(end 387.557772 -262.423402)
		(width 0.0889)
		(layer "In11.Cu")
		(net "M_L_CPU0_SB_CA<1>")
	)
	(arc
		(start 387.931914 -262.423402)
		(mid 388.21487 -262.499579)
		(end 388.497826 -262.423402)
		(width 0.0889)
		(layer "In11.Cu")
		(net "M_L_CPU0_SB_CA<1>")
	)
	(arc
		(start 390.751822 -262.423402)
		(mid 391.034778 -262.499579)
		(end 391.317734 -262.423402)
		(width 0.0889)
		(layer "In11.Cu")
		(net "M_L_CPU0_SB_CA<1>")
	)
	(arc
		(start 388.506208 -262.418576)
		(mid 388.689716 -262.373082)
		(end 388.871968 -262.423402)
		(width 0.0889)
		(layer "In11.Cu")
		(net "M_L_CPU0_SB_CA<1>")
	)
	(arc
		(start 388.871968 -262.423402)
		(mid 389.154924 -262.499579)
		(end 389.43788 -262.423402)
		(width 0.0889)
		(layer "In11.Cu")
		(net "M_L_CPU0_SB_CA<1>")
	)
	(arc
		(start 391.326116 -262.418576)
		(mid 391.509624 -262.373082)
		(end 391.691876 -262.423402)
		(width 0.0889)
		(layer "In11.Cu")
		(net "M_L_CPU0_SB_CA<1>")
	)
	(segment
		(start 385.86791 -261.670038)
		(end 386.334762 -261.935976)
		(width 0.10668)
		(layer "F.Cu")
		(net "M_L_CPU0_SB_CA<0>")
	)
	(segment
		(start 433.995322 -261.510018)
		(end 436.814976 -261.510018)
		(width 0.14478)
		(layer "In11.Cu")
		(net "M_L_CPU0_SB_CA<0>")
	)
	(segment
		(start 395.983206 -261.612634)
		(end 410.762704 -261.612634)
		(width 0.14478)
		(layer "In11.Cu")
		(net "M_L_CPU0_SB_CA<0>")
	)
	(segment
		(start 393.544044 -262.140192)
		(end 394.980668 -262.140192)
		(width 0.0889)
		(layer "In11.Cu")
		(net "M_L_CPU0_SB_CA<0>")
	)
	(segment
		(start 429.270922 -261.510018)
		(end 430.120806 -260.660134)
		(width 0.14478)
		(layer "In11.Cu")
		(net "M_L_CPU0_SB_CA<0>")
	)
	(segment
		(start 422.576752 -260.660134)
		(end 425.601384 -260.660134)
		(width 0.14478)
		(layer "In11.Cu")
		(net "M_L_CPU0_SB_CA<0>")
	)
	(segment
		(start 393.083288 -262.269732)
		(end 393.103354 -262.258302)
		(width 0.0889)
		(layer "In11.Cu")
		(net "M_L_CPU0_SB_CA<0>")
	)
	(segment
		(start 395.555216 -261.612634)
		(end 395.983206 -261.612634)
		(width 0.0889)
		(layer "In11.Cu")
		(net "M_L_CPU0_SB_CA<0>")
	)
	(segment
		(start 389.333486 -262.263382)
		(end 389.341868 -262.258556)
		(width 0.0889)
		(layer "In11.Cu")
		(net "M_L_CPU0_SB_CA<0>")
	)
	(segment
		(start 425.601384 -260.660134)
		(end 426.451268 -261.510018)
		(width 0.14478)
		(layer "In11.Cu")
		(net "M_L_CPU0_SB_CA<0>")
	)
	(segment
		(start 437.66486 -260.660134)
		(end 453.763126 -260.660134)
		(width 0.14478)
		(layer "In11.Cu")
		(net "M_L_CPU0_SB_CA<0>")
	)
	(segment
		(start 389.90778 -262.258556)
		(end 389.916162 -262.263382)
		(width 0.0889)
		(layer "In11.Cu")
		(net "M_L_CPU0_SB_CA<0>")
	)
	(segment
		(start 388.393432 -262.263382)
		(end 388.401814 -262.258556)
		(width 0.0889)
		(layer "In11.Cu")
		(net "M_L_CPU0_SB_CA<0>")
	)
	(segment
		(start 453.763126 -260.660134)
		(end 454.188068 -261.085076)
		(width 0.14478)
		(layer "In11.Cu")
		(net "M_L_CPU0_SB_CA<0>")
	)
	(segment
		(start 386.180838 -262.201406)
		(end 386.20319 -262.284718)
		(width 0.0889)
		(layer "In11.Cu")
		(net "M_L_CPU0_SB_CA<0>")
	)
	(segment
		(start 426.451268 -261.510018)
		(end 429.270922 -261.510018)
		(width 0.14478)
		(layer "In11.Cu")
		(net "M_L_CPU0_SB_CA<0>")
	)
	(segment
		(start 392.706606 -262.24484)
		(end 392.729974 -262.258556)
		(width 0.0889)
		(layer "In11.Cu")
		(net "M_L_CPU0_SB_CA<0>")
	)
	(segment
		(start 410.86532 -261.510018)
		(end 421.726868 -261.510018)
		(width 0.14478)
		(layer "In11.Cu")
		(net "M_L_CPU0_SB_CA<0>")
	)
	(segment
		(start 433.145438 -260.660134)
		(end 433.995322 -261.510018)
		(width 0.14478)
		(layer "In11.Cu")
		(net "M_L_CPU0_SB_CA<0>")
	)
	(segment
		(start 410.762704 -261.612634)
		(end 410.86532 -261.510018)
		(width 0.14478)
		(layer "In11.Cu")
		(net "M_L_CPU0_SB_CA<0>")
	)
	(segment
		(start 436.814976 -261.510018)
		(end 437.66486 -260.660134)
		(width 0.14478)
		(layer "In11.Cu")
		(net "M_L_CPU0_SB_CA<0>")
	)
	(segment
		(start 430.120806 -260.660134)
		(end 433.145438 -260.660134)
		(width 0.14478)
		(layer "In11.Cu")
		(net "M_L_CPU0_SB_CA<0>")
	)
	(segment
		(start 391.787634 -262.258556)
		(end 391.802112 -262.266938)
		(width 0.0889)
		(layer "In11.Cu")
		(net "M_L_CPU0_SB_CA<0>")
	)
	(segment
		(start 395.060932 -262.106918)
		(end 395.555216 -261.612634)
		(width 0.0889)
		(layer "In11.Cu")
		(net "M_L_CPU0_SB_CA<0>")
	)
	(segment
		(start 386.334762 -261.935976)
		(end 386.180838 -262.201406)
		(width 0.0889)
		(layer "In11.Cu")
		(net "M_L_CPU0_SB_CA<0>")
	)
	(segment
		(start 421.726868 -261.510018)
		(end 422.576752 -260.660134)
		(width 0.14478)
		(layer "In11.Cu")
		(net "M_L_CPU0_SB_CA<0>")
	)
	(arc
		(start 393.103354 -262.258302)
		(mid 393.31593 -262.170274)
		(end 393.544044 -262.140192)
		(width 0.0889)
		(layer "In11.Cu")
		(net "M_L_CPU0_SB_CA<0>")
	)
	(arc
		(start 387.087872 -262.258556)
		(mid 387.274816 -262.308811)
		(end 387.46176 -262.258556)
		(width 0.0889)
		(layer "In11.Cu")
		(net "M_L_CPU0_SB_CA<0>")
	)
	(arc
		(start 386.52196 -262.258556)
		(mid 386.804916 -262.182379)
		(end 387.087872 -262.258556)
		(width 0.0889)
		(layer "In11.Cu")
		(net "M_L_CPU0_SB_CA<0>")
	)
	(arc
		(start 387.46176 -262.258556)
		(mid 387.744716 -262.182379)
		(end 388.027672 -262.258556)
		(width 0.0889)
		(layer "In11.Cu")
		(net "M_L_CPU0_SB_CA<0>")
	)
	(arc
		(start 392.162792 -262.258556)
		(mid 392.432949 -262.181794)
		(end 392.706606 -262.24484)
		(width 0.0889)
		(layer "In11.Cu")
		(net "M_L_CPU0_SB_CA<0>")
	)
	(arc
		(start 390.281922 -262.258556)
		(mid 390.564878 -262.182379)
		(end 390.847834 -262.258556)
		(width 0.0889)
		(layer "In11.Cu")
		(net "M_L_CPU0_SB_CA<0>")
	)
	(arc
		(start 391.221722 -262.258556)
		(mid 391.504678 -262.182379)
		(end 391.787634 -262.258556)
		(width 0.0889)
		(layer "In11.Cu")
		(net "M_L_CPU0_SB_CA<0>")
	)
	(arc
		(start 389.916162 -262.263382)
		(mid 390.09967 -262.308876)
		(end 390.281922 -262.258556)
		(width 0.0889)
		(layer "In11.Cu")
		(net "M_L_CPU0_SB_CA<0>")
	)
	(arc
		(start 388.401814 -262.258556)
		(mid 388.68477 -262.182379)
		(end 388.967726 -262.258556)
		(width 0.0889)
		(layer "In11.Cu")
		(net "M_L_CPU0_SB_CA<0>")
	)
	(arc
		(start 391.802112 -262.266938)
		(mid 391.983528 -262.309195)
		(end 392.162792 -262.258556)
		(width 0.0889)
		(layer "In11.Cu")
		(net "M_L_CPU0_SB_CA<0>")
	)
	(arc
		(start 389.341868 -262.258556)
		(mid 389.624824 -262.182379)
		(end 389.90778 -262.258556)
		(width 0.0889)
		(layer "In11.Cu")
		(net "M_L_CPU0_SB_CA<0>")
	)
	(arc
		(start 388.027672 -262.258556)
		(mid 388.209923 -262.308906)
		(end 388.393432 -262.263382)
		(width 0.0889)
		(layer "In11.Cu")
		(net "M_L_CPU0_SB_CA<0>")
	)
	(arc
		(start 386.20319 -262.284718)
		(mid 386.365522 -262.307536)
		(end 386.52196 -262.258556)
		(width 0.0889)
		(layer "In11.Cu")
		(net "M_L_CPU0_SB_CA<0>")
	)
	(arc
		(start 390.847834 -262.258556)
		(mid 391.034778 -262.308811)
		(end 391.221722 -262.258556)
		(width 0.0889)
		(layer "In11.Cu")
		(net "M_L_CPU0_SB_CA<0>")
	)
	(arc
		(start 388.967726 -262.258556)
		(mid 389.149977 -262.308906)
		(end 389.333486 -262.263382)
		(width 0.0889)
		(layer "In11.Cu")
		(net "M_L_CPU0_SB_CA<0>")
	)
	(arc
		(start 392.729974 -262.258556)
		(mid 392.905213 -262.308627)
		(end 393.083288 -262.269732)
		(width 0.0889)
		(layer "In11.Cu")
		(net "M_L_CPU0_SB_CA<0>")
	)
	(arc
		(start 394.980668 -262.140192)
		(mid 395.024103 -262.131534)
		(end 395.060932 -262.106918)
		(width 0.0889)
		(layer "In11.Cu")
		(net "M_L_CPU0_SB_CA<0>")
	)
	(segment
		(start 385.86791 -266.530074)
		(end 386.334762 -266.796012)
		(width 0.10668)
		(layer "F.Cu")
		(net "M_L_CPU0_SA_RSP<0>")
	)
	(segment
		(start 389.333486 -267.123418)
		(end 389.341868 -267.118592)
		(width 0.0889)
		(layer "In11.Cu")
		(net "M_L_CPU0_SA_RSP<0>")
	)
	(segment
		(start 388.393432 -267.123418)
		(end 388.401814 -267.118592)
		(width 0.0889)
		(layer "In11.Cu")
		(net "M_L_CPU0_SA_RSP<0>")
	)
	(segment
		(start 433.210462 -269.160244)
		(end 434.0606 -270.010382)
		(width 0.11684)
		(layer "In11.Cu")
		(net "M_L_CPU0_SA_RSP<0>")
	)
	(segment
		(start 393.102084 -267.118592)
		(end 394.356844 -265.863832)
		(width 0.0889)
		(layer "In11.Cu")
		(net "M_L_CPU0_SA_RSP<0>")
	)
	(segment
		(start 386.180838 -267.061442)
		(end 386.20319 -267.144754)
		(width 0.0889)
		(layer "In11.Cu")
		(net "M_L_CPU0_SA_RSP<0>")
	)
	(segment
		(start 395.329918 -265.863832)
		(end 395.609826 -266.14374)
		(width 0.0889)
		(layer "In11.Cu")
		(net "M_L_CPU0_SA_RSP<0>")
	)
	(segment
		(start 393.0904 -267.12545)
		(end 393.102084 -267.118592)
		(width 0.0889)
		(layer "In11.Cu")
		(net "M_L_CPU0_SA_RSP<0>")
	)
	(segment
		(start 422.484042 -269.160244)
		(end 425.666408 -269.160244)
		(width 0.11684)
		(layer "In11.Cu")
		(net "M_L_CPU0_SA_RSP<0>")
	)
	(segment
		(start 452.050912 -269.160244)
		(end 454.188068 -269.585186)
		(width 0.11684)
		(layer "In11.Cu")
		(net "M_L_CPU0_SA_RSP<0>")
	)
	(segment
		(start 436.250588 -270.010382)
		(end 438.303162 -269.160244)
		(width 0.11684)
		(layer "In11.Cu")
		(net "M_L_CPU0_SA_RSP<0>")
	)
	(segment
		(start 429.177958 -270.010382)
		(end 430.028096 -269.160244)
		(width 0.11684)
		(layer "In11.Cu")
		(net "M_L_CPU0_SA_RSP<0>")
	)
	(segment
		(start 434.0606 -270.010382)
		(end 436.250588 -270.010382)
		(width 0.11684)
		(layer "In11.Cu")
		(net "M_L_CPU0_SA_RSP<0>")
	)
	(segment
		(start 386.334762 -266.796012)
		(end 386.180838 -267.061442)
		(width 0.0889)
		(layer "In11.Cu")
		(net "M_L_CPU0_SA_RSP<0>")
	)
	(segment
		(start 425.666408 -269.160244)
		(end 426.516546 -270.010382)
		(width 0.11684)
		(layer "In11.Cu")
		(net "M_L_CPU0_SA_RSP<0>")
	)
	(segment
		(start 394.356844 -265.863832)
		(end 395.329918 -265.863832)
		(width 0.0889)
		(layer "In11.Cu")
		(net "M_L_CPU0_SA_RSP<0>")
	)
	(segment
		(start 411.595062 -270.010382)
		(end 421.633904 -270.010382)
		(width 0.11684)
		(layer "In11.Cu")
		(net "M_L_CPU0_SA_RSP<0>")
	)
	(segment
		(start 407.72842 -266.14374)
		(end 411.595062 -270.010382)
		(width 0.11684)
		(layer "In11.Cu")
		(net "M_L_CPU0_SA_RSP<0>")
	)
	(segment
		(start 389.90778 -267.118592)
		(end 389.916162 -267.123418)
		(width 0.0889)
		(layer "In11.Cu")
		(net "M_L_CPU0_SA_RSP<0>")
	)
	(segment
		(start 421.633904 -270.010382)
		(end 422.484042 -269.160244)
		(width 0.11684)
		(layer "In11.Cu")
		(net "M_L_CPU0_SA_RSP<0>")
	)
	(segment
		(start 395.94028 -266.14374)
		(end 407.72842 -266.14374)
		(width 0.11684)
		(layer "In11.Cu")
		(net "M_L_CPU0_SA_RSP<0>")
	)
	(segment
		(start 392.717782 -267.112496)
		(end 392.728196 -267.118592)
		(width 0.0889)
		(layer "In11.Cu")
		(net "M_L_CPU0_SA_RSP<0>")
	)
	(segment
		(start 438.303162 -269.160244)
		(end 452.050912 -269.160244)
		(width 0.11684)
		(layer "In11.Cu")
		(net "M_L_CPU0_SA_RSP<0>")
	)
	(segment
		(start 395.609826 -266.14374)
		(end 395.94028 -266.14374)
		(width 0.0889)
		(layer "In11.Cu")
		(net "M_L_CPU0_SA_RSP<0>")
	)
	(segment
		(start 430.028096 -269.160244)
		(end 433.210462 -269.160244)
		(width 0.11684)
		(layer "In11.Cu")
		(net "M_L_CPU0_SA_RSP<0>")
	)
	(segment
		(start 426.516546 -270.010382)
		(end 429.177958 -270.010382)
		(width 0.11684)
		(layer "In11.Cu")
		(net "M_L_CPU0_SA_RSP<0>")
	)
	(arc
		(start 389.341868 -267.118592)
		(mid 389.624824 -267.042415)
		(end 389.90778 -267.118592)
		(width 0.0889)
		(layer "In11.Cu")
		(net "M_L_CPU0_SA_RSP<0>")
	)
	(arc
		(start 391.787634 -267.118592)
		(mid 391.974832 -267.168974)
		(end 392.16203 -267.118592)
		(width 0.0889)
		(layer "In11.Cu")
		(net "M_L_CPU0_SA_RSP<0>")
	)
	(arc
		(start 387.087872 -267.118592)
		(mid 387.274816 -267.168847)
		(end 387.46176 -267.118592)
		(width 0.0889)
		(layer "In11.Cu")
		(net "M_L_CPU0_SA_RSP<0>")
	)
	(arc
		(start 391.221722 -267.118592)
		(mid 391.504678 -267.042415)
		(end 391.787634 -267.118592)
		(width 0.0889)
		(layer "In11.Cu")
		(net "M_L_CPU0_SA_RSP<0>")
	)
	(arc
		(start 388.027672 -267.118592)
		(mid 388.209923 -267.168942)
		(end 388.393432 -267.123418)
		(width 0.0889)
		(layer "In11.Cu")
		(net "M_L_CPU0_SA_RSP<0>")
	)
	(arc
		(start 388.401814 -267.118592)
		(mid 388.68477 -267.042415)
		(end 388.967726 -267.118592)
		(width 0.0889)
		(layer "In11.Cu")
		(net "M_L_CPU0_SA_RSP<0>")
	)
	(arc
		(start 388.967726 -267.118592)
		(mid 389.149977 -267.168942)
		(end 389.333486 -267.123418)
		(width 0.0889)
		(layer "In11.Cu")
		(net "M_L_CPU0_SA_RSP<0>")
	)
	(arc
		(start 386.52196 -267.118592)
		(mid 386.804916 -267.042415)
		(end 387.087872 -267.118592)
		(width 0.0889)
		(layer "In11.Cu")
		(net "M_L_CPU0_SA_RSP<0>")
	)
	(arc
		(start 392.16203 -267.118592)
		(mid 392.439097 -267.042321)
		(end 392.717782 -267.112496)
		(width 0.0889)
		(layer "In11.Cu")
		(net "M_L_CPU0_SA_RSP<0>")
	)
	(arc
		(start 390.847834 -267.118592)
		(mid 391.034778 -267.168847)
		(end 391.221722 -267.118592)
		(width 0.0889)
		(layer "In11.Cu")
		(net "M_L_CPU0_SA_RSP<0>")
	)
	(arc
		(start 387.46176 -267.118592)
		(mid 387.744716 -267.042415)
		(end 388.027672 -267.118592)
		(width 0.0889)
		(layer "In11.Cu")
		(net "M_L_CPU0_SA_RSP<0>")
	)
	(arc
		(start 386.20319 -267.144754)
		(mid 386.365522 -267.167572)
		(end 386.52196 -267.118592)
		(width 0.0889)
		(layer "In11.Cu")
		(net "M_L_CPU0_SA_RSP<0>")
	)
	(arc
		(start 389.916162 -267.123418)
		(mid 390.09967 -267.168912)
		(end 390.281922 -267.118592)
		(width 0.0889)
		(layer "In11.Cu")
		(net "M_L_CPU0_SA_RSP<0>")
	)
	(arc
		(start 390.281922 -267.118592)
		(mid 390.564878 -267.042415)
		(end 390.847834 -267.118592)
		(width 0.0889)
		(layer "In11.Cu")
		(net "M_L_CPU0_SA_RSP<0>")
	)
	(arc
		(start 392.728196 -267.118592)
		(mid 392.908401 -267.168909)
		(end 393.0904 -267.12545)
		(width 0.0889)
		(layer "In11.Cu")
		(net "M_L_CPU0_SA_RSP<0>")
	)
	(segment
		(start 385.567936 -256.090166)
		(end 386.034788 -255.824228)
		(width 0.10668)
		(layer "F.Cu")
		(net "M_L_CPU0_SA_PAR")
	)
	(segment
		(start 385.880864 -255.558798)
		(end 385.903216 -255.475486)
		(width 0.0889)
		(layer "In11.Cu")
		(net "M_L_CPU0_SA_PAR")
	)
	(segment
		(start 398.926304 -256.551684)
		(end 400.324828 -255.15316)
		(width 0.14478)
		(layer "In11.Cu")
		(net "M_L_CPU0_SA_PAR")
	)
	(segment
		(start 389.607806 -255.501648)
		(end 389.616188 -255.496822)
		(width 0.0889)
		(layer "In11.Cu")
		(net "M_L_CPU0_SA_PAR")
	)
	(segment
		(start 388.093458 -255.496822)
		(end 388.10184 -255.501648)
		(width 0.0889)
		(layer "In11.Cu")
		(net "M_L_CPU0_SA_PAR")
	)
	(segment
		(start 406.424638 -255.15316)
		(end 406.84323 -255.571752)
		(width 0.14478)
		(layer "In11.Cu")
		(net "M_L_CPU0_SA_PAR")
	)
	(segment
		(start 395.759686 -256.551684)
		(end 398.926304 -256.551684)
		(width 0.14478)
		(layer "In11.Cu")
		(net "M_L_CPU0_SA_PAR")
	)
	(segment
		(start 389.033512 -255.496822)
		(end 389.041894 -255.501648)
		(width 0.0889)
		(layer "In11.Cu")
		(net "M_L_CPU0_SA_PAR")
	)
	(segment
		(start 393.084812 -255.577594)
		(end 393.61618 -255.577594)
		(width 0.0889)
		(layer "In11.Cu")
		(net "M_L_CPU0_SA_PAR")
	)
	(segment
		(start 392.417808 -255.507744)
		(end 392.428222 -255.501648)
		(width 0.0889)
		(layer "In11.Cu")
		(net "M_L_CPU0_SA_PAR")
	)
	(segment
		(start 393.61618 -255.577594)
		(end 394.59027 -256.551684)
		(width 0.0889)
		(layer "In11.Cu")
		(net "M_L_CPU0_SA_PAR")
	)
	(segment
		(start 448.639438 -253.010162)
		(end 451.11035 -253.010162)
		(width 0.14478)
		(layer "In11.Cu")
		(net "M_L_CPU0_SA_PAR")
	)
	(segment
		(start 447.783204 -254.694436)
		(end 447.783204 -253.866396)
		(width 0.14478)
		(layer "In11.Cu")
		(net "M_L_CPU0_SA_PAR")
	)
	(segment
		(start 386.034788 -255.824228)
		(end 385.880864 -255.558798)
		(width 0.0889)
		(layer "In11.Cu")
		(net "M_L_CPU0_SA_PAR")
	)
	(segment
		(start 451.11035 -253.010162)
		(end 454.188068 -254.284988)
		(width 0.14478)
		(layer "In11.Cu")
		(net "M_L_CPU0_SA_PAR")
	)
	(segment
		(start 447.783204 -253.866396)
		(end 448.639438 -253.010162)
		(width 0.14478)
		(layer "In11.Cu")
		(net "M_L_CPU0_SA_PAR")
	)
	(segment
		(start 446.905888 -255.571752)
		(end 447.783204 -254.694436)
		(width 0.14478)
		(layer "In11.Cu")
		(net "M_L_CPU0_SA_PAR")
	)
	(segment
		(start 406.84323 -255.571752)
		(end 446.905888 -255.571752)
		(width 0.14478)
		(layer "In11.Cu")
		(net "M_L_CPU0_SA_PAR")
	)
	(segment
		(start 400.324828 -255.15316)
		(end 406.424638 -255.15316)
		(width 0.14478)
		(layer "In11.Cu")
		(net "M_L_CPU0_SA_PAR")
	)
	(segment
		(start 394.59027 -256.551684)
		(end 395.759686 -256.551684)
		(width 0.0889)
		(layer "In11.Cu")
		(net "M_L_CPU0_SA_PAR")
	)
	(arc
		(start 385.903216 -255.475486)
		(mid 386.065548 -255.452668)
		(end 386.221986 -255.501648)
		(width 0.0889)
		(layer "In11.Cu")
		(net "M_L_CPU0_SA_PAR")
	)
	(arc
		(start 392.80211 -255.501648)
		(mid 392.938444 -255.558291)
		(end 393.084812 -255.577594)
		(width 0.0889)
		(layer "In11.Cu")
		(net "M_L_CPU0_SA_PAR")
	)
	(arc
		(start 386.221986 -255.501648)
		(mid 386.504942 -255.577825)
		(end 386.787898 -255.501648)
		(width 0.0889)
		(layer "In11.Cu")
		(net "M_L_CPU0_SA_PAR")
	)
	(arc
		(start 387.161786 -255.501648)
		(mid 387.444742 -255.577825)
		(end 387.727698 -255.501648)
		(width 0.0889)
		(layer "In11.Cu")
		(net "M_L_CPU0_SA_PAR")
	)
	(arc
		(start 390.921748 -255.501648)
		(mid 391.204704 -255.577825)
		(end 391.48766 -255.501648)
		(width 0.0889)
		(layer "In11.Cu")
		(net "M_L_CPU0_SA_PAR")
	)
	(arc
		(start 386.787898 -255.501648)
		(mid 386.974842 -255.451393)
		(end 387.161786 -255.501648)
		(width 0.0889)
		(layer "In11.Cu")
		(net "M_L_CPU0_SA_PAR")
	)
	(arc
		(start 388.667752 -255.501648)
		(mid 388.850003 -255.451298)
		(end 389.033512 -255.496822)
		(width 0.0889)
		(layer "In11.Cu")
		(net "M_L_CPU0_SA_PAR")
	)
	(arc
		(start 391.862056 -255.501648)
		(mid 392.139123 -255.577919)
		(end 392.417808 -255.507744)
		(width 0.0889)
		(layer "In11.Cu")
		(net "M_L_CPU0_SA_PAR")
	)
	(arc
		(start 390.54786 -255.501648)
		(mid 390.734804 -255.451393)
		(end 390.921748 -255.501648)
		(width 0.0889)
		(layer "In11.Cu")
		(net "M_L_CPU0_SA_PAR")
	)
	(arc
		(start 391.48766 -255.501648)
		(mid 391.674858 -255.451266)
		(end 391.862056 -255.501648)
		(width 0.0889)
		(layer "In11.Cu")
		(net "M_L_CPU0_SA_PAR")
	)
	(arc
		(start 389.616188 -255.496822)
		(mid 389.799696 -255.451328)
		(end 389.981948 -255.501648)
		(width 0.0889)
		(layer "In11.Cu")
		(net "M_L_CPU0_SA_PAR")
	)
	(arc
		(start 392.428222 -255.501648)
		(mid 392.615166 -255.451393)
		(end 392.80211 -255.501648)
		(width 0.0889)
		(layer "In11.Cu")
		(net "M_L_CPU0_SA_PAR")
	)
	(arc
		(start 389.041894 -255.501648)
		(mid 389.32485 -255.577825)
		(end 389.607806 -255.501648)
		(width 0.0889)
		(layer "In11.Cu")
		(net "M_L_CPU0_SA_PAR")
	)
	(arc
		(start 389.981948 -255.501648)
		(mid 390.264904 -255.577825)
		(end 390.54786 -255.501648)
		(width 0.0889)
		(layer "In11.Cu")
		(net "M_L_CPU0_SA_PAR")
	)
	(arc
		(start 388.10184 -255.501648)
		(mid 388.384796 -255.577825)
		(end 388.667752 -255.501648)
		(width 0.0889)
		(layer "In11.Cu")
		(net "M_L_CPU0_SA_PAR")
	)
	(arc
		(start 387.727698 -255.501648)
		(mid 387.909949 -255.451298)
		(end 388.093458 -255.496822)
		(width 0.0889)
		(layer "In11.Cu")
		(net "M_L_CPU0_SA_PAR")
	)
	(segment
		(start 385.567936 -247.990106)
		(end 386.034788 -247.724168)
		(width 0.12954)
		(layer "F.Cu")
		(net "M_L_CPU0_SA_DQS_DP<9>")
	)
	(segment
		(start 392.405108 -247.41251)
		(end 392.428476 -247.399048)
		(width 0.09525)
		(layer "In11.Cu")
		(net "M_L_CPU0_SA_DQS_DP<9>")
	)
	(segment
		(start 395.428978 -248.057416)
		(end 395.776704 -248.057416)
		(width 0.09525)
		(layer "In11.Cu")
		(net "M_L_CPU0_SA_DQS_DP<9>")
	)
	(segment
		(start 423.05605 -239.331754)
		(end 423.43451 -239.710214)
		(width 0.16002)
		(layer "In11.Cu")
		(net "M_L_CPU0_SA_DQS_DP<9>")
	)
	(segment
		(start 395.776704 -248.057416)
		(end 395.835632 -248.116344)
		(width 0.09525)
		(layer "In11.Cu")
		(net "M_L_CPU0_SA_DQS_DP<9>")
	)
	(segment
		(start 418.335714 -239.501172)
		(end 418.495734 -239.661192)
		(width 0.16002)
		(layer "In11.Cu")
		(net "M_L_CPU0_SA_DQS_DP<9>")
	)
	(segment
		(start 414.873694 -241.410236)
		(end 415.723578 -240.560352)
		(width 0.16002)
		(layer "In11.Cu")
		(net "M_L_CPU0_SA_DQS_DP<9>")
	)
	(segment
		(start 385.880864 -247.458738)
		(end 385.904232 -247.37187)
		(width 0.09525)
		(layer "In11.Cu")
		(net "M_L_CPU0_SA_DQS_DP<9>")
	)
	(segment
		(start 431.120042 -239.851692)
		(end 431.593244 -239.851692)
		(width 0.16002)
		(layer "In11.Cu")
		(net "M_L_CPU0_SA_DQS_DP<9>")
	)
	(segment
		(start 428.178214 -240.560352)
		(end 428.553372 -240.185194)
		(width 0.16002)
		(layer "In11.Cu")
		(net "M_L_CPU0_SA_DQS_DP<9>")
	)
	(segment
		(start 434.043836 -239.630712)
		(end 434.043836 -240.223294)
		(width 0.16002)
		(layer "In11.Cu")
		(net "M_L_CPU0_SA_DQS_DP<9>")
	)
	(segment
		(start 441.696094 -240.560352)
		(end 443.266322 -240.560352)
		(width 0.16002)
		(layer "In11.Cu")
		(net "M_L_CPU0_SA_DQS_DP<9>")
	)
	(segment
		(start 434.380894 -240.560352)
		(end 435.722268 -240.560352)
		(width 0.16002)
		(layer "In11.Cu")
		(net "M_L_CPU0_SA_DQS_DP<9>")
	)
	(segment
		(start 417.82746 -239.661192)
		(end 417.98748 -239.501172)
		(width 0.16002)
		(layer "In11.Cu")
		(net "M_L_CPU0_SA_DQS_DP<9>")
	)
	(segment
		(start 415.723578 -240.560352)
		(end 417.490402 -240.560352)
		(width 0.16002)
		(layer "In11.Cu")
		(net "M_L_CPU0_SA_DQS_DP<9>")
	)
	(segment
		(start 445.688212 -239.331754)
		(end 446.066672 -239.710214)
		(width 0.16002)
		(layer "In11.Cu")
		(net "M_L_CPU0_SA_DQS_DP<9>")
	)
	(segment
		(start 433.375562 -240.223294)
		(end 433.375562 -239.630712)
		(width 0.16002)
		(layer "In11.Cu")
		(net "M_L_CPU0_SA_DQS_DP<9>")
	)
	(segment
		(start 447.37782 -239.710214)
		(end 447.526664 -239.56137)
		(width 0.16002)
		(layer "In11.Cu")
		(net "M_L_CPU0_SA_DQS_DP<9>")
	)
	(segment
		(start 395.835632 -248.116344)
		(end 395.859254 -248.116344)
		(width 0.09525)
		(layer "In11.Cu")
		(net "M_L_CPU0_SA_DQS_DP<9>")
	)
	(segment
		(start 433.883816 -239.470692)
		(end 434.043836 -239.630712)
		(width 0.16002)
		(layer "In11.Cu")
		(net "M_L_CPU0_SA_DQS_DP<9>")
	)
	(segment
		(start 396.127986 -248.116344)
		(end 397.064738 -247.179592)
		(width 0.16002)
		(layer "In11.Cu")
		(net "M_L_CPU0_SA_DQS_DP<9>")
	)
	(segment
		(start 433.535582 -239.470692)
		(end 433.883816 -239.470692)
		(width 0.16002)
		(layer "In11.Cu")
		(net "M_L_CPU0_SA_DQS_DP<9>")
	)
	(segment
		(start 444.262764 -240.185194)
		(end 445.116204 -239.331754)
		(width 0.16002)
		(layer "In11.Cu")
		(net "M_L_CPU0_SA_DQS_DP<9>")
	)
	(segment
		(start 434.043836 -240.223294)
		(end 434.380894 -240.560352)
		(width 0.16002)
		(layer "In11.Cu")
		(net "M_L_CPU0_SA_DQS_DP<9>")
	)
	(segment
		(start 448.247008 -239.56137)
		(end 448.374008 -239.68837)
		(width 0.16002)
		(layer "In11.Cu")
		(net "M_L_CPU0_SA_DQS_DP<9>")
	)
	(segment
		(start 430.600104 -239.331754)
		(end 431.120042 -239.851692)
		(width 0.16002)
		(layer "In11.Cu")
		(net "M_L_CPU0_SA_DQS_DP<9>")
	)
	(segment
		(start 435.722268 -240.560352)
		(end 436.097426 -240.185194)
		(width 0.16002)
		(layer "In11.Cu")
		(net "M_L_CPU0_SA_DQS_DP<9>")
	)
	(segment
		(start 446.066672 -239.710214)
		(end 447.37782 -239.710214)
		(width 0.16002)
		(layer "In11.Cu")
		(net "M_L_CPU0_SA_DQS_DP<9>")
	)
	(segment
		(start 448.374008 -239.68837)
		(end 448.854068 -239.68837)
		(width 0.16002)
		(layer "In11.Cu")
		(net "M_L_CPU0_SA_DQS_DP<9>")
	)
	(segment
		(start 438.144158 -239.331754)
		(end 438.522618 -239.710214)
		(width 0.16002)
		(layer "In11.Cu")
		(net "M_L_CPU0_SA_DQS_DP<9>")
	)
	(segment
		(start 406.404318 -247.179592)
		(end 412.173674 -241.410236)
		(width 0.16002)
		(layer "In11.Cu")
		(net "M_L_CPU0_SA_DQS_DP<9>")
	)
	(segment
		(start 429.174656 -240.185194)
		(end 430.028096 -239.331754)
		(width 0.16002)
		(layer "In11.Cu")
		(net "M_L_CPU0_SA_DQS_DP<9>")
	)
	(segment
		(start 418.495734 -240.223294)
		(end 418.832792 -240.560352)
		(width 0.16002)
		(layer "In11.Cu")
		(net "M_L_CPU0_SA_DQS_DP<9>")
	)
	(segment
		(start 449.814188 -239.56137)
		(end 450.088 -239.835182)
		(width 0.16002)
		(layer "In11.Cu")
		(net "M_L_CPU0_SA_DQS_DP<9>")
	)
	(segment
		(start 437.57215 -239.331754)
		(end 438.144158 -239.331754)
		(width 0.16002)
		(layer "In11.Cu")
		(net "M_L_CPU0_SA_DQS_DP<9>")
	)
	(segment
		(start 420.63416 -240.560352)
		(end 421.009318 -240.185194)
		(width 0.16002)
		(layer "In11.Cu")
		(net "M_L_CPU0_SA_DQS_DP<9>")
	)
	(segment
		(start 418.495734 -239.661192)
		(end 418.495734 -240.223294)
		(width 0.16002)
		(layer "In11.Cu")
		(net "M_L_CPU0_SA_DQS_DP<9>")
	)
	(segment
		(start 430.028096 -239.331754)
		(end 430.600104 -239.331754)
		(width 0.16002)
		(layer "In11.Cu")
		(net "M_L_CPU0_SA_DQS_DP<9>")
	)
	(segment
		(start 393.084812 -247.473978)
		(end 394.84554 -247.473978)
		(width 0.09525)
		(layer "In11.Cu")
		(net "M_L_CPU0_SA_DQS_DP<9>")
	)
	(segment
		(start 397.064738 -247.179592)
		(end 406.404318 -247.179592)
		(width 0.16002)
		(layer "In11.Cu")
		(net "M_L_CPU0_SA_DQS_DP<9>")
	)
	(segment
		(start 418.832792 -240.560352)
		(end 420.63416 -240.560352)
		(width 0.16002)
		(layer "In11.Cu")
		(net "M_L_CPU0_SA_DQS_DP<9>")
	)
	(segment
		(start 412.173674 -241.410236)
		(end 414.873694 -241.410236)
		(width 0.16002)
		(layer "In11.Cu")
		(net "M_L_CPU0_SA_DQS_DP<9>")
	)
	(segment
		(start 391.486136 -247.399048)
		(end 391.500614 -247.390666)
		(width 0.09525)
		(layer "In11.Cu")
		(net "M_L_CPU0_SA_DQS_DP<9>")
	)
	(segment
		(start 436.097426 -240.185194)
		(end 436.71871 -240.185194)
		(width 0.16002)
		(layer "In11.Cu")
		(net "M_L_CPU0_SA_DQS_DP<9>")
	)
	(segment
		(start 389.606282 -247.399048)
		(end 389.614664 -247.394222)
		(width 0.09525)
		(layer "In11.Cu")
		(net "M_L_CPU0_SA_DQS_DP<9>")
	)
	(segment
		(start 421.009318 -240.185194)
		(end 421.630602 -240.185194)
		(width 0.16002)
		(layer "In11.Cu")
		(net "M_L_CPU0_SA_DQS_DP<9>")
	)
	(segment
		(start 388.094982 -247.394222)
		(end 388.103364 -247.399048)
		(width 0.09525)
		(layer "In11.Cu")
		(net "M_L_CPU0_SA_DQS_DP<9>")
	)
	(segment
		(start 431.593244 -239.851692)
		(end 432.301904 -240.560352)
		(width 0.16002)
		(layer "In11.Cu")
		(net "M_L_CPU0_SA_DQS_DP<9>")
	)
	(segment
		(start 438.522618 -239.710214)
		(end 440.845956 -239.710214)
		(width 0.16002)
		(layer "In11.Cu")
		(net "M_L_CPU0_SA_DQS_DP<9>")
	)
	(segment
		(start 426.607986 -240.560352)
		(end 428.178214 -240.560352)
		(width 0.16002)
		(layer "In11.Cu")
		(net "M_L_CPU0_SA_DQS_DP<9>")
	)
	(segment
		(start 395.859254 -248.116344)
		(end 396.127986 -248.116344)
		(width 0.16002)
		(layer "In11.Cu")
		(net "M_L_CPU0_SA_DQS_DP<9>")
	)
	(segment
		(start 422.484042 -239.331754)
		(end 423.05605 -239.331754)
		(width 0.16002)
		(layer "In11.Cu")
		(net "M_L_CPU0_SA_DQS_DP<9>")
	)
	(segment
		(start 433.375562 -239.630712)
		(end 433.535582 -239.470692)
		(width 0.16002)
		(layer "In11.Cu")
		(net "M_L_CPU0_SA_DQS_DP<9>")
	)
	(segment
		(start 445.116204 -239.331754)
		(end 445.688212 -239.331754)
		(width 0.16002)
		(layer "In11.Cu")
		(net "M_L_CPU0_SA_DQS_DP<9>")
	)
	(segment
		(start 432.301904 -240.560352)
		(end 433.038504 -240.560352)
		(width 0.16002)
		(layer "In11.Cu")
		(net "M_L_CPU0_SA_DQS_DP<9>")
	)
	(segment
		(start 433.038504 -240.560352)
		(end 433.375562 -240.223294)
		(width 0.16002)
		(layer "In11.Cu")
		(net "M_L_CPU0_SA_DQS_DP<9>")
	)
	(segment
		(start 448.854068 -239.68837)
		(end 448.981068 -239.56137)
		(width 0.16002)
		(layer "In11.Cu")
		(net "M_L_CPU0_SA_DQS_DP<9>")
	)
	(segment
		(start 417.98748 -239.501172)
		(end 418.335714 -239.501172)
		(width 0.16002)
		(layer "In11.Cu")
		(net "M_L_CPU0_SA_DQS_DP<9>")
	)
	(segment
		(start 428.553372 -240.185194)
		(end 429.174656 -240.185194)
		(width 0.16002)
		(layer "In11.Cu")
		(net "M_L_CPU0_SA_DQS_DP<9>")
	)
	(segment
		(start 447.526664 -239.56137)
		(end 448.247008 -239.56137)
		(width 0.16002)
		(layer "In11.Cu")
		(net "M_L_CPU0_SA_DQS_DP<9>")
	)
	(segment
		(start 436.71871 -240.185194)
		(end 437.57215 -239.331754)
		(width 0.16002)
		(layer "In11.Cu")
		(net "M_L_CPU0_SA_DQS_DP<9>")
	)
	(segment
		(start 443.64148 -240.185194)
		(end 444.262764 -240.185194)
		(width 0.16002)
		(layer "In11.Cu")
		(net "M_L_CPU0_SA_DQS_DP<9>")
	)
	(segment
		(start 443.266322 -240.560352)
		(end 443.64148 -240.185194)
		(width 0.16002)
		(layer "In11.Cu")
		(net "M_L_CPU0_SA_DQS_DP<9>")
	)
	(segment
		(start 440.845956 -239.710214)
		(end 441.696094 -240.560352)
		(width 0.16002)
		(layer "In11.Cu")
		(net "M_L_CPU0_SA_DQS_DP<9>")
	)
	(segment
		(start 417.490402 -240.560352)
		(end 417.82746 -240.223294)
		(width 0.16002)
		(layer "In11.Cu")
		(net "M_L_CPU0_SA_DQS_DP<9>")
	)
	(segment
		(start 417.82746 -240.223294)
		(end 417.82746 -239.661192)
		(width 0.16002)
		(layer "In11.Cu")
		(net "M_L_CPU0_SA_DQS_DP<9>")
	)
	(segment
		(start 386.034788 -247.724168)
		(end 385.880864 -247.458738)
		(width 0.09525)
		(layer "In11.Cu")
		(net "M_L_CPU0_SA_DQS_DP<9>")
	)
	(segment
		(start 423.43451 -239.710214)
		(end 425.757848 -239.710214)
		(width 0.16002)
		(layer "In11.Cu")
		(net "M_L_CPU0_SA_DQS_DP<9>")
	)
	(segment
		(start 392.78814 -247.389396)
		(end 392.804904 -247.399048)
		(width 0.09525)
		(layer "In11.Cu")
		(net "M_L_CPU0_SA_DQS_DP<9>")
	)
	(segment
		(start 425.757848 -239.710214)
		(end 426.607986 -240.560352)
		(width 0.16002)
		(layer "In11.Cu")
		(net "M_L_CPU0_SA_DQS_DP<9>")
	)
	(segment
		(start 421.630602 -240.185194)
		(end 422.484042 -239.331754)
		(width 0.16002)
		(layer "In11.Cu")
		(net "M_L_CPU0_SA_DQS_DP<9>")
	)
	(segment
		(start 448.981068 -239.56137)
		(end 449.814188 -239.56137)
		(width 0.16002)
		(layer "In11.Cu")
		(net "M_L_CPU0_SA_DQS_DP<9>")
	)
	(segment
		(start 389.035036 -247.394222)
		(end 389.043418 -247.399048)
		(width 0.09525)
		(layer "In11.Cu")
		(net "M_L_CPU0_SA_DQS_DP<9>")
	)
	(segment
		(start 394.84554 -247.473978)
		(end 395.428978 -248.057416)
		(width 0.09525)
		(layer "In11.Cu")
		(net "M_L_CPU0_SA_DQS_DP<9>")
	)
	(arc
		(start 388.103364 -247.399048)
		(mid 388.384796 -247.474803)
		(end 388.666228 -247.399048)
		(width 0.09525)
		(layer "In11.Cu")
		(net "M_L_CPU0_SA_DQS_DP<9>")
	)
	(arc
		(start 386.22351 -247.399048)
		(mid 386.504942 -247.474803)
		(end 386.786374 -247.399048)
		(width 0.09525)
		(layer "In11.Cu")
		(net "M_L_CPU0_SA_DQS_DP<9>")
	)
	(arc
		(start 389.043418 -247.399048)
		(mid 389.32485 -247.474803)
		(end 389.606282 -247.399048)
		(width 0.09525)
		(layer "In11.Cu")
		(net "M_L_CPU0_SA_DQS_DP<9>")
	)
	(arc
		(start 392.428476 -247.399048)
		(mid 392.607082 -247.34838)
		(end 392.78814 -247.389396)
		(width 0.09525)
		(layer "In11.Cu")
		(net "M_L_CPU0_SA_DQS_DP<9>")
	)
	(arc
		(start 390.546336 -247.399048)
		(mid 390.734804 -247.348371)
		(end 390.923272 -247.399048)
		(width 0.09525)
		(layer "In11.Cu")
		(net "M_L_CPU0_SA_DQS_DP<9>")
	)
	(arc
		(start 387.16331 -247.399048)
		(mid 387.444742 -247.474803)
		(end 387.726174 -247.399048)
		(width 0.09525)
		(layer "In11.Cu")
		(net "M_L_CPU0_SA_DQS_DP<9>")
	)
	(arc
		(start 389.614664 -247.394222)
		(mid 389.799696 -247.348308)
		(end 389.983472 -247.399048)
		(width 0.09525)
		(layer "In11.Cu")
		(net "M_L_CPU0_SA_DQS_DP<9>")
	)
	(arc
		(start 389.983472 -247.399048)
		(mid 390.264904 -247.474803)
		(end 390.546336 -247.399048)
		(width 0.09525)
		(layer "In11.Cu")
		(net "M_L_CPU0_SA_DQS_DP<9>")
	)
	(arc
		(start 385.904232 -247.37187)
		(mid 386.066914 -247.349738)
		(end 386.22351 -247.399048)
		(width 0.09525)
		(layer "In11.Cu")
		(net "M_L_CPU0_SA_DQS_DP<9>")
	)
	(arc
		(start 390.923272 -247.399048)
		(mid 391.204704 -247.474803)
		(end 391.486136 -247.399048)
		(width 0.09525)
		(layer "In11.Cu")
		(net "M_L_CPU0_SA_DQS_DP<9>")
	)
	(arc
		(start 386.786374 -247.399048)
		(mid 386.974842 -247.348371)
		(end 387.16331 -247.399048)
		(width 0.09525)
		(layer "In11.Cu")
		(net "M_L_CPU0_SA_DQS_DP<9>")
	)
	(arc
		(start 391.864342 -247.399048)
		(mid 392.133005 -247.475266)
		(end 392.405108 -247.41251)
		(width 0.09525)
		(layer "In11.Cu")
		(net "M_L_CPU0_SA_DQS_DP<9>")
	)
	(arc
		(start 387.726174 -247.399048)
		(mid 387.909949 -247.348276)
		(end 388.094982 -247.394222)
		(width 0.09525)
		(layer "In11.Cu")
		(net "M_L_CPU0_SA_DQS_DP<9>")
	)
	(arc
		(start 391.500614 -247.390666)
		(mid 391.683554 -247.347991)
		(end 391.864342 -247.399048)
		(width 0.09525)
		(layer "In11.Cu")
		(net "M_L_CPU0_SA_DQS_DP<9>")
	)
	(arc
		(start 388.666228 -247.399048)
		(mid 388.850003 -247.348276)
		(end 389.035036 -247.394222)
		(width 0.09525)
		(layer "In11.Cu")
		(net "M_L_CPU0_SA_DQS_DP<9>")
	)
	(arc
		(start 392.804904 -247.399048)
		(mid 392.939922 -247.454967)
		(end 393.084812 -247.473978)
		(width 0.09525)
		(layer "In11.Cu")
		(net "M_L_CPU0_SA_DQS_DP<9>")
	)
	(segment
		(start 385.567936 -243.13007)
		(end 386.034788 -242.864132)
		(width 0.12954)
		(layer "F.Cu")
		(net "M_L_CPU0_SA_DQS_DP<8>")
	)
	(segment
		(start 402.461984 -241.050826)
		(end 402.766022 -241.354864)
		(width 0.16002)
		(layer "In11.Cu")
		(net "M_L_CPU0_SA_DQS_DP<8>")
	)
	(segment
		(start 430.978564 -230.36022)
		(end 433.537106 -230.36022)
		(width 0.16002)
		(layer "In11.Cu")
		(net "M_L_CPU0_SA_DQS_DP<8>")
	)
	(segment
		(start 403.66823 -240.92916)
		(end 403.66823 -240.452656)
		(width 0.16002)
		(layer "In11.Cu")
		(net "M_L_CPU0_SA_DQS_DP<8>")
	)
	(segment
		(start 404.740618 -238.772192)
		(end 404.740618 -238.546132)
		(width 0.16002)
		(layer "In11.Cu")
		(net "M_L_CPU0_SA_DQS_DP<8>")
	)
	(segment
		(start 422.484042 -229.98176)
		(end 423.05605 -229.98176)
		(width 0.16002)
		(layer "In11.Cu")
		(net "M_L_CPU0_SA_DQS_DP<8>")
	)
	(segment
		(start 416.638232 -230.679752)
		(end 416.97529 -230.342694)
		(width 0.16002)
		(layer "In11.Cu")
		(net "M_L_CPU0_SA_DQS_DP<8>")
	)
	(segment
		(start 416.97529 -230.342694)
		(end 416.97529 -230.126032)
		(width 0.16002)
		(layer "In11.Cu")
		(net "M_L_CPU0_SA_DQS_DP<8>")
	)
	(segment
		(start 414.086548 -230.8352)
		(end 414.939988 -229.98176)
		(width 0.16002)
		(layer "In11.Cu")
		(net "M_L_CPU0_SA_DQS_DP<8>")
	)
	(segment
		(start 421.630602 -230.8352)
		(end 422.484042 -229.98176)
		(width 0.16002)
		(layer "In11.Cu")
		(net "M_L_CPU0_SA_DQS_DP<8>")
	)
	(segment
		(start 434.387244 -231.210358)
		(end 435.722268 -231.210358)
		(width 0.16002)
		(layer "In11.Cu")
		(net "M_L_CPU0_SA_DQS_DP<8>")
	)
	(segment
		(start 417.483544 -229.966012)
		(end 417.643564 -230.126032)
		(width 0.16002)
		(layer "In11.Cu")
		(net "M_L_CPU0_SA_DQS_DP<8>")
	)
	(segment
		(start 405.044656 -239.07623)
		(end 404.740618 -238.772192)
		(width 0.16002)
		(layer "In11.Cu")
		(net "M_L_CPU0_SA_DQS_DP<8>")
	)
	(segment
		(start 437.57215 -229.98176)
		(end 438.144158 -229.98176)
		(width 0.16002)
		(layer "In11.Cu")
		(net "M_L_CPU0_SA_DQS_DP<8>")
	)
	(segment
		(start 436.71871 -230.8352)
		(end 437.57215 -229.98176)
		(width 0.16002)
		(layer "In11.Cu")
		(net "M_L_CPU0_SA_DQS_DP<8>")
	)
	(segment
		(start 417.980622 -230.679752)
		(end 418.799518 -230.679752)
		(width 0.16002)
		(layer "In11.Cu")
		(net "M_L_CPU0_SA_DQS_DP<8>")
	)
	(segment
		(start 404.740618 -238.546132)
		(end 412.45155 -230.8352)
		(width 0.16002)
		(layer "In11.Cu")
		(net "M_L_CPU0_SA_DQS_DP<8>")
	)
	(segment
		(start 395.495272 -241.524282)
		(end 395.776704 -241.524282)
		(width 0.09525)
		(layer "In11.Cu")
		(net "M_L_CPU0_SA_DQS_DP<8>")
	)
	(segment
		(start 430.600104 -229.98176)
		(end 430.978564 -230.36022)
		(width 0.16002)
		(layer "In11.Cu")
		(net "M_L_CPU0_SA_DQS_DP<8>")
	)
	(segment
		(start 441.696094 -231.210358)
		(end 443.266322 -231.210358)
		(width 0.16002)
		(layer "In11.Cu")
		(net "M_L_CPU0_SA_DQS_DP<8>")
	)
	(segment
		(start 394.40485 -242.614704)
		(end 395.495272 -241.524282)
		(width 0.09525)
		(layer "In11.Cu")
		(net "M_L_CPU0_SA_DQS_DP<8>")
	)
	(segment
		(start 403.364192 -239.922558)
		(end 403.61235 -239.6744)
		(width 0.16002)
		(layer "In11.Cu")
		(net "M_L_CPU0_SA_DQS_DP<8>")
	)
	(segment
		(start 448.307968 -230.211376)
		(end 448.434968 -230.338376)
		(width 0.16002)
		(layer "In11.Cu")
		(net "M_L_CPU0_SA_DQS_DP<8>")
	)
	(segment
		(start 402.235924 -241.050826)
		(end 402.461984 -241.050826)
		(width 0.16002)
		(layer "In11.Cu")
		(net "M_L_CPU0_SA_DQS_DP<8>")
	)
	(segment
		(start 421.009318 -230.8352)
		(end 421.630602 -230.8352)
		(width 0.16002)
		(layer "In11.Cu")
		(net "M_L_CPU0_SA_DQS_DP<8>")
	)
	(segment
		(start 389.035036 -242.534186)
		(end 389.043418 -242.539012)
		(width 0.09525)
		(layer "In11.Cu")
		(net "M_L_CPU0_SA_DQS_DP<8>")
	)
	(segment
		(start 430.028096 -229.98176)
		(end 430.600104 -229.98176)
		(width 0.16002)
		(layer "In11.Cu")
		(net "M_L_CPU0_SA_DQS_DP<8>")
	)
	(segment
		(start 428.178214 -231.210358)
		(end 428.553372 -230.8352)
		(width 0.16002)
		(layer "In11.Cu")
		(net "M_L_CPU0_SA_DQS_DP<8>")
	)
	(segment
		(start 388.094982 -242.534186)
		(end 388.103364 -242.539012)
		(width 0.09525)
		(layer "In11.Cu")
		(net "M_L_CPU0_SA_DQS_DP<8>")
	)
	(segment
		(start 401.70354 -241.58321)
		(end 402.235924 -241.050826)
		(width 0.16002)
		(layer "In11.Cu")
		(net "M_L_CPU0_SA_DQS_DP<8>")
	)
	(segment
		(start 404.618952 -239.978438)
		(end 405.044656 -239.552734)
		(width 0.16002)
		(layer "In11.Cu")
		(net "M_L_CPU0_SA_DQS_DP<8>")
	)
	(segment
		(start 447.526664 -230.211376)
		(end 448.307968 -230.211376)
		(width 0.16002)
		(layer "In11.Cu")
		(net "M_L_CPU0_SA_DQS_DP<8>")
	)
	(segment
		(start 389.606282 -242.539012)
		(end 389.614664 -242.534186)
		(width 0.09525)
		(layer "In11.Cu")
		(net "M_L_CPU0_SA_DQS_DP<8>")
	)
	(segment
		(start 403.364192 -240.148618)
		(end 403.364192 -239.922558)
		(width 0.16002)
		(layer "In11.Cu")
		(net "M_L_CPU0_SA_DQS_DP<8>")
	)
	(segment
		(start 449.042028 -230.211376)
		(end 449.814188 -230.211376)
		(width 0.16002)
		(layer "In11.Cu")
		(net "M_L_CPU0_SA_DQS_DP<8>")
	)
	(segment
		(start 445.688212 -229.98176)
		(end 446.066672 -230.36022)
		(width 0.16002)
		(layer "In11.Cu")
		(net "M_L_CPU0_SA_DQS_DP<8>")
	)
	(segment
		(start 393.084812 -242.614704)
		(end 394.40485 -242.614704)
		(width 0.09525)
		(layer "In11.Cu")
		(net "M_L_CPU0_SA_DQS_DP<8>")
	)
	(segment
		(start 433.537106 -230.36022)
		(end 434.387244 -231.210358)
		(width 0.16002)
		(layer "In11.Cu")
		(net "M_L_CPU0_SA_DQS_DP<8>")
	)
	(segment
		(start 418.799518 -230.679752)
		(end 419.330124 -231.210358)
		(width 0.16002)
		(layer "In11.Cu")
		(net "M_L_CPU0_SA_DQS_DP<8>")
	)
	(segment
		(start 428.553372 -230.8352)
		(end 429.174656 -230.8352)
		(width 0.16002)
		(layer "In11.Cu")
		(net "M_L_CPU0_SA_DQS_DP<8>")
	)
	(segment
		(start 386.034788 -242.864132)
		(end 385.880864 -242.598702)
		(width 0.09525)
		(layer "In11.Cu")
		(net "M_L_CPU0_SA_DQS_DP<8>")
	)
	(segment
		(start 403.61235 -239.6744)
		(end 403.83841 -239.6744)
		(width 0.16002)
		(layer "In11.Cu")
		(net "M_L_CPU0_SA_DQS_DP<8>")
	)
	(segment
		(start 405.044656 -239.552734)
		(end 405.044656 -239.07623)
		(width 0.16002)
		(layer "In11.Cu")
		(net "M_L_CPU0_SA_DQS_DP<8>")
	)
	(segment
		(start 445.116204 -229.98176)
		(end 445.688212 -229.98176)
		(width 0.16002)
		(layer "In11.Cu")
		(net "M_L_CPU0_SA_DQS_DP<8>")
	)
	(segment
		(start 449.814188 -230.211376)
		(end 450.088 -230.485188)
		(width 0.16002)
		(layer "In11.Cu")
		(net "M_L_CPU0_SA_DQS_DP<8>")
	)
	(segment
		(start 435.722268 -231.210358)
		(end 436.097426 -230.8352)
		(width 0.16002)
		(layer "In11.Cu")
		(net "M_L_CPU0_SA_DQS_DP<8>")
	)
	(segment
		(start 443.64148 -230.8352)
		(end 444.262764 -230.8352)
		(width 0.16002)
		(layer "In11.Cu")
		(net "M_L_CPU0_SA_DQS_DP<8>")
	)
	(segment
		(start 423.05605 -229.98176)
		(end 423.43451 -230.36022)
		(width 0.16002)
		(layer "In11.Cu")
		(net "M_L_CPU0_SA_DQS_DP<8>")
	)
	(segment
		(start 443.266322 -231.210358)
		(end 443.64148 -230.8352)
		(width 0.16002)
		(layer "In11.Cu")
		(net "M_L_CPU0_SA_DQS_DP<8>")
	)
	(segment
		(start 395.776704 -241.524282)
		(end 395.835632 -241.58321)
		(width 0.09525)
		(layer "In11.Cu")
		(net "M_L_CPU0_SA_DQS_DP<8>")
	)
	(segment
		(start 395.835632 -241.58321)
		(end 395.859254 -241.58321)
		(width 0.09525)
		(layer "In11.Cu")
		(net "M_L_CPU0_SA_DQS_DP<8>")
	)
	(segment
		(start 426.996098 -231.210358)
		(end 428.178214 -231.210358)
		(width 0.16002)
		(layer "In11.Cu")
		(net "M_L_CPU0_SA_DQS_DP<8>")
	)
	(segment
		(start 412.45155 -230.8352)
		(end 414.086548 -230.8352)
		(width 0.16002)
		(layer "In11.Cu")
		(net "M_L_CPU0_SA_DQS_DP<8>")
	)
	(segment
		(start 403.83841 -239.6744)
		(end 404.142448 -239.978438)
		(width 0.16002)
		(layer "In11.Cu")
		(net "M_L_CPU0_SA_DQS_DP<8>")
	)
	(segment
		(start 444.262764 -230.8352)
		(end 445.116204 -229.98176)
		(width 0.16002)
		(layer "In11.Cu")
		(net "M_L_CPU0_SA_DQS_DP<8>")
	)
	(segment
		(start 392.416284 -242.545108)
		(end 392.426698 -242.539012)
		(width 0.09525)
		(layer "In11.Cu")
		(net "M_L_CPU0_SA_DQS_DP<8>")
	)
	(segment
		(start 404.142448 -239.978438)
		(end 404.618952 -239.978438)
		(width 0.16002)
		(layer "In11.Cu")
		(net "M_L_CPU0_SA_DQS_DP<8>")
	)
	(segment
		(start 446.066672 -230.36022)
		(end 447.37782 -230.36022)
		(width 0.16002)
		(layer "In11.Cu")
		(net "M_L_CPU0_SA_DQS_DP<8>")
	)
	(segment
		(start 438.522618 -230.36022)
		(end 440.845956 -230.36022)
		(width 0.16002)
		(layer "In11.Cu")
		(net "M_L_CPU0_SA_DQS_DP<8>")
	)
	(segment
		(start 436.097426 -230.8352)
		(end 436.71871 -230.8352)
		(width 0.16002)
		(layer "In11.Cu")
		(net "M_L_CPU0_SA_DQS_DP<8>")
	)
	(segment
		(start 416.97529 -230.126032)
		(end 417.13531 -229.966012)
		(width 0.16002)
		(layer "In11.Cu")
		(net "M_L_CPU0_SA_DQS_DP<8>")
	)
	(segment
		(start 440.845956 -230.36022)
		(end 441.696094 -231.210358)
		(width 0.16002)
		(layer "In11.Cu")
		(net "M_L_CPU0_SA_DQS_DP<8>")
	)
	(segment
		(start 417.13531 -229.966012)
		(end 417.483544 -229.966012)
		(width 0.16002)
		(layer "In11.Cu")
		(net "M_L_CPU0_SA_DQS_DP<8>")
	)
	(segment
		(start 415.931604 -230.679752)
		(end 416.638232 -230.679752)
		(width 0.16002)
		(layer "In11.Cu")
		(net "M_L_CPU0_SA_DQS_DP<8>")
	)
	(segment
		(start 402.766022 -241.354864)
		(end 403.242526 -241.354864)
		(width 0.16002)
		(layer "In11.Cu")
		(net "M_L_CPU0_SA_DQS_DP<8>")
	)
	(segment
		(start 448.434968 -230.338376)
		(end 448.915028 -230.338376)
		(width 0.16002)
		(layer "In11.Cu")
		(net "M_L_CPU0_SA_DQS_DP<8>")
	)
	(segment
		(start 417.643564 -230.126032)
		(end 417.643564 -230.342694)
		(width 0.16002)
		(layer "In11.Cu")
		(net "M_L_CPU0_SA_DQS_DP<8>")
	)
	(segment
		(start 417.643564 -230.342694)
		(end 417.980622 -230.679752)
		(width 0.16002)
		(layer "In11.Cu")
		(net "M_L_CPU0_SA_DQS_DP<8>")
	)
	(segment
		(start 423.43451 -230.36022)
		(end 426.14596 -230.36022)
		(width 0.16002)
		(layer "In11.Cu")
		(net "M_L_CPU0_SA_DQS_DP<8>")
	)
	(segment
		(start 403.66823 -240.452656)
		(end 403.364192 -240.148618)
		(width 0.16002)
		(layer "In11.Cu")
		(net "M_L_CPU0_SA_DQS_DP<8>")
	)
	(segment
		(start 414.939988 -229.98176)
		(end 415.233612 -229.98176)
		(width 0.16002)
		(layer "In11.Cu")
		(net "M_L_CPU0_SA_DQS_DP<8>")
	)
	(segment
		(start 403.242526 -241.354864)
		(end 403.66823 -240.92916)
		(width 0.16002)
		(layer "In11.Cu")
		(net "M_L_CPU0_SA_DQS_DP<8>")
	)
	(segment
		(start 415.233612 -229.98176)
		(end 415.931604 -230.679752)
		(width 0.16002)
		(layer "In11.Cu")
		(net "M_L_CPU0_SA_DQS_DP<8>")
	)
	(segment
		(start 420.63416 -231.210358)
		(end 421.009318 -230.8352)
		(width 0.16002)
		(layer "In11.Cu")
		(net "M_L_CPU0_SA_DQS_DP<8>")
	)
	(segment
		(start 385.880864 -242.598702)
		(end 385.904232 -242.511834)
		(width 0.09525)
		(layer "In11.Cu")
		(net "M_L_CPU0_SA_DQS_DP<8>")
	)
	(segment
		(start 429.174656 -230.8352)
		(end 430.028096 -229.98176)
		(width 0.16002)
		(layer "In11.Cu")
		(net "M_L_CPU0_SA_DQS_DP<8>")
	)
	(segment
		(start 419.330124 -231.210358)
		(end 420.63416 -231.210358)
		(width 0.16002)
		(layer "In11.Cu")
		(net "M_L_CPU0_SA_DQS_DP<8>")
	)
	(segment
		(start 395.859254 -241.58321)
		(end 401.70354 -241.58321)
		(width 0.16002)
		(layer "In11.Cu")
		(net "M_L_CPU0_SA_DQS_DP<8>")
	)
	(segment
		(start 447.37782 -230.36022)
		(end 447.526664 -230.211376)
		(width 0.16002)
		(layer "In11.Cu")
		(net "M_L_CPU0_SA_DQS_DP<8>")
	)
	(segment
		(start 438.144158 -229.98176)
		(end 438.522618 -230.36022)
		(width 0.16002)
		(layer "In11.Cu")
		(net "M_L_CPU0_SA_DQS_DP<8>")
	)
	(segment
		(start 448.915028 -230.338376)
		(end 449.042028 -230.211376)
		(width 0.16002)
		(layer "In11.Cu")
		(net "M_L_CPU0_SA_DQS_DP<8>")
	)
	(segment
		(start 426.14596 -230.36022)
		(end 426.996098 -231.210358)
		(width 0.16002)
		(layer "In11.Cu")
		(net "M_L_CPU0_SA_DQS_DP<8>")
	)
	(arc
		(start 391.486136 -242.539012)
		(mid 391.674858 -242.488208)
		(end 391.86358 -242.539012)
		(width 0.09525)
		(layer "In11.Cu")
		(net "M_L_CPU0_SA_DQS_DP<8>")
	)
	(arc
		(start 386.786374 -242.539012)
		(mid 386.974842 -242.488335)
		(end 387.16331 -242.539012)
		(width 0.09525)
		(layer "In11.Cu")
		(net "M_L_CPU0_SA_DQS_DP<8>")
	)
	(arc
		(start 388.666228 -242.539012)
		(mid 388.850003 -242.48824)
		(end 389.035036 -242.534186)
		(width 0.09525)
		(layer "In11.Cu")
		(net "M_L_CPU0_SA_DQS_DP<8>")
	)
	(arc
		(start 386.22351 -242.539012)
		(mid 386.504942 -242.614767)
		(end 386.786374 -242.539012)
		(width 0.09525)
		(layer "In11.Cu")
		(net "M_L_CPU0_SA_DQS_DP<8>")
	)
	(arc
		(start 389.983472 -242.539012)
		(mid 390.264904 -242.614767)
		(end 390.546336 -242.539012)
		(width 0.09525)
		(layer "In11.Cu")
		(net "M_L_CPU0_SA_DQS_DP<8>")
	)
	(arc
		(start 385.904232 -242.511834)
		(mid 386.066914 -242.489702)
		(end 386.22351 -242.539012)
		(width 0.09525)
		(layer "In11.Cu")
		(net "M_L_CPU0_SA_DQS_DP<8>")
	)
	(arc
		(start 390.923272 -242.539012)
		(mid 391.204704 -242.614767)
		(end 391.486136 -242.539012)
		(width 0.09525)
		(layer "In11.Cu")
		(net "M_L_CPU0_SA_DQS_DP<8>")
	)
	(arc
		(start 391.86358 -242.539012)
		(mid 392.139123 -242.614861)
		(end 392.416284 -242.545108)
		(width 0.09525)
		(layer "In11.Cu")
		(net "M_L_CPU0_SA_DQS_DP<8>")
	)
	(arc
		(start 387.726174 -242.539012)
		(mid 387.909949 -242.48824)
		(end 388.094982 -242.534186)
		(width 0.09525)
		(layer "In11.Cu")
		(net "M_L_CPU0_SA_DQS_DP<8>")
	)
	(arc
		(start 392.803634 -242.539012)
		(mid 392.939226 -242.595403)
		(end 393.084812 -242.614704)
		(width 0.09525)
		(layer "In11.Cu")
		(net "M_L_CPU0_SA_DQS_DP<8>")
	)
	(arc
		(start 389.614664 -242.534186)
		(mid 389.799696 -242.488272)
		(end 389.983472 -242.539012)
		(width 0.09525)
		(layer "In11.Cu")
		(net "M_L_CPU0_SA_DQS_DP<8>")
	)
	(arc
		(start 388.103364 -242.539012)
		(mid 388.384796 -242.614767)
		(end 388.666228 -242.539012)
		(width 0.09525)
		(layer "In11.Cu")
		(net "M_L_CPU0_SA_DQS_DP<8>")
	)
	(arc
		(start 387.16331 -242.539012)
		(mid 387.444742 -242.614767)
		(end 387.726174 -242.539012)
		(width 0.09525)
		(layer "In11.Cu")
		(net "M_L_CPU0_SA_DQS_DP<8>")
	)
	(arc
		(start 389.043418 -242.539012)
		(mid 389.32485 -242.614767)
		(end 389.606282 -242.539012)
		(width 0.09525)
		(layer "In11.Cu")
		(net "M_L_CPU0_SA_DQS_DP<8>")
	)
	(arc
		(start 392.426698 -242.539012)
		(mid 392.615166 -242.488335)
		(end 392.803634 -242.539012)
		(width 0.09525)
		(layer "In11.Cu")
		(net "M_L_CPU0_SA_DQS_DP<8>")
	)
	(arc
		(start 390.546336 -242.539012)
		(mid 390.734804 -242.488335)
		(end 390.923272 -242.539012)
		(width 0.09525)
		(layer "In11.Cu")
		(net "M_L_CPU0_SA_DQS_DP<8>")
	)
	(segment
		(start 385.567936 -238.270034)
		(end 386.034788 -238.004096)
		(width 0.12954)
		(layer "F.Cu")
		(net "M_L_CPU0_SA_DQS_DP<7>")
	)
	(segment
		(start 393.623038 -237.450122)
		(end 394.664692 -237.450122)
		(width 0.09525)
		(layer "In11.Cu")
		(net "M_L_CPU0_SA_DQS_DP<7>")
	)
	(segment
		(start 385.880864 -237.738666)
		(end 385.904232 -237.651798)
		(width 0.09525)
		(layer "In11.Cu")
		(net "M_L_CPU0_SA_DQS_DP<7>")
	)
	(segment
		(start 429.174656 -221.485206)
		(end 430.028096 -220.631766)
		(width 0.16002)
		(layer "In11.Cu")
		(net "M_L_CPU0_SA_DQS_DP<7>")
	)
	(segment
		(start 448.879468 -220.988382)
		(end 449.006468 -220.861382)
		(width 0.16002)
		(layer "In11.Cu")
		(net "M_L_CPU0_SA_DQS_DP<7>")
	)
	(segment
		(start 397.774668 -235.946442)
		(end 405.652478 -228.068632)
		(width 0.16002)
		(layer "In11.Cu")
		(net "M_L_CPU0_SA_DQS_DP<7>")
	)
	(segment
		(start 410.83738 -223.46031)
		(end 410.83738 -222.88373)
		(width 0.16002)
		(layer "In11.Cu")
		(net "M_L_CPU0_SA_DQS_DP<7>")
	)
	(segment
		(start 393.48156 -237.5916)
		(end 393.623038 -237.450122)
		(width 0.09525)
		(layer "In11.Cu")
		(net "M_L_CPU0_SA_DQS_DP<7>")
	)
	(segment
		(start 408.976322 -225.321368)
		(end 409.463748 -224.833942)
		(width 0.16002)
		(layer "In11.Cu")
		(net "M_L_CPU0_SA_DQS_DP<7>")
	)
	(segment
		(start 426.137832 -221.010226)
		(end 426.98797 -221.860364)
		(width 0.16002)
		(layer "In11.Cu")
		(net "M_L_CPU0_SA_DQS_DP<7>")
	)
	(segment
		(start 426.98797 -221.860364)
		(end 428.178214 -221.860364)
		(width 0.16002)
		(layer "In11.Cu")
		(net "M_L_CPU0_SA_DQS_DP<7>")
	)
	(segment
		(start 409.463748 -224.833942)
		(end 409.463748 -224.257362)
		(width 0.16002)
		(layer "In11.Cu")
		(net "M_L_CPU0_SA_DQS_DP<7>")
	)
	(segment
		(start 386.034788 -238.004096)
		(end 385.880864 -237.738666)
		(width 0.09525)
		(layer "In11.Cu")
		(net "M_L_CPU0_SA_DQS_DP<7>")
	)
	(segment
		(start 422.484042 -220.631766)
		(end 423.05605 -220.631766)
		(width 0.16002)
		(layer "In11.Cu")
		(net "M_L_CPU0_SA_DQS_DP<7>")
	)
	(segment
		(start 448.272408 -220.861382)
		(end 448.399408 -220.988382)
		(width 0.16002)
		(layer "In11.Cu")
		(net "M_L_CPU0_SA_DQS_DP<7>")
	)
	(segment
		(start 394.664692 -237.450122)
		(end 395.308328 -236.806486)
		(width 0.09525)
		(layer "In11.Cu")
		(net "M_L_CPU0_SA_DQS_DP<7>")
	)
	(segment
		(start 430.978564 -221.010226)
		(end 433.549806 -221.010226)
		(width 0.16002)
		(layer "In11.Cu")
		(net "M_L_CPU0_SA_DQS_DP<7>")
	)
	(segment
		(start 418.334444 -220.877892)
		(end 419.316916 -221.860364)
		(width 0.16002)
		(layer "In11.Cu")
		(net "M_L_CPU0_SA_DQS_DP<7>")
	)
	(segment
		(start 388.094982 -237.67415)
		(end 388.103364 -237.678976)
		(width 0.09525)
		(layer "In11.Cu")
		(net "M_L_CPU0_SA_DQS_DP<7>")
	)
	(segment
		(start 395.840458 -235.946442)
		(end 397.774668 -235.946442)
		(width 0.16002)
		(layer "In11.Cu")
		(net "M_L_CPU0_SA_DQS_DP<7>")
	)
	(segment
		(start 417.24199 -220.877892)
		(end 418.334444 -220.877892)
		(width 0.16002)
		(layer "In11.Cu")
		(net "M_L_CPU0_SA_DQS_DP<7>")
	)
	(segment
		(start 407.60269 -226.695)
		(end 408.090116 -226.207574)
		(width 0.16002)
		(layer "In11.Cu")
		(net "M_L_CPU0_SA_DQS_DP<7>")
	)
	(segment
		(start 410.83738 -222.88373)
		(end 412.235904 -221.485206)
		(width 0.16002)
		(layer "In11.Cu")
		(net "M_L_CPU0_SA_DQS_DP<7>")
	)
	(segment
		(start 389.606282 -237.678976)
		(end 389.614664 -237.67415)
		(width 0.09525)
		(layer "In11.Cu")
		(net "M_L_CPU0_SA_DQS_DP<7>")
	)
	(segment
		(start 407.02611 -226.695)
		(end 407.60269 -226.695)
		(width 0.16002)
		(layer "In11.Cu")
		(net "M_L_CPU0_SA_DQS_DP<7>")
	)
	(segment
		(start 392.804904 -237.678976)
		(end 392.840972 -237.699804)
		(width 0.09525)
		(layer "In11.Cu")
		(net "M_L_CPU0_SA_DQS_DP<7>")
	)
	(segment
		(start 395.757908 -235.887514)
		(end 395.816836 -235.946442)
		(width 0.09525)
		(layer "In11.Cu")
		(net "M_L_CPU0_SA_DQS_DP<7>")
	)
	(segment
		(start 441.696094 -221.860364)
		(end 443.266322 -221.860364)
		(width 0.16002)
		(layer "In11.Cu")
		(net "M_L_CPU0_SA_DQS_DP<7>")
	)
	(segment
		(start 391.486136 -237.678976)
		(end 391.500614 -237.670594)
		(width 0.09525)
		(layer "In11.Cu")
		(net "M_L_CPU0_SA_DQS_DP<7>")
	)
	(segment
		(start 430.028096 -220.631766)
		(end 430.600104 -220.631766)
		(width 0.16002)
		(layer "In11.Cu")
		(net "M_L_CPU0_SA_DQS_DP<7>")
	)
	(segment
		(start 395.308328 -236.186726)
		(end 395.60754 -235.887514)
		(width 0.09525)
		(layer "In11.Cu")
		(net "M_L_CPU0_SA_DQS_DP<7>")
	)
	(segment
		(start 443.64148 -221.485206)
		(end 444.262764 -221.485206)
		(width 0.16002)
		(layer "In11.Cu")
		(net "M_L_CPU0_SA_DQS_DP<7>")
	)
	(segment
		(start 447.526664 -220.861382)
		(end 448.272408 -220.861382)
		(width 0.16002)
		(layer "In11.Cu")
		(net "M_L_CPU0_SA_DQS_DP<7>")
	)
	(segment
		(start 414.939988 -220.631766)
		(end 415.440876 -220.631766)
		(width 0.16002)
		(layer "In11.Cu")
		(net "M_L_CPU0_SA_DQS_DP<7>")
	)
	(segment
		(start 405.652478 -228.068632)
		(end 406.229058 -228.068632)
		(width 0.16002)
		(layer "In11.Cu")
		(net "M_L_CPU0_SA_DQS_DP<7>")
	)
	(segment
		(start 438.522618 -221.010226)
		(end 440.845956 -221.010226)
		(width 0.16002)
		(layer "In11.Cu")
		(net "M_L_CPU0_SA_DQS_DP<7>")
	)
	(segment
		(start 412.235904 -221.485206)
		(end 414.086548 -221.485206)
		(width 0.16002)
		(layer "In11.Cu")
		(net "M_L_CPU0_SA_DQS_DP<7>")
	)
	(segment
		(start 406.716484 -227.004626)
		(end 407.02611 -226.695)
		(width 0.16002)
		(layer "In11.Cu")
		(net "M_L_CPU0_SA_DQS_DP<7>")
	)
	(segment
		(start 395.308328 -236.806486)
		(end 395.308328 -236.186726)
		(width 0.09525)
		(layer "In11.Cu")
		(net "M_L_CPU0_SA_DQS_DP<7>")
	)
	(segment
		(start 423.43451 -221.010226)
		(end 426.137832 -221.010226)
		(width 0.16002)
		(layer "In11.Cu")
		(net "M_L_CPU0_SA_DQS_DP<7>")
	)
	(segment
		(start 446.066672 -221.010226)
		(end 447.37782 -221.010226)
		(width 0.16002)
		(layer "In11.Cu")
		(net "M_L_CPU0_SA_DQS_DP<7>")
	)
	(segment
		(start 435.722268 -221.860364)
		(end 436.097426 -221.485206)
		(width 0.16002)
		(layer "In11.Cu")
		(net "M_L_CPU0_SA_DQS_DP<7>")
	)
	(segment
		(start 449.814442 -220.861382)
		(end 450.088 -221.13494)
		(width 0.16002)
		(layer "In11.Cu")
		(net "M_L_CPU0_SA_DQS_DP<7>")
	)
	(segment
		(start 416.07105 -220.001592)
		(end 416.36569 -220.001592)
		(width 0.16002)
		(layer "In11.Cu")
		(net "M_L_CPU0_SA_DQS_DP<7>")
	)
	(segment
		(start 444.262764 -221.485206)
		(end 445.116204 -220.631766)
		(width 0.16002)
		(layer "In11.Cu")
		(net "M_L_CPU0_SA_DQS_DP<7>")
	)
	(segment
		(start 440.845956 -221.010226)
		(end 441.696094 -221.860364)
		(width 0.16002)
		(layer "In11.Cu")
		(net "M_L_CPU0_SA_DQS_DP<7>")
	)
	(segment
		(start 437.57215 -220.631766)
		(end 438.144158 -220.631766)
		(width 0.16002)
		(layer "In11.Cu")
		(net "M_L_CPU0_SA_DQS_DP<7>")
	)
	(segment
		(start 408.399742 -225.321368)
		(end 408.976322 -225.321368)
		(width 0.16002)
		(layer "In11.Cu")
		(net "M_L_CPU0_SA_DQS_DP<7>")
	)
	(segment
		(start 392.405108 -237.692438)
		(end 392.428476 -237.678976)
		(width 0.09525)
		(layer "In11.Cu")
		(net "M_L_CPU0_SA_DQS_DP<7>")
	)
	(segment
		(start 408.090116 -226.207574)
		(end 408.090116 -225.630994)
		(width 0.16002)
		(layer "In11.Cu")
		(net "M_L_CPU0_SA_DQS_DP<7>")
	)
	(segment
		(start 449.006468 -220.861382)
		(end 449.814442 -220.861382)
		(width 0.16002)
		(layer "In11.Cu")
		(net "M_L_CPU0_SA_DQS_DP<7>")
	)
	(segment
		(start 433.549806 -221.010226)
		(end 434.399944 -221.860364)
		(width 0.16002)
		(layer "In11.Cu")
		(net "M_L_CPU0_SA_DQS_DP<7>")
	)
	(segment
		(start 415.440876 -220.631766)
		(end 416.07105 -220.001592)
		(width 0.16002)
		(layer "In11.Cu")
		(net "M_L_CPU0_SA_DQS_DP<7>")
	)
	(segment
		(start 406.229058 -228.068632)
		(end 406.716484 -227.581206)
		(width 0.16002)
		(layer "In11.Cu")
		(net "M_L_CPU0_SA_DQS_DP<7>")
	)
	(segment
		(start 406.716484 -227.581206)
		(end 406.716484 -227.004626)
		(width 0.16002)
		(layer "In11.Cu")
		(net "M_L_CPU0_SA_DQS_DP<7>")
	)
	(segment
		(start 409.773374 -223.947736)
		(end 410.349954 -223.947736)
		(width 0.16002)
		(layer "In11.Cu")
		(net "M_L_CPU0_SA_DQS_DP<7>")
	)
	(segment
		(start 428.553372 -221.485206)
		(end 429.174656 -221.485206)
		(width 0.16002)
		(layer "In11.Cu")
		(net "M_L_CPU0_SA_DQS_DP<7>")
	)
	(segment
		(start 438.144158 -220.631766)
		(end 438.522618 -221.010226)
		(width 0.16002)
		(layer "In11.Cu")
		(net "M_L_CPU0_SA_DQS_DP<7>")
	)
	(segment
		(start 416.36569 -220.001592)
		(end 417.24199 -220.877892)
		(width 0.16002)
		(layer "In11.Cu")
		(net "M_L_CPU0_SA_DQS_DP<7>")
	)
	(segment
		(start 395.60754 -235.887514)
		(end 395.757908 -235.887514)
		(width 0.09525)
		(layer "In11.Cu")
		(net "M_L_CPU0_SA_DQS_DP<7>")
	)
	(segment
		(start 420.63416 -221.860364)
		(end 421.009318 -221.485206)
		(width 0.16002)
		(layer "In11.Cu")
		(net "M_L_CPU0_SA_DQS_DP<7>")
	)
	(segment
		(start 408.090116 -225.630994)
		(end 408.399742 -225.321368)
		(width 0.16002)
		(layer "In11.Cu")
		(net "M_L_CPU0_SA_DQS_DP<7>")
	)
	(segment
		(start 447.37782 -221.010226)
		(end 447.526664 -220.861382)
		(width 0.16002)
		(layer "In11.Cu")
		(net "M_L_CPU0_SA_DQS_DP<7>")
	)
	(segment
		(start 428.178214 -221.860364)
		(end 428.553372 -221.485206)
		(width 0.16002)
		(layer "In11.Cu")
		(net "M_L_CPU0_SA_DQS_DP<7>")
	)
	(segment
		(start 392.78814 -237.669324)
		(end 392.804904 -237.678976)
		(width 0.09525)
		(layer "In11.Cu")
		(net "M_L_CPU0_SA_DQS_DP<7>")
	)
	(segment
		(start 389.035036 -237.67415)
		(end 389.043418 -237.678976)
		(width 0.09525)
		(layer "In11.Cu")
		(net "M_L_CPU0_SA_DQS_DP<7>")
	)
	(segment
		(start 448.399408 -220.988382)
		(end 448.879468 -220.988382)
		(width 0.16002)
		(layer "In11.Cu")
		(net "M_L_CPU0_SA_DQS_DP<7>")
	)
	(segment
		(start 436.71871 -221.485206)
		(end 437.57215 -220.631766)
		(width 0.16002)
		(layer "In11.Cu")
		(net "M_L_CPU0_SA_DQS_DP<7>")
	)
	(segment
		(start 419.316916 -221.860364)
		(end 420.63416 -221.860364)
		(width 0.16002)
		(layer "In11.Cu")
		(net "M_L_CPU0_SA_DQS_DP<7>")
	)
	(segment
		(start 445.116204 -220.631766)
		(end 445.688212 -220.631766)
		(width 0.16002)
		(layer "In11.Cu")
		(net "M_L_CPU0_SA_DQS_DP<7>")
	)
	(segment
		(start 436.097426 -221.485206)
		(end 436.71871 -221.485206)
		(width 0.16002)
		(layer "In11.Cu")
		(net "M_L_CPU0_SA_DQS_DP<7>")
	)
	(segment
		(start 443.266322 -221.860364)
		(end 443.64148 -221.485206)
		(width 0.16002)
		(layer "In11.Cu")
		(net "M_L_CPU0_SA_DQS_DP<7>")
	)
	(segment
		(start 423.05605 -220.631766)
		(end 423.43451 -221.010226)
		(width 0.16002)
		(layer "In11.Cu")
		(net "M_L_CPU0_SA_DQS_DP<7>")
	)
	(segment
		(start 434.399944 -221.860364)
		(end 435.722268 -221.860364)
		(width 0.16002)
		(layer "In11.Cu")
		(net "M_L_CPU0_SA_DQS_DP<7>")
	)
	(segment
		(start 421.009318 -221.485206)
		(end 421.630602 -221.485206)
		(width 0.16002)
		(layer "In11.Cu")
		(net "M_L_CPU0_SA_DQS_DP<7>")
	)
	(segment
		(start 395.816836 -235.946442)
		(end 395.840458 -235.946442)
		(width 0.09525)
		(layer "In11.Cu")
		(net "M_L_CPU0_SA_DQS_DP<7>")
	)
	(segment
		(start 421.630602 -221.485206)
		(end 422.484042 -220.631766)
		(width 0.16002)
		(layer "In11.Cu")
		(net "M_L_CPU0_SA_DQS_DP<7>")
	)
	(segment
		(start 414.086548 -221.485206)
		(end 414.939988 -220.631766)
		(width 0.16002)
		(layer "In11.Cu")
		(net "M_L_CPU0_SA_DQS_DP<7>")
	)
	(segment
		(start 410.349954 -223.947736)
		(end 410.83738 -223.46031)
		(width 0.16002)
		(layer "In11.Cu")
		(net "M_L_CPU0_SA_DQS_DP<7>")
	)
	(segment
		(start 430.600104 -220.631766)
		(end 430.978564 -221.010226)
		(width 0.16002)
		(layer "In11.Cu")
		(net "M_L_CPU0_SA_DQS_DP<7>")
	)
	(segment
		(start 445.688212 -220.631766)
		(end 446.066672 -221.010226)
		(width 0.16002)
		(layer "In11.Cu")
		(net "M_L_CPU0_SA_DQS_DP<7>")
	)
	(segment
		(start 409.463748 -224.257362)
		(end 409.773374 -223.947736)
		(width 0.16002)
		(layer "In11.Cu")
		(net "M_L_CPU0_SA_DQS_DP<7>")
	)
	(arc
		(start 385.904232 -237.651798)
		(mid 386.066914 -237.629666)
		(end 386.22351 -237.678976)
		(width 0.09525)
		(layer "In11.Cu")
		(net "M_L_CPU0_SA_DQS_DP<7>")
	)
	(arc
		(start 391.864342 -237.678976)
		(mid 392.133005 -237.755194)
		(end 392.405108 -237.692438)
		(width 0.09525)
		(layer "In11.Cu")
		(net "M_L_CPU0_SA_DQS_DP<7>")
	)
	(arc
		(start 389.043418 -237.678976)
		(mid 389.32485 -237.754731)
		(end 389.606282 -237.678976)
		(width 0.09525)
		(layer "In11.Cu")
		(net "M_L_CPU0_SA_DQS_DP<7>")
	)
	(arc
		(start 389.614664 -237.67415)
		(mid 389.799696 -237.628236)
		(end 389.983472 -237.678976)
		(width 0.09525)
		(layer "In11.Cu")
		(net "M_L_CPU0_SA_DQS_DP<7>")
	)
	(arc
		(start 389.983472 -237.678976)
		(mid 390.264904 -237.754731)
		(end 390.546336 -237.678976)
		(width 0.09525)
		(layer "In11.Cu")
		(net "M_L_CPU0_SA_DQS_DP<7>")
	)
	(arc
		(start 386.786374 -237.678976)
		(mid 386.974842 -237.628299)
		(end 387.16331 -237.678976)
		(width 0.09525)
		(layer "In11.Cu")
		(net "M_L_CPU0_SA_DQS_DP<7>")
	)
	(arc
		(start 390.546336 -237.678976)
		(mid 390.734804 -237.628299)
		(end 390.923272 -237.678976)
		(width 0.09525)
		(layer "In11.Cu")
		(net "M_L_CPU0_SA_DQS_DP<7>")
	)
	(arc
		(start 392.840972 -237.699804)
		(mid 393.10697 -237.755083)
		(end 393.367768 -237.678976)
		(width 0.09525)
		(layer "In11.Cu")
		(net "M_L_CPU0_SA_DQS_DP<7>")
	)
	(arc
		(start 387.726174 -237.678976)
		(mid 387.909949 -237.628204)
		(end 388.094982 -237.67415)
		(width 0.09525)
		(layer "In11.Cu")
		(net "M_L_CPU0_SA_DQS_DP<7>")
	)
	(arc
		(start 386.22351 -237.678976)
		(mid 386.504942 -237.754731)
		(end 386.786374 -237.678976)
		(width 0.09525)
		(layer "In11.Cu")
		(net "M_L_CPU0_SA_DQS_DP<7>")
	)
	(arc
		(start 393.367768 -237.678976)
		(mid 393.427472 -237.638944)
		(end 393.48156 -237.5916)
		(width 0.09525)
		(layer "In11.Cu")
		(net "M_L_CPU0_SA_DQS_DP<7>")
	)
	(arc
		(start 388.666228 -237.678976)
		(mid 388.850003 -237.628204)
		(end 389.035036 -237.67415)
		(width 0.09525)
		(layer "In11.Cu")
		(net "M_L_CPU0_SA_DQS_DP<7>")
	)
	(arc
		(start 388.103364 -237.678976)
		(mid 388.384796 -237.754731)
		(end 388.666228 -237.678976)
		(width 0.09525)
		(layer "In11.Cu")
		(net "M_L_CPU0_SA_DQS_DP<7>")
	)
	(arc
		(start 392.428476 -237.678976)
		(mid 392.607082 -237.628308)
		(end 392.78814 -237.669324)
		(width 0.09525)
		(layer "In11.Cu")
		(net "M_L_CPU0_SA_DQS_DP<7>")
	)
	(arc
		(start 391.500614 -237.670594)
		(mid 391.683554 -237.627919)
		(end 391.864342 -237.678976)
		(width 0.09525)
		(layer "In11.Cu")
		(net "M_L_CPU0_SA_DQS_DP<7>")
	)
	(arc
		(start 390.923272 -237.678976)
		(mid 391.204704 -237.754731)
		(end 391.486136 -237.678976)
		(width 0.09525)
		(layer "In11.Cu")
		(net "M_L_CPU0_SA_DQS_DP<7>")
	)
	(arc
		(start 387.16331 -237.678976)
		(mid 387.444742 -237.754731)
		(end 387.726174 -237.678976)
		(width 0.09525)
		(layer "In11.Cu")
		(net "M_L_CPU0_SA_DQS_DP<7>")
	)
	(segment
		(start 385.567936 -233.409998)
		(end 386.034788 -233.14406)
		(width 0.12954)
		(layer "F.Cu")
		(net "M_L_CPU0_SA_DQS_DP<6>")
	)
	(segment
		(start 436.097426 -212.135212)
		(end 436.71871 -212.135212)
		(width 0.16002)
		(layer "In11.Cu")
		(net "M_L_CPU0_SA_DQS_DP<6>")
	)
	(segment
		(start 448.978528 -211.511388)
		(end 449.814442 -211.511388)
		(width 0.16002)
		(layer "In11.Cu")
		(net "M_L_CPU0_SA_DQS_DP<6>")
	)
	(segment
		(start 448.244468 -211.511388)
		(end 448.371468 -211.638388)
		(width 0.16002)
		(layer "In11.Cu")
		(net "M_L_CPU0_SA_DQS_DP<6>")
	)
	(segment
		(start 395.627098 -230.115364)
		(end 395.643862 -230.0986)
		(width 0.09525)
		(layer "In11.Cu")
		(net "M_L_CPU0_SA_DQS_DP<6>")
	)
	(segment
		(start 405.876506 -218.27236)
		(end 405.71293 -218.108784)
		(width 0.16002)
		(layer "In11.Cu")
		(net "M_L_CPU0_SA_DQS_DP<6>")
	)
	(segment
		(start 446.066672 -211.660232)
		(end 447.37782 -211.660232)
		(width 0.16002)
		(layer "In11.Cu")
		(net "M_L_CPU0_SA_DQS_DP<6>")
	)
	(segment
		(start 418.421058 -211.520532)
		(end 419.410896 -212.51037)
		(width 0.16002)
		(layer "In11.Cu")
		(net "M_L_CPU0_SA_DQS_DP<6>")
	)
	(segment
		(start 417.661598 -211.520532)
		(end 418.421058 -211.520532)
		(width 0.16002)
		(layer "In11.Cu")
		(net "M_L_CPU0_SA_DQS_DP<6>")
	)
	(segment
		(start 414.086548 -212.135212)
		(end 414.939988 -211.281772)
		(width 0.16002)
		(layer "In11.Cu")
		(net "M_L_CPU0_SA_DQS_DP<6>")
	)
	(segment
		(start 435.722268 -212.51037)
		(end 436.097426 -212.135212)
		(width 0.16002)
		(layer "In11.Cu")
		(net "M_L_CPU0_SA_DQS_DP<6>")
	)
	(segment
		(start 428.553372 -212.135212)
		(end 429.174656 -212.135212)
		(width 0.16002)
		(layer "In11.Cu")
		(net "M_L_CPU0_SA_DQS_DP<6>")
	)
	(segment
		(start 430.600104 -211.281772)
		(end 430.978564 -211.660232)
		(width 0.16002)
		(layer "In11.Cu")
		(net "M_L_CPU0_SA_DQS_DP<6>")
	)
	(segment
		(start 395.643862 -230.0986)
		(end 395.643608 -230.0986)
		(width 0.16002)
		(layer "In11.Cu")
		(net "M_L_CPU0_SA_DQS_DP<6>")
	)
	(segment
		(start 430.978564 -211.660232)
		(end 433.554378 -211.660232)
		(width 0.16002)
		(layer "In11.Cu")
		(net "M_L_CPU0_SA_DQS_DP<6>")
	)
	(segment
		(start 403.129242 -221.496128)
		(end 403.129242 -221.019624)
		(width 0.16002)
		(layer "In11.Cu")
		(net "M_L_CPU0_SA_DQS_DP<6>")
	)
	(segment
		(start 389.606282 -232.81894)
		(end 389.614664 -232.814114)
		(width 0.09525)
		(layer "In11.Cu")
		(net "M_L_CPU0_SA_DQS_DP<6>")
	)
	(segment
		(start 402.228304 -221.920562)
		(end 402.704808 -221.920562)
		(width 0.16002)
		(layer "In11.Cu")
		(net "M_L_CPU0_SA_DQS_DP<6>")
	)
	(segment
		(start 404.585932 -219.009722)
		(end 404.811992 -219.009722)
		(width 0.16002)
		(layer "In11.Cu")
		(net "M_L_CPU0_SA_DQS_DP<6>")
	)
	(segment
		(start 394.180568 -232.032302)
		(end 394.180568 -231.478582)
		(width 0.09525)
		(layer "In11.Cu")
		(net "M_L_CPU0_SA_DQS_DP<6>")
	)
	(segment
		(start 420.63416 -212.51037)
		(end 421.009318 -212.135212)
		(width 0.16002)
		(layer "In11.Cu")
		(net "M_L_CPU0_SA_DQS_DP<6>")
	)
	(segment
		(start 428.178214 -212.51037)
		(end 428.553372 -212.135212)
		(width 0.16002)
		(layer "In11.Cu")
		(net "M_L_CPU0_SA_DQS_DP<6>")
	)
	(segment
		(start 401.838668 -221.756986)
		(end 402.064728 -221.756986)
		(width 0.16002)
		(layer "In11.Cu")
		(net "M_L_CPU0_SA_DQS_DP<6>")
	)
	(segment
		(start 421.009318 -212.135212)
		(end 421.630602 -212.135212)
		(width 0.16002)
		(layer "In11.Cu")
		(net "M_L_CPU0_SA_DQS_DP<6>")
	)
	(segment
		(start 405.876506 -218.748864)
		(end 405.876506 -218.27236)
		(width 0.16002)
		(layer "In11.Cu")
		(net "M_L_CPU0_SA_DQS_DP<6>")
	)
	(segment
		(start 392.405108 -232.832402)
		(end 392.428476 -232.81894)
		(width 0.09525)
		(layer "In11.Cu")
		(net "M_L_CPU0_SA_DQS_DP<6>")
	)
	(segment
		(start 422.484042 -211.281772)
		(end 423.05605 -211.281772)
		(width 0.16002)
		(layer "In11.Cu")
		(net "M_L_CPU0_SA_DQS_DP<6>")
	)
	(segment
		(start 416.950398 -211.520532)
		(end 417.077398 -211.647532)
		(width 0.16002)
		(layer "In11.Cu")
		(net "M_L_CPU0_SA_DQS_DP<6>")
	)
	(segment
		(start 423.05605 -211.281772)
		(end 423.43451 -211.660232)
		(width 0.16002)
		(layer "In11.Cu")
		(net "M_L_CPU0_SA_DQS_DP<6>")
	)
	(segment
		(start 437.57215 -211.281772)
		(end 438.144158 -211.281772)
		(width 0.16002)
		(layer "In11.Cu")
		(net "M_L_CPU0_SA_DQS_DP<6>")
	)
	(segment
		(start 405.71293 -218.108784)
		(end 405.71293 -217.882724)
		(width 0.16002)
		(layer "In11.Cu")
		(net "M_L_CPU0_SA_DQS_DP<6>")
	)
	(segment
		(start 414.939988 -211.281772)
		(end 415.511996 -211.281772)
		(width 0.16002)
		(layer "In11.Cu")
		(net "M_L_CPU0_SA_DQS_DP<6>")
	)
	(segment
		(start 443.266322 -212.51037)
		(end 443.64148 -212.135212)
		(width 0.16002)
		(layer "In11.Cu")
		(net "M_L_CPU0_SA_DQS_DP<6>")
	)
	(segment
		(start 444.262764 -212.135212)
		(end 445.116204 -211.281772)
		(width 0.16002)
		(layer "In11.Cu")
		(net "M_L_CPU0_SA_DQS_DP<6>")
	)
	(segment
		(start 440.845956 -211.660232)
		(end 441.696094 -212.51037)
		(width 0.16002)
		(layer "In11.Cu")
		(net "M_L_CPU0_SA_DQS_DP<6>")
	)
	(segment
		(start 405.71293 -217.882724)
		(end 411.460442 -212.135212)
		(width 0.16002)
		(layer "In11.Cu")
		(net "M_L_CPU0_SA_DQS_DP<6>")
	)
	(segment
		(start 402.704808 -221.920562)
		(end 403.129242 -221.496128)
		(width 0.16002)
		(layer "In11.Cu")
		(net "M_L_CPU0_SA_DQS_DP<6>")
	)
	(segment
		(start 395.643608 -230.0986)
		(end 401.169378 -224.572322)
		(width 0.16002)
		(layer "In11.Cu")
		(net "M_L_CPU0_SA_DQS_DP<6>")
	)
	(segment
		(start 404.975568 -219.173298)
		(end 405.452072 -219.173298)
		(width 0.16002)
		(layer "In11.Cu")
		(net "M_L_CPU0_SA_DQS_DP<6>")
	)
	(segment
		(start 433.554378 -211.660232)
		(end 434.404516 -212.51037)
		(width 0.16002)
		(layer "In11.Cu")
		(net "M_L_CPU0_SA_DQS_DP<6>")
	)
	(segment
		(start 392.804904 -232.81894)
		(end 392.840972 -232.839768)
		(width 0.09525)
		(layer "In11.Cu")
		(net "M_L_CPU0_SA_DQS_DP<6>")
	)
	(segment
		(start 393.888468 -232.324402)
		(end 394.180568 -232.032302)
		(width 0.09525)
		(layer "In11.Cu")
		(net "M_L_CPU0_SA_DQS_DP<6>")
	)
	(segment
		(start 401.169378 -224.572322)
		(end 401.169378 -222.426276)
		(width 0.16002)
		(layer "In11.Cu")
		(net "M_L_CPU0_SA_DQS_DP<6>")
	)
	(segment
		(start 403.2123 -220.383354)
		(end 403.43836 -220.383354)
		(width 0.16002)
		(layer "In11.Cu")
		(net "M_L_CPU0_SA_DQS_DP<6>")
	)
	(segment
		(start 415.750756 -211.520532)
		(end 416.950398 -211.520532)
		(width 0.16002)
		(layer "In11.Cu")
		(net "M_L_CPU0_SA_DQS_DP<6>")
	)
	(segment
		(start 436.71871 -212.135212)
		(end 437.57215 -211.281772)
		(width 0.16002)
		(layer "In11.Cu")
		(net "M_L_CPU0_SA_DQS_DP<6>")
	)
	(segment
		(start 421.630602 -212.135212)
		(end 422.484042 -211.281772)
		(width 0.16002)
		(layer "In11.Cu")
		(net "M_L_CPU0_SA_DQS_DP<6>")
	)
	(segment
		(start 448.851528 -211.638388)
		(end 448.978528 -211.511388)
		(width 0.16002)
		(layer "In11.Cu")
		(net "M_L_CPU0_SA_DQS_DP<6>")
	)
	(segment
		(start 404.811992 -219.009722)
		(end 404.975568 -219.173298)
		(width 0.16002)
		(layer "In11.Cu")
		(net "M_L_CPU0_SA_DQS_DP<6>")
	)
	(segment
		(start 438.144158 -211.281772)
		(end 438.522618 -211.660232)
		(width 0.16002)
		(layer "In11.Cu")
		(net "M_L_CPU0_SA_DQS_DP<6>")
	)
	(segment
		(start 441.696094 -212.51037)
		(end 443.266322 -212.51037)
		(width 0.16002)
		(layer "In11.Cu")
		(net "M_L_CPU0_SA_DQS_DP<6>")
	)
	(segment
		(start 401.169378 -222.426276)
		(end 401.838668 -221.756986)
		(width 0.16002)
		(layer "In11.Cu")
		(net "M_L_CPU0_SA_DQS_DP<6>")
	)
	(segment
		(start 426.98289 -212.51037)
		(end 428.178214 -212.51037)
		(width 0.16002)
		(layer "In11.Cu")
		(net "M_L_CPU0_SA_DQS_DP<6>")
	)
	(segment
		(start 402.965666 -220.856048)
		(end 402.965666 -220.629988)
		(width 0.16002)
		(layer "In11.Cu")
		(net "M_L_CPU0_SA_DQS_DP<6>")
	)
	(segment
		(start 404.502874 -219.645992)
		(end 404.339298 -219.482416)
		(width 0.16002)
		(layer "In11.Cu")
		(net "M_L_CPU0_SA_DQS_DP<6>")
	)
	(segment
		(start 449.814442 -211.511388)
		(end 450.088 -211.784946)
		(width 0.16002)
		(layer "In11.Cu")
		(net "M_L_CPU0_SA_DQS_DP<6>")
	)
	(segment
		(start 395.543786 -230.115364)
		(end 395.627098 -230.115364)
		(width 0.09525)
		(layer "In11.Cu")
		(net "M_L_CPU0_SA_DQS_DP<6>")
	)
	(segment
		(start 386.034788 -233.14406)
		(end 385.880864 -232.87863)
		(width 0.09525)
		(layer "In11.Cu")
		(net "M_L_CPU0_SA_DQS_DP<6>")
	)
	(segment
		(start 417.534598 -211.647532)
		(end 417.661598 -211.520532)
		(width 0.16002)
		(layer "In11.Cu")
		(net "M_L_CPU0_SA_DQS_DP<6>")
	)
	(segment
		(start 405.452072 -219.173298)
		(end 405.876506 -218.748864)
		(width 0.16002)
		(layer "In11.Cu")
		(net "M_L_CPU0_SA_DQS_DP<6>")
	)
	(segment
		(start 447.37782 -211.660232)
		(end 447.526664 -211.511388)
		(width 0.16002)
		(layer "In11.Cu")
		(net "M_L_CPU0_SA_DQS_DP<6>")
	)
	(segment
		(start 429.174656 -212.135212)
		(end 430.028096 -211.281772)
		(width 0.16002)
		(layer "In11.Cu")
		(net "M_L_CPU0_SA_DQS_DP<6>")
	)
	(segment
		(start 417.077398 -211.647532)
		(end 417.534598 -211.647532)
		(width 0.16002)
		(layer "In11.Cu")
		(net "M_L_CPU0_SA_DQS_DP<6>")
	)
	(segment
		(start 404.339298 -219.482416)
		(end 404.339298 -219.256356)
		(width 0.16002)
		(layer "In11.Cu")
		(net "M_L_CPU0_SA_DQS_DP<6>")
	)
	(segment
		(start 426.132752 -211.660232)
		(end 426.98289 -212.51037)
		(width 0.16002)
		(layer "In11.Cu")
		(net "M_L_CPU0_SA_DQS_DP<6>")
	)
	(segment
		(start 430.028096 -211.281772)
		(end 430.600104 -211.281772)
		(width 0.16002)
		(layer "In11.Cu")
		(net "M_L_CPU0_SA_DQS_DP<6>")
	)
	(segment
		(start 411.460442 -212.135212)
		(end 414.086548 -212.135212)
		(width 0.16002)
		(layer "In11.Cu")
		(net "M_L_CPU0_SA_DQS_DP<6>")
	)
	(segment
		(start 447.526664 -211.511388)
		(end 448.244468 -211.511388)
		(width 0.16002)
		(layer "In11.Cu")
		(net "M_L_CPU0_SA_DQS_DP<6>")
	)
	(segment
		(start 392.78814 -232.809288)
		(end 392.804904 -232.81894)
		(width 0.09525)
		(layer "In11.Cu")
		(net "M_L_CPU0_SA_DQS_DP<6>")
	)
	(segment
		(start 403.601936 -220.54693)
		(end 404.07844 -220.54693)
		(width 0.16002)
		(layer "In11.Cu")
		(net "M_L_CPU0_SA_DQS_DP<6>")
	)
	(segment
		(start 434.404516 -212.51037)
		(end 435.722268 -212.51037)
		(width 0.16002)
		(layer "In11.Cu")
		(net "M_L_CPU0_SA_DQS_DP<6>")
	)
	(segment
		(start 423.43451 -211.660232)
		(end 426.132752 -211.660232)
		(width 0.16002)
		(layer "In11.Cu")
		(net "M_L_CPU0_SA_DQS_DP<6>")
	)
	(segment
		(start 389.035036 -232.814114)
		(end 389.043418 -232.81894)
		(width 0.09525)
		(layer "In11.Cu")
		(net "M_L_CPU0_SA_DQS_DP<6>")
	)
	(segment
		(start 415.511996 -211.281772)
		(end 415.750756 -211.520532)
		(width 0.16002)
		(layer "In11.Cu")
		(net "M_L_CPU0_SA_DQS_DP<6>")
	)
	(segment
		(start 393.48156 -232.731564)
		(end 393.888468 -232.324402)
		(width 0.09525)
		(layer "In11.Cu")
		(net "M_L_CPU0_SA_DQS_DP<6>")
	)
	(segment
		(start 402.965666 -220.629988)
		(end 403.2123 -220.383354)
		(width 0.16002)
		(layer "In11.Cu")
		(net "M_L_CPU0_SA_DQS_DP<6>")
	)
	(segment
		(start 419.410896 -212.51037)
		(end 420.63416 -212.51037)
		(width 0.16002)
		(layer "In11.Cu")
		(net "M_L_CPU0_SA_DQS_DP<6>")
	)
	(segment
		(start 448.371468 -211.638388)
		(end 448.851528 -211.638388)
		(width 0.16002)
		(layer "In11.Cu")
		(net "M_L_CPU0_SA_DQS_DP<6>")
	)
	(segment
		(start 443.64148 -212.135212)
		(end 444.262764 -212.135212)
		(width 0.16002)
		(layer "In11.Cu")
		(net "M_L_CPU0_SA_DQS_DP<6>")
	)
	(segment
		(start 391.486136 -232.81894)
		(end 391.500614 -232.810558)
		(width 0.09525)
		(layer "In11.Cu")
		(net "M_L_CPU0_SA_DQS_DP<6>")
	)
	(segment
		(start 394.180568 -231.478582)
		(end 395.543786 -230.115364)
		(width 0.09525)
		(layer "In11.Cu")
		(net "M_L_CPU0_SA_DQS_DP<6>")
	)
	(segment
		(start 445.116204 -211.281772)
		(end 445.688212 -211.281772)
		(width 0.16002)
		(layer "In11.Cu")
		(net "M_L_CPU0_SA_DQS_DP<6>")
	)
	(segment
		(start 403.129242 -221.019624)
		(end 402.965666 -220.856048)
		(width 0.16002)
		(layer "In11.Cu")
		(net "M_L_CPU0_SA_DQS_DP<6>")
	)
	(segment
		(start 385.880864 -232.87863)
		(end 385.904232 -232.791762)
		(width 0.09525)
		(layer "In11.Cu")
		(net "M_L_CPU0_SA_DQS_DP<6>")
	)
	(segment
		(start 438.522618 -211.660232)
		(end 440.845956 -211.660232)
		(width 0.16002)
		(layer "In11.Cu")
		(net "M_L_CPU0_SA_DQS_DP<6>")
	)
	(segment
		(start 402.064728 -221.756986)
		(end 402.228304 -221.920562)
		(width 0.16002)
		(layer "In11.Cu")
		(net "M_L_CPU0_SA_DQS_DP<6>")
	)
	(segment
		(start 445.688212 -211.281772)
		(end 446.066672 -211.660232)
		(width 0.16002)
		(layer "In11.Cu")
		(net "M_L_CPU0_SA_DQS_DP<6>")
	)
	(segment
		(start 404.502874 -220.122496)
		(end 404.502874 -219.645992)
		(width 0.16002)
		(layer "In11.Cu")
		(net "M_L_CPU0_SA_DQS_DP<6>")
	)
	(segment
		(start 404.339298 -219.256356)
		(end 404.585932 -219.009722)
		(width 0.16002)
		(layer "In11.Cu")
		(net "M_L_CPU0_SA_DQS_DP<6>")
	)
	(segment
		(start 388.094982 -232.814114)
		(end 388.103364 -232.81894)
		(width 0.09525)
		(layer "In11.Cu")
		(net "M_L_CPU0_SA_DQS_DP<6>")
	)
	(segment
		(start 404.07844 -220.54693)
		(end 404.502874 -220.122496)
		(width 0.16002)
		(layer "In11.Cu")
		(net "M_L_CPU0_SA_DQS_DP<6>")
	)
	(segment
		(start 403.43836 -220.383354)
		(end 403.601936 -220.54693)
		(width 0.16002)
		(layer "In11.Cu")
		(net "M_L_CPU0_SA_DQS_DP<6>")
	)
	(arc
		(start 386.786374 -232.81894)
		(mid 386.974842 -232.768263)
		(end 387.16331 -232.81894)
		(width 0.09525)
		(layer "In11.Cu")
		(net "M_L_CPU0_SA_DQS_DP<6>")
	)
	(arc
		(start 386.22351 -232.81894)
		(mid 386.504942 -232.894695)
		(end 386.786374 -232.81894)
		(width 0.09525)
		(layer "In11.Cu")
		(net "M_L_CPU0_SA_DQS_DP<6>")
	)
	(arc
		(start 390.923272 -232.81894)
		(mid 391.204704 -232.894695)
		(end 391.486136 -232.81894)
		(width 0.09525)
		(layer "In11.Cu")
		(net "M_L_CPU0_SA_DQS_DP<6>")
	)
	(arc
		(start 393.367768 -232.81894)
		(mid 393.427472 -232.778908)
		(end 393.48156 -232.731564)
		(width 0.09525)
		(layer "In11.Cu")
		(net "M_L_CPU0_SA_DQS_DP<6>")
	)
	(arc
		(start 390.546336 -232.81894)
		(mid 390.734804 -232.768263)
		(end 390.923272 -232.81894)
		(width 0.09525)
		(layer "In11.Cu")
		(net "M_L_CPU0_SA_DQS_DP<6>")
	)
	(arc
		(start 389.043418 -232.81894)
		(mid 389.32485 -232.894695)
		(end 389.606282 -232.81894)
		(width 0.09525)
		(layer "In11.Cu")
		(net "M_L_CPU0_SA_DQS_DP<6>")
	)
	(arc
		(start 392.840972 -232.839768)
		(mid 393.10697 -232.895047)
		(end 393.367768 -232.81894)
		(width 0.09525)
		(layer "In11.Cu")
		(net "M_L_CPU0_SA_DQS_DP<6>")
	)
	(arc
		(start 389.614664 -232.814114)
		(mid 389.799696 -232.7682)
		(end 389.983472 -232.81894)
		(width 0.09525)
		(layer "In11.Cu")
		(net "M_L_CPU0_SA_DQS_DP<6>")
	)
	(arc
		(start 391.864342 -232.81894)
		(mid 392.133005 -232.895158)
		(end 392.405108 -232.832402)
		(width 0.09525)
		(layer "In11.Cu")
		(net "M_L_CPU0_SA_DQS_DP<6>")
	)
	(arc
		(start 387.726174 -232.81894)
		(mid 387.909949 -232.768168)
		(end 388.094982 -232.814114)
		(width 0.09525)
		(layer "In11.Cu")
		(net "M_L_CPU0_SA_DQS_DP<6>")
	)
	(arc
		(start 388.666228 -232.81894)
		(mid 388.850003 -232.768168)
		(end 389.035036 -232.814114)
		(width 0.09525)
		(layer "In11.Cu")
		(net "M_L_CPU0_SA_DQS_DP<6>")
	)
	(arc
		(start 387.16331 -232.81894)
		(mid 387.444742 -232.894695)
		(end 387.726174 -232.81894)
		(width 0.09525)
		(layer "In11.Cu")
		(net "M_L_CPU0_SA_DQS_DP<6>")
	)
	(arc
		(start 389.983472 -232.81894)
		(mid 390.264904 -232.894695)
		(end 390.546336 -232.81894)
		(width 0.09525)
		(layer "In11.Cu")
		(net "M_L_CPU0_SA_DQS_DP<6>")
	)
	(arc
		(start 392.428476 -232.81894)
		(mid 392.607082 -232.768272)
		(end 392.78814 -232.809288)
		(width 0.09525)
		(layer "In11.Cu")
		(net "M_L_CPU0_SA_DQS_DP<6>")
	)
	(arc
		(start 391.500614 -232.810558)
		(mid 391.683554 -232.767883)
		(end 391.864342 -232.81894)
		(width 0.09525)
		(layer "In11.Cu")
		(net "M_L_CPU0_SA_DQS_DP<6>")
	)
	(arc
		(start 385.904232 -232.791762)
		(mid 386.066914 -232.76963)
		(end 386.22351 -232.81894)
		(width 0.09525)
		(layer "In11.Cu")
		(net "M_L_CPU0_SA_DQS_DP<6>")
	)
	(arc
		(start 388.103364 -232.81894)
		(mid 388.384796 -232.894695)
		(end 388.666228 -232.81894)
		(width 0.09525)
		(layer "In11.Cu")
		(net "M_L_CPU0_SA_DQS_DP<6>")
	)
	(segment
		(start 385.567936 -228.550216)
		(end 386.034788 -228.284278)
		(width 0.12954)
		(layer "F.Cu")
		(net "M_L_CPU0_SA_DQS_DP<5>")
	)
	(segment
		(start 423.43451 -202.310238)
		(end 426.111924 -202.310238)
		(width 0.16002)
		(layer "In11.Cu")
		(net "M_L_CPU0_SA_DQS_DP<5>")
	)
	(segment
		(start 434.383688 -203.160376)
		(end 435.722268 -203.160376)
		(width 0.16002)
		(layer "In11.Cu")
		(net "M_L_CPU0_SA_DQS_DP<5>")
	)
	(segment
		(start 402.999194 -210.337654)
		(end 410.55163 -202.785218)
		(width 0.16002)
		(layer "In11.Cu")
		(net "M_L_CPU0_SA_DQS_DP<5>")
	)
	(segment
		(start 389.035036 -227.954332)
		(end 389.043418 -227.959158)
		(width 0.09525)
		(layer "In11.Cu")
		(net "M_L_CPU0_SA_DQS_DP<5>")
	)
	(segment
		(start 385.880864 -228.018848)
		(end 385.904232 -227.93198)
		(width 0.09525)
		(layer "In11.Cu")
		(net "M_L_CPU0_SA_DQS_DP<5>")
	)
	(segment
		(start 386.034788 -228.284278)
		(end 385.880864 -228.018848)
		(width 0.09525)
		(layer "In11.Cu")
		(net "M_L_CPU0_SA_DQS_DP<5>")
	)
	(segment
		(start 445.688212 -201.931778)
		(end 446.066672 -202.310238)
		(width 0.16002)
		(layer "In11.Cu")
		(net "M_L_CPU0_SA_DQS_DP<5>")
	)
	(segment
		(start 400.967956 -213.081362)
		(end 401.44446 -213.081362)
		(width 0.16002)
		(layer "In11.Cu")
		(net "M_L_CPU0_SA_DQS_DP<5>")
	)
	(segment
		(start 414.086548 -202.785218)
		(end 414.939988 -201.931778)
		(width 0.16002)
		(layer "In11.Cu")
		(net "M_L_CPU0_SA_DQS_DP<5>")
	)
	(segment
		(start 395.008608 -222.385128)
		(end 395.230096 -222.16364)
		(width 0.09525)
		(layer "In11.Cu")
		(net "M_L_CPU0_SA_DQS_DP<5>")
	)
	(segment
		(start 449.016628 -202.161394)
		(end 449.814442 -202.161394)
		(width 0.16002)
		(layer "In11.Cu")
		(net "M_L_CPU0_SA_DQS_DP<5>")
	)
	(segment
		(start 420.63416 -203.160376)
		(end 421.009318 -202.785218)
		(width 0.16002)
		(layer "In11.Cu")
		(net "M_L_CPU0_SA_DQS_DP<5>")
	)
	(segment
		(start 401.625562 -211.937346)
		(end 401.625562 -211.711286)
		(width 0.16002)
		(layer "In11.Cu")
		(net "M_L_CPU0_SA_DQS_DP<5>")
	)
	(segment
		(start 415.511996 -201.931778)
		(end 415.67481 -202.094592)
		(width 0.16002)
		(layer "In11.Cu")
		(net "M_L_CPU0_SA_DQS_DP<5>")
	)
	(segment
		(start 388.094982 -227.954332)
		(end 388.103364 -227.959158)
		(width 0.09525)
		(layer "In11.Cu")
		(net "M_L_CPU0_SA_DQS_DP<5>")
	)
	(segment
		(start 416.613848 -202.094592)
		(end 416.740848 -202.221592)
		(width 0.16002)
		(layer "In11.Cu")
		(net "M_L_CPU0_SA_DQS_DP<5>")
	)
	(segment
		(start 414.939988 -201.931778)
		(end 415.511996 -201.931778)
		(width 0.16002)
		(layer "In11.Cu")
		(net "M_L_CPU0_SA_DQS_DP<5>")
	)
	(segment
		(start 401.868894 -212.180424)
		(end 401.625562 -211.937346)
		(width 0.16002)
		(layer "In11.Cu")
		(net "M_L_CPU0_SA_DQS_DP<5>")
	)
	(segment
		(start 447.313812 -202.310238)
		(end 447.462656 -202.161394)
		(width 0.16002)
		(layer "In11.Cu")
		(net "M_L_CPU0_SA_DQS_DP<5>")
	)
	(segment
		(start 433.53355 -202.310238)
		(end 434.383688 -203.160376)
		(width 0.16002)
		(layer "In11.Cu")
		(net "M_L_CPU0_SA_DQS_DP<5>")
	)
	(segment
		(start 393.836144 -223.909128)
		(end 393.874244 -223.88703)
		(width 0.09525)
		(layer "In11.Cu")
		(net "M_L_CPU0_SA_DQS_DP<5>")
	)
	(segment
		(start 447.462656 -202.161394)
		(end 448.282568 -202.161394)
		(width 0.16002)
		(layer "In11.Cu")
		(net "M_L_CPU0_SA_DQS_DP<5>")
	)
	(segment
		(start 421.009318 -202.785218)
		(end 421.630602 -202.785218)
		(width 0.16002)
		(layer "In11.Cu")
		(net "M_L_CPU0_SA_DQS_DP<5>")
	)
	(segment
		(start 410.55163 -202.785218)
		(end 414.086548 -202.785218)
		(width 0.16002)
		(layer "In11.Cu")
		(net "M_L_CPU0_SA_DQS_DP<5>")
	)
	(segment
		(start 417.347908 -202.094592)
		(end 418.276532 -202.094592)
		(width 0.16002)
		(layer "In11.Cu")
		(net "M_L_CPU0_SA_DQS_DP<5>")
	)
	(segment
		(start 449.814442 -202.161394)
		(end 450.088 -202.434952)
		(width 0.16002)
		(layer "In11.Cu")
		(net "M_L_CPU0_SA_DQS_DP<5>")
	)
	(segment
		(start 416.740848 -202.221592)
		(end 417.220908 -202.221592)
		(width 0.16002)
		(layer "In11.Cu")
		(net "M_L_CPU0_SA_DQS_DP<5>")
	)
	(segment
		(start 444.262764 -202.785218)
		(end 445.116204 -201.931778)
		(width 0.16002)
		(layer "In11.Cu")
		(net "M_L_CPU0_SA_DQS_DP<5>")
	)
	(segment
		(start 395.230096 -222.16364)
		(end 395.230096 -221.474538)
		(width 0.09525)
		(layer "In11.Cu")
		(net "M_L_CPU0_SA_DQS_DP<5>")
	)
	(segment
		(start 389.606282 -227.959158)
		(end 389.614664 -227.954332)
		(width 0.09525)
		(layer "In11.Cu")
		(net "M_L_CPU0_SA_DQS_DP<5>")
	)
	(segment
		(start 415.67481 -202.094592)
		(end 416.613848 -202.094592)
		(width 0.16002)
		(layer "In11.Cu")
		(net "M_L_CPU0_SA_DQS_DP<5>")
	)
	(segment
		(start 448.889628 -202.288394)
		(end 449.016628 -202.161394)
		(width 0.16002)
		(layer "In11.Cu")
		(net "M_L_CPU0_SA_DQS_DP<5>")
	)
	(segment
		(start 426.111924 -202.310238)
		(end 426.962062 -203.160376)
		(width 0.16002)
		(layer "In11.Cu")
		(net "M_L_CPU0_SA_DQS_DP<5>")
	)
	(segment
		(start 395.289024 -221.391988)
		(end 395.289024 -218.047824)
		(width 0.16002)
		(layer "In11.Cu")
		(net "M_L_CPU0_SA_DQS_DP<5>")
	)
	(segment
		(start 421.630602 -202.785218)
		(end 422.484042 -201.931778)
		(width 0.16002)
		(layer "In11.Cu")
		(net "M_L_CPU0_SA_DQS_DP<5>")
	)
	(segment
		(start 435.722268 -203.160376)
		(end 436.097426 -202.785218)
		(width 0.16002)
		(layer "In11.Cu")
		(net "M_L_CPU0_SA_DQS_DP<5>")
	)
	(segment
		(start 395.289024 -221.41561)
		(end 395.289024 -221.391988)
		(width 0.09525)
		(layer "In11.Cu")
		(net "M_L_CPU0_SA_DQS_DP<5>")
	)
	(segment
		(start 422.484042 -201.931778)
		(end 423.05605 -201.931778)
		(width 0.16002)
		(layer "In11.Cu")
		(net "M_L_CPU0_SA_DQS_DP<5>")
	)
	(segment
		(start 436.71871 -202.785218)
		(end 437.57215 -201.931778)
		(width 0.16002)
		(layer "In11.Cu")
		(net "M_L_CPU0_SA_DQS_DP<5>")
	)
	(segment
		(start 448.409568 -202.288394)
		(end 448.889628 -202.288394)
		(width 0.16002)
		(layer "In11.Cu")
		(net "M_L_CPU0_SA_DQS_DP<5>")
	)
	(segment
		(start 395.289024 -218.047824)
		(end 400.498564 -212.838284)
		(width 0.16002)
		(layer "In11.Cu")
		(net "M_L_CPU0_SA_DQS_DP<5>")
	)
	(segment
		(start 441.696094 -203.160376)
		(end 443.266322 -203.160376)
		(width 0.16002)
		(layer "In11.Cu")
		(net "M_L_CPU0_SA_DQS_DP<5>")
	)
	(segment
		(start 440.845956 -202.310238)
		(end 441.696094 -203.160376)
		(width 0.16002)
		(layer "In11.Cu")
		(net "M_L_CPU0_SA_DQS_DP<5>")
	)
	(segment
		(start 448.282568 -202.161394)
		(end 448.409568 -202.288394)
		(width 0.16002)
		(layer "In11.Cu")
		(net "M_L_CPU0_SA_DQS_DP<5>")
	)
	(segment
		(start 430.028096 -201.931778)
		(end 430.600104 -201.931778)
		(width 0.16002)
		(layer "In11.Cu")
		(net "M_L_CPU0_SA_DQS_DP<5>")
	)
	(segment
		(start 402.999194 -210.563714)
		(end 402.999194 -210.337654)
		(width 0.16002)
		(layer "In11.Cu")
		(net "M_L_CPU0_SA_DQS_DP<5>")
	)
	(segment
		(start 417.220908 -202.221592)
		(end 417.347908 -202.094592)
		(width 0.16002)
		(layer "In11.Cu")
		(net "M_L_CPU0_SA_DQS_DP<5>")
	)
	(segment
		(start 443.64148 -202.785218)
		(end 444.262764 -202.785218)
		(width 0.16002)
		(layer "In11.Cu")
		(net "M_L_CPU0_SA_DQS_DP<5>")
	)
	(segment
		(start 419.342316 -203.160376)
		(end 420.63416 -203.160376)
		(width 0.16002)
		(layer "In11.Cu")
		(net "M_L_CPU0_SA_DQS_DP<5>")
	)
	(segment
		(start 394.117068 -223.424242)
		(end 394.11656 -223.424242)
		(width 0.09525)
		(layer "In11.Cu")
		(net "M_L_CPU0_SA_DQS_DP<5>")
	)
	(segment
		(start 445.116204 -201.931778)
		(end 445.688212 -201.931778)
		(width 0.16002)
		(layer "In11.Cu")
		(net "M_L_CPU0_SA_DQS_DP<5>")
	)
	(segment
		(start 402.818092 -211.70773)
		(end 403.242526 -211.283296)
		(width 0.16002)
		(layer "In11.Cu")
		(net "M_L_CPU0_SA_DQS_DP<5>")
	)
	(segment
		(start 393.333986 -224.73793)
		(end 393.366498 -224.719134)
		(width 0.09525)
		(layer "In11.Cu")
		(net "M_L_CPU0_SA_DQS_DP<5>")
	)
	(segment
		(start 395.230096 -221.474538)
		(end 395.289024 -221.41561)
		(width 0.09525)
		(layer "In11.Cu")
		(net "M_L_CPU0_SA_DQS_DP<5>")
	)
	(segment
		(start 428.553372 -202.785218)
		(end 429.174656 -202.785218)
		(width 0.16002)
		(layer "In11.Cu")
		(net "M_L_CPU0_SA_DQS_DP<5>")
	)
	(segment
		(start 391.922508 -227.16871)
		(end 391.95629 -227.149152)
		(width 0.09525)
		(layer "In11.Cu")
		(net "M_L_CPU0_SA_DQS_DP<5>")
	)
	(segment
		(start 428.178214 -203.160376)
		(end 428.553372 -202.785218)
		(width 0.16002)
		(layer "In11.Cu")
		(net "M_L_CPU0_SA_DQS_DP<5>")
	)
	(segment
		(start 400.724624 -212.838284)
		(end 400.967956 -213.081362)
		(width 0.16002)
		(layer "In11.Cu")
		(net "M_L_CPU0_SA_DQS_DP<5>")
	)
	(segment
		(start 401.625562 -211.711286)
		(end 401.872196 -211.464652)
		(width 0.16002)
		(layer "In11.Cu")
		(net "M_L_CPU0_SA_DQS_DP<5>")
	)
	(segment
		(start 443.266322 -203.160376)
		(end 443.64148 -202.785218)
		(width 0.16002)
		(layer "In11.Cu")
		(net "M_L_CPU0_SA_DQS_DP<5>")
	)
	(segment
		(start 392.3919 -226.359212)
		(end 392.426698 -226.339146)
		(width 0.09525)
		(layer "In11.Cu")
		(net "M_L_CPU0_SA_DQS_DP<5>")
	)
	(segment
		(start 446.066672 -202.310238)
		(end 447.313812 -202.310238)
		(width 0.16002)
		(layer "In11.Cu")
		(net "M_L_CPU0_SA_DQS_DP<5>")
	)
	(segment
		(start 403.242526 -210.806792)
		(end 402.999194 -210.563714)
		(width 0.16002)
		(layer "In11.Cu")
		(net "M_L_CPU0_SA_DQS_DP<5>")
	)
	(segment
		(start 418.276532 -202.094592)
		(end 419.342316 -203.160376)
		(width 0.16002)
		(layer "In11.Cu")
		(net "M_L_CPU0_SA_DQS_DP<5>")
	)
	(segment
		(start 391.95629 -227.149152)
		(end 391.99439 -227.127054)
		(width 0.09525)
		(layer "In11.Cu")
		(net "M_L_CPU0_SA_DQS_DP<5>")
	)
	(segment
		(start 438.522618 -202.310238)
		(end 440.845956 -202.310238)
		(width 0.16002)
		(layer "In11.Cu")
		(net "M_L_CPU0_SA_DQS_DP<5>")
	)
	(segment
		(start 438.144158 -201.931778)
		(end 438.522618 -202.310238)
		(width 0.16002)
		(layer "In11.Cu")
		(net "M_L_CPU0_SA_DQS_DP<5>")
	)
	(segment
		(start 400.498564 -212.838284)
		(end 400.724624 -212.838284)
		(width 0.16002)
		(layer "In11.Cu")
		(net "M_L_CPU0_SA_DQS_DP<5>")
	)
	(segment
		(start 437.57215 -201.931778)
		(end 438.144158 -201.931778)
		(width 0.16002)
		(layer "In11.Cu")
		(net "M_L_CPU0_SA_DQS_DP<5>")
	)
	(segment
		(start 391.486136 -227.959158)
		(end 391.524236 -227.93706)
		(width 0.09525)
		(layer "In11.Cu")
		(net "M_L_CPU0_SA_DQS_DP<5>")
	)
	(segment
		(start 430.978564 -202.310238)
		(end 433.53355 -202.310238)
		(width 0.16002)
		(layer "In11.Cu")
		(net "M_L_CPU0_SA_DQS_DP<5>")
	)
	(segment
		(start 423.05605 -201.931778)
		(end 423.43451 -202.310238)
		(width 0.16002)
		(layer "In11.Cu")
		(net "M_L_CPU0_SA_DQS_DP<5>")
	)
	(segment
		(start 430.600104 -201.931778)
		(end 430.978564 -202.310238)
		(width 0.16002)
		(layer "In11.Cu")
		(net "M_L_CPU0_SA_DQS_DP<5>")
	)
	(segment
		(start 426.962062 -203.160376)
		(end 428.178214 -203.160376)
		(width 0.16002)
		(layer "In11.Cu")
		(net "M_L_CPU0_SA_DQS_DP<5>")
	)
	(segment
		(start 429.174656 -202.785218)
		(end 430.028096 -201.931778)
		(width 0.16002)
		(layer "In11.Cu")
		(net "M_L_CPU0_SA_DQS_DP<5>")
	)
	(segment
		(start 436.097426 -202.785218)
		(end 436.71871 -202.785218)
		(width 0.16002)
		(layer "In11.Cu")
		(net "M_L_CPU0_SA_DQS_DP<5>")
	)
	(segment
		(start 403.242526 -211.283296)
		(end 403.242526 -210.806792)
		(width 0.16002)
		(layer "In11.Cu")
		(net "M_L_CPU0_SA_DQS_DP<5>")
	)
	(segment
		(start 392.896344 -225.52914)
		(end 392.937238 -225.505518)
		(width 0.09525)
		(layer "In11.Cu")
		(net "M_L_CPU0_SA_DQS_DP<5>")
	)
	(segment
		(start 393.366498 -224.719134)
		(end 393.403074 -224.697798)
		(width 0.09525)
		(layer "In11.Cu")
		(net "M_L_CPU0_SA_DQS_DP<5>")
	)
	(segment
		(start 402.098256 -211.464652)
		(end 402.341588 -211.70773)
		(width 0.16002)
		(layer "In11.Cu")
		(net "M_L_CPU0_SA_DQS_DP<5>")
	)
	(segment
		(start 392.866118 -225.546666)
		(end 392.896344 -225.52914)
		(width 0.09525)
		(layer "In11.Cu")
		(net "M_L_CPU0_SA_DQS_DP<5>")
	)
	(segment
		(start 401.868894 -212.656928)
		(end 401.868894 -212.180424)
		(width 0.16002)
		(layer "In11.Cu")
		(net "M_L_CPU0_SA_DQS_DP<5>")
	)
	(segment
		(start 394.182092 -223.211898)
		(end 395.008608 -222.385128)
		(width 0.09525)
		(layer "In11.Cu")
		(net "M_L_CPU0_SA_DQS_DP<5>")
	)
	(segment
		(start 392.426698 -226.339146)
		(end 392.46175 -226.318572)
		(width 0.09525)
		(layer "In11.Cu")
		(net "M_L_CPU0_SA_DQS_DP<5>")
	)
	(segment
		(start 401.44446 -213.081362)
		(end 401.868894 -212.656928)
		(width 0.16002)
		(layer "In11.Cu")
		(net "M_L_CPU0_SA_DQS_DP<5>")
	)
	(segment
		(start 402.341588 -211.70773)
		(end 402.818092 -211.70773)
		(width 0.16002)
		(layer "In11.Cu")
		(net "M_L_CPU0_SA_DQS_DP<5>")
	)
	(segment
		(start 393.804648 -223.927416)
		(end 393.836144 -223.909128)
		(width 0.09525)
		(layer "In11.Cu")
		(net "M_L_CPU0_SA_DQS_DP<5>")
	)
	(segment
		(start 401.872196 -211.464652)
		(end 402.098256 -211.464652)
		(width 0.16002)
		(layer "In11.Cu")
		(net "M_L_CPU0_SA_DQS_DP<5>")
	)
	(arc
		(start 390.923272 -227.959158)
		(mid 391.204704 -228.034913)
		(end 391.486136 -227.959158)
		(width 0.09525)
		(layer "In11.Cu")
		(net "M_L_CPU0_SA_DQS_DP<5>")
	)
	(arc
		(start 394.11656 -223.424242)
		(mid 394.133398 -223.313158)
		(end 394.182092 -223.211898)
		(width 0.09525)
		(layer "In11.Cu")
		(net "M_L_CPU0_SA_DQS_DP<5>")
	)
	(arc
		(start 388.666228 -227.959158)
		(mid 388.850003 -227.908386)
		(end 389.035036 -227.954332)
		(width 0.09525)
		(layer "In11.Cu")
		(net "M_L_CPU0_SA_DQS_DP<5>")
	)
	(arc
		(start 390.546336 -227.959158)
		(mid 390.734804 -227.908481)
		(end 390.923272 -227.959158)
		(width 0.09525)
		(layer "In11.Cu")
		(net "M_L_CPU0_SA_DQS_DP<5>")
	)
	(arc
		(start 386.786374 -227.959158)
		(mid 386.974842 -227.908481)
		(end 387.16331 -227.959158)
		(width 0.09525)
		(layer "In11.Cu")
		(net "M_L_CPU0_SA_DQS_DP<5>")
	)
	(arc
		(start 392.237214 -226.664266)
		(mid 392.27809 -226.493244)
		(end 392.3919 -226.359212)
		(width 0.09525)
		(layer "In11.Cu")
		(net "M_L_CPU0_SA_DQS_DP<5>")
	)
	(arc
		(start 385.904232 -227.93198)
		(mid 386.066914 -227.909848)
		(end 386.22351 -227.959158)
		(width 0.09525)
		(layer "In11.Cu")
		(net "M_L_CPU0_SA_DQS_DP<5>")
	)
	(arc
		(start 389.043418 -227.959158)
		(mid 389.32485 -228.034913)
		(end 389.606282 -227.959158)
		(width 0.09525)
		(layer "In11.Cu")
		(net "M_L_CPU0_SA_DQS_DP<5>")
	)
	(arc
		(start 389.983472 -227.959158)
		(mid 390.264904 -228.034913)
		(end 390.546336 -227.959158)
		(width 0.09525)
		(layer "In11.Cu")
		(net "M_L_CPU0_SA_DQS_DP<5>")
	)
	(arc
		(start 391.76706 -227.474272)
		(mid 391.808162 -227.302866)
		(end 391.922508 -227.16871)
		(width 0.09525)
		(layer "In11.Cu")
		(net "M_L_CPU0_SA_DQS_DP<5>")
	)
	(arc
		(start 386.22351 -227.959158)
		(mid 386.504942 -228.034913)
		(end 386.786374 -227.959158)
		(width 0.09525)
		(layer "In11.Cu")
		(net "M_L_CPU0_SA_DQS_DP<5>")
	)
	(arc
		(start 387.726174 -227.959158)
		(mid 387.909949 -227.908386)
		(end 388.094982 -227.954332)
		(width 0.09525)
		(layer "In11.Cu")
		(net "M_L_CPU0_SA_DQS_DP<5>")
	)
	(arc
		(start 392.707368 -225.85426)
		(mid 392.74939 -225.681181)
		(end 392.866118 -225.546666)
		(width 0.09525)
		(layer "In11.Cu")
		(net "M_L_CPU0_SA_DQS_DP<5>")
	)
	(arc
		(start 391.524236 -227.93706)
		(mid 391.702686 -227.73559)
		(end 391.76706 -227.474272)
		(width 0.09525)
		(layer "In11.Cu")
		(net "M_L_CPU0_SA_DQS_DP<5>")
	)
	(arc
		(start 393.403074 -224.697798)
		(mid 393.582446 -224.496203)
		(end 393.647168 -224.234248)
		(width 0.09525)
		(layer "In11.Cu")
		(net "M_L_CPU0_SA_DQS_DP<5>")
	)
	(arc
		(start 393.177522 -225.044254)
		(mid 393.218894 -224.872258)
		(end 393.333986 -224.73793)
		(width 0.09525)
		(layer "In11.Cu")
		(net "M_L_CPU0_SA_DQS_DP<5>")
	)
	(arc
		(start 392.46175 -226.318572)
		(mid 392.642141 -226.116873)
		(end 392.707368 -225.85426)
		(width 0.09525)
		(layer "In11.Cu")
		(net "M_L_CPU0_SA_DQS_DP<5>")
	)
	(arc
		(start 387.16331 -227.959158)
		(mid 387.444742 -228.034913)
		(end 387.726174 -227.959158)
		(width 0.09525)
		(layer "In11.Cu")
		(net "M_L_CPU0_SA_DQS_DP<5>")
	)
	(arc
		(start 393.874244 -223.88703)
		(mid 394.052694 -223.68556)
		(end 394.117068 -223.424242)
		(width 0.09525)
		(layer "In11.Cu")
		(net "M_L_CPU0_SA_DQS_DP<5>")
	)
	(arc
		(start 393.647168 -224.234248)
		(mid 393.688833 -224.061801)
		(end 393.804648 -223.927416)
		(width 0.09525)
		(layer "In11.Cu")
		(net "M_L_CPU0_SA_DQS_DP<5>")
	)
	(arc
		(start 389.614664 -227.954332)
		(mid 389.799696 -227.908418)
		(end 389.983472 -227.959158)
		(width 0.09525)
		(layer "In11.Cu")
		(net "M_L_CPU0_SA_DQS_DP<5>")
	)
	(arc
		(start 391.99439 -227.127054)
		(mid 392.17284 -226.925584)
		(end 392.237214 -226.664266)
		(width 0.09525)
		(layer "In11.Cu")
		(net "M_L_CPU0_SA_DQS_DP<5>")
	)
	(arc
		(start 392.937238 -225.505518)
		(mid 393.113854 -225.304304)
		(end 393.177522 -225.044254)
		(width 0.09525)
		(layer "In11.Cu")
		(net "M_L_CPU0_SA_DQS_DP<5>")
	)
	(arc
		(start 388.103364 -227.959158)
		(mid 388.384796 -228.034913)
		(end 388.666228 -227.959158)
		(width 0.09525)
		(layer "In11.Cu")
		(net "M_L_CPU0_SA_DQS_DP<5>")
	)
	(segment
		(start 386.50799 -246.370094)
		(end 386.974842 -246.104156)
		(width 0.12954)
		(layer "F.Cu")
		(net "M_L_CPU0_SA_DQS_DP<4>")
	)
	(segment
		(start 420.818056 -238.587534)
		(end 421.541956 -238.587534)
		(width 0.16002)
		(layer "In11.Cu")
		(net "M_L_CPU0_SA_DQS_DP<4>")
	)
	(segment
		(start 393.084812 -246.353076)
		(end 393.789662 -246.353076)
		(width 0.09525)
		(layer "In11.Cu")
		(net "M_L_CPU0_SA_DQS_DP<4>")
	)
	(segment
		(start 389.606282 -246.429276)
		(end 389.614664 -246.434102)
		(width 0.09525)
		(layer "In11.Cu")
		(net "M_L_CPU0_SA_DQS_DP<4>")
	)
	(segment
		(start 418.346382 -238.259874)
		(end 420.490396 -238.259874)
		(width 0.16002)
		(layer "In11.Cu")
		(net "M_L_CPU0_SA_DQS_DP<4>")
	)
	(segment
		(start 422.776396 -237.764574)
		(end 423.13098 -237.40999)
		(width 0.16002)
		(layer "In11.Cu")
		(net "M_L_CPU0_SA_DQS_DP<4>")
	)
	(segment
		(start 443.450218 -238.587534)
		(end 444.174118 -238.587534)
		(width 0.16002)
		(layer "In11.Cu")
		(net "M_L_CPU0_SA_DQS_DP<4>")
	)
	(segment
		(start 435.906164 -238.587534)
		(end 436.630064 -238.587534)
		(width 0.16002)
		(layer "In11.Cu")
		(net "M_L_CPU0_SA_DQS_DP<4>")
	)
	(segment
		(start 451.895464 -238.408972)
		(end 453.914256 -238.408972)
		(width 0.16002)
		(layer "In11.Cu")
		(net "M_L_CPU0_SA_DQS_DP<4>")
	)
	(segment
		(start 451.287134 -238.602774)
		(end 451.701662 -238.602774)
		(width 0.16002)
		(layer "In11.Cu")
		(net "M_L_CPU0_SA_DQS_DP<4>")
	)
	(segment
		(start 450.66839 -237.98403)
		(end 451.287134 -238.602774)
		(width 0.16002)
		(layer "In11.Cu")
		(net "M_L_CPU0_SA_DQS_DP<4>")
	)
	(segment
		(start 435.578504 -238.259874)
		(end 435.906164 -238.587534)
		(width 0.16002)
		(layer "In11.Cu")
		(net "M_L_CPU0_SA_DQS_DP<4>")
	)
	(segment
		(start 422.364916 -237.764574)
		(end 422.776396 -237.764574)
		(width 0.16002)
		(layer "In11.Cu")
		(net "M_L_CPU0_SA_DQS_DP<4>")
	)
	(segment
		(start 395.891004 -246.67718)
		(end 396.562072 -246.006112)
		(width 0.16002)
		(layer "In11.Cu")
		(net "M_L_CPU0_SA_DQS_DP<4>")
	)
	(segment
		(start 430.32045 -237.764574)
		(end 430.675034 -237.40999)
		(width 0.16002)
		(layer "In11.Cu")
		(net "M_L_CPU0_SA_DQS_DP<4>")
	)
	(segment
		(start 389.035036 -246.434102)
		(end 389.043418 -246.429276)
		(width 0.09525)
		(layer "In11.Cu")
		(net "M_L_CPU0_SA_DQS_DP<4>")
	)
	(segment
		(start 448.246754 -237.98403)
		(end 450.66839 -237.98403)
		(width 0.16002)
		(layer "In11.Cu")
		(net "M_L_CPU0_SA_DQS_DP<4>")
	)
	(segment
		(start 437.453024 -237.764574)
		(end 437.864504 -237.764574)
		(width 0.16002)
		(layer "In11.Cu")
		(net "M_L_CPU0_SA_DQS_DP<4>")
	)
	(segment
		(start 388.094982 -246.434102)
		(end 388.103364 -246.429276)
		(width 0.09525)
		(layer "In11.Cu")
		(net "M_L_CPU0_SA_DQS_DP<4>")
	)
	(segment
		(start 415.816034 -237.764574)
		(end 417.851082 -237.764574)
		(width 0.16002)
		(layer "In11.Cu")
		(net "M_L_CPU0_SA_DQS_DP<4>")
	)
	(segment
		(start 391.851134 -246.436134)
		(end 391.863072 -246.429276)
		(width 0.09525)
		(layer "In11.Cu")
		(net "M_L_CPU0_SA_DQS_DP<4>")
	)
	(segment
		(start 440.978544 -238.259874)
		(end 443.122558 -238.259874)
		(width 0.16002)
		(layer "In11.Cu")
		(net "M_L_CPU0_SA_DQS_DP<4>")
	)
	(segment
		(start 392.425174 -246.429276)
		(end 392.437112 -246.436134)
		(width 0.09525)
		(layer "In11.Cu")
		(net "M_L_CPU0_SA_DQS_DP<4>")
	)
	(segment
		(start 430.675034 -237.40999)
		(end 432.584606 -237.40999)
		(width 0.16002)
		(layer "In11.Cu")
		(net "M_L_CPU0_SA_DQS_DP<4>")
	)
	(segment
		(start 393.789662 -246.353076)
		(end 394.172948 -246.736362)
		(width 0.09525)
		(layer "In11.Cu")
		(net "M_L_CPU0_SA_DQS_DP<4>")
	)
	(segment
		(start 395.66469 -246.67718)
		(end 395.891004 -246.67718)
		(width 0.16002)
		(layer "In11.Cu")
		(net "M_L_CPU0_SA_DQS_DP<4>")
	)
	(segment
		(start 444.174118 -238.587534)
		(end 444.997078 -237.764574)
		(width 0.16002)
		(layer "In11.Cu")
		(net "M_L_CPU0_SA_DQS_DP<4>")
	)
	(segment
		(start 417.851082 -237.764574)
		(end 418.346382 -238.259874)
		(width 0.16002)
		(layer "In11.Cu")
		(net "M_L_CPU0_SA_DQS_DP<4>")
	)
	(segment
		(start 387.128766 -246.369586)
		(end 387.229604 -246.396256)
		(width 0.09525)
		(layer "In11.Cu")
		(net "M_L_CPU0_SA_DQS_DP<4>")
	)
	(segment
		(start 425.890436 -238.259874)
		(end 428.03445 -238.259874)
		(width 0.16002)
		(layer "In11.Cu")
		(net "M_L_CPU0_SA_DQS_DP<4>")
	)
	(segment
		(start 428.36211 -238.587534)
		(end 429.08601 -238.587534)
		(width 0.16002)
		(layer "In11.Cu")
		(net "M_L_CPU0_SA_DQS_DP<4>")
	)
	(segment
		(start 391.863072 -246.429276)
		(end 391.881106 -246.418862)
		(width 0.09525)
		(layer "In11.Cu")
		(net "M_L_CPU0_SA_DQS_DP<4>")
	)
	(segment
		(start 405.918162 -246.006112)
		(end 412.044642 -239.879632)
		(width 0.16002)
		(layer "In11.Cu")
		(net "M_L_CPU0_SA_DQS_DP<4>")
	)
	(segment
		(start 433.43449 -238.259874)
		(end 435.578504 -238.259874)
		(width 0.16002)
		(layer "In11.Cu")
		(net "M_L_CPU0_SA_DQS_DP<4>")
	)
	(segment
		(start 445.408558 -237.764574)
		(end 445.763142 -237.40999)
		(width 0.16002)
		(layer "In11.Cu")
		(net "M_L_CPU0_SA_DQS_DP<4>")
	)
	(segment
		(start 421.541956 -238.587534)
		(end 422.364916 -237.764574)
		(width 0.16002)
		(layer "In11.Cu")
		(net "M_L_CPU0_SA_DQS_DP<4>")
	)
	(segment
		(start 423.13098 -237.40999)
		(end 425.040552 -237.40999)
		(width 0.16002)
		(layer "In11.Cu")
		(net "M_L_CPU0_SA_DQS_DP<4>")
	)
	(segment
		(start 413.700976 -239.879632)
		(end 415.816034 -237.764574)
		(width 0.16002)
		(layer "In11.Cu")
		(net "M_L_CPU0_SA_DQS_DP<4>")
	)
	(segment
		(start 412.044642 -239.879632)
		(end 413.700976 -239.879632)
		(width 0.16002)
		(layer "In11.Cu")
		(net "M_L_CPU0_SA_DQS_DP<4>")
	)
	(segment
		(start 429.08601 -238.587534)
		(end 429.90897 -237.764574)
		(width 0.16002)
		(layer "In11.Cu")
		(net "M_L_CPU0_SA_DQS_DP<4>")
	)
	(segment
		(start 395.581886 -246.736362)
		(end 395.641068 -246.67718)
		(width 0.09525)
		(layer "In11.Cu")
		(net "M_L_CPU0_SA_DQS_DP<4>")
	)
	(segment
		(start 394.172948 -246.736362)
		(end 395.581886 -246.736362)
		(width 0.09525)
		(layer "In11.Cu")
		(net "M_L_CPU0_SA_DQS_DP<4>")
	)
	(segment
		(start 453.914256 -238.408972)
		(end 454.188068 -238.13516)
		(width 0.16002)
		(layer "In11.Cu")
		(net "M_L_CPU0_SA_DQS_DP<4>")
	)
	(segment
		(start 438.219088 -237.40999)
		(end 440.12866 -237.40999)
		(width 0.16002)
		(layer "In11.Cu")
		(net "M_L_CPU0_SA_DQS_DP<4>")
	)
	(segment
		(start 436.630064 -238.587534)
		(end 437.453024 -237.764574)
		(width 0.16002)
		(layer "In11.Cu")
		(net "M_L_CPU0_SA_DQS_DP<4>")
	)
	(segment
		(start 396.562072 -246.006112)
		(end 405.918162 -246.006112)
		(width 0.16002)
		(layer "In11.Cu")
		(net "M_L_CPU0_SA_DQS_DP<4>")
	)
	(segment
		(start 445.763142 -237.40999)
		(end 447.672714 -237.40999)
		(width 0.16002)
		(layer "In11.Cu")
		(net "M_L_CPU0_SA_DQS_DP<4>")
	)
	(segment
		(start 428.03445 -238.259874)
		(end 428.36211 -238.587534)
		(width 0.16002)
		(layer "In11.Cu")
		(net "M_L_CPU0_SA_DQS_DP<4>")
	)
	(segment
		(start 451.701662 -238.602774)
		(end 451.895464 -238.408972)
		(width 0.16002)
		(layer "In11.Cu")
		(net "M_L_CPU0_SA_DQS_DP<4>")
	)
	(segment
		(start 437.864504 -237.764574)
		(end 438.219088 -237.40999)
		(width 0.16002)
		(layer "In11.Cu")
		(net "M_L_CPU0_SA_DQS_DP<4>")
	)
	(segment
		(start 420.490396 -238.259874)
		(end 420.818056 -238.587534)
		(width 0.16002)
		(layer "In11.Cu")
		(net "M_L_CPU0_SA_DQS_DP<4>")
	)
	(segment
		(start 444.997078 -237.764574)
		(end 445.408558 -237.764574)
		(width 0.16002)
		(layer "In11.Cu")
		(net "M_L_CPU0_SA_DQS_DP<4>")
	)
	(segment
		(start 425.040552 -237.40999)
		(end 425.890436 -238.259874)
		(width 0.16002)
		(layer "In11.Cu")
		(net "M_L_CPU0_SA_DQS_DP<4>")
	)
	(segment
		(start 395.641068 -246.67718)
		(end 395.66469 -246.67718)
		(width 0.09525)
		(layer "In11.Cu")
		(net "M_L_CPU0_SA_DQS_DP<4>")
	)
	(segment
		(start 429.90897 -237.764574)
		(end 430.32045 -237.764574)
		(width 0.16002)
		(layer "In11.Cu")
		(net "M_L_CPU0_SA_DQS_DP<4>")
	)
	(segment
		(start 432.584606 -237.40999)
		(end 433.43449 -238.259874)
		(width 0.16002)
		(layer "In11.Cu")
		(net "M_L_CPU0_SA_DQS_DP<4>")
	)
	(segment
		(start 440.12866 -237.40999)
		(end 440.978544 -238.259874)
		(width 0.16002)
		(layer "In11.Cu")
		(net "M_L_CPU0_SA_DQS_DP<4>")
	)
	(segment
		(start 443.122558 -238.259874)
		(end 443.450218 -238.587534)
		(width 0.16002)
		(layer "In11.Cu")
		(net "M_L_CPU0_SA_DQS_DP<4>")
	)
	(segment
		(start 447.672714 -237.40999)
		(end 448.246754 -237.98403)
		(width 0.16002)
		(layer "In11.Cu")
		(net "M_L_CPU0_SA_DQS_DP<4>")
	)
	(segment
		(start 386.974842 -246.104156)
		(end 387.128766 -246.369586)
		(width 0.09525)
		(layer "In11.Cu")
		(net "M_L_CPU0_SA_DQS_DP<4>")
	)
	(arc
		(start 389.043418 -246.429276)
		(mid 389.32485 -246.353521)
		(end 389.606282 -246.429276)
		(width 0.09525)
		(layer "In11.Cu")
		(net "M_L_CPU0_SA_DQS_DP<4>")
	)
	(arc
		(start 388.103364 -246.429276)
		(mid 388.384796 -246.353521)
		(end 388.666228 -246.429276)
		(width 0.09525)
		(layer "In11.Cu")
		(net "M_L_CPU0_SA_DQS_DP<4>")
	)
	(arc
		(start 390.923272 -246.429276)
		(mid 391.204704 -246.353521)
		(end 391.486136 -246.429276)
		(width 0.09525)
		(layer "In11.Cu")
		(net "M_L_CPU0_SA_DQS_DP<4>")
	)
	(arc
		(start 391.881106 -246.418862)
		(mid 392.154486 -246.353641)
		(end 392.425174 -246.429276)
		(width 0.09525)
		(layer "In11.Cu")
		(net "M_L_CPU0_SA_DQS_DP<4>")
	)
	(arc
		(start 389.614664 -246.434102)
		(mid 389.799696 -246.480016)
		(end 389.983472 -246.429276)
		(width 0.09525)
		(layer "In11.Cu")
		(net "M_L_CPU0_SA_DQS_DP<4>")
	)
	(arc
		(start 387.229604 -246.396256)
		(mid 387.481745 -246.354686)
		(end 387.726174 -246.429276)
		(width 0.09525)
		(layer "In11.Cu")
		(net "M_L_CPU0_SA_DQS_DP<4>")
	)
	(arc
		(start 391.486136 -246.429276)
		(mid 391.667752 -246.480013)
		(end 391.851134 -246.436134)
		(width 0.09525)
		(layer "In11.Cu")
		(net "M_L_CPU0_SA_DQS_DP<4>")
	)
	(arc
		(start 392.802618 -246.429276)
		(mid 392.93867 -246.372507)
		(end 393.084812 -246.353076)
		(width 0.09525)
		(layer "In11.Cu")
		(net "M_L_CPU0_SA_DQS_DP<4>")
	)
	(arc
		(start 392.437112 -246.436134)
		(mid 392.620747 -246.480084)
		(end 392.802618 -246.429276)
		(width 0.09525)
		(layer "In11.Cu")
		(net "M_L_CPU0_SA_DQS_DP<4>")
	)
	(arc
		(start 390.546336 -246.429276)
		(mid 390.734804 -246.479953)
		(end 390.923272 -246.429276)
		(width 0.09525)
		(layer "In11.Cu")
		(net "M_L_CPU0_SA_DQS_DP<4>")
	)
	(arc
		(start 389.983472 -246.429276)
		(mid 390.264904 -246.353521)
		(end 390.546336 -246.429276)
		(width 0.09525)
		(layer "In11.Cu")
		(net "M_L_CPU0_SA_DQS_DP<4>")
	)
	(arc
		(start 388.666228 -246.429276)
		(mid 388.850003 -246.480048)
		(end 389.035036 -246.434102)
		(width 0.09525)
		(layer "In11.Cu")
		(net "M_L_CPU0_SA_DQS_DP<4>")
	)
	(arc
		(start 387.726174 -246.429276)
		(mid 387.909949 -246.480048)
		(end 388.094982 -246.434102)
		(width 0.09525)
		(layer "In11.Cu")
		(net "M_L_CPU0_SA_DQS_DP<4>")
	)
	(segment
		(start 386.50799 -241.510058)
		(end 386.974842 -241.24412)
		(width 0.12954)
		(layer "F.Cu")
		(net "M_L_CPU0_SA_DQS_DP<3>")
	)
	(segment
		(start 437.864504 -228.41458)
		(end 438.219088 -228.059996)
		(width 0.16002)
		(layer "In11.Cu")
		(net "M_L_CPU0_SA_DQS_DP<3>")
	)
	(segment
		(start 425.040552 -228.059996)
		(end 425.890436 -228.90988)
		(width 0.16002)
		(layer "In11.Cu")
		(net "M_L_CPU0_SA_DQS_DP<3>")
	)
	(segment
		(start 432.584606 -228.059996)
		(end 433.43449 -228.90988)
		(width 0.16002)
		(layer "In11.Cu")
		(net "M_L_CPU0_SA_DQS_DP<3>")
	)
	(segment
		(start 401.217892 -240.411)
		(end 412.391352 -229.23754)
		(width 0.16002)
		(layer "In11.Cu")
		(net "M_L_CPU0_SA_DQS_DP<3>")
	)
	(segment
		(start 393.819634 -241.510312)
		(end 394.566394 -240.763552)
		(width 0.09525)
		(layer "In11.Cu")
		(net "M_L_CPU0_SA_DQS_DP<3>")
	)
	(segment
		(start 391.863072 -241.56924)
		(end 391.881106 -241.558826)
		(width 0.09525)
		(layer "In11.Cu")
		(net "M_L_CPU0_SA_DQS_DP<3>")
	)
	(segment
		(start 394.566394 -240.763552)
		(end 395.202918 -240.763552)
		(width 0.09525)
		(layer "In11.Cu")
		(net "M_L_CPU0_SA_DQS_DP<3>")
	)
	(segment
		(start 391.851134 -241.576098)
		(end 391.863072 -241.56924)
		(width 0.09525)
		(layer "In11.Cu")
		(net "M_L_CPU0_SA_DQS_DP<3>")
	)
	(segment
		(start 428.03445 -228.90988)
		(end 428.36211 -229.23754)
		(width 0.16002)
		(layer "In11.Cu")
		(net "M_L_CPU0_SA_DQS_DP<3>")
	)
	(segment
		(start 418.346382 -228.90988)
		(end 420.490396 -228.90988)
		(width 0.16002)
		(layer "In11.Cu")
		(net "M_L_CPU0_SA_DQS_DP<3>")
	)
	(segment
		(start 420.818056 -229.23754)
		(end 421.541956 -229.23754)
		(width 0.16002)
		(layer "In11.Cu")
		(net "M_L_CPU0_SA_DQS_DP<3>")
	)
	(segment
		(start 444.174118 -229.23754)
		(end 444.997078 -228.41458)
		(width 0.16002)
		(layer "In11.Cu")
		(net "M_L_CPU0_SA_DQS_DP<3>")
	)
	(segment
		(start 387.128766 -241.50955)
		(end 387.229604 -241.53622)
		(width 0.09525)
		(layer "In11.Cu")
		(net "M_L_CPU0_SA_DQS_DP<3>")
	)
	(segment
		(start 392.425174 -241.56924)
		(end 392.437112 -241.576098)
		(width 0.09525)
		(layer "In11.Cu")
		(net "M_L_CPU0_SA_DQS_DP<3>")
	)
	(segment
		(start 422.364916 -228.41458)
		(end 422.776396 -228.41458)
		(width 0.16002)
		(layer "In11.Cu")
		(net "M_L_CPU0_SA_DQS_DP<3>")
	)
	(segment
		(start 395.859254 -240.411)
		(end 401.217892 -240.411)
		(width 0.16002)
		(layer "In11.Cu")
		(net "M_L_CPU0_SA_DQS_DP<3>")
	)
	(segment
		(start 433.43449 -228.90988)
		(end 435.578504 -228.90988)
		(width 0.16002)
		(layer "In11.Cu")
		(net "M_L_CPU0_SA_DQS_DP<3>")
	)
	(segment
		(start 448.246754 -228.634036)
		(end 450.66839 -228.634036)
		(width 0.16002)
		(layer "In11.Cu")
		(net "M_L_CPU0_SA_DQS_DP<3>")
	)
	(segment
		(start 440.12866 -228.059996)
		(end 440.978544 -228.90988)
		(width 0.16002)
		(layer "In11.Cu")
		(net "M_L_CPU0_SA_DQS_DP<3>")
	)
	(segment
		(start 417.496498 -228.059996)
		(end 418.346382 -228.90988)
		(width 0.16002)
		(layer "In11.Cu")
		(net "M_L_CPU0_SA_DQS_DP<3>")
	)
	(segment
		(start 440.978544 -228.90988)
		(end 443.122558 -228.90988)
		(width 0.16002)
		(layer "In11.Cu")
		(net "M_L_CPU0_SA_DQS_DP<3>")
	)
	(segment
		(start 414.820862 -228.41458)
		(end 415.232342 -228.41458)
		(width 0.16002)
		(layer "In11.Cu")
		(net "M_L_CPU0_SA_DQS_DP<3>")
	)
	(segment
		(start 421.541956 -229.23754)
		(end 422.364916 -228.41458)
		(width 0.16002)
		(layer "In11.Cu")
		(net "M_L_CPU0_SA_DQS_DP<3>")
	)
	(segment
		(start 451.895464 -229.058978)
		(end 453.914256 -229.058978)
		(width 0.16002)
		(layer "In11.Cu")
		(net "M_L_CPU0_SA_DQS_DP<3>")
	)
	(segment
		(start 393.340082 -241.554508)
		(end 393.365482 -241.56924)
		(width 0.09525)
		(layer "In11.Cu")
		(net "M_L_CPU0_SA_DQS_DP<3>")
	)
	(segment
		(start 435.578504 -228.90988)
		(end 435.906164 -229.23754)
		(width 0.16002)
		(layer "In11.Cu")
		(net "M_L_CPU0_SA_DQS_DP<3>")
	)
	(segment
		(start 430.32045 -228.41458)
		(end 430.675034 -228.059996)
		(width 0.16002)
		(layer "In11.Cu")
		(net "M_L_CPU0_SA_DQS_DP<3>")
	)
	(segment
		(start 443.450218 -229.23754)
		(end 444.174118 -229.23754)
		(width 0.16002)
		(layer "In11.Cu")
		(net "M_L_CPU0_SA_DQS_DP<3>")
	)
	(segment
		(start 445.763142 -228.059996)
		(end 447.672714 -228.059996)
		(width 0.16002)
		(layer "In11.Cu")
		(net "M_L_CPU0_SA_DQS_DP<3>")
	)
	(segment
		(start 412.391352 -229.23754)
		(end 413.997902 -229.23754)
		(width 0.16002)
		(layer "In11.Cu")
		(net "M_L_CPU0_SA_DQS_DP<3>")
	)
	(segment
		(start 389.606282 -241.56924)
		(end 389.614664 -241.574066)
		(width 0.09525)
		(layer "In11.Cu")
		(net "M_L_CPU0_SA_DQS_DP<3>")
	)
	(segment
		(start 437.453024 -228.41458)
		(end 437.864504 -228.41458)
		(width 0.16002)
		(layer "In11.Cu")
		(net "M_L_CPU0_SA_DQS_DP<3>")
	)
	(segment
		(start 395.835632 -240.411)
		(end 395.859254 -240.411)
		(width 0.09525)
		(layer "In11.Cu")
		(net "M_L_CPU0_SA_DQS_DP<3>")
	)
	(segment
		(start 428.36211 -229.23754)
		(end 429.08601 -229.23754)
		(width 0.16002)
		(layer "In11.Cu")
		(net "M_L_CPU0_SA_DQS_DP<3>")
	)
	(segment
		(start 451.701662 -229.25278)
		(end 451.895464 -229.058978)
		(width 0.16002)
		(layer "In11.Cu")
		(net "M_L_CPU0_SA_DQS_DP<3>")
	)
	(segment
		(start 420.490396 -228.90988)
		(end 420.818056 -229.23754)
		(width 0.16002)
		(layer "In11.Cu")
		(net "M_L_CPU0_SA_DQS_DP<3>")
	)
	(segment
		(start 395.496288 -240.470182)
		(end 395.77645 -240.470182)
		(width 0.09525)
		(layer "In11.Cu")
		(net "M_L_CPU0_SA_DQS_DP<3>")
	)
	(segment
		(start 438.219088 -228.059996)
		(end 440.12866 -228.059996)
		(width 0.16002)
		(layer "In11.Cu")
		(net "M_L_CPU0_SA_DQS_DP<3>")
	)
	(segment
		(start 430.675034 -228.059996)
		(end 432.584606 -228.059996)
		(width 0.16002)
		(layer "In11.Cu")
		(net "M_L_CPU0_SA_DQS_DP<3>")
	)
	(segment
		(start 388.094982 -241.574066)
		(end 388.103364 -241.56924)
		(width 0.09525)
		(layer "In11.Cu")
		(net "M_L_CPU0_SA_DQS_DP<3>")
	)
	(segment
		(start 423.13098 -228.059996)
		(end 425.040552 -228.059996)
		(width 0.16002)
		(layer "In11.Cu")
		(net "M_L_CPU0_SA_DQS_DP<3>")
	)
	(segment
		(start 447.672714 -228.059996)
		(end 448.246754 -228.634036)
		(width 0.16002)
		(layer "In11.Cu")
		(net "M_L_CPU0_SA_DQS_DP<3>")
	)
	(segment
		(start 395.77645 -240.470182)
		(end 395.835632 -240.411)
		(width 0.09525)
		(layer "In11.Cu")
		(net "M_L_CPU0_SA_DQS_DP<3>")
	)
	(segment
		(start 443.122558 -228.90988)
		(end 443.450218 -229.23754)
		(width 0.16002)
		(layer "In11.Cu")
		(net "M_L_CPU0_SA_DQS_DP<3>")
	)
	(segment
		(start 436.630064 -229.23754)
		(end 437.453024 -228.41458)
		(width 0.16002)
		(layer "In11.Cu")
		(net "M_L_CPU0_SA_DQS_DP<3>")
	)
	(segment
		(start 389.035036 -241.574066)
		(end 389.043418 -241.56924)
		(width 0.09525)
		(layer "In11.Cu")
		(net "M_L_CPU0_SA_DQS_DP<3>")
	)
	(segment
		(start 429.08601 -229.23754)
		(end 429.90897 -228.41458)
		(width 0.16002)
		(layer "In11.Cu")
		(net "M_L_CPU0_SA_DQS_DP<3>")
	)
	(segment
		(start 395.202918 -240.763552)
		(end 395.496288 -240.470182)
		(width 0.09525)
		(layer "In11.Cu")
		(net "M_L_CPU0_SA_DQS_DP<3>")
	)
	(segment
		(start 444.997078 -228.41458)
		(end 445.408558 -228.41458)
		(width 0.16002)
		(layer "In11.Cu")
		(net "M_L_CPU0_SA_DQS_DP<3>")
	)
	(segment
		(start 453.914256 -229.058978)
		(end 454.188068 -228.785166)
		(width 0.16002)
		(layer "In11.Cu")
		(net "M_L_CPU0_SA_DQS_DP<3>")
	)
	(segment
		(start 386.974842 -241.24412)
		(end 387.128766 -241.50955)
		(width 0.09525)
		(layer "In11.Cu")
		(net "M_L_CPU0_SA_DQS_DP<3>")
	)
	(segment
		(start 435.906164 -229.23754)
		(end 436.630064 -229.23754)
		(width 0.16002)
		(layer "In11.Cu")
		(net "M_L_CPU0_SA_DQS_DP<3>")
	)
	(segment
		(start 450.66839 -228.634036)
		(end 451.287134 -229.25278)
		(width 0.16002)
		(layer "In11.Cu")
		(net "M_L_CPU0_SA_DQS_DP<3>")
	)
	(segment
		(start 425.890436 -228.90988)
		(end 428.03445 -228.90988)
		(width 0.16002)
		(layer "In11.Cu")
		(net "M_L_CPU0_SA_DQS_DP<3>")
	)
	(segment
		(start 429.90897 -228.41458)
		(end 430.32045 -228.41458)
		(width 0.16002)
		(layer "In11.Cu")
		(net "M_L_CPU0_SA_DQS_DP<3>")
	)
	(segment
		(start 415.586926 -228.059996)
		(end 417.496498 -228.059996)
		(width 0.16002)
		(layer "In11.Cu")
		(net "M_L_CPU0_SA_DQS_DP<3>")
	)
	(segment
		(start 445.408558 -228.41458)
		(end 445.763142 -228.059996)
		(width 0.16002)
		(layer "In11.Cu")
		(net "M_L_CPU0_SA_DQS_DP<3>")
	)
	(segment
		(start 393.365482 -241.56924)
		(end 393.37742 -241.576098)
		(width 0.09525)
		(layer "In11.Cu")
		(net "M_L_CPU0_SA_DQS_DP<3>")
	)
	(segment
		(start 422.776396 -228.41458)
		(end 423.13098 -228.059996)
		(width 0.16002)
		(layer "In11.Cu")
		(net "M_L_CPU0_SA_DQS_DP<3>")
	)
	(segment
		(start 413.997902 -229.23754)
		(end 414.820862 -228.41458)
		(width 0.16002)
		(layer "In11.Cu")
		(net "M_L_CPU0_SA_DQS_DP<3>")
	)
	(segment
		(start 415.232342 -228.41458)
		(end 415.586926 -228.059996)
		(width 0.16002)
		(layer "In11.Cu")
		(net "M_L_CPU0_SA_DQS_DP<3>")
	)
	(segment
		(start 451.287134 -229.25278)
		(end 451.701662 -229.25278)
		(width 0.16002)
		(layer "In11.Cu")
		(net "M_L_CPU0_SA_DQS_DP<3>")
	)
	(arc
		(start 389.614664 -241.574066)
		(mid 389.799696 -241.61998)
		(end 389.983472 -241.56924)
		(width 0.09525)
		(layer "In11.Cu")
		(net "M_L_CPU0_SA_DQS_DP<3>")
	)
	(arc
		(start 389.043418 -241.56924)
		(mid 389.32485 -241.493485)
		(end 389.606282 -241.56924)
		(width 0.09525)
		(layer "In11.Cu")
		(net "M_L_CPU0_SA_DQS_DP<3>")
	)
	(arc
		(start 393.74191 -241.56924)
		(mid 393.782691 -241.542307)
		(end 393.819634 -241.510312)
		(width 0.09525)
		(layer "In11.Cu")
		(net "M_L_CPU0_SA_DQS_DP<3>")
	)
	(arc
		(start 392.802618 -241.56924)
		(mid 393.069467 -241.493312)
		(end 393.340082 -241.554508)
		(width 0.09525)
		(layer "In11.Cu")
		(net "M_L_CPU0_SA_DQS_DP<3>")
	)
	(arc
		(start 387.726174 -241.56924)
		(mid 387.909949 -241.620012)
		(end 388.094982 -241.574066)
		(width 0.09525)
		(layer "In11.Cu")
		(net "M_L_CPU0_SA_DQS_DP<3>")
	)
	(arc
		(start 389.983472 -241.56924)
		(mid 390.264904 -241.493485)
		(end 390.546336 -241.56924)
		(width 0.09525)
		(layer "In11.Cu")
		(net "M_L_CPU0_SA_DQS_DP<3>")
	)
	(arc
		(start 392.437112 -241.576098)
		(mid 392.620747 -241.620048)
		(end 392.802618 -241.56924)
		(width 0.09525)
		(layer "In11.Cu")
		(net "M_L_CPU0_SA_DQS_DP<3>")
	)
	(arc
		(start 391.486136 -241.56924)
		(mid 391.667752 -241.619977)
		(end 391.851134 -241.576098)
		(width 0.09525)
		(layer "In11.Cu")
		(net "M_L_CPU0_SA_DQS_DP<3>")
	)
	(arc
		(start 387.229604 -241.53622)
		(mid 387.481745 -241.49465)
		(end 387.726174 -241.56924)
		(width 0.09525)
		(layer "In11.Cu")
		(net "M_L_CPU0_SA_DQS_DP<3>")
	)
	(arc
		(start 388.666228 -241.56924)
		(mid 388.850003 -241.620012)
		(end 389.035036 -241.574066)
		(width 0.09525)
		(layer "In11.Cu")
		(net "M_L_CPU0_SA_DQS_DP<3>")
	)
	(arc
		(start 393.37742 -241.576098)
		(mid 393.560547 -241.61981)
		(end 393.74191 -241.56924)
		(width 0.09525)
		(layer "In11.Cu")
		(net "M_L_CPU0_SA_DQS_DP<3>")
	)
	(arc
		(start 390.546336 -241.56924)
		(mid 390.734804 -241.619917)
		(end 390.923272 -241.56924)
		(width 0.09525)
		(layer "In11.Cu")
		(net "M_L_CPU0_SA_DQS_DP<3>")
	)
	(arc
		(start 391.881106 -241.558826)
		(mid 392.154486 -241.493605)
		(end 392.425174 -241.56924)
		(width 0.09525)
		(layer "In11.Cu")
		(net "M_L_CPU0_SA_DQS_DP<3>")
	)
	(arc
		(start 388.103364 -241.56924)
		(mid 388.384796 -241.493485)
		(end 388.666228 -241.56924)
		(width 0.09525)
		(layer "In11.Cu")
		(net "M_L_CPU0_SA_DQS_DP<3>")
	)
	(arc
		(start 390.923272 -241.56924)
		(mid 391.204704 -241.493485)
		(end 391.486136 -241.56924)
		(width 0.09525)
		(layer "In11.Cu")
		(net "M_L_CPU0_SA_DQS_DP<3>")
	)
	(segment
		(start 386.50799 -236.650022)
		(end 386.974842 -236.384084)
		(width 0.12954)
		(layer "F.Cu")
		(net "M_L_CPU0_SA_DQS_DP<2>")
	)
	(segment
		(start 415.232342 -219.064586)
		(end 415.586926 -218.710002)
		(width 0.16002)
		(layer "In11.Cu")
		(net "M_L_CPU0_SA_DQS_DP<2>")
	)
	(segment
		(start 397.253968 -234.755182)
		(end 412.121604 -219.887546)
		(width 0.16002)
		(layer "In11.Cu")
		(net "M_L_CPU0_SA_DQS_DP<2>")
	)
	(segment
		(start 395.859254 -234.755182)
		(end 397.253968 -234.755182)
		(width 0.16002)
		(layer "In11.Cu")
		(net "M_L_CPU0_SA_DQS_DP<2>")
	)
	(segment
		(start 451.287134 -219.902786)
		(end 451.701662 -219.902786)
		(width 0.16002)
		(layer "In11.Cu")
		(net "M_L_CPU0_SA_DQS_DP<2>")
	)
	(segment
		(start 413.997902 -219.887546)
		(end 414.820862 -219.064586)
		(width 0.16002)
		(layer "In11.Cu")
		(net "M_L_CPU0_SA_DQS_DP<2>")
	)
	(segment
		(start 428.03445 -219.559886)
		(end 428.36211 -219.887546)
		(width 0.16002)
		(layer "In11.Cu")
		(net "M_L_CPU0_SA_DQS_DP<2>")
	)
	(segment
		(start 388.094982 -236.71403)
		(end 388.103364 -236.709204)
		(width 0.09525)
		(layer "In11.Cu")
		(net "M_L_CPU0_SA_DQS_DP<2>")
	)
	(segment
		(start 440.978544 -219.559886)
		(end 443.122558 -219.559886)
		(width 0.16002)
		(layer "In11.Cu")
		(net "M_L_CPU0_SA_DQS_DP<2>")
	)
	(segment
		(start 451.701662 -219.902786)
		(end 451.895464 -219.708984)
		(width 0.16002)
		(layer "In11.Cu")
		(net "M_L_CPU0_SA_DQS_DP<2>")
	)
	(segment
		(start 421.541956 -219.887546)
		(end 422.364916 -219.064586)
		(width 0.16002)
		(layer "In11.Cu")
		(net "M_L_CPU0_SA_DQS_DP<2>")
	)
	(segment
		(start 391.851134 -236.716062)
		(end 391.863072 -236.709204)
		(width 0.09525)
		(layer "In11.Cu")
		(net "M_L_CPU0_SA_DQS_DP<2>")
	)
	(segment
		(start 435.906164 -219.887546)
		(end 436.630064 -219.887546)
		(width 0.16002)
		(layer "In11.Cu")
		(net "M_L_CPU0_SA_DQS_DP<2>")
	)
	(segment
		(start 393.814046 -236.633004)
		(end 394.387578 -236.059472)
		(width 0.09525)
		(layer "In11.Cu")
		(net "M_L_CPU0_SA_DQS_DP<2>")
	)
	(segment
		(start 445.408558 -219.064586)
		(end 445.763142 -218.710002)
		(width 0.16002)
		(layer "In11.Cu")
		(net "M_L_CPU0_SA_DQS_DP<2>")
	)
	(segment
		(start 443.450218 -219.887546)
		(end 444.174118 -219.887546)
		(width 0.16002)
		(layer "In11.Cu")
		(net "M_L_CPU0_SA_DQS_DP<2>")
	)
	(segment
		(start 417.496498 -218.710002)
		(end 418.346382 -219.559886)
		(width 0.16002)
		(layer "In11.Cu")
		(net "M_L_CPU0_SA_DQS_DP<2>")
	)
	(segment
		(start 422.776396 -219.064586)
		(end 423.13098 -218.710002)
		(width 0.16002)
		(layer "In11.Cu")
		(net "M_L_CPU0_SA_DQS_DP<2>")
	)
	(segment
		(start 453.914256 -219.708984)
		(end 454.188068 -219.435172)
		(width 0.16002)
		(layer "In11.Cu")
		(net "M_L_CPU0_SA_DQS_DP<2>")
	)
	(segment
		(start 451.895464 -219.708984)
		(end 453.914256 -219.708984)
		(width 0.16002)
		(layer "In11.Cu")
		(net "M_L_CPU0_SA_DQS_DP<2>")
	)
	(segment
		(start 447.672714 -218.710002)
		(end 448.246754 -219.284042)
		(width 0.16002)
		(layer "In11.Cu")
		(net "M_L_CPU0_SA_DQS_DP<2>")
	)
	(segment
		(start 420.490396 -219.559886)
		(end 420.818056 -219.887546)
		(width 0.16002)
		(layer "In11.Cu")
		(net "M_L_CPU0_SA_DQS_DP<2>")
	)
	(segment
		(start 437.864504 -219.064586)
		(end 438.219088 -218.710002)
		(width 0.16002)
		(layer "In11.Cu")
		(net "M_L_CPU0_SA_DQS_DP<2>")
	)
	(segment
		(start 420.818056 -219.887546)
		(end 421.541956 -219.887546)
		(width 0.16002)
		(layer "In11.Cu")
		(net "M_L_CPU0_SA_DQS_DP<2>")
	)
	(segment
		(start 450.66839 -219.284042)
		(end 451.287134 -219.902786)
		(width 0.16002)
		(layer "In11.Cu")
		(net "M_L_CPU0_SA_DQS_DP<2>")
	)
	(segment
		(start 433.43449 -219.559886)
		(end 435.578504 -219.559886)
		(width 0.16002)
		(layer "In11.Cu")
		(net "M_L_CPU0_SA_DQS_DP<2>")
	)
	(segment
		(start 437.453024 -219.064586)
		(end 437.864504 -219.064586)
		(width 0.16002)
		(layer "In11.Cu")
		(net "M_L_CPU0_SA_DQS_DP<2>")
	)
	(segment
		(start 394.565378 -235.985812)
		(end 395.346936 -235.204254)
		(width 0.09525)
		(layer "In11.Cu")
		(net "M_L_CPU0_SA_DQS_DP<2>")
	)
	(segment
		(start 425.890436 -219.559886)
		(end 428.03445 -219.559886)
		(width 0.16002)
		(layer "In11.Cu")
		(net "M_L_CPU0_SA_DQS_DP<2>")
	)
	(segment
		(start 415.586926 -218.710002)
		(end 417.496498 -218.710002)
		(width 0.16002)
		(layer "In11.Cu")
		(net "M_L_CPU0_SA_DQS_DP<2>")
	)
	(segment
		(start 422.364916 -219.064586)
		(end 422.776396 -219.064586)
		(width 0.16002)
		(layer "In11.Cu")
		(net "M_L_CPU0_SA_DQS_DP<2>")
	)
	(segment
		(start 387.128766 -236.649514)
		(end 387.229604 -236.676184)
		(width 0.09525)
		(layer "In11.Cu")
		(net "M_L_CPU0_SA_DQS_DP<2>")
	)
	(segment
		(start 448.246754 -219.284042)
		(end 450.66839 -219.284042)
		(width 0.16002)
		(layer "In11.Cu")
		(net "M_L_CPU0_SA_DQS_DP<2>")
	)
	(segment
		(start 395.346936 -235.204254)
		(end 395.346936 -235.01731)
		(width 0.09525)
		(layer "In11.Cu")
		(net "M_L_CPU0_SA_DQS_DP<2>")
	)
	(segment
		(start 395.549882 -234.814364)
		(end 395.77645 -234.814364)
		(width 0.09525)
		(layer "In11.Cu")
		(net "M_L_CPU0_SA_DQS_DP<2>")
	)
	(segment
		(start 440.12866 -218.710002)
		(end 440.978544 -219.559886)
		(width 0.16002)
		(layer "In11.Cu")
		(net "M_L_CPU0_SA_DQS_DP<2>")
	)
	(segment
		(start 394.387578 -236.059472)
		(end 394.565378 -235.985812)
		(width 0.09525)
		(layer "In11.Cu")
		(net "M_L_CPU0_SA_DQS_DP<2>")
	)
	(segment
		(start 429.90897 -219.064586)
		(end 430.32045 -219.064586)
		(width 0.16002)
		(layer "In11.Cu")
		(net "M_L_CPU0_SA_DQS_DP<2>")
	)
	(segment
		(start 429.08601 -219.887546)
		(end 429.90897 -219.064586)
		(width 0.16002)
		(layer "In11.Cu")
		(net "M_L_CPU0_SA_DQS_DP<2>")
	)
	(segment
		(start 395.77645 -234.814364)
		(end 395.835632 -234.755182)
		(width 0.09525)
		(layer "In11.Cu")
		(net "M_L_CPU0_SA_DQS_DP<2>")
	)
	(segment
		(start 443.122558 -219.559886)
		(end 443.450218 -219.887546)
		(width 0.16002)
		(layer "In11.Cu")
		(net "M_L_CPU0_SA_DQS_DP<2>")
	)
	(segment
		(start 444.174118 -219.887546)
		(end 444.997078 -219.064586)
		(width 0.16002)
		(layer "In11.Cu")
		(net "M_L_CPU0_SA_DQS_DP<2>")
	)
	(segment
		(start 389.035036 -236.71403)
		(end 389.043418 -236.709204)
		(width 0.09525)
		(layer "In11.Cu")
		(net "M_L_CPU0_SA_DQS_DP<2>")
	)
	(segment
		(start 430.32045 -219.064586)
		(end 430.675034 -218.710002)
		(width 0.16002)
		(layer "In11.Cu")
		(net "M_L_CPU0_SA_DQS_DP<2>")
	)
	(segment
		(start 395.835632 -234.755182)
		(end 395.859254 -234.755182)
		(width 0.09525)
		(layer "In11.Cu")
		(net "M_L_CPU0_SA_DQS_DP<2>")
	)
	(segment
		(start 445.763142 -218.710002)
		(end 447.672714 -218.710002)
		(width 0.16002)
		(layer "In11.Cu")
		(net "M_L_CPU0_SA_DQS_DP<2>")
	)
	(segment
		(start 425.040552 -218.710002)
		(end 425.890436 -219.559886)
		(width 0.16002)
		(layer "In11.Cu")
		(net "M_L_CPU0_SA_DQS_DP<2>")
	)
	(segment
		(start 386.974842 -236.384084)
		(end 387.128766 -236.649514)
		(width 0.09525)
		(layer "In11.Cu")
		(net "M_L_CPU0_SA_DQS_DP<2>")
	)
	(segment
		(start 423.13098 -218.710002)
		(end 425.040552 -218.710002)
		(width 0.16002)
		(layer "In11.Cu")
		(net "M_L_CPU0_SA_DQS_DP<2>")
	)
	(segment
		(start 418.346382 -219.559886)
		(end 420.490396 -219.559886)
		(width 0.16002)
		(layer "In11.Cu")
		(net "M_L_CPU0_SA_DQS_DP<2>")
	)
	(segment
		(start 430.675034 -218.710002)
		(end 432.584606 -218.710002)
		(width 0.16002)
		(layer "In11.Cu")
		(net "M_L_CPU0_SA_DQS_DP<2>")
	)
	(segment
		(start 393.084812 -236.633004)
		(end 393.814046 -236.633004)
		(width 0.09525)
		(layer "In11.Cu")
		(net "M_L_CPU0_SA_DQS_DP<2>")
	)
	(segment
		(start 428.36211 -219.887546)
		(end 429.08601 -219.887546)
		(width 0.16002)
		(layer "In11.Cu")
		(net "M_L_CPU0_SA_DQS_DP<2>")
	)
	(segment
		(start 412.121604 -219.887546)
		(end 413.997902 -219.887546)
		(width 0.16002)
		(layer "In11.Cu")
		(net "M_L_CPU0_SA_DQS_DP<2>")
	)
	(segment
		(start 389.606282 -236.709204)
		(end 389.614664 -236.71403)
		(width 0.09525)
		(layer "In11.Cu")
		(net "M_L_CPU0_SA_DQS_DP<2>")
	)
	(segment
		(start 391.863072 -236.709204)
		(end 391.881106 -236.69879)
		(width 0.09525)
		(layer "In11.Cu")
		(net "M_L_CPU0_SA_DQS_DP<2>")
	)
	(segment
		(start 414.820862 -219.064586)
		(end 415.232342 -219.064586)
		(width 0.16002)
		(layer "In11.Cu")
		(net "M_L_CPU0_SA_DQS_DP<2>")
	)
	(segment
		(start 435.578504 -219.559886)
		(end 435.906164 -219.887546)
		(width 0.16002)
		(layer "In11.Cu")
		(net "M_L_CPU0_SA_DQS_DP<2>")
	)
	(segment
		(start 444.997078 -219.064586)
		(end 445.408558 -219.064586)
		(width 0.16002)
		(layer "In11.Cu")
		(net "M_L_CPU0_SA_DQS_DP<2>")
	)
	(segment
		(start 395.346936 -235.01731)
		(end 395.549882 -234.814364)
		(width 0.09525)
		(layer "In11.Cu")
		(net "M_L_CPU0_SA_DQS_DP<2>")
	)
	(segment
		(start 436.630064 -219.887546)
		(end 437.453024 -219.064586)
		(width 0.16002)
		(layer "In11.Cu")
		(net "M_L_CPU0_SA_DQS_DP<2>")
	)
	(segment
		(start 432.584606 -218.710002)
		(end 433.43449 -219.559886)
		(width 0.16002)
		(layer "In11.Cu")
		(net "M_L_CPU0_SA_DQS_DP<2>")
	)
	(segment
		(start 438.219088 -218.710002)
		(end 440.12866 -218.710002)
		(width 0.16002)
		(layer "In11.Cu")
		(net "M_L_CPU0_SA_DQS_DP<2>")
	)
	(segment
		(start 392.425174 -236.709204)
		(end 392.437112 -236.716062)
		(width 0.09525)
		(layer "In11.Cu")
		(net "M_L_CPU0_SA_DQS_DP<2>")
	)
	(arc
		(start 391.486136 -236.709204)
		(mid 391.667752 -236.759941)
		(end 391.851134 -236.716062)
		(width 0.09525)
		(layer "In11.Cu")
		(net "M_L_CPU0_SA_DQS_DP<2>")
	)
	(arc
		(start 389.043418 -236.709204)
		(mid 389.32485 -236.633449)
		(end 389.606282 -236.709204)
		(width 0.09525)
		(layer "In11.Cu")
		(net "M_L_CPU0_SA_DQS_DP<2>")
	)
	(arc
		(start 387.229604 -236.676184)
		(mid 387.481745 -236.634614)
		(end 387.726174 -236.709204)
		(width 0.09525)
		(layer "In11.Cu")
		(net "M_L_CPU0_SA_DQS_DP<2>")
	)
	(arc
		(start 392.437112 -236.716062)
		(mid 392.620747 -236.760012)
		(end 392.802618 -236.709204)
		(width 0.09525)
		(layer "In11.Cu")
		(net "M_L_CPU0_SA_DQS_DP<2>")
	)
	(arc
		(start 390.546336 -236.709204)
		(mid 390.734804 -236.759881)
		(end 390.923272 -236.709204)
		(width 0.09525)
		(layer "In11.Cu")
		(net "M_L_CPU0_SA_DQS_DP<2>")
	)
	(arc
		(start 388.666228 -236.709204)
		(mid 388.850003 -236.759976)
		(end 389.035036 -236.71403)
		(width 0.09525)
		(layer "In11.Cu")
		(net "M_L_CPU0_SA_DQS_DP<2>")
	)
	(arc
		(start 390.923272 -236.709204)
		(mid 391.204704 -236.633449)
		(end 391.486136 -236.709204)
		(width 0.09525)
		(layer "In11.Cu")
		(net "M_L_CPU0_SA_DQS_DP<2>")
	)
	(arc
		(start 387.726174 -236.709204)
		(mid 387.909949 -236.759976)
		(end 388.094982 -236.71403)
		(width 0.09525)
		(layer "In11.Cu")
		(net "M_L_CPU0_SA_DQS_DP<2>")
	)
	(arc
		(start 388.103364 -236.709204)
		(mid 388.384796 -236.633449)
		(end 388.666228 -236.709204)
		(width 0.09525)
		(layer "In11.Cu")
		(net "M_L_CPU0_SA_DQS_DP<2>")
	)
	(arc
		(start 392.802618 -236.709204)
		(mid 392.93867 -236.652435)
		(end 393.084812 -236.633004)
		(width 0.09525)
		(layer "In11.Cu")
		(net "M_L_CPU0_SA_DQS_DP<2>")
	)
	(arc
		(start 389.614664 -236.71403)
		(mid 389.799696 -236.759944)
		(end 389.983472 -236.709204)
		(width 0.09525)
		(layer "In11.Cu")
		(net "M_L_CPU0_SA_DQS_DP<2>")
	)
	(arc
		(start 389.983472 -236.709204)
		(mid 390.264904 -236.633449)
		(end 390.546336 -236.709204)
		(width 0.09525)
		(layer "In11.Cu")
		(net "M_L_CPU0_SA_DQS_DP<2>")
	)
	(arc
		(start 391.881106 -236.69879)
		(mid 392.154486 -236.633569)
		(end 392.425174 -236.709204)
		(width 0.09525)
		(layer "In11.Cu")
		(net "M_L_CPU0_SA_DQS_DP<2>")
	)
	(segment
		(start 386.50799 -231.789986)
		(end 386.974842 -231.524048)
		(width 0.12954)
		(layer "F.Cu")
		(net "M_L_CPU0_SA_DQS_DP<1>")
	)
	(segment
		(start 392.795252 -231.853994)
		(end 392.803634 -231.849168)
		(width 0.09525)
		(layer "In11.Cu")
		(net "M_L_CPU0_SA_DQS_DP<1>")
	)
	(segment
		(start 437.453024 -209.714592)
		(end 437.864504 -209.714592)
		(width 0.16002)
		(layer "In11.Cu")
		(net "M_L_CPU0_SA_DQS_DP<1>")
	)
	(segment
		(start 389.035036 -231.853994)
		(end 389.043418 -231.849168)
		(width 0.09525)
		(layer "In11.Cu")
		(net "M_L_CPU0_SA_DQS_DP<1>")
	)
	(segment
		(start 392.881104 -231.789986)
		(end 394.092938 -230.578152)
		(width 0.09525)
		(layer "In11.Cu")
		(net "M_L_CPU0_SA_DQS_DP<1>")
	)
	(segment
		(start 389.606282 -231.849168)
		(end 389.614664 -231.853994)
		(width 0.09525)
		(layer "In11.Cu")
		(net "M_L_CPU0_SA_DQS_DP<1>")
	)
	(segment
		(start 435.578504 -210.209892)
		(end 435.906164 -210.537552)
		(width 0.16002)
		(layer "In11.Cu")
		(net "M_L_CPU0_SA_DQS_DP<1>")
	)
	(segment
		(start 428.36211 -210.537552)
		(end 429.08601 -210.537552)
		(width 0.16002)
		(layer "In11.Cu")
		(net "M_L_CPU0_SA_DQS_DP<1>")
	)
	(segment
		(start 417.496498 -209.360008)
		(end 418.346382 -210.209892)
		(width 0.16002)
		(layer "In11.Cu")
		(net "M_L_CPU0_SA_DQS_DP<1>")
	)
	(segment
		(start 422.364916 -209.714592)
		(end 422.776396 -209.714592)
		(width 0.16002)
		(layer "In11.Cu")
		(net "M_L_CPU0_SA_DQS_DP<1>")
	)
	(segment
		(start 413.997902 -210.537552)
		(end 414.820862 -209.714592)
		(width 0.16002)
		(layer "In11.Cu")
		(net "M_L_CPU0_SA_DQS_DP<1>")
	)
	(segment
		(start 435.906164 -210.537552)
		(end 436.630064 -210.537552)
		(width 0.16002)
		(layer "In11.Cu")
		(net "M_L_CPU0_SA_DQS_DP<1>")
	)
	(segment
		(start 443.122558 -210.209892)
		(end 443.450218 -210.537552)
		(width 0.16002)
		(layer "In11.Cu")
		(net "M_L_CPU0_SA_DQS_DP<1>")
	)
	(segment
		(start 436.630064 -210.537552)
		(end 437.453024 -209.714592)
		(width 0.16002)
		(layer "In11.Cu")
		(net "M_L_CPU0_SA_DQS_DP<1>")
	)
	(segment
		(start 425.040552 -209.360008)
		(end 425.890436 -210.209892)
		(width 0.16002)
		(layer "In11.Cu")
		(net "M_L_CPU0_SA_DQS_DP<1>")
	)
	(segment
		(start 422.776396 -209.714592)
		(end 423.13098 -209.360008)
		(width 0.16002)
		(layer "In11.Cu")
		(net "M_L_CPU0_SA_DQS_DP<1>")
	)
	(segment
		(start 430.675034 -209.360008)
		(end 432.584606 -209.360008)
		(width 0.16002)
		(layer "In11.Cu")
		(net "M_L_CPU0_SA_DQS_DP<1>")
	)
	(segment
		(start 444.997078 -209.714592)
		(end 445.408558 -209.714592)
		(width 0.16002)
		(layer "In11.Cu")
		(net "M_L_CPU0_SA_DQS_DP<1>")
	)
	(segment
		(start 411.873192 -210.537552)
		(end 413.997902 -210.537552)
		(width 0.16002)
		(layer "In11.Cu")
		(net "M_L_CPU0_SA_DQS_DP<1>")
	)
	(segment
		(start 438.219088 -209.360008)
		(end 440.12866 -209.360008)
		(width 0.16002)
		(layer "In11.Cu")
		(net "M_L_CPU0_SA_DQS_DP<1>")
	)
	(segment
		(start 387.128766 -231.789478)
		(end 387.229604 -231.816148)
		(width 0.09525)
		(layer "In11.Cu")
		(net "M_L_CPU0_SA_DQS_DP<1>")
	)
	(segment
		(start 395.224762 -228.764592)
		(end 399.922238 -224.067878)
		(width 0.16002)
		(layer "In11.Cu")
		(net "M_L_CPU0_SA_DQS_DP<1>")
	)
	(segment
		(start 395.207998 -228.865176)
		(end 395.207998 -228.781356)
		(width 0.09525)
		(layer "In11.Cu")
		(net "M_L_CPU0_SA_DQS_DP<1>")
	)
	(segment
		(start 451.287134 -210.552792)
		(end 451.701662 -210.552792)
		(width 0.16002)
		(layer "In11.Cu")
		(net "M_L_CPU0_SA_DQS_DP<1>")
	)
	(segment
		(start 448.246754 -209.934048)
		(end 450.66839 -209.934048)
		(width 0.16002)
		(layer "In11.Cu")
		(net "M_L_CPU0_SA_DQS_DP<1>")
	)
	(segment
		(start 451.895464 -210.35899)
		(end 453.914256 -210.35899)
		(width 0.16002)
		(layer "In11.Cu")
		(net "M_L_CPU0_SA_DQS_DP<1>")
	)
	(segment
		(start 415.232342 -209.714592)
		(end 415.586926 -209.360008)
		(width 0.16002)
		(layer "In11.Cu")
		(net "M_L_CPU0_SA_DQS_DP<1>")
	)
	(segment
		(start 420.818056 -210.537552)
		(end 421.541956 -210.537552)
		(width 0.16002)
		(layer "In11.Cu")
		(net "M_L_CPU0_SA_DQS_DP<1>")
	)
	(segment
		(start 437.864504 -209.714592)
		(end 438.219088 -209.360008)
		(width 0.16002)
		(layer "In11.Cu")
		(net "M_L_CPU0_SA_DQS_DP<1>")
	)
	(segment
		(start 425.890436 -210.209892)
		(end 428.03445 -210.209892)
		(width 0.16002)
		(layer "In11.Cu")
		(net "M_L_CPU0_SA_DQS_DP<1>")
	)
	(segment
		(start 450.66839 -209.934048)
		(end 451.287134 -210.552792)
		(width 0.16002)
		(layer "In11.Cu")
		(net "M_L_CPU0_SA_DQS_DP<1>")
	)
	(segment
		(start 386.974842 -231.524048)
		(end 387.128766 -231.789478)
		(width 0.09525)
		(layer "In11.Cu")
		(net "M_L_CPU0_SA_DQS_DP<1>")
	)
	(segment
		(start 440.12866 -209.360008)
		(end 440.978544 -210.209892)
		(width 0.16002)
		(layer "In11.Cu")
		(net "M_L_CPU0_SA_DQS_DP<1>")
	)
	(segment
		(start 395.207998 -228.781356)
		(end 395.224762 -228.764592)
		(width 0.09525)
		(layer "In11.Cu")
		(net "M_L_CPU0_SA_DQS_DP<1>")
	)
	(segment
		(start 399.922238 -221.965012)
		(end 410.979366 -210.907884)
		(width 0.16002)
		(layer "In11.Cu")
		(net "M_L_CPU0_SA_DQS_DP<1>")
	)
	(segment
		(start 430.32045 -209.714592)
		(end 430.675034 -209.360008)
		(width 0.16002)
		(layer "In11.Cu")
		(net "M_L_CPU0_SA_DQS_DP<1>")
	)
	(segment
		(start 423.13098 -209.360008)
		(end 425.040552 -209.360008)
		(width 0.16002)
		(layer "In11.Cu")
		(net "M_L_CPU0_SA_DQS_DP<1>")
	)
	(segment
		(start 445.763142 -209.360008)
		(end 447.672714 -209.360008)
		(width 0.16002)
		(layer "In11.Cu")
		(net "M_L_CPU0_SA_DQS_DP<1>")
	)
	(segment
		(start 414.820862 -209.714592)
		(end 415.232342 -209.714592)
		(width 0.16002)
		(layer "In11.Cu")
		(net "M_L_CPU0_SA_DQS_DP<1>")
	)
	(segment
		(start 447.672714 -209.360008)
		(end 448.246754 -209.934048)
		(width 0.16002)
		(layer "In11.Cu")
		(net "M_L_CPU0_SA_DQS_DP<1>")
	)
	(segment
		(start 394.092938 -229.980236)
		(end 395.207998 -228.865176)
		(width 0.09525)
		(layer "In11.Cu")
		(net "M_L_CPU0_SA_DQS_DP<1>")
	)
	(segment
		(start 429.90897 -209.714592)
		(end 430.32045 -209.714592)
		(width 0.16002)
		(layer "In11.Cu")
		(net "M_L_CPU0_SA_DQS_DP<1>")
	)
	(segment
		(start 421.541956 -210.537552)
		(end 422.364916 -209.714592)
		(width 0.16002)
		(layer "In11.Cu")
		(net "M_L_CPU0_SA_DQS_DP<1>")
	)
	(segment
		(start 429.08601 -210.537552)
		(end 429.90897 -209.714592)
		(width 0.16002)
		(layer "In11.Cu")
		(net "M_L_CPU0_SA_DQS_DP<1>")
	)
	(segment
		(start 418.346382 -210.209892)
		(end 420.490396 -210.209892)
		(width 0.16002)
		(layer "In11.Cu")
		(net "M_L_CPU0_SA_DQS_DP<1>")
	)
	(segment
		(start 433.43449 -210.209892)
		(end 435.578504 -210.209892)
		(width 0.16002)
		(layer "In11.Cu")
		(net "M_L_CPU0_SA_DQS_DP<1>")
	)
	(segment
		(start 388.094982 -231.853994)
		(end 388.103364 -231.849168)
		(width 0.09525)
		(layer "In11.Cu")
		(net "M_L_CPU0_SA_DQS_DP<1>")
	)
	(segment
		(start 453.914256 -210.35899)
		(end 454.188068 -210.085178)
		(width 0.16002)
		(layer "In11.Cu")
		(net "M_L_CPU0_SA_DQS_DP<1>")
	)
	(segment
		(start 440.978544 -210.209892)
		(end 443.122558 -210.209892)
		(width 0.16002)
		(layer "In11.Cu")
		(net "M_L_CPU0_SA_DQS_DP<1>")
	)
	(segment
		(start 451.701662 -210.552792)
		(end 451.895464 -210.35899)
		(width 0.16002)
		(layer "In11.Cu")
		(net "M_L_CPU0_SA_DQS_DP<1>")
	)
	(segment
		(start 415.586926 -209.360008)
		(end 417.496498 -209.360008)
		(width 0.16002)
		(layer "In11.Cu")
		(net "M_L_CPU0_SA_DQS_DP<1>")
	)
	(segment
		(start 444.174118 -210.537552)
		(end 444.997078 -209.714592)
		(width 0.16002)
		(layer "In11.Cu")
		(net "M_L_CPU0_SA_DQS_DP<1>")
	)
	(segment
		(start 410.979366 -210.907884)
		(end 411.873192 -210.537552)
		(width 0.16002)
		(layer "In11.Cu")
		(net "M_L_CPU0_SA_DQS_DP<1>")
	)
	(segment
		(start 394.092938 -230.578152)
		(end 394.092938 -229.980236)
		(width 0.09525)
		(layer "In11.Cu")
		(net "M_L_CPU0_SA_DQS_DP<1>")
	)
	(segment
		(start 420.490396 -210.209892)
		(end 420.818056 -210.537552)
		(width 0.16002)
		(layer "In11.Cu")
		(net "M_L_CPU0_SA_DQS_DP<1>")
	)
	(segment
		(start 399.922238 -224.067878)
		(end 399.922238 -221.965012)
		(width 0.16002)
		(layer "In11.Cu")
		(net "M_L_CPU0_SA_DQS_DP<1>")
	)
	(segment
		(start 432.584606 -209.360008)
		(end 433.43449 -210.209892)
		(width 0.16002)
		(layer "In11.Cu")
		(net "M_L_CPU0_SA_DQS_DP<1>")
	)
	(segment
		(start 428.03445 -210.209892)
		(end 428.36211 -210.537552)
		(width 0.16002)
		(layer "In11.Cu")
		(net "M_L_CPU0_SA_DQS_DP<1>")
	)
	(segment
		(start 443.450218 -210.537552)
		(end 444.174118 -210.537552)
		(width 0.16002)
		(layer "In11.Cu")
		(net "M_L_CPU0_SA_DQS_DP<1>")
	)
	(segment
		(start 445.408558 -209.714592)
		(end 445.763142 -209.360008)
		(width 0.16002)
		(layer "In11.Cu")
		(net "M_L_CPU0_SA_DQS_DP<1>")
	)
	(arc
		(start 388.103364 -231.849168)
		(mid 388.384796 -231.773413)
		(end 388.666228 -231.849168)
		(width 0.09525)
		(layer "In11.Cu")
		(net "M_L_CPU0_SA_DQS_DP<1>")
	)
	(arc
		(start 387.726174 -231.849168)
		(mid 387.909949 -231.89994)
		(end 388.094982 -231.853994)
		(width 0.09525)
		(layer "In11.Cu")
		(net "M_L_CPU0_SA_DQS_DP<1>")
	)
	(arc
		(start 389.614664 -231.853994)
		(mid 389.799696 -231.899908)
		(end 389.983472 -231.849168)
		(width 0.09525)
		(layer "In11.Cu")
		(net "M_L_CPU0_SA_DQS_DP<1>")
	)
	(arc
		(start 391.86358 -231.849168)
		(mid 392.145012 -231.773413)
		(end 392.426444 -231.849168)
		(width 0.09525)
		(layer "In11.Cu")
		(net "M_L_CPU0_SA_DQS_DP<1>")
	)
	(arc
		(start 389.043418 -231.849168)
		(mid 389.32485 -231.773413)
		(end 389.606282 -231.849168)
		(width 0.09525)
		(layer "In11.Cu")
		(net "M_L_CPU0_SA_DQS_DP<1>")
	)
	(arc
		(start 389.983472 -231.849168)
		(mid 390.264904 -231.773413)
		(end 390.546336 -231.849168)
		(width 0.09525)
		(layer "In11.Cu")
		(net "M_L_CPU0_SA_DQS_DP<1>")
	)
	(arc
		(start 391.486136 -231.849168)
		(mid 391.674858 -231.899972)
		(end 391.86358 -231.849168)
		(width 0.09525)
		(layer "In11.Cu")
		(net "M_L_CPU0_SA_DQS_DP<1>")
	)
	(arc
		(start 390.923272 -231.849168)
		(mid 391.204704 -231.773413)
		(end 391.486136 -231.849168)
		(width 0.09525)
		(layer "In11.Cu")
		(net "M_L_CPU0_SA_DQS_DP<1>")
	)
	(arc
		(start 392.803634 -231.849168)
		(mid 392.844306 -231.822111)
		(end 392.881104 -231.789986)
		(width 0.09525)
		(layer "In11.Cu")
		(net "M_L_CPU0_SA_DQS_DP<1>")
	)
	(arc
		(start 392.426444 -231.849168)
		(mid 392.610219 -231.89994)
		(end 392.795252 -231.853994)
		(width 0.09525)
		(layer "In11.Cu")
		(net "M_L_CPU0_SA_DQS_DP<1>")
	)
	(arc
		(start 388.666228 -231.849168)
		(mid 388.850003 -231.89994)
		(end 389.035036 -231.853994)
		(width 0.09525)
		(layer "In11.Cu")
		(net "M_L_CPU0_SA_DQS_DP<1>")
	)
	(arc
		(start 387.229604 -231.816148)
		(mid 387.481745 -231.774578)
		(end 387.726174 -231.849168)
		(width 0.09525)
		(layer "In11.Cu")
		(net "M_L_CPU0_SA_DQS_DP<1>")
	)
	(arc
		(start 390.546336 -231.849168)
		(mid 390.734804 -231.899845)
		(end 390.923272 -231.849168)
		(width 0.09525)
		(layer "In11.Cu")
		(net "M_L_CPU0_SA_DQS_DP<1>")
	)
	(segment
		(start 386.50799 -226.930204)
		(end 386.974842 -226.664266)
		(width 0.12954)
		(layer "F.Cu")
		(net "M_L_CPU0_SA_DQS_DP<0>")
	)
	(segment
		(start 410.460952 -201.187558)
		(end 413.997902 -201.187558)
		(width 0.16002)
		(layer "In11.Cu")
		(net "M_L_CPU0_SA_DQS_DP<0>")
	)
	(segment
		(start 393.516866 -222.659956)
		(end 394.154152 -222.02267)
		(width 0.09525)
		(layer "In11.Cu")
		(net "M_L_CPU0_SA_DQS_DP<0>")
	)
	(segment
		(start 433.43449 -200.859898)
		(end 435.578504 -200.859898)
		(width 0.16002)
		(layer "In11.Cu")
		(net "M_L_CPU0_SA_DQS_DP<0>")
	)
	(segment
		(start 451.701662 -201.202798)
		(end 451.895464 -201.008996)
		(width 0.16002)
		(layer "In11.Cu")
		(net "M_L_CPU0_SA_DQS_DP<0>")
	)
	(segment
		(start 429.90897 -200.364598)
		(end 430.32045 -200.364598)
		(width 0.16002)
		(layer "In11.Cu")
		(net "M_L_CPU0_SA_DQS_DP<0>")
	)
	(segment
		(start 417.496498 -200.010014)
		(end 418.346382 -200.859898)
		(width 0.16002)
		(layer "In11.Cu")
		(net "M_L_CPU0_SA_DQS_DP<0>")
	)
	(segment
		(start 435.906164 -201.187558)
		(end 436.630064 -201.187558)
		(width 0.16002)
		(layer "In11.Cu")
		(net "M_L_CPU0_SA_DQS_DP<0>")
	)
	(segment
		(start 394.095224 -221.197932)
		(end 394.095224 -221.17431)
		(width 0.09525)
		(layer "In11.Cu")
		(net "M_L_CPU0_SA_DQS_DP<0>")
	)
	(segment
		(start 387.128766 -226.929696)
		(end 387.229604 -226.956366)
		(width 0.09525)
		(layer "In11.Cu")
		(net "M_L_CPU0_SA_DQS_DP<0>")
	)
	(segment
		(start 393.236958 -222.960692)
		(end 393.309348 -222.918782)
		(width 0.09525)
		(layer "In11.Cu")
		(net "M_L_CPU0_SA_DQS_DP<0>")
	)
	(segment
		(start 430.32045 -200.364598)
		(end 430.675034 -200.010014)
		(width 0.16002)
		(layer "In11.Cu")
		(net "M_L_CPU0_SA_DQS_DP<0>")
	)
	(segment
		(start 422.776396 -200.364598)
		(end 423.13098 -200.010014)
		(width 0.16002)
		(layer "In11.Cu")
		(net "M_L_CPU0_SA_DQS_DP<0>")
	)
	(segment
		(start 445.408558 -200.364598)
		(end 445.763142 -200.010014)
		(width 0.16002)
		(layer "In11.Cu")
		(net "M_L_CPU0_SA_DQS_DP<0>")
	)
	(segment
		(start 414.820862 -200.364598)
		(end 415.232342 -200.364598)
		(width 0.16002)
		(layer "In11.Cu")
		(net "M_L_CPU0_SA_DQS_DP<0>")
	)
	(segment
		(start 394.154152 -221.25686)
		(end 394.095224 -221.197932)
		(width 0.09525)
		(layer "In11.Cu")
		(net "M_L_CPU0_SA_DQS_DP<0>")
	)
	(segment
		(start 429.08601 -201.187558)
		(end 429.90897 -200.364598)
		(width 0.16002)
		(layer "In11.Cu")
		(net "M_L_CPU0_SA_DQS_DP<0>")
	)
	(segment
		(start 437.864504 -200.364598)
		(end 438.219088 -200.010014)
		(width 0.16002)
		(layer "In11.Cu")
		(net "M_L_CPU0_SA_DQS_DP<0>")
	)
	(segment
		(start 392.333226 -224.559368)
		(end 392.367008 -224.53981)
		(width 0.09525)
		(layer "In11.Cu")
		(net "M_L_CPU0_SA_DQS_DP<0>")
	)
	(segment
		(start 437.453024 -200.364598)
		(end 437.864504 -200.364598)
		(width 0.16002)
		(layer "In11.Cu")
		(net "M_L_CPU0_SA_DQS_DP<0>")
	)
	(segment
		(start 418.346382 -200.859898)
		(end 420.490396 -200.859898)
		(width 0.16002)
		(layer "In11.Cu")
		(net "M_L_CPU0_SA_DQS_DP<0>")
	)
	(segment
		(start 388.094982 -226.994212)
		(end 388.103364 -226.989386)
		(width 0.09525)
		(layer "In11.Cu")
		(net "M_L_CPU0_SA_DQS_DP<0>")
	)
	(segment
		(start 394.095224 -221.17431)
		(end 394.095224 -217.553286)
		(width 0.16002)
		(layer "In11.Cu")
		(net "M_L_CPU0_SA_DQS_DP<0>")
	)
	(segment
		(start 425.890436 -200.859898)
		(end 428.03445 -200.859898)
		(width 0.16002)
		(layer "In11.Cu")
		(net "M_L_CPU0_SA_DQS_DP<0>")
	)
	(segment
		(start 390.923272 -226.989386)
		(end 390.955784 -226.97059)
		(width 0.09525)
		(layer "In11.Cu")
		(net "M_L_CPU0_SA_DQS_DP<0>")
	)
	(segment
		(start 443.122558 -200.859898)
		(end 443.450218 -201.187558)
		(width 0.16002)
		(layer "In11.Cu")
		(net "M_L_CPU0_SA_DQS_DP<0>")
	)
	(segment
		(start 413.997902 -201.187558)
		(end 414.820862 -200.364598)
		(width 0.16002)
		(layer "In11.Cu")
		(net "M_L_CPU0_SA_DQS_DP<0>")
	)
	(segment
		(start 448.246754 -200.584054)
		(end 450.66839 -200.584054)
		(width 0.16002)
		(layer "In11.Cu")
		(net "M_L_CPU0_SA_DQS_DP<0>")
	)
	(segment
		(start 392.29665 -224.580704)
		(end 392.333226 -224.559368)
		(width 0.09525)
		(layer "In11.Cu")
		(net "M_L_CPU0_SA_DQS_DP<0>")
	)
	(segment
		(start 436.630064 -201.187558)
		(end 437.453024 -200.364598)
		(width 0.16002)
		(layer "In11.Cu")
		(net "M_L_CPU0_SA_DQS_DP<0>")
	)
	(segment
		(start 391.355326 -226.201478)
		(end 391.393426 -226.17938)
		(width 0.09525)
		(layer "In11.Cu")
		(net "M_L_CPU0_SA_DQS_DP<0>")
	)
	(segment
		(start 428.03445 -200.859898)
		(end 428.36211 -201.187558)
		(width 0.16002)
		(layer "In11.Cu")
		(net "M_L_CPU0_SA_DQS_DP<0>")
	)
	(segment
		(start 389.035036 -226.994212)
		(end 389.043418 -226.989386)
		(width 0.09525)
		(layer "In11.Cu")
		(net "M_L_CPU0_SA_DQS_DP<0>")
	)
	(segment
		(start 444.174118 -201.187558)
		(end 444.997078 -200.364598)
		(width 0.16002)
		(layer "In11.Cu")
		(net "M_L_CPU0_SA_DQS_DP<0>")
	)
	(segment
		(start 451.287134 -201.202798)
		(end 451.701662 -201.202798)
		(width 0.16002)
		(layer "In11.Cu")
		(net "M_L_CPU0_SA_DQS_DP<0>")
	)
	(segment
		(start 444.997078 -200.364598)
		(end 445.408558 -200.364598)
		(width 0.16002)
		(layer "In11.Cu")
		(net "M_L_CPU0_SA_DQS_DP<0>")
	)
	(segment
		(start 445.763142 -200.010014)
		(end 447.672714 -200.010014)
		(width 0.16002)
		(layer "In11.Cu")
		(net "M_L_CPU0_SA_DQS_DP<0>")
	)
	(segment
		(start 391.863326 -225.369374)
		(end 391.895838 -225.350578)
		(width 0.09525)
		(layer "In11.Cu")
		(net "M_L_CPU0_SA_DQS_DP<0>")
	)
	(segment
		(start 389.606282 -226.989386)
		(end 389.614664 -226.994212)
		(width 0.09525)
		(layer "In11.Cu")
		(net "M_L_CPU0_SA_DQS_DP<0>")
	)
	(segment
		(start 421.541956 -201.187558)
		(end 422.364916 -200.364598)
		(width 0.16002)
		(layer "In11.Cu")
		(net "M_L_CPU0_SA_DQS_DP<0>")
	)
	(segment
		(start 391.393426 -226.17938)
		(end 391.424922 -226.161092)
		(width 0.09525)
		(layer "In11.Cu")
		(net "M_L_CPU0_SA_DQS_DP<0>")
	)
	(segment
		(start 450.66839 -200.584054)
		(end 451.287134 -201.202798)
		(width 0.16002)
		(layer "In11.Cu")
		(net "M_L_CPU0_SA_DQS_DP<0>")
	)
	(segment
		(start 423.13098 -200.010014)
		(end 425.040552 -200.010014)
		(width 0.16002)
		(layer "In11.Cu")
		(net "M_L_CPU0_SA_DQS_DP<0>")
	)
	(segment
		(start 386.974842 -226.664266)
		(end 387.128766 -226.929696)
		(width 0.09525)
		(layer "In11.Cu")
		(net "M_L_CPU0_SA_DQS_DP<0>")
	)
	(segment
		(start 415.586926 -200.010014)
		(end 417.496498 -200.010014)
		(width 0.16002)
		(layer "In11.Cu")
		(net "M_L_CPU0_SA_DQS_DP<0>")
	)
	(segment
		(start 428.36211 -201.187558)
		(end 429.08601 -201.187558)
		(width 0.16002)
		(layer "In11.Cu")
		(net "M_L_CPU0_SA_DQS_DP<0>")
	)
	(segment
		(start 430.675034 -200.010014)
		(end 432.584606 -200.010014)
		(width 0.16002)
		(layer "In11.Cu")
		(net "M_L_CPU0_SA_DQS_DP<0>")
	)
	(segment
		(start 443.450218 -201.187558)
		(end 444.174118 -201.187558)
		(width 0.16002)
		(layer "In11.Cu")
		(net "M_L_CPU0_SA_DQS_DP<0>")
	)
	(segment
		(start 394.154152 -222.02267)
		(end 394.154152 -221.25686)
		(width 0.09525)
		(layer "In11.Cu")
		(net "M_L_CPU0_SA_DQS_DP<0>")
	)
	(segment
		(start 392.76528 -223.77146)
		(end 392.80338 -223.749362)
		(width 0.09525)
		(layer "In11.Cu")
		(net "M_L_CPU0_SA_DQS_DP<0>")
	)
	(segment
		(start 435.578504 -200.859898)
		(end 435.906164 -201.187558)
		(width 0.16002)
		(layer "In11.Cu")
		(net "M_L_CPU0_SA_DQS_DP<0>")
	)
	(segment
		(start 425.040552 -200.010014)
		(end 425.890436 -200.859898)
		(width 0.16002)
		(layer "In11.Cu")
		(net "M_L_CPU0_SA_DQS_DP<0>")
	)
	(segment
		(start 420.818056 -201.187558)
		(end 421.541956 -201.187558)
		(width 0.16002)
		(layer "In11.Cu")
		(net "M_L_CPU0_SA_DQS_DP<0>")
	)
	(segment
		(start 440.978544 -200.859898)
		(end 443.122558 -200.859898)
		(width 0.16002)
		(layer "In11.Cu")
		(net "M_L_CPU0_SA_DQS_DP<0>")
	)
	(segment
		(start 422.364916 -200.364598)
		(end 422.776396 -200.364598)
		(width 0.16002)
		(layer "In11.Cu")
		(net "M_L_CPU0_SA_DQS_DP<0>")
	)
	(segment
		(start 453.914256 -201.008996)
		(end 454.188068 -200.735184)
		(width 0.16002)
		(layer "In11.Cu")
		(net "M_L_CPU0_SA_DQS_DP<0>")
	)
	(segment
		(start 438.219088 -200.010014)
		(end 440.12866 -200.010014)
		(width 0.16002)
		(layer "In11.Cu")
		(net "M_L_CPU0_SA_DQS_DP<0>")
	)
	(segment
		(start 420.490396 -200.859898)
		(end 420.818056 -201.187558)
		(width 0.16002)
		(layer "In11.Cu")
		(net "M_L_CPU0_SA_DQS_DP<0>")
	)
	(segment
		(start 451.895464 -201.008996)
		(end 453.914256 -201.008996)
		(width 0.16002)
		(layer "In11.Cu")
		(net "M_L_CPU0_SA_DQS_DP<0>")
	)
	(segment
		(start 392.80338 -223.749362)
		(end 392.835892 -223.730566)
		(width 0.09525)
		(layer "In11.Cu")
		(net "M_L_CPU0_SA_DQS_DP<0>")
	)
	(segment
		(start 440.12866 -200.010014)
		(end 440.978544 -200.859898)
		(width 0.16002)
		(layer "In11.Cu")
		(net "M_L_CPU0_SA_DQS_DP<0>")
	)
	(segment
		(start 432.584606 -200.010014)
		(end 433.43449 -200.859898)
		(width 0.16002)
		(layer "In11.Cu")
		(net "M_L_CPU0_SA_DQS_DP<0>")
	)
	(segment
		(start 415.232342 -200.364598)
		(end 415.586926 -200.010014)
		(width 0.16002)
		(layer "In11.Cu")
		(net "M_L_CPU0_SA_DQS_DP<0>")
	)
	(segment
		(start 391.82675 -225.39071)
		(end 391.863326 -225.369374)
		(width 0.09525)
		(layer "In11.Cu")
		(net "M_L_CPU0_SA_DQS_DP<0>")
	)
	(segment
		(start 394.095224 -217.553286)
		(end 410.460952 -201.187558)
		(width 0.16002)
		(layer "In11.Cu")
		(net "M_L_CPU0_SA_DQS_DP<0>")
	)
	(segment
		(start 447.672714 -200.010014)
		(end 448.246754 -200.584054)
		(width 0.16002)
		(layer "In11.Cu")
		(net "M_L_CPU0_SA_DQS_DP<0>")
	)
	(arc
		(start 391.424922 -226.161092)
		(mid 391.54072 -226.026698)
		(end 391.582402 -225.85426)
		(width 0.09525)
		(layer "In11.Cu")
		(net "M_L_CPU0_SA_DQS_DP<0>")
	)
	(arc
		(start 389.614664 -226.994212)
		(mid 389.799696 -227.040126)
		(end 389.983472 -226.989386)
		(width 0.09525)
		(layer "In11.Cu")
		(net "M_L_CPU0_SA_DQS_DP<0>")
	)
	(arc
		(start 391.582402 -225.85426)
		(mid 391.647231 -225.592258)
		(end 391.82675 -225.39071)
		(width 0.09525)
		(layer "In11.Cu")
		(net "M_L_CPU0_SA_DQS_DP<0>")
	)
	(arc
		(start 388.103364 -226.989386)
		(mid 388.384796 -226.913631)
		(end 388.666228 -226.989386)
		(width 0.09525)
		(layer "In11.Cu")
		(net "M_L_CPU0_SA_DQS_DP<0>")
	)
	(arc
		(start 390.546336 -226.989386)
		(mid 390.734804 -227.040063)
		(end 390.923272 -226.989386)
		(width 0.09525)
		(layer "In11.Cu")
		(net "M_L_CPU0_SA_DQS_DP<0>")
	)
	(arc
		(start 390.955784 -226.97059)
		(mid 391.071058 -226.836312)
		(end 391.112502 -226.664266)
		(width 0.09525)
		(layer "In11.Cu")
		(net "M_L_CPU0_SA_DQS_DP<0>")
	)
	(arc
		(start 392.052556 -225.044254)
		(mid 392.117316 -224.782319)
		(end 392.29665 -224.580704)
		(width 0.09525)
		(layer "In11.Cu")
		(net "M_L_CPU0_SA_DQS_DP<0>")
	)
	(arc
		(start 392.835892 -223.730566)
		(mid 392.951166 -223.596288)
		(end 392.99261 -223.424242)
		(width 0.09525)
		(layer "In11.Cu")
		(net "M_L_CPU0_SA_DQS_DP<0>")
	)
	(arc
		(start 392.522456 -224.234248)
		(mid 392.586853 -223.972942)
		(end 392.76528 -223.77146)
		(width 0.09525)
		(layer "In11.Cu")
		(net "M_L_CPU0_SA_DQS_DP<0>")
	)
	(arc
		(start 387.726174 -226.989386)
		(mid 387.909949 -227.040158)
		(end 388.094982 -226.994212)
		(width 0.09525)
		(layer "In11.Cu")
		(net "M_L_CPU0_SA_DQS_DP<0>")
	)
	(arc
		(start 392.367008 -224.53981)
		(mid 392.481387 -224.405671)
		(end 392.522456 -224.234248)
		(width 0.09525)
		(layer "In11.Cu")
		(net "M_L_CPU0_SA_DQS_DP<0>")
	)
	(arc
		(start 391.895838 -225.350578)
		(mid 392.011112 -225.2163)
		(end 392.052556 -225.044254)
		(width 0.09525)
		(layer "In11.Cu")
		(net "M_L_CPU0_SA_DQS_DP<0>")
	)
	(arc
		(start 393.309348 -222.918782)
		(mid 393.371028 -222.861777)
		(end 393.418568 -222.792544)
		(width 0.09525)
		(layer "In11.Cu")
		(net "M_L_CPU0_SA_DQS_DP<0>")
	)
	(arc
		(start 392.99261 -223.424242)
		(mid 393.057439 -223.16224)
		(end 393.236958 -222.960692)
		(width 0.09525)
		(layer "In11.Cu")
		(net "M_L_CPU0_SA_DQS_DP<0>")
	)
	(arc
		(start 389.983472 -226.989386)
		(mid 390.264904 -226.913631)
		(end 390.546336 -226.989386)
		(width 0.09525)
		(layer "In11.Cu")
		(net "M_L_CPU0_SA_DQS_DP<0>")
	)
	(arc
		(start 389.043418 -226.989386)
		(mid 389.32485 -226.913631)
		(end 389.606282 -226.989386)
		(width 0.09525)
		(layer "In11.Cu")
		(net "M_L_CPU0_SA_DQS_DP<0>")
	)
	(arc
		(start 391.112502 -226.664266)
		(mid 391.176899 -226.40296)
		(end 391.355326 -226.201478)
		(width 0.09525)
		(layer "In11.Cu")
		(net "M_L_CPU0_SA_DQS_DP<0>")
	)
	(arc
		(start 388.666228 -226.989386)
		(mid 388.850003 -227.040158)
		(end 389.035036 -226.994212)
		(width 0.09525)
		(layer "In11.Cu")
		(net "M_L_CPU0_SA_DQS_DP<0>")
	)
	(arc
		(start 393.418568 -222.792544)
		(mid 393.46284 -222.722636)
		(end 393.516866 -222.659956)
		(width 0.09525)
		(layer "In11.Cu")
		(net "M_L_CPU0_SA_DQS_DP<0>")
	)
	(arc
		(start 387.229604 -226.956366)
		(mid 387.481745 -226.914796)
		(end 387.726174 -226.989386)
		(width 0.09525)
		(layer "In11.Cu")
		(net "M_L_CPU0_SA_DQS_DP<0>")
	)
	(segment
		(start 385.098036 -247.1801)
		(end 385.564888 -246.914162)
		(width 0.12954)
		(layer "F.Cu")
		(net "M_L_CPU0_SA_DQS_DN<9>")
	)
	(segment
		(start 447.401442 -239.25911)
		(end 449.813934 -239.25911)
		(width 0.16002)
		(layer "In11.Cu")
		(net "M_L_CPU0_SA_DQS_DN<9>")
	)
	(segment
		(start 395.859254 -247.814084)
		(end 396.002764 -247.814084)
		(width 0.16002)
		(layer "In11.Cu")
		(net "M_L_CPU0_SA_DQS_DN<9>")
	)
	(segment
		(start 425.88307 -239.407954)
		(end 426.733208 -240.258092)
		(width 0.16002)
		(layer "In11.Cu")
		(net "M_L_CPU0_SA_DQS_DN<9>")
	)
	(segment
		(start 391.016236 -247.239282)
		(end 391.024618 -247.244108)
		(width 0.09525)
		(layer "In11.Cu")
		(net "M_L_CPU0_SA_DQS_DN<9>")
	)
	(segment
		(start 391.393426 -247.239282)
		(end 391.416794 -247.22582)
		(width 0.09525)
		(layer "In11.Cu")
		(net "M_L_CPU0_SA_DQS_DN<9>")
	)
	(segment
		(start 429.902874 -239.029494)
		(end 430.725326 -239.029494)
		(width 0.16002)
		(layer "In11.Cu")
		(net "M_L_CPU0_SA_DQS_DN<9>")
	)
	(segment
		(start 428.42815 -239.882934)
		(end 429.049434 -239.882934)
		(width 0.16002)
		(layer "In11.Cu")
		(net "M_L_CPU0_SA_DQS_DN<9>")
	)
	(segment
		(start 393.084812 -247.289828)
		(end 394.921994 -247.289828)
		(width 0.09525)
		(layer "In11.Cu")
		(net "M_L_CPU0_SA_DQS_DN<9>")
	)
	(segment
		(start 428.052992 -240.258092)
		(end 428.42815 -239.882934)
		(width 0.16002)
		(layer "In11.Cu")
		(net "M_L_CPU0_SA_DQS_DN<9>")
	)
	(segment
		(start 386.685028 -247.244108)
		(end 386.69341 -247.239282)
		(width 0.09525)
		(layer "In11.Cu")
		(net "M_L_CPU0_SA_DQS_DN<9>")
	)
	(segment
		(start 446.191894 -239.407954)
		(end 447.252598 -239.407954)
		(width 0.16002)
		(layer "In11.Cu")
		(net "M_L_CPU0_SA_DQS_DN<9>")
	)
	(segment
		(start 390.44499 -247.244108)
		(end 390.453372 -247.239282)
		(width 0.09525)
		(layer "In11.Cu")
		(net "M_L_CPU0_SA_DQS_DN<9>")
	)
	(segment
		(start 443.516258 -239.882934)
		(end 444.137542 -239.882934)
		(width 0.16002)
		(layer "In11.Cu")
		(net "M_L_CPU0_SA_DQS_DN<9>")
	)
	(segment
		(start 392.321288 -247.247664)
		(end 392.335766 -247.239282)
		(width 0.09525)
		(layer "In11.Cu")
		(net "M_L_CPU0_SA_DQS_DN<9>")
	)
	(segment
		(start 433.073302 -239.50549)
		(end 433.41036 -239.168432)
		(width 0.16002)
		(layer "In11.Cu")
		(net "M_L_CPU0_SA_DQS_DN<9>")
	)
	(segment
		(start 434.506116 -240.258092)
		(end 435.597046 -240.258092)
		(width 0.16002)
		(layer "In11.Cu")
		(net "M_L_CPU0_SA_DQS_DN<9>")
	)
	(segment
		(start 426.733208 -240.258092)
		(end 428.052992 -240.258092)
		(width 0.16002)
		(layer "In11.Cu")
		(net "M_L_CPU0_SA_DQS_DN<9>")
	)
	(segment
		(start 435.597046 -240.258092)
		(end 435.972204 -239.882934)
		(width 0.16002)
		(layer "In11.Cu")
		(net "M_L_CPU0_SA_DQS_DN<9>")
	)
	(segment
		(start 396.002764 -247.814084)
		(end 396.939516 -246.877332)
		(width 0.16002)
		(layer "In11.Cu")
		(net "M_L_CPU0_SA_DQS_DN<9>")
	)
	(segment
		(start 440.971178 -239.407954)
		(end 441.821316 -240.258092)
		(width 0.16002)
		(layer "In11.Cu")
		(net "M_L_CPU0_SA_DQS_DN<9>")
	)
	(segment
		(start 415.598356 -240.258092)
		(end 417.36518 -240.258092)
		(width 0.16002)
		(layer "In11.Cu")
		(net "M_L_CPU0_SA_DQS_DN<9>")
	)
	(segment
		(start 392.871706 -247.22455)
		(end 392.897106 -247.239282)
		(width 0.09525)
		(layer "In11.Cu")
		(net "M_L_CPU0_SA_DQS_DN<9>")
	)
	(segment
		(start 423.181272 -239.029494)
		(end 423.559732 -239.407954)
		(width 0.16002)
		(layer "In11.Cu")
		(net "M_L_CPU0_SA_DQS_DN<9>")
	)
	(segment
		(start 436.593488 -239.882934)
		(end 437.446928 -239.029494)
		(width 0.16002)
		(layer "In11.Cu")
		(net "M_L_CPU0_SA_DQS_DN<9>")
	)
	(segment
		(start 434.009038 -239.168432)
		(end 434.346096 -239.50549)
		(width 0.16002)
		(layer "In11.Cu")
		(net "M_L_CPU0_SA_DQS_DN<9>")
	)
	(segment
		(start 417.862258 -239.198912)
		(end 418.460936 -239.198912)
		(width 0.16002)
		(layer "In11.Cu")
		(net "M_L_CPU0_SA_DQS_DN<9>")
	)
	(segment
		(start 406.279096 -246.877332)
		(end 412.048452 -241.107976)
		(width 0.16002)
		(layer "In11.Cu")
		(net "M_L_CPU0_SA_DQS_DN<9>")
	)
	(segment
		(start 418.797994 -240.098072)
		(end 418.958014 -240.258092)
		(width 0.16002)
		(layer "In11.Cu")
		(net "M_L_CPU0_SA_DQS_DN<9>")
	)
	(segment
		(start 412.048452 -241.107976)
		(end 414.748472 -241.107976)
		(width 0.16002)
		(layer "In11.Cu")
		(net "M_L_CPU0_SA_DQS_DN<9>")
	)
	(segment
		(start 423.559732 -239.407954)
		(end 425.88307 -239.407954)
		(width 0.16002)
		(layer "In11.Cu")
		(net "M_L_CPU0_SA_DQS_DN<9>")
	)
	(segment
		(start 434.346096 -239.50549)
		(end 434.346096 -240.098072)
		(width 0.16002)
		(layer "In11.Cu")
		(net "M_L_CPU0_SA_DQS_DN<9>")
	)
	(segment
		(start 385.564888 -246.914162)
		(end 385.718812 -247.179592)
		(width 0.09525)
		(layer "In11.Cu")
		(net "M_L_CPU0_SA_DQS_DN<9>")
	)
	(segment
		(start 432.427126 -240.258092)
		(end 432.913282 -240.258092)
		(width 0.16002)
		(layer "In11.Cu")
		(net "M_L_CPU0_SA_DQS_DN<9>")
	)
	(segment
		(start 421.50538 -239.882934)
		(end 422.35882 -239.029494)
		(width 0.16002)
		(layer "In11.Cu")
		(net "M_L_CPU0_SA_DQS_DN<9>")
	)
	(segment
		(start 431.245264 -239.549432)
		(end 431.718466 -239.549432)
		(width 0.16002)
		(layer "In11.Cu")
		(net "M_L_CPU0_SA_DQS_DN<9>")
	)
	(segment
		(start 417.5252 -239.53597)
		(end 417.862258 -239.198912)
		(width 0.16002)
		(layer "In11.Cu")
		(net "M_L_CPU0_SA_DQS_DN<9>")
	)
	(segment
		(start 430.725326 -239.029494)
		(end 431.245264 -239.549432)
		(width 0.16002)
		(layer "In11.Cu")
		(net "M_L_CPU0_SA_DQS_DN<9>")
	)
	(segment
		(start 388.196328 -247.239282)
		(end 388.20471 -247.244108)
		(width 0.09525)
		(layer "In11.Cu")
		(net "M_L_CPU0_SA_DQS_DN<9>")
	)
	(segment
		(start 395.77645 -247.873266)
		(end 395.835632 -247.814084)
		(width 0.09525)
		(layer "In11.Cu")
		(net "M_L_CPU0_SA_DQS_DN<9>")
	)
	(segment
		(start 433.41036 -239.168432)
		(end 434.009038 -239.168432)
		(width 0.16002)
		(layer "In11.Cu")
		(net "M_L_CPU0_SA_DQS_DN<9>")
	)
	(segment
		(start 418.797994 -239.53597)
		(end 418.797994 -240.098072)
		(width 0.16002)
		(layer "In11.Cu")
		(net "M_L_CPU0_SA_DQS_DN<9>")
	)
	(segment
		(start 441.821316 -240.258092)
		(end 443.1411 -240.258092)
		(width 0.16002)
		(layer "In11.Cu")
		(net "M_L_CPU0_SA_DQS_DN<9>")
	)
	(segment
		(start 444.990982 -239.029494)
		(end 445.813434 -239.029494)
		(width 0.16002)
		(layer "In11.Cu")
		(net "M_L_CPU0_SA_DQS_DN<9>")
	)
	(segment
		(start 435.972204 -239.882934)
		(end 436.593488 -239.882934)
		(width 0.16002)
		(layer "In11.Cu")
		(net "M_L_CPU0_SA_DQS_DN<9>")
	)
	(segment
		(start 418.958014 -240.258092)
		(end 420.508938 -240.258092)
		(width 0.16002)
		(layer "In11.Cu")
		(net "M_L_CPU0_SA_DQS_DN<9>")
	)
	(segment
		(start 443.1411 -240.258092)
		(end 443.516258 -239.882934)
		(width 0.16002)
		(layer "In11.Cu")
		(net "M_L_CPU0_SA_DQS_DN<9>")
	)
	(segment
		(start 445.813434 -239.029494)
		(end 446.191894 -239.407954)
		(width 0.16002)
		(layer "In11.Cu")
		(net "M_L_CPU0_SA_DQS_DN<9>")
	)
	(segment
		(start 418.460936 -239.198912)
		(end 418.797994 -239.53597)
		(width 0.16002)
		(layer "In11.Cu")
		(net "M_L_CPU0_SA_DQS_DN<9>")
	)
	(segment
		(start 447.252598 -239.407954)
		(end 447.401442 -239.25911)
		(width 0.16002)
		(layer "In11.Cu")
		(net "M_L_CPU0_SA_DQS_DN<9>")
	)
	(segment
		(start 422.35882 -239.029494)
		(end 423.181272 -239.029494)
		(width 0.16002)
		(layer "In11.Cu")
		(net "M_L_CPU0_SA_DQS_DN<9>")
	)
	(segment
		(start 395.505432 -247.873266)
		(end 395.77645 -247.873266)
		(width 0.09525)
		(layer "In11.Cu")
		(net "M_L_CPU0_SA_DQS_DN<9>")
	)
	(segment
		(start 414.748472 -241.107976)
		(end 415.598356 -240.258092)
		(width 0.16002)
		(layer "In11.Cu")
		(net "M_L_CPU0_SA_DQS_DN<9>")
	)
	(segment
		(start 438.26938 -239.029494)
		(end 438.64784 -239.407954)
		(width 0.16002)
		(layer "In11.Cu")
		(net "M_L_CPU0_SA_DQS_DN<9>")
	)
	(segment
		(start 420.884096 -239.882934)
		(end 421.50538 -239.882934)
		(width 0.16002)
		(layer "In11.Cu")
		(net "M_L_CPU0_SA_DQS_DN<9>")
	)
	(segment
		(start 433.073302 -240.098072)
		(end 433.073302 -239.50549)
		(width 0.16002)
		(layer "In11.Cu")
		(net "M_L_CPU0_SA_DQS_DN<9>")
	)
	(segment
		(start 431.718466 -239.549432)
		(end 432.427126 -240.258092)
		(width 0.16002)
		(layer "In11.Cu")
		(net "M_L_CPU0_SA_DQS_DN<9>")
	)
	(segment
		(start 417.36518 -240.258092)
		(end 417.5252 -240.098072)
		(width 0.16002)
		(layer "In11.Cu")
		(net "M_L_CPU0_SA_DQS_DN<9>")
	)
	(segment
		(start 437.446928 -239.029494)
		(end 438.26938 -239.029494)
		(width 0.16002)
		(layer "In11.Cu")
		(net "M_L_CPU0_SA_DQS_DN<9>")
	)
	(segment
		(start 385.718812 -247.179592)
		(end 385.81965 -247.206262)
		(width 0.09525)
		(layer "In11.Cu")
		(net "M_L_CPU0_SA_DQS_DN<9>")
	)
	(segment
		(start 438.64784 -239.407954)
		(end 440.971178 -239.407954)
		(width 0.16002)
		(layer "In11.Cu")
		(net "M_L_CPU0_SA_DQS_DN<9>")
	)
	(segment
		(start 387.256274 -247.239282)
		(end 387.264656 -247.244108)
		(width 0.09525)
		(layer "In11.Cu")
		(net "M_L_CPU0_SA_DQS_DN<9>")
	)
	(segment
		(start 444.137542 -239.882934)
		(end 444.990982 -239.029494)
		(width 0.16002)
		(layer "In11.Cu")
		(net "M_L_CPU0_SA_DQS_DN<9>")
	)
	(segment
		(start 394.921994 -247.289828)
		(end 395.505432 -247.873266)
		(width 0.09525)
		(layer "In11.Cu")
		(net "M_L_CPU0_SA_DQS_DN<9>")
	)
	(segment
		(start 434.346096 -240.098072)
		(end 434.506116 -240.258092)
		(width 0.16002)
		(layer "In11.Cu")
		(net "M_L_CPU0_SA_DQS_DN<9>")
	)
	(segment
		(start 396.939516 -246.877332)
		(end 406.279096 -246.877332)
		(width 0.16002)
		(layer "In11.Cu")
		(net "M_L_CPU0_SA_DQS_DN<9>")
	)
	(segment
		(start 420.508938 -240.258092)
		(end 420.884096 -239.882934)
		(width 0.16002)
		(layer "In11.Cu")
		(net "M_L_CPU0_SA_DQS_DN<9>")
	)
	(segment
		(start 429.049434 -239.882934)
		(end 429.902874 -239.029494)
		(width 0.16002)
		(layer "In11.Cu")
		(net "M_L_CPU0_SA_DQS_DN<9>")
	)
	(segment
		(start 395.835632 -247.814084)
		(end 395.859254 -247.814084)
		(width 0.09525)
		(layer "In11.Cu")
		(net "M_L_CPU0_SA_DQS_DN<9>")
	)
	(segment
		(start 432.913282 -240.258092)
		(end 433.073302 -240.098072)
		(width 0.16002)
		(layer "In11.Cu")
		(net "M_L_CPU0_SA_DQS_DN<9>")
	)
	(segment
		(start 417.5252 -240.098072)
		(end 417.5252 -239.53597)
		(width 0.16002)
		(layer "In11.Cu")
		(net "M_L_CPU0_SA_DQS_DN<9>")
	)
	(segment
		(start 449.813934 -239.25911)
		(end 450.088 -238.985044)
		(width 0.16002)
		(layer "In11.Cu")
		(net "M_L_CPU0_SA_DQS_DN<9>")
	)
	(arc
		(start 389.136382 -247.239282)
		(mid 389.32485 -247.289959)
		(end 389.513318 -247.239282)
		(width 0.09525)
		(layer "In11.Cu")
		(net "M_L_CPU0_SA_DQS_DN<9>")
	)
	(arc
		(start 386.31622 -247.239282)
		(mid 386.499995 -247.290054)
		(end 386.685028 -247.244108)
		(width 0.09525)
		(layer "In11.Cu")
		(net "M_L_CPU0_SA_DQS_DN<9>")
	)
	(arc
		(start 389.513318 -247.239282)
		(mid 389.79475 -247.163527)
		(end 390.076182 -247.239282)
		(width 0.09525)
		(layer "In11.Cu")
		(net "M_L_CPU0_SA_DQS_DN<9>")
	)
	(arc
		(start 388.20471 -247.244108)
		(mid 388.389742 -247.290022)
		(end 388.573518 -247.239282)
		(width 0.09525)
		(layer "In11.Cu")
		(net "M_L_CPU0_SA_DQS_DN<9>")
	)
	(arc
		(start 390.076182 -247.239282)
		(mid 390.259957 -247.290054)
		(end 390.44499 -247.244108)
		(width 0.09525)
		(layer "In11.Cu")
		(net "M_L_CPU0_SA_DQS_DN<9>")
	)
	(arc
		(start 387.264656 -247.244108)
		(mid 387.449688 -247.290022)
		(end 387.633464 -247.239282)
		(width 0.09525)
		(layer "In11.Cu")
		(net "M_L_CPU0_SA_DQS_DN<9>")
	)
	(arc
		(start 391.95756 -247.239282)
		(mid 392.138347 -247.290369)
		(end 392.321288 -247.247664)
		(width 0.09525)
		(layer "In11.Cu")
		(net "M_L_CPU0_SA_DQS_DN<9>")
	)
	(arc
		(start 387.633464 -247.239282)
		(mid 387.914896 -247.163527)
		(end 388.196328 -247.239282)
		(width 0.09525)
		(layer "In11.Cu")
		(net "M_L_CPU0_SA_DQS_DN<9>")
	)
	(arc
		(start 388.573518 -247.239282)
		(mid 388.85495 -247.163527)
		(end 389.136382 -247.239282)
		(width 0.09525)
		(layer "In11.Cu")
		(net "M_L_CPU0_SA_DQS_DN<9>")
	)
	(arc
		(start 391.024618 -247.244108)
		(mid 391.20965 -247.290022)
		(end 391.393426 -247.239282)
		(width 0.09525)
		(layer "In11.Cu")
		(net "M_L_CPU0_SA_DQS_DN<9>")
	)
	(arc
		(start 392.897106 -247.239282)
		(mid 392.987633 -247.276908)
		(end 393.084812 -247.289828)
		(width 0.09525)
		(layer "In11.Cu")
		(net "M_L_CPU0_SA_DQS_DN<9>")
	)
	(arc
		(start 391.416794 -247.22582)
		(mid 391.688895 -247.163142)
		(end 391.95756 -247.239282)
		(width 0.09525)
		(layer "In11.Cu")
		(net "M_L_CPU0_SA_DQS_DN<9>")
	)
	(arc
		(start 392.335766 -247.239282)
		(mid 392.601853 -247.163737)
		(end 392.871706 -247.22455)
		(width 0.09525)
		(layer "In11.Cu")
		(net "M_L_CPU0_SA_DQS_DN<9>")
	)
	(arc
		(start 390.453372 -247.239282)
		(mid 390.734804 -247.163527)
		(end 391.016236 -247.239282)
		(width 0.09525)
		(layer "In11.Cu")
		(net "M_L_CPU0_SA_DQS_DN<9>")
	)
	(arc
		(start 386.69341 -247.239282)
		(mid 386.974842 -247.163527)
		(end 387.256274 -247.239282)
		(width 0.09525)
		(layer "In11.Cu")
		(net "M_L_CPU0_SA_DQS_DN<9>")
	)
	(arc
		(start 385.81965 -247.206262)
		(mid 386.071791 -247.164692)
		(end 386.31622 -247.239282)
		(width 0.09525)
		(layer "In11.Cu")
		(net "M_L_CPU0_SA_DQS_DN<9>")
	)
	(segment
		(start 385.098036 -242.320064)
		(end 385.564888 -242.054126)
		(width 0.12954)
		(layer "F.Cu")
		(net "M_L_CPU0_SA_DQS_DN<8>")
	)
	(segment
		(start 403.117304 -241.052604)
		(end 403.36597 -240.803938)
		(width 0.16002)
		(layer "In11.Cu")
		(net "M_L_CPU0_SA_DQS_DN<8>")
	)
	(segment
		(start 422.35882 -229.6795)
		(end 423.181272 -229.6795)
		(width 0.16002)
		(layer "In11.Cu")
		(net "M_L_CPU0_SA_DQS_DN<8>")
	)
	(segment
		(start 403.36597 -240.577878)
		(end 403.061932 -240.27384)
		(width 0.16002)
		(layer "In11.Cu")
		(net "M_L_CPU0_SA_DQS_DN<8>")
	)
	(segment
		(start 387.256274 -242.379246)
		(end 387.264656 -242.384072)
		(width 0.09525)
		(layer "In11.Cu")
		(net "M_L_CPU0_SA_DQS_DN<8>")
	)
	(segment
		(start 391.016236 -242.379246)
		(end 391.024618 -242.384072)
		(width 0.09525)
		(layer "In11.Cu")
		(net "M_L_CPU0_SA_DQS_DN<8>")
	)
	(segment
		(start 391.393426 -242.379246)
		(end 391.40384 -242.37315)
		(width 0.09525)
		(layer "In11.Cu")
		(net "M_L_CPU0_SA_DQS_DN<8>")
	)
	(segment
		(start 447.252598 -230.05796)
		(end 447.401442 -229.909116)
		(width 0.16002)
		(layer "In11.Cu")
		(net "M_L_CPU0_SA_DQS_DN<8>")
	)
	(segment
		(start 385.718812 -242.319556)
		(end 385.81965 -242.346226)
		(width 0.09525)
		(layer "In11.Cu")
		(net "M_L_CPU0_SA_DQS_DN<8>")
	)
	(segment
		(start 385.564888 -242.054126)
		(end 385.718812 -242.319556)
		(width 0.09525)
		(layer "In11.Cu")
		(net "M_L_CPU0_SA_DQS_DN<8>")
	)
	(segment
		(start 420.508938 -230.908098)
		(end 420.884096 -230.53294)
		(width 0.16002)
		(layer "In11.Cu")
		(net "M_L_CPU0_SA_DQS_DN<8>")
	)
	(segment
		(start 413.961326 -230.53294)
		(end 414.814766 -229.6795)
		(width 0.16002)
		(layer "In11.Cu")
		(net "M_L_CPU0_SA_DQS_DN<8>")
	)
	(segment
		(start 416.67303 -230.00081)
		(end 417.010088 -229.663752)
		(width 0.16002)
		(layer "In11.Cu")
		(net "M_L_CPU0_SA_DQS_DN<8>")
	)
	(segment
		(start 403.963632 -239.37214)
		(end 404.26767 -239.676178)
		(width 0.16002)
		(layer "In11.Cu")
		(net "M_L_CPU0_SA_DQS_DN<8>")
	)
	(segment
		(start 428.052992 -230.908098)
		(end 428.42815 -230.53294)
		(width 0.16002)
		(layer "In11.Cu")
		(net "M_L_CPU0_SA_DQS_DN<8>")
	)
	(segment
		(start 445.813434 -229.6795)
		(end 446.191894 -230.05796)
		(width 0.16002)
		(layer "In11.Cu")
		(net "M_L_CPU0_SA_DQS_DN<8>")
	)
	(segment
		(start 414.814766 -229.6795)
		(end 415.358834 -229.6795)
		(width 0.16002)
		(layer "In11.Cu")
		(net "M_L_CPU0_SA_DQS_DN<8>")
	)
	(segment
		(start 427.12132 -230.908098)
		(end 428.052992 -230.908098)
		(width 0.16002)
		(layer "In11.Cu")
		(net "M_L_CPU0_SA_DQS_DN<8>")
	)
	(segment
		(start 392.325352 -242.384072)
		(end 392.333734 -242.379246)
		(width 0.09525)
		(layer "In11.Cu")
		(net "M_L_CPU0_SA_DQS_DN<8>")
	)
	(segment
		(start 416.056826 -230.377492)
		(end 416.51301 -230.377492)
		(width 0.16002)
		(layer "In11.Cu")
		(net "M_L_CPU0_SA_DQS_DN<8>")
	)
	(segment
		(start 447.401442 -229.909116)
		(end 449.813934 -229.909116)
		(width 0.16002)
		(layer "In11.Cu")
		(net "M_L_CPU0_SA_DQS_DN<8>")
	)
	(segment
		(start 431.103786 -230.05796)
		(end 433.662328 -230.05796)
		(width 0.16002)
		(layer "In11.Cu")
		(net "M_L_CPU0_SA_DQS_DN<8>")
	)
	(segment
		(start 394.328396 -242.430554)
		(end 395.418818 -241.340132)
		(width 0.09525)
		(layer "In11.Cu")
		(net "M_L_CPU0_SA_DQS_DN<8>")
	)
	(segment
		(start 438.26938 -229.6795)
		(end 438.64784 -230.05796)
		(width 0.16002)
		(layer "In11.Cu")
		(net "M_L_CPU0_SA_DQS_DN<8>")
	)
	(segment
		(start 417.945824 -230.217472)
		(end 418.105844 -230.377492)
		(width 0.16002)
		(layer "In11.Cu")
		(net "M_L_CPU0_SA_DQS_DN<8>")
	)
	(segment
		(start 402.587206 -240.748566)
		(end 402.891244 -241.052604)
		(width 0.16002)
		(layer "In11.Cu")
		(net "M_L_CPU0_SA_DQS_DN<8>")
	)
	(segment
		(start 403.487128 -239.37214)
		(end 403.963632 -239.37214)
		(width 0.16002)
		(layer "In11.Cu")
		(net "M_L_CPU0_SA_DQS_DN<8>")
	)
	(segment
		(start 416.67303 -230.217472)
		(end 416.67303 -230.00081)
		(width 0.16002)
		(layer "In11.Cu")
		(net "M_L_CPU0_SA_DQS_DN<8>")
	)
	(segment
		(start 404.742396 -239.427512)
		(end 404.742396 -239.201452)
		(width 0.16002)
		(layer "In11.Cu")
		(net "M_L_CPU0_SA_DQS_DN<8>")
	)
	(segment
		(start 440.971178 -230.05796)
		(end 441.821316 -230.908098)
		(width 0.16002)
		(layer "In11.Cu")
		(net "M_L_CPU0_SA_DQS_DN<8>")
	)
	(segment
		(start 415.358834 -229.6795)
		(end 416.056826 -230.377492)
		(width 0.16002)
		(layer "In11.Cu")
		(net "M_L_CPU0_SA_DQS_DN<8>")
	)
	(segment
		(start 418.105844 -230.377492)
		(end 418.92474 -230.377492)
		(width 0.16002)
		(layer "In11.Cu")
		(net "M_L_CPU0_SA_DQS_DN<8>")
	)
	(segment
		(start 404.438358 -238.42091)
		(end 412.326328 -230.53294)
		(width 0.16002)
		(layer "In11.Cu")
		(net "M_L_CPU0_SA_DQS_DN<8>")
	)
	(segment
		(start 404.26767 -239.676178)
		(end 404.49373 -239.676178)
		(width 0.16002)
		(layer "In11.Cu")
		(net "M_L_CPU0_SA_DQS_DN<8>")
	)
	(segment
		(start 404.438358 -238.897414)
		(end 404.438358 -238.42091)
		(width 0.16002)
		(layer "In11.Cu")
		(net "M_L_CPU0_SA_DQS_DN<8>")
	)
	(segment
		(start 395.835632 -241.28095)
		(end 395.859254 -241.28095)
		(width 0.09525)
		(layer "In11.Cu")
		(net "M_L_CPU0_SA_DQS_DN<8>")
	)
	(segment
		(start 446.191894 -230.05796)
		(end 447.252598 -230.05796)
		(width 0.16002)
		(layer "In11.Cu")
		(net "M_L_CPU0_SA_DQS_DN<8>")
	)
	(segment
		(start 403.36597 -240.803938)
		(end 403.36597 -240.577878)
		(width 0.16002)
		(layer "In11.Cu")
		(net "M_L_CPU0_SA_DQS_DN<8>")
	)
	(segment
		(start 430.725326 -229.6795)
		(end 431.103786 -230.05796)
		(width 0.16002)
		(layer "In11.Cu")
		(net "M_L_CPU0_SA_DQS_DN<8>")
	)
	(segment
		(start 404.742396 -239.201452)
		(end 404.438358 -238.897414)
		(width 0.16002)
		(layer "In11.Cu")
		(net "M_L_CPU0_SA_DQS_DN<8>")
	)
	(segment
		(start 388.196328 -242.379246)
		(end 388.20471 -242.384072)
		(width 0.09525)
		(layer "In11.Cu")
		(net "M_L_CPU0_SA_DQS_DN<8>")
	)
	(segment
		(start 421.50538 -230.53294)
		(end 422.35882 -229.6795)
		(width 0.16002)
		(layer "In11.Cu")
		(net "M_L_CPU0_SA_DQS_DN<8>")
	)
	(segment
		(start 429.049434 -230.53294)
		(end 429.902874 -229.6795)
		(width 0.16002)
		(layer "In11.Cu")
		(net "M_L_CPU0_SA_DQS_DN<8>")
	)
	(segment
		(start 401.578318 -241.28095)
		(end 402.110702 -240.748566)
		(width 0.16002)
		(layer "In11.Cu")
		(net "M_L_CPU0_SA_DQS_DN<8>")
	)
	(segment
		(start 437.446928 -229.6795)
		(end 438.26938 -229.6795)
		(width 0.16002)
		(layer "In11.Cu")
		(net "M_L_CPU0_SA_DQS_DN<8>")
	)
	(segment
		(start 404.49373 -239.676178)
		(end 404.742396 -239.427512)
		(width 0.16002)
		(layer "In11.Cu")
		(net "M_L_CPU0_SA_DQS_DN<8>")
	)
	(segment
		(start 418.92474 -230.377492)
		(end 419.455346 -230.908098)
		(width 0.16002)
		(layer "In11.Cu")
		(net "M_L_CPU0_SA_DQS_DN<8>")
	)
	(segment
		(start 429.902874 -229.6795)
		(end 430.725326 -229.6795)
		(width 0.16002)
		(layer "In11.Cu")
		(net "M_L_CPU0_SA_DQS_DN<8>")
	)
	(segment
		(start 444.990982 -229.6795)
		(end 445.813434 -229.6795)
		(width 0.16002)
		(layer "In11.Cu")
		(net "M_L_CPU0_SA_DQS_DN<8>")
	)
	(segment
		(start 395.77645 -241.340132)
		(end 395.835632 -241.28095)
		(width 0.09525)
		(layer "In11.Cu")
		(net "M_L_CPU0_SA_DQS_DN<8>")
	)
	(segment
		(start 403.061932 -239.797336)
		(end 403.487128 -239.37214)
		(width 0.16002)
		(layer "In11.Cu")
		(net "M_L_CPU0_SA_DQS_DN<8>")
	)
	(segment
		(start 395.859254 -241.28095)
		(end 401.578318 -241.28095)
		(width 0.16002)
		(layer "In11.Cu")
		(net "M_L_CPU0_SA_DQS_DN<8>")
	)
	(segment
		(start 434.512466 -230.908098)
		(end 435.597046 -230.908098)
		(width 0.16002)
		(layer "In11.Cu")
		(net "M_L_CPU0_SA_DQS_DN<8>")
	)
	(segment
		(start 449.813934 -229.909116)
		(end 450.088 -229.63505)
		(width 0.16002)
		(layer "In11.Cu")
		(net "M_L_CPU0_SA_DQS_DN<8>")
	)
	(segment
		(start 444.137542 -230.53294)
		(end 444.990982 -229.6795)
		(width 0.16002)
		(layer "In11.Cu")
		(net "M_L_CPU0_SA_DQS_DN<8>")
	)
	(segment
		(start 426.271182 -230.05796)
		(end 427.12132 -230.908098)
		(width 0.16002)
		(layer "In11.Cu")
		(net "M_L_CPU0_SA_DQS_DN<8>")
	)
	(segment
		(start 443.516258 -230.53294)
		(end 444.137542 -230.53294)
		(width 0.16002)
		(layer "In11.Cu")
		(net "M_L_CPU0_SA_DQS_DN<8>")
	)
	(segment
		(start 416.51301 -230.377492)
		(end 416.67303 -230.217472)
		(width 0.16002)
		(layer "In11.Cu")
		(net "M_L_CPU0_SA_DQS_DN<8>")
	)
	(segment
		(start 417.010088 -229.663752)
		(end 417.608766 -229.663752)
		(width 0.16002)
		(layer "In11.Cu")
		(net "M_L_CPU0_SA_DQS_DN<8>")
	)
	(segment
		(start 393.084812 -242.430554)
		(end 394.328396 -242.430554)
		(width 0.09525)
		(layer "In11.Cu")
		(net "M_L_CPU0_SA_DQS_DN<8>")
	)
	(segment
		(start 443.1411 -230.908098)
		(end 443.516258 -230.53294)
		(width 0.16002)
		(layer "In11.Cu")
		(net "M_L_CPU0_SA_DQS_DN<8>")
	)
	(segment
		(start 392.88593 -242.37315)
		(end 392.896344 -242.379246)
		(width 0.09525)
		(layer "In11.Cu")
		(net "M_L_CPU0_SA_DQS_DN<8>")
	)
	(segment
		(start 412.326328 -230.53294)
		(end 413.961326 -230.53294)
		(width 0.16002)
		(layer "In11.Cu")
		(net "M_L_CPU0_SA_DQS_DN<8>")
	)
	(segment
		(start 386.685028 -242.384072)
		(end 386.69341 -242.379246)
		(width 0.09525)
		(layer "In11.Cu")
		(net "M_L_CPU0_SA_DQS_DN<8>")
	)
	(segment
		(start 441.821316 -230.908098)
		(end 443.1411 -230.908098)
		(width 0.16002)
		(layer "In11.Cu")
		(net "M_L_CPU0_SA_DQS_DN<8>")
	)
	(segment
		(start 419.455346 -230.908098)
		(end 420.508938 -230.908098)
		(width 0.16002)
		(layer "In11.Cu")
		(net "M_L_CPU0_SA_DQS_DN<8>")
	)
	(segment
		(start 395.418818 -241.340132)
		(end 395.77645 -241.340132)
		(width 0.09525)
		(layer "In11.Cu")
		(net "M_L_CPU0_SA_DQS_DN<8>")
	)
	(segment
		(start 433.662328 -230.05796)
		(end 434.512466 -230.908098)
		(width 0.16002)
		(layer "In11.Cu")
		(net "M_L_CPU0_SA_DQS_DN<8>")
	)
	(segment
		(start 436.593488 -230.53294)
		(end 437.446928 -229.6795)
		(width 0.16002)
		(layer "In11.Cu")
		(net "M_L_CPU0_SA_DQS_DN<8>")
	)
	(segment
		(start 417.608766 -229.663752)
		(end 417.945824 -230.00081)
		(width 0.16002)
		(layer "In11.Cu")
		(net "M_L_CPU0_SA_DQS_DN<8>")
	)
	(segment
		(start 428.42815 -230.53294)
		(end 429.049434 -230.53294)
		(width 0.16002)
		(layer "In11.Cu")
		(net "M_L_CPU0_SA_DQS_DN<8>")
	)
	(segment
		(start 423.181272 -229.6795)
		(end 423.559732 -230.05796)
		(width 0.16002)
		(layer "In11.Cu")
		(net "M_L_CPU0_SA_DQS_DN<8>")
	)
	(segment
		(start 402.891244 -241.052604)
		(end 403.117304 -241.052604)
		(width 0.16002)
		(layer "In11.Cu")
		(net "M_L_CPU0_SA_DQS_DN<8>")
	)
	(segment
		(start 435.597046 -230.908098)
		(end 435.972204 -230.53294)
		(width 0.16002)
		(layer "In11.Cu")
		(net "M_L_CPU0_SA_DQS_DN<8>")
	)
	(segment
		(start 402.110702 -240.748566)
		(end 402.587206 -240.748566)
		(width 0.16002)
		(layer "In11.Cu")
		(net "M_L_CPU0_SA_DQS_DN<8>")
	)
	(segment
		(start 420.884096 -230.53294)
		(end 421.50538 -230.53294)
		(width 0.16002)
		(layer "In11.Cu")
		(net "M_L_CPU0_SA_DQS_DN<8>")
	)
	(segment
		(start 390.44499 -242.384072)
		(end 390.453372 -242.379246)
		(width 0.09525)
		(layer "In11.Cu")
		(net "M_L_CPU0_SA_DQS_DN<8>")
	)
	(segment
		(start 423.559732 -230.05796)
		(end 426.271182 -230.05796)
		(width 0.16002)
		(layer "In11.Cu")
		(net "M_L_CPU0_SA_DQS_DN<8>")
	)
	(segment
		(start 438.64784 -230.05796)
		(end 440.971178 -230.05796)
		(width 0.16002)
		(layer "In11.Cu")
		(net "M_L_CPU0_SA_DQS_DN<8>")
	)
	(segment
		(start 435.972204 -230.53294)
		(end 436.593488 -230.53294)
		(width 0.16002)
		(layer "In11.Cu")
		(net "M_L_CPU0_SA_DQS_DN<8>")
	)
	(segment
		(start 403.061932 -240.27384)
		(end 403.061932 -239.797336)
		(width 0.16002)
		(layer "In11.Cu")
		(net "M_L_CPU0_SA_DQS_DN<8>")
	)
	(segment
		(start 417.945824 -230.00081)
		(end 417.945824 -230.217472)
		(width 0.16002)
		(layer "In11.Cu")
		(net "M_L_CPU0_SA_DQS_DN<8>")
	)
	(arc
		(start 388.20471 -242.384072)
		(mid 388.389742 -242.429986)
		(end 388.573518 -242.379246)
		(width 0.09525)
		(layer "In11.Cu")
		(net "M_L_CPU0_SA_DQS_DN<8>")
	)
	(arc
		(start 390.453372 -242.379246)
		(mid 390.734804 -242.303491)
		(end 391.016236 -242.379246)
		(width 0.09525)
		(layer "In11.Cu")
		(net "M_L_CPU0_SA_DQS_DN<8>")
	)
	(arc
		(start 386.69341 -242.379246)
		(mid 386.974842 -242.303491)
		(end 387.256274 -242.379246)
		(width 0.09525)
		(layer "In11.Cu")
		(net "M_L_CPU0_SA_DQS_DN<8>")
	)
	(arc
		(start 392.333734 -242.379246)
		(mid 392.609023 -242.303525)
		(end 392.88593 -242.37315)
		(width 0.09525)
		(layer "In11.Cu")
		(net "M_L_CPU0_SA_DQS_DN<8>")
	)
	(arc
		(start 392.896344 -242.379246)
		(mid 392.987187 -242.417365)
		(end 393.084812 -242.430554)
		(width 0.09525)
		(layer "In11.Cu")
		(net "M_L_CPU0_SA_DQS_DN<8>")
	)
	(arc
		(start 388.573518 -242.379246)
		(mid 388.85495 -242.303491)
		(end 389.136382 -242.379246)
		(width 0.09525)
		(layer "In11.Cu")
		(net "M_L_CPU0_SA_DQS_DN<8>")
	)
	(arc
		(start 390.076182 -242.379246)
		(mid 390.259957 -242.430018)
		(end 390.44499 -242.384072)
		(width 0.09525)
		(layer "In11.Cu")
		(net "M_L_CPU0_SA_DQS_DN<8>")
	)
	(arc
		(start 386.31622 -242.379246)
		(mid 386.499995 -242.430018)
		(end 386.685028 -242.384072)
		(width 0.09525)
		(layer "In11.Cu")
		(net "M_L_CPU0_SA_DQS_DN<8>")
	)
	(arc
		(start 385.81965 -242.346226)
		(mid 386.071791 -242.304656)
		(end 386.31622 -242.379246)
		(width 0.09525)
		(layer "In11.Cu")
		(net "M_L_CPU0_SA_DQS_DN<8>")
	)
	(arc
		(start 389.513318 -242.379246)
		(mid 389.79475 -242.303491)
		(end 390.076182 -242.379246)
		(width 0.09525)
		(layer "In11.Cu")
		(net "M_L_CPU0_SA_DQS_DN<8>")
	)
	(arc
		(start 391.40384 -242.37315)
		(mid 391.681002 -242.30335)
		(end 391.956544 -242.379246)
		(width 0.09525)
		(layer "In11.Cu")
		(net "M_L_CPU0_SA_DQS_DN<8>")
	)
	(arc
		(start 391.956544 -242.379246)
		(mid 392.140319 -242.430018)
		(end 392.325352 -242.384072)
		(width 0.09525)
		(layer "In11.Cu")
		(net "M_L_CPU0_SA_DQS_DN<8>")
	)
	(arc
		(start 389.136382 -242.379246)
		(mid 389.32485 -242.429923)
		(end 389.513318 -242.379246)
		(width 0.09525)
		(layer "In11.Cu")
		(net "M_L_CPU0_SA_DQS_DN<8>")
	)
	(arc
		(start 387.633464 -242.379246)
		(mid 387.914896 -242.303491)
		(end 388.196328 -242.379246)
		(width 0.09525)
		(layer "In11.Cu")
		(net "M_L_CPU0_SA_DQS_DN<8>")
	)
	(arc
		(start 391.024618 -242.384072)
		(mid 391.20965 -242.429986)
		(end 391.393426 -242.379246)
		(width 0.09525)
		(layer "In11.Cu")
		(net "M_L_CPU0_SA_DQS_DN<8>")
	)
	(arc
		(start 387.264656 -242.384072)
		(mid 387.449688 -242.429986)
		(end 387.633464 -242.379246)
		(width 0.09525)
		(layer "In11.Cu")
		(net "M_L_CPU0_SA_DQS_DN<8>")
	)
	(segment
		(start 385.098036 -237.460028)
		(end 385.564888 -237.19409)
		(width 0.12954)
		(layer "F.Cu")
		(net "M_L_CPU0_SA_DQS_DN<7>")
	)
	(segment
		(start 444.137542 -221.182946)
		(end 444.990982 -220.329506)
		(width 0.16002)
		(layer "In11.Cu")
		(net "M_L_CPU0_SA_DQS_DN<7>")
	)
	(segment
		(start 422.35882 -220.329506)
		(end 423.181272 -220.329506)
		(width 0.16002)
		(layer "In11.Cu")
		(net "M_L_CPU0_SA_DQS_DN<7>")
	)
	(segment
		(start 429.902874 -220.329506)
		(end 430.725326 -220.329506)
		(width 0.16002)
		(layer "In11.Cu")
		(net "M_L_CPU0_SA_DQS_DN<7>")
	)
	(segment
		(start 395.124178 -236.110272)
		(end 395.531086 -235.703364)
		(width 0.09525)
		(layer "In11.Cu")
		(net "M_L_CPU0_SA_DQS_DN<7>")
	)
	(segment
		(start 433.675028 -220.707966)
		(end 434.525166 -221.558104)
		(width 0.16002)
		(layer "In11.Cu")
		(net "M_L_CPU0_SA_DQS_DN<7>")
	)
	(segment
		(start 395.840458 -235.644182)
		(end 397.649446 -235.644182)
		(width 0.16002)
		(layer "In11.Cu")
		(net "M_L_CPU0_SA_DQS_DN<7>")
	)
	(segment
		(start 443.516258 -221.182946)
		(end 444.137542 -221.182946)
		(width 0.16002)
		(layer "In11.Cu")
		(net "M_L_CPU0_SA_DQS_DN<7>")
	)
	(segment
		(start 420.508938 -221.558104)
		(end 420.884096 -221.182946)
		(width 0.16002)
		(layer "In11.Cu")
		(net "M_L_CPU0_SA_DQS_DN<7>")
	)
	(segment
		(start 429.049434 -221.182946)
		(end 429.902874 -220.329506)
		(width 0.16002)
		(layer "In11.Cu")
		(net "M_L_CPU0_SA_DQS_DN<7>")
	)
	(segment
		(start 446.191894 -220.707966)
		(end 447.252598 -220.707966)
		(width 0.16002)
		(layer "In11.Cu")
		(net "M_L_CPU0_SA_DQS_DN<7>")
	)
	(segment
		(start 436.593488 -221.182946)
		(end 437.446928 -220.329506)
		(width 0.16002)
		(layer "In11.Cu")
		(net "M_L_CPU0_SA_DQS_DN<7>")
	)
	(segment
		(start 405.527256 -227.766372)
		(end 406.103836 -227.766372)
		(width 0.16002)
		(layer "In11.Cu")
		(net "M_L_CPU0_SA_DQS_DN<7>")
	)
	(segment
		(start 391.393426 -237.51921)
		(end 391.416794 -237.505748)
		(width 0.09525)
		(layer "In11.Cu")
		(net "M_L_CPU0_SA_DQS_DN<7>")
	)
	(segment
		(start 413.961326 -221.182946)
		(end 414.814766 -220.329506)
		(width 0.16002)
		(layer "In11.Cu")
		(net "M_L_CPU0_SA_DQS_DN<7>")
	)
	(segment
		(start 385.564888 -237.19409)
		(end 385.718812 -237.45952)
		(width 0.09525)
		(layer "In11.Cu")
		(net "M_L_CPU0_SA_DQS_DN<7>")
	)
	(segment
		(start 391.016236 -237.51921)
		(end 391.024618 -237.524036)
		(width 0.09525)
		(layer "In11.Cu")
		(net "M_L_CPU0_SA_DQS_DN<7>")
	)
	(segment
		(start 423.559732 -220.707966)
		(end 426.263054 -220.707966)
		(width 0.16002)
		(layer "In11.Cu")
		(net "M_L_CPU0_SA_DQS_DN<7>")
	)
	(segment
		(start 440.971178 -220.707966)
		(end 441.821316 -221.558104)
		(width 0.16002)
		(layer "In11.Cu")
		(net "M_L_CPU0_SA_DQS_DN<7>")
	)
	(segment
		(start 434.525166 -221.558104)
		(end 435.597046 -221.558104)
		(width 0.16002)
		(layer "In11.Cu")
		(net "M_L_CPU0_SA_DQS_DN<7>")
	)
	(segment
		(start 421.50538 -221.182946)
		(end 422.35882 -220.329506)
		(width 0.16002)
		(layer "In11.Cu")
		(net "M_L_CPU0_SA_DQS_DN<7>")
	)
	(segment
		(start 437.446928 -220.329506)
		(end 438.26938 -220.329506)
		(width 0.16002)
		(layer "In11.Cu")
		(net "M_L_CPU0_SA_DQS_DN<7>")
	)
	(segment
		(start 395.816836 -235.644182)
		(end 395.840458 -235.644182)
		(width 0.09525)
		(layer "In11.Cu")
		(net "M_L_CPU0_SA_DQS_DN<7>")
	)
	(segment
		(start 392.321288 -237.527592)
		(end 392.335766 -237.51921)
		(width 0.09525)
		(layer "In11.Cu")
		(net "M_L_CPU0_SA_DQS_DN<7>")
	)
	(segment
		(start 420.884096 -221.182946)
		(end 421.50538 -221.182946)
		(width 0.16002)
		(layer "In11.Cu")
		(net "M_L_CPU0_SA_DQS_DN<7>")
	)
	(segment
		(start 441.821316 -221.558104)
		(end 443.1411 -221.558104)
		(width 0.16002)
		(layer "In11.Cu")
		(net "M_L_CPU0_SA_DQS_DN<7>")
	)
	(segment
		(start 447.252598 -220.707966)
		(end 447.401442 -220.559122)
		(width 0.16002)
		(layer "In11.Cu")
		(net "M_L_CPU0_SA_DQS_DN<7>")
	)
	(segment
		(start 408.27452 -225.019108)
		(end 408.8511 -225.019108)
		(width 0.16002)
		(layer "In11.Cu")
		(net "M_L_CPU0_SA_DQS_DN<7>")
	)
	(segment
		(start 390.44499 -237.524036)
		(end 390.453372 -237.51921)
		(width 0.09525)
		(layer "In11.Cu")
		(net "M_L_CPU0_SA_DQS_DN<7>")
	)
	(segment
		(start 394.588238 -237.265972)
		(end 395.124178 -236.730032)
		(width 0.09525)
		(layer "In11.Cu")
		(net "M_L_CPU0_SA_DQS_DN<7>")
	)
	(segment
		(start 438.64784 -220.707966)
		(end 440.971178 -220.707966)
		(width 0.16002)
		(layer "In11.Cu")
		(net "M_L_CPU0_SA_DQS_DN<7>")
	)
	(segment
		(start 438.26938 -220.329506)
		(end 438.64784 -220.707966)
		(width 0.16002)
		(layer "In11.Cu")
		(net "M_L_CPU0_SA_DQS_DN<7>")
	)
	(segment
		(start 415.315654 -220.329506)
		(end 415.945828 -219.699332)
		(width 0.16002)
		(layer "In11.Cu")
		(net "M_L_CPU0_SA_DQS_DN<7>")
	)
	(segment
		(start 406.103836 -227.766372)
		(end 406.414224 -227.455984)
		(width 0.16002)
		(layer "In11.Cu")
		(net "M_L_CPU0_SA_DQS_DN<7>")
	)
	(segment
		(start 395.757654 -235.703364)
		(end 395.816836 -235.644182)
		(width 0.09525)
		(layer "In11.Cu")
		(net "M_L_CPU0_SA_DQS_DN<7>")
	)
	(segment
		(start 410.53512 -222.758508)
		(end 412.110682 -221.182946)
		(width 0.16002)
		(layer "In11.Cu")
		(net "M_L_CPU0_SA_DQS_DN<7>")
	)
	(segment
		(start 435.972204 -221.182946)
		(end 436.593488 -221.182946)
		(width 0.16002)
		(layer "In11.Cu")
		(net "M_L_CPU0_SA_DQS_DN<7>")
	)
	(segment
		(start 431.103786 -220.707966)
		(end 433.675028 -220.707966)
		(width 0.16002)
		(layer "In11.Cu")
		(net "M_L_CPU0_SA_DQS_DN<7>")
	)
	(segment
		(start 430.725326 -220.329506)
		(end 431.103786 -220.707966)
		(width 0.16002)
		(layer "In11.Cu")
		(net "M_L_CPU0_SA_DQS_DN<7>")
	)
	(segment
		(start 443.1411 -221.558104)
		(end 443.516258 -221.182946)
		(width 0.16002)
		(layer "In11.Cu")
		(net "M_L_CPU0_SA_DQS_DN<7>")
	)
	(segment
		(start 412.110682 -221.182946)
		(end 413.961326 -221.182946)
		(width 0.16002)
		(layer "In11.Cu")
		(net "M_L_CPU0_SA_DQS_DN<7>")
	)
	(segment
		(start 392.871706 -237.504478)
		(end 392.897106 -237.51921)
		(width 0.09525)
		(layer "In11.Cu")
		(net "M_L_CPU0_SA_DQS_DN<7>")
	)
	(segment
		(start 393.54633 -237.265972)
		(end 394.588238 -237.265972)
		(width 0.09525)
		(layer "In11.Cu")
		(net "M_L_CPU0_SA_DQS_DN<7>")
	)
	(segment
		(start 435.597046 -221.558104)
		(end 435.972204 -221.182946)
		(width 0.16002)
		(layer "In11.Cu")
		(net "M_L_CPU0_SA_DQS_DN<7>")
	)
	(segment
		(start 416.490912 -219.699332)
		(end 417.367212 -220.575632)
		(width 0.16002)
		(layer "In11.Cu")
		(net "M_L_CPU0_SA_DQS_DN<7>")
	)
	(segment
		(start 388.196328 -237.51921)
		(end 388.20471 -237.524036)
		(width 0.09525)
		(layer "In11.Cu")
		(net "M_L_CPU0_SA_DQS_DN<7>")
	)
	(segment
		(start 428.052992 -221.558104)
		(end 428.42815 -221.182946)
		(width 0.16002)
		(layer "In11.Cu")
		(net "M_L_CPU0_SA_DQS_DN<7>")
	)
	(segment
		(start 386.685028 -237.524036)
		(end 386.69341 -237.51921)
		(width 0.09525)
		(layer "In11.Cu")
		(net "M_L_CPU0_SA_DQS_DN<7>")
	)
	(segment
		(start 444.990982 -220.329506)
		(end 445.813434 -220.329506)
		(width 0.16002)
		(layer "In11.Cu")
		(net "M_L_CPU0_SA_DQS_DN<7>")
	)
	(segment
		(start 423.181272 -220.329506)
		(end 423.559732 -220.707966)
		(width 0.16002)
		(layer "In11.Cu")
		(net "M_L_CPU0_SA_DQS_DN<7>")
	)
	(segment
		(start 409.161488 -224.13214)
		(end 409.648152 -223.645476)
		(width 0.16002)
		(layer "In11.Cu")
		(net "M_L_CPU0_SA_DQS_DN<7>")
	)
	(segment
		(start 409.161488 -224.70872)
		(end 409.161488 -224.13214)
		(width 0.16002)
		(layer "In11.Cu")
		(net "M_L_CPU0_SA_DQS_DN<7>")
	)
	(segment
		(start 410.53512 -223.335088)
		(end 410.53512 -222.758508)
		(width 0.16002)
		(layer "In11.Cu")
		(net "M_L_CPU0_SA_DQS_DN<7>")
	)
	(segment
		(start 419.442138 -221.558104)
		(end 420.508938 -221.558104)
		(width 0.16002)
		(layer "In11.Cu")
		(net "M_L_CPU0_SA_DQS_DN<7>")
	)
	(segment
		(start 406.900888 -226.39274)
		(end 407.477468 -226.39274)
		(width 0.16002)
		(layer "In11.Cu")
		(net "M_L_CPU0_SA_DQS_DN<7>")
	)
	(segment
		(start 414.814766 -220.329506)
		(end 415.315654 -220.329506)
		(width 0.16002)
		(layer "In11.Cu")
		(net "M_L_CPU0_SA_DQS_DN<7>")
	)
	(segment
		(start 395.124178 -236.730032)
		(end 395.124178 -236.110272)
		(width 0.09525)
		(layer "In11.Cu")
		(net "M_L_CPU0_SA_DQS_DN<7>")
	)
	(segment
		(start 397.649446 -235.644182)
		(end 405.527256 -227.766372)
		(width 0.16002)
		(layer "In11.Cu")
		(net "M_L_CPU0_SA_DQS_DN<7>")
	)
	(segment
		(start 410.224732 -223.645476)
		(end 410.53512 -223.335088)
		(width 0.16002)
		(layer "In11.Cu")
		(net "M_L_CPU0_SA_DQS_DN<7>")
	)
	(segment
		(start 407.787856 -225.505772)
		(end 408.27452 -225.019108)
		(width 0.16002)
		(layer "In11.Cu")
		(net "M_L_CPU0_SA_DQS_DN<7>")
	)
	(segment
		(start 406.414224 -226.879404)
		(end 406.900888 -226.39274)
		(width 0.16002)
		(layer "In11.Cu")
		(net "M_L_CPU0_SA_DQS_DN<7>")
	)
	(segment
		(start 427.113192 -221.558104)
		(end 428.052992 -221.558104)
		(width 0.16002)
		(layer "In11.Cu")
		(net "M_L_CPU0_SA_DQS_DN<7>")
	)
	(segment
		(start 447.401442 -220.559122)
		(end 449.813934 -220.559122)
		(width 0.16002)
		(layer "In11.Cu")
		(net "M_L_CPU0_SA_DQS_DN<7>")
	)
	(segment
		(start 409.648152 -223.645476)
		(end 410.224732 -223.645476)
		(width 0.16002)
		(layer "In11.Cu")
		(net "M_L_CPU0_SA_DQS_DN<7>")
	)
	(segment
		(start 392.897106 -237.51921)
		(end 392.920982 -237.532926)
		(width 0.09525)
		(layer "In11.Cu")
		(net "M_L_CPU0_SA_DQS_DN<7>")
	)
	(segment
		(start 428.42815 -221.182946)
		(end 429.049434 -221.182946)
		(width 0.16002)
		(layer "In11.Cu")
		(net "M_L_CPU0_SA_DQS_DN<7>")
	)
	(segment
		(start 426.263054 -220.707966)
		(end 427.113192 -221.558104)
		(width 0.16002)
		(layer "In11.Cu")
		(net "M_L_CPU0_SA_DQS_DN<7>")
	)
	(segment
		(start 445.813434 -220.329506)
		(end 446.191894 -220.707966)
		(width 0.16002)
		(layer "In11.Cu")
		(net "M_L_CPU0_SA_DQS_DN<7>")
	)
	(segment
		(start 393.351512 -237.46079)
		(end 393.54633 -237.265972)
		(width 0.09525)
		(layer "In11.Cu")
		(net "M_L_CPU0_SA_DQS_DN<7>")
	)
	(segment
		(start 407.787856 -226.082352)
		(end 407.787856 -225.505772)
		(width 0.16002)
		(layer "In11.Cu")
		(net "M_L_CPU0_SA_DQS_DN<7>")
	)
	(segment
		(start 415.945828 -219.699332)
		(end 416.490912 -219.699332)
		(width 0.16002)
		(layer "In11.Cu")
		(net "M_L_CPU0_SA_DQS_DN<7>")
	)
	(segment
		(start 395.531086 -235.703364)
		(end 395.757654 -235.703364)
		(width 0.09525)
		(layer "In11.Cu")
		(net "M_L_CPU0_SA_DQS_DN<7>")
	)
	(segment
		(start 385.718812 -237.45952)
		(end 385.81965 -237.48619)
		(width 0.09525)
		(layer "In11.Cu")
		(net "M_L_CPU0_SA_DQS_DN<7>")
	)
	(segment
		(start 449.813934 -220.559122)
		(end 450.088 -220.285056)
		(width 0.16002)
		(layer "In11.Cu")
		(net "M_L_CPU0_SA_DQS_DN<7>")
	)
	(segment
		(start 418.459666 -220.575632)
		(end 419.442138 -221.558104)
		(width 0.16002)
		(layer "In11.Cu")
		(net "M_L_CPU0_SA_DQS_DN<7>")
	)
	(segment
		(start 408.8511 -225.019108)
		(end 409.161488 -224.70872)
		(width 0.16002)
		(layer "In11.Cu")
		(net "M_L_CPU0_SA_DQS_DN<7>")
	)
	(segment
		(start 407.477468 -226.39274)
		(end 407.787856 -226.082352)
		(width 0.16002)
		(layer "In11.Cu")
		(net "M_L_CPU0_SA_DQS_DN<7>")
	)
	(segment
		(start 406.414224 -227.455984)
		(end 406.414224 -226.879404)
		(width 0.16002)
		(layer "In11.Cu")
		(net "M_L_CPU0_SA_DQS_DN<7>")
	)
	(segment
		(start 387.256274 -237.51921)
		(end 387.264656 -237.524036)
		(width 0.09525)
		(layer "In11.Cu")
		(net "M_L_CPU0_SA_DQS_DN<7>")
	)
	(segment
		(start 417.367212 -220.575632)
		(end 418.459666 -220.575632)
		(width 0.16002)
		(layer "In11.Cu")
		(net "M_L_CPU0_SA_DQS_DN<7>")
	)
	(arc
		(start 386.69341 -237.51921)
		(mid 386.974842 -237.443455)
		(end 387.256274 -237.51921)
		(width 0.09525)
		(layer "In11.Cu")
		(net "M_L_CPU0_SA_DQS_DN<7>")
	)
	(arc
		(start 389.513318 -237.51921)
		(mid 389.79475 -237.443455)
		(end 390.076182 -237.51921)
		(width 0.09525)
		(layer "In11.Cu")
		(net "M_L_CPU0_SA_DQS_DN<7>")
	)
	(arc
		(start 389.136382 -237.51921)
		(mid 389.32485 -237.569887)
		(end 389.513318 -237.51921)
		(width 0.09525)
		(layer "In11.Cu")
		(net "M_L_CPU0_SA_DQS_DN<7>")
	)
	(arc
		(start 385.81965 -237.48619)
		(mid 386.071791 -237.44462)
		(end 386.31622 -237.51921)
		(width 0.09525)
		(layer "In11.Cu")
		(net "M_L_CPU0_SA_DQS_DN<7>")
	)
	(arc
		(start 391.95756 -237.51921)
		(mid 392.138347 -237.570297)
		(end 392.321288 -237.527592)
		(width 0.09525)
		(layer "In11.Cu")
		(net "M_L_CPU0_SA_DQS_DN<7>")
	)
	(arc
		(start 386.31622 -237.51921)
		(mid 386.499995 -237.569982)
		(end 386.685028 -237.524036)
		(width 0.09525)
		(layer "In11.Cu")
		(net "M_L_CPU0_SA_DQS_DN<7>")
	)
	(arc
		(start 387.264656 -237.524036)
		(mid 387.449688 -237.56995)
		(end 387.633464 -237.51921)
		(width 0.09525)
		(layer "In11.Cu")
		(net "M_L_CPU0_SA_DQS_DN<7>")
	)
	(arc
		(start 388.20471 -237.524036)
		(mid 388.389742 -237.56995)
		(end 388.573518 -237.51921)
		(width 0.09525)
		(layer "In11.Cu")
		(net "M_L_CPU0_SA_DQS_DN<7>")
	)
	(arc
		(start 387.633464 -237.51921)
		(mid 387.914896 -237.443455)
		(end 388.196328 -237.51921)
		(width 0.09525)
		(layer "In11.Cu")
		(net "M_L_CPU0_SA_DQS_DN<7>")
	)
	(arc
		(start 388.573518 -237.51921)
		(mid 388.85495 -237.443455)
		(end 389.136382 -237.51921)
		(width 0.09525)
		(layer "In11.Cu")
		(net "M_L_CPU0_SA_DQS_DN<7>")
	)
	(arc
		(start 391.416794 -237.505748)
		(mid 391.688895 -237.44307)
		(end 391.95756 -237.51921)
		(width 0.09525)
		(layer "In11.Cu")
		(net "M_L_CPU0_SA_DQS_DN<7>")
	)
	(arc
		(start 393.27455 -237.51921)
		(mid 393.314914 -237.49248)
		(end 393.351512 -237.46079)
		(width 0.09525)
		(layer "In11.Cu")
		(net "M_L_CPU0_SA_DQS_DN<7>")
	)
	(arc
		(start 390.076182 -237.51921)
		(mid 390.259957 -237.569982)
		(end 390.44499 -237.524036)
		(width 0.09525)
		(layer "In11.Cu")
		(net "M_L_CPU0_SA_DQS_DN<7>")
	)
	(arc
		(start 392.920982 -237.532926)
		(mid 393.099468 -237.570169)
		(end 393.27455 -237.51921)
		(width 0.09525)
		(layer "In11.Cu")
		(net "M_L_CPU0_SA_DQS_DN<7>")
	)
	(arc
		(start 390.453372 -237.51921)
		(mid 390.734804 -237.443455)
		(end 391.016236 -237.51921)
		(width 0.09525)
		(layer "In11.Cu")
		(net "M_L_CPU0_SA_DQS_DN<7>")
	)
	(arc
		(start 391.024618 -237.524036)
		(mid 391.20965 -237.56995)
		(end 391.393426 -237.51921)
		(width 0.09525)
		(layer "In11.Cu")
		(net "M_L_CPU0_SA_DQS_DN<7>")
	)
	(arc
		(start 392.335766 -237.51921)
		(mid 392.601853 -237.443665)
		(end 392.871706 -237.504478)
		(width 0.09525)
		(layer "In11.Cu")
		(net "M_L_CPU0_SA_DQS_DN<7>")
	)
	(segment
		(start 385.098036 -232.599992)
		(end 385.564888 -232.334054)
		(width 0.12954)
		(layer "F.Cu")
		(net "M_L_CPU0_SA_DQS_DN<6>")
	)
	(segment
		(start 402.826982 -221.370906)
		(end 402.826982 -221.144846)
		(width 0.16002)
		(layer "In11.Cu")
		(net "M_L_CPU0_SA_DQS_DN<6>")
	)
	(segment
		(start 428.42815 -211.832952)
		(end 429.049434 -211.832952)
		(width 0.16002)
		(layer "In11.Cu")
		(net "M_L_CPU0_SA_DQS_DN<6>")
	)
	(segment
		(start 435.597046 -212.20811)
		(end 435.972204 -211.832952)
		(width 0.16002)
		(layer "In11.Cu")
		(net "M_L_CPU0_SA_DQS_DN<6>")
	)
	(segment
		(start 403.563582 -220.081094)
		(end 403.727158 -220.24467)
		(width 0.16002)
		(layer "In11.Cu")
		(net "M_L_CPU0_SA_DQS_DN<6>")
	)
	(segment
		(start 428.052992 -212.20811)
		(end 428.42815 -211.832952)
		(width 0.16002)
		(layer "In11.Cu")
		(net "M_L_CPU0_SA_DQS_DN<6>")
	)
	(segment
		(start 392.897106 -232.659174)
		(end 392.920982 -232.67289)
		(width 0.09525)
		(layer "In11.Cu")
		(net "M_L_CPU0_SA_DQS_DN<6>")
	)
	(segment
		(start 400.867118 -222.301054)
		(end 401.713446 -221.454726)
		(width 0.16002)
		(layer "In11.Cu")
		(net "M_L_CPU0_SA_DQS_DN<6>")
	)
	(segment
		(start 421.50538 -211.832952)
		(end 422.35882 -210.979512)
		(width 0.16002)
		(layer "In11.Cu")
		(net "M_L_CPU0_SA_DQS_DN<6>")
	)
	(segment
		(start 387.256274 -232.659174)
		(end 387.264656 -232.664)
		(width 0.09525)
		(layer "In11.Cu")
		(net "M_L_CPU0_SA_DQS_DN<6>")
	)
	(segment
		(start 443.516258 -211.832952)
		(end 444.137542 -211.832952)
		(width 0.16002)
		(layer "In11.Cu")
		(net "M_L_CPU0_SA_DQS_DN<6>")
	)
	(segment
		(start 413.961326 -211.832952)
		(end 414.814766 -210.979512)
		(width 0.16002)
		(layer "In11.Cu")
		(net "M_L_CPU0_SA_DQS_DN<6>")
	)
	(segment
		(start 441.821316 -212.20811)
		(end 443.1411 -212.20811)
		(width 0.16002)
		(layer "In11.Cu")
		(net "M_L_CPU0_SA_DQS_DN<6>")
	)
	(segment
		(start 449.813934 -211.209128)
		(end 450.088 -210.935062)
		(width 0.16002)
		(layer "In11.Cu")
		(net "M_L_CPU0_SA_DQS_DN<6>")
	)
	(segment
		(start 419.536118 -212.20811)
		(end 420.508938 -212.20811)
		(width 0.16002)
		(layer "In11.Cu")
		(net "M_L_CPU0_SA_DQS_DN<6>")
	)
	(segment
		(start 405.41067 -218.234006)
		(end 405.41067 -217.757502)
		(width 0.16002)
		(layer "In11.Cu")
		(net "M_L_CPU0_SA_DQS_DN<6>")
	)
	(segment
		(start 404.037038 -219.607638)
		(end 404.037038 -219.131134)
		(width 0.16002)
		(layer "In11.Cu")
		(net "M_L_CPU0_SA_DQS_DN<6>")
	)
	(segment
		(start 405.41067 -217.757502)
		(end 411.33522 -211.832952)
		(width 0.16002)
		(layer "In11.Cu")
		(net "M_L_CPU0_SA_DQS_DN<6>")
	)
	(segment
		(start 423.559732 -211.357972)
		(end 426.257974 -211.357972)
		(width 0.16002)
		(layer "In11.Cu")
		(net "M_L_CPU0_SA_DQS_DN<6>")
	)
	(segment
		(start 391.393426 -232.659174)
		(end 391.416794 -232.645712)
		(width 0.09525)
		(layer "In11.Cu")
		(net "M_L_CPU0_SA_DQS_DN<6>")
	)
	(segment
		(start 402.663406 -220.98127)
		(end 402.663406 -220.504766)
		(width 0.16002)
		(layer "In11.Cu")
		(net "M_L_CPU0_SA_DQS_DN<6>")
	)
	(segment
		(start 395.41323 -229.901496)
		(end 395.429994 -229.884732)
		(width 0.09525)
		(layer "In11.Cu")
		(net "M_L_CPU0_SA_DQS_DN<6>")
	)
	(segment
		(start 423.181272 -210.979512)
		(end 423.559732 -211.357972)
		(width 0.16002)
		(layer "In11.Cu")
		(net "M_L_CPU0_SA_DQS_DN<6>")
	)
	(segment
		(start 434.529738 -212.20811)
		(end 435.597046 -212.20811)
		(width 0.16002)
		(layer "In11.Cu")
		(net "M_L_CPU0_SA_DQS_DN<6>")
	)
	(segment
		(start 445.813434 -210.979512)
		(end 446.191894 -211.357972)
		(width 0.16002)
		(layer "In11.Cu")
		(net "M_L_CPU0_SA_DQS_DN<6>")
	)
	(segment
		(start 401.713446 -221.454726)
		(end 402.18995 -221.454726)
		(width 0.16002)
		(layer "In11.Cu")
		(net "M_L_CPU0_SA_DQS_DN<6>")
	)
	(segment
		(start 427.108112 -212.20811)
		(end 428.052992 -212.20811)
		(width 0.16002)
		(layer "In11.Cu")
		(net "M_L_CPU0_SA_DQS_DN<6>")
	)
	(segment
		(start 444.137542 -211.832952)
		(end 444.990982 -210.979512)
		(width 0.16002)
		(layer "In11.Cu")
		(net "M_L_CPU0_SA_DQS_DN<6>")
	)
	(segment
		(start 404.200614 -219.997274)
		(end 404.200614 -219.771214)
		(width 0.16002)
		(layer "In11.Cu")
		(net "M_L_CPU0_SA_DQS_DN<6>")
	)
	(segment
		(start 404.200614 -219.771214)
		(end 404.037038 -219.607638)
		(width 0.16002)
		(layer "In11.Cu")
		(net "M_L_CPU0_SA_DQS_DN<6>")
	)
	(segment
		(start 430.725326 -210.979512)
		(end 431.103786 -211.357972)
		(width 0.16002)
		(layer "In11.Cu")
		(net "M_L_CPU0_SA_DQS_DN<6>")
	)
	(segment
		(start 431.103786 -211.357972)
		(end 433.6796 -211.357972)
		(width 0.16002)
		(layer "In11.Cu")
		(net "M_L_CPU0_SA_DQS_DN<6>")
	)
	(segment
		(start 443.1411 -212.20811)
		(end 443.516258 -211.832952)
		(width 0.16002)
		(layer "In11.Cu")
		(net "M_L_CPU0_SA_DQS_DN<6>")
	)
	(segment
		(start 402.663406 -220.504766)
		(end 403.087078 -220.081094)
		(width 0.16002)
		(layer "In11.Cu")
		(net "M_L_CPU0_SA_DQS_DN<6>")
	)
	(segment
		(start 385.718812 -232.599484)
		(end 385.81965 -232.626154)
		(width 0.09525)
		(layer "In11.Cu")
		(net "M_L_CPU0_SA_DQS_DN<6>")
	)
	(segment
		(start 437.446928 -210.979512)
		(end 438.26938 -210.979512)
		(width 0.16002)
		(layer "In11.Cu")
		(net "M_L_CPU0_SA_DQS_DN<6>")
	)
	(segment
		(start 402.18995 -221.454726)
		(end 402.353526 -221.618302)
		(width 0.16002)
		(layer "In11.Cu")
		(net "M_L_CPU0_SA_DQS_DN<6>")
	)
	(segment
		(start 429.049434 -211.832952)
		(end 429.902874 -210.979512)
		(width 0.16002)
		(layer "In11.Cu")
		(net "M_L_CPU0_SA_DQS_DN<6>")
	)
	(segment
		(start 436.593488 -211.832952)
		(end 437.446928 -210.979512)
		(width 0.16002)
		(layer "In11.Cu")
		(net "M_L_CPU0_SA_DQS_DN<6>")
	)
	(segment
		(start 405.32685 -218.871038)
		(end 405.574246 -218.623642)
		(width 0.16002)
		(layer "In11.Cu")
		(net "M_L_CPU0_SA_DQS_DN<6>")
	)
	(segment
		(start 420.884096 -211.832952)
		(end 421.50538 -211.832952)
		(width 0.16002)
		(layer "In11.Cu")
		(net "M_L_CPU0_SA_DQS_DN<6>")
	)
	(segment
		(start 440.971178 -211.357972)
		(end 441.821316 -212.20811)
		(width 0.16002)
		(layer "In11.Cu")
		(net "M_L_CPU0_SA_DQS_DN<6>")
	)
	(segment
		(start 388.196328 -232.659174)
		(end 388.20471 -232.664)
		(width 0.09525)
		(layer "In11.Cu")
		(net "M_L_CPU0_SA_DQS_DN<6>")
	)
	(segment
		(start 393.996418 -231.402128)
		(end 395.41323 -229.985316)
		(width 0.09525)
		(layer "In11.Cu")
		(net "M_L_CPU0_SA_DQS_DN<6>")
	)
	(segment
		(start 392.321288 -232.667556)
		(end 392.335766 -232.659174)
		(width 0.09525)
		(layer "In11.Cu")
		(net "M_L_CPU0_SA_DQS_DN<6>")
	)
	(segment
		(start 395.429994 -229.884732)
		(end 400.867118 -224.4471)
		(width 0.16002)
		(layer "In11.Cu")
		(net "M_L_CPU0_SA_DQS_DN<6>")
	)
	(segment
		(start 404.46071 -218.707462)
		(end 404.937214 -218.707462)
		(width 0.16002)
		(layer "In11.Cu")
		(net "M_L_CPU0_SA_DQS_DN<6>")
	)
	(segment
		(start 385.564888 -232.334054)
		(end 385.718812 -232.599484)
		(width 0.09525)
		(layer "In11.Cu")
		(net "M_L_CPU0_SA_DQS_DN<6>")
	)
	(segment
		(start 404.937214 -218.707462)
		(end 405.10079 -218.871038)
		(width 0.16002)
		(layer "In11.Cu")
		(net "M_L_CPU0_SA_DQS_DN<6>")
	)
	(segment
		(start 444.990982 -210.979512)
		(end 445.813434 -210.979512)
		(width 0.16002)
		(layer "In11.Cu")
		(net "M_L_CPU0_SA_DQS_DN<6>")
	)
	(segment
		(start 422.35882 -210.979512)
		(end 423.181272 -210.979512)
		(width 0.16002)
		(layer "In11.Cu")
		(net "M_L_CPU0_SA_DQS_DN<6>")
	)
	(segment
		(start 402.826982 -221.144846)
		(end 402.663406 -220.98127)
		(width 0.16002)
		(layer "In11.Cu")
		(net "M_L_CPU0_SA_DQS_DN<6>")
	)
	(segment
		(start 405.574246 -218.397582)
		(end 405.41067 -218.234006)
		(width 0.16002)
		(layer "In11.Cu")
		(net "M_L_CPU0_SA_DQS_DN<6>")
	)
	(segment
		(start 391.016236 -232.659174)
		(end 391.024618 -232.664)
		(width 0.09525)
		(layer "In11.Cu")
		(net "M_L_CPU0_SA_DQS_DN<6>")
	)
	(segment
		(start 447.401442 -211.209128)
		(end 449.813934 -211.209128)
		(width 0.16002)
		(layer "In11.Cu")
		(net "M_L_CPU0_SA_DQS_DN<6>")
	)
	(segment
		(start 393.996418 -231.955848)
		(end 393.996418 -231.402128)
		(width 0.09525)
		(layer "In11.Cu")
		(net "M_L_CPU0_SA_DQS_DN<6>")
	)
	(segment
		(start 435.972204 -211.832952)
		(end 436.593488 -211.832952)
		(width 0.16002)
		(layer "In11.Cu")
		(net "M_L_CPU0_SA_DQS_DN<6>")
	)
	(segment
		(start 395.41323 -229.985316)
		(end 395.41323 -229.901496)
		(width 0.09525)
		(layer "In11.Cu")
		(net "M_L_CPU0_SA_DQS_DN<6>")
	)
	(segment
		(start 420.508938 -212.20811)
		(end 420.884096 -211.832952)
		(width 0.16002)
		(layer "In11.Cu")
		(net "M_L_CPU0_SA_DQS_DN<6>")
	)
	(segment
		(start 405.574246 -218.623642)
		(end 405.574246 -218.397582)
		(width 0.16002)
		(layer "In11.Cu")
		(net "M_L_CPU0_SA_DQS_DN<6>")
	)
	(segment
		(start 411.33522 -211.832952)
		(end 413.961326 -211.832952)
		(width 0.16002)
		(layer "In11.Cu")
		(net "M_L_CPU0_SA_DQS_DN<6>")
	)
	(segment
		(start 392.871706 -232.644442)
		(end 392.897106 -232.659174)
		(width 0.09525)
		(layer "In11.Cu")
		(net "M_L_CPU0_SA_DQS_DN<6>")
	)
	(segment
		(start 404.037038 -219.131134)
		(end 404.46071 -218.707462)
		(width 0.16002)
		(layer "In11.Cu")
		(net "M_L_CPU0_SA_DQS_DN<6>")
	)
	(segment
		(start 393.351512 -232.600754)
		(end 393.996418 -231.955848)
		(width 0.09525)
		(layer "In11.Cu")
		(net "M_L_CPU0_SA_DQS_DN<6>")
	)
	(segment
		(start 429.902874 -210.979512)
		(end 430.725326 -210.979512)
		(width 0.16002)
		(layer "In11.Cu")
		(net "M_L_CPU0_SA_DQS_DN<6>")
	)
	(segment
		(start 400.867118 -224.4471)
		(end 400.867118 -222.301054)
		(width 0.16002)
		(layer "In11.Cu")
		(net "M_L_CPU0_SA_DQS_DN<6>")
	)
	(segment
		(start 405.10079 -218.871038)
		(end 405.32685 -218.871038)
		(width 0.16002)
		(layer "In11.Cu")
		(net "M_L_CPU0_SA_DQS_DN<6>")
	)
	(segment
		(start 402.579586 -221.618302)
		(end 402.826982 -221.370906)
		(width 0.16002)
		(layer "In11.Cu")
		(net "M_L_CPU0_SA_DQS_DN<6>")
	)
	(segment
		(start 447.252598 -211.357972)
		(end 447.401442 -211.209128)
		(width 0.16002)
		(layer "In11.Cu")
		(net "M_L_CPU0_SA_DQS_DN<6>")
	)
	(segment
		(start 415.875978 -211.218272)
		(end 418.54628 -211.218272)
		(width 0.16002)
		(layer "In11.Cu")
		(net "M_L_CPU0_SA_DQS_DN<6>")
	)
	(segment
		(start 438.26938 -210.979512)
		(end 438.64784 -211.357972)
		(width 0.16002)
		(layer "In11.Cu")
		(net "M_L_CPU0_SA_DQS_DN<6>")
	)
	(segment
		(start 433.6796 -211.357972)
		(end 434.529738 -212.20811)
		(width 0.16002)
		(layer "In11.Cu")
		(net "M_L_CPU0_SA_DQS_DN<6>")
	)
	(segment
		(start 390.44499 -232.664)
		(end 390.453372 -232.659174)
		(width 0.09525)
		(layer "In11.Cu")
		(net "M_L_CPU0_SA_DQS_DN<6>")
	)
	(segment
		(start 426.257974 -211.357972)
		(end 427.108112 -212.20811)
		(width 0.16002)
		(layer "In11.Cu")
		(net "M_L_CPU0_SA_DQS_DN<6>")
	)
	(segment
		(start 403.953218 -220.24467)
		(end 404.200614 -219.997274)
		(width 0.16002)
		(layer "In11.Cu")
		(net "M_L_CPU0_SA_DQS_DN<6>")
	)
	(segment
		(start 438.64784 -211.357972)
		(end 440.971178 -211.357972)
		(width 0.16002)
		(layer "In11.Cu")
		(net "M_L_CPU0_SA_DQS_DN<6>")
	)
	(segment
		(start 446.191894 -211.357972)
		(end 447.252598 -211.357972)
		(width 0.16002)
		(layer "In11.Cu")
		(net "M_L_CPU0_SA_DQS_DN<6>")
	)
	(segment
		(start 386.685028 -232.664)
		(end 386.69341 -232.659174)
		(width 0.09525)
		(layer "In11.Cu")
		(net "M_L_CPU0_SA_DQS_DN<6>")
	)
	(segment
		(start 415.637218 -210.979512)
		(end 415.875978 -211.218272)
		(width 0.16002)
		(layer "In11.Cu")
		(net "M_L_CPU0_SA_DQS_DN<6>")
	)
	(segment
		(start 403.087078 -220.081094)
		(end 403.563582 -220.081094)
		(width 0.16002)
		(layer "In11.Cu")
		(net "M_L_CPU0_SA_DQS_DN<6>")
	)
	(segment
		(start 402.353526 -221.618302)
		(end 402.579586 -221.618302)
		(width 0.16002)
		(layer "In11.Cu")
		(net "M_L_CPU0_SA_DQS_DN<6>")
	)
	(segment
		(start 403.727158 -220.24467)
		(end 403.953218 -220.24467)
		(width 0.16002)
		(layer "In11.Cu")
		(net "M_L_CPU0_SA_DQS_DN<6>")
	)
	(segment
		(start 418.54628 -211.218272)
		(end 419.536118 -212.20811)
		(width 0.16002)
		(layer "In11.Cu")
		(net "M_L_CPU0_SA_DQS_DN<6>")
	)
	(segment
		(start 414.814766 -210.979512)
		(end 415.637218 -210.979512)
		(width 0.16002)
		(layer "In11.Cu")
		(net "M_L_CPU0_SA_DQS_DN<6>")
	)
	(arc
		(start 390.453372 -232.659174)
		(mid 390.734804 -232.583419)
		(end 391.016236 -232.659174)
		(width 0.09525)
		(layer "In11.Cu")
		(net "M_L_CPU0_SA_DQS_DN<6>")
	)
	(arc
		(start 390.076182 -232.659174)
		(mid 390.259957 -232.709946)
		(end 390.44499 -232.664)
		(width 0.09525)
		(layer "In11.Cu")
		(net "M_L_CPU0_SA_DQS_DN<6>")
	)
	(arc
		(start 386.31622 -232.659174)
		(mid 386.499995 -232.709946)
		(end 386.685028 -232.664)
		(width 0.09525)
		(layer "In11.Cu")
		(net "M_L_CPU0_SA_DQS_DN<6>")
	)
	(arc
		(start 388.20471 -232.664)
		(mid 388.389742 -232.709914)
		(end 388.573518 -232.659174)
		(width 0.09525)
		(layer "In11.Cu")
		(net "M_L_CPU0_SA_DQS_DN<6>")
	)
	(arc
		(start 385.81965 -232.626154)
		(mid 386.071791 -232.584584)
		(end 386.31622 -232.659174)
		(width 0.09525)
		(layer "In11.Cu")
		(net "M_L_CPU0_SA_DQS_DN<6>")
	)
	(arc
		(start 392.920982 -232.67289)
		(mid 393.099468 -232.710133)
		(end 393.27455 -232.659174)
		(width 0.09525)
		(layer "In11.Cu")
		(net "M_L_CPU0_SA_DQS_DN<6>")
	)
	(arc
		(start 393.27455 -232.659174)
		(mid 393.314914 -232.632444)
		(end 393.351512 -232.600754)
		(width 0.09525)
		(layer "In11.Cu")
		(net "M_L_CPU0_SA_DQS_DN<6>")
	)
	(arc
		(start 391.024618 -232.664)
		(mid 391.20965 -232.709914)
		(end 391.393426 -232.659174)
		(width 0.09525)
		(layer "In11.Cu")
		(net "M_L_CPU0_SA_DQS_DN<6>")
	)
	(arc
		(start 389.136382 -232.659174)
		(mid 389.32485 -232.709851)
		(end 389.513318 -232.659174)
		(width 0.09525)
		(layer "In11.Cu")
		(net "M_L_CPU0_SA_DQS_DN<6>")
	)
	(arc
		(start 391.95756 -232.659174)
		(mid 392.138347 -232.710261)
		(end 392.321288 -232.667556)
		(width 0.09525)
		(layer "In11.Cu")
		(net "M_L_CPU0_SA_DQS_DN<6>")
	)
	(arc
		(start 391.416794 -232.645712)
		(mid 391.688895 -232.583034)
		(end 391.95756 -232.659174)
		(width 0.09525)
		(layer "In11.Cu")
		(net "M_L_CPU0_SA_DQS_DN<6>")
	)
	(arc
		(start 388.573518 -232.659174)
		(mid 388.85495 -232.583419)
		(end 389.136382 -232.659174)
		(width 0.09525)
		(layer "In11.Cu")
		(net "M_L_CPU0_SA_DQS_DN<6>")
	)
	(arc
		(start 389.513318 -232.659174)
		(mid 389.79475 -232.583419)
		(end 390.076182 -232.659174)
		(width 0.09525)
		(layer "In11.Cu")
		(net "M_L_CPU0_SA_DQS_DN<6>")
	)
	(arc
		(start 392.335766 -232.659174)
		(mid 392.601853 -232.583629)
		(end 392.871706 -232.644442)
		(width 0.09525)
		(layer "In11.Cu")
		(net "M_L_CPU0_SA_DQS_DN<6>")
	)
	(arc
		(start 387.633464 -232.659174)
		(mid 387.914896 -232.583419)
		(end 388.196328 -232.659174)
		(width 0.09525)
		(layer "In11.Cu")
		(net "M_L_CPU0_SA_DQS_DN<6>")
	)
	(arc
		(start 387.264656 -232.664)
		(mid 387.449688 -232.709914)
		(end 387.633464 -232.659174)
		(width 0.09525)
		(layer "In11.Cu")
		(net "M_L_CPU0_SA_DQS_DN<6>")
	)
	(arc
		(start 386.69341 -232.659174)
		(mid 386.974842 -232.583419)
		(end 387.256274 -232.659174)
		(width 0.09525)
		(layer "In11.Cu")
		(net "M_L_CPU0_SA_DQS_DN<6>")
	)
	(segment
		(start 385.098036 -227.74021)
		(end 385.564888 -227.474272)
		(width 0.12954)
		(layer "F.Cu")
		(net "M_L_CPU0_SA_DQS_DN<5>")
	)
	(segment
		(start 435.597046 -202.858116)
		(end 435.972204 -202.482958)
		(width 0.16002)
		(layer "In11.Cu")
		(net "M_L_CPU0_SA_DQS_DN<5>")
	)
	(segment
		(start 423.559732 -202.007978)
		(end 426.237146 -202.007978)
		(width 0.16002)
		(layer "In11.Cu")
		(net "M_L_CPU0_SA_DQS_DN<5>")
	)
	(segment
		(start 429.049434 -202.482958)
		(end 429.902874 -201.629518)
		(width 0.16002)
		(layer "In11.Cu")
		(net "M_L_CPU0_SA_DQS_DN<5>")
	)
	(segment
		(start 394.986764 -221.41561)
		(end 394.986764 -221.391988)
		(width 0.09525)
		(layer "In11.Cu")
		(net "M_L_CPU0_SA_DQS_DN<5>")
	)
	(segment
		(start 431.103786 -202.007978)
		(end 433.658772 -202.007978)
		(width 0.16002)
		(layer "In11.Cu")
		(net "M_L_CPU0_SA_DQS_DN<5>")
	)
	(segment
		(start 392.80338 -225.369374)
		(end 392.838178 -225.349308)
		(width 0.09525)
		(layer "In11.Cu")
		(net "M_L_CPU0_SA_DQS_DN<5>")
	)
	(segment
		(start 426.237146 -202.007978)
		(end 427.087284 -202.858116)
		(width 0.16002)
		(layer "In11.Cu")
		(net "M_L_CPU0_SA_DQS_DN<5>")
	)
	(segment
		(start 402.940266 -211.158074)
		(end 402.940266 -210.932268)
		(width 0.16002)
		(layer "In11.Cu")
		(net "M_L_CPU0_SA_DQS_DN<5>")
	)
	(segment
		(start 402.696934 -210.68919)
		(end 402.696934 -210.212432)
		(width 0.16002)
		(layer "In11.Cu")
		(net "M_L_CPU0_SA_DQS_DN<5>")
	)
	(segment
		(start 420.884096 -202.482958)
		(end 421.50538 -202.482958)
		(width 0.16002)
		(layer "In11.Cu")
		(net "M_L_CPU0_SA_DQS_DN<5>")
	)
	(segment
		(start 387.256274 -227.799392)
		(end 387.264656 -227.804218)
		(width 0.09525)
		(layer "In11.Cu")
		(net "M_L_CPU0_SA_DQS_DN<5>")
	)
	(segment
		(start 401.746974 -211.162392)
		(end 402.223478 -211.162392)
		(width 0.16002)
		(layer "In11.Cu")
		(net "M_L_CPU0_SA_DQS_DN<5>")
	)
	(segment
		(start 443.1411 -202.858116)
		(end 443.516258 -202.482958)
		(width 0.16002)
		(layer "In11.Cu")
		(net "M_L_CPU0_SA_DQS_DN<5>")
	)
	(segment
		(start 390.44499 -227.804218)
		(end 390.453372 -227.799392)
		(width 0.09525)
		(layer "In11.Cu")
		(net "M_L_CPU0_SA_DQS_DN<5>")
	)
	(segment
		(start 419.467538 -202.858116)
		(end 420.508938 -202.858116)
		(width 0.16002)
		(layer "In11.Cu")
		(net "M_L_CPU0_SA_DQS_DN<5>")
	)
	(segment
		(start 393.234418 -224.582228)
		(end 393.273788 -224.559368)
		(width 0.09525)
		(layer "In11.Cu")
		(net "M_L_CPU0_SA_DQS_DN<5>")
	)
	(segment
		(start 437.446928 -201.629518)
		(end 438.26938 -201.629518)
		(width 0.16002)
		(layer "In11.Cu")
		(net "M_L_CPU0_SA_DQS_DN<5>")
	)
	(segment
		(start 386.685028 -227.804218)
		(end 386.69341 -227.799392)
		(width 0.09525)
		(layer "In11.Cu")
		(net "M_L_CPU0_SA_DQS_DN<5>")
	)
	(segment
		(start 428.052992 -202.858116)
		(end 428.42815 -202.482958)
		(width 0.16002)
		(layer "In11.Cu")
		(net "M_L_CPU0_SA_DQS_DN<5>")
	)
	(segment
		(start 436.593488 -202.482958)
		(end 437.446928 -201.629518)
		(width 0.16002)
		(layer "In11.Cu")
		(net "M_L_CPU0_SA_DQS_DN<5>")
	)
	(segment
		(start 414.814766 -201.629518)
		(end 415.637218 -201.629518)
		(width 0.16002)
		(layer "In11.Cu")
		(net "M_L_CPU0_SA_DQS_DN<5>")
	)
	(segment
		(start 401.323302 -212.062822)
		(end 401.323302 -211.586064)
		(width 0.16002)
		(layer "In11.Cu")
		(net "M_L_CPU0_SA_DQS_DN<5>")
	)
	(segment
		(start 401.093178 -212.779102)
		(end 401.319238 -212.779102)
		(width 0.16002)
		(layer "In11.Cu")
		(net "M_L_CPU0_SA_DQS_DN<5>")
	)
	(segment
		(start 444.137542 -202.482958)
		(end 444.990982 -201.629518)
		(width 0.16002)
		(layer "In11.Cu")
		(net "M_L_CPU0_SA_DQS_DN<5>")
	)
	(segment
		(start 392.768328 -225.389948)
		(end 392.80338 -225.369374)
		(width 0.09525)
		(layer "In11.Cu")
		(net "M_L_CPU0_SA_DQS_DN<5>")
	)
	(segment
		(start 402.223478 -211.162392)
		(end 402.46681 -211.40547)
		(width 0.16002)
		(layer "In11.Cu")
		(net "M_L_CPU0_SA_DQS_DN<5>")
	)
	(segment
		(start 438.64784 -202.007978)
		(end 440.971178 -202.007978)
		(width 0.16002)
		(layer "In11.Cu")
		(net "M_L_CPU0_SA_DQS_DN<5>")
	)
	(segment
		(start 428.42815 -202.482958)
		(end 429.049434 -202.482958)
		(width 0.16002)
		(layer "In11.Cu")
		(net "M_L_CPU0_SA_DQS_DN<5>")
	)
	(segment
		(start 385.564888 -227.474272)
		(end 385.718812 -227.739702)
		(width 0.09525)
		(layer "In11.Cu")
		(net "M_L_CPU0_SA_DQS_DN<5>")
	)
	(segment
		(start 421.50538 -202.482958)
		(end 422.35882 -201.629518)
		(width 0.16002)
		(layer "In11.Cu")
		(net "M_L_CPU0_SA_DQS_DN<5>")
	)
	(segment
		(start 433.658772 -202.007978)
		(end 434.50891 -202.858116)
		(width 0.16002)
		(layer "In11.Cu")
		(net "M_L_CPU0_SA_DQS_DN<5>")
	)
	(segment
		(start 401.319238 -212.779102)
		(end 401.566634 -212.531706)
		(width 0.16002)
		(layer "In11.Cu")
		(net "M_L_CPU0_SA_DQS_DN<5>")
	)
	(segment
		(start 388.196328 -227.799392)
		(end 388.20471 -227.804218)
		(width 0.09525)
		(layer "In11.Cu")
		(net "M_L_CPU0_SA_DQS_DN<5>")
	)
	(segment
		(start 401.323302 -211.586064)
		(end 401.746974 -211.162392)
		(width 0.16002)
		(layer "In11.Cu")
		(net "M_L_CPU0_SA_DQS_DN<5>")
	)
	(segment
		(start 392.333734 -226.17938)
		(end 392.36396 -226.161854)
		(width 0.09525)
		(layer "In11.Cu")
		(net "M_L_CPU0_SA_DQS_DN<5>")
	)
	(segment
		(start 391.016236 -227.799392)
		(end 391.024618 -227.804218)
		(width 0.09525)
		(layer "In11.Cu")
		(net "M_L_CPU0_SA_DQS_DN<5>")
	)
	(segment
		(start 393.743434 -223.749362)
		(end 393.77493 -223.731074)
		(width 0.09525)
		(layer "In11.Cu")
		(net "M_L_CPU0_SA_DQS_DN<5>")
	)
	(segment
		(start 391.86358 -226.989386)
		(end 391.897362 -226.969828)
		(width 0.09525)
		(layer "In11.Cu")
		(net "M_L_CPU0_SA_DQS_DN<5>")
	)
	(segment
		(start 410.426408 -202.482958)
		(end 413.961326 -202.482958)
		(width 0.16002)
		(layer "In11.Cu")
		(net "M_L_CPU0_SA_DQS_DN<5>")
	)
	(segment
		(start 440.971178 -202.007978)
		(end 441.821316 -202.858116)
		(width 0.16002)
		(layer "In11.Cu")
		(net "M_L_CPU0_SA_DQS_DN<5>")
	)
	(segment
		(start 394.040614 -223.092518)
		(end 395.045946 -222.087186)
		(width 0.09525)
		(layer "In11.Cu")
		(net "M_L_CPU0_SA_DQS_DN<5>")
	)
	(segment
		(start 447.337434 -201.859134)
		(end 449.813934 -201.859134)
		(width 0.16002)
		(layer "In11.Cu")
		(net "M_L_CPU0_SA_DQS_DN<5>")
	)
	(segment
		(start 393.273788 -224.559368)
		(end 393.304014 -224.541842)
		(width 0.09525)
		(layer "In11.Cu")
		(net "M_L_CPU0_SA_DQS_DN<5>")
	)
	(segment
		(start 441.821316 -202.858116)
		(end 443.1411 -202.858116)
		(width 0.16002)
		(layer "In11.Cu")
		(net "M_L_CPU0_SA_DQS_DN<5>")
	)
	(segment
		(start 447.18859 -202.007978)
		(end 447.337434 -201.859134)
		(width 0.16002)
		(layer "In11.Cu")
		(net "M_L_CPU0_SA_DQS_DN<5>")
	)
	(segment
		(start 449.813934 -201.859134)
		(end 450.088 -201.585068)
		(width 0.16002)
		(layer "In11.Cu")
		(net "M_L_CPU0_SA_DQS_DN<5>")
	)
	(segment
		(start 423.181272 -201.629518)
		(end 423.559732 -202.007978)
		(width 0.16002)
		(layer "In11.Cu")
		(net "M_L_CPU0_SA_DQS_DN<5>")
	)
	(segment
		(start 385.718812 -227.739702)
		(end 385.81965 -227.766372)
		(width 0.09525)
		(layer "In11.Cu")
		(net "M_L_CPU0_SA_DQS_DN<5>")
	)
	(segment
		(start 446.191894 -202.007978)
		(end 447.18859 -202.007978)
		(width 0.16002)
		(layer "In11.Cu")
		(net "M_L_CPU0_SA_DQS_DN<5>")
	)
	(segment
		(start 445.813434 -201.629518)
		(end 446.191894 -202.007978)
		(width 0.16002)
		(layer "In11.Cu")
		(net "M_L_CPU0_SA_DQS_DN<5>")
	)
	(segment
		(start 418.401754 -201.792332)
		(end 419.467538 -202.858116)
		(width 0.16002)
		(layer "In11.Cu")
		(net "M_L_CPU0_SA_DQS_DN<5>")
	)
	(segment
		(start 395.045946 -221.474792)
		(end 394.986764 -221.41561)
		(width 0.09525)
		(layer "In11.Cu")
		(net "M_L_CPU0_SA_DQS_DN<5>")
	)
	(segment
		(start 394.986764 -217.922602)
		(end 400.373342 -212.536024)
		(width 0.16002)
		(layer "In11.Cu")
		(net "M_L_CPU0_SA_DQS_DN<5>")
	)
	(segment
		(start 420.508938 -202.858116)
		(end 420.884096 -202.482958)
		(width 0.16002)
		(layer "In11.Cu")
		(net "M_L_CPU0_SA_DQS_DN<5>")
	)
	(segment
		(start 427.087284 -202.858116)
		(end 428.052992 -202.858116)
		(width 0.16002)
		(layer "In11.Cu")
		(net "M_L_CPU0_SA_DQS_DN<5>")
	)
	(segment
		(start 400.373342 -212.536024)
		(end 400.849846 -212.536024)
		(width 0.16002)
		(layer "In11.Cu")
		(net "M_L_CPU0_SA_DQS_DN<5>")
	)
	(segment
		(start 413.961326 -202.482958)
		(end 414.814766 -201.629518)
		(width 0.16002)
		(layer "In11.Cu")
		(net "M_L_CPU0_SA_DQS_DN<5>")
	)
	(segment
		(start 393.705334 -223.77146)
		(end 393.743434 -223.749362)
		(width 0.09525)
		(layer "In11.Cu")
		(net "M_L_CPU0_SA_DQS_DN<5>")
	)
	(segment
		(start 415.800032 -201.792332)
		(end 418.401754 -201.792332)
		(width 0.16002)
		(layer "In11.Cu")
		(net "M_L_CPU0_SA_DQS_DN<5>")
	)
	(segment
		(start 430.725326 -201.629518)
		(end 431.103786 -202.007978)
		(width 0.16002)
		(layer "In11.Cu")
		(net "M_L_CPU0_SA_DQS_DN<5>")
	)
	(segment
		(start 401.566634 -212.531706)
		(end 401.566634 -212.3059)
		(width 0.16002)
		(layer "In11.Cu")
		(net "M_L_CPU0_SA_DQS_DN<5>")
	)
	(segment
		(start 394.986764 -221.391988)
		(end 394.986764 -217.922602)
		(width 0.16002)
		(layer "In11.Cu")
		(net "M_L_CPU0_SA_DQS_DN<5>")
	)
	(segment
		(start 391.82548 -227.011484)
		(end 391.86358 -226.989386)
		(width 0.09525)
		(layer "In11.Cu")
		(net "M_L_CPU0_SA_DQS_DN<5>")
	)
	(segment
		(start 392.295634 -226.201478)
		(end 392.333734 -226.17938)
		(width 0.09525)
		(layer "In11.Cu")
		(net "M_L_CPU0_SA_DQS_DN<5>")
	)
	(segment
		(start 400.849846 -212.536024)
		(end 401.093178 -212.779102)
		(width 0.16002)
		(layer "In11.Cu")
		(net "M_L_CPU0_SA_DQS_DN<5>")
	)
	(segment
		(start 438.26938 -201.629518)
		(end 438.64784 -202.007978)
		(width 0.16002)
		(layer "In11.Cu")
		(net "M_L_CPU0_SA_DQS_DN<5>")
	)
	(segment
		(start 391.393426 -227.799392)
		(end 391.427208 -227.779834)
		(width 0.09525)
		(layer "In11.Cu")
		(net "M_L_CPU0_SA_DQS_DN<5>")
	)
	(segment
		(start 401.566634 -212.3059)
		(end 401.323302 -212.062822)
		(width 0.16002)
		(layer "In11.Cu")
		(net "M_L_CPU0_SA_DQS_DN<5>")
	)
	(segment
		(start 395.045946 -222.087186)
		(end 395.045946 -221.474792)
		(width 0.09525)
		(layer "In11.Cu")
		(net "M_L_CPU0_SA_DQS_DN<5>")
	)
	(segment
		(start 444.990982 -201.629518)
		(end 445.813434 -201.629518)
		(width 0.16002)
		(layer "In11.Cu")
		(net "M_L_CPU0_SA_DQS_DN<5>")
	)
	(segment
		(start 402.69287 -211.40547)
		(end 402.940266 -211.158074)
		(width 0.16002)
		(layer "In11.Cu")
		(net "M_L_CPU0_SA_DQS_DN<5>")
	)
	(segment
		(start 429.902874 -201.629518)
		(end 430.725326 -201.629518)
		(width 0.16002)
		(layer "In11.Cu")
		(net "M_L_CPU0_SA_DQS_DN<5>")
	)
	(segment
		(start 435.972204 -202.482958)
		(end 436.593488 -202.482958)
		(width 0.16002)
		(layer "In11.Cu")
		(net "M_L_CPU0_SA_DQS_DN<5>")
	)
	(segment
		(start 422.35882 -201.629518)
		(end 423.181272 -201.629518)
		(width 0.16002)
		(layer "In11.Cu")
		(net "M_L_CPU0_SA_DQS_DN<5>")
	)
	(segment
		(start 415.637218 -201.629518)
		(end 415.800032 -201.792332)
		(width 0.16002)
		(layer "In11.Cu")
		(net "M_L_CPU0_SA_DQS_DN<5>")
	)
	(segment
		(start 402.696934 -210.212432)
		(end 410.426408 -202.482958)
		(width 0.16002)
		(layer "In11.Cu")
		(net "M_L_CPU0_SA_DQS_DN<5>")
	)
	(segment
		(start 443.516258 -202.482958)
		(end 444.137542 -202.482958)
		(width 0.16002)
		(layer "In11.Cu")
		(net "M_L_CPU0_SA_DQS_DN<5>")
	)
	(segment
		(start 402.940266 -210.932268)
		(end 402.696934 -210.68919)
		(width 0.16002)
		(layer "In11.Cu")
		(net "M_L_CPU0_SA_DQS_DN<5>")
	)
	(segment
		(start 402.46681 -211.40547)
		(end 402.69287 -211.40547)
		(width 0.16002)
		(layer "In11.Cu")
		(net "M_L_CPU0_SA_DQS_DN<5>")
	)
	(segment
		(start 434.50891 -202.858116)
		(end 435.597046 -202.858116)
		(width 0.16002)
		(layer "In11.Cu")
		(net "M_L_CPU0_SA_DQS_DN<5>")
	)
	(arc
		(start 390.453372 -227.799392)
		(mid 390.734804 -227.723637)
		(end 391.016236 -227.799392)
		(width 0.09525)
		(layer "In11.Cu")
		(net "M_L_CPU0_SA_DQS_DN<5>")
	)
	(arc
		(start 393.77493 -223.731074)
		(mid 393.890728 -223.59668)
		(end 393.93241 -223.424242)
		(width 0.09525)
		(layer "In11.Cu")
		(net "M_L_CPU0_SA_DQS_DN<5>")
	)
	(arc
		(start 392.05281 -226.664266)
		(mid 392.117207 -226.40296)
		(end 392.295634 -226.201478)
		(width 0.09525)
		(layer "In11.Cu")
		(net "M_L_CPU0_SA_DQS_DN<5>")
	)
	(arc
		(start 388.573518 -227.799392)
		(mid 388.85495 -227.723637)
		(end 389.136382 -227.799392)
		(width 0.09525)
		(layer "In11.Cu")
		(net "M_L_CPU0_SA_DQS_DN<5>")
	)
	(arc
		(start 388.20471 -227.804218)
		(mid 388.389742 -227.850132)
		(end 388.573518 -227.799392)
		(width 0.09525)
		(layer "In11.Cu")
		(net "M_L_CPU0_SA_DQS_DN<5>")
	)
	(arc
		(start 387.264656 -227.804218)
		(mid 387.449688 -227.850132)
		(end 387.633464 -227.799392)
		(width 0.09525)
		(layer "In11.Cu")
		(net "M_L_CPU0_SA_DQS_DN<5>")
	)
	(arc
		(start 392.52271 -225.85426)
		(mid 392.587957 -225.591657)
		(end 392.768328 -225.389948)
		(width 0.09525)
		(layer "In11.Cu")
		(net "M_L_CPU0_SA_DQS_DN<5>")
	)
	(arc
		(start 391.024618 -227.804218)
		(mid 391.20965 -227.850132)
		(end 391.393426 -227.799392)
		(width 0.09525)
		(layer "In11.Cu")
		(net "M_L_CPU0_SA_DQS_DN<5>")
	)
	(arc
		(start 389.136382 -227.799392)
		(mid 389.32485 -227.850069)
		(end 389.513318 -227.799392)
		(width 0.09525)
		(layer "In11.Cu")
		(net "M_L_CPU0_SA_DQS_DN<5>")
	)
	(arc
		(start 393.46251 -224.234248)
		(mid 393.526907 -223.972942)
		(end 393.705334 -223.77146)
		(width 0.09525)
		(layer "In11.Cu")
		(net "M_L_CPU0_SA_DQS_DN<5>")
	)
	(arc
		(start 386.69341 -227.799392)
		(mid 386.974842 -227.723637)
		(end 387.256274 -227.799392)
		(width 0.09525)
		(layer "In11.Cu")
		(net "M_L_CPU0_SA_DQS_DN<5>")
	)
	(arc
		(start 385.81965 -227.766372)
		(mid 386.071791 -227.724802)
		(end 386.31622 -227.799392)
		(width 0.09525)
		(layer "In11.Cu")
		(net "M_L_CPU0_SA_DQS_DN<5>")
	)
	(arc
		(start 391.897362 -226.969828)
		(mid 392.011741 -226.835689)
		(end 392.05281 -226.664266)
		(width 0.09525)
		(layer "In11.Cu")
		(net "M_L_CPU0_SA_DQS_DN<5>")
	)
	(arc
		(start 386.31622 -227.799392)
		(mid 386.499995 -227.850164)
		(end 386.685028 -227.804218)
		(width 0.09525)
		(layer "In11.Cu")
		(net "M_L_CPU0_SA_DQS_DN<5>")
	)
	(arc
		(start 393.304014 -224.541842)
		(mid 393.420563 -224.407264)
		(end 393.46251 -224.234248)
		(width 0.09525)
		(layer "In11.Cu")
		(net "M_L_CPU0_SA_DQS_DN<5>")
	)
	(arc
		(start 391.582656 -227.474272)
		(mid 391.647053 -227.212966)
		(end 391.82548 -227.011484)
		(width 0.09525)
		(layer "In11.Cu")
		(net "M_L_CPU0_SA_DQS_DN<5>")
	)
	(arc
		(start 392.838178 -225.349308)
		(mid 392.951963 -225.215264)
		(end 392.992864 -225.044254)
		(width 0.09525)
		(layer "In11.Cu")
		(net "M_L_CPU0_SA_DQS_DN<5>")
	)
	(arc
		(start 387.633464 -227.799392)
		(mid 387.914896 -227.723637)
		(end 388.196328 -227.799392)
		(width 0.09525)
		(layer "In11.Cu")
		(net "M_L_CPU0_SA_DQS_DN<5>")
	)
	(arc
		(start 389.513318 -227.799392)
		(mid 389.79475 -227.723637)
		(end 390.076182 -227.799392)
		(width 0.09525)
		(layer "In11.Cu")
		(net "M_L_CPU0_SA_DQS_DN<5>")
	)
	(arc
		(start 392.992864 -225.044254)
		(mid 393.056899 -224.783577)
		(end 393.234418 -224.582228)
		(width 0.09525)
		(layer "In11.Cu")
		(net "M_L_CPU0_SA_DQS_DN<5>")
	)
	(arc
		(start 392.36396 -226.161854)
		(mid 392.480661 -226.027325)
		(end 392.52271 -225.85426)
		(width 0.09525)
		(layer "In11.Cu")
		(net "M_L_CPU0_SA_DQS_DN<5>")
	)
	(arc
		(start 390.076182 -227.799392)
		(mid 390.259957 -227.850164)
		(end 390.44499 -227.804218)
		(width 0.09525)
		(layer "In11.Cu")
		(net "M_L_CPU0_SA_DQS_DN<5>")
	)
	(arc
		(start 391.427208 -227.779834)
		(mid 391.541587 -227.645695)
		(end 391.582656 -227.474272)
		(width 0.09525)
		(layer "In11.Cu")
		(net "M_L_CPU0_SA_DQS_DN<5>")
	)
	(arc
		(start 393.93241 -223.424242)
		(mid 393.960144 -223.249779)
		(end 394.040614 -223.092518)
		(width 0.09525)
		(layer "In11.Cu")
		(net "M_L_CPU0_SA_DQS_DN<5>")
	)
	(segment
		(start 386.97789 -247.1801)
		(end 387.444742 -246.914162)
		(width 0.12954)
		(layer "F.Cu")
		(net "M_L_CPU0_SA_DQS_DN<4>")
	)
	(segment
		(start 425.765214 -238.562134)
		(end 427.909228 -238.562134)
		(width 0.16002)
		(layer "In11.Cu")
		(net "M_L_CPU0_SA_DQS_DN<4>")
	)
	(segment
		(start 430.445672 -238.066834)
		(end 430.800256 -237.71225)
		(width 0.16002)
		(layer "In11.Cu")
		(net "M_L_CPU0_SA_DQS_DN<4>")
	)
	(segment
		(start 420.692834 -238.889794)
		(end 421.667178 -238.889794)
		(width 0.16002)
		(layer "In11.Cu")
		(net "M_L_CPU0_SA_DQS_DN<4>")
	)
	(segment
		(start 420.365174 -238.562134)
		(end 420.692834 -238.889794)
		(width 0.16002)
		(layer "In11.Cu")
		(net "M_L_CPU0_SA_DQS_DN<4>")
	)
	(segment
		(start 445.888364 -237.71225)
		(end 447.547492 -237.71225)
		(width 0.16002)
		(layer "In11.Cu")
		(net "M_L_CPU0_SA_DQS_DN<4>")
	)
	(segment
		(start 437.989726 -238.066834)
		(end 438.34431 -237.71225)
		(width 0.16002)
		(layer "In11.Cu")
		(net "M_L_CPU0_SA_DQS_DN<4>")
	)
	(segment
		(start 390.44499 -246.584216)
		(end 390.453372 -246.589042)
		(width 0.09525)
		(layer "In11.Cu")
		(net "M_L_CPU0_SA_DQS_DN<4>")
	)
	(segment
		(start 395.641068 -246.97944)
		(end 395.66469 -246.97944)
		(width 0.09525)
		(layer "In11.Cu")
		(net "M_L_CPU0_SA_DQS_DN<4>")
	)
	(segment
		(start 435.453282 -238.562134)
		(end 435.780942 -238.889794)
		(width 0.16002)
		(layer "In11.Cu")
		(net "M_L_CPU0_SA_DQS_DN<4>")
	)
	(segment
		(start 447.547492 -237.71225)
		(end 448.121532 -238.28629)
		(width 0.16002)
		(layer "In11.Cu")
		(net "M_L_CPU0_SA_DQS_DN<4>")
	)
	(segment
		(start 453.914256 -238.711232)
		(end 454.188068 -238.985044)
		(width 0.16002)
		(layer "In11.Cu")
		(net "M_L_CPU0_SA_DQS_DN<4>")
	)
	(segment
		(start 387.444742 -246.914162)
		(end 387.290818 -246.648732)
		(width 0.09525)
		(layer "In11.Cu")
		(net "M_L_CPU0_SA_DQS_DN<4>")
	)
	(segment
		(start 440.853322 -238.562134)
		(end 442.997336 -238.562134)
		(width 0.16002)
		(layer "In11.Cu")
		(net "M_L_CPU0_SA_DQS_DN<4>")
	)
	(segment
		(start 394.096494 -246.920512)
		(end 395.58214 -246.920512)
		(width 0.09525)
		(layer "In11.Cu")
		(net "M_L_CPU0_SA_DQS_DN<4>")
	)
	(segment
		(start 427.909228 -238.562134)
		(end 428.236888 -238.889794)
		(width 0.16002)
		(layer "In11.Cu")
		(net "M_L_CPU0_SA_DQS_DN<4>")
	)
	(segment
		(start 435.780942 -238.889794)
		(end 436.755286 -238.889794)
		(width 0.16002)
		(layer "In11.Cu")
		(net "M_L_CPU0_SA_DQS_DN<4>")
	)
	(segment
		(start 393.713208 -246.537226)
		(end 394.096494 -246.920512)
		(width 0.09525)
		(layer "In11.Cu")
		(net "M_L_CPU0_SA_DQS_DN<4>")
	)
	(segment
		(start 445.1223 -238.066834)
		(end 445.53378 -238.066834)
		(width 0.16002)
		(layer "In11.Cu")
		(net "M_L_CPU0_SA_DQS_DN<4>")
	)
	(segment
		(start 392.33221 -246.589042)
		(end 392.350244 -246.599456)
		(width 0.09525)
		(layer "In11.Cu")
		(net "M_L_CPU0_SA_DQS_DN<4>")
	)
	(segment
		(start 415.941256 -238.066834)
		(end 417.72586 -238.066834)
		(width 0.16002)
		(layer "In11.Cu")
		(net "M_L_CPU0_SA_DQS_DN<4>")
	)
	(segment
		(start 440.003438 -237.71225)
		(end 440.853322 -238.562134)
		(width 0.16002)
		(layer "In11.Cu")
		(net "M_L_CPU0_SA_DQS_DN<4>")
	)
	(segment
		(start 417.72586 -238.066834)
		(end 418.22116 -238.562134)
		(width 0.16002)
		(layer "In11.Cu")
		(net "M_L_CPU0_SA_DQS_DN<4>")
	)
	(segment
		(start 438.34431 -237.71225)
		(end 440.003438 -237.71225)
		(width 0.16002)
		(layer "In11.Cu")
		(net "M_L_CPU0_SA_DQS_DN<4>")
	)
	(segment
		(start 395.58214 -246.920512)
		(end 395.641068 -246.97944)
		(width 0.09525)
		(layer "In11.Cu")
		(net "M_L_CPU0_SA_DQS_DN<4>")
	)
	(segment
		(start 437.578246 -238.066834)
		(end 437.989726 -238.066834)
		(width 0.16002)
		(layer "In11.Cu")
		(net "M_L_CPU0_SA_DQS_DN<4>")
	)
	(segment
		(start 424.91533 -237.71225)
		(end 425.765214 -238.562134)
		(width 0.16002)
		(layer "In11.Cu")
		(net "M_L_CPU0_SA_DQS_DN<4>")
	)
	(segment
		(start 422.901618 -238.066834)
		(end 423.256202 -237.71225)
		(width 0.16002)
		(layer "In11.Cu")
		(net "M_L_CPU0_SA_DQS_DN<4>")
	)
	(segment
		(start 451.161912 -238.905034)
		(end 451.826884 -238.905034)
		(width 0.16002)
		(layer "In11.Cu")
		(net "M_L_CPU0_SA_DQS_DN<4>")
	)
	(segment
		(start 396.016226 -246.97944)
		(end 396.687294 -246.308372)
		(width 0.16002)
		(layer "In11.Cu")
		(net "M_L_CPU0_SA_DQS_DN<4>")
	)
	(segment
		(start 452.732648 -238.838232)
		(end 453.212708 -238.838232)
		(width 0.16002)
		(layer "In11.Cu")
		(net "M_L_CPU0_SA_DQS_DN<4>")
	)
	(segment
		(start 421.667178 -238.889794)
		(end 422.490138 -238.066834)
		(width 0.16002)
		(layer "In11.Cu")
		(net "M_L_CPU0_SA_DQS_DN<4>")
	)
	(segment
		(start 387.290818 -246.648732)
		(end 387.314186 -246.561864)
		(width 0.09525)
		(layer "In11.Cu")
		(net "M_L_CPU0_SA_DQS_DN<4>")
	)
	(segment
		(start 430.800256 -237.71225)
		(end 432.459384 -237.71225)
		(width 0.16002)
		(layer "In11.Cu")
		(net "M_L_CPU0_SA_DQS_DN<4>")
	)
	(segment
		(start 452.020686 -238.711232)
		(end 452.605648 -238.711232)
		(width 0.16002)
		(layer "In11.Cu")
		(net "M_L_CPU0_SA_DQS_DN<4>")
	)
	(segment
		(start 388.196328 -246.589042)
		(end 388.20471 -246.584216)
		(width 0.09525)
		(layer "In11.Cu")
		(net "M_L_CPU0_SA_DQS_DN<4>")
	)
	(segment
		(start 432.459384 -237.71225)
		(end 433.309268 -238.562134)
		(width 0.16002)
		(layer "In11.Cu")
		(net "M_L_CPU0_SA_DQS_DN<4>")
	)
	(segment
		(start 448.121532 -238.28629)
		(end 450.543168 -238.28629)
		(width 0.16002)
		(layer "In11.Cu")
		(net "M_L_CPU0_SA_DQS_DN<4>")
	)
	(segment
		(start 422.490138 -238.066834)
		(end 422.901618 -238.066834)
		(width 0.16002)
		(layer "In11.Cu")
		(net "M_L_CPU0_SA_DQS_DN<4>")
	)
	(segment
		(start 451.826884 -238.905034)
		(end 452.020686 -238.711232)
		(width 0.16002)
		(layer "In11.Cu")
		(net "M_L_CPU0_SA_DQS_DN<4>")
	)
	(segment
		(start 429.211232 -238.889794)
		(end 430.034192 -238.066834)
		(width 0.16002)
		(layer "In11.Cu")
		(net "M_L_CPU0_SA_DQS_DN<4>")
	)
	(segment
		(start 436.755286 -238.889794)
		(end 437.578246 -238.066834)
		(width 0.16002)
		(layer "In11.Cu")
		(net "M_L_CPU0_SA_DQS_DN<4>")
	)
	(segment
		(start 396.687294 -246.308372)
		(end 406.043384 -246.308372)
		(width 0.16002)
		(layer "In11.Cu")
		(net "M_L_CPU0_SA_DQS_DN<4>")
	)
	(segment
		(start 443.324996 -238.889794)
		(end 444.29934 -238.889794)
		(width 0.16002)
		(layer "In11.Cu")
		(net "M_L_CPU0_SA_DQS_DN<4>")
	)
	(segment
		(start 391.937494 -246.599456)
		(end 391.955528 -246.589042)
		(width 0.09525)
		(layer "In11.Cu")
		(net "M_L_CPU0_SA_DQS_DN<4>")
	)
	(segment
		(start 406.043384 -246.308372)
		(end 412.169864 -240.181892)
		(width 0.16002)
		(layer "In11.Cu")
		(net "M_L_CPU0_SA_DQS_DN<4>")
	)
	(segment
		(start 450.543168 -238.28629)
		(end 451.161912 -238.905034)
		(width 0.16002)
		(layer "In11.Cu")
		(net "M_L_CPU0_SA_DQS_DN<4>")
	)
	(segment
		(start 442.997336 -238.562134)
		(end 443.324996 -238.889794)
		(width 0.16002)
		(layer "In11.Cu")
		(net "M_L_CPU0_SA_DQS_DN<4>")
	)
	(segment
		(start 423.256202 -237.71225)
		(end 424.91533 -237.71225)
		(width 0.16002)
		(layer "In11.Cu")
		(net "M_L_CPU0_SA_DQS_DN<4>")
	)
	(segment
		(start 452.605648 -238.711232)
		(end 452.732648 -238.838232)
		(width 0.16002)
		(layer "In11.Cu")
		(net "M_L_CPU0_SA_DQS_DN<4>")
	)
	(segment
		(start 395.66469 -246.97944)
		(end 396.016226 -246.97944)
		(width 0.16002)
		(layer "In11.Cu")
		(net "M_L_CPU0_SA_DQS_DN<4>")
	)
	(segment
		(start 412.169864 -240.181892)
		(end 413.826198 -240.181892)
		(width 0.16002)
		(layer "In11.Cu")
		(net "M_L_CPU0_SA_DQS_DN<4>")
	)
	(segment
		(start 391.016236 -246.589042)
		(end 391.024618 -246.584216)
		(width 0.09525)
		(layer "In11.Cu")
		(net "M_L_CPU0_SA_DQS_DN<4>")
	)
	(segment
		(start 430.034192 -238.066834)
		(end 430.445672 -238.066834)
		(width 0.16002)
		(layer "In11.Cu")
		(net "M_L_CPU0_SA_DQS_DN<4>")
	)
	(segment
		(start 445.53378 -238.066834)
		(end 445.888364 -237.71225)
		(width 0.16002)
		(layer "In11.Cu")
		(net "M_L_CPU0_SA_DQS_DN<4>")
	)
	(segment
		(start 391.955528 -246.589042)
		(end 391.96391 -246.584216)
		(width 0.09525)
		(layer "In11.Cu")
		(net "M_L_CPU0_SA_DQS_DN<4>")
	)
	(segment
		(start 453.212708 -238.838232)
		(end 453.339708 -238.711232)
		(width 0.16002)
		(layer "In11.Cu")
		(net "M_L_CPU0_SA_DQS_DN<4>")
	)
	(segment
		(start 413.826198 -240.181892)
		(end 415.941256 -238.066834)
		(width 0.16002)
		(layer "In11.Cu")
		(net "M_L_CPU0_SA_DQS_DN<4>")
	)
	(segment
		(start 428.236888 -238.889794)
		(end 429.211232 -238.889794)
		(width 0.16002)
		(layer "In11.Cu")
		(net "M_L_CPU0_SA_DQS_DN<4>")
	)
	(segment
		(start 433.309268 -238.562134)
		(end 435.453282 -238.562134)
		(width 0.16002)
		(layer "In11.Cu")
		(net "M_L_CPU0_SA_DQS_DN<4>")
	)
	(segment
		(start 453.339708 -238.711232)
		(end 453.914256 -238.711232)
		(width 0.16002)
		(layer "In11.Cu")
		(net "M_L_CPU0_SA_DQS_DN<4>")
	)
	(segment
		(start 418.22116 -238.562134)
		(end 420.365174 -238.562134)
		(width 0.16002)
		(layer "In11.Cu")
		(net "M_L_CPU0_SA_DQS_DN<4>")
	)
	(segment
		(start 393.085066 -246.537226)
		(end 393.713208 -246.537226)
		(width 0.09525)
		(layer "In11.Cu")
		(net "M_L_CPU0_SA_DQS_DN<4>")
	)
	(segment
		(start 444.29934 -238.889794)
		(end 445.1223 -238.066834)
		(width 0.16002)
		(layer "In11.Cu")
		(net "M_L_CPU0_SA_DQS_DN<4>")
	)
	(arc
		(start 390.453372 -246.589042)
		(mid 390.734804 -246.664797)
		(end 391.016236 -246.589042)
		(width 0.09525)
		(layer "In11.Cu")
		(net "M_L_CPU0_SA_DQS_DN<4>")
	)
	(arc
		(start 391.024618 -246.584216)
		(mid 391.20965 -246.538302)
		(end 391.393426 -246.589042)
		(width 0.09525)
		(layer "In11.Cu")
		(net "M_L_CPU0_SA_DQS_DN<4>")
	)
	(arc
		(start 391.96391 -246.584216)
		(mid 392.148688 -246.538423)
		(end 392.33221 -246.589042)
		(width 0.09525)
		(layer "In11.Cu")
		(net "M_L_CPU0_SA_DQS_DN<4>")
	)
	(arc
		(start 392.895836 -246.589042)
		(mid 392.987019 -246.550612)
		(end 393.085066 -246.537226)
		(width 0.09525)
		(layer "In11.Cu")
		(net "M_L_CPU0_SA_DQS_DN<4>")
	)
	(arc
		(start 389.136382 -246.589042)
		(mid 389.32485 -246.538365)
		(end 389.513318 -246.589042)
		(width 0.09525)
		(layer "In11.Cu")
		(net "M_L_CPU0_SA_DQS_DN<4>")
	)
	(arc
		(start 387.633464 -246.589042)
		(mid 387.914896 -246.664797)
		(end 388.196328 -246.589042)
		(width 0.09525)
		(layer "In11.Cu")
		(net "M_L_CPU0_SA_DQS_DN<4>")
	)
	(arc
		(start 387.314186 -246.561864)
		(mid 387.476868 -246.539732)
		(end 387.633464 -246.589042)
		(width 0.09525)
		(layer "In11.Cu")
		(net "M_L_CPU0_SA_DQS_DN<4>")
	)
	(arc
		(start 389.513318 -246.589042)
		(mid 389.79475 -246.664797)
		(end 390.076182 -246.589042)
		(width 0.09525)
		(layer "In11.Cu")
		(net "M_L_CPU0_SA_DQS_DN<4>")
	)
	(arc
		(start 391.393426 -246.589042)
		(mid 391.664114 -246.664694)
		(end 391.937494 -246.599456)
		(width 0.09525)
		(layer "In11.Cu")
		(net "M_L_CPU0_SA_DQS_DN<4>")
	)
	(arc
		(start 390.076182 -246.589042)
		(mid 390.259957 -246.53827)
		(end 390.44499 -246.584216)
		(width 0.09525)
		(layer "In11.Cu")
		(net "M_L_CPU0_SA_DQS_DN<4>")
	)
	(arc
		(start 388.573518 -246.589042)
		(mid 388.85495 -246.664797)
		(end 389.136382 -246.589042)
		(width 0.09525)
		(layer "In11.Cu")
		(net "M_L_CPU0_SA_DQS_DN<4>")
	)
	(arc
		(start 392.350244 -246.599456)
		(mid 392.624386 -246.665035)
		(end 392.895836 -246.589042)
		(width 0.09525)
		(layer "In11.Cu")
		(net "M_L_CPU0_SA_DQS_DN<4>")
	)
	(arc
		(start 388.20471 -246.584216)
		(mid 388.389742 -246.538302)
		(end 388.573518 -246.589042)
		(width 0.09525)
		(layer "In11.Cu")
		(net "M_L_CPU0_SA_DQS_DN<4>")
	)
	(segment
		(start 386.97789 -242.320064)
		(end 387.444742 -242.054126)
		(width 0.12954)
		(layer "F.Cu")
		(net "M_L_CPU0_SA_DQS_DN<3>")
	)
	(segment
		(start 401.343114 -240.71326)
		(end 412.516574 -229.5398)
		(width 0.16002)
		(layer "In11.Cu")
		(net "M_L_CPU0_SA_DQS_DN<3>")
	)
	(segment
		(start 421.667178 -229.5398)
		(end 422.490138 -228.71684)
		(width 0.16002)
		(layer "In11.Cu")
		(net "M_L_CPU0_SA_DQS_DN<3>")
	)
	(segment
		(start 422.490138 -228.71684)
		(end 422.901618 -228.71684)
		(width 0.16002)
		(layer "In11.Cu")
		(net "M_L_CPU0_SA_DQS_DN<3>")
	)
	(segment
		(start 425.765214 -229.21214)
		(end 427.909228 -229.21214)
		(width 0.16002)
		(layer "In11.Cu")
		(net "M_L_CPU0_SA_DQS_DN<3>")
	)
	(segment
		(start 435.780942 -229.5398)
		(end 436.755286 -229.5398)
		(width 0.16002)
		(layer "In11.Cu")
		(net "M_L_CPU0_SA_DQS_DN<3>")
	)
	(segment
		(start 412.516574 -229.5398)
		(end 414.123124 -229.5398)
		(width 0.16002)
		(layer "In11.Cu")
		(net "M_L_CPU0_SA_DQS_DN<3>")
	)
	(segment
		(start 420.365174 -229.21214)
		(end 420.692834 -229.5398)
		(width 0.16002)
		(layer "In11.Cu")
		(net "M_L_CPU0_SA_DQS_DN<3>")
	)
	(segment
		(start 453.230488 -229.488238)
		(end 453.357488 -229.361238)
		(width 0.16002)
		(layer "In11.Cu")
		(net "M_L_CPU0_SA_DQS_DN<3>")
	)
	(segment
		(start 395.279372 -240.947702)
		(end 395.572742 -240.654332)
		(width 0.09525)
		(layer "In11.Cu")
		(net "M_L_CPU0_SA_DQS_DN<3>")
	)
	(segment
		(start 393.256008 -241.719354)
		(end 393.290806 -241.73942)
		(width 0.09525)
		(layer "In11.Cu")
		(net "M_L_CPU0_SA_DQS_DN<3>")
	)
	(segment
		(start 445.53378 -228.71684)
		(end 445.888364 -228.362256)
		(width 0.16002)
		(layer "In11.Cu")
		(net "M_L_CPU0_SA_DQS_DN<3>")
	)
	(segment
		(start 453.914256 -229.361238)
		(end 454.188068 -229.63505)
		(width 0.16002)
		(layer "In11.Cu")
		(net "M_L_CPU0_SA_DQS_DN<3>")
	)
	(segment
		(start 430.445672 -228.71684)
		(end 430.800256 -228.362256)
		(width 0.16002)
		(layer "In11.Cu")
		(net "M_L_CPU0_SA_DQS_DN<3>")
	)
	(segment
		(start 390.44499 -241.72418)
		(end 390.453372 -241.729006)
		(width 0.09525)
		(layer "In11.Cu")
		(net "M_L_CPU0_SA_DQS_DN<3>")
	)
	(segment
		(start 427.909228 -229.21214)
		(end 428.236888 -229.5398)
		(width 0.16002)
		(layer "In11.Cu")
		(net "M_L_CPU0_SA_DQS_DN<3>")
	)
	(segment
		(start 387.290818 -241.788696)
		(end 387.314186 -241.701828)
		(width 0.09525)
		(layer "In11.Cu")
		(net "M_L_CPU0_SA_DQS_DN<3>")
	)
	(segment
		(start 450.543168 -228.936296)
		(end 451.161912 -229.55504)
		(width 0.16002)
		(layer "In11.Cu")
		(net "M_L_CPU0_SA_DQS_DN<3>")
	)
	(segment
		(start 437.989726 -228.71684)
		(end 438.34431 -228.362256)
		(width 0.16002)
		(layer "In11.Cu")
		(net "M_L_CPU0_SA_DQS_DN<3>")
	)
	(segment
		(start 414.946084 -228.71684)
		(end 415.357564 -228.71684)
		(width 0.16002)
		(layer "In11.Cu")
		(net "M_L_CPU0_SA_DQS_DN<3>")
	)
	(segment
		(start 393.949936 -241.640614)
		(end 394.642848 -240.947702)
		(width 0.09525)
		(layer "In11.Cu")
		(net "M_L_CPU0_SA_DQS_DN<3>")
	)
	(segment
		(start 388.196328 -241.729006)
		(end 388.20471 -241.72418)
		(width 0.09525)
		(layer "In11.Cu")
		(net "M_L_CPU0_SA_DQS_DN<3>")
	)
	(segment
		(start 391.955528 -241.729006)
		(end 391.96391 -241.72418)
		(width 0.09525)
		(layer "In11.Cu")
		(net "M_L_CPU0_SA_DQS_DN<3>")
	)
	(segment
		(start 395.776704 -240.654332)
		(end 395.835632 -240.71326)
		(width 0.09525)
		(layer "In11.Cu")
		(net "M_L_CPU0_SA_DQS_DN<3>")
	)
	(segment
		(start 452.750428 -229.488238)
		(end 453.230488 -229.488238)
		(width 0.16002)
		(layer "In11.Cu")
		(net "M_L_CPU0_SA_DQS_DN<3>")
	)
	(segment
		(start 430.034192 -228.71684)
		(end 430.445672 -228.71684)
		(width 0.16002)
		(layer "In11.Cu")
		(net "M_L_CPU0_SA_DQS_DN<3>")
	)
	(segment
		(start 436.755286 -229.5398)
		(end 437.578246 -228.71684)
		(width 0.16002)
		(layer "In11.Cu")
		(net "M_L_CPU0_SA_DQS_DN<3>")
	)
	(segment
		(start 448.121532 -228.936296)
		(end 450.543168 -228.936296)
		(width 0.16002)
		(layer "In11.Cu")
		(net "M_L_CPU0_SA_DQS_DN<3>")
	)
	(segment
		(start 451.161912 -229.55504)
		(end 451.826884 -229.55504)
		(width 0.16002)
		(layer "In11.Cu")
		(net "M_L_CPU0_SA_DQS_DN<3>")
	)
	(segment
		(start 415.357564 -228.71684)
		(end 415.712148 -228.362256)
		(width 0.16002)
		(layer "In11.Cu")
		(net "M_L_CPU0_SA_DQS_DN<3>")
	)
	(segment
		(start 432.459384 -228.362256)
		(end 433.309268 -229.21214)
		(width 0.16002)
		(layer "In11.Cu")
		(net "M_L_CPU0_SA_DQS_DN<3>")
	)
	(segment
		(start 452.020686 -229.361238)
		(end 452.623428 -229.361238)
		(width 0.16002)
		(layer "In11.Cu")
		(net "M_L_CPU0_SA_DQS_DN<3>")
	)
	(segment
		(start 394.642848 -240.947702)
		(end 395.279372 -240.947702)
		(width 0.09525)
		(layer "In11.Cu")
		(net "M_L_CPU0_SA_DQS_DN<3>")
	)
	(segment
		(start 442.997336 -229.21214)
		(end 443.324996 -229.5398)
		(width 0.16002)
		(layer "In11.Cu")
		(net "M_L_CPU0_SA_DQS_DN<3>")
	)
	(segment
		(start 435.453282 -229.21214)
		(end 435.780942 -229.5398)
		(width 0.16002)
		(layer "In11.Cu")
		(net "M_L_CPU0_SA_DQS_DN<3>")
	)
	(segment
		(start 392.33221 -241.729006)
		(end 392.350244 -241.73942)
		(width 0.09525)
		(layer "In11.Cu")
		(net "M_L_CPU0_SA_DQS_DN<3>")
	)
	(segment
		(start 433.309268 -229.21214)
		(end 435.453282 -229.21214)
		(width 0.16002)
		(layer "In11.Cu")
		(net "M_L_CPU0_SA_DQS_DN<3>")
	)
	(segment
		(start 423.256202 -228.362256)
		(end 424.91533 -228.362256)
		(width 0.16002)
		(layer "In11.Cu")
		(net "M_L_CPU0_SA_DQS_DN<3>")
	)
	(segment
		(start 395.835632 -240.71326)
		(end 395.859254 -240.71326)
		(width 0.09525)
		(layer "In11.Cu")
		(net "M_L_CPU0_SA_DQS_DN<3>")
	)
	(segment
		(start 417.371276 -228.362256)
		(end 418.22116 -229.21214)
		(width 0.16002)
		(layer "In11.Cu")
		(net "M_L_CPU0_SA_DQS_DN<3>")
	)
	(segment
		(start 418.22116 -229.21214)
		(end 420.365174 -229.21214)
		(width 0.16002)
		(layer "In11.Cu")
		(net "M_L_CPU0_SA_DQS_DN<3>")
	)
	(segment
		(start 387.444742 -242.054126)
		(end 387.290818 -241.788696)
		(width 0.09525)
		(layer "In11.Cu")
		(net "M_L_CPU0_SA_DQS_DN<3>")
	)
	(segment
		(start 391.016236 -241.729006)
		(end 391.024618 -241.72418)
		(width 0.09525)
		(layer "In11.Cu")
		(net "M_L_CPU0_SA_DQS_DN<3>")
	)
	(segment
		(start 420.692834 -229.5398)
		(end 421.667178 -229.5398)
		(width 0.16002)
		(layer "In11.Cu")
		(net "M_L_CPU0_SA_DQS_DN<3>")
	)
	(segment
		(start 452.623428 -229.361238)
		(end 452.750428 -229.488238)
		(width 0.16002)
		(layer "In11.Cu")
		(net "M_L_CPU0_SA_DQS_DN<3>")
	)
	(segment
		(start 429.211232 -229.5398)
		(end 430.034192 -228.71684)
		(width 0.16002)
		(layer "In11.Cu")
		(net "M_L_CPU0_SA_DQS_DN<3>")
	)
	(segment
		(start 414.123124 -229.5398)
		(end 414.946084 -228.71684)
		(width 0.16002)
		(layer "In11.Cu")
		(net "M_L_CPU0_SA_DQS_DN<3>")
	)
	(segment
		(start 445.888364 -228.362256)
		(end 447.547492 -228.362256)
		(width 0.16002)
		(layer "In11.Cu")
		(net "M_L_CPU0_SA_DQS_DN<3>")
	)
	(segment
		(start 428.236888 -229.5398)
		(end 429.211232 -229.5398)
		(width 0.16002)
		(layer "In11.Cu")
		(net "M_L_CPU0_SA_DQS_DN<3>")
	)
	(segment
		(start 445.1223 -228.71684)
		(end 445.53378 -228.71684)
		(width 0.16002)
		(layer "In11.Cu")
		(net "M_L_CPU0_SA_DQS_DN<3>")
	)
	(segment
		(start 437.578246 -228.71684)
		(end 437.989726 -228.71684)
		(width 0.16002)
		(layer "In11.Cu")
		(net "M_L_CPU0_SA_DQS_DN<3>")
	)
	(segment
		(start 395.572742 -240.654332)
		(end 395.776704 -240.654332)
		(width 0.09525)
		(layer "In11.Cu")
		(net "M_L_CPU0_SA_DQS_DN<3>")
	)
	(segment
		(start 440.853322 -229.21214)
		(end 442.997336 -229.21214)
		(width 0.16002)
		(layer "In11.Cu")
		(net "M_L_CPU0_SA_DQS_DN<3>")
	)
	(segment
		(start 395.859254 -240.71326)
		(end 401.343114 -240.71326)
		(width 0.16002)
		(layer "In11.Cu")
		(net "M_L_CPU0_SA_DQS_DN<3>")
	)
	(segment
		(start 424.91533 -228.362256)
		(end 425.765214 -229.21214)
		(width 0.16002)
		(layer "In11.Cu")
		(net "M_L_CPU0_SA_DQS_DN<3>")
	)
	(segment
		(start 391.937494 -241.73942)
		(end 391.955528 -241.729006)
		(width 0.09525)
		(layer "In11.Cu")
		(net "M_L_CPU0_SA_DQS_DN<3>")
	)
	(segment
		(start 430.800256 -228.362256)
		(end 432.459384 -228.362256)
		(width 0.16002)
		(layer "In11.Cu")
		(net "M_L_CPU0_SA_DQS_DN<3>")
	)
	(segment
		(start 415.712148 -228.362256)
		(end 417.371276 -228.362256)
		(width 0.16002)
		(layer "In11.Cu")
		(net "M_L_CPU0_SA_DQS_DN<3>")
	)
	(segment
		(start 422.901618 -228.71684)
		(end 423.256202 -228.362256)
		(width 0.16002)
		(layer "In11.Cu")
		(net "M_L_CPU0_SA_DQS_DN<3>")
	)
	(segment
		(start 438.34431 -228.362256)
		(end 440.003438 -228.362256)
		(width 0.16002)
		(layer "In11.Cu")
		(net "M_L_CPU0_SA_DQS_DN<3>")
	)
	(segment
		(start 440.003438 -228.362256)
		(end 440.853322 -229.21214)
		(width 0.16002)
		(layer "In11.Cu")
		(net "M_L_CPU0_SA_DQS_DN<3>")
	)
	(segment
		(start 447.547492 -228.362256)
		(end 448.121532 -228.936296)
		(width 0.16002)
		(layer "In11.Cu")
		(net "M_L_CPU0_SA_DQS_DN<3>")
	)
	(segment
		(start 451.826884 -229.55504)
		(end 452.020686 -229.361238)
		(width 0.16002)
		(layer "In11.Cu")
		(net "M_L_CPU0_SA_DQS_DN<3>")
	)
	(segment
		(start 453.357488 -229.361238)
		(end 453.914256 -229.361238)
		(width 0.16002)
		(layer "In11.Cu")
		(net "M_L_CPU0_SA_DQS_DN<3>")
	)
	(segment
		(start 443.324996 -229.5398)
		(end 444.29934 -229.5398)
		(width 0.16002)
		(layer "In11.Cu")
		(net "M_L_CPU0_SA_DQS_DN<3>")
	)
	(segment
		(start 444.29934 -229.5398)
		(end 445.1223 -228.71684)
		(width 0.16002)
		(layer "In11.Cu")
		(net "M_L_CPU0_SA_DQS_DN<3>")
	)
	(arc
		(start 390.076182 -241.729006)
		(mid 390.259957 -241.678234)
		(end 390.44499 -241.72418)
		(width 0.09525)
		(layer "In11.Cu")
		(net "M_L_CPU0_SA_DQS_DN<3>")
	)
	(arc
		(start 391.96391 -241.72418)
		(mid 392.148688 -241.678387)
		(end 392.33221 -241.729006)
		(width 0.09525)
		(layer "In11.Cu")
		(net "M_L_CPU0_SA_DQS_DN<3>")
	)
	(arc
		(start 387.314186 -241.701828)
		(mid 387.476868 -241.679696)
		(end 387.633464 -241.729006)
		(width 0.09525)
		(layer "In11.Cu")
		(net "M_L_CPU0_SA_DQS_DN<3>")
	)
	(arc
		(start 388.573518 -241.729006)
		(mid 388.85495 -241.804761)
		(end 389.136382 -241.729006)
		(width 0.09525)
		(layer "In11.Cu")
		(net "M_L_CPU0_SA_DQS_DN<3>")
	)
	(arc
		(start 392.350244 -241.73942)
		(mid 392.624386 -241.804999)
		(end 392.895836 -241.729006)
		(width 0.09525)
		(layer "In11.Cu")
		(net "M_L_CPU0_SA_DQS_DN<3>")
	)
	(arc
		(start 390.453372 -241.729006)
		(mid 390.734804 -241.804761)
		(end 391.016236 -241.729006)
		(width 0.09525)
		(layer "In11.Cu")
		(net "M_L_CPU0_SA_DQS_DN<3>")
	)
	(arc
		(start 393.290806 -241.73942)
		(mid 393.636622 -241.798539)
		(end 393.949936 -241.640614)
		(width 0.09525)
		(layer "In11.Cu")
		(net "M_L_CPU0_SA_DQS_DN<3>")
	)
	(arc
		(start 387.633464 -241.729006)
		(mid 387.914896 -241.804761)
		(end 388.196328 -241.729006)
		(width 0.09525)
		(layer "In11.Cu")
		(net "M_L_CPU0_SA_DQS_DN<3>")
	)
	(arc
		(start 392.895836 -241.729006)
		(mid 393.074696 -241.67821)
		(end 393.256008 -241.719354)
		(width 0.09525)
		(layer "In11.Cu")
		(net "M_L_CPU0_SA_DQS_DN<3>")
	)
	(arc
		(start 391.024618 -241.72418)
		(mid 391.20965 -241.678266)
		(end 391.393426 -241.729006)
		(width 0.09525)
		(layer "In11.Cu")
		(net "M_L_CPU0_SA_DQS_DN<3>")
	)
	(arc
		(start 389.513318 -241.729006)
		(mid 389.79475 -241.804761)
		(end 390.076182 -241.729006)
		(width 0.09525)
		(layer "In11.Cu")
		(net "M_L_CPU0_SA_DQS_DN<3>")
	)
	(arc
		(start 388.20471 -241.72418)
		(mid 388.389742 -241.678266)
		(end 388.573518 -241.729006)
		(width 0.09525)
		(layer "In11.Cu")
		(net "M_L_CPU0_SA_DQS_DN<3>")
	)
	(arc
		(start 391.393426 -241.729006)
		(mid 391.664114 -241.804658)
		(end 391.937494 -241.73942)
		(width 0.09525)
		(layer "In11.Cu")
		(net "M_L_CPU0_SA_DQS_DN<3>")
	)
	(arc
		(start 389.136382 -241.729006)
		(mid 389.32485 -241.678329)
		(end 389.513318 -241.729006)
		(width 0.09525)
		(layer "In11.Cu")
		(net "M_L_CPU0_SA_DQS_DN<3>")
	)
	(segment
		(start 386.97789 -237.460028)
		(end 387.444742 -237.19409)
		(width 0.12954)
		(layer "F.Cu")
		(net "M_L_CPU0_SA_DQS_DN<2>")
	)
	(segment
		(start 423.256202 -219.012262)
		(end 424.91533 -219.012262)
		(width 0.16002)
		(layer "In11.Cu")
		(net "M_L_CPU0_SA_DQS_DN<2>")
	)
	(segment
		(start 430.800256 -219.012262)
		(end 432.459384 -219.012262)
		(width 0.16002)
		(layer "In11.Cu")
		(net "M_L_CPU0_SA_DQS_DN<2>")
	)
	(segment
		(start 430.445672 -219.366846)
		(end 430.800256 -219.012262)
		(width 0.16002)
		(layer "In11.Cu")
		(net "M_L_CPU0_SA_DQS_DN<2>")
	)
	(segment
		(start 422.490138 -219.366846)
		(end 422.901618 -219.366846)
		(width 0.16002)
		(layer "In11.Cu")
		(net "M_L_CPU0_SA_DQS_DN<2>")
	)
	(segment
		(start 451.161912 -220.205046)
		(end 451.826884 -220.205046)
		(width 0.16002)
		(layer "In11.Cu")
		(net "M_L_CPU0_SA_DQS_DN<2>")
	)
	(segment
		(start 443.324996 -220.189806)
		(end 444.29934 -220.189806)
		(width 0.16002)
		(layer "In11.Cu")
		(net "M_L_CPU0_SA_DQS_DN<2>")
	)
	(segment
		(start 414.946084 -219.366846)
		(end 415.357564 -219.366846)
		(width 0.16002)
		(layer "In11.Cu")
		(net "M_L_CPU0_SA_DQS_DN<2>")
	)
	(segment
		(start 440.853322 -219.862146)
		(end 442.997336 -219.862146)
		(width 0.16002)
		(layer "In11.Cu")
		(net "M_L_CPU0_SA_DQS_DN<2>")
	)
	(segment
		(start 445.1223 -219.366846)
		(end 445.53378 -219.366846)
		(width 0.16002)
		(layer "In11.Cu")
		(net "M_L_CPU0_SA_DQS_DN<2>")
	)
	(segment
		(start 414.123124 -220.189806)
		(end 414.946084 -219.366846)
		(width 0.16002)
		(layer "In11.Cu")
		(net "M_L_CPU0_SA_DQS_DN<2>")
	)
	(segment
		(start 442.997336 -219.862146)
		(end 443.324996 -220.189806)
		(width 0.16002)
		(layer "In11.Cu")
		(net "M_L_CPU0_SA_DQS_DN<2>")
	)
	(segment
		(start 450.543168 -219.586302)
		(end 451.161912 -220.205046)
		(width 0.16002)
		(layer "In11.Cu")
		(net "M_L_CPU0_SA_DQS_DN<2>")
	)
	(segment
		(start 420.365174 -219.862146)
		(end 420.692834 -220.189806)
		(width 0.16002)
		(layer "In11.Cu")
		(net "M_L_CPU0_SA_DQS_DN<2>")
	)
	(segment
		(start 437.989726 -219.366846)
		(end 438.34431 -219.012262)
		(width 0.16002)
		(layer "In11.Cu")
		(net "M_L_CPU0_SA_DQS_DN<2>")
	)
	(segment
		(start 438.34431 -219.012262)
		(end 440.003438 -219.012262)
		(width 0.16002)
		(layer "In11.Cu")
		(net "M_L_CPU0_SA_DQS_DN<2>")
	)
	(segment
		(start 417.371276 -219.012262)
		(end 418.22116 -219.862146)
		(width 0.16002)
		(layer "In11.Cu")
		(net "M_L_CPU0_SA_DQS_DN<2>")
	)
	(segment
		(start 391.016236 -236.86897)
		(end 391.024618 -236.864144)
		(width 0.09525)
		(layer "In11.Cu")
		(net "M_L_CPU0_SA_DQS_DN<2>")
	)
	(segment
		(start 432.459384 -219.012262)
		(end 433.309268 -219.862146)
		(width 0.16002)
		(layer "In11.Cu")
		(net "M_L_CPU0_SA_DQS_DN<2>")
	)
	(segment
		(start 394.491972 -236.215682)
		(end 394.669772 -236.142022)
		(width 0.09525)
		(layer "In11.Cu")
		(net "M_L_CPU0_SA_DQS_DN<2>")
	)
	(segment
		(start 452.580248 -220.011244)
		(end 452.707248 -220.138244)
		(width 0.16002)
		(layer "In11.Cu")
		(net "M_L_CPU0_SA_DQS_DN<2>")
	)
	(segment
		(start 440.003438 -219.012262)
		(end 440.853322 -219.862146)
		(width 0.16002)
		(layer "In11.Cu")
		(net "M_L_CPU0_SA_DQS_DN<2>")
	)
	(segment
		(start 391.955528 -236.86897)
		(end 391.96391 -236.864144)
		(width 0.09525)
		(layer "In11.Cu")
		(net "M_L_CPU0_SA_DQS_DN<2>")
	)
	(segment
		(start 445.888364 -219.012262)
		(end 447.547492 -219.012262)
		(width 0.16002)
		(layer "In11.Cu")
		(net "M_L_CPU0_SA_DQS_DN<2>")
	)
	(segment
		(start 395.626336 -234.998514)
		(end 395.776704 -234.998514)
		(width 0.09525)
		(layer "In11.Cu")
		(net "M_L_CPU0_SA_DQS_DN<2>")
	)
	(segment
		(start 395.776704 -234.998514)
		(end 395.835632 -235.057442)
		(width 0.09525)
		(layer "In11.Cu")
		(net "M_L_CPU0_SA_DQS_DN<2>")
	)
	(segment
		(start 444.29934 -220.189806)
		(end 445.1223 -219.366846)
		(width 0.16002)
		(layer "In11.Cu")
		(net "M_L_CPU0_SA_DQS_DN<2>")
	)
	(segment
		(start 445.53378 -219.366846)
		(end 445.888364 -219.012262)
		(width 0.16002)
		(layer "In11.Cu")
		(net "M_L_CPU0_SA_DQS_DN<2>")
	)
	(segment
		(start 387.444742 -237.19409)
		(end 387.290818 -236.92866)
		(width 0.09525)
		(layer "In11.Cu")
		(net "M_L_CPU0_SA_DQS_DN<2>")
	)
	(segment
		(start 425.765214 -219.862146)
		(end 427.909228 -219.862146)
		(width 0.16002)
		(layer "In11.Cu")
		(net "M_L_CPU0_SA_DQS_DN<2>")
	)
	(segment
		(start 453.187308 -220.138244)
		(end 453.314308 -220.011244)
		(width 0.16002)
		(layer "In11.Cu")
		(net "M_L_CPU0_SA_DQS_DN<2>")
	)
	(segment
		(start 415.712148 -219.012262)
		(end 417.371276 -219.012262)
		(width 0.16002)
		(layer "In11.Cu")
		(net "M_L_CPU0_SA_DQS_DN<2>")
	)
	(segment
		(start 420.692834 -220.189806)
		(end 421.667178 -220.189806)
		(width 0.16002)
		(layer "In11.Cu")
		(net "M_L_CPU0_SA_DQS_DN<2>")
	)
	(segment
		(start 427.909228 -219.862146)
		(end 428.236888 -220.189806)
		(width 0.16002)
		(layer "In11.Cu")
		(net "M_L_CPU0_SA_DQS_DN<2>")
	)
	(segment
		(start 412.246826 -220.189806)
		(end 414.123124 -220.189806)
		(width 0.16002)
		(layer "In11.Cu")
		(net "M_L_CPU0_SA_DQS_DN<2>")
	)
	(segment
		(start 393.084812 -236.817154)
		(end 393.8905 -236.817154)
		(width 0.09525)
		(layer "In11.Cu")
		(net "M_L_CPU0_SA_DQS_DN<2>")
	)
	(segment
		(start 395.531086 -235.280708)
		(end 395.531086 -235.093764)
		(width 0.09525)
		(layer "In11.Cu")
		(net "M_L_CPU0_SA_DQS_DN<2>")
	)
	(segment
		(start 447.547492 -219.012262)
		(end 448.121532 -219.586302)
		(width 0.16002)
		(layer "In11.Cu")
		(net "M_L_CPU0_SA_DQS_DN<2>")
	)
	(segment
		(start 395.531086 -235.093764)
		(end 395.626336 -234.998514)
		(width 0.09525)
		(layer "In11.Cu")
		(net "M_L_CPU0_SA_DQS_DN<2>")
	)
	(segment
		(start 395.859254 -235.057442)
		(end 397.37919 -235.057442)
		(width 0.16002)
		(layer "In11.Cu")
		(net "M_L_CPU0_SA_DQS_DN<2>")
	)
	(segment
		(start 421.667178 -220.189806)
		(end 422.490138 -219.366846)
		(width 0.16002)
		(layer "In11.Cu")
		(net "M_L_CPU0_SA_DQS_DN<2>")
	)
	(segment
		(start 452.707248 -220.138244)
		(end 453.187308 -220.138244)
		(width 0.16002)
		(layer "In11.Cu")
		(net "M_L_CPU0_SA_DQS_DN<2>")
	)
	(segment
		(start 388.196328 -236.86897)
		(end 388.20471 -236.864144)
		(width 0.09525)
		(layer "In11.Cu")
		(net "M_L_CPU0_SA_DQS_DN<2>")
	)
	(segment
		(start 387.290818 -236.92866)
		(end 387.314186 -236.841792)
		(width 0.09525)
		(layer "In11.Cu")
		(net "M_L_CPU0_SA_DQS_DN<2>")
	)
	(segment
		(start 418.22116 -219.862146)
		(end 420.365174 -219.862146)
		(width 0.16002)
		(layer "In11.Cu")
		(net "M_L_CPU0_SA_DQS_DN<2>")
	)
	(segment
		(start 435.453282 -219.862146)
		(end 435.780942 -220.189806)
		(width 0.16002)
		(layer "In11.Cu")
		(net "M_L_CPU0_SA_DQS_DN<2>")
	)
	(segment
		(start 390.44499 -236.864144)
		(end 390.453372 -236.86897)
		(width 0.09525)
		(layer "In11.Cu")
		(net "M_L_CPU0_SA_DQS_DN<2>")
	)
	(segment
		(start 424.91533 -219.012262)
		(end 425.765214 -219.862146)
		(width 0.16002)
		(layer "In11.Cu")
		(net "M_L_CPU0_SA_DQS_DN<2>")
	)
	(segment
		(start 391.937494 -236.879384)
		(end 391.955528 -236.86897)
		(width 0.09525)
		(layer "In11.Cu")
		(net "M_L_CPU0_SA_DQS_DN<2>")
	)
	(segment
		(start 422.901618 -219.366846)
		(end 423.256202 -219.012262)
		(width 0.16002)
		(layer "In11.Cu")
		(net "M_L_CPU0_SA_DQS_DN<2>")
	)
	(segment
		(start 395.835632 -235.057442)
		(end 395.859254 -235.057442)
		(width 0.09525)
		(layer "In11.Cu")
		(net "M_L_CPU0_SA_DQS_DN<2>")
	)
	(segment
		(start 415.357564 -219.366846)
		(end 415.712148 -219.012262)
		(width 0.16002)
		(layer "In11.Cu")
		(net "M_L_CPU0_SA_DQS_DN<2>")
	)
	(segment
		(start 451.826884 -220.205046)
		(end 452.020686 -220.011244)
		(width 0.16002)
		(layer "In11.Cu")
		(net "M_L_CPU0_SA_DQS_DN<2>")
	)
	(segment
		(start 436.755286 -220.189806)
		(end 437.578246 -219.366846)
		(width 0.16002)
		(layer "In11.Cu")
		(net "M_L_CPU0_SA_DQS_DN<2>")
	)
	(segment
		(start 453.314308 -220.011244)
		(end 453.914256 -220.011244)
		(width 0.16002)
		(layer "In11.Cu")
		(net "M_L_CPU0_SA_DQS_DN<2>")
	)
	(segment
		(start 448.121532 -219.586302)
		(end 450.543168 -219.586302)
		(width 0.16002)
		(layer "In11.Cu")
		(net "M_L_CPU0_SA_DQS_DN<2>")
	)
	(segment
		(start 453.914256 -220.011244)
		(end 454.188068 -220.285056)
		(width 0.16002)
		(layer "In11.Cu")
		(net "M_L_CPU0_SA_DQS_DN<2>")
	)
	(segment
		(start 437.578246 -219.366846)
		(end 437.989726 -219.366846)
		(width 0.16002)
		(layer "In11.Cu")
		(net "M_L_CPU0_SA_DQS_DN<2>")
	)
	(segment
		(start 429.211232 -220.189806)
		(end 430.034192 -219.366846)
		(width 0.16002)
		(layer "In11.Cu")
		(net "M_L_CPU0_SA_DQS_DN<2>")
	)
	(segment
		(start 452.020686 -220.011244)
		(end 452.580248 -220.011244)
		(width 0.16002)
		(layer "In11.Cu")
		(net "M_L_CPU0_SA_DQS_DN<2>")
	)
	(segment
		(start 430.034192 -219.366846)
		(end 430.445672 -219.366846)
		(width 0.16002)
		(layer "In11.Cu")
		(net "M_L_CPU0_SA_DQS_DN<2>")
	)
	(segment
		(start 397.37919 -235.057442)
		(end 412.246826 -220.189806)
		(width 0.16002)
		(layer "In11.Cu")
		(net "M_L_CPU0_SA_DQS_DN<2>")
	)
	(segment
		(start 392.33221 -236.86897)
		(end 392.350244 -236.879384)
		(width 0.09525)
		(layer "In11.Cu")
		(net "M_L_CPU0_SA_DQS_DN<2>")
	)
	(segment
		(start 428.236888 -220.189806)
		(end 429.211232 -220.189806)
		(width 0.16002)
		(layer "In11.Cu")
		(net "M_L_CPU0_SA_DQS_DN<2>")
	)
	(segment
		(start 394.669772 -236.142022)
		(end 395.531086 -235.280708)
		(width 0.09525)
		(layer "In11.Cu")
		(net "M_L_CPU0_SA_DQS_DN<2>")
	)
	(segment
		(start 435.780942 -220.189806)
		(end 436.755286 -220.189806)
		(width 0.16002)
		(layer "In11.Cu")
		(net "M_L_CPU0_SA_DQS_DN<2>")
	)
	(segment
		(start 433.309268 -219.862146)
		(end 435.453282 -219.862146)
		(width 0.16002)
		(layer "In11.Cu")
		(net "M_L_CPU0_SA_DQS_DN<2>")
	)
	(segment
		(start 393.8905 -236.817154)
		(end 394.491972 -236.215682)
		(width 0.09525)
		(layer "In11.Cu")
		(net "M_L_CPU0_SA_DQS_DN<2>")
	)
	(arc
		(start 390.453372 -236.86897)
		(mid 390.734804 -236.944725)
		(end 391.016236 -236.86897)
		(width 0.09525)
		(layer "In11.Cu")
		(net "M_L_CPU0_SA_DQS_DN<2>")
	)
	(arc
		(start 392.895836 -236.86897)
		(mid 392.986896 -236.830574)
		(end 393.084812 -236.817154)
		(width 0.09525)
		(layer "In11.Cu")
		(net "M_L_CPU0_SA_DQS_DN<2>")
	)
	(arc
		(start 391.393426 -236.86897)
		(mid 391.664114 -236.944622)
		(end 391.937494 -236.879384)
		(width 0.09525)
		(layer "In11.Cu")
		(net "M_L_CPU0_SA_DQS_DN<2>")
	)
	(arc
		(start 389.136382 -236.86897)
		(mid 389.32485 -236.818293)
		(end 389.513318 -236.86897)
		(width 0.09525)
		(layer "In11.Cu")
		(net "M_L_CPU0_SA_DQS_DN<2>")
	)
	(arc
		(start 391.024618 -236.864144)
		(mid 391.20965 -236.81823)
		(end 391.393426 -236.86897)
		(width 0.09525)
		(layer "In11.Cu")
		(net "M_L_CPU0_SA_DQS_DN<2>")
	)
	(arc
		(start 392.350244 -236.879384)
		(mid 392.624386 -236.944963)
		(end 392.895836 -236.86897)
		(width 0.09525)
		(layer "In11.Cu")
		(net "M_L_CPU0_SA_DQS_DN<2>")
	)
	(arc
		(start 387.314186 -236.841792)
		(mid 387.476868 -236.81966)
		(end 387.633464 -236.86897)
		(width 0.09525)
		(layer "In11.Cu")
		(net "M_L_CPU0_SA_DQS_DN<2>")
	)
	(arc
		(start 388.573518 -236.86897)
		(mid 388.85495 -236.944725)
		(end 389.136382 -236.86897)
		(width 0.09525)
		(layer "In11.Cu")
		(net "M_L_CPU0_SA_DQS_DN<2>")
	)
	(arc
		(start 389.513318 -236.86897)
		(mid 389.79475 -236.944725)
		(end 390.076182 -236.86897)
		(width 0.09525)
		(layer "In11.Cu")
		(net "M_L_CPU0_SA_DQS_DN<2>")
	)
	(arc
		(start 391.96391 -236.864144)
		(mid 392.148688 -236.818351)
		(end 392.33221 -236.86897)
		(width 0.09525)
		(layer "In11.Cu")
		(net "M_L_CPU0_SA_DQS_DN<2>")
	)
	(arc
		(start 387.633464 -236.86897)
		(mid 387.914896 -236.944725)
		(end 388.196328 -236.86897)
		(width 0.09525)
		(layer "In11.Cu")
		(net "M_L_CPU0_SA_DQS_DN<2>")
	)
	(arc
		(start 390.076182 -236.86897)
		(mid 390.259957 -236.818198)
		(end 390.44499 -236.864144)
		(width 0.09525)
		(layer "In11.Cu")
		(net "M_L_CPU0_SA_DQS_DN<2>")
	)
	(arc
		(start 388.20471 -236.864144)
		(mid 388.389742 -236.81823)
		(end 388.573518 -236.86897)
		(width 0.09525)
		(layer "In11.Cu")
		(net "M_L_CPU0_SA_DQS_DN<2>")
	)
	(segment
		(start 386.97789 -232.599992)
		(end 387.444742 -232.334054)
		(width 0.12954)
		(layer "F.Cu")
		(net "M_L_CPU0_SA_DQS_DN<1>")
	)
	(segment
		(start 450.543168 -210.236308)
		(end 451.161912 -210.855052)
		(width 0.16002)
		(layer "In11.Cu")
		(net "M_L_CPU0_SA_DQS_DN<1>")
	)
	(segment
		(start 453.293988 -210.66125)
		(end 453.914256 -210.66125)
		(width 0.16002)
		(layer "In11.Cu")
		(net "M_L_CPU0_SA_DQS_DN<1>")
	)
	(segment
		(start 427.909228 -210.512152)
		(end 428.236888 -210.839812)
		(width 0.16002)
		(layer "In11.Cu")
		(net "M_L_CPU0_SA_DQS_DN<1>")
	)
	(segment
		(start 395.43863 -228.978206)
		(end 400.224498 -224.1931)
		(width 0.16002)
		(layer "In11.Cu")
		(net "M_L_CPU0_SA_DQS_DN<1>")
	)
	(segment
		(start 417.371276 -209.662268)
		(end 418.22116 -210.512152)
		(width 0.16002)
		(layer "In11.Cu")
		(net "M_L_CPU0_SA_DQS_DN<1>")
	)
	(segment
		(start 411.150562 -211.16417)
		(end 411.93339 -210.839812)
		(width 0.16002)
		(layer "In11.Cu")
		(net "M_L_CPU0_SA_DQS_DN<1>")
	)
	(segment
		(start 436.755286 -210.839812)
		(end 437.578246 -210.016852)
		(width 0.16002)
		(layer "In11.Cu")
		(net "M_L_CPU0_SA_DQS_DN<1>")
	)
	(segment
		(start 440.003438 -209.662268)
		(end 440.853322 -210.512152)
		(width 0.16002)
		(layer "In11.Cu")
		(net "M_L_CPU0_SA_DQS_DN<1>")
	)
	(segment
		(start 452.686928 -210.78825)
		(end 453.166988 -210.78825)
		(width 0.16002)
		(layer "In11.Cu")
		(net "M_L_CPU0_SA_DQS_DN<1>")
	)
	(segment
		(start 422.490138 -210.016852)
		(end 422.901618 -210.016852)
		(width 0.16002)
		(layer "In11.Cu")
		(net "M_L_CPU0_SA_DQS_DN<1>")
	)
	(segment
		(start 387.444742 -232.334054)
		(end 387.290818 -232.068624)
		(width 0.09525)
		(layer "In11.Cu")
		(net "M_L_CPU0_SA_DQS_DN<1>")
	)
	(segment
		(start 420.692834 -210.839812)
		(end 421.667178 -210.839812)
		(width 0.16002)
		(layer "In11.Cu")
		(net "M_L_CPU0_SA_DQS_DN<1>")
	)
	(segment
		(start 443.324996 -210.839812)
		(end 444.29934 -210.839812)
		(width 0.16002)
		(layer "In11.Cu")
		(net "M_L_CPU0_SA_DQS_DN<1>")
	)
	(segment
		(start 452.559928 -210.66125)
		(end 452.686928 -210.78825)
		(width 0.16002)
		(layer "In11.Cu")
		(net "M_L_CPU0_SA_DQS_DN<1>")
	)
	(segment
		(start 453.914256 -210.66125)
		(end 454.188068 -210.935062)
		(width 0.16002)
		(layer "In11.Cu")
		(net "M_L_CPU0_SA_DQS_DN<1>")
	)
	(segment
		(start 433.309268 -210.512152)
		(end 435.453282 -210.512152)
		(width 0.16002)
		(layer "In11.Cu")
		(net "M_L_CPU0_SA_DQS_DN<1>")
	)
	(segment
		(start 445.888364 -209.662268)
		(end 447.547492 -209.662268)
		(width 0.16002)
		(layer "In11.Cu")
		(net "M_L_CPU0_SA_DQS_DN<1>")
	)
	(segment
		(start 416.787076 -209.789268)
		(end 416.914076 -209.662268)
		(width 0.16002)
		(layer "In11.Cu")
		(net "M_L_CPU0_SA_DQS_DN<1>")
	)
	(segment
		(start 432.459384 -209.662268)
		(end 433.309268 -210.512152)
		(width 0.16002)
		(layer "In11.Cu")
		(net "M_L_CPU0_SA_DQS_DN<1>")
	)
	(segment
		(start 400.224498 -222.090234)
		(end 411.150562 -211.16417)
		(width 0.16002)
		(layer "In11.Cu")
		(net "M_L_CPU0_SA_DQS_DN<1>")
	)
	(segment
		(start 411.93339 -210.839812)
		(end 414.123124 -210.839812)
		(width 0.16002)
		(layer "In11.Cu")
		(net "M_L_CPU0_SA_DQS_DN<1>")
	)
	(segment
		(start 415.712148 -209.662268)
		(end 416.202876 -209.662268)
		(width 0.16002)
		(layer "In11.Cu")
		(net "M_L_CPU0_SA_DQS_DN<1>")
	)
	(segment
		(start 421.667178 -210.839812)
		(end 422.490138 -210.016852)
		(width 0.16002)
		(layer "In11.Cu")
		(net "M_L_CPU0_SA_DQS_DN<1>")
	)
	(segment
		(start 416.329876 -209.789268)
		(end 416.787076 -209.789268)
		(width 0.16002)
		(layer "In11.Cu")
		(net "M_L_CPU0_SA_DQS_DN<1>")
	)
	(segment
		(start 429.211232 -210.839812)
		(end 430.034192 -210.016852)
		(width 0.16002)
		(layer "In11.Cu")
		(net "M_L_CPU0_SA_DQS_DN<1>")
	)
	(segment
		(start 447.547492 -209.662268)
		(end 448.121532 -210.236308)
		(width 0.16002)
		(layer "In11.Cu")
		(net "M_L_CPU0_SA_DQS_DN<1>")
	)
	(segment
		(start 442.997336 -210.512152)
		(end 443.324996 -210.839812)
		(width 0.16002)
		(layer "In11.Cu")
		(net "M_L_CPU0_SA_DQS_DN<1>")
	)
	(segment
		(start 423.256202 -209.662268)
		(end 424.91533 -209.662268)
		(width 0.16002)
		(layer "In11.Cu")
		(net "M_L_CPU0_SA_DQS_DN<1>")
	)
	(segment
		(start 435.453282 -210.512152)
		(end 435.780942 -210.839812)
		(width 0.16002)
		(layer "In11.Cu")
		(net "M_L_CPU0_SA_DQS_DN<1>")
	)
	(segment
		(start 415.357564 -210.016852)
		(end 415.712148 -209.662268)
		(width 0.16002)
		(layer "In11.Cu")
		(net "M_L_CPU0_SA_DQS_DN<1>")
	)
	(segment
		(start 391.016236 -232.008934)
		(end 391.024618 -232.004108)
		(width 0.09525)
		(layer "In11.Cu")
		(net "M_L_CPU0_SA_DQS_DN<1>")
	)
	(segment
		(start 394.277088 -230.654606)
		(end 394.277088 -230.05669)
		(width 0.09525)
		(layer "In11.Cu")
		(net "M_L_CPU0_SA_DQS_DN<1>")
	)
	(segment
		(start 430.445672 -210.016852)
		(end 430.800256 -209.662268)
		(width 0.16002)
		(layer "In11.Cu")
		(net "M_L_CPU0_SA_DQS_DN<1>")
	)
	(segment
		(start 451.826884 -210.855052)
		(end 452.020686 -210.66125)
		(width 0.16002)
		(layer "In11.Cu")
		(net "M_L_CPU0_SA_DQS_DN<1>")
	)
	(segment
		(start 440.853322 -210.512152)
		(end 442.997336 -210.512152)
		(width 0.16002)
		(layer "In11.Cu")
		(net "M_L_CPU0_SA_DQS_DN<1>")
	)
	(segment
		(start 416.202876 -209.662268)
		(end 416.329876 -209.789268)
		(width 0.16002)
		(layer "In11.Cu")
		(net "M_L_CPU0_SA_DQS_DN<1>")
	)
	(segment
		(start 414.946084 -210.016852)
		(end 415.357564 -210.016852)
		(width 0.16002)
		(layer "In11.Cu")
		(net "M_L_CPU0_SA_DQS_DN<1>")
	)
	(segment
		(start 445.53378 -210.016852)
		(end 445.888364 -209.662268)
		(width 0.16002)
		(layer "In11.Cu")
		(net "M_L_CPU0_SA_DQS_DN<1>")
	)
	(segment
		(start 416.914076 -209.662268)
		(end 417.371276 -209.662268)
		(width 0.16002)
		(layer "In11.Cu")
		(net "M_L_CPU0_SA_DQS_DN<1>")
	)
	(segment
		(start 394.277088 -230.05669)
		(end 395.338808 -228.99497)
		(width 0.09525)
		(layer "In11.Cu")
		(net "M_L_CPU0_SA_DQS_DN<1>")
	)
	(segment
		(start 425.765214 -210.512152)
		(end 427.909228 -210.512152)
		(width 0.16002)
		(layer "In11.Cu")
		(net "M_L_CPU0_SA_DQS_DN<1>")
	)
	(segment
		(start 424.91533 -209.662268)
		(end 425.765214 -210.512152)
		(width 0.16002)
		(layer "In11.Cu")
		(net "M_L_CPU0_SA_DQS_DN<1>")
	)
	(segment
		(start 428.236888 -210.839812)
		(end 429.211232 -210.839812)
		(width 0.16002)
		(layer "In11.Cu")
		(net "M_L_CPU0_SA_DQS_DN<1>")
	)
	(segment
		(start 395.338808 -228.99497)
		(end 395.421866 -228.99497)
		(width 0.09525)
		(layer "In11.Cu")
		(net "M_L_CPU0_SA_DQS_DN<1>")
	)
	(segment
		(start 387.290818 -232.068624)
		(end 387.314186 -231.981756)
		(width 0.09525)
		(layer "In11.Cu")
		(net "M_L_CPU0_SA_DQS_DN<1>")
	)
	(segment
		(start 435.780942 -210.839812)
		(end 436.755286 -210.839812)
		(width 0.16002)
		(layer "In11.Cu")
		(net "M_L_CPU0_SA_DQS_DN<1>")
	)
	(segment
		(start 448.121532 -210.236308)
		(end 450.543168 -210.236308)
		(width 0.16002)
		(layer "In11.Cu")
		(net "M_L_CPU0_SA_DQS_DN<1>")
	)
	(segment
		(start 430.800256 -209.662268)
		(end 432.459384 -209.662268)
		(width 0.16002)
		(layer "In11.Cu")
		(net "M_L_CPU0_SA_DQS_DN<1>")
	)
	(segment
		(start 395.421866 -228.99497)
		(end 395.43863 -228.978206)
		(width 0.09525)
		(layer "In11.Cu")
		(net "M_L_CPU0_SA_DQS_DN<1>")
	)
	(segment
		(start 388.196328 -232.008934)
		(end 388.20471 -232.004108)
		(width 0.09525)
		(layer "In11.Cu")
		(net "M_L_CPU0_SA_DQS_DN<1>")
	)
	(segment
		(start 418.22116 -210.512152)
		(end 420.365174 -210.512152)
		(width 0.16002)
		(layer "In11.Cu")
		(net "M_L_CPU0_SA_DQS_DN<1>")
	)
	(segment
		(start 422.901618 -210.016852)
		(end 423.256202 -209.662268)
		(width 0.16002)
		(layer "In11.Cu")
		(net "M_L_CPU0_SA_DQS_DN<1>")
	)
	(segment
		(start 445.1223 -210.016852)
		(end 445.53378 -210.016852)
		(width 0.16002)
		(layer "In11.Cu")
		(net "M_L_CPU0_SA_DQS_DN<1>")
	)
	(segment
		(start 414.123124 -210.839812)
		(end 414.946084 -210.016852)
		(width 0.16002)
		(layer "In11.Cu")
		(net "M_L_CPU0_SA_DQS_DN<1>")
	)
	(segment
		(start 430.034192 -210.016852)
		(end 430.445672 -210.016852)
		(width 0.16002)
		(layer "In11.Cu")
		(net "M_L_CPU0_SA_DQS_DN<1>")
	)
	(segment
		(start 452.020686 -210.66125)
		(end 452.559928 -210.66125)
		(width 0.16002)
		(layer "In11.Cu")
		(net "M_L_CPU0_SA_DQS_DN<1>")
	)
	(segment
		(start 437.578246 -210.016852)
		(end 437.989726 -210.016852)
		(width 0.16002)
		(layer "In11.Cu")
		(net "M_L_CPU0_SA_DQS_DN<1>")
	)
	(segment
		(start 394.14958 -230.782114)
		(end 394.277088 -230.654606)
		(width 0.09525)
		(layer "In11.Cu")
		(net "M_L_CPU0_SA_DQS_DN<1>")
	)
	(segment
		(start 451.161912 -210.855052)
		(end 451.826884 -210.855052)
		(width 0.16002)
		(layer "In11.Cu")
		(net "M_L_CPU0_SA_DQS_DN<1>")
	)
	(segment
		(start 400.224498 -224.1931)
		(end 400.224498 -222.090234)
		(width 0.16002)
		(layer "In11.Cu")
		(net "M_L_CPU0_SA_DQS_DN<1>")
	)
	(segment
		(start 392.88593 -232.01503)
		(end 392.896344 -232.008934)
		(width 0.09525)
		(layer "In11.Cu")
		(net "M_L_CPU0_SA_DQS_DN<1>")
	)
	(segment
		(start 393.011406 -231.920542)
		(end 394.14958 -230.782114)
		(width 0.09525)
		(layer "In11.Cu")
		(net "M_L_CPU0_SA_DQS_DN<1>")
	)
	(segment
		(start 438.34431 -209.662268)
		(end 440.003438 -209.662268)
		(width 0.16002)
		(layer "In11.Cu")
		(net "M_L_CPU0_SA_DQS_DN<1>")
	)
	(segment
		(start 390.44499 -232.004108)
		(end 390.453372 -232.008934)
		(width 0.09525)
		(layer "In11.Cu")
		(net "M_L_CPU0_SA_DQS_DN<1>")
	)
	(segment
		(start 437.989726 -210.016852)
		(end 438.34431 -209.662268)
		(width 0.16002)
		(layer "In11.Cu")
		(net "M_L_CPU0_SA_DQS_DN<1>")
	)
	(segment
		(start 453.166988 -210.78825)
		(end 453.293988 -210.66125)
		(width 0.16002)
		(layer "In11.Cu")
		(net "M_L_CPU0_SA_DQS_DN<1>")
	)
	(segment
		(start 444.29934 -210.839812)
		(end 445.1223 -210.016852)
		(width 0.16002)
		(layer "In11.Cu")
		(net "M_L_CPU0_SA_DQS_DN<1>")
	)
	(segment
		(start 420.365174 -210.512152)
		(end 420.692834 -210.839812)
		(width 0.16002)
		(layer "In11.Cu")
		(net "M_L_CPU0_SA_DQS_DN<1>")
	)
	(arc
		(start 391.393426 -232.008934)
		(mid 391.674858 -232.084689)
		(end 391.95629 -232.008934)
		(width 0.09525)
		(layer "In11.Cu")
		(net "M_L_CPU0_SA_DQS_DN<1>")
	)
	(arc
		(start 391.024618 -232.004108)
		(mid 391.20965 -231.958194)
		(end 391.393426 -232.008934)
		(width 0.09525)
		(layer "In11.Cu")
		(net "M_L_CPU0_SA_DQS_DN<1>")
	)
	(arc
		(start 389.513318 -232.008934)
		(mid 389.79475 -232.084689)
		(end 390.076182 -232.008934)
		(width 0.09525)
		(layer "In11.Cu")
		(net "M_L_CPU0_SA_DQS_DN<1>")
	)
	(arc
		(start 392.333734 -232.008934)
		(mid 392.609023 -232.084655)
		(end 392.88593 -232.01503)
		(width 0.09525)
		(layer "In11.Cu")
		(net "M_L_CPU0_SA_DQS_DN<1>")
	)
	(arc
		(start 391.95629 -232.008934)
		(mid 392.145012 -231.95813)
		(end 392.333734 -232.008934)
		(width 0.09525)
		(layer "In11.Cu")
		(net "M_L_CPU0_SA_DQS_DN<1>")
	)
	(arc
		(start 388.20471 -232.004108)
		(mid 388.389742 -231.958194)
		(end 388.573518 -232.008934)
		(width 0.09525)
		(layer "In11.Cu")
		(net "M_L_CPU0_SA_DQS_DN<1>")
	)
	(arc
		(start 388.573518 -232.008934)
		(mid 388.85495 -232.084689)
		(end 389.136382 -232.008934)
		(width 0.09525)
		(layer "In11.Cu")
		(net "M_L_CPU0_SA_DQS_DN<1>")
	)
	(arc
		(start 392.896344 -232.008934)
		(mid 392.953193 -231.971218)
		(end 393.005056 -231.926892)
		(width 0.09525)
		(layer "In11.Cu")
		(net "M_L_CPU0_SA_DQS_DN<1>")
	)
	(arc
		(start 390.453372 -232.008934)
		(mid 390.734804 -232.084689)
		(end 391.016236 -232.008934)
		(width 0.09525)
		(layer "In11.Cu")
		(net "M_L_CPU0_SA_DQS_DN<1>")
	)
	(arc
		(start 389.136382 -232.008934)
		(mid 389.32485 -231.958257)
		(end 389.513318 -232.008934)
		(width 0.09525)
		(layer "In11.Cu")
		(net "M_L_CPU0_SA_DQS_DN<1>")
	)
	(arc
		(start 387.633464 -232.008934)
		(mid 387.914896 -232.084689)
		(end 388.196328 -232.008934)
		(width 0.09525)
		(layer "In11.Cu")
		(net "M_L_CPU0_SA_DQS_DN<1>")
	)
	(arc
		(start 393.005056 -231.926892)
		(mid 393.008244 -231.92373)
		(end 393.011406 -231.920542)
		(width 0.09525)
		(layer "In11.Cu")
		(net "M_L_CPU0_SA_DQS_DN<1>")
	)
	(arc
		(start 390.076182 -232.008934)
		(mid 390.259957 -231.958162)
		(end 390.44499 -232.004108)
		(width 0.09525)
		(layer "In11.Cu")
		(net "M_L_CPU0_SA_DQS_DN<1>")
	)
	(arc
		(start 387.314186 -231.981756)
		(mid 387.476868 -231.959624)
		(end 387.633464 -232.008934)
		(width 0.09525)
		(layer "In11.Cu")
		(net "M_L_CPU0_SA_DQS_DN<1>")
	)
	(segment
		(start 386.97789 -227.74021)
		(end 387.444742 -227.474272)
		(width 0.12954)
		(layer "F.Cu")
		(net "M_L_CPU0_SA_DQS_DN<0>")
	)
	(segment
		(start 392.896344 -223.909128)
		(end 392.931396 -223.888554)
		(width 0.09525)
		(layer "In11.Cu")
		(net "M_L_CPU0_SA_DQS_DN<0>")
	)
	(segment
		(start 432.459384 -200.312274)
		(end 433.309268 -201.162158)
		(width 0.16002)
		(layer "In11.Cu")
		(net "M_L_CPU0_SA_DQS_DN<0>")
	)
	(segment
		(start 394.397484 -217.678508)
		(end 410.586174 -201.489818)
		(width 0.16002)
		(layer "In11.Cu")
		(net "M_L_CPU0_SA_DQS_DN<0>")
	)
	(segment
		(start 428.236888 -201.489818)
		(end 429.211232 -201.489818)
		(width 0.16002)
		(layer "In11.Cu")
		(net "M_L_CPU0_SA_DQS_DN<0>")
	)
	(segment
		(start 435.780942 -201.489818)
		(end 436.755286 -201.489818)
		(width 0.16002)
		(layer "In11.Cu")
		(net "M_L_CPU0_SA_DQS_DN<0>")
	)
	(segment
		(start 449.087748 -201.013314)
		(end 449.567808 -201.013314)
		(width 0.16002)
		(layer "In11.Cu")
		(net "M_L_CPU0_SA_DQS_DN<0>")
	)
	(segment
		(start 391.016236 -227.149152)
		(end 391.054336 -227.127054)
		(width 0.09525)
		(layer "In11.Cu")
		(net "M_L_CPU0_SA_DQS_DN<0>")
	)
	(segment
		(start 421.667178 -201.489818)
		(end 422.490138 -200.666858)
		(width 0.16002)
		(layer "In11.Cu")
		(net "M_L_CPU0_SA_DQS_DN<0>")
	)
	(segment
		(start 388.196328 -227.149152)
		(end 388.20471 -227.144326)
		(width 0.09525)
		(layer "In11.Cu")
		(net "M_L_CPU0_SA_DQS_DN<0>")
	)
	(segment
		(start 449.694808 -200.886314)
		(end 450.543168 -200.886314)
		(width 0.16002)
		(layer "In11.Cu")
		(net "M_L_CPU0_SA_DQS_DN<0>")
	)
	(segment
		(start 442.997336 -201.162158)
		(end 443.324996 -201.489818)
		(width 0.16002)
		(layer "In11.Cu")
		(net "M_L_CPU0_SA_DQS_DN<0>")
	)
	(segment
		(start 443.324996 -201.489818)
		(end 444.29934 -201.489818)
		(width 0.16002)
		(layer "In11.Cu")
		(net "M_L_CPU0_SA_DQS_DN<0>")
	)
	(segment
		(start 391.923524 -225.547936)
		(end 391.956036 -225.52914)
		(width 0.09525)
		(layer "In11.Cu")
		(net "M_L_CPU0_SA_DQS_DN<0>")
	)
	(segment
		(start 422.901618 -200.666858)
		(end 423.256202 -200.312274)
		(width 0.16002)
		(layer "In11.Cu")
		(net "M_L_CPU0_SA_DQS_DN<0>")
	)
	(segment
		(start 429.211232 -201.489818)
		(end 430.034192 -200.666858)
		(width 0.16002)
		(layer "In11.Cu")
		(net "M_L_CPU0_SA_DQS_DN<0>")
	)
	(segment
		(start 452.020686 -201.311256)
		(end 452.623428 -201.311256)
		(width 0.16002)
		(layer "In11.Cu")
		(net "M_L_CPU0_SA_DQS_DN<0>")
	)
	(segment
		(start 453.230488 -201.438256)
		(end 453.357488 -201.311256)
		(width 0.16002)
		(layer "In11.Cu")
		(net "M_L_CPU0_SA_DQS_DN<0>")
	)
	(segment
		(start 425.765214 -201.162158)
		(end 427.909228 -201.162158)
		(width 0.16002)
		(layer "In11.Cu")
		(net "M_L_CPU0_SA_DQS_DN<0>")
	)
	(segment
		(start 394.338302 -222.099124)
		(end 394.338302 -221.257114)
		(width 0.09525)
		(layer "In11.Cu")
		(net "M_L_CPU0_SA_DQS_DN<0>")
	)
	(segment
		(start 392.42619 -224.719134)
		(end 392.462766 -224.697798)
		(width 0.09525)
		(layer "In11.Cu")
		(net "M_L_CPU0_SA_DQS_DN<0>")
	)
	(segment
		(start 451.826884 -201.505058)
		(end 452.020686 -201.311256)
		(width 0.16002)
		(layer "In11.Cu")
		(net "M_L_CPU0_SA_DQS_DN<0>")
	)
	(segment
		(start 437.989726 -200.666858)
		(end 438.34431 -200.312274)
		(width 0.16002)
		(layer "In11.Cu")
		(net "M_L_CPU0_SA_DQS_DN<0>")
	)
	(segment
		(start 445.888364 -200.312274)
		(end 447.547492 -200.312274)
		(width 0.16002)
		(layer "In11.Cu")
		(net "M_L_CPU0_SA_DQS_DN<0>")
	)
	(segment
		(start 449.567808 -201.013314)
		(end 449.694808 -200.886314)
		(width 0.16002)
		(layer "In11.Cu")
		(net "M_L_CPU0_SA_DQS_DN<0>")
	)
	(segment
		(start 436.755286 -201.489818)
		(end 437.578246 -200.666858)
		(width 0.16002)
		(layer "In11.Cu")
		(net "M_L_CPU0_SA_DQS_DN<0>")
	)
	(segment
		(start 435.453282 -201.162158)
		(end 435.780942 -201.489818)
		(width 0.16002)
		(layer "In11.Cu")
		(net "M_L_CPU0_SA_DQS_DN<0>")
	)
	(segment
		(start 427.909228 -201.162158)
		(end 428.236888 -201.489818)
		(width 0.16002)
		(layer "In11.Cu")
		(net "M_L_CPU0_SA_DQS_DN<0>")
	)
	(segment
		(start 394.397484 -221.17431)
		(end 394.397484 -217.678508)
		(width 0.16002)
		(layer "In11.Cu")
		(net "M_L_CPU0_SA_DQS_DN<0>")
	)
	(segment
		(start 445.1223 -200.666858)
		(end 445.53378 -200.666858)
		(width 0.16002)
		(layer "In11.Cu")
		(net "M_L_CPU0_SA_DQS_DN<0>")
	)
	(segment
		(start 430.034192 -200.666858)
		(end 430.445672 -200.666858)
		(width 0.16002)
		(layer "In11.Cu")
		(net "M_L_CPU0_SA_DQS_DN<0>")
	)
	(segment
		(start 452.623428 -201.311256)
		(end 452.750428 -201.438256)
		(width 0.16002)
		(layer "In11.Cu")
		(net "M_L_CPU0_SA_DQS_DN<0>")
	)
	(segment
		(start 393.408916 -223.07423)
		(end 393.409678 -223.073722)
		(width 0.09525)
		(layer "In11.Cu")
		(net "M_L_CPU0_SA_DQS_DN<0>")
	)
	(segment
		(start 444.29934 -201.489818)
		(end 445.1223 -200.666858)
		(width 0.16002)
		(layer "In11.Cu")
		(net "M_L_CPU0_SA_DQS_DN<0>")
	)
	(segment
		(start 417.371276 -200.312274)
		(end 418.22116 -201.162158)
		(width 0.16002)
		(layer "In11.Cu")
		(net "M_L_CPU0_SA_DQS_DN<0>")
	)
	(segment
		(start 430.445672 -200.666858)
		(end 430.800256 -200.312274)
		(width 0.16002)
		(layer "In11.Cu")
		(net "M_L_CPU0_SA_DQS_DN<0>")
	)
	(segment
		(start 433.309268 -201.162158)
		(end 435.453282 -201.162158)
		(width 0.16002)
		(layer "In11.Cu")
		(net "M_L_CPU0_SA_DQS_DN<0>")
	)
	(segment
		(start 448.960748 -200.886314)
		(end 449.087748 -201.013314)
		(width 0.16002)
		(layer "In11.Cu")
		(net "M_L_CPU0_SA_DQS_DN<0>")
	)
	(segment
		(start 452.750428 -201.438256)
		(end 453.230488 -201.438256)
		(width 0.16002)
		(layer "In11.Cu")
		(net "M_L_CPU0_SA_DQS_DN<0>")
	)
	(segment
		(start 450.543168 -200.886314)
		(end 451.161912 -201.505058)
		(width 0.16002)
		(layer "In11.Cu")
		(net "M_L_CPU0_SA_DQS_DN<0>")
	)
	(segment
		(start 392.394694 -224.737422)
		(end 392.42619 -224.719134)
		(width 0.09525)
		(layer "In11.Cu")
		(net "M_L_CPU0_SA_DQS_DN<0>")
	)
	(segment
		(start 453.357488 -201.311256)
		(end 453.914256 -201.311256)
		(width 0.16002)
		(layer "In11.Cu")
		(net "M_L_CPU0_SA_DQS_DN<0>")
	)
	(segment
		(start 387.290818 -227.208842)
		(end 387.314186 -227.121974)
		(width 0.09525)
		(layer "In11.Cu")
		(net "M_L_CPU0_SA_DQS_DN<0>")
	)
	(segment
		(start 394.338302 -221.257114)
		(end 394.397484 -221.197932)
		(width 0.09525)
		(layer "In11.Cu")
		(net "M_L_CPU0_SA_DQS_DN<0>")
	)
	(segment
		(start 414.123124 -201.489818)
		(end 414.946084 -200.666858)
		(width 0.16002)
		(layer "In11.Cu")
		(net "M_L_CPU0_SA_DQS_DN<0>")
	)
	(segment
		(start 415.712148 -200.312274)
		(end 417.371276 -200.312274)
		(width 0.16002)
		(layer "In11.Cu")
		(net "M_L_CPU0_SA_DQS_DN<0>")
	)
	(segment
		(start 415.357564 -200.666858)
		(end 415.712148 -200.312274)
		(width 0.16002)
		(layer "In11.Cu")
		(net "M_L_CPU0_SA_DQS_DN<0>")
	)
	(segment
		(start 390.44499 -227.144326)
		(end 390.453372 -227.149152)
		(width 0.09525)
		(layer "In11.Cu")
		(net "M_L_CPU0_SA_DQS_DN<0>")
	)
	(segment
		(start 424.91533 -200.312274)
		(end 425.765214 -201.162158)
		(width 0.16002)
		(layer "In11.Cu")
		(net "M_L_CPU0_SA_DQS_DN<0>")
	)
	(segment
		(start 445.53378 -200.666858)
		(end 445.888364 -200.312274)
		(width 0.16002)
		(layer "In11.Cu")
		(net "M_L_CPU0_SA_DQS_DN<0>")
	)
	(segment
		(start 418.22116 -201.162158)
		(end 420.365174 -201.162158)
		(width 0.16002)
		(layer "In11.Cu")
		(net "M_L_CPU0_SA_DQS_DN<0>")
	)
	(segment
		(start 391.486136 -226.339146)
		(end 391.521188 -226.318572)
		(width 0.09525)
		(layer "In11.Cu")
		(net "M_L_CPU0_SA_DQS_DN<0>")
	)
	(segment
		(start 437.578246 -200.666858)
		(end 437.989726 -200.666858)
		(width 0.16002)
		(layer "In11.Cu")
		(net "M_L_CPU0_SA_DQS_DN<0>")
	)
	(segment
		(start 393.332716 -223.11868)
		(end 393.405868 -223.076262)
		(width 0.09525)
		(layer "In11.Cu")
		(net "M_L_CPU0_SA_DQS_DN<0>")
	)
	(segment
		(start 447.547492 -200.312274)
		(end 448.121532 -200.886314)
		(width 0.16002)
		(layer "In11.Cu")
		(net "M_L_CPU0_SA_DQS_DN<0>")
	)
	(segment
		(start 391.956036 -225.52914)
		(end 391.995406 -225.50628)
		(width 0.09525)
		(layer "In11.Cu")
		(net "M_L_CPU0_SA_DQS_DN<0>")
	)
	(segment
		(start 387.444742 -227.474272)
		(end 387.290818 -227.208842)
		(width 0.09525)
		(layer "In11.Cu")
		(net "M_L_CPU0_SA_DQS_DN<0>")
	)
	(segment
		(start 392.861546 -223.929194)
		(end 392.896344 -223.909128)
		(width 0.09525)
		(layer "In11.Cu")
		(net "M_L_CPU0_SA_DQS_DN<0>")
	)
	(segment
		(start 453.914256 -201.311256)
		(end 454.188068 -201.585068)
		(width 0.16002)
		(layer "In11.Cu")
		(net "M_L_CPU0_SA_DQS_DN<0>")
	)
	(segment
		(start 448.121532 -200.886314)
		(end 448.960748 -200.886314)
		(width 0.16002)
		(layer "In11.Cu")
		(net "M_L_CPU0_SA_DQS_DN<0>")
	)
	(segment
		(start 414.946084 -200.666858)
		(end 415.357564 -200.666858)
		(width 0.16002)
		(layer "In11.Cu")
		(net "M_L_CPU0_SA_DQS_DN<0>")
	)
	(segment
		(start 430.800256 -200.312274)
		(end 432.459384 -200.312274)
		(width 0.16002)
		(layer "In11.Cu")
		(net "M_L_CPU0_SA_DQS_DN<0>")
	)
	(segment
		(start 423.256202 -200.312274)
		(end 424.91533 -200.312274)
		(width 0.16002)
		(layer "In11.Cu")
		(net "M_L_CPU0_SA_DQS_DN<0>")
	)
	(segment
		(start 451.161912 -201.505058)
		(end 451.826884 -201.505058)
		(width 0.16002)
		(layer "In11.Cu")
		(net "M_L_CPU0_SA_DQS_DN<0>")
	)
	(segment
		(start 391.45464 -226.357434)
		(end 391.486136 -226.339146)
		(width 0.09525)
		(layer "In11.Cu")
		(net "M_L_CPU0_SA_DQS_DN<0>")
	)
	(segment
		(start 440.003438 -200.312274)
		(end 440.853322 -201.162158)
		(width 0.16002)
		(layer "In11.Cu")
		(net "M_L_CPU0_SA_DQS_DN<0>")
	)
	(segment
		(start 394.397484 -221.197932)
		(end 394.397484 -221.17431)
		(width 0.09525)
		(layer "In11.Cu")
		(net "M_L_CPU0_SA_DQS_DN<0>")
	)
	(segment
		(start 440.853322 -201.162158)
		(end 442.997336 -201.162158)
		(width 0.16002)
		(layer "In11.Cu")
		(net "M_L_CPU0_SA_DQS_DN<0>")
	)
	(segment
		(start 410.586174 -201.489818)
		(end 414.123124 -201.489818)
		(width 0.16002)
		(layer "In11.Cu")
		(net "M_L_CPU0_SA_DQS_DN<0>")
	)
	(segment
		(start 393.647168 -222.790258)
		(end 394.338302 -222.099124)
		(width 0.09525)
		(layer "In11.Cu")
		(net "M_L_CPU0_SA_DQS_DN<0>")
	)
	(segment
		(start 420.365174 -201.162158)
		(end 420.692834 -201.489818)
		(width 0.16002)
		(layer "In11.Cu")
		(net "M_L_CPU0_SA_DQS_DN<0>")
	)
	(segment
		(start 422.490138 -200.666858)
		(end 422.901618 -200.666858)
		(width 0.16002)
		(layer "In11.Cu")
		(net "M_L_CPU0_SA_DQS_DN<0>")
	)
	(segment
		(start 438.34431 -200.312274)
		(end 440.003438 -200.312274)
		(width 0.16002)
		(layer "In11.Cu")
		(net "M_L_CPU0_SA_DQS_DN<0>")
	)
	(segment
		(start 420.692834 -201.489818)
		(end 421.667178 -201.489818)
		(width 0.16002)
		(layer "In11.Cu")
		(net "M_L_CPU0_SA_DQS_DN<0>")
	)
	(arc
		(start 388.573518 -227.149152)
		(mid 388.85495 -227.224907)
		(end 389.136382 -227.149152)
		(width 0.09525)
		(layer "In11.Cu")
		(net "M_L_CPU0_SA_DQS_DN<0>")
	)
	(arc
		(start 391.995406 -225.50628)
		(mid 392.173092 -225.304988)
		(end 392.237214 -225.044254)
		(width 0.09525)
		(layer "In11.Cu")
		(net "M_L_CPU0_SA_DQS_DN<0>")
	)
	(arc
		(start 392.931396 -223.888554)
		(mid 393.111787 -223.686855)
		(end 393.177014 -223.424242)
		(width 0.09525)
		(layer "In11.Cu")
		(net "M_L_CPU0_SA_DQS_DN<0>")
	)
	(arc
		(start 389.136382 -227.149152)
		(mid 389.32485 -227.098475)
		(end 389.513318 -227.149152)
		(width 0.09525)
		(layer "In11.Cu")
		(net "M_L_CPU0_SA_DQS_DN<0>")
	)
	(arc
		(start 391.766806 -225.85426)
		(mid 391.808263 -225.68222)
		(end 391.923524 -225.547936)
		(width 0.09525)
		(layer "In11.Cu")
		(net "M_L_CPU0_SA_DQS_DN<0>")
	)
	(arc
		(start 388.20471 -227.144326)
		(mid 388.389742 -227.098412)
		(end 388.573518 -227.149152)
		(width 0.09525)
		(layer "In11.Cu")
		(net "M_L_CPU0_SA_DQS_DN<0>")
	)
	(arc
		(start 393.177014 -223.424242)
		(mid 393.218182 -223.252768)
		(end 393.332716 -223.11868)
		(width 0.09525)
		(layer "In11.Cu")
		(net "M_L_CPU0_SA_DQS_DN<0>")
	)
	(arc
		(start 389.513318 -227.149152)
		(mid 389.79475 -227.224907)
		(end 390.076182 -227.149152)
		(width 0.09525)
		(layer "In11.Cu")
		(net "M_L_CPU0_SA_DQS_DN<0>")
	)
	(arc
		(start 393.581128 -222.879158)
		(mid 393.610883 -222.832283)
		(end 393.647168 -222.790258)
		(width 0.09525)
		(layer "In11.Cu")
		(net "M_L_CPU0_SA_DQS_DN<0>")
	)
	(arc
		(start 392.237214 -225.044254)
		(mid 392.278879 -224.871807)
		(end 392.394694 -224.737422)
		(width 0.09525)
		(layer "In11.Cu")
		(net "M_L_CPU0_SA_DQS_DN<0>")
	)
	(arc
		(start 391.521188 -226.318572)
		(mid 391.701579 -226.116873)
		(end 391.766806 -225.85426)
		(width 0.09525)
		(layer "In11.Cu")
		(net "M_L_CPU0_SA_DQS_DN<0>")
	)
	(arc
		(start 390.453372 -227.149152)
		(mid 390.734804 -227.224907)
		(end 391.016236 -227.149152)
		(width 0.09525)
		(layer "In11.Cu")
		(net "M_L_CPU0_SA_DQS_DN<0>")
	)
	(arc
		(start 393.405868 -223.076262)
		(mid 393.407394 -223.075248)
		(end 393.408916 -223.07423)
		(width 0.09525)
		(layer "In11.Cu")
		(net "M_L_CPU0_SA_DQS_DN<0>")
	)
	(arc
		(start 391.054336 -227.127054)
		(mid 391.232786 -226.925584)
		(end 391.29716 -226.664266)
		(width 0.09525)
		(layer "In11.Cu")
		(net "M_L_CPU0_SA_DQS_DN<0>")
	)
	(arc
		(start 387.633464 -227.149152)
		(mid 387.914896 -227.224907)
		(end 388.196328 -227.149152)
		(width 0.09525)
		(layer "In11.Cu")
		(net "M_L_CPU0_SA_DQS_DN<0>")
	)
	(arc
		(start 390.076182 -227.149152)
		(mid 390.259957 -227.09838)
		(end 390.44499 -227.144326)
		(width 0.09525)
		(layer "In11.Cu")
		(net "M_L_CPU0_SA_DQS_DN<0>")
	)
	(arc
		(start 392.70686 -224.234248)
		(mid 392.747736 -224.063226)
		(end 392.861546 -223.929194)
		(width 0.09525)
		(layer "In11.Cu")
		(net "M_L_CPU0_SA_DQS_DN<0>")
	)
	(arc
		(start 391.29716 -226.664266)
		(mid 391.338825 -226.491819)
		(end 391.45464 -226.357434)
		(width 0.09525)
		(layer "In11.Cu")
		(net "M_L_CPU0_SA_DQS_DN<0>")
	)
	(arc
		(start 387.314186 -227.121974)
		(mid 387.476868 -227.099842)
		(end 387.633464 -227.149152)
		(width 0.09525)
		(layer "In11.Cu")
		(net "M_L_CPU0_SA_DQS_DN<0>")
	)
	(arc
		(start 392.462766 -224.697798)
		(mid 392.642138 -224.496203)
		(end 392.70686 -224.234248)
		(width 0.09525)
		(layer "In11.Cu")
		(net "M_L_CPU0_SA_DQS_DN<0>")
	)
	(arc
		(start 393.409678 -223.073722)
		(mid 393.506788 -222.986469)
		(end 393.581128 -222.879158)
		(width 0.09525)
		(layer "In11.Cu")
		(net "M_L_CPU0_SA_DQS_DN<0>")
	)
	(segment
		(start 385.098036 -230.97998)
		(end 385.564888 -230.714296)
		(width 0.10668)
		(layer "F.Cu")
		(net "M_L_CPU0_SA_DQ<9>")
	)
	(segment
		(start 428.291244 -208.810098)
		(end 430.343056 -207.960214)
		(width 0.14478)
		(layer "In11.Cu")
		(net "M_L_CPU0_SA_DQ<9>")
	)
	(segment
		(start 391.01776 -231.036622)
		(end 391.026142 -231.041448)
		(width 0.0889)
		(layer "In11.Cu")
		(net "M_L_CPU0_SA_DQ<9>")
	)
	(segment
		(start 432.588924 -207.960214)
		(end 434.64099 -208.810098)
		(width 0.14478)
		(layer "In11.Cu")
		(net "M_L_CPU0_SA_DQ<9>")
	)
	(segment
		(start 394.357098 -227.890832)
		(end 394.594334 -227.890832)
		(width 0.0889)
		(layer "In11.Cu")
		(net "M_L_CPU0_SA_DQ<9>")
	)
	(segment
		(start 408.039062 -212.400388)
		(end 408.039062 -211.37372)
		(width 0.14478)
		(layer "In11.Cu")
		(net "M_L_CPU0_SA_DQ<9>")
	)
	(segment
		(start 441.800488 -208.810098)
		(end 443.436248 -208.810098)
		(width 0.14478)
		(layer "In11.Cu")
		(net "M_L_CPU0_SA_DQ<9>")
	)
	(segment
		(start 398.887442 -223.597724)
		(end 398.887442 -221.552008)
		(width 0.14478)
		(layer "In11.Cu")
		(net "M_L_CPU0_SA_DQ<9>")
	)
	(segment
		(start 388.197852 -231.036622)
		(end 388.206234 -231.041448)
		(width 0.0889)
		(layer "In11.Cu")
		(net "M_L_CPU0_SA_DQ<9>")
	)
	(segment
		(start 427.106588 -208.810098)
		(end 428.291244 -208.810098)
		(width 0.14478)
		(layer "In11.Cu")
		(net "M_L_CPU0_SA_DQ<9>")
	)
	(segment
		(start 440.950604 -207.960214)
		(end 441.800488 -208.810098)
		(width 0.14478)
		(layer "In11.Cu")
		(net "M_L_CPU0_SA_DQ<9>")
	)
	(segment
		(start 430.343056 -207.960214)
		(end 432.588924 -207.960214)
		(width 0.14478)
		(layer "In11.Cu")
		(net "M_L_CPU0_SA_DQ<9>")
	)
	(segment
		(start 387.257798 -231.036622)
		(end 387.26618 -231.041448)
		(width 0.0889)
		(layer "In11.Cu")
		(net "M_L_CPU0_SA_DQ<9>")
	)
	(segment
		(start 420.971726 -208.810098)
		(end 423.023538 -207.960214)
		(width 0.14478)
		(layer "In11.Cu")
		(net "M_L_CPU0_SA_DQ<9>")
	)
	(segment
		(start 419.057582 -208.810098)
		(end 420.971726 -208.810098)
		(width 0.14478)
		(layer "In11.Cu")
		(net "M_L_CPU0_SA_DQ<9>")
	)
	(segment
		(start 392.285728 -230.960422)
		(end 393.904978 -229.341172)
		(width 0.0889)
		(layer "In11.Cu")
		(net "M_L_CPU0_SA_DQ<9>")
	)
	(segment
		(start 393.904978 -229.341172)
		(end 393.904978 -228.342952)
		(width 0.0889)
		(layer "In11.Cu")
		(net "M_L_CPU0_SA_DQ<9>")
	)
	(segment
		(start 390.443466 -231.041448)
		(end 390.451848 -231.036622)
		(width 0.0889)
		(layer "In11.Cu")
		(net "M_L_CPU0_SA_DQ<9>")
	)
	(segment
		(start 423.023538 -207.960214)
		(end 425.054776 -207.960214)
		(width 0.14478)
		(layer "In11.Cu")
		(net "M_L_CPU0_SA_DQ<9>")
	)
	(segment
		(start 385.564888 -230.714296)
		(end 385.718812 -230.979726)
		(width 0.0889)
		(layer "In11.Cu")
		(net "M_L_CPU0_SA_DQ<9>")
	)
	(segment
		(start 414.706562 -207.960214)
		(end 418.207698 -207.960214)
		(width 0.14478)
		(layer "In11.Cu")
		(net "M_L_CPU0_SA_DQ<9>")
	)
	(segment
		(start 452.050912 -207.960214)
		(end 454.188068 -208.385156)
		(width 0.14478)
		(layer "In11.Cu")
		(net "M_L_CPU0_SA_DQ<9>")
	)
	(segment
		(start 418.207698 -207.960214)
		(end 419.057582 -208.810098)
		(width 0.14478)
		(layer "In11.Cu")
		(net "M_L_CPU0_SA_DQ<9>")
	)
	(segment
		(start 385.718812 -230.979726)
		(end 385.81457 -231.005126)
		(width 0.0889)
		(layer "In11.Cu")
		(net "M_L_CPU0_SA_DQ<9>")
	)
	(segment
		(start 410.602684 -208.810098)
		(end 413.856678 -208.810098)
		(width 0.14478)
		(layer "In11.Cu")
		(net "M_L_CPU0_SA_DQ<9>")
	)
	(segment
		(start 394.594334 -227.890832)
		(end 395.485366 -226.9998)
		(width 0.0889)
		(layer "In11.Cu")
		(net "M_L_CPU0_SA_DQ<9>")
	)
	(segment
		(start 425.054776 -207.960214)
		(end 427.106588 -208.810098)
		(width 0.14478)
		(layer "In11.Cu")
		(net "M_L_CPU0_SA_DQ<9>")
	)
	(segment
		(start 413.856678 -208.810098)
		(end 414.706562 -207.960214)
		(width 0.14478)
		(layer "In11.Cu")
		(net "M_L_CPU0_SA_DQ<9>")
	)
	(segment
		(start 438.035192 -207.960214)
		(end 440.950604 -207.960214)
		(width 0.14478)
		(layer "In11.Cu")
		(net "M_L_CPU0_SA_DQ<9>")
	)
	(segment
		(start 398.887442 -221.552008)
		(end 408.039062 -212.400388)
		(width 0.14478)
		(layer "In11.Cu")
		(net "M_L_CPU0_SA_DQ<9>")
	)
	(segment
		(start 408.039062 -211.37372)
		(end 410.602684 -208.810098)
		(width 0.14478)
		(layer "In11.Cu")
		(net "M_L_CPU0_SA_DQ<9>")
	)
	(segment
		(start 443.436248 -208.810098)
		(end 445.488314 -207.960214)
		(width 0.14478)
		(layer "In11.Cu")
		(net "M_L_CPU0_SA_DQ<9>")
	)
	(segment
		(start 395.485366 -226.9998)
		(end 398.887442 -223.597724)
		(width 0.14478)
		(layer "In11.Cu")
		(net "M_L_CPU0_SA_DQ<9>")
	)
	(segment
		(start 434.64099 -208.810098)
		(end 435.98338 -208.810098)
		(width 0.14478)
		(layer "In11.Cu")
		(net "M_L_CPU0_SA_DQ<9>")
	)
	(segment
		(start 435.98338 -208.810098)
		(end 438.035192 -207.960214)
		(width 0.14478)
		(layer "In11.Cu")
		(net "M_L_CPU0_SA_DQ<9>")
	)
	(segment
		(start 393.904978 -228.342952)
		(end 394.357098 -227.890832)
		(width 0.0889)
		(layer "In11.Cu")
		(net "M_L_CPU0_SA_DQ<9>")
	)
	(segment
		(start 391.391902 -231.036622)
		(end 391.402316 -231.030526)
		(width 0.0889)
		(layer "In11.Cu")
		(net "M_L_CPU0_SA_DQ<9>")
	)
	(segment
		(start 445.488314 -207.960214)
		(end 452.050912 -207.960214)
		(width 0.14478)
		(layer "In11.Cu")
		(net "M_L_CPU0_SA_DQ<9>")
	)
	(segment
		(start 386.683504 -231.041448)
		(end 386.691886 -231.036622)
		(width 0.0889)
		(layer "In11.Cu")
		(net "M_L_CPU0_SA_DQ<9>")
	)
	(segment
		(start 391.672318 -230.960422)
		(end 392.285728 -230.960422)
		(width 0.0889)
		(layer "In11.Cu")
		(net "M_L_CPU0_SA_DQ<9>")
	)
	(arc
		(start 386.317744 -231.036622)
		(mid 386.499995 -231.087006)
		(end 386.683504 -231.041448)
		(width 0.0889)
		(layer "In11.Cu")
		(net "M_L_CPU0_SA_DQ<9>")
	)
	(arc
		(start 386.691886 -231.036622)
		(mid 386.974842 -230.960445)
		(end 387.257798 -231.036622)
		(width 0.0889)
		(layer "In11.Cu")
		(net "M_L_CPU0_SA_DQ<9>")
	)
	(arc
		(start 388.206234 -231.041448)
		(mid 388.389742 -231.086973)
		(end 388.571994 -231.036622)
		(width 0.0889)
		(layer "In11.Cu")
		(net "M_L_CPU0_SA_DQ<9>")
	)
	(arc
		(start 390.451848 -231.036622)
		(mid 390.734804 -230.960445)
		(end 391.01776 -231.036622)
		(width 0.0889)
		(layer "In11.Cu")
		(net "M_L_CPU0_SA_DQ<9>")
	)
	(arc
		(start 387.26618 -231.041448)
		(mid 387.449688 -231.086973)
		(end 387.63194 -231.036622)
		(width 0.0889)
		(layer "In11.Cu")
		(net "M_L_CPU0_SA_DQ<9>")
	)
	(arc
		(start 389.511794 -231.036622)
		(mid 389.79475 -230.960445)
		(end 390.077706 -231.036622)
		(width 0.0889)
		(layer "In11.Cu")
		(net "M_L_CPU0_SA_DQ<9>")
	)
	(arc
		(start 387.63194 -231.036622)
		(mid 387.914896 -230.960445)
		(end 388.197852 -231.036622)
		(width 0.0889)
		(layer "In11.Cu")
		(net "M_L_CPU0_SA_DQ<9>")
	)
	(arc
		(start 388.571994 -231.036622)
		(mid 388.85495 -230.960445)
		(end 389.137906 -231.036622)
		(width 0.0889)
		(layer "In11.Cu")
		(net "M_L_CPU0_SA_DQ<9>")
	)
	(arc
		(start 390.077706 -231.036622)
		(mid 390.259957 -231.087006)
		(end 390.443466 -231.041448)
		(width 0.0889)
		(layer "In11.Cu")
		(net "M_L_CPU0_SA_DQ<9>")
	)
	(arc
		(start 385.81457 -231.005126)
		(mid 386.069892 -230.961426)
		(end 386.317744 -231.036622)
		(width 0.0889)
		(layer "In11.Cu")
		(net "M_L_CPU0_SA_DQ<9>")
	)
	(arc
		(start 391.402316 -231.030526)
		(mid 391.53291 -230.978495)
		(end 391.672318 -230.960422)
		(width 0.0889)
		(layer "In11.Cu")
		(net "M_L_CPU0_SA_DQ<9>")
	)
	(arc
		(start 389.137906 -231.036622)
		(mid 389.32485 -231.086911)
		(end 389.511794 -231.036622)
		(width 0.0889)
		(layer "In11.Cu")
		(net "M_L_CPU0_SA_DQ<9>")
	)
	(arc
		(start 391.026142 -231.041448)
		(mid 391.20965 -231.086973)
		(end 391.391902 -231.036622)
		(width 0.0889)
		(layer "In11.Cu")
		(net "M_L_CPU0_SA_DQ<9>")
	)
	(segment
		(start 386.50799 -230.169974)
		(end 386.974842 -229.904036)
		(width 0.10668)
		(layer "F.Cu")
		(net "M_L_CPU0_SA_DQ<8>")
	)
	(segment
		(start 413.760666 -207.110076)
		(end 414.61055 -206.260192)
		(width 0.14478)
		(layer "In11.Cu")
		(net "M_L_CPU0_SA_DQ<8>")
	)
	(segment
		(start 418.927788 -207.110076)
		(end 421.538908 -207.110076)
		(width 0.14478)
		(layer "In11.Cu")
		(net "M_L_CPU0_SA_DQ<8>")
	)
	(segment
		(start 393.978638 -227.677472)
		(end 393.978638 -226.641152)
		(width 0.0889)
		(layer "In11.Cu")
		(net "M_L_CPU0_SA_DQ<8>")
	)
	(segment
		(start 386.974842 -229.904036)
		(end 387.128766 -230.169466)
		(width 0.0889)
		(layer "In11.Cu")
		(net "M_L_CPU0_SA_DQ<8>")
	)
	(segment
		(start 389.607806 -230.226616)
		(end 389.616188 -230.231442)
		(width 0.0889)
		(layer "In11.Cu")
		(net "M_L_CPU0_SA_DQ<8>")
	)
	(segment
		(start 421.538908 -207.110076)
		(end 422.388792 -206.260192)
		(width 0.14478)
		(layer "In11.Cu")
		(net "M_L_CPU0_SA_DQ<8>")
	)
	(segment
		(start 429.787304 -206.260192)
		(end 433.190904 -206.260192)
		(width 0.14478)
		(layer "In11.Cu")
		(net "M_L_CPU0_SA_DQ<8>")
	)
	(segment
		(start 394.930884 -226.267772)
		(end 395.73454 -225.464116)
		(width 0.0889)
		(layer "In11.Cu")
		(net "M_L_CPU0_SA_DQ<8>")
	)
	(segment
		(start 393.450318 -229.239572)
		(end 393.450318 -228.205792)
		(width 0.0889)
		(layer "In11.Cu")
		(net "M_L_CPU0_SA_DQ<8>")
	)
	(segment
		(start 428.93742 -207.110076)
		(end 429.787304 -206.260192)
		(width 0.14478)
		(layer "In11.Cu")
		(net "M_L_CPU0_SA_DQ<8>")
	)
	(segment
		(start 440.676284 -206.260192)
		(end 441.526168 -207.110076)
		(width 0.14478)
		(layer "In11.Cu")
		(net "M_L_CPU0_SA_DQ<8>")
	)
	(segment
		(start 411.01645 -207.110076)
		(end 413.760666 -207.110076)
		(width 0.14478)
		(layer "In11.Cu")
		(net "M_L_CPU0_SA_DQ<8>")
	)
	(segment
		(start 397.949674 -223.248982)
		(end 397.949674 -221.20352)
		(width 0.14478)
		(layer "In11.Cu")
		(net "M_L_CPU0_SA_DQ<8>")
	)
	(segment
		(start 443.487048 -207.110076)
		(end 445.53886 -206.260192)
		(width 0.14478)
		(layer "In11.Cu")
		(net "M_L_CPU0_SA_DQ<8>")
	)
	(segment
		(start 433.190904 -206.260192)
		(end 434.040788 -207.110076)
		(width 0.14478)
		(layer "In11.Cu")
		(net "M_L_CPU0_SA_DQ<8>")
	)
	(segment
		(start 437.463184 -206.260192)
		(end 440.676284 -206.260192)
		(width 0.14478)
		(layer "In11.Cu")
		(net "M_L_CPU0_SA_DQ<8>")
	)
	(segment
		(start 414.61055 -206.260192)
		(end 418.077904 -206.260192)
		(width 0.14478)
		(layer "In11.Cu")
		(net "M_L_CPU0_SA_DQ<8>")
	)
	(segment
		(start 392.00709 -230.167688)
		(end 393.098528 -229.591362)
		(width 0.0889)
		(layer "In11.Cu")
		(net "M_L_CPU0_SA_DQ<8>")
	)
	(segment
		(start 422.388792 -206.260192)
		(end 425.912534 -206.260192)
		(width 0.14478)
		(layer "In11.Cu")
		(net "M_L_CPU0_SA_DQ<8>")
	)
	(segment
		(start 436.6133 -207.110076)
		(end 437.463184 -206.260192)
		(width 0.14478)
		(layer "In11.Cu")
		(net "M_L_CPU0_SA_DQ<8>")
	)
	(segment
		(start 434.040788 -207.110076)
		(end 436.6133 -207.110076)
		(width 0.14478)
		(layer "In11.Cu")
		(net "M_L_CPU0_SA_DQ<8>")
	)
	(segment
		(start 389.033512 -230.231442)
		(end 389.041894 -230.226616)
		(width 0.0889)
		(layer "In11.Cu")
		(net "M_L_CPU0_SA_DQ<8>")
	)
	(segment
		(start 403.624542 -215.528652)
		(end 403.624542 -214.501984)
		(width 0.14478)
		(layer "In11.Cu")
		(net "M_L_CPU0_SA_DQ<8>")
	)
	(segment
		(start 397.949674 -221.20352)
		(end 403.624542 -215.528652)
		(width 0.14478)
		(layer "In11.Cu")
		(net "M_L_CPU0_SA_DQ<8>")
	)
	(segment
		(start 452.051674 -206.260192)
		(end 454.188068 -206.685134)
		(width 0.14478)
		(layer "In11.Cu")
		(net "M_L_CPU0_SA_DQ<8>")
	)
	(segment
		(start 441.526168 -207.110076)
		(end 443.487048 -207.110076)
		(width 0.14478)
		(layer "In11.Cu")
		(net "M_L_CPU0_SA_DQ<8>")
	)
	(segment
		(start 387.128766 -230.169466)
		(end 387.224778 -230.194866)
		(width 0.0889)
		(layer "In11.Cu")
		(net "M_L_CPU0_SA_DQ<8>")
	)
	(segment
		(start 388.093458 -230.231442)
		(end 388.10184 -230.226616)
		(width 0.0889)
		(layer "In11.Cu")
		(net "M_L_CPU0_SA_DQ<8>")
	)
	(segment
		(start 425.912534 -206.260192)
		(end 426.762418 -207.110076)
		(width 0.14478)
		(layer "In11.Cu")
		(net "M_L_CPU0_SA_DQ<8>")
	)
	(segment
		(start 393.098528 -229.591362)
		(end 393.450318 -229.239572)
		(width 0.0889)
		(layer "In11.Cu")
		(net "M_L_CPU0_SA_DQ<8>")
	)
	(segment
		(start 418.077904 -206.260192)
		(end 418.927788 -207.110076)
		(width 0.14478)
		(layer "In11.Cu")
		(net "M_L_CPU0_SA_DQ<8>")
	)
	(segment
		(start 393.450318 -228.205792)
		(end 393.978638 -227.677472)
		(width 0.0889)
		(layer "In11.Cu")
		(net "M_L_CPU0_SA_DQ<8>")
	)
	(segment
		(start 403.624542 -214.501984)
		(end 411.01645 -207.110076)
		(width 0.14478)
		(layer "In11.Cu")
		(net "M_L_CPU0_SA_DQ<8>")
	)
	(segment
		(start 394.352018 -226.267772)
		(end 394.930884 -226.267772)
		(width 0.0889)
		(layer "In11.Cu")
		(net "M_L_CPU0_SA_DQ<8>")
	)
	(segment
		(start 426.762418 -207.110076)
		(end 428.93742 -207.110076)
		(width 0.14478)
		(layer "In11.Cu")
		(net "M_L_CPU0_SA_DQ<8>")
	)
	(segment
		(start 445.53886 -206.260192)
		(end 452.051674 -206.260192)
		(width 0.14478)
		(layer "In11.Cu")
		(net "M_L_CPU0_SA_DQ<8>")
	)
	(segment
		(start 395.73454 -225.464116)
		(end 397.949674 -223.248982)
		(width 0.14478)
		(layer "In11.Cu")
		(net "M_L_CPU0_SA_DQ<8>")
	)
	(segment
		(start 391.849864 -230.233474)
		(end 391.861548 -230.226616)
		(width 0.0889)
		(layer "In11.Cu")
		(net "M_L_CPU0_SA_DQ<8>")
	)
	(segment
		(start 393.978638 -226.641152)
		(end 394.352018 -226.267772)
		(width 0.0889)
		(layer "In11.Cu")
		(net "M_L_CPU0_SA_DQ<8>")
	)
	(arc
		(start 388.10184 -230.226616)
		(mid 388.384796 -230.150473)
		(end 388.667752 -230.226616)
		(width 0.0889)
		(layer "In11.Cu")
		(net "M_L_CPU0_SA_DQ<8>")
	)
	(arc
		(start 389.616188 -230.231442)
		(mid 389.799696 -230.276936)
		(end 389.981948 -230.226616)
		(width 0.0889)
		(layer "In11.Cu")
		(net "M_L_CPU0_SA_DQ<8>")
	)
	(arc
		(start 387.727698 -230.226616)
		(mid 387.909949 -230.276966)
		(end 388.093458 -230.231442)
		(width 0.0889)
		(layer "In11.Cu")
		(net "M_L_CPU0_SA_DQ<8>")
	)
	(arc
		(start 389.981948 -230.226616)
		(mid 390.264904 -230.150473)
		(end 390.54786 -230.226616)
		(width 0.0889)
		(layer "In11.Cu")
		(net "M_L_CPU0_SA_DQ<8>")
	)
	(arc
		(start 389.041894 -230.226616)
		(mid 389.32485 -230.150473)
		(end 389.607806 -230.226616)
		(width 0.0889)
		(layer "In11.Cu")
		(net "M_L_CPU0_SA_DQ<8>")
	)
	(arc
		(start 390.54786 -230.226616)
		(mid 390.734804 -230.276871)
		(end 390.921748 -230.226616)
		(width 0.0889)
		(layer "In11.Cu")
		(net "M_L_CPU0_SA_DQ<8>")
	)
	(arc
		(start 388.667752 -230.226616)
		(mid 388.850003 -230.276966)
		(end 389.033512 -230.231442)
		(width 0.0889)
		(layer "In11.Cu")
		(net "M_L_CPU0_SA_DQ<8>")
	)
	(arc
		(start 391.48766 -230.226616)
		(mid 391.667865 -230.276933)
		(end 391.849864 -230.233474)
		(width 0.0889)
		(layer "In11.Cu")
		(net "M_L_CPU0_SA_DQ<8>")
	)
	(arc
		(start 391.861548 -230.226616)
		(mid 391.93226 -230.192067)
		(end 392.00709 -230.167688)
		(width 0.0889)
		(layer "In11.Cu")
		(net "M_L_CPU0_SA_DQ<8>")
	)
	(arc
		(start 387.224778 -230.194866)
		(mid 387.479986 -230.151409)
		(end 387.727698 -230.226616)
		(width 0.0889)
		(layer "In11.Cu")
		(net "M_L_CPU0_SA_DQ<8>")
	)
	(arc
		(start 390.921748 -230.226616)
		(mid 391.204704 -230.150473)
		(end 391.48766 -230.226616)
		(width 0.0889)
		(layer "In11.Cu")
		(net "M_L_CPU0_SA_DQ<8>")
	)
	(segment
		(start 385.567936 -230.169974)
		(end 386.034788 -229.904036)
		(width 0.10668)
		(layer "F.Cu")
		(net "M_L_CPU0_SA_DQ<7>")
	)
	(segment
		(start 385.880864 -229.638606)
		(end 385.903216 -229.555548)
		(width 0.0889)
		(layer "In11.Cu")
		(net "M_L_CPU0_SA_DQ<7>")
	)
	(segment
		(start 400.67484 -216.612724)
		(end 400.837908 -216.449656)
		(width 0.14478)
		(layer "In11.Cu")
		(net "M_L_CPU0_SA_DQ<7>")
	)
	(segment
		(start 398.22755 -219.907866)
		(end 398.458182 -219.907866)
		(width 0.14478)
		(layer "In11.Cu")
		(net "M_L_CPU0_SA_DQ<7>")
	)
	(segment
		(start 433.190904 -205.410308)
		(end 434.040788 -206.260192)
		(width 0.14478)
		(layer "In11.Cu")
		(net "M_L_CPU0_SA_DQ<7>")
	)
	(segment
		(start 419.25494 -206.260192)
		(end 421.43426 -206.260192)
		(width 0.14478)
		(layer "In11.Cu")
		(net "M_L_CPU0_SA_DQ<7>")
	)
	(segment
		(start 398.70634 -218.811856)
		(end 399.01495 -219.120466)
		(width 0.14478)
		(layer "In11.Cu")
		(net "M_L_CPU0_SA_DQ<7>")
	)
	(segment
		(start 397.83385 -220.532198)
		(end 397.83385 -220.301566)
		(width 0.14478)
		(layer "In11.Cu")
		(net "M_L_CPU0_SA_DQ<7>")
	)
	(segment
		(start 399.88744 -217.630756)
		(end 399.88744 -217.400124)
		(width 0.14478)
		(layer "In11.Cu")
		(net "M_L_CPU0_SA_DQ<7>")
	)
	(segment
		(start 399.263108 -218.024456)
		(end 399.49374 -218.024456)
		(width 0.14478)
		(layer "In11.Cu")
		(net "M_L_CPU0_SA_DQ<7>")
	)
	(segment
		(start 399.01495 -219.120466)
		(end 399.245582 -219.120466)
		(width 0.14478)
		(layer "In11.Cu")
		(net "M_L_CPU0_SA_DQ<7>")
	)
	(segment
		(start 411.079188 -206.260192)
		(end 413.531304 -206.260192)
		(width 0.14478)
		(layer "In11.Cu")
		(net "M_L_CPU0_SA_DQ<7>")
	)
	(segment
		(start 403.068282 -214.271098)
		(end 411.079188 -206.260192)
		(width 0.14478)
		(layer "In11.Cu")
		(net "M_L_CPU0_SA_DQ<7>")
	)
	(segment
		(start 398.62125 -219.744798)
		(end 398.62125 -219.514166)
		(width 0.14478)
		(layer "In11.Cu")
		(net "M_L_CPU0_SA_DQ<7>")
	)
	(segment
		(start 401.06854 -216.449656)
		(end 401.37715 -216.758266)
		(width 0.14478)
		(layer "In11.Cu")
		(net "M_L_CPU0_SA_DQ<7>")
	)
	(segment
		(start 400.050508 -217.237056)
		(end 400.28114 -217.237056)
		(width 0.14478)
		(layer "In11.Cu")
		(net "M_L_CPU0_SA_DQ<7>")
	)
	(segment
		(start 397.83385 -220.301566)
		(end 397.52524 -219.992956)
		(width 0.14478)
		(layer "In11.Cu")
		(net "M_L_CPU0_SA_DQ<7>")
	)
	(segment
		(start 397.52524 -219.992956)
		(end 397.52524 -219.762324)
		(width 0.14478)
		(layer "In11.Cu")
		(net "M_L_CPU0_SA_DQ<7>")
	)
	(segment
		(start 426.762418 -206.260192)
		(end 428.846996 -206.260192)
		(width 0.14478)
		(layer "In11.Cu")
		(net "M_L_CPU0_SA_DQ<7>")
	)
	(segment
		(start 443.982856 -206.260192)
		(end 444.83274 -205.410308)
		(width 0.14478)
		(layer "In11.Cu")
		(net "M_L_CPU0_SA_DQ<7>")
	)
	(segment
		(start 393.234418 -228.147372)
		(end 393.772898 -227.608892)
		(width 0.0889)
		(layer "In11.Cu")
		(net "M_L_CPU0_SA_DQ<7>")
	)
	(segment
		(start 399.88744 -217.400124)
		(end 400.050508 -217.237056)
		(width 0.14478)
		(layer "In11.Cu")
		(net "M_L_CPU0_SA_DQ<7>")
	)
	(segment
		(start 437.463184 -205.410308)
		(end 440.635644 -205.410308)
		(width 0.14478)
		(layer "In11.Cu")
		(net "M_L_CPU0_SA_DQ<7>")
	)
	(segment
		(start 400.67484 -216.843356)
		(end 400.67484 -216.612724)
		(width 0.14478)
		(layer "In11.Cu")
		(net "M_L_CPU0_SA_DQ<7>")
	)
	(segment
		(start 397.383254 -220.982794)
		(end 397.83385 -220.532198)
		(width 0.14478)
		(layer "In11.Cu")
		(net "M_L_CPU0_SA_DQ<7>")
	)
	(segment
		(start 398.31264 -218.974924)
		(end 398.475708 -218.811856)
		(width 0.14478)
		(layer "In11.Cu")
		(net "M_L_CPU0_SA_DQ<7>")
	)
	(segment
		(start 388.093458 -229.576884)
		(end 388.10184 -229.58171)
		(width 0.0889)
		(layer "In11.Cu")
		(net "M_L_CPU0_SA_DQ<7>")
	)
	(segment
		(start 386.034788 -229.904036)
		(end 385.880864 -229.638606)
		(width 0.0889)
		(layer "In11.Cu")
		(net "M_L_CPU0_SA_DQ<7>")
	)
	(segment
		(start 400.837908 -216.449656)
		(end 401.06854 -216.449656)
		(width 0.14478)
		(layer "In11.Cu")
		(net "M_L_CPU0_SA_DQ<7>")
	)
	(segment
		(start 394.679678 -226.003612)
		(end 395.195298 -225.487992)
		(width 0.0889)
		(layer "In11.Cu")
		(net "M_L_CPU0_SA_DQ<7>")
	)
	(segment
		(start 399.40865 -218.726766)
		(end 399.10004 -218.418156)
		(width 0.14478)
		(layer "In11.Cu")
		(net "M_L_CPU0_SA_DQ<7>")
	)
	(segment
		(start 400.98345 -217.382598)
		(end 400.98345 -217.151966)
		(width 0.14478)
		(layer "In11.Cu")
		(net "M_L_CPU0_SA_DQ<7>")
	)
	(segment
		(start 444.83274 -205.410308)
		(end 449.663312 -205.410308)
		(width 0.14478)
		(layer "In11.Cu")
		(net "M_L_CPU0_SA_DQ<7>")
	)
	(segment
		(start 436.6133 -206.260192)
		(end 437.463184 -205.410308)
		(width 0.14478)
		(layer "In11.Cu")
		(net "M_L_CPU0_SA_DQ<7>")
	)
	(segment
		(start 422.284144 -205.410308)
		(end 425.912534 -205.410308)
		(width 0.14478)
		(layer "In11.Cu")
		(net "M_L_CPU0_SA_DQ<7>")
	)
	(segment
		(start 393.772898 -226.531932)
		(end 394.301218 -226.003612)
		(width 0.0889)
		(layer "In11.Cu")
		(net "M_L_CPU0_SA_DQ<7>")
	)
	(segment
		(start 403.068282 -215.297766)
		(end 403.068282 -214.271098)
		(width 0.14478)
		(layer "In11.Cu")
		(net "M_L_CPU0_SA_DQ<7>")
	)
	(segment
		(start 397.91894 -219.599256)
		(end 398.22755 -219.907866)
		(width 0.14478)
		(layer "In11.Cu")
		(net "M_L_CPU0_SA_DQ<7>")
	)
	(segment
		(start 401.607782 -216.758266)
		(end 403.068282 -215.297766)
		(width 0.14478)
		(layer "In11.Cu")
		(net "M_L_CPU0_SA_DQ<7>")
	)
	(segment
		(start 395.195298 -225.487992)
		(end 395.195298 -225.216466)
		(width 0.0889)
		(layer "In11.Cu")
		(net "M_L_CPU0_SA_DQ<7>")
	)
	(segment
		(start 399.40865 -218.957398)
		(end 399.40865 -218.726766)
		(width 0.14478)
		(layer "In11.Cu")
		(net "M_L_CPU0_SA_DQ<7>")
	)
	(segment
		(start 429.69688 -205.410308)
		(end 433.190904 -205.410308)
		(width 0.14478)
		(layer "In11.Cu")
		(net "M_L_CPU0_SA_DQ<7>")
	)
	(segment
		(start 414.381442 -205.410054)
		(end 418.404802 -205.410054)
		(width 0.14478)
		(layer "In11.Cu")
		(net "M_L_CPU0_SA_DQ<7>")
	)
	(segment
		(start 395.195298 -225.216466)
		(end 395.782038 -224.629726)
		(width 0.0889)
		(layer "In11.Cu")
		(net "M_L_CPU0_SA_DQ<7>")
	)
	(segment
		(start 400.28114 -217.237056)
		(end 400.58975 -217.545666)
		(width 0.14478)
		(layer "In11.Cu")
		(net "M_L_CPU0_SA_DQ<7>")
	)
	(segment
		(start 400.19605 -218.169998)
		(end 400.19605 -217.939366)
		(width 0.14478)
		(layer "In11.Cu")
		(net "M_L_CPU0_SA_DQ<7>")
	)
	(segment
		(start 389.033512 -229.576884)
		(end 389.041894 -229.58171)
		(width 0.0889)
		(layer "In11.Cu")
		(net "M_L_CPU0_SA_DQ<7>")
	)
	(segment
		(start 428.846996 -206.260192)
		(end 429.69688 -205.410308)
		(width 0.14478)
		(layer "In11.Cu")
		(net "M_L_CPU0_SA_DQ<7>")
	)
	(segment
		(start 391.674858 -229.53091)
		(end 392.04138 -229.53091)
		(width 0.0889)
		(layer "In11.Cu")
		(net "M_L_CPU0_SA_DQ<7>")
	)
	(segment
		(start 398.475708 -218.811856)
		(end 398.70634 -218.811856)
		(width 0.14478)
		(layer "In11.Cu")
		(net "M_L_CPU0_SA_DQ<7>")
	)
	(segment
		(start 397.383254 -223.02851)
		(end 397.383254 -220.982794)
		(width 0.14478)
		(layer "In11.Cu")
		(net "M_L_CPU0_SA_DQ<7>")
	)
	(segment
		(start 394.301218 -226.003612)
		(end 394.679678 -226.003612)
		(width 0.0889)
		(layer "In11.Cu")
		(net "M_L_CPU0_SA_DQ<7>")
	)
	(segment
		(start 401.37715 -216.758266)
		(end 401.607782 -216.758266)
		(width 0.14478)
		(layer "In11.Cu")
		(net "M_L_CPU0_SA_DQ<7>")
	)
	(segment
		(start 413.531304 -206.260192)
		(end 414.381442 -205.410054)
		(width 0.14478)
		(layer "In11.Cu")
		(net "M_L_CPU0_SA_DQ<7>")
	)
	(segment
		(start 421.43426 -206.260192)
		(end 422.284144 -205.410308)
		(width 0.14478)
		(layer "In11.Cu")
		(net "M_L_CPU0_SA_DQ<7>")
	)
	(segment
		(start 395.782038 -224.629726)
		(end 397.383254 -223.02851)
		(width 0.14478)
		(layer "In11.Cu")
		(net "M_L_CPU0_SA_DQ<7>")
	)
	(segment
		(start 440.635644 -205.410308)
		(end 441.485528 -206.260192)
		(width 0.14478)
		(layer "In11.Cu")
		(net "M_L_CPU0_SA_DQ<7>")
	)
	(segment
		(start 434.040788 -206.260192)
		(end 436.6133 -206.260192)
		(width 0.14478)
		(layer "In11.Cu")
		(net "M_L_CPU0_SA_DQ<7>")
	)
	(segment
		(start 399.245582 -219.120466)
		(end 399.40865 -218.957398)
		(width 0.14478)
		(layer "In11.Cu")
		(net "M_L_CPU0_SA_DQ<7>")
	)
	(segment
		(start 397.688308 -219.599256)
		(end 397.91894 -219.599256)
		(width 0.14478)
		(layer "In11.Cu")
		(net "M_L_CPU0_SA_DQ<7>")
	)
	(segment
		(start 399.49374 -218.024456)
		(end 399.80235 -218.333066)
		(width 0.14478)
		(layer "In11.Cu")
		(net "M_L_CPU0_SA_DQ<7>")
	)
	(segment
		(start 397.52524 -219.762324)
		(end 397.688308 -219.599256)
		(width 0.14478)
		(layer "In11.Cu")
		(net "M_L_CPU0_SA_DQ<7>")
	)
	(segment
		(start 400.032982 -218.333066)
		(end 400.19605 -218.169998)
		(width 0.14478)
		(layer "In11.Cu")
		(net "M_L_CPU0_SA_DQ<7>")
	)
	(segment
		(start 399.10004 -218.187524)
		(end 399.263108 -218.024456)
		(width 0.14478)
		(layer "In11.Cu")
		(net "M_L_CPU0_SA_DQ<7>")
	)
	(segment
		(start 393.234418 -228.337872)
		(end 393.234418 -228.147372)
		(width 0.0889)
		(layer "In11.Cu")
		(net "M_L_CPU0_SA_DQ<7>")
	)
	(segment
		(start 418.404802 -205.410054)
		(end 419.25494 -206.260192)
		(width 0.14478)
		(layer "In11.Cu")
		(net "M_L_CPU0_SA_DQ<7>")
	)
	(segment
		(start 449.663312 -205.410308)
		(end 450.088 -205.834996)
		(width 0.14478)
		(layer "In11.Cu")
		(net "M_L_CPU0_SA_DQ<7>")
	)
	(segment
		(start 400.58975 -217.545666)
		(end 400.820382 -217.545666)
		(width 0.14478)
		(layer "In11.Cu")
		(net "M_L_CPU0_SA_DQ<7>")
	)
	(segment
		(start 441.485528 -206.260192)
		(end 443.982856 -206.260192)
		(width 0.14478)
		(layer "In11.Cu")
		(net "M_L_CPU0_SA_DQ<7>")
	)
	(segment
		(start 400.98345 -217.151966)
		(end 400.67484 -216.843356)
		(width 0.14478)
		(layer "In11.Cu")
		(net "M_L_CPU0_SA_DQ<7>")
	)
	(segment
		(start 393.772898 -227.608892)
		(end 393.772898 -226.531932)
		(width 0.0889)
		(layer "In11.Cu")
		(net "M_L_CPU0_SA_DQ<7>")
	)
	(segment
		(start 392.04138 -229.53091)
		(end 393.234418 -228.337872)
		(width 0.0889)
		(layer "In11.Cu")
		(net "M_L_CPU0_SA_DQ<7>")
	)
	(segment
		(start 400.820382 -217.545666)
		(end 400.98345 -217.382598)
		(width 0.14478)
		(layer "In11.Cu")
		(net "M_L_CPU0_SA_DQ<7>")
	)
	(segment
		(start 400.19605 -217.939366)
		(end 399.88744 -217.630756)
		(width 0.14478)
		(layer "In11.Cu")
		(net "M_L_CPU0_SA_DQ<7>")
	)
	(segment
		(start 389.607806 -229.58171)
		(end 389.616188 -229.576884)
		(width 0.0889)
		(layer "In11.Cu")
		(net "M_L_CPU0_SA_DQ<7>")
	)
	(segment
		(start 425.912534 -205.410308)
		(end 426.762418 -206.260192)
		(width 0.14478)
		(layer "In11.Cu")
		(net "M_L_CPU0_SA_DQ<7>")
	)
	(segment
		(start 399.80235 -218.333066)
		(end 400.032982 -218.333066)
		(width 0.14478)
		(layer "In11.Cu")
		(net "M_L_CPU0_SA_DQ<7>")
	)
	(segment
		(start 398.31264 -219.205556)
		(end 398.31264 -218.974924)
		(width 0.14478)
		(layer "In11.Cu")
		(net "M_L_CPU0_SA_DQ<7>")
	)
	(segment
		(start 398.62125 -219.514166)
		(end 398.31264 -219.205556)
		(width 0.14478)
		(layer "In11.Cu")
		(net "M_L_CPU0_SA_DQ<7>")
	)
	(segment
		(start 399.10004 -218.418156)
		(end 399.10004 -218.187524)
		(width 0.14478)
		(layer "In11.Cu")
		(net "M_L_CPU0_SA_DQ<7>")
	)
	(segment
		(start 398.458182 -219.907866)
		(end 398.62125 -219.744798)
		(width 0.14478)
		(layer "In11.Cu")
		(net "M_L_CPU0_SA_DQ<7>")
	)
	(arc
		(start 386.221986 -229.58171)
		(mid 386.504942 -229.657887)
		(end 386.787898 -229.58171)
		(width 0.0889)
		(layer "In11.Cu")
		(net "M_L_CPU0_SA_DQ<7>")
	)
	(arc
		(start 388.10184 -229.58171)
		(mid 388.384796 -229.657887)
		(end 388.667752 -229.58171)
		(width 0.0889)
		(layer "In11.Cu")
		(net "M_L_CPU0_SA_DQ<7>")
	)
	(arc
		(start 390.921748 -229.58171)
		(mid 391.204704 -229.657887)
		(end 391.48766 -229.58171)
		(width 0.0889)
		(layer "In11.Cu")
		(net "M_L_CPU0_SA_DQ<7>")
	)
	(arc
		(start 389.616188 -229.576884)
		(mid 389.799696 -229.531359)
		(end 389.981948 -229.58171)
		(width 0.0889)
		(layer "In11.Cu")
		(net "M_L_CPU0_SA_DQ<7>")
	)
	(arc
		(start 389.981948 -229.58171)
		(mid 390.264904 -229.657887)
		(end 390.54786 -229.58171)
		(width 0.0889)
		(layer "In11.Cu")
		(net "M_L_CPU0_SA_DQ<7>")
	)
	(arc
		(start 387.161786 -229.58171)
		(mid 387.444742 -229.657887)
		(end 387.727698 -229.58171)
		(width 0.0889)
		(layer "In11.Cu")
		(net "M_L_CPU0_SA_DQ<7>")
	)
	(arc
		(start 385.903216 -229.555548)
		(mid 386.065548 -229.532714)
		(end 386.221986 -229.58171)
		(width 0.0889)
		(layer "In11.Cu")
		(net "M_L_CPU0_SA_DQ<7>")
	)
	(arc
		(start 388.667752 -229.58171)
		(mid 388.850003 -229.531326)
		(end 389.033512 -229.576884)
		(width 0.0889)
		(layer "In11.Cu")
		(net "M_L_CPU0_SA_DQ<7>")
	)
	(arc
		(start 391.48766 -229.58171)
		(mid 391.577896 -229.543908)
		(end 391.674858 -229.53091)
		(width 0.0889)
		(layer "In11.Cu")
		(net "M_L_CPU0_SA_DQ<7>")
	)
	(arc
		(start 386.787898 -229.58171)
		(mid 386.974842 -229.531421)
		(end 387.161786 -229.58171)
		(width 0.0889)
		(layer "In11.Cu")
		(net "M_L_CPU0_SA_DQ<7>")
	)
	(arc
		(start 387.727698 -229.58171)
		(mid 387.909949 -229.531326)
		(end 388.093458 -229.576884)
		(width 0.0889)
		(layer "In11.Cu")
		(net "M_L_CPU0_SA_DQ<7>")
	)
	(arc
		(start 389.041894 -229.58171)
		(mid 389.32485 -229.657887)
		(end 389.607806 -229.58171)
		(width 0.0889)
		(layer "In11.Cu")
		(net "M_L_CPU0_SA_DQ<7>")
	)
	(arc
		(start 390.54786 -229.58171)
		(mid 390.734804 -229.531421)
		(end 390.921748 -229.58171)
		(width 0.0889)
		(layer "In11.Cu")
		(net "M_L_CPU0_SA_DQ<7>")
	)
	(segment
		(start 386.97789 -229.360222)
		(end 387.444742 -229.094284)
		(width 0.10668)
		(layer "F.Cu")
		(net "M_L_CPU0_SA_DQ<6>")
	)
	(segment
		(start 399.450306 -216.32037)
		(end 399.07972 -215.949784)
		(width 0.14478)
		(layer "In11.Cu")
		(net "M_L_CPU0_SA_DQ<6>")
	)
	(segment
		(start 413.88792 -204.56017)
		(end 414.738058 -203.710032)
		(width 0.14478)
		(layer "In11.Cu")
		(net "M_L_CPU0_SA_DQ<6>")
	)
	(segment
		(start 391.690098 -228.84765)
		(end 391.99058 -228.84765)
		(width 0.0889)
		(layer "In11.Cu")
		(net "M_L_CPU0_SA_DQ<6>")
	)
	(segment
		(start 425.912534 -203.710286)
		(end 426.762418 -204.56017)
		(width 0.14478)
		(layer "In11.Cu")
		(net "M_L_CPU0_SA_DQ<6>")
	)
	(segment
		(start 399.450052 -216.551002)
		(end 399.450306 -216.32037)
		(width 0.14478)
		(layer "In11.Cu")
		(net "M_L_CPU0_SA_DQ<6>")
	)
	(segment
		(start 400.631152 -215.13927)
		(end 400.861784 -215.13927)
		(width 0.14478)
		(layer "In11.Cu")
		(net "M_L_CPU0_SA_DQ<6>")
	)
	(segment
		(start 400.861784 -215.13927)
		(end 411.440884 -204.56017)
		(width 0.14478)
		(layer "In11.Cu")
		(net "M_L_CPU0_SA_DQ<6>")
	)
	(segment
		(start 397.088106 -218.68257)
		(end 396.71752 -218.311984)
		(width 0.14478)
		(layer "In11.Cu")
		(net "M_L_CPU0_SA_DQ<6>")
	)
	(segment
		(start 393.673838 -226.05619)
		(end 393.673838 -225.284792)
		(width 0.0889)
		(layer "In11.Cu")
		(net "M_L_CPU0_SA_DQ<6>")
	)
	(segment
		(start 397.712184 -218.28887)
		(end 397.875252 -218.125802)
		(width 0.14478)
		(layer "In11.Cu")
		(net "M_L_CPU0_SA_DQ<6>")
	)
	(segment
		(start 437.463184 -203.710286)
		(end 440.538108 -203.710286)
		(width 0.14478)
		(layer "In11.Cu")
		(net "M_L_CPU0_SA_DQ<6>")
	)
	(segment
		(start 392.734038 -228.104192)
		(end 392.734038 -226.99599)
		(width 0.0889)
		(layer "In11.Cu")
		(net "M_L_CPU0_SA_DQ<6>")
	)
	(segment
		(start 391.99058 -228.84765)
		(end 392.734038 -228.104192)
		(width 0.0889)
		(layer "In11.Cu")
		(net "M_L_CPU0_SA_DQ<6>")
	)
	(segment
		(start 426.762418 -204.56017)
		(end 429.005492 -204.56017)
		(width 0.14478)
		(layer "In11.Cu")
		(net "M_L_CPU0_SA_DQ<6>")
	)
	(segment
		(start 400.237706 -215.53297)
		(end 399.86712 -215.162384)
		(width 0.14478)
		(layer "In11.Cu")
		(net "M_L_CPU0_SA_DQ<6>")
	)
	(segment
		(start 388.197852 -228.771704)
		(end 388.206234 -228.766878)
		(width 0.0889)
		(layer "In11.Cu")
		(net "M_L_CPU0_SA_DQ<6>")
	)
	(segment
		(start 398.662906 -217.10777)
		(end 398.29232 -216.737184)
		(width 0.14478)
		(layer "In11.Cu")
		(net "M_L_CPU0_SA_DQ<6>")
	)
	(segment
		(start 399.07972 -215.949784)
		(end 399.07972 -215.719152)
		(width 0.14478)
		(layer "In11.Cu")
		(net "M_L_CPU0_SA_DQ<6>")
	)
	(segment
		(start 387.444742 -229.094284)
		(end 387.290818 -228.828854)
		(width 0.0889)
		(layer "In11.Cu")
		(net "M_L_CPU0_SA_DQ<6>")
	)
	(segment
		(start 398.662652 -217.338402)
		(end 398.662906 -217.10777)
		(width 0.14478)
		(layer "In11.Cu")
		(net "M_L_CPU0_SA_DQ<6>")
	)
	(segment
		(start 398.268952 -217.50147)
		(end 398.499584 -217.50147)
		(width 0.14478)
		(layer "In11.Cu")
		(net "M_L_CPU0_SA_DQ<6>")
	)
	(segment
		(start 394.079222 -224.879408)
		(end 394.582396 -224.543112)
		(width 0.0889)
		(layer "In11.Cu")
		(net "M_L_CPU0_SA_DQ<6>")
	)
	(segment
		(start 433.190904 -203.710286)
		(end 434.040788 -204.56017)
		(width 0.14478)
		(layer "In11.Cu")
		(net "M_L_CPU0_SA_DQ<6>")
	)
	(segment
		(start 392.734038 -226.99599)
		(end 393.673838 -226.05619)
		(width 0.0889)
		(layer "In11.Cu")
		(net "M_L_CPU0_SA_DQ<6>")
	)
	(segment
		(start 434.040788 -204.56017)
		(end 436.6133 -204.56017)
		(width 0.14478)
		(layer "In11.Cu")
		(net "M_L_CPU0_SA_DQ<6>")
	)
	(segment
		(start 399.473166 -215.556084)
		(end 399.843752 -215.92667)
		(width 0.14478)
		(layer "In11.Cu")
		(net "M_L_CPU0_SA_DQ<6>")
	)
	(segment
		(start 397.481552 -218.28887)
		(end 397.712184 -218.28887)
		(width 0.14478)
		(layer "In11.Cu")
		(net "M_L_CPU0_SA_DQ<6>")
	)
	(segment
		(start 387.290818 -228.828854)
		(end 387.31317 -228.745542)
		(width 0.0889)
		(layer "In11.Cu")
		(net "M_L_CPU0_SA_DQ<6>")
	)
	(segment
		(start 398.455642 -216.34323)
		(end 398.685766 -216.343484)
		(width 0.14478)
		(layer "In11.Cu")
		(net "M_L_CPU0_SA_DQ<6>")
	)
	(segment
		(start 419.076124 -204.56017)
		(end 421.446452 -204.56017)
		(width 0.14478)
		(layer "In11.Cu")
		(net "M_L_CPU0_SA_DQ<6>")
	)
	(segment
		(start 399.07972 -215.719152)
		(end 399.243042 -215.55583)
		(width 0.14478)
		(layer "In11.Cu")
		(net "M_L_CPU0_SA_DQ<6>")
	)
	(segment
		(start 399.286984 -216.71407)
		(end 399.450052 -216.551002)
		(width 0.14478)
		(layer "In11.Cu")
		(net "M_L_CPU0_SA_DQ<6>")
	)
	(segment
		(start 397.875506 -217.89517)
		(end 397.50492 -217.524584)
		(width 0.14478)
		(layer "In11.Cu")
		(net "M_L_CPU0_SA_DQ<6>")
	)
	(segment
		(start 397.087852 -218.913202)
		(end 397.088106 -218.68257)
		(width 0.14478)
		(layer "In11.Cu")
		(net "M_L_CPU0_SA_DQ<6>")
	)
	(segment
		(start 396.71752 -218.081352)
		(end 396.880842 -217.91803)
		(width 0.14478)
		(layer "In11.Cu")
		(net "M_L_CPU0_SA_DQ<6>")
	)
	(segment
		(start 418.225986 -203.710032)
		(end 419.076124 -204.56017)
		(width 0.14478)
		(layer "In11.Cu")
		(net "M_L_CPU0_SA_DQ<6>")
	)
	(segment
		(start 441.387992 -204.56017)
		(end 444.20282 -204.56017)
		(width 0.14478)
		(layer "In11.Cu")
		(net "M_L_CPU0_SA_DQ<6>")
	)
	(segment
		(start 399.86712 -215.162384)
		(end 399.86712 -214.931752)
		(width 0.14478)
		(layer "In11.Cu")
		(net "M_L_CPU0_SA_DQ<6>")
	)
	(segment
		(start 391.01776 -228.771704)
		(end 391.026142 -228.766878)
		(width 0.0889)
		(layer "In11.Cu")
		(net "M_L_CPU0_SA_DQ<6>")
	)
	(segment
		(start 396.71752 -218.311984)
		(end 396.71752 -218.081352)
		(width 0.14478)
		(layer "In11.Cu")
		(net "M_L_CPU0_SA_DQ<6>")
	)
	(segment
		(start 397.50492 -217.524584)
		(end 397.50492 -217.293952)
		(width 0.14478)
		(layer "In11.Cu")
		(net "M_L_CPU0_SA_DQ<6>")
	)
	(segment
		(start 397.898366 -217.130884)
		(end 398.268952 -217.50147)
		(width 0.14478)
		(layer "In11.Cu")
		(net "M_L_CPU0_SA_DQ<6>")
	)
	(segment
		(start 445.052704 -203.710286)
		(end 449.663312 -203.710286)
		(width 0.14478)
		(layer "In11.Cu")
		(net "M_L_CPU0_SA_DQ<6>")
	)
	(segment
		(start 393.673838 -225.284792)
		(end 394.079222 -224.879408)
		(width 0.0889)
		(layer "In11.Cu")
		(net "M_L_CPU0_SA_DQ<6>")
	)
	(segment
		(start 436.6133 -204.56017)
		(end 437.463184 -203.710286)
		(width 0.14478)
		(layer "In11.Cu")
		(net "M_L_CPU0_SA_DQ<6>")
	)
	(segment
		(start 400.074384 -215.92667)
		(end 400.237452 -215.763602)
		(width 0.14478)
		(layer "In11.Cu")
		(net "M_L_CPU0_SA_DQ<6>")
	)
	(segment
		(start 400.237452 -215.763602)
		(end 400.237706 -215.53297)
		(width 0.14478)
		(layer "In11.Cu")
		(net "M_L_CPU0_SA_DQ<6>")
	)
	(segment
		(start 397.668242 -217.13063)
		(end 397.898366 -217.130884)
		(width 0.14478)
		(layer "In11.Cu")
		(net "M_L_CPU0_SA_DQ<6>")
	)
	(segment
		(start 399.056352 -216.71407)
		(end 399.286984 -216.71407)
		(width 0.14478)
		(layer "In11.Cu")
		(net "M_L_CPU0_SA_DQ<6>")
	)
	(segment
		(start 429.855376 -203.710286)
		(end 433.190904 -203.710286)
		(width 0.14478)
		(layer "In11.Cu")
		(net "M_L_CPU0_SA_DQ<6>")
	)
	(segment
		(start 397.50492 -217.293952)
		(end 397.668242 -217.13063)
		(width 0.14478)
		(layer "In11.Cu")
		(net "M_L_CPU0_SA_DQ<6>")
	)
	(segment
		(start 398.685766 -216.343484)
		(end 399.056352 -216.71407)
		(width 0.14478)
		(layer "In11.Cu")
		(net "M_L_CPU0_SA_DQ<6>")
	)
	(segment
		(start 399.843752 -215.92667)
		(end 400.074384 -215.92667)
		(width 0.14478)
		(layer "In11.Cu")
		(net "M_L_CPU0_SA_DQ<6>")
	)
	(segment
		(start 440.538108 -203.710286)
		(end 441.387992 -204.56017)
		(width 0.14478)
		(layer "In11.Cu")
		(net "M_L_CPU0_SA_DQ<6>")
	)
	(segment
		(start 449.663312 -203.710286)
		(end 450.088 -204.134974)
		(width 0.14478)
		(layer "In11.Cu")
		(net "M_L_CPU0_SA_DQ<6>")
	)
	(segment
		(start 398.29232 -216.737184)
		(end 398.29232 -216.506552)
		(width 0.14478)
		(layer "In11.Cu")
		(net "M_L_CPU0_SA_DQ<6>")
	)
	(segment
		(start 414.738058 -203.710032)
		(end 418.225986 -203.710032)
		(width 0.14478)
		(layer "In11.Cu")
		(net "M_L_CPU0_SA_DQ<6>")
	)
	(segment
		(start 396.363698 -222.76181)
		(end 396.363698 -219.637356)
		(width 0.14478)
		(layer "In11.Cu")
		(net "M_L_CPU0_SA_DQ<6>")
	)
	(segment
		(start 395.701774 -223.423734)
		(end 396.363698 -222.76181)
		(width 0.14478)
		(layer "In11.Cu")
		(net "M_L_CPU0_SA_DQ<6>")
	)
	(segment
		(start 400.260566 -214.768684)
		(end 400.631152 -215.13927)
		(width 0.14478)
		(layer "In11.Cu")
		(net "M_L_CPU0_SA_DQ<6>")
	)
	(segment
		(start 399.243042 -215.55583)
		(end 399.473166 -215.556084)
		(width 0.14478)
		(layer "In11.Cu")
		(net "M_L_CPU0_SA_DQ<6>")
	)
	(segment
		(start 422.296336 -203.710286)
		(end 425.912534 -203.710286)
		(width 0.14478)
		(layer "In11.Cu")
		(net "M_L_CPU0_SA_DQ<6>")
	)
	(segment
		(start 394.582396 -224.543112)
		(end 395.701774 -223.423734)
		(width 0.0889)
		(layer "In11.Cu")
		(net "M_L_CPU0_SA_DQ<6>")
	)
	(segment
		(start 398.29232 -216.506552)
		(end 398.455642 -216.34323)
		(width 0.14478)
		(layer "In11.Cu")
		(net "M_L_CPU0_SA_DQ<6>")
	)
	(segment
		(start 397.875252 -218.125802)
		(end 397.875506 -217.89517)
		(width 0.14478)
		(layer "In11.Cu")
		(net "M_L_CPU0_SA_DQ<6>")
	)
	(segment
		(start 396.363698 -219.637356)
		(end 397.087852 -218.913202)
		(width 0.14478)
		(layer "In11.Cu")
		(net "M_L_CPU0_SA_DQ<6>")
	)
	(segment
		(start 390.443466 -228.766878)
		(end 390.451848 -228.771704)
		(width 0.0889)
		(layer "In11.Cu")
		(net "M_L_CPU0_SA_DQ<6>")
	)
	(segment
		(start 411.440884 -204.56017)
		(end 413.88792 -204.56017)
		(width 0.14478)
		(layer "In11.Cu")
		(net "M_L_CPU0_SA_DQ<6>")
	)
	(segment
		(start 429.005492 -204.56017)
		(end 429.855376 -203.710286)
		(width 0.14478)
		(layer "In11.Cu")
		(net "M_L_CPU0_SA_DQ<6>")
	)
	(segment
		(start 400.030442 -214.76843)
		(end 400.260566 -214.768684)
		(width 0.14478)
		(layer "In11.Cu")
		(net "M_L_CPU0_SA_DQ<6>")
	)
	(segment
		(start 397.110966 -217.918284)
		(end 397.481552 -218.28887)
		(width 0.14478)
		(layer "In11.Cu")
		(net "M_L_CPU0_SA_DQ<6>")
	)
	(segment
		(start 399.86712 -214.931752)
		(end 400.030442 -214.76843)
		(width 0.14478)
		(layer "In11.Cu")
		(net "M_L_CPU0_SA_DQ<6>")
	)
	(segment
		(start 444.20282 -204.56017)
		(end 445.052704 -203.710286)
		(width 0.14478)
		(layer "In11.Cu")
		(net "M_L_CPU0_SA_DQ<6>")
	)
	(segment
		(start 396.880842 -217.91803)
		(end 397.110966 -217.918284)
		(width 0.14478)
		(layer "In11.Cu")
		(net "M_L_CPU0_SA_DQ<6>")
	)
	(segment
		(start 421.446452 -204.56017)
		(end 422.296336 -203.710286)
		(width 0.14478)
		(layer "In11.Cu")
		(net "M_L_CPU0_SA_DQ<6>")
	)
	(segment
		(start 398.499584 -217.50147)
		(end 398.662652 -217.338402)
		(width 0.14478)
		(layer "In11.Cu")
		(net "M_L_CPU0_SA_DQ<6>")
	)
	(arc
		(start 388.571994 -228.771704)
		(mid 388.85495 -228.847881)
		(end 389.137906 -228.771704)
		(width 0.0889)
		(layer "In11.Cu")
		(net "M_L_CPU0_SA_DQ<6>")
	)
	(arc
		(start 389.137906 -228.771704)
		(mid 389.32485 -228.721449)
		(end 389.511794 -228.771704)
		(width 0.0889)
		(layer "In11.Cu")
		(net "M_L_CPU0_SA_DQ<6>")
	)
	(arc
		(start 391.026142 -228.766878)
		(mid 391.20965 -228.721384)
		(end 391.391902 -228.771704)
		(width 0.0889)
		(layer "In11.Cu")
		(net "M_L_CPU0_SA_DQ<6>")
	)
	(arc
		(start 387.63194 -228.771704)
		(mid 387.914896 -228.847881)
		(end 388.197852 -228.771704)
		(width 0.0889)
		(layer "In11.Cu")
		(net "M_L_CPU0_SA_DQ<6>")
	)
	(arc
		(start 389.511794 -228.771704)
		(mid 389.79475 -228.847881)
		(end 390.077706 -228.771704)
		(width 0.0889)
		(layer "In11.Cu")
		(net "M_L_CPU0_SA_DQ<6>")
	)
	(arc
		(start 390.077706 -228.771704)
		(mid 390.259957 -228.721354)
		(end 390.443466 -228.766878)
		(width 0.0889)
		(layer "In11.Cu")
		(net "M_L_CPU0_SA_DQ<6>")
	)
	(arc
		(start 390.451848 -228.771704)
		(mid 390.734804 -228.847881)
		(end 391.01776 -228.771704)
		(width 0.0889)
		(layer "In11.Cu")
		(net "M_L_CPU0_SA_DQ<6>")
	)
	(arc
		(start 388.206234 -228.766878)
		(mid 388.389742 -228.721384)
		(end 388.571994 -228.771704)
		(width 0.0889)
		(layer "In11.Cu")
		(net "M_L_CPU0_SA_DQ<6>")
	)
	(arc
		(start 387.31317 -228.745542)
		(mid 387.475502 -228.722724)
		(end 387.63194 -228.771704)
		(width 0.0889)
		(layer "In11.Cu")
		(net "M_L_CPU0_SA_DQ<6>")
	)
	(arc
		(start 391.391902 -228.771704)
		(mid 391.535715 -228.830435)
		(end 391.690098 -228.84765)
		(width 0.0889)
		(layer "In11.Cu")
		(net "M_L_CPU0_SA_DQ<6>")
	)
	(segment
		(start 385.098036 -229.360222)
		(end 385.564888 -229.094284)
		(width 0.10668)
		(layer "F.Cu")
		(net "M_L_CPU0_SA_DQ<5>")
	)
	(segment
		(start 452.030846 -204.56017)
		(end 452.193914 -204.723238)
		(width 0.14478)
		(layer "In11.Cu")
		(net "M_L_CPU0_SA_DQ<5>")
	)
	(segment
		(start 387.257798 -229.41661)
		(end 387.26618 -229.421436)
		(width 0.0889)
		(layer "In11.Cu")
		(net "M_L_CPU0_SA_DQ<5>")
	)
	(segment
		(start 421.45966 -205.410054)
		(end 422.309544 -204.56017)
		(width 0.14478)
		(layer "In11.Cu")
		(net "M_L_CPU0_SA_DQ<5>")
	)
	(segment
		(start 452.356982 -205.42631)
		(end 452.58736 -205.42631)
		(width 0.14478)
		(layer "In11.Cu")
		(net "M_L_CPU0_SA_DQ<5>")
	)
	(segment
		(start 394.353288 -225.67773)
		(end 394.591286 -225.67773)
		(width 0.0889)
		(layer "In11.Cu")
		(net "M_L_CPU0_SA_DQ<5>")
	)
	(segment
		(start 422.309544 -204.56017)
		(end 425.912534 -204.56017)
		(width 0.14478)
		(layer "In11.Cu")
		(net "M_L_CPU0_SA_DQ<5>")
	)
	(segment
		(start 394.591286 -225.67773)
		(end 394.903198 -225.365818)
		(width 0.0889)
		(layer "In11.Cu")
		(net "M_L_CPU0_SA_DQ<5>")
	)
	(segment
		(start 433.190904 -204.56017)
		(end 434.040788 -205.410054)
		(width 0.14478)
		(layer "In11.Cu")
		(net "M_L_CPU0_SA_DQ<5>")
	)
	(segment
		(start 392.947398 -228.355398)
		(end 392.947398 -228.134672)
		(width 0.0889)
		(layer "In11.Cu")
		(net "M_L_CPU0_SA_DQ<5>")
	)
	(segment
		(start 413.685482 -205.410054)
		(end 414.535366 -204.56017)
		(width 0.14478)
		(layer "In11.Cu")
		(net "M_L_CPU0_SA_DQ<5>")
	)
	(segment
		(start 444.063882 -205.408784)
		(end 444.912496 -204.56017)
		(width 0.14478)
		(layer "In11.Cu")
		(net "M_L_CPU0_SA_DQ<5>")
	)
	(segment
		(start 440.602116 -204.56017)
		(end 441.45073 -205.408784)
		(width 0.14478)
		(layer "In11.Cu")
		(net "M_L_CPU0_SA_DQ<5>")
	)
	(segment
		(start 452.193914 -204.723238)
		(end 452.193914 -205.263242)
		(width 0.14478)
		(layer "In11.Cu")
		(net "M_L_CPU0_SA_DQ<5>")
	)
	(segment
		(start 452.913496 -204.56017)
		(end 453.763126 -204.56017)
		(width 0.14478)
		(layer "In11.Cu")
		(net "M_L_CPU0_SA_DQ<5>")
	)
	(segment
		(start 452.750428 -205.263242)
		(end 452.750428 -204.723238)
		(width 0.14478)
		(layer "In11.Cu")
		(net "M_L_CPU0_SA_DQ<5>")
	)
	(segment
		(start 393.514834 -227.567236)
		(end 393.514834 -226.516184)
		(width 0.0889)
		(layer "In11.Cu")
		(net "M_L_CPU0_SA_DQ<5>")
	)
	(segment
		(start 411.234128 -205.410054)
		(end 413.685482 -205.410054)
		(width 0.14478)
		(layer "In11.Cu")
		(net "M_L_CPU0_SA_DQ<5>")
	)
	(segment
		(start 429.791876 -204.56017)
		(end 433.190904 -204.56017)
		(width 0.14478)
		(layer "In11.Cu")
		(net "M_L_CPU0_SA_DQ<5>")
	)
	(segment
		(start 390.443466 -229.421436)
		(end 390.451848 -229.41661)
		(width 0.0889)
		(layer "In11.Cu")
		(net "M_L_CPU0_SA_DQ<5>")
	)
	(segment
		(start 452.193914 -205.263242)
		(end 452.356982 -205.42631)
		(width 0.14478)
		(layer "In11.Cu")
		(net "M_L_CPU0_SA_DQ<5>")
	)
	(segment
		(start 392.947398 -228.134672)
		(end 393.514834 -227.567236)
		(width 0.0889)
		(layer "In11.Cu")
		(net "M_L_CPU0_SA_DQ<5>")
	)
	(segment
		(start 391.01776 -229.41661)
		(end 391.026142 -229.421436)
		(width 0.0889)
		(layer "In11.Cu")
		(net "M_L_CPU0_SA_DQ<5>")
	)
	(segment
		(start 385.718812 -229.359714)
		(end 385.81457 -229.385114)
		(width 0.0889)
		(layer "In11.Cu")
		(net "M_L_CPU0_SA_DQ<5>")
	)
	(segment
		(start 394.903198 -225.365818)
		(end 394.903198 -224.865692)
		(width 0.0889)
		(layer "In11.Cu")
		(net "M_L_CPU0_SA_DQ<5>")
	)
	(segment
		(start 441.45073 -205.408784)
		(end 444.063882 -205.408784)
		(width 0.14478)
		(layer "In11.Cu")
		(net "M_L_CPU0_SA_DQ<5>")
	)
	(segment
		(start 388.197852 -229.41661)
		(end 388.206234 -229.421436)
		(width 0.0889)
		(layer "In11.Cu")
		(net "M_L_CPU0_SA_DQ<5>")
	)
	(segment
		(start 396.881604 -219.762578)
		(end 411.234128 -205.410054)
		(width 0.14478)
		(layer "In11.Cu")
		(net "M_L_CPU0_SA_DQ<5>")
	)
	(segment
		(start 393.514834 -226.516184)
		(end 394.353288 -225.67773)
		(width 0.0889)
		(layer "In11.Cu")
		(net "M_L_CPU0_SA_DQ<5>")
	)
	(segment
		(start 425.912534 -204.56017)
		(end 426.762418 -205.410054)
		(width 0.14478)
		(layer "In11.Cu")
		(net "M_L_CPU0_SA_DQ<5>")
	)
	(segment
		(start 394.903198 -224.865692)
		(end 395.731746 -224.037144)
		(width 0.0889)
		(layer "In11.Cu")
		(net "M_L_CPU0_SA_DQ<5>")
	)
	(segment
		(start 418.331396 -204.56017)
		(end 419.18128 -205.410054)
		(width 0.14478)
		(layer "In11.Cu")
		(net "M_L_CPU0_SA_DQ<5>")
	)
	(segment
		(start 452.750428 -204.723238)
		(end 452.913496 -204.56017)
		(width 0.14478)
		(layer "In11.Cu")
		(net "M_L_CPU0_SA_DQ<5>")
	)
	(segment
		(start 444.912496 -204.56017)
		(end 452.030846 -204.56017)
		(width 0.14478)
		(layer "In11.Cu")
		(net "M_L_CPU0_SA_DQ<5>")
	)
	(segment
		(start 391.674604 -229.34041)
		(end 391.962386 -229.34041)
		(width 0.0889)
		(layer "In11.Cu")
		(net "M_L_CPU0_SA_DQ<5>")
	)
	(segment
		(start 453.763126 -204.56017)
		(end 454.188068 -204.985112)
		(width 0.14478)
		(layer "In11.Cu")
		(net "M_L_CPU0_SA_DQ<5>")
	)
	(segment
		(start 386.683504 -229.421436)
		(end 386.691886 -229.41661)
		(width 0.0889)
		(layer "In11.Cu")
		(net "M_L_CPU0_SA_DQ<5>")
	)
	(segment
		(start 426.762418 -205.410054)
		(end 428.941992 -205.410054)
		(width 0.14478)
		(layer "In11.Cu")
		(net "M_L_CPU0_SA_DQ<5>")
	)
	(segment
		(start 452.58736 -205.42631)
		(end 452.750428 -205.263242)
		(width 0.14478)
		(layer "In11.Cu")
		(net "M_L_CPU0_SA_DQ<5>")
	)
	(segment
		(start 434.040788 -205.410054)
		(end 436.6133 -205.410054)
		(width 0.14478)
		(layer "In11.Cu")
		(net "M_L_CPU0_SA_DQ<5>")
	)
	(segment
		(start 436.6133 -205.410054)
		(end 437.463184 -204.56017)
		(width 0.14478)
		(layer "In11.Cu")
		(net "M_L_CPU0_SA_DQ<5>")
	)
	(segment
		(start 428.941992 -205.410054)
		(end 429.791876 -204.56017)
		(width 0.14478)
		(layer "In11.Cu")
		(net "M_L_CPU0_SA_DQ<5>")
	)
	(segment
		(start 396.881604 -222.887286)
		(end 396.881604 -219.762578)
		(width 0.14478)
		(layer "In11.Cu")
		(net "M_L_CPU0_SA_DQ<5>")
	)
	(segment
		(start 395.731746 -224.037144)
		(end 396.881604 -222.887286)
		(width 0.14478)
		(layer "In11.Cu")
		(net "M_L_CPU0_SA_DQ<5>")
	)
	(segment
		(start 419.18128 -205.410054)
		(end 421.45966 -205.410054)
		(width 0.14478)
		(layer "In11.Cu")
		(net "M_L_CPU0_SA_DQ<5>")
	)
	(segment
		(start 391.962386 -229.34041)
		(end 392.947398 -228.355398)
		(width 0.0889)
		(layer "In11.Cu")
		(net "M_L_CPU0_SA_DQ<5>")
	)
	(segment
		(start 437.463184 -204.56017)
		(end 440.602116 -204.56017)
		(width 0.14478)
		(layer "In11.Cu")
		(net "M_L_CPU0_SA_DQ<5>")
	)
	(segment
		(start 385.564888 -229.094284)
		(end 385.718812 -229.359714)
		(width 0.0889)
		(layer "In11.Cu")
		(net "M_L_CPU0_SA_DQ<5>")
	)
	(segment
		(start 414.535366 -204.56017)
		(end 418.331396 -204.56017)
		(width 0.14478)
		(layer "In11.Cu")
		(net "M_L_CPU0_SA_DQ<5>")
	)
	(arc
		(start 386.317744 -229.41661)
		(mid 386.499995 -229.466994)
		(end 386.683504 -229.421436)
		(width 0.0889)
		(layer "In11.Cu")
		(net "M_L_CPU0_SA_DQ<5>")
	)
	(arc
		(start 389.511794 -229.41661)
		(mid 389.79475 -229.340433)
		(end 390.077706 -229.41661)
		(width 0.0889)
		(layer "In11.Cu")
		(net "M_L_CPU0_SA_DQ<5>")
	)
	(arc
		(start 387.26618 -229.421436)
		(mid 387.449688 -229.466961)
		(end 387.63194 -229.41661)
		(width 0.0889)
		(layer "In11.Cu")
		(net "M_L_CPU0_SA_DQ<5>")
	)
	(arc
		(start 389.137906 -229.41661)
		(mid 389.32485 -229.466899)
		(end 389.511794 -229.41661)
		(width 0.0889)
		(layer "In11.Cu")
		(net "M_L_CPU0_SA_DQ<5>")
	)
	(arc
		(start 388.571994 -229.41661)
		(mid 388.85495 -229.340433)
		(end 389.137906 -229.41661)
		(width 0.0889)
		(layer "In11.Cu")
		(net "M_L_CPU0_SA_DQ<5>")
	)
	(arc
		(start 391.026142 -229.421436)
		(mid 391.20965 -229.466961)
		(end 391.391902 -229.41661)
		(width 0.0889)
		(layer "In11.Cu")
		(net "M_L_CPU0_SA_DQ<5>")
	)
	(arc
		(start 390.077706 -229.41661)
		(mid 390.259957 -229.466994)
		(end 390.443466 -229.421436)
		(width 0.0889)
		(layer "In11.Cu")
		(net "M_L_CPU0_SA_DQ<5>")
	)
	(arc
		(start 386.691886 -229.41661)
		(mid 386.974842 -229.340433)
		(end 387.257798 -229.41661)
		(width 0.0889)
		(layer "In11.Cu")
		(net "M_L_CPU0_SA_DQ<5>")
	)
	(arc
		(start 390.451848 -229.41661)
		(mid 390.734804 -229.340433)
		(end 391.01776 -229.41661)
		(width 0.0889)
		(layer "In11.Cu")
		(net "M_L_CPU0_SA_DQ<5>")
	)
	(arc
		(start 391.391902 -229.41661)
		(mid 391.52822 -229.359843)
		(end 391.674604 -229.34041)
		(width 0.0889)
		(layer "In11.Cu")
		(net "M_L_CPU0_SA_DQ<5>")
	)
	(arc
		(start 388.206234 -229.421436)
		(mid 388.389742 -229.466961)
		(end 388.571994 -229.41661)
		(width 0.0889)
		(layer "In11.Cu")
		(net "M_L_CPU0_SA_DQ<5>")
	)
	(arc
		(start 385.81457 -229.385114)
		(mid 386.069892 -229.341414)
		(end 386.317744 -229.41661)
		(width 0.0889)
		(layer "In11.Cu")
		(net "M_L_CPU0_SA_DQ<5>")
	)
	(arc
		(start 387.63194 -229.41661)
		(mid 387.914896 -229.340433)
		(end 388.197852 -229.41661)
		(width 0.0889)
		(layer "In11.Cu")
		(net "M_L_CPU0_SA_DQ<5>")
	)
	(segment
		(start 386.50799 -228.550216)
		(end 386.974842 -228.284278)
		(width 0.10668)
		(layer "F.Cu")
		(net "M_L_CPU0_SA_DQ<4>")
	)
	(segment
		(start 392.526012 -227.942902)
		(end 392.526012 -226.916234)
		(width 0.0889)
		(layer "In11.Cu")
		(net "M_L_CPU0_SA_DQ<4>")
	)
	(segment
		(start 436.603902 -203.71943)
		(end 437.453786 -202.869546)
		(width 0.14478)
		(layer "In11.Cu")
		(net "M_L_CPU0_SA_DQ<4>")
	)
	(segment
		(start 437.453786 -202.869546)
		(end 440.552586 -202.869546)
		(width 0.14478)
		(layer "In11.Cu")
		(net "M_L_CPU0_SA_DQ<4>")
	)
	(segment
		(start 445.13881 -202.869546)
		(end 452.313802 -202.869546)
		(width 0.14478)
		(layer "In11.Cu")
		(net "M_L_CPU0_SA_DQ<4>")
	)
	(segment
		(start 394.369036 -224.456244)
		(end 394.611352 -223.870774)
		(width 0.0889)
		(layer "In11.Cu")
		(net "M_L_CPU0_SA_DQ<4>")
	)
	(segment
		(start 425.845732 -202.869546)
		(end 426.695616 -203.71943)
		(width 0.14478)
		(layer "In11.Cu")
		(net "M_L_CPU0_SA_DQ<4>")
	)
	(segment
		(start 395.53134 -222.950786)
		(end 395.861794 -222.620332)
		(width 0.14478)
		(layer "In11.Cu")
		(net "M_L_CPU0_SA_DQ<4>")
	)
	(segment
		(start 401.044156 -214.31377)
		(end 411.647894 -203.710032)
		(width 0.14478)
		(layer "In11.Cu")
		(net "M_L_CPU0_SA_DQ<4>")
	)
	(segment
		(start 422.381934 -202.869546)
		(end 425.845732 -202.869546)
		(width 0.14478)
		(layer "In11.Cu")
		(net "M_L_CPU0_SA_DQ<4>")
	)
	(segment
		(start 440.552586 -202.869546)
		(end 441.40247 -203.71943)
		(width 0.14478)
		(layer "In11.Cu")
		(net "M_L_CPU0_SA_DQ<4>")
	)
	(segment
		(start 389.607806 -228.606858)
		(end 389.616188 -228.611684)
		(width 0.0889)
		(layer "In11.Cu")
		(net "M_L_CPU0_SA_DQ<4>")
	)
	(segment
		(start 453.023986 -203.023216)
		(end 453.187054 -202.860148)
		(width 0.14478)
		(layer "In11.Cu")
		(net "M_L_CPU0_SA_DQ<4>")
	)
	(segment
		(start 444.288926 -203.71943)
		(end 445.13881 -202.869546)
		(width 0.14478)
		(layer "In11.Cu")
		(net "M_L_CPU0_SA_DQ<4>")
	)
	(segment
		(start 394.611352 -223.870774)
		(end 395.53134 -222.950786)
		(width 0.0889)
		(layer "In11.Cu")
		(net "M_L_CPU0_SA_DQ<4>")
	)
	(segment
		(start 452.860918 -203.67371)
		(end 453.023986 -203.510642)
		(width 0.14478)
		(layer "In11.Cu")
		(net "M_L_CPU0_SA_DQ<4>")
	)
	(segment
		(start 391.862056 -228.606858)
		(end 392.526012 -227.942902)
		(width 0.0889)
		(layer "In11.Cu")
		(net "M_L_CPU0_SA_DQ<4>")
	)
	(segment
		(start 418.963856 -203.71943)
		(end 421.53205 -203.71943)
		(width 0.14478)
		(layer "In11.Cu")
		(net "M_L_CPU0_SA_DQ<4>")
	)
	(segment
		(start 453.763126 -202.860148)
		(end 454.188068 -203.28509)
		(width 0.14478)
		(layer "In11.Cu")
		(net "M_L_CPU0_SA_DQ<4>")
	)
	(segment
		(start 411.647894 -203.710032)
		(end 414.025588 -203.710032)
		(width 0.14478)
		(layer "In11.Cu")
		(net "M_L_CPU0_SA_DQ<4>")
	)
	(segment
		(start 452.467472 -203.510642)
		(end 452.63054 -203.67371)
		(width 0.14478)
		(layer "In11.Cu")
		(net "M_L_CPU0_SA_DQ<4>")
	)
	(segment
		(start 392.526012 -226.916234)
		(end 393.470638 -225.971608)
		(width 0.0889)
		(layer "In11.Cu")
		(net "M_L_CPU0_SA_DQ<4>")
	)
	(segment
		(start 414.866074 -202.869546)
		(end 418.113972 -202.869546)
		(width 0.14478)
		(layer "In11.Cu")
		(net "M_L_CPU0_SA_DQ<4>")
	)
	(segment
		(start 395.861794 -222.620332)
		(end 395.861794 -218.293696)
		(width 0.14478)
		(layer "In11.Cu")
		(net "M_L_CPU0_SA_DQ<4>")
	)
	(segment
		(start 418.113972 -202.869546)
		(end 418.963856 -203.71943)
		(width 0.14478)
		(layer "In11.Cu")
		(net "M_L_CPU0_SA_DQ<4>")
	)
	(segment
		(start 430.002442 -202.869546)
		(end 433.200302 -202.869546)
		(width 0.14478)
		(layer "In11.Cu")
		(net "M_L_CPU0_SA_DQ<4>")
	)
	(segment
		(start 452.63054 -203.67371)
		(end 452.860918 -203.67371)
		(width 0.14478)
		(layer "In11.Cu")
		(net "M_L_CPU0_SA_DQ<4>")
	)
	(segment
		(start 434.050186 -203.71943)
		(end 436.603902 -203.71943)
		(width 0.14478)
		(layer "In11.Cu")
		(net "M_L_CPU0_SA_DQ<4>")
	)
	(segment
		(start 453.023986 -203.510642)
		(end 453.023986 -203.023216)
		(width 0.14478)
		(layer "In11.Cu")
		(net "M_L_CPU0_SA_DQ<4>")
	)
	(segment
		(start 395.861794 -218.293696)
		(end 399.84172 -214.31377)
		(width 0.14478)
		(layer "In11.Cu")
		(net "M_L_CPU0_SA_DQ<4>")
	)
	(segment
		(start 388.093458 -228.611684)
		(end 388.10184 -228.606858)
		(width 0.0889)
		(layer "In11.Cu")
		(net "M_L_CPU0_SA_DQ<4>")
	)
	(segment
		(start 393.470638 -225.971608)
		(end 393.470638 -225.172778)
		(width 0.0889)
		(layer "In11.Cu")
		(net "M_L_CPU0_SA_DQ<4>")
	)
	(segment
		(start 441.40247 -203.71943)
		(end 444.288926 -203.71943)
		(width 0.14478)
		(layer "In11.Cu")
		(net "M_L_CPU0_SA_DQ<4>")
	)
	(segment
		(start 414.025588 -203.710032)
		(end 414.866074 -202.869546)
		(width 0.14478)
		(layer "In11.Cu")
		(net "M_L_CPU0_SA_DQ<4>")
	)
	(segment
		(start 386.974842 -228.284278)
		(end 387.128766 -228.549708)
		(width 0.0889)
		(layer "In11.Cu")
		(net "M_L_CPU0_SA_DQ<4>")
	)
	(segment
		(start 452.467472 -203.023216)
		(end 452.467472 -203.510642)
		(width 0.14478)
		(layer "In11.Cu")
		(net "M_L_CPU0_SA_DQ<4>")
	)
	(segment
		(start 393.470638 -225.172778)
		(end 393.819634 -224.823782)
		(width 0.0889)
		(layer "In11.Cu")
		(net "M_L_CPU0_SA_DQ<4>")
	)
	(segment
		(start 399.84172 -214.31377)
		(end 401.044156 -214.31377)
		(width 0.14478)
		(layer "In11.Cu")
		(net "M_L_CPU0_SA_DQ<4>")
	)
	(segment
		(start 452.313802 -202.869546)
		(end 452.467472 -203.023216)
		(width 0.14478)
		(layer "In11.Cu")
		(net "M_L_CPU0_SA_DQ<4>")
	)
	(segment
		(start 387.128766 -228.549708)
		(end 387.224778 -228.575108)
		(width 0.0889)
		(layer "In11.Cu")
		(net "M_L_CPU0_SA_DQ<4>")
	)
	(segment
		(start 426.695616 -203.71943)
		(end 429.152558 -203.71943)
		(width 0.14478)
		(layer "In11.Cu")
		(net "M_L_CPU0_SA_DQ<4>")
	)
	(segment
		(start 453.187054 -202.860148)
		(end 453.763126 -202.860148)
		(width 0.14478)
		(layer "In11.Cu")
		(net "M_L_CPU0_SA_DQ<4>")
	)
	(segment
		(start 389.033512 -228.611684)
		(end 389.041894 -228.606858)
		(width 0.0889)
		(layer "In11.Cu")
		(net "M_L_CPU0_SA_DQ<4>")
	)
	(segment
		(start 429.152558 -203.71943)
		(end 430.002442 -202.869546)
		(width 0.14478)
		(layer "In11.Cu")
		(net "M_L_CPU0_SA_DQ<4>")
	)
	(segment
		(start 421.53205 -203.71943)
		(end 422.381934 -202.869546)
		(width 0.14478)
		(layer "In11.Cu")
		(net "M_L_CPU0_SA_DQ<4>")
	)
	(segment
		(start 393.819634 -224.823782)
		(end 394.369036 -224.456244)
		(width 0.0889)
		(layer "In11.Cu")
		(net "M_L_CPU0_SA_DQ<4>")
	)
	(segment
		(start 433.200302 -202.869546)
		(end 434.050186 -203.71943)
		(width 0.14478)
		(layer "In11.Cu")
		(net "M_L_CPU0_SA_DQ<4>")
	)
	(arc
		(start 387.224778 -228.575108)
		(mid 387.479986 -228.531631)
		(end 387.727698 -228.606858)
		(width 0.0889)
		(layer "In11.Cu")
		(net "M_L_CPU0_SA_DQ<4>")
	)
	(arc
		(start 389.981948 -228.606858)
		(mid 390.264904 -228.530681)
		(end 390.54786 -228.606858)
		(width 0.0889)
		(layer "In11.Cu")
		(net "M_L_CPU0_SA_DQ<4>")
	)
	(arc
		(start 388.10184 -228.606858)
		(mid 388.384796 -228.530681)
		(end 388.667752 -228.606858)
		(width 0.0889)
		(layer "In11.Cu")
		(net "M_L_CPU0_SA_DQ<4>")
	)
	(arc
		(start 389.616188 -228.611684)
		(mid 389.799696 -228.657178)
		(end 389.981948 -228.606858)
		(width 0.0889)
		(layer "In11.Cu")
		(net "M_L_CPU0_SA_DQ<4>")
	)
	(arc
		(start 389.041894 -228.606858)
		(mid 389.32485 -228.530681)
		(end 389.607806 -228.606858)
		(width 0.0889)
		(layer "In11.Cu")
		(net "M_L_CPU0_SA_DQ<4>")
	)
	(arc
		(start 390.921748 -228.606858)
		(mid 391.204704 -228.530681)
		(end 391.48766 -228.606858)
		(width 0.0889)
		(layer "In11.Cu")
		(net "M_L_CPU0_SA_DQ<4>")
	)
	(arc
		(start 391.48766 -228.606858)
		(mid 391.674858 -228.65724)
		(end 391.862056 -228.606858)
		(width 0.0889)
		(layer "In11.Cu")
		(net "M_L_CPU0_SA_DQ<4>")
	)
	(arc
		(start 390.54786 -228.606858)
		(mid 390.734804 -228.657113)
		(end 390.921748 -228.606858)
		(width 0.0889)
		(layer "In11.Cu")
		(net "M_L_CPU0_SA_DQ<4>")
	)
	(arc
		(start 387.727698 -228.606858)
		(mid 387.909949 -228.657208)
		(end 388.093458 -228.611684)
		(width 0.0889)
		(layer "In11.Cu")
		(net "M_L_CPU0_SA_DQ<4>")
	)
	(arc
		(start 388.667752 -228.606858)
		(mid 388.850003 -228.657208)
		(end 389.033512 -228.611684)
		(width 0.0889)
		(layer "In11.Cu")
		(net "M_L_CPU0_SA_DQ<4>")
	)
	(segment
		(start 385.567936 -226.930204)
		(end 386.034788 -226.664266)
		(width 0.10668)
		(layer "F.Cu")
		(net "M_L_CPU0_SA_DQ<3>")
	)
	(segment
		(start 389.607806 -226.341686)
		(end 389.616188 -226.33686)
		(width 0.0889)
		(layer "In11.Cu")
		(net "M_L_CPU0_SA_DQ<3>")
	)
	(segment
		(start 406.54732 -203.42479)
		(end 406.777952 -203.42479)
		(width 0.14478)
		(layer "In11.Cu")
		(net "M_L_CPU0_SA_DQ<3>")
	)
	(segment
		(start 408.115516 -202.630786)
		(end 408.115516 -202.400154)
		(width 0.14478)
		(layer "In11.Cu")
		(net "M_L_CPU0_SA_DQ<3>")
	)
	(segment
		(start 433.181506 -199.45096)
		(end 434.03139 -200.300844)
		(width 0.14478)
		(layer "In11.Cu")
		(net "M_L_CPU0_SA_DQ<3>")
	)
	(segment
		(start 444.786766 -199.45096)
		(end 449.653914 -199.45096)
		(width 0.14478)
		(layer "In11.Cu")
		(net "M_L_CPU0_SA_DQ<3>")
	)
	(segment
		(start 449.653914 -199.45096)
		(end 450.088 -199.885046)
		(width 0.14478)
		(layer "In11.Cu")
		(net "M_L_CPU0_SA_DQ<3>")
	)
	(segment
		(start 393.024868 -222.217488)
		(end 393.522454 -221.719902)
		(width 0.0889)
		(layer "In11.Cu")
		(net "M_L_CPU0_SA_DQ<3>")
	)
	(segment
		(start 407.952448 -202.793854)
		(end 408.115516 -202.630786)
		(width 0.14478)
		(layer "In11.Cu")
		(net "M_L_CPU0_SA_DQ<3>")
	)
	(segment
		(start 413.913574 -200.309988)
		(end 414.772856 -199.450706)
		(width 0.14478)
		(layer "In11.Cu")
		(net "M_L_CPU0_SA_DQ<3>")
	)
	(segment
		(start 391.01776 -225.53168)
		(end 391.056876 -225.50882)
		(width 0.0889)
		(layer "In11.Cu")
		(net "M_L_CPU0_SA_DQ<3>")
	)
	(segment
		(start 407.328116 -203.418186)
		(end 407.328116 -203.187554)
		(width 0.14478)
		(layer "In11.Cu")
		(net "M_L_CPU0_SA_DQ<3>")
	)
	(segment
		(start 405.596852 -204.375258)
		(end 405.75992 -204.21219)
		(width 0.14478)
		(layer "In11.Cu")
		(net "M_L_CPU0_SA_DQ<3>")
	)
	(segment
		(start 426.805598 -200.30059)
		(end 428.940468 -200.30059)
		(width 0.14478)
		(layer "In11.Cu")
		(net "M_L_CPU0_SA_DQ<3>")
	)
	(segment
		(start 409.140152 -201.06259)
		(end 409.296616 -201.219054)
		(width 0.14478)
		(layer "In11.Cu")
		(net "M_L_CPU0_SA_DQ<3>")
	)
	(segment
		(start 406.384252 -203.81849)
		(end 406.384252 -203.587858)
		(width 0.14478)
		(layer "In11.Cu")
		(net "M_L_CPU0_SA_DQ<3>")
	)
	(segment
		(start 441.947554 -200.300844)
		(end 443.936882 -200.300844)
		(width 0.14478)
		(layer "In11.Cu")
		(net "M_L_CPU0_SA_DQ<3>")
	)
	(segment
		(start 410.436314 -200.309988)
		(end 413.913574 -200.309988)
		(width 0.14478)
		(layer "In11.Cu")
		(net "M_L_CPU0_SA_DQ<3>")
	)
	(segment
		(start 434.03139 -200.300844)
		(end 436.622698 -200.300844)
		(width 0.14478)
		(layer "In11.Cu")
		(net "M_L_CPU0_SA_DQ<3>")
	)
	(segment
		(start 443.936882 -200.300844)
		(end 444.786766 -199.45096)
		(width 0.14478)
		(layer "In11.Cu")
		(net "M_L_CPU0_SA_DQ<3>")
	)
	(segment
		(start 408.352752 -201.84999)
		(end 408.509216 -202.006454)
		(width 0.14478)
		(layer "In11.Cu")
		(net "M_L_CPU0_SA_DQ<3>")
	)
	(segment
		(start 386.034788 -226.664266)
		(end 385.880864 -226.398836)
		(width 0.0889)
		(layer "In11.Cu")
		(net "M_L_CPU0_SA_DQ<3>")
	)
	(segment
		(start 428.940468 -200.30059)
		(end 429.790098 -199.45096)
		(width 0.14478)
		(layer "In11.Cu")
		(net "M_L_CPU0_SA_DQ<3>")
	)
	(segment
		(start 408.902916 -201.612754)
		(end 408.746452 -201.45629)
		(width 0.14478)
		(layer "In11.Cu")
		(net "M_L_CPU0_SA_DQ<3>")
	)
	(segment
		(start 391.45718 -224.739454)
		(end 391.48766 -224.721674)
		(width 0.0889)
		(layer "In11.Cu")
		(net "M_L_CPU0_SA_DQ<3>")
	)
	(segment
		(start 406.147016 -204.368654)
		(end 406.377648 -204.368654)
		(width 0.14478)
		(layer "In11.Cu")
		(net "M_L_CPU0_SA_DQ<3>")
	)
	(segment
		(start 406.934416 -203.581254)
		(end 407.165048 -203.581254)
		(width 0.14478)
		(layer "In11.Cu")
		(net "M_L_CPU0_SA_DQ<3>")
	)
	(segment
		(start 414.772856 -199.450706)
		(end 418.280596 -199.450706)
		(width 0.14478)
		(layer "In11.Cu")
		(net "M_L_CPU0_SA_DQ<3>")
	)
	(segment
		(start 437.472582 -199.45096)
		(end 441.09767 -199.45096)
		(width 0.14478)
		(layer "In11.Cu")
		(net "M_L_CPU0_SA_DQ<3>")
	)
	(segment
		(start 392.427714 -223.101662)
		(end 392.462512 -223.081342)
		(width 0.0889)
		(layer "In11.Cu")
		(net "M_L_CPU0_SA_DQ<3>")
	)
	(segment
		(start 393.522454 -217.323924)
		(end 405.753316 -205.093062)
		(width 0.14478)
		(layer "In11.Cu")
		(net "M_L_CPU0_SA_DQ<3>")
	)
	(segment
		(start 392.397234 -223.119442)
		(end 392.427714 -223.101662)
		(width 0.0889)
		(layer "In11.Cu")
		(net "M_L_CPU0_SA_DQ<3>")
	)
	(segment
		(start 391.48766 -224.721674)
		(end 391.523982 -224.700592)
		(width 0.0889)
		(layer "In11.Cu")
		(net "M_L_CPU0_SA_DQ<3>")
	)
	(segment
		(start 407.959052 -202.013058)
		(end 408.12212 -201.84999)
		(width 0.14478)
		(layer "In11.Cu")
		(net "M_L_CPU0_SA_DQ<3>")
	)
	(segment
		(start 405.596852 -204.60589)
		(end 405.596852 -204.375258)
		(width 0.14478)
		(layer "In11.Cu")
		(net "M_L_CPU0_SA_DQ<3>")
	)
	(segment
		(start 408.746452 -201.225658)
		(end 408.90952 -201.06259)
		(width 0.14478)
		(layer "In11.Cu")
		(net "M_L_CPU0_SA_DQ<3>")
	)
	(segment
		(start 405.753316 -204.762354)
		(end 405.596852 -204.60589)
		(width 0.14478)
		(layer "In11.Cu")
		(net "M_L_CPU0_SA_DQ<3>")
	)
	(segment
		(start 407.721816 -202.793854)
		(end 407.952448 -202.793854)
		(width 0.14478)
		(layer "In11.Cu")
		(net "M_L_CPU0_SA_DQ<3>")
	)
	(segment
		(start 409.296616 -201.219054)
		(end 409.527248 -201.219054)
		(width 0.14478)
		(layer "In11.Cu")
		(net "M_L_CPU0_SA_DQ<3>")
	)
	(segment
		(start 406.377648 -204.368654)
		(end 406.540716 -204.205586)
		(width 0.14478)
		(layer "In11.Cu")
		(net "M_L_CPU0_SA_DQ<3>")
	)
	(segment
		(start 408.12212 -201.84999)
		(end 408.352752 -201.84999)
		(width 0.14478)
		(layer "In11.Cu")
		(net "M_L_CPU0_SA_DQ<3>")
	)
	(segment
		(start 407.959052 -202.24369)
		(end 407.959052 -202.013058)
		(width 0.14478)
		(layer "In11.Cu")
		(net "M_L_CPU0_SA_DQ<3>")
	)
	(segment
		(start 441.09767 -199.45096)
		(end 441.947554 -200.300844)
		(width 0.14478)
		(layer "In11.Cu")
		(net "M_L_CPU0_SA_DQ<3>")
	)
	(segment
		(start 429.790098 -199.45096)
		(end 433.181506 -199.45096)
		(width 0.14478)
		(layer "In11.Cu")
		(net "M_L_CPU0_SA_DQ<3>")
	)
	(segment
		(start 407.565352 -202.63739)
		(end 407.721816 -202.793854)
		(width 0.14478)
		(layer "In11.Cu")
		(net "M_L_CPU0_SA_DQ<3>")
	)
	(segment
		(start 406.540716 -203.974954)
		(end 406.384252 -203.81849)
		(width 0.14478)
		(layer "In11.Cu")
		(net "M_L_CPU0_SA_DQ<3>")
	)
	(segment
		(start 388.093458 -226.33686)
		(end 388.10184 -226.341686)
		(width 0.0889)
		(layer "In11.Cu")
		(net "M_L_CPU0_SA_DQ<3>")
	)
	(segment
		(start 425.955714 -199.450706)
		(end 426.805598 -200.30059)
		(width 0.14478)
		(layer "In11.Cu")
		(net "M_L_CPU0_SA_DQ<3>")
	)
	(segment
		(start 389.033512 -226.33686)
		(end 389.041894 -226.341686)
		(width 0.0889)
		(layer "In11.Cu")
		(net "M_L_CPU0_SA_DQ<3>")
	)
	(segment
		(start 407.328116 -203.187554)
		(end 407.171652 -203.03109)
		(width 0.14478)
		(layer "In11.Cu")
		(net "M_L_CPU0_SA_DQ<3>")
	)
	(segment
		(start 405.990552 -204.21219)
		(end 406.147016 -204.368654)
		(width 0.14478)
		(layer "In11.Cu")
		(net "M_L_CPU0_SA_DQ<3>")
	)
	(segment
		(start 422.376346 -199.450706)
		(end 425.955714 -199.450706)
		(width 0.14478)
		(layer "In11.Cu")
		(net "M_L_CPU0_SA_DQ<3>")
	)
	(segment
		(start 407.171652 -203.03109)
		(end 407.171652 -202.800458)
		(width 0.14478)
		(layer "In11.Cu")
		(net "M_L_CPU0_SA_DQ<3>")
	)
	(segment
		(start 393.522454 -221.719902)
		(end 393.522454 -221.213172)
		(width 0.0889)
		(layer "In11.Cu")
		(net "M_L_CPU0_SA_DQ<3>")
	)
	(segment
		(start 408.739848 -202.006454)
		(end 408.902916 -201.843386)
		(width 0.14478)
		(layer "In11.Cu")
		(net "M_L_CPU0_SA_DQ<3>")
	)
	(segment
		(start 406.384252 -203.587858)
		(end 406.54732 -203.42479)
		(width 0.14478)
		(layer "In11.Cu")
		(net "M_L_CPU0_SA_DQ<3>")
	)
	(segment
		(start 391.95756 -223.911668)
		(end 391.997946 -223.888046)
		(width 0.0889)
		(layer "In11.Cu")
		(net "M_L_CPU0_SA_DQ<3>")
	)
	(segment
		(start 408.115516 -202.400154)
		(end 407.959052 -202.24369)
		(width 0.14478)
		(layer "In11.Cu")
		(net "M_L_CPU0_SA_DQ<3>")
	)
	(segment
		(start 385.880864 -226.398836)
		(end 385.903216 -226.315524)
		(width 0.0889)
		(layer "In11.Cu")
		(net "M_L_CPU0_SA_DQ<3>")
	)
	(segment
		(start 405.753316 -205.093062)
		(end 405.753316 -204.762354)
		(width 0.14478)
		(layer "In11.Cu")
		(net "M_L_CPU0_SA_DQ<3>")
	)
	(segment
		(start 419.13048 -200.30059)
		(end 421.526462 -200.30059)
		(width 0.14478)
		(layer "In11.Cu")
		(net "M_L_CPU0_SA_DQ<3>")
	)
	(segment
		(start 418.280596 -199.450706)
		(end 419.13048 -200.30059)
		(width 0.14478)
		(layer "In11.Cu")
		(net "M_L_CPU0_SA_DQ<3>")
	)
	(segment
		(start 407.165048 -203.581254)
		(end 407.328116 -203.418186)
		(width 0.14478)
		(layer "In11.Cu")
		(net "M_L_CPU0_SA_DQ<3>")
	)
	(segment
		(start 407.171652 -202.800458)
		(end 407.33472 -202.63739)
		(width 0.14478)
		(layer "In11.Cu")
		(net "M_L_CPU0_SA_DQ<3>")
	)
	(segment
		(start 406.777952 -203.42479)
		(end 406.934416 -203.581254)
		(width 0.14478)
		(layer "In11.Cu")
		(net "M_L_CPU0_SA_DQ<3>")
	)
	(segment
		(start 392.864848 -222.310706)
		(end 393.024868 -222.217488)
		(width 0.0889)
		(layer "In11.Cu")
		(net "M_L_CPU0_SA_DQ<3>")
	)
	(segment
		(start 409.527248 -201.219054)
		(end 410.436314 -200.309988)
		(width 0.14478)
		(layer "In11.Cu")
		(net "M_L_CPU0_SA_DQ<3>")
	)
	(segment
		(start 436.622698 -200.300844)
		(end 437.472582 -199.45096)
		(width 0.14478)
		(layer "In11.Cu")
		(net "M_L_CPU0_SA_DQ<3>")
	)
	(segment
		(start 407.33472 -202.63739)
		(end 407.565352 -202.63739)
		(width 0.14478)
		(layer "In11.Cu")
		(net "M_L_CPU0_SA_DQ<3>")
	)
	(segment
		(start 408.746452 -201.45629)
		(end 408.746452 -201.225658)
		(width 0.14478)
		(layer "In11.Cu")
		(net "M_L_CPU0_SA_DQ<3>")
	)
	(segment
		(start 390.98601 -225.549968)
		(end 391.01776 -225.53168)
		(width 0.0889)
		(layer "In11.Cu")
		(net "M_L_CPU0_SA_DQ<3>")
	)
	(segment
		(start 390.54786 -226.341686)
		(end 390.584182 -226.320604)
		(width 0.0889)
		(layer "In11.Cu")
		(net "M_L_CPU0_SA_DQ<3>")
	)
	(segment
		(start 406.540716 -204.205586)
		(end 406.540716 -203.974954)
		(width 0.14478)
		(layer "In11.Cu")
		(net "M_L_CPU0_SA_DQ<3>")
	)
	(segment
		(start 408.90952 -201.06259)
		(end 409.140152 -201.06259)
		(width 0.14478)
		(layer "In11.Cu")
		(net "M_L_CPU0_SA_DQ<3>")
	)
	(segment
		(start 405.75992 -204.21219)
		(end 405.990552 -204.21219)
		(width 0.14478)
		(layer "In11.Cu")
		(net "M_L_CPU0_SA_DQ<3>")
	)
	(segment
		(start 408.509216 -202.006454)
		(end 408.739848 -202.006454)
		(width 0.14478)
		(layer "In11.Cu")
		(net "M_L_CPU0_SA_DQ<3>")
	)
	(segment
		(start 421.526462 -200.30059)
		(end 422.376346 -199.450706)
		(width 0.14478)
		(layer "In11.Cu")
		(net "M_L_CPU0_SA_DQ<3>")
	)
	(segment
		(start 391.92581 -223.929956)
		(end 391.95756 -223.911668)
		(width 0.0889)
		(layer "In11.Cu")
		(net "M_L_CPU0_SA_DQ<3>")
	)
	(segment
		(start 408.902916 -201.843386)
		(end 408.902916 -201.612754)
		(width 0.14478)
		(layer "In11.Cu")
		(net "M_L_CPU0_SA_DQ<3>")
	)
	(segment
		(start 393.522454 -221.213172)
		(end 393.522454 -217.323924)
		(width 0.14478)
		(layer "In11.Cu")
		(net "M_L_CPU0_SA_DQ<3>")
	)
	(arc
		(start 389.041894 -226.341686)
		(mid 389.32485 -226.417863)
		(end 389.607806 -226.341686)
		(width 0.0889)
		(layer "In11.Cu")
		(net "M_L_CPU0_SA_DQ<3>")
	)
	(arc
		(start 389.981948 -226.341686)
		(mid 390.264904 -226.417863)
		(end 390.54786 -226.341686)
		(width 0.0889)
		(layer "In11.Cu")
		(net "M_L_CPU0_SA_DQ<3>")
	)
	(arc
		(start 385.903216 -226.315524)
		(mid 386.065548 -226.292706)
		(end 386.221986 -226.341686)
		(width 0.0889)
		(layer "In11.Cu")
		(net "M_L_CPU0_SA_DQ<3>")
	)
	(arc
		(start 391.523982 -224.700592)
		(mid 391.704634 -224.497847)
		(end 391.769854 -224.234248)
		(width 0.0889)
		(layer "In11.Cu")
		(net "M_L_CPU0_SA_DQ<3>")
	)
	(arc
		(start 391.056876 -225.50882)
		(mid 391.235689 -225.30647)
		(end 391.300208 -225.044254)
		(width 0.0889)
		(layer "In11.Cu")
		(net "M_L_CPU0_SA_DQ<3>")
	)
	(arc
		(start 392.709654 -222.614236)
		(mid 392.750704 -222.443786)
		(end 392.864848 -222.310706)
		(width 0.0889)
		(layer "In11.Cu")
		(net "M_L_CPU0_SA_DQ<3>")
	)
	(arc
		(start 391.300208 -225.044254)
		(mid 391.341757 -224.872832)
		(end 391.45718 -224.739454)
		(width 0.0889)
		(layer "In11.Cu")
		(net "M_L_CPU0_SA_DQ<3>")
	)
	(arc
		(start 390.584182 -226.320604)
		(mid 390.764834 -226.117859)
		(end 390.830054 -225.85426)
		(width 0.0889)
		(layer "In11.Cu")
		(net "M_L_CPU0_SA_DQ<3>")
	)
	(arc
		(start 392.462512 -223.081342)
		(mid 392.644091 -222.878475)
		(end 392.709654 -222.614236)
		(width 0.0889)
		(layer "In11.Cu")
		(net "M_L_CPU0_SA_DQ<3>")
	)
	(arc
		(start 390.830054 -225.85426)
		(mid 390.871309 -225.683289)
		(end 390.98601 -225.549968)
		(width 0.0889)
		(layer "In11.Cu")
		(net "M_L_CPU0_SA_DQ<3>")
	)
	(arc
		(start 391.997946 -223.888046)
		(mid 392.176011 -223.685869)
		(end 392.240262 -223.424242)
		(width 0.0889)
		(layer "In11.Cu")
		(net "M_L_CPU0_SA_DQ<3>")
	)
	(arc
		(start 392.240262 -223.424242)
		(mid 392.281811 -223.25282)
		(end 392.397234 -223.119442)
		(width 0.0889)
		(layer "In11.Cu")
		(net "M_L_CPU0_SA_DQ<3>")
	)
	(arc
		(start 388.10184 -226.341686)
		(mid 388.384796 -226.417863)
		(end 388.667752 -226.341686)
		(width 0.0889)
		(layer "In11.Cu")
		(net "M_L_CPU0_SA_DQ<3>")
	)
	(arc
		(start 391.769854 -224.234248)
		(mid 391.811109 -224.063277)
		(end 391.92581 -223.929956)
		(width 0.0889)
		(layer "In11.Cu")
		(net "M_L_CPU0_SA_DQ<3>")
	)
	(arc
		(start 389.616188 -226.33686)
		(mid 389.799696 -226.291366)
		(end 389.981948 -226.341686)
		(width 0.0889)
		(layer "In11.Cu")
		(net "M_L_CPU0_SA_DQ<3>")
	)
	(arc
		(start 388.667752 -226.341686)
		(mid 388.850003 -226.291336)
		(end 389.033512 -226.33686)
		(width 0.0889)
		(layer "In11.Cu")
		(net "M_L_CPU0_SA_DQ<3>")
	)
	(arc
		(start 386.221986 -226.341686)
		(mid 386.504942 -226.417863)
		(end 386.787898 -226.341686)
		(width 0.0889)
		(layer "In11.Cu")
		(net "M_L_CPU0_SA_DQ<3>")
	)
	(arc
		(start 387.727698 -226.341686)
		(mid 387.909949 -226.291336)
		(end 388.093458 -226.33686)
		(width 0.0889)
		(layer "In11.Cu")
		(net "M_L_CPU0_SA_DQ<3>")
	)
	(arc
		(start 387.161786 -226.341686)
		(mid 387.444742 -226.417863)
		(end 387.727698 -226.341686)
		(width 0.0889)
		(layer "In11.Cu")
		(net "M_L_CPU0_SA_DQ<3>")
	)
	(arc
		(start 386.787898 -226.341686)
		(mid 386.974842 -226.291431)
		(end 387.161786 -226.341686)
		(width 0.0889)
		(layer "In11.Cu")
		(net "M_L_CPU0_SA_DQ<3>")
	)
	(segment
		(start 385.567936 -244.750082)
		(end 386.034788 -244.484144)
		(width 0.10668)
		(layer "F.Cu")
		(net "M_L_CPU0_SA_DQ<31>")
	)
	(segment
		(start 389.033512 -244.156738)
		(end 389.041894 -244.161564)
		(width 0.0889)
		(layer "In11.Cu")
		(net "M_L_CPU0_SA_DQ<31>")
	)
	(segment
		(start 385.880864 -244.218714)
		(end 385.903216 -244.135402)
		(width 0.0889)
		(layer "In11.Cu")
		(net "M_L_CPU0_SA_DQ<31>")
	)
	(segment
		(start 437.463184 -233.46029)
		(end 440.635644 -233.46029)
		(width 0.14478)
		(layer "In11.Cu")
		(net "M_L_CPU0_SA_DQ<31>")
	)
	(segment
		(start 411.878018 -234.563412)
		(end 412.131256 -234.310174)
		(width 0.14478)
		(layer "In11.Cu")
		(net "M_L_CPU0_SA_DQ<31>")
	)
	(segment
		(start 395.1732 -244.23751)
		(end 395.89075 -243.51996)
		(width 0.0889)
		(layer "In11.Cu")
		(net "M_L_CPU0_SA_DQ<31>")
	)
	(segment
		(start 410.298646 -236.340396)
		(end 410.579316 -236.621066)
		(width 0.14478)
		(layer "In11.Cu")
		(net "M_L_CPU0_SA_DQ<31>")
	)
	(segment
		(start 428.846996 -234.310174)
		(end 429.69688 -233.46029)
		(width 0.14478)
		(layer "In11.Cu")
		(net "M_L_CPU0_SA_DQ<31>")
	)
	(segment
		(start 418.404802 -233.460036)
		(end 419.25494 -234.310174)
		(width 0.14478)
		(layer "In11.Cu")
		(net "M_L_CPU0_SA_DQ<31>")
	)
	(segment
		(start 411.078934 -235.560108)
		(end 411.359604 -235.840778)
		(width 0.14478)
		(layer "In11.Cu")
		(net "M_L_CPU0_SA_DQ<31>")
	)
	(segment
		(start 410.68879 -235.745528)
		(end 410.87421 -235.560108)
		(width 0.14478)
		(layer "In11.Cu")
		(net "M_L_CPU0_SA_DQ<31>")
	)
	(segment
		(start 408.628342 -238.571786)
		(end 408.347672 -238.291116)
		(width 0.14478)
		(layer "In11.Cu")
		(net "M_L_CPU0_SA_DQ<31>")
	)
	(segment
		(start 422.284144 -233.46029)
		(end 425.912534 -233.46029)
		(width 0.14478)
		(layer "In11.Cu")
		(net "M_L_CPU0_SA_DQ<31>")
	)
	(segment
		(start 411.56382 -235.841032)
		(end 411.878018 -235.526834)
		(width 0.14478)
		(layer "In11.Cu")
		(net "M_L_CPU0_SA_DQ<31>")
	)
	(segment
		(start 409.12796 -237.510828)
		(end 409.128214 -237.306104)
		(width 0.14478)
		(layer "In11.Cu")
		(net "M_L_CPU0_SA_DQ<31>")
	)
	(segment
		(start 410.579316 -236.621066)
		(end 410.783532 -236.62132)
		(width 0.14478)
		(layer "In11.Cu")
		(net "M_L_CPU0_SA_DQ<31>")
	)
	(segment
		(start 433.190904 -233.46029)
		(end 434.040788 -234.310174)
		(width 0.14478)
		(layer "In11.Cu")
		(net "M_L_CPU0_SA_DQ<31>")
	)
	(segment
		(start 409.128214 -237.306104)
		(end 409.313634 -237.120684)
		(width 0.14478)
		(layer "In11.Cu")
		(net "M_L_CPU0_SA_DQ<31>")
	)
	(segment
		(start 410.969206 -236.435646)
		(end 410.969206 -236.230922)
		(width 0.14478)
		(layer "In11.Cu")
		(net "M_L_CPU0_SA_DQ<31>")
	)
	(segment
		(start 408.628342 -238.77651)
		(end 408.628342 -238.571786)
		(width 0.14478)
		(layer "In11.Cu")
		(net "M_L_CPU0_SA_DQ<31>")
	)
	(segment
		(start 411.359604 -235.840778)
		(end 411.56382 -235.841032)
		(width 0.14478)
		(layer "In11.Cu")
		(net "M_L_CPU0_SA_DQ<31>")
	)
	(segment
		(start 413.531304 -234.310174)
		(end 414.381442 -233.460036)
		(width 0.14478)
		(layer "In11.Cu")
		(net "M_L_CPU0_SA_DQ<31>")
	)
	(segment
		(start 408.73807 -237.900972)
		(end 409.01874 -238.181642)
		(width 0.14478)
		(layer "In11.Cu")
		(net "M_L_CPU0_SA_DQ<31>")
	)
	(segment
		(start 409.908502 -236.525816)
		(end 410.093922 -236.340396)
		(width 0.14478)
		(layer "In11.Cu")
		(net "M_L_CPU0_SA_DQ<31>")
	)
	(segment
		(start 443.982856 -234.310174)
		(end 444.83274 -233.46029)
		(width 0.14478)
		(layer "In11.Cu")
		(net "M_L_CPU0_SA_DQ<31>")
	)
	(segment
		(start 425.912534 -233.46029)
		(end 426.762418 -234.310174)
		(width 0.14478)
		(layer "In11.Cu")
		(net "M_L_CPU0_SA_DQ<31>")
	)
	(segment
		(start 449.663312 -233.46029)
		(end 450.088 -233.884978)
		(width 0.14478)
		(layer "In11.Cu")
		(net "M_L_CPU0_SA_DQ<31>")
	)
	(segment
		(start 421.43426 -234.310174)
		(end 422.284144 -233.46029)
		(width 0.14478)
		(layer "In11.Cu")
		(net "M_L_CPU0_SA_DQ<31>")
	)
	(segment
		(start 393.084812 -244.23751)
		(end 395.1732 -244.23751)
		(width 0.0889)
		(layer "In11.Cu")
		(net "M_L_CPU0_SA_DQ<31>")
	)
	(segment
		(start 440.635644 -233.46029)
		(end 441.485528 -234.310174)
		(width 0.14478)
		(layer "In11.Cu")
		(net "M_L_CPU0_SA_DQ<31>")
	)
	(segment
		(start 414.381442 -233.460036)
		(end 418.404802 -233.460036)
		(width 0.14478)
		(layer "In11.Cu")
		(net "M_L_CPU0_SA_DQ<31>")
	)
	(segment
		(start 419.25494 -234.310174)
		(end 421.43426 -234.310174)
		(width 0.14478)
		(layer "In11.Cu")
		(net "M_L_CPU0_SA_DQ<31>")
	)
	(segment
		(start 448.20078 -233.46029)
		(end 448.4878 -233.74731)
		(width 0.14478)
		(layer "In11.Cu")
		(net "M_L_CPU0_SA_DQ<31>")
	)
	(segment
		(start 447.644266 -233.74731)
		(end 447.931286 -233.46029)
		(width 0.14478)
		(layer "In11.Cu")
		(net "M_L_CPU0_SA_DQ<31>")
	)
	(segment
		(start 410.188918 -237.215934)
		(end 410.188918 -237.01121)
		(width 0.14478)
		(layer "In11.Cu")
		(net "M_L_CPU0_SA_DQ<31>")
	)
	(segment
		(start 441.485528 -234.310174)
		(end 443.982856 -234.310174)
		(width 0.14478)
		(layer "In11.Cu")
		(net "M_L_CPU0_SA_DQ<31>")
	)
	(segment
		(start 410.87421 -235.560108)
		(end 411.078934 -235.560108)
		(width 0.14478)
		(layer "In11.Cu")
		(net "M_L_CPU0_SA_DQ<31>")
	)
	(segment
		(start 396.084298 -243.51996)
		(end 403.884892 -243.51996)
		(width 0.14478)
		(layer "In11.Cu")
		(net "M_L_CPU0_SA_DQ<31>")
	)
	(segment
		(start 410.003244 -237.401608)
		(end 410.188918 -237.215934)
		(width 0.14478)
		(layer "In11.Cu")
		(net "M_L_CPU0_SA_DQ<31>")
	)
	(segment
		(start 409.313634 -237.120684)
		(end 409.518358 -237.120684)
		(width 0.14478)
		(layer "In11.Cu")
		(net "M_L_CPU0_SA_DQ<31>")
	)
	(segment
		(start 410.093922 -236.340396)
		(end 410.298646 -236.340396)
		(width 0.14478)
		(layer "In11.Cu")
		(net "M_L_CPU0_SA_DQ<31>")
	)
	(segment
		(start 426.762418 -234.310174)
		(end 428.846996 -234.310174)
		(width 0.14478)
		(layer "In11.Cu")
		(net "M_L_CPU0_SA_DQ<31>")
	)
	(segment
		(start 410.688536 -235.950252)
		(end 410.68879 -235.745528)
		(width 0.14478)
		(layer "In11.Cu")
		(net "M_L_CPU0_SA_DQ<31>")
	)
	(segment
		(start 409.40863 -237.791498)
		(end 409.12796 -237.510828)
		(width 0.14478)
		(layer "In11.Cu")
		(net "M_L_CPU0_SA_DQ<31>")
	)
	(segment
		(start 447.374772 -233.74731)
		(end 447.644266 -233.74731)
		(width 0.14478)
		(layer "In11.Cu")
		(net "M_L_CPU0_SA_DQ<31>")
	)
	(segment
		(start 395.89075 -243.51996)
		(end 396.084298 -243.51996)
		(width 0.0889)
		(layer "In11.Cu")
		(net "M_L_CPU0_SA_DQ<31>")
	)
	(segment
		(start 409.518358 -237.120684)
		(end 409.799028 -237.401354)
		(width 0.14478)
		(layer "In11.Cu")
		(net "M_L_CPU0_SA_DQ<31>")
	)
	(segment
		(start 409.40863 -237.996222)
		(end 409.40863 -237.791498)
		(width 0.14478)
		(layer "In11.Cu")
		(net "M_L_CPU0_SA_DQ<31>")
	)
	(segment
		(start 447.087752 -233.46029)
		(end 447.374772 -233.74731)
		(width 0.14478)
		(layer "In11.Cu")
		(net "M_L_CPU0_SA_DQ<31>")
	)
	(segment
		(start 410.969206 -236.230922)
		(end 410.688536 -235.950252)
		(width 0.14478)
		(layer "In11.Cu")
		(net "M_L_CPU0_SA_DQ<31>")
	)
	(segment
		(start 444.83274 -233.46029)
		(end 447.087752 -233.46029)
		(width 0.14478)
		(layer "In11.Cu")
		(net "M_L_CPU0_SA_DQ<31>")
	)
	(segment
		(start 388.093458 -244.156738)
		(end 388.10184 -244.161564)
		(width 0.0889)
		(layer "In11.Cu")
		(net "M_L_CPU0_SA_DQ<31>")
	)
	(segment
		(start 410.188918 -237.01121)
		(end 409.908248 -236.73054)
		(width 0.14478)
		(layer "In11.Cu")
		(net "M_L_CPU0_SA_DQ<31>")
	)
	(segment
		(start 436.6133 -234.310174)
		(end 437.463184 -233.46029)
		(width 0.14478)
		(layer "In11.Cu")
		(net "M_L_CPU0_SA_DQ<31>")
	)
	(segment
		(start 448.4878 -233.74731)
		(end 448.757294 -233.74731)
		(width 0.14478)
		(layer "In11.Cu")
		(net "M_L_CPU0_SA_DQ<31>")
	)
	(segment
		(start 403.884892 -243.51996)
		(end 408.628342 -238.77651)
		(width 0.14478)
		(layer "In11.Cu")
		(net "M_L_CPU0_SA_DQ<31>")
	)
	(segment
		(start 408.347926 -238.086392)
		(end 408.533346 -237.900972)
		(width 0.14478)
		(layer "In11.Cu")
		(net "M_L_CPU0_SA_DQ<31>")
	)
	(segment
		(start 408.347672 -238.291116)
		(end 408.347926 -238.086392)
		(width 0.14478)
		(layer "In11.Cu")
		(net "M_L_CPU0_SA_DQ<31>")
	)
	(segment
		(start 386.034788 -244.484144)
		(end 385.880864 -244.218714)
		(width 0.0889)
		(layer "In11.Cu")
		(net "M_L_CPU0_SA_DQ<31>")
	)
	(segment
		(start 449.044314 -233.46029)
		(end 449.663312 -233.46029)
		(width 0.14478)
		(layer "In11.Cu")
		(net "M_L_CPU0_SA_DQ<31>")
	)
	(segment
		(start 412.131256 -234.310174)
		(end 413.531304 -234.310174)
		(width 0.14478)
		(layer "In11.Cu")
		(net "M_L_CPU0_SA_DQ<31>")
	)
	(segment
		(start 429.69688 -233.46029)
		(end 433.190904 -233.46029)
		(width 0.14478)
		(layer "In11.Cu")
		(net "M_L_CPU0_SA_DQ<31>")
	)
	(segment
		(start 409.799028 -237.401354)
		(end 410.003244 -237.401608)
		(width 0.14478)
		(layer "In11.Cu")
		(net "M_L_CPU0_SA_DQ<31>")
	)
	(segment
		(start 409.222956 -238.181896)
		(end 409.40863 -237.996222)
		(width 0.14478)
		(layer "In11.Cu")
		(net "M_L_CPU0_SA_DQ<31>")
	)
	(segment
		(start 408.533346 -237.900972)
		(end 408.73807 -237.900972)
		(width 0.14478)
		(layer "In11.Cu")
		(net "M_L_CPU0_SA_DQ<31>")
	)
	(segment
		(start 448.757294 -233.74731)
		(end 449.044314 -233.46029)
		(width 0.14478)
		(layer "In11.Cu")
		(net "M_L_CPU0_SA_DQ<31>")
	)
	(segment
		(start 410.783532 -236.62132)
		(end 410.969206 -236.435646)
		(width 0.14478)
		(layer "In11.Cu")
		(net "M_L_CPU0_SA_DQ<31>")
	)
	(segment
		(start 389.607806 -244.161564)
		(end 389.616188 -244.156738)
		(width 0.0889)
		(layer "In11.Cu")
		(net "M_L_CPU0_SA_DQ<31>")
	)
	(segment
		(start 447.931286 -233.46029)
		(end 448.20078 -233.46029)
		(width 0.14478)
		(layer "In11.Cu")
		(net "M_L_CPU0_SA_DQ<31>")
	)
	(segment
		(start 392.417808 -244.16766)
		(end 392.428222 -244.161564)
		(width 0.0889)
		(layer "In11.Cu")
		(net "M_L_CPU0_SA_DQ<31>")
	)
	(segment
		(start 434.040788 -234.310174)
		(end 436.6133 -234.310174)
		(width 0.14478)
		(layer "In11.Cu")
		(net "M_L_CPU0_SA_DQ<31>")
	)
	(segment
		(start 409.908248 -236.73054)
		(end 409.908502 -236.525816)
		(width 0.14478)
		(layer "In11.Cu")
		(net "M_L_CPU0_SA_DQ<31>")
	)
	(segment
		(start 411.878018 -235.526834)
		(end 411.878018 -234.563412)
		(width 0.14478)
		(layer "In11.Cu")
		(net "M_L_CPU0_SA_DQ<31>")
	)
	(segment
		(start 409.01874 -238.181642)
		(end 409.222956 -238.181896)
		(width 0.14478)
		(layer "In11.Cu")
		(net "M_L_CPU0_SA_DQ<31>")
	)
	(arc
		(start 388.667752 -244.161564)
		(mid 388.850003 -244.111214)
		(end 389.033512 -244.156738)
		(width 0.0889)
		(layer "In11.Cu")
		(net "M_L_CPU0_SA_DQ<31>")
	)
	(arc
		(start 386.787898 -244.161564)
		(mid 386.974842 -244.111309)
		(end 387.161786 -244.161564)
		(width 0.0889)
		(layer "In11.Cu")
		(net "M_L_CPU0_SA_DQ<31>")
	)
	(arc
		(start 392.428222 -244.161564)
		(mid 392.615166 -244.111309)
		(end 392.80211 -244.161564)
		(width 0.0889)
		(layer "In11.Cu")
		(net "M_L_CPU0_SA_DQ<31>")
	)
	(arc
		(start 386.221986 -244.161564)
		(mid 386.504942 -244.237741)
		(end 386.787898 -244.161564)
		(width 0.0889)
		(layer "In11.Cu")
		(net "M_L_CPU0_SA_DQ<31>")
	)
	(arc
		(start 385.903216 -244.135402)
		(mid 386.065548 -244.112584)
		(end 386.221986 -244.161564)
		(width 0.0889)
		(layer "In11.Cu")
		(net "M_L_CPU0_SA_DQ<31>")
	)
	(arc
		(start 391.48766 -244.161564)
		(mid 391.674858 -244.111182)
		(end 391.862056 -244.161564)
		(width 0.0889)
		(layer "In11.Cu")
		(net "M_L_CPU0_SA_DQ<31>")
	)
	(arc
		(start 392.80211 -244.161564)
		(mid 392.938444 -244.218207)
		(end 393.084812 -244.23751)
		(width 0.0889)
		(layer "In11.Cu")
		(net "M_L_CPU0_SA_DQ<31>")
	)
	(arc
		(start 391.862056 -244.161564)
		(mid 392.139123 -244.237835)
		(end 392.417808 -244.16766)
		(width 0.0889)
		(layer "In11.Cu")
		(net "M_L_CPU0_SA_DQ<31>")
	)
	(arc
		(start 389.981948 -244.161564)
		(mid 390.264904 -244.237741)
		(end 390.54786 -244.161564)
		(width 0.0889)
		(layer "In11.Cu")
		(net "M_L_CPU0_SA_DQ<31>")
	)
	(arc
		(start 390.921748 -244.161564)
		(mid 391.204704 -244.237741)
		(end 391.48766 -244.161564)
		(width 0.0889)
		(layer "In11.Cu")
		(net "M_L_CPU0_SA_DQ<31>")
	)
	(arc
		(start 389.041894 -244.161564)
		(mid 389.32485 -244.237741)
		(end 389.607806 -244.161564)
		(width 0.0889)
		(layer "In11.Cu")
		(net "M_L_CPU0_SA_DQ<31>")
	)
	(arc
		(start 390.54786 -244.161564)
		(mid 390.734804 -244.111309)
		(end 390.921748 -244.161564)
		(width 0.0889)
		(layer "In11.Cu")
		(net "M_L_CPU0_SA_DQ<31>")
	)
	(arc
		(start 388.10184 -244.161564)
		(mid 388.384796 -244.237741)
		(end 388.667752 -244.161564)
		(width 0.0889)
		(layer "In11.Cu")
		(net "M_L_CPU0_SA_DQ<31>")
	)
	(arc
		(start 387.161786 -244.161564)
		(mid 387.444742 -244.237741)
		(end 387.727698 -244.161564)
		(width 0.0889)
		(layer "In11.Cu")
		(net "M_L_CPU0_SA_DQ<31>")
	)
	(arc
		(start 389.616188 -244.156738)
		(mid 389.799696 -244.111244)
		(end 389.981948 -244.161564)
		(width 0.0889)
		(layer "In11.Cu")
		(net "M_L_CPU0_SA_DQ<31>")
	)
	(arc
		(start 387.727698 -244.161564)
		(mid 387.909949 -244.111214)
		(end 388.093458 -244.156738)
		(width 0.0889)
		(layer "In11.Cu")
		(net "M_L_CPU0_SA_DQ<31>")
	)
	(segment
		(start 386.97789 -243.940076)
		(end 387.444742 -243.674138)
		(width 0.10668)
		(layer "F.Cu")
		(net "M_L_CPU0_SA_DQ<30>")
	)
	(segment
		(start 447.480944 -231.543352)
		(end 447.480944 -231.615488)
		(width 0.14478)
		(layer "In11.Cu")
		(net "M_L_CPU0_SA_DQ<30>")
	)
	(segment
		(start 407.354024 -237.457742)
		(end 407.354024 -238.764318)
		(width 0.14478)
		(layer "In11.Cu")
		(net "M_L_CPU0_SA_DQ<30>")
	)
	(segment
		(start 417.75761 -232.000552)
		(end 417.61283 -232.145332)
		(width 0.14478)
		(layer "In11.Cu")
		(net "M_L_CPU0_SA_DQ<30>")
	)
	(segment
		(start 440.124088 -231.528112)
		(end 439.979308 -231.383332)
		(width 0.14478)
		(layer "In11.Cu")
		(net "M_L_CPU0_SA_DQ<30>")
	)
	(segment
		(start 423.487088 -231.760268)
		(end 423.342308 -231.615488)
		(width 0.14478)
		(layer "In11.Cu")
		(net "M_L_CPU0_SA_DQ<30>")
	)
	(segment
		(start 437.463184 -231.760268)
		(end 436.6133 -232.610152)
		(width 0.14478)
		(layer "In11.Cu")
		(net "M_L_CPU0_SA_DQ<30>")
	)
	(segment
		(start 417.206176 -232.000552)
		(end 417.206176 -231.904794)
		(width 0.14478)
		(layer "In11.Cu")
		(net "M_L_CPU0_SA_DQ<30>")
	)
	(segment
		(start 438.505854 -231.515412)
		(end 438.361074 -231.370632)
		(width 0.14478)
		(layer "In11.Cu")
		(net "M_L_CPU0_SA_DQ<30>")
	)
	(segment
		(start 429.005492 -232.610152)
		(end 426.762418 -232.610152)
		(width 0.14478)
		(layer "In11.Cu")
		(net "M_L_CPU0_SA_DQ<30>")
	)
	(segment
		(start 437.95442 -231.615488)
		(end 437.80964 -231.760268)
		(width 0.14478)
		(layer "In11.Cu")
		(net "M_L_CPU0_SA_DQ<30>")
	)
	(segment
		(start 395.368018 -243.275612)
		(end 394.860018 -243.783612)
		(width 0.0889)
		(layer "In11.Cu")
		(net "M_L_CPU0_SA_DQ<30>")
	)
	(segment
		(start 441.387992 -232.610152)
		(end 440.538108 -231.760268)
		(width 0.14478)
		(layer "In11.Cu")
		(net "M_L_CPU0_SA_DQ<30>")
	)
	(segment
		(start 431.9778 -231.760268)
		(end 431.07102 -231.760268)
		(width 0.14478)
		(layer "In11.Cu")
		(net "M_L_CPU0_SA_DQ<30>")
	)
	(segment
		(start 424.99407 -231.615488)
		(end 424.84929 -231.760268)
		(width 0.14478)
		(layer "In11.Cu")
		(net "M_L_CPU0_SA_DQ<30>")
	)
	(segment
		(start 417.61283 -232.145332)
		(end 417.350956 -232.145332)
		(width 0.14478)
		(layer "In11.Cu")
		(net "M_L_CPU0_SA_DQ<30>")
	)
	(segment
		(start 432.674014 -231.515412)
		(end 432.529234 -231.370632)
		(width 0.14478)
		(layer "In11.Cu")
		(net "M_L_CPU0_SA_DQ<30>")
	)
	(segment
		(start 422.935654 -231.380792)
		(end 422.790874 -231.525572)
		(width 0.14478)
		(layer "In11.Cu")
		(net "M_L_CPU0_SA_DQ<30>")
	)
	(segment
		(start 421.446452 -232.610152)
		(end 419.076124 -232.610152)
		(width 0.14478)
		(layer "In11.Cu")
		(net "M_L_CPU0_SA_DQ<30>")
	)
	(segment
		(start 424.84929 -231.760268)
		(end 423.487088 -231.760268)
		(width 0.14478)
		(layer "In11.Cu")
		(net "M_L_CPU0_SA_DQ<30>")
	)
	(segment
		(start 430.519586 -231.375712)
		(end 430.374806 -231.520492)
		(width 0.14478)
		(layer "In11.Cu")
		(net "M_L_CPU0_SA_DQ<30>")
	)
	(segment
		(start 432.12258 -231.515412)
		(end 432.12258 -231.615488)
		(width 0.14478)
		(layer "In11.Cu")
		(net "M_L_CPU0_SA_DQ<30>")
	)
	(segment
		(start 448.439032 -232.121964)
		(end 448.177158 -232.121964)
		(width 0.14478)
		(layer "In11.Cu")
		(net "M_L_CPU0_SA_DQ<30>")
	)
	(segment
		(start 449.280026 -231.760268)
		(end 449.135246 -231.615488)
		(width 0.14478)
		(layer "In11.Cu")
		(net "M_L_CPU0_SA_DQ<30>")
	)
	(segment
		(start 439.427874 -231.760268)
		(end 438.650634 -231.760268)
		(width 0.14478)
		(layer "In11.Cu")
		(net "M_L_CPU0_SA_DQ<30>")
	)
	(segment
		(start 422.790874 -231.525572)
		(end 422.790874 -231.615488)
		(width 0.14478)
		(layer "In11.Cu")
		(net "M_L_CPU0_SA_DQ<30>")
	)
	(segment
		(start 425.545504 -231.533192)
		(end 425.400724 -231.388412)
		(width 0.14478)
		(layer "In11.Cu")
		(net "M_L_CPU0_SA_DQ<30>")
	)
	(segment
		(start 448.032378 -231.977184)
		(end 448.032378 -231.543352)
		(width 0.14478)
		(layer "In11.Cu")
		(net "M_L_CPU0_SA_DQ<30>")
	)
	(segment
		(start 430.78146 -231.375712)
		(end 430.519586 -231.375712)
		(width 0.14478)
		(layer "In11.Cu")
		(net "M_L_CPU0_SA_DQ<30>")
	)
	(segment
		(start 449.135246 -231.615488)
		(end 449.135246 -231.543352)
		(width 0.14478)
		(layer "In11.Cu")
		(net "M_L_CPU0_SA_DQ<30>")
	)
	(segment
		(start 440.538108 -231.760268)
		(end 440.268868 -231.760268)
		(width 0.14478)
		(layer "In11.Cu")
		(net "M_L_CPU0_SA_DQ<30>")
	)
	(segment
		(start 391.957052 -243.351812)
		(end 391.945114 -243.35867)
		(width 0.0889)
		(layer "In11.Cu")
		(net "M_L_CPU0_SA_DQ<30>")
	)
	(segment
		(start 390.451848 -243.351558)
		(end 390.443466 -243.346732)
		(width 0.0889)
		(layer "In11.Cu")
		(net "M_L_CPU0_SA_DQ<30>")
	)
	(segment
		(start 437.80964 -231.760268)
		(end 437.463184 -231.760268)
		(width 0.14478)
		(layer "In11.Cu")
		(net "M_L_CPU0_SA_DQ<30>")
	)
	(segment
		(start 440.124088 -231.615488)
		(end 440.124088 -231.528112)
		(width 0.14478)
		(layer "In11.Cu")
		(net "M_L_CPU0_SA_DQ<30>")
	)
	(segment
		(start 430.230026 -231.760268)
		(end 429.855376 -231.760268)
		(width 0.14478)
		(layer "In11.Cu")
		(net "M_L_CPU0_SA_DQ<30>")
	)
	(segment
		(start 403.507702 -242.61064)
		(end 395.962886 -242.61064)
		(width 0.14478)
		(layer "In11.Cu")
		(net "M_L_CPU0_SA_DQ<30>")
	)
	(segment
		(start 448.990466 -231.398572)
		(end 448.728592 -231.398572)
		(width 0.14478)
		(layer "In11.Cu")
		(net "M_L_CPU0_SA_DQ<30>")
	)
	(segment
		(start 430.374806 -231.615488)
		(end 430.230026 -231.760268)
		(width 0.14478)
		(layer "In11.Cu")
		(net "M_L_CPU0_SA_DQ<30>")
	)
	(segment
		(start 439.979308 -231.383332)
		(end 439.717434 -231.383332)
		(width 0.14478)
		(layer "In11.Cu")
		(net "M_L_CPU0_SA_DQ<30>")
	)
	(segment
		(start 432.26736 -231.370632)
		(end 432.12258 -231.515412)
		(width 0.14478)
		(layer "In11.Cu")
		(net "M_L_CPU0_SA_DQ<30>")
	)
	(segment
		(start 448.032378 -231.543352)
		(end 447.887598 -231.398572)
		(width 0.14478)
		(layer "In11.Cu")
		(net "M_L_CPU0_SA_DQ<30>")
	)
	(segment
		(start 436.6133 -232.610152)
		(end 434.040788 -232.610152)
		(width 0.14478)
		(layer "In11.Cu")
		(net "M_L_CPU0_SA_DQ<30>")
	)
	(segment
		(start 419.076124 -232.610152)
		(end 418.225986 -231.760014)
		(width 0.14478)
		(layer "In11.Cu")
		(net "M_L_CPU0_SA_DQ<30>")
	)
	(segment
		(start 438.505854 -231.615488)
		(end 438.505854 -231.515412)
		(width 0.14478)
		(layer "In11.Cu")
		(net "M_L_CPU0_SA_DQ<30>")
	)
	(segment
		(start 448.728592 -231.398572)
		(end 448.583812 -231.543352)
		(width 0.14478)
		(layer "In11.Cu")
		(net "M_L_CPU0_SA_DQ<30>")
	)
	(segment
		(start 407.354024 -238.764318)
		(end 403.507702 -242.61064)
		(width 0.14478)
		(layer "In11.Cu")
		(net "M_L_CPU0_SA_DQ<30>")
	)
	(segment
		(start 434.040788 -232.610152)
		(end 433.190904 -231.760268)
		(width 0.14478)
		(layer "In11.Cu")
		(net "M_L_CPU0_SA_DQ<30>")
	)
	(segment
		(start 422.790874 -231.615488)
		(end 422.646094 -231.760268)
		(width 0.14478)
		(layer "In11.Cu")
		(net "M_L_CPU0_SA_DQ<30>")
	)
	(segment
		(start 437.95442 -231.515412)
		(end 437.95442 -231.615488)
		(width 0.14478)
		(layer "In11.Cu")
		(net "M_L_CPU0_SA_DQ<30>")
	)
	(segment
		(start 447.625724 -231.398572)
		(end 447.480944 -231.543352)
		(width 0.14478)
		(layer "In11.Cu")
		(net "M_L_CPU0_SA_DQ<30>")
	)
	(segment
		(start 448.583812 -231.543352)
		(end 448.583812 -231.977184)
		(width 0.14478)
		(layer "In11.Cu")
		(net "M_L_CPU0_SA_DQ<30>")
	)
	(segment
		(start 391.026142 -243.346732)
		(end 391.01776 -243.351558)
		(width 0.0889)
		(layer "In11.Cu")
		(net "M_L_CPU0_SA_DQ<30>")
	)
	(segment
		(start 425.912534 -231.760268)
		(end 425.690284 -231.760268)
		(width 0.14478)
		(layer "In11.Cu")
		(net "M_L_CPU0_SA_DQ<30>")
	)
	(segment
		(start 394.258038 -243.783612)
		(end 393.775184 -243.300758)
		(width 0.0889)
		(layer "In11.Cu")
		(net "M_L_CPU0_SA_DQ<30>")
	)
	(segment
		(start 394.860018 -243.783612)
		(end 394.258038 -243.783612)
		(width 0.0889)
		(layer "In11.Cu")
		(net "M_L_CPU0_SA_DQ<30>")
	)
	(segment
		(start 412.201614 -232.610152)
		(end 407.354024 -237.457742)
		(width 0.14478)
		(layer "In11.Cu")
		(net "M_L_CPU0_SA_DQ<30>")
	)
	(segment
		(start 439.572654 -231.615488)
		(end 439.427874 -231.760268)
		(width 0.14478)
		(layer "In11.Cu")
		(net "M_L_CPU0_SA_DQ<30>")
	)
	(segment
		(start 433.190904 -231.760268)
		(end 432.818794 -231.760268)
		(width 0.14478)
		(layer "In11.Cu")
		(net "M_L_CPU0_SA_DQ<30>")
	)
	(segment
		(start 449.663312 -231.760268)
		(end 449.280026 -231.760268)
		(width 0.14478)
		(layer "In11.Cu")
		(net "M_L_CPU0_SA_DQ<30>")
	)
	(segment
		(start 423.197528 -231.380792)
		(end 422.935654 -231.380792)
		(width 0.14478)
		(layer "In11.Cu")
		(net "M_L_CPU0_SA_DQ<30>")
	)
	(segment
		(start 387.31317 -243.325396)
		(end 387.290818 -243.408708)
		(width 0.0889)
		(layer "In11.Cu")
		(net "M_L_CPU0_SA_DQ<30>")
	)
	(segment
		(start 438.0992 -231.370632)
		(end 437.95442 -231.515412)
		(width 0.14478)
		(layer "In11.Cu")
		(net "M_L_CPU0_SA_DQ<30>")
	)
	(segment
		(start 432.529234 -231.370632)
		(end 432.26736 -231.370632)
		(width 0.14478)
		(layer "In11.Cu")
		(net "M_L_CPU0_SA_DQ<30>")
	)
	(segment
		(start 423.342308 -231.525572)
		(end 423.197528 -231.380792)
		(width 0.14478)
		(layer "In11.Cu")
		(net "M_L_CPU0_SA_DQ<30>")
	)
	(segment
		(start 391.970768 -243.343938)
		(end 391.957052 -243.351812)
		(width 0.0889)
		(layer "In11.Cu")
		(net "M_L_CPU0_SA_DQ<30>")
	)
	(segment
		(start 388.206234 -243.346732)
		(end 388.197852 -243.351558)
		(width 0.0889)
		(layer "In11.Cu")
		(net "M_L_CPU0_SA_DQ<30>")
	)
	(segment
		(start 432.818794 -231.760268)
		(end 432.674014 -231.615488)
		(width 0.14478)
		(layer "In11.Cu")
		(net "M_L_CPU0_SA_DQ<30>")
	)
	(segment
		(start 395.962886 -242.61064)
		(end 395.649958 -242.61064)
		(width 0.0889)
		(layer "In11.Cu")
		(net "M_L_CPU0_SA_DQ<30>")
	)
	(segment
		(start 439.717434 -231.383332)
		(end 439.572654 -231.528112)
		(width 0.14478)
		(layer "In11.Cu")
		(net "M_L_CPU0_SA_DQ<30>")
	)
	(segment
		(start 448.177158 -232.121964)
		(end 448.032378 -231.977184)
		(width 0.14478)
		(layer "In11.Cu")
		(net "M_L_CPU0_SA_DQ<30>")
	)
	(segment
		(start 438.650634 -231.760268)
		(end 438.505854 -231.615488)
		(width 0.14478)
		(layer "In11.Cu")
		(net "M_L_CPU0_SA_DQ<30>")
	)
	(segment
		(start 418.225986 -231.760014)
		(end 417.90239 -231.760014)
		(width 0.14478)
		(layer "In11.Cu")
		(net "M_L_CPU0_SA_DQ<30>")
	)
	(segment
		(start 432.674014 -231.615488)
		(end 432.674014 -231.515412)
		(width 0.14478)
		(layer "In11.Cu")
		(net "M_L_CPU0_SA_DQ<30>")
	)
	(segment
		(start 432.12258 -231.615488)
		(end 431.9778 -231.760268)
		(width 0.14478)
		(layer "In11.Cu")
		(net "M_L_CPU0_SA_DQ<30>")
	)
	(segment
		(start 426.762418 -232.610152)
		(end 425.912534 -231.760268)
		(width 0.14478)
		(layer "In11.Cu")
		(net "M_L_CPU0_SA_DQ<30>")
	)
	(segment
		(start 450.088 -232.184956)
		(end 449.663312 -231.760268)
		(width 0.14478)
		(layer "In11.Cu")
		(net "M_L_CPU0_SA_DQ<30>")
	)
	(segment
		(start 395.368018 -242.89258)
		(end 395.368018 -243.275612)
		(width 0.0889)
		(layer "In11.Cu")
		(net "M_L_CPU0_SA_DQ<30>")
	)
	(segment
		(start 449.135246 -231.543352)
		(end 448.990466 -231.398572)
		(width 0.14478)
		(layer "In11.Cu")
		(net "M_L_CPU0_SA_DQ<30>")
	)
	(segment
		(start 425.400724 -231.388412)
		(end 425.13885 -231.388412)
		(width 0.14478)
		(layer "In11.Cu")
		(net "M_L_CPU0_SA_DQ<30>")
	)
	(segment
		(start 430.374806 -231.520492)
		(end 430.374806 -231.615488)
		(width 0.14478)
		(layer "In11.Cu")
		(net "M_L_CPU0_SA_DQ<30>")
	)
	(segment
		(start 439.572654 -231.528112)
		(end 439.572654 -231.615488)
		(width 0.14478)
		(layer "In11.Cu")
		(net "M_L_CPU0_SA_DQ<30>")
	)
	(segment
		(start 445.052704 -231.760268)
		(end 444.20282 -232.610152)
		(width 0.14478)
		(layer "In11.Cu")
		(net "M_L_CPU0_SA_DQ<30>")
	)
	(segment
		(start 430.92624 -231.520492)
		(end 430.78146 -231.375712)
		(width 0.14478)
		(layer "In11.Cu")
		(net "M_L_CPU0_SA_DQ<30>")
	)
	(segment
		(start 430.92624 -231.615488)
		(end 430.92624 -231.520492)
		(width 0.14478)
		(layer "In11.Cu")
		(net "M_L_CPU0_SA_DQ<30>")
	)
	(segment
		(start 425.690284 -231.760268)
		(end 425.545504 -231.615488)
		(width 0.14478)
		(layer "In11.Cu")
		(net "M_L_CPU0_SA_DQ<30>")
	)
	(segment
		(start 393.775184 -243.300758)
		(end 393.084812 -243.300758)
		(width 0.0889)
		(layer "In11.Cu")
		(net "M_L_CPU0_SA_DQ<30>")
	)
	(segment
		(start 423.342308 -231.615488)
		(end 423.342308 -231.525572)
		(width 0.14478)
		(layer "In11.Cu")
		(net "M_L_CPU0_SA_DQ<30>")
	)
	(segment
		(start 414.738058 -231.760014)
		(end 413.88792 -232.610152)
		(width 0.14478)
		(layer "In11.Cu")
		(net "M_L_CPU0_SA_DQ<30>")
	)
	(segment
		(start 447.480944 -231.615488)
		(end 447.336164 -231.760268)
		(width 0.14478)
		(layer "In11.Cu")
		(net "M_L_CPU0_SA_DQ<30>")
	)
	(segment
		(start 431.07102 -231.760268)
		(end 430.92624 -231.615488)
		(width 0.14478)
		(layer "In11.Cu")
		(net "M_L_CPU0_SA_DQ<30>")
	)
	(segment
		(start 395.649958 -242.61064)
		(end 395.368018 -242.89258)
		(width 0.0889)
		(layer "In11.Cu")
		(net "M_L_CPU0_SA_DQ<30>")
	)
	(segment
		(start 425.545504 -231.615488)
		(end 425.545504 -231.533192)
		(width 0.14478)
		(layer "In11.Cu")
		(net "M_L_CPU0_SA_DQ<30>")
	)
	(segment
		(start 447.336164 -231.760268)
		(end 445.052704 -231.760268)
		(width 0.14478)
		(layer "In11.Cu")
		(net "M_L_CPU0_SA_DQ<30>")
	)
	(segment
		(start 424.99407 -231.533192)
		(end 424.99407 -231.615488)
		(width 0.14478)
		(layer "In11.Cu")
		(net "M_L_CPU0_SA_DQ<30>")
	)
	(segment
		(start 387.290818 -243.408708)
		(end 387.444742 -243.674138)
		(width 0.0889)
		(layer "In11.Cu")
		(net "M_L_CPU0_SA_DQ<30>")
	)
	(segment
		(start 425.13885 -231.388412)
		(end 424.99407 -231.533192)
		(width 0.14478)
		(layer "In11.Cu")
		(net "M_L_CPU0_SA_DQ<30>")
	)
	(segment
		(start 447.887598 -231.398572)
		(end 447.625724 -231.398572)
		(width 0.14478)
		(layer "In11.Cu")
		(net "M_L_CPU0_SA_DQ<30>")
	)
	(segment
		(start 422.296336 -231.760268)
		(end 421.446452 -232.610152)
		(width 0.14478)
		(layer "In11.Cu")
		(net "M_L_CPU0_SA_DQ<30>")
	)
	(segment
		(start 417.75761 -231.904794)
		(end 417.75761 -232.000552)
		(width 0.14478)
		(layer "In11.Cu")
		(net "M_L_CPU0_SA_DQ<30>")
	)
	(segment
		(start 438.361074 -231.370632)
		(end 438.0992 -231.370632)
		(width 0.14478)
		(layer "In11.Cu")
		(net "M_L_CPU0_SA_DQ<30>")
	)
	(segment
		(start 422.646094 -231.760268)
		(end 422.296336 -231.760268)
		(width 0.14478)
		(layer "In11.Cu")
		(net "M_L_CPU0_SA_DQ<30>")
	)
	(segment
		(start 440.268868 -231.760268)
		(end 440.124088 -231.615488)
		(width 0.14478)
		(layer "In11.Cu")
		(net "M_L_CPU0_SA_DQ<30>")
	)
	(segment
		(start 429.855376 -231.760268)
		(end 429.005492 -232.610152)
		(width 0.14478)
		(layer "In11.Cu")
		(net "M_L_CPU0_SA_DQ<30>")
	)
	(segment
		(start 417.90239 -231.760014)
		(end 417.75761 -231.904794)
		(width 0.14478)
		(layer "In11.Cu")
		(net "M_L_CPU0_SA_DQ<30>")
	)
	(segment
		(start 392.34872 -243.362226)
		(end 392.330686 -243.351558)
		(width 0.0889)
		(layer "In11.Cu")
		(net "M_L_CPU0_SA_DQ<30>")
	)
	(segment
		(start 417.206176 -231.904794)
		(end 417.061396 -231.760014)
		(width 0.14478)
		(layer "In11.Cu")
		(net "M_L_CPU0_SA_DQ<30>")
	)
	(segment
		(start 417.350956 -232.145332)
		(end 417.206176 -232.000552)
		(width 0.14478)
		(layer "In11.Cu")
		(net "M_L_CPU0_SA_DQ<30>")
	)
	(segment
		(start 413.88792 -232.610152)
		(end 412.201614 -232.610152)
		(width 0.14478)
		(layer "In11.Cu")
		(net "M_L_CPU0_SA_DQ<30>")
	)
	(segment
		(start 417.061396 -231.760014)
		(end 414.738058 -231.760014)
		(width 0.14478)
		(layer "In11.Cu")
		(net "M_L_CPU0_SA_DQ<30>")
	)
	(segment
		(start 444.20282 -232.610152)
		(end 441.387992 -232.610152)
		(width 0.14478)
		(layer "In11.Cu")
		(net "M_L_CPU0_SA_DQ<30>")
	)
	(segment
		(start 448.583812 -231.977184)
		(end 448.439032 -232.121964)
		(width 0.14478)
		(layer "In11.Cu")
		(net "M_L_CPU0_SA_DQ<30>")
	)
	(arc
		(start 388.197852 -243.351558)
		(mid 387.914896 -243.427735)
		(end 387.63194 -243.351558)
		(width 0.0889)
		(layer "In11.Cu")
		(net "M_L_CPU0_SA_DQ<30>")
	)
	(arc
		(start 392.330686 -243.351558)
		(mid 392.151699 -243.301388)
		(end 391.970768 -243.343938)
		(width 0.0889)
		(layer "In11.Cu")
		(net "M_L_CPU0_SA_DQ<30>")
	)
	(arc
		(start 391.391902 -243.351558)
		(mid 391.209651 -243.301208)
		(end 391.026142 -243.346732)
		(width 0.0889)
		(layer "In11.Cu")
		(net "M_L_CPU0_SA_DQ<30>")
	)
	(arc
		(start 391.01776 -243.351558)
		(mid 390.734804 -243.427735)
		(end 390.451848 -243.351558)
		(width 0.0889)
		(layer "In11.Cu")
		(net "M_L_CPU0_SA_DQ<30>")
	)
	(arc
		(start 389.511794 -243.351558)
		(mid 389.32485 -243.301303)
		(end 389.137906 -243.351558)
		(width 0.0889)
		(layer "In11.Cu")
		(net "M_L_CPU0_SA_DQ<30>")
	)
	(arc
		(start 389.137906 -243.351558)
		(mid 388.85495 -243.427735)
		(end 388.571994 -243.351558)
		(width 0.0889)
		(layer "In11.Cu")
		(net "M_L_CPU0_SA_DQ<30>")
	)
	(arc
		(start 390.443466 -243.346732)
		(mid 390.259958 -243.301238)
		(end 390.077706 -243.351558)
		(width 0.0889)
		(layer "In11.Cu")
		(net "M_L_CPU0_SA_DQ<30>")
	)
	(arc
		(start 392.89736 -243.351558)
		(mid 392.624416 -243.428138)
		(end 392.34872 -243.362226)
		(width 0.0889)
		(layer "In11.Cu")
		(net "M_L_CPU0_SA_DQ<30>")
	)
	(arc
		(start 391.945114 -243.35867)
		(mid 391.66758 -243.427651)
		(end 391.391902 -243.351558)
		(width 0.0889)
		(layer "In11.Cu")
		(net "M_L_CPU0_SA_DQ<30>")
	)
	(arc
		(start 390.077706 -243.351558)
		(mid 389.79475 -243.427735)
		(end 389.511794 -243.351558)
		(width 0.0889)
		(layer "In11.Cu")
		(net "M_L_CPU0_SA_DQ<30>")
	)
	(arc
		(start 393.084812 -243.300758)
		(mid 392.987723 -243.313748)
		(end 392.89736 -243.351558)
		(width 0.0889)
		(layer "In11.Cu")
		(net "M_L_CPU0_SA_DQ<30>")
	)
	(arc
		(start 387.63194 -243.351558)
		(mid 387.475502 -243.302587)
		(end 387.31317 -243.325396)
		(width 0.0889)
		(layer "In11.Cu")
		(net "M_L_CPU0_SA_DQ<30>")
	)
	(arc
		(start 388.571994 -243.351558)
		(mid 388.389743 -243.301208)
		(end 388.206234 -243.346732)
		(width 0.0889)
		(layer "In11.Cu")
		(net "M_L_CPU0_SA_DQ<30>")
	)
	(segment
		(start 386.97789 -226.120198)
		(end 387.444742 -225.85426)
		(width 0.10668)
		(layer "F.Cu")
		(net "M_L_CPU0_SA_DQ<2>")
	)
	(segment
		(start 425.912534 -197.760336)
		(end 422.40962 -197.760336)
		(width 0.14478)
		(layer "In11.Cu")
		(net "M_L_CPU0_SA_DQ<2>")
	)
	(segment
		(start 448.256406 -197.905116)
		(end 448.111626 -197.760336)
		(width 0.14478)
		(layer "In11.Cu")
		(net "M_L_CPU0_SA_DQ<2>")
	)
	(segment
		(start 402.959824 -206.269336)
		(end 402.959824 -206.499968)
		(width 0.14478)
		(layer "In11.Cu")
		(net "M_L_CPU0_SA_DQ<2>")
	)
	(segment
		(start 402.566124 -206.663036)
		(end 402.392642 -206.489554)
		(width 0.14478)
		(layer "In11.Cu")
		(net "M_L_CPU0_SA_DQ<2>")
	)
	(segment
		(start 400.817842 -208.064354)
		(end 400.58721 -208.064354)
		(width 0.14478)
		(layer "In11.Cu")
		(net "M_L_CPU0_SA_DQ<2>")
	)
	(segment
		(start 404.140924 -205.088236)
		(end 403.967442 -204.914754)
		(width 0.14478)
		(layer "In11.Cu")
		(net "M_L_CPU0_SA_DQ<2>")
	)
	(segment
		(start 390.116822 -225.50882)
		(end 390.077706 -225.53168)
		(width 0.0889)
		(layer "In11.Cu")
		(net "M_L_CPU0_SA_DQ<2>")
	)
	(segment
		(start 413.945832 -198.61022)
		(end 410.041344 -198.61022)
		(width 0.14478)
		(layer "In11.Cu")
		(net "M_L_CPU0_SA_DQ<2>")
	)
	(segment
		(start 390.584182 -224.700592)
		(end 390.54786 -224.721674)
		(width 0.0889)
		(layer "In11.Cu")
		(net "M_L_CPU0_SA_DQ<2>")
	)
	(segment
		(start 449.663312 -197.760336)
		(end 448.95262 -197.760336)
		(width 0.14478)
		(layer "In11.Cu")
		(net "M_L_CPU0_SA_DQ<2>")
	)
	(segment
		(start 414.79597 -197.760082)
		(end 413.945832 -198.61022)
		(width 0.14478)
		(layer "In11.Cu")
		(net "M_L_CPU0_SA_DQ<2>")
	)
	(segment
		(start 401.385024 -207.844136)
		(end 401.385024 -208.074768)
		(width 0.14478)
		(layer "In11.Cu")
		(net "M_L_CPU0_SA_DQ<2>")
	)
	(segment
		(start 421.559736 -198.61022)
		(end 419.618922 -198.61022)
		(width 0.14478)
		(layer "In11.Cu")
		(net "M_L_CPU0_SA_DQ<2>")
	)
	(segment
		(start 422.40962 -197.760336)
		(end 421.559736 -198.61022)
		(width 0.14478)
		(layer "In11.Cu")
		(net "M_L_CPU0_SA_DQ<2>")
	)
	(segment
		(start 434.040788 -198.61022)
		(end 433.190904 -197.760336)
		(width 0.14478)
		(layer "In11.Cu")
		(net "M_L_CPU0_SA_DQ<2>")
	)
	(segment
		(start 391.01776 -223.911668)
		(end 390.98601 -223.929956)
		(width 0.0889)
		(layer "In11.Cu")
		(net "M_L_CPU0_SA_DQ<2>")
	)
	(segment
		(start 448.111626 -197.760336)
		(end 444.750952 -197.760336)
		(width 0.14478)
		(layer "In11.Cu")
		(net "M_L_CPU0_SA_DQ<2>")
	)
	(segment
		(start 403.180042 -205.702154)
		(end 402.94941 -205.702154)
		(width 0.14478)
		(layer "In11.Cu")
		(net "M_L_CPU0_SA_DQ<2>")
	)
	(segment
		(start 403.967442 -204.914754)
		(end 403.73681 -204.914754)
		(width 0.14478)
		(layer "In11.Cu")
		(net "M_L_CPU0_SA_DQ<2>")
	)
	(segment
		(start 448.80784 -197.905116)
		(end 448.80784 -198.015352)
		(width 0.14478)
		(layer "In11.Cu")
		(net "M_L_CPU0_SA_DQ<2>")
	)
	(segment
		(start 402.172424 -207.287368)
		(end 402.009356 -207.450436)
		(width 0.14478)
		(layer "In11.Cu")
		(net "M_L_CPU0_SA_DQ<2>")
	)
	(segment
		(start 403.73681 -204.914754)
		(end 403.573742 -205.077822)
		(width 0.14478)
		(layer "In11.Cu")
		(net "M_L_CPU0_SA_DQ<2>")
	)
	(segment
		(start 403.353524 -205.875636)
		(end 403.180042 -205.702154)
		(width 0.14478)
		(layer "In11.Cu")
		(net "M_L_CPU0_SA_DQ<2>")
	)
	(segment
		(start 401.605242 -207.276954)
		(end 401.37461 -207.276954)
		(width 0.14478)
		(layer "In11.Cu")
		(net "M_L_CPU0_SA_DQ<2>")
	)
	(segment
		(start 392.460988 -221.389702)
		(end 392.240516 -221.610174)
		(width 0.0889)
		(layer "In11.Cu")
		(net "M_L_CPU0_SA_DQ<2>")
	)
	(segment
		(start 433.190904 -197.760336)
		(end 429.777144 -197.760336)
		(width 0.14478)
		(layer "In11.Cu")
		(net "M_L_CPU0_SA_DQ<2>")
	)
	(segment
		(start 402.392642 -206.489554)
		(end 402.16201 -206.489554)
		(width 0.14478)
		(layer "In11.Cu")
		(net "M_L_CPU0_SA_DQ<2>")
	)
	(segment
		(start 400.597624 -208.631536)
		(end 400.597624 -208.862168)
		(width 0.14478)
		(layer "In11.Cu")
		(net "M_L_CPU0_SA_DQ<2>")
	)
	(segment
		(start 402.94941 -205.702154)
		(end 402.786342 -205.865222)
		(width 0.14478)
		(layer "In11.Cu")
		(net "M_L_CPU0_SA_DQ<2>")
	)
	(segment
		(start 400.597624 -208.862168)
		(end 392.460988 -216.998804)
		(width 0.14478)
		(layer "In11.Cu")
		(net "M_L_CPU0_SA_DQ<2>")
	)
	(segment
		(start 392.460988 -221.201234)
		(end 392.460988 -221.389702)
		(width 0.0889)
		(layer "In11.Cu")
		(net "M_L_CPU0_SA_DQ<2>")
	)
	(segment
		(start 401.998942 -206.652622)
		(end 401.998942 -206.883254)
		(width 0.14478)
		(layer "In11.Cu")
		(net "M_L_CPU0_SA_DQ<2>")
	)
	(segment
		(start 392.240516 -221.610174)
		(end 392.240516 -221.80423)
		(width 0.0889)
		(layer "In11.Cu")
		(net "M_L_CPU0_SA_DQ<2>")
	)
	(segment
		(start 448.80784 -198.015352)
		(end 448.66306 -198.160132)
		(width 0.14478)
		(layer "In11.Cu")
		(net "M_L_CPU0_SA_DQ<2>")
	)
	(segment
		(start 441.636404 -198.61022)
		(end 440.78652 -197.760336)
		(width 0.14478)
		(layer "In11.Cu")
		(net "M_L_CPU0_SA_DQ<2>")
	)
	(segment
		(start 404.361142 -204.290422)
		(end 404.361142 -204.521054)
		(width 0.14478)
		(layer "In11.Cu")
		(net "M_L_CPU0_SA_DQ<2>")
	)
	(segment
		(start 400.991324 -208.237836)
		(end 400.817842 -208.064354)
		(width 0.14478)
		(layer "In11.Cu")
		(net "M_L_CPU0_SA_DQ<2>")
	)
	(segment
		(start 402.959824 -206.499968)
		(end 402.796756 -206.663036)
		(width 0.14478)
		(layer "In11.Cu")
		(net "M_L_CPU0_SA_DQ<2>")
	)
	(segment
		(start 387.31317 -225.505518)
		(end 387.290818 -225.58883)
		(width 0.0889)
		(layer "In11.Cu")
		(net "M_L_CPU0_SA_DQ<2>")
	)
	(segment
		(start 440.78652 -197.760336)
		(end 437.463184 -197.760336)
		(width 0.14478)
		(layer "In11.Cu")
		(net "M_L_CPU0_SA_DQ<2>")
	)
	(segment
		(start 418.768784 -197.760082)
		(end 414.79597 -197.760082)
		(width 0.14478)
		(layer "In11.Cu")
		(net "M_L_CPU0_SA_DQ<2>")
	)
	(segment
		(start 391.48766 -223.101662)
		(end 391.45718 -223.119442)
		(width 0.0889)
		(layer "In11.Cu")
		(net "M_L_CPU0_SA_DQ<2>")
	)
	(segment
		(start 404.534624 -204.925168)
		(end 404.371556 -205.088236)
		(width 0.14478)
		(layer "In11.Cu")
		(net "M_L_CPU0_SA_DQ<2>")
	)
	(segment
		(start 402.786342 -205.865222)
		(end 402.786342 -206.095854)
		(width 0.14478)
		(layer "In11.Cu")
		(net "M_L_CPU0_SA_DQ<2>")
	)
	(segment
		(start 448.401186 -198.160132)
		(end 448.256406 -198.015352)
		(width 0.14478)
		(layer "In11.Cu")
		(net "M_L_CPU0_SA_DQ<2>")
	)
	(segment
		(start 403.584156 -205.875636)
		(end 403.353524 -205.875636)
		(width 0.14478)
		(layer "In11.Cu")
		(net "M_L_CPU0_SA_DQ<2>")
	)
	(segment
		(start 428.92726 -198.61022)
		(end 426.762418 -198.61022)
		(width 0.14478)
		(layer "In11.Cu")
		(net "M_L_CPU0_SA_DQ<2>")
	)
	(segment
		(start 402.009356 -207.450436)
		(end 401.778724 -207.450436)
		(width 0.14478)
		(layer "In11.Cu")
		(net "M_L_CPU0_SA_DQ<2>")
	)
	(segment
		(start 401.37461 -207.276954)
		(end 401.211542 -207.440022)
		(width 0.14478)
		(layer "In11.Cu")
		(net "M_L_CPU0_SA_DQ<2>")
	)
	(segment
		(start 391.99185 -222.272352)
		(end 391.93597 -222.310198)
		(width 0.0889)
		(layer "In11.Cu")
		(net "M_L_CPU0_SA_DQ<2>")
	)
	(segment
		(start 426.762418 -198.61022)
		(end 425.912534 -197.760336)
		(width 0.14478)
		(layer "In11.Cu")
		(net "M_L_CPU0_SA_DQ<2>")
	)
	(segment
		(start 402.172424 -207.056736)
		(end 402.172424 -207.287368)
		(width 0.14478)
		(layer "In11.Cu")
		(net "M_L_CPU0_SA_DQ<2>")
	)
	(segment
		(start 387.290818 -225.58883)
		(end 387.444742 -225.85426)
		(width 0.0889)
		(layer "In11.Cu")
		(net "M_L_CPU0_SA_DQ<2>")
	)
	(segment
		(start 436.6133 -198.61022)
		(end 434.040788 -198.61022)
		(width 0.14478)
		(layer "In11.Cu")
		(net "M_L_CPU0_SA_DQ<2>")
	)
	(segment
		(start 419.618922 -198.61022)
		(end 418.768784 -197.760082)
		(width 0.14478)
		(layer "In11.Cu")
		(net "M_L_CPU0_SA_DQ<2>")
	)
	(segment
		(start 390.54786 -224.721674)
		(end 390.51611 -224.739962)
		(width 0.0889)
		(layer "In11.Cu")
		(net "M_L_CPU0_SA_DQ<2>")
	)
	(segment
		(start 401.998942 -206.883254)
		(end 402.172424 -207.056736)
		(width 0.14478)
		(layer "In11.Cu")
		(net "M_L_CPU0_SA_DQ<2>")
	)
	(segment
		(start 403.573742 -205.077822)
		(end 403.573742 -205.308454)
		(width 0.14478)
		(layer "In11.Cu")
		(net "M_L_CPU0_SA_DQ<2>")
	)
	(segment
		(start 437.463184 -197.760336)
		(end 436.6133 -198.61022)
		(width 0.14478)
		(layer "In11.Cu")
		(net "M_L_CPU0_SA_DQ<2>")
	)
	(segment
		(start 391.52957 -223.077278)
		(end 391.48766 -223.101662)
		(width 0.0889)
		(layer "In11.Cu")
		(net "M_L_CPU0_SA_DQ<2>")
	)
	(segment
		(start 448.256406 -198.015352)
		(end 448.256406 -197.905116)
		(width 0.14478)
		(layer "In11.Cu")
		(net "M_L_CPU0_SA_DQ<2>")
	)
	(segment
		(start 401.385024 -208.074768)
		(end 401.221956 -208.237836)
		(width 0.14478)
		(layer "In11.Cu")
		(net "M_L_CPU0_SA_DQ<2>")
	)
	(segment
		(start 410.041344 -198.61022)
		(end 404.361142 -204.290422)
		(width 0.14478)
		(layer "In11.Cu")
		(net "M_L_CPU0_SA_DQ<2>")
	)
	(segment
		(start 400.424142 -208.227422)
		(end 400.424142 -208.458054)
		(width 0.14478)
		(layer "In11.Cu")
		(net "M_L_CPU0_SA_DQ<2>")
	)
	(segment
		(start 402.796756 -206.663036)
		(end 402.566124 -206.663036)
		(width 0.14478)
		(layer "In11.Cu")
		(net "M_L_CPU0_SA_DQ<2>")
	)
	(segment
		(start 429.777144 -197.760336)
		(end 428.92726 -198.61022)
		(width 0.14478)
		(layer "In11.Cu")
		(net "M_L_CPU0_SA_DQ<2>")
	)
	(segment
		(start 404.534624 -204.694536)
		(end 404.534624 -204.925168)
		(width 0.14478)
		(layer "In11.Cu")
		(net "M_L_CPU0_SA_DQ<2>")
	)
	(segment
		(start 401.211542 -207.440022)
		(end 401.211542 -207.670654)
		(width 0.14478)
		(layer "In11.Cu")
		(net "M_L_CPU0_SA_DQ<2>")
	)
	(segment
		(start 403.747224 -205.481936)
		(end 403.747224 -205.712568)
		(width 0.14478)
		(layer "In11.Cu")
		(net "M_L_CPU0_SA_DQ<2>")
	)
	(segment
		(start 448.95262 -197.760336)
		(end 448.80784 -197.905116)
		(width 0.14478)
		(layer "In11.Cu")
		(net "M_L_CPU0_SA_DQ<2>")
	)
	(segment
		(start 448.66306 -198.160132)
		(end 448.401186 -198.160132)
		(width 0.14478)
		(layer "In11.Cu")
		(net "M_L_CPU0_SA_DQ<2>")
	)
	(segment
		(start 402.16201 -206.489554)
		(end 401.998942 -206.652622)
		(width 0.14478)
		(layer "In11.Cu")
		(net "M_L_CPU0_SA_DQ<2>")
	)
	(segment
		(start 444.750952 -197.760336)
		(end 443.901068 -198.61022)
		(width 0.14478)
		(layer "In11.Cu")
		(net "M_L_CPU0_SA_DQ<2>")
	)
	(segment
		(start 401.211542 -207.670654)
		(end 401.385024 -207.844136)
		(width 0.14478)
		(layer "In11.Cu")
		(net "M_L_CPU0_SA_DQ<2>")
	)
	(segment
		(start 404.361142 -204.521054)
		(end 404.534624 -204.694536)
		(width 0.14478)
		(layer "In11.Cu")
		(net "M_L_CPU0_SA_DQ<2>")
	)
	(segment
		(start 400.424142 -208.458054)
		(end 400.597624 -208.631536)
		(width 0.14478)
		(layer "In11.Cu")
		(net "M_L_CPU0_SA_DQ<2>")
	)
	(segment
		(start 392.460988 -216.998804)
		(end 392.460988 -221.201234)
		(width 0.14478)
		(layer "In11.Cu")
		(net "M_L_CPU0_SA_DQ<2>")
	)
	(segment
		(start 450.088 -198.185024)
		(end 449.663312 -197.760336)
		(width 0.14478)
		(layer "In11.Cu")
		(net "M_L_CPU0_SA_DQ<2>")
	)
	(segment
		(start 391.929366 -222.315532)
		(end 391.869168 -222.37573)
		(width 0.0889)
		(layer "In11.Cu")
		(net "M_L_CPU0_SA_DQ<2>")
	)
	(segment
		(start 400.58721 -208.064354)
		(end 400.424142 -208.227422)
		(width 0.14478)
		(layer "In11.Cu")
		(net "M_L_CPU0_SA_DQ<2>")
	)
	(segment
		(start 391.056876 -223.888808)
		(end 391.01776 -223.911668)
		(width 0.0889)
		(layer "In11.Cu")
		(net "M_L_CPU0_SA_DQ<2>")
	)
	(segment
		(start 401.778724 -207.450436)
		(end 401.605242 -207.276954)
		(width 0.14478)
		(layer "In11.Cu")
		(net "M_L_CPU0_SA_DQ<2>")
	)
	(segment
		(start 402.786342 -206.095854)
		(end 402.959824 -206.269336)
		(width 0.14478)
		(layer "In11.Cu")
		(net "M_L_CPU0_SA_DQ<2>")
	)
	(segment
		(start 388.206234 -225.526854)
		(end 388.197852 -225.53168)
		(width 0.0889)
		(layer "In11.Cu")
		(net "M_L_CPU0_SA_DQ<2>")
	)
	(segment
		(start 401.221956 -208.237836)
		(end 400.991324 -208.237836)
		(width 0.14478)
		(layer "In11.Cu")
		(net "M_L_CPU0_SA_DQ<2>")
	)
	(segment
		(start 404.371556 -205.088236)
		(end 404.140924 -205.088236)
		(width 0.14478)
		(layer "In11.Cu")
		(net "M_L_CPU0_SA_DQ<2>")
	)
	(segment
		(start 403.573742 -205.308454)
		(end 403.747224 -205.481936)
		(width 0.14478)
		(layer "In11.Cu")
		(net "M_L_CPU0_SA_DQ<2>")
	)
	(segment
		(start 443.901068 -198.61022)
		(end 441.636404 -198.61022)
		(width 0.14478)
		(layer "In11.Cu")
		(net "M_L_CPU0_SA_DQ<2>")
	)
	(segment
		(start 403.747224 -205.712568)
		(end 403.584156 -205.875636)
		(width 0.14478)
		(layer "In11.Cu")
		(net "M_L_CPU0_SA_DQ<2>")
	)
	(arc
		(start 390.830054 -224.234248)
		(mid 390.764818 -224.497839)
		(end 390.584182 -224.700592)
		(width 0.0889)
		(layer "In11.Cu")
		(net "M_L_CPU0_SA_DQ<2>")
	)
	(arc
		(start 389.511794 -225.53168)
		(mid 389.32485 -225.481425)
		(end 389.137906 -225.53168)
		(width 0.0889)
		(layer "In11.Cu")
		(net "M_L_CPU0_SA_DQ<2>")
	)
	(arc
		(start 388.197852 -225.53168)
		(mid 387.914896 -225.607857)
		(end 387.63194 -225.53168)
		(width 0.0889)
		(layer "In11.Cu")
		(net "M_L_CPU0_SA_DQ<2>")
	)
	(arc
		(start 390.51611 -224.739962)
		(mid 390.401434 -224.873296)
		(end 390.360154 -225.044254)
		(width 0.0889)
		(layer "In11.Cu")
		(net "M_L_CPU0_SA_DQ<2>")
	)
	(arc
		(start 391.869168 -222.37573)
		(mid 391.796051 -222.485157)
		(end 391.770362 -222.614236)
		(width 0.0889)
		(layer "In11.Cu")
		(net "M_L_CPU0_SA_DQ<2>")
	)
	(arc
		(start 391.300208 -223.424242)
		(mid 391.235693 -223.686461)
		(end 391.056876 -223.888808)
		(width 0.0889)
		(layer "In11.Cu")
		(net "M_L_CPU0_SA_DQ<2>")
	)
	(arc
		(start 390.98601 -223.929956)
		(mid 390.871334 -224.06329)
		(end 390.830054 -224.234248)
		(width 0.0889)
		(layer "In11.Cu")
		(net "M_L_CPU0_SA_DQ<2>")
	)
	(arc
		(start 389.137906 -225.53168)
		(mid 388.85495 -225.607857)
		(end 388.571994 -225.53168)
		(width 0.0889)
		(layer "In11.Cu")
		(net "M_L_CPU0_SA_DQ<2>")
	)
	(arc
		(start 391.93597 -222.310198)
		(mid 391.932544 -222.312711)
		(end 391.929366 -222.315532)
		(width 0.0889)
		(layer "In11.Cu")
		(net "M_L_CPU0_SA_DQ<2>")
	)
	(arc
		(start 391.770362 -222.614236)
		(mid 391.70657 -222.875195)
		(end 391.52957 -223.077278)
		(width 0.0889)
		(layer "In11.Cu")
		(net "M_L_CPU0_SA_DQ<2>")
	)
	(arc
		(start 387.63194 -225.53168)
		(mid 387.475502 -225.482709)
		(end 387.31317 -225.505518)
		(width 0.0889)
		(layer "In11.Cu")
		(net "M_L_CPU0_SA_DQ<2>")
	)
	(arc
		(start 392.240516 -221.80423)
		(mid 392.174486 -222.069258)
		(end 391.99185 -222.272352)
		(width 0.0889)
		(layer "In11.Cu")
		(net "M_L_CPU0_SA_DQ<2>")
	)
	(arc
		(start 390.077706 -225.53168)
		(mid 389.79475 -225.607857)
		(end 389.511794 -225.53168)
		(width 0.0889)
		(layer "In11.Cu")
		(net "M_L_CPU0_SA_DQ<2>")
	)
	(arc
		(start 390.360154 -225.044254)
		(mid 390.295639 -225.306473)
		(end 390.116822 -225.50882)
		(width 0.0889)
		(layer "In11.Cu")
		(net "M_L_CPU0_SA_DQ<2>")
	)
	(arc
		(start 391.45718 -223.119442)
		(mid 391.341753 -223.252818)
		(end 391.300208 -223.424242)
		(width 0.0889)
		(layer "In11.Cu")
		(net "M_L_CPU0_SA_DQ<2>")
	)
	(arc
		(start 388.571994 -225.53168)
		(mid 388.389743 -225.48133)
		(end 388.206234 -225.526854)
		(width 0.0889)
		(layer "In11.Cu")
		(net "M_L_CPU0_SA_DQ<2>")
	)
	(segment
		(start 385.098036 -243.940076)
		(end 385.564888 -243.674138)
		(width 0.10668)
		(layer "F.Cu")
		(net "M_L_CPU0_SA_DQ<29>")
	)
	(segment
		(start 437.463184 -232.610152)
		(end 440.602116 -232.610152)
		(width 0.14478)
		(layer "In11.Cu")
		(net "M_L_CPU0_SA_DQ<29>")
	)
	(segment
		(start 395.583918 -243.486432)
		(end 395.583918 -243.209572)
		(width 0.0889)
		(layer "In11.Cu")
		(net "M_L_CPU0_SA_DQ<29>")
	)
	(segment
		(start 407.869898 -237.857284)
		(end 412.267146 -233.460036)
		(width 0.14478)
		(layer "In11.Cu")
		(net "M_L_CPU0_SA_DQ<29>")
	)
	(segment
		(start 388.197852 -243.996718)
		(end 388.206234 -244.001544)
		(width 0.0889)
		(layer "In11.Cu")
		(net "M_L_CPU0_SA_DQ<29>")
	)
	(segment
		(start 392.323828 -244.001544)
		(end 392.33221 -243.996718)
		(width 0.0889)
		(layer "In11.Cu")
		(net "M_L_CPU0_SA_DQ<29>")
	)
	(segment
		(start 395.02334 -244.04701)
		(end 395.583918 -243.486432)
		(width 0.0889)
		(layer "In11.Cu")
		(net "M_L_CPU0_SA_DQ<29>")
	)
	(segment
		(start 395.72819 -243.0653)
		(end 395.969998 -243.0653)
		(width 0.0889)
		(layer "In11.Cu")
		(net "M_L_CPU0_SA_DQ<29>")
	)
	(segment
		(start 395.583918 -243.209572)
		(end 395.72819 -243.0653)
		(width 0.0889)
		(layer "In11.Cu")
		(net "M_L_CPU0_SA_DQ<29>")
	)
	(segment
		(start 385.718812 -243.939568)
		(end 385.814824 -243.964968)
		(width 0.0889)
		(layer "In11.Cu")
		(net "M_L_CPU0_SA_DQ<29>")
	)
	(segment
		(start 392.887454 -243.990622)
		(end 392.897868 -243.996718)
		(width 0.0889)
		(layer "In11.Cu")
		(net "M_L_CPU0_SA_DQ<29>")
	)
	(segment
		(start 418.331396 -232.610152)
		(end 419.18128 -233.460036)
		(width 0.14478)
		(layer "In11.Cu")
		(net "M_L_CPU0_SA_DQ<29>")
	)
	(segment
		(start 413.685482 -233.460036)
		(end 414.535366 -232.610152)
		(width 0.14478)
		(layer "In11.Cu")
		(net "M_L_CPU0_SA_DQ<29>")
	)
	(segment
		(start 425.912534 -232.610152)
		(end 426.762418 -233.460036)
		(width 0.14478)
		(layer "In11.Cu")
		(net "M_L_CPU0_SA_DQ<29>")
	)
	(segment
		(start 445.530732 -232.610152)
		(end 452.051674 -232.610152)
		(width 0.14478)
		(layer "In11.Cu")
		(net "M_L_CPU0_SA_DQ<29>")
	)
	(segment
		(start 443.481968 -233.458766)
		(end 445.530732 -232.610152)
		(width 0.14478)
		(layer "In11.Cu")
		(net "M_L_CPU0_SA_DQ<29>")
	)
	(segment
		(start 386.683504 -244.001544)
		(end 386.691886 -243.996718)
		(width 0.0889)
		(layer "In11.Cu")
		(net "M_L_CPU0_SA_DQ<29>")
	)
	(segment
		(start 433.190904 -232.610152)
		(end 434.040788 -233.460036)
		(width 0.14478)
		(layer "In11.Cu")
		(net "M_L_CPU0_SA_DQ<29>")
	)
	(segment
		(start 428.941992 -233.460036)
		(end 429.791876 -232.610152)
		(width 0.14478)
		(layer "In11.Cu")
		(net "M_L_CPU0_SA_DQ<29>")
	)
	(segment
		(start 421.45966 -233.460036)
		(end 422.309544 -232.610152)
		(width 0.14478)
		(layer "In11.Cu")
		(net "M_L_CPU0_SA_DQ<29>")
	)
	(segment
		(start 440.602116 -232.610152)
		(end 441.45073 -233.458766)
		(width 0.14478)
		(layer "In11.Cu")
		(net "M_L_CPU0_SA_DQ<29>")
	)
	(segment
		(start 391.01776 -243.996718)
		(end 391.026142 -244.001544)
		(width 0.0889)
		(layer "In11.Cu")
		(net "M_L_CPU0_SA_DQ<29>")
	)
	(segment
		(start 434.040788 -233.460036)
		(end 436.6133 -233.460036)
		(width 0.14478)
		(layer "In11.Cu")
		(net "M_L_CPU0_SA_DQ<29>")
	)
	(segment
		(start 414.535366 -232.610152)
		(end 418.331396 -232.610152)
		(width 0.14478)
		(layer "In11.Cu")
		(net "M_L_CPU0_SA_DQ<29>")
	)
	(segment
		(start 393.084812 -244.04701)
		(end 395.02334 -244.04701)
		(width 0.0889)
		(layer "In11.Cu")
		(net "M_L_CPU0_SA_DQ<29>")
	)
	(segment
		(start 441.45073 -233.458766)
		(end 443.481968 -233.458766)
		(width 0.14478)
		(layer "In11.Cu")
		(net "M_L_CPU0_SA_DQ<29>")
	)
	(segment
		(start 395.969998 -243.0653)
		(end 403.696424 -243.0653)
		(width 0.14478)
		(layer "In11.Cu")
		(net "M_L_CPU0_SA_DQ<29>")
	)
	(segment
		(start 426.762418 -233.460036)
		(end 428.941992 -233.460036)
		(width 0.14478)
		(layer "In11.Cu")
		(net "M_L_CPU0_SA_DQ<29>")
	)
	(segment
		(start 419.18128 -233.460036)
		(end 421.45966 -233.460036)
		(width 0.14478)
		(layer "In11.Cu")
		(net "M_L_CPU0_SA_DQ<29>")
	)
	(segment
		(start 452.051674 -232.610152)
		(end 454.188068 -233.035094)
		(width 0.14478)
		(layer "In11.Cu")
		(net "M_L_CPU0_SA_DQ<29>")
	)
	(segment
		(start 391.391902 -243.996718)
		(end 391.402316 -243.990622)
		(width 0.0889)
		(layer "In11.Cu")
		(net "M_L_CPU0_SA_DQ<29>")
	)
	(segment
		(start 403.696424 -243.0653)
		(end 407.869898 -238.891826)
		(width 0.14478)
		(layer "In11.Cu")
		(net "M_L_CPU0_SA_DQ<29>")
	)
	(segment
		(start 407.869898 -238.891826)
		(end 407.869898 -237.857284)
		(width 0.14478)
		(layer "In11.Cu")
		(net "M_L_CPU0_SA_DQ<29>")
	)
	(segment
		(start 412.267146 -233.460036)
		(end 413.685482 -233.460036)
		(width 0.14478)
		(layer "In11.Cu")
		(net "M_L_CPU0_SA_DQ<29>")
	)
	(segment
		(start 436.6133 -233.460036)
		(end 437.463184 -232.610152)
		(width 0.14478)
		(layer "In11.Cu")
		(net "M_L_CPU0_SA_DQ<29>")
	)
	(segment
		(start 385.564888 -243.674138)
		(end 385.718812 -243.939568)
		(width 0.0889)
		(layer "In11.Cu")
		(net "M_L_CPU0_SA_DQ<29>")
	)
	(segment
		(start 429.791876 -232.610152)
		(end 433.190904 -232.610152)
		(width 0.14478)
		(layer "In11.Cu")
		(net "M_L_CPU0_SA_DQ<29>")
	)
	(segment
		(start 422.309544 -232.610152)
		(end 425.912534 -232.610152)
		(width 0.14478)
		(layer "In11.Cu")
		(net "M_L_CPU0_SA_DQ<29>")
	)
	(segment
		(start 390.443466 -244.001544)
		(end 390.451848 -243.996718)
		(width 0.0889)
		(layer "In11.Cu")
		(net "M_L_CPU0_SA_DQ<29>")
	)
	(segment
		(start 387.257798 -243.996718)
		(end 387.26618 -244.001544)
		(width 0.0889)
		(layer "In11.Cu")
		(net "M_L_CPU0_SA_DQ<29>")
	)
	(arc
		(start 388.206234 -244.001544)
		(mid 388.389742 -244.047038)
		(end 388.571994 -243.996718)
		(width 0.0889)
		(layer "In11.Cu")
		(net "M_L_CPU0_SA_DQ<29>")
	)
	(arc
		(start 388.571994 -243.996718)
		(mid 388.85495 -243.920541)
		(end 389.137906 -243.996718)
		(width 0.0889)
		(layer "In11.Cu")
		(net "M_L_CPU0_SA_DQ<29>")
	)
	(arc
		(start 386.691886 -243.996718)
		(mid 386.974842 -243.920541)
		(end 387.257798 -243.996718)
		(width 0.0889)
		(layer "In11.Cu")
		(net "M_L_CPU0_SA_DQ<29>")
	)
	(arc
		(start 389.511794 -243.996718)
		(mid 389.79475 -243.920541)
		(end 390.077706 -243.996718)
		(width 0.0889)
		(layer "In11.Cu")
		(net "M_L_CPU0_SA_DQ<29>")
	)
	(arc
		(start 391.958068 -243.996718)
		(mid 392.140319 -244.047068)
		(end 392.323828 -244.001544)
		(width 0.0889)
		(layer "In11.Cu")
		(net "M_L_CPU0_SA_DQ<29>")
	)
	(arc
		(start 385.814824 -243.964968)
		(mid 386.070032 -243.921491)
		(end 386.317744 -243.996718)
		(width 0.0889)
		(layer "In11.Cu")
		(net "M_L_CPU0_SA_DQ<29>")
	)
	(arc
		(start 389.137906 -243.996718)
		(mid 389.32485 -244.046973)
		(end 389.511794 -243.996718)
		(width 0.0889)
		(layer "In11.Cu")
		(net "M_L_CPU0_SA_DQ<29>")
	)
	(arc
		(start 392.897868 -243.996718)
		(mid 392.988017 -244.034215)
		(end 393.084812 -244.04701)
		(width 0.0889)
		(layer "In11.Cu")
		(net "M_L_CPU0_SA_DQ<29>")
	)
	(arc
		(start 386.317744 -243.996718)
		(mid 386.499995 -244.047068)
		(end 386.683504 -244.001544)
		(width 0.0889)
		(layer "In11.Cu")
		(net "M_L_CPU0_SA_DQ<29>")
	)
	(arc
		(start 391.026142 -244.001544)
		(mid 391.20965 -244.047038)
		(end 391.391902 -243.996718)
		(width 0.0889)
		(layer "In11.Cu")
		(net "M_L_CPU0_SA_DQ<29>")
	)
	(arc
		(start 390.077706 -243.996718)
		(mid 390.259957 -244.047068)
		(end 390.443466 -244.001544)
		(width 0.0889)
		(layer "In11.Cu")
		(net "M_L_CPU0_SA_DQ<29>")
	)
	(arc
		(start 387.63194 -243.996718)
		(mid 387.914896 -243.920541)
		(end 388.197852 -243.996718)
		(width 0.0889)
		(layer "In11.Cu")
		(net "M_L_CPU0_SA_DQ<29>")
	)
	(arc
		(start 387.26618 -244.001544)
		(mid 387.449688 -244.047038)
		(end 387.63194 -243.996718)
		(width 0.0889)
		(layer "In11.Cu")
		(net "M_L_CPU0_SA_DQ<29>")
	)
	(arc
		(start 391.402316 -243.990622)
		(mid 391.681002 -243.920402)
		(end 391.958068 -243.996718)
		(width 0.0889)
		(layer "In11.Cu")
		(net "M_L_CPU0_SA_DQ<29>")
	)
	(arc
		(start 392.33221 -243.996718)
		(mid 392.609023 -243.920575)
		(end 392.887454 -243.990622)
		(width 0.0889)
		(layer "In11.Cu")
		(net "M_L_CPU0_SA_DQ<29>")
	)
	(arc
		(start 390.451848 -243.996718)
		(mid 390.734804 -243.920541)
		(end 391.01776 -243.996718)
		(width 0.0889)
		(layer "In11.Cu")
		(net "M_L_CPU0_SA_DQ<29>")
	)
	(segment
		(start 386.50799 -243.13007)
		(end 386.974842 -242.864132)
		(width 0.10668)
		(layer "F.Cu")
		(net "M_L_CPU0_SA_DQ<28>")
	)
	(segment
		(start 393.854178 -243.110258)
		(end 394.240512 -243.496592)
		(width 0.0889)
		(layer "In11.Cu")
		(net "M_L_CPU0_SA_DQ<28>")
	)
	(segment
		(start 433.200302 -230.919528)
		(end 434.050186 -231.769412)
		(width 0.14478)
		(layer "In11.Cu")
		(net "M_L_CPU0_SA_DQ<28>")
	)
	(segment
		(start 391.861548 -243.186458)
		(end 391.873486 -243.1796)
		(width 0.0889)
		(layer "In11.Cu")
		(net "M_L_CPU0_SA_DQ<28>")
	)
	(segment
		(start 389.033512 -243.191538)
		(end 389.041894 -243.186712)
		(width 0.0889)
		(layer "In11.Cu")
		(net "M_L_CPU0_SA_DQ<28>")
	)
	(segment
		(start 395.726158 -242.15598)
		(end 403.279356 -242.15598)
		(width 0.14478)
		(layer "In11.Cu")
		(net "M_L_CPU0_SA_DQ<28>")
	)
	(segment
		(start 453.763126 -230.91013)
		(end 454.188068 -231.335072)
		(width 0.14478)
		(layer "In11.Cu")
		(net "M_L_CPU0_SA_DQ<28>")
	)
	(segment
		(start 386.974842 -242.864132)
		(end 387.128766 -243.129562)
		(width 0.0889)
		(layer "In11.Cu")
		(net "M_L_CPU0_SA_DQ<28>")
	)
	(segment
		(start 394.240512 -243.496592)
		(end 394.860018 -243.496592)
		(width 0.0889)
		(layer "In11.Cu")
		(net "M_L_CPU0_SA_DQ<28>")
	)
	(segment
		(start 452.869808 -231.064308)
		(end 453.014588 -230.919528)
		(width 0.14478)
		(layer "In11.Cu")
		(net "M_L_CPU0_SA_DQ<28>")
	)
	(segment
		(start 395.108938 -243.247672)
		(end 395.108938 -242.572032)
		(width 0.0889)
		(layer "In11.Cu")
		(net "M_L_CPU0_SA_DQ<28>")
	)
	(segment
		(start 452.463154 -231.528112)
		(end 452.725028 -231.528112)
		(width 0.14478)
		(layer "In11.Cu")
		(net "M_L_CPU0_SA_DQ<28>")
	)
	(segment
		(start 429.152558 -231.769412)
		(end 430.002442 -230.919528)
		(width 0.14478)
		(layer "In11.Cu")
		(net "M_L_CPU0_SA_DQ<28>")
	)
	(segment
		(start 425.83862 -230.919528)
		(end 426.688504 -231.769412)
		(width 0.14478)
		(layer "In11.Cu")
		(net "M_L_CPU0_SA_DQ<28>")
	)
	(segment
		(start 436.603902 -231.769412)
		(end 437.453786 -230.919528)
		(width 0.14478)
		(layer "In11.Cu")
		(net "M_L_CPU0_SA_DQ<28>")
	)
	(segment
		(start 452.318374 -231.064308)
		(end 452.318374 -231.383332)
		(width 0.14478)
		(layer "In11.Cu")
		(net "M_L_CPU0_SA_DQ<28>")
	)
	(segment
		(start 444.288926 -231.769412)
		(end 445.13881 -230.919528)
		(width 0.14478)
		(layer "In11.Cu")
		(net "M_L_CPU0_SA_DQ<28>")
	)
	(segment
		(start 391.845292 -243.195856)
		(end 391.861548 -243.186458)
		(width 0.0889)
		(layer "In11.Cu")
		(net "M_L_CPU0_SA_DQ<28>")
	)
	(segment
		(start 406.729438 -237.438946)
		(end 412.40837 -231.760014)
		(width 0.14478)
		(layer "In11.Cu")
		(net "M_L_CPU0_SA_DQ<28>")
	)
	(segment
		(start 453.014588 -230.919528)
		(end 453.753728 -230.919528)
		(width 0.14478)
		(layer "In11.Cu")
		(net "M_L_CPU0_SA_DQ<28>")
	)
	(segment
		(start 437.453786 -230.919528)
		(end 440.552586 -230.919528)
		(width 0.14478)
		(layer "In11.Cu")
		(net "M_L_CPU0_SA_DQ<28>")
	)
	(segment
		(start 414.52419 -231.261412)
		(end 418.455856 -231.261412)
		(width 0.14478)
		(layer "In11.Cu")
		(net "M_L_CPU0_SA_DQ<28>")
	)
	(segment
		(start 418.455856 -231.261412)
		(end 418.963856 -231.769412)
		(width 0.14478)
		(layer "In11.Cu")
		(net "M_L_CPU0_SA_DQ<28>")
	)
	(segment
		(start 414.025588 -231.760014)
		(end 414.52419 -231.261412)
		(width 0.14478)
		(layer "In11.Cu")
		(net "M_L_CPU0_SA_DQ<28>")
	)
	(segment
		(start 421.53205 -231.769412)
		(end 422.381934 -230.919528)
		(width 0.14478)
		(layer "In11.Cu")
		(net "M_L_CPU0_SA_DQ<28>")
	)
	(segment
		(start 422.381934 -230.919528)
		(end 425.83862 -230.919528)
		(width 0.14478)
		(layer "In11.Cu")
		(net "M_L_CPU0_SA_DQ<28>")
	)
	(segment
		(start 392.426698 -243.186712)
		(end 392.438382 -243.19357)
		(width 0.0889)
		(layer "In11.Cu")
		(net "M_L_CPU0_SA_DQ<28>")
	)
	(segment
		(start 430.002442 -230.919528)
		(end 433.200302 -230.919528)
		(width 0.14478)
		(layer "In11.Cu")
		(net "M_L_CPU0_SA_DQ<28>")
	)
	(segment
		(start 426.688504 -231.769412)
		(end 429.152558 -231.769412)
		(width 0.14478)
		(layer "In11.Cu")
		(net "M_L_CPU0_SA_DQ<28>")
	)
	(segment
		(start 389.607806 -243.186712)
		(end 389.616188 -243.191538)
		(width 0.0889)
		(layer "In11.Cu")
		(net "M_L_CPU0_SA_DQ<28>")
	)
	(segment
		(start 412.40837 -231.760014)
		(end 414.025588 -231.760014)
		(width 0.14478)
		(layer "In11.Cu")
		(net "M_L_CPU0_SA_DQ<28>")
	)
	(segment
		(start 452.318374 -231.383332)
		(end 452.463154 -231.528112)
		(width 0.14478)
		(layer "In11.Cu")
		(net "M_L_CPU0_SA_DQ<28>")
	)
	(segment
		(start 388.093458 -243.191538)
		(end 388.10184 -243.186712)
		(width 0.0889)
		(layer "In11.Cu")
		(net "M_L_CPU0_SA_DQ<28>")
	)
	(segment
		(start 434.050186 -231.769412)
		(end 436.603902 -231.769412)
		(width 0.14478)
		(layer "In11.Cu")
		(net "M_L_CPU0_SA_DQ<28>")
	)
	(segment
		(start 395.108938 -242.572032)
		(end 395.52499 -242.15598)
		(width 0.0889)
		(layer "In11.Cu")
		(net "M_L_CPU0_SA_DQ<28>")
	)
	(segment
		(start 403.279356 -242.15598)
		(end 406.729438 -238.705898)
		(width 0.14478)
		(layer "In11.Cu")
		(net "M_L_CPU0_SA_DQ<28>")
	)
	(segment
		(start 395.52499 -242.15598)
		(end 395.726158 -242.15598)
		(width 0.0889)
		(layer "In11.Cu")
		(net "M_L_CPU0_SA_DQ<28>")
	)
	(segment
		(start 452.173594 -230.919528)
		(end 452.318374 -231.064308)
		(width 0.14478)
		(layer "In11.Cu")
		(net "M_L_CPU0_SA_DQ<28>")
	)
	(segment
		(start 393.084812 -243.110258)
		(end 393.854178 -243.110258)
		(width 0.0889)
		(layer "In11.Cu")
		(net "M_L_CPU0_SA_DQ<28>")
	)
	(segment
		(start 387.128766 -243.129562)
		(end 387.224778 -243.154962)
		(width 0.0889)
		(layer "In11.Cu")
		(net "M_L_CPU0_SA_DQ<28>")
	)
	(segment
		(start 406.729438 -238.705898)
		(end 406.729438 -237.438946)
		(width 0.14478)
		(layer "In11.Cu")
		(net "M_L_CPU0_SA_DQ<28>")
	)
	(segment
		(start 445.13881 -230.919528)
		(end 452.173594 -230.919528)
		(width 0.14478)
		(layer "In11.Cu")
		(net "M_L_CPU0_SA_DQ<28>")
	)
	(segment
		(start 440.552586 -230.919528)
		(end 441.40247 -231.769412)
		(width 0.14478)
		(layer "In11.Cu")
		(net "M_L_CPU0_SA_DQ<28>")
	)
	(segment
		(start 441.40247 -231.769412)
		(end 444.288926 -231.769412)
		(width 0.14478)
		(layer "In11.Cu")
		(net "M_L_CPU0_SA_DQ<28>")
	)
	(segment
		(start 453.753728 -230.919528)
		(end 453.763126 -230.91013)
		(width 0.14478)
		(layer "In11.Cu")
		(net "M_L_CPU0_SA_DQ<28>")
	)
	(segment
		(start 452.725028 -231.528112)
		(end 452.869808 -231.383332)
		(width 0.14478)
		(layer "In11.Cu")
		(net "M_L_CPU0_SA_DQ<28>")
	)
	(segment
		(start 418.963856 -231.769412)
		(end 421.53205 -231.769412)
		(width 0.14478)
		(layer "In11.Cu")
		(net "M_L_CPU0_SA_DQ<28>")
	)
	(segment
		(start 394.860018 -243.496592)
		(end 395.108938 -243.247672)
		(width 0.0889)
		(layer "In11.Cu")
		(net "M_L_CPU0_SA_DQ<28>")
	)
	(segment
		(start 452.869808 -231.383332)
		(end 452.869808 -231.064308)
		(width 0.14478)
		(layer "In11.Cu")
		(net "M_L_CPU0_SA_DQ<28>")
	)
	(arc
		(start 392.801094 -243.186712)
		(mid 392.937887 -243.12969)
		(end 393.084812 -243.110258)
		(width 0.0889)
		(layer "In11.Cu")
		(net "M_L_CPU0_SA_DQ<28>")
	)
	(arc
		(start 387.727698 -243.186712)
		(mid 387.909949 -243.237062)
		(end 388.093458 -243.191538)
		(width 0.0889)
		(layer "In11.Cu")
		(net "M_L_CPU0_SA_DQ<28>")
	)
	(arc
		(start 389.041894 -243.186712)
		(mid 389.32485 -243.110535)
		(end 389.607806 -243.186712)
		(width 0.0889)
		(layer "In11.Cu")
		(net "M_L_CPU0_SA_DQ<28>")
	)
	(arc
		(start 390.54786 -243.186712)
		(mid 390.734804 -243.236967)
		(end 390.921748 -243.186712)
		(width 0.0889)
		(layer "In11.Cu")
		(net "M_L_CPU0_SA_DQ<28>")
	)
	(arc
		(start 389.981948 -243.186712)
		(mid 390.264904 -243.110535)
		(end 390.54786 -243.186712)
		(width 0.0889)
		(layer "In11.Cu")
		(net "M_L_CPU0_SA_DQ<28>")
	)
	(arc
		(start 387.224778 -243.154962)
		(mid 387.479986 -243.111485)
		(end 387.727698 -243.186712)
		(width 0.0889)
		(layer "In11.Cu")
		(net "M_L_CPU0_SA_DQ<28>")
	)
	(arc
		(start 391.48766 -243.186712)
		(mid 391.66531 -243.236972)
		(end 391.845292 -243.195856)
		(width 0.0889)
		(layer "In11.Cu")
		(net "M_L_CPU0_SA_DQ<28>")
	)
	(arc
		(start 389.616188 -243.191538)
		(mid 389.799696 -243.237032)
		(end 389.981948 -243.186712)
		(width 0.0889)
		(layer "In11.Cu")
		(net "M_L_CPU0_SA_DQ<28>")
	)
	(arc
		(start 390.921748 -243.186712)
		(mid 391.204704 -243.110535)
		(end 391.48766 -243.186712)
		(width 0.0889)
		(layer "In11.Cu")
		(net "M_L_CPU0_SA_DQ<28>")
	)
	(arc
		(start 392.438382 -243.19357)
		(mid 392.620637 -243.237223)
		(end 392.801094 -243.186712)
		(width 0.0889)
		(layer "In11.Cu")
		(net "M_L_CPU0_SA_DQ<28>")
	)
	(arc
		(start 391.873486 -243.1796)
		(mid 392.15102 -243.110619)
		(end 392.426698 -243.186712)
		(width 0.0889)
		(layer "In11.Cu")
		(net "M_L_CPU0_SA_DQ<28>")
	)
	(arc
		(start 388.10184 -243.186712)
		(mid 388.384796 -243.110535)
		(end 388.667752 -243.186712)
		(width 0.0889)
		(layer "In11.Cu")
		(net "M_L_CPU0_SA_DQ<28>")
	)
	(arc
		(start 388.667752 -243.186712)
		(mid 388.850003 -243.237062)
		(end 389.033512 -243.191538)
		(width 0.0889)
		(layer "In11.Cu")
		(net "M_L_CPU0_SA_DQ<28>")
	)
	(segment
		(start 385.567936 -241.510058)
		(end 386.034788 -241.24412)
		(width 0.10668)
		(layer "F.Cu")
		(net "M_L_CPU0_SA_DQ<27>")
	)
	(segment
		(start 441.09767 -227.500942)
		(end 437.472582 -227.500942)
		(width 0.14478)
		(layer "In11.Cu")
		(net "M_L_CPU0_SA_DQ<27>")
	)
	(segment
		(start 434.03139 -228.350826)
		(end 433.181506 -227.500942)
		(width 0.14478)
		(layer "In11.Cu")
		(net "M_L_CPU0_SA_DQ<27>")
	)
	(segment
		(start 443.936882 -228.350826)
		(end 441.947554 -228.350826)
		(width 0.14478)
		(layer "In11.Cu")
		(net "M_L_CPU0_SA_DQ<27>")
	)
	(segment
		(start 436.622698 -228.350826)
		(end 434.03139 -228.350826)
		(width 0.14478)
		(layer "In11.Cu")
		(net "M_L_CPU0_SA_DQ<27>")
	)
	(segment
		(start 449.653914 -227.500942)
		(end 444.786766 -227.500942)
		(width 0.14478)
		(layer "In11.Cu")
		(net "M_L_CPU0_SA_DQ<27>")
	)
	(segment
		(start 405.25065 -234.668314)
		(end 405.087582 -234.831382)
		(width 0.14478)
		(layer "In11.Cu")
		(net "M_L_CPU0_SA_DQ<27>")
	)
	(segment
		(start 437.472582 -227.500942)
		(end 436.622698 -228.350826)
		(width 0.14478)
		(layer "In11.Cu")
		(net "M_L_CPU0_SA_DQ<27>")
	)
	(segment
		(start 426.503846 -228.350572)
		(end 425.653962 -227.500688)
		(width 0.14478)
		(layer "In11.Cu")
		(net "M_L_CPU0_SA_DQ<27>")
	)
	(segment
		(start 450.088 -227.935028)
		(end 449.653914 -227.500942)
		(width 0.14478)
		(layer "In11.Cu")
		(net "M_L_CPU0_SA_DQ<27>")
	)
	(segment
		(start 405.142446 -235.673646)
		(end 404.911814 -235.673646)
		(width 0.14478)
		(layer "In11.Cu")
		(net "M_L_CPU0_SA_DQ<27>")
	)
	(segment
		(start 405.874982 -234.274614)
		(end 406.092914 -234.492546)
		(width 0.14478)
		(layer "In11.Cu")
		(net "M_L_CPU0_SA_DQ<27>")
	)
	(segment
		(start 412.456122 -228.35997)
		(end 407.504646 -233.311446)
		(width 0.14478)
		(layer "In11.Cu")
		(net "M_L_CPU0_SA_DQ<27>")
	)
	(segment
		(start 406.486614 -234.098846)
		(end 406.268682 -233.880914)
		(width 0.14478)
		(layer "In11.Cu")
		(net "M_L_CPU0_SA_DQ<27>")
	)
	(segment
		(start 406.092914 -234.723178)
		(end 405.929846 -234.886246)
		(width 0.14478)
		(layer "In11.Cu")
		(net "M_L_CPU0_SA_DQ<27>")
	)
	(segment
		(start 406.662382 -233.487214)
		(end 406.880314 -233.705146)
		(width 0.14478)
		(layer "In11.Cu")
		(net "M_L_CPU0_SA_DQ<27>")
	)
	(segment
		(start 433.181506 -227.500942)
		(end 429.790098 -227.500942)
		(width 0.14478)
		(layer "In11.Cu")
		(net "M_L_CPU0_SA_DQ<27>")
	)
	(segment
		(start 405.305514 -235.510578)
		(end 405.142446 -235.673646)
		(width 0.14478)
		(layer "In11.Cu")
		(net "M_L_CPU0_SA_DQ<27>")
	)
	(segment
		(start 392.801856 -240.92154)
		(end 392.793474 -240.916714)
		(width 0.0889)
		(layer "In11.Cu")
		(net "M_L_CPU0_SA_DQ<27>")
	)
	(segment
		(start 391.861802 -240.92154)
		(end 391.85342 -240.916714)
		(width 0.0889)
		(layer "In11.Cu")
		(net "M_L_CPU0_SA_DQ<27>")
	)
	(segment
		(start 406.03805 -233.880914)
		(end 405.874982 -234.043982)
		(width 0.14478)
		(layer "In11.Cu")
		(net "M_L_CPU0_SA_DQ<27>")
	)
	(segment
		(start 406.880314 -233.705146)
		(end 406.880314 -233.935778)
		(width 0.14478)
		(layer "In11.Cu")
		(net "M_L_CPU0_SA_DQ<27>")
	)
	(segment
		(start 414.772856 -227.500688)
		(end 413.913574 -228.35997)
		(width 0.14478)
		(layer "In11.Cu")
		(net "M_L_CPU0_SA_DQ<27>")
	)
	(segment
		(start 407.056082 -233.093514)
		(end 406.82545 -233.093514)
		(width 0.14478)
		(layer "In11.Cu")
		(net "M_L_CPU0_SA_DQ<27>")
	)
	(segment
		(start 407.504646 -233.311446)
		(end 407.274014 -233.311446)
		(width 0.14478)
		(layer "In11.Cu")
		(net "M_L_CPU0_SA_DQ<27>")
	)
	(segment
		(start 421.526462 -228.350572)
		(end 419.072568 -228.350572)
		(width 0.14478)
		(layer "In11.Cu")
		(net "M_L_CPU0_SA_DQ<27>")
	)
	(segment
		(start 405.087582 -234.831382)
		(end 405.087582 -235.062014)
		(width 0.14478)
		(layer "In11.Cu")
		(net "M_L_CPU0_SA_DQ<27>")
	)
	(segment
		(start 404.300182 -235.618782)
		(end 404.300182 -235.849414)
		(width 0.14478)
		(layer "In11.Cu")
		(net "M_L_CPU0_SA_DQ<27>")
	)
	(segment
		(start 407.274014 -233.311446)
		(end 407.056082 -233.093514)
		(width 0.14478)
		(layer "In11.Cu")
		(net "M_L_CPU0_SA_DQ<27>")
	)
	(segment
		(start 405.481282 -234.668314)
		(end 405.25065 -234.668314)
		(width 0.14478)
		(layer "In11.Cu")
		(net "M_L_CPU0_SA_DQ<27>")
	)
	(segment
		(start 404.518114 -236.067346)
		(end 404.518114 -236.297978)
		(width 0.14478)
		(layer "In11.Cu")
		(net "M_L_CPU0_SA_DQ<27>")
	)
	(segment
		(start 389.041894 -240.92154)
		(end 389.033512 -240.916714)
		(width 0.0889)
		(layer "In11.Cu")
		(net "M_L_CPU0_SA_DQ<27>")
	)
	(segment
		(start 428.940468 -228.350572)
		(end 426.503846 -228.350572)
		(width 0.14478)
		(layer "In11.Cu")
		(net "M_L_CPU0_SA_DQ<27>")
	)
	(segment
		(start 388.10184 -240.92154)
		(end 388.093458 -240.916714)
		(width 0.0889)
		(layer "In11.Cu")
		(net "M_L_CPU0_SA_DQ<27>")
	)
	(segment
		(start 404.518114 -236.297978)
		(end 400.999452 -239.81664)
		(width 0.14478)
		(layer "In11.Cu")
		(net "M_L_CPU0_SA_DQ<27>")
	)
	(segment
		(start 406.662382 -233.256582)
		(end 406.662382 -233.487214)
		(width 0.14478)
		(layer "In11.Cu")
		(net "M_L_CPU0_SA_DQ<27>")
	)
	(segment
		(start 385.903216 -240.895378)
		(end 385.880864 -240.97869)
		(width 0.0889)
		(layer "In11.Cu")
		(net "M_L_CPU0_SA_DQ<27>")
	)
	(segment
		(start 404.911814 -235.673646)
		(end 404.693882 -235.455714)
		(width 0.14478)
		(layer "In11.Cu")
		(net "M_L_CPU0_SA_DQ<27>")
	)
	(segment
		(start 395.95044 -239.81664)
		(end 395.69263 -239.81664)
		(width 0.0889)
		(layer "In11.Cu")
		(net "M_L_CPU0_SA_DQ<27>")
	)
	(segment
		(start 422.376346 -227.500688)
		(end 421.526462 -228.350572)
		(width 0.14478)
		(layer "In11.Cu")
		(net "M_L_CPU0_SA_DQ<27>")
	)
	(segment
		(start 405.929846 -234.886246)
		(end 405.699214 -234.886246)
		(width 0.14478)
		(layer "In11.Cu")
		(net "M_L_CPU0_SA_DQ<27>")
	)
	(segment
		(start 419.072568 -228.350572)
		(end 418.222684 -227.500688)
		(width 0.14478)
		(layer "In11.Cu")
		(net "M_L_CPU0_SA_DQ<27>")
	)
	(segment
		(start 405.305514 -235.279946)
		(end 405.305514 -235.510578)
		(width 0.14478)
		(layer "In11.Cu")
		(net "M_L_CPU0_SA_DQ<27>")
	)
	(segment
		(start 395.69263 -239.81664)
		(end 395.032738 -240.476532)
		(width 0.0889)
		(layer "In11.Cu")
		(net "M_L_CPU0_SA_DQ<27>")
	)
	(segment
		(start 405.874982 -234.043982)
		(end 405.874982 -234.274614)
		(width 0.14478)
		(layer "In11.Cu")
		(net "M_L_CPU0_SA_DQ<27>")
	)
	(segment
		(start 413.913574 -228.35997)
		(end 412.456122 -228.35997)
		(width 0.14478)
		(layer "In11.Cu")
		(net "M_L_CPU0_SA_DQ<27>")
	)
	(segment
		(start 393.839446 -240.476532)
		(end 393.483338 -240.83264)
		(width 0.0889)
		(layer "In11.Cu")
		(net "M_L_CPU0_SA_DQ<27>")
	)
	(segment
		(start 418.222684 -227.500688)
		(end 414.772856 -227.500688)
		(width 0.14478)
		(layer "In11.Cu")
		(net "M_L_CPU0_SA_DQ<27>")
	)
	(segment
		(start 404.300182 -235.849414)
		(end 404.518114 -236.067346)
		(width 0.14478)
		(layer "In11.Cu")
		(net "M_L_CPU0_SA_DQ<27>")
	)
	(segment
		(start 405.699214 -234.886246)
		(end 405.481282 -234.668314)
		(width 0.14478)
		(layer "In11.Cu")
		(net "M_L_CPU0_SA_DQ<27>")
	)
	(segment
		(start 404.46325 -235.455714)
		(end 404.300182 -235.618782)
		(width 0.14478)
		(layer "In11.Cu")
		(net "M_L_CPU0_SA_DQ<27>")
	)
	(segment
		(start 406.092914 -234.492546)
		(end 406.092914 -234.723178)
		(width 0.14478)
		(layer "In11.Cu")
		(net "M_L_CPU0_SA_DQ<27>")
	)
	(segment
		(start 429.790098 -227.500942)
		(end 428.940468 -228.350572)
		(width 0.14478)
		(layer "In11.Cu")
		(net "M_L_CPU0_SA_DQ<27>")
	)
	(segment
		(start 425.653962 -227.500688)
		(end 422.376346 -227.500688)
		(width 0.14478)
		(layer "In11.Cu")
		(net "M_L_CPU0_SA_DQ<27>")
	)
	(segment
		(start 406.880314 -233.935778)
		(end 406.717246 -234.098846)
		(width 0.14478)
		(layer "In11.Cu")
		(net "M_L_CPU0_SA_DQ<27>")
	)
	(segment
		(start 385.880864 -240.97869)
		(end 386.034788 -241.24412)
		(width 0.0889)
		(layer "In11.Cu")
		(net "M_L_CPU0_SA_DQ<27>")
	)
	(segment
		(start 406.717246 -234.098846)
		(end 406.486614 -234.098846)
		(width 0.14478)
		(layer "In11.Cu")
		(net "M_L_CPU0_SA_DQ<27>")
	)
	(segment
		(start 441.947554 -228.350826)
		(end 441.09767 -227.500942)
		(width 0.14478)
		(layer "In11.Cu")
		(net "M_L_CPU0_SA_DQ<27>")
	)
	(segment
		(start 406.268682 -233.880914)
		(end 406.03805 -233.880914)
		(width 0.14478)
		(layer "In11.Cu")
		(net "M_L_CPU0_SA_DQ<27>")
	)
	(segment
		(start 405.087582 -235.062014)
		(end 405.305514 -235.279946)
		(width 0.14478)
		(layer "In11.Cu")
		(net "M_L_CPU0_SA_DQ<27>")
	)
	(segment
		(start 395.032738 -240.476532)
		(end 393.839446 -240.476532)
		(width 0.0889)
		(layer "In11.Cu")
		(net "M_L_CPU0_SA_DQ<27>")
	)
	(segment
		(start 406.82545 -233.093514)
		(end 406.662382 -233.256582)
		(width 0.14478)
		(layer "In11.Cu")
		(net "M_L_CPU0_SA_DQ<27>")
	)
	(segment
		(start 404.693882 -235.455714)
		(end 404.46325 -235.455714)
		(width 0.14478)
		(layer "In11.Cu")
		(net "M_L_CPU0_SA_DQ<27>")
	)
	(segment
		(start 444.786766 -227.500942)
		(end 443.936882 -228.350826)
		(width 0.14478)
		(layer "In11.Cu")
		(net "M_L_CPU0_SA_DQ<27>")
	)
	(segment
		(start 400.999452 -239.81664)
		(end 395.95044 -239.81664)
		(width 0.14478)
		(layer "In11.Cu")
		(net "M_L_CPU0_SA_DQ<27>")
	)
	(segment
		(start 389.616188 -240.916714)
		(end 389.607806 -240.92154)
		(width 0.0889)
		(layer "In11.Cu")
		(net "M_L_CPU0_SA_DQ<27>")
	)
	(arc
		(start 388.667752 -240.92154)
		(mid 388.384796 -240.997717)
		(end 388.10184 -240.92154)
		(width 0.0889)
		(layer "In11.Cu")
		(net "M_L_CPU0_SA_DQ<27>")
	)
	(arc
		(start 392.793474 -240.916714)
		(mid 392.609966 -240.87122)
		(end 392.427714 -240.92154)
		(width 0.0889)
		(layer "In11.Cu")
		(net "M_L_CPU0_SA_DQ<27>")
	)
	(arc
		(start 389.607806 -240.92154)
		(mid 389.32485 -240.997717)
		(end 389.041894 -240.92154)
		(width 0.0889)
		(layer "In11.Cu")
		(net "M_L_CPU0_SA_DQ<27>")
	)
	(arc
		(start 389.981948 -240.92154)
		(mid 389.799697 -240.87119)
		(end 389.616188 -240.916714)
		(width 0.0889)
		(layer "In11.Cu")
		(net "M_L_CPU0_SA_DQ<27>")
	)
	(arc
		(start 391.85342 -240.916714)
		(mid 391.669912 -240.87122)
		(end 391.48766 -240.92154)
		(width 0.0889)
		(layer "In11.Cu")
		(net "M_L_CPU0_SA_DQ<27>")
	)
	(arc
		(start 389.033512 -240.916714)
		(mid 388.850004 -240.87122)
		(end 388.667752 -240.92154)
		(width 0.0889)
		(layer "In11.Cu")
		(net "M_L_CPU0_SA_DQ<27>")
	)
	(arc
		(start 393.367768 -240.92154)
		(mid 393.084812 -240.997717)
		(end 392.801856 -240.92154)
		(width 0.0889)
		(layer "In11.Cu")
		(net "M_L_CPU0_SA_DQ<27>")
	)
	(arc
		(start 386.787898 -240.92154)
		(mid 386.504942 -240.997717)
		(end 386.221986 -240.92154)
		(width 0.0889)
		(layer "In11.Cu")
		(net "M_L_CPU0_SA_DQ<27>")
	)
	(arc
		(start 387.161786 -240.92154)
		(mid 386.974842 -240.871285)
		(end 386.787898 -240.92154)
		(width 0.0889)
		(layer "In11.Cu")
		(net "M_L_CPU0_SA_DQ<27>")
	)
	(arc
		(start 391.48766 -240.92154)
		(mid 391.204704 -240.997717)
		(end 390.921748 -240.92154)
		(width 0.0889)
		(layer "In11.Cu")
		(net "M_L_CPU0_SA_DQ<27>")
	)
	(arc
		(start 392.427714 -240.92154)
		(mid 392.144758 -240.997717)
		(end 391.861802 -240.92154)
		(width 0.0889)
		(layer "In11.Cu")
		(net "M_L_CPU0_SA_DQ<27>")
	)
	(arc
		(start 393.483338 -240.83264)
		(mid 393.428439 -240.880842)
		(end 393.367768 -240.92154)
		(width 0.0889)
		(layer "In11.Cu")
		(net "M_L_CPU0_SA_DQ<27>")
	)
	(arc
		(start 387.727698 -240.92154)
		(mid 387.444742 -240.997717)
		(end 387.161786 -240.92154)
		(width 0.0889)
		(layer "In11.Cu")
		(net "M_L_CPU0_SA_DQ<27>")
	)
	(arc
		(start 390.54786 -240.92154)
		(mid 390.264904 -240.997717)
		(end 389.981948 -240.92154)
		(width 0.0889)
		(layer "In11.Cu")
		(net "M_L_CPU0_SA_DQ<27>")
	)
	(arc
		(start 388.093458 -240.916714)
		(mid 387.90995 -240.87122)
		(end 387.727698 -240.92154)
		(width 0.0889)
		(layer "In11.Cu")
		(net "M_L_CPU0_SA_DQ<27>")
	)
	(arc
		(start 386.221986 -240.92154)
		(mid 386.065548 -240.872569)
		(end 385.903216 -240.895378)
		(width 0.0889)
		(layer "In11.Cu")
		(net "M_L_CPU0_SA_DQ<27>")
	)
	(arc
		(start 390.921748 -240.92154)
		(mid 390.734804 -240.871285)
		(end 390.54786 -240.92154)
		(width 0.0889)
		(layer "In11.Cu")
		(net "M_L_CPU0_SA_DQ<27>")
	)
	(segment
		(start 386.97789 -240.700052)
		(end 387.444742 -240.434114)
		(width 0.10668)
		(layer "F.Cu")
		(net "M_L_CPU0_SA_DQ<26>")
	)
	(segment
		(start 422.40962 -225.810318)
		(end 425.912534 -225.810318)
		(width 0.14478)
		(layer "In11.Cu")
		(net "M_L_CPU0_SA_DQ<26>")
	)
	(segment
		(start 401.557998 -237.971838)
		(end 401.557998 -237.741206)
		(width 0.14478)
		(layer "In11.Cu")
		(net "M_L_CPU0_SA_DQ<26>")
	)
	(segment
		(start 391.957052 -240.111788)
		(end 391.970768 -240.103914)
		(width 0.0889)
		(layer "In11.Cu")
		(net "M_L_CPU0_SA_DQ<26>")
	)
	(segment
		(start 388.197852 -240.111534)
		(end 388.206234 -240.106708)
		(width 0.0889)
		(layer "In11.Cu")
		(net "M_L_CPU0_SA_DQ<26>")
	)
	(segment
		(start 403.132798 -236.397038)
		(end 403.132798 -236.166406)
		(width 0.14478)
		(layer "In11.Cu")
		(net "M_L_CPU0_SA_DQ<26>")
	)
	(segment
		(start 429.777144 -225.810318)
		(end 433.190904 -225.810318)
		(width 0.14478)
		(layer "In11.Cu")
		(net "M_L_CPU0_SA_DQ<26>")
	)
	(segment
		(start 391.945114 -240.118646)
		(end 391.957052 -240.111788)
		(width 0.0889)
		(layer "In11.Cu")
		(net "M_L_CPU0_SA_DQ<26>")
	)
	(segment
		(start 407.345642 -232.184194)
		(end 411.949138 -227.580698)
		(width 0.14478)
		(layer "In11.Cu")
		(net "M_L_CPU0_SA_DQ<26>")
	)
	(segment
		(start 448.442334 -225.955098)
		(end 448.442334 -226.049332)
		(width 0.14478)
		(layer "In11.Cu")
		(net "M_L_CPU0_SA_DQ<26>")
	)
	(segment
		(start 416.520884 -225.810064)
		(end 416.835844 -225.810064)
		(width 0.14478)
		(layer "In11.Cu")
		(net "M_L_CPU0_SA_DQ<26>")
	)
	(segment
		(start 400.620738 -238.90732)
		(end 400.770598 -238.75746)
		(width 0.14478)
		(layer "In11.Cu")
		(net "M_L_CPU0_SA_DQ<26>")
	)
	(segment
		(start 401.39493 -238.134906)
		(end 401.557998 -237.971838)
		(width 0.14478)
		(layer "In11.Cu")
		(net "M_L_CPU0_SA_DQ<26>")
	)
	(segment
		(start 393.084812 -240.060734)
		(end 393.510516 -240.060734)
		(width 0.0889)
		(layer "In11.Cu")
		(net "M_L_CPU0_SA_DQ<26>")
	)
	(segment
		(start 401.322794 -237.27537)
		(end 401.485862 -237.112302)
		(width 0.14478)
		(layer "In11.Cu")
		(net "M_L_CPU0_SA_DQ<26>")
	)
	(segment
		(start 417.178998 -225.46691)
		(end 417.493958 -225.46691)
		(width 0.14478)
		(layer "In11.Cu")
		(net "M_L_CPU0_SA_DQ<26>")
	)
	(segment
		(start 434.040788 -226.660202)
		(end 436.6133 -226.660202)
		(width 0.14478)
		(layer "In11.Cu")
		(net "M_L_CPU0_SA_DQ<26>")
	)
	(segment
		(start 421.559736 -226.660202)
		(end 422.40962 -225.810318)
		(width 0.14478)
		(layer "In11.Cu")
		(net "M_L_CPU0_SA_DQ<26>")
	)
	(segment
		(start 400.770598 -238.75746)
		(end 400.770598 -238.528606)
		(width 0.14478)
		(layer "In11.Cu")
		(net "M_L_CPU0_SA_DQ<26>")
	)
	(segment
		(start 433.190904 -225.810318)
		(end 434.040788 -226.660202)
		(width 0.14478)
		(layer "In11.Cu")
		(net "M_L_CPU0_SA_DQ<26>")
	)
	(segment
		(start 419.081966 -226.660202)
		(end 421.559736 -226.660202)
		(width 0.14478)
		(layer "In11.Cu")
		(net "M_L_CPU0_SA_DQ<26>")
	)
	(segment
		(start 436.6133 -226.660202)
		(end 437.463184 -225.810318)
		(width 0.14478)
		(layer "In11.Cu")
		(net "M_L_CPU0_SA_DQ<26>")
	)
	(segment
		(start 441.636404 -226.660202)
		(end 443.901068 -226.660202)
		(width 0.14478)
		(layer "In11.Cu")
		(net "M_L_CPU0_SA_DQ<26>")
	)
	(segment
		(start 387.290818 -240.168684)
		(end 387.31317 -240.085372)
		(width 0.0889)
		(layer "In11.Cu")
		(net "M_L_CPU0_SA_DQ<26>")
	)
	(segment
		(start 400.929094 -237.899702)
		(end 401.164298 -238.134906)
		(width 0.14478)
		(layer "In11.Cu")
		(net "M_L_CPU0_SA_DQ<26>")
	)
	(segment
		(start 415.519616 -225.810064)
		(end 415.86277 -225.46691)
		(width 0.14478)
		(layer "In11.Cu")
		(net "M_L_CPU0_SA_DQ<26>")
	)
	(segment
		(start 400.535394 -238.06277)
		(end 400.698462 -237.899702)
		(width 0.14478)
		(layer "In11.Cu")
		(net "M_L_CPU0_SA_DQ<26>")
	)
	(segment
		(start 426.762418 -226.660202)
		(end 428.92726 -226.660202)
		(width 0.14478)
		(layer "In11.Cu")
		(net "M_L_CPU0_SA_DQ<26>")
	)
	(segment
		(start 402.739098 -236.560106)
		(end 402.96973 -236.560106)
		(width 0.14478)
		(layer "In11.Cu")
		(net "M_L_CPU0_SA_DQ<26>")
	)
	(segment
		(start 403.132798 -236.166406)
		(end 402.905722 -235.93933)
		(width 0.14478)
		(layer "In11.Cu")
		(net "M_L_CPU0_SA_DQ<26>")
	)
	(segment
		(start 390.443466 -240.106708)
		(end 390.451848 -240.111534)
		(width 0.0889)
		(layer "In11.Cu")
		(net "M_L_CPU0_SA_DQ<26>")
	)
	(segment
		(start 449.663312 -225.810318)
		(end 450.088 -226.235006)
		(width 0.14478)
		(layer "In11.Cu")
		(net "M_L_CPU0_SA_DQ<26>")
	)
	(segment
		(start 391.01776 -240.111534)
		(end 391.026142 -240.106708)
		(width 0.0889)
		(layer "In11.Cu")
		(net "M_L_CPU0_SA_DQ<26>")
	)
	(segment
		(start 448.993768 -226.049332)
		(end 448.993768 -225.955098)
		(width 0.14478)
		(layer "In11.Cu")
		(net "M_L_CPU0_SA_DQ<26>")
	)
	(segment
		(start 413.945832 -226.660202)
		(end 414.79597 -225.810064)
		(width 0.14478)
		(layer "In11.Cu")
		(net "M_L_CPU0_SA_DQ<26>")
	)
	(segment
		(start 440.78652 -225.810318)
		(end 441.636404 -226.660202)
		(width 0.14478)
		(layer "In11.Cu")
		(net "M_L_CPU0_SA_DQ<26>")
	)
	(segment
		(start 448.993768 -225.955098)
		(end 449.138548 -225.810318)
		(width 0.14478)
		(layer "In11.Cu")
		(net "M_L_CPU0_SA_DQ<26>")
	)
	(segment
		(start 395.77137 -238.90732)
		(end 395.930882 -238.90732)
		(width 0.0889)
		(layer "In11.Cu")
		(net "M_L_CPU0_SA_DQ<26>")
	)
	(segment
		(start 417.493958 -225.46691)
		(end 417.837112 -225.810064)
		(width 0.14478)
		(layer "In11.Cu")
		(net "M_L_CPU0_SA_DQ<26>")
	)
	(segment
		(start 402.110194 -236.48797)
		(end 402.273262 -236.324902)
		(width 0.14478)
		(layer "In11.Cu")
		(net "M_L_CPU0_SA_DQ<26>")
	)
	(segment
		(start 400.770598 -238.528606)
		(end 400.535394 -238.293402)
		(width 0.14478)
		(layer "In11.Cu")
		(net "M_L_CPU0_SA_DQ<26>")
	)
	(segment
		(start 448.297554 -225.810318)
		(end 448.442334 -225.955098)
		(width 0.14478)
		(layer "In11.Cu")
		(net "M_L_CPU0_SA_DQ<26>")
	)
	(segment
		(start 417.837112 -225.810064)
		(end 418.231828 -225.810064)
		(width 0.14478)
		(layer "In11.Cu")
		(net "M_L_CPU0_SA_DQ<26>")
	)
	(segment
		(start 416.17773 -225.46691)
		(end 416.520884 -225.810064)
		(width 0.14478)
		(layer "In11.Cu")
		(net "M_L_CPU0_SA_DQ<26>")
	)
	(segment
		(start 416.835844 -225.810064)
		(end 417.178998 -225.46691)
		(width 0.14478)
		(layer "In11.Cu")
		(net "M_L_CPU0_SA_DQ<26>")
	)
	(segment
		(start 394.067538 -239.503712)
		(end 395.174978 -239.503712)
		(width 0.0889)
		(layer "In11.Cu")
		(net "M_L_CPU0_SA_DQ<26>")
	)
	(segment
		(start 425.912534 -225.810318)
		(end 426.762418 -226.660202)
		(width 0.14478)
		(layer "In11.Cu")
		(net "M_L_CPU0_SA_DQ<26>")
	)
	(segment
		(start 400.535394 -238.293402)
		(end 400.535394 -238.06277)
		(width 0.14478)
		(layer "In11.Cu")
		(net "M_L_CPU0_SA_DQ<26>")
	)
	(segment
		(start 402.905722 -235.93933)
		(end 402.905722 -235.726986)
		(width 0.14478)
		(layer "In11.Cu")
		(net "M_L_CPU0_SA_DQ<26>")
	)
	(segment
		(start 401.322794 -237.506002)
		(end 401.322794 -237.27537)
		(width 0.14478)
		(layer "In11.Cu")
		(net "M_L_CPU0_SA_DQ<26>")
	)
	(segment
		(start 437.463184 -225.810318)
		(end 440.78652 -225.810318)
		(width 0.14478)
		(layer "In11.Cu")
		(net "M_L_CPU0_SA_DQ<26>")
	)
	(segment
		(start 402.345398 -236.953806)
		(end 402.110194 -236.718602)
		(width 0.14478)
		(layer "In11.Cu")
		(net "M_L_CPU0_SA_DQ<26>")
	)
	(segment
		(start 411.949138 -227.580698)
		(end 411.949138 -226.905312)
		(width 0.14478)
		(layer "In11.Cu")
		(net "M_L_CPU0_SA_DQ<26>")
	)
	(segment
		(start 401.164298 -238.134906)
		(end 401.39493 -238.134906)
		(width 0.14478)
		(layer "In11.Cu")
		(net "M_L_CPU0_SA_DQ<26>")
	)
	(segment
		(start 400.698462 -237.899702)
		(end 400.929094 -237.899702)
		(width 0.14478)
		(layer "In11.Cu")
		(net "M_L_CPU0_SA_DQ<26>")
	)
	(segment
		(start 448.587114 -226.194112)
		(end 448.848988 -226.194112)
		(width 0.14478)
		(layer "In11.Cu")
		(net "M_L_CPU0_SA_DQ<26>")
	)
	(segment
		(start 418.231828 -225.810064)
		(end 419.081966 -226.660202)
		(width 0.14478)
		(layer "In11.Cu")
		(net "M_L_CPU0_SA_DQ<26>")
	)
	(segment
		(start 401.557998 -237.741206)
		(end 401.322794 -237.506002)
		(width 0.14478)
		(layer "In11.Cu")
		(net "M_L_CPU0_SA_DQ<26>")
	)
	(segment
		(start 393.510516 -240.060734)
		(end 394.067538 -239.503712)
		(width 0.0889)
		(layer "In11.Cu")
		(net "M_L_CPU0_SA_DQ<26>")
	)
	(segment
		(start 428.92726 -226.660202)
		(end 429.777144 -225.810318)
		(width 0.14478)
		(layer "In11.Cu")
		(net "M_L_CPU0_SA_DQ<26>")
	)
	(segment
		(start 443.901068 -226.660202)
		(end 444.750952 -225.810318)
		(width 0.14478)
		(layer "In11.Cu")
		(net "M_L_CPU0_SA_DQ<26>")
	)
	(segment
		(start 411.949138 -226.905312)
		(end 412.194248 -226.660202)
		(width 0.14478)
		(layer "In11.Cu")
		(net "M_L_CPU0_SA_DQ<26>")
	)
	(segment
		(start 401.716494 -237.112302)
		(end 401.951698 -237.347506)
		(width 0.14478)
		(layer "In11.Cu")
		(net "M_L_CPU0_SA_DQ<26>")
	)
	(segment
		(start 448.442334 -226.049332)
		(end 448.587114 -226.194112)
		(width 0.14478)
		(layer "In11.Cu")
		(net "M_L_CPU0_SA_DQ<26>")
	)
	(segment
		(start 402.110194 -236.718602)
		(end 402.110194 -236.48797)
		(width 0.14478)
		(layer "In11.Cu")
		(net "M_L_CPU0_SA_DQ<26>")
	)
	(segment
		(start 402.18233 -237.347506)
		(end 402.345398 -237.184438)
		(width 0.14478)
		(layer "In11.Cu")
		(net "M_L_CPU0_SA_DQ<26>")
	)
	(segment
		(start 401.485862 -237.112302)
		(end 401.716494 -237.112302)
		(width 0.14478)
		(layer "In11.Cu")
		(net "M_L_CPU0_SA_DQ<26>")
	)
	(segment
		(start 392.330686 -240.111534)
		(end 392.34872 -240.122202)
		(width 0.0889)
		(layer "In11.Cu")
		(net "M_L_CPU0_SA_DQ<26>")
	)
	(segment
		(start 415.86277 -225.46691)
		(end 416.17773 -225.46691)
		(width 0.14478)
		(layer "In11.Cu")
		(net "M_L_CPU0_SA_DQ<26>")
	)
	(segment
		(start 406.448514 -232.184194)
		(end 407.345642 -232.184194)
		(width 0.14478)
		(layer "In11.Cu")
		(net "M_L_CPU0_SA_DQ<26>")
	)
	(segment
		(start 449.138548 -225.810318)
		(end 449.663312 -225.810318)
		(width 0.14478)
		(layer "In11.Cu")
		(net "M_L_CPU0_SA_DQ<26>")
	)
	(segment
		(start 402.905722 -235.726986)
		(end 406.448514 -232.184194)
		(width 0.14478)
		(layer "In11.Cu")
		(net "M_L_CPU0_SA_DQ<26>")
	)
	(segment
		(start 402.96973 -236.560106)
		(end 403.132798 -236.397038)
		(width 0.14478)
		(layer "In11.Cu")
		(net "M_L_CPU0_SA_DQ<26>")
	)
	(segment
		(start 387.444742 -240.434114)
		(end 387.290818 -240.168684)
		(width 0.0889)
		(layer "In11.Cu")
		(net "M_L_CPU0_SA_DQ<26>")
	)
	(segment
		(start 402.503894 -236.324902)
		(end 402.739098 -236.560106)
		(width 0.14478)
		(layer "In11.Cu")
		(net "M_L_CPU0_SA_DQ<26>")
	)
	(segment
		(start 401.951698 -237.347506)
		(end 402.18233 -237.347506)
		(width 0.14478)
		(layer "In11.Cu")
		(net "M_L_CPU0_SA_DQ<26>")
	)
	(segment
		(start 414.79597 -225.810064)
		(end 415.519616 -225.810064)
		(width 0.14478)
		(layer "In11.Cu")
		(net "M_L_CPU0_SA_DQ<26>")
	)
	(segment
		(start 395.174978 -239.503712)
		(end 395.77137 -238.90732)
		(width 0.0889)
		(layer "In11.Cu")
		(net "M_L_CPU0_SA_DQ<26>")
	)
	(segment
		(start 412.194248 -226.660202)
		(end 413.945832 -226.660202)
		(width 0.14478)
		(layer "In11.Cu")
		(net "M_L_CPU0_SA_DQ<26>")
	)
	(segment
		(start 448.848988 -226.194112)
		(end 448.993768 -226.049332)
		(width 0.14478)
		(layer "In11.Cu")
		(net "M_L_CPU0_SA_DQ<26>")
	)
	(segment
		(start 395.930882 -238.90732)
		(end 400.620738 -238.90732)
		(width 0.14478)
		(layer "In11.Cu")
		(net "M_L_CPU0_SA_DQ<26>")
	)
	(segment
		(start 444.750952 -225.810318)
		(end 448.297554 -225.810318)
		(width 0.14478)
		(layer "In11.Cu")
		(net "M_L_CPU0_SA_DQ<26>")
	)
	(segment
		(start 402.345398 -237.184438)
		(end 402.345398 -236.953806)
		(width 0.14478)
		(layer "In11.Cu")
		(net "M_L_CPU0_SA_DQ<26>")
	)
	(segment
		(start 402.273262 -236.324902)
		(end 402.503894 -236.324902)
		(width 0.14478)
		(layer "In11.Cu")
		(net "M_L_CPU0_SA_DQ<26>")
	)
	(arc
		(start 392.89736 -240.111534)
		(mid 392.987723 -240.073724)
		(end 393.084812 -240.060734)
		(width 0.0889)
		(layer "In11.Cu")
		(net "M_L_CPU0_SA_DQ<26>")
	)
	(arc
		(start 387.31317 -240.085372)
		(mid 387.475502 -240.062554)
		(end 387.63194 -240.111534)
		(width 0.0889)
		(layer "In11.Cu")
		(net "M_L_CPU0_SA_DQ<26>")
	)
	(arc
		(start 390.451848 -240.111534)
		(mid 390.734804 -240.187711)
		(end 391.01776 -240.111534)
		(width 0.0889)
		(layer "In11.Cu")
		(net "M_L_CPU0_SA_DQ<26>")
	)
	(arc
		(start 389.137906 -240.111534)
		(mid 389.32485 -240.061279)
		(end 389.511794 -240.111534)
		(width 0.0889)
		(layer "In11.Cu")
		(net "M_L_CPU0_SA_DQ<26>")
	)
	(arc
		(start 391.391902 -240.111534)
		(mid 391.66758 -240.187664)
		(end 391.945114 -240.118646)
		(width 0.0889)
		(layer "In11.Cu")
		(net "M_L_CPU0_SA_DQ<26>")
	)
	(arc
		(start 390.077706 -240.111534)
		(mid 390.259957 -240.061184)
		(end 390.443466 -240.106708)
		(width 0.0889)
		(layer "In11.Cu")
		(net "M_L_CPU0_SA_DQ<26>")
	)
	(arc
		(start 387.63194 -240.111534)
		(mid 387.914896 -240.187711)
		(end 388.197852 -240.111534)
		(width 0.0889)
		(layer "In11.Cu")
		(net "M_L_CPU0_SA_DQ<26>")
	)
	(arc
		(start 389.511794 -240.111534)
		(mid 389.79475 -240.187711)
		(end 390.077706 -240.111534)
		(width 0.0889)
		(layer "In11.Cu")
		(net "M_L_CPU0_SA_DQ<26>")
	)
	(arc
		(start 392.34872 -240.122202)
		(mid 392.624415 -240.188045)
		(end 392.89736 -240.111534)
		(width 0.0889)
		(layer "In11.Cu")
		(net "M_L_CPU0_SA_DQ<26>")
	)
	(arc
		(start 391.970768 -240.103914)
		(mid 392.151698 -240.061436)
		(end 392.330686 -240.111534)
		(width 0.0889)
		(layer "In11.Cu")
		(net "M_L_CPU0_SA_DQ<26>")
	)
	(arc
		(start 391.026142 -240.106708)
		(mid 391.20965 -240.061214)
		(end 391.391902 -240.111534)
		(width 0.0889)
		(layer "In11.Cu")
		(net "M_L_CPU0_SA_DQ<26>")
	)
	(arc
		(start 388.206234 -240.106708)
		(mid 388.389742 -240.061214)
		(end 388.571994 -240.111534)
		(width 0.0889)
		(layer "In11.Cu")
		(net "M_L_CPU0_SA_DQ<26>")
	)
	(arc
		(start 388.571994 -240.111534)
		(mid 388.85495 -240.187711)
		(end 389.137906 -240.111534)
		(width 0.0889)
		(layer "In11.Cu")
		(net "M_L_CPU0_SA_DQ<26>")
	)
	(segment
		(start 385.098036 -240.700052)
		(end 385.564888 -240.434114)
		(width 0.10668)
		(layer "F.Cu")
		(net "M_L_CPU0_SA_DQ<25>")
	)
	(segment
		(start 388.206234 -240.76152)
		(end 388.197852 -240.756694)
		(width 0.0889)
		(layer "In11.Cu")
		(net "M_L_CPU0_SA_DQ<25>")
	)
	(segment
		(start 436.045864 -227.510086)
		(end 434.638704 -227.510086)
		(width 0.14478)
		(layer "In11.Cu")
		(net "M_L_CPU0_SA_DQ<25>")
	)
	(segment
		(start 428.319946 -227.510086)
		(end 427.164754 -227.510086)
		(width 0.14478)
		(layer "In11.Cu")
		(net "M_L_CPU0_SA_DQ<25>")
	)
	(segment
		(start 434.638704 -227.510086)
		(end 432.586892 -226.660202)
		(width 0.14478)
		(layer "In11.Cu")
		(net "M_L_CPU0_SA_DQ<25>")
	)
	(segment
		(start 419.057582 -227.510086)
		(end 418.207698 -226.660202)
		(width 0.14478)
		(layer "In11.Cu")
		(net "M_L_CPU0_SA_DQ<25>")
	)
	(segment
		(start 442.314076 -227.510086)
		(end 440.262264 -226.660202)
		(width 0.14478)
		(layer "In11.Cu")
		(net "M_L_CPU0_SA_DQ<25>")
	)
	(segment
		(start 418.207698 -226.660202)
		(end 414.706562 -226.660202)
		(width 0.14478)
		(layer "In11.Cu")
		(net "M_L_CPU0_SA_DQ<25>")
	)
	(segment
		(start 454.188068 -227.085144)
		(end 452.051674 -226.660202)
		(width 0.14478)
		(layer "In11.Cu")
		(net "M_L_CPU0_SA_DQ<25>")
	)
	(segment
		(start 403.587458 -236.585506)
		(end 400.810984 -239.36198)
		(width 0.14478)
		(layer "In11.Cu")
		(net "M_L_CPU0_SA_DQ<25>")
	)
	(segment
		(start 393.760452 -240.286032)
		(end 393.348464 -240.697766)
		(width 0.0889)
		(layer "In11.Cu")
		(net "M_L_CPU0_SA_DQ<25>")
	)
	(segment
		(start 392.90625 -240.76152)
		(end 392.897868 -240.756694)
		(width 0.0889)
		(layer "In11.Cu")
		(net "M_L_CPU0_SA_DQ<25>")
	)
	(segment
		(start 413.856678 -227.510086)
		(end 412.662878 -227.510086)
		(width 0.14478)
		(layer "In11.Cu")
		(net "M_L_CPU0_SA_DQ<25>")
	)
	(segment
		(start 400.810984 -239.36198)
		(end 395.952472 -239.36198)
		(width 0.14478)
		(layer "In11.Cu")
		(net "M_L_CPU0_SA_DQ<25>")
	)
	(segment
		(start 432.586892 -226.660202)
		(end 430.371758 -226.660202)
		(width 0.14478)
		(layer "In11.Cu")
		(net "M_L_CPU0_SA_DQ<25>")
	)
	(segment
		(start 414.706562 -226.660202)
		(end 413.856678 -227.510086)
		(width 0.14478)
		(layer "In11.Cu")
		(net "M_L_CPU0_SA_DQ<25>")
	)
	(segment
		(start 430.371758 -226.660202)
		(end 428.319946 -227.510086)
		(width 0.14478)
		(layer "In11.Cu")
		(net "M_L_CPU0_SA_DQ<25>")
	)
	(segment
		(start 406.636982 -232.638854)
		(end 403.587458 -235.688378)
		(width 0.14478)
		(layer "In11.Cu")
		(net "M_L_CPU0_SA_DQ<25>")
	)
	(segment
		(start 395.80185 -239.36198)
		(end 394.877798 -240.286032)
		(width 0.0889)
		(layer "In11.Cu")
		(net "M_L_CPU0_SA_DQ<25>")
	)
	(segment
		(start 412.662878 -227.510086)
		(end 407.53411 -232.638854)
		(width 0.14478)
		(layer "In11.Cu")
		(net "M_L_CPU0_SA_DQ<25>")
	)
	(segment
		(start 391.966196 -240.76152)
		(end 391.957814 -240.756694)
		(width 0.0889)
		(layer "In11.Cu")
		(net "M_L_CPU0_SA_DQ<25>")
	)
	(segment
		(start 443.473332 -227.510086)
		(end 442.314076 -227.510086)
		(width 0.14478)
		(layer "In11.Cu")
		(net "M_L_CPU0_SA_DQ<25>")
	)
	(segment
		(start 425.112942 -226.660202)
		(end 422.507664 -226.660202)
		(width 0.14478)
		(layer "In11.Cu")
		(net "M_L_CPU0_SA_DQ<25>")
	)
	(segment
		(start 395.952472 -239.36198)
		(end 395.80185 -239.36198)
		(width 0.0889)
		(layer "In11.Cu")
		(net "M_L_CPU0_SA_DQ<25>")
	)
	(segment
		(start 427.164754 -227.510086)
		(end 425.112942 -226.660202)
		(width 0.14478)
		(layer "In11.Cu")
		(net "M_L_CPU0_SA_DQ<25>")
	)
	(segment
		(start 452.051674 -226.660202)
		(end 445.525144 -226.660202)
		(width 0.14478)
		(layer "In11.Cu")
		(net "M_L_CPU0_SA_DQ<25>")
	)
	(segment
		(start 438.097676 -226.660202)
		(end 436.045864 -227.510086)
		(width 0.14478)
		(layer "In11.Cu")
		(net "M_L_CPU0_SA_DQ<25>")
	)
	(segment
		(start 385.814824 -240.724944)
		(end 385.718812 -240.699544)
		(width 0.0889)
		(layer "In11.Cu")
		(net "M_L_CPU0_SA_DQ<25>")
	)
	(segment
		(start 403.587458 -235.688378)
		(end 403.587458 -236.585506)
		(width 0.14478)
		(layer "In11.Cu")
		(net "M_L_CPU0_SA_DQ<25>")
	)
	(segment
		(start 390.451848 -240.756694)
		(end 390.443466 -240.76152)
		(width 0.0889)
		(layer "In11.Cu")
		(net "M_L_CPU0_SA_DQ<25>")
	)
	(segment
		(start 422.507664 -226.660202)
		(end 421.65778 -227.510086)
		(width 0.14478)
		(layer "In11.Cu")
		(net "M_L_CPU0_SA_DQ<25>")
	)
	(segment
		(start 386.691886 -240.756694)
		(end 386.683504 -240.76152)
		(width 0.0889)
		(layer "In11.Cu")
		(net "M_L_CPU0_SA_DQ<25>")
	)
	(segment
		(start 407.53411 -232.638854)
		(end 406.636982 -232.638854)
		(width 0.14478)
		(layer "In11.Cu")
		(net "M_L_CPU0_SA_DQ<25>")
	)
	(segment
		(start 445.525144 -226.660202)
		(end 443.473332 -227.510086)
		(width 0.14478)
		(layer "In11.Cu")
		(net "M_L_CPU0_SA_DQ<25>")
	)
	(segment
		(start 421.65778 -227.510086)
		(end 419.057582 -227.510086)
		(width 0.14478)
		(layer "In11.Cu")
		(net "M_L_CPU0_SA_DQ<25>")
	)
	(segment
		(start 391.026142 -240.76152)
		(end 391.01776 -240.756694)
		(width 0.0889)
		(layer "In11.Cu")
		(net "M_L_CPU0_SA_DQ<25>")
	)
	(segment
		(start 394.877798 -240.286032)
		(end 393.760452 -240.286032)
		(width 0.0889)
		(layer "In11.Cu")
		(net "M_L_CPU0_SA_DQ<25>")
	)
	(segment
		(start 387.26618 -240.76152)
		(end 387.257798 -240.756694)
		(width 0.0889)
		(layer "In11.Cu")
		(net "M_L_CPU0_SA_DQ<25>")
	)
	(segment
		(start 385.718812 -240.699544)
		(end 385.564888 -240.434114)
		(width 0.0889)
		(layer "In11.Cu")
		(net "M_L_CPU0_SA_DQ<25>")
	)
	(segment
		(start 440.262264 -226.660202)
		(end 438.097676 -226.660202)
		(width 0.14478)
		(layer "In11.Cu")
		(net "M_L_CPU0_SA_DQ<25>")
	)
	(arc
		(start 388.571994 -240.756694)
		(mid 388.389743 -240.807044)
		(end 388.206234 -240.76152)
		(width 0.0889)
		(layer "In11.Cu")
		(net "M_L_CPU0_SA_DQ<25>")
	)
	(arc
		(start 388.197852 -240.756694)
		(mid 387.914896 -240.680517)
		(end 387.63194 -240.756694)
		(width 0.0889)
		(layer "In11.Cu")
		(net "M_L_CPU0_SA_DQ<25>")
	)
	(arc
		(start 390.443466 -240.76152)
		(mid 390.259958 -240.807014)
		(end 390.077706 -240.756694)
		(width 0.0889)
		(layer "In11.Cu")
		(net "M_L_CPU0_SA_DQ<25>")
	)
	(arc
		(start 389.511794 -240.756694)
		(mid 389.32485 -240.806949)
		(end 389.137906 -240.756694)
		(width 0.0889)
		(layer "In11.Cu")
		(net "M_L_CPU0_SA_DQ<25>")
	)
	(arc
		(start 386.317744 -240.756694)
		(mid 386.070031 -240.681474)
		(end 385.814824 -240.724944)
		(width 0.0889)
		(layer "In11.Cu")
		(net "M_L_CPU0_SA_DQ<25>")
	)
	(arc
		(start 392.897868 -240.756694)
		(mid 392.614912 -240.680517)
		(end 392.331956 -240.756694)
		(width 0.0889)
		(layer "In11.Cu")
		(net "M_L_CPU0_SA_DQ<25>")
	)
	(arc
		(start 393.27201 -240.756694)
		(mid 393.089759 -240.807044)
		(end 392.90625 -240.76152)
		(width 0.0889)
		(layer "In11.Cu")
		(net "M_L_CPU0_SA_DQ<25>")
	)
	(arc
		(start 386.683504 -240.76152)
		(mid 386.499996 -240.807014)
		(end 386.317744 -240.756694)
		(width 0.0889)
		(layer "In11.Cu")
		(net "M_L_CPU0_SA_DQ<25>")
	)
	(arc
		(start 391.391902 -240.756694)
		(mid 391.209651 -240.807044)
		(end 391.026142 -240.76152)
		(width 0.0889)
		(layer "In11.Cu")
		(net "M_L_CPU0_SA_DQ<25>")
	)
	(arc
		(start 390.077706 -240.756694)
		(mid 389.79475 -240.680517)
		(end 389.511794 -240.756694)
		(width 0.0889)
		(layer "In11.Cu")
		(net "M_L_CPU0_SA_DQ<25>")
	)
	(arc
		(start 387.257798 -240.756694)
		(mid 386.974842 -240.680517)
		(end 386.691886 -240.756694)
		(width 0.0889)
		(layer "In11.Cu")
		(net "M_L_CPU0_SA_DQ<25>")
	)
	(arc
		(start 389.137906 -240.756694)
		(mid 388.85495 -240.680517)
		(end 388.571994 -240.756694)
		(width 0.0889)
		(layer "In11.Cu")
		(net "M_L_CPU0_SA_DQ<25>")
	)
	(arc
		(start 392.331956 -240.756694)
		(mid 392.149705 -240.807044)
		(end 391.966196 -240.76152)
		(width 0.0889)
		(layer "In11.Cu")
		(net "M_L_CPU0_SA_DQ<25>")
	)
	(arc
		(start 391.01776 -240.756694)
		(mid 390.734804 -240.680517)
		(end 390.451848 -240.756694)
		(width 0.0889)
		(layer "In11.Cu")
		(net "M_L_CPU0_SA_DQ<25>")
	)
	(arc
		(start 393.348464 -240.697766)
		(mid 393.312149 -240.72971)
		(end 393.27201 -240.756694)
		(width 0.0889)
		(layer "In11.Cu")
		(net "M_L_CPU0_SA_DQ<25>")
	)
	(arc
		(start 387.63194 -240.756694)
		(mid 387.449689 -240.807044)
		(end 387.26618 -240.76152)
		(width 0.0889)
		(layer "In11.Cu")
		(net "M_L_CPU0_SA_DQ<25>")
	)
	(arc
		(start 391.957814 -240.756694)
		(mid 391.674858 -240.680517)
		(end 391.391902 -240.756694)
		(width 0.0889)
		(layer "In11.Cu")
		(net "M_L_CPU0_SA_DQ<25>")
	)
	(segment
		(start 386.50799 -239.890046)
		(end 386.974842 -239.624108)
		(width 0.10668)
		(layer "F.Cu")
		(net "M_L_CPU0_SA_DQ<24>")
	)
	(segment
		(start 437.463184 -224.96018)
		(end 440.676284 -224.96018)
		(width 0.14478)
		(layer "In11.Cu")
		(net "M_L_CPU0_SA_DQ<24>")
	)
	(segment
		(start 391.861548 -239.946434)
		(end 391.873486 -239.939576)
		(width 0.0889)
		(layer "In11.Cu")
		(net "M_L_CPU0_SA_DQ<24>")
	)
	(segment
		(start 393.431522 -239.870234)
		(end 394.054584 -239.247172)
		(width 0.0889)
		(layer "In11.Cu")
		(net "M_L_CPU0_SA_DQ<24>")
	)
	(segment
		(start 418.077904 -224.96018)
		(end 418.927788 -225.810064)
		(width 0.14478)
		(layer "In11.Cu")
		(net "M_L_CPU0_SA_DQ<24>")
	)
	(segment
		(start 418.927788 -225.810064)
		(end 421.538908 -225.810064)
		(width 0.14478)
		(layer "In11.Cu")
		(net "M_L_CPU0_SA_DQ<24>")
	)
	(segment
		(start 425.912534 -224.96018)
		(end 426.762418 -225.810064)
		(width 0.14478)
		(layer "In11.Cu")
		(net "M_L_CPU0_SA_DQ<24>")
	)
	(segment
		(start 422.388792 -224.96018)
		(end 425.912534 -224.96018)
		(width 0.14478)
		(layer "In11.Cu")
		(net "M_L_CPU0_SA_DQ<24>")
	)
	(segment
		(start 428.93742 -225.810064)
		(end 429.787304 -224.96018)
		(width 0.14478)
		(layer "In11.Cu")
		(net "M_L_CPU0_SA_DQ<24>")
	)
	(segment
		(start 411.493208 -226.695762)
		(end 412.378906 -225.810064)
		(width 0.14478)
		(layer "In11.Cu")
		(net "M_L_CPU0_SA_DQ<24>")
	)
	(segment
		(start 421.538908 -225.810064)
		(end 422.388792 -224.96018)
		(width 0.14478)
		(layer "In11.Cu")
		(net "M_L_CPU0_SA_DQ<24>")
	)
	(segment
		(start 387.128766 -239.889538)
		(end 387.224778 -239.914938)
		(width 0.0889)
		(layer "In11.Cu")
		(net "M_L_CPU0_SA_DQ<24>")
	)
	(segment
		(start 413.760666 -225.810064)
		(end 414.61055 -224.96018)
		(width 0.14478)
		(layer "In11.Cu")
		(net "M_L_CPU0_SA_DQ<24>")
	)
	(segment
		(start 389.607806 -239.946688)
		(end 389.616188 -239.951514)
		(width 0.0889)
		(layer "In11.Cu")
		(net "M_L_CPU0_SA_DQ<24>")
	)
	(segment
		(start 392.426698 -239.946688)
		(end 392.438382 -239.953546)
		(width 0.0889)
		(layer "In11.Cu")
		(net "M_L_CPU0_SA_DQ<24>")
	)
	(segment
		(start 433.190904 -224.96018)
		(end 434.040788 -225.810064)
		(width 0.14478)
		(layer "In11.Cu")
		(net "M_L_CPU0_SA_DQ<24>")
	)
	(segment
		(start 440.676284 -224.96018)
		(end 441.526168 -225.810064)
		(width 0.14478)
		(layer "In11.Cu")
		(net "M_L_CPU0_SA_DQ<24>")
	)
	(segment
		(start 412.378906 -225.810064)
		(end 413.760666 -225.810064)
		(width 0.14478)
		(layer "In11.Cu")
		(net "M_L_CPU0_SA_DQ<24>")
	)
	(segment
		(start 395.045438 -239.247172)
		(end 395.83995 -238.45266)
		(width 0.0889)
		(layer "In11.Cu")
		(net "M_L_CPU0_SA_DQ<24>")
	)
	(segment
		(start 414.61055 -224.96018)
		(end 418.077904 -224.96018)
		(width 0.14478)
		(layer "In11.Cu")
		(net "M_L_CPU0_SA_DQ<24>")
	)
	(segment
		(start 436.6133 -225.810064)
		(end 437.463184 -224.96018)
		(width 0.14478)
		(layer "In11.Cu")
		(net "M_L_CPU0_SA_DQ<24>")
	)
	(segment
		(start 391.845292 -239.955832)
		(end 391.861548 -239.946434)
		(width 0.0889)
		(layer "In11.Cu")
		(net "M_L_CPU0_SA_DQ<24>")
	)
	(segment
		(start 434.040788 -225.810064)
		(end 436.6133 -225.810064)
		(width 0.14478)
		(layer "In11.Cu")
		(net "M_L_CPU0_SA_DQ<24>")
	)
	(segment
		(start 388.093458 -239.951514)
		(end 388.10184 -239.946688)
		(width 0.0889)
		(layer "In11.Cu")
		(net "M_L_CPU0_SA_DQ<24>")
	)
	(segment
		(start 393.084812 -239.870234)
		(end 393.431522 -239.870234)
		(width 0.0889)
		(layer "In11.Cu")
		(net "M_L_CPU0_SA_DQ<24>")
	)
	(segment
		(start 444.876936 -224.96018)
		(end 453.763126 -224.96018)
		(width 0.14478)
		(layer "In11.Cu")
		(net "M_L_CPU0_SA_DQ<24>")
	)
	(segment
		(start 394.054584 -239.247172)
		(end 395.045438 -239.247172)
		(width 0.0889)
		(layer "In11.Cu")
		(net "M_L_CPU0_SA_DQ<24>")
	)
	(segment
		(start 389.033512 -239.951514)
		(end 389.041894 -239.946688)
		(width 0.0889)
		(layer "In11.Cu")
		(net "M_L_CPU0_SA_DQ<24>")
	)
	(segment
		(start 411.493208 -227.3935)
		(end 411.493208 -226.695762)
		(width 0.14478)
		(layer "In11.Cu")
		(net "M_L_CPU0_SA_DQ<24>")
	)
	(segment
		(start 395.83995 -238.45266)
		(end 395.998954 -238.45266)
		(width 0.0889)
		(layer "In11.Cu")
		(net "M_L_CPU0_SA_DQ<24>")
	)
	(segment
		(start 429.787304 -224.96018)
		(end 433.190904 -224.96018)
		(width 0.14478)
		(layer "In11.Cu")
		(net "M_L_CPU0_SA_DQ<24>")
	)
	(segment
		(start 406.225502 -231.729534)
		(end 407.157174 -231.729534)
		(width 0.14478)
		(layer "In11.Cu")
		(net "M_L_CPU0_SA_DQ<24>")
	)
	(segment
		(start 426.762418 -225.810064)
		(end 428.93742 -225.810064)
		(width 0.14478)
		(layer "In11.Cu")
		(net "M_L_CPU0_SA_DQ<24>")
	)
	(segment
		(start 399.502376 -238.45266)
		(end 406.225502 -231.729534)
		(width 0.14478)
		(layer "In11.Cu")
		(net "M_L_CPU0_SA_DQ<24>")
	)
	(segment
		(start 395.998954 -238.45266)
		(end 399.502376 -238.45266)
		(width 0.14478)
		(layer "In11.Cu")
		(net "M_L_CPU0_SA_DQ<24>")
	)
	(segment
		(start 444.027052 -225.810064)
		(end 444.876936 -224.96018)
		(width 0.14478)
		(layer "In11.Cu")
		(net "M_L_CPU0_SA_DQ<24>")
	)
	(segment
		(start 453.763126 -224.96018)
		(end 454.188068 -225.385122)
		(width 0.14478)
		(layer "In11.Cu")
		(net "M_L_CPU0_SA_DQ<24>")
	)
	(segment
		(start 407.157174 -231.729534)
		(end 411.493208 -227.3935)
		(width 0.14478)
		(layer "In11.Cu")
		(net "M_L_CPU0_SA_DQ<24>")
	)
	(segment
		(start 441.526168 -225.810064)
		(end 444.027052 -225.810064)
		(width 0.14478)
		(layer "In11.Cu")
		(net "M_L_CPU0_SA_DQ<24>")
	)
	(segment
		(start 386.974842 -239.624108)
		(end 387.128766 -239.889538)
		(width 0.0889)
		(layer "In11.Cu")
		(net "M_L_CPU0_SA_DQ<24>")
	)
	(arc
		(start 388.10184 -239.946688)
		(mid 388.384796 -239.870511)
		(end 388.667752 -239.946688)
		(width 0.0889)
		(layer "In11.Cu")
		(net "M_L_CPU0_SA_DQ<24>")
	)
	(arc
		(start 392.438382 -239.953546)
		(mid 392.620637 -239.997199)
		(end 392.801094 -239.946688)
		(width 0.0889)
		(layer "In11.Cu")
		(net "M_L_CPU0_SA_DQ<24>")
	)
	(arc
		(start 387.727698 -239.946688)
		(mid 387.909949 -239.997038)
		(end 388.093458 -239.951514)
		(width 0.0889)
		(layer "In11.Cu")
		(net "M_L_CPU0_SA_DQ<24>")
	)
	(arc
		(start 391.873486 -239.939576)
		(mid 392.15102 -239.870595)
		(end 392.426698 -239.946688)
		(width 0.0889)
		(layer "In11.Cu")
		(net "M_L_CPU0_SA_DQ<24>")
	)
	(arc
		(start 389.981948 -239.946688)
		(mid 390.264904 -239.870511)
		(end 390.54786 -239.946688)
		(width 0.0889)
		(layer "In11.Cu")
		(net "M_L_CPU0_SA_DQ<24>")
	)
	(arc
		(start 389.616188 -239.951514)
		(mid 389.799696 -239.997008)
		(end 389.981948 -239.946688)
		(width 0.0889)
		(layer "In11.Cu")
		(net "M_L_CPU0_SA_DQ<24>")
	)
	(arc
		(start 389.041894 -239.946688)
		(mid 389.32485 -239.870511)
		(end 389.607806 -239.946688)
		(width 0.0889)
		(layer "In11.Cu")
		(net "M_L_CPU0_SA_DQ<24>")
	)
	(arc
		(start 392.801094 -239.946688)
		(mid 392.937887 -239.889666)
		(end 393.084812 -239.870234)
		(width 0.0889)
		(layer "In11.Cu")
		(net "M_L_CPU0_SA_DQ<24>")
	)
	(arc
		(start 390.921748 -239.946688)
		(mid 391.204704 -239.870511)
		(end 391.48766 -239.946688)
		(width 0.0889)
		(layer "In11.Cu")
		(net "M_L_CPU0_SA_DQ<24>")
	)
	(arc
		(start 388.667752 -239.946688)
		(mid 388.850003 -239.997038)
		(end 389.033512 -239.951514)
		(width 0.0889)
		(layer "In11.Cu")
		(net "M_L_CPU0_SA_DQ<24>")
	)
	(arc
		(start 390.54786 -239.946688)
		(mid 390.734804 -239.996943)
		(end 390.921748 -239.946688)
		(width 0.0889)
		(layer "In11.Cu")
		(net "M_L_CPU0_SA_DQ<24>")
	)
	(arc
		(start 387.224778 -239.914938)
		(mid 387.479986 -239.871461)
		(end 387.727698 -239.946688)
		(width 0.0889)
		(layer "In11.Cu")
		(net "M_L_CPU0_SA_DQ<24>")
	)
	(arc
		(start 391.48766 -239.946688)
		(mid 391.66531 -239.996948)
		(end 391.845292 -239.955832)
		(width 0.0889)
		(layer "In11.Cu")
		(net "M_L_CPU0_SA_DQ<24>")
	)
	(segment
		(start 385.567936 -239.890046)
		(end 386.034788 -239.624108)
		(width 0.10668)
		(layer "F.Cu")
		(net "M_L_CPU0_SA_DQ<23>")
	)
	(segment
		(start 407.793952 -230.270304)
		(end 407.957274 -230.106982)
		(width 0.14478)
		(layer "In11.Cu")
		(net "M_L_CPU0_SA_DQ<23>")
	)
	(segment
		(start 407.95702 -229.876858)
		(end 407.736294 -229.656132)
		(width 0.14478)
		(layer "In11.Cu")
		(net "M_L_CPU0_SA_DQ<23>")
	)
	(segment
		(start 409.13812 -228.695504)
		(end 409.368752 -228.695504)
		(width 0.14478)
		(layer "In11.Cu")
		(net "M_L_CPU0_SA_DQ<23>")
	)
	(segment
		(start 395.81455 -237.8964)
		(end 395.978888 -237.8964)
		(width 0.0889)
		(layer "In11.Cu")
		(net "M_L_CPU0_SA_DQ<23>")
	)
	(segment
		(start 415.94024 -224.110042)
		(end 416.259772 -223.79051)
		(width 0.14478)
		(layer "In11.Cu")
		(net "M_L_CPU0_SA_DQ<23>")
	)
	(segment
		(start 415.146744 -223.79051)
		(end 415.383726 -223.79051)
		(width 0.14478)
		(layer "In11.Cu")
		(net "M_L_CPU0_SA_DQ<23>")
	)
	(segment
		(start 408.523694 -228.6381)
		(end 408.686762 -228.475032)
		(width 0.14478)
		(layer "In11.Cu")
		(net "M_L_CPU0_SA_DQ<23>")
	)
	(segment
		(start 406.77592 -231.057704)
		(end 407.006552 -231.057704)
		(width 0.14478)
		(layer "In11.Cu")
		(net "M_L_CPU0_SA_DQ<23>")
	)
	(segment
		(start 408.917394 -228.474778)
		(end 409.13812 -228.695504)
		(width 0.14478)
		(layer "In11.Cu")
		(net "M_L_CPU0_SA_DQ<23>")
	)
	(segment
		(start 418.404802 -224.110042)
		(end 419.25494 -224.96018)
		(width 0.14478)
		(layer "In11.Cu")
		(net "M_L_CPU0_SA_DQ<23>")
	)
	(segment
		(start 410.319474 -227.744782)
		(end 410.31922 -227.514658)
		(width 0.14478)
		(layer "In11.Cu")
		(net "M_L_CPU0_SA_DQ<23>")
	)
	(segment
		(start 416.816286 -224.110042)
		(end 417.053268 -224.110042)
		(width 0.14478)
		(layer "In11.Cu")
		(net "M_L_CPU0_SA_DQ<23>")
	)
	(segment
		(start 417.3728 -223.79051)
		(end 417.609782 -223.79051)
		(width 0.14478)
		(layer "In11.Cu")
		(net "M_L_CPU0_SA_DQ<23>")
	)
	(segment
		(start 408.129994 -229.262178)
		(end 408.35072 -229.482904)
		(width 0.14478)
		(layer "In11.Cu")
		(net "M_L_CPU0_SA_DQ<23>")
	)
	(segment
		(start 386.034788 -239.624108)
		(end 385.880864 -239.358678)
		(width 0.0889)
		(layer "In11.Cu")
		(net "M_L_CPU0_SA_DQ<23>")
	)
	(segment
		(start 408.744674 -229.319582)
		(end 408.74442 -229.089458)
		(width 0.14478)
		(layer "In11.Cu")
		(net "M_L_CPU0_SA_DQ<23>")
	)
	(segment
		(start 449.663312 -224.110296)
		(end 450.088 -224.534984)
		(width 0.14478)
		(layer "In11.Cu")
		(net "M_L_CPU0_SA_DQ<23>")
	)
	(segment
		(start 410.098494 -227.293932)
		(end 410.098494 -227.0633)
		(width 0.14478)
		(layer "In11.Cu")
		(net "M_L_CPU0_SA_DQ<23>")
	)
	(segment
		(start 406.948894 -230.2129)
		(end 407.111962 -230.049832)
		(width 0.14478)
		(layer "In11.Cu")
		(net "M_L_CPU0_SA_DQ<23>")
	)
	(segment
		(start 408.581352 -229.482904)
		(end 408.744674 -229.319582)
		(width 0.14478)
		(layer "In11.Cu")
		(net "M_L_CPU0_SA_DQ<23>")
	)
	(segment
		(start 410.156152 -227.908104)
		(end 410.319474 -227.744782)
		(width 0.14478)
		(layer "In11.Cu")
		(net "M_L_CPU0_SA_DQ<23>")
	)
	(segment
		(start 413.531304 -224.96018)
		(end 414.381442 -224.110042)
		(width 0.14478)
		(layer "In11.Cu")
		(net "M_L_CPU0_SA_DQ<23>")
	)
	(segment
		(start 409.311094 -227.8507)
		(end 409.474162 -227.687632)
		(width 0.14478)
		(layer "In11.Cu")
		(net "M_L_CPU0_SA_DQ<23>")
	)
	(segment
		(start 385.880864 -239.358678)
		(end 385.903216 -239.275366)
		(width 0.0889)
		(layer "In11.Cu")
		(net "M_L_CPU0_SA_DQ<23>")
	)
	(segment
		(start 436.6133 -224.96018)
		(end 437.463184 -224.110296)
		(width 0.14478)
		(layer "In11.Cu")
		(net "M_L_CPU0_SA_DQ<23>")
	)
	(segment
		(start 415.383726 -223.79051)
		(end 415.703258 -224.110042)
		(width 0.14478)
		(layer "In11.Cu")
		(net "M_L_CPU0_SA_DQ<23>")
	)
	(segment
		(start 433.190904 -224.110296)
		(end 434.040788 -224.96018)
		(width 0.14478)
		(layer "In11.Cu")
		(net "M_L_CPU0_SA_DQ<23>")
	)
	(segment
		(start 429.69688 -224.110296)
		(end 433.190904 -224.110296)
		(width 0.14478)
		(layer "In11.Cu")
		(net "M_L_CPU0_SA_DQ<23>")
	)
	(segment
		(start 395.423898 -238.287052)
		(end 395.81455 -237.8964)
		(width 0.0889)
		(layer "In11.Cu")
		(net "M_L_CPU0_SA_DQ<23>")
	)
	(segment
		(start 409.532074 -228.532182)
		(end 409.53182 -228.302058)
		(width 0.14478)
		(layer "In11.Cu")
		(net "M_L_CPU0_SA_DQ<23>")
	)
	(segment
		(start 407.006552 -231.057704)
		(end 407.169874 -230.894382)
		(width 0.14478)
		(layer "In11.Cu")
		(net "M_L_CPU0_SA_DQ<23>")
	)
	(segment
		(start 406.555194 -230.836978)
		(end 406.77592 -231.057704)
		(width 0.14478)
		(layer "In11.Cu")
		(net "M_L_CPU0_SA_DQ<23>")
	)
	(segment
		(start 428.846996 -224.96018)
		(end 429.69688 -224.110296)
		(width 0.14478)
		(layer "In11.Cu")
		(net "M_L_CPU0_SA_DQ<23>")
	)
	(segment
		(start 425.912534 -224.110296)
		(end 426.762418 -224.96018)
		(width 0.14478)
		(layer "In11.Cu")
		(net "M_L_CPU0_SA_DQ<23>")
	)
	(segment
		(start 441.485528 -224.96018)
		(end 443.982856 -224.96018)
		(width 0.14478)
		(layer "In11.Cu")
		(net "M_L_CPU0_SA_DQ<23>")
	)
	(segment
		(start 407.342594 -230.049578)
		(end 407.56332 -230.270304)
		(width 0.14478)
		(layer "In11.Cu")
		(net "M_L_CPU0_SA_DQ<23>")
	)
	(segment
		(start 416.259772 -223.79051)
		(end 416.496754 -223.79051)
		(width 0.14478)
		(layer "In11.Cu")
		(net "M_L_CPU0_SA_DQ<23>")
	)
	(segment
		(start 399.265394 -237.8964)
		(end 406.324562 -230.837232)
		(width 0.14478)
		(layer "In11.Cu")
		(net "M_L_CPU0_SA_DQ<23>")
	)
	(segment
		(start 395.978888 -237.8964)
		(end 399.265394 -237.8964)
		(width 0.14478)
		(layer "In11.Cu")
		(net "M_L_CPU0_SA_DQ<23>")
	)
	(segment
		(start 417.609782 -223.79051)
		(end 417.929314 -224.110042)
		(width 0.14478)
		(layer "In11.Cu")
		(net "M_L_CPU0_SA_DQ<23>")
	)
	(segment
		(start 389.607806 -239.301528)
		(end 389.616188 -239.296702)
		(width 0.0889)
		(layer "In11.Cu")
		(net "M_L_CPU0_SA_DQ<23>")
	)
	(segment
		(start 407.736294 -229.4255)
		(end 407.899362 -229.262432)
		(width 0.14478)
		(layer "In11.Cu")
		(net "M_L_CPU0_SA_DQ<23>")
	)
	(segment
		(start 394.948918 -238.962692)
		(end 395.423898 -238.487712)
		(width 0.0889)
		(layer "In11.Cu")
		(net "M_L_CPU0_SA_DQ<23>")
	)
	(segment
		(start 415.703258 -224.110042)
		(end 415.94024 -224.110042)
		(width 0.14478)
		(layer "In11.Cu")
		(net "M_L_CPU0_SA_DQ<23>")
	)
	(segment
		(start 389.033512 -239.296702)
		(end 389.041894 -239.301528)
		(width 0.0889)
		(layer "In11.Cu")
		(net "M_L_CPU0_SA_DQ<23>")
	)
	(segment
		(start 407.899362 -229.262432)
		(end 408.129994 -229.262178)
		(width 0.14478)
		(layer "In11.Cu")
		(net "M_L_CPU0_SA_DQ<23>")
	)
	(segment
		(start 408.35072 -229.482904)
		(end 408.581352 -229.482904)
		(width 0.14478)
		(layer "In11.Cu")
		(net "M_L_CPU0_SA_DQ<23>")
	)
	(segment
		(start 409.474162 -227.687632)
		(end 409.704794 -227.687378)
		(width 0.14478)
		(layer "In11.Cu")
		(net "M_L_CPU0_SA_DQ<23>")
	)
	(segment
		(start 408.686762 -228.475032)
		(end 408.917394 -228.474778)
		(width 0.14478)
		(layer "In11.Cu")
		(net "M_L_CPU0_SA_DQ<23>")
	)
	(segment
		(start 440.635644 -224.110296)
		(end 441.485528 -224.96018)
		(width 0.14478)
		(layer "In11.Cu")
		(net "M_L_CPU0_SA_DQ<23>")
	)
	(segment
		(start 437.463184 -224.110296)
		(end 440.635644 -224.110296)
		(width 0.14478)
		(layer "In11.Cu")
		(net "M_L_CPU0_SA_DQ<23>")
	)
	(segment
		(start 388.093458 -239.296702)
		(end 388.10184 -239.301528)
		(width 0.0889)
		(layer "In11.Cu")
		(net "M_L_CPU0_SA_DQ<23>")
	)
	(segment
		(start 407.16962 -230.664258)
		(end 406.948894 -230.443532)
		(width 0.14478)
		(layer "In11.Cu")
		(net "M_L_CPU0_SA_DQ<23>")
	)
	(segment
		(start 393.733274 -238.962692)
		(end 394.948918 -238.962692)
		(width 0.0889)
		(layer "In11.Cu")
		(net "M_L_CPU0_SA_DQ<23>")
	)
	(segment
		(start 392.80211 -239.301528)
		(end 392.816842 -239.310164)
		(width 0.0889)
		(layer "In11.Cu")
		(net "M_L_CPU0_SA_DQ<23>")
	)
	(segment
		(start 407.56332 -230.270304)
		(end 407.793952 -230.270304)
		(width 0.14478)
		(layer "In11.Cu")
		(net "M_L_CPU0_SA_DQ<23>")
	)
	(segment
		(start 422.284144 -224.110296)
		(end 425.912534 -224.110296)
		(width 0.14478)
		(layer "In11.Cu")
		(net "M_L_CPU0_SA_DQ<23>")
	)
	(segment
		(start 409.368752 -228.695504)
		(end 409.532074 -228.532182)
		(width 0.14478)
		(layer "In11.Cu")
		(net "M_L_CPU0_SA_DQ<23>")
	)
	(segment
		(start 421.43426 -224.96018)
		(end 422.284144 -224.110296)
		(width 0.14478)
		(layer "In11.Cu")
		(net "M_L_CPU0_SA_DQ<23>")
	)
	(segment
		(start 408.74442 -229.089458)
		(end 408.523694 -228.868732)
		(width 0.14478)
		(layer "In11.Cu")
		(net "M_L_CPU0_SA_DQ<23>")
	)
	(segment
		(start 393.483338 -239.212628)
		(end 393.733274 -238.962692)
		(width 0.0889)
		(layer "In11.Cu")
		(net "M_L_CPU0_SA_DQ<23>")
	)
	(segment
		(start 408.523694 -228.868732)
		(end 408.523694 -228.6381)
		(width 0.14478)
		(layer "In11.Cu")
		(net "M_L_CPU0_SA_DQ<23>")
	)
	(segment
		(start 434.040788 -224.96018)
		(end 436.6133 -224.96018)
		(width 0.14478)
		(layer "In11.Cu")
		(net "M_L_CPU0_SA_DQ<23>")
	)
	(segment
		(start 407.169874 -230.894382)
		(end 407.16962 -230.664258)
		(width 0.14478)
		(layer "In11.Cu")
		(net "M_L_CPU0_SA_DQ<23>")
	)
	(segment
		(start 409.311094 -228.081332)
		(end 409.311094 -227.8507)
		(width 0.14478)
		(layer "In11.Cu")
		(net "M_L_CPU0_SA_DQ<23>")
	)
	(segment
		(start 410.31922 -227.514658)
		(end 410.098494 -227.293932)
		(width 0.14478)
		(layer "In11.Cu")
		(net "M_L_CPU0_SA_DQ<23>")
	)
	(segment
		(start 406.948894 -230.443532)
		(end 406.948894 -230.2129)
		(width 0.14478)
		(layer "In11.Cu")
		(net "M_L_CPU0_SA_DQ<23>")
	)
	(segment
		(start 407.736294 -229.656132)
		(end 407.736294 -229.4255)
		(width 0.14478)
		(layer "In11.Cu")
		(net "M_L_CPU0_SA_DQ<23>")
	)
	(segment
		(start 392.417808 -239.307624)
		(end 392.428222 -239.301528)
		(width 0.0889)
		(layer "In11.Cu")
		(net "M_L_CPU0_SA_DQ<23>")
	)
	(segment
		(start 414.827212 -224.110042)
		(end 415.146744 -223.79051)
		(width 0.14478)
		(layer "In11.Cu")
		(net "M_L_CPU0_SA_DQ<23>")
	)
	(segment
		(start 407.957274 -230.106982)
		(end 407.95702 -229.876858)
		(width 0.14478)
		(layer "In11.Cu")
		(net "M_L_CPU0_SA_DQ<23>")
	)
	(segment
		(start 417.053268 -224.110042)
		(end 417.3728 -223.79051)
		(width 0.14478)
		(layer "In11.Cu")
		(net "M_L_CPU0_SA_DQ<23>")
	)
	(segment
		(start 407.111962 -230.049832)
		(end 407.342594 -230.049578)
		(width 0.14478)
		(layer "In11.Cu")
		(net "M_L_CPU0_SA_DQ<23>")
	)
	(segment
		(start 444.83274 -224.110296)
		(end 449.663312 -224.110296)
		(width 0.14478)
		(layer "In11.Cu")
		(net "M_L_CPU0_SA_DQ<23>")
	)
	(segment
		(start 409.704794 -227.687378)
		(end 409.92552 -227.908104)
		(width 0.14478)
		(layer "In11.Cu")
		(net "M_L_CPU0_SA_DQ<23>")
	)
	(segment
		(start 412.201614 -224.96018)
		(end 413.531304 -224.96018)
		(width 0.14478)
		(layer "In11.Cu")
		(net "M_L_CPU0_SA_DQ<23>")
	)
	(segment
		(start 426.762418 -224.96018)
		(end 428.846996 -224.96018)
		(width 0.14478)
		(layer "In11.Cu")
		(net "M_L_CPU0_SA_DQ<23>")
	)
	(segment
		(start 416.496754 -223.79051)
		(end 416.816286 -224.110042)
		(width 0.14478)
		(layer "In11.Cu")
		(net "M_L_CPU0_SA_DQ<23>")
	)
	(segment
		(start 443.982856 -224.96018)
		(end 444.83274 -224.110296)
		(width 0.14478)
		(layer "In11.Cu")
		(net "M_L_CPU0_SA_DQ<23>")
	)
	(segment
		(start 409.92552 -227.908104)
		(end 410.156152 -227.908104)
		(width 0.14478)
		(layer "In11.Cu")
		(net "M_L_CPU0_SA_DQ<23>")
	)
	(segment
		(start 410.098494 -227.0633)
		(end 412.201614 -224.96018)
		(width 0.14478)
		(layer "In11.Cu")
		(net "M_L_CPU0_SA_DQ<23>")
	)
	(segment
		(start 409.53182 -228.302058)
		(end 409.311094 -228.081332)
		(width 0.14478)
		(layer "In11.Cu")
		(net "M_L_CPU0_SA_DQ<23>")
	)
	(segment
		(start 395.423898 -238.487712)
		(end 395.423898 -238.287052)
		(width 0.0889)
		(layer "In11.Cu")
		(net "M_L_CPU0_SA_DQ<23>")
	)
	(segment
		(start 417.929314 -224.110042)
		(end 418.404802 -224.110042)
		(width 0.14478)
		(layer "In11.Cu")
		(net "M_L_CPU0_SA_DQ<23>")
	)
	(segment
		(start 419.25494 -224.96018)
		(end 421.43426 -224.96018)
		(width 0.14478)
		(layer "In11.Cu")
		(net "M_L_CPU0_SA_DQ<23>")
	)
	(segment
		(start 406.324562 -230.837232)
		(end 406.555194 -230.836978)
		(width 0.14478)
		(layer "In11.Cu")
		(net "M_L_CPU0_SA_DQ<23>")
	)
	(segment
		(start 414.381442 -224.110042)
		(end 414.827212 -224.110042)
		(width 0.14478)
		(layer "In11.Cu")
		(net "M_L_CPU0_SA_DQ<23>")
	)
	(arc
		(start 392.428222 -239.301528)
		(mid 392.615166 -239.251273)
		(end 392.80211 -239.301528)
		(width 0.0889)
		(layer "In11.Cu")
		(net "M_L_CPU0_SA_DQ<23>")
	)
	(arc
		(start 390.54786 -239.301528)
		(mid 390.734804 -239.251273)
		(end 390.921748 -239.301528)
		(width 0.0889)
		(layer "In11.Cu")
		(net "M_L_CPU0_SA_DQ<23>")
	)
	(arc
		(start 387.161786 -239.301528)
		(mid 387.444742 -239.377705)
		(end 387.727698 -239.301528)
		(width 0.0889)
		(layer "In11.Cu")
		(net "M_L_CPU0_SA_DQ<23>")
	)
	(arc
		(start 385.903216 -239.275366)
		(mid 386.065548 -239.252548)
		(end 386.221986 -239.301528)
		(width 0.0889)
		(layer "In11.Cu")
		(net "M_L_CPU0_SA_DQ<23>")
	)
	(arc
		(start 389.616188 -239.296702)
		(mid 389.799696 -239.251208)
		(end 389.981948 -239.301528)
		(width 0.0889)
		(layer "In11.Cu")
		(net "M_L_CPU0_SA_DQ<23>")
	)
	(arc
		(start 390.921748 -239.301528)
		(mid 391.204704 -239.377705)
		(end 391.48766 -239.301528)
		(width 0.0889)
		(layer "In11.Cu")
		(net "M_L_CPU0_SA_DQ<23>")
	)
	(arc
		(start 387.727698 -239.301528)
		(mid 387.909949 -239.251178)
		(end 388.093458 -239.296702)
		(width 0.0889)
		(layer "In11.Cu")
		(net "M_L_CPU0_SA_DQ<23>")
	)
	(arc
		(start 388.10184 -239.301528)
		(mid 388.384796 -239.377705)
		(end 388.667752 -239.301528)
		(width 0.0889)
		(layer "In11.Cu")
		(net "M_L_CPU0_SA_DQ<23>")
	)
	(arc
		(start 392.816842 -239.310164)
		(mid 393.093571 -239.377847)
		(end 393.368022 -239.301528)
		(width 0.0889)
		(layer "In11.Cu")
		(net "M_L_CPU0_SA_DQ<23>")
	)
	(arc
		(start 386.221986 -239.301528)
		(mid 386.504942 -239.377705)
		(end 386.787898 -239.301528)
		(width 0.0889)
		(layer "In11.Cu")
		(net "M_L_CPU0_SA_DQ<23>")
	)
	(arc
		(start 386.787898 -239.301528)
		(mid 386.974842 -239.251273)
		(end 387.161786 -239.301528)
		(width 0.0889)
		(layer "In11.Cu")
		(net "M_L_CPU0_SA_DQ<23>")
	)
	(arc
		(start 389.041894 -239.301528)
		(mid 389.32485 -239.377705)
		(end 389.607806 -239.301528)
		(width 0.0889)
		(layer "In11.Cu")
		(net "M_L_CPU0_SA_DQ<23>")
	)
	(arc
		(start 388.667752 -239.301528)
		(mid 388.850003 -239.251178)
		(end 389.033512 -239.296702)
		(width 0.0889)
		(layer "In11.Cu")
		(net "M_L_CPU0_SA_DQ<23>")
	)
	(arc
		(start 391.862056 -239.301528)
		(mid 392.139123 -239.377799)
		(end 392.417808 -239.307624)
		(width 0.0889)
		(layer "In11.Cu")
		(net "M_L_CPU0_SA_DQ<23>")
	)
	(arc
		(start 393.368022 -239.301528)
		(mid 393.428557 -239.260811)
		(end 393.483338 -239.212628)
		(width 0.0889)
		(layer "In11.Cu")
		(net "M_L_CPU0_SA_DQ<23>")
	)
	(arc
		(start 391.48766 -239.301528)
		(mid 391.674858 -239.251146)
		(end 391.862056 -239.301528)
		(width 0.0889)
		(layer "In11.Cu")
		(net "M_L_CPU0_SA_DQ<23>")
	)
	(arc
		(start 389.981948 -239.301528)
		(mid 390.264904 -239.377705)
		(end 390.54786 -239.301528)
		(width 0.0889)
		(layer "In11.Cu")
		(net "M_L_CPU0_SA_DQ<23>")
	)
	(segment
		(start 386.97789 -239.08004)
		(end 387.444742 -238.814102)
		(width 0.10668)
		(layer "F.Cu")
		(net "M_L_CPU0_SA_DQ<22>")
	)
	(segment
		(start 398.900396 -236.92866)
		(end 398.669764 -236.92866)
		(width 0.14478)
		(layer "In11.Cu")
		(net "M_L_CPU0_SA_DQ<22>")
	)
	(segment
		(start 402.896832 -232.26395)
		(end 402.896832 -232.494582)
		(width 0.14478)
		(layer "In11.Cu")
		(net "M_L_CPU0_SA_DQ<22>")
	)
	(segment
		(start 387.290818 -238.548672)
		(end 387.444742 -238.814102)
		(width 0.0889)
		(layer "In11.Cu")
		(net "M_L_CPU0_SA_DQ<22>")
	)
	(segment
		(start 399.747232 -235.644182)
		(end 399.850864 -235.747814)
		(width 0.14478)
		(layer "In11.Cu")
		(net "M_L_CPU0_SA_DQ<22>")
	)
	(segment
		(start 387.31317 -238.46536)
		(end 387.290818 -238.548672)
		(width 0.0889)
		(layer "In11.Cu")
		(net "M_L_CPU0_SA_DQ<22>")
	)
	(segment
		(start 401.819364 -233.77906)
		(end 401.715732 -233.675428)
		(width 0.14478)
		(layer "In11.Cu")
		(net "M_L_CPU0_SA_DQ<22>")
	)
	(segment
		(start 402.606764 -232.99166)
		(end 402.503132 -232.888028)
		(width 0.14478)
		(layer "In11.Cu")
		(net "M_L_CPU0_SA_DQ<22>")
	)
	(segment
		(start 419.076124 -223.260158)
		(end 418.225986 -222.41002)
		(width 0.14478)
		(layer "In11.Cu")
		(net "M_L_CPU0_SA_DQ<22>")
	)
	(segment
		(start 404.968964 -230.62946)
		(end 404.865332 -230.525828)
		(width 0.14478)
		(layer "In11.Cu")
		(net "M_L_CPU0_SA_DQ<22>")
	)
	(segment
		(start 402.837396 -232.99166)
		(end 402.606764 -232.99166)
		(width 0.14478)
		(layer "In11.Cu")
		(net "M_L_CPU0_SA_DQ<22>")
	)
	(segment
		(start 393.868148 -238.440722)
		(end 393.084812 -238.440722)
		(width 0.0889)
		(layer "In11.Cu")
		(net "M_L_CPU0_SA_DQ<22>")
	)
	(segment
		(start 399.687796 -236.14126)
		(end 399.457164 -236.14126)
		(width 0.14478)
		(layer "In11.Cu")
		(net "M_L_CPU0_SA_DQ<22>")
	)
	(segment
		(start 437.463184 -222.410274)
		(end 436.6133 -223.260158)
		(width 0.14478)
		(layer "In11.Cu")
		(net "M_L_CPU0_SA_DQ<22>")
	)
	(segment
		(start 404.471632 -230.68915)
		(end 404.471632 -230.919782)
		(width 0.14478)
		(layer "In11.Cu")
		(net "M_L_CPU0_SA_DQ<22>")
	)
	(segment
		(start 403.787864 -231.810814)
		(end 403.788118 -232.040938)
		(width 0.14478)
		(layer "In11.Cu")
		(net "M_L_CPU0_SA_DQ<22>")
	)
	(segment
		(start 402.896832 -232.494582)
		(end 403.000464 -232.598214)
		(width 0.14478)
		(layer "In11.Cu")
		(net "M_L_CPU0_SA_DQ<22>")
	)
	(segment
		(start 401.4851 -233.675682)
		(end 401.322032 -233.83875)
		(width 0.14478)
		(layer "In11.Cu")
		(net "M_L_CPU0_SA_DQ<22>")
	)
	(segment
		(start 448.228466 -222.265494)
		(end 448.083686 -222.410274)
		(width 0.14478)
		(layer "In11.Cu")
		(net "M_L_CPU0_SA_DQ<22>")
	)
	(segment
		(start 448.7799 -222.265494)
		(end 448.7799 -222.173292)
		(width 0.14478)
		(layer "In11.Cu")
		(net "M_L_CPU0_SA_DQ<22>")
	)
	(segment
		(start 421.446452 -223.260158)
		(end 419.076124 -223.260158)
		(width 0.14478)
		(layer "In11.Cu")
		(net "M_L_CPU0_SA_DQ<22>")
	)
	(segment
		(start 392.34872 -238.50219)
		(end 392.330686 -238.491522)
		(width 0.0889)
		(layer "In11.Cu")
		(net "M_L_CPU0_SA_DQ<22>")
	)
	(segment
		(start 399.747232 -235.41355)
		(end 399.747232 -235.644182)
		(width 0.14478)
		(layer "In11.Cu")
		(net "M_L_CPU0_SA_DQ<22>")
	)
	(segment
		(start 403.684232 -231.47655)
		(end 403.684232 -231.707182)
		(width 0.14478)
		(layer "In11.Cu")
		(net "M_L_CPU0_SA_DQ<22>")
	)
	(segment
		(start 401.262596 -234.56646)
		(end 401.031964 -234.56646)
		(width 0.14478)
		(layer "In11.Cu")
		(net "M_L_CPU0_SA_DQ<22>")
	)
	(segment
		(start 402.109432 -233.05135)
		(end 402.109432 -233.281982)
		(width 0.14478)
		(layer "In11.Cu")
		(net "M_L_CPU0_SA_DQ<22>")
	)
	(segment
		(start 411.918404 -223.404938)
		(end 411.918404 -223.910652)
		(width 0.14478)
		(layer "In11.Cu")
		(net "M_L_CPU0_SA_DQ<22>")
	)
	(segment
		(start 398.959832 -236.20095)
		(end 398.959832 -236.431582)
		(width 0.14478)
		(layer "In11.Cu")
		(net "M_L_CPU0_SA_DQ<22>")
	)
	(segment
		(start 398.173702 -236.98708)
		(end 396.086584 -236.98708)
		(width 0.14478)
		(layer "In11.Cu")
		(net "M_L_CPU0_SA_DQ<22>")
	)
	(segment
		(start 399.063718 -236.765338)
		(end 398.900396 -236.92866)
		(width 0.14478)
		(layer "In11.Cu")
		(net "M_L_CPU0_SA_DQ<22>")
	)
	(segment
		(start 403.0599 -232.100882)
		(end 402.896832 -232.26395)
		(width 0.14478)
		(layer "In11.Cu")
		(net "M_L_CPU0_SA_DQ<22>")
	)
	(segment
		(start 404.575264 -231.023414)
		(end 404.575518 -231.253538)
		(width 0.14478)
		(layer "In11.Cu")
		(net "M_L_CPU0_SA_DQ<22>")
	)
	(segment
		(start 399.1229 -236.037882)
		(end 398.959832 -236.20095)
		(width 0.14478)
		(layer "In11.Cu")
		(net "M_L_CPU0_SA_DQ<22>")
	)
	(segment
		(start 405.259032 -229.90175)
		(end 405.259032 -230.132382)
		(width 0.14478)
		(layer "In11.Cu")
		(net "M_L_CPU0_SA_DQ<22>")
	)
	(segment
		(start 396.086584 -236.98708)
		(end 395.87551 -236.98708)
		(width 0.0889)
		(layer "In11.Cu")
		(net "M_L_CPU0_SA_DQ<22>")
	)
	(segment
		(start 422.296336 -222.410274)
		(end 421.446452 -223.260158)
		(width 0.14478)
		(layer "In11.Cu")
		(net "M_L_CPU0_SA_DQ<22>")
	)
	(segment
		(start 441.387992 -223.260158)
		(end 440.538108 -222.410274)
		(width 0.14478)
		(layer "In11.Cu")
		(net "M_L_CPU0_SA_DQ<22>")
	)
	(segment
		(start 403.394164 -232.20426)
		(end 403.290532 -232.100628)
		(width 0.14478)
		(layer "In11.Cu")
		(net "M_L_CPU0_SA_DQ<22>")
	)
	(segment
		(start 405.199596 -230.62946)
		(end 404.968964 -230.62946)
		(width 0.14478)
		(layer "In11.Cu")
		(net "M_L_CPU0_SA_DQ<22>")
	)
	(segment
		(start 394.420598 -237.888272)
		(end 393.868148 -238.440722)
		(width 0.0889)
		(layer "In11.Cu")
		(net "M_L_CPU0_SA_DQ<22>")
	)
	(segment
		(start 414.738058 -222.41002)
		(end 413.88792 -223.260158)
		(width 0.14478)
		(layer "In11.Cu")
		(net "M_L_CPU0_SA_DQ<22>")
	)
	(segment
		(start 402.049996 -233.77906)
		(end 401.819364 -233.77906)
		(width 0.14478)
		(layer "In11.Cu")
		(net "M_L_CPU0_SA_DQ<22>")
	)
	(segment
		(start 448.92468 -222.410274)
		(end 448.7799 -222.265494)
		(width 0.14478)
		(layer "In11.Cu")
		(net "M_L_CPU0_SA_DQ<22>")
	)
	(segment
		(start 401.322032 -234.069382)
		(end 401.425664 -234.173014)
		(width 0.14478)
		(layer "In11.Cu")
		(net "M_L_CPU0_SA_DQ<22>")
	)
	(segment
		(start 448.7799 -222.173292)
		(end 448.63512 -222.028512)
		(width 0.14478)
		(layer "In11.Cu")
		(net "M_L_CPU0_SA_DQ<22>")
	)
	(segment
		(start 403.624796 -232.20426)
		(end 403.394164 -232.20426)
		(width 0.14478)
		(layer "In11.Cu")
		(net "M_L_CPU0_SA_DQ<22>")
	)
	(segment
		(start 401.322032 -233.83875)
		(end 401.322032 -234.069382)
		(width 0.14478)
		(layer "In11.Cu")
		(net "M_L_CPU0_SA_DQ<22>")
	)
	(segment
		(start 402.503132 -232.888028)
		(end 402.2725 -232.888282)
		(width 0.14478)
		(layer "In11.Cu")
		(net "M_L_CPU0_SA_DQ<22>")
	)
	(segment
		(start 398.3355 -236.825282)
		(end 398.173702 -236.98708)
		(width 0.14478)
		(layer "In11.Cu")
		(net "M_L_CPU0_SA_DQ<22>")
	)
	(segment
		(start 404.181564 -231.41686)
		(end 404.077932 -231.313228)
		(width 0.14478)
		(layer "In11.Cu")
		(net "M_L_CPU0_SA_DQ<22>")
	)
	(segment
		(start 425.912534 -222.410274)
		(end 422.296336 -222.410274)
		(width 0.14478)
		(layer "In11.Cu")
		(net "M_L_CPU0_SA_DQ<22>")
	)
	(segment
		(start 398.669764 -236.92866)
		(end 398.566132 -236.825028)
		(width 0.14478)
		(layer "In11.Cu")
		(net "M_L_CPU0_SA_DQ<22>")
	)
	(segment
		(start 433.190904 -222.410274)
		(end 429.855376 -222.410274)
		(width 0.14478)
		(layer "In11.Cu")
		(net "M_L_CPU0_SA_DQ<22>")
	)
	(segment
		(start 449.663312 -222.410274)
		(end 448.92468 -222.410274)
		(width 0.14478)
		(layer "In11.Cu")
		(net "M_L_CPU0_SA_DQ<22>")
	)
	(segment
		(start 403.788118 -232.040938)
		(end 403.624796 -232.20426)
		(width 0.14478)
		(layer "In11.Cu")
		(net "M_L_CPU0_SA_DQ<22>")
	)
	(segment
		(start 400.638264 -234.960414)
		(end 400.638518 -235.190538)
		(width 0.14478)
		(layer "In11.Cu")
		(net "M_L_CPU0_SA_DQ<22>")
	)
	(segment
		(start 404.077932 -231.313228)
		(end 403.8473 -231.313482)
		(width 0.14478)
		(layer "In11.Cu")
		(net "M_L_CPU0_SA_DQ<22>")
	)
	(segment
		(start 412.063184 -223.260158)
		(end 411.918404 -223.404938)
		(width 0.14478)
		(layer "In11.Cu")
		(net "M_L_CPU0_SA_DQ<22>")
	)
	(segment
		(start 388.206234 -238.486696)
		(end 388.197852 -238.491522)
		(width 0.0889)
		(layer "In11.Cu")
		(net "M_L_CPU0_SA_DQ<22>")
	)
	(segment
		(start 436.6133 -223.260158)
		(end 434.040788 -223.260158)
		(width 0.14478)
		(layer "In11.Cu")
		(net "M_L_CPU0_SA_DQ<22>")
	)
	(segment
		(start 399.353532 -236.037628)
		(end 399.1229 -236.037882)
		(width 0.14478)
		(layer "In11.Cu")
		(net "M_L_CPU0_SA_DQ<22>")
	)
	(segment
		(start 400.534632 -234.856782)
		(end 400.638264 -234.960414)
		(width 0.14478)
		(layer "In11.Cu")
		(net "M_L_CPU0_SA_DQ<22>")
	)
	(segment
		(start 400.534632 -234.62615)
		(end 400.534632 -234.856782)
		(width 0.14478)
		(layer "In11.Cu")
		(net "M_L_CPU0_SA_DQ<22>")
	)
	(segment
		(start 448.083686 -222.410274)
		(end 445.052704 -222.410274)
		(width 0.14478)
		(layer "In11.Cu")
		(net "M_L_CPU0_SA_DQ<22>")
	)
	(segment
		(start 402.213064 -233.385614)
		(end 402.213318 -233.615738)
		(width 0.14478)
		(layer "In11.Cu")
		(net "M_L_CPU0_SA_DQ<22>")
	)
	(segment
		(start 429.005492 -223.260158)
		(end 426.762418 -223.260158)
		(width 0.14478)
		(layer "In11.Cu")
		(net "M_L_CPU0_SA_DQ<22>")
	)
	(segment
		(start 401.425664 -234.173014)
		(end 401.425918 -234.403138)
		(width 0.14478)
		(layer "In11.Cu")
		(net "M_L_CPU0_SA_DQ<22>")
	)
	(segment
		(start 403.000464 -232.598214)
		(end 403.000718 -232.828338)
		(width 0.14478)
		(layer "In11.Cu")
		(net "M_L_CPU0_SA_DQ<22>")
	)
	(segment
		(start 450.088 -222.834962)
		(end 449.663312 -222.410274)
		(width 0.14478)
		(layer "In11.Cu")
		(net "M_L_CPU0_SA_DQ<22>")
	)
	(segment
		(start 404.471632 -230.919782)
		(end 404.575264 -231.023414)
		(width 0.14478)
		(layer "In11.Cu")
		(net "M_L_CPU0_SA_DQ<22>")
	)
	(segment
		(start 391.970768 -238.483902)
		(end 391.957052 -238.491776)
		(width 0.0889)
		(layer "In11.Cu")
		(net "M_L_CPU0_SA_DQ<22>")
	)
	(segment
		(start 400.244564 -235.35386)
		(end 400.140932 -235.250228)
		(width 0.14478)
		(layer "In11.Cu")
		(net "M_L_CPU0_SA_DQ<22>")
	)
	(segment
		(start 402.109432 -233.281982)
		(end 402.213064 -233.385614)
		(width 0.14478)
		(layer "In11.Cu")
		(net "M_L_CPU0_SA_DQ<22>")
	)
	(segment
		(start 405.259032 -230.132382)
		(end 405.362664 -230.236014)
		(width 0.14478)
		(layer "In11.Cu")
		(net "M_L_CPU0_SA_DQ<22>")
	)
	(segment
		(start 390.451848 -238.491522)
		(end 390.443466 -238.486696)
		(width 0.0889)
		(layer "In11.Cu")
		(net "M_L_CPU0_SA_DQ<22>")
	)
	(segment
		(start 400.475196 -235.35386)
		(end 400.244564 -235.35386)
		(width 0.14478)
		(layer "In11.Cu")
		(net "M_L_CPU0_SA_DQ<22>")
	)
	(segment
		(start 404.6347 -230.526082)
		(end 404.471632 -230.68915)
		(width 0.14478)
		(layer "In11.Cu")
		(net "M_L_CPU0_SA_DQ<22>")
	)
	(segment
		(start 444.20282 -223.260158)
		(end 441.387992 -223.260158)
		(width 0.14478)
		(layer "In11.Cu")
		(net "M_L_CPU0_SA_DQ<22>")
	)
	(segment
		(start 413.88792 -223.260158)
		(end 412.063184 -223.260158)
		(width 0.14478)
		(layer "In11.Cu")
		(net "M_L_CPU0_SA_DQ<22>")
	)
	(segment
		(start 440.538108 -222.410274)
		(end 437.463184 -222.410274)
		(width 0.14478)
		(layer "In11.Cu")
		(net "M_L_CPU0_SA_DQ<22>")
	)
	(segment
		(start 405.986996 -229.84206)
		(end 405.756364 -229.84206)
		(width 0.14478)
		(layer "In11.Cu")
		(net "M_L_CPU0_SA_DQ<22>")
	)
	(segment
		(start 399.063464 -236.535214)
		(end 399.063718 -236.765338)
		(width 0.14478)
		(layer "In11.Cu")
		(net "M_L_CPU0_SA_DQ<22>")
	)
	(segment
		(start 404.865332 -230.525828)
		(end 404.6347 -230.526082)
		(width 0.14478)
		(layer "In11.Cu")
		(net "M_L_CPU0_SA_DQ<22>")
	)
	(segment
		(start 411.918404 -223.910652)
		(end 405.986996 -229.84206)
		(width 0.14478)
		(layer "In11.Cu")
		(net "M_L_CPU0_SA_DQ<22>")
	)
	(segment
		(start 391.957052 -238.491776)
		(end 391.945114 -238.498634)
		(width 0.0889)
		(layer "In11.Cu")
		(net "M_L_CPU0_SA_DQ<22>")
	)
	(segment
		(start 404.575518 -231.253538)
		(end 404.412196 -231.41686)
		(width 0.14478)
		(layer "In11.Cu")
		(net "M_L_CPU0_SA_DQ<22>")
	)
	(segment
		(start 391.026142 -238.486696)
		(end 391.01776 -238.491522)
		(width 0.0889)
		(layer "In11.Cu")
		(net "M_L_CPU0_SA_DQ<22>")
	)
	(segment
		(start 405.362664 -230.236014)
		(end 405.362918 -230.466138)
		(width 0.14478)
		(layer "In11.Cu")
		(net "M_L_CPU0_SA_DQ<22>")
	)
	(segment
		(start 448.373246 -222.028512)
		(end 448.228466 -222.173292)
		(width 0.14478)
		(layer "In11.Cu")
		(net "M_L_CPU0_SA_DQ<22>")
	)
	(segment
		(start 434.040788 -223.260158)
		(end 433.190904 -222.410274)
		(width 0.14478)
		(layer "In11.Cu")
		(net "M_L_CPU0_SA_DQ<22>")
	)
	(segment
		(start 405.652732 -229.738428)
		(end 405.4221 -229.738682)
		(width 0.14478)
		(layer "In11.Cu")
		(net "M_L_CPU0_SA_DQ<22>")
	)
	(segment
		(start 402.213318 -233.615738)
		(end 402.049996 -233.77906)
		(width 0.14478)
		(layer "In11.Cu")
		(net "M_L_CPU0_SA_DQ<22>")
	)
	(segment
		(start 400.6977 -234.463082)
		(end 400.534632 -234.62615)
		(width 0.14478)
		(layer "In11.Cu")
		(net "M_L_CPU0_SA_DQ<22>")
	)
	(segment
		(start 394.974318 -237.888272)
		(end 394.420598 -237.888272)
		(width 0.0889)
		(layer "In11.Cu")
		(net "M_L_CPU0_SA_DQ<22>")
	)
	(segment
		(start 399.9103 -235.250482)
		(end 399.747232 -235.41355)
		(width 0.14478)
		(layer "In11.Cu")
		(net "M_L_CPU0_SA_DQ<22>")
	)
	(segment
		(start 401.425918 -234.403138)
		(end 401.262596 -234.56646)
		(width 0.14478)
		(layer "In11.Cu")
		(net "M_L_CPU0_SA_DQ<22>")
	)
	(segment
		(start 399.457164 -236.14126)
		(end 399.353532 -236.037628)
		(width 0.14478)
		(layer "In11.Cu")
		(net "M_L_CPU0_SA_DQ<22>")
	)
	(segment
		(start 400.140932 -235.250228)
		(end 399.9103 -235.250482)
		(width 0.14478)
		(layer "In11.Cu")
		(net "M_L_CPU0_SA_DQ<22>")
	)
	(segment
		(start 448.228466 -222.173292)
		(end 448.228466 -222.265494)
		(width 0.14478)
		(layer "In11.Cu")
		(net "M_L_CPU0_SA_DQ<22>")
	)
	(segment
		(start 401.715732 -233.675428)
		(end 401.4851 -233.675682)
		(width 0.14478)
		(layer "In11.Cu")
		(net "M_L_CPU0_SA_DQ<22>")
	)
	(segment
		(start 401.031964 -234.56646)
		(end 400.928332 -234.462828)
		(width 0.14478)
		(layer "In11.Cu")
		(net "M_L_CPU0_SA_DQ<22>")
	)
	(segment
		(start 405.4221 -229.738682)
		(end 405.259032 -229.90175)
		(width 0.14478)
		(layer "In11.Cu")
		(net "M_L_CPU0_SA_DQ<22>")
	)
	(segment
		(start 403.290532 -232.100628)
		(end 403.0599 -232.100882)
		(width 0.14478)
		(layer "In11.Cu")
		(net "M_L_CPU0_SA_DQ<22>")
	)
	(segment
		(start 400.638518 -235.190538)
		(end 400.475196 -235.35386)
		(width 0.14478)
		(layer "In11.Cu")
		(net "M_L_CPU0_SA_DQ<22>")
	)
	(segment
		(start 448.63512 -222.028512)
		(end 448.373246 -222.028512)
		(width 0.14478)
		(layer "In11.Cu")
		(net "M_L_CPU0_SA_DQ<22>")
	)
	(segment
		(start 445.052704 -222.410274)
		(end 444.20282 -223.260158)
		(width 0.14478)
		(layer "In11.Cu")
		(net "M_L_CPU0_SA_DQ<22>")
	)
	(segment
		(start 403.8473 -231.313482)
		(end 403.684232 -231.47655)
		(width 0.14478)
		(layer "In11.Cu")
		(net "M_L_CPU0_SA_DQ<22>")
	)
	(segment
		(start 395.87551 -236.98708)
		(end 394.974318 -237.888272)
		(width 0.0889)
		(layer "In11.Cu")
		(net "M_L_CPU0_SA_DQ<22>")
	)
	(segment
		(start 429.855376 -222.410274)
		(end 429.005492 -223.260158)
		(width 0.14478)
		(layer "In11.Cu")
		(net "M_L_CPU0_SA_DQ<22>")
	)
	(segment
		(start 403.684232 -231.707182)
		(end 403.787864 -231.810814)
		(width 0.14478)
		(layer "In11.Cu")
		(net "M_L_CPU0_SA_DQ<22>")
	)
	(segment
		(start 398.959832 -236.431582)
		(end 399.063464 -236.535214)
		(width 0.14478)
		(layer "In11.Cu")
		(net "M_L_CPU0_SA_DQ<22>")
	)
	(segment
		(start 404.412196 -231.41686)
		(end 404.181564 -231.41686)
		(width 0.14478)
		(layer "In11.Cu")
		(net "M_L_CPU0_SA_DQ<22>")
	)
	(segment
		(start 405.756364 -229.84206)
		(end 405.652732 -229.738428)
		(width 0.14478)
		(layer "In11.Cu")
		(net "M_L_CPU0_SA_DQ<22>")
	)
	(segment
		(start 398.566132 -236.825028)
		(end 398.3355 -236.825282)
		(width 0.14478)
		(layer "In11.Cu")
		(net "M_L_CPU0_SA_DQ<22>")
	)
	(segment
		(start 418.225986 -222.41002)
		(end 414.738058 -222.41002)
		(width 0.14478)
		(layer "In11.Cu")
		(net "M_L_CPU0_SA_DQ<22>")
	)
	(segment
		(start 400.928332 -234.462828)
		(end 400.6977 -234.463082)
		(width 0.14478)
		(layer "In11.Cu")
		(net "M_L_CPU0_SA_DQ<22>")
	)
	(segment
		(start 399.850864 -235.747814)
		(end 399.851118 -235.977938)
		(width 0.14478)
		(layer "In11.Cu")
		(net "M_L_CPU0_SA_DQ<22>")
	)
	(segment
		(start 402.2725 -232.888282)
		(end 402.109432 -233.05135)
		(width 0.14478)
		(layer "In11.Cu")
		(net "M_L_CPU0_SA_DQ<22>")
	)
	(segment
		(start 426.762418 -223.260158)
		(end 425.912534 -222.410274)
		(width 0.14478)
		(layer "In11.Cu")
		(net "M_L_CPU0_SA_DQ<22>")
	)
	(segment
		(start 405.362918 -230.466138)
		(end 405.199596 -230.62946)
		(width 0.14478)
		(layer "In11.Cu")
		(net "M_L_CPU0_SA_DQ<22>")
	)
	(segment
		(start 399.851118 -235.977938)
		(end 399.687796 -236.14126)
		(width 0.14478)
		(layer "In11.Cu")
		(net "M_L_CPU0_SA_DQ<22>")
	)
	(segment
		(start 403.000718 -232.828338)
		(end 402.837396 -232.99166)
		(width 0.14478)
		(layer "In11.Cu")
		(net "M_L_CPU0_SA_DQ<22>")
	)
	(arc
		(start 389.511794 -238.491522)
		(mid 389.32485 -238.441267)
		(end 389.137906 -238.491522)
		(width 0.0889)
		(layer "In11.Cu")
		(net "M_L_CPU0_SA_DQ<22>")
	)
	(arc
		(start 388.571994 -238.491522)
		(mid 388.389743 -238.441172)
		(end 388.206234 -238.486696)
		(width 0.0889)
		(layer "In11.Cu")
		(net "M_L_CPU0_SA_DQ<22>")
	)
	(arc
		(start 388.197852 -238.491522)
		(mid 387.914896 -238.567699)
		(end 387.63194 -238.491522)
		(width 0.0889)
		(layer "In11.Cu")
		(net "M_L_CPU0_SA_DQ<22>")
	)
	(arc
		(start 392.89736 -238.491522)
		(mid 392.624416 -238.568102)
		(end 392.34872 -238.50219)
		(width 0.0889)
		(layer "In11.Cu")
		(net "M_L_CPU0_SA_DQ<22>")
	)
	(arc
		(start 390.077706 -238.491522)
		(mid 389.79475 -238.567699)
		(end 389.511794 -238.491522)
		(width 0.0889)
		(layer "In11.Cu")
		(net "M_L_CPU0_SA_DQ<22>")
	)
	(arc
		(start 391.01776 -238.491522)
		(mid 390.734804 -238.567699)
		(end 390.451848 -238.491522)
		(width 0.0889)
		(layer "In11.Cu")
		(net "M_L_CPU0_SA_DQ<22>")
	)
	(arc
		(start 391.391902 -238.491522)
		(mid 391.209651 -238.441172)
		(end 391.026142 -238.486696)
		(width 0.0889)
		(layer "In11.Cu")
		(net "M_L_CPU0_SA_DQ<22>")
	)
	(arc
		(start 390.443466 -238.486696)
		(mid 390.259958 -238.441202)
		(end 390.077706 -238.491522)
		(width 0.0889)
		(layer "In11.Cu")
		(net "M_L_CPU0_SA_DQ<22>")
	)
	(arc
		(start 387.63194 -238.491522)
		(mid 387.475502 -238.442551)
		(end 387.31317 -238.46536)
		(width 0.0889)
		(layer "In11.Cu")
		(net "M_L_CPU0_SA_DQ<22>")
	)
	(arc
		(start 393.084812 -238.440722)
		(mid 392.987723 -238.453712)
		(end 392.89736 -238.491522)
		(width 0.0889)
		(layer "In11.Cu")
		(net "M_L_CPU0_SA_DQ<22>")
	)
	(arc
		(start 391.945114 -238.498634)
		(mid 391.66758 -238.567615)
		(end 391.391902 -238.491522)
		(width 0.0889)
		(layer "In11.Cu")
		(net "M_L_CPU0_SA_DQ<22>")
	)
	(arc
		(start 389.137906 -238.491522)
		(mid 388.85495 -238.567699)
		(end 388.571994 -238.491522)
		(width 0.0889)
		(layer "In11.Cu")
		(net "M_L_CPU0_SA_DQ<22>")
	)
	(arc
		(start 392.330686 -238.491522)
		(mid 392.151699 -238.441352)
		(end 391.970768 -238.483902)
		(width 0.0889)
		(layer "In11.Cu")
		(net "M_L_CPU0_SA_DQ<22>")
	)
	(segment
		(start 385.098036 -239.08004)
		(end 385.564888 -238.814102)
		(width 0.10668)
		(layer "F.Cu")
		(net "M_L_CPU0_SA_DQ<21>")
	)
	(segment
		(start 385.564888 -238.814102)
		(end 385.718812 -239.079532)
		(width 0.0889)
		(layer "In11.Cu")
		(net "M_L_CPU0_SA_DQ<21>")
	)
	(segment
		(start 395.192758 -238.320072)
		(end 395.192758 -238.096552)
		(width 0.0889)
		(layer "In11.Cu")
		(net "M_L_CPU0_SA_DQ<21>")
	)
	(segment
		(start 433.190904 -223.260158)
		(end 434.040788 -224.110042)
		(width 0.14478)
		(layer "In11.Cu")
		(net "M_L_CPU0_SA_DQ<21>")
	)
	(segment
		(start 391.01776 -239.136682)
		(end 391.026142 -239.141508)
		(width 0.0889)
		(layer "In11.Cu")
		(net "M_L_CPU0_SA_DQ<21>")
	)
	(segment
		(start 437.463184 -223.260158)
		(end 440.602116 -223.260158)
		(width 0.14478)
		(layer "In11.Cu")
		(net "M_L_CPU0_SA_DQ<21>")
	)
	(segment
		(start 387.257798 -239.136682)
		(end 387.26618 -239.141508)
		(width 0.0889)
		(layer "In11.Cu")
		(net "M_L_CPU0_SA_DQ<21>")
	)
	(segment
		(start 388.197852 -239.136682)
		(end 388.206234 -239.141508)
		(width 0.0889)
		(layer "In11.Cu")
		(net "M_L_CPU0_SA_DQ<21>")
	)
	(segment
		(start 393.348464 -239.078008)
		(end 393.78128 -238.645192)
		(width 0.0889)
		(layer "In11.Cu")
		(net "M_L_CPU0_SA_DQ<21>")
	)
	(segment
		(start 395.192758 -238.096552)
		(end 395.84757 -237.44174)
		(width 0.0889)
		(layer "In11.Cu")
		(net "M_L_CPU0_SA_DQ<21>")
	)
	(segment
		(start 396.02537 -237.44174)
		(end 399.076926 -237.44174)
		(width 0.14478)
		(layer "In11.Cu")
		(net "M_L_CPU0_SA_DQ<21>")
	)
	(segment
		(start 436.6133 -224.110042)
		(end 437.463184 -223.260158)
		(width 0.14478)
		(layer "In11.Cu")
		(net "M_L_CPU0_SA_DQ<21>")
	)
	(segment
		(start 441.45073 -224.108772)
		(end 444.063882 -224.108772)
		(width 0.14478)
		(layer "In11.Cu")
		(net "M_L_CPU0_SA_DQ<21>")
	)
	(segment
		(start 444.912496 -223.260158)
		(end 453.763126 -223.260158)
		(width 0.14478)
		(layer "In11.Cu")
		(net "M_L_CPU0_SA_DQ<21>")
	)
	(segment
		(start 428.941992 -224.110042)
		(end 429.791876 -223.260158)
		(width 0.14478)
		(layer "In11.Cu")
		(net "M_L_CPU0_SA_DQ<21>")
	)
	(segment
		(start 434.040788 -224.110042)
		(end 436.6133 -224.110042)
		(width 0.14478)
		(layer "In11.Cu")
		(net "M_L_CPU0_SA_DQ<21>")
	)
	(segment
		(start 429.791876 -223.260158)
		(end 433.190904 -223.260158)
		(width 0.14478)
		(layer "In11.Cu")
		(net "M_L_CPU0_SA_DQ<21>")
	)
	(segment
		(start 390.443466 -239.141508)
		(end 390.451848 -239.136682)
		(width 0.0889)
		(layer "In11.Cu")
		(net "M_L_CPU0_SA_DQ<21>")
	)
	(segment
		(start 421.45966 -224.110042)
		(end 422.309544 -223.260158)
		(width 0.14478)
		(layer "In11.Cu")
		(net "M_L_CPU0_SA_DQ<21>")
	)
	(segment
		(start 422.309544 -223.260158)
		(end 425.912534 -223.260158)
		(width 0.14478)
		(layer "In11.Cu")
		(net "M_L_CPU0_SA_DQ<21>")
	)
	(segment
		(start 386.683504 -239.141508)
		(end 386.691886 -239.136682)
		(width 0.0889)
		(layer "In11.Cu")
		(net "M_L_CPU0_SA_DQ<21>")
	)
	(segment
		(start 444.063882 -224.108772)
		(end 444.912496 -223.260158)
		(width 0.14478)
		(layer "In11.Cu")
		(net "M_L_CPU0_SA_DQ<21>")
	)
	(segment
		(start 425.912534 -223.260158)
		(end 426.762418 -224.110042)
		(width 0.14478)
		(layer "In11.Cu")
		(net "M_L_CPU0_SA_DQ<21>")
	)
	(segment
		(start 453.763126 -223.260158)
		(end 454.188068 -223.6851)
		(width 0.14478)
		(layer "In11.Cu")
		(net "M_L_CPU0_SA_DQ<21>")
	)
	(segment
		(start 394.867638 -238.645192)
		(end 395.192758 -238.320072)
		(width 0.0889)
		(layer "In11.Cu")
		(net "M_L_CPU0_SA_DQ<21>")
	)
	(segment
		(start 399.076926 -237.44174)
		(end 412.408624 -224.110042)
		(width 0.14478)
		(layer "In11.Cu")
		(net "M_L_CPU0_SA_DQ<21>")
	)
	(segment
		(start 412.408624 -224.110042)
		(end 413.685482 -224.110042)
		(width 0.14478)
		(layer "In11.Cu")
		(net "M_L_CPU0_SA_DQ<21>")
	)
	(segment
		(start 418.331396 -223.260158)
		(end 419.18128 -224.110042)
		(width 0.14478)
		(layer "In11.Cu")
		(net "M_L_CPU0_SA_DQ<21>")
	)
	(segment
		(start 393.78128 -238.645192)
		(end 394.867638 -238.645192)
		(width 0.0889)
		(layer "In11.Cu")
		(net "M_L_CPU0_SA_DQ<21>")
	)
	(segment
		(start 413.685482 -224.110042)
		(end 414.535366 -223.260158)
		(width 0.14478)
		(layer "In11.Cu")
		(net "M_L_CPU0_SA_DQ<21>")
	)
	(segment
		(start 395.84757 -237.44174)
		(end 396.02537 -237.44174)
		(width 0.0889)
		(layer "In11.Cu")
		(net "M_L_CPU0_SA_DQ<21>")
	)
	(segment
		(start 414.535366 -223.260158)
		(end 418.331396 -223.260158)
		(width 0.14478)
		(layer "In11.Cu")
		(net "M_L_CPU0_SA_DQ<21>")
	)
	(segment
		(start 391.391902 -239.136682)
		(end 391.402316 -239.130586)
		(width 0.0889)
		(layer "In11.Cu")
		(net "M_L_CPU0_SA_DQ<21>")
	)
	(segment
		(start 392.887454 -239.130586)
		(end 392.90625 -239.141508)
		(width 0.0889)
		(layer "In11.Cu")
		(net "M_L_CPU0_SA_DQ<21>")
	)
	(segment
		(start 392.323828 -239.141508)
		(end 392.33221 -239.136682)
		(width 0.0889)
		(layer "In11.Cu")
		(net "M_L_CPU0_SA_DQ<21>")
	)
	(segment
		(start 440.602116 -223.260158)
		(end 441.45073 -224.108772)
		(width 0.14478)
		(layer "In11.Cu")
		(net "M_L_CPU0_SA_DQ<21>")
	)
	(segment
		(start 426.762418 -224.110042)
		(end 428.941992 -224.110042)
		(width 0.14478)
		(layer "In11.Cu")
		(net "M_L_CPU0_SA_DQ<21>")
	)
	(segment
		(start 419.18128 -224.110042)
		(end 421.45966 -224.110042)
		(width 0.14478)
		(layer "In11.Cu")
		(net "M_L_CPU0_SA_DQ<21>")
	)
	(segment
		(start 385.718812 -239.079532)
		(end 385.814824 -239.104932)
		(width 0.0889)
		(layer "In11.Cu")
		(net "M_L_CPU0_SA_DQ<21>")
	)
	(arc
		(start 392.33221 -239.136682)
		(mid 392.609023 -239.060539)
		(end 392.887454 -239.130586)
		(width 0.0889)
		(layer "In11.Cu")
		(net "M_L_CPU0_SA_DQ<21>")
	)
	(arc
		(start 385.814824 -239.104932)
		(mid 386.070032 -239.061455)
		(end 386.317744 -239.136682)
		(width 0.0889)
		(layer "In11.Cu")
		(net "M_L_CPU0_SA_DQ<21>")
	)
	(arc
		(start 386.691886 -239.136682)
		(mid 386.974842 -239.060505)
		(end 387.257798 -239.136682)
		(width 0.0889)
		(layer "In11.Cu")
		(net "M_L_CPU0_SA_DQ<21>")
	)
	(arc
		(start 388.571994 -239.136682)
		(mid 388.85495 -239.060505)
		(end 389.137906 -239.136682)
		(width 0.0889)
		(layer "In11.Cu")
		(net "M_L_CPU0_SA_DQ<21>")
	)
	(arc
		(start 391.958068 -239.136682)
		(mid 392.140319 -239.187032)
		(end 392.323828 -239.141508)
		(width 0.0889)
		(layer "In11.Cu")
		(net "M_L_CPU0_SA_DQ<21>")
	)
	(arc
		(start 386.317744 -239.136682)
		(mid 386.499995 -239.187032)
		(end 386.683504 -239.141508)
		(width 0.0889)
		(layer "In11.Cu")
		(net "M_L_CPU0_SA_DQ<21>")
	)
	(arc
		(start 389.511794 -239.136682)
		(mid 389.79475 -239.060505)
		(end 390.077706 -239.136682)
		(width 0.0889)
		(layer "In11.Cu")
		(net "M_L_CPU0_SA_DQ<21>")
	)
	(arc
		(start 388.206234 -239.141508)
		(mid 388.389742 -239.187002)
		(end 388.571994 -239.136682)
		(width 0.0889)
		(layer "In11.Cu")
		(net "M_L_CPU0_SA_DQ<21>")
	)
	(arc
		(start 391.026142 -239.141508)
		(mid 391.20965 -239.187002)
		(end 391.391902 -239.136682)
		(width 0.0889)
		(layer "In11.Cu")
		(net "M_L_CPU0_SA_DQ<21>")
	)
	(arc
		(start 391.402316 -239.130586)
		(mid 391.681002 -239.060366)
		(end 391.958068 -239.136682)
		(width 0.0889)
		(layer "In11.Cu")
		(net "M_L_CPU0_SA_DQ<21>")
	)
	(arc
		(start 392.90625 -239.141508)
		(mid 393.137891 -239.183238)
		(end 393.348464 -239.078008)
		(width 0.0889)
		(layer "In11.Cu")
		(net "M_L_CPU0_SA_DQ<21>")
	)
	(arc
		(start 390.451848 -239.136682)
		(mid 390.734804 -239.060505)
		(end 391.01776 -239.136682)
		(width 0.0889)
		(layer "In11.Cu")
		(net "M_L_CPU0_SA_DQ<21>")
	)
	(arc
		(start 389.137906 -239.136682)
		(mid 389.32485 -239.186937)
		(end 389.511794 -239.136682)
		(width 0.0889)
		(layer "In11.Cu")
		(net "M_L_CPU0_SA_DQ<21>")
	)
	(arc
		(start 390.077706 -239.136682)
		(mid 390.259957 -239.187032)
		(end 390.443466 -239.141508)
		(width 0.0889)
		(layer "In11.Cu")
		(net "M_L_CPU0_SA_DQ<21>")
	)
	(arc
		(start 387.63194 -239.136682)
		(mid 387.914896 -239.060505)
		(end 388.197852 -239.136682)
		(width 0.0889)
		(layer "In11.Cu")
		(net "M_L_CPU0_SA_DQ<21>")
	)
	(arc
		(start 387.26618 -239.141508)
		(mid 387.449688 -239.187002)
		(end 387.63194 -239.136682)
		(width 0.0889)
		(layer "In11.Cu")
		(net "M_L_CPU0_SA_DQ<21>")
	)
	(segment
		(start 386.50799 -238.270034)
		(end 386.974842 -238.004096)
		(width 0.10668)
		(layer "F.Cu")
		(net "M_L_CPU0_SA_DQ<20>")
	)
	(segment
		(start 426.660564 -222.419418)
		(end 429.152558 -222.419418)
		(width 0.14478)
		(layer "In11.Cu")
		(net "M_L_CPU0_SA_DQ<20>")
	)
	(segment
		(start 452.513446 -221.723204)
		(end 452.513446 -222.306642)
		(width 0.14478)
		(layer "In11.Cu")
		(net "M_L_CPU0_SA_DQ<20>")
	)
	(segment
		(start 452.513446 -222.306642)
		(end 452.676514 -222.46971)
		(width 0.14478)
		(layer "In11.Cu")
		(net "M_L_CPU0_SA_DQ<20>")
	)
	(segment
		(start 453.06996 -222.306642)
		(end 453.06996 -221.723204)
		(width 0.14478)
		(layer "In11.Cu")
		(net "M_L_CPU0_SA_DQ<20>")
	)
	(segment
		(start 453.06996 -221.723204)
		(end 453.233028 -221.560136)
		(width 0.14478)
		(layer "In11.Cu")
		(net "M_L_CPU0_SA_DQ<20>")
	)
	(segment
		(start 391.845292 -238.33582)
		(end 391.861548 -238.326422)
		(width 0.0889)
		(layer "In11.Cu")
		(net "M_L_CPU0_SA_DQ<20>")
	)
	(segment
		(start 393.710668 -238.250222)
		(end 394.273278 -237.687612)
		(width 0.0889)
		(layer "In11.Cu")
		(net "M_L_CPU0_SA_DQ<20>")
	)
	(segment
		(start 441.40247 -222.419418)
		(end 444.288926 -222.419418)
		(width 0.14478)
		(layer "In11.Cu")
		(net "M_L_CPU0_SA_DQ<20>")
	)
	(segment
		(start 413.652716 -222.782892)
		(end 414.658556 -221.777052)
		(width 0.14478)
		(layer "In11.Cu")
		(net "M_L_CPU0_SA_DQ<20>")
	)
	(segment
		(start 433.200302 -221.569534)
		(end 434.050186 -222.419418)
		(width 0.14478)
		(layer "In11.Cu")
		(net "M_L_CPU0_SA_DQ<20>")
	)
	(segment
		(start 437.453786 -221.569534)
		(end 440.552586 -221.569534)
		(width 0.14478)
		(layer "In11.Cu")
		(net "M_L_CPU0_SA_DQ<20>")
	)
	(segment
		(start 422.381934 -221.569534)
		(end 425.81068 -221.569534)
		(width 0.14478)
		(layer "In11.Cu")
		(net "M_L_CPU0_SA_DQ<20>")
	)
	(segment
		(start 453.763126 -221.560136)
		(end 454.188068 -221.985078)
		(width 0.14478)
		(layer "In11.Cu")
		(net "M_L_CPU0_SA_DQ<20>")
	)
	(segment
		(start 429.152558 -222.419418)
		(end 430.002442 -221.569534)
		(width 0.14478)
		(layer "In11.Cu")
		(net "M_L_CPU0_SA_DQ<20>")
	)
	(segment
		(start 418.963856 -222.419418)
		(end 421.53205 -222.419418)
		(width 0.14478)
		(layer "In11.Cu")
		(net "M_L_CPU0_SA_DQ<20>")
	)
	(segment
		(start 389.607806 -238.326676)
		(end 389.616188 -238.331502)
		(width 0.0889)
		(layer "In11.Cu")
		(net "M_L_CPU0_SA_DQ<20>")
	)
	(segment
		(start 444.288926 -222.419418)
		(end 445.13881 -221.569534)
		(width 0.14478)
		(layer "In11.Cu")
		(net "M_L_CPU0_SA_DQ<20>")
	)
	(segment
		(start 397.985234 -236.53242)
		(end 405.816562 -228.701092)
		(width 0.14478)
		(layer "In11.Cu")
		(net "M_L_CPU0_SA_DQ<20>")
	)
	(segment
		(start 394.273278 -237.687612)
		(end 394.748258 -237.687612)
		(width 0.0889)
		(layer "In11.Cu")
		(net "M_L_CPU0_SA_DQ<20>")
	)
	(segment
		(start 425.81068 -221.569534)
		(end 426.660564 -222.419418)
		(width 0.14478)
		(layer "In11.Cu")
		(net "M_L_CPU0_SA_DQ<20>")
	)
	(segment
		(start 453.233028 -221.560136)
		(end 453.763126 -221.560136)
		(width 0.14478)
		(layer "In11.Cu")
		(net "M_L_CPU0_SA_DQ<20>")
	)
	(segment
		(start 411.734762 -222.782892)
		(end 413.652716 -222.782892)
		(width 0.14478)
		(layer "In11.Cu")
		(net "M_L_CPU0_SA_DQ<20>")
	)
	(segment
		(start 411.466538 -223.051116)
		(end 411.734762 -222.782892)
		(width 0.14478)
		(layer "In11.Cu")
		(net "M_L_CPU0_SA_DQ<20>")
	)
	(segment
		(start 421.53205 -222.419418)
		(end 422.381934 -221.569534)
		(width 0.14478)
		(layer "In11.Cu")
		(net "M_L_CPU0_SA_DQ<20>")
	)
	(segment
		(start 434.050186 -222.419418)
		(end 436.603902 -222.419418)
		(width 0.14478)
		(layer "In11.Cu")
		(net "M_L_CPU0_SA_DQ<20>")
	)
	(segment
		(start 394.748258 -237.687612)
		(end 395.90345 -236.53242)
		(width 0.0889)
		(layer "In11.Cu")
		(net "M_L_CPU0_SA_DQ<20>")
	)
	(segment
		(start 440.552586 -221.569534)
		(end 441.40247 -222.419418)
		(width 0.14478)
		(layer "In11.Cu")
		(net "M_L_CPU0_SA_DQ<20>")
	)
	(segment
		(start 414.658556 -221.777052)
		(end 418.32149 -221.777052)
		(width 0.14478)
		(layer "In11.Cu")
		(net "M_L_CPU0_SA_DQ<20>")
	)
	(segment
		(start 392.426698 -238.326676)
		(end 392.438382 -238.333534)
		(width 0.0889)
		(layer "In11.Cu")
		(net "M_L_CPU0_SA_DQ<20>")
	)
	(segment
		(start 452.676514 -222.46971)
		(end 452.906892 -222.46971)
		(width 0.14478)
		(layer "In11.Cu")
		(net "M_L_CPU0_SA_DQ<20>")
	)
	(segment
		(start 406.429718 -228.701092)
		(end 411.466538 -223.664272)
		(width 0.14478)
		(layer "In11.Cu")
		(net "M_L_CPU0_SA_DQ<20>")
	)
	(segment
		(start 387.128766 -238.269526)
		(end 387.224778 -238.294926)
		(width 0.0889)
		(layer "In11.Cu")
		(net "M_L_CPU0_SA_DQ<20>")
	)
	(segment
		(start 395.90345 -236.53242)
		(end 396.047214 -236.53242)
		(width 0.0889)
		(layer "In11.Cu")
		(net "M_L_CPU0_SA_DQ<20>")
	)
	(segment
		(start 388.093458 -238.331502)
		(end 388.10184 -238.326676)
		(width 0.0889)
		(layer "In11.Cu")
		(net "M_L_CPU0_SA_DQ<20>")
	)
	(segment
		(start 411.466538 -223.664272)
		(end 411.466538 -223.051116)
		(width 0.14478)
		(layer "In11.Cu")
		(net "M_L_CPU0_SA_DQ<20>")
	)
	(segment
		(start 430.002442 -221.569534)
		(end 433.200302 -221.569534)
		(width 0.14478)
		(layer "In11.Cu")
		(net "M_L_CPU0_SA_DQ<20>")
	)
	(segment
		(start 386.974842 -238.004096)
		(end 387.128766 -238.269526)
		(width 0.0889)
		(layer "In11.Cu")
		(net "M_L_CPU0_SA_DQ<20>")
	)
	(segment
		(start 405.816562 -228.701092)
		(end 406.429718 -228.701092)
		(width 0.14478)
		(layer "In11.Cu")
		(net "M_L_CPU0_SA_DQ<20>")
	)
	(segment
		(start 393.084812 -238.250222)
		(end 393.710668 -238.250222)
		(width 0.0889)
		(layer "In11.Cu")
		(net "M_L_CPU0_SA_DQ<20>")
	)
	(segment
		(start 445.13881 -221.569534)
		(end 452.359776 -221.569534)
		(width 0.14478)
		(layer "In11.Cu")
		(net "M_L_CPU0_SA_DQ<20>")
	)
	(segment
		(start 389.033512 -238.331502)
		(end 389.041894 -238.326676)
		(width 0.0889)
		(layer "In11.Cu")
		(net "M_L_CPU0_SA_DQ<20>")
	)
	(segment
		(start 436.603902 -222.419418)
		(end 437.453786 -221.569534)
		(width 0.14478)
		(layer "In11.Cu")
		(net "M_L_CPU0_SA_DQ<20>")
	)
	(segment
		(start 418.32149 -221.777052)
		(end 418.963856 -222.419418)
		(width 0.14478)
		(layer "In11.Cu")
		(net "M_L_CPU0_SA_DQ<20>")
	)
	(segment
		(start 452.359776 -221.569534)
		(end 452.513446 -221.723204)
		(width 0.14478)
		(layer "In11.Cu")
		(net "M_L_CPU0_SA_DQ<20>")
	)
	(segment
		(start 396.047214 -236.53242)
		(end 397.985234 -236.53242)
		(width 0.14478)
		(layer "In11.Cu")
		(net "M_L_CPU0_SA_DQ<20>")
	)
	(segment
		(start 452.906892 -222.46971)
		(end 453.06996 -222.306642)
		(width 0.14478)
		(layer "In11.Cu")
		(net "M_L_CPU0_SA_DQ<20>")
	)
	(segment
		(start 391.861548 -238.326422)
		(end 391.873486 -238.319564)
		(width 0.0889)
		(layer "In11.Cu")
		(net "M_L_CPU0_SA_DQ<20>")
	)
	(arc
		(start 387.727698 -238.326676)
		(mid 387.909949 -238.377026)
		(end 388.093458 -238.331502)
		(width 0.0889)
		(layer "In11.Cu")
		(net "M_L_CPU0_SA_DQ<20>")
	)
	(arc
		(start 391.48766 -238.326676)
		(mid 391.66531 -238.376936)
		(end 391.845292 -238.33582)
		(width 0.0889)
		(layer "In11.Cu")
		(net "M_L_CPU0_SA_DQ<20>")
	)
	(arc
		(start 390.921748 -238.326676)
		(mid 391.204704 -238.250499)
		(end 391.48766 -238.326676)
		(width 0.0889)
		(layer "In11.Cu")
		(net "M_L_CPU0_SA_DQ<20>")
	)
	(arc
		(start 388.10184 -238.326676)
		(mid 388.384796 -238.250499)
		(end 388.667752 -238.326676)
		(width 0.0889)
		(layer "In11.Cu")
		(net "M_L_CPU0_SA_DQ<20>")
	)
	(arc
		(start 392.801094 -238.326676)
		(mid 392.937887 -238.269654)
		(end 393.084812 -238.250222)
		(width 0.0889)
		(layer "In11.Cu")
		(net "M_L_CPU0_SA_DQ<20>")
	)
	(arc
		(start 390.54786 -238.326676)
		(mid 390.734804 -238.376931)
		(end 390.921748 -238.326676)
		(width 0.0889)
		(layer "In11.Cu")
		(net "M_L_CPU0_SA_DQ<20>")
	)
	(arc
		(start 391.873486 -238.319564)
		(mid 392.15102 -238.250583)
		(end 392.426698 -238.326676)
		(width 0.0889)
		(layer "In11.Cu")
		(net "M_L_CPU0_SA_DQ<20>")
	)
	(arc
		(start 389.616188 -238.331502)
		(mid 389.799696 -238.376996)
		(end 389.981948 -238.326676)
		(width 0.0889)
		(layer "In11.Cu")
		(net "M_L_CPU0_SA_DQ<20>")
	)
	(arc
		(start 389.041894 -238.326676)
		(mid 389.32485 -238.250499)
		(end 389.607806 -238.326676)
		(width 0.0889)
		(layer "In11.Cu")
		(net "M_L_CPU0_SA_DQ<20>")
	)
	(arc
		(start 389.981948 -238.326676)
		(mid 390.264904 -238.250499)
		(end 390.54786 -238.326676)
		(width 0.0889)
		(layer "In11.Cu")
		(net "M_L_CPU0_SA_DQ<20>")
	)
	(arc
		(start 392.438382 -238.333534)
		(mid 392.620637 -238.377187)
		(end 392.801094 -238.326676)
		(width 0.0889)
		(layer "In11.Cu")
		(net "M_L_CPU0_SA_DQ<20>")
	)
	(arc
		(start 387.224778 -238.294926)
		(mid 387.479986 -238.251449)
		(end 387.727698 -238.326676)
		(width 0.0889)
		(layer "In11.Cu")
		(net "M_L_CPU0_SA_DQ<20>")
	)
	(arc
		(start 388.667752 -238.326676)
		(mid 388.850003 -238.377026)
		(end 389.033512 -238.331502)
		(width 0.0889)
		(layer "In11.Cu")
		(net "M_L_CPU0_SA_DQ<20>")
	)
	(segment
		(start 385.098036 -226.120198)
		(end 385.564888 -225.85426)
		(width 0.10668)
		(layer "F.Cu")
		(net "M_L_CPU0_SA_DQ<1>")
	)
	(segment
		(start 392.331702 -222.936816)
		(end 392.362182 -222.919036)
		(width 0.0889)
		(layer "In11.Cu")
		(net "M_L_CPU0_SA_DQ<1>")
	)
	(segment
		(start 392.29411 -222.95866)
		(end 392.331702 -222.936816)
		(width 0.0889)
		(layer "In11.Cu")
		(net "M_L_CPU0_SA_DQ<1>")
	)
	(segment
		(start 386.683504 -226.181666)
		(end 386.691886 -226.17684)
		(width 0.0889)
		(layer "In11.Cu")
		(net "M_L_CPU0_SA_DQ<1>")
	)
	(segment
		(start 393.0523 -217.15095)
		(end 404.989284 -205.213966)
		(width 0.14478)
		(layer "In11.Cu")
		(net "M_L_CPU0_SA_DQ<1>")
	)
	(segment
		(start 415.414714 -198.61022)
		(end 417.65093 -198.61022)
		(width 0.14478)
		(layer "In11.Cu")
		(net "M_L_CPU0_SA_DQ<1>")
	)
	(segment
		(start 393.0523 -221.8944)
		(end 393.0523 -221.153228)
		(width 0.0889)
		(layer "In11.Cu")
		(net "M_L_CPU0_SA_DQ<1>")
	)
	(segment
		(start 391.352786 -224.579688)
		(end 391.391902 -224.556828)
		(width 0.0889)
		(layer "In11.Cu")
		(net "M_L_CPU0_SA_DQ<1>")
	)
	(segment
		(start 390.921748 -225.366834)
		(end 390.953498 -225.348546)
		(width 0.0889)
		(layer "In11.Cu")
		(net "M_L_CPU0_SA_DQ<1>")
	)
	(segment
		(start 417.65093 -198.61022)
		(end 419.702742 -199.460104)
		(width 0.14478)
		(layer "In11.Cu")
		(net "M_L_CPU0_SA_DQ<1>")
	)
	(segment
		(start 392.900662 -222.046038)
		(end 393.0523 -221.8944)
		(width 0.0889)
		(layer "In11.Cu")
		(net "M_L_CPU0_SA_DQ<1>")
	)
	(segment
		(start 423.020236 -198.61022)
		(end 425.236386 -198.61022)
		(width 0.14478)
		(layer "In11.Cu")
		(net "M_L_CPU0_SA_DQ<1>")
	)
	(segment
		(start 434.72227 -199.460104)
		(end 436.066692 -199.460104)
		(width 0.14478)
		(layer "In11.Cu")
		(net "M_L_CPU0_SA_DQ<1>")
	)
	(segment
		(start 388.197852 -226.17684)
		(end 388.206234 -226.181666)
		(width 0.0889)
		(layer "In11.Cu")
		(net "M_L_CPU0_SA_DQ<1>")
	)
	(segment
		(start 441.75934 -199.460104)
		(end 443.989206 -199.460104)
		(width 0.14478)
		(layer "In11.Cu")
		(net "M_L_CPU0_SA_DQ<1>")
	)
	(segment
		(start 419.702742 -199.460104)
		(end 420.968424 -199.460104)
		(width 0.14478)
		(layer "In11.Cu")
		(net "M_L_CPU0_SA_DQ<1>")
	)
	(segment
		(start 393.0523 -221.153228)
		(end 393.0523 -217.15095)
		(width 0.14478)
		(layer "In11.Cu")
		(net "M_L_CPU0_SA_DQ<1>")
	)
	(segment
		(start 391.861802 -223.746822)
		(end 391.893552 -223.728534)
		(width 0.0889)
		(layer "In11.Cu")
		(net "M_L_CPU0_SA_DQ<1>")
	)
	(segment
		(start 409.834842 -199.460104)
		(end 413.362902 -199.460104)
		(width 0.14478)
		(layer "In11.Cu")
		(net "M_L_CPU0_SA_DQ<1>")
	)
	(segment
		(start 390.451848 -226.17684)
		(end 390.483598 -226.158552)
		(width 0.0889)
		(layer "In11.Cu")
		(net "M_L_CPU0_SA_DQ<1>")
	)
	(segment
		(start 432.670458 -198.61022)
		(end 434.72227 -199.460104)
		(width 0.14478)
		(layer "In11.Cu")
		(net "M_L_CPU0_SA_DQ<1>")
	)
	(segment
		(start 404.989284 -204.305662)
		(end 409.834842 -199.460104)
		(width 0.14478)
		(layer "In11.Cu")
		(net "M_L_CPU0_SA_DQ<1>")
	)
	(segment
		(start 425.236386 -198.61022)
		(end 427.288198 -199.460104)
		(width 0.14478)
		(layer "In11.Cu")
		(net "M_L_CPU0_SA_DQ<1>")
	)
	(segment
		(start 385.564888 -225.85426)
		(end 385.718812 -226.11969)
		(width 0.0889)
		(layer "In11.Cu")
		(net "M_L_CPU0_SA_DQ<1>")
	)
	(segment
		(start 430.43221 -198.61022)
		(end 432.670458 -198.61022)
		(width 0.14478)
		(layer "In11.Cu")
		(net "M_L_CPU0_SA_DQ<1>")
	)
	(segment
		(start 420.968424 -199.460104)
		(end 423.020236 -198.61022)
		(width 0.14478)
		(layer "In11.Cu")
		(net "M_L_CPU0_SA_DQ<1>")
	)
	(segment
		(start 385.718812 -226.11969)
		(end 385.814824 -226.14509)
		(width 0.0889)
		(layer "In11.Cu")
		(net "M_L_CPU0_SA_DQ<1>")
	)
	(segment
		(start 453.763126 -198.61022)
		(end 454.188068 -199.035162)
		(width 0.14478)
		(layer "In11.Cu")
		(net "M_L_CPU0_SA_DQ<1>")
	)
	(segment
		(start 428.380398 -199.460104)
		(end 430.43221 -198.61022)
		(width 0.14478)
		(layer "In11.Cu")
		(net "M_L_CPU0_SA_DQ<1>")
	)
	(segment
		(start 436.066692 -199.460104)
		(end 438.118504 -198.61022)
		(width 0.14478)
		(layer "In11.Cu")
		(net "M_L_CPU0_SA_DQ<1>")
	)
	(segment
		(start 427.288198 -199.460104)
		(end 428.380398 -199.460104)
		(width 0.14478)
		(layer "In11.Cu")
		(net "M_L_CPU0_SA_DQ<1>")
	)
	(segment
		(start 392.763756 -222.148654)
		(end 392.832336 -222.10903)
		(width 0.0889)
		(layer "In11.Cu")
		(net "M_L_CPU0_SA_DQ<1>")
	)
	(segment
		(start 440.909456 -198.61022)
		(end 441.75934 -199.460104)
		(width 0.14478)
		(layer "In11.Cu")
		(net "M_L_CPU0_SA_DQ<1>")
	)
	(segment
		(start 391.391902 -224.556828)
		(end 391.422382 -224.539048)
		(width 0.0889)
		(layer "In11.Cu")
		(net "M_L_CPU0_SA_DQ<1>")
	)
	(segment
		(start 413.362902 -199.460104)
		(end 415.414714 -198.61022)
		(width 0.14478)
		(layer "In11.Cu")
		(net "M_L_CPU0_SA_DQ<1>")
	)
	(segment
		(start 390.885426 -225.387916)
		(end 390.921748 -225.366834)
		(width 0.0889)
		(layer "In11.Cu")
		(net "M_L_CPU0_SA_DQ<1>")
	)
	(segment
		(start 438.118504 -198.61022)
		(end 440.909456 -198.61022)
		(width 0.14478)
		(layer "In11.Cu")
		(net "M_L_CPU0_SA_DQ<1>")
	)
	(segment
		(start 387.257798 -226.17684)
		(end 387.26618 -226.181666)
		(width 0.0889)
		(layer "In11.Cu")
		(net "M_L_CPU0_SA_DQ<1>")
	)
	(segment
		(start 391.823956 -223.768666)
		(end 391.861802 -223.746822)
		(width 0.0889)
		(layer "In11.Cu")
		(net "M_L_CPU0_SA_DQ<1>")
	)
	(segment
		(start 444.83909 -198.61022)
		(end 453.763126 -198.61022)
		(width 0.14478)
		(layer "In11.Cu")
		(net "M_L_CPU0_SA_DQ<1>")
	)
	(segment
		(start 404.989284 -205.213966)
		(end 404.989284 -204.305662)
		(width 0.14478)
		(layer "In11.Cu")
		(net "M_L_CPU0_SA_DQ<1>")
	)
	(segment
		(start 443.989206 -199.460104)
		(end 444.83909 -198.61022)
		(width 0.14478)
		(layer "In11.Cu")
		(net "M_L_CPU0_SA_DQ<1>")
	)
	(segment
		(start 390.443466 -226.181666)
		(end 390.451848 -226.17684)
		(width 0.0889)
		(layer "In11.Cu")
		(net "M_L_CPU0_SA_DQ<1>")
	)
	(arc
		(start 392.362182 -222.919036)
		(mid 392.477609 -222.78566)
		(end 392.519154 -222.614236)
		(width 0.0889)
		(layer "In11.Cu")
		(net "M_L_CPU0_SA_DQ<1>")
	)
	(arc
		(start 388.571994 -226.17684)
		(mid 388.85495 -226.100663)
		(end 389.137906 -226.17684)
		(width 0.0889)
		(layer "In11.Cu")
		(net "M_L_CPU0_SA_DQ<1>")
	)
	(arc
		(start 389.511794 -226.17684)
		(mid 389.79475 -226.100663)
		(end 390.077706 -226.17684)
		(width 0.0889)
		(layer "In11.Cu")
		(net "M_L_CPU0_SA_DQ<1>")
	)
	(arc
		(start 391.109454 -225.044254)
		(mid 391.173969 -224.782035)
		(end 391.352786 -224.579688)
		(width 0.0889)
		(layer "In11.Cu")
		(net "M_L_CPU0_SA_DQ<1>")
	)
	(arc
		(start 390.483598 -226.158552)
		(mid 390.598274 -226.025218)
		(end 390.639554 -225.85426)
		(width 0.0889)
		(layer "In11.Cu")
		(net "M_L_CPU0_SA_DQ<1>")
	)
	(arc
		(start 392.832336 -222.10903)
		(mid 392.868454 -222.079656)
		(end 392.900662 -222.046038)
		(width 0.0889)
		(layer "In11.Cu")
		(net "M_L_CPU0_SA_DQ<1>")
	)
	(arc
		(start 388.206234 -226.181666)
		(mid 388.389742 -226.22716)
		(end 388.571994 -226.17684)
		(width 0.0889)
		(layer "In11.Cu")
		(net "M_L_CPU0_SA_DQ<1>")
	)
	(arc
		(start 391.422382 -224.539048)
		(mid 391.537809 -224.405672)
		(end 391.579354 -224.234248)
		(width 0.0889)
		(layer "In11.Cu")
		(net "M_L_CPU0_SA_DQ<1>")
	)
	(arc
		(start 391.579354 -224.234248)
		(mid 391.644226 -223.971285)
		(end 391.823956 -223.768666)
		(width 0.0889)
		(layer "In11.Cu")
		(net "M_L_CPU0_SA_DQ<1>")
	)
	(arc
		(start 392.519154 -222.614236)
		(mid 392.584026 -222.351273)
		(end 392.763756 -222.148654)
		(width 0.0889)
		(layer "In11.Cu")
		(net "M_L_CPU0_SA_DQ<1>")
	)
	(arc
		(start 387.26618 -226.181666)
		(mid 387.449688 -226.22716)
		(end 387.63194 -226.17684)
		(width 0.0889)
		(layer "In11.Cu")
		(net "M_L_CPU0_SA_DQ<1>")
	)
	(arc
		(start 392.049508 -223.424242)
		(mid 392.11438 -223.161279)
		(end 392.29411 -222.95866)
		(width 0.0889)
		(layer "In11.Cu")
		(net "M_L_CPU0_SA_DQ<1>")
	)
	(arc
		(start 386.691886 -226.17684)
		(mid 386.974842 -226.100663)
		(end 387.257798 -226.17684)
		(width 0.0889)
		(layer "In11.Cu")
		(net "M_L_CPU0_SA_DQ<1>")
	)
	(arc
		(start 387.63194 -226.17684)
		(mid 387.914896 -226.100663)
		(end 388.197852 -226.17684)
		(width 0.0889)
		(layer "In11.Cu")
		(net "M_L_CPU0_SA_DQ<1>")
	)
	(arc
		(start 389.137906 -226.17684)
		(mid 389.32485 -226.227095)
		(end 389.511794 -226.17684)
		(width 0.0889)
		(layer "In11.Cu")
		(net "M_L_CPU0_SA_DQ<1>")
	)
	(arc
		(start 390.639554 -225.85426)
		(mid 390.70479 -225.590669)
		(end 390.885426 -225.387916)
		(width 0.0889)
		(layer "In11.Cu")
		(net "M_L_CPU0_SA_DQ<1>")
	)
	(arc
		(start 385.814824 -226.14509)
		(mid 386.070032 -226.101613)
		(end 386.317744 -226.17684)
		(width 0.0889)
		(layer "In11.Cu")
		(net "M_L_CPU0_SA_DQ<1>")
	)
	(arc
		(start 390.077706 -226.17684)
		(mid 390.259957 -226.22719)
		(end 390.443466 -226.181666)
		(width 0.0889)
		(layer "In11.Cu")
		(net "M_L_CPU0_SA_DQ<1>")
	)
	(arc
		(start 386.317744 -226.17684)
		(mid 386.499995 -226.22719)
		(end 386.683504 -226.181666)
		(width 0.0889)
		(layer "In11.Cu")
		(net "M_L_CPU0_SA_DQ<1>")
	)
	(arc
		(start 391.893552 -223.728534)
		(mid 392.008228 -223.5952)
		(end 392.049508 -223.424242)
		(width 0.0889)
		(layer "In11.Cu")
		(net "M_L_CPU0_SA_DQ<1>")
	)
	(arc
		(start 390.953498 -225.348546)
		(mid 391.068174 -225.215212)
		(end 391.109454 -225.044254)
		(width 0.0889)
		(layer "In11.Cu")
		(net "M_L_CPU0_SA_DQ<1>")
	)
	(segment
		(start 385.567936 -236.650022)
		(end 386.034788 -236.384084)
		(width 0.10668)
		(layer "F.Cu")
		(net "M_L_CPU0_SA_DQ<19>")
	)
	(segment
		(start 437.472582 -218.150948)
		(end 440.864498 -218.150948)
		(width 0.14478)
		(layer "In11.Cu")
		(net "M_L_CPU0_SA_DQ<19>")
	)
	(segment
		(start 429.790098 -218.150948)
		(end 433.181506 -218.150948)
		(width 0.14478)
		(layer "In11.Cu")
		(net "M_L_CPU0_SA_DQ<19>")
	)
	(segment
		(start 433.181506 -218.150948)
		(end 434.03139 -219.000832)
		(width 0.14478)
		(layer "In11.Cu")
		(net "M_L_CPU0_SA_DQ<19>")
	)
	(segment
		(start 409.871672 -221.106492)
		(end 409.631388 -220.866208)
		(width 0.14478)
		(layer "In11.Cu")
		(net "M_L_CPU0_SA_DQ<19>")
	)
	(segment
		(start 409.477972 -221.500192)
		(end 409.708604 -221.500192)
		(width 0.14478)
		(layer "In11.Cu")
		(net "M_L_CPU0_SA_DQ<19>")
	)
	(segment
		(start 393.555474 -236.010704)
		(end 393.897358 -236.010704)
		(width 0.0889)
		(layer "In11.Cu")
		(net "M_L_CPU0_SA_DQ<19>")
	)
	(segment
		(start 395.070838 -234.979972)
		(end 395.85773 -234.19308)
		(width 0.0889)
		(layer "In11.Cu")
		(net "M_L_CPU0_SA_DQ<19>")
	)
	(segment
		(start 449.260468 -218.150948)
		(end 449.653914 -218.150948)
		(width 0.14478)
		(layer "In11.Cu")
		(net "M_L_CPU0_SA_DQ<19>")
	)
	(segment
		(start 410.659072 -220.319092)
		(end 410.418788 -220.078808)
		(width 0.14478)
		(layer "In11.Cu")
		(net "M_L_CPU0_SA_DQ<19>")
	)
	(segment
		(start 449.115688 -218.295728)
		(end 449.260468 -218.150948)
		(width 0.14478)
		(layer "In11.Cu")
		(net "M_L_CPU0_SA_DQ<19>")
	)
	(segment
		(start 422.376346 -218.150694)
		(end 425.653962 -218.150694)
		(width 0.14478)
		(layer "In11.Cu")
		(net "M_L_CPU0_SA_DQ<19>")
	)
	(segment
		(start 449.115688 -218.553792)
		(end 449.115688 -218.295728)
		(width 0.14478)
		(layer "In11.Cu")
		(net "M_L_CPU0_SA_DQ<19>")
	)
	(segment
		(start 397.015716 -234.19308)
		(end 409.084272 -222.124524)
		(width 0.14478)
		(layer "In11.Cu")
		(net "M_L_CPU0_SA_DQ<19>")
	)
	(segment
		(start 444.786766 -218.150948)
		(end 448.419474 -218.150948)
		(width 0.14478)
		(layer "In11.Cu")
		(net "M_L_CPU0_SA_DQ<19>")
	)
	(segment
		(start 410.265372 -220.712792)
		(end 410.496004 -220.712792)
		(width 0.14478)
		(layer "In11.Cu")
		(net "M_L_CPU0_SA_DQ<19>")
	)
	(segment
		(start 448.419474 -218.150948)
		(end 448.564254 -218.295728)
		(width 0.14478)
		(layer "In11.Cu")
		(net "M_L_CPU0_SA_DQ<19>")
	)
	(segment
		(start 409.007056 -221.259908)
		(end 409.237688 -221.259908)
		(width 0.14478)
		(layer "In11.Cu")
		(net "M_L_CPU0_SA_DQ<19>")
	)
	(segment
		(start 449.653914 -218.150948)
		(end 450.088 -218.585034)
		(width 0.14478)
		(layer "In11.Cu")
		(net "M_L_CPU0_SA_DQ<19>")
	)
	(segment
		(start 394.684758 -235.554012)
		(end 395.070838 -235.167932)
		(width 0.0889)
		(layer "In11.Cu")
		(net "M_L_CPU0_SA_DQ<19>")
	)
	(segment
		(start 392.417808 -236.0676)
		(end 392.428222 -236.061504)
		(width 0.0889)
		(layer "In11.Cu")
		(net "M_L_CPU0_SA_DQ<19>")
	)
	(segment
		(start 409.631388 -220.635576)
		(end 409.794456 -220.472508)
		(width 0.14478)
		(layer "In11.Cu")
		(net "M_L_CPU0_SA_DQ<19>")
	)
	(segment
		(start 395.070838 -235.167932)
		(end 395.070838 -234.979972)
		(width 0.0889)
		(layer "In11.Cu")
		(net "M_L_CPU0_SA_DQ<19>")
	)
	(segment
		(start 385.880864 -236.118654)
		(end 385.903216 -236.035342)
		(width 0.0889)
		(layer "In11.Cu")
		(net "M_L_CPU0_SA_DQ<19>")
	)
	(segment
		(start 389.607806 -236.061504)
		(end 389.616188 -236.056678)
		(width 0.0889)
		(layer "In11.Cu")
		(net "M_L_CPU0_SA_DQ<19>")
	)
	(segment
		(start 434.03139 -219.000832)
		(end 436.622698 -219.000832)
		(width 0.14478)
		(layer "In11.Cu")
		(net "M_L_CPU0_SA_DQ<19>")
	)
	(segment
		(start 414.772856 -218.150694)
		(end 418.222684 -218.150694)
		(width 0.14478)
		(layer "In11.Cu")
		(net "M_L_CPU0_SA_DQ<19>")
	)
	(segment
		(start 448.564254 -218.553792)
		(end 448.709034 -218.698572)
		(width 0.14478)
		(layer "In11.Cu")
		(net "M_L_CPU0_SA_DQ<19>")
	)
	(segment
		(start 386.034788 -236.384084)
		(end 385.880864 -236.118654)
		(width 0.0889)
		(layer "In11.Cu")
		(net "M_L_CPU0_SA_DQ<19>")
	)
	(segment
		(start 410.025088 -220.472508)
		(end 410.265372 -220.712792)
		(width 0.14478)
		(layer "In11.Cu")
		(net "M_L_CPU0_SA_DQ<19>")
	)
	(segment
		(start 410.659072 -220.549724)
		(end 410.659072 -220.319092)
		(width 0.14478)
		(layer "In11.Cu")
		(net "M_L_CPU0_SA_DQ<19>")
	)
	(segment
		(start 396.354554 -234.19308)
		(end 397.015716 -234.19308)
		(width 0.14478)
		(layer "In11.Cu")
		(net "M_L_CPU0_SA_DQ<19>")
	)
	(segment
		(start 410.496004 -220.712792)
		(end 410.659072 -220.549724)
		(width 0.14478)
		(layer "In11.Cu")
		(net "M_L_CPU0_SA_DQ<19>")
	)
	(segment
		(start 441.714382 -219.000832)
		(end 443.936882 -219.000832)
		(width 0.14478)
		(layer "In11.Cu")
		(net "M_L_CPU0_SA_DQ<19>")
	)
	(segment
		(start 408.843988 -221.653608)
		(end 408.843988 -221.422976)
		(width 0.14478)
		(layer "In11.Cu")
		(net "M_L_CPU0_SA_DQ<19>")
	)
	(segment
		(start 393.897358 -236.010704)
		(end 394.35405 -235.554012)
		(width 0.0889)
		(layer "In11.Cu")
		(net "M_L_CPU0_SA_DQ<19>")
	)
	(segment
		(start 409.084272 -222.124524)
		(end 409.084272 -221.893892)
		(width 0.14478)
		(layer "In11.Cu")
		(net "M_L_CPU0_SA_DQ<19>")
	)
	(segment
		(start 419.072568 -219.000578)
		(end 421.526462 -219.000578)
		(width 0.14478)
		(layer "In11.Cu")
		(net "M_L_CPU0_SA_DQ<19>")
	)
	(segment
		(start 448.564254 -218.295728)
		(end 448.564254 -218.553792)
		(width 0.14478)
		(layer "In11.Cu")
		(net "M_L_CPU0_SA_DQ<19>")
	)
	(segment
		(start 413.913574 -219.009976)
		(end 414.772856 -218.150694)
		(width 0.14478)
		(layer "In11.Cu")
		(net "M_L_CPU0_SA_DQ<19>")
	)
	(segment
		(start 410.418788 -220.078808)
		(end 410.418788 -219.848176)
		(width 0.14478)
		(layer "In11.Cu")
		(net "M_L_CPU0_SA_DQ<19>")
	)
	(segment
		(start 392.80211 -236.061504)
		(end 392.816842 -236.07014)
		(width 0.0889)
		(layer "In11.Cu")
		(net "M_L_CPU0_SA_DQ<19>")
	)
	(segment
		(start 410.581856 -219.685108)
		(end 410.764228 -219.685108)
		(width 0.14478)
		(layer "In11.Cu")
		(net "M_L_CPU0_SA_DQ<19>")
	)
	(segment
		(start 421.526462 -219.000578)
		(end 422.376346 -218.150694)
		(width 0.14478)
		(layer "In11.Cu")
		(net "M_L_CPU0_SA_DQ<19>")
	)
	(segment
		(start 408.843988 -221.422976)
		(end 409.007056 -221.259908)
		(width 0.14478)
		(layer "In11.Cu")
		(net "M_L_CPU0_SA_DQ<19>")
	)
	(segment
		(start 411.43936 -219.009976)
		(end 413.913574 -219.009976)
		(width 0.14478)
		(layer "In11.Cu")
		(net "M_L_CPU0_SA_DQ<19>")
	)
	(segment
		(start 410.764228 -219.685108)
		(end 411.43936 -219.009976)
		(width 0.14478)
		(layer "In11.Cu")
		(net "M_L_CPU0_SA_DQ<19>")
	)
	(segment
		(start 389.033512 -236.056678)
		(end 389.041894 -236.061504)
		(width 0.0889)
		(layer "In11.Cu")
		(net "M_L_CPU0_SA_DQ<19>")
	)
	(segment
		(start 426.503846 -219.000578)
		(end 428.940468 -219.000578)
		(width 0.14478)
		(layer "In11.Cu")
		(net "M_L_CPU0_SA_DQ<19>")
	)
	(segment
		(start 443.936882 -219.000832)
		(end 444.786766 -218.150948)
		(width 0.14478)
		(layer "In11.Cu")
		(net "M_L_CPU0_SA_DQ<19>")
	)
	(segment
		(start 425.653962 -218.150694)
		(end 426.503846 -219.000578)
		(width 0.14478)
		(layer "In11.Cu")
		(net "M_L_CPU0_SA_DQ<19>")
	)
	(segment
		(start 418.222684 -218.150694)
		(end 419.072568 -219.000578)
		(width 0.14478)
		(layer "In11.Cu")
		(net "M_L_CPU0_SA_DQ<19>")
	)
	(segment
		(start 436.622698 -219.000832)
		(end 437.472582 -218.150948)
		(width 0.14478)
		(layer "In11.Cu")
		(net "M_L_CPU0_SA_DQ<19>")
	)
	(segment
		(start 440.864498 -218.150948)
		(end 441.714382 -219.000832)
		(width 0.14478)
		(layer "In11.Cu")
		(net "M_L_CPU0_SA_DQ<19>")
	)
	(segment
		(start 409.237688 -221.259908)
		(end 409.477972 -221.500192)
		(width 0.14478)
		(layer "In11.Cu")
		(net "M_L_CPU0_SA_DQ<19>")
	)
	(segment
		(start 448.709034 -218.698572)
		(end 448.970908 -218.698572)
		(width 0.14478)
		(layer "In11.Cu")
		(net "M_L_CPU0_SA_DQ<19>")
	)
	(segment
		(start 388.093458 -236.056678)
		(end 388.10184 -236.061504)
		(width 0.0889)
		(layer "In11.Cu")
		(net "M_L_CPU0_SA_DQ<19>")
	)
	(segment
		(start 409.631388 -220.866208)
		(end 409.631388 -220.635576)
		(width 0.14478)
		(layer "In11.Cu")
		(net "M_L_CPU0_SA_DQ<19>")
	)
	(segment
		(start 448.970908 -218.698572)
		(end 449.115688 -218.553792)
		(width 0.14478)
		(layer "In11.Cu")
		(net "M_L_CPU0_SA_DQ<19>")
	)
	(segment
		(start 409.871672 -221.337124)
		(end 409.871672 -221.106492)
		(width 0.14478)
		(layer "In11.Cu")
		(net "M_L_CPU0_SA_DQ<19>")
	)
	(segment
		(start 428.940468 -219.000578)
		(end 429.790098 -218.150948)
		(width 0.14478)
		(layer "In11.Cu")
		(net "M_L_CPU0_SA_DQ<19>")
	)
	(segment
		(start 394.35405 -235.554012)
		(end 394.684758 -235.554012)
		(width 0.0889)
		(layer "In11.Cu")
		(net "M_L_CPU0_SA_DQ<19>")
	)
	(segment
		(start 409.794456 -220.472508)
		(end 410.025088 -220.472508)
		(width 0.14478)
		(layer "In11.Cu")
		(net "M_L_CPU0_SA_DQ<19>")
	)
	(segment
		(start 410.418788 -219.848176)
		(end 410.581856 -219.685108)
		(width 0.14478)
		(layer "In11.Cu")
		(net "M_L_CPU0_SA_DQ<19>")
	)
	(segment
		(start 395.85773 -234.19308)
		(end 396.354554 -234.19308)
		(width 0.0889)
		(layer "In11.Cu")
		(net "M_L_CPU0_SA_DQ<19>")
	)
	(segment
		(start 409.084272 -221.893892)
		(end 408.843988 -221.653608)
		(width 0.14478)
		(layer "In11.Cu")
		(net "M_L_CPU0_SA_DQ<19>")
	)
	(segment
		(start 409.708604 -221.500192)
		(end 409.871672 -221.337124)
		(width 0.14478)
		(layer "In11.Cu")
		(net "M_L_CPU0_SA_DQ<19>")
	)
	(arc
		(start 391.862056 -236.061504)
		(mid 392.139123 -236.137775)
		(end 392.417808 -236.0676)
		(width 0.0889)
		(layer "In11.Cu")
		(net "M_L_CPU0_SA_DQ<19>")
	)
	(arc
		(start 390.921748 -236.061504)
		(mid 391.204704 -236.137681)
		(end 391.48766 -236.061504)
		(width 0.0889)
		(layer "In11.Cu")
		(net "M_L_CPU0_SA_DQ<19>")
	)
	(arc
		(start 386.787898 -236.061504)
		(mid 386.974842 -236.011249)
		(end 387.161786 -236.061504)
		(width 0.0889)
		(layer "In11.Cu")
		(net "M_L_CPU0_SA_DQ<19>")
	)
	(arc
		(start 386.221986 -236.061504)
		(mid 386.504942 -236.137681)
		(end 386.787898 -236.061504)
		(width 0.0889)
		(layer "In11.Cu")
		(net "M_L_CPU0_SA_DQ<19>")
	)
	(arc
		(start 390.54786 -236.061504)
		(mid 390.734804 -236.011249)
		(end 390.921748 -236.061504)
		(width 0.0889)
		(layer "In11.Cu")
		(net "M_L_CPU0_SA_DQ<19>")
	)
	(arc
		(start 389.981948 -236.061504)
		(mid 390.264904 -236.137681)
		(end 390.54786 -236.061504)
		(width 0.0889)
		(layer "In11.Cu")
		(net "M_L_CPU0_SA_DQ<19>")
	)
	(arc
		(start 389.041894 -236.061504)
		(mid 389.32485 -236.137681)
		(end 389.607806 -236.061504)
		(width 0.0889)
		(layer "In11.Cu")
		(net "M_L_CPU0_SA_DQ<19>")
	)
	(arc
		(start 388.10184 -236.061504)
		(mid 388.384796 -236.137681)
		(end 388.667752 -236.061504)
		(width 0.0889)
		(layer "In11.Cu")
		(net "M_L_CPU0_SA_DQ<19>")
	)
	(arc
		(start 387.161786 -236.061504)
		(mid 387.444742 -236.137681)
		(end 387.727698 -236.061504)
		(width 0.0889)
		(layer "In11.Cu")
		(net "M_L_CPU0_SA_DQ<19>")
	)
	(arc
		(start 389.616188 -236.056678)
		(mid 389.799696 -236.011184)
		(end 389.981948 -236.061504)
		(width 0.0889)
		(layer "In11.Cu")
		(net "M_L_CPU0_SA_DQ<19>")
	)
	(arc
		(start 392.428222 -236.061504)
		(mid 392.615166 -236.011249)
		(end 392.80211 -236.061504)
		(width 0.0889)
		(layer "In11.Cu")
		(net "M_L_CPU0_SA_DQ<19>")
	)
	(arc
		(start 385.903216 -236.035342)
		(mid 386.065548 -236.012524)
		(end 386.221986 -236.061504)
		(width 0.0889)
		(layer "In11.Cu")
		(net "M_L_CPU0_SA_DQ<19>")
	)
	(arc
		(start 391.48766 -236.061504)
		(mid 391.674858 -236.011122)
		(end 391.862056 -236.061504)
		(width 0.0889)
		(layer "In11.Cu")
		(net "M_L_CPU0_SA_DQ<19>")
	)
	(arc
		(start 387.727698 -236.061504)
		(mid 387.909949 -236.011154)
		(end 388.093458 -236.056678)
		(width 0.0889)
		(layer "In11.Cu")
		(net "M_L_CPU0_SA_DQ<19>")
	)
	(arc
		(start 388.667752 -236.061504)
		(mid 388.850003 -236.011154)
		(end 389.033512 -236.056678)
		(width 0.0889)
		(layer "In11.Cu")
		(net "M_L_CPU0_SA_DQ<19>")
	)
	(arc
		(start 392.816842 -236.07014)
		(mid 393.093571 -236.137823)
		(end 393.368022 -236.061504)
		(width 0.0889)
		(layer "In11.Cu")
		(net "M_L_CPU0_SA_DQ<19>")
	)
	(arc
		(start 393.368022 -236.061504)
		(mid 393.458385 -236.023694)
		(end 393.555474 -236.010704)
		(width 0.0889)
		(layer "In11.Cu")
		(net "M_L_CPU0_SA_DQ<19>")
	)
	(segment
		(start 386.97789 -235.840016)
		(end 387.444742 -235.574078)
		(width 0.10668)
		(layer "F.Cu")
		(net "M_L_CPU0_SA_DQ<18>")
	)
	(segment
		(start 414.79597 -216.46007)
		(end 418.231828 -216.46007)
		(width 0.14478)
		(layer "In11.Cu")
		(net "M_L_CPU0_SA_DQ<18>")
	)
	(segment
		(start 393.271248 -235.251752)
		(end 393.283186 -235.25861)
		(width 0.0889)
		(layer "In11.Cu")
		(net "M_L_CPU0_SA_DQ<18>")
	)
	(segment
		(start 405.007572 -223.913192)
		(end 405.17064 -223.750124)
		(width 0.14478)
		(layer "In11.Cu")
		(net "M_L_CPU0_SA_DQ<18>")
	)
	(segment
		(start 405.277828 -224.644712)
		(end 405.277828 -224.41408)
		(width 0.14478)
		(layer "In11.Cu")
		(net "M_L_CPU0_SA_DQ<18>")
	)
	(segment
		(start 444.750952 -216.460324)
		(end 449.663312 -216.460324)
		(width 0.14478)
		(layer "In11.Cu")
		(net "M_L_CPU0_SA_DQ<18>")
	)
	(segment
		(start 406.68956 -223.23298)
		(end 406.852628 -223.069912)
		(width 0.14478)
		(layer "In11.Cu")
		(net "M_L_CPU0_SA_DQ<18>")
	)
	(segment
		(start 387.290818 -235.308648)
		(end 387.31317 -235.225336)
		(width 0.0889)
		(layer "In11.Cu")
		(net "M_L_CPU0_SA_DQ<18>")
	)
	(segment
		(start 405.11476 -224.80778)
		(end 405.277828 -224.644712)
		(width 0.14478)
		(layer "In11.Cu")
		(net "M_L_CPU0_SA_DQ<18>")
	)
	(segment
		(start 440.78652 -216.460324)
		(end 441.636404 -217.310208)
		(width 0.14478)
		(layer "In11.Cu")
		(net "M_L_CPU0_SA_DQ<18>")
	)
	(segment
		(start 404.220172 -224.700592)
		(end 404.38324 -224.537524)
		(width 0.14478)
		(layer "In11.Cu")
		(net "M_L_CPU0_SA_DQ<18>")
	)
	(segment
		(start 407.721054 -221.17431)
		(end 411.585156 -217.310208)
		(width 0.14478)
		(layer "In11.Cu")
		(net "M_L_CPU0_SA_DQ<18>")
	)
	(segment
		(start 441.636404 -217.310208)
		(end 443.901068 -217.310208)
		(width 0.14478)
		(layer "In11.Cu")
		(net "M_L_CPU0_SA_DQ<18>")
	)
	(segment
		(start 406.582372 -222.338392)
		(end 406.74544 -222.175324)
		(width 0.14478)
		(layer "In11.Cu")
		(net "M_L_CPU0_SA_DQ<18>")
	)
	(segment
		(start 406.74544 -222.175324)
		(end 406.976072 -222.175324)
		(width 0.14478)
		(layer "In11.Cu")
		(net "M_L_CPU0_SA_DQ<18>")
	)
	(segment
		(start 394.402818 -234.436412)
		(end 394.867638 -234.436412)
		(width 0.0889)
		(layer "In11.Cu")
		(net "M_L_CPU0_SA_DQ<18>")
	)
	(segment
		(start 394.044678 -235.069888)
		(end 394.044678 -234.794552)
		(width 0.0889)
		(layer "In11.Cu")
		(net "M_L_CPU0_SA_DQ<18>")
	)
	(segment
		(start 405.401272 -223.750124)
		(end 405.671528 -224.02038)
		(width 0.14478)
		(layer "In11.Cu")
		(net "M_L_CPU0_SA_DQ<18>")
	)
	(segment
		(start 406.852628 -223.069912)
		(end 406.852628 -222.83928)
		(width 0.14478)
		(layer "In11.Cu")
		(net "M_L_CPU0_SA_DQ<18>")
	)
	(segment
		(start 404.613872 -224.537524)
		(end 404.884128 -224.80778)
		(width 0.14478)
		(layer "In11.Cu")
		(net "M_L_CPU0_SA_DQ<18>")
	)
	(segment
		(start 407.721054 -222.201486)
		(end 407.721054 -221.17431)
		(width 0.14478)
		(layer "In11.Cu")
		(net "M_L_CPU0_SA_DQ<18>")
	)
	(segment
		(start 406.852628 -222.83928)
		(end 406.582372 -222.569024)
		(width 0.14478)
		(layer "In11.Cu")
		(net "M_L_CPU0_SA_DQ<18>")
	)
	(segment
		(start 419.081966 -217.310208)
		(end 421.559736 -217.310208)
		(width 0.14478)
		(layer "In11.Cu")
		(net "M_L_CPU0_SA_DQ<18>")
	)
	(segment
		(start 421.559736 -217.310208)
		(end 422.40962 -216.460324)
		(width 0.14478)
		(layer "In11.Cu")
		(net "M_L_CPU0_SA_DQ<18>")
	)
	(segment
		(start 405.277828 -224.41408)
		(end 405.007572 -224.143824)
		(width 0.14478)
		(layer "In11.Cu")
		(net "M_L_CPU0_SA_DQ<18>")
	)
	(segment
		(start 395.566138 -233.539792)
		(end 395.82217 -233.28376)
		(width 0.0889)
		(layer "In11.Cu")
		(net "M_L_CPU0_SA_DQ<18>")
	)
	(segment
		(start 395.82217 -233.28376)
		(end 396.340584 -233.28376)
		(width 0.0889)
		(layer "In11.Cu")
		(net "M_L_CPU0_SA_DQ<18>")
	)
	(segment
		(start 405.794972 -223.125792)
		(end 405.95804 -222.962724)
		(width 0.14478)
		(layer "In11.Cu")
		(net "M_L_CPU0_SA_DQ<18>")
	)
	(segment
		(start 425.912534 -216.460324)
		(end 426.762418 -217.310208)
		(width 0.14478)
		(layer "In11.Cu")
		(net "M_L_CPU0_SA_DQ<18>")
	)
	(segment
		(start 391.945114 -235.25861)
		(end 391.957052 -235.251752)
		(width 0.0889)
		(layer "In11.Cu")
		(net "M_L_CPU0_SA_DQ<18>")
	)
	(segment
		(start 394.867638 -234.436412)
		(end 395.566138 -233.737912)
		(width 0.0889)
		(layer "In11.Cu")
		(net "M_L_CPU0_SA_DQ<18>")
	)
	(segment
		(start 449.663312 -216.460324)
		(end 450.088 -216.885012)
		(width 0.14478)
		(layer "In11.Cu")
		(net "M_L_CPU0_SA_DQ<18>")
	)
	(segment
		(start 413.945832 -217.310208)
		(end 414.79597 -216.46007)
		(width 0.14478)
		(layer "In11.Cu")
		(net "M_L_CPU0_SA_DQ<18>")
	)
	(segment
		(start 437.463184 -216.460324)
		(end 440.78652 -216.460324)
		(width 0.14478)
		(layer "In11.Cu")
		(net "M_L_CPU0_SA_DQ<18>")
	)
	(segment
		(start 404.490428 -225.432112)
		(end 404.490428 -225.20148)
		(width 0.14478)
		(layer "In11.Cu")
		(net "M_L_CPU0_SA_DQ<18>")
	)
	(segment
		(start 396.340584 -233.28376)
		(end 396.63878 -233.28376)
		(width 0.14478)
		(layer "In11.Cu")
		(net "M_L_CPU0_SA_DQ<18>")
	)
	(segment
		(start 406.976072 -222.175324)
		(end 407.246328 -222.44558)
		(width 0.14478)
		(layer "In11.Cu")
		(net "M_L_CPU0_SA_DQ<18>")
	)
	(segment
		(start 390.443466 -235.246672)
		(end 390.451848 -235.251498)
		(width 0.0889)
		(layer "In11.Cu")
		(net "M_L_CPU0_SA_DQ<18>")
	)
	(segment
		(start 436.6133 -217.310208)
		(end 437.463184 -216.460324)
		(width 0.14478)
		(layer "In11.Cu")
		(net "M_L_CPU0_SA_DQ<18>")
	)
	(segment
		(start 429.777144 -216.460324)
		(end 433.190904 -216.460324)
		(width 0.14478)
		(layer "In11.Cu")
		(net "M_L_CPU0_SA_DQ<18>")
	)
	(segment
		(start 434.040788 -217.310208)
		(end 436.6133 -217.310208)
		(width 0.14478)
		(layer "In11.Cu")
		(net "M_L_CPU0_SA_DQ<18>")
	)
	(segment
		(start 392.330686 -235.251498)
		(end 392.34872 -235.262166)
		(width 0.0889)
		(layer "In11.Cu")
		(net "M_L_CPU0_SA_DQ<18>")
	)
	(segment
		(start 406.065228 -223.62668)
		(end 405.794972 -223.356424)
		(width 0.14478)
		(layer "In11.Cu")
		(net "M_L_CPU0_SA_DQ<18>")
	)
	(segment
		(start 443.901068 -217.310208)
		(end 444.750952 -216.460324)
		(width 0.14478)
		(layer "In11.Cu")
		(net "M_L_CPU0_SA_DQ<18>")
	)
	(segment
		(start 404.884128 -224.80778)
		(end 405.11476 -224.80778)
		(width 0.14478)
		(layer "In11.Cu")
		(net "M_L_CPU0_SA_DQ<18>")
	)
	(segment
		(start 418.231828 -216.46007)
		(end 419.081966 -217.310208)
		(width 0.14478)
		(layer "In11.Cu")
		(net "M_L_CPU0_SA_DQ<18>")
	)
	(segment
		(start 404.220172 -224.931224)
		(end 404.220172 -224.700592)
		(width 0.14478)
		(layer "In11.Cu")
		(net "M_L_CPU0_SA_DQ<18>")
	)
	(segment
		(start 387.444742 -235.574078)
		(end 387.290818 -235.308648)
		(width 0.0889)
		(layer "In11.Cu")
		(net "M_L_CPU0_SA_DQ<18>")
	)
	(segment
		(start 426.762418 -217.310208)
		(end 428.92726 -217.310208)
		(width 0.14478)
		(layer "In11.Cu")
		(net "M_L_CPU0_SA_DQ<18>")
	)
	(segment
		(start 393.951968 -235.162598)
		(end 394.044678 -235.069888)
		(width 0.0889)
		(layer "In11.Cu")
		(net "M_L_CPU0_SA_DQ<18>")
	)
	(segment
		(start 391.01776 -235.251498)
		(end 391.026142 -235.246672)
		(width 0.0889)
		(layer "In11.Cu")
		(net "M_L_CPU0_SA_DQ<18>")
	)
	(segment
		(start 406.458928 -223.23298)
		(end 406.68956 -223.23298)
		(width 0.14478)
		(layer "In11.Cu")
		(net "M_L_CPU0_SA_DQ<18>")
	)
	(segment
		(start 405.17064 -223.750124)
		(end 405.401272 -223.750124)
		(width 0.14478)
		(layer "In11.Cu")
		(net "M_L_CPU0_SA_DQ<18>")
	)
	(segment
		(start 406.065228 -223.857312)
		(end 406.065228 -223.62668)
		(width 0.14478)
		(layer "In11.Cu")
		(net "M_L_CPU0_SA_DQ<18>")
	)
	(segment
		(start 391.957052 -235.251752)
		(end 391.970768 -235.243878)
		(width 0.0889)
		(layer "In11.Cu")
		(net "M_L_CPU0_SA_DQ<18>")
	)
	(segment
		(start 407.47696 -222.44558)
		(end 407.721054 -222.201486)
		(width 0.14478)
		(layer "In11.Cu")
		(net "M_L_CPU0_SA_DQ<18>")
	)
	(segment
		(start 404.490428 -225.20148)
		(end 404.220172 -224.931224)
		(width 0.14478)
		(layer "In11.Cu")
		(net "M_L_CPU0_SA_DQ<18>")
	)
	(segment
		(start 406.188672 -222.962724)
		(end 406.458928 -223.23298)
		(width 0.14478)
		(layer "In11.Cu")
		(net "M_L_CPU0_SA_DQ<18>")
	)
	(segment
		(start 396.63878 -233.28376)
		(end 404.490428 -225.432112)
		(width 0.14478)
		(layer "In11.Cu")
		(net "M_L_CPU0_SA_DQ<18>")
	)
	(segment
		(start 388.197852 -235.251498)
		(end 388.206234 -235.246672)
		(width 0.0889)
		(layer "In11.Cu")
		(net "M_L_CPU0_SA_DQ<18>")
	)
	(segment
		(start 411.585156 -217.310208)
		(end 413.945832 -217.310208)
		(width 0.14478)
		(layer "In11.Cu")
		(net "M_L_CPU0_SA_DQ<18>")
	)
	(segment
		(start 404.38324 -224.537524)
		(end 404.613872 -224.537524)
		(width 0.14478)
		(layer "In11.Cu")
		(net "M_L_CPU0_SA_DQ<18>")
	)
	(segment
		(start 428.92726 -217.310208)
		(end 429.777144 -216.460324)
		(width 0.14478)
		(layer "In11.Cu")
		(net "M_L_CPU0_SA_DQ<18>")
	)
	(segment
		(start 405.007572 -224.143824)
		(end 405.007572 -223.913192)
		(width 0.14478)
		(layer "In11.Cu")
		(net "M_L_CPU0_SA_DQ<18>")
	)
	(segment
		(start 433.190904 -216.460324)
		(end 434.040788 -217.310208)
		(width 0.14478)
		(layer "In11.Cu")
		(net "M_L_CPU0_SA_DQ<18>")
	)
	(segment
		(start 393.251182 -235.240322)
		(end 393.271248 -235.251752)
		(width 0.0889)
		(layer "In11.Cu")
		(net "M_L_CPU0_SA_DQ<18>")
	)
	(segment
		(start 394.044678 -234.794552)
		(end 394.402818 -234.436412)
		(width 0.0889)
		(layer "In11.Cu")
		(net "M_L_CPU0_SA_DQ<18>")
	)
	(segment
		(start 407.246328 -222.44558)
		(end 407.47696 -222.44558)
		(width 0.14478)
		(layer "In11.Cu")
		(net "M_L_CPU0_SA_DQ<18>")
	)
	(segment
		(start 405.95804 -222.962724)
		(end 406.188672 -222.962724)
		(width 0.14478)
		(layer "In11.Cu")
		(net "M_L_CPU0_SA_DQ<18>")
	)
	(segment
		(start 422.40962 -216.460324)
		(end 425.912534 -216.460324)
		(width 0.14478)
		(layer "In11.Cu")
		(net "M_L_CPU0_SA_DQ<18>")
	)
	(segment
		(start 405.90216 -224.02038)
		(end 406.065228 -223.857312)
		(width 0.14478)
		(layer "In11.Cu")
		(net "M_L_CPU0_SA_DQ<18>")
	)
	(segment
		(start 395.566138 -233.737912)
		(end 395.566138 -233.539792)
		(width 0.0889)
		(layer "In11.Cu")
		(net "M_L_CPU0_SA_DQ<18>")
	)
	(segment
		(start 405.671528 -224.02038)
		(end 405.90216 -224.02038)
		(width 0.14478)
		(layer "In11.Cu")
		(net "M_L_CPU0_SA_DQ<18>")
	)
	(segment
		(start 406.582372 -222.569024)
		(end 406.582372 -222.338392)
		(width 0.14478)
		(layer "In11.Cu")
		(net "M_L_CPU0_SA_DQ<18>")
	)
	(segment
		(start 405.794972 -223.356424)
		(end 405.794972 -223.125792)
		(width 0.14478)
		(layer "In11.Cu")
		(net "M_L_CPU0_SA_DQ<18>")
	)
	(arc
		(start 393.836398 -235.251498)
		(mid 393.897071 -235.210802)
		(end 393.951968 -235.162598)
		(width 0.0889)
		(layer "In11.Cu")
		(net "M_L_CPU0_SA_DQ<18>")
	)
	(arc
		(start 390.451848 -235.251498)
		(mid 390.734804 -235.327675)
		(end 391.01776 -235.251498)
		(width 0.0889)
		(layer "In11.Cu")
		(net "M_L_CPU0_SA_DQ<18>")
	)
	(arc
		(start 388.571994 -235.251498)
		(mid 388.85495 -235.327675)
		(end 389.137906 -235.251498)
		(width 0.0889)
		(layer "In11.Cu")
		(net "M_L_CPU0_SA_DQ<18>")
	)
	(arc
		(start 391.970768 -235.243878)
		(mid 392.151698 -235.2014)
		(end 392.330686 -235.251498)
		(width 0.0889)
		(layer "In11.Cu")
		(net "M_L_CPU0_SA_DQ<18>")
	)
	(arc
		(start 392.89736 -235.251498)
		(mid 393.072852 -235.201299)
		(end 393.251182 -235.240322)
		(width 0.0889)
		(layer "In11.Cu")
		(net "M_L_CPU0_SA_DQ<18>")
	)
	(arc
		(start 392.34872 -235.262166)
		(mid 392.624415 -235.328009)
		(end 392.89736 -235.251498)
		(width 0.0889)
		(layer "In11.Cu")
		(net "M_L_CPU0_SA_DQ<18>")
	)
	(arc
		(start 391.391902 -235.251498)
		(mid 391.66758 -235.327628)
		(end 391.945114 -235.25861)
		(width 0.0889)
		(layer "In11.Cu")
		(net "M_L_CPU0_SA_DQ<18>")
	)
	(arc
		(start 387.31317 -235.225336)
		(mid 387.475502 -235.202518)
		(end 387.63194 -235.251498)
		(width 0.0889)
		(layer "In11.Cu")
		(net "M_L_CPU0_SA_DQ<18>")
	)
	(arc
		(start 389.511794 -235.251498)
		(mid 389.79475 -235.327675)
		(end 390.077706 -235.251498)
		(width 0.0889)
		(layer "In11.Cu")
		(net "M_L_CPU0_SA_DQ<18>")
	)
	(arc
		(start 388.206234 -235.246672)
		(mid 388.389742 -235.201178)
		(end 388.571994 -235.251498)
		(width 0.0889)
		(layer "In11.Cu")
		(net "M_L_CPU0_SA_DQ<18>")
	)
	(arc
		(start 390.077706 -235.251498)
		(mid 390.259957 -235.201148)
		(end 390.443466 -235.246672)
		(width 0.0889)
		(layer "In11.Cu")
		(net "M_L_CPU0_SA_DQ<18>")
	)
	(arc
		(start 391.026142 -235.246672)
		(mid 391.20965 -235.201178)
		(end 391.391902 -235.251498)
		(width 0.0889)
		(layer "In11.Cu")
		(net "M_L_CPU0_SA_DQ<18>")
	)
	(arc
		(start 393.283186 -235.25861)
		(mid 393.56072 -235.327591)
		(end 393.836398 -235.251498)
		(width 0.0889)
		(layer "In11.Cu")
		(net "M_L_CPU0_SA_DQ<18>")
	)
	(arc
		(start 389.137906 -235.251498)
		(mid 389.32485 -235.201243)
		(end 389.511794 -235.251498)
		(width 0.0889)
		(layer "In11.Cu")
		(net "M_L_CPU0_SA_DQ<18>")
	)
	(arc
		(start 387.63194 -235.251498)
		(mid 387.914896 -235.327675)
		(end 388.197852 -235.251498)
		(width 0.0889)
		(layer "In11.Cu")
		(net "M_L_CPU0_SA_DQ<18>")
	)
	(segment
		(start 385.098036 -235.840016)
		(end 385.564888 -235.574078)
		(width 0.10668)
		(layer "F.Cu")
		(net "M_L_CPU0_SA_DQ<17>")
	)
	(segment
		(start 385.718812 -235.839508)
		(end 385.814824 -235.864908)
		(width 0.0889)
		(layer "In11.Cu")
		(net "M_L_CPU0_SA_DQ<17>")
	)
	(segment
		(start 414.706562 -217.310208)
		(end 418.207698 -217.310208)
		(width 0.14478)
		(layer "In11.Cu")
		(net "M_L_CPU0_SA_DQ<17>")
	)
	(segment
		(start 388.197852 -235.896658)
		(end 388.206234 -235.901484)
		(width 0.0889)
		(layer "In11.Cu")
		(net "M_L_CPU0_SA_DQ<17>")
	)
	(segment
		(start 434.5559 -218.160092)
		(end 435.838854 -218.160092)
		(width 0.14478)
		(layer "In11.Cu")
		(net "M_L_CPU0_SA_DQ<17>")
	)
	(segment
		(start 437.890666 -217.310208)
		(end 440.295538 -217.310208)
		(width 0.14478)
		(layer "In11.Cu")
		(net "M_L_CPU0_SA_DQ<17>")
	)
	(segment
		(start 418.207698 -217.310208)
		(end 419.057582 -218.160092)
		(width 0.14478)
		(layer "In11.Cu")
		(net "M_L_CPU0_SA_DQ<17>")
	)
	(segment
		(start 385.564888 -235.574078)
		(end 385.718812 -235.839508)
		(width 0.0889)
		(layer "In11.Cu")
		(net "M_L_CPU0_SA_DQ<17>")
	)
	(segment
		(start 443.495176 -218.160092)
		(end 445.546988 -217.310208)
		(width 0.14478)
		(layer "In11.Cu")
		(net "M_L_CPU0_SA_DQ<17>")
	)
	(segment
		(start 392.323828 -235.901484)
		(end 392.33221 -235.896658)
		(width 0.0889)
		(layer "In11.Cu")
		(net "M_L_CPU0_SA_DQ<17>")
	)
	(segment
		(start 390.443466 -235.901484)
		(end 390.451848 -235.896658)
		(width 0.0889)
		(layer "In11.Cu")
		(net "M_L_CPU0_SA_DQ<17>")
	)
	(segment
		(start 386.683504 -235.901484)
		(end 386.691886 -235.896658)
		(width 0.0889)
		(layer "In11.Cu")
		(net "M_L_CPU0_SA_DQ<17>")
	)
	(segment
		(start 445.546988 -217.310208)
		(end 452.27621 -217.310208)
		(width 0.14478)
		(layer "In11.Cu")
		(net "M_L_CPU0_SA_DQ<17>")
	)
	(segment
		(start 394.987018 -234.654852)
		(end 395.90345 -233.73842)
		(width 0.0889)
		(layer "In11.Cu")
		(net "M_L_CPU0_SA_DQ<17>")
	)
	(segment
		(start 411.3784 -218.160092)
		(end 413.856678 -218.160092)
		(width 0.14478)
		(layer "In11.Cu")
		(net "M_L_CPU0_SA_DQ<17>")
	)
	(segment
		(start 391.01776 -235.896658)
		(end 391.026142 -235.901484)
		(width 0.0889)
		(layer "In11.Cu")
		(net "M_L_CPU0_SA_DQ<17>")
	)
	(segment
		(start 396.327884 -233.73842)
		(end 396.827248 -233.73842)
		(width 0.14478)
		(layer "In11.Cu")
		(net "M_L_CPU0_SA_DQ<17>")
	)
	(segment
		(start 430.577244 -217.310208)
		(end 432.504088 -217.310208)
		(width 0.14478)
		(layer "In11.Cu")
		(net "M_L_CPU0_SA_DQ<17>")
	)
	(segment
		(start 440.295538 -217.310208)
		(end 442.34735 -218.160092)
		(width 0.14478)
		(layer "In11.Cu")
		(net "M_L_CPU0_SA_DQ<17>")
	)
	(segment
		(start 394.321538 -235.216192)
		(end 394.321538 -234.875832)
		(width 0.0889)
		(layer "In11.Cu")
		(net "M_L_CPU0_SA_DQ<17>")
	)
	(segment
		(start 422.507664 -217.310208)
		(end 425.117006 -217.310208)
		(width 0.14478)
		(layer "In11.Cu")
		(net "M_L_CPU0_SA_DQ<17>")
	)
	(segment
		(start 442.34735 -218.160092)
		(end 443.495176 -218.160092)
		(width 0.14478)
		(layer "In11.Cu")
		(net "M_L_CPU0_SA_DQ<17>")
	)
	(segment
		(start 421.65778 -218.160092)
		(end 422.507664 -217.310208)
		(width 0.14478)
		(layer "In11.Cu")
		(net "M_L_CPU0_SA_DQ<17>")
	)
	(segment
		(start 393.717526 -235.820204)
		(end 394.321538 -235.216192)
		(width 0.0889)
		(layer "In11.Cu")
		(net "M_L_CPU0_SA_DQ<17>")
	)
	(segment
		(start 392.897868 -235.896658)
		(end 392.90625 -235.901484)
		(width 0.0889)
		(layer "In11.Cu")
		(net "M_L_CPU0_SA_DQ<17>")
	)
	(segment
		(start 452.27621 -217.310208)
		(end 453.98055 -217.649298)
		(width 0.14478)
		(layer "In11.Cu")
		(net "M_L_CPU0_SA_DQ<17>")
	)
	(segment
		(start 435.838854 -218.160092)
		(end 437.890666 -217.310208)
		(width 0.14478)
		(layer "In11.Cu")
		(net "M_L_CPU0_SA_DQ<17>")
	)
	(segment
		(start 408.175714 -221.362778)
		(end 411.3784 -218.160092)
		(width 0.14478)
		(layer "In11.Cu")
		(net "M_L_CPU0_SA_DQ<17>")
	)
	(segment
		(start 394.542518 -234.654852)
		(end 394.987018 -234.654852)
		(width 0.0889)
		(layer "In11.Cu")
		(net "M_L_CPU0_SA_DQ<17>")
	)
	(segment
		(start 419.057582 -218.160092)
		(end 421.65778 -218.160092)
		(width 0.14478)
		(layer "In11.Cu")
		(net "M_L_CPU0_SA_DQ<17>")
	)
	(segment
		(start 392.887454 -235.890562)
		(end 392.897868 -235.896658)
		(width 0.0889)
		(layer "In11.Cu")
		(net "M_L_CPU0_SA_DQ<17>")
	)
	(segment
		(start 408.175714 -222.389954)
		(end 408.175714 -221.362778)
		(width 0.14478)
		(layer "In11.Cu")
		(net "M_L_CPU0_SA_DQ<17>")
	)
	(segment
		(start 387.257798 -235.896658)
		(end 387.26618 -235.901484)
		(width 0.0889)
		(layer "In11.Cu")
		(net "M_L_CPU0_SA_DQ<17>")
	)
	(segment
		(start 394.321538 -234.875832)
		(end 394.542518 -234.654852)
		(width 0.0889)
		(layer "In11.Cu")
		(net "M_L_CPU0_SA_DQ<17>")
	)
	(segment
		(start 393.55522 -235.820204)
		(end 393.717526 -235.820204)
		(width 0.0889)
		(layer "In11.Cu")
		(net "M_L_CPU0_SA_DQ<17>")
	)
	(segment
		(start 428.525432 -218.160092)
		(end 430.577244 -217.310208)
		(width 0.14478)
		(layer "In11.Cu")
		(net "M_L_CPU0_SA_DQ<17>")
	)
	(segment
		(start 432.504088 -217.310208)
		(end 434.5559 -218.160092)
		(width 0.14478)
		(layer "In11.Cu")
		(net "M_L_CPU0_SA_DQ<17>")
	)
	(segment
		(start 391.391902 -235.896658)
		(end 391.402316 -235.890562)
		(width 0.0889)
		(layer "In11.Cu")
		(net "M_L_CPU0_SA_DQ<17>")
	)
	(segment
		(start 396.827248 -233.73842)
		(end 408.175714 -222.389954)
		(width 0.14478)
		(layer "In11.Cu")
		(net "M_L_CPU0_SA_DQ<17>")
	)
	(segment
		(start 425.117006 -217.310208)
		(end 427.168818 -218.160092)
		(width 0.14478)
		(layer "In11.Cu")
		(net "M_L_CPU0_SA_DQ<17>")
	)
	(segment
		(start 427.168818 -218.160092)
		(end 428.525432 -218.160092)
		(width 0.14478)
		(layer "In11.Cu")
		(net "M_L_CPU0_SA_DQ<17>")
	)
	(segment
		(start 413.856678 -218.160092)
		(end 414.706562 -217.310208)
		(width 0.14478)
		(layer "In11.Cu")
		(net "M_L_CPU0_SA_DQ<17>")
	)
	(segment
		(start 395.90345 -233.73842)
		(end 396.327884 -233.73842)
		(width 0.0889)
		(layer "In11.Cu")
		(net "M_L_CPU0_SA_DQ<17>")
	)
	(segment
		(start 453.98055 -217.649298)
		(end 454.188068 -217.73515)
		(width 0.14478)
		(layer "In11.Cu")
		(net "M_L_CPU0_SA_DQ<17>")
	)
	(arc
		(start 388.206234 -235.901484)
		(mid 388.389742 -235.946978)
		(end 388.571994 -235.896658)
		(width 0.0889)
		(layer "In11.Cu")
		(net "M_L_CPU0_SA_DQ<17>")
	)
	(arc
		(start 387.63194 -235.896658)
		(mid 387.914896 -235.820481)
		(end 388.197852 -235.896658)
		(width 0.0889)
		(layer "In11.Cu")
		(net "M_L_CPU0_SA_DQ<17>")
	)
	(arc
		(start 388.571994 -235.896658)
		(mid 388.85495 -235.820481)
		(end 389.137906 -235.896658)
		(width 0.0889)
		(layer "In11.Cu")
		(net "M_L_CPU0_SA_DQ<17>")
	)
	(arc
		(start 391.958068 -235.896658)
		(mid 392.140319 -235.947008)
		(end 392.323828 -235.901484)
		(width 0.0889)
		(layer "In11.Cu")
		(net "M_L_CPU0_SA_DQ<17>")
	)
	(arc
		(start 386.317744 -235.896658)
		(mid 386.499995 -235.947008)
		(end 386.683504 -235.901484)
		(width 0.0889)
		(layer "In11.Cu")
		(net "M_L_CPU0_SA_DQ<17>")
	)
	(arc
		(start 385.814824 -235.864908)
		(mid 386.070032 -235.821431)
		(end 386.317744 -235.896658)
		(width 0.0889)
		(layer "In11.Cu")
		(net "M_L_CPU0_SA_DQ<17>")
	)
	(arc
		(start 391.402316 -235.890562)
		(mid 391.681002 -235.820342)
		(end 391.958068 -235.896658)
		(width 0.0889)
		(layer "In11.Cu")
		(net "M_L_CPU0_SA_DQ<17>")
	)
	(arc
		(start 391.026142 -235.901484)
		(mid 391.20965 -235.946978)
		(end 391.391902 -235.896658)
		(width 0.0889)
		(layer "In11.Cu")
		(net "M_L_CPU0_SA_DQ<17>")
	)
	(arc
		(start 392.33221 -235.896658)
		(mid 392.609023 -235.820515)
		(end 392.887454 -235.890562)
		(width 0.0889)
		(layer "In11.Cu")
		(net "M_L_CPU0_SA_DQ<17>")
	)
	(arc
		(start 393.27201 -235.896658)
		(mid 393.408558 -235.839702)
		(end 393.55522 -235.820204)
		(width 0.0889)
		(layer "In11.Cu")
		(net "M_L_CPU0_SA_DQ<17>")
	)
	(arc
		(start 387.26618 -235.901484)
		(mid 387.449688 -235.946978)
		(end 387.63194 -235.896658)
		(width 0.0889)
		(layer "In11.Cu")
		(net "M_L_CPU0_SA_DQ<17>")
	)
	(arc
		(start 389.511794 -235.896658)
		(mid 389.79475 -235.820481)
		(end 390.077706 -235.896658)
		(width 0.0889)
		(layer "In11.Cu")
		(net "M_L_CPU0_SA_DQ<17>")
	)
	(arc
		(start 390.451848 -235.896658)
		(mid 390.734804 -235.820481)
		(end 391.01776 -235.896658)
		(width 0.0889)
		(layer "In11.Cu")
		(net "M_L_CPU0_SA_DQ<17>")
	)
	(arc
		(start 389.137906 -235.896658)
		(mid 389.32485 -235.946913)
		(end 389.511794 -235.896658)
		(width 0.0889)
		(layer "In11.Cu")
		(net "M_L_CPU0_SA_DQ<17>")
	)
	(arc
		(start 392.90625 -235.901484)
		(mid 393.089758 -235.946978)
		(end 393.27201 -235.896658)
		(width 0.0889)
		(layer "In11.Cu")
		(net "M_L_CPU0_SA_DQ<17>")
	)
	(arc
		(start 386.691886 -235.896658)
		(mid 386.974842 -235.820481)
		(end 387.257798 -235.896658)
		(width 0.0889)
		(layer "In11.Cu")
		(net "M_L_CPU0_SA_DQ<17>")
	)
	(arc
		(start 390.077706 -235.896658)
		(mid 390.259957 -235.947008)
		(end 390.443466 -235.901484)
		(width 0.0889)
		(layer "In11.Cu")
		(net "M_L_CPU0_SA_DQ<17>")
	)
	(segment
		(start 386.50799 -235.03001)
		(end 386.974842 -234.764072)
		(width 0.10668)
		(layer "F.Cu")
		(net "M_L_CPU0_SA_DQ<16>")
	)
	(segment
		(start 433.190904 -215.610186)
		(end 434.040788 -216.46007)
		(width 0.14478)
		(layer "In11.Cu")
		(net "M_L_CPU0_SA_DQ<16>")
	)
	(segment
		(start 391.861548 -235.086398)
		(end 391.873486 -235.07954)
		(width 0.0889)
		(layer "In11.Cu")
		(net "M_L_CPU0_SA_DQ<16>")
	)
	(segment
		(start 443.51194 -216.46007)
		(end 445.563752 -215.610186)
		(width 0.14478)
		(layer "In11.Cu")
		(net "M_L_CPU0_SA_DQ<16>")
	)
	(segment
		(start 411.792166 -216.46007)
		(end 413.760666 -216.46007)
		(width 0.14478)
		(layer "In11.Cu")
		(net "M_L_CPU0_SA_DQ<16>")
	)
	(segment
		(start 389.607806 -235.086652)
		(end 389.616188 -235.091478)
		(width 0.0889)
		(layer "In11.Cu")
		(net "M_L_CPU0_SA_DQ<16>")
	)
	(segment
		(start 393.831318 -235.0135)
		(end 393.831318 -234.728512)
		(width 0.0889)
		(layer "In11.Cu")
		(net "M_L_CPU0_SA_DQ<16>")
	)
	(segment
		(start 454.18629 -216.03335)
		(end 454.188068 -216.035128)
		(width 0.14478)
		(layer "In11.Cu")
		(net "M_L_CPU0_SA_DQ<16>")
	)
	(segment
		(start 389.033512 -235.091478)
		(end 389.041894 -235.086652)
		(width 0.0889)
		(layer "In11.Cu")
		(net "M_L_CPU0_SA_DQ<16>")
	)
	(segment
		(start 452.058786 -215.610186)
		(end 454.18629 -216.03335)
		(width 0.14478)
		(layer "In11.Cu")
		(net "M_L_CPU0_SA_DQ<16>")
	)
	(segment
		(start 393.831318 -234.728512)
		(end 394.329158 -234.230672)
		(width 0.0889)
		(layer "In11.Cu")
		(net "M_L_CPU0_SA_DQ<16>")
	)
	(segment
		(start 422.388792 -215.610186)
		(end 425.912534 -215.610186)
		(width 0.14478)
		(layer "In11.Cu")
		(net "M_L_CPU0_SA_DQ<16>")
	)
	(segment
		(start 430.393856 -215.610186)
		(end 433.190904 -215.610186)
		(width 0.14478)
		(layer "In11.Cu")
		(net "M_L_CPU0_SA_DQ<16>")
	)
	(segment
		(start 434.040788 -216.46007)
		(end 436.063644 -216.46007)
		(width 0.14478)
		(layer "In11.Cu")
		(net "M_L_CPU0_SA_DQ<16>")
	)
	(segment
		(start 393.817094 -235.027724)
		(end 393.831318 -235.0135)
		(width 0.0889)
		(layer "In11.Cu")
		(net "M_L_CPU0_SA_DQ<16>")
	)
	(segment
		(start 428.342044 -216.46007)
		(end 430.393856 -215.610186)
		(width 0.14478)
		(layer "In11.Cu")
		(net "M_L_CPU0_SA_DQ<16>")
	)
	(segment
		(start 396.4305 -232.848912)
		(end 396.511018 -232.768394)
		(width 0.0889)
		(layer "In11.Cu")
		(net "M_L_CPU0_SA_DQ<16>")
	)
	(segment
		(start 425.912534 -215.610186)
		(end 426.762418 -216.46007)
		(width 0.14478)
		(layer "In11.Cu")
		(net "M_L_CPU0_SA_DQ<16>")
	)
	(segment
		(start 394.329158 -234.230672)
		(end 394.763498 -234.230672)
		(width 0.0889)
		(layer "In11.Cu")
		(net "M_L_CPU0_SA_DQ<16>")
	)
	(segment
		(start 440.676284 -215.610186)
		(end 441.526168 -216.46007)
		(width 0.14478)
		(layer "In11.Cu")
		(net "M_L_CPU0_SA_DQ<16>")
	)
	(segment
		(start 395.294358 -233.699812)
		(end 395.294358 -233.450892)
		(width 0.0889)
		(layer "In11.Cu")
		(net "M_L_CPU0_SA_DQ<16>")
	)
	(segment
		(start 418.077904 -215.610186)
		(end 418.927788 -216.46007)
		(width 0.14478)
		(layer "In11.Cu")
		(net "M_L_CPU0_SA_DQ<16>")
	)
	(segment
		(start 394.763498 -234.230672)
		(end 395.294358 -233.699812)
		(width 0.0889)
		(layer "In11.Cu")
		(net "M_L_CPU0_SA_DQ<16>")
	)
	(segment
		(start 438.115202 -215.610186)
		(end 440.676284 -215.610186)
		(width 0.14478)
		(layer "In11.Cu")
		(net "M_L_CPU0_SA_DQ<16>")
	)
	(segment
		(start 414.61055 -215.610186)
		(end 418.077904 -215.610186)
		(width 0.14478)
		(layer "In11.Cu")
		(net "M_L_CPU0_SA_DQ<16>")
	)
	(segment
		(start 395.294358 -233.450892)
		(end 395.896338 -232.848912)
		(width 0.0889)
		(layer "In11.Cu")
		(net "M_L_CPU0_SA_DQ<16>")
	)
	(segment
		(start 436.063644 -216.46007)
		(end 438.115202 -215.610186)
		(width 0.14478)
		(layer "In11.Cu")
		(net "M_L_CPU0_SA_DQ<16>")
	)
	(segment
		(start 426.762418 -216.46007)
		(end 428.342044 -216.46007)
		(width 0.14478)
		(layer "In11.Cu")
		(net "M_L_CPU0_SA_DQ<16>")
	)
	(segment
		(start 392.426698 -235.086652)
		(end 392.438382 -235.09351)
		(width 0.0889)
		(layer "In11.Cu")
		(net "M_L_CPU0_SA_DQ<16>")
	)
	(segment
		(start 388.093458 -235.091478)
		(end 388.10184 -235.086652)
		(width 0.0889)
		(layer "In11.Cu")
		(net "M_L_CPU0_SA_DQ<16>")
	)
	(segment
		(start 421.538908 -216.46007)
		(end 422.388792 -215.610186)
		(width 0.14478)
		(layer "In11.Cu")
		(net "M_L_CPU0_SA_DQ<16>")
	)
	(segment
		(start 403.690328 -225.589084)
		(end 403.690328 -224.561908)
		(width 0.14478)
		(layer "In11.Cu")
		(net "M_L_CPU0_SA_DQ<16>")
	)
	(segment
		(start 391.845292 -235.095796)
		(end 391.861548 -235.086398)
		(width 0.0889)
		(layer "In11.Cu")
		(net "M_L_CPU0_SA_DQ<16>")
	)
	(segment
		(start 393.345416 -235.073952)
		(end 393.383262 -235.095796)
		(width 0.0889)
		(layer "In11.Cu")
		(net "M_L_CPU0_SA_DQ<16>")
	)
	(segment
		(start 445.563752 -215.610186)
		(end 452.058786 -215.610186)
		(width 0.14478)
		(layer "In11.Cu")
		(net "M_L_CPU0_SA_DQ<16>")
	)
	(segment
		(start 387.128766 -235.029502)
		(end 387.224778 -235.054902)
		(width 0.0889)
		(layer "In11.Cu")
		(net "M_L_CPU0_SA_DQ<16>")
	)
	(segment
		(start 395.896338 -232.848912)
		(end 396.4305 -232.848912)
		(width 0.0889)
		(layer "In11.Cu")
		(net "M_L_CPU0_SA_DQ<16>")
	)
	(segment
		(start 403.690328 -224.561908)
		(end 411.792166 -216.46007)
		(width 0.14478)
		(layer "In11.Cu")
		(net "M_L_CPU0_SA_DQ<16>")
	)
	(segment
		(start 396.511018 -232.768394)
		(end 403.690328 -225.589084)
		(width 0.14478)
		(layer "In11.Cu")
		(net "M_L_CPU0_SA_DQ<16>")
	)
	(segment
		(start 441.526168 -216.46007)
		(end 443.51194 -216.46007)
		(width 0.14478)
		(layer "In11.Cu")
		(net "M_L_CPU0_SA_DQ<16>")
	)
	(segment
		(start 413.760666 -216.46007)
		(end 414.61055 -215.610186)
		(width 0.14478)
		(layer "In11.Cu")
		(net "M_L_CPU0_SA_DQ<16>")
	)
	(segment
		(start 418.927788 -216.46007)
		(end 421.538908 -216.46007)
		(width 0.14478)
		(layer "In11.Cu")
		(net "M_L_CPU0_SA_DQ<16>")
	)
	(segment
		(start 386.974842 -234.764072)
		(end 387.128766 -235.029502)
		(width 0.0889)
		(layer "In11.Cu")
		(net "M_L_CPU0_SA_DQ<16>")
	)
	(arc
		(start 388.10184 -235.086652)
		(mid 388.384796 -235.010475)
		(end 388.667752 -235.086652)
		(width 0.0889)
		(layer "In11.Cu")
		(net "M_L_CPU0_SA_DQ<16>")
	)
	(arc
		(start 391.48766 -235.086652)
		(mid 391.66531 -235.136912)
		(end 391.845292 -235.095796)
		(width 0.0889)
		(layer "In11.Cu")
		(net "M_L_CPU0_SA_DQ<16>")
	)
	(arc
		(start 389.616188 -235.091478)
		(mid 389.799696 -235.136972)
		(end 389.981948 -235.086652)
		(width 0.0889)
		(layer "In11.Cu")
		(net "M_L_CPU0_SA_DQ<16>")
	)
	(arc
		(start 390.921748 -235.086652)
		(mid 391.204704 -235.010475)
		(end 391.48766 -235.086652)
		(width 0.0889)
		(layer "In11.Cu")
		(net "M_L_CPU0_SA_DQ<16>")
	)
	(arc
		(start 389.041894 -235.086652)
		(mid 389.32485 -235.010475)
		(end 389.607806 -235.086652)
		(width 0.0889)
		(layer "In11.Cu")
		(net "M_L_CPU0_SA_DQ<16>")
	)
	(arc
		(start 391.873486 -235.07954)
		(mid 392.15102 -235.010559)
		(end 392.426698 -235.086652)
		(width 0.0889)
		(layer "In11.Cu")
		(net "M_L_CPU0_SA_DQ<16>")
	)
	(arc
		(start 389.981948 -235.086652)
		(mid 390.264904 -235.010475)
		(end 390.54786 -235.086652)
		(width 0.0889)
		(layer "In11.Cu")
		(net "M_L_CPU0_SA_DQ<16>")
	)
	(arc
		(start 387.727698 -235.086652)
		(mid 387.909949 -235.137002)
		(end 388.093458 -235.091478)
		(width 0.0889)
		(layer "In11.Cu")
		(net "M_L_CPU0_SA_DQ<16>")
	)
	(arc
		(start 390.54786 -235.086652)
		(mid 390.734804 -235.136907)
		(end 390.921748 -235.086652)
		(width 0.0889)
		(layer "In11.Cu")
		(net "M_L_CPU0_SA_DQ<16>")
	)
	(arc
		(start 388.667752 -235.086652)
		(mid 388.850003 -235.137002)
		(end 389.033512 -235.091478)
		(width 0.0889)
		(layer "In11.Cu")
		(net "M_L_CPU0_SA_DQ<16>")
	)
	(arc
		(start 392.801094 -235.086652)
		(mid 393.071625 -235.010246)
		(end 393.345416 -235.073952)
		(width 0.0889)
		(layer "In11.Cu")
		(net "M_L_CPU0_SA_DQ<16>")
	)
	(arc
		(start 387.224778 -235.054902)
		(mid 387.479986 -235.011425)
		(end 387.727698 -235.086652)
		(width 0.0889)
		(layer "In11.Cu")
		(net "M_L_CPU0_SA_DQ<16>")
	)
	(arc
		(start 393.383262 -235.095796)
		(mid 393.611256 -235.132392)
		(end 393.817094 -235.027724)
		(width 0.0889)
		(layer "In11.Cu")
		(net "M_L_CPU0_SA_DQ<16>")
	)
	(arc
		(start 392.438382 -235.09351)
		(mid 392.620637 -235.137163)
		(end 392.801094 -235.086652)
		(width 0.0889)
		(layer "In11.Cu")
		(net "M_L_CPU0_SA_DQ<16>")
	)
	(segment
		(start 385.567936 -235.03001)
		(end 386.034788 -234.764072)
		(width 0.10668)
		(layer "F.Cu")
		(net "M_L_CPU0_SA_DQ<15>")
	)
	(segment
		(start 448.498976 -214.46871)
		(end 448.763898 -214.46871)
		(width 0.14478)
		(layer "In11.Cu")
		(net "M_L_CPU0_SA_DQ<15>")
	)
	(segment
		(start 410.557472 -216.468452)
		(end 410.868622 -216.468452)
		(width 0.14478)
		(layer "In11.Cu")
		(net "M_L_CPU0_SA_DQ<15>")
	)
	(segment
		(start 447.65087 -214.46871)
		(end 447.942462 -214.760302)
		(width 0.14478)
		(layer "In11.Cu")
		(net "M_L_CPU0_SA_DQ<15>")
	)
	(segment
		(start 409.943808 -216.642188)
		(end 409.943808 -216.411556)
		(width 0.14478)
		(layer "In11.Cu")
		(net "M_L_CPU0_SA_DQ<15>")
	)
	(segment
		(start 409.550108 -217.035888)
		(end 409.874466 -217.360246)
		(width 0.14478)
		(layer "In11.Cu")
		(net "M_L_CPU0_SA_DQ<15>")
	)
	(segment
		(start 449.663312 -214.760302)
		(end 450.088 -215.18499)
		(width 0.14478)
		(layer "In11.Cu")
		(net "M_L_CPU0_SA_DQ<15>")
	)
	(segment
		(start 410.868622 -216.468452)
		(end 411.726888 -215.610186)
		(width 0.14478)
		(layer "In11.Cu")
		(net "M_L_CPU0_SA_DQ<15>")
	)
	(segment
		(start 413.531304 -215.610186)
		(end 414.381442 -214.760048)
		(width 0.14478)
		(layer "In11.Cu")
		(net "M_L_CPU0_SA_DQ<15>")
	)
	(segment
		(start 409.156408 -217.198956)
		(end 409.319476 -217.035888)
		(width 0.14478)
		(layer "In11.Cu")
		(net "M_L_CPU0_SA_DQ<15>")
	)
	(segment
		(start 393.864338 -234.390692)
		(end 394.321538 -233.933492)
		(width 0.0889)
		(layer "In11.Cu")
		(net "M_L_CPU0_SA_DQ<15>")
	)
	(segment
		(start 444.83274 -214.760302)
		(end 445.114426 -214.760302)
		(width 0.14478)
		(layer "In11.Cu")
		(net "M_L_CPU0_SA_DQ<15>")
	)
	(segment
		(start 422.284144 -214.760302)
		(end 425.912534 -214.760302)
		(width 0.14478)
		(layer "In11.Cu")
		(net "M_L_CPU0_SA_DQ<15>")
	)
	(segment
		(start 416.893502 -214.760048)
		(end 417.133278 -214.760048)
		(width 0.14478)
		(layer "In11.Cu")
		(net "M_L_CPU0_SA_DQ<15>")
	)
	(segment
		(start 445.114426 -214.760302)
		(end 445.384936 -214.489792)
		(width 0.14478)
		(layer "In11.Cu")
		(net "M_L_CPU0_SA_DQ<15>")
	)
	(segment
		(start 430.119282 -214.760302)
		(end 430.389792 -214.489792)
		(width 0.14478)
		(layer "In11.Cu")
		(net "M_L_CPU0_SA_DQ<15>")
	)
	(segment
		(start 418.00653 -214.760048)
		(end 418.404802 -214.760048)
		(width 0.14478)
		(layer "In11.Cu")
		(net "M_L_CPU0_SA_DQ<15>")
	)
	(segment
		(start 433.190904 -214.760302)
		(end 434.040788 -215.610186)
		(width 0.14478)
		(layer "In11.Cu")
		(net "M_L_CPU0_SA_DQ<15>")
	)
	(segment
		(start 445.384936 -214.489792)
		(end 445.66586 -214.489792)
		(width 0.14478)
		(layer "In11.Cu")
		(net "M_L_CPU0_SA_DQ<15>")
	)
	(segment
		(start 394.321538 -233.933492)
		(end 394.771118 -233.933492)
		(width 0.0889)
		(layer "In11.Cu")
		(net "M_L_CPU0_SA_DQ<15>")
	)
	(segment
		(start 417.450016 -214.44331)
		(end 417.689792 -214.44331)
		(width 0.14478)
		(layer "In11.Cu")
		(net "M_L_CPU0_SA_DQ<15>")
	)
	(segment
		(start 410.268166 -217.197178)
		(end 410.268166 -216.966546)
		(width 0.14478)
		(layer "In11.Cu")
		(net "M_L_CPU0_SA_DQ<15>")
	)
	(segment
		(start 416.576764 -214.44331)
		(end 416.893502 -214.760048)
		(width 0.14478)
		(layer "In11.Cu")
		(net "M_L_CPU0_SA_DQ<15>")
	)
	(segment
		(start 429.69688 -214.760302)
		(end 430.119282 -214.760302)
		(width 0.14478)
		(layer "In11.Cu")
		(net "M_L_CPU0_SA_DQ<15>")
	)
	(segment
		(start 434.040788 -215.610186)
		(end 436.6133 -215.610186)
		(width 0.14478)
		(layer "In11.Cu")
		(net "M_L_CPU0_SA_DQ<15>")
	)
	(segment
		(start 408.693366 -218.771978)
		(end 408.693366 -218.541346)
		(width 0.14478)
		(layer "In11.Cu")
		(net "M_L_CPU0_SA_DQ<15>")
	)
	(segment
		(start 417.133278 -214.760048)
		(end 417.450016 -214.44331)
		(width 0.14478)
		(layer "In11.Cu")
		(net "M_L_CPU0_SA_DQ<15>")
	)
	(segment
		(start 409.480766 -217.753946)
		(end 409.156408 -217.429588)
		(width 0.14478)
		(layer "In11.Cu")
		(net "M_L_CPU0_SA_DQ<15>")
	)
	(segment
		(start 395.827758 -232.340912)
		(end 396.151608 -232.340912)
		(width 0.0889)
		(layer "In11.Cu")
		(net "M_L_CPU0_SA_DQ<15>")
	)
	(segment
		(start 448.207384 -214.760302)
		(end 448.498976 -214.46871)
		(width 0.14478)
		(layer "In11.Cu")
		(net "M_L_CPU0_SA_DQ<15>")
	)
	(segment
		(start 408.532076 -217.823288)
		(end 408.762708 -217.823288)
		(width 0.14478)
		(layer "In11.Cu")
		(net "M_L_CPU0_SA_DQ<15>")
	)
	(segment
		(start 395.103858 -233.600752)
		(end 395.103858 -233.064812)
		(width 0.0889)
		(layer "In11.Cu")
		(net "M_L_CPU0_SA_DQ<15>")
	)
	(segment
		(start 443.982856 -215.610186)
		(end 444.83274 -214.760302)
		(width 0.14478)
		(layer "In11.Cu")
		(net "M_L_CPU0_SA_DQ<15>")
	)
	(segment
		(start 440.635644 -214.760302)
		(end 441.485528 -215.610186)
		(width 0.14478)
		(layer "In11.Cu")
		(net "M_L_CPU0_SA_DQ<15>")
	)
	(segment
		(start 415.780474 -214.760048)
		(end 416.02025 -214.760048)
		(width 0.14478)
		(layer "In11.Cu")
		(net "M_L_CPU0_SA_DQ<15>")
	)
	(segment
		(start 414.907222 -214.760048)
		(end 415.22396 -214.44331)
		(width 0.14478)
		(layer "In11.Cu")
		(net "M_L_CPU0_SA_DQ<15>")
	)
	(segment
		(start 417.689792 -214.44331)
		(end 418.00653 -214.760048)
		(width 0.14478)
		(layer "In11.Cu")
		(net "M_L_CPU0_SA_DQ<15>")
	)
	(segment
		(start 418.404802 -214.760048)
		(end 419.25494 -215.610186)
		(width 0.14478)
		(layer "In11.Cu")
		(net "M_L_CPU0_SA_DQ<15>")
	)
	(segment
		(start 386.034788 -234.764072)
		(end 385.880864 -234.498642)
		(width 0.0889)
		(layer "In11.Cu")
		(net "M_L_CPU0_SA_DQ<15>")
	)
	(segment
		(start 396.320772 -232.171748)
		(end 403.134068 -225.358452)
		(width 0.14478)
		(layer "In11.Cu")
		(net "M_L_CPU0_SA_DQ<15>")
	)
	(segment
		(start 403.134068 -225.358452)
		(end 403.134068 -224.331276)
		(width 0.14478)
		(layer "In11.Cu")
		(net "M_L_CPU0_SA_DQ<15>")
	)
	(segment
		(start 393.555474 -234.390692)
		(end 393.864338 -234.390692)
		(width 0.0889)
		(layer "In11.Cu")
		(net "M_L_CPU0_SA_DQ<15>")
	)
	(segment
		(start 392.80211 -234.441492)
		(end 392.816842 -234.450128)
		(width 0.0889)
		(layer "In11.Cu")
		(net "M_L_CPU0_SA_DQ<15>")
	)
	(segment
		(start 408.762708 -217.823288)
		(end 409.087066 -218.147646)
		(width 0.14478)
		(layer "In11.Cu")
		(net "M_L_CPU0_SA_DQ<15>")
	)
	(segment
		(start 447.094356 -214.760302)
		(end 447.385948 -214.46871)
		(width 0.14478)
		(layer "In11.Cu")
		(net "M_L_CPU0_SA_DQ<15>")
	)
	(segment
		(start 410.337508 -216.248488)
		(end 410.557472 -216.468452)
		(width 0.14478)
		(layer "In11.Cu")
		(net "M_L_CPU0_SA_DQ<15>")
	)
	(segment
		(start 409.087066 -218.147646)
		(end 409.317698 -218.147646)
		(width 0.14478)
		(layer "In11.Cu")
		(net "M_L_CPU0_SA_DQ<15>")
	)
	(segment
		(start 394.771118 -233.933492)
		(end 395.103858 -233.600752)
		(width 0.0889)
		(layer "In11.Cu")
		(net "M_L_CPU0_SA_DQ<15>")
	)
	(segment
		(start 408.693366 -218.541346)
		(end 408.369008 -218.216988)
		(width 0.14478)
		(layer "In11.Cu")
		(net "M_L_CPU0_SA_DQ<15>")
	)
	(segment
		(start 437.463184 -214.760302)
		(end 440.635644 -214.760302)
		(width 0.14478)
		(layer "In11.Cu")
		(net "M_L_CPU0_SA_DQ<15>")
	)
	(segment
		(start 409.319476 -217.035888)
		(end 409.550108 -217.035888)
		(width 0.14478)
		(layer "In11.Cu")
		(net "M_L_CPU0_SA_DQ<15>")
	)
	(segment
		(start 430.941226 -214.760302)
		(end 433.190904 -214.760302)
		(width 0.14478)
		(layer "In11.Cu")
		(net "M_L_CPU0_SA_DQ<15>")
	)
	(segment
		(start 409.480766 -217.984578)
		(end 409.480766 -217.753946)
		(width 0.14478)
		(layer "In11.Cu")
		(net "M_L_CPU0_SA_DQ<15>")
	)
	(segment
		(start 410.105098 -217.360246)
		(end 410.268166 -217.197178)
		(width 0.14478)
		(layer "In11.Cu")
		(net "M_L_CPU0_SA_DQ<15>")
	)
	(segment
		(start 421.43426 -215.610186)
		(end 422.284144 -214.760302)
		(width 0.14478)
		(layer "In11.Cu")
		(net "M_L_CPU0_SA_DQ<15>")
	)
	(segment
		(start 385.880864 -234.498642)
		(end 385.903216 -234.41533)
		(width 0.0889)
		(layer "In11.Cu")
		(net "M_L_CPU0_SA_DQ<15>")
	)
	(segment
		(start 448.763898 -214.46871)
		(end 449.05549 -214.760302)
		(width 0.14478)
		(layer "In11.Cu")
		(net "M_L_CPU0_SA_DQ<15>")
	)
	(segment
		(start 389.033512 -234.436666)
		(end 389.041894 -234.441492)
		(width 0.0889)
		(layer "In11.Cu")
		(net "M_L_CPU0_SA_DQ<15>")
	)
	(segment
		(start 389.607806 -234.441492)
		(end 389.616188 -234.436666)
		(width 0.0889)
		(layer "In11.Cu")
		(net "M_L_CPU0_SA_DQ<15>")
	)
	(segment
		(start 395.103858 -233.064812)
		(end 395.827758 -232.340912)
		(width 0.0889)
		(layer "In11.Cu")
		(net "M_L_CPU0_SA_DQ<15>")
	)
	(segment
		(start 447.942462 -214.760302)
		(end 448.207384 -214.760302)
		(width 0.14478)
		(layer "In11.Cu")
		(net "M_L_CPU0_SA_DQ<15>")
	)
	(segment
		(start 408.369008 -218.216988)
		(end 408.369008 -217.986356)
		(width 0.14478)
		(layer "In11.Cu")
		(net "M_L_CPU0_SA_DQ<15>")
	)
	(segment
		(start 392.417808 -234.447588)
		(end 392.428222 -234.441492)
		(width 0.0889)
		(layer "In11.Cu")
		(net "M_L_CPU0_SA_DQ<15>")
	)
	(segment
		(start 447.385948 -214.46871)
		(end 447.65087 -214.46871)
		(width 0.14478)
		(layer "In11.Cu")
		(net "M_L_CPU0_SA_DQ<15>")
	)
	(segment
		(start 409.317698 -218.147646)
		(end 409.480766 -217.984578)
		(width 0.14478)
		(layer "In11.Cu")
		(net "M_L_CPU0_SA_DQ<15>")
	)
	(segment
		(start 441.485528 -215.610186)
		(end 443.982856 -215.610186)
		(width 0.14478)
		(layer "In11.Cu")
		(net "M_L_CPU0_SA_DQ<15>")
	)
	(segment
		(start 416.02025 -214.760048)
		(end 416.336988 -214.44331)
		(width 0.14478)
		(layer "In11.Cu")
		(net "M_L_CPU0_SA_DQ<15>")
	)
	(segment
		(start 428.846996 -215.610186)
		(end 429.69688 -214.760302)
		(width 0.14478)
		(layer "In11.Cu")
		(net "M_L_CPU0_SA_DQ<15>")
	)
	(segment
		(start 410.268166 -216.966546)
		(end 409.943808 -216.642188)
		(width 0.14478)
		(layer "In11.Cu")
		(net "M_L_CPU0_SA_DQ<15>")
	)
	(segment
		(start 408.369008 -217.986356)
		(end 408.532076 -217.823288)
		(width 0.14478)
		(layer "In11.Cu")
		(net "M_L_CPU0_SA_DQ<15>")
	)
	(segment
		(start 419.25494 -215.610186)
		(end 421.43426 -215.610186)
		(width 0.14478)
		(layer "In11.Cu")
		(net "M_L_CPU0_SA_DQ<15>")
	)
	(segment
		(start 403.134068 -224.331276)
		(end 408.693366 -218.771978)
		(width 0.14478)
		(layer "In11.Cu")
		(net "M_L_CPU0_SA_DQ<15>")
	)
	(segment
		(start 415.22396 -214.44331)
		(end 415.463736 -214.44331)
		(width 0.14478)
		(layer "In11.Cu")
		(net "M_L_CPU0_SA_DQ<15>")
	)
	(segment
		(start 411.726888 -215.610186)
		(end 413.531304 -215.610186)
		(width 0.14478)
		(layer "In11.Cu")
		(net "M_L_CPU0_SA_DQ<15>")
	)
	(segment
		(start 410.106876 -216.248488)
		(end 410.337508 -216.248488)
		(width 0.14478)
		(layer "In11.Cu")
		(net "M_L_CPU0_SA_DQ<15>")
	)
	(segment
		(start 449.05549 -214.760302)
		(end 449.663312 -214.760302)
		(width 0.14478)
		(layer "In11.Cu")
		(net "M_L_CPU0_SA_DQ<15>")
	)
	(segment
		(start 425.912534 -214.760302)
		(end 426.762418 -215.610186)
		(width 0.14478)
		(layer "In11.Cu")
		(net "M_L_CPU0_SA_DQ<15>")
	)
	(segment
		(start 409.156408 -217.429588)
		(end 409.156408 -217.198956)
		(width 0.14478)
		(layer "In11.Cu")
		(net "M_L_CPU0_SA_DQ<15>")
	)
	(segment
		(start 388.093458 -234.436666)
		(end 388.10184 -234.441492)
		(width 0.0889)
		(layer "In11.Cu")
		(net "M_L_CPU0_SA_DQ<15>")
	)
	(segment
		(start 396.151608 -232.340912)
		(end 396.320772 -232.171748)
		(width 0.0889)
		(layer "In11.Cu")
		(net "M_L_CPU0_SA_DQ<15>")
	)
	(segment
		(start 415.463736 -214.44331)
		(end 415.780474 -214.760048)
		(width 0.14478)
		(layer "In11.Cu")
		(net "M_L_CPU0_SA_DQ<15>")
	)
	(segment
		(start 445.93637 -214.760302)
		(end 447.094356 -214.760302)
		(width 0.14478)
		(layer "In11.Cu")
		(net "M_L_CPU0_SA_DQ<15>")
	)
	(segment
		(start 409.943808 -216.411556)
		(end 410.106876 -216.248488)
		(width 0.14478)
		(layer "In11.Cu")
		(net "M_L_CPU0_SA_DQ<15>")
	)
	(segment
		(start 430.670716 -214.489792)
		(end 430.941226 -214.760302)
		(width 0.14478)
		(layer "In11.Cu")
		(net "M_L_CPU0_SA_DQ<15>")
	)
	(segment
		(start 416.336988 -214.44331)
		(end 416.576764 -214.44331)
		(width 0.14478)
		(layer "In11.Cu")
		(net "M_L_CPU0_SA_DQ<15>")
	)
	(segment
		(start 426.762418 -215.610186)
		(end 428.846996 -215.610186)
		(width 0.14478)
		(layer "In11.Cu")
		(net "M_L_CPU0_SA_DQ<15>")
	)
	(segment
		(start 414.381442 -214.760048)
		(end 414.907222 -214.760048)
		(width 0.14478)
		(layer "In11.Cu")
		(net "M_L_CPU0_SA_DQ<15>")
	)
	(segment
		(start 445.66586 -214.489792)
		(end 445.93637 -214.760302)
		(width 0.14478)
		(layer "In11.Cu")
		(net "M_L_CPU0_SA_DQ<15>")
	)
	(segment
		(start 409.874466 -217.360246)
		(end 410.105098 -217.360246)
		(width 0.14478)
		(layer "In11.Cu")
		(net "M_L_CPU0_SA_DQ<15>")
	)
	(segment
		(start 436.6133 -215.610186)
		(end 437.463184 -214.760302)
		(width 0.14478)
		(layer "In11.Cu")
		(net "M_L_CPU0_SA_DQ<15>")
	)
	(segment
		(start 430.389792 -214.489792)
		(end 430.670716 -214.489792)
		(width 0.14478)
		(layer "In11.Cu")
		(net "M_L_CPU0_SA_DQ<15>")
	)
	(arc
		(start 385.903216 -234.41533)
		(mid 386.065548 -234.392512)
		(end 386.221986 -234.441492)
		(width 0.0889)
		(layer "In11.Cu")
		(net "M_L_CPU0_SA_DQ<15>")
	)
	(arc
		(start 389.616188 -234.436666)
		(mid 389.799696 -234.391172)
		(end 389.981948 -234.441492)
		(width 0.0889)
		(layer "In11.Cu")
		(net "M_L_CPU0_SA_DQ<15>")
	)
	(arc
		(start 391.48766 -234.441492)
		(mid 391.674858 -234.39111)
		(end 391.862056 -234.441492)
		(width 0.0889)
		(layer "In11.Cu")
		(net "M_L_CPU0_SA_DQ<15>")
	)
	(arc
		(start 390.921748 -234.441492)
		(mid 391.204704 -234.517669)
		(end 391.48766 -234.441492)
		(width 0.0889)
		(layer "In11.Cu")
		(net "M_L_CPU0_SA_DQ<15>")
	)
	(arc
		(start 389.041894 -234.441492)
		(mid 389.32485 -234.517669)
		(end 389.607806 -234.441492)
		(width 0.0889)
		(layer "In11.Cu")
		(net "M_L_CPU0_SA_DQ<15>")
	)
	(arc
		(start 387.161786 -234.441492)
		(mid 387.444742 -234.517669)
		(end 387.727698 -234.441492)
		(width 0.0889)
		(layer "In11.Cu")
		(net "M_L_CPU0_SA_DQ<15>")
	)
	(arc
		(start 388.667752 -234.441492)
		(mid 388.850003 -234.391142)
		(end 389.033512 -234.436666)
		(width 0.0889)
		(layer "In11.Cu")
		(net "M_L_CPU0_SA_DQ<15>")
	)
	(arc
		(start 390.54786 -234.441492)
		(mid 390.734804 -234.391237)
		(end 390.921748 -234.441492)
		(width 0.0889)
		(layer "In11.Cu")
		(net "M_L_CPU0_SA_DQ<15>")
	)
	(arc
		(start 388.10184 -234.441492)
		(mid 388.384796 -234.517669)
		(end 388.667752 -234.441492)
		(width 0.0889)
		(layer "In11.Cu")
		(net "M_L_CPU0_SA_DQ<15>")
	)
	(arc
		(start 386.787898 -234.441492)
		(mid 386.974842 -234.391237)
		(end 387.161786 -234.441492)
		(width 0.0889)
		(layer "In11.Cu")
		(net "M_L_CPU0_SA_DQ<15>")
	)
	(arc
		(start 389.981948 -234.441492)
		(mid 390.264904 -234.517669)
		(end 390.54786 -234.441492)
		(width 0.0889)
		(layer "In11.Cu")
		(net "M_L_CPU0_SA_DQ<15>")
	)
	(arc
		(start 392.428222 -234.441492)
		(mid 392.615166 -234.391237)
		(end 392.80211 -234.441492)
		(width 0.0889)
		(layer "In11.Cu")
		(net "M_L_CPU0_SA_DQ<15>")
	)
	(arc
		(start 393.368022 -234.441492)
		(mid 393.458385 -234.403682)
		(end 393.555474 -234.390692)
		(width 0.0889)
		(layer "In11.Cu")
		(net "M_L_CPU0_SA_DQ<15>")
	)
	(arc
		(start 391.862056 -234.441492)
		(mid 392.139123 -234.517763)
		(end 392.417808 -234.447588)
		(width 0.0889)
		(layer "In11.Cu")
		(net "M_L_CPU0_SA_DQ<15>")
	)
	(arc
		(start 386.221986 -234.441492)
		(mid 386.504942 -234.517669)
		(end 386.787898 -234.441492)
		(width 0.0889)
		(layer "In11.Cu")
		(net "M_L_CPU0_SA_DQ<15>")
	)
	(arc
		(start 392.816842 -234.450128)
		(mid 393.093571 -234.517811)
		(end 393.368022 -234.441492)
		(width 0.0889)
		(layer "In11.Cu")
		(net "M_L_CPU0_SA_DQ<15>")
	)
	(arc
		(start 387.727698 -234.441492)
		(mid 387.909949 -234.391142)
		(end 388.093458 -234.436666)
		(width 0.0889)
		(layer "In11.Cu")
		(net "M_L_CPU0_SA_DQ<15>")
	)
	(segment
		(start 386.97789 -234.220004)
		(end 387.444742 -233.954066)
		(width 0.10668)
		(layer "F.Cu")
		(net "M_L_CPU0_SA_DQ<14>")
	)
	(segment
		(start 411.607 -213.765384)
		(end 411.607 -213.593172)
		(width 0.14478)
		(layer "In11.Cu")
		(net "M_L_CPU0_SA_DQ<14>")
	)
	(segment
		(start 447.549778 -212.706712)
		(end 447.811652 -212.706712)
		(width 0.14478)
		(layer "In11.Cu")
		(net "M_L_CPU0_SA_DQ<14>")
	)
	(segment
		(start 412.709868 -213.765384)
		(end 412.709868 -213.593172)
		(width 0.14478)
		(layer "In11.Cu")
		(net "M_L_CPU0_SA_DQ<14>")
	)
	(segment
		(start 426.762418 -213.910164)
		(end 429.005492 -213.910164)
		(width 0.14478)
		(layer "In11.Cu")
		(net "M_L_CPU0_SA_DQ<14>")
	)
	(segment
		(start 443.472824 -213.522052)
		(end 443.617604 -213.666832)
		(width 0.14478)
		(layer "In11.Cu")
		(net "M_L_CPU0_SA_DQ<14>")
	)
	(segment
		(start 416.821366 -212.696552)
		(end 416.966146 -212.841332)
		(width 0.14478)
		(layer "In11.Cu")
		(net "M_L_CPU0_SA_DQ<14>")
	)
	(segment
		(start 437.836564 -212.9155)
		(end 437.836564 -212.823552)
		(width 0.14478)
		(layer "In11.Cu")
		(net "M_L_CPU0_SA_DQ<14>")
	)
	(segment
		(start 445.298576 -213.20506)
		(end 445.298576 -213.295992)
		(width 0.14478)
		(layer "In11.Cu")
		(net "M_L_CPU0_SA_DQ<14>")
	)
	(segment
		(start 417.3728 -213.080092)
		(end 417.51758 -212.935312)
		(width 0.14478)
		(layer "In11.Cu")
		(net "M_L_CPU0_SA_DQ<14>")
	)
	(segment
		(start 413.406082 -213.910164)
		(end 413.895032 -213.910164)
		(width 0.14478)
		(layer "In11.Cu")
		(net "M_L_CPU0_SA_DQ<14>")
	)
	(segment
		(start 447.404998 -212.851492)
		(end 447.549778 -212.706712)
		(width 0.14478)
		(layer "In11.Cu")
		(net "M_L_CPU0_SA_DQ<14>")
	)
	(segment
		(start 390.443466 -233.62666)
		(end 390.451848 -233.631486)
		(width 0.0889)
		(layer "In11.Cu")
		(net "M_L_CPU0_SA_DQ<14>")
	)
	(segment
		(start 448.652646 -212.706712)
		(end 448.91452 -212.706712)
		(width 0.14478)
		(layer "In11.Cu")
		(net "M_L_CPU0_SA_DQ<14>")
	)
	(segment
		(start 447.956432 -213.269068)
		(end 448.101212 -213.413848)
		(width 0.14478)
		(layer "In11.Cu")
		(net "M_L_CPU0_SA_DQ<14>")
	)
	(segment
		(start 412.709868 -213.593172)
		(end 412.854648 -213.448392)
		(width 0.14478)
		(layer "In11.Cu")
		(net "M_L_CPU0_SA_DQ<14>")
	)
	(segment
		(start 415.863278 -212.841332)
		(end 415.863278 -212.935312)
		(width 0.14478)
		(layer "In11.Cu")
		(net "M_L_CPU0_SA_DQ<14>")
	)
	(segment
		(start 440.174126 -212.818472)
		(end 440.174126 -212.9155)
		(width 0.14478)
		(layer "In11.Cu")
		(net "M_L_CPU0_SA_DQ<14>")
	)
	(segment
		(start 411.46222 -213.910164)
		(end 411.607 -213.765384)
		(width 0.14478)
		(layer "In11.Cu")
		(net "M_L_CPU0_SA_DQ<14>")
	)
	(segment
		(start 436.078884 -213.532212)
		(end 436.223664 -213.676992)
		(width 0.14478)
		(layer "In11.Cu")
		(net "M_L_CPU0_SA_DQ<14>")
	)
	(segment
		(start 412.565088 -213.910164)
		(end 412.709868 -213.765384)
		(width 0.14478)
		(layer "In11.Cu")
		(net "M_L_CPU0_SA_DQ<14>")
	)
	(segment
		(start 417.51758 -212.841332)
		(end 417.66236 -212.696552)
		(width 0.14478)
		(layer "In11.Cu")
		(net "M_L_CPU0_SA_DQ<14>")
	)
	(segment
		(start 448.91452 -212.706712)
		(end 449.0593 -212.851492)
		(width 0.14478)
		(layer "In11.Cu")
		(net "M_L_CPU0_SA_DQ<14>")
	)
	(segment
		(start 429.005492 -213.910164)
		(end 429.855376 -213.06028)
		(width 0.14478)
		(layer "In11.Cu")
		(net "M_L_CPU0_SA_DQ<14>")
	)
	(segment
		(start 445.052704 -213.06028)
		(end 445.153796 -213.06028)
		(width 0.14478)
		(layer "In11.Cu")
		(net "M_L_CPU0_SA_DQ<14>")
	)
	(segment
		(start 422.94556 -213.06028)
		(end 425.912534 -213.06028)
		(width 0.14478)
		(layer "In11.Cu")
		(net "M_L_CPU0_SA_DQ<14>")
	)
	(segment
		(start 416.269932 -213.080092)
		(end 416.414712 -212.935312)
		(width 0.14478)
		(layer "In11.Cu")
		(net "M_L_CPU0_SA_DQ<14>")
	)
	(segment
		(start 416.559492 -212.696552)
		(end 416.821366 -212.696552)
		(width 0.14478)
		(layer "In11.Cu")
		(net "M_L_CPU0_SA_DQ<14>")
	)
	(segment
		(start 445.153796 -213.06028)
		(end 445.298576 -213.20506)
		(width 0.14478)
		(layer "In11.Cu")
		(net "M_L_CPU0_SA_DQ<14>")
	)
	(segment
		(start 443.21095 -213.522052)
		(end 443.472824 -213.522052)
		(width 0.14478)
		(layer "In11.Cu")
		(net "M_L_CPU0_SA_DQ<14>")
	)
	(segment
		(start 439.477912 -213.06028)
		(end 439.622692 -212.9155)
		(width 0.14478)
		(layer "In11.Cu")
		(net "M_L_CPU0_SA_DQ<14>")
	)
	(segment
		(start 402.224748 -224.981516)
		(end 402.224748 -223.88703)
		(width 0.14478)
		(layer "In11.Cu")
		(net "M_L_CPU0_SA_DQ<14>")
	)
	(segment
		(start 425.912534 -213.06028)
		(end 426.762418 -213.910164)
		(width 0.14478)
		(layer "In11.Cu")
		(net "M_L_CPU0_SA_DQ<14>")
	)
	(segment
		(start 445.443356 -213.440772)
		(end 445.70523 -213.440772)
		(width 0.14478)
		(layer "In11.Cu")
		(net "M_L_CPU0_SA_DQ<14>")
	)
	(segment
		(start 387.290818 -233.688636)
		(end 387.31317 -233.605324)
		(width 0.0889)
		(layer "In11.Cu")
		(net "M_L_CPU0_SA_DQ<14>")
	)
	(segment
		(start 434.040788 -213.910164)
		(end 435.52745 -213.910164)
		(width 0.14478)
		(layer "In11.Cu")
		(net "M_L_CPU0_SA_DQ<14>")
	)
	(segment
		(start 393.62507 -233.581194)
		(end 394.476478 -232.729786)
		(width 0.0889)
		(layer "In11.Cu")
		(net "M_L_CPU0_SA_DQ<14>")
	)
	(segment
		(start 392.330686 -233.631486)
		(end 392.34872 -233.642154)
		(width 0.0889)
		(layer "In11.Cu")
		(net "M_L_CPU0_SA_DQ<14>")
	)
	(segment
		(start 447.811652 -212.706712)
		(end 447.956432 -212.851492)
		(width 0.14478)
		(layer "In11.Cu")
		(net "M_L_CPU0_SA_DQ<14>")
	)
	(segment
		(start 448.507866 -212.851492)
		(end 448.652646 -212.706712)
		(width 0.14478)
		(layer "In11.Cu")
		(net "M_L_CPU0_SA_DQ<14>")
	)
	(segment
		(start 412.158434 -213.593172)
		(end 412.158434 -213.765384)
		(width 0.14478)
		(layer "In11.Cu")
		(net "M_L_CPU0_SA_DQ<14>")
	)
	(segment
		(start 438.387998 -212.9155)
		(end 438.532778 -213.06028)
		(width 0.14478)
		(layer "In11.Cu")
		(net "M_L_CPU0_SA_DQ<14>")
	)
	(segment
		(start 437.691784 -213.06028)
		(end 437.836564 -212.9155)
		(width 0.14478)
		(layer "In11.Cu")
		(net "M_L_CPU0_SA_DQ<14>")
	)
	(segment
		(start 407.365454 -218.746324)
		(end 407.365454 -217.669872)
		(width 0.14478)
		(layer "In11.Cu")
		(net "M_L_CPU0_SA_DQ<14>")
	)
	(segment
		(start 447.404998 -212.9155)
		(end 447.404998 -212.851492)
		(width 0.14478)
		(layer "In11.Cu")
		(net "M_L_CPU0_SA_DQ<14>")
	)
	(segment
		(start 415.718498 -212.696552)
		(end 415.863278 -212.841332)
		(width 0.14478)
		(layer "In11.Cu")
		(net "M_L_CPU0_SA_DQ<14>")
	)
	(segment
		(start 440.029346 -212.673692)
		(end 440.174126 -212.818472)
		(width 0.14478)
		(layer "In11.Cu")
		(net "M_L_CPU0_SA_DQ<14>")
	)
	(segment
		(start 445.85001 -213.20506)
		(end 445.99479 -213.06028)
		(width 0.14478)
		(layer "In11.Cu")
		(net "M_L_CPU0_SA_DQ<14>")
	)
	(segment
		(start 437.463184 -213.06028)
		(end 437.691784 -213.06028)
		(width 0.14478)
		(layer "In11.Cu")
		(net "M_L_CPU0_SA_DQ<14>")
	)
	(segment
		(start 402.224748 -223.88703)
		(end 407.365454 -218.746324)
		(width 0.14478)
		(layer "In11.Cu")
		(net "M_L_CPU0_SA_DQ<14>")
	)
	(segment
		(start 447.956432 -212.851492)
		(end 447.956432 -213.269068)
		(width 0.14478)
		(layer "In11.Cu")
		(net "M_L_CPU0_SA_DQ<14>")
	)
	(segment
		(start 387.444742 -233.954066)
		(end 387.290818 -233.688636)
		(width 0.0889)
		(layer "In11.Cu")
		(net "M_L_CPU0_SA_DQ<14>")
	)
	(segment
		(start 429.855376 -213.06028)
		(end 433.190904 -213.06028)
		(width 0.14478)
		(layer "In11.Cu")
		(net "M_L_CPU0_SA_DQ<14>")
	)
	(segment
		(start 411.75178 -213.448392)
		(end 412.013654 -213.448392)
		(width 0.14478)
		(layer "In11.Cu")
		(net "M_L_CPU0_SA_DQ<14>")
	)
	(segment
		(start 435.52745 -213.910164)
		(end 435.67223 -213.765384)
		(width 0.14478)
		(layer "In11.Cu")
		(net "M_L_CPU0_SA_DQ<14>")
	)
	(segment
		(start 438.387998 -212.823552)
		(end 438.387998 -212.9155)
		(width 0.14478)
		(layer "In11.Cu")
		(net "M_L_CPU0_SA_DQ<14>")
	)
	(segment
		(start 415.108644 -212.696552)
		(end 415.718498 -212.696552)
		(width 0.14478)
		(layer "In11.Cu")
		(net "M_L_CPU0_SA_DQ<14>")
	)
	(segment
		(start 391.957052 -233.63174)
		(end 391.970768 -233.623866)
		(width 0.0889)
		(layer "In11.Cu")
		(net "M_L_CPU0_SA_DQ<14>")
	)
	(segment
		(start 438.243218 -212.678772)
		(end 438.387998 -212.823552)
		(width 0.14478)
		(layer "In11.Cu")
		(net "M_L_CPU0_SA_DQ<14>")
	)
	(segment
		(start 443.06617 -213.666832)
		(end 443.21095 -213.522052)
		(width 0.14478)
		(layer "In11.Cu")
		(net "M_L_CPU0_SA_DQ<14>")
	)
	(segment
		(start 443.617604 -213.765384)
		(end 443.762384 -213.910164)
		(width 0.14478)
		(layer "In11.Cu")
		(net "M_L_CPU0_SA_DQ<14>")
	)
	(segment
		(start 436.223664 -213.765384)
		(end 436.368444 -213.910164)
		(width 0.14478)
		(layer "In11.Cu")
		(net "M_L_CPU0_SA_DQ<14>")
	)
	(segment
		(start 416.966146 -212.841332)
		(end 416.966146 -212.935312)
		(width 0.14478)
		(layer "In11.Cu")
		(net "M_L_CPU0_SA_DQ<14>")
	)
	(segment
		(start 449.20408 -213.06028)
		(end 449.663312 -213.06028)
		(width 0.14478)
		(layer "In11.Cu")
		(net "M_L_CPU0_SA_DQ<14>")
	)
	(segment
		(start 416.008058 -213.080092)
		(end 416.269932 -213.080092)
		(width 0.14478)
		(layer "In11.Cu")
		(net "M_L_CPU0_SA_DQ<14>")
	)
	(segment
		(start 449.0593 -212.9155)
		(end 449.20408 -213.06028)
		(width 0.14478)
		(layer "In11.Cu")
		(net "M_L_CPU0_SA_DQ<14>")
	)
	(segment
		(start 435.67223 -213.765384)
		(end 435.67223 -213.676992)
		(width 0.14478)
		(layer "In11.Cu")
		(net "M_L_CPU0_SA_DQ<14>")
	)
	(segment
		(start 388.197852 -233.631486)
		(end 388.206234 -233.62666)
		(width 0.0889)
		(layer "In11.Cu")
		(net "M_L_CPU0_SA_DQ<14>")
	)
	(segment
		(start 416.966146 -212.935312)
		(end 417.110926 -213.080092)
		(width 0.14478)
		(layer "In11.Cu")
		(net "M_L_CPU0_SA_DQ<14>")
	)
	(segment
		(start 415.863278 -212.935312)
		(end 416.008058 -213.080092)
		(width 0.14478)
		(layer "In11.Cu")
		(net "M_L_CPU0_SA_DQ<14>")
	)
	(segment
		(start 411.607 -213.593172)
		(end 411.75178 -213.448392)
		(width 0.14478)
		(layer "In11.Cu")
		(net "M_L_CPU0_SA_DQ<14>")
	)
	(segment
		(start 412.013654 -213.448392)
		(end 412.158434 -213.593172)
		(width 0.14478)
		(layer "In11.Cu")
		(net "M_L_CPU0_SA_DQ<14>")
	)
	(segment
		(start 395.418818 -231.880918)
		(end 395.418818 -231.787446)
		(width 0.0889)
		(layer "In11.Cu")
		(net "M_L_CPU0_SA_DQ<14>")
	)
	(segment
		(start 391.945114 -233.638598)
		(end 391.957052 -233.63174)
		(width 0.0889)
		(layer "In11.Cu")
		(net "M_L_CPU0_SA_DQ<14>")
	)
	(segment
		(start 416.414712 -212.841332)
		(end 416.559492 -212.696552)
		(width 0.14478)
		(layer "In11.Cu")
		(net "M_L_CPU0_SA_DQ<14>")
	)
	(segment
		(start 393.082272 -233.581194)
		(end 393.62507 -233.581194)
		(width 0.0889)
		(layer "In11.Cu")
		(net "M_L_CPU0_SA_DQ<14>")
	)
	(segment
		(start 445.99479 -213.06028)
		(end 447.260218 -213.06028)
		(width 0.14478)
		(layer "In11.Cu")
		(net "M_L_CPU0_SA_DQ<14>")
	)
	(segment
		(start 412.854648 -213.448392)
		(end 413.116522 -213.448392)
		(width 0.14478)
		(layer "In11.Cu")
		(net "M_L_CPU0_SA_DQ<14>")
	)
	(segment
		(start 416.414712 -212.935312)
		(end 416.414712 -212.841332)
		(width 0.14478)
		(layer "In11.Cu")
		(net "M_L_CPU0_SA_DQ<14>")
	)
	(segment
		(start 448.101212 -213.413848)
		(end 448.363086 -213.413848)
		(width 0.14478)
		(layer "In11.Cu")
		(net "M_L_CPU0_SA_DQ<14>")
	)
	(segment
		(start 395.418818 -231.787446)
		(end 395.825472 -231.380792)
		(width 0.0889)
		(layer "In11.Cu")
		(net "M_L_CPU0_SA_DQ<14>")
	)
	(segment
		(start 445.70523 -213.440772)
		(end 445.85001 -213.295992)
		(width 0.14478)
		(layer "In11.Cu")
		(net "M_L_CPU0_SA_DQ<14>")
	)
	(segment
		(start 394.476478 -232.729786)
		(end 394.56995 -232.729786)
		(width 0.0889)
		(layer "In11.Cu")
		(net "M_L_CPU0_SA_DQ<14>")
	)
	(segment
		(start 433.190904 -213.06028)
		(end 434.040788 -213.910164)
		(width 0.14478)
		(layer "In11.Cu")
		(net "M_L_CPU0_SA_DQ<14>")
	)
	(segment
		(start 439.622692 -212.9155)
		(end 439.622692 -212.818472)
		(width 0.14478)
		(layer "In11.Cu")
		(net "M_L_CPU0_SA_DQ<14>")
	)
	(segment
		(start 440.318906 -213.06028)
		(end 440.538108 -213.06028)
		(width 0.14478)
		(layer "In11.Cu")
		(net "M_L_CPU0_SA_DQ<14>")
	)
	(segment
		(start 394.56995 -232.729786)
		(end 395.418818 -231.880918)
		(width 0.0889)
		(layer "In11.Cu")
		(net "M_L_CPU0_SA_DQ<14>")
	)
	(segment
		(start 439.767472 -212.673692)
		(end 440.029346 -212.673692)
		(width 0.14478)
		(layer "In11.Cu")
		(net "M_L_CPU0_SA_DQ<14>")
	)
	(segment
		(start 440.538108 -213.06028)
		(end 441.387992 -213.910164)
		(width 0.14478)
		(layer "In11.Cu")
		(net "M_L_CPU0_SA_DQ<14>")
	)
	(segment
		(start 449.0593 -212.851492)
		(end 449.0593 -212.9155)
		(width 0.14478)
		(layer "In11.Cu")
		(net "M_L_CPU0_SA_DQ<14>")
	)
	(segment
		(start 443.762384 -213.910164)
		(end 444.20282 -213.910164)
		(width 0.14478)
		(layer "In11.Cu")
		(net "M_L_CPU0_SA_DQ<14>")
	)
	(segment
		(start 436.6133 -213.910164)
		(end 437.463184 -213.06028)
		(width 0.14478)
		(layer "In11.Cu")
		(net "M_L_CPU0_SA_DQ<14>")
	)
	(segment
		(start 407.365454 -217.669872)
		(end 411.125162 -213.910164)
		(width 0.14478)
		(layer "In11.Cu")
		(net "M_L_CPU0_SA_DQ<14>")
	)
	(segment
		(start 413.261302 -213.593172)
		(end 413.261302 -213.765384)
		(width 0.14478)
		(layer "In11.Cu")
		(net "M_L_CPU0_SA_DQ<14>")
	)
	(segment
		(start 413.261302 -213.765384)
		(end 413.406082 -213.910164)
		(width 0.14478)
		(layer "In11.Cu")
		(net "M_L_CPU0_SA_DQ<14>")
	)
	(segment
		(start 442.92139 -213.910164)
		(end 443.06617 -213.765384)
		(width 0.14478)
		(layer "In11.Cu")
		(net "M_L_CPU0_SA_DQ<14>")
	)
	(segment
		(start 435.81701 -213.532212)
		(end 436.078884 -213.532212)
		(width 0.14478)
		(layer "In11.Cu")
		(net "M_L_CPU0_SA_DQ<14>")
	)
	(segment
		(start 417.66236 -212.696552)
		(end 418.037772 -212.696552)
		(width 0.14478)
		(layer "In11.Cu")
		(net "M_L_CPU0_SA_DQ<14>")
	)
	(segment
		(start 441.387992 -213.910164)
		(end 442.92139 -213.910164)
		(width 0.14478)
		(layer "In11.Cu")
		(net "M_L_CPU0_SA_DQ<14>")
	)
	(segment
		(start 448.363086 -213.413848)
		(end 448.507866 -213.269068)
		(width 0.14478)
		(layer "In11.Cu")
		(net "M_L_CPU0_SA_DQ<14>")
	)
	(segment
		(start 443.06617 -213.765384)
		(end 443.06617 -213.666832)
		(width 0.14478)
		(layer "In11.Cu")
		(net "M_L_CPU0_SA_DQ<14>")
	)
	(segment
		(start 412.303214 -213.910164)
		(end 412.565088 -213.910164)
		(width 0.14478)
		(layer "In11.Cu")
		(net "M_L_CPU0_SA_DQ<14>")
	)
	(segment
		(start 420.893748 -213.910164)
		(end 422.94556 -213.06028)
		(width 0.14478)
		(layer "In11.Cu")
		(net "M_L_CPU0_SA_DQ<14>")
	)
	(segment
		(start 413.116522 -213.448392)
		(end 413.261302 -213.593172)
		(width 0.14478)
		(layer "In11.Cu")
		(net "M_L_CPU0_SA_DQ<14>")
	)
	(segment
		(start 417.51758 -212.935312)
		(end 417.51758 -212.841332)
		(width 0.14478)
		(layer "In11.Cu")
		(net "M_L_CPU0_SA_DQ<14>")
	)
	(segment
		(start 419.251384 -213.910164)
		(end 420.893748 -213.910164)
		(width 0.14478)
		(layer "In11.Cu")
		(net "M_L_CPU0_SA_DQ<14>")
	)
	(segment
		(start 413.895032 -213.910164)
		(end 415.108644 -212.696552)
		(width 0.14478)
		(layer "In11.Cu")
		(net "M_L_CPU0_SA_DQ<14>")
	)
	(segment
		(start 417.110926 -213.080092)
		(end 417.3728 -213.080092)
		(width 0.14478)
		(layer "In11.Cu")
		(net "M_L_CPU0_SA_DQ<14>")
	)
	(segment
		(start 439.622692 -212.818472)
		(end 439.767472 -212.673692)
		(width 0.14478)
		(layer "In11.Cu")
		(net "M_L_CPU0_SA_DQ<14>")
	)
	(segment
		(start 412.158434 -213.765384)
		(end 412.303214 -213.910164)
		(width 0.14478)
		(layer "In11.Cu")
		(net "M_L_CPU0_SA_DQ<14>")
	)
	(segment
		(start 440.174126 -212.9155)
		(end 440.318906 -213.06028)
		(width 0.14478)
		(layer "In11.Cu")
		(net "M_L_CPU0_SA_DQ<14>")
	)
	(segment
		(start 411.125162 -213.910164)
		(end 411.46222 -213.910164)
		(width 0.14478)
		(layer "In11.Cu")
		(net "M_L_CPU0_SA_DQ<14>")
	)
	(segment
		(start 443.617604 -213.666832)
		(end 443.617604 -213.765384)
		(width 0.14478)
		(layer "In11.Cu")
		(net "M_L_CPU0_SA_DQ<14>")
	)
	(segment
		(start 437.836564 -212.823552)
		(end 437.981344 -212.678772)
		(width 0.14478)
		(layer "In11.Cu")
		(net "M_L_CPU0_SA_DQ<14>")
	)
	(segment
		(start 448.507866 -213.269068)
		(end 448.507866 -212.851492)
		(width 0.14478)
		(layer "In11.Cu")
		(net "M_L_CPU0_SA_DQ<14>")
	)
	(segment
		(start 449.663312 -213.06028)
		(end 450.088 -213.484968)
		(width 0.14478)
		(layer "In11.Cu")
		(net "M_L_CPU0_SA_DQ<14>")
	)
	(segment
		(start 418.037772 -212.696552)
		(end 419.251384 -213.910164)
		(width 0.14478)
		(layer "In11.Cu")
		(net "M_L_CPU0_SA_DQ<14>")
	)
	(segment
		(start 436.368444 -213.910164)
		(end 436.6133 -213.910164)
		(width 0.14478)
		(layer "In11.Cu")
		(net "M_L_CPU0_SA_DQ<14>")
	)
	(segment
		(start 395.825472 -231.380792)
		(end 402.224748 -224.981516)
		(width 0.14478)
		(layer "In11.Cu")
		(net "M_L_CPU0_SA_DQ<14>")
	)
	(segment
		(start 436.223664 -213.676992)
		(end 436.223664 -213.765384)
		(width 0.14478)
		(layer "In11.Cu")
		(net "M_L_CPU0_SA_DQ<14>")
	)
	(segment
		(start 437.981344 -212.678772)
		(end 438.243218 -212.678772)
		(width 0.14478)
		(layer "In11.Cu")
		(net "M_L_CPU0_SA_DQ<14>")
	)
	(segment
		(start 445.298576 -213.295992)
		(end 445.443356 -213.440772)
		(width 0.14478)
		(layer "In11.Cu")
		(net "M_L_CPU0_SA_DQ<14>")
	)
	(segment
		(start 447.260218 -213.06028)
		(end 447.404998 -212.9155)
		(width 0.14478)
		(layer "In11.Cu")
		(net "M_L_CPU0_SA_DQ<14>")
	)
	(segment
		(start 391.01776 -233.631486)
		(end 391.026142 -233.62666)
		(width 0.0889)
		(layer "In11.Cu")
		(net "M_L_CPU0_SA_DQ<14>")
	)
	(segment
		(start 438.532778 -213.06028)
		(end 439.477912 -213.06028)
		(width 0.14478)
		(layer "In11.Cu")
		(net "M_L_CPU0_SA_DQ<14>")
	)
	(segment
		(start 445.85001 -213.295992)
		(end 445.85001 -213.20506)
		(width 0.14478)
		(layer "In11.Cu")
		(net "M_L_CPU0_SA_DQ<14>")
	)
	(segment
		(start 444.20282 -213.910164)
		(end 445.052704 -213.06028)
		(width 0.14478)
		(layer "In11.Cu")
		(net "M_L_CPU0_SA_DQ<14>")
	)
	(segment
		(start 435.67223 -213.676992)
		(end 435.81701 -213.532212)
		(width 0.14478)
		(layer "In11.Cu")
		(net "M_L_CPU0_SA_DQ<14>")
	)
	(arc
		(start 391.970768 -233.623866)
		(mid 392.151698 -233.581388)
		(end 392.330686 -233.631486)
		(width 0.0889)
		(layer "In11.Cu")
		(net "M_L_CPU0_SA_DQ<14>")
	)
	(arc
		(start 391.026142 -233.62666)
		(mid 391.20965 -233.581166)
		(end 391.391902 -233.631486)
		(width 0.0889)
		(layer "In11.Cu")
		(net "M_L_CPU0_SA_DQ<14>")
	)
	(arc
		(start 387.31317 -233.605324)
		(mid 387.475502 -233.582506)
		(end 387.63194 -233.631486)
		(width 0.0889)
		(layer "In11.Cu")
		(net "M_L_CPU0_SA_DQ<14>")
	)
	(arc
		(start 390.077706 -233.631486)
		(mid 390.259957 -233.581136)
		(end 390.443466 -233.62666)
		(width 0.0889)
		(layer "In11.Cu")
		(net "M_L_CPU0_SA_DQ<14>")
	)
	(arc
		(start 387.63194 -233.631486)
		(mid 387.914896 -233.707663)
		(end 388.197852 -233.631486)
		(width 0.0889)
		(layer "In11.Cu")
		(net "M_L_CPU0_SA_DQ<14>")
	)
	(arc
		(start 390.451848 -233.631486)
		(mid 390.734804 -233.707663)
		(end 391.01776 -233.631486)
		(width 0.0889)
		(layer "In11.Cu")
		(net "M_L_CPU0_SA_DQ<14>")
	)
	(arc
		(start 391.391902 -233.631486)
		(mid 391.66758 -233.707616)
		(end 391.945114 -233.638598)
		(width 0.0889)
		(layer "In11.Cu")
		(net "M_L_CPU0_SA_DQ<14>")
	)
	(arc
		(start 388.206234 -233.62666)
		(mid 388.389742 -233.581166)
		(end 388.571994 -233.631486)
		(width 0.0889)
		(layer "In11.Cu")
		(net "M_L_CPU0_SA_DQ<14>")
	)
	(arc
		(start 389.137906 -233.631486)
		(mid 389.32485 -233.581231)
		(end 389.511794 -233.631486)
		(width 0.0889)
		(layer "In11.Cu")
		(net "M_L_CPU0_SA_DQ<14>")
	)
	(arc
		(start 388.571994 -233.631486)
		(mid 388.85495 -233.707663)
		(end 389.137906 -233.631486)
		(width 0.0889)
		(layer "In11.Cu")
		(net "M_L_CPU0_SA_DQ<14>")
	)
	(arc
		(start 389.511794 -233.631486)
		(mid 389.79475 -233.707663)
		(end 390.077706 -233.631486)
		(width 0.0889)
		(layer "In11.Cu")
		(net "M_L_CPU0_SA_DQ<14>")
	)
	(arc
		(start 392.89736 -233.631486)
		(mid 392.986533 -233.594279)
		(end 393.082272 -233.581194)
		(width 0.0889)
		(layer "In11.Cu")
		(net "M_L_CPU0_SA_DQ<14>")
	)
	(arc
		(start 392.34872 -233.642154)
		(mid 392.624415 -233.707997)
		(end 392.89736 -233.631486)
		(width 0.0889)
		(layer "In11.Cu")
		(net "M_L_CPU0_SA_DQ<14>")
	)
	(segment
		(start 385.098036 -234.220004)
		(end 385.564888 -233.954066)
		(width 0.10668)
		(layer "F.Cu")
		(net "M_L_CPU0_SA_DQ<13>")
	)
	(segment
		(start 392.897868 -234.276646)
		(end 392.90625 -234.281472)
		(width 0.0889)
		(layer "In11.Cu")
		(net "M_L_CPU0_SA_DQ<13>")
	)
	(segment
		(start 392.887454 -234.27055)
		(end 392.897868 -234.276646)
		(width 0.0889)
		(layer "In11.Cu")
		(net "M_L_CPU0_SA_DQ<13>")
	)
	(segment
		(start 452.047864 -213.910164)
		(end 452.210932 -214.073232)
		(width 0.14478)
		(layer "In11.Cu")
		(net "M_L_CPU0_SA_DQ<13>")
	)
	(segment
		(start 425.912534 -213.910164)
		(end 426.762418 -214.760048)
		(width 0.14478)
		(layer "In11.Cu")
		(net "M_L_CPU0_SA_DQ<13>")
	)
	(segment
		(start 421.45966 -214.760048)
		(end 422.309544 -213.910164)
		(width 0.14478)
		(layer "In11.Cu")
		(net "M_L_CPU0_SA_DQ<13>")
	)
	(segment
		(start 437.463184 -213.910164)
		(end 440.602116 -213.910164)
		(width 0.14478)
		(layer "In11.Cu")
		(net "M_L_CPU0_SA_DQ<13>")
	)
	(segment
		(start 452.604378 -214.49411)
		(end 452.767446 -214.331042)
		(width 0.14478)
		(layer "In11.Cu")
		(net "M_L_CPU0_SA_DQ<13>")
	)
	(segment
		(start 388.197852 -234.276646)
		(end 388.206234 -234.281472)
		(width 0.0889)
		(layer "In11.Cu")
		(net "M_L_CPU0_SA_DQ<13>")
	)
	(segment
		(start 394.308838 -233.273092)
		(end 395.675358 -231.906572)
		(width 0.0889)
		(layer "In11.Cu")
		(net "M_L_CPU0_SA_DQ<13>")
	)
	(segment
		(start 452.210932 -214.331042)
		(end 452.374 -214.49411)
		(width 0.14478)
		(layer "In11.Cu")
		(net "M_L_CPU0_SA_DQ<13>")
	)
	(segment
		(start 453.763126 -213.910164)
		(end 454.188068 -214.335106)
		(width 0.14478)
		(layer "In11.Cu")
		(net "M_L_CPU0_SA_DQ<13>")
	)
	(segment
		(start 434.040788 -214.760048)
		(end 436.6133 -214.760048)
		(width 0.14478)
		(layer "In11.Cu")
		(net "M_L_CPU0_SA_DQ<13>")
	)
	(segment
		(start 428.941992 -214.760048)
		(end 429.791876 -213.910164)
		(width 0.14478)
		(layer "In11.Cu")
		(net "M_L_CPU0_SA_DQ<13>")
	)
	(segment
		(start 396.194788 -231.654604)
		(end 402.679408 -225.169984)
		(width 0.14478)
		(layer "In11.Cu")
		(net "M_L_CPU0_SA_DQ<13>")
	)
	(segment
		(start 413.685482 -214.760048)
		(end 414.535366 -213.910164)
		(width 0.14478)
		(layer "In11.Cu")
		(net "M_L_CPU0_SA_DQ<13>")
	)
	(segment
		(start 385.564888 -233.954066)
		(end 385.718812 -234.219496)
		(width 0.0889)
		(layer "In11.Cu")
		(net "M_L_CPU0_SA_DQ<13>")
	)
	(segment
		(start 394.308838 -233.628692)
		(end 394.308838 -233.273092)
		(width 0.0889)
		(layer "In11.Cu")
		(net "M_L_CPU0_SA_DQ<13>")
	)
	(segment
		(start 444.063882 -214.758778)
		(end 444.912496 -213.910164)
		(width 0.14478)
		(layer "In11.Cu")
		(net "M_L_CPU0_SA_DQ<13>")
	)
	(segment
		(start 441.45073 -214.758778)
		(end 444.063882 -214.758778)
		(width 0.14478)
		(layer "In11.Cu")
		(net "M_L_CPU0_SA_DQ<13>")
	)
	(segment
		(start 436.6133 -214.760048)
		(end 437.463184 -213.910164)
		(width 0.14478)
		(layer "In11.Cu")
		(net "M_L_CPU0_SA_DQ<13>")
	)
	(segment
		(start 385.718812 -234.219496)
		(end 385.814824 -234.244896)
		(width 0.0889)
		(layer "In11.Cu")
		(net "M_L_CPU0_SA_DQ<13>")
	)
	(segment
		(start 422.309544 -213.910164)
		(end 425.912534 -213.910164)
		(width 0.14478)
		(layer "In11.Cu")
		(net "M_L_CPU0_SA_DQ<13>")
	)
	(segment
		(start 392.323828 -234.281472)
		(end 392.33221 -234.276646)
		(width 0.0889)
		(layer "In11.Cu")
		(net "M_L_CPU0_SA_DQ<13>")
	)
	(segment
		(start 418.331396 -213.910164)
		(end 419.18128 -214.760048)
		(width 0.14478)
		(layer "In11.Cu")
		(net "M_L_CPU0_SA_DQ<13>")
	)
	(segment
		(start 452.930514 -213.910164)
		(end 453.763126 -213.910164)
		(width 0.14478)
		(layer "In11.Cu")
		(net "M_L_CPU0_SA_DQ<13>")
	)
	(segment
		(start 390.443466 -234.281472)
		(end 390.451848 -234.276646)
		(width 0.0889)
		(layer "In11.Cu")
		(net "M_L_CPU0_SA_DQ<13>")
	)
	(segment
		(start 410.918406 -214.760048)
		(end 413.685482 -214.760048)
		(width 0.14478)
		(layer "In11.Cu")
		(net "M_L_CPU0_SA_DQ<13>")
	)
	(segment
		(start 407.820114 -217.85834)
		(end 410.918406 -214.760048)
		(width 0.14478)
		(layer "In11.Cu")
		(net "M_L_CPU0_SA_DQ<13>")
	)
	(segment
		(start 391.01776 -234.276646)
		(end 391.026142 -234.281472)
		(width 0.0889)
		(layer "In11.Cu")
		(net "M_L_CPU0_SA_DQ<13>")
	)
	(segment
		(start 426.762418 -214.760048)
		(end 428.941992 -214.760048)
		(width 0.14478)
		(layer "In11.Cu")
		(net "M_L_CPU0_SA_DQ<13>")
	)
	(segment
		(start 395.675358 -231.906572)
		(end 395.94282 -231.906572)
		(width 0.0889)
		(layer "In11.Cu")
		(net "M_L_CPU0_SA_DQ<13>")
	)
	(segment
		(start 407.820114 -219.001848)
		(end 407.820114 -217.85834)
		(width 0.14478)
		(layer "In11.Cu")
		(net "M_L_CPU0_SA_DQ<13>")
	)
	(segment
		(start 402.679408 -224.142554)
		(end 407.820114 -219.001848)
		(width 0.14478)
		(layer "In11.Cu")
		(net "M_L_CPU0_SA_DQ<13>")
	)
	(segment
		(start 452.210932 -214.073232)
		(end 452.210932 -214.331042)
		(width 0.14478)
		(layer "In11.Cu")
		(net "M_L_CPU0_SA_DQ<13>")
	)
	(segment
		(start 386.683504 -234.281472)
		(end 386.691886 -234.276646)
		(width 0.0889)
		(layer "In11.Cu")
		(net "M_L_CPU0_SA_DQ<13>")
	)
	(segment
		(start 391.391902 -234.276646)
		(end 391.402316 -234.27055)
		(width 0.0889)
		(layer "In11.Cu")
		(net "M_L_CPU0_SA_DQ<13>")
	)
	(segment
		(start 387.257798 -234.276646)
		(end 387.26618 -234.281472)
		(width 0.0889)
		(layer "In11.Cu")
		(net "M_L_CPU0_SA_DQ<13>")
	)
	(segment
		(start 419.18128 -214.760048)
		(end 421.45966 -214.760048)
		(width 0.14478)
		(layer "In11.Cu")
		(net "M_L_CPU0_SA_DQ<13>")
	)
	(segment
		(start 452.374 -214.49411)
		(end 452.604378 -214.49411)
		(width 0.14478)
		(layer "In11.Cu")
		(net "M_L_CPU0_SA_DQ<13>")
	)
	(segment
		(start 414.535366 -213.910164)
		(end 418.331396 -213.910164)
		(width 0.14478)
		(layer "In11.Cu")
		(net "M_L_CPU0_SA_DQ<13>")
	)
	(segment
		(start 452.767446 -214.331042)
		(end 452.767446 -214.073232)
		(width 0.14478)
		(layer "In11.Cu")
		(net "M_L_CPU0_SA_DQ<13>")
	)
	(segment
		(start 444.912496 -213.910164)
		(end 452.047864 -213.910164)
		(width 0.14478)
		(layer "In11.Cu")
		(net "M_L_CPU0_SA_DQ<13>")
	)
	(segment
		(start 393.737338 -234.200192)
		(end 394.308838 -233.628692)
		(width 0.0889)
		(layer "In11.Cu")
		(net "M_L_CPU0_SA_DQ<13>")
	)
	(segment
		(start 429.791876 -213.910164)
		(end 433.190904 -213.910164)
		(width 0.14478)
		(layer "In11.Cu")
		(net "M_L_CPU0_SA_DQ<13>")
	)
	(segment
		(start 393.55522 -234.200192)
		(end 393.737338 -234.200192)
		(width 0.0889)
		(layer "In11.Cu")
		(net "M_L_CPU0_SA_DQ<13>")
	)
	(segment
		(start 402.679408 -225.169984)
		(end 402.679408 -224.142554)
		(width 0.14478)
		(layer "In11.Cu")
		(net "M_L_CPU0_SA_DQ<13>")
	)
	(segment
		(start 440.602116 -213.910164)
		(end 441.45073 -214.758778)
		(width 0.14478)
		(layer "In11.Cu")
		(net "M_L_CPU0_SA_DQ<13>")
	)
	(segment
		(start 395.94282 -231.906572)
		(end 396.194788 -231.654604)
		(width 0.0889)
		(layer "In11.Cu")
		(net "M_L_CPU0_SA_DQ<13>")
	)
	(segment
		(start 452.767446 -214.073232)
		(end 452.930514 -213.910164)
		(width 0.14478)
		(layer "In11.Cu")
		(net "M_L_CPU0_SA_DQ<13>")
	)
	(segment
		(start 433.190904 -213.910164)
		(end 434.040788 -214.760048)
		(width 0.14478)
		(layer "In11.Cu")
		(net "M_L_CPU0_SA_DQ<13>")
	)
	(arc
		(start 392.90625 -234.281472)
		(mid 393.089758 -234.326966)
		(end 393.27201 -234.276646)
		(width 0.0889)
		(layer "In11.Cu")
		(net "M_L_CPU0_SA_DQ<13>")
	)
	(arc
		(start 388.571994 -234.276646)
		(mid 388.85495 -234.200469)
		(end 389.137906 -234.276646)
		(width 0.0889)
		(layer "In11.Cu")
		(net "M_L_CPU0_SA_DQ<13>")
	)
	(arc
		(start 388.206234 -234.281472)
		(mid 388.389742 -234.326966)
		(end 388.571994 -234.276646)
		(width 0.0889)
		(layer "In11.Cu")
		(net "M_L_CPU0_SA_DQ<13>")
	)
	(arc
		(start 386.691886 -234.276646)
		(mid 386.974842 -234.200469)
		(end 387.257798 -234.276646)
		(width 0.0889)
		(layer "In11.Cu")
		(net "M_L_CPU0_SA_DQ<13>")
	)
	(arc
		(start 387.26618 -234.281472)
		(mid 387.449688 -234.326966)
		(end 387.63194 -234.276646)
		(width 0.0889)
		(layer "In11.Cu")
		(net "M_L_CPU0_SA_DQ<13>")
	)
	(arc
		(start 387.63194 -234.276646)
		(mid 387.914896 -234.200469)
		(end 388.197852 -234.276646)
		(width 0.0889)
		(layer "In11.Cu")
		(net "M_L_CPU0_SA_DQ<13>")
	)
	(arc
		(start 391.026142 -234.281472)
		(mid 391.20965 -234.326966)
		(end 391.391902 -234.276646)
		(width 0.0889)
		(layer "In11.Cu")
		(net "M_L_CPU0_SA_DQ<13>")
	)
	(arc
		(start 389.137906 -234.276646)
		(mid 389.32485 -234.326901)
		(end 389.511794 -234.276646)
		(width 0.0889)
		(layer "In11.Cu")
		(net "M_L_CPU0_SA_DQ<13>")
	)
	(arc
		(start 391.958068 -234.276646)
		(mid 392.140319 -234.326996)
		(end 392.323828 -234.281472)
		(width 0.0889)
		(layer "In11.Cu")
		(net "M_L_CPU0_SA_DQ<13>")
	)
	(arc
		(start 389.511794 -234.276646)
		(mid 389.79475 -234.200469)
		(end 390.077706 -234.276646)
		(width 0.0889)
		(layer "In11.Cu")
		(net "M_L_CPU0_SA_DQ<13>")
	)
	(arc
		(start 385.814824 -234.244896)
		(mid 386.070032 -234.201419)
		(end 386.317744 -234.276646)
		(width 0.0889)
		(layer "In11.Cu")
		(net "M_L_CPU0_SA_DQ<13>")
	)
	(arc
		(start 386.317744 -234.276646)
		(mid 386.499995 -234.326996)
		(end 386.683504 -234.281472)
		(width 0.0889)
		(layer "In11.Cu")
		(net "M_L_CPU0_SA_DQ<13>")
	)
	(arc
		(start 390.077706 -234.276646)
		(mid 390.259957 -234.326996)
		(end 390.443466 -234.281472)
		(width 0.0889)
		(layer "In11.Cu")
		(net "M_L_CPU0_SA_DQ<13>")
	)
	(arc
		(start 390.451848 -234.276646)
		(mid 390.734804 -234.200469)
		(end 391.01776 -234.276646)
		(width 0.0889)
		(layer "In11.Cu")
		(net "M_L_CPU0_SA_DQ<13>")
	)
	(arc
		(start 392.33221 -234.276646)
		(mid 392.609023 -234.200503)
		(end 392.887454 -234.27055)
		(width 0.0889)
		(layer "In11.Cu")
		(net "M_L_CPU0_SA_DQ<13>")
	)
	(arc
		(start 393.27201 -234.276646)
		(mid 393.408558 -234.21969)
		(end 393.55522 -234.200192)
		(width 0.0889)
		(layer "In11.Cu")
		(net "M_L_CPU0_SA_DQ<13>")
	)
	(arc
		(start 391.402316 -234.27055)
		(mid 391.681002 -234.20033)
		(end 391.958068 -234.276646)
		(width 0.0889)
		(layer "In11.Cu")
		(net "M_L_CPU0_SA_DQ<13>")
	)
	(segment
		(start 386.50799 -233.409998)
		(end 386.974842 -233.14406)
		(width 0.10668)
		(layer "F.Cu")
		(net "M_L_CPU0_SA_DQ<12>")
	)
	(segment
		(start 453.278494 -212.210142)
		(end 453.763126 -212.210142)
		(width 0.14478)
		(layer "In11.Cu")
		(net "M_L_CPU0_SA_DQ<12>")
	)
	(segment
		(start 394.415518 -232.320592)
		(end 394.661898 -232.320592)
		(width 0.0889)
		(layer "In11.Cu")
		(net "M_L_CPU0_SA_DQ<12>")
	)
	(segment
		(start 453.763126 -212.210142)
		(end 454.188068 -212.635084)
		(width 0.14478)
		(layer "In11.Cu")
		(net "M_L_CPU0_SA_DQ<12>")
	)
	(segment
		(start 389.607806 -233.46664)
		(end 389.616188 -233.471466)
		(width 0.0889)
		(layer "In11.Cu")
		(net "M_L_CPU0_SA_DQ<12>")
	)
	(segment
		(start 422.381934 -212.21954)
		(end 425.855892 -212.21954)
		(width 0.14478)
		(layer "In11.Cu")
		(net "M_L_CPU0_SA_DQ<12>")
	)
	(segment
		(start 395.802104 -230.761286)
		(end 401.770088 -224.793302)
		(width 0.14478)
		(layer "In11.Cu")
		(net "M_L_CPU0_SA_DQ<12>")
	)
	(segment
		(start 393.846558 -233.041952)
		(end 393.846558 -232.889552)
		(width 0.0889)
		(layer "In11.Cu")
		(net "M_L_CPU0_SA_DQ<12>")
	)
	(segment
		(start 391.861548 -233.466386)
		(end 391.873486 -233.459528)
		(width 0.0889)
		(layer "In11.Cu")
		(net "M_L_CPU0_SA_DQ<12>")
	)
	(segment
		(start 452.952358 -213.17331)
		(end 453.115426 -213.010242)
		(width 0.14478)
		(layer "In11.Cu")
		(net "M_L_CPU0_SA_DQ<12>")
	)
	(segment
		(start 414.025588 -213.060026)
		(end 414.866074 -212.21954)
		(width 0.14478)
		(layer "In11.Cu")
		(net "M_L_CPU0_SA_DQ<12>")
	)
	(segment
		(start 452.558912 -213.010242)
		(end 452.72198 -213.17331)
		(width 0.14478)
		(layer "In11.Cu")
		(net "M_L_CPU0_SA_DQ<12>")
	)
	(segment
		(start 444.288926 -213.069424)
		(end 445.13881 -212.21954)
		(width 0.14478)
		(layer "In11.Cu")
		(net "M_L_CPU0_SA_DQ<12>")
	)
	(segment
		(start 388.093458 -233.471466)
		(end 388.10184 -233.46664)
		(width 0.0889)
		(layer "In11.Cu")
		(net "M_L_CPU0_SA_DQ<12>")
	)
	(segment
		(start 434.050186 -213.069424)
		(end 436.603902 -213.069424)
		(width 0.14478)
		(layer "In11.Cu")
		(net "M_L_CPU0_SA_DQ<12>")
	)
	(segment
		(start 445.13881 -212.21954)
		(end 452.405242 -212.21954)
		(width 0.14478)
		(layer "In11.Cu")
		(net "M_L_CPU0_SA_DQ<12>")
	)
	(segment
		(start 414.866074 -212.21954)
		(end 418.289232 -212.21954)
		(width 0.14478)
		(layer "In11.Cu")
		(net "M_L_CPU0_SA_DQ<12>")
	)
	(segment
		(start 395.042898 -231.520492)
		(end 395.802104 -230.761286)
		(width 0.0889)
		(layer "In11.Cu")
		(net "M_L_CPU0_SA_DQ<12>")
	)
	(segment
		(start 413.046418 -212.724492)
		(end 413.381952 -213.060026)
		(width 0.14478)
		(layer "In11.Cu")
		(net "M_L_CPU0_SA_DQ<12>")
	)
	(segment
		(start 440.552586 -212.21954)
		(end 441.40247 -213.069424)
		(width 0.14478)
		(layer "In11.Cu")
		(net "M_L_CPU0_SA_DQ<12>")
	)
	(segment
		(start 421.53205 -213.069424)
		(end 422.381934 -212.21954)
		(width 0.14478)
		(layer "In11.Cu")
		(net "M_L_CPU0_SA_DQ<12>")
	)
	(segment
		(start 393.49807 -233.39044)
		(end 393.846558 -233.041952)
		(width 0.0889)
		(layer "In11.Cu")
		(net "M_L_CPU0_SA_DQ<12>")
	)
	(segment
		(start 436.603902 -213.069424)
		(end 437.453786 -212.21954)
		(width 0.14478)
		(layer "In11.Cu")
		(net "M_L_CPU0_SA_DQ<12>")
	)
	(segment
		(start 394.661898 -232.320592)
		(end 395.042898 -231.939592)
		(width 0.0889)
		(layer "In11.Cu")
		(net "M_L_CPU0_SA_DQ<12>")
	)
	(segment
		(start 429.152558 -213.069424)
		(end 430.002442 -212.21954)
		(width 0.14478)
		(layer "In11.Cu")
		(net "M_L_CPU0_SA_DQ<12>")
	)
	(segment
		(start 441.40247 -213.069424)
		(end 444.288926 -213.069424)
		(width 0.14478)
		(layer "In11.Cu")
		(net "M_L_CPU0_SA_DQ<12>")
	)
	(segment
		(start 418.289232 -212.21954)
		(end 419.139116 -213.069424)
		(width 0.14478)
		(layer "In11.Cu")
		(net "M_L_CPU0_SA_DQ<12>")
	)
	(segment
		(start 391.845292 -233.475784)
		(end 391.861548 -233.466386)
		(width 0.0889)
		(layer "In11.Cu")
		(net "M_L_CPU0_SA_DQ<12>")
	)
	(segment
		(start 393.10183 -233.39044)
		(end 393.49807 -233.39044)
		(width 0.0889)
		(layer "In11.Cu")
		(net "M_L_CPU0_SA_DQ<12>")
	)
	(segment
		(start 406.845262 -218.604338)
		(end 406.845262 -217.546682)
		(width 0.14478)
		(layer "In11.Cu")
		(net "M_L_CPU0_SA_DQ<12>")
	)
	(segment
		(start 430.002442 -212.21954)
		(end 433.200302 -212.21954)
		(width 0.14478)
		(layer "In11.Cu")
		(net "M_L_CPU0_SA_DQ<12>")
	)
	(segment
		(start 453.115426 -213.010242)
		(end 453.115426 -212.37321)
		(width 0.14478)
		(layer "In11.Cu")
		(net "M_L_CPU0_SA_DQ<12>")
	)
	(segment
		(start 452.72198 -213.17331)
		(end 452.952358 -213.17331)
		(width 0.14478)
		(layer "In11.Cu")
		(net "M_L_CPU0_SA_DQ<12>")
	)
	(segment
		(start 419.139116 -213.069424)
		(end 421.53205 -213.069424)
		(width 0.14478)
		(layer "In11.Cu")
		(net "M_L_CPU0_SA_DQ<12>")
	)
	(segment
		(start 386.974842 -233.14406)
		(end 387.128766 -233.40949)
		(width 0.0889)
		(layer "In11.Cu")
		(net "M_L_CPU0_SA_DQ<12>")
	)
	(segment
		(start 437.453786 -212.21954)
		(end 440.552586 -212.21954)
		(width 0.14478)
		(layer "In11.Cu")
		(net "M_L_CPU0_SA_DQ<12>")
	)
	(segment
		(start 395.042898 -231.939592)
		(end 395.042898 -231.520492)
		(width 0.0889)
		(layer "In11.Cu")
		(net "M_L_CPU0_SA_DQ<12>")
	)
	(segment
		(start 387.128766 -233.40949)
		(end 387.224778 -233.43489)
		(width 0.0889)
		(layer "In11.Cu")
		(net "M_L_CPU0_SA_DQ<12>")
	)
	(segment
		(start 389.033512 -233.471466)
		(end 389.041894 -233.46664)
		(width 0.0889)
		(layer "In11.Cu")
		(net "M_L_CPU0_SA_DQ<12>")
	)
	(segment
		(start 392.426698 -233.46664)
		(end 392.438382 -233.473498)
		(width 0.0889)
		(layer "In11.Cu")
		(net "M_L_CPU0_SA_DQ<12>")
	)
	(segment
		(start 453.115426 -212.37321)
		(end 453.278494 -212.210142)
		(width 0.14478)
		(layer "In11.Cu")
		(net "M_L_CPU0_SA_DQ<12>")
	)
	(segment
		(start 426.705776 -213.069424)
		(end 429.152558 -213.069424)
		(width 0.14478)
		(layer "In11.Cu")
		(net "M_L_CPU0_SA_DQ<12>")
	)
	(segment
		(start 425.855892 -212.21954)
		(end 426.705776 -213.069424)
		(width 0.14478)
		(layer "In11.Cu")
		(net "M_L_CPU0_SA_DQ<12>")
	)
	(segment
		(start 393.846558 -232.889552)
		(end 394.415518 -232.320592)
		(width 0.0889)
		(layer "In11.Cu")
		(net "M_L_CPU0_SA_DQ<12>")
	)
	(segment
		(start 433.200302 -212.21954)
		(end 434.050186 -213.069424)
		(width 0.14478)
		(layer "In11.Cu")
		(net "M_L_CPU0_SA_DQ<12>")
	)
	(segment
		(start 452.558912 -212.37321)
		(end 452.558912 -213.010242)
		(width 0.14478)
		(layer "In11.Cu")
		(net "M_L_CPU0_SA_DQ<12>")
	)
	(segment
		(start 452.405242 -212.21954)
		(end 452.558912 -212.37321)
		(width 0.14478)
		(layer "In11.Cu")
		(net "M_L_CPU0_SA_DQ<12>")
	)
	(segment
		(start 401.770088 -223.679512)
		(end 406.845262 -218.604338)
		(width 0.14478)
		(layer "In11.Cu")
		(net "M_L_CPU0_SA_DQ<12>")
	)
	(segment
		(start 401.770088 -224.793302)
		(end 401.770088 -223.679512)
		(width 0.14478)
		(layer "In11.Cu")
		(net "M_L_CPU0_SA_DQ<12>")
	)
	(segment
		(start 413.381952 -213.060026)
		(end 414.025588 -213.060026)
		(width 0.14478)
		(layer "In11.Cu")
		(net "M_L_CPU0_SA_DQ<12>")
	)
	(segment
		(start 411.667452 -212.724492)
		(end 413.046418 -212.724492)
		(width 0.14478)
		(layer "In11.Cu")
		(net "M_L_CPU0_SA_DQ<12>")
	)
	(segment
		(start 406.845262 -217.546682)
		(end 411.667452 -212.724492)
		(width 0.14478)
		(layer "In11.Cu")
		(net "M_L_CPU0_SA_DQ<12>")
	)
	(arc
		(start 387.224778 -233.43489)
		(mid 387.479986 -233.391413)
		(end 387.727698 -233.46664)
		(width 0.0889)
		(layer "In11.Cu")
		(net "M_L_CPU0_SA_DQ<12>")
	)
	(arc
		(start 392.801094 -233.46664)
		(mid 392.94612 -233.407467)
		(end 393.10183 -233.39044)
		(width 0.0889)
		(layer "In11.Cu")
		(net "M_L_CPU0_SA_DQ<12>")
	)
	(arc
		(start 391.48766 -233.46664)
		(mid 391.66531 -233.5169)
		(end 391.845292 -233.475784)
		(width 0.0889)
		(layer "In11.Cu")
		(net "M_L_CPU0_SA_DQ<12>")
	)
	(arc
		(start 388.10184 -233.46664)
		(mid 388.384796 -233.390463)
		(end 388.667752 -233.46664)
		(width 0.0889)
		(layer "In11.Cu")
		(net "M_L_CPU0_SA_DQ<12>")
	)
	(arc
		(start 392.438382 -233.473498)
		(mid 392.620637 -233.517151)
		(end 392.801094 -233.46664)
		(width 0.0889)
		(layer "In11.Cu")
		(net "M_L_CPU0_SA_DQ<12>")
	)
	(arc
		(start 390.54786 -233.46664)
		(mid 390.734804 -233.516895)
		(end 390.921748 -233.46664)
		(width 0.0889)
		(layer "In11.Cu")
		(net "M_L_CPU0_SA_DQ<12>")
	)
	(arc
		(start 391.873486 -233.459528)
		(mid 392.15102 -233.390547)
		(end 392.426698 -233.46664)
		(width 0.0889)
		(layer "In11.Cu")
		(net "M_L_CPU0_SA_DQ<12>")
	)
	(arc
		(start 390.921748 -233.46664)
		(mid 391.204704 -233.390463)
		(end 391.48766 -233.46664)
		(width 0.0889)
		(layer "In11.Cu")
		(net "M_L_CPU0_SA_DQ<12>")
	)
	(arc
		(start 389.041894 -233.46664)
		(mid 389.32485 -233.390463)
		(end 389.607806 -233.46664)
		(width 0.0889)
		(layer "In11.Cu")
		(net "M_L_CPU0_SA_DQ<12>")
	)
	(arc
		(start 387.727698 -233.46664)
		(mid 387.909949 -233.51699)
		(end 388.093458 -233.471466)
		(width 0.0889)
		(layer "In11.Cu")
		(net "M_L_CPU0_SA_DQ<12>")
	)
	(arc
		(start 389.616188 -233.471466)
		(mid 389.799696 -233.51696)
		(end 389.981948 -233.46664)
		(width 0.0889)
		(layer "In11.Cu")
		(net "M_L_CPU0_SA_DQ<12>")
	)
	(arc
		(start 388.667752 -233.46664)
		(mid 388.850003 -233.51699)
		(end 389.033512 -233.471466)
		(width 0.0889)
		(layer "In11.Cu")
		(net "M_L_CPU0_SA_DQ<12>")
	)
	(arc
		(start 389.981948 -233.46664)
		(mid 390.264904 -233.390463)
		(end 390.54786 -233.46664)
		(width 0.0889)
		(layer "In11.Cu")
		(net "M_L_CPU0_SA_DQ<12>")
	)
	(segment
		(start 385.567936 -231.789986)
		(end 386.034788 -231.524048)
		(width 0.10668)
		(layer "F.Cu")
		(net "M_L_CPU0_SA_DQ<11>")
	)
	(segment
		(start 410.913072 -210.120992)
		(end 411.374082 -209.659982)
		(width 0.14478)
		(layer "In11.Cu")
		(net "M_L_CPU0_SA_DQ<11>")
	)
	(segment
		(start 408.751024 -212.101176)
		(end 408.493722 -211.843874)
		(width 0.14478)
		(layer "In11.Cu")
		(net "M_L_CPU0_SA_DQ<11>")
	)
	(segment
		(start 449.187062 -209.176112)
		(end 449.187062 -208.945734)
		(width 0.14478)
		(layer "In11.Cu")
		(net "M_L_CPU0_SA_DQ<11>")
	)
	(segment
		(start 393.572238 -230.776272)
		(end 393.572238 -230.110792)
		(width 0.0889)
		(layer "In11.Cu")
		(net "M_L_CPU0_SA_DQ<11>")
	)
	(segment
		(start 421.526462 -209.650584)
		(end 422.376346 -208.8007)
		(width 0.14478)
		(layer "In11.Cu")
		(net "M_L_CPU0_SA_DQ<11>")
	)
	(segment
		(start 388.093458 -231.196896)
		(end 388.10184 -231.201722)
		(width 0.0889)
		(layer "In11.Cu")
		(net "M_L_CPU0_SA_DQ<11>")
	)
	(segment
		(start 409.538424 -211.313776)
		(end 409.281122 -211.056474)
		(width 0.14478)
		(layer "In11.Cu")
		(net "M_L_CPU0_SA_DQ<11>")
	)
	(segment
		(start 448.635628 -208.945734)
		(end 448.635628 -209.176112)
		(width 0.14478)
		(layer "In11.Cu")
		(net "M_L_CPU0_SA_DQ<11>")
	)
	(segment
		(start 422.376346 -208.8007)
		(end 425.653962 -208.8007)
		(width 0.14478)
		(layer "In11.Cu")
		(net "M_L_CPU0_SA_DQ<11>")
	)
	(segment
		(start 394.232638 -229.219252)
		(end 394.959078 -228.492812)
		(width 0.0889)
		(layer "In11.Cu")
		(net "M_L_CPU0_SA_DQ<11>")
	)
	(segment
		(start 409.144724 -211.707476)
		(end 409.375356 -211.707476)
		(width 0.14478)
		(layer "In11.Cu")
		(net "M_L_CPU0_SA_DQ<11>")
	)
	(segment
		(start 408.751024 -212.331808)
		(end 408.751024 -212.101176)
		(width 0.14478)
		(layer "In11.Cu")
		(net "M_L_CPU0_SA_DQ<11>")
	)
	(segment
		(start 448.635628 -209.176112)
		(end 448.780408 -209.320892)
		(width 0.14478)
		(layer "In11.Cu")
		(net "M_L_CPU0_SA_DQ<11>")
	)
	(segment
		(start 409.281122 -210.825842)
		(end 409.44419 -210.662774)
		(width 0.14478)
		(layer "In11.Cu")
		(net "M_L_CPU0_SA_DQ<11>")
	)
	(segment
		(start 408.493722 -211.613242)
		(end 408.65679 -211.450174)
		(width 0.14478)
		(layer "In11.Cu")
		(net "M_L_CPU0_SA_DQ<11>")
	)
	(segment
		(start 410.068522 -210.269074)
		(end 410.068522 -210.038442)
		(width 0.14478)
		(layer "In11.Cu")
		(net "M_L_CPU0_SA_DQ<11>")
	)
	(segment
		(start 409.932124 -210.920076)
		(end 410.162756 -210.920076)
		(width 0.14478)
		(layer "In11.Cu")
		(net "M_L_CPU0_SA_DQ<11>")
	)
	(segment
		(start 409.281122 -211.056474)
		(end 409.281122 -210.825842)
		(width 0.14478)
		(layer "In11.Cu")
		(net "M_L_CPU0_SA_DQ<11>")
	)
	(segment
		(start 393.572238 -230.110792)
		(end 394.232638 -229.450392)
		(width 0.0889)
		(layer "In11.Cu")
		(net "M_L_CPU0_SA_DQ<11>")
	)
	(segment
		(start 426.503846 -209.650584)
		(end 428.940468 -209.650584)
		(width 0.14478)
		(layer "In11.Cu")
		(net "M_L_CPU0_SA_DQ<11>")
	)
	(segment
		(start 409.44419 -210.662774)
		(end 409.674822 -210.662774)
		(width 0.14478)
		(layer "In11.Cu")
		(net "M_L_CPU0_SA_DQ<11>")
	)
	(segment
		(start 389.607806 -231.201722)
		(end 389.616188 -231.196896)
		(width 0.0889)
		(layer "In11.Cu")
		(net "M_L_CPU0_SA_DQ<11>")
	)
	(segment
		(start 449.331842 -208.800954)
		(end 449.653914 -208.800954)
		(width 0.14478)
		(layer "In11.Cu")
		(net "M_L_CPU0_SA_DQ<11>")
	)
	(segment
		(start 443.936882 -209.650838)
		(end 444.786766 -208.800954)
		(width 0.14478)
		(layer "In11.Cu")
		(net "M_L_CPU0_SA_DQ<11>")
	)
	(segment
		(start 410.70784 -210.120992)
		(end 410.913072 -210.120992)
		(width 0.14478)
		(layer "In11.Cu")
		(net "M_L_CPU0_SA_DQ<11>")
	)
	(segment
		(start 395.772386 -227.355908)
		(end 399.34769 -223.780604)
		(width 0.14478)
		(layer "In11.Cu")
		(net "M_L_CPU0_SA_DQ<11>")
	)
	(segment
		(start 433.229258 -208.800954)
		(end 434.079142 -209.650838)
		(width 0.14478)
		(layer "In11.Cu")
		(net "M_L_CPU0_SA_DQ<11>")
	)
	(segment
		(start 399.34769 -223.780604)
		(end 399.34769 -221.735142)
		(width 0.14478)
		(layer "In11.Cu")
		(net "M_L_CPU0_SA_DQ<11>")
	)
	(segment
		(start 428.940468 -209.650584)
		(end 429.790098 -208.800954)
		(width 0.14478)
		(layer "In11.Cu")
		(net "M_L_CPU0_SA_DQ<11>")
	)
	(segment
		(start 409.538424 -211.544408)
		(end 409.538424 -211.313776)
		(width 0.14478)
		(layer "In11.Cu")
		(net "M_L_CPU0_SA_DQ<11>")
	)
	(segment
		(start 410.325824 -210.757008)
		(end 410.325824 -210.526376)
		(width 0.14478)
		(layer "In11.Cu")
		(net "M_L_CPU0_SA_DQ<11>")
	)
	(segment
		(start 413.913574 -209.659982)
		(end 414.772856 -208.8007)
		(width 0.14478)
		(layer "In11.Cu")
		(net "M_L_CPU0_SA_DQ<11>")
	)
	(segment
		(start 392.210544 -231.274366)
		(end 393.074144 -231.274366)
		(width 0.0889)
		(layer "In11.Cu")
		(net "M_L_CPU0_SA_DQ<11>")
	)
	(segment
		(start 411.374082 -209.659982)
		(end 413.913574 -209.659982)
		(width 0.14478)
		(layer "In11.Cu")
		(net "M_L_CPU0_SA_DQ<11>")
	)
	(segment
		(start 449.653914 -208.800954)
		(end 450.088 -209.23504)
		(width 0.14478)
		(layer "In11.Cu")
		(net "M_L_CPU0_SA_DQ<11>")
	)
	(segment
		(start 410.23159 -209.875374)
		(end 410.462222 -209.875374)
		(width 0.14478)
		(layer "In11.Cu")
		(net "M_L_CPU0_SA_DQ<11>")
	)
	(segment
		(start 419.072568 -209.650584)
		(end 421.526462 -209.650584)
		(width 0.14478)
		(layer "In11.Cu")
		(net "M_L_CPU0_SA_DQ<11>")
	)
	(segment
		(start 410.068522 -210.038442)
		(end 410.23159 -209.875374)
		(width 0.14478)
		(layer "In11.Cu")
		(net "M_L_CPU0_SA_DQ<11>")
	)
	(segment
		(start 394.232638 -229.450392)
		(end 394.232638 -229.219252)
		(width 0.0889)
		(layer "In11.Cu")
		(net "M_L_CPU0_SA_DQ<11>")
	)
	(segment
		(start 441.947554 -209.650838)
		(end 443.936882 -209.650838)
		(width 0.14478)
		(layer "In11.Cu")
		(net "M_L_CPU0_SA_DQ<11>")
	)
	(segment
		(start 414.772856 -208.8007)
		(end 418.222684 -208.8007)
		(width 0.14478)
		(layer "In11.Cu")
		(net "M_L_CPU0_SA_DQ<11>")
	)
	(segment
		(start 418.222684 -208.8007)
		(end 419.072568 -209.650584)
		(width 0.14478)
		(layer "In11.Cu")
		(net "M_L_CPU0_SA_DQ<11>")
	)
	(segment
		(start 394.959078 -228.169216)
		(end 395.772386 -227.355908)
		(width 0.0889)
		(layer "In11.Cu")
		(net "M_L_CPU0_SA_DQ<11>")
	)
	(segment
		(start 436.622698 -209.650838)
		(end 437.472582 -208.800954)
		(width 0.14478)
		(layer "In11.Cu")
		(net "M_L_CPU0_SA_DQ<11>")
	)
	(segment
		(start 434.079142 -209.650838)
		(end 436.622698 -209.650838)
		(width 0.14478)
		(layer "In11.Cu")
		(net "M_L_CPU0_SA_DQ<11>")
	)
	(segment
		(start 409.674822 -210.662774)
		(end 409.932124 -210.920076)
		(width 0.14478)
		(layer "In11.Cu")
		(net "M_L_CPU0_SA_DQ<11>")
	)
	(segment
		(start 394.959078 -228.492812)
		(end 394.959078 -228.169216)
		(width 0.0889)
		(layer "In11.Cu")
		(net "M_L_CPU0_SA_DQ<11>")
	)
	(segment
		(start 410.325824 -210.526376)
		(end 410.068522 -210.269074)
		(width 0.14478)
		(layer "In11.Cu")
		(net "M_L_CPU0_SA_DQ<11>")
	)
	(segment
		(start 448.490848 -208.800954)
		(end 448.635628 -208.945734)
		(width 0.14478)
		(layer "In11.Cu")
		(net "M_L_CPU0_SA_DQ<11>")
	)
	(segment
		(start 409.375356 -211.707476)
		(end 409.538424 -211.544408)
		(width 0.14478)
		(layer "In11.Cu")
		(net "M_L_CPU0_SA_DQ<11>")
	)
	(segment
		(start 393.074144 -231.274366)
		(end 393.572238 -230.776272)
		(width 0.0889)
		(layer "In11.Cu")
		(net "M_L_CPU0_SA_DQ<11>")
	)
	(segment
		(start 410.162756 -210.920076)
		(end 410.325824 -210.757008)
		(width 0.14478)
		(layer "In11.Cu")
		(net "M_L_CPU0_SA_DQ<11>")
	)
	(segment
		(start 429.790098 -208.800954)
		(end 433.229258 -208.800954)
		(width 0.14478)
		(layer "In11.Cu")
		(net "M_L_CPU0_SA_DQ<11>")
	)
	(segment
		(start 408.65679 -211.450174)
		(end 408.887422 -211.450174)
		(width 0.14478)
		(layer "In11.Cu")
		(net "M_L_CPU0_SA_DQ<11>")
	)
	(segment
		(start 408.887422 -211.450174)
		(end 409.144724 -211.707476)
		(width 0.14478)
		(layer "In11.Cu")
		(net "M_L_CPU0_SA_DQ<11>")
	)
	(segment
		(start 441.09767 -208.800954)
		(end 441.947554 -209.650838)
		(width 0.14478)
		(layer "In11.Cu")
		(net "M_L_CPU0_SA_DQ<11>")
	)
	(segment
		(start 448.780408 -209.320892)
		(end 449.042282 -209.320892)
		(width 0.14478)
		(layer "In11.Cu")
		(net "M_L_CPU0_SA_DQ<11>")
	)
	(segment
		(start 408.493722 -211.843874)
		(end 408.493722 -211.613242)
		(width 0.14478)
		(layer "In11.Cu")
		(net "M_L_CPU0_SA_DQ<11>")
	)
	(segment
		(start 449.042282 -209.320892)
		(end 449.187062 -209.176112)
		(width 0.14478)
		(layer "In11.Cu")
		(net "M_L_CPU0_SA_DQ<11>")
	)
	(segment
		(start 389.033512 -231.196896)
		(end 389.041894 -231.201722)
		(width 0.0889)
		(layer "In11.Cu")
		(net "M_L_CPU0_SA_DQ<11>")
	)
	(segment
		(start 386.034788 -231.524048)
		(end 385.880864 -231.258618)
		(width 0.0889)
		(layer "In11.Cu")
		(net "M_L_CPU0_SA_DQ<11>")
	)
	(segment
		(start 449.187062 -208.945734)
		(end 449.331842 -208.800954)
		(width 0.14478)
		(layer "In11.Cu")
		(net "M_L_CPU0_SA_DQ<11>")
	)
	(segment
		(start 444.786766 -208.800954)
		(end 448.490848 -208.800954)
		(width 0.14478)
		(layer "In11.Cu")
		(net "M_L_CPU0_SA_DQ<11>")
	)
	(segment
		(start 437.472582 -208.800954)
		(end 441.09767 -208.800954)
		(width 0.14478)
		(layer "In11.Cu")
		(net "M_L_CPU0_SA_DQ<11>")
	)
	(segment
		(start 410.462222 -209.875374)
		(end 410.70784 -210.120992)
		(width 0.14478)
		(layer "In11.Cu")
		(net "M_L_CPU0_SA_DQ<11>")
	)
	(segment
		(start 425.653962 -208.8007)
		(end 426.503846 -209.650584)
		(width 0.14478)
		(layer "In11.Cu")
		(net "M_L_CPU0_SA_DQ<11>")
	)
	(segment
		(start 385.880864 -231.258618)
		(end 385.903216 -231.17556)
		(width 0.0889)
		(layer "In11.Cu")
		(net "M_L_CPU0_SA_DQ<11>")
	)
	(segment
		(start 399.34769 -221.735142)
		(end 408.751024 -212.331808)
		(width 0.14478)
		(layer "In11.Cu")
		(net "M_L_CPU0_SA_DQ<11>")
	)
	(arc
		(start 388.10184 -231.201722)
		(mid 388.384796 -231.277899)
		(end 388.667752 -231.201722)
		(width 0.0889)
		(layer "In11.Cu")
		(net "M_L_CPU0_SA_DQ<11>")
	)
	(arc
		(start 386.787898 -231.201722)
		(mid 386.974842 -231.151433)
		(end 387.161786 -231.201722)
		(width 0.0889)
		(layer "In11.Cu")
		(net "M_L_CPU0_SA_DQ<11>")
	)
	(arc
		(start 389.981948 -231.201722)
		(mid 390.264904 -231.277899)
		(end 390.54786 -231.201722)
		(width 0.0889)
		(layer "In11.Cu")
		(net "M_L_CPU0_SA_DQ<11>")
	)
	(arc
		(start 385.903216 -231.17556)
		(mid 386.065548 -231.152726)
		(end 386.221986 -231.201722)
		(width 0.0889)
		(layer "In11.Cu")
		(net "M_L_CPU0_SA_DQ<11>")
	)
	(arc
		(start 389.616188 -231.196896)
		(mid 389.799696 -231.151371)
		(end 389.981948 -231.201722)
		(width 0.0889)
		(layer "In11.Cu")
		(net "M_L_CPU0_SA_DQ<11>")
	)
	(arc
		(start 391.48766 -231.201722)
		(mid 391.674858 -231.151305)
		(end 391.862056 -231.201722)
		(width 0.0889)
		(layer "In11.Cu")
		(net "M_L_CPU0_SA_DQ<11>")
	)
	(arc
		(start 390.921748 -231.201722)
		(mid 391.204704 -231.277899)
		(end 391.48766 -231.201722)
		(width 0.0889)
		(layer "In11.Cu")
		(net "M_L_CPU0_SA_DQ<11>")
	)
	(arc
		(start 388.667752 -231.201722)
		(mid 388.850003 -231.151338)
		(end 389.033512 -231.196896)
		(width 0.0889)
		(layer "In11.Cu")
		(net "M_L_CPU0_SA_DQ<11>")
	)
	(arc
		(start 387.727698 -231.201722)
		(mid 387.909949 -231.151338)
		(end 388.093458 -231.196896)
		(width 0.0889)
		(layer "In11.Cu")
		(net "M_L_CPU0_SA_DQ<11>")
	)
	(arc
		(start 386.221986 -231.201722)
		(mid 386.504942 -231.277899)
		(end 386.787898 -231.201722)
		(width 0.0889)
		(layer "In11.Cu")
		(net "M_L_CPU0_SA_DQ<11>")
	)
	(arc
		(start 390.54786 -231.201722)
		(mid 390.734804 -231.151433)
		(end 390.921748 -231.201722)
		(width 0.0889)
		(layer "In11.Cu")
		(net "M_L_CPU0_SA_DQ<11>")
	)
	(arc
		(start 389.041894 -231.201722)
		(mid 389.32485 -231.277899)
		(end 389.607806 -231.201722)
		(width 0.0889)
		(layer "In11.Cu")
		(net "M_L_CPU0_SA_DQ<11>")
	)
	(arc
		(start 391.862056 -231.201722)
		(mid 392.030416 -231.266281)
		(end 392.210544 -231.274366)
		(width 0.0889)
		(layer "In11.Cu")
		(net "M_L_CPU0_SA_DQ<11>")
	)
	(arc
		(start 387.161786 -231.201722)
		(mid 387.444742 -231.277899)
		(end 387.727698 -231.201722)
		(width 0.0889)
		(layer "In11.Cu")
		(net "M_L_CPU0_SA_DQ<11>")
	)
	(segment
		(start 386.97789 -230.97998)
		(end 387.444742 -230.714296)
		(width 0.10668)
		(layer "F.Cu")
		(net "M_L_CPU0_SA_DQ<10>")
	)
	(segment
		(start 395.809724 -226.03206)
		(end 398.404334 -223.43745)
		(width 0.14478)
		(layer "In11.Cu")
		(net "M_L_CPU0_SA_DQ<10>")
	)
	(segment
		(start 405.928576 -213.867746)
		(end 405.928576 -213.637114)
		(width 0.14478)
		(layer "In11.Cu")
		(net "M_L_CPU0_SA_DQ<10>")
	)
	(segment
		(start 391.939018 -230.40213)
		(end 391.957052 -230.391716)
		(width 0.0889)
		(layer "In11.Cu")
		(net "M_L_CPU0_SA_DQ<10>")
	)
	(segment
		(start 449.663312 -207.11033)
		(end 450.088 -207.535018)
		(width 0.14478)
		(layer "In11.Cu")
		(net "M_L_CPU0_SA_DQ<10>")
	)
	(segment
		(start 443.901068 -207.960214)
		(end 444.750952 -207.11033)
		(width 0.14478)
		(layer "In11.Cu")
		(net "M_L_CPU0_SA_DQ<10>")
	)
	(segment
		(start 407.109676 -212.456268)
		(end 407.340308 -212.456014)
		(width 0.14478)
		(layer "In11.Cu")
		(net "M_L_CPU0_SA_DQ<10>")
	)
	(segment
		(start 444.750952 -207.11033)
		(end 449.663312 -207.11033)
		(width 0.14478)
		(layer "In11.Cu")
		(net "M_L_CPU0_SA_DQ<10>")
	)
	(segment
		(start 391.01776 -230.391716)
		(end 391.026142 -230.38689)
		(width 0.0889)
		(layer "In11.Cu")
		(net "M_L_CPU0_SA_DQ<10>")
	)
	(segment
		(start 387.290818 -230.448866)
		(end 387.31317 -230.365554)
		(width 0.0889)
		(layer "In11.Cu")
		(net "M_L_CPU0_SA_DQ<10>")
	)
	(segment
		(start 429.777144 -207.11033)
		(end 433.190904 -207.11033)
		(width 0.14478)
		(layer "In11.Cu")
		(net "M_L_CPU0_SA_DQ<10>")
	)
	(segment
		(start 410.80944 -207.960214)
		(end 413.945832 -207.960214)
		(width 0.14478)
		(layer "In11.Cu")
		(net "M_L_CPU0_SA_DQ<10>")
	)
	(segment
		(start 392.143742 -230.341424)
		(end 392.630406 -230.341424)
		(width 0.0889)
		(layer "In11.Cu")
		(net "M_L_CPU0_SA_DQ<10>")
	)
	(segment
		(start 436.6133 -207.960214)
		(end 437.463184 -207.11033)
		(width 0.14478)
		(layer "In11.Cu")
		(net "M_L_CPU0_SA_DQ<10>")
	)
	(segment
		(start 404.242524 -214.544148)
		(end 404.473156 -214.544148)
		(width 0.14478)
		(layer "In11.Cu")
		(net "M_L_CPU0_SA_DQ<10>")
	)
	(segment
		(start 394.415518 -227.672392)
		(end 395.205458 -226.882452)
		(width 0.0889)
		(layer "In11.Cu")
		(net "M_L_CPU0_SA_DQ<10>")
	)
	(segment
		(start 405.141176 -214.655146)
		(end 405.141176 -214.424514)
		(width 0.14478)
		(layer "In11.Cu")
		(net "M_L_CPU0_SA_DQ<10>")
	)
	(segment
		(start 428.92726 -207.960214)
		(end 429.777144 -207.11033)
		(width 0.14478)
		(layer "In11.Cu")
		(net "M_L_CPU0_SA_DQ<10>")
	)
	(segment
		(start 390.443466 -230.38689)
		(end 390.451848 -230.391716)
		(width 0.0889)
		(layer "In11.Cu")
		(net "M_L_CPU0_SA_DQ<10>")
	)
	(segment
		(start 406.441402 -212.34527)
		(end 406.604724 -212.181948)
		(width 0.14478)
		(layer "In11.Cu")
		(net "M_L_CPU0_SA_DQ<10>")
	)
	(segment
		(start 426.762418 -207.960214)
		(end 428.92726 -207.960214)
		(width 0.14478)
		(layer "In11.Cu")
		(net "M_L_CPU0_SA_DQ<10>")
	)
	(segment
		(start 407.340308 -212.456014)
		(end 407.584402 -212.21192)
		(width 0.14478)
		(layer "In11.Cu")
		(net "M_L_CPU0_SA_DQ<10>")
	)
	(segment
		(start 406.715976 -212.849714)
		(end 406.441656 -212.575394)
		(width 0.14478)
		(layer "In11.Cu")
		(net "M_L_CPU0_SA_DQ<10>")
	)
	(segment
		(start 406.715976 -213.080346)
		(end 406.715976 -212.849714)
		(width 0.14478)
		(layer "In11.Cu")
		(net "M_L_CPU0_SA_DQ<10>")
	)
	(segment
		(start 441.636404 -207.960214)
		(end 443.901068 -207.960214)
		(width 0.14478)
		(layer "In11.Cu")
		(net "M_L_CPU0_SA_DQ<10>")
	)
	(segment
		(start 406.552908 -213.243414)
		(end 406.715976 -213.080346)
		(width 0.14478)
		(layer "In11.Cu")
		(net "M_L_CPU0_SA_DQ<10>")
	)
	(segment
		(start 404.353776 -215.211914)
		(end 404.079456 -214.937594)
		(width 0.14478)
		(layer "In11.Cu")
		(net "M_L_CPU0_SA_DQ<10>")
	)
	(segment
		(start 425.912534 -207.11033)
		(end 426.762418 -207.960214)
		(width 0.14478)
		(layer "In11.Cu")
		(net "M_L_CPU0_SA_DQ<10>")
	)
	(segment
		(start 419.081966 -207.960214)
		(end 421.559736 -207.960214)
		(width 0.14478)
		(layer "In11.Cu")
		(net "M_L_CPU0_SA_DQ<10>")
	)
	(segment
		(start 407.584402 -212.21192)
		(end 407.584402 -211.185252)
		(width 0.14478)
		(layer "In11.Cu")
		(net "M_L_CPU0_SA_DQ<10>")
	)
	(segment
		(start 405.654256 -213.362794)
		(end 405.654002 -213.13267)
		(width 0.14478)
		(layer "In11.Cu")
		(net "M_L_CPU0_SA_DQ<10>")
	)
	(segment
		(start 398.404334 -221.391988)
		(end 404.353776 -215.442546)
		(width 0.14478)
		(layer "In11.Cu")
		(net "M_L_CPU0_SA_DQ<10>")
	)
	(segment
		(start 407.584402 -211.185252)
		(end 410.80944 -207.960214)
		(width 0.14478)
		(layer "In11.Cu")
		(net "M_L_CPU0_SA_DQ<10>")
	)
	(segment
		(start 404.866856 -214.150194)
		(end 404.866602 -213.92007)
		(width 0.14478)
		(layer "In11.Cu")
		(net "M_L_CPU0_SA_DQ<10>")
	)
	(segment
		(start 406.441656 -212.575394)
		(end 406.441402 -212.34527)
		(width 0.14478)
		(layer "In11.Cu")
		(net "M_L_CPU0_SA_DQ<10>")
	)
	(segment
		(start 395.205458 -226.882452)
		(end 395.205458 -226.636326)
		(width 0.0889)
		(layer "In11.Cu")
		(net "M_L_CPU0_SA_DQ<10>")
	)
	(segment
		(start 393.668758 -228.269292)
		(end 394.265658 -227.672392)
		(width 0.0889)
		(layer "In11.Cu")
		(net "M_L_CPU0_SA_DQ<10>")
	)
	(segment
		(start 405.534876 -214.031068)
		(end 405.765508 -214.030814)
		(width 0.14478)
		(layer "In11.Cu")
		(net "M_L_CPU0_SA_DQ<10>")
	)
	(segment
		(start 421.559736 -207.960214)
		(end 422.40962 -207.11033)
		(width 0.14478)
		(layer "In11.Cu")
		(net "M_L_CPU0_SA_DQ<10>")
	)
	(segment
		(start 406.835356 -212.181948)
		(end 407.109676 -212.456268)
		(width 0.14478)
		(layer "In11.Cu")
		(net "M_L_CPU0_SA_DQ<10>")
	)
	(segment
		(start 404.079456 -214.937594)
		(end 404.079202 -214.70747)
		(width 0.14478)
		(layer "In11.Cu")
		(net "M_L_CPU0_SA_DQ<10>")
	)
	(segment
		(start 405.029924 -213.756748)
		(end 405.260556 -213.756748)
		(width 0.14478)
		(layer "In11.Cu")
		(net "M_L_CPU0_SA_DQ<10>")
	)
	(segment
		(start 422.40962 -207.11033)
		(end 425.912534 -207.11033)
		(width 0.14478)
		(layer "In11.Cu")
		(net "M_L_CPU0_SA_DQ<10>")
	)
	(segment
		(start 392.630406 -230.341424)
		(end 393.668758 -229.303072)
		(width 0.0889)
		(layer "In11.Cu")
		(net "M_L_CPU0_SA_DQ<10>")
	)
	(segment
		(start 433.190904 -207.11033)
		(end 434.040788 -207.960214)
		(width 0.14478)
		(layer "In11.Cu")
		(net "M_L_CPU0_SA_DQ<10>")
	)
	(segment
		(start 405.260556 -213.756748)
		(end 405.534876 -214.031068)
		(width 0.14478)
		(layer "In11.Cu")
		(net "M_L_CPU0_SA_DQ<10>")
	)
	(segment
		(start 404.978108 -214.818214)
		(end 405.141176 -214.655146)
		(width 0.14478)
		(layer "In11.Cu")
		(net "M_L_CPU0_SA_DQ<10>")
	)
	(segment
		(start 414.79597 -207.110076)
		(end 418.231828 -207.110076)
		(width 0.14478)
		(layer "In11.Cu")
		(net "M_L_CPU0_SA_DQ<10>")
	)
	(segment
		(start 406.604724 -212.181948)
		(end 406.835356 -212.181948)
		(width 0.14478)
		(layer "In11.Cu")
		(net "M_L_CPU0_SA_DQ<10>")
	)
	(segment
		(start 405.817324 -212.969348)
		(end 406.047956 -212.969348)
		(width 0.14478)
		(layer "In11.Cu")
		(net "M_L_CPU0_SA_DQ<10>")
	)
	(segment
		(start 395.205458 -226.636326)
		(end 395.809724 -226.03206)
		(width 0.0889)
		(layer "In11.Cu")
		(net "M_L_CPU0_SA_DQ<10>")
	)
	(segment
		(start 437.463184 -207.11033)
		(end 440.78652 -207.11033)
		(width 0.14478)
		(layer "In11.Cu")
		(net "M_L_CPU0_SA_DQ<10>")
	)
	(segment
		(start 404.079202 -214.70747)
		(end 404.242524 -214.544148)
		(width 0.14478)
		(layer "In11.Cu")
		(net "M_L_CPU0_SA_DQ<10>")
	)
	(segment
		(start 388.197852 -230.391716)
		(end 388.206234 -230.38689)
		(width 0.0889)
		(layer "In11.Cu")
		(net "M_L_CPU0_SA_DQ<10>")
	)
	(segment
		(start 405.765508 -214.030814)
		(end 405.928576 -213.867746)
		(width 0.14478)
		(layer "In11.Cu")
		(net "M_L_CPU0_SA_DQ<10>")
	)
	(segment
		(start 404.353776 -215.442546)
		(end 404.353776 -215.211914)
		(width 0.14478)
		(layer "In11.Cu")
		(net "M_L_CPU0_SA_DQ<10>")
	)
	(segment
		(start 398.404334 -223.43745)
		(end 398.404334 -221.391988)
		(width 0.14478)
		(layer "In11.Cu")
		(net "M_L_CPU0_SA_DQ<10>")
	)
	(segment
		(start 440.78652 -207.11033)
		(end 441.636404 -207.960214)
		(width 0.14478)
		(layer "In11.Cu")
		(net "M_L_CPU0_SA_DQ<10>")
	)
	(segment
		(start 405.928576 -213.637114)
		(end 405.654256 -213.362794)
		(width 0.14478)
		(layer "In11.Cu")
		(net "M_L_CPU0_SA_DQ<10>")
	)
	(segment
		(start 387.444742 -230.714296)
		(end 387.290818 -230.448866)
		(width 0.0889)
		(layer "In11.Cu")
		(net "M_L_CPU0_SA_DQ<10>")
	)
	(segment
		(start 406.322276 -213.243668)
		(end 406.552908 -213.243414)
		(width 0.14478)
		(layer "In11.Cu")
		(net "M_L_CPU0_SA_DQ<10>")
	)
	(segment
		(start 434.040788 -207.960214)
		(end 436.6133 -207.960214)
		(width 0.14478)
		(layer "In11.Cu")
		(net "M_L_CPU0_SA_DQ<10>")
	)
	(segment
		(start 418.231828 -207.110076)
		(end 419.081966 -207.960214)
		(width 0.14478)
		(layer "In11.Cu")
		(net "M_L_CPU0_SA_DQ<10>")
	)
	(segment
		(start 404.473156 -214.544148)
		(end 404.747476 -214.818468)
		(width 0.14478)
		(layer "In11.Cu")
		(net "M_L_CPU0_SA_DQ<10>")
	)
	(segment
		(start 405.141176 -214.424514)
		(end 404.866856 -214.150194)
		(width 0.14478)
		(layer "In11.Cu")
		(net "M_L_CPU0_SA_DQ<10>")
	)
	(segment
		(start 406.047956 -212.969348)
		(end 406.322276 -213.243668)
		(width 0.14478)
		(layer "In11.Cu")
		(net "M_L_CPU0_SA_DQ<10>")
	)
	(segment
		(start 404.747476 -214.818468)
		(end 404.978108 -214.818214)
		(width 0.14478)
		(layer "In11.Cu")
		(net "M_L_CPU0_SA_DQ<10>")
	)
	(segment
		(start 393.668758 -229.303072)
		(end 393.668758 -228.269292)
		(width 0.0889)
		(layer "In11.Cu")
		(net "M_L_CPU0_SA_DQ<10>")
	)
	(segment
		(start 394.265658 -227.672392)
		(end 394.415518 -227.672392)
		(width 0.0889)
		(layer "In11.Cu")
		(net "M_L_CPU0_SA_DQ<10>")
	)
	(segment
		(start 413.945832 -207.960214)
		(end 414.79597 -207.110076)
		(width 0.14478)
		(layer "In11.Cu")
		(net "M_L_CPU0_SA_DQ<10>")
	)
	(segment
		(start 405.654002 -213.13267)
		(end 405.817324 -212.969348)
		(width 0.14478)
		(layer "In11.Cu")
		(net "M_L_CPU0_SA_DQ<10>")
	)
	(segment
		(start 404.866602 -213.92007)
		(end 405.029924 -213.756748)
		(width 0.14478)
		(layer "In11.Cu")
		(net "M_L_CPU0_SA_DQ<10>")
	)
	(arc
		(start 390.077706 -230.391716)
		(mid 390.259957 -230.341366)
		(end 390.443466 -230.38689)
		(width 0.0889)
		(layer "In11.Cu")
		(net "M_L_CPU0_SA_DQ<10>")
	)
	(arc
		(start 387.63194 -230.391716)
		(mid 387.914896 -230.467859)
		(end 388.197852 -230.391716)
		(width 0.0889)
		(layer "In11.Cu")
		(net "M_L_CPU0_SA_DQ<10>")
	)
	(arc
		(start 391.391902 -230.391716)
		(mid 391.664114 -230.467756)
		(end 391.939018 -230.40213)
		(width 0.0889)
		(layer "In11.Cu")
		(net "M_L_CPU0_SA_DQ<10>")
	)
	(arc
		(start 388.571994 -230.391716)
		(mid 388.85495 -230.467859)
		(end 389.137906 -230.391716)
		(width 0.0889)
		(layer "In11.Cu")
		(net "M_L_CPU0_SA_DQ<10>")
	)
	(arc
		(start 389.137906 -230.391716)
		(mid 389.32485 -230.341461)
		(end 389.511794 -230.391716)
		(width 0.0889)
		(layer "In11.Cu")
		(net "M_L_CPU0_SA_DQ<10>")
	)
	(arc
		(start 391.026142 -230.38689)
		(mid 391.20965 -230.341396)
		(end 391.391902 -230.391716)
		(width 0.0889)
		(layer "In11.Cu")
		(net "M_L_CPU0_SA_DQ<10>")
	)
	(arc
		(start 389.511794 -230.391716)
		(mid 389.79475 -230.467859)
		(end 390.077706 -230.391716)
		(width 0.0889)
		(layer "In11.Cu")
		(net "M_L_CPU0_SA_DQ<10>")
	)
	(arc
		(start 387.31317 -230.365554)
		(mid 387.475502 -230.342736)
		(end 387.63194 -230.391716)
		(width 0.0889)
		(layer "In11.Cu")
		(net "M_L_CPU0_SA_DQ<10>")
	)
	(arc
		(start 388.206234 -230.38689)
		(mid 388.389742 -230.341396)
		(end 388.571994 -230.391716)
		(width 0.0889)
		(layer "In11.Cu")
		(net "M_L_CPU0_SA_DQ<10>")
	)
	(arc
		(start 391.957052 -230.391716)
		(mid 392.047087 -230.354302)
		(end 392.143742 -230.341424)
		(width 0.0889)
		(layer "In11.Cu")
		(net "M_L_CPU0_SA_DQ<10>")
	)
	(arc
		(start 390.451848 -230.391716)
		(mid 390.734804 -230.467859)
		(end 391.01776 -230.391716)
		(width 0.0889)
		(layer "In11.Cu")
		(net "M_L_CPU0_SA_DQ<10>")
	)
	(segment
		(start 386.50799 -225.310192)
		(end 386.974842 -225.044254)
		(width 0.10668)
		(layer "F.Cu")
		(net "M_L_CPU0_SA_DQ<0>")
	)
	(segment
		(start 418.812472 -196.910198)
		(end 414.61055 -196.910198)
		(width 0.14478)
		(layer "In11.Cu")
		(net "M_L_CPU0_SA_DQ<0>")
	)
	(segment
		(start 437.463184 -196.910198)
		(end 436.6133 -197.760082)
		(width 0.14478)
		(layer "In11.Cu")
		(net "M_L_CPU0_SA_DQ<0>")
	)
	(segment
		(start 444.027052 -197.760082)
		(end 441.526168 -197.760082)
		(width 0.14478)
		(layer "In11.Cu")
		(net "M_L_CPU0_SA_DQ<0>")
	)
	(segment
		(start 392.043158 -221.543372)
		(end 392.043158 -221.80423)
		(width 0.0889)
		(layer "In11.Cu")
		(net "M_L_CPU0_SA_DQ<0>")
	)
	(segment
		(start 387.128766 -225.309684)
		(end 386.974842 -225.044254)
		(width 0.0889)
		(layer "In11.Cu")
		(net "M_L_CPU0_SA_DQ<0>")
	)
	(segment
		(start 391.426954 -222.916496)
		(end 391.391902 -222.936816)
		(width 0.0889)
		(layer "In11.Cu")
		(net "M_L_CPU0_SA_DQ<0>")
	)
	(segment
		(start 392.006328 -221.506542)
		(end 392.043158 -221.543372)
		(width 0.0889)
		(layer "In11.Cu")
		(net "M_L_CPU0_SA_DQ<0>")
	)
	(segment
		(start 389.616188 -225.37166)
		(end 389.607806 -225.366834)
		(width 0.0889)
		(layer "In11.Cu")
		(net "M_L_CPU0_SA_DQ<0>")
	)
	(segment
		(start 419.662356 -197.760082)
		(end 418.812472 -196.910198)
		(width 0.14478)
		(layer "In11.Cu")
		(net "M_L_CPU0_SA_DQ<0>")
	)
	(segment
		(start 399.749264 -209.0674)
		(end 392.006328 -216.810336)
		(width 0.14478)
		(layer "In11.Cu")
		(net "M_L_CPU0_SA_DQ<0>")
	)
	(segment
		(start 414.61055 -196.910198)
		(end 413.760666 -197.760082)
		(width 0.14478)
		(layer "In11.Cu")
		(net "M_L_CPU0_SA_DQ<0>")
	)
	(segment
		(start 389.041894 -225.366834)
		(end 389.033512 -225.37166)
		(width 0.0889)
		(layer "In11.Cu")
		(net "M_L_CPU0_SA_DQ<0>")
	)
	(segment
		(start 426.762418 -197.760082)
		(end 425.912534 -196.910198)
		(width 0.14478)
		(layer "In11.Cu")
		(net "M_L_CPU0_SA_DQ<0>")
	)
	(segment
		(start 399.749264 -208.19872)
		(end 399.749264 -209.0674)
		(width 0.14478)
		(layer "In11.Cu")
		(net "M_L_CPU0_SA_DQ<0>")
	)
	(segment
		(start 421.538908 -197.760082)
		(end 419.662356 -197.760082)
		(width 0.14478)
		(layer "In11.Cu")
		(net "M_L_CPU0_SA_DQ<0>")
	)
	(segment
		(start 391.391902 -222.936816)
		(end 391.352786 -222.959676)
		(width 0.0889)
		(layer "In11.Cu")
		(net "M_L_CPU0_SA_DQ<0>")
	)
	(segment
		(start 390.483598 -224.53854)
		(end 390.451848 -224.556828)
		(width 0.0889)
		(layer "In11.Cu")
		(net "M_L_CPU0_SA_DQ<0>")
	)
	(segment
		(start 410.187902 -197.760082)
		(end 399.749264 -208.19872)
		(width 0.14478)
		(layer "In11.Cu")
		(net "M_L_CPU0_SA_DQ<0>")
	)
	(segment
		(start 454.188068 -197.33514)
		(end 453.763126 -196.910198)
		(width 0.14478)
		(layer "In11.Cu")
		(net "M_L_CPU0_SA_DQ<0>")
	)
	(segment
		(start 387.224778 -225.335084)
		(end 387.128766 -225.309684)
		(width 0.0889)
		(layer "In11.Cu")
		(net "M_L_CPU0_SA_DQ<0>")
	)
	(segment
		(start 425.912534 -196.910198)
		(end 422.388792 -196.910198)
		(width 0.14478)
		(layer "In11.Cu")
		(net "M_L_CPU0_SA_DQ<0>")
	)
	(segment
		(start 428.93742 -197.760082)
		(end 426.762418 -197.760082)
		(width 0.14478)
		(layer "In11.Cu")
		(net "M_L_CPU0_SA_DQ<0>")
	)
	(segment
		(start 390.451848 -224.556828)
		(end 390.412732 -224.579688)
		(width 0.0889)
		(layer "In11.Cu")
		(net "M_L_CPU0_SA_DQ<0>")
	)
	(segment
		(start 422.388792 -196.910198)
		(end 421.538908 -197.760082)
		(width 0.14478)
		(layer "In11.Cu")
		(net "M_L_CPU0_SA_DQ<0>")
	)
	(segment
		(start 388.10184 -225.366834)
		(end 388.093458 -225.37166)
		(width 0.0889)
		(layer "In11.Cu")
		(net "M_L_CPU0_SA_DQ<0>")
	)
	(segment
		(start 413.760666 -197.760082)
		(end 410.187902 -197.760082)
		(width 0.14478)
		(layer "In11.Cu")
		(net "M_L_CPU0_SA_DQ<0>")
	)
	(segment
		(start 436.6133 -197.760082)
		(end 434.040788 -197.760082)
		(width 0.14478)
		(layer "In11.Cu")
		(net "M_L_CPU0_SA_DQ<0>")
	)
	(segment
		(start 434.040788 -197.760082)
		(end 433.190904 -196.910198)
		(width 0.14478)
		(layer "In11.Cu")
		(net "M_L_CPU0_SA_DQ<0>")
	)
	(segment
		(start 429.787304 -196.910198)
		(end 428.93742 -197.760082)
		(width 0.14478)
		(layer "In11.Cu")
		(net "M_L_CPU0_SA_DQ<0>")
	)
	(segment
		(start 390.921748 -223.746822)
		(end 390.885426 -223.767904)
		(width 0.0889)
		(layer "In11.Cu")
		(net "M_L_CPU0_SA_DQ<0>")
	)
	(segment
		(start 392.006328 -221.156022)
		(end 392.006328 -221.506542)
		(width 0.0889)
		(layer "In11.Cu")
		(net "M_L_CPU0_SA_DQ<0>")
	)
	(segment
		(start 433.190904 -196.910198)
		(end 429.787304 -196.910198)
		(width 0.14478)
		(layer "In11.Cu")
		(net "M_L_CPU0_SA_DQ<0>")
	)
	(segment
		(start 390.953498 -223.728534)
		(end 390.921748 -223.746822)
		(width 0.0889)
		(layer "In11.Cu")
		(net "M_L_CPU0_SA_DQ<0>")
	)
	(segment
		(start 441.526168 -197.760082)
		(end 440.676284 -196.910198)
		(width 0.14478)
		(layer "In11.Cu")
		(net "M_L_CPU0_SA_DQ<0>")
	)
	(segment
		(start 390.012428 -225.349054)
		(end 389.981948 -225.366834)
		(width 0.0889)
		(layer "In11.Cu")
		(net "M_L_CPU0_SA_DQ<0>")
	)
	(segment
		(start 453.763126 -196.910198)
		(end 444.876936 -196.910198)
		(width 0.14478)
		(layer "In11.Cu")
		(net "M_L_CPU0_SA_DQ<0>")
	)
	(segment
		(start 391.820654 -222.142812)
		(end 391.742676 -222.22079)
		(width 0.0889)
		(layer "In11.Cu")
		(net "M_L_CPU0_SA_DQ<0>")
	)
	(segment
		(start 392.006328 -216.810336)
		(end 392.006328 -221.156022)
		(width 0.14478)
		(layer "In11.Cu")
		(net "M_L_CPU0_SA_DQ<0>")
	)
	(segment
		(start 440.676284 -196.910198)
		(end 437.463184 -196.910198)
		(width 0.14478)
		(layer "In11.Cu")
		(net "M_L_CPU0_SA_DQ<0>")
	)
	(segment
		(start 444.876936 -196.910198)
		(end 444.027052 -197.760082)
		(width 0.14478)
		(layer "In11.Cu")
		(net "M_L_CPU0_SA_DQ<0>")
	)
	(arc
		(start 387.727698 -225.366834)
		(mid 387.479985 -225.291614)
		(end 387.224778 -225.335084)
		(width 0.0889)
		(layer "In11.Cu")
		(net "M_L_CPU0_SA_DQ<0>")
	)
	(arc
		(start 390.639554 -224.234248)
		(mid 390.598299 -224.405219)
		(end 390.483598 -224.53854)
		(width 0.0889)
		(layer "In11.Cu")
		(net "M_L_CPU0_SA_DQ<0>")
	)
	(arc
		(start 391.742676 -222.22079)
		(mid 391.622143 -222.40132)
		(end 391.579862 -222.614236)
		(width 0.0889)
		(layer "In11.Cu")
		(net "M_L_CPU0_SA_DQ<0>")
	)
	(arc
		(start 389.607806 -225.366834)
		(mid 389.32485 -225.290657)
		(end 389.041894 -225.366834)
		(width 0.0889)
		(layer "In11.Cu")
		(net "M_L_CPU0_SA_DQ<0>")
	)
	(arc
		(start 392.043158 -221.80423)
		(mid 391.982549 -222.006796)
		(end 391.820654 -222.142812)
		(width 0.0889)
		(layer "In11.Cu")
		(net "M_L_CPU0_SA_DQ<0>")
	)
	(arc
		(start 391.109454 -223.424242)
		(mid 391.068199 -223.595213)
		(end 390.953498 -223.728534)
		(width 0.0889)
		(layer "In11.Cu")
		(net "M_L_CPU0_SA_DQ<0>")
	)
	(arc
		(start 389.981948 -225.366834)
		(mid 389.799697 -225.417184)
		(end 389.616188 -225.37166)
		(width 0.0889)
		(layer "In11.Cu")
		(net "M_L_CPU0_SA_DQ<0>")
	)
	(arc
		(start 388.093458 -225.37166)
		(mid 387.90995 -225.417154)
		(end 387.727698 -225.366834)
		(width 0.0889)
		(layer "In11.Cu")
		(net "M_L_CPU0_SA_DQ<0>")
	)
	(arc
		(start 391.579862 -222.614236)
		(mid 391.539457 -222.7836)
		(end 391.426954 -222.916496)
		(width 0.0889)
		(layer "In11.Cu")
		(net "M_L_CPU0_SA_DQ<0>")
	)
	(arc
		(start 390.412732 -224.579688)
		(mid 390.233919 -224.782038)
		(end 390.1694 -225.044254)
		(width 0.0889)
		(layer "In11.Cu")
		(net "M_L_CPU0_SA_DQ<0>")
	)
	(arc
		(start 389.033512 -225.37166)
		(mid 388.850004 -225.417154)
		(end 388.667752 -225.366834)
		(width 0.0889)
		(layer "In11.Cu")
		(net "M_L_CPU0_SA_DQ<0>")
	)
	(arc
		(start 388.667752 -225.366834)
		(mid 388.384796 -225.290657)
		(end 388.10184 -225.366834)
		(width 0.0889)
		(layer "In11.Cu")
		(net "M_L_CPU0_SA_DQ<0>")
	)
	(arc
		(start 390.885426 -223.767904)
		(mid 390.704774 -223.970649)
		(end 390.639554 -224.234248)
		(width 0.0889)
		(layer "In11.Cu")
		(net "M_L_CPU0_SA_DQ<0>")
	)
	(arc
		(start 391.352786 -222.959676)
		(mid 391.173973 -223.162026)
		(end 391.109454 -223.424242)
		(width 0.0889)
		(layer "In11.Cu")
		(net "M_L_CPU0_SA_DQ<0>")
	)
	(arc
		(start 390.1694 -225.044254)
		(mid 390.127851 -225.215676)
		(end 390.012428 -225.349054)
		(width 0.0889)
		(layer "In11.Cu")
		(net "M_L_CPU0_SA_DQ<0>")
	)
	(segment
		(start 385.098036 -252.040136)
		(end 385.564888 -251.774198)
		(width 0.10668)
		(layer "F.Cu")
		(net "M_L_CPU0_SA_CS_N<1>")
	)
	(segment
		(start 448.721226 -247.276112)
		(end 448.576446 -247.420892)
		(width 0.14478)
		(layer "In11.Cu")
		(net "M_L_CPU0_SA_CS_N<1>")
	)
	(segment
		(start 447.473578 -247.060212)
		(end 445.613028 -247.060212)
		(width 0.14478)
		(layer "In11.Cu")
		(net "M_L_CPU0_SA_CS_N<1>")
	)
	(segment
		(start 388.2009 -252.09119)
		(end 388.190232 -252.085094)
		(width 0.0889)
		(layer "In11.Cu")
		(net "M_L_CPU0_SA_CS_N<1>")
	)
	(segment
		(start 412.201868 -248.760234)
		(end 409.446222 -251.51588)
		(width 0.14478)
		(layer "In11.Cu")
		(net "M_L_CPU0_SA_CS_N<1>")
	)
	(segment
		(start 392.912854 -252.097794)
		(end 392.90117 -252.09119)
		(width 0.0889)
		(layer "In11.Cu")
		(net "M_L_CPU0_SA_CS_N<1>")
	)
	(segment
		(start 385.816094 -252.057662)
		(end 385.713732 -252.030484)
		(width 0.0889)
		(layer "In11.Cu")
		(net "M_L_CPU0_SA_CS_N<1>")
	)
	(segment
		(start 409.446222 -251.51588)
		(end 398.816068 -251.51588)
		(width 0.14478)
		(layer "In11.Cu")
		(net "M_L_CPU0_SA_CS_N<1>")
	)
	(segment
		(start 447.763138 -246.699532)
		(end 447.618358 -246.844312)
		(width 0.14478)
		(layer "In11.Cu")
		(net "M_L_CPU0_SA_CS_N<1>")
	)
	(segment
		(start 397.417544 -252.914404)
		(end 395.72438 -252.914404)
		(width 0.14478)
		(layer "In11.Cu")
		(net "M_L_CPU0_SA_CS_N<1>")
	)
	(segment
		(start 395.29385 -252.914404)
		(end 394.52042 -252.140974)
		(width 0.0889)
		(layer "In11.Cu")
		(net "M_L_CPU0_SA_CS_N<1>")
	)
	(segment
		(start 447.618358 -246.844312)
		(end 447.618358 -246.915432)
		(width 0.14478)
		(layer "In11.Cu")
		(net "M_L_CPU0_SA_CS_N<1>")
	)
	(segment
		(start 448.169792 -246.844312)
		(end 448.025012 -246.699532)
		(width 0.14478)
		(layer "In11.Cu")
		(net "M_L_CPU0_SA_CS_N<1>")
	)
	(segment
		(start 449.41744 -247.060212)
		(end 449.27266 -246.915432)
		(width 0.14478)
		(layer "In11.Cu")
		(net "M_L_CPU0_SA_CS_N<1>")
	)
	(segment
		(start 445.613028 -247.060212)
		(end 443.913006 -248.760234)
		(width 0.14478)
		(layer "In11.Cu")
		(net "M_L_CPU0_SA_CS_N<1>")
	)
	(segment
		(start 448.169792 -247.276112)
		(end 448.169792 -246.844312)
		(width 0.14478)
		(layer "In11.Cu")
		(net "M_L_CPU0_SA_CS_N<1>")
	)
	(segment
		(start 385.713732 -252.030484)
		(end 385.564888 -251.774198)
		(width 0.0889)
		(layer "In11.Cu")
		(net "M_L_CPU0_SA_CS_N<1>")
	)
	(segment
		(start 395.72438 -252.914404)
		(end 395.29385 -252.914404)
		(width 0.0889)
		(layer "In11.Cu")
		(net "M_L_CPU0_SA_CS_N<1>")
	)
	(segment
		(start 448.721226 -246.844312)
		(end 448.721226 -247.276112)
		(width 0.14478)
		(layer "In11.Cu")
		(net "M_L_CPU0_SA_CS_N<1>")
	)
	(segment
		(start 447.618358 -246.915432)
		(end 447.473578 -247.060212)
		(width 0.14478)
		(layer "In11.Cu")
		(net "M_L_CPU0_SA_CS_N<1>")
	)
	(segment
		(start 448.025012 -246.699532)
		(end 447.763138 -246.699532)
		(width 0.14478)
		(layer "In11.Cu")
		(net "M_L_CPU0_SA_CS_N<1>")
	)
	(segment
		(start 450.088 -246.635016)
		(end 449.662804 -247.060212)
		(width 0.14478)
		(layer "In11.Cu")
		(net "M_L_CPU0_SA_CS_N<1>")
	)
	(segment
		(start 392.329162 -252.09119)
		(end 392.321034 -252.096016)
		(width 0.0889)
		(layer "In11.Cu")
		(net "M_L_CPU0_SA_CS_N<1>")
	)
	(segment
		(start 448.866006 -246.699532)
		(end 448.721226 -246.844312)
		(width 0.14478)
		(layer "In11.Cu")
		(net "M_L_CPU0_SA_CS_N<1>")
	)
	(segment
		(start 449.27266 -246.844312)
		(end 449.12788 -246.699532)
		(width 0.14478)
		(layer "In11.Cu")
		(net "M_L_CPU0_SA_CS_N<1>")
	)
	(segment
		(start 394.52042 -252.140974)
		(end 394.02512 -252.140974)
		(width 0.0889)
		(layer "In11.Cu")
		(net "M_L_CPU0_SA_CS_N<1>")
	)
	(segment
		(start 389.519414 -252.085094)
		(end 389.508746 -252.09119)
		(width 0.0889)
		(layer "In11.Cu")
		(net "M_L_CPU0_SA_CS_N<1>")
	)
	(segment
		(start 448.314572 -247.420892)
		(end 448.169792 -247.276112)
		(width 0.14478)
		(layer "In11.Cu")
		(net "M_L_CPU0_SA_CS_N<1>")
	)
	(segment
		(start 448.576446 -247.420892)
		(end 448.314572 -247.420892)
		(width 0.14478)
		(layer "In11.Cu")
		(net "M_L_CPU0_SA_CS_N<1>")
	)
	(segment
		(start 449.662804 -247.060212)
		(end 449.41744 -247.060212)
		(width 0.14478)
		(layer "In11.Cu")
		(net "M_L_CPU0_SA_CS_N<1>")
	)
	(segment
		(start 398.816068 -251.51588)
		(end 397.417544 -252.914404)
		(width 0.14478)
		(layer "In11.Cu")
		(net "M_L_CPU0_SA_CS_N<1>")
	)
	(segment
		(start 443.913006 -248.760234)
		(end 412.201868 -248.760234)
		(width 0.14478)
		(layer "In11.Cu")
		(net "M_L_CPU0_SA_CS_N<1>")
	)
	(segment
		(start 449.27266 -246.915432)
		(end 449.27266 -246.844312)
		(width 0.14478)
		(layer "In11.Cu")
		(net "M_L_CPU0_SA_CS_N<1>")
	)
	(segment
		(start 388.57936 -252.085094)
		(end 388.568692 -252.09119)
		(width 0.0889)
		(layer "In11.Cu")
		(net "M_L_CPU0_SA_CS_N<1>")
	)
	(segment
		(start 449.12788 -246.699532)
		(end 448.866006 -246.699532)
		(width 0.14478)
		(layer "In11.Cu")
		(net "M_L_CPU0_SA_CS_N<1>")
	)
	(arc
		(start 393.268962 -252.09119)
		(mid 393.091776 -252.140608)
		(end 392.912854 -252.097794)
		(width 0.0889)
		(layer "In11.Cu")
		(net "M_L_CPU0_SA_CS_N<1>")
	)
	(arc
		(start 390.4488 -252.09119)
		(mid 390.264904 -252.14067)
		(end 390.081008 -252.09119)
		(width 0.0889)
		(layer "In11.Cu")
		(net "M_L_CPU0_SA_CS_N<1>")
	)
	(arc
		(start 391.3886 -252.09119)
		(mid 391.204704 -252.14067)
		(end 391.020808 -252.09119)
		(width 0.0889)
		(layer "In11.Cu")
		(net "M_L_CPU0_SA_CS_N<1>")
	)
	(arc
		(start 391.020808 -252.09119)
		(mid 390.734804 -252.014238)
		(end 390.4488 -252.09119)
		(width 0.0889)
		(layer "In11.Cu")
		(net "M_L_CPU0_SA_CS_N<1>")
	)
	(arc
		(start 386.321046 -252.09119)
		(mid 386.072499 -252.015359)
		(end 385.816094 -252.057662)
		(width 0.0889)
		(layer "In11.Cu")
		(net "M_L_CPU0_SA_CS_N<1>")
	)
	(arc
		(start 389.508746 -252.09119)
		(mid 389.32485 -252.14067)
		(end 389.140954 -252.09119)
		(width 0.0889)
		(layer "In11.Cu")
		(net "M_L_CPU0_SA_CS_N<1>")
	)
	(arc
		(start 392.90117 -252.09119)
		(mid 392.615166 -252.014238)
		(end 392.329162 -252.09119)
		(width 0.0889)
		(layer "In11.Cu")
		(net "M_L_CPU0_SA_CS_N<1>")
	)
	(arc
		(start 388.190232 -252.085094)
		(mid 387.908643 -252.01422)
		(end 387.628638 -252.09119)
		(width 0.0889)
		(layer "In11.Cu")
		(net "M_L_CPU0_SA_CS_N<1>")
	)
	(arc
		(start 388.568692 -252.09119)
		(mid 388.384796 -252.14067)
		(end 388.2009 -252.09119)
		(width 0.0889)
		(layer "In11.Cu")
		(net "M_L_CPU0_SA_CS_N<1>")
	)
	(arc
		(start 386.688838 -252.09119)
		(mid 386.504942 -252.14067)
		(end 386.321046 -252.09119)
		(width 0.0889)
		(layer "In11.Cu")
		(net "M_L_CPU0_SA_CS_N<1>")
	)
	(arc
		(start 390.081008 -252.09119)
		(mid 389.801004 -252.014145)
		(end 389.519414 -252.085094)
		(width 0.0889)
		(layer "In11.Cu")
		(net "M_L_CPU0_SA_CS_N<1>")
	)
	(arc
		(start 387.260846 -252.09119)
		(mid 386.974842 -252.014238)
		(end 386.688838 -252.09119)
		(width 0.0889)
		(layer "In11.Cu")
		(net "M_L_CPU0_SA_CS_N<1>")
	)
	(arc
		(start 392.321034 -252.096016)
		(mid 392.14043 -252.140856)
		(end 391.961116 -252.09119)
		(width 0.0889)
		(layer "In11.Cu")
		(net "M_L_CPU0_SA_CS_N<1>")
	)
	(arc
		(start 394.02512 -252.140974)
		(mid 393.930005 -252.128222)
		(end 393.841478 -252.09119)
		(width 0.0889)
		(layer "In11.Cu")
		(net "M_L_CPU0_SA_CS_N<1>")
	)
	(arc
		(start 387.628638 -252.09119)
		(mid 387.444742 -252.14067)
		(end 387.260846 -252.09119)
		(width 0.0889)
		(layer "In11.Cu")
		(net "M_L_CPU0_SA_CS_N<1>")
	)
	(arc
		(start 391.961116 -252.09119)
		(mid 391.674858 -252.014111)
		(end 391.3886 -252.09119)
		(width 0.0889)
		(layer "In11.Cu")
		(net "M_L_CPU0_SA_CS_N<1>")
	)
	(arc
		(start 393.841478 -252.09119)
		(mid 393.55522 -252.014111)
		(end 393.268962 -252.09119)
		(width 0.0889)
		(layer "In11.Cu")
		(net "M_L_CPU0_SA_CS_N<1>")
	)
	(arc
		(start 389.140954 -252.09119)
		(mid 388.86095 -252.014145)
		(end 388.57936 -252.085094)
		(width 0.0889)
		(layer "In11.Cu")
		(net "M_L_CPU0_SA_CS_N<1>")
	)
	(segment
		(start 386.50799 -251.23013)
		(end 386.974842 -250.964192)
		(width 0.10668)
		(layer "F.Cu")
		(net "M_L_CPU0_SA_CS_N<0>")
	)
	(segment
		(start 394.1064 -251.330714)
		(end 395.23543 -252.459744)
		(width 0.0889)
		(layer "In11.Cu")
		(net "M_L_CPU0_SA_CS_N<0>")
	)
	(segment
		(start 390.54024 -251.275088)
		(end 390.550908 -251.281184)
		(width 0.0889)
		(layer "In11.Cu")
		(net "M_L_CPU0_SA_CS_N<0>")
	)
	(segment
		(start 412.408878 -247.910096)
		(end 443.838076 -247.910096)
		(width 0.14478)
		(layer "In11.Cu")
		(net "M_L_CPU0_SA_CS_N<0>")
	)
	(segment
		(start 443.838076 -247.910096)
		(end 445.538098 -246.210074)
		(width 0.14478)
		(layer "In11.Cu")
		(net "M_L_CPU0_SA_CS_N<0>")
	)
	(segment
		(start 453.763126 -246.210074)
		(end 454.188068 -245.785132)
		(width 0.14478)
		(layer "In11.Cu")
		(net "M_L_CPU0_SA_CS_N<0>")
	)
	(segment
		(start 392.787124 -251.288042)
		(end 392.798808 -251.281184)
		(width 0.0889)
		(layer "In11.Cu")
		(net "M_L_CPU0_SA_CS_N<0>")
	)
	(segment
		(start 387.123686 -251.220478)
		(end 387.226048 -251.247656)
		(width 0.0889)
		(layer "In11.Cu")
		(net "M_L_CPU0_SA_CS_N<0>")
	)
	(segment
		(start 390.9187 -251.281184)
		(end 390.929368 -251.275088)
		(width 0.0889)
		(layer "In11.Cu")
		(net "M_L_CPU0_SA_CS_N<0>")
	)
	(segment
		(start 445.538098 -246.210074)
		(end 453.763126 -246.210074)
		(width 0.14478)
		(layer "In11.Cu")
		(net "M_L_CPU0_SA_CS_N<0>")
	)
	(segment
		(start 395.23543 -252.459744)
		(end 395.75867 -252.459744)
		(width 0.0889)
		(layer "In11.Cu")
		(net "M_L_CPU0_SA_CS_N<0>")
	)
	(segment
		(start 398.627346 -251.06122)
		(end 409.257754 -251.06122)
		(width 0.14478)
		(layer "In11.Cu")
		(net "M_L_CPU0_SA_CS_N<0>")
	)
	(segment
		(start 391.846562 -251.287788)
		(end 391.858246 -251.281184)
		(width 0.0889)
		(layer "In11.Cu")
		(net "M_L_CPU0_SA_CS_N<0>")
	)
	(segment
		(start 409.257754 -251.06122)
		(end 412.408878 -247.910096)
		(width 0.14478)
		(layer "In11.Cu")
		(net "M_L_CPU0_SA_CS_N<0>")
	)
	(segment
		(start 397.228822 -252.459744)
		(end 398.627346 -251.06122)
		(width 0.14478)
		(layer "In11.Cu")
		(net "M_L_CPU0_SA_CS_N<0>")
	)
	(segment
		(start 386.974842 -250.964192)
		(end 387.123686 -251.220478)
		(width 0.0889)
		(layer "In11.Cu")
		(net "M_L_CPU0_SA_CS_N<0>")
	)
	(segment
		(start 393.553696 -251.330714)
		(end 394.1064 -251.330714)
		(width 0.0889)
		(layer "In11.Cu")
		(net "M_L_CPU0_SA_CS_N<0>")
	)
	(segment
		(start 391.858246 -251.281184)
		(end 391.881614 -251.267468)
		(width 0.0889)
		(layer "In11.Cu")
		(net "M_L_CPU0_SA_CS_N<0>")
	)
	(segment
		(start 395.75867 -252.459744)
		(end 397.228822 -252.459744)
		(width 0.14478)
		(layer "In11.Cu")
		(net "M_L_CPU0_SA_CS_N<0>")
	)
	(segment
		(start 388.098792 -251.281184)
		(end 388.10946 -251.275088)
		(width 0.0889)
		(layer "In11.Cu")
		(net "M_L_CPU0_SA_CS_N<0>")
	)
	(segment
		(start 393.351766 -251.270516)
		(end 393.370054 -251.281184)
		(width 0.0889)
		(layer "In11.Cu")
		(net "M_L_CPU0_SA_CS_N<0>")
	)
	(arc
		(start 389.038846 -251.281184)
		(mid 389.32485 -251.204232)
		(end 389.610854 -251.281184)
		(width 0.0889)
		(layer "In11.Cu")
		(net "M_L_CPU0_SA_CS_N<0>")
	)
	(arc
		(start 387.731 -251.281184)
		(mid 387.914896 -251.330664)
		(end 388.098792 -251.281184)
		(width 0.0889)
		(layer "In11.Cu")
		(net "M_L_CPU0_SA_CS_N<0>")
	)
	(arc
		(start 391.881614 -251.267468)
		(mid 392.157809 -251.20398)
		(end 392.430508 -251.281184)
		(width 0.0889)
		(layer "In11.Cu")
		(net "M_L_CPU0_SA_CS_N<0>")
	)
	(arc
		(start 389.978646 -251.281184)
		(mid 390.25865 -251.204139)
		(end 390.54024 -251.275088)
		(width 0.0889)
		(layer "In11.Cu")
		(net "M_L_CPU0_SA_CS_N<0>")
	)
	(arc
		(start 392.430508 -251.281184)
		(mid 392.607918 -251.330852)
		(end 392.787124 -251.288042)
		(width 0.0889)
		(layer "In11.Cu")
		(net "M_L_CPU0_SA_CS_N<0>")
	)
	(arc
		(start 388.671054 -251.281184)
		(mid 388.85495 -251.330664)
		(end 389.038846 -251.281184)
		(width 0.0889)
		(layer "In11.Cu")
		(net "M_L_CPU0_SA_CS_N<0>")
	)
	(arc
		(start 393.370054 -251.281184)
		(mid 393.458605 -251.31807)
		(end 393.553696 -251.330714)
		(width 0.0889)
		(layer "In11.Cu")
		(net "M_L_CPU0_SA_CS_N<0>")
	)
	(arc
		(start 390.929368 -251.275088)
		(mid 391.210957 -251.204214)
		(end 391.490962 -251.281184)
		(width 0.0889)
		(layer "In11.Cu")
		(net "M_L_CPU0_SA_CS_N<0>")
	)
	(arc
		(start 390.550908 -251.281184)
		(mid 390.734804 -251.330664)
		(end 390.9187 -251.281184)
		(width 0.0889)
		(layer "In11.Cu")
		(net "M_L_CPU0_SA_CS_N<0>")
	)
	(arc
		(start 388.10946 -251.275088)
		(mid 388.391049 -251.204214)
		(end 388.671054 -251.281184)
		(width 0.0889)
		(layer "In11.Cu")
		(net "M_L_CPU0_SA_CS_N<0>")
	)
	(arc
		(start 391.490962 -251.281184)
		(mid 391.667895 -251.330475)
		(end 391.846562 -251.287788)
		(width 0.0889)
		(layer "In11.Cu")
		(net "M_L_CPU0_SA_CS_N<0>")
	)
	(arc
		(start 392.798808 -251.281184)
		(mid 393.073896 -251.204337)
		(end 393.351766 -251.270516)
		(width 0.0889)
		(layer "In11.Cu")
		(net "M_L_CPU0_SA_CS_N<0>")
	)
	(arc
		(start 389.610854 -251.281184)
		(mid 389.79475 -251.330664)
		(end 389.978646 -251.281184)
		(width 0.0889)
		(layer "In11.Cu")
		(net "M_L_CPU0_SA_CS_N<0>")
	)
	(arc
		(start 387.226048 -251.247656)
		(mid 387.482457 -251.205295)
		(end 387.731 -251.281184)
		(width 0.0889)
		(layer "In11.Cu")
		(net "M_L_CPU0_SA_CS_N<0>")
	)
	(segment
		(start 385.567936 -249.610118)
		(end 386.034788 -249.34418)
		(width 0.10668)
		(layer "F.Cu")
		(net "M_L_CPU0_SA_CB<7>")
	)
	(segment
		(start 410.935932 -246.618252)
		(end 411.121352 -246.432832)
		(width 0.14478)
		(layer "In11.Cu")
		(net "M_L_CPU0_SA_CB<7>")
	)
	(segment
		(start 440.833002 -245.21541)
		(end 440.977782 -245.36019)
		(width 0.14478)
		(layer "In11.Cu")
		(net "M_L_CPU0_SA_CB<7>")
	)
	(segment
		(start 410.364178 -246.251222)
		(end 410.731208 -246.618252)
		(width 0.14478)
		(layer "In11.Cu")
		(net "M_L_CPU0_SA_CB<7>")
	)
	(segment
		(start 393.084812 -249.097292)
		(end 393.539218 -249.097292)
		(width 0.0889)
		(layer "In11.Cu")
		(net "M_L_CPU0_SA_CB<7>")
	)
	(segment
		(start 410.155644 -247.39854)
		(end 410.341064 -247.21312)
		(width 0.14478)
		(layer "In11.Cu")
		(net "M_L_CPU0_SA_CB<7>")
	)
	(segment
		(start 395.74724 -250.053094)
		(end 396.92326 -250.053094)
		(width 0.14478)
		(layer "In11.Cu")
		(net "M_L_CPU0_SA_CB<7>")
	)
	(segment
		(start 410.754322 -245.861078)
		(end 410.754322 -245.656354)
		(width 0.14478)
		(layer "In11.Cu")
		(net "M_L_CPU0_SA_CB<7>")
	)
	(segment
		(start 409.560776 -247.788684)
		(end 409.193746 -247.421654)
		(width 0.14478)
		(layer "In11.Cu")
		(net "M_L_CPU0_SA_CB<7>")
	)
	(segment
		(start 411.71622 -245.837964)
		(end 412.193994 -245.36019)
		(width 0.14478)
		(layer "In11.Cu")
		(net "M_L_CPU0_SA_CB<7>")
	)
	(segment
		(start 409.974034 -246.436642)
		(end 410.159454 -246.251222)
		(width 0.14478)
		(layer "In11.Cu")
		(net "M_L_CPU0_SA_CB<7>")
	)
	(segment
		(start 440.977782 -245.36019)
		(end 441.395866 -245.36019)
		(width 0.14478)
		(layer "In11.Cu")
		(net "M_L_CPU0_SA_CB<7>")
	)
	(segment
		(start 411.511496 -245.837964)
		(end 411.71622 -245.837964)
		(width 0.14478)
		(layer "In11.Cu")
		(net "M_L_CPU0_SA_CB<7>")
	)
	(segment
		(start 449.662804 -243.660168)
		(end 450.088 -243.234972)
		(width 0.14478)
		(layer "In11.Cu")
		(net "M_L_CPU0_SA_CB<7>")
	)
	(segment
		(start 410.754322 -245.656354)
		(end 410.939742 -245.470934)
		(width 0.14478)
		(layer "In11.Cu")
		(net "M_L_CPU0_SA_CB<7>")
	)
	(segment
		(start 389.607806 -249.0216)
		(end 389.616188 -249.016774)
		(width 0.0889)
		(layer "In11.Cu")
		(net "M_L_CPU0_SA_CB<7>")
	)
	(segment
		(start 409.170632 -248.178828)
		(end 409.375356 -248.178828)
		(width 0.14478)
		(layer "In11.Cu")
		(net "M_L_CPU0_SA_CB<7>")
	)
	(segment
		(start 411.144466 -245.470934)
		(end 411.511496 -245.837964)
		(width 0.14478)
		(layer "In11.Cu")
		(net "M_L_CPU0_SA_CB<7>")
	)
	(segment
		(start 412.193994 -245.36019)
		(end 440.136788 -245.36019)
		(width 0.14478)
		(layer "In11.Cu")
		(net "M_L_CPU0_SA_CB<7>")
	)
	(segment
		(start 385.880864 -249.07875)
		(end 385.903216 -248.995438)
		(width 0.0889)
		(layer "In11.Cu")
		(net "M_L_CPU0_SA_CB<7>")
	)
	(segment
		(start 409.974034 -246.641366)
		(end 409.974034 -246.436642)
		(width 0.14478)
		(layer "In11.Cu")
		(net "M_L_CPU0_SA_CB<7>")
	)
	(segment
		(start 409.193746 -247.421654)
		(end 409.193746 -247.21693)
		(width 0.14478)
		(layer "In11.Cu")
		(net "M_L_CPU0_SA_CB<7>")
	)
	(segment
		(start 386.034788 -249.34418)
		(end 385.880864 -249.07875)
		(width 0.0889)
		(layer "In11.Cu")
		(net "M_L_CPU0_SA_CB<7>")
	)
	(segment
		(start 409.58389 -247.03151)
		(end 409.95092 -247.39854)
		(width 0.14478)
		(layer "In11.Cu")
		(net "M_L_CPU0_SA_CB<7>")
	)
	(segment
		(start 392.406632 -249.035316)
		(end 392.43 -249.0216)
		(width 0.0889)
		(layer "In11.Cu")
		(net "M_L_CPU0_SA_CB<7>")
	)
	(segment
		(start 409.560776 -247.993408)
		(end 409.560776 -247.788684)
		(width 0.14478)
		(layer "In11.Cu")
		(net "M_L_CPU0_SA_CB<7>")
	)
	(segment
		(start 409.375356 -248.178828)
		(end 409.560776 -247.993408)
		(width 0.14478)
		(layer "In11.Cu")
		(net "M_L_CPU0_SA_CB<7>")
	)
	(segment
		(start 408.803602 -247.811798)
		(end 409.170632 -248.178828)
		(width 0.14478)
		(layer "In11.Cu")
		(net "M_L_CPU0_SA_CB<7>")
	)
	(segment
		(start 441.961778 -244.589808)
		(end 442.165994 -244.590062)
		(width 0.14478)
		(layer "In11.Cu")
		(net "M_L_CPU0_SA_CB<7>")
	)
	(segment
		(start 408.410664 -249.14352)
		(end 408.780488 -248.773696)
		(width 0.14478)
		(layer "In11.Cu")
		(net "M_L_CPU0_SA_CB<7>")
	)
	(segment
		(start 442.165994 -244.590062)
		(end 442.246004 -244.510052)
		(width 0.14478)
		(layer "In11.Cu")
		(net "M_L_CPU0_SA_CB<7>")
	)
	(segment
		(start 440.281568 -245.21541)
		(end 440.281568 -244.794532)
		(width 0.14478)
		(layer "In11.Cu")
		(net "M_L_CPU0_SA_CB<7>")
	)
	(segment
		(start 408.780488 -248.568972)
		(end 408.413458 -248.201942)
		(width 0.14478)
		(layer "In11.Cu")
		(net "M_L_CPU0_SA_CB<7>")
	)
	(segment
		(start 410.341064 -247.21312)
		(end 410.341064 -247.008396)
		(width 0.14478)
		(layer "In11.Cu")
		(net "M_L_CPU0_SA_CB<7>")
	)
	(segment
		(start 389.033512 -249.016774)
		(end 389.041894 -249.0216)
		(width 0.0889)
		(layer "In11.Cu")
		(net "M_L_CPU0_SA_CB<7>")
	)
	(segment
		(start 396.92326 -250.053094)
		(end 397.832834 -249.14352)
		(width 0.14478)
		(layer "In11.Cu")
		(net "M_L_CPU0_SA_CB<7>")
	)
	(segment
		(start 441.577222 -244.409976)
		(end 441.781946 -244.409976)
		(width 0.14478)
		(layer "In11.Cu")
		(net "M_L_CPU0_SA_CB<7>")
	)
	(segment
		(start 441.391802 -244.595396)
		(end 441.577222 -244.409976)
		(width 0.14478)
		(layer "In11.Cu")
		(net "M_L_CPU0_SA_CB<7>")
	)
	(segment
		(start 408.780488 -248.773696)
		(end 408.780488 -248.568972)
		(width 0.14478)
		(layer "In11.Cu")
		(net "M_L_CPU0_SA_CB<7>")
	)
	(segment
		(start 408.598878 -247.811798)
		(end 408.803602 -247.811798)
		(width 0.14478)
		(layer "In11.Cu")
		(net "M_L_CPU0_SA_CB<7>")
	)
	(segment
		(start 440.688222 -244.649752)
		(end 440.833002 -244.794532)
		(width 0.14478)
		(layer "In11.Cu")
		(net "M_L_CPU0_SA_CB<7>")
	)
	(segment
		(start 440.426348 -244.649752)
		(end 440.688222 -244.649752)
		(width 0.14478)
		(layer "In11.Cu")
		(net "M_L_CPU0_SA_CB<7>")
	)
	(segment
		(start 444.956692 -243.660168)
		(end 449.662804 -243.660168)
		(width 0.14478)
		(layer "In11.Cu")
		(net "M_L_CPU0_SA_CB<7>")
	)
	(segment
		(start 441.57138 -245.184676)
		(end 441.57138 -244.979952)
		(width 0.14478)
		(layer "In11.Cu")
		(net "M_L_CPU0_SA_CB<7>")
	)
	(segment
		(start 410.939742 -245.470934)
		(end 411.144466 -245.470934)
		(width 0.14478)
		(layer "In11.Cu")
		(net "M_L_CPU0_SA_CB<7>")
	)
	(segment
		(start 442.246004 -244.510052)
		(end 444.106808 -244.510052)
		(width 0.14478)
		(layer "In11.Cu")
		(net "M_L_CPU0_SA_CB<7>")
	)
	(segment
		(start 408.413458 -247.997218)
		(end 408.598878 -247.811798)
		(width 0.14478)
		(layer "In11.Cu")
		(net "M_L_CPU0_SA_CB<7>")
	)
	(segment
		(start 440.136788 -245.36019)
		(end 440.281568 -245.21541)
		(width 0.14478)
		(layer "In11.Cu")
		(net "M_L_CPU0_SA_CB<7>")
	)
	(segment
		(start 409.379166 -247.03151)
		(end 409.58389 -247.03151)
		(width 0.14478)
		(layer "In11.Cu")
		(net "M_L_CPU0_SA_CB<7>")
	)
	(segment
		(start 440.833002 -244.794532)
		(end 440.833002 -245.21541)
		(width 0.14478)
		(layer "In11.Cu")
		(net "M_L_CPU0_SA_CB<7>")
	)
	(segment
		(start 391.48766 -249.0216)
		(end 391.502138 -249.013218)
		(width 0.0889)
		(layer "In11.Cu")
		(net "M_L_CPU0_SA_CB<7>")
	)
	(segment
		(start 410.159454 -246.251222)
		(end 410.364178 -246.251222)
		(width 0.14478)
		(layer "In11.Cu")
		(net "M_L_CPU0_SA_CB<7>")
	)
	(segment
		(start 444.106808 -244.510052)
		(end 444.956692 -243.660168)
		(width 0.14478)
		(layer "In11.Cu")
		(net "M_L_CPU0_SA_CB<7>")
	)
	(segment
		(start 393.539218 -249.097292)
		(end 394.49502 -250.053094)
		(width 0.0889)
		(layer "In11.Cu")
		(net "M_L_CPU0_SA_CB<7>")
	)
	(segment
		(start 410.731208 -246.618252)
		(end 410.935932 -246.618252)
		(width 0.14478)
		(layer "In11.Cu")
		(net "M_L_CPU0_SA_CB<7>")
	)
	(segment
		(start 409.95092 -247.39854)
		(end 410.155644 -247.39854)
		(width 0.14478)
		(layer "In11.Cu")
		(net "M_L_CPU0_SA_CB<7>")
	)
	(segment
		(start 411.121352 -246.228108)
		(end 410.754322 -245.861078)
		(width 0.14478)
		(layer "In11.Cu")
		(net "M_L_CPU0_SA_CB<7>")
	)
	(segment
		(start 441.781946 -244.409976)
		(end 441.961778 -244.589808)
		(width 0.14478)
		(layer "In11.Cu")
		(net "M_L_CPU0_SA_CB<7>")
	)
	(segment
		(start 440.281568 -244.794532)
		(end 440.426348 -244.649752)
		(width 0.14478)
		(layer "In11.Cu")
		(net "M_L_CPU0_SA_CB<7>")
	)
	(segment
		(start 388.093458 -249.016774)
		(end 388.10184 -249.0216)
		(width 0.0889)
		(layer "In11.Cu")
		(net "M_L_CPU0_SA_CB<7>")
	)
	(segment
		(start 441.395866 -245.36019)
		(end 441.57138 -245.184676)
		(width 0.14478)
		(layer "In11.Cu")
		(net "M_L_CPU0_SA_CB<7>")
	)
	(segment
		(start 410.341064 -247.008396)
		(end 409.974034 -246.641366)
		(width 0.14478)
		(layer "In11.Cu")
		(net "M_L_CPU0_SA_CB<7>")
	)
	(segment
		(start 408.413458 -248.201942)
		(end 408.413458 -247.997218)
		(width 0.14478)
		(layer "In11.Cu")
		(net "M_L_CPU0_SA_CB<7>")
	)
	(segment
		(start 392.783314 -249.010424)
		(end 392.80338 -249.021854)
		(width 0.0889)
		(layer "In11.Cu")
		(net "M_L_CPU0_SA_CB<7>")
	)
	(segment
		(start 411.121352 -246.432832)
		(end 411.121352 -246.228108)
		(width 0.14478)
		(layer "In11.Cu")
		(net "M_L_CPU0_SA_CB<7>")
	)
	(segment
		(start 441.391548 -244.80012)
		(end 441.391802 -244.595396)
		(width 0.14478)
		(layer "In11.Cu")
		(net "M_L_CPU0_SA_CB<7>")
	)
	(segment
		(start 394.49502 -250.053094)
		(end 395.74724 -250.053094)
		(width 0.0889)
		(layer "In11.Cu")
		(net "M_L_CPU0_SA_CB<7>")
	)
	(segment
		(start 441.57138 -244.979952)
		(end 441.391548 -244.80012)
		(width 0.14478)
		(layer "In11.Cu")
		(net "M_L_CPU0_SA_CB<7>")
	)
	(segment
		(start 409.193746 -247.21693)
		(end 409.379166 -247.03151)
		(width 0.14478)
		(layer "In11.Cu")
		(net "M_L_CPU0_SA_CB<7>")
	)
	(segment
		(start 397.832834 -249.14352)
		(end 408.410664 -249.14352)
		(width 0.14478)
		(layer "In11.Cu")
		(net "M_L_CPU0_SA_CB<7>")
	)
	(arc
		(start 387.727698 -249.0216)
		(mid 387.909949 -248.97125)
		(end 388.093458 -249.016774)
		(width 0.0889)
		(layer "In11.Cu")
		(net "M_L_CPU0_SA_CB<7>")
	)
	(arc
		(start 391.502138 -249.013218)
		(mid 391.683554 -248.970961)
		(end 391.862818 -249.0216)
		(width 0.0889)
		(layer "In11.Cu")
		(net "M_L_CPU0_SA_CB<7>")
	)
	(arc
		(start 389.616188 -249.016774)
		(mid 389.799696 -248.97128)
		(end 389.981948 -249.0216)
		(width 0.0889)
		(layer "In11.Cu")
		(net "M_L_CPU0_SA_CB<7>")
	)
	(arc
		(start 388.10184 -249.0216)
		(mid 388.384796 -249.097777)
		(end 388.667752 -249.0216)
		(width 0.0889)
		(layer "In11.Cu")
		(net "M_L_CPU0_SA_CB<7>")
	)
	(arc
		(start 390.921748 -249.0216)
		(mid 391.204704 -249.097777)
		(end 391.48766 -249.0216)
		(width 0.0889)
		(layer "In11.Cu")
		(net "M_L_CPU0_SA_CB<7>")
	)
	(arc
		(start 388.667752 -249.0216)
		(mid 388.850003 -248.97125)
		(end 389.033512 -249.016774)
		(width 0.0889)
		(layer "In11.Cu")
		(net "M_L_CPU0_SA_CB<7>")
	)
	(arc
		(start 390.54786 -249.0216)
		(mid 390.734804 -248.971345)
		(end 390.921748 -249.0216)
		(width 0.0889)
		(layer "In11.Cu")
		(net "M_L_CPU0_SA_CB<7>")
	)
	(arc
		(start 392.80338 -249.021854)
		(mid 392.939136 -249.078062)
		(end 393.084812 -249.097292)
		(width 0.0889)
		(layer "In11.Cu")
		(net "M_L_CPU0_SA_CB<7>")
	)
	(arc
		(start 387.161786 -249.0216)
		(mid 387.444742 -249.097777)
		(end 387.727698 -249.0216)
		(width 0.0889)
		(layer "In11.Cu")
		(net "M_L_CPU0_SA_CB<7>")
	)
	(arc
		(start 391.862818 -249.0216)
		(mid 392.132975 -249.098362)
		(end 392.406632 -249.035316)
		(width 0.0889)
		(layer "In11.Cu")
		(net "M_L_CPU0_SA_CB<7>")
	)
	(arc
		(start 385.903216 -248.995438)
		(mid 386.065548 -248.97262)
		(end 386.221986 -249.0216)
		(width 0.0889)
		(layer "In11.Cu")
		(net "M_L_CPU0_SA_CB<7>")
	)
	(arc
		(start 389.981948 -249.0216)
		(mid 390.264904 -249.097777)
		(end 390.54786 -249.0216)
		(width 0.0889)
		(layer "In11.Cu")
		(net "M_L_CPU0_SA_CB<7>")
	)
	(arc
		(start 386.221986 -249.0216)
		(mid 386.504942 -249.097777)
		(end 386.787898 -249.0216)
		(width 0.0889)
		(layer "In11.Cu")
		(net "M_L_CPU0_SA_CB<7>")
	)
	(arc
		(start 389.041894 -249.0216)
		(mid 389.32485 -249.097777)
		(end 389.607806 -249.0216)
		(width 0.0889)
		(layer "In11.Cu")
		(net "M_L_CPU0_SA_CB<7>")
	)
	(arc
		(start 386.787898 -249.0216)
		(mid 386.974842 -248.971345)
		(end 387.161786 -249.0216)
		(width 0.0889)
		(layer "In11.Cu")
		(net "M_L_CPU0_SA_CB<7>")
	)
	(arc
		(start 392.43 -249.0216)
		(mid 392.605239 -248.971529)
		(end 392.783314 -249.010424)
		(width 0.0889)
		(layer "In11.Cu")
		(net "M_L_CPU0_SA_CB<7>")
	)
	(segment
		(start 386.97789 -248.800112)
		(end 387.444742 -248.534174)
		(width 0.10668)
		(layer "F.Cu")
		(net "M_L_CPU0_SA_CB<6>")
	)
	(segment
		(start 437.195976 -243.515388)
		(end 437.195976 -242.564412)
		(width 0.14478)
		(layer "In11.Cu")
		(net "M_L_CPU0_SA_CB<6>")
	)
	(segment
		(start 447.939414 -242.19662)
		(end 447.939414 -241.723672)
		(width 0.14478)
		(layer "In11.Cu")
		(net "M_L_CPU0_SA_CB<6>")
	)
	(segment
		(start 448.897502 -241.578892)
		(end 448.635628 -241.578892)
		(width 0.14478)
		(layer "In11.Cu")
		(net "M_L_CPU0_SA_CB<6>")
	)
	(segment
		(start 436.093108 -243.515388)
		(end 436.093108 -242.564412)
		(width 0.14478)
		(layer "In11.Cu")
		(net "M_L_CPU0_SA_CB<6>")
	)
	(segment
		(start 388.206234 -248.206768)
		(end 388.197852 -248.211594)
		(width 0.0889)
		(layer "In11.Cu")
		(net "M_L_CPU0_SA_CB<6>")
	)
	(segment
		(start 447.53276 -241.578892)
		(end 447.38798 -241.723672)
		(width 0.14478)
		(layer "In11.Cu")
		(net "M_L_CPU0_SA_CB<6>")
	)
	(segment
		(start 436.644542 -242.564412)
		(end 436.644542 -243.515388)
		(width 0.14478)
		(layer "In11.Cu")
		(net "M_L_CPU0_SA_CB<6>")
	)
	(segment
		(start 387.290818 -248.268744)
		(end 387.444742 -248.534174)
		(width 0.0889)
		(layer "In11.Cu")
		(net "M_L_CPU0_SA_CB<6>")
	)
	(segment
		(start 411.42539 -243.660168)
		(end 406.851358 -248.2342)
		(width 0.14478)
		(layer "In11.Cu")
		(net "M_L_CPU0_SA_CB<6>")
	)
	(segment
		(start 394.087858 -248.670572)
		(end 393.57808 -248.160794)
		(width 0.0889)
		(layer "In11.Cu")
		(net "M_L_CPU0_SA_CB<6>")
	)
	(segment
		(start 448.490848 -242.19662)
		(end 448.346068 -242.3414)
		(width 0.14478)
		(layer "In11.Cu")
		(net "M_L_CPU0_SA_CB<6>")
	)
	(segment
		(start 438.154064 -242.419632)
		(end 437.89219 -242.419632)
		(width 0.14478)
		(layer "In11.Cu")
		(net "M_L_CPU0_SA_CB<6>")
	)
	(segment
		(start 447.38798 -241.815366)
		(end 447.2432 -241.960146)
		(width 0.14478)
		(layer "In11.Cu")
		(net "M_L_CPU0_SA_CB<6>")
	)
	(segment
		(start 435.541674 -242.564412)
		(end 435.541674 -243.515388)
		(width 0.14478)
		(layer "In11.Cu")
		(net "M_L_CPU0_SA_CB<6>")
	)
	(segment
		(start 392.34872 -248.222262)
		(end 392.330686 -248.211594)
		(width 0.0889)
		(layer "In11.Cu")
		(net "M_L_CPU0_SA_CB<6>")
	)
	(segment
		(start 406.851358 -248.2342)
		(end 397.455898 -248.2342)
		(width 0.14478)
		(layer "In11.Cu")
		(net "M_L_CPU0_SA_CB<6>")
	)
	(segment
		(start 444.168784 -242.81003)
		(end 440.671712 -242.81003)
		(width 0.14478)
		(layer "In11.Cu")
		(net "M_L_CPU0_SA_CB<6>")
	)
	(segment
		(start 390.451848 -248.211594)
		(end 390.443466 -248.206768)
		(width 0.0889)
		(layer "In11.Cu")
		(net "M_L_CPU0_SA_CB<6>")
	)
	(segment
		(start 438.298844 -243.515388)
		(end 438.298844 -242.564412)
		(width 0.14478)
		(layer "In11.Cu")
		(net "M_L_CPU0_SA_CB<6>")
	)
	(segment
		(start 450.088 -241.53495)
		(end 449.662804 -241.960146)
		(width 0.14478)
		(layer "In11.Cu")
		(net "M_L_CPU0_SA_CB<6>")
	)
	(segment
		(start 440.671712 -242.81003)
		(end 439.821574 -243.660168)
		(width 0.14478)
		(layer "In11.Cu")
		(net "M_L_CPU0_SA_CB<6>")
	)
	(segment
		(start 437.89219 -242.419632)
		(end 437.74741 -242.564412)
		(width 0.14478)
		(layer "In11.Cu")
		(net "M_L_CPU0_SA_CB<6>")
	)
	(segment
		(start 436.093108 -242.564412)
		(end 435.948328 -242.419632)
		(width 0.14478)
		(layer "In11.Cu")
		(net "M_L_CPU0_SA_CB<6>")
	)
	(segment
		(start 449.662804 -241.960146)
		(end 449.187062 -241.960146)
		(width 0.14478)
		(layer "In11.Cu")
		(net "M_L_CPU0_SA_CB<6>")
	)
	(segment
		(start 391.026142 -248.206768)
		(end 391.01776 -248.211594)
		(width 0.0889)
		(layer "In11.Cu")
		(net "M_L_CPU0_SA_CB<6>")
	)
	(segment
		(start 448.635628 -241.578892)
		(end 448.490848 -241.723672)
		(width 0.14478)
		(layer "In11.Cu")
		(net "M_L_CPU0_SA_CB<6>")
	)
	(segment
		(start 438.443624 -243.660168)
		(end 438.298844 -243.515388)
		(width 0.14478)
		(layer "In11.Cu")
		(net "M_L_CPU0_SA_CB<6>")
	)
	(segment
		(start 439.821574 -243.660168)
		(end 438.443624 -243.660168)
		(width 0.14478)
		(layer "In11.Cu")
		(net "M_L_CPU0_SA_CB<6>")
	)
	(segment
		(start 395.759686 -249.143774)
		(end 395.22654 -249.143774)
		(width 0.0889)
		(layer "In11.Cu")
		(net "M_L_CPU0_SA_CB<6>")
	)
	(segment
		(start 394.753338 -248.670572)
		(end 394.087858 -248.670572)
		(width 0.0889)
		(layer "In11.Cu")
		(net "M_L_CPU0_SA_CB<6>")
	)
	(segment
		(start 396.546324 -249.143774)
		(end 395.759686 -249.143774)
		(width 0.14478)
		(layer "In11.Cu")
		(net "M_L_CPU0_SA_CB<6>")
	)
	(segment
		(start 436.789322 -242.419632)
		(end 436.644542 -242.564412)
		(width 0.14478)
		(layer "In11.Cu")
		(net "M_L_CPU0_SA_CB<6>")
	)
	(segment
		(start 437.195976 -242.564412)
		(end 437.051196 -242.419632)
		(width 0.14478)
		(layer "In11.Cu")
		(net "M_L_CPU0_SA_CB<6>")
	)
	(segment
		(start 436.644542 -243.515388)
		(end 436.499762 -243.660168)
		(width 0.14478)
		(layer "In11.Cu")
		(net "M_L_CPU0_SA_CB<6>")
	)
	(segment
		(start 387.31317 -248.185432)
		(end 387.290818 -248.268744)
		(width 0.0889)
		(layer "In11.Cu")
		(net "M_L_CPU0_SA_CB<6>")
	)
	(segment
		(start 436.237888 -243.660168)
		(end 436.093108 -243.515388)
		(width 0.14478)
		(layer "In11.Cu")
		(net "M_L_CPU0_SA_CB<6>")
	)
	(segment
		(start 445.018668 -241.960146)
		(end 444.168784 -242.81003)
		(width 0.14478)
		(layer "In11.Cu")
		(net "M_L_CPU0_SA_CB<6>")
	)
	(segment
		(start 435.541674 -243.515388)
		(end 435.396894 -243.660168)
		(width 0.14478)
		(layer "In11.Cu")
		(net "M_L_CPU0_SA_CB<6>")
	)
	(segment
		(start 447.939414 -241.723672)
		(end 447.794634 -241.578892)
		(width 0.14478)
		(layer "In11.Cu")
		(net "M_L_CPU0_SA_CB<6>")
	)
	(segment
		(start 447.2432 -241.960146)
		(end 445.018668 -241.960146)
		(width 0.14478)
		(layer "In11.Cu")
		(net "M_L_CPU0_SA_CB<6>")
	)
	(segment
		(start 449.042282 -241.723672)
		(end 448.897502 -241.578892)
		(width 0.14478)
		(layer "In11.Cu")
		(net "M_L_CPU0_SA_CB<6>")
	)
	(segment
		(start 397.455898 -248.2342)
		(end 396.546324 -249.143774)
		(width 0.14478)
		(layer "In11.Cu")
		(net "M_L_CPU0_SA_CB<6>")
	)
	(segment
		(start 435.396894 -243.660168)
		(end 411.42539 -243.660168)
		(width 0.14478)
		(layer "In11.Cu")
		(net "M_L_CPU0_SA_CB<6>")
	)
	(segment
		(start 447.794634 -241.578892)
		(end 447.53276 -241.578892)
		(width 0.14478)
		(layer "In11.Cu")
		(net "M_L_CPU0_SA_CB<6>")
	)
	(segment
		(start 435.948328 -242.419632)
		(end 435.686454 -242.419632)
		(width 0.14478)
		(layer "In11.Cu")
		(net "M_L_CPU0_SA_CB<6>")
	)
	(segment
		(start 437.051196 -242.419632)
		(end 436.789322 -242.419632)
		(width 0.14478)
		(layer "In11.Cu")
		(net "M_L_CPU0_SA_CB<6>")
	)
	(segment
		(start 437.74741 -242.564412)
		(end 437.74741 -243.515388)
		(width 0.14478)
		(layer "In11.Cu")
		(net "M_L_CPU0_SA_CB<6>")
	)
	(segment
		(start 448.084194 -242.3414)
		(end 447.939414 -242.19662)
		(width 0.14478)
		(layer "In11.Cu")
		(net "M_L_CPU0_SA_CB<6>")
	)
	(segment
		(start 391.957052 -248.211848)
		(end 391.945114 -248.218706)
		(width 0.0889)
		(layer "In11.Cu")
		(net "M_L_CPU0_SA_CB<6>")
	)
	(segment
		(start 438.298844 -242.564412)
		(end 438.154064 -242.419632)
		(width 0.14478)
		(layer "In11.Cu")
		(net "M_L_CPU0_SA_CB<6>")
	)
	(segment
		(start 447.38798 -241.723672)
		(end 447.38798 -241.815366)
		(width 0.14478)
		(layer "In11.Cu")
		(net "M_L_CPU0_SA_CB<6>")
	)
	(segment
		(start 437.74741 -243.515388)
		(end 437.60263 -243.660168)
		(width 0.14478)
		(layer "In11.Cu")
		(net "M_L_CPU0_SA_CB<6>")
	)
	(segment
		(start 449.042282 -241.815366)
		(end 449.042282 -241.723672)
		(width 0.14478)
		(layer "In11.Cu")
		(net "M_L_CPU0_SA_CB<6>")
	)
	(segment
		(start 448.346068 -242.3414)
		(end 448.084194 -242.3414)
		(width 0.14478)
		(layer "In11.Cu")
		(net "M_L_CPU0_SA_CB<6>")
	)
	(segment
		(start 436.499762 -243.660168)
		(end 436.237888 -243.660168)
		(width 0.14478)
		(layer "In11.Cu")
		(net "M_L_CPU0_SA_CB<6>")
	)
	(segment
		(start 437.340756 -243.660168)
		(end 437.195976 -243.515388)
		(width 0.14478)
		(layer "In11.Cu")
		(net "M_L_CPU0_SA_CB<6>")
	)
	(segment
		(start 448.490848 -241.723672)
		(end 448.490848 -242.19662)
		(width 0.14478)
		(layer "In11.Cu")
		(net "M_L_CPU0_SA_CB<6>")
	)
	(segment
		(start 435.686454 -242.419632)
		(end 435.541674 -242.564412)
		(width 0.14478)
		(layer "In11.Cu")
		(net "M_L_CPU0_SA_CB<6>")
	)
	(segment
		(start 391.970768 -248.203974)
		(end 391.957052 -248.211848)
		(width 0.0889)
		(layer "In11.Cu")
		(net "M_L_CPU0_SA_CB<6>")
	)
	(segment
		(start 395.22654 -249.143774)
		(end 394.753338 -248.670572)
		(width 0.0889)
		(layer "In11.Cu")
		(net "M_L_CPU0_SA_CB<6>")
	)
	(segment
		(start 393.57808 -248.160794)
		(end 393.084812 -248.160794)
		(width 0.0889)
		(layer "In11.Cu")
		(net "M_L_CPU0_SA_CB<6>")
	)
	(segment
		(start 449.187062 -241.960146)
		(end 449.042282 -241.815366)
		(width 0.14478)
		(layer "In11.Cu")
		(net "M_L_CPU0_SA_CB<6>")
	)
	(segment
		(start 437.60263 -243.660168)
		(end 437.340756 -243.660168)
		(width 0.14478)
		(layer "In11.Cu")
		(net "M_L_CPU0_SA_CB<6>")
	)
	(arc
		(start 390.443466 -248.206768)
		(mid 390.259958 -248.161274)
		(end 390.077706 -248.211594)
		(width 0.0889)
		(layer "In11.Cu")
		(net "M_L_CPU0_SA_CB<6>")
	)
	(arc
		(start 391.945114 -248.218706)
		(mid 391.66758 -248.287687)
		(end 391.391902 -248.211594)
		(width 0.0889)
		(layer "In11.Cu")
		(net "M_L_CPU0_SA_CB<6>")
	)
	(arc
		(start 392.330686 -248.211594)
		(mid 392.151699 -248.161424)
		(end 391.970768 -248.203974)
		(width 0.0889)
		(layer "In11.Cu")
		(net "M_L_CPU0_SA_CB<6>")
	)
	(arc
		(start 388.571994 -248.211594)
		(mid 388.389743 -248.161244)
		(end 388.206234 -248.206768)
		(width 0.0889)
		(layer "In11.Cu")
		(net "M_L_CPU0_SA_CB<6>")
	)
	(arc
		(start 390.077706 -248.211594)
		(mid 389.79475 -248.287771)
		(end 389.511794 -248.211594)
		(width 0.0889)
		(layer "In11.Cu")
		(net "M_L_CPU0_SA_CB<6>")
	)
	(arc
		(start 389.137906 -248.211594)
		(mid 388.85495 -248.287771)
		(end 388.571994 -248.211594)
		(width 0.0889)
		(layer "In11.Cu")
		(net "M_L_CPU0_SA_CB<6>")
	)
	(arc
		(start 391.391902 -248.211594)
		(mid 391.209651 -248.161244)
		(end 391.026142 -248.206768)
		(width 0.0889)
		(layer "In11.Cu")
		(net "M_L_CPU0_SA_CB<6>")
	)
	(arc
		(start 392.89736 -248.211594)
		(mid 392.624416 -248.288174)
		(end 392.34872 -248.222262)
		(width 0.0889)
		(layer "In11.Cu")
		(net "M_L_CPU0_SA_CB<6>")
	)
	(arc
		(start 389.511794 -248.211594)
		(mid 389.32485 -248.161339)
		(end 389.137906 -248.211594)
		(width 0.0889)
		(layer "In11.Cu")
		(net "M_L_CPU0_SA_CB<6>")
	)
	(arc
		(start 388.197852 -248.211594)
		(mid 387.914896 -248.287771)
		(end 387.63194 -248.211594)
		(width 0.0889)
		(layer "In11.Cu")
		(net "M_L_CPU0_SA_CB<6>")
	)
	(arc
		(start 387.63194 -248.211594)
		(mid 387.475502 -248.162623)
		(end 387.31317 -248.185432)
		(width 0.0889)
		(layer "In11.Cu")
		(net "M_L_CPU0_SA_CB<6>")
	)
	(arc
		(start 393.084812 -248.160794)
		(mid 392.987723 -248.173784)
		(end 392.89736 -248.211594)
		(width 0.0889)
		(layer "In11.Cu")
		(net "M_L_CPU0_SA_CB<6>")
	)
	(arc
		(start 391.01776 -248.211594)
		(mid 390.734804 -248.287771)
		(end 390.451848 -248.211594)
		(width 0.0889)
		(layer "In11.Cu")
		(net "M_L_CPU0_SA_CB<6>")
	)
	(segment
		(start 385.098036 -248.800112)
		(end 385.564888 -248.534174)
		(width 0.10668)
		(layer "F.Cu")
		(net "M_L_CPU0_SA_CB<5>")
	)
	(segment
		(start 451.454012 -241.931952)
		(end 451.715886 -241.931952)
		(width 0.14478)
		(layer "In11.Cu")
		(net "M_L_CPU0_SA_CB<5>")
	)
	(segment
		(start 451.860666 -242.66525)
		(end 452.005446 -242.81003)
		(width 0.14478)
		(layer "In11.Cu")
		(net "M_L_CPU0_SA_CB<5>")
	)
	(segment
		(start 395.31036 -249.598434)
		(end 395.80439 -249.598434)
		(width 0.0889)
		(layer "In11.Cu")
		(net "M_L_CPU0_SA_CB<5>")
	)
	(segment
		(start 392.87704 -248.844054)
		(end 392.89863 -248.8565)
		(width 0.0889)
		(layer "In11.Cu")
		(net "M_L_CPU0_SA_CB<5>")
	)
	(segment
		(start 452.55688 -241.931952)
		(end 452.818754 -241.931952)
		(width 0.14478)
		(layer "In11.Cu")
		(net "M_L_CPU0_SA_CB<5>")
	)
	(segment
		(start 391.01776 -248.856754)
		(end 391.026142 -248.86158)
		(width 0.0889)
		(layer "In11.Cu")
		(net "M_L_CPU0_SA_CB<5>")
	)
	(segment
		(start 396.734792 -249.598434)
		(end 397.644366 -248.68886)
		(width 0.14478)
		(layer "In11.Cu")
		(net "M_L_CPU0_SA_CB<5>")
	)
	(segment
		(start 452.26732 -242.81003)
		(end 452.4121 -242.66525)
		(width 0.14478)
		(layer "In11.Cu")
		(net "M_L_CPU0_SA_CB<5>")
	)
	(segment
		(start 386.683504 -248.86158)
		(end 386.691886 -248.856754)
		(width 0.0889)
		(layer "In11.Cu")
		(net "M_L_CPU0_SA_CB<5>")
	)
	(segment
		(start 391.391902 -248.856754)
		(end 391.41527 -248.843038)
		(width 0.0889)
		(layer "In11.Cu")
		(net "M_L_CPU0_SA_CB<5>")
	)
	(segment
		(start 390.443466 -248.86158)
		(end 390.451848 -248.856754)
		(width 0.0889)
		(layer "In11.Cu")
		(net "M_L_CPU0_SA_CB<5>")
	)
	(segment
		(start 411.218888 -244.510052)
		(end 439.880502 -244.510052)
		(width 0.14478)
		(layer "In11.Cu")
		(net "M_L_CPU0_SA_CB<5>")
	)
	(segment
		(start 451.860666 -242.076732)
		(end 451.860666 -242.66525)
		(width 0.14478)
		(layer "In11.Cu")
		(net "M_L_CPU0_SA_CB<5>")
	)
	(segment
		(start 440.730386 -243.660168)
		(end 444.230506 -243.660168)
		(width 0.14478)
		(layer "In11.Cu")
		(net "M_L_CPU0_SA_CB<5>")
	)
	(segment
		(start 445.080644 -242.81003)
		(end 451.164452 -242.81003)
		(width 0.14478)
		(layer "In11.Cu")
		(net "M_L_CPU0_SA_CB<5>")
	)
	(segment
		(start 453.763126 -242.81003)
		(end 454.188068 -242.385088)
		(width 0.14478)
		(layer "In11.Cu")
		(net "M_L_CPU0_SA_CB<5>")
	)
	(segment
		(start 451.309232 -242.66525)
		(end 451.309232 -242.076732)
		(width 0.14478)
		(layer "In11.Cu")
		(net "M_L_CPU0_SA_CB<5>")
	)
	(segment
		(start 395.80439 -249.598434)
		(end 396.734792 -249.598434)
		(width 0.14478)
		(layer "In11.Cu")
		(net "M_L_CPU0_SA_CB<5>")
	)
	(segment
		(start 397.644366 -248.68886)
		(end 407.04008 -248.68886)
		(width 0.14478)
		(layer "In11.Cu")
		(net "M_L_CPU0_SA_CB<5>")
	)
	(segment
		(start 444.230506 -243.660168)
		(end 445.080644 -242.81003)
		(width 0.14478)
		(layer "In11.Cu")
		(net "M_L_CPU0_SA_CB<5>")
	)
	(segment
		(start 407.04008 -248.68886)
		(end 411.218888 -244.510052)
		(width 0.14478)
		(layer "In11.Cu")
		(net "M_L_CPU0_SA_CB<5>")
	)
	(segment
		(start 452.963534 -242.076732)
		(end 452.963534 -242.66525)
		(width 0.14478)
		(layer "In11.Cu")
		(net "M_L_CPU0_SA_CB<5>")
	)
	(segment
		(start 392.319764 -248.865136)
		(end 392.334242 -248.856754)
		(width 0.0889)
		(layer "In11.Cu")
		(net "M_L_CPU0_SA_CB<5>")
	)
	(segment
		(start 452.4121 -242.66525)
		(end 452.4121 -242.076732)
		(width 0.14478)
		(layer "In11.Cu")
		(net "M_L_CPU0_SA_CB<5>")
	)
	(segment
		(start 452.818754 -241.931952)
		(end 452.963534 -242.076732)
		(width 0.14478)
		(layer "In11.Cu")
		(net "M_L_CPU0_SA_CB<5>")
	)
	(segment
		(start 388.197852 -248.856754)
		(end 388.206234 -248.86158)
		(width 0.0889)
		(layer "In11.Cu")
		(net "M_L_CPU0_SA_CB<5>")
	)
	(segment
		(start 387.257798 -248.856754)
		(end 387.26618 -248.86158)
		(width 0.0889)
		(layer "In11.Cu")
		(net "M_L_CPU0_SA_CB<5>")
	)
	(segment
		(start 393.085066 -248.906792)
		(end 394.618718 -248.906792)
		(width 0.0889)
		(layer "In11.Cu")
		(net "M_L_CPU0_SA_CB<5>")
	)
	(segment
		(start 451.715886 -241.931952)
		(end 451.860666 -242.076732)
		(width 0.14478)
		(layer "In11.Cu")
		(net "M_L_CPU0_SA_CB<5>")
	)
	(segment
		(start 452.005446 -242.81003)
		(end 452.26732 -242.81003)
		(width 0.14478)
		(layer "In11.Cu")
		(net "M_L_CPU0_SA_CB<5>")
	)
	(segment
		(start 452.4121 -242.076732)
		(end 452.55688 -241.931952)
		(width 0.14478)
		(layer "In11.Cu")
		(net "M_L_CPU0_SA_CB<5>")
	)
	(segment
		(start 385.564888 -248.534174)
		(end 385.718812 -248.799604)
		(width 0.0889)
		(layer "In11.Cu")
		(net "M_L_CPU0_SA_CB<5>")
	)
	(segment
		(start 451.309232 -242.076732)
		(end 451.454012 -241.931952)
		(width 0.14478)
		(layer "In11.Cu")
		(net "M_L_CPU0_SA_CB<5>")
	)
	(segment
		(start 385.718812 -248.799604)
		(end 385.814824 -248.825004)
		(width 0.0889)
		(layer "In11.Cu")
		(net "M_L_CPU0_SA_CB<5>")
	)
	(segment
		(start 451.164452 -242.81003)
		(end 451.309232 -242.66525)
		(width 0.14478)
		(layer "In11.Cu")
		(net "M_L_CPU0_SA_CB<5>")
	)
	(segment
		(start 394.618718 -248.906792)
		(end 395.31036 -249.598434)
		(width 0.0889)
		(layer "In11.Cu")
		(net "M_L_CPU0_SA_CB<5>")
	)
	(segment
		(start 452.963534 -242.66525)
		(end 453.108314 -242.81003)
		(width 0.14478)
		(layer "In11.Cu")
		(net "M_L_CPU0_SA_CB<5>")
	)
	(segment
		(start 453.108314 -242.81003)
		(end 453.763126 -242.81003)
		(width 0.14478)
		(layer "In11.Cu")
		(net "M_L_CPU0_SA_CB<5>")
	)
	(segment
		(start 439.880502 -244.510052)
		(end 440.730386 -243.660168)
		(width 0.14478)
		(layer "In11.Cu")
		(net "M_L_CPU0_SA_CB<5>")
	)
	(arc
		(start 392.89863 -248.8565)
		(mid 392.988529 -248.893957)
		(end 393.085066 -248.906792)
		(width 0.0889)
		(layer "In11.Cu")
		(net "M_L_CPU0_SA_CB<5>")
	)
	(arc
		(start 388.206234 -248.86158)
		(mid 388.389742 -248.907074)
		(end 388.571994 -248.856754)
		(width 0.0889)
		(layer "In11.Cu")
		(net "M_L_CPU0_SA_CB<5>")
	)
	(arc
		(start 389.137906 -248.856754)
		(mid 389.32485 -248.907009)
		(end 389.511794 -248.856754)
		(width 0.0889)
		(layer "In11.Cu")
		(net "M_L_CPU0_SA_CB<5>")
	)
	(arc
		(start 390.451848 -248.856754)
		(mid 390.734804 -248.780577)
		(end 391.01776 -248.856754)
		(width 0.0889)
		(layer "In11.Cu")
		(net "M_L_CPU0_SA_CB<5>")
	)
	(arc
		(start 388.571994 -248.856754)
		(mid 388.85495 -248.780577)
		(end 389.137906 -248.856754)
		(width 0.0889)
		(layer "In11.Cu")
		(net "M_L_CPU0_SA_CB<5>")
	)
	(arc
		(start 391.959084 -248.856754)
		(mid 392.138347 -248.907418)
		(end 392.319764 -248.865136)
		(width 0.0889)
		(layer "In11.Cu")
		(net "M_L_CPU0_SA_CB<5>")
	)
	(arc
		(start 392.334242 -248.856754)
		(mid 392.604011 -248.780731)
		(end 392.87704 -248.844054)
		(width 0.0889)
		(layer "In11.Cu")
		(net "M_L_CPU0_SA_CB<5>")
	)
	(arc
		(start 386.691886 -248.856754)
		(mid 386.974842 -248.780577)
		(end 387.257798 -248.856754)
		(width 0.0889)
		(layer "In11.Cu")
		(net "M_L_CPU0_SA_CB<5>")
	)
	(arc
		(start 390.077706 -248.856754)
		(mid 390.259957 -248.907104)
		(end 390.443466 -248.86158)
		(width 0.0889)
		(layer "In11.Cu")
		(net "M_L_CPU0_SA_CB<5>")
	)
	(arc
		(start 391.41527 -248.843038)
		(mid 391.688924 -248.780095)
		(end 391.959084 -248.856754)
		(width 0.0889)
		(layer "In11.Cu")
		(net "M_L_CPU0_SA_CB<5>")
	)
	(arc
		(start 389.511794 -248.856754)
		(mid 389.79475 -248.780577)
		(end 390.077706 -248.856754)
		(width 0.0889)
		(layer "In11.Cu")
		(net "M_L_CPU0_SA_CB<5>")
	)
	(arc
		(start 387.26618 -248.86158)
		(mid 387.449688 -248.907074)
		(end 387.63194 -248.856754)
		(width 0.0889)
		(layer "In11.Cu")
		(net "M_L_CPU0_SA_CB<5>")
	)
	(arc
		(start 387.63194 -248.856754)
		(mid 387.914896 -248.780577)
		(end 388.197852 -248.856754)
		(width 0.0889)
		(layer "In11.Cu")
		(net "M_L_CPU0_SA_CB<5>")
	)
	(arc
		(start 391.026142 -248.86158)
		(mid 391.20965 -248.907074)
		(end 391.391902 -248.856754)
		(width 0.0889)
		(layer "In11.Cu")
		(net "M_L_CPU0_SA_CB<5>")
	)
	(arc
		(start 385.814824 -248.825004)
		(mid 386.070032 -248.781527)
		(end 386.317744 -248.856754)
		(width 0.0889)
		(layer "In11.Cu")
		(net "M_L_CPU0_SA_CB<5>")
	)
	(arc
		(start 386.317744 -248.856754)
		(mid 386.499995 -248.907104)
		(end 386.683504 -248.86158)
		(width 0.0889)
		(layer "In11.Cu")
		(net "M_L_CPU0_SA_CB<5>")
	)
	(segment
		(start 386.50799 -247.990106)
		(end 386.974842 -247.724168)
		(width 0.10668)
		(layer "F.Cu")
		(net "M_L_CPU0_SA_CB<4>")
	)
	(segment
		(start 406.662636 -247.77954)
		(end 397.267176 -247.77954)
		(width 0.14478)
		(layer "In11.Cu")
		(net "M_L_CPU0_SA_CB<4>")
	)
	(segment
		(start 453.763126 -241.110008)
		(end 444.956692 -241.110008)
		(width 0.14478)
		(layer "In11.Cu")
		(net "M_L_CPU0_SA_CB<4>")
	)
	(segment
		(start 434.145944 -241.960146)
		(end 434.001164 -242.104926)
		(width 0.14478)
		(layer "In11.Cu")
		(net "M_L_CPU0_SA_CB<4>")
	)
	(segment
		(start 432.898296 -242.104926)
		(end 432.898296 -242.955572)
		(width 0.14478)
		(layer "In11.Cu")
		(net "M_L_CPU0_SA_CB<4>")
	)
	(segment
		(start 389.616188 -248.051574)
		(end 389.607806 -248.046748)
		(width 0.0889)
		(layer "In11.Cu")
		(net "M_L_CPU0_SA_CB<4>")
	)
	(segment
		(start 416.800538 -242.081812)
		(end 413.417512 -242.081812)
		(width 0.14478)
		(layer "In11.Cu")
		(net "M_L_CPU0_SA_CB<4>")
	)
	(segment
		(start 433.043076 -241.960146)
		(end 432.898296 -242.104926)
		(width 0.14478)
		(layer "In11.Cu")
		(net "M_L_CPU0_SA_CB<4>")
	)
	(segment
		(start 389.041894 -248.046748)
		(end 389.033512 -248.051574)
		(width 0.0889)
		(layer "In11.Cu")
		(net "M_L_CPU0_SA_CB<4>")
	)
	(segment
		(start 432.753516 -243.100352)
		(end 432.491642 -243.100352)
		(width 0.14478)
		(layer "In11.Cu")
		(net "M_L_CPU0_SA_CB<4>")
	)
	(segment
		(start 416.922204 -241.960146)
		(end 416.800538 -242.081812)
		(width 0.14478)
		(layer "In11.Cu")
		(net "M_L_CPU0_SA_CB<4>")
	)
	(segment
		(start 433.856384 -243.100352)
		(end 433.59451 -243.100352)
		(width 0.14478)
		(layer "In11.Cu")
		(net "M_L_CPU0_SA_CB<4>")
	)
	(segment
		(start 433.59451 -243.100352)
		(end 433.44973 -242.955572)
		(width 0.14478)
		(layer "In11.Cu")
		(net "M_L_CPU0_SA_CB<4>")
	)
	(segment
		(start 432.346862 -242.955572)
		(end 432.346862 -242.104926)
		(width 0.14478)
		(layer "In11.Cu")
		(net "M_L_CPU0_SA_CB<4>")
	)
	(segment
		(start 388.10184 -248.046748)
		(end 388.093458 -248.051574)
		(width 0.0889)
		(layer "In11.Cu")
		(net "M_L_CPU0_SA_CB<4>")
	)
	(segment
		(start 454.188068 -240.685066)
		(end 453.763126 -241.110008)
		(width 0.14478)
		(layer "In11.Cu")
		(net "M_L_CPU0_SA_CB<4>")
	)
	(segment
		(start 433.30495 -241.960146)
		(end 433.043076 -241.960146)
		(width 0.14478)
		(layer "In11.Cu")
		(net "M_L_CPU0_SA_CB<4>")
	)
	(segment
		(start 433.44973 -242.955572)
		(end 433.44973 -242.104926)
		(width 0.14478)
		(layer "In11.Cu")
		(net "M_L_CPU0_SA_CB<4>")
	)
	(segment
		(start 396.357602 -248.689114)
		(end 395.753844 -248.689114)
		(width 0.14478)
		(layer "In11.Cu")
		(net "M_L_CPU0_SA_CB<4>")
	)
	(segment
		(start 392.438382 -248.053606)
		(end 392.426698 -248.046748)
		(width 0.0889)
		(layer "In11.Cu")
		(net "M_L_CPU0_SA_CB<4>")
	)
	(segment
		(start 433.44973 -242.104926)
		(end 433.30495 -241.960146)
		(width 0.14478)
		(layer "In11.Cu")
		(net "M_L_CPU0_SA_CB<4>")
	)
	(segment
		(start 413.417512 -242.081812)
		(end 412.358332 -243.140992)
		(width 0.14478)
		(layer "In11.Cu")
		(net "M_L_CPU0_SA_CB<4>")
	)
	(segment
		(start 395.17574 -248.689114)
		(end 394.920978 -248.434352)
		(width 0.0889)
		(layer "In11.Cu")
		(net "M_L_CPU0_SA_CB<4>")
	)
	(segment
		(start 432.346862 -242.104926)
		(end 432.202082 -241.960146)
		(width 0.14478)
		(layer "In11.Cu")
		(net "M_L_CPU0_SA_CB<4>")
	)
	(segment
		(start 391.873486 -248.039636)
		(end 391.861548 -248.046494)
		(width 0.0889)
		(layer "In11.Cu")
		(net "M_L_CPU0_SA_CB<4>")
	)
	(segment
		(start 412.358332 -243.140992)
		(end 411.301184 -243.140992)
		(width 0.14478)
		(layer "In11.Cu")
		(net "M_L_CPU0_SA_CB<4>")
	)
	(segment
		(start 444.956692 -241.110008)
		(end 444.106554 -241.960146)
		(width 0.14478)
		(layer "In11.Cu")
		(net "M_L_CPU0_SA_CB<4>")
	)
	(segment
		(start 391.861548 -248.046494)
		(end 391.845292 -248.055892)
		(width 0.0889)
		(layer "In11.Cu")
		(net "M_L_CPU0_SA_CB<4>")
	)
	(segment
		(start 394.920978 -248.434352)
		(end 394.121132 -248.434352)
		(width 0.0889)
		(layer "In11.Cu")
		(net "M_L_CPU0_SA_CB<4>")
	)
	(segment
		(start 393.657074 -247.970294)
		(end 393.084812 -247.970294)
		(width 0.0889)
		(layer "In11.Cu")
		(net "M_L_CPU0_SA_CB<4>")
	)
	(segment
		(start 434.001164 -242.955572)
		(end 433.856384 -243.100352)
		(width 0.14478)
		(layer "In11.Cu")
		(net "M_L_CPU0_SA_CB<4>")
	)
	(segment
		(start 387.128766 -247.989598)
		(end 386.974842 -247.724168)
		(width 0.0889)
		(layer "In11.Cu")
		(net "M_L_CPU0_SA_CB<4>")
	)
	(segment
		(start 432.898296 -242.955572)
		(end 432.753516 -243.100352)
		(width 0.14478)
		(layer "In11.Cu")
		(net "M_L_CPU0_SA_CB<4>")
	)
	(segment
		(start 387.224778 -248.014998)
		(end 387.128766 -247.989598)
		(width 0.0889)
		(layer "In11.Cu")
		(net "M_L_CPU0_SA_CB<4>")
	)
	(segment
		(start 397.267176 -247.77954)
		(end 396.357602 -248.689114)
		(width 0.14478)
		(layer "In11.Cu")
		(net "M_L_CPU0_SA_CB<4>")
	)
	(segment
		(start 394.121132 -248.434352)
		(end 393.657074 -247.970294)
		(width 0.0889)
		(layer "In11.Cu")
		(net "M_L_CPU0_SA_CB<4>")
	)
	(segment
		(start 411.301184 -243.140992)
		(end 406.662636 -247.77954)
		(width 0.14478)
		(layer "In11.Cu")
		(net "M_L_CPU0_SA_CB<4>")
	)
	(segment
		(start 432.491642 -243.100352)
		(end 432.346862 -242.955572)
		(width 0.14478)
		(layer "In11.Cu")
		(net "M_L_CPU0_SA_CB<4>")
	)
	(segment
		(start 434.001164 -242.104926)
		(end 434.001164 -242.955572)
		(width 0.14478)
		(layer "In11.Cu")
		(net "M_L_CPU0_SA_CB<4>")
	)
	(segment
		(start 432.202082 -241.960146)
		(end 416.922204 -241.960146)
		(width 0.14478)
		(layer "In11.Cu")
		(net "M_L_CPU0_SA_CB<4>")
	)
	(segment
		(start 395.753844 -248.689114)
		(end 395.17574 -248.689114)
		(width 0.0889)
		(layer "In11.Cu")
		(net "M_L_CPU0_SA_CB<4>")
	)
	(segment
		(start 444.106554 -241.960146)
		(end 434.145944 -241.960146)
		(width 0.14478)
		(layer "In11.Cu")
		(net "M_L_CPU0_SA_CB<4>")
	)
	(arc
		(start 387.727698 -248.046748)
		(mid 387.479985 -247.971528)
		(end 387.224778 -248.014998)
		(width 0.0889)
		(layer "In11.Cu")
		(net "M_L_CPU0_SA_CB<4>")
	)
	(arc
		(start 388.093458 -248.051574)
		(mid 387.90995 -248.097068)
		(end 387.727698 -248.046748)
		(width 0.0889)
		(layer "In11.Cu")
		(net "M_L_CPU0_SA_CB<4>")
	)
	(arc
		(start 391.48766 -248.046748)
		(mid 391.204704 -247.970571)
		(end 390.921748 -248.046748)
		(width 0.0889)
		(layer "In11.Cu")
		(net "M_L_CPU0_SA_CB<4>")
	)
	(arc
		(start 392.426698 -248.046748)
		(mid 392.15102 -247.970618)
		(end 391.873486 -248.039636)
		(width 0.0889)
		(layer "In11.Cu")
		(net "M_L_CPU0_SA_CB<4>")
	)
	(arc
		(start 389.607806 -248.046748)
		(mid 389.32485 -247.970571)
		(end 389.041894 -248.046748)
		(width 0.0889)
		(layer "In11.Cu")
		(net "M_L_CPU0_SA_CB<4>")
	)
	(arc
		(start 391.845292 -248.055892)
		(mid 391.66531 -248.096992)
		(end 391.48766 -248.046748)
		(width 0.0889)
		(layer "In11.Cu")
		(net "M_L_CPU0_SA_CB<4>")
	)
	(arc
		(start 389.981948 -248.046748)
		(mid 389.799697 -248.097098)
		(end 389.616188 -248.051574)
		(width 0.0889)
		(layer "In11.Cu")
		(net "M_L_CPU0_SA_CB<4>")
	)
	(arc
		(start 390.921748 -248.046748)
		(mid 390.734804 -248.097003)
		(end 390.54786 -248.046748)
		(width 0.0889)
		(layer "In11.Cu")
		(net "M_L_CPU0_SA_CB<4>")
	)
	(arc
		(start 392.801094 -248.046748)
		(mid 392.620636 -248.097192)
		(end 392.438382 -248.053606)
		(width 0.0889)
		(layer "In11.Cu")
		(net "M_L_CPU0_SA_CB<4>")
	)
	(arc
		(start 390.54786 -248.046748)
		(mid 390.264904 -247.970571)
		(end 389.981948 -248.046748)
		(width 0.0889)
		(layer "In11.Cu")
		(net "M_L_CPU0_SA_CB<4>")
	)
	(arc
		(start 388.667752 -248.046748)
		(mid 388.384796 -247.970571)
		(end 388.10184 -248.046748)
		(width 0.0889)
		(layer "In11.Cu")
		(net "M_L_CPU0_SA_CB<4>")
	)
	(arc
		(start 389.033512 -248.051574)
		(mid 388.850004 -248.097068)
		(end 388.667752 -248.046748)
		(width 0.0889)
		(layer "In11.Cu")
		(net "M_L_CPU0_SA_CB<4>")
	)
	(arc
		(start 393.084812 -247.970294)
		(mid 392.937881 -247.989705)
		(end 392.801094 -248.046748)
		(width 0.0889)
		(layer "In11.Cu")
		(net "M_L_CPU0_SA_CB<4>")
	)
	(segment
		(start 385.567936 -246.370094)
		(end 386.034788 -246.104156)
		(width 0.10668)
		(layer "F.Cu")
		(net "M_L_CPU0_SA_CB<3>")
	)
	(segment
		(start 441.09767 -236.850936)
		(end 437.472582 -236.850936)
		(width 0.14478)
		(layer "In11.Cu")
		(net "M_L_CPU0_SA_CB<3>")
	)
	(segment
		(start 408.036522 -242.488212)
		(end 407.831798 -242.488212)
		(width 0.14478)
		(layer "In11.Cu")
		(net "M_L_CPU0_SA_CB<3>")
	)
	(segment
		(start 395.535658 -245.937532)
		(end 394.288518 -245.937532)
		(width 0.0889)
		(layer "In11.Cu")
		(net "M_L_CPU0_SA_CB<3>")
	)
	(segment
		(start 433.181506 -236.850936)
		(end 429.790098 -236.850936)
		(width 0.14478)
		(layer "In11.Cu")
		(net "M_L_CPU0_SA_CB<3>")
	)
	(segment
		(start 391.502138 -245.773194)
		(end 391.48766 -245.781576)
		(width 0.0889)
		(layer "In11.Cu")
		(net "M_L_CPU0_SA_CB<3>")
	)
	(segment
		(start 396.03299 -245.4402)
		(end 395.535658 -245.937532)
		(width 0.0889)
		(layer "In11.Cu")
		(net "M_L_CPU0_SA_CB<3>")
	)
	(segment
		(start 418.232082 -236.86008)
		(end 414.763458 -236.86008)
		(width 0.14478)
		(layer "In11.Cu")
		(net "M_L_CPU0_SA_CB<3>")
	)
	(segment
		(start 409.40863 -241.519456)
		(end 409.40863 -241.72418)
		(width 0.14478)
		(layer "In11.Cu")
		(net "M_L_CPU0_SA_CB<3>")
	)
	(segment
		(start 409.40863 -241.72418)
		(end 409.22321 -241.9096)
		(width 0.14478)
		(layer "In11.Cu")
		(net "M_L_CPU0_SA_CB<3>")
	)
	(segment
		(start 441.947554 -237.70082)
		(end 441.09767 -236.850936)
		(width 0.14478)
		(layer "In11.Cu")
		(net "M_L_CPU0_SA_CB<3>")
	)
	(segment
		(start 394.208254 -245.857268)
		(end 393.084812 -245.857268)
		(width 0.0889)
		(layer "In11.Cu")
		(net "M_L_CPU0_SA_CB<3>")
	)
	(segment
		(start 407.848054 -243.284756)
		(end 407.662634 -243.470176)
		(width 0.14478)
		(layer "In11.Cu")
		(net "M_L_CPU0_SA_CB<3>")
	)
	(segment
		(start 437.472582 -236.850936)
		(end 436.622698 -237.70082)
		(width 0.14478)
		(layer "In11.Cu")
		(net "M_L_CPU0_SA_CB<3>")
	)
	(segment
		(start 409.597098 -240.927636)
		(end 409.392374 -240.927636)
		(width 0.14478)
		(layer "In11.Cu")
		(net "M_L_CPU0_SA_CB<3>")
	)
	(segment
		(start 413.913574 -237.709964)
		(end 413.422846 -237.709964)
		(width 0.14478)
		(layer "In11.Cu")
		(net "M_L_CPU0_SA_CB<3>")
	)
	(segment
		(start 408.81681 -241.707924)
		(end 408.612086 -241.707924)
		(width 0.14478)
		(layer "In11.Cu")
		(net "M_L_CPU0_SA_CB<3>")
	)
	(segment
		(start 406.085802 -244.234208)
		(end 406.085802 -244.438932)
		(width 0.14478)
		(layer "In11.Cu")
		(net "M_L_CPU0_SA_CB<3>")
	)
	(segment
		(start 406.882346 -244.250464)
		(end 406.677622 -244.250464)
		(width 0.14478)
		(layer "In11.Cu")
		(net "M_L_CPU0_SA_CB<3>")
	)
	(segment
		(start 407.831798 -242.488212)
		(end 407.646378 -242.673632)
		(width 0.14478)
		(layer "In11.Cu")
		(net "M_L_CPU0_SA_CB<3>")
	)
	(segment
		(start 406.085802 -244.438932)
		(end 406.287478 -244.640608)
		(width 0.14478)
		(layer "In11.Cu")
		(net "M_L_CPU0_SA_CB<3>")
	)
	(segment
		(start 444.786766 -236.850936)
		(end 443.936882 -237.70082)
		(width 0.14478)
		(layer "In11.Cu")
		(net "M_L_CPU0_SA_CB<3>")
	)
	(segment
		(start 408.612086 -241.707924)
		(end 408.426666 -241.893344)
		(width 0.14478)
		(layer "In11.Cu")
		(net "M_L_CPU0_SA_CB<3>")
	)
	(segment
		(start 409.392374 -240.927636)
		(end 409.206954 -241.113056)
		(width 0.14478)
		(layer "In11.Cu")
		(net "M_L_CPU0_SA_CB<3>")
	)
	(segment
		(start 407.067766 -243.86032)
		(end 407.067766 -244.065044)
		(width 0.14478)
		(layer "In11.Cu")
		(net "M_L_CPU0_SA_CB<3>")
	)
	(segment
		(start 408.426666 -242.098068)
		(end 408.628342 -242.299744)
		(width 0.14478)
		(layer "In11.Cu")
		(net "M_L_CPU0_SA_CB<3>")
	)
	(segment
		(start 450.088 -237.285022)
		(end 449.653914 -236.850936)
		(width 0.14478)
		(layer "In11.Cu")
		(net "M_L_CPU0_SA_CB<3>")
	)
	(segment
		(start 409.206954 -241.31778)
		(end 409.40863 -241.519456)
		(width 0.14478)
		(layer "In11.Cu")
		(net "M_L_CPU0_SA_CB<3>")
	)
	(segment
		(start 407.45791 -243.470176)
		(end 407.256234 -243.2685)
		(width 0.14478)
		(layer "In11.Cu")
		(net "M_L_CPU0_SA_CB<3>")
	)
	(segment
		(start 407.067766 -244.065044)
		(end 406.882346 -244.250464)
		(width 0.14478)
		(layer "In11.Cu")
		(net "M_L_CPU0_SA_CB<3>")
	)
	(segment
		(start 406.287478 -244.640608)
		(end 406.287478 -244.845332)
		(width 0.14478)
		(layer "In11.Cu")
		(net "M_L_CPU0_SA_CB<3>")
	)
	(segment
		(start 406.86609 -243.658644)
		(end 407.067766 -243.86032)
		(width 0.14478)
		(layer "In11.Cu")
		(net "M_L_CPU0_SA_CB<3>")
	)
	(segment
		(start 449.653914 -236.850936)
		(end 444.786766 -236.850936)
		(width 0.14478)
		(layer "In11.Cu")
		(net "M_L_CPU0_SA_CB<3>")
	)
	(segment
		(start 396.221458 -245.4402)
		(end 396.03299 -245.4402)
		(width 0.0889)
		(layer "In11.Cu")
		(net "M_L_CPU0_SA_CB<3>")
	)
	(segment
		(start 408.426666 -241.893344)
		(end 408.426666 -242.098068)
		(width 0.14478)
		(layer "In11.Cu")
		(net "M_L_CPU0_SA_CB<3>")
	)
	(segment
		(start 434.03139 -237.70082)
		(end 433.181506 -236.850936)
		(width 0.14478)
		(layer "In11.Cu")
		(net "M_L_CPU0_SA_CB<3>")
	)
	(segment
		(start 407.256234 -243.2685)
		(end 407.05151 -243.2685)
		(width 0.14478)
		(layer "In11.Cu")
		(net "M_L_CPU0_SA_CB<3>")
	)
	(segment
		(start 414.763458 -236.86008)
		(end 413.913574 -237.709964)
		(width 0.14478)
		(layer "In11.Cu")
		(net "M_L_CPU0_SA_CB<3>")
	)
	(segment
		(start 419.072568 -237.700566)
		(end 418.232082 -236.86008)
		(width 0.14478)
		(layer "In11.Cu")
		(net "M_L_CPU0_SA_CB<3>")
	)
	(segment
		(start 422.376346 -236.850682)
		(end 421.526462 -237.700566)
		(width 0.14478)
		(layer "In11.Cu")
		(net "M_L_CPU0_SA_CB<3>")
	)
	(segment
		(start 443.936882 -237.70082)
		(end 441.947554 -237.70082)
		(width 0.14478)
		(layer "In11.Cu")
		(net "M_L_CPU0_SA_CB<3>")
	)
	(segment
		(start 409.018486 -241.9096)
		(end 408.81681 -241.707924)
		(width 0.14478)
		(layer "In11.Cu")
		(net "M_L_CPU0_SA_CB<3>")
	)
	(segment
		(start 421.526462 -237.700566)
		(end 419.072568 -237.700566)
		(width 0.14478)
		(layer "In11.Cu")
		(net "M_L_CPU0_SA_CB<3>")
	)
	(segment
		(start 408.628342 -242.504468)
		(end 408.442922 -242.689888)
		(width 0.14478)
		(layer "In11.Cu")
		(net "M_L_CPU0_SA_CB<3>")
	)
	(segment
		(start 410.003498 -241.129312)
		(end 409.798774 -241.129312)
		(width 0.14478)
		(layer "In11.Cu")
		(net "M_L_CPU0_SA_CB<3>")
	)
	(segment
		(start 406.475946 -244.048788)
		(end 406.271222 -244.048788)
		(width 0.14478)
		(layer "In11.Cu")
		(net "M_L_CPU0_SA_CB<3>")
	)
	(segment
		(start 405.69261 -245.4402)
		(end 396.221458 -245.4402)
		(width 0.14478)
		(layer "In11.Cu")
		(net "M_L_CPU0_SA_CB<3>")
	)
	(segment
		(start 409.22321 -241.9096)
		(end 409.018486 -241.9096)
		(width 0.14478)
		(layer "In11.Cu")
		(net "M_L_CPU0_SA_CB<3>")
	)
	(segment
		(start 392.43 -245.781576)
		(end 392.406632 -245.795292)
		(width 0.0889)
		(layer "In11.Cu")
		(net "M_L_CPU0_SA_CB<3>")
	)
	(segment
		(start 385.903216 -245.755414)
		(end 385.880864 -245.838726)
		(width 0.0889)
		(layer "In11.Cu")
		(net "M_L_CPU0_SA_CB<3>")
	)
	(segment
		(start 408.628342 -242.299744)
		(end 408.628342 -242.504468)
		(width 0.14478)
		(layer "In11.Cu")
		(net "M_L_CPU0_SA_CB<3>")
	)
	(segment
		(start 392.80338 -245.78183)
		(end 392.783314 -245.7704)
		(width 0.0889)
		(layer "In11.Cu")
		(net "M_L_CPU0_SA_CB<3>")
	)
	(segment
		(start 406.287478 -244.845332)
		(end 405.69261 -245.4402)
		(width 0.14478)
		(layer "In11.Cu")
		(net "M_L_CPU0_SA_CB<3>")
	)
	(segment
		(start 406.677622 -244.250464)
		(end 406.475946 -244.048788)
		(width 0.14478)
		(layer "In11.Cu")
		(net "M_L_CPU0_SA_CB<3>")
	)
	(segment
		(start 394.288518 -245.937532)
		(end 394.208254 -245.857268)
		(width 0.0889)
		(layer "In11.Cu")
		(net "M_L_CPU0_SA_CB<3>")
	)
	(segment
		(start 409.206954 -241.113056)
		(end 409.206954 -241.31778)
		(width 0.14478)
		(layer "In11.Cu")
		(net "M_L_CPU0_SA_CB<3>")
	)
	(segment
		(start 413.422846 -237.709964)
		(end 410.003498 -241.129312)
		(width 0.14478)
		(layer "In11.Cu")
		(net "M_L_CPU0_SA_CB<3>")
	)
	(segment
		(start 429.790098 -236.850936)
		(end 428.940468 -237.700566)
		(width 0.14478)
		(layer "In11.Cu")
		(net "M_L_CPU0_SA_CB<3>")
	)
	(segment
		(start 385.880864 -245.838726)
		(end 386.034788 -246.104156)
		(width 0.0889)
		(layer "In11.Cu")
		(net "M_L_CPU0_SA_CB<3>")
	)
	(segment
		(start 426.503846 -237.700566)
		(end 425.653962 -236.850682)
		(width 0.14478)
		(layer "In11.Cu")
		(net "M_L_CPU0_SA_CB<3>")
	)
	(segment
		(start 407.646378 -242.878356)
		(end 407.848054 -243.080032)
		(width 0.14478)
		(layer "In11.Cu")
		(net "M_L_CPU0_SA_CB<3>")
	)
	(segment
		(start 428.940468 -237.700566)
		(end 426.503846 -237.700566)
		(width 0.14478)
		(layer "In11.Cu")
		(net "M_L_CPU0_SA_CB<3>")
	)
	(segment
		(start 408.238198 -242.689888)
		(end 408.036522 -242.488212)
		(width 0.14478)
		(layer "In11.Cu")
		(net "M_L_CPU0_SA_CB<3>")
	)
	(segment
		(start 389.041894 -245.781576)
		(end 389.033512 -245.77675)
		(width 0.0889)
		(layer "In11.Cu")
		(net "M_L_CPU0_SA_CB<3>")
	)
	(segment
		(start 389.616188 -245.77675)
		(end 389.607806 -245.781576)
		(width 0.0889)
		(layer "In11.Cu")
		(net "M_L_CPU0_SA_CB<3>")
	)
	(segment
		(start 406.86609 -243.45392)
		(end 406.86609 -243.658644)
		(width 0.14478)
		(layer "In11.Cu")
		(net "M_L_CPU0_SA_CB<3>")
	)
	(segment
		(start 408.442922 -242.689888)
		(end 408.238198 -242.689888)
		(width 0.14478)
		(layer "In11.Cu")
		(net "M_L_CPU0_SA_CB<3>")
	)
	(segment
		(start 388.10184 -245.781576)
		(end 388.093458 -245.77675)
		(width 0.0889)
		(layer "In11.Cu")
		(net "M_L_CPU0_SA_CB<3>")
	)
	(segment
		(start 407.848054 -243.080032)
		(end 407.848054 -243.284756)
		(width 0.14478)
		(layer "In11.Cu")
		(net "M_L_CPU0_SA_CB<3>")
	)
	(segment
		(start 409.798774 -241.129312)
		(end 409.597098 -240.927636)
		(width 0.14478)
		(layer "In11.Cu")
		(net "M_L_CPU0_SA_CB<3>")
	)
	(segment
		(start 436.622698 -237.70082)
		(end 434.03139 -237.70082)
		(width 0.14478)
		(layer "In11.Cu")
		(net "M_L_CPU0_SA_CB<3>")
	)
	(segment
		(start 407.05151 -243.2685)
		(end 406.86609 -243.45392)
		(width 0.14478)
		(layer "In11.Cu")
		(net "M_L_CPU0_SA_CB<3>")
	)
	(segment
		(start 425.653962 -236.850682)
		(end 422.376346 -236.850682)
		(width 0.14478)
		(layer "In11.Cu")
		(net "M_L_CPU0_SA_CB<3>")
	)
	(segment
		(start 407.662634 -243.470176)
		(end 407.45791 -243.470176)
		(width 0.14478)
		(layer "In11.Cu")
		(net "M_L_CPU0_SA_CB<3>")
	)
	(segment
		(start 407.646378 -242.673632)
		(end 407.646378 -242.878356)
		(width 0.14478)
		(layer "In11.Cu")
		(net "M_L_CPU0_SA_CB<3>")
	)
	(segment
		(start 406.271222 -244.048788)
		(end 406.085802 -244.234208)
		(width 0.14478)
		(layer "In11.Cu")
		(net "M_L_CPU0_SA_CB<3>")
	)
	(arc
		(start 392.406632 -245.795292)
		(mid 392.132978 -245.858235)
		(end 391.862818 -245.781576)
		(width 0.0889)
		(layer "In11.Cu")
		(net "M_L_CPU0_SA_CB<3>")
	)
	(arc
		(start 390.921748 -245.781576)
		(mid 390.734804 -245.731321)
		(end 390.54786 -245.781576)
		(width 0.0889)
		(layer "In11.Cu")
		(net "M_L_CPU0_SA_CB<3>")
	)
	(arc
		(start 392.783314 -245.7704)
		(mid 392.605236 -245.731416)
		(end 392.43 -245.781576)
		(width 0.0889)
		(layer "In11.Cu")
		(net "M_L_CPU0_SA_CB<3>")
	)
	(arc
		(start 388.093458 -245.77675)
		(mid 387.90995 -245.731256)
		(end 387.727698 -245.781576)
		(width 0.0889)
		(layer "In11.Cu")
		(net "M_L_CPU0_SA_CB<3>")
	)
	(arc
		(start 387.727698 -245.781576)
		(mid 387.444742 -245.857753)
		(end 387.161786 -245.781576)
		(width 0.0889)
		(layer "In11.Cu")
		(net "M_L_CPU0_SA_CB<3>")
	)
	(arc
		(start 386.221986 -245.781576)
		(mid 386.065548 -245.732605)
		(end 385.903216 -245.755414)
		(width 0.0889)
		(layer "In11.Cu")
		(net "M_L_CPU0_SA_CB<3>")
	)
	(arc
		(start 386.787898 -245.781576)
		(mid 386.504942 -245.857753)
		(end 386.221986 -245.781576)
		(width 0.0889)
		(layer "In11.Cu")
		(net "M_L_CPU0_SA_CB<3>")
	)
	(arc
		(start 391.48766 -245.781576)
		(mid 391.204704 -245.857753)
		(end 390.921748 -245.781576)
		(width 0.0889)
		(layer "In11.Cu")
		(net "M_L_CPU0_SA_CB<3>")
	)
	(arc
		(start 389.033512 -245.77675)
		(mid 388.850004 -245.731256)
		(end 388.667752 -245.781576)
		(width 0.0889)
		(layer "In11.Cu")
		(net "M_L_CPU0_SA_CB<3>")
	)
	(arc
		(start 393.084812 -245.857268)
		(mid 392.939121 -245.838095)
		(end 392.80338 -245.78183)
		(width 0.0889)
		(layer "In11.Cu")
		(net "M_L_CPU0_SA_CB<3>")
	)
	(arc
		(start 391.862818 -245.781576)
		(mid 391.683555 -245.730912)
		(end 391.502138 -245.773194)
		(width 0.0889)
		(layer "In11.Cu")
		(net "M_L_CPU0_SA_CB<3>")
	)
	(arc
		(start 388.667752 -245.781576)
		(mid 388.384796 -245.857753)
		(end 388.10184 -245.781576)
		(width 0.0889)
		(layer "In11.Cu")
		(net "M_L_CPU0_SA_CB<3>")
	)
	(arc
		(start 389.981948 -245.781576)
		(mid 389.799697 -245.731226)
		(end 389.616188 -245.77675)
		(width 0.0889)
		(layer "In11.Cu")
		(net "M_L_CPU0_SA_CB<3>")
	)
	(arc
		(start 390.54786 -245.781576)
		(mid 390.264904 -245.857753)
		(end 389.981948 -245.781576)
		(width 0.0889)
		(layer "In11.Cu")
		(net "M_L_CPU0_SA_CB<3>")
	)
	(arc
		(start 389.607806 -245.781576)
		(mid 389.32485 -245.857753)
		(end 389.041894 -245.781576)
		(width 0.0889)
		(layer "In11.Cu")
		(net "M_L_CPU0_SA_CB<3>")
	)
	(arc
		(start 387.161786 -245.781576)
		(mid 386.974842 -245.731321)
		(end 386.787898 -245.781576)
		(width 0.0889)
		(layer "In11.Cu")
		(net "M_L_CPU0_SA_CB<3>")
	)
	(segment
		(start 386.97789 -245.560088)
		(end 387.444742 -245.29415)
		(width 0.10668)
		(layer "F.Cu")
		(net "M_L_CPU0_SA_CB<2>")
	)
	(segment
		(start 391.957052 -244.971824)
		(end 391.945114 -244.978682)
		(width 0.0889)
		(layer "In11.Cu")
		(net "M_L_CPU0_SA_CB<2>")
	)
	(segment
		(start 448.468496 -234.769152)
		(end 448.323716 -234.913932)
		(width 0.14478)
		(layer "In11.Cu")
		(net "M_L_CPU0_SA_CB<2>")
	)
	(segment
		(start 410.585412 -238.340138)
		(end 410.585412 -238.544862)
		(width 0.14478)
		(layer "In11.Cu")
		(net "M_L_CPU0_SA_CB<2>")
	)
	(segment
		(start 387.31317 -244.945408)
		(end 387.290818 -245.02872)
		(width 0.0889)
		(layer "In11.Cu")
		(net "M_L_CPU0_SA_CB<2>")
	)
	(segment
		(start 396.447518 -244.53088)
		(end 395.91869 -244.53088)
		(width 0.0889)
		(layer "In11.Cu")
		(net "M_L_CPU0_SA_CB<2>")
	)
	(segment
		(start 412.216346 -237.630208)
		(end 412.011622 -237.630208)
		(width 0.14478)
		(layer "In11.Cu")
		(net "M_L_CPU0_SA_CB<2>")
	)
	(segment
		(start 410.060902 -239.785652)
		(end 409.854908 -239.991646)
		(width 0.14478)
		(layer "In11.Cu")
		(net "M_L_CPU0_SA_CB<2>")
	)
	(segment
		(start 425.912534 -235.160312)
		(end 422.40962 -235.160312)
		(width 0.14478)
		(layer "In11.Cu")
		(net "M_L_CPU0_SA_CB<2>")
	)
	(segment
		(start 394.324078 -245.305072)
		(end 393.939776 -244.92077)
		(width 0.0889)
		(layer "In11.Cu")
		(net "M_L_CPU0_SA_CB<2>")
	)
	(segment
		(start 447.076068 -235.160312)
		(end 444.750952 -235.160312)
		(width 0.14478)
		(layer "In11.Cu")
		(net "M_L_CPU0_SA_CB<2>")
	)
	(segment
		(start 448.73037 -234.769152)
		(end 448.468496 -234.769152)
		(width 0.14478)
		(layer "In11.Cu")
		(net "M_L_CPU0_SA_CB<2>")
	)
	(segment
		(start 447.627502 -234.769152)
		(end 447.365628 -234.769152)
		(width 0.14478)
		(layer "In11.Cu")
		(net "M_L_CPU0_SA_CB<2>")
	)
	(segment
		(start 411.436058 -238.410496)
		(end 411.231334 -238.410496)
		(width 0.14478)
		(layer "In11.Cu")
		(net "M_L_CPU0_SA_CB<2>")
	)
	(segment
		(start 447.365628 -234.769152)
		(end 447.220848 -234.913932)
		(width 0.14478)
		(layer "In11.Cu")
		(net "M_L_CPU0_SA_CB<2>")
	)
	(segment
		(start 395.91869 -244.53088)
		(end 395.144498 -245.305072)
		(width 0.0889)
		(layer "In11.Cu")
		(net "M_L_CPU0_SA_CB<2>")
	)
	(segment
		(start 411.3657 -237.764574)
		(end 411.621478 -238.020352)
		(width 0.14478)
		(layer "In11.Cu")
		(net "M_L_CPU0_SA_CB<2>")
	)
	(segment
		(start 409.805124 -239.120426)
		(end 409.805124 -239.32515)
		(width 0.14478)
		(layer "In11.Cu")
		(net "M_L_CPU0_SA_CB<2>")
	)
	(segment
		(start 404.414482 -244.53088)
		(end 396.447518 -244.53088)
		(width 0.14478)
		(layer "In11.Cu")
		(net "M_L_CPU0_SA_CB<2>")
	)
	(segment
		(start 409.854908 -239.991646)
		(end 408.953716 -239.991646)
		(width 0.14478)
		(layer "In11.Cu")
		(net "M_L_CPU0_SA_CB<2>")
	)
	(segment
		(start 409.990544 -238.935006)
		(end 409.805124 -239.120426)
		(width 0.14478)
		(layer "In11.Cu")
		(net "M_L_CPU0_SA_CB<2>")
	)
	(segment
		(start 411.55112 -237.37443)
		(end 411.3657 -237.55985)
		(width 0.14478)
		(layer "In11.Cu")
		(net "M_L_CPU0_SA_CB<2>")
	)
	(segment
		(start 393.939776 -244.92077)
		(end 393.084812 -244.92077)
		(width 0.0889)
		(layer "In11.Cu")
		(net "M_L_CPU0_SA_CB<2>")
	)
	(segment
		(start 391.026142 -244.966744)
		(end 391.01776 -244.97157)
		(width 0.0889)
		(layer "In11.Cu")
		(net "M_L_CPU0_SA_CB<2>")
	)
	(segment
		(start 418.231828 -235.160058)
		(end 414.686496 -235.160058)
		(width 0.14478)
		(layer "In11.Cu")
		(net "M_L_CPU0_SA_CB<2>")
	)
	(segment
		(start 448.323716 -234.913932)
		(end 448.323716 -235.406692)
		(width 0.14478)
		(layer "In11.Cu")
		(net "M_L_CPU0_SA_CB<2>")
	)
	(segment
		(start 390.451848 -244.97157)
		(end 390.443466 -244.966744)
		(width 0.0889)
		(layer "In11.Cu")
		(net "M_L_CPU0_SA_CB<2>")
	)
	(segment
		(start 448.323716 -235.406692)
		(end 448.178936 -235.551472)
		(width 0.14478)
		(layer "In11.Cu")
		(net "M_L_CPU0_SA_CB<2>")
	)
	(segment
		(start 410.451046 -239.190784)
		(end 410.195268 -238.935006)
		(width 0.14478)
		(layer "In11.Cu")
		(net "M_L_CPU0_SA_CB<2>")
	)
	(segment
		(start 391.970768 -244.96395)
		(end 391.957052 -244.971824)
		(width 0.0889)
		(layer "In11.Cu")
		(net "M_L_CPU0_SA_CB<2>")
	)
	(segment
		(start 409.805124 -239.32515)
		(end 410.060902 -239.580928)
		(width 0.14478)
		(layer "In11.Cu")
		(net "M_L_CPU0_SA_CB<2>")
	)
	(segment
		(start 433.190904 -235.160312)
		(end 429.777144 -235.160312)
		(width 0.14478)
		(layer "In11.Cu")
		(net "M_L_CPU0_SA_CB<2>")
	)
	(segment
		(start 421.559736 -236.010196)
		(end 419.081966 -236.010196)
		(width 0.14478)
		(layer "In11.Cu")
		(net "M_L_CPU0_SA_CB<2>")
	)
	(segment
		(start 408.953716 -239.991646)
		(end 404.414482 -244.53088)
		(width 0.14478)
		(layer "In11.Cu")
		(net "M_L_CPU0_SA_CB<2>")
	)
	(segment
		(start 449.01993 -235.160312)
		(end 448.87515 -235.015532)
		(width 0.14478)
		(layer "In11.Cu")
		(net "M_L_CPU0_SA_CB<2>")
	)
	(segment
		(start 411.231334 -238.410496)
		(end 410.975556 -238.154718)
		(width 0.14478)
		(layer "In11.Cu")
		(net "M_L_CPU0_SA_CB<2>")
	)
	(segment
		(start 410.975556 -238.154718)
		(end 410.770832 -238.154718)
		(width 0.14478)
		(layer "In11.Cu")
		(net "M_L_CPU0_SA_CB<2>")
	)
	(segment
		(start 410.770832 -238.154718)
		(end 410.585412 -238.340138)
		(width 0.14478)
		(layer "In11.Cu")
		(net "M_L_CPU0_SA_CB<2>")
	)
	(segment
		(start 448.87515 -234.913932)
		(end 448.73037 -234.769152)
		(width 0.14478)
		(layer "In11.Cu")
		(net "M_L_CPU0_SA_CB<2>")
	)
	(segment
		(start 422.40962 -235.160312)
		(end 421.559736 -236.010196)
		(width 0.14478)
		(layer "In11.Cu")
		(net "M_L_CPU0_SA_CB<2>")
	)
	(segment
		(start 428.92726 -236.010196)
		(end 426.762418 -236.010196)
		(width 0.14478)
		(layer "In11.Cu")
		(net "M_L_CPU0_SA_CB<2>")
	)
	(segment
		(start 441.636404 -236.010196)
		(end 440.78652 -235.160312)
		(width 0.14478)
		(layer "In11.Cu")
		(net "M_L_CPU0_SA_CB<2>")
	)
	(segment
		(start 437.463184 -235.160312)
		(end 436.6133 -236.010196)
		(width 0.14478)
		(layer "In11.Cu")
		(net "M_L_CPU0_SA_CB<2>")
	)
	(segment
		(start 388.206234 -244.966744)
		(end 388.197852 -244.97157)
		(width 0.0889)
		(layer "In11.Cu")
		(net "M_L_CPU0_SA_CB<2>")
	)
	(segment
		(start 387.290818 -245.02872)
		(end 387.444742 -245.29415)
		(width 0.0889)
		(layer "In11.Cu")
		(net "M_L_CPU0_SA_CB<2>")
	)
	(segment
		(start 414.686496 -235.160058)
		(end 412.216346 -237.630208)
		(width 0.14478)
		(layer "In11.Cu")
		(net "M_L_CPU0_SA_CB<2>")
	)
	(segment
		(start 447.220848 -234.913932)
		(end 447.220848 -235.015532)
		(width 0.14478)
		(layer "In11.Cu")
		(net "M_L_CPU0_SA_CB<2>")
	)
	(segment
		(start 411.621478 -238.225076)
		(end 411.436058 -238.410496)
		(width 0.14478)
		(layer "In11.Cu")
		(net "M_L_CPU0_SA_CB<2>")
	)
	(segment
		(start 450.088 -235.585)
		(end 449.663312 -235.160312)
		(width 0.14478)
		(layer "In11.Cu")
		(net "M_L_CPU0_SA_CB<2>")
	)
	(segment
		(start 410.585412 -238.544862)
		(end 410.84119 -238.80064)
		(width 0.14478)
		(layer "In11.Cu")
		(net "M_L_CPU0_SA_CB<2>")
	)
	(segment
		(start 410.195268 -238.935006)
		(end 409.990544 -238.935006)
		(width 0.14478)
		(layer "In11.Cu")
		(net "M_L_CPU0_SA_CB<2>")
	)
	(segment
		(start 440.78652 -235.160312)
		(end 437.463184 -235.160312)
		(width 0.14478)
		(layer "In11.Cu")
		(net "M_L_CPU0_SA_CB<2>")
	)
	(segment
		(start 419.081966 -236.010196)
		(end 418.231828 -235.160058)
		(width 0.14478)
		(layer "In11.Cu")
		(net "M_L_CPU0_SA_CB<2>")
	)
	(segment
		(start 449.663312 -235.160312)
		(end 449.01993 -235.160312)
		(width 0.14478)
		(layer "In11.Cu")
		(net "M_L_CPU0_SA_CB<2>")
	)
	(segment
		(start 426.762418 -236.010196)
		(end 425.912534 -235.160312)
		(width 0.14478)
		(layer "In11.Cu")
		(net "M_L_CPU0_SA_CB<2>")
	)
	(segment
		(start 410.84119 -238.80064)
		(end 410.84119 -239.005364)
		(width 0.14478)
		(layer "In11.Cu")
		(net "M_L_CPU0_SA_CB<2>")
	)
	(segment
		(start 443.901068 -236.010196)
		(end 441.636404 -236.010196)
		(width 0.14478)
		(layer "In11.Cu")
		(net "M_L_CPU0_SA_CB<2>")
	)
	(segment
		(start 410.060902 -239.580928)
		(end 410.060902 -239.785652)
		(width 0.14478)
		(layer "In11.Cu")
		(net "M_L_CPU0_SA_CB<2>")
	)
	(segment
		(start 411.621478 -238.020352)
		(end 411.621478 -238.225076)
		(width 0.14478)
		(layer "In11.Cu")
		(net "M_L_CPU0_SA_CB<2>")
	)
	(segment
		(start 392.34872 -244.982238)
		(end 392.330686 -244.97157)
		(width 0.0889)
		(layer "In11.Cu")
		(net "M_L_CPU0_SA_CB<2>")
	)
	(segment
		(start 448.178936 -235.551472)
		(end 447.917062 -235.551472)
		(width 0.14478)
		(layer "In11.Cu")
		(net "M_L_CPU0_SA_CB<2>")
	)
	(segment
		(start 447.220848 -235.015532)
		(end 447.076068 -235.160312)
		(width 0.14478)
		(layer "In11.Cu")
		(net "M_L_CPU0_SA_CB<2>")
	)
	(segment
		(start 447.772282 -234.913932)
		(end 447.627502 -234.769152)
		(width 0.14478)
		(layer "In11.Cu")
		(net "M_L_CPU0_SA_CB<2>")
	)
	(segment
		(start 410.84119 -239.005364)
		(end 410.65577 -239.190784)
		(width 0.14478)
		(layer "In11.Cu")
		(net "M_L_CPU0_SA_CB<2>")
	)
	(segment
		(start 395.144498 -245.305072)
		(end 394.324078 -245.305072)
		(width 0.0889)
		(layer "In11.Cu")
		(net "M_L_CPU0_SA_CB<2>")
	)
	(segment
		(start 444.750952 -235.160312)
		(end 443.901068 -236.010196)
		(width 0.14478)
		(layer "In11.Cu")
		(net "M_L_CPU0_SA_CB<2>")
	)
	(segment
		(start 447.917062 -235.551472)
		(end 447.772282 -235.406692)
		(width 0.14478)
		(layer "In11.Cu")
		(net "M_L_CPU0_SA_CB<2>")
	)
	(segment
		(start 410.65577 -239.190784)
		(end 410.451046 -239.190784)
		(width 0.14478)
		(layer "In11.Cu")
		(net "M_L_CPU0_SA_CB<2>")
	)
	(segment
		(start 412.011622 -237.630208)
		(end 411.755844 -237.37443)
		(width 0.14478)
		(layer "In11.Cu")
		(net "M_L_CPU0_SA_CB<2>")
	)
	(segment
		(start 411.755844 -237.37443)
		(end 411.55112 -237.37443)
		(width 0.14478)
		(layer "In11.Cu")
		(net "M_L_CPU0_SA_CB<2>")
	)
	(segment
		(start 447.772282 -235.406692)
		(end 447.772282 -234.913932)
		(width 0.14478)
		(layer "In11.Cu")
		(net "M_L_CPU0_SA_CB<2>")
	)
	(segment
		(start 448.87515 -235.015532)
		(end 448.87515 -234.913932)
		(width 0.14478)
		(layer "In11.Cu")
		(net "M_L_CPU0_SA_CB<2>")
	)
	(segment
		(start 436.6133 -236.010196)
		(end 434.040788 -236.010196)
		(width 0.14478)
		(layer "In11.Cu")
		(net "M_L_CPU0_SA_CB<2>")
	)
	(segment
		(start 429.777144 -235.160312)
		(end 428.92726 -236.010196)
		(width 0.14478)
		(layer "In11.Cu")
		(net "M_L_CPU0_SA_CB<2>")
	)
	(segment
		(start 434.040788 -236.010196)
		(end 433.190904 -235.160312)
		(width 0.14478)
		(layer "In11.Cu")
		(net "M_L_CPU0_SA_CB<2>")
	)
	(segment
		(start 411.3657 -237.55985)
		(end 411.3657 -237.764574)
		(width 0.14478)
		(layer "In11.Cu")
		(net "M_L_CPU0_SA_CB<2>")
	)
	(arc
		(start 390.443466 -244.966744)
		(mid 390.259958 -244.92125)
		(end 390.077706 -244.97157)
		(width 0.0889)
		(layer "In11.Cu")
		(net "M_L_CPU0_SA_CB<2>")
	)
	(arc
		(start 391.01776 -244.97157)
		(mid 390.734804 -245.047747)
		(end 390.451848 -244.97157)
		(width 0.0889)
		(layer "In11.Cu")
		(net "M_L_CPU0_SA_CB<2>")
	)
	(arc
		(start 388.571994 -244.97157)
		(mid 388.389743 -244.92122)
		(end 388.206234 -244.966744)
		(width 0.0889)
		(layer "In11.Cu")
		(net "M_L_CPU0_SA_CB<2>")
	)
	(arc
		(start 390.077706 -244.97157)
		(mid 389.79475 -245.047747)
		(end 389.511794 -244.97157)
		(width 0.0889)
		(layer "In11.Cu")
		(net "M_L_CPU0_SA_CB<2>")
	)
	(arc
		(start 391.945114 -244.978682)
		(mid 391.66758 -245.047663)
		(end 391.391902 -244.97157)
		(width 0.0889)
		(layer "In11.Cu")
		(net "M_L_CPU0_SA_CB<2>")
	)
	(arc
		(start 389.137906 -244.97157)
		(mid 388.85495 -245.047747)
		(end 388.571994 -244.97157)
		(width 0.0889)
		(layer "In11.Cu")
		(net "M_L_CPU0_SA_CB<2>")
	)
	(arc
		(start 392.89736 -244.97157)
		(mid 392.624416 -245.04815)
		(end 392.34872 -244.982238)
		(width 0.0889)
		(layer "In11.Cu")
		(net "M_L_CPU0_SA_CB<2>")
	)
	(arc
		(start 391.391902 -244.97157)
		(mid 391.209651 -244.92122)
		(end 391.026142 -244.966744)
		(width 0.0889)
		(layer "In11.Cu")
		(net "M_L_CPU0_SA_CB<2>")
	)
	(arc
		(start 389.511794 -244.97157)
		(mid 389.32485 -244.921315)
		(end 389.137906 -244.97157)
		(width 0.0889)
		(layer "In11.Cu")
		(net "M_L_CPU0_SA_CB<2>")
	)
	(arc
		(start 387.63194 -244.97157)
		(mid 387.475502 -244.922599)
		(end 387.31317 -244.945408)
		(width 0.0889)
		(layer "In11.Cu")
		(net "M_L_CPU0_SA_CB<2>")
	)
	(arc
		(start 388.197852 -244.97157)
		(mid 387.914896 -245.047747)
		(end 387.63194 -244.97157)
		(width 0.0889)
		(layer "In11.Cu")
		(net "M_L_CPU0_SA_CB<2>")
	)
	(arc
		(start 392.330686 -244.97157)
		(mid 392.151699 -244.9214)
		(end 391.970768 -244.96395)
		(width 0.0889)
		(layer "In11.Cu")
		(net "M_L_CPU0_SA_CB<2>")
	)
	(arc
		(start 393.084812 -244.92077)
		(mid 392.987723 -244.93376)
		(end 392.89736 -244.97157)
		(width 0.0889)
		(layer "In11.Cu")
		(net "M_L_CPU0_SA_CB<2>")
	)
	(segment
		(start 385.098036 -245.560088)
		(end 385.564888 -245.29415)
		(width 0.10668)
		(layer "F.Cu")
		(net "M_L_CPU0_SA_CB<1>")
	)
	(segment
		(start 390.451848 -245.61673)
		(end 390.443466 -245.621556)
		(width 0.0889)
		(layer "In11.Cu")
		(net "M_L_CPU0_SA_CB<1>")
	)
	(segment
		(start 454.188068 -236.435138)
		(end 452.051674 -236.010196)
		(width 0.14478)
		(layer "In11.Cu")
		(net "M_L_CPU0_SA_CB<1>")
	)
	(segment
		(start 434.815488 -236.86008)
		(end 432.763676 -236.010196)
		(width 0.14478)
		(layer "In11.Cu")
		(net "M_L_CPU0_SA_CB<1>")
	)
	(segment
		(start 415.546794 -236.010196)
		(end 413.724852 -236.76483)
		(width 0.14478)
		(layer "In11.Cu")
		(net "M_L_CPU0_SA_CB<1>")
	)
	(segment
		(start 413.724852 -236.76483)
		(end 410.043376 -240.446306)
		(width 0.14478)
		(layer "In11.Cu")
		(net "M_L_CPU0_SA_CB<1>")
	)
	(segment
		(start 438.031636 -236.010196)
		(end 435.979824 -236.86008)
		(width 0.14478)
		(layer "In11.Cu")
		(net "M_L_CPU0_SA_CB<1>")
	)
	(segment
		(start 442.395356 -236.86008)
		(end 440.343544 -236.010196)
		(width 0.14478)
		(layer "In11.Cu")
		(net "M_L_CPU0_SA_CB<1>")
	)
	(segment
		(start 410.043376 -240.446306)
		(end 409.142184 -240.446306)
		(width 0.14478)
		(layer "In11.Cu")
		(net "M_L_CPU0_SA_CB<1>")
	)
	(segment
		(start 432.763676 -236.010196)
		(end 430.360836 -236.010196)
		(width 0.14478)
		(layer "In11.Cu")
		(net "M_L_CPU0_SA_CB<1>")
	)
	(segment
		(start 427.301406 -236.86008)
		(end 425.249594 -236.010196)
		(width 0.14478)
		(layer "In11.Cu")
		(net "M_L_CPU0_SA_CB<1>")
	)
	(segment
		(start 450.8627 -236.154976)
		(end 450.71792 -236.010196)
		(width 0.14478)
		(layer "In11.Cu")
		(net "M_L_CPU0_SA_CB<1>")
	)
	(segment
		(start 386.691886 -245.61673)
		(end 386.683504 -245.621556)
		(width 0.0889)
		(layer "In11.Cu")
		(net "M_L_CPU0_SA_CB<1>")
	)
	(segment
		(start 391.41527 -245.603014)
		(end 391.391902 -245.61673)
		(width 0.0889)
		(layer "In11.Cu")
		(net "M_L_CPU0_SA_CB<1>")
	)
	(segment
		(start 404.60295 -244.98554)
		(end 396.190978 -244.98554)
		(width 0.14478)
		(layer "In11.Cu")
		(net "M_L_CPU0_SA_CB<1>")
	)
	(segment
		(start 451.269354 -236.564932)
		(end 451.00748 -236.564932)
		(width 0.14478)
		(layer "In11.Cu")
		(net "M_L_CPU0_SA_CB<1>")
	)
	(segment
		(start 391.026142 -245.621556)
		(end 391.01776 -245.61673)
		(width 0.0889)
		(layer "In11.Cu")
		(net "M_L_CPU0_SA_CB<1>")
	)
	(segment
		(start 385.718812 -245.55958)
		(end 385.564888 -245.29415)
		(width 0.0889)
		(layer "In11.Cu")
		(net "M_L_CPU0_SA_CB<1>")
	)
	(segment
		(start 451.414134 -236.420152)
		(end 451.269354 -236.564932)
		(width 0.14478)
		(layer "In11.Cu")
		(net "M_L_CPU0_SA_CB<1>")
	)
	(segment
		(start 392.89863 -245.616476)
		(end 392.87704 -245.60403)
		(width 0.0889)
		(layer "In11.Cu")
		(net "M_L_CPU0_SA_CB<1>")
	)
	(segment
		(start 451.414134 -236.154976)
		(end 451.414134 -236.420152)
		(width 0.14478)
		(layer "In11.Cu")
		(net "M_L_CPU0_SA_CB<1>")
	)
	(segment
		(start 440.343544 -236.010196)
		(end 438.031636 -236.010196)
		(width 0.14478)
		(layer "In11.Cu")
		(net "M_L_CPU0_SA_CB<1>")
	)
	(segment
		(start 396.190978 -244.98554)
		(end 395.94917 -244.98554)
		(width 0.0889)
		(layer "In11.Cu")
		(net "M_L_CPU0_SA_CB<1>")
	)
	(segment
		(start 425.249594 -236.010196)
		(end 422.999154 -236.010196)
		(width 0.14478)
		(layer "In11.Cu")
		(net "M_L_CPU0_SA_CB<1>")
	)
	(segment
		(start 420.947342 -236.86008)
		(end 419.716966 -236.86008)
		(width 0.14478)
		(layer "In11.Cu")
		(net "M_L_CPU0_SA_CB<1>")
	)
	(segment
		(start 450.8627 -236.420152)
		(end 450.8627 -236.154976)
		(width 0.14478)
		(layer "In11.Cu")
		(net "M_L_CPU0_SA_CB<1>")
	)
	(segment
		(start 419.716966 -236.86008)
		(end 417.665154 -236.010196)
		(width 0.14478)
		(layer "In11.Cu")
		(net "M_L_CPU0_SA_CB<1>")
	)
	(segment
		(start 452.051674 -236.010196)
		(end 451.558914 -236.010196)
		(width 0.14478)
		(layer "In11.Cu")
		(net "M_L_CPU0_SA_CB<1>")
	)
	(segment
		(start 388.206234 -245.621556)
		(end 388.197852 -245.61673)
		(width 0.0889)
		(layer "In11.Cu")
		(net "M_L_CPU0_SA_CB<1>")
	)
	(segment
		(start 443.349888 -236.86008)
		(end 442.395356 -236.86008)
		(width 0.14478)
		(layer "In11.Cu")
		(net "M_L_CPU0_SA_CB<1>")
	)
	(segment
		(start 450.71792 -236.010196)
		(end 445.4017 -236.010196)
		(width 0.14478)
		(layer "In11.Cu")
		(net "M_L_CPU0_SA_CB<1>")
	)
	(segment
		(start 430.360836 -236.010196)
		(end 428.309024 -236.86008)
		(width 0.14478)
		(layer "In11.Cu")
		(net "M_L_CPU0_SA_CB<1>")
	)
	(segment
		(start 417.665154 -236.010196)
		(end 415.546794 -236.010196)
		(width 0.14478)
		(layer "In11.Cu")
		(net "M_L_CPU0_SA_CB<1>")
	)
	(segment
		(start 392.334242 -245.61673)
		(end 392.319764 -245.625112)
		(width 0.0889)
		(layer "In11.Cu")
		(net "M_L_CPU0_SA_CB<1>")
	)
	(segment
		(start 422.999154 -236.010196)
		(end 420.947342 -236.86008)
		(width 0.14478)
		(layer "In11.Cu")
		(net "M_L_CPU0_SA_CB<1>")
	)
	(segment
		(start 428.309024 -236.86008)
		(end 427.301406 -236.86008)
		(width 0.14478)
		(layer "In11.Cu")
		(net "M_L_CPU0_SA_CB<1>")
	)
	(segment
		(start 395.267942 -245.666768)
		(end 393.085066 -245.666768)
		(width 0.0889)
		(layer "In11.Cu")
		(net "M_L_CPU0_SA_CB<1>")
	)
	(segment
		(start 385.814824 -245.58498)
		(end 385.718812 -245.55958)
		(width 0.0889)
		(layer "In11.Cu")
		(net "M_L_CPU0_SA_CB<1>")
	)
	(segment
		(start 395.94917 -244.98554)
		(end 395.267942 -245.666768)
		(width 0.0889)
		(layer "In11.Cu")
		(net "M_L_CPU0_SA_CB<1>")
	)
	(segment
		(start 435.979824 -236.86008)
		(end 434.815488 -236.86008)
		(width 0.14478)
		(layer "In11.Cu")
		(net "M_L_CPU0_SA_CB<1>")
	)
	(segment
		(start 409.142184 -240.446306)
		(end 404.60295 -244.98554)
		(width 0.14478)
		(layer "In11.Cu")
		(net "M_L_CPU0_SA_CB<1>")
	)
	(segment
		(start 445.4017 -236.010196)
		(end 443.349888 -236.86008)
		(width 0.14478)
		(layer "In11.Cu")
		(net "M_L_CPU0_SA_CB<1>")
	)
	(segment
		(start 451.00748 -236.564932)
		(end 450.8627 -236.420152)
		(width 0.14478)
		(layer "In11.Cu")
		(net "M_L_CPU0_SA_CB<1>")
	)
	(segment
		(start 451.558914 -236.010196)
		(end 451.414134 -236.154976)
		(width 0.14478)
		(layer "In11.Cu")
		(net "M_L_CPU0_SA_CB<1>")
	)
	(segment
		(start 387.26618 -245.621556)
		(end 387.257798 -245.61673)
		(width 0.0889)
		(layer "In11.Cu")
		(net "M_L_CPU0_SA_CB<1>")
	)
	(arc
		(start 389.511794 -245.61673)
		(mid 389.32485 -245.666985)
		(end 389.137906 -245.61673)
		(width 0.0889)
		(layer "In11.Cu")
		(net "M_L_CPU0_SA_CB<1>")
	)
	(arc
		(start 389.137906 -245.61673)
		(mid 388.85495 -245.540553)
		(end 388.571994 -245.61673)
		(width 0.0889)
		(layer "In11.Cu")
		(net "M_L_CPU0_SA_CB<1>")
	)
	(arc
		(start 388.571994 -245.61673)
		(mid 388.389743 -245.66708)
		(end 388.206234 -245.621556)
		(width 0.0889)
		(layer "In11.Cu")
		(net "M_L_CPU0_SA_CB<1>")
	)
	(arc
		(start 386.317744 -245.61673)
		(mid 386.070031 -245.54151)
		(end 385.814824 -245.58498)
		(width 0.0889)
		(layer "In11.Cu")
		(net "M_L_CPU0_SA_CB<1>")
	)
	(arc
		(start 391.391902 -245.61673)
		(mid 391.209651 -245.66708)
		(end 391.026142 -245.621556)
		(width 0.0889)
		(layer "In11.Cu")
		(net "M_L_CPU0_SA_CB<1>")
	)
	(arc
		(start 387.63194 -245.61673)
		(mid 387.449689 -245.66708)
		(end 387.26618 -245.621556)
		(width 0.0889)
		(layer "In11.Cu")
		(net "M_L_CPU0_SA_CB<1>")
	)
	(arc
		(start 388.197852 -245.61673)
		(mid 387.914896 -245.540553)
		(end 387.63194 -245.61673)
		(width 0.0889)
		(layer "In11.Cu")
		(net "M_L_CPU0_SA_CB<1>")
	)
	(arc
		(start 392.87704 -245.60403)
		(mid 392.604011 -245.540711)
		(end 392.334242 -245.61673)
		(width 0.0889)
		(layer "In11.Cu")
		(net "M_L_CPU0_SA_CB<1>")
	)
	(arc
		(start 392.319764 -245.625112)
		(mid 392.138348 -245.667369)
		(end 391.959084 -245.61673)
		(width 0.0889)
		(layer "In11.Cu")
		(net "M_L_CPU0_SA_CB<1>")
	)
	(arc
		(start 391.01776 -245.61673)
		(mid 390.734804 -245.540553)
		(end 390.451848 -245.61673)
		(width 0.0889)
		(layer "In11.Cu")
		(net "M_L_CPU0_SA_CB<1>")
	)
	(arc
		(start 386.683504 -245.621556)
		(mid 386.499996 -245.66705)
		(end 386.317744 -245.61673)
		(width 0.0889)
		(layer "In11.Cu")
		(net "M_L_CPU0_SA_CB<1>")
	)
	(arc
		(start 387.257798 -245.61673)
		(mid 386.974842 -245.540553)
		(end 386.691886 -245.61673)
		(width 0.0889)
		(layer "In11.Cu")
		(net "M_L_CPU0_SA_CB<1>")
	)
	(arc
		(start 390.443466 -245.621556)
		(mid 390.259958 -245.66705)
		(end 390.077706 -245.61673)
		(width 0.0889)
		(layer "In11.Cu")
		(net "M_L_CPU0_SA_CB<1>")
	)
	(arc
		(start 390.077706 -245.61673)
		(mid 389.79475 -245.540553)
		(end 389.511794 -245.61673)
		(width 0.0889)
		(layer "In11.Cu")
		(net "M_L_CPU0_SA_CB<1>")
	)
	(arc
		(start 391.959084 -245.61673)
		(mid 391.688927 -245.539968)
		(end 391.41527 -245.603014)
		(width 0.0889)
		(layer "In11.Cu")
		(net "M_L_CPU0_SA_CB<1>")
	)
	(arc
		(start 393.085066 -245.666768)
		(mid 392.988537 -245.653902)
		(end 392.89863 -245.616476)
		(width 0.0889)
		(layer "In11.Cu")
		(net "M_L_CPU0_SA_CB<1>")
	)
	(segment
		(start 386.50799 -244.750082)
		(end 386.974842 -244.484144)
		(width 0.10668)
		(layer "F.Cu")
		(net "M_L_CPU0_SA_CB<0>")
	)
	(segment
		(start 388.10184 -244.806724)
		(end 388.093458 -244.81155)
		(width 0.0889)
		(layer "In11.Cu")
		(net "M_L_CPU0_SA_CB<0>")
	)
	(segment
		(start 451.525894 -234.454954)
		(end 451.525894 -234.865672)
		(width 0.14478)
		(layer "In11.Cu")
		(net "M_L_CPU0_SA_CB<0>")
	)
	(segment
		(start 394.01877 -244.73027)
		(end 393.084812 -244.73027)
		(width 0.0889)
		(layer "In11.Cu")
		(net "M_L_CPU0_SA_CB<0>")
	)
	(segment
		(start 428.349156 -235.160058)
		(end 427.309026 -235.160058)
		(width 0.14478)
		(layer "In11.Cu")
		(net "M_L_CPU0_SA_CB<0>")
	)
	(segment
		(start 421.089328 -235.160058)
		(end 419.42893 -235.160058)
		(width 0.14478)
		(layer "In11.Cu")
		(net "M_L_CPU0_SA_CB<0>")
	)
	(segment
		(start 443.919864 -235.160058)
		(end 441.518548 -235.160058)
		(width 0.14478)
		(layer "In11.Cu")
		(net "M_L_CPU0_SA_CB<0>")
	)
	(segment
		(start 389.616188 -244.81155)
		(end 389.607806 -244.806724)
		(width 0.0889)
		(layer "In11.Cu")
		(net "M_L_CPU0_SA_CB<0>")
	)
	(segment
		(start 441.518548 -235.160058)
		(end 440.668664 -234.310174)
		(width 0.14478)
		(layer "In11.Cu")
		(net "M_L_CPU0_SA_CB<0>")
	)
	(segment
		(start 427.309026 -235.160058)
		(end 425.257214 -234.310174)
		(width 0.14478)
		(layer "In11.Cu")
		(net "M_L_CPU0_SA_CB<0>")
	)
	(segment
		(start 391.873486 -244.799612)
		(end 391.861548 -244.80647)
		(width 0.0889)
		(layer "In11.Cu")
		(net "M_L_CPU0_SA_CB<0>")
	)
	(segment
		(start 391.861548 -244.80647)
		(end 391.845292 -244.815868)
		(width 0.0889)
		(layer "In11.Cu")
		(net "M_L_CPU0_SA_CB<0>")
	)
	(segment
		(start 436.686452 -235.160058)
		(end 434.101748 -235.160058)
		(width 0.14478)
		(layer "In11.Cu")
		(net "M_L_CPU0_SA_CB<0>")
	)
	(segment
		(start 404.115524 -244.07622)
		(end 396.348458 -244.07622)
		(width 0.14478)
		(layer "In11.Cu")
		(net "M_L_CPU0_SA_CB<0>")
	)
	(segment
		(start 450.97446 -234.865672)
		(end 450.97446 -234.454954)
		(width 0.14478)
		(layer "In11.Cu")
		(net "M_L_CPU0_SA_CB<0>")
	)
	(segment
		(start 440.668664 -234.310174)
		(end 437.536336 -234.310174)
		(width 0.14478)
		(layer "In11.Cu")
		(net "M_L_CPU0_SA_CB<0>")
	)
	(segment
		(start 430.400968 -234.310174)
		(end 428.349156 -235.160058)
		(width 0.14478)
		(layer "In11.Cu")
		(net "M_L_CPU0_SA_CB<0>")
	)
	(segment
		(start 413.066738 -235.125006)
		(end 404.115524 -244.07622)
		(width 0.14478)
		(layer "In11.Cu")
		(net "M_L_CPU0_SA_CB<0>")
	)
	(segment
		(start 394.875258 -245.114572)
		(end 394.403072 -245.114572)
		(width 0.0889)
		(layer "In11.Cu")
		(net "M_L_CPU0_SA_CB<0>")
	)
	(segment
		(start 444.769748 -234.310174)
		(end 443.919864 -235.160058)
		(width 0.14478)
		(layer "In11.Cu")
		(net "M_L_CPU0_SA_CB<0>")
	)
	(segment
		(start 451.381114 -235.010452)
		(end 451.11924 -235.010452)
		(width 0.14478)
		(layer "In11.Cu")
		(net "M_L_CPU0_SA_CB<0>")
	)
	(segment
		(start 419.42893 -235.160058)
		(end 417.377118 -234.310174)
		(width 0.14478)
		(layer "In11.Cu")
		(net "M_L_CPU0_SA_CB<0>")
	)
	(segment
		(start 454.188068 -234.735116)
		(end 453.763126 -234.310174)
		(width 0.14478)
		(layer "In11.Cu")
		(net "M_L_CPU0_SA_CB<0>")
	)
	(segment
		(start 433.251864 -234.310174)
		(end 430.400968 -234.310174)
		(width 0.14478)
		(layer "In11.Cu")
		(net "M_L_CPU0_SA_CB<0>")
	)
	(segment
		(start 450.97446 -234.454954)
		(end 450.82968 -234.310174)
		(width 0.14478)
		(layer "In11.Cu")
		(net "M_L_CPU0_SA_CB<0>")
	)
	(segment
		(start 453.763126 -234.310174)
		(end 451.670674 -234.310174)
		(width 0.14478)
		(layer "In11.Cu")
		(net "M_L_CPU0_SA_CB<0>")
	)
	(segment
		(start 389.041894 -244.806724)
		(end 389.033512 -244.81155)
		(width 0.0889)
		(layer "In11.Cu")
		(net "M_L_CPU0_SA_CB<0>")
	)
	(segment
		(start 423.14114 -234.310174)
		(end 421.089328 -235.160058)
		(width 0.14478)
		(layer "In11.Cu")
		(net "M_L_CPU0_SA_CB<0>")
	)
	(segment
		(start 425.257214 -234.310174)
		(end 423.14114 -234.310174)
		(width 0.14478)
		(layer "In11.Cu")
		(net "M_L_CPU0_SA_CB<0>")
	)
	(segment
		(start 450.82968 -234.310174)
		(end 444.769748 -234.310174)
		(width 0.14478)
		(layer "In11.Cu")
		(net "M_L_CPU0_SA_CB<0>")
	)
	(segment
		(start 451.670674 -234.310174)
		(end 451.525894 -234.454954)
		(width 0.14478)
		(layer "In11.Cu")
		(net "M_L_CPU0_SA_CB<0>")
	)
	(segment
		(start 395.91361 -244.07622)
		(end 394.875258 -245.114572)
		(width 0.0889)
		(layer "In11.Cu")
		(net "M_L_CPU0_SA_CB<0>")
	)
	(segment
		(start 387.224778 -244.774974)
		(end 387.128766 -244.749574)
		(width 0.0889)
		(layer "In11.Cu")
		(net "M_L_CPU0_SA_CB<0>")
	)
	(segment
		(start 417.377118 -234.310174)
		(end 415.034222 -234.310174)
		(width 0.14478)
		(layer "In11.Cu")
		(net "M_L_CPU0_SA_CB<0>")
	)
	(segment
		(start 434.101748 -235.160058)
		(end 433.251864 -234.310174)
		(width 0.14478)
		(layer "In11.Cu")
		(net "M_L_CPU0_SA_CB<0>")
	)
	(segment
		(start 437.536336 -234.310174)
		(end 436.686452 -235.160058)
		(width 0.14478)
		(layer "In11.Cu")
		(net "M_L_CPU0_SA_CB<0>")
	)
	(segment
		(start 451.525894 -234.865672)
		(end 451.381114 -235.010452)
		(width 0.14478)
		(layer "In11.Cu")
		(net "M_L_CPU0_SA_CB<0>")
	)
	(segment
		(start 415.034222 -234.310174)
		(end 413.066738 -235.125006)
		(width 0.14478)
		(layer "In11.Cu")
		(net "M_L_CPU0_SA_CB<0>")
	)
	(segment
		(start 387.128766 -244.749574)
		(end 386.974842 -244.484144)
		(width 0.0889)
		(layer "In11.Cu")
		(net "M_L_CPU0_SA_CB<0>")
	)
	(segment
		(start 451.11924 -235.010452)
		(end 450.97446 -234.865672)
		(width 0.14478)
		(layer "In11.Cu")
		(net "M_L_CPU0_SA_CB<0>")
	)
	(segment
		(start 392.438382 -244.813582)
		(end 392.426698 -244.806724)
		(width 0.0889)
		(layer "In11.Cu")
		(net "M_L_CPU0_SA_CB<0>")
	)
	(segment
		(start 396.348458 -244.07622)
		(end 395.91361 -244.07622)
		(width 0.0889)
		(layer "In11.Cu")
		(net "M_L_CPU0_SA_CB<0>")
	)
	(segment
		(start 394.403072 -245.114572)
		(end 394.01877 -244.73027)
		(width 0.0889)
		(layer "In11.Cu")
		(net "M_L_CPU0_SA_CB<0>")
	)
	(arc
		(start 387.727698 -244.806724)
		(mid 387.479985 -244.731504)
		(end 387.224778 -244.774974)
		(width 0.0889)
		(layer "In11.Cu")
		(net "M_L_CPU0_SA_CB<0>")
	)
	(arc
		(start 393.084812 -244.73027)
		(mid 392.937881 -244.749681)
		(end 392.801094 -244.806724)
		(width 0.0889)
		(layer "In11.Cu")
		(net "M_L_CPU0_SA_CB<0>")
	)
	(arc
		(start 388.093458 -244.81155)
		(mid 387.90995 -244.857044)
		(end 387.727698 -244.806724)
		(width 0.0889)
		(layer "In11.Cu")
		(net "M_L_CPU0_SA_CB<0>")
	)
	(arc
		(start 392.426698 -244.806724)
		(mid 392.15102 -244.730594)
		(end 391.873486 -244.799612)
		(width 0.0889)
		(layer "In11.Cu")
		(net "M_L_CPU0_SA_CB<0>")
	)
	(arc
		(start 389.981948 -244.806724)
		(mid 389.799697 -244.857074)
		(end 389.616188 -244.81155)
		(width 0.0889)
		(layer "In11.Cu")
		(net "M_L_CPU0_SA_CB<0>")
	)
	(arc
		(start 391.48766 -244.806724)
		(mid 391.204704 -244.730547)
		(end 390.921748 -244.806724)
		(width 0.0889)
		(layer "In11.Cu")
		(net "M_L_CPU0_SA_CB<0>")
	)
	(arc
		(start 392.801094 -244.806724)
		(mid 392.620636 -244.857168)
		(end 392.438382 -244.813582)
		(width 0.0889)
		(layer "In11.Cu")
		(net "M_L_CPU0_SA_CB<0>")
	)
	(arc
		(start 389.607806 -244.806724)
		(mid 389.32485 -244.730547)
		(end 389.041894 -244.806724)
		(width 0.0889)
		(layer "In11.Cu")
		(net "M_L_CPU0_SA_CB<0>")
	)
	(arc
		(start 390.921748 -244.806724)
		(mid 390.734804 -244.856979)
		(end 390.54786 -244.806724)
		(width 0.0889)
		(layer "In11.Cu")
		(net "M_L_CPU0_SA_CB<0>")
	)
	(arc
		(start 390.54786 -244.806724)
		(mid 390.264904 -244.730547)
		(end 389.981948 -244.806724)
		(width 0.0889)
		(layer "In11.Cu")
		(net "M_L_CPU0_SA_CB<0>")
	)
	(arc
		(start 389.033512 -244.81155)
		(mid 388.850004 -244.857044)
		(end 388.667752 -244.806724)
		(width 0.0889)
		(layer "In11.Cu")
		(net "M_L_CPU0_SA_CB<0>")
	)
	(arc
		(start 391.845292 -244.815868)
		(mid 391.66531 -244.856968)
		(end 391.48766 -244.806724)
		(width 0.0889)
		(layer "In11.Cu")
		(net "M_L_CPU0_SA_CB<0>")
	)
	(arc
		(start 388.667752 -244.806724)
		(mid 388.384796 -244.730547)
		(end 388.10184 -244.806724)
		(width 0.0889)
		(layer "In11.Cu")
		(net "M_L_CPU0_SA_CB<0>")
	)
	(segment
		(start 385.098036 -255.28016)
		(end 385.564888 -255.014222)
		(width 0.10668)
		(layer "F.Cu")
		(net "M_L_CPU0_SA_CA<6>")
	)
	(segment
		(start 447.852038 -253.010162)
		(end 448.46113 -252.40107)
		(width 0.14478)
		(layer "In11.Cu")
		(net "M_L_CPU0_SA_CA<6>")
	)
	(segment
		(start 395.20749 -256.097024)
		(end 395.748256 -256.097024)
		(width 0.0889)
		(layer "In11.Cu")
		(net "M_L_CPU0_SA_CA<6>")
	)
	(segment
		(start 392.887454 -255.330706)
		(end 392.897868 -255.336802)
		(width 0.0889)
		(layer "In11.Cu")
		(net "M_L_CPU0_SA_CA<6>")
	)
	(segment
		(start 446.427098 -253.010162)
		(end 447.852038 -253.010162)
		(width 0.14478)
		(layer "In11.Cu")
		(net "M_L_CPU0_SA_CA<6>")
	)
	(segment
		(start 450.27342 -252.160024)
		(end 453.763126 -252.160024)
		(width 0.14478)
		(layer "In11.Cu")
		(net "M_L_CPU0_SA_CA<6>")
	)
	(segment
		(start 388.197852 -255.336802)
		(end 388.206234 -255.341628)
		(width 0.0889)
		(layer "In11.Cu")
		(net "M_L_CPU0_SA_CA<6>")
	)
	(segment
		(start 386.683504 -255.341628)
		(end 386.691886 -255.336802)
		(width 0.0889)
		(layer "In11.Cu")
		(net "M_L_CPU0_SA_CA<6>")
	)
	(segment
		(start 391.391902 -255.336802)
		(end 391.402316 -255.330706)
		(width 0.0889)
		(layer "In11.Cu")
		(net "M_L_CPU0_SA_CA<6>")
	)
	(segment
		(start 410.764228 -254.6985)
		(end 410.775912 -254.710184)
		(width 0.14478)
		(layer "In11.Cu")
		(net "M_L_CPU0_SA_CA<6>")
	)
	(segment
		(start 387.257798 -255.336802)
		(end 387.26618 -255.341628)
		(width 0.0889)
		(layer "In11.Cu")
		(net "M_L_CPU0_SA_CA<6>")
	)
	(segment
		(start 448.46113 -252.40107)
		(end 449.667122 -252.40107)
		(width 0.14478)
		(layer "In11.Cu")
		(net "M_L_CPU0_SA_CA<6>")
	)
	(segment
		(start 393.084812 -255.387094)
		(end 394.49756 -255.387094)
		(width 0.0889)
		(layer "In11.Cu")
		(net "M_L_CPU0_SA_CA<6>")
	)
	(segment
		(start 410.775912 -254.710184)
		(end 444.727076 -254.710184)
		(width 0.14478)
		(layer "In11.Cu")
		(net "M_L_CPU0_SA_CA<6>")
	)
	(segment
		(start 400.13636 -254.6985)
		(end 410.764228 -254.6985)
		(width 0.14478)
		(layer "In11.Cu")
		(net "M_L_CPU0_SA_CA<6>")
	)
	(segment
		(start 444.727076 -254.710184)
		(end 446.427098 -253.010162)
		(width 0.14478)
		(layer "In11.Cu")
		(net "M_L_CPU0_SA_CA<6>")
	)
	(segment
		(start 449.914772 -252.160024)
		(end 450.27342 -252.160024)
		(width 0.0889)
		(layer "In11.Cu")
		(net "M_L_CPU0_SA_CA<6>")
	)
	(segment
		(start 449.851018 -252.217174)
		(end 449.857622 -252.217174)
		(width 0.0889)
		(layer "In11.Cu")
		(net "M_L_CPU0_SA_CA<6>")
	)
	(segment
		(start 449.667122 -252.40107)
		(end 449.851018 -252.217174)
		(width 0.14478)
		(layer "In11.Cu")
		(net "M_L_CPU0_SA_CA<6>")
	)
	(segment
		(start 395.748256 -256.097024)
		(end 398.737836 -256.097024)
		(width 0.14478)
		(layer "In11.Cu")
		(net "M_L_CPU0_SA_CA<6>")
	)
	(segment
		(start 453.763126 -252.160024)
		(end 454.188068 -252.584966)
		(width 0.14478)
		(layer "In11.Cu")
		(net "M_L_CPU0_SA_CA<6>")
	)
	(segment
		(start 394.49756 -255.387094)
		(end 395.20749 -256.097024)
		(width 0.0889)
		(layer "In11.Cu")
		(net "M_L_CPU0_SA_CA<6>")
	)
	(segment
		(start 398.737836 -256.097024)
		(end 400.13636 -254.6985)
		(width 0.14478)
		(layer "In11.Cu")
		(net "M_L_CPU0_SA_CA<6>")
	)
	(segment
		(start 385.718812 -255.279652)
		(end 385.814824 -255.305052)
		(width 0.0889)
		(layer "In11.Cu")
		(net "M_L_CPU0_SA_CA<6>")
	)
	(segment
		(start 392.323828 -255.341628)
		(end 392.33221 -255.336802)
		(width 0.0889)
		(layer "In11.Cu")
		(net "M_L_CPU0_SA_CA<6>")
	)
	(segment
		(start 385.564888 -255.014222)
		(end 385.718812 -255.279652)
		(width 0.0889)
		(layer "In11.Cu")
		(net "M_L_CPU0_SA_CA<6>")
	)
	(segment
		(start 449.857622 -252.217174)
		(end 449.914772 -252.160024)
		(width 0.0889)
		(layer "In11.Cu")
		(net "M_L_CPU0_SA_CA<6>")
	)
	(segment
		(start 390.443466 -255.341628)
		(end 390.451848 -255.336802)
		(width 0.0889)
		(layer "In11.Cu")
		(net "M_L_CPU0_SA_CA<6>")
	)
	(segment
		(start 391.01776 -255.336802)
		(end 391.026142 -255.341628)
		(width 0.0889)
		(layer "In11.Cu")
		(net "M_L_CPU0_SA_CA<6>")
	)
	(arc
		(start 391.402316 -255.330706)
		(mid 391.681002 -255.260486)
		(end 391.958068 -255.336802)
		(width 0.0889)
		(layer "In11.Cu")
		(net "M_L_CPU0_SA_CA<6>")
	)
	(arc
		(start 388.206234 -255.341628)
		(mid 388.389742 -255.387122)
		(end 388.571994 -255.336802)
		(width 0.0889)
		(layer "In11.Cu")
		(net "M_L_CPU0_SA_CA<6>")
	)
	(arc
		(start 388.571994 -255.336802)
		(mid 388.85495 -255.260625)
		(end 389.137906 -255.336802)
		(width 0.0889)
		(layer "In11.Cu")
		(net "M_L_CPU0_SA_CA<6>")
	)
	(arc
		(start 390.451848 -255.336802)
		(mid 390.734804 -255.260625)
		(end 391.01776 -255.336802)
		(width 0.0889)
		(layer "In11.Cu")
		(net "M_L_CPU0_SA_CA<6>")
	)
	(arc
		(start 389.511794 -255.336802)
		(mid 389.79475 -255.260625)
		(end 390.077706 -255.336802)
		(width 0.0889)
		(layer "In11.Cu")
		(net "M_L_CPU0_SA_CA<6>")
	)
	(arc
		(start 391.958068 -255.336802)
		(mid 392.140319 -255.387152)
		(end 392.323828 -255.341628)
		(width 0.0889)
		(layer "In11.Cu")
		(net "M_L_CPU0_SA_CA<6>")
	)
	(arc
		(start 392.33221 -255.336802)
		(mid 392.609023 -255.260659)
		(end 392.887454 -255.330706)
		(width 0.0889)
		(layer "In11.Cu")
		(net "M_L_CPU0_SA_CA<6>")
	)
	(arc
		(start 385.814824 -255.305052)
		(mid 386.070032 -255.261575)
		(end 386.317744 -255.336802)
		(width 0.0889)
		(layer "In11.Cu")
		(net "M_L_CPU0_SA_CA<6>")
	)
	(arc
		(start 386.317744 -255.336802)
		(mid 386.499995 -255.387152)
		(end 386.683504 -255.341628)
		(width 0.0889)
		(layer "In11.Cu")
		(net "M_L_CPU0_SA_CA<6>")
	)
	(arc
		(start 392.897868 -255.336802)
		(mid 392.988017 -255.374299)
		(end 393.084812 -255.387094)
		(width 0.0889)
		(layer "In11.Cu")
		(net "M_L_CPU0_SA_CA<6>")
	)
	(arc
		(start 386.691886 -255.336802)
		(mid 386.974842 -255.260625)
		(end 387.257798 -255.336802)
		(width 0.0889)
		(layer "In11.Cu")
		(net "M_L_CPU0_SA_CA<6>")
	)
	(arc
		(start 387.63194 -255.336802)
		(mid 387.914896 -255.260625)
		(end 388.197852 -255.336802)
		(width 0.0889)
		(layer "In11.Cu")
		(net "M_L_CPU0_SA_CA<6>")
	)
	(arc
		(start 390.077706 -255.336802)
		(mid 390.259957 -255.387152)
		(end 390.443466 -255.341628)
		(width 0.0889)
		(layer "In11.Cu")
		(net "M_L_CPU0_SA_CA<6>")
	)
	(arc
		(start 389.137906 -255.336802)
		(mid 389.32485 -255.387057)
		(end 389.511794 -255.336802)
		(width 0.0889)
		(layer "In11.Cu")
		(net "M_L_CPU0_SA_CA<6>")
	)
	(arc
		(start 387.26618 -255.341628)
		(mid 387.449688 -255.387122)
		(end 387.63194 -255.336802)
		(width 0.0889)
		(layer "In11.Cu")
		(net "M_L_CPU0_SA_CA<6>")
	)
	(arc
		(start 391.026142 -255.341628)
		(mid 391.20965 -255.387122)
		(end 391.391902 -255.336802)
		(width 0.0889)
		(layer "In11.Cu")
		(net "M_L_CPU0_SA_CA<6>")
	)
	(segment
		(start 386.97789 -255.28016)
		(end 387.444742 -255.014222)
		(width 0.10668)
		(layer "F.Cu")
		(net "M_L_CPU0_SA_CA<5>")
	)
	(segment
		(start 444.589154 -253.25832)
		(end 444.589154 -253.053596)
		(width 0.14478)
		(layer "In11.Cu")
		(net "M_L_CPU0_SA_CA<5>")
	)
	(segment
		(start 441.089796 -253.626112)
		(end 441.234576 -253.481332)
		(width 0.14478)
		(layer "In11.Cu")
		(net "M_L_CPU0_SA_CA<5>")
	)
	(segment
		(start 387.290818 -254.748792)
		(end 387.31317 -254.66548)
		(width 0.0889)
		(layer "In11.Cu")
		(net "M_L_CPU0_SA_CA<5>")
	)
	(segment
		(start 394.649198 -255.056132)
		(end 395.23543 -255.642364)
		(width 0.0889)
		(layer "In11.Cu")
		(net "M_L_CPU0_SA_CA<5>")
	)
	(segment
		(start 412.011114 -254.24384)
		(end 412.012384 -254.24511)
		(width 0.14478)
		(layer "In11.Cu")
		(net "M_L_CPU0_SA_CA<5>")
	)
	(segment
		(start 395.23543 -255.642364)
		(end 395.748256 -255.642364)
		(width 0.0889)
		(layer "In11.Cu")
		(net "M_L_CPU0_SA_CA<5>")
	)
	(segment
		(start 412.242762 -254.24511)
		(end 412.40583 -254.082042)
		(width 0.14478)
		(layer "In11.Cu")
		(net "M_L_CPU0_SA_CA<5>")
	)
	(segment
		(start 448.023488 -251.735082)
		(end 450.088 -251.735082)
		(width 0.14478)
		(layer "In11.Cu")
		(net "M_L_CPU0_SA_CA<5>")
	)
	(segment
		(start 444.774574 -252.868176)
		(end 444.979298 -252.868176)
		(width 0.14478)
		(layer "In11.Cu")
		(net "M_L_CPU0_SA_CA<5>")
	)
	(segment
		(start 445.369442 -252.273308)
		(end 445.554862 -252.087888)
		(width 0.14478)
		(layer "In11.Cu")
		(net "M_L_CPU0_SA_CA<5>")
	)
	(segment
		(start 444.589154 -253.053596)
		(end 444.774574 -252.868176)
		(width 0.14478)
		(layer "In11.Cu")
		(net "M_L_CPU0_SA_CA<5>")
	)
	(segment
		(start 446.197482 -252.32106)
		(end 446.358518 -252.160024)
		(width 0.14478)
		(layer "In11.Cu")
		(net "M_L_CPU0_SA_CA<5>")
	)
	(segment
		(start 440.131708 -253.481332)
		(end 440.393582 -253.481332)
		(width 0.14478)
		(layer "In11.Cu")
		(net "M_L_CPU0_SA_CA<5>")
	)
	(segment
		(start 444.979298 -252.868176)
		(end 445.21247 -253.101348)
		(width 0.14478)
		(layer "In11.Cu")
		(net "M_L_CPU0_SA_CA<5>")
	)
	(segment
		(start 388.197852 -254.691642)
		(end 388.206234 -254.686816)
		(width 0.0889)
		(layer "In11.Cu")
		(net "M_L_CPU0_SA_CA<5>")
	)
	(segment
		(start 445.369442 -252.478032)
		(end 445.369442 -252.273308)
		(width 0.14478)
		(layer "In11.Cu")
		(net "M_L_CPU0_SA_CA<5>")
	)
	(segment
		(start 390.443466 -254.686816)
		(end 390.451848 -254.691642)
		(width 0.0889)
		(layer "In11.Cu")
		(net "M_L_CPU0_SA_CA<5>")
	)
	(segment
		(start 412.40583 -254.004826)
		(end 412.55061 -253.860046)
		(width 0.14478)
		(layer "In11.Cu")
		(net "M_L_CPU0_SA_CA<5>")
	)
	(segment
		(start 393.863068 -254.640842)
		(end 394.278358 -255.056132)
		(width 0.0889)
		(layer "In11.Cu")
		(net "M_L_CPU0_SA_CA<5>")
	)
	(segment
		(start 387.444742 -255.014222)
		(end 387.290818 -254.748792)
		(width 0.0889)
		(layer "In11.Cu")
		(net "M_L_CPU0_SA_CA<5>")
	)
	(segment
		(start 391.01776 -254.691642)
		(end 391.026142 -254.686816)
		(width 0.0889)
		(layer "In11.Cu")
		(net "M_L_CPU0_SA_CA<5>")
	)
	(segment
		(start 441.64123 -253.715266)
		(end 441.78601 -253.860046)
		(width 0.14478)
		(layer "In11.Cu")
		(net "M_L_CPU0_SA_CA<5>")
	)
	(segment
		(start 441.78601 -253.860046)
		(end 444.658496 -253.860046)
		(width 0.14478)
		(layer "In11.Cu")
		(net "M_L_CPU0_SA_CA<5>")
	)
	(segment
		(start 441.234576 -253.481332)
		(end 441.49645 -253.481332)
		(width 0.14478)
		(layer "In11.Cu")
		(net "M_L_CPU0_SA_CA<5>")
	)
	(segment
		(start 445.992758 -252.32106)
		(end 446.197482 -252.32106)
		(width 0.14478)
		(layer "In11.Cu")
		(net "M_L_CPU0_SA_CA<5>")
	)
	(segment
		(start 445.759586 -252.087888)
		(end 445.992758 -252.32106)
		(width 0.14478)
		(layer "In11.Cu")
		(net "M_L_CPU0_SA_CA<5>")
	)
	(segment
		(start 444.658496 -253.860046)
		(end 444.822326 -253.696216)
		(width 0.14478)
		(layer "In11.Cu")
		(net "M_L_CPU0_SA_CA<5>")
	)
	(segment
		(start 440.393582 -253.481332)
		(end 440.538362 -253.626112)
		(width 0.14478)
		(layer "In11.Cu")
		(net "M_L_CPU0_SA_CA<5>")
	)
	(segment
		(start 439.842148 -253.860046)
		(end 439.986928 -253.715266)
		(width 0.14478)
		(layer "In11.Cu")
		(net "M_L_CPU0_SA_CA<5>")
	)
	(segment
		(start 444.822326 -253.491492)
		(end 444.589154 -253.25832)
		(width 0.14478)
		(layer "In11.Cu")
		(net "M_L_CPU0_SA_CA<5>")
	)
	(segment
		(start 445.417194 -253.101348)
		(end 445.602614 -252.915928)
		(width 0.14478)
		(layer "In11.Cu")
		(net "M_L_CPU0_SA_CA<5>")
	)
	(segment
		(start 395.748256 -255.642364)
		(end 398.549114 -255.642364)
		(width 0.14478)
		(layer "In11.Cu")
		(net "M_L_CPU0_SA_CA<5>")
	)
	(segment
		(start 439.986928 -253.715266)
		(end 439.986928 -253.626112)
		(width 0.14478)
		(layer "In11.Cu")
		(net "M_L_CPU0_SA_CA<5>")
	)
	(segment
		(start 398.549114 -255.642364)
		(end 399.947638 -254.24384)
		(width 0.14478)
		(layer "In11.Cu")
		(net "M_L_CPU0_SA_CA<5>")
	)
	(segment
		(start 441.089796 -254.09398)
		(end 441.089796 -253.626112)
		(width 0.14478)
		(layer "In11.Cu")
		(net "M_L_CPU0_SA_CA<5>")
	)
	(segment
		(start 399.947638 -254.24384)
		(end 412.011114 -254.24384)
		(width 0.14478)
		(layer "In11.Cu")
		(net "M_L_CPU0_SA_CA<5>")
	)
	(segment
		(start 412.012384 -254.24511)
		(end 412.242762 -254.24511)
		(width 0.14478)
		(layer "In11.Cu")
		(net "M_L_CPU0_SA_CA<5>")
	)
	(segment
		(start 440.538362 -253.626112)
		(end 440.538362 -254.09398)
		(width 0.14478)
		(layer "In11.Cu")
		(net "M_L_CPU0_SA_CA<5>")
	)
	(segment
		(start 441.49645 -253.481332)
		(end 441.64123 -253.626112)
		(width 0.14478)
		(layer "In11.Cu")
		(net "M_L_CPU0_SA_CA<5>")
	)
	(segment
		(start 445.554862 -252.087888)
		(end 445.759586 -252.087888)
		(width 0.14478)
		(layer "In11.Cu")
		(net "M_L_CPU0_SA_CA<5>")
	)
	(segment
		(start 440.945016 -254.23876)
		(end 441.089796 -254.09398)
		(width 0.14478)
		(layer "In11.Cu")
		(net "M_L_CPU0_SA_CA<5>")
	)
	(segment
		(start 445.602614 -252.711204)
		(end 445.369442 -252.478032)
		(width 0.14478)
		(layer "In11.Cu")
		(net "M_L_CPU0_SA_CA<5>")
	)
	(segment
		(start 412.55061 -253.860046)
		(end 439.842148 -253.860046)
		(width 0.14478)
		(layer "In11.Cu")
		(net "M_L_CPU0_SA_CA<5>")
	)
	(segment
		(start 391.957052 -254.691896)
		(end 391.970768 -254.684022)
		(width 0.0889)
		(layer "In11.Cu")
		(net "M_L_CPU0_SA_CA<5>")
	)
	(segment
		(start 444.822326 -253.696216)
		(end 444.822326 -253.491492)
		(width 0.14478)
		(layer "In11.Cu")
		(net "M_L_CPU0_SA_CA<5>")
	)
	(segment
		(start 440.538362 -254.09398)
		(end 440.683142 -254.23876)
		(width 0.14478)
		(layer "In11.Cu")
		(net "M_L_CPU0_SA_CA<5>")
	)
	(segment
		(start 394.278358 -255.056132)
		(end 394.649198 -255.056132)
		(width 0.0889)
		(layer "In11.Cu")
		(net "M_L_CPU0_SA_CA<5>")
	)
	(segment
		(start 441.64123 -253.626112)
		(end 441.64123 -253.715266)
		(width 0.14478)
		(layer "In11.Cu")
		(net "M_L_CPU0_SA_CA<5>")
	)
	(segment
		(start 445.602614 -252.915928)
		(end 445.602614 -252.711204)
		(width 0.14478)
		(layer "In11.Cu")
		(net "M_L_CPU0_SA_CA<5>")
	)
	(segment
		(start 391.945114 -254.698754)
		(end 391.957052 -254.691896)
		(width 0.0889)
		(layer "In11.Cu")
		(net "M_L_CPU0_SA_CA<5>")
	)
	(segment
		(start 439.986928 -253.626112)
		(end 440.131708 -253.481332)
		(width 0.14478)
		(layer "In11.Cu")
		(net "M_L_CPU0_SA_CA<5>")
	)
	(segment
		(start 447.598546 -252.160024)
		(end 448.023488 -251.735082)
		(width 0.14478)
		(layer "In11.Cu")
		(net "M_L_CPU0_SA_CA<5>")
	)
	(segment
		(start 392.330686 -254.691642)
		(end 392.34872 -254.70231)
		(width 0.0889)
		(layer "In11.Cu")
		(net "M_L_CPU0_SA_CA<5>")
	)
	(segment
		(start 393.084812 -254.640842)
		(end 393.863068 -254.640842)
		(width 0.0889)
		(layer "In11.Cu")
		(net "M_L_CPU0_SA_CA<5>")
	)
	(segment
		(start 412.40583 -254.082042)
		(end 412.40583 -254.004826)
		(width 0.14478)
		(layer "In11.Cu")
		(net "M_L_CPU0_SA_CA<5>")
	)
	(segment
		(start 446.358518 -252.160024)
		(end 447.598546 -252.160024)
		(width 0.14478)
		(layer "In11.Cu")
		(net "M_L_CPU0_SA_CA<5>")
	)
	(segment
		(start 445.21247 -253.101348)
		(end 445.417194 -253.101348)
		(width 0.14478)
		(layer "In11.Cu")
		(net "M_L_CPU0_SA_CA<5>")
	)
	(segment
		(start 440.683142 -254.23876)
		(end 440.945016 -254.23876)
		(width 0.14478)
		(layer "In11.Cu")
		(net "M_L_CPU0_SA_CA<5>")
	)
	(arc
		(start 392.34872 -254.70231)
		(mid 392.624415 -254.768153)
		(end 392.89736 -254.691642)
		(width 0.0889)
		(layer "In11.Cu")
		(net "M_L_CPU0_SA_CA<5>")
	)
	(arc
		(start 389.137906 -254.691642)
		(mid 389.32485 -254.641387)
		(end 389.511794 -254.691642)
		(width 0.0889)
		(layer "In11.Cu")
		(net "M_L_CPU0_SA_CA<5>")
	)
	(arc
		(start 387.63194 -254.691642)
		(mid 387.914896 -254.767819)
		(end 388.197852 -254.691642)
		(width 0.0889)
		(layer "In11.Cu")
		(net "M_L_CPU0_SA_CA<5>")
	)
	(arc
		(start 390.077706 -254.691642)
		(mid 390.259957 -254.641292)
		(end 390.443466 -254.686816)
		(width 0.0889)
		(layer "In11.Cu")
		(net "M_L_CPU0_SA_CA<5>")
	)
	(arc
		(start 391.391902 -254.691642)
		(mid 391.66758 -254.767772)
		(end 391.945114 -254.698754)
		(width 0.0889)
		(layer "In11.Cu")
		(net "M_L_CPU0_SA_CA<5>")
	)
	(arc
		(start 390.451848 -254.691642)
		(mid 390.734804 -254.767819)
		(end 391.01776 -254.691642)
		(width 0.0889)
		(layer "In11.Cu")
		(net "M_L_CPU0_SA_CA<5>")
	)
	(arc
		(start 388.571994 -254.691642)
		(mid 388.85495 -254.767819)
		(end 389.137906 -254.691642)
		(width 0.0889)
		(layer "In11.Cu")
		(net "M_L_CPU0_SA_CA<5>")
	)
	(arc
		(start 387.31317 -254.66548)
		(mid 387.475502 -254.642662)
		(end 387.63194 -254.691642)
		(width 0.0889)
		(layer "In11.Cu")
		(net "M_L_CPU0_SA_CA<5>")
	)
	(arc
		(start 391.970768 -254.684022)
		(mid 392.151698 -254.641544)
		(end 392.330686 -254.691642)
		(width 0.0889)
		(layer "In11.Cu")
		(net "M_L_CPU0_SA_CA<5>")
	)
	(arc
		(start 391.026142 -254.686816)
		(mid 391.20965 -254.641322)
		(end 391.391902 -254.691642)
		(width 0.0889)
		(layer "In11.Cu")
		(net "M_L_CPU0_SA_CA<5>")
	)
	(arc
		(start 389.511794 -254.691642)
		(mid 389.79475 -254.767819)
		(end 390.077706 -254.691642)
		(width 0.0889)
		(layer "In11.Cu")
		(net "M_L_CPU0_SA_CA<5>")
	)
	(arc
		(start 388.206234 -254.686816)
		(mid 388.389742 -254.641322)
		(end 388.571994 -254.691642)
		(width 0.0889)
		(layer "In11.Cu")
		(net "M_L_CPU0_SA_CA<5>")
	)
	(arc
		(start 392.89736 -254.691642)
		(mid 392.987723 -254.653832)
		(end 393.084812 -254.640842)
		(width 0.0889)
		(layer "In11.Cu")
		(net "M_L_CPU0_SA_CA<5>")
	)
	(segment
		(start 386.50799 -254.470154)
		(end 386.974842 -254.204216)
		(width 0.10668)
		(layer "F.Cu")
		(net "M_L_CPU0_SA_CA<4>")
	)
	(segment
		(start 395.23543 -255.187704)
		(end 395.759686 -255.187704)
		(width 0.0889)
		(layer "In11.Cu")
		(net "M_L_CPU0_SA_CA<4>")
	)
	(segment
		(start 411.014164 -253.78918)
		(end 411.793182 -253.010162)
		(width 0.14478)
		(layer "In11.Cu")
		(net "M_L_CPU0_SA_CA<4>")
	)
	(segment
		(start 388.093458 -254.531622)
		(end 388.10184 -254.526796)
		(width 0.0889)
		(layer "In11.Cu")
		(net "M_L_CPU0_SA_CA<4>")
	)
	(segment
		(start 443.867286 -253.010162)
		(end 445.567308 -251.31014)
		(width 0.14478)
		(layer "In11.Cu")
		(net "M_L_CPU0_SA_CA<4>")
	)
	(segment
		(start 445.567308 -251.31014)
		(end 447.22415 -251.31014)
		(width 0.14478)
		(layer "In11.Cu")
		(net "M_L_CPU0_SA_CA<4>")
	)
	(segment
		(start 394.913358 -254.865632)
		(end 395.23543 -255.187704)
		(width 0.0889)
		(layer "In11.Cu")
		(net "M_L_CPU0_SA_CA<4>")
	)
	(segment
		(start 398.360392 -255.187704)
		(end 399.758916 -253.78918)
		(width 0.14478)
		(layer "In11.Cu")
		(net "M_L_CPU0_SA_CA<4>")
	)
	(segment
		(start 391.861548 -254.526542)
		(end 391.873486 -254.519684)
		(width 0.0889)
		(layer "In11.Cu")
		(net "M_L_CPU0_SA_CA<4>")
	)
	(segment
		(start 393.942062 -254.450342)
		(end 394.357352 -254.865632)
		(width 0.0889)
		(layer "In11.Cu")
		(net "M_L_CPU0_SA_CA<4>")
	)
	(segment
		(start 392.426698 -254.526796)
		(end 392.438382 -254.533654)
		(width 0.0889)
		(layer "In11.Cu")
		(net "M_L_CPU0_SA_CA<4>")
	)
	(segment
		(start 450.27342 -251.31014)
		(end 453.762872 -251.31014)
		(width 0.14478)
		(layer "In11.Cu")
		(net "M_L_CPU0_SA_CA<4>")
	)
	(segment
		(start 449.914772 -251.31014)
		(end 450.27342 -251.31014)
		(width 0.0889)
		(layer "In11.Cu")
		(net "M_L_CPU0_SA_CA<4>")
	)
	(segment
		(start 394.357352 -254.865632)
		(end 394.913358 -254.865632)
		(width 0.0889)
		(layer "In11.Cu")
		(net "M_L_CPU0_SA_CA<4>")
	)
	(segment
		(start 447.22415 -251.31014)
		(end 447.44894 -251.08535)
		(width 0.14478)
		(layer "In11.Cu")
		(net "M_L_CPU0_SA_CA<4>")
	)
	(segment
		(start 395.759686 -255.187704)
		(end 398.360392 -255.187704)
		(width 0.14478)
		(layer "In11.Cu")
		(net "M_L_CPU0_SA_CA<4>")
	)
	(segment
		(start 387.128766 -254.469646)
		(end 387.224778 -254.495046)
		(width 0.0889)
		(layer "In11.Cu")
		(net "M_L_CPU0_SA_CA<4>")
	)
	(segment
		(start 389.607806 -254.526796)
		(end 389.616188 -254.531622)
		(width 0.0889)
		(layer "In11.Cu")
		(net "M_L_CPU0_SA_CA<4>")
	)
	(segment
		(start 449.683378 -251.08535)
		(end 449.851018 -251.25299)
		(width 0.14478)
		(layer "In11.Cu")
		(net "M_L_CPU0_SA_CA<4>")
	)
	(segment
		(start 386.974842 -254.204216)
		(end 387.128766 -254.469646)
		(width 0.0889)
		(layer "In11.Cu")
		(net "M_L_CPU0_SA_CA<4>")
	)
	(segment
		(start 449.851018 -251.25299)
		(end 449.857622 -251.25299)
		(width 0.0889)
		(layer "In11.Cu")
		(net "M_L_CPU0_SA_CA<4>")
	)
	(segment
		(start 393.084812 -254.450342)
		(end 393.942062 -254.450342)
		(width 0.0889)
		(layer "In11.Cu")
		(net "M_L_CPU0_SA_CA<4>")
	)
	(segment
		(start 447.44894 -251.08535)
		(end 449.683378 -251.08535)
		(width 0.14478)
		(layer "In11.Cu")
		(net "M_L_CPU0_SA_CA<4>")
	)
	(segment
		(start 449.857622 -251.25299)
		(end 449.914772 -251.31014)
		(width 0.0889)
		(layer "In11.Cu")
		(net "M_L_CPU0_SA_CA<4>")
	)
	(segment
		(start 411.793182 -253.010162)
		(end 443.867286 -253.010162)
		(width 0.14478)
		(layer "In11.Cu")
		(net "M_L_CPU0_SA_CA<4>")
	)
	(segment
		(start 399.758916 -253.78918)
		(end 411.014164 -253.78918)
		(width 0.14478)
		(layer "In11.Cu")
		(net "M_L_CPU0_SA_CA<4>")
	)
	(segment
		(start 389.033512 -254.531622)
		(end 389.041894 -254.526796)
		(width 0.0889)
		(layer "In11.Cu")
		(net "M_L_CPU0_SA_CA<4>")
	)
	(segment
		(start 453.762872 -251.31014)
		(end 454.188068 -250.884944)
		(width 0.14478)
		(layer "In11.Cu")
		(net "M_L_CPU0_SA_CA<4>")
	)
	(segment
		(start 391.845292 -254.53594)
		(end 391.861548 -254.526542)
		(width 0.0889)
		(layer "In11.Cu")
		(net "M_L_CPU0_SA_CA<4>")
	)
	(arc
		(start 391.873486 -254.519684)
		(mid 392.15102 -254.450703)
		(end 392.426698 -254.526796)
		(width 0.0889)
		(layer "In11.Cu")
		(net "M_L_CPU0_SA_CA<4>")
	)
	(arc
		(start 389.981948 -254.526796)
		(mid 390.264904 -254.450619)
		(end 390.54786 -254.526796)
		(width 0.0889)
		(layer "In11.Cu")
		(net "M_L_CPU0_SA_CA<4>")
	)
	(arc
		(start 387.224778 -254.495046)
		(mid 387.479986 -254.451569)
		(end 387.727698 -254.526796)
		(width 0.0889)
		(layer "In11.Cu")
		(net "M_L_CPU0_SA_CA<4>")
	)
	(arc
		(start 389.041894 -254.526796)
		(mid 389.32485 -254.450619)
		(end 389.607806 -254.526796)
		(width 0.0889)
		(layer "In11.Cu")
		(net "M_L_CPU0_SA_CA<4>")
	)
	(arc
		(start 389.616188 -254.531622)
		(mid 389.799696 -254.577116)
		(end 389.981948 -254.526796)
		(width 0.0889)
		(layer "In11.Cu")
		(net "M_L_CPU0_SA_CA<4>")
	)
	(arc
		(start 392.801094 -254.526796)
		(mid 392.937887 -254.469774)
		(end 393.084812 -254.450342)
		(width 0.0889)
		(layer "In11.Cu")
		(net "M_L_CPU0_SA_CA<4>")
	)
	(arc
		(start 388.10184 -254.526796)
		(mid 388.384796 -254.450619)
		(end 388.667752 -254.526796)
		(width 0.0889)
		(layer "In11.Cu")
		(net "M_L_CPU0_SA_CA<4>")
	)
	(arc
		(start 391.48766 -254.526796)
		(mid 391.66531 -254.577056)
		(end 391.845292 -254.53594)
		(width 0.0889)
		(layer "In11.Cu")
		(net "M_L_CPU0_SA_CA<4>")
	)
	(arc
		(start 388.667752 -254.526796)
		(mid 388.850003 -254.577146)
		(end 389.033512 -254.531622)
		(width 0.0889)
		(layer "In11.Cu")
		(net "M_L_CPU0_SA_CA<4>")
	)
	(arc
		(start 392.438382 -254.533654)
		(mid 392.620637 -254.577307)
		(end 392.801094 -254.526796)
		(width 0.0889)
		(layer "In11.Cu")
		(net "M_L_CPU0_SA_CA<4>")
	)
	(arc
		(start 390.54786 -254.526796)
		(mid 390.734804 -254.577051)
		(end 390.921748 -254.526796)
		(width 0.0889)
		(layer "In11.Cu")
		(net "M_L_CPU0_SA_CA<4>")
	)
	(arc
		(start 390.921748 -254.526796)
		(mid 391.204704 -254.450619)
		(end 391.48766 -254.526796)
		(width 0.0889)
		(layer "In11.Cu")
		(net "M_L_CPU0_SA_CA<4>")
	)
	(arc
		(start 387.727698 -254.526796)
		(mid 387.909949 -254.577146)
		(end 388.093458 -254.531622)
		(width 0.0889)
		(layer "In11.Cu")
		(net "M_L_CPU0_SA_CA<4>")
	)
	(segment
		(start 385.567936 -254.470154)
		(end 386.034788 -254.204216)
		(width 0.10668)
		(layer "F.Cu")
		(net "M_L_CPU0_SA_CA<3>")
	)
	(segment
		(start 410.764228 -253.33452)
		(end 399.570448 -253.33452)
		(width 0.14478)
		(layer "In11.Cu")
		(net "M_L_CPU0_SA_CA<3>")
	)
	(segment
		(start 413.346646 -252.540516)
		(end 413.201866 -252.395736)
		(width 0.14478)
		(layer "In11.Cu")
		(net "M_L_CPU0_SA_CA<3>")
	)
	(segment
		(start 388.10184 -253.881636)
		(end 388.093458 -253.87681)
		(width 0.0889)
		(layer "In11.Cu")
		(net "M_L_CPU0_SA_CA<3>")
	)
	(segment
		(start 449.663058 -250.460002)
		(end 445.507364 -250.460002)
		(width 0.14478)
		(layer "In11.Cu")
		(net "M_L_CPU0_SA_CA<3>")
	)
	(segment
		(start 413.89808 -251.779532)
		(end 413.7533 -251.924312)
		(width 0.14478)
		(layer "In11.Cu")
		(net "M_L_CPU0_SA_CA<3>")
	)
	(segment
		(start 385.903216 -253.855474)
		(end 385.880864 -253.938786)
		(width 0.0889)
		(layer "In11.Cu")
		(net "M_L_CPU0_SA_CA<3>")
	)
	(segment
		(start 399.570448 -253.33452)
		(end 398.171924 -254.733044)
		(width 0.14478)
		(layer "In11.Cu")
		(net "M_L_CPU0_SA_CA<3>")
	)
	(segment
		(start 392.428222 -253.881636)
		(end 392.417808 -253.887732)
		(width 0.0889)
		(layer "In11.Cu")
		(net "M_L_CPU0_SA_CA<3>")
	)
	(segment
		(start 411.938724 -252.160024)
		(end 410.764228 -253.33452)
		(width 0.14478)
		(layer "In11.Cu")
		(net "M_L_CPU0_SA_CA<3>")
	)
	(segment
		(start 394.711428 -253.957582)
		(end 393.084812 -253.957582)
		(width 0.0889)
		(layer "In11.Cu")
		(net "M_L_CPU0_SA_CA<3>")
	)
	(segment
		(start 415.552382 -252.160024)
		(end 415.407602 -252.015244)
		(width 0.14478)
		(layer "In11.Cu")
		(net "M_L_CPU0_SA_CA<3>")
	)
	(segment
		(start 395.759686 -254.733044)
		(end 395.48689 -254.733044)
		(width 0.0889)
		(layer "In11.Cu")
		(net "M_L_CPU0_SA_CA<3>")
	)
	(segment
		(start 414.856168 -252.395736)
		(end 414.711388 -252.540516)
		(width 0.14478)
		(layer "In11.Cu")
		(net "M_L_CPU0_SA_CA<3>")
	)
	(segment
		(start 414.304734 -252.395736)
		(end 414.304734 -251.924312)
		(width 0.14478)
		(layer "In11.Cu")
		(net "M_L_CPU0_SA_CA<3>")
	)
	(segment
		(start 443.807342 -252.160024)
		(end 415.552382 -252.160024)
		(width 0.14478)
		(layer "In11.Cu")
		(net "M_L_CPU0_SA_CA<3>")
	)
	(segment
		(start 445.507364 -250.460002)
		(end 443.807342 -252.160024)
		(width 0.14478)
		(layer "In11.Cu")
		(net "M_L_CPU0_SA_CA<3>")
	)
	(segment
		(start 413.201866 -252.395736)
		(end 413.201866 -252.304804)
		(width 0.14478)
		(layer "In11.Cu")
		(net "M_L_CPU0_SA_CA<3>")
	)
	(segment
		(start 415.262822 -251.779532)
		(end 415.000948 -251.779532)
		(width 0.14478)
		(layer "In11.Cu")
		(net "M_L_CPU0_SA_CA<3>")
	)
	(segment
		(start 414.159954 -251.779532)
		(end 413.89808 -251.779532)
		(width 0.14478)
		(layer "In11.Cu")
		(net "M_L_CPU0_SA_CA<3>")
	)
	(segment
		(start 413.201866 -252.304804)
		(end 413.057086 -252.160024)
		(width 0.14478)
		(layer "In11.Cu")
		(net "M_L_CPU0_SA_CA<3>")
	)
	(segment
		(start 413.7533 -252.395736)
		(end 413.60852 -252.540516)
		(width 0.14478)
		(layer "In11.Cu")
		(net "M_L_CPU0_SA_CA<3>")
	)
	(segment
		(start 413.7533 -251.924312)
		(end 413.7533 -252.395736)
		(width 0.14478)
		(layer "In11.Cu")
		(net "M_L_CPU0_SA_CA<3>")
	)
	(segment
		(start 398.171924 -254.733044)
		(end 395.759686 -254.733044)
		(width 0.14478)
		(layer "In11.Cu")
		(net "M_L_CPU0_SA_CA<3>")
	)
	(segment
		(start 385.880864 -253.938786)
		(end 386.034788 -254.204216)
		(width 0.0889)
		(layer "In11.Cu")
		(net "M_L_CPU0_SA_CA<3>")
	)
	(segment
		(start 414.304734 -251.924312)
		(end 414.159954 -251.779532)
		(width 0.14478)
		(layer "In11.Cu")
		(net "M_L_CPU0_SA_CA<3>")
	)
	(segment
		(start 389.616188 -253.87681)
		(end 389.607806 -253.881636)
		(width 0.0889)
		(layer "In11.Cu")
		(net "M_L_CPU0_SA_CA<3>")
	)
	(segment
		(start 389.041894 -253.881636)
		(end 389.033512 -253.87681)
		(width 0.0889)
		(layer "In11.Cu")
		(net "M_L_CPU0_SA_CA<3>")
	)
	(segment
		(start 415.407602 -252.015244)
		(end 415.407602 -251.924312)
		(width 0.14478)
		(layer "In11.Cu")
		(net "M_L_CPU0_SA_CA<3>")
	)
	(segment
		(start 395.48689 -254.733044)
		(end 394.711428 -253.957582)
		(width 0.0889)
		(layer "In11.Cu")
		(net "M_L_CPU0_SA_CA<3>")
	)
	(segment
		(start 414.449514 -252.540516)
		(end 414.304734 -252.395736)
		(width 0.14478)
		(layer "In11.Cu")
		(net "M_L_CPU0_SA_CA<3>")
	)
	(segment
		(start 413.057086 -252.160024)
		(end 411.938724 -252.160024)
		(width 0.14478)
		(layer "In11.Cu")
		(net "M_L_CPU0_SA_CA<3>")
	)
	(segment
		(start 414.711388 -252.540516)
		(end 414.449514 -252.540516)
		(width 0.14478)
		(layer "In11.Cu")
		(net "M_L_CPU0_SA_CA<3>")
	)
	(segment
		(start 414.856168 -251.924312)
		(end 414.856168 -252.395736)
		(width 0.14478)
		(layer "In11.Cu")
		(net "M_L_CPU0_SA_CA<3>")
	)
	(segment
		(start 413.60852 -252.540516)
		(end 413.346646 -252.540516)
		(width 0.14478)
		(layer "In11.Cu")
		(net "M_L_CPU0_SA_CA<3>")
	)
	(segment
		(start 415.407602 -251.924312)
		(end 415.262822 -251.779532)
		(width 0.14478)
		(layer "In11.Cu")
		(net "M_L_CPU0_SA_CA<3>")
	)
	(segment
		(start 415.000948 -251.779532)
		(end 414.856168 -251.924312)
		(width 0.14478)
		(layer "In11.Cu")
		(net "M_L_CPU0_SA_CA<3>")
	)
	(segment
		(start 450.088 -250.03506)
		(end 449.663058 -250.460002)
		(width 0.14478)
		(layer "In11.Cu")
		(net "M_L_CPU0_SA_CA<3>")
	)
	(arc
		(start 392.80211 -253.881636)
		(mid 392.615166 -253.831381)
		(end 392.428222 -253.881636)
		(width 0.0889)
		(layer "In11.Cu")
		(net "M_L_CPU0_SA_CA<3>")
	)
	(arc
		(start 389.033512 -253.87681)
		(mid 388.850004 -253.831316)
		(end 388.667752 -253.881636)
		(width 0.0889)
		(layer "In11.Cu")
		(net "M_L_CPU0_SA_CA<3>")
	)
	(arc
		(start 386.787898 -253.881636)
		(mid 386.504942 -253.957813)
		(end 386.221986 -253.881636)
		(width 0.0889)
		(layer "In11.Cu")
		(net "M_L_CPU0_SA_CA<3>")
	)
	(arc
		(start 387.161786 -253.881636)
		(mid 386.974842 -253.831381)
		(end 386.787898 -253.881636)
		(width 0.0889)
		(layer "In11.Cu")
		(net "M_L_CPU0_SA_CA<3>")
	)
	(arc
		(start 390.921748 -253.881636)
		(mid 390.734804 -253.831381)
		(end 390.54786 -253.881636)
		(width 0.0889)
		(layer "In11.Cu")
		(net "M_L_CPU0_SA_CA<3>")
	)
	(arc
		(start 386.221986 -253.881636)
		(mid 386.065548 -253.832665)
		(end 385.903216 -253.855474)
		(width 0.0889)
		(layer "In11.Cu")
		(net "M_L_CPU0_SA_CA<3>")
	)
	(arc
		(start 389.607806 -253.881636)
		(mid 389.32485 -253.957813)
		(end 389.041894 -253.881636)
		(width 0.0889)
		(layer "In11.Cu")
		(net "M_L_CPU0_SA_CA<3>")
	)
	(arc
		(start 391.862056 -253.881636)
		(mid 391.674858 -253.831254)
		(end 391.48766 -253.881636)
		(width 0.0889)
		(layer "In11.Cu")
		(net "M_L_CPU0_SA_CA<3>")
	)
	(arc
		(start 387.727698 -253.881636)
		(mid 387.444742 -253.957813)
		(end 387.161786 -253.881636)
		(width 0.0889)
		(layer "In11.Cu")
		(net "M_L_CPU0_SA_CA<3>")
	)
	(arc
		(start 388.093458 -253.87681)
		(mid 387.90995 -253.831316)
		(end 387.727698 -253.881636)
		(width 0.0889)
		(layer "In11.Cu")
		(net "M_L_CPU0_SA_CA<3>")
	)
	(arc
		(start 388.667752 -253.881636)
		(mid 388.384796 -253.957813)
		(end 388.10184 -253.881636)
		(width 0.0889)
		(layer "In11.Cu")
		(net "M_L_CPU0_SA_CA<3>")
	)
	(arc
		(start 393.084812 -253.957582)
		(mid 392.938437 -253.938303)
		(end 392.80211 -253.881636)
		(width 0.0889)
		(layer "In11.Cu")
		(net "M_L_CPU0_SA_CA<3>")
	)
	(arc
		(start 392.417808 -253.887732)
		(mid 392.139122 -253.957952)
		(end 391.862056 -253.881636)
		(width 0.0889)
		(layer "In11.Cu")
		(net "M_L_CPU0_SA_CA<3>")
	)
	(arc
		(start 390.54786 -253.881636)
		(mid 390.264904 -253.957813)
		(end 389.981948 -253.881636)
		(width 0.0889)
		(layer "In11.Cu")
		(net "M_L_CPU0_SA_CA<3>")
	)
	(arc
		(start 391.48766 -253.881636)
		(mid 391.204704 -253.957813)
		(end 390.921748 -253.881636)
		(width 0.0889)
		(layer "In11.Cu")
		(net "M_L_CPU0_SA_CA<3>")
	)
	(arc
		(start 389.981948 -253.881636)
		(mid 389.799697 -253.831286)
		(end 389.616188 -253.87681)
		(width 0.0889)
		(layer "In11.Cu")
		(net "M_L_CPU0_SA_CA<3>")
	)
	(segment
		(start 385.098036 -253.660148)
		(end 385.564888 -253.39421)
		(width 0.10668)
		(layer "F.Cu")
		(net "M_L_CPU0_SA_CA<2>")
	)
	(segment
		(start 392.323828 -253.721616)
		(end 392.33221 -253.71679)
		(width 0.0889)
		(layer "In11.Cu")
		(net "M_L_CPU0_SA_CA<2>")
	)
	(segment
		(start 393.084812 -253.767082)
		(end 394.884148 -253.767082)
		(width 0.0889)
		(layer "In11.Cu")
		(net "M_L_CPU0_SA_CA<2>")
	)
	(segment
		(start 399.381726 -252.87986)
		(end 410.558996 -252.87986)
		(width 0.14478)
		(layer "In11.Cu")
		(net "M_L_CPU0_SA_CA<2>")
	)
	(segment
		(start 395.39545 -254.278384)
		(end 395.713712 -254.278384)
		(width 0.0889)
		(layer "In11.Cu")
		(net "M_L_CPU0_SA_CA<2>")
	)
	(segment
		(start 387.257798 -253.71679)
		(end 387.26618 -253.721616)
		(width 0.0889)
		(layer "In11.Cu")
		(net "M_L_CPU0_SA_CA<2>")
	)
	(segment
		(start 391.391902 -253.71679)
		(end 391.402316 -253.710694)
		(width 0.0889)
		(layer "In11.Cu")
		(net "M_L_CPU0_SA_CA<2>")
	)
	(segment
		(start 397.983202 -254.278384)
		(end 399.381726 -252.87986)
		(width 0.14478)
		(layer "In11.Cu")
		(net "M_L_CPU0_SA_CA<2>")
	)
	(segment
		(start 388.197852 -253.71679)
		(end 388.206234 -253.721616)
		(width 0.0889)
		(layer "In11.Cu")
		(net "M_L_CPU0_SA_CA<2>")
	)
	(segment
		(start 392.887454 -253.710694)
		(end 392.897868 -253.71679)
		(width 0.0889)
		(layer "In11.Cu")
		(net "M_L_CPU0_SA_CA<2>")
	)
	(segment
		(start 395.713712 -254.278384)
		(end 397.983202 -254.278384)
		(width 0.14478)
		(layer "In11.Cu")
		(net "M_L_CPU0_SA_CA<2>")
	)
	(segment
		(start 410.558996 -252.87986)
		(end 412.128716 -251.31014)
		(width 0.14478)
		(layer "In11.Cu")
		(net "M_L_CPU0_SA_CA<2>")
	)
	(segment
		(start 453.763126 -249.610118)
		(end 454.188068 -249.185176)
		(width 0.14478)
		(layer "In11.Cu")
		(net "M_L_CPU0_SA_CA<2>")
	)
	(segment
		(start 412.128716 -251.31014)
		(end 443.832234 -251.31014)
		(width 0.14478)
		(layer "In11.Cu")
		(net "M_L_CPU0_SA_CA<2>")
	)
	(segment
		(start 443.832234 -251.31014)
		(end 445.532256 -249.610118)
		(width 0.14478)
		(layer "In11.Cu")
		(net "M_L_CPU0_SA_CA<2>")
	)
	(segment
		(start 394.884148 -253.767082)
		(end 395.39545 -254.278384)
		(width 0.0889)
		(layer "In11.Cu")
		(net "M_L_CPU0_SA_CA<2>")
	)
	(segment
		(start 385.718812 -253.65964)
		(end 385.814824 -253.68504)
		(width 0.0889)
		(layer "In11.Cu")
		(net "M_L_CPU0_SA_CA<2>")
	)
	(segment
		(start 445.532256 -249.610118)
		(end 453.763126 -249.610118)
		(width 0.14478)
		(layer "In11.Cu")
		(net "M_L_CPU0_SA_CA<2>")
	)
	(segment
		(start 390.443466 -253.721616)
		(end 390.451848 -253.71679)
		(width 0.0889)
		(layer "In11.Cu")
		(net "M_L_CPU0_SA_CA<2>")
	)
	(segment
		(start 391.01776 -253.71679)
		(end 391.026142 -253.721616)
		(width 0.0889)
		(layer "In11.Cu")
		(net "M_L_CPU0_SA_CA<2>")
	)
	(segment
		(start 385.564888 -253.39421)
		(end 385.718812 -253.65964)
		(width 0.0889)
		(layer "In11.Cu")
		(net "M_L_CPU0_SA_CA<2>")
	)
	(segment
		(start 386.683504 -253.721616)
		(end 386.691886 -253.71679)
		(width 0.0889)
		(layer "In11.Cu")
		(net "M_L_CPU0_SA_CA<2>")
	)
	(arc
		(start 387.63194 -253.71679)
		(mid 387.914896 -253.640613)
		(end 388.197852 -253.71679)
		(width 0.0889)
		(layer "In11.Cu")
		(net "M_L_CPU0_SA_CA<2>")
	)
	(arc
		(start 391.026142 -253.721616)
		(mid 391.20965 -253.76711)
		(end 391.391902 -253.71679)
		(width 0.0889)
		(layer "In11.Cu")
		(net "M_L_CPU0_SA_CA<2>")
	)
	(arc
		(start 386.317744 -253.71679)
		(mid 386.499995 -253.76714)
		(end 386.683504 -253.721616)
		(width 0.0889)
		(layer "In11.Cu")
		(net "M_L_CPU0_SA_CA<2>")
	)
	(arc
		(start 391.958068 -253.71679)
		(mid 392.140319 -253.76714)
		(end 392.323828 -253.721616)
		(width 0.0889)
		(layer "In11.Cu")
		(net "M_L_CPU0_SA_CA<2>")
	)
	(arc
		(start 392.897868 -253.71679)
		(mid 392.988017 -253.754287)
		(end 393.084812 -253.767082)
		(width 0.0889)
		(layer "In11.Cu")
		(net "M_L_CPU0_SA_CA<2>")
	)
	(arc
		(start 392.33221 -253.71679)
		(mid 392.609023 -253.640647)
		(end 392.887454 -253.710694)
		(width 0.0889)
		(layer "In11.Cu")
		(net "M_L_CPU0_SA_CA<2>")
	)
	(arc
		(start 390.451848 -253.71679)
		(mid 390.734804 -253.640613)
		(end 391.01776 -253.71679)
		(width 0.0889)
		(layer "In11.Cu")
		(net "M_L_CPU0_SA_CA<2>")
	)
	(arc
		(start 389.511794 -253.71679)
		(mid 389.79475 -253.640613)
		(end 390.077706 -253.71679)
		(width 0.0889)
		(layer "In11.Cu")
		(net "M_L_CPU0_SA_CA<2>")
	)
	(arc
		(start 388.206234 -253.721616)
		(mid 388.389742 -253.76711)
		(end 388.571994 -253.71679)
		(width 0.0889)
		(layer "In11.Cu")
		(net "M_L_CPU0_SA_CA<2>")
	)
	(arc
		(start 390.077706 -253.71679)
		(mid 390.259957 -253.76714)
		(end 390.443466 -253.721616)
		(width 0.0889)
		(layer "In11.Cu")
		(net "M_L_CPU0_SA_CA<2>")
	)
	(arc
		(start 386.691886 -253.71679)
		(mid 386.974842 -253.640613)
		(end 387.257798 -253.71679)
		(width 0.0889)
		(layer "In11.Cu")
		(net "M_L_CPU0_SA_CA<2>")
	)
	(arc
		(start 388.571994 -253.71679)
		(mid 388.85495 -253.640613)
		(end 389.137906 -253.71679)
		(width 0.0889)
		(layer "In11.Cu")
		(net "M_L_CPU0_SA_CA<2>")
	)
	(arc
		(start 391.402316 -253.710694)
		(mid 391.681002 -253.640474)
		(end 391.958068 -253.71679)
		(width 0.0889)
		(layer "In11.Cu")
		(net "M_L_CPU0_SA_CA<2>")
	)
	(arc
		(start 389.137906 -253.71679)
		(mid 389.32485 -253.767045)
		(end 389.511794 -253.71679)
		(width 0.0889)
		(layer "In11.Cu")
		(net "M_L_CPU0_SA_CA<2>")
	)
	(arc
		(start 387.26618 -253.721616)
		(mid 387.449688 -253.76711)
		(end 387.63194 -253.71679)
		(width 0.0889)
		(layer "In11.Cu")
		(net "M_L_CPU0_SA_CA<2>")
	)
	(arc
		(start 385.814824 -253.68504)
		(mid 386.070032 -253.641563)
		(end 386.317744 -253.71679)
		(width 0.0889)
		(layer "In11.Cu")
		(net "M_L_CPU0_SA_CA<2>")
	)
	(segment
		(start 386.97789 -253.660148)
		(end 387.444742 -253.39421)
		(width 0.10668)
		(layer "F.Cu")
		(net "M_L_CPU0_SA_CA<1>")
	)
	(segment
		(start 387.290818 -253.12878)
		(end 387.444742 -253.39421)
		(width 0.0889)
		(layer "In11.Cu")
		(net "M_L_CPU0_SA_CA<1>")
	)
	(segment
		(start 448.376548 -249.154696)
		(end 448.114674 -249.154696)
		(width 0.14478)
		(layer "In11.Cu")
		(net "M_L_CPU0_SA_CA<1>")
	)
	(segment
		(start 441.245244 -250.075192)
		(end 441.100464 -250.219972)
		(width 0.14478)
		(layer "In11.Cu")
		(net "M_L_CPU0_SA_CA<1>")
	)
	(segment
		(start 447.41846 -248.615454)
		(end 447.27368 -248.760234)
		(width 0.14478)
		(layer "In11.Cu")
		(net "M_L_CPU0_SA_CA<1>")
	)
	(segment
		(start 395.730984 -253.823724)
		(end 395.32433 -253.823724)
		(width 0.0889)
		(layer "In11.Cu")
		(net "M_L_CPU0_SA_CA<1>")
	)
	(segment
		(start 440.955684 -250.844812)
		(end 440.69381 -250.844812)
		(width 0.14478)
		(layer "In11.Cu")
		(net "M_L_CPU0_SA_CA<1>")
	)
	(segment
		(start 392.34872 -253.082298)
		(end 392.330686 -253.07163)
		(width 0.0889)
		(layer "In11.Cu")
		(net "M_L_CPU0_SA_CA<1>")
	)
	(segment
		(start 449.217542 -248.760234)
		(end 449.072762 -248.615454)
		(width 0.14478)
		(layer "In11.Cu")
		(net "M_L_CPU0_SA_CA<1>")
	)
	(segment
		(start 440.40425 -250.075192)
		(end 440.142376 -250.075192)
		(width 0.14478)
		(layer "In11.Cu")
		(net "M_L_CPU0_SA_CA<1>")
	)
	(segment
		(start 448.666108 -248.365772)
		(end 448.521328 -248.510552)
		(width 0.14478)
		(layer "In11.Cu")
		(net "M_L_CPU0_SA_CA<1>")
	)
	(segment
		(start 447.969894 -248.510552)
		(end 447.825114 -248.365772)
		(width 0.14478)
		(layer "In11.Cu")
		(net "M_L_CPU0_SA_CA<1>")
	)
	(segment
		(start 445.604392 -248.760234)
		(end 443.904624 -250.460002)
		(width 0.14478)
		(layer "In11.Cu")
		(net "M_L_CPU0_SA_CA<1>")
	)
	(segment
		(start 394.232638 -253.415292)
		(end 393.838176 -253.02083)
		(width 0.0889)
		(layer "In11.Cu")
		(net "M_L_CPU0_SA_CA<1>")
	)
	(segment
		(start 447.41846 -248.510552)
		(end 447.41846 -248.615454)
		(width 0.14478)
		(layer "In11.Cu")
		(net "M_L_CPU0_SA_CA<1>")
	)
	(segment
		(start 441.796678 -250.460002)
		(end 441.651898 -250.315222)
		(width 0.14478)
		(layer "In11.Cu")
		(net "M_L_CPU0_SA_CA<1>")
	)
	(segment
		(start 391.970768 -253.06401)
		(end 391.957052 -253.071884)
		(width 0.0889)
		(layer "In11.Cu")
		(net "M_L_CPU0_SA_CA<1>")
	)
	(segment
		(start 387.31317 -253.045468)
		(end 387.290818 -253.12878)
		(width 0.0889)
		(layer "In11.Cu")
		(net "M_L_CPU0_SA_CA<1>")
	)
	(segment
		(start 447.27368 -248.760234)
		(end 445.604392 -248.760234)
		(width 0.14478)
		(layer "In11.Cu")
		(net "M_L_CPU0_SA_CA<1>")
	)
	(segment
		(start 390.451848 -253.07163)
		(end 390.443466 -253.066804)
		(width 0.0889)
		(layer "In11.Cu")
		(net "M_L_CPU0_SA_CA<1>")
	)
	(segment
		(start 441.100464 -250.700032)
		(end 440.955684 -250.844812)
		(width 0.14478)
		(layer "In11.Cu")
		(net "M_L_CPU0_SA_CA<1>")
	)
	(segment
		(start 439.997596 -250.315222)
		(end 439.852816 -250.460002)
		(width 0.14478)
		(layer "In11.Cu")
		(net "M_L_CPU0_SA_CA<1>")
	)
	(segment
		(start 391.026142 -253.066804)
		(end 391.01776 -253.07163)
		(width 0.0889)
		(layer "In11.Cu")
		(net "M_L_CPU0_SA_CA<1>")
	)
	(segment
		(start 440.142376 -250.075192)
		(end 439.997596 -250.219972)
		(width 0.14478)
		(layer "In11.Cu")
		(net "M_L_CPU0_SA_CA<1>")
	)
	(segment
		(start 447.825114 -248.365772)
		(end 447.56324 -248.365772)
		(width 0.14478)
		(layer "In11.Cu")
		(net "M_L_CPU0_SA_CA<1>")
	)
	(segment
		(start 449.072762 -248.510552)
		(end 448.927982 -248.365772)
		(width 0.14478)
		(layer "In11.Cu")
		(net "M_L_CPU0_SA_CA<1>")
	)
	(segment
		(start 448.114674 -249.154696)
		(end 447.969894 -249.009916)
		(width 0.14478)
		(layer "In11.Cu")
		(net "M_L_CPU0_SA_CA<1>")
	)
	(segment
		(start 449.072762 -248.615454)
		(end 449.072762 -248.510552)
		(width 0.14478)
		(layer "In11.Cu")
		(net "M_L_CPU0_SA_CA<1>")
	)
	(segment
		(start 448.521328 -249.009916)
		(end 448.376548 -249.154696)
		(width 0.14478)
		(layer "In11.Cu")
		(net "M_L_CPU0_SA_CA<1>")
	)
	(segment
		(start 448.927982 -248.365772)
		(end 448.666108 -248.365772)
		(width 0.14478)
		(layer "In11.Cu")
		(net "M_L_CPU0_SA_CA<1>")
	)
	(segment
		(start 448.521328 -248.510552)
		(end 448.521328 -249.009916)
		(width 0.14478)
		(layer "In11.Cu")
		(net "M_L_CPU0_SA_CA<1>")
	)
	(segment
		(start 449.662804 -248.760234)
		(end 449.217542 -248.760234)
		(width 0.14478)
		(layer "In11.Cu")
		(net "M_L_CPU0_SA_CA<1>")
	)
	(segment
		(start 440.54903 -250.219972)
		(end 440.40425 -250.075192)
		(width 0.14478)
		(layer "In11.Cu")
		(net "M_L_CPU0_SA_CA<1>")
	)
	(segment
		(start 393.838176 -253.02083)
		(end 393.084812 -253.02083)
		(width 0.0889)
		(layer "In11.Cu")
		(net "M_L_CPU0_SA_CA<1>")
	)
	(segment
		(start 439.997596 -250.219972)
		(end 439.997596 -250.315222)
		(width 0.14478)
		(layer "In11.Cu")
		(net "M_L_CPU0_SA_CA<1>")
	)
	(segment
		(start 441.651898 -250.219972)
		(end 441.507118 -250.075192)
		(width 0.14478)
		(layer "In11.Cu")
		(net "M_L_CPU0_SA_CA<1>")
	)
	(segment
		(start 410.236416 -252.4252)
		(end 399.193258 -252.4252)
		(width 0.14478)
		(layer "In11.Cu")
		(net "M_L_CPU0_SA_CA<1>")
	)
	(segment
		(start 450.088 -248.335038)
		(end 449.662804 -248.760234)
		(width 0.14478)
		(layer "In11.Cu")
		(net "M_L_CPU0_SA_CA<1>")
	)
	(segment
		(start 447.56324 -248.365772)
		(end 447.41846 -248.510552)
		(width 0.14478)
		(layer "In11.Cu")
		(net "M_L_CPU0_SA_CA<1>")
	)
	(segment
		(start 399.193258 -252.4252)
		(end 397.794734 -253.823724)
		(width 0.14478)
		(layer "In11.Cu")
		(net "M_L_CPU0_SA_CA<1>")
	)
	(segment
		(start 397.794734 -253.823724)
		(end 395.730984 -253.823724)
		(width 0.14478)
		(layer "In11.Cu")
		(net "M_L_CPU0_SA_CA<1>")
	)
	(segment
		(start 441.507118 -250.075192)
		(end 441.245244 -250.075192)
		(width 0.14478)
		(layer "In11.Cu")
		(net "M_L_CPU0_SA_CA<1>")
	)
	(segment
		(start 443.904624 -250.460002)
		(end 441.796678 -250.460002)
		(width 0.14478)
		(layer "In11.Cu")
		(net "M_L_CPU0_SA_CA<1>")
	)
	(segment
		(start 440.54903 -250.700032)
		(end 440.54903 -250.219972)
		(width 0.14478)
		(layer "In11.Cu")
		(net "M_L_CPU0_SA_CA<1>")
	)
	(segment
		(start 440.69381 -250.844812)
		(end 440.54903 -250.700032)
		(width 0.14478)
		(layer "In11.Cu")
		(net "M_L_CPU0_SA_CA<1>")
	)
	(segment
		(start 441.100464 -250.219972)
		(end 441.100464 -250.700032)
		(width 0.14478)
		(layer "In11.Cu")
		(net "M_L_CPU0_SA_CA<1>")
	)
	(segment
		(start 395.32433 -253.823724)
		(end 394.915898 -253.415292)
		(width 0.0889)
		(layer "In11.Cu")
		(net "M_L_CPU0_SA_CA<1>")
	)
	(segment
		(start 412.201614 -250.460002)
		(end 410.236416 -252.4252)
		(width 0.14478)
		(layer "In11.Cu")
		(net "M_L_CPU0_SA_CA<1>")
	)
	(segment
		(start 389.511794 -253.07163)
		(end 389.503412 -253.066804)
		(width 0.0889)
		(layer "In11.Cu")
		(net "M_L_CPU0_SA_CA<1>")
	)
	(segment
		(start 391.957052 -253.071884)
		(end 391.945114 -253.078742)
		(width 0.0889)
		(layer "In11.Cu")
		(net "M_L_CPU0_SA_CA<1>")
	)
	(segment
		(start 441.651898 -250.315222)
		(end 441.651898 -250.219972)
		(width 0.14478)
		(layer "In11.Cu")
		(net "M_L_CPU0_SA_CA<1>")
	)
	(segment
		(start 439.852816 -250.460002)
		(end 412.201614 -250.460002)
		(width 0.14478)
		(layer "In11.Cu")
		(net "M_L_CPU0_SA_CA<1>")
	)
	(segment
		(start 447.969894 -249.009916)
		(end 447.969894 -248.510552)
		(width 0.14478)
		(layer "In11.Cu")
		(net "M_L_CPU0_SA_CA<1>")
	)
	(segment
		(start 394.915898 -253.415292)
		(end 394.232638 -253.415292)
		(width 0.0889)
		(layer "In11.Cu")
		(net "M_L_CPU0_SA_CA<1>")
	)
	(arc
		(start 393.084812 -253.02083)
		(mid 392.987723 -253.03382)
		(end 392.89736 -253.07163)
		(width 0.0889)
		(layer "In11.Cu")
		(net "M_L_CPU0_SA_CA<1>")
	)
	(arc
		(start 390.443466 -253.066804)
		(mid 390.259958 -253.02131)
		(end 390.077706 -253.07163)
		(width 0.0889)
		(layer "In11.Cu")
		(net "M_L_CPU0_SA_CA<1>")
	)
	(arc
		(start 391.945114 -253.078742)
		(mid 391.66758 -253.147723)
		(end 391.391902 -253.07163)
		(width 0.0889)
		(layer "In11.Cu")
		(net "M_L_CPU0_SA_CA<1>")
	)
	(arc
		(start 388.57174 -253.07163)
		(mid 388.384796 -253.021375)
		(end 388.197852 -253.07163)
		(width 0.0889)
		(layer "In11.Cu")
		(net "M_L_CPU0_SA_CA<1>")
	)
	(arc
		(start 387.63194 -253.07163)
		(mid 387.475502 -253.022659)
		(end 387.31317 -253.045468)
		(width 0.0889)
		(layer "In11.Cu")
		(net "M_L_CPU0_SA_CA<1>")
	)
	(arc
		(start 388.197852 -253.07163)
		(mid 387.914896 -253.147807)
		(end 387.63194 -253.07163)
		(width 0.0889)
		(layer "In11.Cu")
		(net "M_L_CPU0_SA_CA<1>")
	)
	(arc
		(start 389.503412 -253.066804)
		(mid 389.319904 -253.02131)
		(end 389.137652 -253.07163)
		(width 0.0889)
		(layer "In11.Cu")
		(net "M_L_CPU0_SA_CA<1>")
	)
	(arc
		(start 389.137652 -253.07163)
		(mid 388.854696 -253.147807)
		(end 388.57174 -253.07163)
		(width 0.0889)
		(layer "In11.Cu")
		(net "M_L_CPU0_SA_CA<1>")
	)
	(arc
		(start 390.077706 -253.07163)
		(mid 389.79475 -253.147807)
		(end 389.511794 -253.07163)
		(width 0.0889)
		(layer "In11.Cu")
		(net "M_L_CPU0_SA_CA<1>")
	)
	(arc
		(start 391.391902 -253.07163)
		(mid 391.209651 -253.02128)
		(end 391.026142 -253.066804)
		(width 0.0889)
		(layer "In11.Cu")
		(net "M_L_CPU0_SA_CA<1>")
	)
	(arc
		(start 391.01776 -253.07163)
		(mid 390.734804 -253.147807)
		(end 390.451848 -253.07163)
		(width 0.0889)
		(layer "In11.Cu")
		(net "M_L_CPU0_SA_CA<1>")
	)
	(arc
		(start 392.330686 -253.07163)
		(mid 392.151699 -253.02146)
		(end 391.970768 -253.06401)
		(width 0.0889)
		(layer "In11.Cu")
		(net "M_L_CPU0_SA_CA<1>")
	)
	(arc
		(start 392.89736 -253.07163)
		(mid 392.624416 -253.14821)
		(end 392.34872 -253.082298)
		(width 0.0889)
		(layer "In11.Cu")
		(net "M_L_CPU0_SA_CA<1>")
	)
	(segment
		(start 386.50799 -252.850142)
		(end 386.974842 -252.584204)
		(width 0.10668)
		(layer "F.Cu")
		(net "M_L_CPU0_SA_CA<0>")
	)
	(segment
		(start 386.974842 -252.584204)
		(end 387.128766 -252.849634)
		(width 0.0889)
		(layer "In11.Cu")
		(net "M_L_CPU0_SA_CA<0>")
	)
	(segment
		(start 388.093458 -252.91161)
		(end 388.10184 -252.906784)
		(width 0.0889)
		(layer "In11.Cu")
		(net "M_L_CPU0_SA_CA<0>")
	)
	(segment
		(start 399.00479 -251.97054)
		(end 410.047948 -251.97054)
		(width 0.14478)
		(layer "In11.Cu")
		(net "M_L_CPU0_SA_CA<0>")
	)
	(segment
		(start 410.047948 -251.97054)
		(end 412.40837 -249.610118)
		(width 0.14478)
		(layer "In11.Cu")
		(net "M_L_CPU0_SA_CA<0>")
	)
	(segment
		(start 453.763126 -247.910096)
		(end 454.188068 -247.485154)
		(width 0.14478)
		(layer "In11.Cu")
		(net "M_L_CPU0_SA_CA<0>")
	)
	(segment
		(start 412.40837 -249.610118)
		(end 443.89167 -249.610118)
		(width 0.14478)
		(layer "In11.Cu")
		(net "M_L_CPU0_SA_CA<0>")
	)
	(segment
		(start 391.845292 -252.915928)
		(end 391.861548 -252.90653)
		(width 0.0889)
		(layer "In11.Cu")
		(net "M_L_CPU0_SA_CA<0>")
	)
	(segment
		(start 387.128766 -252.849634)
		(end 387.224778 -252.875034)
		(width 0.0889)
		(layer "In11.Cu")
		(net "M_L_CPU0_SA_CA<0>")
	)
	(segment
		(start 393.084812 -252.83033)
		(end 393.91717 -252.83033)
		(width 0.0889)
		(layer "In11.Cu")
		(net "M_L_CPU0_SA_CA<0>")
	)
	(segment
		(start 395.719554 -253.369064)
		(end 397.606266 -253.369064)
		(width 0.14478)
		(layer "In11.Cu")
		(net "M_L_CPU0_SA_CA<0>")
	)
	(segment
		(start 445.591692 -247.910096)
		(end 453.763126 -247.910096)
		(width 0.14478)
		(layer "In11.Cu")
		(net "M_L_CPU0_SA_CA<0>")
	)
	(segment
		(start 388.667752 -252.906784)
		(end 388.676134 -252.91161)
		(width 0.0889)
		(layer "In11.Cu")
		(net "M_L_CPU0_SA_CA<0>")
	)
	(segment
		(start 443.89167 -249.610118)
		(end 445.591692 -247.910096)
		(width 0.14478)
		(layer "In11.Cu")
		(net "M_L_CPU0_SA_CA<0>")
	)
	(segment
		(start 393.91717 -252.83033)
		(end 394.311632 -253.224792)
		(width 0.0889)
		(layer "In11.Cu")
		(net "M_L_CPU0_SA_CA<0>")
	)
	(segment
		(start 395.30655 -253.369064)
		(end 395.719554 -253.369064)
		(width 0.0889)
		(layer "In11.Cu")
		(net "M_L_CPU0_SA_CA<0>")
	)
	(segment
		(start 391.861548 -252.90653)
		(end 391.873486 -252.899672)
		(width 0.0889)
		(layer "In11.Cu")
		(net "M_L_CPU0_SA_CA<0>")
	)
	(segment
		(start 392.426698 -252.906784)
		(end 392.438382 -252.913642)
		(width 0.0889)
		(layer "In11.Cu")
		(net "M_L_CPU0_SA_CA<0>")
	)
	(segment
		(start 395.162278 -253.224792)
		(end 395.30655 -253.369064)
		(width 0.0889)
		(layer "In11.Cu")
		(net "M_L_CPU0_SA_CA<0>")
	)
	(segment
		(start 394.311632 -253.224792)
		(end 395.162278 -253.224792)
		(width 0.0889)
		(layer "In11.Cu")
		(net "M_L_CPU0_SA_CA<0>")
	)
	(segment
		(start 389.607806 -252.906784)
		(end 389.616188 -252.91161)
		(width 0.0889)
		(layer "In11.Cu")
		(net "M_L_CPU0_SA_CA<0>")
	)
	(segment
		(start 397.606266 -253.369064)
		(end 399.00479 -251.97054)
		(width 0.14478)
		(layer "In11.Cu")
		(net "M_L_CPU0_SA_CA<0>")
	)
	(arc
		(start 389.616188 -252.91161)
		(mid 389.799696 -252.957104)
		(end 389.981948 -252.906784)
		(width 0.0889)
		(layer "In11.Cu")
		(net "M_L_CPU0_SA_CA<0>")
	)
	(arc
		(start 387.224778 -252.875034)
		(mid 387.479986 -252.831557)
		(end 387.727698 -252.906784)
		(width 0.0889)
		(layer "In11.Cu")
		(net "M_L_CPU0_SA_CA<0>")
	)
	(arc
		(start 390.921748 -252.906784)
		(mid 391.204704 -252.830607)
		(end 391.48766 -252.906784)
		(width 0.0889)
		(layer "In11.Cu")
		(net "M_L_CPU0_SA_CA<0>")
	)
	(arc
		(start 392.438382 -252.913642)
		(mid 392.620637 -252.957295)
		(end 392.801094 -252.906784)
		(width 0.0889)
		(layer "In11.Cu")
		(net "M_L_CPU0_SA_CA<0>")
	)
	(arc
		(start 392.801094 -252.906784)
		(mid 392.937887 -252.849762)
		(end 393.084812 -252.83033)
		(width 0.0889)
		(layer "In11.Cu")
		(net "M_L_CPU0_SA_CA<0>")
	)
	(arc
		(start 388.676134 -252.91161)
		(mid 388.859642 -252.957104)
		(end 389.041894 -252.906784)
		(width 0.0889)
		(layer "In11.Cu")
		(net "M_L_CPU0_SA_CA<0>")
	)
	(arc
		(start 391.873486 -252.899672)
		(mid 392.15102 -252.830691)
		(end 392.426698 -252.906784)
		(width 0.0889)
		(layer "In11.Cu")
		(net "M_L_CPU0_SA_CA<0>")
	)
	(arc
		(start 389.981948 -252.906784)
		(mid 390.264904 -252.830607)
		(end 390.54786 -252.906784)
		(width 0.0889)
		(layer "In11.Cu")
		(net "M_L_CPU0_SA_CA<0>")
	)
	(arc
		(start 388.10184 -252.906784)
		(mid 388.384796 -252.830607)
		(end 388.667752 -252.906784)
		(width 0.0889)
		(layer "In11.Cu")
		(net "M_L_CPU0_SA_CA<0>")
	)
	(arc
		(start 389.041894 -252.906784)
		(mid 389.32485 -252.830607)
		(end 389.607806 -252.906784)
		(width 0.0889)
		(layer "In11.Cu")
		(net "M_L_CPU0_SA_CA<0>")
	)
	(arc
		(start 390.54786 -252.906784)
		(mid 390.734804 -252.957039)
		(end 390.921748 -252.906784)
		(width 0.0889)
		(layer "In11.Cu")
		(net "M_L_CPU0_SA_CA<0>")
	)
	(arc
		(start 391.48766 -252.906784)
		(mid 391.66531 -252.957044)
		(end 391.845292 -252.915928)
		(width 0.0889)
		(layer "In11.Cu")
		(net "M_L_CPU0_SA_CA<0>")
	)
	(arc
		(start 387.727698 -252.906784)
		(mid 387.909949 -252.957134)
		(end 388.093458 -252.91161)
		(width 0.0889)
		(layer "In11.Cu")
		(net "M_L_CPU0_SA_CA<0>")
	)
	(segment
		(start 385.567936 -251.23013)
		(end 386.034788 -250.964192)
		(width 0.10668)
		(layer "F.Cu")
		(net "M_L_CPU0_RESET_N")
	)
	(segment
		(start 408.929078 -250.31573)
		(end 412.184596 -247.060212)
		(width 0.11684)
		(layer "In11.Cu")
		(net "M_L_CPU0_RESET_N")
	)
	(segment
		(start 412.184596 -247.060212)
		(end 443.590934 -247.060212)
		(width 0.11684)
		(layer "In11.Cu")
		(net "M_L_CPU0_RESET_N")
	)
	(segment
		(start 389.607806 -250.641612)
		(end 389.616188 -250.636786)
		(width 0.0889)
		(layer "In11.Cu")
		(net "M_L_CPU0_RESET_N")
	)
	(segment
		(start 392.793474 -250.636786)
		(end 392.801856 -250.641612)
		(width 0.0889)
		(layer "In11.Cu")
		(net "M_L_CPU0_RESET_N")
	)
	(segment
		(start 394.758418 -250.717812)
		(end 395.167358 -251.126752)
		(width 0.0889)
		(layer "In11.Cu")
		(net "M_L_CPU0_RESET_N")
	)
	(segment
		(start 395.44371 -251.700284)
		(end 395.708886 -251.700284)
		(width 0.0889)
		(layer "In11.Cu")
		(net "M_L_CPU0_RESET_N")
	)
	(segment
		(start 396.933928 -251.700284)
		(end 398.318482 -250.31573)
		(width 0.11684)
		(layer "In11.Cu")
		(net "M_L_CPU0_RESET_N")
	)
	(segment
		(start 398.318482 -250.31573)
		(end 408.929078 -250.31573)
		(width 0.11684)
		(layer "In11.Cu")
		(net "M_L_CPU0_RESET_N")
	)
	(segment
		(start 386.034788 -250.964192)
		(end 385.880864 -250.698762)
		(width 0.0889)
		(layer "In11.Cu")
		(net "M_L_CPU0_RESET_N")
	)
	(segment
		(start 449.662804 -245.36019)
		(end 450.088 -244.934994)
		(width 0.11684)
		(layer "In11.Cu")
		(net "M_L_CPU0_RESET_N")
	)
	(segment
		(start 445.290956 -245.36019)
		(end 449.662804 -245.36019)
		(width 0.11684)
		(layer "In11.Cu")
		(net "M_L_CPU0_RESET_N")
	)
	(segment
		(start 395.708886 -251.700284)
		(end 396.933928 -251.700284)
		(width 0.11684)
		(layer "In11.Cu")
		(net "M_L_CPU0_RESET_N")
	)
	(segment
		(start 395.167358 -251.126752)
		(end 395.167358 -251.423932)
		(width 0.0889)
		(layer "In11.Cu")
		(net "M_L_CPU0_RESET_N")
	)
	(segment
		(start 395.167358 -251.423932)
		(end 395.44371 -251.700284)
		(width 0.0889)
		(layer "In11.Cu")
		(net "M_L_CPU0_RESET_N")
	)
	(segment
		(start 443.590934 -247.060212)
		(end 445.290956 -245.36019)
		(width 0.11684)
		(layer "In11.Cu")
		(net "M_L_CPU0_RESET_N")
	)
	(segment
		(start 391.85342 -250.636786)
		(end 391.861802 -250.641612)
		(width 0.0889)
		(layer "In11.Cu")
		(net "M_L_CPU0_RESET_N")
	)
	(segment
		(start 385.880864 -250.698762)
		(end 385.903216 -250.61545)
		(width 0.0889)
		(layer "In11.Cu")
		(net "M_L_CPU0_RESET_N")
	)
	(segment
		(start 388.093458 -250.636786)
		(end 388.10184 -250.641612)
		(width 0.0889)
		(layer "In11.Cu")
		(net "M_L_CPU0_RESET_N")
	)
	(segment
		(start 389.033512 -250.636786)
		(end 389.041894 -250.641612)
		(width 0.0889)
		(layer "In11.Cu")
		(net "M_L_CPU0_RESET_N")
	)
	(segment
		(start 393.084812 -250.717812)
		(end 394.758418 -250.717812)
		(width 0.0889)
		(layer "In11.Cu")
		(net "M_L_CPU0_RESET_N")
	)
	(arc
		(start 385.903216 -250.61545)
		(mid 386.065548 -250.592632)
		(end 386.221986 -250.641612)
		(width 0.0889)
		(layer "In11.Cu")
		(net "M_L_CPU0_RESET_N")
	)
	(arc
		(start 392.801856 -250.641612)
		(mid 392.938292 -250.698437)
		(end 393.084812 -250.717812)
		(width 0.0889)
		(layer "In11.Cu")
		(net "M_L_CPU0_RESET_N")
	)
	(arc
		(start 388.10184 -250.641612)
		(mid 388.384796 -250.717789)
		(end 388.667752 -250.641612)
		(width 0.0889)
		(layer "In11.Cu")
		(net "M_L_CPU0_RESET_N")
	)
	(arc
		(start 391.48766 -250.641612)
		(mid 391.669911 -250.591262)
		(end 391.85342 -250.636786)
		(width 0.0889)
		(layer "In11.Cu")
		(net "M_L_CPU0_RESET_N")
	)
	(arc
		(start 392.427714 -250.641612)
		(mid 392.609965 -250.591262)
		(end 392.793474 -250.636786)
		(width 0.0889)
		(layer "In11.Cu")
		(net "M_L_CPU0_RESET_N")
	)
	(arc
		(start 390.921748 -250.641612)
		(mid 391.204704 -250.717789)
		(end 391.48766 -250.641612)
		(width 0.0889)
		(layer "In11.Cu")
		(net "M_L_CPU0_RESET_N")
	)
	(arc
		(start 388.667752 -250.641612)
		(mid 388.850003 -250.591262)
		(end 389.033512 -250.636786)
		(width 0.0889)
		(layer "In11.Cu")
		(net "M_L_CPU0_RESET_N")
	)
	(arc
		(start 391.861802 -250.641612)
		(mid 392.144758 -250.717789)
		(end 392.427714 -250.641612)
		(width 0.0889)
		(layer "In11.Cu")
		(net "M_L_CPU0_RESET_N")
	)
	(arc
		(start 390.54786 -250.641612)
		(mid 390.734804 -250.591357)
		(end 390.921748 -250.641612)
		(width 0.0889)
		(layer "In11.Cu")
		(net "M_L_CPU0_RESET_N")
	)
	(arc
		(start 389.981948 -250.641612)
		(mid 390.264904 -250.717789)
		(end 390.54786 -250.641612)
		(width 0.0889)
		(layer "In11.Cu")
		(net "M_L_CPU0_RESET_N")
	)
	(arc
		(start 386.221986 -250.641612)
		(mid 386.504942 -250.717789)
		(end 386.787898 -250.641612)
		(width 0.0889)
		(layer "In11.Cu")
		(net "M_L_CPU0_RESET_N")
	)
	(arc
		(start 387.161786 -250.641612)
		(mid 387.444742 -250.717789)
		(end 387.727698 -250.641612)
		(width 0.0889)
		(layer "In11.Cu")
		(net "M_L_CPU0_RESET_N")
	)
	(arc
		(start 387.727698 -250.641612)
		(mid 387.909949 -250.591262)
		(end 388.093458 -250.636786)
		(width 0.0889)
		(layer "In11.Cu")
		(net "M_L_CPU0_RESET_N")
	)
	(arc
		(start 389.616188 -250.636786)
		(mid 389.799696 -250.591292)
		(end 389.981948 -250.641612)
		(width 0.0889)
		(layer "In11.Cu")
		(net "M_L_CPU0_RESET_N")
	)
	(arc
		(start 389.041894 -250.641612)
		(mid 389.32485 -250.717789)
		(end 389.607806 -250.641612)
		(width 0.0889)
		(layer "In11.Cu")
		(net "M_L_CPU0_RESET_N")
	)
	(arc
		(start 386.787898 -250.641612)
		(mid 386.974842 -250.591357)
		(end 387.161786 -250.641612)
		(width 0.0889)
		(layer "In11.Cu")
		(net "M_L_CPU0_RESET_N")
	)
	(segment
		(start 386.50799 -256.090166)
		(end 386.974842 -255.824228)
		(width 0.14732)
		(layer "F.Cu")
		(net "M_L_CPU0_CLK_DP<0>")
	)
	(segment
		(start 406.693878 -256.356612)
		(end 407.91511 -256.356612)
		(width 0.16002)
		(layer "In11.Cu")
		(net "M_L_CPU0_CLK_DP<0>")
	)
	(segment
		(start 387.128766 -256.089658)
		(end 387.229604 -256.116328)
		(width 0.09525)
		(layer "In11.Cu")
		(net "M_L_CPU0_CLK_DP<0>")
	)
	(segment
		(start 411.503368 -256.356612)
		(end 447.250058 -256.356612)
		(width 0.16002)
		(layer "In11.Cu")
		(net "M_L_CPU0_CLK_DP<0>")
	)
	(segment
		(start 395.728698 -257.212084)
		(end 395.75232 -257.212084)
		(width 0.09525)
		(layer "In11.Cu")
		(net "M_L_CPU0_CLK_DP<0>")
	)
	(segment
		(start 399.199862 -257.212084)
		(end 400.598386 -255.81356)
		(width 0.16002)
		(layer "In11.Cu")
		(net "M_L_CPU0_CLK_DP<0>")
	)
	(segment
		(start 391.854944 -256.154174)
		(end 391.863326 -256.149348)
		(width 0.09525)
		(layer "In11.Cu")
		(net "M_L_CPU0_CLK_DP<0>")
	)
	(segment
		(start 410.556456 -257.845052)
		(end 411.00629 -257.845052)
		(width 0.16002)
		(layer "In11.Cu")
		(net "M_L_CPU0_CLK_DP<0>")
	)
	(segment
		(start 406.150826 -255.81356)
		(end 406.693878 -256.356612)
		(width 0.16002)
		(layer "In11.Cu")
		(net "M_L_CPU0_CLK_DP<0>")
	)
	(segment
		(start 411.00629 -257.845052)
		(end 411.16631 -257.685032)
		(width 0.16002)
		(layer "In11.Cu")
		(net "M_L_CPU0_CLK_DP<0>")
	)
	(segment
		(start 408.252168 -256.69367)
		(end 408.252168 -257.685032)
		(width 0.16002)
		(layer "In11.Cu")
		(net "M_L_CPU0_CLK_DP<0>")
	)
	(segment
		(start 392.407394 -256.138934)
		(end 392.425428 -256.149348)
		(width 0.09525)
		(layer "In11.Cu")
		(net "M_L_CPU0_CLK_DP<0>")
	)
	(segment
		(start 447.250058 -256.356612)
		(end 448.763898 -254.842772)
		(width 0.16002)
		(layer "In11.Cu")
		(net "M_L_CPU0_CLK_DP<0>")
	)
	(segment
		(start 393.340082 -256.134616)
		(end 393.365482 -256.149348)
		(width 0.09525)
		(layer "In11.Cu")
		(net "M_L_CPU0_CLK_DP<0>")
	)
	(segment
		(start 448.763898 -254.842772)
		(end 448.763898 -254.273812)
		(width 0.16002)
		(layer "In11.Cu")
		(net "M_L_CPU0_CLK_DP<0>")
	)
	(segment
		(start 395.75232 -257.212084)
		(end 399.199862 -257.212084)
		(width 0.16002)
		(layer "In11.Cu")
		(net "M_L_CPU0_CLK_DP<0>")
	)
	(segment
		(start 448.763898 -254.273812)
		(end 449.330318 -253.707392)
		(width 0.16002)
		(layer "In11.Cu")
		(net "M_L_CPU0_CLK_DP<0>")
	)
	(segment
		(start 389.035036 -256.154174)
		(end 389.043418 -256.149348)
		(width 0.09525)
		(layer "In11.Cu")
		(net "M_L_CPU0_CLK_DP<0>")
	)
	(segment
		(start 449.815712 -253.707392)
		(end 450.088 -253.435104)
		(width 0.16002)
		(layer "In11.Cu")
		(net "M_L_CPU0_CLK_DP<0>")
	)
	(segment
		(start 411.16631 -257.685032)
		(end 411.16631 -256.69367)
		(width 0.16002)
		(layer "In11.Cu")
		(net "M_L_CPU0_CLK_DP<0>")
	)
	(segment
		(start 408.412188 -257.845052)
		(end 408.862022 -257.845052)
		(width 0.16002)
		(layer "In11.Cu")
		(net "M_L_CPU0_CLK_DP<0>")
	)
	(segment
		(start 400.598386 -255.81356)
		(end 406.150826 -255.81356)
		(width 0.16002)
		(layer "In11.Cu")
		(net "M_L_CPU0_CLK_DP<0>")
	)
	(segment
		(start 409.3591 -256.356612)
		(end 410.059378 -256.356612)
		(width 0.16002)
		(layer "In11.Cu")
		(net "M_L_CPU0_CLK_DP<0>")
	)
	(segment
		(start 388.094982 -256.154174)
		(end 388.103364 -256.149348)
		(width 0.09525)
		(layer "In11.Cu")
		(net "M_L_CPU0_CLK_DP<0>")
	)
	(segment
		(start 408.252168 -257.685032)
		(end 408.412188 -257.845052)
		(width 0.16002)
		(layer "In11.Cu")
		(net "M_L_CPU0_CLK_DP<0>")
	)
	(segment
		(start 395.66977 -257.271012)
		(end 395.728698 -257.212084)
		(width 0.09525)
		(layer "In11.Cu")
		(net "M_L_CPU0_CLK_DP<0>")
	)
	(segment
		(start 449.330318 -253.707392)
		(end 449.815712 -253.707392)
		(width 0.16002)
		(layer "In11.Cu")
		(net "M_L_CPU0_CLK_DP<0>")
	)
	(segment
		(start 410.396436 -257.685032)
		(end 410.556456 -257.845052)
		(width 0.16002)
		(layer "In11.Cu")
		(net "M_L_CPU0_CLK_DP<0>")
	)
	(segment
		(start 409.022042 -257.685032)
		(end 409.022042 -256.69367)
		(width 0.16002)
		(layer "In11.Cu")
		(net "M_L_CPU0_CLK_DP<0>")
	)
	(segment
		(start 394.51407 -257.271012)
		(end 395.66977 -257.271012)
		(width 0.09525)
		(layer "In11.Cu")
		(net "M_L_CPU0_CLK_DP<0>")
	)
	(segment
		(start 386.974842 -255.824228)
		(end 387.128766 -256.089658)
		(width 0.09525)
		(layer "In11.Cu")
		(net "M_L_CPU0_CLK_DP<0>")
	)
	(segment
		(start 409.022042 -256.69367)
		(end 409.3591 -256.356612)
		(width 0.16002)
		(layer "In11.Cu")
		(net "M_L_CPU0_CLK_DP<0>")
	)
	(segment
		(start 407.91511 -256.356612)
		(end 408.252168 -256.69367)
		(width 0.16002)
		(layer "In11.Cu")
		(net "M_L_CPU0_CLK_DP<0>")
	)
	(segment
		(start 410.396436 -256.69367)
		(end 410.396436 -257.685032)
		(width 0.16002)
		(layer "In11.Cu")
		(net "M_L_CPU0_CLK_DP<0>")
	)
	(segment
		(start 411.16631 -256.69367)
		(end 411.503368 -256.356612)
		(width 0.16002)
		(layer "In11.Cu")
		(net "M_L_CPU0_CLK_DP<0>")
	)
	(segment
		(start 410.059378 -256.356612)
		(end 410.396436 -256.69367)
		(width 0.16002)
		(layer "In11.Cu")
		(net "M_L_CPU0_CLK_DP<0>")
	)
	(segment
		(start 393.481052 -256.237994)
		(end 394.51407 -257.271012)
		(width 0.09525)
		(layer "In11.Cu")
		(net "M_L_CPU0_CLK_DP<0>")
	)
	(segment
		(start 389.606282 -256.149348)
		(end 389.614664 -256.154174)
		(width 0.09525)
		(layer "In11.Cu")
		(net "M_L_CPU0_CLK_DP<0>")
	)
	(segment
		(start 408.862022 -257.845052)
		(end 409.022042 -257.685032)
		(width 0.16002)
		(layer "In11.Cu")
		(net "M_L_CPU0_CLK_DP<0>")
	)
	(segment
		(start 392.425428 -256.149348)
		(end 392.439906 -256.15773)
		(width 0.09525)
		(layer "In11.Cu")
		(net "M_L_CPU0_CLK_DP<0>")
	)
	(arc
		(start 392.439906 -256.15773)
		(mid 392.622338 -256.20017)
		(end 392.802618 -256.149348)
		(width 0.09525)
		(layer "In11.Cu")
		(net "M_L_CPU0_CLK_DP<0>")
	)
	(arc
		(start 389.614664 -256.154174)
		(mid 389.799696 -256.200088)
		(end 389.983472 -256.149348)
		(width 0.09525)
		(layer "In11.Cu")
		(net "M_L_CPU0_CLK_DP<0>")
	)
	(arc
		(start 388.103364 -256.149348)
		(mid 388.384796 -256.073593)
		(end 388.666228 -256.149348)
		(width 0.09525)
		(layer "In11.Cu")
		(net "M_L_CPU0_CLK_DP<0>")
	)
	(arc
		(start 390.546336 -256.149348)
		(mid 390.734804 -256.200025)
		(end 390.923272 -256.149348)
		(width 0.09525)
		(layer "In11.Cu")
		(net "M_L_CPU0_CLK_DP<0>")
	)
	(arc
		(start 387.249924 -256.108454)
		(mid 387.492636 -256.075571)
		(end 387.726174 -256.149348)
		(width 0.09525)
		(layer "In11.Cu")
		(net "M_L_CPU0_CLK_DP<0>")
	)
	(arc
		(start 388.666228 -256.149348)
		(mid 388.850003 -256.20012)
		(end 389.035036 -256.154174)
		(width 0.09525)
		(layer "In11.Cu")
		(net "M_L_CPU0_CLK_DP<0>")
	)
	(arc
		(start 390.923272 -256.149348)
		(mid 391.204704 -256.073593)
		(end 391.486136 -256.149348)
		(width 0.09525)
		(layer "In11.Cu")
		(net "M_L_CPU0_CLK_DP<0>")
	)
	(arc
		(start 391.486136 -256.149348)
		(mid 391.669911 -256.20012)
		(end 391.854944 -256.154174)
		(width 0.09525)
		(layer "In11.Cu")
		(net "M_L_CPU0_CLK_DP<0>")
	)
	(arc
		(start 389.983472 -256.149348)
		(mid 390.264904 -256.073593)
		(end 390.546336 -256.149348)
		(width 0.09525)
		(layer "In11.Cu")
		(net "M_L_CPU0_CLK_DP<0>")
	)
	(arc
		(start 387.229604 -256.116328)
		(mid 387.239726 -256.112293)
		(end 387.249924 -256.108454)
		(width 0.09525)
		(layer "In11.Cu")
		(net "M_L_CPU0_CLK_DP<0>")
	)
	(arc
		(start 387.726174 -256.149348)
		(mid 387.909949 -256.20012)
		(end 388.094982 -256.154174)
		(width 0.09525)
		(layer "In11.Cu")
		(net "M_L_CPU0_CLK_DP<0>")
	)
	(arc
		(start 393.365482 -256.149348)
		(mid 393.426154 -256.189906)
		(end 393.481052 -256.237994)
		(width 0.09525)
		(layer "In11.Cu")
		(net "M_L_CPU0_CLK_DP<0>")
	)
	(arc
		(start 389.043418 -256.149348)
		(mid 389.32485 -256.073593)
		(end 389.606282 -256.149348)
		(width 0.09525)
		(layer "In11.Cu")
		(net "M_L_CPU0_CLK_DP<0>")
	)
	(arc
		(start 391.863326 -256.149348)
		(mid 392.134014 -256.073696)
		(end 392.407394 -256.138934)
		(width 0.09525)
		(layer "In11.Cu")
		(net "M_L_CPU0_CLK_DP<0>")
	)
	(arc
		(start 392.802618 -256.149348)
		(mid 393.069467 -256.07342)
		(end 393.340082 -256.134616)
		(width 0.09525)
		(layer "In11.Cu")
		(net "M_L_CPU0_CLK_DP<0>")
	)
	(segment
		(start 386.97789 -256.900172)
		(end 387.444742 -256.634234)
		(width 0.14732)
		(layer "F.Cu")
		(net "M_L_CPU0_CLK_DN<0>")
	)
	(segment
		(start 449.066158 -254.967994)
		(end 449.066158 -254.399034)
		(width 0.16002)
		(layer "In11.Cu")
		(net "M_L_CPU0_CLK_DN<0>")
	)
	(segment
		(start 409.484322 -256.658872)
		(end 409.934156 -256.658872)
		(width 0.16002)
		(layer "In11.Cu")
		(net "M_L_CPU0_CLK_DN<0>")
	)
	(segment
		(start 392.32459 -256.304288)
		(end 392.332972 -256.309114)
		(width 0.09525)
		(layer "In11.Cu")
		(net "M_L_CPU0_CLK_DN<0>")
	)
	(segment
		(start 449.45554 -254.009652)
		(end 449.812664 -254.009652)
		(width 0.16002)
		(layer "In11.Cu")
		(net "M_L_CPU0_CLK_DN<0>")
	)
	(segment
		(start 408.286966 -258.147312)
		(end 408.987244 -258.147312)
		(width 0.16002)
		(layer "In11.Cu")
		(net "M_L_CPU0_CLK_DN<0>")
	)
	(segment
		(start 409.324302 -256.818892)
		(end 409.484322 -256.658872)
		(width 0.16002)
		(layer "In11.Cu")
		(net "M_L_CPU0_CLK_DN<0>")
	)
	(segment
		(start 411.62859 -256.658872)
		(end 444.548768 -256.658872)
		(width 0.16002)
		(layer "In11.Cu")
		(net "M_L_CPU0_CLK_DN<0>")
	)
	(segment
		(start 409.934156 -256.658872)
		(end 410.094176 -256.818892)
		(width 0.16002)
		(layer "In11.Cu")
		(net "M_L_CPU0_CLK_DN<0>")
	)
	(segment
		(start 400.723608 -256.11582)
		(end 406.025604 -256.11582)
		(width 0.16002)
		(layer "In11.Cu")
		(net "M_L_CPU0_CLK_DN<0>")
	)
	(segment
		(start 406.025604 -256.11582)
		(end 406.568656 -256.658872)
		(width 0.16002)
		(layer "In11.Cu")
		(net "M_L_CPU0_CLK_DN<0>")
	)
	(segment
		(start 391.016236 -256.309114)
		(end 391.024618 -256.304288)
		(width 0.09525)
		(layer "In11.Cu")
		(net "M_L_CPU0_CLK_DN<0>")
	)
	(segment
		(start 444.675768 -256.785872)
		(end 445.155828 -256.785872)
		(width 0.16002)
		(layer "In11.Cu")
		(net "M_L_CPU0_CLK_DN<0>")
	)
	(segment
		(start 449.812664 -254.009652)
		(end 450.088 -254.284988)
		(width 0.16002)
		(layer "In11.Cu")
		(net "M_L_CPU0_CLK_DN<0>")
	)
	(segment
		(start 406.568656 -256.658872)
		(end 407.789888 -256.658872)
		(width 0.16002)
		(layer "In11.Cu")
		(net "M_L_CPU0_CLK_DN<0>")
	)
	(segment
		(start 388.196328 -256.309114)
		(end 388.20471 -256.304288)
		(width 0.09525)
		(layer "In11.Cu")
		(net "M_L_CPU0_CLK_DN<0>")
	)
	(segment
		(start 445.282828 -256.658872)
		(end 447.37528 -256.658872)
		(width 0.16002)
		(layer "In11.Cu")
		(net "M_L_CPU0_CLK_DN<0>")
	)
	(segment
		(start 399.325084 -257.514344)
		(end 400.723608 -256.11582)
		(width 0.16002)
		(layer "In11.Cu")
		(net "M_L_CPU0_CLK_DN<0>")
	)
	(segment
		(start 395.728698 -257.514344)
		(end 395.75232 -257.514344)
		(width 0.09525)
		(layer "In11.Cu")
		(net "M_L_CPU0_CLK_DN<0>")
	)
	(segment
		(start 407.949908 -256.818892)
		(end 407.949908 -257.810254)
		(width 0.16002)
		(layer "In11.Cu")
		(net "M_L_CPU0_CLK_DN<0>")
	)
	(segment
		(start 387.290818 -256.368804)
		(end 387.314186 -256.281936)
		(width 0.09525)
		(layer "In11.Cu")
		(net "M_L_CPU0_CLK_DN<0>")
	)
	(segment
		(start 410.094176 -256.818892)
		(end 410.094176 -257.810254)
		(width 0.16002)
		(layer "In11.Cu")
		(net "M_L_CPU0_CLK_DN<0>")
	)
	(segment
		(start 411.131512 -258.147312)
		(end 411.46857 -257.810254)
		(width 0.16002)
		(layer "In11.Cu")
		(net "M_L_CPU0_CLK_DN<0>")
	)
	(segment
		(start 394.437616 -257.455162)
		(end 395.669516 -257.455162)
		(width 0.09525)
		(layer "In11.Cu")
		(net "M_L_CPU0_CLK_DN<0>")
	)
	(segment
		(start 407.949908 -257.810254)
		(end 408.286966 -258.147312)
		(width 0.16002)
		(layer "In11.Cu")
		(net "M_L_CPU0_CLK_DN<0>")
	)
	(segment
		(start 387.444742 -256.634234)
		(end 387.290818 -256.368804)
		(width 0.09525)
		(layer "In11.Cu")
		(net "M_L_CPU0_CLK_DN<0>")
	)
	(segment
		(start 407.789888 -256.658872)
		(end 407.949908 -256.818892)
		(width 0.16002)
		(layer "In11.Cu")
		(net "M_L_CPU0_CLK_DN<0>")
	)
	(segment
		(start 411.46857 -256.818892)
		(end 411.62859 -256.658872)
		(width 0.16002)
		(layer "In11.Cu")
		(net "M_L_CPU0_CLK_DN<0>")
	)
	(segment
		(start 447.37528 -256.658872)
		(end 449.066158 -254.967994)
		(width 0.16002)
		(layer "In11.Cu")
		(net "M_L_CPU0_CLK_DN<0>")
	)
	(segment
		(start 449.066158 -254.399034)
		(end 449.45554 -254.009652)
		(width 0.16002)
		(layer "In11.Cu")
		(net "M_L_CPU0_CLK_DN<0>")
	)
	(segment
		(start 393.35075 -256.368296)
		(end 394.437616 -257.455162)
		(width 0.09525)
		(layer "In11.Cu")
		(net "M_L_CPU0_CLK_DN<0>")
	)
	(segment
		(start 410.094176 -257.810254)
		(end 410.431234 -258.147312)
		(width 0.16002)
		(layer "In11.Cu")
		(net "M_L_CPU0_CLK_DN<0>")
	)
	(segment
		(start 395.669516 -257.455162)
		(end 395.728698 -257.514344)
		(width 0.09525)
		(layer "In11.Cu")
		(net "M_L_CPU0_CLK_DN<0>")
	)
	(segment
		(start 390.44499 -256.304288)
		(end 390.453372 -256.309114)
		(width 0.09525)
		(layer "In11.Cu")
		(net "M_L_CPU0_CLK_DN<0>")
	)
	(segment
		(start 444.548768 -256.658872)
		(end 444.675768 -256.785872)
		(width 0.16002)
		(layer "In11.Cu")
		(net "M_L_CPU0_CLK_DN<0>")
	)
	(segment
		(start 395.75232 -257.514344)
		(end 399.325084 -257.514344)
		(width 0.16002)
		(layer "In11.Cu")
		(net "M_L_CPU0_CLK_DN<0>")
	)
	(segment
		(start 445.155828 -256.785872)
		(end 445.282828 -256.658872)
		(width 0.16002)
		(layer "In11.Cu")
		(net "M_L_CPU0_CLK_DN<0>")
	)
	(segment
		(start 393.256008 -256.299462)
		(end 393.272772 -256.309114)
		(width 0.09525)
		(layer "In11.Cu")
		(net "M_L_CPU0_CLK_DN<0>")
	)
	(segment
		(start 392.332972 -256.309114)
		(end 392.358372 -256.323846)
		(width 0.09525)
		(layer "In11.Cu")
		(net "M_L_CPU0_CLK_DN<0>")
	)
	(segment
		(start 409.324302 -257.810254)
		(end 409.324302 -256.818892)
		(width 0.16002)
		(layer "In11.Cu")
		(net "M_L_CPU0_CLK_DN<0>")
	)
	(segment
		(start 411.46857 -257.810254)
		(end 411.46857 -256.818892)
		(width 0.16002)
		(layer "In11.Cu")
		(net "M_L_CPU0_CLK_DN<0>")
	)
	(segment
		(start 408.987244 -258.147312)
		(end 409.324302 -257.810254)
		(width 0.16002)
		(layer "In11.Cu")
		(net "M_L_CPU0_CLK_DN<0>")
	)
	(segment
		(start 410.431234 -258.147312)
		(end 411.131512 -258.147312)
		(width 0.16002)
		(layer "In11.Cu")
		(net "M_L_CPU0_CLK_DN<0>")
	)
	(arc
		(start 389.513318 -256.309114)
		(mid 389.79475 -256.384869)
		(end 390.076182 -256.309114)
		(width 0.09525)
		(layer "In11.Cu")
		(net "M_L_CPU0_CLK_DN<0>")
	)
	(arc
		(start 387.314186 -256.281936)
		(mid 387.476868 -256.259804)
		(end 387.633464 -256.309114)
		(width 0.09525)
		(layer "In11.Cu")
		(net "M_L_CPU0_CLK_DN<0>")
	)
	(arc
		(start 391.393426 -256.309114)
		(mid 391.674858 -256.384869)
		(end 391.95629 -256.309114)
		(width 0.09525)
		(layer "In11.Cu")
		(net "M_L_CPU0_CLK_DN<0>")
	)
	(arc
		(start 390.453372 -256.309114)
		(mid 390.734804 -256.384869)
		(end 391.016236 -256.309114)
		(width 0.09525)
		(layer "In11.Cu")
		(net "M_L_CPU0_CLK_DN<0>")
	)
	(arc
		(start 388.573518 -256.309114)
		(mid 388.85495 -256.384869)
		(end 389.136382 -256.309114)
		(width 0.09525)
		(layer "In11.Cu")
		(net "M_L_CPU0_CLK_DN<0>")
	)
	(arc
		(start 391.024618 -256.304288)
		(mid 391.20965 -256.258374)
		(end 391.393426 -256.309114)
		(width 0.09525)
		(layer "In11.Cu")
		(net "M_L_CPU0_CLK_DN<0>")
	)
	(arc
		(start 388.20471 -256.304288)
		(mid 388.389742 -256.258374)
		(end 388.573518 -256.309114)
		(width 0.09525)
		(layer "In11.Cu")
		(net "M_L_CPU0_CLK_DN<0>")
	)
	(arc
		(start 387.633464 -256.309114)
		(mid 387.914896 -256.384869)
		(end 388.196328 -256.309114)
		(width 0.09525)
		(layer "In11.Cu")
		(net "M_L_CPU0_CLK_DN<0>")
	)
	(arc
		(start 389.136382 -256.309114)
		(mid 389.32485 -256.258437)
		(end 389.513318 -256.309114)
		(width 0.09525)
		(layer "In11.Cu")
		(net "M_L_CPU0_CLK_DN<0>")
	)
	(arc
		(start 392.895836 -256.309114)
		(mid 393.074696 -256.258318)
		(end 393.256008 -256.299462)
		(width 0.09525)
		(layer "In11.Cu")
		(net "M_L_CPU0_CLK_DN<0>")
	)
	(arc
		(start 392.358372 -256.323846)
		(mid 392.628988 -256.385071)
		(end 392.895836 -256.309114)
		(width 0.09525)
		(layer "In11.Cu")
		(net "M_L_CPU0_CLK_DN<0>")
	)
	(arc
		(start 390.076182 -256.309114)
		(mid 390.259957 -256.258342)
		(end 390.44499 -256.304288)
		(width 0.09525)
		(layer "In11.Cu")
		(net "M_L_CPU0_CLK_DN<0>")
	)
	(arc
		(start 393.272772 -256.309114)
		(mid 393.313702 -256.336148)
		(end 393.35075 -256.368296)
		(width 0.09525)
		(layer "In11.Cu")
		(net "M_L_CPU0_CLK_DN<0>")
	)
	(arc
		(start 391.95629 -256.309114)
		(mid 392.139811 -256.25847)
		(end 392.32459 -256.304288)
		(width 0.09525)
		(layer "In11.Cu")
		(net "M_L_CPU0_CLK_DN<0>")
	)
	(segment
		(start 385.098036 -250.420124)
		(end 385.564888 -250.154186)
		(width 0.10668)
		(layer "F.Cu")
		(net "M_L_CPU0_ALERT_R_N")
	)
	(segment
		(start 395.833092 -251.251974)
		(end 396.778734 -251.251974)
		(width 0.11684)
		(layer "In11.Cu")
		(net "M_L_CPU0_ALERT_R_N")
	)
	(segment
		(start 452.366126 -244.510052)
		(end 452.791068 -244.08511)
		(width 0.11684)
		(layer "In11.Cu")
		(net "M_L_CPU0_ALERT_R_N")
	)
	(segment
		(start 412.406338 -246.210074)
		(end 443.727586 -246.210074)
		(width 0.11684)
		(layer "In11.Cu")
		(net "M_L_CPU0_ALERT_R_N")
	)
	(segment
		(start 387.257798 -250.476766)
		(end 387.26618 -250.481592)
		(width 0.0889)
		(layer "In11.Cu")
		(net "M_L_CPU0_ALERT_R_N")
	)
	(segment
		(start 394.867638 -250.527312)
		(end 395.5923 -251.251974)
		(width 0.0889)
		(layer "In11.Cu")
		(net "M_L_CPU0_ALERT_R_N")
	)
	(segment
		(start 391.957814 -250.476766)
		(end 391.966196 -250.481592)
		(width 0.0889)
		(layer "In11.Cu")
		(net "M_L_CPU0_ALERT_R_N")
	)
	(segment
		(start 388.197852 -250.476766)
		(end 388.206234 -250.481592)
		(width 0.0889)
		(layer "In11.Cu")
		(net "M_L_CPU0_ALERT_R_N")
	)
	(segment
		(start 390.443466 -250.481592)
		(end 390.451848 -250.476766)
		(width 0.0889)
		(layer "In11.Cu")
		(net "M_L_CPU0_ALERT_R_N")
	)
	(segment
		(start 386.683504 -250.481592)
		(end 386.691886 -250.476766)
		(width 0.0889)
		(layer "In11.Cu")
		(net "M_L_CPU0_ALERT_R_N")
	)
	(segment
		(start 393.084812 -250.527312)
		(end 394.867638 -250.527312)
		(width 0.0889)
		(layer "In11.Cu")
		(net "M_L_CPU0_ALERT_R_N")
	)
	(segment
		(start 395.5923 -251.251974)
		(end 395.833092 -251.251974)
		(width 0.0889)
		(layer "In11.Cu")
		(net "M_L_CPU0_ALERT_R_N")
	)
	(segment
		(start 443.727586 -246.210074)
		(end 445.427608 -244.510052)
		(width 0.11684)
		(layer "In11.Cu")
		(net "M_L_CPU0_ALERT_R_N")
	)
	(segment
		(start 408.727402 -249.88901)
		(end 412.406338 -246.210074)
		(width 0.11684)
		(layer "In11.Cu")
		(net "M_L_CPU0_ALERT_R_N")
	)
	(segment
		(start 398.141698 -249.88901)
		(end 408.727402 -249.88901)
		(width 0.11684)
		(layer "In11.Cu")
		(net "M_L_CPU0_ALERT_R_N")
	)
	(segment
		(start 445.427608 -244.510052)
		(end 452.366126 -244.510052)
		(width 0.11684)
		(layer "In11.Cu")
		(net "M_L_CPU0_ALERT_R_N")
	)
	(segment
		(start 396.778734 -251.251974)
		(end 398.141698 -249.88901)
		(width 0.11684)
		(layer "In11.Cu")
		(net "M_L_CPU0_ALERT_R_N")
	)
	(segment
		(start 391.01776 -250.476766)
		(end 391.026142 -250.481592)
		(width 0.0889)
		(layer "In11.Cu")
		(net "M_L_CPU0_ALERT_R_N")
	)
	(segment
		(start 385.718812 -250.419616)
		(end 385.814824 -250.445016)
		(width 0.0889)
		(layer "In11.Cu")
		(net "M_L_CPU0_ALERT_R_N")
	)
	(segment
		(start 385.564888 -250.154186)
		(end 385.718812 -250.419616)
		(width 0.0889)
		(layer "In11.Cu")
		(net "M_L_CPU0_ALERT_R_N")
	)
	(arc
		(start 390.077706 -250.476766)
		(mid 390.259957 -250.527116)
		(end 390.443466 -250.481592)
		(width 0.0889)
		(layer "In11.Cu")
		(net "M_L_CPU0_ALERT_R_N")
	)
	(arc
		(start 391.966196 -250.481592)
		(mid 392.149704 -250.527086)
		(end 392.331956 -250.476766)
		(width 0.0889)
		(layer "In11.Cu")
		(net "M_L_CPU0_ALERT_R_N")
	)
	(arc
		(start 392.897868 -250.476766)
		(mid 392.988001 -250.514386)
		(end 393.084812 -250.527312)
		(width 0.0889)
		(layer "In11.Cu")
		(net "M_L_CPU0_ALERT_R_N")
	)
	(arc
		(start 385.814824 -250.445016)
		(mid 386.070032 -250.401539)
		(end 386.317744 -250.476766)
		(width 0.0889)
		(layer "In11.Cu")
		(net "M_L_CPU0_ALERT_R_N")
	)
	(arc
		(start 392.331956 -250.476766)
		(mid 392.614912 -250.400589)
		(end 392.897868 -250.476766)
		(width 0.0889)
		(layer "In11.Cu")
		(net "M_L_CPU0_ALERT_R_N")
	)
	(arc
		(start 391.026142 -250.481592)
		(mid 391.20965 -250.527086)
		(end 391.391902 -250.476766)
		(width 0.0889)
		(layer "In11.Cu")
		(net "M_L_CPU0_ALERT_R_N")
	)
	(arc
		(start 387.63194 -250.476766)
		(mid 387.914896 -250.400589)
		(end 388.197852 -250.476766)
		(width 0.0889)
		(layer "In11.Cu")
		(net "M_L_CPU0_ALERT_R_N")
	)
	(arc
		(start 388.206234 -250.481592)
		(mid 388.389742 -250.527086)
		(end 388.571994 -250.476766)
		(width 0.0889)
		(layer "In11.Cu")
		(net "M_L_CPU0_ALERT_R_N")
	)
	(arc
		(start 389.137906 -250.476766)
		(mid 389.32485 -250.527021)
		(end 389.511794 -250.476766)
		(width 0.0889)
		(layer "In11.Cu")
		(net "M_L_CPU0_ALERT_R_N")
	)
	(arc
		(start 388.571994 -250.476766)
		(mid 388.85495 -250.400589)
		(end 389.137906 -250.476766)
		(width 0.0889)
		(layer "In11.Cu")
		(net "M_L_CPU0_ALERT_R_N")
	)
	(arc
		(start 386.317744 -250.476766)
		(mid 386.499995 -250.527116)
		(end 386.683504 -250.481592)
		(width 0.0889)
		(layer "In11.Cu")
		(net "M_L_CPU0_ALERT_R_N")
	)
	(arc
		(start 389.511794 -250.476766)
		(mid 389.79475 -250.400589)
		(end 390.077706 -250.476766)
		(width 0.0889)
		(layer "In11.Cu")
		(net "M_L_CPU0_ALERT_R_N")
	)
	(arc
		(start 387.26618 -250.481592)
		(mid 387.449688 -250.527086)
		(end 387.63194 -250.476766)
		(width 0.0889)
		(layer "In11.Cu")
		(net "M_L_CPU0_ALERT_R_N")
	)
	(arc
		(start 386.691886 -250.476766)
		(mid 386.974842 -250.400589)
		(end 387.257798 -250.476766)
		(width 0.0889)
		(layer "In11.Cu")
		(net "M_L_CPU0_ALERT_R_N")
	)
	(arc
		(start 391.391902 -250.476766)
		(mid 391.674858 -250.400589)
		(end 391.957814 -250.476766)
		(width 0.0889)
		(layer "In11.Cu")
		(net "M_L_CPU0_ALERT_R_N")
	)
	(arc
		(start 390.451848 -250.476766)
		(mid 390.734804 -250.400589)
		(end 391.01776 -250.476766)
		(width 0.0889)
		(layer "In11.Cu")
		(net "M_L_CPU0_ALERT_R_N")
	)
	(via
		(at 454.188068 -244.08511)
		(size 0.4826)
		(drill 0.254)
		(layers "F.Cu" "B.Cu")
		(net "M_L_CPU0_ALERT_N")
	)
	(segment
		(start 453.591168 -244.08511)
		(end 454.188068 -244.08511)
		(width 0.10668)
		(layer "B.Cu")
		(net "M_L_CPU0_ALERT_N")
	)
	(segment
		(start 142.157958 -267.340334)
		(end 142.62481 -267.606272)
		(width 0.10668)
		(layer "F.Cu")
		(net "M_K_CPU1_SB_RSP<0>")
	)
	(segment
		(start 144.691354 -267.928852)
		(end 144.701768 -267.922756)
		(width 0.0889)
		(layer "In6.Cu")
		(net "M_K_CPU1_SB_RSP<0>")
	)
	(segment
		(start 174.78502 -270.010382)
		(end 177.412142 -270.010382)
		(width 0.11684)
		(layer "In6.Cu")
		(net "M_K_CPU1_SB_RSP<0>")
	)
	(segment
		(start 160.041336 -266.570714)
		(end 163.957508 -270.486886)
		(width 0.11684)
		(layer "In6.Cu")
		(net "M_K_CPU1_SB_RSP<0>")
	)
	(segment
		(start 172.732446 -270.86052)
		(end 174.78502 -270.010382)
		(width 0.11684)
		(layer "In6.Cu")
		(net "M_K_CPU1_SB_RSP<0>")
	)
	(segment
		(start 165.455854 -270.486886)
		(end 166.60622 -270.010382)
		(width 0.11684)
		(layer "In6.Cu")
		(net "M_K_CPU1_SB_RSP<0>")
	)
	(segment
		(start 180.117496 -270.86052)
		(end 182.17007 -270.010382)
		(width 0.11684)
		(layer "In6.Cu")
		(net "M_K_CPU1_SB_RSP<0>")
	)
	(segment
		(start 169.86504 -270.010382)
		(end 171.917614 -270.86052)
		(width 0.11684)
		(layer "In6.Cu")
		(net "M_K_CPU1_SB_RSP<0>")
	)
	(segment
		(start 146.806158 -266.140692)
		(end 147.182586 -266.140692)
		(width 0.0889)
		(layer "In6.Cu")
		(net "M_K_CPU1_SB_RSP<0>")
	)
	(segment
		(start 177.412142 -270.010382)
		(end 179.464716 -270.86052)
		(width 0.11684)
		(layer "In6.Cu")
		(net "M_K_CPU1_SB_RSP<0>")
	)
	(segment
		(start 166.60622 -270.010382)
		(end 169.86504 -270.010382)
		(width 0.11684)
		(layer "In6.Cu")
		(net "M_K_CPU1_SB_RSP<0>")
	)
	(segment
		(start 179.464716 -270.86052)
		(end 180.117496 -270.86052)
		(width 0.11684)
		(layer "In6.Cu")
		(net "M_K_CPU1_SB_RSP<0>")
	)
	(segment
		(start 145.826226 -267.120624)
		(end 146.806158 -266.140692)
		(width 0.0889)
		(layer "In6.Cu")
		(net "M_K_CPU1_SB_RSP<0>")
	)
	(segment
		(start 145.826226 -267.59916)
		(end 145.826226 -267.120624)
		(width 0.0889)
		(layer "In6.Cu")
		(net "M_K_CPU1_SB_RSP<0>")
	)
	(segment
		(start 163.957508 -270.486886)
		(end 165.455854 -270.486886)
		(width 0.11684)
		(layer "In6.Cu")
		(net "M_K_CPU1_SB_RSP<0>")
	)
	(segment
		(start 144.307052 -267.922756)
		(end 144.317466 -267.928852)
		(width 0.0889)
		(layer "In6.Cu")
		(net "M_K_CPU1_SB_RSP<0>")
	)
	(segment
		(start 182.17007 -270.010382)
		(end 198.279258 -270.010382)
		(width 0.11684)
		(layer "In6.Cu")
		(net "M_K_CPU1_SB_RSP<0>")
	)
	(segment
		(start 143.377666 -267.928852)
		(end 143.386048 -267.933678)
		(width 0.0889)
		(layer "In6.Cu")
		(net "M_K_CPU1_SB_RSP<0>")
	)
	(segment
		(start 142.778734 -267.871702)
		(end 142.874746 -267.897102)
		(width 0.0889)
		(layer "In6.Cu")
		(net "M_K_CPU1_SB_RSP<0>")
	)
	(segment
		(start 148.040344 -266.570714)
		(end 160.041336 -266.570714)
		(width 0.11684)
		(layer "In6.Cu")
		(net "M_K_CPU1_SB_RSP<0>")
	)
	(segment
		(start 142.62481 -267.606272)
		(end 142.778734 -267.871702)
		(width 0.0889)
		(layer "In6.Cu")
		(net "M_K_CPU1_SB_RSP<0>")
	)
	(segment
		(start 147.182586 -266.140692)
		(end 147.612608 -266.570714)
		(width 0.0889)
		(layer "In6.Cu")
		(net "M_K_CPU1_SB_RSP<0>")
	)
	(segment
		(start 171.917614 -270.86052)
		(end 172.732446 -270.86052)
		(width 0.11684)
		(layer "In6.Cu")
		(net "M_K_CPU1_SB_RSP<0>")
	)
	(segment
		(start 147.612608 -266.570714)
		(end 148.040344 -266.570714)
		(width 0.0889)
		(layer "In6.Cu")
		(net "M_K_CPU1_SB_RSP<0>")
	)
	(segment
		(start 198.279258 -270.010382)
		(end 198.7042 -270.435324)
		(width 0.11684)
		(layer "In6.Cu")
		(net "M_K_CPU1_SB_RSP<0>")
	)
	(arc
		(start 143.751808 -267.928852)
		(mid 144.028621 -267.852709)
		(end 144.307052 -267.922756)
		(width 0.0889)
		(layer "In6.Cu")
		(net "M_K_CPU1_SB_RSP<0>")
	)
	(arc
		(start 144.701768 -267.922756)
		(mid 144.980454 -267.852536)
		(end 145.25752 -267.928852)
		(width 0.0889)
		(layer "In6.Cu")
		(net "M_K_CPU1_SB_RSP<0>")
	)
	(arc
		(start 142.874746 -267.897102)
		(mid 143.129954 -267.853625)
		(end 143.377666 -267.928852)
		(width 0.0889)
		(layer "In6.Cu")
		(net "M_K_CPU1_SB_RSP<0>")
	)
	(arc
		(start 145.56359 -267.953236)
		(mid 145.615135 -267.925469)
		(end 145.66265 -267.89126)
		(width 0.0889)
		(layer "In6.Cu")
		(net "M_K_CPU1_SB_RSP<0>")
	)
	(arc
		(start 145.66265 -267.89126)
		(mid 145.771799 -267.760544)
		(end 145.826226 -267.59916)
		(width 0.0889)
		(layer "In6.Cu")
		(net "M_K_CPU1_SB_RSP<0>")
	)
	(arc
		(start 144.317466 -267.928852)
		(mid 144.50441 -267.979107)
		(end 144.691354 -267.928852)
		(width 0.0889)
		(layer "In6.Cu")
		(net "M_K_CPU1_SB_RSP<0>")
	)
	(arc
		(start 145.444718 -267.979144)
		(mid 145.50555 -267.972594)
		(end 145.56359 -267.953236)
		(width 0.0889)
		(layer "In6.Cu")
		(net "M_K_CPU1_SB_RSP<0>")
	)
	(arc
		(start 145.25752 -267.928852)
		(mid 145.347796 -267.966357)
		(end 145.444718 -267.979144)
		(width 0.0889)
		(layer "In6.Cu")
		(net "M_K_CPU1_SB_RSP<0>")
	)
	(arc
		(start 143.386048 -267.933678)
		(mid 143.569556 -267.979172)
		(end 143.751808 -267.928852)
		(width 0.0889)
		(layer "In6.Cu")
		(net "M_K_CPU1_SB_RSP<0>")
	)
	(segment
		(start 140.748004 -264.910316)
		(end 141.214856 -265.176254)
		(width 0.10668)
		(layer "F.Cu")
		(net "M_K_CPU1_SB_PAR")
	)
	(segment
		(start 145.161508 -265.498834)
		(end 146.111976 -264.544556)
		(width 0.0889)
		(layer "In6.Cu")
		(net "M_K_CPU1_SB_PAR")
	)
	(segment
		(start 178.394106 -266.610338)
		(end 179.244244 -267.460476)
		(width 0.14478)
		(layer "In6.Cu")
		(net "M_K_CPU1_SB_PAR")
	)
	(segment
		(start 165.830758 -266.610338)
		(end 170.77436 -266.610338)
		(width 0.14478)
		(layer "In6.Cu")
		(net "M_K_CPU1_SB_PAR")
	)
	(segment
		(start 147.456144 -264.544556)
		(end 147.705572 -264.793984)
		(width 0.0889)
		(layer "In6.Cu")
		(net "M_K_CPU1_SB_PAR")
	)
	(segment
		(start 144.787112 -265.498834)
		(end 144.798796 -265.505692)
		(width 0.0889)
		(layer "In6.Cu")
		(net "M_K_CPU1_SB_PAR")
	)
	(segment
		(start 194.17919 -266.610338)
		(end 194.604132 -267.03528)
		(width 0.14478)
		(layer "In6.Cu")
		(net "M_K_CPU1_SB_PAR")
	)
	(segment
		(start 174.544228 -266.610338)
		(end 178.394106 -266.610338)
		(width 0.14478)
		(layer "In6.Cu")
		(net "M_K_CPU1_SB_PAR")
	)
	(segment
		(start 170.77436 -266.610338)
		(end 171.624498 -267.460476)
		(width 0.14478)
		(layer "In6.Cu")
		(net "M_K_CPU1_SB_PAR")
	)
	(segment
		(start 179.244244 -267.460476)
		(end 181.238144 -267.460476)
		(width 0.14478)
		(layer "In6.Cu")
		(net "M_K_CPU1_SB_PAR")
	)
	(segment
		(start 141.36878 -265.441684)
		(end 141.464792 -265.467084)
		(width 0.0889)
		(layer "In6.Cu")
		(net "M_K_CPU1_SB_PAR")
	)
	(segment
		(start 161.058606 -264.793984)
		(end 163.725098 -267.460476)
		(width 0.14478)
		(layer "In6.Cu")
		(net "M_K_CPU1_SB_PAR")
	)
	(segment
		(start 146.111976 -264.544556)
		(end 147.456144 -264.544556)
		(width 0.0889)
		(layer "In6.Cu")
		(net "M_K_CPU1_SB_PAR")
	)
	(segment
		(start 171.624498 -267.460476)
		(end 173.69409 -267.460476)
		(width 0.14478)
		(layer "In6.Cu")
		(net "M_K_CPU1_SB_PAR")
	)
	(segment
		(start 147.705572 -264.793984)
		(end 148.025866 -264.793984)
		(width 0.0889)
		(layer "In6.Cu")
		(net "M_K_CPU1_SB_PAR")
	)
	(segment
		(start 144.20977 -265.505692)
		(end 144.221454 -265.498834)
		(width 0.0889)
		(layer "In6.Cu")
		(net "M_K_CPU1_SB_PAR")
	)
	(segment
		(start 181.238144 -267.460476)
		(end 182.088282 -266.610338)
		(width 0.14478)
		(layer "In6.Cu")
		(net "M_K_CPU1_SB_PAR")
	)
	(segment
		(start 182.088282 -266.610338)
		(end 194.17919 -266.610338)
		(width 0.14478)
		(layer "In6.Cu")
		(net "M_K_CPU1_SB_PAR")
	)
	(segment
		(start 163.725098 -267.460476)
		(end 164.98062 -267.460476)
		(width 0.14478)
		(layer "In6.Cu")
		(net "M_K_CPU1_SB_PAR")
	)
	(segment
		(start 144.221454 -265.498834)
		(end 144.231868 -265.492738)
		(width 0.0889)
		(layer "In6.Cu")
		(net "M_K_CPU1_SB_PAR")
	)
	(segment
		(start 173.69409 -267.460476)
		(end 174.544228 -266.610338)
		(width 0.14478)
		(layer "In6.Cu")
		(net "M_K_CPU1_SB_PAR")
	)
	(segment
		(start 164.98062 -267.460476)
		(end 165.830758 -266.610338)
		(width 0.14478)
		(layer "In6.Cu")
		(net "M_K_CPU1_SB_PAR")
	)
	(segment
		(start 148.025866 -264.793984)
		(end 161.058606 -264.793984)
		(width 0.14478)
		(layer "In6.Cu")
		(net "M_K_CPU1_SB_PAR")
	)
	(segment
		(start 141.967712 -265.498834)
		(end 141.976094 -265.50366)
		(width 0.0889)
		(layer "In6.Cu")
		(net "M_K_CPU1_SB_PAR")
	)
	(segment
		(start 141.214856 -265.176254)
		(end 141.36878 -265.441684)
		(width 0.0889)
		(layer "In6.Cu")
		(net "M_K_CPU1_SB_PAR")
	)
	(arc
		(start 142.907766 -265.498834)
		(mid 143.09471 -265.549089)
		(end 143.281654 -265.498834)
		(width 0.0889)
		(layer "In6.Cu")
		(net "M_K_CPU1_SB_PAR")
	)
	(arc
		(start 143.281654 -265.498834)
		(mid 143.56461 -265.422657)
		(end 143.847566 -265.498834)
		(width 0.0889)
		(layer "In6.Cu")
		(net "M_K_CPU1_SB_PAR")
	)
	(arc
		(start 141.464792 -265.467084)
		(mid 141.72 -265.423607)
		(end 141.967712 -265.498834)
		(width 0.0889)
		(layer "In6.Cu")
		(net "M_K_CPU1_SB_PAR")
	)
	(arc
		(start 144.231868 -265.492738)
		(mid 144.5103 -265.42264)
		(end 144.787112 -265.498834)
		(width 0.0889)
		(layer "In6.Cu")
		(net "M_K_CPU1_SB_PAR")
	)
	(arc
		(start 144.798796 -265.505692)
		(mid 144.981051 -265.549345)
		(end 145.161508 -265.498834)
		(width 0.0889)
		(layer "In6.Cu")
		(net "M_K_CPU1_SB_PAR")
	)
	(arc
		(start 141.976094 -265.50366)
		(mid 142.159602 -265.549154)
		(end 142.341854 -265.498834)
		(width 0.0889)
		(layer "In6.Cu")
		(net "M_K_CPU1_SB_PAR")
	)
	(arc
		(start 142.341854 -265.498834)
		(mid 142.62481 -265.422657)
		(end 142.907766 -265.498834)
		(width 0.0889)
		(layer "In6.Cu")
		(net "M_K_CPU1_SB_PAR")
	)
	(arc
		(start 143.847566 -265.498834)
		(mid 144.027771 -265.549151)
		(end 144.20977 -265.505692)
		(width 0.0889)
		(layer "In6.Cu")
		(net "M_K_CPU1_SB_PAR")
	)
	(segment
		(start 142.157958 -270.580358)
		(end 142.62481 -270.846296)
		(width 0.12954)
		(layer "F.Cu")
		(net "M_K_CPU1_SB_DQS_DP<9>")
	)
	(segment
		(start 182.720234 -274.81022)
		(end 184.6834 -274.81022)
		(width 0.16002)
		(layer "In6.Cu")
		(net "M_K_CPU1_SB_DQS_DP<9>")
	)
	(segment
		(start 173.597062 -276.000718)
		(end 174.447962 -275.149818)
		(width 0.16002)
		(layer "In6.Cu")
		(net "M_K_CPU1_SB_DQS_DP<9>")
	)
	(segment
		(start 169.595292 -274.81022)
		(end 170.445176 -275.660104)
		(width 0.16002)
		(layer "In6.Cu")
		(net "M_K_CPU1_SB_DQS_DP<9>")
	)
	(segment
		(start 177.98923 -275.660104)
		(end 180.399182 -275.660104)
		(width 0.16002)
		(layer "In6.Cu")
		(net "M_K_CPU1_SB_DQS_DP<9>")
	)
	(segment
		(start 188.28385 -276.000718)
		(end 188.68517 -276.000718)
		(width 0.16002)
		(layer "In6.Cu")
		(net "M_K_CPU1_SB_DQS_DP<9>")
	)
	(segment
		(start 184.6834 -274.81022)
		(end 185.533284 -275.660104)
		(width 0.16002)
		(layer "In6.Cu")
		(net "M_K_CPU1_SB_DQS_DP<9>")
	)
	(segment
		(start 188.68517 -276.000718)
		(end 189.53607 -275.149818)
		(width 0.16002)
		(layer "In6.Cu")
		(net "M_K_CPU1_SB_DQS_DP<9>")
	)
	(segment
		(start 158.2674 -269.252954)
		(end 165.015164 -276.000718)
		(width 0.16002)
		(layer "In6.Cu")
		(net "M_K_CPU1_SB_DQS_DP<9>")
	)
	(segment
		(start 170.445176 -275.660104)
		(end 172.855128 -275.660104)
		(width 0.16002)
		(layer "In6.Cu")
		(net "M_K_CPU1_SB_DQS_DP<9>")
	)
	(segment
		(start 195.831206 -276.008338)
		(end 196.210682 -276.008338)
		(width 0.16002)
		(layer "In6.Cu")
		(net "M_K_CPU1_SB_DQS_DP<9>")
	)
	(segment
		(start 181.141116 -276.000718)
		(end 181.992016 -275.149818)
		(width 0.16002)
		(layer "In6.Cu")
		(net "M_K_CPU1_SB_DQS_DP<9>")
	)
	(segment
		(start 165.015164 -276.000718)
		(end 166.053008 -276.000718)
		(width 0.16002)
		(layer "In6.Cu")
		(net "M_K_CPU1_SB_DQS_DP<9>")
	)
	(segment
		(start 147.29587 -269.178786)
		(end 147.42922 -269.312136)
		(width 0.09525)
		(layer "In6.Cu")
		(net "M_K_CPU1_SB_DQS_DP<9>")
	)
	(segment
		(start 144.906492 -270.68272)
		(end 144.906746 -270.68272)
		(width 0.09525)
		(layer "In6.Cu")
		(net "M_K_CPU1_SB_DQS_DP<9>")
	)
	(segment
		(start 196.210682 -276.008338)
		(end 196.409818 -275.809202)
		(width 0.16002)
		(layer "In6.Cu")
		(net "M_K_CPU1_SB_DQS_DP<9>")
	)
	(segment
		(start 175.17618 -274.81022)
		(end 177.139346 -274.81022)
		(width 0.16002)
		(layer "In6.Cu")
		(net "M_K_CPU1_SB_DQS_DP<9>")
	)
	(segment
		(start 180.399182 -275.660104)
		(end 180.739796 -276.000718)
		(width 0.16002)
		(layer "In6.Cu")
		(net "M_K_CPU1_SB_DQS_DP<9>")
	)
	(segment
		(start 166.903908 -275.149818)
		(end 167.292528 -275.149818)
		(width 0.16002)
		(layer "In6.Cu")
		(net "M_K_CPU1_SB_DQS_DP<9>")
	)
	(segment
		(start 198.430388 -275.809202)
		(end 198.7042 -275.53539)
		(width 0.16002)
		(layer "In6.Cu")
		(net "M_K_CPU1_SB_DQS_DP<9>")
	)
	(segment
		(start 182.380636 -275.149818)
		(end 182.720234 -274.81022)
		(width 0.16002)
		(layer "In6.Cu")
		(net "M_K_CPU1_SB_DQS_DP<9>")
	)
	(segment
		(start 147.42922 -269.312136)
		(end 147.836382 -269.312136)
		(width 0.09525)
		(layer "In6.Cu")
		(net "M_K_CPU1_SB_DQS_DP<9>")
	)
	(segment
		(start 174.447962 -275.149818)
		(end 174.836582 -275.149818)
		(width 0.16002)
		(layer "In6.Cu")
		(net "M_K_CPU1_SB_DQS_DP<9>")
	)
	(segment
		(start 180.739796 -276.000718)
		(end 181.141116 -276.000718)
		(width 0.16002)
		(layer "In6.Cu")
		(net "M_K_CPU1_SB_DQS_DP<9>")
	)
	(segment
		(start 142.778734 -271.111726)
		(end 142.879572 -271.138396)
		(width 0.09525)
		(layer "In6.Cu")
		(net "M_K_CPU1_SB_DQS_DP<9>")
	)
	(segment
		(start 192.996312 -275.38426)
		(end 195.207128 -275.38426)
		(width 0.16002)
		(layer "In6.Cu")
		(net "M_K_CPU1_SB_DQS_DP<9>")
	)
	(segment
		(start 145.329656 -270.269462)
		(end 145.68932 -270.11249)
		(width 0.09525)
		(layer "In6.Cu")
		(net "M_K_CPU1_SB_DQS_DP<9>")
	)
	(segment
		(start 189.53607 -275.149818)
		(end 189.92469 -275.149818)
		(width 0.16002)
		(layer "In6.Cu")
		(net "M_K_CPU1_SB_DQS_DP<9>")
	)
	(segment
		(start 167.292528 -275.149818)
		(end 167.632126 -274.81022)
		(width 0.16002)
		(layer "In6.Cu")
		(net "M_K_CPU1_SB_DQS_DP<9>")
	)
	(segment
		(start 173.195742 -276.000718)
		(end 173.597062 -276.000718)
		(width 0.16002)
		(layer "In6.Cu")
		(net "M_K_CPU1_SB_DQS_DP<9>")
	)
	(segment
		(start 190.264288 -274.81022)
		(end 192.422272 -274.81022)
		(width 0.16002)
		(layer "In6.Cu")
		(net "M_K_CPU1_SB_DQS_DP<9>")
	)
	(segment
		(start 142.62481 -270.846296)
		(end 142.778734 -271.111726)
		(width 0.09525)
		(layer "In6.Cu")
		(net "M_K_CPU1_SB_DQS_DP<9>")
	)
	(segment
		(start 166.053008 -276.000718)
		(end 166.903908 -275.149818)
		(width 0.16002)
		(layer "In6.Cu")
		(net "M_K_CPU1_SB_DQS_DP<9>")
	)
	(segment
		(start 145.098262 -270.42237)
		(end 145.283428 -270.29537)
		(width 0.09525)
		(layer "In6.Cu")
		(net "M_K_CPU1_SB_DQS_DP<9>")
	)
	(segment
		(start 189.92469 -275.149818)
		(end 190.264288 -274.81022)
		(width 0.16002)
		(layer "In6.Cu")
		(net "M_K_CPU1_SB_DQS_DP<9>")
	)
	(segment
		(start 147.895564 -269.252954)
		(end 147.919186 -269.252954)
		(width 0.09525)
		(layer "In6.Cu")
		(net "M_K_CPU1_SB_DQS_DP<9>")
	)
	(segment
		(start 192.422272 -274.81022)
		(end 192.996312 -275.38426)
		(width 0.16002)
		(layer "In6.Cu")
		(net "M_K_CPU1_SB_DQS_DP<9>")
	)
	(segment
		(start 196.409818 -275.809202)
		(end 198.430388 -275.809202)
		(width 0.16002)
		(layer "In6.Cu")
		(net "M_K_CPU1_SB_DQS_DP<9>")
	)
	(segment
		(start 167.632126 -274.81022)
		(end 169.595292 -274.81022)
		(width 0.16002)
		(layer "In6.Cu")
		(net "M_K_CPU1_SB_DQS_DP<9>")
	)
	(segment
		(start 147.836382 -269.312136)
		(end 147.895564 -269.252954)
		(width 0.09525)
		(layer "In6.Cu")
		(net "M_K_CPU1_SB_DQS_DP<9>")
	)
	(segment
		(start 177.139346 -274.81022)
		(end 177.98923 -275.660104)
		(width 0.16002)
		(layer "In6.Cu")
		(net "M_K_CPU1_SB_DQS_DP<9>")
	)
	(segment
		(start 147.919186 -269.252954)
		(end 158.2674 -269.252954)
		(width 0.16002)
		(layer "In6.Cu")
		(net "M_K_CPU1_SB_DQS_DP<9>")
	)
	(segment
		(start 144.677638 -271.179798)
		(end 144.678654 -271.17929)
		(width 0.09525)
		(layer "In6.Cu")
		(net "M_K_CPU1_SB_DQS_DP<9>")
	)
	(segment
		(start 145.68932 -270.11249)
		(end 146.62277 -269.178786)
		(width 0.09525)
		(layer "In6.Cu")
		(net "M_K_CPU1_SB_DQS_DP<9>")
	)
	(segment
		(start 145.08226 -270.433546)
		(end 145.083784 -270.432022)
		(width 0.09525)
		(layer "In6.Cu")
		(net "M_K_CPU1_SB_DQS_DP<9>")
	)
	(segment
		(start 143.376142 -271.171416)
		(end 143.384524 -271.176242)
		(width 0.09525)
		(layer "In6.Cu")
		(net "M_K_CPU1_SB_DQS_DP<9>")
	)
	(segment
		(start 185.533284 -275.660104)
		(end 187.943236 -275.660104)
		(width 0.16002)
		(layer "In6.Cu")
		(net "M_K_CPU1_SB_DQS_DP<9>")
	)
	(segment
		(start 144.906492 -270.682974)
		(end 144.906492 -270.68272)
		(width 0.09525)
		(layer "In6.Cu")
		(net "M_K_CPU1_SB_DQS_DP<9>")
	)
	(segment
		(start 181.992016 -275.149818)
		(end 182.380636 -275.149818)
		(width 0.16002)
		(layer "In6.Cu")
		(net "M_K_CPU1_SB_DQS_DP<9>")
	)
	(segment
		(start 172.855128 -275.660104)
		(end 173.195742 -276.000718)
		(width 0.16002)
		(layer "In6.Cu")
		(net "M_K_CPU1_SB_DQS_DP<9>")
	)
	(segment
		(start 144.693132 -271.170908)
		(end 144.7292 -271.15008)
		(width 0.09525)
		(layer "In6.Cu")
		(net "M_K_CPU1_SB_DQS_DP<9>")
	)
	(segment
		(start 145.098262 -270.422116)
		(end 145.098262 -270.42237)
		(width 0.09525)
		(layer "In6.Cu")
		(net "M_K_CPU1_SB_DQS_DP<9>")
	)
	(segment
		(start 146.62277 -269.178786)
		(end 147.29587 -269.178786)
		(width 0.09525)
		(layer "In6.Cu")
		(net "M_K_CPU1_SB_DQS_DP<9>")
	)
	(segment
		(start 144.678654 -271.17929)
		(end 144.693132 -271.170908)
		(width 0.09525)
		(layer "In6.Cu")
		(net "M_K_CPU1_SB_DQS_DP<9>")
	)
	(segment
		(start 174.836582 -275.149818)
		(end 175.17618 -274.81022)
		(width 0.16002)
		(layer "In6.Cu")
		(net "M_K_CPU1_SB_DQS_DP<9>")
	)
	(segment
		(start 187.943236 -275.660104)
		(end 188.28385 -276.000718)
		(width 0.16002)
		(layer "In6.Cu")
		(net "M_K_CPU1_SB_DQS_DP<9>")
	)
	(segment
		(start 195.207128 -275.38426)
		(end 195.831206 -276.008338)
		(width 0.16002)
		(layer "In6.Cu")
		(net "M_K_CPU1_SB_DQS_DP<9>")
	)
	(arc
		(start 144.882362 -270.846296)
		(mid 144.888416 -270.763748)
		(end 144.906492 -270.682974)
		(width 0.09525)
		(layer "In6.Cu")
		(net "M_K_CPU1_SB_DQS_DP<9>")
	)
	(arc
		(start 143.384524 -271.176242)
		(mid 143.569556 -271.222156)
		(end 143.753332 -271.171416)
		(width 0.09525)
		(layer "In6.Cu")
		(net "M_K_CPU1_SB_DQS_DP<9>")
	)
	(arc
		(start 144.906746 -270.68272)
		(mid 144.974602 -270.544111)
		(end 145.08226 -270.433546)
		(width 0.09525)
		(layer "In6.Cu")
		(net "M_K_CPU1_SB_DQS_DP<9>")
	)
	(arc
		(start 145.083784 -270.432022)
		(mid 145.091015 -270.427057)
		(end 145.098262 -270.422116)
		(width 0.09525)
		(layer "In6.Cu")
		(net "M_K_CPU1_SB_DQS_DP<9>")
	)
	(arc
		(start 142.879572 -271.138396)
		(mid 143.131713 -271.096826)
		(end 143.376142 -271.171416)
		(width 0.09525)
		(layer "In6.Cu")
		(net "M_K_CPU1_SB_DQS_DP<9>")
	)
	(arc
		(start 144.7292 -271.15008)
		(mid 144.841875 -271.016392)
		(end 144.882362 -270.846296)
		(width 0.09525)
		(layer "In6.Cu")
		(net "M_K_CPU1_SB_DQS_DP<9>")
	)
	(arc
		(start 145.283428 -270.29537)
		(mid 145.305925 -270.281314)
		(end 145.329656 -270.269462)
		(width 0.09525)
		(layer "In6.Cu")
		(net "M_K_CPU1_SB_DQS_DP<9>")
	)
	(arc
		(start 143.753332 -271.171416)
		(mid 144.034764 -271.095661)
		(end 144.316196 -271.171416)
		(width 0.09525)
		(layer "In6.Cu")
		(net "M_K_CPU1_SB_DQS_DP<9>")
	)
	(arc
		(start 144.316196 -271.171416)
		(mid 144.495855 -271.221989)
		(end 144.677638 -271.179798)
		(width 0.09525)
		(layer "In6.Cu")
		(net "M_K_CPU1_SB_DQS_DP<9>")
	)
	(segment
		(start 141.217904 -291.64026)
		(end 141.684756 -291.906198)
		(width 0.12954)
		(layer "F.Cu")
		(net "M_K_CPU1_SB_DQS_DP<8>")
	)
	(segment
		(start 147.57146 -295.913302)
		(end 147.57146 -299.870876)
		(width 0.16002)
		(layer "In6.Cu")
		(net "M_K_CPU1_SB_DQS_DP<8>")
	)
	(segment
		(start 192.256664 -314.361322)
		(end 192.736724 -314.361322)
		(width 0.16002)
		(layer "In6.Cu")
		(net "M_K_CPU1_SB_DQS_DP<8>")
	)
	(segment
		(start 160.695386 -312.994802)
		(end 160.94202 -313.241436)
		(width 0.16002)
		(layer "In6.Cu")
		(net "M_K_CPU1_SB_DQS_DP<8>")
	)
	(segment
		(start 185.613294 -314.51042)
		(end 186.46394 -315.361066)
		(width 0.16002)
		(layer "In6.Cu")
		(net "M_K_CPU1_SB_DQS_DP<8>")
	)
	(segment
		(start 190.675514 -314.51042)
		(end 192.107566 -314.51042)
		(width 0.16002)
		(layer "In6.Cu")
		(net "M_K_CPU1_SB_DQS_DP<8>")
	)
	(segment
		(start 144.305528 -291.587174)
		(end 144.315942 -291.581078)
		(width 0.09525)
		(layer "In6.Cu")
		(net "M_K_CPU1_SB_DQS_DP<8>")
	)
	(segment
		(start 159.484314 -312.654442)
		(end 159.908748 -313.078876)
		(width 0.16002)
		(layer "In6.Cu")
		(net "M_K_CPU1_SB_DQS_DP<8>")
	)
	(segment
		(start 162.681158 -314.980574)
		(end 166.12997 -314.980574)
		(width 0.16002)
		(layer "In6.Cu")
		(net "M_K_CPU1_SB_DQS_DP<8>")
	)
	(segment
		(start 166.91737 -314.193174)
		(end 167.726106 -314.193174)
		(width 0.16002)
		(layer "In6.Cu")
		(net "M_K_CPU1_SB_DQS_DP<8>")
	)
	(segment
		(start 175.587406 -314.51042)
		(end 178.06924 -314.51042)
		(width 0.16002)
		(layer "In6.Cu")
		(net "M_K_CPU1_SB_DQS_DP<8>")
	)
	(segment
		(start 182.814214 -314.193174)
		(end 183.13146 -314.51042)
		(width 0.16002)
		(layer "In6.Cu")
		(net "M_K_CPU1_SB_DQS_DP<8>")
	)
	(segment
		(start 160.94202 -313.467496)
		(end 160.857946 -313.55157)
		(width 0.16002)
		(layer "In6.Cu")
		(net "M_K_CPU1_SB_DQS_DP<8>")
	)
	(segment
		(start 188.157612 -314.980574)
		(end 188.762132 -314.980574)
		(width 0.16002)
		(layer "In6.Cu")
		(net "M_K_CPU1_SB_DQS_DP<8>")
	)
	(segment
		(start 158.110682 -310.804306)
		(end 158.110682 -311.28081)
		(width 0.16002)
		(layer "In6.Cu")
		(net "M_K_CPU1_SB_DQS_DP<8>")
	)
	(segment
		(start 157.948122 -310.247538)
		(end 158.194756 -310.494172)
		(width 0.16002)
		(layer "In6.Cu")
		(net "M_K_CPU1_SB_DQS_DP<8>")
	)
	(segment
		(start 147.57146 -299.870876)
		(end 156.821124 -309.12054)
		(width 0.16002)
		(layer "In6.Cu")
		(net "M_K_CPU1_SB_DQS_DP<8>")
	)
	(segment
		(start 156.73705 -309.907178)
		(end 157.161484 -310.331612)
		(width 0.16002)
		(layer "In6.Cu")
		(net "M_K_CPU1_SB_DQS_DP<8>")
	)
	(segment
		(start 178.919378 -315.360558)
		(end 180.233574 -315.360558)
		(width 0.16002)
		(layer "In6.Cu")
		(net "M_K_CPU1_SB_DQS_DP<8>")
	)
	(segment
		(start 141.684756 -291.906198)
		(end 141.530832 -291.640768)
		(width 0.09525)
		(layer "In6.Cu")
		(net "M_K_CPU1_SB_DQS_DP<8>")
	)
	(segment
		(start 158.194756 -310.494172)
		(end 158.194756 -310.720232)
		(width 0.16002)
		(layer "In6.Cu")
		(net "M_K_CPU1_SB_DQS_DP<8>")
	)
	(segment
		(start 142.804896 -291.576252)
		(end 142.813278 -291.581078)
		(width 0.09525)
		(layer "In6.Cu")
		(net "M_K_CPU1_SB_DQS_DP<8>")
	)
	(segment
		(start 144.967706 -292.222682)
		(end 145.611088 -292.866064)
		(width 0.09525)
		(layer "In6.Cu")
		(net "M_K_CPU1_SB_DQS_DP<8>")
	)
	(segment
		(start 192.736724 -314.361322)
		(end 192.829688 -314.454286)
		(width 0.16002)
		(layer "In6.Cu")
		(net "M_K_CPU1_SB_DQS_DP<8>")
	)
	(segment
		(start 146.038824 -293.955216)
		(end 146.218402 -294.134794)
		(width 0.09525)
		(layer "In6.Cu")
		(net "M_K_CPU1_SB_DQS_DP<8>")
	)
	(segment
		(start 158.535116 -311.705244)
		(end 159.01162 -311.705244)
		(width 0.16002)
		(layer "In6.Cu")
		(net "M_K_CPU1_SB_DQS_DP<8>")
	)
	(segment
		(start 144.315942 -291.581078)
		(end 144.324324 -291.576252)
		(width 0.09525)
		(layer "In6.Cu")
		(net "M_K_CPU1_SB_DQS_DP<8>")
	)
	(segment
		(start 161.842958 -314.368434)
		(end 162.069018 -314.368434)
		(width 0.16002)
		(layer "In6.Cu")
		(net "M_K_CPU1_SB_DQS_DP<8>")
	)
	(segment
		(start 159.484314 -312.177938)
		(end 159.484314 -312.654442)
		(width 0.16002)
		(layer "In6.Cu")
		(net "M_K_CPU1_SB_DQS_DP<8>")
	)
	(segment
		(start 168.043352 -314.51042)
		(end 170.525186 -314.51042)
		(width 0.16002)
		(layer "In6.Cu")
		(net "M_K_CPU1_SB_DQS_DP<8>")
	)
	(segment
		(start 159.321754 -311.62117)
		(end 159.568388 -311.867804)
		(width 0.16002)
		(layer "In6.Cu")
		(net "M_K_CPU1_SB_DQS_DP<8>")
	)
	(segment
		(start 141.530832 -291.640768)
		(end 141.553946 -291.554154)
		(width 0.09525)
		(layer "In6.Cu")
		(net "M_K_CPU1_SB_DQS_DP<8>")
	)
	(segment
		(start 173.069504 -314.980574)
		(end 173.674024 -314.980574)
		(width 0.16002)
		(layer "In6.Cu")
		(net "M_K_CPU1_SB_DQS_DP<8>")
	)
	(segment
		(start 156.821124 -309.12054)
		(end 156.821124 -309.3466)
		(width 0.16002)
		(layer "In6.Cu")
		(net "M_K_CPU1_SB_DQS_DP<8>")
	)
	(segment
		(start 192.829688 -314.454286)
		(end 193.37782 -314.454286)
		(width 0.16002)
		(layer "In6.Cu")
		(net "M_K_CPU1_SB_DQS_DP<8>")
	)
	(segment
		(start 157.722062 -310.247538)
		(end 157.948122 -310.247538)
		(width 0.16002)
		(layer "In6.Cu")
		(net "M_K_CPU1_SB_DQS_DP<8>")
	)
	(segment
		(start 180.613558 -314.980574)
		(end 181.218078 -314.980574)
		(width 0.16002)
		(layer "In6.Cu")
		(net "M_K_CPU1_SB_DQS_DP<8>")
	)
	(segment
		(start 181.218078 -314.980574)
		(end 182.005478 -314.193174)
		(width 0.16002)
		(layer "In6.Cu")
		(net "M_K_CPU1_SB_DQS_DP<8>")
	)
	(segment
		(start 147.410932 -295.753536)
		(end 147.57146 -295.913302)
		(width 0.16002)
		(layer "In6.Cu")
		(net "M_K_CPU1_SB_DQS_DP<8>")
	)
	(segment
		(start 167.726106 -314.193174)
		(end 168.043352 -314.51042)
		(width 0.16002)
		(layer "In6.Cu")
		(net "M_K_CPU1_SB_DQS_DP<8>")
	)
	(segment
		(start 187.77712 -315.361066)
		(end 188.157612 -314.980574)
		(width 0.16002)
		(layer "In6.Cu")
		(net "M_K_CPU1_SB_DQS_DP<8>")
	)
	(segment
		(start 157.637988 -310.331612)
		(end 157.722062 -310.247538)
		(width 0.16002)
		(layer "In6.Cu")
		(net "M_K_CPU1_SB_DQS_DP<8>")
	)
	(segment
		(start 156.821124 -309.3466)
		(end 156.73705 -309.430674)
		(width 0.16002)
		(layer "In6.Cu")
		(net "M_K_CPU1_SB_DQS_DP<8>")
	)
	(segment
		(start 160.469326 -312.994802)
		(end 160.695386 -312.994802)
		(width 0.16002)
		(layer "In6.Cu")
		(net "M_K_CPU1_SB_DQS_DP<8>")
	)
	(segment
		(start 161.28238 -314.452508)
		(end 161.758884 -314.452508)
		(width 0.16002)
		(layer "In6.Cu")
		(net "M_K_CPU1_SB_DQS_DP<8>")
	)
	(segment
		(start 192.107566 -314.51042)
		(end 192.256664 -314.361322)
		(width 0.16002)
		(layer "In6.Cu")
		(net "M_K_CPU1_SB_DQS_DP<8>")
	)
	(segment
		(start 182.005478 -314.193174)
		(end 182.814214 -314.193174)
		(width 0.16002)
		(layer "In6.Cu")
		(net "M_K_CPU1_SB_DQS_DP<8>")
	)
	(segment
		(start 158.110682 -311.28081)
		(end 158.535116 -311.705244)
		(width 0.16002)
		(layer "In6.Cu")
		(net "M_K_CPU1_SB_DQS_DP<8>")
	)
	(segment
		(start 159.095694 -311.62117)
		(end 159.321754 -311.62117)
		(width 0.16002)
		(layer "In6.Cu")
		(net "M_K_CPU1_SB_DQS_DP<8>")
	)
	(segment
		(start 145.831814 -293.399464)
		(end 145.832068 -293.39921)
		(width 0.09525)
		(layer "In6.Cu")
		(net "M_K_CPU1_SB_DQS_DP<8>")
	)
	(segment
		(start 143.376142 -291.581078)
		(end 143.384524 -291.576252)
		(width 0.09525)
		(layer "In6.Cu")
		(net "M_K_CPU1_SB_DQS_DP<8>")
	)
	(segment
		(start 159.568388 -311.867804)
		(end 159.568388 -312.093864)
		(width 0.16002)
		(layer "In6.Cu")
		(net "M_K_CPU1_SB_DQS_DP<8>")
	)
	(segment
		(start 160.385252 -313.078876)
		(end 160.469326 -312.994802)
		(width 0.16002)
		(layer "In6.Cu")
		(net "M_K_CPU1_SB_DQS_DP<8>")
	)
	(segment
		(start 146.301968 -294.33647)
		(end 146.301968 -294.561768)
		(width 0.09525)
		(layer "In6.Cu")
		(net "M_K_CPU1_SB_DQS_DP<8>")
	)
	(segment
		(start 183.13146 -314.51042)
		(end 185.613294 -314.51042)
		(width 0.16002)
		(layer "In6.Cu")
		(net "M_K_CPU1_SB_DQS_DP<8>")
	)
	(segment
		(start 180.233574 -315.360558)
		(end 180.613558 -314.980574)
		(width 0.16002)
		(layer "In6.Cu")
		(net "M_K_CPU1_SB_DQS_DP<8>")
	)
	(segment
		(start 190.358268 -314.193174)
		(end 190.675514 -314.51042)
		(width 0.16002)
		(layer "In6.Cu")
		(net "M_K_CPU1_SB_DQS_DP<8>")
	)
	(segment
		(start 171.375324 -315.360558)
		(end 172.68952 -315.360558)
		(width 0.16002)
		(layer "In6.Cu")
		(net "M_K_CPU1_SB_DQS_DP<8>")
	)
	(segment
		(start 160.857946 -314.028074)
		(end 161.28238 -314.452508)
		(width 0.16002)
		(layer "In6.Cu")
		(net "M_K_CPU1_SB_DQS_DP<8>")
	)
	(segment
		(start 173.674024 -314.980574)
		(end 174.461424 -314.193174)
		(width 0.16002)
		(layer "In6.Cu")
		(net "M_K_CPU1_SB_DQS_DP<8>")
	)
	(segment
		(start 147.394168 -295.736772)
		(end 147.410932 -295.753536)
		(width 0.09525)
		(layer "In6.Cu")
		(net "M_K_CPU1_SB_DQS_DP<8>")
	)
	(segment
		(start 186.46394 -315.361066)
		(end 187.77712 -315.361066)
		(width 0.16002)
		(layer "In6.Cu")
		(net "M_K_CPU1_SB_DQS_DP<8>")
	)
	(segment
		(start 178.06924 -314.51042)
		(end 178.919378 -315.360558)
		(width 0.16002)
		(layer "In6.Cu")
		(net "M_K_CPU1_SB_DQS_DP<8>")
	)
	(segment
		(start 161.758884 -314.452508)
		(end 161.842958 -314.368434)
		(width 0.16002)
		(layer "In6.Cu")
		(net "M_K_CPU1_SB_DQS_DP<8>")
	)
	(segment
		(start 170.525186 -314.51042)
		(end 171.375324 -315.360558)
		(width 0.16002)
		(layer "In6.Cu")
		(net "M_K_CPU1_SB_DQS_DP<8>")
	)
	(segment
		(start 157.161484 -310.331612)
		(end 157.637988 -310.331612)
		(width 0.16002)
		(layer "In6.Cu")
		(net "M_K_CPU1_SB_DQS_DP<8>")
	)
	(segment
		(start 188.762132 -314.980574)
		(end 189.549532 -314.193174)
		(width 0.16002)
		(layer "In6.Cu")
		(net "M_K_CPU1_SB_DQS_DP<8>")
	)
	(segment
		(start 146.301968 -294.561768)
		(end 147.394168 -295.653968)
		(width 0.09525)
		(layer "In6.Cu")
		(net "M_K_CPU1_SB_DQS_DP<8>")
	)
	(segment
		(start 159.568388 -312.093864)
		(end 159.484314 -312.177938)
		(width 0.16002)
		(layer "In6.Cu")
		(net "M_K_CPU1_SB_DQS_DP<8>")
	)
	(segment
		(start 145.832068 -293.39921)
		(end 145.832068 -293.456106)
		(width 0.09525)
		(layer "In6.Cu")
		(net "M_K_CPU1_SB_DQS_DP<8>")
	)
	(segment
		(start 158.194756 -310.720232)
		(end 158.110682 -310.804306)
		(width 0.16002)
		(layer "In6.Cu")
		(net "M_K_CPU1_SB_DQS_DP<8>")
	)
	(segment
		(start 162.069018 -314.368434)
		(end 162.681158 -314.980574)
		(width 0.16002)
		(layer "In6.Cu")
		(net "M_K_CPU1_SB_DQS_DP<8>")
	)
	(segment
		(start 194.330066 -314.361322)
		(end 194.604132 -314.635388)
		(width 0.16002)
		(layer "In6.Cu")
		(net "M_K_CPU1_SB_DQS_DP<8>")
	)
	(segment
		(start 174.461424 -314.193174)
		(end 175.27016 -314.193174)
		(width 0.16002)
		(layer "In6.Cu")
		(net "M_K_CPU1_SB_DQS_DP<8>")
	)
	(segment
		(start 160.94202 -313.241436)
		(end 160.94202 -313.467496)
		(width 0.16002)
		(layer "In6.Cu")
		(net "M_K_CPU1_SB_DQS_DP<8>")
	)
	(segment
		(start 159.908748 -313.078876)
		(end 160.385252 -313.078876)
		(width 0.16002)
		(layer "In6.Cu")
		(net "M_K_CPU1_SB_DQS_DP<8>")
	)
	(segment
		(start 189.549532 -314.193174)
		(end 190.358268 -314.193174)
		(width 0.16002)
		(layer "In6.Cu")
		(net "M_K_CPU1_SB_DQS_DP<8>")
	)
	(segment
		(start 193.470784 -314.361322)
		(end 194.330066 -314.361322)
		(width 0.16002)
		(layer "In6.Cu")
		(net "M_K_CPU1_SB_DQS_DP<8>")
	)
	(segment
		(start 156.73705 -309.430674)
		(end 156.73705 -309.907178)
		(width 0.16002)
		(layer "In6.Cu")
		(net "M_K_CPU1_SB_DQS_DP<8>")
	)
	(segment
		(start 159.01162 -311.705244)
		(end 159.095694 -311.62117)
		(width 0.16002)
		(layer "In6.Cu")
		(net "M_K_CPU1_SB_DQS_DP<8>")
	)
	(segment
		(start 166.12997 -314.980574)
		(end 166.91737 -314.193174)
		(width 0.16002)
		(layer "In6.Cu")
		(net "M_K_CPU1_SB_DQS_DP<8>")
	)
	(segment
		(start 172.68952 -315.360558)
		(end 173.069504 -314.980574)
		(width 0.16002)
		(layer "In6.Cu")
		(net "M_K_CPU1_SB_DQS_DP<8>")
	)
	(segment
		(start 175.27016 -314.193174)
		(end 175.587406 -314.51042)
		(width 0.16002)
		(layer "In6.Cu")
		(net "M_K_CPU1_SB_DQS_DP<8>")
	)
	(segment
		(start 193.37782 -314.454286)
		(end 193.470784 -314.361322)
		(width 0.16002)
		(layer "In6.Cu")
		(net "M_K_CPU1_SB_DQS_DP<8>")
	)
	(segment
		(start 160.857946 -313.55157)
		(end 160.857946 -314.028074)
		(width 0.16002)
		(layer "In6.Cu")
		(net "M_K_CPU1_SB_DQS_DP<8>")
	)
	(segment
		(start 147.394168 -295.653968)
		(end 147.394168 -295.736772)
		(width 0.09525)
		(layer "In6.Cu")
		(net "M_K_CPU1_SB_DQS_DP<8>")
	)
	(arc
		(start 143.384524 -291.576252)
		(mid 143.569556 -291.530338)
		(end 143.753332 -291.581078)
		(width 0.09525)
		(layer "In6.Cu")
		(net "M_K_CPU1_SB_DQS_DP<8>")
	)
	(arc
		(start 141.553946 -291.554154)
		(mid 141.716597 -291.531894)
		(end 141.873224 -291.581078)
		(width 0.09525)
		(layer "In6.Cu")
		(net "M_K_CPU1_SB_DQS_DP<8>")
	)
	(arc
		(start 142.813278 -291.581078)
		(mid 143.09471 -291.656833)
		(end 143.376142 -291.581078)
		(width 0.09525)
		(layer "In6.Cu")
		(net "M_K_CPU1_SB_DQS_DP<8>")
	)
	(arc
		(start 145.611088 -292.866064)
		(mid 145.774472 -293.110819)
		(end 145.831814 -293.399464)
		(width 0.09525)
		(layer "In6.Cu")
		(net "M_K_CPU1_SB_DQS_DP<8>")
	)
	(arc
		(start 146.218402 -294.134794)
		(mid 146.280282 -294.227309)
		(end 146.301968 -294.33647)
		(width 0.09525)
		(layer "In6.Cu")
		(net "M_K_CPU1_SB_DQS_DP<8>")
	)
	(arc
		(start 143.753332 -291.581078)
		(mid 144.028621 -291.656799)
		(end 144.305528 -291.587174)
		(width 0.09525)
		(layer "In6.Cu")
		(net "M_K_CPU1_SB_DQS_DP<8>")
	)
	(arc
		(start 145.832068 -293.456106)
		(mid 145.885867 -293.72619)
		(end 146.038824 -293.955216)
		(width 0.09525)
		(layer "In6.Cu")
		(net "M_K_CPU1_SB_DQS_DP<8>")
	)
	(arc
		(start 144.756886 -291.699442)
		(mid 144.804994 -291.984152)
		(end 144.967706 -292.222682)
		(width 0.09525)
		(layer "In6.Cu")
		(net "M_K_CPU1_SB_DQS_DP<8>")
	)
	(arc
		(start 144.324324 -291.576252)
		(mid 144.509102 -291.530459)
		(end 144.692624 -291.581078)
		(width 0.09525)
		(layer "In6.Cu")
		(net "M_K_CPU1_SB_DQS_DP<8>")
	)
	(arc
		(start 144.692624 -291.581078)
		(mid 144.741303 -291.631268)
		(end 144.756886 -291.699442)
		(width 0.09525)
		(layer "In6.Cu")
		(net "M_K_CPU1_SB_DQS_DP<8>")
	)
	(arc
		(start 141.873224 -291.581078)
		(mid 142.154656 -291.656833)
		(end 142.436088 -291.581078)
		(width 0.09525)
		(layer "In6.Cu")
		(net "M_K_CPU1_SB_DQS_DP<8>")
	)
	(arc
		(start 142.436088 -291.581078)
		(mid 142.619863 -291.530306)
		(end 142.804896 -291.576252)
		(width 0.09525)
		(layer "In6.Cu")
		(net "M_K_CPU1_SB_DQS_DP<8>")
	)
	(segment
		(start 141.217904 -286.780478)
		(end 141.684756 -287.046162)
		(width 0.12954)
		(layer "F.Cu")
		(net "M_K_CPU1_SB_DQS_DP<7>")
	)
	(segment
		(start 159.967676 -302.588168)
		(end 160.086294 -302.46955)
		(width 0.16002)
		(layer "In6.Cu")
		(net "M_K_CPU1_SB_DQS_DP<7>")
	)
	(segment
		(start 161.814002 -304.910998)
		(end 162.238436 -305.335432)
		(width 0.16002)
		(layer "In6.Cu")
		(net "M_K_CPU1_SB_DQS_DP<7>")
	)
	(segment
		(start 163.059618 -305.216814)
		(end 163.473384 -305.63058)
		(width 0.16002)
		(layer "In6.Cu")
		(net "M_K_CPU1_SB_DQS_DP<7>")
	)
	(segment
		(start 185.613294 -305.160426)
		(end 186.463432 -306.010564)
		(width 0.16002)
		(layer "In6.Cu")
		(net "M_K_CPU1_SB_DQS_DP<7>")
	)
	(segment
		(start 192.256664 -305.011328)
		(end 192.8622 -305.011328)
		(width 0.16002)
		(layer "In6.Cu")
		(net "M_K_CPU1_SB_DQS_DP<7>")
	)
	(segment
		(start 143.376142 -286.721042)
		(end 143.384524 -286.716216)
		(width 0.09525)
		(layer "In6.Cu")
		(net "M_K_CPU1_SB_DQS_DP<7>")
	)
	(segment
		(start 157.693106 -300.790102)
		(end 158.11754 -301.214536)
		(width 0.16002)
		(layer "In6.Cu")
		(net "M_K_CPU1_SB_DQS_DP<7>")
	)
	(segment
		(start 161.814002 -304.434494)
		(end 161.814002 -304.910998)
		(width 0.16002)
		(layer "In6.Cu")
		(net "M_K_CPU1_SB_DQS_DP<7>")
	)
	(segment
		(start 173.069504 -305.63058)
		(end 173.674024 -305.63058)
		(width 0.16002)
		(layer "In6.Cu")
		(net "M_K_CPU1_SB_DQS_DP<7>")
	)
	(segment
		(start 160.44037 -303.537366)
		(end 160.864804 -303.9618)
		(width 0.16002)
		(layer "In6.Cu")
		(net "M_K_CPU1_SB_DQS_DP<7>")
	)
	(segment
		(start 192.8622 -305.011328)
		(end 192.965578 -305.114706)
		(width 0.16002)
		(layer "In6.Cu")
		(net "M_K_CPU1_SB_DQS_DP<7>")
	)
	(segment
		(start 144.671288 -286.624776)
		(end 145.766536 -286.624776)
		(width 0.09525)
		(layer "In6.Cu")
		(net "M_K_CPU1_SB_DQS_DP<7>")
	)
	(segment
		(start 161.459926 -303.843182)
		(end 161.685986 -303.843182)
		(width 0.16002)
		(layer "In6.Cu")
		(net "M_K_CPU1_SB_DQS_DP<7>")
	)
	(segment
		(start 157.811724 -300.19498)
		(end 157.693106 -300.313598)
		(width 0.16002)
		(layer "In6.Cu")
		(net "M_K_CPU1_SB_DQS_DP<7>")
	)
	(segment
		(start 190.675514 -305.160426)
		(end 192.107566 -305.160426)
		(width 0.16002)
		(layer "In6.Cu")
		(net "M_K_CPU1_SB_DQS_DP<7>")
	)
	(segment
		(start 188.157612 -305.63058)
		(end 188.762132 -305.63058)
		(width 0.16002)
		(layer "In6.Cu")
		(net "M_K_CPU1_SB_DQS_DP<7>")
	)
	(segment
		(start 162.71494 -305.335432)
		(end 162.833558 -305.216814)
		(width 0.16002)
		(layer "In6.Cu")
		(net "M_K_CPU1_SB_DQS_DP<7>")
	)
	(segment
		(start 158.938722 -301.095918)
		(end 159.185356 -301.342552)
		(width 0.16002)
		(layer "In6.Cu")
		(net "M_K_CPU1_SB_DQS_DP<7>")
	)
	(segment
		(start 190.358268 -304.84318)
		(end 190.675514 -305.160426)
		(width 0.16002)
		(layer "In6.Cu")
		(net "M_K_CPU1_SB_DQS_DP<7>")
	)
	(segment
		(start 180.613558 -305.63058)
		(end 181.218078 -305.63058)
		(width 0.16002)
		(layer "In6.Cu")
		(net "M_K_CPU1_SB_DQS_DP<7>")
	)
	(segment
		(start 147.705318 -287.797748)
		(end 153.43505 -293.52748)
		(width 0.16002)
		(layer "In6.Cu")
		(net "M_K_CPU1_SB_DQS_DP<7>")
	)
	(segment
		(start 175.27016 -304.84318)
		(end 175.587406 -305.160426)
		(width 0.16002)
		(layer "In6.Cu")
		(net "M_K_CPU1_SB_DQS_DP<7>")
	)
	(segment
		(start 160.44037 -303.060862)
		(end 160.44037 -303.537366)
		(width 0.16002)
		(layer "In6.Cu")
		(net "M_K_CPU1_SB_DQS_DP<7>")
	)
	(segment
		(start 159.185356 -301.568612)
		(end 159.066738 -301.68723)
		(width 0.16002)
		(layer "In6.Cu")
		(net "M_K_CPU1_SB_DQS_DP<7>")
	)
	(segment
		(start 159.066738 -301.68723)
		(end 159.066738 -302.163734)
		(width 0.16002)
		(layer "In6.Cu")
		(net "M_K_CPU1_SB_DQS_DP<7>")
	)
	(segment
		(start 194.330066 -305.011328)
		(end 194.604132 -305.285394)
		(width 0.16002)
		(layer "In6.Cu")
		(net "M_K_CPU1_SB_DQS_DP<7>")
	)
	(segment
		(start 178.919378 -306.010564)
		(end 180.233574 -306.010564)
		(width 0.16002)
		(layer "In6.Cu")
		(net "M_K_CPU1_SB_DQS_DP<7>")
	)
	(segment
		(start 172.68952 -306.010564)
		(end 173.069504 -305.63058)
		(width 0.16002)
		(layer "In6.Cu")
		(net "M_K_CPU1_SB_DQS_DP<7>")
	)
	(segment
		(start 178.06924 -305.160426)
		(end 178.919378 -306.010564)
		(width 0.16002)
		(layer "In6.Cu")
		(net "M_K_CPU1_SB_DQS_DP<7>")
	)
	(segment
		(start 158.11754 -301.214536)
		(end 158.594044 -301.214536)
		(width 0.16002)
		(layer "In6.Cu")
		(net "M_K_CPU1_SB_DQS_DP<7>")
	)
	(segment
		(start 160.558988 -302.942244)
		(end 160.44037 -303.060862)
		(width 0.16002)
		(layer "In6.Cu")
		(net "M_K_CPU1_SB_DQS_DP<7>")
	)
	(segment
		(start 187.777628 -306.010564)
		(end 188.157612 -305.63058)
		(width 0.16002)
		(layer "In6.Cu")
		(net "M_K_CPU1_SB_DQS_DP<7>")
	)
	(segment
		(start 168.043352 -305.160426)
		(end 170.525186 -305.160426)
		(width 0.16002)
		(layer "In6.Cu")
		(net "M_K_CPU1_SB_DQS_DP<7>")
	)
	(segment
		(start 192.965578 -305.114706)
		(end 193.492882 -305.114706)
		(width 0.16002)
		(layer "In6.Cu")
		(net "M_K_CPU1_SB_DQS_DP<7>")
	)
	(segment
		(start 142.804896 -286.716216)
		(end 142.813278 -286.721042)
		(width 0.09525)
		(layer "In6.Cu")
		(net "M_K_CPU1_SB_DQS_DP<7>")
	)
	(segment
		(start 157.811724 -299.96892)
		(end 157.811724 -300.19498)
		(width 0.16002)
		(layer "In6.Cu")
		(net "M_K_CPU1_SB_DQS_DP<7>")
	)
	(segment
		(start 147.688554 -287.697672)
		(end 147.688554 -287.780984)
		(width 0.09525)
		(layer "In6.Cu")
		(net "M_K_CPU1_SB_DQS_DP<7>")
	)
	(segment
		(start 181.218078 -305.63058)
		(end 182.005478 -304.84318)
		(width 0.16002)
		(layer "In6.Cu")
		(net "M_K_CPU1_SB_DQS_DP<7>")
	)
	(segment
		(start 182.814214 -304.84318)
		(end 183.13146 -305.160426)
		(width 0.16002)
		(layer "In6.Cu")
		(net "M_K_CPU1_SB_DQS_DP<7>")
	)
	(segment
		(start 145.766536 -286.624776)
		(end 146.353276 -287.211516)
		(width 0.09525)
		(layer "In6.Cu")
		(net "M_K_CPU1_SB_DQS_DP<7>")
	)
	(segment
		(start 161.93262 -304.089816)
		(end 161.93262 -304.315876)
		(width 0.16002)
		(layer "In6.Cu")
		(net "M_K_CPU1_SB_DQS_DP<7>")
	)
	(segment
		(start 159.066738 -302.163734)
		(end 159.491172 -302.588168)
		(width 0.16002)
		(layer "In6.Cu")
		(net "M_K_CPU1_SB_DQS_DP<7>")
	)
	(segment
		(start 141.530832 -286.780732)
		(end 141.553946 -286.694118)
		(width 0.09525)
		(layer "In6.Cu")
		(net "M_K_CPU1_SB_DQS_DP<7>")
	)
	(segment
		(start 182.005478 -304.84318)
		(end 182.814214 -304.84318)
		(width 0.16002)
		(layer "In6.Cu")
		(net "M_K_CPU1_SB_DQS_DP<7>")
	)
	(segment
		(start 159.185356 -301.342552)
		(end 159.185356 -301.568612)
		(width 0.16002)
		(layer "In6.Cu")
		(net "M_K_CPU1_SB_DQS_DP<7>")
	)
	(segment
		(start 193.492882 -305.114706)
		(end 193.59626 -305.011328)
		(width 0.16002)
		(layer "In6.Cu")
		(net "M_K_CPU1_SB_DQS_DP<7>")
	)
	(segment
		(start 160.312354 -302.46955)
		(end 160.558988 -302.716184)
		(width 0.16002)
		(layer "In6.Cu")
		(net "M_K_CPU1_SB_DQS_DP<7>")
	)
	(segment
		(start 156.54909 -299.846746)
		(end 157.68955 -299.846746)
		(width 0.16002)
		(layer "In6.Cu")
		(net "M_K_CPU1_SB_DQS_DP<7>")
	)
	(segment
		(start 180.233574 -306.010564)
		(end 180.613558 -305.63058)
		(width 0.16002)
		(layer "In6.Cu")
		(net "M_K_CPU1_SB_DQS_DP<7>")
	)
	(segment
		(start 160.558988 -302.716184)
		(end 160.558988 -302.942244)
		(width 0.16002)
		(layer "In6.Cu")
		(net "M_K_CPU1_SB_DQS_DP<7>")
	)
	(segment
		(start 160.864804 -303.9618)
		(end 161.341308 -303.9618)
		(width 0.16002)
		(layer "In6.Cu")
		(net "M_K_CPU1_SB_DQS_DP<7>")
	)
	(segment
		(start 193.59626 -305.011328)
		(end 194.330066 -305.011328)
		(width 0.16002)
		(layer "In6.Cu")
		(net "M_K_CPU1_SB_DQS_DP<7>")
	)
	(segment
		(start 141.684756 -287.046162)
		(end 141.530832 -286.780732)
		(width 0.09525)
		(layer "In6.Cu")
		(net "M_K_CPU1_SB_DQS_DP<7>")
	)
	(segment
		(start 161.341308 -303.9618)
		(end 161.459926 -303.843182)
		(width 0.16002)
		(layer "In6.Cu")
		(net "M_K_CPU1_SB_DQS_DP<7>")
	)
	(segment
		(start 147.202398 -287.211516)
		(end 147.688554 -287.697672)
		(width 0.09525)
		(layer "In6.Cu")
		(net "M_K_CPU1_SB_DQS_DP<7>")
	)
	(segment
		(start 170.525186 -305.160426)
		(end 171.375324 -306.010564)
		(width 0.16002)
		(layer "In6.Cu")
		(net "M_K_CPU1_SB_DQS_DP<7>")
	)
	(segment
		(start 171.375324 -306.010564)
		(end 172.68952 -306.010564)
		(width 0.16002)
		(layer "In6.Cu")
		(net "M_K_CPU1_SB_DQS_DP<7>")
	)
	(segment
		(start 159.491172 -302.588168)
		(end 159.967676 -302.588168)
		(width 0.16002)
		(layer "In6.Cu")
		(net "M_K_CPU1_SB_DQS_DP<7>")
	)
	(segment
		(start 160.086294 -302.46955)
		(end 160.312354 -302.46955)
		(width 0.16002)
		(layer "In6.Cu")
		(net "M_K_CPU1_SB_DQS_DP<7>")
	)
	(segment
		(start 167.726106 -304.84318)
		(end 168.043352 -305.160426)
		(width 0.16002)
		(layer "In6.Cu")
		(net "M_K_CPU1_SB_DQS_DP<7>")
	)
	(segment
		(start 161.685986 -303.843182)
		(end 161.93262 -304.089816)
		(width 0.16002)
		(layer "In6.Cu")
		(net "M_K_CPU1_SB_DQS_DP<7>")
	)
	(segment
		(start 175.587406 -305.160426)
		(end 178.06924 -305.160426)
		(width 0.16002)
		(layer "In6.Cu")
		(net "M_K_CPU1_SB_DQS_DP<7>")
	)
	(segment
		(start 161.93262 -304.315876)
		(end 161.814002 -304.434494)
		(width 0.16002)
		(layer "In6.Cu")
		(net "M_K_CPU1_SB_DQS_DP<7>")
	)
	(segment
		(start 189.549532 -304.84318)
		(end 190.358268 -304.84318)
		(width 0.16002)
		(layer "In6.Cu")
		(net "M_K_CPU1_SB_DQS_DP<7>")
	)
	(segment
		(start 146.353276 -287.211516)
		(end 147.202398 -287.211516)
		(width 0.09525)
		(layer "In6.Cu")
		(net "M_K_CPU1_SB_DQS_DP<7>")
	)
	(segment
		(start 186.463432 -306.010564)
		(end 187.777628 -306.010564)
		(width 0.16002)
		(layer "In6.Cu")
		(net "M_K_CPU1_SB_DQS_DP<7>")
	)
	(segment
		(start 173.674024 -305.63058)
		(end 174.461424 -304.84318)
		(width 0.16002)
		(layer "In6.Cu")
		(net "M_K_CPU1_SB_DQS_DP<7>")
	)
	(segment
		(start 158.712662 -301.095918)
		(end 158.938722 -301.095918)
		(width 0.16002)
		(layer "In6.Cu")
		(net "M_K_CPU1_SB_DQS_DP<7>")
	)
	(segment
		(start 162.833558 -305.216814)
		(end 163.059618 -305.216814)
		(width 0.16002)
		(layer "In6.Cu")
		(net "M_K_CPU1_SB_DQS_DP<7>")
	)
	(segment
		(start 153.43505 -296.732706)
		(end 156.54909 -299.846746)
		(width 0.16002)
		(layer "In6.Cu")
		(net "M_K_CPU1_SB_DQS_DP<7>")
	)
	(segment
		(start 183.13146 -305.160426)
		(end 185.613294 -305.160426)
		(width 0.16002)
		(layer "In6.Cu")
		(net "M_K_CPU1_SB_DQS_DP<7>")
	)
	(segment
		(start 174.461424 -304.84318)
		(end 175.27016 -304.84318)
		(width 0.16002)
		(layer "In6.Cu")
		(net "M_K_CPU1_SB_DQS_DP<7>")
	)
	(segment
		(start 162.238436 -305.335432)
		(end 162.71494 -305.335432)
		(width 0.16002)
		(layer "In6.Cu")
		(net "M_K_CPU1_SB_DQS_DP<7>")
	)
	(segment
		(start 163.473384 -305.63058)
		(end 166.12997 -305.63058)
		(width 0.16002)
		(layer "In6.Cu")
		(net "M_K_CPU1_SB_DQS_DP<7>")
	)
	(segment
		(start 147.688554 -287.780984)
		(end 147.705318 -287.797748)
		(width 0.09525)
		(layer "In6.Cu")
		(net "M_K_CPU1_SB_DQS_DP<7>")
	)
	(segment
		(start 188.762132 -305.63058)
		(end 189.549532 -304.84318)
		(width 0.16002)
		(layer "In6.Cu")
		(net "M_K_CPU1_SB_DQS_DP<7>")
	)
	(segment
		(start 143.753332 -286.721042)
		(end 143.762222 -286.726376)
		(width 0.09525)
		(layer "In6.Cu")
		(net "M_K_CPU1_SB_DQS_DP<7>")
	)
	(segment
		(start 157.693106 -300.313598)
		(end 157.693106 -300.790102)
		(width 0.16002)
		(layer "In6.Cu")
		(net "M_K_CPU1_SB_DQS_DP<7>")
	)
	(segment
		(start 158.594044 -301.214536)
		(end 158.712662 -301.095918)
		(width 0.16002)
		(layer "In6.Cu")
		(net "M_K_CPU1_SB_DQS_DP<7>")
	)
	(segment
		(start 157.68955 -299.846746)
		(end 157.811724 -299.96892)
		(width 0.16002)
		(layer "In6.Cu")
		(net "M_K_CPU1_SB_DQS_DP<7>")
	)
	(segment
		(start 166.91737 -304.84318)
		(end 167.726106 -304.84318)
		(width 0.16002)
		(layer "In6.Cu")
		(net "M_K_CPU1_SB_DQS_DP<7>")
	)
	(segment
		(start 153.43505 -293.52748)
		(end 153.43505 -296.732706)
		(width 0.16002)
		(layer "In6.Cu")
		(net "M_K_CPU1_SB_DQS_DP<7>")
	)
	(segment
		(start 166.12997 -305.63058)
		(end 166.91737 -304.84318)
		(width 0.16002)
		(layer "In6.Cu")
		(net "M_K_CPU1_SB_DQS_DP<7>")
	)
	(segment
		(start 192.107566 -305.160426)
		(end 192.256664 -305.011328)
		(width 0.16002)
		(layer "In6.Cu")
		(net "M_K_CPU1_SB_DQS_DP<7>")
	)
	(arc
		(start 141.873224 -286.721042)
		(mid 142.154656 -286.796831)
		(end 142.436088 -286.721042)
		(width 0.09525)
		(layer "In6.Cu")
		(net "M_K_CPU1_SB_DQS_DP<7>")
	)
	(arc
		(start 143.762222 -286.726376)
		(mid 144.025703 -286.796883)
		(end 144.291304 -286.734758)
		(width 0.09525)
		(layer "In6.Cu")
		(net "M_K_CPU1_SB_DQS_DP<7>")
	)
	(arc
		(start 144.315942 -286.721296)
		(mid 144.317337 -286.720531)
		(end 144.318736 -286.719772)
		(width 0.09525)
		(layer "In6.Cu")
		(net "M_K_CPU1_SB_DQS_DP<7>")
	)
	(arc
		(start 141.553946 -286.694118)
		(mid 141.716597 -286.671858)
		(end 141.873224 -286.721042)
		(width 0.09525)
		(layer "In6.Cu")
		(net "M_K_CPU1_SB_DQS_DP<7>")
	)
	(arc
		(start 142.813278 -286.721042)
		(mid 143.09471 -286.796831)
		(end 143.376142 -286.721042)
		(width 0.09525)
		(layer "In6.Cu")
		(net "M_K_CPU1_SB_DQS_DP<7>")
	)
	(arc
		(start 144.291304 -286.734758)
		(mid 144.303709 -286.728184)
		(end 144.315942 -286.721296)
		(width 0.09525)
		(layer "In6.Cu")
		(net "M_K_CPU1_SB_DQS_DP<7>")
	)
	(arc
		(start 142.436088 -286.721042)
		(mid 142.619863 -286.67027)
		(end 142.804896 -286.716216)
		(width 0.09525)
		(layer "In6.Cu")
		(net "M_K_CPU1_SB_DQS_DP<7>")
	)
	(arc
		(start 144.318482 -286.71901)
		(mid 144.488722 -286.648826)
		(end 144.671288 -286.624776)
		(width 0.09525)
		(layer "In6.Cu")
		(net "M_K_CPU1_SB_DQS_DP<7>")
	)
	(arc
		(start 143.384524 -286.716216)
		(mid 143.569556 -286.670302)
		(end 143.753332 -286.721042)
		(width 0.09525)
		(layer "In6.Cu")
		(net "M_K_CPU1_SB_DQS_DP<7>")
	)
	(arc
		(start 144.318736 -286.719772)
		(mid 144.318608 -286.719391)
		(end 144.318482 -286.71901)
		(width 0.09525)
		(layer "In6.Cu")
		(net "M_K_CPU1_SB_DQS_DP<7>")
	)
	(segment
		(start 141.217904 -281.920442)
		(end 141.684756 -282.18638)
		(width 0.12954)
		(layer "F.Cu")
		(net "M_K_CPU1_SB_DQS_DP<6>")
	)
	(segment
		(start 166.12997 -296.280586)
		(end 166.91737 -295.493186)
		(width 0.16002)
		(layer "In6.Cu")
		(net "M_K_CPU1_SB_DQS_DP<6>")
	)
	(segment
		(start 144.692624 -281.86126)
		(end 144.693132 -281.86126)
		(width 0.09525)
		(layer "In6.Cu")
		(net "M_K_CPU1_SB_DQS_DP<6>")
	)
	(segment
		(start 168.29024 -295.653206)
		(end 168.29024 -295.819068)
		(width 0.16002)
		(layer "In6.Cu")
		(net "M_K_CPU1_SB_DQS_DP<6>")
	)
	(segment
		(start 161.668714 -294.488616)
		(end 162.092386 -294.912288)
		(width 0.16002)
		(layer "In6.Cu")
		(net "M_K_CPU1_SB_DQS_DP<6>")
	)
	(segment
		(start 168.13022 -295.493186)
		(end 168.29024 -295.653206)
		(width 0.16002)
		(layer "In6.Cu")
		(net "M_K_CPU1_SB_DQS_DP<6>")
	)
	(segment
		(start 147.919186 -282.120594)
		(end 150.272496 -282.120594)
		(width 0.16002)
		(layer "In6.Cu")
		(net "M_K_CPU1_SB_DQS_DP<6>")
	)
	(segment
		(start 142.804896 -281.856434)
		(end 142.813278 -281.86126)
		(width 0.09525)
		(layer "In6.Cu")
		(net "M_K_CPU1_SB_DQS_DP<6>")
	)
	(segment
		(start 164.077142 -296.1513)
		(end 164.303202 -296.1513)
		(width 0.16002)
		(layer "In6.Cu")
		(net "M_K_CPU1_SB_DQS_DP<6>")
	)
	(segment
		(start 193.61404 -295.661334)
		(end 194.330066 -295.661334)
		(width 0.16002)
		(layer "In6.Cu")
		(net "M_K_CPU1_SB_DQS_DP<6>")
	)
	(segment
		(start 180.613558 -296.280586)
		(end 181.218078 -296.280586)
		(width 0.16002)
		(layer "In6.Cu")
		(net "M_K_CPU1_SB_DQS_DP<6>")
	)
	(segment
		(start 178.919378 -296.66057)
		(end 180.233574 -296.66057)
		(width 0.16002)
		(layer "In6.Cu")
		(net "M_K_CPU1_SB_DQS_DP<6>")
	)
	(segment
		(start 163.042346 -295.385744)
		(end 163.042346 -295.862248)
		(width 0.16002)
		(layer "In6.Cu")
		(net "M_K_CPU1_SB_DQS_DP<6>")
	)
	(segment
		(start 190.358268 -295.493186)
		(end 190.675514 -295.810432)
		(width 0.16002)
		(layer "In6.Cu")
		(net "M_K_CPU1_SB_DQS_DP<6>")
	)
	(segment
		(start 146.576542 -281.834082)
		(end 146.804126 -282.061666)
		(width 0.09525)
		(layer "In6.Cu")
		(net "M_K_CPU1_SB_DQS_DP<6>")
	)
	(segment
		(start 187.777628 -296.66057)
		(end 188.157612 -296.280586)
		(width 0.16002)
		(layer "In6.Cu")
		(net "M_K_CPU1_SB_DQS_DP<6>")
	)
	(segment
		(start 162.70351 -294.777668)
		(end 162.92957 -294.777668)
		(width 0.16002)
		(layer "In6.Cu")
		(net "M_K_CPU1_SB_DQS_DP<6>")
	)
	(segment
		(start 194.330066 -295.661334)
		(end 194.604132 -295.9354)
		(width 0.16002)
		(layer "In6.Cu")
		(net "M_K_CPU1_SB_DQS_DP<6>")
	)
	(segment
		(start 188.157612 -296.280586)
		(end 188.762132 -296.280586)
		(width 0.16002)
		(layer "In6.Cu")
		(net "M_K_CPU1_SB_DQS_DP<6>")
	)
	(segment
		(start 192.87998 -295.661334)
		(end 193.00698 -295.788334)
		(width 0.16002)
		(layer "In6.Cu")
		(net "M_K_CPU1_SB_DQS_DP<6>")
	)
	(segment
		(start 170.20794 -295.493186)
		(end 171.375324 -296.66057)
		(width 0.16002)
		(layer "In6.Cu")
		(net "M_K_CPU1_SB_DQS_DP<6>")
	)
	(segment
		(start 144.305528 -281.867356)
		(end 144.315942 -281.86126)
		(width 0.09525)
		(layer "In6.Cu")
		(net "M_K_CPU1_SB_DQS_DP<6>")
	)
	(segment
		(start 144.693132 -281.86126)
		(end 144.708118 -281.869388)
		(width 0.09525)
		(layer "In6.Cu")
		(net "M_K_CPU1_SB_DQS_DP<6>")
	)
	(segment
		(start 168.29024 -295.819068)
		(end 168.627298 -296.156126)
		(width 0.16002)
		(layer "In6.Cu")
		(net "M_K_CPU1_SB_DQS_DP<6>")
	)
	(segment
		(start 193.00698 -295.788334)
		(end 193.48704 -295.788334)
		(width 0.16002)
		(layer "In6.Cu")
		(net "M_K_CPU1_SB_DQS_DP<6>")
	)
	(segment
		(start 172.68952 -296.66057)
		(end 173.069504 -296.280586)
		(width 0.16002)
		(layer "In6.Cu")
		(net "M_K_CPU1_SB_DQS_DP<6>")
	)
	(segment
		(start 186.463432 -296.66057)
		(end 187.777628 -296.66057)
		(width 0.16002)
		(layer "In6.Cu")
		(net "M_K_CPU1_SB_DQS_DP<6>")
	)
	(segment
		(start 175.27016 -295.493186)
		(end 175.587406 -295.810432)
		(width 0.16002)
		(layer "In6.Cu")
		(net "M_K_CPU1_SB_DQS_DP<6>")
	)
	(segment
		(start 169.225976 -296.156126)
		(end 169.563034 -295.819068)
		(width 0.16002)
		(layer "In6.Cu")
		(net "M_K_CPU1_SB_DQS_DP<6>")
	)
	(segment
		(start 183.13146 -295.810432)
		(end 185.613294 -295.810432)
		(width 0.16002)
		(layer "In6.Cu")
		(net "M_K_CPU1_SB_DQS_DP<6>")
	)
	(segment
		(start 161.668714 -294.012112)
		(end 161.668714 -294.488616)
		(width 0.16002)
		(layer "In6.Cu")
		(net "M_K_CPU1_SB_DQS_DP<6>")
	)
	(segment
		(start 163.042346 -295.862248)
		(end 163.466018 -296.28592)
		(width 0.16002)
		(layer "In6.Cu")
		(net "M_K_CPU1_SB_DQS_DP<6>")
	)
	(segment
		(start 162.56889 -294.912288)
		(end 162.70351 -294.777668)
		(width 0.16002)
		(layer "In6.Cu")
		(net "M_K_CPU1_SB_DQS_DP<6>")
	)
	(segment
		(start 190.675514 -295.810432)
		(end 192.107566 -295.810432)
		(width 0.16002)
		(layer "In6.Cu")
		(net "M_K_CPU1_SB_DQS_DP<6>")
	)
	(segment
		(start 164.432488 -296.280586)
		(end 166.12997 -296.280586)
		(width 0.16002)
		(layer "In6.Cu")
		(net "M_K_CPU1_SB_DQS_DP<6>")
	)
	(segment
		(start 169.563034 -295.819068)
		(end 169.563034 -295.653206)
		(width 0.16002)
		(layer "In6.Cu")
		(net "M_K_CPU1_SB_DQS_DP<6>")
	)
	(segment
		(start 173.674024 -296.280586)
		(end 174.461424 -295.493186)
		(width 0.16002)
		(layer "In6.Cu")
		(net "M_K_CPU1_SB_DQS_DP<6>")
	)
	(segment
		(start 182.005478 -295.493186)
		(end 182.814214 -295.493186)
		(width 0.16002)
		(layer "In6.Cu")
		(net "M_K_CPU1_SB_DQS_DP<6>")
	)
	(segment
		(start 178.06924 -295.810432)
		(end 178.919378 -296.66057)
		(width 0.16002)
		(layer "In6.Cu")
		(net "M_K_CPU1_SB_DQS_DP<6>")
	)
	(segment
		(start 141.684756 -282.18638)
		(end 141.530832 -281.92095)
		(width 0.09525)
		(layer "In6.Cu")
		(net "M_K_CPU1_SB_DQS_DP<6>")
	)
	(segment
		(start 161.803334 -293.651432)
		(end 161.803334 -293.877492)
		(width 0.16002)
		(layer "In6.Cu")
		(net "M_K_CPU1_SB_DQS_DP<6>")
	)
	(segment
		(start 146.804126 -282.061666)
		(end 147.836636 -282.061666)
		(width 0.09525)
		(layer "In6.Cu")
		(net "M_K_CPU1_SB_DQS_DP<6>")
	)
	(segment
		(start 175.587406 -295.810432)
		(end 178.06924 -295.810432)
		(width 0.16002)
		(layer "In6.Cu")
		(net "M_K_CPU1_SB_DQS_DP<6>")
	)
	(segment
		(start 169.723054 -295.493186)
		(end 170.20794 -295.493186)
		(width 0.16002)
		(layer "In6.Cu")
		(net "M_K_CPU1_SB_DQS_DP<6>")
	)
	(segment
		(start 150.272496 -282.120594)
		(end 161.803334 -293.651432)
		(width 0.16002)
		(layer "In6.Cu")
		(net "M_K_CPU1_SB_DQS_DP<6>")
	)
	(segment
		(start 193.48704 -295.788334)
		(end 193.61404 -295.661334)
		(width 0.16002)
		(layer "In6.Cu")
		(net "M_K_CPU1_SB_DQS_DP<6>")
	)
	(segment
		(start 164.303202 -296.1513)
		(end 164.432488 -296.280586)
		(width 0.16002)
		(layer "In6.Cu")
		(net "M_K_CPU1_SB_DQS_DP<6>")
	)
	(segment
		(start 162.92957 -294.777668)
		(end 163.176966 -295.025064)
		(width 0.16002)
		(layer "In6.Cu")
		(net "M_K_CPU1_SB_DQS_DP<6>")
	)
	(segment
		(start 174.461424 -295.493186)
		(end 175.27016 -295.493186)
		(width 0.16002)
		(layer "In6.Cu")
		(net "M_K_CPU1_SB_DQS_DP<6>")
	)
	(segment
		(start 188.762132 -296.280586)
		(end 189.549532 -295.493186)
		(width 0.16002)
		(layer "In6.Cu")
		(net "M_K_CPU1_SB_DQS_DP<6>")
	)
	(segment
		(start 146.500596 -281.802586)
		(end 146.576542 -281.834082)
		(width 0.09525)
		(layer "In6.Cu")
		(net "M_K_CPU1_SB_DQS_DP<6>")
	)
	(segment
		(start 163.942522 -296.28592)
		(end 164.077142 -296.1513)
		(width 0.16002)
		(layer "In6.Cu")
		(net "M_K_CPU1_SB_DQS_DP<6>")
	)
	(segment
		(start 180.233574 -296.66057)
		(end 180.613558 -296.280586)
		(width 0.16002)
		(layer "In6.Cu")
		(net "M_K_CPU1_SB_DQS_DP<6>")
	)
	(segment
		(start 192.107566 -295.810432)
		(end 192.256664 -295.661334)
		(width 0.16002)
		(layer "In6.Cu")
		(net "M_K_CPU1_SB_DQS_DP<6>")
	)
	(segment
		(start 168.627298 -296.156126)
		(end 169.225976 -296.156126)
		(width 0.16002)
		(layer "In6.Cu")
		(net "M_K_CPU1_SB_DQS_DP<6>")
	)
	(segment
		(start 144.315942 -281.86126)
		(end 144.324324 -281.856434)
		(width 0.09525)
		(layer "In6.Cu")
		(net "M_K_CPU1_SB_DQS_DP<6>")
	)
	(segment
		(start 192.256664 -295.661334)
		(end 192.87998 -295.661334)
		(width 0.16002)
		(layer "In6.Cu")
		(net "M_K_CPU1_SB_DQS_DP<6>")
	)
	(segment
		(start 141.530832 -281.92095)
		(end 141.553946 -281.834336)
		(width 0.09525)
		(layer "In6.Cu")
		(net "M_K_CPU1_SB_DQS_DP<6>")
	)
	(segment
		(start 166.91737 -295.493186)
		(end 168.13022 -295.493186)
		(width 0.16002)
		(layer "In6.Cu")
		(net "M_K_CPU1_SB_DQS_DP<6>")
	)
	(segment
		(start 163.466018 -296.28592)
		(end 163.942522 -296.28592)
		(width 0.16002)
		(layer "In6.Cu")
		(net "M_K_CPU1_SB_DQS_DP<6>")
	)
	(segment
		(start 143.376142 -281.86126)
		(end 143.384524 -281.856434)
		(width 0.09525)
		(layer "In6.Cu")
		(net "M_K_CPU1_SB_DQS_DP<6>")
	)
	(segment
		(start 163.176966 -295.025064)
		(end 163.176966 -295.251124)
		(width 0.16002)
		(layer "In6.Cu")
		(net "M_K_CPU1_SB_DQS_DP<6>")
	)
	(segment
		(start 162.092386 -294.912288)
		(end 162.56889 -294.912288)
		(width 0.16002)
		(layer "In6.Cu")
		(net "M_K_CPU1_SB_DQS_DP<6>")
	)
	(segment
		(start 173.069504 -296.280586)
		(end 173.674024 -296.280586)
		(width 0.16002)
		(layer "In6.Cu")
		(net "M_K_CPU1_SB_DQS_DP<6>")
	)
	(segment
		(start 185.613294 -295.810432)
		(end 186.463432 -296.66057)
		(width 0.16002)
		(layer "In6.Cu")
		(net "M_K_CPU1_SB_DQS_DP<6>")
	)
	(segment
		(start 169.563034 -295.653206)
		(end 169.723054 -295.493186)
		(width 0.16002)
		(layer "In6.Cu")
		(net "M_K_CPU1_SB_DQS_DP<6>")
	)
	(segment
		(start 171.375324 -296.66057)
		(end 172.68952 -296.66057)
		(width 0.16002)
		(layer "In6.Cu")
		(net "M_K_CPU1_SB_DQS_DP<6>")
	)
	(segment
		(start 181.218078 -296.280586)
		(end 182.005478 -295.493186)
		(width 0.16002)
		(layer "In6.Cu")
		(net "M_K_CPU1_SB_DQS_DP<6>")
	)
	(segment
		(start 145.243804 -281.86761)
		(end 145.400522 -281.802586)
		(width 0.09525)
		(layer "In6.Cu")
		(net "M_K_CPU1_SB_DQS_DP<6>")
	)
	(segment
		(start 147.895564 -282.120594)
		(end 147.919186 -282.120594)
		(width 0.09525)
		(layer "In6.Cu")
		(net "M_K_CPU1_SB_DQS_DP<6>")
	)
	(segment
		(start 145.400522 -281.802586)
		(end 146.500596 -281.802586)
		(width 0.09525)
		(layer "In6.Cu")
		(net "M_K_CPU1_SB_DQS_DP<6>")
	)
	(segment
		(start 161.803334 -293.877492)
		(end 161.668714 -294.012112)
		(width 0.16002)
		(layer "In6.Cu")
		(net "M_K_CPU1_SB_DQS_DP<6>")
	)
	(segment
		(start 189.549532 -295.493186)
		(end 190.358268 -295.493186)
		(width 0.16002)
		(layer "In6.Cu")
		(net "M_K_CPU1_SB_DQS_DP<6>")
	)
	(segment
		(start 163.176966 -295.251124)
		(end 163.042346 -295.385744)
		(width 0.16002)
		(layer "In6.Cu")
		(net "M_K_CPU1_SB_DQS_DP<6>")
	)
	(segment
		(start 147.836636 -282.061666)
		(end 147.895564 -282.120594)
		(width 0.09525)
		(layer "In6.Cu")
		(net "M_K_CPU1_SB_DQS_DP<6>")
	)
	(segment
		(start 182.814214 -295.493186)
		(end 183.13146 -295.810432)
		(width 0.16002)
		(layer "In6.Cu")
		(net "M_K_CPU1_SB_DQS_DP<6>")
	)
	(arc
		(start 141.873224 -281.86126)
		(mid 142.154656 -281.937015)
		(end 142.436088 -281.86126)
		(width 0.09525)
		(layer "In6.Cu")
		(net "M_K_CPU1_SB_DQS_DP<6>")
	)
	(arc
		(start 144.324324 -281.856434)
		(mid 144.509102 -281.810641)
		(end 144.692624 -281.86126)
		(width 0.09525)
		(layer "In6.Cu")
		(net "M_K_CPU1_SB_DQS_DP<6>")
	)
	(arc
		(start 142.436088 -281.86126)
		(mid 142.619863 -281.810488)
		(end 142.804896 -281.856434)
		(width 0.09525)
		(layer "In6.Cu")
		(net "M_K_CPU1_SB_DQS_DP<6>")
	)
	(arc
		(start 141.553946 -281.834336)
		(mid 141.716597 -281.812076)
		(end 141.873224 -281.86126)
		(width 0.09525)
		(layer "In6.Cu")
		(net "M_K_CPU1_SB_DQS_DP<6>")
	)
	(arc
		(start 144.708118 -281.869388)
		(mid 144.976185 -281.936657)
		(end 145.243804 -281.86761)
		(width 0.09525)
		(layer "In6.Cu")
		(net "M_K_CPU1_SB_DQS_DP<6>")
	)
	(arc
		(start 143.384524 -281.856434)
		(mid 143.569556 -281.81052)
		(end 143.753332 -281.86126)
		(width 0.09525)
		(layer "In6.Cu")
		(net "M_K_CPU1_SB_DQS_DP<6>")
	)
	(arc
		(start 143.753332 -281.86126)
		(mid 144.028621 -281.936981)
		(end 144.305528 -281.867356)
		(width 0.09525)
		(layer "In6.Cu")
		(net "M_K_CPU1_SB_DQS_DP<6>")
	)
	(arc
		(start 142.813278 -281.86126)
		(mid 143.09471 -281.937015)
		(end 143.376142 -281.86126)
		(width 0.09525)
		(layer "In6.Cu")
		(net "M_K_CPU1_SB_DQS_DP<6>")
	)
	(segment
		(start 141.217904 -277.060406)
		(end 141.684756 -277.326344)
		(width 0.12954)
		(layer "F.Cu")
		(net "M_K_CPU1_SB_DQS_DP<5>")
	)
	(segment
		(start 168.424352 -285.497778)
		(end 168.584372 -285.657798)
		(width 0.16002)
		(layer "In6.Cu")
		(net "M_K_CPU1_SB_DQS_DP<5>")
	)
	(segment
		(start 144.315942 -277.001224)
		(end 144.324324 -276.996398)
		(width 0.09525)
		(layer "In6.Cu")
		(net "M_K_CPU1_SB_DQS_DP<5>")
	)
	(segment
		(start 192.256664 -286.31134)
		(end 192.89014 -286.31134)
		(width 0.16002)
		(layer "In6.Cu")
		(net "M_K_CPU1_SB_DQS_DP<5>")
	)
	(segment
		(start 170.017186 -286.143192)
		(end 170.20794 -286.143192)
		(width 0.16002)
		(layer "In6.Cu")
		(net "M_K_CPU1_SB_DQS_DP<5>")
	)
	(segment
		(start 185.613294 -286.460438)
		(end 186.463432 -287.310576)
		(width 0.16002)
		(layer "In6.Cu")
		(net "M_K_CPU1_SB_DQS_DP<5>")
	)
	(segment
		(start 152.972262 -276.11832)
		(end 163.784534 -286.930592)
		(width 0.16002)
		(layer "In6.Cu")
		(net "M_K_CPU1_SB_DQS_DP<5>")
	)
	(segment
		(start 189.549532 -286.143192)
		(end 190.358268 -286.143192)
		(width 0.16002)
		(layer "In6.Cu")
		(net "M_K_CPU1_SB_DQS_DP<5>")
	)
	(segment
		(start 188.762132 -286.930592)
		(end 189.549532 -286.143192)
		(width 0.16002)
		(layer "In6.Cu")
		(net "M_K_CPU1_SB_DQS_DP<5>")
	)
	(segment
		(start 145.37055 -276.912832)
		(end 145.411444 -276.871938)
		(width 0.09525)
		(layer "In6.Cu")
		(net "M_K_CPU1_SB_DQS_DP<5>")
	)
	(segment
		(start 168.584372 -286.451548)
		(end 168.92143 -286.788606)
		(width 0.16002)
		(layer "In6.Cu")
		(net "M_K_CPU1_SB_DQS_DP<5>")
	)
	(segment
		(start 142.804896 -276.996398)
		(end 142.813278 -277.001224)
		(width 0.09525)
		(layer "In6.Cu")
		(net "M_K_CPU1_SB_DQS_DP<5>")
	)
	(segment
		(start 168.076118 -285.497778)
		(end 168.424352 -285.497778)
		(width 0.16002)
		(layer "In6.Cu")
		(net "M_K_CPU1_SB_DQS_DP<5>")
	)
	(segment
		(start 192.89014 -286.31134)
		(end 193.01714 -286.43834)
		(width 0.16002)
		(layer "In6.Cu")
		(net "M_K_CPU1_SB_DQS_DP<5>")
	)
	(segment
		(start 183.13146 -286.460438)
		(end 185.613294 -286.460438)
		(width 0.16002)
		(layer "In6.Cu")
		(net "M_K_CPU1_SB_DQS_DP<5>")
	)
	(segment
		(start 193.6242 -286.31134)
		(end 194.330066 -286.31134)
		(width 0.16002)
		(layer "In6.Cu")
		(net "M_K_CPU1_SB_DQS_DP<5>")
	)
	(segment
		(start 163.784534 -286.930592)
		(end 166.12997 -286.930592)
		(width 0.16002)
		(layer "In6.Cu")
		(net "M_K_CPU1_SB_DQS_DP<5>")
	)
	(segment
		(start 170.20794 -286.143192)
		(end 171.375324 -287.310576)
		(width 0.16002)
		(layer "In6.Cu")
		(net "M_K_CPU1_SB_DQS_DP<5>")
	)
	(segment
		(start 178.06924 -286.460438)
		(end 178.919378 -287.310576)
		(width 0.16002)
		(layer "In6.Cu")
		(net "M_K_CPU1_SB_DQS_DP<5>")
	)
	(segment
		(start 147.836636 -276.059392)
		(end 147.895564 -276.11832)
		(width 0.09525)
		(layer "In6.Cu")
		(net "M_K_CPU1_SB_DQS_DP<5>")
	)
	(segment
		(start 168.584372 -285.657798)
		(end 168.584372 -286.451548)
		(width 0.16002)
		(layer "In6.Cu")
		(net "M_K_CPU1_SB_DQS_DP<5>")
	)
	(segment
		(start 172.68952 -287.310576)
		(end 173.069504 -286.930592)
		(width 0.16002)
		(layer "In6.Cu")
		(net "M_K_CPU1_SB_DQS_DP<5>")
	)
	(segment
		(start 146.77898 -275.863812)
		(end 146.894804 -275.815806)
		(width 0.09525)
		(layer "In6.Cu")
		(net "M_K_CPU1_SB_DQS_DP<5>")
	)
	(segment
		(start 169.520108 -286.788606)
		(end 169.857166 -286.451548)
		(width 0.16002)
		(layer "In6.Cu")
		(net "M_K_CPU1_SB_DQS_DP<5>")
	)
	(segment
		(start 187.777628 -287.310576)
		(end 188.157612 -286.930592)
		(width 0.16002)
		(layer "In6.Cu")
		(net "M_K_CPU1_SB_DQS_DP<5>")
	)
	(segment
		(start 147.895564 -276.11832)
		(end 147.919186 -276.11832)
		(width 0.09525)
		(layer "In6.Cu")
		(net "M_K_CPU1_SB_DQS_DP<5>")
	)
	(segment
		(start 190.358268 -286.143192)
		(end 190.675514 -286.460438)
		(width 0.16002)
		(layer "In6.Cu")
		(net "M_K_CPU1_SB_DQS_DP<5>")
	)
	(segment
		(start 166.12997 -286.930592)
		(end 166.91737 -286.143192)
		(width 0.16002)
		(layer "In6.Cu")
		(net "M_K_CPU1_SB_DQS_DP<5>")
	)
	(segment
		(start 166.91737 -286.143192)
		(end 167.57904 -286.143192)
		(width 0.16002)
		(layer "In6.Cu")
		(net "M_K_CPU1_SB_DQS_DP<5>")
	)
	(segment
		(start 180.613558 -286.930592)
		(end 181.218078 -286.930592)
		(width 0.16002)
		(layer "In6.Cu")
		(net "M_K_CPU1_SB_DQS_DP<5>")
	)
	(segment
		(start 147.919186 -276.11832)
		(end 152.972262 -276.11832)
		(width 0.16002)
		(layer "In6.Cu")
		(net "M_K_CPU1_SB_DQS_DP<5>")
	)
	(segment
		(start 182.005478 -286.143192)
		(end 182.814214 -286.143192)
		(width 0.16002)
		(layer "In6.Cu")
		(net "M_K_CPU1_SB_DQS_DP<5>")
	)
	(segment
		(start 169.857166 -286.451548)
		(end 169.857166 -286.303212)
		(width 0.16002)
		(layer "In6.Cu")
		(net "M_K_CPU1_SB_DQS_DP<5>")
	)
	(segment
		(start 144.305528 -277.00732)
		(end 144.315942 -277.001224)
		(width 0.09525)
		(layer "In6.Cu")
		(net "M_K_CPU1_SB_DQS_DP<5>")
	)
	(segment
		(start 178.919378 -287.310576)
		(end 180.233574 -287.310576)
		(width 0.16002)
		(layer "In6.Cu")
		(net "M_K_CPU1_SB_DQS_DP<5>")
	)
	(segment
		(start 146.894804 -275.815806)
		(end 147.152106 -275.815806)
		(width 0.09525)
		(layer "In6.Cu")
		(net "M_K_CPU1_SB_DQS_DP<5>")
	)
	(segment
		(start 173.069504 -286.930592)
		(end 173.674024 -286.930592)
		(width 0.16002)
		(layer "In6.Cu")
		(net "M_K_CPU1_SB_DQS_DP<5>")
	)
	(segment
		(start 193.4972 -286.43834)
		(end 193.6242 -286.31134)
		(width 0.16002)
		(layer "In6.Cu")
		(net "M_K_CPU1_SB_DQS_DP<5>")
	)
	(segment
		(start 175.587406 -286.460438)
		(end 178.06924 -286.460438)
		(width 0.16002)
		(layer "In6.Cu")
		(net "M_K_CPU1_SB_DQS_DP<5>")
	)
	(segment
		(start 174.461424 -286.143192)
		(end 175.27016 -286.143192)
		(width 0.16002)
		(layer "In6.Cu")
		(net "M_K_CPU1_SB_DQS_DP<5>")
	)
	(segment
		(start 168.92143 -286.788606)
		(end 169.520108 -286.788606)
		(width 0.16002)
		(layer "In6.Cu")
		(net "M_K_CPU1_SB_DQS_DP<5>")
	)
	(segment
		(start 181.218078 -286.930592)
		(end 182.005478 -286.143192)
		(width 0.16002)
		(layer "In6.Cu")
		(net "M_K_CPU1_SB_DQS_DP<5>")
	)
	(segment
		(start 141.530832 -277.060914)
		(end 141.553946 -276.9743)
		(width 0.09525)
		(layer "In6.Cu")
		(net "M_K_CPU1_SB_DQS_DP<5>")
	)
	(segment
		(start 167.916098 -285.657798)
		(end 168.076118 -285.497778)
		(width 0.16002)
		(layer "In6.Cu")
		(net "M_K_CPU1_SB_DQS_DP<5>")
	)
	(segment
		(start 188.157612 -286.930592)
		(end 188.762132 -286.930592)
		(width 0.16002)
		(layer "In6.Cu")
		(net "M_K_CPU1_SB_DQS_DP<5>")
	)
	(segment
		(start 193.01714 -286.43834)
		(end 193.4972 -286.43834)
		(width 0.16002)
		(layer "In6.Cu")
		(net "M_K_CPU1_SB_DQS_DP<5>")
	)
	(segment
		(start 144.692624 -277.001224)
		(end 144.703038 -277.00732)
		(width 0.09525)
		(layer "In6.Cu")
		(net "M_K_CPU1_SB_DQS_DP<5>")
	)
	(segment
		(start 147.152106 -275.815806)
		(end 147.395692 -276.059392)
		(width 0.09525)
		(layer "In6.Cu")
		(net "M_K_CPU1_SB_DQS_DP<5>")
	)
	(segment
		(start 167.57904 -286.143192)
		(end 167.916098 -285.806134)
		(width 0.16002)
		(layer "In6.Cu")
		(net "M_K_CPU1_SB_DQS_DP<5>")
	)
	(segment
		(start 190.675514 -286.460438)
		(end 192.107566 -286.460438)
		(width 0.16002)
		(layer "In6.Cu")
		(net "M_K_CPU1_SB_DQS_DP<5>")
	)
	(segment
		(start 182.814214 -286.143192)
		(end 183.13146 -286.460438)
		(width 0.16002)
		(layer "In6.Cu")
		(net "M_K_CPU1_SB_DQS_DP<5>")
	)
	(segment
		(start 173.674024 -286.930592)
		(end 174.461424 -286.143192)
		(width 0.16002)
		(layer "In6.Cu")
		(net "M_K_CPU1_SB_DQS_DP<5>")
	)
	(segment
		(start 192.107566 -286.460438)
		(end 192.256664 -286.31134)
		(width 0.16002)
		(layer "In6.Cu")
		(net "M_K_CPU1_SB_DQS_DP<5>")
	)
	(segment
		(start 167.916098 -285.806134)
		(end 167.916098 -285.657798)
		(width 0.16002)
		(layer "In6.Cu")
		(net "M_K_CPU1_SB_DQS_DP<5>")
	)
	(segment
		(start 147.395692 -276.059392)
		(end 147.836636 -276.059392)
		(width 0.09525)
		(layer "In6.Cu")
		(net "M_K_CPU1_SB_DQS_DP<5>")
	)
	(segment
		(start 180.233574 -287.310576)
		(end 180.613558 -286.930592)
		(width 0.16002)
		(layer "In6.Cu")
		(net "M_K_CPU1_SB_DQS_DP<5>")
	)
	(segment
		(start 143.376142 -277.001224)
		(end 143.384524 -276.996398)
		(width 0.09525)
		(layer "In6.Cu")
		(net "M_K_CPU1_SB_DQS_DP<5>")
	)
	(segment
		(start 141.684756 -277.326344)
		(end 141.530832 -277.060914)
		(width 0.09525)
		(layer "In6.Cu")
		(net "M_K_CPU1_SB_DQS_DP<5>")
	)
	(segment
		(start 169.857166 -286.303212)
		(end 170.017186 -286.143192)
		(width 0.16002)
		(layer "In6.Cu")
		(net "M_K_CPU1_SB_DQS_DP<5>")
	)
	(segment
		(start 175.27016 -286.143192)
		(end 175.587406 -286.460438)
		(width 0.16002)
		(layer "In6.Cu")
		(net "M_K_CPU1_SB_DQS_DP<5>")
	)
	(segment
		(start 146.005042 -276.638258)
		(end 146.77898 -275.863812)
		(width 0.09525)
		(layer "In6.Cu")
		(net "M_K_CPU1_SB_DQS_DP<5>")
	)
	(segment
		(start 171.375324 -287.310576)
		(end 172.68952 -287.310576)
		(width 0.16002)
		(layer "In6.Cu")
		(net "M_K_CPU1_SB_DQS_DP<5>")
	)
	(segment
		(start 186.463432 -287.310576)
		(end 187.777628 -287.310576)
		(width 0.16002)
		(layer "In6.Cu")
		(net "M_K_CPU1_SB_DQS_DP<5>")
	)
	(segment
		(start 194.330066 -286.31134)
		(end 194.604132 -286.585406)
		(width 0.16002)
		(layer "In6.Cu")
		(net "M_K_CPU1_SB_DQS_DP<5>")
	)
	(arc
		(start 141.553946 -276.9743)
		(mid 141.716597 -276.95204)
		(end 141.873224 -277.001224)
		(width 0.09525)
		(layer "In6.Cu")
		(net "M_K_CPU1_SB_DQS_DP<5>")
	)
	(arc
		(start 143.384524 -276.996398)
		(mid 143.569556 -276.950484)
		(end 143.753332 -277.001224)
		(width 0.09525)
		(layer "In6.Cu")
		(net "M_K_CPU1_SB_DQS_DP<5>")
	)
	(arc
		(start 144.324324 -276.996398)
		(mid 144.509102 -276.950605)
		(end 144.692624 -277.001224)
		(width 0.09525)
		(layer "In6.Cu")
		(net "M_K_CPU1_SB_DQS_DP<5>")
	)
	(arc
		(start 142.436088 -277.001224)
		(mid 142.619863 -276.950452)
		(end 142.804896 -276.996398)
		(width 0.09525)
		(layer "In6.Cu")
		(net "M_K_CPU1_SB_DQS_DP<5>")
	)
	(arc
		(start 142.813278 -277.001224)
		(mid 143.09471 -277.076979)
		(end 143.376142 -277.001224)
		(width 0.09525)
		(layer "In6.Cu")
		(net "M_K_CPU1_SB_DQS_DP<5>")
	)
	(arc
		(start 144.703038 -277.00732)
		(mid 144.980309 -277.077119)
		(end 145.255996 -277.001224)
		(width 0.09525)
		(layer "In6.Cu")
		(net "M_K_CPU1_SB_DQS_DP<5>")
	)
	(arc
		(start 143.753332 -277.001224)
		(mid 144.028621 -277.076945)
		(end 144.305528 -277.00732)
		(width 0.09525)
		(layer "In6.Cu")
		(net "M_K_CPU1_SB_DQS_DP<5>")
	)
	(arc
		(start 145.411444 -276.871938)
		(mid 145.541127 -276.783499)
		(end 145.694146 -276.748494)
		(width 0.09525)
		(layer "In6.Cu")
		(net "M_K_CPU1_SB_DQS_DP<5>")
	)
	(arc
		(start 145.255996 -277.001224)
		(mid 145.316131 -276.960733)
		(end 145.37055 -276.912832)
		(width 0.09525)
		(layer "In6.Cu")
		(net "M_K_CPU1_SB_DQS_DP<5>")
	)
	(arc
		(start 141.873224 -277.001224)
		(mid 142.154656 -277.076979)
		(end 142.436088 -277.001224)
		(width 0.09525)
		(layer "In6.Cu")
		(net "M_K_CPU1_SB_DQS_DP<5>")
	)
	(arc
		(start 145.694146 -276.748494)
		(mid 145.858028 -276.71717)
		(end 146.005042 -276.638258)
		(width 0.09525)
		(layer "In6.Cu")
		(net "M_K_CPU1_SB_DQS_DP<5>")
	)
	(segment
		(start 141.217904 -272.20037)
		(end 141.684756 -272.466308)
		(width 0.12954)
		(layer "F.Cu")
		(net "M_K_CPU1_SB_DQS_DP<4>")
	)
	(segment
		(start 142.804896 -272.136362)
		(end 142.813278 -272.141188)
		(width 0.09525)
		(layer "In6.Cu")
		(net "M_K_CPU1_SB_DQS_DP<4>")
	)
	(segment
		(start 158.910528 -271.660874)
		(end 159.157924 -271.90827)
		(width 0.16002)
		(layer "In6.Cu")
		(net "M_K_CPU1_SB_DQS_DP<4>")
	)
	(segment
		(start 178.06924 -277.110444)
		(end 178.919378 -277.960582)
		(width 0.16002)
		(layer "In6.Cu")
		(net "M_K_CPU1_SB_DQS_DP<4>")
	)
	(segment
		(start 159.157924 -272.134076)
		(end 159.077406 -272.214594)
		(width 0.16002)
		(layer "In6.Cu")
		(net "M_K_CPU1_SB_DQS_DP<4>")
	)
	(segment
		(start 167.726106 -276.793198)
		(end 168.043352 -277.110444)
		(width 0.16002)
		(layer "In6.Cu")
		(net "M_K_CPU1_SB_DQS_DP<4>")
	)
	(segment
		(start 144.693132 -272.14068)
		(end 144.707864 -272.149316)
		(width 0.09525)
		(layer "In6.Cu")
		(net "M_K_CPU1_SB_DQS_DP<4>")
	)
	(segment
		(start 192.256664 -276.961346)
		(end 192.84442 -276.961346)
		(width 0.16002)
		(layer "In6.Cu")
		(net "M_K_CPU1_SB_DQS_DP<4>")
	)
	(segment
		(start 193.45148 -277.088346)
		(end 193.57848 -276.961346)
		(width 0.16002)
		(layer "In6.Cu")
		(net "M_K_CPU1_SB_DQS_DP<4>")
	)
	(segment
		(start 166.91737 -276.793198)
		(end 167.726106 -276.793198)
		(width 0.16002)
		(layer "In6.Cu")
		(net "M_K_CPU1_SB_DQS_DP<4>")
	)
	(segment
		(start 163.27882 -276.254972)
		(end 163.198302 -276.33549)
		(width 0.16002)
		(layer "In6.Cu")
		(net "M_K_CPU1_SB_DQS_DP<4>")
	)
	(segment
		(start 181.218078 -277.580598)
		(end 182.005478 -276.793198)
		(width 0.16002)
		(layer "In6.Cu")
		(net "M_K_CPU1_SB_DQS_DP<4>")
	)
	(segment
		(start 162.724592 -275.862034)
		(end 162.80511 -275.78177)
		(width 0.16002)
		(layer "In6.Cu")
		(net "M_K_CPU1_SB_DQS_DP<4>")
	)
	(segment
		(start 183.13146 -277.110444)
		(end 185.613294 -277.110444)
		(width 0.16002)
		(layer "In6.Cu")
		(net "M_K_CPU1_SB_DQS_DP<4>")
	)
	(segment
		(start 173.674024 -277.580598)
		(end 174.461424 -276.793198)
		(width 0.16002)
		(layer "In6.Cu")
		(net "M_K_CPU1_SB_DQS_DP<4>")
	)
	(segment
		(start 144.305528 -272.147284)
		(end 144.315942 -272.141188)
		(width 0.09525)
		(layer "In6.Cu")
		(net "M_K_CPU1_SB_DQS_DP<4>")
	)
	(segment
		(start 158.603696 -271.741138)
		(end 158.684214 -271.660874)
		(width 0.16002)
		(layer "In6.Cu")
		(net "M_K_CPU1_SB_DQS_DP<4>")
	)
	(segment
		(start 147.836636 -270.387826)
		(end 147.895564 -270.446754)
		(width 0.09525)
		(layer "In6.Cu")
		(net "M_K_CPU1_SB_DQS_DP<4>")
	)
	(segment
		(start 174.461424 -276.793198)
		(end 175.27016 -276.793198)
		(width 0.16002)
		(layer "In6.Cu")
		(net "M_K_CPU1_SB_DQS_DP<4>")
	)
	(segment
		(start 146.67611 -270.387826)
		(end 147.836636 -270.387826)
		(width 0.09525)
		(layer "In6.Cu")
		(net "M_K_CPU1_SB_DQS_DP<4>")
	)
	(segment
		(start 194.330066 -276.961346)
		(end 194.604132 -277.235412)
		(width 0.16002)
		(layer "In6.Cu")
		(net "M_K_CPU1_SB_DQS_DP<4>")
	)
	(segment
		(start 180.233574 -277.960582)
		(end 180.613558 -277.580598)
		(width 0.16002)
		(layer "In6.Cu")
		(net "M_K_CPU1_SB_DQS_DP<4>")
	)
	(segment
		(start 161.905188 -274.655534)
		(end 161.905188 -274.88134)
		(width 0.16002)
		(layer "In6.Cu")
		(net "M_K_CPU1_SB_DQS_DP<4>")
	)
	(segment
		(start 147.919186 -270.446754)
		(end 156.833062 -270.446754)
		(width 0.16002)
		(layer "In6.Cu")
		(net "M_K_CPU1_SB_DQS_DP<4>")
	)
	(segment
		(start 160.531556 -273.281902)
		(end 160.531556 -273.507708)
		(width 0.16002)
		(layer "In6.Cu")
		(net "M_K_CPU1_SB_DQS_DP<4>")
	)
	(segment
		(start 175.27016 -276.793198)
		(end 175.587406 -277.110444)
		(width 0.16002)
		(layer "In6.Cu")
		(net "M_K_CPU1_SB_DQS_DP<4>")
	)
	(segment
		(start 158.684214 -271.660874)
		(end 158.910528 -271.660874)
		(width 0.16002)
		(layer "In6.Cu")
		(net "M_K_CPU1_SB_DQS_DP<4>")
	)
	(segment
		(start 192.97142 -277.088346)
		(end 193.45148 -277.088346)
		(width 0.16002)
		(layer "In6.Cu")
		(net "M_K_CPU1_SB_DQS_DP<4>")
	)
	(segment
		(start 161.657792 -274.408138)
		(end 161.905188 -274.655534)
		(width 0.16002)
		(layer "In6.Cu")
		(net "M_K_CPU1_SB_DQS_DP<4>")
	)
	(segment
		(start 163.966906 -277.580598)
		(end 166.12997 -277.580598)
		(width 0.16002)
		(layer "In6.Cu")
		(net "M_K_CPU1_SB_DQS_DP<4>")
	)
	(segment
		(start 187.777628 -277.960582)
		(end 188.157612 -277.580598)
		(width 0.16002)
		(layer "In6.Cu")
		(net "M_K_CPU1_SB_DQS_DP<4>")
	)
	(segment
		(start 159.501078 -273.11477)
		(end 159.977328 -273.11477)
		(width 0.16002)
		(layer "In6.Cu")
		(net "M_K_CPU1_SB_DQS_DP<4>")
	)
	(segment
		(start 168.043352 -277.110444)
		(end 170.525186 -277.110444)
		(width 0.16002)
		(layer "In6.Cu")
		(net "M_K_CPU1_SB_DQS_DP<4>")
	)
	(segment
		(start 162.248342 -275.862034)
		(end 162.724592 -275.862034)
		(width 0.16002)
		(layer "In6.Cu")
		(net "M_K_CPU1_SB_DQS_DP<4>")
	)
	(segment
		(start 178.919378 -277.960582)
		(end 180.233574 -277.960582)
		(width 0.16002)
		(layer "In6.Cu")
		(net "M_K_CPU1_SB_DQS_DP<4>")
	)
	(segment
		(start 180.613558 -277.580598)
		(end 181.218078 -277.580598)
		(width 0.16002)
		(layer "In6.Cu")
		(net "M_K_CPU1_SB_DQS_DP<4>")
	)
	(segment
		(start 189.549532 -276.793198)
		(end 190.358268 -276.793198)
		(width 0.16002)
		(layer "In6.Cu")
		(net "M_K_CPU1_SB_DQS_DP<4>")
	)
	(segment
		(start 163.27882 -276.029166)
		(end 163.27882 -276.254972)
		(width 0.16002)
		(layer "In6.Cu")
		(net "M_K_CPU1_SB_DQS_DP<4>")
	)
	(segment
		(start 163.198302 -276.33549)
		(end 163.198302 -276.811994)
		(width 0.16002)
		(layer "In6.Cu")
		(net "M_K_CPU1_SB_DQS_DP<4>")
	)
	(segment
		(start 158.127446 -271.741138)
		(end 158.603696 -271.741138)
		(width 0.16002)
		(layer "In6.Cu")
		(net "M_K_CPU1_SB_DQS_DP<4>")
	)
	(segment
		(start 143.376142 -272.141188)
		(end 143.384524 -272.136362)
		(width 0.09525)
		(layer "In6.Cu")
		(net "M_K_CPU1_SB_DQS_DP<4>")
	)
	(segment
		(start 141.530832 -272.200878)
		(end 141.553946 -272.114264)
		(width 0.09525)
		(layer "In6.Cu")
		(net "M_K_CPU1_SB_DQS_DP<4>")
	)
	(segment
		(start 160.28416 -273.034506)
		(end 160.531556 -273.281902)
		(width 0.16002)
		(layer "In6.Cu")
		(net "M_K_CPU1_SB_DQS_DP<4>")
	)
	(segment
		(start 173.069504 -277.580598)
		(end 173.674024 -277.580598)
		(width 0.16002)
		(layer "In6.Cu")
		(net "M_K_CPU1_SB_DQS_DP<4>")
	)
	(segment
		(start 172.68952 -277.960582)
		(end 173.069504 -277.580598)
		(width 0.16002)
		(layer "In6.Cu")
		(net "M_K_CPU1_SB_DQS_DP<4>")
	)
	(segment
		(start 161.905188 -274.88134)
		(end 161.82467 -274.961858)
		(width 0.16002)
		(layer "In6.Cu")
		(net "M_K_CPU1_SB_DQS_DP<4>")
	)
	(segment
		(start 190.358268 -276.793198)
		(end 190.675514 -277.110444)
		(width 0.16002)
		(layer "In6.Cu")
		(net "M_K_CPU1_SB_DQS_DP<4>")
	)
	(segment
		(start 159.977328 -273.11477)
		(end 160.057846 -273.034506)
		(width 0.16002)
		(layer "In6.Cu")
		(net "M_K_CPU1_SB_DQS_DP<4>")
	)
	(segment
		(start 188.762132 -277.580598)
		(end 189.549532 -276.793198)
		(width 0.16002)
		(layer "In6.Cu")
		(net "M_K_CPU1_SB_DQS_DP<4>")
	)
	(segment
		(start 141.684756 -272.466308)
		(end 141.530832 -272.200878)
		(width 0.09525)
		(layer "In6.Cu")
		(net "M_K_CPU1_SB_DQS_DP<4>")
	)
	(segment
		(start 159.077406 -272.214594)
		(end 159.077406 -272.691098)
		(width 0.16002)
		(layer "In6.Cu")
		(net "M_K_CPU1_SB_DQS_DP<4>")
	)
	(segment
		(start 166.12997 -277.580598)
		(end 166.91737 -276.793198)
		(width 0.16002)
		(layer "In6.Cu")
		(net "M_K_CPU1_SB_DQS_DP<4>")
	)
	(segment
		(start 160.057846 -273.034506)
		(end 160.28416 -273.034506)
		(width 0.16002)
		(layer "In6.Cu")
		(net "M_K_CPU1_SB_DQS_DP<4>")
	)
	(segment
		(start 186.463432 -277.960582)
		(end 187.777628 -277.960582)
		(width 0.16002)
		(layer "In6.Cu")
		(net "M_K_CPU1_SB_DQS_DP<4>")
	)
	(segment
		(start 159.157924 -271.90827)
		(end 159.157924 -272.134076)
		(width 0.16002)
		(layer "In6.Cu")
		(net "M_K_CPU1_SB_DQS_DP<4>")
	)
	(segment
		(start 188.157612 -277.580598)
		(end 188.762132 -277.580598)
		(width 0.16002)
		(layer "In6.Cu")
		(net "M_K_CPU1_SB_DQS_DP<4>")
	)
	(segment
		(start 161.35096 -274.488402)
		(end 161.431478 -274.408138)
		(width 0.16002)
		(layer "In6.Cu")
		(net "M_K_CPU1_SB_DQS_DP<4>")
	)
	(segment
		(start 185.613294 -277.110444)
		(end 186.463432 -277.960582)
		(width 0.16002)
		(layer "In6.Cu")
		(net "M_K_CPU1_SB_DQS_DP<4>")
	)
	(segment
		(start 156.833062 -270.446754)
		(end 158.127446 -271.741138)
		(width 0.16002)
		(layer "In6.Cu")
		(net "M_K_CPU1_SB_DQS_DP<4>")
	)
	(segment
		(start 159.077406 -272.691098)
		(end 159.501078 -273.11477)
		(width 0.16002)
		(layer "In6.Cu")
		(net "M_K_CPU1_SB_DQS_DP<4>")
	)
	(segment
		(start 145.371058 -272.052034)
		(end 145.53438 -271.888712)
		(width 0.09525)
		(layer "In6.Cu")
		(net "M_K_CPU1_SB_DQS_DP<4>")
	)
	(segment
		(start 162.80511 -275.78177)
		(end 163.031424 -275.78177)
		(width 0.16002)
		(layer "In6.Cu")
		(net "M_K_CPU1_SB_DQS_DP<4>")
	)
	(segment
		(start 193.57848 -276.961346)
		(end 194.330066 -276.961346)
		(width 0.16002)
		(layer "In6.Cu")
		(net "M_K_CPU1_SB_DQS_DP<4>")
	)
	(segment
		(start 192.84442 -276.961346)
		(end 192.97142 -277.088346)
		(width 0.16002)
		(layer "In6.Cu")
		(net "M_K_CPU1_SB_DQS_DP<4>")
	)
	(segment
		(start 160.87471 -274.488402)
		(end 161.35096 -274.488402)
		(width 0.16002)
		(layer "In6.Cu")
		(net "M_K_CPU1_SB_DQS_DP<4>")
	)
	(segment
		(start 170.525186 -277.110444)
		(end 171.375324 -277.960582)
		(width 0.16002)
		(layer "In6.Cu")
		(net "M_K_CPU1_SB_DQS_DP<4>")
	)
	(segment
		(start 163.031424 -275.78177)
		(end 163.27882 -276.029166)
		(width 0.16002)
		(layer "In6.Cu")
		(net "M_K_CPU1_SB_DQS_DP<4>")
	)
	(segment
		(start 161.431478 -274.408138)
		(end 161.657792 -274.408138)
		(width 0.16002)
		(layer "In6.Cu")
		(net "M_K_CPU1_SB_DQS_DP<4>")
	)
	(segment
		(start 160.451038 -274.06473)
		(end 160.87471 -274.488402)
		(width 0.16002)
		(layer "In6.Cu")
		(net "M_K_CPU1_SB_DQS_DP<4>")
	)
	(segment
		(start 171.375324 -277.960582)
		(end 172.68952 -277.960582)
		(width 0.16002)
		(layer "In6.Cu")
		(net "M_K_CPU1_SB_DQS_DP<4>")
	)
	(segment
		(start 175.587406 -277.110444)
		(end 178.06924 -277.110444)
		(width 0.16002)
		(layer "In6.Cu")
		(net "M_K_CPU1_SB_DQS_DP<4>")
	)
	(segment
		(start 147.895564 -270.446754)
		(end 147.919186 -270.446754)
		(width 0.09525)
		(layer "In6.Cu")
		(net "M_K_CPU1_SB_DQS_DP<4>")
	)
	(segment
		(start 161.82467 -275.438362)
		(end 162.248342 -275.862034)
		(width 0.16002)
		(layer "In6.Cu")
		(net "M_K_CPU1_SB_DQS_DP<4>")
	)
	(segment
		(start 161.82467 -274.961858)
		(end 161.82467 -275.438362)
		(width 0.16002)
		(layer "In6.Cu")
		(net "M_K_CPU1_SB_DQS_DP<4>")
	)
	(segment
		(start 145.78838 -271.275556)
		(end 146.67611 -270.387826)
		(width 0.09525)
		(layer "In6.Cu")
		(net "M_K_CPU1_SB_DQS_DP<4>")
	)
	(segment
		(start 192.107566 -277.110444)
		(end 192.256664 -276.961346)
		(width 0.16002)
		(layer "In6.Cu")
		(net "M_K_CPU1_SB_DQS_DP<4>")
	)
	(segment
		(start 160.451038 -273.588226)
		(end 160.451038 -274.06473)
		(width 0.16002)
		(layer "In6.Cu")
		(net "M_K_CPU1_SB_DQS_DP<4>")
	)
	(segment
		(start 182.814214 -276.793198)
		(end 183.13146 -277.110444)
		(width 0.16002)
		(layer "In6.Cu")
		(net "M_K_CPU1_SB_DQS_DP<4>")
	)
	(segment
		(start 163.198302 -276.811994)
		(end 163.966906 -277.580598)
		(width 0.16002)
		(layer "In6.Cu")
		(net "M_K_CPU1_SB_DQS_DP<4>")
	)
	(segment
		(start 182.005478 -276.793198)
		(end 182.814214 -276.793198)
		(width 0.16002)
		(layer "In6.Cu")
		(net "M_K_CPU1_SB_DQS_DP<4>")
	)
	(segment
		(start 190.675514 -277.110444)
		(end 192.107566 -277.110444)
		(width 0.16002)
		(layer "In6.Cu")
		(net "M_K_CPU1_SB_DQS_DP<4>")
	)
	(segment
		(start 160.531556 -273.507708)
		(end 160.451038 -273.588226)
		(width 0.16002)
		(layer "In6.Cu")
		(net "M_K_CPU1_SB_DQS_DP<4>")
	)
	(segment
		(start 144.315942 -272.141188)
		(end 144.333722 -272.131028)
		(width 0.09525)
		(layer "In6.Cu")
		(net "M_K_CPU1_SB_DQS_DP<4>")
	)
	(arc
		(start 145.53438 -271.888712)
		(mid 145.651881 -271.712859)
		(end 145.69313 -271.505426)
		(width 0.09525)
		(layer "In6.Cu")
		(net "M_K_CPU1_SB_DQS_DP<4>")
	)
	(arc
		(start 145.69313 -271.505426)
		(mid 145.717878 -271.381008)
		(end 145.78838 -271.275556)
		(width 0.09525)
		(layer "In6.Cu")
		(net "M_K_CPU1_SB_DQS_DP<4>")
	)
	(arc
		(start 141.553946 -272.114264)
		(mid 141.716597 -272.092004)
		(end 141.873224 -272.141188)
		(width 0.09525)
		(layer "In6.Cu")
		(net "M_K_CPU1_SB_DQS_DP<4>")
	)
	(arc
		(start 144.333722 -272.131028)
		(mid 144.514669 -272.090098)
		(end 144.693132 -272.14068)
		(width 0.09525)
		(layer "In6.Cu")
		(net "M_K_CPU1_SB_DQS_DP<4>")
	)
	(arc
		(start 143.384524 -272.136362)
		(mid 143.569556 -272.090448)
		(end 143.753332 -272.141188)
		(width 0.09525)
		(layer "In6.Cu")
		(net "M_K_CPU1_SB_DQS_DP<4>")
	)
	(arc
		(start 143.753332 -272.141188)
		(mid 144.028621 -272.216909)
		(end 144.305528 -272.147284)
		(width 0.09525)
		(layer "In6.Cu")
		(net "M_K_CPU1_SB_DQS_DP<4>")
	)
	(arc
		(start 144.707864 -272.149316)
		(mid 144.983069 -272.216519)
		(end 145.255996 -272.14068)
		(width 0.09525)
		(layer "In6.Cu")
		(net "M_K_CPU1_SB_DQS_DP<4>")
	)
	(arc
		(start 141.873224 -272.141188)
		(mid 142.154656 -272.216943)
		(end 142.436088 -272.141188)
		(width 0.09525)
		(layer "In6.Cu")
		(net "M_K_CPU1_SB_DQS_DP<4>")
	)
	(arc
		(start 145.255996 -272.14068)
		(mid 145.316417 -272.100107)
		(end 145.371058 -272.052034)
		(width 0.09525)
		(layer "In6.Cu")
		(net "M_K_CPU1_SB_DQS_DP<4>")
	)
	(arc
		(start 142.813278 -272.141188)
		(mid 143.09471 -272.216943)
		(end 143.376142 -272.141188)
		(width 0.09525)
		(layer "In6.Cu")
		(net "M_K_CPU1_SB_DQS_DP<4>")
	)
	(arc
		(start 142.436088 -272.141188)
		(mid 142.619863 -272.090416)
		(end 142.804896 -272.136362)
		(width 0.09525)
		(layer "In6.Cu")
		(net "M_K_CPU1_SB_DQS_DP<4>")
	)
	(segment
		(start 142.157958 -290.020248)
		(end 142.62481 -290.286186)
		(width 0.12954)
		(layer "F.Cu")
		(net "M_K_CPU1_SB_DQS_DP<3>")
	)
	(segment
		(start 196.409818 -313.209178)
		(end 198.430388 -313.209178)
		(width 0.16002)
		(layer "In6.Cu")
		(net "M_K_CPU1_SB_DQS_DP<3>")
	)
	(segment
		(start 198.430388 -313.209178)
		(end 198.7042 -312.935366)
		(width 0.16002)
		(layer "In6.Cu")
		(net "M_K_CPU1_SB_DQS_DP<3>")
	)
	(segment
		(start 195.831206 -313.408314)
		(end 196.210682 -313.408314)
		(width 0.16002)
		(layer "In6.Cu")
		(net "M_K_CPU1_SB_DQS_DP<3>")
	)
	(segment
		(start 145.37055 -290.69919)
		(end 145.512536 -290.841176)
		(width 0.09525)
		(layer "In6.Cu")
		(net "M_K_CPU1_SB_DQS_DP<3>")
	)
	(segment
		(start 169.595292 -312.210196)
		(end 170.445176 -313.06008)
		(width 0.16002)
		(layer "In6.Cu")
		(net "M_K_CPU1_SB_DQS_DP<3>")
	)
	(segment
		(start 172.855128 -313.06008)
		(end 173.195742 -313.400694)
		(width 0.16002)
		(layer "In6.Cu")
		(net "M_K_CPU1_SB_DQS_DP<3>")
	)
	(segment
		(start 177.139346 -312.210196)
		(end 177.98923 -313.06008)
		(width 0.16002)
		(layer "In6.Cu")
		(net "M_K_CPU1_SB_DQS_DP<3>")
	)
	(segment
		(start 177.98923 -313.06008)
		(end 180.399182 -313.06008)
		(width 0.16002)
		(layer "In6.Cu")
		(net "M_K_CPU1_SB_DQS_DP<3>")
	)
	(segment
		(start 182.380636 -312.549794)
		(end 182.720234 -312.210196)
		(width 0.16002)
		(layer "In6.Cu")
		(net "M_K_CPU1_SB_DQS_DP<3>")
	)
	(segment
		(start 188.68517 -313.400694)
		(end 189.53607 -312.549794)
		(width 0.16002)
		(layer "In6.Cu")
		(net "M_K_CPU1_SB_DQS_DP<3>")
	)
	(segment
		(start 147.103338 -293.524432)
		(end 147.120102 -293.541196)
		(width 0.09525)
		(layer "In6.Cu")
		(net "M_K_CPU1_SB_DQS_DP<3>")
	)
	(segment
		(start 175.17618 -312.210196)
		(end 177.139346 -312.210196)
		(width 0.16002)
		(layer "In6.Cu")
		(net "M_K_CPU1_SB_DQS_DP<3>")
	)
	(segment
		(start 188.28385 -313.400694)
		(end 188.68517 -313.400694)
		(width 0.16002)
		(layer "In6.Cu")
		(net "M_K_CPU1_SB_DQS_DP<3>")
	)
	(segment
		(start 173.597062 -313.400694)
		(end 174.447962 -312.549794)
		(width 0.16002)
		(layer "In6.Cu")
		(net "M_K_CPU1_SB_DQS_DP<3>")
	)
	(segment
		(start 181.141116 -313.400694)
		(end 181.992016 -312.549794)
		(width 0.16002)
		(layer "In6.Cu")
		(net "M_K_CPU1_SB_DQS_DP<3>")
	)
	(segment
		(start 170.445176 -313.06008)
		(end 172.855128 -313.06008)
		(width 0.16002)
		(layer "In6.Cu")
		(net "M_K_CPU1_SB_DQS_DP<3>")
	)
	(segment
		(start 167.292528 -312.549794)
		(end 167.632126 -312.210196)
		(width 0.16002)
		(layer "In6.Cu")
		(net "M_K_CPU1_SB_DQS_DP<3>")
	)
	(segment
		(start 192.422272 -312.210196)
		(end 192.996312 -312.784236)
		(width 0.16002)
		(layer "In6.Cu")
		(net "M_K_CPU1_SB_DQS_DP<3>")
	)
	(segment
		(start 166.053008 -313.400694)
		(end 166.903908 -312.549794)
		(width 0.16002)
		(layer "In6.Cu")
		(net "M_K_CPU1_SB_DQS_DP<3>")
	)
	(segment
		(start 190.264288 -312.210196)
		(end 192.422272 -312.210196)
		(width 0.16002)
		(layer "In6.Cu")
		(net "M_K_CPU1_SB_DQS_DP<3>")
	)
	(segment
		(start 167.632126 -312.210196)
		(end 169.595292 -312.210196)
		(width 0.16002)
		(layer "In6.Cu")
		(net "M_K_CPU1_SB_DQS_DP<3>")
	)
	(segment
		(start 182.720234 -312.210196)
		(end 184.6834 -312.210196)
		(width 0.16002)
		(layer "In6.Cu")
		(net "M_K_CPU1_SB_DQS_DP<3>")
	)
	(segment
		(start 145.75155 -291.386006)
		(end 146.395186 -292.029642)
		(width 0.09525)
		(layer "In6.Cu")
		(net "M_K_CPU1_SB_DQS_DP<3>")
	)
	(segment
		(start 143.376142 -290.611306)
		(end 143.384524 -290.616132)
		(width 0.09525)
		(layer "In6.Cu")
		(net "M_K_CPU1_SB_DQS_DP<3>")
	)
	(segment
		(start 146.395186 -292.029642)
		(end 146.395186 -292.90137)
		(width 0.09525)
		(layer "In6.Cu")
		(net "M_K_CPU1_SB_DQS_DP<3>")
	)
	(segment
		(start 147.020026 -293.52494)
		(end 147.103338 -293.524432)
		(width 0.09525)
		(layer "In6.Cu")
		(net "M_K_CPU1_SB_DQS_DP<3>")
	)
	(segment
		(start 189.92469 -312.549794)
		(end 190.264288 -312.210196)
		(width 0.16002)
		(layer "In6.Cu")
		(net "M_K_CPU1_SB_DQS_DP<3>")
	)
	(segment
		(start 196.210682 -313.408314)
		(end 196.409818 -313.209178)
		(width 0.16002)
		(layer "In6.Cu")
		(net "M_K_CPU1_SB_DQS_DP<3>")
	)
	(segment
		(start 184.6834 -312.210196)
		(end 185.533284 -313.06008)
		(width 0.16002)
		(layer "In6.Cu")
		(net "M_K_CPU1_SB_DQS_DP<3>")
	)
	(segment
		(start 180.739796 -313.400694)
		(end 181.141116 -313.400694)
		(width 0.16002)
		(layer "In6.Cu")
		(net "M_K_CPU1_SB_DQS_DP<3>")
	)
	(segment
		(start 142.62481 -290.286186)
		(end 142.778734 -290.551616)
		(width 0.09525)
		(layer "In6.Cu")
		(net "M_K_CPU1_SB_DQS_DP<3>")
	)
	(segment
		(start 180.399182 -313.06008)
		(end 180.739796 -313.400694)
		(width 0.16002)
		(layer "In6.Cu")
		(net "M_K_CPU1_SB_DQS_DP<3>")
	)
	(segment
		(start 174.836582 -312.549794)
		(end 175.17618 -312.210196)
		(width 0.16002)
		(layer "In6.Cu")
		(net "M_K_CPU1_SB_DQS_DP<3>")
	)
	(segment
		(start 148.78431 -295.204642)
		(end 148.78431 -299.396404)
		(width 0.16002)
		(layer "In6.Cu")
		(net "M_K_CPU1_SB_DQS_DP<3>")
	)
	(segment
		(start 173.195742 -313.400694)
		(end 173.597062 -313.400694)
		(width 0.16002)
		(layer "In6.Cu")
		(net "M_K_CPU1_SB_DQS_DP<3>")
	)
	(segment
		(start 162.7886 -313.400694)
		(end 166.053008 -313.400694)
		(width 0.16002)
		(layer "In6.Cu")
		(net "M_K_CPU1_SB_DQS_DP<3>")
	)
	(segment
		(start 189.53607 -312.549794)
		(end 189.92469 -312.549794)
		(width 0.16002)
		(layer "In6.Cu")
		(net "M_K_CPU1_SB_DQS_DP<3>")
	)
	(segment
		(start 145.512536 -290.841176)
		(end 145.75155 -291.386006)
		(width 0.09525)
		(layer "In6.Cu")
		(net "M_K_CPU1_SB_DQS_DP<3>")
	)
	(segment
		(start 192.996312 -312.784236)
		(end 195.207128 -312.784236)
		(width 0.16002)
		(layer "In6.Cu")
		(net "M_K_CPU1_SB_DQS_DP<3>")
	)
	(segment
		(start 166.903908 -312.549794)
		(end 167.292528 -312.549794)
		(width 0.16002)
		(layer "In6.Cu")
		(net "M_K_CPU1_SB_DQS_DP<3>")
	)
	(segment
		(start 185.533284 -313.06008)
		(end 187.943236 -313.06008)
		(width 0.16002)
		(layer "In6.Cu")
		(net "M_K_CPU1_SB_DQS_DP<3>")
	)
	(segment
		(start 144.693132 -290.611306)
		(end 144.707864 -290.60267)
		(width 0.09525)
		(layer "In6.Cu")
		(net "M_K_CPU1_SB_DQS_DP<3>")
	)
	(segment
		(start 147.120102 -293.541196)
		(end 148.78431 -295.204642)
		(width 0.16002)
		(layer "In6.Cu")
		(net "M_K_CPU1_SB_DQS_DP<3>")
	)
	(segment
		(start 142.778734 -290.551616)
		(end 142.879572 -290.578286)
		(width 0.09525)
		(layer "In6.Cu")
		(net "M_K_CPU1_SB_DQS_DP<3>")
	)
	(segment
		(start 187.943236 -313.06008)
		(end 188.28385 -313.400694)
		(width 0.16002)
		(layer "In6.Cu")
		(net "M_K_CPU1_SB_DQS_DP<3>")
	)
	(segment
		(start 181.992016 -312.549794)
		(end 182.380636 -312.549794)
		(width 0.16002)
		(layer "In6.Cu")
		(net "M_K_CPU1_SB_DQS_DP<3>")
	)
	(segment
		(start 146.395186 -292.90137)
		(end 147.020026 -293.52494)
		(width 0.09525)
		(layer "In6.Cu")
		(net "M_K_CPU1_SB_DQS_DP<3>")
	)
	(segment
		(start 148.78431 -299.396404)
		(end 162.7886 -313.400694)
		(width 0.16002)
		(layer "In6.Cu")
		(net "M_K_CPU1_SB_DQS_DP<3>")
	)
	(segment
		(start 174.447962 -312.549794)
		(end 174.836582 -312.549794)
		(width 0.16002)
		(layer "In6.Cu")
		(net "M_K_CPU1_SB_DQS_DP<3>")
	)
	(segment
		(start 195.207128 -312.784236)
		(end 195.831206 -313.408314)
		(width 0.16002)
		(layer "In6.Cu")
		(net "M_K_CPU1_SB_DQS_DP<3>")
	)
	(arc
		(start 143.384524 -290.616132)
		(mid 143.569556 -290.662046)
		(end 143.753332 -290.611306)
		(width 0.09525)
		(layer "In6.Cu")
		(net "M_K_CPU1_SB_DQS_DP<3>")
	)
	(arc
		(start 144.707864 -290.60267)
		(mid 144.982925 -290.535529)
		(end 145.255742 -290.611306)
		(width 0.09525)
		(layer "In6.Cu")
		(net "M_K_CPU1_SB_DQS_DP<3>")
	)
	(arc
		(start 145.255742 -290.611306)
		(mid 145.300512 -290.640113)
		(end 145.342356 -290.673028)
		(width 0.09525)
		(layer "In6.Cu")
		(net "M_K_CPU1_SB_DQS_DP<3>")
	)
	(arc
		(start 144.316196 -290.611306)
		(mid 144.504664 -290.661983)
		(end 144.693132 -290.611306)
		(width 0.09525)
		(layer "In6.Cu")
		(net "M_K_CPU1_SB_DQS_DP<3>")
	)
	(arc
		(start 145.342356 -290.673028)
		(mid 145.356675 -290.685869)
		(end 145.37055 -290.69919)
		(width 0.09525)
		(layer "In6.Cu")
		(net "M_K_CPU1_SB_DQS_DP<3>")
	)
	(arc
		(start 142.879572 -290.578286)
		(mid 142.88944 -290.574255)
		(end 142.899384 -290.570412)
		(width 0.09525)
		(layer "In6.Cu")
		(net "M_K_CPU1_SB_DQS_DP<3>")
	)
	(arc
		(start 143.753332 -290.611306)
		(mid 144.034764 -290.535551)
		(end 144.316196 -290.611306)
		(width 0.09525)
		(layer "In6.Cu")
		(net "M_K_CPU1_SB_DQS_DP<3>")
	)
	(arc
		(start 142.899384 -290.570412)
		(mid 143.142348 -290.537425)
		(end 143.376142 -290.611306)
		(width 0.09525)
		(layer "In6.Cu")
		(net "M_K_CPU1_SB_DQS_DP<3>")
	)
	(segment
		(start 142.157958 -285.160466)
		(end 142.62481 -285.426404)
		(width 0.12954)
		(layer "F.Cu")
		(net "M_K_CPU1_SB_DQS_DP<2>")
	)
	(segment
		(start 154.668982 -293.015924)
		(end 154.668982 -296.221404)
		(width 0.16002)
		(layer "In6.Cu")
		(net "M_K_CPU1_SB_DQS_DP<2>")
	)
	(segment
		(start 167.292528 -303.1998)
		(end 167.632126 -302.860202)
		(width 0.16002)
		(layer "In6.Cu")
		(net "M_K_CPU1_SB_DQS_DP<2>")
	)
	(segment
		(start 145.9103 -285.803086)
		(end 146.63293 -286.525716)
		(width 0.09525)
		(layer "In6.Cu")
		(net "M_K_CPU1_SB_DQS_DP<2>")
	)
	(segment
		(start 174.836582 -303.1998)
		(end 175.17618 -302.860202)
		(width 0.16002)
		(layer "In6.Cu")
		(net "M_K_CPU1_SB_DQS_DP<2>")
	)
	(segment
		(start 144.693132 -285.751524)
		(end 144.707864 -285.742888)
		(width 0.09525)
		(layer "In6.Cu")
		(net "M_K_CPU1_SB_DQS_DP<2>")
	)
	(segment
		(start 182.380636 -303.1998)
		(end 182.720234 -302.860202)
		(width 0.16002)
		(layer "In6.Cu")
		(net "M_K_CPU1_SB_DQS_DP<2>")
	)
	(segment
		(start 158.200852 -298.612814)
		(end 163.638738 -304.0507)
		(width 0.16002)
		(layer "In6.Cu")
		(net "M_K_CPU1_SB_DQS_DP<2>")
	)
	(segment
		(start 145.444718 -285.803086)
		(end 145.9103 -285.803086)
		(width 0.09525)
		(layer "In6.Cu")
		(net "M_K_CPU1_SB_DQS_DP<2>")
	)
	(segment
		(start 196.409818 -303.859184)
		(end 198.430388 -303.859184)
		(width 0.16002)
		(layer "In6.Cu")
		(net "M_K_CPU1_SB_DQS_DP<2>")
	)
	(segment
		(start 169.595292 -302.860202)
		(end 170.445176 -303.710086)
		(width 0.16002)
		(layer "In6.Cu")
		(net "M_K_CPU1_SB_DQS_DP<2>")
	)
	(segment
		(start 180.399182 -303.710086)
		(end 180.739796 -304.0507)
		(width 0.16002)
		(layer "In6.Cu")
		(net "M_K_CPU1_SB_DQS_DP<2>")
	)
	(segment
		(start 188.68517 -304.0507)
		(end 189.53607 -303.1998)
		(width 0.16002)
		(layer "In6.Cu")
		(net "M_K_CPU1_SB_DQS_DP<2>")
	)
	(segment
		(start 147.45716 -286.525716)
		(end 147.60829 -286.676846)
		(width 0.09525)
		(layer "In6.Cu")
		(net "M_K_CPU1_SB_DQS_DP<2>")
	)
	(segment
		(start 148.270722 -286.617664)
		(end 154.668982 -293.015924)
		(width 0.16002)
		(layer "In6.Cu")
		(net "M_K_CPU1_SB_DQS_DP<2>")
	)
	(segment
		(start 189.92469 -303.1998)
		(end 190.264288 -302.860202)
		(width 0.16002)
		(layer "In6.Cu")
		(net "M_K_CPU1_SB_DQS_DP<2>")
	)
	(segment
		(start 181.141116 -304.0507)
		(end 181.992016 -303.1998)
		(width 0.16002)
		(layer "In6.Cu")
		(net "M_K_CPU1_SB_DQS_DP<2>")
	)
	(segment
		(start 195.831206 -304.05832)
		(end 196.210682 -304.05832)
		(width 0.16002)
		(layer "In6.Cu")
		(net "M_K_CPU1_SB_DQS_DP<2>")
	)
	(segment
		(start 142.62481 -285.426404)
		(end 142.778734 -285.691834)
		(width 0.09525)
		(layer "In6.Cu")
		(net "M_K_CPU1_SB_DQS_DP<2>")
	)
	(segment
		(start 189.53607 -303.1998)
		(end 189.92469 -303.1998)
		(width 0.16002)
		(layer "In6.Cu")
		(net "M_K_CPU1_SB_DQS_DP<2>")
	)
	(segment
		(start 163.638738 -304.0507)
		(end 166.053008 -304.0507)
		(width 0.16002)
		(layer "In6.Cu")
		(net "M_K_CPU1_SB_DQS_DP<2>")
	)
	(segment
		(start 173.195742 -304.0507)
		(end 173.597062 -304.0507)
		(width 0.16002)
		(layer "In6.Cu")
		(net "M_K_CPU1_SB_DQS_DP<2>")
	)
	(segment
		(start 143.376142 -285.751524)
		(end 143.384524 -285.75635)
		(width 0.09525)
		(layer "In6.Cu")
		(net "M_K_CPU1_SB_DQS_DP<2>")
	)
	(segment
		(start 166.053008 -304.0507)
		(end 166.903908 -303.1998)
		(width 0.16002)
		(layer "In6.Cu")
		(net "M_K_CPU1_SB_DQS_DP<2>")
	)
	(segment
		(start 167.632126 -302.860202)
		(end 169.595292 -302.860202)
		(width 0.16002)
		(layer "In6.Cu")
		(net "M_K_CPU1_SB_DQS_DP<2>")
	)
	(segment
		(start 192.996312 -303.434242)
		(end 195.207128 -303.434242)
		(width 0.16002)
		(layer "In6.Cu")
		(net "M_K_CPU1_SB_DQS_DP<2>")
	)
	(segment
		(start 181.992016 -303.1998)
		(end 182.380636 -303.1998)
		(width 0.16002)
		(layer "In6.Cu")
		(net "M_K_CPU1_SB_DQS_DP<2>")
	)
	(segment
		(start 177.98923 -303.710086)
		(end 180.399182 -303.710086)
		(width 0.16002)
		(layer "In6.Cu")
		(net "M_K_CPU1_SB_DQS_DP<2>")
	)
	(segment
		(start 180.739796 -304.0507)
		(end 181.141116 -304.0507)
		(width 0.16002)
		(layer "In6.Cu")
		(net "M_K_CPU1_SB_DQS_DP<2>")
	)
	(segment
		(start 147.836382 -286.676846)
		(end 147.895564 -286.617664)
		(width 0.09525)
		(layer "In6.Cu")
		(net "M_K_CPU1_SB_DQS_DP<2>")
	)
	(segment
		(start 184.6834 -302.860202)
		(end 185.533284 -303.710086)
		(width 0.16002)
		(layer "In6.Cu")
		(net "M_K_CPU1_SB_DQS_DP<2>")
	)
	(segment
		(start 192.422272 -302.860202)
		(end 192.996312 -303.434242)
		(width 0.16002)
		(layer "In6.Cu")
		(net "M_K_CPU1_SB_DQS_DP<2>")
	)
	(segment
		(start 172.855128 -303.710086)
		(end 173.195742 -304.0507)
		(width 0.16002)
		(layer "In6.Cu")
		(net "M_K_CPU1_SB_DQS_DP<2>")
	)
	(segment
		(start 175.17618 -302.860202)
		(end 177.139346 -302.860202)
		(width 0.16002)
		(layer "In6.Cu")
		(net "M_K_CPU1_SB_DQS_DP<2>")
	)
	(segment
		(start 174.447962 -303.1998)
		(end 174.836582 -303.1998)
		(width 0.16002)
		(layer "In6.Cu")
		(net "M_K_CPU1_SB_DQS_DP<2>")
	)
	(segment
		(start 170.445176 -303.710086)
		(end 172.855128 -303.710086)
		(width 0.16002)
		(layer "In6.Cu")
		(net "M_K_CPU1_SB_DQS_DP<2>")
	)
	(segment
		(start 147.919186 -286.617664)
		(end 148.270722 -286.617664)
		(width 0.16002)
		(layer "In6.Cu")
		(net "M_K_CPU1_SB_DQS_DP<2>")
	)
	(segment
		(start 173.597062 -304.0507)
		(end 174.447962 -303.1998)
		(width 0.16002)
		(layer "In6.Cu")
		(net "M_K_CPU1_SB_DQS_DP<2>")
	)
	(segment
		(start 142.778734 -285.691834)
		(end 142.879572 -285.718504)
		(width 0.09525)
		(layer "In6.Cu")
		(net "M_K_CPU1_SB_DQS_DP<2>")
	)
	(segment
		(start 154.668982 -296.221404)
		(end 157.060392 -298.612814)
		(width 0.16002)
		(layer "In6.Cu")
		(net "M_K_CPU1_SB_DQS_DP<2>")
	)
	(segment
		(start 196.210682 -304.05832)
		(end 196.409818 -303.859184)
		(width 0.16002)
		(layer "In6.Cu")
		(net "M_K_CPU1_SB_DQS_DP<2>")
	)
	(segment
		(start 177.139346 -302.860202)
		(end 177.98923 -303.710086)
		(width 0.16002)
		(layer "In6.Cu")
		(net "M_K_CPU1_SB_DQS_DP<2>")
	)
	(segment
		(start 195.207128 -303.434242)
		(end 195.831206 -304.05832)
		(width 0.16002)
		(layer "In6.Cu")
		(net "M_K_CPU1_SB_DQS_DP<2>")
	)
	(segment
		(start 146.63293 -286.525716)
		(end 147.45716 -286.525716)
		(width 0.09525)
		(layer "In6.Cu")
		(net "M_K_CPU1_SB_DQS_DP<2>")
	)
	(segment
		(start 187.943236 -303.710086)
		(end 188.28385 -304.0507)
		(width 0.16002)
		(layer "In6.Cu")
		(net "M_K_CPU1_SB_DQS_DP<2>")
	)
	(segment
		(start 190.264288 -302.860202)
		(end 192.422272 -302.860202)
		(width 0.16002)
		(layer "In6.Cu")
		(net "M_K_CPU1_SB_DQS_DP<2>")
	)
	(segment
		(start 182.720234 -302.860202)
		(end 184.6834 -302.860202)
		(width 0.16002)
		(layer "In6.Cu")
		(net "M_K_CPU1_SB_DQS_DP<2>")
	)
	(segment
		(start 198.430388 -303.859184)
		(end 198.7042 -303.585372)
		(width 0.16002)
		(layer "In6.Cu")
		(net "M_K_CPU1_SB_DQS_DP<2>")
	)
	(segment
		(start 188.28385 -304.0507)
		(end 188.68517 -304.0507)
		(width 0.16002)
		(layer "In6.Cu")
		(net "M_K_CPU1_SB_DQS_DP<2>")
	)
	(segment
		(start 157.060392 -298.612814)
		(end 158.200852 -298.612814)
		(width 0.16002)
		(layer "In6.Cu")
		(net "M_K_CPU1_SB_DQS_DP<2>")
	)
	(segment
		(start 147.895564 -286.617664)
		(end 147.919186 -286.617664)
		(width 0.09525)
		(layer "In6.Cu")
		(net "M_K_CPU1_SB_DQS_DP<2>")
	)
	(segment
		(start 147.60829 -286.676846)
		(end 147.836382 -286.676846)
		(width 0.09525)
		(layer "In6.Cu")
		(net "M_K_CPU1_SB_DQS_DP<2>")
	)
	(segment
		(start 166.903908 -303.1998)
		(end 167.292528 -303.1998)
		(width 0.16002)
		(layer "In6.Cu")
		(net "M_K_CPU1_SB_DQS_DP<2>")
	)
	(segment
		(start 185.533284 -303.710086)
		(end 187.943236 -303.710086)
		(width 0.16002)
		(layer "In6.Cu")
		(net "M_K_CPU1_SB_DQS_DP<2>")
	)
	(arc
		(start 143.753332 -285.751524)
		(mid 144.034764 -285.675769)
		(end 144.316196 -285.751524)
		(width 0.09525)
		(layer "In6.Cu")
		(net "M_K_CPU1_SB_DQS_DP<2>")
	)
	(arc
		(start 144.707864 -285.742888)
		(mid 144.983069 -285.675624)
		(end 145.255996 -285.751524)
		(width 0.09525)
		(layer "In6.Cu")
		(net "M_K_CPU1_SB_DQS_DP<2>")
	)
	(arc
		(start 142.879572 -285.718504)
		(mid 143.131713 -285.676934)
		(end 143.376142 -285.751524)
		(width 0.09525)
		(layer "In6.Cu")
		(net "M_K_CPU1_SB_DQS_DP<2>")
	)
	(arc
		(start 145.255996 -285.751524)
		(mid 145.346942 -285.789825)
		(end 145.444718 -285.803086)
		(width 0.09525)
		(layer "In6.Cu")
		(net "M_K_CPU1_SB_DQS_DP<2>")
	)
	(arc
		(start 143.384524 -285.75635)
		(mid 143.569556 -285.802264)
		(end 143.753332 -285.751524)
		(width 0.09525)
		(layer "In6.Cu")
		(net "M_K_CPU1_SB_DQS_DP<2>")
	)
	(arc
		(start 144.316196 -285.751524)
		(mid 144.504664 -285.802201)
		(end 144.693132 -285.751524)
		(width 0.09525)
		(layer "In6.Cu")
		(net "M_K_CPU1_SB_DQS_DP<2>")
	)
	(segment
		(start 142.157958 -280.30043)
		(end 142.62481 -280.566368)
		(width 0.12954)
		(layer "F.Cu")
		(net "M_K_CPU1_SB_DQS_DP<1>")
	)
	(segment
		(start 147.818602 -280.941526)
		(end 150.791672 -280.941526)
		(width 0.16002)
		(layer "In6.Cu")
		(net "M_K_CPU1_SB_DQS_DP<1>")
	)
	(segment
		(start 145.578068 -280.94305)
		(end 145.681446 -280.900124)
		(width 0.09525)
		(layer "In6.Cu")
		(net "M_K_CPU1_SB_DQS_DP<1>")
	)
	(segment
		(start 177.139346 -293.510208)
		(end 177.98923 -294.360092)
		(width 0.16002)
		(layer "In6.Cu")
		(net "M_K_CPU1_SB_DQS_DP<1>")
	)
	(segment
		(start 180.739796 -294.700706)
		(end 181.141116 -294.700706)
		(width 0.16002)
		(layer "In6.Cu")
		(net "M_K_CPU1_SB_DQS_DP<1>")
	)
	(segment
		(start 192.996312 -294.084248)
		(end 195.207128 -294.084248)
		(width 0.16002)
		(layer "In6.Cu")
		(net "M_K_CPU1_SB_DQS_DP<1>")
	)
	(segment
		(start 175.17618 -293.510208)
		(end 177.139346 -293.510208)
		(width 0.16002)
		(layer "In6.Cu")
		(net "M_K_CPU1_SB_DQS_DP<1>")
	)
	(segment
		(start 184.6834 -293.510208)
		(end 185.533284 -294.360092)
		(width 0.16002)
		(layer "In6.Cu")
		(net "M_K_CPU1_SB_DQS_DP<1>")
	)
	(segment
		(start 195.831206 -294.708326)
		(end 196.210682 -294.708326)
		(width 0.16002)
		(layer "In6.Cu")
		(net "M_K_CPU1_SB_DQS_DP<1>")
	)
	(segment
		(start 170.709336 -294.360092)
		(end 172.855128 -294.360092)
		(width 0.16002)
		(layer "In6.Cu")
		(net "M_K_CPU1_SB_DQS_DP<1>")
	)
	(segment
		(start 173.597062 -294.700706)
		(end 174.447962 -293.849806)
		(width 0.16002)
		(layer "In6.Cu")
		(net "M_K_CPU1_SB_DQS_DP<1>")
	)
	(segment
		(start 142.778734 -280.831798)
		(end 142.879572 -280.858468)
		(width 0.09525)
		(layer "In6.Cu")
		(net "M_K_CPU1_SB_DQS_DP<1>")
	)
	(segment
		(start 198.430388 -294.50919)
		(end 198.7042 -294.235378)
		(width 0.16002)
		(layer "In6.Cu")
		(net "M_K_CPU1_SB_DQS_DP<1>")
	)
	(segment
		(start 189.92469 -293.849806)
		(end 190.264288 -293.510208)
		(width 0.16002)
		(layer "In6.Cu")
		(net "M_K_CPU1_SB_DQS_DP<1>")
	)
	(segment
		(start 196.210682 -294.708326)
		(end 196.409818 -294.50919)
		(width 0.16002)
		(layer "In6.Cu")
		(net "M_K_CPU1_SB_DQS_DP<1>")
	)
	(segment
		(start 166.053008 -294.700706)
		(end 166.903908 -293.849806)
		(width 0.16002)
		(layer "In6.Cu")
		(net "M_K_CPU1_SB_DQS_DP<1>")
	)
	(segment
		(start 143.376142 -280.891488)
		(end 143.384524 -280.896314)
		(width 0.09525)
		(layer "In6.Cu")
		(net "M_K_CPU1_SB_DQS_DP<1>")
	)
	(segment
		(start 185.533284 -294.360092)
		(end 187.943236 -294.360092)
		(width 0.16002)
		(layer "In6.Cu")
		(net "M_K_CPU1_SB_DQS_DP<1>")
	)
	(segment
		(start 164.550852 -294.700706)
		(end 166.053008 -294.700706)
		(width 0.16002)
		(layer "In6.Cu")
		(net "M_K_CPU1_SB_DQS_DP<1>")
	)
	(segment
		(start 174.447962 -293.849806)
		(end 174.836582 -293.849806)
		(width 0.16002)
		(layer "In6.Cu")
		(net "M_K_CPU1_SB_DQS_DP<1>")
	)
	(segment
		(start 166.903908 -293.849806)
		(end 170.19905 -293.849806)
		(width 0.16002)
		(layer "In6.Cu")
		(net "M_K_CPU1_SB_DQS_DP<1>")
	)
	(segment
		(start 147.68576 -280.80843)
		(end 147.702524 -280.825194)
		(width 0.09525)
		(layer "In6.Cu")
		(net "M_K_CPU1_SB_DQS_DP<1>")
	)
	(segment
		(start 145.681446 -280.900124)
		(end 146.0246 -280.55697)
		(width 0.09525)
		(layer "In6.Cu")
		(net "M_K_CPU1_SB_DQS_DP<1>")
	)
	(segment
		(start 142.62481 -280.566368)
		(end 142.778734 -280.831798)
		(width 0.09525)
		(layer "In6.Cu")
		(net "M_K_CPU1_SB_DQS_DP<1>")
	)
	(segment
		(start 177.98923 -294.360092)
		(end 180.399182 -294.360092)
		(width 0.16002)
		(layer "In6.Cu")
		(net "M_K_CPU1_SB_DQS_DP<1>")
	)
	(segment
		(start 180.399182 -294.360092)
		(end 180.739796 -294.700706)
		(width 0.16002)
		(layer "In6.Cu")
		(net "M_K_CPU1_SB_DQS_DP<1>")
	)
	(segment
		(start 192.422272 -293.510208)
		(end 192.996312 -294.084248)
		(width 0.16002)
		(layer "In6.Cu")
		(net "M_K_CPU1_SB_DQS_DP<1>")
	)
	(segment
		(start 182.380636 -293.849806)
		(end 182.720234 -293.510208)
		(width 0.16002)
		(layer "In6.Cu")
		(net "M_K_CPU1_SB_DQS_DP<1>")
	)
	(segment
		(start 144.693132 -280.891488)
		(end 144.707864 -280.882852)
		(width 0.09525)
		(layer "In6.Cu")
		(net "M_K_CPU1_SB_DQS_DP<1>")
	)
	(segment
		(start 182.720234 -293.510208)
		(end 184.6834 -293.510208)
		(width 0.16002)
		(layer "In6.Cu")
		(net "M_K_CPU1_SB_DQS_DP<1>")
	)
	(segment
		(start 189.53607 -293.849806)
		(end 189.92469 -293.849806)
		(width 0.16002)
		(layer "In6.Cu")
		(net "M_K_CPU1_SB_DQS_DP<1>")
	)
	(segment
		(start 174.836582 -293.849806)
		(end 175.17618 -293.510208)
		(width 0.16002)
		(layer "In6.Cu")
		(net "M_K_CPU1_SB_DQS_DP<1>")
	)
	(segment
		(start 181.992016 -293.849806)
		(end 182.380636 -293.849806)
		(width 0.16002)
		(layer "In6.Cu")
		(net "M_K_CPU1_SB_DQS_DP<1>")
	)
	(segment
		(start 195.207128 -294.084248)
		(end 195.831206 -294.708326)
		(width 0.16002)
		(layer "In6.Cu")
		(net "M_K_CPU1_SB_DQS_DP<1>")
	)
	(segment
		(start 147.350226 -280.55697)
		(end 147.601686 -280.80843)
		(width 0.09525)
		(layer "In6.Cu")
		(net "M_K_CPU1_SB_DQS_DP<1>")
	)
	(segment
		(start 190.264288 -293.510208)
		(end 192.422272 -293.510208)
		(width 0.16002)
		(layer "In6.Cu")
		(net "M_K_CPU1_SB_DQS_DP<1>")
	)
	(segment
		(start 173.195742 -294.700706)
		(end 173.597062 -294.700706)
		(width 0.16002)
		(layer "In6.Cu")
		(net "M_K_CPU1_SB_DQS_DP<1>")
	)
	(segment
		(start 196.409818 -294.50919)
		(end 198.430388 -294.50919)
		(width 0.16002)
		(layer "In6.Cu")
		(net "M_K_CPU1_SB_DQS_DP<1>")
	)
	(segment
		(start 147.601686 -280.80843)
		(end 147.68576 -280.80843)
		(width 0.09525)
		(layer "In6.Cu")
		(net "M_K_CPU1_SB_DQS_DP<1>")
	)
	(segment
		(start 188.28385 -294.700706)
		(end 188.68517 -294.700706)
		(width 0.16002)
		(layer "In6.Cu")
		(net "M_K_CPU1_SB_DQS_DP<1>")
	)
	(segment
		(start 150.791672 -280.941526)
		(end 164.550852 -294.700706)
		(width 0.16002)
		(layer "In6.Cu")
		(net "M_K_CPU1_SB_DQS_DP<1>")
	)
	(segment
		(start 146.0246 -280.55697)
		(end 147.350226 -280.55697)
		(width 0.09525)
		(layer "In6.Cu")
		(net "M_K_CPU1_SB_DQS_DP<1>")
	)
	(segment
		(start 188.68517 -294.700706)
		(end 189.53607 -293.849806)
		(width 0.16002)
		(layer "In6.Cu")
		(net "M_K_CPU1_SB_DQS_DP<1>")
	)
	(segment
		(start 181.141116 -294.700706)
		(end 181.992016 -293.849806)
		(width 0.16002)
		(layer "In6.Cu")
		(net "M_K_CPU1_SB_DQS_DP<1>")
	)
	(segment
		(start 145.444718 -280.94305)
		(end 145.578068 -280.94305)
		(width 0.09525)
		(layer "In6.Cu")
		(net "M_K_CPU1_SB_DQS_DP<1>")
	)
	(segment
		(start 187.943236 -294.360092)
		(end 188.28385 -294.700706)
		(width 0.16002)
		(layer "In6.Cu")
		(net "M_K_CPU1_SB_DQS_DP<1>")
	)
	(segment
		(start 172.855128 -294.360092)
		(end 173.195742 -294.700706)
		(width 0.16002)
		(layer "In6.Cu")
		(net "M_K_CPU1_SB_DQS_DP<1>")
	)
	(segment
		(start 170.19905 -293.849806)
		(end 170.709336 -294.360092)
		(width 0.16002)
		(layer "In6.Cu")
		(net "M_K_CPU1_SB_DQS_DP<1>")
	)
	(segment
		(start 147.702524 -280.825194)
		(end 147.818602 -280.941526)
		(width 0.16002)
		(layer "In6.Cu")
		(net "M_K_CPU1_SB_DQS_DP<1>")
	)
	(arc
		(start 143.753332 -280.891488)
		(mid 144.034764 -280.815733)
		(end 144.316196 -280.891488)
		(width 0.09525)
		(layer "In6.Cu")
		(net "M_K_CPU1_SB_DQS_DP<1>")
	)
	(arc
		(start 142.879572 -280.858468)
		(mid 143.131713 -280.816898)
		(end 143.376142 -280.891488)
		(width 0.09525)
		(layer "In6.Cu")
		(net "M_K_CPU1_SB_DQS_DP<1>")
	)
	(arc
		(start 143.384524 -280.896314)
		(mid 143.569556 -280.942228)
		(end 143.753332 -280.891488)
		(width 0.09525)
		(layer "In6.Cu")
		(net "M_K_CPU1_SB_DQS_DP<1>")
	)
	(arc
		(start 145.255996 -280.891488)
		(mid 145.346942 -280.929789)
		(end 145.444718 -280.94305)
		(width 0.09525)
		(layer "In6.Cu")
		(net "M_K_CPU1_SB_DQS_DP<1>")
	)
	(arc
		(start 144.707864 -280.882852)
		(mid 144.983069 -280.815588)
		(end 145.255996 -280.891488)
		(width 0.09525)
		(layer "In6.Cu")
		(net "M_K_CPU1_SB_DQS_DP<1>")
	)
	(arc
		(start 144.316196 -280.891488)
		(mid 144.504664 -280.942165)
		(end 144.693132 -280.891488)
		(width 0.09525)
		(layer "In6.Cu")
		(net "M_K_CPU1_SB_DQS_DP<1>")
	)
	(segment
		(start 142.157958 -275.440394)
		(end 142.62481 -275.706332)
		(width 0.12954)
		(layer "F.Cu")
		(net "M_K_CPU1_SB_DQS_DP<0>")
	)
	(segment
		(start 187.943236 -285.010098)
		(end 188.28385 -285.350712)
		(width 0.16002)
		(layer "In6.Cu")
		(net "M_K_CPU1_SB_DQS_DP<0>")
	)
	(segment
		(start 166.903908 -284.499812)
		(end 167.371522 -284.499812)
		(width 0.16002)
		(layer "In6.Cu")
		(net "M_K_CPU1_SB_DQS_DP<0>")
	)
	(segment
		(start 147.895564 -274.89785)
		(end 147.919186 -274.89785)
		(width 0.09525)
		(layer "In6.Cu")
		(net "M_K_CPU1_SB_DQS_DP<0>")
	)
	(segment
		(start 195.831206 -285.358332)
		(end 196.210682 -285.358332)
		(width 0.16002)
		(layer "In6.Cu")
		(net "M_K_CPU1_SB_DQS_DP<0>")
	)
	(segment
		(start 143.376142 -276.031452)
		(end 143.384524 -276.036278)
		(width 0.09525)
		(layer "In6.Cu")
		(net "M_K_CPU1_SB_DQS_DP<0>")
	)
	(segment
		(start 171.467272 -285.010098)
		(end 172.855128 -285.010098)
		(width 0.16002)
		(layer "In6.Cu")
		(net "M_K_CPU1_SB_DQS_DP<0>")
	)
	(segment
		(start 169.714418 -284.284166)
		(end 171.467272 -285.010098)
		(width 0.16002)
		(layer "In6.Cu")
		(net "M_K_CPU1_SB_DQS_DP<0>")
	)
	(segment
		(start 147.266914 -274.957032)
		(end 147.836382 -274.957032)
		(width 0.09525)
		(layer "In6.Cu")
		(net "M_K_CPU1_SB_DQS_DP<0>")
	)
	(segment
		(start 192.996312 -284.734254)
		(end 195.207128 -284.734254)
		(width 0.16002)
		(layer "In6.Cu")
		(net "M_K_CPU1_SB_DQS_DP<0>")
	)
	(segment
		(start 192.422272 -284.160214)
		(end 192.996312 -284.734254)
		(width 0.16002)
		(layer "In6.Cu")
		(net "M_K_CPU1_SB_DQS_DP<0>")
	)
	(segment
		(start 144.693132 -276.031452)
		(end 144.707864 -276.022816)
		(width 0.09525)
		(layer "In6.Cu")
		(net "M_K_CPU1_SB_DQS_DP<0>")
	)
	(segment
		(start 167.371522 -284.499812)
		(end 167.587168 -284.284166)
		(width 0.16002)
		(layer "In6.Cu")
		(net "M_K_CPU1_SB_DQS_DP<0>")
	)
	(segment
		(start 174.046134 -284.90164)
		(end 175.836072 -284.160214)
		(width 0.16002)
		(layer "In6.Cu")
		(net "M_K_CPU1_SB_DQS_DP<0>")
	)
	(segment
		(start 177.98923 -285.010098)
		(end 180.399182 -285.010098)
		(width 0.16002)
		(layer "In6.Cu")
		(net "M_K_CPU1_SB_DQS_DP<0>")
	)
	(segment
		(start 180.739796 -285.350712)
		(end 181.141116 -285.350712)
		(width 0.16002)
		(layer "In6.Cu")
		(net "M_K_CPU1_SB_DQS_DP<0>")
	)
	(segment
		(start 196.409818 -285.159196)
		(end 198.430388 -285.159196)
		(width 0.16002)
		(layer "In6.Cu")
		(net "M_K_CPU1_SB_DQS_DP<0>")
	)
	(segment
		(start 188.28385 -285.350712)
		(end 188.68517 -285.350712)
		(width 0.16002)
		(layer "In6.Cu")
		(net "M_K_CPU1_SB_DQS_DP<0>")
	)
	(segment
		(start 173.597062 -285.350712)
		(end 174.046134 -284.90164)
		(width 0.16002)
		(layer "In6.Cu")
		(net "M_K_CPU1_SB_DQS_DP<0>")
	)
	(segment
		(start 181.141116 -285.350712)
		(end 181.992016 -284.499812)
		(width 0.16002)
		(layer "In6.Cu")
		(net "M_K_CPU1_SB_DQS_DP<0>")
	)
	(segment
		(start 185.533284 -285.010098)
		(end 187.943236 -285.010098)
		(width 0.16002)
		(layer "In6.Cu")
		(net "M_K_CPU1_SB_DQS_DP<0>")
	)
	(segment
		(start 146.645376 -275.038058)
		(end 147.185888 -275.038058)
		(width 0.09525)
		(layer "In6.Cu")
		(net "M_K_CPU1_SB_DQS_DP<0>")
	)
	(segment
		(start 142.778734 -275.971762)
		(end 142.879572 -275.998432)
		(width 0.09525)
		(layer "In6.Cu")
		(net "M_K_CPU1_SB_DQS_DP<0>")
	)
	(segment
		(start 181.992016 -284.499812)
		(end 182.380636 -284.499812)
		(width 0.16002)
		(layer "In6.Cu")
		(net "M_K_CPU1_SB_DQS_DP<0>")
	)
	(segment
		(start 147.919186 -274.89785)
		(end 153.456894 -274.89785)
		(width 0.16002)
		(layer "In6.Cu")
		(net "M_K_CPU1_SB_DQS_DP<0>")
	)
	(segment
		(start 147.185888 -275.038058)
		(end 147.266914 -274.957032)
		(width 0.09525)
		(layer "In6.Cu")
		(net "M_K_CPU1_SB_DQS_DP<0>")
	)
	(segment
		(start 173.195742 -285.350712)
		(end 173.597062 -285.350712)
		(width 0.16002)
		(layer "In6.Cu")
		(net "M_K_CPU1_SB_DQS_DP<0>")
	)
	(segment
		(start 190.264288 -284.160214)
		(end 192.422272 -284.160214)
		(width 0.16002)
		(layer "In6.Cu")
		(net "M_K_CPU1_SB_DQS_DP<0>")
	)
	(segment
		(start 163.909756 -285.350712)
		(end 166.053008 -285.350712)
		(width 0.16002)
		(layer "In6.Cu")
		(net "M_K_CPU1_SB_DQS_DP<0>")
	)
	(segment
		(start 166.053008 -285.350712)
		(end 166.903908 -284.499812)
		(width 0.16002)
		(layer "In6.Cu")
		(net "M_K_CPU1_SB_DQS_DP<0>")
	)
	(segment
		(start 177.139346 -284.160214)
		(end 177.98923 -285.010098)
		(width 0.16002)
		(layer "In6.Cu")
		(net "M_K_CPU1_SB_DQS_DP<0>")
	)
	(segment
		(start 188.68517 -285.350712)
		(end 189.53607 -284.499812)
		(width 0.16002)
		(layer "In6.Cu")
		(net "M_K_CPU1_SB_DQS_DP<0>")
	)
	(segment
		(start 198.430388 -285.159196)
		(end 198.7042 -284.885384)
		(width 0.16002)
		(layer "In6.Cu")
		(net "M_K_CPU1_SB_DQS_DP<0>")
	)
	(segment
		(start 196.210682 -285.358332)
		(end 196.409818 -285.159196)
		(width 0.16002)
		(layer "In6.Cu")
		(net "M_K_CPU1_SB_DQS_DP<0>")
	)
	(segment
		(start 182.720234 -284.160214)
		(end 184.6834 -284.160214)
		(width 0.16002)
		(layer "In6.Cu")
		(net "M_K_CPU1_SB_DQS_DP<0>")
	)
	(segment
		(start 175.836072 -284.160214)
		(end 177.139346 -284.160214)
		(width 0.16002)
		(layer "In6.Cu")
		(net "M_K_CPU1_SB_DQS_DP<0>")
	)
	(segment
		(start 189.53607 -284.499812)
		(end 189.92469 -284.499812)
		(width 0.16002)
		(layer "In6.Cu")
		(net "M_K_CPU1_SB_DQS_DP<0>")
	)
	(segment
		(start 147.836382 -274.957032)
		(end 147.895564 -274.89785)
		(width 0.09525)
		(layer "In6.Cu")
		(net "M_K_CPU1_SB_DQS_DP<0>")
	)
	(segment
		(start 189.92469 -284.499812)
		(end 190.264288 -284.160214)
		(width 0.16002)
		(layer "In6.Cu")
		(net "M_K_CPU1_SB_DQS_DP<0>")
	)
	(segment
		(start 180.399182 -285.010098)
		(end 180.739796 -285.350712)
		(width 0.16002)
		(layer "In6.Cu")
		(net "M_K_CPU1_SB_DQS_DP<0>")
	)
	(segment
		(start 142.62481 -275.706332)
		(end 142.778734 -275.971762)
		(width 0.09525)
		(layer "In6.Cu")
		(net "M_K_CPU1_SB_DQS_DP<0>")
	)
	(segment
		(start 167.587168 -284.284166)
		(end 169.714418 -284.284166)
		(width 0.16002)
		(layer "In6.Cu")
		(net "M_K_CPU1_SB_DQS_DP<0>")
	)
	(segment
		(start 153.456894 -274.89785)
		(end 163.909756 -285.350712)
		(width 0.16002)
		(layer "In6.Cu")
		(net "M_K_CPU1_SB_DQS_DP<0>")
	)
	(segment
		(start 195.207128 -284.734254)
		(end 195.831206 -285.358332)
		(width 0.16002)
		(layer "In6.Cu")
		(net "M_K_CPU1_SB_DQS_DP<0>")
	)
	(segment
		(start 184.6834 -284.160214)
		(end 185.533284 -285.010098)
		(width 0.16002)
		(layer "In6.Cu")
		(net "M_K_CPU1_SB_DQS_DP<0>")
	)
	(segment
		(start 172.855128 -285.010098)
		(end 173.195742 -285.350712)
		(width 0.16002)
		(layer "In6.Cu")
		(net "M_K_CPU1_SB_DQS_DP<0>")
	)
	(segment
		(start 182.380636 -284.499812)
		(end 182.720234 -284.160214)
		(width 0.16002)
		(layer "In6.Cu")
		(net "M_K_CPU1_SB_DQS_DP<0>")
	)
	(segment
		(start 145.71091 -275.972524)
		(end 146.645376 -275.038058)
		(width 0.09525)
		(layer "In6.Cu")
		(net "M_K_CPU1_SB_DQS_DP<0>")
	)
	(arc
		(start 142.899384 -275.990558)
		(mid 143.142348 -275.957571)
		(end 143.376142 -276.031452)
		(width 0.09525)
		(layer "In6.Cu")
		(net "M_K_CPU1_SB_DQS_DP<0>")
	)
	(arc
		(start 143.753332 -276.031452)
		(mid 144.034764 -275.955697)
		(end 144.316196 -276.031452)
		(width 0.09525)
		(layer "In6.Cu")
		(net "M_K_CPU1_SB_DQS_DP<0>")
	)
	(arc
		(start 145.255996 -276.031452)
		(mid 145.437612 -276.082189)
		(end 145.620994 -276.03831)
		(width 0.09525)
		(layer "In6.Cu")
		(net "M_K_CPU1_SB_DQS_DP<0>")
	)
	(arc
		(start 145.620994 -276.03831)
		(mid 145.668403 -276.008767)
		(end 145.71091 -275.972524)
		(width 0.09525)
		(layer "In6.Cu")
		(net "M_K_CPU1_SB_DQS_DP<0>")
	)
	(arc
		(start 143.384524 -276.036278)
		(mid 143.569556 -276.082192)
		(end 143.753332 -276.031452)
		(width 0.09525)
		(layer "In6.Cu")
		(net "M_K_CPU1_SB_DQS_DP<0>")
	)
	(arc
		(start 142.879572 -275.998432)
		(mid 142.88944 -275.994401)
		(end 142.899384 -275.990558)
		(width 0.09525)
		(layer "In6.Cu")
		(net "M_K_CPU1_SB_DQS_DP<0>")
	)
	(arc
		(start 144.316196 -276.031452)
		(mid 144.504664 -276.082129)
		(end 144.693132 -276.031452)
		(width 0.09525)
		(layer "In6.Cu")
		(net "M_K_CPU1_SB_DQS_DP<0>")
	)
	(arc
		(start 144.707864 -276.022816)
		(mid 144.983069 -275.955552)
		(end 145.255996 -276.031452)
		(width 0.09525)
		(layer "In6.Cu")
		(net "M_K_CPU1_SB_DQS_DP<0>")
	)
	(segment
		(start 142.627858 -271.390364)
		(end 143.09471 -271.656302)
		(width 0.12954)
		(layer "F.Cu")
		(net "M_K_CPU1_SB_DQS_DN<9>")
	)
	(segment
		(start 146.699224 -269.362936)
		(end 147.219416 -269.362936)
		(width 0.09525)
		(layer "In6.Cu")
		(net "M_K_CPU1_SB_DQS_DN<9>")
	)
	(segment
		(start 172.729906 -275.962364)
		(end 173.07052 -276.302978)
		(width 0.16002)
		(layer "In6.Cu")
		(net "M_K_CPU1_SB_DQS_DN<9>")
	)
	(segment
		(start 192.29705 -275.11248)
		(end 192.87109 -275.68652)
		(width 0.16002)
		(layer "In6.Cu")
		(net "M_K_CPU1_SB_DQS_DN<9>")
	)
	(segment
		(start 196.335904 -276.310598)
		(end 196.53504 -276.111462)
		(width 0.16002)
		(layer "In6.Cu")
		(net "M_K_CPU1_SB_DQS_DN<9>")
	)
	(segment
		(start 174.573184 -275.452078)
		(end 174.961804 -275.452078)
		(width 0.16002)
		(layer "In6.Cu")
		(net "M_K_CPU1_SB_DQS_DN<9>")
	)
	(segment
		(start 190.049912 -275.452078)
		(end 190.38951 -275.11248)
		(width 0.16002)
		(layer "In6.Cu")
		(net "M_K_CPU1_SB_DQS_DN<9>")
	)
	(segment
		(start 175.301402 -275.11248)
		(end 177.014124 -275.11248)
		(width 0.16002)
		(layer "In6.Cu")
		(net "M_K_CPU1_SB_DQS_DN<9>")
	)
	(segment
		(start 195.081906 -275.68652)
		(end 195.705984 -276.310598)
		(width 0.16002)
		(layer "In6.Cu")
		(net "M_K_CPU1_SB_DQS_DN<9>")
	)
	(segment
		(start 192.87109 -275.68652)
		(end 195.081906 -275.68652)
		(width 0.16002)
		(layer "In6.Cu")
		(net "M_K_CPU1_SB_DQS_DN<9>")
	)
	(segment
		(start 167.02913 -275.452078)
		(end 167.41775 -275.452078)
		(width 0.16002)
		(layer "In6.Cu")
		(net "M_K_CPU1_SB_DQS_DN<9>")
	)
	(segment
		(start 158.142178 -269.555214)
		(end 164.889942 -276.302978)
		(width 0.16002)
		(layer "In6.Cu")
		(net "M_K_CPU1_SB_DQS_DN<9>")
	)
	(segment
		(start 184.558178 -275.11248)
		(end 185.408062 -275.962364)
		(width 0.16002)
		(layer "In6.Cu")
		(net "M_K_CPU1_SB_DQS_DN<9>")
	)
	(segment
		(start 167.757348 -275.11248)
		(end 169.47007 -275.11248)
		(width 0.16002)
		(layer "In6.Cu")
		(net "M_K_CPU1_SB_DQS_DN<9>")
	)
	(segment
		(start 198.430388 -276.111462)
		(end 198.7042 -276.385274)
		(width 0.16002)
		(layer "In6.Cu")
		(net "M_K_CPU1_SB_DQS_DN<9>")
	)
	(segment
		(start 147.219416 -269.362936)
		(end 147.352766 -269.496286)
		(width 0.09525)
		(layer "In6.Cu")
		(net "M_K_CPU1_SB_DQS_DN<9>")
	)
	(segment
		(start 182.117238 -275.452078)
		(end 182.505858 -275.452078)
		(width 0.16002)
		(layer "In6.Cu")
		(net "M_K_CPU1_SB_DQS_DN<9>")
	)
	(segment
		(start 145.202148 -270.574516)
		(end 145.202402 -270.574262)
		(width 0.09525)
		(layer "In6.Cu")
		(net "M_K_CPU1_SB_DQS_DN<9>")
	)
	(segment
		(start 187.818014 -275.962364)
		(end 188.158628 -276.302978)
		(width 0.16002)
		(layer "In6.Cu")
		(net "M_K_CPU1_SB_DQS_DN<9>")
	)
	(segment
		(start 144.785842 -271.330674)
		(end 144.829784 -271.30502)
		(width 0.09525)
		(layer "In6.Cu")
		(net "M_K_CPU1_SB_DQS_DN<9>")
	)
	(segment
		(start 147.895564 -269.555214)
		(end 147.919186 -269.555214)
		(width 0.09525)
		(layer "In6.Cu")
		(net "M_K_CPU1_SB_DQS_DN<9>")
	)
	(segment
		(start 195.705984 -276.310598)
		(end 196.335904 -276.310598)
		(width 0.16002)
		(layer "In6.Cu")
		(net "M_K_CPU1_SB_DQS_DN<9>")
	)
	(segment
		(start 182.505858 -275.452078)
		(end 182.845456 -275.11248)
		(width 0.16002)
		(layer "In6.Cu")
		(net "M_K_CPU1_SB_DQS_DN<9>")
	)
	(segment
		(start 147.352766 -269.496286)
		(end 147.836636 -269.496286)
		(width 0.09525)
		(layer "In6.Cu")
		(net "M_K_CPU1_SB_DQS_DN<9>")
	)
	(segment
		(start 145.794984 -270.26743)
		(end 146.699224 -269.362936)
		(width 0.09525)
		(layer "In6.Cu")
		(net "M_K_CPU1_SB_DQS_DN<9>")
	)
	(segment
		(start 185.408062 -275.962364)
		(end 187.818014 -275.962364)
		(width 0.16002)
		(layer "In6.Cu")
		(net "M_K_CPU1_SB_DQS_DN<9>")
	)
	(segment
		(start 169.47007 -275.11248)
		(end 170.319954 -275.962364)
		(width 0.16002)
		(layer "In6.Cu")
		(net "M_K_CPU1_SB_DQS_DN<9>")
	)
	(segment
		(start 181.266338 -276.302978)
		(end 182.117238 -275.452078)
		(width 0.16002)
		(layer "In6.Cu")
		(net "M_K_CPU1_SB_DQS_DN<9>")
	)
	(segment
		(start 182.845456 -275.11248)
		(end 184.558178 -275.11248)
		(width 0.16002)
		(layer "In6.Cu")
		(net "M_K_CPU1_SB_DQS_DN<9>")
	)
	(segment
		(start 174.961804 -275.452078)
		(end 175.301402 -275.11248)
		(width 0.16002)
		(layer "In6.Cu")
		(net "M_K_CPU1_SB_DQS_DN<9>")
	)
	(segment
		(start 166.17823 -276.302978)
		(end 167.02913 -275.452078)
		(width 0.16002)
		(layer "In6.Cu")
		(net "M_K_CPU1_SB_DQS_DN<9>")
	)
	(segment
		(start 144.21485 -271.326356)
		(end 144.223232 -271.331182)
		(width 0.09525)
		(layer "In6.Cu")
		(net "M_K_CPU1_SB_DQS_DN<9>")
	)
	(segment
		(start 144.763998 -271.343374)
		(end 144.771618 -271.339056)
		(width 0.09525)
		(layer "In6.Cu")
		(net "M_K_CPU1_SB_DQS_DN<9>")
	)
	(segment
		(start 197.74916 -276.111462)
		(end 198.430388 -276.111462)
		(width 0.16002)
		(layer "In6.Cu")
		(net "M_K_CPU1_SB_DQS_DN<9>")
	)
	(segment
		(start 147.919186 -269.555214)
		(end 158.142178 -269.555214)
		(width 0.16002)
		(layer "In6.Cu")
		(net "M_K_CPU1_SB_DQS_DN<9>")
	)
	(segment
		(start 197.62216 -276.238462)
		(end 197.74916 -276.111462)
		(width 0.16002)
		(layer "In6.Cu")
		(net "M_K_CPU1_SB_DQS_DN<9>")
	)
	(segment
		(start 180.27396 -275.962364)
		(end 180.614574 -276.302978)
		(width 0.16002)
		(layer "In6.Cu")
		(net "M_K_CPU1_SB_DQS_DN<9>")
	)
	(segment
		(start 144.77238 -271.338548)
		(end 144.785842 -271.330674)
		(width 0.09525)
		(layer "In6.Cu")
		(net "M_K_CPU1_SB_DQS_DN<9>")
	)
	(segment
		(start 167.41775 -275.452078)
		(end 167.757348 -275.11248)
		(width 0.16002)
		(layer "In6.Cu")
		(net "M_K_CPU1_SB_DQS_DN<9>")
	)
	(segment
		(start 177.864008 -275.962364)
		(end 180.27396 -275.962364)
		(width 0.16002)
		(layer "In6.Cu")
		(net "M_K_CPU1_SB_DQS_DN<9>")
	)
	(segment
		(start 188.810392 -276.302978)
		(end 189.661292 -275.452078)
		(width 0.16002)
		(layer "In6.Cu")
		(net "M_K_CPU1_SB_DQS_DN<9>")
	)
	(segment
		(start 173.07052 -276.302978)
		(end 173.722284 -276.302978)
		(width 0.16002)
		(layer "In6.Cu")
		(net "M_K_CPU1_SB_DQS_DN<9>")
	)
	(segment
		(start 144.771618 -271.339056)
		(end 144.77238 -271.338548)
		(width 0.09525)
		(layer "In6.Cu")
		(net "M_K_CPU1_SB_DQS_DN<9>")
	)
	(segment
		(start 188.158628 -276.302978)
		(end 188.810392 -276.302978)
		(width 0.16002)
		(layer "In6.Cu")
		(net "M_K_CPU1_SB_DQS_DN<9>")
	)
	(segment
		(start 180.614574 -276.302978)
		(end 181.266338 -276.302978)
		(width 0.16002)
		(layer "In6.Cu")
		(net "M_K_CPU1_SB_DQS_DN<9>")
	)
	(segment
		(start 197.0151 -276.111462)
		(end 197.1421 -276.238462)
		(width 0.16002)
		(layer "In6.Cu")
		(net "M_K_CPU1_SB_DQS_DN<9>")
	)
	(segment
		(start 143.09471 -271.656302)
		(end 142.940786 -271.390872)
		(width 0.09525)
		(layer "In6.Cu")
		(net "M_K_CPU1_SB_DQS_DN<9>")
	)
	(segment
		(start 164.889942 -276.302978)
		(end 166.17823 -276.302978)
		(width 0.16002)
		(layer "In6.Cu")
		(net "M_K_CPU1_SB_DQS_DN<9>")
	)
	(segment
		(start 177.014124 -275.11248)
		(end 177.864008 -275.962364)
		(width 0.16002)
		(layer "In6.Cu")
		(net "M_K_CPU1_SB_DQS_DN<9>")
	)
	(segment
		(start 189.661292 -275.452078)
		(end 190.049912 -275.452078)
		(width 0.16002)
		(layer "In6.Cu")
		(net "M_K_CPU1_SB_DQS_DN<9>")
	)
	(segment
		(start 197.1421 -276.238462)
		(end 197.62216 -276.238462)
		(width 0.16002)
		(layer "In6.Cu")
		(net "M_K_CPU1_SB_DQS_DN<9>")
	)
	(segment
		(start 170.319954 -275.962364)
		(end 172.729906 -275.962364)
		(width 0.16002)
		(layer "In6.Cu")
		(net "M_K_CPU1_SB_DQS_DN<9>")
	)
	(segment
		(start 147.836636 -269.496286)
		(end 147.895564 -269.555214)
		(width 0.09525)
		(layer "In6.Cu")
		(net "M_K_CPU1_SB_DQS_DN<9>")
	)
	(segment
		(start 142.940786 -271.390872)
		(end 142.9639 -271.304258)
		(width 0.09525)
		(layer "In6.Cu")
		(net "M_K_CPU1_SB_DQS_DN<9>")
	)
	(segment
		(start 196.53504 -276.111462)
		(end 197.0151 -276.111462)
		(width 0.16002)
		(layer "In6.Cu")
		(net "M_K_CPU1_SB_DQS_DN<9>")
	)
	(segment
		(start 190.38951 -275.11248)
		(end 192.29705 -275.11248)
		(width 0.16002)
		(layer "In6.Cu")
		(net "M_K_CPU1_SB_DQS_DN<9>")
	)
	(segment
		(start 173.722284 -276.302978)
		(end 174.573184 -275.452078)
		(width 0.16002)
		(layer "In6.Cu")
		(net "M_K_CPU1_SB_DQS_DN<9>")
	)
	(segment
		(start 145.202402 -270.574262)
		(end 145.388076 -270.447008)
		(width 0.09525)
		(layer "In6.Cu")
		(net "M_K_CPU1_SB_DQS_DN<9>")
	)
	(segment
		(start 145.403824 -270.438118)
		(end 145.794984 -270.26743)
		(width 0.09525)
		(layer "In6.Cu")
		(net "M_K_CPU1_SB_DQS_DN<9>")
	)
	(arc
		(start 144.223232 -271.331182)
		(mid 144.492045 -271.406795)
		(end 144.763998 -271.343374)
		(width 0.09525)
		(layer "In6.Cu")
		(net "M_K_CPU1_SB_DQS_DN<9>")
	)
	(arc
		(start 143.846042 -271.331182)
		(mid 144.029817 -271.28041)
		(end 144.21485 -271.326356)
		(width 0.09525)
		(layer "In6.Cu")
		(net "M_K_CPU1_SB_DQS_DN<9>")
	)
	(arc
		(start 145.06702 -270.846296)
		(mid 145.070963 -270.790839)
		(end 145.083022 -270.736568)
		(width 0.09525)
		(layer "In6.Cu")
		(net "M_K_CPU1_SB_DQS_DN<9>")
	)
	(arc
		(start 144.829784 -271.30502)
		(mid 145.004205 -271.104517)
		(end 145.06702 -270.846296)
		(width 0.09525)
		(layer "In6.Cu")
		(net "M_K_CPU1_SB_DQS_DN<9>")
	)
	(arc
		(start 143.283178 -271.331182)
		(mid 143.56461 -271.406937)
		(end 143.846042 -271.331182)
		(width 0.09525)
		(layer "In6.Cu")
		(net "M_K_CPU1_SB_DQS_DN<9>")
	)
	(arc
		(start 142.9639 -271.304258)
		(mid 143.126551 -271.281998)
		(end 143.283178 -271.331182)
		(width 0.09525)
		(layer "In6.Cu")
		(net "M_K_CPU1_SB_DQS_DN<9>")
	)
	(arc
		(start 145.388076 -270.447008)
		(mid 145.395737 -270.442184)
		(end 145.403824 -270.438118)
		(width 0.09525)
		(layer "In6.Cu")
		(net "M_K_CPU1_SB_DQS_DN<9>")
	)
	(arc
		(start 145.083022 -270.736568)
		(mid 145.12887 -270.645467)
		(end 145.202148 -270.574516)
		(width 0.09525)
		(layer "In6.Cu")
		(net "M_K_CPU1_SB_DQS_DN<9>")
	)
	(segment
		(start 140.748004 -290.830254)
		(end 141.214856 -291.096192)
		(width 0.12954)
		(layer "F.Cu")
		(net "M_K_CPU1_SB_DQS_DN<8>")
	)
	(segment
		(start 191.982344 -314.20816)
		(end 192.131442 -314.059062)
		(width 0.16002)
		(layer "In6.Cu")
		(net "M_K_CPU1_SB_DQS_DN<8>")
	)
	(segment
		(start 160.820608 -312.692542)
		(end 161.24428 -313.116214)
		(width 0.16002)
		(layer "In6.Cu")
		(net "M_K_CPU1_SB_DQS_DN<8>")
	)
	(segment
		(start 188.63691 -314.678314)
		(end 189.42431 -313.890914)
		(width 0.16002)
		(layer "In6.Cu")
		(net "M_K_CPU1_SB_DQS_DN<8>")
	)
	(segment
		(start 159.786574 -312.52922)
		(end 160.03397 -312.776616)
		(width 0.16002)
		(layer "In6.Cu")
		(net "M_K_CPU1_SB_DQS_DN<8>")
	)
	(segment
		(start 158.412942 -310.929528)
		(end 158.412942 -311.155588)
		(width 0.16002)
		(layer "In6.Cu")
		(net "M_K_CPU1_SB_DQS_DN<8>")
	)
	(segment
		(start 147.624292 -295.539414)
		(end 147.87372 -295.787572)
		(width 0.16002)
		(layer "In6.Cu")
		(net "M_K_CPU1_SB_DQS_DN<8>")
	)
	(segment
		(start 161.633662 -314.150248)
		(end 161.717736 -314.066174)
		(width 0.16002)
		(layer "In6.Cu")
		(net "M_K_CPU1_SB_DQS_DN<8>")
	)
	(segment
		(start 157.59684 -309.945278)
		(end 158.073344 -309.945278)
		(width 0.16002)
		(layer "In6.Cu")
		(net "M_K_CPU1_SB_DQS_DN<8>")
	)
	(segment
		(start 147.607528 -295.52265)
		(end 147.624292 -295.539414)
		(width 0.09525)
		(layer "In6.Cu")
		(net "M_K_CPU1_SB_DQS_DN<8>")
	)
	(segment
		(start 162.80638 -314.678314)
		(end 166.004748 -314.678314)
		(width 0.16002)
		(layer "In6.Cu")
		(net "M_K_CPU1_SB_DQS_DN<8>")
	)
	(segment
		(start 179.0446 -315.058298)
		(end 180.108352 -315.058298)
		(width 0.16002)
		(layer "In6.Cu")
		(net "M_K_CPU1_SB_DQS_DN<8>")
	)
	(segment
		(start 173.548802 -314.678314)
		(end 174.336202 -313.890914)
		(width 0.16002)
		(layer "In6.Cu")
		(net "M_K_CPU1_SB_DQS_DN<8>")
	)
	(segment
		(start 180.108352 -315.058298)
		(end 180.488336 -314.678314)
		(width 0.16002)
		(layer "In6.Cu")
		(net "M_K_CPU1_SB_DQS_DN<8>")
	)
	(segment
		(start 158.660338 -311.402984)
		(end 158.886398 -311.402984)
		(width 0.16002)
		(layer "In6.Cu")
		(net "M_K_CPU1_SB_DQS_DN<8>")
	)
	(segment
		(start 157.03931 -309.555896)
		(end 157.03931 -309.781956)
		(width 0.16002)
		(layer "In6.Cu")
		(net "M_K_CPU1_SB_DQS_DN<8>")
	)
	(segment
		(start 186.589162 -315.058806)
		(end 187.651898 -315.058806)
		(width 0.16002)
		(layer "In6.Cu")
		(net "M_K_CPU1_SB_DQS_DN<8>")
	)
	(segment
		(start 175.712628 -314.20816)
		(end 178.194462 -314.20816)
		(width 0.16002)
		(layer "In6.Cu")
		(net "M_K_CPU1_SB_DQS_DN<8>")
	)
	(segment
		(start 160.26003 -312.776616)
		(end 160.344104 -312.692542)
		(width 0.16002)
		(layer "In6.Cu")
		(net "M_K_CPU1_SB_DQS_DN<8>")
	)
	(segment
		(start 159.870648 -312.219086)
		(end 159.786574 -312.30316)
		(width 0.16002)
		(layer "In6.Cu")
		(net "M_K_CPU1_SB_DQS_DN<8>")
	)
	(segment
		(start 190.800736 -314.20816)
		(end 191.982344 -314.20816)
		(width 0.16002)
		(layer "In6.Cu")
		(net "M_K_CPU1_SB_DQS_DN<8>")
	)
	(segment
		(start 192.131442 -314.059062)
		(end 194.33032 -314.059062)
		(width 0.16002)
		(layer "In6.Cu")
		(net "M_K_CPU1_SB_DQS_DN<8>")
	)
	(segment
		(start 147.87372 -295.787572)
		(end 147.87372 -299.745654)
		(width 0.16002)
		(layer "In6.Cu")
		(net "M_K_CPU1_SB_DQS_DN<8>")
	)
	(segment
		(start 161.717736 -314.066174)
		(end 162.19424 -314.066174)
		(width 0.16002)
		(layer "In6.Cu")
		(net "M_K_CPU1_SB_DQS_DN<8>")
	)
	(segment
		(start 158.073344 -309.945278)
		(end 158.497016 -310.36895)
		(width 0.16002)
		(layer "In6.Cu")
		(net "M_K_CPU1_SB_DQS_DN<8>")
	)
	(segment
		(start 157.123384 -308.995318)
		(end 157.123384 -309.471822)
		(width 0.16002)
		(layer "In6.Cu")
		(net "M_K_CPU1_SB_DQS_DN<8>")
	)
	(segment
		(start 161.24428 -313.116214)
		(end 161.24428 -313.592718)
		(width 0.16002)
		(layer "In6.Cu")
		(net "M_K_CPU1_SB_DQS_DN<8>")
	)
	(segment
		(start 181.092856 -314.678314)
		(end 181.880256 -313.890914)
		(width 0.16002)
		(layer "In6.Cu")
		(net "M_K_CPU1_SB_DQS_DN<8>")
	)
	(segment
		(start 162.19424 -314.066174)
		(end 162.80638 -314.678314)
		(width 0.16002)
		(layer "In6.Cu")
		(net "M_K_CPU1_SB_DQS_DN<8>")
	)
	(segment
		(start 157.512766 -310.029352)
		(end 157.59684 -309.945278)
		(width 0.16002)
		(layer "In6.Cu")
		(net "M_K_CPU1_SB_DQS_DN<8>")
	)
	(segment
		(start 161.160206 -313.676792)
		(end 161.160206 -313.902852)
		(width 0.16002)
		(layer "In6.Cu")
		(net "M_K_CPU1_SB_DQS_DN<8>")
	)
	(segment
		(start 161.24428 -313.592718)
		(end 161.160206 -313.676792)
		(width 0.16002)
		(layer "In6.Cu")
		(net "M_K_CPU1_SB_DQS_DN<8>")
	)
	(segment
		(start 168.168574 -314.20816)
		(end 170.650408 -314.20816)
		(width 0.16002)
		(layer "In6.Cu")
		(net "M_K_CPU1_SB_DQS_DN<8>")
	)
	(segment
		(start 170.650408 -314.20816)
		(end 171.500546 -315.058298)
		(width 0.16002)
		(layer "In6.Cu")
		(net "M_K_CPU1_SB_DQS_DN<8>")
	)
	(segment
		(start 178.194462 -314.20816)
		(end 179.0446 -315.058298)
		(width 0.16002)
		(layer "In6.Cu")
		(net "M_K_CPU1_SB_DQS_DN<8>")
	)
	(segment
		(start 144.222978 -291.421312)
		(end 144.233392 -291.415216)
		(width 0.09525)
		(layer "In6.Cu")
		(net "M_K_CPU1_SB_DQS_DN<8>")
	)
	(segment
		(start 172.564298 -315.058298)
		(end 172.944282 -314.678314)
		(width 0.16002)
		(layer "In6.Cu")
		(net "M_K_CPU1_SB_DQS_DN<8>")
	)
	(segment
		(start 174.336202 -313.890914)
		(end 175.395382 -313.890914)
		(width 0.16002)
		(layer "In6.Cu")
		(net "M_K_CPU1_SB_DQS_DN<8>")
	)
	(segment
		(start 166.004748 -314.678314)
		(end 166.792148 -313.890914)
		(width 0.16002)
		(layer "In6.Cu")
		(net "M_K_CPU1_SB_DQS_DN<8>")
	)
	(segment
		(start 171.500546 -315.058298)
		(end 172.564298 -315.058298)
		(width 0.16002)
		(layer "In6.Cu")
		(net "M_K_CPU1_SB_DQS_DN<8>")
	)
	(segment
		(start 167.851328 -313.890914)
		(end 168.168574 -314.20816)
		(width 0.16002)
		(layer "In6.Cu")
		(net "M_K_CPU1_SB_DQS_DN<8>")
	)
	(segment
		(start 187.651898 -315.058806)
		(end 188.03239 -314.678314)
		(width 0.16002)
		(layer "In6.Cu")
		(net "M_K_CPU1_SB_DQS_DN<8>")
	)
	(segment
		(start 158.970472 -311.31891)
		(end 159.446976 -311.31891)
		(width 0.16002)
		(layer "In6.Cu")
		(net "M_K_CPU1_SB_DQS_DN<8>")
	)
	(segment
		(start 146.486118 -294.485314)
		(end 147.523708 -295.522904)
		(width 0.09525)
		(layer "In6.Cu")
		(net "M_K_CPU1_SB_DQS_DN<8>")
	)
	(segment
		(start 158.886398 -311.402984)
		(end 158.970472 -311.31891)
		(width 0.16002)
		(layer "In6.Cu")
		(net "M_K_CPU1_SB_DQS_DN<8>")
	)
	(segment
		(start 146.016218 -293.399464)
		(end 146.016218 -293.455852)
		(width 0.09525)
		(layer "In6.Cu")
		(net "M_K_CPU1_SB_DQS_DN<8>")
	)
	(segment
		(start 159.870648 -311.742582)
		(end 159.870648 -312.219086)
		(width 0.16002)
		(layer "In6.Cu")
		(net "M_K_CPU1_SB_DQS_DN<8>")
	)
	(segment
		(start 147.523708 -295.522904)
		(end 147.523962 -295.522904)
		(width 0.09525)
		(layer "In6.Cu")
		(net "M_K_CPU1_SB_DQS_DN<8>")
	)
	(segment
		(start 141.966188 -291.421312)
		(end 141.97457 -291.426138)
		(width 0.09525)
		(layer "In6.Cu")
		(net "M_K_CPU1_SB_DQS_DN<8>")
	)
	(segment
		(start 172.944282 -314.678314)
		(end 173.548802 -314.678314)
		(width 0.16002)
		(layer "In6.Cu")
		(net "M_K_CPU1_SB_DQS_DN<8>")
	)
	(segment
		(start 157.286706 -310.029352)
		(end 157.512766 -310.029352)
		(width 0.16002)
		(layer "In6.Cu")
		(net "M_K_CPU1_SB_DQS_DN<8>")
	)
	(segment
		(start 146.486118 -294.336216)
		(end 146.486118 -294.485314)
		(width 0.09525)
		(layer "In6.Cu")
		(net "M_K_CPU1_SB_DQS_DN<8>")
	)
	(segment
		(start 160.03397 -312.776616)
		(end 160.26003 -312.776616)
		(width 0.16002)
		(layer "In6.Cu")
		(net "M_K_CPU1_SB_DQS_DN<8>")
	)
	(segment
		(start 189.42431 -313.890914)
		(end 190.48349 -313.890914)
		(width 0.16002)
		(layer "In6.Cu")
		(net "M_K_CPU1_SB_DQS_DN<8>")
	)
	(segment
		(start 158.412942 -311.155588)
		(end 158.660338 -311.402984)
		(width 0.16002)
		(layer "In6.Cu")
		(net "M_K_CPU1_SB_DQS_DN<8>")
	)
	(segment
		(start 159.446976 -311.31891)
		(end 159.870648 -311.742582)
		(width 0.16002)
		(layer "In6.Cu")
		(net "M_K_CPU1_SB_DQS_DN<8>")
	)
	(segment
		(start 158.497016 -310.36895)
		(end 158.497016 -310.845454)
		(width 0.16002)
		(layer "In6.Cu")
		(net "M_K_CPU1_SB_DQS_DN<8>")
	)
	(segment
		(start 161.407602 -314.150248)
		(end 161.633662 -314.150248)
		(width 0.16002)
		(layer "In6.Cu")
		(net "M_K_CPU1_SB_DQS_DN<8>")
	)
	(segment
		(start 147.87372 -299.745654)
		(end 157.123384 -308.995318)
		(width 0.16002)
		(layer "In6.Cu")
		(net "M_K_CPU1_SB_DQS_DN<8>")
	)
	(segment
		(start 159.786574 -312.30316)
		(end 159.786574 -312.52922)
		(width 0.16002)
		(layer "In6.Cu")
		(net "M_K_CPU1_SB_DQS_DN<8>")
	)
	(segment
		(start 180.488336 -314.678314)
		(end 181.092856 -314.678314)
		(width 0.16002)
		(layer "In6.Cu")
		(net "M_K_CPU1_SB_DQS_DN<8>")
	)
	(segment
		(start 185.738516 -314.20816)
		(end 186.589162 -315.058806)
		(width 0.16002)
		(layer "In6.Cu")
		(net "M_K_CPU1_SB_DQS_DN<8>")
	)
	(segment
		(start 183.256682 -314.20816)
		(end 185.738516 -314.20816)
		(width 0.16002)
		(layer "In6.Cu")
		(net "M_K_CPU1_SB_DQS_DN<8>")
	)
	(segment
		(start 144.785588 -291.421312)
		(end 144.785334 -291.42182)
		(width 0.09525)
		(layer "In6.Cu")
		(net "M_K_CPU1_SB_DQS_DN<8>")
	)
	(segment
		(start 145.095976 -292.090348)
		(end 145.74139 -292.735762)
		(width 0.09525)
		(layer "In6.Cu")
		(net "M_K_CPU1_SB_DQS_DN<8>")
	)
	(segment
		(start 141.214856 -291.096192)
		(end 141.36878 -291.361622)
		(width 0.09525)
		(layer "In6.Cu")
		(net "M_K_CPU1_SB_DQS_DN<8>")
	)
	(segment
		(start 181.880256 -313.890914)
		(end 182.939436 -313.890914)
		(width 0.16002)
		(layer "In6.Cu")
		(net "M_K_CPU1_SB_DQS_DN<8>")
	)
	(segment
		(start 166.792148 -313.890914)
		(end 167.851328 -313.890914)
		(width 0.16002)
		(layer "In6.Cu")
		(net "M_K_CPU1_SB_DQS_DN<8>")
	)
	(segment
		(start 157.03931 -309.781956)
		(end 157.286706 -310.029352)
		(width 0.16002)
		(layer "In6.Cu")
		(net "M_K_CPU1_SB_DQS_DN<8>")
	)
	(segment
		(start 157.123384 -309.471822)
		(end 157.03931 -309.555896)
		(width 0.16002)
		(layer "In6.Cu")
		(net "M_K_CPU1_SB_DQS_DN<8>")
	)
	(segment
		(start 188.03239 -314.678314)
		(end 188.63691 -314.678314)
		(width 0.16002)
		(layer "In6.Cu")
		(net "M_K_CPU1_SB_DQS_DN<8>")
	)
	(segment
		(start 175.395382 -313.890914)
		(end 175.712628 -314.20816)
		(width 0.16002)
		(layer "In6.Cu")
		(net "M_K_CPU1_SB_DQS_DN<8>")
	)
	(segment
		(start 160.344104 -312.692542)
		(end 160.820608 -312.692542)
		(width 0.16002)
		(layer "In6.Cu")
		(net "M_K_CPU1_SB_DQS_DN<8>")
	)
	(segment
		(start 144.21104 -291.42817)
		(end 144.222978 -291.421312)
		(width 0.09525)
		(layer "In6.Cu")
		(net "M_K_CPU1_SB_DQS_DN<8>")
	)
	(segment
		(start 146.169126 -293.824914)
		(end 146.348704 -294.004492)
		(width 0.09525)
		(layer "In6.Cu")
		(net "M_K_CPU1_SB_DQS_DN<8>")
	)
	(segment
		(start 190.48349 -313.890914)
		(end 190.800736 -314.20816)
		(width 0.16002)
		(layer "In6.Cu")
		(net "M_K_CPU1_SB_DQS_DN<8>")
	)
	(segment
		(start 161.160206 -313.902852)
		(end 161.407602 -314.150248)
		(width 0.16002)
		(layer "In6.Cu")
		(net "M_K_CPU1_SB_DQS_DN<8>")
	)
	(segment
		(start 182.939436 -313.890914)
		(end 183.256682 -314.20816)
		(width 0.16002)
		(layer "In6.Cu")
		(net "M_K_CPU1_SB_DQS_DN<8>")
	)
	(segment
		(start 147.523962 -295.522904)
		(end 147.607528 -295.52265)
		(width 0.09525)
		(layer "In6.Cu")
		(net "M_K_CPU1_SB_DQS_DN<8>")
	)
	(segment
		(start 194.33032 -314.059062)
		(end 194.604132 -313.78525)
		(width 0.16002)
		(layer "In6.Cu")
		(net "M_K_CPU1_SB_DQS_DN<8>")
	)
	(segment
		(start 158.497016 -310.845454)
		(end 158.412942 -310.929528)
		(width 0.16002)
		(layer "In6.Cu")
		(net "M_K_CPU1_SB_DQS_DN<8>")
	)
	(segment
		(start 141.36878 -291.361622)
		(end 141.469618 -291.388292)
		(width 0.09525)
		(layer "In6.Cu")
		(net "M_K_CPU1_SB_DQS_DN<8>")
	)
	(arc
		(start 141.97457 -291.426138)
		(mid 142.159602 -291.472052)
		(end 142.343378 -291.421312)
		(width 0.09525)
		(layer "In6.Cu")
		(net "M_K_CPU1_SB_DQS_DN<8>")
	)
	(arc
		(start 146.348704 -294.004492)
		(mid 146.450398 -294.156688)
		(end 146.486118 -294.336216)
		(width 0.09525)
		(layer "In6.Cu")
		(net "M_K_CPU1_SB_DQS_DN<8>")
	)
	(arc
		(start 142.906242 -291.421312)
		(mid 143.09471 -291.471989)
		(end 143.283178 -291.421312)
		(width 0.09525)
		(layer "In6.Cu")
		(net "M_K_CPU1_SB_DQS_DN<8>")
	)
	(arc
		(start 146.016218 -293.455852)
		(mid 146.055951 -293.655601)
		(end 146.169126 -293.824914)
		(width 0.09525)
		(layer "In6.Cu")
		(net "M_K_CPU1_SB_DQS_DN<8>")
	)
	(arc
		(start 142.343378 -291.421312)
		(mid 142.62481 -291.345557)
		(end 142.906242 -291.421312)
		(width 0.09525)
		(layer "In6.Cu")
		(net "M_K_CPU1_SB_DQS_DN<8>")
	)
	(arc
		(start 144.785334 -291.42182)
		(mid 144.903318 -291.543265)
		(end 144.941036 -291.708332)
		(width 0.09525)
		(layer "In6.Cu")
		(net "M_K_CPU1_SB_DQS_DN<8>")
	)
	(arc
		(start 141.469618 -291.388292)
		(mid 141.479486 -291.384261)
		(end 141.48943 -291.380418)
		(width 0.09525)
		(layer "In6.Cu")
		(net "M_K_CPU1_SB_DQS_DN<8>")
	)
	(arc
		(start 144.941036 -291.708332)
		(mid 144.976459 -291.916386)
		(end 145.095976 -292.090348)
		(width 0.09525)
		(layer "In6.Cu")
		(net "M_K_CPU1_SB_DQS_DN<8>")
	)
	(arc
		(start 143.846042 -291.421312)
		(mid 144.027658 -291.472049)
		(end 144.21104 -291.42817)
		(width 0.09525)
		(layer "In6.Cu")
		(net "M_K_CPU1_SB_DQS_DN<8>")
	)
	(arc
		(start 143.283178 -291.421312)
		(mid 143.56461 -291.345557)
		(end 143.846042 -291.421312)
		(width 0.09525)
		(layer "In6.Cu")
		(net "M_K_CPU1_SB_DQS_DN<8>")
	)
	(arc
		(start 141.48943 -291.380418)
		(mid 141.732394 -291.347431)
		(end 141.966188 -291.421312)
		(width 0.09525)
		(layer "In6.Cu")
		(net "M_K_CPU1_SB_DQS_DN<8>")
	)
	(arc
		(start 145.74139 -292.735762)
		(mid 145.944803 -293.040285)
		(end 146.016218 -293.399464)
		(width 0.09525)
		(layer "In6.Cu")
		(net "M_K_CPU1_SB_DQS_DN<8>")
	)
	(arc
		(start 144.233392 -291.415216)
		(mid 144.5103 -291.345539)
		(end 144.785588 -291.421312)
		(width 0.09525)
		(layer "In6.Cu")
		(net "M_K_CPU1_SB_DQS_DN<8>")
	)
	(segment
		(start 140.748004 -285.970472)
		(end 141.214856 -286.23641)
		(width 0.12954)
		(layer "F.Cu")
		(net "M_K_CPU1_SB_DQS_DN<7>")
	)
	(segment
		(start 179.0446 -305.708304)
		(end 180.108352 -305.708304)
		(width 0.16002)
		(layer "In6.Cu")
		(net "M_K_CPU1_SB_DQS_DN<7>")
	)
	(segment
		(start 170.650408 -304.858166)
		(end 171.500546 -305.708304)
		(width 0.16002)
		(layer "In6.Cu")
		(net "M_K_CPU1_SB_DQS_DN<7>")
	)
	(segment
		(start 162.23488 -304.441098)
		(end 162.116262 -304.559716)
		(width 0.16002)
		(layer "In6.Cu")
		(net "M_K_CPU1_SB_DQS_DN<7>")
	)
	(segment
		(start 174.336202 -304.54092)
		(end 175.395382 -304.54092)
		(width 0.16002)
		(layer "In6.Cu")
		(net "M_K_CPU1_SB_DQS_DN<7>")
	)
	(segment
		(start 163.18484 -304.914554)
		(end 163.598606 -305.32832)
		(width 0.16002)
		(layer "In6.Cu")
		(net "M_K_CPU1_SB_DQS_DN<7>")
	)
	(segment
		(start 180.488336 -305.32832)
		(end 181.092856 -305.32832)
		(width 0.16002)
		(layer "In6.Cu")
		(net "M_K_CPU1_SB_DQS_DN<7>")
	)
	(segment
		(start 192.131442 -304.709068)
		(end 194.33032 -304.709068)
		(width 0.16002)
		(layer "In6.Cu")
		(net "M_K_CPU1_SB_DQS_DN<7>")
	)
	(segment
		(start 160.437576 -302.16729)
		(end 160.861248 -302.590962)
		(width 0.16002)
		(layer "In6.Cu")
		(net "M_K_CPU1_SB_DQS_DN<7>")
	)
	(segment
		(start 162.363658 -305.033172)
		(end 162.589718 -305.033172)
		(width 0.16002)
		(layer "In6.Cu")
		(net "M_K_CPU1_SB_DQS_DN<7>")
	)
	(segment
		(start 159.961072 -302.16729)
		(end 160.437576 -302.16729)
		(width 0.16002)
		(layer "In6.Cu")
		(net "M_K_CPU1_SB_DQS_DN<7>")
	)
	(segment
		(start 187.652406 -305.708304)
		(end 188.03239 -305.32832)
		(width 0.16002)
		(layer "In6.Cu")
		(net "M_K_CPU1_SB_DQS_DN<7>")
	)
	(segment
		(start 147.919186 -287.58388)
		(end 153.73731 -293.402004)
		(width 0.16002)
		(layer "In6.Cu")
		(net "M_K_CPU1_SB_DQS_DN<7>")
	)
	(segment
		(start 145.84299 -286.440626)
		(end 146.42973 -287.027366)
		(width 0.09525)
		(layer "In6.Cu")
		(net "M_K_CPU1_SB_DQS_DN<7>")
	)
	(segment
		(start 159.487616 -301.21733)
		(end 159.487616 -301.693834)
		(width 0.16002)
		(layer "In6.Cu")
		(net "M_K_CPU1_SB_DQS_DN<7>")
	)
	(segment
		(start 178.194462 -304.858166)
		(end 179.0446 -305.708304)
		(width 0.16002)
		(layer "In6.Cu")
		(net "M_K_CPU1_SB_DQS_DN<7>")
	)
	(segment
		(start 171.500546 -305.708304)
		(end 172.564298 -305.708304)
		(width 0.16002)
		(layer "In6.Cu")
		(net "M_K_CPU1_SB_DQS_DN<7>")
	)
	(segment
		(start 191.982344 -304.858166)
		(end 192.131442 -304.709068)
		(width 0.16002)
		(layer "In6.Cu")
		(net "M_K_CPU1_SB_DQS_DN<7>")
	)
	(segment
		(start 162.116262 -304.785776)
		(end 162.363658 -305.033172)
		(width 0.16002)
		(layer "In6.Cu")
		(net "M_K_CPU1_SB_DQS_DN<7>")
	)
	(segment
		(start 158.242762 -300.912276)
		(end 158.468822 -300.912276)
		(width 0.16002)
		(layer "In6.Cu")
		(net "M_K_CPU1_SB_DQS_DN<7>")
	)
	(segment
		(start 163.598606 -305.32832)
		(end 166.004748 -305.32832)
		(width 0.16002)
		(layer "In6.Cu")
		(net "M_K_CPU1_SB_DQS_DN<7>")
	)
	(segment
		(start 167.851328 -304.54092)
		(end 168.168574 -304.858166)
		(width 0.16002)
		(layer "In6.Cu")
		(net "M_K_CPU1_SB_DQS_DN<7>")
	)
	(segment
		(start 141.966188 -286.56153)
		(end 141.97457 -286.566356)
		(width 0.09525)
		(layer "In6.Cu")
		(net "M_K_CPU1_SB_DQS_DN<7>")
	)
	(segment
		(start 158.113984 -299.843698)
		(end 158.113984 -300.320202)
		(width 0.16002)
		(layer "In6.Cu")
		(net "M_K_CPU1_SB_DQS_DN<7>")
	)
	(segment
		(start 172.564298 -305.708304)
		(end 172.944282 -305.32832)
		(width 0.16002)
		(layer "In6.Cu")
		(net "M_K_CPU1_SB_DQS_DN<7>")
	)
	(segment
		(start 166.004748 -305.32832)
		(end 166.792148 -304.54092)
		(width 0.16002)
		(layer "In6.Cu")
		(net "M_K_CPU1_SB_DQS_DN<7>")
	)
	(segment
		(start 161.811208 -303.540922)
		(end 162.23488 -303.964594)
		(width 0.16002)
		(layer "In6.Cu")
		(net "M_K_CPU1_SB_DQS_DN<7>")
	)
	(segment
		(start 186.588654 -305.708304)
		(end 187.652406 -305.708304)
		(width 0.16002)
		(layer "In6.Cu")
		(net "M_K_CPU1_SB_DQS_DN<7>")
	)
	(segment
		(start 175.712628 -304.858166)
		(end 178.194462 -304.858166)
		(width 0.16002)
		(layer "In6.Cu")
		(net "M_K_CPU1_SB_DQS_DN<7>")
	)
	(segment
		(start 146.42973 -287.027366)
		(end 147.278852 -287.027366)
		(width 0.09525)
		(layer "In6.Cu")
		(net "M_K_CPU1_SB_DQS_DN<7>")
	)
	(segment
		(start 185.738516 -304.858166)
		(end 186.588654 -305.708304)
		(width 0.16002)
		(layer "In6.Cu")
		(net "M_K_CPU1_SB_DQS_DN<7>")
	)
	(segment
		(start 147.278852 -287.027366)
		(end 147.818602 -287.567116)
		(width 0.09525)
		(layer "In6.Cu")
		(net "M_K_CPU1_SB_DQS_DN<7>")
	)
	(segment
		(start 189.42431 -304.54092)
		(end 190.48349 -304.54092)
		(width 0.16002)
		(layer "In6.Cu")
		(net "M_K_CPU1_SB_DQS_DN<7>")
	)
	(segment
		(start 160.990026 -303.65954)
		(end 161.216086 -303.65954)
		(width 0.16002)
		(layer "In6.Cu")
		(net "M_K_CPU1_SB_DQS_DN<7>")
	)
	(segment
		(start 180.108352 -305.708304)
		(end 180.488336 -305.32832)
		(width 0.16002)
		(layer "In6.Cu")
		(net "M_K_CPU1_SB_DQS_DN<7>")
	)
	(segment
		(start 160.861248 -302.590962)
		(end 160.861248 -303.067466)
		(width 0.16002)
		(layer "In6.Cu")
		(net "M_K_CPU1_SB_DQS_DN<7>")
	)
	(segment
		(start 168.168574 -304.858166)
		(end 170.650408 -304.858166)
		(width 0.16002)
		(layer "In6.Cu")
		(net "M_K_CPU1_SB_DQS_DN<7>")
	)
	(segment
		(start 162.23488 -303.964594)
		(end 162.23488 -304.441098)
		(width 0.16002)
		(layer "In6.Cu")
		(net "M_K_CPU1_SB_DQS_DN<7>")
	)
	(segment
		(start 159.616394 -302.285908)
		(end 159.842454 -302.285908)
		(width 0.16002)
		(layer "In6.Cu")
		(net "M_K_CPU1_SB_DQS_DN<7>")
	)
	(segment
		(start 156.674312 -299.544486)
		(end 157.814772 -299.544486)
		(width 0.16002)
		(layer "In6.Cu")
		(net "M_K_CPU1_SB_DQS_DN<7>")
	)
	(segment
		(start 182.939436 -304.54092)
		(end 183.256682 -304.858166)
		(width 0.16002)
		(layer "In6.Cu")
		(net "M_K_CPU1_SB_DQS_DN<7>")
	)
	(segment
		(start 175.395382 -304.54092)
		(end 175.712628 -304.858166)
		(width 0.16002)
		(layer "In6.Cu")
		(net "M_K_CPU1_SB_DQS_DN<7>")
	)
	(segment
		(start 181.092856 -305.32832)
		(end 181.880256 -304.54092)
		(width 0.16002)
		(layer "In6.Cu")
		(net "M_K_CPU1_SB_DQS_DN<7>")
	)
	(segment
		(start 188.63691 -305.32832)
		(end 189.42431 -304.54092)
		(width 0.16002)
		(layer "In6.Cu")
		(net "M_K_CPU1_SB_DQS_DN<7>")
	)
	(segment
		(start 166.792148 -304.54092)
		(end 167.851328 -304.54092)
		(width 0.16002)
		(layer "In6.Cu")
		(net "M_K_CPU1_SB_DQS_DN<7>")
	)
	(segment
		(start 160.74263 -303.412144)
		(end 160.990026 -303.65954)
		(width 0.16002)
		(layer "In6.Cu")
		(net "M_K_CPU1_SB_DQS_DN<7>")
	)
	(segment
		(start 157.995366 -300.43882)
		(end 157.995366 -300.66488)
		(width 0.16002)
		(layer "In6.Cu")
		(net "M_K_CPU1_SB_DQS_DN<7>")
	)
	(segment
		(start 161.334704 -303.540922)
		(end 161.811208 -303.540922)
		(width 0.16002)
		(layer "In6.Cu")
		(net "M_K_CPU1_SB_DQS_DN<7>")
	)
	(segment
		(start 159.368998 -302.038512)
		(end 159.616394 -302.285908)
		(width 0.16002)
		(layer "In6.Cu")
		(net "M_K_CPU1_SB_DQS_DN<7>")
	)
	(segment
		(start 159.063944 -300.793658)
		(end 159.487616 -301.21733)
		(width 0.16002)
		(layer "In6.Cu")
		(net "M_K_CPU1_SB_DQS_DN<7>")
	)
	(segment
		(start 181.880256 -304.54092)
		(end 182.939436 -304.54092)
		(width 0.16002)
		(layer "In6.Cu")
		(net "M_K_CPU1_SB_DQS_DN<7>")
	)
	(segment
		(start 173.548802 -305.32832)
		(end 174.336202 -304.54092)
		(width 0.16002)
		(layer "In6.Cu")
		(net "M_K_CPU1_SB_DQS_DN<7>")
	)
	(segment
		(start 159.842454 -302.285908)
		(end 159.961072 -302.16729)
		(width 0.16002)
		(layer "In6.Cu")
		(net "M_K_CPU1_SB_DQS_DN<7>")
	)
	(segment
		(start 144.671542 -286.440626)
		(end 145.84299 -286.440626)
		(width 0.09525)
		(layer "In6.Cu")
		(net "M_K_CPU1_SB_DQS_DN<7>")
	)
	(segment
		(start 159.487616 -301.693834)
		(end 159.368998 -301.812452)
		(width 0.16002)
		(layer "In6.Cu")
		(net "M_K_CPU1_SB_DQS_DN<7>")
	)
	(segment
		(start 160.861248 -303.067466)
		(end 160.74263 -303.186084)
		(width 0.16002)
		(layer "In6.Cu")
		(net "M_K_CPU1_SB_DQS_DN<7>")
	)
	(segment
		(start 144.206722 -286.570674)
		(end 144.222978 -286.561276)
		(width 0.09525)
		(layer "In6.Cu")
		(net "M_K_CPU1_SB_DQS_DN<7>")
	)
	(segment
		(start 158.58744 -300.793658)
		(end 159.063944 -300.793658)
		(width 0.16002)
		(layer "In6.Cu")
		(net "M_K_CPU1_SB_DQS_DN<7>")
	)
	(segment
		(start 141.36878 -286.50184)
		(end 141.469618 -286.52851)
		(width 0.09525)
		(layer "In6.Cu")
		(net "M_K_CPU1_SB_DQS_DN<7>")
	)
	(segment
		(start 157.995366 -300.66488)
		(end 158.242762 -300.912276)
		(width 0.16002)
		(layer "In6.Cu")
		(net "M_K_CPU1_SB_DQS_DN<7>")
	)
	(segment
		(start 183.256682 -304.858166)
		(end 185.738516 -304.858166)
		(width 0.16002)
		(layer "In6.Cu")
		(net "M_K_CPU1_SB_DQS_DN<7>")
	)
	(segment
		(start 194.33032 -304.709068)
		(end 194.604132 -304.435256)
		(width 0.16002)
		(layer "In6.Cu")
		(net "M_K_CPU1_SB_DQS_DN<7>")
	)
	(segment
		(start 141.214856 -286.23641)
		(end 141.36878 -286.50184)
		(width 0.09525)
		(layer "In6.Cu")
		(net "M_K_CPU1_SB_DQS_DN<7>")
	)
	(segment
		(start 162.589718 -305.033172)
		(end 162.708336 -304.914554)
		(width 0.16002)
		(layer "In6.Cu")
		(net "M_K_CPU1_SB_DQS_DN<7>")
	)
	(segment
		(start 158.468822 -300.912276)
		(end 158.58744 -300.793658)
		(width 0.16002)
		(layer "In6.Cu")
		(net "M_K_CPU1_SB_DQS_DN<7>")
	)
	(segment
		(start 161.216086 -303.65954)
		(end 161.334704 -303.540922)
		(width 0.16002)
		(layer "In6.Cu")
		(net "M_K_CPU1_SB_DQS_DN<7>")
	)
	(segment
		(start 147.818602 -287.567116)
		(end 147.902422 -287.567116)
		(width 0.09525)
		(layer "In6.Cu")
		(net "M_K_CPU1_SB_DQS_DN<7>")
	)
	(segment
		(start 162.116262 -304.559716)
		(end 162.116262 -304.785776)
		(width 0.16002)
		(layer "In6.Cu")
		(net "M_K_CPU1_SB_DQS_DN<7>")
	)
	(segment
		(start 188.03239 -305.32832)
		(end 188.63691 -305.32832)
		(width 0.16002)
		(layer "In6.Cu")
		(net "M_K_CPU1_SB_DQS_DN<7>")
	)
	(segment
		(start 157.814772 -299.544486)
		(end 158.113984 -299.843698)
		(width 0.16002)
		(layer "In6.Cu")
		(net "M_K_CPU1_SB_DQS_DN<7>")
	)
	(segment
		(start 158.113984 -300.320202)
		(end 157.995366 -300.43882)
		(width 0.16002)
		(layer "In6.Cu")
		(net "M_K_CPU1_SB_DQS_DN<7>")
	)
	(segment
		(start 160.74263 -303.186084)
		(end 160.74263 -303.412144)
		(width 0.16002)
		(layer "In6.Cu")
		(net "M_K_CPU1_SB_DQS_DN<7>")
	)
	(segment
		(start 153.73731 -296.607484)
		(end 156.674312 -299.544486)
		(width 0.16002)
		(layer "In6.Cu")
		(net "M_K_CPU1_SB_DQS_DN<7>")
	)
	(segment
		(start 147.902422 -287.567116)
		(end 147.919186 -287.58388)
		(width 0.09525)
		(layer "In6.Cu")
		(net "M_K_CPU1_SB_DQS_DN<7>")
	)
	(segment
		(start 190.48349 -304.54092)
		(end 190.800736 -304.858166)
		(width 0.16002)
		(layer "In6.Cu")
		(net "M_K_CPU1_SB_DQS_DN<7>")
	)
	(segment
		(start 159.368998 -301.812452)
		(end 159.368998 -302.038512)
		(width 0.16002)
		(layer "In6.Cu")
		(net "M_K_CPU1_SB_DQS_DN<7>")
	)
	(segment
		(start 162.708336 -304.914554)
		(end 163.18484 -304.914554)
		(width 0.16002)
		(layer "In6.Cu")
		(net "M_K_CPU1_SB_DQS_DN<7>")
	)
	(segment
		(start 190.800736 -304.858166)
		(end 191.982344 -304.858166)
		(width 0.16002)
		(layer "In6.Cu")
		(net "M_K_CPU1_SB_DQS_DN<7>")
	)
	(segment
		(start 153.73731 -293.402004)
		(end 153.73731 -296.607484)
		(width 0.16002)
		(layer "In6.Cu")
		(net "M_K_CPU1_SB_DQS_DN<7>")
	)
	(segment
		(start 172.944282 -305.32832)
		(end 173.548802 -305.32832)
		(width 0.16002)
		(layer "In6.Cu")
		(net "M_K_CPU1_SB_DQS_DN<7>")
	)
	(arc
		(start 144.222978 -286.561276)
		(mid 144.439283 -286.47128)
		(end 144.671542 -286.440626)
		(width 0.09525)
		(layer "In6.Cu")
		(net "M_K_CPU1_SB_DQS_DN<7>")
	)
	(arc
		(start 143.283178 -286.56153)
		(mid 143.56461 -286.485741)
		(end 143.846042 -286.56153)
		(width 0.09525)
		(layer "In6.Cu")
		(net "M_K_CPU1_SB_DQS_DN<7>")
	)
	(arc
		(start 141.97457 -286.566356)
		(mid 142.159602 -286.61227)
		(end 142.343378 -286.56153)
		(width 0.09525)
		(layer "In6.Cu")
		(net "M_K_CPU1_SB_DQS_DN<7>")
	)
	(arc
		(start 142.343378 -286.56153)
		(mid 142.62481 -286.485741)
		(end 142.906242 -286.56153)
		(width 0.09525)
		(layer "In6.Cu")
		(net "M_K_CPU1_SB_DQS_DN<7>")
	)
	(arc
		(start 143.846042 -286.56153)
		(mid 144.025216 -286.612213)
		(end 144.206722 -286.570674)
		(width 0.09525)
		(layer "In6.Cu")
		(net "M_K_CPU1_SB_DQS_DN<7>")
	)
	(arc
		(start 142.906242 -286.56153)
		(mid 143.09471 -286.612207)
		(end 143.283178 -286.56153)
		(width 0.09525)
		(layer "In6.Cu")
		(net "M_K_CPU1_SB_DQS_DN<7>")
	)
	(arc
		(start 141.469618 -286.52851)
		(mid 141.721758 -286.486921)
		(end 141.966188 -286.56153)
		(width 0.09525)
		(layer "In6.Cu")
		(net "M_K_CPU1_SB_DQS_DN<7>")
	)
	(segment
		(start 140.748004 -281.110436)
		(end 141.214856 -281.376374)
		(width 0.12954)
		(layer "F.Cu")
		(net "M_K_CPU1_SB_DQS_DN<6>")
	)
	(segment
		(start 188.03239 -295.978326)
		(end 188.63691 -295.978326)
		(width 0.16002)
		(layer "In6.Cu")
		(net "M_K_CPU1_SB_DQS_DN<6>")
	)
	(segment
		(start 146.537426 -281.618436)
		(end 146.680936 -281.677872)
		(width 0.09525)
		(layer "In6.Cu")
		(net "M_K_CPU1_SB_DQS_DN<6>")
	)
	(segment
		(start 181.880256 -295.190926)
		(end 182.939436 -295.190926)
		(width 0.16002)
		(layer "In6.Cu")
		(net "M_K_CPU1_SB_DQS_DN<6>")
	)
	(segment
		(start 145.363692 -281.618436)
		(end 146.537426 -281.618436)
		(width 0.09525)
		(layer "In6.Cu")
		(net "M_K_CPU1_SB_DQS_DN<6>")
	)
	(segment
		(start 183.256682 -295.508172)
		(end 185.738516 -295.508172)
		(width 0.16002)
		(layer "In6.Cu")
		(net "M_K_CPU1_SB_DQS_DN<6>")
	)
	(segment
		(start 146.88058 -281.877516)
		(end 147.836382 -281.877516)
		(width 0.09525)
		(layer "In6.Cu")
		(net "M_K_CPU1_SB_DQS_DN<6>")
	)
	(segment
		(start 169.260774 -295.693846)
		(end 169.260774 -295.527984)
		(width 0.16002)
		(layer "In6.Cu")
		(net "M_K_CPU1_SB_DQS_DN<6>")
	)
	(segment
		(start 147.895564 -281.818334)
		(end 147.919186 -281.818334)
		(width 0.09525)
		(layer "In6.Cu")
		(net "M_K_CPU1_SB_DQS_DN<6>")
	)
	(segment
		(start 163.59124 -295.98366)
		(end 163.8173 -295.98366)
		(width 0.16002)
		(layer "In6.Cu")
		(net "M_K_CPU1_SB_DQS_DN<6>")
	)
	(segment
		(start 147.919186 -281.818334)
		(end 150.397718 -281.818334)
		(width 0.16002)
		(layer "In6.Cu")
		(net "M_K_CPU1_SB_DQS_DN<6>")
	)
	(segment
		(start 144.21104 -281.708352)
		(end 144.222978 -281.701494)
		(width 0.09525)
		(layer "In6.Cu")
		(net "M_K_CPU1_SB_DQS_DN<6>")
	)
	(segment
		(start 166.004748 -295.978326)
		(end 166.792148 -295.190926)
		(width 0.16002)
		(layer "In6.Cu")
		(net "M_K_CPU1_SB_DQS_DN<6>")
	)
	(segment
		(start 173.548802 -295.978326)
		(end 174.336202 -295.190926)
		(width 0.16002)
		(layer "In6.Cu")
		(net "M_K_CPU1_SB_DQS_DN<6>")
	)
	(segment
		(start 172.564298 -296.35831)
		(end 172.944282 -295.978326)
		(width 0.16002)
		(layer "In6.Cu")
		(net "M_K_CPU1_SB_DQS_DN<6>")
	)
	(segment
		(start 145.163032 -281.701494)
		(end 145.363692 -281.618436)
		(width 0.09525)
		(layer "In6.Cu")
		(net "M_K_CPU1_SB_DQS_DN<6>")
	)
	(segment
		(start 187.652406 -296.35831)
		(end 188.03239 -295.978326)
		(width 0.16002)
		(layer "In6.Cu")
		(net "M_K_CPU1_SB_DQS_DN<6>")
	)
	(segment
		(start 172.944282 -295.978326)
		(end 173.548802 -295.978326)
		(width 0.16002)
		(layer "In6.Cu")
		(net "M_K_CPU1_SB_DQS_DN<6>")
	)
	(segment
		(start 194.33032 -295.359074)
		(end 194.604132 -295.085262)
		(width 0.16002)
		(layer "In6.Cu")
		(net "M_K_CPU1_SB_DQS_DN<6>")
	)
	(segment
		(start 178.194462 -295.508172)
		(end 179.0446 -296.35831)
		(width 0.16002)
		(layer "In6.Cu")
		(net "M_K_CPU1_SB_DQS_DN<6>")
	)
	(segment
		(start 164.428424 -295.84904)
		(end 164.55771 -295.978326)
		(width 0.16002)
		(layer "In6.Cu")
		(net "M_K_CPU1_SB_DQS_DN<6>")
	)
	(segment
		(start 144.785588 -281.701494)
		(end 144.797526 -281.708352)
		(width 0.09525)
		(layer "In6.Cu")
		(net "M_K_CPU1_SB_DQS_DN<6>")
	)
	(segment
		(start 168.75252 -295.853866)
		(end 169.100754 -295.853866)
		(width 0.16002)
		(layer "In6.Cu")
		(net "M_K_CPU1_SB_DQS_DN<6>")
	)
	(segment
		(start 190.800736 -295.508172)
		(end 191.982344 -295.508172)
		(width 0.16002)
		(layer "In6.Cu")
		(net "M_K_CPU1_SB_DQS_DN<6>")
	)
	(segment
		(start 162.105594 -293.52621)
		(end 162.105594 -294.002714)
		(width 0.16002)
		(layer "In6.Cu")
		(net "M_K_CPU1_SB_DQS_DN<6>")
	)
	(segment
		(start 150.397718 -281.818334)
		(end 162.105594 -293.52621)
		(width 0.16002)
		(layer "In6.Cu")
		(net "M_K_CPU1_SB_DQS_DN<6>")
	)
	(segment
		(start 163.344606 -295.737026)
		(end 163.59124 -295.98366)
		(width 0.16002)
		(layer "In6.Cu")
		(net "M_K_CPU1_SB_DQS_DN<6>")
	)
	(segment
		(start 174.336202 -295.190926)
		(end 175.395382 -295.190926)
		(width 0.16002)
		(layer "In6.Cu")
		(net "M_K_CPU1_SB_DQS_DN<6>")
	)
	(segment
		(start 169.597832 -295.190926)
		(end 170.333162 -295.190926)
		(width 0.16002)
		(layer "In6.Cu")
		(net "M_K_CPU1_SB_DQS_DN<6>")
	)
	(segment
		(start 141.36878 -281.641804)
		(end 141.469618 -281.668474)
		(width 0.09525)
		(layer "In6.Cu")
		(net "M_K_CPU1_SB_DQS_DN<6>")
	)
	(segment
		(start 191.982344 -295.508172)
		(end 192.131442 -295.359074)
		(width 0.16002)
		(layer "In6.Cu")
		(net "M_K_CPU1_SB_DQS_DN<6>")
	)
	(segment
		(start 171.500546 -296.35831)
		(end 172.564298 -296.35831)
		(width 0.16002)
		(layer "In6.Cu")
		(net "M_K_CPU1_SB_DQS_DN<6>")
	)
	(segment
		(start 146.680936 -281.677872)
		(end 146.88058 -281.877516)
		(width 0.09525)
		(layer "In6.Cu")
		(net "M_K_CPU1_SB_DQS_DN<6>")
	)
	(segment
		(start 168.255442 -295.190926)
		(end 168.5925 -295.527984)
		(width 0.16002)
		(layer "In6.Cu")
		(net "M_K_CPU1_SB_DQS_DN<6>")
	)
	(segment
		(start 168.5925 -295.693846)
		(end 168.75252 -295.853866)
		(width 0.16002)
		(layer "In6.Cu")
		(net "M_K_CPU1_SB_DQS_DN<6>")
	)
	(segment
		(start 163.054792 -294.475408)
		(end 163.479226 -294.899842)
		(width 0.16002)
		(layer "In6.Cu")
		(net "M_K_CPU1_SB_DQS_DN<6>")
	)
	(segment
		(start 163.95192 -295.84904)
		(end 164.428424 -295.84904)
		(width 0.16002)
		(layer "In6.Cu")
		(net "M_K_CPU1_SB_DQS_DN<6>")
	)
	(segment
		(start 169.100754 -295.853866)
		(end 169.260774 -295.693846)
		(width 0.16002)
		(layer "In6.Cu")
		(net "M_K_CPU1_SB_DQS_DN<6>")
	)
	(segment
		(start 162.105594 -294.002714)
		(end 161.970974 -294.137334)
		(width 0.16002)
		(layer "In6.Cu")
		(net "M_K_CPU1_SB_DQS_DN<6>")
	)
	(segment
		(start 189.42431 -295.190926)
		(end 190.48349 -295.190926)
		(width 0.16002)
		(layer "In6.Cu")
		(net "M_K_CPU1_SB_DQS_DN<6>")
	)
	(segment
		(start 185.738516 -295.508172)
		(end 186.588654 -296.35831)
		(width 0.16002)
		(layer "In6.Cu")
		(net "M_K_CPU1_SB_DQS_DN<6>")
	)
	(segment
		(start 161.970974 -294.137334)
		(end 161.970974 -294.363394)
		(width 0.16002)
		(layer "In6.Cu")
		(net "M_K_CPU1_SB_DQS_DN<6>")
	)
	(segment
		(start 181.092856 -295.978326)
		(end 181.880256 -295.190926)
		(width 0.16002)
		(layer "In6.Cu")
		(net "M_K_CPU1_SB_DQS_DN<6>")
	)
	(segment
		(start 162.217608 -294.610028)
		(end 162.443668 -294.610028)
		(width 0.16002)
		(layer "In6.Cu")
		(net "M_K_CPU1_SB_DQS_DN<6>")
	)
	(segment
		(start 192.131442 -295.359074)
		(end 194.33032 -295.359074)
		(width 0.16002)
		(layer "In6.Cu")
		(net "M_K_CPU1_SB_DQS_DN<6>")
	)
	(segment
		(start 163.479226 -295.376346)
		(end 163.344606 -295.510966)
		(width 0.16002)
		(layer "In6.Cu")
		(net "M_K_CPU1_SB_DQS_DN<6>")
	)
	(segment
		(start 169.260774 -295.527984)
		(end 169.597832 -295.190926)
		(width 0.16002)
		(layer "In6.Cu")
		(net "M_K_CPU1_SB_DQS_DN<6>")
	)
	(segment
		(start 166.792148 -295.190926)
		(end 168.255442 -295.190926)
		(width 0.16002)
		(layer "In6.Cu")
		(net "M_K_CPU1_SB_DQS_DN<6>")
	)
	(segment
		(start 163.8173 -295.98366)
		(end 163.95192 -295.84904)
		(width 0.16002)
		(layer "In6.Cu")
		(net "M_K_CPU1_SB_DQS_DN<6>")
	)
	(segment
		(start 186.588654 -296.35831)
		(end 187.652406 -296.35831)
		(width 0.16002)
		(layer "In6.Cu")
		(net "M_K_CPU1_SB_DQS_DN<6>")
	)
	(segment
		(start 141.966188 -281.701494)
		(end 141.97457 -281.70632)
		(width 0.09525)
		(layer "In6.Cu")
		(net "M_K_CPU1_SB_DQS_DN<6>")
	)
	(segment
		(start 164.55771 -295.978326)
		(end 166.004748 -295.978326)
		(width 0.16002)
		(layer "In6.Cu")
		(net "M_K_CPU1_SB_DQS_DN<6>")
	)
	(segment
		(start 163.344606 -295.510966)
		(end 163.344606 -295.737026)
		(width 0.16002)
		(layer "In6.Cu")
		(net "M_K_CPU1_SB_DQS_DN<6>")
	)
	(segment
		(start 163.479226 -294.899842)
		(end 163.479226 -295.376346)
		(width 0.16002)
		(layer "In6.Cu")
		(net "M_K_CPU1_SB_DQS_DN<6>")
	)
	(segment
		(start 161.970974 -294.363394)
		(end 162.217608 -294.610028)
		(width 0.16002)
		(layer "In6.Cu")
		(net "M_K_CPU1_SB_DQS_DN<6>")
	)
	(segment
		(start 180.108352 -296.35831)
		(end 180.488336 -295.978326)
		(width 0.16002)
		(layer "In6.Cu")
		(net "M_K_CPU1_SB_DQS_DN<6>")
	)
	(segment
		(start 175.712628 -295.508172)
		(end 178.194462 -295.508172)
		(width 0.16002)
		(layer "In6.Cu")
		(net "M_K_CPU1_SB_DQS_DN<6>")
	)
	(segment
		(start 188.63691 -295.978326)
		(end 189.42431 -295.190926)
		(width 0.16002)
		(layer "In6.Cu")
		(net "M_K_CPU1_SB_DQS_DN<6>")
	)
	(segment
		(start 168.5925 -295.527984)
		(end 168.5925 -295.693846)
		(width 0.16002)
		(layer "In6.Cu")
		(net "M_K_CPU1_SB_DQS_DN<6>")
	)
	(segment
		(start 162.578288 -294.475408)
		(end 163.054792 -294.475408)
		(width 0.16002)
		(layer "In6.Cu")
		(net "M_K_CPU1_SB_DQS_DN<6>")
	)
	(segment
		(start 144.222978 -281.701494)
		(end 144.233392 -281.695398)
		(width 0.09525)
		(layer "In6.Cu")
		(net "M_K_CPU1_SB_DQS_DN<6>")
	)
	(segment
		(start 175.395382 -295.190926)
		(end 175.712628 -295.508172)
		(width 0.16002)
		(layer "In6.Cu")
		(net "M_K_CPU1_SB_DQS_DN<6>")
	)
	(segment
		(start 180.488336 -295.978326)
		(end 181.092856 -295.978326)
		(width 0.16002)
		(layer "In6.Cu")
		(net "M_K_CPU1_SB_DQS_DN<6>")
	)
	(segment
		(start 162.443668 -294.610028)
		(end 162.578288 -294.475408)
		(width 0.16002)
		(layer "In6.Cu")
		(net "M_K_CPU1_SB_DQS_DN<6>")
	)
	(segment
		(start 182.939436 -295.190926)
		(end 183.256682 -295.508172)
		(width 0.16002)
		(layer "In6.Cu")
		(net "M_K_CPU1_SB_DQS_DN<6>")
	)
	(segment
		(start 141.214856 -281.376374)
		(end 141.36878 -281.641804)
		(width 0.09525)
		(layer "In6.Cu")
		(net "M_K_CPU1_SB_DQS_DN<6>")
	)
	(segment
		(start 170.333162 -295.190926)
		(end 171.500546 -296.35831)
		(width 0.16002)
		(layer "In6.Cu")
		(net "M_K_CPU1_SB_DQS_DN<6>")
	)
	(segment
		(start 190.48349 -295.190926)
		(end 190.800736 -295.508172)
		(width 0.16002)
		(layer "In6.Cu")
		(net "M_K_CPU1_SB_DQS_DN<6>")
	)
	(segment
		(start 179.0446 -296.35831)
		(end 180.108352 -296.35831)
		(width 0.16002)
		(layer "In6.Cu")
		(net "M_K_CPU1_SB_DQS_DN<6>")
	)
	(segment
		(start 147.836382 -281.877516)
		(end 147.895564 -281.818334)
		(width 0.09525)
		(layer "In6.Cu")
		(net "M_K_CPU1_SB_DQS_DN<6>")
	)
	(arc
		(start 141.469618 -281.668474)
		(mid 141.721759 -281.626904)
		(end 141.966188 -281.701494)
		(width 0.09525)
		(layer "In6.Cu")
		(net "M_K_CPU1_SB_DQS_DN<6>")
	)
	(arc
		(start 143.283178 -281.701494)
		(mid 143.56461 -281.625739)
		(end 143.846042 -281.701494)
		(width 0.09525)
		(layer "In6.Cu")
		(net "M_K_CPU1_SB_DQS_DN<6>")
	)
	(arc
		(start 144.797526 -281.708352)
		(mid 144.981161 -281.752302)
		(end 145.163032 -281.701494)
		(width 0.09525)
		(layer "In6.Cu")
		(net "M_K_CPU1_SB_DQS_DN<6>")
	)
	(arc
		(start 144.233392 -281.695398)
		(mid 144.5103 -281.625721)
		(end 144.785588 -281.701494)
		(width 0.09525)
		(layer "In6.Cu")
		(net "M_K_CPU1_SB_DQS_DN<6>")
	)
	(arc
		(start 143.846042 -281.701494)
		(mid 144.027658 -281.752231)
		(end 144.21104 -281.708352)
		(width 0.09525)
		(layer "In6.Cu")
		(net "M_K_CPU1_SB_DQS_DN<6>")
	)
	(arc
		(start 141.97457 -281.70632)
		(mid 142.159602 -281.752234)
		(end 142.343378 -281.701494)
		(width 0.09525)
		(layer "In6.Cu")
		(net "M_K_CPU1_SB_DQS_DN<6>")
	)
	(arc
		(start 142.906242 -281.701494)
		(mid 143.09471 -281.752171)
		(end 143.283178 -281.701494)
		(width 0.09525)
		(layer "In6.Cu")
		(net "M_K_CPU1_SB_DQS_DN<6>")
	)
	(arc
		(start 142.343378 -281.701494)
		(mid 142.62481 -281.625739)
		(end 142.906242 -281.701494)
		(width 0.09525)
		(layer "In6.Cu")
		(net "M_K_CPU1_SB_DQS_DN<6>")
	)
	(segment
		(start 140.748004 -276.2504)
		(end 141.214856 -276.516338)
		(width 0.12954)
		(layer "F.Cu")
		(net "M_K_CPU1_SB_DQS_DN<5>")
	)
	(segment
		(start 194.33032 -286.00908)
		(end 194.604132 -285.735268)
		(width 0.16002)
		(layer "In6.Cu")
		(net "M_K_CPU1_SB_DQS_DN<5>")
	)
	(segment
		(start 182.939436 -285.840932)
		(end 183.256682 -286.158178)
		(width 0.16002)
		(layer "In6.Cu")
		(net "M_K_CPU1_SB_DQS_DN<5>")
	)
	(segment
		(start 169.046652 -286.486346)
		(end 169.394886 -286.486346)
		(width 0.16002)
		(layer "In6.Cu")
		(net "M_K_CPU1_SB_DQS_DN<5>")
	)
	(segment
		(start 180.488336 -286.628332)
		(end 181.092856 -286.628332)
		(width 0.16002)
		(layer "In6.Cu")
		(net "M_K_CPU1_SB_DQS_DN<5>")
	)
	(segment
		(start 147.836382 -275.875242)
		(end 147.895564 -275.81606)
		(width 0.09525)
		(layer "In6.Cu")
		(net "M_K_CPU1_SB_DQS_DN<5>")
	)
	(segment
		(start 173.548802 -286.628332)
		(end 174.336202 -285.840932)
		(width 0.16002)
		(layer "In6.Cu")
		(net "M_K_CPU1_SB_DQS_DN<5>")
	)
	(segment
		(start 145.884646 -276.497796)
		(end 146.674586 -275.707602)
		(width 0.09525)
		(layer "In6.Cu")
		(net "M_K_CPU1_SB_DQS_DN<5>")
	)
	(segment
		(start 147.472146 -275.875242)
		(end 147.836382 -275.875242)
		(width 0.09525)
		(layer "In6.Cu")
		(net "M_K_CPU1_SB_DQS_DN<5>")
	)
	(segment
		(start 168.549574 -285.195518)
		(end 168.886632 -285.532576)
		(width 0.16002)
		(layer "In6.Cu")
		(net "M_K_CPU1_SB_DQS_DN<5>")
	)
	(segment
		(start 166.004748 -286.628332)
		(end 166.792148 -285.840932)
		(width 0.16002)
		(layer "In6.Cu")
		(net "M_K_CPU1_SB_DQS_DN<5>")
	)
	(segment
		(start 179.0446 -287.008316)
		(end 180.108352 -287.008316)
		(width 0.16002)
		(layer "In6.Cu")
		(net "M_K_CPU1_SB_DQS_DN<5>")
	)
	(segment
		(start 163.909756 -286.628332)
		(end 166.004748 -286.628332)
		(width 0.16002)
		(layer "In6.Cu")
		(net "M_K_CPU1_SB_DQS_DN<5>")
	)
	(segment
		(start 175.712628 -286.158178)
		(end 178.194462 -286.158178)
		(width 0.16002)
		(layer "In6.Cu")
		(net "M_K_CPU1_SB_DQS_DN<5>")
	)
	(segment
		(start 141.214856 -276.516338)
		(end 141.36878 -276.781768)
		(width 0.09525)
		(layer "In6.Cu")
		(net "M_K_CPU1_SB_DQS_DN<5>")
	)
	(segment
		(start 186.588654 -287.008316)
		(end 187.652406 -287.008316)
		(width 0.16002)
		(layer "In6.Cu")
		(net "M_K_CPU1_SB_DQS_DN<5>")
	)
	(segment
		(start 172.564298 -287.008316)
		(end 172.944282 -286.628332)
		(width 0.16002)
		(layer "In6.Cu")
		(net "M_K_CPU1_SB_DQS_DN<5>")
	)
	(segment
		(start 169.394886 -286.486346)
		(end 169.554906 -286.326326)
		(width 0.16002)
		(layer "In6.Cu")
		(net "M_K_CPU1_SB_DQS_DN<5>")
	)
	(segment
		(start 181.092856 -286.628332)
		(end 181.880256 -285.840932)
		(width 0.16002)
		(layer "In6.Cu")
		(net "M_K_CPU1_SB_DQS_DN<5>")
	)
	(segment
		(start 180.108352 -287.008316)
		(end 180.488336 -286.628332)
		(width 0.16002)
		(layer "In6.Cu")
		(net "M_K_CPU1_SB_DQS_DN<5>")
	)
	(segment
		(start 190.48349 -285.840932)
		(end 190.800736 -286.158178)
		(width 0.16002)
		(layer "In6.Cu")
		(net "M_K_CPU1_SB_DQS_DN<5>")
	)
	(segment
		(start 183.256682 -286.158178)
		(end 185.738516 -286.158178)
		(width 0.16002)
		(layer "In6.Cu")
		(net "M_K_CPU1_SB_DQS_DN<5>")
	)
	(segment
		(start 168.886632 -285.532576)
		(end 168.886632 -286.326326)
		(width 0.16002)
		(layer "In6.Cu")
		(net "M_K_CPU1_SB_DQS_DN<5>")
	)
	(segment
		(start 174.336202 -285.840932)
		(end 175.395382 -285.840932)
		(width 0.16002)
		(layer "In6.Cu")
		(net "M_K_CPU1_SB_DQS_DN<5>")
	)
	(segment
		(start 166.792148 -285.840932)
		(end 167.453818 -285.840932)
		(width 0.16002)
		(layer "In6.Cu")
		(net "M_K_CPU1_SB_DQS_DN<5>")
	)
	(segment
		(start 144.21104 -276.848316)
		(end 144.222978 -276.841458)
		(width 0.09525)
		(layer "In6.Cu")
		(net "M_K_CPU1_SB_DQS_DN<5>")
	)
	(segment
		(start 171.500546 -287.008316)
		(end 172.564298 -287.008316)
		(width 0.16002)
		(layer "In6.Cu")
		(net "M_K_CPU1_SB_DQS_DN<5>")
	)
	(segment
		(start 144.785588 -276.841458)
		(end 144.797526 -276.848316)
		(width 0.09525)
		(layer "In6.Cu")
		(net "M_K_CPU1_SB_DQS_DN<5>")
	)
	(segment
		(start 172.944282 -286.628332)
		(end 173.548802 -286.628332)
		(width 0.16002)
		(layer "In6.Cu")
		(net "M_K_CPU1_SB_DQS_DN<5>")
	)
	(segment
		(start 189.42431 -285.840932)
		(end 190.48349 -285.840932)
		(width 0.16002)
		(layer "In6.Cu")
		(net "M_K_CPU1_SB_DQS_DN<5>")
	)
	(segment
		(start 168.886632 -286.326326)
		(end 169.046652 -286.486346)
		(width 0.16002)
		(layer "In6.Cu")
		(net "M_K_CPU1_SB_DQS_DN<5>")
	)
	(segment
		(start 190.800736 -286.158178)
		(end 191.982344 -286.158178)
		(width 0.16002)
		(layer "In6.Cu")
		(net "M_K_CPU1_SB_DQS_DN<5>")
	)
	(segment
		(start 192.131442 -286.00908)
		(end 194.33032 -286.00908)
		(width 0.16002)
		(layer "In6.Cu")
		(net "M_K_CPU1_SB_DQS_DN<5>")
	)
	(segment
		(start 191.982344 -286.158178)
		(end 192.131442 -286.00908)
		(width 0.16002)
		(layer "In6.Cu")
		(net "M_K_CPU1_SB_DQS_DN<5>")
	)
	(segment
		(start 145.240248 -276.78253)
		(end 145.281142 -276.741636)
		(width 0.09525)
		(layer "In6.Cu")
		(net "M_K_CPU1_SB_DQS_DN<5>")
	)
	(segment
		(start 175.395382 -285.840932)
		(end 175.712628 -286.158178)
		(width 0.16002)
		(layer "In6.Cu")
		(net "M_K_CPU1_SB_DQS_DN<5>")
	)
	(segment
		(start 141.966188 -276.841458)
		(end 141.97457 -276.846284)
		(width 0.09525)
		(layer "In6.Cu")
		(net "M_K_CPU1_SB_DQS_DN<5>")
	)
	(segment
		(start 188.03239 -286.628332)
		(end 188.63691 -286.628332)
		(width 0.16002)
		(layer "In6.Cu")
		(net "M_K_CPU1_SB_DQS_DN<5>")
	)
	(segment
		(start 169.891964 -285.840932)
		(end 170.333162 -285.840932)
		(width 0.16002)
		(layer "In6.Cu")
		(net "M_K_CPU1_SB_DQS_DN<5>")
	)
	(segment
		(start 187.652406 -287.008316)
		(end 188.03239 -286.628332)
		(width 0.16002)
		(layer "In6.Cu")
		(net "M_K_CPU1_SB_DQS_DN<5>")
	)
	(segment
		(start 167.950896 -285.195518)
		(end 168.549574 -285.195518)
		(width 0.16002)
		(layer "In6.Cu")
		(net "M_K_CPU1_SB_DQS_DN<5>")
	)
	(segment
		(start 147.22856 -275.631656)
		(end 147.472146 -275.875242)
		(width 0.09525)
		(layer "In6.Cu")
		(net "M_K_CPU1_SB_DQS_DN<5>")
	)
	(segment
		(start 141.36878 -276.781768)
		(end 141.469618 -276.808438)
		(width 0.09525)
		(layer "In6.Cu")
		(net "M_K_CPU1_SB_DQS_DN<5>")
	)
	(segment
		(start 146.674586 -275.707602)
		(end 146.858228 -275.631656)
		(width 0.09525)
		(layer "In6.Cu")
		(net "M_K_CPU1_SB_DQS_DN<5>")
	)
	(segment
		(start 167.453818 -285.840932)
		(end 167.613838 -285.680912)
		(width 0.16002)
		(layer "In6.Cu")
		(net "M_K_CPU1_SB_DQS_DN<5>")
	)
	(segment
		(start 144.222978 -276.841458)
		(end 144.233392 -276.835362)
		(width 0.09525)
		(layer "In6.Cu")
		(net "M_K_CPU1_SB_DQS_DN<5>")
	)
	(segment
		(start 167.613838 -285.680912)
		(end 167.613838 -285.532576)
		(width 0.16002)
		(layer "In6.Cu")
		(net "M_K_CPU1_SB_DQS_DN<5>")
	)
	(segment
		(start 167.613838 -285.532576)
		(end 167.950896 -285.195518)
		(width 0.16002)
		(layer "In6.Cu")
		(net "M_K_CPU1_SB_DQS_DN<5>")
	)
	(segment
		(start 170.333162 -285.840932)
		(end 171.500546 -287.008316)
		(width 0.16002)
		(layer "In6.Cu")
		(net "M_K_CPU1_SB_DQS_DN<5>")
	)
	(segment
		(start 169.554906 -286.17799)
		(end 169.891964 -285.840932)
		(width 0.16002)
		(layer "In6.Cu")
		(net "M_K_CPU1_SB_DQS_DN<5>")
	)
	(segment
		(start 147.919186 -275.81606)
		(end 153.097484 -275.81606)
		(width 0.16002)
		(layer "In6.Cu")
		(net "M_K_CPU1_SB_DQS_DN<5>")
	)
	(segment
		(start 146.858228 -275.631656)
		(end 147.22856 -275.631656)
		(width 0.09525)
		(layer "In6.Cu")
		(net "M_K_CPU1_SB_DQS_DN<5>")
	)
	(segment
		(start 169.554906 -286.326326)
		(end 169.554906 -286.17799)
		(width 0.16002)
		(layer "In6.Cu")
		(net "M_K_CPU1_SB_DQS_DN<5>")
	)
	(segment
		(start 147.895564 -275.81606)
		(end 147.919186 -275.81606)
		(width 0.09525)
		(layer "In6.Cu")
		(net "M_K_CPU1_SB_DQS_DN<5>")
	)
	(segment
		(start 178.194462 -286.158178)
		(end 179.0446 -287.008316)
		(width 0.16002)
		(layer "In6.Cu")
		(net "M_K_CPU1_SB_DQS_DN<5>")
	)
	(segment
		(start 153.097484 -275.81606)
		(end 163.909756 -286.628332)
		(width 0.16002)
		(layer "In6.Cu")
		(net "M_K_CPU1_SB_DQS_DN<5>")
	)
	(segment
		(start 188.63691 -286.628332)
		(end 189.42431 -285.840932)
		(width 0.16002)
		(layer "In6.Cu")
		(net "M_K_CPU1_SB_DQS_DN<5>")
	)
	(segment
		(start 185.738516 -286.158178)
		(end 186.588654 -287.008316)
		(width 0.16002)
		(layer "In6.Cu")
		(net "M_K_CPU1_SB_DQS_DN<5>")
	)
	(segment
		(start 181.880256 -285.840932)
		(end 182.939436 -285.840932)
		(width 0.16002)
		(layer "In6.Cu")
		(net "M_K_CPU1_SB_DQS_DN<5>")
	)
	(arc
		(start 145.687288 -276.564344)
		(mid 145.790779 -276.545355)
		(end 145.884646 -276.497796)
		(width 0.09525)
		(layer "In6.Cu")
		(net "M_K_CPU1_SB_DQS_DN<5>")
	)
	(arc
		(start 142.343378 -276.841458)
		(mid 142.62481 -276.765703)
		(end 142.906242 -276.841458)
		(width 0.09525)
		(layer "In6.Cu")
		(net "M_K_CPU1_SB_DQS_DN<5>")
	)
	(arc
		(start 141.97457 -276.846284)
		(mid 142.159602 -276.892198)
		(end 142.343378 -276.841458)
		(width 0.09525)
		(layer "In6.Cu")
		(net "M_K_CPU1_SB_DQS_DN<5>")
	)
	(arc
		(start 145.163032 -276.841458)
		(mid 145.203556 -276.814503)
		(end 145.240248 -276.78253)
		(width 0.09525)
		(layer "In6.Cu")
		(net "M_K_CPU1_SB_DQS_DN<5>")
	)
	(arc
		(start 143.846042 -276.841458)
		(mid 144.027658 -276.892195)
		(end 144.21104 -276.848316)
		(width 0.09525)
		(layer "In6.Cu")
		(net "M_K_CPU1_SB_DQS_DN<5>")
	)
	(arc
		(start 144.233392 -276.835362)
		(mid 144.5103 -276.765685)
		(end 144.785588 -276.841458)
		(width 0.09525)
		(layer "In6.Cu")
		(net "M_K_CPU1_SB_DQS_DN<5>")
	)
	(arc
		(start 142.906242 -276.841458)
		(mid 143.09471 -276.892135)
		(end 143.283178 -276.841458)
		(width 0.09525)
		(layer "In6.Cu")
		(net "M_K_CPU1_SB_DQS_DN<5>")
	)
	(arc
		(start 145.281142 -276.741636)
		(mid 145.467451 -276.614593)
		(end 145.687288 -276.564344)
		(width 0.09525)
		(layer "In6.Cu")
		(net "M_K_CPU1_SB_DQS_DN<5>")
	)
	(arc
		(start 143.283178 -276.841458)
		(mid 143.56461 -276.765703)
		(end 143.846042 -276.841458)
		(width 0.09525)
		(layer "In6.Cu")
		(net "M_K_CPU1_SB_DQS_DN<5>")
	)
	(arc
		(start 141.469618 -276.808438)
		(mid 141.721759 -276.766868)
		(end 141.966188 -276.841458)
		(width 0.09525)
		(layer "In6.Cu")
		(net "M_K_CPU1_SB_DQS_DN<5>")
	)
	(arc
		(start 144.797526 -276.848316)
		(mid 144.981161 -276.892266)
		(end 145.163032 -276.841458)
		(width 0.09525)
		(layer "In6.Cu")
		(net "M_K_CPU1_SB_DQS_DN<5>")
	)
	(segment
		(start 140.748004 -271.390364)
		(end 141.214856 -271.656302)
		(width 0.12954)
		(layer "F.Cu")
		(net "M_K_CPU1_SB_DQS_DN<4>")
	)
	(segment
		(start 163.58108 -276.380194)
		(end 163.500562 -276.460712)
		(width 0.16002)
		(layer "In6.Cu")
		(net "M_K_CPU1_SB_DQS_DN<4>")
	)
	(segment
		(start 160.833816 -273.15668)
		(end 160.833816 -273.63293)
		(width 0.16002)
		(layer "In6.Cu")
		(net "M_K_CPU1_SB_DQS_DN<4>")
	)
	(segment
		(start 158.478728 -271.438878)
		(end 158.559246 -271.358614)
		(width 0.16002)
		(layer "In6.Cu")
		(net "M_K_CPU1_SB_DQS_DN<4>")
	)
	(segment
		(start 156.958284 -270.144494)
		(end 158.252668 -271.438878)
		(width 0.16002)
		(layer "In6.Cu")
		(net "M_K_CPU1_SB_DQS_DN<4>")
	)
	(segment
		(start 162.12693 -275.31314)
		(end 162.373564 -275.559774)
		(width 0.16002)
		(layer "In6.Cu")
		(net "M_K_CPU1_SB_DQS_DN<4>")
	)
	(segment
		(start 190.800736 -276.808184)
		(end 191.982344 -276.808184)
		(width 0.16002)
		(layer "In6.Cu")
		(net "M_K_CPU1_SB_DQS_DN<4>")
	)
	(segment
		(start 182.939436 -276.490938)
		(end 183.256682 -276.808184)
		(width 0.16002)
		(layer "In6.Cu")
		(net "M_K_CPU1_SB_DQS_DN<4>")
	)
	(segment
		(start 162.207448 -274.530312)
		(end 162.207448 -275.006562)
		(width 0.16002)
		(layer "In6.Cu")
		(net "M_K_CPU1_SB_DQS_DN<4>")
	)
	(segment
		(start 181.880256 -276.490938)
		(end 182.939436 -276.490938)
		(width 0.16002)
		(layer "In6.Cu")
		(net "M_K_CPU1_SB_DQS_DN<4>")
	)
	(segment
		(start 167.851328 -276.490938)
		(end 168.168574 -276.808184)
		(width 0.16002)
		(layer "In6.Cu")
		(net "M_K_CPU1_SB_DQS_DN<4>")
	)
	(segment
		(start 162.12693 -275.08708)
		(end 162.12693 -275.31314)
		(width 0.16002)
		(layer "In6.Cu")
		(net "M_K_CPU1_SB_DQS_DN<4>")
	)
	(segment
		(start 163.58108 -275.903944)
		(end 163.58108 -276.380194)
		(width 0.16002)
		(layer "In6.Cu")
		(net "M_K_CPU1_SB_DQS_DN<4>")
	)
	(segment
		(start 163.500562 -276.686772)
		(end 164.092128 -277.278338)
		(width 0.16002)
		(layer "In6.Cu")
		(net "M_K_CPU1_SB_DQS_DN<4>")
	)
	(segment
		(start 163.500562 -276.460712)
		(end 163.500562 -276.686772)
		(width 0.16002)
		(layer "In6.Cu")
		(net "M_K_CPU1_SB_DQS_DN<4>")
	)
	(segment
		(start 183.256682 -276.808184)
		(end 185.738516 -276.808184)
		(width 0.16002)
		(layer "In6.Cu")
		(net "M_K_CPU1_SB_DQS_DN<4>")
	)
	(segment
		(start 192.131442 -276.659086)
		(end 194.33032 -276.659086)
		(width 0.16002)
		(layer "In6.Cu")
		(net "M_K_CPU1_SB_DQS_DN<4>")
	)
	(segment
		(start 141.36878 -271.921732)
		(end 141.469618 -271.948402)
		(width 0.09525)
		(layer "In6.Cu")
		(net "M_K_CPU1_SB_DQS_DN<4>")
	)
	(segment
		(start 159.932878 -272.732246)
		(end 160.409382 -272.732246)
		(width 0.16002)
		(layer "In6.Cu")
		(net "M_K_CPU1_SB_DQS_DN<4>")
	)
	(segment
		(start 161.783014 -274.105878)
		(end 162.207448 -274.530312)
		(width 0.16002)
		(layer "In6.Cu")
		(net "M_K_CPU1_SB_DQS_DN<4>")
	)
	(segment
		(start 179.0446 -277.658322)
		(end 180.108352 -277.658322)
		(width 0.16002)
		(layer "In6.Cu")
		(net "M_K_CPU1_SB_DQS_DN<4>")
	)
	(segment
		(start 161.30651 -274.105878)
		(end 161.783014 -274.105878)
		(width 0.16002)
		(layer "In6.Cu")
		(net "M_K_CPU1_SB_DQS_DN<4>")
	)
	(segment
		(start 174.336202 -276.490938)
		(end 175.395382 -276.490938)
		(width 0.16002)
		(layer "In6.Cu")
		(net "M_K_CPU1_SB_DQS_DN<4>")
	)
	(segment
		(start 147.919186 -270.144494)
		(end 156.958284 -270.144494)
		(width 0.16002)
		(layer "In6.Cu")
		(net "M_K_CPU1_SB_DQS_DN<4>")
	)
	(segment
		(start 171.500546 -277.658322)
		(end 172.564298 -277.658322)
		(width 0.16002)
		(layer "In6.Cu")
		(net "M_K_CPU1_SB_DQS_DN<4>")
	)
	(segment
		(start 170.650408 -276.808184)
		(end 171.500546 -277.658322)
		(width 0.16002)
		(layer "In6.Cu")
		(net "M_K_CPU1_SB_DQS_DN<4>")
	)
	(segment
		(start 158.252668 -271.438878)
		(end 158.478728 -271.438878)
		(width 0.16002)
		(layer "In6.Cu")
		(net "M_K_CPU1_SB_DQS_DN<4>")
	)
	(segment
		(start 175.712628 -276.808184)
		(end 178.194462 -276.808184)
		(width 0.16002)
		(layer "In6.Cu")
		(net "M_K_CPU1_SB_DQS_DN<4>")
	)
	(segment
		(start 158.559246 -271.358614)
		(end 159.03575 -271.358614)
		(width 0.16002)
		(layer "In6.Cu")
		(net "M_K_CPU1_SB_DQS_DN<4>")
	)
	(segment
		(start 180.488336 -277.278338)
		(end 181.092856 -277.278338)
		(width 0.16002)
		(layer "In6.Cu")
		(net "M_K_CPU1_SB_DQS_DN<4>")
	)
	(segment
		(start 194.33032 -276.659086)
		(end 194.604132 -276.385274)
		(width 0.16002)
		(layer "In6.Cu")
		(net "M_K_CPU1_SB_DQS_DN<4>")
	)
	(segment
		(start 181.092856 -277.278338)
		(end 181.880256 -276.490938)
		(width 0.16002)
		(layer "In6.Cu")
		(net "M_K_CPU1_SB_DQS_DN<4>")
	)
	(segment
		(start 191.982344 -276.808184)
		(end 192.131442 -276.659086)
		(width 0.16002)
		(layer "In6.Cu")
		(net "M_K_CPU1_SB_DQS_DN<4>")
	)
	(segment
		(start 172.944282 -277.278338)
		(end 173.548802 -277.278338)
		(width 0.16002)
		(layer "In6.Cu")
		(net "M_K_CPU1_SB_DQS_DN<4>")
	)
	(segment
		(start 145.240502 -271.921732)
		(end 145.404078 -271.75841)
		(width 0.09525)
		(layer "In6.Cu")
		(net "M_K_CPU1_SB_DQS_DN<4>")
	)
	(segment
		(start 187.652406 -277.658322)
		(end 188.03239 -277.278338)
		(width 0.16002)
		(layer "In6.Cu")
		(net "M_K_CPU1_SB_DQS_DN<4>")
	)
	(segment
		(start 168.168574 -276.808184)
		(end 170.650408 -276.808184)
		(width 0.16002)
		(layer "In6.Cu")
		(net "M_K_CPU1_SB_DQS_DN<4>")
	)
	(segment
		(start 144.21485 -271.986248)
		(end 144.223232 -271.981422)
		(width 0.09525)
		(layer "In6.Cu")
		(net "M_K_CPU1_SB_DQS_DN<4>")
	)
	(segment
		(start 162.207448 -275.006562)
		(end 162.12693 -275.08708)
		(width 0.16002)
		(layer "In6.Cu")
		(net "M_K_CPU1_SB_DQS_DN<4>")
	)
	(segment
		(start 159.85236 -272.81251)
		(end 159.932878 -272.732246)
		(width 0.16002)
		(layer "In6.Cu")
		(net "M_K_CPU1_SB_DQS_DN<4>")
	)
	(segment
		(start 141.966188 -271.981422)
		(end 141.97457 -271.986248)
		(width 0.09525)
		(layer "In6.Cu")
		(net "M_K_CPU1_SB_DQS_DN<4>")
	)
	(segment
		(start 160.999932 -274.186142)
		(end 161.225992 -274.186142)
		(width 0.16002)
		(layer "In6.Cu")
		(net "M_K_CPU1_SB_DQS_DN<4>")
	)
	(segment
		(start 159.460184 -272.259298)
		(end 159.379666 -272.339816)
		(width 0.16002)
		(layer "In6.Cu")
		(net "M_K_CPU1_SB_DQS_DN<4>")
	)
	(segment
		(start 147.836382 -270.203676)
		(end 147.895564 -270.144494)
		(width 0.09525)
		(layer "In6.Cu")
		(net "M_K_CPU1_SB_DQS_DN<4>")
	)
	(segment
		(start 159.03575 -271.358614)
		(end 159.460184 -271.783048)
		(width 0.16002)
		(layer "In6.Cu")
		(net "M_K_CPU1_SB_DQS_DN<4>")
	)
	(segment
		(start 161.225992 -274.186142)
		(end 161.30651 -274.105878)
		(width 0.16002)
		(layer "In6.Cu")
		(net "M_K_CPU1_SB_DQS_DN<4>")
	)
	(segment
		(start 186.588654 -277.658322)
		(end 187.652406 -277.658322)
		(width 0.16002)
		(layer "In6.Cu")
		(net "M_K_CPU1_SB_DQS_DN<4>")
	)
	(segment
		(start 178.194462 -276.808184)
		(end 179.0446 -277.658322)
		(width 0.16002)
		(layer "In6.Cu")
		(net "M_K_CPU1_SB_DQS_DN<4>")
	)
	(segment
		(start 160.753298 -273.939508)
		(end 160.999932 -274.186142)
		(width 0.16002)
		(layer "In6.Cu")
		(net "M_K_CPU1_SB_DQS_DN<4>")
	)
	(segment
		(start 185.738516 -276.808184)
		(end 186.588654 -277.658322)
		(width 0.16002)
		(layer "In6.Cu")
		(net "M_K_CPU1_SB_DQS_DN<4>")
	)
	(segment
		(start 159.379666 -272.565876)
		(end 159.6263 -272.81251)
		(width 0.16002)
		(layer "In6.Cu")
		(net "M_K_CPU1_SB_DQS_DN<4>")
	)
	(segment
		(start 166.004748 -277.278338)
		(end 166.792148 -276.490938)
		(width 0.16002)
		(layer "In6.Cu")
		(net "M_K_CPU1_SB_DQS_DN<4>")
	)
	(segment
		(start 144.223232 -271.981422)
		(end 144.242536 -271.970246)
		(width 0.09525)
		(layer "In6.Cu")
		(net "M_K_CPU1_SB_DQS_DN<4>")
	)
	(segment
		(start 180.108352 -277.658322)
		(end 180.488336 -277.278338)
		(width 0.16002)
		(layer "In6.Cu")
		(net "M_K_CPU1_SB_DQS_DN<4>")
	)
	(segment
		(start 159.6263 -272.81251)
		(end 159.85236 -272.81251)
		(width 0.16002)
		(layer "In6.Cu")
		(net "M_K_CPU1_SB_DQS_DN<4>")
	)
	(segment
		(start 141.214856 -271.656302)
		(end 141.36878 -271.921732)
		(width 0.09525)
		(layer "In6.Cu")
		(net "M_K_CPU1_SB_DQS_DN<4>")
	)
	(segment
		(start 173.548802 -277.278338)
		(end 174.336202 -276.490938)
		(width 0.16002)
		(layer "In6.Cu")
		(net "M_K_CPU1_SB_DQS_DN<4>")
	)
	(segment
		(start 175.395382 -276.490938)
		(end 175.712628 -276.808184)
		(width 0.16002)
		(layer "In6.Cu")
		(net "M_K_CPU1_SB_DQS_DN<4>")
	)
	(segment
		(start 166.792148 -276.490938)
		(end 167.851328 -276.490938)
		(width 0.16002)
		(layer "In6.Cu")
		(net "M_K_CPU1_SB_DQS_DN<4>")
	)
	(segment
		(start 145.240756 -271.921732)
		(end 145.240502 -271.921732)
		(width 0.09525)
		(layer "In6.Cu")
		(net "M_K_CPU1_SB_DQS_DN<4>")
	)
	(segment
		(start 164.092128 -277.278338)
		(end 166.004748 -277.278338)
		(width 0.16002)
		(layer "In6.Cu")
		(net "M_K_CPU1_SB_DQS_DN<4>")
	)
	(segment
		(start 162.680142 -275.47951)
		(end 163.156646 -275.47951)
		(width 0.16002)
		(layer "In6.Cu")
		(net "M_K_CPU1_SB_DQS_DN<4>")
	)
	(segment
		(start 163.156646 -275.47951)
		(end 163.58108 -275.903944)
		(width 0.16002)
		(layer "In6.Cu")
		(net "M_K_CPU1_SB_DQS_DN<4>")
	)
	(segment
		(start 160.833816 -273.63293)
		(end 160.753298 -273.713448)
		(width 0.16002)
		(layer "In6.Cu")
		(net "M_K_CPU1_SB_DQS_DN<4>")
	)
	(segment
		(start 189.42431 -276.490938)
		(end 190.48349 -276.490938)
		(width 0.16002)
		(layer "In6.Cu")
		(net "M_K_CPU1_SB_DQS_DN<4>")
	)
	(segment
		(start 172.564298 -277.658322)
		(end 172.944282 -277.278338)
		(width 0.16002)
		(layer "In6.Cu")
		(net "M_K_CPU1_SB_DQS_DN<4>")
	)
	(segment
		(start 160.409382 -272.732246)
		(end 160.833816 -273.15668)
		(width 0.16002)
		(layer "In6.Cu")
		(net "M_K_CPU1_SB_DQS_DN<4>")
	)
	(segment
		(start 159.379666 -272.339816)
		(end 159.379666 -272.565876)
		(width 0.16002)
		(layer "In6.Cu")
		(net "M_K_CPU1_SB_DQS_DN<4>")
	)
	(segment
		(start 162.373564 -275.559774)
		(end 162.599624 -275.559774)
		(width 0.16002)
		(layer "In6.Cu")
		(net "M_K_CPU1_SB_DQS_DN<4>")
	)
	(segment
		(start 159.460184 -271.783048)
		(end 159.460184 -272.259298)
		(width 0.16002)
		(layer "In6.Cu")
		(net "M_K_CPU1_SB_DQS_DN<4>")
	)
	(segment
		(start 188.63691 -277.278338)
		(end 189.42431 -276.490938)
		(width 0.16002)
		(layer "In6.Cu")
		(net "M_K_CPU1_SB_DQS_DN<4>")
	)
	(segment
		(start 145.658078 -271.145254)
		(end 146.599656 -270.203676)
		(width 0.09525)
		(layer "In6.Cu")
		(net "M_K_CPU1_SB_DQS_DN<4>")
	)
	(segment
		(start 190.48349 -276.490938)
		(end 190.800736 -276.808184)
		(width 0.16002)
		(layer "In6.Cu")
		(net "M_K_CPU1_SB_DQS_DN<4>")
	)
	(segment
		(start 146.599656 -270.203676)
		(end 147.836382 -270.203676)
		(width 0.09525)
		(layer "In6.Cu")
		(net "M_K_CPU1_SB_DQS_DN<4>")
	)
	(segment
		(start 188.03239 -277.278338)
		(end 188.63691 -277.278338)
		(width 0.16002)
		(layer "In6.Cu")
		(net "M_K_CPU1_SB_DQS_DN<4>")
	)
	(segment
		(start 160.753298 -273.713448)
		(end 160.753298 -273.939508)
		(width 0.16002)
		(layer "In6.Cu")
		(net "M_K_CPU1_SB_DQS_DN<4>")
	)
	(segment
		(start 147.895564 -270.144494)
		(end 147.919186 -270.144494)
		(width 0.09525)
		(layer "In6.Cu")
		(net "M_K_CPU1_SB_DQS_DN<4>")
	)
	(segment
		(start 162.599624 -275.559774)
		(end 162.680142 -275.47951)
		(width 0.16002)
		(layer "In6.Cu")
		(net "M_K_CPU1_SB_DQS_DN<4>")
	)
	(arc
		(start 142.343378 -271.981422)
		(mid 142.62481 -271.905667)
		(end 142.906242 -271.981422)
		(width 0.09525)
		(layer "In6.Cu")
		(net "M_K_CPU1_SB_DQS_DN<4>")
	)
	(arc
		(start 144.785588 -271.980914)
		(mid 144.97431 -272.03165)
		(end 145.163032 -271.980914)
		(width 0.09525)
		(layer "In6.Cu")
		(net "M_K_CPU1_SB_DQS_DN<4>")
	)
	(arc
		(start 145.508726 -271.505426)
		(mid 145.547609 -271.310508)
		(end 145.658078 -271.145254)
		(width 0.09525)
		(layer "In6.Cu")
		(net "M_K_CPU1_SB_DQS_DN<4>")
	)
	(arc
		(start 145.163032 -271.980914)
		(mid 145.203812 -271.953844)
		(end 145.240756 -271.921732)
		(width 0.09525)
		(layer "In6.Cu")
		(net "M_K_CPU1_SB_DQS_DN<4>")
	)
	(arc
		(start 141.48943 -271.940528)
		(mid 141.732394 -271.907541)
		(end 141.966188 -271.981422)
		(width 0.09525)
		(layer "In6.Cu")
		(net "M_K_CPU1_SB_DQS_DN<4>")
	)
	(arc
		(start 143.846042 -271.981422)
		(mid 144.029817 -272.032194)
		(end 144.21485 -271.986248)
		(width 0.09525)
		(layer "In6.Cu")
		(net "M_K_CPU1_SB_DQS_DN<4>")
	)
	(arc
		(start 141.97457 -271.986248)
		(mid 142.159602 -272.032162)
		(end 142.343378 -271.981422)
		(width 0.09525)
		(layer "In6.Cu")
		(net "M_K_CPU1_SB_DQS_DN<4>")
	)
	(arc
		(start 143.283178 -271.981422)
		(mid 143.56461 -271.905667)
		(end 143.846042 -271.981422)
		(width 0.09525)
		(layer "In6.Cu")
		(net "M_K_CPU1_SB_DQS_DN<4>")
	)
	(arc
		(start 145.404078 -271.75841)
		(mid 145.481551 -271.642325)
		(end 145.508726 -271.505426)
		(width 0.09525)
		(layer "In6.Cu")
		(net "M_K_CPU1_SB_DQS_DN<4>")
	)
	(arc
		(start 141.469618 -271.948402)
		(mid 141.479486 -271.944371)
		(end 141.48943 -271.940528)
		(width 0.09525)
		(layer "In6.Cu")
		(net "M_K_CPU1_SB_DQS_DN<4>")
	)
	(arc
		(start 142.906242 -271.981422)
		(mid 143.09471 -272.032099)
		(end 143.283178 -271.981422)
		(width 0.09525)
		(layer "In6.Cu")
		(net "M_K_CPU1_SB_DQS_DN<4>")
	)
	(arc
		(start 144.242536 -271.970246)
		(mid 144.515438 -271.905475)
		(end 144.785588 -271.980914)
		(width 0.09525)
		(layer "In6.Cu")
		(net "M_K_CPU1_SB_DQS_DN<4>")
	)
	(segment
		(start 142.627858 -290.830254)
		(end 143.09471 -291.096192)
		(width 0.12954)
		(layer "F.Cu")
		(net "M_K_CPU1_SB_DQS_DN<3>")
	)
	(segment
		(start 146.211036 -292.106096)
		(end 146.211036 -292.977824)
		(width 0.09525)
		(layer "In6.Cu")
		(net "M_K_CPU1_SB_DQS_DN<3>")
	)
	(segment
		(start 169.47007 -312.512456)
		(end 170.319954 -313.36234)
		(width 0.16002)
		(layer "In6.Cu")
		(net "M_K_CPU1_SB_DQS_DN<3>")
	)
	(segment
		(start 175.301402 -312.512456)
		(end 177.014124 -312.512456)
		(width 0.16002)
		(layer "In6.Cu")
		(net "M_K_CPU1_SB_DQS_DN<3>")
	)
	(segment
		(start 197.152768 -313.613546)
		(end 197.682612 -313.613546)
		(width 0.16002)
		(layer "In6.Cu")
		(net "M_K_CPU1_SB_DQS_DN<3>")
	)
	(segment
		(start 184.558178 -312.512456)
		(end 185.408062 -313.36234)
		(width 0.16002)
		(layer "In6.Cu")
		(net "M_K_CPU1_SB_DQS_DN<3>")
	)
	(segment
		(start 197.05066 -313.511438)
		(end 197.152768 -313.613546)
		(width 0.16002)
		(layer "In6.Cu")
		(net "M_K_CPU1_SB_DQS_DN<3>")
	)
	(segment
		(start 182.505858 -312.852054)
		(end 182.845456 -312.512456)
		(width 0.16002)
		(layer "In6.Cu")
		(net "M_K_CPU1_SB_DQS_DN<3>")
	)
	(segment
		(start 185.408062 -313.36234)
		(end 187.818014 -313.36234)
		(width 0.16002)
		(layer "In6.Cu")
		(net "M_K_CPU1_SB_DQS_DN<3>")
	)
	(segment
		(start 145.240502 -290.83)
		(end 145.357596 -290.947094)
		(width 0.09525)
		(layer "In6.Cu")
		(net "M_K_CPU1_SB_DQS_DN<3>")
	)
	(segment
		(start 182.117238 -312.852054)
		(end 182.505858 -312.852054)
		(width 0.16002)
		(layer "In6.Cu")
		(net "M_K_CPU1_SB_DQS_DN<3>")
	)
	(segment
		(start 167.757348 -312.512456)
		(end 169.47007 -312.512456)
		(width 0.16002)
		(layer "In6.Cu")
		(net "M_K_CPU1_SB_DQS_DN<3>")
	)
	(segment
		(start 143.09471 -291.096192)
		(end 142.940786 -290.830762)
		(width 0.09525)
		(layer "In6.Cu")
		(net "M_K_CPU1_SB_DQS_DN<3>")
	)
	(segment
		(start 197.78472 -313.511438)
		(end 198.430388 -313.511438)
		(width 0.16002)
		(layer "In6.Cu")
		(net "M_K_CPU1_SB_DQS_DN<3>")
	)
	(segment
		(start 192.87109 -313.086496)
		(end 195.081906 -313.086496)
		(width 0.16002)
		(layer "In6.Cu")
		(net "M_K_CPU1_SB_DQS_DN<3>")
	)
	(segment
		(start 166.17823 -313.702954)
		(end 167.02913 -312.852054)
		(width 0.16002)
		(layer "In6.Cu")
		(net "M_K_CPU1_SB_DQS_DN<3>")
	)
	(segment
		(start 198.430388 -313.511438)
		(end 198.7042 -313.78525)
		(width 0.16002)
		(layer "In6.Cu")
		(net "M_K_CPU1_SB_DQS_DN<3>")
	)
	(segment
		(start 181.266338 -313.702954)
		(end 182.117238 -312.852054)
		(width 0.16002)
		(layer "In6.Cu")
		(net "M_K_CPU1_SB_DQS_DN<3>")
	)
	(segment
		(start 174.961804 -312.852054)
		(end 175.301402 -312.512456)
		(width 0.16002)
		(layer "In6.Cu")
		(net "M_K_CPU1_SB_DQS_DN<3>")
	)
	(segment
		(start 148.48205 -295.330118)
		(end 148.48205 -299.521626)
		(width 0.16002)
		(layer "In6.Cu")
		(net "M_K_CPU1_SB_DQS_DN<3>")
	)
	(segment
		(start 177.014124 -312.512456)
		(end 177.864008 -313.36234)
		(width 0.16002)
		(layer "In6.Cu")
		(net "M_K_CPU1_SB_DQS_DN<3>")
	)
	(segment
		(start 144.785842 -290.771072)
		(end 144.794224 -290.766246)
		(width 0.09525)
		(layer "In6.Cu")
		(net "M_K_CPU1_SB_DQS_DN<3>")
	)
	(segment
		(start 142.940786 -290.830762)
		(end 142.9639 -290.744148)
		(width 0.09525)
		(layer "In6.Cu")
		(net "M_K_CPU1_SB_DQS_DN<3>")
	)
	(segment
		(start 144.21485 -290.766246)
		(end 144.223232 -290.771072)
		(width 0.09525)
		(layer "In6.Cu")
		(net "M_K_CPU1_SB_DQS_DN<3>")
	)
	(segment
		(start 145.59661 -291.491924)
		(end 146.211036 -292.106096)
		(width 0.09525)
		(layer "In6.Cu")
		(net "M_K_CPU1_SB_DQS_DN<3>")
	)
	(segment
		(start 187.818014 -313.36234)
		(end 188.158628 -313.702954)
		(width 0.16002)
		(layer "In6.Cu")
		(net "M_K_CPU1_SB_DQS_DN<3>")
	)
	(segment
		(start 144.775428 -290.777168)
		(end 144.785842 -290.771072)
		(width 0.09525)
		(layer "In6.Cu")
		(net "M_K_CPU1_SB_DQS_DN<3>")
	)
	(segment
		(start 195.081906 -313.086496)
		(end 195.705984 -313.710574)
		(width 0.16002)
		(layer "In6.Cu")
		(net "M_K_CPU1_SB_DQS_DN<3>")
	)
	(segment
		(start 146.889978 -293.65575)
		(end 146.890232 -293.739062)
		(width 0.09525)
		(layer "In6.Cu")
		(net "M_K_CPU1_SB_DQS_DN<3>")
	)
	(segment
		(start 180.614574 -313.702954)
		(end 181.266338 -313.702954)
		(width 0.16002)
		(layer "In6.Cu")
		(net "M_K_CPU1_SB_DQS_DN<3>")
	)
	(segment
		(start 182.845456 -312.512456)
		(end 184.558178 -312.512456)
		(width 0.16002)
		(layer "In6.Cu")
		(net "M_K_CPU1_SB_DQS_DN<3>")
	)
	(segment
		(start 177.864008 -313.36234)
		(end 180.27396 -313.36234)
		(width 0.16002)
		(layer "In6.Cu")
		(net "M_K_CPU1_SB_DQS_DN<3>")
	)
	(segment
		(start 173.07052 -313.702954)
		(end 173.722284 -313.702954)
		(width 0.16002)
		(layer "In6.Cu")
		(net "M_K_CPU1_SB_DQS_DN<3>")
	)
	(segment
		(start 195.705984 -313.710574)
		(end 196.335904 -313.710574)
		(width 0.16002)
		(layer "In6.Cu")
		(net "M_K_CPU1_SB_DQS_DN<3>")
	)
	(segment
		(start 197.682612 -313.613546)
		(end 197.78472 -313.511438)
		(width 0.16002)
		(layer "In6.Cu")
		(net "M_K_CPU1_SB_DQS_DN<3>")
	)
	(segment
		(start 188.158628 -313.702954)
		(end 188.810392 -313.702954)
		(width 0.16002)
		(layer "In6.Cu")
		(net "M_K_CPU1_SB_DQS_DN<3>")
	)
	(segment
		(start 146.889724 -293.655242)
		(end 146.889978 -293.65575)
		(width 0.09525)
		(layer "In6.Cu")
		(net "M_K_CPU1_SB_DQS_DN<3>")
	)
	(segment
		(start 145.357596 -290.947094)
		(end 145.59661 -291.491924)
		(width 0.09525)
		(layer "In6.Cu")
		(net "M_K_CPU1_SB_DQS_DN<3>")
	)
	(segment
		(start 174.573184 -312.852054)
		(end 174.961804 -312.852054)
		(width 0.16002)
		(layer "In6.Cu")
		(net "M_K_CPU1_SB_DQS_DN<3>")
	)
	(segment
		(start 148.48205 -299.521626)
		(end 162.663378 -313.702954)
		(width 0.16002)
		(layer "In6.Cu")
		(net "M_K_CPU1_SB_DQS_DN<3>")
	)
	(segment
		(start 162.663378 -313.702954)
		(end 166.17823 -313.702954)
		(width 0.16002)
		(layer "In6.Cu")
		(net "M_K_CPU1_SB_DQS_DN<3>")
	)
	(segment
		(start 180.27396 -313.36234)
		(end 180.614574 -313.702954)
		(width 0.16002)
		(layer "In6.Cu")
		(net "M_K_CPU1_SB_DQS_DN<3>")
	)
	(segment
		(start 190.049912 -312.852054)
		(end 190.38951 -312.512456)
		(width 0.16002)
		(layer "In6.Cu")
		(net "M_K_CPU1_SB_DQS_DN<3>")
	)
	(segment
		(start 172.729906 -313.36234)
		(end 173.07052 -313.702954)
		(width 0.16002)
		(layer "In6.Cu")
		(net "M_K_CPU1_SB_DQS_DN<3>")
	)
	(segment
		(start 196.53504 -313.511438)
		(end 197.05066 -313.511438)
		(width 0.16002)
		(layer "In6.Cu")
		(net "M_K_CPU1_SB_DQS_DN<3>")
	)
	(segment
		(start 167.02913 -312.852054)
		(end 167.41775 -312.852054)
		(width 0.16002)
		(layer "In6.Cu")
		(net "M_K_CPU1_SB_DQS_DN<3>")
	)
	(segment
		(start 146.890232 -293.739062)
		(end 146.906996 -293.755826)
		(width 0.09525)
		(layer "In6.Cu")
		(net "M_K_CPU1_SB_DQS_DN<3>")
	)
	(segment
		(start 146.211036 -292.977824)
		(end 146.889724 -293.655242)
		(width 0.09525)
		(layer "In6.Cu")
		(net "M_K_CPU1_SB_DQS_DN<3>")
	)
	(segment
		(start 170.319954 -313.36234)
		(end 172.729906 -313.36234)
		(width 0.16002)
		(layer "In6.Cu")
		(net "M_K_CPU1_SB_DQS_DN<3>")
	)
	(segment
		(start 146.906996 -293.755826)
		(end 148.48205 -295.330118)
		(width 0.16002)
		(layer "In6.Cu")
		(net "M_K_CPU1_SB_DQS_DN<3>")
	)
	(segment
		(start 196.335904 -313.710574)
		(end 196.53504 -313.511438)
		(width 0.16002)
		(layer "In6.Cu")
		(net "M_K_CPU1_SB_DQS_DN<3>")
	)
	(segment
		(start 167.41775 -312.852054)
		(end 167.757348 -312.512456)
		(width 0.16002)
		(layer "In6.Cu")
		(net "M_K_CPU1_SB_DQS_DN<3>")
	)
	(segment
		(start 188.810392 -313.702954)
		(end 189.661292 -312.852054)
		(width 0.16002)
		(layer "In6.Cu")
		(net "M_K_CPU1_SB_DQS_DN<3>")
	)
	(segment
		(start 192.29705 -312.512456)
		(end 192.87109 -313.086496)
		(width 0.16002)
		(layer "In6.Cu")
		(net "M_K_CPU1_SB_DQS_DN<3>")
	)
	(segment
		(start 190.38951 -312.512456)
		(end 192.29705 -312.512456)
		(width 0.16002)
		(layer "In6.Cu")
		(net "M_K_CPU1_SB_DQS_DN<3>")
	)
	(segment
		(start 173.722284 -313.702954)
		(end 174.573184 -312.852054)
		(width 0.16002)
		(layer "In6.Cu")
		(net "M_K_CPU1_SB_DQS_DN<3>")
	)
	(segment
		(start 189.661292 -312.852054)
		(end 190.049912 -312.852054)
		(width 0.16002)
		(layer "In6.Cu")
		(net "M_K_CPU1_SB_DQS_DN<3>")
	)
	(arc
		(start 144.794224 -290.766246)
		(mid 144.979256 -290.720332)
		(end 145.163032 -290.771072)
		(width 0.09525)
		(layer "In6.Cu")
		(net "M_K_CPU1_SB_DQS_DN<3>")
	)
	(arc
		(start 143.846042 -290.771072)
		(mid 144.029817 -290.7203)
		(end 144.21485 -290.766246)
		(width 0.09525)
		(layer "In6.Cu")
		(net "M_K_CPU1_SB_DQS_DN<3>")
	)
	(arc
		(start 144.223232 -290.771072)
		(mid 144.498521 -290.846793)
		(end 144.775428 -290.777168)
		(width 0.09525)
		(layer "In6.Cu")
		(net "M_K_CPU1_SB_DQS_DN<3>")
	)
	(arc
		(start 145.163032 -290.771072)
		(mid 145.203675 -290.798026)
		(end 145.240502 -290.83)
		(width 0.09525)
		(layer "In6.Cu")
		(net "M_K_CPU1_SB_DQS_DN<3>")
	)
	(arc
		(start 143.283178 -290.771072)
		(mid 143.56461 -290.846827)
		(end 143.846042 -290.771072)
		(width 0.09525)
		(layer "In6.Cu")
		(net "M_K_CPU1_SB_DQS_DN<3>")
	)
	(arc
		(start 142.9639 -290.744148)
		(mid 143.126551 -290.721888)
		(end 143.283178 -290.771072)
		(width 0.09525)
		(layer "In6.Cu")
		(net "M_K_CPU1_SB_DQS_DN<3>")
	)
	(segment
		(start 142.627858 -285.970472)
		(end 143.09471 -286.23641)
		(width 0.12954)
		(layer "F.Cu")
		(net "M_K_CPU1_SB_DQS_DN<2>")
	)
	(segment
		(start 196.53504 -304.161444)
		(end 197.17766 -304.161444)
		(width 0.16002)
		(layer "In6.Cu")
		(net "M_K_CPU1_SB_DQS_DN<2>")
	)
	(segment
		(start 156.93517 -298.915074)
		(end 158.07563 -298.915074)
		(width 0.16002)
		(layer "In6.Cu")
		(net "M_K_CPU1_SB_DQS_DN<2>")
	)
	(segment
		(start 177.014124 -303.162462)
		(end 177.864008 -304.012346)
		(width 0.16002)
		(layer "In6.Cu")
		(net "M_K_CPU1_SB_DQS_DN<2>")
	)
	(segment
		(start 175.301402 -303.162462)
		(end 177.014124 -303.162462)
		(width 0.16002)
		(layer "In6.Cu")
		(net "M_K_CPU1_SB_DQS_DN<2>")
	)
	(segment
		(start 172.729906 -304.012346)
		(end 173.07052 -304.35296)
		(width 0.16002)
		(layer "In6.Cu")
		(net "M_K_CPU1_SB_DQS_DN<2>")
	)
	(segment
		(start 196.335904 -304.36058)
		(end 196.53504 -304.161444)
		(width 0.16002)
		(layer "In6.Cu")
		(net "M_K_CPU1_SB_DQS_DN<2>")
	)
	(segment
		(start 147.895564 -286.919924)
		(end 147.919186 -286.919924)
		(width 0.09525)
		(layer "In6.Cu")
		(net "M_K_CPU1_SB_DQS_DN<2>")
	)
	(segment
		(start 169.47007 -303.162462)
		(end 170.319954 -304.012346)
		(width 0.16002)
		(layer "In6.Cu")
		(net "M_K_CPU1_SB_DQS_DN<2>")
	)
	(segment
		(start 197.91172 -304.161444)
		(end 198.430388 -304.161444)
		(width 0.16002)
		(layer "In6.Cu")
		(net "M_K_CPU1_SB_DQS_DN<2>")
	)
	(segment
		(start 197.78472 -304.288444)
		(end 197.91172 -304.161444)
		(width 0.16002)
		(layer "In6.Cu")
		(net "M_K_CPU1_SB_DQS_DN<2>")
	)
	(segment
		(start 154.366722 -293.141146)
		(end 154.366722 -296.346626)
		(width 0.16002)
		(layer "In6.Cu")
		(net "M_K_CPU1_SB_DQS_DN<2>")
	)
	(segment
		(start 148.1455 -286.919924)
		(end 154.366722 -293.141146)
		(width 0.16002)
		(layer "In6.Cu")
		(net "M_K_CPU1_SB_DQS_DN<2>")
	)
	(segment
		(start 166.17823 -304.35296)
		(end 167.02913 -303.50206)
		(width 0.16002)
		(layer "In6.Cu")
		(net "M_K_CPU1_SB_DQS_DN<2>")
	)
	(segment
		(start 147.531836 -286.860996)
		(end 147.836636 -286.860996)
		(width 0.09525)
		(layer "In6.Cu")
		(net "M_K_CPU1_SB_DQS_DN<2>")
	)
	(segment
		(start 192.87109 -303.736502)
		(end 195.081906 -303.736502)
		(width 0.16002)
		(layer "In6.Cu")
		(net "M_K_CPU1_SB_DQS_DN<2>")
	)
	(segment
		(start 182.505858 -303.50206)
		(end 182.845456 -303.162462)
		(width 0.16002)
		(layer "In6.Cu")
		(net "M_K_CPU1_SB_DQS_DN<2>")
	)
	(segment
		(start 167.757348 -303.162462)
		(end 169.47007 -303.162462)
		(width 0.16002)
		(layer "In6.Cu")
		(net "M_K_CPU1_SB_DQS_DN<2>")
	)
	(segment
		(start 173.07052 -304.35296)
		(end 173.722284 -304.35296)
		(width 0.16002)
		(layer "In6.Cu")
		(net "M_K_CPU1_SB_DQS_DN<2>")
	)
	(segment
		(start 180.27396 -304.012346)
		(end 180.614574 -304.35296)
		(width 0.16002)
		(layer "In6.Cu")
		(net "M_K_CPU1_SB_DQS_DN<2>")
	)
	(segment
		(start 145.833846 -285.987236)
		(end 146.556476 -286.709866)
		(width 0.09525)
		(layer "In6.Cu")
		(net "M_K_CPU1_SB_DQS_DN<2>")
	)
	(segment
		(start 173.722284 -304.35296)
		(end 174.573184 -303.50206)
		(width 0.16002)
		(layer "In6.Cu")
		(net "M_K_CPU1_SB_DQS_DN<2>")
	)
	(segment
		(start 158.07563 -298.915074)
		(end 163.513516 -304.35296)
		(width 0.16002)
		(layer "In6.Cu")
		(net "M_K_CPU1_SB_DQS_DN<2>")
	)
	(segment
		(start 144.775428 -285.917386)
		(end 144.785842 -285.91129)
		(width 0.09525)
		(layer "In6.Cu")
		(net "M_K_CPU1_SB_DQS_DN<2>")
	)
	(segment
		(start 147.380706 -286.709866)
		(end 147.531836 -286.860996)
		(width 0.09525)
		(layer "In6.Cu")
		(net "M_K_CPU1_SB_DQS_DN<2>")
	)
	(segment
		(start 195.705984 -304.36058)
		(end 196.335904 -304.36058)
		(width 0.16002)
		(layer "In6.Cu")
		(net "M_K_CPU1_SB_DQS_DN<2>")
	)
	(segment
		(start 147.919186 -286.919924)
		(end 148.1455 -286.919924)
		(width 0.16002)
		(layer "In6.Cu")
		(net "M_K_CPU1_SB_DQS_DN<2>")
	)
	(segment
		(start 197.30466 -304.288444)
		(end 197.78472 -304.288444)
		(width 0.16002)
		(layer "In6.Cu")
		(net "M_K_CPU1_SB_DQS_DN<2>")
	)
	(segment
		(start 195.081906 -303.736502)
		(end 195.705984 -304.36058)
		(width 0.16002)
		(layer "In6.Cu")
		(net "M_K_CPU1_SB_DQS_DN<2>")
	)
	(segment
		(start 167.41775 -303.50206)
		(end 167.757348 -303.162462)
		(width 0.16002)
		(layer "In6.Cu")
		(net "M_K_CPU1_SB_DQS_DN<2>")
	)
	(segment
		(start 181.266338 -304.35296)
		(end 182.117238 -303.50206)
		(width 0.16002)
		(layer "In6.Cu")
		(net "M_K_CPU1_SB_DQS_DN<2>")
	)
	(segment
		(start 197.17766 -304.161444)
		(end 197.30466 -304.288444)
		(width 0.16002)
		(layer "In6.Cu")
		(net "M_K_CPU1_SB_DQS_DN<2>")
	)
	(segment
		(start 142.940786 -285.97098)
		(end 142.9639 -285.884366)
		(width 0.09525)
		(layer "In6.Cu")
		(net "M_K_CPU1_SB_DQS_DN<2>")
	)
	(segment
		(start 188.810392 -304.35296)
		(end 189.661292 -303.50206)
		(width 0.16002)
		(layer "In6.Cu")
		(net "M_K_CPU1_SB_DQS_DN<2>")
	)
	(segment
		(start 188.158628 -304.35296)
		(end 188.810392 -304.35296)
		(width 0.16002)
		(layer "In6.Cu")
		(net "M_K_CPU1_SB_DQS_DN<2>")
	)
	(segment
		(start 147.836636 -286.860996)
		(end 147.895564 -286.919924)
		(width 0.09525)
		(layer "In6.Cu")
		(net "M_K_CPU1_SB_DQS_DN<2>")
	)
	(segment
		(start 177.864008 -304.012346)
		(end 180.27396 -304.012346)
		(width 0.16002)
		(layer "In6.Cu")
		(net "M_K_CPU1_SB_DQS_DN<2>")
	)
	(segment
		(start 174.961804 -303.50206)
		(end 175.301402 -303.162462)
		(width 0.16002)
		(layer "In6.Cu")
		(net "M_K_CPU1_SB_DQS_DN<2>")
	)
	(segment
		(start 189.661292 -303.50206)
		(end 190.049912 -303.50206)
		(width 0.16002)
		(layer "In6.Cu")
		(net "M_K_CPU1_SB_DQS_DN<2>")
	)
	(segment
		(start 170.319954 -304.012346)
		(end 172.729906 -304.012346)
		(width 0.16002)
		(layer "In6.Cu")
		(net "M_K_CPU1_SB_DQS_DN<2>")
	)
	(segment
		(start 144.21485 -285.906464)
		(end 144.223232 -285.91129)
		(width 0.09525)
		(layer "In6.Cu")
		(net "M_K_CPU1_SB_DQS_DN<2>")
	)
	(segment
		(start 180.614574 -304.35296)
		(end 181.266338 -304.35296)
		(width 0.16002)
		(layer "In6.Cu")
		(net "M_K_CPU1_SB_DQS_DN<2>")
	)
	(segment
		(start 187.818014 -304.012346)
		(end 188.158628 -304.35296)
		(width 0.16002)
		(layer "In6.Cu")
		(net "M_K_CPU1_SB_DQS_DN<2>")
	)
	(segment
		(start 182.845456 -303.162462)
		(end 184.558178 -303.162462)
		(width 0.16002)
		(layer "In6.Cu")
		(net "M_K_CPU1_SB_DQS_DN<2>")
	)
	(segment
		(start 167.02913 -303.50206)
		(end 167.41775 -303.50206)
		(width 0.16002)
		(layer "In6.Cu")
		(net "M_K_CPU1_SB_DQS_DN<2>")
	)
	(segment
		(start 143.09471 -286.23641)
		(end 142.940786 -285.97098)
		(width 0.09525)
		(layer "In6.Cu")
		(net "M_K_CPU1_SB_DQS_DN<2>")
	)
	(segment
		(start 192.29705 -303.162462)
		(end 192.87109 -303.736502)
		(width 0.16002)
		(layer "In6.Cu")
		(net "M_K_CPU1_SB_DQS_DN<2>")
	)
	(segment
		(start 163.513516 -304.35296)
		(end 166.17823 -304.35296)
		(width 0.16002)
		(layer "In6.Cu")
		(net "M_K_CPU1_SB_DQS_DN<2>")
	)
	(segment
		(start 182.117238 -303.50206)
		(end 182.505858 -303.50206)
		(width 0.16002)
		(layer "In6.Cu")
		(net "M_K_CPU1_SB_DQS_DN<2>")
	)
	(segment
		(start 144.785842 -285.91129)
		(end 144.794224 -285.906464)
		(width 0.09525)
		(layer "In6.Cu")
		(net "M_K_CPU1_SB_DQS_DN<2>")
	)
	(segment
		(start 190.049912 -303.50206)
		(end 190.38951 -303.162462)
		(width 0.16002)
		(layer "In6.Cu")
		(net "M_K_CPU1_SB_DQS_DN<2>")
	)
	(segment
		(start 185.408062 -304.012346)
		(end 187.818014 -304.012346)
		(width 0.16002)
		(layer "In6.Cu")
		(net "M_K_CPU1_SB_DQS_DN<2>")
	)
	(segment
		(start 154.366722 -296.346626)
		(end 156.93517 -298.915074)
		(width 0.16002)
		(layer "In6.Cu")
		(net "M_K_CPU1_SB_DQS_DN<2>")
	)
	(segment
		(start 174.573184 -303.50206)
		(end 174.961804 -303.50206)
		(width 0.16002)
		(layer "In6.Cu")
		(net "M_K_CPU1_SB_DQS_DN<2>")
	)
	(segment
		(start 184.558178 -303.162462)
		(end 185.408062 -304.012346)
		(width 0.16002)
		(layer "In6.Cu")
		(net "M_K_CPU1_SB_DQS_DN<2>")
	)
	(segment
		(start 190.38951 -303.162462)
		(end 192.29705 -303.162462)
		(width 0.16002)
		(layer "In6.Cu")
		(net "M_K_CPU1_SB_DQS_DN<2>")
	)
	(segment
		(start 146.556476 -286.709866)
		(end 147.380706 -286.709866)
		(width 0.09525)
		(layer "In6.Cu")
		(net "M_K_CPU1_SB_DQS_DN<2>")
	)
	(segment
		(start 198.430388 -304.161444)
		(end 198.7042 -304.435256)
		(width 0.16002)
		(layer "In6.Cu")
		(net "M_K_CPU1_SB_DQS_DN<2>")
	)
	(segment
		(start 145.444718 -285.987236)
		(end 145.833846 -285.987236)
		(width 0.09525)
		(layer "In6.Cu")
		(net "M_K_CPU1_SB_DQS_DN<2>")
	)
	(arc
		(start 143.846042 -285.91129)
		(mid 144.029817 -285.860518)
		(end 144.21485 -285.906464)
		(width 0.09525)
		(layer "In6.Cu")
		(net "M_K_CPU1_SB_DQS_DN<2>")
	)
	(arc
		(start 142.9639 -285.884366)
		(mid 143.126551 -285.862106)
		(end 143.283178 -285.91129)
		(width 0.09525)
		(layer "In6.Cu")
		(net "M_K_CPU1_SB_DQS_DN<2>")
	)
	(arc
		(start 144.223232 -285.91129)
		(mid 144.498521 -285.987011)
		(end 144.775428 -285.917386)
		(width 0.09525)
		(layer "In6.Cu")
		(net "M_K_CPU1_SB_DQS_DN<2>")
	)
	(arc
		(start 143.283178 -285.91129)
		(mid 143.56461 -285.987045)
		(end 143.846042 -285.91129)
		(width 0.09525)
		(layer "In6.Cu")
		(net "M_K_CPU1_SB_DQS_DN<2>")
	)
	(arc
		(start 145.163032 -285.91129)
		(mid 145.298854 -285.96787)
		(end 145.444718 -285.987236)
		(width 0.09525)
		(layer "In6.Cu")
		(net "M_K_CPU1_SB_DQS_DN<2>")
	)
	(arc
		(start 144.794224 -285.906464)
		(mid 144.979256 -285.86055)
		(end 145.163032 -285.91129)
		(width 0.09525)
		(layer "In6.Cu")
		(net "M_K_CPU1_SB_DQS_DN<2>")
	)
	(segment
		(start 142.627858 -281.110436)
		(end 143.09471 -281.376374)
		(width 0.12954)
		(layer "F.Cu")
		(net "M_K_CPU1_SB_DQS_DN<1>")
	)
	(segment
		(start 177.864008 -294.662352)
		(end 180.27396 -294.662352)
		(width 0.16002)
		(layer "In6.Cu")
		(net "M_K_CPU1_SB_DQS_DN<1>")
	)
	(segment
		(start 180.614574 -295.002966)
		(end 181.266338 -295.002966)
		(width 0.16002)
		(layer "In6.Cu")
		(net "M_K_CPU1_SB_DQS_DN<1>")
	)
	(segment
		(start 192.87109 -294.386508)
		(end 195.081906 -294.386508)
		(width 0.16002)
		(layer "In6.Cu")
		(net "M_K_CPU1_SB_DQS_DN<1>")
	)
	(segment
		(start 167.02913 -294.152066)
		(end 170.073828 -294.152066)
		(width 0.16002)
		(layer "In6.Cu")
		(net "M_K_CPU1_SB_DQS_DN<1>")
	)
	(segment
		(start 182.117238 -294.152066)
		(end 182.505858 -294.152066)
		(width 0.16002)
		(layer "In6.Cu")
		(net "M_K_CPU1_SB_DQS_DN<1>")
	)
	(segment
		(start 180.27396 -294.662352)
		(end 180.614574 -295.002966)
		(width 0.16002)
		(layer "In6.Cu")
		(net "M_K_CPU1_SB_DQS_DN<1>")
	)
	(segment
		(start 196.335904 -295.010586)
		(end 196.53504 -294.81145)
		(width 0.16002)
		(layer "In6.Cu")
		(net "M_K_CPU1_SB_DQS_DN<1>")
	)
	(segment
		(start 195.081906 -294.386508)
		(end 195.705984 -295.010586)
		(width 0.16002)
		(layer "In6.Cu")
		(net "M_K_CPU1_SB_DQS_DN<1>")
	)
	(segment
		(start 172.729906 -294.662352)
		(end 173.07052 -295.002966)
		(width 0.16002)
		(layer "In6.Cu")
		(net "M_K_CPU1_SB_DQS_DN<1>")
	)
	(segment
		(start 187.818014 -294.662352)
		(end 188.158628 -295.002966)
		(width 0.16002)
		(layer "In6.Cu")
		(net "M_K_CPU1_SB_DQS_DN<1>")
	)
	(segment
		(start 170.073828 -294.152066)
		(end 170.584114 -294.662352)
		(width 0.16002)
		(layer "In6.Cu")
		(net "M_K_CPU1_SB_DQS_DN<1>")
	)
	(segment
		(start 197.25132 -294.93845)
		(end 197.73138 -294.93845)
		(width 0.16002)
		(layer "In6.Cu")
		(net "M_K_CPU1_SB_DQS_DN<1>")
	)
	(segment
		(start 188.158628 -295.002966)
		(end 188.810392 -295.002966)
		(width 0.16002)
		(layer "In6.Cu")
		(net "M_K_CPU1_SB_DQS_DN<1>")
	)
	(segment
		(start 175.301402 -293.812468)
		(end 177.014124 -293.812468)
		(width 0.16002)
		(layer "In6.Cu")
		(net "M_K_CPU1_SB_DQS_DN<1>")
	)
	(segment
		(start 144.775428 -281.05735)
		(end 144.785842 -281.051254)
		(width 0.09525)
		(layer "In6.Cu")
		(net "M_K_CPU1_SB_DQS_DN<1>")
	)
	(segment
		(start 146.101054 -280.74112)
		(end 147.273772 -280.74112)
		(width 0.09525)
		(layer "In6.Cu")
		(net "M_K_CPU1_SB_DQS_DN<1>")
	)
	(segment
		(start 196.53504 -294.81145)
		(end 197.12432 -294.81145)
		(width 0.16002)
		(layer "In6.Cu")
		(net "M_K_CPU1_SB_DQS_DN<1>")
	)
	(segment
		(start 144.785842 -281.051254)
		(end 144.794224 -281.046428)
		(width 0.09525)
		(layer "In6.Cu")
		(net "M_K_CPU1_SB_DQS_DN<1>")
	)
	(segment
		(start 150.66645 -281.243786)
		(end 164.42563 -295.002966)
		(width 0.16002)
		(layer "In6.Cu")
		(net "M_K_CPU1_SB_DQS_DN<1>")
	)
	(segment
		(start 143.09471 -281.376374)
		(end 142.940786 -281.110944)
		(width 0.09525)
		(layer "In6.Cu")
		(net "M_K_CPU1_SB_DQS_DN<1>")
	)
	(segment
		(start 195.705984 -295.010586)
		(end 196.335904 -295.010586)
		(width 0.16002)
		(layer "In6.Cu")
		(net "M_K_CPU1_SB_DQS_DN<1>")
	)
	(segment
		(start 147.488656 -281.038808)
		(end 147.693126 -281.243786)
		(width 0.16002)
		(layer "In6.Cu")
		(net "M_K_CPU1_SB_DQS_DN<1>")
	)
	(segment
		(start 164.42563 -295.002966)
		(end 166.17823 -295.002966)
		(width 0.16002)
		(layer "In6.Cu")
		(net "M_K_CPU1_SB_DQS_DN<1>")
	)
	(segment
		(start 166.17823 -295.002966)
		(end 167.02913 -294.152066)
		(width 0.16002)
		(layer "In6.Cu")
		(net "M_K_CPU1_SB_DQS_DN<1>")
	)
	(segment
		(start 170.584114 -294.662352)
		(end 172.729906 -294.662352)
		(width 0.16002)
		(layer "In6.Cu")
		(net "M_K_CPU1_SB_DQS_DN<1>")
	)
	(segment
		(start 182.505858 -294.152066)
		(end 182.845456 -293.812468)
		(width 0.16002)
		(layer "In6.Cu")
		(net "M_K_CPU1_SB_DQS_DN<1>")
	)
	(segment
		(start 144.21485 -281.046428)
		(end 144.223232 -281.051254)
		(width 0.09525)
		(layer "In6.Cu")
		(net "M_K_CPU1_SB_DQS_DN<1>")
	)
	(segment
		(start 174.961804 -294.152066)
		(end 175.301402 -293.812468)
		(width 0.16002)
		(layer "In6.Cu")
		(net "M_K_CPU1_SB_DQS_DN<1>")
	)
	(segment
		(start 185.408062 -294.662352)
		(end 187.818014 -294.662352)
		(width 0.16002)
		(layer "In6.Cu")
		(net "M_K_CPU1_SB_DQS_DN<1>")
	)
	(segment
		(start 188.810392 -295.002966)
		(end 189.661292 -294.152066)
		(width 0.16002)
		(layer "In6.Cu")
		(net "M_K_CPU1_SB_DQS_DN<1>")
	)
	(segment
		(start 147.693126 -281.243786)
		(end 150.66645 -281.243786)
		(width 0.16002)
		(layer "In6.Cu")
		(net "M_K_CPU1_SB_DQS_DN<1>")
	)
	(segment
		(start 198.430388 -294.81145)
		(end 198.7042 -295.085262)
		(width 0.16002)
		(layer "In6.Cu")
		(net "M_K_CPU1_SB_DQS_DN<1>")
	)
	(segment
		(start 173.722284 -295.002966)
		(end 174.573184 -294.152066)
		(width 0.16002)
		(layer "In6.Cu")
		(net "M_K_CPU1_SB_DQS_DN<1>")
	)
	(segment
		(start 190.049912 -294.152066)
		(end 190.38951 -293.812468)
		(width 0.16002)
		(layer "In6.Cu")
		(net "M_K_CPU1_SB_DQS_DN<1>")
	)
	(segment
		(start 184.558178 -293.812468)
		(end 185.408062 -294.662352)
		(width 0.16002)
		(layer "In6.Cu")
		(net "M_K_CPU1_SB_DQS_DN<1>")
	)
	(segment
		(start 190.38951 -293.812468)
		(end 192.29705 -293.812468)
		(width 0.16002)
		(layer "In6.Cu")
		(net "M_K_CPU1_SB_DQS_DN<1>")
	)
	(segment
		(start 173.07052 -295.002966)
		(end 173.722284 -295.002966)
		(width 0.16002)
		(layer "In6.Cu")
		(net "M_K_CPU1_SB_DQS_DN<1>")
	)
	(segment
		(start 181.266338 -295.002966)
		(end 182.117238 -294.152066)
		(width 0.16002)
		(layer "In6.Cu")
		(net "M_K_CPU1_SB_DQS_DN<1>")
	)
	(segment
		(start 197.73138 -294.93845)
		(end 197.85838 -294.81145)
		(width 0.16002)
		(layer "In6.Cu")
		(net "M_K_CPU1_SB_DQS_DN<1>")
	)
	(segment
		(start 182.845456 -293.812468)
		(end 184.558178 -293.812468)
		(width 0.16002)
		(layer "In6.Cu")
		(net "M_K_CPU1_SB_DQS_DN<1>")
	)
	(segment
		(start 177.014124 -293.812468)
		(end 177.864008 -294.662352)
		(width 0.16002)
		(layer "In6.Cu")
		(net "M_K_CPU1_SB_DQS_DN<1>")
	)
	(segment
		(start 147.471892 -281.022044)
		(end 147.488656 -281.038808)
		(width 0.09525)
		(layer "In6.Cu")
		(net "M_K_CPU1_SB_DQS_DN<1>")
	)
	(segment
		(start 197.85838 -294.81145)
		(end 198.430388 -294.81145)
		(width 0.16002)
		(layer "In6.Cu")
		(net "M_K_CPU1_SB_DQS_DN<1>")
	)
	(segment
		(start 192.29705 -293.812468)
		(end 192.87109 -294.386508)
		(width 0.16002)
		(layer "In6.Cu")
		(net "M_K_CPU1_SB_DQS_DN<1>")
	)
	(segment
		(start 145.78584 -281.056334)
		(end 146.101054 -280.74112)
		(width 0.09525)
		(layer "In6.Cu")
		(net "M_K_CPU1_SB_DQS_DN<1>")
	)
	(segment
		(start 142.940786 -281.110944)
		(end 142.9639 -281.02433)
		(width 0.09525)
		(layer "In6.Cu")
		(net "M_K_CPU1_SB_DQS_DN<1>")
	)
	(segment
		(start 147.471892 -280.93924)
		(end 147.471892 -281.022044)
		(width 0.09525)
		(layer "In6.Cu")
		(net "M_K_CPU1_SB_DQS_DN<1>")
	)
	(segment
		(start 174.573184 -294.152066)
		(end 174.961804 -294.152066)
		(width 0.16002)
		(layer "In6.Cu")
		(net "M_K_CPU1_SB_DQS_DN<1>")
	)
	(segment
		(start 147.273772 -280.74112)
		(end 147.471892 -280.93924)
		(width 0.09525)
		(layer "In6.Cu")
		(net "M_K_CPU1_SB_DQS_DN<1>")
	)
	(segment
		(start 189.661292 -294.152066)
		(end 190.049912 -294.152066)
		(width 0.16002)
		(layer "In6.Cu")
		(net "M_K_CPU1_SB_DQS_DN<1>")
	)
	(segment
		(start 145.614898 -281.1272)
		(end 145.78584 -281.056334)
		(width 0.09525)
		(layer "In6.Cu")
		(net "M_K_CPU1_SB_DQS_DN<1>")
	)
	(segment
		(start 145.444718 -281.1272)
		(end 145.614898 -281.1272)
		(width 0.09525)
		(layer "In6.Cu")
		(net "M_K_CPU1_SB_DQS_DN<1>")
	)
	(segment
		(start 197.12432 -294.81145)
		(end 197.25132 -294.93845)
		(width 0.16002)
		(layer "In6.Cu")
		(net "M_K_CPU1_SB_DQS_DN<1>")
	)
	(arc
		(start 144.223232 -281.051254)
		(mid 144.498521 -281.126975)
		(end 144.775428 -281.05735)
		(width 0.09525)
		(layer "In6.Cu")
		(net "M_K_CPU1_SB_DQS_DN<1>")
	)
	(arc
		(start 145.163032 -281.051254)
		(mid 145.298854 -281.107834)
		(end 145.444718 -281.1272)
		(width 0.09525)
		(layer "In6.Cu")
		(net "M_K_CPU1_SB_DQS_DN<1>")
	)
	(arc
		(start 143.283178 -281.051254)
		(mid 143.56461 -281.127009)
		(end 143.846042 -281.051254)
		(width 0.09525)
		(layer "In6.Cu")
		(net "M_K_CPU1_SB_DQS_DN<1>")
	)
	(arc
		(start 143.846042 -281.051254)
		(mid 144.029817 -281.000482)
		(end 144.21485 -281.046428)
		(width 0.09525)
		(layer "In6.Cu")
		(net "M_K_CPU1_SB_DQS_DN<1>")
	)
	(arc
		(start 144.794224 -281.046428)
		(mid 144.979256 -281.000514)
		(end 145.163032 -281.051254)
		(width 0.09525)
		(layer "In6.Cu")
		(net "M_K_CPU1_SB_DQS_DN<1>")
	)
	(arc
		(start 142.9639 -281.02433)
		(mid 143.126551 -281.00207)
		(end 143.283178 -281.051254)
		(width 0.09525)
		(layer "In6.Cu")
		(net "M_K_CPU1_SB_DQS_DN<1>")
	)
	(segment
		(start 142.627858 -276.2504)
		(end 143.09471 -276.516338)
		(width 0.12954)
		(layer "F.Cu")
		(net "M_K_CPU1_SB_DQS_DN<0>")
	)
	(segment
		(start 195.081906 -285.036514)
		(end 195.705984 -285.660592)
		(width 0.16002)
		(layer "In6.Cu")
		(net "M_K_CPU1_SB_DQS_DN<0>")
	)
	(segment
		(start 196.53504 -285.461456)
		(end 197.15226 -285.461456)
		(width 0.16002)
		(layer "In6.Cu")
		(net "M_K_CPU1_SB_DQS_DN<0>")
	)
	(segment
		(start 175.89627 -284.462474)
		(end 177.014124 -284.462474)
		(width 0.16002)
		(layer "In6.Cu")
		(net "M_K_CPU1_SB_DQS_DN<0>")
	)
	(segment
		(start 174.21733 -285.157926)
		(end 175.89627 -284.462474)
		(width 0.16002)
		(layer "In6.Cu")
		(net "M_K_CPU1_SB_DQS_DN<0>")
	)
	(segment
		(start 171.407074 -285.312358)
		(end 172.729906 -285.312358)
		(width 0.16002)
		(layer "In6.Cu")
		(net "M_K_CPU1_SB_DQS_DN<0>")
	)
	(segment
		(start 190.38951 -284.462474)
		(end 192.29705 -284.462474)
		(width 0.16002)
		(layer "In6.Cu")
		(net "M_K_CPU1_SB_DQS_DN<0>")
	)
	(segment
		(start 187.818014 -285.312358)
		(end 188.158628 -285.652972)
		(width 0.16002)
		(layer "In6.Cu")
		(net "M_K_CPU1_SB_DQS_DN<0>")
	)
	(segment
		(start 184.558178 -284.462474)
		(end 185.408062 -285.312358)
		(width 0.16002)
		(layer "In6.Cu")
		(net "M_K_CPU1_SB_DQS_DN<0>")
	)
	(segment
		(start 144.775428 -276.197314)
		(end 144.785842 -276.191218)
		(width 0.09525)
		(layer "In6.Cu")
		(net "M_K_CPU1_SB_DQS_DN<0>")
	)
	(segment
		(start 173.722284 -285.652972)
		(end 174.21733 -285.157926)
		(width 0.16002)
		(layer "In6.Cu")
		(net "M_K_CPU1_SB_DQS_DN<0>")
	)
	(segment
		(start 166.17823 -285.652972)
		(end 167.02913 -284.802072)
		(width 0.16002)
		(layer "In6.Cu")
		(net "M_K_CPU1_SB_DQS_DN<0>")
	)
	(segment
		(start 182.845456 -284.462474)
		(end 184.558178 -284.462474)
		(width 0.16002)
		(layer "In6.Cu")
		(net "M_K_CPU1_SB_DQS_DN<0>")
	)
	(segment
		(start 144.785842 -276.191218)
		(end 144.794224 -276.186392)
		(width 0.09525)
		(layer "In6.Cu")
		(net "M_K_CPU1_SB_DQS_DN<0>")
	)
	(segment
		(start 180.27396 -285.312358)
		(end 180.614574 -285.652972)
		(width 0.16002)
		(layer "In6.Cu")
		(net "M_K_CPU1_SB_DQS_DN<0>")
	)
	(segment
		(start 173.07052 -285.652972)
		(end 173.722284 -285.652972)
		(width 0.16002)
		(layer "In6.Cu")
		(net "M_K_CPU1_SB_DQS_DN<0>")
	)
	(segment
		(start 163.784534 -285.652972)
		(end 166.17823 -285.652972)
		(width 0.16002)
		(layer "In6.Cu")
		(net "M_K_CPU1_SB_DQS_DN<0>")
	)
	(segment
		(start 147.919186 -275.20011)
		(end 153.331672 -275.20011)
		(width 0.16002)
		(layer "In6.Cu")
		(net "M_K_CPU1_SB_DQS_DN<0>")
	)
	(segment
		(start 167.496744 -284.802072)
		(end 167.71239 -284.586426)
		(width 0.16002)
		(layer "In6.Cu")
		(net "M_K_CPU1_SB_DQS_DN<0>")
	)
	(segment
		(start 153.331672 -275.20011)
		(end 163.784534 -285.652972)
		(width 0.16002)
		(layer "In6.Cu")
		(net "M_K_CPU1_SB_DQS_DN<0>")
	)
	(segment
		(start 197.75932 -285.588456)
		(end 197.88632 -285.461456)
		(width 0.16002)
		(layer "In6.Cu")
		(net "M_K_CPU1_SB_DQS_DN<0>")
	)
	(segment
		(start 147.895564 -275.20011)
		(end 147.919186 -275.20011)
		(width 0.09525)
		(layer "In6.Cu")
		(net "M_K_CPU1_SB_DQS_DN<0>")
	)
	(segment
		(start 188.810392 -285.652972)
		(end 189.661292 -284.802072)
		(width 0.16002)
		(layer "In6.Cu")
		(net "M_K_CPU1_SB_DQS_DN<0>")
	)
	(segment
		(start 167.02913 -284.802072)
		(end 167.496744 -284.802072)
		(width 0.16002)
		(layer "In6.Cu")
		(net "M_K_CPU1_SB_DQS_DN<0>")
	)
	(segment
		(start 196.335904 -285.660592)
		(end 196.53504 -285.461456)
		(width 0.16002)
		(layer "In6.Cu")
		(net "M_K_CPU1_SB_DQS_DN<0>")
	)
	(segment
		(start 182.117238 -284.802072)
		(end 182.505858 -284.802072)
		(width 0.16002)
		(layer "In6.Cu")
		(net "M_K_CPU1_SB_DQS_DN<0>")
	)
	(segment
		(start 177.864008 -285.312358)
		(end 180.27396 -285.312358)
		(width 0.16002)
		(layer "In6.Cu")
		(net "M_K_CPU1_SB_DQS_DN<0>")
	)
	(segment
		(start 185.408062 -285.312358)
		(end 187.818014 -285.312358)
		(width 0.16002)
		(layer "In6.Cu")
		(net "M_K_CPU1_SB_DQS_DN<0>")
	)
	(segment
		(start 198.430388 -285.461456)
		(end 198.7042 -285.735268)
		(width 0.16002)
		(layer "In6.Cu")
		(net "M_K_CPU1_SB_DQS_DN<0>")
	)
	(segment
		(start 167.71239 -284.586426)
		(end 169.65422 -284.586426)
		(width 0.16002)
		(layer "In6.Cu")
		(net "M_K_CPU1_SB_DQS_DN<0>")
	)
	(segment
		(start 172.729906 -285.312358)
		(end 173.07052 -285.652972)
		(width 0.16002)
		(layer "In6.Cu")
		(net "M_K_CPU1_SB_DQS_DN<0>")
	)
	(segment
		(start 142.940786 -276.250908)
		(end 142.9639 -276.164294)
		(width 0.09525)
		(layer "In6.Cu")
		(net "M_K_CPU1_SB_DQS_DN<0>")
	)
	(segment
		(start 190.049912 -284.802072)
		(end 190.38951 -284.462474)
		(width 0.16002)
		(layer "In6.Cu")
		(net "M_K_CPU1_SB_DQS_DN<0>")
	)
	(segment
		(start 144.21485 -276.186392)
		(end 144.223232 -276.191218)
		(width 0.09525)
		(layer "In6.Cu")
		(net "M_K_CPU1_SB_DQS_DN<0>")
	)
	(segment
		(start 143.09471 -276.516338)
		(end 142.940786 -276.250908)
		(width 0.09525)
		(layer "In6.Cu")
		(net "M_K_CPU1_SB_DQS_DN<0>")
	)
	(segment
		(start 195.705984 -285.660592)
		(end 196.335904 -285.660592)
		(width 0.16002)
		(layer "In6.Cu")
		(net "M_K_CPU1_SB_DQS_DN<0>")
	)
	(segment
		(start 147.262342 -275.222208)
		(end 147.343368 -275.141182)
		(width 0.09525)
		(layer "In6.Cu")
		(net "M_K_CPU1_SB_DQS_DN<0>")
	)
	(segment
		(start 188.158628 -285.652972)
		(end 188.810392 -285.652972)
		(width 0.16002)
		(layer "In6.Cu")
		(net "M_K_CPU1_SB_DQS_DN<0>")
	)
	(segment
		(start 181.266338 -285.652972)
		(end 182.117238 -284.802072)
		(width 0.16002)
		(layer "In6.Cu")
		(net "M_K_CPU1_SB_DQS_DN<0>")
	)
	(segment
		(start 197.88632 -285.461456)
		(end 198.430388 -285.461456)
		(width 0.16002)
		(layer "In6.Cu")
		(net "M_K_CPU1_SB_DQS_DN<0>")
	)
	(segment
		(start 147.836636 -275.141182)
		(end 147.895564 -275.20011)
		(width 0.09525)
		(layer "In6.Cu")
		(net "M_K_CPU1_SB_DQS_DN<0>")
	)
	(segment
		(start 180.614574 -285.652972)
		(end 181.266338 -285.652972)
		(width 0.16002)
		(layer "In6.Cu")
		(net "M_K_CPU1_SB_DQS_DN<0>")
	)
	(segment
		(start 146.72183 -275.222208)
		(end 147.262342 -275.222208)
		(width 0.09525)
		(layer "In6.Cu")
		(net "M_K_CPU1_SB_DQS_DN<0>")
	)
	(segment
		(start 147.343368 -275.141182)
		(end 147.836636 -275.141182)
		(width 0.09525)
		(layer "In6.Cu")
		(net "M_K_CPU1_SB_DQS_DN<0>")
	)
	(segment
		(start 182.505858 -284.802072)
		(end 182.845456 -284.462474)
		(width 0.16002)
		(layer "In6.Cu")
		(net "M_K_CPU1_SB_DQS_DN<0>")
	)
	(segment
		(start 197.15226 -285.461456)
		(end 197.27926 -285.588456)
		(width 0.16002)
		(layer "In6.Cu")
		(net "M_K_CPU1_SB_DQS_DN<0>")
	)
	(segment
		(start 197.27926 -285.588456)
		(end 197.75932 -285.588456)
		(width 0.16002)
		(layer "In6.Cu")
		(net "M_K_CPU1_SB_DQS_DN<0>")
	)
	(segment
		(start 169.65422 -284.586426)
		(end 171.407074 -285.312358)
		(width 0.16002)
		(layer "In6.Cu")
		(net "M_K_CPU1_SB_DQS_DN<0>")
	)
	(segment
		(start 189.661292 -284.802072)
		(end 190.049912 -284.802072)
		(width 0.16002)
		(layer "In6.Cu")
		(net "M_K_CPU1_SB_DQS_DN<0>")
	)
	(segment
		(start 192.87109 -285.036514)
		(end 195.081906 -285.036514)
		(width 0.16002)
		(layer "In6.Cu")
		(net "M_K_CPU1_SB_DQS_DN<0>")
	)
	(segment
		(start 192.29705 -284.462474)
		(end 192.87109 -285.036514)
		(width 0.16002)
		(layer "In6.Cu")
		(net "M_K_CPU1_SB_DQS_DN<0>")
	)
	(segment
		(start 145.840958 -276.103334)
		(end 146.72183 -275.222208)
		(width 0.09525)
		(layer "In6.Cu")
		(net "M_K_CPU1_SB_DQS_DN<0>")
	)
	(segment
		(start 177.014124 -284.462474)
		(end 177.864008 -285.312358)
		(width 0.16002)
		(layer "In6.Cu")
		(net "M_K_CPU1_SB_DQS_DN<0>")
	)
	(arc
		(start 143.846042 -276.191218)
		(mid 144.029817 -276.140446)
		(end 144.21485 -276.186392)
		(width 0.09525)
		(layer "In6.Cu")
		(net "M_K_CPU1_SB_DQS_DN<0>")
	)
	(arc
		(start 144.223232 -276.191218)
		(mid 144.498521 -276.266939)
		(end 144.775428 -276.197314)
		(width 0.09525)
		(layer "In6.Cu")
		(net "M_K_CPU1_SB_DQS_DN<0>")
	)
	(arc
		(start 144.794224 -276.186392)
		(mid 144.979256 -276.140478)
		(end 145.163032 -276.191218)
		(width 0.09525)
		(layer "In6.Cu")
		(net "M_K_CPU1_SB_DQS_DN<0>")
	)
	(arc
		(start 143.283178 -276.191218)
		(mid 143.56461 -276.266973)
		(end 143.846042 -276.191218)
		(width 0.09525)
		(layer "In6.Cu")
		(net "M_K_CPU1_SB_DQS_DN<0>")
	)
	(arc
		(start 142.9639 -276.164294)
		(mid 143.126551 -276.142034)
		(end 143.283178 -276.191218)
		(width 0.09525)
		(layer "In6.Cu")
		(net "M_K_CPU1_SB_DQS_DN<0>")
	)
	(arc
		(start 145.163032 -276.191218)
		(mid 145.433974 -276.266998)
		(end 145.707608 -276.201632)
		(width 0.09525)
		(layer "In6.Cu")
		(net "M_K_CPU1_SB_DQS_DN<0>")
	)
	(arc
		(start 145.81886 -276.124162)
		(mid 145.830047 -276.113895)
		(end 145.840958 -276.103334)
		(width 0.09525)
		(layer "In6.Cu")
		(net "M_K_CPU1_SB_DQS_DN<0>")
	)
	(arc
		(start 145.707608 -276.201632)
		(mid 145.76559 -276.166279)
		(end 145.81886 -276.124162)
		(width 0.09525)
		(layer "In6.Cu")
		(net "M_K_CPU1_SB_DQS_DN<0>")
	)
	(segment
		(start 140.748004 -279.490424)
		(end 141.214856 -279.756362)
		(width 0.10668)
		(layer "F.Cu")
		(net "M_K_CPU1_SB_DQ<9>")
	)
	(segment
		(start 188.33338 -292.960298)
		(end 189.183518 -292.11016)
		(width 0.14478)
		(layer "In6.Cu")
		(net "M_K_CPU1_SB_DQ<9>")
	)
	(segment
		(start 198.279004 -292.11016)
		(end 198.7042 -292.535356)
		(width 0.14478)
		(layer "In6.Cu")
		(net "M_K_CPU1_SB_DQ<9>")
	)
	(segment
		(start 170.117516 -292.110414)
		(end 170.9674 -292.960298)
		(width 0.14478)
		(layer "In6.Cu")
		(net "M_K_CPU1_SB_DQ<9>")
	)
	(segment
		(start 177.66157 -292.110414)
		(end 178.511454 -292.960298)
		(width 0.14478)
		(layer "In6.Cu")
		(net "M_K_CPU1_SB_DQ<9>")
	)
	(segment
		(start 178.511454 -292.960298)
		(end 181.331108 -292.960298)
		(width 0.14478)
		(layer "In6.Cu")
		(net "M_K_CPU1_SB_DQ<9>")
	)
	(segment
		(start 144.787112 -280.078942)
		(end 144.798796 -280.0858)
		(width 0.0889)
		(layer "In6.Cu")
		(net "M_K_CPU1_SB_DQ<9>")
	)
	(segment
		(start 147.188428 -279.929082)
		(end 147.371816 -279.745694)
		(width 0.0889)
		(layer "In6.Cu")
		(net "M_K_CPU1_SB_DQ<9>")
	)
	(segment
		(start 170.9674 -292.960298)
		(end 173.787054 -292.960298)
		(width 0.14478)
		(layer "In6.Cu")
		(net "M_K_CPU1_SB_DQ<9>")
	)
	(segment
		(start 185.205624 -292.110414)
		(end 186.055508 -292.960298)
		(width 0.14478)
		(layer "In6.Cu")
		(net "M_K_CPU1_SB_DQ<9>")
	)
	(segment
		(start 166.34968 -292.110414)
		(end 170.117516 -292.110414)
		(width 0.14478)
		(layer "In6.Cu")
		(net "M_K_CPU1_SB_DQ<9>")
	)
	(segment
		(start 147.371816 -279.745694)
		(end 147.831048 -279.745694)
		(width 0.0889)
		(layer "In6.Cu")
		(net "M_K_CPU1_SB_DQ<9>")
	)
	(segment
		(start 144.20977 -280.0858)
		(end 144.221454 -280.078942)
		(width 0.0889)
		(layer "In6.Cu")
		(net "M_K_CPU1_SB_DQ<9>")
	)
	(segment
		(start 145.504662 -279.929082)
		(end 147.188428 -279.929082)
		(width 0.0889)
		(layer "In6.Cu")
		(net "M_K_CPU1_SB_DQ<9>")
	)
	(segment
		(start 174.636938 -292.110414)
		(end 177.66157 -292.110414)
		(width 0.14478)
		(layer "In6.Cu")
		(net "M_K_CPU1_SB_DQ<9>")
	)
	(segment
		(start 189.183518 -292.11016)
		(end 198.279004 -292.11016)
		(width 0.14478)
		(layer "In6.Cu")
		(net "M_K_CPU1_SB_DQ<9>")
	)
	(segment
		(start 141.967712 -280.078942)
		(end 141.976094 -280.083768)
		(width 0.0889)
		(layer "In6.Cu")
		(net "M_K_CPU1_SB_DQ<9>")
	)
	(segment
		(start 151.033988 -279.745694)
		(end 164.248592 -292.960298)
		(width 0.14478)
		(layer "In6.Cu")
		(net "M_K_CPU1_SB_DQ<9>")
	)
	(segment
		(start 141.36878 -280.021792)
		(end 141.464792 -280.047192)
		(width 0.0889)
		(layer "In6.Cu")
		(net "M_K_CPU1_SB_DQ<9>")
	)
	(segment
		(start 182.180992 -292.110414)
		(end 185.205624 -292.110414)
		(width 0.14478)
		(layer "In6.Cu")
		(net "M_K_CPU1_SB_DQ<9>")
	)
	(segment
		(start 147.831048 -279.745694)
		(end 151.033988 -279.745694)
		(width 0.14478)
		(layer "In6.Cu")
		(net "M_K_CPU1_SB_DQ<9>")
	)
	(segment
		(start 181.331108 -292.960298)
		(end 182.180992 -292.110414)
		(width 0.14478)
		(layer "In6.Cu")
		(net "M_K_CPU1_SB_DQ<9>")
	)
	(segment
		(start 144.221454 -280.078942)
		(end 144.231868 -280.072846)
		(width 0.0889)
		(layer "In6.Cu")
		(net "M_K_CPU1_SB_DQ<9>")
	)
	(segment
		(start 141.214856 -279.756362)
		(end 141.36878 -280.021792)
		(width 0.0889)
		(layer "In6.Cu")
		(net "M_K_CPU1_SB_DQ<9>")
	)
	(segment
		(start 164.248592 -292.960298)
		(end 165.499796 -292.960298)
		(width 0.14478)
		(layer "In6.Cu")
		(net "M_K_CPU1_SB_DQ<9>")
	)
	(segment
		(start 186.055508 -292.960298)
		(end 188.33338 -292.960298)
		(width 0.14478)
		(layer "In6.Cu")
		(net "M_K_CPU1_SB_DQ<9>")
	)
	(segment
		(start 165.499796 -292.960298)
		(end 166.34968 -292.110414)
		(width 0.14478)
		(layer "In6.Cu")
		(net "M_K_CPU1_SB_DQ<9>")
	)
	(segment
		(start 173.787054 -292.960298)
		(end 174.636938 -292.110414)
		(width 0.14478)
		(layer "In6.Cu")
		(net "M_K_CPU1_SB_DQ<9>")
	)
	(segment
		(start 145.161508 -280.078942)
		(end 145.345658 -279.972008)
		(width 0.0889)
		(layer "In6.Cu")
		(net "M_K_CPU1_SB_DQ<9>")
	)
	(arc
		(start 141.976094 -280.083768)
		(mid 142.159602 -280.129262)
		(end 142.341854 -280.078942)
		(width 0.0889)
		(layer "In6.Cu")
		(net "M_K_CPU1_SB_DQ<9>")
	)
	(arc
		(start 141.464792 -280.047192)
		(mid 141.72 -280.003715)
		(end 141.967712 -280.078942)
		(width 0.0889)
		(layer "In6.Cu")
		(net "M_K_CPU1_SB_DQ<9>")
	)
	(arc
		(start 142.341854 -280.078942)
		(mid 142.62481 -280.002765)
		(end 142.907766 -280.078942)
		(width 0.0889)
		(layer "In6.Cu")
		(net "M_K_CPU1_SB_DQ<9>")
	)
	(arc
		(start 143.281654 -280.078942)
		(mid 143.56461 -280.002765)
		(end 143.847566 -280.078942)
		(width 0.0889)
		(layer "In6.Cu")
		(net "M_K_CPU1_SB_DQ<9>")
	)
	(arc
		(start 144.231868 -280.072846)
		(mid 144.5103 -280.002748)
		(end 144.787112 -280.078942)
		(width 0.0889)
		(layer "In6.Cu")
		(net "M_K_CPU1_SB_DQ<9>")
	)
	(arc
		(start 143.847566 -280.078942)
		(mid 144.027771 -280.129259)
		(end 144.20977 -280.0858)
		(width 0.0889)
		(layer "In6.Cu")
		(net "M_K_CPU1_SB_DQ<9>")
	)
	(arc
		(start 145.345658 -279.972008)
		(mid 145.422315 -279.939994)
		(end 145.504662 -279.929082)
		(width 0.0889)
		(layer "In6.Cu")
		(net "M_K_CPU1_SB_DQ<9>")
	)
	(arc
		(start 144.798796 -280.0858)
		(mid 144.981051 -280.129453)
		(end 145.161508 -280.078942)
		(width 0.0889)
		(layer "In6.Cu")
		(net "M_K_CPU1_SB_DQ<9>")
	)
	(arc
		(start 142.907766 -280.078942)
		(mid 143.09471 -280.129197)
		(end 143.281654 -280.078942)
		(width 0.0889)
		(layer "In6.Cu")
		(net "M_K_CPU1_SB_DQ<9>")
	)
	(segment
		(start 142.157958 -278.680418)
		(end 142.62481 -278.946356)
		(width 0.10668)
		(layer "F.Cu")
		(net "M_K_CPU1_SB_DQ<8>")
	)
	(segment
		(start 196.282818 -290.861496)
		(end 196.282818 -290.57346)
		(width 0.14478)
		(layer "In6.Cu")
		(net "M_K_CPU1_SB_DQ<8>")
	)
	(segment
		(start 142.62481 -278.946356)
		(end 142.778734 -279.211786)
		(width 0.0889)
		(layer "In6.Cu")
		(net "M_K_CPU1_SB_DQ<8>")
	)
	(segment
		(start 181.331108 -291.260276)
		(end 182.180992 -290.410392)
		(width 0.14478)
		(layer "In6.Cu")
		(net "M_K_CPU1_SB_DQ<8>")
	)
	(segment
		(start 145.619724 -279.275794)
		(end 145.692622 -279.210008)
		(width 0.0889)
		(layer "In6.Cu")
		(net "M_K_CPU1_SB_DQ<8>")
	)
	(segment
		(start 189.221872 -290.410392)
		(end 195.563236 -290.410392)
		(width 0.14478)
		(layer "In6.Cu")
		(net "M_K_CPU1_SB_DQ<8>")
	)
	(segment
		(start 173.718474 -291.260276)
		(end 174.568358 -290.410392)
		(width 0.14478)
		(layer "In6.Cu")
		(net "M_K_CPU1_SB_DQ<8>")
	)
	(segment
		(start 186.055508 -291.260276)
		(end 188.371988 -291.260276)
		(width 0.14478)
		(layer "In6.Cu")
		(net "M_K_CPU1_SB_DQ<8>")
	)
	(segment
		(start 196.445886 -290.410392)
		(end 196.676264 -290.410392)
		(width 0.14478)
		(layer "In6.Cu")
		(net "M_K_CPU1_SB_DQ<8>")
	)
	(segment
		(start 196.839332 -290.861496)
		(end 197.0024 -291.024564)
		(width 0.14478)
		(layer "In6.Cu")
		(net "M_K_CPU1_SB_DQ<8>")
	)
	(segment
		(start 196.11975 -291.024564)
		(end 196.282818 -290.861496)
		(width 0.14478)
		(layer "In6.Cu")
		(net "M_K_CPU1_SB_DQ<8>")
	)
	(segment
		(start 151.6126 -278.61133)
		(end 164.261546 -291.260276)
		(width 0.14478)
		(layer "In6.Cu")
		(net "M_K_CPU1_SB_DQ<8>")
	)
	(segment
		(start 197.395846 -290.861496)
		(end 197.395846 -290.57346)
		(width 0.14478)
		(layer "In6.Cu")
		(net "M_K_CPU1_SB_DQ<8>")
	)
	(segment
		(start 148.017484 -278.61133)
		(end 151.6126 -278.61133)
		(width 0.14478)
		(layer "In6.Cu")
		(net "M_K_CPU1_SB_DQ<8>")
	)
	(segment
		(start 147.309586 -278.652224)
		(end 147.35048 -278.61133)
		(width 0.0889)
		(layer "In6.Cu")
		(net "M_K_CPU1_SB_DQ<8>")
	)
	(segment
		(start 178.511454 -291.260276)
		(end 181.331108 -291.260276)
		(width 0.14478)
		(layer "In6.Cu")
		(net "M_K_CPU1_SB_DQ<8>")
	)
	(segment
		(start 197.558914 -290.410392)
		(end 198.279258 -290.410392)
		(width 0.14478)
		(layer "In6.Cu")
		(net "M_K_CPU1_SB_DQ<8>")
	)
	(segment
		(start 195.726304 -290.57346)
		(end 195.726304 -290.861496)
		(width 0.14478)
		(layer "In6.Cu")
		(net "M_K_CPU1_SB_DQ<8>")
	)
	(segment
		(start 177.66157 -290.410392)
		(end 178.511454 -291.260276)
		(width 0.14478)
		(layer "In6.Cu")
		(net "M_K_CPU1_SB_DQ<8>")
	)
	(segment
		(start 164.261546 -291.260276)
		(end 165.514528 -291.260276)
		(width 0.14478)
		(layer "In6.Cu")
		(net "M_K_CPU1_SB_DQ<8>")
	)
	(segment
		(start 195.726304 -290.861496)
		(end 195.889372 -291.024564)
		(width 0.14478)
		(layer "In6.Cu")
		(net "M_K_CPU1_SB_DQ<8>")
	)
	(segment
		(start 165.514528 -291.260276)
		(end 166.364412 -290.410392)
		(width 0.14478)
		(layer "In6.Cu")
		(net "M_K_CPU1_SB_DQ<8>")
	)
	(segment
		(start 195.889372 -291.024564)
		(end 196.11975 -291.024564)
		(width 0.14478)
		(layer "In6.Cu")
		(net "M_K_CPU1_SB_DQ<8>")
	)
	(segment
		(start 196.282818 -290.57346)
		(end 196.445886 -290.410392)
		(width 0.14478)
		(layer "In6.Cu")
		(net "M_K_CPU1_SB_DQ<8>")
	)
	(segment
		(start 170.117516 -290.410392)
		(end 170.9674 -291.260276)
		(width 0.14478)
		(layer "In6.Cu")
		(net "M_K_CPU1_SB_DQ<8>")
	)
	(segment
		(start 195.563236 -290.410392)
		(end 195.726304 -290.57346)
		(width 0.14478)
		(layer "In6.Cu")
		(net "M_K_CPU1_SB_DQ<8>")
	)
	(segment
		(start 144.307052 -279.26284)
		(end 144.317466 -279.268936)
		(width 0.0889)
		(layer "In6.Cu")
		(net "M_K_CPU1_SB_DQ<8>")
	)
	(segment
		(start 182.180992 -290.410392)
		(end 185.205624 -290.410392)
		(width 0.14478)
		(layer "In6.Cu")
		(net "M_K_CPU1_SB_DQ<8>")
	)
	(segment
		(start 170.9674 -291.260276)
		(end 173.718474 -291.260276)
		(width 0.14478)
		(layer "In6.Cu")
		(net "M_K_CPU1_SB_DQ<8>")
	)
	(segment
		(start 143.377666 -279.268936)
		(end 143.386048 -279.273762)
		(width 0.0889)
		(layer "In6.Cu")
		(net "M_K_CPU1_SB_DQ<8>")
	)
	(segment
		(start 196.839332 -290.57346)
		(end 196.839332 -290.861496)
		(width 0.14478)
		(layer "In6.Cu")
		(net "M_K_CPU1_SB_DQ<8>")
	)
	(segment
		(start 198.279258 -290.410392)
		(end 198.7042 -290.835334)
		(width 0.14478)
		(layer "In6.Cu")
		(net "M_K_CPU1_SB_DQ<8>")
	)
	(segment
		(start 166.364412 -290.410392)
		(end 170.117516 -290.410392)
		(width 0.14478)
		(layer "In6.Cu")
		(net "M_K_CPU1_SB_DQ<8>")
	)
	(segment
		(start 188.371988 -291.260276)
		(end 189.221872 -290.410392)
		(width 0.14478)
		(layer "In6.Cu")
		(net "M_K_CPU1_SB_DQ<8>")
	)
	(segment
		(start 174.568358 -290.410392)
		(end 177.66157 -290.410392)
		(width 0.14478)
		(layer "In6.Cu")
		(net "M_K_CPU1_SB_DQ<8>")
	)
	(segment
		(start 196.676264 -290.410392)
		(end 196.839332 -290.57346)
		(width 0.14478)
		(layer "In6.Cu")
		(net "M_K_CPU1_SB_DQ<8>")
	)
	(segment
		(start 185.205624 -290.410392)
		(end 186.055508 -291.260276)
		(width 0.14478)
		(layer "In6.Cu")
		(net "M_K_CPU1_SB_DQ<8>")
	)
	(segment
		(start 142.778734 -279.211786)
		(end 142.874746 -279.237186)
		(width 0.0889)
		(layer "In6.Cu")
		(net "M_K_CPU1_SB_DQ<8>")
	)
	(segment
		(start 145.692622 -279.210008)
		(end 146.21256 -278.69007)
		(width 0.0889)
		(layer "In6.Cu")
		(net "M_K_CPU1_SB_DQ<8>")
	)
	(segment
		(start 147.35048 -278.61133)
		(end 148.017484 -278.61133)
		(width 0.0889)
		(layer "In6.Cu")
		(net "M_K_CPU1_SB_DQ<8>")
	)
	(segment
		(start 146.304 -278.652224)
		(end 147.309586 -278.652224)
		(width 0.0889)
		(layer "In6.Cu")
		(net "M_K_CPU1_SB_DQ<8>")
	)
	(segment
		(start 144.691354 -279.268936)
		(end 144.701768 -279.26284)
		(width 0.0889)
		(layer "In6.Cu")
		(net "M_K_CPU1_SB_DQ<8>")
	)
	(segment
		(start 197.0024 -291.024564)
		(end 197.232778 -291.024564)
		(width 0.14478)
		(layer "In6.Cu")
		(net "M_K_CPU1_SB_DQ<8>")
	)
	(segment
		(start 197.232778 -291.024564)
		(end 197.395846 -290.861496)
		(width 0.14478)
		(layer "In6.Cu")
		(net "M_K_CPU1_SB_DQ<8>")
	)
	(segment
		(start 197.395846 -290.57346)
		(end 197.558914 -290.410392)
		(width 0.14478)
		(layer "In6.Cu")
		(net "M_K_CPU1_SB_DQ<8>")
	)
	(arc
		(start 146.21256 -278.69007)
		(mid 146.254513 -278.662038)
		(end 146.304 -278.652224)
		(width 0.0889)
		(layer "In6.Cu")
		(net "M_K_CPU1_SB_DQ<8>")
	)
	(arc
		(start 145.25752 -279.268936)
		(mid 145.437725 -279.319253)
		(end 145.619724 -279.275794)
		(width 0.0889)
		(layer "In6.Cu")
		(net "M_K_CPU1_SB_DQ<8>")
	)
	(arc
		(start 144.317466 -279.268936)
		(mid 144.50441 -279.319191)
		(end 144.691354 -279.268936)
		(width 0.0889)
		(layer "In6.Cu")
		(net "M_K_CPU1_SB_DQ<8>")
	)
	(arc
		(start 143.751808 -279.268936)
		(mid 144.028621 -279.192793)
		(end 144.307052 -279.26284)
		(width 0.0889)
		(layer "In6.Cu")
		(net "M_K_CPU1_SB_DQ<8>")
	)
	(arc
		(start 143.386048 -279.273762)
		(mid 143.569556 -279.319256)
		(end 143.751808 -279.268936)
		(width 0.0889)
		(layer "In6.Cu")
		(net "M_K_CPU1_SB_DQ<8>")
	)
	(arc
		(start 144.701768 -279.26284)
		(mid 144.980454 -279.19262)
		(end 145.25752 -279.268936)
		(width 0.0889)
		(layer "In6.Cu")
		(net "M_K_CPU1_SB_DQ<8>")
	)
	(arc
		(start 142.874746 -279.237186)
		(mid 143.129954 -279.193709)
		(end 143.377666 -279.268936)
		(width 0.0889)
		(layer "In6.Cu")
		(net "M_K_CPU1_SB_DQ<8>")
	)
	(segment
		(start 141.217904 -278.680418)
		(end 141.684756 -278.946356)
		(width 0.10668)
		(layer "F.Cu")
		(net "M_K_CPU1_SB_DQ<7>")
	)
	(segment
		(start 178.576732 -290.410646)
		(end 181.238144 -290.410646)
		(width 0.14478)
		(layer "In6.Cu")
		(net "M_K_CPU1_SB_DQ<7>")
	)
	(segment
		(start 148.042122 -278.05507)
		(end 152.113234 -278.05507)
		(width 0.14478)
		(layer "In6.Cu")
		(net "M_K_CPU1_SB_DQ<7>")
	)
	(segment
		(start 144.6911 -278.623776)
		(end 144.701514 -278.629872)
		(width 0.0889)
		(layer "In6.Cu")
		(net "M_K_CPU1_SB_DQ<7>")
	)
	(segment
		(start 185.202576 -289.560508)
		(end 186.05246 -290.410392)
		(width 0.14478)
		(layer "In6.Cu")
		(net "M_K_CPU1_SB_DQ<7>")
	)
	(segment
		(start 190.203582 -289.271964)
		(end 190.492126 -289.560508)
		(width 0.14478)
		(layer "In6.Cu")
		(net "M_K_CPU1_SB_DQ<7>")
	)
	(segment
		(start 168.377616 -289.560508)
		(end 168.645586 -289.560508)
		(width 0.14478)
		(layer "In6.Cu")
		(net "M_K_CPU1_SB_DQ<7>")
	)
	(segment
		(start 167.821102 -289.271964)
		(end 168.089072 -289.271964)
		(width 0.14478)
		(layer "In6.Cu")
		(net "M_K_CPU1_SB_DQ<7>")
	)
	(segment
		(start 146.800316 -278.236172)
		(end 147.22856 -278.236172)
		(width 0.0889)
		(layer "In6.Cu")
		(net "M_K_CPU1_SB_DQ<7>")
	)
	(segment
		(start 184.182512 -289.331146)
		(end 184.327292 -289.186366)
		(width 0.14478)
		(layer "In6.Cu")
		(net "M_K_CPU1_SB_DQ<7>")
	)
	(segment
		(start 193.023998 -289.84829)
		(end 193.167762 -289.704526)
		(width 0.14478)
		(layer "In6.Cu")
		(net "M_K_CPU1_SB_DQ<7>")
	)
	(segment
		(start 169.2021 -289.271964)
		(end 169.490644 -289.560508)
		(width 0.14478)
		(layer "In6.Cu")
		(net "M_K_CPU1_SB_DQ<7>")
	)
	(segment
		(start 191.92113 -289.560508)
		(end 192.064894 -289.416744)
		(width 0.14478)
		(layer "In6.Cu")
		(net "M_K_CPU1_SB_DQ<7>")
	)
	(segment
		(start 168.645586 -289.560508)
		(end 168.93413 -289.271964)
		(width 0.14478)
		(layer "In6.Cu")
		(net "M_K_CPU1_SB_DQ<7>")
	)
	(segment
		(start 141.684756 -278.946356)
		(end 141.530832 -278.680926)
		(width 0.0889)
		(layer "In6.Cu")
		(net "M_K_CPU1_SB_DQ<7>")
	)
	(segment
		(start 192.472564 -289.272726)
		(end 192.616328 -289.41649)
		(width 0.14478)
		(layer "In6.Cu")
		(net "M_K_CPU1_SB_DQ<7>")
	)
	(segment
		(start 176.865026 -289.271964)
		(end 177.132996 -289.271964)
		(width 0.14478)
		(layer "In6.Cu")
		(net "M_K_CPU1_SB_DQ<7>")
	)
	(segment
		(start 193.167762 -289.704526)
		(end 193.167762 -289.41649)
		(width 0.14478)
		(layer "In6.Cu")
		(net "M_K_CPU1_SB_DQ<7>")
	)
	(segment
		(start 184.327292 -289.186366)
		(end 184.589166 -289.186366)
		(width 0.14478)
		(layer "In6.Cu")
		(net "M_K_CPU1_SB_DQ<7>")
	)
	(segment
		(start 184.878726 -289.560508)
		(end 185.202576 -289.560508)
		(width 0.14478)
		(layer "In6.Cu")
		(net "M_K_CPU1_SB_DQ<7>")
	)
	(segment
		(start 173.478952 -290.410646)
		(end 173.69409 -290.410646)
		(width 0.14478)
		(layer "In6.Cu")
		(net "M_K_CPU1_SB_DQ<7>")
	)
	(segment
		(start 193.719196 -289.41649)
		(end 193.719196 -289.416744)
		(width 0.14478)
		(layer "In6.Cu")
		(net "M_K_CPU1_SB_DQ<7>")
	)
	(segment
		(start 186.05246 -290.410392)
		(end 188.411612 -290.410392)
		(width 0.14478)
		(layer "In6.Cu")
		(net "M_K_CPU1_SB_DQ<7>")
	)
	(segment
		(start 167.532558 -289.560508)
		(end 167.821102 -289.271964)
		(width 0.14478)
		(layer "In6.Cu")
		(net "M_K_CPU1_SB_DQ<7>")
	)
	(segment
		(start 184.037732 -289.560508)
		(end 184.182512 -289.415728)
		(width 0.14478)
		(layer "In6.Cu")
		(net "M_K_CPU1_SB_DQ<7>")
	)
	(segment
		(start 193.311526 -289.272726)
		(end 193.575432 -289.272726)
		(width 0.14478)
		(layer "In6.Cu")
		(net "M_K_CPU1_SB_DQ<7>")
	)
	(segment
		(start 171.032678 -290.410646)
		(end 172.596556 -290.410646)
		(width 0.14478)
		(layer "In6.Cu")
		(net "M_K_CPU1_SB_DQ<7>")
	)
	(segment
		(start 141.530832 -278.680926)
		(end 141.553184 -278.597614)
		(width 0.0889)
		(layer "In6.Cu")
		(net "M_K_CPU1_SB_DQ<7>")
	)
	(segment
		(start 173.15307 -290.084764)
		(end 173.478952 -290.410646)
		(width 0.14478)
		(layer "In6.Cu")
		(net "M_K_CPU1_SB_DQ<7>")
	)
	(segment
		(start 184.182512 -289.415728)
		(end 184.182512 -289.331146)
		(width 0.14478)
		(layer "In6.Cu")
		(net "M_K_CPU1_SB_DQ<7>")
	)
	(segment
		(start 184.733946 -289.331146)
		(end 184.733946 -289.415728)
		(width 0.14478)
		(layer "In6.Cu")
		(net "M_K_CPU1_SB_DQ<7>")
	)
	(segment
		(start 189.647068 -289.560508)
		(end 189.935612 -289.271964)
		(width 0.14478)
		(layer "In6.Cu")
		(net "M_K_CPU1_SB_DQ<7>")
	)
	(segment
		(start 193.719196 -289.416744)
		(end 193.86296 -289.560508)
		(width 0.14478)
		(layer "In6.Cu")
		(net "M_K_CPU1_SB_DQ<7>")
	)
	(segment
		(start 147.409662 -278.05507)
		(end 148.042122 -278.05507)
		(width 0.0889)
		(layer "In6.Cu")
		(net "M_K_CPU1_SB_DQ<7>")
	)
	(segment
		(start 192.064894 -289.41649)
		(end 192.208658 -289.272726)
		(width 0.14478)
		(layer "In6.Cu")
		(net "M_K_CPU1_SB_DQ<7>")
	)
	(segment
		(start 147.22856 -278.236172)
		(end 147.409662 -278.05507)
		(width 0.0889)
		(layer "In6.Cu")
		(net "M_K_CPU1_SB_DQ<7>")
	)
	(segment
		(start 192.208658 -289.272726)
		(end 192.472564 -289.272726)
		(width 0.14478)
		(layer "In6.Cu")
		(net "M_K_CPU1_SB_DQ<7>")
	)
	(segment
		(start 193.575432 -289.272726)
		(end 193.719196 -289.41649)
		(width 0.14478)
		(layer "In6.Cu")
		(net "M_K_CPU1_SB_DQ<7>")
	)
	(segment
		(start 194.17919 -289.560508)
		(end 194.604132 -289.98545)
		(width 0.14478)
		(layer "In6.Cu")
		(net "M_K_CPU1_SB_DQ<7>")
	)
	(segment
		(start 192.064894 -289.416744)
		(end 192.064894 -289.41649)
		(width 0.14478)
		(layer "In6.Cu")
		(net "M_K_CPU1_SB_DQ<7>")
	)
	(segment
		(start 181.238144 -290.410646)
		(end 182.088282 -289.560508)
		(width 0.14478)
		(layer "In6.Cu")
		(net "M_K_CPU1_SB_DQ<7>")
	)
	(segment
		(start 152.113234 -278.05507)
		(end 164.46881 -290.410646)
		(width 0.14478)
		(layer "In6.Cu")
		(net "M_K_CPU1_SB_DQ<7>")
	)
	(segment
		(start 168.089072 -289.271964)
		(end 168.377616 -289.560508)
		(width 0.14478)
		(layer "In6.Cu")
		(net "M_K_CPU1_SB_DQ<7>")
	)
	(segment
		(start 193.86296 -289.560508)
		(end 194.17919 -289.560508)
		(width 0.14478)
		(layer "In6.Cu")
		(net "M_K_CPU1_SB_DQ<7>")
	)
	(segment
		(start 142.803372 -278.61895)
		(end 142.811754 -278.623776)
		(width 0.0889)
		(layer "In6.Cu")
		(net "M_K_CPU1_SB_DQ<7>")
	)
	(segment
		(start 144.317466 -278.623776)
		(end 144.325848 -278.61895)
		(width 0.0889)
		(layer "In6.Cu")
		(net "M_K_CPU1_SB_DQ<7>")
	)
	(segment
		(start 192.760092 -289.84829)
		(end 193.023998 -289.84829)
		(width 0.14478)
		(layer "In6.Cu")
		(net "M_K_CPU1_SB_DQ<7>")
	)
	(segment
		(start 177.726594 -289.560508)
		(end 178.576732 -290.410646)
		(width 0.14478)
		(layer "In6.Cu")
		(net "M_K_CPU1_SB_DQ<7>")
	)
	(segment
		(start 189.261496 -289.560508)
		(end 189.647068 -289.560508)
		(width 0.14478)
		(layer "In6.Cu")
		(net "M_K_CPU1_SB_DQ<7>")
	)
	(segment
		(start 168.93413 -289.271964)
		(end 169.2021 -289.271964)
		(width 0.14478)
		(layer "In6.Cu")
		(net "M_K_CPU1_SB_DQ<7>")
	)
	(segment
		(start 174.544228 -289.560508)
		(end 176.576482 -289.560508)
		(width 0.14478)
		(layer "In6.Cu")
		(net "M_K_CPU1_SB_DQ<7>")
	)
	(segment
		(start 192.616328 -289.704526)
		(end 192.760092 -289.84829)
		(width 0.14478)
		(layer "In6.Cu")
		(net "M_K_CPU1_SB_DQ<7>")
	)
	(segment
		(start 172.596556 -290.410646)
		(end 172.922438 -290.084764)
		(width 0.14478)
		(layer "In6.Cu")
		(net "M_K_CPU1_SB_DQ<7>")
	)
	(segment
		(start 193.167762 -289.41649)
		(end 193.311526 -289.272726)
		(width 0.14478)
		(layer "In6.Cu")
		(net "M_K_CPU1_SB_DQ<7>")
	)
	(segment
		(start 166.401242 -289.560508)
		(end 167.532558 -289.560508)
		(width 0.14478)
		(layer "In6.Cu")
		(net "M_K_CPU1_SB_DQ<7>")
	)
	(segment
		(start 165.551104 -290.410646)
		(end 166.401242 -289.560508)
		(width 0.14478)
		(layer "In6.Cu")
		(net "M_K_CPU1_SB_DQ<7>")
	)
	(segment
		(start 192.616328 -289.41649)
		(end 192.616328 -289.704526)
		(width 0.14478)
		(layer "In6.Cu")
		(net "M_K_CPU1_SB_DQ<7>")
	)
	(segment
		(start 144.307052 -278.629872)
		(end 144.317466 -278.623776)
		(width 0.0889)
		(layer "In6.Cu")
		(net "M_K_CPU1_SB_DQ<7>")
	)
	(segment
		(start 176.576482 -289.560508)
		(end 176.865026 -289.271964)
		(width 0.14478)
		(layer "In6.Cu")
		(net "M_K_CPU1_SB_DQ<7>")
	)
	(segment
		(start 173.69409 -290.410646)
		(end 174.544228 -289.560508)
		(width 0.14478)
		(layer "In6.Cu")
		(net "M_K_CPU1_SB_DQ<7>")
	)
	(segment
		(start 182.088282 -289.560508)
		(end 184.037732 -289.560508)
		(width 0.14478)
		(layer "In6.Cu")
		(net "M_K_CPU1_SB_DQ<7>")
	)
	(segment
		(start 184.733946 -289.415728)
		(end 184.878726 -289.560508)
		(width 0.14478)
		(layer "In6.Cu")
		(net "M_K_CPU1_SB_DQ<7>")
	)
	(segment
		(start 177.132996 -289.271964)
		(end 177.42154 -289.560508)
		(width 0.14478)
		(layer "In6.Cu")
		(net "M_K_CPU1_SB_DQ<7>")
	)
	(segment
		(start 177.42154 -289.560508)
		(end 177.726594 -289.560508)
		(width 0.14478)
		(layer "In6.Cu")
		(net "M_K_CPU1_SB_DQ<7>")
	)
	(segment
		(start 188.411612 -290.410392)
		(end 189.261496 -289.560508)
		(width 0.14478)
		(layer "In6.Cu")
		(net "M_K_CPU1_SB_DQ<7>")
	)
	(segment
		(start 143.377666 -278.623776)
		(end 143.386048 -278.61895)
		(width 0.0889)
		(layer "In6.Cu")
		(net "M_K_CPU1_SB_DQ<7>")
	)
	(segment
		(start 172.922438 -290.084764)
		(end 173.15307 -290.084764)
		(width 0.14478)
		(layer "In6.Cu")
		(net "M_K_CPU1_SB_DQ<7>")
	)
	(segment
		(start 189.935612 -289.271964)
		(end 190.203582 -289.271964)
		(width 0.14478)
		(layer "In6.Cu")
		(net "M_K_CPU1_SB_DQ<7>")
	)
	(segment
		(start 184.589166 -289.186366)
		(end 184.733946 -289.331146)
		(width 0.14478)
		(layer "In6.Cu")
		(net "M_K_CPU1_SB_DQ<7>")
	)
	(segment
		(start 169.490644 -289.560508)
		(end 170.18254 -289.560508)
		(width 0.14478)
		(layer "In6.Cu")
		(net "M_K_CPU1_SB_DQ<7>")
	)
	(segment
		(start 170.18254 -289.560508)
		(end 171.032678 -290.410646)
		(width 0.14478)
		(layer "In6.Cu")
		(net "M_K_CPU1_SB_DQ<7>")
	)
	(segment
		(start 164.46881 -290.410646)
		(end 165.551104 -290.410646)
		(width 0.14478)
		(layer "In6.Cu")
		(net "M_K_CPU1_SB_DQ<7>")
	)
	(segment
		(start 190.492126 -289.560508)
		(end 191.92113 -289.560508)
		(width 0.14478)
		(layer "In6.Cu")
		(net "M_K_CPU1_SB_DQ<7>")
	)
	(arc
		(start 141.8717 -278.623776)
		(mid 142.154656 -278.699953)
		(end 142.437612 -278.623776)
		(width 0.0889)
		(layer "In6.Cu")
		(net "M_K_CPU1_SB_DQ<7>")
	)
	(arc
		(start 144.325848 -278.61895)
		(mid 144.509102 -278.573577)
		(end 144.6911 -278.623776)
		(width 0.0889)
		(layer "In6.Cu")
		(net "M_K_CPU1_SB_DQ<7>")
	)
	(arc
		(start 143.751808 -278.623776)
		(mid 144.028621 -278.699919)
		(end 144.307052 -278.629872)
		(width 0.0889)
		(layer "In6.Cu")
		(net "M_K_CPU1_SB_DQ<7>")
	)
	(arc
		(start 143.386048 -278.61895)
		(mid 143.569556 -278.573456)
		(end 143.751808 -278.623776)
		(width 0.0889)
		(layer "In6.Cu")
		(net "M_K_CPU1_SB_DQ<7>")
	)
	(arc
		(start 142.437612 -278.623776)
		(mid 142.619863 -278.573426)
		(end 142.803372 -278.61895)
		(width 0.0889)
		(layer "In6.Cu")
		(net "M_K_CPU1_SB_DQ<7>")
	)
	(arc
		(start 142.811754 -278.623776)
		(mid 143.09471 -278.699953)
		(end 143.377666 -278.623776)
		(width 0.0889)
		(layer "In6.Cu")
		(net "M_K_CPU1_SB_DQ<7>")
	)
	(arc
		(start 145.257266 -278.623776)
		(mid 146.001457 -278.321171)
		(end 146.800316 -278.236172)
		(width 0.0889)
		(layer "In6.Cu")
		(net "M_K_CPU1_SB_DQ<7>")
	)
	(arc
		(start 144.701514 -278.629872)
		(mid 144.9802 -278.700092)
		(end 145.257266 -278.623776)
		(width 0.0889)
		(layer "In6.Cu")
		(net "M_K_CPU1_SB_DQ<7>")
	)
	(arc
		(start 141.553184 -278.597614)
		(mid 141.715373 -278.574879)
		(end 141.8717 -278.623776)
		(width 0.0889)
		(layer "In6.Cu")
		(net "M_K_CPU1_SB_DQ<7>")
	)
	(segment
		(start 142.627858 -277.870412)
		(end 143.09471 -278.13635)
		(width 0.10668)
		(layer "F.Cu")
		(net "M_K_CPU1_SB_DQ<6>")
	)
	(segment
		(start 185.861452 -288.71037)
		(end 187.601098 -288.71037)
		(width 0.14478)
		(layer "In6.Cu")
		(net "M_K_CPU1_SB_DQ<6>")
	)
	(segment
		(start 166.729918 -287.860486)
		(end 170.412156 -287.860486)
		(width 0.14478)
		(layer "In6.Cu")
		(net "M_K_CPU1_SB_DQ<6>")
	)
	(segment
		(start 180.748432 -288.710624)
		(end 181.238144 -288.710624)
		(width 0.14478)
		(layer "In6.Cu")
		(net "M_K_CPU1_SB_DQ<6>")
	)
	(segment
		(start 192.333626 -287.484566)
		(end 192.5955 -287.484566)
		(width 0.14478)
		(layer "In6.Cu")
		(net "M_K_CPU1_SB_DQ<6>")
	)
	(segment
		(start 191.492632 -287.860486)
		(end 191.637412 -288.005266)
		(width 0.14478)
		(layer "In6.Cu")
		(net "M_K_CPU1_SB_DQ<6>")
	)
	(segment
		(start 175.017938 -287.570164)
		(end 175.28413 -287.570164)
		(width 0.14478)
		(layer "In6.Cu")
		(net "M_K_CPU1_SB_DQ<6>")
	)
	(segment
		(start 173.69409 -288.710624)
		(end 174.544228 -287.860486)
		(width 0.14478)
		(layer "In6.Cu")
		(net "M_K_CPU1_SB_DQ<6>")
	)
	(segment
		(start 193.987928 -287.860486)
		(end 194.17919 -287.860486)
		(width 0.14478)
		(layer "In6.Cu")
		(net "M_K_CPU1_SB_DQ<6>")
	)
	(segment
		(start 182.088282 -287.860486)
		(end 185.011568 -287.860486)
		(width 0.14478)
		(layer "In6.Cu")
		(net "M_K_CPU1_SB_DQ<6>")
	)
	(segment
		(start 193.698368 -287.484566)
		(end 193.843148 -287.629346)
		(width 0.14478)
		(layer "In6.Cu")
		(net "M_K_CPU1_SB_DQ<6>")
	)
	(segment
		(start 192.74028 -287.629346)
		(end 192.74028 -288.091626)
		(width 0.14478)
		(layer "In6.Cu")
		(net "M_K_CPU1_SB_DQ<6>")
	)
	(segment
		(start 144.213326 -277.808944)
		(end 144.221708 -277.81377)
		(width 0.0889)
		(layer "In6.Cu")
		(net "M_K_CPU1_SB_DQ<6>")
	)
	(segment
		(start 188.157612 -288.433764)
		(end 188.434218 -288.71037)
		(width 0.14478)
		(layer "In6.Cu")
		(net "M_K_CPU1_SB_DQ<6>")
	)
	(segment
		(start 147.998434 -277.14575)
		(end 152.550368 -277.14575)
		(width 0.14478)
		(layer "In6.Cu")
		(net "M_K_CPU1_SB_DQ<6>")
	)
	(segment
		(start 192.188846 -287.629346)
		(end 192.333626 -287.484566)
		(width 0.14478)
		(layer "In6.Cu")
		(net "M_K_CPU1_SB_DQ<6>")
	)
	(segment
		(start 165.678104 -288.710624)
		(end 165.87978 -288.710624)
		(width 0.14478)
		(layer "In6.Cu")
		(net "M_K_CPU1_SB_DQ<6>")
	)
	(segment
		(start 192.74028 -288.091626)
		(end 192.88506 -288.236406)
		(width 0.14478)
		(layer "In6.Cu")
		(net "M_K_CPU1_SB_DQ<6>")
	)
	(segment
		(start 194.17919 -287.860486)
		(end 194.604132 -288.285428)
		(width 0.14478)
		(layer "In6.Cu")
		(net "M_K_CPU1_SB_DQ<6>")
	)
	(segment
		(start 144.221708 -277.81377)
		(end 144.232122 -277.819866)
		(width 0.0889)
		(layer "In6.Cu")
		(net "M_K_CPU1_SB_DQ<6>")
	)
	(segment
		(start 152.550368 -277.14575)
		(end 163.812982 -288.408364)
		(width 0.14478)
		(layer "In6.Cu")
		(net "M_K_CPU1_SB_DQ<6>")
	)
	(segment
		(start 189.516004 -287.860486)
		(end 189.951106 -287.860486)
		(width 0.14478)
		(layer "In6.Cu")
		(net "M_K_CPU1_SB_DQ<6>")
	)
	(segment
		(start 143.09471 -278.13635)
		(end 142.940786 -277.87092)
		(width 0.0889)
		(layer "In6.Cu")
		(net "M_K_CPU1_SB_DQ<6>")
	)
	(segment
		(start 176.967134 -287.570164)
		(end 177.233326 -287.570164)
		(width 0.14478)
		(layer "In6.Cu")
		(net "M_K_CPU1_SB_DQ<6>")
	)
	(segment
		(start 180.471572 -288.433764)
		(end 180.748432 -288.710624)
		(width 0.14478)
		(layer "In6.Cu")
		(net "M_K_CPU1_SB_DQ<6>")
	)
	(segment
		(start 174.727616 -287.860486)
		(end 175.017938 -287.570164)
		(width 0.14478)
		(layer "In6.Cu")
		(net "M_K_CPU1_SB_DQ<6>")
	)
	(segment
		(start 190.50762 -287.570164)
		(end 190.797942 -287.860486)
		(width 0.14478)
		(layer "In6.Cu")
		(net "M_K_CPU1_SB_DQ<6>")
	)
	(segment
		(start 164.81933 -288.710624)
		(end 165.12159 -288.408364)
		(width 0.14478)
		(layer "In6.Cu")
		(net "M_K_CPU1_SB_DQ<6>")
	)
	(segment
		(start 171.262294 -288.710624)
		(end 172.678852 -288.710624)
		(width 0.14478)
		(layer "In6.Cu")
		(net "M_K_CPU1_SB_DQ<6>")
	)
	(segment
		(start 188.434218 -288.71037)
		(end 188.66612 -288.71037)
		(width 0.14478)
		(layer "In6.Cu")
		(net "M_K_CPU1_SB_DQ<6>")
	)
	(segment
		(start 177.612802 -287.860486)
		(end 178.46294 -288.710624)
		(width 0.14478)
		(layer "In6.Cu")
		(net "M_K_CPU1_SB_DQ<6>")
	)
	(segment
		(start 177.523648 -287.860486)
		(end 177.612802 -287.860486)
		(width 0.14478)
		(layer "In6.Cu")
		(net "M_K_CPU1_SB_DQ<6>")
	)
	(segment
		(start 193.291714 -287.629346)
		(end 193.436494 -287.484566)
		(width 0.14478)
		(layer "In6.Cu")
		(net "M_K_CPU1_SB_DQ<6>")
	)
	(segment
		(start 145.855436 -277.746714)
		(end 145.94078 -277.66772)
		(width 0.0889)
		(layer "In6.Cu")
		(net "M_K_CPU1_SB_DQ<6>")
	)
	(segment
		(start 173.537626 -288.710624)
		(end 173.69409 -288.710624)
		(width 0.14478)
		(layer "In6.Cu")
		(net "M_K_CPU1_SB_DQ<6>")
	)
	(segment
		(start 176.676812 -287.860486)
		(end 176.967134 -287.570164)
		(width 0.14478)
		(layer "In6.Cu")
		(net "M_K_CPU1_SB_DQ<6>")
	)
	(segment
		(start 147.568666 -276.993604)
		(end 147.720812 -277.14575)
		(width 0.0889)
		(layer "In6.Cu")
		(net "M_K_CPU1_SB_DQ<6>")
	)
	(segment
		(start 177.233326 -287.570164)
		(end 177.523648 -287.860486)
		(width 0.14478)
		(layer "In6.Cu")
		(net "M_K_CPU1_SB_DQ<6>")
	)
	(segment
		(start 181.238144 -288.710624)
		(end 182.088282 -287.860486)
		(width 0.14478)
		(layer "In6.Cu")
		(net "M_K_CPU1_SB_DQ<6>")
	)
	(segment
		(start 180.191918 -288.433764)
		(end 180.471572 -288.433764)
		(width 0.14478)
		(layer "In6.Cu")
		(net "M_K_CPU1_SB_DQ<6>")
	)
	(segment
		(start 191.637412 -288.091626)
		(end 191.782192 -288.236406)
		(width 0.14478)
		(layer "In6.Cu")
		(net "M_K_CPU1_SB_DQ<6>")
	)
	(segment
		(start 142.940786 -277.87092)
		(end 142.963138 -277.787608)
		(width 0.0889)
		(layer "In6.Cu")
		(net "M_K_CPU1_SB_DQ<6>")
	)
	(segment
		(start 179.915058 -288.710624)
		(end 180.191918 -288.433764)
		(width 0.14478)
		(layer "In6.Cu")
		(net "M_K_CPU1_SB_DQ<6>")
	)
	(segment
		(start 174.544228 -287.860486)
		(end 174.727616 -287.860486)
		(width 0.14478)
		(layer "In6.Cu")
		(net "M_K_CPU1_SB_DQ<6>")
	)
	(segment
		(start 188.66612 -288.71037)
		(end 189.516004 -287.860486)
		(width 0.14478)
		(layer "In6.Cu")
		(net "M_K_CPU1_SB_DQ<6>")
	)
	(segment
		(start 172.678852 -288.710624)
		(end 172.981112 -288.408364)
		(width 0.14478)
		(layer "In6.Cu")
		(net "M_K_CPU1_SB_DQ<6>")
	)
	(segment
		(start 190.241428 -287.570164)
		(end 190.50762 -287.570164)
		(width 0.14478)
		(layer "In6.Cu")
		(net "M_K_CPU1_SB_DQ<6>")
	)
	(segment
		(start 178.46294 -288.710624)
		(end 179.915058 -288.710624)
		(width 0.14478)
		(layer "In6.Cu")
		(net "M_K_CPU1_SB_DQ<6>")
	)
	(segment
		(start 187.877704 -288.433764)
		(end 188.157612 -288.433764)
		(width 0.14478)
		(layer "In6.Cu")
		(net "M_K_CPU1_SB_DQ<6>")
	)
	(segment
		(start 147.720812 -277.14575)
		(end 147.998434 -277.14575)
		(width 0.0889)
		(layer "In6.Cu")
		(net "M_K_CPU1_SB_DQ<6>")
	)
	(segment
		(start 191.637412 -288.005266)
		(end 191.637412 -288.091626)
		(width 0.14478)
		(layer "In6.Cu")
		(net "M_K_CPU1_SB_DQ<6>")
	)
	(segment
		(start 144.787366 -277.81377)
		(end 144.795748 -277.808944)
		(width 0.0889)
		(layer "In6.Cu")
		(net "M_K_CPU1_SB_DQ<6>")
	)
	(segment
		(start 190.797942 -287.860486)
		(end 191.492632 -287.860486)
		(width 0.14478)
		(layer "In6.Cu")
		(net "M_K_CPU1_SB_DQ<6>")
	)
	(segment
		(start 175.574452 -287.860486)
		(end 176.676812 -287.860486)
		(width 0.14478)
		(layer "In6.Cu")
		(net "M_K_CPU1_SB_DQ<6>")
	)
	(segment
		(start 193.843148 -287.629346)
		(end 193.843148 -287.715706)
		(width 0.14478)
		(layer "In6.Cu")
		(net "M_K_CPU1_SB_DQ<6>")
	)
	(segment
		(start 192.044066 -288.236406)
		(end 192.188846 -288.091626)
		(width 0.14478)
		(layer "In6.Cu")
		(net "M_K_CPU1_SB_DQ<6>")
	)
	(segment
		(start 185.011568 -287.860486)
		(end 185.861452 -288.71037)
		(width 0.14478)
		(layer "In6.Cu")
		(net "M_K_CPU1_SB_DQ<6>")
	)
	(segment
		(start 170.412156 -287.860486)
		(end 171.262294 -288.710624)
		(width 0.14478)
		(layer "In6.Cu")
		(net "M_K_CPU1_SB_DQ<6>")
	)
	(segment
		(start 193.146934 -288.236406)
		(end 193.291714 -288.091626)
		(width 0.14478)
		(layer "In6.Cu")
		(net "M_K_CPU1_SB_DQ<6>")
	)
	(segment
		(start 163.812982 -288.408364)
		(end 164.262816 -288.408364)
		(width 0.14478)
		(layer "In6.Cu")
		(net "M_K_CPU1_SB_DQ<6>")
	)
	(segment
		(start 165.12159 -288.408364)
		(end 165.375844 -288.408364)
		(width 0.14478)
		(layer "In6.Cu")
		(net "M_K_CPU1_SB_DQ<6>")
	)
	(segment
		(start 192.188846 -288.091626)
		(end 192.188846 -287.629346)
		(width 0.14478)
		(layer "In6.Cu")
		(net "M_K_CPU1_SB_DQ<6>")
	)
	(segment
		(start 189.951106 -287.860486)
		(end 190.241428 -287.570164)
		(width 0.14478)
		(layer "In6.Cu")
		(net "M_K_CPU1_SB_DQ<6>")
	)
	(segment
		(start 165.87978 -288.710624)
		(end 166.729918 -287.860486)
		(width 0.14478)
		(layer "In6.Cu")
		(net "M_K_CPU1_SB_DQ<6>")
	)
	(segment
		(start 187.601098 -288.71037)
		(end 187.877704 -288.433764)
		(width 0.14478)
		(layer "In6.Cu")
		(net "M_K_CPU1_SB_DQ<6>")
	)
	(segment
		(start 164.565076 -288.710624)
		(end 164.81933 -288.710624)
		(width 0.14478)
		(layer "In6.Cu")
		(net "M_K_CPU1_SB_DQ<6>")
	)
	(segment
		(start 193.843148 -287.715706)
		(end 193.987928 -287.860486)
		(width 0.14478)
		(layer "In6.Cu")
		(net "M_K_CPU1_SB_DQ<6>")
	)
	(segment
		(start 193.436494 -287.484566)
		(end 193.698368 -287.484566)
		(width 0.14478)
		(layer "In6.Cu")
		(net "M_K_CPU1_SB_DQ<6>")
	)
	(segment
		(start 164.262816 -288.408364)
		(end 164.565076 -288.710624)
		(width 0.14478)
		(layer "In6.Cu")
		(net "M_K_CPU1_SB_DQ<6>")
	)
	(segment
		(start 192.88506 -288.236406)
		(end 193.146934 -288.236406)
		(width 0.14478)
		(layer "In6.Cu")
		(net "M_K_CPU1_SB_DQ<6>")
	)
	(segment
		(start 172.981112 -288.408364)
		(end 173.235366 -288.408364)
		(width 0.14478)
		(layer "In6.Cu")
		(net "M_K_CPU1_SB_DQ<6>")
	)
	(segment
		(start 193.291714 -288.091626)
		(end 193.291714 -287.629346)
		(width 0.14478)
		(layer "In6.Cu")
		(net "M_K_CPU1_SB_DQ<6>")
	)
	(segment
		(start 173.235366 -288.408364)
		(end 173.537626 -288.710624)
		(width 0.14478)
		(layer "In6.Cu")
		(net "M_K_CPU1_SB_DQ<6>")
	)
	(segment
		(start 192.5955 -287.484566)
		(end 192.74028 -287.629346)
		(width 0.14478)
		(layer "In6.Cu")
		(net "M_K_CPU1_SB_DQ<6>")
	)
	(segment
		(start 175.28413 -287.570164)
		(end 175.574452 -287.860486)
		(width 0.14478)
		(layer "In6.Cu")
		(net "M_K_CPU1_SB_DQ<6>")
	)
	(segment
		(start 191.782192 -288.236406)
		(end 192.044066 -288.236406)
		(width 0.14478)
		(layer "In6.Cu")
		(net "M_K_CPU1_SB_DQ<6>")
	)
	(segment
		(start 165.375844 -288.408364)
		(end 165.678104 -288.710624)
		(width 0.14478)
		(layer "In6.Cu")
		(net "M_K_CPU1_SB_DQ<6>")
	)
	(segment
		(start 146.358356 -276.993604)
		(end 147.568666 -276.993604)
		(width 0.0889)
		(layer "In6.Cu")
		(net "M_K_CPU1_SB_DQ<6>")
	)
	(arc
		(start 142.963138 -277.787608)
		(mid 143.125327 -277.764873)
		(end 143.281654 -277.81377)
		(width 0.0889)
		(layer "In6.Cu")
		(net "M_K_CPU1_SB_DQ<6>")
	)
	(arc
		(start 144.232122 -277.819866)
		(mid 144.510554 -277.889964)
		(end 144.787366 -277.81377)
		(width 0.0889)
		(layer "In6.Cu")
		(net "M_K_CPU1_SB_DQ<6>")
	)
	(arc
		(start 145.94078 -277.66772)
		(mid 146.039602 -277.5241)
		(end 146.067526 -277.351998)
		(width 0.0889)
		(layer "In6.Cu")
		(net "M_K_CPU1_SB_DQ<6>")
	)
	(arc
		(start 143.847566 -277.81377)
		(mid 144.029817 -277.76342)
		(end 144.213326 -277.808944)
		(width 0.0889)
		(layer "In6.Cu")
		(net "M_K_CPU1_SB_DQ<6>")
	)
	(arc
		(start 145.494502 -277.89632)
		(mid 145.688324 -277.853737)
		(end 145.855436 -277.746714)
		(width 0.0889)
		(layer "In6.Cu")
		(net "M_K_CPU1_SB_DQ<6>")
	)
	(arc
		(start 144.795748 -277.808944)
		(mid 144.979256 -277.76345)
		(end 145.161508 -277.81377)
		(width 0.0889)
		(layer "In6.Cu")
		(net "M_K_CPU1_SB_DQ<6>")
	)
	(arc
		(start 145.161508 -277.81377)
		(mid 145.322127 -277.878772)
		(end 145.494502 -277.89632)
		(width 0.0889)
		(layer "In6.Cu")
		(net "M_K_CPU1_SB_DQ<6>")
	)
	(arc
		(start 146.067526 -277.351998)
		(mid 146.090272 -277.216342)
		(end 146.170142 -277.104348)
		(width 0.0889)
		(layer "In6.Cu")
		(net "M_K_CPU1_SB_DQ<6>")
	)
	(arc
		(start 146.170142 -277.104348)
		(mid 146.258904 -277.039892)
		(end 146.358356 -276.993604)
		(width 0.0889)
		(layer "In6.Cu")
		(net "M_K_CPU1_SB_DQ<6>")
	)
	(arc
		(start 143.281654 -277.81377)
		(mid 143.56461 -277.889947)
		(end 143.847566 -277.81377)
		(width 0.0889)
		(layer "In6.Cu")
		(net "M_K_CPU1_SB_DQ<6>")
	)
	(segment
		(start 140.748004 -277.870412)
		(end 141.214856 -278.13635)
		(width 0.10668)
		(layer "F.Cu")
		(net "M_K_CPU1_SB_DQ<5>")
	)
	(segment
		(start 182.180992 -288.710624)
		(end 185.051192 -288.710624)
		(width 0.14478)
		(layer "In6.Cu")
		(net "M_K_CPU1_SB_DQ<5>")
	)
	(segment
		(start 148.003006 -277.60041)
		(end 152.301956 -277.60041)
		(width 0.14478)
		(layer "In6.Cu")
		(net "M_K_CPU1_SB_DQ<5>")
	)
	(segment
		(start 173.787054 -289.560508)
		(end 174.636938 -288.710624)
		(width 0.14478)
		(layer "In6.Cu")
		(net "M_K_CPU1_SB_DQ<5>")
	)
	(segment
		(start 167.204644 -288.710624)
		(end 169.718228 -288.710624)
		(width 0.14478)
		(layer "In6.Cu")
		(net "M_K_CPU1_SB_DQ<5>")
	)
	(segment
		(start 144.787112 -278.45893)
		(end 144.798796 -278.465788)
		(width 0.0889)
		(layer "In6.Cu")
		(net "M_K_CPU1_SB_DQ<5>")
	)
	(segment
		(start 174.636938 -288.710624)
		(end 177.66157 -288.710624)
		(width 0.14478)
		(layer "In6.Cu")
		(net "M_K_CPU1_SB_DQ<5>")
	)
	(segment
		(start 185.051192 -288.710624)
		(end 185.901076 -289.560508)
		(width 0.14478)
		(layer "In6.Cu")
		(net "M_K_CPU1_SB_DQ<5>")
	)
	(segment
		(start 178.511454 -289.560508)
		(end 181.331108 -289.560508)
		(width 0.14478)
		(layer "In6.Cu")
		(net "M_K_CPU1_SB_DQ<5>")
	)
	(segment
		(start 141.967712 -278.45893)
		(end 141.976094 -278.463756)
		(width 0.0889)
		(layer "In6.Cu")
		(net "M_K_CPU1_SB_DQ<5>")
	)
	(segment
		(start 171.77004 -289.560508)
		(end 173.787054 -289.560508)
		(width 0.14478)
		(layer "In6.Cu")
		(net "M_K_CPU1_SB_DQ<5>")
	)
	(segment
		(start 165.152832 -289.560508)
		(end 167.204644 -288.710624)
		(width 0.14478)
		(layer "In6.Cu")
		(net "M_K_CPU1_SB_DQ<5>")
	)
	(segment
		(start 164.262054 -289.560508)
		(end 165.152832 -289.560508)
		(width 0.14478)
		(layer "In6.Cu")
		(net "M_K_CPU1_SB_DQ<5>")
	)
	(segment
		(start 169.718228 -288.710624)
		(end 171.77004 -289.560508)
		(width 0.14478)
		(layer "In6.Cu")
		(net "M_K_CPU1_SB_DQ<5>")
	)
	(segment
		(start 144.221454 -278.45893)
		(end 144.231868 -278.452834)
		(width 0.0889)
		(layer "In6.Cu")
		(net "M_K_CPU1_SB_DQ<5>")
	)
	(segment
		(start 196.568822 -288.710624)
		(end 198.7042 -289.135312)
		(width 0.14478)
		(layer "In6.Cu")
		(net "M_K_CPU1_SB_DQ<5>")
	)
	(segment
		(start 187.83173 -289.560508)
		(end 189.883796 -288.710624)
		(width 0.14478)
		(layer "In6.Cu")
		(net "M_K_CPU1_SB_DQ<5>")
	)
	(segment
		(start 189.883796 -288.710624)
		(end 196.568822 -288.710624)
		(width 0.14478)
		(layer "In6.Cu")
		(net "M_K_CPU1_SB_DQ<5>")
	)
	(segment
		(start 147.548092 -277.60041)
		(end 148.003006 -277.60041)
		(width 0.0889)
		(layer "In6.Cu")
		(net "M_K_CPU1_SB_DQ<5>")
	)
	(segment
		(start 185.901076 -289.560508)
		(end 187.83173 -289.560508)
		(width 0.14478)
		(layer "In6.Cu")
		(net "M_K_CPU1_SB_DQ<5>")
	)
	(segment
		(start 152.301956 -277.60041)
		(end 164.262054 -289.560508)
		(width 0.14478)
		(layer "In6.Cu")
		(net "M_K_CPU1_SB_DQ<5>")
	)
	(segment
		(start 141.36878 -278.40178)
		(end 141.464792 -278.42718)
		(width 0.0889)
		(layer "In6.Cu")
		(net "M_K_CPU1_SB_DQ<5>")
	)
	(segment
		(start 177.66157 -288.710624)
		(end 178.511454 -289.560508)
		(width 0.14478)
		(layer "In6.Cu")
		(net "M_K_CPU1_SB_DQ<5>")
	)
	(segment
		(start 146.815302 -277.506684)
		(end 147.454366 -277.506684)
		(width 0.0889)
		(layer "In6.Cu")
		(net "M_K_CPU1_SB_DQ<5>")
	)
	(segment
		(start 144.20977 -278.465788)
		(end 144.221454 -278.45893)
		(width 0.0889)
		(layer "In6.Cu")
		(net "M_K_CPU1_SB_DQ<5>")
	)
	(segment
		(start 147.454366 -277.506684)
		(end 147.548092 -277.60041)
		(width 0.0889)
		(layer "In6.Cu")
		(net "M_K_CPU1_SB_DQ<5>")
	)
	(segment
		(start 181.331108 -289.560508)
		(end 182.180992 -288.710624)
		(width 0.14478)
		(layer "In6.Cu")
		(net "M_K_CPU1_SB_DQ<5>")
	)
	(segment
		(start 141.214856 -278.13635)
		(end 141.36878 -278.40178)
		(width 0.0889)
		(layer "In6.Cu")
		(net "M_K_CPU1_SB_DQ<5>")
	)
	(segment
		(start 145.161508 -278.45893)
		(end 146.815302 -277.506684)
		(width 0.0889)
		(layer "In6.Cu")
		(net "M_K_CPU1_SB_DQ<5>")
	)
	(arc
		(start 143.281654 -278.45893)
		(mid 143.56461 -278.382753)
		(end 143.847566 -278.45893)
		(width 0.0889)
		(layer "In6.Cu")
		(net "M_K_CPU1_SB_DQ<5>")
	)
	(arc
		(start 141.976094 -278.463756)
		(mid 142.159602 -278.50925)
		(end 142.341854 -278.45893)
		(width 0.0889)
		(layer "In6.Cu")
		(net "M_K_CPU1_SB_DQ<5>")
	)
	(arc
		(start 143.847566 -278.45893)
		(mid 144.027771 -278.509247)
		(end 144.20977 -278.465788)
		(width 0.0889)
		(layer "In6.Cu")
		(net "M_K_CPU1_SB_DQ<5>")
	)
	(arc
		(start 142.341854 -278.45893)
		(mid 142.62481 -278.382753)
		(end 142.907766 -278.45893)
		(width 0.0889)
		(layer "In6.Cu")
		(net "M_K_CPU1_SB_DQ<5>")
	)
	(arc
		(start 144.231868 -278.452834)
		(mid 144.5103 -278.382736)
		(end 144.787112 -278.45893)
		(width 0.0889)
		(layer "In6.Cu")
		(net "M_K_CPU1_SB_DQ<5>")
	)
	(arc
		(start 144.798796 -278.465788)
		(mid 144.981051 -278.509441)
		(end 145.161508 -278.45893)
		(width 0.0889)
		(layer "In6.Cu")
		(net "M_K_CPU1_SB_DQ<5>")
	)
	(arc
		(start 141.464792 -278.42718)
		(mid 141.72 -278.383703)
		(end 141.967712 -278.45893)
		(width 0.0889)
		(layer "In6.Cu")
		(net "M_K_CPU1_SB_DQ<5>")
	)
	(arc
		(start 142.907766 -278.45893)
		(mid 143.09471 -278.509185)
		(end 143.281654 -278.45893)
		(width 0.0889)
		(layer "In6.Cu")
		(net "M_K_CPU1_SB_DQ<5>")
	)
	(segment
		(start 142.157958 -277.060406)
		(end 142.62481 -277.326344)
		(width 0.10668)
		(layer "F.Cu")
		(net "M_K_CPU1_SB_DQ<4>")
	)
	(segment
		(start 178.30038 -287.869884)
		(end 181.32171 -287.869884)
		(width 0.14478)
		(layer "In6.Cu")
		(net "M_K_CPU1_SB_DQ<4>")
	)
	(segment
		(start 148.031708 -276.69109)
		(end 152.738836 -276.69109)
		(width 0.14478)
		(layer "In6.Cu")
		(net "M_K_CPU1_SB_DQ<4>")
	)
	(segment
		(start 177.450496 -287.02)
		(end 178.30038 -287.869884)
		(width 0.14478)
		(layer "In6.Cu")
		(net "M_K_CPU1_SB_DQ<4>")
	)
	(segment
		(start 166.501064 -287.403286)
		(end 170.623484 -287.403286)
		(width 0.14478)
		(layer "In6.Cu")
		(net "M_K_CPU1_SB_DQ<4>")
	)
	(segment
		(start 173.777656 -287.869884)
		(end 174.62754 -287.02)
		(width 0.14478)
		(layer "In6.Cu")
		(net "M_K_CPU1_SB_DQ<4>")
	)
	(segment
		(start 197.703948 -287.019746)
		(end 198.288656 -287.019746)
		(width 0.14478)
		(layer "In6.Cu")
		(net "M_K_CPU1_SB_DQ<4>")
	)
	(segment
		(start 143.377666 -277.648924)
		(end 143.386048 -277.65375)
		(width 0.0889)
		(layer "In6.Cu")
		(net "M_K_CPU1_SB_DQ<4>")
	)
	(segment
		(start 144.691354 -277.648924)
		(end 144.701768 -277.642828)
		(width 0.0889)
		(layer "In6.Cu")
		(net "M_K_CPU1_SB_DQ<4>")
	)
	(segment
		(start 185.856626 -287.869884)
		(end 188.701934 -287.869884)
		(width 0.14478)
		(layer "In6.Cu")
		(net "M_K_CPU1_SB_DQ<4>")
	)
	(segment
		(start 197.007734 -287.164526)
		(end 197.007734 -287.385506)
		(width 0.14478)
		(layer "In6.Cu")
		(net "M_K_CPU1_SB_DQ<4>")
	)
	(segment
		(start 152.738836 -276.69109)
		(end 163.908232 -287.860486)
		(width 0.14478)
		(layer "In6.Cu")
		(net "M_K_CPU1_SB_DQ<4>")
	)
	(segment
		(start 188.701934 -287.869884)
		(end 189.552072 -287.019746)
		(width 0.14478)
		(layer "In6.Cu")
		(net "M_K_CPU1_SB_DQ<4>")
	)
	(segment
		(start 163.908232 -287.860486)
		(end 166.043864 -287.860486)
		(width 0.14478)
		(layer "In6.Cu")
		(net "M_K_CPU1_SB_DQ<4>")
	)
	(segment
		(start 147.370546 -276.711664)
		(end 147.39112 -276.69109)
		(width 0.0889)
		(layer "In6.Cu")
		(net "M_K_CPU1_SB_DQ<4>")
	)
	(segment
		(start 170.623484 -287.403286)
		(end 171.090082 -287.869884)
		(width 0.14478)
		(layer "In6.Cu")
		(net "M_K_CPU1_SB_DQ<4>")
	)
	(segment
		(start 146.47291 -276.711664)
		(end 147.370546 -276.711664)
		(width 0.0889)
		(layer "In6.Cu")
		(net "M_K_CPU1_SB_DQ<4>")
	)
	(segment
		(start 197.414388 -287.530286)
		(end 197.559168 -287.385506)
		(width 0.14478)
		(layer "In6.Cu")
		(net "M_K_CPU1_SB_DQ<4>")
	)
	(segment
		(start 142.778734 -277.591774)
		(end 142.874746 -277.617174)
		(width 0.0889)
		(layer "In6.Cu")
		(net "M_K_CPU1_SB_DQ<4>")
	)
	(segment
		(start 174.62754 -287.02)
		(end 177.450496 -287.02)
		(width 0.14478)
		(layer "In6.Cu")
		(net "M_K_CPU1_SB_DQ<4>")
	)
	(segment
		(start 198.288656 -287.019746)
		(end 198.7042 -287.43529)
		(width 0.14478)
		(layer "In6.Cu")
		(net "M_K_CPU1_SB_DQ<4>")
	)
	(segment
		(start 144.307052 -277.642828)
		(end 144.317466 -277.648924)
		(width 0.0889)
		(layer "In6.Cu")
		(net "M_K_CPU1_SB_DQ<4>")
	)
	(segment
		(start 196.862954 -287.019746)
		(end 197.007734 -287.164526)
		(width 0.14478)
		(layer "In6.Cu")
		(net "M_K_CPU1_SB_DQ<4>")
	)
	(segment
		(start 145.849086 -277.257764)
		(end 145.936208 -277.05431)
		(width 0.0889)
		(layer "In6.Cu")
		(net "M_K_CPU1_SB_DQ<4>")
	)
	(segment
		(start 197.007734 -287.385506)
		(end 197.152514 -287.530286)
		(width 0.14478)
		(layer "In6.Cu")
		(net "M_K_CPU1_SB_DQ<4>")
	)
	(segment
		(start 171.090082 -287.869884)
		(end 173.777656 -287.869884)
		(width 0.14478)
		(layer "In6.Cu")
		(net "M_K_CPU1_SB_DQ<4>")
	)
	(segment
		(start 181.32171 -287.869884)
		(end 182.171594 -287.02)
		(width 0.14478)
		(layer "In6.Cu")
		(net "M_K_CPU1_SB_DQ<4>")
	)
	(segment
		(start 197.559168 -287.385506)
		(end 197.559168 -287.164526)
		(width 0.14478)
		(layer "In6.Cu")
		(net "M_K_CPU1_SB_DQ<4>")
	)
	(segment
		(start 166.043864 -287.860486)
		(end 166.501064 -287.403286)
		(width 0.14478)
		(layer "In6.Cu")
		(net "M_K_CPU1_SB_DQ<4>")
	)
	(segment
		(start 189.552072 -287.019746)
		(end 196.862954 -287.019746)
		(width 0.14478)
		(layer "In6.Cu")
		(net "M_K_CPU1_SB_DQ<4>")
	)
	(segment
		(start 147.39112 -276.69109)
		(end 148.031708 -276.69109)
		(width 0.0889)
		(layer "In6.Cu")
		(net "M_K_CPU1_SB_DQ<4>")
	)
	(segment
		(start 197.152514 -287.530286)
		(end 197.414388 -287.530286)
		(width 0.14478)
		(layer "In6.Cu")
		(net "M_K_CPU1_SB_DQ<4>")
	)
	(segment
		(start 182.171594 -287.02)
		(end 185.006742 -287.02)
		(width 0.14478)
		(layer "In6.Cu")
		(net "M_K_CPU1_SB_DQ<4>")
	)
	(segment
		(start 142.62481 -277.326344)
		(end 142.778734 -277.591774)
		(width 0.0889)
		(layer "In6.Cu")
		(net "M_K_CPU1_SB_DQ<4>")
	)
	(segment
		(start 185.006742 -287.02)
		(end 185.856626 -287.869884)
		(width 0.14478)
		(layer "In6.Cu")
		(net "M_K_CPU1_SB_DQ<4>")
	)
	(segment
		(start 197.559168 -287.164526)
		(end 197.703948 -287.019746)
		(width 0.14478)
		(layer "In6.Cu")
		(net "M_K_CPU1_SB_DQ<4>")
	)
	(arc
		(start 142.874746 -277.617174)
		(mid 143.129954 -277.573697)
		(end 143.377666 -277.648924)
		(width 0.0889)
		(layer "In6.Cu")
		(net "M_K_CPU1_SB_DQ<4>")
	)
	(arc
		(start 146.088608 -276.870922)
		(mid 146.267328 -276.758872)
		(end 146.47291 -276.711664)
		(width 0.0889)
		(layer "In6.Cu")
		(net "M_K_CPU1_SB_DQ<4>")
	)
	(arc
		(start 145.936208 -277.05431)
		(mid 145.959723 -277.00973)
		(end 145.990056 -276.969474)
		(width 0.0889)
		(layer "In6.Cu")
		(net "M_K_CPU1_SB_DQ<4>")
	)
	(arc
		(start 143.751808 -277.648924)
		(mid 144.028621 -277.572781)
		(end 144.307052 -277.642828)
		(width 0.0889)
		(layer "In6.Cu")
		(net "M_K_CPU1_SB_DQ<4>")
	)
	(arc
		(start 145.248376 -277.64359)
		(mid 145.610761 -277.651538)
		(end 145.821654 -277.356824)
		(width 0.0889)
		(layer "In6.Cu")
		(net "M_K_CPU1_SB_DQ<4>")
	)
	(arc
		(start 145.821654 -277.356824)
		(mid 145.832045 -277.306373)
		(end 145.849086 -277.257764)
		(width 0.0889)
		(layer "In6.Cu")
		(net "M_K_CPU1_SB_DQ<4>")
	)
	(arc
		(start 143.386048 -277.65375)
		(mid 143.569556 -277.699244)
		(end 143.751808 -277.648924)
		(width 0.0889)
		(layer "In6.Cu")
		(net "M_K_CPU1_SB_DQ<4>")
	)
	(arc
		(start 144.701768 -277.642828)
		(mid 144.975161 -277.572575)
		(end 145.248376 -277.64359)
		(width 0.0889)
		(layer "In6.Cu")
		(net "M_K_CPU1_SB_DQ<4>")
	)
	(arc
		(start 144.317466 -277.648924)
		(mid 144.50441 -277.699179)
		(end 144.691354 -277.648924)
		(width 0.0889)
		(layer "In6.Cu")
		(net "M_K_CPU1_SB_DQ<4>")
	)
	(arc
		(start 145.990056 -276.969474)
		(mid 146.037891 -276.918757)
		(end 146.088608 -276.870922)
		(width 0.0889)
		(layer "In6.Cu")
		(net "M_K_CPU1_SB_DQ<4>")
	)
	(segment
		(start 141.217904 -275.440394)
		(end 141.684756 -275.706332)
		(width 0.10668)
		(layer "F.Cu")
		(net "M_K_CPU1_SB_DQ<3>")
	)
	(segment
		(start 170.663108 -283.328364)
		(end 170.761406 -283.426662)
		(width 0.14478)
		(layer "In6.Cu")
		(net "M_K_CPU1_SB_DQ<3>")
	)
	(segment
		(start 186.111388 -284.451044)
		(end 188.148214 -284.451044)
		(width 0.14478)
		(layer "In6.Cu")
		(net "M_K_CPU1_SB_DQ<3>")
	)
	(segment
		(start 145.981928 -275.039836)
		(end 146.06524 -274.98167)
		(width 0.0889)
		(layer "In6.Cu")
		(net "M_K_CPU1_SB_DQ<3>")
	)
	(segment
		(start 194.17919 -283.610304)
		(end 194.604132 -284.035246)
		(width 0.14478)
		(layer "In6.Cu")
		(net "M_K_CPU1_SB_DQ<3>")
	)
	(segment
		(start 193.707004 -283.328364)
		(end 193.988944 -283.610304)
		(width 0.14478)
		(layer "In6.Cu")
		(net "M_K_CPU1_SB_DQ<3>")
	)
	(segment
		(start 193.988944 -283.610304)
		(end 194.17919 -283.610304)
		(width 0.14478)
		(layer "In6.Cu")
		(net "M_K_CPU1_SB_DQ<3>")
	)
	(segment
		(start 184.011824 -283.600906)
		(end 184.309766 -283.302964)
		(width 0.14478)
		(layer "In6.Cu")
		(net "M_K_CPU1_SB_DQ<3>")
	)
	(segment
		(start 144.6911 -275.383752)
		(end 144.701514 -275.389848)
		(width 0.0889)
		(layer "In6.Cu")
		(net "M_K_CPU1_SB_DQ<3>")
	)
	(segment
		(start 169.675302 -283.328364)
		(end 170.663108 -283.328364)
		(width 0.14478)
		(layer "In6.Cu")
		(net "M_K_CPU1_SB_DQ<3>")
	)
	(segment
		(start 166.661846 -283.610304)
		(end 167.167306 -283.610304)
		(width 0.14478)
		(layer "In6.Cu")
		(net "M_K_CPU1_SB_DQ<3>")
	)
	(segment
		(start 148.060156 -274.303744)
		(end 153.660856 -274.303744)
		(width 0.14478)
		(layer "In6.Cu")
		(net "M_K_CPU1_SB_DQ<3>")
	)
	(segment
		(start 164.86886 -284.166564)
		(end 165.131496 -284.166564)
		(width 0.14478)
		(layer "In6.Cu")
		(net "M_K_CPU1_SB_DQ<3>")
	)
	(segment
		(start 145.471642 -275.268944)
		(end 145.818606 -275.107146)
		(width 0.0889)
		(layer "In6.Cu")
		(net "M_K_CPU1_SB_DQ<3>")
	)
	(segment
		(start 168.562274 -283.328364)
		(end 168.836848 -283.328364)
		(width 0.14478)
		(layer "In6.Cu")
		(net "M_K_CPU1_SB_DQ<3>")
	)
	(segment
		(start 164.574982 -284.460442)
		(end 164.86886 -284.166564)
		(width 0.14478)
		(layer "In6.Cu")
		(net "M_K_CPU1_SB_DQ<3>")
	)
	(segment
		(start 178.709828 -284.18663)
		(end 179.34813 -284.451044)
		(width 0.14478)
		(layer "In6.Cu")
		(net "M_K_CPU1_SB_DQ<3>")
	)
	(segment
		(start 180.617622 -284.088586)
		(end 180.762402 -284.233366)
		(width 0.14478)
		(layer "In6.Cu")
		(net "M_K_CPU1_SB_DQ<3>")
	)
	(segment
		(start 170.761406 -283.426662)
		(end 170.761406 -283.631386)
		(width 0.14478)
		(layer "In6.Cu")
		(net "M_K_CPU1_SB_DQ<3>")
	)
	(segment
		(start 165.425374 -284.460442)
		(end 165.811708 -284.460442)
		(width 0.14478)
		(layer "In6.Cu")
		(net "M_K_CPU1_SB_DQ<3>")
	)
	(segment
		(start 179.34813 -284.451044)
		(end 180.066188 -284.451044)
		(width 0.14478)
		(layer "In6.Cu")
		(net "M_K_CPU1_SB_DQ<3>")
	)
	(segment
		(start 182.596028 -283.302964)
		(end 182.845202 -283.302964)
		(width 0.14478)
		(layer "In6.Cu")
		(net "M_K_CPU1_SB_DQ<3>")
	)
	(segment
		(start 168.836848 -283.328364)
		(end 169.10939 -283.600906)
		(width 0.14478)
		(layer "In6.Cu")
		(net "M_K_CPU1_SB_DQ<3>")
	)
	(segment
		(start 177.933096 -283.864812)
		(end 178.122072 -283.78658)
		(width 0.14478)
		(layer "In6.Cu")
		(net "M_K_CPU1_SB_DQ<3>")
	)
	(segment
		(start 147.749768 -274.303744)
		(end 148.060156 -274.303744)
		(width 0.0889)
		(layer "In6.Cu")
		(net "M_K_CPU1_SB_DQ<3>")
	)
	(segment
		(start 181.153054 -284.451044)
		(end 181.993794 -283.610304)
		(width 0.14478)
		(layer "In6.Cu")
		(net "M_K_CPU1_SB_DQ<3>")
	)
	(segment
		(start 146.06524 -274.98167)
		(end 146.75104 -274.29587)
		(width 0.0889)
		(layer "In6.Cu")
		(net "M_K_CPU1_SB_DQ<3>")
	)
	(segment
		(start 184.55894 -283.302964)
		(end 184.79516 -283.539184)
		(width 0.14478)
		(layer "In6.Cu")
		(net "M_K_CPU1_SB_DQ<3>")
	)
	(segment
		(start 172.85716 -284.451044)
		(end 173.6979 -283.610304)
		(width 0.14478)
		(layer "In6.Cu")
		(net "M_K_CPU1_SB_DQ<3>")
	)
	(segment
		(start 190.405512 -283.600906)
		(end 192.04686 -283.600906)
		(width 0.14478)
		(layer "In6.Cu")
		(net "M_K_CPU1_SB_DQ<3>")
	)
	(segment
		(start 171.785788 -284.451044)
		(end 172.85716 -284.451044)
		(width 0.14478)
		(layer "In6.Cu")
		(net "M_K_CPU1_SB_DQ<3>")
	)
	(segment
		(start 182.288688 -283.610304)
		(end 182.596028 -283.302964)
		(width 0.14478)
		(layer "In6.Cu")
		(net "M_K_CPU1_SB_DQ<3>")
	)
	(segment
		(start 189.858396 -283.328364)
		(end 190.13297 -283.328364)
		(width 0.14478)
		(layer "In6.Cu")
		(net "M_K_CPU1_SB_DQ<3>")
	)
	(segment
		(start 170.86199 -284.106366)
		(end 171.066714 -284.106366)
		(width 0.14478)
		(layer "In6.Cu")
		(net "M_K_CPU1_SB_DQ<3>")
	)
	(segment
		(start 171.15155 -284.02153)
		(end 171.356274 -284.02153)
		(width 0.14478)
		(layer "In6.Cu")
		(net "M_K_CPU1_SB_DQ<3>")
	)
	(segment
		(start 165.131496 -284.166564)
		(end 165.425374 -284.460442)
		(width 0.14478)
		(layer "In6.Cu")
		(net "M_K_CPU1_SB_DQ<3>")
	)
	(segment
		(start 193.15049 -283.610304)
		(end 193.43243 -283.328364)
		(width 0.14478)
		(layer "In6.Cu")
		(net "M_K_CPU1_SB_DQ<3>")
	)
	(segment
		(start 180.762402 -284.306264)
		(end 180.907182 -284.451044)
		(width 0.14478)
		(layer "In6.Cu")
		(net "M_K_CPU1_SB_DQ<3>")
	)
	(segment
		(start 146.75104 -274.29587)
		(end 146.84248 -274.258024)
		(width 0.0889)
		(layer "In6.Cu")
		(net "M_K_CPU1_SB_DQ<3>")
	)
	(segment
		(start 178.631596 -283.997654)
		(end 178.709828 -284.18663)
		(width 0.14478)
		(layer "In6.Cu")
		(net "M_K_CPU1_SB_DQ<3>")
	)
	(segment
		(start 192.875916 -283.610304)
		(end 193.15049 -283.610304)
		(width 0.14478)
		(layer "In6.Cu")
		(net "M_K_CPU1_SB_DQ<3>")
	)
	(segment
		(start 180.210968 -284.233366)
		(end 180.355748 -284.088586)
		(width 0.14478)
		(layer "In6.Cu")
		(net "M_K_CPU1_SB_DQ<3>")
	)
	(segment
		(start 192.319402 -283.328364)
		(end 192.593976 -283.328364)
		(width 0.14478)
		(layer "In6.Cu")
		(net "M_K_CPU1_SB_DQ<3>")
	)
	(segment
		(start 180.066188 -284.451044)
		(end 180.210968 -284.306264)
		(width 0.14478)
		(layer "In6.Cu")
		(net "M_K_CPU1_SB_DQ<3>")
	)
	(segment
		(start 175.319182 -283.600906)
		(end 177.295556 -283.600906)
		(width 0.14478)
		(layer "In6.Cu")
		(net "M_K_CPU1_SB_DQ<3>")
	)
	(segment
		(start 185.199528 -283.539184)
		(end 186.111388 -284.451044)
		(width 0.14478)
		(layer "In6.Cu")
		(net "M_K_CPU1_SB_DQ<3>")
	)
	(segment
		(start 170.67657 -283.716222)
		(end 170.67657 -283.920946)
		(width 0.14478)
		(layer "In6.Cu")
		(net "M_K_CPU1_SB_DQ<3>")
	)
	(segment
		(start 178.646328 -283.962348)
		(end 178.631596 -283.997654)
		(width 0.14478)
		(layer "In6.Cu")
		(net "M_K_CPU1_SB_DQ<3>")
	)
	(segment
		(start 142.803372 -275.378926)
		(end 142.811754 -275.383752)
		(width 0.0889)
		(layer "In6.Cu")
		(net "M_K_CPU1_SB_DQ<3>")
	)
	(segment
		(start 167.449246 -283.328364)
		(end 167.72382 -283.328364)
		(width 0.14478)
		(layer "In6.Cu")
		(net "M_K_CPU1_SB_DQ<3>")
	)
	(segment
		(start 170.761406 -283.631386)
		(end 170.67657 -283.716222)
		(width 0.14478)
		(layer "In6.Cu")
		(net "M_K_CPU1_SB_DQ<3>")
	)
	(segment
		(start 180.210968 -284.306264)
		(end 180.210968 -284.233366)
		(width 0.14478)
		(layer "In6.Cu")
		(net "M_K_CPU1_SB_DQ<3>")
	)
	(segment
		(start 145.257266 -275.383752)
		(end 145.471642 -275.268944)
		(width 0.0889)
		(layer "In6.Cu")
		(net "M_K_CPU1_SB_DQ<3>")
	)
	(segment
		(start 174.464726 -283.610304)
		(end 174.772066 -283.302964)
		(width 0.14478)
		(layer "In6.Cu")
		(net "M_K_CPU1_SB_DQ<3>")
	)
	(segment
		(start 184.309766 -283.302964)
		(end 184.55894 -283.302964)
		(width 0.14478)
		(layer "In6.Cu")
		(net "M_K_CPU1_SB_DQ<3>")
	)
	(segment
		(start 170.67657 -283.920946)
		(end 170.86199 -284.106366)
		(width 0.14478)
		(layer "In6.Cu")
		(net "M_K_CPU1_SB_DQ<3>")
	)
	(segment
		(start 184.79516 -283.539184)
		(end 185.199528 -283.539184)
		(width 0.14478)
		(layer "In6.Cu")
		(net "M_K_CPU1_SB_DQ<3>")
	)
	(segment
		(start 189.576456 -283.610304)
		(end 189.858396 -283.328364)
		(width 0.14478)
		(layer "In6.Cu")
		(net "M_K_CPU1_SB_DQ<3>")
	)
	(segment
		(start 141.530832 -275.440902)
		(end 141.553184 -275.35759)
		(width 0.0889)
		(layer "In6.Cu")
		(net "M_K_CPU1_SB_DQ<3>")
	)
	(segment
		(start 178.567842 -283.773372)
		(end 178.646328 -283.962348)
		(width 0.14478)
		(layer "In6.Cu")
		(net "M_K_CPU1_SB_DQ<3>")
	)
	(segment
		(start 183.143144 -283.600906)
		(end 184.011824 -283.600906)
		(width 0.14478)
		(layer "In6.Cu")
		(net "M_K_CPU1_SB_DQ<3>")
	)
	(segment
		(start 188.148214 -284.451044)
		(end 188.988954 -283.610304)
		(width 0.14478)
		(layer "In6.Cu")
		(net "M_K_CPU1_SB_DQ<3>")
	)
	(segment
		(start 168.289732 -283.600906)
		(end 168.562274 -283.328364)
		(width 0.14478)
		(layer "In6.Cu")
		(net "M_K_CPU1_SB_DQ<3>")
	)
	(segment
		(start 177.295556 -283.600906)
		(end 177.933096 -283.864812)
		(width 0.14478)
		(layer "In6.Cu")
		(net "M_K_CPU1_SB_DQ<3>")
	)
	(segment
		(start 178.122072 -283.78658)
		(end 178.136804 -283.751274)
		(width 0.14478)
		(layer "In6.Cu")
		(net "M_K_CPU1_SB_DQ<3>")
	)
	(segment
		(start 192.04686 -283.600906)
		(end 192.319402 -283.328364)
		(width 0.14478)
		(layer "In6.Cu")
		(net "M_K_CPU1_SB_DQ<3>")
	)
	(segment
		(start 147.704048 -274.258024)
		(end 147.749768 -274.303744)
		(width 0.0889)
		(layer "In6.Cu")
		(net "M_K_CPU1_SB_DQ<3>")
	)
	(segment
		(start 190.13297 -283.328364)
		(end 190.405512 -283.600906)
		(width 0.14478)
		(layer "In6.Cu")
		(net "M_K_CPU1_SB_DQ<3>")
	)
	(segment
		(start 144.307052 -275.389848)
		(end 144.317466 -275.383752)
		(width 0.0889)
		(layer "In6.Cu")
		(net "M_K_CPU1_SB_DQ<3>")
	)
	(segment
		(start 171.066714 -284.106366)
		(end 171.15155 -284.02153)
		(width 0.14478)
		(layer "In6.Cu")
		(net "M_K_CPU1_SB_DQ<3>")
	)
	(segment
		(start 173.6979 -283.610304)
		(end 174.464726 -283.610304)
		(width 0.14478)
		(layer "In6.Cu")
		(net "M_K_CPU1_SB_DQ<3>")
	)
	(segment
		(start 167.72382 -283.328364)
		(end 167.996362 -283.600906)
		(width 0.14478)
		(layer "In6.Cu")
		(net "M_K_CPU1_SB_DQ<3>")
	)
	(segment
		(start 182.845202 -283.302964)
		(end 183.143144 -283.600906)
		(width 0.14478)
		(layer "In6.Cu")
		(net "M_K_CPU1_SB_DQ<3>")
	)
	(segment
		(start 175.02124 -283.302964)
		(end 175.319182 -283.600906)
		(width 0.14478)
		(layer "In6.Cu")
		(net "M_K_CPU1_SB_DQ<3>")
	)
	(segment
		(start 144.317466 -275.383752)
		(end 144.325848 -275.378926)
		(width 0.0889)
		(layer "In6.Cu")
		(net "M_K_CPU1_SB_DQ<3>")
	)
	(segment
		(start 163.817554 -284.460442)
		(end 164.574982 -284.460442)
		(width 0.14478)
		(layer "In6.Cu")
		(net "M_K_CPU1_SB_DQ<3>")
	)
	(segment
		(start 178.325526 -283.673042)
		(end 178.567842 -283.773372)
		(width 0.14478)
		(layer "In6.Cu")
		(net "M_K_CPU1_SB_DQ<3>")
	)
	(segment
		(start 145.818606 -275.107146)
		(end 145.981928 -275.039836)
		(width 0.0889)
		(layer "In6.Cu")
		(net "M_K_CPU1_SB_DQ<3>")
	)
	(segment
		(start 180.907182 -284.451044)
		(end 181.153054 -284.451044)
		(width 0.14478)
		(layer "In6.Cu")
		(net "M_K_CPU1_SB_DQ<3>")
	)
	(segment
		(start 174.772066 -283.302964)
		(end 175.02124 -283.302964)
		(width 0.14478)
		(layer "In6.Cu")
		(net "M_K_CPU1_SB_DQ<3>")
	)
	(segment
		(start 169.40276 -283.600906)
		(end 169.675302 -283.328364)
		(width 0.14478)
		(layer "In6.Cu")
		(net "M_K_CPU1_SB_DQ<3>")
	)
	(segment
		(start 167.167306 -283.610304)
		(end 167.449246 -283.328364)
		(width 0.14478)
		(layer "In6.Cu")
		(net "M_K_CPU1_SB_DQ<3>")
	)
	(segment
		(start 180.355748 -284.088586)
		(end 180.617622 -284.088586)
		(width 0.14478)
		(layer "In6.Cu")
		(net "M_K_CPU1_SB_DQ<3>")
	)
	(segment
		(start 180.762402 -284.233366)
		(end 180.762402 -284.306264)
		(width 0.14478)
		(layer "In6.Cu")
		(net "M_K_CPU1_SB_DQ<3>")
	)
	(segment
		(start 153.660856 -274.303744)
		(end 163.817554 -284.460442)
		(width 0.14478)
		(layer "In6.Cu")
		(net "M_K_CPU1_SB_DQ<3>")
	)
	(segment
		(start 193.43243 -283.328364)
		(end 193.707004 -283.328364)
		(width 0.14478)
		(layer "In6.Cu")
		(net "M_K_CPU1_SB_DQ<3>")
	)
	(segment
		(start 146.84248 -274.258024)
		(end 147.704048 -274.258024)
		(width 0.0889)
		(layer "In6.Cu")
		(net "M_K_CPU1_SB_DQ<3>")
	)
	(segment
		(start 165.811708 -284.460442)
		(end 166.661846 -283.610304)
		(width 0.14478)
		(layer "In6.Cu")
		(net "M_K_CPU1_SB_DQ<3>")
	)
	(segment
		(start 167.996362 -283.600906)
		(end 168.289732 -283.600906)
		(width 0.14478)
		(layer "In6.Cu")
		(net "M_K_CPU1_SB_DQ<3>")
	)
	(segment
		(start 181.993794 -283.610304)
		(end 182.288688 -283.610304)
		(width 0.14478)
		(layer "In6.Cu")
		(net "M_K_CPU1_SB_DQ<3>")
	)
	(segment
		(start 178.136804 -283.751274)
		(end 178.325526 -283.673042)
		(width 0.14478)
		(layer "In6.Cu")
		(net "M_K_CPU1_SB_DQ<3>")
	)
	(segment
		(start 192.593976 -283.328364)
		(end 192.875916 -283.610304)
		(width 0.14478)
		(layer "In6.Cu")
		(net "M_K_CPU1_SB_DQ<3>")
	)
	(segment
		(start 171.356274 -284.02153)
		(end 171.785788 -284.451044)
		(width 0.14478)
		(layer "In6.Cu")
		(net "M_K_CPU1_SB_DQ<3>")
	)
	(segment
		(start 188.988954 -283.610304)
		(end 189.576456 -283.610304)
		(width 0.14478)
		(layer "In6.Cu")
		(net "M_K_CPU1_SB_DQ<3>")
	)
	(segment
		(start 169.10939 -283.600906)
		(end 169.40276 -283.600906)
		(width 0.14478)
		(layer "In6.Cu")
		(net "M_K_CPU1_SB_DQ<3>")
	)
	(segment
		(start 141.684756 -275.706332)
		(end 141.530832 -275.440902)
		(width 0.0889)
		(layer "In6.Cu")
		(net "M_K_CPU1_SB_DQ<3>")
	)
	(segment
		(start 143.377666 -275.383752)
		(end 143.386048 -275.378926)
		(width 0.0889)
		(layer "In6.Cu")
		(net "M_K_CPU1_SB_DQ<3>")
	)
	(arc
		(start 142.437612 -275.383752)
		(mid 142.619863 -275.333402)
		(end 142.803372 -275.378926)
		(width 0.0889)
		(layer "In6.Cu")
		(net "M_K_CPU1_SB_DQ<3>")
	)
	(arc
		(start 141.8717 -275.383752)
		(mid 142.154656 -275.459929)
		(end 142.437612 -275.383752)
		(width 0.0889)
		(layer "In6.Cu")
		(net "M_K_CPU1_SB_DQ<3>")
	)
	(arc
		(start 144.701514 -275.389848)
		(mid 144.9802 -275.460068)
		(end 145.257266 -275.383752)
		(width 0.0889)
		(layer "In6.Cu")
		(net "M_K_CPU1_SB_DQ<3>")
	)
	(arc
		(start 142.811754 -275.383752)
		(mid 143.09471 -275.459929)
		(end 143.377666 -275.383752)
		(width 0.0889)
		(layer "In6.Cu")
		(net "M_K_CPU1_SB_DQ<3>")
	)
	(arc
		(start 143.751808 -275.383752)
		(mid 144.028621 -275.459895)
		(end 144.307052 -275.389848)
		(width 0.0889)
		(layer "In6.Cu")
		(net "M_K_CPU1_SB_DQ<3>")
	)
	(arc
		(start 143.386048 -275.378926)
		(mid 143.569556 -275.333432)
		(end 143.751808 -275.383752)
		(width 0.0889)
		(layer "In6.Cu")
		(net "M_K_CPU1_SB_DQ<3>")
	)
	(arc
		(start 144.325848 -275.378926)
		(mid 144.509102 -275.333553)
		(end 144.6911 -275.383752)
		(width 0.0889)
		(layer "In6.Cu")
		(net "M_K_CPU1_SB_DQ<3>")
	)
	(arc
		(start 141.553184 -275.35759)
		(mid 141.715373 -275.334855)
		(end 141.8717 -275.383752)
		(width 0.0889)
		(layer "In6.Cu")
		(net "M_K_CPU1_SB_DQ<3>")
	)
	(segment
		(start 141.217904 -293.260272)
		(end 141.684756 -293.52621)
		(width 0.10668)
		(layer "F.Cu")
		(net "M_K_CPU1_SB_DQ<31>")
	)
	(segment
		(start 152.897332 -308.04231)
		(end 152.897332 -308.272942)
		(width 0.14478)
		(layer "In6.Cu")
		(net "M_K_CPU1_SB_DQ<31>")
	)
	(segment
		(start 141.530832 -293.26078)
		(end 141.553184 -293.177468)
		(width 0.0889)
		(layer "In6.Cu")
		(net "M_K_CPU1_SB_DQ<31>")
	)
	(segment
		(start 152.503632 -307.879242)
		(end 152.734264 -307.879242)
		(width 0.14478)
		(layer "In6.Cu")
		(net "M_K_CPU1_SB_DQ<31>")
	)
	(segment
		(start 154.078432 -309.454042)
		(end 154.309064 -309.454042)
		(width 0.14478)
		(layer "In6.Cu")
		(net "M_K_CPU1_SB_DQ<31>")
	)
	(segment
		(start 142.803372 -293.198804)
		(end 142.811754 -293.20363)
		(width 0.0889)
		(layer "In6.Cu")
		(net "M_K_CPU1_SB_DQ<31>")
	)
	(segment
		(start 141.684756 -293.52621)
		(end 141.530832 -293.26078)
		(width 0.0889)
		(layer "In6.Cu")
		(net "M_K_CPU1_SB_DQ<31>")
	)
	(segment
		(start 143.377666 -293.20363)
		(end 143.386048 -293.198804)
		(width 0.0889)
		(layer "In6.Cu")
		(net "M_K_CPU1_SB_DQ<31>")
	)
	(segment
		(start 151.769064 -307.82641)
		(end 151.769064 -308.057042)
		(width 0.14478)
		(layer "In6.Cu")
		(net "M_K_CPU1_SB_DQ<31>")
	)
	(segment
		(start 152.719532 -309.00751)
		(end 152.950164 -309.00751)
		(width 0.14478)
		(layer "In6.Cu")
		(net "M_K_CPU1_SB_DQ<31>")
	)
	(segment
		(start 145.318988 -296.196258)
		(end 145.318988 -296.520616)
		(width 0.0889)
		(layer "In6.Cu")
		(net "M_K_CPU1_SB_DQ<31>")
	)
	(segment
		(start 154.309064 -309.454042)
		(end 154.472132 -309.61711)
		(width 0.14478)
		(layer "In6.Cu")
		(net "M_K_CPU1_SB_DQ<31>")
	)
	(segment
		(start 153.684732 -308.82971)
		(end 153.684732 -309.060342)
		(width 0.14478)
		(layer "In6.Cu")
		(net "M_K_CPU1_SB_DQ<31>")
	)
	(segment
		(start 151.769064 -308.057042)
		(end 151.932132 -308.22011)
		(width 0.14478)
		(layer "In6.Cu")
		(net "M_K_CPU1_SB_DQ<31>")
	)
	(segment
		(start 152.897332 -308.272942)
		(end 152.556464 -308.61381)
		(width 0.14478)
		(layer "In6.Cu")
		(net "M_K_CPU1_SB_DQ<31>")
	)
	(segment
		(start 145.343118 -296.172128)
		(end 145.318988 -296.196258)
		(width 0.0889)
		(layer "In6.Cu")
		(net "M_K_CPU1_SB_DQ<31>")
	)
	(segment
		(start 145.318988 -301.606966)
		(end 151.144732 -307.43271)
		(width 0.14478)
		(layer "In6.Cu")
		(net "M_K_CPU1_SB_DQ<31>")
	)
	(segment
		(start 152.556464 -308.61381)
		(end 152.556464 -308.844442)
		(width 0.14478)
		(layer "In6.Cu")
		(net "M_K_CPU1_SB_DQ<31>")
	)
	(segment
		(start 144.876266 -295.144698)
		(end 144.876266 -295.15689)
		(width 0.0889)
		(layer "In6.Cu")
		(net "M_K_CPU1_SB_DQ<31>")
	)
	(segment
		(start 144.652492 -294.800782)
		(end 144.691608 -294.823642)
		(width 0.0889)
		(layer "In6.Cu")
		(net "M_K_CPU1_SB_DQ<31>")
	)
	(segment
		(start 154.131264 -310.475122)
		(end 160.251394 -316.595252)
		(width 0.14478)
		(layer "In6.Cu")
		(net "M_K_CPU1_SB_DQ<31>")
	)
	(segment
		(start 152.109932 -307.25491)
		(end 152.109932 -307.485542)
		(width 0.14478)
		(layer "In6.Cu")
		(net "M_K_CPU1_SB_DQ<31>")
	)
	(segment
		(start 194.17919 -318.460374)
		(end 194.604132 -318.035432)
		(width 0.14478)
		(layer "In6.Cu")
		(net "M_K_CPU1_SB_DQ<31>")
	)
	(segment
		(start 151.932132 -308.22011)
		(end 152.162764 -308.22011)
		(width 0.14478)
		(layer "In6.Cu")
		(net "M_K_CPU1_SB_DQ<31>")
	)
	(segment
		(start 164.754052 -318.460374)
		(end 194.17919 -318.460374)
		(width 0.14478)
		(layer "In6.Cu")
		(net "M_K_CPU1_SB_DQ<31>")
	)
	(segment
		(start 160.251394 -316.595252)
		(end 164.754052 -318.460374)
		(width 0.14478)
		(layer "In6.Cu")
		(net "M_K_CPU1_SB_DQ<31>")
	)
	(segment
		(start 151.716232 -307.091842)
		(end 151.946864 -307.091842)
		(width 0.14478)
		(layer "In6.Cu")
		(net "M_K_CPU1_SB_DQ<31>")
	)
	(segment
		(start 152.734264 -307.879242)
		(end 152.897332 -308.04231)
		(width 0.14478)
		(layer "In6.Cu")
		(net "M_K_CPU1_SB_DQ<31>")
	)
	(segment
		(start 152.109932 -307.485542)
		(end 151.769064 -307.82641)
		(width 0.14478)
		(layer "In6.Cu")
		(net "M_K_CPU1_SB_DQ<31>")
	)
	(segment
		(start 143.751808 -293.20363)
		(end 143.782288 -293.22141)
		(width 0.0889)
		(layer "In6.Cu")
		(net "M_K_CPU1_SB_DQ<31>")
	)
	(segment
		(start 145.343118 -295.956228)
		(end 145.343118 -296.172128)
		(width 0.0889)
		(layer "In6.Cu")
		(net "M_K_CPU1_SB_DQ<31>")
	)
	(segment
		(start 152.162764 -308.22011)
		(end 152.503632 -307.879242)
		(width 0.14478)
		(layer "In6.Cu")
		(net "M_K_CPU1_SB_DQ<31>")
	)
	(segment
		(start 152.950164 -309.00751)
		(end 153.291032 -308.666642)
		(width 0.14478)
		(layer "In6.Cu")
		(net "M_K_CPU1_SB_DQ<31>")
	)
	(segment
		(start 153.737564 -309.79491)
		(end 154.078432 -309.454042)
		(width 0.14478)
		(layer "In6.Cu")
		(net "M_K_CPU1_SB_DQ<31>")
	)
	(segment
		(start 151.144732 -307.43271)
		(end 151.375364 -307.43271)
		(width 0.14478)
		(layer "In6.Cu")
		(net "M_K_CPU1_SB_DQ<31>")
	)
	(segment
		(start 151.375364 -307.43271)
		(end 151.716232 -307.091842)
		(width 0.14478)
		(layer "In6.Cu")
		(net "M_K_CPU1_SB_DQ<31>")
	)
	(segment
		(start 153.506932 -309.79491)
		(end 153.737564 -309.79491)
		(width 0.14478)
		(layer "In6.Cu")
		(net "M_K_CPU1_SB_DQ<31>")
	)
	(segment
		(start 153.684732 -309.060342)
		(end 153.343864 -309.40121)
		(width 0.14478)
		(layer "In6.Cu")
		(net "M_K_CPU1_SB_DQ<31>")
	)
	(segment
		(start 153.291032 -308.666642)
		(end 153.521664 -308.666642)
		(width 0.14478)
		(layer "In6.Cu")
		(net "M_K_CPU1_SB_DQ<31>")
	)
	(segment
		(start 154.472132 -309.847742)
		(end 154.131264 -310.18861)
		(width 0.14478)
		(layer "In6.Cu")
		(net "M_K_CPU1_SB_DQ<31>")
	)
	(segment
		(start 145.318988 -296.520616)
		(end 145.318988 -301.606966)
		(width 0.14478)
		(layer "In6.Cu")
		(net "M_K_CPU1_SB_DQ<31>")
	)
	(segment
		(start 154.472132 -309.61711)
		(end 154.472132 -309.847742)
		(width 0.14478)
		(layer "In6.Cu")
		(net "M_K_CPU1_SB_DQ<31>")
	)
	(segment
		(start 144.221708 -294.013636)
		(end 144.252188 -294.031416)
		(width 0.0889)
		(layer "In6.Cu")
		(net "M_K_CPU1_SB_DQ<31>")
	)
	(segment
		(start 153.521664 -308.666642)
		(end 153.684732 -308.82971)
		(width 0.14478)
		(layer "In6.Cu")
		(net "M_K_CPU1_SB_DQ<31>")
	)
	(segment
		(start 144.182592 -293.990776)
		(end 144.221708 -294.013636)
		(width 0.0889)
		(layer "In6.Cu")
		(net "M_K_CPU1_SB_DQ<31>")
	)
	(segment
		(start 153.343864 -309.631842)
		(end 153.506932 -309.79491)
		(width 0.14478)
		(layer "In6.Cu")
		(net "M_K_CPU1_SB_DQ<31>")
	)
	(segment
		(start 152.556464 -308.844442)
		(end 152.719532 -309.00751)
		(width 0.14478)
		(layer "In6.Cu")
		(net "M_K_CPU1_SB_DQ<31>")
	)
	(segment
		(start 151.946864 -307.091842)
		(end 152.109932 -307.25491)
		(width 0.14478)
		(layer "In6.Cu")
		(net "M_K_CPU1_SB_DQ<31>")
	)
	(segment
		(start 153.343864 -309.40121)
		(end 153.343864 -309.631842)
		(width 0.14478)
		(layer "In6.Cu")
		(net "M_K_CPU1_SB_DQ<31>")
	)
	(segment
		(start 154.131264 -310.18861)
		(end 154.131264 -310.475122)
		(width 0.14478)
		(layer "In6.Cu")
		(net "M_K_CPU1_SB_DQ<31>")
	)
	(arc
		(start 144.40916 -294.336216)
		(mid 144.473675 -294.598435)
		(end 144.652492 -294.800782)
		(width 0.0889)
		(layer "In6.Cu")
		(net "M_K_CPU1_SB_DQ<31>")
	)
	(arc
		(start 144.876266 -295.15689)
		(mid 144.940781 -295.419109)
		(end 145.119598 -295.621456)
		(width 0.0889)
		(layer "In6.Cu")
		(net "M_K_CPU1_SB_DQ<31>")
	)
	(arc
		(start 143.386048 -293.198804)
		(mid 143.569556 -293.15331)
		(end 143.751808 -293.20363)
		(width 0.0889)
		(layer "In6.Cu")
		(net "M_K_CPU1_SB_DQ<31>")
	)
	(arc
		(start 142.437612 -293.20363)
		(mid 142.619863 -293.15328)
		(end 142.803372 -293.198804)
		(width 0.0889)
		(layer "In6.Cu")
		(net "M_K_CPU1_SB_DQ<31>")
	)
	(arc
		(start 141.8717 -293.20363)
		(mid 142.154656 -293.279807)
		(end 142.437612 -293.20363)
		(width 0.0889)
		(layer "In6.Cu")
		(net "M_K_CPU1_SB_DQ<31>")
	)
	(arc
		(start 145.119598 -295.621456)
		(mid 145.179756 -295.654588)
		(end 145.232628 -295.698418)
		(width 0.0889)
		(layer "In6.Cu")
		(net "M_K_CPU1_SB_DQ<31>")
	)
	(arc
		(start 143.782288 -293.22141)
		(mid 143.897715 -293.354786)
		(end 143.93926 -293.52621)
		(width 0.0889)
		(layer "In6.Cu")
		(net "M_K_CPU1_SB_DQ<31>")
	)
	(arc
		(start 142.811754 -293.20363)
		(mid 143.09471 -293.279807)
		(end 143.377666 -293.20363)
		(width 0.0889)
		(layer "In6.Cu")
		(net "M_K_CPU1_SB_DQ<31>")
	)
	(arc
		(start 144.252188 -294.031416)
		(mid 144.367615 -294.164792)
		(end 144.40916 -294.336216)
		(width 0.0889)
		(layer "In6.Cu")
		(net "M_K_CPU1_SB_DQ<31>")
	)
	(arc
		(start 144.691608 -294.823642)
		(mid 144.826838 -294.959502)
		(end 144.876266 -295.144698)
		(width 0.0889)
		(layer "In6.Cu")
		(net "M_K_CPU1_SB_DQ<31>")
	)
	(arc
		(start 145.232628 -295.698418)
		(mid 145.312691 -295.816684)
		(end 145.343118 -295.956228)
		(width 0.0889)
		(layer "In6.Cu")
		(net "M_K_CPU1_SB_DQ<31>")
	)
	(arc
		(start 141.553184 -293.177468)
		(mid 141.715373 -293.154733)
		(end 141.8717 -293.20363)
		(width 0.0889)
		(layer "In6.Cu")
		(net "M_K_CPU1_SB_DQ<31>")
	)
	(arc
		(start 143.93926 -293.52621)
		(mid 144.003775 -293.788429)
		(end 144.182592 -293.990776)
		(width 0.0889)
		(layer "In6.Cu")
		(net "M_K_CPU1_SB_DQ<31>")
	)
	(segment
		(start 142.627858 -292.450266)
		(end 143.09471 -292.716204)
		(width 0.10668)
		(layer "F.Cu")
		(net "M_K_CPU1_SB_DQ<30>")
	)
	(segment
		(start 143.09471 -292.716204)
		(end 142.940786 -292.450774)
		(width 0.0889)
		(layer "In6.Cu")
		(net "M_K_CPU1_SB_DQ<30>")
	)
	(segment
		(start 142.940786 -292.450774)
		(end 142.963138 -292.367462)
		(width 0.0889)
		(layer "In6.Cu")
		(net "M_K_CPU1_SB_DQ<30>")
	)
	(segment
		(start 144.652746 -293.18077)
		(end 144.691862 -293.20363)
		(width 0.0889)
		(layer "In6.Cu")
		(net "M_K_CPU1_SB_DQ<30>")
	)
	(segment
		(start 145.161762 -294.013636)
		(end 145.192242 -294.031416)
		(width 0.0889)
		(layer "In6.Cu")
		(net "M_K_CPU1_SB_DQ<30>")
	)
	(segment
		(start 150.134828 -305.05146)
		(end 150.36546 -305.05146)
		(width 0.14478)
		(layer "In6.Cu")
		(net "M_K_CPU1_SB_DQ<30>")
	)
	(segment
		(start 150.922228 -305.83886)
		(end 151.15286 -305.83886)
		(width 0.14478)
		(layer "In6.Cu")
		(net "M_K_CPU1_SB_DQ<30>")
	)
	(segment
		(start 147.21586 -301.90186)
		(end 147.552664 -301.565056)
		(width 0.14478)
		(layer "In6.Cu")
		(net "M_K_CPU1_SB_DQ<30>")
	)
	(segment
		(start 147.946364 -301.958756)
		(end 147.60956 -302.29556)
		(width 0.14478)
		(layer "In6.Cu")
		(net "M_K_CPU1_SB_DQ<30>")
	)
	(segment
		(start 146.268186 -300.049946)
		(end 147.158964 -300.940724)
		(width 0.14478)
		(layer "In6.Cu")
		(net "M_K_CPU1_SB_DQ<30>")
	)
	(segment
		(start 145.813018 -294.987218)
		(end 145.813018 -295.230296)
		(width 0.0889)
		(layer "In6.Cu")
		(net "M_K_CPU1_SB_DQ<30>")
	)
	(segment
		(start 155.42895 -310.151526)
		(end 160.626806 -315.349382)
		(width 0.14478)
		(layer "In6.Cu")
		(net "M_K_CPU1_SB_DQ<30>")
	)
	(segment
		(start 146.268186 -295.685464)
		(end 146.268186 -296.540682)
		(width 0.0889)
		(layer "In6.Cu")
		(net "M_K_CPU1_SB_DQ<30>")
	)
	(segment
		(start 160.626806 -315.349382)
		(end 164.0332 -316.760352)
		(width 0.14478)
		(layer "In6.Cu")
		(net "M_K_CPU1_SB_DQ<30>")
	)
	(segment
		(start 149.914864 -303.927256)
		(end 150.145496 -303.927256)
		(width 0.14478)
		(layer "In6.Cu")
		(net "M_K_CPU1_SB_DQ<30>")
	)
	(segment
		(start 149.127464 -303.139856)
		(end 149.358096 -303.139856)
		(width 0.14478)
		(layer "In6.Cu")
		(net "M_K_CPU1_SB_DQ<30>")
	)
	(segment
		(start 151.095964 -305.108356)
		(end 150.75916 -305.44516)
		(width 0.14478)
		(layer "In6.Cu")
		(net "M_K_CPU1_SB_DQ<30>")
	)
	(segment
		(start 151.15286 -305.83886)
		(end 151.489664 -305.502056)
		(width 0.14478)
		(layer "In6.Cu")
		(net "M_K_CPU1_SB_DQ<30>")
	)
	(segment
		(start 144.691862 -293.20363)
		(end 144.722342 -293.22141)
		(width 0.0889)
		(layer "In6.Cu")
		(net "M_K_CPU1_SB_DQ<30>")
	)
	(segment
		(start 149.97176 -304.888392)
		(end 150.134828 -305.05146)
		(width 0.14478)
		(layer "In6.Cu")
		(net "M_K_CPU1_SB_DQ<30>")
	)
	(segment
		(start 149.521164 -303.302924)
		(end 149.521164 -303.533556)
		(width 0.14478)
		(layer "In6.Cu")
		(net "M_K_CPU1_SB_DQ<30>")
	)
	(segment
		(start 147.783296 -301.565056)
		(end 147.946364 -301.728124)
		(width 0.14478)
		(layer "In6.Cu")
		(net "M_K_CPU1_SB_DQ<30>")
	)
	(segment
		(start 146.82216 -301.738792)
		(end 146.985228 -301.90186)
		(width 0.14478)
		(layer "In6.Cu")
		(net "M_K_CPU1_SB_DQ<30>")
	)
	(segment
		(start 145.592546 -294.800782)
		(end 145.631662 -294.823642)
		(width 0.0889)
		(layer "In6.Cu")
		(net "M_K_CPU1_SB_DQ<30>")
	)
	(segment
		(start 145.813018 -295.230296)
		(end 146.268186 -295.685464)
		(width 0.0889)
		(layer "In6.Cu")
		(net "M_K_CPU1_SB_DQ<30>")
	)
	(segment
		(start 164.0332 -316.760352)
		(end 194.17919 -316.760352)
		(width 0.14478)
		(layer "In6.Cu")
		(net "M_K_CPU1_SB_DQ<30>")
	)
	(segment
		(start 147.158964 -301.171356)
		(end 146.82216 -301.50816)
		(width 0.14478)
		(layer "In6.Cu")
		(net "M_K_CPU1_SB_DQ<30>")
	)
	(segment
		(start 194.17919 -316.760352)
		(end 194.604132 -316.33541)
		(width 0.14478)
		(layer "In6.Cu")
		(net "M_K_CPU1_SB_DQ<30>")
	)
	(segment
		(start 146.82216 -301.50816)
		(end 146.82216 -301.738792)
		(width 0.14478)
		(layer "In6.Cu")
		(net "M_K_CPU1_SB_DQ<30>")
	)
	(segment
		(start 144.221962 -292.393624)
		(end 144.252442 -292.411404)
		(width 0.0889)
		(layer "In6.Cu")
		(net "M_K_CPU1_SB_DQ<30>")
	)
	(segment
		(start 155.42895 -309.21071)
		(end 155.42895 -310.151526)
		(width 0.14478)
		(layer "In6.Cu")
		(net "M_K_CPU1_SB_DQ<30>")
	)
	(segment
		(start 148.79066 -303.47666)
		(end 149.127464 -303.139856)
		(width 0.14478)
		(layer "In6.Cu")
		(net "M_K_CPU1_SB_DQ<30>")
	)
	(segment
		(start 149.358096 -303.139856)
		(end 149.521164 -303.302924)
		(width 0.14478)
		(layer "In6.Cu")
		(net "M_K_CPU1_SB_DQ<30>")
	)
	(segment
		(start 146.985228 -301.90186)
		(end 147.21586 -301.90186)
		(width 0.14478)
		(layer "In6.Cu")
		(net "M_K_CPU1_SB_DQ<30>")
	)
	(segment
		(start 147.158964 -300.940724)
		(end 147.158964 -301.171356)
		(width 0.14478)
		(layer "In6.Cu")
		(net "M_K_CPU1_SB_DQ<30>")
	)
	(segment
		(start 148.00326 -302.68926)
		(end 148.340064 -302.352456)
		(width 0.14478)
		(layer "In6.Cu")
		(net "M_K_CPU1_SB_DQ<30>")
	)
	(segment
		(start 148.733764 -302.515524)
		(end 148.733764 -302.746156)
		(width 0.14478)
		(layer "In6.Cu")
		(net "M_K_CPU1_SB_DQ<30>")
	)
	(segment
		(start 150.702264 -304.714656)
		(end 150.932896 -304.714656)
		(width 0.14478)
		(layer "In6.Cu")
		(net "M_K_CPU1_SB_DQ<30>")
	)
	(segment
		(start 149.18436 -303.87036)
		(end 149.18436 -304.100992)
		(width 0.14478)
		(layer "In6.Cu")
		(net "M_K_CPU1_SB_DQ<30>")
	)
	(segment
		(start 150.308564 -304.320956)
		(end 149.97176 -304.65776)
		(width 0.14478)
		(layer "In6.Cu")
		(net "M_K_CPU1_SB_DQ<30>")
	)
	(segment
		(start 147.772628 -302.68926)
		(end 148.00326 -302.68926)
		(width 0.14478)
		(layer "In6.Cu")
		(net "M_K_CPU1_SB_DQ<30>")
	)
	(segment
		(start 149.57806 -304.26406)
		(end 149.914864 -303.927256)
		(width 0.14478)
		(layer "In6.Cu")
		(net "M_K_CPU1_SB_DQ<30>")
	)
	(segment
		(start 150.932896 -304.714656)
		(end 151.095964 -304.877724)
		(width 0.14478)
		(layer "In6.Cu")
		(net "M_K_CPU1_SB_DQ<30>")
	)
	(segment
		(start 150.308564 -304.090324)
		(end 150.308564 -304.320956)
		(width 0.14478)
		(layer "In6.Cu")
		(net "M_K_CPU1_SB_DQ<30>")
	)
	(segment
		(start 147.60956 -302.526192)
		(end 147.772628 -302.68926)
		(width 0.14478)
		(layer "In6.Cu")
		(net "M_K_CPU1_SB_DQ<30>")
	)
	(segment
		(start 151.720296 -305.502056)
		(end 155.42895 -309.21071)
		(width 0.14478)
		(layer "In6.Cu")
		(net "M_K_CPU1_SB_DQ<30>")
	)
	(segment
		(start 149.521164 -303.533556)
		(end 149.18436 -303.87036)
		(width 0.14478)
		(layer "In6.Cu")
		(net "M_K_CPU1_SB_DQ<30>")
	)
	(segment
		(start 145.70837 -294.88257)
		(end 145.813018 -294.987218)
		(width 0.0889)
		(layer "In6.Cu")
		(net "M_K_CPU1_SB_DQ<30>")
	)
	(segment
		(start 150.75916 -305.44516)
		(end 150.75916 -305.675792)
		(width 0.14478)
		(layer "In6.Cu")
		(net "M_K_CPU1_SB_DQ<30>")
	)
	(segment
		(start 150.145496 -303.927256)
		(end 150.308564 -304.090324)
		(width 0.14478)
		(layer "In6.Cu")
		(net "M_K_CPU1_SB_DQ<30>")
	)
	(segment
		(start 148.39696 -303.08296)
		(end 148.39696 -303.313592)
		(width 0.14478)
		(layer "In6.Cu")
		(net "M_K_CPU1_SB_DQ<30>")
	)
	(segment
		(start 149.347428 -304.26406)
		(end 149.57806 -304.26406)
		(width 0.14478)
		(layer "In6.Cu")
		(net "M_K_CPU1_SB_DQ<30>")
	)
	(segment
		(start 146.268186 -296.540682)
		(end 146.268186 -300.049946)
		(width 0.14478)
		(layer "In6.Cu")
		(net "M_K_CPU1_SB_DQ<30>")
	)
	(segment
		(start 147.60956 -302.29556)
		(end 147.60956 -302.526192)
		(width 0.14478)
		(layer "In6.Cu")
		(net "M_K_CPU1_SB_DQ<30>")
	)
	(segment
		(start 145.122646 -293.990776)
		(end 145.161762 -294.013636)
		(width 0.0889)
		(layer "In6.Cu")
		(net "M_K_CPU1_SB_DQ<30>")
	)
	(segment
		(start 148.340064 -302.352456)
		(end 148.570696 -302.352456)
		(width 0.14478)
		(layer "In6.Cu")
		(net "M_K_CPU1_SB_DQ<30>")
	)
	(segment
		(start 148.560028 -303.47666)
		(end 148.79066 -303.47666)
		(width 0.14478)
		(layer "In6.Cu")
		(net "M_K_CPU1_SB_DQ<30>")
	)
	(segment
		(start 148.570696 -302.352456)
		(end 148.733764 -302.515524)
		(width 0.14478)
		(layer "In6.Cu")
		(net "M_K_CPU1_SB_DQ<30>")
	)
	(segment
		(start 148.733764 -302.746156)
		(end 148.39696 -303.08296)
		(width 0.14478)
		(layer "In6.Cu")
		(net "M_K_CPU1_SB_DQ<30>")
	)
	(segment
		(start 150.75916 -305.675792)
		(end 150.922228 -305.83886)
		(width 0.14478)
		(layer "In6.Cu")
		(net "M_K_CPU1_SB_DQ<30>")
	)
	(segment
		(start 151.489664 -305.502056)
		(end 151.720296 -305.502056)
		(width 0.14478)
		(layer "In6.Cu")
		(net "M_K_CPU1_SB_DQ<30>")
	)
	(segment
		(start 150.36546 -305.05146)
		(end 150.702264 -304.714656)
		(width 0.14478)
		(layer "In6.Cu")
		(net "M_K_CPU1_SB_DQ<30>")
	)
	(segment
		(start 151.095964 -304.877724)
		(end 151.095964 -305.108356)
		(width 0.14478)
		(layer "In6.Cu")
		(net "M_K_CPU1_SB_DQ<30>")
	)
	(segment
		(start 149.18436 -304.100992)
		(end 149.347428 -304.26406)
		(width 0.14478)
		(layer "In6.Cu")
		(net "M_K_CPU1_SB_DQ<30>")
	)
	(segment
		(start 147.946364 -301.728124)
		(end 147.946364 -301.958756)
		(width 0.14478)
		(layer "In6.Cu")
		(net "M_K_CPU1_SB_DQ<30>")
	)
	(segment
		(start 149.97176 -304.65776)
		(end 149.97176 -304.888392)
		(width 0.14478)
		(layer "In6.Cu")
		(net "M_K_CPU1_SB_DQ<30>")
	)
	(segment
		(start 147.552664 -301.565056)
		(end 147.783296 -301.565056)
		(width 0.14478)
		(layer "In6.Cu")
		(net "M_K_CPU1_SB_DQ<30>")
	)
	(segment
		(start 148.39696 -303.313592)
		(end 148.560028 -303.47666)
		(width 0.14478)
		(layer "In6.Cu")
		(net "M_K_CPU1_SB_DQ<30>")
	)
	(arc
		(start 143.281654 -292.393624)
		(mid 143.56461 -292.469801)
		(end 143.847566 -292.393624)
		(width 0.0889)
		(layer "In6.Cu")
		(net "M_K_CPU1_SB_DQ<30>")
	)
	(arc
		(start 145.192242 -294.031416)
		(mid 145.307669 -294.164792)
		(end 145.349214 -294.336216)
		(width 0.0889)
		(layer "In6.Cu")
		(net "M_K_CPU1_SB_DQ<30>")
	)
	(arc
		(start 142.963138 -292.367462)
		(mid 143.125327 -292.344727)
		(end 143.281654 -292.393624)
		(width 0.0889)
		(layer "In6.Cu")
		(net "M_K_CPU1_SB_DQ<30>")
	)
	(arc
		(start 144.409414 -292.716204)
		(mid 144.473929 -292.978423)
		(end 144.652746 -293.18077)
		(width 0.0889)
		(layer "In6.Cu")
		(net "M_K_CPU1_SB_DQ<30>")
	)
	(arc
		(start 145.631662 -294.823642)
		(mid 145.671927 -294.850617)
		(end 145.70837 -294.88257)
		(width 0.0889)
		(layer "In6.Cu")
		(net "M_K_CPU1_SB_DQ<30>")
	)
	(arc
		(start 143.847566 -292.393624)
		(mid 144.034764 -292.343242)
		(end 144.221962 -292.393624)
		(width 0.0889)
		(layer "In6.Cu")
		(net "M_K_CPU1_SB_DQ<30>")
	)
	(arc
		(start 144.722342 -293.22141)
		(mid 144.837769 -293.354786)
		(end 144.879314 -293.52621)
		(width 0.0889)
		(layer "In6.Cu")
		(net "M_K_CPU1_SB_DQ<30>")
	)
	(arc
		(start 144.879314 -293.52621)
		(mid 144.943829 -293.788429)
		(end 145.122646 -293.990776)
		(width 0.0889)
		(layer "In6.Cu")
		(net "M_K_CPU1_SB_DQ<30>")
	)
	(arc
		(start 145.349214 -294.336216)
		(mid 145.413729 -294.598435)
		(end 145.592546 -294.800782)
		(width 0.0889)
		(layer "In6.Cu")
		(net "M_K_CPU1_SB_DQ<30>")
	)
	(arc
		(start 144.252442 -292.411404)
		(mid 144.367869 -292.54478)
		(end 144.409414 -292.716204)
		(width 0.0889)
		(layer "In6.Cu")
		(net "M_K_CPU1_SB_DQ<30>")
	)
	(segment
		(start 142.627858 -274.630388)
		(end 143.09471 -274.896326)
		(width 0.10668)
		(layer "F.Cu")
		(net "M_K_CPU1_SB_DQ<2>")
	)
	(segment
		(start 168.105836 -281.910282)
		(end 168.378632 -281.910282)
		(width 0.14478)
		(layer "In6.Cu")
		(net "M_K_CPU1_SB_DQ<2>")
	)
	(segment
		(start 159.958278 -278.882856)
		(end 160.136078 -279.060656)
		(width 0.14478)
		(layer "In6.Cu")
		(net "M_K_CPU1_SB_DQ<2>")
	)
	(segment
		(start 155.589478 -274.945856)
		(end 156.021278 -274.945856)
		(width 0.14478)
		(layer "In6.Cu")
		(net "M_K_CPU1_SB_DQ<2>")
	)
	(segment
		(start 155.233878 -274.158456)
		(end 155.411678 -274.336256)
		(width 0.14478)
		(layer "In6.Cu")
		(net "M_K_CPU1_SB_DQ<2>")
	)
	(segment
		(start 170.048174 -281.626564)
		(end 170.331892 -281.910282)
		(width 0.14478)
		(layer "In6.Cu")
		(net "M_K_CPU1_SB_DQ<2>")
	)
	(segment
		(start 145.161508 -274.573746)
		(end 145.230088 -274.613624)
		(width 0.0889)
		(layer "In6.Cu")
		(net "M_K_CPU1_SB_DQ<2>")
	)
	(segment
		(start 166.150036 -282.76042)
		(end 167.000174 -281.910282)
		(width 0.14478)
		(layer "In6.Cu")
		(net "M_K_CPU1_SB_DQ<2>")
	)
	(segment
		(start 154.802078 -274.158456)
		(end 155.233878 -274.158456)
		(width 0.14478)
		(layer "In6.Cu")
		(net "M_K_CPU1_SB_DQ<2>")
	)
	(segment
		(start 157.164278 -276.520656)
		(end 157.596078 -276.520656)
		(width 0.14478)
		(layer "In6.Cu")
		(net "M_K_CPU1_SB_DQ<2>")
	)
	(segment
		(start 168.378632 -281.910282)
		(end 168.66235 -281.626564)
		(width 0.14478)
		(layer "In6.Cu")
		(net "M_K_CPU1_SB_DQ<2>")
	)
	(segment
		(start 156.199078 -275.555456)
		(end 156.376878 -275.733256)
		(width 0.14478)
		(layer "In6.Cu")
		(net "M_K_CPU1_SB_DQ<2>")
	)
	(segment
		(start 192.203324 -281.673046)
		(end 192.348104 -281.528266)
		(width 0.14478)
		(layer "In6.Cu")
		(net "M_K_CPU1_SB_DQ<2>")
	)
	(segment
		(start 190.748412 -281.910282)
		(end 191.624712 -281.910282)
		(width 0.14478)
		(layer "In6.Cu")
		(net "M_K_CPU1_SB_DQ<2>")
	)
	(segment
		(start 193.306192 -282.147518)
		(end 193.306192 -281.673046)
		(width 0.14478)
		(layer "In6.Cu")
		(net "M_K_CPU1_SB_DQ<2>")
	)
	(segment
		(start 167.549322 -281.626564)
		(end 167.822118 -281.626564)
		(width 0.14478)
		(layer "In6.Cu")
		(net "M_K_CPU1_SB_DQ<2>")
	)
	(segment
		(start 156.986478 -276.342856)
		(end 157.164278 -276.520656)
		(width 0.14478)
		(layer "In6.Cu")
		(net "M_K_CPU1_SB_DQ<2>")
	)
	(segment
		(start 157.773878 -277.130256)
		(end 157.951678 -277.308056)
		(width 0.14478)
		(layer "In6.Cu")
		(net "M_K_CPU1_SB_DQ<2>")
	)
	(segment
		(start 188.969142 -281.910282)
		(end 189.90818 -281.910282)
		(width 0.14478)
		(layer "In6.Cu")
		(net "M_K_CPU1_SB_DQ<2>")
	)
	(segment
		(start 177.40503 -281.910282)
		(end 178.20005 -281.910282)
		(width 0.14478)
		(layer "In6.Cu")
		(net "M_K_CPU1_SB_DQ<2>")
	)
	(segment
		(start 163.835842 -282.76042)
		(end 166.150036 -282.76042)
		(width 0.14478)
		(layer "In6.Cu")
		(net "M_K_CPU1_SB_DQ<2>")
	)
	(segment
		(start 158.561278 -277.485856)
		(end 158.561278 -277.917656)
		(width 0.14478)
		(layer "In6.Cu")
		(net "M_K_CPU1_SB_DQ<2>")
	)
	(segment
		(start 192.203324 -281.765502)
		(end 192.203324 -281.673046)
		(width 0.14478)
		(layer "In6.Cu")
		(net "M_K_CPU1_SB_DQ<2>")
	)
	(segment
		(start 193.857626 -281.765502)
		(end 194.002406 -281.910282)
		(width 0.14478)
		(layer "In6.Cu")
		(net "M_K_CPU1_SB_DQ<2>")
	)
	(segment
		(start 154.624278 -273.980656)
		(end 154.802078 -274.158456)
		(width 0.14478)
		(layer "In6.Cu")
		(net "M_K_CPU1_SB_DQ<2>")
	)
	(segment
		(start 175.019462 -281.910282)
		(end 176.564798 -281.910282)
		(width 0.14478)
		(layer "In6.Cu")
		(net "M_K_CPU1_SB_DQ<2>")
	)
	(segment
		(start 159.348678 -278.705056)
		(end 159.526478 -278.882856)
		(width 0.14478)
		(layer "In6.Cu")
		(net "M_K_CPU1_SB_DQ<2>")
	)
	(segment
		(start 157.596078 -276.520656)
		(end 157.773878 -276.698456)
		(width 0.14478)
		(layer "In6.Cu")
		(net "M_K_CPU1_SB_DQ<2>")
	)
	(segment
		(start 148.048218 -273.394424)
		(end 154.469846 -273.394424)
		(width 0.14478)
		(layer "In6.Cu")
		(net "M_K_CPU1_SB_DQ<2>")
	)
	(segment
		(start 156.376878 -275.733256)
		(end 156.808678 -275.733256)
		(width 0.14478)
		(layer "In6.Cu")
		(net "M_K_CPU1_SB_DQ<2>")
	)
	(segment
		(start 156.808678 -275.733256)
		(end 156.986478 -275.911056)
		(width 0.14478)
		(layer "In6.Cu")
		(net "M_K_CPU1_SB_DQ<2>")
	)
	(segment
		(start 155.411678 -274.336256)
		(end 155.411678 -274.768056)
		(width 0.14478)
		(layer "In6.Cu")
		(net "M_K_CPU1_SB_DQ<2>")
	)
	(segment
		(start 173.02353 -282.76042)
		(end 173.873668 -281.910282)
		(width 0.14478)
		(layer "In6.Cu")
		(net "M_K_CPU1_SB_DQ<2>")
	)
	(segment
		(start 170.331892 -281.910282)
		(end 170.707304 -281.910282)
		(width 0.14478)
		(layer "In6.Cu")
		(net "M_K_CPU1_SB_DQ<2>")
	)
	(segment
		(start 159.348678 -278.273256)
		(end 159.348678 -278.705056)
		(width 0.14478)
		(layer "In6.Cu")
		(net "M_K_CPU1_SB_DQ<2>")
	)
	(segment
		(start 154.469846 -273.394424)
		(end 154.624278 -273.548856)
		(width 0.14478)
		(layer "In6.Cu")
		(net "M_K_CPU1_SB_DQ<2>")
	)
	(segment
		(start 156.199078 -275.123656)
		(end 156.199078 -275.555456)
		(width 0.14478)
		(layer "In6.Cu")
		(net "M_K_CPU1_SB_DQ<2>")
	)
	(segment
		(start 158.739078 -278.095456)
		(end 159.170878 -278.095456)
		(width 0.14478)
		(layer "In6.Cu")
		(net "M_K_CPU1_SB_DQ<2>")
	)
	(segment
		(start 160.313878 -279.670256)
		(end 160.745678 -279.670256)
		(width 0.14478)
		(layer "In6.Cu")
		(net "M_K_CPU1_SB_DQ<2>")
	)
	(segment
		(start 167.000174 -281.910282)
		(end 167.265604 -281.910282)
		(width 0.14478)
		(layer "In6.Cu")
		(net "M_K_CPU1_SB_DQ<2>")
	)
	(segment
		(start 169.775378 -281.626564)
		(end 170.048174 -281.626564)
		(width 0.14478)
		(layer "In6.Cu")
		(net "M_K_CPU1_SB_DQ<2>")
	)
	(segment
		(start 190.464694 -281.626564)
		(end 190.748412 -281.910282)
		(width 0.14478)
		(layer "In6.Cu")
		(net "M_K_CPU1_SB_DQ<2>")
	)
	(segment
		(start 167.265604 -281.910282)
		(end 167.549322 -281.626564)
		(width 0.14478)
		(layer "In6.Cu")
		(net "M_K_CPU1_SB_DQ<2>")
	)
	(segment
		(start 157.951678 -277.308056)
		(end 158.383478 -277.308056)
		(width 0.14478)
		(layer "In6.Cu")
		(net "M_K_CPU1_SB_DQ<2>")
	)
	(segment
		(start 174.20463 -281.910282)
		(end 174.462948 -281.651964)
		(width 0.14478)
		(layer "In6.Cu")
		(net "M_K_CPU1_SB_DQ<2>")
	)
	(segment
		(start 157.773878 -276.698456)
		(end 157.773878 -277.130256)
		(width 0.14478)
		(layer "In6.Cu")
		(net "M_K_CPU1_SB_DQ<2>")
	)
	(segment
		(start 167.822118 -281.626564)
		(end 168.105836 -281.910282)
		(width 0.14478)
		(layer "In6.Cu")
		(net "M_K_CPU1_SB_DQ<2>")
	)
	(segment
		(start 194.17919 -281.910282)
		(end 194.604132 -282.335224)
		(width 0.14478)
		(layer "In6.Cu")
		(net "M_K_CPU1_SB_DQ<2>")
	)
	(segment
		(start 193.450972 -281.528266)
		(end 193.712846 -281.528266)
		(width 0.14478)
		(layer "In6.Cu")
		(net "M_K_CPU1_SB_DQ<2>")
	)
	(segment
		(start 177.121312 -281.626564)
		(end 177.40503 -281.910282)
		(width 0.14478)
		(layer "In6.Cu")
		(net "M_K_CPU1_SB_DQ<2>")
	)
	(segment
		(start 189.90818 -281.910282)
		(end 190.191898 -281.626564)
		(width 0.14478)
		(layer "In6.Cu")
		(net "M_K_CPU1_SB_DQ<2>")
	)
	(segment
		(start 146.73326 -273.645884)
		(end 147.319492 -273.645884)
		(width 0.0889)
		(layer "In6.Cu")
		(net "M_K_CPU1_SB_DQ<2>")
	)
	(segment
		(start 193.306192 -281.673046)
		(end 193.450972 -281.528266)
		(width 0.14478)
		(layer "In6.Cu")
		(net "M_K_CPU1_SB_DQ<2>")
	)
	(segment
		(start 159.526478 -278.882856)
		(end 159.958278 -278.882856)
		(width 0.14478)
		(layer "In6.Cu")
		(net "M_K_CPU1_SB_DQ<2>")
	)
	(segment
		(start 159.170878 -278.095456)
		(end 159.348678 -278.273256)
		(width 0.14478)
		(layer "In6.Cu")
		(net "M_K_CPU1_SB_DQ<2>")
	)
	(segment
		(start 160.745678 -279.670256)
		(end 160.923478 -279.848056)
		(width 0.14478)
		(layer "In6.Cu")
		(net "M_K_CPU1_SB_DQ<2>")
	)
	(segment
		(start 174.462948 -281.651964)
		(end 174.761144 -281.651964)
		(width 0.14478)
		(layer "In6.Cu")
		(net "M_K_CPU1_SB_DQ<2>")
	)
	(segment
		(start 174.761144 -281.651964)
		(end 175.019462 -281.910282)
		(width 0.14478)
		(layer "In6.Cu")
		(net "M_K_CPU1_SB_DQ<2>")
	)
	(segment
		(start 181.238144 -282.76042)
		(end 182.088282 -281.910282)
		(width 0.14478)
		(layer "In6.Cu")
		(net "M_K_CPU1_SB_DQ<2>")
	)
	(segment
		(start 145.784062 -274.541488)
		(end 146.64182 -273.68373)
		(width 0.0889)
		(layer "In6.Cu")
		(net "M_K_CPU1_SB_DQ<2>")
	)
	(segment
		(start 160.923478 -280.279856)
		(end 161.101278 -280.457656)
		(width 0.14478)
		(layer "In6.Cu")
		(net "M_K_CPU1_SB_DQ<2>")
	)
	(segment
		(start 192.754758 -281.673046)
		(end 192.754758 -282.147518)
		(width 0.14478)
		(layer "In6.Cu")
		(net "M_K_CPU1_SB_DQ<2>")
	)
	(segment
		(start 176.848516 -281.626564)
		(end 177.121312 -281.626564)
		(width 0.14478)
		(layer "In6.Cu")
		(net "M_K_CPU1_SB_DQ<2>")
	)
	(segment
		(start 158.383478 -277.308056)
		(end 158.561278 -277.485856)
		(width 0.14478)
		(layer "In6.Cu")
		(net "M_K_CPU1_SB_DQ<2>")
	)
	(segment
		(start 147.319492 -273.645884)
		(end 147.570952 -273.394424)
		(width 0.0889)
		(layer "In6.Cu")
		(net "M_K_CPU1_SB_DQ<2>")
	)
	(segment
		(start 179.050188 -282.76042)
		(end 181.238144 -282.76042)
		(width 0.14478)
		(layer "In6.Cu")
		(net "M_K_CPU1_SB_DQ<2>")
	)
	(segment
		(start 154.624278 -273.548856)
		(end 154.624278 -273.980656)
		(width 0.14478)
		(layer "In6.Cu")
		(net "M_K_CPU1_SB_DQ<2>")
	)
	(segment
		(start 190.191898 -281.626564)
		(end 190.464694 -281.626564)
		(width 0.14478)
		(layer "In6.Cu")
		(net "M_K_CPU1_SB_DQ<2>")
	)
	(segment
		(start 147.570952 -273.394424)
		(end 148.048218 -273.394424)
		(width 0.0889)
		(layer "In6.Cu")
		(net "M_K_CPU1_SB_DQ<2>")
	)
	(segment
		(start 169.218864 -281.910282)
		(end 169.49166 -281.910282)
		(width 0.14478)
		(layer "In6.Cu")
		(net "M_K_CPU1_SB_DQ<2>")
	)
	(segment
		(start 192.754758 -282.147518)
		(end 192.899538 -282.292298)
		(width 0.14478)
		(layer "In6.Cu")
		(net "M_K_CPU1_SB_DQ<2>")
	)
	(segment
		(start 161.101278 -280.457656)
		(end 161.533078 -280.457656)
		(width 0.14478)
		(layer "In6.Cu")
		(net "M_K_CPU1_SB_DQ<2>")
	)
	(segment
		(start 142.940786 -274.630896)
		(end 142.963138 -274.547584)
		(width 0.0889)
		(layer "In6.Cu")
		(net "M_K_CPU1_SB_DQ<2>")
	)
	(segment
		(start 192.058544 -281.910282)
		(end 192.203324 -281.765502)
		(width 0.14478)
		(layer "In6.Cu")
		(net "M_K_CPU1_SB_DQ<2>")
	)
	(segment
		(start 193.857626 -281.673046)
		(end 193.857626 -281.765502)
		(width 0.14478)
		(layer "In6.Cu")
		(net "M_K_CPU1_SB_DQ<2>")
	)
	(segment
		(start 169.49166 -281.910282)
		(end 169.775378 -281.626564)
		(width 0.14478)
		(layer "In6.Cu")
		(net "M_K_CPU1_SB_DQ<2>")
	)
	(segment
		(start 191.93383 -281.910282)
		(end 192.058544 -281.910282)
		(width 0.14478)
		(layer "In6.Cu")
		(net "M_K_CPU1_SB_DQ<2>")
	)
	(segment
		(start 188.119004 -282.76042)
		(end 188.969142 -281.910282)
		(width 0.14478)
		(layer "In6.Cu")
		(net "M_K_CPU1_SB_DQ<2>")
	)
	(segment
		(start 144.787366 -274.573746)
		(end 144.795748 -274.56892)
		(width 0.0889)
		(layer "In6.Cu")
		(net "M_K_CPU1_SB_DQ<2>")
	)
	(segment
		(start 160.923478 -279.848056)
		(end 160.923478 -280.279856)
		(width 0.14478)
		(layer "In6.Cu")
		(net "M_K_CPU1_SB_DQ<2>")
	)
	(segment
		(start 176.564798 -281.910282)
		(end 176.848516 -281.626564)
		(width 0.14478)
		(layer "In6.Cu")
		(net "M_K_CPU1_SB_DQ<2>")
	)
	(segment
		(start 160.136078 -279.060656)
		(end 160.136078 -279.492456)
		(width 0.14478)
		(layer "In6.Cu")
		(net "M_K_CPU1_SB_DQ<2>")
	)
	(segment
		(start 170.707304 -281.910282)
		(end 171.557442 -282.76042)
		(width 0.14478)
		(layer "In6.Cu")
		(net "M_K_CPU1_SB_DQ<2>")
	)
	(segment
		(start 156.986478 -275.911056)
		(end 156.986478 -276.342856)
		(width 0.14478)
		(layer "In6.Cu")
		(net "M_K_CPU1_SB_DQ<2>")
	)
	(segment
		(start 155.411678 -274.768056)
		(end 155.589478 -274.945856)
		(width 0.14478)
		(layer "In6.Cu")
		(net "M_K_CPU1_SB_DQ<2>")
	)
	(segment
		(start 161.533078 -280.457656)
		(end 163.835842 -282.76042)
		(width 0.14478)
		(layer "In6.Cu")
		(net "M_K_CPU1_SB_DQ<2>")
	)
	(segment
		(start 194.002406 -281.910282)
		(end 194.17919 -281.910282)
		(width 0.14478)
		(layer "In6.Cu")
		(net "M_K_CPU1_SB_DQ<2>")
	)
	(segment
		(start 182.088282 -281.910282)
		(end 185.270648 -281.910282)
		(width 0.14478)
		(layer "In6.Cu")
		(net "M_K_CPU1_SB_DQ<2>")
	)
	(segment
		(start 156.021278 -274.945856)
		(end 156.199078 -275.123656)
		(width 0.14478)
		(layer "In6.Cu")
		(net "M_K_CPU1_SB_DQ<2>")
	)
	(segment
		(start 171.557442 -282.76042)
		(end 173.02353 -282.76042)
		(width 0.14478)
		(layer "In6.Cu")
		(net "M_K_CPU1_SB_DQ<2>")
	)
	(segment
		(start 143.09471 -274.896326)
		(end 142.940786 -274.630896)
		(width 0.0889)
		(layer "In6.Cu")
		(net "M_K_CPU1_SB_DQ<2>")
	)
	(segment
		(start 185.270648 -281.910282)
		(end 186.120786 -282.76042)
		(width 0.14478)
		(layer "In6.Cu")
		(net "M_K_CPU1_SB_DQ<2>")
	)
	(segment
		(start 160.136078 -279.492456)
		(end 160.313878 -279.670256)
		(width 0.14478)
		(layer "In6.Cu")
		(net "M_K_CPU1_SB_DQ<2>")
	)
	(segment
		(start 193.161412 -282.292298)
		(end 193.306192 -282.147518)
		(width 0.14478)
		(layer "In6.Cu")
		(net "M_K_CPU1_SB_DQ<2>")
	)
	(segment
		(start 158.561278 -277.917656)
		(end 158.739078 -278.095456)
		(width 0.14478)
		(layer "In6.Cu")
		(net "M_K_CPU1_SB_DQ<2>")
	)
	(segment
		(start 191.677036 -281.857958)
		(end 191.88176 -281.858212)
		(width 0.14478)
		(layer "In6.Cu")
		(net "M_K_CPU1_SB_DQ<2>")
	)
	(segment
		(start 168.66235 -281.626564)
		(end 168.935146 -281.626564)
		(width 0.14478)
		(layer "In6.Cu")
		(net "M_K_CPU1_SB_DQ<2>")
	)
	(segment
		(start 168.935146 -281.626564)
		(end 169.218864 -281.910282)
		(width 0.14478)
		(layer "In6.Cu")
		(net "M_K_CPU1_SB_DQ<2>")
	)
	(segment
		(start 192.348104 -281.528266)
		(end 192.609978 -281.528266)
		(width 0.14478)
		(layer "In6.Cu")
		(net "M_K_CPU1_SB_DQ<2>")
	)
	(segment
		(start 178.20005 -281.910282)
		(end 179.050188 -282.76042)
		(width 0.14478)
		(layer "In6.Cu")
		(net "M_K_CPU1_SB_DQ<2>")
	)
	(segment
		(start 186.120786 -282.76042)
		(end 188.119004 -282.76042)
		(width 0.14478)
		(layer "In6.Cu")
		(net "M_K_CPU1_SB_DQ<2>")
	)
	(segment
		(start 192.899538 -282.292298)
		(end 193.161412 -282.292298)
		(width 0.14478)
		(layer "In6.Cu")
		(net "M_K_CPU1_SB_DQ<2>")
	)
	(segment
		(start 144.213326 -274.56892)
		(end 144.221708 -274.573746)
		(width 0.0889)
		(layer "In6.Cu")
		(net "M_K_CPU1_SB_DQ<2>")
	)
	(segment
		(start 191.88176 -281.858212)
		(end 191.93383 -281.910282)
		(width 0.14478)
		(layer "In6.Cu")
		(net "M_K_CPU1_SB_DQ<2>")
	)
	(segment
		(start 173.873668 -281.910282)
		(end 174.20463 -281.910282)
		(width 0.14478)
		(layer "In6.Cu")
		(net "M_K_CPU1_SB_DQ<2>")
	)
	(segment
		(start 192.609978 -281.528266)
		(end 192.754758 -281.673046)
		(width 0.14478)
		(layer "In6.Cu")
		(net "M_K_CPU1_SB_DQ<2>")
	)
	(segment
		(start 191.624712 -281.910282)
		(end 191.677036 -281.857958)
		(width 0.14478)
		(layer "In6.Cu")
		(net "M_K_CPU1_SB_DQ<2>")
	)
	(segment
		(start 144.221708 -274.573746)
		(end 144.232122 -274.579842)
		(width 0.0889)
		(layer "In6.Cu")
		(net "M_K_CPU1_SB_DQ<2>")
	)
	(segment
		(start 193.712846 -281.528266)
		(end 193.857626 -281.673046)
		(width 0.14478)
		(layer "In6.Cu")
		(net "M_K_CPU1_SB_DQ<2>")
	)
	(arc
		(start 143.281654 -274.573746)
		(mid 143.56461 -274.649923)
		(end 143.847566 -274.573746)
		(width 0.0889)
		(layer "In6.Cu")
		(net "M_K_CPU1_SB_DQ<2>")
	)
	(arc
		(start 145.230088 -274.613624)
		(mid 145.519348 -274.671802)
		(end 145.784062 -274.541488)
		(width 0.0889)
		(layer "In6.Cu")
		(net "M_K_CPU1_SB_DQ<2>")
	)
	(arc
		(start 144.232122 -274.579842)
		(mid 144.510554 -274.64994)
		(end 144.787366 -274.573746)
		(width 0.0889)
		(layer "In6.Cu")
		(net "M_K_CPU1_SB_DQ<2>")
	)
	(arc
		(start 146.64182 -273.68373)
		(mid 146.683773 -273.655698)
		(end 146.73326 -273.645884)
		(width 0.0889)
		(layer "In6.Cu")
		(net "M_K_CPU1_SB_DQ<2>")
	)
	(arc
		(start 142.963138 -274.547584)
		(mid 143.125327 -274.524849)
		(end 143.281654 -274.573746)
		(width 0.0889)
		(layer "In6.Cu")
		(net "M_K_CPU1_SB_DQ<2>")
	)
	(arc
		(start 143.847566 -274.573746)
		(mid 144.029817 -274.523396)
		(end 144.213326 -274.56892)
		(width 0.0889)
		(layer "In6.Cu")
		(net "M_K_CPU1_SB_DQ<2>")
	)
	(arc
		(start 144.795748 -274.56892)
		(mid 144.979256 -274.523426)
		(end 145.161508 -274.573746)
		(width 0.0889)
		(layer "In6.Cu")
		(net "M_K_CPU1_SB_DQ<2>")
	)
	(segment
		(start 140.748004 -292.450266)
		(end 141.214856 -292.716204)
		(width 0.10668)
		(layer "F.Cu")
		(net "M_K_CPU1_SB_DQ<29>")
	)
	(segment
		(start 141.967712 -293.038784)
		(end 141.976094 -293.04361)
		(width 0.0889)
		(layer "In6.Cu")
		(net "M_K_CPU1_SB_DQ<29>")
	)
	(segment
		(start 145.810986 -296.509186)
		(end 145.810986 -301.432468)
		(width 0.14478)
		(layer "In6.Cu")
		(net "M_K_CPU1_SB_DQ<29>")
	)
	(segment
		(start 197.366636 -318.014096)
		(end 197.366636 -317.773558)
		(width 0.14478)
		(layer "In6.Cu")
		(net "M_K_CPU1_SB_DQ<29>")
	)
	(segment
		(start 141.36878 -292.981634)
		(end 141.464792 -293.007034)
		(width 0.0889)
		(layer "In6.Cu")
		(net "M_K_CPU1_SB_DQ<29>")
	)
	(segment
		(start 154.971496 -309.456074)
		(end 154.971496 -310.583072)
		(width 0.14478)
		(layer "In6.Cu")
		(net "M_K_CPU1_SB_DQ<29>")
	)
	(segment
		(start 197.366636 -317.773558)
		(end 197.529704 -317.61049)
		(width 0.14478)
		(layer "In6.Cu")
		(net "M_K_CPU1_SB_DQ<29>")
	)
	(segment
		(start 144.756886 -294.641016)
		(end 144.787366 -294.658796)
		(width 0.0889)
		(layer "In6.Cu")
		(net "M_K_CPU1_SB_DQ<29>")
	)
	(segment
		(start 144.317466 -293.84879)
		(end 144.356582 -293.87165)
		(width 0.0889)
		(layer "In6.Cu")
		(net "M_K_CPU1_SB_DQ<29>")
	)
	(segment
		(start 143.847566 -293.038784)
		(end 143.886682 -293.061644)
		(width 0.0889)
		(layer "In6.Cu")
		(net "M_K_CPU1_SB_DQ<29>")
	)
	(segment
		(start 196.97319 -318.177164)
		(end 197.203568 -318.177164)
		(width 0.14478)
		(layer "In6.Cu")
		(net "M_K_CPU1_SB_DQ<29>")
	)
	(segment
		(start 197.203568 -318.177164)
		(end 197.366636 -318.014096)
		(width 0.14478)
		(layer "In6.Cu")
		(net "M_K_CPU1_SB_DQ<29>")
	)
	(segment
		(start 145.808446 -296.2529)
		(end 145.810986 -296.509186)
		(width 0.0889)
		(layer "In6.Cu")
		(net "M_K_CPU1_SB_DQ<29>")
	)
	(segment
		(start 196.810122 -318.014096)
		(end 196.97319 -318.177164)
		(width 0.14478)
		(layer "In6.Cu")
		(net "M_K_CPU1_SB_DQ<29>")
	)
	(segment
		(start 197.529704 -317.61049)
		(end 198.279004 -317.61049)
		(width 0.14478)
		(layer "In6.Cu")
		(net "M_K_CPU1_SB_DQ<29>")
	)
	(segment
		(start 196.810122 -317.773558)
		(end 196.810122 -318.014096)
		(width 0.14478)
		(layer "In6.Cu")
		(net "M_K_CPU1_SB_DQ<29>")
	)
	(segment
		(start 150.744682 -306.366164)
		(end 151.881586 -306.366164)
		(width 0.14478)
		(layer "In6.Cu")
		(net "M_K_CPU1_SB_DQ<29>")
	)
	(segment
		(start 160.546288 -316.157864)
		(end 164.053266 -317.61049)
		(width 0.14478)
		(layer "In6.Cu")
		(net "M_K_CPU1_SB_DQ<29>")
	)
	(segment
		(start 144.286986 -293.83101)
		(end 144.317466 -293.84879)
		(width 0.0889)
		(layer "In6.Cu")
		(net "M_K_CPU1_SB_DQ<29>")
	)
	(segment
		(start 198.279004 -317.61049)
		(end 198.7042 -317.185294)
		(width 0.14478)
		(layer "In6.Cu")
		(net "M_K_CPU1_SB_DQ<29>")
	)
	(segment
		(start 144.787366 -294.658796)
		(end 144.826482 -294.681656)
		(width 0.0889)
		(layer "In6.Cu")
		(net "M_K_CPU1_SB_DQ<29>")
	)
	(segment
		(start 196.647054 -317.61049)
		(end 196.810122 -317.773558)
		(width 0.14478)
		(layer "In6.Cu")
		(net "M_K_CPU1_SB_DQ<29>")
	)
	(segment
		(start 141.214856 -292.716204)
		(end 141.36878 -292.981634)
		(width 0.0889)
		(layer "In6.Cu")
		(net "M_K_CPU1_SB_DQ<29>")
	)
	(segment
		(start 145.810986 -301.432468)
		(end 150.744682 -306.366164)
		(width 0.14478)
		(layer "In6.Cu")
		(net "M_K_CPU1_SB_DQ<29>")
	)
	(segment
		(start 154.971496 -310.583072)
		(end 160.546288 -316.157864)
		(width 0.14478)
		(layer "In6.Cu")
		(net "M_K_CPU1_SB_DQ<29>")
	)
	(segment
		(start 145.745962 -296.18559)
		(end 145.808446 -296.2529)
		(width 0.0889)
		(layer "In6.Cu")
		(net "M_K_CPU1_SB_DQ<29>")
	)
	(segment
		(start 164.053266 -317.61049)
		(end 196.647054 -317.61049)
		(width 0.14478)
		(layer "In6.Cu")
		(net "M_K_CPU1_SB_DQ<29>")
	)
	(segment
		(start 151.881586 -306.366164)
		(end 154.971496 -309.456074)
		(width 0.14478)
		(layer "In6.Cu")
		(net "M_K_CPU1_SB_DQ<29>")
	)
	(arc
		(start 144.599914 -294.336216)
		(mid 144.641463 -294.507638)
		(end 144.756886 -294.641016)
		(width 0.0889)
		(layer "In6.Cu")
		(net "M_K_CPU1_SB_DQ<29>")
	)
	(arc
		(start 142.907766 -293.038784)
		(mid 143.09471 -293.089039)
		(end 143.281654 -293.038784)
		(width 0.0889)
		(layer "In6.Cu")
		(net "M_K_CPU1_SB_DQ<29>")
	)
	(arc
		(start 142.341854 -293.038784)
		(mid 142.62481 -292.962607)
		(end 142.907766 -293.038784)
		(width 0.0889)
		(layer "In6.Cu")
		(net "M_K_CPU1_SB_DQ<29>")
	)
	(arc
		(start 143.281654 -293.038784)
		(mid 143.56461 -292.962607)
		(end 143.847566 -293.038784)
		(width 0.0889)
		(layer "In6.Cu")
		(net "M_K_CPU1_SB_DQ<29>")
	)
	(arc
		(start 143.886682 -293.061644)
		(mid 144.065495 -293.263994)
		(end 144.130014 -293.52621)
		(width 0.0889)
		(layer "In6.Cu")
		(net "M_K_CPU1_SB_DQ<29>")
	)
	(arc
		(start 145.229326 -295.444926)
		(mid 145.268319 -295.466299)
		(end 145.305526 -295.490646)
		(width 0.0889)
		(layer "In6.Cu")
		(net "M_K_CPU1_SB_DQ<29>")
	)
	(arc
		(start 141.464792 -293.007034)
		(mid 141.72 -292.963557)
		(end 141.967712 -293.038784)
		(width 0.0889)
		(layer "In6.Cu")
		(net "M_K_CPU1_SB_DQ<29>")
	)
	(arc
		(start 141.976094 -293.04361)
		(mid 142.159602 -293.089104)
		(end 142.341854 -293.038784)
		(width 0.0889)
		(layer "In6.Cu")
		(net "M_K_CPU1_SB_DQ<29>")
	)
	(arc
		(start 144.356582 -293.87165)
		(mid 144.535395 -294.074)
		(end 144.599914 -294.336216)
		(width 0.0889)
		(layer "In6.Cu")
		(net "M_K_CPU1_SB_DQ<29>")
	)
	(arc
		(start 145.076418 -295.146222)
		(mid 145.112495 -295.316243)
		(end 145.229326 -295.444926)
		(width 0.0889)
		(layer "In6.Cu")
		(net "M_K_CPU1_SB_DQ<29>")
	)
	(arc
		(start 145.305526 -295.490646)
		(mid 145.343396 -295.519973)
		(end 145.378678 -295.552368)
		(width 0.0889)
		(layer "In6.Cu")
		(net "M_K_CPU1_SB_DQ<29>")
	)
	(arc
		(start 145.378678 -295.552368)
		(mid 145.494341 -295.701388)
		(end 145.569432 -295.87444)
		(width 0.0889)
		(layer "In6.Cu")
		(net "M_K_CPU1_SB_DQ<29>")
	)
	(arc
		(start 144.826482 -294.681656)
		(mid 145.016798 -294.878786)
		(end 145.076418 -295.146222)
		(width 0.0889)
		(layer "In6.Cu")
		(net "M_K_CPU1_SB_DQ<29>")
	)
	(arc
		(start 145.569432 -295.87444)
		(mid 145.639572 -296.040297)
		(end 145.745962 -296.18559)
		(width 0.0889)
		(layer "In6.Cu")
		(net "M_K_CPU1_SB_DQ<29>")
	)
	(arc
		(start 144.130014 -293.52621)
		(mid 144.171563 -293.697632)
		(end 144.286986 -293.83101)
		(width 0.0889)
		(layer "In6.Cu")
		(net "M_K_CPU1_SB_DQ<29>")
	)
	(segment
		(start 142.157958 -291.64026)
		(end 142.62481 -291.906198)
		(width 0.10668)
		(layer "F.Cu")
		(net "M_K_CPU1_SB_DQ<28>")
	)
	(segment
		(start 198.279004 -315.910468)
		(end 198.7042 -315.485272)
		(width 0.14478)
		(layer "In6.Cu")
		(net "M_K_CPU1_SB_DQ<28>")
	)
	(segment
		(start 145.920206 -294.708326)
		(end 146.110198 -294.898318)
		(width 0.0889)
		(layer "In6.Cu")
		(net "M_K_CPU1_SB_DQ<28>")
	)
	(segment
		(start 197.527926 -316.073536)
		(end 197.690994 -315.910468)
		(width 0.14478)
		(layer "In6.Cu")
		(net "M_K_CPU1_SB_DQ<28>")
	)
	(segment
		(start 144.75714 -293.021004)
		(end 144.78762 -293.038784)
		(width 0.0889)
		(layer "In6.Cu")
		(net "M_K_CPU1_SB_DQ<28>")
	)
	(segment
		(start 195.858384 -316.073536)
		(end 195.858384 -316.642496)
		(width 0.14478)
		(layer "In6.Cu")
		(net "M_K_CPU1_SB_DQ<28>")
	)
	(segment
		(start 145.22704 -293.83101)
		(end 145.25752 -293.84879)
		(width 0.0889)
		(layer "In6.Cu")
		(net "M_K_CPU1_SB_DQ<28>")
	)
	(segment
		(start 197.364858 -316.805564)
		(end 197.527926 -316.642496)
		(width 0.14478)
		(layer "In6.Cu")
		(net "M_K_CPU1_SB_DQ<28>")
	)
	(segment
		(start 196.25183 -316.805564)
		(end 196.414898 -316.642496)
		(width 0.14478)
		(layer "In6.Cu")
		(net "M_K_CPU1_SB_DQ<28>")
	)
	(segment
		(start 196.414898 -316.073536)
		(end 196.577966 -315.910468)
		(width 0.14478)
		(layer "In6.Cu")
		(net "M_K_CPU1_SB_DQ<28>")
	)
	(segment
		(start 146.750786 -296.517822)
		(end 146.750786 -299.889164)
		(width 0.14478)
		(layer "In6.Cu")
		(net "M_K_CPU1_SB_DQ<28>")
	)
	(segment
		(start 197.690994 -315.910468)
		(end 198.279004 -315.910468)
		(width 0.14478)
		(layer "In6.Cu")
		(net "M_K_CPU1_SB_DQ<28>")
	)
	(segment
		(start 146.750786 -295.584626)
		(end 146.750786 -296.517822)
		(width 0.0889)
		(layer "In6.Cu")
		(net "M_K_CPU1_SB_DQ<28>")
	)
	(segment
		(start 196.577966 -315.910468)
		(end 196.808344 -315.910468)
		(width 0.14478)
		(layer "In6.Cu")
		(net "M_K_CPU1_SB_DQ<28>")
	)
	(segment
		(start 160.963356 -314.946792)
		(end 163.313364 -315.92012)
		(width 0.14478)
		(layer "In6.Cu")
		(net "M_K_CPU1_SB_DQ<28>")
	)
	(segment
		(start 145.25752 -293.84879)
		(end 145.296636 -293.87165)
		(width 0.0889)
		(layer "In6.Cu")
		(net "M_K_CPU1_SB_DQ<28>")
	)
	(segment
		(start 196.021452 -316.805564)
		(end 196.25183 -316.805564)
		(width 0.14478)
		(layer "In6.Cu")
		(net "M_K_CPU1_SB_DQ<28>")
	)
	(segment
		(start 196.414898 -316.642496)
		(end 196.414898 -316.073536)
		(width 0.14478)
		(layer "In6.Cu")
		(net "M_K_CPU1_SB_DQ<28>")
	)
	(segment
		(start 144.31772 -292.228778)
		(end 144.356836 -292.251638)
		(width 0.0889)
		(layer "In6.Cu")
		(net "M_K_CPU1_SB_DQ<28>")
	)
	(segment
		(start 145.906236 -294.708326)
		(end 145.920206 -294.708326)
		(width 0.0889)
		(layer "In6.Cu")
		(net "M_K_CPU1_SB_DQ<28>")
	)
	(segment
		(start 146.110198 -294.898318)
		(end 146.110198 -294.944038)
		(width 0.0889)
		(layer "In6.Cu")
		(net "M_K_CPU1_SB_DQ<28>")
	)
	(segment
		(start 142.62481 -291.906198)
		(end 142.778734 -292.171628)
		(width 0.0889)
		(layer "In6.Cu")
		(net "M_K_CPU1_SB_DQ<28>")
	)
	(segment
		(start 146.110198 -294.944038)
		(end 146.750786 -295.584626)
		(width 0.0889)
		(layer "In6.Cu")
		(net "M_K_CPU1_SB_DQ<28>")
	)
	(segment
		(start 155.979876 -309.118254)
		(end 155.979876 -309.963312)
		(width 0.14478)
		(layer "In6.Cu")
		(net "M_K_CPU1_SB_DQ<28>")
	)
	(segment
		(start 144.78762 -293.038784)
		(end 144.826736 -293.061644)
		(width 0.0889)
		(layer "In6.Cu")
		(net "M_K_CPU1_SB_DQ<28>")
	)
	(segment
		(start 197.13448 -316.805564)
		(end 197.364858 -316.805564)
		(width 0.14478)
		(layer "In6.Cu")
		(net "M_K_CPU1_SB_DQ<28>")
	)
	(segment
		(start 195.858384 -316.642496)
		(end 196.021452 -316.805564)
		(width 0.14478)
		(layer "In6.Cu")
		(net "M_K_CPU1_SB_DQ<28>")
	)
	(segment
		(start 143.377666 -292.228778)
		(end 143.386048 -292.233604)
		(width 0.0889)
		(layer "In6.Cu")
		(net "M_K_CPU1_SB_DQ<28>")
	)
	(segment
		(start 155.979876 -309.963312)
		(end 160.963356 -314.946792)
		(width 0.14478)
		(layer "In6.Cu")
		(net "M_K_CPU1_SB_DQ<28>")
	)
	(segment
		(start 196.971412 -316.073536)
		(end 196.971412 -316.642496)
		(width 0.14478)
		(layer "In6.Cu")
		(net "M_K_CPU1_SB_DQ<28>")
	)
	(segment
		(start 196.971412 -316.642496)
		(end 197.13448 -316.805564)
		(width 0.14478)
		(layer "In6.Cu")
		(net "M_K_CPU1_SB_DQ<28>")
	)
	(segment
		(start 163.313364 -315.92012)
		(end 195.704968 -315.92012)
		(width 0.14478)
		(layer "In6.Cu")
		(net "M_K_CPU1_SB_DQ<28>")
	)
	(segment
		(start 195.704968 -315.92012)
		(end 195.858384 -316.073536)
		(width 0.14478)
		(layer "In6.Cu")
		(net "M_K_CPU1_SB_DQ<28>")
	)
	(segment
		(start 142.778734 -292.171628)
		(end 142.874746 -292.197028)
		(width 0.0889)
		(layer "In6.Cu")
		(net "M_K_CPU1_SB_DQ<28>")
	)
	(segment
		(start 196.808344 -315.910468)
		(end 196.971412 -316.073536)
		(width 0.14478)
		(layer "In6.Cu")
		(net "M_K_CPU1_SB_DQ<28>")
	)
	(segment
		(start 197.527926 -316.642496)
		(end 197.527926 -316.073536)
		(width 0.14478)
		(layer "In6.Cu")
		(net "M_K_CPU1_SB_DQ<28>")
	)
	(segment
		(start 146.750786 -299.889164)
		(end 155.979876 -309.118254)
		(width 0.14478)
		(layer "In6.Cu")
		(net "M_K_CPU1_SB_DQ<28>")
	)
	(arc
		(start 144.600168 -292.716204)
		(mid 144.641717 -292.887626)
		(end 144.75714 -293.021004)
		(width 0.0889)
		(layer "In6.Cu")
		(net "M_K_CPU1_SB_DQ<28>")
	)
	(arc
		(start 145.689574 -294.635682)
		(mid 145.695867 -294.640158)
		(end 145.702528 -294.644064)
		(width 0.0889)
		(layer "In6.Cu")
		(net "M_K_CPU1_SB_DQ<28>")
	)
	(arc
		(start 145.070068 -293.52621)
		(mid 145.111617 -293.697632)
		(end 145.22704 -293.83101)
		(width 0.0889)
		(layer "In6.Cu")
		(net "M_K_CPU1_SB_DQ<28>")
	)
	(arc
		(start 142.874746 -292.197028)
		(mid 143.129954 -292.153551)
		(end 143.377666 -292.228778)
		(width 0.0889)
		(layer "In6.Cu")
		(net "M_K_CPU1_SB_DQ<28>")
	)
	(arc
		(start 145.296636 -293.87165)
		(mid 145.475449 -294.074)
		(end 145.539968 -294.336216)
		(width 0.0889)
		(layer "In6.Cu")
		(net "M_K_CPU1_SB_DQ<28>")
	)
	(arc
		(start 145.702528 -294.644064)
		(mid 145.801726 -294.684616)
		(end 145.906236 -294.708326)
		(width 0.0889)
		(layer "In6.Cu")
		(net "M_K_CPU1_SB_DQ<28>")
	)
	(arc
		(start 143.386048 -292.233604)
		(mid 143.569556 -292.279098)
		(end 143.751808 -292.228778)
		(width 0.0889)
		(layer "In6.Cu")
		(net "M_K_CPU1_SB_DQ<28>")
	)
	(arc
		(start 144.826736 -293.061644)
		(mid 145.005549 -293.263994)
		(end 145.070068 -293.52621)
		(width 0.0889)
		(layer "In6.Cu")
		(net "M_K_CPU1_SB_DQ<28>")
	)
	(arc
		(start 145.539968 -294.336216)
		(mid 145.579441 -294.503606)
		(end 145.689574 -294.635682)
		(width 0.0889)
		(layer "In6.Cu")
		(net "M_K_CPU1_SB_DQ<28>")
	)
	(arc
		(start 143.751808 -292.228778)
		(mid 144.034764 -292.152601)
		(end 144.31772 -292.228778)
		(width 0.0889)
		(layer "In6.Cu")
		(net "M_K_CPU1_SB_DQ<28>")
	)
	(arc
		(start 144.356836 -292.251638)
		(mid 144.535649 -292.453988)
		(end 144.600168 -292.716204)
		(width 0.0889)
		(layer "In6.Cu")
		(net "M_K_CPU1_SB_DQ<28>")
	)
	(segment
		(start 141.217904 -290.020248)
		(end 141.684756 -290.286186)
		(width 0.10668)
		(layer "F.Cu")
		(net "M_K_CPU1_SB_DQ<27>")
	)
	(segment
		(start 156.632148 -305.759358)
		(end 156.86278 -305.759358)
		(width 0.14478)
		(layer "In6.Cu")
		(net "M_K_CPU1_SB_DQ<27>")
	)
	(segment
		(start 156.407612 -305.983894)
		(end 156.632148 -305.759358)
		(width 0.14478)
		(layer "In6.Cu")
		(net "M_K_CPU1_SB_DQ<27>")
	)
	(segment
		(start 144.647412 -289.782504)
		(end 145.503646 -289.782504)
		(width 0.0889)
		(layer "In6.Cu")
		(net "M_K_CPU1_SB_DQ<27>")
	)
	(segment
		(start 157.195012 -306.771294)
		(end 157.419548 -306.546758)
		(width 0.14478)
		(layer "In6.Cu")
		(net "M_K_CPU1_SB_DQ<27>")
	)
	(segment
		(start 149.366986 -294.978328)
		(end 149.366986 -299.1739)
		(width 0.14478)
		(layer "In6.Cu")
		(net "M_K_CPU1_SB_DQ<27>")
	)
	(segment
		(start 145.503646 -289.782504)
		(end 145.976086 -290.254944)
		(width 0.0889)
		(layer "In6.Cu")
		(net "M_K_CPU1_SB_DQ<27>")
	)
	(segment
		(start 141.530832 -290.020756)
		(end 141.553184 -289.937444)
		(width 0.0889)
		(layer "In6.Cu")
		(net "M_K_CPU1_SB_DQ<27>")
	)
	(segment
		(start 188.640466 -312.500518)
		(end 189.49035 -311.650634)
		(width 0.14478)
		(layer "In6.Cu")
		(net "M_K_CPU1_SB_DQ<27>")
	)
	(segment
		(start 194.169538 -311.650634)
		(end 194.604132 -312.085228)
		(width 0.14478)
		(layer "In6.Cu")
		(net "M_K_CPU1_SB_DQ<27>")
	)
	(segment
		(start 185.311796 -311.650634)
		(end 186.16168 -312.500518)
		(width 0.14478)
		(layer "In6.Cu")
		(net "M_K_CPU1_SB_DQ<27>")
	)
	(segment
		(start 181.03596 -312.500772)
		(end 181.886098 -311.650634)
		(width 0.14478)
		(layer "In6.Cu")
		(net "M_K_CPU1_SB_DQ<27>")
	)
	(segment
		(start 145.976086 -290.254944)
		(end 145.976086 -291.171884)
		(width 0.0889)
		(layer "In6.Cu")
		(net "M_K_CPU1_SB_DQ<27>")
	)
	(segment
		(start 156.013912 -305.590194)
		(end 156.013912 -305.820826)
		(width 0.14478)
		(layer "In6.Cu")
		(net "M_K_CPU1_SB_DQ<27>")
	)
	(segment
		(start 145.976086 -291.171884)
		(end 146.679666 -291.875464)
		(width 0.0889)
		(layer "In6.Cu")
		(net "M_K_CPU1_SB_DQ<27>")
	)
	(segment
		(start 156.801312 -306.377594)
		(end 156.801312 -306.608226)
		(width 0.14478)
		(layer "In6.Cu")
		(net "M_K_CPU1_SB_DQ<27>")
	)
	(segment
		(start 166.81577 -311.650634)
		(end 169.944796 -311.650634)
		(width 0.14478)
		(layer "In6.Cu")
		(net "M_K_CPU1_SB_DQ<27>")
	)
	(segment
		(start 157.025848 -306.153058)
		(end 156.801312 -306.377594)
		(width 0.14478)
		(layer "In6.Cu")
		(net "M_K_CPU1_SB_DQ<27>")
	)
	(segment
		(start 157.75178 -307.558694)
		(end 157.982412 -307.558694)
		(width 0.14478)
		(layer "In6.Cu")
		(net "M_K_CPU1_SB_DQ<27>")
	)
	(segment
		(start 158.600648 -307.497226)
		(end 158.600648 -307.727858)
		(width 0.14478)
		(layer "In6.Cu")
		(net "M_K_CPU1_SB_DQ<27>")
	)
	(segment
		(start 155.38958 -305.196494)
		(end 155.620212 -305.196494)
		(width 0.14478)
		(layer "In6.Cu")
		(net "M_K_CPU1_SB_DQ<27>")
	)
	(segment
		(start 149.366986 -299.1739)
		(end 155.38958 -305.196494)
		(width 0.14478)
		(layer "In6.Cu")
		(net "M_K_CPU1_SB_DQ<27>")
	)
	(segment
		(start 189.49035 -311.650634)
		(end 194.169538 -311.650634)
		(width 0.14478)
		(layer "In6.Cu")
		(net "M_K_CPU1_SB_DQ<27>")
	)
	(segment
		(start 156.96438 -306.771294)
		(end 157.195012 -306.771294)
		(width 0.14478)
		(layer "In6.Cu")
		(net "M_K_CPU1_SB_DQ<27>")
	)
	(segment
		(start 157.813248 -306.940458)
		(end 157.588712 -307.164994)
		(width 0.14478)
		(layer "In6.Cu")
		(net "M_K_CPU1_SB_DQ<27>")
	)
	(segment
		(start 141.684756 -290.286186)
		(end 141.530832 -290.020756)
		(width 0.0889)
		(layer "In6.Cu")
		(net "M_K_CPU1_SB_DQ<27>")
	)
	(segment
		(start 156.801312 -306.608226)
		(end 156.96438 -306.771294)
		(width 0.14478)
		(layer "In6.Cu")
		(net "M_K_CPU1_SB_DQ<27>")
	)
	(segment
		(start 157.025848 -305.922426)
		(end 157.025848 -306.153058)
		(width 0.14478)
		(layer "In6.Cu")
		(net "M_K_CPU1_SB_DQ<27>")
	)
	(segment
		(start 165.95598 -312.510424)
		(end 166.81577 -311.650634)
		(width 0.14478)
		(layer "In6.Cu")
		(net "M_K_CPU1_SB_DQ<27>")
	)
	(segment
		(start 155.844748 -304.971958)
		(end 156.07538 -304.971958)
		(width 0.14478)
		(layer "In6.Cu")
		(net "M_K_CPU1_SB_DQ<27>")
	)
	(segment
		(start 174.342044 -311.650634)
		(end 177.91557 -311.650634)
		(width 0.14478)
		(layer "In6.Cu")
		(net "M_K_CPU1_SB_DQ<27>")
	)
	(segment
		(start 144.307052 -289.969702)
		(end 144.647412 -289.782504)
		(width 0.0889)
		(layer "In6.Cu")
		(net "M_K_CPU1_SB_DQ<27>")
	)
	(segment
		(start 142.803372 -289.95878)
		(end 142.811754 -289.963606)
		(width 0.0889)
		(layer "In6.Cu")
		(net "M_K_CPU1_SB_DQ<27>")
	)
	(segment
		(start 173.491906 -312.500772)
		(end 174.342044 -311.650634)
		(width 0.14478)
		(layer "In6.Cu")
		(net "M_K_CPU1_SB_DQ<27>")
	)
	(segment
		(start 155.620212 -305.196494)
		(end 155.844748 -304.971958)
		(width 0.14478)
		(layer "In6.Cu")
		(net "M_K_CPU1_SB_DQ<27>")
	)
	(segment
		(start 158.376112 -307.952394)
		(end 158.376112 -308.183026)
		(width 0.14478)
		(layer "In6.Cu")
		(net "M_K_CPU1_SB_DQ<27>")
	)
	(segment
		(start 143.377666 -289.963606)
		(end 143.386048 -289.95878)
		(width 0.0889)
		(layer "In6.Cu")
		(net "M_K_CPU1_SB_DQ<27>")
	)
	(segment
		(start 158.600648 -307.727858)
		(end 158.376112 -307.952394)
		(width 0.14478)
		(layer "In6.Cu")
		(net "M_K_CPU1_SB_DQ<27>")
	)
	(segment
		(start 156.17698 -305.983894)
		(end 156.407612 -305.983894)
		(width 0.14478)
		(layer "In6.Cu")
		(net "M_K_CPU1_SB_DQ<27>")
	)
	(segment
		(start 177.91557 -311.650634)
		(end 178.765708 -312.500772)
		(width 0.14478)
		(layer "In6.Cu")
		(net "M_K_CPU1_SB_DQ<27>")
	)
	(segment
		(start 186.16168 -312.500518)
		(end 188.640466 -312.500518)
		(width 0.14478)
		(layer "In6.Cu")
		(net "M_K_CPU1_SB_DQ<27>")
	)
	(segment
		(start 158.376112 -308.183026)
		(end 162.70351 -312.510424)
		(width 0.14478)
		(layer "In6.Cu")
		(net "M_K_CPU1_SB_DQ<27>")
	)
	(segment
		(start 146.679666 -291.875464)
		(end 146.679666 -292.596824)
		(width 0.0889)
		(layer "In6.Cu")
		(net "M_K_CPU1_SB_DQ<27>")
	)
	(segment
		(start 146.679666 -292.596824)
		(end 146.91233 -292.829488)
		(width 0.0889)
		(layer "In6.Cu")
		(net "M_K_CPU1_SB_DQ<27>")
	)
	(segment
		(start 170.794934 -312.500772)
		(end 173.491906 -312.500772)
		(width 0.14478)
		(layer "In6.Cu")
		(net "M_K_CPU1_SB_DQ<27>")
	)
	(segment
		(start 158.43758 -307.334158)
		(end 158.600648 -307.497226)
		(width 0.14478)
		(layer "In6.Cu")
		(net "M_K_CPU1_SB_DQ<27>")
	)
	(segment
		(start 147.218146 -292.829488)
		(end 147.839684 -293.451026)
		(width 0.0889)
		(layer "In6.Cu")
		(net "M_K_CPU1_SB_DQ<27>")
	)
	(segment
		(start 156.238448 -305.135026)
		(end 156.238448 -305.365658)
		(width 0.14478)
		(layer "In6.Cu")
		(net "M_K_CPU1_SB_DQ<27>")
	)
	(segment
		(start 169.944796 -311.650634)
		(end 170.794934 -312.500772)
		(width 0.14478)
		(layer "In6.Cu")
		(net "M_K_CPU1_SB_DQ<27>")
	)
	(segment
		(start 157.588712 -307.395626)
		(end 157.75178 -307.558694)
		(width 0.14478)
		(layer "In6.Cu")
		(net "M_K_CPU1_SB_DQ<27>")
	)
	(segment
		(start 157.982412 -307.558694)
		(end 158.206948 -307.334158)
		(width 0.14478)
		(layer "In6.Cu")
		(net "M_K_CPU1_SB_DQ<27>")
	)
	(segment
		(start 158.206948 -307.334158)
		(end 158.43758 -307.334158)
		(width 0.14478)
		(layer "In6.Cu")
		(net "M_K_CPU1_SB_DQ<27>")
	)
	(segment
		(start 156.86278 -305.759358)
		(end 157.025848 -305.922426)
		(width 0.14478)
		(layer "In6.Cu")
		(net "M_K_CPU1_SB_DQ<27>")
	)
	(segment
		(start 146.91233 -292.829488)
		(end 147.218146 -292.829488)
		(width 0.0889)
		(layer "In6.Cu")
		(net "M_K_CPU1_SB_DQ<27>")
	)
	(segment
		(start 156.013912 -305.820826)
		(end 156.17698 -305.983894)
		(width 0.14478)
		(layer "In6.Cu")
		(net "M_K_CPU1_SB_DQ<27>")
	)
	(segment
		(start 157.813248 -306.709826)
		(end 157.813248 -306.940458)
		(width 0.14478)
		(layer "In6.Cu")
		(net "M_K_CPU1_SB_DQ<27>")
	)
	(segment
		(start 157.588712 -307.164994)
		(end 157.588712 -307.395626)
		(width 0.14478)
		(layer "In6.Cu")
		(net "M_K_CPU1_SB_DQ<27>")
	)
	(segment
		(start 162.70351 -312.510424)
		(end 165.95598 -312.510424)
		(width 0.14478)
		(layer "In6.Cu")
		(net "M_K_CPU1_SB_DQ<27>")
	)
	(segment
		(start 147.839684 -293.451026)
		(end 149.366986 -294.978328)
		(width 0.14478)
		(layer "In6.Cu")
		(net "M_K_CPU1_SB_DQ<27>")
	)
	(segment
		(start 178.765708 -312.500772)
		(end 181.03596 -312.500772)
		(width 0.14478)
		(layer "In6.Cu")
		(net "M_K_CPU1_SB_DQ<27>")
	)
	(segment
		(start 156.07538 -304.971958)
		(end 156.238448 -305.135026)
		(width 0.14478)
		(layer "In6.Cu")
		(net "M_K_CPU1_SB_DQ<27>")
	)
	(segment
		(start 157.65018 -306.546758)
		(end 157.813248 -306.709826)
		(width 0.14478)
		(layer "In6.Cu")
		(net "M_K_CPU1_SB_DQ<27>")
	)
	(segment
		(start 157.419548 -306.546758)
		(end 157.65018 -306.546758)
		(width 0.14478)
		(layer "In6.Cu")
		(net "M_K_CPU1_SB_DQ<27>")
	)
	(segment
		(start 156.238448 -305.365658)
		(end 156.013912 -305.590194)
		(width 0.14478)
		(layer "In6.Cu")
		(net "M_K_CPU1_SB_DQ<27>")
	)
	(segment
		(start 181.886098 -311.650634)
		(end 185.311796 -311.650634)
		(width 0.14478)
		(layer "In6.Cu")
		(net "M_K_CPU1_SB_DQ<27>")
	)
	(arc
		(start 143.751808 -289.963606)
		(mid 144.028621 -290.039749)
		(end 144.307052 -289.969702)
		(width 0.0889)
		(layer "In6.Cu")
		(net "M_K_CPU1_SB_DQ<27>")
	)
	(arc
		(start 141.553184 -289.937444)
		(mid 141.715373 -289.914709)
		(end 141.8717 -289.963606)
		(width 0.0889)
		(layer "In6.Cu")
		(net "M_K_CPU1_SB_DQ<27>")
	)
	(arc
		(start 142.437612 -289.963606)
		(mid 142.619863 -289.913256)
		(end 142.803372 -289.95878)
		(width 0.0889)
		(layer "In6.Cu")
		(net "M_K_CPU1_SB_DQ<27>")
	)
	(arc
		(start 142.811754 -289.963606)
		(mid 143.09471 -290.039783)
		(end 143.377666 -289.963606)
		(width 0.0889)
		(layer "In6.Cu")
		(net "M_K_CPU1_SB_DQ<27>")
	)
	(arc
		(start 141.8717 -289.963606)
		(mid 142.154656 -290.039783)
		(end 142.437612 -289.963606)
		(width 0.0889)
		(layer "In6.Cu")
		(net "M_K_CPU1_SB_DQ<27>")
	)
	(arc
		(start 143.386048 -289.95878)
		(mid 143.569556 -289.913286)
		(end 143.751808 -289.963606)
		(width 0.0889)
		(layer "In6.Cu")
		(net "M_K_CPU1_SB_DQ<27>")
	)
	(segment
		(start 142.627858 -289.210242)
		(end 143.09471 -289.47618)
		(width 0.10668)
		(layer "F.Cu")
		(net "M_K_CPU1_SB_DQ<26>")
	)
	(segment
		(start 166.150036 -310.810402)
		(end 167.000174 -309.960264)
		(width 0.14478)
		(layer "In6.Cu")
		(net "M_K_CPU1_SB_DQ<26>")
	)
	(segment
		(start 163.279074 -310.810402)
		(end 166.150036 -310.810402)
		(width 0.14478)
		(layer "In6.Cu")
		(net "M_K_CPU1_SB_DQ<26>")
	)
	(segment
		(start 193.048382 -309.815484)
		(end 193.048382 -309.722266)
		(width 0.14478)
		(layer "In6.Cu")
		(net "M_K_CPU1_SB_DQ<26>")
	)
	(segment
		(start 153.837132 -301.36846)
		(end 153.837386 -301.599092)
		(width 0.14478)
		(layer "In6.Cu")
		(net "M_K_CPU1_SB_DQ<26>")
	)
	(segment
		(start 151.645366 -299.853858)
		(end 151.868632 -299.630592)
		(width 0.14478)
		(layer "In6.Cu")
		(net "M_K_CPU1_SB_DQ<26>")
	)
	(segment
		(start 152.262332 -299.79366)
		(end 152.262586 -300.024292)
		(width 0.14478)
		(layer "In6.Cu")
		(net "M_K_CPU1_SB_DQ<26>")
	)
	(segment
		(start 155.352242 -303.791112)
		(end 155.582366 -303.790858)
		(width 0.14478)
		(layer "In6.Cu")
		(net "M_K_CPU1_SB_DQ<26>")
	)
	(segment
		(start 154.007566 -302.216058)
		(end 154.230832 -301.992792)
		(width 0.14478)
		(layer "In6.Cu")
		(net "M_K_CPU1_SB_DQ<26>")
	)
	(segment
		(start 193.048382 -309.722266)
		(end 193.193162 -309.577486)
		(width 0.14478)
		(layer "In6.Cu")
		(net "M_K_CPU1_SB_DQ<26>")
	)
	(segment
		(start 155.248864 -302.780192)
		(end 155.411932 -302.94326)
		(width 0.14478)
		(layer "In6.Cu")
		(net "M_K_CPU1_SB_DQ<26>")
	)
	(segment
		(start 193.599816 -309.722266)
		(end 193.599816 -309.815484)
		(width 0.14478)
		(layer "In6.Cu")
		(net "M_K_CPU1_SB_DQ<26>")
	)
	(segment
		(start 152.03932 -300.247558)
		(end 152.03932 -300.47819)
		(width 0.14478)
		(layer "In6.Cu")
		(net "M_K_CPU1_SB_DQ<26>")
	)
	(segment
		(start 155.805632 -303.567592)
		(end 156.036264 -303.567592)
		(width 0.14478)
		(layer "In6.Cu")
		(net "M_K_CPU1_SB_DQ<26>")
	)
	(segment
		(start 152.990042 -301.428912)
		(end 153.220166 -301.428658)
		(width 0.14478)
		(layer "In6.Cu")
		(net "M_K_CPU1_SB_DQ<26>")
	)
	(segment
		(start 154.230832 -301.992792)
		(end 154.461464 -301.992792)
		(width 0.14478)
		(layer "In6.Cu")
		(net "M_K_CPU1_SB_DQ<26>")
	)
	(segment
		(start 155.018232 -302.780192)
		(end 155.248864 -302.780192)
		(width 0.14478)
		(layer "In6.Cu")
		(net "M_K_CPU1_SB_DQ<26>")
	)
	(segment
		(start 181.238144 -310.810402)
		(end 182.088282 -309.960264)
		(width 0.14478)
		(layer "In6.Cu")
		(net "M_K_CPU1_SB_DQ<26>")
	)
	(segment
		(start 151.415242 -299.854112)
		(end 151.645366 -299.853858)
		(width 0.14478)
		(layer "In6.Cu")
		(net "M_K_CPU1_SB_DQ<26>")
	)
	(segment
		(start 153.837386 -301.599092)
		(end 153.61412 -301.822358)
		(width 0.14478)
		(layer "In6.Cu")
		(net "M_K_CPU1_SB_DQ<26>")
	)
	(segment
		(start 155.582366 -303.790858)
		(end 155.805632 -303.567592)
		(width 0.14478)
		(layer "In6.Cu")
		(net "M_K_CPU1_SB_DQ<26>")
	)
	(segment
		(start 151.868632 -299.630592)
		(end 152.099264 -299.630592)
		(width 0.14478)
		(layer "In6.Cu")
		(net "M_K_CPU1_SB_DQ<26>")
	)
	(segment
		(start 193.455036 -309.577486)
		(end 193.599816 -309.722266)
		(width 0.14478)
		(layer "In6.Cu")
		(net "M_K_CPU1_SB_DQ<26>")
	)
	(segment
		(start 156.036264 -303.567592)
		(end 163.279074 -310.810402)
		(width 0.14478)
		(layer "In6.Cu")
		(net "M_K_CPU1_SB_DQ<26>")
	)
	(segment
		(start 151.474932 -299.00626)
		(end 151.475186 -299.236892)
		(width 0.14478)
		(layer "In6.Cu")
		(net "M_K_CPU1_SB_DQ<26>")
	)
	(segment
		(start 154.40152 -302.84039)
		(end 154.564842 -303.003712)
		(width 0.14478)
		(layer "In6.Cu")
		(net "M_K_CPU1_SB_DQ<26>")
	)
	(segment
		(start 177.726594 -309.960264)
		(end 178.576732 -310.810402)
		(width 0.14478)
		(layer "In6.Cu")
		(net "M_K_CPU1_SB_DQ<26>")
	)
	(segment
		(start 171.032678 -310.810402)
		(end 173.69409 -310.810402)
		(width 0.14478)
		(layer "In6.Cu")
		(net "M_K_CPU1_SB_DQ<26>")
	)
	(segment
		(start 150.46452 -298.90339)
		(end 150.627842 -299.066712)
		(width 0.14478)
		(layer "In6.Cu")
		(net "M_K_CPU1_SB_DQ<26>")
	)
	(segment
		(start 182.088282 -309.960264)
		(end 185.03138 -309.960264)
		(width 0.14478)
		(layer "In6.Cu")
		(net "M_K_CPU1_SB_DQ<26>")
	)
	(segment
		(start 150.357586 -294.682418)
		(end 150.357586 -297.888914)
		(width 0.14478)
		(layer "In6.Cu")
		(net "M_K_CPU1_SB_DQ<26>")
	)
	(segment
		(start 151.25192 -299.460158)
		(end 151.25192 -299.69079)
		(width 0.14478)
		(layer "In6.Cu")
		(net "M_K_CPU1_SB_DQ<26>")
	)
	(segment
		(start 154.564842 -303.003712)
		(end 154.794966 -303.003458)
		(width 0.14478)
		(layer "In6.Cu")
		(net "M_K_CPU1_SB_DQ<26>")
	)
	(segment
		(start 185.881264 -310.810148)
		(end 188.684916 -310.810148)
		(width 0.14478)
		(layer "In6.Cu")
		(net "M_K_CPU1_SB_DQ<26>")
	)
	(segment
		(start 153.049732 -300.58106)
		(end 153.049986 -300.811692)
		(width 0.14478)
		(layer "In6.Cu")
		(net "M_K_CPU1_SB_DQ<26>")
	)
	(segment
		(start 152.262586 -300.024292)
		(end 152.03932 -300.247558)
		(width 0.14478)
		(layer "In6.Cu")
		(net "M_K_CPU1_SB_DQ<26>")
	)
	(segment
		(start 153.61412 -302.05299)
		(end 153.777442 -302.216312)
		(width 0.14478)
		(layer "In6.Cu")
		(net "M_K_CPU1_SB_DQ<26>")
	)
	(segment
		(start 152.886664 -300.417992)
		(end 153.049732 -300.58106)
		(width 0.14478)
		(layer "In6.Cu")
		(net "M_K_CPU1_SB_DQ<26>")
	)
	(segment
		(start 170.18254 -309.960264)
		(end 171.032678 -310.810402)
		(width 0.14478)
		(layer "In6.Cu")
		(net "M_K_CPU1_SB_DQ<26>")
	)
	(segment
		(start 152.82672 -301.034958)
		(end 152.82672 -301.26559)
		(width 0.14478)
		(layer "In6.Cu")
		(net "M_K_CPU1_SB_DQ<26>")
	)
	(segment
		(start 154.624532 -302.15586)
		(end 154.624786 -302.386492)
		(width 0.14478)
		(layer "In6.Cu")
		(net "M_K_CPU1_SB_DQ<26>")
	)
	(segment
		(start 167.000174 -309.960264)
		(end 170.18254 -309.960264)
		(width 0.14478)
		(layer "In6.Cu")
		(net "M_K_CPU1_SB_DQ<26>")
	)
	(segment
		(start 153.049986 -300.811692)
		(end 152.82672 -301.034958)
		(width 0.14478)
		(layer "In6.Cu")
		(net "M_K_CPU1_SB_DQ<26>")
	)
	(segment
		(start 154.40152 -302.609758)
		(end 154.40152 -302.84039)
		(width 0.14478)
		(layer "In6.Cu")
		(net "M_K_CPU1_SB_DQ<26>")
	)
	(segment
		(start 193.744596 -309.960264)
		(end 194.17919 -309.960264)
		(width 0.14478)
		(layer "In6.Cu")
		(net "M_K_CPU1_SB_DQ<26>")
	)
	(segment
		(start 193.599816 -309.815484)
		(end 193.744596 -309.960264)
		(width 0.14478)
		(layer "In6.Cu")
		(net "M_K_CPU1_SB_DQ<26>")
	)
	(segment
		(start 152.099264 -299.630592)
		(end 152.262332 -299.79366)
		(width 0.14478)
		(layer "In6.Cu")
		(net "M_K_CPU1_SB_DQ<26>")
	)
	(segment
		(start 153.61412 -301.822358)
		(end 153.61412 -302.05299)
		(width 0.14478)
		(layer "In6.Cu")
		(net "M_K_CPU1_SB_DQ<26>")
	)
	(segment
		(start 193.193162 -309.577486)
		(end 193.455036 -309.577486)
		(width 0.14478)
		(layer "In6.Cu")
		(net "M_K_CPU1_SB_DQ<26>")
	)
	(segment
		(start 153.443432 -301.205392)
		(end 153.674064 -301.205392)
		(width 0.14478)
		(layer "In6.Cu")
		(net "M_K_CPU1_SB_DQ<26>")
	)
	(segment
		(start 150.687532 -298.21886)
		(end 150.687786 -298.449492)
		(width 0.14478)
		(layer "In6.Cu")
		(net "M_K_CPU1_SB_DQ<26>")
	)
	(segment
		(start 146.405346 -290.730178)
		(end 147.792948 -292.11778)
		(width 0.0889)
		(layer "In6.Cu")
		(net "M_K_CPU1_SB_DQ<26>")
	)
	(segment
		(start 150.687786 -298.449492)
		(end 150.46452 -298.672758)
		(width 0.14478)
		(layer "In6.Cu")
		(net "M_K_CPU1_SB_DQ<26>")
	)
	(segment
		(start 155.412186 -303.173892)
		(end 155.18892 -303.397158)
		(width 0.14478)
		(layer "In6.Cu")
		(net "M_K_CPU1_SB_DQ<26>")
	)
	(segment
		(start 151.475186 -299.236892)
		(end 151.25192 -299.460158)
		(width 0.14478)
		(layer "In6.Cu")
		(net "M_K_CPU1_SB_DQ<26>")
	)
	(segment
		(start 173.69409 -310.810402)
		(end 174.544228 -309.960264)
		(width 0.14478)
		(layer "In6.Cu")
		(net "M_K_CPU1_SB_DQ<26>")
	)
	(segment
		(start 150.46452 -298.672758)
		(end 150.46452 -298.90339)
		(width 0.14478)
		(layer "In6.Cu")
		(net "M_K_CPU1_SB_DQ<26>")
	)
	(segment
		(start 152.656032 -300.417992)
		(end 152.886664 -300.417992)
		(width 0.14478)
		(layer "In6.Cu")
		(net "M_K_CPU1_SB_DQ<26>")
	)
	(segment
		(start 143.09471 -289.47618)
		(end 142.940786 -289.21075)
		(width 0.0889)
		(layer "In6.Cu")
		(net "M_K_CPU1_SB_DQ<26>")
	)
	(segment
		(start 146.405346 -290.092384)
		(end 146.405346 -290.730178)
		(width 0.0889)
		(layer "In6.Cu")
		(net "M_K_CPU1_SB_DQ<26>")
	)
	(segment
		(start 147.792948 -292.11778)
		(end 150.357586 -294.682418)
		(width 0.14478)
		(layer "In6.Cu")
		(net "M_K_CPU1_SB_DQ<26>")
	)
	(segment
		(start 155.18892 -303.397158)
		(end 155.18892 -303.62779)
		(width 0.14478)
		(layer "In6.Cu")
		(net "M_K_CPU1_SB_DQ<26>")
	)
	(segment
		(start 144.213326 -289.148774)
		(end 144.387062 -289.245548)
		(width 0.0889)
		(layer "In6.Cu")
		(net "M_K_CPU1_SB_DQ<26>")
	)
	(segment
		(start 188.684916 -310.810148)
		(end 189.5348 -309.960264)
		(width 0.14478)
		(layer "In6.Cu")
		(net "M_K_CPU1_SB_DQ<26>")
	)
	(segment
		(start 154.624786 -302.386492)
		(end 154.40152 -302.609758)
		(width 0.14478)
		(layer "In6.Cu")
		(net "M_K_CPU1_SB_DQ<26>")
	)
	(segment
		(start 189.5348 -309.960264)
		(end 192.903602 -309.960264)
		(width 0.14478)
		(layer "In6.Cu")
		(net "M_K_CPU1_SB_DQ<26>")
	)
	(segment
		(start 154.794966 -303.003458)
		(end 155.018232 -302.780192)
		(width 0.14478)
		(layer "In6.Cu")
		(net "M_K_CPU1_SB_DQ<26>")
	)
	(segment
		(start 154.461464 -301.992792)
		(end 154.624532 -302.15586)
		(width 0.14478)
		(layer "In6.Cu")
		(net "M_K_CPU1_SB_DQ<26>")
	)
	(segment
		(start 152.202642 -300.641512)
		(end 152.432766 -300.641258)
		(width 0.14478)
		(layer "In6.Cu")
		(net "M_K_CPU1_SB_DQ<26>")
	)
	(segment
		(start 152.03932 -300.47819)
		(end 152.202642 -300.641512)
		(width 0.14478)
		(layer "In6.Cu")
		(net "M_K_CPU1_SB_DQ<26>")
	)
	(segment
		(start 150.357586 -297.888914)
		(end 150.687532 -298.21886)
		(width 0.14478)
		(layer "In6.Cu")
		(net "M_K_CPU1_SB_DQ<26>")
	)
	(segment
		(start 145.60296 -289.289998)
		(end 146.405346 -290.092384)
		(width 0.0889)
		(layer "In6.Cu")
		(net "M_K_CPU1_SB_DQ<26>")
	)
	(segment
		(start 151.311864 -298.843192)
		(end 151.474932 -299.00626)
		(width 0.14478)
		(layer "In6.Cu")
		(net "M_K_CPU1_SB_DQ<26>")
	)
	(segment
		(start 144.430496 -289.256724)
		(end 145.522696 -289.256724)
		(width 0.0889)
		(layer "In6.Cu")
		(net "M_K_CPU1_SB_DQ<26>")
	)
	(segment
		(start 153.220166 -301.428658)
		(end 153.443432 -301.205392)
		(width 0.14478)
		(layer "In6.Cu")
		(net "M_K_CPU1_SB_DQ<26>")
	)
	(segment
		(start 151.25192 -299.69079)
		(end 151.415242 -299.854112)
		(width 0.14478)
		(layer "In6.Cu")
		(net "M_K_CPU1_SB_DQ<26>")
	)
	(segment
		(start 150.627842 -299.066712)
		(end 150.857966 -299.066458)
		(width 0.14478)
		(layer "In6.Cu")
		(net "M_K_CPU1_SB_DQ<26>")
	)
	(segment
		(start 150.857966 -299.066458)
		(end 151.081232 -298.843192)
		(width 0.14478)
		(layer "In6.Cu")
		(net "M_K_CPU1_SB_DQ<26>")
	)
	(segment
		(start 155.411932 -302.94326)
		(end 155.412186 -303.173892)
		(width 0.14478)
		(layer "In6.Cu")
		(net "M_K_CPU1_SB_DQ<26>")
	)
	(segment
		(start 194.17919 -309.960264)
		(end 194.604132 -310.385206)
		(width 0.14478)
		(layer "In6.Cu")
		(net "M_K_CPU1_SB_DQ<26>")
	)
	(segment
		(start 155.18892 -303.62779)
		(end 155.352242 -303.791112)
		(width 0.14478)
		(layer "In6.Cu")
		(net "M_K_CPU1_SB_DQ<26>")
	)
	(segment
		(start 152.82672 -301.26559)
		(end 152.990042 -301.428912)
		(width 0.14478)
		(layer "In6.Cu")
		(net "M_K_CPU1_SB_DQ<26>")
	)
	(segment
		(start 178.576732 -310.810402)
		(end 181.238144 -310.810402)
		(width 0.14478)
		(layer "In6.Cu")
		(net "M_K_CPU1_SB_DQ<26>")
	)
	(segment
		(start 153.777442 -302.216312)
		(end 154.007566 -302.216058)
		(width 0.14478)
		(layer "In6.Cu")
		(net "M_K_CPU1_SB_DQ<26>")
	)
	(segment
		(start 153.674064 -301.205392)
		(end 153.837132 -301.36846)
		(width 0.14478)
		(layer "In6.Cu")
		(net "M_K_CPU1_SB_DQ<26>")
	)
	(segment
		(start 142.940786 -289.21075)
		(end 142.963138 -289.127438)
		(width 0.0889)
		(layer "In6.Cu")
		(net "M_K_CPU1_SB_DQ<26>")
	)
	(segment
		(start 174.544228 -309.960264)
		(end 177.726594 -309.960264)
		(width 0.14478)
		(layer "In6.Cu")
		(net "M_K_CPU1_SB_DQ<26>")
	)
	(segment
		(start 192.903602 -309.960264)
		(end 193.048382 -309.815484)
		(width 0.14478)
		(layer "In6.Cu")
		(net "M_K_CPU1_SB_DQ<26>")
	)
	(segment
		(start 151.081232 -298.843192)
		(end 151.311864 -298.843192)
		(width 0.14478)
		(layer "In6.Cu")
		(net "M_K_CPU1_SB_DQ<26>")
	)
	(segment
		(start 185.03138 -309.960264)
		(end 185.881264 -310.810148)
		(width 0.14478)
		(layer "In6.Cu")
		(net "M_K_CPU1_SB_DQ<26>")
	)
	(segment
		(start 152.432766 -300.641258)
		(end 152.656032 -300.417992)
		(width 0.14478)
		(layer "In6.Cu")
		(net "M_K_CPU1_SB_DQ<26>")
	)
	(arc
		(start 143.847566 -289.1536)
		(mid 144.029817 -289.10325)
		(end 144.213326 -289.148774)
		(width 0.0889)
		(layer "In6.Cu")
		(net "M_K_CPU1_SB_DQ<26>")
	)
	(arc
		(start 144.387062 -289.245548)
		(mid 144.408066 -289.253903)
		(end 144.430496 -289.256724)
		(width 0.0889)
		(layer "In6.Cu")
		(net "M_K_CPU1_SB_DQ<26>")
	)
	(arc
		(start 143.281654 -289.1536)
		(mid 143.56461 -289.229777)
		(end 143.847566 -289.1536)
		(width 0.0889)
		(layer "In6.Cu")
		(net "M_K_CPU1_SB_DQ<26>")
	)
	(arc
		(start 145.522696 -289.256724)
		(mid 145.566131 -289.265382)
		(end 145.60296 -289.289998)
		(width 0.0889)
		(layer "In6.Cu")
		(net "M_K_CPU1_SB_DQ<26>")
	)
	(arc
		(start 142.963138 -289.127438)
		(mid 143.125327 -289.104703)
		(end 143.281654 -289.1536)
		(width 0.0889)
		(layer "In6.Cu")
		(net "M_K_CPU1_SB_DQ<26>")
	)
	(segment
		(start 140.748004 -289.210242)
		(end 141.214856 -289.47618)
		(width 0.10668)
		(layer "F.Cu")
		(net "M_K_CPU1_SB_DQ<25>")
	)
	(segment
		(start 189.507622 -310.810148)
		(end 198.279258 -310.810148)
		(width 0.14478)
		(layer "In6.Cu")
		(net "M_K_CPU1_SB_DQ<25>")
	)
	(segment
		(start 181.974236 -310.810402)
		(end 185.144664 -310.810402)
		(width 0.14478)
		(layer "In6.Cu")
		(net "M_K_CPU1_SB_DQ<25>")
	)
	(segment
		(start 149.874986 -294.8432)
		(end 149.874986 -299.038518)
		(width 0.14478)
		(layer "In6.Cu")
		(net "M_K_CPU1_SB_DQ<25>")
	)
	(segment
		(start 147.630388 -292.500558)
		(end 147.630388 -292.598602)
		(width 0.0889)
		(layer "In6.Cu")
		(net "M_K_CPU1_SB_DQ<25>")
	)
	(segment
		(start 170.216576 -310.810402)
		(end 171.06646 -311.660286)
		(width 0.14478)
		(layer "In6.Cu")
		(net "M_K_CPU1_SB_DQ<25>")
	)
	(segment
		(start 177.76063 -310.810402)
		(end 178.610514 -311.660286)
		(width 0.14478)
		(layer "In6.Cu")
		(net "M_K_CPU1_SB_DQ<25>")
	)
	(segment
		(start 147.883626 -292.85184)
		(end 149.874986 -294.8432)
		(width 0.14478)
		(layer "In6.Cu")
		(net "M_K_CPU1_SB_DQ<25>")
	)
	(segment
		(start 156.07284 -304.283364)
		(end 163.449762 -311.660286)
		(width 0.14478)
		(layer "In6.Cu")
		(net "M_K_CPU1_SB_DQ<25>")
	)
	(segment
		(start 141.36878 -289.74161)
		(end 141.464792 -289.76701)
		(width 0.0889)
		(layer "In6.Cu")
		(net "M_K_CPU1_SB_DQ<25>")
	)
	(segment
		(start 178.610514 -311.660286)
		(end 181.124352 -311.660286)
		(width 0.14478)
		(layer "In6.Cu")
		(net "M_K_CPU1_SB_DQ<25>")
	)
	(segment
		(start 198.279258 -310.810148)
		(end 198.7042 -311.23509)
		(width 0.14478)
		(layer "In6.Cu")
		(net "M_K_CPU1_SB_DQ<25>")
	)
	(segment
		(start 146.179286 -290.170616)
		(end 146.179286 -291.049456)
		(width 0.0889)
		(layer "In6.Cu")
		(net "M_K_CPU1_SB_DQ<25>")
	)
	(segment
		(start 171.06646 -311.660286)
		(end 173.580298 -311.660286)
		(width 0.14478)
		(layer "In6.Cu")
		(net "M_K_CPU1_SB_DQ<25>")
	)
	(segment
		(start 149.874986 -299.038518)
		(end 155.119832 -304.283364)
		(width 0.14478)
		(layer "In6.Cu")
		(net "M_K_CPU1_SB_DQ<25>")
	)
	(segment
		(start 144.597374 -289.576764)
		(end 145.585434 -289.576764)
		(width 0.0889)
		(layer "In6.Cu")
		(net "M_K_CPU1_SB_DQ<25>")
	)
	(segment
		(start 198.7042 -311.23509)
		(end 198.7042 -311.235344)
		(width 0.14478)
		(layer "In6.Cu")
		(net "M_K_CPU1_SB_DQ<25>")
	)
	(segment
		(start 147.630388 -292.598602)
		(end 147.883626 -292.85184)
		(width 0.0889)
		(layer "In6.Cu")
		(net "M_K_CPU1_SB_DQ<25>")
	)
	(segment
		(start 185.144664 -310.810402)
		(end 185.994294 -311.660032)
		(width 0.14478)
		(layer "In6.Cu")
		(net "M_K_CPU1_SB_DQ<25>")
	)
	(segment
		(start 163.449762 -311.660286)
		(end 166.036244 -311.660286)
		(width 0.14478)
		(layer "In6.Cu")
		(net "M_K_CPU1_SB_DQ<25>")
	)
	(segment
		(start 166.886128 -310.810402)
		(end 170.216576 -310.810402)
		(width 0.14478)
		(layer "In6.Cu")
		(net "M_K_CPU1_SB_DQ<25>")
	)
	(segment
		(start 141.967712 -289.79876)
		(end 141.976094 -289.803586)
		(width 0.0889)
		(layer "In6.Cu")
		(net "M_K_CPU1_SB_DQ<25>")
	)
	(segment
		(start 166.036244 -311.660286)
		(end 166.886128 -310.810402)
		(width 0.14478)
		(layer "In6.Cu")
		(net "M_K_CPU1_SB_DQ<25>")
	)
	(segment
		(start 145.585434 -289.576764)
		(end 146.179286 -290.170616)
		(width 0.0889)
		(layer "In6.Cu")
		(net "M_K_CPU1_SB_DQ<25>")
	)
	(segment
		(start 144.20977 -289.805618)
		(end 144.597374 -289.576764)
		(width 0.0889)
		(layer "In6.Cu")
		(net "M_K_CPU1_SB_DQ<25>")
	)
	(segment
		(start 185.994294 -311.660032)
		(end 188.657738 -311.660032)
		(width 0.14478)
		(layer "In6.Cu")
		(net "M_K_CPU1_SB_DQ<25>")
	)
	(segment
		(start 181.124352 -311.660286)
		(end 181.974236 -310.810402)
		(width 0.14478)
		(layer "In6.Cu")
		(net "M_K_CPU1_SB_DQ<25>")
	)
	(segment
		(start 173.580298 -311.660286)
		(end 174.430182 -310.810402)
		(width 0.14478)
		(layer "In6.Cu")
		(net "M_K_CPU1_SB_DQ<25>")
	)
	(segment
		(start 155.119832 -304.283364)
		(end 156.07284 -304.283364)
		(width 0.14478)
		(layer "In6.Cu")
		(net "M_K_CPU1_SB_DQ<25>")
	)
	(segment
		(start 141.214856 -289.47618)
		(end 141.36878 -289.74161)
		(width 0.0889)
		(layer "In6.Cu")
		(net "M_K_CPU1_SB_DQ<25>")
	)
	(segment
		(start 146.179286 -291.049456)
		(end 147.630388 -292.500558)
		(width 0.0889)
		(layer "In6.Cu")
		(net "M_K_CPU1_SB_DQ<25>")
	)
	(segment
		(start 174.430182 -310.810402)
		(end 177.76063 -310.810402)
		(width 0.14478)
		(layer "In6.Cu")
		(net "M_K_CPU1_SB_DQ<25>")
	)
	(segment
		(start 188.657738 -311.660032)
		(end 189.507622 -310.810148)
		(width 0.14478)
		(layer "In6.Cu")
		(net "M_K_CPU1_SB_DQ<25>")
	)
	(arc
		(start 143.847566 -289.79876)
		(mid 144.027771 -289.849077)
		(end 144.20977 -289.805618)
		(width 0.0889)
		(layer "In6.Cu")
		(net "M_K_CPU1_SB_DQ<25>")
	)
	(arc
		(start 143.281654 -289.79876)
		(mid 143.56461 -289.722583)
		(end 143.847566 -289.79876)
		(width 0.0889)
		(layer "In6.Cu")
		(net "M_K_CPU1_SB_DQ<25>")
	)
	(arc
		(start 142.907766 -289.79876)
		(mid 143.09471 -289.849015)
		(end 143.281654 -289.79876)
		(width 0.0889)
		(layer "In6.Cu")
		(net "M_K_CPU1_SB_DQ<25>")
	)
	(arc
		(start 141.976094 -289.803586)
		(mid 142.159602 -289.84908)
		(end 142.341854 -289.79876)
		(width 0.0889)
		(layer "In6.Cu")
		(net "M_K_CPU1_SB_DQ<25>")
	)
	(arc
		(start 142.341854 -289.79876)
		(mid 142.62481 -289.722583)
		(end 142.907766 -289.79876)
		(width 0.0889)
		(layer "In6.Cu")
		(net "M_K_CPU1_SB_DQ<25>")
	)
	(arc
		(start 141.464792 -289.76701)
		(mid 141.72 -289.723533)
		(end 141.967712 -289.79876)
		(width 0.0889)
		(layer "In6.Cu")
		(net "M_K_CPU1_SB_DQ<25>")
	)
	(segment
		(start 142.157958 -288.400236)
		(end 142.62481 -288.666174)
		(width 0.10668)
		(layer "F.Cu")
		(net "M_K_CPU1_SB_DQ<24>")
	)
	(segment
		(start 167.092884 -309.11038)
		(end 170.117516 -309.11038)
		(width 0.14478)
		(layer "In6.Cu")
		(net "M_K_CPU1_SB_DQ<24>")
	)
	(segment
		(start 144.544796 -289.044126)
		(end 145.639028 -289.044126)
		(width 0.0889)
		(layer "In6.Cu")
		(net "M_K_CPU1_SB_DQ<24>")
	)
	(segment
		(start 196.201538 -310.075326)
		(end 196.463412 -310.075326)
		(width 0.14478)
		(layer "In6.Cu")
		(net "M_K_CPU1_SB_DQ<24>")
	)
	(segment
		(start 145.719292 -289.0774)
		(end 146.853656 -290.211764)
		(width 0.0889)
		(layer "In6.Cu")
		(net "M_K_CPU1_SB_DQ<24>")
	)
	(segment
		(start 178.511454 -309.960264)
		(end 181.331108 -309.960264)
		(width 0.14478)
		(layer "In6.Cu")
		(net "M_K_CPU1_SB_DQ<24>")
	)
	(segment
		(start 196.056758 -309.254906)
		(end 196.056758 -309.930546)
		(width 0.14478)
		(layer "In6.Cu")
		(net "M_K_CPU1_SB_DQ<24>")
	)
	(segment
		(start 198.279258 -309.110126)
		(end 198.7042 -309.535068)
		(width 0.14478)
		(layer "In6.Cu")
		(net "M_K_CPU1_SB_DQ<24>")
	)
	(segment
		(start 196.608192 -309.930546)
		(end 196.608192 -309.254906)
		(width 0.14478)
		(layer "In6.Cu")
		(net "M_K_CPU1_SB_DQ<24>")
	)
	(segment
		(start 163.14039 -309.960264)
		(end 166.243 -309.960264)
		(width 0.14478)
		(layer "In6.Cu")
		(net "M_K_CPU1_SB_DQ<24>")
	)
	(segment
		(start 174.636938 -309.11038)
		(end 177.66157 -309.11038)
		(width 0.14478)
		(layer "In6.Cu")
		(net "M_K_CPU1_SB_DQ<24>")
	)
	(segment
		(start 147.558506 -291.24021)
		(end 147.831556 -291.51326)
		(width 0.0889)
		(layer "In6.Cu")
		(net "M_K_CPU1_SB_DQ<24>")
	)
	(segment
		(start 146.853656 -290.211764)
		(end 146.943572 -290.211764)
		(width 0.0889)
		(layer "In6.Cu")
		(net "M_K_CPU1_SB_DQ<24>")
	)
	(segment
		(start 197.159626 -309.930546)
		(end 197.304406 -310.075326)
		(width 0.14478)
		(layer "In6.Cu")
		(net "M_K_CPU1_SB_DQ<24>")
	)
	(segment
		(start 142.62481 -288.666174)
		(end 142.778734 -288.931604)
		(width 0.0889)
		(layer "In6.Cu")
		(net "M_K_CPU1_SB_DQ<24>")
	)
	(segment
		(start 197.014846 -309.110126)
		(end 197.159626 -309.254906)
		(width 0.14478)
		(layer "In6.Cu")
		(net "M_K_CPU1_SB_DQ<24>")
	)
	(segment
		(start 147.558506 -290.826698)
		(end 147.558506 -291.24021)
		(width 0.0889)
		(layer "In6.Cu")
		(net "M_K_CPU1_SB_DQ<24>")
	)
	(segment
		(start 173.787054 -309.960264)
		(end 174.636938 -309.11038)
		(width 0.14478)
		(layer "In6.Cu")
		(net "M_K_CPU1_SB_DQ<24>")
	)
	(segment
		(start 196.056758 -309.930546)
		(end 196.201538 -310.075326)
		(width 0.14478)
		(layer "In6.Cu")
		(net "M_K_CPU1_SB_DQ<24>")
	)
	(segment
		(start 197.159626 -309.254906)
		(end 197.159626 -309.930546)
		(width 0.14478)
		(layer "In6.Cu")
		(net "M_K_CPU1_SB_DQ<24>")
	)
	(segment
		(start 147.831556 -291.51326)
		(end 150.814786 -294.49649)
		(width 0.14478)
		(layer "In6.Cu")
		(net "M_K_CPU1_SB_DQ<24>")
	)
	(segment
		(start 188.676534 -309.96001)
		(end 189.526418 -309.110126)
		(width 0.14478)
		(layer "In6.Cu")
		(net "M_K_CPU1_SB_DQ<24>")
	)
	(segment
		(start 185.818018 -309.96001)
		(end 188.676534 -309.96001)
		(width 0.14478)
		(layer "In6.Cu")
		(net "M_K_CPU1_SB_DQ<24>")
	)
	(segment
		(start 150.814786 -294.49649)
		(end 150.814786 -297.63466)
		(width 0.14478)
		(layer "In6.Cu")
		(net "M_K_CPU1_SB_DQ<24>")
	)
	(segment
		(start 184.968388 -309.11038)
		(end 185.818018 -309.96001)
		(width 0.14478)
		(layer "In6.Cu")
		(net "M_K_CPU1_SB_DQ<24>")
	)
	(segment
		(start 170.9674 -309.960264)
		(end 173.787054 -309.960264)
		(width 0.14478)
		(layer "In6.Cu")
		(net "M_K_CPU1_SB_DQ<24>")
	)
	(segment
		(start 197.71106 -309.254906)
		(end 197.85584 -309.110126)
		(width 0.14478)
		(layer "In6.Cu")
		(net "M_K_CPU1_SB_DQ<24>")
	)
	(segment
		(start 196.608192 -309.254906)
		(end 196.752972 -309.110126)
		(width 0.14478)
		(layer "In6.Cu")
		(net "M_K_CPU1_SB_DQ<24>")
	)
	(segment
		(start 150.814786 -297.63466)
		(end 163.14039 -309.960264)
		(width 0.14478)
		(layer "In6.Cu")
		(net "M_K_CPU1_SB_DQ<24>")
	)
	(segment
		(start 143.377666 -288.988754)
		(end 143.386048 -288.99358)
		(width 0.0889)
		(layer "In6.Cu")
		(net "M_K_CPU1_SB_DQ<24>")
	)
	(segment
		(start 142.778734 -288.931604)
		(end 142.874746 -288.957004)
		(width 0.0889)
		(layer "In6.Cu")
		(net "M_K_CPU1_SB_DQ<24>")
	)
	(segment
		(start 196.463412 -310.075326)
		(end 196.608192 -309.930546)
		(width 0.14478)
		(layer "In6.Cu")
		(net "M_K_CPU1_SB_DQ<24>")
	)
	(segment
		(start 198.7042 -309.535068)
		(end 198.7042 -309.535322)
		(width 0.14478)
		(layer "In6.Cu")
		(net "M_K_CPU1_SB_DQ<24>")
	)
	(segment
		(start 181.331108 -309.960264)
		(end 182.180992 -309.11038)
		(width 0.14478)
		(layer "In6.Cu")
		(net "M_K_CPU1_SB_DQ<24>")
	)
	(segment
		(start 182.180992 -309.11038)
		(end 184.968388 -309.11038)
		(width 0.14478)
		(layer "In6.Cu")
		(net "M_K_CPU1_SB_DQ<24>")
	)
	(segment
		(start 196.752972 -309.110126)
		(end 197.014846 -309.110126)
		(width 0.14478)
		(layer "In6.Cu")
		(net "M_K_CPU1_SB_DQ<24>")
	)
	(segment
		(start 197.304406 -310.075326)
		(end 197.56628 -310.075326)
		(width 0.14478)
		(layer "In6.Cu")
		(net "M_K_CPU1_SB_DQ<24>")
	)
	(segment
		(start 166.243 -309.960264)
		(end 167.092884 -309.11038)
		(width 0.14478)
		(layer "In6.Cu")
		(net "M_K_CPU1_SB_DQ<24>")
	)
	(segment
		(start 189.526418 -309.110126)
		(end 195.911978 -309.110126)
		(width 0.14478)
		(layer "In6.Cu")
		(net "M_K_CPU1_SB_DQ<24>")
	)
	(segment
		(start 197.71106 -309.930546)
		(end 197.71106 -309.254906)
		(width 0.14478)
		(layer "In6.Cu")
		(net "M_K_CPU1_SB_DQ<24>")
	)
	(segment
		(start 146.943572 -290.211764)
		(end 147.558506 -290.826698)
		(width 0.0889)
		(layer "In6.Cu")
		(net "M_K_CPU1_SB_DQ<24>")
	)
	(segment
		(start 177.66157 -309.11038)
		(end 178.511454 -309.960264)
		(width 0.14478)
		(layer "In6.Cu")
		(net "M_K_CPU1_SB_DQ<24>")
	)
	(segment
		(start 195.911978 -309.110126)
		(end 196.056758 -309.254906)
		(width 0.14478)
		(layer "In6.Cu")
		(net "M_K_CPU1_SB_DQ<24>")
	)
	(segment
		(start 170.117516 -309.11038)
		(end 170.9674 -309.960264)
		(width 0.14478)
		(layer "In6.Cu")
		(net "M_K_CPU1_SB_DQ<24>")
	)
	(segment
		(start 197.56628 -310.075326)
		(end 197.71106 -309.930546)
		(width 0.14478)
		(layer "In6.Cu")
		(net "M_K_CPU1_SB_DQ<24>")
	)
	(segment
		(start 197.85584 -309.110126)
		(end 198.279258 -309.110126)
		(width 0.14478)
		(layer "In6.Cu")
		(net "M_K_CPU1_SB_DQ<24>")
	)
	(arc
		(start 144.307052 -288.982658)
		(mid 144.422023 -289.028466)
		(end 144.544796 -289.044126)
		(width 0.0889)
		(layer "In6.Cu")
		(net "M_K_CPU1_SB_DQ<24>")
	)
	(arc
		(start 143.386048 -288.99358)
		(mid 143.569556 -289.039074)
		(end 143.751808 -288.988754)
		(width 0.0889)
		(layer "In6.Cu")
		(net "M_K_CPU1_SB_DQ<24>")
	)
	(arc
		(start 142.874746 -288.957004)
		(mid 143.129954 -288.913527)
		(end 143.377666 -288.988754)
		(width 0.0889)
		(layer "In6.Cu")
		(net "M_K_CPU1_SB_DQ<24>")
	)
	(arc
		(start 145.639028 -289.044126)
		(mid 145.682463 -289.052784)
		(end 145.719292 -289.0774)
		(width 0.0889)
		(layer "In6.Cu")
		(net "M_K_CPU1_SB_DQ<24>")
	)
	(arc
		(start 143.751808 -288.988754)
		(mid 144.028621 -288.912611)
		(end 144.307052 -288.982658)
		(width 0.0889)
		(layer "In6.Cu")
		(net "M_K_CPU1_SB_DQ<24>")
	)
	(segment
		(start 141.217904 -288.400236)
		(end 141.684756 -288.666174)
		(width 0.10668)
		(layer "F.Cu")
		(net "M_K_CPU1_SB_DQ<23>")
	)
	(segment
		(start 193.165476 -308.528466)
		(end 193.299334 -308.394608)
		(width 0.14478)
		(layer "In6.Cu")
		(net "M_K_CPU1_SB_DQ<23>")
	)
	(segment
		(start 192.062608 -308.260496)
		(end 192.196466 -308.126638)
		(width 0.14478)
		(layer "In6.Cu")
		(net "M_K_CPU1_SB_DQ<23>")
	)
	(segment
		(start 147.845272 -290.6776)
		(end 151.373586 -294.205914)
		(width 0.14478)
		(layer "In6.Cu")
		(net "M_K_CPU1_SB_DQ<23>")
	)
	(segment
		(start 192.196466 -308.126384)
		(end 192.330324 -307.992526)
		(width 0.14478)
		(layer "In6.Cu")
		(net "M_K_CPU1_SB_DQ<23>")
	)
	(segment
		(start 169.567098 -307.966364)
		(end 169.86123 -308.260496)
		(width 0.14478)
		(layer "In6.Cu")
		(net "M_K_CPU1_SB_DQ<23>")
	)
	(segment
		(start 174.544228 -308.260496)
		(end 177.726594 -308.260496)
		(width 0.14478)
		(layer "In6.Cu")
		(net "M_K_CPU1_SB_DQ<23>")
	)
	(segment
		(start 142.803372 -288.339022)
		(end 142.811754 -288.343848)
		(width 0.0889)
		(layer "In6.Cu")
		(net "M_K_CPU1_SB_DQ<23>")
	)
	(segment
		(start 167.000174 -308.260496)
		(end 167.897556 -308.260496)
		(width 0.14478)
		(layer "In6.Cu")
		(net "M_K_CPU1_SB_DQ<23>")
	)
	(segment
		(start 192.881758 -308.528466)
		(end 193.165476 -308.528466)
		(width 0.14478)
		(layer "In6.Cu")
		(net "M_K_CPU1_SB_DQ<23>")
	)
	(segment
		(start 192.196466 -308.126638)
		(end 192.196466 -308.126384)
		(width 0.14478)
		(layer "In6.Cu")
		(net "M_K_CPU1_SB_DQ<23>")
	)
	(segment
		(start 151.373586 -297.406314)
		(end 163.077906 -309.110634)
		(width 0.14478)
		(layer "In6.Cu")
		(net "M_K_CPU1_SB_DQ<23>")
	)
	(segment
		(start 177.726594 -308.260496)
		(end 178.576732 -309.110634)
		(width 0.14478)
		(layer "In6.Cu")
		(net "M_K_CPU1_SB_DQ<23>")
	)
	(segment
		(start 164.129974 -308.804564)
		(end 164.380418 -308.804564)
		(width 0.14478)
		(layer "In6.Cu")
		(net "M_K_CPU1_SB_DQ<23>")
	)
	(segment
		(start 165.493446 -308.804564)
		(end 165.799516 -309.110634)
		(width 0.14478)
		(layer "In6.Cu")
		(net "M_K_CPU1_SB_DQ<23>")
	)
	(segment
		(start 178.576732 -309.110634)
		(end 181.238144 -309.110634)
		(width 0.14478)
		(layer "In6.Cu")
		(net "M_K_CPU1_SB_DQ<23>")
	)
	(segment
		(start 169.010584 -308.260496)
		(end 169.304716 -307.966364)
		(width 0.14478)
		(layer "In6.Cu")
		(net "M_K_CPU1_SB_DQ<23>")
	)
	(segment
		(start 166.150036 -309.110634)
		(end 167.000174 -308.260496)
		(width 0.14478)
		(layer "In6.Cu")
		(net "M_K_CPU1_SB_DQ<23>")
	)
	(segment
		(start 163.077906 -309.110634)
		(end 163.823904 -309.110634)
		(width 0.14478)
		(layer "In6.Cu")
		(net "M_K_CPU1_SB_DQ<23>")
	)
	(segment
		(start 171.032678 -309.110634)
		(end 173.69409 -309.110634)
		(width 0.14478)
		(layer "In6.Cu")
		(net "M_K_CPU1_SB_DQ<23>")
	)
	(segment
		(start 182.088282 -308.260496)
		(end 184.926224 -308.260496)
		(width 0.14478)
		(layer "In6.Cu")
		(net "M_K_CPU1_SB_DQ<23>")
	)
	(segment
		(start 181.238144 -309.110634)
		(end 182.088282 -308.260496)
		(width 0.14478)
		(layer "In6.Cu")
		(net "M_K_CPU1_SB_DQ<23>")
	)
	(segment
		(start 165.243002 -308.804564)
		(end 165.493446 -308.804564)
		(width 0.14478)
		(layer "In6.Cu")
		(net "M_K_CPU1_SB_DQ<23>")
	)
	(segment
		(start 169.86123 -308.260496)
		(end 170.18254 -308.260496)
		(width 0.14478)
		(layer "In6.Cu")
		(net "M_K_CPU1_SB_DQ<23>")
	)
	(segment
		(start 193.71691 -307.992526)
		(end 193.850768 -308.126384)
		(width 0.14478)
		(layer "In6.Cu")
		(net "M_K_CPU1_SB_DQ<23>")
	)
	(segment
		(start 188.617352 -309.110126)
		(end 189.466982 -308.260496)
		(width 0.14478)
		(layer "In6.Cu")
		(net "M_K_CPU1_SB_DQ<23>")
	)
	(segment
		(start 164.686488 -309.110634)
		(end 164.936932 -309.110634)
		(width 0.14478)
		(layer "In6.Cu")
		(net "M_K_CPU1_SB_DQ<23>")
	)
	(segment
		(start 193.984626 -308.260496)
		(end 194.17919 -308.260496)
		(width 0.14478)
		(layer "In6.Cu")
		(net "M_K_CPU1_SB_DQ<23>")
	)
	(segment
		(start 193.850768 -308.126638)
		(end 193.984626 -308.260496)
		(width 0.14478)
		(layer "In6.Cu")
		(net "M_K_CPU1_SB_DQ<23>")
	)
	(segment
		(start 163.823904 -309.110634)
		(end 164.129974 -308.804564)
		(width 0.14478)
		(layer "In6.Cu")
		(net "M_K_CPU1_SB_DQ<23>")
	)
	(segment
		(start 145.56486 -288.159444)
		(end 145.943066 -288.53765)
		(width 0.0889)
		(layer "In6.Cu")
		(net "M_K_CPU1_SB_DQ<23>")
	)
	(segment
		(start 141.684756 -288.666174)
		(end 141.530832 -288.400744)
		(width 0.0889)
		(layer "In6.Cu")
		(net "M_K_CPU1_SB_DQ<23>")
	)
	(segment
		(start 168.748202 -308.260496)
		(end 169.010584 -308.260496)
		(width 0.14478)
		(layer "In6.Cu")
		(net "M_K_CPU1_SB_DQ<23>")
	)
	(segment
		(start 184.926224 -308.260496)
		(end 185.775854 -309.110126)
		(width 0.14478)
		(layer "In6.Cu")
		(net "M_K_CPU1_SB_DQ<23>")
	)
	(segment
		(start 164.936932 -309.110634)
		(end 165.243002 -308.804564)
		(width 0.14478)
		(layer "In6.Cu")
		(net "M_K_CPU1_SB_DQ<23>")
	)
	(segment
		(start 145.943066 -288.913824)
		(end 146.961606 -289.932364)
		(width 0.0889)
		(layer "In6.Cu")
		(net "M_K_CPU1_SB_DQ<23>")
	)
	(segment
		(start 146.961606 -289.932364)
		(end 147.100036 -289.932364)
		(width 0.0889)
		(layer "In6.Cu")
		(net "M_K_CPU1_SB_DQ<23>")
	)
	(segment
		(start 193.299334 -308.394608)
		(end 193.299334 -308.126384)
		(width 0.14478)
		(layer "In6.Cu")
		(net "M_K_CPU1_SB_DQ<23>")
	)
	(segment
		(start 193.299334 -308.126384)
		(end 193.433192 -307.992526)
		(width 0.14478)
		(layer "In6.Cu")
		(net "M_K_CPU1_SB_DQ<23>")
	)
	(segment
		(start 193.850768 -308.126384)
		(end 193.850768 -308.126638)
		(width 0.14478)
		(layer "In6.Cu")
		(net "M_K_CPU1_SB_DQ<23>")
	)
	(segment
		(start 192.330324 -307.992526)
		(end 192.614042 -307.992526)
		(width 0.14478)
		(layer "In6.Cu")
		(net "M_K_CPU1_SB_DQ<23>")
	)
	(segment
		(start 151.373586 -294.205914)
		(end 151.373586 -297.406314)
		(width 0.14478)
		(layer "In6.Cu")
		(net "M_K_CPU1_SB_DQ<23>")
	)
	(segment
		(start 147.100036 -289.932364)
		(end 147.845272 -290.6776)
		(width 0.0889)
		(layer "In6.Cu")
		(net "M_K_CPU1_SB_DQ<23>")
	)
	(segment
		(start 141.530832 -288.400744)
		(end 141.55293 -288.317686)
		(width 0.0889)
		(layer "In6.Cu")
		(net "M_K_CPU1_SB_DQ<23>")
	)
	(segment
		(start 192.7479 -308.126384)
		(end 192.7479 -308.394608)
		(width 0.14478)
		(layer "In6.Cu")
		(net "M_K_CPU1_SB_DQ<23>")
	)
	(segment
		(start 165.799516 -309.110634)
		(end 166.150036 -309.110634)
		(width 0.14478)
		(layer "In6.Cu")
		(net "M_K_CPU1_SB_DQ<23>")
	)
	(segment
		(start 189.466982 -308.260496)
		(end 192.062608 -308.260496)
		(width 0.14478)
		(layer "In6.Cu")
		(net "M_K_CPU1_SB_DQ<23>")
	)
	(segment
		(start 167.897556 -308.260496)
		(end 168.191688 -307.966364)
		(width 0.14478)
		(layer "In6.Cu")
		(net "M_K_CPU1_SB_DQ<23>")
	)
	(segment
		(start 170.18254 -308.260496)
		(end 171.032678 -309.110634)
		(width 0.14478)
		(layer "In6.Cu")
		(net "M_K_CPU1_SB_DQ<23>")
	)
	(segment
		(start 192.614042 -307.992526)
		(end 192.7479 -308.126384)
		(width 0.14478)
		(layer "In6.Cu")
		(net "M_K_CPU1_SB_DQ<23>")
	)
	(segment
		(start 144.307052 -288.349944)
		(end 144.544034 -288.219134)
		(width 0.0889)
		(layer "In6.Cu")
		(net "M_K_CPU1_SB_DQ<23>")
	)
	(segment
		(start 145.943066 -288.53765)
		(end 145.943066 -288.913824)
		(width 0.0889)
		(layer "In6.Cu")
		(net "M_K_CPU1_SB_DQ<23>")
	)
	(segment
		(start 144.775936 -288.159444)
		(end 145.56486 -288.159444)
		(width 0.0889)
		(layer "In6.Cu")
		(net "M_K_CPU1_SB_DQ<23>")
	)
	(segment
		(start 192.7479 -308.394608)
		(end 192.881758 -308.528466)
		(width 0.14478)
		(layer "In6.Cu")
		(net "M_K_CPU1_SB_DQ<23>")
	)
	(segment
		(start 193.433192 -307.992526)
		(end 193.71691 -307.992526)
		(width 0.14478)
		(layer "In6.Cu")
		(net "M_K_CPU1_SB_DQ<23>")
	)
	(segment
		(start 143.377666 -288.343848)
		(end 143.386048 -288.339022)
		(width 0.0889)
		(layer "In6.Cu")
		(net "M_K_CPU1_SB_DQ<23>")
	)
	(segment
		(start 173.69409 -309.110634)
		(end 174.544228 -308.260496)
		(width 0.14478)
		(layer "In6.Cu")
		(net "M_K_CPU1_SB_DQ<23>")
	)
	(segment
		(start 169.304716 -307.966364)
		(end 169.567098 -307.966364)
		(width 0.14478)
		(layer "In6.Cu")
		(net "M_K_CPU1_SB_DQ<23>")
	)
	(segment
		(start 164.380418 -308.804564)
		(end 164.686488 -309.110634)
		(width 0.14478)
		(layer "In6.Cu")
		(net "M_K_CPU1_SB_DQ<23>")
	)
	(segment
		(start 168.45407 -307.966364)
		(end 168.748202 -308.260496)
		(width 0.14478)
		(layer "In6.Cu")
		(net "M_K_CPU1_SB_DQ<23>")
	)
	(segment
		(start 168.191688 -307.966364)
		(end 168.45407 -307.966364)
		(width 0.14478)
		(layer "In6.Cu")
		(net "M_K_CPU1_SB_DQ<23>")
	)
	(segment
		(start 185.775854 -309.110126)
		(end 188.617352 -309.110126)
		(width 0.14478)
		(layer "In6.Cu")
		(net "M_K_CPU1_SB_DQ<23>")
	)
	(segment
		(start 194.17919 -308.260496)
		(end 194.604132 -308.685438)
		(width 0.14478)
		(layer "In6.Cu")
		(net "M_K_CPU1_SB_DQ<23>")
	)
	(arc
		(start 141.8717 -288.343848)
		(mid 142.154656 -288.420025)
		(end 142.437612 -288.343848)
		(width 0.0889)
		(layer "In6.Cu")
		(net "M_K_CPU1_SB_DQ<23>")
	)
	(arc
		(start 143.751808 -288.343848)
		(mid 144.028621 -288.419991)
		(end 144.307052 -288.349944)
		(width 0.0889)
		(layer "In6.Cu")
		(net "M_K_CPU1_SB_DQ<23>")
	)
	(arc
		(start 142.437612 -288.343848)
		(mid 142.619863 -288.293464)
		(end 142.803372 -288.339022)
		(width 0.0889)
		(layer "In6.Cu")
		(net "M_K_CPU1_SB_DQ<23>")
	)
	(arc
		(start 143.386048 -288.339022)
		(mid 143.569556 -288.293497)
		(end 143.751808 -288.343848)
		(width 0.0889)
		(layer "In6.Cu")
		(net "M_K_CPU1_SB_DQ<23>")
	)
	(arc
		(start 141.55293 -288.317686)
		(mid 141.715261 -288.294837)
		(end 141.8717 -288.343848)
		(width 0.0889)
		(layer "In6.Cu")
		(net "M_K_CPU1_SB_DQ<23>")
	)
	(arc
		(start 142.811754 -288.343848)
		(mid 143.09471 -288.420025)
		(end 143.377666 -288.343848)
		(width 0.0889)
		(layer "In6.Cu")
		(net "M_K_CPU1_SB_DQ<23>")
	)
	(arc
		(start 144.544034 -288.219134)
		(mid 144.656202 -288.174581)
		(end 144.775936 -288.159444)
		(width 0.0889)
		(layer "In6.Cu")
		(net "M_K_CPU1_SB_DQ<23>")
	)
	(segment
		(start 142.627858 -287.590484)
		(end 143.09471 -287.856422)
		(width 0.10668)
		(layer "F.Cu")
		(net "M_K_CPU1_SB_DQ<22>")
	)
	(segment
		(start 192.656968 -306.769262)
		(end 192.801748 -306.914042)
		(width 0.14478)
		(layer "In6.Cu")
		(net "M_K_CPU1_SB_DQ<22>")
	)
	(segment
		(start 177.887122 -307.016404)
		(end 178.182524 -307.016404)
		(width 0.14478)
		(layer "In6.Cu")
		(net "M_K_CPU1_SB_DQ<22>")
	)
	(segment
		(start 192.801748 -306.914042)
		(end 193.063622 -306.914042)
		(width 0.14478)
		(layer "In6.Cu")
		(net "M_K_CPU1_SB_DQ<22>")
	)
	(segment
		(start 192.105534 -306.351686)
		(end 192.250314 -306.206906)
		(width 0.14478)
		(layer "In6.Cu")
		(net "M_K_CPU1_SB_DQ<22>")
	)
	(segment
		(start 147.77974 -289.325304)
		(end 152.287986 -293.83355)
		(width 0.14478)
		(layer "In6.Cu")
		(net "M_K_CPU1_SB_DQ<22>")
	)
	(segment
		(start 163.21532 -306.732686)
		(end 163.477194 -306.732686)
		(width 0.14478)
		(layer "In6.Cu")
		(net "M_K_CPU1_SB_DQ<22>")
	)
	(segment
		(start 164.028628 -307.410612)
		(end 164.173408 -307.265832)
		(width 0.14478)
		(layer "In6.Cu")
		(net "M_K_CPU1_SB_DQ<22>")
	)
	(segment
		(start 164.173408 -306.877466)
		(end 164.318188 -306.732686)
		(width 0.14478)
		(layer "In6.Cu")
		(net "M_K_CPU1_SB_DQ<22>")
	)
	(segment
		(start 190.387478 -306.196746)
		(end 190.532258 -306.341526)
		(width 0.14478)
		(layer "In6.Cu")
		(net "M_K_CPU1_SB_DQ<22>")
	)
	(segment
		(start 152.287986 -293.83355)
		(end 152.287986 -297.03395)
		(width 0.14478)
		(layer "In6.Cu")
		(net "M_K_CPU1_SB_DQ<22>")
	)
	(segment
		(start 163.621974 -306.877466)
		(end 163.621974 -307.265832)
		(width 0.14478)
		(layer "In6.Cu")
		(net "M_K_CPU1_SB_DQ<22>")
	)
	(segment
		(start 168.740328 -306.289964)
		(end 169.026332 -306.289964)
		(width 0.14478)
		(layer "In6.Cu")
		(net "M_K_CPU1_SB_DQ<22>")
	)
	(segment
		(start 168.469818 -306.560474)
		(end 168.740328 -306.289964)
		(width 0.14478)
		(layer "In6.Cu")
		(net "M_K_CPU1_SB_DQ<22>")
	)
	(segment
		(start 188.79058 -307.410104)
		(end 189.64021 -306.560474)
		(width 0.14478)
		(layer "In6.Cu")
		(net "M_K_CPU1_SB_DQ<22>")
	)
	(segment
		(start 193.759836 -306.351686)
		(end 193.759836 -306.415694)
		(width 0.14478)
		(layer "In6.Cu")
		(net "M_K_CPU1_SB_DQ<22>")
	)
	(segment
		(start 190.125604 -306.196746)
		(end 190.387478 -306.196746)
		(width 0.14478)
		(layer "In6.Cu")
		(net "M_K_CPU1_SB_DQ<22>")
	)
	(segment
		(start 193.353182 -306.206906)
		(end 193.615056 -306.206906)
		(width 0.14478)
		(layer "In6.Cu")
		(net "M_K_CPU1_SB_DQ<22>")
	)
	(segment
		(start 170.18254 -306.560474)
		(end 171.032678 -307.410612)
		(width 0.14478)
		(layer "In6.Cu")
		(net "M_K_CPU1_SB_DQ<22>")
	)
	(segment
		(start 162.664648 -307.410612)
		(end 162.92576 -307.410612)
		(width 0.14478)
		(layer "In6.Cu")
		(net "M_K_CPU1_SB_DQ<22>")
	)
	(segment
		(start 182.088282 -306.560474)
		(end 184.836816 -306.560474)
		(width 0.14478)
		(layer "In6.Cu")
		(net "M_K_CPU1_SB_DQ<22>")
	)
	(segment
		(start 171.032678 -307.410612)
		(end 173.69409 -307.410612)
		(width 0.14478)
		(layer "In6.Cu")
		(net "M_K_CPU1_SB_DQ<22>")
	)
	(segment
		(start 192.656968 -306.351686)
		(end 192.656968 -306.769262)
		(width 0.14478)
		(layer "In6.Cu")
		(net "M_K_CPU1_SB_DQ<22>")
	)
	(segment
		(start 194.17919 -306.560474)
		(end 194.604132 -306.985416)
		(width 0.14478)
		(layer "In6.Cu")
		(net "M_K_CPU1_SB_DQ<22>")
	)
	(segment
		(start 163.766754 -307.410612)
		(end 164.028628 -307.410612)
		(width 0.14478)
		(layer "In6.Cu")
		(net "M_K_CPU1_SB_DQ<22>")
	)
	(segment
		(start 192.512188 -306.206906)
		(end 192.656968 -306.351686)
		(width 0.14478)
		(layer "In6.Cu")
		(net "M_K_CPU1_SB_DQ<22>")
	)
	(segment
		(start 184.836816 -306.560474)
		(end 185.686446 -307.410104)
		(width 0.14478)
		(layer "In6.Cu")
		(net "M_K_CPU1_SB_DQ<22>")
	)
	(segment
		(start 163.07054 -307.265832)
		(end 163.07054 -306.877466)
		(width 0.14478)
		(layer "In6.Cu")
		(net "M_K_CPU1_SB_DQ<22>")
	)
	(segment
		(start 190.532258 -306.415694)
		(end 190.677038 -306.560474)
		(width 0.14478)
		(layer "In6.Cu")
		(net "M_K_CPU1_SB_DQ<22>")
	)
	(segment
		(start 189.836044 -306.560474)
		(end 189.980824 -306.415694)
		(width 0.14478)
		(layer "In6.Cu")
		(net "M_K_CPU1_SB_DQ<22>")
	)
	(segment
		(start 193.759836 -306.415694)
		(end 193.904616 -306.560474)
		(width 0.14478)
		(layer "In6.Cu")
		(net "M_K_CPU1_SB_DQ<22>")
	)
	(segment
		(start 174.544228 -306.560474)
		(end 176.578768 -306.560474)
		(width 0.14478)
		(layer "In6.Cu")
		(net "M_K_CPU1_SB_DQ<22>")
	)
	(segment
		(start 185.686446 -307.410104)
		(end 188.79058 -307.410104)
		(width 0.14478)
		(layer "In6.Cu")
		(net "M_K_CPU1_SB_DQ<22>")
	)
	(segment
		(start 168.183814 -306.560474)
		(end 168.469818 -306.560474)
		(width 0.14478)
		(layer "In6.Cu")
		(net "M_K_CPU1_SB_DQ<22>")
	)
	(segment
		(start 193.208402 -306.351686)
		(end 193.353182 -306.206906)
		(width 0.14478)
		(layer "In6.Cu")
		(net "M_K_CPU1_SB_DQ<22>")
	)
	(segment
		(start 167.000174 -306.560474)
		(end 167.35679 -306.560474)
		(width 0.14478)
		(layer "In6.Cu")
		(net "M_K_CPU1_SB_DQ<22>")
	)
	(segment
		(start 191.960754 -306.560474)
		(end 192.105534 -306.415694)
		(width 0.14478)
		(layer "In6.Cu")
		(net "M_K_CPU1_SB_DQ<22>")
	)
	(segment
		(start 164.724842 -306.877466)
		(end 164.724842 -307.265832)
		(width 0.14478)
		(layer "In6.Cu")
		(net "M_K_CPU1_SB_DQ<22>")
	)
	(segment
		(start 167.913304 -306.289964)
		(end 168.183814 -306.560474)
		(width 0.14478)
		(layer "In6.Cu")
		(net "M_K_CPU1_SB_DQ<22>")
	)
	(segment
		(start 169.296842 -306.560474)
		(end 170.18254 -306.560474)
		(width 0.14478)
		(layer "In6.Cu")
		(net "M_K_CPU1_SB_DQ<22>")
	)
	(segment
		(start 190.677038 -306.560474)
		(end 191.960754 -306.560474)
		(width 0.14478)
		(layer "In6.Cu")
		(net "M_K_CPU1_SB_DQ<22>")
	)
	(segment
		(start 177.135282 -306.264564)
		(end 177.887122 -307.016404)
		(width 0.14478)
		(layer "In6.Cu")
		(net "M_K_CPU1_SB_DQ<22>")
	)
	(segment
		(start 144.621758 -287.641284)
		(end 146.04873 -287.641284)
		(width 0.0889)
		(layer "In6.Cu")
		(net "M_K_CPU1_SB_DQ<22>")
	)
	(segment
		(start 166.150036 -307.410612)
		(end 167.000174 -306.560474)
		(width 0.14478)
		(layer "In6.Cu")
		(net "M_K_CPU1_SB_DQ<22>")
	)
	(segment
		(start 164.869622 -307.410612)
		(end 166.150036 -307.410612)
		(width 0.14478)
		(layer "In6.Cu")
		(net "M_K_CPU1_SB_DQ<22>")
	)
	(segment
		(start 167.6273 -306.289964)
		(end 167.913304 -306.289964)
		(width 0.14478)
		(layer "In6.Cu")
		(net "M_K_CPU1_SB_DQ<22>")
	)
	(segment
		(start 176.874678 -306.264564)
		(end 177.135282 -306.264564)
		(width 0.14478)
		(layer "In6.Cu")
		(net "M_K_CPU1_SB_DQ<22>")
	)
	(segment
		(start 152.287986 -297.03395)
		(end 162.664648 -307.410612)
		(width 0.14478)
		(layer "In6.Cu")
		(net "M_K_CPU1_SB_DQ<22>")
	)
	(segment
		(start 142.940786 -287.590992)
		(end 142.963138 -287.50768)
		(width 0.0889)
		(layer "In6.Cu")
		(net "M_K_CPU1_SB_DQ<22>")
	)
	(segment
		(start 164.724842 -307.265832)
		(end 164.869622 -307.410612)
		(width 0.14478)
		(layer "In6.Cu")
		(net "M_K_CPU1_SB_DQ<22>")
	)
	(segment
		(start 181.238144 -307.410612)
		(end 182.088282 -306.560474)
		(width 0.14478)
		(layer "In6.Cu")
		(net "M_K_CPU1_SB_DQ<22>")
	)
	(segment
		(start 193.208402 -306.769262)
		(end 193.208402 -306.351686)
		(width 0.14478)
		(layer "In6.Cu")
		(net "M_K_CPU1_SB_DQ<22>")
	)
	(segment
		(start 163.621974 -307.265832)
		(end 163.766754 -307.410612)
		(width 0.14478)
		(layer "In6.Cu")
		(net "M_K_CPU1_SB_DQ<22>")
	)
	(segment
		(start 192.250314 -306.206906)
		(end 192.512188 -306.206906)
		(width 0.14478)
		(layer "In6.Cu")
		(net "M_K_CPU1_SB_DQ<22>")
	)
	(segment
		(start 164.173408 -307.265832)
		(end 164.173408 -306.877466)
		(width 0.14478)
		(layer "In6.Cu")
		(net "M_K_CPU1_SB_DQ<22>")
	)
	(segment
		(start 167.35679 -306.560474)
		(end 167.6273 -306.289964)
		(width 0.14478)
		(layer "In6.Cu")
		(net "M_K_CPU1_SB_DQ<22>")
	)
	(segment
		(start 164.580062 -306.732686)
		(end 164.724842 -306.877466)
		(width 0.14478)
		(layer "In6.Cu")
		(net "M_K_CPU1_SB_DQ<22>")
	)
	(segment
		(start 193.615056 -306.206906)
		(end 193.759836 -306.351686)
		(width 0.14478)
		(layer "In6.Cu")
		(net "M_K_CPU1_SB_DQ<22>")
	)
	(segment
		(start 144.213326 -287.529016)
		(end 144.221708 -287.533842)
		(width 0.0889)
		(layer "In6.Cu")
		(net "M_K_CPU1_SB_DQ<22>")
	)
	(segment
		(start 163.07054 -306.877466)
		(end 163.21532 -306.732686)
		(width 0.14478)
		(layer "In6.Cu")
		(net "M_K_CPU1_SB_DQ<22>")
	)
	(segment
		(start 169.026332 -306.289964)
		(end 169.296842 -306.560474)
		(width 0.14478)
		(layer "In6.Cu")
		(net "M_K_CPU1_SB_DQ<22>")
	)
	(segment
		(start 164.318188 -306.732686)
		(end 164.580062 -306.732686)
		(width 0.14478)
		(layer "In6.Cu")
		(net "M_K_CPU1_SB_DQ<22>")
	)
	(segment
		(start 178.182524 -307.016404)
		(end 178.576732 -307.410612)
		(width 0.14478)
		(layer "In6.Cu")
		(net "M_K_CPU1_SB_DQ<22>")
	)
	(segment
		(start 178.576732 -307.410612)
		(end 181.238144 -307.410612)
		(width 0.14478)
		(layer "In6.Cu")
		(net "M_K_CPU1_SB_DQ<22>")
	)
	(segment
		(start 176.578768 -306.560474)
		(end 176.874678 -306.264564)
		(width 0.14478)
		(layer "In6.Cu")
		(net "M_K_CPU1_SB_DQ<22>")
	)
	(segment
		(start 193.063622 -306.914042)
		(end 193.208402 -306.769262)
		(width 0.14478)
		(layer "In6.Cu")
		(net "M_K_CPU1_SB_DQ<22>")
	)
	(segment
		(start 173.69409 -307.410612)
		(end 174.544228 -306.560474)
		(width 0.14478)
		(layer "In6.Cu")
		(net "M_K_CPU1_SB_DQ<22>")
	)
	(segment
		(start 143.09471 -287.856422)
		(end 142.940786 -287.590992)
		(width 0.0889)
		(layer "In6.Cu")
		(net "M_K_CPU1_SB_DQ<22>")
	)
	(segment
		(start 189.980824 -306.341526)
		(end 190.125604 -306.196746)
		(width 0.14478)
		(layer "In6.Cu")
		(net "M_K_CPU1_SB_DQ<22>")
	)
	(segment
		(start 192.105534 -306.415694)
		(end 192.105534 -306.351686)
		(width 0.14478)
		(layer "In6.Cu")
		(net "M_K_CPU1_SB_DQ<22>")
	)
	(segment
		(start 193.904616 -306.560474)
		(end 194.17919 -306.560474)
		(width 0.14478)
		(layer "In6.Cu")
		(net "M_K_CPU1_SB_DQ<22>")
	)
	(segment
		(start 190.532258 -306.341526)
		(end 190.532258 -306.415694)
		(width 0.14478)
		(layer "In6.Cu")
		(net "M_K_CPU1_SB_DQ<22>")
	)
	(segment
		(start 146.128994 -287.674558)
		(end 147.77974 -289.325304)
		(width 0.0889)
		(layer "In6.Cu")
		(net "M_K_CPU1_SB_DQ<22>")
	)
	(segment
		(start 163.477194 -306.732686)
		(end 163.621974 -306.877466)
		(width 0.14478)
		(layer "In6.Cu")
		(net "M_K_CPU1_SB_DQ<22>")
	)
	(segment
		(start 189.980824 -306.415694)
		(end 189.980824 -306.341526)
		(width 0.14478)
		(layer "In6.Cu")
		(net "M_K_CPU1_SB_DQ<22>")
	)
	(segment
		(start 189.64021 -306.560474)
		(end 189.836044 -306.560474)
		(width 0.14478)
		(layer "In6.Cu")
		(net "M_K_CPU1_SB_DQ<22>")
	)
	(segment
		(start 162.92576 -307.410612)
		(end 163.07054 -307.265832)
		(width 0.14478)
		(layer "In6.Cu")
		(net "M_K_CPU1_SB_DQ<22>")
	)
	(arc
		(start 143.847566 -287.533842)
		(mid 144.029817 -287.483492)
		(end 144.213326 -287.529016)
		(width 0.0889)
		(layer "In6.Cu")
		(net "M_K_CPU1_SB_DQ<22>")
	)
	(arc
		(start 146.04873 -287.641284)
		(mid 146.092165 -287.649942)
		(end 146.128994 -287.674558)
		(width 0.0889)
		(layer "In6.Cu")
		(net "M_K_CPU1_SB_DQ<22>")
	)
	(arc
		(start 144.221708 -287.533842)
		(mid 144.414637 -287.613998)
		(end 144.621758 -287.641284)
		(width 0.0889)
		(layer "In6.Cu")
		(net "M_K_CPU1_SB_DQ<22>")
	)
	(arc
		(start 142.963138 -287.50768)
		(mid 143.125327 -287.484945)
		(end 143.281654 -287.533842)
		(width 0.0889)
		(layer "In6.Cu")
		(net "M_K_CPU1_SB_DQ<22>")
	)
	(arc
		(start 143.281654 -287.533842)
		(mid 143.56461 -287.609985)
		(end 143.847566 -287.533842)
		(width 0.0889)
		(layer "In6.Cu")
		(net "M_K_CPU1_SB_DQ<22>")
	)
	(segment
		(start 140.748004 -287.590484)
		(end 141.214856 -287.856422)
		(width 0.10668)
		(layer "F.Cu")
		(net "M_K_CPU1_SB_DQ<21>")
	)
	(segment
		(start 184.397904 -307.410612)
		(end 186.449208 -308.260242)
		(width 0.14478)
		(layer "In6.Cu")
		(net "M_K_CPU1_SB_DQ<21>")
	)
	(segment
		(start 167.514016 -307.410612)
		(end 169.593768 -307.410612)
		(width 0.14478)
		(layer "In6.Cu")
		(net "M_K_CPU1_SB_DQ<21>")
	)
	(segment
		(start 141.36878 -288.121852)
		(end 141.464538 -288.147252)
		(width 0.0889)
		(layer "In6.Cu")
		(net "M_K_CPU1_SB_DQ<21>")
	)
	(segment
		(start 144.674844 -287.935924)
		(end 145.643346 -287.935924)
		(width 0.0889)
		(layer "In6.Cu")
		(net "M_K_CPU1_SB_DQ<21>")
	)
	(segment
		(start 196.567806 -307.410358)
		(end 198.7042 -307.8353)
		(width 0.14478)
		(layer "In6.Cu")
		(net "M_K_CPU1_SB_DQ<21>")
	)
	(segment
		(start 175.143922 -307.410612)
		(end 176.964086 -307.410612)
		(width 0.14478)
		(layer "In6.Cu")
		(net "M_K_CPU1_SB_DQ<21>")
	)
	(segment
		(start 147.863814 -290.05276)
		(end 151.830786 -294.019732)
		(width 0.14478)
		(layer "In6.Cu")
		(net "M_K_CPU1_SB_DQ<21>")
	)
	(segment
		(start 179.015898 -308.260496)
		(end 180.513228 -308.260496)
		(width 0.14478)
		(layer "In6.Cu")
		(net "M_K_CPU1_SB_DQ<21>")
	)
	(segment
		(start 146.898106 -289.576764)
		(end 147.387818 -289.576764)
		(width 0.0889)
		(layer "In6.Cu")
		(net "M_K_CPU1_SB_DQ<21>")
	)
	(segment
		(start 146.158966 -288.451544)
		(end 146.158966 -288.837624)
		(width 0.0889)
		(layer "In6.Cu")
		(net "M_K_CPU1_SB_DQ<21>")
	)
	(segment
		(start 182.56504 -307.410612)
		(end 184.397904 -307.410612)
		(width 0.14478)
		(layer "In6.Cu")
		(net "M_K_CPU1_SB_DQ<21>")
	)
	(segment
		(start 173.091856 -308.260496)
		(end 175.143922 -307.410612)
		(width 0.14478)
		(layer "In6.Cu")
		(net "M_K_CPU1_SB_DQ<21>")
	)
	(segment
		(start 180.513228 -308.260496)
		(end 182.56504 -307.410612)
		(width 0.14478)
		(layer "In6.Cu")
		(net "M_K_CPU1_SB_DQ<21>")
	)
	(segment
		(start 141.967712 -288.178748)
		(end 141.976094 -288.183574)
		(width 0.0889)
		(layer "In6.Cu")
		(net "M_K_CPU1_SB_DQ<21>")
	)
	(segment
		(start 171.64558 -308.260496)
		(end 173.091856 -308.260496)
		(width 0.14478)
		(layer "In6.Cu")
		(net "M_K_CPU1_SB_DQ<21>")
	)
	(segment
		(start 146.158966 -288.837624)
		(end 146.898106 -289.576764)
		(width 0.0889)
		(layer "In6.Cu")
		(net "M_K_CPU1_SB_DQ<21>")
	)
	(segment
		(start 151.830786 -297.220386)
		(end 162.870896 -308.260496)
		(width 0.14478)
		(layer "In6.Cu")
		(net "M_K_CPU1_SB_DQ<21>")
	)
	(segment
		(start 186.449208 -308.260242)
		(end 188.231018 -308.260242)
		(width 0.14478)
		(layer "In6.Cu")
		(net "M_K_CPU1_SB_DQ<21>")
	)
	(segment
		(start 188.231018 -308.260242)
		(end 190.28283 -307.410358)
		(width 0.14478)
		(layer "In6.Cu")
		(net "M_K_CPU1_SB_DQ<21>")
	)
	(segment
		(start 141.214856 -287.856422)
		(end 141.36878 -288.121852)
		(width 0.0889)
		(layer "In6.Cu")
		(net "M_K_CPU1_SB_DQ<21>")
	)
	(segment
		(start 165.462204 -308.260496)
		(end 167.514016 -307.410612)
		(width 0.14478)
		(layer "In6.Cu")
		(net "M_K_CPU1_SB_DQ<21>")
	)
	(segment
		(start 169.593768 -307.410612)
		(end 171.64558 -308.260496)
		(width 0.14478)
		(layer "In6.Cu")
		(net "M_K_CPU1_SB_DQ<21>")
	)
	(segment
		(start 162.870896 -308.260496)
		(end 165.462204 -308.260496)
		(width 0.14478)
		(layer "In6.Cu")
		(net "M_K_CPU1_SB_DQ<21>")
	)
	(segment
		(start 176.964086 -307.410612)
		(end 179.015898 -308.260496)
		(width 0.14478)
		(layer "In6.Cu")
		(net "M_K_CPU1_SB_DQ<21>")
	)
	(segment
		(start 145.643346 -287.935924)
		(end 146.158966 -288.451544)
		(width 0.0889)
		(layer "In6.Cu")
		(net "M_K_CPU1_SB_DQ<21>")
	)
	(segment
		(start 151.830786 -294.019732)
		(end 151.830786 -297.220386)
		(width 0.14478)
		(layer "In6.Cu")
		(net "M_K_CPU1_SB_DQ<21>")
	)
	(segment
		(start 190.28283 -307.410358)
		(end 196.567806 -307.410358)
		(width 0.14478)
		(layer "In6.Cu")
		(net "M_K_CPU1_SB_DQ<21>")
	)
	(segment
		(start 147.387818 -289.576764)
		(end 147.863814 -290.05276)
		(width 0.0889)
		(layer "In6.Cu")
		(net "M_K_CPU1_SB_DQ<21>")
	)
	(arc
		(start 141.464538 -288.147252)
		(mid 141.71986 -288.103552)
		(end 141.967712 -288.178748)
		(width 0.0889)
		(layer "In6.Cu")
		(net "M_K_CPU1_SB_DQ<21>")
	)
	(arc
		(start 143.847566 -288.178748)
		(mid 144.027771 -288.229099)
		(end 144.20977 -288.185606)
		(width 0.0889)
		(layer "In6.Cu")
		(net "M_K_CPU1_SB_DQ<21>")
	)
	(arc
		(start 144.295368 -288.115502)
		(mid 144.464952 -287.983149)
		(end 144.674844 -287.935924)
		(width 0.0889)
		(layer "In6.Cu")
		(net "M_K_CPU1_SB_DQ<21>")
	)
	(arc
		(start 141.976094 -288.183574)
		(mid 142.159602 -288.229099)
		(end 142.341854 -288.178748)
		(width 0.0889)
		(layer "In6.Cu")
		(net "M_K_CPU1_SB_DQ<21>")
	)
	(arc
		(start 144.20977 -288.185606)
		(mid 144.256045 -288.154797)
		(end 144.295368 -288.115502)
		(width 0.0889)
		(layer "In6.Cu")
		(net "M_K_CPU1_SB_DQ<21>")
	)
	(arc
		(start 142.907766 -288.178748)
		(mid 143.09471 -288.229037)
		(end 143.281654 -288.178748)
		(width 0.0889)
		(layer "In6.Cu")
		(net "M_K_CPU1_SB_DQ<21>")
	)
	(arc
		(start 143.281654 -288.178748)
		(mid 143.56461 -288.102571)
		(end 143.847566 -288.178748)
		(width 0.0889)
		(layer "In6.Cu")
		(net "M_K_CPU1_SB_DQ<21>")
	)
	(arc
		(start 142.341854 -288.178748)
		(mid 142.62481 -288.102571)
		(end 142.907766 -288.178748)
		(width 0.0889)
		(layer "In6.Cu")
		(net "M_K_CPU1_SB_DQ<21>")
	)
	(segment
		(start 142.157958 -286.780478)
		(end 142.62481 -287.046162)
		(width 0.10668)
		(layer "F.Cu")
		(net "M_K_CPU1_SB_DQ<20>")
	)
	(segment
		(start 144.50441 -287.419288)
		(end 146.20494 -287.419288)
		(width 0.0889)
		(layer "In6.Cu")
		(net "M_K_CPU1_SB_DQ<20>")
	)
	(segment
		(start 146.861276 -288.075624)
		(end 147.173188 -288.075624)
		(width 0.0889)
		(layer "In6.Cu")
		(net "M_K_CPU1_SB_DQ<20>")
	)
	(segment
		(start 197.484238 -306.366164)
		(end 197.647306 -306.203096)
		(width 0.14478)
		(layer "In6.Cu")
		(net "M_K_CPU1_SB_DQ<20>")
	)
	(segment
		(start 143.377666 -287.368742)
		(end 143.386048 -287.373568)
		(width 0.0889)
		(layer "In6.Cu")
		(net "M_K_CPU1_SB_DQ<20>")
	)
	(segment
		(start 174.62754 -305.719988)
		(end 177.514504 -305.719988)
		(width 0.14478)
		(layer "In6.Cu")
		(net "M_K_CPU1_SB_DQ<20>")
	)
	(segment
		(start 147.898612 -288.801048)
		(end 152.795986 -293.698422)
		(width 0.14478)
		(layer "In6.Cu")
		(net "M_K_CPU1_SB_DQ<20>")
	)
	(segment
		(start 144.307052 -287.362646)
		(end 144.317466 -287.368742)
		(width 0.0889)
		(layer "In6.Cu")
		(net "M_K_CPU1_SB_DQ<20>")
	)
	(segment
		(start 198.279258 -305.710336)
		(end 198.7042 -306.135278)
		(width 0.14478)
		(layer "In6.Cu")
		(net "M_K_CPU1_SB_DQ<20>")
	)
	(segment
		(start 170.976798 -306.569872)
		(end 173.777656 -306.569872)
		(width 0.14478)
		(layer "In6.Cu")
		(net "M_K_CPU1_SB_DQ<20>")
	)
	(segment
		(start 177.514504 -305.719988)
		(end 178.364642 -306.570126)
		(width 0.14478)
		(layer "In6.Cu")
		(net "M_K_CPU1_SB_DQ<20>")
	)
	(segment
		(start 142.62481 -287.046162)
		(end 142.778734 -287.311592)
		(width 0.0889)
		(layer "In6.Cu")
		(net "M_K_CPU1_SB_DQ<20>")
	)
	(segment
		(start 181.321456 -306.570126)
		(end 182.171594 -305.719988)
		(width 0.14478)
		(layer "In6.Cu")
		(net "M_K_CPU1_SB_DQ<20>")
	)
	(segment
		(start 197.647306 -306.203096)
		(end 197.647306 -305.873404)
		(width 0.14478)
		(layer "In6.Cu")
		(net "M_K_CPU1_SB_DQ<20>")
	)
	(segment
		(start 197.810374 -305.710336)
		(end 198.279258 -305.710336)
		(width 0.14478)
		(layer "In6.Cu")
		(net "M_K_CPU1_SB_DQ<20>")
	)
	(segment
		(start 197.090792 -305.873404)
		(end 197.090792 -306.203096)
		(width 0.14478)
		(layer "In6.Cu")
		(net "M_K_CPU1_SB_DQ<20>")
	)
	(segment
		(start 197.647306 -305.873404)
		(end 197.810374 -305.710336)
		(width 0.14478)
		(layer "In6.Cu")
		(net "M_K_CPU1_SB_DQ<20>")
	)
	(segment
		(start 167.083486 -305.719988)
		(end 170.126914 -305.719988)
		(width 0.14478)
		(layer "In6.Cu")
		(net "M_K_CPU1_SB_DQ<20>")
	)
	(segment
		(start 184.96661 -305.719988)
		(end 185.816494 -306.569872)
		(width 0.14478)
		(layer "In6.Cu")
		(net "M_K_CPU1_SB_DQ<20>")
	)
	(segment
		(start 142.778734 -287.311592)
		(end 142.874746 -287.336992)
		(width 0.0889)
		(layer "In6.Cu")
		(net "M_K_CPU1_SB_DQ<20>")
	)
	(segment
		(start 146.20494 -287.419288)
		(end 146.861276 -288.075624)
		(width 0.0889)
		(layer "In6.Cu")
		(net "M_K_CPU1_SB_DQ<20>")
	)
	(segment
		(start 152.795986 -296.898822)
		(end 162.12185 -306.224686)
		(width 0.14478)
		(layer "In6.Cu")
		(net "M_K_CPU1_SB_DQ<20>")
	)
	(segment
		(start 197.090792 -306.203096)
		(end 197.25386 -306.366164)
		(width 0.14478)
		(layer "In6.Cu")
		(net "M_K_CPU1_SB_DQ<20>")
	)
	(segment
		(start 147.173188 -288.075624)
		(end 147.898612 -288.801048)
		(width 0.0889)
		(layer "In6.Cu")
		(net "M_K_CPU1_SB_DQ<20>")
	)
	(segment
		(start 173.777656 -306.569872)
		(end 174.62754 -305.719988)
		(width 0.14478)
		(layer "In6.Cu")
		(net "M_K_CPU1_SB_DQ<20>")
	)
	(segment
		(start 152.795986 -293.698422)
		(end 152.795986 -296.898822)
		(width 0.14478)
		(layer "In6.Cu")
		(net "M_K_CPU1_SB_DQ<20>")
	)
	(segment
		(start 197.25386 -306.366164)
		(end 197.484238 -306.366164)
		(width 0.14478)
		(layer "In6.Cu")
		(net "M_K_CPU1_SB_DQ<20>")
	)
	(segment
		(start 188.802518 -306.569872)
		(end 189.652402 -305.719988)
		(width 0.14478)
		(layer "In6.Cu")
		(net "M_K_CPU1_SB_DQ<20>")
	)
	(segment
		(start 170.126914 -305.719988)
		(end 170.976798 -306.569872)
		(width 0.14478)
		(layer "In6.Cu")
		(net "M_K_CPU1_SB_DQ<20>")
	)
	(segment
		(start 165.072822 -306.224686)
		(end 165.40861 -306.560474)
		(width 0.14478)
		(layer "In6.Cu")
		(net "M_K_CPU1_SB_DQ<20>")
	)
	(segment
		(start 166.243 -306.560474)
		(end 167.083486 -305.719988)
		(width 0.14478)
		(layer "In6.Cu")
		(net "M_K_CPU1_SB_DQ<20>")
	)
	(segment
		(start 165.40861 -306.560474)
		(end 166.243 -306.560474)
		(width 0.14478)
		(layer "In6.Cu")
		(net "M_K_CPU1_SB_DQ<20>")
	)
	(segment
		(start 189.652402 -305.719988)
		(end 196.937376 -305.719988)
		(width 0.14478)
		(layer "In6.Cu")
		(net "M_K_CPU1_SB_DQ<20>")
	)
	(segment
		(start 162.12185 -306.224686)
		(end 165.072822 -306.224686)
		(width 0.14478)
		(layer "In6.Cu")
		(net "M_K_CPU1_SB_DQ<20>")
	)
	(segment
		(start 196.937376 -305.719988)
		(end 197.090792 -305.873404)
		(width 0.14478)
		(layer "In6.Cu")
		(net "M_K_CPU1_SB_DQ<20>")
	)
	(segment
		(start 182.171594 -305.719988)
		(end 184.96661 -305.719988)
		(width 0.14478)
		(layer "In6.Cu")
		(net "M_K_CPU1_SB_DQ<20>")
	)
	(segment
		(start 178.364642 -306.570126)
		(end 181.321456 -306.570126)
		(width 0.14478)
		(layer "In6.Cu")
		(net "M_K_CPU1_SB_DQ<20>")
	)
	(segment
		(start 185.816494 -306.569872)
		(end 188.802518 -306.569872)
		(width 0.14478)
		(layer "In6.Cu")
		(net "M_K_CPU1_SB_DQ<20>")
	)
	(arc
		(start 143.751808 -287.368742)
		(mid 144.028621 -287.292633)
		(end 144.307052 -287.362646)
		(width 0.0889)
		(layer "In6.Cu")
		(net "M_K_CPU1_SB_DQ<20>")
	)
	(arc
		(start 144.317466 -287.368742)
		(mid 144.407584 -287.406417)
		(end 144.50441 -287.419288)
		(width 0.0889)
		(layer "In6.Cu")
		(net "M_K_CPU1_SB_DQ<20>")
	)
	(arc
		(start 142.874746 -287.336992)
		(mid 143.129954 -287.293535)
		(end 143.377666 -287.368742)
		(width 0.0889)
		(layer "In6.Cu")
		(net "M_K_CPU1_SB_DQ<20>")
	)
	(arc
		(start 143.386048 -287.373568)
		(mid 143.569556 -287.419062)
		(end 143.751808 -287.368742)
		(width 0.0889)
		(layer "In6.Cu")
		(net "M_K_CPU1_SB_DQ<20>")
	)
	(segment
		(start 140.748004 -274.630388)
		(end 141.214856 -274.896326)
		(width 0.10668)
		(layer "F.Cu")
		(net "M_K_CPU1_SB_DQ<1>")
	)
	(segment
		(start 177.309526 -282.76042)
		(end 179.361338 -283.610304)
		(width 0.14478)
		(layer "In6.Cu")
		(net "M_K_CPU1_SB_DQ<1>")
	)
	(segment
		(start 141.967712 -275.218906)
		(end 141.976094 -275.223732)
		(width 0.0889)
		(layer "In6.Cu")
		(net "M_K_CPU1_SB_DQ<1>")
	)
	(segment
		(start 147.562316 -273.849084)
		(end 148.060918 -273.849084)
		(width 0.0889)
		(layer "In6.Cu")
		(net "M_K_CPU1_SB_DQ<1>")
	)
	(segment
		(start 171.69638 -283.610304)
		(end 172.834046 -283.610304)
		(width 0.14478)
		(layer "In6.Cu")
		(net "M_K_CPU1_SB_DQ<1>")
	)
	(segment
		(start 189.569598 -282.76042)
		(end 196.567806 -282.76042)
		(width 0.14478)
		(layer "In6.Cu")
		(net "M_K_CPU1_SB_DQ<1>")
	)
	(segment
		(start 184.811162 -282.76042)
		(end 186.862974 -283.610304)
		(width 0.14478)
		(layer "In6.Cu")
		(net "M_K_CPU1_SB_DQ<1>")
	)
	(segment
		(start 173.68393 -282.76042)
		(end 177.309526 -282.76042)
		(width 0.14478)
		(layer "In6.Cu")
		(net "M_K_CPU1_SB_DQ<1>")
	)
	(segment
		(start 186.862974 -283.610304)
		(end 187.517786 -283.610304)
		(width 0.14478)
		(layer "In6.Cu")
		(net "M_K_CPU1_SB_DQ<1>")
	)
	(segment
		(start 187.517786 -283.610304)
		(end 189.569598 -282.76042)
		(width 0.14478)
		(layer "In6.Cu")
		(net "M_K_CPU1_SB_DQ<1>")
	)
	(segment
		(start 166.800276 -282.76042)
		(end 170.846496 -282.76042)
		(width 0.14478)
		(layer "In6.Cu")
		(net "M_K_CPU1_SB_DQ<1>")
	)
	(segment
		(start 146.743166 -274.009104)
		(end 147.402296 -274.009104)
		(width 0.0889)
		(layer "In6.Cu")
		(net "M_K_CPU1_SB_DQ<1>")
	)
	(segment
		(start 172.834046 -283.610304)
		(end 173.68393 -282.76042)
		(width 0.14478)
		(layer "In6.Cu")
		(net "M_K_CPU1_SB_DQ<1>")
	)
	(segment
		(start 145.161508 -275.218906)
		(end 145.554954 -274.987004)
		(width 0.0889)
		(layer "In6.Cu")
		(net "M_K_CPU1_SB_DQ<1>")
	)
	(segment
		(start 182.605172 -282.76042)
		(end 184.811162 -282.76042)
		(width 0.14478)
		(layer "In6.Cu")
		(net "M_K_CPU1_SB_DQ<1>")
	)
	(segment
		(start 145.975578 -274.776692)
		(end 146.743166 -274.009104)
		(width 0.0889)
		(layer "In6.Cu")
		(net "M_K_CPU1_SB_DQ<1>")
	)
	(segment
		(start 148.060918 -273.849084)
		(end 153.849324 -273.849084)
		(width 0.14478)
		(layer "In6.Cu")
		(net "M_K_CPU1_SB_DQ<1>")
	)
	(segment
		(start 165.950392 -283.610304)
		(end 166.800276 -282.76042)
		(width 0.14478)
		(layer "In6.Cu")
		(net "M_K_CPU1_SB_DQ<1>")
	)
	(segment
		(start 196.567806 -282.76042)
		(end 198.7042 -283.185362)
		(width 0.14478)
		(layer "In6.Cu")
		(net "M_K_CPU1_SB_DQ<1>")
	)
	(segment
		(start 145.554954 -274.987004)
		(end 145.894044 -274.837398)
		(width 0.0889)
		(layer "In6.Cu")
		(net "M_K_CPU1_SB_DQ<1>")
	)
	(segment
		(start 141.214856 -274.896326)
		(end 141.36878 -275.161756)
		(width 0.0889)
		(layer "In6.Cu")
		(net "M_K_CPU1_SB_DQ<1>")
	)
	(segment
		(start 144.221454 -275.218906)
		(end 144.231868 -275.21281)
		(width 0.0889)
		(layer "In6.Cu")
		(net "M_K_CPU1_SB_DQ<1>")
	)
	(segment
		(start 163.610544 -283.610304)
		(end 165.950392 -283.610304)
		(width 0.14478)
		(layer "In6.Cu")
		(net "M_K_CPU1_SB_DQ<1>")
	)
	(segment
		(start 145.894044 -274.837398)
		(end 145.975578 -274.776692)
		(width 0.0889)
		(layer "In6.Cu")
		(net "M_K_CPU1_SB_DQ<1>")
	)
	(segment
		(start 170.846496 -282.76042)
		(end 171.69638 -283.610304)
		(width 0.14478)
		(layer "In6.Cu")
		(net "M_K_CPU1_SB_DQ<1>")
	)
	(segment
		(start 147.402296 -274.009104)
		(end 147.562316 -273.849084)
		(width 0.0889)
		(layer "In6.Cu")
		(net "M_K_CPU1_SB_DQ<1>")
	)
	(segment
		(start 144.787112 -275.218906)
		(end 144.798796 -275.225764)
		(width 0.0889)
		(layer "In6.Cu")
		(net "M_K_CPU1_SB_DQ<1>")
	)
	(segment
		(start 144.20977 -275.225764)
		(end 144.221454 -275.218906)
		(width 0.0889)
		(layer "In6.Cu")
		(net "M_K_CPU1_SB_DQ<1>")
	)
	(segment
		(start 180.55336 -283.610304)
		(end 182.605172 -282.76042)
		(width 0.14478)
		(layer "In6.Cu")
		(net "M_K_CPU1_SB_DQ<1>")
	)
	(segment
		(start 179.361338 -283.610304)
		(end 180.55336 -283.610304)
		(width 0.14478)
		(layer "In6.Cu")
		(net "M_K_CPU1_SB_DQ<1>")
	)
	(segment
		(start 141.36878 -275.161756)
		(end 141.464792 -275.187156)
		(width 0.0889)
		(layer "In6.Cu")
		(net "M_K_CPU1_SB_DQ<1>")
	)
	(segment
		(start 153.849324 -273.849084)
		(end 163.610544 -283.610304)
		(width 0.14478)
		(layer "In6.Cu")
		(net "M_K_CPU1_SB_DQ<1>")
	)
	(arc
		(start 144.798796 -275.225764)
		(mid 144.981051 -275.269417)
		(end 145.161508 -275.218906)
		(width 0.0889)
		(layer "In6.Cu")
		(net "M_K_CPU1_SB_DQ<1>")
	)
	(arc
		(start 141.464792 -275.187156)
		(mid 141.72 -275.143679)
		(end 141.967712 -275.218906)
		(width 0.0889)
		(layer "In6.Cu")
		(net "M_K_CPU1_SB_DQ<1>")
	)
	(arc
		(start 142.341854 -275.218906)
		(mid 142.62481 -275.142729)
		(end 142.907766 -275.218906)
		(width 0.0889)
		(layer "In6.Cu")
		(net "M_K_CPU1_SB_DQ<1>")
	)
	(arc
		(start 143.281654 -275.218906)
		(mid 143.56461 -275.142729)
		(end 143.847566 -275.218906)
		(width 0.0889)
		(layer "In6.Cu")
		(net "M_K_CPU1_SB_DQ<1>")
	)
	(arc
		(start 141.976094 -275.223732)
		(mid 142.159602 -275.269226)
		(end 142.341854 -275.218906)
		(width 0.0889)
		(layer "In6.Cu")
		(net "M_K_CPU1_SB_DQ<1>")
	)
	(arc
		(start 143.847566 -275.218906)
		(mid 144.027771 -275.269223)
		(end 144.20977 -275.225764)
		(width 0.0889)
		(layer "In6.Cu")
		(net "M_K_CPU1_SB_DQ<1>")
	)
	(arc
		(start 142.907766 -275.218906)
		(mid 143.09471 -275.269161)
		(end 143.281654 -275.218906)
		(width 0.0889)
		(layer "In6.Cu")
		(net "M_K_CPU1_SB_DQ<1>")
	)
	(arc
		(start 144.231868 -275.21281)
		(mid 144.5103 -275.142712)
		(end 144.787112 -275.218906)
		(width 0.0889)
		(layer "In6.Cu")
		(net "M_K_CPU1_SB_DQ<1>")
	)
	(segment
		(start 141.217904 -285.160466)
		(end 141.684756 -285.426404)
		(width 0.10668)
		(layer "F.Cu")
		(net "M_K_CPU1_SB_DQ<19>")
	)
	(segment
		(start 157.449266 -297.065446)
		(end 157.449012 -297.29557)
		(width 0.14478)
		(layer "In6.Cu")
		(net "M_K_CPU1_SB_DQ<19>")
	)
	(segment
		(start 157.120336 -297.624246)
		(end 157.120336 -297.854878)
		(width 0.14478)
		(layer "In6.Cu")
		(net "M_K_CPU1_SB_DQ<19>")
	)
	(segment
		(start 155.69946 -296.45229)
		(end 155.930092 -296.452544)
		(width 0.14478)
		(layer "In6.Cu")
		(net "M_K_CPU1_SB_DQ<19>")
	)
	(segment
		(start 166.198042 -302.310292)
		(end 166.51097 -301.997364)
		(width 0.14478)
		(layer "In6.Cu")
		(net "M_K_CPU1_SB_DQ<19>")
	)
	(segment
		(start 165.775386 -302.310292)
		(end 166.198042 -302.310292)
		(width 0.14478)
		(layer "In6.Cu")
		(net "M_K_CPU1_SB_DQ<19>")
	)
	(segment
		(start 167.067484 -302.310292)
		(end 167.31107 -302.310292)
		(width 0.14478)
		(layer "In6.Cu")
		(net "M_K_CPU1_SB_DQ<19>")
	)
	(segment
		(start 168.980612 -301.997364)
		(end 169.284142 -302.300894)
		(width 0.14478)
		(layer "In6.Cu")
		(net "M_K_CPU1_SB_DQ<19>")
	)
	(segment
		(start 186.088274 -303.150778)
		(end 188.691012 -303.150778)
		(width 0.14478)
		(layer "In6.Cu")
		(net "M_K_CPU1_SB_DQ<19>")
	)
	(segment
		(start 156.498544 -296.114724)
		(end 156.661866 -296.278046)
		(width 0.14478)
		(layer "In6.Cu")
		(net "M_K_CPU1_SB_DQ<19>")
	)
	(segment
		(start 157.449012 -297.29557)
		(end 157.120336 -297.624246)
		(width 0.14478)
		(layer "In6.Cu")
		(net "M_K_CPU1_SB_DQ<19>")
	)
	(segment
		(start 158.073344 -297.689524)
		(end 163.54425 -303.16043)
		(width 0.14478)
		(layer "In6.Cu")
		(net "M_K_CPU1_SB_DQ<19>")
	)
	(segment
		(start 156.661612 -296.50817)
		(end 156.326332 -296.84345)
		(width 0.14478)
		(layer "In6.Cu")
		(net "M_K_CPU1_SB_DQ<19>")
	)
	(segment
		(start 166.754556 -301.997364)
		(end 167.067484 -302.310292)
		(width 0.14478)
		(layer "In6.Cu")
		(net "M_K_CPU1_SB_DQ<19>")
	)
	(segment
		(start 147.598384 -286.011874)
		(end 147.876768 -286.011874)
		(width 0.0889)
		(layer "In6.Cu")
		(net "M_K_CPU1_SB_DQ<19>")
	)
	(segment
		(start 148.45538 -286.011874)
		(end 155.290266 -292.84676)
		(width 0.14478)
		(layer "In6.Cu")
		(net "M_K_CPU1_SB_DQ<19>")
	)
	(segment
		(start 146.181572 -285.053278)
		(end 146.737578 -285.609284)
		(width 0.0889)
		(layer "In6.Cu")
		(net "M_K_CPU1_SB_DQ<19>")
	)
	(segment
		(start 157.120336 -297.854878)
		(end 157.283404 -298.017946)
		(width 0.14478)
		(layer "In6.Cu")
		(net "M_K_CPU1_SB_DQ<19>")
	)
	(segment
		(start 147.876768 -286.011874)
		(end 148.45538 -286.011874)
		(width 0.14478)
		(layer "In6.Cu")
		(net "M_K_CPU1_SB_DQ<19>")
	)
	(segment
		(start 164.925248 -303.16043)
		(end 165.775386 -302.310292)
		(width 0.14478)
		(layer "In6.Cu")
		(net "M_K_CPU1_SB_DQ<19>")
	)
	(segment
		(start 177.717196 -302.300894)
		(end 178.567334 -303.151032)
		(width 0.14478)
		(layer "In6.Cu")
		(net "M_K_CPU1_SB_DQ<19>")
	)
	(segment
		(start 173.407832 -303.151032)
		(end 174.25797 -302.300894)
		(width 0.14478)
		(layer "In6.Cu")
		(net "M_K_CPU1_SB_DQ<19>")
	)
	(segment
		(start 167.867584 -301.997364)
		(end 168.171114 -302.300894)
		(width 0.14478)
		(layer "In6.Cu")
		(net "M_K_CPU1_SB_DQ<19>")
	)
	(segment
		(start 171.02328 -303.151032)
		(end 173.407832 -303.151032)
		(width 0.14478)
		(layer "In6.Cu")
		(net "M_K_CPU1_SB_DQ<19>")
	)
	(segment
		(start 167.623998 -301.997364)
		(end 167.867584 -301.997364)
		(width 0.14478)
		(layer "In6.Cu")
		(net "M_K_CPU1_SB_DQ<19>")
	)
	(segment
		(start 144.317466 -285.103824)
		(end 144.325848 -285.098998)
		(width 0.0889)
		(layer "In6.Cu")
		(net "M_K_CPU1_SB_DQ<19>")
	)
	(segment
		(start 174.25797 -302.300894)
		(end 177.717196 -302.300894)
		(width 0.14478)
		(layer "In6.Cu")
		(net "M_K_CPU1_SB_DQ<19>")
	)
	(segment
		(start 189.540896 -302.300894)
		(end 194.169792 -302.300894)
		(width 0.14478)
		(layer "In6.Cu")
		(net "M_K_CPU1_SB_DQ<19>")
	)
	(segment
		(start 143.377666 -285.103824)
		(end 143.386048 -285.098998)
		(width 0.0889)
		(layer "In6.Cu")
		(net "M_K_CPU1_SB_DQ<19>")
	)
	(segment
		(start 157.842712 -297.689524)
		(end 158.073344 -297.689524)
		(width 0.14478)
		(layer "In6.Cu")
		(net "M_K_CPU1_SB_DQ<19>")
	)
	(segment
		(start 157.055312 -296.902124)
		(end 157.285944 -296.902124)
		(width 0.14478)
		(layer "In6.Cu")
		(net "M_K_CPU1_SB_DQ<19>")
	)
	(segment
		(start 181.890416 -302.300894)
		(end 185.23839 -302.300894)
		(width 0.14478)
		(layer "In6.Cu")
		(net "M_K_CPU1_SB_DQ<19>")
	)
	(segment
		(start 157.514036 -298.0182)
		(end 157.842712 -297.689524)
		(width 0.14478)
		(layer "In6.Cu")
		(net "M_K_CPU1_SB_DQ<19>")
	)
	(segment
		(start 168.433496 -302.300894)
		(end 168.737026 -301.997364)
		(width 0.14478)
		(layer "In6.Cu")
		(net "M_K_CPU1_SB_DQ<19>")
	)
	(segment
		(start 146.737578 -285.609284)
		(end 147.195794 -285.609284)
		(width 0.0889)
		(layer "In6.Cu")
		(net "M_K_CPU1_SB_DQ<19>")
	)
	(segment
		(start 181.040278 -303.151032)
		(end 181.890416 -302.300894)
		(width 0.14478)
		(layer "In6.Cu")
		(net "M_K_CPU1_SB_DQ<19>")
	)
	(segment
		(start 163.54425 -303.16043)
		(end 164.925248 -303.16043)
		(width 0.14478)
		(layer "In6.Cu")
		(net "M_K_CPU1_SB_DQ<19>")
	)
	(segment
		(start 155.290266 -294.906446)
		(end 155.874466 -295.490646)
		(width 0.14478)
		(layer "In6.Cu")
		(net "M_K_CPU1_SB_DQ<19>")
	)
	(segment
		(start 168.737026 -301.997364)
		(end 168.980612 -301.997364)
		(width 0.14478)
		(layer "In6.Cu")
		(net "M_K_CPU1_SB_DQ<19>")
	)
	(segment
		(start 170.173142 -302.300894)
		(end 171.02328 -303.151032)
		(width 0.14478)
		(layer "In6.Cu")
		(net "M_K_CPU1_SB_DQ<19>")
	)
	(segment
		(start 168.171114 -302.300894)
		(end 168.433496 -302.300894)
		(width 0.14478)
		(layer "In6.Cu")
		(net "M_K_CPU1_SB_DQ<19>")
	)
	(segment
		(start 157.283404 -298.017946)
		(end 157.514036 -298.0182)
		(width 0.14478)
		(layer "In6.Cu")
		(net "M_K_CPU1_SB_DQ<19>")
	)
	(segment
		(start 155.874466 -295.490646)
		(end 155.874212 -295.72077)
		(width 0.14478)
		(layer "In6.Cu")
		(net "M_K_CPU1_SB_DQ<19>")
	)
	(segment
		(start 155.536392 -296.289222)
		(end 155.69946 -296.45229)
		(width 0.14478)
		(layer "In6.Cu")
		(net "M_K_CPU1_SB_DQ<19>")
	)
	(segment
		(start 169.284142 -302.300894)
		(end 170.173142 -302.300894)
		(width 0.14478)
		(layer "In6.Cu")
		(net "M_K_CPU1_SB_DQ<19>")
	)
	(segment
		(start 156.661866 -296.278046)
		(end 156.661612 -296.50817)
		(width 0.14478)
		(layer "In6.Cu")
		(net "M_K_CPU1_SB_DQ<19>")
	)
	(segment
		(start 156.4894 -297.23715)
		(end 156.720032 -297.237404)
		(width 0.14478)
		(layer "In6.Cu")
		(net "M_K_CPU1_SB_DQ<19>")
	)
	(segment
		(start 156.720032 -297.237404)
		(end 157.055312 -296.902124)
		(width 0.14478)
		(layer "In6.Cu")
		(net "M_K_CPU1_SB_DQ<19>")
	)
	(segment
		(start 194.169792 -302.300894)
		(end 194.604132 -302.735234)
		(width 0.14478)
		(layer "In6.Cu")
		(net "M_K_CPU1_SB_DQ<19>")
	)
	(segment
		(start 156.326332 -296.84345)
		(end 156.326332 -297.074082)
		(width 0.14478)
		(layer "In6.Cu")
		(net "M_K_CPU1_SB_DQ<19>")
	)
	(segment
		(start 156.267912 -296.114724)
		(end 156.498544 -296.114724)
		(width 0.14478)
		(layer "In6.Cu")
		(net "M_K_CPU1_SB_DQ<19>")
	)
	(segment
		(start 155.930092 -296.452544)
		(end 156.267912 -296.114724)
		(width 0.14478)
		(layer "In6.Cu")
		(net "M_K_CPU1_SB_DQ<19>")
	)
	(segment
		(start 141.530832 -285.160974)
		(end 141.553184 -285.077662)
		(width 0.0889)
		(layer "In6.Cu")
		(net "M_K_CPU1_SB_DQ<19>")
	)
	(segment
		(start 155.536392 -296.05859)
		(end 155.536392 -296.289222)
		(width 0.14478)
		(layer "In6.Cu")
		(net "M_K_CPU1_SB_DQ<19>")
	)
	(segment
		(start 155.874212 -295.72077)
		(end 155.536392 -296.05859)
		(width 0.14478)
		(layer "In6.Cu")
		(net "M_K_CPU1_SB_DQ<19>")
	)
	(segment
		(start 178.567334 -303.151032)
		(end 181.040278 -303.151032)
		(width 0.14478)
		(layer "In6.Cu")
		(net "M_K_CPU1_SB_DQ<19>")
	)
	(segment
		(start 167.31107 -302.310292)
		(end 167.623998 -301.997364)
		(width 0.14478)
		(layer "In6.Cu")
		(net "M_K_CPU1_SB_DQ<19>")
	)
	(segment
		(start 144.307052 -285.10992)
		(end 144.317466 -285.103824)
		(width 0.0889)
		(layer "In6.Cu")
		(net "M_K_CPU1_SB_DQ<19>")
	)
	(segment
		(start 142.803372 -285.098998)
		(end 142.811754 -285.103824)
		(width 0.0889)
		(layer "In6.Cu")
		(net "M_K_CPU1_SB_DQ<19>")
	)
	(segment
		(start 156.326332 -297.074082)
		(end 156.4894 -297.23715)
		(width 0.14478)
		(layer "In6.Cu")
		(net "M_K_CPU1_SB_DQ<19>")
	)
	(segment
		(start 157.285944 -296.902124)
		(end 157.449266 -297.065446)
		(width 0.14478)
		(layer "In6.Cu")
		(net "M_K_CPU1_SB_DQ<19>")
	)
	(segment
		(start 144.6911 -285.103824)
		(end 144.701514 -285.10992)
		(width 0.0889)
		(layer "In6.Cu")
		(net "M_K_CPU1_SB_DQ<19>")
	)
	(segment
		(start 141.684756 -285.426404)
		(end 141.530832 -285.160974)
		(width 0.0889)
		(layer "In6.Cu")
		(net "M_K_CPU1_SB_DQ<19>")
	)
	(segment
		(start 185.23839 -302.300894)
		(end 186.088274 -303.150778)
		(width 0.14478)
		(layer "In6.Cu")
		(net "M_K_CPU1_SB_DQ<19>")
	)
	(segment
		(start 145.444718 -285.053278)
		(end 146.181572 -285.053278)
		(width 0.0889)
		(layer "In6.Cu")
		(net "M_K_CPU1_SB_DQ<19>")
	)
	(segment
		(start 188.691012 -303.150778)
		(end 189.540896 -302.300894)
		(width 0.14478)
		(layer "In6.Cu")
		(net "M_K_CPU1_SB_DQ<19>")
	)
	(segment
		(start 147.195794 -285.609284)
		(end 147.598384 -286.011874)
		(width 0.0889)
		(layer "In6.Cu")
		(net "M_K_CPU1_SB_DQ<19>")
	)
	(segment
		(start 166.51097 -301.997364)
		(end 166.754556 -301.997364)
		(width 0.14478)
		(layer "In6.Cu")
		(net "M_K_CPU1_SB_DQ<19>")
	)
	(segment
		(start 155.290266 -292.84676)
		(end 155.290266 -294.906446)
		(width 0.14478)
		(layer "In6.Cu")
		(net "M_K_CPU1_SB_DQ<19>")
	)
	(arc
		(start 143.751808 -285.103824)
		(mid 144.028621 -285.179967)
		(end 144.307052 -285.10992)
		(width 0.0889)
		(layer "In6.Cu")
		(net "M_K_CPU1_SB_DQ<19>")
	)
	(arc
		(start 142.437612 -285.103824)
		(mid 142.619863 -285.053474)
		(end 142.803372 -285.098998)
		(width 0.0889)
		(layer "In6.Cu")
		(net "M_K_CPU1_SB_DQ<19>")
	)
	(arc
		(start 141.8717 -285.103824)
		(mid 142.154656 -285.180001)
		(end 142.437612 -285.103824)
		(width 0.0889)
		(layer "In6.Cu")
		(net "M_K_CPU1_SB_DQ<19>")
	)
	(arc
		(start 145.257266 -285.103824)
		(mid 145.347645 -285.066137)
		(end 145.444718 -285.053278)
		(width 0.0889)
		(layer "In6.Cu")
		(net "M_K_CPU1_SB_DQ<19>")
	)
	(arc
		(start 142.811754 -285.103824)
		(mid 143.09471 -285.180001)
		(end 143.377666 -285.103824)
		(width 0.0889)
		(layer "In6.Cu")
		(net "M_K_CPU1_SB_DQ<19>")
	)
	(arc
		(start 144.701514 -285.10992)
		(mid 144.9802 -285.18014)
		(end 145.257266 -285.103824)
		(width 0.0889)
		(layer "In6.Cu")
		(net "M_K_CPU1_SB_DQ<19>")
	)
	(arc
		(start 141.553184 -285.077662)
		(mid 141.715373 -285.054927)
		(end 141.8717 -285.103824)
		(width 0.0889)
		(layer "In6.Cu")
		(net "M_K_CPU1_SB_DQ<19>")
	)
	(arc
		(start 143.386048 -285.098998)
		(mid 143.569556 -285.053504)
		(end 143.751808 -285.103824)
		(width 0.0889)
		(layer "In6.Cu")
		(net "M_K_CPU1_SB_DQ<19>")
	)
	(arc
		(start 144.325848 -285.098998)
		(mid 144.509102 -285.053625)
		(end 144.6911 -285.103824)
		(width 0.0889)
		(layer "In6.Cu")
		(net "M_K_CPU1_SB_DQ<19>")
	)
	(segment
		(start 142.627858 -284.35046)
		(end 143.09471 -284.616398)
		(width 0.10668)
		(layer "F.Cu")
		(net "M_K_CPU1_SB_DQ<18>")
	)
	(segment
		(start 160.695894 -298.795186)
		(end 160.880552 -298.610528)
		(width 0.14478)
		(layer "In6.Cu")
		(net "M_K_CPU1_SB_DQ<18>")
	)
	(segment
		(start 156.943552 -294.673528)
		(end 157.174184 -294.673528)
		(width 0.14478)
		(layer "In6.Cu")
		(net "M_K_CPU1_SB_DQ<18>")
	)
	(segment
		(start 160.302448 -298.632118)
		(end 160.46577 -298.79544)
		(width 0.14478)
		(layer "In6.Cu")
		(net "M_K_CPU1_SB_DQ<18>")
	)
	(segment
		(start 160.486852 -297.986196)
		(end 160.487106 -298.216828)
		(width 0.14478)
		(layer "In6.Cu")
		(net "M_K_CPU1_SB_DQ<18>")
	)
	(segment
		(start 168.934892 -300.75505)
		(end 168.934892 -300.807374)
		(width 0.14478)
		(layer "In6.Cu")
		(net "M_K_CPU1_SB_DQ<18>")
	)
	(segment
		(start 160.880552 -298.610528)
		(end 161.111184 -298.610528)
		(width 0.14478)
		(layer "In6.Cu")
		(net "M_K_CPU1_SB_DQ<18>")
	)
	(segment
		(start 178.576732 -301.460408)
		(end 181.021736 -301.460408)
		(width 0.14478)
		(layer "In6.Cu")
		(net "M_K_CPU1_SB_DQ<18>")
	)
	(segment
		(start 158.10357 -296.43324)
		(end 158.333694 -296.432986)
		(width 0.14478)
		(layer "In6.Cu")
		(net "M_K_CPU1_SB_DQ<18>")
	)
	(segment
		(start 169.341546 -300.952154)
		(end 169.486326 -300.807374)
		(width 0.14478)
		(layer "In6.Cu")
		(net "M_K_CPU1_SB_DQ<18>")
	)
	(segment
		(start 161.877248 -300.206918)
		(end 162.04057 -300.37024)
		(width 0.14478)
		(layer "In6.Cu")
		(net "M_K_CPU1_SB_DQ<18>")
	)
	(segment
		(start 148.804122 -285.07436)
		(end 156.199586 -292.469824)
		(width 0.14478)
		(layer "In6.Cu")
		(net "M_K_CPU1_SB_DQ<18>")
	)
	(segment
		(start 194.17919 -300.61027)
		(end 194.604132 -301.035212)
		(width 0.14478)
		(layer "In6.Cu")
		(net "M_K_CPU1_SB_DQ<18>")
	)
	(segment
		(start 168.790112 -300.61027)
		(end 168.934892 -300.75505)
		(width 0.14478)
		(layer "In6.Cu")
		(net "M_K_CPU1_SB_DQ<18>")
	)
	(segment
		(start 169.486326 -300.413166)
		(end 169.631106 -300.268386)
		(width 0.14478)
		(layer "In6.Cu")
		(net "M_K_CPU1_SB_DQ<18>")
	)
	(segment
		(start 156.199586 -292.469824)
		(end 156.199586 -293.69893)
		(width 0.14478)
		(layer "In6.Cu")
		(net "M_K_CPU1_SB_DQ<18>")
	)
	(segment
		(start 169.89298 -300.268386)
		(end 170.03776 -300.413166)
		(width 0.14478)
		(layer "In6.Cu")
		(net "M_K_CPU1_SB_DQ<18>")
	)
	(segment
		(start 177.726594 -300.61027)
		(end 178.576732 -301.460408)
		(width 0.14478)
		(layer "In6.Cu")
		(net "M_K_CPU1_SB_DQ<18>")
	)
	(segment
		(start 157.31617 -295.64584)
		(end 157.546294 -295.645586)
		(width 0.14478)
		(layer "In6.Cu")
		(net "M_K_CPU1_SB_DQ<18>")
	)
	(segment
		(start 159.305752 -297.035728)
		(end 159.536384 -297.035728)
		(width 0.14478)
		(layer "In6.Cu")
		(net "M_K_CPU1_SB_DQ<18>")
	)
	(segment
		(start 161.089848 -299.188886)
		(end 161.089848 -299.419518)
		(width 0.14478)
		(layer "In6.Cu")
		(net "M_K_CPU1_SB_DQ<18>")
	)
	(segment
		(start 163.961064 -301.460408)
		(end 165.33876 -301.460408)
		(width 0.14478)
		(layer "In6.Cu")
		(net "M_K_CPU1_SB_DQ<18>")
	)
	(segment
		(start 162.270694 -300.369986)
		(end 162.455352 -300.185328)
		(width 0.14478)
		(layer "In6.Cu")
		(net "M_K_CPU1_SB_DQ<18>")
	)
	(segment
		(start 157.152848 -295.482518)
		(end 157.31617 -295.64584)
		(width 0.14478)
		(layer "In6.Cu")
		(net "M_K_CPU1_SB_DQ<18>")
	)
	(segment
		(start 161.111184 -298.610528)
		(end 161.274252 -298.773596)
		(width 0.14478)
		(layer "In6.Cu")
		(net "M_K_CPU1_SB_DQ<18>")
	)
	(segment
		(start 146.906234 -285.07436)
		(end 147.882102 -285.07436)
		(width 0.0889)
		(layer "In6.Cu")
		(net "M_K_CPU1_SB_DQ<18>")
	)
	(segment
		(start 147.882102 -285.07436)
		(end 148.804122 -285.07436)
		(width 0.14478)
		(layer "In6.Cu")
		(net "M_K_CPU1_SB_DQ<18>")
	)
	(segment
		(start 173.365922 -301.460408)
		(end 174.21606 -300.61027)
		(width 0.14478)
		(layer "In6.Cu")
		(net "M_K_CPU1_SB_DQ<18>")
	)
	(segment
		(start 174.21606 -300.61027)
		(end 177.726594 -300.61027)
		(width 0.14478)
		(layer "In6.Cu")
		(net "M_K_CPU1_SB_DQ<18>")
	)
	(segment
		(start 160.302448 -298.401486)
		(end 160.302448 -298.632118)
		(width 0.14478)
		(layer "In6.Cu")
		(net "M_K_CPU1_SB_DQ<18>")
	)
	(segment
		(start 158.912306 -296.642028)
		(end 158.727648 -296.826686)
		(width 0.14478)
		(layer "In6.Cu")
		(net "M_K_CPU1_SB_DQ<18>")
	)
	(segment
		(start 144.213326 -284.288992)
		(end 144.221708 -284.293818)
		(width 0.0889)
		(layer "In6.Cu")
		(net "M_K_CPU1_SB_DQ<18>")
	)
	(segment
		(start 159.536384 -297.035728)
		(end 159.699452 -297.198796)
		(width 0.14478)
		(layer "In6.Cu")
		(net "M_K_CPU1_SB_DQ<18>")
	)
	(segment
		(start 160.323784 -297.823128)
		(end 160.486852 -297.986196)
		(width 0.14478)
		(layer "In6.Cu")
		(net "M_K_CPU1_SB_DQ<18>")
	)
	(segment
		(start 142.940786 -284.350968)
		(end 142.963138 -284.267656)
		(width 0.0889)
		(layer "In6.Cu")
		(net "M_K_CPU1_SB_DQ<18>")
	)
	(segment
		(start 159.67837 -298.00804)
		(end 159.908494 -298.007786)
		(width 0.14478)
		(layer "In6.Cu")
		(net "M_K_CPU1_SB_DQ<18>")
	)
	(segment
		(start 170.03776 -300.46549)
		(end 171.032678 -301.460408)
		(width 0.14478)
		(layer "In6.Cu")
		(net "M_K_CPU1_SB_DQ<18>")
	)
	(segment
		(start 160.093152 -297.823128)
		(end 160.323784 -297.823128)
		(width 0.14478)
		(layer "In6.Cu")
		(net "M_K_CPU1_SB_DQ<18>")
	)
	(segment
		(start 157.152848 -295.251886)
		(end 157.152848 -295.482518)
		(width 0.14478)
		(layer "In6.Cu")
		(net "M_K_CPU1_SB_DQ<18>")
	)
	(segment
		(start 159.121094 -297.220386)
		(end 159.305752 -297.035728)
		(width 0.14478)
		(layer "In6.Cu")
		(net "M_K_CPU1_SB_DQ<18>")
	)
	(segment
		(start 157.174184 -294.673528)
		(end 157.337252 -294.836596)
		(width 0.14478)
		(layer "In6.Cu")
		(net "M_K_CPU1_SB_DQ<18>")
	)
	(segment
		(start 159.699452 -297.198796)
		(end 159.699706 -297.429428)
		(width 0.14478)
		(layer "In6.Cu")
		(net "M_K_CPU1_SB_DQ<18>")
	)
	(segment
		(start 160.46577 -298.79544)
		(end 160.695894 -298.795186)
		(width 0.14478)
		(layer "In6.Cu")
		(net "M_K_CPU1_SB_DQ<18>")
	)
	(segment
		(start 157.940248 -296.269918)
		(end 158.10357 -296.43324)
		(width 0.14478)
		(layer "In6.Cu")
		(net "M_K_CPU1_SB_DQ<18>")
	)
	(segment
		(start 161.898584 -299.397928)
		(end 162.061652 -299.560996)
		(width 0.14478)
		(layer "In6.Cu")
		(net "M_K_CPU1_SB_DQ<18>")
	)
	(segment
		(start 159.515048 -297.614086)
		(end 159.515048 -297.844718)
		(width 0.14478)
		(layer "In6.Cu")
		(net "M_K_CPU1_SB_DQ<18>")
	)
	(segment
		(start 157.337252 -294.836596)
		(end 157.337506 -295.067228)
		(width 0.14478)
		(layer "In6.Cu")
		(net "M_K_CPU1_SB_DQ<18>")
	)
	(segment
		(start 165.33876 -301.460408)
		(end 166.188898 -300.61027)
		(width 0.14478)
		(layer "In6.Cu")
		(net "M_K_CPU1_SB_DQ<18>")
	)
	(segment
		(start 146.201892 -284.370018)
		(end 146.906234 -285.07436)
		(width 0.0889)
		(layer "In6.Cu")
		(net "M_K_CPU1_SB_DQ<18>")
	)
	(segment
		(start 145.444718 -284.370018)
		(end 146.201892 -284.370018)
		(width 0.0889)
		(layer "In6.Cu")
		(net "M_K_CPU1_SB_DQ<18>")
	)
	(segment
		(start 143.09471 -284.616398)
		(end 142.940786 -284.350968)
		(width 0.0889)
		(layer "In6.Cu")
		(net "M_K_CPU1_SB_DQ<18>")
	)
	(segment
		(start 156.365448 -294.464486)
		(end 156.365448 -294.695118)
		(width 0.14478)
		(layer "In6.Cu")
		(net "M_K_CPU1_SB_DQ<18>")
	)
	(segment
		(start 158.748984 -296.248328)
		(end 158.912052 -296.411396)
		(width 0.14478)
		(layer "In6.Cu")
		(net "M_K_CPU1_SB_DQ<18>")
	)
	(segment
		(start 161.483294 -299.582586)
		(end 161.667952 -299.397928)
		(width 0.14478)
		(layer "In6.Cu")
		(net "M_K_CPU1_SB_DQ<18>")
	)
	(segment
		(start 189.67958 -300.61027)
		(end 194.17919 -300.61027)
		(width 0.14478)
		(layer "In6.Cu")
		(net "M_K_CPU1_SB_DQ<18>")
	)
	(segment
		(start 161.274252 -298.773596)
		(end 161.274506 -299.004228)
		(width 0.14478)
		(layer "In6.Cu")
		(net "M_K_CPU1_SB_DQ<18>")
	)
	(segment
		(start 169.631106 -300.268386)
		(end 169.89298 -300.268386)
		(width 0.14478)
		(layer "In6.Cu")
		(net "M_K_CPU1_SB_DQ<18>")
	)
	(segment
		(start 156.365448 -294.695118)
		(end 156.52877 -294.85844)
		(width 0.14478)
		(layer "In6.Cu")
		(net "M_K_CPU1_SB_DQ<18>")
	)
	(segment
		(start 158.89097 -297.22064)
		(end 159.121094 -297.220386)
		(width 0.14478)
		(layer "In6.Cu")
		(net "M_K_CPU1_SB_DQ<18>")
	)
	(segment
		(start 161.089848 -299.419518)
		(end 161.25317 -299.58284)
		(width 0.14478)
		(layer "In6.Cu")
		(net "M_K_CPU1_SB_DQ<18>")
	)
	(segment
		(start 156.549852 -294.049196)
		(end 156.550106 -294.279828)
		(width 0.14478)
		(layer "In6.Cu")
		(net "M_K_CPU1_SB_DQ<18>")
	)
	(segment
		(start 158.124652 -295.623996)
		(end 158.124906 -295.854628)
		(width 0.14478)
		(layer "In6.Cu")
		(net "M_K_CPU1_SB_DQ<18>")
	)
	(segment
		(start 186.120532 -301.460154)
		(end 188.829696 -301.460154)
		(width 0.14478)
		(layer "In6.Cu")
		(net "M_K_CPU1_SB_DQ<18>")
	)
	(segment
		(start 144.787366 -284.293818)
		(end 144.795748 -284.288992)
		(width 0.0889)
		(layer "In6.Cu")
		(net "M_K_CPU1_SB_DQ<18>")
	)
	(segment
		(start 156.758894 -294.858186)
		(end 156.943552 -294.673528)
		(width 0.14478)
		(layer "In6.Cu")
		(net "M_K_CPU1_SB_DQ<18>")
	)
	(segment
		(start 161.25317 -299.58284)
		(end 161.483294 -299.582586)
		(width 0.14478)
		(layer "In6.Cu")
		(net "M_K_CPU1_SB_DQ<18>")
	)
	(segment
		(start 168.934892 -300.807374)
		(end 169.079672 -300.952154)
		(width 0.14478)
		(layer "In6.Cu")
		(net "M_K_CPU1_SB_DQ<18>")
	)
	(segment
		(start 166.188898 -300.61027)
		(end 168.790112 -300.61027)
		(width 0.14478)
		(layer "In6.Cu")
		(net "M_K_CPU1_SB_DQ<18>")
	)
	(segment
		(start 181.871874 -300.61027)
		(end 185.270648 -300.61027)
		(width 0.14478)
		(layer "In6.Cu")
		(net "M_K_CPU1_SB_DQ<18>")
	)
	(segment
		(start 157.546294 -295.645586)
		(end 157.730952 -295.460928)
		(width 0.14478)
		(layer "In6.Cu")
		(net "M_K_CPU1_SB_DQ<18>")
	)
	(segment
		(start 169.079672 -300.952154)
		(end 169.341546 -300.952154)
		(width 0.14478)
		(layer "In6.Cu")
		(net "M_K_CPU1_SB_DQ<18>")
	)
	(segment
		(start 188.829696 -301.460154)
		(end 189.67958 -300.61027)
		(width 0.14478)
		(layer "In6.Cu")
		(net "M_K_CPU1_SB_DQ<18>")
	)
	(segment
		(start 159.908494 -298.007786)
		(end 160.093152 -297.823128)
		(width 0.14478)
		(layer "In6.Cu")
		(net "M_K_CPU1_SB_DQ<18>")
	)
	(segment
		(start 158.518352 -296.248328)
		(end 158.748984 -296.248328)
		(width 0.14478)
		(layer "In6.Cu")
		(net "M_K_CPU1_SB_DQ<18>")
	)
	(segment
		(start 157.940248 -296.039286)
		(end 157.940248 -296.269918)
		(width 0.14478)
		(layer "In6.Cu")
		(net "M_K_CPU1_SB_DQ<18>")
	)
	(segment
		(start 156.52877 -294.85844)
		(end 156.758894 -294.858186)
		(width 0.14478)
		(layer "In6.Cu")
		(net "M_K_CPU1_SB_DQ<18>")
	)
	(segment
		(start 158.727648 -297.057318)
		(end 158.89097 -297.22064)
		(width 0.14478)
		(layer "In6.Cu")
		(net "M_K_CPU1_SB_DQ<18>")
	)
	(segment
		(start 169.486326 -300.807374)
		(end 169.486326 -300.413166)
		(width 0.14478)
		(layer "In6.Cu")
		(net "M_K_CPU1_SB_DQ<18>")
	)
	(segment
		(start 161.274506 -299.004228)
		(end 161.089848 -299.188886)
		(width 0.14478)
		(layer "In6.Cu")
		(net "M_K_CPU1_SB_DQ<18>")
	)
	(segment
		(start 159.699706 -297.429428)
		(end 159.515048 -297.614086)
		(width 0.14478)
		(layer "In6.Cu")
		(net "M_K_CPU1_SB_DQ<18>")
	)
	(segment
		(start 157.730952 -295.460928)
		(end 157.961584 -295.460928)
		(width 0.14478)
		(layer "In6.Cu")
		(net "M_K_CPU1_SB_DQ<18>")
	)
	(segment
		(start 185.270648 -300.61027)
		(end 186.120532 -301.460154)
		(width 0.14478)
		(layer "In6.Cu")
		(net "M_K_CPU1_SB_DQ<18>")
	)
	(segment
		(start 156.550106 -294.279828)
		(end 156.365448 -294.464486)
		(width 0.14478)
		(layer "In6.Cu")
		(net "M_K_CPU1_SB_DQ<18>")
	)
	(segment
		(start 181.021736 -301.460408)
		(end 181.871874 -300.61027)
		(width 0.14478)
		(layer "In6.Cu")
		(net "M_K_CPU1_SB_DQ<18>")
	)
	(segment
		(start 157.961584 -295.460928)
		(end 158.124652 -295.623996)
		(width 0.14478)
		(layer "In6.Cu")
		(net "M_K_CPU1_SB_DQ<18>")
	)
	(segment
		(start 157.337506 -295.067228)
		(end 157.152848 -295.251886)
		(width 0.14478)
		(layer "In6.Cu")
		(net "M_K_CPU1_SB_DQ<18>")
	)
	(segment
		(start 162.685984 -300.185328)
		(end 163.961064 -301.460408)
		(width 0.14478)
		(layer "In6.Cu")
		(net "M_K_CPU1_SB_DQ<18>")
	)
	(segment
		(start 156.199586 -293.69893)
		(end 156.549852 -294.049196)
		(width 0.14478)
		(layer "In6.Cu")
		(net "M_K_CPU1_SB_DQ<18>")
	)
	(segment
		(start 162.061906 -299.791628)
		(end 161.877248 -299.976286)
		(width 0.14478)
		(layer "In6.Cu")
		(net "M_K_CPU1_SB_DQ<18>")
	)
	(segment
		(start 170.03776 -300.413166)
		(end 170.03776 -300.46549)
		(width 0.14478)
		(layer "In6.Cu")
		(net "M_K_CPU1_SB_DQ<18>")
	)
	(segment
		(start 158.912052 -296.411396)
		(end 158.912306 -296.642028)
		(width 0.14478)
		(layer "In6.Cu")
		(net "M_K_CPU1_SB_DQ<18>")
	)
	(segment
		(start 144.221708 -284.293818)
		(end 144.232122 -284.299914)
		(width 0.0889)
		(layer "In6.Cu")
		(net "M_K_CPU1_SB_DQ<18>")
	)
	(segment
		(start 171.032678 -301.460408)
		(end 173.365922 -301.460408)
		(width 0.14478)
		(layer "In6.Cu")
		(net "M_K_CPU1_SB_DQ<18>")
	)
	(segment
		(start 158.727648 -296.826686)
		(end 158.727648 -297.057318)
		(width 0.14478)
		(layer "In6.Cu")
		(net "M_K_CPU1_SB_DQ<18>")
	)
	(segment
		(start 162.061652 -299.560996)
		(end 162.061906 -299.791628)
		(width 0.14478)
		(layer "In6.Cu")
		(net "M_K_CPU1_SB_DQ<18>")
	)
	(segment
		(start 159.515048 -297.844718)
		(end 159.67837 -298.00804)
		(width 0.14478)
		(layer "In6.Cu")
		(net "M_K_CPU1_SB_DQ<18>")
	)
	(segment
		(start 162.04057 -300.37024)
		(end 162.270694 -300.369986)
		(width 0.14478)
		(layer "In6.Cu")
		(net "M_K_CPU1_SB_DQ<18>")
	)
	(segment
		(start 162.455352 -300.185328)
		(end 162.685984 -300.185328)
		(width 0.14478)
		(layer "In6.Cu")
		(net "M_K_CPU1_SB_DQ<18>")
	)
	(segment
		(start 158.124906 -295.854628)
		(end 157.940248 -296.039286)
		(width 0.14478)
		(layer "In6.Cu")
		(net "M_K_CPU1_SB_DQ<18>")
	)
	(segment
		(start 161.877248 -299.976286)
		(end 161.877248 -300.206918)
		(width 0.14478)
		(layer "In6.Cu")
		(net "M_K_CPU1_SB_DQ<18>")
	)
	(segment
		(start 158.333694 -296.432986)
		(end 158.518352 -296.248328)
		(width 0.14478)
		(layer "In6.Cu")
		(net "M_K_CPU1_SB_DQ<18>")
	)
	(segment
		(start 160.487106 -298.216828)
		(end 160.302448 -298.401486)
		(width 0.14478)
		(layer "In6.Cu")
		(net "M_K_CPU1_SB_DQ<18>")
	)
	(segment
		(start 161.667952 -299.397928)
		(end 161.898584 -299.397928)
		(width 0.14478)
		(layer "In6.Cu")
		(net "M_K_CPU1_SB_DQ<18>")
	)
	(arc
		(start 145.161508 -284.293818)
		(mid 145.298071 -284.350651)
		(end 145.444718 -284.370018)
		(width 0.0889)
		(layer "In6.Cu")
		(net "M_K_CPU1_SB_DQ<18>")
	)
	(arc
		(start 143.281654 -284.293818)
		(mid 143.56461 -284.369995)
		(end 143.847566 -284.293818)
		(width 0.0889)
		(layer "In6.Cu")
		(net "M_K_CPU1_SB_DQ<18>")
	)
	(arc
		(start 143.847566 -284.293818)
		(mid 144.029817 -284.243468)
		(end 144.213326 -284.288992)
		(width 0.0889)
		(layer "In6.Cu")
		(net "M_K_CPU1_SB_DQ<18>")
	)
	(arc
		(start 144.232122 -284.299914)
		(mid 144.510554 -284.370012)
		(end 144.787366 -284.293818)
		(width 0.0889)
		(layer "In6.Cu")
		(net "M_K_CPU1_SB_DQ<18>")
	)
	(arc
		(start 144.795748 -284.288992)
		(mid 144.979256 -284.243498)
		(end 145.161508 -284.293818)
		(width 0.0889)
		(layer "In6.Cu")
		(net "M_K_CPU1_SB_DQ<18>")
	)
	(arc
		(start 142.963138 -284.267656)
		(mid 143.125327 -284.244921)
		(end 143.281654 -284.293818)
		(width 0.0889)
		(layer "In6.Cu")
		(net "M_K_CPU1_SB_DQ<18>")
	)
	(segment
		(start 140.748004 -284.35046)
		(end 141.214856 -284.616398)
		(width 0.10668)
		(layer "F.Cu")
		(net "M_K_CPU1_SB_DQ<17>")
	)
	(segment
		(start 196.05244 -301.604934)
		(end 196.19722 -301.460154)
		(width 0.14478)
		(layer "In6.Cu")
		(net "M_K_CPU1_SB_DQ<17>")
	)
	(segment
		(start 196.05244 -301.914306)
		(end 196.05244 -301.604934)
		(width 0.14478)
		(layer "In6.Cu")
		(net "M_K_CPU1_SB_DQ<17>")
	)
	(segment
		(start 155.744926 -294.717978)
		(end 163.33724 -302.310292)
		(width 0.14478)
		(layer "In6.Cu")
		(net "M_K_CPU1_SB_DQ<17>")
	)
	(segment
		(start 155.744926 -292.658292)
		(end 155.744926 -294.717978)
		(width 0.14478)
		(layer "In6.Cu")
		(net "M_K_CPU1_SB_DQ<17>")
	)
	(segment
		(start 144.221454 -284.938978)
		(end 144.231868 -284.932882)
		(width 0.0889)
		(layer "In6.Cu")
		(net "M_K_CPU1_SB_DQ<17>")
	)
	(segment
		(start 178.511454 -302.310292)
		(end 181.083204 -302.310292)
		(width 0.14478)
		(layer "In6.Cu")
		(net "M_K_CPU1_SB_DQ<17>")
	)
	(segment
		(start 147.801076 -285.545784)
		(end 148.632418 -285.545784)
		(width 0.14478)
		(layer "In6.Cu")
		(net "M_K_CPU1_SB_DQ<17>")
	)
	(segment
		(start 196.56552 -301.460154)
		(end 198.7042 -301.88535)
		(width 0.14478)
		(layer "In6.Cu")
		(net "M_K_CPU1_SB_DQ<17>")
	)
	(segment
		(start 195.90766 -302.059086)
		(end 196.05244 -301.914306)
		(width 0.14478)
		(layer "In6.Cu")
		(net "M_K_CPU1_SB_DQ<17>")
	)
	(segment
		(start 171.23918 -302.310292)
		(end 173.476158 -302.310292)
		(width 0.14478)
		(layer "In6.Cu")
		(net "M_K_CPU1_SB_DQ<17>")
	)
	(segment
		(start 195.501006 -301.604934)
		(end 195.501006 -301.914306)
		(width 0.14478)
		(layer "In6.Cu")
		(net "M_K_CPU1_SB_DQ<17>")
	)
	(segment
		(start 188.823346 -302.310038)
		(end 189.67323 -301.460154)
		(width 0.14478)
		(layer "In6.Cu")
		(net "M_K_CPU1_SB_DQ<17>")
	)
	(segment
		(start 195.645786 -302.059086)
		(end 195.90766 -302.059086)
		(width 0.14478)
		(layer "In6.Cu")
		(net "M_K_CPU1_SB_DQ<17>")
	)
	(segment
		(start 144.787112 -284.938978)
		(end 144.798796 -284.945836)
		(width 0.0889)
		(layer "In6.Cu")
		(net "M_K_CPU1_SB_DQ<17>")
	)
	(segment
		(start 185.205624 -301.460408)
		(end 186.055508 -302.310292)
		(width 0.14478)
		(layer "In6.Cu")
		(net "M_K_CPU1_SB_DQ<17>")
	)
	(segment
		(start 173.476158 -302.310292)
		(end 174.326042 -301.460408)
		(width 0.14478)
		(layer "In6.Cu")
		(net "M_K_CPU1_SB_DQ<17>")
	)
	(segment
		(start 145.444718 -284.862778)
		(end 146.321272 -284.862778)
		(width 0.0889)
		(layer "In6.Cu")
		(net "M_K_CPU1_SB_DQ<17>")
	)
	(segment
		(start 146.808698 -285.350204)
		(end 147.605496 -285.350204)
		(width 0.0889)
		(layer "In6.Cu")
		(net "M_K_CPU1_SB_DQ<17>")
	)
	(segment
		(start 163.33724 -302.310292)
		(end 165.132004 -302.310292)
		(width 0.14478)
		(layer "In6.Cu")
		(net "M_K_CPU1_SB_DQ<17>")
	)
	(segment
		(start 181.933088 -301.460408)
		(end 185.205624 -301.460408)
		(width 0.14478)
		(layer "In6.Cu")
		(net "M_K_CPU1_SB_DQ<17>")
	)
	(segment
		(start 146.321272 -284.862778)
		(end 146.808698 -285.350204)
		(width 0.0889)
		(layer "In6.Cu")
		(net "M_K_CPU1_SB_DQ<17>")
	)
	(segment
		(start 195.501006 -301.914306)
		(end 195.645786 -302.059086)
		(width 0.14478)
		(layer "In6.Cu")
		(net "M_K_CPU1_SB_DQ<17>")
	)
	(segment
		(start 165.981888 -301.460408)
		(end 170.389296 -301.460408)
		(width 0.14478)
		(layer "In6.Cu")
		(net "M_K_CPU1_SB_DQ<17>")
	)
	(segment
		(start 144.20977 -284.945836)
		(end 144.221454 -284.938978)
		(width 0.0889)
		(layer "In6.Cu")
		(net "M_K_CPU1_SB_DQ<17>")
	)
	(segment
		(start 174.326042 -301.460408)
		(end 177.66157 -301.460408)
		(width 0.14478)
		(layer "In6.Cu")
		(net "M_K_CPU1_SB_DQ<17>")
	)
	(segment
		(start 186.055762 -302.310038)
		(end 188.823346 -302.310038)
		(width 0.14478)
		(layer "In6.Cu")
		(net "M_K_CPU1_SB_DQ<17>")
	)
	(segment
		(start 181.083204 -302.310292)
		(end 181.933088 -301.460408)
		(width 0.14478)
		(layer "In6.Cu")
		(net "M_K_CPU1_SB_DQ<17>")
	)
	(segment
		(start 141.967712 -284.938978)
		(end 141.976094 -284.943804)
		(width 0.0889)
		(layer "In6.Cu")
		(net "M_K_CPU1_SB_DQ<17>")
	)
	(segment
		(start 147.605496 -285.350204)
		(end 147.801076 -285.545784)
		(width 0.0889)
		(layer "In6.Cu")
		(net "M_K_CPU1_SB_DQ<17>")
	)
	(segment
		(start 148.632418 -285.545784)
		(end 155.744926 -292.658292)
		(width 0.14478)
		(layer "In6.Cu")
		(net "M_K_CPU1_SB_DQ<17>")
	)
	(segment
		(start 195.356226 -301.460154)
		(end 195.501006 -301.604934)
		(width 0.14478)
		(layer "In6.Cu")
		(net "M_K_CPU1_SB_DQ<17>")
	)
	(segment
		(start 141.214856 -284.616398)
		(end 141.36878 -284.881828)
		(width 0.0889)
		(layer "In6.Cu")
		(net "M_K_CPU1_SB_DQ<17>")
	)
	(segment
		(start 170.389296 -301.460408)
		(end 171.23918 -302.310292)
		(width 0.14478)
		(layer "In6.Cu")
		(net "M_K_CPU1_SB_DQ<17>")
	)
	(segment
		(start 141.36878 -284.881828)
		(end 141.464792 -284.907228)
		(width 0.0889)
		(layer "In6.Cu")
		(net "M_K_CPU1_SB_DQ<17>")
	)
	(segment
		(start 189.67323 -301.460154)
		(end 195.356226 -301.460154)
		(width 0.14478)
		(layer "In6.Cu")
		(net "M_K_CPU1_SB_DQ<17>")
	)
	(segment
		(start 165.132004 -302.310292)
		(end 165.981888 -301.460408)
		(width 0.14478)
		(layer "In6.Cu")
		(net "M_K_CPU1_SB_DQ<17>")
	)
	(segment
		(start 196.19722 -301.460154)
		(end 196.56552 -301.460154)
		(width 0.14478)
		(layer "In6.Cu")
		(net "M_K_CPU1_SB_DQ<17>")
	)
	(segment
		(start 186.055508 -302.310292)
		(end 186.055762 -302.310038)
		(width 0.14478)
		(layer "In6.Cu")
		(net "M_K_CPU1_SB_DQ<17>")
	)
	(segment
		(start 177.66157 -301.460408)
		(end 178.511454 -302.310292)
		(width 0.14478)
		(layer "In6.Cu")
		(net "M_K_CPU1_SB_DQ<17>")
	)
	(arc
		(start 145.161508 -284.938978)
		(mid 145.298067 -284.88212)
		(end 145.444718 -284.862778)
		(width 0.0889)
		(layer "In6.Cu")
		(net "M_K_CPU1_SB_DQ<17>")
	)
	(arc
		(start 143.281654 -284.938978)
		(mid 143.56461 -284.862801)
		(end 143.847566 -284.938978)
		(width 0.0889)
		(layer "In6.Cu")
		(net "M_K_CPU1_SB_DQ<17>")
	)
	(arc
		(start 144.798796 -284.945836)
		(mid 144.981051 -284.989489)
		(end 145.161508 -284.938978)
		(width 0.0889)
		(layer "In6.Cu")
		(net "M_K_CPU1_SB_DQ<17>")
	)
	(arc
		(start 141.464792 -284.907228)
		(mid 141.72 -284.863751)
		(end 141.967712 -284.938978)
		(width 0.0889)
		(layer "In6.Cu")
		(net "M_K_CPU1_SB_DQ<17>")
	)
	(arc
		(start 141.976094 -284.943804)
		(mid 142.159602 -284.989298)
		(end 142.341854 -284.938978)
		(width 0.0889)
		(layer "In6.Cu")
		(net "M_K_CPU1_SB_DQ<17>")
	)
	(arc
		(start 142.341854 -284.938978)
		(mid 142.62481 -284.862801)
		(end 142.907766 -284.938978)
		(width 0.0889)
		(layer "In6.Cu")
		(net "M_K_CPU1_SB_DQ<17>")
	)
	(arc
		(start 144.231868 -284.932882)
		(mid 144.5103 -284.862784)
		(end 144.787112 -284.938978)
		(width 0.0889)
		(layer "In6.Cu")
		(net "M_K_CPU1_SB_DQ<17>")
	)
	(arc
		(start 143.847566 -284.938978)
		(mid 144.027771 -284.989295)
		(end 144.20977 -284.945836)
		(width 0.0889)
		(layer "In6.Cu")
		(net "M_K_CPU1_SB_DQ<17>")
	)
	(arc
		(start 142.907766 -284.938978)
		(mid 143.09471 -284.989233)
		(end 143.281654 -284.938978)
		(width 0.0889)
		(layer "In6.Cu")
		(net "M_K_CPU1_SB_DQ<17>")
	)
	(segment
		(start 142.157958 -283.540454)
		(end 142.62481 -283.806392)
		(width 0.10668)
		(layer "F.Cu")
		(net "M_K_CPU1_SB_DQ<16>")
	)
	(segment
		(start 198.279004 -299.760132)
		(end 198.7042 -300.185328)
		(width 0.14478)
		(layer "In6.Cu")
		(net "M_K_CPU1_SB_DQ<16>")
	)
	(segment
		(start 166.3954 -299.760386)
		(end 166.669974 -299.760386)
		(width 0.14478)
		(layer "In6.Cu")
		(net "M_K_CPU1_SB_DQ<16>")
	)
	(segment
		(start 163.754054 -300.61027)
		(end 165.545516 -300.61027)
		(width 0.14478)
		(layer "In6.Cu")
		(net "M_K_CPU1_SB_DQ<16>")
	)
	(segment
		(start 170.9674 -300.61027)
		(end 173.456854 -300.61027)
		(width 0.14478)
		(layer "In6.Cu")
		(net "M_K_CPU1_SB_DQ<16>")
	)
	(segment
		(start 197.464172 -300.625764)
		(end 197.62724 -300.462696)
		(width 0.14478)
		(layer "In6.Cu")
		(net "M_K_CPU1_SB_DQ<16>")
	)
	(segment
		(start 147.905216 -284.613604)
		(end 149.003258 -284.613604)
		(width 0.14478)
		(layer "In6.Cu")
		(net "M_K_CPU1_SB_DQ<16>")
	)
	(segment
		(start 195.957698 -300.462696)
		(end 196.120766 -300.625764)
		(width 0.14478)
		(layer "In6.Cu")
		(net "M_K_CPU1_SB_DQ<16>")
	)
	(segment
		(start 178.511454 -300.61027)
		(end 181.17566 -300.61027)
		(width 0.14478)
		(layer "In6.Cu")
		(net "M_K_CPU1_SB_DQ<16>")
	)
	(segment
		(start 165.545516 -300.61027)
		(end 166.3954 -299.760386)
		(width 0.14478)
		(layer "In6.Cu")
		(net "M_K_CPU1_SB_DQ<16>")
	)
	(segment
		(start 166.949374 -300.039786)
		(end 167.221408 -300.039786)
		(width 0.14478)
		(layer "In6.Cu")
		(net "M_K_CPU1_SB_DQ<16>")
	)
	(segment
		(start 145.444972 -284.179518)
		(end 146.34718 -284.179518)
		(width 0.0889)
		(layer "In6.Cu")
		(net "M_K_CPU1_SB_DQ<16>")
	)
	(segment
		(start 144.691354 -284.128972)
		(end 144.701768 -284.122876)
		(width 0.0889)
		(layer "In6.Cu")
		(net "M_K_CPU1_SB_DQ<16>")
	)
	(segment
		(start 197.070726 -300.462696)
		(end 197.233794 -300.625764)
		(width 0.14478)
		(layer "In6.Cu")
		(net "M_K_CPU1_SB_DQ<16>")
	)
	(segment
		(start 167.772842 -299.480986)
		(end 168.052242 -299.760386)
		(width 0.14478)
		(layer "In6.Cu")
		(net "M_K_CPU1_SB_DQ<16>")
	)
	(segment
		(start 147.634452 -284.613604)
		(end 147.905216 -284.613604)
		(width 0.0889)
		(layer "In6.Cu")
		(net "M_K_CPU1_SB_DQ<16>")
	)
	(segment
		(start 195.79463 -299.760132)
		(end 195.957698 -299.9232)
		(width 0.14478)
		(layer "In6.Cu")
		(net "M_K_CPU1_SB_DQ<16>")
	)
	(segment
		(start 197.790308 -299.760132)
		(end 198.279004 -299.760132)
		(width 0.14478)
		(layer "In6.Cu")
		(net "M_K_CPU1_SB_DQ<16>")
	)
	(segment
		(start 156.654246 -292.264592)
		(end 156.654246 -293.510462)
		(width 0.14478)
		(layer "In6.Cu")
		(net "M_K_CPU1_SB_DQ<16>")
	)
	(segment
		(start 145.444718 -284.179264)
		(end 145.444972 -284.179518)
		(width 0.0889)
		(layer "In6.Cu")
		(net "M_K_CPU1_SB_DQ<16>")
	)
	(segment
		(start 196.514212 -300.462696)
		(end 196.514212 -299.9232)
		(width 0.14478)
		(layer "In6.Cu")
		(net "M_K_CPU1_SB_DQ<16>")
	)
	(segment
		(start 197.62724 -299.9232)
		(end 197.790308 -299.760132)
		(width 0.14478)
		(layer "In6.Cu")
		(net "M_K_CPU1_SB_DQ<16>")
	)
	(segment
		(start 196.120766 -300.625764)
		(end 196.351144 -300.625764)
		(width 0.14478)
		(layer "In6.Cu")
		(net "M_K_CPU1_SB_DQ<16>")
	)
	(segment
		(start 185.227976 -299.760386)
		(end 186.077606 -300.610016)
		(width 0.14478)
		(layer "In6.Cu")
		(net "M_K_CPU1_SB_DQ<16>")
	)
	(segment
		(start 196.907658 -299.760132)
		(end 197.070726 -299.9232)
		(width 0.14478)
		(layer "In6.Cu")
		(net "M_K_CPU1_SB_DQ<16>")
	)
	(segment
		(start 147.522438 -284.725618)
		(end 147.634452 -284.613604)
		(width 0.0889)
		(layer "In6.Cu")
		(net "M_K_CPU1_SB_DQ<16>")
	)
	(segment
		(start 167.361108 -299.900086)
		(end 167.361108 -299.620686)
		(width 0.14478)
		(layer "In6.Cu")
		(net "M_K_CPU1_SB_DQ<16>")
	)
	(segment
		(start 146.34718 -284.179518)
		(end 146.89328 -284.725618)
		(width 0.0889)
		(layer "In6.Cu")
		(net "M_K_CPU1_SB_DQ<16>")
	)
	(segment
		(start 168.052242 -299.760386)
		(end 170.117516 -299.760386)
		(width 0.14478)
		(layer "In6.Cu")
		(net "M_K_CPU1_SB_DQ<16>")
	)
	(segment
		(start 170.117516 -299.760386)
		(end 170.9674 -300.61027)
		(width 0.14478)
		(layer "In6.Cu")
		(net "M_K_CPU1_SB_DQ<16>")
	)
	(segment
		(start 146.89328 -284.725618)
		(end 147.522438 -284.725618)
		(width 0.0889)
		(layer "In6.Cu")
		(net "M_K_CPU1_SB_DQ<16>")
	)
	(segment
		(start 174.306738 -299.760386)
		(end 177.66157 -299.760386)
		(width 0.14478)
		(layer "In6.Cu")
		(net "M_K_CPU1_SB_DQ<16>")
	)
	(segment
		(start 197.233794 -300.625764)
		(end 197.464172 -300.625764)
		(width 0.14478)
		(layer "In6.Cu")
		(net "M_K_CPU1_SB_DQ<16>")
	)
	(segment
		(start 186.077606 -300.610016)
		(end 188.905642 -300.610016)
		(width 0.14478)
		(layer "In6.Cu")
		(net "M_K_CPU1_SB_DQ<16>")
	)
	(segment
		(start 144.307052 -284.122876)
		(end 144.317466 -284.128972)
		(width 0.0889)
		(layer "In6.Cu")
		(net "M_K_CPU1_SB_DQ<16>")
	)
	(segment
		(start 197.070726 -299.9232)
		(end 197.070726 -300.462696)
		(width 0.14478)
		(layer "In6.Cu")
		(net "M_K_CPU1_SB_DQ<16>")
	)
	(segment
		(start 173.456854 -300.61027)
		(end 174.306738 -299.760386)
		(width 0.14478)
		(layer "In6.Cu")
		(net "M_K_CPU1_SB_DQ<16>")
	)
	(segment
		(start 142.62481 -283.806392)
		(end 142.778734 -284.071822)
		(width 0.0889)
		(layer "In6.Cu")
		(net "M_K_CPU1_SB_DQ<16>")
	)
	(segment
		(start 196.514212 -299.9232)
		(end 196.67728 -299.760132)
		(width 0.14478)
		(layer "In6.Cu")
		(net "M_K_CPU1_SB_DQ<16>")
	)
	(segment
		(start 167.500808 -299.480986)
		(end 167.772842 -299.480986)
		(width 0.14478)
		(layer "In6.Cu")
		(net "M_K_CPU1_SB_DQ<16>")
	)
	(segment
		(start 196.67728 -299.760132)
		(end 196.907658 -299.760132)
		(width 0.14478)
		(layer "In6.Cu")
		(net "M_K_CPU1_SB_DQ<16>")
	)
	(segment
		(start 196.351144 -300.625764)
		(end 196.514212 -300.462696)
		(width 0.14478)
		(layer "In6.Cu")
		(net "M_K_CPU1_SB_DQ<16>")
	)
	(segment
		(start 177.66157 -299.760386)
		(end 178.511454 -300.61027)
		(width 0.14478)
		(layer "In6.Cu")
		(net "M_K_CPU1_SB_DQ<16>")
	)
	(segment
		(start 149.003258 -284.613604)
		(end 156.654246 -292.264592)
		(width 0.14478)
		(layer "In6.Cu")
		(net "M_K_CPU1_SB_DQ<16>")
	)
	(segment
		(start 188.905642 -300.610016)
		(end 189.755526 -299.760132)
		(width 0.14478)
		(layer "In6.Cu")
		(net "M_K_CPU1_SB_DQ<16>")
	)
	(segment
		(start 167.221408 -300.039786)
		(end 167.361108 -299.900086)
		(width 0.14478)
		(layer "In6.Cu")
		(net "M_K_CPU1_SB_DQ<16>")
	)
	(segment
		(start 156.654246 -293.510462)
		(end 163.754054 -300.61027)
		(width 0.14478)
		(layer "In6.Cu")
		(net "M_K_CPU1_SB_DQ<16>")
	)
	(segment
		(start 182.025544 -299.760386)
		(end 185.227976 -299.760386)
		(width 0.14478)
		(layer "In6.Cu")
		(net "M_K_CPU1_SB_DQ<16>")
	)
	(segment
		(start 166.669974 -299.760386)
		(end 166.949374 -300.039786)
		(width 0.14478)
		(layer "In6.Cu")
		(net "M_K_CPU1_SB_DQ<16>")
	)
	(segment
		(start 167.361108 -299.620686)
		(end 167.500808 -299.480986)
		(width 0.14478)
		(layer "In6.Cu")
		(net "M_K_CPU1_SB_DQ<16>")
	)
	(segment
		(start 142.778734 -284.071822)
		(end 142.874746 -284.097222)
		(width 0.0889)
		(layer "In6.Cu")
		(net "M_K_CPU1_SB_DQ<16>")
	)
	(segment
		(start 195.957698 -299.9232)
		(end 195.957698 -300.462696)
		(width 0.14478)
		(layer "In6.Cu")
		(net "M_K_CPU1_SB_DQ<16>")
	)
	(segment
		(start 181.17566 -300.61027)
		(end 182.025544 -299.760386)
		(width 0.14478)
		(layer "In6.Cu")
		(net "M_K_CPU1_SB_DQ<16>")
	)
	(segment
		(start 189.755526 -299.760132)
		(end 195.79463 -299.760132)
		(width 0.14478)
		(layer "In6.Cu")
		(net "M_K_CPU1_SB_DQ<16>")
	)
	(segment
		(start 143.377666 -284.128972)
		(end 143.386048 -284.133798)
		(width 0.0889)
		(layer "In6.Cu")
		(net "M_K_CPU1_SB_DQ<16>")
	)
	(segment
		(start 197.62724 -300.462696)
		(end 197.62724 -299.9232)
		(width 0.14478)
		(layer "In6.Cu")
		(net "M_K_CPU1_SB_DQ<16>")
	)
	(arc
		(start 143.751808 -284.128972)
		(mid 144.028621 -284.052829)
		(end 144.307052 -284.122876)
		(width 0.0889)
		(layer "In6.Cu")
		(net "M_K_CPU1_SB_DQ<16>")
	)
	(arc
		(start 144.317466 -284.128972)
		(mid 144.50441 -284.179227)
		(end 144.691354 -284.128972)
		(width 0.0889)
		(layer "In6.Cu")
		(net "M_K_CPU1_SB_DQ<16>")
	)
	(arc
		(start 142.874746 -284.097222)
		(mid 143.129954 -284.053745)
		(end 143.377666 -284.128972)
		(width 0.0889)
		(layer "In6.Cu")
		(net "M_K_CPU1_SB_DQ<16>")
	)
	(arc
		(start 145.25752 -284.128972)
		(mid 145.347796 -284.166477)
		(end 145.444718 -284.179264)
		(width 0.0889)
		(layer "In6.Cu")
		(net "M_K_CPU1_SB_DQ<16>")
	)
	(arc
		(start 144.701768 -284.122876)
		(mid 144.980454 -284.052656)
		(end 145.25752 -284.128972)
		(width 0.0889)
		(layer "In6.Cu")
		(net "M_K_CPU1_SB_DQ<16>")
	)
	(arc
		(start 143.386048 -284.133798)
		(mid 143.569556 -284.179292)
		(end 143.751808 -284.128972)
		(width 0.0889)
		(layer "In6.Cu")
		(net "M_K_CPU1_SB_DQ<16>")
	)
	(segment
		(start 141.217904 -283.540454)
		(end 141.684756 -283.806392)
		(width 0.10668)
		(layer "F.Cu")
		(net "M_K_CPU1_SB_DQ<15>")
	)
	(segment
		(start 160.793176 -296.472864)
		(end 160.992058 -296.671746)
		(width 0.14478)
		(layer "In6.Cu")
		(net "M_K_CPU1_SB_DQ<15>")
	)
	(segment
		(start 171.032678 -299.76064)
		(end 173.49597 -299.76064)
		(width 0.14478)
		(layer "In6.Cu")
		(net "M_K_CPU1_SB_DQ<15>")
	)
	(segment
		(start 158.82874 -294.898064)
		(end 159.218376 -294.898064)
		(width 0.14478)
		(layer "In6.Cu")
		(net "M_K_CPU1_SB_DQ<15>")
	)
	(segment
		(start 147.852892 -284.057344)
		(end 149.23389 -284.057344)
		(width 0.14478)
		(layer "In6.Cu")
		(net "M_K_CPU1_SB_DQ<15>")
	)
	(segment
		(start 143.377666 -283.483812)
		(end 143.386048 -283.478986)
		(width 0.0889)
		(layer "In6.Cu")
		(net "M_K_CPU1_SB_DQ<15>")
	)
	(segment
		(start 146.476466 -283.433266)
		(end 146.933412 -283.890212)
		(width 0.0889)
		(layer "In6.Cu")
		(net "M_K_CPU1_SB_DQ<15>")
	)
	(segment
		(start 193.55816 -298.619164)
		(end 193.849498 -298.910502)
		(width 0.14478)
		(layer "In6.Cu")
		(net "M_K_CPU1_SB_DQ<15>")
	)
	(segment
		(start 161.19094 -297.260264)
		(end 161.580576 -297.260264)
		(width 0.14478)
		(layer "In6.Cu")
		(net "M_K_CPU1_SB_DQ<15>")
	)
	(segment
		(start 165.608 -299.76064)
		(end 166.458138 -298.910502)
		(width 0.14478)
		(layer "In6.Cu")
		(net "M_K_CPU1_SB_DQ<15>")
	)
	(segment
		(start 144.6911 -283.483812)
		(end 144.701514 -283.489908)
		(width 0.0889)
		(layer "In6.Cu")
		(net "M_K_CPU1_SB_DQ<15>")
	)
	(segment
		(start 160.204658 -295.884346)
		(end 160.204658 -296.273982)
		(width 0.14478)
		(layer "In6.Cu")
		(net "M_K_CPU1_SB_DQ<15>")
	)
	(segment
		(start 185.198258 -298.910502)
		(end 186.047888 -299.760132)
		(width 0.14478)
		(layer "In6.Cu")
		(net "M_K_CPU1_SB_DQ<15>")
	)
	(segment
		(start 192.179956 -298.619164)
		(end 192.445132 -298.619164)
		(width 0.14478)
		(layer "In6.Cu")
		(net "M_K_CPU1_SB_DQ<15>")
	)
	(segment
		(start 159.61614 -295.685464)
		(end 160.005776 -295.685464)
		(width 0.14478)
		(layer "In6.Cu")
		(net "M_K_CPU1_SB_DQ<15>")
	)
	(segment
		(start 192.73647 -298.910502)
		(end 193.001646 -298.910502)
		(width 0.14478)
		(layer "In6.Cu")
		(net "M_K_CPU1_SB_DQ<15>")
	)
	(segment
		(start 141.684756 -283.806392)
		(end 141.530832 -283.540962)
		(width 0.0889)
		(layer "In6.Cu")
		(net "M_K_CPU1_SB_DQ<15>")
	)
	(segment
		(start 147.25269 -283.890212)
		(end 147.419822 -284.057344)
		(width 0.0889)
		(layer "In6.Cu")
		(net "M_K_CPU1_SB_DQ<15>")
	)
	(segment
		(start 174.346108 -298.910502)
		(end 177.726594 -298.910502)
		(width 0.14478)
		(layer "In6.Cu")
		(net "M_K_CPU1_SB_DQ<15>")
	)
	(segment
		(start 182.088282 -298.910502)
		(end 185.198258 -298.910502)
		(width 0.14478)
		(layer "In6.Cu")
		(net "M_K_CPU1_SB_DQ<15>")
	)
	(segment
		(start 145.444718 -283.433266)
		(end 146.476466 -283.433266)
		(width 0.0889)
		(layer "In6.Cu")
		(net "M_K_CPU1_SB_DQ<15>")
	)
	(segment
		(start 194.17919 -298.910502)
		(end 194.604132 -299.335444)
		(width 0.14478)
		(layer "In6.Cu")
		(net "M_K_CPU1_SB_DQ<15>")
	)
	(segment
		(start 157.842458 -293.522146)
		(end 157.842458 -293.911782)
		(width 0.14478)
		(layer "In6.Cu")
		(net "M_K_CPU1_SB_DQ<15>")
	)
	(segment
		(start 186.047888 -299.760132)
		(end 188.838078 -299.760132)
		(width 0.14478)
		(layer "In6.Cu")
		(net "M_K_CPU1_SB_DQ<15>")
	)
	(segment
		(start 178.576732 -299.76064)
		(end 181.238144 -299.76064)
		(width 0.14478)
		(layer "In6.Cu")
		(net "M_K_CPU1_SB_DQ<15>")
	)
	(segment
		(start 163.749736 -299.76064)
		(end 165.608 -299.76064)
		(width 0.14478)
		(layer "In6.Cu")
		(net "M_K_CPU1_SB_DQ<15>")
	)
	(segment
		(start 158.430976 -294.110664)
		(end 158.629858 -294.309546)
		(width 0.14478)
		(layer "In6.Cu")
		(net "M_K_CPU1_SB_DQ<15>")
	)
	(segment
		(start 193.001646 -298.910502)
		(end 193.292984 -298.619164)
		(width 0.14478)
		(layer "In6.Cu")
		(net "M_K_CPU1_SB_DQ<15>")
	)
	(segment
		(start 146.933412 -283.890212)
		(end 147.25269 -283.890212)
		(width 0.0889)
		(layer "In6.Cu")
		(net "M_K_CPU1_SB_DQ<15>")
	)
	(segment
		(start 161.779458 -297.459146)
		(end 161.779458 -297.848782)
		(width 0.14478)
		(layer "In6.Cu")
		(net "M_K_CPU1_SB_DQ<15>")
	)
	(segment
		(start 160.992058 -296.671746)
		(end 160.992058 -297.061382)
		(width 0.14478)
		(layer "In6.Cu")
		(net "M_K_CPU1_SB_DQ<15>")
	)
	(segment
		(start 188.838078 -299.760132)
		(end 189.687708 -298.910502)
		(width 0.14478)
		(layer "In6.Cu")
		(net "M_K_CPU1_SB_DQ<15>")
	)
	(segment
		(start 147.419822 -284.057344)
		(end 147.852892 -284.057344)
		(width 0.0889)
		(layer "In6.Cu")
		(net "M_K_CPU1_SB_DQ<15>")
	)
	(segment
		(start 158.629858 -294.309546)
		(end 158.629858 -294.699182)
		(width 0.14478)
		(layer "In6.Cu")
		(net "M_K_CPU1_SB_DQ<15>")
	)
	(segment
		(start 162.566858 -298.636182)
		(end 162.76574 -298.835064)
		(width 0.14478)
		(layer "In6.Cu")
		(net "M_K_CPU1_SB_DQ<15>")
	)
	(segment
		(start 159.218376 -294.898064)
		(end 159.417258 -295.096946)
		(width 0.14478)
		(layer "In6.Cu")
		(net "M_K_CPU1_SB_DQ<15>")
	)
	(segment
		(start 157.842458 -293.911782)
		(end 158.04134 -294.110664)
		(width 0.14478)
		(layer "In6.Cu")
		(net "M_K_CPU1_SB_DQ<15>")
	)
	(segment
		(start 158.04134 -294.110664)
		(end 158.430976 -294.110664)
		(width 0.14478)
		(layer "In6.Cu")
		(net "M_K_CPU1_SB_DQ<15>")
	)
	(segment
		(start 162.566858 -298.246546)
		(end 162.566858 -298.636182)
		(width 0.14478)
		(layer "In6.Cu")
		(net "M_K_CPU1_SB_DQ<15>")
	)
	(segment
		(start 162.82416 -298.835064)
		(end 163.749736 -299.76064)
		(width 0.14478)
		(layer "In6.Cu")
		(net "M_K_CPU1_SB_DQ<15>")
	)
	(segment
		(start 166.458138 -298.910502)
		(end 170.18254 -298.910502)
		(width 0.14478)
		(layer "In6.Cu")
		(net "M_K_CPU1_SB_DQ<15>")
	)
	(segment
		(start 160.992058 -297.061382)
		(end 161.19094 -297.260264)
		(width 0.14478)
		(layer "In6.Cu")
		(net "M_K_CPU1_SB_DQ<15>")
	)
	(segment
		(start 161.779458 -297.848782)
		(end 161.97834 -298.047664)
		(width 0.14478)
		(layer "In6.Cu")
		(net "M_K_CPU1_SB_DQ<15>")
	)
	(segment
		(start 173.49597 -299.76064)
		(end 174.346108 -298.910502)
		(width 0.14478)
		(layer "In6.Cu")
		(net "M_K_CPU1_SB_DQ<15>")
	)
	(segment
		(start 149.23389 -284.057344)
		(end 157.261306 -292.08476)
		(width 0.14478)
		(layer "In6.Cu")
		(net "M_K_CPU1_SB_DQ<15>")
	)
	(segment
		(start 161.580576 -297.260264)
		(end 161.779458 -297.459146)
		(width 0.14478)
		(layer "In6.Cu")
		(net "M_K_CPU1_SB_DQ<15>")
	)
	(segment
		(start 193.849498 -298.910502)
		(end 194.17919 -298.910502)
		(width 0.14478)
		(layer "In6.Cu")
		(net "M_K_CPU1_SB_DQ<15>")
	)
	(segment
		(start 160.40354 -296.472864)
		(end 160.793176 -296.472864)
		(width 0.14478)
		(layer "In6.Cu")
		(net "M_K_CPU1_SB_DQ<15>")
	)
	(segment
		(start 159.417258 -295.486582)
		(end 159.61614 -295.685464)
		(width 0.14478)
		(layer "In6.Cu")
		(net "M_K_CPU1_SB_DQ<15>")
	)
	(segment
		(start 177.726594 -298.910502)
		(end 178.576732 -299.76064)
		(width 0.14478)
		(layer "In6.Cu")
		(net "M_K_CPU1_SB_DQ<15>")
	)
	(segment
		(start 191.888618 -298.910502)
		(end 192.179956 -298.619164)
		(width 0.14478)
		(layer "In6.Cu")
		(net "M_K_CPU1_SB_DQ<15>")
	)
	(segment
		(start 189.687708 -298.910502)
		(end 191.888618 -298.910502)
		(width 0.14478)
		(layer "In6.Cu")
		(net "M_K_CPU1_SB_DQ<15>")
	)
	(segment
		(start 144.307052 -283.489908)
		(end 144.317466 -283.483812)
		(width 0.0889)
		(layer "In6.Cu")
		(net "M_K_CPU1_SB_DQ<15>")
	)
	(segment
		(start 159.417258 -295.096946)
		(end 159.417258 -295.486582)
		(width 0.14478)
		(layer "In6.Cu")
		(net "M_K_CPU1_SB_DQ<15>")
	)
	(segment
		(start 181.238144 -299.76064)
		(end 182.088282 -298.910502)
		(width 0.14478)
		(layer "In6.Cu")
		(net "M_K_CPU1_SB_DQ<15>")
	)
	(segment
		(start 170.18254 -298.910502)
		(end 171.032678 -299.76064)
		(width 0.14478)
		(layer "In6.Cu")
		(net "M_K_CPU1_SB_DQ<15>")
	)
	(segment
		(start 193.292984 -298.619164)
		(end 193.55816 -298.619164)
		(width 0.14478)
		(layer "In6.Cu")
		(net "M_K_CPU1_SB_DQ<15>")
	)
	(segment
		(start 142.803372 -283.478986)
		(end 142.811754 -283.483812)
		(width 0.0889)
		(layer "In6.Cu")
		(net "M_K_CPU1_SB_DQ<15>")
	)
	(segment
		(start 160.204658 -296.273982)
		(end 160.40354 -296.472864)
		(width 0.14478)
		(layer "In6.Cu")
		(net "M_K_CPU1_SB_DQ<15>")
	)
	(segment
		(start 158.629858 -294.699182)
		(end 158.82874 -294.898064)
		(width 0.14478)
		(layer "In6.Cu")
		(net "M_K_CPU1_SB_DQ<15>")
	)
	(segment
		(start 157.261306 -292.940994)
		(end 157.842458 -293.522146)
		(width 0.14478)
		(layer "In6.Cu")
		(net "M_K_CPU1_SB_DQ<15>")
	)
	(segment
		(start 157.261306 -292.08476)
		(end 157.261306 -292.940994)
		(width 0.14478)
		(layer "In6.Cu")
		(net "M_K_CPU1_SB_DQ<15>")
	)
	(segment
		(start 192.445132 -298.619164)
		(end 192.73647 -298.910502)
		(width 0.14478)
		(layer "In6.Cu")
		(net "M_K_CPU1_SB_DQ<15>")
	)
	(segment
		(start 161.97834 -298.047664)
		(end 162.367976 -298.047664)
		(width 0.14478)
		(layer "In6.Cu")
		(net "M_K_CPU1_SB_DQ<15>")
	)
	(segment
		(start 141.530832 -283.540962)
		(end 141.553184 -283.45765)
		(width 0.0889)
		(layer "In6.Cu")
		(net "M_K_CPU1_SB_DQ<15>")
	)
	(segment
		(start 162.76574 -298.835064)
		(end 162.82416 -298.835064)
		(width 0.14478)
		(layer "In6.Cu")
		(net "M_K_CPU1_SB_DQ<15>")
	)
	(segment
		(start 144.317466 -283.483812)
		(end 144.325848 -283.478986)
		(width 0.0889)
		(layer "In6.Cu")
		(net "M_K_CPU1_SB_DQ<15>")
	)
	(segment
		(start 162.367976 -298.047664)
		(end 162.566858 -298.246546)
		(width 0.14478)
		(layer "In6.Cu")
		(net "M_K_CPU1_SB_DQ<15>")
	)
	(segment
		(start 160.005776 -295.685464)
		(end 160.204658 -295.884346)
		(width 0.14478)
		(layer "In6.Cu")
		(net "M_K_CPU1_SB_DQ<15>")
	)
	(arc
		(start 143.386048 -283.478986)
		(mid 143.569556 -283.433492)
		(end 143.751808 -283.483812)
		(width 0.0889)
		(layer "In6.Cu")
		(net "M_K_CPU1_SB_DQ<15>")
	)
	(arc
		(start 142.437612 -283.483812)
		(mid 142.619863 -283.433462)
		(end 142.803372 -283.478986)
		(width 0.0889)
		(layer "In6.Cu")
		(net "M_K_CPU1_SB_DQ<15>")
	)
	(arc
		(start 144.701514 -283.489908)
		(mid 144.9802 -283.560128)
		(end 145.257266 -283.483812)
		(width 0.0889)
		(layer "In6.Cu")
		(net "M_K_CPU1_SB_DQ<15>")
	)
	(arc
		(start 143.751808 -283.483812)
		(mid 144.028621 -283.559955)
		(end 144.307052 -283.489908)
		(width 0.0889)
		(layer "In6.Cu")
		(net "M_K_CPU1_SB_DQ<15>")
	)
	(arc
		(start 145.257266 -283.483812)
		(mid 145.347645 -283.446125)
		(end 145.444718 -283.433266)
		(width 0.0889)
		(layer "In6.Cu")
		(net "M_K_CPU1_SB_DQ<15>")
	)
	(arc
		(start 141.8717 -283.483812)
		(mid 142.154656 -283.559989)
		(end 142.437612 -283.483812)
		(width 0.0889)
		(layer "In6.Cu")
		(net "M_K_CPU1_SB_DQ<15>")
	)
	(arc
		(start 141.553184 -283.45765)
		(mid 141.715373 -283.434915)
		(end 141.8717 -283.483812)
		(width 0.0889)
		(layer "In6.Cu")
		(net "M_K_CPU1_SB_DQ<15>")
	)
	(arc
		(start 144.325848 -283.478986)
		(mid 144.509102 -283.433613)
		(end 144.6911 -283.483812)
		(width 0.0889)
		(layer "In6.Cu")
		(net "M_K_CPU1_SB_DQ<15>")
	)
	(arc
		(start 142.811754 -283.483812)
		(mid 143.09471 -283.559989)
		(end 143.377666 -283.483812)
		(width 0.0889)
		(layer "In6.Cu")
		(net "M_K_CPU1_SB_DQ<15>")
	)
	(segment
		(start 142.627858 -282.730448)
		(end 143.09471 -282.996386)
		(width 0.10668)
		(layer "F.Cu")
		(net "M_K_CPU1_SB_DQ<14>")
	)
	(segment
		(start 158.807404 -292.996112)
		(end 159.116014 -292.687502)
		(width 0.14478)
		(layer "In6.Cu")
		(net "M_K_CPU1_SB_DQ<14>")
	)
	(segment
		(start 170.18254 -297.21048)
		(end 171.032678 -298.060618)
		(width 0.14478)
		(layer "In6.Cu")
		(net "M_K_CPU1_SB_DQ<14>")
	)
	(segment
		(start 189.78753 -297.21048)
		(end 191.725042 -297.21048)
		(width 0.14478)
		(layer "In6.Cu")
		(net "M_K_CPU1_SB_DQ<14>")
	)
	(segment
		(start 192.014602 -296.826686)
		(end 192.276476 -296.826686)
		(width 0.14478)
		(layer "In6.Cu")
		(net "M_K_CPU1_SB_DQ<14>")
	)
	(segment
		(start 144.787366 -282.673806)
		(end 144.795748 -282.66898)
		(width 0.0889)
		(layer "In6.Cu")
		(net "M_K_CPU1_SB_DQ<14>")
	)
	(segment
		(start 181.238144 -298.060618)
		(end 182.088282 -297.21048)
		(width 0.14478)
		(layer "In6.Cu")
		(net "M_K_CPU1_SB_DQ<14>")
	)
	(segment
		(start 160.101026 -293.46779)
		(end 160.286446 -293.65321)
		(width 0.14478)
		(layer "In6.Cu")
		(net "M_K_CPU1_SB_DQ<14>")
	)
	(segment
		(start 173.69409 -298.060618)
		(end 174.544228 -297.21048)
		(width 0.14478)
		(layer "In6.Cu")
		(net "M_K_CPU1_SB_DQ<14>")
	)
	(segment
		(start 193.524124 -297.0657)
		(end 193.668904 -297.21048)
		(width 0.14478)
		(layer "In6.Cu")
		(net "M_K_CPU1_SB_DQ<14>")
	)
	(segment
		(start 192.421256 -296.971466)
		(end 192.421256 -297.449494)
		(width 0.14478)
		(layer "In6.Cu")
		(net "M_K_CPU1_SB_DQ<14>")
	)
	(segment
		(start 193.668904 -297.21048)
		(end 194.17919 -297.21048)
		(width 0.14478)
		(layer "In6.Cu")
		(net "M_K_CPU1_SB_DQ<14>")
	)
	(segment
		(start 193.379344 -296.826686)
		(end 193.524124 -296.971466)
		(width 0.14478)
		(layer "In6.Cu")
		(net "M_K_CPU1_SB_DQ<14>")
	)
	(segment
		(start 163.66744 -298.060618)
		(end 166.124128 -298.060618)
		(width 0.14478)
		(layer "In6.Cu")
		(net "M_K_CPU1_SB_DQ<14>")
	)
	(segment
		(start 142.940786 -282.730956)
		(end 142.963138 -282.647644)
		(width 0.0889)
		(layer "In6.Cu")
		(net "M_K_CPU1_SB_DQ<14>")
	)
	(segment
		(start 166.124128 -298.060618)
		(end 166.974266 -297.21048)
		(width 0.14478)
		(layer "In6.Cu")
		(net "M_K_CPU1_SB_DQ<14>")
	)
	(segment
		(start 159.977836 -294.371014)
		(end 163.66744 -298.060618)
		(width 0.14478)
		(layer "In6.Cu")
		(net "M_K_CPU1_SB_DQ<14>")
	)
	(segment
		(start 160.286446 -293.857934)
		(end 159.977836 -294.166544)
		(width 0.14478)
		(layer "In6.Cu")
		(net "M_K_CPU1_SB_DQ<14>")
	)
	(segment
		(start 159.320738 -292.687502)
		(end 159.506158 -292.872922)
		(width 0.14478)
		(layer "In6.Cu")
		(net "M_K_CPU1_SB_DQ<14>")
	)
	(segment
		(start 159.197548 -293.590726)
		(end 159.382968 -293.776146)
		(width 0.14478)
		(layer "In6.Cu")
		(net "M_K_CPU1_SB_DQ<14>")
	)
	(segment
		(start 192.97269 -296.971466)
		(end 193.11747 -296.826686)
		(width 0.14478)
		(layer "In6.Cu")
		(net "M_K_CPU1_SB_DQ<14>")
	)
	(segment
		(start 192.566036 -297.594274)
		(end 192.82791 -297.594274)
		(width 0.14478)
		(layer "In6.Cu")
		(net "M_K_CPU1_SB_DQ<14>")
	)
	(segment
		(start 147.813776 -283.148024)
		(end 149.610826 -283.148024)
		(width 0.14478)
		(layer "In6.Cu")
		(net "M_K_CPU1_SB_DQ<14>")
	)
	(segment
		(start 158.60268 -292.995858)
		(end 158.807404 -292.996112)
		(width 0.14478)
		(layer "In6.Cu")
		(net "M_K_CPU1_SB_DQ<14>")
	)
	(segment
		(start 149.610826 -283.148024)
		(end 158.21279 -291.749988)
		(width 0.14478)
		(layer "In6.Cu")
		(net "M_K_CPU1_SB_DQ<14>")
	)
	(segment
		(start 158.21279 -291.749988)
		(end 158.21279 -292.605968)
		(width 0.14478)
		(layer "In6.Cu")
		(net "M_K_CPU1_SB_DQ<14>")
	)
	(segment
		(start 159.197548 -293.386256)
		(end 159.197548 -293.590726)
		(width 0.14478)
		(layer "In6.Cu")
		(net "M_K_CPU1_SB_DQ<14>")
	)
	(segment
		(start 159.116014 -292.687502)
		(end 159.320738 -292.687502)
		(width 0.14478)
		(layer "In6.Cu")
		(net "M_K_CPU1_SB_DQ<14>")
	)
	(segment
		(start 144.221708 -282.673806)
		(end 144.232122 -282.679902)
		(width 0.0889)
		(layer "In6.Cu")
		(net "M_K_CPU1_SB_DQ<14>")
	)
	(segment
		(start 182.088282 -297.21048)
		(end 184.955688 -297.21048)
		(width 0.14478)
		(layer "In6.Cu")
		(net "M_K_CPU1_SB_DQ<14>")
	)
	(segment
		(start 184.955688 -297.21048)
		(end 185.805572 -298.060364)
		(width 0.14478)
		(layer "In6.Cu")
		(net "M_K_CPU1_SB_DQ<14>")
	)
	(segment
		(start 146.501358 -282.756356)
		(end 146.893026 -283.148024)
		(width 0.0889)
		(layer "In6.Cu")
		(net "M_K_CPU1_SB_DQ<14>")
	)
	(segment
		(start 160.286446 -293.65321)
		(end 160.286446 -293.857934)
		(width 0.14478)
		(layer "In6.Cu")
		(net "M_K_CPU1_SB_DQ<14>")
	)
	(segment
		(start 191.725042 -297.21048)
		(end 191.869822 -297.0657)
		(width 0.14478)
		(layer "In6.Cu")
		(net "M_K_CPU1_SB_DQ<14>")
	)
	(segment
		(start 191.869822 -296.971466)
		(end 192.014602 -296.826686)
		(width 0.14478)
		(layer "In6.Cu")
		(net "M_K_CPU1_SB_DQ<14>")
	)
	(segment
		(start 185.805572 -298.060364)
		(end 188.937646 -298.060364)
		(width 0.14478)
		(layer "In6.Cu")
		(net "M_K_CPU1_SB_DQ<14>")
	)
	(segment
		(start 191.869822 -297.0657)
		(end 191.869822 -296.971466)
		(width 0.14478)
		(layer "In6.Cu")
		(net "M_K_CPU1_SB_DQ<14>")
	)
	(segment
		(start 177.432462 -297.21048)
		(end 178.2826 -298.060618)
		(width 0.14478)
		(layer "In6.Cu")
		(net "M_K_CPU1_SB_DQ<14>")
	)
	(segment
		(start 178.2826 -298.060618)
		(end 181.238144 -298.060618)
		(width 0.14478)
		(layer "In6.Cu")
		(net "M_K_CPU1_SB_DQ<14>")
	)
	(segment
		(start 192.421256 -297.449494)
		(end 192.566036 -297.594274)
		(width 0.14478)
		(layer "In6.Cu")
		(net "M_K_CPU1_SB_DQ<14>")
	)
	(segment
		(start 159.382968 -293.776146)
		(end 159.587692 -293.7764)
		(width 0.14478)
		(layer "In6.Cu")
		(net "M_K_CPU1_SB_DQ<14>")
	)
	(segment
		(start 174.544228 -297.21048)
		(end 177.432462 -297.21048)
		(width 0.14478)
		(layer "In6.Cu")
		(net "M_K_CPU1_SB_DQ<14>")
	)
	(segment
		(start 171.032678 -298.060618)
		(end 173.69409 -298.060618)
		(width 0.14478)
		(layer "In6.Cu")
		(net "M_K_CPU1_SB_DQ<14>")
	)
	(segment
		(start 145.444718 -282.756356)
		(end 146.501358 -282.756356)
		(width 0.0889)
		(layer "In6.Cu")
		(net "M_K_CPU1_SB_DQ<14>")
	)
	(segment
		(start 159.506158 -292.872922)
		(end 159.506158 -293.077646)
		(width 0.14478)
		(layer "In6.Cu")
		(net "M_K_CPU1_SB_DQ<14>")
	)
	(segment
		(start 144.213326 -282.66898)
		(end 144.221708 -282.673806)
		(width 0.0889)
		(layer "In6.Cu")
		(net "M_K_CPU1_SB_DQ<14>")
	)
	(segment
		(start 192.276476 -296.826686)
		(end 192.421256 -296.971466)
		(width 0.14478)
		(layer "In6.Cu")
		(net "M_K_CPU1_SB_DQ<14>")
	)
	(segment
		(start 193.524124 -296.971466)
		(end 193.524124 -297.0657)
		(width 0.14478)
		(layer "In6.Cu")
		(net "M_K_CPU1_SB_DQ<14>")
	)
	(segment
		(start 146.893026 -283.148024)
		(end 147.813776 -283.148024)
		(width 0.0889)
		(layer "In6.Cu")
		(net "M_K_CPU1_SB_DQ<14>")
	)
	(segment
		(start 158.21279 -292.605968)
		(end 158.60268 -292.995858)
		(width 0.14478)
		(layer "In6.Cu")
		(net "M_K_CPU1_SB_DQ<14>")
	)
	(segment
		(start 143.09471 -282.996386)
		(end 142.940786 -282.730956)
		(width 0.0889)
		(layer "In6.Cu")
		(net "M_K_CPU1_SB_DQ<14>")
	)
	(segment
		(start 159.506158 -293.077646)
		(end 159.197548 -293.386256)
		(width 0.14478)
		(layer "In6.Cu")
		(net "M_K_CPU1_SB_DQ<14>")
	)
	(segment
		(start 166.974266 -297.21048)
		(end 170.18254 -297.21048)
		(width 0.14478)
		(layer "In6.Cu")
		(net "M_K_CPU1_SB_DQ<14>")
	)
	(segment
		(start 188.937646 -298.060364)
		(end 189.78753 -297.21048)
		(width 0.14478)
		(layer "In6.Cu")
		(net "M_K_CPU1_SB_DQ<14>")
	)
	(segment
		(start 193.11747 -296.826686)
		(end 193.379344 -296.826686)
		(width 0.14478)
		(layer "In6.Cu")
		(net "M_K_CPU1_SB_DQ<14>")
	)
	(segment
		(start 159.896302 -293.46779)
		(end 160.101026 -293.46779)
		(width 0.14478)
		(layer "In6.Cu")
		(net "M_K_CPU1_SB_DQ<14>")
	)
	(segment
		(start 194.17919 -297.21048)
		(end 194.604132 -297.635422)
		(width 0.14478)
		(layer "In6.Cu")
		(net "M_K_CPU1_SB_DQ<14>")
	)
	(segment
		(start 192.82791 -297.594274)
		(end 192.97269 -297.449494)
		(width 0.14478)
		(layer "In6.Cu")
		(net "M_K_CPU1_SB_DQ<14>")
	)
	(segment
		(start 192.97269 -297.449494)
		(end 192.97269 -296.971466)
		(width 0.14478)
		(layer "In6.Cu")
		(net "M_K_CPU1_SB_DQ<14>")
	)
	(segment
		(start 159.587692 -293.7764)
		(end 159.896302 -293.46779)
		(width 0.14478)
		(layer "In6.Cu")
		(net "M_K_CPU1_SB_DQ<14>")
	)
	(segment
		(start 159.977836 -294.166544)
		(end 159.977836 -294.371014)
		(width 0.14478)
		(layer "In6.Cu")
		(net "M_K_CPU1_SB_DQ<14>")
	)
	(arc
		(start 144.795748 -282.66898)
		(mid 144.979256 -282.623486)
		(end 145.161508 -282.673806)
		(width 0.0889)
		(layer "In6.Cu")
		(net "M_K_CPU1_SB_DQ<14>")
	)
	(arc
		(start 142.963138 -282.647644)
		(mid 143.125327 -282.624909)
		(end 143.281654 -282.673806)
		(width 0.0889)
		(layer "In6.Cu")
		(net "M_K_CPU1_SB_DQ<14>")
	)
	(arc
		(start 145.161508 -282.673806)
		(mid 145.298092 -282.732302)
		(end 145.444718 -282.756356)
		(width 0.0889)
		(layer "In6.Cu")
		(net "M_K_CPU1_SB_DQ<14>")
	)
	(arc
		(start 143.847566 -282.673806)
		(mid 144.029817 -282.623456)
		(end 144.213326 -282.66898)
		(width 0.0889)
		(layer "In6.Cu")
		(net "M_K_CPU1_SB_DQ<14>")
	)
	(arc
		(start 143.281654 -282.673806)
		(mid 143.56461 -282.749983)
		(end 143.847566 -282.673806)
		(width 0.0889)
		(layer "In6.Cu")
		(net "M_K_CPU1_SB_DQ<14>")
	)
	(arc
		(start 144.232122 -282.679902)
		(mid 144.510554 -282.75)
		(end 144.787366 -282.673806)
		(width 0.0889)
		(layer "In6.Cu")
		(net "M_K_CPU1_SB_DQ<14>")
	)
	(segment
		(start 140.748004 -282.730448)
		(end 141.214856 -282.996386)
		(width 0.10668)
		(layer "F.Cu")
		(net "M_K_CPU1_SB_DQ<13>")
	)
	(segment
		(start 144.221454 -283.318966)
		(end 144.231868 -283.31287)
		(width 0.0889)
		(layer "In6.Cu")
		(net "M_K_CPU1_SB_DQ<13>")
	)
	(segment
		(start 157.715966 -292.752526)
		(end 163.873942 -298.910502)
		(width 0.14478)
		(layer "In6.Cu")
		(net "M_K_CPU1_SB_DQ<13>")
	)
	(segment
		(start 180.74894 -298.910502)
		(end 182.800752 -298.060618)
		(width 0.14478)
		(layer "In6.Cu")
		(net "M_K_CPU1_SB_DQ<13>")
	)
	(segment
		(start 188.354208 -298.910248)
		(end 190.40602 -298.060364)
		(width 0.14478)
		(layer "In6.Cu")
		(net "M_K_CPU1_SB_DQ<13>")
	)
	(segment
		(start 149.422358 -283.602684)
		(end 157.715966 -291.896292)
		(width 0.14478)
		(layer "In6.Cu")
		(net "M_K_CPU1_SB_DQ<13>")
	)
	(segment
		(start 141.967712 -283.318966)
		(end 141.976094 -283.323792)
		(width 0.0889)
		(layer "In6.Cu")
		(net "M_K_CPU1_SB_DQ<13>")
	)
	(segment
		(start 145.444718 -283.242766)
		(end 146.599148 -283.242766)
		(width 0.0889)
		(layer "In6.Cu")
		(net "M_K_CPU1_SB_DQ<13>")
	)
	(segment
		(start 141.36878 -283.261816)
		(end 141.464792 -283.287216)
		(width 0.0889)
		(layer "In6.Cu")
		(net "M_K_CPU1_SB_DQ<13>")
	)
	(segment
		(start 169.474388 -298.060618)
		(end 171.5262 -298.910502)
		(width 0.14478)
		(layer "In6.Cu")
		(net "M_K_CPU1_SB_DQ<13>")
	)
	(segment
		(start 171.5262 -298.910502)
		(end 173.063662 -298.910502)
		(width 0.14478)
		(layer "In6.Cu")
		(net "M_K_CPU1_SB_DQ<13>")
	)
	(segment
		(start 190.40602 -298.060364)
		(end 198.279258 -298.060364)
		(width 0.14478)
		(layer "In6.Cu")
		(net "M_K_CPU1_SB_DQ<13>")
	)
	(segment
		(start 176.936146 -298.060618)
		(end 178.987958 -298.910502)
		(width 0.14478)
		(layer "In6.Cu")
		(net "M_K_CPU1_SB_DQ<13>")
	)
	(segment
		(start 198.279258 -298.060364)
		(end 198.7042 -298.485306)
		(width 0.14478)
		(layer "In6.Cu")
		(net "M_K_CPU1_SB_DQ<13>")
	)
	(segment
		(start 182.800752 -298.060618)
		(end 184.576974 -298.060618)
		(width 0.14478)
		(layer "In6.Cu")
		(net "M_K_CPU1_SB_DQ<13>")
	)
	(segment
		(start 146.763486 -283.407104)
		(end 147.378166 -283.407104)
		(width 0.0889)
		(layer "In6.Cu")
		(net "M_K_CPU1_SB_DQ<13>")
	)
	(segment
		(start 157.715966 -291.896292)
		(end 157.715966 -292.752526)
		(width 0.14478)
		(layer "In6.Cu")
		(net "M_K_CPU1_SB_DQ<13>")
	)
	(segment
		(start 186.628278 -298.910248)
		(end 188.354208 -298.910248)
		(width 0.14478)
		(layer "In6.Cu")
		(net "M_K_CPU1_SB_DQ<13>")
	)
	(segment
		(start 178.987958 -298.910502)
		(end 180.74894 -298.910502)
		(width 0.14478)
		(layer "In6.Cu")
		(net "M_K_CPU1_SB_DQ<13>")
	)
	(segment
		(start 173.063662 -298.910502)
		(end 175.115474 -298.060618)
		(width 0.14478)
		(layer "In6.Cu")
		(net "M_K_CPU1_SB_DQ<13>")
	)
	(segment
		(start 163.873942 -298.910502)
		(end 165.269672 -298.910502)
		(width 0.14478)
		(layer "In6.Cu")
		(net "M_K_CPU1_SB_DQ<13>")
	)
	(segment
		(start 141.214856 -282.996386)
		(end 141.36878 -283.261816)
		(width 0.0889)
		(layer "In6.Cu")
		(net "M_K_CPU1_SB_DQ<13>")
	)
	(segment
		(start 146.599148 -283.242766)
		(end 146.763486 -283.407104)
		(width 0.0889)
		(layer "In6.Cu")
		(net "M_K_CPU1_SB_DQ<13>")
	)
	(segment
		(start 167.321484 -298.060618)
		(end 169.474388 -298.060618)
		(width 0.14478)
		(layer "In6.Cu")
		(net "M_K_CPU1_SB_DQ<13>")
	)
	(segment
		(start 165.269672 -298.910502)
		(end 167.321484 -298.060618)
		(width 0.14478)
		(layer "In6.Cu")
		(net "M_K_CPU1_SB_DQ<13>")
	)
	(segment
		(start 147.573746 -283.602684)
		(end 147.876768 -283.602684)
		(width 0.0889)
		(layer "In6.Cu")
		(net "M_K_CPU1_SB_DQ<13>")
	)
	(segment
		(start 175.115474 -298.060618)
		(end 176.936146 -298.060618)
		(width 0.14478)
		(layer "In6.Cu")
		(net "M_K_CPU1_SB_DQ<13>")
	)
	(segment
		(start 147.378166 -283.407104)
		(end 147.573746 -283.602684)
		(width 0.0889)
		(layer "In6.Cu")
		(net "M_K_CPU1_SB_DQ<13>")
	)
	(segment
		(start 147.876768 -283.602684)
		(end 149.422358 -283.602684)
		(width 0.14478)
		(layer "In6.Cu")
		(net "M_K_CPU1_SB_DQ<13>")
	)
	(segment
		(start 144.787112 -283.318966)
		(end 144.798796 -283.325824)
		(width 0.0889)
		(layer "In6.Cu")
		(net "M_K_CPU1_SB_DQ<13>")
	)
	(segment
		(start 184.576974 -298.060618)
		(end 186.628278 -298.910248)
		(width 0.14478)
		(layer "In6.Cu")
		(net "M_K_CPU1_SB_DQ<13>")
	)
	(segment
		(start 144.20977 -283.325824)
		(end 144.221454 -283.318966)
		(width 0.0889)
		(layer "In6.Cu")
		(net "M_K_CPU1_SB_DQ<13>")
	)
	(arc
		(start 141.464792 -283.287216)
		(mid 141.72 -283.243739)
		(end 141.967712 -283.318966)
		(width 0.0889)
		(layer "In6.Cu")
		(net "M_K_CPU1_SB_DQ<13>")
	)
	(arc
		(start 145.161508 -283.318966)
		(mid 145.298067 -283.262108)
		(end 145.444718 -283.242766)
		(width 0.0889)
		(layer "In6.Cu")
		(net "M_K_CPU1_SB_DQ<13>")
	)
	(arc
		(start 143.847566 -283.318966)
		(mid 144.027771 -283.369283)
		(end 144.20977 -283.325824)
		(width 0.0889)
		(layer "In6.Cu")
		(net "M_K_CPU1_SB_DQ<13>")
	)
	(arc
		(start 142.907766 -283.318966)
		(mid 143.09471 -283.369221)
		(end 143.281654 -283.318966)
		(width 0.0889)
		(layer "In6.Cu")
		(net "M_K_CPU1_SB_DQ<13>")
	)
	(arc
		(start 141.976094 -283.323792)
		(mid 142.159602 -283.369286)
		(end 142.341854 -283.318966)
		(width 0.0889)
		(layer "In6.Cu")
		(net "M_K_CPU1_SB_DQ<13>")
	)
	(arc
		(start 142.341854 -283.318966)
		(mid 142.62481 -283.242789)
		(end 142.907766 -283.318966)
		(width 0.0889)
		(layer "In6.Cu")
		(net "M_K_CPU1_SB_DQ<13>")
	)
	(arc
		(start 144.231868 -283.31287)
		(mid 144.5103 -283.242772)
		(end 144.787112 -283.318966)
		(width 0.0889)
		(layer "In6.Cu")
		(net "M_K_CPU1_SB_DQ<13>")
	)
	(arc
		(start 144.798796 -283.325824)
		(mid 144.981051 -283.369477)
		(end 145.161508 -283.318966)
		(width 0.0889)
		(layer "In6.Cu")
		(net "M_K_CPU1_SB_DQ<13>")
	)
	(arc
		(start 143.281654 -283.318966)
		(mid 143.56461 -283.242789)
		(end 143.847566 -283.318966)
		(width 0.0889)
		(layer "In6.Cu")
		(net "M_K_CPU1_SB_DQ<13>")
	)
	(segment
		(start 142.157958 -281.920442)
		(end 142.62481 -282.18638)
		(width 0.10668)
		(layer "F.Cu")
		(net "M_K_CPU1_SB_DQ<12>")
	)
	(segment
		(start 178.26482 -297.219878)
		(end 181.32171 -297.219878)
		(width 0.14478)
		(layer "In6.Cu")
		(net "M_K_CPU1_SB_DQ<12>")
	)
	(segment
		(start 197.6247 -296.993564)
		(end 197.787768 -296.830496)
		(width 0.14478)
		(layer "In6.Cu")
		(net "M_K_CPU1_SB_DQ<12>")
	)
	(segment
		(start 170.976798 -297.219878)
		(end 173.777656 -297.219878)
		(width 0.14478)
		(layer "In6.Cu")
		(net "M_K_CPU1_SB_DQ<12>")
	)
	(segment
		(start 163.81349 -297.492166)
		(end 165.961314 -297.492166)
		(width 0.14478)
		(layer "In6.Cu")
		(net "M_K_CPU1_SB_DQ<12>")
	)
	(segment
		(start 144.691354 -282.50896)
		(end 144.701768 -282.502864)
		(width 0.0889)
		(layer "In6.Cu")
		(net "M_K_CPU1_SB_DQ<12>")
	)
	(segment
		(start 182.171594 -296.369994)
		(end 184.98947 -296.369994)
		(width 0.14478)
		(layer "In6.Cu")
		(net "M_K_CPU1_SB_DQ<12>")
	)
	(segment
		(start 197.787768 -296.52341)
		(end 197.950836 -296.360342)
		(width 0.14478)
		(layer "In6.Cu")
		(net "M_K_CPU1_SB_DQ<12>")
	)
	(segment
		(start 147.274534 -282.350464)
		(end 147.617434 -282.693364)
		(width 0.0889)
		(layer "In6.Cu")
		(net "M_K_CPU1_SB_DQ<12>")
	)
	(segment
		(start 185.839354 -297.219878)
		(end 188.782452 -297.219878)
		(width 0.14478)
		(layer "In6.Cu")
		(net "M_K_CPU1_SB_DQ<12>")
	)
	(segment
		(start 144.307052 -282.502864)
		(end 144.317466 -282.50896)
		(width 0.0889)
		(layer "In6.Cu")
		(net "M_K_CPU1_SB_DQ<12>")
	)
	(segment
		(start 142.62481 -282.18638)
		(end 142.778734 -282.45181)
		(width 0.0889)
		(layer "In6.Cu")
		(net "M_K_CPU1_SB_DQ<12>")
	)
	(segment
		(start 173.777656 -297.219878)
		(end 174.62754 -296.369994)
		(width 0.14478)
		(layer "In6.Cu")
		(net "M_K_CPU1_SB_DQ<12>")
	)
	(segment
		(start 197.394322 -296.993564)
		(end 197.6247 -296.993564)
		(width 0.14478)
		(layer "In6.Cu")
		(net "M_K_CPU1_SB_DQ<12>")
	)
	(segment
		(start 177.414936 -296.369994)
		(end 178.26482 -297.219878)
		(width 0.14478)
		(layer "In6.Cu")
		(net "M_K_CPU1_SB_DQ<12>")
	)
	(segment
		(start 197.950836 -296.360342)
		(end 198.279258 -296.360342)
		(width 0.14478)
		(layer "In6.Cu")
		(net "M_K_CPU1_SB_DQ<12>")
	)
	(segment
		(start 170.494706 -296.737786)
		(end 170.976798 -297.219878)
		(width 0.14478)
		(layer "In6.Cu")
		(net "M_K_CPU1_SB_DQ<12>")
	)
	(segment
		(start 197.077584 -296.36974)
		(end 197.231254 -296.52341)
		(width 0.14478)
		(layer "In6.Cu")
		(net "M_K_CPU1_SB_DQ<12>")
	)
	(segment
		(start 165.961314 -297.492166)
		(end 166.715694 -296.737786)
		(width 0.14478)
		(layer "In6.Cu")
		(net "M_K_CPU1_SB_DQ<12>")
	)
	(segment
		(start 188.782452 -297.219878)
		(end 189.63259 -296.36974)
		(width 0.14478)
		(layer "In6.Cu")
		(net "M_K_CPU1_SB_DQ<12>")
	)
	(segment
		(start 160.86709 -293.531544)
		(end 160.86709 -294.545766)
		(width 0.14478)
		(layer "In6.Cu")
		(net "M_K_CPU1_SB_DQ<12>")
	)
	(segment
		(start 166.715694 -296.737786)
		(end 170.494706 -296.737786)
		(width 0.14478)
		(layer "In6.Cu")
		(net "M_K_CPU1_SB_DQ<12>")
	)
	(segment
		(start 181.32171 -297.219878)
		(end 182.171594 -296.369994)
		(width 0.14478)
		(layer "In6.Cu")
		(net "M_K_CPU1_SB_DQ<12>")
	)
	(segment
		(start 147.808188 -282.693364)
		(end 150.02891 -282.693364)
		(width 0.14478)
		(layer "In6.Cu")
		(net "M_K_CPU1_SB_DQ<12>")
	)
	(segment
		(start 146.026124 -282.350464)
		(end 147.274534 -282.350464)
		(width 0.0889)
		(layer "In6.Cu")
		(net "M_K_CPU1_SB_DQ<12>")
	)
	(segment
		(start 147.617434 -282.693364)
		(end 147.808188 -282.693364)
		(width 0.0889)
		(layer "In6.Cu")
		(net "M_K_CPU1_SB_DQ<12>")
	)
	(segment
		(start 184.98947 -296.369994)
		(end 185.839354 -297.219878)
		(width 0.14478)
		(layer "In6.Cu")
		(net "M_K_CPU1_SB_DQ<12>")
	)
	(segment
		(start 189.63259 -296.36974)
		(end 197.077584 -296.36974)
		(width 0.14478)
		(layer "In6.Cu")
		(net "M_K_CPU1_SB_DQ<12>")
	)
	(segment
		(start 142.778734 -282.45181)
		(end 142.874746 -282.47721)
		(width 0.0889)
		(layer "In6.Cu")
		(net "M_K_CPU1_SB_DQ<12>")
	)
	(segment
		(start 160.86709 -294.545766)
		(end 163.81349 -297.492166)
		(width 0.14478)
		(layer "In6.Cu")
		(net "M_K_CPU1_SB_DQ<12>")
	)
	(segment
		(start 197.787768 -296.830496)
		(end 197.787768 -296.52341)
		(width 0.14478)
		(layer "In6.Cu")
		(net "M_K_CPU1_SB_DQ<12>")
	)
	(segment
		(start 150.02891 -282.693364)
		(end 160.86709 -293.531544)
		(width 0.14478)
		(layer "In6.Cu")
		(net "M_K_CPU1_SB_DQ<12>")
	)
	(segment
		(start 174.62754 -296.369994)
		(end 177.414936 -296.369994)
		(width 0.14478)
		(layer "In6.Cu")
		(net "M_K_CPU1_SB_DQ<12>")
	)
	(segment
		(start 197.231254 -296.52341)
		(end 197.231254 -296.830496)
		(width 0.14478)
		(layer "In6.Cu")
		(net "M_K_CPU1_SB_DQ<12>")
	)
	(segment
		(start 198.279258 -296.360342)
		(end 198.7042 -296.785284)
		(width 0.14478)
		(layer "In6.Cu")
		(net "M_K_CPU1_SB_DQ<12>")
	)
	(segment
		(start 197.231254 -296.830496)
		(end 197.394322 -296.993564)
		(width 0.14478)
		(layer "In6.Cu")
		(net "M_K_CPU1_SB_DQ<12>")
	)
	(segment
		(start 143.377666 -282.50896)
		(end 143.386048 -282.513786)
		(width 0.0889)
		(layer "In6.Cu")
		(net "M_K_CPU1_SB_DQ<12>")
	)
	(arc
		(start 144.701768 -282.502864)
		(mid 144.980454 -282.432644)
		(end 145.25752 -282.50896)
		(width 0.0889)
		(layer "In6.Cu")
		(net "M_K_CPU1_SB_DQ<12>")
	)
	(arc
		(start 145.25752 -282.50896)
		(mid 145.347849 -282.544844)
		(end 145.444718 -282.552902)
		(width 0.0889)
		(layer "In6.Cu")
		(net "M_K_CPU1_SB_DQ<12>")
	)
	(arc
		(start 145.444718 -282.552902)
		(mid 145.491454 -282.551371)
		(end 145.53819 -282.552902)
		(width 0.0889)
		(layer "In6.Cu")
		(net "M_K_CPU1_SB_DQ<12>")
	)
	(arc
		(start 144.317466 -282.50896)
		(mid 144.50441 -282.559215)
		(end 144.691354 -282.50896)
		(width 0.0889)
		(layer "In6.Cu")
		(net "M_K_CPU1_SB_DQ<12>")
	)
	(arc
		(start 142.874746 -282.47721)
		(mid 143.129954 -282.433733)
		(end 143.377666 -282.50896)
		(width 0.0889)
		(layer "In6.Cu")
		(net "M_K_CPU1_SB_DQ<12>")
	)
	(arc
		(start 143.386048 -282.513786)
		(mid 143.569556 -282.55928)
		(end 143.751808 -282.50896)
		(width 0.0889)
		(layer "In6.Cu")
		(net "M_K_CPU1_SB_DQ<12>")
	)
	(arc
		(start 143.751808 -282.50896)
		(mid 144.028621 -282.432817)
		(end 144.307052 -282.502864)
		(width 0.0889)
		(layer "In6.Cu")
		(net "M_K_CPU1_SB_DQ<12>")
	)
	(arc
		(start 145.71472 -282.47975)
		(mid 145.855361 -282.37881)
		(end 146.026124 -282.350464)
		(width 0.0889)
		(layer "In6.Cu")
		(net "M_K_CPU1_SB_DQ<12>")
	)
	(arc
		(start 145.53819 -282.552902)
		(mid 145.635006 -282.536946)
		(end 145.71472 -282.47975)
		(width 0.0889)
		(layer "In6.Cu")
		(net "M_K_CPU1_SB_DQ<12>")
	)
	(segment
		(start 141.217904 -280.30043)
		(end 141.684756 -280.566368)
		(width 0.10668)
		(layer "F.Cu")
		(net "M_K_CPU1_SB_DQ<11>")
	)
	(segment
		(start 144.307052 -280.249884)
		(end 144.317466 -280.243788)
		(width 0.0889)
		(layer "In6.Cu")
		(net "M_K_CPU1_SB_DQ<11>")
	)
	(segment
		(start 167.99941 -293.092124)
		(end 167.99941 -293.092378)
		(width 0.14478)
		(layer "In6.Cu")
		(net "M_K_CPU1_SB_DQ<11>")
	)
	(segment
		(start 180.37302 -293.513764)
		(end 180.632862 -293.513764)
		(width 0.14478)
		(layer "In6.Cu")
		(net "M_K_CPU1_SB_DQ<11>")
	)
	(segment
		(start 141.684756 -280.566368)
		(end 141.530832 -280.300938)
		(width 0.0889)
		(layer "In6.Cu")
		(net "M_K_CPU1_SB_DQ<11>")
	)
	(segment
		(start 171.02328 -293.801038)
		(end 172.570902 -293.801038)
		(width 0.14478)
		(layer "In6.Cu")
		(net "M_K_CPU1_SB_DQ<11>")
	)
	(segment
		(start 193.453512 -292.722046)
		(end 193.598292 -292.577266)
		(width 0.14478)
		(layer "In6.Cu")
		(net "M_K_CPU1_SB_DQ<11>")
	)
	(segment
		(start 173.118018 -293.539164)
		(end 173.191678 -293.612824)
		(width 0.14478)
		(layer "In6.Cu")
		(net "M_K_CPU1_SB_DQ<11>")
	)
	(segment
		(start 183.143144 -292.9509)
		(end 184.173368 -292.9509)
		(width 0.14478)
		(layer "In6.Cu")
		(net "M_K_CPU1_SB_DQ<11>")
	)
	(segment
		(start 177.050954 -292.675564)
		(end 177.246534 -292.871144)
		(width 0.14478)
		(layer "In6.Cu")
		(net "M_K_CPU1_SB_DQ<11>")
	)
	(segment
		(start 174.728886 -292.960298)
		(end 175.03902 -292.650164)
		(width 0.14478)
		(layer "In6.Cu")
		(net "M_K_CPU1_SB_DQ<11>")
	)
	(segment
		(start 193.796158 -292.577266)
		(end 194.604132 -293.38524)
		(width 0.14478)
		(layer "In6.Cu")
		(net "M_K_CPU1_SB_DQ<11>")
	)
	(segment
		(start 168.131236 -293.224204)
		(end 168.424098 -293.224204)
		(width 0.14478)
		(layer "In6.Cu")
		(net "M_K_CPU1_SB_DQ<11>")
	)
	(segment
		(start 166.143178 -292.960298)
		(end 166.761922 -292.960298)
		(width 0.14478)
		(layer "In6.Cu")
		(net "M_K_CPU1_SB_DQ<11>")
	)
	(segment
		(start 168.424098 -293.224204)
		(end 168.555924 -293.092378)
		(width 0.14478)
		(layer "In6.Cu")
		(net "M_K_CPU1_SB_DQ<11>")
	)
	(segment
		(start 177.246534 -292.871144)
		(end 177.63744 -292.871144)
		(width 0.14478)
		(layer "In6.Cu")
		(net "M_K_CPU1_SB_DQ<11>")
	)
	(segment
		(start 176.503838 -292.9509)
		(end 176.779174 -292.675564)
		(width 0.14478)
		(layer "In6.Cu")
		(net "M_K_CPU1_SB_DQ<11>")
	)
	(segment
		(start 167.60317 -292.960298)
		(end 167.867584 -292.960298)
		(width 0.14478)
		(layer "In6.Cu")
		(net "M_K_CPU1_SB_DQ<11>")
	)
	(segment
		(start 184.448704 -292.675564)
		(end 184.720484 -292.675564)
		(width 0.14478)
		(layer "In6.Cu")
		(net "M_K_CPU1_SB_DQ<11>")
	)
	(segment
		(start 168.68775 -292.696392)
		(end 168.980612 -292.696392)
		(width 0.14478)
		(layer "In6.Cu")
		(net "M_K_CPU1_SB_DQ<11>")
	)
	(segment
		(start 150.84552 -280.200354)
		(end 164.455602 -293.810436)
		(width 0.14478)
		(layer "In6.Cu")
		(net "M_K_CPU1_SB_DQ<11>")
	)
	(segment
		(start 144.6911 -280.243788)
		(end 144.701514 -280.249884)
		(width 0.0889)
		(layer "In6.Cu")
		(net "M_K_CPU1_SB_DQ<11>")
	)
	(segment
		(start 173.191678 -293.612824)
		(end 173.865286 -293.612824)
		(width 0.14478)
		(layer "In6.Cu")
		(net "M_K_CPU1_SB_DQ<11>")
	)
	(segment
		(start 165.29304 -293.810436)
		(end 166.143178 -292.960298)
		(width 0.14478)
		(layer "In6.Cu")
		(net "M_K_CPU1_SB_DQ<11>")
	)
	(segment
		(start 190.139828 -292.650164)
		(end 190.440564 -292.9509)
		(width 0.14478)
		(layer "In6.Cu")
		(net "M_K_CPU1_SB_DQ<11>")
	)
	(segment
		(start 169.112438 -292.828218)
		(end 169.112438 -293.092378)
		(width 0.14478)
		(layer "In6.Cu")
		(net "M_K_CPU1_SB_DQ<11>")
	)
	(segment
		(start 193.308732 -293.306246)
		(end 193.453512 -293.161466)
		(width 0.14478)
		(layer "In6.Cu")
		(net "M_K_CPU1_SB_DQ<11>")
	)
	(segment
		(start 188.35878 -293.800784)
		(end 189.199266 -292.960298)
		(width 0.14478)
		(layer "In6.Cu")
		(net "M_K_CPU1_SB_DQ<11>")
	)
	(segment
		(start 147.819618 -280.200354)
		(end 150.84552 -280.200354)
		(width 0.14478)
		(layer "In6.Cu")
		(net "M_K_CPU1_SB_DQ<11>")
	)
	(segment
		(start 184.885584 -292.840664)
		(end 185.151014 -292.840664)
		(width 0.14478)
		(layer "In6.Cu")
		(net "M_K_CPU1_SB_DQ<11>")
	)
	(segment
		(start 172.832776 -293.539164)
		(end 173.118018 -293.539164)
		(width 0.14478)
		(layer "In6.Cu")
		(net "M_K_CPU1_SB_DQ<11>")
	)
	(segment
		(start 172.570902 -293.801038)
		(end 172.832776 -293.539164)
		(width 0.14478)
		(layer "In6.Cu")
		(net "M_K_CPU1_SB_DQ<11>")
	)
	(segment
		(start 174.517812 -292.960298)
		(end 174.728886 -292.960298)
		(width 0.14478)
		(layer "In6.Cu")
		(net "M_K_CPU1_SB_DQ<11>")
	)
	(segment
		(start 177.63744 -292.871144)
		(end 178.567334 -293.801038)
		(width 0.14478)
		(layer "In6.Cu")
		(net "M_K_CPU1_SB_DQ<11>")
	)
	(segment
		(start 145.257266 -280.243788)
		(end 145.319242 -280.20772)
		(width 0.0889)
		(layer "In6.Cu")
		(net "M_K_CPU1_SB_DQ<11>")
	)
	(segment
		(start 169.112438 -293.092378)
		(end 169.244264 -293.224204)
		(width 0.14478)
		(layer "In6.Cu")
		(net "M_K_CPU1_SB_DQ<11>")
	)
	(segment
		(start 191.539876 -292.9509)
		(end 191.91351 -292.577266)
		(width 0.14478)
		(layer "In6.Cu")
		(net "M_K_CPU1_SB_DQ<11>")
	)
	(segment
		(start 180.085746 -293.801038)
		(end 180.37302 -293.513764)
		(width 0.14478)
		(layer "In6.Cu")
		(net "M_K_CPU1_SB_DQ<11>")
	)
	(segment
		(start 193.598292 -292.577266)
		(end 193.796158 -292.577266)
		(width 0.14478)
		(layer "In6.Cu")
		(net "M_K_CPU1_SB_DQ<11>")
	)
	(segment
		(start 168.980612 -292.696392)
		(end 169.112438 -292.828218)
		(width 0.14478)
		(layer "In6.Cu")
		(net "M_K_CPU1_SB_DQ<11>")
	)
	(segment
		(start 180.632862 -293.513764)
		(end 180.757322 -293.638224)
		(width 0.14478)
		(layer "In6.Cu")
		(net "M_K_CPU1_SB_DQ<11>")
	)
	(segment
		(start 166.761922 -292.960298)
		(end 167.046656 -292.675564)
		(width 0.14478)
		(layer "In6.Cu")
		(net "M_K_CPU1_SB_DQ<11>")
	)
	(segment
		(start 167.318436 -292.675564)
		(end 167.60317 -292.960298)
		(width 0.14478)
		(layer "In6.Cu")
		(net "M_K_CPU1_SB_DQ<11>")
	)
	(segment
		(start 168.555924 -293.092378)
		(end 168.555924 -292.828218)
		(width 0.14478)
		(layer "In6.Cu")
		(net "M_K_CPU1_SB_DQ<11>")
	)
	(segment
		(start 181.38648 -293.638224)
		(end 182.064406 -292.960298)
		(width 0.14478)
		(layer "In6.Cu")
		(net "M_K_CPU1_SB_DQ<11>")
	)
	(segment
		(start 144.317466 -280.243788)
		(end 144.325848 -280.238962)
		(width 0.0889)
		(layer "In6.Cu")
		(net "M_K_CPU1_SB_DQ<11>")
	)
	(segment
		(start 167.99941 -293.092378)
		(end 168.131236 -293.224204)
		(width 0.14478)
		(layer "In6.Cu")
		(net "M_K_CPU1_SB_DQ<11>")
	)
	(segment
		(start 192.902078 -292.722046)
		(end 192.902078 -293.161466)
		(width 0.14478)
		(layer "In6.Cu")
		(net "M_K_CPU1_SB_DQ<11>")
	)
	(segment
		(start 175.2854 -292.650164)
		(end 175.586136 -292.9509)
		(width 0.14478)
		(layer "In6.Cu")
		(net "M_K_CPU1_SB_DQ<11>")
	)
	(segment
		(start 193.453512 -293.161466)
		(end 193.453512 -292.722046)
		(width 0.14478)
		(layer "In6.Cu")
		(net "M_K_CPU1_SB_DQ<11>")
	)
	(segment
		(start 169.668952 -293.092124)
		(end 169.800778 -292.960298)
		(width 0.14478)
		(layer "In6.Cu")
		(net "M_K_CPU1_SB_DQ<11>")
	)
	(segment
		(start 164.455602 -293.810436)
		(end 165.29304 -293.810436)
		(width 0.14478)
		(layer "In6.Cu")
		(net "M_K_CPU1_SB_DQ<11>")
	)
	(segment
		(start 193.046858 -293.306246)
		(end 193.308732 -293.306246)
		(width 0.14478)
		(layer "In6.Cu")
		(net "M_K_CPU1_SB_DQ<11>")
	)
	(segment
		(start 182.336694 -292.960298)
		(end 182.596028 -292.700964)
		(width 0.14478)
		(layer "In6.Cu")
		(net "M_K_CPU1_SB_DQ<11>")
	)
	(segment
		(start 143.377666 -280.243788)
		(end 143.386048 -280.238962)
		(width 0.0889)
		(layer "In6.Cu")
		(net "M_K_CPU1_SB_DQ<11>")
	)
	(segment
		(start 184.720484 -292.675564)
		(end 184.885584 -292.840664)
		(width 0.14478)
		(layer "In6.Cu")
		(net "M_K_CPU1_SB_DQ<11>")
	)
	(segment
		(start 141.530832 -280.300938)
		(end 141.553184 -280.217626)
		(width 0.0889)
		(layer "In6.Cu")
		(net "M_K_CPU1_SB_DQ<11>")
	)
	(segment
		(start 169.244264 -293.224204)
		(end 169.537126 -293.224204)
		(width 0.14478)
		(layer "In6.Cu")
		(net "M_K_CPU1_SB_DQ<11>")
	)
	(segment
		(start 169.800778 -292.960298)
		(end 170.18254 -292.960298)
		(width 0.14478)
		(layer "In6.Cu")
		(net "M_K_CPU1_SB_DQ<11>")
	)
	(segment
		(start 173.865286 -293.612824)
		(end 174.517812 -292.960298)
		(width 0.14478)
		(layer "In6.Cu")
		(net "M_K_CPU1_SB_DQ<11>")
	)
	(segment
		(start 192.757298 -292.577266)
		(end 192.902078 -292.722046)
		(width 0.14478)
		(layer "In6.Cu")
		(net "M_K_CPU1_SB_DQ<11>")
	)
	(segment
		(start 169.668952 -293.092378)
		(end 169.668952 -293.092124)
		(width 0.14478)
		(layer "In6.Cu")
		(net "M_K_CPU1_SB_DQ<11>")
	)
	(segment
		(start 167.046656 -292.675564)
		(end 167.318436 -292.675564)
		(width 0.14478)
		(layer "In6.Cu")
		(net "M_K_CPU1_SB_DQ<11>")
	)
	(segment
		(start 185.151014 -292.840664)
		(end 186.111134 -293.800784)
		(width 0.14478)
		(layer "In6.Cu")
		(net "M_K_CPU1_SB_DQ<11>")
	)
	(segment
		(start 170.18254 -292.960298)
		(end 171.02328 -293.801038)
		(width 0.14478)
		(layer "In6.Cu")
		(net "M_K_CPU1_SB_DQ<11>")
	)
	(segment
		(start 182.596028 -292.700964)
		(end 182.893208 -292.700964)
		(width 0.14478)
		(layer "In6.Cu")
		(net "M_K_CPU1_SB_DQ<11>")
	)
	(segment
		(start 186.111134 -293.800784)
		(end 188.35878 -293.800784)
		(width 0.14478)
		(layer "In6.Cu")
		(net "M_K_CPU1_SB_DQ<11>")
	)
	(segment
		(start 189.583314 -292.960298)
		(end 189.893448 -292.650164)
		(width 0.14478)
		(layer "In6.Cu")
		(net "M_K_CPU1_SB_DQ<11>")
	)
	(segment
		(start 191.91351 -292.577266)
		(end 192.757298 -292.577266)
		(width 0.14478)
		(layer "In6.Cu")
		(net "M_K_CPU1_SB_DQ<11>")
	)
	(segment
		(start 182.064406 -292.960298)
		(end 182.336694 -292.960298)
		(width 0.14478)
		(layer "In6.Cu")
		(net "M_K_CPU1_SB_DQ<11>")
	)
	(segment
		(start 142.803372 -280.238962)
		(end 142.811754 -280.243788)
		(width 0.0889)
		(layer "In6.Cu")
		(net "M_K_CPU1_SB_DQ<11>")
	)
	(segment
		(start 145.346674 -280.200354)
		(end 147.819618 -280.200354)
		(width 0.0889)
		(layer "In6.Cu")
		(net "M_K_CPU1_SB_DQ<11>")
	)
	(segment
		(start 167.867584 -292.960298)
		(end 167.99941 -293.092124)
		(width 0.14478)
		(layer "In6.Cu")
		(net "M_K_CPU1_SB_DQ<11>")
	)
	(segment
		(start 184.173368 -292.9509)
		(end 184.448704 -292.675564)
		(width 0.14478)
		(layer "In6.Cu")
		(net "M_K_CPU1_SB_DQ<11>")
	)
	(segment
		(start 189.199266 -292.960298)
		(end 189.583314 -292.960298)
		(width 0.14478)
		(layer "In6.Cu")
		(net "M_K_CPU1_SB_DQ<11>")
	)
	(segment
		(start 192.902078 -293.161466)
		(end 193.046858 -293.306246)
		(width 0.14478)
		(layer "In6.Cu")
		(net "M_K_CPU1_SB_DQ<11>")
	)
	(segment
		(start 190.440564 -292.9509)
		(end 191.539876 -292.9509)
		(width 0.14478)
		(layer "In6.Cu")
		(net "M_K_CPU1_SB_DQ<11>")
	)
	(segment
		(start 178.567334 -293.801038)
		(end 180.085746 -293.801038)
		(width 0.14478)
		(layer "In6.Cu")
		(net "M_K_CPU1_SB_DQ<11>")
	)
	(segment
		(start 176.779174 -292.675564)
		(end 177.050954 -292.675564)
		(width 0.14478)
		(layer "In6.Cu")
		(net "M_K_CPU1_SB_DQ<11>")
	)
	(segment
		(start 182.893208 -292.700964)
		(end 183.143144 -292.9509)
		(width 0.14478)
		(layer "In6.Cu")
		(net "M_K_CPU1_SB_DQ<11>")
	)
	(segment
		(start 169.537126 -293.224204)
		(end 169.668952 -293.092378)
		(width 0.14478)
		(layer "In6.Cu")
		(net "M_K_CPU1_SB_DQ<11>")
	)
	(segment
		(start 189.893448 -292.650164)
		(end 190.139828 -292.650164)
		(width 0.14478)
		(layer "In6.Cu")
		(net "M_K_CPU1_SB_DQ<11>")
	)
	(segment
		(start 180.757322 -293.638224)
		(end 181.38648 -293.638224)
		(width 0.14478)
		(layer "In6.Cu")
		(net "M_K_CPU1_SB_DQ<11>")
	)
	(segment
		(start 175.03902 -292.650164)
		(end 175.2854 -292.650164)
		(width 0.14478)
		(layer "In6.Cu")
		(net "M_K_CPU1_SB_DQ<11>")
	)
	(segment
		(start 168.555924 -292.828218)
		(end 168.68775 -292.696392)
		(width 0.14478)
		(layer "In6.Cu")
		(net "M_K_CPU1_SB_DQ<11>")
	)
	(segment
		(start 175.586136 -292.9509)
		(end 176.503838 -292.9509)
		(width 0.14478)
		(layer "In6.Cu")
		(net "M_K_CPU1_SB_DQ<11>")
	)
	(arc
		(start 141.553184 -280.217626)
		(mid 141.715373 -280.194891)
		(end 141.8717 -280.243788)
		(width 0.0889)
		(layer "In6.Cu")
		(net "M_K_CPU1_SB_DQ<11>")
	)
	(arc
		(start 143.386048 -280.238962)
		(mid 143.569556 -280.193468)
		(end 143.751808 -280.243788)
		(width 0.0889)
		(layer "In6.Cu")
		(net "M_K_CPU1_SB_DQ<11>")
	)
	(arc
		(start 142.811754 -280.243788)
		(mid 143.09471 -280.319965)
		(end 143.377666 -280.243788)
		(width 0.0889)
		(layer "In6.Cu")
		(net "M_K_CPU1_SB_DQ<11>")
	)
	(arc
		(start 142.437612 -280.243788)
		(mid 142.619863 -280.193438)
		(end 142.803372 -280.238962)
		(width 0.0889)
		(layer "In6.Cu")
		(net "M_K_CPU1_SB_DQ<11>")
	)
	(arc
		(start 144.325848 -280.238962)
		(mid 144.509102 -280.193589)
		(end 144.6911 -280.243788)
		(width 0.0889)
		(layer "In6.Cu")
		(net "M_K_CPU1_SB_DQ<11>")
	)
	(arc
		(start 144.701514 -280.249884)
		(mid 144.9802 -280.320104)
		(end 145.257266 -280.243788)
		(width 0.0889)
		(layer "In6.Cu")
		(net "M_K_CPU1_SB_DQ<11>")
	)
	(arc
		(start 143.751808 -280.243788)
		(mid 144.028621 -280.319931)
		(end 144.307052 -280.249884)
		(width 0.0889)
		(layer "In6.Cu")
		(net "M_K_CPU1_SB_DQ<11>")
	)
	(arc
		(start 145.319242 -280.20772)
		(mid 145.332465 -280.202187)
		(end 145.346674 -280.200354)
		(width 0.0889)
		(layer "In6.Cu")
		(net "M_K_CPU1_SB_DQ<11>")
	)
	(arc
		(start 141.8717 -280.243788)
		(mid 142.154656 -280.319965)
		(end 142.437612 -280.243788)
		(width 0.0889)
		(layer "In6.Cu")
		(net "M_K_CPU1_SB_DQ<11>")
	)
	(segment
		(start 142.627858 -279.490424)
		(end 143.09471 -279.756362)
		(width 0.10668)
		(layer "F.Cu")
		(net "M_K_CPU1_SB_DQ<10>")
	)
	(segment
		(start 155.360624 -283.403802)
		(end 155.553664 -283.596842)
		(width 0.14478)
		(layer "In6.Cu")
		(net "M_K_CPU1_SB_DQ<10>")
	)
	(segment
		(start 156.935424 -284.978602)
		(end 157.128464 -285.171642)
		(width 0.14478)
		(layer "In6.Cu")
		(net "M_K_CPU1_SB_DQ<10>")
	)
	(segment
		(start 158.510224 -286.152082)
		(end 158.510224 -286.553402)
		(width 0.14478)
		(layer "In6.Cu")
		(net "M_K_CPU1_SB_DQ<10>")
	)
	(segment
		(start 158.510224 -286.553402)
		(end 158.703264 -286.746442)
		(width 0.14478)
		(layer "In6.Cu")
		(net "M_K_CPU1_SB_DQ<10>")
	)
	(segment
		(start 161.065464 -289.108642)
		(end 161.466784 -289.108642)
		(width 0.14478)
		(layer "In6.Cu")
		(net "M_K_CPU1_SB_DQ<10>")
	)
	(segment
		(start 162.447224 -290.089082)
		(end 162.447224 -290.490402)
		(width 0.14478)
		(layer "In6.Cu")
		(net "M_K_CPU1_SB_DQ<10>")
	)
	(segment
		(start 193.128392 -291.260276)
		(end 193.440304 -290.948364)
		(width 0.14478)
		(layer "In6.Cu")
		(net "M_K_CPU1_SB_DQ<10>")
	)
	(segment
		(start 152.998424 -281.041602)
		(end 153.191464 -281.234642)
		(width 0.14478)
		(layer "In6.Cu")
		(net "M_K_CPU1_SB_DQ<10>")
	)
	(segment
		(start 155.360624 -283.002482)
		(end 155.360624 -283.403802)
		(width 0.14478)
		(layer "In6.Cu")
		(net "M_K_CPU1_SB_DQ<10>")
	)
	(segment
		(start 192.327276 -290.948364)
		(end 192.571878 -290.948364)
		(width 0.14478)
		(layer "In6.Cu")
		(net "M_K_CPU1_SB_DQ<10>")
	)
	(segment
		(start 153.191464 -281.234642)
		(end 153.592784 -281.234642)
		(width 0.14478)
		(layer "In6.Cu")
		(net "M_K_CPU1_SB_DQ<10>")
	)
	(segment
		(start 144.221708 -279.433782)
		(end 144.232122 -279.439878)
		(width 0.0889)
		(layer "In6.Cu")
		(net "M_K_CPU1_SB_DQ<10>")
	)
	(segment
		(start 166.556436 -291.260276)
		(end 166.851076 -291.260276)
		(width 0.14478)
		(layer "In6.Cu")
		(net "M_K_CPU1_SB_DQ<10>")
	)
	(segment
		(start 143.09471 -279.756362)
		(end 142.940786 -279.490932)
		(width 0.0889)
		(layer "In6.Cu")
		(net "M_K_CPU1_SB_DQ<10>")
	)
	(segment
		(start 193.996818 -291.260276)
		(end 194.17919 -291.260276)
		(width 0.14478)
		(layer "In6.Cu")
		(net "M_K_CPU1_SB_DQ<10>")
	)
	(segment
		(start 167.137588 -290.973764)
		(end 167.40759 -290.973764)
		(width 0.14478)
		(layer "In6.Cu")
		(net "M_K_CPU1_SB_DQ<10>")
	)
	(segment
		(start 152.404064 -280.447242)
		(end 152.805384 -280.447242)
		(width 0.14478)
		(layer "In6.Cu")
		(net "M_K_CPU1_SB_DQ<10>")
	)
	(segment
		(start 146.393154 -278.913844)
		(end 147.286726 -278.913844)
		(width 0.0889)
		(layer "In6.Cu")
		(net "M_K_CPU1_SB_DQ<10>")
	)
	(segment
		(start 178.576732 -292.110414)
		(end 181.238144 -292.110414)
		(width 0.14478)
		(layer "In6.Cu")
		(net "M_K_CPU1_SB_DQ<10>")
	)
	(segment
		(start 155.553664 -283.596842)
		(end 155.954984 -283.596842)
		(width 0.14478)
		(layer "In6.Cu")
		(net "M_K_CPU1_SB_DQ<10>")
	)
	(segment
		(start 190.583312 -291.260276)
		(end 192.015364 -291.260276)
		(width 0.14478)
		(layer "In6.Cu")
		(net "M_K_CPU1_SB_DQ<10>")
	)
	(segment
		(start 189.194948 -291.260276)
		(end 189.740286 -291.260276)
		(width 0.14478)
		(layer "In6.Cu")
		(net "M_K_CPU1_SB_DQ<10>")
	)
	(segment
		(start 157.128464 -285.171642)
		(end 157.529784 -285.171642)
		(width 0.14478)
		(layer "In6.Cu")
		(net "M_K_CPU1_SB_DQ<10>")
	)
	(segment
		(start 159.297624 -286.939482)
		(end 159.297624 -287.340802)
		(width 0.14478)
		(layer "In6.Cu")
		(net "M_K_CPU1_SB_DQ<10>")
	)
	(segment
		(start 184.709562 -291.017706)
		(end 184.709562 -291.115496)
		(width 0.14478)
		(layer "In6.Cu")
		(net "M_K_CPU1_SB_DQ<10>")
	)
	(segment
		(start 157.722824 -285.364682)
		(end 157.722824 -285.766002)
		(width 0.14478)
		(layer "In6.Cu")
		(net "M_K_CPU1_SB_DQ<10>")
	)
	(segment
		(start 144.213326 -279.428956)
		(end 144.221708 -279.433782)
		(width 0.0889)
		(layer "In6.Cu")
		(net "M_K_CPU1_SB_DQ<10>")
	)
	(segment
		(start 155.167584 -282.809442)
		(end 155.360624 -283.002482)
		(width 0.14478)
		(layer "In6.Cu")
		(net "M_K_CPU1_SB_DQ<10>")
	)
	(segment
		(start 155.954984 -283.596842)
		(end 156.148024 -283.789882)
		(width 0.14478)
		(layer "In6.Cu")
		(net "M_K_CPU1_SB_DQ<10>")
	)
	(segment
		(start 157.915864 -285.959042)
		(end 158.317184 -285.959042)
		(width 0.14478)
		(layer "In6.Cu")
		(net "M_K_CPU1_SB_DQ<10>")
	)
	(segment
		(start 158.703264 -286.746442)
		(end 159.104584 -286.746442)
		(width 0.14478)
		(layer "In6.Cu")
		(net "M_K_CPU1_SB_DQ<10>")
	)
	(segment
		(start 160.872424 -288.915602)
		(end 161.065464 -289.108642)
		(width 0.14478)
		(layer "In6.Cu")
		(net "M_K_CPU1_SB_DQ<10>")
	)
	(segment
		(start 165.706298 -292.110414)
		(end 166.556436 -291.260276)
		(width 0.14478)
		(layer "In6.Cu")
		(net "M_K_CPU1_SB_DQ<10>")
	)
	(segment
		(start 192.571878 -290.948364)
		(end 192.88379 -291.260276)
		(width 0.14478)
		(layer "In6.Cu")
		(net "M_K_CPU1_SB_DQ<10>")
	)
	(segment
		(start 181.238144 -292.110414)
		(end 182.088282 -291.260276)
		(width 0.14478)
		(layer "In6.Cu")
		(net "M_K_CPU1_SB_DQ<10>")
	)
	(segment
		(start 184.158128 -291.017706)
		(end 184.302908 -290.872926)
		(width 0.14478)
		(layer "In6.Cu")
		(net "M_K_CPU1_SB_DQ<10>")
	)
	(segment
		(start 169.920158 -291.260276)
		(end 170.18254 -291.260276)
		(width 0.14478)
		(layer "In6.Cu")
		(net "M_K_CPU1_SB_DQ<10>")
	)
	(segment
		(start 159.104584 -286.746442)
		(end 159.297624 -286.939482)
		(width 0.14478)
		(layer "In6.Cu")
		(net "M_K_CPU1_SB_DQ<10>")
	)
	(segment
		(start 152.805384 -280.447242)
		(end 152.998424 -280.640282)
		(width 0.14478)
		(layer "In6.Cu")
		(net "M_K_CPU1_SB_DQ<10>")
	)
	(segment
		(start 194.17919 -291.260276)
		(end 194.604132 -291.685218)
		(width 0.14478)
		(layer "In6.Cu")
		(net "M_K_CPU1_SB_DQ<10>")
	)
	(segment
		(start 142.940786 -279.490932)
		(end 142.963138 -279.40762)
		(width 0.0889)
		(layer "In6.Cu")
		(net "M_K_CPU1_SB_DQ<10>")
	)
	(segment
		(start 161.659824 -289.703002)
		(end 161.852864 -289.896042)
		(width 0.14478)
		(layer "In6.Cu")
		(net "M_K_CPU1_SB_DQ<10>")
	)
	(segment
		(start 184.709562 -291.115496)
		(end 184.854342 -291.260276)
		(width 0.14478)
		(layer "In6.Cu")
		(net "M_K_CPU1_SB_DQ<10>")
	)
	(segment
		(start 193.440304 -290.948364)
		(end 193.684906 -290.948364)
		(width 0.14478)
		(layer "In6.Cu")
		(net "M_K_CPU1_SB_DQ<10>")
	)
	(segment
		(start 157.529784 -285.171642)
		(end 157.722824 -285.364682)
		(width 0.14478)
		(layer "In6.Cu")
		(net "M_K_CPU1_SB_DQ<10>")
	)
	(segment
		(start 153.785824 -281.427682)
		(end 153.785824 -281.829002)
		(width 0.14478)
		(layer "In6.Cu")
		(net "M_K_CPU1_SB_DQ<10>")
	)
	(segment
		(start 154.573224 -282.215082)
		(end 154.573224 -282.616402)
		(width 0.14478)
		(layer "In6.Cu")
		(net "M_K_CPU1_SB_DQ<10>")
	)
	(segment
		(start 147.286726 -278.913844)
		(end 147.438872 -279.06599)
		(width 0.0889)
		(layer "In6.Cu")
		(net "M_K_CPU1_SB_DQ<10>")
	)
	(segment
		(start 145.91284 -279.340564)
		(end 146.301714 -278.95169)
		(width 0.0889)
		(layer "In6.Cu")
		(net "M_K_CPU1_SB_DQ<10>")
	)
	(segment
		(start 160.278064 -288.321242)
		(end 160.679384 -288.321242)
		(width 0.14478)
		(layer "In6.Cu")
		(net "M_K_CPU1_SB_DQ<10>")
	)
	(segment
		(start 156.935424 -284.577282)
		(end 156.935424 -284.978602)
		(width 0.14478)
		(layer "In6.Cu")
		(net "M_K_CPU1_SB_DQ<10>")
	)
	(segment
		(start 154.573224 -282.616402)
		(end 154.766264 -282.809442)
		(width 0.14478)
		(layer "In6.Cu")
		(net "M_K_CPU1_SB_DQ<10>")
	)
	(segment
		(start 152.998424 -280.640282)
		(end 152.998424 -281.041602)
		(width 0.14478)
		(layer "In6.Cu")
		(net "M_K_CPU1_SB_DQ<10>")
	)
	(segment
		(start 156.148024 -283.789882)
		(end 156.148024 -284.191202)
		(width 0.14478)
		(layer "In6.Cu")
		(net "M_K_CPU1_SB_DQ<10>")
	)
	(segment
		(start 156.341064 -284.384242)
		(end 156.742384 -284.384242)
		(width 0.14478)
		(layer "In6.Cu")
		(net "M_K_CPU1_SB_DQ<10>")
	)
	(segment
		(start 184.013348 -291.260276)
		(end 184.158128 -291.115496)
		(width 0.14478)
		(layer "In6.Cu")
		(net "M_K_CPU1_SB_DQ<10>")
	)
	(segment
		(start 159.297624 -287.340802)
		(end 159.490664 -287.533842)
		(width 0.14478)
		(layer "In6.Cu")
		(net "M_K_CPU1_SB_DQ<10>")
	)
	(segment
		(start 153.978864 -282.022042)
		(end 154.380184 -282.022042)
		(width 0.14478)
		(layer "In6.Cu")
		(net "M_K_CPU1_SB_DQ<10>")
	)
	(segment
		(start 167.40759 -290.973764)
		(end 167.694102 -291.260276)
		(width 0.14478)
		(layer "In6.Cu")
		(net "M_K_CPU1_SB_DQ<10>")
	)
	(segment
		(start 192.88379 -291.260276)
		(end 193.128392 -291.260276)
		(width 0.14478)
		(layer "In6.Cu")
		(net "M_K_CPU1_SB_DQ<10>")
	)
	(segment
		(start 168.250616 -290.973764)
		(end 168.520618 -290.973764)
		(width 0.14478)
		(layer "In6.Cu")
		(net "M_K_CPU1_SB_DQ<10>")
	)
	(segment
		(start 185.270648 -291.260276)
		(end 186.120532 -292.11016)
		(width 0.14478)
		(layer "In6.Cu")
		(net "M_K_CPU1_SB_DQ<10>")
	)
	(segment
		(start 164.251132 -292.110414)
		(end 165.706298 -292.110414)
		(width 0.14478)
		(layer "In6.Cu")
		(net "M_K_CPU1_SB_DQ<10>")
	)
	(segment
		(start 160.085024 -287.726882)
		(end 160.085024 -288.128202)
		(width 0.14478)
		(layer "In6.Cu")
		(net "M_K_CPU1_SB_DQ<10>")
	)
	(segment
		(start 189.740286 -291.260276)
		(end 190.026798 -290.973764)
		(width 0.14478)
		(layer "In6.Cu")
		(net "M_K_CPU1_SB_DQ<10>")
	)
	(segment
		(start 160.679384 -288.321242)
		(end 160.872424 -288.514282)
		(width 0.14478)
		(layer "In6.Cu")
		(net "M_K_CPU1_SB_DQ<10>")
	)
	(segment
		(start 162.447224 -290.490402)
		(end 162.640264 -290.683442)
		(width 0.14478)
		(layer "In6.Cu")
		(net "M_K_CPU1_SB_DQ<10>")
	)
	(segment
		(start 161.852864 -289.896042)
		(end 162.254184 -289.896042)
		(width 0.14478)
		(layer "In6.Cu")
		(net "M_K_CPU1_SB_DQ<10>")
	)
	(segment
		(start 168.80713 -291.260276)
		(end 169.077132 -291.260276)
		(width 0.14478)
		(layer "In6.Cu")
		(net "M_K_CPU1_SB_DQ<10>")
	)
	(segment
		(start 184.564782 -290.872926)
		(end 184.709562 -291.017706)
		(width 0.14478)
		(layer "In6.Cu")
		(net "M_K_CPU1_SB_DQ<10>")
	)
	(segment
		(start 154.766264 -282.809442)
		(end 155.167584 -282.809442)
		(width 0.14478)
		(layer "In6.Cu")
		(net "M_K_CPU1_SB_DQ<10>")
	)
	(segment
		(start 153.592784 -281.234642)
		(end 153.785824 -281.427682)
		(width 0.14478)
		(layer "In6.Cu")
		(net "M_K_CPU1_SB_DQ<10>")
	)
	(segment
		(start 167.694102 -291.260276)
		(end 167.964104 -291.260276)
		(width 0.14478)
		(layer "In6.Cu")
		(net "M_K_CPU1_SB_DQ<10>")
	)
	(segment
		(start 193.684906 -290.948364)
		(end 193.996818 -291.260276)
		(width 0.14478)
		(layer "In6.Cu")
		(net "M_K_CPU1_SB_DQ<10>")
	)
	(segment
		(start 188.345064 -292.11016)
		(end 189.194948 -291.260276)
		(width 0.14478)
		(layer "In6.Cu")
		(net "M_K_CPU1_SB_DQ<10>")
	)
	(segment
		(start 184.854342 -291.260276)
		(end 185.270648 -291.260276)
		(width 0.14478)
		(layer "In6.Cu")
		(net "M_K_CPU1_SB_DQ<10>")
	)
	(segment
		(start 173.630082 -292.110414)
		(end 174.48022 -291.260276)
		(width 0.14478)
		(layer "In6.Cu")
		(net "M_K_CPU1_SB_DQ<10>")
	)
	(segment
		(start 190.026798 -290.973764)
		(end 190.2968 -290.973764)
		(width 0.14478)
		(layer "In6.Cu")
		(net "M_K_CPU1_SB_DQ<10>")
	)
	(segment
		(start 169.077132 -291.260276)
		(end 169.363644 -290.973764)
		(width 0.14478)
		(layer "In6.Cu")
		(net "M_K_CPU1_SB_DQ<10>")
	)
	(segment
		(start 162.254184 -289.896042)
		(end 162.447224 -290.089082)
		(width 0.14478)
		(layer "In6.Cu")
		(net "M_K_CPU1_SB_DQ<10>")
	)
	(segment
		(start 161.466784 -289.108642)
		(end 161.659824 -289.301682)
		(width 0.14478)
		(layer "In6.Cu")
		(net "M_K_CPU1_SB_DQ<10>")
	)
	(segment
		(start 186.120532 -292.11016)
		(end 188.345064 -292.11016)
		(width 0.14478)
		(layer "In6.Cu")
		(net "M_K_CPU1_SB_DQ<10>")
	)
	(segment
		(start 190.2968 -290.973764)
		(end 190.583312 -291.260276)
		(width 0.14478)
		(layer "In6.Cu")
		(net "M_K_CPU1_SB_DQ<10>")
	)
	(segment
		(start 152.211024 -279.852882)
		(end 152.211024 -280.254202)
		(width 0.14478)
		(layer "In6.Cu")
		(net "M_K_CPU1_SB_DQ<10>")
	)
	(segment
		(start 147.438872 -279.06599)
		(end 147.931632 -279.06599)
		(width 0.0889)
		(layer "In6.Cu")
		(net "M_K_CPU1_SB_DQ<10>")
	)
	(segment
		(start 171.032678 -292.110414)
		(end 173.630082 -292.110414)
		(width 0.14478)
		(layer "In6.Cu")
		(net "M_K_CPU1_SB_DQ<10>")
	)
	(segment
		(start 192.015364 -291.260276)
		(end 192.327276 -290.948364)
		(width 0.14478)
		(layer "In6.Cu")
		(net "M_K_CPU1_SB_DQ<10>")
	)
	(segment
		(start 162.82416 -290.683442)
		(end 164.251132 -292.110414)
		(width 0.14478)
		(layer "In6.Cu")
		(net "M_K_CPU1_SB_DQ<10>")
	)
	(segment
		(start 168.520618 -290.973764)
		(end 168.80713 -291.260276)
		(width 0.14478)
		(layer "In6.Cu")
		(net "M_K_CPU1_SB_DQ<10>")
	)
	(segment
		(start 154.380184 -282.022042)
		(end 154.573224 -282.215082)
		(width 0.14478)
		(layer "In6.Cu")
		(net "M_K_CPU1_SB_DQ<10>")
	)
	(segment
		(start 147.931632 -279.06599)
		(end 151.424132 -279.06599)
		(width 0.14478)
		(layer "In6.Cu")
		(net "M_K_CPU1_SB_DQ<10>")
	)
	(segment
		(start 159.891984 -287.533842)
		(end 160.085024 -287.726882)
		(width 0.14478)
		(layer "In6.Cu")
		(net "M_K_CPU1_SB_DQ<10>")
	)
	(segment
		(start 182.088282 -291.260276)
		(end 184.013348 -291.260276)
		(width 0.14478)
		(layer "In6.Cu")
		(net "M_K_CPU1_SB_DQ<10>")
	)
	(segment
		(start 160.872424 -288.514282)
		(end 160.872424 -288.915602)
		(width 0.14478)
		(layer "In6.Cu")
		(net "M_K_CPU1_SB_DQ<10>")
	)
	(segment
		(start 156.148024 -284.191202)
		(end 156.341064 -284.384242)
		(width 0.14478)
		(layer "In6.Cu")
		(net "M_K_CPU1_SB_DQ<10>")
	)
	(segment
		(start 153.785824 -281.829002)
		(end 153.978864 -282.022042)
		(width 0.14478)
		(layer "In6.Cu")
		(net "M_K_CPU1_SB_DQ<10>")
	)
	(segment
		(start 156.742384 -284.384242)
		(end 156.935424 -284.577282)
		(width 0.14478)
		(layer "In6.Cu")
		(net "M_K_CPU1_SB_DQ<10>")
	)
	(segment
		(start 151.424132 -279.06599)
		(end 152.211024 -279.852882)
		(width 0.14478)
		(layer "In6.Cu")
		(net "M_K_CPU1_SB_DQ<10>")
	)
	(segment
		(start 169.363644 -290.973764)
		(end 169.633646 -290.973764)
		(width 0.14478)
		(layer "In6.Cu")
		(net "M_K_CPU1_SB_DQ<10>")
	)
	(segment
		(start 174.48022 -291.260276)
		(end 177.726594 -291.260276)
		(width 0.14478)
		(layer "In6.Cu")
		(net "M_K_CPU1_SB_DQ<10>")
	)
	(segment
		(start 184.158128 -291.115496)
		(end 184.158128 -291.017706)
		(width 0.14478)
		(layer "In6.Cu")
		(net "M_K_CPU1_SB_DQ<10>")
	)
	(segment
		(start 162.640264 -290.683442)
		(end 162.82416 -290.683442)
		(width 0.14478)
		(layer "In6.Cu")
		(net "M_K_CPU1_SB_DQ<10>")
	)
	(segment
		(start 170.18254 -291.260276)
		(end 171.032678 -292.110414)
		(width 0.14478)
		(layer "In6.Cu")
		(net "M_K_CPU1_SB_DQ<10>")
	)
	(segment
		(start 159.490664 -287.533842)
		(end 159.891984 -287.533842)
		(width 0.14478)
		(layer "In6.Cu")
		(net "M_K_CPU1_SB_DQ<10>")
	)
	(segment
		(start 152.211024 -280.254202)
		(end 152.404064 -280.447242)
		(width 0.14478)
		(layer "In6.Cu")
		(net "M_K_CPU1_SB_DQ<10>")
	)
	(segment
		(start 157.722824 -285.766002)
		(end 157.915864 -285.959042)
		(width 0.14478)
		(layer "In6.Cu")
		(net "M_K_CPU1_SB_DQ<10>")
	)
	(segment
		(start 184.302908 -290.872926)
		(end 184.564782 -290.872926)
		(width 0.14478)
		(layer "In6.Cu")
		(net "M_K_CPU1_SB_DQ<10>")
	)
	(segment
		(start 160.085024 -288.128202)
		(end 160.278064 -288.321242)
		(width 0.14478)
		(layer "In6.Cu")
		(net "M_K_CPU1_SB_DQ<10>")
	)
	(segment
		(start 161.659824 -289.301682)
		(end 161.659824 -289.703002)
		(width 0.14478)
		(layer "In6.Cu")
		(net "M_K_CPU1_SB_DQ<10>")
	)
	(segment
		(start 177.726594 -291.260276)
		(end 178.576732 -292.110414)
		(width 0.14478)
		(layer "In6.Cu")
		(net "M_K_CPU1_SB_DQ<10>")
	)
	(segment
		(start 158.317184 -285.959042)
		(end 158.510224 -286.152082)
		(width 0.14478)
		(layer "In6.Cu")
		(net "M_K_CPU1_SB_DQ<10>")
	)
	(segment
		(start 144.787366 -279.433782)
		(end 144.795748 -279.428956)
		(width 0.0889)
		(layer "In6.Cu")
		(net "M_K_CPU1_SB_DQ<10>")
	)
	(segment
		(start 167.964104 -291.260276)
		(end 168.250616 -290.973764)
		(width 0.14478)
		(layer "In6.Cu")
		(net "M_K_CPU1_SB_DQ<10>")
	)
	(segment
		(start 169.633646 -290.973764)
		(end 169.920158 -291.260276)
		(width 0.14478)
		(layer "In6.Cu")
		(net "M_K_CPU1_SB_DQ<10>")
	)
	(segment
		(start 166.851076 -291.260276)
		(end 167.137588 -290.973764)
		(width 0.14478)
		(layer "In6.Cu")
		(net "M_K_CPU1_SB_DQ<10>")
	)
	(arc
		(start 146.301714 -278.95169)
		(mid 146.343667 -278.923658)
		(end 146.393154 -278.913844)
		(width 0.0889)
		(layer "In6.Cu")
		(net "M_K_CPU1_SB_DQ<10>")
	)
	(arc
		(start 143.281654 -279.433782)
		(mid 143.56461 -279.509959)
		(end 143.847566 -279.433782)
		(width 0.0889)
		(layer "In6.Cu")
		(net "M_K_CPU1_SB_DQ<10>")
	)
	(arc
		(start 143.847566 -279.433782)
		(mid 144.029817 -279.383432)
		(end 144.213326 -279.428956)
		(width 0.0889)
		(layer "In6.Cu")
		(net "M_K_CPU1_SB_DQ<10>")
	)
	(arc
		(start 142.963138 -279.40762)
		(mid 143.125327 -279.384885)
		(end 143.281654 -279.433782)
		(width 0.0889)
		(layer "In6.Cu")
		(net "M_K_CPU1_SB_DQ<10>")
	)
	(arc
		(start 145.161508 -279.433782)
		(mid 145.552842 -279.513561)
		(end 145.91284 -279.340564)
		(width 0.0889)
		(layer "In6.Cu")
		(net "M_K_CPU1_SB_DQ<10>")
	)
	(arc
		(start 144.232122 -279.439878)
		(mid 144.510554 -279.509976)
		(end 144.787366 -279.433782)
		(width 0.0889)
		(layer "In6.Cu")
		(net "M_K_CPU1_SB_DQ<10>")
	)
	(arc
		(start 144.795748 -279.428956)
		(mid 144.979256 -279.383462)
		(end 145.161508 -279.433782)
		(width 0.0889)
		(layer "In6.Cu")
		(net "M_K_CPU1_SB_DQ<10>")
	)
	(segment
		(start 142.157958 -273.820382)
		(end 142.62481 -274.08632)
		(width 0.10668)
		(layer "F.Cu")
		(net "M_K_CPU1_SB_DQ<0>")
	)
	(segment
		(start 148.037296 -272.939764)
		(end 154.700732 -272.939764)
		(width 0.14478)
		(layer "In6.Cu")
		(net "M_K_CPU1_SB_DQ<0>")
	)
	(segment
		(start 196.49059 -281.060398)
		(end 196.63537 -281.205178)
		(width 0.14478)
		(layer "In6.Cu")
		(net "M_K_CPU1_SB_DQ<0>")
	)
	(segment
		(start 142.778734 -274.35175)
		(end 142.874746 -274.37715)
		(width 0.0889)
		(layer "In6.Cu")
		(net "M_K_CPU1_SB_DQ<0>")
	)
	(segment
		(start 170.56862 -281.060398)
		(end 171.418504 -281.910282)
		(width 0.14478)
		(layer "In6.Cu")
		(net "M_K_CPU1_SB_DQ<0>")
	)
	(segment
		(start 197.186804 -281.685746)
		(end 197.186804 -281.205178)
		(width 0.14478)
		(layer "In6.Cu")
		(net "M_K_CPU1_SB_DQ<0>")
	)
	(segment
		(start 145.619724 -274.415758)
		(end 146.605752 -273.43227)
		(width 0.0889)
		(layer "In6.Cu")
		(net "M_K_CPU1_SB_DQ<0>")
	)
	(segment
		(start 185.205624 -281.060398)
		(end 186.055508 -281.910282)
		(width 0.14478)
		(layer "In6.Cu")
		(net "M_K_CPU1_SB_DQ<0>")
	)
	(segment
		(start 166.243 -281.910282)
		(end 167.092884 -281.060398)
		(width 0.14478)
		(layer "In6.Cu")
		(net "M_K_CPU1_SB_DQ<0>")
	)
	(segment
		(start 144.691354 -274.4089)
		(end 144.701768 -274.402804)
		(width 0.0889)
		(layer "In6.Cu")
		(net "M_K_CPU1_SB_DQ<0>")
	)
	(segment
		(start 146.697192 -273.394424)
		(end 147.17395 -273.394424)
		(width 0.0889)
		(layer "In6.Cu")
		(net "M_K_CPU1_SB_DQ<0>")
	)
	(segment
		(start 178.860958 -281.910282)
		(end 181.331108 -281.910282)
		(width 0.14478)
		(layer "In6.Cu")
		(net "M_K_CPU1_SB_DQ<0>")
	)
	(segment
		(start 196.63537 -281.205178)
		(end 196.63537 -281.685746)
		(width 0.14478)
		(layer "In6.Cu")
		(net "M_K_CPU1_SB_DQ<0>")
	)
	(segment
		(start 181.331108 -281.910282)
		(end 182.180992 -281.060398)
		(width 0.14478)
		(layer "In6.Cu")
		(net "M_K_CPU1_SB_DQ<0>")
	)
	(segment
		(start 167.092884 -281.060398)
		(end 170.56862 -281.060398)
		(width 0.14478)
		(layer "In6.Cu")
		(net "M_K_CPU1_SB_DQ<0>")
	)
	(segment
		(start 163.67125 -281.910282)
		(end 166.243 -281.910282)
		(width 0.14478)
		(layer "In6.Cu")
		(net "M_K_CPU1_SB_DQ<0>")
	)
	(segment
		(start 147.62861 -272.939764)
		(end 148.037296 -272.939764)
		(width 0.0889)
		(layer "In6.Cu")
		(net "M_K_CPU1_SB_DQ<0>")
	)
	(segment
		(start 147.17395 -273.394424)
		(end 147.62861 -272.939764)
		(width 0.0889)
		(layer "In6.Cu")
		(net "M_K_CPU1_SB_DQ<0>")
	)
	(segment
		(start 174.062898 -281.060398)
		(end 178.011074 -281.060398)
		(width 0.14478)
		(layer "In6.Cu")
		(net "M_K_CPU1_SB_DQ<0>")
	)
	(segment
		(start 198.279258 -281.060398)
		(end 198.7042 -281.48534)
		(width 0.14478)
		(layer "In6.Cu")
		(net "M_K_CPU1_SB_DQ<0>")
	)
	(segment
		(start 144.307052 -274.402804)
		(end 144.317466 -274.4089)
		(width 0.0889)
		(layer "In6.Cu")
		(net "M_K_CPU1_SB_DQ<0>")
	)
	(segment
		(start 142.62481 -274.08632)
		(end 142.778734 -274.35175)
		(width 0.0889)
		(layer "In6.Cu")
		(net "M_K_CPU1_SB_DQ<0>")
	)
	(segment
		(start 186.055508 -281.910282)
		(end 188.191648 -281.910282)
		(width 0.14478)
		(layer "In6.Cu")
		(net "M_K_CPU1_SB_DQ<0>")
	)
	(segment
		(start 143.377666 -274.4089)
		(end 143.386048 -274.413726)
		(width 0.0889)
		(layer "In6.Cu")
		(net "M_K_CPU1_SB_DQ<0>")
	)
	(segment
		(start 189.041532 -281.060398)
		(end 196.49059 -281.060398)
		(width 0.14478)
		(layer "In6.Cu")
		(net "M_K_CPU1_SB_DQ<0>")
	)
	(segment
		(start 171.418504 -281.910282)
		(end 173.213014 -281.910282)
		(width 0.14478)
		(layer "In6.Cu")
		(net "M_K_CPU1_SB_DQ<0>")
	)
	(segment
		(start 178.011074 -281.060398)
		(end 178.860958 -281.910282)
		(width 0.14478)
		(layer "In6.Cu")
		(net "M_K_CPU1_SB_DQ<0>")
	)
	(segment
		(start 154.700732 -272.939764)
		(end 163.67125 -281.910282)
		(width 0.14478)
		(layer "In6.Cu")
		(net "M_K_CPU1_SB_DQ<0>")
	)
	(segment
		(start 188.191648 -281.910282)
		(end 189.041532 -281.060398)
		(width 0.14478)
		(layer "In6.Cu")
		(net "M_K_CPU1_SB_DQ<0>")
	)
	(segment
		(start 197.331584 -281.060398)
		(end 198.279258 -281.060398)
		(width 0.14478)
		(layer "In6.Cu")
		(net "M_K_CPU1_SB_DQ<0>")
	)
	(segment
		(start 197.042024 -281.830526)
		(end 197.186804 -281.685746)
		(width 0.14478)
		(layer "In6.Cu")
		(net "M_K_CPU1_SB_DQ<0>")
	)
	(segment
		(start 196.78015 -281.830526)
		(end 197.042024 -281.830526)
		(width 0.14478)
		(layer "In6.Cu")
		(net "M_K_CPU1_SB_DQ<0>")
	)
	(segment
		(start 173.213014 -281.910282)
		(end 174.062898 -281.060398)
		(width 0.14478)
		(layer "In6.Cu")
		(net "M_K_CPU1_SB_DQ<0>")
	)
	(segment
		(start 196.63537 -281.685746)
		(end 196.78015 -281.830526)
		(width 0.14478)
		(layer "In6.Cu")
		(net "M_K_CPU1_SB_DQ<0>")
	)
	(segment
		(start 182.180992 -281.060398)
		(end 185.205624 -281.060398)
		(width 0.14478)
		(layer "In6.Cu")
		(net "M_K_CPU1_SB_DQ<0>")
	)
	(segment
		(start 197.186804 -281.205178)
		(end 197.331584 -281.060398)
		(width 0.14478)
		(layer "In6.Cu")
		(net "M_K_CPU1_SB_DQ<0>")
	)
	(arc
		(start 143.751808 -274.4089)
		(mid 144.028621 -274.332757)
		(end 144.307052 -274.402804)
		(width 0.0889)
		(layer "In6.Cu")
		(net "M_K_CPU1_SB_DQ<0>")
	)
	(arc
		(start 146.605752 -273.43227)
		(mid 146.647705 -273.404238)
		(end 146.697192 -273.394424)
		(width 0.0889)
		(layer "In6.Cu")
		(net "M_K_CPU1_SB_DQ<0>")
	)
	(arc
		(start 144.701768 -274.402804)
		(mid 144.980454 -274.332584)
		(end 145.25752 -274.4089)
		(width 0.0889)
		(layer "In6.Cu")
		(net "M_K_CPU1_SB_DQ<0>")
	)
	(arc
		(start 145.25752 -274.4089)
		(mid 145.437725 -274.459217)
		(end 145.619724 -274.415758)
		(width 0.0889)
		(layer "In6.Cu")
		(net "M_K_CPU1_SB_DQ<0>")
	)
	(arc
		(start 142.874746 -274.37715)
		(mid 143.129954 -274.333673)
		(end 143.377666 -274.4089)
		(width 0.0889)
		(layer "In6.Cu")
		(net "M_K_CPU1_SB_DQ<0>")
	)
	(arc
		(start 144.317466 -274.4089)
		(mid 144.50441 -274.459155)
		(end 144.691354 -274.4089)
		(width 0.0889)
		(layer "In6.Cu")
		(net "M_K_CPU1_SB_DQ<0>")
	)
	(arc
		(start 143.386048 -274.413726)
		(mid 143.569556 -274.45922)
		(end 143.751808 -274.4089)
		(width 0.0889)
		(layer "In6.Cu")
		(net "M_K_CPU1_SB_DQ<0>")
	)
	(segment
		(start 142.627858 -266.530328)
		(end 143.09471 -266.796266)
		(width 0.10668)
		(layer "F.Cu")
		(net "M_K_CPU1_SB_CS_N<1>")
	)
	(segment
		(start 178.367182 -268.31036)
		(end 179.21732 -269.160498)
		(width 0.14478)
		(layer "In6.Cu")
		(net "M_K_CPU1_SB_CS_N<1>")
	)
	(segment
		(start 187.77966 -268.534896)
		(end 187.942728 -268.697964)
		(width 0.14478)
		(layer "In6.Cu")
		(net "M_K_CPU1_SB_CS_N<1>")
	)
	(segment
		(start 187.942728 -268.697964)
		(end 188.173106 -268.697964)
		(width 0.14478)
		(layer "In6.Cu")
		(net "M_K_CPU1_SB_CS_N<1>")
	)
	(segment
		(start 190.725298 -268.31036)
		(end 194.17919 -268.31036)
		(width 0.14478)
		(layer "In6.Cu")
		(net "M_K_CPU1_SB_CS_N<1>")
	)
	(segment
		(start 145.161508 -266.473686)
		(end 145.467324 -266.473686)
		(width 0.0889)
		(layer "In6.Cu")
		(net "M_K_CPU1_SB_CS_N<1>")
	)
	(segment
		(start 188.72962 -267.922756)
		(end 188.892688 -268.085824)
		(width 0.14478)
		(layer "In6.Cu")
		(net "M_K_CPU1_SB_CS_N<1>")
	)
	(segment
		(start 188.499242 -267.922756)
		(end 188.72962 -267.922756)
		(width 0.14478)
		(layer "In6.Cu")
		(net "M_K_CPU1_SB_CS_N<1>")
	)
	(segment
		(start 166.03599 -268.31036)
		(end 170.849036 -268.31036)
		(width 0.14478)
		(layer "In6.Cu")
		(net "M_K_CPU1_SB_CS_N<1>")
	)
	(segment
		(start 144.221708 -266.473686)
		(end 144.232122 -266.479782)
		(width 0.0889)
		(layer "In6.Cu")
		(net "M_K_CPU1_SB_CS_N<1>")
	)
	(segment
		(start 194.17919 -268.31036)
		(end 194.604132 -268.735302)
		(width 0.14478)
		(layer "In6.Cu")
		(net "M_K_CPU1_SB_CS_N<1>")
	)
	(segment
		(start 173.69409 -269.160498)
		(end 174.544228 -268.31036)
		(width 0.14478)
		(layer "In6.Cu")
		(net "M_K_CPU1_SB_CS_N<1>")
	)
	(segment
		(start 190.56223 -268.473428)
		(end 190.725298 -268.31036)
		(width 0.14478)
		(layer "In6.Cu")
		(net "M_K_CPU1_SB_CS_N<1>")
	)
	(segment
		(start 189.286134 -268.697964)
		(end 189.449202 -268.534896)
		(width 0.14478)
		(layer "In6.Cu")
		(net "M_K_CPU1_SB_CS_N<1>")
	)
	(segment
		(start 190.168784 -268.697964)
		(end 190.399162 -268.697964)
		(width 0.14478)
		(layer "In6.Cu")
		(net "M_K_CPU1_SB_CS_N<1>")
	)
	(segment
		(start 188.336174 -268.085824)
		(end 188.499242 -267.922756)
		(width 0.14478)
		(layer "In6.Cu")
		(net "M_K_CPU1_SB_CS_N<1>")
	)
	(segment
		(start 181.238144 -269.160498)
		(end 182.088282 -268.31036)
		(width 0.14478)
		(layer "In6.Cu")
		(net "M_K_CPU1_SB_CS_N<1>")
	)
	(segment
		(start 143.09471 -266.796266)
		(end 142.940786 -266.530836)
		(width 0.0889)
		(layer "In6.Cu")
		(net "M_K_CPU1_SB_CS_N<1>")
	)
	(segment
		(start 190.399162 -268.697964)
		(end 190.56223 -268.534896)
		(width 0.14478)
		(layer "In6.Cu")
		(net "M_K_CPU1_SB_CS_N<1>")
	)
	(segment
		(start 189.055756 -268.697964)
		(end 189.286134 -268.697964)
		(width 0.14478)
		(layer "In6.Cu")
		(net "M_K_CPU1_SB_CS_N<1>")
	)
	(segment
		(start 190.56223 -268.534896)
		(end 190.56223 -268.473428)
		(width 0.14478)
		(layer "In6.Cu")
		(net "M_K_CPU1_SB_CS_N<1>")
	)
	(segment
		(start 174.544228 -268.31036)
		(end 178.367182 -268.31036)
		(width 0.14478)
		(layer "In6.Cu")
		(net "M_K_CPU1_SB_CS_N<1>")
	)
	(segment
		(start 163.951666 -269.160498)
		(end 165.185852 -269.160498)
		(width 0.14478)
		(layer "In6.Cu")
		(net "M_K_CPU1_SB_CS_N<1>")
	)
	(segment
		(start 146.389852 -265.551158)
		(end 147.72132 -265.551158)
		(width 0.0889)
		(layer "In6.Cu")
		(net "M_K_CPU1_SB_CS_N<1>")
	)
	(segment
		(start 188.892688 -268.085824)
		(end 188.892688 -268.534896)
		(width 0.14478)
		(layer "In6.Cu")
		(net "M_K_CPU1_SB_CS_N<1>")
	)
	(segment
		(start 147.72132 -265.551158)
		(end 147.873466 -265.703304)
		(width 0.0889)
		(layer "In6.Cu")
		(net "M_K_CPU1_SB_CS_N<1>")
	)
	(segment
		(start 189.842648 -267.922756)
		(end 190.005716 -268.085824)
		(width 0.14478)
		(layer "In6.Cu")
		(net "M_K_CPU1_SB_CS_N<1>")
	)
	(segment
		(start 188.173106 -268.697964)
		(end 188.336174 -268.534896)
		(width 0.14478)
		(layer "In6.Cu")
		(net "M_K_CPU1_SB_CS_N<1>")
	)
	(segment
		(start 142.940786 -266.530836)
		(end 142.963138 -266.447524)
		(width 0.0889)
		(layer "In6.Cu")
		(net "M_K_CPU1_SB_CS_N<1>")
	)
	(segment
		(start 144.787366 -266.473686)
		(end 144.795748 -266.46886)
		(width 0.0889)
		(layer "In6.Cu")
		(net "M_K_CPU1_SB_CS_N<1>")
	)
	(segment
		(start 171.699174 -269.160498)
		(end 173.69409 -269.160498)
		(width 0.14478)
		(layer "In6.Cu")
		(net "M_K_CPU1_SB_CS_N<1>")
	)
	(segment
		(start 190.005716 -268.085824)
		(end 190.005716 -268.534896)
		(width 0.14478)
		(layer "In6.Cu")
		(net "M_K_CPU1_SB_CS_N<1>")
	)
	(segment
		(start 189.449202 -268.534896)
		(end 189.449202 -268.085824)
		(width 0.14478)
		(layer "In6.Cu")
		(net "M_K_CPU1_SB_CS_N<1>")
	)
	(segment
		(start 188.336174 -268.534896)
		(end 188.336174 -268.085824)
		(width 0.14478)
		(layer "In6.Cu")
		(net "M_K_CPU1_SB_CS_N<1>")
	)
	(segment
		(start 144.213326 -266.46886)
		(end 144.221708 -266.473686)
		(width 0.0889)
		(layer "In6.Cu")
		(net "M_K_CPU1_SB_CS_N<1>")
	)
	(segment
		(start 187.616592 -268.31036)
		(end 187.77966 -268.473428)
		(width 0.14478)
		(layer "In6.Cu")
		(net "M_K_CPU1_SB_CS_N<1>")
	)
	(segment
		(start 145.467324 -266.473686)
		(end 146.389852 -265.551158)
		(width 0.0889)
		(layer "In6.Cu")
		(net "M_K_CPU1_SB_CS_N<1>")
	)
	(segment
		(start 187.77966 -268.473428)
		(end 187.77966 -268.534896)
		(width 0.14478)
		(layer "In6.Cu")
		(net "M_K_CPU1_SB_CS_N<1>")
	)
	(segment
		(start 188.892688 -268.534896)
		(end 189.055756 -268.697964)
		(width 0.14478)
		(layer "In6.Cu")
		(net "M_K_CPU1_SB_CS_N<1>")
	)
	(segment
		(start 160.494472 -265.703304)
		(end 163.951666 -269.160498)
		(width 0.14478)
		(layer "In6.Cu")
		(net "M_K_CPU1_SB_CS_N<1>")
	)
	(segment
		(start 189.449202 -268.085824)
		(end 189.61227 -267.922756)
		(width 0.14478)
		(layer "In6.Cu")
		(net "M_K_CPU1_SB_CS_N<1>")
	)
	(segment
		(start 170.849036 -268.31036)
		(end 171.699174 -269.160498)
		(width 0.14478)
		(layer "In6.Cu")
		(net "M_K_CPU1_SB_CS_N<1>")
	)
	(segment
		(start 190.005716 -268.534896)
		(end 190.168784 -268.697964)
		(width 0.14478)
		(layer "In6.Cu")
		(net "M_K_CPU1_SB_CS_N<1>")
	)
	(segment
		(start 165.185852 -269.160498)
		(end 166.03599 -268.31036)
		(width 0.14478)
		(layer "In6.Cu")
		(net "M_K_CPU1_SB_CS_N<1>")
	)
	(segment
		(start 179.21732 -269.160498)
		(end 181.238144 -269.160498)
		(width 0.14478)
		(layer "In6.Cu")
		(net "M_K_CPU1_SB_CS_N<1>")
	)
	(segment
		(start 182.088282 -268.31036)
		(end 187.616592 -268.31036)
		(width 0.14478)
		(layer "In6.Cu")
		(net "M_K_CPU1_SB_CS_N<1>")
	)
	(segment
		(start 147.873466 -265.703304)
		(end 160.494472 -265.703304)
		(width 0.14478)
		(layer "In6.Cu")
		(net "M_K_CPU1_SB_CS_N<1>")
	)
	(segment
		(start 189.61227 -267.922756)
		(end 189.842648 -267.922756)
		(width 0.14478)
		(layer "In6.Cu")
		(net "M_K_CPU1_SB_CS_N<1>")
	)
	(arc
		(start 144.795748 -266.46886)
		(mid 144.979256 -266.423366)
		(end 145.161508 -266.473686)
		(width 0.0889)
		(layer "In6.Cu")
		(net "M_K_CPU1_SB_CS_N<1>")
	)
	(arc
		(start 144.232122 -266.479782)
		(mid 144.510554 -266.54988)
		(end 144.787366 -266.473686)
		(width 0.0889)
		(layer "In6.Cu")
		(net "M_K_CPU1_SB_CS_N<1>")
	)
	(arc
		(start 142.963138 -266.447524)
		(mid 143.125327 -266.424789)
		(end 143.281654 -266.473686)
		(width 0.0889)
		(layer "In6.Cu")
		(net "M_K_CPU1_SB_CS_N<1>")
	)
	(arc
		(start 143.281654 -266.473686)
		(mid 143.56461 -266.549863)
		(end 143.847566 -266.473686)
		(width 0.0889)
		(layer "In6.Cu")
		(net "M_K_CPU1_SB_CS_N<1>")
	)
	(arc
		(start 143.847566 -266.473686)
		(mid 144.029817 -266.423336)
		(end 144.213326 -266.46886)
		(width 0.0889)
		(layer "In6.Cu")
		(net "M_K_CPU1_SB_CS_N<1>")
	)
	(segment
		(start 141.217904 -265.720322)
		(end 141.684756 -265.98626)
		(width 0.10668)
		(layer "F.Cu")
		(net "M_K_CPU1_SB_CS_N<0>")
	)
	(segment
		(start 144.307052 -265.669776)
		(end 144.317466 -265.66368)
		(width 0.0889)
		(layer "In6.Cu")
		(net "M_K_CPU1_SB_CS_N<0>")
	)
	(segment
		(start 198.279258 -267.460476)
		(end 198.7042 -267.885418)
		(width 0.14478)
		(layer "In6.Cu")
		(net "M_K_CPU1_SB_CS_N<0>")
	)
	(segment
		(start 174.636938 -267.460476)
		(end 178.406298 -267.460476)
		(width 0.14478)
		(layer "In6.Cu")
		(net "M_K_CPU1_SB_CS_N<0>")
	)
	(segment
		(start 141.684756 -265.98626)
		(end 141.530832 -265.72083)
		(width 0.0889)
		(layer "In6.Cu")
		(net "M_K_CPU1_SB_CS_N<0>")
	)
	(segment
		(start 165.94582 -267.460476)
		(end 170.786044 -267.460476)
		(width 0.14478)
		(layer "In6.Cu")
		(net "M_K_CPU1_SB_CS_N<0>")
	)
	(segment
		(start 144.317466 -265.66368)
		(end 144.325848 -265.658854)
		(width 0.0889)
		(layer "In6.Cu")
		(net "M_K_CPU1_SB_CS_N<0>")
	)
	(segment
		(start 147.25015 -265.248644)
		(end 148.008848 -265.248644)
		(width 0.0889)
		(layer "In6.Cu")
		(net "M_K_CPU1_SB_CS_N<0>")
	)
	(segment
		(start 170.786044 -267.460476)
		(end 171.635928 -268.31036)
		(width 0.14478)
		(layer "In6.Cu")
		(net "M_K_CPU1_SB_CS_N<0>")
	)
	(segment
		(start 178.406298 -267.460476)
		(end 179.256182 -268.31036)
		(width 0.14478)
		(layer "In6.Cu")
		(net "M_K_CPU1_SB_CS_N<0>")
	)
	(segment
		(start 145.257266 -265.66368)
		(end 145.952464 -265.274044)
		(width 0.0889)
		(layer "In6.Cu")
		(net "M_K_CPU1_SB_CS_N<0>")
	)
	(segment
		(start 165.095936 -268.31036)
		(end 165.94582 -267.460476)
		(width 0.14478)
		(layer "In6.Cu")
		(net "M_K_CPU1_SB_CS_N<0>")
	)
	(segment
		(start 144.6911 -265.66368)
		(end 144.701514 -265.669776)
		(width 0.0889)
		(layer "In6.Cu")
		(net "M_K_CPU1_SB_CS_N<0>")
	)
	(segment
		(start 171.635928 -268.31036)
		(end 173.787054 -268.31036)
		(width 0.14478)
		(layer "In6.Cu")
		(net "M_K_CPU1_SB_CS_N<0>")
	)
	(segment
		(start 182.180992 -267.460476)
		(end 198.279258 -267.460476)
		(width 0.14478)
		(layer "In6.Cu")
		(net "M_K_CPU1_SB_CS_N<0>")
	)
	(segment
		(start 141.530832 -265.72083)
		(end 141.553184 -265.637518)
		(width 0.0889)
		(layer "In6.Cu")
		(net "M_K_CPU1_SB_CS_N<0>")
	)
	(segment
		(start 147.22475 -265.274044)
		(end 147.25015 -265.248644)
		(width 0.0889)
		(layer "In6.Cu")
		(net "M_K_CPU1_SB_CS_N<0>")
	)
	(segment
		(start 173.787054 -268.31036)
		(end 174.636938 -267.460476)
		(width 0.14478)
		(layer "In6.Cu")
		(net "M_K_CPU1_SB_CS_N<0>")
	)
	(segment
		(start 143.377666 -265.66368)
		(end 143.386048 -265.658854)
		(width 0.0889)
		(layer "In6.Cu")
		(net "M_K_CPU1_SB_CS_N<0>")
	)
	(segment
		(start 181.331108 -268.31036)
		(end 182.180992 -267.460476)
		(width 0.14478)
		(layer "In6.Cu")
		(net "M_K_CPU1_SB_CS_N<0>")
	)
	(segment
		(start 179.256182 -268.31036)
		(end 181.331108 -268.31036)
		(width 0.14478)
		(layer "In6.Cu")
		(net "M_K_CPU1_SB_CS_N<0>")
	)
	(segment
		(start 148.008848 -265.248644)
		(end 160.725866 -265.248644)
		(width 0.14478)
		(layer "In6.Cu")
		(net "M_K_CPU1_SB_CS_N<0>")
	)
	(segment
		(start 142.803372 -265.658854)
		(end 142.811754 -265.66368)
		(width 0.0889)
		(layer "In6.Cu")
		(net "M_K_CPU1_SB_CS_N<0>")
	)
	(segment
		(start 160.725866 -265.248644)
		(end 163.787582 -268.31036)
		(width 0.14478)
		(layer "In6.Cu")
		(net "M_K_CPU1_SB_CS_N<0>")
	)
	(segment
		(start 145.952464 -265.274044)
		(end 147.22475 -265.274044)
		(width 0.0889)
		(layer "In6.Cu")
		(net "M_K_CPU1_SB_CS_N<0>")
	)
	(segment
		(start 163.787582 -268.31036)
		(end 165.095936 -268.31036)
		(width 0.14478)
		(layer "In6.Cu")
		(net "M_K_CPU1_SB_CS_N<0>")
	)
	(arc
		(start 144.325848 -265.658854)
		(mid 144.509102 -265.613481)
		(end 144.6911 -265.66368)
		(width 0.0889)
		(layer "In6.Cu")
		(net "M_K_CPU1_SB_CS_N<0>")
	)
	(arc
		(start 143.751808 -265.66368)
		(mid 144.028621 -265.739823)
		(end 144.307052 -265.669776)
		(width 0.0889)
		(layer "In6.Cu")
		(net "M_K_CPU1_SB_CS_N<0>")
	)
	(arc
		(start 144.701514 -265.669776)
		(mid 144.9802 -265.739996)
		(end 145.257266 -265.66368)
		(width 0.0889)
		(layer "In6.Cu")
		(net "M_K_CPU1_SB_CS_N<0>")
	)
	(arc
		(start 142.811754 -265.66368)
		(mid 143.09471 -265.739857)
		(end 143.377666 -265.66368)
		(width 0.0889)
		(layer "In6.Cu")
		(net "M_K_CPU1_SB_CS_N<0>")
	)
	(arc
		(start 143.386048 -265.658854)
		(mid 143.569556 -265.61336)
		(end 143.751808 -265.66368)
		(width 0.0889)
		(layer "In6.Cu")
		(net "M_K_CPU1_SB_CS_N<0>")
	)
	(arc
		(start 142.437612 -265.66368)
		(mid 142.619863 -265.61333)
		(end 142.803372 -265.658854)
		(width 0.0889)
		(layer "In6.Cu")
		(net "M_K_CPU1_SB_CS_N<0>")
	)
	(arc
		(start 141.8717 -265.66368)
		(mid 142.154656 -265.739857)
		(end 142.437612 -265.66368)
		(width 0.0889)
		(layer "In6.Cu")
		(net "M_K_CPU1_SB_CS_N<0>")
	)
	(arc
		(start 141.553184 -265.637518)
		(mid 141.715373 -265.614783)
		(end 141.8717 -265.66368)
		(width 0.0889)
		(layer "In6.Cu")
		(net "M_K_CPU1_SB_CS_N<0>")
	)
	(segment
		(start 141.217904 -270.580358)
		(end 141.684756 -270.846296)
		(width 0.10668)
		(layer "F.Cu")
		(net "M_K_CPU1_SB_CB<7>")
	)
	(segment
		(start 190.38189 -273.554952)
		(end 190.52667 -273.410172)
		(width 0.14478)
		(layer "In6.Cu")
		(net "M_K_CPU1_SB_CB<7>")
	)
	(segment
		(start 192.766188 -273.410172)
		(end 194.041268 -274.685252)
		(width 0.14478)
		(layer "In6.Cu")
		(net "M_K_CPU1_SB_CB<7>")
	)
	(segment
		(start 168.485566 -273.410426)
		(end 168.715944 -273.410426)
		(width 0.14478)
		(layer "In6.Cu")
		(net "M_K_CPU1_SB_CB<7>")
	)
	(segment
		(start 189.423802 -273.410172)
		(end 189.685676 -273.410172)
		(width 0.14478)
		(layer "In6.Cu")
		(net "M_K_CPU1_SB_CB<7>")
	)
	(segment
		(start 158.523432 -268.680184)
		(end 164.103558 -274.26031)
		(width 0.14478)
		(layer "In6.Cu")
		(net "M_K_CPU1_SB_CB<7>")
	)
	(segment
		(start 189.279022 -273.554952)
		(end 189.423802 -273.410172)
		(width 0.14478)
		(layer "In6.Cu")
		(net "M_K_CPU1_SB_CB<7>")
	)
	(segment
		(start 167.602916 -273.410426)
		(end 167.765984 -273.573494)
		(width 0.14478)
		(layer "In6.Cu")
		(net "M_K_CPU1_SB_CB<7>")
	)
	(segment
		(start 167.092884 -273.410426)
		(end 167.602916 -273.410426)
		(width 0.14478)
		(layer "In6.Cu")
		(net "M_K_CPU1_SB_CB<7>")
	)
	(segment
		(start 173.787054 -274.26031)
		(end 174.636938 -273.410426)
		(width 0.14478)
		(layer "In6.Cu")
		(net "M_K_CPU1_SB_CB<7>")
	)
	(segment
		(start 142.803372 -270.51889)
		(end 142.811754 -270.523716)
		(width 0.0889)
		(layer "In6.Cu")
		(net "M_K_CPU1_SB_CB<7>")
	)
	(segment
		(start 169.598594 -273.410426)
		(end 170.487848 -273.410426)
		(width 0.14478)
		(layer "In6.Cu")
		(net "M_K_CPU1_SB_CB<7>")
	)
	(segment
		(start 169.435526 -273.573494)
		(end 169.598594 -273.410426)
		(width 0.14478)
		(layer "In6.Cu")
		(net "M_K_CPU1_SB_CB<7>")
	)
	(segment
		(start 169.272458 -274.209764)
		(end 169.435526 -274.046696)
		(width 0.14478)
		(layer "In6.Cu")
		(net "M_K_CPU1_SB_CB<7>")
	)
	(segment
		(start 168.322498 -274.046696)
		(end 168.322498 -273.573494)
		(width 0.14478)
		(layer "In6.Cu")
		(net "M_K_CPU1_SB_CB<7>")
	)
	(segment
		(start 168.715944 -273.410426)
		(end 168.879012 -273.573494)
		(width 0.14478)
		(layer "In6.Cu")
		(net "M_K_CPU1_SB_CB<7>")
	)
	(segment
		(start 144.757902 -269.730982)
		(end 144.78762 -269.71371)
		(width 0.0889)
		(layer "In6.Cu")
		(net "M_K_CPU1_SB_CB<7>")
	)
	(segment
		(start 168.322498 -273.573494)
		(end 168.485566 -273.410426)
		(width 0.14478)
		(layer "In6.Cu")
		(net "M_K_CPU1_SB_CB<7>")
	)
	(segment
		(start 188.727588 -273.554952)
		(end 188.727588 -273.974306)
		(width 0.14478)
		(layer "In6.Cu")
		(net "M_K_CPU1_SB_CB<7>")
	)
	(segment
		(start 147.32127 -268.833092)
		(end 147.474178 -268.680184)
		(width 0.0889)
		(layer "In6.Cu")
		(net "M_K_CPU1_SB_CB<7>")
	)
	(segment
		(start 148.043138 -268.680184)
		(end 158.523432 -268.680184)
		(width 0.14478)
		(layer "In6.Cu")
		(net "M_K_CPU1_SB_CB<7>")
	)
	(segment
		(start 145.15338 -269.708884)
		(end 145.161762 -269.71371)
		(width 0.0889)
		(layer "In6.Cu")
		(net "M_K_CPU1_SB_CB<7>")
	)
	(segment
		(start 170.487848 -273.410426)
		(end 171.337732 -274.26031)
		(width 0.14478)
		(layer "In6.Cu")
		(net "M_K_CPU1_SB_CB<7>")
	)
	(segment
		(start 171.337732 -274.26031)
		(end 173.787054 -274.26031)
		(width 0.14478)
		(layer "In6.Cu")
		(net "M_K_CPU1_SB_CB<7>")
	)
	(segment
		(start 168.15943 -274.209764)
		(end 168.322498 -274.046696)
		(width 0.14478)
		(layer "In6.Cu")
		(net "M_K_CPU1_SB_CB<7>")
	)
	(segment
		(start 178.511454 -274.26031)
		(end 181.331108 -274.26031)
		(width 0.14478)
		(layer "In6.Cu")
		(net "M_K_CPU1_SB_CB<7>")
	)
	(segment
		(start 144.75714 -269.73149)
		(end 144.757902 -269.730982)
		(width 0.0889)
		(layer "In6.Cu")
		(net "M_K_CPU1_SB_CB<7>")
	)
	(segment
		(start 189.134242 -274.119086)
		(end 189.279022 -273.974306)
		(width 0.14478)
		(layer "In6.Cu")
		(net "M_K_CPU1_SB_CB<7>")
	)
	(segment
		(start 182.181246 -273.410172)
		(end 188.582808 -273.410172)
		(width 0.14478)
		(layer "In6.Cu")
		(net "M_K_CPU1_SB_CB<7>")
	)
	(segment
		(start 145.843244 -269.62481)
		(end 146.634962 -268.833092)
		(width 0.0889)
		(layer "In6.Cu")
		(net "M_K_CPU1_SB_CB<7>")
	)
	(segment
		(start 167.765984 -273.573494)
		(end 167.765984 -274.046696)
		(width 0.14478)
		(layer "In6.Cu")
		(net "M_K_CPU1_SB_CB<7>")
	)
	(segment
		(start 194.041268 -274.685252)
		(end 194.604132 -274.685252)
		(width 0.14478)
		(layer "In6.Cu")
		(net "M_K_CPU1_SB_CB<7>")
	)
	(segment
		(start 181.331108 -274.26031)
		(end 182.181246 -273.410172)
		(width 0.14478)
		(layer "In6.Cu")
		(net "M_K_CPU1_SB_CB<7>")
	)
	(segment
		(start 189.685676 -273.410172)
		(end 189.830456 -273.554952)
		(width 0.14478)
		(layer "In6.Cu")
		(net "M_K_CPU1_SB_CB<7>")
	)
	(segment
		(start 190.23711 -274.119086)
		(end 190.38189 -273.974306)
		(width 0.14478)
		(layer "In6.Cu")
		(net "M_K_CPU1_SB_CB<7>")
	)
	(segment
		(start 174.636938 -273.410426)
		(end 177.66157 -273.410426)
		(width 0.14478)
		(layer "In6.Cu")
		(net "M_K_CPU1_SB_CB<7>")
	)
	(segment
		(start 189.279022 -273.974306)
		(end 189.279022 -273.554952)
		(width 0.14478)
		(layer "In6.Cu")
		(net "M_K_CPU1_SB_CB<7>")
	)
	(segment
		(start 146.634962 -268.833092)
		(end 147.32127 -268.833092)
		(width 0.0889)
		(layer "In6.Cu")
		(net "M_K_CPU1_SB_CB<7>")
	)
	(segment
		(start 169.435526 -274.046696)
		(end 169.435526 -273.573494)
		(width 0.14478)
		(layer "In6.Cu")
		(net "M_K_CPU1_SB_CB<7>")
	)
	(segment
		(start 144.31772 -270.523716)
		(end 144.356836 -270.500856)
		(width 0.0889)
		(layer "In6.Cu")
		(net "M_K_CPU1_SB_CB<7>")
	)
	(segment
		(start 190.52667 -273.410172)
		(end 192.766188 -273.410172)
		(width 0.14478)
		(layer "In6.Cu")
		(net "M_K_CPU1_SB_CB<7>")
	)
	(segment
		(start 167.765984 -274.046696)
		(end 167.929052 -274.209764)
		(width 0.14478)
		(layer "In6.Cu")
		(net "M_K_CPU1_SB_CB<7>")
	)
	(segment
		(start 167.929052 -274.209764)
		(end 168.15943 -274.209764)
		(width 0.14478)
		(layer "In6.Cu")
		(net "M_K_CPU1_SB_CB<7>")
	)
	(segment
		(start 190.38189 -273.974306)
		(end 190.38189 -273.554952)
		(width 0.14478)
		(layer "In6.Cu")
		(net "M_K_CPU1_SB_CB<7>")
	)
	(segment
		(start 164.103558 -274.26031)
		(end 166.243 -274.26031)
		(width 0.14478)
		(layer "In6.Cu")
		(net "M_K_CPU1_SB_CB<7>")
	)
	(segment
		(start 143.377666 -270.523716)
		(end 143.386048 -270.51889)
		(width 0.0889)
		(layer "In6.Cu")
		(net "M_K_CPU1_SB_CB<7>")
	)
	(segment
		(start 141.530832 -270.580866)
		(end 141.553184 -270.497554)
		(width 0.0889)
		(layer "In6.Cu")
		(net "M_K_CPU1_SB_CB<7>")
	)
	(segment
		(start 168.879012 -274.046696)
		(end 169.04208 -274.209764)
		(width 0.14478)
		(layer "In6.Cu")
		(net "M_K_CPU1_SB_CB<7>")
	)
	(segment
		(start 188.582808 -273.410172)
		(end 188.727588 -273.554952)
		(width 0.14478)
		(layer "In6.Cu")
		(net "M_K_CPU1_SB_CB<7>")
	)
	(segment
		(start 177.66157 -273.410426)
		(end 178.511454 -274.26031)
		(width 0.14478)
		(layer "In6.Cu")
		(net "M_K_CPU1_SB_CB<7>")
	)
	(segment
		(start 141.684756 -270.846296)
		(end 141.530832 -270.580866)
		(width 0.0889)
		(layer "In6.Cu")
		(net "M_K_CPU1_SB_CB<7>")
	)
	(segment
		(start 189.830456 -273.554952)
		(end 189.830456 -273.974306)
		(width 0.14478)
		(layer "In6.Cu")
		(net "M_K_CPU1_SB_CB<7>")
	)
	(segment
		(start 189.975236 -274.119086)
		(end 190.23711 -274.119086)
		(width 0.14478)
		(layer "In6.Cu")
		(net "M_K_CPU1_SB_CB<7>")
	)
	(segment
		(start 188.872368 -274.119086)
		(end 189.134242 -274.119086)
		(width 0.14478)
		(layer "In6.Cu")
		(net "M_K_CPU1_SB_CB<7>")
	)
	(segment
		(start 168.879012 -273.573494)
		(end 168.879012 -274.046696)
		(width 0.14478)
		(layer "In6.Cu")
		(net "M_K_CPU1_SB_CB<7>")
	)
	(segment
		(start 169.04208 -274.209764)
		(end 169.272458 -274.209764)
		(width 0.14478)
		(layer "In6.Cu")
		(net "M_K_CPU1_SB_CB<7>")
	)
	(segment
		(start 166.243 -274.26031)
		(end 167.092884 -273.410426)
		(width 0.14478)
		(layer "In6.Cu")
		(net "M_K_CPU1_SB_CB<7>")
	)
	(segment
		(start 189.830456 -273.974306)
		(end 189.975236 -274.119086)
		(width 0.14478)
		(layer "In6.Cu")
		(net "M_K_CPU1_SB_CB<7>")
	)
	(segment
		(start 188.727588 -273.974306)
		(end 188.872368 -274.119086)
		(width 0.14478)
		(layer "In6.Cu")
		(net "M_K_CPU1_SB_CB<7>")
	)
	(segment
		(start 147.474178 -268.680184)
		(end 148.043138 -268.680184)
		(width 0.0889)
		(layer "In6.Cu")
		(net "M_K_CPU1_SB_CB<7>")
	)
	(arc
		(start 141.553184 -270.497554)
		(mid 141.715373 -270.474819)
		(end 141.8717 -270.523716)
		(width 0.0889)
		(layer "In6.Cu")
		(net "M_K_CPU1_SB_CB<7>")
	)
	(arc
		(start 141.8717 -270.523716)
		(mid 142.154656 -270.599893)
		(end 142.437612 -270.523716)
		(width 0.0889)
		(layer "In6.Cu")
		(net "M_K_CPU1_SB_CB<7>")
	)
	(arc
		(start 143.386048 -270.51889)
		(mid 143.569556 -270.473396)
		(end 143.751808 -270.523716)
		(width 0.0889)
		(layer "In6.Cu")
		(net "M_K_CPU1_SB_CB<7>")
	)
	(arc
		(start 142.437612 -270.523716)
		(mid 142.619863 -270.473366)
		(end 142.803372 -270.51889)
		(width 0.0889)
		(layer "In6.Cu")
		(net "M_K_CPU1_SB_CB<7>")
	)
	(arc
		(start 145.161762 -269.71371)
		(mid 145.517622 -269.785152)
		(end 145.843244 -269.62481)
		(width 0.0889)
		(layer "In6.Cu")
		(net "M_K_CPU1_SB_CB<7>")
	)
	(arc
		(start 143.751808 -270.523716)
		(mid 144.034764 -270.599893)
		(end 144.31772 -270.523716)
		(width 0.0889)
		(layer "In6.Cu")
		(net "M_K_CPU1_SB_CB<7>")
	)
	(arc
		(start 144.78762 -269.71371)
		(mid 144.969871 -269.66336)
		(end 145.15338 -269.708884)
		(width 0.0889)
		(layer "In6.Cu")
		(net "M_K_CPU1_SB_CB<7>")
	)
	(arc
		(start 144.356836 -270.500856)
		(mid 144.535649 -270.298506)
		(end 144.600168 -270.03629)
		(width 0.0889)
		(layer "In6.Cu")
		(net "M_K_CPU1_SB_CB<7>")
	)
	(arc
		(start 142.811754 -270.523716)
		(mid 143.09471 -270.599893)
		(end 143.377666 -270.523716)
		(width 0.0889)
		(layer "In6.Cu")
		(net "M_K_CPU1_SB_CB<7>")
	)
	(arc
		(start 144.600168 -270.03629)
		(mid 144.641717 -269.864868)
		(end 144.75714 -269.73149)
		(width 0.0889)
		(layer "In6.Cu")
		(net "M_K_CPU1_SB_CB<7>")
	)
	(segment
		(start 142.627858 -269.770352)
		(end 143.09471 -270.03629)
		(width 0.10668)
		(layer "F.Cu")
		(net "M_K_CPU1_SB_CB<6>")
	)
	(segment
		(start 192.84696 -271.710404)
		(end 193.329306 -271.710404)
		(width 0.14478)
		(layer "In6.Cu")
		(net "M_K_CPU1_SB_CB<6>")
	)
	(segment
		(start 189.50178 -272.085562)
		(end 189.763654 -272.085562)
		(width 0.14478)
		(layer "In6.Cu")
		(net "M_K_CPU1_SB_CB<6>")
	)
	(segment
		(start 185.380122 -271.490186)
		(end 185.380122 -271.930622)
		(width 0.14478)
		(layer "In6.Cu")
		(net "M_K_CPU1_SB_CB<6>")
	)
	(segment
		(start 192.70218 -271.472406)
		(end 192.70218 -271.565624)
		(width 0.14478)
		(layer "In6.Cu")
		(net "M_K_CPU1_SB_CB<6>")
	)
	(segment
		(start 186.62777 -271.710404)
		(end 187.557918 -271.710404)
		(width 0.14478)
		(layer "In6.Cu")
		(net "M_K_CPU1_SB_CB<6>")
	)
	(segment
		(start 188.254132 -271.480026)
		(end 188.254132 -271.940782)
		(width 0.14478)
		(layer "In6.Cu")
		(net "M_K_CPU1_SB_CB<6>")
	)
	(segment
		(start 146.638518 -267.770864)
		(end 148.056854 -267.770864)
		(width 0.0889)
		(layer "In6.Cu")
		(net "M_K_CPU1_SB_CB<6>")
	)
	(segment
		(start 184.277254 -271.855184)
		(end 184.277254 -271.930622)
		(width 0.14478)
		(layer "In6.Cu")
		(net "M_K_CPU1_SB_CB<6>")
	)
	(segment
		(start 184.132474 -271.710404)
		(end 184.277254 -271.855184)
		(width 0.14478)
		(layer "In6.Cu")
		(net "M_K_CPU1_SB_CB<6>")
	)
	(segment
		(start 188.805566 -271.940782)
		(end 188.805566 -271.480026)
		(width 0.14478)
		(layer "In6.Cu")
		(net "M_K_CPU1_SB_CB<6>")
	)
	(segment
		(start 185.931556 -271.490186)
		(end 186.076336 -271.345406)
		(width 0.14478)
		(layer "In6.Cu")
		(net "M_K_CPU1_SB_CB<6>")
	)
	(segment
		(start 189.357 -271.940782)
		(end 189.50178 -272.085562)
		(width 0.14478)
		(layer "In6.Cu")
		(net "M_K_CPU1_SB_CB<6>")
	)
	(segment
		(start 184.973468 -271.345406)
		(end 185.235342 -271.345406)
		(width 0.14478)
		(layer "In6.Cu")
		(net "M_K_CPU1_SB_CB<6>")
	)
	(segment
		(start 189.908434 -271.480026)
		(end 190.053214 -271.335246)
		(width 0.14478)
		(layer "In6.Cu")
		(net "M_K_CPU1_SB_CB<6>")
	)
	(segment
		(start 181.331108 -272.560288)
		(end 182.180992 -271.710404)
		(width 0.14478)
		(layer "In6.Cu")
		(net "M_K_CPU1_SB_CB<6>")
	)
	(segment
		(start 190.053214 -271.335246)
		(end 190.315088 -271.335246)
		(width 0.14478)
		(layer "In6.Cu")
		(net "M_K_CPU1_SB_CB<6>")
	)
	(segment
		(start 177.66157 -271.710404)
		(end 178.511454 -272.560288)
		(width 0.14478)
		(layer "In6.Cu")
		(net "M_K_CPU1_SB_CB<6>")
	)
	(segment
		(start 186.48299 -271.565624)
		(end 186.62777 -271.710404)
		(width 0.14478)
		(layer "In6.Cu")
		(net "M_K_CPU1_SB_CB<6>")
	)
	(segment
		(start 144.28597 -268.921992)
		(end 144.31772 -268.903704)
		(width 0.0889)
		(layer "In6.Cu")
		(net "M_K_CPU1_SB_CB<6>")
	)
	(segment
		(start 182.180992 -271.710404)
		(end 184.132474 -271.710404)
		(width 0.14478)
		(layer "In6.Cu")
		(net "M_K_CPU1_SB_CB<6>")
	)
	(segment
		(start 186.33821 -271.345406)
		(end 186.48299 -271.490186)
		(width 0.14478)
		(layer "In6.Cu")
		(net "M_K_CPU1_SB_CB<6>")
	)
	(segment
		(start 192.150746 -271.948402)
		(end 192.150746 -271.472406)
		(width 0.14478)
		(layer "In6.Cu")
		(net "M_K_CPU1_SB_CB<6>")
	)
	(segment
		(start 189.763654 -272.085562)
		(end 189.908434 -271.940782)
		(width 0.14478)
		(layer "In6.Cu")
		(net "M_K_CPU1_SB_CB<6>")
	)
	(segment
		(start 167.092884 -271.710404)
		(end 170.133772 -271.710404)
		(width 0.14478)
		(layer "In6.Cu")
		(net "M_K_CPU1_SB_CB<6>")
	)
	(segment
		(start 187.847478 -271.335246)
		(end 188.109352 -271.335246)
		(width 0.14478)
		(layer "In6.Cu")
		(net "M_K_CPU1_SB_CB<6>")
	)
	(segment
		(start 193.329306 -271.710404)
		(end 194.604132 -272.98523)
		(width 0.14478)
		(layer "In6.Cu")
		(net "M_K_CPU1_SB_CB<6>")
	)
	(segment
		(start 148.056854 -267.770864)
		(end 159.327088 -267.770864)
		(width 0.14478)
		(layer "In6.Cu")
		(net "M_K_CPU1_SB_CB<6>")
	)
	(segment
		(start 185.786776 -272.075402)
		(end 185.931556 -271.930622)
		(width 0.14478)
		(layer "In6.Cu")
		(net "M_K_CPU1_SB_CB<6>")
	)
	(segment
		(start 185.931556 -271.930622)
		(end 185.931556 -271.490186)
		(width 0.14478)
		(layer "In6.Cu")
		(net "M_K_CPU1_SB_CB<6>")
	)
	(segment
		(start 186.076336 -271.345406)
		(end 186.33821 -271.345406)
		(width 0.14478)
		(layer "In6.Cu")
		(net "M_K_CPU1_SB_CB<6>")
	)
	(segment
		(start 189.908434 -271.940782)
		(end 189.908434 -271.480026)
		(width 0.14478)
		(layer "In6.Cu")
		(net "M_K_CPU1_SB_CB<6>")
	)
	(segment
		(start 185.235342 -271.345406)
		(end 185.380122 -271.490186)
		(width 0.14478)
		(layer "In6.Cu")
		(net "M_K_CPU1_SB_CB<6>")
	)
	(segment
		(start 184.828688 -271.930622)
		(end 184.828688 -271.490186)
		(width 0.14478)
		(layer "In6.Cu")
		(net "M_K_CPU1_SB_CB<6>")
	)
	(segment
		(start 185.524902 -272.075402)
		(end 185.786776 -272.075402)
		(width 0.14478)
		(layer "In6.Cu")
		(net "M_K_CPU1_SB_CB<6>")
	)
	(segment
		(start 173.787054 -272.560288)
		(end 174.636938 -271.710404)
		(width 0.14478)
		(layer "In6.Cu")
		(net "M_K_CPU1_SB_CB<6>")
	)
	(segment
		(start 191.599312 -271.855184)
		(end 191.599312 -271.948402)
		(width 0.14478)
		(layer "In6.Cu")
		(net "M_K_CPU1_SB_CB<6>")
	)
	(segment
		(start 184.683908 -272.075402)
		(end 184.828688 -271.930622)
		(width 0.14478)
		(layer "In6.Cu")
		(net "M_K_CPU1_SB_CB<6>")
	)
	(segment
		(start 191.599312 -271.948402)
		(end 191.744092 -272.093182)
		(width 0.14478)
		(layer "In6.Cu")
		(net "M_K_CPU1_SB_CB<6>")
	)
	(segment
		(start 145.290032 -268.887702)
		(end 145.685764 -268.723618)
		(width 0.0889)
		(layer "In6.Cu")
		(net "M_K_CPU1_SB_CB<6>")
	)
	(segment
		(start 184.828688 -271.490186)
		(end 184.973468 -271.345406)
		(width 0.14478)
		(layer "In6.Cu")
		(net "M_K_CPU1_SB_CB<6>")
	)
	(segment
		(start 178.511454 -272.560288)
		(end 181.331108 -272.560288)
		(width 0.14478)
		(layer "In6.Cu")
		(net "M_K_CPU1_SB_CB<6>")
	)
	(segment
		(start 142.940786 -269.77086)
		(end 142.963138 -269.687548)
		(width 0.0889)
		(layer "In6.Cu")
		(net "M_K_CPU1_SB_CB<6>")
	)
	(segment
		(start 191.454532 -271.710404)
		(end 191.599312 -271.855184)
		(width 0.14478)
		(layer "In6.Cu")
		(net "M_K_CPU1_SB_CB<6>")
	)
	(segment
		(start 166.243 -272.560288)
		(end 167.092884 -271.710404)
		(width 0.14478)
		(layer "In6.Cu")
		(net "M_K_CPU1_SB_CB<6>")
	)
	(segment
		(start 190.459868 -271.565624)
		(end 190.604648 -271.710404)
		(width 0.14478)
		(layer "In6.Cu")
		(net "M_K_CPU1_SB_CB<6>")
	)
	(segment
		(start 143.847566 -269.71371)
		(end 143.886682 -269.69085)
		(width 0.0889)
		(layer "In6.Cu")
		(net "M_K_CPU1_SB_CB<6>")
	)
	(segment
		(start 164.116512 -272.560288)
		(end 166.243 -272.560288)
		(width 0.14478)
		(layer "In6.Cu")
		(net "M_K_CPU1_SB_CB<6>")
	)
	(segment
		(start 190.459868 -271.480026)
		(end 190.459868 -271.565624)
		(width 0.14478)
		(layer "In6.Cu")
		(net "M_K_CPU1_SB_CB<6>")
	)
	(segment
		(start 184.422034 -272.075402)
		(end 184.683908 -272.075402)
		(width 0.14478)
		(layer "In6.Cu")
		(net "M_K_CPU1_SB_CB<6>")
	)
	(segment
		(start 188.660786 -272.085562)
		(end 188.805566 -271.940782)
		(width 0.14478)
		(layer "In6.Cu")
		(net "M_K_CPU1_SB_CB<6>")
	)
	(segment
		(start 192.70218 -271.565624)
		(end 192.84696 -271.710404)
		(width 0.14478)
		(layer "In6.Cu")
		(net "M_K_CPU1_SB_CB<6>")
	)
	(segment
		(start 144.31772 -268.903704)
		(end 144.326102 -268.898878)
		(width 0.0889)
		(layer "In6.Cu")
		(net "M_K_CPU1_SB_CB<6>")
	)
	(segment
		(start 143.09471 -270.03629)
		(end 142.940786 -269.77086)
		(width 0.0889)
		(layer "In6.Cu")
		(net "M_K_CPU1_SB_CB<6>")
	)
	(segment
		(start 187.702698 -271.480026)
		(end 187.847478 -271.335246)
		(width 0.14478)
		(layer "In6.Cu")
		(net "M_K_CPU1_SB_CB<6>")
	)
	(segment
		(start 186.48299 -271.490186)
		(end 186.48299 -271.565624)
		(width 0.14478)
		(layer "In6.Cu")
		(net "M_K_CPU1_SB_CB<6>")
	)
	(segment
		(start 187.702698 -271.565624)
		(end 187.702698 -271.480026)
		(width 0.14478)
		(layer "In6.Cu")
		(net "M_K_CPU1_SB_CB<6>")
	)
	(segment
		(start 188.805566 -271.480026)
		(end 188.950346 -271.335246)
		(width 0.14478)
		(layer "In6.Cu")
		(net "M_K_CPU1_SB_CB<6>")
	)
	(segment
		(start 145.685764 -268.723618)
		(end 146.638518 -267.770864)
		(width 0.0889)
		(layer "In6.Cu")
		(net "M_K_CPU1_SB_CB<6>")
	)
	(segment
		(start 189.21222 -271.335246)
		(end 189.357 -271.480026)
		(width 0.14478)
		(layer "In6.Cu")
		(net "M_K_CPU1_SB_CB<6>")
	)
	(segment
		(start 174.636938 -271.710404)
		(end 177.66157 -271.710404)
		(width 0.14478)
		(layer "In6.Cu")
		(net "M_K_CPU1_SB_CB<6>")
	)
	(segment
		(start 189.357 -271.480026)
		(end 189.357 -271.940782)
		(width 0.14478)
		(layer "In6.Cu")
		(net "M_K_CPU1_SB_CB<6>")
	)
	(segment
		(start 188.109352 -271.335246)
		(end 188.254132 -271.480026)
		(width 0.14478)
		(layer "In6.Cu")
		(net "M_K_CPU1_SB_CB<6>")
	)
	(segment
		(start 190.315088 -271.335246)
		(end 190.459868 -271.480026)
		(width 0.14478)
		(layer "In6.Cu")
		(net "M_K_CPU1_SB_CB<6>")
	)
	(segment
		(start 192.150746 -271.472406)
		(end 192.295526 -271.327626)
		(width 0.14478)
		(layer "In6.Cu")
		(net "M_K_CPU1_SB_CB<6>")
	)
	(segment
		(start 184.277254 -271.930622)
		(end 184.422034 -272.075402)
		(width 0.14478)
		(layer "In6.Cu")
		(net "M_K_CPU1_SB_CB<6>")
	)
	(segment
		(start 192.5574 -271.327626)
		(end 192.70218 -271.472406)
		(width 0.14478)
		(layer "In6.Cu")
		(net "M_K_CPU1_SB_CB<6>")
	)
	(segment
		(start 170.133772 -271.710404)
		(end 170.983656 -272.560288)
		(width 0.14478)
		(layer "In6.Cu")
		(net "M_K_CPU1_SB_CB<6>")
	)
	(segment
		(start 188.254132 -271.940782)
		(end 188.398912 -272.085562)
		(width 0.14478)
		(layer "In6.Cu")
		(net "M_K_CPU1_SB_CB<6>")
	)
	(segment
		(start 185.380122 -271.930622)
		(end 185.524902 -272.075402)
		(width 0.14478)
		(layer "In6.Cu")
		(net "M_K_CPU1_SB_CB<6>")
	)
	(segment
		(start 188.398912 -272.085562)
		(end 188.660786 -272.085562)
		(width 0.14478)
		(layer "In6.Cu")
		(net "M_K_CPU1_SB_CB<6>")
	)
	(segment
		(start 159.327088 -267.770864)
		(end 164.116512 -272.560288)
		(width 0.14478)
		(layer "In6.Cu")
		(net "M_K_CPU1_SB_CB<6>")
	)
	(segment
		(start 191.744092 -272.093182)
		(end 192.005966 -272.093182)
		(width 0.14478)
		(layer "In6.Cu")
		(net "M_K_CPU1_SB_CB<6>")
	)
	(segment
		(start 170.983656 -272.560288)
		(end 173.787054 -272.560288)
		(width 0.14478)
		(layer "In6.Cu")
		(net "M_K_CPU1_SB_CB<6>")
	)
	(segment
		(start 188.950346 -271.335246)
		(end 189.21222 -271.335246)
		(width 0.14478)
		(layer "In6.Cu")
		(net "M_K_CPU1_SB_CB<6>")
	)
	(segment
		(start 192.295526 -271.327626)
		(end 192.5574 -271.327626)
		(width 0.14478)
		(layer "In6.Cu")
		(net "M_K_CPU1_SB_CB<6>")
	)
	(segment
		(start 190.604648 -271.710404)
		(end 191.454532 -271.710404)
		(width 0.14478)
		(layer "In6.Cu")
		(net "M_K_CPU1_SB_CB<6>")
	)
	(segment
		(start 187.557918 -271.710404)
		(end 187.702698 -271.565624)
		(width 0.14478)
		(layer "In6.Cu")
		(net "M_K_CPU1_SB_CB<6>")
	)
	(segment
		(start 192.005966 -272.093182)
		(end 192.150746 -271.948402)
		(width 0.14478)
		(layer "In6.Cu")
		(net "M_K_CPU1_SB_CB<6>")
	)
	(arc
		(start 143.886682 -269.69085)
		(mid 144.065495 -269.4885)
		(end 144.130014 -269.226284)
		(width 0.0889)
		(layer "In6.Cu")
		(net "M_K_CPU1_SB_CB<6>")
	)
	(arc
		(start 144.130014 -269.226284)
		(mid 144.171269 -269.055313)
		(end 144.28597 -268.921992)
		(width 0.0889)
		(layer "In6.Cu")
		(net "M_K_CPU1_SB_CB<6>")
	)
	(arc
		(start 143.281654 -269.71371)
		(mid 143.56461 -269.789887)
		(end 143.847566 -269.71371)
		(width 0.0889)
		(layer "In6.Cu")
		(net "M_K_CPU1_SB_CB<6>")
	)
	(arc
		(start 144.326102 -268.898878)
		(mid 144.50961 -268.853384)
		(end 144.691862 -268.903704)
		(width 0.0889)
		(layer "In6.Cu")
		(net "M_K_CPU1_SB_CB<6>")
	)
	(arc
		(start 142.963138 -269.687548)
		(mid 143.125327 -269.664813)
		(end 143.281654 -269.71371)
		(width 0.0889)
		(layer "In6.Cu")
		(net "M_K_CPU1_SB_CB<6>")
	)
	(arc
		(start 144.691862 -268.903704)
		(mid 144.974818 -268.979881)
		(end 145.257774 -268.903704)
		(width 0.0889)
		(layer "In6.Cu")
		(net "M_K_CPU1_SB_CB<6>")
	)
	(arc
		(start 145.257774 -268.903704)
		(mid 145.273641 -268.895176)
		(end 145.290032 -268.887702)
		(width 0.0889)
		(layer "In6.Cu")
		(net "M_K_CPU1_SB_CB<6>")
	)
	(segment
		(start 140.748004 -269.770352)
		(end 141.214856 -270.03629)
		(width 0.10668)
		(layer "F.Cu")
		(net "M_K_CPU1_SB_CB<5>")
	)
	(segment
		(start 173.69409 -273.410426)
		(end 174.544228 -272.560288)
		(width 0.14478)
		(layer "In6.Cu")
		(net "M_K_CPU1_SB_CB<5>")
	)
	(segment
		(start 145.70837 -269.489936)
		(end 146.609562 -268.588744)
		(width 0.0889)
		(layer "In6.Cu")
		(net "M_K_CPU1_SB_CB<5>")
	)
	(segment
		(start 141.967712 -270.35887)
		(end 141.976094 -270.363696)
		(width 0.0889)
		(layer "In6.Cu")
		(net "M_K_CPU1_SB_CB<5>")
	)
	(segment
		(start 145.257774 -269.548864)
		(end 145.266156 -269.55369)
		(width 0.0889)
		(layer "In6.Cu")
		(net "M_K_CPU1_SB_CB<5>")
	)
	(segment
		(start 177.726594 -272.560288)
		(end 178.576732 -273.410426)
		(width 0.14478)
		(layer "In6.Cu")
		(net "M_K_CPU1_SB_CB<5>")
	)
	(segment
		(start 167.000174 -272.560288)
		(end 170.298364 -272.560288)
		(width 0.14478)
		(layer "In6.Cu")
		(net "M_K_CPU1_SB_CB<5>")
	)
	(segment
		(start 147.578826 -268.225524)
		(end 148.034502 -268.225524)
		(width 0.0889)
		(layer "In6.Cu")
		(net "M_K_CPU1_SB_CB<5>")
	)
	(segment
		(start 144.213326 -270.363696)
		(end 144.221708 -270.35887)
		(width 0.0889)
		(layer "In6.Cu")
		(net "M_K_CPU1_SB_CB<5>")
	)
	(segment
		(start 141.214856 -270.03629)
		(end 141.36878 -270.30172)
		(width 0.0889)
		(layer "In6.Cu")
		(net "M_K_CPU1_SB_CB<5>")
	)
	(segment
		(start 193.779902 -273.410426)
		(end 198.279258 -273.410426)
		(width 0.14478)
		(layer "In6.Cu")
		(net "M_K_CPU1_SB_CB<5>")
	)
	(segment
		(start 158.830772 -268.225524)
		(end 164.015674 -273.410426)
		(width 0.14478)
		(layer "In6.Cu")
		(net "M_K_CPU1_SB_CB<5>")
	)
	(segment
		(start 174.544228 -272.560288)
		(end 177.726594 -272.560288)
		(width 0.14478)
		(layer "In6.Cu")
		(net "M_K_CPU1_SB_CB<5>")
	)
	(segment
		(start 178.576732 -273.410426)
		(end 181.238144 -273.410426)
		(width 0.14478)
		(layer "In6.Cu")
		(net "M_K_CPU1_SB_CB<5>")
	)
	(segment
		(start 170.298364 -272.560288)
		(end 171.148502 -273.410426)
		(width 0.14478)
		(layer "In6.Cu")
		(net "M_K_CPU1_SB_CB<5>")
	)
	(segment
		(start 182.088282 -272.560288)
		(end 192.929764 -272.560288)
		(width 0.14478)
		(layer "In6.Cu")
		(net "M_K_CPU1_SB_CB<5>")
	)
	(segment
		(start 144.221708 -270.35887)
		(end 144.253458 -270.340582)
		(width 0.0889)
		(layer "In6.Cu")
		(net "M_K_CPU1_SB_CB<5>")
	)
	(segment
		(start 147.215606 -268.588744)
		(end 147.578826 -268.225524)
		(width 0.0889)
		(layer "In6.Cu")
		(net "M_K_CPU1_SB_CB<5>")
	)
	(segment
		(start 181.238144 -273.410426)
		(end 182.088282 -272.560288)
		(width 0.14478)
		(layer "In6.Cu")
		(net "M_K_CPU1_SB_CB<5>")
	)
	(segment
		(start 166.150036 -273.410426)
		(end 167.000174 -272.560288)
		(width 0.14478)
		(layer "In6.Cu")
		(net "M_K_CPU1_SB_CB<5>")
	)
	(segment
		(start 198.279258 -273.410426)
		(end 198.7042 -273.835368)
		(width 0.14478)
		(layer "In6.Cu")
		(net "M_K_CPU1_SB_CB<5>")
	)
	(segment
		(start 148.034502 -268.225524)
		(end 158.830772 -268.225524)
		(width 0.14478)
		(layer "In6.Cu")
		(net "M_K_CPU1_SB_CB<5>")
	)
	(segment
		(start 192.929764 -272.560288)
		(end 193.779902 -273.410426)
		(width 0.14478)
		(layer "In6.Cu")
		(net "M_K_CPU1_SB_CB<5>")
	)
	(segment
		(start 141.36878 -270.30172)
		(end 141.464792 -270.32712)
		(width 0.0889)
		(layer "In6.Cu")
		(net "M_K_CPU1_SB_CB<5>")
	)
	(segment
		(start 164.015674 -273.410426)
		(end 166.150036 -273.410426)
		(width 0.14478)
		(layer "In6.Cu")
		(net "M_K_CPU1_SB_CB<5>")
	)
	(segment
		(start 171.148502 -273.410426)
		(end 173.69409 -273.410426)
		(width 0.14478)
		(layer "In6.Cu")
		(net "M_K_CPU1_SB_CB<5>")
	)
	(segment
		(start 144.652746 -269.571724)
		(end 144.691862 -269.548864)
		(width 0.0889)
		(layer "In6.Cu")
		(net "M_K_CPU1_SB_CB<5>")
	)
	(segment
		(start 146.609562 -268.588744)
		(end 147.215606 -268.588744)
		(width 0.0889)
		(layer "In6.Cu")
		(net "M_K_CPU1_SB_CB<5>")
	)
	(arc
		(start 145.631916 -269.548864)
		(mid 145.672061 -269.521888)
		(end 145.70837 -269.489936)
		(width 0.0889)
		(layer "In6.Cu")
		(net "M_K_CPU1_SB_CB<5>")
	)
	(arc
		(start 143.847566 -270.35887)
		(mid 144.029817 -270.40922)
		(end 144.213326 -270.363696)
		(width 0.0889)
		(layer "In6.Cu")
		(net "M_K_CPU1_SB_CB<5>")
	)
	(arc
		(start 144.691862 -269.548864)
		(mid 144.974818 -269.472687)
		(end 145.257774 -269.548864)
		(width 0.0889)
		(layer "In6.Cu")
		(net "M_K_CPU1_SB_CB<5>")
	)
	(arc
		(start 144.409414 -270.03629)
		(mid 144.473929 -269.774071)
		(end 144.652746 -269.571724)
		(width 0.0889)
		(layer "In6.Cu")
		(net "M_K_CPU1_SB_CB<5>")
	)
	(arc
		(start 142.341854 -270.35887)
		(mid 142.62481 -270.282693)
		(end 142.907766 -270.35887)
		(width 0.0889)
		(layer "In6.Cu")
		(net "M_K_CPU1_SB_CB<5>")
	)
	(arc
		(start 145.266156 -269.55369)
		(mid 145.449664 -269.599184)
		(end 145.631916 -269.548864)
		(width 0.0889)
		(layer "In6.Cu")
		(net "M_K_CPU1_SB_CB<5>")
	)
	(arc
		(start 144.253458 -270.340582)
		(mid 144.368134 -270.207248)
		(end 144.409414 -270.03629)
		(width 0.0889)
		(layer "In6.Cu")
		(net "M_K_CPU1_SB_CB<5>")
	)
	(arc
		(start 141.464792 -270.32712)
		(mid 141.72 -270.283643)
		(end 141.967712 -270.35887)
		(width 0.0889)
		(layer "In6.Cu")
		(net "M_K_CPU1_SB_CB<5>")
	)
	(arc
		(start 142.907766 -270.35887)
		(mid 143.09471 -270.409125)
		(end 143.281654 -270.35887)
		(width 0.0889)
		(layer "In6.Cu")
		(net "M_K_CPU1_SB_CB<5>")
	)
	(arc
		(start 141.976094 -270.363696)
		(mid 142.159602 -270.40919)
		(end 142.341854 -270.35887)
		(width 0.0889)
		(layer "In6.Cu")
		(net "M_K_CPU1_SB_CB<5>")
	)
	(arc
		(start 143.281654 -270.35887)
		(mid 143.56461 -270.282693)
		(end 143.847566 -270.35887)
		(width 0.0889)
		(layer "In6.Cu")
		(net "M_K_CPU1_SB_CB<5>")
	)
	(segment
		(start 142.157958 -268.960346)
		(end 142.62481 -269.226284)
		(width 0.10668)
		(layer "F.Cu")
		(net "M_K_CPU1_SB_CB<4>")
	)
	(segment
		(start 169.944288 -270.860266)
		(end 170.794172 -271.71015)
		(width 0.14478)
		(layer "In6.Cu")
		(net "M_K_CPU1_SB_CB<4>")
	)
	(segment
		(start 166.149782 -271.710404)
		(end 166.150036 -271.71015)
		(width 0.14478)
		(layer "In6.Cu")
		(net "M_K_CPU1_SB_CB<4>")
	)
	(segment
		(start 197.108318 -270.860266)
		(end 197.42912 -270.860266)
		(width 0.14478)
		(layer "In6.Cu")
		(net "M_K_CPU1_SB_CB<4>")
	)
	(segment
		(start 170.794172 -271.71015)
		(end 173.901354 -271.71015)
		(width 0.14478)
		(layer "In6.Cu")
		(net "M_K_CPU1_SB_CB<4>")
	)
	(segment
		(start 195.164456 -270.860266)
		(end 195.309236 -271.005046)
		(width 0.14478)
		(layer "In6.Cu")
		(net "M_K_CPU1_SB_CB<4>")
	)
	(segment
		(start 195.71589 -271.518126)
		(end 195.86067 -271.373346)
		(width 0.14478)
		(layer "In6.Cu")
		(net "M_K_CPU1_SB_CB<4>")
	)
	(segment
		(start 196.412104 -271.005046)
		(end 196.412104 -271.373346)
		(width 0.14478)
		(layer "In6.Cu")
		(net "M_K_CPU1_SB_CB<4>")
	)
	(segment
		(start 196.556884 -271.518126)
		(end 196.818758 -271.518126)
		(width 0.14478)
		(layer "In6.Cu")
		(net "M_K_CPU1_SB_CB<4>")
	)
	(segment
		(start 145.450306 -268.613636)
		(end 145.562066 -268.53896)
		(width 0.0889)
		(layer "In6.Cu")
		(net "M_K_CPU1_SB_CB<4>")
	)
	(segment
		(start 142.62481 -269.226284)
		(end 142.778734 -269.491714)
		(width 0.0889)
		(layer "In6.Cu")
		(net "M_K_CPU1_SB_CB<4>")
	)
	(segment
		(start 145.232882 -268.703806)
		(end 145.450306 -268.613636)
		(width 0.0889)
		(layer "In6.Cu")
		(net "M_K_CPU1_SB_CB<4>")
	)
	(segment
		(start 147.974558 -267.316204)
		(end 159.69488 -267.316204)
		(width 0.14478)
		(layer "In6.Cu")
		(net "M_K_CPU1_SB_CB<4>")
	)
	(segment
		(start 159.69488 -267.316204)
		(end 164.08908 -271.710404)
		(width 0.14478)
		(layer "In6.Cu")
		(net "M_K_CPU1_SB_CB<4>")
	)
	(segment
		(start 196.267324 -270.860266)
		(end 196.412104 -271.005046)
		(width 0.14478)
		(layer "In6.Cu")
		(net "M_K_CPU1_SB_CB<4>")
	)
	(segment
		(start 196.00545 -270.860266)
		(end 196.267324 -270.860266)
		(width 0.14478)
		(layer "In6.Cu")
		(net "M_K_CPU1_SB_CB<4>")
	)
	(segment
		(start 182.302912 -270.860266)
		(end 195.164456 -270.860266)
		(width 0.14478)
		(layer "In6.Cu")
		(net "M_K_CPU1_SB_CB<4>")
	)
	(segment
		(start 174.751238 -270.860266)
		(end 177.511202 -270.860266)
		(width 0.14478)
		(layer "In6.Cu")
		(net "M_K_CPU1_SB_CB<4>")
	)
	(segment
		(start 166.150036 -271.71015)
		(end 166.367968 -271.71015)
		(width 0.14478)
		(layer "In6.Cu")
		(net "M_K_CPU1_SB_CB<4>")
	)
	(segment
		(start 146.784822 -267.316204)
		(end 147.974558 -267.316204)
		(width 0.0889)
		(layer "In6.Cu")
		(net "M_K_CPU1_SB_CB<4>")
	)
	(segment
		(start 173.901354 -271.71015)
		(end 174.751238 -270.860266)
		(width 0.14478)
		(layer "In6.Cu")
		(net "M_K_CPU1_SB_CB<4>")
	)
	(segment
		(start 143.751808 -269.548864)
		(end 143.782288 -269.531084)
		(width 0.0889)
		(layer "In6.Cu")
		(net "M_K_CPU1_SB_CB<4>")
	)
	(segment
		(start 164.08908 -271.710404)
		(end 166.149782 -271.710404)
		(width 0.14478)
		(layer "In6.Cu")
		(net "M_K_CPU1_SB_CB<4>")
	)
	(segment
		(start 195.309236 -271.005046)
		(end 195.309236 -271.373346)
		(width 0.14478)
		(layer "In6.Cu")
		(net "M_K_CPU1_SB_CB<4>")
	)
	(segment
		(start 178.361086 -271.71015)
		(end 181.453028 -271.71015)
		(width 0.14478)
		(layer "In6.Cu")
		(net "M_K_CPU1_SB_CB<4>")
	)
	(segment
		(start 142.778734 -269.491714)
		(end 142.874746 -269.517114)
		(width 0.0889)
		(layer "In6.Cu")
		(net "M_K_CPU1_SB_CB<4>")
	)
	(segment
		(start 145.562066 -268.53896)
		(end 146.784822 -267.316204)
		(width 0.0889)
		(layer "In6.Cu")
		(net "M_K_CPU1_SB_CB<4>")
	)
	(segment
		(start 195.309236 -271.373346)
		(end 195.454016 -271.518126)
		(width 0.14478)
		(layer "In6.Cu")
		(net "M_K_CPU1_SB_CB<4>")
	)
	(segment
		(start 196.963538 -271.005046)
		(end 197.108318 -270.860266)
		(width 0.14478)
		(layer "In6.Cu")
		(net "M_K_CPU1_SB_CB<4>")
	)
	(segment
		(start 196.412104 -271.373346)
		(end 196.556884 -271.518126)
		(width 0.14478)
		(layer "In6.Cu")
		(net "M_K_CPU1_SB_CB<4>")
	)
	(segment
		(start 144.182592 -268.761718)
		(end 144.221708 -268.738858)
		(width 0.0889)
		(layer "In6.Cu")
		(net "M_K_CPU1_SB_CB<4>")
	)
	(segment
		(start 195.86067 -271.005046)
		(end 196.00545 -270.860266)
		(width 0.14478)
		(layer "In6.Cu")
		(net "M_K_CPU1_SB_CB<4>")
	)
	(segment
		(start 196.963538 -271.373346)
		(end 196.963538 -271.005046)
		(width 0.14478)
		(layer "In6.Cu")
		(net "M_K_CPU1_SB_CB<4>")
	)
	(segment
		(start 166.367968 -271.71015)
		(end 167.217852 -270.860266)
		(width 0.14478)
		(layer "In6.Cu")
		(net "M_K_CPU1_SB_CB<4>")
	)
	(segment
		(start 195.86067 -271.373346)
		(end 195.86067 -271.005046)
		(width 0.14478)
		(layer "In6.Cu")
		(net "M_K_CPU1_SB_CB<4>")
	)
	(segment
		(start 195.454016 -271.518126)
		(end 195.71589 -271.518126)
		(width 0.14478)
		(layer "In6.Cu")
		(net "M_K_CPU1_SB_CB<4>")
	)
	(segment
		(start 167.217852 -270.860266)
		(end 169.944288 -270.860266)
		(width 0.14478)
		(layer "In6.Cu")
		(net "M_K_CPU1_SB_CB<4>")
	)
	(segment
		(start 177.511202 -270.860266)
		(end 178.361086 -271.71015)
		(width 0.14478)
		(layer "In6.Cu")
		(net "M_K_CPU1_SB_CB<4>")
	)
	(segment
		(start 181.453028 -271.71015)
		(end 182.302912 -270.860266)
		(width 0.14478)
		(layer "In6.Cu")
		(net "M_K_CPU1_SB_CB<4>")
	)
	(segment
		(start 143.377666 -269.548864)
		(end 143.386048 -269.55369)
		(width 0.0889)
		(layer "In6.Cu")
		(net "M_K_CPU1_SB_CB<4>")
	)
	(segment
		(start 196.818758 -271.518126)
		(end 196.963538 -271.373346)
		(width 0.14478)
		(layer "In6.Cu")
		(net "M_K_CPU1_SB_CB<4>")
	)
	(segment
		(start 197.42912 -270.860266)
		(end 198.7042 -272.135346)
		(width 0.14478)
		(layer "In6.Cu")
		(net "M_K_CPU1_SB_CB<4>")
	)
	(arc
		(start 144.78762 -268.738858)
		(mid 144.969871 -268.789208)
		(end 145.15338 -268.743684)
		(width 0.0889)
		(layer "In6.Cu")
		(net "M_K_CPU1_SB_CB<4>")
	)
	(arc
		(start 142.874746 -269.517114)
		(mid 143.129954 -269.473637)
		(end 143.377666 -269.548864)
		(width 0.0889)
		(layer "In6.Cu")
		(net "M_K_CPU1_SB_CB<4>")
	)
	(arc
		(start 143.386048 -269.55369)
		(mid 143.569556 -269.599184)
		(end 143.751808 -269.548864)
		(width 0.0889)
		(layer "In6.Cu")
		(net "M_K_CPU1_SB_CB<4>")
	)
	(arc
		(start 144.221708 -268.738858)
		(mid 144.504664 -268.662681)
		(end 144.78762 -268.738858)
		(width 0.0889)
		(layer "In6.Cu")
		(net "M_K_CPU1_SB_CB<4>")
	)
	(arc
		(start 143.93926 -269.226284)
		(mid 144.003775 -268.964065)
		(end 144.182592 -268.761718)
		(width 0.0889)
		(layer "In6.Cu")
		(net "M_K_CPU1_SB_CB<4>")
	)
	(arc
		(start 143.782288 -269.531084)
		(mid 143.897715 -269.397708)
		(end 143.93926 -269.226284)
		(width 0.0889)
		(layer "In6.Cu")
		(net "M_K_CPU1_SB_CB<4>")
	)
	(arc
		(start 145.15338 -268.743684)
		(mid 145.192339 -268.722165)
		(end 145.232882 -268.703806)
		(width 0.0889)
		(layer "In6.Cu")
		(net "M_K_CPU1_SB_CB<4>")
	)
	(segment
		(start 141.217904 -273.820382)
		(end 141.684756 -274.08632)
		(width 0.10668)
		(layer "F.Cu")
		(net "M_K_CPU1_SB_CB<3>")
	)
	(segment
		(start 141.530832 -273.82089)
		(end 141.553184 -273.737578)
		(width 0.0889)
		(layer "In6.Cu")
		(net "M_K_CPU1_SB_CB<3>")
	)
	(segment
		(start 147.609306 -272.383504)
		(end 148.068792 -272.383504)
		(width 0.0889)
		(layer "In6.Cu")
		(net "M_K_CPU1_SB_CB<3>")
	)
	(segment
		(start 156.498036 -273.642074)
		(end 156.498036 -273.872706)
		(width 0.14478)
		(layer "In6.Cu")
		(net "M_K_CPU1_SB_CB<3>")
	)
	(segment
		(start 188.084206 -281.060398)
		(end 188.934344 -280.21026)
		(width 0.14478)
		(layer "In6.Cu")
		(net "M_K_CPU1_SB_CB<3>")
	)
	(segment
		(start 166.150036 -281.060398)
		(end 167.000174 -280.21026)
		(width 0.14478)
		(layer "In6.Cu")
		(net "M_K_CPU1_SB_CB<3>")
	)
	(segment
		(start 157.839918 -274.662138)
		(end 158.07055 -274.662138)
		(width 0.14478)
		(layer "In6.Cu")
		(net "M_K_CPU1_SB_CB<3>")
	)
	(segment
		(start 157.28315 -273.874738)
		(end 157.446218 -274.037806)
		(width 0.14478)
		(layer "In6.Cu")
		(net "M_K_CPU1_SB_CB<3>")
	)
	(segment
		(start 156.658818 -273.250406)
		(end 156.659072 -273.481038)
		(width 0.14478)
		(layer "In6.Cu")
		(net "M_K_CPU1_SB_CB<3>")
	)
	(segment
		(start 144.317466 -273.76374)
		(end 144.325848 -273.758914)
		(width 0.0889)
		(layer "In6.Cu")
		(net "M_K_CPU1_SB_CB<3>")
	)
	(segment
		(start 157.448758 -274.823428)
		(end 157.678882 -274.823174)
		(width 0.14478)
		(layer "In6.Cu")
		(net "M_K_CPU1_SB_CB<3>")
	)
	(segment
		(start 159.039052 -275.63064)
		(end 159.397954 -275.989542)
		(width 0.14478)
		(layer "In6.Cu")
		(net "M_K_CPU1_SB_CB<3>")
	)
	(segment
		(start 156.49575 -273.087338)
		(end 156.658818 -273.250406)
		(width 0.14478)
		(layer "In6.Cu")
		(net "M_K_CPU1_SB_CB<3>")
	)
	(segment
		(start 157.446218 -274.037806)
		(end 157.446472 -274.268438)
		(width 0.14478)
		(layer "In6.Cu")
		(net "M_K_CPU1_SB_CB<3>")
	)
	(segment
		(start 182.088282 -280.21026)
		(end 185.20537 -280.21026)
		(width 0.14478)
		(layer "In6.Cu")
		(net "M_K_CPU1_SB_CB<3>")
	)
	(segment
		(start 144.6911 -273.76374)
		(end 144.701514 -273.769836)
		(width 0.0889)
		(layer "In6.Cu")
		(net "M_K_CPU1_SB_CB<3>")
	)
	(segment
		(start 158.230824 -275.420836)
		(end 158.23057 -275.65096)
		(width 0.14478)
		(layer "In6.Cu")
		(net "M_K_CPU1_SB_CB<3>")
	)
	(segment
		(start 156.659072 -273.481038)
		(end 156.498036 -273.642074)
		(width 0.14478)
		(layer "In6.Cu")
		(net "M_K_CPU1_SB_CB<3>")
	)
	(segment
		(start 157.052518 -273.874738)
		(end 157.28315 -273.874738)
		(width 0.14478)
		(layer "In6.Cu")
		(net "M_K_CPU1_SB_CB<3>")
	)
	(segment
		(start 147.500086 -272.492724)
		(end 147.609306 -272.383504)
		(width 0.0889)
		(layer "In6.Cu")
		(net "M_K_CPU1_SB_CB<3>")
	)
	(segment
		(start 156.265118 -273.087338)
		(end 156.49575 -273.087338)
		(width 0.14478)
		(layer "In6.Cu")
		(net "M_K_CPU1_SB_CB<3>")
	)
	(segment
		(start 158.41472 -275.23694)
		(end 158.230824 -275.420836)
		(width 0.14478)
		(layer "In6.Cu")
		(net "M_K_CPU1_SB_CB<3>")
	)
	(segment
		(start 156.104082 -273.248374)
		(end 156.265118 -273.087338)
		(width 0.14478)
		(layer "In6.Cu")
		(net "M_K_CPU1_SB_CB<3>")
	)
	(segment
		(start 158.23057 -275.65096)
		(end 158.393892 -275.814282)
		(width 0.14478)
		(layer "In6.Cu")
		(net "M_K_CPU1_SB_CB<3>")
	)
	(segment
		(start 143.377666 -273.76374)
		(end 143.386048 -273.758914)
		(width 0.0889)
		(layer "In6.Cu")
		(net "M_K_CPU1_SB_CB<3>")
	)
	(segment
		(start 186.055508 -281.060398)
		(end 188.084206 -281.060398)
		(width 0.14478)
		(layer "In6.Cu")
		(net "M_K_CPU1_SB_CB<3>")
	)
	(segment
		(start 144.307052 -273.769836)
		(end 144.317466 -273.76374)
		(width 0.0889)
		(layer "In6.Cu")
		(net "M_K_CPU1_SB_CB<3>")
	)
	(segment
		(start 141.684756 -274.08632)
		(end 141.530832 -273.82089)
		(width 0.0889)
		(layer "In6.Cu")
		(net "M_K_CPU1_SB_CB<3>")
	)
	(segment
		(start 155.669996 -272.383504)
		(end 155.819856 -272.533364)
		(width 0.14478)
		(layer "In6.Cu")
		(net "M_K_CPU1_SB_CB<3>")
	)
	(segment
		(start 148.068792 -272.383504)
		(end 155.669996 -272.383504)
		(width 0.14478)
		(layer "In6.Cu")
		(net "M_K_CPU1_SB_CB<3>")
	)
	(segment
		(start 174.125636 -280.21026)
		(end 177.973482 -280.21026)
		(width 0.14478)
		(layer "In6.Cu")
		(net "M_K_CPU1_SB_CB<3>")
	)
	(segment
		(start 155.819856 -272.745454)
		(end 155.710636 -272.854674)
		(width 0.14478)
		(layer "In6.Cu")
		(net "M_K_CPU1_SB_CB<3>")
	)
	(segment
		(start 159.397954 -275.989542)
		(end 159.397954 -276.823678)
		(width 0.14478)
		(layer "In6.Cu")
		(net "M_K_CPU1_SB_CB<3>")
	)
	(segment
		(start 159.397954 -276.823678)
		(end 163.634674 -281.060398)
		(width 0.14478)
		(layer "In6.Cu")
		(net "M_K_CPU1_SB_CB<3>")
	)
	(segment
		(start 163.634674 -281.060398)
		(end 166.150036 -281.060398)
		(width 0.14478)
		(layer "In6.Cu")
		(net "M_K_CPU1_SB_CB<3>")
	)
	(segment
		(start 158.41472 -275.006308)
		(end 158.41472 -275.23694)
		(width 0.14478)
		(layer "In6.Cu")
		(net "M_K_CPU1_SB_CB<3>")
	)
	(segment
		(start 155.873958 -273.248628)
		(end 156.104082 -273.248374)
		(width 0.14478)
		(layer "In6.Cu")
		(net "M_K_CPU1_SB_CB<3>")
	)
	(segment
		(start 155.710636 -273.085306)
		(end 155.873958 -273.248628)
		(width 0.14478)
		(layer "In6.Cu")
		(net "M_K_CPU1_SB_CB<3>")
	)
	(segment
		(start 178.82362 -281.060398)
		(end 181.238144 -281.060398)
		(width 0.14478)
		(layer "In6.Cu")
		(net "M_K_CPU1_SB_CB<3>")
	)
	(segment
		(start 158.07055 -274.662138)
		(end 158.41472 -275.006308)
		(width 0.14478)
		(layer "In6.Cu")
		(net "M_K_CPU1_SB_CB<3>")
	)
	(segment
		(start 185.20537 -280.21026)
		(end 186.055508 -281.060398)
		(width 0.14478)
		(layer "In6.Cu")
		(net "M_K_CPU1_SB_CB<3>")
	)
	(segment
		(start 158.80842 -275.630386)
		(end 159.039052 -275.63064)
		(width 0.14478)
		(layer "In6.Cu")
		(net "M_K_CPU1_SB_CB<3>")
	)
	(segment
		(start 173.275498 -281.060398)
		(end 174.125636 -280.21026)
		(width 0.14478)
		(layer "In6.Cu")
		(net "M_K_CPU1_SB_CB<3>")
	)
	(segment
		(start 146.974306 -272.492724)
		(end 147.500086 -272.492724)
		(width 0.0889)
		(layer "In6.Cu")
		(net "M_K_CPU1_SB_CB<3>")
	)
	(segment
		(start 194.17919 -280.21026)
		(end 194.604132 -280.635202)
		(width 0.14478)
		(layer "In6.Cu")
		(net "M_K_CPU1_SB_CB<3>")
	)
	(segment
		(start 142.803372 -273.758914)
		(end 142.811754 -273.76374)
		(width 0.0889)
		(layer "In6.Cu")
		(net "M_K_CPU1_SB_CB<3>")
	)
	(segment
		(start 157.446472 -274.268438)
		(end 157.285436 -274.429474)
		(width 0.14478)
		(layer "In6.Cu")
		(net "M_K_CPU1_SB_CB<3>")
	)
	(segment
		(start 156.498036 -273.872706)
		(end 156.661358 -274.036028)
		(width 0.14478)
		(layer "In6.Cu")
		(net "M_K_CPU1_SB_CB<3>")
	)
	(segment
		(start 157.678882 -274.823174)
		(end 157.839918 -274.662138)
		(width 0.14478)
		(layer "In6.Cu")
		(net "M_K_CPU1_SB_CB<3>")
	)
	(segment
		(start 158.624524 -275.814282)
		(end 158.80842 -275.630386)
		(width 0.14478)
		(layer "In6.Cu")
		(net "M_K_CPU1_SB_CB<3>")
	)
	(segment
		(start 155.710636 -272.854674)
		(end 155.710636 -273.085306)
		(width 0.14478)
		(layer "In6.Cu")
		(net "M_K_CPU1_SB_CB<3>")
	)
	(segment
		(start 158.393892 -275.814282)
		(end 158.624524 -275.814282)
		(width 0.14478)
		(layer "In6.Cu")
		(net "M_K_CPU1_SB_CB<3>")
	)
	(segment
		(start 157.285436 -274.660106)
		(end 157.448758 -274.823428)
		(width 0.14478)
		(layer "In6.Cu")
		(net "M_K_CPU1_SB_CB<3>")
	)
	(segment
		(start 155.819856 -272.533364)
		(end 155.819856 -272.745454)
		(width 0.14478)
		(layer "In6.Cu")
		(net "M_K_CPU1_SB_CB<3>")
	)
	(segment
		(start 177.973482 -280.21026)
		(end 178.82362 -281.060398)
		(width 0.14478)
		(layer "In6.Cu")
		(net "M_K_CPU1_SB_CB<3>")
	)
	(segment
		(start 181.238144 -281.060398)
		(end 182.088282 -280.21026)
		(width 0.14478)
		(layer "In6.Cu")
		(net "M_K_CPU1_SB_CB<3>")
	)
	(segment
		(start 167.000174 -280.21026)
		(end 170.531028 -280.21026)
		(width 0.14478)
		(layer "In6.Cu")
		(net "M_K_CPU1_SB_CB<3>")
	)
	(segment
		(start 188.934344 -280.21026)
		(end 194.17919 -280.21026)
		(width 0.14478)
		(layer "In6.Cu")
		(net "M_K_CPU1_SB_CB<3>")
	)
	(segment
		(start 156.891482 -274.035774)
		(end 157.052518 -273.874738)
		(width 0.14478)
		(layer "In6.Cu")
		(net "M_K_CPU1_SB_CB<3>")
	)
	(segment
		(start 171.381166 -281.060398)
		(end 173.275498 -281.060398)
		(width 0.14478)
		(layer "In6.Cu")
		(net "M_K_CPU1_SB_CB<3>")
	)
	(segment
		(start 156.661358 -274.036028)
		(end 156.891482 -274.035774)
		(width 0.14478)
		(layer "In6.Cu")
		(net "M_K_CPU1_SB_CB<3>")
	)
	(segment
		(start 145.798032 -273.668998)
		(end 146.974306 -272.492724)
		(width 0.0889)
		(layer "In6.Cu")
		(net "M_K_CPU1_SB_CB<3>")
	)
	(segment
		(start 170.531028 -280.21026)
		(end 171.381166 -281.060398)
		(width 0.14478)
		(layer "In6.Cu")
		(net "M_K_CPU1_SB_CB<3>")
	)
	(segment
		(start 157.285436 -274.429474)
		(end 157.285436 -274.660106)
		(width 0.14478)
		(layer "In6.Cu")
		(net "M_K_CPU1_SB_CB<3>")
	)
	(arc
		(start 144.325848 -273.758914)
		(mid 144.509102 -273.713541)
		(end 144.6911 -273.76374)
		(width 0.0889)
		(layer "In6.Cu")
		(net "M_K_CPU1_SB_CB<3>")
	)
	(arc
		(start 145.257266 -273.76374)
		(mid 145.370976 -273.71812)
		(end 145.492978 -273.706844)
		(width 0.0889)
		(layer "In6.Cu")
		(net "M_K_CPU1_SB_CB<3>")
	)
	(arc
		(start 144.701514 -273.769836)
		(mid 144.9802 -273.840056)
		(end 145.257266 -273.76374)
		(width 0.0889)
		(layer "In6.Cu")
		(net "M_K_CPU1_SB_CB<3>")
	)
	(arc
		(start 145.706592 -273.706844)
		(mid 145.755551 -273.695751)
		(end 145.798032 -273.668998)
		(width 0.0889)
		(layer "In6.Cu")
		(net "M_K_CPU1_SB_CB<3>")
	)
	(arc
		(start 141.8717 -273.76374)
		(mid 142.154656 -273.839917)
		(end 142.437612 -273.76374)
		(width 0.0889)
		(layer "In6.Cu")
		(net "M_K_CPU1_SB_CB<3>")
	)
	(arc
		(start 142.437612 -273.76374)
		(mid 142.619863 -273.71339)
		(end 142.803372 -273.758914)
		(width 0.0889)
		(layer "In6.Cu")
		(net "M_K_CPU1_SB_CB<3>")
	)
	(arc
		(start 145.492978 -273.706844)
		(mid 145.599785 -273.709663)
		(end 145.706592 -273.706844)
		(width 0.0889)
		(layer "In6.Cu")
		(net "M_K_CPU1_SB_CB<3>")
	)
	(arc
		(start 143.386048 -273.758914)
		(mid 143.569556 -273.71342)
		(end 143.751808 -273.76374)
		(width 0.0889)
		(layer "In6.Cu")
		(net "M_K_CPU1_SB_CB<3>")
	)
	(arc
		(start 142.811754 -273.76374)
		(mid 143.09471 -273.839917)
		(end 143.377666 -273.76374)
		(width 0.0889)
		(layer "In6.Cu")
		(net "M_K_CPU1_SB_CB<3>")
	)
	(arc
		(start 143.751808 -273.76374)
		(mid 144.028621 -273.839883)
		(end 144.307052 -273.769836)
		(width 0.0889)
		(layer "In6.Cu")
		(net "M_K_CPU1_SB_CB<3>")
	)
	(arc
		(start 141.553184 -273.737578)
		(mid 141.715373 -273.714843)
		(end 141.8717 -273.76374)
		(width 0.0889)
		(layer "In6.Cu")
		(net "M_K_CPU1_SB_CB<3>")
	)
	(segment
		(start 142.627858 -273.010376)
		(end 143.09471 -273.276314)
		(width 0.10668)
		(layer "F.Cu")
		(net "M_K_CPU1_SB_CB<2>")
	)
	(segment
		(start 162.257232 -278.131778)
		(end 162.257232 -278.36241)
		(width 0.14478)
		(layer "In6.Cu")
		(net "M_K_CPU1_SB_CB<2>")
	)
	(segment
		(start 161.469832 -277.57501)
		(end 161.6329 -277.738078)
		(width 0.14478)
		(layer "In6.Cu")
		(net "M_K_CPU1_SB_CB<2>")
	)
	(segment
		(start 144.213326 -272.948908)
		(end 144.221708 -272.953734)
		(width 0.0889)
		(layer "In6.Cu")
		(net "M_K_CPU1_SB_CB<2>")
	)
	(segment
		(start 173.69409 -279.360376)
		(end 174.544228 -278.510238)
		(width 0.14478)
		(layer "In6.Cu")
		(net "M_K_CPU1_SB_CB<2>")
	)
	(segment
		(start 180.96992 -279.360376)
		(end 181.820058 -278.510238)
		(width 0.14478)
		(layer "In6.Cu")
		(net "M_K_CPU1_SB_CB<2>")
	)
	(segment
		(start 162.381438 -277.450804)
		(end 162.544506 -277.613872)
		(width 0.14478)
		(layer "In6.Cu")
		(net "M_K_CPU1_SB_CB<2>")
	)
	(segment
		(start 166.783766 -278.510238)
		(end 170.346116 -278.510238)
		(width 0.14478)
		(layer "In6.Cu")
		(net "M_K_CPU1_SB_CB<2>")
	)
	(segment
		(start 144.787366 -272.953734)
		(end 144.795748 -272.948908)
		(width 0.0889)
		(layer "In6.Cu")
		(net "M_K_CPU1_SB_CB<2>")
	)
	(segment
		(start 162.544506 -277.613872)
		(end 162.544506 -277.844504)
		(width 0.14478)
		(layer "In6.Cu")
		(net "M_K_CPU1_SB_CB<2>")
	)
	(segment
		(start 161.863532 -277.738078)
		(end 162.150806 -277.450804)
		(width 0.14478)
		(layer "In6.Cu")
		(net "M_K_CPU1_SB_CB<2>")
	)
	(segment
		(start 192.926716 -278.284686)
		(end 193.071496 -278.139906)
		(width 0.14478)
		(layer "In6.Cu")
		(net "M_K_CPU1_SB_CB<2>")
	)
	(segment
		(start 160.969706 -276.039072)
		(end 160.969706 -276.269704)
		(width 0.14478)
		(layer "In6.Cu")
		(net "M_K_CPU1_SB_CB<2>")
	)
	(segment
		(start 161.757106 -276.826472)
		(end 161.757106 -277.057104)
		(width 0.14478)
		(layer "In6.Cu")
		(net "M_K_CPU1_SB_CB<2>")
	)
	(segment
		(start 156.404818 -271.474184)
		(end 160.969706 -276.039072)
		(width 0.14478)
		(layer "In6.Cu")
		(net "M_K_CPU1_SB_CB<2>")
	)
	(segment
		(start 161.757106 -277.057104)
		(end 161.469832 -277.344378)
		(width 0.14478)
		(layer "In6.Cu")
		(net "M_K_CPU1_SB_CB<2>")
	)
	(segment
		(start 193.62293 -278.510238)
		(end 194.178936 -278.510238)
		(width 0.14478)
		(layer "In6.Cu")
		(net "M_K_CPU1_SB_CB<2>")
	)
	(segment
		(start 160.682432 -276.78761)
		(end 160.8455 -276.950678)
		(width 0.14478)
		(layer "In6.Cu")
		(net "M_K_CPU1_SB_CB<2>")
	)
	(segment
		(start 192.520062 -278.88057)
		(end 192.781936 -278.88057)
		(width 0.14478)
		(layer "In6.Cu")
		(net "M_K_CPU1_SB_CB<2>")
	)
	(segment
		(start 191.968628 -278.139906)
		(end 192.230502 -278.139906)
		(width 0.14478)
		(layer "In6.Cu")
		(net "M_K_CPU1_SB_CB<2>")
	)
	(segment
		(start 142.940786 -273.010884)
		(end 142.963138 -272.927572)
		(width 0.0889)
		(layer "In6.Cu")
		(net "M_K_CPU1_SB_CB<2>")
	)
	(segment
		(start 147.476718 -271.474184)
		(end 148.031708 -271.474184)
		(width 0.0889)
		(layer "In6.Cu")
		(net "M_K_CPU1_SB_CB<2>")
	)
	(segment
		(start 177.555906 -278.510238)
		(end 178.406044 -279.360376)
		(width 0.14478)
		(layer "In6.Cu")
		(net "M_K_CPU1_SB_CB<2>")
	)
	(segment
		(start 192.926716 -278.73579)
		(end 192.926716 -278.284686)
		(width 0.14478)
		(layer "In6.Cu")
		(net "M_K_CPU1_SB_CB<2>")
	)
	(segment
		(start 174.544228 -278.510238)
		(end 177.555906 -278.510238)
		(width 0.14478)
		(layer "In6.Cu")
		(net "M_K_CPU1_SB_CB<2>")
	)
	(segment
		(start 165.933628 -279.360376)
		(end 166.783766 -278.510238)
		(width 0.14478)
		(layer "In6.Cu")
		(net "M_K_CPU1_SB_CB<2>")
	)
	(segment
		(start 192.375282 -278.284686)
		(end 192.375282 -278.73579)
		(width 0.14478)
		(layer "In6.Cu")
		(net "M_K_CPU1_SB_CB<2>")
	)
	(segment
		(start 193.33337 -278.139906)
		(end 193.47815 -278.284686)
		(width 0.14478)
		(layer "In6.Cu")
		(net "M_K_CPU1_SB_CB<2>")
	)
	(segment
		(start 192.781936 -278.88057)
		(end 192.926716 -278.73579)
		(width 0.14478)
		(layer "In6.Cu")
		(net "M_K_CPU1_SB_CB<2>")
	)
	(segment
		(start 185.990738 -279.360376)
		(end 188.513974 -279.360376)
		(width 0.14478)
		(layer "In6.Cu")
		(net "M_K_CPU1_SB_CB<2>")
	)
	(segment
		(start 162.257232 -278.36241)
		(end 163.255198 -279.360376)
		(width 0.14478)
		(layer "In6.Cu")
		(net "M_K_CPU1_SB_CB<2>")
	)
	(segment
		(start 161.6329 -277.738078)
		(end 161.863532 -277.738078)
		(width 0.14478)
		(layer "In6.Cu")
		(net "M_K_CPU1_SB_CB<2>")
	)
	(segment
		(start 193.47815 -278.365458)
		(end 193.62293 -278.510238)
		(width 0.14478)
		(layer "In6.Cu")
		(net "M_K_CPU1_SB_CB<2>")
	)
	(segment
		(start 162.150806 -277.450804)
		(end 162.381438 -277.450804)
		(width 0.14478)
		(layer "In6.Cu")
		(net "M_K_CPU1_SB_CB<2>")
	)
	(segment
		(start 160.969706 -276.269704)
		(end 160.682432 -276.556978)
		(width 0.14478)
		(layer "In6.Cu")
		(net "M_K_CPU1_SB_CB<2>")
	)
	(segment
		(start 161.469832 -277.344378)
		(end 161.469832 -277.57501)
		(width 0.14478)
		(layer "In6.Cu")
		(net "M_K_CPU1_SB_CB<2>")
	)
	(segment
		(start 144.221708 -272.953734)
		(end 144.232122 -272.95983)
		(width 0.0889)
		(layer "In6.Cu")
		(net "M_K_CPU1_SB_CB<2>")
	)
	(segment
		(start 185.1406 -278.510238)
		(end 185.990738 -279.360376)
		(width 0.14478)
		(layer "In6.Cu")
		(net "M_K_CPU1_SB_CB<2>")
	)
	(segment
		(start 160.8455 -276.950678)
		(end 161.076132 -276.950678)
		(width 0.14478)
		(layer "In6.Cu")
		(net "M_K_CPU1_SB_CB<2>")
	)
	(segment
		(start 171.196254 -279.360376)
		(end 173.69409 -279.360376)
		(width 0.14478)
		(layer "In6.Cu")
		(net "M_K_CPU1_SB_CB<2>")
	)
	(segment
		(start 191.823848 -278.365458)
		(end 191.823848 -278.284686)
		(width 0.14478)
		(layer "In6.Cu")
		(net "M_K_CPU1_SB_CB<2>")
	)
	(segment
		(start 160.682432 -276.556978)
		(end 160.682432 -276.78761)
		(width 0.14478)
		(layer "In6.Cu")
		(net "M_K_CPU1_SB_CB<2>")
	)
	(segment
		(start 161.076132 -276.950678)
		(end 161.363406 -276.663404)
		(width 0.14478)
		(layer "In6.Cu")
		(net "M_K_CPU1_SB_CB<2>")
	)
	(segment
		(start 191.679068 -278.510238)
		(end 191.823848 -278.365458)
		(width 0.14478)
		(layer "In6.Cu")
		(net "M_K_CPU1_SB_CB<2>")
	)
	(segment
		(start 191.823848 -278.284686)
		(end 191.968628 -278.139906)
		(width 0.14478)
		(layer "In6.Cu")
		(net "M_K_CPU1_SB_CB<2>")
	)
	(segment
		(start 188.513974 -279.360376)
		(end 189.364112 -278.510238)
		(width 0.14478)
		(layer "In6.Cu")
		(net "M_K_CPU1_SB_CB<2>")
	)
	(segment
		(start 193.071496 -278.139906)
		(end 193.33337 -278.139906)
		(width 0.14478)
		(layer "In6.Cu")
		(net "M_K_CPU1_SB_CB<2>")
	)
	(segment
		(start 192.230502 -278.139906)
		(end 192.375282 -278.284686)
		(width 0.14478)
		(layer "In6.Cu")
		(net "M_K_CPU1_SB_CB<2>")
	)
	(segment
		(start 193.47815 -278.284686)
		(end 193.47815 -278.365458)
		(width 0.14478)
		(layer "In6.Cu")
		(net "M_K_CPU1_SB_CB<2>")
	)
	(segment
		(start 161.594038 -276.663404)
		(end 161.757106 -276.826472)
		(width 0.14478)
		(layer "In6.Cu")
		(net "M_K_CPU1_SB_CB<2>")
	)
	(segment
		(start 161.363406 -276.663404)
		(end 161.594038 -276.663404)
		(width 0.14478)
		(layer "In6.Cu")
		(net "M_K_CPU1_SB_CB<2>")
	)
	(segment
		(start 163.255198 -279.360376)
		(end 165.933628 -279.360376)
		(width 0.14478)
		(layer "In6.Cu")
		(net "M_K_CPU1_SB_CB<2>")
	)
	(segment
		(start 148.031708 -271.474184)
		(end 156.404818 -271.474184)
		(width 0.14478)
		(layer "In6.Cu")
		(net "M_K_CPU1_SB_CB<2>")
	)
	(segment
		(start 189.364112 -278.510238)
		(end 191.679068 -278.510238)
		(width 0.14478)
		(layer "In6.Cu")
		(net "M_K_CPU1_SB_CB<2>")
	)
	(segment
		(start 194.178936 -278.510238)
		(end 194.604132 -278.935434)
		(width 0.14478)
		(layer "In6.Cu")
		(net "M_K_CPU1_SB_CB<2>")
	)
	(segment
		(start 192.375282 -278.73579)
		(end 192.520062 -278.88057)
		(width 0.14478)
		(layer "In6.Cu")
		(net "M_K_CPU1_SB_CB<2>")
	)
	(segment
		(start 162.544506 -277.844504)
		(end 162.257232 -278.131778)
		(width 0.14478)
		(layer "In6.Cu")
		(net "M_K_CPU1_SB_CB<2>")
	)
	(segment
		(start 143.09471 -273.276314)
		(end 142.940786 -273.010884)
		(width 0.0889)
		(layer "In6.Cu")
		(net "M_K_CPU1_SB_CB<2>")
	)
	(segment
		(start 181.820058 -278.510238)
		(end 185.1406 -278.510238)
		(width 0.14478)
		(layer "In6.Cu")
		(net "M_K_CPU1_SB_CB<2>")
	)
	(segment
		(start 145.90903 -272.856452)
		(end 147.009358 -271.756124)
		(width 0.0889)
		(layer "In6.Cu")
		(net "M_K_CPU1_SB_CB<2>")
	)
	(segment
		(start 178.406044 -279.360376)
		(end 180.96992 -279.360376)
		(width 0.14478)
		(layer "In6.Cu")
		(net "M_K_CPU1_SB_CB<2>")
	)
	(segment
		(start 170.346116 -278.510238)
		(end 171.196254 -279.360376)
		(width 0.14478)
		(layer "In6.Cu")
		(net "M_K_CPU1_SB_CB<2>")
	)
	(segment
		(start 147.194778 -271.756124)
		(end 147.476718 -271.474184)
		(width 0.0889)
		(layer "In6.Cu")
		(net "M_K_CPU1_SB_CB<2>")
	)
	(segment
		(start 147.009358 -271.756124)
		(end 147.194778 -271.756124)
		(width 0.0889)
		(layer "In6.Cu")
		(net "M_K_CPU1_SB_CB<2>")
	)
	(arc
		(start 144.795748 -272.948908)
		(mid 144.979256 -272.903414)
		(end 145.161508 -272.953734)
		(width 0.0889)
		(layer "In6.Cu")
		(net "M_K_CPU1_SB_CB<2>")
	)
	(arc
		(start 143.281654 -272.953734)
		(mid 143.56461 -273.029911)
		(end 143.847566 -272.953734)
		(width 0.0889)
		(layer "In6.Cu")
		(net "M_K_CPU1_SB_CB<2>")
	)
	(arc
		(start 143.847566 -272.953734)
		(mid 144.029817 -272.903384)
		(end 144.213326 -272.948908)
		(width 0.0889)
		(layer "In6.Cu")
		(net "M_K_CPU1_SB_CB<2>")
	)
	(arc
		(start 145.161508 -272.953734)
		(mid 145.312657 -273.016149)
		(end 145.474944 -273.036284)
		(width 0.0889)
		(layer "In6.Cu")
		(net "M_K_CPU1_SB_CB<2>")
	)
	(arc
		(start 145.474944 -273.036284)
		(mid 145.70988 -272.989552)
		(end 145.90903 -272.856452)
		(width 0.0889)
		(layer "In6.Cu")
		(net "M_K_CPU1_SB_CB<2>")
	)
	(arc
		(start 144.232122 -272.95983)
		(mid 144.510554 -273.029928)
		(end 144.787366 -272.953734)
		(width 0.0889)
		(layer "In6.Cu")
		(net "M_K_CPU1_SB_CB<2>")
	)
	(arc
		(start 142.963138 -272.927572)
		(mid 143.125327 -272.904837)
		(end 143.281654 -272.953734)
		(width 0.0889)
		(layer "In6.Cu")
		(net "M_K_CPU1_SB_CB<2>")
	)
	(segment
		(start 140.748004 -273.010376)
		(end 141.214856 -273.276314)
		(width 0.10668)
		(layer "F.Cu")
		(net "M_K_CPU1_SB_CB<1>")
	)
	(segment
		(start 147.029678 -272.149824)
		(end 147.27301 -272.149824)
		(width 0.0889)
		(layer "In6.Cu")
		(net "M_K_CPU1_SB_CB<1>")
	)
	(segment
		(start 165.537896 -280.21026)
		(end 167.589708 -279.360376)
		(width 0.14478)
		(layer "In6.Cu")
		(net "M_K_CPU1_SB_CB<1>")
	)
	(segment
		(start 167.589708 -279.360376)
		(end 169.670476 -279.360376)
		(width 0.14478)
		(layer "In6.Cu")
		(net "M_K_CPU1_SB_CB<1>")
	)
	(segment
		(start 189.765686 -279.360376)
		(end 196.567806 -279.360376)
		(width 0.14478)
		(layer "In6.Cu")
		(net "M_K_CPU1_SB_CB<1>")
	)
	(segment
		(start 147.27301 -272.149824)
		(end 147.49399 -271.928844)
		(width 0.0889)
		(layer "In6.Cu")
		(net "M_K_CPU1_SB_CB<1>")
	)
	(segment
		(start 180.780436 -280.21026)
		(end 181.63032 -279.360376)
		(width 0.14478)
		(layer "In6.Cu")
		(net "M_K_CPU1_SB_CB<1>")
	)
	(segment
		(start 141.214856 -273.276314)
		(end 141.36878 -273.541744)
		(width 0.0889)
		(layer "In6.Cu")
		(net "M_K_CPU1_SB_CB<1>")
	)
	(segment
		(start 145.680938 -273.498564)
		(end 147.029678 -272.149824)
		(width 0.0889)
		(layer "In6.Cu")
		(net "M_K_CPU1_SB_CB<1>")
	)
	(segment
		(start 169.670476 -279.360376)
		(end 171.722288 -280.21026)
		(width 0.14478)
		(layer "In6.Cu")
		(net "M_K_CPU1_SB_CB<1>")
	)
	(segment
		(start 148.014436 -271.928844)
		(end 155.980384 -271.928844)
		(width 0.14478)
		(layer "In6.Cu")
		(net "M_K_CPU1_SB_CB<1>")
	)
	(segment
		(start 159.852614 -276.617938)
		(end 163.444936 -280.21026)
		(width 0.14478)
		(layer "In6.Cu")
		(net "M_K_CPU1_SB_CB<1>")
	)
	(segment
		(start 145.161508 -273.598894)
		(end 145.324576 -273.498564)
		(width 0.0889)
		(layer "In6.Cu")
		(net "M_K_CPU1_SB_CB<1>")
	)
	(segment
		(start 186.83986 -280.21026)
		(end 187.713874 -280.21026)
		(width 0.14478)
		(layer "In6.Cu")
		(net "M_K_CPU1_SB_CB<1>")
	)
	(segment
		(start 179.21097 -280.21026)
		(end 180.780436 -280.21026)
		(width 0.14478)
		(layer "In6.Cu")
		(net "M_K_CPU1_SB_CB<1>")
	)
	(segment
		(start 196.567806 -279.360376)
		(end 198.7042 -279.785318)
		(width 0.14478)
		(layer "In6.Cu")
		(net "M_K_CPU1_SB_CB<1>")
	)
	(segment
		(start 181.63032 -279.360376)
		(end 184.788048 -279.360376)
		(width 0.14478)
		(layer "In6.Cu")
		(net "M_K_CPU1_SB_CB<1>")
	)
	(segment
		(start 145.324576 -273.498564)
		(end 145.680938 -273.498564)
		(width 0.0889)
		(layer "In6.Cu")
		(net "M_K_CPU1_SB_CB<1>")
	)
	(segment
		(start 159.852614 -275.801074)
		(end 159.852614 -276.617938)
		(width 0.14478)
		(layer "In6.Cu")
		(net "M_K_CPU1_SB_CB<1>")
	)
	(segment
		(start 187.713874 -280.21026)
		(end 189.765686 -279.360376)
		(width 0.14478)
		(layer "In6.Cu")
		(net "M_K_CPU1_SB_CB<1>")
	)
	(segment
		(start 144.20977 -273.605752)
		(end 144.221454 -273.598894)
		(width 0.0889)
		(layer "In6.Cu")
		(net "M_K_CPU1_SB_CB<1>")
	)
	(segment
		(start 144.221454 -273.598894)
		(end 144.231868 -273.592798)
		(width 0.0889)
		(layer "In6.Cu")
		(net "M_K_CPU1_SB_CB<1>")
	)
	(segment
		(start 141.967712 -273.598894)
		(end 141.976094 -273.60372)
		(width 0.0889)
		(layer "In6.Cu")
		(net "M_K_CPU1_SB_CB<1>")
	)
	(segment
		(start 155.980384 -271.928844)
		(end 159.852614 -275.801074)
		(width 0.14478)
		(layer "In6.Cu")
		(net "M_K_CPU1_SB_CB<1>")
	)
	(segment
		(start 184.788048 -279.360376)
		(end 186.83986 -280.21026)
		(width 0.14478)
		(layer "In6.Cu")
		(net "M_K_CPU1_SB_CB<1>")
	)
	(segment
		(start 171.722288 -280.21026)
		(end 172.933614 -280.21026)
		(width 0.14478)
		(layer "In6.Cu")
		(net "M_K_CPU1_SB_CB<1>")
	)
	(segment
		(start 163.444936 -280.21026)
		(end 165.537896 -280.21026)
		(width 0.14478)
		(layer "In6.Cu")
		(net "M_K_CPU1_SB_CB<1>")
	)
	(segment
		(start 177.159158 -279.360376)
		(end 179.21097 -280.21026)
		(width 0.14478)
		(layer "In6.Cu")
		(net "M_K_CPU1_SB_CB<1>")
	)
	(segment
		(start 144.787112 -273.598894)
		(end 144.798796 -273.605752)
		(width 0.0889)
		(layer "In6.Cu")
		(net "M_K_CPU1_SB_CB<1>")
	)
	(segment
		(start 174.985426 -279.360376)
		(end 177.159158 -279.360376)
		(width 0.14478)
		(layer "In6.Cu")
		(net "M_K_CPU1_SB_CB<1>")
	)
	(segment
		(start 147.49399 -271.928844)
		(end 148.014436 -271.928844)
		(width 0.0889)
		(layer "In6.Cu")
		(net "M_K_CPU1_SB_CB<1>")
	)
	(segment
		(start 141.36878 -273.541744)
		(end 141.464792 -273.567144)
		(width 0.0889)
		(layer "In6.Cu")
		(net "M_K_CPU1_SB_CB<1>")
	)
	(segment
		(start 172.933614 -280.21026)
		(end 174.985426 -279.360376)
		(width 0.14478)
		(layer "In6.Cu")
		(net "M_K_CPU1_SB_CB<1>")
	)
	(arc
		(start 143.847566 -273.598894)
		(mid 144.027771 -273.649211)
		(end 144.20977 -273.605752)
		(width 0.0889)
		(layer "In6.Cu")
		(net "M_K_CPU1_SB_CB<1>")
	)
	(arc
		(start 144.798796 -273.605752)
		(mid 144.981051 -273.649405)
		(end 145.161508 -273.598894)
		(width 0.0889)
		(layer "In6.Cu")
		(net "M_K_CPU1_SB_CB<1>")
	)
	(arc
		(start 142.907766 -273.598894)
		(mid 143.09471 -273.649149)
		(end 143.281654 -273.598894)
		(width 0.0889)
		(layer "In6.Cu")
		(net "M_K_CPU1_SB_CB<1>")
	)
	(arc
		(start 142.341854 -273.598894)
		(mid 142.62481 -273.522717)
		(end 142.907766 -273.598894)
		(width 0.0889)
		(layer "In6.Cu")
		(net "M_K_CPU1_SB_CB<1>")
	)
	(arc
		(start 143.281654 -273.598894)
		(mid 143.56461 -273.522717)
		(end 143.847566 -273.598894)
		(width 0.0889)
		(layer "In6.Cu")
		(net "M_K_CPU1_SB_CB<1>")
	)
	(arc
		(start 141.976094 -273.60372)
		(mid 142.159602 -273.649214)
		(end 142.341854 -273.598894)
		(width 0.0889)
		(layer "In6.Cu")
		(net "M_K_CPU1_SB_CB<1>")
	)
	(arc
		(start 141.464792 -273.567144)
		(mid 141.72 -273.523667)
		(end 141.967712 -273.598894)
		(width 0.0889)
		(layer "In6.Cu")
		(net "M_K_CPU1_SB_CB<1>")
	)
	(arc
		(start 144.231868 -273.592798)
		(mid 144.5103 -273.5227)
		(end 144.787112 -273.598894)
		(width 0.0889)
		(layer "In6.Cu")
		(net "M_K_CPU1_SB_CB<1>")
	)
	(segment
		(start 142.157958 -272.20037)
		(end 142.62481 -272.466308)
		(width 0.10668)
		(layer "F.Cu")
		(net "M_K_CPU1_SB_CB<0>")
	)
	(segment
		(start 145.877026 -272.556478)
		(end 145.877026 -272.012664)
		(width 0.0889)
		(layer "In6.Cu")
		(net "M_K_CPU1_SB_CB<0>")
	)
	(segment
		(start 197.716648 -278.157686)
		(end 197.716648 -277.814278)
		(width 0.14478)
		(layer "In6.Cu")
		(net "M_K_CPU1_SB_CB<0>")
	)
	(segment
		(start 144.691354 -272.788888)
		(end 144.701768 -272.782792)
		(width 0.0889)
		(layer "In6.Cu")
		(net "M_K_CPU1_SB_CB<0>")
	)
	(segment
		(start 166.963598 -277.669752)
		(end 170.23207 -277.669752)
		(width 0.14478)
		(layer "In6.Cu")
		(net "M_K_CPU1_SB_CB<0>")
	)
	(segment
		(start 197.165214 -278.157686)
		(end 197.309994 -278.302466)
		(width 0.14478)
		(layer "In6.Cu")
		(net "M_K_CPU1_SB_CB<0>")
	)
	(segment
		(start 181.150514 -278.519636)
		(end 182.000398 -277.669752)
		(width 0.14478)
		(layer "In6.Cu")
		(net "M_K_CPU1_SB_CB<0>")
	)
	(segment
		(start 184.970674 -277.669752)
		(end 185.820558 -278.519636)
		(width 0.14478)
		(layer "In6.Cu")
		(net "M_K_CPU1_SB_CB<0>")
	)
	(segment
		(start 189.529466 -277.669498)
		(end 197.020434 -277.669498)
		(width 0.14478)
		(layer "In6.Cu")
		(net "M_K_CPU1_SB_CB<0>")
	)
	(segment
		(start 197.020434 -277.669498)
		(end 197.165214 -277.814278)
		(width 0.14478)
		(layer "In6.Cu")
		(net "M_K_CPU1_SB_CB<0>")
	)
	(segment
		(start 142.62481 -272.466308)
		(end 142.778734 -272.731738)
		(width 0.0889)
		(layer "In6.Cu")
		(net "M_K_CPU1_SB_CB<0>")
	)
	(segment
		(start 170.23207 -277.669752)
		(end 171.081954 -278.519636)
		(width 0.14478)
		(layer "In6.Cu")
		(net "M_K_CPU1_SB_CB<0>")
	)
	(segment
		(start 198.288402 -277.669498)
		(end 198.7042 -278.085296)
		(width 0.14478)
		(layer "In6.Cu")
		(net "M_K_CPU1_SB_CB<0>")
	)
	(segment
		(start 156.59354 -271.019524)
		(end 164.084254 -278.510238)
		(width 0.14478)
		(layer "In6.Cu")
		(net "M_K_CPU1_SB_CB<0>")
	)
	(segment
		(start 144.307052 -272.782792)
		(end 144.317466 -272.788888)
		(width 0.0889)
		(layer "In6.Cu")
		(net "M_K_CPU1_SB_CB<0>")
	)
	(segment
		(start 188.679328 -278.519636)
		(end 189.529466 -277.669498)
		(width 0.14478)
		(layer "In6.Cu")
		(net "M_K_CPU1_SB_CB<0>")
	)
	(segment
		(start 145.710656 -272.722848)
		(end 145.877026 -272.556478)
		(width 0.0889)
		(layer "In6.Cu")
		(net "M_K_CPU1_SB_CB<0>")
	)
	(segment
		(start 174.62754 -277.669752)
		(end 177.457608 -277.669752)
		(width 0.14478)
		(layer "In6.Cu")
		(net "M_K_CPU1_SB_CB<0>")
	)
	(segment
		(start 197.716648 -277.814278)
		(end 197.861428 -277.669498)
		(width 0.14478)
		(layer "In6.Cu")
		(net "M_K_CPU1_SB_CB<0>")
	)
	(segment
		(start 185.820558 -278.519636)
		(end 188.679328 -278.519636)
		(width 0.14478)
		(layer "In6.Cu")
		(net "M_K_CPU1_SB_CB<0>")
	)
	(segment
		(start 182.000398 -277.669752)
		(end 184.970674 -277.669752)
		(width 0.14478)
		(layer "In6.Cu")
		(net "M_K_CPU1_SB_CB<0>")
	)
	(segment
		(start 197.309994 -278.302466)
		(end 197.571868 -278.302466)
		(width 0.14478)
		(layer "In6.Cu")
		(net "M_K_CPU1_SB_CB<0>")
	)
	(segment
		(start 197.571868 -278.302466)
		(end 197.716648 -278.157686)
		(width 0.14478)
		(layer "In6.Cu")
		(net "M_K_CPU1_SB_CB<0>")
	)
	(segment
		(start 178.307492 -278.519636)
		(end 181.150514 -278.519636)
		(width 0.14478)
		(layer "In6.Cu")
		(net "M_K_CPU1_SB_CB<0>")
	)
	(segment
		(start 145.877026 -272.012664)
		(end 146.870166 -271.019524)
		(width 0.0889)
		(layer "In6.Cu")
		(net "M_K_CPU1_SB_CB<0>")
	)
	(segment
		(start 143.377666 -272.788888)
		(end 143.386048 -272.793714)
		(width 0.0889)
		(layer "In6.Cu")
		(net "M_K_CPU1_SB_CB<0>")
	)
	(segment
		(start 166.123112 -278.510238)
		(end 166.963598 -277.669752)
		(width 0.14478)
		(layer "In6.Cu")
		(net "M_K_CPU1_SB_CB<0>")
	)
	(segment
		(start 142.778734 -272.731738)
		(end 142.874746 -272.757138)
		(width 0.0889)
		(layer "In6.Cu")
		(net "M_K_CPU1_SB_CB<0>")
	)
	(segment
		(start 164.084254 -278.510238)
		(end 166.123112 -278.510238)
		(width 0.14478)
		(layer "In6.Cu")
		(net "M_K_CPU1_SB_CB<0>")
	)
	(segment
		(start 197.165214 -277.814278)
		(end 197.165214 -278.157686)
		(width 0.14478)
		(layer "In6.Cu")
		(net "M_K_CPU1_SB_CB<0>")
	)
	(segment
		(start 197.861428 -277.669498)
		(end 198.288402 -277.669498)
		(width 0.14478)
		(layer "In6.Cu")
		(net "M_K_CPU1_SB_CB<0>")
	)
	(segment
		(start 173.777656 -278.519636)
		(end 174.62754 -277.669752)
		(width 0.14478)
		(layer "In6.Cu")
		(net "M_K_CPU1_SB_CB<0>")
	)
	(segment
		(start 177.457608 -277.669752)
		(end 178.307492 -278.519636)
		(width 0.14478)
		(layer "In6.Cu")
		(net "M_K_CPU1_SB_CB<0>")
	)
	(segment
		(start 171.081954 -278.519636)
		(end 173.777656 -278.519636)
		(width 0.14478)
		(layer "In6.Cu")
		(net "M_K_CPU1_SB_CB<0>")
	)
	(segment
		(start 146.870166 -271.019524)
		(end 147.974558 -271.019524)
		(width 0.0889)
		(layer "In6.Cu")
		(net "M_K_CPU1_SB_CB<0>")
	)
	(segment
		(start 147.974558 -271.019524)
		(end 156.59354 -271.019524)
		(width 0.14478)
		(layer "In6.Cu")
		(net "M_K_CPU1_SB_CB<0>")
	)
	(arc
		(start 143.386048 -272.793714)
		(mid 143.569556 -272.839208)
		(end 143.751808 -272.788888)
		(width 0.0889)
		(layer "In6.Cu")
		(net "M_K_CPU1_SB_CB<0>")
	)
	(arc
		(start 145.25752 -272.788888)
		(mid 145.437725 -272.839205)
		(end 145.619724 -272.795746)
		(width 0.0889)
		(layer "In6.Cu")
		(net "M_K_CPU1_SB_CB<0>")
	)
	(arc
		(start 142.874746 -272.757138)
		(mid 143.129954 -272.713661)
		(end 143.377666 -272.788888)
		(width 0.0889)
		(layer "In6.Cu")
		(net "M_K_CPU1_SB_CB<0>")
	)
	(arc
		(start 144.701768 -272.782792)
		(mid 144.980454 -272.712572)
		(end 145.25752 -272.788888)
		(width 0.0889)
		(layer "In6.Cu")
		(net "M_K_CPU1_SB_CB<0>")
	)
	(arc
		(start 143.751808 -272.788888)
		(mid 144.028621 -272.712745)
		(end 144.307052 -272.782792)
		(width 0.0889)
		(layer "In6.Cu")
		(net "M_K_CPU1_SB_CB<0>")
	)
	(arc
		(start 145.619724 -272.795746)
		(mid 145.6686 -272.763554)
		(end 145.710656 -272.722848)
		(width 0.0889)
		(layer "In6.Cu")
		(net "M_K_CPU1_SB_CB<0>")
	)
	(arc
		(start 144.317466 -272.788888)
		(mid 144.50441 -272.839143)
		(end 144.691354 -272.788888)
		(width 0.0889)
		(layer "In6.Cu")
		(net "M_K_CPU1_SB_CB<0>")
	)
	(segment
		(start 142.157958 -264.10031)
		(end 142.62481 -264.366248)
		(width 0.10668)
		(layer "F.Cu")
		(net "M_K_CPU1_SB_CA<6>")
	)
	(segment
		(start 181.331108 -266.610338)
		(end 182.180992 -265.760454)
		(width 0.14478)
		(layer "In6.Cu")
		(net "M_K_CPU1_SB_CA<6>")
	)
	(segment
		(start 165.893496 -265.760454)
		(end 170.762676 -265.760454)
		(width 0.14478)
		(layer "In6.Cu")
		(net "M_K_CPU1_SB_CA<6>")
	)
	(segment
		(start 142.778734 -264.631678)
		(end 142.874746 -264.657078)
		(width 0.0889)
		(layer "In6.Cu")
		(net "M_K_CPU1_SB_CA<6>")
	)
	(segment
		(start 171.61256 -266.610338)
		(end 173.787054 -266.610338)
		(width 0.14478)
		(layer "In6.Cu")
		(net "M_K_CPU1_SB_CA<6>")
	)
	(segment
		(start 161.8234 -264.339324)
		(end 164.094414 -266.610338)
		(width 0.14478)
		(layer "In6.Cu")
		(net "M_K_CPU1_SB_CA<6>")
	)
	(segment
		(start 143.377666 -264.688828)
		(end 143.386048 -264.693654)
		(width 0.0889)
		(layer "In6.Cu")
		(net "M_K_CPU1_SB_CA<6>")
	)
	(segment
		(start 198.279258 -265.760454)
		(end 198.7042 -266.185396)
		(width 0.14478)
		(layer "In6.Cu")
		(net "M_K_CPU1_SB_CA<6>")
	)
	(segment
		(start 170.762676 -265.760454)
		(end 171.61256 -266.610338)
		(width 0.14478)
		(layer "In6.Cu")
		(net "M_K_CPU1_SB_CA<6>")
	)
	(segment
		(start 148.014436 -264.339324)
		(end 161.8234 -264.339324)
		(width 0.14478)
		(layer "In6.Cu")
		(net "M_K_CPU1_SB_CA<6>")
	)
	(segment
		(start 144.307052 -264.682732)
		(end 144.317466 -264.688828)
		(width 0.0889)
		(layer "In6.Cu")
		(net "M_K_CPU1_SB_CA<6>")
	)
	(segment
		(start 174.636938 -265.760454)
		(end 178.40833 -265.760454)
		(width 0.14478)
		(layer "In6.Cu")
		(net "M_K_CPU1_SB_CA<6>")
	)
	(segment
		(start 182.180992 -265.760454)
		(end 198.279258 -265.760454)
		(width 0.14478)
		(layer "In6.Cu")
		(net "M_K_CPU1_SB_CA<6>")
	)
	(segment
		(start 142.62481 -264.366248)
		(end 142.778734 -264.631678)
		(width 0.0889)
		(layer "In6.Cu")
		(net "M_K_CPU1_SB_CA<6>")
	)
	(segment
		(start 164.094414 -266.610338)
		(end 165.043612 -266.610338)
		(width 0.14478)
		(layer "In6.Cu")
		(net "M_K_CPU1_SB_CA<6>")
	)
	(segment
		(start 165.043612 -266.610338)
		(end 165.893496 -265.760454)
		(width 0.14478)
		(layer "In6.Cu")
		(net "M_K_CPU1_SB_CA<6>")
	)
	(segment
		(start 173.787054 -266.610338)
		(end 174.636938 -265.760454)
		(width 0.14478)
		(layer "In6.Cu")
		(net "M_K_CPU1_SB_CA<6>")
	)
	(segment
		(start 179.258214 -266.610338)
		(end 181.331108 -266.610338)
		(width 0.14478)
		(layer "In6.Cu")
		(net "M_K_CPU1_SB_CA<6>")
	)
	(segment
		(start 146.065494 -264.339324)
		(end 148.014436 -264.339324)
		(width 0.0889)
		(layer "In6.Cu")
		(net "M_K_CPU1_SB_CA<6>")
	)
	(segment
		(start 144.691354 -264.688828)
		(end 144.701768 -264.682732)
		(width 0.0889)
		(layer "In6.Cu")
		(net "M_K_CPU1_SB_CA<6>")
	)
	(segment
		(start 145.69059 -264.65784)
		(end 145.969228 -264.379202)
		(width 0.0889)
		(layer "In6.Cu")
		(net "M_K_CPU1_SB_CA<6>")
	)
	(segment
		(start 178.40833 -265.760454)
		(end 179.258214 -266.610338)
		(width 0.14478)
		(layer "In6.Cu")
		(net "M_K_CPU1_SB_CA<6>")
	)
	(arc
		(start 143.386048 -264.693654)
		(mid 143.569556 -264.739148)
		(end 143.751808 -264.688828)
		(width 0.0889)
		(layer "In6.Cu")
		(net "M_K_CPU1_SB_CA<6>")
	)
	(arc
		(start 145.25752 -264.688828)
		(mid 145.336147 -264.721585)
		(end 145.420588 -264.73277)
		(width 0.0889)
		(layer "In6.Cu")
		(net "M_K_CPU1_SB_CA<6>")
	)
	(arc
		(start 142.874746 -264.657078)
		(mid 143.129954 -264.613601)
		(end 143.377666 -264.688828)
		(width 0.0889)
		(layer "In6.Cu")
		(net "M_K_CPU1_SB_CA<6>")
	)
	(arc
		(start 145.420588 -264.73277)
		(mid 145.513026 -264.727417)
		(end 145.60423 -264.711434)
		(width 0.0889)
		(layer "In6.Cu")
		(net "M_K_CPU1_SB_CA<6>")
	)
	(arc
		(start 144.317466 -264.688828)
		(mid 144.50441 -264.739083)
		(end 144.691354 -264.688828)
		(width 0.0889)
		(layer "In6.Cu")
		(net "M_K_CPU1_SB_CA<6>")
	)
	(arc
		(start 143.751808 -264.688828)
		(mid 144.028621 -264.612685)
		(end 144.307052 -264.682732)
		(width 0.0889)
		(layer "In6.Cu")
		(net "M_K_CPU1_SB_CA<6>")
	)
	(arc
		(start 145.969228 -264.379202)
		(mid 146.013395 -264.34969)
		(end 146.065494 -264.339324)
		(width 0.0889)
		(layer "In6.Cu")
		(net "M_K_CPU1_SB_CA<6>")
	)
	(arc
		(start 144.701768 -264.682732)
		(mid 144.980454 -264.612512)
		(end 145.25752 -264.688828)
		(width 0.0889)
		(layer "In6.Cu")
		(net "M_K_CPU1_SB_CA<6>")
	)
	(arc
		(start 145.60423 -264.711434)
		(mid 145.651803 -264.691709)
		(end 145.69059 -264.65784)
		(width 0.0889)
		(layer "In6.Cu")
		(net "M_K_CPU1_SB_CA<6>")
	)
	(segment
		(start 141.217904 -264.10031)
		(end 141.684756 -264.366248)
		(width 0.10668)
		(layer "F.Cu")
		(net "M_K_CPU1_SB_CA<5>")
	)
	(segment
		(start 179.246276 -265.760454)
		(end 181.238144 -265.760454)
		(width 0.14478)
		(layer "In6.Cu")
		(net "M_K_CPU1_SB_CA<5>")
	)
	(segment
		(start 147.354544 -263.993122)
		(end 147.463002 -263.884664)
		(width 0.0889)
		(layer "In6.Cu")
		(net "M_K_CPU1_SB_CA<5>")
	)
	(segment
		(start 174.544228 -264.910316)
		(end 178.396138 -264.910316)
		(width 0.14478)
		(layer "In6.Cu")
		(net "M_K_CPU1_SB_CA<5>")
	)
	(segment
		(start 182.088282 -264.910316)
		(end 188.038486 -264.910316)
		(width 0.14478)
		(layer "In6.Cu")
		(net "M_K_CPU1_SB_CA<5>")
	)
	(segment
		(start 144.317466 -264.043668)
		(end 144.325848 -264.038842)
		(width 0.0889)
		(layer "In6.Cu")
		(net "M_K_CPU1_SB_CA<5>")
	)
	(segment
		(start 170.725084 -264.910316)
		(end 171.575222 -265.760454)
		(width 0.14478)
		(layer "In6.Cu")
		(net "M_K_CPU1_SB_CA<5>")
	)
	(segment
		(start 165.106096 -265.760454)
		(end 165.956234 -264.910316)
		(width 0.14478)
		(layer "In6.Cu")
		(net "M_K_CPU1_SB_CA<5>")
	)
	(segment
		(start 188.758068 -265.131296)
		(end 188.758068 -264.689336)
		(width 0.14478)
		(layer "In6.Cu")
		(net "M_K_CPU1_SB_CA<5>")
	)
	(segment
		(start 188.364622 -265.294364)
		(end 188.595 -265.294364)
		(width 0.14478)
		(layer "In6.Cu")
		(net "M_K_CPU1_SB_CA<5>")
	)
	(segment
		(start 188.921136 -264.526268)
		(end 189.151514 -264.526268)
		(width 0.14478)
		(layer "In6.Cu")
		(net "M_K_CPU1_SB_CA<5>")
	)
	(segment
		(start 194.17919 -264.910316)
		(end 194.604132 -265.335258)
		(width 0.14478)
		(layer "In6.Cu")
		(net "M_K_CPU1_SB_CA<5>")
	)
	(segment
		(start 189.151514 -264.526268)
		(end 189.314582 -264.689336)
		(width 0.14478)
		(layer "In6.Cu")
		(net "M_K_CPU1_SB_CA<5>")
	)
	(segment
		(start 165.956234 -264.910316)
		(end 170.725084 -264.910316)
		(width 0.14478)
		(layer "In6.Cu")
		(net "M_K_CPU1_SB_CA<5>")
	)
	(segment
		(start 189.708028 -265.294364)
		(end 189.871096 -265.131296)
		(width 0.14478)
		(layer "In6.Cu")
		(net "M_K_CPU1_SB_CA<5>")
	)
	(segment
		(start 145.344134 -263.993122)
		(end 147.354544 -263.993122)
		(width 0.0889)
		(layer "In6.Cu")
		(net "M_K_CPU1_SB_CA<5>")
	)
	(segment
		(start 162.28314 -263.884664)
		(end 164.15893 -265.760454)
		(width 0.14478)
		(layer "In6.Cu")
		(net "M_K_CPU1_SB_CA<5>")
	)
	(segment
		(start 188.595 -265.294364)
		(end 188.758068 -265.131296)
		(width 0.14478)
		(layer "In6.Cu")
		(net "M_K_CPU1_SB_CA<5>")
	)
	(segment
		(start 189.47765 -265.294364)
		(end 189.708028 -265.294364)
		(width 0.14478)
		(layer "In6.Cu")
		(net "M_K_CPU1_SB_CA<5>")
	)
	(segment
		(start 144.6911 -264.043668)
		(end 144.701514 -264.049764)
		(width 0.0889)
		(layer "In6.Cu")
		(net "M_K_CPU1_SB_CA<5>")
	)
	(segment
		(start 189.314582 -264.689336)
		(end 189.314582 -265.131296)
		(width 0.14478)
		(layer "In6.Cu")
		(net "M_K_CPU1_SB_CA<5>")
	)
	(segment
		(start 147.463002 -263.884664)
		(end 148.037296 -263.884664)
		(width 0.0889)
		(layer "In6.Cu")
		(net "M_K_CPU1_SB_CA<5>")
	)
	(segment
		(start 188.201554 -265.073384)
		(end 188.201554 -265.131296)
		(width 0.14478)
		(layer "In6.Cu")
		(net "M_K_CPU1_SB_CA<5>")
	)
	(segment
		(start 173.69409 -265.760454)
		(end 174.544228 -264.910316)
		(width 0.14478)
		(layer "In6.Cu")
		(net "M_K_CPU1_SB_CA<5>")
	)
	(segment
		(start 144.307052 -264.049764)
		(end 144.317466 -264.043668)
		(width 0.0889)
		(layer "In6.Cu")
		(net "M_K_CPU1_SB_CA<5>")
	)
	(segment
		(start 189.871096 -265.073384)
		(end 190.034164 -264.910316)
		(width 0.14478)
		(layer "In6.Cu")
		(net "M_K_CPU1_SB_CA<5>")
	)
	(segment
		(start 190.034164 -264.910316)
		(end 194.17919 -264.910316)
		(width 0.14478)
		(layer "In6.Cu")
		(net "M_K_CPU1_SB_CA<5>")
	)
	(segment
		(start 188.201554 -265.131296)
		(end 188.364622 -265.294364)
		(width 0.14478)
		(layer "In6.Cu")
		(net "M_K_CPU1_SB_CA<5>")
	)
	(segment
		(start 148.037296 -263.884664)
		(end 162.28314 -263.884664)
		(width 0.14478)
		(layer "In6.Cu")
		(net "M_K_CPU1_SB_CA<5>")
	)
	(segment
		(start 141.530832 -264.100818)
		(end 141.553184 -264.017506)
		(width 0.0889)
		(layer "In6.Cu")
		(net "M_K_CPU1_SB_CA<5>")
	)
	(segment
		(start 164.15893 -265.760454)
		(end 165.106096 -265.760454)
		(width 0.14478)
		(layer "In6.Cu")
		(net "M_K_CPU1_SB_CA<5>")
	)
	(segment
		(start 171.575222 -265.760454)
		(end 173.69409 -265.760454)
		(width 0.14478)
		(layer "In6.Cu")
		(net "M_K_CPU1_SB_CA<5>")
	)
	(segment
		(start 181.238144 -265.760454)
		(end 182.088282 -264.910316)
		(width 0.14478)
		(layer "In6.Cu")
		(net "M_K_CPU1_SB_CA<5>")
	)
	(segment
		(start 143.377666 -264.043668)
		(end 143.386048 -264.038842)
		(width 0.0889)
		(layer "In6.Cu")
		(net "M_K_CPU1_SB_CA<5>")
	)
	(segment
		(start 178.396138 -264.910316)
		(end 179.246276 -265.760454)
		(width 0.14478)
		(layer "In6.Cu")
		(net "M_K_CPU1_SB_CA<5>")
	)
	(segment
		(start 188.758068 -264.689336)
		(end 188.921136 -264.526268)
		(width 0.14478)
		(layer "In6.Cu")
		(net "M_K_CPU1_SB_CA<5>")
	)
	(segment
		(start 141.684756 -264.366248)
		(end 141.530832 -264.100818)
		(width 0.0889)
		(layer "In6.Cu")
		(net "M_K_CPU1_SB_CA<5>")
	)
	(segment
		(start 189.314582 -265.131296)
		(end 189.47765 -265.294364)
		(width 0.14478)
		(layer "In6.Cu")
		(net "M_K_CPU1_SB_CA<5>")
	)
	(segment
		(start 189.871096 -265.131296)
		(end 189.871096 -265.073384)
		(width 0.14478)
		(layer "In6.Cu")
		(net "M_K_CPU1_SB_CA<5>")
	)
	(segment
		(start 142.803372 -264.038842)
		(end 142.811754 -264.043668)
		(width 0.0889)
		(layer "In6.Cu")
		(net "M_K_CPU1_SB_CA<5>")
	)
	(segment
		(start 188.038486 -264.910316)
		(end 188.201554 -265.073384)
		(width 0.14478)
		(layer "In6.Cu")
		(net "M_K_CPU1_SB_CA<5>")
	)
	(segment
		(start 145.257266 -264.043668)
		(end 145.344134 -263.993122)
		(width 0.0889)
		(layer "In6.Cu")
		(net "M_K_CPU1_SB_CA<5>")
	)
	(arc
		(start 143.386048 -264.038842)
		(mid 143.569556 -263.993348)
		(end 143.751808 -264.043668)
		(width 0.0889)
		(layer "In6.Cu")
		(net "M_K_CPU1_SB_CA<5>")
	)
	(arc
		(start 142.811754 -264.043668)
		(mid 143.09471 -264.119845)
		(end 143.377666 -264.043668)
		(width 0.0889)
		(layer "In6.Cu")
		(net "M_K_CPU1_SB_CA<5>")
	)
	(arc
		(start 144.325848 -264.038842)
		(mid 144.509102 -263.993469)
		(end 144.6911 -264.043668)
		(width 0.0889)
		(layer "In6.Cu")
		(net "M_K_CPU1_SB_CA<5>")
	)
	(arc
		(start 141.8717 -264.043668)
		(mid 142.154656 -264.119845)
		(end 142.437612 -264.043668)
		(width 0.0889)
		(layer "In6.Cu")
		(net "M_K_CPU1_SB_CA<5>")
	)
	(arc
		(start 144.701514 -264.049764)
		(mid 144.9802 -264.119984)
		(end 145.257266 -264.043668)
		(width 0.0889)
		(layer "In6.Cu")
		(net "M_K_CPU1_SB_CA<5>")
	)
	(arc
		(start 141.553184 -264.017506)
		(mid 141.715373 -263.994771)
		(end 141.8717 -264.043668)
		(width 0.0889)
		(layer "In6.Cu")
		(net "M_K_CPU1_SB_CA<5>")
	)
	(arc
		(start 142.437612 -264.043668)
		(mid 142.619863 -263.993318)
		(end 142.803372 -264.038842)
		(width 0.0889)
		(layer "In6.Cu")
		(net "M_K_CPU1_SB_CA<5>")
	)
	(arc
		(start 143.751808 -264.043668)
		(mid 144.028621 -264.119811)
		(end 144.307052 -264.049764)
		(width 0.0889)
		(layer "In6.Cu")
		(net "M_K_CPU1_SB_CA<5>")
	)
	(segment
		(start 140.748004 -263.290304)
		(end 141.214856 -263.556242)
		(width 0.10668)
		(layer "F.Cu")
		(net "M_K_CPU1_SB_CA<4>")
	)
	(segment
		(start 170.764708 -264.060432)
		(end 171.614592 -264.910316)
		(width 0.14478)
		(layer "In6.Cu")
		(net "M_K_CPU1_SB_CA<4>")
	)
	(segment
		(start 164.965888 -264.910316)
		(end 165.815772 -264.060432)
		(width 0.14478)
		(layer "In6.Cu")
		(net "M_K_CPU1_SB_CA<4>")
	)
	(segment
		(start 179.208938 -264.910316)
		(end 181.331108 -264.910316)
		(width 0.14478)
		(layer "In6.Cu")
		(net "M_K_CPU1_SB_CA<4>")
	)
	(segment
		(start 141.967712 -263.878822)
		(end 141.976094 -263.883648)
		(width 0.0889)
		(layer "In6.Cu")
		(net "M_K_CPU1_SB_CA<4>")
	)
	(segment
		(start 173.787054 -264.910316)
		(end 174.636938 -264.060432)
		(width 0.14478)
		(layer "In6.Cu")
		(net "M_K_CPU1_SB_CA<4>")
	)
	(segment
		(start 174.636938 -264.060432)
		(end 178.359054 -264.060432)
		(width 0.14478)
		(layer "In6.Cu")
		(net "M_K_CPU1_SB_CA<4>")
	)
	(segment
		(start 144.20977 -263.88568)
		(end 144.221454 -263.878822)
		(width 0.0889)
		(layer "In6.Cu")
		(net "M_K_CPU1_SB_CA<4>")
	)
	(segment
		(start 198.279258 -264.060432)
		(end 198.7042 -264.485374)
		(width 0.14478)
		(layer "In6.Cu")
		(net "M_K_CPU1_SB_CA<4>")
	)
	(segment
		(start 163.994338 -264.910316)
		(end 164.965888 -264.910316)
		(width 0.14478)
		(layer "In6.Cu")
		(net "M_K_CPU1_SB_CA<4>")
	)
	(segment
		(start 147.522946 -263.430004)
		(end 148.011642 -263.430004)
		(width 0.0889)
		(layer "In6.Cu")
		(net "M_K_CPU1_SB_CA<4>")
	)
	(segment
		(start 182.180992 -264.060432)
		(end 198.279258 -264.060432)
		(width 0.14478)
		(layer "In6.Cu")
		(net "M_K_CPU1_SB_CA<4>")
	)
	(segment
		(start 171.614592 -264.910316)
		(end 173.787054 -264.910316)
		(width 0.14478)
		(layer "In6.Cu")
		(net "M_K_CPU1_SB_CA<4>")
	)
	(segment
		(start 145.161508 -263.878822)
		(end 145.324576 -263.78408)
		(width 0.0889)
		(layer "In6.Cu")
		(net "M_K_CPU1_SB_CA<4>")
	)
	(segment
		(start 162.514026 -263.430004)
		(end 163.994338 -264.910316)
		(width 0.14478)
		(layer "In6.Cu")
		(net "M_K_CPU1_SB_CA<4>")
	)
	(segment
		(start 148.011642 -263.430004)
		(end 162.514026 -263.430004)
		(width 0.14478)
		(layer "In6.Cu")
		(net "M_K_CPU1_SB_CA<4>")
	)
	(segment
		(start 147.173188 -263.779762)
		(end 147.522946 -263.430004)
		(width 0.0889)
		(layer "In6.Cu")
		(net "M_K_CPU1_SB_CA<4>")
	)
	(segment
		(start 144.787112 -263.878822)
		(end 144.798796 -263.88568)
		(width 0.0889)
		(layer "In6.Cu")
		(net "M_K_CPU1_SB_CA<4>")
	)
	(segment
		(start 141.36878 -263.821672)
		(end 141.464792 -263.847072)
		(width 0.0889)
		(layer "In6.Cu")
		(net "M_K_CPU1_SB_CA<4>")
	)
	(segment
		(start 145.324576 -263.78408)
		(end 145.328894 -263.779762)
		(width 0.0889)
		(layer "In6.Cu")
		(net "M_K_CPU1_SB_CA<4>")
	)
	(segment
		(start 141.214856 -263.556242)
		(end 141.36878 -263.821672)
		(width 0.0889)
		(layer "In6.Cu")
		(net "M_K_CPU1_SB_CA<4>")
	)
	(segment
		(start 178.359054 -264.060432)
		(end 179.208938 -264.910316)
		(width 0.14478)
		(layer "In6.Cu")
		(net "M_K_CPU1_SB_CA<4>")
	)
	(segment
		(start 165.815772 -264.060432)
		(end 170.764708 -264.060432)
		(width 0.14478)
		(layer "In6.Cu")
		(net "M_K_CPU1_SB_CA<4>")
	)
	(segment
		(start 145.328894 -263.779762)
		(end 147.173188 -263.779762)
		(width 0.0889)
		(layer "In6.Cu")
		(net "M_K_CPU1_SB_CA<4>")
	)
	(segment
		(start 144.221454 -263.878822)
		(end 144.231868 -263.872726)
		(width 0.0889)
		(layer "In6.Cu")
		(net "M_K_CPU1_SB_CA<4>")
	)
	(segment
		(start 181.331108 -264.910316)
		(end 182.180992 -264.060432)
		(width 0.14478)
		(layer "In6.Cu")
		(net "M_K_CPU1_SB_CA<4>")
	)
	(arc
		(start 143.281654 -263.878822)
		(mid 143.56461 -263.802645)
		(end 143.847566 -263.878822)
		(width 0.0889)
		(layer "In6.Cu")
		(net "M_K_CPU1_SB_CA<4>")
	)
	(arc
		(start 142.341854 -263.878822)
		(mid 142.62481 -263.802645)
		(end 142.907766 -263.878822)
		(width 0.0889)
		(layer "In6.Cu")
		(net "M_K_CPU1_SB_CA<4>")
	)
	(arc
		(start 144.231868 -263.872726)
		(mid 144.5103 -263.802628)
		(end 144.787112 -263.878822)
		(width 0.0889)
		(layer "In6.Cu")
		(net "M_K_CPU1_SB_CA<4>")
	)
	(arc
		(start 144.798796 -263.88568)
		(mid 144.981051 -263.929333)
		(end 145.161508 -263.878822)
		(width 0.0889)
		(layer "In6.Cu")
		(net "M_K_CPU1_SB_CA<4>")
	)
	(arc
		(start 141.464792 -263.847072)
		(mid 141.72 -263.803595)
		(end 141.967712 -263.878822)
		(width 0.0889)
		(layer "In6.Cu")
		(net "M_K_CPU1_SB_CA<4>")
	)
	(arc
		(start 141.976094 -263.883648)
		(mid 142.159602 -263.929142)
		(end 142.341854 -263.878822)
		(width 0.0889)
		(layer "In6.Cu")
		(net "M_K_CPU1_SB_CA<4>")
	)
	(arc
		(start 143.847566 -263.878822)
		(mid 144.027771 -263.929139)
		(end 144.20977 -263.88568)
		(width 0.0889)
		(layer "In6.Cu")
		(net "M_K_CPU1_SB_CA<4>")
	)
	(arc
		(start 142.907766 -263.878822)
		(mid 143.09471 -263.929077)
		(end 143.281654 -263.878822)
		(width 0.0889)
		(layer "In6.Cu")
		(net "M_K_CPU1_SB_CA<4>")
	)
	(segment
		(start 142.627858 -263.290304)
		(end 143.09471 -263.556242)
		(width 0.10668)
		(layer "F.Cu")
		(net "M_K_CPU1_SB_CA<3>")
	)
	(segment
		(start 190.40729 -263.210294)
		(end 192.303654 -263.210294)
		(width 0.14478)
		(layer "In6.Cu")
		(net "M_K_CPU1_SB_CA<3>")
	)
	(segment
		(start 187.855098 -263.210294)
		(end 188.018166 -263.373362)
		(width 0.14478)
		(layer "In6.Cu")
		(net "M_K_CPU1_SB_CA<3>")
	)
	(segment
		(start 188.57468 -263.429496)
		(end 188.57468 -262.991092)
		(width 0.14478)
		(layer "In6.Cu")
		(net "M_K_CPU1_SB_CA<3>")
	)
	(segment
		(start 188.018166 -263.429496)
		(end 188.181234 -263.592564)
		(width 0.14478)
		(layer "In6.Cu")
		(net "M_K_CPU1_SB_CA<3>")
	)
	(segment
		(start 164.952172 -264.060432)
		(end 165.80231 -263.210294)
		(width 0.14478)
		(layer "In6.Cu")
		(net "M_K_CPU1_SB_CA<3>")
	)
	(segment
		(start 189.294262 -263.592564)
		(end 189.52464 -263.592564)
		(width 0.14478)
		(layer "In6.Cu")
		(net "M_K_CPU1_SB_CA<3>")
	)
	(segment
		(start 185.015632 -263.521444)
		(end 185.260996 -263.521444)
		(width 0.14478)
		(layer "In6.Cu")
		(net "M_K_CPU1_SB_CA<3>")
	)
	(segment
		(start 178.39817 -263.210294)
		(end 179.248308 -264.060432)
		(width 0.14478)
		(layer "In6.Cu")
		(net "M_K_CPU1_SB_CA<3>")
	)
	(segment
		(start 144.787366 -263.233662)
		(end 144.795748 -263.228836)
		(width 0.0889)
		(layer "In6.Cu")
		(net "M_K_CPU1_SB_CA<3>")
	)
	(segment
		(start 146.136106 -262.924544)
		(end 147.583906 -262.924544)
		(width 0.0889)
		(layer "In6.Cu")
		(net "M_K_CPU1_SB_CA<3>")
	)
	(segment
		(start 189.850776 -262.828024)
		(end 190.081154 -262.828024)
		(width 0.14478)
		(layer "In6.Cu")
		(net "M_K_CPU1_SB_CA<3>")
	)
	(segment
		(start 189.687708 -262.991092)
		(end 189.850776 -262.828024)
		(width 0.14478)
		(layer "In6.Cu")
		(net "M_K_CPU1_SB_CA<3>")
	)
	(segment
		(start 189.131194 -263.429496)
		(end 189.294262 -263.592564)
		(width 0.14478)
		(layer "In6.Cu")
		(net "M_K_CPU1_SB_CA<3>")
	)
	(segment
		(start 188.411612 -263.592564)
		(end 188.57468 -263.429496)
		(width 0.14478)
		(layer "In6.Cu")
		(net "M_K_CPU1_SB_CA<3>")
	)
	(segment
		(start 179.248308 -264.060432)
		(end 181.238144 -264.060432)
		(width 0.14478)
		(layer "In6.Cu")
		(net "M_K_CPU1_SB_CA<3>")
	)
	(segment
		(start 145.912586 -263.148064)
		(end 146.136106 -262.924544)
		(width 0.0889)
		(layer "In6.Cu")
		(net "M_K_CPU1_SB_CA<3>")
	)
	(segment
		(start 189.687708 -263.429496)
		(end 189.687708 -262.991092)
		(width 0.14478)
		(layer "In6.Cu")
		(net "M_K_CPU1_SB_CA<3>")
	)
	(segment
		(start 193.171318 -263.210294)
		(end 194.17919 -263.210294)
		(width 0.14478)
		(layer "In6.Cu")
		(net "M_K_CPU1_SB_CA<3>")
	)
	(segment
		(start 173.69409 -264.060432)
		(end 174.544228 -263.210294)
		(width 0.14478)
		(layer "In6.Cu")
		(net "M_K_CPU1_SB_CA<3>")
	)
	(segment
		(start 170.676316 -263.210294)
		(end 171.526454 -264.060432)
		(width 0.14478)
		(layer "In6.Cu")
		(net "M_K_CPU1_SB_CA<3>")
	)
	(segment
		(start 164.122862 -264.060432)
		(end 164.952172 -264.060432)
		(width 0.14478)
		(layer "In6.Cu")
		(net "M_K_CPU1_SB_CA<3>")
	)
	(segment
		(start 188.737748 -262.828024)
		(end 188.968126 -262.828024)
		(width 0.14478)
		(layer "In6.Cu")
		(net "M_K_CPU1_SB_CA<3>")
	)
	(segment
		(start 185.572146 -263.210294)
		(end 187.855098 -263.210294)
		(width 0.14478)
		(layer "In6.Cu")
		(net "M_K_CPU1_SB_CA<3>")
	)
	(segment
		(start 188.181234 -263.592564)
		(end 188.411612 -263.592564)
		(width 0.14478)
		(layer "In6.Cu")
		(net "M_K_CPU1_SB_CA<3>")
	)
	(segment
		(start 174.544228 -263.210294)
		(end 178.39817 -263.210294)
		(width 0.14478)
		(layer "In6.Cu")
		(net "M_K_CPU1_SB_CA<3>")
	)
	(segment
		(start 145.161508 -263.233662)
		(end 145.181828 -263.245346)
		(width 0.0889)
		(layer "In6.Cu")
		(net "M_K_CPU1_SB_CA<3>")
	)
	(segment
		(start 185.260996 -263.521444)
		(end 185.572146 -263.210294)
		(width 0.14478)
		(layer "In6.Cu")
		(net "M_K_CPU1_SB_CA<3>")
	)
	(segment
		(start 192.303654 -263.210294)
		(end 192.614804 -262.899144)
		(width 0.14478)
		(layer "In6.Cu")
		(net "M_K_CPU1_SB_CA<3>")
	)
	(segment
		(start 144.221708 -263.233662)
		(end 144.232122 -263.239758)
		(width 0.0889)
		(layer "In6.Cu")
		(net "M_K_CPU1_SB_CA<3>")
	)
	(segment
		(start 181.238144 -264.060432)
		(end 182.088282 -263.210294)
		(width 0.14478)
		(layer "In6.Cu")
		(net "M_K_CPU1_SB_CA<3>")
	)
	(segment
		(start 147.634706 -262.975344)
		(end 148.02612 -262.975344)
		(width 0.0889)
		(layer "In6.Cu")
		(net "M_K_CPU1_SB_CA<3>")
	)
	(segment
		(start 148.02612 -262.975344)
		(end 163.037774 -262.975344)
		(width 0.14478)
		(layer "In6.Cu")
		(net "M_K_CPU1_SB_CA<3>")
	)
	(segment
		(start 190.244222 -262.991092)
		(end 190.244222 -263.047226)
		(width 0.14478)
		(layer "In6.Cu")
		(net "M_K_CPU1_SB_CA<3>")
	)
	(segment
		(start 190.244222 -263.047226)
		(end 190.40729 -263.210294)
		(width 0.14478)
		(layer "In6.Cu")
		(net "M_K_CPU1_SB_CA<3>")
	)
	(segment
		(start 145.444718 -263.316212)
		(end 145.506694 -263.316212)
		(width 0.0889)
		(layer "In6.Cu")
		(net "M_K_CPU1_SB_CA<3>")
	)
	(segment
		(start 143.09471 -263.556242)
		(end 142.940786 -263.290812)
		(width 0.0889)
		(layer "In6.Cu")
		(net "M_K_CPU1_SB_CA<3>")
	)
	(segment
		(start 184.704482 -263.210294)
		(end 185.015632 -263.521444)
		(width 0.14478)
		(layer "In6.Cu")
		(net "M_K_CPU1_SB_CA<3>")
	)
	(segment
		(start 188.968126 -262.828024)
		(end 189.131194 -262.991092)
		(width 0.14478)
		(layer "In6.Cu")
		(net "M_K_CPU1_SB_CA<3>")
	)
	(segment
		(start 192.860168 -262.899144)
		(end 193.171318 -263.210294)
		(width 0.14478)
		(layer "In6.Cu")
		(net "M_K_CPU1_SB_CA<3>")
	)
	(segment
		(start 188.018166 -263.373362)
		(end 188.018166 -263.429496)
		(width 0.14478)
		(layer "In6.Cu")
		(net "M_K_CPU1_SB_CA<3>")
	)
	(segment
		(start 144.213326 -263.228836)
		(end 144.221708 -263.233662)
		(width 0.0889)
		(layer "In6.Cu")
		(net "M_K_CPU1_SB_CA<3>")
	)
	(segment
		(start 190.081154 -262.828024)
		(end 190.244222 -262.991092)
		(width 0.14478)
		(layer "In6.Cu")
		(net "M_K_CPU1_SB_CA<3>")
	)
	(segment
		(start 163.037774 -262.975344)
		(end 164.122862 -264.060432)
		(width 0.14478)
		(layer "In6.Cu")
		(net "M_K_CPU1_SB_CA<3>")
	)
	(segment
		(start 188.57468 -262.991092)
		(end 188.737748 -262.828024)
		(width 0.14478)
		(layer "In6.Cu")
		(net "M_K_CPU1_SB_CA<3>")
	)
	(segment
		(start 192.614804 -262.899144)
		(end 192.860168 -262.899144)
		(width 0.14478)
		(layer "In6.Cu")
		(net "M_K_CPU1_SB_CA<3>")
	)
	(segment
		(start 182.088282 -263.210294)
		(end 184.704482 -263.210294)
		(width 0.14478)
		(layer "In6.Cu")
		(net "M_K_CPU1_SB_CA<3>")
	)
	(segment
		(start 171.526454 -264.060432)
		(end 173.69409 -264.060432)
		(width 0.14478)
		(layer "In6.Cu")
		(net "M_K_CPU1_SB_CA<3>")
	)
	(segment
		(start 189.131194 -262.991092)
		(end 189.131194 -263.429496)
		(width 0.14478)
		(layer "In6.Cu")
		(net "M_K_CPU1_SB_CA<3>")
	)
	(segment
		(start 165.80231 -263.210294)
		(end 170.676316 -263.210294)
		(width 0.14478)
		(layer "In6.Cu")
		(net "M_K_CPU1_SB_CA<3>")
	)
	(segment
		(start 142.940786 -263.290812)
		(end 142.963138 -263.2075)
		(width 0.0889)
		(layer "In6.Cu")
		(net "M_K_CPU1_SB_CA<3>")
	)
	(segment
		(start 147.583906 -262.924544)
		(end 147.634706 -262.975344)
		(width 0.0889)
		(layer "In6.Cu")
		(net "M_K_CPU1_SB_CA<3>")
	)
	(segment
		(start 194.17919 -263.210294)
		(end 194.604132 -263.635236)
		(width 0.14478)
		(layer "In6.Cu")
		(net "M_K_CPU1_SB_CA<3>")
	)
	(segment
		(start 189.52464 -263.592564)
		(end 189.687708 -263.429496)
		(width 0.14478)
		(layer "In6.Cu")
		(net "M_K_CPU1_SB_CA<3>")
	)
	(arc
		(start 143.281654 -263.233662)
		(mid 143.56461 -263.309839)
		(end 143.847566 -263.233662)
		(width 0.0889)
		(layer "In6.Cu")
		(net "M_K_CPU1_SB_CA<3>")
	)
	(arc
		(start 144.795748 -263.228836)
		(mid 144.979256 -263.183342)
		(end 145.161508 -263.233662)
		(width 0.0889)
		(layer "In6.Cu")
		(net "M_K_CPU1_SB_CA<3>")
	)
	(arc
		(start 145.181828 -263.245346)
		(mid 145.308585 -263.298177)
		(end 145.444718 -263.316212)
		(width 0.0889)
		(layer "In6.Cu")
		(net "M_K_CPU1_SB_CA<3>")
	)
	(arc
		(start 145.506694 -263.316212)
		(mid 145.72637 -263.272516)
		(end 145.912586 -263.148064)
		(width 0.0889)
		(layer "In6.Cu")
		(net "M_K_CPU1_SB_CA<3>")
	)
	(arc
		(start 143.847566 -263.233662)
		(mid 144.029817 -263.183312)
		(end 144.213326 -263.228836)
		(width 0.0889)
		(layer "In6.Cu")
		(net "M_K_CPU1_SB_CA<3>")
	)
	(arc
		(start 144.232122 -263.239758)
		(mid 144.510554 -263.309856)
		(end 144.787366 -263.233662)
		(width 0.0889)
		(layer "In6.Cu")
		(net "M_K_CPU1_SB_CA<3>")
	)
	(arc
		(start 142.963138 -263.2075)
		(mid 143.125327 -263.184765)
		(end 143.281654 -263.233662)
		(width 0.0889)
		(layer "In6.Cu")
		(net "M_K_CPU1_SB_CA<3>")
	)
	(segment
		(start 142.157958 -262.480298)
		(end 142.62481 -262.746236)
		(width 0.10668)
		(layer "F.Cu")
		(net "M_K_CPU1_SB_CA<2>")
	)
	(segment
		(start 174.636938 -262.36041)
		(end 178.360578 -262.36041)
		(width 0.14478)
		(layer "In6.Cu")
		(net "M_K_CPU1_SB_CA<2>")
	)
	(segment
		(start 171.616116 -263.210294)
		(end 173.787054 -263.210294)
		(width 0.14478)
		(layer "In6.Cu")
		(net "M_K_CPU1_SB_CA<2>")
	)
	(segment
		(start 144.691354 -263.068816)
		(end 144.701768 -263.06272)
		(width 0.0889)
		(layer "In6.Cu")
		(net "M_K_CPU1_SB_CA<2>")
	)
	(segment
		(start 142.62481 -262.746236)
		(end 142.778734 -263.011666)
		(width 0.0889)
		(layer "In6.Cu")
		(net "M_K_CPU1_SB_CA<2>")
	)
	(segment
		(start 181.331108 -263.210294)
		(end 182.180992 -262.36041)
		(width 0.14478)
		(layer "In6.Cu")
		(net "M_K_CPU1_SB_CA<2>")
	)
	(segment
		(start 147.33016 -262.721344)
		(end 147.53082 -262.520684)
		(width 0.0889)
		(layer "In6.Cu")
		(net "M_K_CPU1_SB_CA<2>")
	)
	(segment
		(start 165.83914 -262.36041)
		(end 170.766232 -262.36041)
		(width 0.14478)
		(layer "In6.Cu")
		(net "M_K_CPU1_SB_CA<2>")
	)
	(segment
		(start 164.989256 -263.210294)
		(end 165.83914 -262.36041)
		(width 0.14478)
		(layer "In6.Cu")
		(net "M_K_CPU1_SB_CA<2>")
	)
	(segment
		(start 178.360578 -262.36041)
		(end 179.210462 -263.210294)
		(width 0.14478)
		(layer "In6.Cu")
		(net "M_K_CPU1_SB_CA<2>")
	)
	(segment
		(start 163.502848 -262.520684)
		(end 164.192458 -263.210294)
		(width 0.14478)
		(layer "In6.Cu")
		(net "M_K_CPU1_SB_CA<2>")
	)
	(segment
		(start 170.766232 -262.36041)
		(end 171.616116 -263.210294)
		(width 0.14478)
		(layer "In6.Cu")
		(net "M_K_CPU1_SB_CA<2>")
	)
	(segment
		(start 142.778734 -263.011666)
		(end 142.874746 -263.037066)
		(width 0.0889)
		(layer "In6.Cu")
		(net "M_K_CPU1_SB_CA<2>")
	)
	(segment
		(start 143.377666 -263.068816)
		(end 143.386048 -263.073642)
		(width 0.0889)
		(layer "In6.Cu")
		(net "M_K_CPU1_SB_CA<2>")
	)
	(segment
		(start 148.03755 -262.520684)
		(end 163.502848 -262.520684)
		(width 0.14478)
		(layer "In6.Cu")
		(net "M_K_CPU1_SB_CA<2>")
	)
	(segment
		(start 182.180992 -262.36041)
		(end 198.279258 -262.36041)
		(width 0.14478)
		(layer "In6.Cu")
		(net "M_K_CPU1_SB_CA<2>")
	)
	(segment
		(start 145.770346 -263.002776)
		(end 146.051778 -262.721344)
		(width 0.0889)
		(layer "In6.Cu")
		(net "M_K_CPU1_SB_CA<2>")
	)
	(segment
		(start 179.210462 -263.210294)
		(end 181.331108 -263.210294)
		(width 0.14478)
		(layer "In6.Cu")
		(net "M_K_CPU1_SB_CA<2>")
	)
	(segment
		(start 144.307052 -263.06272)
		(end 144.317466 -263.068816)
		(width 0.0889)
		(layer "In6.Cu")
		(net "M_K_CPU1_SB_CA<2>")
	)
	(segment
		(start 147.53082 -262.520684)
		(end 148.03755 -262.520684)
		(width 0.0889)
		(layer "In6.Cu")
		(net "M_K_CPU1_SB_CA<2>")
	)
	(segment
		(start 145.444718 -263.112758)
		(end 145.541746 -263.106408)
		(width 0.0889)
		(layer "In6.Cu")
		(net "M_K_CPU1_SB_CA<2>")
	)
	(segment
		(start 164.192458 -263.210294)
		(end 164.989256 -263.210294)
		(width 0.14478)
		(layer "In6.Cu")
		(net "M_K_CPU1_SB_CA<2>")
	)
	(segment
		(start 198.279258 -262.36041)
		(end 198.7042 -262.785352)
		(width 0.14478)
		(layer "In6.Cu")
		(net "M_K_CPU1_SB_CA<2>")
	)
	(segment
		(start 173.787054 -263.210294)
		(end 174.636938 -262.36041)
		(width 0.14478)
		(layer "In6.Cu")
		(net "M_K_CPU1_SB_CA<2>")
	)
	(segment
		(start 146.051778 -262.721344)
		(end 147.33016 -262.721344)
		(width 0.0889)
		(layer "In6.Cu")
		(net "M_K_CPU1_SB_CA<2>")
	)
	(arc
		(start 145.541746 -263.106408)
		(mid 145.665481 -263.075397)
		(end 145.770346 -263.002776)
		(width 0.0889)
		(layer "In6.Cu")
		(net "M_K_CPU1_SB_CA<2>")
	)
	(arc
		(start 142.874746 -263.037066)
		(mid 143.129954 -262.993589)
		(end 143.377666 -263.068816)
		(width 0.0889)
		(layer "In6.Cu")
		(net "M_K_CPU1_SB_CA<2>")
	)
	(arc
		(start 143.751808 -263.068816)
		(mid 144.028621 -262.992673)
		(end 144.307052 -263.06272)
		(width 0.0889)
		(layer "In6.Cu")
		(net "M_K_CPU1_SB_CA<2>")
	)
	(arc
		(start 144.701768 -263.06272)
		(mid 144.980454 -262.9925)
		(end 145.25752 -263.068816)
		(width 0.0889)
		(layer "In6.Cu")
		(net "M_K_CPU1_SB_CA<2>")
	)
	(arc
		(start 145.25752 -263.068816)
		(mid 145.347849 -263.1047)
		(end 145.444718 -263.112758)
		(width 0.0889)
		(layer "In6.Cu")
		(net "M_K_CPU1_SB_CA<2>")
	)
	(arc
		(start 144.317466 -263.068816)
		(mid 144.50441 -263.119071)
		(end 144.691354 -263.068816)
		(width 0.0889)
		(layer "In6.Cu")
		(net "M_K_CPU1_SB_CA<2>")
	)
	(arc
		(start 143.386048 -263.073642)
		(mid 143.569556 -263.119136)
		(end 143.751808 -263.068816)
		(width 0.0889)
		(layer "In6.Cu")
		(net "M_K_CPU1_SB_CA<2>")
	)
	(segment
		(start 141.217904 -262.480298)
		(end 141.684756 -262.746236)
		(width 0.10668)
		(layer "F.Cu")
		(net "M_K_CPU1_SB_CA<1>")
	)
	(segment
		(start 188.810392 -261.727696)
		(end 188.810392 -261.292848)
		(width 0.14478)
		(layer "In6.Cu")
		(net "M_K_CPU1_SB_CA<1>")
	)
	(segment
		(start 148.043138 -262.066024)
		(end 165.219126 -262.066024)
		(width 0.14478)
		(layer "In6.Cu")
		(net "M_K_CPU1_SB_CA<1>")
	)
	(segment
		(start 189.366906 -261.292848)
		(end 189.366906 -261.727696)
		(width 0.14478)
		(layer "In6.Cu")
		(net "M_K_CPU1_SB_CA<1>")
	)
	(segment
		(start 141.530832 -262.480806)
		(end 141.553184 -262.397494)
		(width 0.0889)
		(layer "In6.Cu")
		(net "M_K_CPU1_SB_CA<1>")
	)
	(segment
		(start 189.529974 -261.890764)
		(end 189.760352 -261.890764)
		(width 0.14478)
		(layer "In6.Cu")
		(net "M_K_CPU1_SB_CA<1>")
	)
	(segment
		(start 189.366906 -261.727696)
		(end 189.529974 -261.890764)
		(width 0.14478)
		(layer "In6.Cu")
		(net "M_K_CPU1_SB_CA<1>")
	)
	(segment
		(start 179.199032 -262.36041)
		(end 181.238144 -262.36041)
		(width 0.14478)
		(layer "In6.Cu")
		(net "M_K_CPU1_SB_CA<1>")
	)
	(segment
		(start 188.810392 -261.292848)
		(end 188.97346 -261.12978)
		(width 0.14478)
		(layer "In6.Cu")
		(net "M_K_CPU1_SB_CA<1>")
	)
	(segment
		(start 189.760352 -261.890764)
		(end 189.92342 -261.727696)
		(width 0.14478)
		(layer "In6.Cu")
		(net "M_K_CPU1_SB_CA<1>")
	)
	(segment
		(start 189.92342 -261.727696)
		(end 189.92342 -261.292848)
		(width 0.14478)
		(layer "In6.Cu")
		(net "M_K_CPU1_SB_CA<1>")
	)
	(segment
		(start 188.253878 -261.727696)
		(end 188.416946 -261.890764)
		(width 0.14478)
		(layer "In6.Cu")
		(net "M_K_CPU1_SB_CA<1>")
	)
	(segment
		(start 174.544228 -261.510272)
		(end 178.348894 -261.510272)
		(width 0.14478)
		(layer "In6.Cu")
		(net "M_K_CPU1_SB_CA<1>")
	)
	(segment
		(start 165.774878 -261.510272)
		(end 170.856148 -261.510272)
		(width 0.14478)
		(layer "In6.Cu")
		(net "M_K_CPU1_SB_CA<1>")
	)
	(segment
		(start 188.416946 -261.890764)
		(end 188.647324 -261.890764)
		(width 0.14478)
		(layer "In6.Cu")
		(net "M_K_CPU1_SB_CA<1>")
	)
	(segment
		(start 190.643002 -261.510272)
		(end 194.17919 -261.510272)
		(width 0.14478)
		(layer "In6.Cu")
		(net "M_K_CPU1_SB_CA<1>")
	)
	(segment
		(start 142.803372 -262.41883)
		(end 142.811754 -262.423656)
		(width 0.0889)
		(layer "In6.Cu")
		(net "M_K_CPU1_SB_CA<1>")
	)
	(segment
		(start 181.238144 -262.36041)
		(end 182.088282 -261.510272)
		(width 0.14478)
		(layer "In6.Cu")
		(net "M_K_CPU1_SB_CA<1>")
	)
	(segment
		(start 171.706286 -262.36041)
		(end 173.69409 -262.36041)
		(width 0.14478)
		(layer "In6.Cu")
		(net "M_K_CPU1_SB_CA<1>")
	)
	(segment
		(start 141.684756 -262.746236)
		(end 141.530832 -262.480806)
		(width 0.0889)
		(layer "In6.Cu")
		(net "M_K_CPU1_SB_CA<1>")
	)
	(segment
		(start 188.97346 -261.12978)
		(end 189.203838 -261.12978)
		(width 0.14478)
		(layer "In6.Cu")
		(net "M_K_CPU1_SB_CA<1>")
	)
	(segment
		(start 144.6911 -262.423656)
		(end 144.701514 -262.429752)
		(width 0.0889)
		(layer "In6.Cu")
		(net "M_K_CPU1_SB_CA<1>")
	)
	(segment
		(start 170.856148 -261.510272)
		(end 171.706286 -262.36041)
		(width 0.14478)
		(layer "In6.Cu")
		(net "M_K_CPU1_SB_CA<1>")
	)
	(segment
		(start 190.479934 -261.347204)
		(end 190.643002 -261.510272)
		(width 0.14478)
		(layer "In6.Cu")
		(net "M_K_CPU1_SB_CA<1>")
	)
	(segment
		(start 165.219126 -262.066024)
		(end 165.774878 -261.510272)
		(width 0.14478)
		(layer "In6.Cu")
		(net "M_K_CPU1_SB_CA<1>")
	)
	(segment
		(start 145.257266 -262.423656)
		(end 145.34388 -262.373364)
		(width 0.0889)
		(layer "In6.Cu")
		(net "M_K_CPU1_SB_CA<1>")
	)
	(segment
		(start 188.647324 -261.890764)
		(end 188.810392 -261.727696)
		(width 0.14478)
		(layer "In6.Cu")
		(net "M_K_CPU1_SB_CA<1>")
	)
	(segment
		(start 190.086488 -261.12978)
		(end 190.316866 -261.12978)
		(width 0.14478)
		(layer "In6.Cu")
		(net "M_K_CPU1_SB_CA<1>")
	)
	(segment
		(start 188.09081 -261.510272)
		(end 188.253878 -261.67334)
		(width 0.14478)
		(layer "In6.Cu")
		(net "M_K_CPU1_SB_CA<1>")
	)
	(segment
		(start 147.574254 -262.066024)
		(end 148.043138 -262.066024)
		(width 0.0889)
		(layer "In6.Cu")
		(net "M_K_CPU1_SB_CA<1>")
	)
	(segment
		(start 144.307052 -262.429752)
		(end 144.317466 -262.423656)
		(width 0.0889)
		(layer "In6.Cu")
		(net "M_K_CPU1_SB_CA<1>")
	)
	(segment
		(start 182.088282 -261.510272)
		(end 188.09081 -261.510272)
		(width 0.14478)
		(layer "In6.Cu")
		(net "M_K_CPU1_SB_CA<1>")
	)
	(segment
		(start 147.266914 -262.373364)
		(end 147.574254 -262.066024)
		(width 0.0889)
		(layer "In6.Cu")
		(net "M_K_CPU1_SB_CA<1>")
	)
	(segment
		(start 189.92342 -261.292848)
		(end 190.086488 -261.12978)
		(width 0.14478)
		(layer "In6.Cu")
		(net "M_K_CPU1_SB_CA<1>")
	)
	(segment
		(start 178.348894 -261.510272)
		(end 179.199032 -262.36041)
		(width 0.14478)
		(layer "In6.Cu")
		(net "M_K_CPU1_SB_CA<1>")
	)
	(segment
		(start 190.316866 -261.12978)
		(end 190.479934 -261.292848)
		(width 0.14478)
		(layer "In6.Cu")
		(net "M_K_CPU1_SB_CA<1>")
	)
	(segment
		(start 194.17919 -261.510272)
		(end 194.604132 -261.935214)
		(width 0.14478)
		(layer "In6.Cu")
		(net "M_K_CPU1_SB_CA<1>")
	)
	(segment
		(start 173.69409 -262.36041)
		(end 174.544228 -261.510272)
		(width 0.14478)
		(layer "In6.Cu")
		(net "M_K_CPU1_SB_CA<1>")
	)
	(segment
		(start 145.34388 -262.373364)
		(end 147.266914 -262.373364)
		(width 0.0889)
		(layer "In6.Cu")
		(net "M_K_CPU1_SB_CA<1>")
	)
	(segment
		(start 143.377666 -262.423656)
		(end 143.386048 -262.41883)
		(width 0.0889)
		(layer "In6.Cu")
		(net "M_K_CPU1_SB_CA<1>")
	)
	(segment
		(start 144.317466 -262.423656)
		(end 144.325848 -262.41883)
		(width 0.0889)
		(layer "In6.Cu")
		(net "M_K_CPU1_SB_CA<1>")
	)
	(segment
		(start 189.203838 -261.12978)
		(end 189.366906 -261.292848)
		(width 0.14478)
		(layer "In6.Cu")
		(net "M_K_CPU1_SB_CA<1>")
	)
	(segment
		(start 188.253878 -261.67334)
		(end 188.253878 -261.727696)
		(width 0.14478)
		(layer "In6.Cu")
		(net "M_K_CPU1_SB_CA<1>")
	)
	(segment
		(start 190.479934 -261.292848)
		(end 190.479934 -261.347204)
		(width 0.14478)
		(layer "In6.Cu")
		(net "M_K_CPU1_SB_CA<1>")
	)
	(arc
		(start 143.386048 -262.41883)
		(mid 143.569556 -262.373336)
		(end 143.751808 -262.423656)
		(width 0.0889)
		(layer "In6.Cu")
		(net "M_K_CPU1_SB_CA<1>")
	)
	(arc
		(start 144.325848 -262.41883)
		(mid 144.509102 -262.373457)
		(end 144.6911 -262.423656)
		(width 0.0889)
		(layer "In6.Cu")
		(net "M_K_CPU1_SB_CA<1>")
	)
	(arc
		(start 142.811754 -262.423656)
		(mid 143.09471 -262.499833)
		(end 143.377666 -262.423656)
		(width 0.0889)
		(layer "In6.Cu")
		(net "M_K_CPU1_SB_CA<1>")
	)
	(arc
		(start 144.701514 -262.429752)
		(mid 144.9802 -262.499972)
		(end 145.257266 -262.423656)
		(width 0.0889)
		(layer "In6.Cu")
		(net "M_K_CPU1_SB_CA<1>")
	)
	(arc
		(start 141.8717 -262.423656)
		(mid 142.154656 -262.499833)
		(end 142.437612 -262.423656)
		(width 0.0889)
		(layer "In6.Cu")
		(net "M_K_CPU1_SB_CA<1>")
	)
	(arc
		(start 143.751808 -262.423656)
		(mid 144.028621 -262.499799)
		(end 144.307052 -262.429752)
		(width 0.0889)
		(layer "In6.Cu")
		(net "M_K_CPU1_SB_CA<1>")
	)
	(arc
		(start 141.553184 -262.397494)
		(mid 141.715373 -262.374759)
		(end 141.8717 -262.423656)
		(width 0.0889)
		(layer "In6.Cu")
		(net "M_K_CPU1_SB_CA<1>")
	)
	(arc
		(start 142.437612 -262.423656)
		(mid 142.619863 -262.373306)
		(end 142.803372 -262.41883)
		(width 0.0889)
		(layer "In6.Cu")
		(net "M_K_CPU1_SB_CA<1>")
	)
	(segment
		(start 140.748004 -261.670292)
		(end 141.214856 -261.93623)
		(width 0.10668)
		(layer "F.Cu")
		(net "M_K_CPU1_SB_CA<0>")
	)
	(segment
		(start 147.608798 -261.611364)
		(end 148.028914 -261.611364)
		(width 0.0889)
		(layer "In6.Cu")
		(net "M_K_CPU1_SB_CA<0>")
	)
	(segment
		(start 144.20977 -262.265668)
		(end 144.221454 -262.25881)
		(width 0.0889)
		(layer "In6.Cu")
		(net "M_K_CPU1_SB_CA<0>")
	)
	(segment
		(start 144.787112 -262.25881)
		(end 144.798796 -262.265668)
		(width 0.0889)
		(layer "In6.Cu")
		(net "M_K_CPU1_SB_CA<0>")
	)
	(segment
		(start 198.279258 -260.660388)
		(end 198.7042 -261.08533)
		(width 0.14478)
		(layer "In6.Cu")
		(net "M_K_CPU1_SB_CA<0>")
	)
	(segment
		(start 144.221454 -262.25881)
		(end 144.231868 -262.252714)
		(width 0.0889)
		(layer "In6.Cu")
		(net "M_K_CPU1_SB_CA<0>")
	)
	(segment
		(start 162.82416 -261.611364)
		(end 163.775136 -260.660388)
		(width 0.14478)
		(layer "In6.Cu")
		(net "M_K_CPU1_SB_CA<0>")
	)
	(segment
		(start 145.372328 -262.134604)
		(end 147.085558 -262.134604)
		(width 0.0889)
		(layer "In6.Cu")
		(net "M_K_CPU1_SB_CA<0>")
	)
	(segment
		(start 141.967712 -262.25881)
		(end 141.976094 -262.263636)
		(width 0.0889)
		(layer "In6.Cu")
		(net "M_K_CPU1_SB_CA<0>")
	)
	(segment
		(start 163.775136 -260.660388)
		(end 198.279258 -260.660388)
		(width 0.14478)
		(layer "In6.Cu")
		(net "M_K_CPU1_SB_CA<0>")
	)
	(segment
		(start 148.028914 -261.611364)
		(end 162.82416 -261.611364)
		(width 0.14478)
		(layer "In6.Cu")
		(net "M_K_CPU1_SB_CA<0>")
	)
	(segment
		(start 145.161508 -262.25881)
		(end 145.368264 -262.138668)
		(width 0.0889)
		(layer "In6.Cu")
		(net "M_K_CPU1_SB_CA<0>")
	)
	(segment
		(start 141.214856 -261.93623)
		(end 141.36878 -262.20166)
		(width 0.0889)
		(layer "In6.Cu")
		(net "M_K_CPU1_SB_CA<0>")
	)
	(segment
		(start 141.36878 -262.20166)
		(end 141.464792 -262.22706)
		(width 0.0889)
		(layer "In6.Cu")
		(net "M_K_CPU1_SB_CA<0>")
	)
	(segment
		(start 145.368264 -262.138668)
		(end 145.372328 -262.134604)
		(width 0.0889)
		(layer "In6.Cu")
		(net "M_K_CPU1_SB_CA<0>")
	)
	(segment
		(start 147.085558 -262.134604)
		(end 147.608798 -261.611364)
		(width 0.0889)
		(layer "In6.Cu")
		(net "M_K_CPU1_SB_CA<0>")
	)
	(arc
		(start 144.798796 -262.265668)
		(mid 144.981051 -262.309321)
		(end 145.161508 -262.25881)
		(width 0.0889)
		(layer "In6.Cu")
		(net "M_K_CPU1_SB_CA<0>")
	)
	(arc
		(start 141.976094 -262.263636)
		(mid 142.159602 -262.30913)
		(end 142.341854 -262.25881)
		(width 0.0889)
		(layer "In6.Cu")
		(net "M_K_CPU1_SB_CA<0>")
	)
	(arc
		(start 144.231868 -262.252714)
		(mid 144.5103 -262.182616)
		(end 144.787112 -262.25881)
		(width 0.0889)
		(layer "In6.Cu")
		(net "M_K_CPU1_SB_CA<0>")
	)
	(arc
		(start 142.341854 -262.25881)
		(mid 142.62481 -262.182633)
		(end 142.907766 -262.25881)
		(width 0.0889)
		(layer "In6.Cu")
		(net "M_K_CPU1_SB_CA<0>")
	)
	(arc
		(start 141.464792 -262.22706)
		(mid 141.72 -262.183583)
		(end 141.967712 -262.25881)
		(width 0.0889)
		(layer "In6.Cu")
		(net "M_K_CPU1_SB_CA<0>")
	)
	(arc
		(start 143.847566 -262.25881)
		(mid 144.027771 -262.309127)
		(end 144.20977 -262.265668)
		(width 0.0889)
		(layer "In6.Cu")
		(net "M_K_CPU1_SB_CA<0>")
	)
	(arc
		(start 143.281654 -262.25881)
		(mid 143.56461 -262.182633)
		(end 143.847566 -262.25881)
		(width 0.0889)
		(layer "In6.Cu")
		(net "M_K_CPU1_SB_CA<0>")
	)
	(arc
		(start 142.907766 -262.25881)
		(mid 143.09471 -262.309065)
		(end 143.281654 -262.25881)
		(width 0.0889)
		(layer "In6.Cu")
		(net "M_K_CPU1_SB_CA<0>")
	)
	(segment
		(start 140.748004 -266.530328)
		(end 141.214856 -266.796266)
		(width 0.10668)
		(layer "F.Cu")
		(net "M_K_CPU1_SA_RSP<0>")
	)
	(segment
		(start 180.720746 -270.010636)
		(end 182.77332 -269.160498)
		(width 0.11684)
		(layer "In6.Cu")
		(net "M_K_CPU1_SA_RSP<0>")
	)
	(segment
		(start 146.46148 -265.818874)
		(end 147.352512 -265.818874)
		(width 0.0889)
		(layer "In6.Cu")
		(net "M_K_CPU1_SA_RSP<0>")
	)
	(segment
		(start 141.967712 -267.118846)
		(end 141.976094 -267.123672)
		(width 0.0889)
		(layer "In6.Cu")
		(net "M_K_CPU1_SA_RSP<0>")
	)
	(segment
		(start 147.352512 -265.818874)
		(end 147.677632 -266.143994)
		(width 0.0889)
		(layer "In6.Cu")
		(net "M_K_CPU1_SA_RSP<0>")
	)
	(segment
		(start 145.161508 -267.118846)
		(end 146.46148 -265.818874)
		(width 0.0889)
		(layer "In6.Cu")
		(net "M_K_CPU1_SA_RSP<0>")
	)
	(segment
		(start 141.36878 -267.061696)
		(end 141.464792 -267.087096)
		(width 0.0889)
		(layer "In6.Cu")
		(net "M_K_CPU1_SA_RSP<0>")
	)
	(segment
		(start 144.20977 -267.125704)
		(end 144.221454 -267.118846)
		(width 0.0889)
		(layer "In6.Cu")
		(net "M_K_CPU1_SA_RSP<0>")
	)
	(segment
		(start 182.77332 -269.160498)
		(end 198.279258 -269.160498)
		(width 0.11684)
		(layer "In6.Cu")
		(net "M_K_CPU1_SA_RSP<0>")
	)
	(segment
		(start 160.224216 -266.143994)
		(end 164.090858 -270.010636)
		(width 0.11684)
		(layer "In6.Cu")
		(net "M_K_CPU1_SA_RSP<0>")
	)
	(segment
		(start 164.090858 -270.010636)
		(end 165.17366 -270.010636)
		(width 0.11684)
		(layer "In6.Cu")
		(net "M_K_CPU1_SA_RSP<0>")
	)
	(segment
		(start 144.221454 -267.118846)
		(end 144.231868 -267.11275)
		(width 0.0889)
		(layer "In6.Cu")
		(net "M_K_CPU1_SA_RSP<0>")
	)
	(segment
		(start 171.90847 -270.010636)
		(end 173.06036 -270.010636)
		(width 0.11684)
		(layer "In6.Cu")
		(net "M_K_CPU1_SA_RSP<0>")
	)
	(segment
		(start 198.279258 -269.160498)
		(end 198.7042 -269.58544)
		(width 0.11684)
		(layer "In6.Cu")
		(net "M_K_CPU1_SA_RSP<0>")
	)
	(segment
		(start 169.855896 -269.160498)
		(end 171.90847 -270.010636)
		(width 0.11684)
		(layer "In6.Cu")
		(net "M_K_CPU1_SA_RSP<0>")
	)
	(segment
		(start 147.677632 -266.143994)
		(end 148.025866 -266.143994)
		(width 0.0889)
		(layer "In6.Cu")
		(net "M_K_CPU1_SA_RSP<0>")
	)
	(segment
		(start 144.787112 -267.118846)
		(end 144.798796 -267.125704)
		(width 0.0889)
		(layer "In6.Cu")
		(net "M_K_CPU1_SA_RSP<0>")
	)
	(segment
		(start 167.226234 -269.160498)
		(end 169.855896 -269.160498)
		(width 0.11684)
		(layer "In6.Cu")
		(net "M_K_CPU1_SA_RSP<0>")
	)
	(segment
		(start 177.382678 -269.160498)
		(end 179.435252 -270.010636)
		(width 0.11684)
		(layer "In6.Cu")
		(net "M_K_CPU1_SA_RSP<0>")
	)
	(segment
		(start 173.06036 -270.010636)
		(end 175.112934 -269.160498)
		(width 0.11684)
		(layer "In6.Cu")
		(net "M_K_CPU1_SA_RSP<0>")
	)
	(segment
		(start 175.112934 -269.160498)
		(end 177.382678 -269.160498)
		(width 0.11684)
		(layer "In6.Cu")
		(net "M_K_CPU1_SA_RSP<0>")
	)
	(segment
		(start 179.435252 -270.010636)
		(end 180.720746 -270.010636)
		(width 0.11684)
		(layer "In6.Cu")
		(net "M_K_CPU1_SA_RSP<0>")
	)
	(segment
		(start 148.025866 -266.143994)
		(end 160.224216 -266.143994)
		(width 0.11684)
		(layer "In6.Cu")
		(net "M_K_CPU1_SA_RSP<0>")
	)
	(segment
		(start 141.214856 -266.796266)
		(end 141.36878 -267.061696)
		(width 0.0889)
		(layer "In6.Cu")
		(net "M_K_CPU1_SA_RSP<0>")
	)
	(segment
		(start 165.17366 -270.010636)
		(end 167.226234 -269.160498)
		(width 0.11684)
		(layer "In6.Cu")
		(net "M_K_CPU1_SA_RSP<0>")
	)
	(arc
		(start 141.976094 -267.123672)
		(mid 142.159602 -267.169166)
		(end 142.341854 -267.118846)
		(width 0.0889)
		(layer "In6.Cu")
		(net "M_K_CPU1_SA_RSP<0>")
	)
	(arc
		(start 142.907766 -267.118846)
		(mid 143.09471 -267.169101)
		(end 143.281654 -267.118846)
		(width 0.0889)
		(layer "In6.Cu")
		(net "M_K_CPU1_SA_RSP<0>")
	)
	(arc
		(start 143.847566 -267.118846)
		(mid 144.027771 -267.169163)
		(end 144.20977 -267.125704)
		(width 0.0889)
		(layer "In6.Cu")
		(net "M_K_CPU1_SA_RSP<0>")
	)
	(arc
		(start 141.464792 -267.087096)
		(mid 141.72 -267.043619)
		(end 141.967712 -267.118846)
		(width 0.0889)
		(layer "In6.Cu")
		(net "M_K_CPU1_SA_RSP<0>")
	)
	(arc
		(start 143.281654 -267.118846)
		(mid 143.56461 -267.042669)
		(end 143.847566 -267.118846)
		(width 0.0889)
		(layer "In6.Cu")
		(net "M_K_CPU1_SA_RSP<0>")
	)
	(arc
		(start 142.341854 -267.118846)
		(mid 142.62481 -267.042669)
		(end 142.907766 -267.118846)
		(width 0.0889)
		(layer "In6.Cu")
		(net "M_K_CPU1_SA_RSP<0>")
	)
	(arc
		(start 144.231868 -267.11275)
		(mid 144.5103 -267.042652)
		(end 144.787112 -267.118846)
		(width 0.0889)
		(layer "In6.Cu")
		(net "M_K_CPU1_SA_RSP<0>")
	)
	(arc
		(start 144.798796 -267.125704)
		(mid 144.981051 -267.169357)
		(end 145.161508 -267.118846)
		(width 0.0889)
		(layer "In6.Cu")
		(net "M_K_CPU1_SA_RSP<0>")
	)
	(segment
		(start 140.447776 -256.09042)
		(end 140.914882 -255.824482)
		(width 0.10668)
		(layer "F.Cu")
		(net "M_K_CPU1_SA_PAR")
	)
	(segment
		(start 145.743168 -255.652524)
		(end 146.606768 -256.516124)
		(width 0.0889)
		(layer "In6.Cu")
		(net "M_K_CPU1_SA_PAR")
	)
	(segment
		(start 143.92148 -255.501902)
		(end 143.931894 -255.507998)
		(width 0.0889)
		(layer "In6.Cu")
		(net "M_K_CPU1_SA_PAR")
	)
	(segment
		(start 147.876768 -256.516124)
		(end 150.733252 -256.516124)
		(width 0.14478)
		(layer "In6.Cu")
		(net "M_K_CPU1_SA_PAR")
	)
	(segment
		(start 193.185288 -253.010162)
		(end 197.42912 -253.010162)
		(width 0.14478)
		(layer "In6.Cu")
		(net "M_K_CPU1_SA_PAR")
	)
	(segment
		(start 158.462218 -255.153414)
		(end 159.052768 -255.743964)
		(width 0.14478)
		(layer "In6.Cu")
		(net "M_K_CPU1_SA_PAR")
	)
	(segment
		(start 141.667738 -255.501902)
		(end 141.67612 -255.497076)
		(width 0.0889)
		(layer "In6.Cu")
		(net "M_K_CPU1_SA_PAR")
	)
	(segment
		(start 145.012156 -255.652524)
		(end 145.743168 -255.652524)
		(width 0.0889)
		(layer "In6.Cu")
		(net "M_K_CPU1_SA_PAR")
	)
	(segment
		(start 197.42912 -253.010162)
		(end 198.7042 -254.285242)
		(width 0.14478)
		(layer "In6.Cu")
		(net "M_K_CPU1_SA_PAR")
	)
	(segment
		(start 143.909796 -255.495044)
		(end 143.92148 -255.501902)
		(width 0.0889)
		(layer "In6.Cu")
		(net "M_K_CPU1_SA_PAR")
	)
	(segment
		(start 144.861534 -255.501902)
		(end 145.012156 -255.652524)
		(width 0.0889)
		(layer "In6.Cu")
		(net "M_K_CPU1_SA_PAR")
	)
	(segment
		(start 150.733252 -256.516124)
		(end 152.095962 -255.153414)
		(width 0.14478)
		(layer "In6.Cu")
		(net "M_K_CPU1_SA_PAR")
	)
	(segment
		(start 190.799466 -254.710184)
		(end 191.485266 -254.710184)
		(width 0.14478)
		(layer "In6.Cu")
		(net "M_K_CPU1_SA_PAR")
	)
	(segment
		(start 146.606768 -256.516124)
		(end 147.876768 -256.516124)
		(width 0.0889)
		(layer "In6.Cu")
		(net "M_K_CPU1_SA_PAR")
	)
	(segment
		(start 189.765686 -255.743964)
		(end 190.799466 -254.710184)
		(width 0.14478)
		(layer "In6.Cu")
		(net "M_K_CPU1_SA_PAR")
	)
	(segment
		(start 159.052768 -255.743964)
		(end 189.765686 -255.743964)
		(width 0.14478)
		(layer "In6.Cu")
		(net "M_K_CPU1_SA_PAR")
	)
	(segment
		(start 141.068806 -255.559052)
		(end 141.164818 -255.533652)
		(width 0.0889)
		(layer "In6.Cu")
		(net "M_K_CPU1_SA_PAR")
	)
	(segment
		(start 191.485266 -254.710184)
		(end 193.185288 -253.010162)
		(width 0.14478)
		(layer "In6.Cu")
		(net "M_K_CPU1_SA_PAR")
	)
	(segment
		(start 140.914882 -255.824482)
		(end 141.068806 -255.559052)
		(width 0.0889)
		(layer "In6.Cu")
		(net "M_K_CPU1_SA_PAR")
	)
	(segment
		(start 144.487138 -255.501902)
		(end 144.498822 -255.495044)
		(width 0.0889)
		(layer "In6.Cu")
		(net "M_K_CPU1_SA_PAR")
	)
	(segment
		(start 152.095962 -255.153414)
		(end 158.462218 -255.153414)
		(width 0.14478)
		(layer "In6.Cu")
		(net "M_K_CPU1_SA_PAR")
	)
	(arc
		(start 142.607792 -255.501902)
		(mid 142.794736 -255.451647)
		(end 142.98168 -255.501902)
		(width 0.0889)
		(layer "In6.Cu")
		(net "M_K_CPU1_SA_PAR")
	)
	(arc
		(start 141.67612 -255.497076)
		(mid 141.859628 -255.451582)
		(end 142.04188 -255.501902)
		(width 0.0889)
		(layer "In6.Cu")
		(net "M_K_CPU1_SA_PAR")
	)
	(arc
		(start 143.931894 -255.507998)
		(mid 144.210326 -255.578096)
		(end 144.487138 -255.501902)
		(width 0.0889)
		(layer "In6.Cu")
		(net "M_K_CPU1_SA_PAR")
	)
	(arc
		(start 141.164818 -255.533652)
		(mid 141.420026 -255.577129)
		(end 141.667738 -255.501902)
		(width 0.0889)
		(layer "In6.Cu")
		(net "M_K_CPU1_SA_PAR")
	)
	(arc
		(start 143.547592 -255.501902)
		(mid 143.727797 -255.451585)
		(end 143.909796 -255.495044)
		(width 0.0889)
		(layer "In6.Cu")
		(net "M_K_CPU1_SA_PAR")
	)
	(arc
		(start 144.498822 -255.495044)
		(mid 144.681077 -255.451391)
		(end 144.861534 -255.501902)
		(width 0.0889)
		(layer "In6.Cu")
		(net "M_K_CPU1_SA_PAR")
	)
	(arc
		(start 142.04188 -255.501902)
		(mid 142.324836 -255.578079)
		(end 142.607792 -255.501902)
		(width 0.0889)
		(layer "In6.Cu")
		(net "M_K_CPU1_SA_PAR")
	)
	(arc
		(start 142.98168 -255.501902)
		(mid 143.264636 -255.578079)
		(end 143.547592 -255.501902)
		(width 0.0889)
		(layer "In6.Cu")
		(net "M_K_CPU1_SA_PAR")
	)
	(segment
		(start 140.447776 -247.99036)
		(end 140.914882 -247.724422)
		(width 0.12954)
		(layer "F.Cu")
		(net "M_K_CPU1_SA_DQS_DP<9>")
	)
	(segment
		(start 183.899556 -239.710468)
		(end 184.059576 -239.870488)
		(width 0.16002)
		(layer "In6.Cu")
		(net "M_K_CPU1_SA_DQS_DP<9>")
	)
	(segment
		(start 175.587406 -239.710468)
		(end 176.31537 -239.710468)
		(width 0.16002)
		(layer "In6.Cu")
		(net "M_K_CPU1_SA_DQS_DP<9>")
	)
	(segment
		(start 180.233574 -240.560606)
		(end 180.613558 -240.180622)
		(width 0.16002)
		(layer "In6.Cu")
		(net "M_K_CPU1_SA_DQS_DP<9>")
	)
	(segment
		(start 180.613558 -240.180622)
		(end 181.218078 -240.180622)
		(width 0.16002)
		(layer "In6.Cu")
		(net "M_K_CPU1_SA_DQS_DP<9>")
	)
	(segment
		(start 148.16328 -247.682258)
		(end 148.698712 -247.146826)
		(width 0.16002)
		(layer "In6.Cu")
		(net "M_K_CPU1_SA_DQS_DP<9>")
	)
	(segment
		(start 189.549532 -239.393222)
		(end 190.358268 -239.393222)
		(width 0.16002)
		(layer "In6.Cu")
		(net "M_K_CPU1_SA_DQS_DP<9>")
	)
	(segment
		(start 143.923004 -247.399302)
		(end 143.933418 -247.405398)
		(width 0.09525)
		(layer "In6.Cu")
		(net "M_K_CPU1_SA_DQS_DP<9>")
	)
	(segment
		(start 170.134026 -239.710468)
		(end 170.525186 -239.710468)
		(width 0.16002)
		(layer "In6.Cu")
		(net "M_K_CPU1_SA_DQS_DP<9>")
	)
	(segment
		(start 147.722336 -247.682258)
		(end 147.745958 -247.682258)
		(width 0.09525)
		(layer "In6.Cu")
		(net "M_K_CPU1_SA_DQS_DP<9>")
	)
	(segment
		(start 145.425668 -247.399302)
		(end 145.43405 -247.394476)
		(width 0.09525)
		(layer "In6.Cu")
		(net "M_K_CPU1_SA_DQS_DP<9>")
	)
	(segment
		(start 176.31537 -239.710468)
		(end 176.47539 -239.870488)
		(width 0.16002)
		(layer "In6.Cu")
		(net "M_K_CPU1_SA_DQS_DP<9>")
	)
	(segment
		(start 143.911066 -247.392444)
		(end 143.923004 -247.399302)
		(width 0.09525)
		(layer "In6.Cu")
		(net "M_K_CPU1_SA_DQS_DP<9>")
	)
	(segment
		(start 147.745958 -247.682258)
		(end 148.16328 -247.682258)
		(width 0.16002)
		(layer "In6.Cu")
		(net "M_K_CPU1_SA_DQS_DP<9>")
	)
	(segment
		(start 184.995312 -240.525046)
		(end 185.33237 -240.187988)
		(width 0.16002)
		(layer "In6.Cu")
		(net "M_K_CPU1_SA_DQS_DP<9>")
	)
	(segment
		(start 182.005478 -239.393222)
		(end 182.814214 -239.393222)
		(width 0.16002)
		(layer "In6.Cu")
		(net "M_K_CPU1_SA_DQS_DP<9>")
	)
	(segment
		(start 181.218078 -240.180622)
		(end 182.005478 -239.393222)
		(width 0.16002)
		(layer "In6.Cu")
		(net "M_K_CPU1_SA_DQS_DP<9>")
	)
	(segment
		(start 185.49239 -239.710468)
		(end 185.896758 -239.710468)
		(width 0.16002)
		(layer "In6.Cu")
		(net "M_K_CPU1_SA_DQS_DP<9>")
	)
	(segment
		(start 177.748184 -240.193068)
		(end 177.748184 -239.870488)
		(width 0.16002)
		(layer "In6.Cu")
		(net "M_K_CPU1_SA_DQS_DP<9>")
	)
	(segment
		(start 145.880074 -247.45823)
		(end 145.880074 -247.458484)
		(width 0.09525)
		(layer "In6.Cu")
		(net "M_K_CPU1_SA_DQS_DP<9>")
	)
	(segment
		(start 185.33237 -240.187988)
		(end 185.33237 -239.870488)
		(width 0.16002)
		(layer "In6.Cu")
		(net "M_K_CPU1_SA_DQS_DP<9>")
	)
	(segment
		(start 184.059576 -239.870488)
		(end 184.059576 -240.187988)
		(width 0.16002)
		(layer "In6.Cu")
		(net "M_K_CPU1_SA_DQS_DP<9>")
	)
	(segment
		(start 148.698712 -247.146826)
		(end 157.42539 -247.146826)
		(width 0.16002)
		(layer "In6.Cu")
		(net "M_K_CPU1_SA_DQS_DP<9>")
	)
	(segment
		(start 169.974006 -240.170208)
		(end 169.974006 -239.870488)
		(width 0.16002)
		(layer "In6.Cu")
		(net "M_K_CPU1_SA_DQS_DP<9>")
	)
	(segment
		(start 140.914882 -247.724422)
		(end 141.068806 -247.458992)
		(width 0.09525)
		(layer "In6.Cu")
		(net "M_K_CPU1_SA_DQS_DP<9>")
	)
	(segment
		(start 192.107566 -239.710468)
		(end 192.256664 -239.56137)
		(width 0.16002)
		(layer "In6.Cu")
		(net "M_K_CPU1_SA_DQS_DP<9>")
	)
	(segment
		(start 172.68952 -240.560606)
		(end 173.069504 -240.180622)
		(width 0.16002)
		(layer "In6.Cu")
		(net "M_K_CPU1_SA_DQS_DP<9>")
	)
	(segment
		(start 185.896758 -239.710468)
		(end 186.746896 -240.560606)
		(width 0.16002)
		(layer "In6.Cu")
		(net "M_K_CPU1_SA_DQS_DP<9>")
	)
	(segment
		(start 175.27016 -239.393222)
		(end 175.587406 -239.710468)
		(width 0.16002)
		(layer "In6.Cu")
		(net "M_K_CPU1_SA_DQS_DP<9>")
	)
	(segment
		(start 166.12997 -240.180622)
		(end 166.91737 -239.393222)
		(width 0.16002)
		(layer "In6.Cu")
		(net "M_K_CPU1_SA_DQS_DP<9>")
	)
	(segment
		(start 183.13146 -239.710468)
		(end 183.899556 -239.710468)
		(width 0.16002)
		(layer "In6.Cu")
		(net "M_K_CPU1_SA_DQS_DP<9>")
	)
	(segment
		(start 178.343052 -239.710468)
		(end 179.19319 -240.560606)
		(width 0.16002)
		(layer "In6.Cu")
		(net "M_K_CPU1_SA_DQS_DP<9>")
	)
	(segment
		(start 188.157612 -240.180622)
		(end 188.762132 -240.180622)
		(width 0.16002)
		(layer "In6.Cu")
		(net "M_K_CPU1_SA_DQS_DP<9>")
	)
	(segment
		(start 187.777628 -240.560606)
		(end 188.157612 -240.180622)
		(width 0.16002)
		(layer "In6.Cu")
		(net "M_K_CPU1_SA_DQS_DP<9>")
	)
	(segment
		(start 177.411126 -240.530126)
		(end 177.748184 -240.193068)
		(width 0.16002)
		(layer "In6.Cu")
		(net "M_K_CPU1_SA_DQS_DP<9>")
	)
	(segment
		(start 176.812448 -240.530126)
		(end 177.411126 -240.530126)
		(width 0.16002)
		(layer "In6.Cu")
		(net "M_K_CPU1_SA_DQS_DP<9>")
	)
	(segment
		(start 182.814214 -239.393222)
		(end 183.13146 -239.710468)
		(width 0.16002)
		(layer "In6.Cu")
		(net "M_K_CPU1_SA_DQS_DP<9>")
	)
	(segment
		(start 174.461424 -239.393222)
		(end 175.27016 -239.393222)
		(width 0.16002)
		(layer "In6.Cu")
		(net "M_K_CPU1_SA_DQS_DP<9>")
	)
	(segment
		(start 194.330066 -239.56137)
		(end 194.604132 -239.835436)
		(width 0.16002)
		(layer "In6.Cu")
		(net "M_K_CPU1_SA_DQS_DP<9>")
	)
	(segment
		(start 177.748184 -239.870488)
		(end 177.908204 -239.710468)
		(width 0.16002)
		(layer "In6.Cu")
		(net "M_K_CPU1_SA_DQS_DP<9>")
	)
	(segment
		(start 173.674024 -240.180622)
		(end 174.461424 -239.393222)
		(width 0.16002)
		(layer "In6.Cu")
		(net "M_K_CPU1_SA_DQS_DP<9>")
	)
	(segment
		(start 170.525186 -239.710468)
		(end 171.375324 -240.560606)
		(width 0.16002)
		(layer "In6.Cu")
		(net "M_K_CPU1_SA_DQS_DP<9>")
	)
	(segment
		(start 188.762132 -240.180622)
		(end 189.549532 -239.393222)
		(width 0.16002)
		(layer "In6.Cu")
		(net "M_K_CPU1_SA_DQS_DP<9>")
	)
	(segment
		(start 145.880074 -247.458484)
		(end 146.045174 -247.62333)
		(width 0.09525)
		(layer "In6.Cu")
		(net "M_K_CPU1_SA_DQS_DP<9>")
	)
	(segment
		(start 169.03827 -240.507266)
		(end 169.636948 -240.507266)
		(width 0.16002)
		(layer "In6.Cu")
		(net "M_K_CPU1_SA_DQS_DP<9>")
	)
	(segment
		(start 190.675514 -239.710468)
		(end 192.107566 -239.710468)
		(width 0.16002)
		(layer "In6.Cu")
		(net "M_K_CPU1_SA_DQS_DP<9>")
	)
	(segment
		(start 147.663408 -247.62333)
		(end 147.722336 -247.682258)
		(width 0.09525)
		(layer "In6.Cu")
		(net "M_K_CPU1_SA_DQS_DP<9>")
	)
	(segment
		(start 190.358268 -239.393222)
		(end 190.675514 -239.710468)
		(width 0.16002)
		(layer "In6.Cu")
		(net "M_K_CPU1_SA_DQS_DP<9>")
	)
	(segment
		(start 192.256664 -239.56137)
		(end 194.330066 -239.56137)
		(width 0.16002)
		(layer "In6.Cu")
		(net "M_K_CPU1_SA_DQS_DP<9>")
	)
	(segment
		(start 144.485614 -247.399302)
		(end 144.497552 -247.392444)
		(width 0.09525)
		(layer "In6.Cu")
		(net "M_K_CPU1_SA_DQS_DP<9>")
	)
	(segment
		(start 176.47539 -240.193068)
		(end 176.812448 -240.530126)
		(width 0.16002)
		(layer "In6.Cu")
		(net "M_K_CPU1_SA_DQS_DP<9>")
	)
	(segment
		(start 168.701212 -240.170208)
		(end 169.03827 -240.507266)
		(width 0.16002)
		(layer "In6.Cu")
		(net "M_K_CPU1_SA_DQS_DP<9>")
	)
	(segment
		(start 185.33237 -239.870488)
		(end 185.49239 -239.710468)
		(width 0.16002)
		(layer "In6.Cu")
		(net "M_K_CPU1_SA_DQS_DP<9>")
	)
	(segment
		(start 186.746896 -240.560606)
		(end 187.777628 -240.560606)
		(width 0.16002)
		(layer "In6.Cu")
		(net "M_K_CPU1_SA_DQS_DP<9>")
	)
	(segment
		(start 166.91737 -239.393222)
		(end 167.726106 -239.393222)
		(width 0.16002)
		(layer "In6.Cu")
		(net "M_K_CPU1_SA_DQS_DP<9>")
	)
	(segment
		(start 168.541192 -239.710468)
		(end 168.701212 -239.870488)
		(width 0.16002)
		(layer "In6.Cu")
		(net "M_K_CPU1_SA_DQS_DP<9>")
	)
	(segment
		(start 167.726106 -239.393222)
		(end 168.043352 -239.710468)
		(width 0.16002)
		(layer "In6.Cu")
		(net "M_K_CPU1_SA_DQS_DP<9>")
	)
	(segment
		(start 168.701212 -239.870488)
		(end 168.701212 -240.170208)
		(width 0.16002)
		(layer "In6.Cu")
		(net "M_K_CPU1_SA_DQS_DP<9>")
	)
	(segment
		(start 141.068806 -247.458992)
		(end 141.169644 -247.432322)
		(width 0.09525)
		(layer "In6.Cu")
		(net "M_K_CPU1_SA_DQS_DP<9>")
	)
	(segment
		(start 141.666214 -247.399302)
		(end 141.674596 -247.394476)
		(width 0.09525)
		(layer "In6.Cu")
		(net "M_K_CPU1_SA_DQS_DP<9>")
	)
	(segment
		(start 157.42539 -247.146826)
		(end 164.391594 -240.180622)
		(width 0.16002)
		(layer "In6.Cu")
		(net "M_K_CPU1_SA_DQS_DP<9>")
	)
	(segment
		(start 184.396634 -240.525046)
		(end 184.995312 -240.525046)
		(width 0.16002)
		(layer "In6.Cu")
		(net "M_K_CPU1_SA_DQS_DP<9>")
	)
	(segment
		(start 177.908204 -239.710468)
		(end 178.343052 -239.710468)
		(width 0.16002)
		(layer "In6.Cu")
		(net "M_K_CPU1_SA_DQS_DP<9>")
	)
	(segment
		(start 164.391594 -240.180622)
		(end 166.12997 -240.180622)
		(width 0.16002)
		(layer "In6.Cu")
		(net "M_K_CPU1_SA_DQS_DP<9>")
	)
	(segment
		(start 169.636948 -240.507266)
		(end 169.974006 -240.170208)
		(width 0.16002)
		(layer "In6.Cu")
		(net "M_K_CPU1_SA_DQS_DP<9>")
	)
	(segment
		(start 176.47539 -239.870488)
		(end 176.47539 -240.193068)
		(width 0.16002)
		(layer "In6.Cu")
		(net "M_K_CPU1_SA_DQS_DP<9>")
	)
	(segment
		(start 179.19319 -240.560606)
		(end 180.233574 -240.560606)
		(width 0.16002)
		(layer "In6.Cu")
		(net "M_K_CPU1_SA_DQS_DP<9>")
	)
	(segment
		(start 169.974006 -239.870488)
		(end 170.134026 -239.710468)
		(width 0.16002)
		(layer "In6.Cu")
		(net "M_K_CPU1_SA_DQS_DP<9>")
	)
	(segment
		(start 168.043352 -239.710468)
		(end 168.541192 -239.710468)
		(width 0.16002)
		(layer "In6.Cu")
		(net "M_K_CPU1_SA_DQS_DP<9>")
	)
	(segment
		(start 184.059576 -240.187988)
		(end 184.396634 -240.525046)
		(width 0.16002)
		(layer "In6.Cu")
		(net "M_K_CPU1_SA_DQS_DP<9>")
	)
	(segment
		(start 145.407634 -247.409716)
		(end 145.425668 -247.399302)
		(width 0.09525)
		(layer "In6.Cu")
		(net "M_K_CPU1_SA_DQS_DP<9>")
	)
	(segment
		(start 171.375324 -240.560606)
		(end 172.68952 -240.560606)
		(width 0.16002)
		(layer "In6.Cu")
		(net "M_K_CPU1_SA_DQS_DP<9>")
	)
	(segment
		(start 173.069504 -240.180622)
		(end 173.674024 -240.180622)
		(width 0.16002)
		(layer "In6.Cu")
		(net "M_K_CPU1_SA_DQS_DP<9>")
	)
	(segment
		(start 146.045174 -247.62333)
		(end 147.663408 -247.62333)
		(width 0.09525)
		(layer "In6.Cu")
		(net "M_K_CPU1_SA_DQS_DP<9>")
	)
	(arc
		(start 141.674596 -247.394476)
		(mid 141.859628 -247.348562)
		(end 142.043404 -247.399302)
		(width 0.09525)
		(layer "In6.Cu")
		(net "M_K_CPU1_SA_DQS_DP<9>")
	)
	(arc
		(start 144.497552 -247.392444)
		(mid 144.681187 -247.348494)
		(end 144.863058 -247.399302)
		(width 0.09525)
		(layer "In6.Cu")
		(net "M_K_CPU1_SA_DQS_DP<9>")
	)
	(arc
		(start 142.983204 -247.399302)
		(mid 143.264636 -247.475057)
		(end 143.546068 -247.399302)
		(width 0.09525)
		(layer "In6.Cu")
		(net "M_K_CPU1_SA_DQS_DP<9>")
	)
	(arc
		(start 144.863058 -247.399302)
		(mid 145.134 -247.475082)
		(end 145.407634 -247.409716)
		(width 0.09525)
		(layer "In6.Cu")
		(net "M_K_CPU1_SA_DQS_DP<9>")
	)
	(arc
		(start 143.546068 -247.399302)
		(mid 143.727684 -247.348565)
		(end 143.911066 -247.392444)
		(width 0.09525)
		(layer "In6.Cu")
		(net "M_K_CPU1_SA_DQS_DP<9>")
	)
	(arc
		(start 141.189456 -247.440196)
		(mid 141.43242 -247.473183)
		(end 141.666214 -247.399302)
		(width 0.09525)
		(layer "In6.Cu")
		(net "M_K_CPU1_SA_DQS_DP<9>")
	)
	(arc
		(start 142.043404 -247.399302)
		(mid 142.324836 -247.475057)
		(end 142.606268 -247.399302)
		(width 0.09525)
		(layer "In6.Cu")
		(net "M_K_CPU1_SA_DQS_DP<9>")
	)
	(arc
		(start 145.43405 -247.394476)
		(mid 145.618828 -247.348683)
		(end 145.80235 -247.399302)
		(width 0.09525)
		(layer "In6.Cu")
		(net "M_K_CPU1_SA_DQS_DP<9>")
	)
	(arc
		(start 142.606268 -247.399302)
		(mid 142.794736 -247.348625)
		(end 142.983204 -247.399302)
		(width 0.09525)
		(layer "In6.Cu")
		(net "M_K_CPU1_SA_DQS_DP<9>")
	)
	(arc
		(start 141.169644 -247.432322)
		(mid 141.179512 -247.436353)
		(end 141.189456 -247.440196)
		(width 0.09525)
		(layer "In6.Cu")
		(net "M_K_CPU1_SA_DQS_DP<9>")
	)
	(arc
		(start 145.80235 -247.399302)
		(mid 145.843131 -247.426235)
		(end 145.880074 -247.45823)
		(width 0.09525)
		(layer "In6.Cu")
		(net "M_K_CPU1_SA_DQS_DP<9>")
	)
	(arc
		(start 143.933418 -247.405398)
		(mid 144.210326 -247.475075)
		(end 144.485614 -247.399302)
		(width 0.09525)
		(layer "In6.Cu")
		(net "M_K_CPU1_SA_DQS_DP<9>")
	)
	(segment
		(start 140.447776 -243.130324)
		(end 140.914882 -242.864386)
		(width 0.12954)
		(layer "F.Cu")
		(net "M_K_CPU1_SA_DQS_DP<8>")
	)
	(segment
		(start 146.895058 -242.138454)
		(end 147.578826 -241.454686)
		(width 0.09525)
		(layer "In6.Cu")
		(net "M_K_CPU1_SA_DQS_DP<8>")
	)
	(segment
		(start 145.14449 -242.614958)
		(end 145.684748 -242.614958)
		(width 0.09525)
		(layer "In6.Cu")
		(net "M_K_CPU1_SA_DQS_DP<8>")
	)
	(segment
		(start 169.811192 -230.001826)
		(end 169.971212 -230.161846)
		(width 0.16002)
		(layer "In6.Cu")
		(net "M_K_CPU1_SA_DQS_DP<8>")
	)
	(segment
		(start 169.302938 -230.161846)
		(end 169.462958 -230.001826)
		(width 0.16002)
		(layer "In6.Cu")
		(net "M_K_CPU1_SA_DQS_DP<8>")
	)
	(segment
		(start 161.007552 -233.75366)
		(end 161.484056 -233.75366)
		(width 0.16002)
		(layer "In6.Cu")
		(net "M_K_CPU1_SA_DQS_DP<8>")
	)
	(segment
		(start 169.971212 -230.368348)
		(end 170.30827 -230.705406)
		(width 0.16002)
		(layer "In6.Cu")
		(net "M_K_CPU1_SA_DQS_DP<8>")
	)
	(segment
		(start 192.256664 -230.211376)
		(end 194.330066 -230.211376)
		(width 0.16002)
		(layer "In6.Cu")
		(net "M_K_CPU1_SA_DQS_DP<8>")
	)
	(segment
		(start 180.233574 -231.210612)
		(end 180.613558 -230.830628)
		(width 0.16002)
		(layer "In6.Cu")
		(net "M_K_CPU1_SA_DQS_DP<8>")
	)
	(segment
		(start 143.911066 -242.532408)
		(end 143.923004 -242.539266)
		(width 0.09525)
		(layer "In6.Cu")
		(net "M_K_CPU1_SA_DQS_DP<8>")
	)
	(segment
		(start 144.485614 -242.539266)
		(end 144.490186 -242.535964)
		(width 0.09525)
		(layer "In6.Cu")
		(net "M_K_CPU1_SA_DQS_DP<8>")
	)
	(segment
		(start 175.587406 -230.360474)
		(end 178.06924 -230.360474)
		(width 0.16002)
		(layer "In6.Cu")
		(net "M_K_CPU1_SA_DQS_DP<8>")
	)
	(segment
		(start 161.484056 -233.75366)
		(end 161.90849 -233.329226)
		(width 0.16002)
		(layer "In6.Cu")
		(net "M_K_CPU1_SA_DQS_DP<8>")
	)
	(segment
		(start 160.906968 -233.653076)
		(end 161.007552 -233.75366)
		(width 0.16002)
		(layer "In6.Cu")
		(net "M_K_CPU1_SA_DQS_DP<8>")
	)
	(segment
		(start 192.107566 -230.360474)
		(end 192.256664 -230.211376)
		(width 0.16002)
		(layer "In6.Cu")
		(net "M_K_CPU1_SA_DQS_DP<8>")
	)
	(segment
		(start 162.381184 -232.380028)
		(end 162.857688 -232.380028)
		(width 0.16002)
		(layer "In6.Cu")
		(net "M_K_CPU1_SA_DQS_DP<8>")
	)
	(segment
		(start 173.069504 -230.830628)
		(end 173.674024 -230.830628)
		(width 0.16002)
		(layer "In6.Cu")
		(net "M_K_CPU1_SA_DQS_DP<8>")
	)
	(segment
		(start 162.857688 -232.380028)
		(end 163.282122 -231.955594)
		(width 0.16002)
		(layer "In6.Cu")
		(net "M_K_CPU1_SA_DQS_DP<8>")
	)
	(segment
		(start 147.919186 -241.513614)
		(end 154.826462 -241.513614)
		(width 0.16002)
		(layer "In6.Cu")
		(net "M_K_CPU1_SA_DQS_DP<8>")
	)
	(segment
		(start 171.375324 -231.210612)
		(end 172.68952 -231.210612)
		(width 0.16002)
		(layer "In6.Cu")
		(net "M_K_CPU1_SA_DQS_DP<8>")
	)
	(segment
		(start 180.613558 -230.830628)
		(end 181.218078 -230.830628)
		(width 0.16002)
		(layer "In6.Cu")
		(net "M_K_CPU1_SA_DQS_DP<8>")
	)
	(segment
		(start 160.39719 -235.942886)
		(end 160.39719 -233.936794)
		(width 0.16002)
		(layer "In6.Cu")
		(net "M_K_CPU1_SA_DQS_DP<8>")
	)
	(segment
		(start 194.330066 -230.211376)
		(end 194.604132 -230.485442)
		(width 0.16002)
		(layer "In6.Cu")
		(net "M_K_CPU1_SA_DQS_DP<8>")
	)
	(segment
		(start 154.826462 -241.513614)
		(end 160.39719 -235.942886)
		(width 0.16002)
		(layer "In6.Cu")
		(net "M_K_CPU1_SA_DQS_DP<8>")
	)
	(segment
		(start 161.90849 -232.852722)
		(end 161.807906 -232.752138)
		(width 0.16002)
		(layer "In6.Cu")
		(net "M_K_CPU1_SA_DQS_DP<8>")
	)
	(segment
		(start 141.068806 -242.598956)
		(end 141.169644 -242.572286)
		(width 0.09525)
		(layer "In6.Cu")
		(net "M_K_CPU1_SA_DQS_DP<8>")
	)
	(segment
		(start 161.90849 -233.329226)
		(end 161.90849 -232.852722)
		(width 0.16002)
		(layer "In6.Cu")
		(net "M_K_CPU1_SA_DQS_DP<8>")
	)
	(segment
		(start 144.490948 -242.535456)
		(end 144.492726 -242.53444)
		(width 0.09525)
		(layer "In6.Cu")
		(net "M_K_CPU1_SA_DQS_DP<8>")
	)
	(segment
		(start 146.161252 -242.138454)
		(end 146.895058 -242.138454)
		(width 0.09525)
		(layer "In6.Cu")
		(net "M_K_CPU1_SA_DQS_DP<8>")
	)
	(segment
		(start 170.30827 -230.705406)
		(end 170.870118 -230.705406)
		(width 0.16002)
		(layer "In6.Cu")
		(net "M_K_CPU1_SA_DQS_DP<8>")
	)
	(segment
		(start 188.762132 -230.830628)
		(end 189.549532 -230.043228)
		(width 0.16002)
		(layer "In6.Cu")
		(net "M_K_CPU1_SA_DQS_DP<8>")
	)
	(segment
		(start 169.302938 -230.368348)
		(end 169.302938 -230.161846)
		(width 0.16002)
		(layer "In6.Cu")
		(net "M_K_CPU1_SA_DQS_DP<8>")
	)
	(segment
		(start 167.726106 -230.043228)
		(end 168.388284 -230.705406)
		(width 0.16002)
		(layer "In6.Cu")
		(net "M_K_CPU1_SA_DQS_DP<8>")
	)
	(segment
		(start 185.613294 -230.360474)
		(end 186.463432 -231.210612)
		(width 0.16002)
		(layer "In6.Cu")
		(net "M_K_CPU1_SA_DQS_DP<8>")
	)
	(segment
		(start 147.578826 -241.454686)
		(end 147.836636 -241.454686)
		(width 0.09525)
		(layer "In6.Cu")
		(net "M_K_CPU1_SA_DQS_DP<8>")
	)
	(segment
		(start 141.666214 -242.539266)
		(end 141.674596 -242.53444)
		(width 0.09525)
		(layer "In6.Cu")
		(net "M_K_CPU1_SA_DQS_DP<8>")
	)
	(segment
		(start 161.807906 -232.526078)
		(end 162.05454 -232.279444)
		(width 0.16002)
		(layer "In6.Cu")
		(net "M_K_CPU1_SA_DQS_DP<8>")
	)
	(segment
		(start 174.461424 -230.043228)
		(end 175.27016 -230.043228)
		(width 0.16002)
		(layer "In6.Cu")
		(net "M_K_CPU1_SA_DQS_DP<8>")
	)
	(segment
		(start 163.181538 -231.152446)
		(end 163.503356 -230.830628)
		(width 0.16002)
		(layer "In6.Cu")
		(net "M_K_CPU1_SA_DQS_DP<8>")
	)
	(segment
		(start 145.684748 -242.614958)
		(end 146.161252 -242.138454)
		(width 0.09525)
		(layer "In6.Cu")
		(net "M_K_CPU1_SA_DQS_DP<8>")
	)
	(segment
		(start 143.923004 -242.539266)
		(end 143.933418 -242.545362)
		(width 0.09525)
		(layer "In6.Cu")
		(net "M_K_CPU1_SA_DQS_DP<8>")
	)
	(segment
		(start 147.836636 -241.454686)
		(end 147.895564 -241.513614)
		(width 0.09525)
		(layer "In6.Cu")
		(net "M_K_CPU1_SA_DQS_DP<8>")
	)
	(segment
		(start 168.388284 -230.705406)
		(end 168.96588 -230.705406)
		(width 0.16002)
		(layer "In6.Cu")
		(net "M_K_CPU1_SA_DQS_DP<8>")
	)
	(segment
		(start 163.282122 -231.955594)
		(end 163.282122 -231.47909)
		(width 0.16002)
		(layer "In6.Cu")
		(net "M_K_CPU1_SA_DQS_DP<8>")
	)
	(segment
		(start 170.870118 -230.705406)
		(end 171.375324 -231.210612)
		(width 0.16002)
		(layer "In6.Cu")
		(net "M_K_CPU1_SA_DQS_DP<8>")
	)
	(segment
		(start 181.218078 -230.830628)
		(end 182.101998 -229.946708)
		(width 0.16002)
		(layer "In6.Cu")
		(net "M_K_CPU1_SA_DQS_DP<8>")
	)
	(segment
		(start 147.895564 -241.513614)
		(end 147.919186 -241.513614)
		(width 0.09525)
		(layer "In6.Cu")
		(net "M_K_CPU1_SA_DQS_DP<8>")
	)
	(segment
		(start 160.39719 -233.936794)
		(end 160.680908 -233.653076)
		(width 0.16002)
		(layer "In6.Cu")
		(net "M_K_CPU1_SA_DQS_DP<8>")
	)
	(segment
		(start 169.971212 -230.161846)
		(end 169.971212 -230.368348)
		(width 0.16002)
		(layer "In6.Cu")
		(net "M_K_CPU1_SA_DQS_DP<8>")
	)
	(segment
		(start 173.674024 -230.830628)
		(end 174.461424 -230.043228)
		(width 0.16002)
		(layer "In6.Cu")
		(net "M_K_CPU1_SA_DQS_DP<8>")
	)
	(segment
		(start 169.462958 -230.001826)
		(end 169.811192 -230.001826)
		(width 0.16002)
		(layer "In6.Cu")
		(net "M_K_CPU1_SA_DQS_DP<8>")
	)
	(segment
		(start 178.06924 -230.360474)
		(end 178.919378 -231.210612)
		(width 0.16002)
		(layer "In6.Cu")
		(net "M_K_CPU1_SA_DQS_DP<8>")
	)
	(segment
		(start 162.05454 -232.279444)
		(end 162.2806 -232.279444)
		(width 0.16002)
		(layer "In6.Cu")
		(net "M_K_CPU1_SA_DQS_DP<8>")
	)
	(segment
		(start 144.492726 -242.53444)
		(end 144.494758 -242.53317)
		(width 0.09525)
		(layer "In6.Cu")
		(net "M_K_CPU1_SA_DQS_DP<8>")
	)
	(segment
		(start 190.675514 -230.360474)
		(end 192.107566 -230.360474)
		(width 0.16002)
		(layer "In6.Cu")
		(net "M_K_CPU1_SA_DQS_DP<8>")
	)
	(segment
		(start 172.68952 -231.210612)
		(end 173.069504 -230.830628)
		(width 0.16002)
		(layer "In6.Cu")
		(net "M_K_CPU1_SA_DQS_DP<8>")
	)
	(segment
		(start 166.91737 -230.043228)
		(end 167.726106 -230.043228)
		(width 0.16002)
		(layer "In6.Cu")
		(net "M_K_CPU1_SA_DQS_DP<8>")
	)
	(segment
		(start 144.490186 -242.535964)
		(end 144.490948 -242.535456)
		(width 0.09525)
		(layer "In6.Cu")
		(net "M_K_CPU1_SA_DQS_DP<8>")
	)
	(segment
		(start 140.914882 -242.864386)
		(end 141.068806 -242.598956)
		(width 0.09525)
		(layer "In6.Cu")
		(net "M_K_CPU1_SA_DQS_DP<8>")
	)
	(segment
		(start 175.27016 -230.043228)
		(end 175.587406 -230.360474)
		(width 0.16002)
		(layer "In6.Cu")
		(net "M_K_CPU1_SA_DQS_DP<8>")
	)
	(segment
		(start 188.157612 -230.830628)
		(end 188.762132 -230.830628)
		(width 0.16002)
		(layer "In6.Cu")
		(net "M_K_CPU1_SA_DQS_DP<8>")
	)
	(segment
		(start 182.717694 -229.946708)
		(end 183.13146 -230.360474)
		(width 0.16002)
		(layer "In6.Cu")
		(net "M_K_CPU1_SA_DQS_DP<8>")
	)
	(segment
		(start 163.503356 -230.830628)
		(end 166.12997 -230.830628)
		(width 0.16002)
		(layer "In6.Cu")
		(net "M_K_CPU1_SA_DQS_DP<8>")
	)
	(segment
		(start 186.463432 -231.210612)
		(end 187.777628 -231.210612)
		(width 0.16002)
		(layer "In6.Cu")
		(net "M_K_CPU1_SA_DQS_DP<8>")
	)
	(segment
		(start 183.13146 -230.360474)
		(end 185.613294 -230.360474)
		(width 0.16002)
		(layer "In6.Cu")
		(net "M_K_CPU1_SA_DQS_DP<8>")
	)
	(segment
		(start 163.181538 -231.378506)
		(end 163.181538 -231.152446)
		(width 0.16002)
		(layer "In6.Cu")
		(net "M_K_CPU1_SA_DQS_DP<8>")
	)
	(segment
		(start 178.919378 -231.210612)
		(end 180.233574 -231.210612)
		(width 0.16002)
		(layer "In6.Cu")
		(net "M_K_CPU1_SA_DQS_DP<8>")
	)
	(segment
		(start 163.282122 -231.47909)
		(end 163.181538 -231.378506)
		(width 0.16002)
		(layer "In6.Cu")
		(net "M_K_CPU1_SA_DQS_DP<8>")
	)
	(segment
		(start 190.358268 -230.043228)
		(end 190.675514 -230.360474)
		(width 0.16002)
		(layer "In6.Cu")
		(net "M_K_CPU1_SA_DQS_DP<8>")
	)
	(segment
		(start 161.807906 -232.752138)
		(end 161.807906 -232.526078)
		(width 0.16002)
		(layer "In6.Cu")
		(net "M_K_CPU1_SA_DQS_DP<8>")
	)
	(segment
		(start 189.549532 -230.043228)
		(end 190.358268 -230.043228)
		(width 0.16002)
		(layer "In6.Cu")
		(net "M_K_CPU1_SA_DQS_DP<8>")
	)
	(segment
		(start 160.680908 -233.653076)
		(end 160.906968 -233.653076)
		(width 0.16002)
		(layer "In6.Cu")
		(net "M_K_CPU1_SA_DQS_DP<8>")
	)
	(segment
		(start 168.96588 -230.705406)
		(end 169.302938 -230.368348)
		(width 0.16002)
		(layer "In6.Cu")
		(net "M_K_CPU1_SA_DQS_DP<8>")
	)
	(segment
		(start 162.2806 -232.279444)
		(end 162.381184 -232.380028)
		(width 0.16002)
		(layer "In6.Cu")
		(net "M_K_CPU1_SA_DQS_DP<8>")
	)
	(segment
		(start 166.12997 -230.830628)
		(end 166.91737 -230.043228)
		(width 0.16002)
		(layer "In6.Cu")
		(net "M_K_CPU1_SA_DQS_DP<8>")
	)
	(segment
		(start 187.777628 -231.210612)
		(end 188.157612 -230.830628)
		(width 0.16002)
		(layer "In6.Cu")
		(net "M_K_CPU1_SA_DQS_DP<8>")
	)
	(segment
		(start 182.101998 -229.946708)
		(end 182.717694 -229.946708)
		(width 0.16002)
		(layer "In6.Cu")
		(net "M_K_CPU1_SA_DQS_DP<8>")
	)
	(arc
		(start 144.863058 -242.538758)
		(mid 144.998728 -242.595504)
		(end 145.14449 -242.614958)
		(width 0.09525)
		(layer "In6.Cu")
		(net "M_K_CPU1_SA_DQS_DP<8>")
	)
	(arc
		(start 141.189456 -242.58016)
		(mid 141.43242 -242.613147)
		(end 141.666214 -242.539266)
		(width 0.09525)
		(layer "In6.Cu")
		(net "M_K_CPU1_SA_DQS_DP<8>")
	)
	(arc
		(start 141.169644 -242.572286)
		(mid 141.179512 -242.576317)
		(end 141.189456 -242.58016)
		(width 0.09525)
		(layer "In6.Cu")
		(net "M_K_CPU1_SA_DQS_DP<8>")
	)
	(arc
		(start 142.983204 -242.539266)
		(mid 143.264636 -242.615021)
		(end 143.546068 -242.539266)
		(width 0.09525)
		(layer "In6.Cu")
		(net "M_K_CPU1_SA_DQS_DP<8>")
	)
	(arc
		(start 143.933418 -242.545362)
		(mid 144.210326 -242.615039)
		(end 144.485614 -242.539266)
		(width 0.09525)
		(layer "In6.Cu")
		(net "M_K_CPU1_SA_DQS_DP<8>")
	)
	(arc
		(start 142.606268 -242.539266)
		(mid 142.794736 -242.488589)
		(end 142.983204 -242.539266)
		(width 0.09525)
		(layer "In6.Cu")
		(net "M_K_CPU1_SA_DQS_DP<8>")
	)
	(arc
		(start 143.546068 -242.539266)
		(mid 143.727684 -242.488529)
		(end 143.911066 -242.532408)
		(width 0.09525)
		(layer "In6.Cu")
		(net "M_K_CPU1_SA_DQS_DP<8>")
	)
	(arc
		(start 141.674596 -242.53444)
		(mid 141.859628 -242.488526)
		(end 142.043404 -242.539266)
		(width 0.09525)
		(layer "In6.Cu")
		(net "M_K_CPU1_SA_DQS_DP<8>")
	)
	(arc
		(start 142.043404 -242.539266)
		(mid 142.324836 -242.615021)
		(end 142.606268 -242.539266)
		(width 0.09525)
		(layer "In6.Cu")
		(net "M_K_CPU1_SA_DQS_DP<8>")
	)
	(arc
		(start 144.494758 -242.53317)
		(mid 144.679625 -242.487907)
		(end 144.863058 -242.538758)
		(width 0.09525)
		(layer "In6.Cu")
		(net "M_K_CPU1_SA_DQS_DP<8>")
	)
	(segment
		(start 140.447776 -238.270288)
		(end 140.914882 -238.00435)
		(width 0.12954)
		(layer "F.Cu")
		(net "M_K_CPU1_SA_DQS_DP<7>")
	)
	(segment
		(start 147.895564 -235.874814)
		(end 147.919186 -235.874814)
		(width 0.09525)
		(layer "In6.Cu")
		(net "M_K_CPU1_SA_DQS_DP<7>")
	)
	(segment
		(start 175.27016 -220.693234)
		(end 175.587406 -221.01048)
		(width 0.16002)
		(layer "In6.Cu")
		(net "M_K_CPU1_SA_DQS_DP<7>")
	)
	(segment
		(start 163.998402 -221.480634)
		(end 166.12997 -221.480634)
		(width 0.16002)
		(layer "In6.Cu")
		(net "M_K_CPU1_SA_DQS_DP<7>")
	)
	(segment
		(start 146.603212 -236.26191)
		(end 147.147534 -236.26191)
		(width 0.09525)
		(layer "In6.Cu")
		(net "M_K_CPU1_SA_DQS_DP<7>")
	)
	(segment
		(start 167.726106 -220.693234)
		(end 168.043352 -221.01048)
		(width 0.16002)
		(layer "In6.Cu")
		(net "M_K_CPU1_SA_DQS_DP<7>")
	)
	(segment
		(start 162.28441 -223.194626)
		(end 163.998402 -221.480634)
		(width 0.16002)
		(layer "In6.Cu")
		(net "M_K_CPU1_SA_DQS_DP<7>")
	)
	(segment
		(start 180.613558 -221.480634)
		(end 181.218078 -221.480634)
		(width 0.16002)
		(layer "In6.Cu")
		(net "M_K_CPU1_SA_DQS_DP<7>")
	)
	(segment
		(start 152.724104 -233.661712)
		(end 152.724104 -233.435652)
		(width 0.16002)
		(layer "In6.Cu")
		(net "M_K_CPU1_SA_DQS_DP<7>")
	)
	(segment
		(start 154.503374 -233.170222)
		(end 154.503374 -232.693718)
		(width 0.16002)
		(layer "In6.Cu")
		(net "M_K_CPU1_SA_DQS_DP<7>")
	)
	(segment
		(start 143.923004 -237.67923)
		(end 143.933418 -237.685326)
		(width 0.09525)
		(layer "In6.Cu")
		(net "M_K_CPU1_SA_DQS_DP<7>")
	)
	(segment
		(start 174.461424 -220.693234)
		(end 175.27016 -220.693234)
		(width 0.16002)
		(layer "In6.Cu")
		(net "M_K_CPU1_SA_DQS_DP<7>")
	)
	(segment
		(start 154.503374 -232.693718)
		(end 154.097736 -232.28808)
		(width 0.16002)
		(layer "In6.Cu")
		(net "M_K_CPU1_SA_DQS_DP<7>")
	)
	(segment
		(start 146.350228 -236.514894)
		(end 146.603212 -236.26191)
		(width 0.09525)
		(layer "In6.Cu")
		(net "M_K_CPU1_SA_DQS_DP<7>")
	)
	(segment
		(start 178.06924 -221.01048)
		(end 178.919124 -221.860364)
		(width 0.16002)
		(layer "In6.Cu")
		(net "M_K_CPU1_SA_DQS_DP<7>")
	)
	(segment
		(start 152.705308 -234.968288)
		(end 153.129742 -234.543854)
		(width 0.16002)
		(layer "In6.Cu")
		(net "M_K_CPU1_SA_DQS_DP<7>")
	)
	(segment
		(start 143.911066 -237.672372)
		(end 143.923004 -237.67923)
		(width 0.09525)
		(layer "In6.Cu")
		(net "M_K_CPU1_SA_DQS_DP<7>")
	)
	(segment
		(start 147.836636 -235.815886)
		(end 147.895564 -235.874814)
		(width 0.09525)
		(layer "In6.Cu")
		(net "M_K_CPU1_SA_DQS_DP<7>")
	)
	(segment
		(start 151.823166 -234.56265)
		(end 152.228804 -234.968288)
		(width 0.16002)
		(layer "In6.Cu")
		(net "M_K_CPU1_SA_DQS_DP<7>")
	)
	(segment
		(start 183.13146 -221.01048)
		(end 185.613294 -221.01048)
		(width 0.16002)
		(layer "In6.Cu")
		(net "M_K_CPU1_SA_DQS_DP<7>")
	)
	(segment
		(start 178.919124 -221.860364)
		(end 180.233828 -221.860364)
		(width 0.16002)
		(layer "In6.Cu")
		(net "M_K_CPU1_SA_DQS_DP<7>")
	)
	(segment
		(start 186.463178 -221.860364)
		(end 187.777882 -221.860364)
		(width 0.16002)
		(layer "In6.Cu")
		(net "M_K_CPU1_SA_DQS_DP<7>")
	)
	(segment
		(start 141.666214 -237.67923)
		(end 141.674596 -237.674404)
		(width 0.09525)
		(layer "In6.Cu")
		(net "M_K_CPU1_SA_DQS_DP<7>")
	)
	(segment
		(start 170.525186 -221.01048)
		(end 171.37507 -221.860364)
		(width 0.16002)
		(layer "In6.Cu")
		(net "M_K_CPU1_SA_DQS_DP<7>")
	)
	(segment
		(start 154.097736 -232.06202)
		(end 162.28441 -223.875346)
		(width 0.16002)
		(layer "In6.Cu")
		(net "M_K_CPU1_SA_DQS_DP<7>")
	)
	(segment
		(start 181.218078 -221.480634)
		(end 182.005478 -220.693234)
		(width 0.16002)
		(layer "In6.Cu")
		(net "M_K_CPU1_SA_DQS_DP<7>")
	)
	(segment
		(start 190.358268 -220.693234)
		(end 190.675514 -221.01048)
		(width 0.16002)
		(layer "In6.Cu")
		(net "M_K_CPU1_SA_DQS_DP<7>")
	)
	(segment
		(start 153.129742 -234.06735)
		(end 152.724104 -233.661712)
		(width 0.16002)
		(layer "In6.Cu")
		(net "M_K_CPU1_SA_DQS_DP<7>")
	)
	(segment
		(start 153.129742 -234.543854)
		(end 153.129742 -234.06735)
		(width 0.16002)
		(layer "In6.Cu")
		(net "M_K_CPU1_SA_DQS_DP<7>")
	)
	(segment
		(start 147.593558 -235.815886)
		(end 147.836636 -235.815886)
		(width 0.09525)
		(layer "In6.Cu")
		(net "M_K_CPU1_SA_DQS_DP<7>")
	)
	(segment
		(start 153.602436 -233.594656)
		(end 154.07894 -233.594656)
		(width 0.16002)
		(layer "In6.Cu")
		(net "M_K_CPU1_SA_DQS_DP<7>")
	)
	(segment
		(start 173.069504 -221.480634)
		(end 173.674024 -221.480634)
		(width 0.16002)
		(layer "In6.Cu")
		(net "M_K_CPU1_SA_DQS_DP<7>")
	)
	(segment
		(start 140.914882 -238.00435)
		(end 141.068806 -237.73892)
		(width 0.09525)
		(layer "In6.Cu")
		(net "M_K_CPU1_SA_DQS_DP<7>")
	)
	(segment
		(start 188.762132 -221.480634)
		(end 189.549532 -220.693234)
		(width 0.16002)
		(layer "In6.Cu")
		(net "M_K_CPU1_SA_DQS_DP<7>")
	)
	(segment
		(start 171.37507 -221.860364)
		(end 172.689774 -221.860364)
		(width 0.16002)
		(layer "In6.Cu")
		(net "M_K_CPU1_SA_DQS_DP<7>")
	)
	(segment
		(start 147.919186 -235.874814)
		(end 150.284942 -235.874814)
		(width 0.16002)
		(layer "In6.Cu")
		(net "M_K_CPU1_SA_DQS_DP<7>")
	)
	(segment
		(start 152.970738 -233.189018)
		(end 153.196798 -233.189018)
		(width 0.16002)
		(layer "In6.Cu")
		(net "M_K_CPU1_SA_DQS_DP<7>")
	)
	(segment
		(start 172.689774 -221.860364)
		(end 173.069504 -221.480634)
		(width 0.16002)
		(layer "In6.Cu")
		(net "M_K_CPU1_SA_DQS_DP<7>")
	)
	(segment
		(start 166.91737 -220.693234)
		(end 167.726106 -220.693234)
		(width 0.16002)
		(layer "In6.Cu")
		(net "M_K_CPU1_SA_DQS_DP<7>")
	)
	(segment
		(start 194.33032 -220.861382)
		(end 194.604132 -221.135194)
		(width 0.16002)
		(layer "In6.Cu")
		(net "M_K_CPU1_SA_DQS_DP<7>")
	)
	(segment
		(start 168.043352 -221.01048)
		(end 170.525186 -221.01048)
		(width 0.16002)
		(layer "In6.Cu")
		(net "M_K_CPU1_SA_DQS_DP<7>")
	)
	(segment
		(start 144.485614 -237.67923)
		(end 144.497552 -237.672372)
		(width 0.09525)
		(layer "In6.Cu")
		(net "M_K_CPU1_SA_DQS_DP<7>")
	)
	(segment
		(start 146.350228 -236.79277)
		(end 146.350228 -236.514894)
		(width 0.09525)
		(layer "In6.Cu")
		(net "M_K_CPU1_SA_DQS_DP<7>")
	)
	(segment
		(start 153.196798 -233.189018)
		(end 153.602436 -233.594656)
		(width 0.16002)
		(layer "In6.Cu")
		(net "M_K_CPU1_SA_DQS_DP<7>")
	)
	(segment
		(start 141.068806 -237.73892)
		(end 141.169644 -237.71225)
		(width 0.09525)
		(layer "In6.Cu")
		(net "M_K_CPU1_SA_DQS_DP<7>")
	)
	(segment
		(start 166.12997 -221.480634)
		(end 166.91737 -220.693234)
		(width 0.16002)
		(layer "In6.Cu")
		(net "M_K_CPU1_SA_DQS_DP<7>")
	)
	(segment
		(start 182.814214 -220.693234)
		(end 183.13146 -221.01048)
		(width 0.16002)
		(layer "In6.Cu")
		(net "M_K_CPU1_SA_DQS_DP<7>")
	)
	(segment
		(start 182.005478 -220.693234)
		(end 182.814214 -220.693234)
		(width 0.16002)
		(layer "In6.Cu")
		(net "M_K_CPU1_SA_DQS_DP<7>")
	)
	(segment
		(start 192.256664 -220.861382)
		(end 194.33032 -220.861382)
		(width 0.16002)
		(layer "In6.Cu")
		(net "M_K_CPU1_SA_DQS_DP<7>")
	)
	(segment
		(start 173.674024 -221.480634)
		(end 174.461424 -220.693234)
		(width 0.16002)
		(layer "In6.Cu")
		(net "M_K_CPU1_SA_DQS_DP<7>")
	)
	(segment
		(start 192.107566 -221.01048)
		(end 192.256664 -220.861382)
		(width 0.16002)
		(layer "In6.Cu")
		(net "M_K_CPU1_SA_DQS_DP<7>")
	)
	(segment
		(start 185.613294 -221.01048)
		(end 186.463178 -221.860364)
		(width 0.16002)
		(layer "In6.Cu")
		(net "M_K_CPU1_SA_DQS_DP<7>")
	)
	(segment
		(start 175.587406 -221.01048)
		(end 178.06924 -221.01048)
		(width 0.16002)
		(layer "In6.Cu")
		(net "M_K_CPU1_SA_DQS_DP<7>")
	)
	(segment
		(start 152.724104 -233.435652)
		(end 152.970738 -233.189018)
		(width 0.16002)
		(layer "In6.Cu")
		(net "M_K_CPU1_SA_DQS_DP<7>")
	)
	(segment
		(start 187.777882 -221.860364)
		(end 188.157612 -221.480634)
		(width 0.16002)
		(layer "In6.Cu")
		(net "M_K_CPU1_SA_DQS_DP<7>")
	)
	(segment
		(start 154.097736 -232.28808)
		(end 154.097736 -232.06202)
		(width 0.16002)
		(layer "In6.Cu")
		(net "M_K_CPU1_SA_DQS_DP<7>")
	)
	(segment
		(start 188.157612 -221.480634)
		(end 188.762132 -221.480634)
		(width 0.16002)
		(layer "In6.Cu")
		(net "M_K_CPU1_SA_DQS_DP<7>")
	)
	(segment
		(start 180.233828 -221.860364)
		(end 180.613558 -221.480634)
		(width 0.16002)
		(layer "In6.Cu")
		(net "M_K_CPU1_SA_DQS_DP<7>")
	)
	(segment
		(start 154.07894 -233.594656)
		(end 154.503374 -233.170222)
		(width 0.16002)
		(layer "In6.Cu")
		(net "M_K_CPU1_SA_DQS_DP<7>")
	)
	(segment
		(start 190.675514 -221.01048)
		(end 192.107566 -221.01048)
		(width 0.16002)
		(layer "In6.Cu")
		(net "M_K_CPU1_SA_DQS_DP<7>")
	)
	(segment
		(start 145.553684 -237.589314)
		(end 146.350228 -236.79277)
		(width 0.09525)
		(layer "In6.Cu")
		(net "M_K_CPU1_SA_DQS_DP<7>")
	)
	(segment
		(start 162.28441 -223.875346)
		(end 162.28441 -223.194626)
		(width 0.16002)
		(layer "In6.Cu")
		(net "M_K_CPU1_SA_DQS_DP<7>")
	)
	(segment
		(start 189.549532 -220.693234)
		(end 190.358268 -220.693234)
		(width 0.16002)
		(layer "In6.Cu")
		(net "M_K_CPU1_SA_DQS_DP<7>")
	)
	(segment
		(start 150.284942 -235.874814)
		(end 151.597106 -234.56265)
		(width 0.16002)
		(layer "In6.Cu")
		(net "M_K_CPU1_SA_DQS_DP<7>")
	)
	(segment
		(start 152.228804 -234.968288)
		(end 152.705308 -234.968288)
		(width 0.16002)
		(layer "In6.Cu")
		(net "M_K_CPU1_SA_DQS_DP<7>")
	)
	(segment
		(start 147.147534 -236.26191)
		(end 147.593558 -235.815886)
		(width 0.09525)
		(layer "In6.Cu")
		(net "M_K_CPU1_SA_DQS_DP<7>")
	)
	(segment
		(start 151.597106 -234.56265)
		(end 151.823166 -234.56265)
		(width 0.16002)
		(layer "In6.Cu")
		(net "M_K_CPU1_SA_DQS_DP<7>")
	)
	(arc
		(start 143.546068 -237.67923)
		(mid 143.727684 -237.628493)
		(end 143.911066 -237.672372)
		(width 0.09525)
		(layer "In6.Cu")
		(net "M_K_CPU1_SA_DQS_DP<7>")
	)
	(arc
		(start 141.169644 -237.71225)
		(mid 141.421785 -237.75382)
		(end 141.666214 -237.67923)
		(width 0.09525)
		(layer "In6.Cu")
		(net "M_K_CPU1_SA_DQS_DP<7>")
	)
	(arc
		(start 142.606268 -237.67923)
		(mid 142.794736 -237.628553)
		(end 142.983204 -237.67923)
		(width 0.09525)
		(layer "In6.Cu")
		(net "M_K_CPU1_SA_DQS_DP<7>")
	)
	(arc
		(start 141.674596 -237.674404)
		(mid 141.859628 -237.62849)
		(end 142.043404 -237.67923)
		(width 0.09525)
		(layer "In6.Cu")
		(net "M_K_CPU1_SA_DQS_DP<7>")
	)
	(arc
		(start 144.863058 -237.67923)
		(mid 145.223632 -237.751671)
		(end 145.553684 -237.589314)
		(width 0.09525)
		(layer "In6.Cu")
		(net "M_K_CPU1_SA_DQS_DP<7>")
	)
	(arc
		(start 142.983204 -237.67923)
		(mid 143.264636 -237.754985)
		(end 143.546068 -237.67923)
		(width 0.09525)
		(layer "In6.Cu")
		(net "M_K_CPU1_SA_DQS_DP<7>")
	)
	(arc
		(start 143.933418 -237.685326)
		(mid 144.210326 -237.755003)
		(end 144.485614 -237.67923)
		(width 0.09525)
		(layer "In6.Cu")
		(net "M_K_CPU1_SA_DQS_DP<7>")
	)
	(arc
		(start 142.043404 -237.67923)
		(mid 142.324836 -237.754985)
		(end 142.606268 -237.67923)
		(width 0.09525)
		(layer "In6.Cu")
		(net "M_K_CPU1_SA_DQS_DP<7>")
	)
	(arc
		(start 144.497552 -237.672372)
		(mid 144.681187 -237.628422)
		(end 144.863058 -237.67923)
		(width 0.09525)
		(layer "In6.Cu")
		(net "M_K_CPU1_SA_DQS_DP<7>")
	)
	(segment
		(start 140.447776 -233.410252)
		(end 140.914882 -233.144314)
		(width 0.12954)
		(layer "F.Cu")
		(net "M_K_CPU1_SA_DQS_DP<6>")
	)
	(segment
		(start 157.778704 -218.447874)
		(end 157.778704 -218.221814)
		(width 0.16002)
		(layer "In6.Cu")
		(net "M_K_CPU1_SA_DQS_DP<6>")
	)
	(segment
		(start 157.778704 -218.221814)
		(end 158.0261 -217.974418)
		(width 0.16002)
		(layer "In6.Cu")
		(net "M_K_CPU1_SA_DQS_DP<6>")
	)
	(segment
		(start 162.373056 -213.853522)
		(end 162.374834 -213.8553)
		(width 0.16002)
		(layer "In6.Cu")
		(net "M_K_CPU1_SA_DQS_DP<6>")
	)
	(segment
		(start 149.93493 -228.259132)
		(end 156.105606 -222.088456)
		(width 0.16002)
		(layer "In6.Cu")
		(net "M_K_CPU1_SA_DQS_DP<6>")
	)
	(segment
		(start 159.154114 -217.552524)
		(end 159.154114 -217.07602)
		(width 0.16002)
		(layer "In6.Cu")
		(net "M_K_CPU1_SA_DQS_DP<6>")
	)
	(segment
		(start 174.461424 -211.34324)
		(end 175.27016 -211.34324)
		(width 0.16002)
		(layer "In6.Cu")
		(net "M_K_CPU1_SA_DQS_DP<6>")
	)
	(segment
		(start 157.780482 -218.449652)
		(end 157.778704 -218.447874)
		(width 0.16002)
		(layer "In6.Cu")
		(net "M_K_CPU1_SA_DQS_DP<6>")
	)
	(segment
		(start 156.652468 -219.34805)
		(end 156.878528 -219.34805)
		(width 0.16002)
		(layer "In6.Cu")
		(net "M_K_CPU1_SA_DQS_DP<6>")
	)
	(segment
		(start 160.999424 -215.227154)
		(end 161.001202 -215.228932)
		(width 0.16002)
		(layer "In6.Cu")
		(net "M_K_CPU1_SA_DQS_DP<6>")
	)
	(segment
		(start 160.527746 -215.702388)
		(end 160.525968 -215.70061)
		(width 0.16002)
		(layer "In6.Cu")
		(net "M_K_CPU1_SA_DQS_DP<6>")
	)
	(segment
		(start 147.919186 -230.27513)
		(end 149.93493 -228.259386)
		(width 0.16002)
		(layer "In6.Cu")
		(net "M_K_CPU1_SA_DQS_DP<6>")
	)
	(segment
		(start 167.726106 -211.34324)
		(end 168.043352 -211.660486)
		(width 0.16002)
		(layer "In6.Cu")
		(net "M_K_CPU1_SA_DQS_DP<6>")
	)
	(segment
		(start 172.689774 -212.51037)
		(end 173.069504 -212.13064)
		(width 0.16002)
		(layer "In6.Cu")
		(net "M_K_CPU1_SA_DQS_DP<6>")
	)
	(segment
		(start 173.674024 -212.13064)
		(end 174.461424 -211.34324)
		(width 0.16002)
		(layer "In6.Cu")
		(net "M_K_CPU1_SA_DQS_DP<6>")
	)
	(segment
		(start 182.72252 -211.251546)
		(end 183.13146 -211.660486)
		(width 0.16002)
		(layer "In6.Cu")
		(net "M_K_CPU1_SA_DQS_DP<6>")
	)
	(segment
		(start 192.107566 -211.660486)
		(end 192.256664 -211.511388)
		(width 0.16002)
		(layer "In6.Cu")
		(net "M_K_CPU1_SA_DQS_DP<6>")
	)
	(segment
		(start 168.043352 -211.660486)
		(end 170.525186 -211.660486)
		(width 0.16002)
		(layer "In6.Cu")
		(net "M_K_CPU1_SA_DQS_DP<6>")
	)
	(segment
		(start 163.27501 -212.955124)
		(end 163.273232 -212.953346)
		(width 0.16002)
		(layer "In6.Cu")
		(net "M_K_CPU1_SA_DQS_DP<6>")
	)
	(segment
		(start 164.575998 -212.13064)
		(end 166.12997 -212.13064)
		(width 0.16002)
		(layer "In6.Cu")
		(net "M_K_CPU1_SA_DQS_DP<6>")
	)
	(segment
		(start 185.613294 -211.660486)
		(end 186.463178 -212.51037)
		(width 0.16002)
		(layer "In6.Cu")
		(net "M_K_CPU1_SA_DQS_DP<6>")
	)
	(segment
		(start 178.919124 -212.51037)
		(end 180.233828 -212.51037)
		(width 0.16002)
		(layer "In6.Cu")
		(net "M_K_CPU1_SA_DQS_DP<6>")
	)
	(segment
		(start 190.358268 -211.34324)
		(end 190.675514 -211.660486)
		(width 0.16002)
		(layer "In6.Cu")
		(net "M_K_CPU1_SA_DQS_DP<6>")
	)
	(segment
		(start 161.477706 -215.228932)
		(end 161.901378 -214.80526)
		(width 0.16002)
		(layer "In6.Cu")
		(net "M_K_CPU1_SA_DQS_DP<6>")
	)
	(segment
		(start 147.818602 -230.291894)
		(end 147.902422 -230.291894)
		(width 0.09525)
		(layer "In6.Cu")
		(net "M_K_CPU1_SA_DQS_DP<6>")
	)
	(segment
		(start 187.777882 -212.51037)
		(end 188.157612 -212.13064)
		(width 0.16002)
		(layer "In6.Cu")
		(net "M_K_CPU1_SA_DQS_DP<6>")
	)
	(segment
		(start 156.40685 -220.299788)
		(end 156.40685 -219.823284)
		(width 0.16002)
		(layer "In6.Cu")
		(net "M_K_CPU1_SA_DQS_DP<6>")
	)
	(segment
		(start 160.525968 -215.70061)
		(end 160.525968 -215.47455)
		(width 0.16002)
		(layer "In6.Cu")
		(net "M_K_CPU1_SA_DQS_DP<6>")
	)
	(segment
		(start 157.35681 -219.349828)
		(end 157.780482 -218.926156)
		(width 0.16002)
		(layer "In6.Cu")
		(net "M_K_CPU1_SA_DQS_DP<6>")
	)
	(segment
		(start 144.485868 -232.819194)
		(end 144.49425 -232.814368)
		(width 0.09525)
		(layer "In6.Cu")
		(net "M_K_CPU1_SA_DQS_DP<6>")
	)
	(segment
		(start 161.8996 -214.100918)
		(end 162.146996 -213.853522)
		(width 0.16002)
		(layer "In6.Cu")
		(net "M_K_CPU1_SA_DQS_DP<6>")
	)
	(segment
		(start 186.463178 -212.51037)
		(end 187.777882 -212.51037)
		(width 0.16002)
		(layer "In6.Cu")
		(net "M_K_CPU1_SA_DQS_DP<6>")
	)
	(segment
		(start 161.901378 -214.80526)
		(end 161.901378 -214.328756)
		(width 0.16002)
		(layer "In6.Cu")
		(net "M_K_CPU1_SA_DQS_DP<6>")
	)
	(segment
		(start 162.851338 -213.8553)
		(end 163.27501 -213.431628)
		(width 0.16002)
		(layer "In6.Cu")
		(net "M_K_CPU1_SA_DQS_DP<6>")
	)
	(segment
		(start 147.466304 -230.644192)
		(end 147.818602 -230.291894)
		(width 0.09525)
		(layer "In6.Cu")
		(net "M_K_CPU1_SA_DQS_DP<6>")
	)
	(segment
		(start 180.613558 -212.13064)
		(end 181.218078 -212.13064)
		(width 0.16002)
		(layer "In6.Cu")
		(net "M_K_CPU1_SA_DQS_DP<6>")
	)
	(segment
		(start 159.399732 -216.600786)
		(end 159.625792 -216.600786)
		(width 0.16002)
		(layer "In6.Cu")
		(net "M_K_CPU1_SA_DQS_DP<6>")
	)
	(segment
		(start 141.666214 -232.819194)
		(end 141.674596 -232.814368)
		(width 0.09525)
		(layer "In6.Cu")
		(net "M_K_CPU1_SA_DQS_DP<6>")
	)
	(segment
		(start 163.746688 -212.47989)
		(end 163.748466 -212.481668)
		(width 0.16002)
		(layer "In6.Cu")
		(net "M_K_CPU1_SA_DQS_DP<6>")
	)
	(segment
		(start 182.097172 -211.251546)
		(end 182.72252 -211.251546)
		(width 0.16002)
		(layer "In6.Cu")
		(net "M_K_CPU1_SA_DQS_DP<6>")
	)
	(segment
		(start 158.730442 -217.976196)
		(end 159.154114 -217.552524)
		(width 0.16002)
		(layer "In6.Cu")
		(net "M_K_CPU1_SA_DQS_DP<6>")
	)
	(segment
		(start 183.13146 -211.660486)
		(end 185.613294 -211.660486)
		(width 0.16002)
		(layer "In6.Cu")
		(net "M_K_CPU1_SA_DQS_DP<6>")
	)
	(segment
		(start 194.33032 -211.511388)
		(end 194.604132 -211.7852)
		(width 0.16002)
		(layer "In6.Cu")
		(net "M_K_CPU1_SA_DQS_DP<6>")
	)
	(segment
		(start 166.91737 -211.34324)
		(end 167.726106 -211.34324)
		(width 0.16002)
		(layer "In6.Cu")
		(net "M_K_CPU1_SA_DQS_DP<6>")
	)
	(segment
		(start 160.527746 -216.178892)
		(end 160.527746 -215.702388)
		(width 0.16002)
		(layer "In6.Cu")
		(net "M_K_CPU1_SA_DQS_DP<6>")
	)
	(segment
		(start 171.37507 -212.51037)
		(end 172.689774 -212.51037)
		(width 0.16002)
		(layer "In6.Cu")
		(net "M_K_CPU1_SA_DQS_DP<6>")
	)
	(segment
		(start 145.540984 -232.730548)
		(end 146.182588 -232.088944)
		(width 0.09525)
		(layer "In6.Cu")
		(net "M_K_CPU1_SA_DQS_DP<6>")
	)
	(segment
		(start 156.105606 -220.601032)
		(end 156.40685 -220.299788)
		(width 0.16002)
		(layer "In6.Cu")
		(net "M_K_CPU1_SA_DQS_DP<6>")
	)
	(segment
		(start 158.0261 -217.974418)
		(end 158.25216 -217.974418)
		(width 0.16002)
		(layer "In6.Cu")
		(net "M_K_CPU1_SA_DQS_DP<6>")
	)
	(segment
		(start 156.878528 -219.34805)
		(end 156.880306 -219.349828)
		(width 0.16002)
		(layer "In6.Cu")
		(net "M_K_CPU1_SA_DQS_DP<6>")
	)
	(segment
		(start 147.902422 -230.291894)
		(end 147.919186 -230.27513)
		(width 0.09525)
		(layer "In6.Cu")
		(net "M_K_CPU1_SA_DQS_DP<6>")
	)
	(segment
		(start 178.06924 -211.660486)
		(end 178.919124 -212.51037)
		(width 0.16002)
		(layer "In6.Cu")
		(net "M_K_CPU1_SA_DQS_DP<6>")
	)
	(segment
		(start 163.273232 -212.953346)
		(end 163.273232 -212.727286)
		(width 0.16002)
		(layer "In6.Cu")
		(net "M_K_CPU1_SA_DQS_DP<6>")
	)
	(segment
		(start 158.25216 -217.974418)
		(end 158.253938 -217.976196)
		(width 0.16002)
		(layer "In6.Cu")
		(net "M_K_CPU1_SA_DQS_DP<6>")
	)
	(segment
		(start 146.182588 -231.525826)
		(end 147.064222 -230.644192)
		(width 0.09525)
		(layer "In6.Cu")
		(net "M_K_CPU1_SA_DQS_DP<6>")
	)
	(segment
		(start 159.152336 -216.848182)
		(end 159.399732 -216.600786)
		(width 0.16002)
		(layer "In6.Cu")
		(net "M_K_CPU1_SA_DQS_DP<6>")
	)
	(segment
		(start 188.157612 -212.13064)
		(end 188.762132 -212.13064)
		(width 0.16002)
		(layer "In6.Cu")
		(net "M_K_CPU1_SA_DQS_DP<6>")
	)
	(segment
		(start 140.914882 -233.144314)
		(end 141.068806 -232.878884)
		(width 0.09525)
		(layer "In6.Cu")
		(net "M_K_CPU1_SA_DQS_DP<6>")
	)
	(segment
		(start 159.152336 -217.074242)
		(end 159.152336 -216.848182)
		(width 0.16002)
		(layer "In6.Cu")
		(net "M_K_CPU1_SA_DQS_DP<6>")
	)
	(segment
		(start 161.001202 -215.228932)
		(end 161.477706 -215.228932)
		(width 0.16002)
		(layer "In6.Cu")
		(net "M_K_CPU1_SA_DQS_DP<6>")
	)
	(segment
		(start 158.253938 -217.976196)
		(end 158.730442 -217.976196)
		(width 0.16002)
		(layer "In6.Cu")
		(net "M_K_CPU1_SA_DQS_DP<6>")
	)
	(segment
		(start 175.27016 -211.34324)
		(end 175.587406 -211.660486)
		(width 0.16002)
		(layer "In6.Cu")
		(net "M_K_CPU1_SA_DQS_DP<6>")
	)
	(segment
		(start 173.069504 -212.13064)
		(end 173.674024 -212.13064)
		(width 0.16002)
		(layer "In6.Cu")
		(net "M_K_CPU1_SA_DQS_DP<6>")
	)
	(segment
		(start 160.104074 -216.602564)
		(end 160.527746 -216.178892)
		(width 0.16002)
		(layer "In6.Cu")
		(net "M_K_CPU1_SA_DQS_DP<6>")
	)
	(segment
		(start 189.549532 -211.34324)
		(end 190.358268 -211.34324)
		(width 0.16002)
		(layer "In6.Cu")
		(net "M_K_CPU1_SA_DQS_DP<6>")
	)
	(segment
		(start 141.068806 -232.878884)
		(end 141.169644 -232.852214)
		(width 0.09525)
		(layer "In6.Cu")
		(net "M_K_CPU1_SA_DQS_DP<6>")
	)
	(segment
		(start 156.880306 -219.349828)
		(end 157.35681 -219.349828)
		(width 0.16002)
		(layer "In6.Cu")
		(net "M_K_CPU1_SA_DQS_DP<6>")
	)
	(segment
		(start 149.93493 -228.259386)
		(end 149.93493 -228.259132)
		(width 0.16002)
		(layer "In6.Cu")
		(net "M_K_CPU1_SA_DQS_DP<6>")
	)
	(segment
		(start 160.525968 -215.47455)
		(end 160.773364 -215.227154)
		(width 0.16002)
		(layer "In6.Cu")
		(net "M_K_CPU1_SA_DQS_DP<6>")
	)
	(segment
		(start 145.41119 -232.82783)
		(end 145.425922 -232.819194)
		(width 0.09525)
		(layer "In6.Cu")
		(net "M_K_CPU1_SA_DQS_DP<6>")
	)
	(segment
		(start 163.273232 -212.727286)
		(end 163.520628 -212.47989)
		(width 0.16002)
		(layer "In6.Cu")
		(net "M_K_CPU1_SA_DQS_DP<6>")
	)
	(segment
		(start 163.748466 -212.481668)
		(end 164.22497 -212.481668)
		(width 0.16002)
		(layer "In6.Cu")
		(net "M_K_CPU1_SA_DQS_DP<6>")
	)
	(segment
		(start 162.374834 -213.8553)
		(end 162.851338 -213.8553)
		(width 0.16002)
		(layer "In6.Cu")
		(net "M_K_CPU1_SA_DQS_DP<6>")
	)
	(segment
		(start 156.105606 -222.088456)
		(end 156.105606 -220.601032)
		(width 0.16002)
		(layer "In6.Cu")
		(net "M_K_CPU1_SA_DQS_DP<6>")
	)
	(segment
		(start 192.256664 -211.511388)
		(end 194.33032 -211.511388)
		(width 0.16002)
		(layer "In6.Cu")
		(net "M_K_CPU1_SA_DQS_DP<6>")
	)
	(segment
		(start 161.8996 -214.326978)
		(end 161.8996 -214.100918)
		(width 0.16002)
		(layer "In6.Cu")
		(net "M_K_CPU1_SA_DQS_DP<6>")
	)
	(segment
		(start 159.62757 -216.602564)
		(end 160.104074 -216.602564)
		(width 0.16002)
		(layer "In6.Cu")
		(net "M_K_CPU1_SA_DQS_DP<6>")
	)
	(segment
		(start 160.773364 -215.227154)
		(end 160.999424 -215.227154)
		(width 0.16002)
		(layer "In6.Cu")
		(net "M_K_CPU1_SA_DQS_DP<6>")
	)
	(segment
		(start 181.218078 -212.13064)
		(end 182.097172 -211.251546)
		(width 0.16002)
		(layer "In6.Cu")
		(net "M_K_CPU1_SA_DQS_DP<6>")
	)
	(segment
		(start 156.405072 -219.595446)
		(end 156.652468 -219.34805)
		(width 0.16002)
		(layer "In6.Cu")
		(net "M_K_CPU1_SA_DQS_DP<6>")
	)
	(segment
		(start 164.22497 -212.481668)
		(end 164.575998 -212.13064)
		(width 0.16002)
		(layer "In6.Cu")
		(net "M_K_CPU1_SA_DQS_DP<6>")
	)
	(segment
		(start 162.146996 -213.853522)
		(end 162.373056 -213.853522)
		(width 0.16002)
		(layer "In6.Cu")
		(net "M_K_CPU1_SA_DQS_DP<6>")
	)
	(segment
		(start 188.762132 -212.13064)
		(end 189.549532 -211.34324)
		(width 0.16002)
		(layer "In6.Cu")
		(net "M_K_CPU1_SA_DQS_DP<6>")
	)
	(segment
		(start 147.064222 -230.644192)
		(end 147.466304 -230.644192)
		(width 0.09525)
		(layer "In6.Cu")
		(net "M_K_CPU1_SA_DQS_DP<6>")
	)
	(segment
		(start 146.182588 -232.088944)
		(end 146.182588 -231.525826)
		(width 0.09525)
		(layer "In6.Cu")
		(net "M_K_CPU1_SA_DQS_DP<6>")
	)
	(segment
		(start 143.914876 -232.814368)
		(end 143.923258 -232.819194)
		(width 0.09525)
		(layer "In6.Cu")
		(net "M_K_CPU1_SA_DQS_DP<6>")
	)
	(segment
		(start 190.675514 -211.660486)
		(end 192.107566 -211.660486)
		(width 0.16002)
		(layer "In6.Cu")
		(net "M_K_CPU1_SA_DQS_DP<6>")
	)
	(segment
		(start 157.780482 -218.926156)
		(end 157.780482 -218.449652)
		(width 0.16002)
		(layer "In6.Cu")
		(net "M_K_CPU1_SA_DQS_DP<6>")
	)
	(segment
		(start 163.27501 -213.431628)
		(end 163.27501 -212.955124)
		(width 0.16002)
		(layer "In6.Cu")
		(net "M_K_CPU1_SA_DQS_DP<6>")
	)
	(segment
		(start 166.12997 -212.13064)
		(end 166.91737 -211.34324)
		(width 0.16002)
		(layer "In6.Cu")
		(net "M_K_CPU1_SA_DQS_DP<6>")
	)
	(segment
		(start 175.587406 -211.660486)
		(end 178.06924 -211.660486)
		(width 0.16002)
		(layer "In6.Cu")
		(net "M_K_CPU1_SA_DQS_DP<6>")
	)
	(segment
		(start 159.625792 -216.600786)
		(end 159.62757 -216.602564)
		(width 0.16002)
		(layer "In6.Cu")
		(net "M_K_CPU1_SA_DQS_DP<6>")
	)
	(segment
		(start 156.40685 -219.823284)
		(end 156.405072 -219.821506)
		(width 0.16002)
		(layer "In6.Cu")
		(net "M_K_CPU1_SA_DQS_DP<6>")
	)
	(segment
		(start 161.901378 -214.328756)
		(end 161.8996 -214.326978)
		(width 0.16002)
		(layer "In6.Cu")
		(net "M_K_CPU1_SA_DQS_DP<6>")
	)
	(segment
		(start 143.923258 -232.819194)
		(end 143.933672 -232.82529)
		(width 0.09525)
		(layer "In6.Cu")
		(net "M_K_CPU1_SA_DQS_DP<6>")
	)
	(segment
		(start 159.154114 -217.07602)
		(end 159.152336 -217.074242)
		(width 0.16002)
		(layer "In6.Cu")
		(net "M_K_CPU1_SA_DQS_DP<6>")
	)
	(segment
		(start 170.525186 -211.660486)
		(end 171.37507 -212.51037)
		(width 0.16002)
		(layer "In6.Cu")
		(net "M_K_CPU1_SA_DQS_DP<6>")
	)
	(segment
		(start 163.520628 -212.47989)
		(end 163.746688 -212.47989)
		(width 0.16002)
		(layer "In6.Cu")
		(net "M_K_CPU1_SA_DQS_DP<6>")
	)
	(segment
		(start 156.405072 -219.821506)
		(end 156.405072 -219.595446)
		(width 0.16002)
		(layer "In6.Cu")
		(net "M_K_CPU1_SA_DQS_DP<6>")
	)
	(segment
		(start 180.233828 -212.51037)
		(end 180.613558 -212.13064)
		(width 0.16002)
		(layer "In6.Cu")
		(net "M_K_CPU1_SA_DQS_DP<6>")
	)
	(arc
		(start 141.674596 -232.814368)
		(mid 141.859628 -232.768454)
		(end 142.043404 -232.819194)
		(width 0.09525)
		(layer "In6.Cu")
		(net "M_K_CPU1_SA_DQS_DP<6>")
	)
	(arc
		(start 142.043404 -232.819194)
		(mid 142.324836 -232.894949)
		(end 142.606268 -232.819194)
		(width 0.09525)
		(layer "In6.Cu")
		(net "M_K_CPU1_SA_DQS_DP<6>")
	)
	(arc
		(start 142.983204 -232.819194)
		(mid 143.264636 -232.894949)
		(end 143.546068 -232.819194)
		(width 0.09525)
		(layer "In6.Cu")
		(net "M_K_CPU1_SA_DQS_DP<6>")
	)
	(arc
		(start 144.49425 -232.814368)
		(mid 144.679282 -232.768454)
		(end 144.863058 -232.819194)
		(width 0.09525)
		(layer "In6.Cu")
		(net "M_K_CPU1_SA_DQS_DP<6>")
	)
	(arc
		(start 142.606268 -232.819194)
		(mid 142.794736 -232.768517)
		(end 142.983204 -232.819194)
		(width 0.09525)
		(layer "In6.Cu")
		(net "M_K_CPU1_SA_DQS_DP<6>")
	)
	(arc
		(start 141.169644 -232.852214)
		(mid 141.421785 -232.893784)
		(end 141.666214 -232.819194)
		(width 0.09525)
		(layer "In6.Cu")
		(net "M_K_CPU1_SA_DQS_DP<6>")
	)
	(arc
		(start 143.546068 -232.819194)
		(mid 143.729843 -232.768422)
		(end 143.914876 -232.814368)
		(width 0.09525)
		(layer "In6.Cu")
		(net "M_K_CPU1_SA_DQS_DP<6>")
	)
	(arc
		(start 143.933672 -232.82529)
		(mid 144.21058 -232.894967)
		(end 144.485868 -232.819194)
		(width 0.09525)
		(layer "In6.Cu")
		(net "M_K_CPU1_SA_DQS_DP<6>")
	)
	(arc
		(start 144.863058 -232.819194)
		(mid 145.135986 -232.895008)
		(end 145.41119 -232.82783)
		(width 0.09525)
		(layer "In6.Cu")
		(net "M_K_CPU1_SA_DQS_DP<6>")
	)
	(arc
		(start 145.425922 -232.819194)
		(mid 145.486337 -232.778614)
		(end 145.540984 -232.730548)
		(width 0.09525)
		(layer "In6.Cu")
		(net "M_K_CPU1_SA_DQS_DP<6>")
	)
	(segment
		(start 140.447776 -228.55047)
		(end 140.914882 -228.284532)
		(width 0.12954)
		(layer "F.Cu")
		(net "M_K_CPU1_SA_DQS_DP<5>")
	)
	(segment
		(start 187.777882 -203.160376)
		(end 188.157612 -202.780646)
		(width 0.16002)
		(layer "In6.Cu")
		(net "M_K_CPU1_SA_DQS_DP<5>")
	)
	(segment
		(start 171.37507 -203.160376)
		(end 172.689774 -203.160376)
		(width 0.16002)
		(layer "In6.Cu")
		(net "M_K_CPU1_SA_DQS_DP<5>")
	)
	(segment
		(start 154.579828 -212.523324)
		(end 154.47899 -212.422486)
		(width 0.16002)
		(layer "In6.Cu")
		(net "M_K_CPU1_SA_DQS_DP<5>")
	)
	(segment
		(start 175.27016 -201.993246)
		(end 175.587406 -202.310492)
		(width 0.16002)
		(layer "In6.Cu")
		(net "M_K_CPU1_SA_DQS_DP<5>")
	)
	(segment
		(start 140.914882 -228.284532)
		(end 141.068806 -228.019102)
		(width 0.09525)
		(layer "In6.Cu")
		(net "M_K_CPU1_SA_DQS_DP<5>")
	)
	(segment
		(start 151.40813 -216.171526)
		(end 151.832564 -215.747092)
		(width 0.16002)
		(layer "In6.Cu")
		(net "M_K_CPU1_SA_DQS_DP<5>")
	)
	(segment
		(start 173.069504 -202.780646)
		(end 173.674024 -202.780646)
		(width 0.16002)
		(layer "In6.Cu")
		(net "M_K_CPU1_SA_DQS_DP<5>")
	)
	(segment
		(start 154.47899 -212.422486)
		(end 154.47899 -212.196426)
		(width 0.16002)
		(layer "In6.Cu")
		(net "M_K_CPU1_SA_DQS_DP<5>")
	)
	(segment
		(start 145.896076 -223.909382)
		(end 145.934176 -223.887284)
		(width 0.09525)
		(layer "In6.Cu")
		(net "M_K_CPU1_SA_DQS_DP<5>")
	)
	(segment
		(start 148.55444 -220.924628)
		(end 148.554694 -220.924628)
		(width 0.16002)
		(layer "In6.Cu")
		(net "M_K_CPU1_SA_DQS_DP<5>")
	)
	(segment
		(start 150.12797 -216.547446)
		(end 150.604728 -216.070688)
		(width 0.16002)
		(layer "In6.Cu")
		(net "M_K_CPU1_SA_DQS_DP<5>")
	)
	(segment
		(start 157.226254 -209.675222)
		(end 157.226254 -209.449162)
		(width 0.16002)
		(layer "In6.Cu")
		(net "M_K_CPU1_SA_DQS_DP<5>")
	)
	(segment
		(start 172.689774 -203.160376)
		(end 173.069504 -202.780646)
		(width 0.16002)
		(layer "In6.Cu")
		(net "M_K_CPU1_SA_DQS_DP<5>")
	)
	(segment
		(start 173.674024 -202.780646)
		(end 174.461424 -201.993246)
		(width 0.16002)
		(layer "In6.Cu")
		(net "M_K_CPU1_SA_DQS_DP<5>")
	)
	(segment
		(start 174.461424 -201.993246)
		(end 175.27016 -201.993246)
		(width 0.16002)
		(layer "In6.Cu")
		(net "M_K_CPU1_SA_DQS_DP<5>")
	)
	(segment
		(start 156.099256 -210.57616)
		(end 156.325316 -210.57616)
		(width 0.16002)
		(layer "In6.Cu")
		(net "M_K_CPU1_SA_DQS_DP<5>")
	)
	(segment
		(start 153.105358 -213.570058)
		(end 153.351992 -213.323424)
		(width 0.16002)
		(layer "In6.Cu")
		(net "M_K_CPU1_SA_DQS_DP<5>")
	)
	(segment
		(start 178.919124 -203.160376)
		(end 180.233828 -203.160376)
		(width 0.16002)
		(layer "In6.Cu")
		(net "M_K_CPU1_SA_DQS_DP<5>")
	)
	(segment
		(start 167.726106 -201.993246)
		(end 168.043352 -202.310492)
		(width 0.16002)
		(layer "In6.Cu")
		(net "M_K_CPU1_SA_DQS_DP<5>")
	)
	(segment
		(start 150.830788 -216.070688)
		(end 150.931626 -216.171526)
		(width 0.16002)
		(layer "In6.Cu")
		(net "M_K_CPU1_SA_DQS_DP<5>")
	)
	(segment
		(start 155.052522 -212.05063)
		(end 155.529026 -212.05063)
		(width 0.16002)
		(layer "In6.Cu")
		(net "M_K_CPU1_SA_DQS_DP<5>")
	)
	(segment
		(start 153.67889 -213.424262)
		(end 154.155394 -213.424262)
		(width 0.16002)
		(layer "In6.Cu")
		(net "M_K_CPU1_SA_DQS_DP<5>")
	)
	(segment
		(start 157.226254 -209.449162)
		(end 163.89477 -202.780646)
		(width 0.16002)
		(layer "In6.Cu")
		(net "M_K_CPU1_SA_DQS_DP<5>")
	)
	(segment
		(start 156.902658 -210.676998)
		(end 157.327092 -210.252564)
		(width 0.16002)
		(layer "In6.Cu")
		(net "M_K_CPU1_SA_DQS_DP<5>")
	)
	(segment
		(start 154.155394 -213.424262)
		(end 154.579828 -212.999828)
		(width 0.16002)
		(layer "In6.Cu")
		(net "M_K_CPU1_SA_DQS_DP<5>")
	)
	(segment
		(start 192.256664 -202.161394)
		(end 194.33032 -202.161394)
		(width 0.16002)
		(layer "In6.Cu")
		(net "M_K_CPU1_SA_DQS_DP<5>")
	)
	(segment
		(start 168.043352 -202.310492)
		(end 170.525186 -202.310492)
		(width 0.16002)
		(layer "In6.Cu")
		(net "M_K_CPU1_SA_DQS_DP<5>")
	)
	(segment
		(start 155.529026 -212.05063)
		(end 155.95346 -211.626196)
		(width 0.16002)
		(layer "In6.Cu")
		(net "M_K_CPU1_SA_DQS_DP<5>")
	)
	(segment
		(start 152.20442 -214.697056)
		(end 152.305258 -214.797894)
		(width 0.16002)
		(layer "In6.Cu")
		(net "M_K_CPU1_SA_DQS_DP<5>")
	)
	(segment
		(start 150.931626 -216.171526)
		(end 151.40813 -216.171526)
		(width 0.16002)
		(layer "In6.Cu")
		(net "M_K_CPU1_SA_DQS_DP<5>")
	)
	(segment
		(start 156.426154 -210.676998)
		(end 156.902658 -210.676998)
		(width 0.16002)
		(layer "In6.Cu")
		(net "M_K_CPU1_SA_DQS_DP<5>")
	)
	(segment
		(start 178.06924 -202.310492)
		(end 178.919124 -203.160376)
		(width 0.16002)
		(layer "In6.Cu")
		(net "M_K_CPU1_SA_DQS_DP<5>")
	)
	(segment
		(start 155.95346 -211.626196)
		(end 155.95346 -211.149692)
		(width 0.16002)
		(layer "In6.Cu")
		(net "M_K_CPU1_SA_DQS_DP<5>")
	)
	(segment
		(start 156.325316 -210.57616)
		(end 156.426154 -210.676998)
		(width 0.16002)
		(layer "In6.Cu")
		(net "M_K_CPU1_SA_DQS_DP<5>")
	)
	(segment
		(start 152.781762 -214.797894)
		(end 153.206196 -214.37346)
		(width 0.16002)
		(layer "In6.Cu")
		(net "M_K_CPU1_SA_DQS_DP<5>")
	)
	(segment
		(start 153.105358 -213.796118)
		(end 153.105358 -213.570058)
		(width 0.16002)
		(layer "In6.Cu")
		(net "M_K_CPU1_SA_DQS_DP<5>")
	)
	(segment
		(start 194.33032 -202.161394)
		(end 194.604132 -202.435206)
		(width 0.16002)
		(layer "In6.Cu")
		(net "M_K_CPU1_SA_DQS_DP<5>")
	)
	(segment
		(start 154.579828 -212.999828)
		(end 154.579828 -212.523324)
		(width 0.16002)
		(layer "In6.Cu")
		(net "M_K_CPU1_SA_DQS_DP<5>")
	)
	(segment
		(start 155.852622 -211.048854)
		(end 155.852622 -210.822794)
		(width 0.16002)
		(layer "In6.Cu")
		(net "M_K_CPU1_SA_DQS_DP<5>")
	)
	(segment
		(start 192.107566 -202.310492)
		(end 192.256664 -202.161394)
		(width 0.16002)
		(layer "In6.Cu")
		(net "M_K_CPU1_SA_DQS_DP<5>")
	)
	(segment
		(start 181.218078 -202.780646)
		(end 182.005478 -201.993246)
		(width 0.16002)
		(layer "In6.Cu")
		(net "M_K_CPU1_SA_DQS_DP<5>")
	)
	(segment
		(start 175.587406 -202.310492)
		(end 178.06924 -202.310492)
		(width 0.16002)
		(layer "In6.Cu")
		(net "M_K_CPU1_SA_DQS_DP<5>")
	)
	(segment
		(start 170.525186 -202.310492)
		(end 171.37507 -203.160376)
		(width 0.16002)
		(layer "In6.Cu")
		(net "M_K_CPU1_SA_DQS_DP<5>")
	)
	(segment
		(start 153.206196 -214.37346)
		(end 153.206196 -213.896956)
		(width 0.16002)
		(layer "In6.Cu")
		(net "M_K_CPU1_SA_DQS_DP<5>")
	)
	(segment
		(start 189.549532 -201.993246)
		(end 190.358268 -201.993246)
		(width 0.16002)
		(layer "In6.Cu")
		(net "M_K_CPU1_SA_DQS_DP<5>")
	)
	(segment
		(start 190.675514 -202.310492)
		(end 192.107566 -202.310492)
		(width 0.16002)
		(layer "In6.Cu")
		(net "M_K_CPU1_SA_DQS_DP<5>")
	)
	(segment
		(start 150.604728 -216.070688)
		(end 150.830788 -216.070688)
		(width 0.16002)
		(layer "In6.Cu")
		(net "M_K_CPU1_SA_DQS_DP<5>")
	)
	(segment
		(start 151.832564 -215.747092)
		(end 151.832564 -215.270588)
		(width 0.16002)
		(layer "In6.Cu")
		(net "M_K_CPU1_SA_DQS_DP<5>")
	)
	(segment
		(start 153.578052 -213.323424)
		(end 153.67889 -213.424262)
		(width 0.16002)
		(layer "In6.Cu")
		(net "M_K_CPU1_SA_DQS_DP<5>")
	)
	(segment
		(start 190.358268 -201.993246)
		(end 190.675514 -202.310492)
		(width 0.16002)
		(layer "In6.Cu")
		(net "M_K_CPU1_SA_DQS_DP<5>")
	)
	(segment
		(start 146.706336 -222.772478)
		(end 148.55444 -220.924628)
		(width 0.16002)
		(layer "In6.Cu")
		(net "M_K_CPU1_SA_DQS_DP<5>")
	)
	(segment
		(start 146.64563 -222.789242)
		(end 146.689572 -222.789242)
		(width 0.09525)
		(layer "In6.Cu")
		(net "M_K_CPU1_SA_DQS_DP<5>")
	)
	(segment
		(start 154.951684 -211.949792)
		(end 155.052522 -212.05063)
		(width 0.16002)
		(layer "In6.Cu")
		(net "M_K_CPU1_SA_DQS_DP<5>")
	)
	(segment
		(start 151.832564 -215.270588)
		(end 151.731726 -215.16975)
		(width 0.16002)
		(layer "In6.Cu")
		(net "M_K_CPU1_SA_DQS_DP<5>")
	)
	(segment
		(start 152.305258 -214.797894)
		(end 152.781762 -214.797894)
		(width 0.16002)
		(layer "In6.Cu")
		(net "M_K_CPU1_SA_DQS_DP<5>")
	)
	(segment
		(start 180.233828 -203.160376)
		(end 180.613558 -202.780646)
		(width 0.16002)
		(layer "In6.Cu")
		(net "M_K_CPU1_SA_DQS_DP<5>")
	)
	(segment
		(start 182.814214 -201.993246)
		(end 183.13146 -202.310492)
		(width 0.16002)
		(layer "In6.Cu")
		(net "M_K_CPU1_SA_DQS_DP<5>")
	)
	(segment
		(start 180.613558 -202.780646)
		(end 181.218078 -202.780646)
		(width 0.16002)
		(layer "In6.Cu")
		(net "M_K_CPU1_SA_DQS_DP<5>")
	)
	(segment
		(start 141.666214 -227.959412)
		(end 141.674596 -227.954586)
		(width 0.09525)
		(layer "In6.Cu")
		(net "M_K_CPU1_SA_DQS_DP<5>")
	)
	(segment
		(start 151.731726 -215.16975)
		(end 151.731726 -214.94369)
		(width 0.16002)
		(layer "In6.Cu")
		(net "M_K_CPU1_SA_DQS_DP<5>")
	)
	(segment
		(start 146.177 -223.424496)
		(end 146.176492 -223.423988)
		(width 0.09525)
		(layer "In6.Cu")
		(net "M_K_CPU1_SA_DQS_DP<5>")
	)
	(segment
		(start 145.7071 -225.91649)
		(end 145.7071 -224.234502)
		(width 0.09525)
		(layer "In6.Cu")
		(net "M_K_CPU1_SA_DQS_DP<5>")
	)
	(segment
		(start 166.91737 -201.993246)
		(end 167.726106 -201.993246)
		(width 0.16002)
		(layer "In6.Cu")
		(net "M_K_CPU1_SA_DQS_DP<5>")
	)
	(segment
		(start 154.725624 -211.949792)
		(end 154.951684 -211.949792)
		(width 0.16002)
		(layer "In6.Cu")
		(net "M_K_CPU1_SA_DQS_DP<5>")
	)
	(segment
		(start 154.47899 -212.196426)
		(end 154.725624 -211.949792)
		(width 0.16002)
		(layer "In6.Cu")
		(net "M_K_CPU1_SA_DQS_DP<5>")
	)
	(segment
		(start 155.95346 -211.149692)
		(end 155.852622 -211.048854)
		(width 0.16002)
		(layer "In6.Cu")
		(net "M_K_CPU1_SA_DQS_DP<5>")
	)
	(segment
		(start 143.73479 -227.908104)
		(end 143.96085 -227.908104)
		(width 0.09525)
		(layer "In6.Cu")
		(net "M_K_CPU1_SA_DQS_DP<5>")
	)
	(segment
		(start 144.753076 -227.234496)
		(end 144.908524 -227.166932)
		(width 0.09525)
		(layer "In6.Cu")
		(net "M_K_CPU1_SA_DQS_DP<5>")
	)
	(segment
		(start 182.005478 -201.993246)
		(end 182.814214 -201.993246)
		(width 0.16002)
		(layer "In6.Cu")
		(net "M_K_CPU1_SA_DQS_DP<5>")
	)
	(segment
		(start 185.613294 -202.310492)
		(end 186.463178 -203.160376)
		(width 0.16002)
		(layer "In6.Cu")
		(net "M_K_CPU1_SA_DQS_DP<5>")
	)
	(segment
		(start 188.157612 -202.780646)
		(end 188.762132 -202.780646)
		(width 0.16002)
		(layer "In6.Cu")
		(net "M_K_CPU1_SA_DQS_DP<5>")
	)
	(segment
		(start 166.12997 -202.780646)
		(end 166.91737 -201.993246)
		(width 0.16002)
		(layer "In6.Cu")
		(net "M_K_CPU1_SA_DQS_DP<5>")
	)
	(segment
		(start 155.852622 -210.822794)
		(end 156.099256 -210.57616)
		(width 0.16002)
		(layer "In6.Cu")
		(net "M_K_CPU1_SA_DQS_DP<5>")
	)
	(segment
		(start 146.176492 -223.21901)
		(end 146.57832 -222.817182)
		(width 0.09525)
		(layer "In6.Cu")
		(net "M_K_CPU1_SA_DQS_DP<5>")
	)
	(segment
		(start 163.89477 -202.780646)
		(end 166.12997 -202.780646)
		(width 0.16002)
		(layer "In6.Cu")
		(net "M_K_CPU1_SA_DQS_DP<5>")
	)
	(segment
		(start 157.327092 -210.252564)
		(end 157.327092 -209.77606)
		(width 0.16002)
		(layer "In6.Cu")
		(net "M_K_CPU1_SA_DQS_DP<5>")
	)
	(segment
		(start 141.068806 -228.019102)
		(end 141.169644 -227.992432)
		(width 0.09525)
		(layer "In6.Cu")
		(net "M_K_CPU1_SA_DQS_DP<5>")
	)
	(segment
		(start 157.327092 -209.77606)
		(end 157.226254 -209.675222)
		(width 0.16002)
		(layer "In6.Cu")
		(net "M_K_CPU1_SA_DQS_DP<5>")
	)
	(segment
		(start 150.12797 -219.351352)
		(end 150.12797 -216.547446)
		(width 0.16002)
		(layer "In6.Cu")
		(net "M_K_CPU1_SA_DQS_DP<5>")
	)
	(segment
		(start 153.206196 -213.896956)
		(end 153.105358 -213.796118)
		(width 0.16002)
		(layer "In6.Cu")
		(net "M_K_CPU1_SA_DQS_DP<5>")
	)
	(segment
		(start 188.762132 -202.780646)
		(end 189.549532 -201.993246)
		(width 0.16002)
		(layer "In6.Cu")
		(net "M_K_CPU1_SA_DQS_DP<5>")
	)
	(segment
		(start 145.86458 -223.92767)
		(end 145.896076 -223.909382)
		(width 0.09525)
		(layer "In6.Cu")
		(net "M_K_CPU1_SA_DQS_DP<5>")
	)
	(segment
		(start 148.554694 -220.924628)
		(end 150.12797 -219.351352)
		(width 0.16002)
		(layer "In6.Cu")
		(net "M_K_CPU1_SA_DQS_DP<5>")
	)
	(segment
		(start 146.176492 -223.423988)
		(end 146.176492 -223.21901)
		(width 0.09525)
		(layer "In6.Cu")
		(net "M_K_CPU1_SA_DQS_DP<5>")
	)
	(segment
		(start 153.351992 -213.323424)
		(end 153.578052 -213.323424)
		(width 0.16002)
		(layer "In6.Cu")
		(net "M_K_CPU1_SA_DQS_DP<5>")
	)
	(segment
		(start 183.13146 -202.310492)
		(end 185.613294 -202.310492)
		(width 0.16002)
		(layer "In6.Cu")
		(net "M_K_CPU1_SA_DQS_DP<5>")
	)
	(segment
		(start 151.731726 -214.94369)
		(end 151.97836 -214.697056)
		(width 0.16002)
		(layer "In6.Cu")
		(net "M_K_CPU1_SA_DQS_DP<5>")
	)
	(segment
		(start 151.97836 -214.697056)
		(end 152.20442 -214.697056)
		(width 0.16002)
		(layer "In6.Cu")
		(net "M_K_CPU1_SA_DQS_DP<5>")
	)
	(segment
		(start 186.463178 -203.160376)
		(end 187.777882 -203.160376)
		(width 0.16002)
		(layer "In6.Cu")
		(net "M_K_CPU1_SA_DQS_DP<5>")
	)
	(segment
		(start 146.689572 -222.789242)
		(end 146.706336 -222.772478)
		(width 0.09525)
		(layer "In6.Cu")
		(net "M_K_CPU1_SA_DQS_DP<5>")
	)
	(arc
		(start 145.7071 -224.234502)
		(mid 145.748765 -224.062055)
		(end 145.86458 -223.92767)
		(width 0.09525)
		(layer "In6.Cu")
		(net "M_K_CPU1_SA_DQS_DP<5>")
	)
	(arc
		(start 144.658334 -227.329746)
		(mid 144.696633 -227.273089)
		(end 144.753076 -227.234496)
		(width 0.09525)
		(layer "In6.Cu")
		(net "M_K_CPU1_SA_DQS_DP<5>")
	)
	(arc
		(start 143.96085 -227.908104)
		(mid 144.166421 -227.870398)
		(end 144.345152 -227.762054)
		(width 0.09525)
		(layer "In6.Cu")
		(net "M_K_CPU1_SA_DQS_DP<5>")
	)
	(arc
		(start 145.934176 -223.887284)
		(mid 146.112626 -223.685814)
		(end 146.177 -223.424496)
		(width 0.09525)
		(layer "In6.Cu")
		(net "M_K_CPU1_SA_DQS_DP<5>")
	)
	(arc
		(start 143.546068 -227.959412)
		(mid 143.637034 -227.921259)
		(end 143.73479 -227.908104)
		(width 0.09525)
		(layer "In6.Cu")
		(net "M_K_CPU1_SA_DQS_DP<5>")
	)
	(arc
		(start 141.189456 -228.000306)
		(mid 141.43242 -228.033293)
		(end 141.666214 -227.959412)
		(width 0.09525)
		(layer "In6.Cu")
		(net "M_K_CPU1_SA_DQS_DP<5>")
	)
	(arc
		(start 145.444972 -226.33051)
		(mid 145.623413 -226.153498)
		(end 145.7071 -225.91649)
		(width 0.09525)
		(layer "In6.Cu")
		(net "M_K_CPU1_SA_DQS_DP<5>")
	)
	(arc
		(start 144.908524 -227.166932)
		(mid 145.145742 -226.971066)
		(end 145.24228 -226.678998)
		(width 0.09525)
		(layer "In6.Cu")
		(net "M_K_CPU1_SA_DQS_DP<5>")
	)
	(arc
		(start 142.043404 -227.959412)
		(mid 142.324836 -228.035167)
		(end 142.606268 -227.959412)
		(width 0.09525)
		(layer "In6.Cu")
		(net "M_K_CPU1_SA_DQS_DP<5>")
	)
	(arc
		(start 144.345152 -227.762054)
		(mid 144.525123 -227.562836)
		(end 144.658334 -227.329746)
		(width 0.09525)
		(layer "In6.Cu")
		(net "M_K_CPU1_SA_DQS_DP<5>")
	)
	(arc
		(start 142.606268 -227.959412)
		(mid 142.794736 -227.908735)
		(end 142.983204 -227.959412)
		(width 0.09525)
		(layer "In6.Cu")
		(net "M_K_CPU1_SA_DQS_DP<5>")
	)
	(arc
		(start 141.674596 -227.954586)
		(mid 141.859628 -227.908672)
		(end 142.043404 -227.959412)
		(width 0.09525)
		(layer "In6.Cu")
		(net "M_K_CPU1_SA_DQS_DP<5>")
	)
	(arc
		(start 141.169644 -227.992432)
		(mid 141.179512 -227.996463)
		(end 141.189456 -228.000306)
		(width 0.09525)
		(layer "In6.Cu")
		(net "M_K_CPU1_SA_DQS_DP<5>")
	)
	(arc
		(start 142.983204 -227.959412)
		(mid 143.264636 -228.035167)
		(end 143.546068 -227.959412)
		(width 0.09525)
		(layer "In6.Cu")
		(net "M_K_CPU1_SA_DQS_DP<5>")
	)
	(arc
		(start 146.57832 -222.817182)
		(mid 146.609188 -222.796493)
		(end 146.64563 -222.789242)
		(width 0.09525)
		(layer "In6.Cu")
		(net "M_K_CPU1_SA_DQS_DP<5>")
	)
	(arc
		(start 145.24228 -226.678998)
		(mid 145.300194 -226.479479)
		(end 145.444972 -226.33051)
		(width 0.09525)
		(layer "In6.Cu")
		(net "M_K_CPU1_SA_DQS_DP<5>")
	)
	(segment
		(start 142.327884 -246.370348)
		(end 142.794736 -246.10441)
		(width 0.12954)
		(layer "F.Cu")
		(net "M_K_CPU1_SA_DQS_DP<4>")
	)
	(segment
		(start 147.688554 -246.515382)
		(end 147.688554 -246.43207)
		(width 0.09525)
		(layer "In6.Cu")
		(net "M_K_CPU1_SA_DQS_DP<4>")
	)
	(segment
		(start 167.632126 -237.410244)
		(end 169.595292 -237.410244)
		(width 0.16002)
		(layer "In6.Cu")
		(net "M_K_CPU1_SA_DQS_DP<4>")
	)
	(segment
		(start 196.409818 -238.409226)
		(end 197.16242 -238.409226)
		(width 0.16002)
		(layer "In6.Cu")
		(net "M_K_CPU1_SA_DQS_DP<4>")
	)
	(segment
		(start 148.177758 -245.942866)
		(end 156.926534 -245.942866)
		(width 0.16002)
		(layer "In6.Cu")
		(net "M_K_CPU1_SA_DQS_DP<4>")
	)
	(segment
		(start 182.380636 -237.749842)
		(end 182.720234 -237.410244)
		(width 0.16002)
		(layer "In6.Cu")
		(net "M_K_CPU1_SA_DQS_DP<4>")
	)
	(segment
		(start 197.16242 -238.409226)
		(end 197.28942 -238.282226)
		(width 0.16002)
		(layer "In6.Cu")
		(net "M_K_CPU1_SA_DQS_DP<4>")
	)
	(segment
		(start 142.794736 -246.10441)
		(end 142.640812 -246.36984)
		(width 0.09525)
		(layer "In6.Cu")
		(net "M_K_CPU1_SA_DQS_DP<4>")
	)
	(segment
		(start 189.53607 -237.749842)
		(end 189.92469 -237.749842)
		(width 0.16002)
		(layer "In6.Cu")
		(net "M_K_CPU1_SA_DQS_DP<4>")
	)
	(segment
		(start 182.720234 -237.410244)
		(end 184.6834 -237.410244)
		(width 0.16002)
		(layer "In6.Cu")
		(net "M_K_CPU1_SA_DQS_DP<4>")
	)
	(segment
		(start 146.560286 -246.761254)
		(end 147.442682 -246.761254)
		(width 0.09525)
		(layer "In6.Cu")
		(net "M_K_CPU1_SA_DQS_DP<4>")
	)
	(segment
		(start 177.98923 -238.260128)
		(end 180.399182 -238.260128)
		(width 0.16002)
		(layer "In6.Cu")
		(net "M_K_CPU1_SA_DQS_DP<4>")
	)
	(segment
		(start 156.926534 -245.942866)
		(end 164.268658 -238.600742)
		(width 0.16002)
		(layer "In6.Cu")
		(net "M_K_CPU1_SA_DQS_DP<4>")
	)
	(segment
		(start 192.996312 -237.984284)
		(end 195.207128 -237.984284)
		(width 0.16002)
		(layer "In6.Cu")
		(net "M_K_CPU1_SA_DQS_DP<4>")
	)
	(segment
		(start 142.640812 -246.36984)
		(end 142.663926 -246.456454)
		(width 0.09525)
		(layer "In6.Cu")
		(net "M_K_CPU1_SA_DQS_DP<4>")
	)
	(segment
		(start 197.76948 -238.282226)
		(end 197.89648 -238.409226)
		(width 0.16002)
		(layer "In6.Cu")
		(net "M_K_CPU1_SA_DQS_DP<4>")
	)
	(segment
		(start 195.207128 -237.984284)
		(end 195.831206 -238.608362)
		(width 0.16002)
		(layer "In6.Cu")
		(net "M_K_CPU1_SA_DQS_DP<4>")
	)
	(segment
		(start 177.139346 -237.410244)
		(end 177.98923 -238.260128)
		(width 0.16002)
		(layer "In6.Cu")
		(net "M_K_CPU1_SA_DQS_DP<4>")
	)
	(segment
		(start 189.92469 -237.749842)
		(end 190.264288 -237.410244)
		(width 0.16002)
		(layer "In6.Cu")
		(net "M_K_CPU1_SA_DQS_DP<4>")
	)
	(segment
		(start 143.923258 -246.42953)
		(end 143.933672 -246.423434)
		(width 0.09525)
		(layer "In6.Cu")
		(net "M_K_CPU1_SA_DQS_DP<4>")
	)
	(segment
		(start 146.2659 -246.466868)
		(end 146.560286 -246.761254)
		(width 0.09525)
		(layer "In6.Cu")
		(net "M_K_CPU1_SA_DQS_DP<4>")
	)
	(segment
		(start 187.943236 -238.260128)
		(end 188.28385 -238.600742)
		(width 0.16002)
		(layer "In6.Cu")
		(net "M_K_CPU1_SA_DQS_DP<4>")
	)
	(segment
		(start 174.447962 -237.749842)
		(end 174.836582 -237.749842)
		(width 0.16002)
		(layer "In6.Cu")
		(net "M_K_CPU1_SA_DQS_DP<4>")
	)
	(segment
		(start 185.533284 -238.260128)
		(end 187.943236 -238.260128)
		(width 0.16002)
		(layer "In6.Cu")
		(net "M_K_CPU1_SA_DQS_DP<4>")
	)
	(segment
		(start 173.597062 -238.600742)
		(end 174.447962 -237.749842)
		(width 0.16002)
		(layer "In6.Cu")
		(net "M_K_CPU1_SA_DQS_DP<4>")
	)
	(segment
		(start 173.195742 -238.600742)
		(end 173.597062 -238.600742)
		(width 0.16002)
		(layer "In6.Cu")
		(net "M_K_CPU1_SA_DQS_DP<4>")
	)
	(segment
		(start 174.836582 -237.749842)
		(end 175.17618 -237.410244)
		(width 0.16002)
		(layer "In6.Cu")
		(net "M_K_CPU1_SA_DQS_DP<4>")
	)
	(segment
		(start 170.445176 -238.260128)
		(end 172.855128 -238.260128)
		(width 0.16002)
		(layer "In6.Cu")
		(net "M_K_CPU1_SA_DQS_DP<4>")
	)
	(segment
		(start 181.141116 -238.600742)
		(end 181.992016 -237.749842)
		(width 0.16002)
		(layer "In6.Cu")
		(net "M_K_CPU1_SA_DQS_DP<4>")
	)
	(segment
		(start 164.268658 -238.600742)
		(end 166.053008 -238.600742)
		(width 0.16002)
		(layer "In6.Cu")
		(net "M_K_CPU1_SA_DQS_DP<4>")
	)
	(segment
		(start 147.705318 -246.415306)
		(end 148.177758 -245.942866)
		(width 0.16002)
		(layer "In6.Cu")
		(net "M_K_CPU1_SA_DQS_DP<4>")
	)
	(segment
		(start 188.68517 -238.600742)
		(end 189.53607 -237.749842)
		(width 0.16002)
		(layer "In6.Cu")
		(net "M_K_CPU1_SA_DQS_DP<4>")
	)
	(segment
		(start 181.992016 -237.749842)
		(end 182.380636 -237.749842)
		(width 0.16002)
		(layer "In6.Cu")
		(net "M_K_CPU1_SA_DQS_DP<4>")
	)
	(segment
		(start 184.6834 -237.410244)
		(end 185.533284 -238.260128)
		(width 0.16002)
		(layer "In6.Cu")
		(net "M_K_CPU1_SA_DQS_DP<4>")
	)
	(segment
		(start 167.292528 -237.749842)
		(end 167.632126 -237.410244)
		(width 0.16002)
		(layer "In6.Cu")
		(net "M_K_CPU1_SA_DQS_DP<4>")
	)
	(segment
		(start 195.831206 -238.608362)
		(end 196.210682 -238.608362)
		(width 0.16002)
		(layer "In6.Cu")
		(net "M_K_CPU1_SA_DQS_DP<4>")
	)
	(segment
		(start 147.688554 -246.43207)
		(end 147.705318 -246.415306)
		(width 0.09525)
		(layer "In6.Cu")
		(net "M_K_CPU1_SA_DQS_DP<4>")
	)
	(segment
		(start 143.914876 -246.434356)
		(end 143.923258 -246.42953)
		(width 0.09525)
		(layer "In6.Cu")
		(net "M_K_CPU1_SA_DQS_DP<4>")
	)
	(segment
		(start 166.903908 -237.749842)
		(end 167.292528 -237.749842)
		(width 0.16002)
		(layer "In6.Cu")
		(net "M_K_CPU1_SA_DQS_DP<4>")
	)
	(segment
		(start 197.89648 -238.409226)
		(end 198.430388 -238.409226)
		(width 0.16002)
		(layer "In6.Cu")
		(net "M_K_CPU1_SA_DQS_DP<4>")
	)
	(segment
		(start 172.855128 -238.260128)
		(end 173.195742 -238.600742)
		(width 0.16002)
		(layer "In6.Cu")
		(net "M_K_CPU1_SA_DQS_DP<4>")
	)
	(segment
		(start 180.739796 -238.600742)
		(end 181.141116 -238.600742)
		(width 0.16002)
		(layer "In6.Cu")
		(net "M_K_CPU1_SA_DQS_DP<4>")
	)
	(segment
		(start 145.589752 -246.466868)
		(end 146.2659 -246.466868)
		(width 0.09525)
		(layer "In6.Cu")
		(net "M_K_CPU1_SA_DQS_DP<4>")
	)
	(segment
		(start 147.442682 -246.761254)
		(end 147.688554 -246.515382)
		(width 0.09525)
		(layer "In6.Cu")
		(net "M_K_CPU1_SA_DQS_DP<4>")
	)
	(segment
		(start 169.595292 -237.410244)
		(end 170.445176 -238.260128)
		(width 0.16002)
		(layer "In6.Cu")
		(net "M_K_CPU1_SA_DQS_DP<4>")
	)
	(segment
		(start 192.422272 -237.410244)
		(end 192.996312 -237.984284)
		(width 0.16002)
		(layer "In6.Cu")
		(net "M_K_CPU1_SA_DQS_DP<4>")
	)
	(segment
		(start 166.053008 -238.600742)
		(end 166.903908 -237.749842)
		(width 0.16002)
		(layer "In6.Cu")
		(net "M_K_CPU1_SA_DQS_DP<4>")
	)
	(segment
		(start 198.430388 -238.409226)
		(end 198.7042 -238.135414)
		(width 0.16002)
		(layer "In6.Cu")
		(net "M_K_CPU1_SA_DQS_DP<4>")
	)
	(segment
		(start 180.399182 -238.260128)
		(end 180.739796 -238.600742)
		(width 0.16002)
		(layer "In6.Cu")
		(net "M_K_CPU1_SA_DQS_DP<4>")
	)
	(segment
		(start 196.210682 -238.608362)
		(end 196.409818 -238.409226)
		(width 0.16002)
		(layer "In6.Cu")
		(net "M_K_CPU1_SA_DQS_DP<4>")
	)
	(segment
		(start 175.17618 -237.410244)
		(end 177.139346 -237.410244)
		(width 0.16002)
		(layer "In6.Cu")
		(net "M_K_CPU1_SA_DQS_DP<4>")
	)
	(segment
		(start 197.28942 -238.282226)
		(end 197.76948 -238.282226)
		(width 0.16002)
		(layer "In6.Cu")
		(net "M_K_CPU1_SA_DQS_DP<4>")
	)
	(segment
		(start 188.28385 -238.600742)
		(end 188.68517 -238.600742)
		(width 0.16002)
		(layer "In6.Cu")
		(net "M_K_CPU1_SA_DQS_DP<4>")
	)
	(segment
		(start 190.264288 -237.410244)
		(end 192.422272 -237.410244)
		(width 0.16002)
		(layer "In6.Cu")
		(net "M_K_CPU1_SA_DQS_DP<4>")
	)
	(segment
		(start 144.485868 -246.42953)
		(end 144.49425 -246.434356)
		(width 0.09525)
		(layer "In6.Cu")
		(net "M_K_CPU1_SA_DQS_DP<4>")
	)
	(arc
		(start 142.983204 -246.42953)
		(mid 143.264636 -246.353775)
		(end 143.546068 -246.42953)
		(width 0.09525)
		(layer "In6.Cu")
		(net "M_K_CPU1_SA_DQS_DP<4>")
	)
	(arc
		(start 143.933672 -246.423434)
		(mid 144.21058 -246.353757)
		(end 144.485868 -246.42953)
		(width 0.09525)
		(layer "In6.Cu")
		(net "M_K_CPU1_SA_DQS_DP<4>")
	)
	(arc
		(start 145.41119 -246.420894)
		(mid 145.497611 -246.454997)
		(end 145.589752 -246.466868)
		(width 0.09525)
		(layer "In6.Cu")
		(net "M_K_CPU1_SA_DQS_DP<4>")
	)
	(arc
		(start 144.863058 -246.42953)
		(mid 145.135986 -246.353716)
		(end 145.41119 -246.420894)
		(width 0.09525)
		(layer "In6.Cu")
		(net "M_K_CPU1_SA_DQS_DP<4>")
	)
	(arc
		(start 142.663926 -246.456454)
		(mid 142.826577 -246.478714)
		(end 142.983204 -246.42953)
		(width 0.09525)
		(layer "In6.Cu")
		(net "M_K_CPU1_SA_DQS_DP<4>")
	)
	(arc
		(start 143.546068 -246.42953)
		(mid 143.729843 -246.480302)
		(end 143.914876 -246.434356)
		(width 0.09525)
		(layer "In6.Cu")
		(net "M_K_CPU1_SA_DQS_DP<4>")
	)
	(arc
		(start 144.49425 -246.434356)
		(mid 144.679282 -246.48027)
		(end 144.863058 -246.42953)
		(width 0.09525)
		(layer "In6.Cu")
		(net "M_K_CPU1_SA_DQS_DP<4>")
	)
	(segment
		(start 142.327884 -241.510312)
		(end 142.794736 -241.244374)
		(width 0.12954)
		(layer "F.Cu")
		(net "M_K_CPU1_SA_DQS_DP<3>")
	)
	(segment
		(start 175.17618 -228.06025)
		(end 177.139346 -228.06025)
		(width 0.16002)
		(layer "In6.Cu")
		(net "M_K_CPU1_SA_DQS_DP<3>")
	)
	(segment
		(start 180.399182 -228.910134)
		(end 180.739796 -229.250748)
		(width 0.16002)
		(layer "In6.Cu")
		(net "M_K_CPU1_SA_DQS_DP<3>")
	)
	(segment
		(start 174.447962 -228.399848)
		(end 174.836582 -228.399848)
		(width 0.16002)
		(layer "In6.Cu")
		(net "M_K_CPU1_SA_DQS_DP<3>")
	)
	(segment
		(start 188.28385 -229.250748)
		(end 188.68517 -229.250748)
		(width 0.16002)
		(layer "In6.Cu")
		(net "M_K_CPU1_SA_DQS_DP<3>")
	)
	(segment
		(start 197.08114 -229.059232)
		(end 197.20814 -228.932232)
		(width 0.16002)
		(layer "In6.Cu")
		(net "M_K_CPU1_SA_DQS_DP<3>")
	)
	(segment
		(start 147.919186 -240.324894)
		(end 154.333956 -240.324894)
		(width 0.16002)
		(layer "In6.Cu")
		(net "M_K_CPU1_SA_DQS_DP<3>")
	)
	(segment
		(start 190.264288 -228.06025)
		(end 192.422272 -228.06025)
		(width 0.16002)
		(layer "In6.Cu")
		(net "M_K_CPU1_SA_DQS_DP<3>")
	)
	(segment
		(start 181.992016 -228.399848)
		(end 182.380636 -228.399848)
		(width 0.16002)
		(layer "In6.Cu")
		(net "M_K_CPU1_SA_DQS_DP<3>")
	)
	(segment
		(start 173.195742 -229.250748)
		(end 173.597062 -229.250748)
		(width 0.16002)
		(layer "In6.Cu")
		(net "M_K_CPU1_SA_DQS_DP<3>")
	)
	(segment
		(start 195.207128 -228.63429)
		(end 195.831206 -229.258368)
		(width 0.16002)
		(layer "In6.Cu")
		(net "M_K_CPU1_SA_DQS_DP<3>")
	)
	(segment
		(start 145.94459 -241.493548)
		(end 146.508724 -240.929414)
		(width 0.09525)
		(layer "In6.Cu")
		(net "M_K_CPU1_SA_DQS_DP<3>")
	)
	(segment
		(start 192.422272 -228.06025)
		(end 192.996312 -228.63429)
		(width 0.16002)
		(layer "In6.Cu")
		(net "M_K_CPU1_SA_DQS_DP<3>")
	)
	(segment
		(start 182.380636 -228.399848)
		(end 182.720234 -228.06025)
		(width 0.16002)
		(layer "In6.Cu")
		(net "M_K_CPU1_SA_DQS_DP<3>")
	)
	(segment
		(start 159.20847 -235.45038)
		(end 159.20847 -233.42092)
		(width 0.16002)
		(layer "In6.Cu")
		(net "M_K_CPU1_SA_DQS_DP<3>")
	)
	(segment
		(start 197.20814 -228.932232)
		(end 197.6882 -228.932232)
		(width 0.16002)
		(layer "In6.Cu")
		(net "M_K_CPU1_SA_DQS_DP<3>")
	)
	(segment
		(start 198.430388 -229.059232)
		(end 198.7042 -228.78542)
		(width 0.16002)
		(layer "In6.Cu")
		(net "M_K_CPU1_SA_DQS_DP<3>")
	)
	(segment
		(start 196.210682 -229.258368)
		(end 196.409818 -229.059232)
		(width 0.16002)
		(layer "In6.Cu")
		(net "M_K_CPU1_SA_DQS_DP<3>")
	)
	(segment
		(start 189.53607 -228.399848)
		(end 189.92469 -228.399848)
		(width 0.16002)
		(layer "In6.Cu")
		(net "M_K_CPU1_SA_DQS_DP<3>")
	)
	(segment
		(start 146.508724 -240.929414)
		(end 147.019772 -240.929414)
		(width 0.09525)
		(layer "In6.Cu")
		(net "M_K_CPU1_SA_DQS_DP<3>")
	)
	(segment
		(start 166.053008 -229.250748)
		(end 166.903908 -228.399848)
		(width 0.16002)
		(layer "In6.Cu")
		(net "M_K_CPU1_SA_DQS_DP<3>")
	)
	(segment
		(start 154.333956 -240.324894)
		(end 159.20847 -235.45038)
		(width 0.16002)
		(layer "In6.Cu")
		(net "M_K_CPU1_SA_DQS_DP<3>")
	)
	(segment
		(start 196.409818 -229.059232)
		(end 197.08114 -229.059232)
		(width 0.16002)
		(layer "In6.Cu")
		(net "M_K_CPU1_SA_DQS_DP<3>")
	)
	(segment
		(start 189.92469 -228.399848)
		(end 190.264288 -228.06025)
		(width 0.16002)
		(layer "In6.Cu")
		(net "M_K_CPU1_SA_DQS_DP<3>")
	)
	(segment
		(start 181.141116 -229.250748)
		(end 181.992016 -228.399848)
		(width 0.16002)
		(layer "In6.Cu")
		(net "M_K_CPU1_SA_DQS_DP<3>")
	)
	(segment
		(start 163.378642 -229.250748)
		(end 166.053008 -229.250748)
		(width 0.16002)
		(layer "In6.Cu")
		(net "M_K_CPU1_SA_DQS_DP<3>")
	)
	(segment
		(start 143.923258 -241.569494)
		(end 143.933672 -241.563398)
		(width 0.09525)
		(layer "In6.Cu")
		(net "M_K_CPU1_SA_DQS_DP<3>")
	)
	(segment
		(start 185.533284 -228.910134)
		(end 187.943236 -228.910134)
		(width 0.16002)
		(layer "In6.Cu")
		(net "M_K_CPU1_SA_DQS_DP<3>")
	)
	(segment
		(start 180.739796 -229.250748)
		(end 181.141116 -229.250748)
		(width 0.16002)
		(layer "In6.Cu")
		(net "M_K_CPU1_SA_DQS_DP<3>")
	)
	(segment
		(start 174.836582 -228.399848)
		(end 175.17618 -228.06025)
		(width 0.16002)
		(layer "In6.Cu")
		(net "M_K_CPU1_SA_DQS_DP<3>")
	)
	(segment
		(start 142.640812 -241.509804)
		(end 142.663926 -241.596418)
		(width 0.09525)
		(layer "In6.Cu")
		(net "M_K_CPU1_SA_DQS_DP<3>")
	)
	(segment
		(start 195.831206 -229.258368)
		(end 196.210682 -229.258368)
		(width 0.16002)
		(layer "In6.Cu")
		(net "M_K_CPU1_SA_DQS_DP<3>")
	)
	(segment
		(start 147.836382 -240.384076)
		(end 147.895564 -240.324894)
		(width 0.09525)
		(layer "In6.Cu")
		(net "M_K_CPU1_SA_DQS_DP<3>")
	)
	(segment
		(start 197.6882 -228.932232)
		(end 197.8152 -229.059232)
		(width 0.16002)
		(layer "In6.Cu")
		(net "M_K_CPU1_SA_DQS_DP<3>")
	)
	(segment
		(start 192.996312 -228.63429)
		(end 195.207128 -228.63429)
		(width 0.16002)
		(layer "In6.Cu")
		(net "M_K_CPU1_SA_DQS_DP<3>")
	)
	(segment
		(start 188.68517 -229.250748)
		(end 189.53607 -228.399848)
		(width 0.16002)
		(layer "In6.Cu")
		(net "M_K_CPU1_SA_DQS_DP<3>")
	)
	(segment
		(start 142.794736 -241.244374)
		(end 142.640812 -241.509804)
		(width 0.09525)
		(layer "In6.Cu")
		(net "M_K_CPU1_SA_DQS_DP<3>")
	)
	(segment
		(start 184.6834 -228.06025)
		(end 185.533284 -228.910134)
		(width 0.16002)
		(layer "In6.Cu")
		(net "M_K_CPU1_SA_DQS_DP<3>")
	)
	(segment
		(start 170.445176 -228.910134)
		(end 172.855128 -228.910134)
		(width 0.16002)
		(layer "In6.Cu")
		(net "M_K_CPU1_SA_DQS_DP<3>")
	)
	(segment
		(start 143.914876 -241.57432)
		(end 143.923258 -241.569494)
		(width 0.09525)
		(layer "In6.Cu")
		(net "M_K_CPU1_SA_DQS_DP<3>")
	)
	(segment
		(start 177.98923 -228.910134)
		(end 180.399182 -228.910134)
		(width 0.16002)
		(layer "In6.Cu")
		(net "M_K_CPU1_SA_DQS_DP<3>")
	)
	(segment
		(start 182.720234 -228.06025)
		(end 184.6834 -228.06025)
		(width 0.16002)
		(layer "In6.Cu")
		(net "M_K_CPU1_SA_DQS_DP<3>")
	)
	(segment
		(start 167.292528 -228.399848)
		(end 167.632126 -228.06025)
		(width 0.16002)
		(layer "In6.Cu")
		(net "M_K_CPU1_SA_DQS_DP<3>")
	)
	(segment
		(start 173.597062 -229.250748)
		(end 174.447962 -228.399848)
		(width 0.16002)
		(layer "In6.Cu")
		(net "M_K_CPU1_SA_DQS_DP<3>")
	)
	(segment
		(start 169.595292 -228.06025)
		(end 170.445176 -228.910134)
		(width 0.16002)
		(layer "In6.Cu")
		(net "M_K_CPU1_SA_DQS_DP<3>")
	)
	(segment
		(start 172.855128 -228.910134)
		(end 173.195742 -229.250748)
		(width 0.16002)
		(layer "In6.Cu")
		(net "M_K_CPU1_SA_DQS_DP<3>")
	)
	(segment
		(start 147.56511 -240.384076)
		(end 147.836382 -240.384076)
		(width 0.09525)
		(layer "In6.Cu")
		(net "M_K_CPU1_SA_DQS_DP<3>")
	)
	(segment
		(start 159.20847 -233.42092)
		(end 163.378642 -229.250748)
		(width 0.16002)
		(layer "In6.Cu")
		(net "M_K_CPU1_SA_DQS_DP<3>")
	)
	(segment
		(start 147.895564 -240.324894)
		(end 147.919186 -240.324894)
		(width 0.09525)
		(layer "In6.Cu")
		(net "M_K_CPU1_SA_DQS_DP<3>")
	)
	(segment
		(start 144.485868 -241.569494)
		(end 144.49425 -241.57432)
		(width 0.09525)
		(layer "In6.Cu")
		(net "M_K_CPU1_SA_DQS_DP<3>")
	)
	(segment
		(start 166.903908 -228.399848)
		(end 167.292528 -228.399848)
		(width 0.16002)
		(layer "In6.Cu")
		(net "M_K_CPU1_SA_DQS_DP<3>")
	)
	(segment
		(start 147.019772 -240.929414)
		(end 147.56511 -240.384076)
		(width 0.09525)
		(layer "In6.Cu")
		(net "M_K_CPU1_SA_DQS_DP<3>")
	)
	(segment
		(start 187.943236 -228.910134)
		(end 188.28385 -229.250748)
		(width 0.16002)
		(layer "In6.Cu")
		(net "M_K_CPU1_SA_DQS_DP<3>")
	)
	(segment
		(start 167.632126 -228.06025)
		(end 169.595292 -228.06025)
		(width 0.16002)
		(layer "In6.Cu")
		(net "M_K_CPU1_SA_DQS_DP<3>")
	)
	(segment
		(start 145.144744 -241.493548)
		(end 145.94459 -241.493548)
		(width 0.09525)
		(layer "In6.Cu")
		(net "M_K_CPU1_SA_DQS_DP<3>")
	)
	(segment
		(start 197.8152 -229.059232)
		(end 198.430388 -229.059232)
		(width 0.16002)
		(layer "In6.Cu")
		(net "M_K_CPU1_SA_DQS_DP<3>")
	)
	(segment
		(start 177.139346 -228.06025)
		(end 177.98923 -228.910134)
		(width 0.16002)
		(layer "In6.Cu")
		(net "M_K_CPU1_SA_DQS_DP<3>")
	)
	(arc
		(start 142.983204 -241.569494)
		(mid 143.264636 -241.493739)
		(end 143.546068 -241.569494)
		(width 0.09525)
		(layer "In6.Cu")
		(net "M_K_CPU1_SA_DQS_DP<3>")
	)
	(arc
		(start 144.49425 -241.57432)
		(mid 144.679282 -241.620234)
		(end 144.863058 -241.569494)
		(width 0.09525)
		(layer "In6.Cu")
		(net "M_K_CPU1_SA_DQS_DP<3>")
	)
	(arc
		(start 142.663926 -241.596418)
		(mid 142.826577 -241.618678)
		(end 142.983204 -241.569494)
		(width 0.09525)
		(layer "In6.Cu")
		(net "M_K_CPU1_SA_DQS_DP<3>")
	)
	(arc
		(start 144.863058 -241.569494)
		(mid 144.99888 -241.512914)
		(end 145.144744 -241.493548)
		(width 0.09525)
		(layer "In6.Cu")
		(net "M_K_CPU1_SA_DQS_DP<3>")
	)
	(arc
		(start 143.933672 -241.563398)
		(mid 144.21058 -241.493721)
		(end 144.485868 -241.569494)
		(width 0.09525)
		(layer "In6.Cu")
		(net "M_K_CPU1_SA_DQS_DP<3>")
	)
	(arc
		(start 143.546068 -241.569494)
		(mid 143.729843 -241.620266)
		(end 143.914876 -241.57432)
		(width 0.09525)
		(layer "In6.Cu")
		(net "M_K_CPU1_SA_DQS_DP<3>")
	)
	(segment
		(start 142.327884 -236.650276)
		(end 142.794736 -236.384338)
		(width 0.12954)
		(layer "F.Cu")
		(net "M_K_CPU1_SA_DQS_DP<2>")
	)
	(segment
		(start 174.447962 -219.049854)
		(end 174.836582 -219.049854)
		(width 0.16002)
		(layer "In6.Cu")
		(net "M_K_CPU1_SA_DQS_DP<2>")
	)
	(segment
		(start 146.555206 -235.472224)
		(end 146.852894 -235.472224)
		(width 0.09525)
		(layer "In6.Cu")
		(net "M_K_CPU1_SA_DQS_DP<2>")
	)
	(segment
		(start 177.98923 -219.56014)
		(end 180.399182 -219.56014)
		(width 0.16002)
		(layer "In6.Cu")
		(net "M_K_CPU1_SA_DQS_DP<2>")
	)
	(segment
		(start 188.68517 -219.900754)
		(end 189.53607 -219.049854)
		(width 0.16002)
		(layer "In6.Cu")
		(net "M_K_CPU1_SA_DQS_DP<2>")
	)
	(segment
		(start 188.28385 -219.900754)
		(end 188.68517 -219.900754)
		(width 0.16002)
		(layer "In6.Cu")
		(net "M_K_CPU1_SA_DQS_DP<2>")
	)
	(segment
		(start 196.409818 -219.709238)
		(end 197.02526 -219.709238)
		(width 0.16002)
		(layer "In6.Cu")
		(net "M_K_CPU1_SA_DQS_DP<2>")
	)
	(segment
		(start 167.632126 -218.710256)
		(end 169.595292 -218.710256)
		(width 0.16002)
		(layer "In6.Cu")
		(net "M_K_CPU1_SA_DQS_DP<2>")
	)
	(segment
		(start 189.53607 -219.049854)
		(end 189.92469 -219.049854)
		(width 0.16002)
		(layer "In6.Cu")
		(net "M_K_CPU1_SA_DQS_DP<2>")
	)
	(segment
		(start 181.992016 -219.049854)
		(end 182.380636 -219.049854)
		(width 0.16002)
		(layer "In6.Cu")
		(net "M_K_CPU1_SA_DQS_DP<2>")
	)
	(segment
		(start 147.567142 -234.757976)
		(end 147.836382 -234.757976)
		(width 0.09525)
		(layer "In6.Cu")
		(net "M_K_CPU1_SA_DQS_DP<2>")
	)
	(segment
		(start 166.053008 -219.900754)
		(end 166.903908 -219.049854)
		(width 0.16002)
		(layer "In6.Cu")
		(net "M_K_CPU1_SA_DQS_DP<2>")
	)
	(segment
		(start 167.292528 -219.049854)
		(end 167.632126 -218.710256)
		(width 0.16002)
		(layer "In6.Cu")
		(net "M_K_CPU1_SA_DQS_DP<2>")
	)
	(segment
		(start 182.720234 -218.710256)
		(end 184.6834 -218.710256)
		(width 0.16002)
		(layer "In6.Cu")
		(net "M_K_CPU1_SA_DQS_DP<2>")
	)
	(segment
		(start 145.144744 -236.633512)
		(end 145.393918 -236.633512)
		(width 0.09525)
		(layer "In6.Cu")
		(net "M_K_CPU1_SA_DQS_DP<2>")
	)
	(segment
		(start 163.91509 -219.900754)
		(end 166.053008 -219.900754)
		(width 0.16002)
		(layer "In6.Cu")
		(net "M_K_CPU1_SA_DQS_DP<2>")
	)
	(segment
		(start 185.533284 -219.56014)
		(end 187.943236 -219.56014)
		(width 0.16002)
		(layer "In6.Cu")
		(net "M_K_CPU1_SA_DQS_DP<2>")
	)
	(segment
		(start 169.595292 -218.710256)
		(end 170.445176 -219.56014)
		(width 0.16002)
		(layer "In6.Cu")
		(net "M_K_CPU1_SA_DQS_DP<2>")
	)
	(segment
		(start 197.63232 -219.582238)
		(end 197.75932 -219.709238)
		(width 0.16002)
		(layer "In6.Cu")
		(net "M_K_CPU1_SA_DQS_DP<2>")
	)
	(segment
		(start 147.836382 -234.757976)
		(end 147.895564 -234.698794)
		(width 0.09525)
		(layer "In6.Cu")
		(net "M_K_CPU1_SA_DQS_DP<2>")
	)
	(segment
		(start 142.794736 -236.384338)
		(end 142.640812 -236.649768)
		(width 0.09525)
		(layer "In6.Cu")
		(net "M_K_CPU1_SA_DQS_DP<2>")
	)
	(segment
		(start 189.92469 -219.049854)
		(end 190.264288 -218.710256)
		(width 0.16002)
		(layer "In6.Cu")
		(net "M_K_CPU1_SA_DQS_DP<2>")
	)
	(segment
		(start 197.75932 -219.709238)
		(end 198.430388 -219.709238)
		(width 0.16002)
		(layer "In6.Cu")
		(net "M_K_CPU1_SA_DQS_DP<2>")
	)
	(segment
		(start 161.10839 -222.707454)
		(end 163.91509 -219.900754)
		(width 0.16002)
		(layer "In6.Cu")
		(net "M_K_CPU1_SA_DQS_DP<2>")
	)
	(segment
		(start 180.739796 -219.900754)
		(end 181.141116 -219.900754)
		(width 0.16002)
		(layer "In6.Cu")
		(net "M_K_CPU1_SA_DQS_DP<2>")
	)
	(segment
		(start 173.195742 -219.900754)
		(end 173.597062 -219.900754)
		(width 0.16002)
		(layer "In6.Cu")
		(net "M_K_CPU1_SA_DQS_DP<2>")
	)
	(segment
		(start 195.207128 -219.284296)
		(end 195.831206 -219.908374)
		(width 0.16002)
		(layer "In6.Cu")
		(net "M_K_CPU1_SA_DQS_DP<2>")
	)
	(segment
		(start 147.895564 -234.698794)
		(end 147.919186 -234.698794)
		(width 0.09525)
		(layer "In6.Cu")
		(net "M_K_CPU1_SA_DQS_DP<2>")
	)
	(segment
		(start 197.02526 -219.709238)
		(end 197.15226 -219.582238)
		(width 0.16002)
		(layer "In6.Cu")
		(net "M_K_CPU1_SA_DQS_DP<2>")
	)
	(segment
		(start 177.139346 -218.710256)
		(end 177.98923 -219.56014)
		(width 0.16002)
		(layer "In6.Cu")
		(net "M_K_CPU1_SA_DQS_DP<2>")
	)
	(segment
		(start 190.264288 -218.710256)
		(end 192.422272 -218.710256)
		(width 0.16002)
		(layer "In6.Cu")
		(net "M_K_CPU1_SA_DQS_DP<2>")
	)
	(segment
		(start 192.422272 -218.710256)
		(end 192.996312 -219.284296)
		(width 0.16002)
		(layer "In6.Cu")
		(net "M_K_CPU1_SA_DQS_DP<2>")
	)
	(segment
		(start 144.485868 -236.709458)
		(end 144.49425 -236.714284)
		(width 0.09525)
		(layer "In6.Cu")
		(net "M_K_CPU1_SA_DQS_DP<2>")
	)
	(segment
		(start 149.79777 -234.698794)
		(end 161.10839 -223.388174)
		(width 0.16002)
		(layer "In6.Cu")
		(net "M_K_CPU1_SA_DQS_DP<2>")
	)
	(segment
		(start 181.141116 -219.900754)
		(end 181.992016 -219.049854)
		(width 0.16002)
		(layer "In6.Cu")
		(net "M_K_CPU1_SA_DQS_DP<2>")
	)
	(segment
		(start 198.430388 -219.709238)
		(end 198.7042 -219.435426)
		(width 0.16002)
		(layer "In6.Cu")
		(net "M_K_CPU1_SA_DQS_DP<2>")
	)
	(segment
		(start 184.6834 -218.710256)
		(end 185.533284 -219.56014)
		(width 0.16002)
		(layer "In6.Cu")
		(net "M_K_CPU1_SA_DQS_DP<2>")
	)
	(segment
		(start 147.919186 -234.698794)
		(end 149.79777 -234.698794)
		(width 0.16002)
		(layer "In6.Cu")
		(net "M_K_CPU1_SA_DQS_DP<2>")
	)
	(segment
		(start 196.210682 -219.908374)
		(end 196.409818 -219.709238)
		(width 0.16002)
		(layer "In6.Cu")
		(net "M_K_CPU1_SA_DQS_DP<2>")
	)
	(segment
		(start 187.943236 -219.56014)
		(end 188.28385 -219.900754)
		(width 0.16002)
		(layer "In6.Cu")
		(net "M_K_CPU1_SA_DQS_DP<2>")
	)
	(segment
		(start 192.996312 -219.284296)
		(end 195.207128 -219.284296)
		(width 0.16002)
		(layer "In6.Cu")
		(net "M_K_CPU1_SA_DQS_DP<2>")
	)
	(segment
		(start 182.380636 -219.049854)
		(end 182.720234 -218.710256)
		(width 0.16002)
		(layer "In6.Cu")
		(net "M_K_CPU1_SA_DQS_DP<2>")
	)
	(segment
		(start 197.15226 -219.582238)
		(end 197.63232 -219.582238)
		(width 0.16002)
		(layer "In6.Cu")
		(net "M_K_CPU1_SA_DQS_DP<2>")
	)
	(segment
		(start 146.852894 -235.472224)
		(end 147.567142 -234.757976)
		(width 0.09525)
		(layer "In6.Cu")
		(net "M_K_CPU1_SA_DQS_DP<2>")
	)
	(segment
		(start 143.923258 -236.709458)
		(end 143.933672 -236.703362)
		(width 0.09525)
		(layer "In6.Cu")
		(net "M_K_CPU1_SA_DQS_DP<2>")
	)
	(segment
		(start 166.903908 -219.049854)
		(end 167.292528 -219.049854)
		(width 0.16002)
		(layer "In6.Cu")
		(net "M_K_CPU1_SA_DQS_DP<2>")
	)
	(segment
		(start 142.640812 -236.649768)
		(end 142.663926 -236.736382)
		(width 0.09525)
		(layer "In6.Cu")
		(net "M_K_CPU1_SA_DQS_DP<2>")
	)
	(segment
		(start 175.17618 -218.710256)
		(end 177.139346 -218.710256)
		(width 0.16002)
		(layer "In6.Cu")
		(net "M_K_CPU1_SA_DQS_DP<2>")
	)
	(segment
		(start 145.393918 -236.633512)
		(end 146.555206 -235.472224)
		(width 0.09525)
		(layer "In6.Cu")
		(net "M_K_CPU1_SA_DQS_DP<2>")
	)
	(segment
		(start 174.836582 -219.049854)
		(end 175.17618 -218.710256)
		(width 0.16002)
		(layer "In6.Cu")
		(net "M_K_CPU1_SA_DQS_DP<2>")
	)
	(segment
		(start 195.831206 -219.908374)
		(end 196.210682 -219.908374)
		(width 0.16002)
		(layer "In6.Cu")
		(net "M_K_CPU1_SA_DQS_DP<2>")
	)
	(segment
		(start 180.399182 -219.56014)
		(end 180.739796 -219.900754)
		(width 0.16002)
		(layer "In6.Cu")
		(net "M_K_CPU1_SA_DQS_DP<2>")
	)
	(segment
		(start 170.445176 -219.56014)
		(end 172.855128 -219.56014)
		(width 0.16002)
		(layer "In6.Cu")
		(net "M_K_CPU1_SA_DQS_DP<2>")
	)
	(segment
		(start 143.914876 -236.714284)
		(end 143.923258 -236.709458)
		(width 0.09525)
		(layer "In6.Cu")
		(net "M_K_CPU1_SA_DQS_DP<2>")
	)
	(segment
		(start 161.10839 -223.388174)
		(end 161.10839 -222.707454)
		(width 0.16002)
		(layer "In6.Cu")
		(net "M_K_CPU1_SA_DQS_DP<2>")
	)
	(segment
		(start 173.597062 -219.900754)
		(end 174.447962 -219.049854)
		(width 0.16002)
		(layer "In6.Cu")
		(net "M_K_CPU1_SA_DQS_DP<2>")
	)
	(segment
		(start 172.855128 -219.56014)
		(end 173.195742 -219.900754)
		(width 0.16002)
		(layer "In6.Cu")
		(net "M_K_CPU1_SA_DQS_DP<2>")
	)
	(arc
		(start 143.933672 -236.703362)
		(mid 144.21058 -236.633685)
		(end 144.485868 -236.709458)
		(width 0.09525)
		(layer "In6.Cu")
		(net "M_K_CPU1_SA_DQS_DP<2>")
	)
	(arc
		(start 142.983204 -236.709458)
		(mid 143.264636 -236.633703)
		(end 143.546068 -236.709458)
		(width 0.09525)
		(layer "In6.Cu")
		(net "M_K_CPU1_SA_DQS_DP<2>")
	)
	(arc
		(start 143.546068 -236.709458)
		(mid 143.729843 -236.76023)
		(end 143.914876 -236.714284)
		(width 0.09525)
		(layer "In6.Cu")
		(net "M_K_CPU1_SA_DQS_DP<2>")
	)
	(arc
		(start 144.863058 -236.709458)
		(mid 144.99888 -236.652878)
		(end 145.144744 -236.633512)
		(width 0.09525)
		(layer "In6.Cu")
		(net "M_K_CPU1_SA_DQS_DP<2>")
	)
	(arc
		(start 144.49425 -236.714284)
		(mid 144.679282 -236.760198)
		(end 144.863058 -236.709458)
		(width 0.09525)
		(layer "In6.Cu")
		(net "M_K_CPU1_SA_DQS_DP<2>")
	)
	(arc
		(start 142.663926 -236.736382)
		(mid 142.826577 -236.758642)
		(end 142.983204 -236.709458)
		(width 0.09525)
		(layer "In6.Cu")
		(net "M_K_CPU1_SA_DQS_DP<2>")
	)
	(segment
		(start 142.327884 -231.79024)
		(end 142.794736 -231.524302)
		(width 0.12954)
		(layer "F.Cu")
		(net "M_K_CPU1_SA_DQS_DP<1>")
	)
	(segment
		(start 145.10512 -231.625902)
		(end 145.226786 -231.625902)
		(width 0.09525)
		(layer "In6.Cu")
		(net "M_K_CPU1_SA_DQS_DP<1>")
	)
	(segment
		(start 142.640812 -231.789732)
		(end 142.663926 -231.876346)
		(width 0.09525)
		(layer "In6.Cu")
		(net "M_K_CPU1_SA_DQS_DP<1>")
	)
	(segment
		(start 182.380636 -209.69986)
		(end 182.720234 -209.360262)
		(width 0.16002)
		(layer "In6.Cu")
		(net "M_K_CPU1_SA_DQS_DP<1>")
	)
	(segment
		(start 180.399182 -210.210146)
		(end 180.739796 -210.55076)
		(width 0.16002)
		(layer "In6.Cu")
		(net "M_K_CPU1_SA_DQS_DP<1>")
	)
	(segment
		(start 197.74916 -210.359244)
		(end 198.430388 -210.359244)
		(width 0.16002)
		(layer "In6.Cu")
		(net "M_K_CPU1_SA_DQS_DP<1>")
	)
	(segment
		(start 181.992016 -209.69986)
		(end 182.380636 -209.69986)
		(width 0.16002)
		(layer "In6.Cu")
		(net "M_K_CPU1_SA_DQS_DP<1>")
	)
	(segment
		(start 196.409818 -210.359244)
		(end 197.0151 -210.359244)
		(width 0.16002)
		(layer "In6.Cu")
		(net "M_K_CPU1_SA_DQS_DP<1>")
	)
	(segment
		(start 182.720234 -209.360262)
		(end 184.6834 -209.360262)
		(width 0.16002)
		(layer "In6.Cu")
		(net "M_K_CPU1_SA_DQS_DP<1>")
	)
	(segment
		(start 147.688554 -228.89845)
		(end 147.688554 -228.815138)
		(width 0.09525)
		(layer "In6.Cu")
		(net "M_K_CPU1_SA_DQS_DP<1>")
	)
	(segment
		(start 147.705318 -228.798374)
		(end 154.91079 -221.592902)
		(width 0.16002)
		(layer "In6.Cu")
		(net "M_K_CPU1_SA_DQS_DP<1>")
	)
	(segment
		(start 190.264288 -209.360262)
		(end 192.422272 -209.360262)
		(width 0.16002)
		(layer "In6.Cu")
		(net "M_K_CPU1_SA_DQS_DP<1>")
	)
	(segment
		(start 192.996312 -209.934302)
		(end 195.207128 -209.934302)
		(width 0.16002)
		(layer "In6.Cu")
		(net "M_K_CPU1_SA_DQS_DP<1>")
	)
	(segment
		(start 198.430388 -210.359244)
		(end 198.7042 -210.085432)
		(width 0.16002)
		(layer "In6.Cu")
		(net "M_K_CPU1_SA_DQS_DP<1>")
	)
	(segment
		(start 181.141116 -210.55076)
		(end 181.992016 -209.69986)
		(width 0.16002)
		(layer "In6.Cu")
		(net "M_K_CPU1_SA_DQS_DP<1>")
	)
	(segment
		(start 197.0151 -210.359244)
		(end 197.118478 -210.255866)
		(width 0.16002)
		(layer "In6.Cu")
		(net "M_K_CPU1_SA_DQS_DP<1>")
	)
	(segment
		(start 189.53607 -209.69986)
		(end 189.92469 -209.69986)
		(width 0.16002)
		(layer "In6.Cu")
		(net "M_K_CPU1_SA_DQS_DP<1>")
	)
	(segment
		(start 154.91079 -221.592902)
		(end 154.91079 -219.432886)
		(width 0.16002)
		(layer "In6.Cu")
		(net "M_K_CPU1_SA_DQS_DP<1>")
	)
	(segment
		(start 180.739796 -210.55076)
		(end 181.141116 -210.55076)
		(width 0.16002)
		(layer "In6.Cu")
		(net "M_K_CPU1_SA_DQS_DP<1>")
	)
	(segment
		(start 184.6834 -209.360262)
		(end 185.533284 -210.210146)
		(width 0.16002)
		(layer "In6.Cu")
		(net "M_K_CPU1_SA_DQS_DP<1>")
	)
	(segment
		(start 170.445176 -210.210146)
		(end 172.855128 -210.210146)
		(width 0.16002)
		(layer "In6.Cu")
		(net "M_K_CPU1_SA_DQS_DP<1>")
	)
	(segment
		(start 172.855128 -210.210146)
		(end 173.195742 -210.55076)
		(width 0.16002)
		(layer "In6.Cu")
		(net "M_K_CPU1_SA_DQS_DP<1>")
	)
	(segment
		(start 188.68517 -210.55076)
		(end 189.53607 -209.69986)
		(width 0.16002)
		(layer "In6.Cu")
		(net "M_K_CPU1_SA_DQS_DP<1>")
	)
	(segment
		(start 144.940528 -231.790494)
		(end 145.10512 -231.625902)
		(width 0.09525)
		(layer "In6.Cu")
		(net "M_K_CPU1_SA_DQS_DP<1>")
	)
	(segment
		(start 146.96059 -229.626414)
		(end 147.688554 -228.89845)
		(width 0.09525)
		(layer "In6.Cu")
		(net "M_K_CPU1_SA_DQS_DP<1>")
	)
	(segment
		(start 195.831206 -210.55838)
		(end 196.210682 -210.55838)
		(width 0.16002)
		(layer "In6.Cu")
		(net "M_K_CPU1_SA_DQS_DP<1>")
	)
	(segment
		(start 146.077178 -230.07193)
		(end 146.522694 -229.626414)
		(width 0.09525)
		(layer "In6.Cu")
		(net "M_K_CPU1_SA_DQS_DP<1>")
	)
	(segment
		(start 197.118478 -210.255866)
		(end 197.645782 -210.255866)
		(width 0.16002)
		(layer "In6.Cu")
		(net "M_K_CPU1_SA_DQS_DP<1>")
	)
	(segment
		(start 143.923258 -231.849422)
		(end 143.933672 -231.843326)
		(width 0.09525)
		(layer "In6.Cu")
		(net "M_K_CPU1_SA_DQS_DP<1>")
	)
	(segment
		(start 147.688554 -228.815138)
		(end 147.705318 -228.798374)
		(width 0.09525)
		(layer "In6.Cu")
		(net "M_K_CPU1_SA_DQS_DP<1>")
	)
	(segment
		(start 166.053008 -210.55076)
		(end 166.903908 -209.69986)
		(width 0.16002)
		(layer "In6.Cu")
		(net "M_K_CPU1_SA_DQS_DP<1>")
	)
	(segment
		(start 146.077178 -230.77551)
		(end 146.077178 -230.07193)
		(width 0.09525)
		(layer "In6.Cu")
		(net "M_K_CPU1_SA_DQS_DP<1>")
	)
	(segment
		(start 187.943236 -210.210146)
		(end 188.28385 -210.55076)
		(width 0.16002)
		(layer "In6.Cu")
		(net "M_K_CPU1_SA_DQS_DP<1>")
	)
	(segment
		(start 185.533284 -210.210146)
		(end 187.943236 -210.210146)
		(width 0.16002)
		(layer "In6.Cu")
		(net "M_K_CPU1_SA_DQS_DP<1>")
	)
	(segment
		(start 146.522694 -229.626414)
		(end 146.96059 -229.626414)
		(width 0.09525)
		(layer "In6.Cu")
		(net "M_K_CPU1_SA_DQS_DP<1>")
	)
	(segment
		(start 173.597062 -210.55076)
		(end 174.447962 -209.69986)
		(width 0.16002)
		(layer "In6.Cu")
		(net "M_K_CPU1_SA_DQS_DP<1>")
	)
	(segment
		(start 163.792916 -210.55076)
		(end 166.053008 -210.55076)
		(width 0.16002)
		(layer "In6.Cu")
		(net "M_K_CPU1_SA_DQS_DP<1>")
	)
	(segment
		(start 144.485868 -231.849422)
		(end 144.49425 -231.854248)
		(width 0.09525)
		(layer "In6.Cu")
		(net "M_K_CPU1_SA_DQS_DP<1>")
	)
	(segment
		(start 177.139346 -209.360262)
		(end 177.98923 -210.210146)
		(width 0.16002)
		(layer "In6.Cu")
		(net "M_K_CPU1_SA_DQS_DP<1>")
	)
	(segment
		(start 174.836582 -209.69986)
		(end 175.17618 -209.360262)
		(width 0.16002)
		(layer "In6.Cu")
		(net "M_K_CPU1_SA_DQS_DP<1>")
	)
	(segment
		(start 175.17618 -209.360262)
		(end 177.139346 -209.360262)
		(width 0.16002)
		(layer "In6.Cu")
		(net "M_K_CPU1_SA_DQS_DP<1>")
	)
	(segment
		(start 196.210682 -210.55838)
		(end 196.409818 -210.359244)
		(width 0.16002)
		(layer "In6.Cu")
		(net "M_K_CPU1_SA_DQS_DP<1>")
	)
	(segment
		(start 177.98923 -210.210146)
		(end 180.399182 -210.210146)
		(width 0.16002)
		(layer "In6.Cu")
		(net "M_K_CPU1_SA_DQS_DP<1>")
	)
	(segment
		(start 145.226786 -231.625902)
		(end 146.077178 -230.77551)
		(width 0.09525)
		(layer "In6.Cu")
		(net "M_K_CPU1_SA_DQS_DP<1>")
	)
	(segment
		(start 195.207128 -209.934302)
		(end 195.831206 -210.55838)
		(width 0.16002)
		(layer "In6.Cu")
		(net "M_K_CPU1_SA_DQS_DP<1>")
	)
	(segment
		(start 166.903908 -209.69986)
		(end 169.93489 -209.69986)
		(width 0.16002)
		(layer "In6.Cu")
		(net "M_K_CPU1_SA_DQS_DP<1>")
	)
	(segment
		(start 142.794736 -231.524302)
		(end 142.640812 -231.789732)
		(width 0.09525)
		(layer "In6.Cu")
		(net "M_K_CPU1_SA_DQS_DP<1>")
	)
	(segment
		(start 197.645782 -210.255866)
		(end 197.74916 -210.359244)
		(width 0.16002)
		(layer "In6.Cu")
		(net "M_K_CPU1_SA_DQS_DP<1>")
	)
	(segment
		(start 169.93489 -209.69986)
		(end 170.445176 -210.210146)
		(width 0.16002)
		(layer "In6.Cu")
		(net "M_K_CPU1_SA_DQS_DP<1>")
	)
	(segment
		(start 174.447962 -209.69986)
		(end 174.836582 -209.69986)
		(width 0.16002)
		(layer "In6.Cu")
		(net "M_K_CPU1_SA_DQS_DP<1>")
	)
	(segment
		(start 192.422272 -209.360262)
		(end 192.996312 -209.934302)
		(width 0.16002)
		(layer "In6.Cu")
		(net "M_K_CPU1_SA_DQS_DP<1>")
	)
	(segment
		(start 188.28385 -210.55076)
		(end 188.68517 -210.55076)
		(width 0.16002)
		(layer "In6.Cu")
		(net "M_K_CPU1_SA_DQS_DP<1>")
	)
	(segment
		(start 173.195742 -210.55076)
		(end 173.597062 -210.55076)
		(width 0.16002)
		(layer "In6.Cu")
		(net "M_K_CPU1_SA_DQS_DP<1>")
	)
	(segment
		(start 143.914876 -231.854248)
		(end 143.923258 -231.849422)
		(width 0.09525)
		(layer "In6.Cu")
		(net "M_K_CPU1_SA_DQS_DP<1>")
	)
	(segment
		(start 154.91079 -219.432886)
		(end 163.792916 -210.55076)
		(width 0.16002)
		(layer "In6.Cu")
		(net "M_K_CPU1_SA_DQS_DP<1>")
	)
	(segment
		(start 189.92469 -209.69986)
		(end 190.264288 -209.360262)
		(width 0.16002)
		(layer "In6.Cu")
		(net "M_K_CPU1_SA_DQS_DP<1>")
	)
	(arc
		(start 144.863058 -231.849422)
		(mid 144.903701 -231.822468)
		(end 144.940528 -231.790494)
		(width 0.09525)
		(layer "In6.Cu")
		(net "M_K_CPU1_SA_DQS_DP<1>")
	)
	(arc
		(start 143.933672 -231.843326)
		(mid 144.21058 -231.773649)
		(end 144.485868 -231.849422)
		(width 0.09525)
		(layer "In6.Cu")
		(net "M_K_CPU1_SA_DQS_DP<1>")
	)
	(arc
		(start 144.49425 -231.854248)
		(mid 144.679282 -231.900162)
		(end 144.863058 -231.849422)
		(width 0.09525)
		(layer "In6.Cu")
		(net "M_K_CPU1_SA_DQS_DP<1>")
	)
	(arc
		(start 142.983204 -231.849422)
		(mid 143.264636 -231.773667)
		(end 143.546068 -231.849422)
		(width 0.09525)
		(layer "In6.Cu")
		(net "M_K_CPU1_SA_DQS_DP<1>")
	)
	(arc
		(start 142.663926 -231.876346)
		(mid 142.826577 -231.898606)
		(end 142.983204 -231.849422)
		(width 0.09525)
		(layer "In6.Cu")
		(net "M_K_CPU1_SA_DQS_DP<1>")
	)
	(arc
		(start 143.546068 -231.849422)
		(mid 143.729843 -231.900194)
		(end 143.914876 -231.854248)
		(width 0.09525)
		(layer "In6.Cu")
		(net "M_K_CPU1_SA_DQS_DP<1>")
	)
	(segment
		(start 142.327884 -226.930458)
		(end 142.794736 -226.66452)
		(width 0.12954)
		(layer "F.Cu")
		(net "M_K_CPU1_SA_DQS_DP<0>")
	)
	(segment
		(start 148.95449 -218.822524)
		(end 148.95449 -215.919304)
		(width 0.16002)
		(layer "In6.Cu")
		(net "M_K_CPU1_SA_DQS_DP<0>")
	)
	(segment
		(start 180.739796 -201.200766)
		(end 181.141116 -201.200766)
		(width 0.16002)
		(layer "In6.Cu")
		(net "M_K_CPU1_SA_DQS_DP<0>")
	)
	(segment
		(start 188.68517 -201.200766)
		(end 189.53607 -200.349866)
		(width 0.16002)
		(layer "In6.Cu")
		(net "M_K_CPU1_SA_DQS_DP<0>")
	)
	(segment
		(start 142.640812 -226.92995)
		(end 142.663926 -227.016564)
		(width 0.09525)
		(layer "In6.Cu")
		(net "M_K_CPU1_SA_DQS_DP<0>")
	)
	(segment
		(start 144.895824 -224.738184)
		(end 144.863312 -224.719388)
		(width 0.09525)
		(layer "In6.Cu")
		(net "M_K_CPU1_SA_DQS_DP<0>")
	)
	(segment
		(start 187.943236 -200.860152)
		(end 188.28385 -201.200766)
		(width 0.16002)
		(layer "In6.Cu")
		(net "M_K_CPU1_SA_DQS_DP<0>")
	)
	(segment
		(start 170.445176 -200.860152)
		(end 172.855128 -200.860152)
		(width 0.16002)
		(layer "In6.Cu")
		(net "M_K_CPU1_SA_DQS_DP<0>")
	)
	(segment
		(start 144.355312 -226.201732)
		(end 144.393412 -226.179634)
		(width 0.09525)
		(layer "In6.Cu")
		(net "M_K_CPU1_SA_DQS_DP<0>")
	)
	(segment
		(start 172.855128 -200.860152)
		(end 173.195742 -201.200766)
		(width 0.16002)
		(layer "In6.Cu")
		(net "M_K_CPU1_SA_DQS_DP<0>")
	)
	(segment
		(start 144.863312 -224.719388)
		(end 144.825212 -224.69729)
		(width 0.09525)
		(layer "In6.Cu")
		(net "M_K_CPU1_SA_DQS_DP<0>")
	)
	(segment
		(start 188.28385 -201.200766)
		(end 188.68517 -201.200766)
		(width 0.16002)
		(layer "In6.Cu")
		(net "M_K_CPU1_SA_DQS_DP<0>")
	)
	(segment
		(start 181.992016 -200.349866)
		(end 182.380636 -200.349866)
		(width 0.16002)
		(layer "In6.Cu")
		(net "M_K_CPU1_SA_DQS_DP<0>")
	)
	(segment
		(start 167.292528 -200.349866)
		(end 167.632126 -200.010268)
		(width 0.16002)
		(layer "In6.Cu")
		(net "M_K_CPU1_SA_DQS_DP<0>")
	)
	(segment
		(start 144.863312 -225.369628)
		(end 144.895824 -225.350832)
		(width 0.09525)
		(layer "In6.Cu")
		(net "M_K_CPU1_SA_DQS_DP<0>")
	)
	(segment
		(start 177.139346 -200.010268)
		(end 177.98923 -200.860152)
		(width 0.16002)
		(layer "In6.Cu")
		(net "M_K_CPU1_SA_DQS_DP<0>")
	)
	(segment
		(start 163.673028 -201.200766)
		(end 166.053008 -201.200766)
		(width 0.16002)
		(layer "In6.Cu")
		(net "M_K_CPU1_SA_DQS_DP<0>")
	)
	(segment
		(start 196.409818 -201.00925)
		(end 197.09638 -201.00925)
		(width 0.16002)
		(layer "In6.Cu")
		(net "M_K_CPU1_SA_DQS_DP<0>")
	)
	(segment
		(start 197.737476 -200.916286)
		(end 197.83044 -201.00925)
		(width 0.16002)
		(layer "In6.Cu")
		(net "M_K_CPU1_SA_DQS_DP<0>")
	)
	(segment
		(start 174.447962 -200.349866)
		(end 174.836582 -200.349866)
		(width 0.16002)
		(layer "In6.Cu")
		(net "M_K_CPU1_SA_DQS_DP<0>")
	)
	(segment
		(start 166.053008 -201.200766)
		(end 166.903908 -200.349866)
		(width 0.16002)
		(layer "In6.Cu")
		(net "M_K_CPU1_SA_DQS_DP<0>")
	)
	(segment
		(start 189.53607 -200.349866)
		(end 189.92469 -200.349866)
		(width 0.16002)
		(layer "In6.Cu")
		(net "M_K_CPU1_SA_DQS_DP<0>")
	)
	(segment
		(start 182.380636 -200.349866)
		(end 182.720234 -200.010268)
		(width 0.16002)
		(layer "In6.Cu")
		(net "M_K_CPU1_SA_DQS_DP<0>")
	)
	(segment
		(start 173.195742 -201.200766)
		(end 173.597062 -201.200766)
		(width 0.16002)
		(layer "In6.Cu")
		(net "M_K_CPU1_SA_DQS_DP<0>")
	)
	(segment
		(start 146.012154 -221.76486)
		(end 146.028918 -221.748096)
		(width 0.09525)
		(layer "In6.Cu")
		(net "M_K_CPU1_SA_DQS_DP<0>")
	)
	(segment
		(start 174.836582 -200.349866)
		(end 175.17618 -200.010268)
		(width 0.16002)
		(layer "In6.Cu")
		(net "M_K_CPU1_SA_DQS_DP<0>")
	)
	(segment
		(start 181.141116 -201.200766)
		(end 181.992016 -200.349866)
		(width 0.16002)
		(layer "In6.Cu")
		(net "M_K_CPU1_SA_DQS_DP<0>")
	)
	(segment
		(start 192.996312 -200.584308)
		(end 195.207128 -200.584308)
		(width 0.16002)
		(layer "In6.Cu")
		(net "M_K_CPU1_SA_DQS_DP<0>")
	)
	(segment
		(start 146.012154 -221.84868)
		(end 146.012154 -221.76486)
		(width 0.09525)
		(layer "In6.Cu")
		(net "M_K_CPU1_SA_DQS_DP<0>")
	)
	(segment
		(start 184.6834 -200.010268)
		(end 185.533284 -200.860152)
		(width 0.16002)
		(layer "In6.Cu")
		(net "M_K_CPU1_SA_DQS_DP<0>")
	)
	(segment
		(start 144.863312 -223.749616)
		(end 144.895824 -223.73082)
		(width 0.09525)
		(layer "In6.Cu")
		(net "M_K_CPU1_SA_DQS_DP<0>")
	)
	(segment
		(start 148.95449 -215.919304)
		(end 163.673028 -201.200766)
		(width 0.16002)
		(layer "In6.Cu")
		(net "M_K_CPU1_SA_DQS_DP<0>")
	)
	(segment
		(start 144.825212 -225.391726)
		(end 144.863312 -225.369628)
		(width 0.09525)
		(layer "In6.Cu")
		(net "M_K_CPU1_SA_DQS_DP<0>")
	)
	(segment
		(start 142.794736 -226.66452)
		(end 142.640812 -226.92995)
		(width 0.09525)
		(layer "In6.Cu")
		(net "M_K_CPU1_SA_DQS_DP<0>")
	)
	(segment
		(start 145.29816 -222.960184)
		(end 145.333212 -222.93961)
		(width 0.09525)
		(layer "In6.Cu")
		(net "M_K_CPU1_SA_DQS_DP<0>")
	)
	(segment
		(start 145.522442 -222.338392)
		(end 146.012154 -221.84868)
		(width 0.09525)
		(layer "In6.Cu")
		(net "M_K_CPU1_SA_DQS_DP<0>")
	)
	(segment
		(start 192.422272 -200.010268)
		(end 192.996312 -200.584308)
		(width 0.16002)
		(layer "In6.Cu")
		(net "M_K_CPU1_SA_DQS_DP<0>")
	)
	(segment
		(start 180.399182 -200.860152)
		(end 180.739796 -201.200766)
		(width 0.16002)
		(layer "In6.Cu")
		(net "M_K_CPU1_SA_DQS_DP<0>")
	)
	(segment
		(start 195.831206 -201.208386)
		(end 196.210682 -201.208386)
		(width 0.16002)
		(layer "In6.Cu")
		(net "M_K_CPU1_SA_DQS_DP<0>")
	)
	(segment
		(start 185.533284 -200.860152)
		(end 187.943236 -200.860152)
		(width 0.16002)
		(layer "In6.Cu")
		(net "M_K_CPU1_SA_DQS_DP<0>")
	)
	(segment
		(start 167.632126 -200.010268)
		(end 169.595292 -200.010268)
		(width 0.16002)
		(layer "In6.Cu")
		(net "M_K_CPU1_SA_DQS_DP<0>")
	)
	(segment
		(start 182.720234 -200.010268)
		(end 184.6834 -200.010268)
		(width 0.16002)
		(layer "In6.Cu")
		(net "M_K_CPU1_SA_DQS_DP<0>")
	)
	(segment
		(start 189.92469 -200.349866)
		(end 190.264288 -200.010268)
		(width 0.16002)
		(layer "In6.Cu")
		(net "M_K_CPU1_SA_DQS_DP<0>")
	)
	(segment
		(start 198.430388 -201.00925)
		(end 198.7042 -200.735438)
		(width 0.16002)
		(layer "In6.Cu")
		(net "M_K_CPU1_SA_DQS_DP<0>")
	)
	(segment
		(start 177.98923 -200.860152)
		(end 180.399182 -200.860152)
		(width 0.16002)
		(layer "In6.Cu")
		(net "M_K_CPU1_SA_DQS_DP<0>")
	)
	(segment
		(start 197.09638 -201.00925)
		(end 197.189344 -200.916286)
		(width 0.16002)
		(layer "In6.Cu")
		(net "M_K_CPU1_SA_DQS_DP<0>")
	)
	(segment
		(start 175.17618 -200.010268)
		(end 177.139346 -200.010268)
		(width 0.16002)
		(layer "In6.Cu")
		(net "M_K_CPU1_SA_DQS_DP<0>")
	)
	(segment
		(start 144.825212 -223.771714)
		(end 144.863312 -223.749616)
		(width 0.09525)
		(layer "In6.Cu")
		(net "M_K_CPU1_SA_DQS_DP<0>")
	)
	(segment
		(start 173.597062 -201.200766)
		(end 174.447962 -200.349866)
		(width 0.16002)
		(layer "In6.Cu")
		(net "M_K_CPU1_SA_DQS_DP<0>")
	)
	(segment
		(start 190.264288 -200.010268)
		(end 192.422272 -200.010268)
		(width 0.16002)
		(layer "In6.Cu")
		(net "M_K_CPU1_SA_DQS_DP<0>")
	)
	(segment
		(start 143.914876 -226.994466)
		(end 143.923258 -226.98964)
		(width 0.09525)
		(layer "In6.Cu")
		(net "M_K_CPU1_SA_DQS_DP<0>")
	)
	(segment
		(start 197.189344 -200.916286)
		(end 197.737476 -200.916286)
		(width 0.16002)
		(layer "In6.Cu")
		(net "M_K_CPU1_SA_DQS_DP<0>")
	)
	(segment
		(start 197.83044 -201.00925)
		(end 198.430388 -201.00925)
		(width 0.16002)
		(layer "In6.Cu")
		(net "M_K_CPU1_SA_DQS_DP<0>")
	)
	(segment
		(start 144.393412 -226.179634)
		(end 144.424908 -226.161346)
		(width 0.09525)
		(layer "In6.Cu")
		(net "M_K_CPU1_SA_DQS_DP<0>")
	)
	(segment
		(start 145.333212 -222.93961)
		(end 145.365724 -222.920814)
		(width 0.09525)
		(layer "In6.Cu")
		(net "M_K_CPU1_SA_DQS_DP<0>")
	)
	(segment
		(start 166.903908 -200.349866)
		(end 167.292528 -200.349866)
		(width 0.16002)
		(layer "In6.Cu")
		(net "M_K_CPU1_SA_DQS_DP<0>")
	)
	(segment
		(start 143.923258 -226.98964)
		(end 143.95577 -226.970844)
		(width 0.09525)
		(layer "In6.Cu")
		(net "M_K_CPU1_SA_DQS_DP<0>")
	)
	(segment
		(start 195.207128 -200.584308)
		(end 195.831206 -201.208386)
		(width 0.16002)
		(layer "In6.Cu")
		(net "M_K_CPU1_SA_DQS_DP<0>")
	)
	(segment
		(start 146.028918 -221.748096)
		(end 148.95449 -218.822524)
		(width 0.16002)
		(layer "In6.Cu")
		(net "M_K_CPU1_SA_DQS_DP<0>")
	)
	(segment
		(start 145.522442 -222.61449)
		(end 145.522442 -222.338392)
		(width 0.09525)
		(layer "In6.Cu")
		(net "M_K_CPU1_SA_DQS_DP<0>")
	)
	(segment
		(start 169.595292 -200.010268)
		(end 170.445176 -200.860152)
		(width 0.16002)
		(layer "In6.Cu")
		(net "M_K_CPU1_SA_DQS_DP<0>")
	)
	(segment
		(start 196.210682 -201.208386)
		(end 196.409818 -201.00925)
		(width 0.16002)
		(layer "In6.Cu")
		(net "M_K_CPU1_SA_DQS_DP<0>")
	)
	(arc
		(start 144.825212 -224.69729)
		(mid 144.582362 -224.234502)
		(end 144.825212 -223.771714)
		(width 0.09525)
		(layer "In6.Cu")
		(net "M_K_CPU1_SA_DQS_DP<0>")
	)
	(arc
		(start 144.112488 -226.66452)
		(mid 144.176885 -226.403214)
		(end 144.355312 -226.201732)
		(width 0.09525)
		(layer "In6.Cu")
		(net "M_K_CPU1_SA_DQS_DP<0>")
	)
	(arc
		(start 145.052542 -223.424496)
		(mid 145.117789 -223.161893)
		(end 145.29816 -222.960184)
		(width 0.09525)
		(layer "In6.Cu")
		(net "M_K_CPU1_SA_DQS_DP<0>")
	)
	(arc
		(start 144.424908 -226.161346)
		(mid 144.540706 -226.026952)
		(end 144.582388 -225.854514)
		(width 0.09525)
		(layer "In6.Cu")
		(net "M_K_CPU1_SA_DQS_DP<0>")
	)
	(arc
		(start 142.983204 -226.98964)
		(mid 143.264636 -226.913885)
		(end 143.546068 -226.98964)
		(width 0.09525)
		(layer "In6.Cu")
		(net "M_K_CPU1_SA_DQS_DP<0>")
	)
	(arc
		(start 145.365724 -222.920814)
		(mid 145.480998 -222.786536)
		(end 145.522442 -222.61449)
		(width 0.09525)
		(layer "In6.Cu")
		(net "M_K_CPU1_SA_DQS_DP<0>")
	)
	(arc
		(start 144.895824 -225.350832)
		(mid 145.052556 -225.044508)
		(end 144.895824 -224.738184)
		(width 0.09525)
		(layer "In6.Cu")
		(net "M_K_CPU1_SA_DQS_DP<0>")
	)
	(arc
		(start 144.582388 -225.854514)
		(mid 144.646785 -225.593208)
		(end 144.825212 -225.391726)
		(width 0.09525)
		(layer "In6.Cu")
		(net "M_K_CPU1_SA_DQS_DP<0>")
	)
	(arc
		(start 143.546068 -226.98964)
		(mid 143.729843 -227.040412)
		(end 143.914876 -226.994466)
		(width 0.09525)
		(layer "In6.Cu")
		(net "M_K_CPU1_SA_DQS_DP<0>")
	)
	(arc
		(start 144.895824 -223.73082)
		(mid 145.011098 -223.596542)
		(end 145.052542 -223.424496)
		(width 0.09525)
		(layer "In6.Cu")
		(net "M_K_CPU1_SA_DQS_DP<0>")
	)
	(arc
		(start 142.663926 -227.016564)
		(mid 142.826577 -227.038824)
		(end 142.983204 -226.98964)
		(width 0.09525)
		(layer "In6.Cu")
		(net "M_K_CPU1_SA_DQS_DP<0>")
	)
	(arc
		(start 143.95577 -226.970844)
		(mid 144.071044 -226.836566)
		(end 144.112488 -226.66452)
		(width 0.09525)
		(layer "In6.Cu")
		(net "M_K_CPU1_SA_DQS_DP<0>")
	)
	(segment
		(start 140.91793 -247.180354)
		(end 141.384782 -246.914416)
		(width 0.12954)
		(layer "F.Cu")
		(net "M_K_CPU1_SA_DQS_DN<9>")
	)
	(segment
		(start 185.367168 -239.408208)
		(end 186.02198 -239.408208)
		(width 0.16002)
		(layer "In6.Cu")
		(net "M_K_CPU1_SA_DQS_DN<9>")
	)
	(segment
		(start 157.300168 -246.844566)
		(end 164.266372 -239.878362)
		(width 0.16002)
		(layer "In6.Cu")
		(net "M_K_CPU1_SA_DQS_DN<9>")
	)
	(segment
		(start 187.652406 -240.258346)
		(end 188.03239 -239.878362)
		(width 0.16002)
		(layer "In6.Cu")
		(net "M_K_CPU1_SA_DQS_DN<9>")
	)
	(segment
		(start 147.745958 -247.379998)
		(end 148.038058 -247.379998)
		(width 0.16002)
		(layer "In6.Cu")
		(net "M_K_CPU1_SA_DQS_DN<9>")
	)
	(segment
		(start 180.488336 -239.878362)
		(end 181.092856 -239.878362)
		(width 0.16002)
		(layer "In6.Cu")
		(net "M_K_CPU1_SA_DQS_DN<9>")
	)
	(segment
		(start 188.63691 -239.878362)
		(end 189.42431 -239.090962)
		(width 0.16002)
		(layer "In6.Cu")
		(net "M_K_CPU1_SA_DQS_DN<9>")
	)
	(segment
		(start 176.77765 -239.745266)
		(end 176.77765 -240.067846)
		(width 0.16002)
		(layer "In6.Cu")
		(net "M_K_CPU1_SA_DQS_DN<9>")
	)
	(segment
		(start 146.010376 -247.327928)
		(end 146.121628 -247.43918)
		(width 0.09525)
		(layer "In6.Cu")
		(net "M_K_CPU1_SA_DQS_DN<9>")
	)
	(segment
		(start 148.038058 -247.379998)
		(end 148.57349 -246.844566)
		(width 0.16002)
		(layer "In6.Cu")
		(net "M_K_CPU1_SA_DQS_DN<9>")
	)
	(segment
		(start 193.46418 -239.13211)
		(end 193.59118 -239.25911)
		(width 0.16002)
		(layer "In6.Cu")
		(net "M_K_CPU1_SA_DQS_DN<9>")
	)
	(segment
		(start 166.792148 -239.090962)
		(end 167.851328 -239.090962)
		(width 0.16002)
		(layer "In6.Cu")
		(net "M_K_CPU1_SA_DQS_DN<9>")
	)
	(segment
		(start 183.256682 -239.408208)
		(end 184.024778 -239.408208)
		(width 0.16002)
		(layer "In6.Cu")
		(net "M_K_CPU1_SA_DQS_DN<9>")
	)
	(segment
		(start 143.076168 -247.239536)
		(end 143.08455 -247.244362)
		(width 0.09525)
		(layer "In6.Cu")
		(net "M_K_CPU1_SA_DQS_DN<9>")
	)
	(segment
		(start 145.31848 -247.247918)
		(end 145.332958 -247.239536)
		(width 0.09525)
		(layer "In6.Cu")
		(net "M_K_CPU1_SA_DQS_DN<9>")
	)
	(segment
		(start 172.564298 -240.258346)
		(end 172.944282 -239.878362)
		(width 0.16002)
		(layer "In6.Cu")
		(net "M_K_CPU1_SA_DQS_DN<9>")
	)
	(segment
		(start 194.33032 -239.25911)
		(end 194.604132 -238.985298)
		(width 0.16002)
		(layer "In6.Cu")
		(net "M_K_CPU1_SA_DQS_DN<9>")
	)
	(segment
		(start 177.445924 -240.067846)
		(end 177.445924 -239.745266)
		(width 0.16002)
		(layer "In6.Cu")
		(net "M_K_CPU1_SA_DQS_DN<9>")
	)
	(segment
		(start 191.982344 -239.408208)
		(end 192.131442 -239.25911)
		(width 0.16002)
		(layer "In6.Cu")
		(net "M_K_CPU1_SA_DQS_DN<9>")
	)
	(segment
		(start 141.384782 -246.914416)
		(end 141.230858 -247.179846)
		(width 0.09525)
		(layer "In6.Cu")
		(net "M_K_CPU1_SA_DQS_DN<9>")
	)
	(segment
		(start 184.361836 -239.745266)
		(end 184.361836 -240.062766)
		(width 0.16002)
		(layer "In6.Cu")
		(net "M_K_CPU1_SA_DQS_DN<9>")
	)
	(segment
		(start 144.015968 -247.239536)
		(end 144.02435 -247.244362)
		(width 0.09525)
		(layer "In6.Cu")
		(net "M_K_CPU1_SA_DQS_DN<9>")
	)
	(segment
		(start 192.85712 -239.25911)
		(end 192.98412 -239.13211)
		(width 0.16002)
		(layer "In6.Cu")
		(net "M_K_CPU1_SA_DQS_DN<9>")
	)
	(segment
		(start 185.03011 -240.062766)
		(end 185.03011 -239.745266)
		(width 0.16002)
		(layer "In6.Cu")
		(net "M_K_CPU1_SA_DQS_DN<9>")
	)
	(segment
		(start 188.03239 -239.878362)
		(end 188.63691 -239.878362)
		(width 0.16002)
		(layer "In6.Cu")
		(net "M_K_CPU1_SA_DQS_DN<9>")
	)
	(segment
		(start 141.230858 -247.179846)
		(end 141.253972 -247.26646)
		(width 0.09525)
		(layer "In6.Cu")
		(net "M_K_CPU1_SA_DQS_DN<9>")
	)
	(segment
		(start 169.163492 -240.205006)
		(end 169.511726 -240.205006)
		(width 0.16002)
		(layer "In6.Cu")
		(net "M_K_CPU1_SA_DQS_DN<9>")
	)
	(segment
		(start 186.02198 -239.408208)
		(end 186.872118 -240.258346)
		(width 0.16002)
		(layer "In6.Cu")
		(net "M_K_CPU1_SA_DQS_DN<9>")
	)
	(segment
		(start 172.944282 -239.878362)
		(end 173.548802 -239.878362)
		(width 0.16002)
		(layer "In6.Cu")
		(net "M_K_CPU1_SA_DQS_DN<9>")
	)
	(segment
		(start 184.521856 -240.222786)
		(end 184.87009 -240.222786)
		(width 0.16002)
		(layer "In6.Cu")
		(net "M_K_CPU1_SA_DQS_DN<9>")
	)
	(segment
		(start 144.005554 -247.23344)
		(end 144.015968 -247.239536)
		(width 0.09525)
		(layer "In6.Cu")
		(net "M_K_CPU1_SA_DQS_DN<9>")
	)
	(segment
		(start 142.504922 -247.244362)
		(end 142.513304 -247.239536)
		(width 0.09525)
		(layer "In6.Cu")
		(net "M_K_CPU1_SA_DQS_DN<9>")
	)
	(segment
		(start 181.880256 -239.090962)
		(end 182.939436 -239.090962)
		(width 0.16002)
		(layer "In6.Cu")
		(net "M_K_CPU1_SA_DQS_DN<9>")
	)
	(segment
		(start 169.511726 -240.205006)
		(end 169.671746 -240.044986)
		(width 0.16002)
		(layer "In6.Cu")
		(net "M_K_CPU1_SA_DQS_DN<9>")
	)
	(segment
		(start 147.663154 -247.43918)
		(end 147.722336 -247.379998)
		(width 0.09525)
		(layer "In6.Cu")
		(net "M_K_CPU1_SA_DQS_DN<9>")
	)
	(segment
		(start 174.336202 -239.090962)
		(end 175.395382 -239.090962)
		(width 0.16002)
		(layer "In6.Cu")
		(net "M_K_CPU1_SA_DQS_DN<9>")
	)
	(segment
		(start 192.131442 -239.25911)
		(end 192.85712 -239.25911)
		(width 0.16002)
		(layer "In6.Cu")
		(net "M_K_CPU1_SA_DQS_DN<9>")
	)
	(segment
		(start 177.782982 -239.408208)
		(end 178.468274 -239.408208)
		(width 0.16002)
		(layer "In6.Cu")
		(net "M_K_CPU1_SA_DQS_DN<9>")
	)
	(segment
		(start 166.004748 -239.878362)
		(end 166.792148 -239.090962)
		(width 0.16002)
		(layer "In6.Cu")
		(net "M_K_CPU1_SA_DQS_DN<9>")
	)
	(segment
		(start 182.939436 -239.090962)
		(end 183.256682 -239.408208)
		(width 0.16002)
		(layer "In6.Cu")
		(net "M_K_CPU1_SA_DQS_DN<9>")
	)
	(segment
		(start 184.024778 -239.408208)
		(end 184.361836 -239.745266)
		(width 0.16002)
		(layer "In6.Cu")
		(net "M_K_CPU1_SA_DQS_DN<9>")
	)
	(segment
		(start 145.332958 -247.239536)
		(end 145.34769 -247.2309)
		(width 0.09525)
		(layer "In6.Cu")
		(net "M_K_CPU1_SA_DQS_DN<9>")
	)
	(segment
		(start 175.712628 -239.408208)
		(end 176.440592 -239.408208)
		(width 0.16002)
		(layer "In6.Cu")
		(net "M_K_CPU1_SA_DQS_DN<9>")
	)
	(segment
		(start 180.108352 -240.258346)
		(end 180.488336 -239.878362)
		(width 0.16002)
		(layer "In6.Cu")
		(net "M_K_CPU1_SA_DQS_DN<9>")
	)
	(segment
		(start 189.42431 -239.090962)
		(end 190.48349 -239.090962)
		(width 0.16002)
		(layer "In6.Cu")
		(net "M_K_CPU1_SA_DQS_DN<9>")
	)
	(segment
		(start 177.285904 -240.227866)
		(end 177.445924 -240.067846)
		(width 0.16002)
		(layer "In6.Cu")
		(net "M_K_CPU1_SA_DQS_DN<9>")
	)
	(segment
		(start 184.87009 -240.222786)
		(end 185.03011 -240.062766)
		(width 0.16002)
		(layer "In6.Cu")
		(net "M_K_CPU1_SA_DQS_DN<9>")
	)
	(segment
		(start 178.468274 -239.408208)
		(end 179.318412 -240.258346)
		(width 0.16002)
		(layer "In6.Cu")
		(net "M_K_CPU1_SA_DQS_DN<9>")
	)
	(segment
		(start 179.318412 -240.258346)
		(end 180.108352 -240.258346)
		(width 0.16002)
		(layer "In6.Cu")
		(net "M_K_CPU1_SA_DQS_DN<9>")
	)
	(segment
		(start 181.092856 -239.878362)
		(end 181.880256 -239.090962)
		(width 0.16002)
		(layer "In6.Cu")
		(net "M_K_CPU1_SA_DQS_DN<9>")
	)
	(segment
		(start 169.671746 -240.044986)
		(end 169.671746 -239.745266)
		(width 0.16002)
		(layer "In6.Cu")
		(net "M_K_CPU1_SA_DQS_DN<9>")
	)
	(segment
		(start 170.008804 -239.408208)
		(end 170.650408 -239.408208)
		(width 0.16002)
		(layer "In6.Cu")
		(net "M_K_CPU1_SA_DQS_DN<9>")
	)
	(segment
		(start 167.851328 -239.090962)
		(end 168.168574 -239.408208)
		(width 0.16002)
		(layer "In6.Cu")
		(net "M_K_CPU1_SA_DQS_DN<9>")
	)
	(segment
		(start 168.666414 -239.408208)
		(end 169.003472 -239.745266)
		(width 0.16002)
		(layer "In6.Cu")
		(net "M_K_CPU1_SA_DQS_DN<9>")
	)
	(segment
		(start 190.48349 -239.090962)
		(end 190.800736 -239.408208)
		(width 0.16002)
		(layer "In6.Cu")
		(net "M_K_CPU1_SA_DQS_DN<9>")
	)
	(segment
		(start 168.168574 -239.408208)
		(end 168.666414 -239.408208)
		(width 0.16002)
		(layer "In6.Cu")
		(net "M_K_CPU1_SA_DQS_DN<9>")
	)
	(segment
		(start 144.39265 -247.239536)
		(end 144.403064 -247.23344)
		(width 0.09525)
		(layer "In6.Cu")
		(net "M_K_CPU1_SA_DQS_DN<9>")
	)
	(segment
		(start 146.121628 -247.43918)
		(end 147.663154 -247.43918)
		(width 0.09525)
		(layer "In6.Cu")
		(net "M_K_CPU1_SA_DQS_DN<9>")
	)
	(segment
		(start 169.671746 -239.745266)
		(end 170.008804 -239.408208)
		(width 0.16002)
		(layer "In6.Cu")
		(net "M_K_CPU1_SA_DQS_DN<9>")
	)
	(segment
		(start 169.003472 -239.745266)
		(end 169.003472 -240.044986)
		(width 0.16002)
		(layer "In6.Cu")
		(net "M_K_CPU1_SA_DQS_DN<9>")
	)
	(segment
		(start 169.003472 -240.044986)
		(end 169.163492 -240.205006)
		(width 0.16002)
		(layer "In6.Cu")
		(net "M_K_CPU1_SA_DQS_DN<9>")
	)
	(segment
		(start 148.57349 -246.844566)
		(end 157.300168 -246.844566)
		(width 0.16002)
		(layer "In6.Cu")
		(net "M_K_CPU1_SA_DQS_DN<9>")
	)
	(segment
		(start 185.03011 -239.745266)
		(end 185.367168 -239.408208)
		(width 0.16002)
		(layer "In6.Cu")
		(net "M_K_CPU1_SA_DQS_DN<9>")
	)
	(segment
		(start 192.98412 -239.13211)
		(end 193.46418 -239.13211)
		(width 0.16002)
		(layer "In6.Cu")
		(net "M_K_CPU1_SA_DQS_DN<9>")
	)
	(segment
		(start 176.77765 -240.067846)
		(end 176.93767 -240.227866)
		(width 0.16002)
		(layer "In6.Cu")
		(net "M_K_CPU1_SA_DQS_DN<9>")
	)
	(segment
		(start 193.59118 -239.25911)
		(end 194.33032 -239.25911)
		(width 0.16002)
		(layer "In6.Cu")
		(net "M_K_CPU1_SA_DQS_DN<9>")
	)
	(segment
		(start 173.548802 -239.878362)
		(end 174.336202 -239.090962)
		(width 0.16002)
		(layer "In6.Cu")
		(net "M_K_CPU1_SA_DQS_DN<9>")
	)
	(segment
		(start 190.800736 -239.408208)
		(end 191.982344 -239.408208)
		(width 0.16002)
		(layer "In6.Cu")
		(net "M_K_CPU1_SA_DQS_DN<9>")
	)
	(segment
		(start 184.361836 -240.062766)
		(end 184.521856 -240.222786)
		(width 0.16002)
		(layer "In6.Cu")
		(net "M_K_CPU1_SA_DQS_DN<9>")
	)
	(segment
		(start 171.500546 -240.258346)
		(end 172.564298 -240.258346)
		(width 0.16002)
		(layer "In6.Cu")
		(net "M_K_CPU1_SA_DQS_DN<9>")
	)
	(segment
		(start 186.872118 -240.258346)
		(end 187.652406 -240.258346)
		(width 0.16002)
		(layer "In6.Cu")
		(net "M_K_CPU1_SA_DQS_DN<9>")
	)
	(segment
		(start 176.93767 -240.227866)
		(end 177.285904 -240.227866)
		(width 0.16002)
		(layer "In6.Cu")
		(net "M_K_CPU1_SA_DQS_DN<9>")
	)
	(segment
		(start 175.395382 -239.090962)
		(end 175.712628 -239.408208)
		(width 0.16002)
		(layer "In6.Cu")
		(net "M_K_CPU1_SA_DQS_DN<9>")
	)
	(segment
		(start 176.440592 -239.408208)
		(end 176.77765 -239.745266)
		(width 0.16002)
		(layer "In6.Cu")
		(net "M_K_CPU1_SA_DQS_DN<9>")
	)
	(segment
		(start 164.266372 -239.878362)
		(end 166.004748 -239.878362)
		(width 0.16002)
		(layer "In6.Cu")
		(net "M_K_CPU1_SA_DQS_DN<9>")
	)
	(segment
		(start 170.650408 -239.408208)
		(end 171.500546 -240.258346)
		(width 0.16002)
		(layer "In6.Cu")
		(net "M_K_CPU1_SA_DQS_DN<9>")
	)
	(segment
		(start 147.722336 -247.379998)
		(end 147.745958 -247.379998)
		(width 0.09525)
		(layer "In6.Cu")
		(net "M_K_CPU1_SA_DQS_DN<9>")
	)
	(segment
		(start 177.445924 -239.745266)
		(end 177.782982 -239.408208)
		(width 0.16002)
		(layer "In6.Cu")
		(net "M_K_CPU1_SA_DQS_DN<9>")
	)
	(arc
		(start 144.403064 -247.23344)
		(mid 144.680226 -247.16364)
		(end 144.955768 -247.239536)
		(width 0.09525)
		(layer "In6.Cu")
		(net "M_K_CPU1_SA_DQS_DN<9>")
	)
	(arc
		(start 143.08455 -247.244362)
		(mid 143.269582 -247.290276)
		(end 143.453358 -247.239536)
		(width 0.09525)
		(layer "In6.Cu")
		(net "M_K_CPU1_SA_DQS_DN<9>")
	)
	(arc
		(start 142.136114 -247.239536)
		(mid 142.319889 -247.290308)
		(end 142.504922 -247.244362)
		(width 0.09525)
		(layer "In6.Cu")
		(net "M_K_CPU1_SA_DQS_DN<9>")
	)
	(arc
		(start 143.453358 -247.239536)
		(mid 143.728647 -247.163815)
		(end 144.005554 -247.23344)
		(width 0.09525)
		(layer "In6.Cu")
		(net "M_K_CPU1_SA_DQS_DN<9>")
	)
	(arc
		(start 141.253972 -247.26646)
		(mid 141.416623 -247.28872)
		(end 141.57325 -247.239536)
		(width 0.09525)
		(layer "In6.Cu")
		(net "M_K_CPU1_SA_DQS_DN<9>")
	)
	(arc
		(start 142.513304 -247.239536)
		(mid 142.794736 -247.163781)
		(end 143.076168 -247.239536)
		(width 0.09525)
		(layer "In6.Cu")
		(net "M_K_CPU1_SA_DQS_DN<9>")
	)
	(arc
		(start 145.34769 -247.2309)
		(mid 145.622641 -247.163757)
		(end 145.895314 -247.239536)
		(width 0.09525)
		(layer "In6.Cu")
		(net "M_K_CPU1_SA_DQS_DN<9>")
	)
	(arc
		(start 145.895314 -247.239536)
		(mid 145.955718 -247.279992)
		(end 146.010376 -247.327928)
		(width 0.09525)
		(layer "In6.Cu")
		(net "M_K_CPU1_SA_DQS_DN<9>")
	)
	(arc
		(start 144.955768 -247.239536)
		(mid 145.136047 -247.290367)
		(end 145.31848 -247.247918)
		(width 0.09525)
		(layer "In6.Cu")
		(net "M_K_CPU1_SA_DQS_DN<9>")
	)
	(arc
		(start 141.57325 -247.239536)
		(mid 141.854682 -247.163781)
		(end 142.136114 -247.239536)
		(width 0.09525)
		(layer "In6.Cu")
		(net "M_K_CPU1_SA_DQS_DN<9>")
	)
	(arc
		(start 144.02435 -247.244362)
		(mid 144.209128 -247.290155)
		(end 144.39265 -247.239536)
		(width 0.09525)
		(layer "In6.Cu")
		(net "M_K_CPU1_SA_DQS_DN<9>")
	)
	(segment
		(start 140.91793 -242.320318)
		(end 141.384782 -242.05438)
		(width 0.12954)
		(layer "F.Cu")
		(net "M_K_CPU1_SA_DQS_DN<8>")
	)
	(segment
		(start 170.273472 -230.243126)
		(end 170.433492 -230.403146)
		(width 0.16002)
		(layer "In6.Cu")
		(net "M_K_CPU1_SA_DQS_DN<8>")
	)
	(segment
		(start 186.588654 -230.908352)
		(end 187.652406 -230.908352)
		(width 0.16002)
		(layer "In6.Cu")
		(net "M_K_CPU1_SA_DQS_DN<8>")
	)
	(segment
		(start 146.084798 -241.954304)
		(end 146.818604 -241.954304)
		(width 0.09525)
		(layer "In6.Cu")
		(net "M_K_CPU1_SA_DQS_DN<8>")
	)
	(segment
		(start 166.004748 -230.528368)
		(end 166.792148 -229.740968)
		(width 0.16002)
		(layer "In6.Cu")
		(net "M_K_CPU1_SA_DQS_DN<8>")
	)
	(segment
		(start 161.505646 -232.87736)
		(end 161.505646 -232.400856)
		(width 0.16002)
		(layer "In6.Cu")
		(net "M_K_CPU1_SA_DQS_DN<8>")
	)
	(segment
		(start 180.108352 -230.908352)
		(end 180.488336 -230.528368)
		(width 0.16002)
		(layer "In6.Cu")
		(net "M_K_CPU1_SA_DQS_DN<8>")
	)
	(segment
		(start 162.879278 -231.027224)
		(end 163.378134 -230.528368)
		(width 0.16002)
		(layer "In6.Cu")
		(net "M_K_CPU1_SA_DQS_DN<8>")
	)
	(segment
		(start 173.548802 -230.528368)
		(end 174.336202 -229.740968)
		(width 0.16002)
		(layer "In6.Cu")
		(net "M_K_CPU1_SA_DQS_DN<8>")
	)
	(segment
		(start 146.818604 -241.954304)
		(end 147.502372 -241.270536)
		(width 0.09525)
		(layer "In6.Cu")
		(net "M_K_CPU1_SA_DQS_DN<8>")
	)
	(segment
		(start 181.976776 -229.644448)
		(end 182.842916 -229.644448)
		(width 0.16002)
		(layer "In6.Cu")
		(net "M_K_CPU1_SA_DQS_DN<8>")
	)
	(segment
		(start 183.256682 -230.058214)
		(end 185.738516 -230.058214)
		(width 0.16002)
		(layer "In6.Cu")
		(net "M_K_CPU1_SA_DQS_DN<8>")
	)
	(segment
		(start 185.738516 -230.058214)
		(end 186.588654 -230.908352)
		(width 0.16002)
		(layer "In6.Cu")
		(net "M_K_CPU1_SA_DQS_DN<8>")
	)
	(segment
		(start 171.500546 -230.908352)
		(end 172.564298 -230.908352)
		(width 0.16002)
		(layer "In6.Cu")
		(net "M_K_CPU1_SA_DQS_DN<8>")
	)
	(segment
		(start 175.712628 -230.058214)
		(end 178.194462 -230.058214)
		(width 0.16002)
		(layer "In6.Cu")
		(net "M_K_CPU1_SA_DQS_DN<8>")
	)
	(segment
		(start 188.03239 -230.528368)
		(end 188.63691 -230.528368)
		(width 0.16002)
		(layer "In6.Cu")
		(net "M_K_CPU1_SA_DQS_DN<8>")
	)
	(segment
		(start 187.652406 -230.908352)
		(end 188.03239 -230.528368)
		(width 0.16002)
		(layer "In6.Cu")
		(net "M_K_CPU1_SA_DQS_DN<8>")
	)
	(segment
		(start 141.384782 -242.05438)
		(end 141.230858 -242.31981)
		(width 0.09525)
		(layer "In6.Cu")
		(net "M_K_CPU1_SA_DQS_DN<8>")
	)
	(segment
		(start 142.504922 -242.384326)
		(end 142.513304 -242.3795)
		(width 0.09525)
		(layer "In6.Cu")
		(net "M_K_CPU1_SA_DQS_DN<8>")
	)
	(segment
		(start 145.144744 -242.430808)
		(end 145.608294 -242.430808)
		(width 0.09525)
		(layer "In6.Cu")
		(net "M_K_CPU1_SA_DQS_DN<8>")
	)
	(segment
		(start 161.132774 -233.4514)
		(end 161.358834 -233.4514)
		(width 0.16002)
		(layer "In6.Cu")
		(net "M_K_CPU1_SA_DQS_DN<8>")
	)
	(segment
		(start 174.336202 -229.740968)
		(end 175.395382 -229.740968)
		(width 0.16002)
		(layer "In6.Cu")
		(net "M_K_CPU1_SA_DQS_DN<8>")
	)
	(segment
		(start 162.979862 -231.604312)
		(end 162.879278 -231.503728)
		(width 0.16002)
		(layer "In6.Cu")
		(net "M_K_CPU1_SA_DQS_DN<8>")
	)
	(segment
		(start 144.015968 -242.3795)
		(end 144.02435 -242.384326)
		(width 0.09525)
		(layer "In6.Cu")
		(net "M_K_CPU1_SA_DQS_DN<8>")
	)
	(segment
		(start 144.005554 -242.373404)
		(end 144.015968 -242.3795)
		(width 0.09525)
		(layer "In6.Cu")
		(net "M_K_CPU1_SA_DQS_DN<8>")
	)
	(segment
		(start 175.395382 -229.740968)
		(end 175.712628 -230.058214)
		(width 0.16002)
		(layer "In6.Cu")
		(net "M_K_CPU1_SA_DQS_DN<8>")
	)
	(segment
		(start 162.879278 -231.503728)
		(end 162.879278 -231.027224)
		(width 0.16002)
		(layer "In6.Cu")
		(net "M_K_CPU1_SA_DQS_DN<8>")
	)
	(segment
		(start 191.982344 -230.058214)
		(end 192.131442 -229.909116)
		(width 0.16002)
		(layer "In6.Cu")
		(net "M_K_CPU1_SA_DQS_DN<8>")
	)
	(segment
		(start 160.09493 -233.811572)
		(end 160.555686 -233.350816)
		(width 0.16002)
		(layer "In6.Cu")
		(net "M_K_CPU1_SA_DQS_DN<8>")
	)
	(segment
		(start 170.99534 -230.403146)
		(end 171.500546 -230.908352)
		(width 0.16002)
		(layer "In6.Cu")
		(net "M_K_CPU1_SA_DQS_DN<8>")
	)
	(segment
		(start 169.337736 -229.699566)
		(end 169.936414 -229.699566)
		(width 0.16002)
		(layer "In6.Cu")
		(net "M_K_CPU1_SA_DQS_DN<8>")
	)
	(segment
		(start 170.433492 -230.403146)
		(end 170.99534 -230.403146)
		(width 0.16002)
		(layer "In6.Cu")
		(net "M_K_CPU1_SA_DQS_DN<8>")
	)
	(segment
		(start 147.895564 -241.211354)
		(end 147.919186 -241.211354)
		(width 0.09525)
		(layer "In6.Cu")
		(net "M_K_CPU1_SA_DQS_DN<8>")
	)
	(segment
		(start 193.49974 -229.782116)
		(end 193.62674 -229.909116)
		(width 0.16002)
		(layer "In6.Cu")
		(net "M_K_CPU1_SA_DQS_DN<8>")
	)
	(segment
		(start 189.42431 -229.740968)
		(end 190.48349 -229.740968)
		(width 0.16002)
		(layer "In6.Cu")
		(net "M_K_CPU1_SA_DQS_DN<8>")
	)
	(segment
		(start 169.936414 -229.699566)
		(end 170.273472 -230.036624)
		(width 0.16002)
		(layer "In6.Cu")
		(net "M_K_CPU1_SA_DQS_DN<8>")
	)
	(segment
		(start 163.378134 -230.528368)
		(end 166.004748 -230.528368)
		(width 0.16002)
		(layer "In6.Cu")
		(net "M_K_CPU1_SA_DQS_DN<8>")
	)
	(segment
		(start 182.842916 -229.644448)
		(end 183.256682 -230.058214)
		(width 0.16002)
		(layer "In6.Cu")
		(net "M_K_CPU1_SA_DQS_DN<8>")
	)
	(segment
		(start 162.979862 -231.830372)
		(end 162.979862 -231.604312)
		(width 0.16002)
		(layer "In6.Cu")
		(net "M_K_CPU1_SA_DQS_DN<8>")
	)
	(segment
		(start 172.564298 -230.908352)
		(end 172.944282 -230.528368)
		(width 0.16002)
		(layer "In6.Cu")
		(net "M_K_CPU1_SA_DQS_DN<8>")
	)
	(segment
		(start 192.131442 -229.909116)
		(end 192.89268 -229.909116)
		(width 0.16002)
		(layer "In6.Cu")
		(net "M_K_CPU1_SA_DQS_DN<8>")
	)
	(segment
		(start 161.505646 -232.400856)
		(end 161.929318 -231.977184)
		(width 0.16002)
		(layer "In6.Cu")
		(net "M_K_CPU1_SA_DQS_DN<8>")
	)
	(segment
		(start 162.405822 -231.977184)
		(end 162.506406 -232.077768)
		(width 0.16002)
		(layer "In6.Cu")
		(net "M_K_CPU1_SA_DQS_DN<8>")
	)
	(segment
		(start 168.513506 -230.403146)
		(end 168.840658 -230.403146)
		(width 0.16002)
		(layer "In6.Cu")
		(net "M_K_CPU1_SA_DQS_DN<8>")
	)
	(segment
		(start 188.63691 -230.528368)
		(end 189.42431 -229.740968)
		(width 0.16002)
		(layer "In6.Cu")
		(net "M_K_CPU1_SA_DQS_DN<8>")
	)
	(segment
		(start 141.230858 -242.31981)
		(end 141.253972 -242.406424)
		(width 0.09525)
		(layer "In6.Cu")
		(net "M_K_CPU1_SA_DQS_DN<8>")
	)
	(segment
		(start 190.48349 -229.740968)
		(end 190.800736 -230.058214)
		(width 0.16002)
		(layer "In6.Cu")
		(net "M_K_CPU1_SA_DQS_DN<8>")
	)
	(segment
		(start 161.03219 -233.350816)
		(end 161.132774 -233.4514)
		(width 0.16002)
		(layer "In6.Cu")
		(net "M_K_CPU1_SA_DQS_DN<8>")
	)
	(segment
		(start 180.488336 -230.528368)
		(end 181.092856 -230.528368)
		(width 0.16002)
		(layer "In6.Cu")
		(net "M_K_CPU1_SA_DQS_DN<8>")
	)
	(segment
		(start 169.000678 -230.243126)
		(end 169.000678 -230.036624)
		(width 0.16002)
		(layer "In6.Cu")
		(net "M_K_CPU1_SA_DQS_DN<8>")
	)
	(segment
		(start 147.836382 -241.270536)
		(end 147.895564 -241.211354)
		(width 0.09525)
		(layer "In6.Cu")
		(net "M_K_CPU1_SA_DQS_DN<8>")
	)
	(segment
		(start 145.608294 -242.430808)
		(end 146.084798 -241.954304)
		(width 0.09525)
		(layer "In6.Cu")
		(net "M_K_CPU1_SA_DQS_DN<8>")
	)
	(segment
		(start 144.39265 -242.3795)
		(end 144.397984 -242.376452)
		(width 0.09525)
		(layer "In6.Cu")
		(net "M_K_CPU1_SA_DQS_DN<8>")
	)
	(segment
		(start 178.194462 -230.058214)
		(end 179.0446 -230.908352)
		(width 0.16002)
		(layer "In6.Cu")
		(net "M_K_CPU1_SA_DQS_DN<8>")
	)
	(segment
		(start 190.800736 -230.058214)
		(end 191.982344 -230.058214)
		(width 0.16002)
		(layer "In6.Cu")
		(net "M_K_CPU1_SA_DQS_DN<8>")
	)
	(segment
		(start 144.397984 -242.376452)
		(end 144.403064 -242.373404)
		(width 0.09525)
		(layer "In6.Cu")
		(net "M_K_CPU1_SA_DQS_DN<8>")
	)
	(segment
		(start 160.09493 -235.817664)
		(end 160.09493 -233.811572)
		(width 0.16002)
		(layer "In6.Cu")
		(net "M_K_CPU1_SA_DQS_DN<8>")
	)
	(segment
		(start 162.506406 -232.077768)
		(end 162.732466 -232.077768)
		(width 0.16002)
		(layer "In6.Cu")
		(net "M_K_CPU1_SA_DQS_DN<8>")
	)
	(segment
		(start 160.555686 -233.350816)
		(end 161.03219 -233.350816)
		(width 0.16002)
		(layer "In6.Cu")
		(net "M_K_CPU1_SA_DQS_DN<8>")
	)
	(segment
		(start 170.273472 -230.036624)
		(end 170.273472 -230.243126)
		(width 0.16002)
		(layer "In6.Cu")
		(net "M_K_CPU1_SA_DQS_DN<8>")
	)
	(segment
		(start 192.89268 -229.909116)
		(end 193.01968 -229.782116)
		(width 0.16002)
		(layer "In6.Cu")
		(net "M_K_CPU1_SA_DQS_DN<8>")
	)
	(segment
		(start 179.0446 -230.908352)
		(end 180.108352 -230.908352)
		(width 0.16002)
		(layer "In6.Cu")
		(net "M_K_CPU1_SA_DQS_DN<8>")
	)
	(segment
		(start 161.60623 -232.977944)
		(end 161.505646 -232.87736)
		(width 0.16002)
		(layer "In6.Cu")
		(net "M_K_CPU1_SA_DQS_DN<8>")
	)
	(segment
		(start 194.33032 -229.909116)
		(end 194.604132 -229.635304)
		(width 0.16002)
		(layer "In6.Cu")
		(net "M_K_CPU1_SA_DQS_DN<8>")
	)
	(segment
		(start 181.092856 -230.528368)
		(end 181.976776 -229.644448)
		(width 0.16002)
		(layer "In6.Cu")
		(net "M_K_CPU1_SA_DQS_DN<8>")
	)
	(segment
		(start 168.840658 -230.403146)
		(end 169.000678 -230.243126)
		(width 0.16002)
		(layer "In6.Cu")
		(net "M_K_CPU1_SA_DQS_DN<8>")
	)
	(segment
		(start 161.929318 -231.977184)
		(end 162.405822 -231.977184)
		(width 0.16002)
		(layer "In6.Cu")
		(net "M_K_CPU1_SA_DQS_DN<8>")
	)
	(segment
		(start 172.944282 -230.528368)
		(end 173.548802 -230.528368)
		(width 0.16002)
		(layer "In6.Cu")
		(net "M_K_CPU1_SA_DQS_DN<8>")
	)
	(segment
		(start 193.01968 -229.782116)
		(end 193.49974 -229.782116)
		(width 0.16002)
		(layer "In6.Cu")
		(net "M_K_CPU1_SA_DQS_DN<8>")
	)
	(segment
		(start 193.62674 -229.909116)
		(end 194.33032 -229.909116)
		(width 0.16002)
		(layer "In6.Cu")
		(net "M_K_CPU1_SA_DQS_DN<8>")
	)
	(segment
		(start 143.076168 -242.3795)
		(end 143.08455 -242.384326)
		(width 0.09525)
		(layer "In6.Cu")
		(net "M_K_CPU1_SA_DQS_DN<8>")
	)
	(segment
		(start 161.358834 -233.4514)
		(end 161.60623 -233.204004)
		(width 0.16002)
		(layer "In6.Cu")
		(net "M_K_CPU1_SA_DQS_DN<8>")
	)
	(segment
		(start 147.919186 -241.211354)
		(end 154.70124 -241.211354)
		(width 0.16002)
		(layer "In6.Cu")
		(net "M_K_CPU1_SA_DQS_DN<8>")
	)
	(segment
		(start 167.851328 -229.740968)
		(end 168.513506 -230.403146)
		(width 0.16002)
		(layer "In6.Cu")
		(net "M_K_CPU1_SA_DQS_DN<8>")
	)
	(segment
		(start 161.60623 -233.204004)
		(end 161.60623 -232.977944)
		(width 0.16002)
		(layer "In6.Cu")
		(net "M_K_CPU1_SA_DQS_DN<8>")
	)
	(segment
		(start 154.70124 -241.211354)
		(end 160.09493 -235.817664)
		(width 0.16002)
		(layer "In6.Cu")
		(net "M_K_CPU1_SA_DQS_DN<8>")
	)
	(segment
		(start 169.000678 -230.036624)
		(end 169.337736 -229.699566)
		(width 0.16002)
		(layer "In6.Cu")
		(net "M_K_CPU1_SA_DQS_DN<8>")
	)
	(segment
		(start 166.792148 -229.740968)
		(end 167.851328 -229.740968)
		(width 0.16002)
		(layer "In6.Cu")
		(net "M_K_CPU1_SA_DQS_DN<8>")
	)
	(segment
		(start 147.502372 -241.270536)
		(end 147.836382 -241.270536)
		(width 0.09525)
		(layer "In6.Cu")
		(net "M_K_CPU1_SA_DQS_DN<8>")
	)
	(segment
		(start 162.732466 -232.077768)
		(end 162.979862 -231.830372)
		(width 0.16002)
		(layer "In6.Cu")
		(net "M_K_CPU1_SA_DQS_DN<8>")
	)
	(arc
		(start 142.136114 -242.3795)
		(mid 142.319889 -242.430272)
		(end 142.504922 -242.384326)
		(width 0.09525)
		(layer "In6.Cu")
		(net "M_K_CPU1_SA_DQS_DN<8>")
	)
	(arc
		(start 141.253972 -242.406424)
		(mid 141.416623 -242.428684)
		(end 141.57325 -242.3795)
		(width 0.09525)
		(layer "In6.Cu")
		(net "M_K_CPU1_SA_DQS_DN<8>")
	)
	(arc
		(start 144.403064 -242.373404)
		(mid 144.680226 -242.303604)
		(end 144.955768 -242.3795)
		(width 0.09525)
		(layer "In6.Cu")
		(net "M_K_CPU1_SA_DQS_DN<8>")
	)
	(arc
		(start 143.453358 -242.3795)
		(mid 143.728647 -242.303779)
		(end 144.005554 -242.373404)
		(width 0.09525)
		(layer "In6.Cu")
		(net "M_K_CPU1_SA_DQS_DN<8>")
	)
	(arc
		(start 141.57325 -242.3795)
		(mid 141.854682 -242.303745)
		(end 142.136114 -242.3795)
		(width 0.09525)
		(layer "In6.Cu")
		(net "M_K_CPU1_SA_DQS_DN<8>")
	)
	(arc
		(start 144.02435 -242.384326)
		(mid 144.209128 -242.430119)
		(end 144.39265 -242.3795)
		(width 0.09525)
		(layer "In6.Cu")
		(net "M_K_CPU1_SA_DQS_DN<8>")
	)
	(arc
		(start 143.08455 -242.384326)
		(mid 143.269582 -242.43024)
		(end 143.453358 -242.3795)
		(width 0.09525)
		(layer "In6.Cu")
		(net "M_K_CPU1_SA_DQS_DN<8>")
	)
	(arc
		(start 144.955768 -242.3795)
		(mid 145.046856 -242.417686)
		(end 145.144744 -242.430808)
		(width 0.09525)
		(layer "In6.Cu")
		(net "M_K_CPU1_SA_DQS_DN<8>")
	)
	(arc
		(start 142.513304 -242.3795)
		(mid 142.794736 -242.303745)
		(end 143.076168 -242.3795)
		(width 0.09525)
		(layer "In6.Cu")
		(net "M_K_CPU1_SA_DQS_DN<8>")
	)
	(segment
		(start 140.91793 -237.460282)
		(end 141.384782 -237.194344)
		(width 0.12954)
		(layer "F.Cu")
		(net "M_K_CPU1_SA_DQS_DN<7>")
	)
	(segment
		(start 151.948388 -234.26039)
		(end 152.354026 -234.666028)
		(width 0.16002)
		(layer "In6.Cu")
		(net "M_K_CPU1_SA_DQS_DN<7>")
	)
	(segment
		(start 152.354026 -234.666028)
		(end 152.580086 -234.666028)
		(width 0.16002)
		(layer "In6.Cu")
		(net "M_K_CPU1_SA_DQS_DN<7>")
	)
	(segment
		(start 153.727658 -233.292396)
		(end 153.953718 -233.292396)
		(width 0.16002)
		(layer "In6.Cu")
		(net "M_K_CPU1_SA_DQS_DN<7>")
	)
	(segment
		(start 153.32202 -232.886758)
		(end 153.727658 -233.292396)
		(width 0.16002)
		(layer "In6.Cu")
		(net "M_K_CPU1_SA_DQS_DN<7>")
	)
	(segment
		(start 161.98215 -223.750124)
		(end 161.98215 -223.069404)
		(width 0.16002)
		(layer "In6.Cu")
		(net "M_K_CPU1_SA_DQS_DN<7>")
	)
	(segment
		(start 152.421844 -233.31043)
		(end 152.845516 -232.886758)
		(width 0.16002)
		(layer "In6.Cu")
		(net "M_K_CPU1_SA_DQS_DN<7>")
	)
	(segment
		(start 173.548802 -221.178374)
		(end 174.336202 -220.390974)
		(width 0.16002)
		(layer "In6.Cu")
		(net "M_K_CPU1_SA_DQS_DN<7>")
	)
	(segment
		(start 142.504922 -237.52429)
		(end 142.513304 -237.519464)
		(width 0.09525)
		(layer "In6.Cu")
		(net "M_K_CPU1_SA_DQS_DN<7>")
	)
	(segment
		(start 144.015968 -237.519464)
		(end 144.02435 -237.52429)
		(width 0.09525)
		(layer "In6.Cu")
		(net "M_K_CPU1_SA_DQS_DN<7>")
	)
	(segment
		(start 170.650408 -220.70822)
		(end 171.500292 -221.558104)
		(width 0.16002)
		(layer "In6.Cu")
		(net "M_K_CPU1_SA_DQS_DN<7>")
	)
	(segment
		(start 143.076168 -237.519464)
		(end 143.08455 -237.52429)
		(width 0.09525)
		(layer "In6.Cu")
		(net "M_K_CPU1_SA_DQS_DN<7>")
	)
	(segment
		(start 166.792148 -220.390974)
		(end 167.851328 -220.390974)
		(width 0.16002)
		(layer "In6.Cu")
		(net "M_K_CPU1_SA_DQS_DN<7>")
	)
	(segment
		(start 147.517104 -235.631736)
		(end 147.836382 -235.631736)
		(width 0.09525)
		(layer "In6.Cu")
		(net "M_K_CPU1_SA_DQS_DN<7>")
	)
	(segment
		(start 188.03239 -221.178374)
		(end 188.63691 -221.178374)
		(width 0.16002)
		(layer "In6.Cu")
		(net "M_K_CPU1_SA_DQS_DN<7>")
	)
	(segment
		(start 180.488336 -221.178374)
		(end 181.092856 -221.178374)
		(width 0.16002)
		(layer "In6.Cu")
		(net "M_K_CPU1_SA_DQS_DN<7>")
	)
	(segment
		(start 181.092856 -221.178374)
		(end 181.880256 -220.390974)
		(width 0.16002)
		(layer "In6.Cu")
		(net "M_K_CPU1_SA_DQS_DN<7>")
	)
	(segment
		(start 147.919186 -235.572554)
		(end 150.15972 -235.572554)
		(width 0.16002)
		(layer "In6.Cu")
		(net "M_K_CPU1_SA_DQS_DN<7>")
	)
	(segment
		(start 193.58102 -220.559122)
		(end 194.33032 -220.559122)
		(width 0.16002)
		(layer "In6.Cu")
		(net "M_K_CPU1_SA_DQS_DN<7>")
	)
	(segment
		(start 171.500292 -221.558104)
		(end 172.564552 -221.558104)
		(width 0.16002)
		(layer "In6.Cu")
		(net "M_K_CPU1_SA_DQS_DN<7>")
	)
	(segment
		(start 166.004748 -221.178374)
		(end 166.792148 -220.390974)
		(width 0.16002)
		(layer "In6.Cu")
		(net "M_K_CPU1_SA_DQS_DN<7>")
	)
	(segment
		(start 153.953718 -233.292396)
		(end 154.201114 -233.045)
		(width 0.16002)
		(layer "In6.Cu")
		(net "M_K_CPU1_SA_DQS_DN<7>")
	)
	(segment
		(start 192.84696 -220.559122)
		(end 192.97396 -220.432122)
		(width 0.16002)
		(layer "In6.Cu")
		(net "M_K_CPU1_SA_DQS_DN<7>")
	)
	(segment
		(start 182.939436 -220.390974)
		(end 183.256682 -220.70822)
		(width 0.16002)
		(layer "In6.Cu")
		(net "M_K_CPU1_SA_DQS_DN<7>")
	)
	(segment
		(start 190.48349 -220.390974)
		(end 190.800736 -220.70822)
		(width 0.16002)
		(layer "In6.Cu")
		(net "M_K_CPU1_SA_DQS_DN<7>")
	)
	(segment
		(start 188.63691 -221.178374)
		(end 189.42431 -220.390974)
		(width 0.16002)
		(layer "In6.Cu")
		(net "M_K_CPU1_SA_DQS_DN<7>")
	)
	(segment
		(start 190.800736 -220.70822)
		(end 191.982344 -220.70822)
		(width 0.16002)
		(layer "In6.Cu")
		(net "M_K_CPU1_SA_DQS_DN<7>")
	)
	(segment
		(start 152.421844 -233.786934)
		(end 152.421844 -233.31043)
		(width 0.16002)
		(layer "In6.Cu")
		(net "M_K_CPU1_SA_DQS_DN<7>")
	)
	(segment
		(start 187.65266 -221.558104)
		(end 188.03239 -221.178374)
		(width 0.16002)
		(layer "In6.Cu")
		(net "M_K_CPU1_SA_DQS_DN<7>")
	)
	(segment
		(start 172.944282 -221.178374)
		(end 173.548802 -221.178374)
		(width 0.16002)
		(layer "In6.Cu")
		(net "M_K_CPU1_SA_DQS_DN<7>")
	)
	(segment
		(start 175.395382 -220.390974)
		(end 175.712628 -220.70822)
		(width 0.16002)
		(layer "In6.Cu")
		(net "M_K_CPU1_SA_DQS_DN<7>")
	)
	(segment
		(start 152.580086 -234.666028)
		(end 152.827482 -234.418632)
		(width 0.16002)
		(layer "In6.Cu")
		(net "M_K_CPU1_SA_DQS_DN<7>")
	)
	(segment
		(start 146.526758 -236.07776)
		(end 147.07108 -236.07776)
		(width 0.09525)
		(layer "In6.Cu")
		(net "M_K_CPU1_SA_DQS_DN<7>")
	)
	(segment
		(start 181.880256 -220.390974)
		(end 182.939436 -220.390974)
		(width 0.16002)
		(layer "In6.Cu")
		(net "M_K_CPU1_SA_DQS_DN<7>")
	)
	(segment
		(start 147.895564 -235.572554)
		(end 147.919186 -235.572554)
		(width 0.09525)
		(layer "In6.Cu")
		(net "M_K_CPU1_SA_DQS_DN<7>")
	)
	(segment
		(start 153.795476 -231.936798)
		(end 161.98215 -223.750124)
		(width 0.16002)
		(layer "In6.Cu")
		(net "M_K_CPU1_SA_DQS_DN<7>")
	)
	(segment
		(start 147.836382 -235.631736)
		(end 147.895564 -235.572554)
		(width 0.09525)
		(layer "In6.Cu")
		(net "M_K_CPU1_SA_DQS_DN<7>")
	)
	(segment
		(start 175.712628 -220.70822)
		(end 178.194462 -220.70822)
		(width 0.16002)
		(layer "In6.Cu")
		(net "M_K_CPU1_SA_DQS_DN<7>")
	)
	(segment
		(start 186.5884 -221.558104)
		(end 187.65266 -221.558104)
		(width 0.16002)
		(layer "In6.Cu")
		(net "M_K_CPU1_SA_DQS_DN<7>")
	)
	(segment
		(start 150.15972 -235.572554)
		(end 151.471884 -234.26039)
		(width 0.16002)
		(layer "In6.Cu")
		(net "M_K_CPU1_SA_DQS_DN<7>")
	)
	(segment
		(start 151.471884 -234.26039)
		(end 151.948388 -234.26039)
		(width 0.16002)
		(layer "In6.Cu")
		(net "M_K_CPU1_SA_DQS_DN<7>")
	)
	(segment
		(start 193.45402 -220.432122)
		(end 193.58102 -220.559122)
		(width 0.16002)
		(layer "In6.Cu")
		(net "M_K_CPU1_SA_DQS_DN<7>")
	)
	(segment
		(start 146.166078 -236.716316)
		(end 146.166078 -236.43844)
		(width 0.09525)
		(layer "In6.Cu")
		(net "M_K_CPU1_SA_DQS_DN<7>")
	)
	(segment
		(start 167.851328 -220.390974)
		(end 168.168574 -220.70822)
		(width 0.16002)
		(layer "In6.Cu")
		(net "M_K_CPU1_SA_DQS_DN<7>")
	)
	(segment
		(start 145.423382 -237.459012)
		(end 146.166078 -236.716316)
		(width 0.09525)
		(layer "In6.Cu")
		(net "M_K_CPU1_SA_DQS_DN<7>")
	)
	(segment
		(start 192.131442 -220.559122)
		(end 192.84696 -220.559122)
		(width 0.16002)
		(layer "In6.Cu")
		(net "M_K_CPU1_SA_DQS_DN<7>")
	)
	(segment
		(start 152.845516 -232.886758)
		(end 153.32202 -232.886758)
		(width 0.16002)
		(layer "In6.Cu")
		(net "M_K_CPU1_SA_DQS_DN<7>")
	)
	(segment
		(start 174.336202 -220.390974)
		(end 175.395382 -220.390974)
		(width 0.16002)
		(layer "In6.Cu")
		(net "M_K_CPU1_SA_DQS_DN<7>")
	)
	(segment
		(start 152.827482 -234.418632)
		(end 152.827482 -234.192572)
		(width 0.16002)
		(layer "In6.Cu")
		(net "M_K_CPU1_SA_DQS_DN<7>")
	)
	(segment
		(start 144.39265 -237.519464)
		(end 144.393158 -237.519464)
		(width 0.09525)
		(layer "In6.Cu")
		(net "M_K_CPU1_SA_DQS_DN<7>")
	)
	(segment
		(start 192.97396 -220.432122)
		(end 193.45402 -220.432122)
		(width 0.16002)
		(layer "In6.Cu")
		(net "M_K_CPU1_SA_DQS_DN<7>")
	)
	(segment
		(start 194.33032 -220.559122)
		(end 194.604132 -220.28531)
		(width 0.16002)
		(layer "In6.Cu")
		(net "M_K_CPU1_SA_DQS_DN<7>")
	)
	(segment
		(start 152.827482 -234.192572)
		(end 152.421844 -233.786934)
		(width 0.16002)
		(layer "In6.Cu")
		(net "M_K_CPU1_SA_DQS_DN<7>")
	)
	(segment
		(start 191.982344 -220.70822)
		(end 192.131442 -220.559122)
		(width 0.16002)
		(layer "In6.Cu")
		(net "M_K_CPU1_SA_DQS_DN<7>")
	)
	(segment
		(start 161.98215 -223.069404)
		(end 163.87318 -221.178374)
		(width 0.16002)
		(layer "In6.Cu")
		(net "M_K_CPU1_SA_DQS_DN<7>")
	)
	(segment
		(start 185.738516 -220.70822)
		(end 186.5884 -221.558104)
		(width 0.16002)
		(layer "In6.Cu")
		(net "M_K_CPU1_SA_DQS_DN<7>")
	)
	(segment
		(start 172.564552 -221.558104)
		(end 172.944282 -221.178374)
		(width 0.16002)
		(layer "In6.Cu")
		(net "M_K_CPU1_SA_DQS_DN<7>")
	)
	(segment
		(start 141.230858 -237.459774)
		(end 141.253972 -237.546388)
		(width 0.09525)
		(layer "In6.Cu")
		(net "M_K_CPU1_SA_DQS_DN<7>")
	)
	(segment
		(start 146.166078 -236.43844)
		(end 146.526758 -236.07776)
		(width 0.09525)
		(layer "In6.Cu")
		(net "M_K_CPU1_SA_DQS_DN<7>")
	)
	(segment
		(start 144.393158 -237.519464)
		(end 144.408144 -237.511336)
		(width 0.09525)
		(layer "In6.Cu")
		(net "M_K_CPU1_SA_DQS_DN<7>")
	)
	(segment
		(start 163.87318 -221.178374)
		(end 166.004748 -221.178374)
		(width 0.16002)
		(layer "In6.Cu")
		(net "M_K_CPU1_SA_DQS_DN<7>")
	)
	(segment
		(start 189.42431 -220.390974)
		(end 190.48349 -220.390974)
		(width 0.16002)
		(layer "In6.Cu")
		(net "M_K_CPU1_SA_DQS_DN<7>")
	)
	(segment
		(start 180.108606 -221.558104)
		(end 180.488336 -221.178374)
		(width 0.16002)
		(layer "In6.Cu")
		(net "M_K_CPU1_SA_DQS_DN<7>")
	)
	(segment
		(start 154.201114 -232.81894)
		(end 153.795476 -232.413302)
		(width 0.16002)
		(layer "In6.Cu")
		(net "M_K_CPU1_SA_DQS_DN<7>")
	)
	(segment
		(start 168.168574 -220.70822)
		(end 170.650408 -220.70822)
		(width 0.16002)
		(layer "In6.Cu")
		(net "M_K_CPU1_SA_DQS_DN<7>")
	)
	(segment
		(start 183.256682 -220.70822)
		(end 185.738516 -220.70822)
		(width 0.16002)
		(layer "In6.Cu")
		(net "M_K_CPU1_SA_DQS_DN<7>")
	)
	(segment
		(start 154.201114 -233.045)
		(end 154.201114 -232.81894)
		(width 0.16002)
		(layer "In6.Cu")
		(net "M_K_CPU1_SA_DQS_DN<7>")
	)
	(segment
		(start 141.384782 -237.194344)
		(end 141.230858 -237.459774)
		(width 0.09525)
		(layer "In6.Cu")
		(net "M_K_CPU1_SA_DQS_DN<7>")
	)
	(segment
		(start 179.044346 -221.558104)
		(end 180.108606 -221.558104)
		(width 0.16002)
		(layer "In6.Cu")
		(net "M_K_CPU1_SA_DQS_DN<7>")
	)
	(segment
		(start 144.005554 -237.513368)
		(end 144.015968 -237.519464)
		(width 0.09525)
		(layer "In6.Cu")
		(net "M_K_CPU1_SA_DQS_DN<7>")
	)
	(segment
		(start 153.795476 -232.413302)
		(end 153.795476 -231.936798)
		(width 0.16002)
		(layer "In6.Cu")
		(net "M_K_CPU1_SA_DQS_DN<7>")
	)
	(segment
		(start 147.07108 -236.07776)
		(end 147.517104 -235.631736)
		(width 0.09525)
		(layer "In6.Cu")
		(net "M_K_CPU1_SA_DQS_DN<7>")
	)
	(segment
		(start 178.194462 -220.70822)
		(end 179.044346 -221.558104)
		(width 0.16002)
		(layer "In6.Cu")
		(net "M_K_CPU1_SA_DQS_DN<7>")
	)
	(arc
		(start 144.408144 -237.511336)
		(mid 144.682921 -237.444129)
		(end 144.955514 -237.519718)
		(width 0.09525)
		(layer "In6.Cu")
		(net "M_K_CPU1_SA_DQS_DN<7>")
	)
	(arc
		(start 143.453358 -237.519464)
		(mid 143.728647 -237.443743)
		(end 144.005554 -237.513368)
		(width 0.09525)
		(layer "In6.Cu")
		(net "M_K_CPU1_SA_DQS_DN<7>")
	)
	(arc
		(start 144.955514 -237.519718)
		(mid 145.199798 -237.568978)
		(end 145.423382 -237.459012)
		(width 0.09525)
		(layer "In6.Cu")
		(net "M_K_CPU1_SA_DQS_DN<7>")
	)
	(arc
		(start 141.57325 -237.519464)
		(mid 141.854682 -237.443709)
		(end 142.136114 -237.519464)
		(width 0.09525)
		(layer "In6.Cu")
		(net "M_K_CPU1_SA_DQS_DN<7>")
	)
	(arc
		(start 141.253972 -237.546388)
		(mid 141.416623 -237.568648)
		(end 141.57325 -237.519464)
		(width 0.09525)
		(layer "In6.Cu")
		(net "M_K_CPU1_SA_DQS_DN<7>")
	)
	(arc
		(start 144.02435 -237.52429)
		(mid 144.209128 -237.570083)
		(end 144.39265 -237.519464)
		(width 0.09525)
		(layer "In6.Cu")
		(net "M_K_CPU1_SA_DQS_DN<7>")
	)
	(arc
		(start 142.513304 -237.519464)
		(mid 142.794736 -237.443709)
		(end 143.076168 -237.519464)
		(width 0.09525)
		(layer "In6.Cu")
		(net "M_K_CPU1_SA_DQS_DN<7>")
	)
	(arc
		(start 142.136114 -237.519464)
		(mid 142.319889 -237.570236)
		(end 142.504922 -237.52429)
		(width 0.09525)
		(layer "In6.Cu")
		(net "M_K_CPU1_SA_DQS_DN<7>")
	)
	(arc
		(start 143.08455 -237.52429)
		(mid 143.269582 -237.570204)
		(end 143.453358 -237.519464)
		(width 0.09525)
		(layer "In6.Cu")
		(net "M_K_CPU1_SA_DQS_DN<7>")
	)
	(segment
		(start 140.91793 -232.600246)
		(end 141.384782 -232.334308)
		(width 0.12954)
		(layer "F.Cu")
		(net "M_K_CPU1_SA_DQS_DN<6>")
	)
	(segment
		(start 180.108606 -212.20811)
		(end 180.488336 -211.82838)
		(width 0.16002)
		(layer "In6.Cu")
		(net "M_K_CPU1_SA_DQS_DN<6>")
	)
	(segment
		(start 185.738516 -211.358226)
		(end 186.5884 -212.20811)
		(width 0.16002)
		(layer "In6.Cu")
		(net "M_K_CPU1_SA_DQS_DN<6>")
	)
	(segment
		(start 161.124646 -214.924894)
		(end 161.126424 -214.926672)
		(width 0.16002)
		(layer "In6.Cu")
		(net "M_K_CPU1_SA_DQS_DN<6>")
	)
	(segment
		(start 187.65266 -212.20811)
		(end 188.03239 -211.82838)
		(width 0.16002)
		(layer "In6.Cu")
		(net "M_K_CPU1_SA_DQS_DN<6>")
	)
	(segment
		(start 188.63691 -211.82838)
		(end 189.42431 -211.04098)
		(width 0.16002)
		(layer "In6.Cu")
		(net "M_K_CPU1_SA_DQS_DN<6>")
	)
	(segment
		(start 175.395382 -211.04098)
		(end 175.712628 -211.358226)
		(width 0.16002)
		(layer "In6.Cu")
		(net "M_K_CPU1_SA_DQS_DN<6>")
	)
	(segment
		(start 161.59734 -213.975696)
		(end 162.021774 -213.551262)
		(width 0.16002)
		(layer "In6.Cu")
		(net "M_K_CPU1_SA_DQS_DN<6>")
	)
	(segment
		(start 145.410428 -232.599738)
		(end 145.410428 -232.600246)
		(width 0.09525)
		(layer "In6.Cu")
		(net "M_K_CPU1_SA_DQS_DN<6>")
	)
	(segment
		(start 147.705318 -230.061262)
		(end 155.803346 -221.963234)
		(width 0.16002)
		(layer "In6.Cu")
		(net "M_K_CPU1_SA_DQS_DN<6>")
	)
	(segment
		(start 190.800736 -211.358226)
		(end 191.982344 -211.358226)
		(width 0.16002)
		(layer "In6.Cu")
		(net "M_K_CPU1_SA_DQS_DN<6>")
	)
	(segment
		(start 156.10459 -220.174566)
		(end 156.10459 -219.948506)
		(width 0.16002)
		(layer "In6.Cu")
		(net "M_K_CPU1_SA_DQS_DN<6>")
	)
	(segment
		(start 160.223708 -215.825832)
		(end 160.223708 -215.349328)
		(width 0.16002)
		(layer "In6.Cu")
		(net "M_K_CPU1_SA_DQS_DN<6>")
	)
	(segment
		(start 158.850076 -217.199464)
		(end 158.850076 -216.72296)
		(width 0.16002)
		(layer "In6.Cu")
		(net "M_K_CPU1_SA_DQS_DN<6>")
	)
	(segment
		(start 172.944282 -211.82838)
		(end 173.548802 -211.82838)
		(width 0.16002)
		(layer "In6.Cu")
		(net "M_K_CPU1_SA_DQS_DN<6>")
	)
	(segment
		(start 161.599118 -214.680038)
		(end 161.599118 -214.453978)
		(width 0.16002)
		(layer "In6.Cu")
		(net "M_K_CPU1_SA_DQS_DN<6>")
	)
	(segment
		(start 162.97275 -213.306406)
		(end 162.97275 -213.080346)
		(width 0.16002)
		(layer "In6.Cu")
		(net "M_K_CPU1_SA_DQS_DN<6>")
	)
	(segment
		(start 158.60522 -217.673936)
		(end 158.851854 -217.427302)
		(width 0.16002)
		(layer "In6.Cu")
		(net "M_K_CPU1_SA_DQS_DN<6>")
	)
	(segment
		(start 161.126424 -214.926672)
		(end 161.352484 -214.926672)
		(width 0.16002)
		(layer "In6.Cu")
		(net "M_K_CPU1_SA_DQS_DN<6>")
	)
	(segment
		(start 157.231588 -219.047568)
		(end 157.478222 -218.800934)
		(width 0.16002)
		(layer "In6.Cu")
		(net "M_K_CPU1_SA_DQS_DN<6>")
	)
	(segment
		(start 179.044346 -212.20811)
		(end 180.108606 -212.20811)
		(width 0.16002)
		(layer "In6.Cu")
		(net "M_K_CPU1_SA_DQS_DN<6>")
	)
	(segment
		(start 180.488336 -211.82838)
		(end 181.092856 -211.82838)
		(width 0.16002)
		(layer "In6.Cu")
		(net "M_K_CPU1_SA_DQS_DN<6>")
	)
	(segment
		(start 147.38985 -230.460042)
		(end 147.688554 -230.161338)
		(width 0.09525)
		(layer "In6.Cu")
		(net "M_K_CPU1_SA_DQS_DN<6>")
	)
	(segment
		(start 162.970972 -213.078568)
		(end 162.970972 -212.602064)
		(width 0.16002)
		(layer "In6.Cu")
		(net "M_K_CPU1_SA_DQS_DN<6>")
	)
	(segment
		(start 162.97275 -213.080346)
		(end 162.970972 -213.078568)
		(width 0.16002)
		(layer "In6.Cu")
		(net "M_K_CPU1_SA_DQS_DN<6>")
	)
	(segment
		(start 160.648142 -214.924894)
		(end 161.124646 -214.924894)
		(width 0.16002)
		(layer "In6.Cu")
		(net "M_K_CPU1_SA_DQS_DN<6>")
	)
	(segment
		(start 162.726116 -213.55304)
		(end 162.97275 -213.306406)
		(width 0.16002)
		(layer "In6.Cu")
		(net "M_K_CPU1_SA_DQS_DN<6>")
	)
	(segment
		(start 145.410428 -232.600246)
		(end 145.998438 -232.012236)
		(width 0.09525)
		(layer "In6.Cu")
		(net "M_K_CPU1_SA_DQS_DN<6>")
	)
	(segment
		(start 186.5884 -212.20811)
		(end 187.65266 -212.20811)
		(width 0.16002)
		(layer "In6.Cu")
		(net "M_K_CPU1_SA_DQS_DN<6>")
	)
	(segment
		(start 183.256682 -211.358226)
		(end 185.738516 -211.358226)
		(width 0.16002)
		(layer "In6.Cu")
		(net "M_K_CPU1_SA_DQS_DN<6>")
	)
	(segment
		(start 143.076168 -232.659428)
		(end 143.08455 -232.664254)
		(width 0.09525)
		(layer "In6.Cu")
		(net "M_K_CPU1_SA_DQS_DN<6>")
	)
	(segment
		(start 194.33032 -211.209128)
		(end 194.604132 -210.935316)
		(width 0.16002)
		(layer "In6.Cu")
		(net "M_K_CPU1_SA_DQS_DN<6>")
	)
	(segment
		(start 173.548802 -211.82838)
		(end 174.336202 -211.04098)
		(width 0.16002)
		(layer "In6.Cu")
		(net "M_K_CPU1_SA_DQS_DN<6>")
	)
	(segment
		(start 190.48349 -211.04098)
		(end 190.800736 -211.358226)
		(width 0.16002)
		(layer "In6.Cu")
		(net "M_K_CPU1_SA_DQS_DN<6>")
	)
	(segment
		(start 156.102812 -219.946728)
		(end 156.102812 -219.470224)
		(width 0.16002)
		(layer "In6.Cu")
		(net "M_K_CPU1_SA_DQS_DN<6>")
	)
	(segment
		(start 166.792148 -211.04098)
		(end 167.851328 -211.04098)
		(width 0.16002)
		(layer "In6.Cu")
		(net "M_K_CPU1_SA_DQS_DN<6>")
	)
	(segment
		(start 166.004748 -211.82838)
		(end 166.792148 -211.04098)
		(width 0.16002)
		(layer "In6.Cu")
		(net "M_K_CPU1_SA_DQS_DN<6>")
	)
	(segment
		(start 162.500056 -213.55304)
		(end 162.726116 -213.55304)
		(width 0.16002)
		(layer "In6.Cu")
		(net "M_K_CPU1_SA_DQS_DN<6>")
	)
	(segment
		(start 182.847742 -210.949286)
		(end 183.256682 -211.358226)
		(width 0.16002)
		(layer "In6.Cu")
		(net "M_K_CPU1_SA_DQS_DN<6>")
	)
	(segment
		(start 157.478222 -218.800934)
		(end 157.478222 -218.574874)
		(width 0.16002)
		(layer "In6.Cu")
		(net "M_K_CPU1_SA_DQS_DN<6>")
	)
	(segment
		(start 142.504922 -232.664254)
		(end 142.513304 -232.659428)
		(width 0.09525)
		(layer "In6.Cu")
		(net "M_K_CPU1_SA_DQS_DN<6>")
	)
	(segment
		(start 178.194462 -211.358226)
		(end 179.044346 -212.20811)
		(width 0.16002)
		(layer "In6.Cu")
		(net "M_K_CPU1_SA_DQS_DN<6>")
	)
	(segment
		(start 158.851854 -217.427302)
		(end 158.851854 -217.201242)
		(width 0.16002)
		(layer "In6.Cu")
		(net "M_K_CPU1_SA_DQS_DN<6>")
	)
	(segment
		(start 181.97195 -210.949286)
		(end 182.847742 -210.949286)
		(width 0.16002)
		(layer "In6.Cu")
		(net "M_K_CPU1_SA_DQS_DN<6>")
	)
	(segment
		(start 145.32102 -232.666286)
		(end 145.332958 -232.659428)
		(width 0.09525)
		(layer "In6.Cu")
		(net "M_K_CPU1_SA_DQS_DN<6>")
	)
	(segment
		(start 156.102812 -219.470224)
		(end 156.527246 -219.04579)
		(width 0.16002)
		(layer "In6.Cu")
		(net "M_K_CPU1_SA_DQS_DN<6>")
	)
	(segment
		(start 158.850076 -216.72296)
		(end 159.27451 -216.298526)
		(width 0.16002)
		(layer "In6.Cu")
		(net "M_K_CPU1_SA_DQS_DN<6>")
	)
	(segment
		(start 164.099748 -212.179408)
		(end 164.450776 -211.82838)
		(width 0.16002)
		(layer "In6.Cu")
		(net "M_K_CPU1_SA_DQS_DN<6>")
	)
	(segment
		(start 167.851328 -211.04098)
		(end 168.168574 -211.358226)
		(width 0.16002)
		(layer "In6.Cu")
		(net "M_K_CPU1_SA_DQS_DN<6>")
	)
	(segment
		(start 159.752792 -216.300304)
		(end 159.978852 -216.300304)
		(width 0.16002)
		(layer "In6.Cu")
		(net "M_K_CPU1_SA_DQS_DN<6>")
	)
	(segment
		(start 141.230858 -232.599738)
		(end 141.253972 -232.686352)
		(width 0.09525)
		(layer "In6.Cu")
		(net "M_K_CPU1_SA_DQS_DN<6>")
	)
	(segment
		(start 158.851854 -217.201242)
		(end 158.850076 -217.199464)
		(width 0.16002)
		(layer "In6.Cu")
		(net "M_K_CPU1_SA_DQS_DN<6>")
	)
	(segment
		(start 162.970972 -212.602064)
		(end 163.395406 -212.17763)
		(width 0.16002)
		(layer "In6.Cu")
		(net "M_K_CPU1_SA_DQS_DN<6>")
	)
	(segment
		(start 188.03239 -211.82838)
		(end 188.63691 -211.82838)
		(width 0.16002)
		(layer "In6.Cu")
		(net "M_K_CPU1_SA_DQS_DN<6>")
	)
	(segment
		(start 158.37916 -217.673936)
		(end 158.60522 -217.673936)
		(width 0.16002)
		(layer "In6.Cu")
		(net "M_K_CPU1_SA_DQS_DN<6>")
	)
	(segment
		(start 145.998438 -231.449372)
		(end 146.987768 -230.460042)
		(width 0.09525)
		(layer "In6.Cu")
		(net "M_K_CPU1_SA_DQS_DN<6>")
	)
	(segment
		(start 157.005528 -219.047568)
		(end 157.231588 -219.047568)
		(width 0.16002)
		(layer "In6.Cu")
		(net "M_K_CPU1_SA_DQS_DN<6>")
	)
	(segment
		(start 157.476444 -218.096592)
		(end 157.900878 -217.672158)
		(width 0.16002)
		(layer "In6.Cu")
		(net "M_K_CPU1_SA_DQS_DN<6>")
	)
	(segment
		(start 160.225486 -215.82761)
		(end 160.223708 -215.825832)
		(width 0.16002)
		(layer "In6.Cu")
		(net "M_K_CPU1_SA_DQS_DN<6>")
	)
	(segment
		(start 147.688554 -230.161338)
		(end 147.688554 -230.078026)
		(width 0.09525)
		(layer "In6.Cu")
		(net "M_K_CPU1_SA_DQS_DN<6>")
	)
	(segment
		(start 146.987768 -230.460042)
		(end 147.38985 -230.460042)
		(width 0.09525)
		(layer "In6.Cu")
		(net "M_K_CPU1_SA_DQS_DN<6>")
	)
	(segment
		(start 144.005554 -232.653332)
		(end 144.015968 -232.659428)
		(width 0.09525)
		(layer "In6.Cu")
		(net "M_K_CPU1_SA_DQS_DN<6>")
	)
	(segment
		(start 159.27451 -216.298526)
		(end 159.751014 -216.298526)
		(width 0.16002)
		(layer "In6.Cu")
		(net "M_K_CPU1_SA_DQS_DN<6>")
	)
	(segment
		(start 170.650408 -211.358226)
		(end 171.500292 -212.20811)
		(width 0.16002)
		(layer "In6.Cu")
		(net "M_K_CPU1_SA_DQS_DN<6>")
	)
	(segment
		(start 157.900878 -217.672158)
		(end 158.377382 -217.672158)
		(width 0.16002)
		(layer "In6.Cu")
		(net "M_K_CPU1_SA_DQS_DN<6>")
	)
	(segment
		(start 163.395406 -212.17763)
		(end 163.87191 -212.17763)
		(width 0.16002)
		(layer "In6.Cu")
		(net "M_K_CPU1_SA_DQS_DN<6>")
	)
	(segment
		(start 162.021774 -213.551262)
		(end 162.498278 -213.551262)
		(width 0.16002)
		(layer "In6.Cu")
		(net "M_K_CPU1_SA_DQS_DN<6>")
	)
	(segment
		(start 193.61658 -211.209128)
		(end 194.33032 -211.209128)
		(width 0.16002)
		(layer "In6.Cu")
		(net "M_K_CPU1_SA_DQS_DN<6>")
	)
	(segment
		(start 192.88252 -211.209128)
		(end 192.989962 -211.101686)
		(width 0.16002)
		(layer "In6.Cu")
		(net "M_K_CPU1_SA_DQS_DN<6>")
	)
	(segment
		(start 144.392904 -232.659428)
		(end 144.403318 -232.653332)
		(width 0.09525)
		(layer "In6.Cu")
		(net "M_K_CPU1_SA_DQS_DN<6>")
	)
	(segment
		(start 156.10459 -219.948506)
		(end 156.102812 -219.946728)
		(width 0.16002)
		(layer "In6.Cu")
		(net "M_K_CPU1_SA_DQS_DN<6>")
	)
	(segment
		(start 161.59734 -214.4522)
		(end 161.59734 -213.975696)
		(width 0.16002)
		(layer "In6.Cu")
		(net "M_K_CPU1_SA_DQS_DN<6>")
	)
	(segment
		(start 160.225486 -216.05367)
		(end 160.225486 -215.82761)
		(width 0.16002)
		(layer "In6.Cu")
		(net "M_K_CPU1_SA_DQS_DN<6>")
	)
	(segment
		(start 193.509138 -211.101686)
		(end 193.61658 -211.209128)
		(width 0.16002)
		(layer "In6.Cu")
		(net "M_K_CPU1_SA_DQS_DN<6>")
	)
	(segment
		(start 164.450776 -211.82838)
		(end 166.004748 -211.82838)
		(width 0.16002)
		(layer "In6.Cu")
		(net "M_K_CPU1_SA_DQS_DN<6>")
	)
	(segment
		(start 160.223708 -215.349328)
		(end 160.648142 -214.924894)
		(width 0.16002)
		(layer "In6.Cu")
		(net "M_K_CPU1_SA_DQS_DN<6>")
	)
	(segment
		(start 171.500292 -212.20811)
		(end 172.564552 -212.20811)
		(width 0.16002)
		(layer "In6.Cu")
		(net "M_K_CPU1_SA_DQS_DN<6>")
	)
	(segment
		(start 155.803346 -221.963234)
		(end 155.803346 -220.47581)
		(width 0.16002)
		(layer "In6.Cu")
		(net "M_K_CPU1_SA_DQS_DN<6>")
	)
	(segment
		(start 145.998438 -232.012236)
		(end 145.998438 -231.449372)
		(width 0.09525)
		(layer "In6.Cu")
		(net "M_K_CPU1_SA_DQS_DN<6>")
	)
	(segment
		(start 181.092856 -211.82838)
		(end 181.97195 -210.949286)
		(width 0.16002)
		(layer "In6.Cu")
		(net "M_K_CPU1_SA_DQS_DN<6>")
	)
	(segment
		(start 159.978852 -216.300304)
		(end 160.225486 -216.05367)
		(width 0.16002)
		(layer "In6.Cu")
		(net "M_K_CPU1_SA_DQS_DN<6>")
	)
	(segment
		(start 168.168574 -211.358226)
		(end 170.650408 -211.358226)
		(width 0.16002)
		(layer "In6.Cu")
		(net "M_K_CPU1_SA_DQS_DN<6>")
	)
	(segment
		(start 192.989962 -211.101686)
		(end 193.509138 -211.101686)
		(width 0.16002)
		(layer "In6.Cu")
		(net "M_K_CPU1_SA_DQS_DN<6>")
	)
	(segment
		(start 147.688554 -230.078026)
		(end 147.705318 -230.061262)
		(width 0.09525)
		(layer "In6.Cu")
		(net "M_K_CPU1_SA_DQS_DN<6>")
	)
	(segment
		(start 191.982344 -211.358226)
		(end 192.131442 -211.209128)
		(width 0.16002)
		(layer "In6.Cu")
		(net "M_K_CPU1_SA_DQS_DN<6>")
	)
	(segment
		(start 162.498278 -213.551262)
		(end 162.500056 -213.55304)
		(width 0.16002)
		(layer "In6.Cu")
		(net "M_K_CPU1_SA_DQS_DN<6>")
	)
	(segment
		(start 157.00375 -219.04579)
		(end 157.005528 -219.047568)
		(width 0.16002)
		(layer "In6.Cu")
		(net "M_K_CPU1_SA_DQS_DN<6>")
	)
	(segment
		(start 175.712628 -211.358226)
		(end 178.194462 -211.358226)
		(width 0.16002)
		(layer "In6.Cu")
		(net "M_K_CPU1_SA_DQS_DN<6>")
	)
	(segment
		(start 161.352484 -214.926672)
		(end 161.599118 -214.680038)
		(width 0.16002)
		(layer "In6.Cu")
		(net "M_K_CPU1_SA_DQS_DN<6>")
	)
	(segment
		(start 158.377382 -217.672158)
		(end 158.37916 -217.673936)
		(width 0.16002)
		(layer "In6.Cu")
		(net "M_K_CPU1_SA_DQS_DN<6>")
	)
	(segment
		(start 172.564552 -212.20811)
		(end 172.944282 -211.82838)
		(width 0.16002)
		(layer "In6.Cu")
		(net "M_K_CPU1_SA_DQS_DN<6>")
	)
	(segment
		(start 174.336202 -211.04098)
		(end 175.395382 -211.04098)
		(width 0.16002)
		(layer "In6.Cu")
		(net "M_K_CPU1_SA_DQS_DN<6>")
	)
	(segment
		(start 192.131442 -211.209128)
		(end 192.88252 -211.209128)
		(width 0.16002)
		(layer "In6.Cu")
		(net "M_K_CPU1_SA_DQS_DN<6>")
	)
	(segment
		(start 157.476444 -218.573096)
		(end 157.476444 -218.096592)
		(width 0.16002)
		(layer "In6.Cu")
		(net "M_K_CPU1_SA_DQS_DN<6>")
	)
	(segment
		(start 156.527246 -219.04579)
		(end 157.00375 -219.04579)
		(width 0.16002)
		(layer "In6.Cu")
		(net "M_K_CPU1_SA_DQS_DN<6>")
	)
	(segment
		(start 161.599118 -214.453978)
		(end 161.59734 -214.4522)
		(width 0.16002)
		(layer "In6.Cu")
		(net "M_K_CPU1_SA_DQS_DN<6>")
	)
	(segment
		(start 163.873688 -212.179408)
		(end 164.099748 -212.179408)
		(width 0.16002)
		(layer "In6.Cu")
		(net "M_K_CPU1_SA_DQS_DN<6>")
	)
	(segment
		(start 157.478222 -218.574874)
		(end 157.476444 -218.573096)
		(width 0.16002)
		(layer "In6.Cu")
		(net "M_K_CPU1_SA_DQS_DN<6>")
	)
	(segment
		(start 141.384782 -232.334308)
		(end 141.230858 -232.599738)
		(width 0.09525)
		(layer "In6.Cu")
		(net "M_K_CPU1_SA_DQS_DN<6>")
	)
	(segment
		(start 155.803346 -220.47581)
		(end 156.10459 -220.174566)
		(width 0.16002)
		(layer "In6.Cu")
		(net "M_K_CPU1_SA_DQS_DN<6>")
	)
	(segment
		(start 189.42431 -211.04098)
		(end 190.48349 -211.04098)
		(width 0.16002)
		(layer "In6.Cu")
		(net "M_K_CPU1_SA_DQS_DN<6>")
	)
	(segment
		(start 163.87191 -212.17763)
		(end 163.873688 -212.179408)
		(width 0.16002)
		(layer "In6.Cu")
		(net "M_K_CPU1_SA_DQS_DN<6>")
	)
	(segment
		(start 159.751014 -216.298526)
		(end 159.752792 -216.300304)
		(width 0.16002)
		(layer "In6.Cu")
		(net "M_K_CPU1_SA_DQS_DN<6>")
	)
	(arc
		(start 144.403318 -232.653332)
		(mid 144.68048 -232.583532)
		(end 144.956022 -232.659428)
		(width 0.09525)
		(layer "In6.Cu")
		(net "M_K_CPU1_SA_DQS_DN<6>")
	)
	(arc
		(start 143.08455 -232.664254)
		(mid 143.269582 -232.710168)
		(end 143.453358 -232.659428)
		(width 0.09525)
		(layer "In6.Cu")
		(net "M_K_CPU1_SA_DQS_DN<6>")
	)
	(arc
		(start 142.513304 -232.659428)
		(mid 142.794736 -232.583673)
		(end 143.076168 -232.659428)
		(width 0.09525)
		(layer "In6.Cu")
		(net "M_K_CPU1_SA_DQS_DN<6>")
	)
	(arc
		(start 144.015968 -232.659428)
		(mid 144.204436 -232.710105)
		(end 144.392904 -232.659428)
		(width 0.09525)
		(layer "In6.Cu")
		(net "M_K_CPU1_SA_DQS_DN<6>")
	)
	(arc
		(start 143.453358 -232.659428)
		(mid 143.728647 -232.583707)
		(end 144.005554 -232.653332)
		(width 0.09525)
		(layer "In6.Cu")
		(net "M_K_CPU1_SA_DQS_DN<6>")
	)
	(arc
		(start 141.57325 -232.659428)
		(mid 141.854682 -232.583673)
		(end 142.136114 -232.659428)
		(width 0.09525)
		(layer "In6.Cu")
		(net "M_K_CPU1_SA_DQS_DN<6>")
	)
	(arc
		(start 145.332958 -232.659428)
		(mid 145.373652 -232.632124)
		(end 145.410428 -232.599738)
		(width 0.09525)
		(layer "In6.Cu")
		(net "M_K_CPU1_SA_DQS_DN<6>")
	)
	(arc
		(start 144.956022 -232.659428)
		(mid 145.137638 -232.710165)
		(end 145.32102 -232.666286)
		(width 0.09525)
		(layer "In6.Cu")
		(net "M_K_CPU1_SA_DQS_DN<6>")
	)
	(arc
		(start 142.136114 -232.659428)
		(mid 142.319889 -232.7102)
		(end 142.504922 -232.664254)
		(width 0.09525)
		(layer "In6.Cu")
		(net "M_K_CPU1_SA_DQS_DN<6>")
	)
	(arc
		(start 141.253972 -232.686352)
		(mid 141.416623 -232.708612)
		(end 141.57325 -232.659428)
		(width 0.09525)
		(layer "In6.Cu")
		(net "M_K_CPU1_SA_DQS_DN<6>")
	)
	(segment
		(start 140.91793 -227.740464)
		(end 141.384782 -227.474526)
		(width 0.12954)
		(layer "F.Cu")
		(net "M_K_CPU1_SA_DQS_DN<5>")
	)
	(segment
		(start 146.475704 -222.619824)
		(end 146.475704 -222.575374)
		(width 0.09525)
		(layer "In6.Cu")
		(net "M_K_CPU1_SA_DQS_DN<5>")
	)
	(segment
		(start 149.82571 -216.422224)
		(end 150.479506 -215.768428)
		(width 0.16002)
		(layer "In6.Cu")
		(net "M_K_CPU1_SA_DQS_DN<5>")
	)
	(segment
		(start 179.044346 -202.858116)
		(end 180.108606 -202.858116)
		(width 0.16002)
		(layer "In6.Cu")
		(net "M_K_CPU1_SA_DQS_DN<5>")
	)
	(segment
		(start 189.42431 -201.690986)
		(end 190.48349 -201.690986)
		(width 0.16002)
		(layer "In6.Cu")
		(net "M_K_CPU1_SA_DQS_DN<5>")
	)
	(segment
		(start 187.65266 -202.858116)
		(end 188.03239 -202.478386)
		(width 0.16002)
		(layer "In6.Cu")
		(net "M_K_CPU1_SA_DQS_DN<5>")
	)
	(segment
		(start 168.168574 -202.008232)
		(end 170.650408 -202.008232)
		(width 0.16002)
		(layer "In6.Cu")
		(net "M_K_CPU1_SA_DQS_DN<5>")
	)
	(segment
		(start 172.564552 -202.858116)
		(end 172.944282 -202.478386)
		(width 0.16002)
		(layer "In6.Cu")
		(net "M_K_CPU1_SA_DQS_DN<5>")
	)
	(segment
		(start 166.004748 -202.478386)
		(end 166.792148 -201.690986)
		(width 0.16002)
		(layer "In6.Cu")
		(net "M_K_CPU1_SA_DQS_DN<5>")
	)
	(segment
		(start 151.530304 -215.62187)
		(end 151.530304 -215.39581)
		(width 0.16002)
		(layer "In6.Cu")
		(net "M_K_CPU1_SA_DQS_DN<5>")
	)
	(segment
		(start 167.851328 -201.690986)
		(end 168.168574 -202.008232)
		(width 0.16002)
		(layer "In6.Cu")
		(net "M_K_CPU1_SA_DQS_DN<5>")
	)
	(segment
		(start 143.73479 -227.723954)
		(end 143.96085 -227.723954)
		(width 0.09525)
		(layer "In6.Cu")
		(net "M_K_CPU1_SA_DQS_DN<5>")
	)
	(segment
		(start 153.22677 -213.021164)
		(end 153.703274 -213.021164)
		(width 0.16002)
		(layer "In6.Cu")
		(net "M_K_CPU1_SA_DQS_DN<5>")
	)
	(segment
		(start 157.024832 -209.901282)
		(end 156.923994 -209.800444)
		(width 0.16002)
		(layer "In6.Cu")
		(net "M_K_CPU1_SA_DQS_DN<5>")
	)
	(segment
		(start 152.803098 -213.444836)
		(end 153.22677 -213.021164)
		(width 0.16002)
		(layer "In6.Cu")
		(net "M_K_CPU1_SA_DQS_DN<5>")
	)
	(segment
		(start 145.52295 -224.253806)
		(end 145.522442 -224.253298)
		(width 0.09525)
		(layer "In6.Cu")
		(net "M_K_CPU1_SA_DQS_DN<5>")
	)
	(segment
		(start 154.030172 -213.122002)
		(end 154.277568 -212.874606)
		(width 0.16002)
		(layer "In6.Cu")
		(net "M_K_CPU1_SA_DQS_DN<5>")
	)
	(segment
		(start 186.5884 -202.858116)
		(end 187.65266 -202.858116)
		(width 0.16002)
		(layer "In6.Cu")
		(net "M_K_CPU1_SA_DQS_DN<5>")
	)
	(segment
		(start 155.6512 -211.500974)
		(end 155.6512 -211.274914)
		(width 0.16002)
		(layer "In6.Cu")
		(net "M_K_CPU1_SA_DQS_DN<5>")
	)
	(segment
		(start 152.65654 -214.495634)
		(end 152.903936 -214.248238)
		(width 0.16002)
		(layer "In6.Cu")
		(net "M_K_CPU1_SA_DQS_DN<5>")
	)
	(segment
		(start 155.550362 -211.174076)
		(end 155.550362 -210.697572)
		(width 0.16002)
		(layer "In6.Cu")
		(net "M_K_CPU1_SA_DQS_DN<5>")
	)
	(segment
		(start 151.429466 -214.818468)
		(end 151.853138 -214.394796)
		(width 0.16002)
		(layer "In6.Cu")
		(net "M_K_CPU1_SA_DQS_DN<5>")
	)
	(segment
		(start 192.837308 -201.777346)
		(end 193.407792 -201.777346)
		(width 0.16002)
		(layer "In6.Cu")
		(net "M_K_CPU1_SA_DQS_DN<5>")
	)
	(segment
		(start 154.17673 -212.547708)
		(end 154.17673 -212.071204)
		(width 0.16002)
		(layer "In6.Cu")
		(net "M_K_CPU1_SA_DQS_DN<5>")
	)
	(segment
		(start 190.800736 -202.008232)
		(end 191.982344 -202.008232)
		(width 0.16002)
		(layer "In6.Cu")
		(net "M_K_CPU1_SA_DQS_DN<5>")
	)
	(segment
		(start 192.131442 -201.859134)
		(end 192.75552 -201.859134)
		(width 0.16002)
		(layer "In6.Cu")
		(net "M_K_CPU1_SA_DQS_DN<5>")
	)
	(segment
		(start 145.992342 -223.142556)
		(end 146.447764 -222.687134)
		(width 0.09525)
		(layer "In6.Cu")
		(net "M_K_CPU1_SA_DQS_DN<5>")
	)
	(segment
		(start 188.03239 -202.478386)
		(end 188.63691 -202.478386)
		(width 0.16002)
		(layer "In6.Cu")
		(net "M_K_CPU1_SA_DQS_DN<5>")
	)
	(segment
		(start 145.52295 -225.904806)
		(end 145.52295 -224.253806)
		(width 0.09525)
		(layer "In6.Cu")
		(net "M_K_CPU1_SA_DQS_DN<5>")
	)
	(segment
		(start 156.450538 -210.2739)
		(end 156.551376 -210.374738)
		(width 0.16002)
		(layer "In6.Cu")
		(net "M_K_CPU1_SA_DQS_DN<5>")
	)
	(segment
		(start 144.67967 -227.065586)
		(end 144.835118 -226.998022)
		(width 0.09525)
		(layer "In6.Cu")
		(net "M_K_CPU1_SA_DQS_DN<5>")
	)
	(segment
		(start 156.777436 -210.374738)
		(end 157.024832 -210.127342)
		(width 0.16002)
		(layer "In6.Cu")
		(net "M_K_CPU1_SA_DQS_DN<5>")
	)
	(segment
		(start 181.880256 -201.690986)
		(end 182.939436 -201.690986)
		(width 0.16002)
		(layer "In6.Cu")
		(net "M_K_CPU1_SA_DQS_DN<5>")
	)
	(segment
		(start 185.738516 -202.008232)
		(end 186.5884 -202.858116)
		(width 0.16002)
		(layer "In6.Cu")
		(net "M_K_CPU1_SA_DQS_DN<5>")
	)
	(segment
		(start 183.256682 -202.008232)
		(end 185.738516 -202.008232)
		(width 0.16002)
		(layer "In6.Cu")
		(net "M_K_CPU1_SA_DQS_DN<5>")
	)
	(segment
		(start 170.650408 -202.008232)
		(end 171.500292 -202.858116)
		(width 0.16002)
		(layer "In6.Cu")
		(net "M_K_CPU1_SA_DQS_DN<5>")
	)
	(segment
		(start 141.230858 -227.739956)
		(end 141.253972 -227.82657)
		(width 0.09525)
		(layer "In6.Cu")
		(net "M_K_CPU1_SA_DQS_DN<5>")
	)
	(segment
		(start 180.488336 -202.478386)
		(end 181.092856 -202.478386)
		(width 0.16002)
		(layer "In6.Cu")
		(net "M_K_CPU1_SA_DQS_DN<5>")
	)
	(segment
		(start 173.548802 -202.478386)
		(end 174.336202 -201.690986)
		(width 0.16002)
		(layer "In6.Cu")
		(net "M_K_CPU1_SA_DQS_DN<5>")
	)
	(segment
		(start 182.939436 -201.690986)
		(end 183.256682 -202.008232)
		(width 0.16002)
		(layer "In6.Cu")
		(net "M_K_CPU1_SA_DQS_DN<5>")
	)
	(segment
		(start 149.82571 -219.22613)
		(end 149.82571 -216.422224)
		(width 0.16002)
		(layer "In6.Cu")
		(net "M_K_CPU1_SA_DQS_DN<5>")
	)
	(segment
		(start 154.277568 -212.648546)
		(end 154.17673 -212.547708)
		(width 0.16002)
		(layer "In6.Cu")
		(net "M_K_CPU1_SA_DQS_DN<5>")
	)
	(segment
		(start 190.48349 -201.690986)
		(end 190.800736 -202.008232)
		(width 0.16002)
		(layer "In6.Cu")
		(net "M_K_CPU1_SA_DQS_DN<5>")
	)
	(segment
		(start 156.923994 -209.32394)
		(end 163.769548 -202.478386)
		(width 0.16002)
		(layer "In6.Cu")
		(net "M_K_CPU1_SA_DQS_DN<5>")
	)
	(segment
		(start 155.550362 -210.697572)
		(end 155.974034 -210.2739)
		(width 0.16002)
		(layer "In6.Cu")
		(net "M_K_CPU1_SA_DQS_DN<5>")
	)
	(segment
		(start 193.407792 -201.777346)
		(end 193.48958 -201.859134)
		(width 0.16002)
		(layer "In6.Cu")
		(net "M_K_CPU1_SA_DQS_DN<5>")
	)
	(segment
		(start 194.33032 -201.859134)
		(end 194.604132 -201.585322)
		(width 0.16002)
		(layer "In6.Cu")
		(net "M_K_CPU1_SA_DQS_DN<5>")
	)
	(segment
		(start 155.974034 -210.2739)
		(end 156.450538 -210.2739)
		(width 0.16002)
		(layer "In6.Cu")
		(net "M_K_CPU1_SA_DQS_DN<5>")
	)
	(segment
		(start 151.429466 -215.294972)
		(end 151.429466 -214.818468)
		(width 0.16002)
		(layer "In6.Cu")
		(net "M_K_CPU1_SA_DQS_DN<5>")
	)
	(segment
		(start 180.108606 -202.858116)
		(end 180.488336 -202.478386)
		(width 0.16002)
		(layer "In6.Cu")
		(net "M_K_CPU1_SA_DQS_DN<5>")
	)
	(segment
		(start 146.492468 -222.55861)
		(end 149.82571 -219.22613)
		(width 0.16002)
		(layer "In6.Cu")
		(net "M_K_CPU1_SA_DQS_DN<5>")
	)
	(segment
		(start 181.092856 -202.478386)
		(end 181.880256 -201.690986)
		(width 0.16002)
		(layer "In6.Cu")
		(net "M_K_CPU1_SA_DQS_DN<5>")
	)
	(segment
		(start 142.504922 -227.804472)
		(end 142.513304 -227.799646)
		(width 0.09525)
		(layer "In6.Cu")
		(net "M_K_CPU1_SA_DQS_DN<5>")
	)
	(segment
		(start 150.479506 -215.768428)
		(end 150.95601 -215.768428)
		(width 0.16002)
		(layer "In6.Cu")
		(net "M_K_CPU1_SA_DQS_DN<5>")
	)
	(segment
		(start 151.056848 -215.869266)
		(end 151.282908 -215.869266)
		(width 0.16002)
		(layer "In6.Cu")
		(net "M_K_CPU1_SA_DQS_DN<5>")
	)
	(segment
		(start 152.903936 -214.248238)
		(end 152.903936 -214.022178)
		(width 0.16002)
		(layer "In6.Cu")
		(net "M_K_CPU1_SA_DQS_DN<5>")
	)
	(segment
		(start 152.903936 -214.022178)
		(end 152.803098 -213.92134)
		(width 0.16002)
		(layer "In6.Cu")
		(net "M_K_CPU1_SA_DQS_DN<5>")
	)
	(segment
		(start 156.551376 -210.374738)
		(end 156.777436 -210.374738)
		(width 0.16002)
		(layer "In6.Cu")
		(net "M_K_CPU1_SA_DQS_DN<5>")
	)
	(segment
		(start 151.853138 -214.394796)
		(end 152.329642 -214.394796)
		(width 0.16002)
		(layer "In6.Cu")
		(net "M_K_CPU1_SA_DQS_DN<5>")
	)
	(segment
		(start 145.803366 -223.749616)
		(end 145.834862 -223.731328)
		(width 0.09525)
		(layer "In6.Cu")
		(net "M_K_CPU1_SA_DQS_DN<5>")
	)
	(segment
		(start 172.944282 -202.478386)
		(end 173.548802 -202.478386)
		(width 0.16002)
		(layer "In6.Cu")
		(net "M_K_CPU1_SA_DQS_DN<5>")
	)
	(segment
		(start 171.500292 -202.858116)
		(end 172.564552 -202.858116)
		(width 0.16002)
		(layer "In6.Cu")
		(net "M_K_CPU1_SA_DQS_DN<5>")
	)
	(segment
		(start 178.194462 -202.008232)
		(end 179.044346 -202.858116)
		(width 0.16002)
		(layer "In6.Cu")
		(net "M_K_CPU1_SA_DQS_DN<5>")
	)
	(segment
		(start 154.277568 -212.874606)
		(end 154.277568 -212.648546)
		(width 0.16002)
		(layer "In6.Cu")
		(net "M_K_CPU1_SA_DQS_DN<5>")
	)
	(segment
		(start 145.765266 -223.771714)
		(end 145.803366 -223.749616)
		(width 0.09525)
		(layer "In6.Cu")
		(net "M_K_CPU1_SA_DQS_DN<5>")
	)
	(segment
		(start 156.923994 -209.800444)
		(end 156.923994 -209.32394)
		(width 0.16002)
		(layer "In6.Cu")
		(net "M_K_CPU1_SA_DQS_DN<5>")
	)
	(segment
		(start 188.63691 -202.478386)
		(end 189.42431 -201.690986)
		(width 0.16002)
		(layer "In6.Cu")
		(net "M_K_CPU1_SA_DQS_DN<5>")
	)
	(segment
		(start 152.43048 -214.495634)
		(end 152.65654 -214.495634)
		(width 0.16002)
		(layer "In6.Cu")
		(net "M_K_CPU1_SA_DQS_DN<5>")
	)
	(segment
		(start 155.177744 -211.74837)
		(end 155.403804 -211.74837)
		(width 0.16002)
		(layer "In6.Cu")
		(net "M_K_CPU1_SA_DQS_DN<5>")
	)
	(segment
		(start 155.403804 -211.74837)
		(end 155.6512 -211.500974)
		(width 0.16002)
		(layer "In6.Cu")
		(net "M_K_CPU1_SA_DQS_DN<5>")
	)
	(segment
		(start 145.992342 -223.424496)
		(end 145.992342 -223.142556)
		(width 0.09525)
		(layer "In6.Cu")
		(net "M_K_CPU1_SA_DQS_DN<5>")
	)
	(segment
		(start 153.804112 -213.122002)
		(end 154.030172 -213.122002)
		(width 0.16002)
		(layer "In6.Cu")
		(net "M_K_CPU1_SA_DQS_DN<5>")
	)
	(segment
		(start 151.530304 -215.39581)
		(end 151.429466 -215.294972)
		(width 0.16002)
		(layer "In6.Cu")
		(net "M_K_CPU1_SA_DQS_DN<5>")
	)
	(segment
		(start 152.329642 -214.394796)
		(end 152.43048 -214.495634)
		(width 0.16002)
		(layer "In6.Cu")
		(net "M_K_CPU1_SA_DQS_DN<5>")
	)
	(segment
		(start 155.076906 -211.647532)
		(end 155.177744 -211.74837)
		(width 0.16002)
		(layer "In6.Cu")
		(net "M_K_CPU1_SA_DQS_DN<5>")
	)
	(segment
		(start 141.384782 -227.474526)
		(end 141.230858 -227.739956)
		(width 0.09525)
		(layer "In6.Cu")
		(net "M_K_CPU1_SA_DQS_DN<5>")
	)
	(segment
		(start 155.6512 -211.274914)
		(end 155.550362 -211.174076)
		(width 0.16002)
		(layer "In6.Cu")
		(net "M_K_CPU1_SA_DQS_DN<5>")
	)
	(segment
		(start 146.475704 -222.575374)
		(end 146.492468 -222.55861)
		(width 0.09525)
		(layer "In6.Cu")
		(net "M_K_CPU1_SA_DQS_DN<5>")
	)
	(segment
		(start 175.712628 -202.008232)
		(end 178.194462 -202.008232)
		(width 0.16002)
		(layer "In6.Cu")
		(net "M_K_CPU1_SA_DQS_DN<5>")
	)
	(segment
		(start 191.982344 -202.008232)
		(end 192.131442 -201.859134)
		(width 0.16002)
		(layer "In6.Cu")
		(net "M_K_CPU1_SA_DQS_DN<5>")
	)
	(segment
		(start 145.522442 -224.253298)
		(end 145.522442 -224.234502)
		(width 0.09525)
		(layer "In6.Cu")
		(net "M_K_CPU1_SA_DQS_DN<5>")
	)
	(segment
		(start 163.769548 -202.478386)
		(end 166.004748 -202.478386)
		(width 0.16002)
		(layer "In6.Cu")
		(net "M_K_CPU1_SA_DQS_DN<5>")
	)
	(segment
		(start 166.792148 -201.690986)
		(end 167.851328 -201.690986)
		(width 0.16002)
		(layer "In6.Cu")
		(net "M_K_CPU1_SA_DQS_DN<5>")
	)
	(segment
		(start 150.95601 -215.768428)
		(end 151.056848 -215.869266)
		(width 0.16002)
		(layer "In6.Cu")
		(net "M_K_CPU1_SA_DQS_DN<5>")
	)
	(segment
		(start 192.75552 -201.859134)
		(end 192.837308 -201.777346)
		(width 0.16002)
		(layer "In6.Cu")
		(net "M_K_CPU1_SA_DQS_DN<5>")
	)
	(segment
		(start 153.703274 -213.021164)
		(end 153.804112 -213.122002)
		(width 0.16002)
		(layer "In6.Cu")
		(net "M_K_CPU1_SA_DQS_DN<5>")
	)
	(segment
		(start 174.336202 -201.690986)
		(end 175.395382 -201.690986)
		(width 0.16002)
		(layer "In6.Cu")
		(net "M_K_CPU1_SA_DQS_DN<5>")
	)
	(segment
		(start 193.48958 -201.859134)
		(end 194.33032 -201.859134)
		(width 0.16002)
		(layer "In6.Cu")
		(net "M_K_CPU1_SA_DQS_DN<5>")
	)
	(segment
		(start 175.395382 -201.690986)
		(end 175.712628 -202.008232)
		(width 0.16002)
		(layer "In6.Cu")
		(net "M_K_CPU1_SA_DQS_DN<5>")
	)
	(segment
		(start 154.17673 -212.071204)
		(end 154.600402 -211.647532)
		(width 0.16002)
		(layer "In6.Cu")
		(net "M_K_CPU1_SA_DQS_DN<5>")
	)
	(segment
		(start 151.282908 -215.869266)
		(end 151.530304 -215.62187)
		(width 0.16002)
		(layer "In6.Cu")
		(net "M_K_CPU1_SA_DQS_DN<5>")
	)
	(segment
		(start 143.076168 -227.799646)
		(end 143.08455 -227.804472)
		(width 0.09525)
		(layer "In6.Cu")
		(net "M_K_CPU1_SA_DQS_DN<5>")
	)
	(segment
		(start 154.600402 -211.647532)
		(end 155.076906 -211.647532)
		(width 0.16002)
		(layer "In6.Cu")
		(net "M_K_CPU1_SA_DQS_DN<5>")
	)
	(segment
		(start 152.803098 -213.92134)
		(end 152.803098 -213.444836)
		(width 0.16002)
		(layer "In6.Cu")
		(net "M_K_CPU1_SA_DQS_DN<5>")
	)
	(segment
		(start 157.024832 -210.127342)
		(end 157.024832 -209.901282)
		(width 0.16002)
		(layer "In6.Cu")
		(net "M_K_CPU1_SA_DQS_DN<5>")
	)
	(arc
		(start 144.835118 -226.998022)
		(mid 144.993607 -226.867075)
		(end 145.05813 -226.671886)
		(width 0.09525)
		(layer "In6.Cu")
		(net "M_K_CPU1_SA_DQS_DN<5>")
	)
	(arc
		(start 143.08455 -227.804472)
		(mid 143.269582 -227.850386)
		(end 143.453358 -227.799646)
		(width 0.09525)
		(layer "In6.Cu")
		(net "M_K_CPU1_SA_DQS_DN<5>")
	)
	(arc
		(start 143.96085 -227.723954)
		(mid 144.100811 -227.698218)
		(end 144.22247 -227.624386)
		(width 0.09525)
		(layer "In6.Cu")
		(net "M_K_CPU1_SA_DQS_DN<5>")
	)
	(arc
		(start 143.453358 -227.799646)
		(mid 143.589065 -227.743161)
		(end 143.73479 -227.723954)
		(width 0.09525)
		(layer "In6.Cu")
		(net "M_K_CPU1_SA_DQS_DN<5>")
	)
	(arc
		(start 142.136114 -227.799646)
		(mid 142.319889 -227.850418)
		(end 142.504922 -227.804472)
		(width 0.09525)
		(layer "In6.Cu")
		(net "M_K_CPU1_SA_DQS_DN<5>")
	)
	(arc
		(start 141.57325 -227.799646)
		(mid 141.854682 -227.723891)
		(end 142.136114 -227.799646)
		(width 0.09525)
		(layer "In6.Cu")
		(net "M_K_CPU1_SA_DQS_DN<5>")
	)
	(arc
		(start 141.253972 -227.82657)
		(mid 141.416623 -227.84883)
		(end 141.57325 -227.799646)
		(width 0.09525)
		(layer "In6.Cu")
		(net "M_K_CPU1_SA_DQS_DN<5>")
	)
	(arc
		(start 146.447764 -222.687134)
		(mid 146.468453 -222.656266)
		(end 146.475704 -222.619824)
		(width 0.09525)
		(layer "In6.Cu")
		(net "M_K_CPU1_SA_DQS_DN<5>")
	)
	(arc
		(start 145.522442 -224.234502)
		(mid 145.586839 -223.973196)
		(end 145.765266 -223.771714)
		(width 0.09525)
		(layer "In6.Cu")
		(net "M_K_CPU1_SA_DQS_DN<5>")
	)
	(arc
		(start 145.834862 -223.731328)
		(mid 145.95066 -223.596934)
		(end 145.992342 -223.424496)
		(width 0.09525)
		(layer "In6.Cu")
		(net "M_K_CPU1_SA_DQS_DN<5>")
	)
	(arc
		(start 142.513304 -227.799646)
		(mid 142.794736 -227.723891)
		(end 143.076168 -227.799646)
		(width 0.09525)
		(layer "In6.Cu")
		(net "M_K_CPU1_SA_DQS_DN<5>")
	)
	(arc
		(start 145.05813 -226.671886)
		(mid 145.140893 -226.386892)
		(end 145.34769 -226.174046)
		(width 0.09525)
		(layer "In6.Cu")
		(net "M_K_CPU1_SA_DQS_DN<5>")
	)
	(arc
		(start 145.34769 -226.174046)
		(mid 145.465287 -226.058921)
		(end 145.52295 -225.904806)
		(width 0.09525)
		(layer "In6.Cu")
		(net "M_K_CPU1_SA_DQS_DN<5>")
	)
	(arc
		(start 144.22247 -227.624386)
		(mid 144.375707 -227.454639)
		(end 144.48917 -227.256086)
		(width 0.09525)
		(layer "In6.Cu")
		(net "M_K_CPU1_SA_DQS_DN<5>")
	)
	(arc
		(start 144.48917 -227.256086)
		(mid 144.566319 -227.142735)
		(end 144.67967 -227.065586)
		(width 0.09525)
		(layer "In6.Cu")
		(net "M_K_CPU1_SA_DQS_DN<5>")
	)
	(segment
		(start 141.857984 -247.180354)
		(end 142.324836 -246.914416)
		(width 0.12954)
		(layer "F.Cu")
		(net "M_K_CPU1_SA_DQS_DN<4>")
	)
	(segment
		(start 180.614574 -238.903002)
		(end 181.266338 -238.903002)
		(width 0.16002)
		(layer "In6.Cu")
		(net "M_K_CPU1_SA_DQS_DN<4>")
	)
	(segment
		(start 195.705984 -238.910622)
		(end 196.335904 -238.910622)
		(width 0.16002)
		(layer "In6.Cu")
		(net "M_K_CPU1_SA_DQS_DN<4>")
	)
	(segment
		(start 180.27396 -238.562388)
		(end 180.614574 -238.903002)
		(width 0.16002)
		(layer "In6.Cu")
		(net "M_K_CPU1_SA_DQS_DN<4>")
	)
	(segment
		(start 192.87109 -238.286544)
		(end 195.081906 -238.286544)
		(width 0.16002)
		(layer "In6.Cu")
		(net "M_K_CPU1_SA_DQS_DN<4>")
	)
	(segment
		(start 146.483832 -246.945404)
		(end 147.519136 -246.945404)
		(width 0.09525)
		(layer "In6.Cu")
		(net "M_K_CPU1_SA_DQS_DN<4>")
	)
	(segment
		(start 175.301402 -237.712504)
		(end 177.014124 -237.712504)
		(width 0.16002)
		(layer "In6.Cu")
		(net "M_K_CPU1_SA_DQS_DN<4>")
	)
	(segment
		(start 187.818014 -238.562388)
		(end 188.158628 -238.903002)
		(width 0.16002)
		(layer "In6.Cu")
		(net "M_K_CPU1_SA_DQS_DN<4>")
	)
	(segment
		(start 182.117238 -238.052102)
		(end 182.505858 -238.052102)
		(width 0.16002)
		(layer "In6.Cu")
		(net "M_K_CPU1_SA_DQS_DN<4>")
	)
	(segment
		(start 190.049912 -238.052102)
		(end 190.38951 -237.712504)
		(width 0.16002)
		(layer "In6.Cu")
		(net "M_K_CPU1_SA_DQS_DN<4>")
	)
	(segment
		(start 177.864008 -238.562388)
		(end 180.27396 -238.562388)
		(width 0.16002)
		(layer "In6.Cu")
		(net "M_K_CPU1_SA_DQS_DN<4>")
	)
	(segment
		(start 144.392904 -246.589296)
		(end 144.403318 -246.595392)
		(width 0.09525)
		(layer "In6.Cu")
		(net "M_K_CPU1_SA_DQS_DN<4>")
	)
	(segment
		(start 181.266338 -238.903002)
		(end 182.117238 -238.052102)
		(width 0.16002)
		(layer "In6.Cu")
		(net "M_K_CPU1_SA_DQS_DN<4>")
	)
	(segment
		(start 188.158628 -238.903002)
		(end 188.810392 -238.903002)
		(width 0.16002)
		(layer "In6.Cu")
		(net "M_K_CPU1_SA_DQS_DN<4>")
	)
	(segment
		(start 143.076168 -246.589296)
		(end 143.08455 -246.58447)
		(width 0.09525)
		(layer "In6.Cu")
		(net "M_K_CPU1_SA_DQS_DN<4>")
	)
	(segment
		(start 174.573184 -238.052102)
		(end 174.961804 -238.052102)
		(width 0.16002)
		(layer "In6.Cu")
		(net "M_K_CPU1_SA_DQS_DN<4>")
	)
	(segment
		(start 148.303234 -246.245126)
		(end 157.051756 -246.245126)
		(width 0.16002)
		(layer "In6.Cu")
		(net "M_K_CPU1_SA_DQS_DN<4>")
	)
	(segment
		(start 173.07052 -238.903002)
		(end 173.722284 -238.903002)
		(width 0.16002)
		(layer "In6.Cu")
		(net "M_K_CPU1_SA_DQS_DN<4>")
	)
	(segment
		(start 147.818602 -246.645938)
		(end 147.902422 -246.645938)
		(width 0.09525)
		(layer "In6.Cu")
		(net "M_K_CPU1_SA_DQS_DN<4>")
	)
	(segment
		(start 190.38951 -237.712504)
		(end 192.29705 -237.712504)
		(width 0.16002)
		(layer "In6.Cu")
		(net "M_K_CPU1_SA_DQS_DN<4>")
	)
	(segment
		(start 172.729906 -238.562388)
		(end 173.07052 -238.903002)
		(width 0.16002)
		(layer "In6.Cu")
		(net "M_K_CPU1_SA_DQS_DN<4>")
	)
	(segment
		(start 157.051756 -246.245126)
		(end 164.39388 -238.903002)
		(width 0.16002)
		(layer "In6.Cu")
		(net "M_K_CPU1_SA_DQS_DN<4>")
	)
	(segment
		(start 167.41775 -238.052102)
		(end 167.757348 -237.712504)
		(width 0.16002)
		(layer "In6.Cu")
		(net "M_K_CPU1_SA_DQS_DN<4>")
	)
	(segment
		(start 145.589752 -246.651018)
		(end 146.189446 -246.651018)
		(width 0.09525)
		(layer "In6.Cu")
		(net "M_K_CPU1_SA_DQS_DN<4>")
	)
	(segment
		(start 166.17823 -238.903002)
		(end 167.02913 -238.052102)
		(width 0.16002)
		(layer "In6.Cu")
		(net "M_K_CPU1_SA_DQS_DN<4>")
	)
	(segment
		(start 147.919186 -246.629174)
		(end 148.303234 -246.245126)
		(width 0.16002)
		(layer "In6.Cu")
		(net "M_K_CPU1_SA_DQS_DN<4>")
	)
	(segment
		(start 167.757348 -237.712504)
		(end 169.47007 -237.712504)
		(width 0.16002)
		(layer "In6.Cu")
		(net "M_K_CPU1_SA_DQS_DN<4>")
	)
	(segment
		(start 173.722284 -238.903002)
		(end 174.573184 -238.052102)
		(width 0.16002)
		(layer "In6.Cu")
		(net "M_K_CPU1_SA_DQS_DN<4>")
	)
	(segment
		(start 174.961804 -238.052102)
		(end 175.301402 -237.712504)
		(width 0.16002)
		(layer "In6.Cu")
		(net "M_K_CPU1_SA_DQS_DN<4>")
	)
	(segment
		(start 146.189446 -246.651018)
		(end 146.483832 -246.945404)
		(width 0.09525)
		(layer "In6.Cu")
		(net "M_K_CPU1_SA_DQS_DN<4>")
	)
	(segment
		(start 196.335904 -238.910622)
		(end 196.53504 -238.711486)
		(width 0.16002)
		(layer "In6.Cu")
		(net "M_K_CPU1_SA_DQS_DN<4>")
	)
	(segment
		(start 188.810392 -238.903002)
		(end 189.661292 -238.052102)
		(width 0.16002)
		(layer "In6.Cu")
		(net "M_K_CPU1_SA_DQS_DN<4>")
	)
	(segment
		(start 192.29705 -237.712504)
		(end 192.87109 -238.286544)
		(width 0.16002)
		(layer "In6.Cu")
		(net "M_K_CPU1_SA_DQS_DN<4>")
	)
	(segment
		(start 147.519136 -246.945404)
		(end 147.818602 -246.645938)
		(width 0.09525)
		(layer "In6.Cu")
		(net "M_K_CPU1_SA_DQS_DN<4>")
	)
	(segment
		(start 189.661292 -238.052102)
		(end 190.049912 -238.052102)
		(width 0.16002)
		(layer "In6.Cu")
		(net "M_K_CPU1_SA_DQS_DN<4>")
	)
	(segment
		(start 144.005554 -246.595392)
		(end 144.015968 -246.589296)
		(width 0.09525)
		(layer "In6.Cu")
		(net "M_K_CPU1_SA_DQS_DN<4>")
	)
	(segment
		(start 198.430388 -238.711486)
		(end 198.7042 -238.985298)
		(width 0.16002)
		(layer "In6.Cu")
		(net "M_K_CPU1_SA_DQS_DN<4>")
	)
	(segment
		(start 170.319954 -238.562388)
		(end 172.729906 -238.562388)
		(width 0.16002)
		(layer "In6.Cu")
		(net "M_K_CPU1_SA_DQS_DN<4>")
	)
	(segment
		(start 142.47876 -246.648986)
		(end 142.579598 -246.622316)
		(width 0.09525)
		(layer "In6.Cu")
		(net "M_K_CPU1_SA_DQS_DN<4>")
	)
	(segment
		(start 167.02913 -238.052102)
		(end 167.41775 -238.052102)
		(width 0.16002)
		(layer "In6.Cu")
		(net "M_K_CPU1_SA_DQS_DN<4>")
	)
	(segment
		(start 142.324836 -246.914416)
		(end 142.47876 -246.648986)
		(width 0.09525)
		(layer "In6.Cu")
		(net "M_K_CPU1_SA_DQS_DN<4>")
	)
	(segment
		(start 182.505858 -238.052102)
		(end 182.845456 -237.712504)
		(width 0.16002)
		(layer "In6.Cu")
		(net "M_K_CPU1_SA_DQS_DN<4>")
	)
	(segment
		(start 182.845456 -237.712504)
		(end 184.558178 -237.712504)
		(width 0.16002)
		(layer "In6.Cu")
		(net "M_K_CPU1_SA_DQS_DN<4>")
	)
	(segment
		(start 164.39388 -238.903002)
		(end 166.17823 -238.903002)
		(width 0.16002)
		(layer "In6.Cu")
		(net "M_K_CPU1_SA_DQS_DN<4>")
	)
	(segment
		(start 195.081906 -238.286544)
		(end 195.705984 -238.910622)
		(width 0.16002)
		(layer "In6.Cu")
		(net "M_K_CPU1_SA_DQS_DN<4>")
	)
	(segment
		(start 147.902422 -246.645938)
		(end 147.919186 -246.629174)
		(width 0.09525)
		(layer "In6.Cu")
		(net "M_K_CPU1_SA_DQS_DN<4>")
	)
	(segment
		(start 177.014124 -237.712504)
		(end 177.864008 -238.562388)
		(width 0.16002)
		(layer "In6.Cu")
		(net "M_K_CPU1_SA_DQS_DN<4>")
	)
	(segment
		(start 169.47007 -237.712504)
		(end 170.319954 -238.562388)
		(width 0.16002)
		(layer "In6.Cu")
		(net "M_K_CPU1_SA_DQS_DN<4>")
	)
	(segment
		(start 185.408062 -238.562388)
		(end 187.818014 -238.562388)
		(width 0.16002)
		(layer "In6.Cu")
		(net "M_K_CPU1_SA_DQS_DN<4>")
	)
	(segment
		(start 196.53504 -238.711486)
		(end 198.430388 -238.711486)
		(width 0.16002)
		(layer "In6.Cu")
		(net "M_K_CPU1_SA_DQS_DN<4>")
	)
	(segment
		(start 184.558178 -237.712504)
		(end 185.408062 -238.562388)
		(width 0.16002)
		(layer "In6.Cu")
		(net "M_K_CPU1_SA_DQS_DN<4>")
	)
	(arc
		(start 143.08455 -246.58447)
		(mid 143.269582 -246.538556)
		(end 143.453358 -246.589296)
		(width 0.09525)
		(layer "In6.Cu")
		(net "M_K_CPU1_SA_DQS_DN<4>")
	)
	(arc
		(start 144.956022 -246.589296)
		(mid 145.137638 -246.538559)
		(end 145.32102 -246.582438)
		(width 0.09525)
		(layer "In6.Cu")
		(net "M_K_CPU1_SA_DQS_DN<4>")
	)
	(arc
		(start 142.59941 -246.63019)
		(mid 142.842374 -246.663177)
		(end 143.076168 -246.589296)
		(width 0.09525)
		(layer "In6.Cu")
		(net "M_K_CPU1_SA_DQS_DN<4>")
	)
	(arc
		(start 144.015968 -246.589296)
		(mid 144.204436 -246.538619)
		(end 144.392904 -246.589296)
		(width 0.09525)
		(layer "In6.Cu")
		(net "M_K_CPU1_SA_DQS_DN<4>")
	)
	(arc
		(start 143.453358 -246.589296)
		(mid 143.728647 -246.665017)
		(end 144.005554 -246.595392)
		(width 0.09525)
		(layer "In6.Cu")
		(net "M_K_CPU1_SA_DQS_DN<4>")
	)
	(arc
		(start 142.579598 -246.622316)
		(mid 142.589466 -246.626347)
		(end 142.59941 -246.63019)
		(width 0.09525)
		(layer "In6.Cu")
		(net "M_K_CPU1_SA_DQS_DN<4>")
	)
	(arc
		(start 144.403318 -246.595392)
		(mid 144.68048 -246.665192)
		(end 144.956022 -246.589296)
		(width 0.09525)
		(layer "In6.Cu")
		(net "M_K_CPU1_SA_DQS_DN<4>")
	)
	(arc
		(start 145.32102 -246.582438)
		(mid 145.45108 -246.6336)
		(end 145.589752 -246.651018)
		(width 0.09525)
		(layer "In6.Cu")
		(net "M_K_CPU1_SA_DQS_DN<4>")
	)
	(segment
		(start 141.857984 -242.320318)
		(end 142.324836 -242.05438)
		(width 0.12954)
		(layer "F.Cu")
		(net "M_K_CPU1_SA_DQS_DN<3>")
	)
	(segment
		(start 195.705984 -229.560628)
		(end 196.335904 -229.560628)
		(width 0.16002)
		(layer "In6.Cu")
		(net "M_K_CPU1_SA_DQS_DN<3>")
	)
	(segment
		(start 154.459178 -240.627154)
		(end 159.51073 -235.575602)
		(width 0.16002)
		(layer "In6.Cu")
		(net "M_K_CPU1_SA_DQS_DN<3>")
	)
	(segment
		(start 196.335904 -229.560628)
		(end 196.53504 -229.361492)
		(width 0.16002)
		(layer "In6.Cu")
		(net "M_K_CPU1_SA_DQS_DN<3>")
	)
	(segment
		(start 147.895564 -240.627154)
		(end 147.919186 -240.627154)
		(width 0.09525)
		(layer "In6.Cu")
		(net "M_K_CPU1_SA_DQS_DN<3>")
	)
	(segment
		(start 174.961804 -228.702108)
		(end 175.301402 -228.36251)
		(width 0.16002)
		(layer "In6.Cu")
		(net "M_K_CPU1_SA_DQS_DN<3>")
	)
	(segment
		(start 146.021044 -241.677698)
		(end 146.585178 -241.113564)
		(width 0.09525)
		(layer "In6.Cu")
		(net "M_K_CPU1_SA_DQS_DN<3>")
	)
	(segment
		(start 196.53504 -229.361492)
		(end 198.430388 -229.361492)
		(width 0.16002)
		(layer "In6.Cu")
		(net "M_K_CPU1_SA_DQS_DN<3>")
	)
	(segment
		(start 177.014124 -228.36251)
		(end 177.864008 -229.212394)
		(width 0.16002)
		(layer "In6.Cu")
		(net "M_K_CPU1_SA_DQS_DN<3>")
	)
	(segment
		(start 144.392904 -241.72926)
		(end 144.403318 -241.735356)
		(width 0.09525)
		(layer "In6.Cu")
		(net "M_K_CPU1_SA_DQS_DN<3>")
	)
	(segment
		(start 177.864008 -229.212394)
		(end 180.27396 -229.212394)
		(width 0.16002)
		(layer "In6.Cu")
		(net "M_K_CPU1_SA_DQS_DN<3>")
	)
	(segment
		(start 190.38951 -228.36251)
		(end 192.29705 -228.36251)
		(width 0.16002)
		(layer "In6.Cu")
		(net "M_K_CPU1_SA_DQS_DN<3>")
	)
	(segment
		(start 166.17823 -229.553008)
		(end 167.02913 -228.702108)
		(width 0.16002)
		(layer "In6.Cu")
		(net "M_K_CPU1_SA_DQS_DN<3>")
	)
	(segment
		(start 144.005554 -241.735356)
		(end 144.015968 -241.72926)
		(width 0.09525)
		(layer "In6.Cu")
		(net "M_K_CPU1_SA_DQS_DN<3>")
	)
	(segment
		(start 195.081906 -228.93655)
		(end 195.705984 -229.560628)
		(width 0.16002)
		(layer "In6.Cu")
		(net "M_K_CPU1_SA_DQS_DN<3>")
	)
	(segment
		(start 173.722284 -229.553008)
		(end 174.573184 -228.702108)
		(width 0.16002)
		(layer "In6.Cu")
		(net "M_K_CPU1_SA_DQS_DN<3>")
	)
	(segment
		(start 147.836636 -240.568226)
		(end 147.895564 -240.627154)
		(width 0.09525)
		(layer "In6.Cu")
		(net "M_K_CPU1_SA_DQS_DN<3>")
	)
	(segment
		(start 167.757348 -228.36251)
		(end 169.47007 -228.36251)
		(width 0.16002)
		(layer "In6.Cu")
		(net "M_K_CPU1_SA_DQS_DN<3>")
	)
	(segment
		(start 192.87109 -228.93655)
		(end 195.081906 -228.93655)
		(width 0.16002)
		(layer "In6.Cu")
		(net "M_K_CPU1_SA_DQS_DN<3>")
	)
	(segment
		(start 173.07052 -229.553008)
		(end 173.722284 -229.553008)
		(width 0.16002)
		(layer "In6.Cu")
		(net "M_K_CPU1_SA_DQS_DN<3>")
	)
	(segment
		(start 188.158628 -229.553008)
		(end 188.810392 -229.553008)
		(width 0.16002)
		(layer "In6.Cu")
		(net "M_K_CPU1_SA_DQS_DN<3>")
	)
	(segment
		(start 170.319954 -229.212394)
		(end 172.729906 -229.212394)
		(width 0.16002)
		(layer "In6.Cu")
		(net "M_K_CPU1_SA_DQS_DN<3>")
	)
	(segment
		(start 188.810392 -229.553008)
		(end 189.661292 -228.702108)
		(width 0.16002)
		(layer "In6.Cu")
		(net "M_K_CPU1_SA_DQS_DN<3>")
	)
	(segment
		(start 147.919186 -240.627154)
		(end 154.459178 -240.627154)
		(width 0.16002)
		(layer "In6.Cu")
		(net "M_K_CPU1_SA_DQS_DN<3>")
	)
	(segment
		(start 181.266338 -229.553008)
		(end 182.117238 -228.702108)
		(width 0.16002)
		(layer "In6.Cu")
		(net "M_K_CPU1_SA_DQS_DN<3>")
	)
	(segment
		(start 172.729906 -229.212394)
		(end 173.07052 -229.553008)
		(width 0.16002)
		(layer "In6.Cu")
		(net "M_K_CPU1_SA_DQS_DN<3>")
	)
	(segment
		(start 143.076168 -241.72926)
		(end 143.08455 -241.724434)
		(width 0.09525)
		(layer "In6.Cu")
		(net "M_K_CPU1_SA_DQS_DN<3>")
	)
	(segment
		(start 147.641564 -240.568226)
		(end 147.836636 -240.568226)
		(width 0.09525)
		(layer "In6.Cu")
		(net "M_K_CPU1_SA_DQS_DN<3>")
	)
	(segment
		(start 175.301402 -228.36251)
		(end 177.014124 -228.36251)
		(width 0.16002)
		(layer "In6.Cu")
		(net "M_K_CPU1_SA_DQS_DN<3>")
	)
	(segment
		(start 180.27396 -229.212394)
		(end 180.614574 -229.553008)
		(width 0.16002)
		(layer "In6.Cu")
		(net "M_K_CPU1_SA_DQS_DN<3>")
	)
	(segment
		(start 142.47876 -241.78895)
		(end 142.579598 -241.76228)
		(width 0.09525)
		(layer "In6.Cu")
		(net "M_K_CPU1_SA_DQS_DN<3>")
	)
	(segment
		(start 145.144744 -241.677698)
		(end 146.021044 -241.677698)
		(width 0.09525)
		(layer "In6.Cu")
		(net "M_K_CPU1_SA_DQS_DN<3>")
	)
	(segment
		(start 167.02913 -228.702108)
		(end 167.41775 -228.702108)
		(width 0.16002)
		(layer "In6.Cu")
		(net "M_K_CPU1_SA_DQS_DN<3>")
	)
	(segment
		(start 174.573184 -228.702108)
		(end 174.961804 -228.702108)
		(width 0.16002)
		(layer "In6.Cu")
		(net "M_K_CPU1_SA_DQS_DN<3>")
	)
	(segment
		(start 147.096226 -241.113564)
		(end 147.641564 -240.568226)
		(width 0.09525)
		(layer "In6.Cu")
		(net "M_K_CPU1_SA_DQS_DN<3>")
	)
	(segment
		(start 167.41775 -228.702108)
		(end 167.757348 -228.36251)
		(width 0.16002)
		(layer "In6.Cu")
		(net "M_K_CPU1_SA_DQS_DN<3>")
	)
	(segment
		(start 185.408062 -229.212394)
		(end 187.818014 -229.212394)
		(width 0.16002)
		(layer "In6.Cu")
		(net "M_K_CPU1_SA_DQS_DN<3>")
	)
	(segment
		(start 163.503864 -229.553008)
		(end 166.17823 -229.553008)
		(width 0.16002)
		(layer "In6.Cu")
		(net "M_K_CPU1_SA_DQS_DN<3>")
	)
	(segment
		(start 187.818014 -229.212394)
		(end 188.158628 -229.553008)
		(width 0.16002)
		(layer "In6.Cu")
		(net "M_K_CPU1_SA_DQS_DN<3>")
	)
	(segment
		(start 198.430388 -229.361492)
		(end 198.7042 -229.635304)
		(width 0.16002)
		(layer "In6.Cu")
		(net "M_K_CPU1_SA_DQS_DN<3>")
	)
	(segment
		(start 182.845456 -228.36251)
		(end 184.558178 -228.36251)
		(width 0.16002)
		(layer "In6.Cu")
		(net "M_K_CPU1_SA_DQS_DN<3>")
	)
	(segment
		(start 180.614574 -229.553008)
		(end 181.266338 -229.553008)
		(width 0.16002)
		(layer "In6.Cu")
		(net "M_K_CPU1_SA_DQS_DN<3>")
	)
	(segment
		(start 190.049912 -228.702108)
		(end 190.38951 -228.36251)
		(width 0.16002)
		(layer "In6.Cu")
		(net "M_K_CPU1_SA_DQS_DN<3>")
	)
	(segment
		(start 182.505858 -228.702108)
		(end 182.845456 -228.36251)
		(width 0.16002)
		(layer "In6.Cu")
		(net "M_K_CPU1_SA_DQS_DN<3>")
	)
	(segment
		(start 142.324836 -242.05438)
		(end 142.47876 -241.78895)
		(width 0.09525)
		(layer "In6.Cu")
		(net "M_K_CPU1_SA_DQS_DN<3>")
	)
	(segment
		(start 159.51073 -235.575602)
		(end 159.51073 -233.546142)
		(width 0.16002)
		(layer "In6.Cu")
		(net "M_K_CPU1_SA_DQS_DN<3>")
	)
	(segment
		(start 184.558178 -228.36251)
		(end 185.408062 -229.212394)
		(width 0.16002)
		(layer "In6.Cu")
		(net "M_K_CPU1_SA_DQS_DN<3>")
	)
	(segment
		(start 146.585178 -241.113564)
		(end 147.096226 -241.113564)
		(width 0.09525)
		(layer "In6.Cu")
		(net "M_K_CPU1_SA_DQS_DN<3>")
	)
	(segment
		(start 182.117238 -228.702108)
		(end 182.505858 -228.702108)
		(width 0.16002)
		(layer "In6.Cu")
		(net "M_K_CPU1_SA_DQS_DN<3>")
	)
	(segment
		(start 189.661292 -228.702108)
		(end 190.049912 -228.702108)
		(width 0.16002)
		(layer "In6.Cu")
		(net "M_K_CPU1_SA_DQS_DN<3>")
	)
	(segment
		(start 159.51073 -233.546142)
		(end 163.503864 -229.553008)
		(width 0.16002)
		(layer "In6.Cu")
		(net "M_K_CPU1_SA_DQS_DN<3>")
	)
	(segment
		(start 192.29705 -228.36251)
		(end 192.87109 -228.93655)
		(width 0.16002)
		(layer "In6.Cu")
		(net "M_K_CPU1_SA_DQS_DN<3>")
	)
	(segment
		(start 169.47007 -228.36251)
		(end 170.319954 -229.212394)
		(width 0.16002)
		(layer "In6.Cu")
		(net "M_K_CPU1_SA_DQS_DN<3>")
	)
	(arc
		(start 144.956022 -241.72926)
		(mid 145.046968 -241.690959)
		(end 145.144744 -241.677698)
		(width 0.09525)
		(layer "In6.Cu")
		(net "M_K_CPU1_SA_DQS_DN<3>")
	)
	(arc
		(start 143.453358 -241.72926)
		(mid 143.728647 -241.804981)
		(end 144.005554 -241.735356)
		(width 0.09525)
		(layer "In6.Cu")
		(net "M_K_CPU1_SA_DQS_DN<3>")
	)
	(arc
		(start 144.015968 -241.72926)
		(mid 144.204436 -241.678583)
		(end 144.392904 -241.72926)
		(width 0.09525)
		(layer "In6.Cu")
		(net "M_K_CPU1_SA_DQS_DN<3>")
	)
	(arc
		(start 143.08455 -241.724434)
		(mid 143.269582 -241.67852)
		(end 143.453358 -241.72926)
		(width 0.09525)
		(layer "In6.Cu")
		(net "M_K_CPU1_SA_DQS_DN<3>")
	)
	(arc
		(start 144.403318 -241.735356)
		(mid 144.68048 -241.805156)
		(end 144.956022 -241.72926)
		(width 0.09525)
		(layer "In6.Cu")
		(net "M_K_CPU1_SA_DQS_DN<3>")
	)
	(arc
		(start 142.579598 -241.76228)
		(mid 142.831739 -241.80385)
		(end 143.076168 -241.72926)
		(width 0.09525)
		(layer "In6.Cu")
		(net "M_K_CPU1_SA_DQS_DN<3>")
	)
	(segment
		(start 141.857984 -237.460282)
		(end 142.324836 -237.194344)
		(width 0.12954)
		(layer "F.Cu")
		(net "M_K_CPU1_SA_DQS_DN<2>")
	)
	(segment
		(start 192.87109 -219.586556)
		(end 195.081906 -219.586556)
		(width 0.16002)
		(layer "In6.Cu")
		(net "M_K_CPU1_SA_DQS_DN<2>")
	)
	(segment
		(start 169.47007 -219.012516)
		(end 170.319954 -219.8624)
		(width 0.16002)
		(layer "In6.Cu")
		(net "M_K_CPU1_SA_DQS_DN<2>")
	)
	(segment
		(start 144.005554 -236.87532)
		(end 144.015968 -236.869224)
		(width 0.09525)
		(layer "In6.Cu")
		(net "M_K_CPU1_SA_DQS_DN<2>")
	)
	(segment
		(start 190.049912 -219.352114)
		(end 190.38951 -219.012516)
		(width 0.16002)
		(layer "In6.Cu")
		(net "M_K_CPU1_SA_DQS_DN<2>")
	)
	(segment
		(start 182.845456 -219.012516)
		(end 184.558178 -219.012516)
		(width 0.16002)
		(layer "In6.Cu")
		(net "M_K_CPU1_SA_DQS_DN<2>")
	)
	(segment
		(start 142.47876 -236.928914)
		(end 142.579598 -236.902244)
		(width 0.09525)
		(layer "In6.Cu")
		(net "M_K_CPU1_SA_DQS_DN<2>")
	)
	(segment
		(start 167.757348 -219.012516)
		(end 169.47007 -219.012516)
		(width 0.16002)
		(layer "In6.Cu")
		(net "M_K_CPU1_SA_DQS_DN<2>")
	)
	(segment
		(start 174.573184 -219.352114)
		(end 174.961804 -219.352114)
		(width 0.16002)
		(layer "In6.Cu")
		(net "M_K_CPU1_SA_DQS_DN<2>")
	)
	(segment
		(start 173.07052 -220.203014)
		(end 173.722284 -220.203014)
		(width 0.16002)
		(layer "In6.Cu")
		(net "M_K_CPU1_SA_DQS_DN<2>")
	)
	(segment
		(start 196.53504 -220.011498)
		(end 198.430388 -220.011498)
		(width 0.16002)
		(layer "In6.Cu")
		(net "M_K_CPU1_SA_DQS_DN<2>")
	)
	(segment
		(start 142.324836 -237.194344)
		(end 142.47876 -236.928914)
		(width 0.09525)
		(layer "In6.Cu")
		(net "M_K_CPU1_SA_DQS_DN<2>")
	)
	(segment
		(start 175.301402 -219.012516)
		(end 177.014124 -219.012516)
		(width 0.16002)
		(layer "In6.Cu")
		(net "M_K_CPU1_SA_DQS_DN<2>")
	)
	(segment
		(start 170.319954 -219.8624)
		(end 172.729906 -219.8624)
		(width 0.16002)
		(layer "In6.Cu")
		(net "M_K_CPU1_SA_DQS_DN<2>")
	)
	(segment
		(start 166.17823 -220.203014)
		(end 167.02913 -219.352114)
		(width 0.16002)
		(layer "In6.Cu")
		(net "M_K_CPU1_SA_DQS_DN<2>")
	)
	(segment
		(start 195.705984 -220.210634)
		(end 196.335904 -220.210634)
		(width 0.16002)
		(layer "In6.Cu")
		(net "M_K_CPU1_SA_DQS_DN<2>")
	)
	(segment
		(start 146.63166 -235.656374)
		(end 146.929348 -235.656374)
		(width 0.09525)
		(layer "In6.Cu")
		(net "M_K_CPU1_SA_DQS_DN<2>")
	)
	(segment
		(start 188.158628 -220.203014)
		(end 188.810392 -220.203014)
		(width 0.16002)
		(layer "In6.Cu")
		(net "M_K_CPU1_SA_DQS_DN<2>")
	)
	(segment
		(start 147.836636 -234.942126)
		(end 147.895564 -235.001054)
		(width 0.09525)
		(layer "In6.Cu")
		(net "M_K_CPU1_SA_DQS_DN<2>")
	)
	(segment
		(start 180.614574 -220.203014)
		(end 181.266338 -220.203014)
		(width 0.16002)
		(layer "In6.Cu")
		(net "M_K_CPU1_SA_DQS_DN<2>")
	)
	(segment
		(start 161.41065 -223.513396)
		(end 161.41065 -222.832676)
		(width 0.16002)
		(layer "In6.Cu")
		(net "M_K_CPU1_SA_DQS_DN<2>")
	)
	(segment
		(start 149.922992 -235.001054)
		(end 161.41065 -223.513396)
		(width 0.16002)
		(layer "In6.Cu")
		(net "M_K_CPU1_SA_DQS_DN<2>")
	)
	(segment
		(start 167.41775 -219.352114)
		(end 167.757348 -219.012516)
		(width 0.16002)
		(layer "In6.Cu")
		(net "M_K_CPU1_SA_DQS_DN<2>")
	)
	(segment
		(start 146.929348 -235.656374)
		(end 147.643596 -234.942126)
		(width 0.09525)
		(layer "In6.Cu")
		(net "M_K_CPU1_SA_DQS_DN<2>")
	)
	(segment
		(start 187.818014 -219.8624)
		(end 188.158628 -220.203014)
		(width 0.16002)
		(layer "In6.Cu")
		(net "M_K_CPU1_SA_DQS_DN<2>")
	)
	(segment
		(start 147.643596 -234.942126)
		(end 147.836636 -234.942126)
		(width 0.09525)
		(layer "In6.Cu")
		(net "M_K_CPU1_SA_DQS_DN<2>")
	)
	(segment
		(start 177.014124 -219.012516)
		(end 177.864008 -219.8624)
		(width 0.16002)
		(layer "In6.Cu")
		(net "M_K_CPU1_SA_DQS_DN<2>")
	)
	(segment
		(start 196.335904 -220.210634)
		(end 196.53504 -220.011498)
		(width 0.16002)
		(layer "In6.Cu")
		(net "M_K_CPU1_SA_DQS_DN<2>")
	)
	(segment
		(start 161.41065 -222.832676)
		(end 164.040312 -220.203014)
		(width 0.16002)
		(layer "In6.Cu")
		(net "M_K_CPU1_SA_DQS_DN<2>")
	)
	(segment
		(start 182.505858 -219.352114)
		(end 182.845456 -219.012516)
		(width 0.16002)
		(layer "In6.Cu")
		(net "M_K_CPU1_SA_DQS_DN<2>")
	)
	(segment
		(start 190.38951 -219.012516)
		(end 192.29705 -219.012516)
		(width 0.16002)
		(layer "In6.Cu")
		(net "M_K_CPU1_SA_DQS_DN<2>")
	)
	(segment
		(start 172.729906 -219.8624)
		(end 173.07052 -220.203014)
		(width 0.16002)
		(layer "In6.Cu")
		(net "M_K_CPU1_SA_DQS_DN<2>")
	)
	(segment
		(start 145.470372 -236.817662)
		(end 146.63166 -235.656374)
		(width 0.09525)
		(layer "In6.Cu")
		(net "M_K_CPU1_SA_DQS_DN<2>")
	)
	(segment
		(start 177.864008 -219.8624)
		(end 180.27396 -219.8624)
		(width 0.16002)
		(layer "In6.Cu")
		(net "M_K_CPU1_SA_DQS_DN<2>")
	)
	(segment
		(start 173.722284 -220.203014)
		(end 174.573184 -219.352114)
		(width 0.16002)
		(layer "In6.Cu")
		(net "M_K_CPU1_SA_DQS_DN<2>")
	)
	(segment
		(start 147.919186 -235.001054)
		(end 149.922992 -235.001054)
		(width 0.16002)
		(layer "In6.Cu")
		(net "M_K_CPU1_SA_DQS_DN<2>")
	)
	(segment
		(start 180.27396 -219.8624)
		(end 180.614574 -220.203014)
		(width 0.16002)
		(layer "In6.Cu")
		(net "M_K_CPU1_SA_DQS_DN<2>")
	)
	(segment
		(start 143.076168 -236.869224)
		(end 143.08455 -236.864398)
		(width 0.09525)
		(layer "In6.Cu")
		(net "M_K_CPU1_SA_DQS_DN<2>")
	)
	(segment
		(start 184.558178 -219.012516)
		(end 185.408062 -219.8624)
		(width 0.16002)
		(layer "In6.Cu")
		(net "M_K_CPU1_SA_DQS_DN<2>")
	)
	(segment
		(start 195.081906 -219.586556)
		(end 195.705984 -220.210634)
		(width 0.16002)
		(layer "In6.Cu")
		(net "M_K_CPU1_SA_DQS_DN<2>")
	)
	(segment
		(start 188.810392 -220.203014)
		(end 189.661292 -219.352114)
		(width 0.16002)
		(layer "In6.Cu")
		(net "M_K_CPU1_SA_DQS_DN<2>")
	)
	(segment
		(start 145.144744 -236.817662)
		(end 145.470372 -236.817662)
		(width 0.09525)
		(layer "In6.Cu")
		(net "M_K_CPU1_SA_DQS_DN<2>")
	)
	(segment
		(start 144.392904 -236.869224)
		(end 144.403318 -236.87532)
		(width 0.09525)
		(layer "In6.Cu")
		(net "M_K_CPU1_SA_DQS_DN<2>")
	)
	(segment
		(start 147.895564 -235.001054)
		(end 147.919186 -235.001054)
		(width 0.09525)
		(layer "In6.Cu")
		(net "M_K_CPU1_SA_DQS_DN<2>")
	)
	(segment
		(start 185.408062 -219.8624)
		(end 187.818014 -219.8624)
		(width 0.16002)
		(layer "In6.Cu")
		(net "M_K_CPU1_SA_DQS_DN<2>")
	)
	(segment
		(start 167.02913 -219.352114)
		(end 167.41775 -219.352114)
		(width 0.16002)
		(layer "In6.Cu")
		(net "M_K_CPU1_SA_DQS_DN<2>")
	)
	(segment
		(start 181.266338 -220.203014)
		(end 182.117238 -219.352114)
		(width 0.16002)
		(layer "In6.Cu")
		(net "M_K_CPU1_SA_DQS_DN<2>")
	)
	(segment
		(start 164.040312 -220.203014)
		(end 166.17823 -220.203014)
		(width 0.16002)
		(layer "In6.Cu")
		(net "M_K_CPU1_SA_DQS_DN<2>")
	)
	(segment
		(start 192.29705 -219.012516)
		(end 192.87109 -219.586556)
		(width 0.16002)
		(layer "In6.Cu")
		(net "M_K_CPU1_SA_DQS_DN<2>")
	)
	(segment
		(start 182.117238 -219.352114)
		(end 182.505858 -219.352114)
		(width 0.16002)
		(layer "In6.Cu")
		(net "M_K_CPU1_SA_DQS_DN<2>")
	)
	(segment
		(start 174.961804 -219.352114)
		(end 175.301402 -219.012516)
		(width 0.16002)
		(layer "In6.Cu")
		(net "M_K_CPU1_SA_DQS_DN<2>")
	)
	(segment
		(start 198.430388 -220.011498)
		(end 198.7042 -220.28531)
		(width 0.16002)
		(layer "In6.Cu")
		(net "M_K_CPU1_SA_DQS_DN<2>")
	)
	(segment
		(start 189.661292 -219.352114)
		(end 190.049912 -219.352114)
		(width 0.16002)
		(layer "In6.Cu")
		(net "M_K_CPU1_SA_DQS_DN<2>")
	)
	(arc
		(start 144.015968 -236.869224)
		(mid 144.204436 -236.818547)
		(end 144.392904 -236.869224)
		(width 0.09525)
		(layer "In6.Cu")
		(net "M_K_CPU1_SA_DQS_DN<2>")
	)
	(arc
		(start 143.08455 -236.864398)
		(mid 143.269582 -236.818484)
		(end 143.453358 -236.869224)
		(width 0.09525)
		(layer "In6.Cu")
		(net "M_K_CPU1_SA_DQS_DN<2>")
	)
	(arc
		(start 144.403318 -236.87532)
		(mid 144.68048 -236.94512)
		(end 144.956022 -236.869224)
		(width 0.09525)
		(layer "In6.Cu")
		(net "M_K_CPU1_SA_DQS_DN<2>")
	)
	(arc
		(start 143.453358 -236.869224)
		(mid 143.728647 -236.944945)
		(end 144.005554 -236.87532)
		(width 0.09525)
		(layer "In6.Cu")
		(net "M_K_CPU1_SA_DQS_DN<2>")
	)
	(arc
		(start 144.956022 -236.869224)
		(mid 145.046968 -236.830923)
		(end 145.144744 -236.817662)
		(width 0.09525)
		(layer "In6.Cu")
		(net "M_K_CPU1_SA_DQS_DN<2>")
	)
	(arc
		(start 142.579598 -236.902244)
		(mid 142.831739 -236.943814)
		(end 143.076168 -236.869224)
		(width 0.09525)
		(layer "In6.Cu")
		(net "M_K_CPU1_SA_DQS_DN<2>")
	)
	(segment
		(start 141.857984 -232.600246)
		(end 142.324836 -232.334308)
		(width 0.12954)
		(layer "F.Cu")
		(net "M_K_CPU1_SA_DQS_DN<1>")
	)
	(segment
		(start 187.818014 -210.512406)
		(end 188.158628 -210.85302)
		(width 0.16002)
		(layer "In6.Cu")
		(net "M_K_CPU1_SA_DQS_DN<1>")
	)
	(segment
		(start 182.505858 -210.00212)
		(end 182.845456 -209.662522)
		(width 0.16002)
		(layer "In6.Cu")
		(net "M_K_CPU1_SA_DQS_DN<1>")
	)
	(segment
		(start 155.21305 -219.558108)
		(end 163.918138 -210.85302)
		(width 0.16002)
		(layer "In6.Cu")
		(net "M_K_CPU1_SA_DQS_DN<1>")
	)
	(segment
		(start 142.47876 -232.068878)
		(end 142.579598 -232.042208)
		(width 0.09525)
		(layer "In6.Cu")
		(net "M_K_CPU1_SA_DQS_DN<1>")
	)
	(segment
		(start 192.87109 -210.236562)
		(end 195.081906 -210.236562)
		(width 0.16002)
		(layer "In6.Cu")
		(net "M_K_CPU1_SA_DQS_DN<1>")
	)
	(segment
		(start 143.076168 -232.009188)
		(end 143.08455 -232.004362)
		(width 0.09525)
		(layer "In6.Cu")
		(net "M_K_CPU1_SA_DQS_DN<1>")
	)
	(segment
		(start 155.21305 -221.718124)
		(end 155.21305 -219.558108)
		(width 0.16002)
		(layer "In6.Cu")
		(net "M_K_CPU1_SA_DQS_DN<1>")
	)
	(segment
		(start 170.319954 -210.512406)
		(end 172.729906 -210.512406)
		(width 0.16002)
		(layer "In6.Cu")
		(net "M_K_CPU1_SA_DQS_DN<1>")
	)
	(segment
		(start 184.558178 -209.662522)
		(end 185.408062 -210.512406)
		(width 0.16002)
		(layer "In6.Cu")
		(net "M_K_CPU1_SA_DQS_DN<1>")
	)
	(segment
		(start 169.809668 -210.00212)
		(end 170.319954 -210.512406)
		(width 0.16002)
		(layer "In6.Cu")
		(net "M_K_CPU1_SA_DQS_DN<1>")
	)
	(segment
		(start 177.014124 -209.662522)
		(end 177.864008 -210.512406)
		(width 0.16002)
		(layer "In6.Cu")
		(net "M_K_CPU1_SA_DQS_DN<1>")
	)
	(segment
		(start 190.049912 -210.00212)
		(end 190.38951 -209.662522)
		(width 0.16002)
		(layer "In6.Cu")
		(net "M_K_CPU1_SA_DQS_DN<1>")
	)
	(segment
		(start 192.29705 -209.662522)
		(end 192.87109 -210.236562)
		(width 0.16002)
		(layer "In6.Cu")
		(net "M_K_CPU1_SA_DQS_DN<1>")
	)
	(segment
		(start 166.17823 -210.85302)
		(end 167.02913 -210.00212)
		(width 0.16002)
		(layer "In6.Cu")
		(net "M_K_CPU1_SA_DQS_DN<1>")
	)
	(segment
		(start 145.30324 -231.810052)
		(end 146.261328 -230.851964)
		(width 0.09525)
		(layer "In6.Cu")
		(net "M_K_CPU1_SA_DQS_DN<1>")
	)
	(segment
		(start 196.53504 -210.661504)
		(end 198.430388 -210.661504)
		(width 0.16002)
		(layer "In6.Cu")
		(net "M_K_CPU1_SA_DQS_DN<1>")
	)
	(segment
		(start 180.27396 -210.512406)
		(end 180.614574 -210.85302)
		(width 0.16002)
		(layer "In6.Cu")
		(net "M_K_CPU1_SA_DQS_DN<1>")
	)
	(segment
		(start 188.810392 -210.85302)
		(end 189.661292 -210.00212)
		(width 0.16002)
		(layer "In6.Cu")
		(net "M_K_CPU1_SA_DQS_DN<1>")
	)
	(segment
		(start 147.818602 -229.029006)
		(end 147.902422 -229.029006)
		(width 0.09525)
		(layer "In6.Cu")
		(net "M_K_CPU1_SA_DQS_DN<1>")
	)
	(segment
		(start 142.324836 -232.334308)
		(end 142.47876 -232.068878)
		(width 0.09525)
		(layer "In6.Cu")
		(net "M_K_CPU1_SA_DQS_DN<1>")
	)
	(segment
		(start 147.037044 -229.810564)
		(end 147.818602 -229.029006)
		(width 0.09525)
		(layer "In6.Cu")
		(net "M_K_CPU1_SA_DQS_DN<1>")
	)
	(segment
		(start 174.573184 -210.00212)
		(end 174.961804 -210.00212)
		(width 0.16002)
		(layer "In6.Cu")
		(net "M_K_CPU1_SA_DQS_DN<1>")
	)
	(segment
		(start 145.07083 -231.920796)
		(end 145.181574 -231.810052)
		(width 0.09525)
		(layer "In6.Cu")
		(net "M_K_CPU1_SA_DQS_DN<1>")
	)
	(segment
		(start 147.919186 -229.012242)
		(end 151.521922 -225.409506)
		(width 0.16002)
		(layer "In6.Cu")
		(net "M_K_CPU1_SA_DQS_DN<1>")
	)
	(segment
		(start 195.705984 -210.86064)
		(end 196.335904 -210.86064)
		(width 0.16002)
		(layer "In6.Cu")
		(net "M_K_CPU1_SA_DQS_DN<1>")
	)
	(segment
		(start 163.918138 -210.85302)
		(end 166.17823 -210.85302)
		(width 0.16002)
		(layer "In6.Cu")
		(net "M_K_CPU1_SA_DQS_DN<1>")
	)
	(segment
		(start 144.005554 -232.015284)
		(end 144.015968 -232.009188)
		(width 0.09525)
		(layer "In6.Cu")
		(net "M_K_CPU1_SA_DQS_DN<1>")
	)
	(segment
		(start 144.392904 -232.009188)
		(end 144.403318 -232.015284)
		(width 0.09525)
		(layer "In6.Cu")
		(net "M_K_CPU1_SA_DQS_DN<1>")
	)
	(segment
		(start 146.261328 -230.148384)
		(end 146.599148 -229.810564)
		(width 0.09525)
		(layer "In6.Cu")
		(net "M_K_CPU1_SA_DQS_DN<1>")
	)
	(segment
		(start 146.599148 -229.810564)
		(end 147.037044 -229.810564)
		(width 0.09525)
		(layer "In6.Cu")
		(net "M_K_CPU1_SA_DQS_DN<1>")
	)
	(segment
		(start 177.864008 -210.512406)
		(end 180.27396 -210.512406)
		(width 0.16002)
		(layer "In6.Cu")
		(net "M_K_CPU1_SA_DQS_DN<1>")
	)
	(segment
		(start 196.335904 -210.86064)
		(end 196.53504 -210.661504)
		(width 0.16002)
		(layer "In6.Cu")
		(net "M_K_CPU1_SA_DQS_DN<1>")
	)
	(segment
		(start 195.081906 -210.236562)
		(end 195.705984 -210.86064)
		(width 0.16002)
		(layer "In6.Cu")
		(net "M_K_CPU1_SA_DQS_DN<1>")
	)
	(segment
		(start 172.729906 -210.512406)
		(end 173.07052 -210.85302)
		(width 0.16002)
		(layer "In6.Cu")
		(net "M_K_CPU1_SA_DQS_DN<1>")
	)
	(segment
		(start 190.38951 -209.662522)
		(end 192.29705 -209.662522)
		(width 0.16002)
		(layer "In6.Cu")
		(net "M_K_CPU1_SA_DQS_DN<1>")
	)
	(segment
		(start 174.961804 -210.00212)
		(end 175.301402 -209.662522)
		(width 0.16002)
		(layer "In6.Cu")
		(net "M_K_CPU1_SA_DQS_DN<1>")
	)
	(segment
		(start 173.07052 -210.85302)
		(end 173.722284 -210.85302)
		(width 0.16002)
		(layer "In6.Cu")
		(net "M_K_CPU1_SA_DQS_DN<1>")
	)
	(segment
		(start 198.430388 -210.661504)
		(end 198.7042 -210.935316)
		(width 0.16002)
		(layer "In6.Cu")
		(net "M_K_CPU1_SA_DQS_DN<1>")
	)
	(segment
		(start 181.266338 -210.85302)
		(end 182.117238 -210.00212)
		(width 0.16002)
		(layer "In6.Cu")
		(net "M_K_CPU1_SA_DQS_DN<1>")
	)
	(segment
		(start 151.521922 -225.409506)
		(end 151.521922 -225.409252)
		(width 0.16002)
		(layer "In6.Cu")
		(net "M_K_CPU1_SA_DQS_DN<1>")
	)
	(segment
		(start 175.301402 -209.662522)
		(end 177.014124 -209.662522)
		(width 0.16002)
		(layer "In6.Cu")
		(net "M_K_CPU1_SA_DQS_DN<1>")
	)
	(segment
		(start 167.02913 -210.00212)
		(end 169.809668 -210.00212)
		(width 0.16002)
		(layer "In6.Cu")
		(net "M_K_CPU1_SA_DQS_DN<1>")
	)
	(segment
		(start 180.614574 -210.85302)
		(end 181.266338 -210.85302)
		(width 0.16002)
		(layer "In6.Cu")
		(net "M_K_CPU1_SA_DQS_DN<1>")
	)
	(segment
		(start 151.521922 -225.409252)
		(end 155.21305 -221.718124)
		(width 0.16002)
		(layer "In6.Cu")
		(net "M_K_CPU1_SA_DQS_DN<1>")
	)
	(segment
		(start 185.408062 -210.512406)
		(end 187.818014 -210.512406)
		(width 0.16002)
		(layer "In6.Cu")
		(net "M_K_CPU1_SA_DQS_DN<1>")
	)
	(segment
		(start 182.845456 -209.662522)
		(end 184.558178 -209.662522)
		(width 0.16002)
		(layer "In6.Cu")
		(net "M_K_CPU1_SA_DQS_DN<1>")
	)
	(segment
		(start 146.261328 -230.851964)
		(end 146.261328 -230.148384)
		(width 0.09525)
		(layer "In6.Cu")
		(net "M_K_CPU1_SA_DQS_DN<1>")
	)
	(segment
		(start 188.158628 -210.85302)
		(end 188.810392 -210.85302)
		(width 0.16002)
		(layer "In6.Cu")
		(net "M_K_CPU1_SA_DQS_DN<1>")
	)
	(segment
		(start 145.181574 -231.810052)
		(end 145.30324 -231.810052)
		(width 0.09525)
		(layer "In6.Cu")
		(net "M_K_CPU1_SA_DQS_DN<1>")
	)
	(segment
		(start 173.722284 -210.85302)
		(end 174.573184 -210.00212)
		(width 0.16002)
		(layer "In6.Cu")
		(net "M_K_CPU1_SA_DQS_DN<1>")
	)
	(segment
		(start 189.661292 -210.00212)
		(end 190.049912 -210.00212)
		(width 0.16002)
		(layer "In6.Cu")
		(net "M_K_CPU1_SA_DQS_DN<1>")
	)
	(segment
		(start 182.117238 -210.00212)
		(end 182.505858 -210.00212)
		(width 0.16002)
		(layer "In6.Cu")
		(net "M_K_CPU1_SA_DQS_DN<1>")
	)
	(segment
		(start 147.902422 -229.029006)
		(end 147.919186 -229.012242)
		(width 0.09525)
		(layer "In6.Cu")
		(net "M_K_CPU1_SA_DQS_DN<1>")
	)
	(arc
		(start 143.08455 -232.004362)
		(mid 143.269582 -231.958448)
		(end 143.453358 -232.009188)
		(width 0.09525)
		(layer "In6.Cu")
		(net "M_K_CPU1_SA_DQS_DN<1>")
	)
	(arc
		(start 144.956022 -232.009188)
		(mid 145.016289 -231.968711)
		(end 145.07083 -231.920796)
		(width 0.09525)
		(layer "In6.Cu")
		(net "M_K_CPU1_SA_DQS_DN<1>")
	)
	(arc
		(start 144.015968 -232.009188)
		(mid 144.204436 -231.958511)
		(end 144.392904 -232.009188)
		(width 0.09525)
		(layer "In6.Cu")
		(net "M_K_CPU1_SA_DQS_DN<1>")
	)
	(arc
		(start 143.453358 -232.009188)
		(mid 143.728647 -232.084909)
		(end 144.005554 -232.015284)
		(width 0.09525)
		(layer "In6.Cu")
		(net "M_K_CPU1_SA_DQS_DN<1>")
	)
	(arc
		(start 144.403318 -232.015284)
		(mid 144.68048 -232.085084)
		(end 144.956022 -232.009188)
		(width 0.09525)
		(layer "In6.Cu")
		(net "M_K_CPU1_SA_DQS_DN<1>")
	)
	(arc
		(start 142.579598 -232.042208)
		(mid 142.831739 -232.083778)
		(end 143.076168 -232.009188)
		(width 0.09525)
		(layer "In6.Cu")
		(net "M_K_CPU1_SA_DQS_DN<1>")
	)
	(segment
		(start 141.857984 -227.740464)
		(end 142.324836 -227.474526)
		(width 0.12954)
		(layer "F.Cu")
		(net "M_K_CPU1_SA_DQS_DN<0>")
	)
	(segment
		(start 144.956276 -225.529394)
		(end 144.991328 -225.50882)
		(width 0.09525)
		(layer "In6.Cu")
		(net "M_K_CPU1_SA_DQS_DN<0>")
	)
	(segment
		(start 149.25675 -218.947746)
		(end 149.25675 -216.044526)
		(width 0.16002)
		(layer "In6.Cu")
		(net "M_K_CPU1_SA_DQS_DN<0>")
	)
	(segment
		(start 175.301402 -200.312528)
		(end 177.014124 -200.312528)
		(width 0.16002)
		(layer "In6.Cu")
		(net "M_K_CPU1_SA_DQS_DN<0>")
	)
	(segment
		(start 190.049912 -200.652126)
		(end 190.38951 -200.312528)
		(width 0.16002)
		(layer "In6.Cu")
		(net "M_K_CPU1_SA_DQS_DN<0>")
	)
	(segment
		(start 144.956276 -223.909382)
		(end 144.991328 -223.888808)
		(width 0.09525)
		(layer "In6.Cu")
		(net "M_K_CPU1_SA_DQS_DN<0>")
	)
	(segment
		(start 190.38951 -200.312528)
		(end 192.29705 -200.312528)
		(width 0.16002)
		(layer "In6.Cu")
		(net "M_K_CPU1_SA_DQS_DN<0>")
	)
	(segment
		(start 144.956276 -224.559622)
		(end 144.923764 -224.540826)
		(width 0.09525)
		(layer "In6.Cu")
		(net "M_K_CPU1_SA_DQS_DN<0>")
	)
	(segment
		(start 173.722284 -201.503026)
		(end 174.573184 -200.652126)
		(width 0.16002)
		(layer "In6.Cu")
		(net "M_K_CPU1_SA_DQS_DN<0>")
	)
	(segment
		(start 192.29705 -200.312528)
		(end 192.87109 -200.886568)
		(width 0.16002)
		(layer "In6.Cu")
		(net "M_K_CPU1_SA_DQS_DN<0>")
	)
	(segment
		(start 181.266338 -201.503026)
		(end 182.117238 -200.652126)
		(width 0.16002)
		(layer "In6.Cu")
		(net "M_K_CPU1_SA_DQS_DN<0>")
	)
	(segment
		(start 177.014124 -200.312528)
		(end 177.864008 -201.162412)
		(width 0.16002)
		(layer "In6.Cu")
		(net "M_K_CPU1_SA_DQS_DN<0>")
	)
	(segment
		(start 182.845456 -200.312528)
		(end 184.558178 -200.312528)
		(width 0.16002)
		(layer "In6.Cu")
		(net "M_K_CPU1_SA_DQS_DN<0>")
	)
	(segment
		(start 189.661292 -200.652126)
		(end 190.049912 -200.652126)
		(width 0.16002)
		(layer "In6.Cu")
		(net "M_K_CPU1_SA_DQS_DN<0>")
	)
	(segment
		(start 188.158628 -201.503026)
		(end 188.810392 -201.503026)
		(width 0.16002)
		(layer "In6.Cu")
		(net "M_K_CPU1_SA_DQS_DN<0>")
	)
	(segment
		(start 147.705572 -220.498924)
		(end 149.25675 -218.947746)
		(width 0.16002)
		(layer "In6.Cu")
		(net "M_K_CPU1_SA_DQS_DN<0>")
	)
	(segment
		(start 167.757348 -200.312528)
		(end 169.47007 -200.312528)
		(width 0.16002)
		(layer "In6.Cu")
		(net "M_K_CPU1_SA_DQS_DN<0>")
	)
	(segment
		(start 166.17823 -201.503026)
		(end 167.02913 -200.652126)
		(width 0.16002)
		(layer "In6.Cu")
		(net "M_K_CPU1_SA_DQS_DN<0>")
	)
	(segment
		(start 182.505858 -200.652126)
		(end 182.845456 -200.312528)
		(width 0.16002)
		(layer "In6.Cu")
		(net "M_K_CPU1_SA_DQS_DN<0>")
	)
	(segment
		(start 196.335904 -201.510646)
		(end 196.53504 -201.31151)
		(width 0.16002)
		(layer "In6.Cu")
		(net "M_K_CPU1_SA_DQS_DN<0>")
	)
	(segment
		(start 163.79825 -201.503026)
		(end 166.17823 -201.503026)
		(width 0.16002)
		(layer "In6.Cu")
		(net "M_K_CPU1_SA_DQS_DN<0>")
	)
	(segment
		(start 172.729906 -201.162412)
		(end 173.07052 -201.503026)
		(width 0.16002)
		(layer "In6.Cu")
		(net "M_K_CPU1_SA_DQS_DN<0>")
	)
	(segment
		(start 167.41775 -200.652126)
		(end 167.757348 -200.312528)
		(width 0.16002)
		(layer "In6.Cu")
		(net "M_K_CPU1_SA_DQS_DN<0>")
	)
	(segment
		(start 177.864008 -201.162412)
		(end 180.27396 -201.162412)
		(width 0.16002)
		(layer "In6.Cu")
		(net "M_K_CPU1_SA_DQS_DN<0>")
	)
	(segment
		(start 144.486122 -226.3394)
		(end 144.524222 -226.317302)
		(width 0.09525)
		(layer "In6.Cu")
		(net "M_K_CPU1_SA_DQS_DN<0>")
	)
	(segment
		(start 188.810392 -201.503026)
		(end 189.661292 -200.652126)
		(width 0.16002)
		(layer "In6.Cu")
		(net "M_K_CPU1_SA_DQS_DN<0>")
	)
	(segment
		(start 144.454626 -226.357688)
		(end 144.486122 -226.3394)
		(width 0.09525)
		(layer "In6.Cu")
		(net "M_K_CPU1_SA_DQS_DN<0>")
	)
	(segment
		(start 145.706592 -222.414846)
		(end 146.14271 -221.978728)
		(width 0.09525)
		(layer "In6.Cu")
		(net "M_K_CPU1_SA_DQS_DN<0>")
	)
	(segment
		(start 182.117238 -200.652126)
		(end 182.505858 -200.652126)
		(width 0.16002)
		(layer "In6.Cu")
		(net "M_K_CPU1_SA_DQS_DN<0>")
	)
	(segment
		(start 195.705984 -201.510646)
		(end 196.335904 -201.510646)
		(width 0.16002)
		(layer "In6.Cu")
		(net "M_K_CPU1_SA_DQS_DN<0>")
	)
	(segment
		(start 146.14271 -221.978728)
		(end 146.226022 -221.978728)
		(width 0.09525)
		(layer "In6.Cu")
		(net "M_K_CPU1_SA_DQS_DN<0>")
	)
	(segment
		(start 167.02913 -200.652126)
		(end 167.41775 -200.652126)
		(width 0.16002)
		(layer "In6.Cu")
		(net "M_K_CPU1_SA_DQS_DN<0>")
	)
	(segment
		(start 170.319954 -201.162412)
		(end 172.729906 -201.162412)
		(width 0.16002)
		(layer "In6.Cu")
		(net "M_K_CPU1_SA_DQS_DN<0>")
	)
	(segment
		(start 144.016222 -227.149406)
		(end 144.054322 -227.127308)
		(width 0.09525)
		(layer "In6.Cu")
		(net "M_K_CPU1_SA_DQS_DN<0>")
	)
	(segment
		(start 145.46326 -223.077532)
		(end 145.465292 -223.076262)
		(width 0.09525)
		(layer "In6.Cu")
		(net "M_K_CPU1_SA_DQS_DN<0>")
	)
	(segment
		(start 187.818014 -201.162412)
		(end 188.158628 -201.503026)
		(width 0.16002)
		(layer "In6.Cu")
		(net "M_K_CPU1_SA_DQS_DN<0>")
	)
	(segment
		(start 146.226022 -221.978728)
		(end 146.242786 -221.961964)
		(width 0.09525)
		(layer "In6.Cu")
		(net "M_K_CPU1_SA_DQS_DN<0>")
	)
	(segment
		(start 180.27396 -201.162412)
		(end 180.614574 -201.503026)
		(width 0.16002)
		(layer "In6.Cu")
		(net "M_K_CPU1_SA_DQS_DN<0>")
	)
	(segment
		(start 184.558178 -200.312528)
		(end 185.408062 -201.162412)
		(width 0.16002)
		(layer "In6.Cu")
		(net "M_K_CPU1_SA_DQS_DN<0>")
	)
	(segment
		(start 142.324836 -227.474526)
		(end 142.47876 -227.209096)
		(width 0.09525)
		(layer "In6.Cu")
		(net "M_K_CPU1_SA_DQS_DN<0>")
	)
	(segment
		(start 146.242786 -221.961964)
		(end 147.705572 -220.499178)
		(width 0.16002)
		(layer "In6.Cu")
		(net "M_K_CPU1_SA_DQS_DN<0>")
	)
	(segment
		(start 173.07052 -201.503026)
		(end 173.722284 -201.503026)
		(width 0.16002)
		(layer "In6.Cu")
		(net "M_K_CPU1_SA_DQS_DN<0>")
	)
	(segment
		(start 174.961804 -200.652126)
		(end 175.301402 -200.312528)
		(width 0.16002)
		(layer "In6.Cu")
		(net "M_K_CPU1_SA_DQS_DN<0>")
	)
	(segment
		(start 144.923764 -225.54819)
		(end 144.956276 -225.529394)
		(width 0.09525)
		(layer "In6.Cu")
		(net "M_K_CPU1_SA_DQS_DN<0>")
	)
	(segment
		(start 144.991328 -224.580196)
		(end 144.956276 -224.559622)
		(width 0.09525)
		(layer "In6.Cu")
		(net "M_K_CPU1_SA_DQS_DN<0>")
	)
	(segment
		(start 143.076168 -227.149406)
		(end 143.08455 -227.14458)
		(width 0.09525)
		(layer "In6.Cu")
		(net "M_K_CPU1_SA_DQS_DN<0>")
	)
	(segment
		(start 142.47876 -227.209096)
		(end 142.579598 -227.182426)
		(width 0.09525)
		(layer "In6.Cu")
		(net "M_K_CPU1_SA_DQS_DN<0>")
	)
	(segment
		(start 180.614574 -201.503026)
		(end 181.266338 -201.503026)
		(width 0.16002)
		(layer "In6.Cu")
		(net "M_K_CPU1_SA_DQS_DN<0>")
	)
	(segment
		(start 195.081906 -200.886568)
		(end 195.705984 -201.510646)
		(width 0.16002)
		(layer "In6.Cu")
		(net "M_K_CPU1_SA_DQS_DN<0>")
	)
	(segment
		(start 192.87109 -200.886568)
		(end 195.081906 -200.886568)
		(width 0.16002)
		(layer "In6.Cu")
		(net "M_K_CPU1_SA_DQS_DN<0>")
	)
	(segment
		(start 144.923764 -223.928178)
		(end 144.956276 -223.909382)
		(width 0.09525)
		(layer "In6.Cu")
		(net "M_K_CPU1_SA_DQS_DN<0>")
	)
	(segment
		(start 145.393664 -223.118172)
		(end 145.461228 -223.078802)
		(width 0.09525)
		(layer "In6.Cu")
		(net "M_K_CPU1_SA_DQS_DN<0>")
	)
	(segment
		(start 174.573184 -200.652126)
		(end 174.961804 -200.652126)
		(width 0.16002)
		(layer "In6.Cu")
		(net "M_K_CPU1_SA_DQS_DN<0>")
	)
	(segment
		(start 147.705572 -220.499178)
		(end 147.705572 -220.498924)
		(width 0.16002)
		(layer "In6.Cu")
		(net "M_K_CPU1_SA_DQS_DN<0>")
	)
	(segment
		(start 149.25675 -216.044526)
		(end 163.79825 -201.503026)
		(width 0.16002)
		(layer "In6.Cu")
		(net "M_K_CPU1_SA_DQS_DN<0>")
	)
	(segment
		(start 169.47007 -200.312528)
		(end 170.319954 -201.162412)
		(width 0.16002)
		(layer "In6.Cu")
		(net "M_K_CPU1_SA_DQS_DN<0>")
	)
	(segment
		(start 198.430388 -201.31151)
		(end 198.7042 -201.585322)
		(width 0.16002)
		(layer "In6.Cu")
		(net "M_K_CPU1_SA_DQS_DN<0>")
	)
	(segment
		(start 196.53504 -201.31151)
		(end 198.430388 -201.31151)
		(width 0.16002)
		(layer "In6.Cu")
		(net "M_K_CPU1_SA_DQS_DN<0>")
	)
	(segment
		(start 185.408062 -201.162412)
		(end 187.818014 -201.162412)
		(width 0.16002)
		(layer "In6.Cu")
		(net "M_K_CPU1_SA_DQS_DN<0>")
	)
	(segment
		(start 145.706592 -222.61449)
		(end 145.706592 -222.414846)
		(width 0.09525)
		(layer "In6.Cu")
		(net "M_K_CPU1_SA_DQS_DN<0>")
	)
	(arc
		(start 142.579598 -227.182426)
		(mid 142.589466 -227.186457)
		(end 142.59941 -227.1903)
		(width 0.09525)
		(layer "In6.Cu")
		(net "M_K_CPU1_SA_DQS_DN<0>")
	)
	(arc
		(start 143.08455 -227.14458)
		(mid 143.269582 -227.098666)
		(end 143.453358 -227.149406)
		(width 0.09525)
		(layer "In6.Cu")
		(net "M_K_CPU1_SA_DQS_DN<0>")
	)
	(arc
		(start 144.054322 -227.127308)
		(mid 144.232772 -226.925838)
		(end 144.297146 -226.66452)
		(width 0.09525)
		(layer "In6.Cu")
		(net "M_K_CPU1_SA_DQS_DN<0>")
	)
	(arc
		(start 145.465292 -223.076262)
		(mid 145.642657 -222.875018)
		(end 145.706592 -222.61449)
		(width 0.09525)
		(layer "In6.Cu")
		(net "M_K_CPU1_SA_DQS_DN<0>")
	)
	(arc
		(start 144.767046 -225.854514)
		(mid 144.808503 -225.682474)
		(end 144.923764 -225.54819)
		(width 0.09525)
		(layer "In6.Cu")
		(net "M_K_CPU1_SA_DQS_DN<0>")
	)
	(arc
		(start 145.236946 -225.044508)
		(mid 145.171699 -224.781905)
		(end 144.991328 -224.580196)
		(width 0.09525)
		(layer "In6.Cu")
		(net "M_K_CPU1_SA_DQS_DN<0>")
	)
	(arc
		(start 144.923764 -224.540826)
		(mid 144.767032 -224.234502)
		(end 144.923764 -223.928178)
		(width 0.09525)
		(layer "In6.Cu")
		(net "M_K_CPU1_SA_DQS_DN<0>")
	)
	(arc
		(start 144.297146 -226.66452)
		(mid 144.338811 -226.492073)
		(end 144.454626 -226.357688)
		(width 0.09525)
		(layer "In6.Cu")
		(net "M_K_CPU1_SA_DQS_DN<0>")
	)
	(arc
		(start 142.59941 -227.1903)
		(mid 142.842374 -227.223287)
		(end 143.076168 -227.149406)
		(width 0.09525)
		(layer "In6.Cu")
		(net "M_K_CPU1_SA_DQS_DN<0>")
	)
	(arc
		(start 145.461228 -223.078802)
		(mid 145.462245 -223.078168)
		(end 145.46326 -223.077532)
		(width 0.09525)
		(layer "In6.Cu")
		(net "M_K_CPU1_SA_DQS_DN<0>")
	)
	(arc
		(start 145.236946 -223.424496)
		(mid 145.278403 -223.252456)
		(end 145.393664 -223.118172)
		(width 0.09525)
		(layer "In6.Cu")
		(net "M_K_CPU1_SA_DQS_DN<0>")
	)
	(arc
		(start 144.524222 -226.317302)
		(mid 144.702672 -226.115832)
		(end 144.767046 -225.854514)
		(width 0.09525)
		(layer "In6.Cu")
		(net "M_K_CPU1_SA_DQS_DN<0>")
	)
	(arc
		(start 144.991328 -223.888808)
		(mid 145.171719 -223.687109)
		(end 145.236946 -223.424496)
		(width 0.09525)
		(layer "In6.Cu")
		(net "M_K_CPU1_SA_DQS_DN<0>")
	)
	(arc
		(start 144.991328 -225.50882)
		(mid 145.171719 -225.307121)
		(end 145.236946 -225.044508)
		(width 0.09525)
		(layer "In6.Cu")
		(net "M_K_CPU1_SA_DQS_DN<0>")
	)
	(arc
		(start 143.453358 -227.149406)
		(mid 143.73479 -227.225161)
		(end 144.016222 -227.149406)
		(width 0.09525)
		(layer "In6.Cu")
		(net "M_K_CPU1_SA_DQS_DN<0>")
	)
	(segment
		(start 140.91793 -230.980234)
		(end 141.384782 -230.71455)
		(width 0.10668)
		(layer "F.Cu")
		(net "M_K_CPU1_SA_DQ<9>")
	)
	(segment
		(start 171.601638 -208.810352)
		(end 172.774356 -208.810352)
		(width 0.14478)
		(layer "In6.Cu")
		(net "M_K_CPU1_SA_DQ<9>")
	)
	(segment
		(start 141.384782 -230.71455)
		(end 141.230858 -230.97998)
		(width 0.0889)
		(layer "In6.Cu")
		(net "M_K_CPU1_SA_DQ<9>")
	)
	(segment
		(start 147.141946 -228.33965)
		(end 147.141946 -227.908358)
		(width 0.0889)
		(layer "In6.Cu")
		(net "M_K_CPU1_SA_DQ<9>")
	)
	(segment
		(start 153.741628 -221.308676)
		(end 153.741628 -219.081096)
		(width 0.14478)
		(layer "In6.Cu")
		(net "M_K_CPU1_SA_DQ<9>")
	)
	(segment
		(start 153.741628 -219.081096)
		(end 164.012372 -208.810352)
		(width 0.14478)
		(layer "In6.Cu")
		(net "M_K_CPU1_SA_DQ<9>")
	)
	(segment
		(start 147.84832 -227.201984)
		(end 153.741628 -221.308676)
		(width 0.14478)
		(layer "In6.Cu")
		(net "M_K_CPU1_SA_DQ<9>")
	)
	(segment
		(start 146.294348 -229.175564)
		(end 146.647408 -229.175564)
		(width 0.0889)
		(layer "In6.Cu")
		(net "M_K_CPU1_SA_DQ<9>")
	)
	(segment
		(start 177.089054 -207.960468)
		(end 179.140866 -208.810352)
		(width 0.14478)
		(layer "In6.Cu")
		(net "M_K_CPU1_SA_DQ<9>")
	)
	(segment
		(start 189.451996 -208.159604)
		(end 189.932818 -207.960468)
		(width 0.14478)
		(layer "In6.Cu")
		(net "M_K_CPU1_SA_DQ<9>")
	)
	(segment
		(start 172.774356 -208.810352)
		(end 174.199804 -208.219802)
		(width 0.14478)
		(layer "In6.Cu")
		(net "M_K_CPU1_SA_DQ<9>")
	)
	(segment
		(start 147.141946 -227.908358)
		(end 147.84832 -227.201984)
		(width 0.0889)
		(layer "In6.Cu")
		(net "M_K_CPU1_SA_DQ<9>")
	)
	(segment
		(start 167.263318 -207.960214)
		(end 169.549064 -207.960214)
		(width 0.14478)
		(layer "In6.Cu")
		(net "M_K_CPU1_SA_DQ<9>")
	)
	(segment
		(start 198.279258 -207.960468)
		(end 198.7042 -208.38541)
		(width 0.14478)
		(layer "In6.Cu")
		(net "M_K_CPU1_SA_DQ<9>")
	)
	(segment
		(start 179.140866 -208.810352)
		(end 180.2892 -208.810352)
		(width 0.14478)
		(layer "In6.Cu")
		(net "M_K_CPU1_SA_DQ<9>")
	)
	(segment
		(start 189.932818 -207.960468)
		(end 198.279258 -207.960468)
		(width 0.14478)
		(layer "In6.Cu")
		(net "M_K_CPU1_SA_DQ<9>")
	)
	(segment
		(start 145.67408 -229.795832)
		(end 146.294348 -229.175564)
		(width 0.0889)
		(layer "In6.Cu")
		(net "M_K_CPU1_SA_DQ<9>")
	)
	(segment
		(start 182.341012 -207.960468)
		(end 184.650126 -207.960468)
		(width 0.14478)
		(layer "In6.Cu")
		(net "M_K_CPU1_SA_DQ<9>")
	)
	(segment
		(start 142.503398 -231.041702)
		(end 142.51178 -231.036876)
		(width 0.0889)
		(layer "In6.Cu")
		(net "M_K_CPU1_SA_DQ<9>")
	)
	(segment
		(start 186.701684 -208.810352)
		(end 187.880752 -208.810352)
		(width 0.14478)
		(layer "In6.Cu")
		(net "M_K_CPU1_SA_DQ<9>")
	)
	(segment
		(start 146.647408 -229.175564)
		(end 146.900646 -228.922326)
		(width 0.0889)
		(layer "In6.Cu")
		(net "M_K_CPU1_SA_DQ<9>")
	)
	(segment
		(start 174.825914 -207.960468)
		(end 177.089054 -207.960468)
		(width 0.14478)
		(layer "In6.Cu")
		(net "M_K_CPU1_SA_DQ<9>")
	)
	(segment
		(start 174.199804 -208.219802)
		(end 174.825914 -207.960468)
		(width 0.14478)
		(layer "In6.Cu")
		(net "M_K_CPU1_SA_DQ<9>")
	)
	(segment
		(start 187.880752 -208.810352)
		(end 189.451996 -208.159604)
		(width 0.14478)
		(layer "In6.Cu")
		(net "M_K_CPU1_SA_DQ<9>")
	)
	(segment
		(start 184.650126 -207.960468)
		(end 186.701684 -208.810352)
		(width 0.14478)
		(layer "In6.Cu")
		(net "M_K_CPU1_SA_DQ<9>")
	)
	(segment
		(start 146.900646 -228.922326)
		(end 147.141946 -228.33965)
		(width 0.0889)
		(layer "In6.Cu")
		(net "M_K_CPU1_SA_DQ<9>")
	)
	(segment
		(start 143.077692 -231.036876)
		(end 143.086074 -231.041702)
		(width 0.0889)
		(layer "In6.Cu")
		(net "M_K_CPU1_SA_DQ<9>")
	)
	(segment
		(start 169.549064 -207.960214)
		(end 171.601638 -208.810352)
		(width 0.14478)
		(layer "In6.Cu")
		(net "M_K_CPU1_SA_DQ<9>")
	)
	(segment
		(start 180.2892 -208.810352)
		(end 181.743096 -208.208118)
		(width 0.14478)
		(layer "In6.Cu")
		(net "M_K_CPU1_SA_DQ<9>")
	)
	(segment
		(start 165.210744 -208.810352)
		(end 167.263318 -207.960214)
		(width 0.14478)
		(layer "In6.Cu")
		(net "M_K_CPU1_SA_DQ<9>")
	)
	(segment
		(start 144.171924 -230.779574)
		(end 144.568672 -230.382826)
		(width 0.0889)
		(layer "In6.Cu")
		(net "M_K_CPU1_SA_DQ<9>")
	)
	(segment
		(start 164.012372 -208.810352)
		(end 165.210744 -208.810352)
		(width 0.14478)
		(layer "In6.Cu")
		(net "M_K_CPU1_SA_DQ<9>")
	)
	(segment
		(start 181.743096 -208.208118)
		(end 182.341012 -207.960468)
		(width 0.14478)
		(layer "In6.Cu")
		(net "M_K_CPU1_SA_DQ<9>")
	)
	(segment
		(start 141.230858 -230.97998)
		(end 141.252956 -231.063038)
		(width 0.0889)
		(layer "In6.Cu")
		(net "M_K_CPU1_SA_DQ<9>")
	)
	(arc
		(start 141.571726 -231.036876)
		(mid 141.854682 -230.960699)
		(end 142.137638 -231.036876)
		(width 0.0889)
		(layer "In6.Cu")
		(net "M_K_CPU1_SA_DQ<9>")
	)
	(arc
		(start 142.51178 -231.036876)
		(mid 142.794736 -230.960699)
		(end 143.077692 -231.036876)
		(width 0.0889)
		(layer "In6.Cu")
		(net "M_K_CPU1_SA_DQ<9>")
	)
	(arc
		(start 143.73479 -230.960676)
		(mid 143.971379 -230.913616)
		(end 144.171924 -230.779574)
		(width 0.0889)
		(layer "In6.Cu")
		(net "M_K_CPU1_SA_DQ<9>")
	)
	(arc
		(start 143.086074 -231.041702)
		(mid 143.269582 -231.087227)
		(end 143.451834 -231.036876)
		(width 0.0889)
		(layer "In6.Cu")
		(net "M_K_CPU1_SA_DQ<9>")
	)
	(arc
		(start 141.252956 -231.063038)
		(mid 141.415287 -231.085887)
		(end 141.571726 -231.036876)
		(width 0.0889)
		(layer "In6.Cu")
		(net "M_K_CPU1_SA_DQ<9>")
	)
	(arc
		(start 142.137638 -231.036876)
		(mid 142.319889 -231.08726)
		(end 142.503398 -231.041702)
		(width 0.0889)
		(layer "In6.Cu")
		(net "M_K_CPU1_SA_DQ<9>")
	)
	(arc
		(start 144.568672 -230.382826)
		(mid 144.825254 -230.195513)
		(end 145.12671 -230.095298)
		(width 0.0889)
		(layer "In6.Cu")
		(net "M_K_CPU1_SA_DQ<9>")
	)
	(arc
		(start 145.12671 -230.095298)
		(mid 145.42568 -229.991773)
		(end 145.67408 -229.795832)
		(width 0.0889)
		(layer "In6.Cu")
		(net "M_K_CPU1_SA_DQ<9>")
	)
	(arc
		(start 143.451834 -231.036876)
		(mid 143.58827 -230.980051)
		(end 143.73479 -230.960676)
		(width 0.0889)
		(layer "In6.Cu")
		(net "M_K_CPU1_SA_DQ<9>")
	)
	(segment
		(start 142.327884 -230.170228)
		(end 142.794736 -229.90429)
		(width 0.10668)
		(layer "F.Cu")
		(net "M_K_CPU1_SA_DQ<8>")
	)
	(segment
		(start 166.106348 -207.11033)
		(end 166.956486 -206.260192)
		(width 0.14478)
		(layer "In6.Cu")
		(net "M_K_CPU1_SA_DQ<8>")
	)
	(segment
		(start 146.159728 -228.642164)
		(end 146.159728 -228.164136)
		(width 0.0889)
		(layer "In6.Cu")
		(net "M_K_CPU1_SA_DQ<8>")
	)
	(segment
		(start 142.794736 -229.90429)
		(end 142.640812 -230.16972)
		(width 0.0889)
		(layer "In6.Cu")
		(net "M_K_CPU1_SA_DQ<8>")
	)
	(segment
		(start 166.956486 -206.260192)
		(end 169.907966 -206.260192)
		(width 0.14478)
		(layer "In6.Cu")
		(net "M_K_CPU1_SA_DQ<8>")
	)
	(segment
		(start 145.191988 -229.609904)
		(end 146.159728 -228.642164)
		(width 0.0889)
		(layer "In6.Cu")
		(net "M_K_CPU1_SA_DQ<8>")
	)
	(segment
		(start 182.633874 -206.260446)
		(end 184.3659 -206.260446)
		(width 0.14478)
		(layer "In6.Cu")
		(net "M_K_CPU1_SA_DQ<8>")
	)
	(segment
		(start 198.279258 -206.260446)
		(end 198.7042 -206.685388)
		(width 0.14478)
		(layer "In6.Cu")
		(net "M_K_CPU1_SA_DQ<8>")
	)
	(segment
		(start 190.14694 -206.260446)
		(end 198.279258 -206.260446)
		(width 0.14478)
		(layer "In6.Cu")
		(net "M_K_CPU1_SA_DQ<8>")
	)
	(segment
		(start 180.581808 -207.11033)
		(end 181.536086 -206.715106)
		(width 0.14478)
		(layer "In6.Cu")
		(net "M_K_CPU1_SA_DQ<8>")
	)
	(segment
		(start 147.87372 -225.890328)
		(end 152.832308 -220.93174)
		(width 0.14478)
		(layer "In6.Cu")
		(net "M_K_CPU1_SA_DQ<8>")
	)
	(segment
		(start 152.832308 -218.631516)
		(end 164.353494 -207.11033)
		(width 0.14478)
		(layer "In6.Cu")
		(net "M_K_CPU1_SA_DQ<8>")
	)
	(segment
		(start 147.177506 -226.586542)
		(end 147.87372 -225.890328)
		(width 0.0889)
		(layer "In6.Cu")
		(net "M_K_CPU1_SA_DQ<8>")
	)
	(segment
		(start 173.609254 -207.11033)
		(end 174.459138 -206.260446)
		(width 0.14478)
		(layer "In6.Cu")
		(net "M_K_CPU1_SA_DQ<8>")
	)
	(segment
		(start 184.3659 -206.260446)
		(end 186.417712 -207.11033)
		(width 0.14478)
		(layer "In6.Cu")
		(net "M_K_CPU1_SA_DQ<8>")
	)
	(segment
		(start 188.095128 -207.11033)
		(end 189.300612 -206.610966)
		(width 0.14478)
		(layer "In6.Cu")
		(net "M_K_CPU1_SA_DQ<8>")
	)
	(segment
		(start 146.159728 -228.164136)
		(end 147.177506 -227.146358)
		(width 0.0889)
		(layer "In6.Cu")
		(net "M_K_CPU1_SA_DQ<8>")
	)
	(segment
		(start 169.907966 -206.260192)
		(end 170.758104 -207.11033)
		(width 0.14478)
		(layer "In6.Cu")
		(net "M_K_CPU1_SA_DQ<8>")
	)
	(segment
		(start 177.452274 -206.260446)
		(end 178.302158 -207.11033)
		(width 0.14478)
		(layer "In6.Cu")
		(net "M_K_CPU1_SA_DQ<8>")
	)
	(segment
		(start 164.353494 -207.11033)
		(end 166.106348 -207.11033)
		(width 0.14478)
		(layer "In6.Cu")
		(net "M_K_CPU1_SA_DQ<8>")
	)
	(segment
		(start 142.640812 -230.16972)
		(end 142.663164 -230.253032)
		(width 0.0889)
		(layer "In6.Cu")
		(net "M_K_CPU1_SA_DQ<8>")
	)
	(segment
		(start 178.302158 -207.11033)
		(end 180.581808 -207.11033)
		(width 0.14478)
		(layer "In6.Cu")
		(net "M_K_CPU1_SA_DQ<8>")
	)
	(segment
		(start 143.998442 -230.167942)
		(end 144.55648 -229.609904)
		(width 0.0889)
		(layer "In6.Cu")
		(net "M_K_CPU1_SA_DQ<8>")
	)
	(segment
		(start 144.55648 -229.609904)
		(end 145.191988 -229.609904)
		(width 0.0889)
		(layer "In6.Cu")
		(net "M_K_CPU1_SA_DQ<8>")
	)
	(segment
		(start 181.536086 -206.715106)
		(end 182.633874 -206.260446)
		(width 0.14478)
		(layer "In6.Cu")
		(net "M_K_CPU1_SA_DQ<8>")
	)
	(segment
		(start 147.177506 -227.146358)
		(end 147.177506 -226.586542)
		(width 0.0889)
		(layer "In6.Cu")
		(net "M_K_CPU1_SA_DQ<8>")
	)
	(segment
		(start 170.758104 -207.11033)
		(end 173.609254 -207.11033)
		(width 0.14478)
		(layer "In6.Cu")
		(net "M_K_CPU1_SA_DQ<8>")
	)
	(segment
		(start 189.300612 -206.610966)
		(end 190.14694 -206.260446)
		(width 0.14478)
		(layer "In6.Cu")
		(net "M_K_CPU1_SA_DQ<8>")
	)
	(segment
		(start 174.459138 -206.260446)
		(end 177.452274 -206.260446)
		(width 0.14478)
		(layer "In6.Cu")
		(net "M_K_CPU1_SA_DQ<8>")
	)
	(segment
		(start 152.832308 -220.93174)
		(end 152.832308 -218.631516)
		(width 0.14478)
		(layer "In6.Cu")
		(net "M_K_CPU1_SA_DQ<8>")
	)
	(segment
		(start 186.417712 -207.11033)
		(end 188.095128 -207.11033)
		(width 0.14478)
		(layer "In6.Cu")
		(net "M_K_CPU1_SA_DQ<8>")
	)
	(arc
		(start 142.663164 -230.253032)
		(mid 142.825353 -230.275767)
		(end 142.98168 -230.22687)
		(width 0.0889)
		(layer "In6.Cu")
		(net "M_K_CPU1_SA_DQ<8>")
	)
	(arc
		(start 143.547592 -230.22687)
		(mid 143.783061 -230.274115)
		(end 143.998442 -230.167942)
		(width 0.0889)
		(layer "In6.Cu")
		(net "M_K_CPU1_SA_DQ<8>")
	)
	(arc
		(start 142.98168 -230.22687)
		(mid 143.264636 -230.150727)
		(end 143.547592 -230.22687)
		(width 0.0889)
		(layer "In6.Cu")
		(net "M_K_CPU1_SA_DQ<8>")
	)
	(segment
		(start 140.447776 -230.170228)
		(end 140.914882 -229.90429)
		(width 0.10668)
		(layer "F.Cu")
		(net "M_K_CPU1_SA_DQ<7>")
	)
	(segment
		(start 190.48603 -205.265528)
		(end 190.63081 -205.410308)
		(width 0.14478)
		(layer "In6.Cu")
		(net "M_K_CPU1_SA_DQ<7>")
	)
	(segment
		(start 168.664128 -205.178152)
		(end 168.827196 -205.015084)
		(width 0.14478)
		(layer "In6.Cu")
		(net "M_K_CPU1_SA_DQ<7>")
	)
	(segment
		(start 173.13529 -206.097378)
		(end 173.298358 -206.260446)
		(width 0.14478)
		(layer "In6.Cu")
		(net "M_K_CPU1_SA_DQ<7>")
	)
	(segment
		(start 194.027552 -205.410308)
		(end 194.17919 -205.410308)
		(width 0.14478)
		(layer "In6.Cu")
		(net "M_K_CPU1_SA_DQ<7>")
	)
	(segment
		(start 168.270682 -205.410308)
		(end 168.50106 -205.410308)
		(width 0.14478)
		(layer "In6.Cu")
		(net "M_K_CPU1_SA_DQ<7>")
	)
	(segment
		(start 192.37325 -205.117446)
		(end 192.635124 -205.117446)
		(width 0.14478)
		(layer "In6.Cu")
		(net "M_K_CPU1_SA_DQ<7>")
	)
	(segment
		(start 187.444126 -206.260446)
		(end 187.607194 -206.097378)
		(width 0.14478)
		(layer "In6.Cu")
		(net "M_K_CPU1_SA_DQ<7>")
	)
	(segment
		(start 168.50106 -205.410308)
		(end 168.664128 -205.24724)
		(width 0.14478)
		(layer "In6.Cu")
		(net "M_K_CPU1_SA_DQ<7>")
	)
	(segment
		(start 175.0695 -205.24724)
		(end 175.0695 -205.188312)
		(width 0.14478)
		(layer "In6.Cu")
		(net "M_K_CPU1_SA_DQ<7>")
	)
	(segment
		(start 167.5511 -205.24724)
		(end 167.5511 -205.178152)
		(width 0.14478)
		(layer "In6.Cu")
		(net "M_K_CPU1_SA_DQ<7>")
	)
	(segment
		(start 183.318404 -205.410308)
		(end 184.99582 -205.410308)
		(width 0.14478)
		(layer "In6.Cu")
		(net "M_K_CPU1_SA_DQ<7>")
	)
	(segment
		(start 144.186148 -229.531164)
		(end 144.986248 -228.731064)
		(width 0.0889)
		(layer "In6.Cu")
		(net "M_K_CPU1_SA_DQ<7>")
	)
	(segment
		(start 175.626014 -205.24724)
		(end 175.789082 -205.410308)
		(width 0.14478)
		(layer "In6.Cu")
		(net "M_K_CPU1_SA_DQ<7>")
	)
	(segment
		(start 184.99582 -205.410308)
		(end 185.845958 -206.260446)
		(width 0.14478)
		(layer "In6.Cu")
		(net "M_K_CPU1_SA_DQ<7>")
	)
	(segment
		(start 152.27046 -220.702886)
		(end 152.27046 -218.237816)
		(width 0.14478)
		(layer "In6.Cu")
		(net "M_K_CPU1_SA_DQ<7>")
	)
	(segment
		(start 180.119782 -206.036672)
		(end 180.28285 -205.873604)
		(width 0.14478)
		(layer "In6.Cu")
		(net "M_K_CPU1_SA_DQ<7>")
	)
	(segment
		(start 192.635124 -205.117446)
		(end 192.779904 -205.262226)
		(width 0.14478)
		(layer "In6.Cu")
		(net "M_K_CPU1_SA_DQ<7>")
	)
	(segment
		(start 185.845958 -206.260446)
		(end 187.444126 -206.260446)
		(width 0.14478)
		(layer "In6.Cu")
		(net "M_K_CPU1_SA_DQ<7>")
	)
	(segment
		(start 191.677036 -205.555088)
		(end 191.677036 -205.55839)
		(width 0.14478)
		(layer "In6.Cu")
		(net "M_K_CPU1_SA_DQ<7>")
	)
	(segment
		(start 190.63081 -205.410308)
		(end 191.532256 -205.410308)
		(width 0.14478)
		(layer "In6.Cu")
		(net "M_K_CPU1_SA_DQ<7>")
	)
	(segment
		(start 191.677036 -205.55839)
		(end 191.821816 -205.70317)
		(width 0.14478)
		(layer "In6.Cu")
		(net "M_K_CPU1_SA_DQ<7>")
	)
	(segment
		(start 168.664128 -205.24724)
		(end 168.664128 -205.178152)
		(width 0.14478)
		(layer "In6.Cu")
		(net "M_K_CPU1_SA_DQ<7>")
	)
	(segment
		(start 169.220642 -205.24724)
		(end 169.38371 -205.410308)
		(width 0.14478)
		(layer "In6.Cu")
		(net "M_K_CPU1_SA_DQ<7>")
	)
	(segment
		(start 165.10127 -205.868524)
		(end 165.331648 -205.868524)
		(width 0.14478)
		(layer "In6.Cu")
		(net "M_K_CPU1_SA_DQ<7>")
	)
	(segment
		(start 167.5511 -205.178152)
		(end 167.714168 -205.015084)
		(width 0.14478)
		(layer "In6.Cu")
		(net "M_K_CPU1_SA_DQ<7>")
	)
	(segment
		(start 145.269712 -228.731064)
		(end 146.941286 -227.05949)
		(width 0.0889)
		(layer "In6.Cu")
		(net "M_K_CPU1_SA_DQ<7>")
	)
	(segment
		(start 191.821816 -205.70317)
		(end 192.08369 -205.70317)
		(width 0.14478)
		(layer "In6.Cu")
		(net "M_K_CPU1_SA_DQ<7>")
	)
	(segment
		(start 175.0695 -205.188312)
		(end 175.232568 -205.025244)
		(width 0.14478)
		(layer "In6.Cu")
		(net "M_K_CPU1_SA_DQ<7>")
	)
	(segment
		(start 182.76189 -205.015084)
		(end 182.992268 -205.015084)
		(width 0.14478)
		(layer "In6.Cu")
		(net "M_K_CPU1_SA_DQ<7>")
	)
	(segment
		(start 182.992268 -205.015084)
		(end 183.155336 -205.178152)
		(width 0.14478)
		(layer "In6.Cu")
		(net "M_K_CPU1_SA_DQ<7>")
	)
	(segment
		(start 193.737992 -205.117446)
		(end 193.882772 -205.262226)
		(width 0.14478)
		(layer "In6.Cu")
		(net "M_K_CPU1_SA_DQ<7>")
	)
	(segment
		(start 146.941286 -227.05949)
		(end 146.941286 -226.03206)
		(width 0.0889)
		(layer "In6.Cu")
		(net "M_K_CPU1_SA_DQ<7>")
	)
	(segment
		(start 172.415708 -206.260446)
		(end 172.578776 -206.097378)
		(width 0.14478)
		(layer "In6.Cu")
		(net "M_K_CPU1_SA_DQ<7>")
	)
	(segment
		(start 163.652708 -206.855568)
		(end 163.652708 -206.650844)
		(width 0.14478)
		(layer "In6.Cu")
		(net "M_K_CPU1_SA_DQ<7>")
	)
	(segment
		(start 180.513228 -205.873604)
		(end 180.676296 -206.036672)
		(width 0.14478)
		(layer "In6.Cu")
		(net "M_K_CPU1_SA_DQ<7>")
	)
	(segment
		(start 175.232568 -205.025244)
		(end 175.462946 -205.025244)
		(width 0.14478)
		(layer "In6.Cu")
		(net "M_K_CPU1_SA_DQ<7>")
	)
	(segment
		(start 172.972222 -205.868524)
		(end 173.13529 -206.031592)
		(width 0.14478)
		(layer "In6.Cu")
		(net "M_K_CPU1_SA_DQ<7>")
	)
	(segment
		(start 192.22847 -205.55839)
		(end 192.22847 -205.262226)
		(width 0.14478)
		(layer "In6.Cu")
		(net "M_K_CPU1_SA_DQ<7>")
	)
	(segment
		(start 188.163708 -206.097378)
		(end 188.326776 -206.260446)
		(width 0.14478)
		(layer "In6.Cu")
		(net "M_K_CPU1_SA_DQ<7>")
	)
	(segment
		(start 188.163708 -206.031592)
		(end 188.163708 -206.097378)
		(width 0.14478)
		(layer "In6.Cu")
		(net "M_K_CPU1_SA_DQ<7>")
	)
	(segment
		(start 179.956714 -206.260446)
		(end 180.119782 -206.097378)
		(width 0.14478)
		(layer "In6.Cu")
		(net "M_K_CPU1_SA_DQ<7>")
	)
	(segment
		(start 181.991 -205.410308)
		(end 182.435754 -205.410308)
		(width 0.14478)
		(layer "In6.Cu")
		(net "M_K_CPU1_SA_DQ<7>")
	)
	(segment
		(start 180.676296 -206.036672)
		(end 180.676296 -206.097378)
		(width 0.14478)
		(layer "In6.Cu")
		(net "M_K_CPU1_SA_DQ<7>")
	)
	(segment
		(start 194.17919 -205.410308)
		(end 194.604132 -205.83525)
		(width 0.14478)
		(layer "In6.Cu")
		(net "M_K_CPU1_SA_DQ<7>")
	)
	(segment
		(start 166.066724 -206.260446)
		(end 166.916862 -205.410308)
		(width 0.14478)
		(layer "In6.Cu")
		(net "M_K_CPU1_SA_DQ<7>")
	)
	(segment
		(start 188.673232 -206.260446)
		(end 189.52337 -205.410308)
		(width 0.14478)
		(layer "In6.Cu")
		(net "M_K_CPU1_SA_DQ<7>")
	)
	(segment
		(start 163.652708 -206.650844)
		(end 163.401502 -206.399638)
		(width 0.14478)
		(layer "In6.Cu")
		(net "M_K_CPU1_SA_DQ<7>")
	)
	(segment
		(start 187.607194 -206.031592)
		(end 187.770262 -205.868524)
		(width 0.14478)
		(layer "In6.Cu")
		(net "M_K_CPU1_SA_DQ<7>")
	)
	(segment
		(start 189.934596 -205.163166)
		(end 190.079376 -205.018386)
		(width 0.14478)
		(layer "In6.Cu")
		(net "M_K_CPU1_SA_DQ<7>")
	)
	(segment
		(start 192.22847 -205.262226)
		(end 192.37325 -205.117446)
		(width 0.14478)
		(layer "In6.Cu")
		(net "M_K_CPU1_SA_DQ<7>")
	)
	(segment
		(start 163.401502 -206.194914)
		(end 163.586922 -206.009494)
		(width 0.14478)
		(layer "In6.Cu")
		(net "M_K_CPU1_SA_DQ<7>")
	)
	(segment
		(start 193.882772 -205.265528)
		(end 194.027552 -205.410308)
		(width 0.14478)
		(layer "In6.Cu")
		(net "M_K_CPU1_SA_DQ<7>")
	)
	(segment
		(start 173.13529 -206.031592)
		(end 173.13529 -206.097378)
		(width 0.14478)
		(layer "In6.Cu")
		(net "M_K_CPU1_SA_DQ<7>")
	)
	(segment
		(start 182.598822 -205.24724)
		(end 182.598822 -205.178152)
		(width 0.14478)
		(layer "In6.Cu")
		(net "M_K_CPU1_SA_DQ<7>")
	)
	(segment
		(start 180.839364 -206.260446)
		(end 181.140862 -206.260446)
		(width 0.14478)
		(layer "In6.Cu")
		(net "M_K_CPU1_SA_DQ<7>")
	)
	(segment
		(start 192.08369 -205.70317)
		(end 192.22847 -205.55839)
		(width 0.14478)
		(layer "In6.Cu")
		(net "M_K_CPU1_SA_DQ<7>")
	)
	(segment
		(start 192.779904 -205.55839)
		(end 192.924684 -205.70317)
		(width 0.14478)
		(layer "In6.Cu")
		(net "M_K_CPU1_SA_DQ<7>")
	)
	(segment
		(start 175.789082 -205.410308)
		(end 177.45202 -205.410308)
		(width 0.14478)
		(layer "In6.Cu")
		(net "M_K_CPU1_SA_DQ<7>")
	)
	(segment
		(start 189.789816 -205.410308)
		(end 189.934596 -205.265528)
		(width 0.14478)
		(layer "In6.Cu")
		(net "M_K_CPU1_SA_DQ<7>")
	)
	(segment
		(start 175.626014 -205.188312)
		(end 175.626014 -205.24724)
		(width 0.14478)
		(layer "In6.Cu")
		(net "M_K_CPU1_SA_DQ<7>")
	)
	(segment
		(start 190.48603 -205.163166)
		(end 190.48603 -205.265528)
		(width 0.14478)
		(layer "In6.Cu")
		(net "M_K_CPU1_SA_DQ<7>")
	)
	(segment
		(start 152.27046 -218.237816)
		(end 163.652708 -206.855568)
		(width 0.14478)
		(layer "In6.Cu")
		(net "M_K_CPU1_SA_DQ<7>")
	)
	(segment
		(start 177.45202 -205.410308)
		(end 178.302158 -206.260446)
		(width 0.14478)
		(layer "In6.Cu")
		(net "M_K_CPU1_SA_DQ<7>")
	)
	(segment
		(start 147.832572 -225.140774)
		(end 152.27046 -220.702886)
		(width 0.14478)
		(layer "In6.Cu")
		(net "M_K_CPU1_SA_DQ<7>")
	)
	(segment
		(start 175.462946 -205.025244)
		(end 175.626014 -205.188312)
		(width 0.14478)
		(layer "In6.Cu")
		(net "M_K_CPU1_SA_DQ<7>")
	)
	(segment
		(start 190.079376 -205.018386)
		(end 190.34125 -205.018386)
		(width 0.14478)
		(layer "In6.Cu")
		(net "M_K_CPU1_SA_DQ<7>")
	)
	(segment
		(start 169.220642 -205.178152)
		(end 169.220642 -205.24724)
		(width 0.14478)
		(layer "In6.Cu")
		(net "M_K_CPU1_SA_DQ<7>")
	)
	(segment
		(start 172.741844 -205.868524)
		(end 172.972222 -205.868524)
		(width 0.14478)
		(layer "In6.Cu")
		(net "M_K_CPU1_SA_DQ<7>")
	)
	(segment
		(start 163.791646 -206.009494)
		(end 164.042598 -206.260446)
		(width 0.14478)
		(layer "In6.Cu")
		(net "M_K_CPU1_SA_DQ<7>")
	)
	(segment
		(start 180.119782 -206.097378)
		(end 180.119782 -206.036672)
		(width 0.14478)
		(layer "In6.Cu")
		(net "M_K_CPU1_SA_DQ<7>")
	)
	(segment
		(start 169.38371 -205.410308)
		(end 169.907966 -205.410308)
		(width 0.14478)
		(layer "In6.Cu")
		(net "M_K_CPU1_SA_DQ<7>")
	)
	(segment
		(start 187.607194 -206.097378)
		(end 187.607194 -206.031592)
		(width 0.14478)
		(layer "In6.Cu")
		(net "M_K_CPU1_SA_DQ<7>")
	)
	(segment
		(start 165.657784 -206.260446)
		(end 166.066724 -206.260446)
		(width 0.14478)
		(layer "In6.Cu")
		(net "M_K_CPU1_SA_DQ<7>")
	)
	(segment
		(start 182.598822 -205.178152)
		(end 182.76189 -205.015084)
		(width 0.14478)
		(layer "In6.Cu")
		(net "M_K_CPU1_SA_DQ<7>")
	)
	(segment
		(start 180.676296 -206.097378)
		(end 180.839364 -206.260446)
		(width 0.14478)
		(layer "In6.Cu")
		(net "M_K_CPU1_SA_DQ<7>")
	)
	(segment
		(start 167.388032 -205.410308)
		(end 167.5511 -205.24724)
		(width 0.14478)
		(layer "In6.Cu")
		(net "M_K_CPU1_SA_DQ<7>")
	)
	(segment
		(start 188.00064 -205.868524)
		(end 188.163708 -206.031592)
		(width 0.14478)
		(layer "In6.Cu")
		(net "M_K_CPU1_SA_DQ<7>")
	)
	(segment
		(start 193.476118 -205.117446)
		(end 193.737992 -205.117446)
		(width 0.14478)
		(layer "In6.Cu")
		(net "M_K_CPU1_SA_DQ<7>")
	)
	(segment
		(start 144.986248 -228.731064)
		(end 145.269712 -228.731064)
		(width 0.0889)
		(layer "In6.Cu")
		(net "M_K_CPU1_SA_DQ<7>")
	)
	(segment
		(start 189.934596 -205.265528)
		(end 189.934596 -205.163166)
		(width 0.14478)
		(layer "In6.Cu")
		(net "M_K_CPU1_SA_DQ<7>")
	)
	(segment
		(start 173.298358 -206.260446)
		(end 173.609254 -206.260446)
		(width 0.14478)
		(layer "In6.Cu")
		(net "M_K_CPU1_SA_DQ<7>")
	)
	(segment
		(start 166.916862 -205.410308)
		(end 167.388032 -205.410308)
		(width 0.14478)
		(layer "In6.Cu")
		(net "M_K_CPU1_SA_DQ<7>")
	)
	(segment
		(start 178.302158 -206.260446)
		(end 179.956714 -206.260446)
		(width 0.14478)
		(layer "In6.Cu")
		(net "M_K_CPU1_SA_DQ<7>")
	)
	(segment
		(start 164.938202 -206.031592)
		(end 165.10127 -205.868524)
		(width 0.14478)
		(layer "In6.Cu")
		(net "M_K_CPU1_SA_DQ<7>")
	)
	(segment
		(start 164.042598 -206.260446)
		(end 164.775134 -206.260446)
		(width 0.14478)
		(layer "In6.Cu")
		(net "M_K_CPU1_SA_DQ<7>")
	)
	(segment
		(start 188.326776 -206.260446)
		(end 188.673232 -206.260446)
		(width 0.14478)
		(layer "In6.Cu")
		(net "M_K_CPU1_SA_DQ<7>")
	)
	(segment
		(start 182.435754 -205.410308)
		(end 182.598822 -205.24724)
		(width 0.14478)
		(layer "In6.Cu")
		(net "M_K_CPU1_SA_DQ<7>")
	)
	(segment
		(start 192.924684 -205.70317)
		(end 193.186558 -205.70317)
		(width 0.14478)
		(layer "In6.Cu")
		(net "M_K_CPU1_SA_DQ<7>")
	)
	(segment
		(start 192.779904 -205.262226)
		(end 192.779904 -205.55839)
		(width 0.14478)
		(layer "In6.Cu")
		(net "M_K_CPU1_SA_DQ<7>")
	)
	(segment
		(start 187.770262 -205.868524)
		(end 188.00064 -205.868524)
		(width 0.14478)
		(layer "In6.Cu")
		(net "M_K_CPU1_SA_DQ<7>")
	)
	(segment
		(start 173.609254 -206.260446)
		(end 174.459392 -205.410308)
		(width 0.14478)
		(layer "In6.Cu")
		(net "M_K_CPU1_SA_DQ<7>")
	)
	(segment
		(start 165.494716 -206.031592)
		(end 165.494716 -206.097378)
		(width 0.14478)
		(layer "In6.Cu")
		(net "M_K_CPU1_SA_DQ<7>")
	)
	(segment
		(start 193.331338 -205.55839)
		(end 193.331338 -205.262226)
		(width 0.14478)
		(layer "In6.Cu")
		(net "M_K_CPU1_SA_DQ<7>")
	)
	(segment
		(start 168.107614 -205.178152)
		(end 168.107614 -205.24724)
		(width 0.14478)
		(layer "In6.Cu")
		(net "M_K_CPU1_SA_DQ<7>")
	)
	(segment
		(start 172.578776 -206.031592)
		(end 172.741844 -205.868524)
		(width 0.14478)
		(layer "In6.Cu")
		(net "M_K_CPU1_SA_DQ<7>")
	)
	(segment
		(start 170.758104 -206.260446)
		(end 172.415708 -206.260446)
		(width 0.14478)
		(layer "In6.Cu")
		(net "M_K_CPU1_SA_DQ<7>")
	)
	(segment
		(start 163.401502 -206.399638)
		(end 163.401502 -206.194914)
		(width 0.14478)
		(layer "In6.Cu")
		(net "M_K_CPU1_SA_DQ<7>")
	)
	(segment
		(start 140.914882 -229.90429)
		(end 141.068806 -229.63886)
		(width 0.0889)
		(layer "In6.Cu")
		(net "M_K_CPU1_SA_DQ<7>")
	)
	(segment
		(start 174.906432 -205.410308)
		(end 175.0695 -205.24724)
		(width 0.14478)
		(layer "In6.Cu")
		(net "M_K_CPU1_SA_DQ<7>")
	)
	(segment
		(start 180.28285 -205.873604)
		(end 180.513228 -205.873604)
		(width 0.14478)
		(layer "In6.Cu")
		(net "M_K_CPU1_SA_DQ<7>")
	)
	(segment
		(start 193.331338 -205.262226)
		(end 193.476118 -205.117446)
		(width 0.14478)
		(layer "In6.Cu")
		(net "M_K_CPU1_SA_DQ<7>")
	)
	(segment
		(start 146.941286 -226.03206)
		(end 147.832572 -225.140774)
		(width 0.0889)
		(layer "In6.Cu")
		(net "M_K_CPU1_SA_DQ<7>")
	)
	(segment
		(start 193.186558 -205.70317)
		(end 193.331338 -205.55839)
		(width 0.14478)
		(layer "In6.Cu")
		(net "M_K_CPU1_SA_DQ<7>")
	)
	(segment
		(start 183.155336 -205.24724)
		(end 183.318404 -205.410308)
		(width 0.14478)
		(layer "In6.Cu")
		(net "M_K_CPU1_SA_DQ<7>")
	)
	(segment
		(start 190.34125 -205.018386)
		(end 190.48603 -205.163166)
		(width 0.14478)
		(layer "In6.Cu")
		(net "M_K_CPU1_SA_DQ<7>")
	)
	(segment
		(start 191.532256 -205.410308)
		(end 191.677036 -205.555088)
		(width 0.14478)
		(layer "In6.Cu")
		(net "M_K_CPU1_SA_DQ<7>")
	)
	(segment
		(start 167.714168 -205.015084)
		(end 167.944546 -205.015084)
		(width 0.14478)
		(layer "In6.Cu")
		(net "M_K_CPU1_SA_DQ<7>")
	)
	(segment
		(start 167.944546 -205.015084)
		(end 168.107614 -205.178152)
		(width 0.14478)
		(layer "In6.Cu")
		(net "M_K_CPU1_SA_DQ<7>")
	)
	(segment
		(start 174.459392 -205.410308)
		(end 174.906432 -205.410308)
		(width 0.14478)
		(layer "In6.Cu")
		(net "M_K_CPU1_SA_DQ<7>")
	)
	(segment
		(start 163.586922 -206.009494)
		(end 163.791646 -206.009494)
		(width 0.14478)
		(layer "In6.Cu")
		(net "M_K_CPU1_SA_DQ<7>")
	)
	(segment
		(start 172.578776 -206.097378)
		(end 172.578776 -206.031592)
		(width 0.14478)
		(layer "In6.Cu")
		(net "M_K_CPU1_SA_DQ<7>")
	)
	(segment
		(start 168.107614 -205.24724)
		(end 168.270682 -205.410308)
		(width 0.14478)
		(layer "In6.Cu")
		(net "M_K_CPU1_SA_DQ<7>")
	)
	(segment
		(start 164.938202 -206.097378)
		(end 164.938202 -206.031592)
		(width 0.14478)
		(layer "In6.Cu")
		(net "M_K_CPU1_SA_DQ<7>")
	)
	(segment
		(start 169.907966 -205.410308)
		(end 170.758104 -206.260446)
		(width 0.14478)
		(layer "In6.Cu")
		(net "M_K_CPU1_SA_DQ<7>")
	)
	(segment
		(start 181.140862 -206.260446)
		(end 181.991 -205.410308)
		(width 0.14478)
		(layer "In6.Cu")
		(net "M_K_CPU1_SA_DQ<7>")
	)
	(segment
		(start 168.827196 -205.015084)
		(end 169.057574 -205.015084)
		(width 0.14478)
		(layer "In6.Cu")
		(net "M_K_CPU1_SA_DQ<7>")
	)
	(segment
		(start 183.155336 -205.178152)
		(end 183.155336 -205.24724)
		(width 0.14478)
		(layer "In6.Cu")
		(net "M_K_CPU1_SA_DQ<7>")
	)
	(segment
		(start 141.667738 -229.581964)
		(end 141.67612 -229.577138)
		(width 0.0889)
		(layer "In6.Cu")
		(net "M_K_CPU1_SA_DQ<7>")
	)
	(segment
		(start 165.331648 -205.868524)
		(end 165.494716 -206.031592)
		(width 0.14478)
		(layer "In6.Cu")
		(net "M_K_CPU1_SA_DQ<7>")
	)
	(segment
		(start 141.068806 -229.63886)
		(end 141.164564 -229.61346)
		(width 0.0889)
		(layer "In6.Cu")
		(net "M_K_CPU1_SA_DQ<7>")
	)
	(segment
		(start 143.73479 -229.531164)
		(end 144.186148 -229.531164)
		(width 0.0889)
		(layer "In6.Cu")
		(net "M_K_CPU1_SA_DQ<7>")
	)
	(segment
		(start 189.52337 -205.410308)
		(end 189.789816 -205.410308)
		(width 0.14478)
		(layer "In6.Cu")
		(net "M_K_CPU1_SA_DQ<7>")
	)
	(segment
		(start 193.882772 -205.262226)
		(end 193.882772 -205.265528)
		(width 0.14478)
		(layer "In6.Cu")
		(net "M_K_CPU1_SA_DQ<7>")
	)
	(segment
		(start 164.775134 -206.260446)
		(end 164.938202 -206.097378)
		(width 0.14478)
		(layer "In6.Cu")
		(net "M_K_CPU1_SA_DQ<7>")
	)
	(segment
		(start 165.494716 -206.097378)
		(end 165.657784 -206.260446)
		(width 0.14478)
		(layer "In6.Cu")
		(net "M_K_CPU1_SA_DQ<7>")
	)
	(segment
		(start 169.057574 -205.015084)
		(end 169.220642 -205.178152)
		(width 0.14478)
		(layer "In6.Cu")
		(net "M_K_CPU1_SA_DQ<7>")
	)
	(arc
		(start 142.607792 -229.581964)
		(mid 142.794736 -229.531675)
		(end 142.98168 -229.581964)
		(width 0.0889)
		(layer "In6.Cu")
		(net "M_K_CPU1_SA_DQ<7>")
	)
	(arc
		(start 141.164564 -229.61346)
		(mid 141.419886 -229.65716)
		(end 141.667738 -229.581964)
		(width 0.0889)
		(layer "In6.Cu")
		(net "M_K_CPU1_SA_DQ<7>")
	)
	(arc
		(start 142.98168 -229.581964)
		(mid 143.264636 -229.658141)
		(end 143.547592 -229.581964)
		(width 0.0889)
		(layer "In6.Cu")
		(net "M_K_CPU1_SA_DQ<7>")
	)
	(arc
		(start 142.04188 -229.581964)
		(mid 142.324836 -229.658141)
		(end 142.607792 -229.581964)
		(width 0.0889)
		(layer "In6.Cu")
		(net "M_K_CPU1_SA_DQ<7>")
	)
	(arc
		(start 143.547592 -229.581964)
		(mid 143.637828 -229.544162)
		(end 143.73479 -229.531164)
		(width 0.0889)
		(layer "In6.Cu")
		(net "M_K_CPU1_SA_DQ<7>")
	)
	(arc
		(start 141.67612 -229.577138)
		(mid 141.859628 -229.531613)
		(end 142.04188 -229.581964)
		(width 0.0889)
		(layer "In6.Cu")
		(net "M_K_CPU1_SA_DQ<7>")
	)
	(segment
		(start 141.857984 -229.360476)
		(end 142.324836 -229.094538)
		(width 0.10668)
		(layer "F.Cu")
		(net "M_K_CPU1_SA_DQ<6>")
	)
	(segment
		(start 158.638748 -209.734658)
		(end 158.638748 -209.529934)
		(width 0.14478)
		(layer "In6.Cu")
		(net "M_K_CPU1_SA_DQ<6>")
	)
	(segment
		(start 168.946576 -203.321666)
		(end 169.176954 -203.321666)
		(width 0.14478)
		(layer "In6.Cu")
		(net "M_K_CPU1_SA_DQ<6>")
	)
	(segment
		(start 180.066188 -204.397356)
		(end 180.066188 -204.334872)
		(width 0.14478)
		(layer "In6.Cu")
		(net "M_K_CPU1_SA_DQ<6>")
	)
	(segment
		(start 168.226994 -203.482194)
		(end 168.226994 -203.547218)
		(width 0.14478)
		(layer "In6.Cu")
		(net "M_K_CPU1_SA_DQ<6>")
	)
	(segment
		(start 187.450222 -204.560424)
		(end 187.61329 -204.397356)
		(width 0.14478)
		(layer "In6.Cu")
		(net "M_K_CPU1_SA_DQ<6>")
	)
	(segment
		(start 142.47876 -228.829108)
		(end 142.574772 -228.803708)
		(width 0.0889)
		(layer "In6.Cu")
		(net "M_K_CPU1_SA_DQ<6>")
	)
	(segment
		(start 158.9278 -210.02371)
		(end 158.638748 -209.734658)
		(width 0.14478)
		(layer "In6.Cu")
		(net "M_K_CPU1_SA_DQ<6>")
	)
	(segment
		(start 146.090132 -226.170744)
		(end 146.984466 -225.27641)
		(width 0.0889)
		(layer "In6.Cu")
		(net "M_K_CPU1_SA_DQ<6>")
	)
	(segment
		(start 180.622702 -204.397356)
		(end 180.78577 -204.560424)
		(width 0.14478)
		(layer "In6.Cu")
		(net "M_K_CPU1_SA_DQ<6>")
	)
	(segment
		(start 146.984466 -224.57156)
		(end 147.811236 -223.74479)
		(width 0.0889)
		(layer "In6.Cu")
		(net "M_K_CPU1_SA_DQ<6>")
	)
	(segment
		(start 190.00851 -203.873354)
		(end 190.00851 -203.937616)
		(width 0.14478)
		(layer "In6.Cu")
		(net "M_K_CPU1_SA_DQ<6>")
	)
	(segment
		(start 188.169804 -204.335634)
		(end 188.169804 -204.397356)
		(width 0.14478)
		(layer "In6.Cu")
		(net "M_K_CPU1_SA_DQ<6>")
	)
	(segment
		(start 183.101742 -203.486512)
		(end 183.101742 -203.547218)
		(width 0.14478)
		(layer "In6.Cu")
		(net "M_K_CPU1_SA_DQ<6>")
	)
	(segment
		(start 191.73698 -203.710286)
		(end 191.900048 -203.547218)
		(width 0.14478)
		(layer "In6.Cu")
		(net "M_K_CPU1_SA_DQ<6>")
	)
	(segment
		(start 193.406522 -203.341986)
		(end 193.56959 -203.505054)
		(width 0.14478)
		(layer "In6.Cu")
		(net "M_K_CPU1_SA_DQ<6>")
	)
	(segment
		(start 173.609254 -204.560424)
		(end 174.459392 -203.710286)
		(width 0.14478)
		(layer "In6.Cu")
		(net "M_K_CPU1_SA_DQ<6>")
	)
	(segment
		(start 169.50309 -203.710286)
		(end 169.907966 -203.710286)
		(width 0.14478)
		(layer "In6.Cu")
		(net "M_K_CPU1_SA_DQ<6>")
	)
	(segment
		(start 172.578522 -204.332332)
		(end 172.74159 -204.169264)
		(width 0.14478)
		(layer "In6.Cu")
		(net "M_K_CPU1_SA_DQ<6>")
	)
	(segment
		(start 158.824168 -209.344514)
		(end 159.028892 -209.344514)
		(width 0.14478)
		(layer "In6.Cu")
		(net "M_K_CPU1_SA_DQ<6>")
	)
	(segment
		(start 181.991 -203.710286)
		(end 182.38216 -203.710286)
		(width 0.14478)
		(layer "In6.Cu")
		(net "M_K_CPU1_SA_DQ<6>")
	)
	(segment
		(start 175.421036 -203.321666)
		(end 175.584104 -203.484734)
		(width 0.14478)
		(layer "In6.Cu")
		(net "M_K_CPU1_SA_DQ<6>")
	)
	(segment
		(start 182.38216 -203.710286)
		(end 182.545228 -203.547218)
		(width 0.14478)
		(layer "In6.Cu")
		(net "M_K_CPU1_SA_DQ<6>")
	)
	(segment
		(start 169.340022 -203.547218)
		(end 169.50309 -203.710286)
		(width 0.14478)
		(layer "In6.Cu")
		(net "M_K_CPU1_SA_DQ<6>")
	)
	(segment
		(start 160.302956 -208.853278)
		(end 160.507426 -208.648808)
		(width 0.14478)
		(layer "In6.Cu")
		(net "M_K_CPU1_SA_DQ<6>")
	)
	(segment
		(start 193.013076 -203.93914)
		(end 193.013076 -203.505054)
		(width 0.14478)
		(layer "In6.Cu")
		(net "M_K_CPU1_SA_DQ<6>")
	)
	(segment
		(start 144.783556 -228.167184)
		(end 145.24482 -228.167184)
		(width 0.0889)
		(layer "In6.Cu")
		(net "M_K_CPU1_SA_DQ<6>")
	)
	(segment
		(start 175.584104 -203.547218)
		(end 175.747172 -203.710286)
		(width 0.14478)
		(layer "In6.Cu")
		(net "M_K_CPU1_SA_DQ<6>")
	)
	(segment
		(start 193.732658 -203.710286)
		(end 194.17919 -203.710286)
		(width 0.14478)
		(layer "In6.Cu")
		(net "M_K_CPU1_SA_DQ<6>")
	)
	(segment
		(start 192.063116 -203.331826)
		(end 192.293494 -203.331826)
		(width 0.14478)
		(layer "In6.Cu")
		(net "M_K_CPU1_SA_DQ<6>")
	)
	(segment
		(start 192.456562 -203.494894)
		(end 192.456562 -203.93914)
		(width 0.14478)
		(layer "In6.Cu")
		(net "M_K_CPU1_SA_DQ<6>")
	)
	(segment
		(start 182.938674 -203.323444)
		(end 183.101742 -203.486512)
		(width 0.14478)
		(layer "In6.Cu")
		(net "M_K_CPU1_SA_DQ<6>")
	)
	(segment
		(start 173.135036 -204.332332)
		(end 173.135036 -204.397356)
		(width 0.14478)
		(layer "In6.Cu")
		(net "M_K_CPU1_SA_DQ<6>")
	)
	(segment
		(start 168.783508 -203.547218)
		(end 168.783508 -203.484734)
		(width 0.14478)
		(layer "In6.Cu")
		(net "M_K_CPU1_SA_DQ<6>")
	)
	(segment
		(start 191.900048 -203.494894)
		(end 192.063116 -203.331826)
		(width 0.14478)
		(layer "In6.Cu")
		(net "M_K_CPU1_SA_DQ<6>")
	)
	(segment
		(start 175.02759 -203.547218)
		(end 175.02759 -203.484734)
		(width 0.14478)
		(layer "In6.Cu")
		(net "M_K_CPU1_SA_DQ<6>")
	)
	(segment
		(start 169.340022 -203.484734)
		(end 169.340022 -203.547218)
		(width 0.14478)
		(layer "In6.Cu")
		(net "M_K_CPU1_SA_DQ<6>")
	)
	(segment
		(start 167.507412 -203.710286)
		(end 167.67048 -203.547218)
		(width 0.14478)
		(layer "In6.Cu")
		(net "M_K_CPU1_SA_DQ<6>")
	)
	(segment
		(start 159.80918 -208.564226)
		(end 160.098232 -208.853278)
		(width 0.14478)
		(layer "In6.Cu")
		(net "M_K_CPU1_SA_DQ<6>")
	)
	(segment
		(start 145.760948 -227.651056)
		(end 145.760948 -226.96551)
		(width 0.0889)
		(layer "In6.Cu")
		(net "M_K_CPU1_SA_DQ<6>")
	)
	(segment
		(start 159.317944 -209.633566)
		(end 159.522668 -209.633566)
		(width 0.14478)
		(layer "In6.Cu")
		(net "M_K_CPU1_SA_DQ<6>")
	)
	(segment
		(start 188.673232 -204.560424)
		(end 189.52337 -203.710286)
		(width 0.14478)
		(layer "In6.Cu")
		(net "M_K_CPU1_SA_DQ<6>")
	)
	(segment
		(start 174.864522 -203.710286)
		(end 175.02759 -203.547218)
		(width 0.14478)
		(layer "In6.Cu")
		(net "M_K_CPU1_SA_DQ<6>")
	)
	(segment
		(start 164.67963 -204.560424)
		(end 164.842698 -204.397356)
		(width 0.14478)
		(layer "In6.Cu")
		(net "M_K_CPU1_SA_DQ<6>")
	)
	(segment
		(start 165.236144 -204.166724)
		(end 165.399212 -204.329792)
		(width 0.14478)
		(layer "In6.Cu")
		(net "M_K_CPU1_SA_DQ<6>")
	)
	(segment
		(start 172.578522 -204.397356)
		(end 172.578522 -204.332332)
		(width 0.14478)
		(layer "In6.Cu")
		(net "M_K_CPU1_SA_DQ<6>")
	)
	(segment
		(start 188.169804 -204.397356)
		(end 188.332872 -204.560424)
		(width 0.14478)
		(layer "In6.Cu")
		(net "M_K_CPU1_SA_DQ<6>")
	)
	(segment
		(start 189.52337 -203.710286)
		(end 189.845442 -203.710286)
		(width 0.14478)
		(layer "In6.Cu")
		(net "M_K_CPU1_SA_DQ<6>")
	)
	(segment
		(start 182.708296 -203.323444)
		(end 182.938674 -203.323444)
		(width 0.14478)
		(layer "In6.Cu")
		(net "M_K_CPU1_SA_DQ<6>")
	)
	(segment
		(start 151.270208 -220.288104)
		(end 151.270208 -217.886026)
		(width 0.14478)
		(layer "In6.Cu")
		(net "M_K_CPU1_SA_DQ<6>")
	)
	(segment
		(start 163.593272 -204.560424)
		(end 164.67963 -204.560424)
		(width 0.14478)
		(layer "In6.Cu")
		(net "M_K_CPU1_SA_DQ<6>")
	)
	(segment
		(start 159.419036 -208.95437)
		(end 159.419036 -208.749646)
		(width 0.14478)
		(layer "In6.Cu")
		(net "M_K_CPU1_SA_DQ<6>")
	)
	(segment
		(start 190.728092 -203.710286)
		(end 191.73698 -203.710286)
		(width 0.14478)
		(layer "In6.Cu")
		(net "M_K_CPU1_SA_DQ<6>")
	)
	(segment
		(start 158.638748 -209.529934)
		(end 158.824168 -209.344514)
		(width 0.14478)
		(layer "In6.Cu")
		(net "M_K_CPU1_SA_DQ<6>")
	)
	(segment
		(start 165.56228 -204.560424)
		(end 166.066724 -204.560424)
		(width 0.14478)
		(layer "In6.Cu")
		(net "M_K_CPU1_SA_DQ<6>")
	)
	(segment
		(start 187.776358 -204.172566)
		(end 188.006736 -204.172566)
		(width 0.14478)
		(layer "In6.Cu")
		(net "M_K_CPU1_SA_DQ<6>")
	)
	(segment
		(start 143.077692 -228.771958)
		(end 143.086074 -228.767132)
		(width 0.0889)
		(layer "In6.Cu")
		(net "M_K_CPU1_SA_DQ<6>")
	)
	(segment
		(start 183.26481 -203.710286)
		(end 184.99582 -203.710286)
		(width 0.14478)
		(layer "In6.Cu")
		(net "M_K_CPU1_SA_DQ<6>")
	)
	(segment
		(start 188.006736 -204.172566)
		(end 188.169804 -204.335634)
		(width 0.14478)
		(layer "In6.Cu")
		(net "M_K_CPU1_SA_DQ<6>")
	)
	(segment
		(start 175.02759 -203.484734)
		(end 175.190658 -203.321666)
		(width 0.14478)
		(layer "In6.Cu")
		(net "M_K_CPU1_SA_DQ<6>")
	)
	(segment
		(start 187.61329 -204.397356)
		(end 187.61329 -204.335634)
		(width 0.14478)
		(layer "In6.Cu")
		(net "M_K_CPU1_SA_DQ<6>")
	)
	(segment
		(start 145.760948 -226.96551)
		(end 146.090132 -226.170744)
		(width 0.0889)
		(layer "In6.Cu")
		(net "M_K_CPU1_SA_DQ<6>")
	)
	(segment
		(start 182.545228 -203.547218)
		(end 182.545228 -203.486512)
		(width 0.14478)
		(layer "In6.Cu")
		(net "M_K_CPU1_SA_DQ<6>")
	)
	(segment
		(start 180.229256 -204.171804)
		(end 180.459634 -204.171804)
		(width 0.14478)
		(layer "In6.Cu")
		(net "M_K_CPU1_SA_DQ<6>")
	)
	(segment
		(start 193.176144 -203.341986)
		(end 193.406522 -203.341986)
		(width 0.14478)
		(layer "In6.Cu")
		(net "M_K_CPU1_SA_DQ<6>")
	)
	(segment
		(start 183.101742 -203.547218)
		(end 183.26481 -203.710286)
		(width 0.14478)
		(layer "In6.Cu")
		(net "M_K_CPU1_SA_DQ<6>")
	)
	(segment
		(start 142.324836 -229.094538)
		(end 142.47876 -228.829108)
		(width 0.0889)
		(layer "In6.Cu")
		(net "M_K_CPU1_SA_DQ<6>")
	)
	(segment
		(start 172.971968 -204.169264)
		(end 173.135036 -204.332332)
		(width 0.14478)
		(layer "In6.Cu")
		(net "M_K_CPU1_SA_DQ<6>")
	)
	(segment
		(start 179.90312 -204.560424)
		(end 180.066188 -204.397356)
		(width 0.14478)
		(layer "In6.Cu")
		(net "M_K_CPU1_SA_DQ<6>")
	)
	(segment
		(start 174.459392 -203.710286)
		(end 174.864522 -203.710286)
		(width 0.14478)
		(layer "In6.Cu")
		(net "M_K_CPU1_SA_DQ<6>")
	)
	(segment
		(start 193.56959 -203.505054)
		(end 193.56959 -203.547218)
		(width 0.14478)
		(layer "In6.Cu")
		(net "M_K_CPU1_SA_DQ<6>")
	)
	(segment
		(start 164.842698 -204.329792)
		(end 165.005766 -204.166724)
		(width 0.14478)
		(layer "In6.Cu")
		(net "M_K_CPU1_SA_DQ<6>")
	)
	(segment
		(start 175.747172 -203.710286)
		(end 177.45202 -203.710286)
		(width 0.14478)
		(layer "In6.Cu")
		(net "M_K_CPU1_SA_DQ<6>")
	)
	(segment
		(start 172.415454 -204.560424)
		(end 172.578522 -204.397356)
		(width 0.14478)
		(layer "In6.Cu")
		(net "M_K_CPU1_SA_DQ<6>")
	)
	(segment
		(start 180.066188 -204.334872)
		(end 180.229256 -204.171804)
		(width 0.14478)
		(layer "In6.Cu")
		(net "M_K_CPU1_SA_DQ<6>")
	)
	(segment
		(start 190.00851 -203.937616)
		(end 190.171578 -204.100684)
		(width 0.14478)
		(layer "In6.Cu")
		(net "M_K_CPU1_SA_DQ<6>")
	)
	(segment
		(start 160.507426 -208.648808)
		(end 160.507426 -207.64627)
		(width 0.14478)
		(layer "In6.Cu")
		(net "M_K_CPU1_SA_DQ<6>")
	)
	(segment
		(start 159.708088 -209.243422)
		(end 159.419036 -208.95437)
		(width 0.14478)
		(layer "In6.Cu")
		(net "M_K_CPU1_SA_DQ<6>")
	)
	(segment
		(start 151.270208 -217.886026)
		(end 158.9278 -210.228434)
		(width 0.14478)
		(layer "In6.Cu")
		(net "M_K_CPU1_SA_DQ<6>")
	)
	(segment
		(start 182.545228 -203.486512)
		(end 182.708296 -203.323444)
		(width 0.14478)
		(layer "In6.Cu")
		(net "M_K_CPU1_SA_DQ<6>")
	)
	(segment
		(start 173.298104 -204.560424)
		(end 173.609254 -204.560424)
		(width 0.14478)
		(layer "In6.Cu")
		(net "M_K_CPU1_SA_DQ<6>")
	)
	(segment
		(start 190.565024 -203.873354)
		(end 190.728092 -203.710286)
		(width 0.14478)
		(layer "In6.Cu")
		(net "M_K_CPU1_SA_DQ<6>")
	)
	(segment
		(start 168.62044 -203.710286)
		(end 168.783508 -203.547218)
		(width 0.14478)
		(layer "In6.Cu")
		(net "M_K_CPU1_SA_DQ<6>")
	)
	(segment
		(start 158.9278 -210.228434)
		(end 158.9278 -210.02371)
		(width 0.14478)
		(layer "In6.Cu")
		(net "M_K_CPU1_SA_DQ<6>")
	)
	(segment
		(start 169.907966 -203.710286)
		(end 170.758104 -204.560424)
		(width 0.14478)
		(layer "In6.Cu")
		(net "M_K_CPU1_SA_DQ<6>")
	)
	(segment
		(start 170.758104 -204.560424)
		(end 172.415454 -204.560424)
		(width 0.14478)
		(layer "In6.Cu")
		(net "M_K_CPU1_SA_DQ<6>")
	)
	(segment
		(start 147.811236 -223.74479)
		(end 147.813522 -223.74479)
		(width 0.0889)
		(layer "In6.Cu")
		(net "M_K_CPU1_SA_DQ<6>")
	)
	(segment
		(start 159.419036 -208.749646)
		(end 159.604456 -208.564226)
		(width 0.14478)
		(layer "In6.Cu")
		(net "M_K_CPU1_SA_DQ<6>")
	)
	(segment
		(start 172.74159 -204.169264)
		(end 172.971968 -204.169264)
		(width 0.14478)
		(layer "In6.Cu")
		(net "M_K_CPU1_SA_DQ<6>")
	)
	(segment
		(start 168.783508 -203.484734)
		(end 168.946576 -203.321666)
		(width 0.14478)
		(layer "In6.Cu")
		(net "M_K_CPU1_SA_DQ<6>")
	)
	(segment
		(start 167.67048 -203.482194)
		(end 167.833548 -203.319126)
		(width 0.14478)
		(layer "In6.Cu")
		(net "M_K_CPU1_SA_DQ<6>")
	)
	(segment
		(start 177.45202 -203.710286)
		(end 178.302158 -204.560424)
		(width 0.14478)
		(layer "In6.Cu")
		(net "M_K_CPU1_SA_DQ<6>")
	)
	(segment
		(start 167.833548 -203.319126)
		(end 168.063926 -203.319126)
		(width 0.14478)
		(layer "In6.Cu")
		(net "M_K_CPU1_SA_DQ<6>")
	)
	(segment
		(start 165.399212 -204.329792)
		(end 165.399212 -204.397356)
		(width 0.14478)
		(layer "In6.Cu")
		(net "M_K_CPU1_SA_DQ<6>")
	)
	(segment
		(start 165.399212 -204.397356)
		(end 165.56228 -204.560424)
		(width 0.14478)
		(layer "In6.Cu")
		(net "M_K_CPU1_SA_DQ<6>")
	)
	(segment
		(start 145.24482 -228.167184)
		(end 145.760948 -227.651056)
		(width 0.0889)
		(layer "In6.Cu")
		(net "M_K_CPU1_SA_DQ<6>")
	)
	(segment
		(start 166.066724 -204.560424)
		(end 166.916862 -203.710286)
		(width 0.14478)
		(layer "In6.Cu")
		(net "M_K_CPU1_SA_DQ<6>")
	)
	(segment
		(start 166.916862 -203.710286)
		(end 167.507412 -203.710286)
		(width 0.14478)
		(layer "In6.Cu")
		(net "M_K_CPU1_SA_DQ<6>")
	)
	(segment
		(start 173.135036 -204.397356)
		(end 173.298104 -204.560424)
		(width 0.14478)
		(layer "In6.Cu")
		(net "M_K_CPU1_SA_DQ<6>")
	)
	(segment
		(start 168.226994 -203.547218)
		(end 168.390062 -203.710286)
		(width 0.14478)
		(layer "In6.Cu")
		(net "M_K_CPU1_SA_DQ<6>")
	)
	(segment
		(start 188.332872 -204.560424)
		(end 188.673232 -204.560424)
		(width 0.14478)
		(layer "In6.Cu")
		(net "M_K_CPU1_SA_DQ<6>")
	)
	(segment
		(start 192.293494 -203.331826)
		(end 192.456562 -203.494894)
		(width 0.14478)
		(layer "In6.Cu")
		(net "M_K_CPU1_SA_DQ<6>")
	)
	(segment
		(start 169.176954 -203.321666)
		(end 169.340022 -203.484734)
		(width 0.14478)
		(layer "In6.Cu")
		(net "M_K_CPU1_SA_DQ<6>")
	)
	(segment
		(start 164.842698 -204.397356)
		(end 164.842698 -204.329792)
		(width 0.14478)
		(layer "In6.Cu")
		(net "M_K_CPU1_SA_DQ<6>")
	)
	(segment
		(start 185.845958 -204.560424)
		(end 187.450222 -204.560424)
		(width 0.14478)
		(layer "In6.Cu")
		(net "M_K_CPU1_SA_DQ<6>")
	)
	(segment
		(start 160.098232 -208.853278)
		(end 160.302956 -208.853278)
		(width 0.14478)
		(layer "In6.Cu")
		(net "M_K_CPU1_SA_DQ<6>")
	)
	(segment
		(start 178.302158 -204.560424)
		(end 179.90312 -204.560424)
		(width 0.14478)
		(layer "In6.Cu")
		(net "M_K_CPU1_SA_DQ<6>")
	)
	(segment
		(start 168.390062 -203.710286)
		(end 168.62044 -203.710286)
		(width 0.14478)
		(layer "In6.Cu")
		(net "M_K_CPU1_SA_DQ<6>")
	)
	(segment
		(start 192.456562 -203.93914)
		(end 192.61963 -204.102208)
		(width 0.14478)
		(layer "In6.Cu")
		(net "M_K_CPU1_SA_DQ<6>")
	)
	(segment
		(start 190.171578 -204.100684)
		(end 190.401956 -204.100684)
		(width 0.14478)
		(layer "In6.Cu")
		(net "M_K_CPU1_SA_DQ<6>")
	)
	(segment
		(start 191.900048 -203.547218)
		(end 191.900048 -203.494894)
		(width 0.14478)
		(layer "In6.Cu")
		(net "M_K_CPU1_SA_DQ<6>")
	)
	(segment
		(start 180.459634 -204.171804)
		(end 180.622702 -204.334872)
		(width 0.14478)
		(layer "In6.Cu")
		(net "M_K_CPU1_SA_DQ<6>")
	)
	(segment
		(start 181.140862 -204.560424)
		(end 181.991 -203.710286)
		(width 0.14478)
		(layer "In6.Cu")
		(net "M_K_CPU1_SA_DQ<6>")
	)
	(segment
		(start 146.984466 -225.27641)
		(end 146.984466 -224.57156)
		(width 0.0889)
		(layer "In6.Cu")
		(net "M_K_CPU1_SA_DQ<6>")
	)
	(segment
		(start 190.565024 -203.937616)
		(end 190.565024 -203.873354)
		(width 0.14478)
		(layer "In6.Cu")
		(net "M_K_CPU1_SA_DQ<6>")
	)
	(segment
		(start 192.850008 -204.102208)
		(end 193.013076 -203.93914)
		(width 0.14478)
		(layer "In6.Cu")
		(net "M_K_CPU1_SA_DQ<6>")
	)
	(segment
		(start 180.78577 -204.560424)
		(end 181.140862 -204.560424)
		(width 0.14478)
		(layer "In6.Cu")
		(net "M_K_CPU1_SA_DQ<6>")
	)
	(segment
		(start 159.028892 -209.344514)
		(end 159.317944 -209.633566)
		(width 0.14478)
		(layer "In6.Cu")
		(net "M_K_CPU1_SA_DQ<6>")
	)
	(segment
		(start 190.401956 -204.100684)
		(end 190.565024 -203.937616)
		(width 0.14478)
		(layer "In6.Cu")
		(net "M_K_CPU1_SA_DQ<6>")
	)
	(segment
		(start 159.604456 -208.564226)
		(end 159.80918 -208.564226)
		(width 0.14478)
		(layer "In6.Cu")
		(net "M_K_CPU1_SA_DQ<6>")
	)
	(segment
		(start 193.013076 -203.505054)
		(end 193.176144 -203.341986)
		(width 0.14478)
		(layer "In6.Cu")
		(net "M_K_CPU1_SA_DQ<6>")
	)
	(segment
		(start 147.813522 -223.74479)
		(end 151.270208 -220.288104)
		(width 0.14478)
		(layer "In6.Cu")
		(net "M_K_CPU1_SA_DQ<6>")
	)
	(segment
		(start 168.063926 -203.319126)
		(end 168.226994 -203.482194)
		(width 0.14478)
		(layer "In6.Cu")
		(net "M_K_CPU1_SA_DQ<6>")
	)
	(segment
		(start 160.507426 -207.64627)
		(end 163.593272 -204.560424)
		(width 0.14478)
		(layer "In6.Cu")
		(net "M_K_CPU1_SA_DQ<6>")
	)
	(segment
		(start 175.190658 -203.321666)
		(end 175.421036 -203.321666)
		(width 0.14478)
		(layer "In6.Cu")
		(net "M_K_CPU1_SA_DQ<6>")
	)
	(segment
		(start 184.99582 -203.710286)
		(end 185.845958 -204.560424)
		(width 0.14478)
		(layer "In6.Cu")
		(net "M_K_CPU1_SA_DQ<6>")
	)
	(segment
		(start 187.61329 -204.335634)
		(end 187.776358 -204.172566)
		(width 0.14478)
		(layer "In6.Cu")
		(net "M_K_CPU1_SA_DQ<6>")
	)
	(segment
		(start 159.708088 -209.448146)
		(end 159.708088 -209.243422)
		(width 0.14478)
		(layer "In6.Cu")
		(net "M_K_CPU1_SA_DQ<6>")
	)
	(segment
		(start 193.56959 -203.547218)
		(end 193.732658 -203.710286)
		(width 0.14478)
		(layer "In6.Cu")
		(net "M_K_CPU1_SA_DQ<6>")
	)
	(segment
		(start 194.17919 -203.710286)
		(end 194.604132 -204.135228)
		(width 0.14478)
		(layer "In6.Cu")
		(net "M_K_CPU1_SA_DQ<6>")
	)
	(segment
		(start 144.102582 -228.848158)
		(end 144.783556 -228.167184)
		(width 0.0889)
		(layer "In6.Cu")
		(net "M_K_CPU1_SA_DQ<6>")
	)
	(segment
		(start 180.622702 -204.334872)
		(end 180.622702 -204.397356)
		(width 0.14478)
		(layer "In6.Cu")
		(net "M_K_CPU1_SA_DQ<6>")
	)
	(segment
		(start 175.584104 -203.484734)
		(end 175.584104 -203.547218)
		(width 0.14478)
		(layer "In6.Cu")
		(net "M_K_CPU1_SA_DQ<6>")
	)
	(segment
		(start 159.522668 -209.633566)
		(end 159.708088 -209.448146)
		(width 0.14478)
		(layer "In6.Cu")
		(net "M_K_CPU1_SA_DQ<6>")
	)
	(segment
		(start 189.845442 -203.710286)
		(end 190.00851 -203.873354)
		(width 0.14478)
		(layer "In6.Cu")
		(net "M_K_CPU1_SA_DQ<6>")
	)
	(segment
		(start 192.61963 -204.102208)
		(end 192.850008 -204.102208)
		(width 0.14478)
		(layer "In6.Cu")
		(net "M_K_CPU1_SA_DQ<6>")
	)
	(segment
		(start 167.67048 -203.547218)
		(end 167.67048 -203.482194)
		(width 0.14478)
		(layer "In6.Cu")
		(net "M_K_CPU1_SA_DQ<6>")
	)
	(segment
		(start 143.73479 -228.848158)
		(end 144.102582 -228.848158)
		(width 0.0889)
		(layer "In6.Cu")
		(net "M_K_CPU1_SA_DQ<6>")
	)
	(segment
		(start 165.005766 -204.166724)
		(end 165.236144 -204.166724)
		(width 0.14478)
		(layer "In6.Cu")
		(net "M_K_CPU1_SA_DQ<6>")
	)
	(arc
		(start 143.451834 -228.771958)
		(mid 143.58827 -228.828783)
		(end 143.73479 -228.848158)
		(width 0.0889)
		(layer "In6.Cu")
		(net "M_K_CPU1_SA_DQ<6>")
	)
	(arc
		(start 142.574772 -228.803708)
		(mid 142.82998 -228.847185)
		(end 143.077692 -228.771958)
		(width 0.0889)
		(layer "In6.Cu")
		(net "M_K_CPU1_SA_DQ<6>")
	)
	(arc
		(start 143.086074 -228.767132)
		(mid 143.269582 -228.721638)
		(end 143.451834 -228.771958)
		(width 0.0889)
		(layer "In6.Cu")
		(net "M_K_CPU1_SA_DQ<6>")
	)
	(segment
		(start 140.91793 -229.360476)
		(end 141.384782 -229.094538)
		(width 0.10668)
		(layer "F.Cu")
		(net "M_K_CPU1_SA_DQ<5>")
	)
	(segment
		(start 151.805386 -220.509846)
		(end 151.805386 -218.02471)
		(width 0.14478)
		(layer "In6.Cu")
		(net "M_K_CPU1_SA_DQ<5>")
	)
	(segment
		(start 166.956486 -204.56017)
		(end 169.907966 -204.56017)
		(width 0.14478)
		(layer "In6.Cu")
		(net "M_K_CPU1_SA_DQ<5>")
	)
	(segment
		(start 146.232626 -226.44227)
		(end 147.363688 -225.311208)
		(width 0.0889)
		(layer "In6.Cu")
		(net "M_K_CPU1_SA_DQ<5>")
	)
	(segment
		(start 166.106348 -205.410308)
		(end 166.956486 -204.56017)
		(width 0.14478)
		(layer "In6.Cu")
		(net "M_K_CPU1_SA_DQ<5>")
	)
	(segment
		(start 143.734536 -229.340664)
		(end 144.007078 -229.340664)
		(width 0.0889)
		(layer "In6.Cu")
		(net "M_K_CPU1_SA_DQ<5>")
	)
	(segment
		(start 145.18132 -228.520244)
		(end 146.017488 -227.684076)
		(width 0.0889)
		(layer "In6.Cu")
		(net "M_K_CPU1_SA_DQ<5>")
	)
	(segment
		(start 162.88893 -206.941166)
		(end 162.88893 -206.001366)
		(width 0.14478)
		(layer "In6.Cu")
		(net "M_K_CPU1_SA_DQ<5>")
	)
	(segment
		(start 151.805386 -218.02471)
		(end 162.88893 -206.941166)
		(width 0.14478)
		(layer "In6.Cu")
		(net "M_K_CPU1_SA_DQ<5>")
	)
	(segment
		(start 181.140862 -205.410308)
		(end 181.990746 -204.560424)
		(width 0.14478)
		(layer "In6.Cu")
		(net "M_K_CPU1_SA_DQ<5>")
	)
	(segment
		(start 144.007078 -229.340664)
		(end 144.827498 -228.520244)
		(width 0.0889)
		(layer "In6.Cu")
		(net "M_K_CPU1_SA_DQ<5>")
	)
	(segment
		(start 196.457824 -205.332584)
		(end 196.688202 -205.332584)
		(width 0.14478)
		(layer "In6.Cu")
		(net "M_K_CPU1_SA_DQ<5>")
	)
	(segment
		(start 162.88893 -206.001366)
		(end 163.479988 -205.410308)
		(width 0.14478)
		(layer "In6.Cu")
		(net "M_K_CPU1_SA_DQ<5>")
	)
	(segment
		(start 143.077692 -229.416864)
		(end 143.086074 -229.42169)
		(width 0.0889)
		(layer "In6.Cu")
		(net "M_K_CPU1_SA_DQ<5>")
	)
	(segment
		(start 185.845958 -205.410308)
		(end 188.801248 -205.410308)
		(width 0.14478)
		(layer "In6.Cu")
		(net "M_K_CPU1_SA_DQ<5>")
	)
	(segment
		(start 177.452274 -204.560424)
		(end 178.302158 -205.410308)
		(width 0.14478)
		(layer "In6.Cu")
		(net "M_K_CPU1_SA_DQ<5>")
	)
	(segment
		(start 197.014338 -204.560424)
		(end 198.279258 -204.560424)
		(width 0.14478)
		(layer "In6.Cu")
		(net "M_K_CPU1_SA_DQ<5>")
	)
	(segment
		(start 142.503398 -229.42169)
		(end 142.51178 -229.416864)
		(width 0.0889)
		(layer "In6.Cu")
		(net "M_K_CPU1_SA_DQ<5>")
	)
	(segment
		(start 163.479988 -205.410308)
		(end 166.106348 -205.410308)
		(width 0.14478)
		(layer "In6.Cu")
		(net "M_K_CPU1_SA_DQ<5>")
	)
	(segment
		(start 147.363688 -224.951544)
		(end 147.869148 -224.446084)
		(width 0.0889)
		(layer "In6.Cu")
		(net "M_K_CPU1_SA_DQ<5>")
	)
	(segment
		(start 147.869148 -224.446084)
		(end 151.805386 -220.509846)
		(width 0.14478)
		(layer "In6.Cu")
		(net "M_K_CPU1_SA_DQ<5>")
	)
	(segment
		(start 198.279258 -204.560424)
		(end 198.7042 -204.985366)
		(width 0.14478)
		(layer "In6.Cu")
		(net "M_K_CPU1_SA_DQ<5>")
	)
	(segment
		(start 146.017488 -226.961954)
		(end 146.232626 -226.44227)
		(width 0.0889)
		(layer "In6.Cu")
		(net "M_K_CPU1_SA_DQ<5>")
	)
	(segment
		(start 189.651132 -204.560424)
		(end 196.131688 -204.560424)
		(width 0.14478)
		(layer "In6.Cu")
		(net "M_K_CPU1_SA_DQ<5>")
	)
	(segment
		(start 181.990746 -204.560424)
		(end 184.996074 -204.560424)
		(width 0.14478)
		(layer "In6.Cu")
		(net "M_K_CPU1_SA_DQ<5>")
	)
	(segment
		(start 144.827498 -228.520244)
		(end 145.18132 -228.520244)
		(width 0.0889)
		(layer "In6.Cu")
		(net "M_K_CPU1_SA_DQ<5>")
	)
	(segment
		(start 196.688202 -205.332584)
		(end 196.85127 -205.169516)
		(width 0.14478)
		(layer "In6.Cu")
		(net "M_K_CPU1_SA_DQ<5>")
	)
	(segment
		(start 196.85127 -204.723492)
		(end 197.014338 -204.560424)
		(width 0.14478)
		(layer "In6.Cu")
		(net "M_K_CPU1_SA_DQ<5>")
	)
	(segment
		(start 147.363688 -225.311208)
		(end 147.363688 -224.951544)
		(width 0.0889)
		(layer "In6.Cu")
		(net "M_K_CPU1_SA_DQ<5>")
	)
	(segment
		(start 196.85127 -205.169516)
		(end 196.85127 -204.723492)
		(width 0.14478)
		(layer "In6.Cu")
		(net "M_K_CPU1_SA_DQ<5>")
	)
	(segment
		(start 196.294756 -204.723492)
		(end 196.294756 -205.169516)
		(width 0.14478)
		(layer "In6.Cu")
		(net "M_K_CPU1_SA_DQ<5>")
	)
	(segment
		(start 196.131688 -204.560424)
		(end 196.294756 -204.723492)
		(width 0.14478)
		(layer "In6.Cu")
		(net "M_K_CPU1_SA_DQ<5>")
	)
	(segment
		(start 178.302158 -205.410308)
		(end 181.140862 -205.410308)
		(width 0.14478)
		(layer "In6.Cu")
		(net "M_K_CPU1_SA_DQ<5>")
	)
	(segment
		(start 141.230858 -229.359968)
		(end 141.252956 -229.443026)
		(width 0.0889)
		(layer "In6.Cu")
		(net "M_K_CPU1_SA_DQ<5>")
	)
	(segment
		(start 141.384782 -229.094538)
		(end 141.230858 -229.359968)
		(width 0.0889)
		(layer "In6.Cu")
		(net "M_K_CPU1_SA_DQ<5>")
	)
	(segment
		(start 146.017488 -227.684076)
		(end 146.017488 -226.961954)
		(width 0.0889)
		(layer "In6.Cu")
		(net "M_K_CPU1_SA_DQ<5>")
	)
	(segment
		(start 170.758104 -205.410308)
		(end 173.609254 -205.410308)
		(width 0.14478)
		(layer "In6.Cu")
		(net "M_K_CPU1_SA_DQ<5>")
	)
	(segment
		(start 188.801248 -205.410308)
		(end 189.651132 -204.560424)
		(width 0.14478)
		(layer "In6.Cu")
		(net "M_K_CPU1_SA_DQ<5>")
	)
	(segment
		(start 169.907966 -204.56017)
		(end 170.758104 -205.410308)
		(width 0.14478)
		(layer "In6.Cu")
		(net "M_K_CPU1_SA_DQ<5>")
	)
	(segment
		(start 173.609254 -205.410308)
		(end 174.459138 -204.560424)
		(width 0.14478)
		(layer "In6.Cu")
		(net "M_K_CPU1_SA_DQ<5>")
	)
	(segment
		(start 174.459138 -204.560424)
		(end 177.452274 -204.560424)
		(width 0.14478)
		(layer "In6.Cu")
		(net "M_K_CPU1_SA_DQ<5>")
	)
	(segment
		(start 184.996074 -204.560424)
		(end 185.845958 -205.410308)
		(width 0.14478)
		(layer "In6.Cu")
		(net "M_K_CPU1_SA_DQ<5>")
	)
	(segment
		(start 196.294756 -205.169516)
		(end 196.457824 -205.332584)
		(width 0.14478)
		(layer "In6.Cu")
		(net "M_K_CPU1_SA_DQ<5>")
	)
	(arc
		(start 141.571726 -229.416864)
		(mid 141.854682 -229.340687)
		(end 142.137638 -229.416864)
		(width 0.0889)
		(layer "In6.Cu")
		(net "M_K_CPU1_SA_DQ<5>")
	)
	(arc
		(start 141.252956 -229.443026)
		(mid 141.415287 -229.465875)
		(end 141.571726 -229.416864)
		(width 0.0889)
		(layer "In6.Cu")
		(net "M_K_CPU1_SA_DQ<5>")
	)
	(arc
		(start 142.137638 -229.416864)
		(mid 142.319889 -229.467248)
		(end 142.503398 -229.42169)
		(width 0.0889)
		(layer "In6.Cu")
		(net "M_K_CPU1_SA_DQ<5>")
	)
	(arc
		(start 143.451834 -229.416864)
		(mid 143.588152 -229.360097)
		(end 143.734536 -229.340664)
		(width 0.0889)
		(layer "In6.Cu")
		(net "M_K_CPU1_SA_DQ<5>")
	)
	(arc
		(start 142.51178 -229.416864)
		(mid 142.794736 -229.340687)
		(end 143.077692 -229.416864)
		(width 0.0889)
		(layer "In6.Cu")
		(net "M_K_CPU1_SA_DQ<5>")
	)
	(arc
		(start 143.086074 -229.42169)
		(mid 143.269582 -229.467215)
		(end 143.451834 -229.416864)
		(width 0.0889)
		(layer "In6.Cu")
		(net "M_K_CPU1_SA_DQ<5>")
	)
	(segment
		(start 142.327884 -228.55047)
		(end 142.794736 -228.284532)
		(width 0.10668)
		(layer "F.Cu")
		(net "M_K_CPU1_SA_DQ<4>")
	)
	(segment
		(start 189.641734 -202.8698)
		(end 196.42963 -202.8698)
		(width 0.14478)
		(layer "In6.Cu")
		(net "M_K_CPU1_SA_DQ<4>")
	)
	(segment
		(start 157.90799 -209.587846)
		(end 163.78555 -203.710286)
		(width 0.14478)
		(layer "In6.Cu")
		(net "M_K_CPU1_SA_DQ<4>")
	)
	(segment
		(start 197.315836 -203.923646)
		(end 197.57771 -203.923646)
		(width 0.14478)
		(layer "In6.Cu")
		(net "M_K_CPU1_SA_DQ<4>")
	)
	(segment
		(start 163.78555 -203.710286)
		(end 166.106348 -203.710286)
		(width 0.14478)
		(layer "In6.Cu")
		(net "M_K_CPU1_SA_DQ<4>")
	)
	(segment
		(start 197.171056 -203.778866)
		(end 197.315836 -203.923646)
		(width 0.14478)
		(layer "In6.Cu")
		(net "M_K_CPU1_SA_DQ<4>")
	)
	(segment
		(start 145.522188 -227.600256)
		(end 145.522188 -227.00361)
		(width 0.0889)
		(layer "In6.Cu")
		(net "M_K_CPU1_SA_DQ<4>")
	)
	(segment
		(start 188.79185 -203.719684)
		(end 189.641734 -202.8698)
		(width 0.14478)
		(layer "In6.Cu")
		(net "M_K_CPU1_SA_DQ<4>")
	)
	(segment
		(start 145.522188 -227.00361)
		(end 145.931128 -226.016566)
		(width 0.0889)
		(layer "In6.Cu")
		(net "M_K_CPU1_SA_DQ<4>")
	)
	(segment
		(start 174.44974 -202.8698)
		(end 177.461672 -202.8698)
		(width 0.14478)
		(layer "In6.Cu")
		(net "M_K_CPU1_SA_DQ<4>")
	)
	(segment
		(start 197.72249 -203.778866)
		(end 197.72249 -203.005182)
		(width 0.14478)
		(layer "In6.Cu")
		(net "M_K_CPU1_SA_DQ<4>")
	)
	(segment
		(start 181.131464 -203.719684)
		(end 181.981348 -202.8698)
		(width 0.14478)
		(layer "In6.Cu")
		(net "M_K_CPU1_SA_DQ<4>")
	)
	(segment
		(start 197.72249 -203.005182)
		(end 197.86727 -202.860402)
		(width 0.14478)
		(layer "In6.Cu")
		(net "M_K_CPU1_SA_DQ<4>")
	)
	(segment
		(start 197.171056 -203.005182)
		(end 197.171056 -203.778866)
		(width 0.14478)
		(layer "In6.Cu")
		(net "M_K_CPU1_SA_DQ<4>")
	)
	(segment
		(start 147.878038 -223.034606)
		(end 147.880578 -223.034606)
		(width 0.0889)
		(layer "In6.Cu")
		(net "M_K_CPU1_SA_DQ<4>")
	)
	(segment
		(start 150.815548 -217.683842)
		(end 157.90799 -210.5914)
		(width 0.14478)
		(layer "In6.Cu")
		(net "M_K_CPU1_SA_DQ<4>")
	)
	(segment
		(start 144.699228 -227.963984)
		(end 145.15846 -227.963984)
		(width 0.0889)
		(layer "In6.Cu")
		(net "M_K_CPU1_SA_DQ<4>")
	)
	(segment
		(start 185.005472 -202.8698)
		(end 185.855356 -203.719684)
		(width 0.14478)
		(layer "In6.Cu")
		(net "M_K_CPU1_SA_DQ<4>")
	)
	(segment
		(start 197.026276 -202.860402)
		(end 197.171056 -203.005182)
		(width 0.14478)
		(layer "In6.Cu")
		(net "M_K_CPU1_SA_DQ<4>")
	)
	(segment
		(start 145.15846 -227.963984)
		(end 145.522188 -227.600256)
		(width 0.0889)
		(layer "In6.Cu")
		(net "M_K_CPU1_SA_DQ<4>")
	)
	(segment
		(start 142.794736 -228.284532)
		(end 142.640812 -228.549962)
		(width 0.0889)
		(layer "In6.Cu")
		(net "M_K_CPU1_SA_DQ<4>")
	)
	(segment
		(start 169.917364 -202.869546)
		(end 170.767502 -203.719684)
		(width 0.14478)
		(layer "In6.Cu")
		(net "M_K_CPU1_SA_DQ<4>")
	)
	(segment
		(start 166.106348 -203.710286)
		(end 166.947088 -202.869546)
		(width 0.14478)
		(layer "In6.Cu")
		(net "M_K_CPU1_SA_DQ<4>")
	)
	(segment
		(start 144.005554 -228.657658)
		(end 144.699228 -227.963984)
		(width 0.0889)
		(layer "In6.Cu")
		(net "M_K_CPU1_SA_DQ<4>")
	)
	(segment
		(start 142.640812 -228.549962)
		(end 142.663164 -228.633274)
		(width 0.0889)
		(layer "In6.Cu")
		(net "M_K_CPU1_SA_DQ<4>")
	)
	(segment
		(start 177.461672 -202.8698)
		(end 178.311556 -203.719684)
		(width 0.14478)
		(layer "In6.Cu")
		(net "M_K_CPU1_SA_DQ<4>")
	)
	(segment
		(start 166.947088 -202.869546)
		(end 169.917364 -202.869546)
		(width 0.14478)
		(layer "In6.Cu")
		(net "M_K_CPU1_SA_DQ<4>")
	)
	(segment
		(start 197.57771 -203.923646)
		(end 197.72249 -203.778866)
		(width 0.14478)
		(layer "In6.Cu")
		(net "M_K_CPU1_SA_DQ<4>")
	)
	(segment
		(start 197.86727 -202.860402)
		(end 198.279258 -202.860402)
		(width 0.14478)
		(layer "In6.Cu")
		(net "M_K_CPU1_SA_DQ<4>")
	)
	(segment
		(start 196.439028 -202.860402)
		(end 197.026276 -202.860402)
		(width 0.14478)
		(layer "In6.Cu")
		(net "M_K_CPU1_SA_DQ<4>")
	)
	(segment
		(start 145.931128 -224.981516)
		(end 147.878038 -223.034606)
		(width 0.0889)
		(layer "In6.Cu")
		(net "M_K_CPU1_SA_DQ<4>")
	)
	(segment
		(start 145.931128 -226.016566)
		(end 145.931128 -224.981516)
		(width 0.0889)
		(layer "In6.Cu")
		(net "M_K_CPU1_SA_DQ<4>")
	)
	(segment
		(start 157.90799 -210.5914)
		(end 157.90799 -209.587846)
		(width 0.14478)
		(layer "In6.Cu")
		(net "M_K_CPU1_SA_DQ<4>")
	)
	(segment
		(start 178.311556 -203.719684)
		(end 181.131464 -203.719684)
		(width 0.14478)
		(layer "In6.Cu")
		(net "M_K_CPU1_SA_DQ<4>")
	)
	(segment
		(start 173.599856 -203.719684)
		(end 174.44974 -202.8698)
		(width 0.14478)
		(layer "In6.Cu")
		(net "M_K_CPU1_SA_DQ<4>")
	)
	(segment
		(start 170.767502 -203.719684)
		(end 173.599856 -203.719684)
		(width 0.14478)
		(layer "In6.Cu")
		(net "M_K_CPU1_SA_DQ<4>")
	)
	(segment
		(start 196.42963 -202.8698)
		(end 196.439028 -202.860402)
		(width 0.14478)
		(layer "In6.Cu")
		(net "M_K_CPU1_SA_DQ<4>")
	)
	(segment
		(start 181.981348 -202.8698)
		(end 185.005472 -202.8698)
		(width 0.14478)
		(layer "In6.Cu")
		(net "M_K_CPU1_SA_DQ<4>")
	)
	(segment
		(start 185.855356 -203.719684)
		(end 188.79185 -203.719684)
		(width 0.14478)
		(layer "In6.Cu")
		(net "M_K_CPU1_SA_DQ<4>")
	)
	(segment
		(start 147.880578 -223.034606)
		(end 150.815548 -220.099636)
		(width 0.14478)
		(layer "In6.Cu")
		(net "M_K_CPU1_SA_DQ<4>")
	)
	(segment
		(start 150.815548 -220.099636)
		(end 150.815548 -217.683842)
		(width 0.14478)
		(layer "In6.Cu")
		(net "M_K_CPU1_SA_DQ<4>")
	)
	(segment
		(start 143.73479 -228.657658)
		(end 144.005554 -228.657658)
		(width 0.0889)
		(layer "In6.Cu")
		(net "M_K_CPU1_SA_DQ<4>")
	)
	(segment
		(start 198.279258 -202.860402)
		(end 198.7042 -203.285344)
		(width 0.14478)
		(layer "In6.Cu")
		(net "M_K_CPU1_SA_DQ<4>")
	)
	(arc
		(start 142.663164 -228.633274)
		(mid 142.825353 -228.656009)
		(end 142.98168 -228.607112)
		(width 0.0889)
		(layer "In6.Cu")
		(net "M_K_CPU1_SA_DQ<4>")
	)
	(arc
		(start 142.98168 -228.607112)
		(mid 143.264636 -228.530935)
		(end 143.547592 -228.607112)
		(width 0.0889)
		(layer "In6.Cu")
		(net "M_K_CPU1_SA_DQ<4>")
	)
	(arc
		(start 143.547592 -228.607112)
		(mid 143.637848 -228.644765)
		(end 143.73479 -228.657658)
		(width 0.0889)
		(layer "In6.Cu")
		(net "M_K_CPU1_SA_DQ<4>")
	)
	(segment
		(start 140.447776 -226.930458)
		(end 140.914882 -226.66452)
		(width 0.10668)
		(layer "F.Cu")
		(net "M_K_CPU1_SA_DQ<3>")
	)
	(segment
		(start 165.219126 -200.476866)
		(end 165.219126 -200.455276)
		(width 0.14478)
		(layer "In6.Cu")
		(net "M_K_CPU1_SA_DQ<3>")
	)
	(segment
		(start 188.368686 -200.310496)
		(end 188.673232 -200.310496)
		(width 0.14478)
		(layer "In6.Cu")
		(net "M_K_CPU1_SA_DQ<3>")
	)
	(segment
		(start 141.667738 -226.34194)
		(end 141.67612 -226.337114)
		(width 0.0889)
		(layer "In6.Cu")
		(net "M_K_CPU1_SA_DQ<3>")
	)
	(segment
		(start 188.673232 -200.310496)
		(end 189.532768 -199.45096)
		(width 0.14478)
		(layer "In6.Cu")
		(net "M_K_CPU1_SA_DQ<3>")
	)
	(segment
		(start 143.547592 -226.34194)
		(end 143.586708 -226.31908)
		(width 0.0889)
		(layer "In6.Cu")
		(net "M_K_CPU1_SA_DQ<3>")
	)
	(segment
		(start 181.140862 -200.310496)
		(end 181.991 -199.460358)
		(width 0.14478)
		(layer "In6.Cu")
		(net "M_K_CPU1_SA_DQ<3>")
	)
	(segment
		(start 188.04255 -199.924924)
		(end 188.205618 -200.087992)
		(width 0.14478)
		(layer "In6.Cu")
		(net "M_K_CPU1_SA_DQ<3>")
	)
	(segment
		(start 188.205618 -200.087992)
		(end 188.205618 -200.147428)
		(width 0.14478)
		(layer "In6.Cu")
		(net "M_K_CPU1_SA_DQ<3>")
	)
	(segment
		(start 192.312798 -199.066404)
		(end 192.475866 -199.229472)
		(width 0.14478)
		(layer "In6.Cu")
		(net "M_K_CPU1_SA_DQ<3>")
	)
	(segment
		(start 140.914882 -226.66452)
		(end 141.068806 -226.39909)
		(width 0.0889)
		(layer "In6.Cu")
		(net "M_K_CPU1_SA_DQ<3>")
	)
	(segment
		(start 192.475866 -199.229472)
		(end 192.475866 -199.29729)
		(width 0.14478)
		(layer "In6.Cu")
		(net "M_K_CPU1_SA_DQ<3>")
	)
	(segment
		(start 174.459392 -199.460358)
		(end 174.787052 -199.460358)
		(width 0.14478)
		(layer "In6.Cu")
		(net "M_K_CPU1_SA_DQ<3>")
	)
	(segment
		(start 183.267096 -199.45096)
		(end 184.986422 -199.45096)
		(width 0.14478)
		(layer "In6.Cu")
		(net "M_K_CPU1_SA_DQ<3>")
	)
	(segment
		(start 144.017746 -223.911922)
		(end 144.056862 -223.889062)
		(width 0.0889)
		(layer "In6.Cu")
		(net "M_K_CPU1_SA_DQ<3>")
	)
	(segment
		(start 192.638934 -199.460358)
		(end 193.04889 -199.460358)
		(width 0.14478)
		(layer "In6.Cu")
		(net "M_K_CPU1_SA_DQ<3>")
	)
	(segment
		(start 183.113426 -199.29729)
		(end 183.267096 -199.45096)
		(width 0.14478)
		(layer "In6.Cu")
		(net "M_K_CPU1_SA_DQ<3>")
	)
	(segment
		(start 144.457166 -223.119696)
		(end 144.487646 -223.101916)
		(width 0.0889)
		(layer "In6.Cu")
		(net "M_K_CPU1_SA_DQ<3>")
	)
	(segment
		(start 175.343566 -199.074024)
		(end 175.506634 -199.237092)
		(width 0.14478)
		(layer "In6.Cu")
		(net "M_K_CPU1_SA_DQ<3>")
	)
	(segment
		(start 164.667692 -200.144126)
		(end 164.667692 -200.476866)
		(width 0.14478)
		(layer "In6.Cu")
		(net "M_K_CPU1_SA_DQ<3>")
	)
	(segment
		(start 192.08242 -199.066404)
		(end 192.312798 -199.066404)
		(width 0.14478)
		(layer "In6.Cu")
		(net "M_K_CPU1_SA_DQ<3>")
	)
	(segment
		(start 180.6702 -200.147428)
		(end 180.833268 -200.310496)
		(width 0.14478)
		(layer "In6.Cu")
		(net "M_K_CPU1_SA_DQ<3>")
	)
	(segment
		(start 166.066724 -200.310496)
		(end 166.92626 -199.45096)
		(width 0.14478)
		(layer "In6.Cu")
		(net "M_K_CPU1_SA_DQ<3>")
	)
	(segment
		(start 174.95012 -199.29729)
		(end 174.95012 -199.237092)
		(width 0.14478)
		(layer "In6.Cu")
		(net "M_K_CPU1_SA_DQ<3>")
	)
	(segment
		(start 163.711128 -200.310496)
		(end 163.971478 -200.310496)
		(width 0.14478)
		(layer "In6.Cu")
		(net "M_K_CPU1_SA_DQ<3>")
	)
	(segment
		(start 182.393844 -199.460358)
		(end 182.556912 -199.29729)
		(width 0.14478)
		(layer "In6.Cu")
		(net "M_K_CPU1_SA_DQ<3>")
	)
	(segment
		(start 182.71998 -199.066404)
		(end 182.950358 -199.066404)
		(width 0.14478)
		(layer "In6.Cu")
		(net "M_K_CPU1_SA_DQ<3>")
	)
	(segment
		(start 187.649104 -200.147428)
		(end 187.649104 -200.087992)
		(width 0.14478)
		(layer "In6.Cu")
		(net "M_K_CPU1_SA_DQ<3>")
	)
	(segment
		(start 182.950358 -199.066404)
		(end 183.113426 -199.229472)
		(width 0.14478)
		(layer "In6.Cu")
		(net "M_K_CPU1_SA_DQ<3>")
	)
	(segment
		(start 175.506634 -199.237092)
		(end 175.506634 -199.29729)
		(width 0.14478)
		(layer "In6.Cu")
		(net "M_K_CPU1_SA_DQ<3>")
	)
	(segment
		(start 144.925034 -222.31096)
		(end 144.9578 -222.29191)
		(width 0.0889)
		(layer "In6.Cu")
		(net "M_K_CPU1_SA_DQ<3>")
	)
	(segment
		(start 177.442622 -199.45096)
		(end 178.29276 -200.301098)
		(width 0.14478)
		(layer "In6.Cu")
		(net "M_K_CPU1_SA_DQ<3>")
	)
	(segment
		(start 143.985996 -225.550222)
		(end 144.017746 -225.531934)
		(width 0.0889)
		(layer "In6.Cu")
		(net "M_K_CPU1_SA_DQ<3>")
	)
	(segment
		(start 193.04889 -199.460358)
		(end 193.211958 -199.623426)
		(width 0.14478)
		(layer "In6.Cu")
		(net "M_K_CPU1_SA_DQ<3>")
	)
	(segment
		(start 145.144744 -222.247968)
		(end 145.313908 -222.078804)
		(width 0.0889)
		(layer "In6.Cu")
		(net "M_K_CPU1_SA_DQ<3>")
	)
	(segment
		(start 193.605404 -199.984106)
		(end 193.768472 -199.821038)
		(width 0.14478)
		(layer "In6.Cu")
		(net "M_K_CPU1_SA_DQ<3>")
	)
	(segment
		(start 180.113686 -200.090532)
		(end 180.276754 -199.927464)
		(width 0.14478)
		(layer "In6.Cu")
		(net "M_K_CPU1_SA_DQ<3>")
	)
	(segment
		(start 175.660304 -199.45096)
		(end 177.442622 -199.45096)
		(width 0.14478)
		(layer "In6.Cu")
		(net "M_K_CPU1_SA_DQ<3>")
	)
	(segment
		(start 185.83656 -200.301098)
		(end 187.495434 -200.301098)
		(width 0.14478)
		(layer "In6.Cu")
		(net "M_K_CPU1_SA_DQ<3>")
	)
	(segment
		(start 170.936666 -200.301098)
		(end 172.490892 -200.301098)
		(width 0.14478)
		(layer "In6.Cu")
		(net "M_K_CPU1_SA_DQ<3>")
	)
	(segment
		(start 182.556912 -199.29729)
		(end 182.556912 -199.229472)
		(width 0.14478)
		(layer "In6.Cu")
		(net "M_K_CPU1_SA_DQ<3>")
	)
	(segment
		(start 144.017746 -225.531934)
		(end 144.056862 -225.509074)
		(width 0.0889)
		(layer "In6.Cu")
		(net "M_K_CPU1_SA_DQ<3>")
	)
	(segment
		(start 164.261038 -199.999346)
		(end 164.522912 -199.999346)
		(width 0.14478)
		(layer "In6.Cu")
		(net "M_K_CPU1_SA_DQ<3>")
	)
	(segment
		(start 175.506634 -199.29729)
		(end 175.660304 -199.45096)
		(width 0.14478)
		(layer "In6.Cu")
		(net "M_K_CPU1_SA_DQ<3>")
	)
	(segment
		(start 164.116258 -200.144126)
		(end 164.261038 -199.999346)
		(width 0.14478)
		(layer "In6.Cu")
		(net "M_K_CPU1_SA_DQ<3>")
	)
	(segment
		(start 194.17919 -199.460358)
		(end 194.604132 -199.8853)
		(width 0.14478)
		(layer "In6.Cu")
		(net "M_K_CPU1_SA_DQ<3>")
	)
	(segment
		(start 173.187106 -200.062846)
		(end 173.187106 -200.156318)
		(width 0.14478)
		(layer "In6.Cu")
		(net "M_K_CPU1_SA_DQ<3>")
	)
	(segment
		(start 144.056862 -224.579942)
		(end 144.017746 -224.557082)
		(width 0.0889)
		(layer "In6.Cu")
		(net "M_K_CPU1_SA_DQ<3>")
	)
	(segment
		(start 189.532768 -199.45096)
		(end 191.765682 -199.45096)
		(width 0.14478)
		(layer "In6.Cu")
		(net "M_K_CPU1_SA_DQ<3>")
	)
	(segment
		(start 173.331886 -200.301098)
		(end 173.618652 -200.301098)
		(width 0.14478)
		(layer "In6.Cu")
		(net "M_K_CPU1_SA_DQ<3>")
	)
	(segment
		(start 191.919352 -199.29729)
		(end 191.919352 -199.229472)
		(width 0.14478)
		(layer "In6.Cu")
		(net "M_K_CPU1_SA_DQ<3>")
	)
	(segment
		(start 145.723356 -221.240096)
		(end 148.389848 -218.573604)
		(width 0.14478)
		(layer "In6.Cu")
		(net "M_K_CPU1_SA_DQ<3>")
	)
	(segment
		(start 179.960016 -200.301098)
		(end 180.113686 -200.147428)
		(width 0.14478)
		(layer "In6.Cu")
		(net "M_K_CPU1_SA_DQ<3>")
	)
	(segment
		(start 164.812472 -200.621646)
		(end 165.074346 -200.621646)
		(width 0.14478)
		(layer "In6.Cu")
		(net "M_K_CPU1_SA_DQ<3>")
	)
	(segment
		(start 143.985996 -223.93021)
		(end 144.017746 -223.911922)
		(width 0.0889)
		(layer "In6.Cu")
		(net "M_K_CPU1_SA_DQ<3>")
	)
	(segment
		(start 144.017746 -224.557082)
		(end 143.985996 -224.538794)
		(width 0.0889)
		(layer "In6.Cu")
		(net "M_K_CPU1_SA_DQ<3>")
	)
	(segment
		(start 187.495434 -200.301098)
		(end 187.649104 -200.147428)
		(width 0.14478)
		(layer "In6.Cu")
		(net "M_K_CPU1_SA_DQ<3>")
	)
	(segment
		(start 181.991 -199.460358)
		(end 182.393844 -199.460358)
		(width 0.14478)
		(layer "In6.Cu")
		(net "M_K_CPU1_SA_DQ<3>")
	)
	(segment
		(start 193.93154 -199.460358)
		(end 194.17919 -199.460358)
		(width 0.14478)
		(layer "In6.Cu")
		(net "M_K_CPU1_SA_DQ<3>")
	)
	(segment
		(start 184.986422 -199.45096)
		(end 185.83656 -200.301098)
		(width 0.14478)
		(layer "In6.Cu")
		(net "M_K_CPU1_SA_DQ<3>")
	)
	(segment
		(start 192.475866 -199.29729)
		(end 192.638934 -199.460358)
		(width 0.14478)
		(layer "In6.Cu")
		(net "M_K_CPU1_SA_DQ<3>")
	)
	(segment
		(start 145.313908 -222.078804)
		(end 145.313908 -221.649544)
		(width 0.0889)
		(layer "In6.Cu")
		(net "M_K_CPU1_SA_DQ<3>")
	)
	(segment
		(start 145.313908 -221.649544)
		(end 145.723356 -221.240096)
		(width 0.0889)
		(layer "In6.Cu")
		(net "M_K_CPU1_SA_DQ<3>")
	)
	(segment
		(start 172.635672 -200.062846)
		(end 172.780452 -199.918066)
		(width 0.14478)
		(layer "In6.Cu")
		(net "M_K_CPU1_SA_DQ<3>")
	)
	(segment
		(start 172.780452 -199.918066)
		(end 173.042326 -199.918066)
		(width 0.14478)
		(layer "In6.Cu")
		(net "M_K_CPU1_SA_DQ<3>")
	)
	(segment
		(start 166.92626 -199.45096)
		(end 170.086528 -199.45096)
		(width 0.14478)
		(layer "In6.Cu")
		(net "M_K_CPU1_SA_DQ<3>")
	)
	(segment
		(start 148.389848 -218.573604)
		(end 148.389848 -215.631776)
		(width 0.14478)
		(layer "In6.Cu")
		(net "M_K_CPU1_SA_DQ<3>")
	)
	(segment
		(start 144.487646 -223.101916)
		(end 144.526762 -223.079056)
		(width 0.0889)
		(layer "In6.Cu")
		(net "M_K_CPU1_SA_DQ<3>")
	)
	(segment
		(start 187.812172 -199.924924)
		(end 188.04255 -199.924924)
		(width 0.14478)
		(layer "In6.Cu")
		(net "M_K_CPU1_SA_DQ<3>")
	)
	(segment
		(start 172.490892 -200.301098)
		(end 172.635672 -200.156318)
		(width 0.14478)
		(layer "In6.Cu")
		(net "M_K_CPU1_SA_DQ<3>")
	)
	(segment
		(start 180.6702 -200.090532)
		(end 180.6702 -200.147428)
		(width 0.14478)
		(layer "In6.Cu")
		(net "M_K_CPU1_SA_DQ<3>")
	)
	(segment
		(start 164.522912 -199.999346)
		(end 164.667692 -200.144126)
		(width 0.14478)
		(layer "In6.Cu")
		(net "M_K_CPU1_SA_DQ<3>")
	)
	(segment
		(start 193.768472 -199.623426)
		(end 193.93154 -199.460358)
		(width 0.14478)
		(layer "In6.Cu")
		(net "M_K_CPU1_SA_DQ<3>")
	)
	(segment
		(start 191.765682 -199.45096)
		(end 191.919352 -199.29729)
		(width 0.14478)
		(layer "In6.Cu")
		(net "M_K_CPU1_SA_DQ<3>")
	)
	(segment
		(start 193.768472 -199.821038)
		(end 193.768472 -199.623426)
		(width 0.14478)
		(layer "In6.Cu")
		(net "M_K_CPU1_SA_DQ<3>")
	)
	(segment
		(start 180.276754 -199.927464)
		(end 180.507132 -199.927464)
		(width 0.14478)
		(layer "In6.Cu")
		(net "M_K_CPU1_SA_DQ<3>")
	)
	(segment
		(start 174.95012 -199.237092)
		(end 175.113188 -199.074024)
		(width 0.14478)
		(layer "In6.Cu")
		(net "M_K_CPU1_SA_DQ<3>")
	)
	(segment
		(start 191.919352 -199.229472)
		(end 192.08242 -199.066404)
		(width 0.14478)
		(layer "In6.Cu")
		(net "M_K_CPU1_SA_DQ<3>")
	)
	(segment
		(start 175.113188 -199.074024)
		(end 175.343566 -199.074024)
		(width 0.14478)
		(layer "In6.Cu")
		(net "M_K_CPU1_SA_DQ<3>")
	)
	(segment
		(start 165.363906 -200.310496)
		(end 166.066724 -200.310496)
		(width 0.14478)
		(layer "In6.Cu")
		(net "M_K_CPU1_SA_DQ<3>")
	)
	(segment
		(start 141.068806 -226.39909)
		(end 141.164818 -226.37369)
		(width 0.0889)
		(layer "In6.Cu")
		(net "M_K_CPU1_SA_DQ<3>")
	)
	(segment
		(start 187.649104 -200.087992)
		(end 187.812172 -199.924924)
		(width 0.14478)
		(layer "In6.Cu")
		(net "M_K_CPU1_SA_DQ<3>")
	)
	(segment
		(start 173.618652 -200.301098)
		(end 174.459392 -199.460358)
		(width 0.14478)
		(layer "In6.Cu")
		(net "M_K_CPU1_SA_DQ<3>")
	)
	(segment
		(start 178.29276 -200.301098)
		(end 179.960016 -200.301098)
		(width 0.14478)
		(layer "In6.Cu")
		(net "M_K_CPU1_SA_DQ<3>")
	)
	(segment
		(start 180.113686 -200.147428)
		(end 180.113686 -200.090532)
		(width 0.14478)
		(layer "In6.Cu")
		(net "M_K_CPU1_SA_DQ<3>")
	)
	(segment
		(start 164.667692 -200.476866)
		(end 164.812472 -200.621646)
		(width 0.14478)
		(layer "In6.Cu")
		(net "M_K_CPU1_SA_DQ<3>")
	)
	(segment
		(start 193.375026 -199.984106)
		(end 193.605404 -199.984106)
		(width 0.14478)
		(layer "In6.Cu")
		(net "M_K_CPU1_SA_DQ<3>")
	)
	(segment
		(start 188.205618 -200.147428)
		(end 188.368686 -200.310496)
		(width 0.14478)
		(layer "In6.Cu")
		(net "M_K_CPU1_SA_DQ<3>")
	)
	(segment
		(start 193.211958 -199.821038)
		(end 193.375026 -199.984106)
		(width 0.14478)
		(layer "In6.Cu")
		(net "M_K_CPU1_SA_DQ<3>")
	)
	(segment
		(start 182.556912 -199.229472)
		(end 182.71998 -199.066404)
		(width 0.14478)
		(layer "In6.Cu")
		(net "M_K_CPU1_SA_DQ<3>")
	)
	(segment
		(start 173.187106 -200.156318)
		(end 173.331886 -200.301098)
		(width 0.14478)
		(layer "In6.Cu")
		(net "M_K_CPU1_SA_DQ<3>")
	)
	(segment
		(start 180.833268 -200.310496)
		(end 181.140862 -200.310496)
		(width 0.14478)
		(layer "In6.Cu")
		(net "M_K_CPU1_SA_DQ<3>")
	)
	(segment
		(start 148.389848 -215.631776)
		(end 163.711128 -200.310496)
		(width 0.14478)
		(layer "In6.Cu")
		(net "M_K_CPU1_SA_DQ<3>")
	)
	(segment
		(start 180.507132 -199.927464)
		(end 180.6702 -200.090532)
		(width 0.14478)
		(layer "In6.Cu")
		(net "M_K_CPU1_SA_DQ<3>")
	)
	(segment
		(start 170.086528 -199.45096)
		(end 170.936666 -200.301098)
		(width 0.14478)
		(layer "In6.Cu")
		(net "M_K_CPU1_SA_DQ<3>")
	)
	(segment
		(start 172.635672 -200.156318)
		(end 172.635672 -200.062846)
		(width 0.14478)
		(layer "In6.Cu")
		(net "M_K_CPU1_SA_DQ<3>")
	)
	(segment
		(start 173.042326 -199.918066)
		(end 173.187106 -200.062846)
		(width 0.14478)
		(layer "In6.Cu")
		(net "M_K_CPU1_SA_DQ<3>")
	)
	(segment
		(start 193.211958 -199.623426)
		(end 193.211958 -199.821038)
		(width 0.14478)
		(layer "In6.Cu")
		(net "M_K_CPU1_SA_DQ<3>")
	)
	(segment
		(start 164.116258 -200.165716)
		(end 164.116258 -200.144126)
		(width 0.14478)
		(layer "In6.Cu")
		(net "M_K_CPU1_SA_DQ<3>")
	)
	(segment
		(start 183.113426 -199.229472)
		(end 183.113426 -199.29729)
		(width 0.14478)
		(layer "In6.Cu")
		(net "M_K_CPU1_SA_DQ<3>")
	)
	(segment
		(start 165.219126 -200.455276)
		(end 165.363906 -200.310496)
		(width 0.14478)
		(layer "In6.Cu")
		(net "M_K_CPU1_SA_DQ<3>")
	)
	(segment
		(start 174.787052 -199.460358)
		(end 174.95012 -199.29729)
		(width 0.14478)
		(layer "In6.Cu")
		(net "M_K_CPU1_SA_DQ<3>")
	)
	(segment
		(start 163.971478 -200.310496)
		(end 164.116258 -200.165716)
		(width 0.14478)
		(layer "In6.Cu")
		(net "M_K_CPU1_SA_DQ<3>")
	)
	(segment
		(start 165.074346 -200.621646)
		(end 165.219126 -200.476866)
		(width 0.14478)
		(layer "In6.Cu")
		(net "M_K_CPU1_SA_DQ<3>")
	)
	(arc
		(start 144.300194 -223.424496)
		(mid 144.341743 -223.253074)
		(end 144.457166 -223.119696)
		(width 0.0889)
		(layer "In6.Cu")
		(net "M_K_CPU1_SA_DQ<3>")
	)
	(arc
		(start 141.67612 -226.337114)
		(mid 141.859628 -226.29162)
		(end 142.04188 -226.34194)
		(width 0.0889)
		(layer "In6.Cu")
		(net "M_K_CPU1_SA_DQ<3>")
	)
	(arc
		(start 144.770094 -222.61449)
		(mid 144.81106 -222.444084)
		(end 144.925034 -222.31096)
		(width 0.0889)
		(layer "In6.Cu")
		(net "M_K_CPU1_SA_DQ<3>")
	)
	(arc
		(start 143.83004 -225.854514)
		(mid 143.871295 -225.683543)
		(end 143.985996 -225.550222)
		(width 0.0889)
		(layer "In6.Cu")
		(net "M_K_CPU1_SA_DQ<3>")
	)
	(arc
		(start 142.04188 -226.34194)
		(mid 142.324836 -226.418117)
		(end 142.607792 -226.34194)
		(width 0.0889)
		(layer "In6.Cu")
		(net "M_K_CPU1_SA_DQ<3>")
	)
	(arc
		(start 144.526762 -223.079056)
		(mid 144.705575 -222.876706)
		(end 144.770094 -222.61449)
		(width 0.0889)
		(layer "In6.Cu")
		(net "M_K_CPU1_SA_DQ<3>")
	)
	(arc
		(start 144.056862 -225.509074)
		(mid 144.300189 -225.044508)
		(end 144.056862 -224.579942)
		(width 0.0889)
		(layer "In6.Cu")
		(net "M_K_CPU1_SA_DQ<3>")
	)
	(arc
		(start 144.9578 -222.29191)
		(mid 145.047997 -222.256)
		(end 145.144744 -222.247968)
		(width 0.0889)
		(layer "In6.Cu")
		(net "M_K_CPU1_SA_DQ<3>")
	)
	(arc
		(start 143.586708 -226.31908)
		(mid 143.765521 -226.11673)
		(end 143.83004 -225.854514)
		(width 0.0889)
		(layer "In6.Cu")
		(net "M_K_CPU1_SA_DQ<3>")
	)
	(arc
		(start 142.607792 -226.34194)
		(mid 142.794736 -226.291685)
		(end 142.98168 -226.34194)
		(width 0.0889)
		(layer "In6.Cu")
		(net "M_K_CPU1_SA_DQ<3>")
	)
	(arc
		(start 142.98168 -226.34194)
		(mid 143.264636 -226.418117)
		(end 143.547592 -226.34194)
		(width 0.0889)
		(layer "In6.Cu")
		(net "M_K_CPU1_SA_DQ<3>")
	)
	(arc
		(start 141.164818 -226.37369)
		(mid 141.420026 -226.417167)
		(end 141.667738 -226.34194)
		(width 0.0889)
		(layer "In6.Cu")
		(net "M_K_CPU1_SA_DQ<3>")
	)
	(arc
		(start 144.056862 -223.889062)
		(mid 144.235675 -223.686712)
		(end 144.300194 -223.424496)
		(width 0.0889)
		(layer "In6.Cu")
		(net "M_K_CPU1_SA_DQ<3>")
	)
	(arc
		(start 143.985996 -224.538794)
		(mid 143.830068 -224.234502)
		(end 143.985996 -223.93021)
		(width 0.0889)
		(layer "In6.Cu")
		(net "M_K_CPU1_SA_DQ<3>")
	)
	(segment
		(start 140.447776 -244.750336)
		(end 140.914882 -244.484398)
		(width 0.10668)
		(layer "F.Cu")
		(net "M_K_CPU1_SA_DQ<31>")
	)
	(segment
		(start 181.991 -233.46029)
		(end 182.29834 -233.46029)
		(width 0.14478)
		(layer "In6.Cu")
		(net "M_K_CPU1_SA_DQ<31>")
	)
	(segment
		(start 187.686188 -234.106212)
		(end 187.849256 -233.943144)
		(width 0.14478)
		(layer "In6.Cu")
		(net "M_K_CPU1_SA_DQ<31>")
	)
	(segment
		(start 190.564516 -233.297222)
		(end 190.727584 -233.46029)
		(width 0.14478)
		(layer "In6.Cu")
		(net "M_K_CPU1_SA_DQ<31>")
	)
	(segment
		(start 180.490368 -233.920284)
		(end 180.653436 -234.083352)
		(width 0.14478)
		(layer "In6.Cu")
		(net "M_K_CPU1_SA_DQ<31>")
	)
	(segment
		(start 189.52337 -233.46029)
		(end 189.844934 -233.46029)
		(width 0.14478)
		(layer "In6.Cu")
		(net "M_K_CPU1_SA_DQ<31>")
	)
	(segment
		(start 147.975066 -243.440204)
		(end 155.716732 -243.440204)
		(width 0.14478)
		(layer "In6.Cu")
		(net "M_K_CPU1_SA_DQ<31>")
	)
	(segment
		(start 191.47155 -233.46029)
		(end 191.739774 -233.728514)
		(width 0.14478)
		(layer "In6.Cu")
		(net "M_K_CPU1_SA_DQ<31>")
	)
	(segment
		(start 165.547294 -234.083352)
		(end 165.547294 -234.14736)
		(width 0.14478)
		(layer "In6.Cu")
		(net "M_K_CPU1_SA_DQ<31>")
	)
	(segment
		(start 188.673232 -234.310428)
		(end 189.52337 -233.46029)
		(width 0.14478)
		(layer "In6.Cu")
		(net "M_K_CPU1_SA_DQ<31>")
	)
	(segment
		(start 164.99078 -234.083352)
		(end 165.153848 -233.920284)
		(width 0.14478)
		(layer "In6.Cu")
		(net "M_K_CPU1_SA_DQ<31>")
	)
	(segment
		(start 192.70853 -233.326178)
		(end 192.70853 -233.594402)
		(width 0.14478)
		(layer "In6.Cu")
		(net "M_K_CPU1_SA_DQ<31>")
	)
	(segment
		(start 166.066724 -234.310428)
		(end 166.916862 -233.46029)
		(width 0.14478)
		(layer "In6.Cu")
		(net "M_K_CPU1_SA_DQ<31>")
	)
	(segment
		(start 169.907966 -233.46029)
		(end 170.758104 -234.310428)
		(width 0.14478)
		(layer "In6.Cu")
		(net "M_K_CPU1_SA_DQ<31>")
	)
	(segment
		(start 175.434752 -233.297222)
		(end 175.59782 -233.46029)
		(width 0.14478)
		(layer "In6.Cu")
		(net "M_K_CPU1_SA_DQ<31>")
	)
	(segment
		(start 141.667738 -244.161818)
		(end 141.67612 -244.156992)
		(width 0.0889)
		(layer "In6.Cu")
		(net "M_K_CPU1_SA_DQ<31>")
	)
	(segment
		(start 193.125852 -233.728514)
		(end 193.259964 -233.594402)
		(width 0.14478)
		(layer "In6.Cu")
		(net "M_K_CPU1_SA_DQ<31>")
	)
	(segment
		(start 165.384226 -233.920284)
		(end 165.547294 -234.083352)
		(width 0.14478)
		(layer "In6.Cu")
		(net "M_K_CPU1_SA_DQ<31>")
	)
	(segment
		(start 165.710362 -234.310428)
		(end 166.066724 -234.310428)
		(width 0.14478)
		(layer "In6.Cu")
		(net "M_K_CPU1_SA_DQ<31>")
	)
	(segment
		(start 180.653436 -234.083352)
		(end 180.653436 -234.14736)
		(width 0.14478)
		(layer "In6.Cu")
		(net "M_K_CPU1_SA_DQ<31>")
	)
	(segment
		(start 167.931338 -233.066844)
		(end 168.094406 -233.229912)
		(width 0.14478)
		(layer "In6.Cu")
		(net "M_K_CPU1_SA_DQ<31>")
	)
	(segment
		(start 180.096922 -234.14736)
		(end 180.096922 -234.083352)
		(width 0.14478)
		(layer "In6.Cu")
		(net "M_K_CPU1_SA_DQ<31>")
	)
	(segment
		(start 162.516566 -235.979208)
		(end 164.185346 -234.310428)
		(width 0.14478)
		(layer "In6.Cu")
		(net "M_K_CPU1_SA_DQ<31>")
	)
	(segment
		(start 165.153848 -233.920284)
		(end 165.384226 -233.920284)
		(width 0.14478)
		(layer "In6.Cu")
		(net "M_K_CPU1_SA_DQ<31>")
	)
	(segment
		(start 162.516566 -236.64037)
		(end 162.516566 -235.979208)
		(width 0.14478)
		(layer "In6.Cu")
		(net "M_K_CPU1_SA_DQ<31>")
	)
	(segment
		(start 169.370502 -233.46029)
		(end 169.907966 -233.46029)
		(width 0.14478)
		(layer "In6.Cu")
		(net "M_K_CPU1_SA_DQ<31>")
	)
	(segment
		(start 168.257474 -233.46029)
		(end 168.487852 -233.46029)
		(width 0.14478)
		(layer "In6.Cu")
		(net "M_K_CPU1_SA_DQ<31>")
	)
	(segment
		(start 165.547294 -234.14736)
		(end 165.710362 -234.310428)
		(width 0.14478)
		(layer "In6.Cu")
		(net "M_K_CPU1_SA_DQ<31>")
	)
	(segment
		(start 192.842642 -233.728514)
		(end 193.125852 -233.728514)
		(width 0.14478)
		(layer "In6.Cu")
		(net "M_K_CPU1_SA_DQ<31>")
	)
	(segment
		(start 194.17919 -233.46029)
		(end 194.604132 -233.885232)
		(width 0.14478)
		(layer "In6.Cu")
		(net "M_K_CPU1_SA_DQ<31>")
	)
	(segment
		(start 147.335748 -243.732304)
		(end 147.627848 -243.440204)
		(width 0.0889)
		(layer "In6.Cu")
		(net "M_K_CPU1_SA_DQ<31>")
	)
	(segment
		(start 174.878238 -233.234992)
		(end 175.041306 -233.071924)
		(width 0.14478)
		(layer "In6.Cu")
		(net "M_K_CPU1_SA_DQ<31>")
	)
	(segment
		(start 193.259964 -233.326178)
		(end 193.394076 -233.192066)
		(width 0.14478)
		(layer "In6.Cu")
		(net "M_K_CPU1_SA_DQ<31>")
	)
	(segment
		(start 182.624476 -233.066844)
		(end 182.854854 -233.066844)
		(width 0.14478)
		(layer "In6.Cu")
		(net "M_K_CPU1_SA_DQ<31>")
	)
	(segment
		(start 190.17107 -233.077004)
		(end 190.401448 -233.077004)
		(width 0.14478)
		(layer "In6.Cu")
		(net "M_K_CPU1_SA_DQ<31>")
	)
	(segment
		(start 169.207434 -233.229912)
		(end 169.207434 -233.297222)
		(width 0.14478)
		(layer "In6.Cu")
		(net "M_K_CPU1_SA_DQ<31>")
	)
	(segment
		(start 143.92148 -244.161818)
		(end 143.931894 -244.167914)
		(width 0.0889)
		(layer "In6.Cu")
		(net "M_K_CPU1_SA_DQ<31>")
	)
	(segment
		(start 193.677286 -233.192066)
		(end 193.94551 -233.46029)
		(width 0.14478)
		(layer "In6.Cu")
		(net "M_K_CPU1_SA_DQ<31>")
	)
	(segment
		(start 146.246596 -243.732304)
		(end 147.335748 -243.732304)
		(width 0.0889)
		(layer "In6.Cu")
		(net "M_K_CPU1_SA_DQ<31>")
	)
	(segment
		(start 173.200568 -234.083352)
		(end 173.200568 -234.14736)
		(width 0.14478)
		(layer "In6.Cu")
		(net "M_K_CPU1_SA_DQ<31>")
	)
	(segment
		(start 168.487852 -233.46029)
		(end 168.65092 -233.297222)
		(width 0.14478)
		(layer "In6.Cu")
		(net "M_K_CPU1_SA_DQ<31>")
	)
	(segment
		(start 175.59782 -233.46029)
		(end 177.45202 -233.46029)
		(width 0.14478)
		(layer "In6.Cu")
		(net "M_K_CPU1_SA_DQ<31>")
	)
	(segment
		(start 147.627848 -243.440204)
		(end 147.975066 -243.440204)
		(width 0.0889)
		(layer "In6.Cu")
		(net "M_K_CPU1_SA_DQ<31>")
	)
	(segment
		(start 190.008002 -233.240072)
		(end 190.17107 -233.077004)
		(width 0.14478)
		(layer "In6.Cu")
		(net "M_K_CPU1_SA_DQ<31>")
	)
	(segment
		(start 173.363636 -234.310428)
		(end 173.609254 -234.310428)
		(width 0.14478)
		(layer "In6.Cu")
		(net "M_K_CPU1_SA_DQ<31>")
	)
	(segment
		(start 188.242702 -234.14736)
		(end 188.40577 -234.310428)
		(width 0.14478)
		(layer "In6.Cu")
		(net "M_K_CPU1_SA_DQ<31>")
	)
	(segment
		(start 168.094406 -233.229912)
		(end 168.094406 -233.297222)
		(width 0.14478)
		(layer "In6.Cu")
		(net "M_K_CPU1_SA_DQ<31>")
	)
	(segment
		(start 168.813988 -233.066844)
		(end 169.044366 -233.066844)
		(width 0.14478)
		(layer "In6.Cu")
		(net "M_K_CPU1_SA_DQ<31>")
	)
	(segment
		(start 191.739774 -233.728514)
		(end 192.022984 -233.728514)
		(width 0.14478)
		(layer "In6.Cu")
		(net "M_K_CPU1_SA_DQ<31>")
	)
	(segment
		(start 187.686188 -234.14736)
		(end 187.686188 -234.106212)
		(width 0.14478)
		(layer "In6.Cu")
		(net "M_K_CPU1_SA_DQ<31>")
	)
	(segment
		(start 192.157096 -233.326178)
		(end 192.291208 -233.192066)
		(width 0.14478)
		(layer "In6.Cu")
		(net "M_K_CPU1_SA_DQ<31>")
	)
	(segment
		(start 180.096922 -234.083352)
		(end 180.25999 -233.920284)
		(width 0.14478)
		(layer "In6.Cu")
		(net "M_K_CPU1_SA_DQ<31>")
	)
	(segment
		(start 190.727584 -233.46029)
		(end 191.47155 -233.46029)
		(width 0.14478)
		(layer "In6.Cu")
		(net "M_K_CPU1_SA_DQ<31>")
	)
	(segment
		(start 168.65092 -233.229912)
		(end 168.813988 -233.066844)
		(width 0.14478)
		(layer "In6.Cu")
		(net "M_K_CPU1_SA_DQ<31>")
	)
	(segment
		(start 172.644054 -234.14736)
		(end 172.644054 -234.083352)
		(width 0.14478)
		(layer "In6.Cu")
		(net "M_K_CPU1_SA_DQ<31>")
	)
	(segment
		(start 175.041306 -233.071924)
		(end 175.271684 -233.071924)
		(width 0.14478)
		(layer "In6.Cu")
		(net "M_K_CPU1_SA_DQ<31>")
	)
	(segment
		(start 182.461408 -233.297222)
		(end 182.461408 -233.229912)
		(width 0.14478)
		(layer "In6.Cu")
		(net "M_K_CPU1_SA_DQ<31>")
	)
	(segment
		(start 144.487138 -244.161818)
		(end 144.498822 -244.15496)
		(width 0.0889)
		(layer "In6.Cu")
		(net "M_K_CPU1_SA_DQ<31>")
	)
	(segment
		(start 182.29834 -233.46029)
		(end 182.461408 -233.297222)
		(width 0.14478)
		(layer "In6.Cu")
		(net "M_K_CPU1_SA_DQ<31>")
	)
	(segment
		(start 190.564516 -233.240072)
		(end 190.564516 -233.297222)
		(width 0.14478)
		(layer "In6.Cu")
		(net "M_K_CPU1_SA_DQ<31>")
	)
	(segment
		(start 169.207434 -233.297222)
		(end 169.370502 -233.46029)
		(width 0.14478)
		(layer "In6.Cu")
		(net "M_K_CPU1_SA_DQ<31>")
	)
	(segment
		(start 145.740882 -244.238018)
		(end 146.246596 -243.732304)
		(width 0.0889)
		(layer "In6.Cu")
		(net "M_K_CPU1_SA_DQ<31>")
	)
	(segment
		(start 173.0375 -233.920284)
		(end 173.200568 -234.083352)
		(width 0.14478)
		(layer "In6.Cu")
		(net "M_K_CPU1_SA_DQ<31>")
	)
	(segment
		(start 178.302158 -234.310428)
		(end 179.933854 -234.310428)
		(width 0.14478)
		(layer "In6.Cu")
		(net "M_K_CPU1_SA_DQ<31>")
	)
	(segment
		(start 167.70096 -233.066844)
		(end 167.931338 -233.066844)
		(width 0.14478)
		(layer "In6.Cu")
		(net "M_K_CPU1_SA_DQ<31>")
	)
	(segment
		(start 140.914882 -244.484398)
		(end 141.068806 -244.218968)
		(width 0.0889)
		(layer "In6.Cu")
		(net "M_K_CPU1_SA_DQ<31>")
	)
	(segment
		(start 174.459392 -233.46029)
		(end 174.71517 -233.46029)
		(width 0.14478)
		(layer "In6.Cu")
		(net "M_K_CPU1_SA_DQ<31>")
	)
	(segment
		(start 175.434752 -233.234992)
		(end 175.434752 -233.297222)
		(width 0.14478)
		(layer "In6.Cu")
		(net "M_K_CPU1_SA_DQ<31>")
	)
	(segment
		(start 143.909796 -244.15496)
		(end 143.92148 -244.161818)
		(width 0.0889)
		(layer "In6.Cu")
		(net "M_K_CPU1_SA_DQ<31>")
	)
	(segment
		(start 141.068806 -244.218968)
		(end 141.164818 -244.193568)
		(width 0.0889)
		(layer "In6.Cu")
		(net "M_K_CPU1_SA_DQ<31>")
	)
	(segment
		(start 183.017922 -233.297222)
		(end 183.18099 -233.46029)
		(width 0.14478)
		(layer "In6.Cu")
		(net "M_K_CPU1_SA_DQ<31>")
	)
	(segment
		(start 174.878238 -233.297222)
		(end 174.878238 -233.234992)
		(width 0.14478)
		(layer "In6.Cu")
		(net "M_K_CPU1_SA_DQ<31>")
	)
	(segment
		(start 166.916862 -233.46029)
		(end 167.374824 -233.46029)
		(width 0.14478)
		(layer "In6.Cu")
		(net "M_K_CPU1_SA_DQ<31>")
	)
	(segment
		(start 145.144744 -244.238018)
		(end 145.740882 -244.238018)
		(width 0.0889)
		(layer "In6.Cu")
		(net "M_K_CPU1_SA_DQ<31>")
	)
	(segment
		(start 181.140862 -234.310428)
		(end 181.991 -233.46029)
		(width 0.14478)
		(layer "In6.Cu")
		(net "M_K_CPU1_SA_DQ<31>")
	)
	(segment
		(start 172.480986 -234.310428)
		(end 172.644054 -234.14736)
		(width 0.14478)
		(layer "In6.Cu")
		(net "M_K_CPU1_SA_DQ<31>")
	)
	(segment
		(start 179.933854 -234.310428)
		(end 180.096922 -234.14736)
		(width 0.14478)
		(layer "In6.Cu")
		(net "M_K_CPU1_SA_DQ<31>")
	)
	(segment
		(start 182.461408 -233.229912)
		(end 182.624476 -233.066844)
		(width 0.14478)
		(layer "In6.Cu")
		(net "M_K_CPU1_SA_DQ<31>")
	)
	(segment
		(start 182.854854 -233.066844)
		(end 183.017922 -233.229912)
		(width 0.14478)
		(layer "In6.Cu")
		(net "M_K_CPU1_SA_DQ<31>")
	)
	(segment
		(start 180.653436 -234.14736)
		(end 180.816504 -234.310428)
		(width 0.14478)
		(layer "In6.Cu")
		(net "M_K_CPU1_SA_DQ<31>")
	)
	(segment
		(start 173.609254 -234.310428)
		(end 174.459392 -233.46029)
		(width 0.14478)
		(layer "In6.Cu")
		(net "M_K_CPU1_SA_DQ<31>")
	)
	(segment
		(start 174.71517 -233.46029)
		(end 174.878238 -233.297222)
		(width 0.14478)
		(layer "In6.Cu")
		(net "M_K_CPU1_SA_DQ<31>")
	)
	(segment
		(start 183.017922 -233.229912)
		(end 183.017922 -233.297222)
		(width 0.14478)
		(layer "In6.Cu")
		(net "M_K_CPU1_SA_DQ<31>")
	)
	(segment
		(start 192.70853 -233.594402)
		(end 192.842642 -233.728514)
		(width 0.14478)
		(layer "In6.Cu")
		(net "M_K_CPU1_SA_DQ<31>")
	)
	(segment
		(start 188.40577 -234.310428)
		(end 188.673232 -234.310428)
		(width 0.14478)
		(layer "In6.Cu")
		(net "M_K_CPU1_SA_DQ<31>")
	)
	(segment
		(start 192.157096 -233.594402)
		(end 192.157096 -233.326178)
		(width 0.14478)
		(layer "In6.Cu")
		(net "M_K_CPU1_SA_DQ<31>")
	)
	(segment
		(start 187.52312 -234.310428)
		(end 187.686188 -234.14736)
		(width 0.14478)
		(layer "In6.Cu")
		(net "M_K_CPU1_SA_DQ<31>")
	)
	(segment
		(start 187.849256 -233.943144)
		(end 188.079634 -233.943144)
		(width 0.14478)
		(layer "In6.Cu")
		(net "M_K_CPU1_SA_DQ<31>")
	)
	(segment
		(start 155.716732 -243.440204)
		(end 162.516566 -236.64037)
		(width 0.14478)
		(layer "In6.Cu")
		(net "M_K_CPU1_SA_DQ<31>")
	)
	(segment
		(start 192.291208 -233.192066)
		(end 192.574418 -233.192066)
		(width 0.14478)
		(layer "In6.Cu")
		(net "M_K_CPU1_SA_DQ<31>")
	)
	(segment
		(start 193.394076 -233.192066)
		(end 193.677286 -233.192066)
		(width 0.14478)
		(layer "In6.Cu")
		(net "M_K_CPU1_SA_DQ<31>")
	)
	(segment
		(start 164.99078 -234.14736)
		(end 164.99078 -234.083352)
		(width 0.14478)
		(layer "In6.Cu")
		(net "M_K_CPU1_SA_DQ<31>")
	)
	(segment
		(start 184.99582 -233.46029)
		(end 185.845958 -234.310428)
		(width 0.14478)
		(layer "In6.Cu")
		(net "M_K_CPU1_SA_DQ<31>")
	)
	(segment
		(start 193.94551 -233.46029)
		(end 194.17919 -233.46029)
		(width 0.14478)
		(layer "In6.Cu")
		(net "M_K_CPU1_SA_DQ<31>")
	)
	(segment
		(start 180.25999 -233.920284)
		(end 180.490368 -233.920284)
		(width 0.14478)
		(layer "In6.Cu")
		(net "M_K_CPU1_SA_DQ<31>")
	)
	(segment
		(start 172.807122 -233.920284)
		(end 173.0375 -233.920284)
		(width 0.14478)
		(layer "In6.Cu")
		(net "M_K_CPU1_SA_DQ<31>")
	)
	(segment
		(start 168.65092 -233.297222)
		(end 168.65092 -233.229912)
		(width 0.14478)
		(layer "In6.Cu")
		(net "M_K_CPU1_SA_DQ<31>")
	)
	(segment
		(start 193.259964 -233.594402)
		(end 193.259964 -233.326178)
		(width 0.14478)
		(layer "In6.Cu")
		(net "M_K_CPU1_SA_DQ<31>")
	)
	(segment
		(start 188.079634 -233.943144)
		(end 188.242702 -234.106212)
		(width 0.14478)
		(layer "In6.Cu")
		(net "M_K_CPU1_SA_DQ<31>")
	)
	(segment
		(start 170.758104 -234.310428)
		(end 172.480986 -234.310428)
		(width 0.14478)
		(layer "In6.Cu")
		(net "M_K_CPU1_SA_DQ<31>")
	)
	(segment
		(start 164.827712 -234.310428)
		(end 164.99078 -234.14736)
		(width 0.14478)
		(layer "In6.Cu")
		(net "M_K_CPU1_SA_DQ<31>")
	)
	(segment
		(start 180.816504 -234.310428)
		(end 181.140862 -234.310428)
		(width 0.14478)
		(layer "In6.Cu")
		(net "M_K_CPU1_SA_DQ<31>")
	)
	(segment
		(start 183.18099 -233.46029)
		(end 184.99582 -233.46029)
		(width 0.14478)
		(layer "In6.Cu")
		(net "M_K_CPU1_SA_DQ<31>")
	)
	(segment
		(start 172.644054 -234.083352)
		(end 172.807122 -233.920284)
		(width 0.14478)
		(layer "In6.Cu")
		(net "M_K_CPU1_SA_DQ<31>")
	)
	(segment
		(start 190.401448 -233.077004)
		(end 190.564516 -233.240072)
		(width 0.14478)
		(layer "In6.Cu")
		(net "M_K_CPU1_SA_DQ<31>")
	)
	(segment
		(start 177.45202 -233.46029)
		(end 178.302158 -234.310428)
		(width 0.14478)
		(layer "In6.Cu")
		(net "M_K_CPU1_SA_DQ<31>")
	)
	(segment
		(start 167.374824 -233.46029)
		(end 167.537892 -233.297222)
		(width 0.14478)
		(layer "In6.Cu")
		(net "M_K_CPU1_SA_DQ<31>")
	)
	(segment
		(start 192.574418 -233.192066)
		(end 192.70853 -233.326178)
		(width 0.14478)
		(layer "In6.Cu")
		(net "M_K_CPU1_SA_DQ<31>")
	)
	(segment
		(start 192.022984 -233.728514)
		(end 192.157096 -233.594402)
		(width 0.14478)
		(layer "In6.Cu")
		(net "M_K_CPU1_SA_DQ<31>")
	)
	(segment
		(start 190.008002 -233.297222)
		(end 190.008002 -233.240072)
		(width 0.14478)
		(layer "In6.Cu")
		(net "M_K_CPU1_SA_DQ<31>")
	)
	(segment
		(start 188.242702 -234.106212)
		(end 188.242702 -234.14736)
		(width 0.14478)
		(layer "In6.Cu")
		(net "M_K_CPU1_SA_DQ<31>")
	)
	(segment
		(start 189.844934 -233.46029)
		(end 190.008002 -233.297222)
		(width 0.14478)
		(layer "In6.Cu")
		(net "M_K_CPU1_SA_DQ<31>")
	)
	(segment
		(start 173.200568 -234.14736)
		(end 173.363636 -234.310428)
		(width 0.14478)
		(layer "In6.Cu")
		(net "M_K_CPU1_SA_DQ<31>")
	)
	(segment
		(start 175.271684 -233.071924)
		(end 175.434752 -233.234992)
		(width 0.14478)
		(layer "In6.Cu")
		(net "M_K_CPU1_SA_DQ<31>")
	)
	(segment
		(start 168.094406 -233.297222)
		(end 168.257474 -233.46029)
		(width 0.14478)
		(layer "In6.Cu")
		(net "M_K_CPU1_SA_DQ<31>")
	)
	(segment
		(start 164.185346 -234.310428)
		(end 164.827712 -234.310428)
		(width 0.14478)
		(layer "In6.Cu")
		(net "M_K_CPU1_SA_DQ<31>")
	)
	(segment
		(start 167.537892 -233.229912)
		(end 167.70096 -233.066844)
		(width 0.14478)
		(layer "In6.Cu")
		(net "M_K_CPU1_SA_DQ<31>")
	)
	(segment
		(start 167.537892 -233.297222)
		(end 167.537892 -233.229912)
		(width 0.14478)
		(layer "In6.Cu")
		(net "M_K_CPU1_SA_DQ<31>")
	)
	(segment
		(start 185.845958 -234.310428)
		(end 187.52312 -234.310428)
		(width 0.14478)
		(layer "In6.Cu")
		(net "M_K_CPU1_SA_DQ<31>")
	)
	(segment
		(start 169.044366 -233.066844)
		(end 169.207434 -233.229912)
		(width 0.14478)
		(layer "In6.Cu")
		(net "M_K_CPU1_SA_DQ<31>")
	)
	(arc
		(start 142.607792 -244.161818)
		(mid 142.794736 -244.111563)
		(end 142.98168 -244.161818)
		(width 0.0889)
		(layer "In6.Cu")
		(net "M_K_CPU1_SA_DQ<31>")
	)
	(arc
		(start 143.931894 -244.167914)
		(mid 144.210326 -244.238012)
		(end 144.487138 -244.161818)
		(width 0.0889)
		(layer "In6.Cu")
		(net "M_K_CPU1_SA_DQ<31>")
	)
	(arc
		(start 141.164818 -244.193568)
		(mid 141.420026 -244.237045)
		(end 141.667738 -244.161818)
		(width 0.0889)
		(layer "In6.Cu")
		(net "M_K_CPU1_SA_DQ<31>")
	)
	(arc
		(start 144.861534 -244.161818)
		(mid 144.998097 -244.218651)
		(end 145.144744 -244.238018)
		(width 0.0889)
		(layer "In6.Cu")
		(net "M_K_CPU1_SA_DQ<31>")
	)
	(arc
		(start 143.547592 -244.161818)
		(mid 143.727797 -244.111501)
		(end 143.909796 -244.15496)
		(width 0.0889)
		(layer "In6.Cu")
		(net "M_K_CPU1_SA_DQ<31>")
	)
	(arc
		(start 144.498822 -244.15496)
		(mid 144.681077 -244.111307)
		(end 144.861534 -244.161818)
		(width 0.0889)
		(layer "In6.Cu")
		(net "M_K_CPU1_SA_DQ<31>")
	)
	(arc
		(start 142.98168 -244.161818)
		(mid 143.264636 -244.237995)
		(end 143.547592 -244.161818)
		(width 0.0889)
		(layer "In6.Cu")
		(net "M_K_CPU1_SA_DQ<31>")
	)
	(arc
		(start 141.67612 -244.156992)
		(mid 141.859628 -244.111498)
		(end 142.04188 -244.161818)
		(width 0.0889)
		(layer "In6.Cu")
		(net "M_K_CPU1_SA_DQ<31>")
	)
	(arc
		(start 142.04188 -244.161818)
		(mid 142.324836 -244.237995)
		(end 142.607792 -244.161818)
		(width 0.0889)
		(layer "In6.Cu")
		(net "M_K_CPU1_SA_DQ<31>")
	)
	(segment
		(start 141.857984 -243.94033)
		(end 142.324836 -243.674392)
		(width 0.10668)
		(layer "F.Cu")
		(net "M_K_CPU1_SA_DQ<30>")
	)
	(segment
		(start 176.730406 -231.383586)
		(end 176.99228 -231.383586)
		(width 0.14478)
		(layer "In6.Cu")
		(net "M_K_CPU1_SA_DQ<30>")
	)
	(segment
		(start 188.0616 -232.236264)
		(end 188.224668 -232.399332)
		(width 0.14478)
		(layer "In6.Cu")
		(net "M_K_CPU1_SA_DQ<30>")
	)
	(segment
		(start 174.848774 -231.615488)
		(end 174.848774 -231.515666)
		(width 0.14478)
		(layer "In6.Cu")
		(net "M_K_CPU1_SA_DQ<30>")
	)
	(segment
		(start 180.626766 -232.231946)
		(end 180.771546 -232.376726)
		(width 0.14478)
		(layer "In6.Cu")
		(net "M_K_CPU1_SA_DQ<30>")
	)
	(segment
		(start 145.925286 -243.301266)
		(end 146.456908 -242.769644)
		(width 0.0889)
		(layer "In6.Cu")
		(net "M_K_CPU1_SA_DQ<30>")
	)
	(segment
		(start 176.585626 -231.528366)
		(end 176.730406 -231.383586)
		(width 0.14478)
		(layer "In6.Cu")
		(net "M_K_CPU1_SA_DQ<30>")
	)
	(segment
		(start 192.619376 -231.375712)
		(end 192.849754 -231.375712)
		(width 0.14478)
		(layer "In6.Cu")
		(net "M_K_CPU1_SA_DQ<30>")
	)
	(segment
		(start 167.251634 -231.995726)
		(end 167.396414 -232.140506)
		(width 0.14478)
		(layer "In6.Cu")
		(net "M_K_CPU1_SA_DQ<30>")
	)
	(segment
		(start 183.216804 -231.760268)
		(end 183.950864 -231.760268)
		(width 0.14478)
		(layer "In6.Cu")
		(net "M_K_CPU1_SA_DQ<30>")
	)
	(segment
		(start 193.012822 -231.981756)
		(end 193.17589 -232.144824)
		(width 0.14478)
		(layer "In6.Cu")
		(net "M_K_CPU1_SA_DQ<30>")
	)
	(segment
		(start 169.026332 -231.905048)
		(end 169.026332 -231.995726)
		(width 0.14478)
		(layer "In6.Cu")
		(net "M_K_CPU1_SA_DQ<30>")
	)
	(segment
		(start 143.077692 -243.351812)
		(end 143.086074 -243.346986)
		(width 0.0889)
		(layer "In6.Cu")
		(net "M_K_CPU1_SA_DQ<30>")
	)
	(segment
		(start 161.571686 -235.248704)
		(end 164.209984 -232.610406)
		(width 0.14478)
		(layer "In6.Cu")
		(net "M_K_CPU1_SA_DQ<30>")
	)
	(segment
		(start 172.478192 -232.386632)
		(end 172.64126 -232.223564)
		(width 0.14478)
		(layer "In6.Cu")
		(net "M_K_CPU1_SA_DQ<30>")
	)
	(segment
		(start 167.947848 -231.760268)
		(end 168.881552 -231.760268)
		(width 0.14478)
		(layer "In6.Cu")
		(net "M_K_CPU1_SA_DQ<30>")
	)
	(segment
		(start 145.144744 -243.301266)
		(end 145.925286 -243.301266)
		(width 0.0889)
		(layer "In6.Cu")
		(net "M_K_CPU1_SA_DQ<30>")
	)
	(segment
		(start 167.106854 -231.760268)
		(end 167.251634 -231.905048)
		(width 0.14478)
		(layer "In6.Cu")
		(net "M_K_CPU1_SA_DQ<30>")
	)
	(segment
		(start 165.458902 -232.447338)
		(end 165.62197 -232.610406)
		(width 0.14478)
		(layer "In6.Cu")
		(net "M_K_CPU1_SA_DQ<30>")
	)
	(segment
		(start 191.899794 -231.923336)
		(end 191.899794 -231.981756)
		(width 0.14478)
		(layer "In6.Cu")
		(net "M_K_CPU1_SA_DQ<30>")
	)
	(segment
		(start 172.871638 -232.223564)
		(end 173.034706 -232.386632)
		(width 0.14478)
		(layer "In6.Cu")
		(net "M_K_CPU1_SA_DQ<30>")
	)
	(segment
		(start 190.258954 -231.370124)
		(end 190.422022 -231.533192)
		(width 0.14478)
		(layer "In6.Cu")
		(net "M_K_CPU1_SA_DQ<30>")
	)
	(segment
		(start 188.673232 -232.610406)
		(end 189.52337 -231.760268)
		(width 0.14478)
		(layer "In6.Cu")
		(net "M_K_CPU1_SA_DQ<30>")
	)
	(segment
		(start 146.456908 -242.769644)
		(end 147.358608 -242.769644)
		(width 0.0889)
		(layer "In6.Cu")
		(net "M_K_CPU1_SA_DQ<30>")
	)
	(segment
		(start 188.224668 -232.447338)
		(end 188.387736 -232.610406)
		(width 0.14478)
		(layer "In6.Cu")
		(net "M_K_CPU1_SA_DQ<30>")
	)
	(segment
		(start 169.171112 -232.140506)
		(end 169.432986 -232.140506)
		(width 0.14478)
		(layer "In6.Cu")
		(net "M_K_CPU1_SA_DQ<30>")
	)
	(segment
		(start 180.916326 -232.610406)
		(end 181.140862 -232.610406)
		(width 0.14478)
		(layer "In6.Cu")
		(net "M_K_CPU1_SA_DQ<30>")
	)
	(segment
		(start 142.324836 -243.674392)
		(end 142.47876 -243.408962)
		(width 0.0889)
		(layer "In6.Cu")
		(net "M_K_CPU1_SA_DQ<30>")
	)
	(segment
		(start 173.034706 -232.447338)
		(end 173.197774 -232.610406)
		(width 0.14478)
		(layer "In6.Cu")
		(net "M_K_CPU1_SA_DQ<30>")
	)
	(segment
		(start 192.29324 -232.144824)
		(end 192.456308 -231.981756)
		(width 0.14478)
		(layer "In6.Cu")
		(net "M_K_CPU1_SA_DQ<30>")
	)
	(segment
		(start 177.13706 -231.615488)
		(end 177.28184 -231.760268)
		(width 0.14478)
		(layer "In6.Cu")
		(net "M_K_CPU1_SA_DQ<30>")
	)
	(segment
		(start 188.224668 -232.399332)
		(end 188.224668 -232.447338)
		(width 0.14478)
		(layer "In6.Cu")
		(net "M_K_CPU1_SA_DQ<30>")
	)
	(segment
		(start 180.364892 -232.231946)
		(end 180.626766 -232.231946)
		(width 0.14478)
		(layer "In6.Cu")
		(net "M_K_CPU1_SA_DQ<30>")
	)
	(segment
		(start 192.456308 -231.53878)
		(end 192.619376 -231.375712)
		(width 0.14478)
		(layer "In6.Cu")
		(net "M_K_CPU1_SA_DQ<30>")
	)
	(segment
		(start 187.505086 -232.610406)
		(end 187.668154 -232.447338)
		(width 0.14478)
		(layer "In6.Cu")
		(net "M_K_CPU1_SA_DQ<30>")
	)
	(segment
		(start 167.251634 -231.905048)
		(end 167.251634 -231.995726)
		(width 0.14478)
		(layer "In6.Cu")
		(net "M_K_CPU1_SA_DQ<30>")
	)
	(segment
		(start 169.907966 -231.760268)
		(end 170.758104 -232.610406)
		(width 0.14478)
		(layer "In6.Cu")
		(net "M_K_CPU1_SA_DQ<30>")
	)
	(segment
		(start 184.095644 -231.515666)
		(end 184.240424 -231.370886)
		(width 0.14478)
		(layer "In6.Cu")
		(net "M_K_CPU1_SA_DQ<30>")
	)
	(segment
		(start 192.849754 -231.375712)
		(end 193.012822 -231.53878)
		(width 0.14478)
		(layer "In6.Cu")
		(net "M_K_CPU1_SA_DQ<30>")
	)
	(segment
		(start 187.668154 -232.447338)
		(end 187.668154 -232.399332)
		(width 0.14478)
		(layer "In6.Cu")
		(net "M_K_CPU1_SA_DQ<30>")
	)
	(segment
		(start 167.658288 -232.140506)
		(end 167.803068 -231.995726)
		(width 0.14478)
		(layer "In6.Cu")
		(net "M_K_CPU1_SA_DQ<30>")
	)
	(segment
		(start 189.865508 -231.533192)
		(end 190.028576 -231.370124)
		(width 0.14478)
		(layer "In6.Cu")
		(net "M_K_CPU1_SA_DQ<30>")
	)
	(segment
		(start 168.881552 -231.760268)
		(end 169.026332 -231.905048)
		(width 0.14478)
		(layer "In6.Cu")
		(net "M_K_CPU1_SA_DQ<30>")
	)
	(segment
		(start 155.339796 -242.530884)
		(end 161.571686 -236.298994)
		(width 0.14478)
		(layer "In6.Cu")
		(net "M_K_CPU1_SA_DQ<30>")
	)
	(segment
		(start 174.993554 -231.370886)
		(end 175.255428 -231.370886)
		(width 0.14478)
		(layer "In6.Cu")
		(net "M_K_CPU1_SA_DQ<30>")
	)
	(segment
		(start 192.456308 -231.981756)
		(end 192.456308 -231.53878)
		(width 0.14478)
		(layer "In6.Cu")
		(net "M_K_CPU1_SA_DQ<30>")
	)
	(segment
		(start 180.220112 -232.376726)
		(end 180.364892 -232.231946)
		(width 0.14478)
		(layer "In6.Cu")
		(net "M_K_CPU1_SA_DQ<30>")
	)
	(segment
		(start 183.053736 -231.5972)
		(end 183.216804 -231.760268)
		(width 0.14478)
		(layer "In6.Cu")
		(net "M_K_CPU1_SA_DQ<30>")
	)
	(segment
		(start 164.209984 -232.610406)
		(end 164.73932 -232.610406)
		(width 0.14478)
		(layer "In6.Cu")
		(net "M_K_CPU1_SA_DQ<30>")
	)
	(segment
		(start 165.62197 -232.610406)
		(end 166.066724 -232.610406)
		(width 0.14478)
		(layer "In6.Cu")
		(net "M_K_CPU1_SA_DQ<30>")
	)
	(segment
		(start 184.240424 -231.370886)
		(end 184.502298 -231.370886)
		(width 0.14478)
		(layer "In6.Cu")
		(net "M_K_CPU1_SA_DQ<30>")
	)
	(segment
		(start 176.440846 -231.760268)
		(end 176.585626 -231.615488)
		(width 0.14478)
		(layer "In6.Cu")
		(net "M_K_CPU1_SA_DQ<30>")
	)
	(segment
		(start 190.422022 -231.533192)
		(end 190.422022 -231.5972)
		(width 0.14478)
		(layer "In6.Cu")
		(net "M_K_CPU1_SA_DQ<30>")
	)
	(segment
		(start 193.569336 -231.923336)
		(end 193.732404 -231.760268)
		(width 0.14478)
		(layer "In6.Cu")
		(net "M_K_CPU1_SA_DQ<30>")
	)
	(segment
		(start 176.585626 -231.615488)
		(end 176.585626 -231.528366)
		(width 0.14478)
		(layer "In6.Cu")
		(net "M_K_CPU1_SA_DQ<30>")
	)
	(segment
		(start 180.220112 -232.465626)
		(end 180.220112 -232.376726)
		(width 0.14478)
		(layer "In6.Cu")
		(net "M_K_CPU1_SA_DQ<30>")
	)
	(segment
		(start 173.197774 -232.610406)
		(end 173.609254 -232.610406)
		(width 0.14478)
		(layer "In6.Cu")
		(net "M_K_CPU1_SA_DQ<30>")
	)
	(segment
		(start 181.140862 -232.610406)
		(end 181.991 -231.760268)
		(width 0.14478)
		(layer "In6.Cu")
		(net "M_K_CPU1_SA_DQ<30>")
	)
	(segment
		(start 177.45202 -231.760268)
		(end 178.302158 -232.610406)
		(width 0.14478)
		(layer "In6.Cu")
		(net "M_K_CPU1_SA_DQ<30>")
	)
	(segment
		(start 182.890668 -231.370124)
		(end 183.053736 -231.533192)
		(width 0.14478)
		(layer "In6.Cu")
		(net "M_K_CPU1_SA_DQ<30>")
	)
	(segment
		(start 167.803068 -231.905048)
		(end 167.947848 -231.760268)
		(width 0.14478)
		(layer "In6.Cu")
		(net "M_K_CPU1_SA_DQ<30>")
	)
	(segment
		(start 187.668154 -232.399332)
		(end 187.831222 -232.236264)
		(width 0.14478)
		(layer "In6.Cu")
		(net "M_K_CPU1_SA_DQ<30>")
	)
	(segment
		(start 189.70244 -231.760268)
		(end 189.865508 -231.5972)
		(width 0.14478)
		(layer "In6.Cu")
		(net "M_K_CPU1_SA_DQ<30>")
	)
	(segment
		(start 174.459392 -231.760268)
		(end 174.703994 -231.760268)
		(width 0.14478)
		(layer "In6.Cu")
		(net "M_K_CPU1_SA_DQ<30>")
	)
	(segment
		(start 185.845958 -232.610406)
		(end 187.505086 -232.610406)
		(width 0.14478)
		(layer "In6.Cu")
		(net "M_K_CPU1_SA_DQ<30>")
	)
	(segment
		(start 165.295834 -232.236264)
		(end 165.458902 -232.399332)
		(width 0.14478)
		(layer "In6.Cu")
		(net "M_K_CPU1_SA_DQ<30>")
	)
	(segment
		(start 144.007078 -243.357908)
		(end 144.017492 -243.351812)
		(width 0.0889)
		(layer "In6.Cu")
		(net "M_K_CPU1_SA_DQ<30>")
	)
	(segment
		(start 191.899794 -231.981756)
		(end 192.062862 -232.144824)
		(width 0.14478)
		(layer "In6.Cu")
		(net "M_K_CPU1_SA_DQ<30>")
	)
	(segment
		(start 194.17919 -231.760268)
		(end 194.604132 -232.18521)
		(width 0.14478)
		(layer "In6.Cu")
		(net "M_K_CPU1_SA_DQ<30>")
	)
	(segment
		(start 187.831222 -232.236264)
		(end 188.0616 -232.236264)
		(width 0.14478)
		(layer "In6.Cu")
		(net "M_K_CPU1_SA_DQ<30>")
	)
	(segment
		(start 175.255428 -231.370886)
		(end 175.400208 -231.515666)
		(width 0.14478)
		(layer "In6.Cu")
		(net "M_K_CPU1_SA_DQ<30>")
	)
	(segment
		(start 173.034706 -232.386632)
		(end 173.034706 -232.447338)
		(width 0.14478)
		(layer "In6.Cu")
		(net "M_K_CPU1_SA_DQ<30>")
	)
	(segment
		(start 167.803068 -231.995726)
		(end 167.803068 -231.905048)
		(width 0.14478)
		(layer "In6.Cu")
		(net "M_K_CPU1_SA_DQ<30>")
	)
	(segment
		(start 184.095644 -231.615488)
		(end 184.095644 -231.515666)
		(width 0.14478)
		(layer "In6.Cu")
		(net "M_K_CPU1_SA_DQ<30>")
	)
	(segment
		(start 174.703994 -231.760268)
		(end 174.848774 -231.615488)
		(width 0.14478)
		(layer "In6.Cu")
		(net "M_K_CPU1_SA_DQ<30>")
	)
	(segment
		(start 184.502298 -231.370886)
		(end 184.647078 -231.515666)
		(width 0.14478)
		(layer "In6.Cu")
		(net "M_K_CPU1_SA_DQ<30>")
	)
	(segment
		(start 178.302158 -232.610406)
		(end 180.075332 -232.610406)
		(width 0.14478)
		(layer "In6.Cu")
		(net "M_K_CPU1_SA_DQ<30>")
	)
	(segment
		(start 170.758104 -232.610406)
		(end 172.315124 -232.610406)
		(width 0.14478)
		(layer "In6.Cu")
		(net "M_K_CPU1_SA_DQ<30>")
	)
	(segment
		(start 184.99582 -231.760268)
		(end 185.845958 -232.610406)
		(width 0.14478)
		(layer "In6.Cu")
		(net "M_K_CPU1_SA_DQ<30>")
	)
	(segment
		(start 166.066724 -232.610406)
		(end 166.916862 -231.760268)
		(width 0.14478)
		(layer "In6.Cu")
		(net "M_K_CPU1_SA_DQ<30>")
	)
	(segment
		(start 144.39138 -243.351812)
		(end 144.401794 -243.357908)
		(width 0.0889)
		(layer "In6.Cu")
		(net "M_K_CPU1_SA_DQ<30>")
	)
	(segment
		(start 190.422022 -231.5972)
		(end 190.58509 -231.760268)
		(width 0.14478)
		(layer "In6.Cu")
		(net "M_K_CPU1_SA_DQ<30>")
	)
	(segment
		(start 176.99228 -231.383586)
		(end 177.13706 -231.528366)
		(width 0.14478)
		(layer "In6.Cu")
		(net "M_K_CPU1_SA_DQ<30>")
	)
	(segment
		(start 165.458902 -232.399332)
		(end 165.458902 -232.447338)
		(width 0.14478)
		(layer "In6.Cu")
		(net "M_K_CPU1_SA_DQ<30>")
	)
	(segment
		(start 175.400208 -231.615488)
		(end 175.544988 -231.760268)
		(width 0.14478)
		(layer "In6.Cu")
		(net "M_K_CPU1_SA_DQ<30>")
	)
	(segment
		(start 174.848774 -231.515666)
		(end 174.993554 -231.370886)
		(width 0.14478)
		(layer "In6.Cu")
		(net "M_K_CPU1_SA_DQ<30>")
	)
	(segment
		(start 177.13706 -231.528366)
		(end 177.13706 -231.615488)
		(width 0.14478)
		(layer "In6.Cu")
		(net "M_K_CPU1_SA_DQ<30>")
	)
	(segment
		(start 180.771546 -232.376726)
		(end 180.771546 -232.465626)
		(width 0.14478)
		(layer "In6.Cu")
		(net "M_K_CPU1_SA_DQ<30>")
	)
	(segment
		(start 169.722546 -231.760268)
		(end 169.907966 -231.760268)
		(width 0.14478)
		(layer "In6.Cu")
		(net "M_K_CPU1_SA_DQ<30>")
	)
	(segment
		(start 193.569336 -231.981756)
		(end 193.569336 -231.923336)
		(width 0.14478)
		(layer "In6.Cu")
		(net "M_K_CPU1_SA_DQ<30>")
	)
	(segment
		(start 147.358608 -242.769644)
		(end 147.597368 -242.530884)
		(width 0.0889)
		(layer "In6.Cu")
		(net "M_K_CPU1_SA_DQ<30>")
	)
	(segment
		(start 175.544988 -231.760268)
		(end 176.440846 -231.760268)
		(width 0.14478)
		(layer "In6.Cu")
		(net "M_K_CPU1_SA_DQ<30>")
	)
	(segment
		(start 161.571686 -236.298994)
		(end 161.571686 -235.248704)
		(width 0.14478)
		(layer "In6.Cu")
		(net "M_K_CPU1_SA_DQ<30>")
	)
	(segment
		(start 172.64126 -232.223564)
		(end 172.871638 -232.223564)
		(width 0.14478)
		(layer "In6.Cu")
		(net "M_K_CPU1_SA_DQ<30>")
	)
	(segment
		(start 191.736726 -231.760268)
		(end 191.899794 -231.923336)
		(width 0.14478)
		(layer "In6.Cu")
		(net "M_K_CPU1_SA_DQ<30>")
	)
	(segment
		(start 193.17589 -232.144824)
		(end 193.406268 -232.144824)
		(width 0.14478)
		(layer "In6.Cu")
		(net "M_K_CPU1_SA_DQ<30>")
	)
	(segment
		(start 180.075332 -232.610406)
		(end 180.220112 -232.465626)
		(width 0.14478)
		(layer "In6.Cu")
		(net "M_K_CPU1_SA_DQ<30>")
	)
	(segment
		(start 193.012822 -231.53878)
		(end 193.012822 -231.981756)
		(width 0.14478)
		(layer "In6.Cu")
		(net "M_K_CPU1_SA_DQ<30>")
	)
	(segment
		(start 173.609254 -232.610406)
		(end 174.459392 -231.760268)
		(width 0.14478)
		(layer "In6.Cu")
		(net "M_K_CPU1_SA_DQ<30>")
	)
	(segment
		(start 180.771546 -232.465626)
		(end 180.916326 -232.610406)
		(width 0.14478)
		(layer "In6.Cu")
		(net "M_K_CPU1_SA_DQ<30>")
	)
	(segment
		(start 193.406268 -232.144824)
		(end 193.569336 -231.981756)
		(width 0.14478)
		(layer "In6.Cu")
		(net "M_K_CPU1_SA_DQ<30>")
	)
	(segment
		(start 192.062862 -232.144824)
		(end 192.29324 -232.144824)
		(width 0.14478)
		(layer "In6.Cu")
		(net "M_K_CPU1_SA_DQ<30>")
	)
	(segment
		(start 164.902388 -232.399332)
		(end 165.065456 -232.236264)
		(width 0.14478)
		(layer "In6.Cu")
		(net "M_K_CPU1_SA_DQ<30>")
	)
	(segment
		(start 166.916862 -231.760268)
		(end 167.106854 -231.760268)
		(width 0.14478)
		(layer "In6.Cu")
		(net "M_K_CPU1_SA_DQ<30>")
	)
	(segment
		(start 169.577766 -231.995726)
		(end 169.577766 -231.905048)
		(width 0.14478)
		(layer "In6.Cu")
		(net "M_K_CPU1_SA_DQ<30>")
	)
	(segment
		(start 147.597368 -242.530884)
		(end 147.946618 -242.530884)
		(width 0.0889)
		(layer "In6.Cu")
		(net "M_K_CPU1_SA_DQ<30>")
	)
	(segment
		(start 169.577766 -231.905048)
		(end 169.722546 -231.760268)
		(width 0.14478)
		(layer "In6.Cu")
		(net "M_K_CPU1_SA_DQ<30>")
	)
	(segment
		(start 183.053736 -231.533192)
		(end 183.053736 -231.5972)
		(width 0.14478)
		(layer "In6.Cu")
		(net "M_K_CPU1_SA_DQ<30>")
	)
	(segment
		(start 142.47876 -243.408962)
		(end 142.574772 -243.383562)
		(width 0.0889)
		(layer "In6.Cu")
		(net "M_K_CPU1_SA_DQ<30>")
	)
	(segment
		(start 167.396414 -232.140506)
		(end 167.658288 -232.140506)
		(width 0.14478)
		(layer "In6.Cu")
		(net "M_K_CPU1_SA_DQ<30>")
	)
	(segment
		(start 172.478192 -232.447338)
		(end 172.478192 -232.386632)
		(width 0.14478)
		(layer "In6.Cu")
		(net "M_K_CPU1_SA_DQ<30>")
	)
	(segment
		(start 190.58509 -231.760268)
		(end 191.736726 -231.760268)
		(width 0.14478)
		(layer "In6.Cu")
		(net "M_K_CPU1_SA_DQ<30>")
	)
	(segment
		(start 183.950864 -231.760268)
		(end 184.095644 -231.615488)
		(width 0.14478)
		(layer "In6.Cu")
		(net "M_K_CPU1_SA_DQ<30>")
	)
	(segment
		(start 193.732404 -231.760268)
		(end 194.17919 -231.760268)
		(width 0.14478)
		(layer "In6.Cu")
		(net "M_K_CPU1_SA_DQ<30>")
	)
	(segment
		(start 184.647078 -231.615488)
		(end 184.791858 -231.760268)
		(width 0.14478)
		(layer "In6.Cu")
		(net "M_K_CPU1_SA_DQ<30>")
	)
	(segment
		(start 189.865508 -231.5972)
		(end 189.865508 -231.533192)
		(width 0.14478)
		(layer "In6.Cu")
		(net "M_K_CPU1_SA_DQ<30>")
	)
	(segment
		(start 182.66029 -231.370124)
		(end 182.890668 -231.370124)
		(width 0.14478)
		(layer "In6.Cu")
		(net "M_K_CPU1_SA_DQ<30>")
	)
	(segment
		(start 169.432986 -232.140506)
		(end 169.577766 -231.995726)
		(width 0.14478)
		(layer "In6.Cu")
		(net "M_K_CPU1_SA_DQ<30>")
	)
	(segment
		(start 177.28184 -231.760268)
		(end 177.45202 -231.760268)
		(width 0.14478)
		(layer "In6.Cu")
		(net "M_K_CPU1_SA_DQ<30>")
	)
	(segment
		(start 182.334154 -231.760268)
		(end 182.497222 -231.5972)
		(width 0.14478)
		(layer "In6.Cu")
		(net "M_K_CPU1_SA_DQ<30>")
	)
	(segment
		(start 182.497222 -231.5972)
		(end 182.497222 -231.533192)
		(width 0.14478)
		(layer "In6.Cu")
		(net "M_K_CPU1_SA_DQ<30>")
	)
	(segment
		(start 190.028576 -231.370124)
		(end 190.258954 -231.370124)
		(width 0.14478)
		(layer "In6.Cu")
		(net "M_K_CPU1_SA_DQ<30>")
	)
	(segment
		(start 175.400208 -231.515666)
		(end 175.400208 -231.615488)
		(width 0.14478)
		(layer "In6.Cu")
		(net "M_K_CPU1_SA_DQ<30>")
	)
	(segment
		(start 184.791858 -231.760268)
		(end 184.99582 -231.760268)
		(width 0.14478)
		(layer "In6.Cu")
		(net "M_K_CPU1_SA_DQ<30>")
	)
	(segment
		(start 172.315124 -232.610406)
		(end 172.478192 -232.447338)
		(width 0.14478)
		(layer "In6.Cu")
		(net "M_K_CPU1_SA_DQ<30>")
	)
	(segment
		(start 165.065456 -232.236264)
		(end 165.295834 -232.236264)
		(width 0.14478)
		(layer "In6.Cu")
		(net "M_K_CPU1_SA_DQ<30>")
	)
	(segment
		(start 184.647078 -231.515666)
		(end 184.647078 -231.615488)
		(width 0.14478)
		(layer "In6.Cu")
		(net "M_K_CPU1_SA_DQ<30>")
	)
	(segment
		(start 164.902388 -232.447338)
		(end 164.902388 -232.399332)
		(width 0.14478)
		(layer "In6.Cu")
		(net "M_K_CPU1_SA_DQ<30>")
	)
	(segment
		(start 182.497222 -231.533192)
		(end 182.66029 -231.370124)
		(width 0.14478)
		(layer "In6.Cu")
		(net "M_K_CPU1_SA_DQ<30>")
	)
	(segment
		(start 188.387736 -232.610406)
		(end 188.673232 -232.610406)
		(width 0.14478)
		(layer "In6.Cu")
		(net "M_K_CPU1_SA_DQ<30>")
	)
	(segment
		(start 169.026332 -231.995726)
		(end 169.171112 -232.140506)
		(width 0.14478)
		(layer "In6.Cu")
		(net "M_K_CPU1_SA_DQ<30>")
	)
	(segment
		(start 164.73932 -232.610406)
		(end 164.902388 -232.447338)
		(width 0.14478)
		(layer "In6.Cu")
		(net "M_K_CPU1_SA_DQ<30>")
	)
	(segment
		(start 189.52337 -231.760268)
		(end 189.70244 -231.760268)
		(width 0.14478)
		(layer "In6.Cu")
		(net "M_K_CPU1_SA_DQ<30>")
	)
	(segment
		(start 181.991 -231.760268)
		(end 182.334154 -231.760268)
		(width 0.14478)
		(layer "In6.Cu")
		(net "M_K_CPU1_SA_DQ<30>")
	)
	(segment
		(start 147.946618 -242.530884)
		(end 155.339796 -242.530884)
		(width 0.14478)
		(layer "In6.Cu")
		(net "M_K_CPU1_SA_DQ<30>")
	)
	(arc
		(start 142.574772 -243.383562)
		(mid 142.82998 -243.427039)
		(end 143.077692 -243.351812)
		(width 0.0889)
		(layer "In6.Cu")
		(net "M_K_CPU1_SA_DQ<30>")
	)
	(arc
		(start 144.957546 -243.351812)
		(mid 145.047806 -243.314184)
		(end 145.144744 -243.301266)
		(width 0.0889)
		(layer "In6.Cu")
		(net "M_K_CPU1_SA_DQ<30>")
	)
	(arc
		(start 143.086074 -243.346986)
		(mid 143.269582 -243.301492)
		(end 143.451834 -243.351812)
		(width 0.0889)
		(layer "In6.Cu")
		(net "M_K_CPU1_SA_DQ<30>")
	)
	(arc
		(start 143.451834 -243.351812)
		(mid 143.728647 -243.427955)
		(end 144.007078 -243.357908)
		(width 0.0889)
		(layer "In6.Cu")
		(net "M_K_CPU1_SA_DQ<30>")
	)
	(arc
		(start 144.017492 -243.351812)
		(mid 144.204436 -243.301557)
		(end 144.39138 -243.351812)
		(width 0.0889)
		(layer "In6.Cu")
		(net "M_K_CPU1_SA_DQ<30>")
	)
	(arc
		(start 144.401794 -243.357908)
		(mid 144.68048 -243.428128)
		(end 144.957546 -243.351812)
		(width 0.0889)
		(layer "In6.Cu")
		(net "M_K_CPU1_SA_DQ<30>")
	)
	(segment
		(start 141.857984 -226.120452)
		(end 142.324836 -225.854514)
		(width 0.10668)
		(layer "F.Cu")
		(net "M_K_CPU1_SA_DQ<2>")
	)
	(segment
		(start 181.140862 -198.610474)
		(end 181.991 -197.760336)
		(width 0.14478)
		(layer "In6.Cu")
		(net "M_K_CPU1_SA_DQ<2>")
	)
	(segment
		(start 143.547592 -223.101916)
		(end 143.586708 -223.079056)
		(width 0.0889)
		(layer "In6.Cu")
		(net "M_K_CPU1_SA_DQ<2>")
	)
	(segment
		(start 183.119268 -197.535292)
		(end 183.119268 -197.597268)
		(width 0.14478)
		(layer "In6.Cu")
		(net "M_K_CPU1_SA_DQ<2>")
	)
	(segment
		(start 143.077692 -225.531934)
		(end 143.116808 -225.509074)
		(width 0.0889)
		(layer "In6.Cu")
		(net "M_K_CPU1_SA_DQ<2>")
	)
	(segment
		(start 180.839364 -198.610474)
		(end 181.140862 -198.610474)
		(width 0.14478)
		(layer "In6.Cu")
		(net "M_K_CPU1_SA_DQ<2>")
	)
	(segment
		(start 193.073274 -197.991476)
		(end 193.236342 -198.154544)
		(width 0.14478)
		(layer "In6.Cu")
		(net "M_K_CPU1_SA_DQ<2>")
	)
	(segment
		(start 189.94628 -197.760336)
		(end 190.109348 -197.923404)
		(width 0.14478)
		(layer "In6.Cu")
		(net "M_K_CPU1_SA_DQ<2>")
	)
	(segment
		(start 144.506188 -221.258384)
		(end 144.506188 -221.080584)
		(width 0.14478)
		(layer "In6.Cu")
		(net "M_K_CPU1_SA_DQ<2>")
	)
	(segment
		(start 173.037754 -198.220584)
		(end 173.200822 -198.383652)
		(width 0.14478)
		(layer "In6.Cu")
		(net "M_K_CPU1_SA_DQ<2>")
	)
	(segment
		(start 144.29994 -221.643194)
		(end 144.506188 -221.436946)
		(width 0.0889)
		(layer "In6.Cu")
		(net "M_K_CPU1_SA_DQ<2>")
	)
	(segment
		(start 180.28285 -198.225664)
		(end 180.513228 -198.225664)
		(width 0.14478)
		(layer "In6.Cu")
		(net "M_K_CPU1_SA_DQ<2>")
	)
	(segment
		(start 185.845958 -198.610474)
		(end 187.444126 -198.610474)
		(width 0.14478)
		(layer "In6.Cu")
		(net "M_K_CPU1_SA_DQ<2>")
	)
	(segment
		(start 191.797178 -197.760336)
		(end 191.960246 -197.923404)
		(width 0.14478)
		(layer "In6.Cu")
		(net "M_K_CPU1_SA_DQ<2>")
	)
	(segment
		(start 188.326776 -198.610474)
		(end 188.673232 -198.610474)
		(width 0.14478)
		(layer "In6.Cu")
		(net "M_K_CPU1_SA_DQ<2>")
	)
	(segment
		(start 190.502794 -198.146924)
		(end 190.665862 -197.983856)
		(width 0.14478)
		(layer "In6.Cu")
		(net "M_K_CPU1_SA_DQ<2>")
	)
	(segment
		(start 189.52337 -197.760336)
		(end 189.94628 -197.760336)
		(width 0.14478)
		(layer "In6.Cu")
		(net "M_K_CPU1_SA_DQ<2>")
	)
	(segment
		(start 144.29994 -221.804484)
		(end 144.29994 -221.643194)
		(width 0.0889)
		(layer "In6.Cu")
		(net "M_K_CPU1_SA_DQ<2>")
	)
	(segment
		(start 168.848024 -197.597268)
		(end 169.011092 -197.760336)
		(width 0.14478)
		(layer "In6.Cu")
		(net "M_K_CPU1_SA_DQ<2>")
	)
	(segment
		(start 169.907966 -197.760336)
		(end 170.758104 -198.610474)
		(width 0.14478)
		(layer "In6.Cu")
		(net "M_K_CPU1_SA_DQ<2>")
	)
	(segment
		(start 168.128442 -197.760336)
		(end 168.29151 -197.597268)
		(width 0.14478)
		(layer "In6.Cu")
		(net "M_K_CPU1_SA_DQ<2>")
	)
	(segment
		(start 182.562754 -197.535292)
		(end 182.725822 -197.372224)
		(width 0.14478)
		(layer "In6.Cu")
		(net "M_K_CPU1_SA_DQ<2>")
	)
	(segment
		(start 173.609254 -198.610474)
		(end 174.459392 -197.760336)
		(width 0.14478)
		(layer "In6.Cu")
		(net "M_K_CPU1_SA_DQ<2>")
	)
	(segment
		(start 180.119782 -198.388732)
		(end 180.28285 -198.225664)
		(width 0.14478)
		(layer "In6.Cu")
		(net "M_K_CPU1_SA_DQ<2>")
	)
	(segment
		(start 174.459392 -197.760336)
		(end 174.780956 -197.760336)
		(width 0.14478)
		(layer "In6.Cu")
		(net "M_K_CPU1_SA_DQ<2>")
	)
	(segment
		(start 169.011092 -197.760336)
		(end 169.907966 -197.760336)
		(width 0.14478)
		(layer "In6.Cu")
		(net "M_K_CPU1_SA_DQ<2>")
	)
	(segment
		(start 173.36389 -198.610474)
		(end 173.609254 -198.610474)
		(width 0.14478)
		(layer "In6.Cu")
		(net "M_K_CPU1_SA_DQ<2>")
	)
	(segment
		(start 194.17919 -197.760336)
		(end 194.604132 -198.185278)
		(width 0.14478)
		(layer "In6.Cu")
		(net "M_K_CPU1_SA_DQ<2>")
	)
	(segment
		(start 183.119268 -197.597268)
		(end 183.282336 -197.760336)
		(width 0.14478)
		(layer "In6.Cu")
		(net "M_K_CPU1_SA_DQ<2>")
	)
	(segment
		(start 143.045942 -223.93021)
		(end 143.077692 -223.911922)
		(width 0.0889)
		(layer "In6.Cu")
		(net "M_K_CPU1_SA_DQ<2>")
	)
	(segment
		(start 168.29151 -197.540372)
		(end 168.454578 -197.377304)
		(width 0.14478)
		(layer "In6.Cu")
		(net "M_K_CPU1_SA_DQ<2>")
	)
	(segment
		(start 183.282336 -197.760336)
		(end 184.99582 -197.760336)
		(width 0.14478)
		(layer "In6.Cu")
		(net "M_K_CPU1_SA_DQ<2>")
	)
	(segment
		(start 180.513228 -198.225664)
		(end 180.676296 -198.388732)
		(width 0.14478)
		(layer "In6.Cu")
		(net "M_K_CPU1_SA_DQ<2>")
	)
	(segment
		(start 178.302158 -198.610474)
		(end 179.956714 -198.610474)
		(width 0.14478)
		(layer "In6.Cu")
		(net "M_K_CPU1_SA_DQ<2>")
	)
	(segment
		(start 175.33747 -197.377304)
		(end 175.500538 -197.540372)
		(width 0.14478)
		(layer "In6.Cu")
		(net "M_K_CPU1_SA_DQ<2>")
	)
	(segment
		(start 142.324836 -225.854514)
		(end 142.47876 -225.589084)
		(width 0.0889)
		(layer "In6.Cu")
		(net "M_K_CPU1_SA_DQ<2>")
	)
	(segment
		(start 182.9562 -197.372224)
		(end 183.119268 -197.535292)
		(width 0.14478)
		(layer "In6.Cu")
		(net "M_K_CPU1_SA_DQ<2>")
	)
	(segment
		(start 187.607194 -198.383652)
		(end 187.770262 -198.220584)
		(width 0.14478)
		(layer "In6.Cu")
		(net "M_K_CPU1_SA_DQ<2>")
	)
	(segment
		(start 143.077692 -224.557082)
		(end 143.045942 -224.538794)
		(width 0.0889)
		(layer "In6.Cu")
		(net "M_K_CPU1_SA_DQ<2>")
	)
	(segment
		(start 144.506188 -221.436946)
		(end 144.506188 -221.258384)
		(width 0.0889)
		(layer "In6.Cu")
		(net "M_K_CPU1_SA_DQ<2>")
	)
	(segment
		(start 187.770262 -198.220584)
		(end 188.00064 -198.220584)
		(width 0.14478)
		(layer "In6.Cu")
		(net "M_K_CPU1_SA_DQ<2>")
	)
	(segment
		(start 192.123314 -198.154544)
		(end 192.353692 -198.154544)
		(width 0.14478)
		(layer "In6.Cu")
		(net "M_K_CPU1_SA_DQ<2>")
	)
	(segment
		(start 180.119782 -198.447406)
		(end 180.119782 -198.388732)
		(width 0.14478)
		(layer "In6.Cu")
		(net "M_K_CPU1_SA_DQ<2>")
	)
	(segment
		(start 191.960246 -197.923404)
		(end 191.960246 -197.991476)
		(width 0.14478)
		(layer "In6.Cu")
		(net "M_K_CPU1_SA_DQ<2>")
	)
	(segment
		(start 175.500538 -197.597268)
		(end 175.663606 -197.760336)
		(width 0.14478)
		(layer "In6.Cu")
		(net "M_K_CPU1_SA_DQ<2>")
	)
	(segment
		(start 182.562754 -197.597268)
		(end 182.562754 -197.535292)
		(width 0.14478)
		(layer "In6.Cu")
		(net "M_K_CPU1_SA_DQ<2>")
	)
	(segment
		(start 174.780956 -197.760336)
		(end 174.944024 -197.597268)
		(width 0.14478)
		(layer "In6.Cu")
		(net "M_K_CPU1_SA_DQ<2>")
	)
	(segment
		(start 191.960246 -197.991476)
		(end 192.123314 -198.154544)
		(width 0.14478)
		(layer "In6.Cu")
		(net "M_K_CPU1_SA_DQ<2>")
	)
	(segment
		(start 168.29151 -197.597268)
		(end 168.29151 -197.540372)
		(width 0.14478)
		(layer "In6.Cu")
		(net "M_K_CPU1_SA_DQ<2>")
	)
	(segment
		(start 177.45202 -197.760336)
		(end 178.302158 -198.610474)
		(width 0.14478)
		(layer "In6.Cu")
		(net "M_K_CPU1_SA_DQ<2>")
	)
	(segment
		(start 147.419568 -214.823548)
		(end 163.632642 -198.610474)
		(width 0.14478)
		(layer "In6.Cu")
		(net "M_K_CPU1_SA_DQ<2>")
	)
	(segment
		(start 173.200822 -198.383652)
		(end 173.200822 -198.447406)
		(width 0.14478)
		(layer "In6.Cu")
		(net "M_K_CPU1_SA_DQ<2>")
	)
	(segment
		(start 182.725822 -197.372224)
		(end 182.9562 -197.372224)
		(width 0.14478)
		(layer "In6.Cu")
		(net "M_K_CPU1_SA_DQ<2>")
	)
	(segment
		(start 172.48124 -198.610474)
		(end 172.644308 -198.447406)
		(width 0.14478)
		(layer "In6.Cu")
		(net "M_K_CPU1_SA_DQ<2>")
	)
	(segment
		(start 190.665862 -197.923404)
		(end 190.82893 -197.760336)
		(width 0.14478)
		(layer "In6.Cu")
		(net "M_K_CPU1_SA_DQ<2>")
	)
	(segment
		(start 166.916862 -197.760336)
		(end 168.128442 -197.760336)
		(width 0.14478)
		(layer "In6.Cu")
		(net "M_K_CPU1_SA_DQ<2>")
	)
	(segment
		(start 190.665862 -197.983856)
		(end 190.665862 -197.923404)
		(width 0.14478)
		(layer "In6.Cu")
		(net "M_K_CPU1_SA_DQ<2>")
	)
	(segment
		(start 175.500538 -197.540372)
		(end 175.500538 -197.597268)
		(width 0.14478)
		(layer "In6.Cu")
		(net "M_K_CPU1_SA_DQ<2>")
	)
	(segment
		(start 190.109348 -197.983856)
		(end 190.272416 -198.146924)
		(width 0.14478)
		(layer "In6.Cu")
		(net "M_K_CPU1_SA_DQ<2>")
	)
	(segment
		(start 179.956714 -198.610474)
		(end 180.119782 -198.447406)
		(width 0.14478)
		(layer "In6.Cu")
		(net "M_K_CPU1_SA_DQ<2>")
	)
	(segment
		(start 168.454578 -197.377304)
		(end 168.684956 -197.377304)
		(width 0.14478)
		(layer "In6.Cu")
		(net "M_K_CPU1_SA_DQ<2>")
	)
	(segment
		(start 192.51676 -197.529196)
		(end 192.679828 -197.366128)
		(width 0.14478)
		(layer "In6.Cu")
		(net "M_K_CPU1_SA_DQ<2>")
	)
	(segment
		(start 192.51676 -197.991476)
		(end 192.51676 -197.529196)
		(width 0.14478)
		(layer "In6.Cu")
		(net "M_K_CPU1_SA_DQ<2>")
	)
	(segment
		(start 163.632642 -198.610474)
		(end 166.066724 -198.610474)
		(width 0.14478)
		(layer "In6.Cu")
		(net "M_K_CPU1_SA_DQ<2>")
	)
	(segment
		(start 193.073274 -197.529196)
		(end 193.073274 -197.991476)
		(width 0.14478)
		(layer "In6.Cu")
		(net "M_K_CPU1_SA_DQ<2>")
	)
	(segment
		(start 173.200822 -198.447406)
		(end 173.36389 -198.610474)
		(width 0.14478)
		(layer "In6.Cu")
		(net "M_K_CPU1_SA_DQ<2>")
	)
	(segment
		(start 143.116808 -224.579942)
		(end 143.077692 -224.557082)
		(width 0.0889)
		(layer "In6.Cu")
		(net "M_K_CPU1_SA_DQ<2>")
	)
	(segment
		(start 187.444126 -198.610474)
		(end 187.607194 -198.447406)
		(width 0.14478)
		(layer "In6.Cu")
		(net "M_K_CPU1_SA_DQ<2>")
	)
	(segment
		(start 192.679828 -197.366128)
		(end 192.910206 -197.366128)
		(width 0.14478)
		(layer "In6.Cu")
		(net "M_K_CPU1_SA_DQ<2>")
	)
	(segment
		(start 147.419568 -218.167204)
		(end 147.419568 -214.823548)
		(width 0.14478)
		(layer "In6.Cu")
		(net "M_K_CPU1_SA_DQ<2>")
	)
	(segment
		(start 144.017492 -222.29191)
		(end 144.056608 -222.26905)
		(width 0.0889)
		(layer "In6.Cu")
		(net "M_K_CPU1_SA_DQ<2>")
	)
	(segment
		(start 193.629788 -197.923404)
		(end 193.792856 -197.760336)
		(width 0.14478)
		(layer "In6.Cu")
		(net "M_K_CPU1_SA_DQ<2>")
	)
	(segment
		(start 166.066724 -198.610474)
		(end 166.916862 -197.760336)
		(width 0.14478)
		(layer "In6.Cu")
		(net "M_K_CPU1_SA_DQ<2>")
	)
	(segment
		(start 190.272416 -198.146924)
		(end 190.502794 -198.146924)
		(width 0.14478)
		(layer "In6.Cu")
		(net "M_K_CPU1_SA_DQ<2>")
	)
	(segment
		(start 187.607194 -198.447406)
		(end 187.607194 -198.383652)
		(width 0.14478)
		(layer "In6.Cu")
		(net "M_K_CPU1_SA_DQ<2>")
	)
	(segment
		(start 174.944024 -197.540372)
		(end 175.107092 -197.377304)
		(width 0.14478)
		(layer "In6.Cu")
		(net "M_K_CPU1_SA_DQ<2>")
	)
	(segment
		(start 192.910206 -197.366128)
		(end 193.073274 -197.529196)
		(width 0.14478)
		(layer "In6.Cu")
		(net "M_K_CPU1_SA_DQ<2>")
	)
	(segment
		(start 172.644308 -198.383652)
		(end 172.807376 -198.220584)
		(width 0.14478)
		(layer "In6.Cu")
		(net "M_K_CPU1_SA_DQ<2>")
	)
	(segment
		(start 175.107092 -197.377304)
		(end 175.33747 -197.377304)
		(width 0.14478)
		(layer "In6.Cu")
		(net "M_K_CPU1_SA_DQ<2>")
	)
	(segment
		(start 143.987012 -222.30969)
		(end 144.017492 -222.29191)
		(width 0.0889)
		(layer "In6.Cu")
		(net "M_K_CPU1_SA_DQ<2>")
	)
	(segment
		(start 193.236342 -198.154544)
		(end 193.46672 -198.154544)
		(width 0.14478)
		(layer "In6.Cu")
		(net "M_K_CPU1_SA_DQ<2>")
	)
	(segment
		(start 184.99582 -197.760336)
		(end 185.845958 -198.610474)
		(width 0.14478)
		(layer "In6.Cu")
		(net "M_K_CPU1_SA_DQ<2>")
	)
	(segment
		(start 192.353692 -198.154544)
		(end 192.51676 -197.991476)
		(width 0.14478)
		(layer "In6.Cu")
		(net "M_K_CPU1_SA_DQ<2>")
	)
	(segment
		(start 188.163708 -198.447406)
		(end 188.326776 -198.610474)
		(width 0.14478)
		(layer "In6.Cu")
		(net "M_K_CPU1_SA_DQ<2>")
	)
	(segment
		(start 175.663606 -197.760336)
		(end 177.45202 -197.760336)
		(width 0.14478)
		(layer "In6.Cu")
		(net "M_K_CPU1_SA_DQ<2>")
	)
	(segment
		(start 170.758104 -198.610474)
		(end 172.48124 -198.610474)
		(width 0.14478)
		(layer "In6.Cu")
		(net "M_K_CPU1_SA_DQ<2>")
	)
	(segment
		(start 182.399686 -197.760336)
		(end 182.562754 -197.597268)
		(width 0.14478)
		(layer "In6.Cu")
		(net "M_K_CPU1_SA_DQ<2>")
	)
	(segment
		(start 180.676296 -198.447406)
		(end 180.839364 -198.610474)
		(width 0.14478)
		(layer "In6.Cu")
		(net "M_K_CPU1_SA_DQ<2>")
	)
	(segment
		(start 143.517112 -223.119696)
		(end 143.547592 -223.101916)
		(width 0.0889)
		(layer "In6.Cu")
		(net "M_K_CPU1_SA_DQ<2>")
	)
	(segment
		(start 168.684956 -197.377304)
		(end 168.848024 -197.540372)
		(width 0.14478)
		(layer "In6.Cu")
		(net "M_K_CPU1_SA_DQ<2>")
	)
	(segment
		(start 193.46672 -198.154544)
		(end 193.629788 -197.991476)
		(width 0.14478)
		(layer "In6.Cu")
		(net "M_K_CPU1_SA_DQ<2>")
	)
	(segment
		(start 193.792856 -197.760336)
		(end 194.17919 -197.760336)
		(width 0.14478)
		(layer "In6.Cu")
		(net "M_K_CPU1_SA_DQ<2>")
	)
	(segment
		(start 181.991 -197.760336)
		(end 182.399686 -197.760336)
		(width 0.14478)
		(layer "In6.Cu")
		(net "M_K_CPU1_SA_DQ<2>")
	)
	(segment
		(start 190.82893 -197.760336)
		(end 191.797178 -197.760336)
		(width 0.14478)
		(layer "In6.Cu")
		(net "M_K_CPU1_SA_DQ<2>")
	)
	(segment
		(start 188.163708 -198.383652)
		(end 188.163708 -198.447406)
		(width 0.14478)
		(layer "In6.Cu")
		(net "M_K_CPU1_SA_DQ<2>")
	)
	(segment
		(start 188.00064 -198.220584)
		(end 188.163708 -198.383652)
		(width 0.14478)
		(layer "In6.Cu")
		(net "M_K_CPU1_SA_DQ<2>")
	)
	(segment
		(start 172.807376 -198.220584)
		(end 173.037754 -198.220584)
		(width 0.14478)
		(layer "In6.Cu")
		(net "M_K_CPU1_SA_DQ<2>")
	)
	(segment
		(start 143.077692 -223.911922)
		(end 143.116808 -223.889062)
		(width 0.0889)
		(layer "In6.Cu")
		(net "M_K_CPU1_SA_DQ<2>")
	)
	(segment
		(start 172.644308 -198.447406)
		(end 172.644308 -198.383652)
		(width 0.14478)
		(layer "In6.Cu")
		(net "M_K_CPU1_SA_DQ<2>")
	)
	(segment
		(start 180.676296 -198.388732)
		(end 180.676296 -198.447406)
		(width 0.14478)
		(layer "In6.Cu")
		(net "M_K_CPU1_SA_DQ<2>")
	)
	(segment
		(start 142.47876 -225.589084)
		(end 142.574772 -225.563684)
		(width 0.0889)
		(layer "In6.Cu")
		(net "M_K_CPU1_SA_DQ<2>")
	)
	(segment
		(start 174.944024 -197.597268)
		(end 174.944024 -197.540372)
		(width 0.14478)
		(layer "In6.Cu")
		(net "M_K_CPU1_SA_DQ<2>")
	)
	(segment
		(start 168.848024 -197.540372)
		(end 168.848024 -197.597268)
		(width 0.14478)
		(layer "In6.Cu")
		(net "M_K_CPU1_SA_DQ<2>")
	)
	(segment
		(start 193.629788 -197.991476)
		(end 193.629788 -197.923404)
		(width 0.14478)
		(layer "In6.Cu")
		(net "M_K_CPU1_SA_DQ<2>")
	)
	(segment
		(start 144.506188 -221.080584)
		(end 147.419568 -218.167204)
		(width 0.14478)
		(layer "In6.Cu")
		(net "M_K_CPU1_SA_DQ<2>")
	)
	(segment
		(start 188.673232 -198.610474)
		(end 189.52337 -197.760336)
		(width 0.14478)
		(layer "In6.Cu")
		(net "M_K_CPU1_SA_DQ<2>")
	)
	(segment
		(start 190.109348 -197.923404)
		(end 190.109348 -197.983856)
		(width 0.14478)
		(layer "In6.Cu")
		(net "M_K_CPU1_SA_DQ<2>")
	)
	(arc
		(start 142.574772 -225.563684)
		(mid 142.82998 -225.607161)
		(end 143.077692 -225.531934)
		(width 0.0889)
		(layer "In6.Cu")
		(net "M_K_CPU1_SA_DQ<2>")
	)
	(arc
		(start 143.045942 -224.538794)
		(mid 142.890014 -224.234502)
		(end 143.045942 -223.93021)
		(width 0.0889)
		(layer "In6.Cu")
		(net "M_K_CPU1_SA_DQ<2>")
	)
	(arc
		(start 143.116808 -225.509074)
		(mid 143.360135 -225.044508)
		(end 143.116808 -224.579942)
		(width 0.0889)
		(layer "In6.Cu")
		(net "M_K_CPU1_SA_DQ<2>")
	)
	(arc
		(start 143.36014 -223.424496)
		(mid 143.401689 -223.253074)
		(end 143.517112 -223.119696)
		(width 0.0889)
		(layer "In6.Cu")
		(net "M_K_CPU1_SA_DQ<2>")
	)
	(arc
		(start 143.586708 -223.079056)
		(mid 143.765521 -222.876706)
		(end 143.83004 -222.61449)
		(width 0.0889)
		(layer "In6.Cu")
		(net "M_K_CPU1_SA_DQ<2>")
	)
	(arc
		(start 144.056608 -222.26905)
		(mid 144.235421 -222.0667)
		(end 144.29994 -221.804484)
		(width 0.0889)
		(layer "In6.Cu")
		(net "M_K_CPU1_SA_DQ<2>")
	)
	(arc
		(start 143.116808 -223.889062)
		(mid 143.295621 -223.686712)
		(end 143.36014 -223.424496)
		(width 0.0889)
		(layer "In6.Cu")
		(net "M_K_CPU1_SA_DQ<2>")
	)
	(arc
		(start 143.83004 -222.61449)
		(mid 143.871589 -222.443068)
		(end 143.987012 -222.30969)
		(width 0.0889)
		(layer "In6.Cu")
		(net "M_K_CPU1_SA_DQ<2>")
	)
	(segment
		(start 140.91793 -243.94033)
		(end 141.384782 -243.674392)
		(width 0.10668)
		(layer "F.Cu")
		(net "M_K_CPU1_SA_DQ<29>")
	)
	(segment
		(start 189.651132 -232.610406)
		(end 196.05371 -232.610406)
		(width 0.14478)
		(layer "In6.Cu")
		(net "M_K_CPU1_SA_DQ<29>")
	)
	(segment
		(start 196.216778 -232.913936)
		(end 196.379846 -233.077004)
		(width 0.14478)
		(layer "In6.Cu")
		(net "M_K_CPU1_SA_DQ<29>")
	)
	(segment
		(start 141.230858 -243.939822)
		(end 141.25321 -244.023134)
		(width 0.0889)
		(layer "In6.Cu")
		(net "M_K_CPU1_SA_DQ<29>")
	)
	(segment
		(start 166.956486 -232.610152)
		(end 169.907966 -232.610152)
		(width 0.14478)
		(layer "In6.Cu")
		(net "M_K_CPU1_SA_DQ<29>")
	)
	(segment
		(start 166.106348 -233.46029)
		(end 166.956486 -232.610152)
		(width 0.14478)
		(layer "In6.Cu")
		(net "M_K_CPU1_SA_DQ<29>")
	)
	(segment
		(start 142.503398 -244.001798)
		(end 142.51178 -243.996972)
		(width 0.0889)
		(layer "In6.Cu")
		(net "M_K_CPU1_SA_DQ<29>")
	)
	(segment
		(start 181.990746 -232.610406)
		(end 184.996074 -232.610406)
		(width 0.14478)
		(layer "In6.Cu")
		(net "M_K_CPU1_SA_DQ<29>")
	)
	(segment
		(start 196.93636 -232.610406)
		(end 198.279258 -232.610406)
		(width 0.14478)
		(layer "In6.Cu")
		(net "M_K_CPU1_SA_DQ<29>")
	)
	(segment
		(start 162.061906 -235.57865)
		(end 164.180266 -233.46029)
		(width 0.14478)
		(layer "In6.Cu")
		(net "M_K_CPU1_SA_DQ<29>")
	)
	(segment
		(start 198.279258 -232.610406)
		(end 198.7042 -233.035348)
		(width 0.14478)
		(layer "In6.Cu")
		(net "M_K_CPU1_SA_DQ<29>")
	)
	(segment
		(start 145.650712 -244.047518)
		(end 146.212306 -243.485924)
		(width 0.0889)
		(layer "In6.Cu")
		(net "M_K_CPU1_SA_DQ<29>")
	)
	(segment
		(start 169.907966 -232.610152)
		(end 170.758104 -233.46029)
		(width 0.14478)
		(layer "In6.Cu")
		(net "M_K_CPU1_SA_DQ<29>")
	)
	(segment
		(start 141.384782 -243.674392)
		(end 141.230858 -243.939822)
		(width 0.0889)
		(layer "In6.Cu")
		(net "M_K_CPU1_SA_DQ<29>")
	)
	(segment
		(start 143.077692 -243.996972)
		(end 143.086074 -244.001798)
		(width 0.0889)
		(layer "In6.Cu")
		(net "M_K_CPU1_SA_DQ<29>")
	)
	(segment
		(start 145.14449 -244.047518)
		(end 145.650712 -244.047518)
		(width 0.0889)
		(layer "In6.Cu")
		(net "M_K_CPU1_SA_DQ<29>")
	)
	(segment
		(start 184.996074 -232.610406)
		(end 185.845958 -233.46029)
		(width 0.14478)
		(layer "In6.Cu")
		(net "M_K_CPU1_SA_DQ<29>")
	)
	(segment
		(start 147.604988 -242.985544)
		(end 147.946618 -242.985544)
		(width 0.0889)
		(layer "In6.Cu")
		(net "M_K_CPU1_SA_DQ<29>")
	)
	(segment
		(start 144.391126 -243.996972)
		(end 144.40154 -243.990876)
		(width 0.0889)
		(layer "In6.Cu")
		(net "M_K_CPU1_SA_DQ<29>")
	)
	(segment
		(start 170.758104 -233.46029)
		(end 173.609254 -233.46029)
		(width 0.14478)
		(layer "In6.Cu")
		(net "M_K_CPU1_SA_DQ<29>")
	)
	(segment
		(start 162.061906 -236.451902)
		(end 162.061906 -235.57865)
		(width 0.14478)
		(layer "In6.Cu")
		(net "M_K_CPU1_SA_DQ<29>")
	)
	(segment
		(start 173.609254 -233.46029)
		(end 174.459138 -232.610406)
		(width 0.14478)
		(layer "In6.Cu")
		(net "M_K_CPU1_SA_DQ<29>")
	)
	(segment
		(start 147.104608 -243.485924)
		(end 147.604988 -242.985544)
		(width 0.0889)
		(layer "In6.Cu")
		(net "M_K_CPU1_SA_DQ<29>")
	)
	(segment
		(start 144.007078 -243.990876)
		(end 144.017492 -243.996972)
		(width 0.0889)
		(layer "In6.Cu")
		(net "M_K_CPU1_SA_DQ<29>")
	)
	(segment
		(start 181.140862 -233.46029)
		(end 181.990746 -232.610406)
		(width 0.14478)
		(layer "In6.Cu")
		(net "M_K_CPU1_SA_DQ<29>")
	)
	(segment
		(start 196.773292 -232.913936)
		(end 196.773292 -232.773474)
		(width 0.14478)
		(layer "In6.Cu")
		(net "M_K_CPU1_SA_DQ<29>")
	)
	(segment
		(start 147.946618 -242.985544)
		(end 155.528264 -242.985544)
		(width 0.14478)
		(layer "In6.Cu")
		(net "M_K_CPU1_SA_DQ<29>")
	)
	(segment
		(start 188.801248 -233.46029)
		(end 189.651132 -232.610406)
		(width 0.14478)
		(layer "In6.Cu")
		(net "M_K_CPU1_SA_DQ<29>")
	)
	(segment
		(start 196.773292 -232.773474)
		(end 196.93636 -232.610406)
		(width 0.14478)
		(layer "In6.Cu")
		(net "M_K_CPU1_SA_DQ<29>")
	)
	(segment
		(start 196.610224 -233.077004)
		(end 196.773292 -232.913936)
		(width 0.14478)
		(layer "In6.Cu")
		(net "M_K_CPU1_SA_DQ<29>")
	)
	(segment
		(start 144.017492 -243.996972)
		(end 144.025874 -244.001798)
		(width 0.0889)
		(layer "In6.Cu")
		(net "M_K_CPU1_SA_DQ<29>")
	)
	(segment
		(start 196.05371 -232.610406)
		(end 196.216778 -232.773474)
		(width 0.14478)
		(layer "In6.Cu")
		(net "M_K_CPU1_SA_DQ<29>")
	)
	(segment
		(start 174.459138 -232.610406)
		(end 177.452274 -232.610406)
		(width 0.14478)
		(layer "In6.Cu")
		(net "M_K_CPU1_SA_DQ<29>")
	)
	(segment
		(start 185.845958 -233.46029)
		(end 188.801248 -233.46029)
		(width 0.14478)
		(layer "In6.Cu")
		(net "M_K_CPU1_SA_DQ<29>")
	)
	(segment
		(start 146.212306 -243.485924)
		(end 147.104608 -243.485924)
		(width 0.0889)
		(layer "In6.Cu")
		(net "M_K_CPU1_SA_DQ<29>")
	)
	(segment
		(start 196.379846 -233.077004)
		(end 196.610224 -233.077004)
		(width 0.14478)
		(layer "In6.Cu")
		(net "M_K_CPU1_SA_DQ<29>")
	)
	(segment
		(start 178.302158 -233.46029)
		(end 181.140862 -233.46029)
		(width 0.14478)
		(layer "In6.Cu")
		(net "M_K_CPU1_SA_DQ<29>")
	)
	(segment
		(start 164.180266 -233.46029)
		(end 166.106348 -233.46029)
		(width 0.14478)
		(layer "In6.Cu")
		(net "M_K_CPU1_SA_DQ<29>")
	)
	(segment
		(start 196.216778 -232.773474)
		(end 196.216778 -232.913936)
		(width 0.14478)
		(layer "In6.Cu")
		(net "M_K_CPU1_SA_DQ<29>")
	)
	(segment
		(start 177.452274 -232.610406)
		(end 178.302158 -233.46029)
		(width 0.14478)
		(layer "In6.Cu")
		(net "M_K_CPU1_SA_DQ<29>")
	)
	(segment
		(start 155.528264 -242.985544)
		(end 162.061906 -236.451902)
		(width 0.14478)
		(layer "In6.Cu")
		(net "M_K_CPU1_SA_DQ<29>")
	)
	(arc
		(start 143.451834 -243.996972)
		(mid 143.728647 -243.920829)
		(end 144.007078 -243.990876)
		(width 0.0889)
		(layer "In6.Cu")
		(net "M_K_CPU1_SA_DQ<29>")
	)
	(arc
		(start 141.25321 -244.023134)
		(mid 141.415399 -244.045869)
		(end 141.571726 -243.996972)
		(width 0.0889)
		(layer "In6.Cu")
		(net "M_K_CPU1_SA_DQ<29>")
	)
	(arc
		(start 142.137638 -243.996972)
		(mid 142.319889 -244.047322)
		(end 142.503398 -244.001798)
		(width 0.0889)
		(layer "In6.Cu")
		(net "M_K_CPU1_SA_DQ<29>")
	)
	(arc
		(start 144.025874 -244.001798)
		(mid 144.209128 -244.047171)
		(end 144.391126 -243.996972)
		(width 0.0889)
		(layer "In6.Cu")
		(net "M_K_CPU1_SA_DQ<29>")
	)
	(arc
		(start 142.51178 -243.996972)
		(mid 142.794736 -243.920795)
		(end 143.077692 -243.996972)
		(width 0.0889)
		(layer "In6.Cu")
		(net "M_K_CPU1_SA_DQ<29>")
	)
	(arc
		(start 141.571726 -243.996972)
		(mid 141.854682 -243.920795)
		(end 142.137638 -243.996972)
		(width 0.0889)
		(layer "In6.Cu")
		(net "M_K_CPU1_SA_DQ<29>")
	)
	(arc
		(start 143.086074 -244.001798)
		(mid 143.269582 -244.047292)
		(end 143.451834 -243.996972)
		(width 0.0889)
		(layer "In6.Cu")
		(net "M_K_CPU1_SA_DQ<29>")
	)
	(arc
		(start 144.40154 -243.990876)
		(mid 144.680226 -243.920656)
		(end 144.957292 -243.996972)
		(width 0.0889)
		(layer "In6.Cu")
		(net "M_K_CPU1_SA_DQ<29>")
	)
	(arc
		(start 144.957292 -243.996972)
		(mid 145.047552 -244.0346)
		(end 145.14449 -244.047518)
		(width 0.0889)
		(layer "In6.Cu")
		(net "M_K_CPU1_SA_DQ<29>")
	)
	(segment
		(start 142.327884 -243.130324)
		(end 142.794736 -242.864386)
		(width 0.10668)
		(layer "F.Cu")
		(net "M_K_CPU1_SA_DQ<28>")
	)
	(segment
		(start 198.279258 -230.910384)
		(end 198.7042 -231.335326)
		(width 0.14478)
		(layer "In6.Cu")
		(net "M_K_CPU1_SA_DQ<28>")
	)
	(segment
		(start 196.61886 -230.919782)
		(end 196.77253 -231.073452)
		(width 0.14478)
		(layer "In6.Cu")
		(net "M_K_CPU1_SA_DQ<28>")
	)
	(segment
		(start 197.492112 -230.910384)
		(end 198.279258 -230.910384)
		(width 0.14478)
		(layer "In6.Cu")
		(net "M_K_CPU1_SA_DQ<28>")
	)
	(segment
		(start 188.79185 -231.769666)
		(end 189.641734 -230.919782)
		(width 0.14478)
		(layer "In6.Cu")
		(net "M_K_CPU1_SA_DQ<28>")
	)
	(segment
		(start 161.101786 -236.125766)
		(end 161.101786 -234.976924)
		(width 0.14478)
		(layer "In6.Cu")
		(net "M_K_CPU1_SA_DQ<28>")
	)
	(segment
		(start 166.58209 -231.284526)
		(end 170.282362 -231.284526)
		(width 0.14478)
		(layer "In6.Cu")
		(net "M_K_CPU1_SA_DQ<28>")
	)
	(segment
		(start 196.77253 -231.073452)
		(end 196.77253 -231.816656)
		(width 0.14478)
		(layer "In6.Cu")
		(net "M_K_CPU1_SA_DQ<28>")
	)
	(segment
		(start 161.101786 -234.976924)
		(end 164.318442 -231.760268)
		(width 0.14478)
		(layer "In6.Cu")
		(net "M_K_CPU1_SA_DQ<28>")
	)
	(segment
		(start 143.913352 -243.191792)
		(end 143.921734 -243.186966)
		(width 0.0889)
		(layer "In6.Cu")
		(net "M_K_CPU1_SA_DQ<28>")
	)
	(segment
		(start 196.935598 -231.979724)
		(end 197.165976 -231.979724)
		(width 0.14478)
		(layer "In6.Cu")
		(net "M_K_CPU1_SA_DQ<28>")
	)
	(segment
		(start 174.44974 -230.919782)
		(end 177.461672 -230.919782)
		(width 0.14478)
		(layer "In6.Cu")
		(net "M_K_CPU1_SA_DQ<28>")
	)
	(segment
		(start 147.193762 -242.50523)
		(end 147.622768 -242.076224)
		(width 0.0889)
		(layer "In6.Cu")
		(net "M_K_CPU1_SA_DQ<28>")
	)
	(segment
		(start 181.981348 -230.919782)
		(end 185.005472 -230.919782)
		(width 0.14478)
		(layer "In6.Cu")
		(net "M_K_CPU1_SA_DQ<28>")
	)
	(segment
		(start 155.151328 -242.076224)
		(end 161.101786 -236.125766)
		(width 0.14478)
		(layer "In6.Cu")
		(net "M_K_CPU1_SA_DQ<28>")
	)
	(segment
		(start 144.487392 -243.186966)
		(end 144.495774 -243.191792)
		(width 0.0889)
		(layer "In6.Cu")
		(net "M_K_CPU1_SA_DQ<28>")
	)
	(segment
		(start 170.282362 -231.284526)
		(end 170.767502 -231.769666)
		(width 0.14478)
		(layer "In6.Cu")
		(net "M_K_CPU1_SA_DQ<28>")
	)
	(segment
		(start 170.767502 -231.769666)
		(end 173.599856 -231.769666)
		(width 0.14478)
		(layer "In6.Cu")
		(net "M_K_CPU1_SA_DQ<28>")
	)
	(segment
		(start 142.794736 -242.864386)
		(end 142.640812 -243.129816)
		(width 0.0889)
		(layer "In6.Cu")
		(net "M_K_CPU1_SA_DQ<28>")
	)
	(segment
		(start 142.640812 -243.129816)
		(end 142.663164 -243.213128)
		(width 0.0889)
		(layer "In6.Cu")
		(net "M_K_CPU1_SA_DQ<28>")
	)
	(segment
		(start 196.77253 -231.816656)
		(end 196.935598 -231.979724)
		(width 0.14478)
		(layer "In6.Cu")
		(net "M_K_CPU1_SA_DQ<28>")
	)
	(segment
		(start 185.855356 -231.769666)
		(end 188.79185 -231.769666)
		(width 0.14478)
		(layer "In6.Cu")
		(net "M_K_CPU1_SA_DQ<28>")
	)
	(segment
		(start 189.641734 -230.919782)
		(end 196.61886 -230.919782)
		(width 0.14478)
		(layer "In6.Cu")
		(net "M_K_CPU1_SA_DQ<28>")
	)
	(segment
		(start 178.311556 -231.769666)
		(end 181.131464 -231.769666)
		(width 0.14478)
		(layer "In6.Cu")
		(net "M_K_CPU1_SA_DQ<28>")
	)
	(segment
		(start 164.318442 -231.760268)
		(end 166.106348 -231.760268)
		(width 0.14478)
		(layer "In6.Cu")
		(net "M_K_CPU1_SA_DQ<28>")
	)
	(segment
		(start 197.165976 -231.979724)
		(end 197.329044 -231.816656)
		(width 0.14478)
		(layer "In6.Cu")
		(net "M_K_CPU1_SA_DQ<28>")
	)
	(segment
		(start 166.106348 -231.760268)
		(end 166.58209 -231.284526)
		(width 0.14478)
		(layer "In6.Cu")
		(net "M_K_CPU1_SA_DQ<28>")
	)
	(segment
		(start 181.131464 -231.769666)
		(end 181.981348 -230.919782)
		(width 0.14478)
		(layer "In6.Cu")
		(net "M_K_CPU1_SA_DQ<28>")
	)
	(segment
		(start 145.144744 -243.110766)
		(end 145.834354 -243.110766)
		(width 0.0889)
		(layer "In6.Cu")
		(net "M_K_CPU1_SA_DQ<28>")
	)
	(segment
		(start 197.329044 -231.073452)
		(end 197.492112 -230.910384)
		(width 0.14478)
		(layer "In6.Cu")
		(net "M_K_CPU1_SA_DQ<28>")
	)
	(segment
		(start 147.622768 -242.076224)
		(end 147.952206 -242.076224)
		(width 0.0889)
		(layer "In6.Cu")
		(net "M_K_CPU1_SA_DQ<28>")
	)
	(segment
		(start 185.005472 -230.919782)
		(end 185.855356 -231.769666)
		(width 0.14478)
		(layer "In6.Cu")
		(net "M_K_CPU1_SA_DQ<28>")
	)
	(segment
		(start 173.599856 -231.769666)
		(end 174.44974 -230.919782)
		(width 0.14478)
		(layer "In6.Cu")
		(net "M_K_CPU1_SA_DQ<28>")
	)
	(segment
		(start 146.43989 -242.50523)
		(end 147.193762 -242.50523)
		(width 0.0889)
		(layer "In6.Cu")
		(net "M_K_CPU1_SA_DQ<28>")
	)
	(segment
		(start 143.921734 -243.186966)
		(end 143.932148 -243.18087)
		(width 0.0889)
		(layer "In6.Cu")
		(net "M_K_CPU1_SA_DQ<28>")
	)
	(segment
		(start 197.329044 -231.816656)
		(end 197.329044 -231.073452)
		(width 0.14478)
		(layer "In6.Cu")
		(net "M_K_CPU1_SA_DQ<28>")
	)
	(segment
		(start 147.952206 -242.076224)
		(end 155.151328 -242.076224)
		(width 0.14478)
		(layer "In6.Cu")
		(net "M_K_CPU1_SA_DQ<28>")
	)
	(segment
		(start 145.834354 -243.110766)
		(end 146.43989 -242.50523)
		(width 0.0889)
		(layer "In6.Cu")
		(net "M_K_CPU1_SA_DQ<28>")
	)
	(segment
		(start 177.461672 -230.919782)
		(end 178.311556 -231.769666)
		(width 0.14478)
		(layer "In6.Cu")
		(net "M_K_CPU1_SA_DQ<28>")
	)
	(arc
		(start 142.98168 -243.186966)
		(mid 143.264636 -243.110789)
		(end 143.547592 -243.186966)
		(width 0.0889)
		(layer "In6.Cu")
		(net "M_K_CPU1_SA_DQ<28>")
	)
	(arc
		(start 143.547592 -243.186966)
		(mid 143.729843 -243.237316)
		(end 143.913352 -243.191792)
		(width 0.0889)
		(layer "In6.Cu")
		(net "M_K_CPU1_SA_DQ<28>")
	)
	(arc
		(start 144.861534 -243.186966)
		(mid 144.998097 -243.130133)
		(end 145.144744 -243.110766)
		(width 0.0889)
		(layer "In6.Cu")
		(net "M_K_CPU1_SA_DQ<28>")
	)
	(arc
		(start 143.932148 -243.18087)
		(mid 144.21058 -243.110772)
		(end 144.487392 -243.186966)
		(width 0.0889)
		(layer "In6.Cu")
		(net "M_K_CPU1_SA_DQ<28>")
	)
	(arc
		(start 144.495774 -243.191792)
		(mid 144.679282 -243.237286)
		(end 144.861534 -243.186966)
		(width 0.0889)
		(layer "In6.Cu")
		(net "M_K_CPU1_SA_DQ<28>")
	)
	(arc
		(start 142.663164 -243.213128)
		(mid 142.825353 -243.235863)
		(end 142.98168 -243.186966)
		(width 0.0889)
		(layer "In6.Cu")
		(net "M_K_CPU1_SA_DQ<28>")
	)
	(segment
		(start 140.447776 -241.510312)
		(end 140.914882 -241.244374)
		(width 0.10668)
		(layer "F.Cu")
		(net "M_K_CPU1_SA_DQ<27>")
	)
	(segment
		(start 175.516794 -227.500942)
		(end 177.442622 -227.500942)
		(width 0.14478)
		(layer "In6.Cu")
		(net "M_K_CPU1_SA_DQ<27>")
	)
	(segment
		(start 140.914882 -241.244374)
		(end 141.068806 -240.978944)
		(width 0.0889)
		(layer "In6.Cu")
		(net "M_K_CPU1_SA_DQ<27>")
	)
	(segment
		(start 158.577788 -233.23804)
		(end 163.45535 -228.360478)
		(width 0.14478)
		(layer "In6.Cu")
		(net "M_K_CPU1_SA_DQ<27>")
	)
	(segment
		(start 143.92148 -240.921794)
		(end 143.931894 -240.92789)
		(width 0.0889)
		(layer "In6.Cu")
		(net "M_K_CPU1_SA_DQ<27>")
	)
	(segment
		(start 187.729622 -227.971604)
		(end 187.96 -227.971604)
		(width 0.14478)
		(layer "In6.Cu")
		(net "M_K_CPU1_SA_DQ<27>")
	)
	(segment
		(start 169.898568 -227.500942)
		(end 170.748706 -228.35108)
		(width 0.14478)
		(layer "In6.Cu")
		(net "M_K_CPU1_SA_DQ<27>")
	)
	(segment
		(start 180.013356 -228.129592)
		(end 180.176424 -227.966524)
		(width 0.14478)
		(layer "In6.Cu")
		(net "M_K_CPU1_SA_DQ<27>")
	)
	(segment
		(start 192.450466 -227.500942)
		(end 192.913 -227.500942)
		(width 0.14478)
		(layer "In6.Cu")
		(net "M_K_CPU1_SA_DQ<27>")
	)
	(segment
		(start 146.980656 -240.554764)
		(end 147.798536 -239.736884)
		(width 0.0889)
		(layer "In6.Cu")
		(net "M_K_CPU1_SA_DQ<27>")
	)
	(segment
		(start 175.200056 -227.130864)
		(end 175.363124 -227.293932)
		(width 0.14478)
		(layer "In6.Cu")
		(net "M_K_CPU1_SA_DQ<27>")
	)
	(segment
		(start 166.92626 -227.500942)
		(end 169.898568 -227.500942)
		(width 0.14478)
		(layer "In6.Cu")
		(net "M_K_CPU1_SA_DQ<27>")
	)
	(segment
		(start 172.707046 -227.966524)
		(end 172.937424 -227.966524)
		(width 0.14478)
		(layer "In6.Cu")
		(net "M_K_CPU1_SA_DQ<27>")
	)
	(segment
		(start 180.56987 -228.129592)
		(end 180.56987 -228.19741)
		(width 0.14478)
		(layer "In6.Cu")
		(net "M_K_CPU1_SA_DQ<27>")
	)
	(segment
		(start 193.085466 -227.673408)
		(end 193.085466 -227.880418)
		(width 0.14478)
		(layer "In6.Cu")
		(net "M_K_CPU1_SA_DQ<27>")
	)
	(segment
		(start 185.83656 -228.35108)
		(end 187.412884 -228.35108)
		(width 0.14478)
		(layer "In6.Cu")
		(net "M_K_CPU1_SA_DQ<27>")
	)
	(segment
		(start 193.085466 -227.880418)
		(end 193.248534 -228.043486)
		(width 0.14478)
		(layer "In6.Cu")
		(net "M_K_CPU1_SA_DQ<27>")
	)
	(segment
		(start 188.286136 -228.360478)
		(end 188.673232 -228.360478)
		(width 0.14478)
		(layer "In6.Cu")
		(net "M_K_CPU1_SA_DQ<27>")
	)
	(segment
		(start 147.798536 -239.736884)
		(end 147.952206 -239.736884)
		(width 0.0889)
		(layer "In6.Cu")
		(net "M_K_CPU1_SA_DQ<27>")
	)
	(segment
		(start 172.390308 -228.35108)
		(end 172.543978 -228.19741)
		(width 0.14478)
		(layer "In6.Cu")
		(net "M_K_CPU1_SA_DQ<27>")
	)
	(segment
		(start 182.946294 -227.347272)
		(end 183.099964 -227.500942)
		(width 0.14478)
		(layer "In6.Cu")
		(net "M_K_CPU1_SA_DQ<27>")
	)
	(segment
		(start 145.277332 -241.039904)
		(end 145.788888 -241.039904)
		(width 0.0889)
		(layer "In6.Cu")
		(net "M_K_CPU1_SA_DQ<27>")
	)
	(segment
		(start 172.543978 -228.19741)
		(end 172.543978 -228.129592)
		(width 0.14478)
		(layer "In6.Cu")
		(net "M_K_CPU1_SA_DQ<27>")
	)
	(segment
		(start 174.80661 -227.347272)
		(end 174.80661 -227.293932)
		(width 0.14478)
		(layer "In6.Cu")
		(net "M_K_CPU1_SA_DQ<27>")
	)
	(segment
		(start 192.133728 -227.118164)
		(end 192.296796 -227.281232)
		(width 0.14478)
		(layer "In6.Cu")
		(net "M_K_CPU1_SA_DQ<27>")
	)
	(segment
		(start 180.406802 -227.966524)
		(end 180.56987 -228.129592)
		(width 0.14478)
		(layer "In6.Cu")
		(net "M_K_CPU1_SA_DQ<27>")
	)
	(segment
		(start 180.013356 -228.19741)
		(end 180.013356 -228.129592)
		(width 0.14478)
		(layer "In6.Cu")
		(net "M_K_CPU1_SA_DQ<27>")
	)
	(segment
		(start 191.740282 -227.281232)
		(end 191.90335 -227.118164)
		(width 0.14478)
		(layer "In6.Cu")
		(net "M_K_CPU1_SA_DQ<27>")
	)
	(segment
		(start 182.226712 -227.51034)
		(end 182.38978 -227.347272)
		(width 0.14478)
		(layer "In6.Cu")
		(net "M_K_CPU1_SA_DQ<27>")
	)
	(segment
		(start 191.90335 -227.118164)
		(end 192.133728 -227.118164)
		(width 0.14478)
		(layer "In6.Cu")
		(net "M_K_CPU1_SA_DQ<27>")
	)
	(segment
		(start 193.478912 -228.043486)
		(end 193.64198 -227.880418)
		(width 0.14478)
		(layer "In6.Cu")
		(net "M_K_CPU1_SA_DQ<27>")
	)
	(segment
		(start 141.667738 -240.921794)
		(end 141.67612 -240.916968)
		(width 0.0889)
		(layer "In6.Cu")
		(net "M_K_CPU1_SA_DQ<27>")
	)
	(segment
		(start 194.17919 -227.51034)
		(end 194.604132 -227.935282)
		(width 0.14478)
		(layer "In6.Cu")
		(net "M_K_CPU1_SA_DQ<27>")
	)
	(segment
		(start 193.64198 -227.673408)
		(end 193.805048 -227.51034)
		(width 0.14478)
		(layer "In6.Cu")
		(net "M_K_CPU1_SA_DQ<27>")
	)
	(segment
		(start 182.38978 -227.286312)
		(end 182.552848 -227.123244)
		(width 0.14478)
		(layer "In6.Cu")
		(net "M_K_CPU1_SA_DQ<27>")
	)
	(segment
		(start 163.45535 -228.360478)
		(end 166.066724 -228.360478)
		(width 0.14478)
		(layer "In6.Cu")
		(net "M_K_CPU1_SA_DQ<27>")
	)
	(segment
		(start 193.64198 -227.880418)
		(end 193.64198 -227.673408)
		(width 0.14478)
		(layer "In6.Cu")
		(net "M_K_CPU1_SA_DQ<27>")
	)
	(segment
		(start 188.123068 -228.134672)
		(end 188.123068 -228.19741)
		(width 0.14478)
		(layer "In6.Cu")
		(net "M_K_CPU1_SA_DQ<27>")
	)
	(segment
		(start 192.913 -227.500942)
		(end 193.085466 -227.673408)
		(width 0.14478)
		(layer "In6.Cu")
		(net "M_K_CPU1_SA_DQ<27>")
	)
	(segment
		(start 180.732938 -228.360478)
		(end 181.140862 -228.360478)
		(width 0.14478)
		(layer "In6.Cu")
		(net "M_K_CPU1_SA_DQ<27>")
	)
	(segment
		(start 178.29276 -228.35108)
		(end 179.859686 -228.35108)
		(width 0.14478)
		(layer "In6.Cu")
		(net "M_K_CPU1_SA_DQ<27>")
	)
	(segment
		(start 144.861534 -240.921794)
		(end 144.880838 -240.93297)
		(width 0.0889)
		(layer "In6.Cu")
		(net "M_K_CPU1_SA_DQ<27>")
	)
	(segment
		(start 170.748706 -228.35108)
		(end 172.390308 -228.35108)
		(width 0.14478)
		(layer "In6.Cu")
		(net "M_K_CPU1_SA_DQ<27>")
	)
	(segment
		(start 187.566554 -228.19741)
		(end 187.566554 -228.134672)
		(width 0.14478)
		(layer "In6.Cu")
		(net "M_K_CPU1_SA_DQ<27>")
	)
	(segment
		(start 193.805048 -227.51034)
		(end 194.17919 -227.51034)
		(width 0.14478)
		(layer "In6.Cu")
		(net "M_K_CPU1_SA_DQ<27>")
	)
	(segment
		(start 173.100492 -228.129592)
		(end 173.100492 -228.19741)
		(width 0.14478)
		(layer "In6.Cu")
		(net "M_K_CPU1_SA_DQ<27>")
	)
	(segment
		(start 182.38978 -227.347272)
		(end 182.38978 -227.286312)
		(width 0.14478)
		(layer "In6.Cu")
		(net "M_K_CPU1_SA_DQ<27>")
	)
	(segment
		(start 182.783226 -227.123244)
		(end 182.946294 -227.286312)
		(width 0.14478)
		(layer "In6.Cu")
		(net "M_K_CPU1_SA_DQ<27>")
	)
	(segment
		(start 192.296796 -227.347272)
		(end 192.450466 -227.500942)
		(width 0.14478)
		(layer "In6.Cu")
		(net "M_K_CPU1_SA_DQ<27>")
	)
	(segment
		(start 182.552848 -227.123244)
		(end 182.783226 -227.123244)
		(width 0.14478)
		(layer "In6.Cu")
		(net "M_K_CPU1_SA_DQ<27>")
	)
	(segment
		(start 143.909796 -240.914936)
		(end 143.92148 -240.921794)
		(width 0.0889)
		(layer "In6.Cu")
		(net "M_K_CPU1_SA_DQ<27>")
	)
	(segment
		(start 175.363124 -227.347272)
		(end 175.516794 -227.500942)
		(width 0.14478)
		(layer "In6.Cu")
		(net "M_K_CPU1_SA_DQ<27>")
	)
	(segment
		(start 184.986422 -227.500942)
		(end 185.83656 -228.35108)
		(width 0.14478)
		(layer "In6.Cu")
		(net "M_K_CPU1_SA_DQ<27>")
	)
	(segment
		(start 191.586612 -227.500942)
		(end 191.740282 -227.347272)
		(width 0.14478)
		(layer "In6.Cu")
		(net "M_K_CPU1_SA_DQ<27>")
	)
	(segment
		(start 174.80661 -227.293932)
		(end 174.969678 -227.130864)
		(width 0.14478)
		(layer "In6.Cu")
		(net "M_K_CPU1_SA_DQ<27>")
	)
	(segment
		(start 189.532768 -227.500942)
		(end 191.586612 -227.500942)
		(width 0.14478)
		(layer "In6.Cu")
		(net "M_K_CPU1_SA_DQ<27>")
	)
	(segment
		(start 180.56987 -228.19741)
		(end 180.732938 -228.360478)
		(width 0.14478)
		(layer "In6.Cu")
		(net "M_K_CPU1_SA_DQ<27>")
	)
	(segment
		(start 182.946294 -227.286312)
		(end 182.946294 -227.347272)
		(width 0.14478)
		(layer "In6.Cu")
		(net "M_K_CPU1_SA_DQ<27>")
	)
	(segment
		(start 192.296796 -227.281232)
		(end 192.296796 -227.347272)
		(width 0.14478)
		(layer "In6.Cu")
		(net "M_K_CPU1_SA_DQ<27>")
	)
	(segment
		(start 174.643542 -227.51034)
		(end 174.80661 -227.347272)
		(width 0.14478)
		(layer "In6.Cu")
		(net "M_K_CPU1_SA_DQ<27>")
	)
	(segment
		(start 193.248534 -228.043486)
		(end 193.478912 -228.043486)
		(width 0.14478)
		(layer "In6.Cu")
		(net "M_K_CPU1_SA_DQ<27>")
	)
	(segment
		(start 175.363124 -227.293932)
		(end 175.363124 -227.347272)
		(width 0.14478)
		(layer "In6.Cu")
		(net "M_K_CPU1_SA_DQ<27>")
	)
	(segment
		(start 179.859686 -228.35108)
		(end 180.013356 -228.19741)
		(width 0.14478)
		(layer "In6.Cu")
		(net "M_K_CPU1_SA_DQ<27>")
	)
	(segment
		(start 188.673232 -228.360478)
		(end 189.532768 -227.500942)
		(width 0.14478)
		(layer "In6.Cu")
		(net "M_K_CPU1_SA_DQ<27>")
	)
	(segment
		(start 174.969678 -227.130864)
		(end 175.200056 -227.130864)
		(width 0.14478)
		(layer "In6.Cu")
		(net "M_K_CPU1_SA_DQ<27>")
	)
	(segment
		(start 173.609254 -228.360478)
		(end 174.459392 -227.51034)
		(width 0.14478)
		(layer "In6.Cu")
		(net "M_K_CPU1_SA_DQ<27>")
	)
	(segment
		(start 172.937424 -227.966524)
		(end 173.100492 -228.129592)
		(width 0.14478)
		(layer "In6.Cu")
		(net "M_K_CPU1_SA_DQ<27>")
	)
	(segment
		(start 187.96 -227.971604)
		(end 188.123068 -228.134672)
		(width 0.14478)
		(layer "In6.Cu")
		(net "M_K_CPU1_SA_DQ<27>")
	)
	(segment
		(start 177.442622 -227.500942)
		(end 178.29276 -228.35108)
		(width 0.14478)
		(layer "In6.Cu")
		(net "M_K_CPU1_SA_DQ<27>")
	)
	(segment
		(start 141.068806 -240.978944)
		(end 141.164818 -240.953544)
		(width 0.0889)
		(layer "In6.Cu")
		(net "M_K_CPU1_SA_DQ<27>")
	)
	(segment
		(start 181.991 -227.51034)
		(end 182.226712 -227.51034)
		(width 0.14478)
		(layer "In6.Cu")
		(net "M_K_CPU1_SA_DQ<27>")
	)
	(segment
		(start 191.740282 -227.347272)
		(end 191.740282 -227.281232)
		(width 0.14478)
		(layer "In6.Cu")
		(net "M_K_CPU1_SA_DQ<27>")
	)
	(segment
		(start 187.566554 -228.134672)
		(end 187.729622 -227.971604)
		(width 0.14478)
		(layer "In6.Cu")
		(net "M_K_CPU1_SA_DQ<27>")
	)
	(segment
		(start 145.788888 -241.039904)
		(end 146.274028 -240.554764)
		(width 0.0889)
		(layer "In6.Cu")
		(net "M_K_CPU1_SA_DQ<27>")
	)
	(segment
		(start 154.113484 -239.736884)
		(end 158.577788 -235.27258)
		(width 0.14478)
		(layer "In6.Cu")
		(net "M_K_CPU1_SA_DQ<27>")
	)
	(segment
		(start 173.26356 -228.360478)
		(end 173.609254 -228.360478)
		(width 0.14478)
		(layer "In6.Cu")
		(net "M_K_CPU1_SA_DQ<27>")
	)
	(segment
		(start 172.543978 -228.129592)
		(end 172.707046 -227.966524)
		(width 0.14478)
		(layer "In6.Cu")
		(net "M_K_CPU1_SA_DQ<27>")
	)
	(segment
		(start 166.066724 -228.360478)
		(end 166.92626 -227.500942)
		(width 0.14478)
		(layer "In6.Cu")
		(net "M_K_CPU1_SA_DQ<27>")
	)
	(segment
		(start 183.099964 -227.500942)
		(end 184.986422 -227.500942)
		(width 0.14478)
		(layer "In6.Cu")
		(net "M_K_CPU1_SA_DQ<27>")
	)
	(segment
		(start 158.577788 -235.27258)
		(end 158.577788 -233.23804)
		(width 0.14478)
		(layer "In6.Cu")
		(net "M_K_CPU1_SA_DQ<27>")
	)
	(segment
		(start 173.100492 -228.19741)
		(end 173.26356 -228.360478)
		(width 0.14478)
		(layer "In6.Cu")
		(net "M_K_CPU1_SA_DQ<27>")
	)
	(segment
		(start 188.123068 -228.19741)
		(end 188.286136 -228.360478)
		(width 0.14478)
		(layer "In6.Cu")
		(net "M_K_CPU1_SA_DQ<27>")
	)
	(segment
		(start 146.274028 -240.554764)
		(end 146.980656 -240.554764)
		(width 0.0889)
		(layer "In6.Cu")
		(net "M_K_CPU1_SA_DQ<27>")
	)
	(segment
		(start 187.412884 -228.35108)
		(end 187.566554 -228.19741)
		(width 0.14478)
		(layer "In6.Cu")
		(net "M_K_CPU1_SA_DQ<27>")
	)
	(segment
		(start 181.140862 -228.360478)
		(end 181.991 -227.51034)
		(width 0.14478)
		(layer "In6.Cu")
		(net "M_K_CPU1_SA_DQ<27>")
	)
	(segment
		(start 180.176424 -227.966524)
		(end 180.406802 -227.966524)
		(width 0.14478)
		(layer "In6.Cu")
		(net "M_K_CPU1_SA_DQ<27>")
	)
	(segment
		(start 147.952206 -239.736884)
		(end 154.113484 -239.736884)
		(width 0.14478)
		(layer "In6.Cu")
		(net "M_K_CPU1_SA_DQ<27>")
	)
	(segment
		(start 174.459392 -227.51034)
		(end 174.643542 -227.51034)
		(width 0.14478)
		(layer "In6.Cu")
		(net "M_K_CPU1_SA_DQ<27>")
	)
	(segment
		(start 144.487138 -240.921794)
		(end 144.498822 -240.914936)
		(width 0.0889)
		(layer "In6.Cu")
		(net "M_K_CPU1_SA_DQ<27>")
	)
	(arc
		(start 141.164818 -240.953544)
		(mid 141.420026 -240.997021)
		(end 141.667738 -240.921794)
		(width 0.0889)
		(layer "In6.Cu")
		(net "M_K_CPU1_SA_DQ<27>")
	)
	(arc
		(start 141.67612 -240.916968)
		(mid 141.859628 -240.871474)
		(end 142.04188 -240.921794)
		(width 0.0889)
		(layer "In6.Cu")
		(net "M_K_CPU1_SA_DQ<27>")
	)
	(arc
		(start 142.98168 -240.921794)
		(mid 143.264636 -240.997971)
		(end 143.547592 -240.921794)
		(width 0.0889)
		(layer "In6.Cu")
		(net "M_K_CPU1_SA_DQ<27>")
	)
	(arc
		(start 144.498822 -240.914936)
		(mid 144.681077 -240.871283)
		(end 144.861534 -240.921794)
		(width 0.0889)
		(layer "In6.Cu")
		(net "M_K_CPU1_SA_DQ<27>")
	)
	(arc
		(start 142.04188 -240.921794)
		(mid 142.324836 -240.997971)
		(end 142.607792 -240.921794)
		(width 0.0889)
		(layer "In6.Cu")
		(net "M_K_CPU1_SA_DQ<27>")
	)
	(arc
		(start 144.880838 -240.93297)
		(mid 145.072008 -241.012662)
		(end 145.277332 -241.039904)
		(width 0.0889)
		(layer "In6.Cu")
		(net "M_K_CPU1_SA_DQ<27>")
	)
	(arc
		(start 142.607792 -240.921794)
		(mid 142.794736 -240.871539)
		(end 142.98168 -240.921794)
		(width 0.0889)
		(layer "In6.Cu")
		(net "M_K_CPU1_SA_DQ<27>")
	)
	(arc
		(start 143.931894 -240.92789)
		(mid 144.210326 -240.997988)
		(end 144.487138 -240.921794)
		(width 0.0889)
		(layer "In6.Cu")
		(net "M_K_CPU1_SA_DQ<27>")
	)
	(arc
		(start 143.547592 -240.921794)
		(mid 143.727797 -240.871477)
		(end 143.909796 -240.914936)
		(width 0.0889)
		(layer "In6.Cu")
		(net "M_K_CPU1_SA_DQ<27>")
	)
	(segment
		(start 141.857984 -240.700306)
		(end 142.324836 -240.434368)
		(width 0.10668)
		(layer "F.Cu")
		(net "M_K_CPU1_SA_DQ<26>")
	)
	(segment
		(start 145.144744 -240.061242)
		(end 145.95475 -240.061242)
		(width 0.0889)
		(layer "In6.Cu")
		(net "M_K_CPU1_SA_DQ<26>")
	)
	(segment
		(start 188.673232 -226.660456)
		(end 189.52337 -225.810318)
		(width 0.14478)
		(layer "In6.Cu")
		(net "M_K_CPU1_SA_DQ<26>")
	)
	(segment
		(start 188.146944 -226.497388)
		(end 188.310012 -226.660456)
		(width 0.14478)
		(layer "In6.Cu")
		(net "M_K_CPU1_SA_DQ<26>")
	)
	(segment
		(start 182.597552 -225.416364)
		(end 182.82793 -225.416364)
		(width 0.14478)
		(layer "In6.Cu")
		(net "M_K_CPU1_SA_DQ<26>")
	)
	(segment
		(start 187.59043 -226.497388)
		(end 187.59043 -226.445572)
		(width 0.14478)
		(layer "In6.Cu")
		(net "M_K_CPU1_SA_DQ<26>")
	)
	(segment
		(start 146.502628 -239.513364)
		(end 146.858228 -239.513364)
		(width 0.0889)
		(layer "In6.Cu")
		(net "M_K_CPU1_SA_DQ<26>")
	)
	(segment
		(start 168.072308 -225.810318)
		(end 168.302686 -225.810318)
		(width 0.14478)
		(layer "In6.Cu")
		(net "M_K_CPU1_SA_DQ<26>")
	)
	(segment
		(start 179.939188 -226.660456)
		(end 180.102256 -226.497388)
		(width 0.14478)
		(layer "In6.Cu")
		(net "M_K_CPU1_SA_DQ<26>")
	)
	(segment
		(start 187.427362 -226.660456)
		(end 187.59043 -226.497388)
		(width 0.14478)
		(layer "In6.Cu")
		(net "M_K_CPU1_SA_DQ<26>")
	)
	(segment
		(start 174.77105 -225.587052)
		(end 174.934118 -225.423984)
		(width 0.14478)
		(layer "In6.Cu")
		(net "M_K_CPU1_SA_DQ<26>")
	)
	(segment
		(start 188.310012 -226.660456)
		(end 188.673232 -226.660456)
		(width 0.14478)
		(layer "In6.Cu")
		(net "M_K_CPU1_SA_DQ<26>")
	)
	(segment
		(start 182.434484 -225.579432)
		(end 182.597552 -225.416364)
		(width 0.14478)
		(layer "In6.Cu")
		(net "M_K_CPU1_SA_DQ<26>")
	)
	(segment
		(start 192.763394 -225.421952)
		(end 192.993772 -225.421952)
		(width 0.14478)
		(layer "In6.Cu")
		(net "M_K_CPU1_SA_DQ<26>")
	)
	(segment
		(start 182.990998 -225.64725)
		(end 183.154066 -225.810318)
		(width 0.14478)
		(layer "In6.Cu")
		(net "M_K_CPU1_SA_DQ<26>")
	)
	(segment
		(start 144.39138 -240.111788)
		(end 144.401794 -240.117884)
		(width 0.0889)
		(layer "In6.Cu")
		(net "M_K_CPU1_SA_DQ<26>")
	)
	(segment
		(start 174.607982 -225.810318)
		(end 174.77105 -225.64725)
		(width 0.14478)
		(layer "In6.Cu")
		(net "M_K_CPU1_SA_DQ<26>")
	)
	(segment
		(start 168.628822 -225.423984)
		(end 168.8592 -225.423984)
		(width 0.14478)
		(layer "In6.Cu")
		(net "M_K_CPU1_SA_DQ<26>")
	)
	(segment
		(start 167.189658 -225.810318)
		(end 167.352726 -225.64725)
		(width 0.14478)
		(layer "In6.Cu")
		(net "M_K_CPU1_SA_DQ<26>")
	)
	(segment
		(start 145.95475 -240.061242)
		(end 146.502628 -239.513364)
		(width 0.0889)
		(layer "In6.Cu")
		(net "M_K_CPU1_SA_DQ<26>")
	)
	(segment
		(start 170.758104 -226.660456)
		(end 173.609254 -226.660456)
		(width 0.14478)
		(layer "In6.Cu")
		(net "M_K_CPU1_SA_DQ<26>")
	)
	(segment
		(start 190.469774 -225.64725)
		(end 190.632842 -225.810318)
		(width 0.14478)
		(layer "In6.Cu")
		(net "M_K_CPU1_SA_DQ<26>")
	)
	(segment
		(start 166.916862 -225.810318)
		(end 167.189658 -225.810318)
		(width 0.14478)
		(layer "In6.Cu")
		(net "M_K_CPU1_SA_DQ<26>")
	)
	(segment
		(start 180.102256 -226.432872)
		(end 180.265324 -226.269804)
		(width 0.14478)
		(layer "In6.Cu")
		(net "M_K_CPU1_SA_DQ<26>")
	)
	(segment
		(start 143.077692 -240.111788)
		(end 143.086074 -240.106962)
		(width 0.0889)
		(layer "In6.Cu")
		(net "M_K_CPU1_SA_DQ<26>")
	)
	(segment
		(start 192.437258 -226.198684)
		(end 192.600326 -226.035616)
		(width 0.14478)
		(layer "In6.Cu")
		(net "M_K_CPU1_SA_DQ<26>")
	)
	(segment
		(start 182.82793 -225.416364)
		(end 182.990998 -225.579432)
		(width 0.14478)
		(layer "In6.Cu")
		(net "M_K_CPU1_SA_DQ<26>")
	)
	(segment
		(start 181.991 -225.810318)
		(end 182.271416 -225.810318)
		(width 0.14478)
		(layer "In6.Cu")
		(net "M_K_CPU1_SA_DQ<26>")
	)
	(segment
		(start 187.983876 -226.282504)
		(end 188.146944 -226.445572)
		(width 0.14478)
		(layer "In6.Cu")
		(net "M_K_CPU1_SA_DQ<26>")
	)
	(segment
		(start 177.45202 -225.810318)
		(end 178.302158 -226.660456)
		(width 0.14478)
		(layer "In6.Cu")
		(net "M_K_CPU1_SA_DQ<26>")
	)
	(segment
		(start 192.043812 -225.973386)
		(end 192.043812 -226.035616)
		(width 0.14478)
		(layer "In6.Cu")
		(net "M_K_CPU1_SA_DQ<26>")
	)
	(segment
		(start 187.753498 -226.282504)
		(end 187.983876 -226.282504)
		(width 0.14478)
		(layer "In6.Cu")
		(net "M_K_CPU1_SA_DQ<26>")
	)
	(segment
		(start 189.91326 -225.587052)
		(end 190.076328 -225.423984)
		(width 0.14478)
		(layer "In6.Cu")
		(net "M_K_CPU1_SA_DQ<26>")
	)
	(segment
		(start 175.490632 -225.810318)
		(end 177.45202 -225.810318)
		(width 0.14478)
		(layer "In6.Cu")
		(net "M_K_CPU1_SA_DQ<26>")
	)
	(segment
		(start 168.465754 -225.64725)
		(end 168.465754 -225.587052)
		(width 0.14478)
		(layer "In6.Cu")
		(net "M_K_CPU1_SA_DQ<26>")
	)
	(segment
		(start 181.140862 -226.660456)
		(end 181.991 -225.810318)
		(width 0.14478)
		(layer "In6.Cu")
		(net "M_K_CPU1_SA_DQ<26>")
	)
	(segment
		(start 190.469774 -225.587052)
		(end 190.469774 -225.64725)
		(width 0.14478)
		(layer "In6.Cu")
		(net "M_K_CPU1_SA_DQ<26>")
	)
	(segment
		(start 144.007078 -240.117884)
		(end 144.017492 -240.111788)
		(width 0.0889)
		(layer "In6.Cu")
		(net "M_K_CPU1_SA_DQ<26>")
	)
	(segment
		(start 182.434484 -225.64725)
		(end 182.434484 -225.579432)
		(width 0.14478)
		(layer "In6.Cu")
		(net "M_K_CPU1_SA_DQ<26>")
	)
	(segment
		(start 142.47876 -240.168938)
		(end 142.574772 -240.143538)
		(width 0.0889)
		(layer "In6.Cu")
		(net "M_K_CPU1_SA_DQ<26>")
	)
	(segment
		(start 175.327564 -225.587052)
		(end 175.327564 -225.64725)
		(width 0.14478)
		(layer "In6.Cu")
		(net "M_K_CPU1_SA_DQ<26>")
	)
	(segment
		(start 157.663388 -234.893612)
		(end 157.663388 -232.845102)
		(width 0.14478)
		(layer "In6.Cu")
		(net "M_K_CPU1_SA_DQ<26>")
	)
	(segment
		(start 193.15684 -225.58502)
		(end 193.15684 -226.035616)
		(width 0.14478)
		(layer "In6.Cu")
		(net "M_K_CPU1_SA_DQ<26>")
	)
	(segment
		(start 169.907966 -225.810318)
		(end 170.758104 -226.660456)
		(width 0.14478)
		(layer "In6.Cu")
		(net "M_K_CPU1_SA_DQ<26>")
	)
	(segment
		(start 178.302158 -226.660456)
		(end 179.939188 -226.660456)
		(width 0.14478)
		(layer "In6.Cu")
		(net "M_K_CPU1_SA_DQ<26>")
	)
	(segment
		(start 147.549108 -238.822484)
		(end 147.917916 -238.822484)
		(width 0.0889)
		(layer "In6.Cu")
		(net "M_K_CPU1_SA_DQ<26>")
	)
	(segment
		(start 180.65877 -226.497388)
		(end 180.821838 -226.660456)
		(width 0.14478)
		(layer "In6.Cu")
		(net "M_K_CPU1_SA_DQ<26>")
	)
	(segment
		(start 175.164496 -225.423984)
		(end 175.327564 -225.587052)
		(width 0.14478)
		(layer "In6.Cu")
		(net "M_K_CPU1_SA_DQ<26>")
	)
	(segment
		(start 189.52337 -225.810318)
		(end 189.750192 -225.810318)
		(width 0.14478)
		(layer "In6.Cu")
		(net "M_K_CPU1_SA_DQ<26>")
	)
	(segment
		(start 180.65877 -226.432872)
		(end 180.65877 -226.497388)
		(width 0.14478)
		(layer "In6.Cu")
		(net "M_K_CPU1_SA_DQ<26>")
	)
	(segment
		(start 167.352726 -225.587052)
		(end 167.515794 -225.423984)
		(width 0.14478)
		(layer "In6.Cu")
		(net "M_K_CPU1_SA_DQ<26>")
	)
	(segment
		(start 191.880744 -225.810318)
		(end 192.043812 -225.973386)
		(width 0.14478)
		(layer "In6.Cu")
		(net "M_K_CPU1_SA_DQ<26>")
	)
	(segment
		(start 182.990998 -225.579432)
		(end 182.990998 -225.64725)
		(width 0.14478)
		(layer "In6.Cu")
		(net "M_K_CPU1_SA_DQ<26>")
	)
	(segment
		(start 147.917916 -238.822484)
		(end 153.734516 -238.822484)
		(width 0.14478)
		(layer "In6.Cu")
		(net "M_K_CPU1_SA_DQ<26>")
	)
	(segment
		(start 174.934118 -225.423984)
		(end 175.164496 -225.423984)
		(width 0.14478)
		(layer "In6.Cu")
		(net "M_K_CPU1_SA_DQ<26>")
	)
	(segment
		(start 173.609254 -226.660456)
		(end 174.459392 -225.810318)
		(width 0.14478)
		(layer "In6.Cu")
		(net "M_K_CPU1_SA_DQ<26>")
	)
	(segment
		(start 180.265324 -226.269804)
		(end 180.495702 -226.269804)
		(width 0.14478)
		(layer "In6.Cu")
		(net "M_K_CPU1_SA_DQ<26>")
	)
	(segment
		(start 193.713354 -226.035616)
		(end 193.713354 -225.973386)
		(width 0.14478)
		(layer "In6.Cu")
		(net "M_K_CPU1_SA_DQ<26>")
	)
	(segment
		(start 168.302686 -225.810318)
		(end 168.465754 -225.64725)
		(width 0.14478)
		(layer "In6.Cu")
		(net "M_K_CPU1_SA_DQ<26>")
	)
	(segment
		(start 168.465754 -225.587052)
		(end 168.628822 -225.423984)
		(width 0.14478)
		(layer "In6.Cu")
		(net "M_K_CPU1_SA_DQ<26>")
	)
	(segment
		(start 193.550286 -226.198684)
		(end 193.713354 -226.035616)
		(width 0.14478)
		(layer "In6.Cu")
		(net "M_K_CPU1_SA_DQ<26>")
	)
	(segment
		(start 168.8592 -225.423984)
		(end 169.022268 -225.587052)
		(width 0.14478)
		(layer "In6.Cu")
		(net "M_K_CPU1_SA_DQ<26>")
	)
	(segment
		(start 167.352726 -225.64725)
		(end 167.352726 -225.587052)
		(width 0.14478)
		(layer "In6.Cu")
		(net "M_K_CPU1_SA_DQ<26>")
	)
	(segment
		(start 188.146944 -226.445572)
		(end 188.146944 -226.497388)
		(width 0.14478)
		(layer "In6.Cu")
		(net "M_K_CPU1_SA_DQ<26>")
	)
	(segment
		(start 192.993772 -225.421952)
		(end 193.15684 -225.58502)
		(width 0.14478)
		(layer "In6.Cu")
		(net "M_K_CPU1_SA_DQ<26>")
	)
	(segment
		(start 189.91326 -225.64725)
		(end 189.91326 -225.587052)
		(width 0.14478)
		(layer "In6.Cu")
		(net "M_K_CPU1_SA_DQ<26>")
	)
	(segment
		(start 190.632842 -225.810318)
		(end 191.880744 -225.810318)
		(width 0.14478)
		(layer "In6.Cu")
		(net "M_K_CPU1_SA_DQ<26>")
	)
	(segment
		(start 146.858228 -239.513364)
		(end 147.549108 -238.822484)
		(width 0.0889)
		(layer "In6.Cu")
		(net "M_K_CPU1_SA_DQ<26>")
	)
	(segment
		(start 192.043812 -226.035616)
		(end 192.20688 -226.198684)
		(width 0.14478)
		(layer "In6.Cu")
		(net "M_K_CPU1_SA_DQ<26>")
	)
	(segment
		(start 166.066724 -226.660456)
		(end 166.916862 -225.810318)
		(width 0.14478)
		(layer "In6.Cu")
		(net "M_K_CPU1_SA_DQ<26>")
	)
	(segment
		(start 180.102256 -226.497388)
		(end 180.102256 -226.432872)
		(width 0.14478)
		(layer "In6.Cu")
		(net "M_K_CPU1_SA_DQ<26>")
	)
	(segment
		(start 169.185336 -225.810318)
		(end 169.907966 -225.810318)
		(width 0.14478)
		(layer "In6.Cu")
		(net "M_K_CPU1_SA_DQ<26>")
	)
	(segment
		(start 180.821838 -226.660456)
		(end 181.140862 -226.660456)
		(width 0.14478)
		(layer "In6.Cu")
		(net "M_K_CPU1_SA_DQ<26>")
	)
	(segment
		(start 174.459392 -225.810318)
		(end 174.607982 -225.810318)
		(width 0.14478)
		(layer "In6.Cu")
		(net "M_K_CPU1_SA_DQ<26>")
	)
	(segment
		(start 192.20688 -226.198684)
		(end 192.437258 -226.198684)
		(width 0.14478)
		(layer "In6.Cu")
		(net "M_K_CPU1_SA_DQ<26>")
	)
	(segment
		(start 183.154066 -225.810318)
		(end 184.99582 -225.810318)
		(width 0.14478)
		(layer "In6.Cu")
		(net "M_K_CPU1_SA_DQ<26>")
	)
	(segment
		(start 184.99582 -225.810318)
		(end 185.845958 -226.660456)
		(width 0.14478)
		(layer "In6.Cu")
		(net "M_K_CPU1_SA_DQ<26>")
	)
	(segment
		(start 180.495702 -226.269804)
		(end 180.65877 -226.432872)
		(width 0.14478)
		(layer "In6.Cu")
		(net "M_K_CPU1_SA_DQ<26>")
	)
	(segment
		(start 187.59043 -226.445572)
		(end 187.753498 -226.282504)
		(width 0.14478)
		(layer "In6.Cu")
		(net "M_K_CPU1_SA_DQ<26>")
	)
	(segment
		(start 142.324836 -240.434368)
		(end 142.47876 -240.168938)
		(width 0.0889)
		(layer "In6.Cu")
		(net "M_K_CPU1_SA_DQ<26>")
	)
	(segment
		(start 169.022268 -225.64725)
		(end 169.185336 -225.810318)
		(width 0.14478)
		(layer "In6.Cu")
		(net "M_K_CPU1_SA_DQ<26>")
	)
	(segment
		(start 174.77105 -225.64725)
		(end 174.77105 -225.587052)
		(width 0.14478)
		(layer "In6.Cu")
		(net "M_K_CPU1_SA_DQ<26>")
	)
	(segment
		(start 190.076328 -225.423984)
		(end 190.306706 -225.423984)
		(width 0.14478)
		(layer "In6.Cu")
		(net "M_K_CPU1_SA_DQ<26>")
	)
	(segment
		(start 192.600326 -226.035616)
		(end 192.600326 -225.58502)
		(width 0.14478)
		(layer "In6.Cu")
		(net "M_K_CPU1_SA_DQ<26>")
	)
	(segment
		(start 167.515794 -225.423984)
		(end 167.746172 -225.423984)
		(width 0.14478)
		(layer "In6.Cu")
		(net "M_K_CPU1_SA_DQ<26>")
	)
	(segment
		(start 182.271416 -225.810318)
		(end 182.434484 -225.64725)
		(width 0.14478)
		(layer "In6.Cu")
		(net "M_K_CPU1_SA_DQ<26>")
	)
	(segment
		(start 175.327564 -225.64725)
		(end 175.490632 -225.810318)
		(width 0.14478)
		(layer "In6.Cu")
		(net "M_K_CPU1_SA_DQ<26>")
	)
	(segment
		(start 190.306706 -225.423984)
		(end 190.469774 -225.587052)
		(width 0.14478)
		(layer "In6.Cu")
		(net "M_K_CPU1_SA_DQ<26>")
	)
	(segment
		(start 185.845958 -226.660456)
		(end 187.427362 -226.660456)
		(width 0.14478)
		(layer "In6.Cu")
		(net "M_K_CPU1_SA_DQ<26>")
	)
	(segment
		(start 167.746172 -225.423984)
		(end 167.90924 -225.587052)
		(width 0.14478)
		(layer "In6.Cu")
		(net "M_K_CPU1_SA_DQ<26>")
	)
	(segment
		(start 167.90924 -225.587052)
		(end 167.90924 -225.64725)
		(width 0.14478)
		(layer "In6.Cu")
		(net "M_K_CPU1_SA_DQ<26>")
	)
	(segment
		(start 153.734516 -238.822484)
		(end 157.663388 -234.893612)
		(width 0.14478)
		(layer "In6.Cu")
		(net "M_K_CPU1_SA_DQ<26>")
	)
	(segment
		(start 163.848034 -226.660456)
		(end 166.066724 -226.660456)
		(width 0.14478)
		(layer "In6.Cu")
		(net "M_K_CPU1_SA_DQ<26>")
	)
	(segment
		(start 169.022268 -225.587052)
		(end 169.022268 -225.64725)
		(width 0.14478)
		(layer "In6.Cu")
		(net "M_K_CPU1_SA_DQ<26>")
	)
	(segment
		(start 194.17919 -225.810318)
		(end 194.604132 -226.23526)
		(width 0.14478)
		(layer "In6.Cu")
		(net "M_K_CPU1_SA_DQ<26>")
	)
	(segment
		(start 193.713354 -225.973386)
		(end 193.876422 -225.810318)
		(width 0.14478)
		(layer "In6.Cu")
		(net "M_K_CPU1_SA_DQ<26>")
	)
	(segment
		(start 189.750192 -225.810318)
		(end 189.91326 -225.64725)
		(width 0.14478)
		(layer "In6.Cu")
		(net "M_K_CPU1_SA_DQ<26>")
	)
	(segment
		(start 192.600326 -225.58502)
		(end 192.763394 -225.421952)
		(width 0.14478)
		(layer "In6.Cu")
		(net "M_K_CPU1_SA_DQ<26>")
	)
	(segment
		(start 167.90924 -225.64725)
		(end 168.072308 -225.810318)
		(width 0.14478)
		(layer "In6.Cu")
		(net "M_K_CPU1_SA_DQ<26>")
	)
	(segment
		(start 157.663388 -232.845102)
		(end 163.848034 -226.660456)
		(width 0.14478)
		(layer "In6.Cu")
		(net "M_K_CPU1_SA_DQ<26>")
	)
	(segment
		(start 193.319908 -226.198684)
		(end 193.550286 -226.198684)
		(width 0.14478)
		(layer "In6.Cu")
		(net "M_K_CPU1_SA_DQ<26>")
	)
	(segment
		(start 193.15684 -226.035616)
		(end 193.319908 -226.198684)
		(width 0.14478)
		(layer "In6.Cu")
		(net "M_K_CPU1_SA_DQ<26>")
	)
	(segment
		(start 193.876422 -225.810318)
		(end 194.17919 -225.810318)
		(width 0.14478)
		(layer "In6.Cu")
		(net "M_K_CPU1_SA_DQ<26>")
	)
	(arc
		(start 142.574772 -240.143538)
		(mid 142.82998 -240.187015)
		(end 143.077692 -240.111788)
		(width 0.0889)
		(layer "In6.Cu")
		(net "M_K_CPU1_SA_DQ<26>")
	)
	(arc
		(start 143.451834 -240.111788)
		(mid 143.728647 -240.187931)
		(end 144.007078 -240.117884)
		(width 0.0889)
		(layer "In6.Cu")
		(net "M_K_CPU1_SA_DQ<26>")
	)
	(arc
		(start 144.017492 -240.111788)
		(mid 144.204436 -240.061533)
		(end 144.39138 -240.111788)
		(width 0.0889)
		(layer "In6.Cu")
		(net "M_K_CPU1_SA_DQ<26>")
	)
	(arc
		(start 144.957546 -240.111788)
		(mid 145.047806 -240.07416)
		(end 145.144744 -240.061242)
		(width 0.0889)
		(layer "In6.Cu")
		(net "M_K_CPU1_SA_DQ<26>")
	)
	(arc
		(start 143.086074 -240.106962)
		(mid 143.269582 -240.061468)
		(end 143.451834 -240.111788)
		(width 0.0889)
		(layer "In6.Cu")
		(net "M_K_CPU1_SA_DQ<26>")
	)
	(arc
		(start 144.401794 -240.117884)
		(mid 144.68048 -240.188104)
		(end 144.957546 -240.111788)
		(width 0.0889)
		(layer "In6.Cu")
		(net "M_K_CPU1_SA_DQ<26>")
	)
	(segment
		(start 140.91793 -240.700306)
		(end 141.384782 -240.434368)
		(width 0.10668)
		(layer "F.Cu")
		(net "M_K_CPU1_SA_DQ<25>")
	)
	(segment
		(start 144.391126 -240.756948)
		(end 144.40154 -240.750852)
		(width 0.0889)
		(layer "In6.Cu")
		(net "M_K_CPU1_SA_DQ<25>")
	)
	(segment
		(start 198.279258 -226.660456)
		(end 198.7042 -227.085398)
		(width 0.14478)
		(layer "In6.Cu")
		(net "M_K_CPU1_SA_DQ<25>")
	)
	(segment
		(start 181.990746 -226.660456)
		(end 184.996074 -226.660456)
		(width 0.14478)
		(layer "In6.Cu")
		(net "M_K_CPU1_SA_DQ<25>")
	)
	(segment
		(start 171.101004 -227.51034)
		(end 172.773594 -227.51034)
		(width 0.14478)
		(layer "In6.Cu")
		(net "M_K_CPU1_SA_DQ<25>")
	)
	(segment
		(start 153.925016 -239.282224)
		(end 158.123128 -235.084112)
		(width 0.14478)
		(layer "In6.Cu")
		(net "M_K_CPU1_SA_DQ<25>")
	)
	(segment
		(start 174.82566 -226.660456)
		(end 177.452274 -226.660456)
		(width 0.14478)
		(layer "In6.Cu")
		(net "M_K_CPU1_SA_DQ<25>")
	)
	(segment
		(start 188.801248 -227.51034)
		(end 189.651132 -226.660456)
		(width 0.14478)
		(layer "In6.Cu")
		(net "M_K_CPU1_SA_DQ<25>")
	)
	(segment
		(start 145.435574 -240.694464)
		(end 145.8214 -240.308638)
		(width 0.0889)
		(layer "In6.Cu")
		(net "M_K_CPU1_SA_DQ<25>")
	)
	(segment
		(start 146.865848 -240.275364)
		(end 147.858988 -239.282224)
		(width 0.0889)
		(layer "In6.Cu")
		(net "M_K_CPU1_SA_DQ<25>")
	)
	(segment
		(start 141.230858 -240.699798)
		(end 141.25321 -240.78311)
		(width 0.0889)
		(layer "In6.Cu")
		(net "M_K_CPU1_SA_DQ<25>")
	)
	(segment
		(start 147.858988 -239.282224)
		(end 153.925016 -239.282224)
		(width 0.14478)
		(layer "In6.Cu")
		(net "M_K_CPU1_SA_DQ<25>")
	)
	(segment
		(start 167.264842 -226.660202)
		(end 169.04843 -226.660202)
		(width 0.14478)
		(layer "In6.Cu")
		(net "M_K_CPU1_SA_DQ<25>")
	)
	(segment
		(start 181.140862 -227.51034)
		(end 181.990746 -226.660456)
		(width 0.14478)
		(layer "In6.Cu")
		(net "M_K_CPU1_SA_DQ<25>")
	)
	(segment
		(start 165.212014 -227.51034)
		(end 167.264842 -226.660202)
		(width 0.14478)
		(layer "In6.Cu")
		(net "M_K_CPU1_SA_DQ<25>")
	)
	(segment
		(start 189.651132 -226.660456)
		(end 198.279258 -226.660456)
		(width 0.14478)
		(layer "In6.Cu")
		(net "M_K_CPU1_SA_DQ<25>")
	)
	(segment
		(start 169.04843 -226.660202)
		(end 170.515788 -227.268024)
		(width 0.14478)
		(layer "In6.Cu")
		(net "M_K_CPU1_SA_DQ<25>")
	)
	(segment
		(start 177.452274 -226.660456)
		(end 178.302158 -227.51034)
		(width 0.14478)
		(layer "In6.Cu")
		(net "M_K_CPU1_SA_DQ<25>")
	)
	(segment
		(start 158.123128 -233.049572)
		(end 163.66236 -227.51034)
		(width 0.14478)
		(layer "In6.Cu")
		(net "M_K_CPU1_SA_DQ<25>")
	)
	(segment
		(start 185.845958 -227.51034)
		(end 188.801248 -227.51034)
		(width 0.14478)
		(layer "In6.Cu")
		(net "M_K_CPU1_SA_DQ<25>")
	)
	(segment
		(start 143.077692 -240.756948)
		(end 143.086074 -240.761774)
		(width 0.0889)
		(layer "In6.Cu")
		(net "M_K_CPU1_SA_DQ<25>")
	)
	(segment
		(start 141.384782 -240.434368)
		(end 141.230858 -240.699798)
		(width 0.0889)
		(layer "In6.Cu")
		(net "M_K_CPU1_SA_DQ<25>")
	)
	(segment
		(start 145.901664 -240.275364)
		(end 146.865848 -240.275364)
		(width 0.0889)
		(layer "In6.Cu")
		(net "M_K_CPU1_SA_DQ<25>")
	)
	(segment
		(start 178.302158 -227.51034)
		(end 181.140862 -227.51034)
		(width 0.14478)
		(layer "In6.Cu")
		(net "M_K_CPU1_SA_DQ<25>")
	)
	(segment
		(start 172.773594 -227.51034)
		(end 174.200058 -226.919536)
		(width 0.14478)
		(layer "In6.Cu")
		(net "M_K_CPU1_SA_DQ<25>")
	)
	(segment
		(start 184.996074 -226.660456)
		(end 185.845958 -227.51034)
		(width 0.14478)
		(layer "In6.Cu")
		(net "M_K_CPU1_SA_DQ<25>")
	)
	(segment
		(start 163.66236 -227.51034)
		(end 165.212014 -227.51034)
		(width 0.14478)
		(layer "In6.Cu")
		(net "M_K_CPU1_SA_DQ<25>")
	)
	(segment
		(start 144.017492 -240.756948)
		(end 144.025874 -240.761774)
		(width 0.0889)
		(layer "In6.Cu")
		(net "M_K_CPU1_SA_DQ<25>")
	)
	(segment
		(start 174.200058 -226.919536)
		(end 174.82566 -226.660456)
		(width 0.14478)
		(layer "In6.Cu")
		(net "M_K_CPU1_SA_DQ<25>")
	)
	(segment
		(start 144.007078 -240.750852)
		(end 144.017492 -240.756948)
		(width 0.0889)
		(layer "In6.Cu")
		(net "M_K_CPU1_SA_DQ<25>")
	)
	(segment
		(start 158.123128 -235.084112)
		(end 158.123128 -233.049572)
		(width 0.14478)
		(layer "In6.Cu")
		(net "M_K_CPU1_SA_DQ<25>")
	)
	(segment
		(start 170.515788 -227.268024)
		(end 171.101004 -227.51034)
		(width 0.14478)
		(layer "In6.Cu")
		(net "M_K_CPU1_SA_DQ<25>")
	)
	(segment
		(start 142.503398 -240.761774)
		(end 142.51178 -240.756948)
		(width 0.0889)
		(layer "In6.Cu")
		(net "M_K_CPU1_SA_DQ<25>")
	)
	(arc
		(start 144.957292 -240.756948)
		(mid 145.207086 -240.807135)
		(end 145.435574 -240.694464)
		(width 0.0889)
		(layer "In6.Cu")
		(net "M_K_CPU1_SA_DQ<25>")
	)
	(arc
		(start 144.025874 -240.761774)
		(mid 144.209128 -240.807147)
		(end 144.391126 -240.756948)
		(width 0.0889)
		(layer "In6.Cu")
		(net "M_K_CPU1_SA_DQ<25>")
	)
	(arc
		(start 143.451834 -240.756948)
		(mid 143.728647 -240.680805)
		(end 144.007078 -240.750852)
		(width 0.0889)
		(layer "In6.Cu")
		(net "M_K_CPU1_SA_DQ<25>")
	)
	(arc
		(start 144.40154 -240.750852)
		(mid 144.680226 -240.680632)
		(end 144.957292 -240.756948)
		(width 0.0889)
		(layer "In6.Cu")
		(net "M_K_CPU1_SA_DQ<25>")
	)
	(arc
		(start 141.571726 -240.756948)
		(mid 141.854682 -240.680771)
		(end 142.137638 -240.756948)
		(width 0.0889)
		(layer "In6.Cu")
		(net "M_K_CPU1_SA_DQ<25>")
	)
	(arc
		(start 143.086074 -240.761774)
		(mid 143.269582 -240.807268)
		(end 143.451834 -240.756948)
		(width 0.0889)
		(layer "In6.Cu")
		(net "M_K_CPU1_SA_DQ<25>")
	)
	(arc
		(start 145.8214 -240.308638)
		(mid 145.858211 -240.283978)
		(end 145.901664 -240.275364)
		(width 0.0889)
		(layer "In6.Cu")
		(net "M_K_CPU1_SA_DQ<25>")
	)
	(arc
		(start 141.25321 -240.78311)
		(mid 141.415399 -240.805845)
		(end 141.571726 -240.756948)
		(width 0.0889)
		(layer "In6.Cu")
		(net "M_K_CPU1_SA_DQ<25>")
	)
	(arc
		(start 142.51178 -240.756948)
		(mid 142.794736 -240.680771)
		(end 143.077692 -240.756948)
		(width 0.0889)
		(layer "In6.Cu")
		(net "M_K_CPU1_SA_DQ<25>")
	)
	(arc
		(start 142.137638 -240.756948)
		(mid 142.319889 -240.807298)
		(end 142.503398 -240.761774)
		(width 0.0889)
		(layer "In6.Cu")
		(net "M_K_CPU1_SA_DQ<25>")
	)
	(segment
		(start 142.327884 -239.8903)
		(end 142.794736 -239.624362)
		(width 0.10668)
		(layer "F.Cu")
		(net "M_K_CPU1_SA_DQ<24>")
	)
	(segment
		(start 145.144744 -239.870742)
		(end 145.796 -239.870742)
		(width 0.0889)
		(layer "In6.Cu")
		(net "M_K_CPU1_SA_DQ<24>")
	)
	(segment
		(start 147.912328 -238.367824)
		(end 153.546048 -238.367824)
		(width 0.14478)
		(layer "In6.Cu")
		(net "M_K_CPU1_SA_DQ<24>")
	)
	(segment
		(start 181.990746 -224.960434)
		(end 184.996074 -224.960434)
		(width 0.14478)
		(layer "In6.Cu")
		(net "M_K_CPU1_SA_DQ<24>")
	)
	(segment
		(start 169.907966 -224.96018)
		(end 170.758104 -225.810318)
		(width 0.14478)
		(layer "In6.Cu")
		(net "M_K_CPU1_SA_DQ<24>")
	)
	(segment
		(start 198.279258 -224.960434)
		(end 198.7042 -225.385376)
		(width 0.14478)
		(layer "In6.Cu")
		(net "M_K_CPU1_SA_DQ<24>")
	)
	(segment
		(start 146.680428 -239.259364)
		(end 147.571968 -238.367824)
		(width 0.0889)
		(layer "In6.Cu")
		(net "M_K_CPU1_SA_DQ<24>")
	)
	(segment
		(start 147.571968 -238.367824)
		(end 147.912328 -238.367824)
		(width 0.0889)
		(layer "In6.Cu")
		(net "M_K_CPU1_SA_DQ<24>")
	)
	(segment
		(start 170.758104 -225.810318)
		(end 173.609254 -225.810318)
		(width 0.14478)
		(layer "In6.Cu")
		(net "M_K_CPU1_SA_DQ<24>")
	)
	(segment
		(start 153.546048 -238.367824)
		(end 157.208728 -234.705144)
		(width 0.14478)
		(layer "In6.Cu")
		(net "M_K_CPU1_SA_DQ<24>")
	)
	(segment
		(start 188.801248 -225.810318)
		(end 189.651132 -224.960434)
		(width 0.14478)
		(layer "In6.Cu")
		(net "M_K_CPU1_SA_DQ<24>")
	)
	(segment
		(start 189.651132 -224.960434)
		(end 198.279258 -224.960434)
		(width 0.14478)
		(layer "In6.Cu")
		(net "M_K_CPU1_SA_DQ<24>")
	)
	(segment
		(start 166.106348 -225.810318)
		(end 166.956486 -224.96018)
		(width 0.14478)
		(layer "In6.Cu")
		(net "M_K_CPU1_SA_DQ<24>")
	)
	(segment
		(start 173.609254 -225.810318)
		(end 174.459138 -224.960434)
		(width 0.14478)
		(layer "In6.Cu")
		(net "M_K_CPU1_SA_DQ<24>")
	)
	(segment
		(start 166.956486 -224.96018)
		(end 169.907966 -224.96018)
		(width 0.14478)
		(layer "In6.Cu")
		(net "M_K_CPU1_SA_DQ<24>")
	)
	(segment
		(start 157.208728 -232.644442)
		(end 164.042852 -225.810318)
		(width 0.14478)
		(layer "In6.Cu")
		(net "M_K_CPU1_SA_DQ<24>")
	)
	(segment
		(start 146.407378 -239.259364)
		(end 146.680428 -239.259364)
		(width 0.0889)
		(layer "In6.Cu")
		(net "M_K_CPU1_SA_DQ<24>")
	)
	(segment
		(start 177.452274 -224.960434)
		(end 178.302158 -225.810318)
		(width 0.14478)
		(layer "In6.Cu")
		(net "M_K_CPU1_SA_DQ<24>")
	)
	(segment
		(start 178.302158 -225.810318)
		(end 181.140862 -225.810318)
		(width 0.14478)
		(layer "In6.Cu")
		(net "M_K_CPU1_SA_DQ<24>")
	)
	(segment
		(start 157.208728 -234.705144)
		(end 157.208728 -232.644442)
		(width 0.14478)
		(layer "In6.Cu")
		(net "M_K_CPU1_SA_DQ<24>")
	)
	(segment
		(start 174.459138 -224.960434)
		(end 177.452274 -224.960434)
		(width 0.14478)
		(layer "In6.Cu")
		(net "M_K_CPU1_SA_DQ<24>")
	)
	(segment
		(start 185.845958 -225.810318)
		(end 188.801248 -225.810318)
		(width 0.14478)
		(layer "In6.Cu")
		(net "M_K_CPU1_SA_DQ<24>")
	)
	(segment
		(start 142.640812 -239.889792)
		(end 142.663164 -239.973104)
		(width 0.0889)
		(layer "In6.Cu")
		(net "M_K_CPU1_SA_DQ<24>")
	)
	(segment
		(start 142.794736 -239.624362)
		(end 142.640812 -239.889792)
		(width 0.0889)
		(layer "In6.Cu")
		(net "M_K_CPU1_SA_DQ<24>")
	)
	(segment
		(start 144.487392 -239.946942)
		(end 144.495774 -239.951768)
		(width 0.0889)
		(layer "In6.Cu")
		(net "M_K_CPU1_SA_DQ<24>")
	)
	(segment
		(start 143.921734 -239.946942)
		(end 143.932148 -239.940846)
		(width 0.0889)
		(layer "In6.Cu")
		(net "M_K_CPU1_SA_DQ<24>")
	)
	(segment
		(start 181.140862 -225.810318)
		(end 181.990746 -224.960434)
		(width 0.14478)
		(layer "In6.Cu")
		(net "M_K_CPU1_SA_DQ<24>")
	)
	(segment
		(start 164.042852 -225.810318)
		(end 166.106348 -225.810318)
		(width 0.14478)
		(layer "In6.Cu")
		(net "M_K_CPU1_SA_DQ<24>")
	)
	(segment
		(start 143.913352 -239.951768)
		(end 143.921734 -239.946942)
		(width 0.0889)
		(layer "In6.Cu")
		(net "M_K_CPU1_SA_DQ<24>")
	)
	(segment
		(start 145.796 -239.870742)
		(end 146.407378 -239.259364)
		(width 0.0889)
		(layer "In6.Cu")
		(net "M_K_CPU1_SA_DQ<24>")
	)
	(segment
		(start 184.996074 -224.960434)
		(end 185.845958 -225.810318)
		(width 0.14478)
		(layer "In6.Cu")
		(net "M_K_CPU1_SA_DQ<24>")
	)
	(arc
		(start 144.495774 -239.951768)
		(mid 144.679282 -239.997262)
		(end 144.861534 -239.946942)
		(width 0.0889)
		(layer "In6.Cu")
		(net "M_K_CPU1_SA_DQ<24>")
	)
	(arc
		(start 143.547592 -239.946942)
		(mid 143.729843 -239.997292)
		(end 143.913352 -239.951768)
		(width 0.0889)
		(layer "In6.Cu")
		(net "M_K_CPU1_SA_DQ<24>")
	)
	(arc
		(start 142.98168 -239.946942)
		(mid 143.264636 -239.870765)
		(end 143.547592 -239.946942)
		(width 0.0889)
		(layer "In6.Cu")
		(net "M_K_CPU1_SA_DQ<24>")
	)
	(arc
		(start 143.932148 -239.940846)
		(mid 144.21058 -239.870748)
		(end 144.487392 -239.946942)
		(width 0.0889)
		(layer "In6.Cu")
		(net "M_K_CPU1_SA_DQ<24>")
	)
	(arc
		(start 144.861534 -239.946942)
		(mid 144.998097 -239.890109)
		(end 145.144744 -239.870742)
		(width 0.0889)
		(layer "In6.Cu")
		(net "M_K_CPU1_SA_DQ<24>")
	)
	(arc
		(start 142.663164 -239.973104)
		(mid 142.825353 -239.995839)
		(end 142.98168 -239.946942)
		(width 0.0889)
		(layer "In6.Cu")
		(net "M_K_CPU1_SA_DQ<24>")
	)
	(segment
		(start 140.447776 -239.8903)
		(end 140.914882 -239.624362)
		(width 0.10668)
		(layer "F.Cu")
		(net "M_K_CPU1_SA_DQ<23>")
	)
	(segment
		(start 185.845958 -224.960434)
		(end 187.445142 -224.960434)
		(width 0.14478)
		(layer "In6.Cu")
		(net "M_K_CPU1_SA_DQ<23>")
	)
	(segment
		(start 190.171832 -223.724724)
		(end 190.40221 -223.724724)
		(width 0.14478)
		(layer "In6.Cu")
		(net "M_K_CPU1_SA_DQ<23>")
	)
	(segment
		(start 192.354962 -223.882712)
		(end 192.354962 -224.046796)
		(width 0.14478)
		(layer "In6.Cu")
		(net "M_K_CPU1_SA_DQ<23>")
	)
	(segment
		(start 190.008764 -223.887792)
		(end 190.171832 -223.724724)
		(width 0.14478)
		(layer "In6.Cu")
		(net "M_K_CPU1_SA_DQ<23>")
	)
	(segment
		(start 193.304922 -223.719644)
		(end 193.46799 -223.882712)
		(width 0.14478)
		(layer "In6.Cu")
		(net "M_K_CPU1_SA_DQ<23>")
	)
	(segment
		(start 167.411908 -224.110296)
		(end 167.574976 -223.947228)
		(width 0.14478)
		(layer "In6.Cu")
		(net "M_K_CPU1_SA_DQ<23>")
	)
	(segment
		(start 188.673232 -224.960434)
		(end 189.52337 -224.110296)
		(width 0.14478)
		(layer "In6.Cu")
		(net "M_K_CPU1_SA_DQ<23>")
	)
	(segment
		(start 173.245272 -224.960434)
		(end 173.609254 -224.960434)
		(width 0.14478)
		(layer "In6.Cu")
		(net "M_K_CPU1_SA_DQ<23>")
	)
	(segment
		(start 169.244518 -223.947228)
		(end 169.407586 -224.110296)
		(width 0.14478)
		(layer "In6.Cu")
		(net "M_K_CPU1_SA_DQ<23>")
	)
	(segment
		(start 189.845696 -224.110296)
		(end 190.008764 -223.947228)
		(width 0.14478)
		(layer "In6.Cu")
		(net "M_K_CPU1_SA_DQ<23>")
	)
	(segment
		(start 156.624528 -232.311448)
		(end 163.975542 -224.960434)
		(width 0.14478)
		(layer "In6.Cu")
		(net "M_K_CPU1_SA_DQ<23>")
	)
	(segment
		(start 175.47082 -223.947228)
		(end 175.633888 -224.110296)
		(width 0.14478)
		(layer "In6.Cu")
		(net "M_K_CPU1_SA_DQ<23>")
	)
	(segment
		(start 180.055266 -224.797366)
		(end 180.055266 -224.731072)
		(width 0.14478)
		(layer "In6.Cu")
		(net "M_K_CPU1_SA_DQ<23>")
	)
	(segment
		(start 173.082204 -224.797366)
		(end 173.245272 -224.960434)
		(width 0.14478)
		(layer "In6.Cu")
		(net "M_K_CPU1_SA_DQ<23>")
	)
	(segment
		(start 141.068806 -239.358932)
		(end 141.164818 -239.333532)
		(width 0.0889)
		(layer "In6.Cu")
		(net "M_K_CPU1_SA_DQ<23>")
	)
	(segment
		(start 190.565278 -223.887792)
		(end 190.565278 -223.947228)
		(width 0.14478)
		(layer "In6.Cu")
		(net "M_K_CPU1_SA_DQ<23>")
	)
	(segment
		(start 147.747228 -237.811564)
		(end 147.952206 -237.811564)
		(width 0.0889)
		(layer "In6.Cu")
		(net "M_K_CPU1_SA_DQ<23>")
	)
	(segment
		(start 165.270434 -224.588324)
		(end 165.433502 -224.751392)
		(width 0.14478)
		(layer "In6.Cu")
		(net "M_K_CPU1_SA_DQ<23>")
	)
	(segment
		(start 165.433502 -224.751392)
		(end 165.433502 -224.797366)
		(width 0.14478)
		(layer "In6.Cu")
		(net "M_K_CPU1_SA_DQ<23>")
	)
	(segment
		(start 166.916862 -224.110296)
		(end 167.411908 -224.110296)
		(width 0.14478)
		(layer "In6.Cu")
		(net "M_K_CPU1_SA_DQ<23>")
	)
	(segment
		(start 182.376064 -224.110296)
		(end 182.539132 -223.947228)
		(width 0.14478)
		(layer "In6.Cu")
		(net "M_K_CPU1_SA_DQ<23>")
	)
	(segment
		(start 182.932578 -223.732344)
		(end 183.095646 -223.895412)
		(width 0.14478)
		(layer "In6.Cu")
		(net "M_K_CPU1_SA_DQ<23>")
	)
	(segment
		(start 172.52569 -224.731072)
		(end 172.688758 -224.568004)
		(width 0.14478)
		(layer "In6.Cu")
		(net "M_K_CPU1_SA_DQ<23>")
	)
	(segment
		(start 168.688004 -223.947228)
		(end 168.688004 -223.890332)
		(width 0.14478)
		(layer "In6.Cu")
		(net "M_K_CPU1_SA_DQ<23>")
	)
	(segment
		(start 146.553428 -239.005364)
		(end 147.747228 -237.811564)
		(width 0.0889)
		(layer "In6.Cu")
		(net "M_K_CPU1_SA_DQ<23>")
	)
	(segment
		(start 181.140862 -224.960434)
		(end 181.991 -224.110296)
		(width 0.14478)
		(layer "In6.Cu")
		(net "M_K_CPU1_SA_DQ<23>")
	)
	(segment
		(start 167.574976 -223.890332)
		(end 167.738044 -223.727264)
		(width 0.14478)
		(layer "In6.Cu")
		(net "M_K_CPU1_SA_DQ<23>")
	)
	(segment
		(start 187.60821 -224.797366)
		(end 187.60821 -224.738692)
		(width 0.14478)
		(layer "In6.Cu")
		(net "M_K_CPU1_SA_DQ<23>")
	)
	(segment
		(start 180.218334 -224.568004)
		(end 180.448712 -224.568004)
		(width 0.14478)
		(layer "In6.Cu")
		(net "M_K_CPU1_SA_DQ<23>")
	)
	(segment
		(start 156.624528 -234.495848)
		(end 156.624528 -232.311448)
		(width 0.14478)
		(layer "In6.Cu")
		(net "M_K_CPU1_SA_DQ<23>")
	)
	(segment
		(start 173.609254 -224.960434)
		(end 174.459392 -224.110296)
		(width 0.14478)
		(layer "In6.Cu")
		(net "M_K_CPU1_SA_DQ<23>")
	)
	(segment
		(start 191.798448 -223.882712)
		(end 191.961516 -223.719644)
		(width 0.14478)
		(layer "In6.Cu")
		(net "M_K_CPU1_SA_DQ<23>")
	)
	(segment
		(start 182.539132 -223.895412)
		(end 182.7022 -223.732344)
		(width 0.14478)
		(layer "In6.Cu")
		(net "M_K_CPU1_SA_DQ<23>")
	)
	(segment
		(start 172.362622 -224.960434)
		(end 172.52569 -224.797366)
		(width 0.14478)
		(layer "In6.Cu")
		(net "M_K_CPU1_SA_DQ<23>")
	)
	(segment
		(start 172.52569 -224.797366)
		(end 172.52569 -224.731072)
		(width 0.14478)
		(layer "In6.Cu")
		(net "M_K_CPU1_SA_DQ<23>")
	)
	(segment
		(start 183.095646 -223.895412)
		(end 183.095646 -223.947228)
		(width 0.14478)
		(layer "In6.Cu")
		(net "M_K_CPU1_SA_DQ<23>")
	)
	(segment
		(start 180.61178 -224.797366)
		(end 180.774848 -224.960434)
		(width 0.14478)
		(layer "In6.Cu")
		(net "M_K_CPU1_SA_DQ<23>")
	)
	(segment
		(start 147.952206 -237.811564)
		(end 153.308812 -237.811564)
		(width 0.14478)
		(layer "In6.Cu")
		(net "M_K_CPU1_SA_DQ<23>")
	)
	(segment
		(start 187.60821 -224.738692)
		(end 187.771278 -224.575624)
		(width 0.14478)
		(layer "In6.Cu")
		(net "M_K_CPU1_SA_DQ<23>")
	)
	(segment
		(start 174.914306 -223.947228)
		(end 174.914306 -223.890332)
		(width 0.14478)
		(layer "In6.Cu")
		(net "M_K_CPU1_SA_DQ<23>")
	)
	(segment
		(start 180.055266 -224.731072)
		(end 180.218334 -224.568004)
		(width 0.14478)
		(layer "In6.Cu")
		(net "M_K_CPU1_SA_DQ<23>")
	)
	(segment
		(start 177.45202 -224.110296)
		(end 178.302158 -224.960434)
		(width 0.14478)
		(layer "In6.Cu")
		(net "M_K_CPU1_SA_DQ<23>")
	)
	(segment
		(start 193.631058 -224.110296)
		(end 194.17919 -224.110296)
		(width 0.14478)
		(layer "In6.Cu")
		(net "M_K_CPU1_SA_DQ<23>")
	)
	(segment
		(start 169.244518 -223.890332)
		(end 169.244518 -223.947228)
		(width 0.14478)
		(layer "In6.Cu")
		(net "M_K_CPU1_SA_DQ<23>")
	)
	(segment
		(start 188.164724 -224.797366)
		(end 188.327792 -224.960434)
		(width 0.14478)
		(layer "In6.Cu")
		(net "M_K_CPU1_SA_DQ<23>")
	)
	(segment
		(start 168.851072 -223.727264)
		(end 169.08145 -223.727264)
		(width 0.14478)
		(layer "In6.Cu")
		(net "M_K_CPU1_SA_DQ<23>")
	)
	(segment
		(start 167.574976 -223.947228)
		(end 167.574976 -223.890332)
		(width 0.14478)
		(layer "In6.Cu")
		(net "M_K_CPU1_SA_DQ<23>")
	)
	(segment
		(start 169.407586 -224.110296)
		(end 169.907966 -224.110296)
		(width 0.14478)
		(layer "In6.Cu")
		(net "M_K_CPU1_SA_DQ<23>")
	)
	(segment
		(start 191.961516 -223.719644)
		(end 192.191894 -223.719644)
		(width 0.14478)
		(layer "In6.Cu")
		(net "M_K_CPU1_SA_DQ<23>")
	)
	(segment
		(start 193.074544 -223.719644)
		(end 193.304922 -223.719644)
		(width 0.14478)
		(layer "In6.Cu")
		(net "M_K_CPU1_SA_DQ<23>")
	)
	(segment
		(start 143.909796 -239.294924)
		(end 143.92148 -239.301782)
		(width 0.0889)
		(layer "In6.Cu")
		(net "M_K_CPU1_SA_DQ<23>")
	)
	(segment
		(start 165.433502 -224.797366)
		(end 165.59657 -224.960434)
		(width 0.14478)
		(layer "In6.Cu")
		(net "M_K_CPU1_SA_DQ<23>")
	)
	(segment
		(start 144.487138 -239.301782)
		(end 144.498822 -239.294924)
		(width 0.0889)
		(layer "In6.Cu")
		(net "M_K_CPU1_SA_DQ<23>")
	)
	(segment
		(start 172.919136 -224.568004)
		(end 173.082204 -224.731072)
		(width 0.14478)
		(layer "In6.Cu")
		(net "M_K_CPU1_SA_DQ<23>")
	)
	(segment
		(start 187.445142 -224.960434)
		(end 187.60821 -224.797366)
		(width 0.14478)
		(layer "In6.Cu")
		(net "M_K_CPU1_SA_DQ<23>")
	)
	(segment
		(start 145.971006 -239.262666)
		(end 146.228308 -239.005364)
		(width 0.0889)
		(layer "In6.Cu")
		(net "M_K_CPU1_SA_DQ<23>")
	)
	(segment
		(start 188.327792 -224.960434)
		(end 188.673232 -224.960434)
		(width 0.14478)
		(layer "In6.Cu")
		(net "M_K_CPU1_SA_DQ<23>")
	)
	(segment
		(start 190.565278 -223.947228)
		(end 190.728346 -224.110296)
		(width 0.14478)
		(layer "In6.Cu")
		(net "M_K_CPU1_SA_DQ<23>")
	)
	(segment
		(start 140.914882 -239.624362)
		(end 141.068806 -239.358932)
		(width 0.0889)
		(layer "In6.Cu")
		(net "M_K_CPU1_SA_DQ<23>")
	)
	(segment
		(start 183.258714 -224.110296)
		(end 184.99582 -224.110296)
		(width 0.14478)
		(layer "In6.Cu")
		(net "M_K_CPU1_SA_DQ<23>")
	)
	(segment
		(start 167.738044 -223.727264)
		(end 167.968422 -223.727264)
		(width 0.14478)
		(layer "In6.Cu")
		(net "M_K_CPU1_SA_DQ<23>")
	)
	(segment
		(start 191.798448 -223.947228)
		(end 191.798448 -223.882712)
		(width 0.14478)
		(layer "In6.Cu")
		(net "M_K_CPU1_SA_DQ<23>")
	)
	(segment
		(start 143.92148 -239.301782)
		(end 143.931894 -239.307878)
		(width 0.0889)
		(layer "In6.Cu")
		(net "M_K_CPU1_SA_DQ<23>")
	)
	(segment
		(start 191.63538 -224.110296)
		(end 191.798448 -223.947228)
		(width 0.14478)
		(layer "In6.Cu")
		(net "M_K_CPU1_SA_DQ<23>")
	)
	(segment
		(start 175.307752 -223.727264)
		(end 175.47082 -223.890332)
		(width 0.14478)
		(layer "In6.Cu")
		(net "M_K_CPU1_SA_DQ<23>")
	)
	(segment
		(start 168.524936 -224.110296)
		(end 168.688004 -223.947228)
		(width 0.14478)
		(layer "In6.Cu")
		(net "M_K_CPU1_SA_DQ<23>")
	)
	(segment
		(start 146.228308 -239.005364)
		(end 146.553428 -239.005364)
		(width 0.0889)
		(layer "In6.Cu")
		(net "M_K_CPU1_SA_DQ<23>")
	)
	(segment
		(start 188.164724 -224.738692)
		(end 188.164724 -224.797366)
		(width 0.14478)
		(layer "In6.Cu")
		(net "M_K_CPU1_SA_DQ<23>")
	)
	(segment
		(start 187.771278 -224.575624)
		(end 188.001656 -224.575624)
		(width 0.14478)
		(layer "In6.Cu")
		(net "M_K_CPU1_SA_DQ<23>")
	)
	(segment
		(start 174.459392 -224.110296)
		(end 174.751238 -224.110296)
		(width 0.14478)
		(layer "In6.Cu")
		(net "M_K_CPU1_SA_DQ<23>")
	)
	(segment
		(start 194.17919 -224.110296)
		(end 194.604132 -224.535238)
		(width 0.14478)
		(layer "In6.Cu")
		(net "M_K_CPU1_SA_DQ<23>")
	)
	(segment
		(start 182.539132 -223.947228)
		(end 182.539132 -223.895412)
		(width 0.14478)
		(layer "In6.Cu")
		(net "M_K_CPU1_SA_DQ<23>")
	)
	(segment
		(start 178.302158 -224.960434)
		(end 179.892198 -224.960434)
		(width 0.14478)
		(layer "In6.Cu")
		(net "M_K_CPU1_SA_DQ<23>")
	)
	(segment
		(start 192.191894 -223.719644)
		(end 192.354962 -223.882712)
		(width 0.14478)
		(layer "In6.Cu")
		(net "M_K_CPU1_SA_DQ<23>")
	)
	(segment
		(start 174.914306 -223.890332)
		(end 175.077374 -223.727264)
		(width 0.14478)
		(layer "In6.Cu")
		(net "M_K_CPU1_SA_DQ<23>")
	)
	(segment
		(start 164.71392 -224.960434)
		(end 164.876988 -224.797366)
		(width 0.14478)
		(layer "In6.Cu")
		(net "M_K_CPU1_SA_DQ<23>")
	)
	(segment
		(start 190.728346 -224.110296)
		(end 191.63538 -224.110296)
		(width 0.14478)
		(layer "In6.Cu")
		(net "M_K_CPU1_SA_DQ<23>")
	)
	(segment
		(start 168.294558 -224.110296)
		(end 168.524936 -224.110296)
		(width 0.14478)
		(layer "In6.Cu")
		(net "M_K_CPU1_SA_DQ<23>")
	)
	(segment
		(start 181.991 -224.110296)
		(end 182.376064 -224.110296)
		(width 0.14478)
		(layer "In6.Cu")
		(net "M_K_CPU1_SA_DQ<23>")
	)
	(segment
		(start 179.892198 -224.960434)
		(end 180.055266 -224.797366)
		(width 0.14478)
		(layer "In6.Cu")
		(net "M_K_CPU1_SA_DQ<23>")
	)
	(segment
		(start 180.774848 -224.960434)
		(end 181.140862 -224.960434)
		(width 0.14478)
		(layer "In6.Cu")
		(net "M_K_CPU1_SA_DQ<23>")
	)
	(segment
		(start 192.911476 -224.046796)
		(end 192.911476 -223.882712)
		(width 0.14478)
		(layer "In6.Cu")
		(net "M_K_CPU1_SA_DQ<23>")
	)
	(segment
		(start 192.354962 -224.046796)
		(end 192.51803 -224.209864)
		(width 0.14478)
		(layer "In6.Cu")
		(net "M_K_CPU1_SA_DQ<23>")
	)
	(segment
		(start 193.46799 -223.882712)
		(end 193.46799 -223.947228)
		(width 0.14478)
		(layer "In6.Cu")
		(net "M_K_CPU1_SA_DQ<23>")
	)
	(segment
		(start 164.876988 -224.751392)
		(end 165.040056 -224.588324)
		(width 0.14478)
		(layer "In6.Cu")
		(net "M_K_CPU1_SA_DQ<23>")
	)
	(segment
		(start 169.907966 -224.110296)
		(end 170.758104 -224.960434)
		(width 0.14478)
		(layer "In6.Cu")
		(net "M_K_CPU1_SA_DQ<23>")
	)
	(segment
		(start 163.975542 -224.960434)
		(end 164.71392 -224.960434)
		(width 0.14478)
		(layer "In6.Cu")
		(net "M_K_CPU1_SA_DQ<23>")
	)
	(segment
		(start 188.001656 -224.575624)
		(end 188.164724 -224.738692)
		(width 0.14478)
		(layer "In6.Cu")
		(net "M_K_CPU1_SA_DQ<23>")
	)
	(segment
		(start 192.748408 -224.209864)
		(end 192.911476 -224.046796)
		(width 0.14478)
		(layer "In6.Cu")
		(net "M_K_CPU1_SA_DQ<23>")
	)
	(segment
		(start 167.968422 -223.727264)
		(end 168.13149 -223.890332)
		(width 0.14478)
		(layer "In6.Cu")
		(net "M_K_CPU1_SA_DQ<23>")
	)
	(segment
		(start 180.448712 -224.568004)
		(end 180.61178 -224.731072)
		(width 0.14478)
		(layer "In6.Cu")
		(net "M_K_CPU1_SA_DQ<23>")
	)
	(segment
		(start 182.7022 -223.732344)
		(end 182.932578 -223.732344)
		(width 0.14478)
		(layer "In6.Cu")
		(net "M_K_CPU1_SA_DQ<23>")
	)
	(segment
		(start 173.082204 -224.731072)
		(end 173.082204 -224.797366)
		(width 0.14478)
		(layer "In6.Cu")
		(net "M_K_CPU1_SA_DQ<23>")
	)
	(segment
		(start 141.667738 -239.301782)
		(end 141.67612 -239.296956)
		(width 0.0889)
		(layer "In6.Cu")
		(net "M_K_CPU1_SA_DQ<23>")
	)
	(segment
		(start 175.077374 -223.727264)
		(end 175.307752 -223.727264)
		(width 0.14478)
		(layer "In6.Cu")
		(net "M_K_CPU1_SA_DQ<23>")
	)
	(segment
		(start 165.59657 -224.960434)
		(end 166.066724 -224.960434)
		(width 0.14478)
		(layer "In6.Cu")
		(net "M_K_CPU1_SA_DQ<23>")
	)
	(segment
		(start 168.688004 -223.890332)
		(end 168.851072 -223.727264)
		(width 0.14478)
		(layer "In6.Cu")
		(net "M_K_CPU1_SA_DQ<23>")
	)
	(segment
		(start 165.040056 -224.588324)
		(end 165.270434 -224.588324)
		(width 0.14478)
		(layer "In6.Cu")
		(net "M_K_CPU1_SA_DQ<23>")
	)
	(segment
		(start 166.066724 -224.960434)
		(end 166.916862 -224.110296)
		(width 0.14478)
		(layer "In6.Cu")
		(net "M_K_CPU1_SA_DQ<23>")
	)
	(segment
		(start 170.758104 -224.960434)
		(end 172.362622 -224.960434)
		(width 0.14478)
		(layer "In6.Cu")
		(net "M_K_CPU1_SA_DQ<23>")
	)
	(segment
		(start 168.13149 -223.947228)
		(end 168.294558 -224.110296)
		(width 0.14478)
		(layer "In6.Cu")
		(net "M_K_CPU1_SA_DQ<23>")
	)
	(segment
		(start 145.594324 -239.262666)
		(end 145.971006 -239.262666)
		(width 0.0889)
		(layer "In6.Cu")
		(net "M_K_CPU1_SA_DQ<23>")
	)
	(segment
		(start 192.911476 -223.882712)
		(end 193.074544 -223.719644)
		(width 0.14478)
		(layer "In6.Cu")
		(net "M_K_CPU1_SA_DQ<23>")
	)
	(segment
		(start 183.095646 -223.947228)
		(end 183.258714 -224.110296)
		(width 0.14478)
		(layer "In6.Cu")
		(net "M_K_CPU1_SA_DQ<23>")
	)
	(segment
		(start 168.13149 -223.890332)
		(end 168.13149 -223.947228)
		(width 0.14478)
		(layer "In6.Cu")
		(net "M_K_CPU1_SA_DQ<23>")
	)
	(segment
		(start 175.47082 -223.890332)
		(end 175.47082 -223.947228)
		(width 0.14478)
		(layer "In6.Cu")
		(net "M_K_CPU1_SA_DQ<23>")
	)
	(segment
		(start 180.61178 -224.731072)
		(end 180.61178 -224.797366)
		(width 0.14478)
		(layer "In6.Cu")
		(net "M_K_CPU1_SA_DQ<23>")
	)
	(segment
		(start 192.51803 -224.209864)
		(end 192.748408 -224.209864)
		(width 0.14478)
		(layer "In6.Cu")
		(net "M_K_CPU1_SA_DQ<23>")
	)
	(segment
		(start 189.52337 -224.110296)
		(end 189.845696 -224.110296)
		(width 0.14478)
		(layer "In6.Cu")
		(net "M_K_CPU1_SA_DQ<23>")
	)
	(segment
		(start 193.46799 -223.947228)
		(end 193.631058 -224.110296)
		(width 0.14478)
		(layer "In6.Cu")
		(net "M_K_CPU1_SA_DQ<23>")
	)
	(segment
		(start 164.876988 -224.797366)
		(end 164.876988 -224.751392)
		(width 0.14478)
		(layer "In6.Cu")
		(net "M_K_CPU1_SA_DQ<23>")
	)
	(segment
		(start 169.08145 -223.727264)
		(end 169.244518 -223.890332)
		(width 0.14478)
		(layer "In6.Cu")
		(net "M_K_CPU1_SA_DQ<23>")
	)
	(segment
		(start 175.633888 -224.110296)
		(end 177.45202 -224.110296)
		(width 0.14478)
		(layer "In6.Cu")
		(net "M_K_CPU1_SA_DQ<23>")
	)
	(segment
		(start 174.751238 -224.110296)
		(end 174.914306 -223.947228)
		(width 0.14478)
		(layer "In6.Cu")
		(net "M_K_CPU1_SA_DQ<23>")
	)
	(segment
		(start 190.008764 -223.947228)
		(end 190.008764 -223.887792)
		(width 0.14478)
		(layer "In6.Cu")
		(net "M_K_CPU1_SA_DQ<23>")
	)
	(segment
		(start 153.308812 -237.811564)
		(end 156.624528 -234.495848)
		(width 0.14478)
		(layer "In6.Cu")
		(net "M_K_CPU1_SA_DQ<23>")
	)
	(segment
		(start 172.688758 -224.568004)
		(end 172.919136 -224.568004)
		(width 0.14478)
		(layer "In6.Cu")
		(net "M_K_CPU1_SA_DQ<23>")
	)
	(segment
		(start 190.40221 -223.724724)
		(end 190.565278 -223.887792)
		(width 0.14478)
		(layer "In6.Cu")
		(net "M_K_CPU1_SA_DQ<23>")
	)
	(segment
		(start 184.99582 -224.110296)
		(end 185.845958 -224.960434)
		(width 0.14478)
		(layer "In6.Cu")
		(net "M_K_CPU1_SA_DQ<23>")
	)
	(arc
		(start 145.415254 -239.308894)
		(mid 145.501878 -239.274488)
		(end 145.594324 -239.262666)
		(width 0.0889)
		(layer "In6.Cu")
		(net "M_K_CPU1_SA_DQ<23>")
	)
	(arc
		(start 141.67612 -239.296956)
		(mid 141.859628 -239.251462)
		(end 142.04188 -239.301782)
		(width 0.0889)
		(layer "In6.Cu")
		(net "M_K_CPU1_SA_DQ<23>")
	)
	(arc
		(start 143.547592 -239.301782)
		(mid 143.727797 -239.251465)
		(end 143.909796 -239.294924)
		(width 0.0889)
		(layer "In6.Cu")
		(net "M_K_CPU1_SA_DQ<23>")
	)
	(arc
		(start 143.931894 -239.307878)
		(mid 144.210326 -239.377976)
		(end 144.487138 -239.301782)
		(width 0.0889)
		(layer "In6.Cu")
		(net "M_K_CPU1_SA_DQ<23>")
	)
	(arc
		(start 142.98168 -239.301782)
		(mid 143.264636 -239.377959)
		(end 143.547592 -239.301782)
		(width 0.0889)
		(layer "In6.Cu")
		(net "M_K_CPU1_SA_DQ<23>")
	)
	(arc
		(start 144.498822 -239.294924)
		(mid 144.681077 -239.251271)
		(end 144.861534 -239.301782)
		(width 0.0889)
		(layer "In6.Cu")
		(net "M_K_CPU1_SA_DQ<23>")
	)
	(arc
		(start 141.164818 -239.333532)
		(mid 141.420026 -239.377009)
		(end 141.667738 -239.301782)
		(width 0.0889)
		(layer "In6.Cu")
		(net "M_K_CPU1_SA_DQ<23>")
	)
	(arc
		(start 142.04188 -239.301782)
		(mid 142.324836 -239.377959)
		(end 142.607792 -239.301782)
		(width 0.0889)
		(layer "In6.Cu")
		(net "M_K_CPU1_SA_DQ<23>")
	)
	(arc
		(start 142.607792 -239.301782)
		(mid 142.794736 -239.251527)
		(end 142.98168 -239.301782)
		(width 0.0889)
		(layer "In6.Cu")
		(net "M_K_CPU1_SA_DQ<23>")
	)
	(arc
		(start 144.861534 -239.301782)
		(mid 145.137466 -239.378039)
		(end 145.415254 -239.308894)
		(width 0.0889)
		(layer "In6.Cu")
		(net "M_K_CPU1_SA_DQ<23>")
	)
	(segment
		(start 141.857984 -239.080294)
		(end 142.324836 -238.814356)
		(width 0.10668)
		(layer "F.Cu")
		(net "M_K_CPU1_SA_DQ<22>")
	)
	(segment
		(start 182.940452 -222.188532)
		(end 182.940452 -222.247206)
		(width 0.14478)
		(layer "In6.Cu")
		(net "M_K_CPU1_SA_DQ<22>")
	)
	(segment
		(start 175.265842 -222.025464)
		(end 175.42891 -222.188532)
		(width 0.14478)
		(layer "In6.Cu")
		(net "M_K_CPU1_SA_DQ<22>")
	)
	(segment
		(start 169.907966 -222.410274)
		(end 170.758104 -223.260412)
		(width 0.14478)
		(layer "In6.Cu")
		(net "M_K_CPU1_SA_DQ<22>")
	)
	(segment
		(start 168.26738 -222.183452)
		(end 168.26738 -222.247206)
		(width 0.14478)
		(layer "In6.Cu")
		(net "M_K_CPU1_SA_DQ<22>")
	)
	(segment
		(start 144.007078 -238.497872)
		(end 144.017492 -238.491776)
		(width 0.0889)
		(layer "In6.Cu")
		(net "M_K_CPU1_SA_DQ<22>")
	)
	(segment
		(start 153.478484 -235.969556)
		(end 153.569162 -236.060234)
		(width 0.14478)
		(layer "In6.Cu")
		(net "M_K_CPU1_SA_DQ<22>")
	)
	(segment
		(start 182.383938 -222.188532)
		(end 182.547006 -222.025464)
		(width 0.14478)
		(layer "In6.Cu")
		(net "M_K_CPU1_SA_DQ<22>")
	)
	(segment
		(start 169.543476 -222.410274)
		(end 169.907966 -222.410274)
		(width 0.14478)
		(layer "In6.Cu")
		(net "M_K_CPU1_SA_DQ<22>")
	)
	(segment
		(start 165.553136 -223.036892)
		(end 165.553136 -223.097344)
		(width 0.14478)
		(layer "In6.Cu")
		(net "M_K_CPU1_SA_DQ<22>")
	)
	(segment
		(start 147.935188 -236.902244)
		(end 152.931876 -236.902244)
		(width 0.14478)
		(layer "In6.Cu")
		(net "M_K_CPU1_SA_DQ<22>")
	)
	(segment
		(start 193.22796 -222.188532)
		(end 193.22796 -222.632016)
		(width 0.14478)
		(layer "In6.Cu")
		(net "M_K_CPU1_SA_DQ<22>")
	)
	(segment
		(start 193.784474 -222.573342)
		(end 193.947542 -222.410274)
		(width 0.14478)
		(layer "In6.Cu")
		(net "M_K_CPU1_SA_DQ<22>")
	)
	(segment
		(start 168.823894 -222.247206)
		(end 168.823894 -222.183452)
		(width 0.14478)
		(layer "In6.Cu")
		(net "M_K_CPU1_SA_DQ<22>")
	)
	(segment
		(start 188.673232 -223.260412)
		(end 189.52337 -222.410274)
		(width 0.14478)
		(layer "In6.Cu")
		(net "M_K_CPU1_SA_DQ<22>")
	)
	(segment
		(start 172.724826 -222.878904)
		(end 172.955204 -222.878904)
		(width 0.14478)
		(layer "In6.Cu")
		(net "M_K_CPU1_SA_DQ<22>")
	)
	(segment
		(start 168.986962 -222.020384)
		(end 169.21734 -222.020384)
		(width 0.14478)
		(layer "In6.Cu")
		(net "M_K_CPU1_SA_DQ<22>")
	)
	(segment
		(start 178.302158 -223.260412)
		(end 181.140862 -223.260412)
		(width 0.14478)
		(layer "In6.Cu")
		(net "M_K_CPU1_SA_DQ<22>")
	)
	(segment
		(start 169.21734 -222.020384)
		(end 169.380408 -222.183452)
		(width 0.14478)
		(layer "In6.Cu")
		(net "M_K_CPU1_SA_DQ<22>")
	)
	(segment
		(start 193.064892 -222.025464)
		(end 193.22796 -222.188532)
		(width 0.14478)
		(layer "In6.Cu")
		(net "M_K_CPU1_SA_DQ<22>")
	)
	(segment
		(start 181.140862 -223.260412)
		(end 181.991 -222.410274)
		(width 0.14478)
		(layer "In6.Cu")
		(net "M_K_CPU1_SA_DQ<22>")
	)
	(segment
		(start 153.08834 -236.154976)
		(end 153.27376 -235.969556)
		(width 0.14478)
		(layer "In6.Cu")
		(net "M_K_CPU1_SA_DQ<22>")
	)
	(segment
		(start 144.39138 -238.491776)
		(end 144.401794 -238.497872)
		(width 0.0889)
		(layer "In6.Cu")
		(net "M_K_CPU1_SA_DQ<22>")
	)
	(segment
		(start 155.129738 -234.499658)
		(end 155.334462 -234.499658)
		(width 0.14478)
		(layer "In6.Cu")
		(net "M_K_CPU1_SA_DQ<22>")
	)
	(segment
		(start 170.758104 -223.260412)
		(end 172.39869 -223.260412)
		(width 0.14478)
		(layer "In6.Cu")
		(net "M_K_CPU1_SA_DQ<22>")
	)
	(segment
		(start 173.28134 -223.260412)
		(end 173.609254 -223.260412)
		(width 0.14478)
		(layer "In6.Cu")
		(net "M_K_CPU1_SA_DQ<22>")
	)
	(segment
		(start 154.648916 -234.799124)
		(end 154.648916 -234.5944)
		(width 0.14478)
		(layer "In6.Cu")
		(net "M_K_CPU1_SA_DQ<22>")
	)
	(segment
		(start 192.671446 -222.632016)
		(end 192.671446 -222.188532)
		(width 0.14478)
		(layer "In6.Cu")
		(net "M_K_CPU1_SA_DQ<22>")
	)
	(segment
		(start 173.118272 -223.097344)
		(end 173.28134 -223.260412)
		(width 0.14478)
		(layer "In6.Cu")
		(net "M_K_CPU1_SA_DQ<22>")
	)
	(segment
		(start 191.951864 -222.410274)
		(end 192.114932 -222.573342)
		(width 0.14478)
		(layer "In6.Cu")
		(net "M_K_CPU1_SA_DQ<22>")
	)
	(segment
		(start 192.114932 -222.573342)
		(end 192.114932 -222.632016)
		(width 0.14478)
		(layer "In6.Cu")
		(net "M_K_CPU1_SA_DQ<22>")
	)
	(segment
		(start 154.554174 -235.279946)
		(end 154.739594 -235.094526)
		(width 0.14478)
		(layer "In6.Cu")
		(net "M_K_CPU1_SA_DQ<22>")
	)
	(segment
		(start 167.710866 -222.183452)
		(end 167.873934 -222.020384)
		(width 0.14478)
		(layer "In6.Cu")
		(net "M_K_CPU1_SA_DQ<22>")
	)
	(segment
		(start 145.144744 -238.44123)
		(end 145.695162 -238.44123)
		(width 0.0889)
		(layer "In6.Cu")
		(net "M_K_CPU1_SA_DQ<22>")
	)
	(segment
		(start 172.39869 -223.260412)
		(end 172.561758 -223.097344)
		(width 0.14478)
		(layer "In6.Cu")
		(net "M_K_CPU1_SA_DQ<22>")
	)
	(segment
		(start 163.96081 -223.443546)
		(end 164.143944 -223.260412)
		(width 0.14478)
		(layer "In6.Cu")
		(net "M_K_CPU1_SA_DQ<22>")
	)
	(segment
		(start 153.773886 -236.060234)
		(end 153.959306 -235.874814)
		(width 0.14478)
		(layer "In6.Cu")
		(net "M_K_CPU1_SA_DQ<22>")
	)
	(segment
		(start 188.194696 -223.036892)
		(end 188.194696 -223.097344)
		(width 0.14478)
		(layer "In6.Cu")
		(net "M_K_CPU1_SA_DQ<22>")
	)
	(segment
		(start 174.459392 -222.410274)
		(end 174.709328 -222.410274)
		(width 0.14478)
		(layer "In6.Cu")
		(net "M_K_CPU1_SA_DQ<22>")
	)
	(segment
		(start 143.077692 -238.491776)
		(end 143.086074 -238.48695)
		(width 0.0889)
		(layer "In6.Cu")
		(net "M_K_CPU1_SA_DQ<22>")
	)
	(segment
		(start 174.709328 -222.410274)
		(end 174.872396 -222.247206)
		(width 0.14478)
		(layer "In6.Cu")
		(net "M_K_CPU1_SA_DQ<22>")
	)
	(segment
		(start 173.609254 -223.260412)
		(end 174.459392 -222.410274)
		(width 0.14478)
		(layer "In6.Cu")
		(net "M_K_CPU1_SA_DQ<22>")
	)
	(segment
		(start 147.665948 -236.902244)
		(end 147.935188 -236.902244)
		(width 0.0889)
		(layer "In6.Cu")
		(net "M_K_CPU1_SA_DQ<22>")
	)
	(segment
		(start 175.42891 -222.188532)
		(end 175.42891 -222.247206)
		(width 0.14478)
		(layer "In6.Cu")
		(net "M_K_CPU1_SA_DQ<22>")
	)
	(segment
		(start 172.561758 -223.097344)
		(end 172.561758 -223.041972)
		(width 0.14478)
		(layer "In6.Cu")
		(net "M_K_CPU1_SA_DQ<22>")
	)
	(segment
		(start 187.80125 -222.873824)
		(end 188.031628 -222.873824)
		(width 0.14478)
		(layer "In6.Cu")
		(net "M_K_CPU1_SA_DQ<22>")
	)
	(segment
		(start 165.553136 -223.097344)
		(end 165.716204 -223.260412)
		(width 0.14478)
		(layer "In6.Cu")
		(net "M_K_CPU1_SA_DQ<22>")
	)
	(segment
		(start 177.45202 -222.410274)
		(end 178.302158 -223.260412)
		(width 0.14478)
		(layer "In6.Cu")
		(net "M_K_CPU1_SA_DQ<22>")
	)
	(segment
		(start 154.834336 -234.40898)
		(end 155.03906 -234.40898)
		(width 0.14478)
		(layer "In6.Cu")
		(net "M_K_CPU1_SA_DQ<22>")
	)
	(segment
		(start 164.996622 -223.036892)
		(end 165.15969 -222.873824)
		(width 0.14478)
		(layer "In6.Cu")
		(net "M_K_CPU1_SA_DQ<22>")
	)
	(segment
		(start 153.27376 -235.969556)
		(end 153.478484 -235.969556)
		(width 0.14478)
		(layer "In6.Cu")
		(net "M_K_CPU1_SA_DQ<22>")
	)
	(segment
		(start 154.258772 -235.189268)
		(end 154.34945 -235.279946)
		(width 0.14478)
		(layer "In6.Cu")
		(net "M_K_CPU1_SA_DQ<22>")
	)
	(segment
		(start 168.823894 -222.183452)
		(end 168.986962 -222.020384)
		(width 0.14478)
		(layer "In6.Cu")
		(net "M_K_CPU1_SA_DQ<22>")
	)
	(segment
		(start 153.179018 -236.655102)
		(end 153.179018 -236.450378)
		(width 0.14478)
		(layer "In6.Cu")
		(net "M_K_CPU1_SA_DQ<22>")
	)
	(segment
		(start 183.10352 -222.410274)
		(end 184.99582 -222.410274)
		(width 0.14478)
		(layer "In6.Cu")
		(net "M_K_CPU1_SA_DQ<22>")
	)
	(segment
		(start 167.873934 -222.020384)
		(end 168.104312 -222.020384)
		(width 0.14478)
		(layer "In6.Cu")
		(net "M_K_CPU1_SA_DQ<22>")
	)
	(segment
		(start 192.278 -222.795084)
		(end 192.508378 -222.795084)
		(width 0.14478)
		(layer "In6.Cu")
		(net "M_K_CPU1_SA_DQ<22>")
	)
	(segment
		(start 182.383938 -222.247206)
		(end 182.383938 -222.188532)
		(width 0.14478)
		(layer "In6.Cu")
		(net "M_K_CPU1_SA_DQ<22>")
	)
	(segment
		(start 147.112228 -237.455964)
		(end 147.665948 -236.902244)
		(width 0.0889)
		(layer "In6.Cu")
		(net "M_K_CPU1_SA_DQ<22>")
	)
	(segment
		(start 185.845958 -223.260412)
		(end 187.475114 -223.260412)
		(width 0.14478)
		(layer "In6.Cu")
		(net "M_K_CPU1_SA_DQ<22>")
	)
	(segment
		(start 154.054048 -235.189268)
		(end 154.258772 -235.189268)
		(width 0.14478)
		(layer "In6.Cu")
		(net "M_K_CPU1_SA_DQ<22>")
	)
	(segment
		(start 146.680428 -237.455964)
		(end 147.112228 -237.455964)
		(width 0.0889)
		(layer "In6.Cu")
		(net "M_K_CPU1_SA_DQ<22>")
	)
	(segment
		(start 194.17919 -222.410274)
		(end 194.604132 -222.835216)
		(width 0.14478)
		(layer "In6.Cu")
		(net "M_K_CPU1_SA_DQ<22>")
	)
	(segment
		(start 174.872396 -222.247206)
		(end 174.872396 -222.188532)
		(width 0.14478)
		(layer "In6.Cu")
		(net "M_K_CPU1_SA_DQ<22>")
	)
	(segment
		(start 168.660826 -222.410274)
		(end 168.823894 -222.247206)
		(width 0.14478)
		(layer "In6.Cu")
		(net "M_K_CPU1_SA_DQ<22>")
	)
	(segment
		(start 166.066724 -223.260412)
		(end 166.916862 -222.410274)
		(width 0.14478)
		(layer "In6.Cu")
		(net "M_K_CPU1_SA_DQ<22>")
	)
	(segment
		(start 182.940452 -222.247206)
		(end 183.10352 -222.410274)
		(width 0.14478)
		(layer "In6.Cu")
		(net "M_K_CPU1_SA_DQ<22>")
	)
	(segment
		(start 165.15969 -222.873824)
		(end 165.390068 -222.873824)
		(width 0.14478)
		(layer "In6.Cu")
		(net "M_K_CPU1_SA_DQ<22>")
	)
	(segment
		(start 153.868628 -235.374688)
		(end 154.054048 -235.189268)
		(width 0.14478)
		(layer "In6.Cu")
		(net "M_K_CPU1_SA_DQ<22>")
	)
	(segment
		(start 182.22087 -222.410274)
		(end 182.383938 -222.247206)
		(width 0.14478)
		(layer "In6.Cu")
		(net "M_K_CPU1_SA_DQ<22>")
	)
	(segment
		(start 153.959306 -235.67009)
		(end 153.868628 -235.579412)
		(width 0.14478)
		(layer "In6.Cu")
		(net "M_K_CPU1_SA_DQ<22>")
	)
	(segment
		(start 167.547798 -222.410274)
		(end 167.710866 -222.247206)
		(width 0.14478)
		(layer "In6.Cu")
		(net "M_K_CPU1_SA_DQ<22>")
	)
	(segment
		(start 188.194696 -223.097344)
		(end 188.357764 -223.260412)
		(width 0.14478)
		(layer "In6.Cu")
		(net "M_K_CPU1_SA_DQ<22>")
	)
	(segment
		(start 155.334462 -234.499658)
		(end 155.715208 -234.118912)
		(width 0.14478)
		(layer "In6.Cu")
		(net "M_K_CPU1_SA_DQ<22>")
	)
	(segment
		(start 153.868628 -235.579412)
		(end 153.868628 -235.374688)
		(width 0.14478)
		(layer "In6.Cu")
		(net "M_K_CPU1_SA_DQ<22>")
	)
	(segment
		(start 165.390068 -222.873824)
		(end 165.553136 -223.036892)
		(width 0.14478)
		(layer "In6.Cu")
		(net "M_K_CPU1_SA_DQ<22>")
	)
	(segment
		(start 187.475114 -223.260412)
		(end 187.638182 -223.097344)
		(width 0.14478)
		(layer "In6.Cu")
		(net "M_K_CPU1_SA_DQ<22>")
	)
	(segment
		(start 163.96081 -223.68891)
		(end 163.96081 -223.443546)
		(width 0.14478)
		(layer "In6.Cu")
		(net "M_K_CPU1_SA_DQ<22>")
	)
	(segment
		(start 187.638182 -223.097344)
		(end 187.638182 -223.036892)
		(width 0.14478)
		(layer "In6.Cu")
		(net "M_K_CPU1_SA_DQ<22>")
	)
	(segment
		(start 174.872396 -222.188532)
		(end 175.035464 -222.025464)
		(width 0.14478)
		(layer "In6.Cu")
		(net "M_K_CPU1_SA_DQ<22>")
	)
	(segment
		(start 175.035464 -222.025464)
		(end 175.265842 -222.025464)
		(width 0.14478)
		(layer "In6.Cu")
		(net "M_K_CPU1_SA_DQ<22>")
	)
	(segment
		(start 181.991 -222.410274)
		(end 182.22087 -222.410274)
		(width 0.14478)
		(layer "In6.Cu")
		(net "M_K_CPU1_SA_DQ<22>")
	)
	(segment
		(start 153.569162 -236.060234)
		(end 153.773886 -236.060234)
		(width 0.14478)
		(layer "In6.Cu")
		(net "M_K_CPU1_SA_DQ<22>")
	)
	(segment
		(start 154.34945 -235.279946)
		(end 154.554174 -235.279946)
		(width 0.14478)
		(layer "In6.Cu")
		(net "M_K_CPU1_SA_DQ<22>")
	)
	(segment
		(start 172.955204 -222.878904)
		(end 173.118272 -223.041972)
		(width 0.14478)
		(layer "In6.Cu")
		(net "M_K_CPU1_SA_DQ<22>")
	)
	(segment
		(start 153.959306 -235.874814)
		(end 153.959306 -235.67009)
		(width 0.14478)
		(layer "In6.Cu")
		(net "M_K_CPU1_SA_DQ<22>")
	)
	(segment
		(start 168.26738 -222.247206)
		(end 168.430448 -222.410274)
		(width 0.14478)
		(layer "In6.Cu")
		(net "M_K_CPU1_SA_DQ<22>")
	)
	(segment
		(start 182.547006 -222.025464)
		(end 182.777384 -222.025464)
		(width 0.14478)
		(layer "In6.Cu")
		(net "M_K_CPU1_SA_DQ<22>")
	)
	(segment
		(start 145.695162 -238.44123)
		(end 146.680428 -237.455964)
		(width 0.0889)
		(layer "In6.Cu")
		(net "M_K_CPU1_SA_DQ<22>")
	)
	(segment
		(start 175.591978 -222.410274)
		(end 177.45202 -222.410274)
		(width 0.14478)
		(layer "In6.Cu")
		(net "M_K_CPU1_SA_DQ<22>")
	)
	(segment
		(start 155.715208 -231.934512)
		(end 163.96081 -223.68891)
		(width 0.14478)
		(layer "In6.Cu")
		(net "M_K_CPU1_SA_DQ<22>")
	)
	(segment
		(start 193.784474 -222.632016)
		(end 193.784474 -222.573342)
		(width 0.14478)
		(layer "In6.Cu")
		(net "M_K_CPU1_SA_DQ<22>")
	)
	(segment
		(start 164.143944 -223.260412)
		(end 164.833554 -223.260412)
		(width 0.14478)
		(layer "In6.Cu")
		(net "M_K_CPU1_SA_DQ<22>")
	)
	(segment
		(start 142.47876 -238.548926)
		(end 142.574772 -238.523526)
		(width 0.0889)
		(layer "In6.Cu")
		(net "M_K_CPU1_SA_DQ<22>")
	)
	(segment
		(start 182.777384 -222.025464)
		(end 182.940452 -222.188532)
		(width 0.14478)
		(layer "In6.Cu")
		(net "M_K_CPU1_SA_DQ<22>")
	)
	(segment
		(start 173.118272 -223.041972)
		(end 173.118272 -223.097344)
		(width 0.14478)
		(layer "In6.Cu")
		(net "M_K_CPU1_SA_DQ<22>")
	)
	(segment
		(start 164.833554 -223.260412)
		(end 164.996622 -223.097344)
		(width 0.14478)
		(layer "In6.Cu")
		(net "M_K_CPU1_SA_DQ<22>")
	)
	(segment
		(start 165.716204 -223.260412)
		(end 166.066724 -223.260412)
		(width 0.14478)
		(layer "In6.Cu")
		(net "M_K_CPU1_SA_DQ<22>")
	)
	(segment
		(start 169.380408 -222.183452)
		(end 169.380408 -222.247206)
		(width 0.14478)
		(layer "In6.Cu")
		(net "M_K_CPU1_SA_DQ<22>")
	)
	(segment
		(start 184.99582 -222.410274)
		(end 185.845958 -223.260412)
		(width 0.14478)
		(layer "In6.Cu")
		(net "M_K_CPU1_SA_DQ<22>")
	)
	(segment
		(start 153.179018 -236.450378)
		(end 153.08834 -236.3597)
		(width 0.14478)
		(layer "In6.Cu")
		(net "M_K_CPU1_SA_DQ<22>")
	)
	(segment
		(start 166.916862 -222.410274)
		(end 167.547798 -222.410274)
		(width 0.14478)
		(layer "In6.Cu")
		(net "M_K_CPU1_SA_DQ<22>")
	)
	(segment
		(start 192.834514 -222.025464)
		(end 193.064892 -222.025464)
		(width 0.14478)
		(layer "In6.Cu")
		(net "M_K_CPU1_SA_DQ<22>")
	)
	(segment
		(start 142.324836 -238.814356)
		(end 142.47876 -238.548926)
		(width 0.0889)
		(layer "In6.Cu")
		(net "M_K_CPU1_SA_DQ<22>")
	)
	(segment
		(start 154.739594 -235.094526)
		(end 154.739594 -234.889802)
		(width 0.14478)
		(layer "In6.Cu")
		(net "M_K_CPU1_SA_DQ<22>")
	)
	(segment
		(start 193.391028 -222.795084)
		(end 193.621406 -222.795084)
		(width 0.14478)
		(layer "In6.Cu")
		(net "M_K_CPU1_SA_DQ<22>")
	)
	(segment
		(start 175.42891 -222.247206)
		(end 175.591978 -222.410274)
		(width 0.14478)
		(layer "In6.Cu")
		(net "M_K_CPU1_SA_DQ<22>")
	)
	(segment
		(start 168.430448 -222.410274)
		(end 168.660826 -222.410274)
		(width 0.14478)
		(layer "In6.Cu")
		(net "M_K_CPU1_SA_DQ<22>")
	)
	(segment
		(start 155.03906 -234.40898)
		(end 155.129738 -234.499658)
		(width 0.14478)
		(layer "In6.Cu")
		(net "M_K_CPU1_SA_DQ<22>")
	)
	(segment
		(start 192.671446 -222.188532)
		(end 192.834514 -222.025464)
		(width 0.14478)
		(layer "In6.Cu")
		(net "M_K_CPU1_SA_DQ<22>")
	)
	(segment
		(start 193.947542 -222.410274)
		(end 194.17919 -222.410274)
		(width 0.14478)
		(layer "In6.Cu")
		(net "M_K_CPU1_SA_DQ<22>")
	)
	(segment
		(start 168.104312 -222.020384)
		(end 168.26738 -222.183452)
		(width 0.14478)
		(layer "In6.Cu")
		(net "M_K_CPU1_SA_DQ<22>")
	)
	(segment
		(start 187.638182 -223.036892)
		(end 187.80125 -222.873824)
		(width 0.14478)
		(layer "In6.Cu")
		(net "M_K_CPU1_SA_DQ<22>")
	)
	(segment
		(start 154.648916 -234.5944)
		(end 154.834336 -234.40898)
		(width 0.14478)
		(layer "In6.Cu")
		(net "M_K_CPU1_SA_DQ<22>")
	)
	(segment
		(start 188.357764 -223.260412)
		(end 188.673232 -223.260412)
		(width 0.14478)
		(layer "In6.Cu")
		(net "M_K_CPU1_SA_DQ<22>")
	)
	(segment
		(start 193.621406 -222.795084)
		(end 193.784474 -222.632016)
		(width 0.14478)
		(layer "In6.Cu")
		(net "M_K_CPU1_SA_DQ<22>")
	)
	(segment
		(start 155.715208 -234.118912)
		(end 155.715208 -231.934512)
		(width 0.14478)
		(layer "In6.Cu")
		(net "M_K_CPU1_SA_DQ<22>")
	)
	(segment
		(start 188.031628 -222.873824)
		(end 188.194696 -223.036892)
		(width 0.14478)
		(layer "In6.Cu")
		(net "M_K_CPU1_SA_DQ<22>")
	)
	(segment
		(start 192.508378 -222.795084)
		(end 192.671446 -222.632016)
		(width 0.14478)
		(layer "In6.Cu")
		(net "M_K_CPU1_SA_DQ<22>")
	)
	(segment
		(start 193.22796 -222.632016)
		(end 193.391028 -222.795084)
		(width 0.14478)
		(layer "In6.Cu")
		(net "M_K_CPU1_SA_DQ<22>")
	)
	(segment
		(start 167.710866 -222.247206)
		(end 167.710866 -222.183452)
		(width 0.14478)
		(layer "In6.Cu")
		(net "M_K_CPU1_SA_DQ<22>")
	)
	(segment
		(start 164.996622 -223.097344)
		(end 164.996622 -223.036892)
		(width 0.14478)
		(layer "In6.Cu")
		(net "M_K_CPU1_SA_DQ<22>")
	)
	(segment
		(start 169.380408 -222.247206)
		(end 169.543476 -222.410274)
		(width 0.14478)
		(layer "In6.Cu")
		(net "M_K_CPU1_SA_DQ<22>")
	)
	(segment
		(start 189.52337 -222.410274)
		(end 191.951864 -222.410274)
		(width 0.14478)
		(layer "In6.Cu")
		(net "M_K_CPU1_SA_DQ<22>")
	)
	(segment
		(start 154.739594 -234.889802)
		(end 154.648916 -234.799124)
		(width 0.14478)
		(layer "In6.Cu")
		(net "M_K_CPU1_SA_DQ<22>")
	)
	(segment
		(start 192.114932 -222.632016)
		(end 192.278 -222.795084)
		(width 0.14478)
		(layer "In6.Cu")
		(net "M_K_CPU1_SA_DQ<22>")
	)
	(segment
		(start 152.931876 -236.902244)
		(end 153.179018 -236.655102)
		(width 0.14478)
		(layer "In6.Cu")
		(net "M_K_CPU1_SA_DQ<22>")
	)
	(segment
		(start 153.08834 -236.3597)
		(end 153.08834 -236.154976)
		(width 0.14478)
		(layer "In6.Cu")
		(net "M_K_CPU1_SA_DQ<22>")
	)
	(segment
		(start 172.561758 -223.041972)
		(end 172.724826 -222.878904)
		(width 0.14478)
		(layer "In6.Cu")
		(net "M_K_CPU1_SA_DQ<22>")
	)
	(arc
		(start 144.957546 -238.491776)
		(mid 145.047806 -238.454148)
		(end 145.144744 -238.44123)
		(width 0.0889)
		(layer "In6.Cu")
		(net "M_K_CPU1_SA_DQ<22>")
	)
	(arc
		(start 144.401794 -238.497872)
		(mid 144.68048 -238.568092)
		(end 144.957546 -238.491776)
		(width 0.0889)
		(layer "In6.Cu")
		(net "M_K_CPU1_SA_DQ<22>")
	)
	(arc
		(start 142.574772 -238.523526)
		(mid 142.82998 -238.567003)
		(end 143.077692 -238.491776)
		(width 0.0889)
		(layer "In6.Cu")
		(net "M_K_CPU1_SA_DQ<22>")
	)
	(arc
		(start 143.086074 -238.48695)
		(mid 143.269582 -238.441456)
		(end 143.451834 -238.491776)
		(width 0.0889)
		(layer "In6.Cu")
		(net "M_K_CPU1_SA_DQ<22>")
	)
	(arc
		(start 144.017492 -238.491776)
		(mid 144.204436 -238.441521)
		(end 144.39138 -238.491776)
		(width 0.0889)
		(layer "In6.Cu")
		(net "M_K_CPU1_SA_DQ<22>")
	)
	(arc
		(start 143.451834 -238.491776)
		(mid 143.728647 -238.567919)
		(end 144.007078 -238.497872)
		(width 0.0889)
		(layer "In6.Cu")
		(net "M_K_CPU1_SA_DQ<22>")
	)
	(segment
		(start 140.91793 -239.080294)
		(end 141.384782 -238.814356)
		(width 0.10668)
		(layer "F.Cu")
		(net "M_K_CPU1_SA_DQ<21>")
	)
	(segment
		(start 185.845958 -224.110296)
		(end 188.801248 -224.110296)
		(width 0.14478)
		(layer "In6.Cu")
		(net "M_K_CPU1_SA_DQ<21>")
	)
	(segment
		(start 144.391126 -239.136936)
		(end 144.40154 -239.13084)
		(width 0.0889)
		(layer "In6.Cu")
		(net "M_K_CPU1_SA_DQ<21>")
	)
	(segment
		(start 177.452274 -223.260412)
		(end 178.302158 -224.110296)
		(width 0.14478)
		(layer "In6.Cu")
		(net "M_K_CPU1_SA_DQ<21>")
	)
	(segment
		(start 170.758104 -224.110296)
		(end 173.609254 -224.110296)
		(width 0.14478)
		(layer "In6.Cu")
		(net "M_K_CPU1_SA_DQ<21>")
	)
	(segment
		(start 144.017492 -239.136936)
		(end 144.025874 -239.141762)
		(width 0.0889)
		(layer "In6.Cu")
		(net "M_K_CPU1_SA_DQ<21>")
	)
	(segment
		(start 147.188428 -237.786164)
		(end 147.617688 -237.356904)
		(width 0.0889)
		(layer "In6.Cu")
		(net "M_K_CPU1_SA_DQ<21>")
	)
	(segment
		(start 198.279258 -223.260412)
		(end 198.7042 -223.685354)
		(width 0.14478)
		(layer "In6.Cu")
		(net "M_K_CPU1_SA_DQ<21>")
	)
	(segment
		(start 146.375628 -238.540544)
		(end 146.375628 -238.116364)
		(width 0.0889)
		(layer "In6.Cu")
		(net "M_K_CPU1_SA_DQ<21>")
	)
	(segment
		(start 173.609254 -224.110296)
		(end 174.459138 -223.260412)
		(width 0.14478)
		(layer "In6.Cu")
		(net "M_K_CPU1_SA_DQ<21>")
	)
	(segment
		(start 143.077692 -239.136936)
		(end 143.086074 -239.141762)
		(width 0.0889)
		(layer "In6.Cu")
		(net "M_K_CPU1_SA_DQ<21>")
	)
	(segment
		(start 153.120344 -237.356904)
		(end 156.169868 -234.30738)
		(width 0.14478)
		(layer "In6.Cu")
		(net "M_K_CPU1_SA_DQ<21>")
	)
	(segment
		(start 174.459138 -223.260412)
		(end 177.452274 -223.260412)
		(width 0.14478)
		(layer "In6.Cu")
		(net "M_K_CPU1_SA_DQ<21>")
	)
	(segment
		(start 146.375628 -238.116364)
		(end 146.705828 -237.786164)
		(width 0.0889)
		(layer "In6.Cu")
		(net "M_K_CPU1_SA_DQ<21>")
	)
	(segment
		(start 196.033644 -223.709484)
		(end 196.264022 -223.709484)
		(width 0.14478)
		(layer "In6.Cu")
		(net "M_K_CPU1_SA_DQ<21>")
	)
	(segment
		(start 184.996074 -223.260412)
		(end 185.845958 -224.110296)
		(width 0.14478)
		(layer "In6.Cu")
		(net "M_K_CPU1_SA_DQ<21>")
	)
	(segment
		(start 145.594324 -239.072166)
		(end 145.844006 -239.072166)
		(width 0.0889)
		(layer "In6.Cu")
		(net "M_K_CPU1_SA_DQ<21>")
	)
	(segment
		(start 195.870576 -223.42348)
		(end 195.870576 -223.546416)
		(width 0.14478)
		(layer "In6.Cu")
		(net "M_K_CPU1_SA_DQ<21>")
	)
	(segment
		(start 178.302158 -224.110296)
		(end 181.140862 -224.110296)
		(width 0.14478)
		(layer "In6.Cu")
		(net "M_K_CPU1_SA_DQ<21>")
	)
	(segment
		(start 141.384782 -238.814356)
		(end 141.230858 -239.079786)
		(width 0.0889)
		(layer "In6.Cu")
		(net "M_K_CPU1_SA_DQ<21>")
	)
	(segment
		(start 156.169868 -232.12298)
		(end 164.182552 -224.110296)
		(width 0.14478)
		(layer "In6.Cu")
		(net "M_K_CPU1_SA_DQ<21>")
	)
	(segment
		(start 196.264022 -223.709484)
		(end 196.42709 -223.546416)
		(width 0.14478)
		(layer "In6.Cu")
		(net "M_K_CPU1_SA_DQ<21>")
	)
	(segment
		(start 147.935188 -237.356904)
		(end 153.120344 -237.356904)
		(width 0.14478)
		(layer "In6.Cu")
		(net "M_K_CPU1_SA_DQ<21>")
	)
	(segment
		(start 144.007078 -239.13084)
		(end 144.017492 -239.136936)
		(width 0.0889)
		(layer "In6.Cu")
		(net "M_K_CPU1_SA_DQ<21>")
	)
	(segment
		(start 141.230858 -239.079786)
		(end 141.25321 -239.163098)
		(width 0.0889)
		(layer "In6.Cu")
		(net "M_K_CPU1_SA_DQ<21>")
	)
	(segment
		(start 195.707508 -223.260412)
		(end 195.870576 -223.42348)
		(width 0.14478)
		(layer "In6.Cu")
		(net "M_K_CPU1_SA_DQ<21>")
	)
	(segment
		(start 189.651132 -223.260412)
		(end 195.707508 -223.260412)
		(width 0.14478)
		(layer "In6.Cu")
		(net "M_K_CPU1_SA_DQ<21>")
	)
	(segment
		(start 146.705828 -237.786164)
		(end 147.188428 -237.786164)
		(width 0.0889)
		(layer "In6.Cu")
		(net "M_K_CPU1_SA_DQ<21>")
	)
	(segment
		(start 166.106348 -224.110296)
		(end 166.956486 -223.260158)
		(width 0.14478)
		(layer "In6.Cu")
		(net "M_K_CPU1_SA_DQ<21>")
	)
	(segment
		(start 196.42709 -223.42348)
		(end 196.590158 -223.260412)
		(width 0.14478)
		(layer "In6.Cu")
		(net "M_K_CPU1_SA_DQ<21>")
	)
	(segment
		(start 169.907966 -223.260158)
		(end 170.758104 -224.110296)
		(width 0.14478)
		(layer "In6.Cu")
		(net "M_K_CPU1_SA_DQ<21>")
	)
	(segment
		(start 195.870576 -223.546416)
		(end 196.033644 -223.709484)
		(width 0.14478)
		(layer "In6.Cu")
		(net "M_K_CPU1_SA_DQ<21>")
	)
	(segment
		(start 142.503398 -239.141762)
		(end 142.51178 -239.136936)
		(width 0.0889)
		(layer "In6.Cu")
		(net "M_K_CPU1_SA_DQ<21>")
	)
	(segment
		(start 196.590158 -223.260412)
		(end 198.279258 -223.260412)
		(width 0.14478)
		(layer "In6.Cu")
		(net "M_K_CPU1_SA_DQ<21>")
	)
	(segment
		(start 166.956486 -223.260158)
		(end 169.907966 -223.260158)
		(width 0.14478)
		(layer "In6.Cu")
		(net "M_K_CPU1_SA_DQ<21>")
	)
	(segment
		(start 181.140862 -224.110296)
		(end 181.990746 -223.260412)
		(width 0.14478)
		(layer "In6.Cu")
		(net "M_K_CPU1_SA_DQ<21>")
	)
	(segment
		(start 196.42709 -223.546416)
		(end 196.42709 -223.42348)
		(width 0.14478)
		(layer "In6.Cu")
		(net "M_K_CPU1_SA_DQ<21>")
	)
	(segment
		(start 147.617688 -237.356904)
		(end 147.935188 -237.356904)
		(width 0.0889)
		(layer "In6.Cu")
		(net "M_K_CPU1_SA_DQ<21>")
	)
	(segment
		(start 181.990746 -223.260412)
		(end 184.996074 -223.260412)
		(width 0.14478)
		(layer "In6.Cu")
		(net "M_K_CPU1_SA_DQ<21>")
	)
	(segment
		(start 145.844006 -239.072166)
		(end 146.375628 -238.540544)
		(width 0.0889)
		(layer "In6.Cu")
		(net "M_K_CPU1_SA_DQ<21>")
	)
	(segment
		(start 156.169868 -234.30738)
		(end 156.169868 -232.12298)
		(width 0.14478)
		(layer "In6.Cu")
		(net "M_K_CPU1_SA_DQ<21>")
	)
	(segment
		(start 188.801248 -224.110296)
		(end 189.651132 -223.260412)
		(width 0.14478)
		(layer "In6.Cu")
		(net "M_K_CPU1_SA_DQ<21>")
	)
	(segment
		(start 164.182552 -224.110296)
		(end 166.106348 -224.110296)
		(width 0.14478)
		(layer "In6.Cu")
		(net "M_K_CPU1_SA_DQ<21>")
	)
	(arc
		(start 143.451834 -239.136936)
		(mid 143.728647 -239.060793)
		(end 144.007078 -239.13084)
		(width 0.0889)
		(layer "In6.Cu")
		(net "M_K_CPU1_SA_DQ<21>")
	)
	(arc
		(start 142.137638 -239.136936)
		(mid 142.319889 -239.187286)
		(end 142.503398 -239.141762)
		(width 0.0889)
		(layer "In6.Cu")
		(net "M_K_CPU1_SA_DQ<21>")
	)
	(arc
		(start 144.957292 -239.136936)
		(mid 145.13392 -239.187169)
		(end 145.313146 -239.147096)
		(width 0.0889)
		(layer "In6.Cu")
		(net "M_K_CPU1_SA_DQ<21>")
	)
	(arc
		(start 141.571726 -239.136936)
		(mid 141.854682 -239.060759)
		(end 142.137638 -239.136936)
		(width 0.0889)
		(layer "In6.Cu")
		(net "M_K_CPU1_SA_DQ<21>")
	)
	(arc
		(start 141.25321 -239.163098)
		(mid 141.415399 -239.185833)
		(end 141.571726 -239.136936)
		(width 0.0889)
		(layer "In6.Cu")
		(net "M_K_CPU1_SA_DQ<21>")
	)
	(arc
		(start 144.025874 -239.141762)
		(mid 144.209128 -239.187135)
		(end 144.391126 -239.136936)
		(width 0.0889)
		(layer "In6.Cu")
		(net "M_K_CPU1_SA_DQ<21>")
	)
	(arc
		(start 142.51178 -239.136936)
		(mid 142.794736 -239.060759)
		(end 143.077692 -239.136936)
		(width 0.0889)
		(layer "In6.Cu")
		(net "M_K_CPU1_SA_DQ<21>")
	)
	(arc
		(start 145.313146 -239.147096)
		(mid 145.448821 -239.091193)
		(end 145.594324 -239.072166)
		(width 0.0889)
		(layer "In6.Cu")
		(net "M_K_CPU1_SA_DQ<21>")
	)
	(arc
		(start 143.086074 -239.141762)
		(mid 143.269582 -239.187256)
		(end 143.451834 -239.136936)
		(width 0.0889)
		(layer "In6.Cu")
		(net "M_K_CPU1_SA_DQ<21>")
	)
	(arc
		(start 144.40154 -239.13084)
		(mid 144.680226 -239.06062)
		(end 144.957292 -239.136936)
		(width 0.0889)
		(layer "In6.Cu")
		(net "M_K_CPU1_SA_DQ<21>")
	)
	(segment
		(start 142.327884 -238.270288)
		(end 142.794736 -238.00435)
		(width 0.10668)
		(layer "F.Cu")
		(net "M_K_CPU1_SA_DQ<20>")
	)
	(segment
		(start 185.005472 -221.569788)
		(end 185.855356 -222.419672)
		(width 0.14478)
		(layer "In6.Cu")
		(net "M_K_CPU1_SA_DQ<20>")
	)
	(segment
		(start 143.921734 -238.32693)
		(end 143.932148 -238.320834)
		(width 0.0889)
		(layer "In6.Cu")
		(net "M_K_CPU1_SA_DQ<20>")
	)
	(segment
		(start 185.855356 -222.419672)
		(end 188.79185 -222.419672)
		(width 0.14478)
		(layer "In6.Cu")
		(net "M_K_CPU1_SA_DQ<20>")
	)
	(segment
		(start 196.926962 -221.723458)
		(end 196.926962 -222.172276)
		(width 0.14478)
		(layer "In6.Cu")
		(net "M_K_CPU1_SA_DQ<20>")
	)
	(segment
		(start 198.279258 -221.56039)
		(end 198.7042 -221.985332)
		(width 0.14478)
		(layer "In6.Cu")
		(net "M_K_CPU1_SA_DQ<20>")
	)
	(segment
		(start 145.14449 -238.25073)
		(end 145.561558 -238.25073)
		(width 0.0889)
		(layer "In6.Cu")
		(net "M_K_CPU1_SA_DQ<20>")
	)
	(segment
		(start 164.333682 -222.410274)
		(end 166.106348 -222.410274)
		(width 0.14478)
		(layer "In6.Cu")
		(net "M_K_CPU1_SA_DQ<20>")
	)
	(segment
		(start 146.711924 -237.100364)
		(end 146.959828 -237.100364)
		(width 0.0889)
		(layer "In6.Cu")
		(net "M_K_CPU1_SA_DQ<20>")
	)
	(segment
		(start 143.913352 -238.331756)
		(end 143.921734 -238.32693)
		(width 0.0889)
		(layer "In6.Cu")
		(net "M_K_CPU1_SA_DQ<20>")
	)
	(segment
		(start 174.44974 -221.569788)
		(end 177.461672 -221.569788)
		(width 0.14478)
		(layer "In6.Cu")
		(net "M_K_CPU1_SA_DQ<20>")
	)
	(segment
		(start 147.612608 -236.447584)
		(end 147.946618 -236.447584)
		(width 0.0889)
		(layer "In6.Cu")
		(net "M_K_CPU1_SA_DQ<20>")
	)
	(segment
		(start 173.599856 -222.419672)
		(end 174.44974 -221.569788)
		(width 0.14478)
		(layer "In6.Cu")
		(net "M_K_CPU1_SA_DQ<20>")
	)
	(segment
		(start 189.641734 -221.569788)
		(end 196.773292 -221.569788)
		(width 0.14478)
		(layer "In6.Cu")
		(net "M_K_CPU1_SA_DQ<20>")
	)
	(segment
		(start 144.487392 -238.32693)
		(end 144.495774 -238.331756)
		(width 0.0889)
		(layer "In6.Cu")
		(net "M_K_CPU1_SA_DQ<20>")
	)
	(segment
		(start 163.44519 -223.298766)
		(end 164.333682 -222.410274)
		(width 0.14478)
		(layer "In6.Cu")
		(net "M_K_CPU1_SA_DQ<20>")
	)
	(segment
		(start 197.320408 -222.335344)
		(end 197.483476 -222.172276)
		(width 0.14478)
		(layer "In6.Cu")
		(net "M_K_CPU1_SA_DQ<20>")
	)
	(segment
		(start 155.260548 -233.291888)
		(end 155.260548 -231.746044)
		(width 0.14478)
		(layer "In6.Cu")
		(net "M_K_CPU1_SA_DQ<20>")
	)
	(segment
		(start 197.09003 -222.335344)
		(end 197.320408 -222.335344)
		(width 0.14478)
		(layer "In6.Cu")
		(net "M_K_CPU1_SA_DQ<20>")
	)
	(segment
		(start 178.311556 -222.419672)
		(end 181.131464 -222.419672)
		(width 0.14478)
		(layer "In6.Cu")
		(net "M_K_CPU1_SA_DQ<20>")
	)
	(segment
		(start 181.981348 -221.569788)
		(end 185.005472 -221.569788)
		(width 0.14478)
		(layer "In6.Cu")
		(net "M_K_CPU1_SA_DQ<20>")
	)
	(segment
		(start 196.773292 -221.569788)
		(end 196.926962 -221.723458)
		(width 0.14478)
		(layer "In6.Cu")
		(net "M_K_CPU1_SA_DQ<20>")
	)
	(segment
		(start 196.926962 -222.172276)
		(end 197.09003 -222.335344)
		(width 0.14478)
		(layer "In6.Cu")
		(net "M_K_CPU1_SA_DQ<20>")
	)
	(segment
		(start 166.106348 -222.410274)
		(end 166.947088 -221.569534)
		(width 0.14478)
		(layer "In6.Cu")
		(net "M_K_CPU1_SA_DQ<20>")
	)
	(segment
		(start 146.959828 -237.100364)
		(end 147.612608 -236.447584)
		(width 0.0889)
		(layer "In6.Cu")
		(net "M_K_CPU1_SA_DQ<20>")
	)
	(segment
		(start 166.947088 -221.569534)
		(end 169.917364 -221.569534)
		(width 0.14478)
		(layer "In6.Cu")
		(net "M_K_CPU1_SA_DQ<20>")
	)
	(segment
		(start 181.131464 -222.419672)
		(end 181.981348 -221.569788)
		(width 0.14478)
		(layer "In6.Cu")
		(net "M_K_CPU1_SA_DQ<20>")
	)
	(segment
		(start 169.917364 -221.569534)
		(end 170.767502 -222.419672)
		(width 0.14478)
		(layer "In6.Cu")
		(net "M_K_CPU1_SA_DQ<20>")
	)
	(segment
		(start 147.946618 -236.447584)
		(end 152.104852 -236.447584)
		(width 0.14478)
		(layer "In6.Cu")
		(net "M_K_CPU1_SA_DQ<20>")
	)
	(segment
		(start 142.640812 -238.26978)
		(end 142.663164 -238.353092)
		(width 0.0889)
		(layer "In6.Cu")
		(net "M_K_CPU1_SA_DQ<20>")
	)
	(segment
		(start 177.461672 -221.569788)
		(end 178.311556 -222.419672)
		(width 0.14478)
		(layer "In6.Cu")
		(net "M_K_CPU1_SA_DQ<20>")
	)
	(segment
		(start 155.260548 -231.746044)
		(end 163.44519 -223.561402)
		(width 0.14478)
		(layer "In6.Cu")
		(net "M_K_CPU1_SA_DQ<20>")
	)
	(segment
		(start 170.767502 -222.419672)
		(end 173.599856 -222.419672)
		(width 0.14478)
		(layer "In6.Cu")
		(net "M_K_CPU1_SA_DQ<20>")
	)
	(segment
		(start 152.104852 -236.447584)
		(end 155.260548 -233.291888)
		(width 0.14478)
		(layer "In6.Cu")
		(net "M_K_CPU1_SA_DQ<20>")
	)
	(segment
		(start 163.44519 -223.561402)
		(end 163.44519 -223.298766)
		(width 0.14478)
		(layer "In6.Cu")
		(net "M_K_CPU1_SA_DQ<20>")
	)
	(segment
		(start 145.561558 -238.25073)
		(end 146.711924 -237.100364)
		(width 0.0889)
		(layer "In6.Cu")
		(net "M_K_CPU1_SA_DQ<20>")
	)
	(segment
		(start 197.483476 -222.172276)
		(end 197.483476 -221.723458)
		(width 0.14478)
		(layer "In6.Cu")
		(net "M_K_CPU1_SA_DQ<20>")
	)
	(segment
		(start 197.483476 -221.723458)
		(end 197.646544 -221.56039)
		(width 0.14478)
		(layer "In6.Cu")
		(net "M_K_CPU1_SA_DQ<20>")
	)
	(segment
		(start 197.646544 -221.56039)
		(end 198.279258 -221.56039)
		(width 0.14478)
		(layer "In6.Cu")
		(net "M_K_CPU1_SA_DQ<20>")
	)
	(segment
		(start 188.79185 -222.419672)
		(end 189.641734 -221.569788)
		(width 0.14478)
		(layer "In6.Cu")
		(net "M_K_CPU1_SA_DQ<20>")
	)
	(segment
		(start 142.794736 -238.00435)
		(end 142.640812 -238.26978)
		(width 0.0889)
		(layer "In6.Cu")
		(net "M_K_CPU1_SA_DQ<20>")
	)
	(arc
		(start 143.932148 -238.320834)
		(mid 144.21058 -238.250736)
		(end 144.487392 -238.32693)
		(width 0.0889)
		(layer "In6.Cu")
		(net "M_K_CPU1_SA_DQ<20>")
	)
	(arc
		(start 143.547592 -238.32693)
		(mid 143.729843 -238.37728)
		(end 143.913352 -238.331756)
		(width 0.0889)
		(layer "In6.Cu")
		(net "M_K_CPU1_SA_DQ<20>")
	)
	(arc
		(start 142.663164 -238.353092)
		(mid 142.825353 -238.375827)
		(end 142.98168 -238.32693)
		(width 0.0889)
		(layer "In6.Cu")
		(net "M_K_CPU1_SA_DQ<20>")
	)
	(arc
		(start 144.861534 -238.32693)
		(mid 144.997975 -238.27013)
		(end 145.14449 -238.25073)
		(width 0.0889)
		(layer "In6.Cu")
		(net "M_K_CPU1_SA_DQ<20>")
	)
	(arc
		(start 142.98168 -238.32693)
		(mid 143.264636 -238.250753)
		(end 143.547592 -238.32693)
		(width 0.0889)
		(layer "In6.Cu")
		(net "M_K_CPU1_SA_DQ<20>")
	)
	(arc
		(start 144.495774 -238.331756)
		(mid 144.679282 -238.37725)
		(end 144.861534 -238.32693)
		(width 0.0889)
		(layer "In6.Cu")
		(net "M_K_CPU1_SA_DQ<20>")
	)
	(segment
		(start 140.91793 -226.120452)
		(end 141.384782 -225.854514)
		(width 0.10668)
		(layer "F.Cu")
		(net "M_K_CPU1_SA_DQ<1>")
	)
	(segment
		(start 180.31079 -199.460358)
		(end 181.727856 -198.873364)
		(width 0.14478)
		(layer "In6.Cu")
		(net "M_K_CPU1_SA_DQ<1>")
	)
	(segment
		(start 145.031968 -222.006668)
		(end 145.031968 -221.260924)
		(width 0.0889)
		(layer "In6.Cu")
		(net "M_K_CPU1_SA_DQ<1>")
	)
	(segment
		(start 187.837064 -199.460358)
		(end 189.483238 -198.778368)
		(width 0.14478)
		(layer "In6.Cu")
		(net "M_K_CPU1_SA_DQ<1>")
	)
	(segment
		(start 179.15255 -199.460358)
		(end 180.31079 -199.460358)
		(width 0.14478)
		(layer "In6.Cu")
		(net "M_K_CPU1_SA_DQ<1>")
	)
	(segment
		(start 143.921734 -225.367088)
		(end 143.953484 -225.3488)
		(width 0.0889)
		(layer "In6.Cu")
		(net "M_K_CPU1_SA_DQ<1>")
	)
	(segment
		(start 143.882618 -225.389948)
		(end 143.921734 -225.367088)
		(width 0.0889)
		(layer "In6.Cu")
		(net "M_K_CPU1_SA_DQ<1>")
	)
	(segment
		(start 198.279258 -198.610474)
		(end 198.7042 -199.035416)
		(width 0.14478)
		(layer "In6.Cu")
		(net "M_K_CPU1_SA_DQ<1>")
	)
	(segment
		(start 181.727856 -198.873364)
		(end 182.362602 -198.610474)
		(width 0.14478)
		(layer "In6.Cu")
		(net "M_K_CPU1_SA_DQ<1>")
	)
	(segment
		(start 167.288972 -198.61022)
		(end 169.553382 -198.61022)
		(width 0.14478)
		(layer "In6.Cu")
		(net "M_K_CPU1_SA_DQ<1>")
	)
	(segment
		(start 143.921734 -223.747076)
		(end 143.953484 -223.728788)
		(width 0.0889)
		(layer "In6.Cu")
		(net "M_K_CPU1_SA_DQ<1>")
	)
	(segment
		(start 145.031968 -221.260924)
		(end 145.145252 -221.14764)
		(width 0.0889)
		(layer "In6.Cu")
		(net "M_K_CPU1_SA_DQ<1>")
	)
	(segment
		(start 142.503398 -226.18192)
		(end 142.51178 -226.177094)
		(width 0.0889)
		(layer "In6.Cu")
		(net "M_K_CPU1_SA_DQ<1>")
	)
	(segment
		(start 143.921734 -224.721928)
		(end 143.882618 -224.699068)
		(width 0.0889)
		(layer "In6.Cu")
		(net "M_K_CPU1_SA_DQ<1>")
	)
	(segment
		(start 144.352772 -222.95993)
		(end 144.391888 -222.93707)
		(width 0.0889)
		(layer "In6.Cu")
		(net "M_K_CPU1_SA_DQ<1>")
	)
	(segment
		(start 189.888622 -198.610474)
		(end 198.279258 -198.610474)
		(width 0.14478)
		(layer "In6.Cu")
		(net "M_K_CPU1_SA_DQ<1>")
	)
	(segment
		(start 171.605956 -199.460358)
		(end 172.748956 -199.460358)
		(width 0.14478)
		(layer "In6.Cu")
		(net "M_K_CPU1_SA_DQ<1>")
	)
	(segment
		(start 147.927568 -218.365324)
		(end 147.927568 -215.390476)
		(width 0.14478)
		(layer "In6.Cu")
		(net "M_K_CPU1_SA_DQ<1>")
	)
	(segment
		(start 184.594246 -198.610474)
		(end 186.646312 -199.460358)
		(width 0.14478)
		(layer "In6.Cu")
		(net "M_K_CPU1_SA_DQ<1>")
	)
	(segment
		(start 144.822926 -222.149924)
		(end 144.862042 -222.127064)
		(width 0.0889)
		(layer "In6.Cu")
		(net "M_K_CPU1_SA_DQ<1>")
	)
	(segment
		(start 174.800768 -198.610474)
		(end 177.100484 -198.610474)
		(width 0.14478)
		(layer "In6.Cu")
		(net "M_K_CPU1_SA_DQ<1>")
	)
	(segment
		(start 182.362602 -198.610474)
		(end 184.594246 -198.610474)
		(width 0.14478)
		(layer "In6.Cu")
		(net "M_K_CPU1_SA_DQ<1>")
	)
	(segment
		(start 141.230858 -226.119944)
		(end 141.25321 -226.203256)
		(width 0.0889)
		(layer "In6.Cu")
		(net "M_K_CPU1_SA_DQ<1>")
	)
	(segment
		(start 165.236398 -199.460358)
		(end 167.288972 -198.61022)
		(width 0.14478)
		(layer "In6.Cu")
		(net "M_K_CPU1_SA_DQ<1>")
	)
	(segment
		(start 186.646312 -199.460358)
		(end 187.837064 -199.460358)
		(width 0.14478)
		(layer "In6.Cu")
		(net "M_K_CPU1_SA_DQ<1>")
	)
	(segment
		(start 145.145252 -221.14764)
		(end 147.927568 -218.365324)
		(width 0.14478)
		(layer "In6.Cu")
		(net "M_K_CPU1_SA_DQ<1>")
	)
	(segment
		(start 172.748956 -199.460358)
		(end 174.217584 -198.852028)
		(width 0.14478)
		(layer "In6.Cu")
		(net "M_K_CPU1_SA_DQ<1>")
	)
	(segment
		(start 163.857686 -199.460358)
		(end 165.236398 -199.460358)
		(width 0.14478)
		(layer "In6.Cu")
		(net "M_K_CPU1_SA_DQ<1>")
	)
	(segment
		(start 143.077692 -226.177094)
		(end 143.086074 -226.18192)
		(width 0.0889)
		(layer "In6.Cu")
		(net "M_K_CPU1_SA_DQ<1>")
	)
	(segment
		(start 147.927568 -215.390476)
		(end 163.857686 -199.460358)
		(width 0.14478)
		(layer "In6.Cu")
		(net "M_K_CPU1_SA_DQ<1>")
	)
	(segment
		(start 144.391888 -222.93707)
		(end 144.424654 -222.91802)
		(width 0.0889)
		(layer "In6.Cu")
		(net "M_K_CPU1_SA_DQ<1>")
	)
	(segment
		(start 169.553382 -198.61022)
		(end 171.605956 -199.460358)
		(width 0.14478)
		(layer "In6.Cu")
		(net "M_K_CPU1_SA_DQ<1>")
	)
	(segment
		(start 177.100484 -198.610474)
		(end 179.15255 -199.460358)
		(width 0.14478)
		(layer "In6.Cu")
		(net "M_K_CPU1_SA_DQ<1>")
	)
	(segment
		(start 141.384782 -225.854514)
		(end 141.230858 -226.119944)
		(width 0.0889)
		(layer "In6.Cu")
		(net "M_K_CPU1_SA_DQ<1>")
	)
	(segment
		(start 174.217584 -198.852028)
		(end 174.800768 -198.610474)
		(width 0.14478)
		(layer "In6.Cu")
		(net "M_K_CPU1_SA_DQ<1>")
	)
	(segment
		(start 143.882618 -223.769936)
		(end 143.921734 -223.747076)
		(width 0.0889)
		(layer "In6.Cu")
		(net "M_K_CPU1_SA_DQ<1>")
	)
	(segment
		(start 144.96161 -222.077026)
		(end 145.031968 -222.006668)
		(width 0.0889)
		(layer "In6.Cu")
		(net "M_K_CPU1_SA_DQ<1>")
	)
	(segment
		(start 143.451834 -226.177094)
		(end 143.482314 -226.159314)
		(width 0.0889)
		(layer "In6.Cu")
		(net "M_K_CPU1_SA_DQ<1>")
	)
	(segment
		(start 189.483238 -198.778368)
		(end 189.888622 -198.610474)
		(width 0.14478)
		(layer "In6.Cu")
		(net "M_K_CPU1_SA_DQ<1>")
	)
	(segment
		(start 143.953484 -224.740216)
		(end 143.921734 -224.721928)
		(width 0.0889)
		(layer "In6.Cu")
		(net "M_K_CPU1_SA_DQ<1>")
	)
	(arc
		(start 142.137638 -226.177094)
		(mid 142.319889 -226.227444)
		(end 142.503398 -226.18192)
		(width 0.0889)
		(layer "In6.Cu")
		(net "M_K_CPU1_SA_DQ<1>")
	)
	(arc
		(start 141.25321 -226.203256)
		(mid 141.415399 -226.225991)
		(end 141.571726 -226.177094)
		(width 0.0889)
		(layer "In6.Cu")
		(net "M_K_CPU1_SA_DQ<1>")
	)
	(arc
		(start 143.953484 -225.3488)
		(mid 144.109412 -225.044508)
		(end 143.953484 -224.740216)
		(width 0.0889)
		(layer "In6.Cu")
		(net "M_K_CPU1_SA_DQ<1>")
	)
	(arc
		(start 143.882618 -224.699068)
		(mid 143.639291 -224.234502)
		(end 143.882618 -223.769936)
		(width 0.0889)
		(layer "In6.Cu")
		(net "M_K_CPU1_SA_DQ<1>")
	)
	(arc
		(start 144.10944 -223.424496)
		(mid 144.173955 -223.162277)
		(end 144.352772 -222.95993)
		(width 0.0889)
		(layer "In6.Cu")
		(net "M_K_CPU1_SA_DQ<1>")
	)
	(arc
		(start 144.862042 -222.127064)
		(mid 144.911033 -222.100467)
		(end 144.96161 -222.077026)
		(width 0.0889)
		(layer "In6.Cu")
		(net "M_K_CPU1_SA_DQ<1>")
	)
	(arc
		(start 143.953484 -223.728788)
		(mid 144.06816 -223.595454)
		(end 144.10944 -223.424496)
		(width 0.0889)
		(layer "In6.Cu")
		(net "M_K_CPU1_SA_DQ<1>")
	)
	(arc
		(start 141.571726 -226.177094)
		(mid 141.854682 -226.100917)
		(end 142.137638 -226.177094)
		(width 0.0889)
		(layer "In6.Cu")
		(net "M_K_CPU1_SA_DQ<1>")
	)
	(arc
		(start 143.482314 -226.159314)
		(mid 143.597741 -226.025938)
		(end 143.639286 -225.854514)
		(width 0.0889)
		(layer "In6.Cu")
		(net "M_K_CPU1_SA_DQ<1>")
	)
	(arc
		(start 144.424654 -222.91802)
		(mid 144.538583 -222.784873)
		(end 144.579594 -222.61449)
		(width 0.0889)
		(layer "In6.Cu")
		(net "M_K_CPU1_SA_DQ<1>")
	)
	(arc
		(start 144.579594 -222.61449)
		(mid 144.644109 -222.352271)
		(end 144.822926 -222.149924)
		(width 0.0889)
		(layer "In6.Cu")
		(net "M_K_CPU1_SA_DQ<1>")
	)
	(arc
		(start 143.086074 -226.18192)
		(mid 143.269582 -226.227414)
		(end 143.451834 -226.177094)
		(width 0.0889)
		(layer "In6.Cu")
		(net "M_K_CPU1_SA_DQ<1>")
	)
	(arc
		(start 143.639286 -225.854514)
		(mid 143.703801 -225.592295)
		(end 143.882618 -225.389948)
		(width 0.0889)
		(layer "In6.Cu")
		(net "M_K_CPU1_SA_DQ<1>")
	)
	(arc
		(start 142.51178 -226.177094)
		(mid 142.794736 -226.100917)
		(end 143.077692 -226.177094)
		(width 0.0889)
		(layer "In6.Cu")
		(net "M_K_CPU1_SA_DQ<1>")
	)
	(segment
		(start 140.447776 -236.650276)
		(end 140.914882 -236.384338)
		(width 0.10668)
		(layer "F.Cu")
		(net "M_K_CPU1_SA_DQ<19>")
	)
	(segment
		(start 146.375628 -235.172504)
		(end 146.375628 -234.890564)
		(width 0.0889)
		(layer "In6.Cu")
		(net "M_K_CPU1_SA_DQ<19>")
	)
	(segment
		(start 187.65012 -218.847416)
		(end 187.65012 -218.784932)
		(width 0.14478)
		(layer "In6.Cu")
		(net "M_K_CPU1_SA_DQ<19>")
	)
	(segment
		(start 191.76492 -218.150948)
		(end 191.91859 -217.997278)
		(width 0.14478)
		(layer "In6.Cu")
		(net "M_K_CPU1_SA_DQ<19>")
	)
	(segment
		(start 167.76192 -217.768424)
		(end 169.105326 -217.768424)
		(width 0.14478)
		(layer "In6.Cu")
		(net "M_K_CPU1_SA_DQ<19>")
	)
	(segment
		(start 169.422064 -218.150948)
		(end 169.898568 -218.150948)
		(width 0.14478)
		(layer "In6.Cu")
		(net "M_K_CPU1_SA_DQ<19>")
	)
	(segment
		(start 175.517556 -217.997278)
		(end 175.671226 -218.150948)
		(width 0.14478)
		(layer "In6.Cu")
		(net "M_K_CPU1_SA_DQ<19>")
	)
	(segment
		(start 164.057584 -219.162122)
		(end 164.202364 -219.306902)
		(width 0.14478)
		(layer "In6.Cu")
		(net "M_K_CPU1_SA_DQ<19>")
	)
	(segment
		(start 165.015672 -218.714066)
		(end 165.160452 -218.858846)
		(width 0.14478)
		(layer "In6.Cu")
		(net "M_K_CPU1_SA_DQ<19>")
	)
	(segment
		(start 191.91859 -217.997278)
		(end 191.91859 -217.941652)
		(width 0.14478)
		(layer "In6.Cu")
		(net "M_K_CPU1_SA_DQ<19>")
	)
	(segment
		(start 187.65012 -218.784932)
		(end 187.813188 -218.621864)
		(width 0.14478)
		(layer "In6.Cu")
		(net "M_K_CPU1_SA_DQ<19>")
	)
	(segment
		(start 193.336164 -218.653106)
		(end 193.566542 -218.653106)
		(width 0.14478)
		(layer "In6.Cu")
		(net "M_K_CPU1_SA_DQ<19>")
	)
	(segment
		(start 193.72961 -218.323414)
		(end 193.892678 -218.160346)
		(width 0.14478)
		(layer "In6.Cu")
		(net "M_K_CPU1_SA_DQ<19>")
	)
	(segment
		(start 169.268394 -217.997278)
		(end 169.422064 -218.150948)
		(width 0.14478)
		(layer "In6.Cu")
		(net "M_K_CPU1_SA_DQ<19>")
	)
	(segment
		(start 183.18353 -218.150948)
		(end 184.986422 -218.150948)
		(width 0.14478)
		(layer "In6.Cu")
		(net "M_K_CPU1_SA_DQ<19>")
	)
	(segment
		(start 164.609018 -218.858846)
		(end 164.753798 -218.714066)
		(width 0.14478)
		(layer "In6.Cu")
		(net "M_K_CPU1_SA_DQ<19>")
	)
	(segment
		(start 179.960016 -219.001086)
		(end 180.113686 -218.847416)
		(width 0.14478)
		(layer "In6.Cu")
		(net "M_K_CPU1_SA_DQ<19>")
	)
	(segment
		(start 165.160452 -218.858846)
		(end 165.160452 -218.865704)
		(width 0.14478)
		(layer "In6.Cu")
		(net "M_K_CPU1_SA_DQ<19>")
	)
	(segment
		(start 193.173096 -218.323414)
		(end 193.173096 -218.490038)
		(width 0.14478)
		(layer "In6.Cu")
		(net "M_K_CPU1_SA_DQ<19>")
	)
	(segment
		(start 188.673232 -219.010484)
		(end 189.532768 -218.150948)
		(width 0.14478)
		(layer "In6.Cu")
		(net "M_K_CPU1_SA_DQ<19>")
	)
	(segment
		(start 165.305232 -219.010484)
		(end 166.066724 -219.010484)
		(width 0.14478)
		(layer "In6.Cu")
		(net "M_K_CPU1_SA_DQ<19>")
	)
	(segment
		(start 192.081658 -217.778584)
		(end 192.312036 -217.778584)
		(width 0.14478)
		(layer "In6.Cu")
		(net "M_K_CPU1_SA_DQ<19>")
	)
	(segment
		(start 193.173096 -218.490038)
		(end 193.336164 -218.653106)
		(width 0.14478)
		(layer "In6.Cu")
		(net "M_K_CPU1_SA_DQ<19>")
	)
	(segment
		(start 184.986422 -218.150948)
		(end 185.83656 -219.001086)
		(width 0.14478)
		(layer "In6.Cu")
		(net "M_K_CPU1_SA_DQ<19>")
	)
	(segment
		(start 164.464238 -219.306902)
		(end 164.609018 -219.162122)
		(width 0.14478)
		(layer "In6.Cu")
		(net "M_K_CPU1_SA_DQ<19>")
	)
	(segment
		(start 192.312036 -217.778584)
		(end 192.475104 -217.941652)
		(width 0.14478)
		(layer "In6.Cu")
		(net "M_K_CPU1_SA_DQ<19>")
	)
	(segment
		(start 174.961042 -217.997278)
		(end 174.961042 -217.931492)
		(width 0.14478)
		(layer "In6.Cu")
		(net "M_K_CPU1_SA_DQ<19>")
	)
	(segment
		(start 182.473346 -217.997278)
		(end 182.473346 -217.936572)
		(width 0.14478)
		(layer "In6.Cu")
		(net "M_K_CPU1_SA_DQ<19>")
	)
	(segment
		(start 144.487138 -236.061758)
		(end 144.498822 -236.0549)
		(width 0.0889)
		(layer "In6.Cu")
		(net "M_K_CPU1_SA_DQ<19>")
	)
	(segment
		(start 175.12411 -217.768424)
		(end 175.354488 -217.768424)
		(width 0.14478)
		(layer "In6.Cu")
		(net "M_K_CPU1_SA_DQ<19>")
	)
	(segment
		(start 191.91859 -217.941652)
		(end 192.081658 -217.778584)
		(width 0.14478)
		(layer "In6.Cu")
		(net "M_K_CPU1_SA_DQ<19>")
	)
	(segment
		(start 177.442622 -218.150948)
		(end 178.29276 -219.001086)
		(width 0.14478)
		(layer "In6.Cu")
		(net "M_K_CPU1_SA_DQ<19>")
	)
	(segment
		(start 160.124648 -223.543368)
		(end 160.124648 -222.640144)
		(width 0.14478)
		(layer "In6.Cu")
		(net "M_K_CPU1_SA_DQ<19>")
	)
	(segment
		(start 164.609018 -219.162122)
		(end 164.609018 -218.858846)
		(width 0.14478)
		(layer "In6.Cu")
		(net "M_K_CPU1_SA_DQ<19>")
	)
	(segment
		(start 192.475104 -217.941652)
		(end 192.475104 -217.997278)
		(width 0.14478)
		(layer "In6.Cu")
		(net "M_K_CPU1_SA_DQ<19>")
	)
	(segment
		(start 175.517556 -217.931492)
		(end 175.517556 -217.997278)
		(width 0.14478)
		(layer "In6.Cu")
		(net "M_K_CPU1_SA_DQ<19>")
	)
	(segment
		(start 166.066724 -219.010484)
		(end 166.916862 -218.160346)
		(width 0.14478)
		(layer "In6.Cu")
		(net "M_K_CPU1_SA_DQ<19>")
	)
	(segment
		(start 175.671226 -218.150948)
		(end 177.442622 -218.150948)
		(width 0.14478)
		(layer "In6.Cu")
		(net "M_K_CPU1_SA_DQ<19>")
	)
	(segment
		(start 147.115784 -234.674664)
		(end 147.705064 -234.085384)
		(width 0.0889)
		(layer "In6.Cu")
		(net "M_K_CPU1_SA_DQ<19>")
	)
	(segment
		(start 169.898568 -218.150948)
		(end 170.748706 -219.001086)
		(width 0.14478)
		(layer "In6.Cu")
		(net "M_K_CPU1_SA_DQ<19>")
	)
	(segment
		(start 182.473346 -217.936572)
		(end 182.636414 -217.773504)
		(width 0.14478)
		(layer "In6.Cu")
		(net "M_K_CPU1_SA_DQ<19>")
	)
	(segment
		(start 188.206634 -218.784932)
		(end 188.206634 -218.847416)
		(width 0.14478)
		(layer "In6.Cu")
		(net "M_K_CPU1_SA_DQ<19>")
	)
	(segment
		(start 164.753798 -218.714066)
		(end 165.015672 -218.714066)
		(width 0.14478)
		(layer "In6.Cu")
		(net "M_K_CPU1_SA_DQ<19>")
	)
	(segment
		(start 146.591528 -234.674664)
		(end 147.115784 -234.674664)
		(width 0.0889)
		(layer "In6.Cu")
		(net "M_K_CPU1_SA_DQ<19>")
	)
	(segment
		(start 182.866792 -217.773504)
		(end 183.02986 -217.936572)
		(width 0.14478)
		(layer "In6.Cu")
		(net "M_K_CPU1_SA_DQ<19>")
	)
	(segment
		(start 143.909796 -236.0549)
		(end 143.92148 -236.061758)
		(width 0.0889)
		(layer "In6.Cu")
		(net "M_K_CPU1_SA_DQ<19>")
	)
	(segment
		(start 167.598852 -217.997278)
		(end 167.598852 -217.931492)
		(width 0.14478)
		(layer "In6.Cu")
		(net "M_K_CPU1_SA_DQ<19>")
	)
	(segment
		(start 193.892678 -218.160346)
		(end 194.17919 -218.160346)
		(width 0.14478)
		(layer "In6.Cu")
		(net "M_K_CPU1_SA_DQ<19>")
	)
	(segment
		(start 193.010028 -218.160346)
		(end 193.173096 -218.323414)
		(width 0.14478)
		(layer "In6.Cu")
		(net "M_K_CPU1_SA_DQ<19>")
	)
	(segment
		(start 180.833268 -219.010484)
		(end 181.140862 -219.010484)
		(width 0.14478)
		(layer "In6.Cu")
		(net "M_K_CPU1_SA_DQ<19>")
	)
	(segment
		(start 185.83656 -219.001086)
		(end 187.49645 -219.001086)
		(width 0.14478)
		(layer "In6.Cu")
		(net "M_K_CPU1_SA_DQ<19>")
	)
	(segment
		(start 183.02986 -217.936572)
		(end 183.02986 -217.997278)
		(width 0.14478)
		(layer "In6.Cu")
		(net "M_K_CPU1_SA_DQ<19>")
	)
	(segment
		(start 169.268394 -217.931492)
		(end 169.268394 -217.997278)
		(width 0.14478)
		(layer "In6.Cu")
		(net "M_K_CPU1_SA_DQ<19>")
	)
	(segment
		(start 141.068806 -236.118908)
		(end 141.164818 -236.093508)
		(width 0.0889)
		(layer "In6.Cu")
		(net "M_K_CPU1_SA_DQ<19>")
	)
	(segment
		(start 164.057584 -219.155264)
		(end 164.057584 -219.162122)
		(width 0.14478)
		(layer "In6.Cu")
		(net "M_K_CPU1_SA_DQ<19>")
	)
	(segment
		(start 175.354488 -217.768424)
		(end 175.517556 -217.931492)
		(width 0.14478)
		(layer "In6.Cu")
		(net "M_K_CPU1_SA_DQ<19>")
	)
	(segment
		(start 145.45437 -236.093762)
		(end 146.375628 -235.172504)
		(width 0.0889)
		(layer "In6.Cu")
		(net "M_K_CPU1_SA_DQ<19>")
	)
	(segment
		(start 192.475104 -217.997278)
		(end 192.638172 -218.160346)
		(width 0.14478)
		(layer "In6.Cu")
		(net "M_K_CPU1_SA_DQ<19>")
	)
	(segment
		(start 140.914882 -236.384338)
		(end 141.068806 -236.118908)
		(width 0.0889)
		(layer "In6.Cu")
		(net "M_K_CPU1_SA_DQ<19>")
	)
	(segment
		(start 188.206634 -218.847416)
		(end 188.369702 -219.010484)
		(width 0.14478)
		(layer "In6.Cu")
		(net "M_K_CPU1_SA_DQ<19>")
	)
	(segment
		(start 188.043566 -218.621864)
		(end 188.206634 -218.784932)
		(width 0.14478)
		(layer "In6.Cu")
		(net "M_K_CPU1_SA_DQ<19>")
	)
	(segment
		(start 181.140862 -219.010484)
		(end 181.991 -218.160346)
		(width 0.14478)
		(layer "In6.Cu")
		(net "M_K_CPU1_SA_DQ<19>")
	)
	(segment
		(start 187.813188 -218.621864)
		(end 188.043566 -218.621864)
		(width 0.14478)
		(layer "In6.Cu")
		(net "M_K_CPU1_SA_DQ<19>")
	)
	(segment
		(start 149.582632 -234.085384)
		(end 160.124648 -223.543368)
		(width 0.14478)
		(layer "In6.Cu")
		(net "M_K_CPU1_SA_DQ<19>")
	)
	(segment
		(start 194.17919 -218.160346)
		(end 194.604132 -218.585288)
		(width 0.14478)
		(layer "In6.Cu")
		(net "M_K_CPU1_SA_DQ<19>")
	)
	(segment
		(start 174.459392 -218.160346)
		(end 174.797974 -218.160346)
		(width 0.14478)
		(layer "In6.Cu")
		(net "M_K_CPU1_SA_DQ<19>")
	)
	(segment
		(start 183.02986 -217.997278)
		(end 183.18353 -218.150948)
		(width 0.14478)
		(layer "In6.Cu")
		(net "M_K_CPU1_SA_DQ<19>")
	)
	(segment
		(start 181.991 -218.160346)
		(end 182.310278 -218.160346)
		(width 0.14478)
		(layer "In6.Cu")
		(net "M_K_CPU1_SA_DQ<19>")
	)
	(segment
		(start 166.916862 -218.160346)
		(end 167.435784 -218.160346)
		(width 0.14478)
		(layer "In6.Cu")
		(net "M_K_CPU1_SA_DQ<19>")
	)
	(segment
		(start 178.29276 -219.001086)
		(end 179.960016 -219.001086)
		(width 0.14478)
		(layer "In6.Cu")
		(net "M_K_CPU1_SA_DQ<19>")
	)
	(segment
		(start 165.160452 -218.865704)
		(end 165.305232 -219.010484)
		(width 0.14478)
		(layer "In6.Cu")
		(net "M_K_CPU1_SA_DQ<19>")
	)
	(segment
		(start 193.566542 -218.653106)
		(end 193.72961 -218.490038)
		(width 0.14478)
		(layer "In6.Cu")
		(net "M_K_CPU1_SA_DQ<19>")
	)
	(segment
		(start 180.276754 -218.621864)
		(end 180.507132 -218.621864)
		(width 0.14478)
		(layer "In6.Cu")
		(net "M_K_CPU1_SA_DQ<19>")
	)
	(segment
		(start 180.507132 -218.621864)
		(end 180.6702 -218.784932)
		(width 0.14478)
		(layer "In6.Cu")
		(net "M_K_CPU1_SA_DQ<19>")
	)
	(segment
		(start 174.797974 -218.160346)
		(end 174.961042 -217.997278)
		(width 0.14478)
		(layer "In6.Cu")
		(net "M_K_CPU1_SA_DQ<19>")
	)
	(segment
		(start 180.6702 -218.784932)
		(end 180.6702 -218.847416)
		(width 0.14478)
		(layer "In6.Cu")
		(net "M_K_CPU1_SA_DQ<19>")
	)
	(segment
		(start 173.618652 -219.001086)
		(end 174.459392 -218.160346)
		(width 0.14478)
		(layer "In6.Cu")
		(net "M_K_CPU1_SA_DQ<19>")
	)
	(segment
		(start 170.748706 -219.001086)
		(end 173.618652 -219.001086)
		(width 0.14478)
		(layer "In6.Cu")
		(net "M_K_CPU1_SA_DQ<19>")
	)
	(segment
		(start 164.202364 -219.306902)
		(end 164.464238 -219.306902)
		(width 0.14478)
		(layer "In6.Cu")
		(net "M_K_CPU1_SA_DQ<19>")
	)
	(segment
		(start 188.369702 -219.010484)
		(end 188.673232 -219.010484)
		(width 0.14478)
		(layer "In6.Cu")
		(net "M_K_CPU1_SA_DQ<19>")
	)
	(segment
		(start 180.113686 -218.847416)
		(end 180.113686 -218.784932)
		(width 0.14478)
		(layer "In6.Cu")
		(net "M_K_CPU1_SA_DQ<19>")
	)
	(segment
		(start 182.310278 -218.160346)
		(end 182.473346 -217.997278)
		(width 0.14478)
		(layer "In6.Cu")
		(net "M_K_CPU1_SA_DQ<19>")
	)
	(segment
		(start 163.912804 -219.010484)
		(end 164.057584 -219.155264)
		(width 0.14478)
		(layer "In6.Cu")
		(net "M_K_CPU1_SA_DQ<19>")
	)
	(segment
		(start 180.113686 -218.784932)
		(end 180.276754 -218.621864)
		(width 0.14478)
		(layer "In6.Cu")
		(net "M_K_CPU1_SA_DQ<19>")
	)
	(segment
		(start 169.105326 -217.768424)
		(end 169.268394 -217.931492)
		(width 0.14478)
		(layer "In6.Cu")
		(net "M_K_CPU1_SA_DQ<19>")
	)
	(segment
		(start 193.72961 -218.490038)
		(end 193.72961 -218.323414)
		(width 0.14478)
		(layer "In6.Cu")
		(net "M_K_CPU1_SA_DQ<19>")
	)
	(segment
		(start 145.363692 -236.093762)
		(end 145.45437 -236.093762)
		(width 0.0889)
		(layer "In6.Cu")
		(net "M_K_CPU1_SA_DQ<19>")
	)
	(segment
		(start 180.6702 -218.847416)
		(end 180.833268 -219.010484)
		(width 0.14478)
		(layer "In6.Cu")
		(net "M_K_CPU1_SA_DQ<19>")
	)
	(segment
		(start 147.980908 -234.085384)
		(end 149.582632 -234.085384)
		(width 0.14478)
		(layer "In6.Cu")
		(net "M_K_CPU1_SA_DQ<19>")
	)
	(segment
		(start 141.667738 -236.061758)
		(end 141.67612 -236.056932)
		(width 0.0889)
		(layer "In6.Cu")
		(net "M_K_CPU1_SA_DQ<19>")
	)
	(segment
		(start 182.636414 -217.773504)
		(end 182.866792 -217.773504)
		(width 0.14478)
		(layer "In6.Cu")
		(net "M_K_CPU1_SA_DQ<19>")
	)
	(segment
		(start 192.638172 -218.160346)
		(end 193.010028 -218.160346)
		(width 0.14478)
		(layer "In6.Cu")
		(net "M_K_CPU1_SA_DQ<19>")
	)
	(segment
		(start 163.754308 -219.010484)
		(end 163.912804 -219.010484)
		(width 0.14478)
		(layer "In6.Cu")
		(net "M_K_CPU1_SA_DQ<19>")
	)
	(segment
		(start 147.705064 -234.085384)
		(end 147.980908 -234.085384)
		(width 0.0889)
		(layer "In6.Cu")
		(net "M_K_CPU1_SA_DQ<19>")
	)
	(segment
		(start 167.435784 -218.160346)
		(end 167.598852 -217.997278)
		(width 0.14478)
		(layer "In6.Cu")
		(net "M_K_CPU1_SA_DQ<19>")
	)
	(segment
		(start 146.375628 -234.890564)
		(end 146.591528 -234.674664)
		(width 0.0889)
		(layer "In6.Cu")
		(net "M_K_CPU1_SA_DQ<19>")
	)
	(segment
		(start 167.598852 -217.931492)
		(end 167.76192 -217.768424)
		(width 0.14478)
		(layer "In6.Cu")
		(net "M_K_CPU1_SA_DQ<19>")
	)
	(segment
		(start 160.124648 -222.640144)
		(end 163.754308 -219.010484)
		(width 0.14478)
		(layer "In6.Cu")
		(net "M_K_CPU1_SA_DQ<19>")
	)
	(segment
		(start 187.49645 -219.001086)
		(end 187.65012 -218.847416)
		(width 0.14478)
		(layer "In6.Cu")
		(net "M_K_CPU1_SA_DQ<19>")
	)
	(segment
		(start 143.92148 -236.061758)
		(end 143.931894 -236.067854)
		(width 0.0889)
		(layer "In6.Cu")
		(net "M_K_CPU1_SA_DQ<19>")
	)
	(segment
		(start 174.961042 -217.931492)
		(end 175.12411 -217.768424)
		(width 0.14478)
		(layer "In6.Cu")
		(net "M_K_CPU1_SA_DQ<19>")
	)
	(segment
		(start 189.532768 -218.150948)
		(end 191.76492 -218.150948)
		(width 0.14478)
		(layer "In6.Cu")
		(net "M_K_CPU1_SA_DQ<19>")
	)
	(arc
		(start 141.67612 -236.056932)
		(mid 141.859628 -236.011438)
		(end 142.04188 -236.061758)
		(width 0.0889)
		(layer "In6.Cu")
		(net "M_K_CPU1_SA_DQ<19>")
	)
	(arc
		(start 143.931894 -236.067854)
		(mid 144.210326 -236.137952)
		(end 144.487138 -236.061758)
		(width 0.0889)
		(layer "In6.Cu")
		(net "M_K_CPU1_SA_DQ<19>")
	)
	(arc
		(start 144.861534 -236.061758)
		(mid 145.108848 -236.136918)
		(end 145.363692 -236.093762)
		(width 0.0889)
		(layer "In6.Cu")
		(net "M_K_CPU1_SA_DQ<19>")
	)
	(arc
		(start 142.607792 -236.061758)
		(mid 142.794736 -236.011503)
		(end 142.98168 -236.061758)
		(width 0.0889)
		(layer "In6.Cu")
		(net "M_K_CPU1_SA_DQ<19>")
	)
	(arc
		(start 142.04188 -236.061758)
		(mid 142.324836 -236.137935)
		(end 142.607792 -236.061758)
		(width 0.0889)
		(layer "In6.Cu")
		(net "M_K_CPU1_SA_DQ<19>")
	)
	(arc
		(start 142.98168 -236.061758)
		(mid 143.264636 -236.137935)
		(end 143.547592 -236.061758)
		(width 0.0889)
		(layer "In6.Cu")
		(net "M_K_CPU1_SA_DQ<19>")
	)
	(arc
		(start 141.164818 -236.093508)
		(mid 141.420026 -236.136985)
		(end 141.667738 -236.061758)
		(width 0.0889)
		(layer "In6.Cu")
		(net "M_K_CPU1_SA_DQ<19>")
	)
	(arc
		(start 143.547592 -236.061758)
		(mid 143.727797 -236.011441)
		(end 143.909796 -236.0549)
		(width 0.0889)
		(layer "In6.Cu")
		(net "M_K_CPU1_SA_DQ<19>")
	)
	(arc
		(start 144.498822 -236.0549)
		(mid 144.681077 -236.011247)
		(end 144.861534 -236.061758)
		(width 0.0889)
		(layer "In6.Cu")
		(net "M_K_CPU1_SA_DQ<19>")
	)
	(segment
		(start 141.857984 -235.84027)
		(end 142.324836 -235.574332)
		(width 0.10668)
		(layer "F.Cu")
		(net "M_K_CPU1_SA_DQ<18>")
	)
	(segment
		(start 173.166024 -217.147394)
		(end 173.329092 -217.310462)
		(width 0.14478)
		(layer "In6.Cu")
		(net "M_K_CPU1_SA_DQ<18>")
	)
	(segment
		(start 165.09746 -216.914984)
		(end 165.260528 -217.078052)
		(width 0.14478)
		(layer "In6.Cu")
		(net "M_K_CPU1_SA_DQ<18>")
	)
	(segment
		(start 188.673232 -217.310462)
		(end 189.52337 -216.460324)
		(width 0.14478)
		(layer "In6.Cu")
		(net "M_K_CPU1_SA_DQ<18>")
	)
	(segment
		(start 172.772578 -216.920064)
		(end 173.002956 -216.920064)
		(width 0.14478)
		(layer "In6.Cu")
		(net "M_K_CPU1_SA_DQ<18>")
	)
	(segment
		(start 165.260528 -217.147394)
		(end 165.423596 -217.310462)
		(width 0.14478)
		(layer "In6.Cu")
		(net "M_K_CPU1_SA_DQ<18>")
	)
	(segment
		(start 167.859964 -216.224866)
		(end 168.004744 -216.080086)
		(width 0.14478)
		(layer "In6.Cu")
		(net "M_K_CPU1_SA_DQ<18>")
	)
	(segment
		(start 174.775114 -216.460324)
		(end 174.938182 -216.297256)
		(width 0.14478)
		(layer "In6.Cu")
		(net "M_K_CPU1_SA_DQ<18>")
	)
	(segment
		(start 181.991 -216.460324)
		(end 182.352188 -216.460324)
		(width 0.14478)
		(layer "In6.Cu")
		(net "M_K_CPU1_SA_DQ<18>")
	)
	(segment
		(start 165.260528 -217.078052)
		(end 165.260528 -217.147394)
		(width 0.14478)
		(layer "In6.Cu")
		(net "M_K_CPU1_SA_DQ<18>")
	)
	(segment
		(start 192.601596 -216.079324)
		(end 192.831974 -216.079324)
		(width 0.14478)
		(layer "In6.Cu")
		(net "M_K_CPU1_SA_DQ<18>")
	)
	(segment
		(start 183.234838 -216.460324)
		(end 184.99582 -216.460324)
		(width 0.14478)
		(layer "In6.Cu")
		(net "M_K_CPU1_SA_DQ<18>")
	)
	(segment
		(start 169.514266 -216.315544)
		(end 169.659046 -216.460324)
		(width 0.14478)
		(layer "In6.Cu")
		(net "M_K_CPU1_SA_DQ<18>")
	)
	(segment
		(start 193.551556 -216.623392)
		(end 193.714624 -216.460324)
		(width 0.14478)
		(layer "In6.Cu")
		(net "M_K_CPU1_SA_DQ<18>")
	)
	(segment
		(start 168.266618 -216.080086)
		(end 168.411398 -216.224866)
		(width 0.14478)
		(layer "In6.Cu")
		(net "M_K_CPU1_SA_DQ<18>")
	)
	(segment
		(start 180.694076 -217.078052)
		(end 180.694076 -217.147394)
		(width 0.14478)
		(layer "In6.Cu")
		(net "M_K_CPU1_SA_DQ<18>")
	)
	(segment
		(start 164.704014 -217.078052)
		(end 164.867082 -216.914984)
		(width 0.14478)
		(layer "In6.Cu")
		(net "M_K_CPU1_SA_DQ<18>")
	)
	(segment
		(start 175.10125 -216.071704)
		(end 175.331628 -216.071704)
		(width 0.14478)
		(layer "In6.Cu")
		(net "M_K_CPU1_SA_DQ<18>")
	)
	(segment
		(start 168.411398 -216.224866)
		(end 168.411398 -216.315544)
		(width 0.14478)
		(layer "In6.Cu")
		(net "M_K_CPU1_SA_DQ<18>")
	)
	(segment
		(start 164.09543 -217.310462)
		(end 164.540946 -217.310462)
		(width 0.14478)
		(layer "In6.Cu")
		(net "M_K_CPU1_SA_DQ<18>")
	)
	(segment
		(start 170.758104 -217.310462)
		(end 172.446442 -217.310462)
		(width 0.14478)
		(layer "In6.Cu")
		(net "M_K_CPU1_SA_DQ<18>")
	)
	(segment
		(start 193.714624 -216.460324)
		(end 194.17919 -216.460324)
		(width 0.14478)
		(layer "In6.Cu")
		(net "M_K_CPU1_SA_DQ<18>")
	)
	(segment
		(start 168.962832 -216.315544)
		(end 168.962832 -216.224866)
		(width 0.14478)
		(layer "In6.Cu")
		(net "M_K_CPU1_SA_DQ<18>")
	)
	(segment
		(start 164.540946 -217.310462)
		(end 164.704014 -217.147394)
		(width 0.14478)
		(layer "In6.Cu")
		(net "M_K_CPU1_SA_DQ<18>")
	)
	(segment
		(start 180.531008 -216.914984)
		(end 180.694076 -217.078052)
		(width 0.14478)
		(layer "In6.Cu")
		(net "M_K_CPU1_SA_DQ<18>")
	)
	(segment
		(start 187.661042 -217.080592)
		(end 187.82411 -216.917524)
		(width 0.14478)
		(layer "In6.Cu")
		(net "M_K_CPU1_SA_DQ<18>")
	)
	(segment
		(start 169.107612 -216.080086)
		(end 169.369486 -216.080086)
		(width 0.14478)
		(layer "In6.Cu")
		(net "M_K_CPU1_SA_DQ<18>")
	)
	(segment
		(start 165.423596 -217.310462)
		(end 166.066724 -217.310462)
		(width 0.14478)
		(layer "In6.Cu")
		(net "M_K_CPU1_SA_DQ<18>")
	)
	(segment
		(start 147.952206 -233.176064)
		(end 149.205696 -233.176064)
		(width 0.14478)
		(layer "In6.Cu")
		(net "M_K_CPU1_SA_DQ<18>")
	)
	(segment
		(start 183.07177 -216.297256)
		(end 183.234838 -216.460324)
		(width 0.14478)
		(layer "In6.Cu")
		(net "M_K_CPU1_SA_DQ<18>")
	)
	(segment
		(start 194.17919 -216.460324)
		(end 194.604132 -216.885266)
		(width 0.14478)
		(layer "In6.Cu")
		(net "M_K_CPU1_SA_DQ<18>")
	)
	(segment
		(start 193.551556 -216.678256)
		(end 193.551556 -216.623392)
		(width 0.14478)
		(layer "In6.Cu")
		(net "M_K_CPU1_SA_DQ<18>")
	)
	(segment
		(start 193.388488 -216.841324)
		(end 193.551556 -216.678256)
		(width 0.14478)
		(layer "In6.Cu")
		(net "M_K_CPU1_SA_DQ<18>")
	)
	(segment
		(start 166.916862 -216.460324)
		(end 167.715184 -216.460324)
		(width 0.14478)
		(layer "In6.Cu")
		(net "M_K_CPU1_SA_DQ<18>")
	)
	(segment
		(start 146.510756 -234.103164)
		(end 146.866356 -234.103164)
		(width 0.0889)
		(layer "In6.Cu")
		(net "M_K_CPU1_SA_DQ<18>")
	)
	(segment
		(start 159.215328 -222.190564)
		(end 164.09543 -217.310462)
		(width 0.14478)
		(layer "In6.Cu")
		(net "M_K_CPU1_SA_DQ<18>")
	)
	(segment
		(start 187.497974 -217.310462)
		(end 187.661042 -217.147394)
		(width 0.14478)
		(layer "In6.Cu")
		(net "M_K_CPU1_SA_DQ<18>")
	)
	(segment
		(start 187.661042 -217.147394)
		(end 187.661042 -217.080592)
		(width 0.14478)
		(layer "In6.Cu")
		(net "M_K_CPU1_SA_DQ<18>")
	)
	(segment
		(start 142.47876 -235.308902)
		(end 142.574772 -235.283502)
		(width 0.0889)
		(layer "In6.Cu")
		(net "M_K_CPU1_SA_DQ<18>")
	)
	(segment
		(start 169.369486 -216.080086)
		(end 169.514266 -216.224866)
		(width 0.14478)
		(layer "In6.Cu")
		(net "M_K_CPU1_SA_DQ<18>")
	)
	(segment
		(start 166.066724 -217.310462)
		(end 166.916862 -216.460324)
		(width 0.14478)
		(layer "In6.Cu")
		(net "M_K_CPU1_SA_DQ<18>")
	)
	(segment
		(start 192.995042 -216.678256)
		(end 193.15811 -216.841324)
		(width 0.14478)
		(layer "In6.Cu")
		(net "M_K_CPU1_SA_DQ<18>")
	)
	(segment
		(start 175.657764 -216.460324)
		(end 177.45202 -216.460324)
		(width 0.14478)
		(layer "In6.Cu")
		(net "M_K_CPU1_SA_DQ<18>")
	)
	(segment
		(start 193.15811 -216.841324)
		(end 193.388488 -216.841324)
		(width 0.14478)
		(layer "In6.Cu")
		(net "M_K_CPU1_SA_DQ<18>")
	)
	(segment
		(start 182.908702 -216.071704)
		(end 183.07177 -216.234772)
		(width 0.14478)
		(layer "In6.Cu")
		(net "M_K_CPU1_SA_DQ<18>")
	)
	(segment
		(start 172.60951 -217.083132)
		(end 172.772578 -216.920064)
		(width 0.14478)
		(layer "In6.Cu")
		(net "M_K_CPU1_SA_DQ<18>")
	)
	(segment
		(start 175.494696 -216.234772)
		(end 175.494696 -216.297256)
		(width 0.14478)
		(layer "In6.Cu")
		(net "M_K_CPU1_SA_DQ<18>")
	)
	(segment
		(start 192.831974 -216.079324)
		(end 192.995042 -216.242392)
		(width 0.14478)
		(layer "In6.Cu")
		(net "M_K_CPU1_SA_DQ<18>")
	)
	(segment
		(start 169.659046 -216.460324)
		(end 169.907966 -216.460324)
		(width 0.14478)
		(layer "In6.Cu")
		(net "M_K_CPU1_SA_DQ<18>")
	)
	(segment
		(start 164.704014 -217.147394)
		(end 164.704014 -217.078052)
		(width 0.14478)
		(layer "In6.Cu")
		(net "M_K_CPU1_SA_DQ<18>")
	)
	(segment
		(start 180.137562 -217.078052)
		(end 180.30063 -216.914984)
		(width 0.14478)
		(layer "In6.Cu")
		(net "M_K_CPU1_SA_DQ<18>")
	)
	(segment
		(start 145.412714 -235.201206)
		(end 146.510756 -234.103164)
		(width 0.0889)
		(layer "In6.Cu")
		(net "M_K_CPU1_SA_DQ<18>")
	)
	(segment
		(start 188.054488 -216.917524)
		(end 188.217556 -217.080592)
		(width 0.14478)
		(layer "In6.Cu")
		(net "M_K_CPU1_SA_DQ<18>")
	)
	(segment
		(start 173.609254 -217.310462)
		(end 174.459392 -216.460324)
		(width 0.14478)
		(layer "In6.Cu")
		(net "M_K_CPU1_SA_DQ<18>")
	)
	(segment
		(start 145.144744 -235.201206)
		(end 145.412714 -235.201206)
		(width 0.0889)
		(layer "In6.Cu")
		(net "M_K_CPU1_SA_DQ<18>")
	)
	(segment
		(start 192.438528 -216.242392)
		(end 192.601596 -216.079324)
		(width 0.14478)
		(layer "In6.Cu")
		(net "M_K_CPU1_SA_DQ<18>")
	)
	(segment
		(start 149.205696 -233.176064)
		(end 159.215328 -223.166432)
		(width 0.14478)
		(layer "In6.Cu")
		(net "M_K_CPU1_SA_DQ<18>")
	)
	(segment
		(start 192.438528 -216.678256)
		(end 192.438528 -216.242392)
		(width 0.14478)
		(layer "In6.Cu")
		(net "M_K_CPU1_SA_DQ<18>")
	)
	(segment
		(start 188.217556 -217.147394)
		(end 188.380624 -217.310462)
		(width 0.14478)
		(layer "In6.Cu")
		(net "M_K_CPU1_SA_DQ<18>")
	)
	(segment
		(start 159.215328 -223.166432)
		(end 159.215328 -222.190564)
		(width 0.14478)
		(layer "In6.Cu")
		(net "M_K_CPU1_SA_DQ<18>")
	)
	(segment
		(start 173.166024 -217.083132)
		(end 173.166024 -217.147394)
		(width 0.14478)
		(layer "In6.Cu")
		(net "M_K_CPU1_SA_DQ<18>")
	)
	(segment
		(start 168.004744 -216.080086)
		(end 168.266618 -216.080086)
		(width 0.14478)
		(layer "In6.Cu")
		(net "M_K_CPU1_SA_DQ<18>")
	)
	(segment
		(start 177.45202 -216.460324)
		(end 178.302158 -217.310462)
		(width 0.14478)
		(layer "In6.Cu")
		(net "M_K_CPU1_SA_DQ<18>")
	)
	(segment
		(start 181.140862 -217.310462)
		(end 181.991 -216.460324)
		(width 0.14478)
		(layer "In6.Cu")
		(net "M_K_CPU1_SA_DQ<18>")
	)
	(segment
		(start 172.446442 -217.310462)
		(end 172.60951 -217.147394)
		(width 0.14478)
		(layer "In6.Cu")
		(net "M_K_CPU1_SA_DQ<18>")
	)
	(segment
		(start 180.857144 -217.310462)
		(end 181.140862 -217.310462)
		(width 0.14478)
		(layer "In6.Cu")
		(net "M_K_CPU1_SA_DQ<18>")
	)
	(segment
		(start 179.974494 -217.310462)
		(end 180.137562 -217.147394)
		(width 0.14478)
		(layer "In6.Cu")
		(net "M_K_CPU1_SA_DQ<18>")
	)
	(segment
		(start 192.27546 -216.841324)
		(end 192.438528 -216.678256)
		(width 0.14478)
		(layer "In6.Cu")
		(net "M_K_CPU1_SA_DQ<18>")
	)
	(segment
		(start 168.556178 -216.460324)
		(end 168.818052 -216.460324)
		(width 0.14478)
		(layer "In6.Cu")
		(net "M_K_CPU1_SA_DQ<18>")
	)
	(segment
		(start 192.995042 -216.242392)
		(end 192.995042 -216.678256)
		(width 0.14478)
		(layer "In6.Cu")
		(net "M_K_CPU1_SA_DQ<18>")
	)
	(segment
		(start 143.077692 -235.251752)
		(end 143.086074 -235.246926)
		(width 0.0889)
		(layer "In6.Cu")
		(net "M_K_CPU1_SA_DQ<18>")
	)
	(segment
		(start 184.99582 -216.460324)
		(end 185.845958 -217.310462)
		(width 0.14478)
		(layer "In6.Cu")
		(net "M_K_CPU1_SA_DQ<18>")
	)
	(segment
		(start 147.793456 -233.176064)
		(end 147.952206 -233.176064)
		(width 0.0889)
		(layer "In6.Cu")
		(net "M_K_CPU1_SA_DQ<18>")
	)
	(segment
		(start 173.002956 -216.920064)
		(end 173.166024 -217.083132)
		(width 0.14478)
		(layer "In6.Cu")
		(net "M_K_CPU1_SA_DQ<18>")
	)
	(segment
		(start 192.045082 -216.841324)
		(end 192.27546 -216.841324)
		(width 0.14478)
		(layer "In6.Cu")
		(net "M_K_CPU1_SA_DQ<18>")
	)
	(segment
		(start 168.962832 -216.224866)
		(end 169.107612 -216.080086)
		(width 0.14478)
		(layer "In6.Cu")
		(net "M_K_CPU1_SA_DQ<18>")
	)
	(segment
		(start 174.938182 -216.234772)
		(end 175.10125 -216.071704)
		(width 0.14478)
		(layer "In6.Cu")
		(net "M_K_CPU1_SA_DQ<18>")
	)
	(segment
		(start 172.60951 -217.147394)
		(end 172.60951 -217.083132)
		(width 0.14478)
		(layer "In6.Cu")
		(net "M_K_CPU1_SA_DQ<18>")
	)
	(segment
		(start 191.882014 -216.623392)
		(end 191.882014 -216.678256)
		(width 0.14478)
		(layer "In6.Cu")
		(net "M_K_CPU1_SA_DQ<18>")
	)
	(segment
		(start 180.694076 -217.147394)
		(end 180.857144 -217.310462)
		(width 0.14478)
		(layer "In6.Cu")
		(net "M_K_CPU1_SA_DQ<18>")
	)
	(segment
		(start 169.907966 -216.460324)
		(end 170.758104 -217.310462)
		(width 0.14478)
		(layer "In6.Cu")
		(net "M_K_CPU1_SA_DQ<18>")
	)
	(segment
		(start 144.007078 -235.257848)
		(end 144.017492 -235.251752)
		(width 0.0889)
		(layer "In6.Cu")
		(net "M_K_CPU1_SA_DQ<18>")
	)
	(segment
		(start 182.352188 -216.460324)
		(end 182.515256 -216.297256)
		(width 0.14478)
		(layer "In6.Cu")
		(net "M_K_CPU1_SA_DQ<18>")
	)
	(segment
		(start 185.845958 -217.310462)
		(end 187.497974 -217.310462)
		(width 0.14478)
		(layer "In6.Cu")
		(net "M_K_CPU1_SA_DQ<18>")
	)
	(segment
		(start 189.52337 -216.460324)
		(end 191.718946 -216.460324)
		(width 0.14478)
		(layer "In6.Cu")
		(net "M_K_CPU1_SA_DQ<18>")
	)
	(segment
		(start 168.411398 -216.315544)
		(end 168.556178 -216.460324)
		(width 0.14478)
		(layer "In6.Cu")
		(net "M_K_CPU1_SA_DQ<18>")
	)
	(segment
		(start 180.30063 -216.914984)
		(end 180.531008 -216.914984)
		(width 0.14478)
		(layer "In6.Cu")
		(net "M_K_CPU1_SA_DQ<18>")
	)
	(segment
		(start 191.882014 -216.678256)
		(end 192.045082 -216.841324)
		(width 0.14478)
		(layer "In6.Cu")
		(net "M_K_CPU1_SA_DQ<18>")
	)
	(segment
		(start 178.302158 -217.310462)
		(end 179.974494 -217.310462)
		(width 0.14478)
		(layer "In6.Cu")
		(net "M_K_CPU1_SA_DQ<18>")
	)
	(segment
		(start 182.515256 -216.297256)
		(end 182.515256 -216.234772)
		(width 0.14478)
		(layer "In6.Cu")
		(net "M_K_CPU1_SA_DQ<18>")
	)
	(segment
		(start 164.867082 -216.914984)
		(end 165.09746 -216.914984)
		(width 0.14478)
		(layer "In6.Cu")
		(net "M_K_CPU1_SA_DQ<18>")
	)
	(segment
		(start 169.514266 -216.224866)
		(end 169.514266 -216.315544)
		(width 0.14478)
		(layer "In6.Cu")
		(net "M_K_CPU1_SA_DQ<18>")
	)
	(segment
		(start 188.380624 -217.310462)
		(end 188.673232 -217.310462)
		(width 0.14478)
		(layer "In6.Cu")
		(net "M_K_CPU1_SA_DQ<18>")
	)
	(segment
		(start 168.818052 -216.460324)
		(end 168.962832 -216.315544)
		(width 0.14478)
		(layer "In6.Cu")
		(net "M_K_CPU1_SA_DQ<18>")
	)
	(segment
		(start 173.329092 -217.310462)
		(end 173.609254 -217.310462)
		(width 0.14478)
		(layer "In6.Cu")
		(net "M_K_CPU1_SA_DQ<18>")
	)
	(segment
		(start 175.494696 -216.297256)
		(end 175.657764 -216.460324)
		(width 0.14478)
		(layer "In6.Cu")
		(net "M_K_CPU1_SA_DQ<18>")
	)
	(segment
		(start 144.39138 -235.251752)
		(end 144.401794 -235.257848)
		(width 0.0889)
		(layer "In6.Cu")
		(net "M_K_CPU1_SA_DQ<18>")
	)
	(segment
		(start 167.859964 -216.315544)
		(end 167.859964 -216.224866)
		(width 0.14478)
		(layer "In6.Cu")
		(net "M_K_CPU1_SA_DQ<18>")
	)
	(segment
		(start 182.515256 -216.234772)
		(end 182.678324 -216.071704)
		(width 0.14478)
		(layer "In6.Cu")
		(net "M_K_CPU1_SA_DQ<18>")
	)
	(segment
		(start 183.07177 -216.234772)
		(end 183.07177 -216.297256)
		(width 0.14478)
		(layer "In6.Cu")
		(net "M_K_CPU1_SA_DQ<18>")
	)
	(segment
		(start 142.324836 -235.574332)
		(end 142.47876 -235.308902)
		(width 0.0889)
		(layer "In6.Cu")
		(net "M_K_CPU1_SA_DQ<18>")
	)
	(segment
		(start 191.718946 -216.460324)
		(end 191.882014 -216.623392)
		(width 0.14478)
		(layer "In6.Cu")
		(net "M_K_CPU1_SA_DQ<18>")
	)
	(segment
		(start 180.137562 -217.147394)
		(end 180.137562 -217.078052)
		(width 0.14478)
		(layer "In6.Cu")
		(net "M_K_CPU1_SA_DQ<18>")
	)
	(segment
		(start 187.82411 -216.917524)
		(end 188.054488 -216.917524)
		(width 0.14478)
		(layer "In6.Cu")
		(net "M_K_CPU1_SA_DQ<18>")
	)
	(segment
		(start 174.459392 -216.460324)
		(end 174.775114 -216.460324)
		(width 0.14478)
		(layer "In6.Cu")
		(net "M_K_CPU1_SA_DQ<18>")
	)
	(segment
		(start 188.217556 -217.080592)
		(end 188.217556 -217.147394)
		(width 0.14478)
		(layer "In6.Cu")
		(net "M_K_CPU1_SA_DQ<18>")
	)
	(segment
		(start 167.715184 -216.460324)
		(end 167.859964 -216.315544)
		(width 0.14478)
		(layer "In6.Cu")
		(net "M_K_CPU1_SA_DQ<18>")
	)
	(segment
		(start 182.678324 -216.071704)
		(end 182.908702 -216.071704)
		(width 0.14478)
		(layer "In6.Cu")
		(net "M_K_CPU1_SA_DQ<18>")
	)
	(segment
		(start 146.866356 -234.103164)
		(end 147.793456 -233.176064)
		(width 0.0889)
		(layer "In6.Cu")
		(net "M_K_CPU1_SA_DQ<18>")
	)
	(segment
		(start 175.331628 -216.071704)
		(end 175.494696 -216.234772)
		(width 0.14478)
		(layer "In6.Cu")
		(net "M_K_CPU1_SA_DQ<18>")
	)
	(segment
		(start 174.938182 -216.297256)
		(end 174.938182 -216.234772)
		(width 0.14478)
		(layer "In6.Cu")
		(net "M_K_CPU1_SA_DQ<18>")
	)
	(arc
		(start 144.401794 -235.257848)
		(mid 144.68048 -235.328068)
		(end 144.957546 -235.251752)
		(width 0.0889)
		(layer "In6.Cu")
		(net "M_K_CPU1_SA_DQ<18>")
	)
	(arc
		(start 142.574772 -235.283502)
		(mid 142.82998 -235.326979)
		(end 143.077692 -235.251752)
		(width 0.0889)
		(layer "In6.Cu")
		(net "M_K_CPU1_SA_DQ<18>")
	)
	(arc
		(start 144.017492 -235.251752)
		(mid 144.204436 -235.201497)
		(end 144.39138 -235.251752)
		(width 0.0889)
		(layer "In6.Cu")
		(net "M_K_CPU1_SA_DQ<18>")
	)
	(arc
		(start 143.086074 -235.246926)
		(mid 143.269582 -235.201432)
		(end 143.451834 -235.251752)
		(width 0.0889)
		(layer "In6.Cu")
		(net "M_K_CPU1_SA_DQ<18>")
	)
	(arc
		(start 143.451834 -235.251752)
		(mid 143.728647 -235.327895)
		(end 144.007078 -235.257848)
		(width 0.0889)
		(layer "In6.Cu")
		(net "M_K_CPU1_SA_DQ<18>")
	)
	(arc
		(start 144.957546 -235.251752)
		(mid 145.047806 -235.214124)
		(end 145.144744 -235.201206)
		(width 0.0889)
		(layer "In6.Cu")
		(net "M_K_CPU1_SA_DQ<18>")
	)
	(segment
		(start 140.91793 -235.84027)
		(end 141.384782 -235.574332)
		(width 0.10668)
		(layer "F.Cu")
		(net "M_K_CPU1_SA_DQ<17>")
	)
	(segment
		(start 174.459138 -217.310462)
		(end 177.452274 -217.310462)
		(width 0.14478)
		(layer "In6.Cu")
		(net "M_K_CPU1_SA_DQ<17>")
	)
	(segment
		(start 180.297074 -218.160346)
		(end 181.737508 -217.5637)
		(width 0.14478)
		(layer "In6.Cu")
		(net "M_K_CPU1_SA_DQ<17>")
	)
	(segment
		(start 187.84316 -218.160346)
		(end 189.478666 -217.482928)
		(width 0.14478)
		(layer "In6.Cu")
		(net "M_K_CPU1_SA_DQ<17>")
	)
	(segment
		(start 173.609254 -218.160346)
		(end 174.459138 -217.310462)
		(width 0.14478)
		(layer "In6.Cu")
		(net "M_K_CPU1_SA_DQ<17>")
	)
	(segment
		(start 146.172428 -235.07954)
		(end 146.172428 -234.763564)
		(width 0.0889)
		(layer "In6.Cu")
		(net "M_K_CPU1_SA_DQ<17>")
	)
	(segment
		(start 178.302158 -218.160346)
		(end 180.297074 -218.160346)
		(width 0.14478)
		(layer "In6.Cu")
		(net "M_K_CPU1_SA_DQ<17>")
	)
	(segment
		(start 147.980908 -233.630724)
		(end 149.394164 -233.630724)
		(width 0.14478)
		(layer "In6.Cu")
		(net "M_K_CPU1_SA_DQ<17>")
	)
	(segment
		(start 198.279258 -217.310462)
		(end 198.7042 -217.735404)
		(width 0.14478)
		(layer "In6.Cu")
		(net "M_K_CPU1_SA_DQ<17>")
	)
	(segment
		(start 170.758104 -218.160346)
		(end 173.609254 -218.160346)
		(width 0.14478)
		(layer "In6.Cu")
		(net "M_K_CPU1_SA_DQ<17>")
	)
	(segment
		(start 146.172428 -234.763564)
		(end 146.477228 -234.458764)
		(width 0.0889)
		(layer "In6.Cu")
		(net "M_K_CPU1_SA_DQ<17>")
	)
	(segment
		(start 144.391126 -235.896912)
		(end 144.40154 -235.890816)
		(width 0.0889)
		(layer "In6.Cu")
		(net "M_K_CPU1_SA_DQ<17>")
	)
	(segment
		(start 182.348886 -217.310462)
		(end 184.610756 -217.310462)
		(width 0.14478)
		(layer "In6.Cu")
		(net "M_K_CPU1_SA_DQ<17>")
	)
	(segment
		(start 169.907966 -217.310208)
		(end 170.758104 -218.160346)
		(width 0.14478)
		(layer "In6.Cu")
		(net "M_K_CPU1_SA_DQ<17>")
	)
	(segment
		(start 143.077692 -235.896912)
		(end 143.086074 -235.901738)
		(width 0.0889)
		(layer "In6.Cu")
		(net "M_K_CPU1_SA_DQ<17>")
	)
	(segment
		(start 147.813268 -233.630724)
		(end 147.980908 -233.630724)
		(width 0.0889)
		(layer "In6.Cu")
		(net "M_K_CPU1_SA_DQ<17>")
	)
	(segment
		(start 166.106348 -218.160346)
		(end 166.956486 -217.310208)
		(width 0.14478)
		(layer "In6.Cu")
		(net "M_K_CPU1_SA_DQ<17>")
	)
	(segment
		(start 146.477228 -234.458764)
		(end 146.985228 -234.458764)
		(width 0.0889)
		(layer "In6.Cu")
		(net "M_K_CPU1_SA_DQ<17>")
	)
	(segment
		(start 166.956486 -217.310208)
		(end 169.907966 -217.310208)
		(width 0.14478)
		(layer "In6.Cu")
		(net "M_K_CPU1_SA_DQ<17>")
	)
	(segment
		(start 159.669988 -223.3549)
		(end 159.669988 -222.403924)
		(width 0.14478)
		(layer "In6.Cu")
		(net "M_K_CPU1_SA_DQ<17>")
	)
	(segment
		(start 177.452274 -217.310462)
		(end 178.302158 -218.160346)
		(width 0.14478)
		(layer "In6.Cu")
		(net "M_K_CPU1_SA_DQ<17>")
	)
	(segment
		(start 142.503398 -235.901738)
		(end 142.51178 -235.896912)
		(width 0.0889)
		(layer "In6.Cu")
		(net "M_K_CPU1_SA_DQ<17>")
	)
	(segment
		(start 141.230858 -235.839762)
		(end 141.25321 -235.923074)
		(width 0.0889)
		(layer "In6.Cu")
		(net "M_K_CPU1_SA_DQ<17>")
	)
	(segment
		(start 181.737508 -217.5637)
		(end 182.348886 -217.310462)
		(width 0.14478)
		(layer "In6.Cu")
		(net "M_K_CPU1_SA_DQ<17>")
	)
	(segment
		(start 141.384782 -235.574332)
		(end 141.230858 -235.839762)
		(width 0.0889)
		(layer "In6.Cu")
		(net "M_K_CPU1_SA_DQ<17>")
	)
	(segment
		(start 146.985228 -234.458764)
		(end 147.813268 -233.630724)
		(width 0.0889)
		(layer "In6.Cu")
		(net "M_K_CPU1_SA_DQ<17>")
	)
	(segment
		(start 144.017492 -235.896912)
		(end 144.025874 -235.901738)
		(width 0.0889)
		(layer "In6.Cu")
		(net "M_K_CPU1_SA_DQ<17>")
	)
	(segment
		(start 144.007078 -235.890816)
		(end 144.017492 -235.896912)
		(width 0.0889)
		(layer "In6.Cu")
		(net "M_K_CPU1_SA_DQ<17>")
	)
	(segment
		(start 189.895226 -217.310462)
		(end 198.279258 -217.310462)
		(width 0.14478)
		(layer "In6.Cu")
		(net "M_K_CPU1_SA_DQ<17>")
	)
	(segment
		(start 163.913566 -218.160346)
		(end 166.106348 -218.160346)
		(width 0.14478)
		(layer "In6.Cu")
		(net "M_K_CPU1_SA_DQ<17>")
	)
	(segment
		(start 189.478666 -217.482928)
		(end 189.895226 -217.310462)
		(width 0.14478)
		(layer "In6.Cu")
		(net "M_K_CPU1_SA_DQ<17>")
	)
	(segment
		(start 186.663076 -218.160346)
		(end 187.84316 -218.160346)
		(width 0.14478)
		(layer "In6.Cu")
		(net "M_K_CPU1_SA_DQ<17>")
	)
	(segment
		(start 145.331434 -235.896658)
		(end 145.389854 -235.862114)
		(width 0.0889)
		(layer "In6.Cu")
		(net "M_K_CPU1_SA_DQ<17>")
	)
	(segment
		(start 145.313146 -235.907072)
		(end 145.331434 -235.896658)
		(width 0.0889)
		(layer "In6.Cu")
		(net "M_K_CPU1_SA_DQ<17>")
	)
	(segment
		(start 149.394164 -233.630724)
		(end 159.669988 -223.3549)
		(width 0.14478)
		(layer "In6.Cu")
		(net "M_K_CPU1_SA_DQ<17>")
	)
	(segment
		(start 159.669988 -222.403924)
		(end 163.913566 -218.160346)
		(width 0.14478)
		(layer "In6.Cu")
		(net "M_K_CPU1_SA_DQ<17>")
	)
	(segment
		(start 145.389854 -235.862114)
		(end 146.172428 -235.07954)
		(width 0.0889)
		(layer "In6.Cu")
		(net "M_K_CPU1_SA_DQ<17>")
	)
	(segment
		(start 184.610756 -217.310462)
		(end 186.663076 -218.160346)
		(width 0.14478)
		(layer "In6.Cu")
		(net "M_K_CPU1_SA_DQ<17>")
	)
	(arc
		(start 144.957292 -235.896912)
		(mid 145.13392 -235.947145)
		(end 145.313146 -235.907072)
		(width 0.0889)
		(layer "In6.Cu")
		(net "M_K_CPU1_SA_DQ<17>")
	)
	(arc
		(start 142.51178 -235.896912)
		(mid 142.794736 -235.820735)
		(end 143.077692 -235.896912)
		(width 0.0889)
		(layer "In6.Cu")
		(net "M_K_CPU1_SA_DQ<17>")
	)
	(arc
		(start 142.137638 -235.896912)
		(mid 142.319889 -235.947262)
		(end 142.503398 -235.901738)
		(width 0.0889)
		(layer "In6.Cu")
		(net "M_K_CPU1_SA_DQ<17>")
	)
	(arc
		(start 144.025874 -235.901738)
		(mid 144.209128 -235.947111)
		(end 144.391126 -235.896912)
		(width 0.0889)
		(layer "In6.Cu")
		(net "M_K_CPU1_SA_DQ<17>")
	)
	(arc
		(start 141.571726 -235.896912)
		(mid 141.854682 -235.820735)
		(end 142.137638 -235.896912)
		(width 0.0889)
		(layer "In6.Cu")
		(net "M_K_CPU1_SA_DQ<17>")
	)
	(arc
		(start 143.451834 -235.896912)
		(mid 143.728647 -235.820769)
		(end 144.007078 -235.890816)
		(width 0.0889)
		(layer "In6.Cu")
		(net "M_K_CPU1_SA_DQ<17>")
	)
	(arc
		(start 141.25321 -235.923074)
		(mid 141.415399 -235.945809)
		(end 141.571726 -235.896912)
		(width 0.0889)
		(layer "In6.Cu")
		(net "M_K_CPU1_SA_DQ<17>")
	)
	(arc
		(start 144.40154 -235.890816)
		(mid 144.680226 -235.820596)
		(end 144.957292 -235.896912)
		(width 0.0889)
		(layer "In6.Cu")
		(net "M_K_CPU1_SA_DQ<17>")
	)
	(arc
		(start 143.086074 -235.901738)
		(mid 143.269582 -235.947232)
		(end 143.451834 -235.896912)
		(width 0.0889)
		(layer "In6.Cu")
		(net "M_K_CPU1_SA_DQ<17>")
	)
	(segment
		(start 142.327884 -235.030264)
		(end 142.794736 -234.764326)
		(width 0.10668)
		(layer "F.Cu")
		(net "M_K_CPU1_SA_DQ<16>")
	)
	(segment
		(start 147.655788 -232.721404)
		(end 147.980908 -232.721404)
		(width 0.0889)
		(layer "In6.Cu")
		(net "M_K_CPU1_SA_DQ<16>")
	)
	(segment
		(start 188.801248 -216.460324)
		(end 189.651132 -215.61044)
		(width 0.14478)
		(layer "In6.Cu")
		(net "M_K_CPU1_SA_DQ<16>")
	)
	(segment
		(start 196.779388 -215.773508)
		(end 196.942456 -215.61044)
		(width 0.14478)
		(layer "In6.Cu")
		(net "M_K_CPU1_SA_DQ<16>")
	)
	(segment
		(start 177.452274 -215.61044)
		(end 178.302158 -216.460324)
		(width 0.14478)
		(layer "In6.Cu")
		(net "M_K_CPU1_SA_DQ<16>")
	)
	(segment
		(start 142.640812 -235.029756)
		(end 142.663164 -235.113068)
		(width 0.0889)
		(layer "In6.Cu")
		(net "M_K_CPU1_SA_DQ<16>")
	)
	(segment
		(start 145.14449 -235.010706)
		(end 145.322036 -235.010706)
		(width 0.0889)
		(layer "In6.Cu")
		(net "M_K_CPU1_SA_DQ<16>")
	)
	(segment
		(start 166.956486 -215.610186)
		(end 169.907966 -215.610186)
		(width 0.14478)
		(layer "In6.Cu")
		(net "M_K_CPU1_SA_DQ<16>")
	)
	(segment
		(start 184.996074 -215.61044)
		(end 185.845958 -216.460324)
		(width 0.14478)
		(layer "In6.Cu")
		(net "M_K_CPU1_SA_DQ<16>")
	)
	(segment
		(start 147.137628 -233.239564)
		(end 147.655788 -232.721404)
		(width 0.0889)
		(layer "In6.Cu")
		(net "M_K_CPU1_SA_DQ<16>")
	)
	(segment
		(start 185.845958 -216.460324)
		(end 188.801248 -216.460324)
		(width 0.14478)
		(layer "In6.Cu")
		(net "M_K_CPU1_SA_DQ<16>")
	)
	(segment
		(start 146.772884 -233.899964)
		(end 147.137628 -233.53522)
		(width 0.0889)
		(layer "In6.Cu")
		(net "M_K_CPU1_SA_DQ<16>")
	)
	(segment
		(start 196.059806 -215.61044)
		(end 196.222874 -215.773508)
		(width 0.14478)
		(layer "In6.Cu")
		(net "M_K_CPU1_SA_DQ<16>")
	)
	(segment
		(start 181.140862 -216.460324)
		(end 181.990746 -215.61044)
		(width 0.14478)
		(layer "In6.Cu")
		(net "M_K_CPU1_SA_DQ<16>")
	)
	(segment
		(start 181.990746 -215.61044)
		(end 184.996074 -215.61044)
		(width 0.14478)
		(layer "In6.Cu")
		(net "M_K_CPU1_SA_DQ<16>")
	)
	(segment
		(start 158.760668 -222.977964)
		(end 158.760668 -221.939104)
		(width 0.14478)
		(layer "In6.Cu")
		(net "M_K_CPU1_SA_DQ<16>")
	)
	(segment
		(start 189.651132 -215.61044)
		(end 196.059806 -215.61044)
		(width 0.14478)
		(layer "In6.Cu")
		(net "M_K_CPU1_SA_DQ<16>")
	)
	(segment
		(start 145.322036 -235.010706)
		(end 146.432778 -233.899964)
		(width 0.0889)
		(layer "In6.Cu")
		(net "M_K_CPU1_SA_DQ<16>")
	)
	(segment
		(start 169.907966 -215.610186)
		(end 170.758104 -216.460324)
		(width 0.14478)
		(layer "In6.Cu")
		(net "M_K_CPU1_SA_DQ<16>")
	)
	(segment
		(start 196.942456 -215.61044)
		(end 198.279258 -215.61044)
		(width 0.14478)
		(layer "In6.Cu")
		(net "M_K_CPU1_SA_DQ<16>")
	)
	(segment
		(start 143.913352 -235.091732)
		(end 143.921734 -235.086906)
		(width 0.0889)
		(layer "In6.Cu")
		(net "M_K_CPU1_SA_DQ<16>")
	)
	(segment
		(start 166.106348 -216.460324)
		(end 166.956486 -215.610186)
		(width 0.14478)
		(layer "In6.Cu")
		(net "M_K_CPU1_SA_DQ<16>")
	)
	(segment
		(start 196.222874 -215.890856)
		(end 196.385942 -216.053924)
		(width 0.14478)
		(layer "In6.Cu")
		(net "M_K_CPU1_SA_DQ<16>")
	)
	(segment
		(start 149.017228 -232.721404)
		(end 158.760668 -222.977964)
		(width 0.14478)
		(layer "In6.Cu")
		(net "M_K_CPU1_SA_DQ<16>")
	)
	(segment
		(start 143.921734 -235.086906)
		(end 143.932148 -235.08081)
		(width 0.0889)
		(layer "In6.Cu")
		(net "M_K_CPU1_SA_DQ<16>")
	)
	(segment
		(start 196.385942 -216.053924)
		(end 196.61632 -216.053924)
		(width 0.14478)
		(layer "In6.Cu")
		(net "M_K_CPU1_SA_DQ<16>")
	)
	(segment
		(start 196.779388 -215.890856)
		(end 196.779388 -215.773508)
		(width 0.14478)
		(layer "In6.Cu")
		(net "M_K_CPU1_SA_DQ<16>")
	)
	(segment
		(start 158.760668 -221.939104)
		(end 164.239448 -216.460324)
		(width 0.14478)
		(layer "In6.Cu")
		(net "M_K_CPU1_SA_DQ<16>")
	)
	(segment
		(start 178.302158 -216.460324)
		(end 181.140862 -216.460324)
		(width 0.14478)
		(layer "In6.Cu")
		(net "M_K_CPU1_SA_DQ<16>")
	)
	(segment
		(start 147.980908 -232.721404)
		(end 149.017228 -232.721404)
		(width 0.14478)
		(layer "In6.Cu")
		(net "M_K_CPU1_SA_DQ<16>")
	)
	(segment
		(start 196.222874 -215.773508)
		(end 196.222874 -215.890856)
		(width 0.14478)
		(layer "In6.Cu")
		(net "M_K_CPU1_SA_DQ<16>")
	)
	(segment
		(start 196.61632 -216.053924)
		(end 196.779388 -215.890856)
		(width 0.14478)
		(layer "In6.Cu")
		(net "M_K_CPU1_SA_DQ<16>")
	)
	(segment
		(start 147.137628 -233.53522)
		(end 147.137628 -233.239564)
		(width 0.0889)
		(layer "In6.Cu")
		(net "M_K_CPU1_SA_DQ<16>")
	)
	(segment
		(start 198.279258 -215.61044)
		(end 198.7042 -216.035382)
		(width 0.14478)
		(layer "In6.Cu")
		(net "M_K_CPU1_SA_DQ<16>")
	)
	(segment
		(start 144.487392 -235.086906)
		(end 144.495774 -235.091732)
		(width 0.0889)
		(layer "In6.Cu")
		(net "M_K_CPU1_SA_DQ<16>")
	)
	(segment
		(start 174.459138 -215.61044)
		(end 177.452274 -215.61044)
		(width 0.14478)
		(layer "In6.Cu")
		(net "M_K_CPU1_SA_DQ<16>")
	)
	(segment
		(start 170.758104 -216.460324)
		(end 173.609254 -216.460324)
		(width 0.14478)
		(layer "In6.Cu")
		(net "M_K_CPU1_SA_DQ<16>")
	)
	(segment
		(start 164.239448 -216.460324)
		(end 166.106348 -216.460324)
		(width 0.14478)
		(layer "In6.Cu")
		(net "M_K_CPU1_SA_DQ<16>")
	)
	(segment
		(start 142.794736 -234.764326)
		(end 142.640812 -235.029756)
		(width 0.0889)
		(layer "In6.Cu")
		(net "M_K_CPU1_SA_DQ<16>")
	)
	(segment
		(start 146.432778 -233.899964)
		(end 146.772884 -233.899964)
		(width 0.0889)
		(layer "In6.Cu")
		(net "M_K_CPU1_SA_DQ<16>")
	)
	(segment
		(start 173.609254 -216.460324)
		(end 174.459138 -215.61044)
		(width 0.14478)
		(layer "In6.Cu")
		(net "M_K_CPU1_SA_DQ<16>")
	)
	(arc
		(start 142.663164 -235.113068)
		(mid 142.825353 -235.135803)
		(end 142.98168 -235.086906)
		(width 0.0889)
		(layer "In6.Cu")
		(net "M_K_CPU1_SA_DQ<16>")
	)
	(arc
		(start 143.932148 -235.08081)
		(mid 144.21058 -235.010712)
		(end 144.487392 -235.086906)
		(width 0.0889)
		(layer "In6.Cu")
		(net "M_K_CPU1_SA_DQ<16>")
	)
	(arc
		(start 142.98168 -235.086906)
		(mid 143.264636 -235.010729)
		(end 143.547592 -235.086906)
		(width 0.0889)
		(layer "In6.Cu")
		(net "M_K_CPU1_SA_DQ<16>")
	)
	(arc
		(start 144.861534 -235.086906)
		(mid 144.997975 -235.030106)
		(end 145.14449 -235.010706)
		(width 0.0889)
		(layer "In6.Cu")
		(net "M_K_CPU1_SA_DQ<16>")
	)
	(arc
		(start 143.547592 -235.086906)
		(mid 143.729843 -235.137256)
		(end 143.913352 -235.091732)
		(width 0.0889)
		(layer "In6.Cu")
		(net "M_K_CPU1_SA_DQ<16>")
	)
	(arc
		(start 144.495774 -235.091732)
		(mid 144.679282 -235.137226)
		(end 144.861534 -235.086906)
		(width 0.0889)
		(layer "In6.Cu")
		(net "M_K_CPU1_SA_DQ<16>")
	)
	(segment
		(start 140.447776 -235.030264)
		(end 140.914882 -234.764326)
		(width 0.10668)
		(layer "F.Cu")
		(net "M_K_CPU1_SA_DQ<15>")
	)
	(segment
		(start 192.94602 -214.597234)
		(end 192.94602 -214.532972)
		(width 0.14478)
		(layer "In6.Cu")
		(net "M_K_CPU1_SA_DQ<15>")
	)
	(segment
		(start 141.068806 -234.498896)
		(end 141.164818 -234.473496)
		(width 0.0889)
		(layer "In6.Cu")
		(net "M_K_CPU1_SA_DQ<15>")
	)
	(segment
		(start 192.389506 -214.532972)
		(end 192.389506 -214.597234)
		(width 0.14478)
		(layer "In6.Cu")
		(net "M_K_CPU1_SA_DQ<15>")
	)
	(segment
		(start 191.669924 -214.760302)
		(end 191.832992 -214.597234)
		(width 0.14478)
		(layer "In6.Cu")
		(net "M_K_CPU1_SA_DQ<15>")
	)
	(segment
		(start 140.914882 -234.764326)
		(end 141.068806 -234.498896)
		(width 0.0889)
		(layer "In6.Cu")
		(net "M_K_CPU1_SA_DQ<15>")
	)
	(segment
		(start 148.787612 -232.157524)
		(end 149.016466 -231.92867)
		(width 0.0889)
		(layer "In6.Cu")
		(net "M_K_CPU1_SA_DQ<15>")
	)
	(segment
		(start 184.99582 -214.760302)
		(end 185.845958 -215.61044)
		(width 0.14478)
		(layer "In6.Cu")
		(net "M_K_CPU1_SA_DQ<15>")
	)
	(segment
		(start 180.003958 -215.61044)
		(end 180.167026 -215.447372)
		(width 0.14478)
		(layer "In6.Cu")
		(net "M_K_CPU1_SA_DQ<15>")
	)
	(segment
		(start 165.063678 -215.394032)
		(end 165.226746 -215.230964)
		(width 0.14478)
		(layer "In6.Cu")
		(net "M_K_CPU1_SA_DQ<15>")
	)
	(segment
		(start 193.502534 -214.532972)
		(end 193.502534 -214.597234)
		(width 0.14478)
		(layer "In6.Cu")
		(net "M_K_CPU1_SA_DQ<15>")
	)
	(segment
		(start 169.146982 -214.369904)
		(end 169.31005 -214.532972)
		(width 0.14478)
		(layer "In6.Cu")
		(net "M_K_CPU1_SA_DQ<15>")
	)
	(segment
		(start 173.609254 -215.61044)
		(end 174.459392 -214.760302)
		(width 0.14478)
		(layer "In6.Cu")
		(net "M_K_CPU1_SA_DQ<15>")
	)
	(segment
		(start 168.753536 -214.597234)
		(end 168.753536 -214.532972)
		(width 0.14478)
		(layer "In6.Cu")
		(net "M_K_CPU1_SA_DQ<15>")
	)
	(segment
		(start 187.673996 -215.381332)
		(end 187.837064 -215.218264)
		(width 0.14478)
		(layer "In6.Cu")
		(net "M_K_CPU1_SA_DQ<15>")
	)
	(segment
		(start 193.665602 -214.760302)
		(end 194.17919 -214.760302)
		(width 0.14478)
		(layer "In6.Cu")
		(net "M_K_CPU1_SA_DQ<15>")
	)
	(segment
		(start 146.82724 -233.03992)
		(end 147.709636 -232.157524)
		(width 0.0889)
		(layer "In6.Cu")
		(net "M_K_CPU1_SA_DQ<15>")
	)
	(segment
		(start 192.226438 -214.369904)
		(end 192.389506 -214.532972)
		(width 0.14478)
		(layer "In6.Cu")
		(net "M_K_CPU1_SA_DQ<15>")
	)
	(segment
		(start 186.622944 -215.389206)
		(end 186.622944 -215.46566)
		(width 0.14478)
		(layer "In6.Cu")
		(net "M_K_CPU1_SA_DQ<15>")
	)
	(segment
		(start 183.240172 -214.760302)
		(end 184.99582 -214.760302)
		(width 0.14478)
		(layer "In6.Cu")
		(net "M_K_CPU1_SA_DQ<15>")
	)
	(segment
		(start 172.542708 -215.447372)
		(end 172.542708 -215.378792)
		(width 0.14478)
		(layer "In6.Cu")
		(net "M_K_CPU1_SA_DQ<15>")
	)
	(segment
		(start 180.72354 -215.447372)
		(end 180.886608 -215.61044)
		(width 0.14478)
		(layer "In6.Cu")
		(net "M_K_CPU1_SA_DQ<15>")
	)
	(segment
		(start 164.90061 -215.61044)
		(end 165.063678 -215.447372)
		(width 0.14478)
		(layer "In6.Cu")
		(net "M_K_CPU1_SA_DQ<15>")
	)
	(segment
		(start 188.23051 -215.381332)
		(end 188.23051 -215.447372)
		(width 0.14478)
		(layer "In6.Cu")
		(net "M_K_CPU1_SA_DQ<15>")
	)
	(segment
		(start 182.52059 -214.597234)
		(end 182.52059 -214.532972)
		(width 0.14478)
		(layer "In6.Cu")
		(net "M_K_CPU1_SA_DQ<15>")
	)
	(segment
		(start 143.92148 -234.441746)
		(end 143.931894 -234.447842)
		(width 0.0889)
		(layer "In6.Cu")
		(net "M_K_CPU1_SA_DQ<15>")
	)
	(segment
		(start 189.52337 -214.760302)
		(end 189.789054 -214.760302)
		(width 0.14478)
		(layer "In6.Cu")
		(net "M_K_CPU1_SA_DQ<15>")
	)
	(segment
		(start 186.478164 -215.244426)
		(end 186.622944 -215.389206)
		(width 0.14478)
		(layer "In6.Cu")
		(net "M_K_CPU1_SA_DQ<15>")
	)
	(segment
		(start 144.487138 -234.441746)
		(end 144.498822 -234.434888)
		(width 0.0889)
		(layer "In6.Cu")
		(net "M_K_CPU1_SA_DQ<15>")
	)
	(segment
		(start 165.063678 -215.447372)
		(end 165.063678 -215.394032)
		(width 0.14478)
		(layer "In6.Cu")
		(net "M_K_CPU1_SA_DQ<15>")
	)
	(segment
		(start 180.167026 -215.386412)
		(end 180.330094 -215.223344)
		(width 0.14478)
		(layer "In6.Cu")
		(net "M_K_CPU1_SA_DQ<15>")
	)
	(segment
		(start 192.94602 -214.532972)
		(end 193.109088 -214.369904)
		(width 0.14478)
		(layer "In6.Cu")
		(net "M_K_CPU1_SA_DQ<15>")
	)
	(segment
		(start 165.457124 -215.230964)
		(end 165.620192 -215.394032)
		(width 0.14478)
		(layer "In6.Cu")
		(net "M_K_CPU1_SA_DQ<15>")
	)
	(segment
		(start 158.173928 -222.771208)
		(end 158.173928 -221.677484)
		(width 0.14478)
		(layer "In6.Cu")
		(net "M_K_CPU1_SA_DQ<15>")
	)
	(segment
		(start 166.916862 -214.760302)
		(end 167.47744 -214.760302)
		(width 0.14478)
		(layer "In6.Cu")
		(net "M_K_CPU1_SA_DQ<15>")
	)
	(segment
		(start 193.502534 -214.597234)
		(end 193.665602 -214.760302)
		(width 0.14478)
		(layer "In6.Cu")
		(net "M_K_CPU1_SA_DQ<15>")
	)
	(segment
		(start 168.197022 -214.532972)
		(end 168.197022 -214.597234)
		(width 0.14478)
		(layer "In6.Cu")
		(net "M_K_CPU1_SA_DQ<15>")
	)
	(segment
		(start 182.357522 -214.760302)
		(end 182.52059 -214.597234)
		(width 0.14478)
		(layer "In6.Cu")
		(net "M_K_CPU1_SA_DQ<15>")
	)
	(segment
		(start 188.23051 -215.447372)
		(end 188.393578 -215.61044)
		(width 0.14478)
		(layer "In6.Cu")
		(net "M_K_CPU1_SA_DQ<15>")
	)
	(segment
		(start 193.109088 -214.369904)
		(end 193.339466 -214.369904)
		(width 0.14478)
		(layer "In6.Cu")
		(net "M_K_CPU1_SA_DQ<15>")
	)
	(segment
		(start 187.673996 -215.447372)
		(end 187.673996 -215.381332)
		(width 0.14478)
		(layer "In6.Cu")
		(net "M_K_CPU1_SA_DQ<15>")
	)
	(segment
		(start 173.099222 -215.378792)
		(end 173.099222 -215.447372)
		(width 0.14478)
		(layer "In6.Cu")
		(net "M_K_CPU1_SA_DQ<15>")
	)
	(segment
		(start 146.379184 -233.558842)
		(end 146.379184 -233.223816)
		(width 0.0889)
		(layer "In6.Cu")
		(net "M_K_CPU1_SA_DQ<15>")
	)
	(segment
		(start 175.482504 -214.532972)
		(end 175.482504 -214.597234)
		(width 0.14478)
		(layer "In6.Cu")
		(net "M_K_CPU1_SA_DQ<15>")
	)
	(segment
		(start 175.482504 -214.597234)
		(end 175.645572 -214.760302)
		(width 0.14478)
		(layer "In6.Cu")
		(net "M_K_CPU1_SA_DQ<15>")
	)
	(segment
		(start 186.21629 -215.244426)
		(end 186.478164 -215.244426)
		(width 0.14478)
		(layer "In6.Cu")
		(net "M_K_CPU1_SA_DQ<15>")
	)
	(segment
		(start 167.640508 -214.532972)
		(end 167.803576 -214.369904)
		(width 0.14478)
		(layer "In6.Cu")
		(net "M_K_CPU1_SA_DQ<15>")
	)
	(segment
		(start 172.936154 -215.215724)
		(end 173.099222 -215.378792)
		(width 0.14478)
		(layer "In6.Cu")
		(net "M_K_CPU1_SA_DQ<15>")
	)
	(segment
		(start 168.753536 -214.532972)
		(end 168.916604 -214.369904)
		(width 0.14478)
		(layer "In6.Cu")
		(net "M_K_CPU1_SA_DQ<15>")
	)
	(segment
		(start 191.832992 -214.597234)
		(end 191.832992 -214.532972)
		(width 0.14478)
		(layer "In6.Cu")
		(net "M_K_CPU1_SA_DQ<15>")
	)
	(segment
		(start 181.140862 -215.61044)
		(end 181.991 -214.760302)
		(width 0.14478)
		(layer "In6.Cu")
		(net "M_K_CPU1_SA_DQ<15>")
	)
	(segment
		(start 169.31005 -214.597234)
		(end 169.473118 -214.760302)
		(width 0.14478)
		(layer "In6.Cu")
		(net "M_K_CPU1_SA_DQ<15>")
	)
	(segment
		(start 172.705776 -215.215724)
		(end 172.936154 -215.215724)
		(width 0.14478)
		(layer "In6.Cu")
		(net "M_K_CPU1_SA_DQ<15>")
	)
	(segment
		(start 168.197022 -214.597234)
		(end 168.36009 -214.760302)
		(width 0.14478)
		(layer "In6.Cu")
		(net "M_K_CPU1_SA_DQ<15>")
	)
	(segment
		(start 158.173928 -221.677484)
		(end 164.240972 -215.61044)
		(width 0.14478)
		(layer "In6.Cu")
		(net "M_K_CPU1_SA_DQ<15>")
	)
	(segment
		(start 190.078614 -214.373206)
		(end 190.340488 -214.373206)
		(width 0.14478)
		(layer "In6.Cu")
		(net "M_K_CPU1_SA_DQ<15>")
	)
	(segment
		(start 182.52059 -214.532972)
		(end 182.683658 -214.369904)
		(width 0.14478)
		(layer "In6.Cu")
		(net "M_K_CPU1_SA_DQ<15>")
	)
	(segment
		(start 168.36009 -214.760302)
		(end 168.590468 -214.760302)
		(width 0.14478)
		(layer "In6.Cu")
		(net "M_K_CPU1_SA_DQ<15>")
	)
	(segment
		(start 174.92599 -214.597234)
		(end 174.92599 -214.532972)
		(width 0.14478)
		(layer "In6.Cu")
		(net "M_K_CPU1_SA_DQ<15>")
	)
	(segment
		(start 170.758104 -215.61044)
		(end 172.37964 -215.61044)
		(width 0.14478)
		(layer "In6.Cu")
		(net "M_K_CPU1_SA_DQ<15>")
	)
	(segment
		(start 185.92673 -215.61044)
		(end 186.07151 -215.46566)
		(width 0.14478)
		(layer "In6.Cu")
		(net "M_K_CPU1_SA_DQ<15>")
	)
	(segment
		(start 168.916604 -214.369904)
		(end 169.146982 -214.369904)
		(width 0.14478)
		(layer "In6.Cu")
		(net "M_K_CPU1_SA_DQ<15>")
	)
	(segment
		(start 183.077104 -214.597234)
		(end 183.240172 -214.760302)
		(width 0.14478)
		(layer "In6.Cu")
		(net "M_K_CPU1_SA_DQ<15>")
	)
	(segment
		(start 174.92599 -214.532972)
		(end 175.089058 -214.369904)
		(width 0.14478)
		(layer "In6.Cu")
		(net "M_K_CPU1_SA_DQ<15>")
	)
	(segment
		(start 143.909796 -234.434888)
		(end 143.92148 -234.441746)
		(width 0.0889)
		(layer "In6.Cu")
		(net "M_K_CPU1_SA_DQ<15>")
	)
	(segment
		(start 190.340488 -214.373206)
		(end 190.485268 -214.517986)
		(width 0.14478)
		(layer "In6.Cu")
		(net "M_K_CPU1_SA_DQ<15>")
	)
	(segment
		(start 183.077104 -214.532972)
		(end 183.077104 -214.597234)
		(width 0.14478)
		(layer "In6.Cu")
		(net "M_K_CPU1_SA_DQ<15>")
	)
	(segment
		(start 165.78326 -215.61044)
		(end 166.066724 -215.61044)
		(width 0.14478)
		(layer "In6.Cu")
		(net "M_K_CPU1_SA_DQ<15>")
	)
	(segment
		(start 180.560472 -215.223344)
		(end 180.72354 -215.386412)
		(width 0.14478)
		(layer "In6.Cu")
		(net "M_K_CPU1_SA_DQ<15>")
	)
	(segment
		(start 169.473118 -214.760302)
		(end 169.907966 -214.760302)
		(width 0.14478)
		(layer "In6.Cu")
		(net "M_K_CPU1_SA_DQ<15>")
	)
	(segment
		(start 167.47744 -214.760302)
		(end 167.640508 -214.597234)
		(width 0.14478)
		(layer "In6.Cu")
		(net "M_K_CPU1_SA_DQ<15>")
	)
	(segment
		(start 188.673232 -215.61044)
		(end 189.52337 -214.760302)
		(width 0.14478)
		(layer "In6.Cu")
		(net "M_K_CPU1_SA_DQ<15>")
	)
	(segment
		(start 187.837064 -215.218264)
		(end 188.067442 -215.218264)
		(width 0.14478)
		(layer "In6.Cu")
		(net "M_K_CPU1_SA_DQ<15>")
	)
	(segment
		(start 145.427192 -234.442)
		(end 145.440908 -234.434126)
		(width 0.0889)
		(layer "In6.Cu")
		(net "M_K_CPU1_SA_DQ<15>")
	)
	(segment
		(start 141.667738 -234.441746)
		(end 141.67612 -234.43692)
		(width 0.0889)
		(layer "In6.Cu")
		(net "M_K_CPU1_SA_DQ<15>")
	)
	(segment
		(start 192.389506 -214.597234)
		(end 192.552574 -214.760302)
		(width 0.14478)
		(layer "In6.Cu")
		(net "M_K_CPU1_SA_DQ<15>")
	)
	(segment
		(start 189.933834 -214.615522)
		(end 189.933834 -214.517986)
		(width 0.14478)
		(layer "In6.Cu")
		(net "M_K_CPU1_SA_DQ<15>")
	)
	(segment
		(start 193.339466 -214.369904)
		(end 193.502534 -214.532972)
		(width 0.14478)
		(layer "In6.Cu")
		(net "M_K_CPU1_SA_DQ<15>")
	)
	(segment
		(start 169.31005 -214.532972)
		(end 169.31005 -214.597234)
		(width 0.14478)
		(layer "In6.Cu")
		(net "M_K_CPU1_SA_DQ<15>")
	)
	(segment
		(start 190.485268 -214.615522)
		(end 190.630048 -214.760302)
		(width 0.14478)
		(layer "In6.Cu")
		(net "M_K_CPU1_SA_DQ<15>")
	)
	(segment
		(start 174.459392 -214.760302)
		(end 174.762922 -214.760302)
		(width 0.14478)
		(layer "In6.Cu")
		(net "M_K_CPU1_SA_DQ<15>")
	)
	(segment
		(start 190.485268 -214.517986)
		(end 190.485268 -214.615522)
		(width 0.14478)
		(layer "In6.Cu")
		(net "M_K_CPU1_SA_DQ<15>")
	)
	(segment
		(start 172.542708 -215.378792)
		(end 172.705776 -215.215724)
		(width 0.14478)
		(layer "In6.Cu")
		(net "M_K_CPU1_SA_DQ<15>")
	)
	(segment
		(start 180.886608 -215.61044)
		(end 181.140862 -215.61044)
		(width 0.14478)
		(layer "In6.Cu")
		(net "M_K_CPU1_SA_DQ<15>")
	)
	(segment
		(start 145.620994 -234.317032)
		(end 146.379184 -233.558842)
		(width 0.0889)
		(layer "In6.Cu")
		(net "M_K_CPU1_SA_DQ<15>")
	)
	(segment
		(start 175.645572 -214.760302)
		(end 177.45202 -214.760302)
		(width 0.14478)
		(layer "In6.Cu")
		(net "M_K_CPU1_SA_DQ<15>")
	)
	(segment
		(start 174.762922 -214.760302)
		(end 174.92599 -214.597234)
		(width 0.14478)
		(layer "In6.Cu")
		(net "M_K_CPU1_SA_DQ<15>")
	)
	(segment
		(start 175.319436 -214.369904)
		(end 175.482504 -214.532972)
		(width 0.14478)
		(layer "In6.Cu")
		(net "M_K_CPU1_SA_DQ<15>")
	)
	(segment
		(start 192.782952 -214.760302)
		(end 192.94602 -214.597234)
		(width 0.14478)
		(layer "In6.Cu")
		(net "M_K_CPU1_SA_DQ<15>")
	)
	(segment
		(start 182.914036 -214.369904)
		(end 183.077104 -214.532972)
		(width 0.14478)
		(layer "In6.Cu")
		(net "M_K_CPU1_SA_DQ<15>")
	)
	(segment
		(start 177.45202 -214.760302)
		(end 178.302158 -215.61044)
		(width 0.14478)
		(layer "In6.Cu")
		(net "M_K_CPU1_SA_DQ<15>")
	)
	(segment
		(start 147.709636 -232.157524)
		(end 148.787612 -232.157524)
		(width 0.0889)
		(layer "In6.Cu")
		(net "M_K_CPU1_SA_DQ<15>")
	)
	(segment
		(start 168.590468 -214.760302)
		(end 168.753536 -214.597234)
		(width 0.14478)
		(layer "In6.Cu")
		(net "M_K_CPU1_SA_DQ<15>")
	)
	(segment
		(start 145.440908 -234.434126)
		(end 145.620994 -234.317032)
		(width 0.0889)
		(layer "In6.Cu")
		(net "M_K_CPU1_SA_DQ<15>")
	)
	(segment
		(start 146.379184 -233.223816)
		(end 146.56308 -233.03992)
		(width 0.0889)
		(layer "In6.Cu")
		(net "M_K_CPU1_SA_DQ<15>")
	)
	(segment
		(start 165.226746 -215.230964)
		(end 165.457124 -215.230964)
		(width 0.14478)
		(layer "In6.Cu")
		(net "M_K_CPU1_SA_DQ<15>")
	)
	(segment
		(start 191.99606 -214.369904)
		(end 192.226438 -214.369904)
		(width 0.14478)
		(layer "In6.Cu")
		(net "M_K_CPU1_SA_DQ<15>")
	)
	(segment
		(start 186.07151 -215.46566)
		(end 186.07151 -215.389206)
		(width 0.14478)
		(layer "In6.Cu")
		(net "M_K_CPU1_SA_DQ<15>")
	)
	(segment
		(start 173.26229 -215.61044)
		(end 173.609254 -215.61044)
		(width 0.14478)
		(layer "In6.Cu")
		(net "M_K_CPU1_SA_DQ<15>")
	)
	(segment
		(start 146.56308 -233.03992)
		(end 146.82724 -233.03992)
		(width 0.0889)
		(layer "In6.Cu")
		(net "M_K_CPU1_SA_DQ<15>")
	)
	(segment
		(start 149.016466 -231.92867)
		(end 158.173928 -222.771208)
		(width 0.14478)
		(layer "In6.Cu")
		(net "M_K_CPU1_SA_DQ<15>")
	)
	(segment
		(start 165.620192 -215.447372)
		(end 165.78326 -215.61044)
		(width 0.14478)
		(layer "In6.Cu")
		(net "M_K_CPU1_SA_DQ<15>")
	)
	(segment
		(start 190.630048 -214.760302)
		(end 191.669924 -214.760302)
		(width 0.14478)
		(layer "In6.Cu")
		(net "M_K_CPU1_SA_DQ<15>")
	)
	(segment
		(start 180.330094 -215.223344)
		(end 180.560472 -215.223344)
		(width 0.14478)
		(layer "In6.Cu")
		(net "M_K_CPU1_SA_DQ<15>")
	)
	(segment
		(start 188.393578 -215.61044)
		(end 188.673232 -215.61044)
		(width 0.14478)
		(layer "In6.Cu")
		(net "M_K_CPU1_SA_DQ<15>")
	)
	(segment
		(start 165.620192 -215.394032)
		(end 165.620192 -215.447372)
		(width 0.14478)
		(layer "In6.Cu")
		(net "M_K_CPU1_SA_DQ<15>")
	)
	(segment
		(start 145.415254 -234.448858)
		(end 145.427192 -234.442)
		(width 0.0889)
		(layer "In6.Cu")
		(net "M_K_CPU1_SA_DQ<15>")
	)
	(segment
		(start 189.789054 -214.760302)
		(end 189.933834 -214.615522)
		(width 0.14478)
		(layer "In6.Cu")
		(net "M_K_CPU1_SA_DQ<15>")
	)
	(segment
		(start 191.832992 -214.532972)
		(end 191.99606 -214.369904)
		(width 0.14478)
		(layer "In6.Cu")
		(net "M_K_CPU1_SA_DQ<15>")
	)
	(segment
		(start 189.933834 -214.517986)
		(end 190.078614 -214.373206)
		(width 0.14478)
		(layer "In6.Cu")
		(net "M_K_CPU1_SA_DQ<15>")
	)
	(segment
		(start 164.240972 -215.61044)
		(end 164.90061 -215.61044)
		(width 0.14478)
		(layer "In6.Cu")
		(net "M_K_CPU1_SA_DQ<15>")
	)
	(segment
		(start 168.033954 -214.369904)
		(end 168.197022 -214.532972)
		(width 0.14478)
		(layer "In6.Cu")
		(net "M_K_CPU1_SA_DQ<15>")
	)
	(segment
		(start 185.845958 -215.61044)
		(end 185.92673 -215.61044)
		(width 0.14478)
		(layer "In6.Cu")
		(net "M_K_CPU1_SA_DQ<15>")
	)
	(segment
		(start 167.803576 -214.369904)
		(end 168.033954 -214.369904)
		(width 0.14478)
		(layer "In6.Cu")
		(net "M_K_CPU1_SA_DQ<15>")
	)
	(segment
		(start 182.683658 -214.369904)
		(end 182.914036 -214.369904)
		(width 0.14478)
		(layer "In6.Cu")
		(net "M_K_CPU1_SA_DQ<15>")
	)
	(segment
		(start 192.552574 -214.760302)
		(end 192.782952 -214.760302)
		(width 0.14478)
		(layer "In6.Cu")
		(net "M_K_CPU1_SA_DQ<15>")
	)
	(segment
		(start 186.767724 -215.61044)
		(end 187.510928 -215.61044)
		(width 0.14478)
		(layer "In6.Cu")
		(net "M_K_CPU1_SA_DQ<15>")
	)
	(segment
		(start 166.066724 -215.61044)
		(end 166.916862 -214.760302)
		(width 0.14478)
		(layer "In6.Cu")
		(net "M_K_CPU1_SA_DQ<15>")
	)
	(segment
		(start 169.907966 -214.760302)
		(end 170.758104 -215.61044)
		(width 0.14478)
		(layer "In6.Cu")
		(net "M_K_CPU1_SA_DQ<15>")
	)
	(segment
		(start 188.067442 -215.218264)
		(end 188.23051 -215.381332)
		(width 0.14478)
		(layer "In6.Cu")
		(net "M_K_CPU1_SA_DQ<15>")
	)
	(segment
		(start 180.72354 -215.386412)
		(end 180.72354 -215.447372)
		(width 0.14478)
		(layer "In6.Cu")
		(net "M_K_CPU1_SA_DQ<15>")
	)
	(segment
		(start 187.510928 -215.61044)
		(end 187.673996 -215.447372)
		(width 0.14478)
		(layer "In6.Cu")
		(net "M_K_CPU1_SA_DQ<15>")
	)
	(segment
		(start 186.622944 -215.46566)
		(end 186.767724 -215.61044)
		(width 0.14478)
		(layer "In6.Cu")
		(net "M_K_CPU1_SA_DQ<15>")
	)
	(segment
		(start 175.089058 -214.369904)
		(end 175.319436 -214.369904)
		(width 0.14478)
		(layer "In6.Cu")
		(net "M_K_CPU1_SA_DQ<15>")
	)
	(segment
		(start 173.099222 -215.447372)
		(end 173.26229 -215.61044)
		(width 0.14478)
		(layer "In6.Cu")
		(net "M_K_CPU1_SA_DQ<15>")
	)
	(segment
		(start 186.07151 -215.389206)
		(end 186.21629 -215.244426)
		(width 0.14478)
		(layer "In6.Cu")
		(net "M_K_CPU1_SA_DQ<15>")
	)
	(segment
		(start 167.640508 -214.597234)
		(end 167.640508 -214.532972)
		(width 0.14478)
		(layer "In6.Cu")
		(net "M_K_CPU1_SA_DQ<15>")
	)
	(segment
		(start 172.37964 -215.61044)
		(end 172.542708 -215.447372)
		(width 0.14478)
		(layer "In6.Cu")
		(net "M_K_CPU1_SA_DQ<15>")
	)
	(segment
		(start 178.302158 -215.61044)
		(end 180.003958 -215.61044)
		(width 0.14478)
		(layer "In6.Cu")
		(net "M_K_CPU1_SA_DQ<15>")
	)
	(segment
		(start 194.17919 -214.760302)
		(end 194.604132 -215.185244)
		(width 0.14478)
		(layer "In6.Cu")
		(net "M_K_CPU1_SA_DQ<15>")
	)
	(segment
		(start 180.167026 -215.447372)
		(end 180.167026 -215.386412)
		(width 0.14478)
		(layer "In6.Cu")
		(net "M_K_CPU1_SA_DQ<15>")
	)
	(segment
		(start 181.991 -214.760302)
		(end 182.357522 -214.760302)
		(width 0.14478)
		(layer "In6.Cu")
		(net "M_K_CPU1_SA_DQ<15>")
	)
	(arc
		(start 141.164818 -234.473496)
		(mid 141.420026 -234.516973)
		(end 141.667738 -234.441746)
		(width 0.0889)
		(layer "In6.Cu")
		(net "M_K_CPU1_SA_DQ<15>")
	)
	(arc
		(start 141.67612 -234.43692)
		(mid 141.859628 -234.391426)
		(end 142.04188 -234.441746)
		(width 0.0889)
		(layer "In6.Cu")
		(net "M_K_CPU1_SA_DQ<15>")
	)
	(arc
		(start 142.04188 -234.441746)
		(mid 142.324836 -234.517923)
		(end 142.607792 -234.441746)
		(width 0.0889)
		(layer "In6.Cu")
		(net "M_K_CPU1_SA_DQ<15>")
	)
	(arc
		(start 144.861534 -234.441746)
		(mid 145.137466 -234.518003)
		(end 145.415254 -234.448858)
		(width 0.0889)
		(layer "In6.Cu")
		(net "M_K_CPU1_SA_DQ<15>")
	)
	(arc
		(start 144.498822 -234.434888)
		(mid 144.681077 -234.391235)
		(end 144.861534 -234.441746)
		(width 0.0889)
		(layer "In6.Cu")
		(net "M_K_CPU1_SA_DQ<15>")
	)
	(arc
		(start 143.547592 -234.441746)
		(mid 143.727797 -234.391429)
		(end 143.909796 -234.434888)
		(width 0.0889)
		(layer "In6.Cu")
		(net "M_K_CPU1_SA_DQ<15>")
	)
	(arc
		(start 142.607792 -234.441746)
		(mid 142.794736 -234.391491)
		(end 142.98168 -234.441746)
		(width 0.0889)
		(layer "In6.Cu")
		(net "M_K_CPU1_SA_DQ<15>")
	)
	(arc
		(start 143.931894 -234.447842)
		(mid 144.210326 -234.51794)
		(end 144.487138 -234.441746)
		(width 0.0889)
		(layer "In6.Cu")
		(net "M_K_CPU1_SA_DQ<15>")
	)
	(arc
		(start 142.98168 -234.441746)
		(mid 143.264636 -234.517923)
		(end 143.547592 -234.441746)
		(width 0.0889)
		(layer "In6.Cu")
		(net "M_K_CPU1_SA_DQ<15>")
	)
	(segment
		(start 141.857984 -234.220258)
		(end 142.324836 -233.95432)
		(width 0.10668)
		(layer "F.Cu")
		(net "M_K_CPU1_SA_DQ<14>")
	)
	(segment
		(start 193.762884 -213.06028)
		(end 194.17919 -213.06028)
		(width 0.14478)
		(layer "In6.Cu")
		(net "M_K_CPU1_SA_DQ<14>")
	)
	(segment
		(start 182.976012 -212.897212)
		(end 183.13908 -213.06028)
		(width 0.14478)
		(layer "In6.Cu")
		(net "M_K_CPU1_SA_DQ<14>")
	)
	(segment
		(start 157.249368 -220.902276)
		(end 164.241226 -213.910418)
		(width 0.14478)
		(layer "In6.Cu")
		(net "M_K_CPU1_SA_DQ<14>")
	)
	(segment
		(start 169.36847 -212.897212)
		(end 169.531538 -213.06028)
		(width 0.14478)
		(layer "In6.Cu")
		(net "M_K_CPU1_SA_DQ<14>")
	)
	(segment
		(start 174.9679 -212.897212)
		(end 174.9679 -212.839554)
		(width 0.14478)
		(layer "In6.Cu")
		(net "M_K_CPU1_SA_DQ<14>")
	)
	(segment
		(start 173.609254 -213.910418)
		(end 174.459392 -213.06028)
		(width 0.14478)
		(layer "In6.Cu")
		(net "M_K_CPU1_SA_DQ<14>")
	)
	(segment
		(start 180.616606 -213.690454)
		(end 180.616606 -213.74735)
		(width 0.14478)
		(layer "In6.Cu")
		(net "M_K_CPU1_SA_DQ<14>")
	)
	(segment
		(start 184.15381 -212.9155)
		(end 184.15381 -212.826346)
		(width 0.14478)
		(layer "In6.Cu")
		(net "M_K_CPU1_SA_DQ<14>")
	)
	(segment
		(start 145.381726 -233.581194)
		(end 146.38401 -232.57891)
		(width 0.0889)
		(layer "In6.Cu")
		(net "M_K_CPU1_SA_DQ<14>")
	)
	(segment
		(start 168.811956 -212.897212)
		(end 168.811956 -212.838792)
		(width 0.14478)
		(layer "In6.Cu")
		(net "M_K_CPU1_SA_DQ<14>")
	)
	(segment
		(start 182.812944 -212.675724)
		(end 182.976012 -212.838792)
		(width 0.14478)
		(layer "In6.Cu")
		(net "M_K_CPU1_SA_DQ<14>")
	)
	(segment
		(start 182.419498 -212.838792)
		(end 182.582566 -212.675724)
		(width 0.14478)
		(layer "In6.Cu")
		(net "M_K_CPU1_SA_DQ<14>")
	)
	(segment
		(start 193.043302 -212.833204)
		(end 193.043302 -213.287356)
		(width 0.14478)
		(layer "In6.Cu")
		(net "M_K_CPU1_SA_DQ<14>")
	)
	(segment
		(start 192.486788 -213.287356)
		(end 192.486788 -212.833204)
		(width 0.14478)
		(layer "In6.Cu")
		(net "M_K_CPU1_SA_DQ<14>")
	)
	(segment
		(start 181.140862 -213.910418)
		(end 181.991 -213.06028)
		(width 0.14478)
		(layer "In6.Cu")
		(net "M_K_CPU1_SA_DQ<14>")
	)
	(segment
		(start 180.453538 -213.527386)
		(end 180.616606 -213.690454)
		(width 0.14478)
		(layer "In6.Cu")
		(net "M_K_CPU1_SA_DQ<14>")
	)
	(segment
		(start 148.664676 -230.994204)
		(end 157.249368 -222.409512)
		(width 0.14478)
		(layer "In6.Cu")
		(net "M_K_CPU1_SA_DQ<14>")
	)
	(segment
		(start 143.077692 -233.63174)
		(end 143.086074 -233.626914)
		(width 0.0889)
		(layer "In6.Cu")
		(net "M_K_CPU1_SA_DQ<14>")
	)
	(segment
		(start 165.363398 -213.74735)
		(end 165.526466 -213.910418)
		(width 0.14478)
		(layer "In6.Cu")
		(net "M_K_CPU1_SA_DQ<14>")
	)
	(segment
		(start 189.52337 -213.06028)
		(end 189.73292 -213.06028)
		(width 0.14478)
		(layer "In6.Cu")
		(net "M_K_CPU1_SA_DQ<14>")
	)
	(segment
		(start 180.060092 -213.74735)
		(end 180.060092 -213.690454)
		(width 0.14478)
		(layer "In6.Cu")
		(net "M_K_CPU1_SA_DQ<14>")
	)
	(segment
		(start 193.043302 -213.287356)
		(end 193.20637 -213.450424)
		(width 0.14478)
		(layer "In6.Cu")
		(net "M_K_CPU1_SA_DQ<14>")
	)
	(segment
		(start 187.42025 -213.910418)
		(end 187.583318 -213.74735)
		(width 0.14478)
		(layer "In6.Cu")
		(net "M_K_CPU1_SA_DQ<14>")
	)
	(segment
		(start 144.007078 -233.637836)
		(end 144.017492 -233.63174)
		(width 0.0889)
		(layer "In6.Cu")
		(net "M_K_CPU1_SA_DQ<14>")
	)
	(segment
		(start 145.144744 -233.581194)
		(end 145.381726 -233.581194)
		(width 0.0889)
		(layer "In6.Cu")
		(net "M_K_CPU1_SA_DQ<14>")
	)
	(segment
		(start 175.524414 -212.839554)
		(end 175.524414 -212.897212)
		(width 0.14478)
		(layer "In6.Cu")
		(net "M_K_CPU1_SA_DQ<14>")
	)
	(segment
		(start 167.698928 -212.897212)
		(end 167.698928 -212.838792)
		(width 0.14478)
		(layer "In6.Cu")
		(net "M_K_CPU1_SA_DQ<14>")
	)
	(segment
		(start 182.582566 -212.675724)
		(end 182.812944 -212.675724)
		(width 0.14478)
		(layer "In6.Cu")
		(net "M_K_CPU1_SA_DQ<14>")
	)
	(segment
		(start 173.098206 -213.667086)
		(end 173.098206 -213.765638)
		(width 0.14478)
		(layer "In6.Cu")
		(net "M_K_CPU1_SA_DQ<14>")
	)
	(segment
		(start 188.139832 -213.74735)
		(end 188.3029 -213.910418)
		(width 0.14478)
		(layer "In6.Cu")
		(net "M_K_CPU1_SA_DQ<14>")
	)
	(segment
		(start 146.38401 -232.57891)
		(end 146.48688 -232.57891)
		(width 0.0889)
		(layer "In6.Cu")
		(net "M_K_CPU1_SA_DQ<14>")
	)
	(segment
		(start 187.583318 -213.685374)
		(end 187.746386 -213.522306)
		(width 0.14478)
		(layer "In6.Cu")
		(net "M_K_CPU1_SA_DQ<14>")
	)
	(segment
		(start 168.41851 -213.06028)
		(end 168.648888 -213.06028)
		(width 0.14478)
		(layer "In6.Cu")
		(net "M_K_CPU1_SA_DQ<14>")
	)
	(segment
		(start 182.25643 -213.06028)
		(end 182.419498 -212.897212)
		(width 0.14478)
		(layer "In6.Cu")
		(net "M_K_CPU1_SA_DQ<14>")
	)
	(segment
		(start 167.861996 -212.675724)
		(end 168.092374 -212.675724)
		(width 0.14478)
		(layer "In6.Cu")
		(net "M_K_CPU1_SA_DQ<14>")
	)
	(segment
		(start 177.45202 -213.06028)
		(end 178.302158 -213.910418)
		(width 0.14478)
		(layer "In6.Cu")
		(net "M_K_CPU1_SA_DQ<14>")
	)
	(segment
		(start 192.486788 -212.833204)
		(end 192.649856 -212.670136)
		(width 0.14478)
		(layer "In6.Cu")
		(net "M_K_CPU1_SA_DQ<14>")
	)
	(segment
		(start 190.284354 -212.681566)
		(end 190.429134 -212.826346)
		(width 0.14478)
		(layer "In6.Cu")
		(net "M_K_CPU1_SA_DQ<14>")
	)
	(segment
		(start 164.806884 -213.74735)
		(end 164.806884 -213.679532)
		(width 0.14478)
		(layer "In6.Cu")
		(net "M_K_CPU1_SA_DQ<14>")
	)
	(segment
		(start 192.093342 -213.450424)
		(end 192.32372 -213.450424)
		(width 0.14478)
		(layer "In6.Cu")
		(net "M_K_CPU1_SA_DQ<14>")
	)
	(segment
		(start 175.687482 -213.06028)
		(end 177.45202 -213.06028)
		(width 0.14478)
		(layer "In6.Cu")
		(net "M_K_CPU1_SA_DQ<14>")
	)
	(segment
		(start 167.698928 -212.838792)
		(end 167.861996 -212.675724)
		(width 0.14478)
		(layer "In6.Cu")
		(net "M_K_CPU1_SA_DQ<14>")
	)
	(segment
		(start 192.649856 -212.670136)
		(end 192.880234 -212.670136)
		(width 0.14478)
		(layer "In6.Cu")
		(net "M_K_CPU1_SA_DQ<14>")
	)
	(segment
		(start 142.47876 -233.68889)
		(end 142.574772 -233.66349)
		(width 0.0889)
		(layer "In6.Cu")
		(net "M_K_CPU1_SA_DQ<14>")
	)
	(segment
		(start 193.599816 -213.287356)
		(end 193.599816 -213.223348)
		(width 0.14478)
		(layer "In6.Cu")
		(net "M_K_CPU1_SA_DQ<14>")
	)
	(segment
		(start 184.29859 -212.681566)
		(end 184.560464 -212.681566)
		(width 0.14478)
		(layer "In6.Cu")
		(net "M_K_CPU1_SA_DQ<14>")
	)
	(segment
		(start 169.36847 -212.838792)
		(end 169.36847 -212.897212)
		(width 0.14478)
		(layer "In6.Cu")
		(net "M_K_CPU1_SA_DQ<14>")
	)
	(segment
		(start 165.20033 -213.516464)
		(end 165.363398 -213.679532)
		(width 0.14478)
		(layer "In6.Cu")
		(net "M_K_CPU1_SA_DQ<14>")
	)
	(segment
		(start 166.066724 -213.910418)
		(end 166.916862 -213.06028)
		(width 0.14478)
		(layer "In6.Cu")
		(net "M_K_CPU1_SA_DQ<14>")
	)
	(segment
		(start 168.975024 -212.675724)
		(end 169.205402 -212.675724)
		(width 0.14478)
		(layer "In6.Cu")
		(net "M_K_CPU1_SA_DQ<14>")
	)
	(segment
		(start 192.32372 -213.450424)
		(end 192.486788 -213.287356)
		(width 0.14478)
		(layer "In6.Cu")
		(net "M_K_CPU1_SA_DQ<14>")
	)
	(segment
		(start 187.976764 -213.522306)
		(end 188.139832 -213.685374)
		(width 0.14478)
		(layer "In6.Cu")
		(net "M_K_CPU1_SA_DQ<14>")
	)
	(segment
		(start 172.691552 -213.522306)
		(end 172.953426 -213.522306)
		(width 0.14478)
		(layer "In6.Cu")
		(net "M_K_CPU1_SA_DQ<14>")
	)
	(segment
		(start 147.761706 -231.304084)
		(end 148.354796 -231.304084)
		(width 0.0889)
		(layer "In6.Cu")
		(net "M_K_CPU1_SA_DQ<14>")
	)
	(segment
		(start 164.643816 -213.910418)
		(end 164.806884 -213.74735)
		(width 0.14478)
		(layer "In6.Cu")
		(net "M_K_CPU1_SA_DQ<14>")
	)
	(segment
		(start 165.363398 -213.679532)
		(end 165.363398 -213.74735)
		(width 0.14478)
		(layer "In6.Cu")
		(net "M_K_CPU1_SA_DQ<14>")
	)
	(segment
		(start 184.15381 -212.826346)
		(end 184.29859 -212.681566)
		(width 0.14478)
		(layer "In6.Cu")
		(net "M_K_CPU1_SA_DQ<14>")
	)
	(segment
		(start 173.242986 -213.910418)
		(end 173.609254 -213.910418)
		(width 0.14478)
		(layer "In6.Cu")
		(net "M_K_CPU1_SA_DQ<14>")
	)
	(segment
		(start 175.361346 -212.676486)
		(end 175.524414 -212.839554)
		(width 0.14478)
		(layer "In6.Cu")
		(net "M_K_CPU1_SA_DQ<14>")
	)
	(segment
		(start 184.850024 -213.06028)
		(end 184.99582 -213.06028)
		(width 0.14478)
		(layer "In6.Cu")
		(net "M_K_CPU1_SA_DQ<14>")
	)
	(segment
		(start 172.546772 -213.765638)
		(end 172.546772 -213.667086)
		(width 0.14478)
		(layer "In6.Cu")
		(net "M_K_CPU1_SA_DQ<14>")
	)
	(segment
		(start 184.560464 -212.681566)
		(end 184.705244 -212.826346)
		(width 0.14478)
		(layer "In6.Cu")
		(net "M_K_CPU1_SA_DQ<14>")
	)
	(segment
		(start 173.098206 -213.765638)
		(end 173.242986 -213.910418)
		(width 0.14478)
		(layer "In6.Cu")
		(net "M_K_CPU1_SA_DQ<14>")
	)
	(segment
		(start 190.429134 -212.9155)
		(end 190.573914 -213.06028)
		(width 0.14478)
		(layer "In6.Cu")
		(net "M_K_CPU1_SA_DQ<14>")
	)
	(segment
		(start 180.22316 -213.527386)
		(end 180.453538 -213.527386)
		(width 0.14478)
		(layer "In6.Cu")
		(net "M_K_CPU1_SA_DQ<14>")
	)
	(segment
		(start 189.8777 -212.826346)
		(end 190.02248 -212.681566)
		(width 0.14478)
		(layer "In6.Cu")
		(net "M_K_CPU1_SA_DQ<14>")
	)
	(segment
		(start 169.205402 -212.675724)
		(end 169.36847 -212.838792)
		(width 0.14478)
		(layer "In6.Cu")
		(net "M_K_CPU1_SA_DQ<14>")
	)
	(segment
		(start 184.705244 -212.9155)
		(end 184.850024 -213.06028)
		(width 0.14478)
		(layer "In6.Cu")
		(net "M_K_CPU1_SA_DQ<14>")
	)
	(segment
		(start 180.060092 -213.690454)
		(end 180.22316 -213.527386)
		(width 0.14478)
		(layer "In6.Cu")
		(net "M_K_CPU1_SA_DQ<14>")
	)
	(segment
		(start 193.436748 -213.450424)
		(end 193.599816 -213.287356)
		(width 0.14478)
		(layer "In6.Cu")
		(net "M_K_CPU1_SA_DQ<14>")
	)
	(segment
		(start 189.8777 -212.9155)
		(end 189.8777 -212.826346)
		(width 0.14478)
		(layer "In6.Cu")
		(net "M_K_CPU1_SA_DQ<14>")
	)
	(segment
		(start 180.779674 -213.910418)
		(end 181.140862 -213.910418)
		(width 0.14478)
		(layer "In6.Cu")
		(net "M_K_CPU1_SA_DQ<14>")
	)
	(segment
		(start 174.9679 -212.839554)
		(end 175.130968 -212.676486)
		(width 0.14478)
		(layer "In6.Cu")
		(net "M_K_CPU1_SA_DQ<14>")
	)
	(segment
		(start 144.39138 -233.63174)
		(end 144.401794 -233.637836)
		(width 0.0889)
		(layer "In6.Cu")
		(net "M_K_CPU1_SA_DQ<14>")
	)
	(segment
		(start 157.249368 -222.409512)
		(end 157.249368 -220.902276)
		(width 0.14478)
		(layer "In6.Cu")
		(net "M_K_CPU1_SA_DQ<14>")
	)
	(segment
		(start 188.673232 -213.910418)
		(end 189.52337 -213.06028)
		(width 0.14478)
		(layer "In6.Cu")
		(net "M_K_CPU1_SA_DQ<14>")
	)
	(segment
		(start 190.429134 -212.826346)
		(end 190.429134 -212.9155)
		(width 0.14478)
		(layer "In6.Cu")
		(net "M_K_CPU1_SA_DQ<14>")
	)
	(segment
		(start 189.73292 -213.06028)
		(end 189.8777 -212.9155)
		(width 0.14478)
		(layer "In6.Cu")
		(net "M_K_CPU1_SA_DQ<14>")
	)
	(segment
		(start 164.241226 -213.910418)
		(end 164.643816 -213.910418)
		(width 0.14478)
		(layer "In6.Cu")
		(net "M_K_CPU1_SA_DQ<14>")
	)
	(segment
		(start 172.401992 -213.910418)
		(end 172.546772 -213.765638)
		(width 0.14478)
		(layer "In6.Cu")
		(net "M_K_CPU1_SA_DQ<14>")
	)
	(segment
		(start 172.546772 -213.667086)
		(end 172.691552 -213.522306)
		(width 0.14478)
		(layer "In6.Cu")
		(net "M_K_CPU1_SA_DQ<14>")
	)
	(segment
		(start 191.930274 -213.287356)
		(end 192.093342 -213.450424)
		(width 0.14478)
		(layer "In6.Cu")
		(net "M_K_CPU1_SA_DQ<14>")
	)
	(segment
		(start 175.130968 -212.676486)
		(end 175.361346 -212.676486)
		(width 0.14478)
		(layer "In6.Cu")
		(net "M_K_CPU1_SA_DQ<14>")
	)
	(segment
		(start 186.252358 -213.529926)
		(end 186.514232 -213.529926)
		(width 0.14478)
		(layer "In6.Cu")
		(net "M_K_CPU1_SA_DQ<14>")
	)
	(segment
		(start 168.811956 -212.838792)
		(end 168.975024 -212.675724)
		(width 0.14478)
		(layer "In6.Cu")
		(net "M_K_CPU1_SA_DQ<14>")
	)
	(segment
		(start 191.930274 -213.223348)
		(end 191.930274 -213.287356)
		(width 0.14478)
		(layer "In6.Cu")
		(net "M_K_CPU1_SA_DQ<14>")
	)
	(segment
		(start 187.583318 -213.74735)
		(end 187.583318 -213.685374)
		(width 0.14478)
		(layer "In6.Cu")
		(net "M_K_CPU1_SA_DQ<14>")
	)
	(segment
		(start 172.953426 -213.522306)
		(end 173.098206 -213.667086)
		(width 0.14478)
		(layer "In6.Cu")
		(net "M_K_CPU1_SA_DQ<14>")
	)
	(segment
		(start 146.48688 -232.57891)
		(end 147.761706 -231.304084)
		(width 0.0889)
		(layer "In6.Cu")
		(net "M_K_CPU1_SA_DQ<14>")
	)
	(segment
		(start 174.459392 -213.06028)
		(end 174.804832 -213.06028)
		(width 0.14478)
		(layer "In6.Cu")
		(net "M_K_CPU1_SA_DQ<14>")
	)
	(segment
		(start 186.659012 -213.674706)
		(end 186.659012 -213.765638)
		(width 0.14478)
		(layer "In6.Cu")
		(net "M_K_CPU1_SA_DQ<14>")
	)
	(segment
		(start 192.880234 -212.670136)
		(end 193.043302 -212.833204)
		(width 0.14478)
		(layer "In6.Cu")
		(net "M_K_CPU1_SA_DQ<14>")
	)
	(segment
		(start 142.324836 -233.95432)
		(end 142.47876 -233.68889)
		(width 0.0889)
		(layer "In6.Cu")
		(net "M_K_CPU1_SA_DQ<14>")
	)
	(segment
		(start 184.00903 -213.06028)
		(end 184.15381 -212.9155)
		(width 0.14478)
		(layer "In6.Cu")
		(net "M_K_CPU1_SA_DQ<14>")
	)
	(segment
		(start 165.526466 -213.910418)
		(end 166.066724 -213.910418)
		(width 0.14478)
		(layer "In6.Cu")
		(net "M_K_CPU1_SA_DQ<14>")
	)
	(segment
		(start 169.531538 -213.06028)
		(end 169.907966 -213.06028)
		(width 0.14478)
		(layer "In6.Cu")
		(net "M_K_CPU1_SA_DQ<14>")
	)
	(segment
		(start 182.419498 -212.897212)
		(end 182.419498 -212.838792)
		(width 0.14478)
		(layer "In6.Cu")
		(net "M_K_CPU1_SA_DQ<14>")
	)
	(segment
		(start 183.13908 -213.06028)
		(end 184.00903 -213.06028)
		(width 0.14478)
		(layer "In6.Cu")
		(net "M_K_CPU1_SA_DQ<14>")
	)
	(segment
		(start 180.616606 -213.74735)
		(end 180.779674 -213.910418)
		(width 0.14478)
		(layer "In6.Cu")
		(net "M_K_CPU1_SA_DQ<14>")
	)
	(segment
		(start 179.897024 -213.910418)
		(end 180.060092 -213.74735)
		(width 0.14478)
		(layer "In6.Cu")
		(net "M_K_CPU1_SA_DQ<14>")
	)
	(segment
		(start 175.524414 -212.897212)
		(end 175.687482 -213.06028)
		(width 0.14478)
		(layer "In6.Cu")
		(net "M_K_CPU1_SA_DQ<14>")
	)
	(segment
		(start 164.806884 -213.679532)
		(end 164.969952 -213.516464)
		(width 0.14478)
		(layer "In6.Cu")
		(net "M_K_CPU1_SA_DQ<14>")
	)
	(segment
		(start 193.599816 -213.223348)
		(end 193.762884 -213.06028)
		(width 0.14478)
		(layer "In6.Cu")
		(net "M_K_CPU1_SA_DQ<14>")
	)
	(segment
		(start 182.976012 -212.838792)
		(end 182.976012 -212.897212)
		(width 0.14478)
		(layer "In6.Cu")
		(net "M_K_CPU1_SA_DQ<14>")
	)
	(segment
		(start 185.845958 -213.910418)
		(end 185.962798 -213.910418)
		(width 0.14478)
		(layer "In6.Cu")
		(net "M_K_CPU1_SA_DQ<14>")
	)
	(segment
		(start 188.3029 -213.910418)
		(end 188.673232 -213.910418)
		(width 0.14478)
		(layer "In6.Cu")
		(net "M_K_CPU1_SA_DQ<14>")
	)
	(segment
		(start 190.573914 -213.06028)
		(end 191.767206 -213.06028)
		(width 0.14478)
		(layer "In6.Cu")
		(net "M_K_CPU1_SA_DQ<14>")
	)
	(segment
		(start 148.354796 -231.304084)
		(end 148.664676 -230.994204)
		(width 0.0889)
		(layer "In6.Cu")
		(net "M_K_CPU1_SA_DQ<14>")
	)
	(segment
		(start 194.17919 -213.06028)
		(end 194.604132 -213.485222)
		(width 0.14478)
		(layer "In6.Cu")
		(net "M_K_CPU1_SA_DQ<14>")
	)
	(segment
		(start 186.514232 -213.529926)
		(end 186.659012 -213.674706)
		(width 0.14478)
		(layer "In6.Cu")
		(net "M_K_CPU1_SA_DQ<14>")
	)
	(segment
		(start 164.969952 -213.516464)
		(end 165.20033 -213.516464)
		(width 0.14478)
		(layer "In6.Cu")
		(net "M_K_CPU1_SA_DQ<14>")
	)
	(segment
		(start 168.255442 -212.897212)
		(end 168.41851 -213.06028)
		(width 0.14478)
		(layer "In6.Cu")
		(net "M_K_CPU1_SA_DQ<14>")
	)
	(segment
		(start 185.962798 -213.910418)
		(end 186.107578 -213.765638)
		(width 0.14478)
		(layer "In6.Cu")
		(net "M_K_CPU1_SA_DQ<14>")
	)
	(segment
		(start 186.107578 -213.765638)
		(end 186.107578 -213.674706)
		(width 0.14478)
		(layer "In6.Cu")
		(net "M_K_CPU1_SA_DQ<14>")
	)
	(segment
		(start 181.991 -213.06028)
		(end 182.25643 -213.06028)
		(width 0.14478)
		(layer "In6.Cu")
		(net "M_K_CPU1_SA_DQ<14>")
	)
	(segment
		(start 190.02248 -212.681566)
		(end 190.284354 -212.681566)
		(width 0.14478)
		(layer "In6.Cu")
		(net "M_K_CPU1_SA_DQ<14>")
	)
	(segment
		(start 178.302158 -213.910418)
		(end 179.897024 -213.910418)
		(width 0.14478)
		(layer "In6.Cu")
		(net "M_K_CPU1_SA_DQ<14>")
	)
	(segment
		(start 193.20637 -213.450424)
		(end 193.436748 -213.450424)
		(width 0.14478)
		(layer "In6.Cu")
		(net "M_K_CPU1_SA_DQ<14>")
	)
	(segment
		(start 168.092374 -212.675724)
		(end 168.255442 -212.838792)
		(width 0.14478)
		(layer "In6.Cu")
		(net "M_K_CPU1_SA_DQ<14>")
	)
	(segment
		(start 170.758104 -213.910418)
		(end 172.401992 -213.910418)
		(width 0.14478)
		(layer "In6.Cu")
		(net "M_K_CPU1_SA_DQ<14>")
	)
	(segment
		(start 188.139832 -213.685374)
		(end 188.139832 -213.74735)
		(width 0.14478)
		(layer "In6.Cu")
		(net "M_K_CPU1_SA_DQ<14>")
	)
	(segment
		(start 186.659012 -213.765638)
		(end 186.803792 -213.910418)
		(width 0.14478)
		(layer "In6.Cu")
		(net "M_K_CPU1_SA_DQ<14>")
	)
	(segment
		(start 168.648888 -213.06028)
		(end 168.811956 -212.897212)
		(width 0.14478)
		(layer "In6.Cu")
		(net "M_K_CPU1_SA_DQ<14>")
	)
	(segment
		(start 184.99582 -213.06028)
		(end 185.845958 -213.910418)
		(width 0.14478)
		(layer "In6.Cu")
		(net "M_K_CPU1_SA_DQ<14>")
	)
	(segment
		(start 166.916862 -213.06028)
		(end 167.53586 -213.06028)
		(width 0.14478)
		(layer "In6.Cu")
		(net "M_K_CPU1_SA_DQ<14>")
	)
	(segment
		(start 167.53586 -213.06028)
		(end 167.698928 -212.897212)
		(width 0.14478)
		(layer "In6.Cu")
		(net "M_K_CPU1_SA_DQ<14>")
	)
	(segment
		(start 184.705244 -212.826346)
		(end 184.705244 -212.9155)
		(width 0.14478)
		(layer "In6.Cu")
		(net "M_K_CPU1_SA_DQ<14>")
	)
	(segment
		(start 191.767206 -213.06028)
		(end 191.930274 -213.223348)
		(width 0.14478)
		(layer "In6.Cu")
		(net "M_K_CPU1_SA_DQ<14>")
	)
	(segment
		(start 186.803792 -213.910418)
		(end 187.42025 -213.910418)
		(width 0.14478)
		(layer "In6.Cu")
		(net "M_K_CPU1_SA_DQ<14>")
	)
	(segment
		(start 168.255442 -212.838792)
		(end 168.255442 -212.897212)
		(width 0.14478)
		(layer "In6.Cu")
		(net "M_K_CPU1_SA_DQ<14>")
	)
	(segment
		(start 187.746386 -213.522306)
		(end 187.976764 -213.522306)
		(width 0.14478)
		(layer "In6.Cu")
		(net "M_K_CPU1_SA_DQ<14>")
	)
	(segment
		(start 174.804832 -213.06028)
		(end 174.9679 -212.897212)
		(width 0.14478)
		(layer "In6.Cu")
		(net "M_K_CPU1_SA_DQ<14>")
	)
	(segment
		(start 186.107578 -213.674706)
		(end 186.252358 -213.529926)
		(width 0.14478)
		(layer "In6.Cu")
		(net "M_K_CPU1_SA_DQ<14>")
	)
	(segment
		(start 169.907966 -213.06028)
		(end 170.758104 -213.910418)
		(width 0.14478)
		(layer "In6.Cu")
		(net "M_K_CPU1_SA_DQ<14>")
	)
	(arc
		(start 143.086074 -233.626914)
		(mid 143.269582 -233.58142)
		(end 143.451834 -233.63174)
		(width 0.0889)
		(layer "In6.Cu")
		(net "M_K_CPU1_SA_DQ<14>")
	)
	(arc
		(start 144.017492 -233.63174)
		(mid 144.204436 -233.581485)
		(end 144.39138 -233.63174)
		(width 0.0889)
		(layer "In6.Cu")
		(net "M_K_CPU1_SA_DQ<14>")
	)
	(arc
		(start 142.574772 -233.66349)
		(mid 142.82998 -233.706967)
		(end 143.077692 -233.63174)
		(width 0.0889)
		(layer "In6.Cu")
		(net "M_K_CPU1_SA_DQ<14>")
	)
	(arc
		(start 144.401794 -233.637836)
		(mid 144.68048 -233.708056)
		(end 144.957546 -233.63174)
		(width 0.0889)
		(layer "In6.Cu")
		(net "M_K_CPU1_SA_DQ<14>")
	)
	(arc
		(start 143.451834 -233.63174)
		(mid 143.728647 -233.707883)
		(end 144.007078 -233.637836)
		(width 0.0889)
		(layer "In6.Cu")
		(net "M_K_CPU1_SA_DQ<14>")
	)
	(arc
		(start 144.957546 -233.63174)
		(mid 145.047806 -233.594112)
		(end 145.144744 -233.581194)
		(width 0.0889)
		(layer "In6.Cu")
		(net "M_K_CPU1_SA_DQ<14>")
	)
	(segment
		(start 140.91793 -234.220258)
		(end 141.384782 -233.95432)
		(width 0.10668)
		(layer "F.Cu")
		(net "M_K_CPU1_SA_DQ<13>")
	)
	(segment
		(start 141.384782 -233.95432)
		(end 141.230858 -234.21975)
		(width 0.0889)
		(layer "In6.Cu")
		(net "M_K_CPU1_SA_DQ<13>")
	)
	(segment
		(start 197.055232 -214.307166)
		(end 197.200012 -214.451946)
		(width 0.14478)
		(layer "In6.Cu")
		(net "M_K_CPU1_SA_DQ<13>")
	)
	(segment
		(start 184.996074 -213.910418)
		(end 185.845958 -214.760302)
		(width 0.14478)
		(layer "In6.Cu")
		(net "M_K_CPU1_SA_DQ<13>")
	)
	(segment
		(start 145.337022 -234.273344)
		(end 145.500852 -234.167426)
		(width 0.0889)
		(layer "In6.Cu")
		(net "M_K_CPU1_SA_DQ<13>")
	)
	(segment
		(start 197.606666 -214.307166)
		(end 197.606666 -214.055198)
		(width 0.14478)
		(layer "In6.Cu")
		(net "M_K_CPU1_SA_DQ<13>")
	)
	(segment
		(start 148.980144 -231.321864)
		(end 157.704028 -222.59798)
		(width 0.14478)
		(layer "In6.Cu")
		(net "M_K_CPU1_SA_DQ<13>")
	)
	(segment
		(start 146.172428 -233.137964)
		(end 146.477228 -232.833164)
		(width 0.0889)
		(layer "In6.Cu")
		(net "M_K_CPU1_SA_DQ<13>")
	)
	(segment
		(start 166.106348 -214.760302)
		(end 166.956486 -213.910164)
		(width 0.14478)
		(layer "In6.Cu")
		(net "M_K_CPU1_SA_DQ<13>")
	)
	(segment
		(start 157.704028 -221.46514)
		(end 164.408866 -214.760302)
		(width 0.14478)
		(layer "In6.Cu")
		(net "M_K_CPU1_SA_DQ<13>")
	)
	(segment
		(start 169.907966 -213.910164)
		(end 170.758104 -214.760302)
		(width 0.14478)
		(layer "In6.Cu")
		(net "M_K_CPU1_SA_DQ<13>")
	)
	(segment
		(start 196.910452 -213.910418)
		(end 197.055232 -214.055198)
		(width 0.14478)
		(layer "In6.Cu")
		(net "M_K_CPU1_SA_DQ<13>")
	)
	(segment
		(start 143.077692 -234.2769)
		(end 143.086074 -234.281726)
		(width 0.0889)
		(layer "In6.Cu")
		(net "M_K_CPU1_SA_DQ<13>")
	)
	(segment
		(start 178.302158 -214.760302)
		(end 181.140862 -214.760302)
		(width 0.14478)
		(layer "In6.Cu")
		(net "M_K_CPU1_SA_DQ<13>")
	)
	(segment
		(start 197.200012 -214.451946)
		(end 197.461886 -214.451946)
		(width 0.14478)
		(layer "In6.Cu")
		(net "M_K_CPU1_SA_DQ<13>")
	)
	(segment
		(start 174.459138 -213.910418)
		(end 177.452274 -213.910418)
		(width 0.14478)
		(layer "In6.Cu")
		(net "M_K_CPU1_SA_DQ<13>")
	)
	(segment
		(start 145.313146 -234.28706)
		(end 145.337022 -234.273344)
		(width 0.0889)
		(layer "In6.Cu")
		(net "M_K_CPU1_SA_DQ<13>")
	)
	(segment
		(start 170.758104 -214.760302)
		(end 173.609254 -214.760302)
		(width 0.14478)
		(layer "In6.Cu")
		(net "M_K_CPU1_SA_DQ<13>")
	)
	(segment
		(start 142.503398 -234.281726)
		(end 142.51178 -234.2769)
		(width 0.0889)
		(layer "In6.Cu")
		(net "M_K_CPU1_SA_DQ<13>")
	)
	(segment
		(start 166.956486 -213.910164)
		(end 169.907966 -213.910164)
		(width 0.14478)
		(layer "In6.Cu")
		(net "M_K_CPU1_SA_DQ<13>")
	)
	(segment
		(start 197.751446 -213.910418)
		(end 198.279258 -213.910418)
		(width 0.14478)
		(layer "In6.Cu")
		(net "M_K_CPU1_SA_DQ<13>")
	)
	(segment
		(start 181.990746 -213.910418)
		(end 184.996074 -213.910418)
		(width 0.14478)
		(layer "In6.Cu")
		(net "M_K_CPU1_SA_DQ<13>")
	)
	(segment
		(start 185.845958 -214.760302)
		(end 188.801248 -214.760302)
		(width 0.14478)
		(layer "In6.Cu")
		(net "M_K_CPU1_SA_DQ<13>")
	)
	(segment
		(start 144.017492 -234.2769)
		(end 144.025874 -234.281726)
		(width 0.0889)
		(layer "In6.Cu")
		(net "M_K_CPU1_SA_DQ<13>")
	)
	(segment
		(start 146.172428 -233.49585)
		(end 146.172428 -233.137964)
		(width 0.0889)
		(layer "In6.Cu")
		(net "M_K_CPU1_SA_DQ<13>")
	)
	(segment
		(start 198.279258 -213.910418)
		(end 198.7042 -214.33536)
		(width 0.14478)
		(layer "In6.Cu")
		(net "M_K_CPU1_SA_DQ<13>")
	)
	(segment
		(start 181.140862 -214.760302)
		(end 181.990746 -213.910418)
		(width 0.14478)
		(layer "In6.Cu")
		(net "M_K_CPU1_SA_DQ<13>")
	)
	(segment
		(start 189.651132 -213.910418)
		(end 196.910452 -213.910418)
		(width 0.14478)
		(layer "In6.Cu")
		(net "M_K_CPU1_SA_DQ<13>")
	)
	(segment
		(start 148.591524 -231.710484)
		(end 148.980144 -231.321864)
		(width 0.0889)
		(layer "In6.Cu")
		(net "M_K_CPU1_SA_DQ<13>")
	)
	(segment
		(start 145.500852 -234.167426)
		(end 146.172428 -233.49585)
		(width 0.0889)
		(layer "In6.Cu")
		(net "M_K_CPU1_SA_DQ<13>")
	)
	(segment
		(start 146.477228 -232.833164)
		(end 146.652488 -232.833164)
		(width 0.0889)
		(layer "In6.Cu")
		(net "M_K_CPU1_SA_DQ<13>")
	)
	(segment
		(start 188.801248 -214.760302)
		(end 189.651132 -213.910418)
		(width 0.14478)
		(layer "In6.Cu")
		(net "M_K_CPU1_SA_DQ<13>")
	)
	(segment
		(start 164.408866 -214.760302)
		(end 166.106348 -214.760302)
		(width 0.14478)
		(layer "In6.Cu")
		(net "M_K_CPU1_SA_DQ<13>")
	)
	(segment
		(start 197.461886 -214.451946)
		(end 197.606666 -214.307166)
		(width 0.14478)
		(layer "In6.Cu")
		(net "M_K_CPU1_SA_DQ<13>")
	)
	(segment
		(start 157.704028 -222.59798)
		(end 157.704028 -221.46514)
		(width 0.14478)
		(layer "In6.Cu")
		(net "M_K_CPU1_SA_DQ<13>")
	)
	(segment
		(start 144.391126 -234.2769)
		(end 144.40154 -234.270804)
		(width 0.0889)
		(layer "In6.Cu")
		(net "M_K_CPU1_SA_DQ<13>")
	)
	(segment
		(start 173.609254 -214.760302)
		(end 174.459138 -213.910418)
		(width 0.14478)
		(layer "In6.Cu")
		(net "M_K_CPU1_SA_DQ<13>")
	)
	(segment
		(start 197.606666 -214.055198)
		(end 197.751446 -213.910418)
		(width 0.14478)
		(layer "In6.Cu")
		(net "M_K_CPU1_SA_DQ<13>")
	)
	(segment
		(start 147.775168 -231.710484)
		(end 148.591524 -231.710484)
		(width 0.0889)
		(layer "In6.Cu")
		(net "M_K_CPU1_SA_DQ<13>")
	)
	(segment
		(start 146.652488 -232.833164)
		(end 147.775168 -231.710484)
		(width 0.0889)
		(layer "In6.Cu")
		(net "M_K_CPU1_SA_DQ<13>")
	)
	(segment
		(start 144.007078 -234.270804)
		(end 144.017492 -234.2769)
		(width 0.0889)
		(layer "In6.Cu")
		(net "M_K_CPU1_SA_DQ<13>")
	)
	(segment
		(start 177.452274 -213.910418)
		(end 178.302158 -214.760302)
		(width 0.14478)
		(layer "In6.Cu")
		(net "M_K_CPU1_SA_DQ<13>")
	)
	(segment
		(start 197.055232 -214.055198)
		(end 197.055232 -214.307166)
		(width 0.14478)
		(layer "In6.Cu")
		(net "M_K_CPU1_SA_DQ<13>")
	)
	(segment
		(start 141.230858 -234.21975)
		(end 141.25321 -234.303062)
		(width 0.0889)
		(layer "In6.Cu")
		(net "M_K_CPU1_SA_DQ<13>")
	)
	(arc
		(start 141.25321 -234.303062)
		(mid 141.415399 -234.325797)
		(end 141.571726 -234.2769)
		(width 0.0889)
		(layer "In6.Cu")
		(net "M_K_CPU1_SA_DQ<13>")
	)
	(arc
		(start 143.451834 -234.2769)
		(mid 143.728647 -234.200757)
		(end 144.007078 -234.270804)
		(width 0.0889)
		(layer "In6.Cu")
		(net "M_K_CPU1_SA_DQ<13>")
	)
	(arc
		(start 141.571726 -234.2769)
		(mid 141.854682 -234.200723)
		(end 142.137638 -234.2769)
		(width 0.0889)
		(layer "In6.Cu")
		(net "M_K_CPU1_SA_DQ<13>")
	)
	(arc
		(start 144.957292 -234.2769)
		(mid 145.13392 -234.327133)
		(end 145.313146 -234.28706)
		(width 0.0889)
		(layer "In6.Cu")
		(net "M_K_CPU1_SA_DQ<13>")
	)
	(arc
		(start 144.025874 -234.281726)
		(mid 144.209128 -234.327099)
		(end 144.391126 -234.2769)
		(width 0.0889)
		(layer "In6.Cu")
		(net "M_K_CPU1_SA_DQ<13>")
	)
	(arc
		(start 144.40154 -234.270804)
		(mid 144.680226 -234.200584)
		(end 144.957292 -234.2769)
		(width 0.0889)
		(layer "In6.Cu")
		(net "M_K_CPU1_SA_DQ<13>")
	)
	(arc
		(start 142.51178 -234.2769)
		(mid 142.794736 -234.200723)
		(end 143.077692 -234.2769)
		(width 0.0889)
		(layer "In6.Cu")
		(net "M_K_CPU1_SA_DQ<13>")
	)
	(arc
		(start 143.086074 -234.281726)
		(mid 143.269582 -234.32722)
		(end 143.451834 -234.2769)
		(width 0.0889)
		(layer "In6.Cu")
		(net "M_K_CPU1_SA_DQ<13>")
	)
	(arc
		(start 142.137638 -234.2769)
		(mid 142.319889 -234.32725)
		(end 142.503398 -234.281726)
		(width 0.0889)
		(layer "In6.Cu")
		(net "M_K_CPU1_SA_DQ<13>")
	)
	(segment
		(start 142.327884 -233.410252)
		(end 142.794736 -233.144314)
		(width 0.10668)
		(layer "F.Cu")
		(net "M_K_CPU1_SA_DQ<12>")
	)
	(segment
		(start 143.921734 -233.466894)
		(end 143.932148 -233.460798)
		(width 0.0889)
		(layer "In6.Cu")
		(net "M_K_CPU1_SA_DQ<12>")
	)
	(segment
		(start 196.696076 -212.219794)
		(end 196.849746 -212.373464)
		(width 0.14478)
		(layer "In6.Cu")
		(net "M_K_CPU1_SA_DQ<12>")
	)
	(segment
		(start 198.279258 -212.210396)
		(end 198.7042 -212.635338)
		(width 0.14478)
		(layer "In6.Cu")
		(net "M_K_CPU1_SA_DQ<12>")
	)
	(segment
		(start 196.849746 -212.779356)
		(end 197.012814 -212.942424)
		(width 0.14478)
		(layer "In6.Cu")
		(net "M_K_CPU1_SA_DQ<12>")
	)
	(segment
		(start 185.005472 -212.219794)
		(end 185.855356 -213.069678)
		(width 0.14478)
		(layer "In6.Cu")
		(net "M_K_CPU1_SA_DQ<12>")
	)
	(segment
		(start 185.855356 -213.069678)
		(end 188.79185 -213.069678)
		(width 0.14478)
		(layer "In6.Cu")
		(net "M_K_CPU1_SA_DQ<12>")
	)
	(segment
		(start 197.40626 -212.779356)
		(end 197.40626 -212.373464)
		(width 0.14478)
		(layer "In6.Cu")
		(net "M_K_CPU1_SA_DQ<12>")
	)
	(segment
		(start 146.387312 -231.63022)
		(end 146.582892 -231.43464)
		(width 0.0889)
		(layer "In6.Cu")
		(net "M_K_CPU1_SA_DQ<12>")
	)
	(segment
		(start 148.290788 -230.724964)
		(end 156.794708 -222.221044)
		(width 0.14478)
		(layer "In6.Cu")
		(net "M_K_CPU1_SA_DQ<12>")
	)
	(segment
		(start 181.131464 -213.069678)
		(end 181.981348 -212.219794)
		(width 0.14478)
		(layer "In6.Cu")
		(net "M_K_CPU1_SA_DQ<12>")
	)
	(segment
		(start 144.487392 -233.466894)
		(end 144.495774 -233.47172)
		(width 0.0889)
		(layer "In6.Cu")
		(net "M_K_CPU1_SA_DQ<12>")
	)
	(segment
		(start 142.794736 -233.144314)
		(end 142.640812 -233.409744)
		(width 0.0889)
		(layer "In6.Cu")
		(net "M_K_CPU1_SA_DQ<12>")
	)
	(segment
		(start 143.913352 -233.47172)
		(end 143.921734 -233.466894)
		(width 0.0889)
		(layer "In6.Cu")
		(net "M_K_CPU1_SA_DQ<12>")
	)
	(segment
		(start 145.144744 -233.390694)
		(end 145.291048 -233.390694)
		(width 0.0889)
		(layer "In6.Cu")
		(net "M_K_CPU1_SA_DQ<12>")
	)
	(segment
		(start 174.44974 -212.219794)
		(end 177.461672 -212.219794)
		(width 0.14478)
		(layer "In6.Cu")
		(net "M_K_CPU1_SA_DQ<12>")
	)
	(segment
		(start 147.047712 -231.43464)
		(end 147.599908 -230.882444)
		(width 0.0889)
		(layer "In6.Cu")
		(net "M_K_CPU1_SA_DQ<12>")
	)
	(segment
		(start 166.106348 -213.06028)
		(end 166.947088 -212.21954)
		(width 0.14478)
		(layer "In6.Cu")
		(net "M_K_CPU1_SA_DQ<12>")
	)
	(segment
		(start 189.641734 -212.219794)
		(end 196.696076 -212.219794)
		(width 0.14478)
		(layer "In6.Cu")
		(net "M_K_CPU1_SA_DQ<12>")
	)
	(segment
		(start 169.917364 -212.21954)
		(end 170.767502 -213.069678)
		(width 0.14478)
		(layer "In6.Cu")
		(net "M_K_CPU1_SA_DQ<12>")
	)
	(segment
		(start 156.794708 -220.713808)
		(end 164.448236 -213.06028)
		(width 0.14478)
		(layer "In6.Cu")
		(net "M_K_CPU1_SA_DQ<12>")
	)
	(segment
		(start 178.311556 -213.069678)
		(end 181.131464 -213.069678)
		(width 0.14478)
		(layer "In6.Cu")
		(net "M_K_CPU1_SA_DQ<12>")
	)
	(segment
		(start 170.767502 -213.069678)
		(end 173.599856 -213.069678)
		(width 0.14478)
		(layer "In6.Cu")
		(net "M_K_CPU1_SA_DQ<12>")
	)
	(segment
		(start 147.599908 -230.882444)
		(end 148.133308 -230.882444)
		(width 0.0889)
		(layer "In6.Cu")
		(net "M_K_CPU1_SA_DQ<12>")
	)
	(segment
		(start 156.794708 -222.221044)
		(end 156.794708 -220.713808)
		(width 0.14478)
		(layer "In6.Cu")
		(net "M_K_CPU1_SA_DQ<12>")
	)
	(segment
		(start 197.40626 -212.373464)
		(end 197.569328 -212.210396)
		(width 0.14478)
		(layer "In6.Cu")
		(net "M_K_CPU1_SA_DQ<12>")
	)
	(segment
		(start 197.243192 -212.942424)
		(end 197.40626 -212.779356)
		(width 0.14478)
		(layer "In6.Cu")
		(net "M_K_CPU1_SA_DQ<12>")
	)
	(segment
		(start 142.640812 -233.409744)
		(end 142.663164 -233.493056)
		(width 0.0889)
		(layer "In6.Cu")
		(net "M_K_CPU1_SA_DQ<12>")
	)
	(segment
		(start 146.582892 -231.43464)
		(end 147.047712 -231.43464)
		(width 0.0889)
		(layer "In6.Cu")
		(net "M_K_CPU1_SA_DQ<12>")
	)
	(segment
		(start 148.133308 -230.882444)
		(end 148.290788 -230.724964)
		(width 0.0889)
		(layer "In6.Cu")
		(net "M_K_CPU1_SA_DQ<12>")
	)
	(segment
		(start 197.012814 -212.942424)
		(end 197.243192 -212.942424)
		(width 0.14478)
		(layer "In6.Cu")
		(net "M_K_CPU1_SA_DQ<12>")
	)
	(segment
		(start 197.569328 -212.210396)
		(end 198.279258 -212.210396)
		(width 0.14478)
		(layer "In6.Cu")
		(net "M_K_CPU1_SA_DQ<12>")
	)
	(segment
		(start 188.79185 -213.069678)
		(end 189.641734 -212.219794)
		(width 0.14478)
		(layer "In6.Cu")
		(net "M_K_CPU1_SA_DQ<12>")
	)
	(segment
		(start 166.947088 -212.21954)
		(end 169.917364 -212.21954)
		(width 0.14478)
		(layer "In6.Cu")
		(net "M_K_CPU1_SA_DQ<12>")
	)
	(segment
		(start 145.291048 -233.390694)
		(end 146.387312 -232.29443)
		(width 0.0889)
		(layer "In6.Cu")
		(net "M_K_CPU1_SA_DQ<12>")
	)
	(segment
		(start 164.448236 -213.06028)
		(end 166.106348 -213.06028)
		(width 0.14478)
		(layer "In6.Cu")
		(net "M_K_CPU1_SA_DQ<12>")
	)
	(segment
		(start 181.981348 -212.219794)
		(end 185.005472 -212.219794)
		(width 0.14478)
		(layer "In6.Cu")
		(net "M_K_CPU1_SA_DQ<12>")
	)
	(segment
		(start 196.849746 -212.373464)
		(end 196.849746 -212.779356)
		(width 0.14478)
		(layer "In6.Cu")
		(net "M_K_CPU1_SA_DQ<12>")
	)
	(segment
		(start 146.387312 -232.29443)
		(end 146.387312 -231.63022)
		(width 0.0889)
		(layer "In6.Cu")
		(net "M_K_CPU1_SA_DQ<12>")
	)
	(segment
		(start 173.599856 -213.069678)
		(end 174.44974 -212.219794)
		(width 0.14478)
		(layer "In6.Cu")
		(net "M_K_CPU1_SA_DQ<12>")
	)
	(segment
		(start 177.461672 -212.219794)
		(end 178.311556 -213.069678)
		(width 0.14478)
		(layer "In6.Cu")
		(net "M_K_CPU1_SA_DQ<12>")
	)
	(arc
		(start 142.663164 -233.493056)
		(mid 142.825353 -233.515791)
		(end 142.98168 -233.466894)
		(width 0.0889)
		(layer "In6.Cu")
		(net "M_K_CPU1_SA_DQ<12>")
	)
	(arc
		(start 144.495774 -233.47172)
		(mid 144.679282 -233.517214)
		(end 144.861534 -233.466894)
		(width 0.0889)
		(layer "In6.Cu")
		(net "M_K_CPU1_SA_DQ<12>")
	)
	(arc
		(start 143.932148 -233.460798)
		(mid 144.21058 -233.3907)
		(end 144.487392 -233.466894)
		(width 0.0889)
		(layer "In6.Cu")
		(net "M_K_CPU1_SA_DQ<12>")
	)
	(arc
		(start 142.98168 -233.466894)
		(mid 143.264636 -233.390717)
		(end 143.547592 -233.466894)
		(width 0.0889)
		(layer "In6.Cu")
		(net "M_K_CPU1_SA_DQ<12>")
	)
	(arc
		(start 143.547592 -233.466894)
		(mid 143.729843 -233.517244)
		(end 143.913352 -233.47172)
		(width 0.0889)
		(layer "In6.Cu")
		(net "M_K_CPU1_SA_DQ<12>")
	)
	(arc
		(start 144.861534 -233.466894)
		(mid 144.998097 -233.410061)
		(end 145.144744 -233.390694)
		(width 0.0889)
		(layer "In6.Cu")
		(net "M_K_CPU1_SA_DQ<12>")
	)
	(segment
		(start 140.447776 -231.79024)
		(end 140.914882 -231.524302)
		(width 0.10668)
		(layer "F.Cu")
		(net "M_K_CPU1_SA_DQ<11>")
	)
	(segment
		(start 188.367924 -209.66049)
		(end 188.673232 -209.66049)
		(width 0.14478)
		(layer "In6.Cu")
		(net "M_K_CPU1_SA_DQ<11>")
	)
	(segment
		(start 193.735706 -208.97342)
		(end 193.898774 -208.810352)
		(width 0.14478)
		(layer "In6.Cu")
		(net "M_K_CPU1_SA_DQ<11>")
	)
	(segment
		(start 182.931816 -208.416144)
		(end 183.094884 -208.579212)
		(width 0.14478)
		(layer "In6.Cu")
		(net "M_K_CPU1_SA_DQ<11>")
	)
	(segment
		(start 193.179192 -209.137758)
		(end 193.34226 -209.300826)
		(width 0.14478)
		(layer "In6.Cu")
		(net "M_K_CPU1_SA_DQ<11>")
	)
	(segment
		(start 188.204856 -209.435192)
		(end 188.204856 -209.497422)
		(width 0.14478)
		(layer "In6.Cu")
		(net "M_K_CPU1_SA_DQ<11>")
	)
	(segment
		(start 193.572638 -209.300826)
		(end 193.735706 -209.137758)
		(width 0.14478)
		(layer "In6.Cu")
		(net "M_K_CPU1_SA_DQ<11>")
	)
	(segment
		(start 180.683408 -209.497422)
		(end 180.846476 -209.66049)
		(width 0.14478)
		(layer "In6.Cu")
		(net "M_K_CPU1_SA_DQ<11>")
	)
	(segment
		(start 146.383248 -229.388924)
		(end 146.754088 -229.388924)
		(width 0.0889)
		(layer "In6.Cu")
		(net "M_K_CPU1_SA_DQ<11>")
	)
	(segment
		(start 146.754088 -229.388924)
		(end 147.06219 -229.080822)
		(width 0.0889)
		(layer "In6.Cu")
		(net "M_K_CPU1_SA_DQ<11>")
	)
	(segment
		(start 183.094884 -208.647284)
		(end 183.248554 -208.800954)
		(width 0.14478)
		(layer "In6.Cu")
		(net "M_K_CPU1_SA_DQ<11>")
	)
	(segment
		(start 185.83656 -209.651092)
		(end 187.494672 -209.651092)
		(width 0.14478)
		(layer "In6.Cu")
		(net "M_K_CPU1_SA_DQ<11>")
	)
	(segment
		(start 191.773556 -208.800954)
		(end 191.927226 -208.647284)
		(width 0.14478)
		(layer "In6.Cu")
		(net "M_K_CPU1_SA_DQ<11>")
	)
	(segment
		(start 191.927226 -208.584292)
		(end 192.090294 -208.421224)
		(width 0.14478)
		(layer "In6.Cu")
		(net "M_K_CPU1_SA_DQ<11>")
	)
	(segment
		(start 182.53837 -208.647284)
		(end 182.53837 -208.579212)
		(width 0.14478)
		(layer "In6.Cu")
		(net "M_K_CPU1_SA_DQ<11>")
	)
	(segment
		(start 192.48374 -208.584292)
		(end 192.48374 -208.647284)
		(width 0.14478)
		(layer "In6.Cu")
		(net "M_K_CPU1_SA_DQ<11>")
	)
	(segment
		(start 193.179192 -208.97342)
		(end 193.179192 -209.137758)
		(width 0.14478)
		(layer "In6.Cu")
		(net "M_K_CPU1_SA_DQ<11>")
	)
	(segment
		(start 188.673232 -209.66049)
		(end 189.532768 -208.800954)
		(width 0.14478)
		(layer "In6.Cu")
		(net "M_K_CPU1_SA_DQ<11>")
	)
	(segment
		(start 190.030354 -208.656174)
		(end 190.030354 -208.566766)
		(width 0.14478)
		(layer "In6.Cu")
		(net "M_K_CPU1_SA_DQ<11>")
	)
	(segment
		(start 190.175134 -208.421986)
		(end 190.437008 -208.421986)
		(width 0.14478)
		(layer "In6.Cu")
		(net "M_K_CPU1_SA_DQ<11>")
	)
	(segment
		(start 192.48374 -208.647284)
		(end 192.646808 -208.810352)
		(width 0.14478)
		(layer "In6.Cu")
		(net "M_K_CPU1_SA_DQ<11>")
	)
	(segment
		(start 163.829746 -209.66049)
		(end 166.066724 -209.66049)
		(width 0.14478)
		(layer "In6.Cu")
		(net "M_K_CPU1_SA_DQ<11>")
	)
	(segment
		(start 147.872704 -227.820728)
		(end 154.196288 -221.497144)
		(width 0.14478)
		(layer "In6.Cu")
		(net "M_K_CPU1_SA_DQ<11>")
	)
	(segment
		(start 180.289962 -209.269584)
		(end 180.52034 -209.269584)
		(width 0.14478)
		(layer "In6.Cu")
		(net "M_K_CPU1_SA_DQ<11>")
	)
	(segment
		(start 180.126894 -209.432652)
		(end 180.289962 -209.269584)
		(width 0.14478)
		(layer "In6.Cu")
		(net "M_K_CPU1_SA_DQ<11>")
	)
	(segment
		(start 143.92148 -231.201976)
		(end 143.931894 -231.208072)
		(width 0.0889)
		(layer "In6.Cu")
		(net "M_K_CPU1_SA_DQ<11>")
	)
	(segment
		(start 180.52034 -209.269584)
		(end 180.683408 -209.432652)
		(width 0.14478)
		(layer "In6.Cu")
		(net "M_K_CPU1_SA_DQ<11>")
	)
	(segment
		(start 141.667738 -231.201976)
		(end 141.67612 -231.19715)
		(width 0.0889)
		(layer "In6.Cu")
		(net "M_K_CPU1_SA_DQ<11>")
	)
	(segment
		(start 190.437008 -208.421986)
		(end 190.581788 -208.566766)
		(width 0.14478)
		(layer "In6.Cu")
		(net "M_K_CPU1_SA_DQ<11>")
	)
	(segment
		(start 145.677128 -230.752904)
		(end 145.677128 -230.095044)
		(width 0.0889)
		(layer "In6.Cu")
		(net "M_K_CPU1_SA_DQ<11>")
	)
	(segment
		(start 147.06219 -229.080822)
		(end 147.380198 -228.313234)
		(width 0.0889)
		(layer "In6.Cu")
		(net "M_K_CPU1_SA_DQ<11>")
	)
	(segment
		(start 182.53837 -208.579212)
		(end 182.701438 -208.416144)
		(width 0.14478)
		(layer "In6.Cu")
		(net "M_K_CPU1_SA_DQ<11>")
	)
	(segment
		(start 181.140862 -209.66049)
		(end 181.991 -208.810352)
		(width 0.14478)
		(layer "In6.Cu")
		(net "M_K_CPU1_SA_DQ<11>")
	)
	(segment
		(start 143.909796 -231.195118)
		(end 143.92148 -231.201976)
		(width 0.0889)
		(layer "In6.Cu")
		(net "M_K_CPU1_SA_DQ<11>")
	)
	(segment
		(start 169.898568 -208.800954)
		(end 170.748706 -209.651092)
		(width 0.14478)
		(layer "In6.Cu")
		(net "M_K_CPU1_SA_DQ<11>")
	)
	(segment
		(start 166.066724 -209.66049)
		(end 166.92626 -208.800954)
		(width 0.14478)
		(layer "In6.Cu")
		(net "M_K_CPU1_SA_DQ<11>")
	)
	(segment
		(start 179.973224 -209.651092)
		(end 180.126894 -209.497422)
		(width 0.14478)
		(layer "In6.Cu")
		(net "M_K_CPU1_SA_DQ<11>")
	)
	(segment
		(start 174.46879 -208.800954)
		(end 177.442622 -208.800954)
		(width 0.14478)
		(layer "In6.Cu")
		(net "M_K_CPU1_SA_DQ<11>")
	)
	(segment
		(start 193.898774 -208.810352)
		(end 194.17919 -208.810352)
		(width 0.14478)
		(layer "In6.Cu")
		(net "M_K_CPU1_SA_DQ<11>")
	)
	(segment
		(start 178.29276 -209.651092)
		(end 179.973224 -209.651092)
		(width 0.14478)
		(layer "In6.Cu")
		(net "M_K_CPU1_SA_DQ<11>")
	)
	(segment
		(start 192.090294 -208.421224)
		(end 192.320672 -208.421224)
		(width 0.14478)
		(layer "In6.Cu")
		(net "M_K_CPU1_SA_DQ<11>")
	)
	(segment
		(start 193.34226 -209.300826)
		(end 193.572638 -209.300826)
		(width 0.14478)
		(layer "In6.Cu")
		(net "M_K_CPU1_SA_DQ<11>")
	)
	(segment
		(start 191.927226 -208.647284)
		(end 191.927226 -208.584292)
		(width 0.14478)
		(layer "In6.Cu")
		(net "M_K_CPU1_SA_DQ<11>")
	)
	(segment
		(start 180.683408 -209.432652)
		(end 180.683408 -209.497422)
		(width 0.14478)
		(layer "In6.Cu")
		(net "M_K_CPU1_SA_DQ<11>")
	)
	(segment
		(start 188.204856 -209.497422)
		(end 188.367924 -209.66049)
		(width 0.14478)
		(layer "In6.Cu")
		(net "M_K_CPU1_SA_DQ<11>")
	)
	(segment
		(start 180.846476 -209.66049)
		(end 181.140862 -209.66049)
		(width 0.14478)
		(layer "In6.Cu")
		(net "M_K_CPU1_SA_DQ<11>")
	)
	(segment
		(start 145.228056 -231.201976)
		(end 145.677128 -230.752904)
		(width 0.0889)
		(layer "In6.Cu")
		(net "M_K_CPU1_SA_DQ<11>")
	)
	(segment
		(start 192.646808 -208.810352)
		(end 193.016124 -208.810352)
		(width 0.14478)
		(layer "In6.Cu")
		(net "M_K_CPU1_SA_DQ<11>")
	)
	(segment
		(start 147.380198 -228.313234)
		(end 147.872704 -227.820728)
		(width 0.0889)
		(layer "In6.Cu")
		(net "M_K_CPU1_SA_DQ<11>")
	)
	(segment
		(start 193.016124 -208.810352)
		(end 193.179192 -208.97342)
		(width 0.14478)
		(layer "In6.Cu")
		(net "M_K_CPU1_SA_DQ<11>")
	)
	(segment
		(start 184.986422 -208.800954)
		(end 185.83656 -209.651092)
		(width 0.14478)
		(layer "In6.Cu")
		(net "M_K_CPU1_SA_DQ<11>")
	)
	(segment
		(start 181.991 -208.810352)
		(end 182.375302 -208.810352)
		(width 0.14478)
		(layer "In6.Cu")
		(net "M_K_CPU1_SA_DQ<11>")
	)
	(segment
		(start 190.030354 -208.566766)
		(end 190.175134 -208.421986)
		(width 0.14478)
		(layer "In6.Cu")
		(net "M_K_CPU1_SA_DQ<11>")
	)
	(segment
		(start 180.126894 -209.497422)
		(end 180.126894 -209.432652)
		(width 0.14478)
		(layer "In6.Cu")
		(net "M_K_CPU1_SA_DQ<11>")
	)
	(segment
		(start 187.648342 -209.497422)
		(end 187.648342 -209.435192)
		(width 0.14478)
		(layer "In6.Cu")
		(net "M_K_CPU1_SA_DQ<11>")
	)
	(segment
		(start 145.677128 -230.095044)
		(end 146.383248 -229.388924)
		(width 0.0889)
		(layer "In6.Cu")
		(net "M_K_CPU1_SA_DQ<11>")
	)
	(segment
		(start 182.375302 -208.810352)
		(end 182.53837 -208.647284)
		(width 0.14478)
		(layer "In6.Cu")
		(net "M_K_CPU1_SA_DQ<11>")
	)
	(segment
		(start 154.196288 -221.497144)
		(end 154.196288 -219.293948)
		(width 0.14478)
		(layer "In6.Cu")
		(net "M_K_CPU1_SA_DQ<11>")
	)
	(segment
		(start 173.618652 -209.651092)
		(end 174.46879 -208.800954)
		(width 0.14478)
		(layer "In6.Cu")
		(net "M_K_CPU1_SA_DQ<11>")
	)
	(segment
		(start 189.532768 -208.800954)
		(end 189.885574 -208.800954)
		(width 0.14478)
		(layer "In6.Cu")
		(net "M_K_CPU1_SA_DQ<11>")
	)
	(segment
		(start 190.726568 -208.800954)
		(end 191.773556 -208.800954)
		(width 0.14478)
		(layer "In6.Cu")
		(net "M_K_CPU1_SA_DQ<11>")
	)
	(segment
		(start 187.494672 -209.651092)
		(end 187.648342 -209.497422)
		(width 0.14478)
		(layer "In6.Cu")
		(net "M_K_CPU1_SA_DQ<11>")
	)
	(segment
		(start 170.748706 -209.651092)
		(end 173.618652 -209.651092)
		(width 0.14478)
		(layer "In6.Cu")
		(net "M_K_CPU1_SA_DQ<11>")
	)
	(segment
		(start 183.248554 -208.800954)
		(end 184.986422 -208.800954)
		(width 0.14478)
		(layer "In6.Cu")
		(net "M_K_CPU1_SA_DQ<11>")
	)
	(segment
		(start 194.17919 -208.810352)
		(end 194.604132 -209.235294)
		(width 0.14478)
		(layer "In6.Cu")
		(net "M_K_CPU1_SA_DQ<11>")
	)
	(segment
		(start 183.094884 -208.579212)
		(end 183.094884 -208.647284)
		(width 0.14478)
		(layer "In6.Cu")
		(net "M_K_CPU1_SA_DQ<11>")
	)
	(segment
		(start 166.92626 -208.800954)
		(end 169.898568 -208.800954)
		(width 0.14478)
		(layer "In6.Cu")
		(net "M_K_CPU1_SA_DQ<11>")
	)
	(segment
		(start 193.735706 -209.137758)
		(end 193.735706 -208.97342)
		(width 0.14478)
		(layer "In6.Cu")
		(net "M_K_CPU1_SA_DQ<11>")
	)
	(segment
		(start 177.442622 -208.800954)
		(end 178.29276 -209.651092)
		(width 0.14478)
		(layer "In6.Cu")
		(net "M_K_CPU1_SA_DQ<11>")
	)
	(segment
		(start 141.068806 -231.258872)
		(end 141.164564 -231.233472)
		(width 0.0889)
		(layer "In6.Cu")
		(net "M_K_CPU1_SA_DQ<11>")
	)
	(segment
		(start 154.196288 -219.293948)
		(end 163.829746 -209.66049)
		(width 0.14478)
		(layer "In6.Cu")
		(net "M_K_CPU1_SA_DQ<11>")
	)
	(segment
		(start 189.885574 -208.800954)
		(end 190.030354 -208.656174)
		(width 0.14478)
		(layer "In6.Cu")
		(net "M_K_CPU1_SA_DQ<11>")
	)
	(segment
		(start 182.701438 -208.416144)
		(end 182.931816 -208.416144)
		(width 0.14478)
		(layer "In6.Cu")
		(net "M_K_CPU1_SA_DQ<11>")
	)
	(segment
		(start 190.581788 -208.566766)
		(end 190.581788 -208.656174)
		(width 0.14478)
		(layer "In6.Cu")
		(net "M_K_CPU1_SA_DQ<11>")
	)
	(segment
		(start 187.648342 -209.435192)
		(end 187.81141 -209.272124)
		(width 0.14478)
		(layer "In6.Cu")
		(net "M_K_CPU1_SA_DQ<11>")
	)
	(segment
		(start 140.914882 -231.524302)
		(end 141.068806 -231.258872)
		(width 0.0889)
		(layer "In6.Cu")
		(net "M_K_CPU1_SA_DQ<11>")
	)
	(segment
		(start 144.487138 -231.201976)
		(end 145.228056 -231.201976)
		(width 0.0889)
		(layer "In6.Cu")
		(net "M_K_CPU1_SA_DQ<11>")
	)
	(segment
		(start 187.81141 -209.272124)
		(end 188.041788 -209.272124)
		(width 0.14478)
		(layer "In6.Cu")
		(net "M_K_CPU1_SA_DQ<11>")
	)
	(segment
		(start 190.581788 -208.656174)
		(end 190.726568 -208.800954)
		(width 0.14478)
		(layer "In6.Cu")
		(net "M_K_CPU1_SA_DQ<11>")
	)
	(segment
		(start 188.041788 -209.272124)
		(end 188.204856 -209.435192)
		(width 0.14478)
		(layer "In6.Cu")
		(net "M_K_CPU1_SA_DQ<11>")
	)
	(segment
		(start 192.320672 -208.421224)
		(end 192.48374 -208.584292)
		(width 0.14478)
		(layer "In6.Cu")
		(net "M_K_CPU1_SA_DQ<11>")
	)
	(arc
		(start 142.04188 -231.201976)
		(mid 142.324836 -231.278153)
		(end 142.607792 -231.201976)
		(width 0.0889)
		(layer "In6.Cu")
		(net "M_K_CPU1_SA_DQ<11>")
	)
	(arc
		(start 143.931894 -231.208072)
		(mid 144.210326 -231.27817)
		(end 144.487138 -231.201976)
		(width 0.0889)
		(layer "In6.Cu")
		(net "M_K_CPU1_SA_DQ<11>")
	)
	(arc
		(start 141.164564 -231.233472)
		(mid 141.419886 -231.277172)
		(end 141.667738 -231.201976)
		(width 0.0889)
		(layer "In6.Cu")
		(net "M_K_CPU1_SA_DQ<11>")
	)
	(arc
		(start 142.98168 -231.201976)
		(mid 143.264636 -231.278153)
		(end 143.547592 -231.201976)
		(width 0.0889)
		(layer "In6.Cu")
		(net "M_K_CPU1_SA_DQ<11>")
	)
	(arc
		(start 143.547592 -231.201976)
		(mid 143.727797 -231.151625)
		(end 143.909796 -231.195118)
		(width 0.0889)
		(layer "In6.Cu")
		(net "M_K_CPU1_SA_DQ<11>")
	)
	(arc
		(start 141.67612 -231.19715)
		(mid 141.859628 -231.151625)
		(end 142.04188 -231.201976)
		(width 0.0889)
		(layer "In6.Cu")
		(net "M_K_CPU1_SA_DQ<11>")
	)
	(arc
		(start 142.607792 -231.201976)
		(mid 142.794736 -231.151687)
		(end 142.98168 -231.201976)
		(width 0.0889)
		(layer "In6.Cu")
		(net "M_K_CPU1_SA_DQ<11>")
	)
	(segment
		(start 141.857984 -230.980234)
		(end 142.324836 -230.71455)
		(width 0.10668)
		(layer "F.Cu")
		(net "M_K_CPU1_SA_DQ<10>")
	)
	(segment
		(start 153.286968 -221.120208)
		(end 153.286968 -218.844368)
		(width 0.14478)
		(layer "In6.Cu")
		(net "M_K_CPU1_SA_DQ<10>")
	)
	(segment
		(start 182.580788 -206.947262)
		(end 182.580788 -206.885032)
		(width 0.14478)
		(layer "In6.Cu")
		(net "M_K_CPU1_SA_DQ<10>")
	)
	(segment
		(start 183.137302 -206.885032)
		(end 183.137302 -206.947262)
		(width 0.14478)
		(layer "In6.Cu")
		(net "M_K_CPU1_SA_DQ<10>")
	)
	(segment
		(start 173.609254 -207.960468)
		(end 174.459392 -207.11033)
		(width 0.14478)
		(layer "In6.Cu")
		(net "M_K_CPU1_SA_DQ<10>")
	)
	(segment
		(start 188.181742 -207.733392)
		(end 188.181742 -207.7974)
		(width 0.14478)
		(layer "In6.Cu")
		(net "M_K_CPU1_SA_DQ<10>")
	)
	(segment
		(start 178.302158 -207.960468)
		(end 179.890928 -207.960468)
		(width 0.14478)
		(layer "In6.Cu")
		(net "M_K_CPU1_SA_DQ<10>")
	)
	(segment
		(start 173.118272 -207.728312)
		(end 173.118272 -207.7974)
		(width 0.14478)
		(layer "In6.Cu")
		(net "M_K_CPU1_SA_DQ<10>")
	)
	(segment
		(start 174.459392 -207.11033)
		(end 174.834804 -207.11033)
		(width 0.14478)
		(layer "In6.Cu")
		(net "M_K_CPU1_SA_DQ<10>")
	)
	(segment
		(start 147.439126 -226.96805)
		(end 147.97405 -226.433126)
		(width 0.0889)
		(layer "In6.Cu")
		(net "M_K_CPU1_SA_DQ<10>")
	)
	(segment
		(start 147.97405 -226.433126)
		(end 153.286968 -221.120208)
		(width 0.14478)
		(layer "In6.Cu")
		(net "M_K_CPU1_SA_DQ<10>")
	)
	(segment
		(start 164.170868 -207.960468)
		(end 166.066724 -207.960468)
		(width 0.14478)
		(layer "In6.Cu")
		(net "M_K_CPU1_SA_DQ<10>")
	)
	(segment
		(start 146.205956 -228.883464)
		(end 146.562826 -228.883464)
		(width 0.0889)
		(layer "In6.Cu")
		(net "M_K_CPU1_SA_DQ<10>")
	)
	(segment
		(start 180.217064 -207.565244)
		(end 180.447442 -207.565244)
		(width 0.14478)
		(layer "In6.Cu")
		(net "M_K_CPU1_SA_DQ<10>")
	)
	(segment
		(start 146.791172 -228.655118)
		(end 146.913346 -228.360224)
		(width 0.0889)
		(layer "In6.Cu")
		(net "M_K_CPU1_SA_DQ<10>")
	)
	(segment
		(start 192.976246 -206.716884)
		(end 193.139314 -206.879952)
		(width 0.14478)
		(layer "In6.Cu")
		(net "M_K_CPU1_SA_DQ<10>")
	)
	(segment
		(start 166.066724 -207.960468)
		(end 166.916862 -207.11033)
		(width 0.14478)
		(layer "In6.Cu")
		(net "M_K_CPU1_SA_DQ<10>")
	)
	(segment
		(start 187.46216 -207.960468)
		(end 187.625228 -207.7974)
		(width 0.14478)
		(layer "In6.Cu")
		(net "M_K_CPU1_SA_DQ<10>")
	)
	(segment
		(start 180.053996 -207.728312)
		(end 180.217064 -207.565244)
		(width 0.14478)
		(layer "In6.Cu")
		(net "M_K_CPU1_SA_DQ<10>")
	)
	(segment
		(start 185.845958 -207.960468)
		(end 187.46216 -207.960468)
		(width 0.14478)
		(layer "In6.Cu")
		(net "M_K_CPU1_SA_DQ<10>")
	)
	(segment
		(start 193.302382 -207.499204)
		(end 193.53276 -207.499204)
		(width 0.14478)
		(layer "In6.Cu")
		(net "M_K_CPU1_SA_DQ<10>")
	)
	(segment
		(start 181.991 -207.11033)
		(end 182.41772 -207.11033)
		(width 0.14478)
		(layer "In6.Cu")
		(net "M_K_CPU1_SA_DQ<10>")
	)
	(segment
		(start 145.281142 -229.808278)
		(end 146.205956 -228.883464)
		(width 0.0889)
		(layer "In6.Cu")
		(net "M_K_CPU1_SA_DQ<10>")
	)
	(segment
		(start 184.99582 -207.11033)
		(end 185.845958 -207.960468)
		(width 0.14478)
		(layer "In6.Cu")
		(net "M_K_CPU1_SA_DQ<10>")
	)
	(segment
		(start 173.28134 -207.960468)
		(end 173.609254 -207.960468)
		(width 0.14478)
		(layer "In6.Cu")
		(net "M_K_CPU1_SA_DQ<10>")
	)
	(segment
		(start 182.974234 -206.721964)
		(end 183.137302 -206.885032)
		(width 0.14478)
		(layer "In6.Cu")
		(net "M_K_CPU1_SA_DQ<10>")
	)
	(segment
		(start 187.625228 -207.733392)
		(end 187.788296 -207.570324)
		(width 0.14478)
		(layer "In6.Cu")
		(net "M_K_CPU1_SA_DQ<10>")
	)
	(segment
		(start 187.788296 -207.570324)
		(end 188.018674 -207.570324)
		(width 0.14478)
		(layer "In6.Cu")
		(net "M_K_CPU1_SA_DQ<10>")
	)
	(segment
		(start 188.673232 -207.960468)
		(end 189.52337 -207.11033)
		(width 0.14478)
		(layer "In6.Cu")
		(net "M_K_CPU1_SA_DQ<10>")
	)
	(segment
		(start 172.561758 -207.7974)
		(end 172.561758 -207.728312)
		(width 0.14478)
		(layer "In6.Cu")
		(net "M_K_CPU1_SA_DQ<10>")
	)
	(segment
		(start 143.077692 -230.39197)
		(end 143.086074 -230.387144)
		(width 0.0889)
		(layer "In6.Cu")
		(net "M_K_CPU1_SA_DQ<10>")
	)
	(segment
		(start 182.41772 -207.11033)
		(end 182.580788 -206.947262)
		(width 0.14478)
		(layer "In6.Cu")
		(net "M_K_CPU1_SA_DQ<10>")
	)
	(segment
		(start 183.137302 -206.947262)
		(end 183.30037 -207.11033)
		(width 0.14478)
		(layer "In6.Cu")
		(net "M_K_CPU1_SA_DQ<10>")
	)
	(segment
		(start 187.625228 -207.7974)
		(end 187.625228 -207.733392)
		(width 0.14478)
		(layer "In6.Cu")
		(net "M_K_CPU1_SA_DQ<10>")
	)
	(segment
		(start 188.181742 -207.7974)
		(end 188.34481 -207.960468)
		(width 0.14478)
		(layer "In6.Cu")
		(net "M_K_CPU1_SA_DQ<10>")
	)
	(segment
		(start 172.39869 -207.960468)
		(end 172.561758 -207.7974)
		(width 0.14478)
		(layer "In6.Cu")
		(net "M_K_CPU1_SA_DQ<10>")
	)
	(segment
		(start 144.007078 -230.398066)
		(end 144.017492 -230.39197)
		(width 0.0889)
		(layer "In6.Cu")
		(net "M_K_CPU1_SA_DQ<10>")
	)
	(segment
		(start 146.913346 -228.360224)
		(end 146.913346 -227.848414)
		(width 0.0889)
		(layer "In6.Cu")
		(net "M_K_CPU1_SA_DQ<10>")
	)
	(segment
		(start 189.52337 -207.11033)
		(end 191.863218 -207.11033)
		(width 0.14478)
		(layer "In6.Cu")
		(net "M_K_CPU1_SA_DQ<10>")
	)
	(segment
		(start 183.30037 -207.11033)
		(end 184.99582 -207.11033)
		(width 0.14478)
		(layer "In6.Cu")
		(net "M_K_CPU1_SA_DQ<10>")
	)
	(segment
		(start 175.554386 -206.947262)
		(end 175.717454 -207.11033)
		(width 0.14478)
		(layer "In6.Cu")
		(net "M_K_CPU1_SA_DQ<10>")
	)
	(segment
		(start 181.140862 -207.960468)
		(end 181.991 -207.11033)
		(width 0.14478)
		(layer "In6.Cu")
		(net "M_K_CPU1_SA_DQ<10>")
	)
	(segment
		(start 142.324836 -230.71455)
		(end 142.47876 -230.44912)
		(width 0.0889)
		(layer "In6.Cu")
		(net "M_K_CPU1_SA_DQ<10>")
	)
	(segment
		(start 142.47876 -230.44912)
		(end 142.574772 -230.42372)
		(width 0.0889)
		(layer "In6.Cu")
		(net "M_K_CPU1_SA_DQ<10>")
	)
	(segment
		(start 172.955204 -207.565244)
		(end 173.118272 -207.728312)
		(width 0.14478)
		(layer "In6.Cu")
		(net "M_K_CPU1_SA_DQ<10>")
	)
	(segment
		(start 174.834804 -207.11033)
		(end 174.997872 -206.947262)
		(width 0.14478)
		(layer "In6.Cu")
		(net "M_K_CPU1_SA_DQ<10>")
	)
	(segment
		(start 193.139314 -207.336136)
		(end 193.302382 -207.499204)
		(width 0.14478)
		(layer "In6.Cu")
		(net "M_K_CPU1_SA_DQ<10>")
	)
	(segment
		(start 182.743856 -206.721964)
		(end 182.974234 -206.721964)
		(width 0.14478)
		(layer "In6.Cu")
		(net "M_K_CPU1_SA_DQ<10>")
	)
	(segment
		(start 177.45202 -207.11033)
		(end 178.302158 -207.960468)
		(width 0.14478)
		(layer "In6.Cu")
		(net "M_K_CPU1_SA_DQ<10>")
	)
	(segment
		(start 180.773578 -207.960468)
		(end 181.140862 -207.960468)
		(width 0.14478)
		(layer "In6.Cu")
		(net "M_K_CPU1_SA_DQ<10>")
	)
	(segment
		(start 166.916862 -207.11033)
		(end 169.907966 -207.11033)
		(width 0.14478)
		(layer "In6.Cu")
		(net "M_K_CPU1_SA_DQ<10>")
	)
	(segment
		(start 191.863218 -207.11033)
		(end 192.026286 -207.273398)
		(width 0.14478)
		(layer "In6.Cu")
		(net "M_K_CPU1_SA_DQ<10>")
	)
	(segment
		(start 144.627854 -229.808278)
		(end 145.281142 -229.808278)
		(width 0.0889)
		(layer "In6.Cu")
		(net "M_K_CPU1_SA_DQ<10>")
	)
	(segment
		(start 170.758104 -207.960468)
		(end 172.39869 -207.960468)
		(width 0.14478)
		(layer "In6.Cu")
		(net "M_K_CPU1_SA_DQ<10>")
	)
	(segment
		(start 188.018674 -207.570324)
		(end 188.181742 -207.733392)
		(width 0.14478)
		(layer "In6.Cu")
		(net "M_K_CPU1_SA_DQ<10>")
	)
	(segment
		(start 192.419732 -207.499204)
		(end 192.5828 -207.336136)
		(width 0.14478)
		(layer "In6.Cu")
		(net "M_K_CPU1_SA_DQ<10>")
	)
	(segment
		(start 192.5828 -206.879952)
		(end 192.745868 -206.716884)
		(width 0.14478)
		(layer "In6.Cu")
		(net "M_K_CPU1_SA_DQ<10>")
	)
	(segment
		(start 180.61051 -207.728312)
		(end 180.61051 -207.7974)
		(width 0.14478)
		(layer "In6.Cu")
		(net "M_K_CPU1_SA_DQ<10>")
	)
	(segment
		(start 192.026286 -207.336136)
		(end 192.189354 -207.499204)
		(width 0.14478)
		(layer "In6.Cu")
		(net "M_K_CPU1_SA_DQ<10>")
	)
	(segment
		(start 175.391318 -206.721964)
		(end 175.554386 -206.885032)
		(width 0.14478)
		(layer "In6.Cu")
		(net "M_K_CPU1_SA_DQ<10>")
	)
	(segment
		(start 192.5828 -207.336136)
		(end 192.5828 -206.879952)
		(width 0.14478)
		(layer "In6.Cu")
		(net "M_K_CPU1_SA_DQ<10>")
	)
	(segment
		(start 174.997872 -206.947262)
		(end 174.997872 -206.885032)
		(width 0.14478)
		(layer "In6.Cu")
		(net "M_K_CPU1_SA_DQ<10>")
	)
	(segment
		(start 173.118272 -207.7974)
		(end 173.28134 -207.960468)
		(width 0.14478)
		(layer "In6.Cu")
		(net "M_K_CPU1_SA_DQ<10>")
	)
	(segment
		(start 193.858896 -207.11033)
		(end 194.17919 -207.11033)
		(width 0.14478)
		(layer "In6.Cu")
		(net "M_K_CPU1_SA_DQ<10>")
	)
	(segment
		(start 193.53276 -207.499204)
		(end 193.695828 -207.336136)
		(width 0.14478)
		(layer "In6.Cu")
		(net "M_K_CPU1_SA_DQ<10>")
	)
	(segment
		(start 146.562826 -228.883464)
		(end 146.791172 -228.655118)
		(width 0.0889)
		(layer "In6.Cu")
		(net "M_K_CPU1_SA_DQ<10>")
	)
	(segment
		(start 194.17919 -207.11033)
		(end 194.604132 -207.535272)
		(width 0.14478)
		(layer "In6.Cu")
		(net "M_K_CPU1_SA_DQ<10>")
	)
	(segment
		(start 180.61051 -207.7974)
		(end 180.773578 -207.960468)
		(width 0.14478)
		(layer "In6.Cu")
		(net "M_K_CPU1_SA_DQ<10>")
	)
	(segment
		(start 153.286968 -218.844368)
		(end 164.170868 -207.960468)
		(width 0.14478)
		(layer "In6.Cu")
		(net "M_K_CPU1_SA_DQ<10>")
	)
	(segment
		(start 144.133316 -230.302816)
		(end 144.627854 -229.808278)
		(width 0.0889)
		(layer "In6.Cu")
		(net "M_K_CPU1_SA_DQ<10>")
	)
	(segment
		(start 182.580788 -206.885032)
		(end 182.743856 -206.721964)
		(width 0.14478)
		(layer "In6.Cu")
		(net "M_K_CPU1_SA_DQ<10>")
	)
	(segment
		(start 180.447442 -207.565244)
		(end 180.61051 -207.728312)
		(width 0.14478)
		(layer "In6.Cu")
		(net "M_K_CPU1_SA_DQ<10>")
	)
	(segment
		(start 169.907966 -207.11033)
		(end 170.758104 -207.960468)
		(width 0.14478)
		(layer "In6.Cu")
		(net "M_K_CPU1_SA_DQ<10>")
	)
	(segment
		(start 172.724826 -207.565244)
		(end 172.955204 -207.565244)
		(width 0.14478)
		(layer "In6.Cu")
		(net "M_K_CPU1_SA_DQ<10>")
	)
	(segment
		(start 172.561758 -207.728312)
		(end 172.724826 -207.565244)
		(width 0.14478)
		(layer "In6.Cu")
		(net "M_K_CPU1_SA_DQ<10>")
	)
	(segment
		(start 193.695828 -207.336136)
		(end 193.695828 -207.273398)
		(width 0.14478)
		(layer "In6.Cu")
		(net "M_K_CPU1_SA_DQ<10>")
	)
	(segment
		(start 193.139314 -206.879952)
		(end 193.139314 -207.336136)
		(width 0.14478)
		(layer "In6.Cu")
		(net "M_K_CPU1_SA_DQ<10>")
	)
	(segment
		(start 192.745868 -206.716884)
		(end 192.976246 -206.716884)
		(width 0.14478)
		(layer "In6.Cu")
		(net "M_K_CPU1_SA_DQ<10>")
	)
	(segment
		(start 175.16094 -206.721964)
		(end 175.391318 -206.721964)
		(width 0.14478)
		(layer "In6.Cu")
		(net "M_K_CPU1_SA_DQ<10>")
	)
	(segment
		(start 193.695828 -207.273398)
		(end 193.858896 -207.11033)
		(width 0.14478)
		(layer "In6.Cu")
		(net "M_K_CPU1_SA_DQ<10>")
	)
	(segment
		(start 175.554386 -206.885032)
		(end 175.554386 -206.947262)
		(width 0.14478)
		(layer "In6.Cu")
		(net "M_K_CPU1_SA_DQ<10>")
	)
	(segment
		(start 146.913346 -227.848414)
		(end 147.439126 -227.322634)
		(width 0.0889)
		(layer "In6.Cu")
		(net "M_K_CPU1_SA_DQ<10>")
	)
	(segment
		(start 179.890928 -207.960468)
		(end 180.053996 -207.7974)
		(width 0.14478)
		(layer "In6.Cu")
		(net "M_K_CPU1_SA_DQ<10>")
	)
	(segment
		(start 188.34481 -207.960468)
		(end 188.673232 -207.960468)
		(width 0.14478)
		(layer "In6.Cu")
		(net "M_K_CPU1_SA_DQ<10>")
	)
	(segment
		(start 175.717454 -207.11033)
		(end 177.45202 -207.11033)
		(width 0.14478)
		(layer "In6.Cu")
		(net "M_K_CPU1_SA_DQ<10>")
	)
	(segment
		(start 174.997872 -206.885032)
		(end 175.16094 -206.721964)
		(width 0.14478)
		(layer "In6.Cu")
		(net "M_K_CPU1_SA_DQ<10>")
	)
	(segment
		(start 180.053996 -207.7974)
		(end 180.053996 -207.728312)
		(width 0.14478)
		(layer "In6.Cu")
		(net "M_K_CPU1_SA_DQ<10>")
	)
	(segment
		(start 192.189354 -207.499204)
		(end 192.419732 -207.499204)
		(width 0.14478)
		(layer "In6.Cu")
		(net "M_K_CPU1_SA_DQ<10>")
	)
	(segment
		(start 192.026286 -207.273398)
		(end 192.026286 -207.336136)
		(width 0.14478)
		(layer "In6.Cu")
		(net "M_K_CPU1_SA_DQ<10>")
	)
	(segment
		(start 147.439126 -227.322634)
		(end 147.439126 -226.96805)
		(width 0.0889)
		(layer "In6.Cu")
		(net "M_K_CPU1_SA_DQ<10>")
	)
	(arc
		(start 143.451834 -230.39197)
		(mid 143.728647 -230.468079)
		(end 144.007078 -230.398066)
		(width 0.0889)
		(layer "In6.Cu")
		(net "M_K_CPU1_SA_DQ<10>")
	)
	(arc
		(start 142.574772 -230.42372)
		(mid 142.82998 -230.467177)
		(end 143.077692 -230.39197)
		(width 0.0889)
		(layer "In6.Cu")
		(net "M_K_CPU1_SA_DQ<10>")
	)
	(arc
		(start 143.086074 -230.387144)
		(mid 143.269582 -230.34165)
		(end 143.451834 -230.39197)
		(width 0.0889)
		(layer "In6.Cu")
		(net "M_K_CPU1_SA_DQ<10>")
	)
	(arc
		(start 144.017492 -230.39197)
		(mid 144.078307 -230.351164)
		(end 144.133316 -230.302816)
		(width 0.0889)
		(layer "In6.Cu")
		(net "M_K_CPU1_SA_DQ<10>")
	)
	(segment
		(start 142.327884 -225.310446)
		(end 142.794736 -225.044508)
		(width 0.10668)
		(layer "F.Cu")
		(net "M_K_CPU1_SA_DQ<0>")
	)
	(segment
		(start 143.451834 -222.93707)
		(end 143.482314 -222.91929)
		(width 0.0889)
		(layer "In6.Cu")
		(net "M_K_CPU1_SA_DQ<0>")
	)
	(segment
		(start 169.907966 -196.910198)
		(end 170.758104 -197.760336)
		(width 0.14478)
		(layer "In6.Cu")
		(net "M_K_CPU1_SA_DQ<0>")
	)
	(segment
		(start 143.993108 -221.436946)
		(end 143.993108 -221.232984)
		(width 0.0889)
		(layer "In6.Cu")
		(net "M_K_CPU1_SA_DQ<0>")
	)
	(segment
		(start 166.106348 -197.760336)
		(end 166.956486 -196.910198)
		(width 0.14478)
		(layer "In6.Cu")
		(net "M_K_CPU1_SA_DQ<0>")
	)
	(segment
		(start 143.921734 -222.127064)
		(end 143.9545 -222.108014)
		(width 0.0889)
		(layer "In6.Cu")
		(net "M_K_CPU1_SA_DQ<0>")
	)
	(segment
		(start 181.990746 -196.910452)
		(end 184.996074 -196.910452)
		(width 0.14478)
		(layer "In6.Cu")
		(net "M_K_CPU1_SA_DQ<0>")
	)
	(segment
		(start 144.10944 -221.804484)
		(end 144.10944 -221.553278)
		(width 0.0889)
		(layer "In6.Cu")
		(net "M_K_CPU1_SA_DQ<0>")
	)
	(segment
		(start 187.59932 -197.760336)
		(end 189.651132 -196.910452)
		(width 0.14478)
		(layer "In6.Cu")
		(net "M_K_CPU1_SA_DQ<0>")
	)
	(segment
		(start 181.140862 -197.760336)
		(end 181.990746 -196.910452)
		(width 0.14478)
		(layer "In6.Cu")
		(net "M_K_CPU1_SA_DQ<0>")
	)
	(segment
		(start 143.882618 -222.149924)
		(end 143.921734 -222.127064)
		(width 0.0889)
		(layer "In6.Cu")
		(net "M_K_CPU1_SA_DQ<0>")
	)
	(segment
		(start 142.98168 -224.721928)
		(end 142.945358 -224.700846)
		(width 0.0889)
		(layer "In6.Cu")
		(net "M_K_CPU1_SA_DQ<0>")
	)
	(segment
		(start 198.279258 -196.910452)
		(end 198.7042 -197.335394)
		(width 0.14478)
		(layer "In6.Cu")
		(net "M_K_CPU1_SA_DQ<0>")
	)
	(segment
		(start 163.79952 -197.760336)
		(end 166.106348 -197.760336)
		(width 0.14478)
		(layer "In6.Cu")
		(net "M_K_CPU1_SA_DQ<0>")
	)
	(segment
		(start 142.98168 -225.367088)
		(end 143.01343 -225.3488)
		(width 0.0889)
		(layer "In6.Cu")
		(net "M_K_CPU1_SA_DQ<0>")
	)
	(segment
		(start 146.959828 -214.600028)
		(end 163.79952 -197.760336)
		(width 0.14478)
		(layer "In6.Cu")
		(net "M_K_CPU1_SA_DQ<0>")
	)
	(segment
		(start 144.10944 -221.553278)
		(end 143.993108 -221.436946)
		(width 0.0889)
		(layer "In6.Cu")
		(net "M_K_CPU1_SA_DQ<0>")
	)
	(segment
		(start 170.758104 -197.760336)
		(end 173.609254 -197.760336)
		(width 0.14478)
		(layer "In6.Cu")
		(net "M_K_CPU1_SA_DQ<0>")
	)
	(segment
		(start 142.945358 -223.768158)
		(end 142.98168 -223.747076)
		(width 0.0889)
		(layer "In6.Cu")
		(net "M_K_CPU1_SA_DQ<0>")
	)
	(segment
		(start 142.794736 -225.044508)
		(end 142.640812 -225.309938)
		(width 0.0889)
		(layer "In6.Cu")
		(net "M_K_CPU1_SA_DQ<0>")
	)
	(segment
		(start 178.302158 -197.760336)
		(end 181.140862 -197.760336)
		(width 0.14478)
		(layer "In6.Cu")
		(net "M_K_CPU1_SA_DQ<0>")
	)
	(segment
		(start 184.996074 -196.910452)
		(end 185.845958 -197.760336)
		(width 0.14478)
		(layer "In6.Cu")
		(net "M_K_CPU1_SA_DQ<0>")
	)
	(segment
		(start 142.640812 -225.309938)
		(end 142.663164 -225.39325)
		(width 0.0889)
		(layer "In6.Cu")
		(net "M_K_CPU1_SA_DQ<0>")
	)
	(segment
		(start 143.993108 -220.943424)
		(end 146.959828 -217.976704)
		(width 0.14478)
		(layer "In6.Cu")
		(net "M_K_CPU1_SA_DQ<0>")
	)
	(segment
		(start 143.01343 -224.740216)
		(end 142.98168 -224.721928)
		(width 0.0889)
		(layer "In6.Cu")
		(net "M_K_CPU1_SA_DQ<0>")
	)
	(segment
		(start 146.959828 -217.976704)
		(end 146.959828 -214.600028)
		(width 0.14478)
		(layer "In6.Cu")
		(net "M_K_CPU1_SA_DQ<0>")
	)
	(segment
		(start 143.993108 -221.232984)
		(end 143.993108 -220.943424)
		(width 0.14478)
		(layer "In6.Cu")
		(net "M_K_CPU1_SA_DQ<0>")
	)
	(segment
		(start 185.845958 -197.760336)
		(end 187.59932 -197.760336)
		(width 0.14478)
		(layer "In6.Cu")
		(net "M_K_CPU1_SA_DQ<0>")
	)
	(segment
		(start 143.412718 -222.95993)
		(end 143.451834 -222.93707)
		(width 0.0889)
		(layer "In6.Cu")
		(net "M_K_CPU1_SA_DQ<0>")
	)
	(segment
		(start 174.459138 -196.910452)
		(end 177.452274 -196.910452)
		(width 0.14478)
		(layer "In6.Cu")
		(net "M_K_CPU1_SA_DQ<0>")
	)
	(segment
		(start 173.609254 -197.760336)
		(end 174.459138 -196.910452)
		(width 0.14478)
		(layer "In6.Cu")
		(net "M_K_CPU1_SA_DQ<0>")
	)
	(segment
		(start 166.956486 -196.910198)
		(end 169.907966 -196.910198)
		(width 0.14478)
		(layer "In6.Cu")
		(net "M_K_CPU1_SA_DQ<0>")
	)
	(segment
		(start 177.452274 -196.910452)
		(end 178.302158 -197.760336)
		(width 0.14478)
		(layer "In6.Cu")
		(net "M_K_CPU1_SA_DQ<0>")
	)
	(segment
		(start 189.651132 -196.910452)
		(end 198.279258 -196.910452)
		(width 0.14478)
		(layer "In6.Cu")
		(net "M_K_CPU1_SA_DQ<0>")
	)
	(segment
		(start 142.98168 -223.747076)
		(end 143.01343 -223.728788)
		(width 0.0889)
		(layer "In6.Cu")
		(net "M_K_CPU1_SA_DQ<0>")
	)
	(arc
		(start 143.9545 -222.108014)
		(mid 144.068429 -221.974867)
		(end 144.10944 -221.804484)
		(width 0.0889)
		(layer "In6.Cu")
		(net "M_K_CPU1_SA_DQ<0>")
	)
	(arc
		(start 143.01343 -225.3488)
		(mid 143.169358 -225.044508)
		(end 143.01343 -224.740216)
		(width 0.0889)
		(layer "In6.Cu")
		(net "M_K_CPU1_SA_DQ<0>")
	)
	(arc
		(start 143.639286 -222.61449)
		(mid 143.703801 -222.352271)
		(end 143.882618 -222.149924)
		(width 0.0889)
		(layer "In6.Cu")
		(net "M_K_CPU1_SA_DQ<0>")
	)
	(arc
		(start 143.169386 -223.424496)
		(mid 143.233901 -223.162277)
		(end 143.412718 -222.95993)
		(width 0.0889)
		(layer "In6.Cu")
		(net "M_K_CPU1_SA_DQ<0>")
	)
	(arc
		(start 142.663164 -225.39325)
		(mid 142.825353 -225.415985)
		(end 142.98168 -225.367088)
		(width 0.0889)
		(layer "In6.Cu")
		(net "M_K_CPU1_SA_DQ<0>")
	)
	(arc
		(start 143.482314 -222.91929)
		(mid 143.597741 -222.785914)
		(end 143.639286 -222.61449)
		(width 0.0889)
		(layer "In6.Cu")
		(net "M_K_CPU1_SA_DQ<0>")
	)
	(arc
		(start 143.01343 -223.728788)
		(mid 143.128106 -223.595454)
		(end 143.169386 -223.424496)
		(width 0.0889)
		(layer "In6.Cu")
		(net "M_K_CPU1_SA_DQ<0>")
	)
	(arc
		(start 142.945358 -224.700846)
		(mid 142.699468 -224.234502)
		(end 142.945358 -223.768158)
		(width 0.0889)
		(layer "In6.Cu")
		(net "M_K_CPU1_SA_DQ<0>")
	)
	(segment
		(start 140.91793 -252.04039)
		(end 141.384782 -251.774452)
		(width 0.10668)
		(layer "F.Cu")
		(net "M_K_CPU1_SA_CS_N<1>")
	)
	(segment
		(start 150.588218 -251.516134)
		(end 160.671764 -251.516134)
		(width 0.14478)
		(layer "In6.Cu")
		(net "M_K_CPU1_SA_CS_N<1>")
	)
	(segment
		(start 144.390872 -252.097032)
		(end 144.401286 -252.090936)
		(width 0.0889)
		(layer "In6.Cu")
		(net "M_K_CPU1_SA_CS_N<1>")
	)
	(segment
		(start 145.33118 -252.096778)
		(end 145.336768 -252.093476)
		(width 0.0889)
		(layer "In6.Cu")
		(net "M_K_CPU1_SA_CS_N<1>")
	)
	(segment
		(start 193.329306 -247.910096)
		(end 194.604132 -246.63527)
		(width 0.14478)
		(layer "In6.Cu")
		(net "M_K_CPU1_SA_CS_N<1>")
	)
	(segment
		(start 141.384782 -251.774452)
		(end 141.230604 -252.039882)
		(width 0.0889)
		(layer "In6.Cu")
		(net "M_K_CPU1_SA_CS_N<1>")
	)
	(segment
		(start 146.02968 -252.093476)
		(end 146.398488 -252.462284)
		(width 0.0889)
		(layer "In6.Cu")
		(net "M_K_CPU1_SA_CS_N<1>")
	)
	(segment
		(start 163.427664 -248.760234)
		(end 189.949328 -248.760234)
		(width 0.14478)
		(layer "In6.Cu")
		(net "M_K_CPU1_SA_CS_N<1>")
	)
	(segment
		(start 145.336768 -252.093476)
		(end 146.02968 -252.093476)
		(width 0.0889)
		(layer "In6.Cu")
		(net "M_K_CPU1_SA_CS_N<1>")
	)
	(segment
		(start 147.020788 -252.462284)
		(end 147.406868 -252.848364)
		(width 0.0889)
		(layer "In6.Cu")
		(net "M_K_CPU1_SA_CS_N<1>")
	)
	(segment
		(start 147.859496 -252.848364)
		(end 149.255988 -252.848364)
		(width 0.14478)
		(layer "In6.Cu")
		(net "M_K_CPU1_SA_CS_N<1>")
	)
	(segment
		(start 142.503144 -252.101858)
		(end 142.511526 -252.097032)
		(width 0.0889)
		(layer "In6.Cu")
		(net "M_K_CPU1_SA_CS_N<1>")
	)
	(segment
		(start 143.077438 -252.097032)
		(end 143.08582 -252.101858)
		(width 0.0889)
		(layer "In6.Cu")
		(net "M_K_CPU1_SA_CS_N<1>")
	)
	(segment
		(start 189.949328 -248.760234)
		(end 190.799466 -247.910096)
		(width 0.14478)
		(layer "In6.Cu")
		(net "M_K_CPU1_SA_CS_N<1>")
	)
	(segment
		(start 141.230604 -252.039882)
		(end 141.252956 -252.123194)
		(width 0.0889)
		(layer "In6.Cu")
		(net "M_K_CPU1_SA_CS_N<1>")
	)
	(segment
		(start 147.406868 -252.848364)
		(end 147.859496 -252.848364)
		(width 0.0889)
		(layer "In6.Cu")
		(net "M_K_CPU1_SA_CS_N<1>")
	)
	(segment
		(start 160.671764 -251.516134)
		(end 163.427664 -248.760234)
		(width 0.14478)
		(layer "In6.Cu")
		(net "M_K_CPU1_SA_CS_N<1>")
	)
	(segment
		(start 144.017238 -252.097032)
		(end 144.02562 -252.101858)
		(width 0.0889)
		(layer "In6.Cu")
		(net "M_K_CPU1_SA_CS_N<1>")
	)
	(segment
		(start 149.255988 -252.848364)
		(end 150.588218 -251.516134)
		(width 0.14478)
		(layer "In6.Cu")
		(net "M_K_CPU1_SA_CS_N<1>")
	)
	(segment
		(start 146.398488 -252.462284)
		(end 147.020788 -252.462284)
		(width 0.0889)
		(layer "In6.Cu")
		(net "M_K_CPU1_SA_CS_N<1>")
	)
	(segment
		(start 144.006824 -252.090936)
		(end 144.017238 -252.097032)
		(width 0.0889)
		(layer "In6.Cu")
		(net "M_K_CPU1_SA_CS_N<1>")
	)
	(segment
		(start 145.312892 -252.107192)
		(end 145.33118 -252.096778)
		(width 0.0889)
		(layer "In6.Cu")
		(net "M_K_CPU1_SA_CS_N<1>")
	)
	(segment
		(start 190.799466 -247.910096)
		(end 193.329306 -247.910096)
		(width 0.14478)
		(layer "In6.Cu")
		(net "M_K_CPU1_SA_CS_N<1>")
	)
	(arc
		(start 144.401286 -252.090936)
		(mid 144.679972 -252.020716)
		(end 144.957038 -252.097032)
		(width 0.0889)
		(layer "In6.Cu")
		(net "M_K_CPU1_SA_CS_N<1>")
	)
	(arc
		(start 144.02562 -252.101858)
		(mid 144.208874 -252.147231)
		(end 144.390872 -252.097032)
		(width 0.0889)
		(layer "In6.Cu")
		(net "M_K_CPU1_SA_CS_N<1>")
	)
	(arc
		(start 142.137384 -252.097032)
		(mid 142.319635 -252.147382)
		(end 142.503144 -252.101858)
		(width 0.0889)
		(layer "In6.Cu")
		(net "M_K_CPU1_SA_CS_N<1>")
	)
	(arc
		(start 141.252956 -252.123194)
		(mid 141.415145 -252.145929)
		(end 141.571472 -252.097032)
		(width 0.0889)
		(layer "In6.Cu")
		(net "M_K_CPU1_SA_CS_N<1>")
	)
	(arc
		(start 141.571472 -252.097032)
		(mid 141.854428 -252.020855)
		(end 142.137384 -252.097032)
		(width 0.0889)
		(layer "In6.Cu")
		(net "M_K_CPU1_SA_CS_N<1>")
	)
	(arc
		(start 144.957038 -252.097032)
		(mid 145.133666 -252.147265)
		(end 145.312892 -252.107192)
		(width 0.0889)
		(layer "In6.Cu")
		(net "M_K_CPU1_SA_CS_N<1>")
	)
	(arc
		(start 143.45158 -252.097032)
		(mid 143.728393 -252.020889)
		(end 144.006824 -252.090936)
		(width 0.0889)
		(layer "In6.Cu")
		(net "M_K_CPU1_SA_CS_N<1>")
	)
	(arc
		(start 143.08582 -252.101858)
		(mid 143.269328 -252.147352)
		(end 143.45158 -252.097032)
		(width 0.0889)
		(layer "In6.Cu")
		(net "M_K_CPU1_SA_CS_N<1>")
	)
	(arc
		(start 142.511526 -252.097032)
		(mid 142.794482 -252.020855)
		(end 143.077438 -252.097032)
		(width 0.0889)
		(layer "In6.Cu")
		(net "M_K_CPU1_SA_CS_N<1>")
	)
	(segment
		(start 142.327884 -251.230384)
		(end 142.794736 -250.964446)
		(width 0.10668)
		(layer "F.Cu")
		(net "M_K_CPU1_SA_CS_N<0>")
	)
	(segment
		(start 144.487392 -251.287026)
		(end 144.495774 -251.291852)
		(width 0.0889)
		(layer "In6.Cu")
		(net "M_K_CPU1_SA_CS_N<0>")
	)
	(segment
		(start 145.427446 -251.287026)
		(end 145.435828 -251.291852)
		(width 0.0889)
		(layer "In6.Cu")
		(net "M_K_CPU1_SA_CS_N<0>")
	)
	(segment
		(start 192.682876 -246.210074)
		(end 198.279512 -246.210074)
		(width 0.14478)
		(layer "In6.Cu")
		(net "M_K_CPU1_SA_CS_N<0>")
	)
	(segment
		(start 145.435828 -251.291852)
		(end 145.738596 -251.45746)
		(width 0.0889)
		(layer "In6.Cu")
		(net "M_K_CPU1_SA_CS_N<0>")
	)
	(segment
		(start 190.799466 -247.060212)
		(end 191.832738 -247.060212)
		(width 0.14478)
		(layer "In6.Cu")
		(net "M_K_CPU1_SA_CS_N<0>")
	)
	(segment
		(start 142.640812 -251.229876)
		(end 142.663164 -251.313188)
		(width 0.0889)
		(layer "In6.Cu")
		(net "M_K_CPU1_SA_CS_N<0>")
	)
	(segment
		(start 147.859496 -252.393704)
		(end 149.06752 -252.393704)
		(width 0.14478)
		(layer "In6.Cu")
		(net "M_K_CPU1_SA_CS_N<0>")
	)
	(segment
		(start 198.279512 -246.210074)
		(end 198.7042 -245.785386)
		(width 0.14478)
		(layer "In6.Cu")
		(net "M_K_CPU1_SA_CS_N<0>")
	)
	(segment
		(start 145.412714 -251.27839)
		(end 145.427446 -251.287026)
		(width 0.0889)
		(layer "In6.Cu")
		(net "M_K_CPU1_SA_CS_N<0>")
	)
	(segment
		(start 160.27654 -251.061474)
		(end 163.427664 -247.91035)
		(width 0.14478)
		(layer "In6.Cu")
		(net "M_K_CPU1_SA_CS_N<0>")
	)
	(segment
		(start 163.427664 -247.91035)
		(end 189.949328 -247.91035)
		(width 0.14478)
		(layer "In6.Cu")
		(net "M_K_CPU1_SA_CS_N<0>")
	)
	(segment
		(start 149.06752 -252.393704)
		(end 150.39975 -251.061474)
		(width 0.14478)
		(layer "In6.Cu")
		(net "M_K_CPU1_SA_CS_N<0>")
	)
	(segment
		(start 143.921734 -251.287026)
		(end 143.932148 -251.28093)
		(width 0.0889)
		(layer "In6.Cu")
		(net "M_K_CPU1_SA_CS_N<0>")
	)
	(segment
		(start 147.150328 -252.078744)
		(end 147.465288 -252.393704)
		(width 0.0889)
		(layer "In6.Cu")
		(net "M_K_CPU1_SA_CS_N<0>")
	)
	(segment
		(start 146.492468 -252.078744)
		(end 147.150328 -252.078744)
		(width 0.0889)
		(layer "In6.Cu")
		(net "M_K_CPU1_SA_CS_N<0>")
	)
	(segment
		(start 145.738596 -251.45746)
		(end 145.871184 -251.45746)
		(width 0.0889)
		(layer "In6.Cu")
		(net "M_K_CPU1_SA_CS_N<0>")
	)
	(segment
		(start 150.39975 -251.061474)
		(end 160.27654 -251.061474)
		(width 0.14478)
		(layer "In6.Cu")
		(net "M_K_CPU1_SA_CS_N<0>")
	)
	(segment
		(start 143.913352 -251.291852)
		(end 143.921734 -251.287026)
		(width 0.0889)
		(layer "In6.Cu")
		(net "M_K_CPU1_SA_CS_N<0>")
	)
	(segment
		(start 145.871184 -251.45746)
		(end 146.492468 -252.078744)
		(width 0.0889)
		(layer "In6.Cu")
		(net "M_K_CPU1_SA_CS_N<0>")
	)
	(segment
		(start 191.832738 -247.060212)
		(end 192.682876 -246.210074)
		(width 0.14478)
		(layer "In6.Cu")
		(net "M_K_CPU1_SA_CS_N<0>")
	)
	(segment
		(start 189.949328 -247.91035)
		(end 190.799466 -247.060212)
		(width 0.14478)
		(layer "In6.Cu")
		(net "M_K_CPU1_SA_CS_N<0>")
	)
	(segment
		(start 142.794736 -250.964446)
		(end 142.640812 -251.229876)
		(width 0.0889)
		(layer "In6.Cu")
		(net "M_K_CPU1_SA_CS_N<0>")
	)
	(segment
		(start 147.465288 -252.393704)
		(end 147.859496 -252.393704)
		(width 0.0889)
		(layer "In6.Cu")
		(net "M_K_CPU1_SA_CS_N<0>")
	)
	(arc
		(start 144.861534 -251.287026)
		(mid 145.135986 -251.21079)
		(end 145.412714 -251.27839)
		(width 0.0889)
		(layer "In6.Cu")
		(net "M_K_CPU1_SA_CS_N<0>")
	)
	(arc
		(start 142.98168 -251.287026)
		(mid 143.264636 -251.210849)
		(end 143.547592 -251.287026)
		(width 0.0889)
		(layer "In6.Cu")
		(net "M_K_CPU1_SA_CS_N<0>")
	)
	(arc
		(start 143.932148 -251.28093)
		(mid 144.21058 -251.210832)
		(end 144.487392 -251.287026)
		(width 0.0889)
		(layer "In6.Cu")
		(net "M_K_CPU1_SA_CS_N<0>")
	)
	(arc
		(start 143.547592 -251.287026)
		(mid 143.729843 -251.337376)
		(end 143.913352 -251.291852)
		(width 0.0889)
		(layer "In6.Cu")
		(net "M_K_CPU1_SA_CS_N<0>")
	)
	(arc
		(start 142.663164 -251.313188)
		(mid 142.825353 -251.335923)
		(end 142.98168 -251.287026)
		(width 0.0889)
		(layer "In6.Cu")
		(net "M_K_CPU1_SA_CS_N<0>")
	)
	(arc
		(start 144.495774 -251.291852)
		(mid 144.679282 -251.337346)
		(end 144.861534 -251.287026)
		(width 0.0889)
		(layer "In6.Cu")
		(net "M_K_CPU1_SA_CS_N<0>")
	)
	(segment
		(start 140.447776 -249.610372)
		(end 140.914882 -249.344434)
		(width 0.10668)
		(layer "F.Cu")
		(net "M_K_CPU1_SA_CB<7>")
	)
	(segment
		(start 185.005726 -243.476526)
		(end 185.005726 -244.365526)
		(width 0.14478)
		(layer "In6.Cu")
		(net "M_K_CPU1_SA_CB<7>")
	)
	(segment
		(start 185.70194 -243.331746)
		(end 185.963814 -243.331746)
		(width 0.14478)
		(layer "In6.Cu")
		(net "M_K_CPU1_SA_CB<7>")
	)
	(segment
		(start 143.92148 -249.021854)
		(end 143.931894 -249.02795)
		(width 0.0889)
		(layer "In6.Cu")
		(net "M_K_CPU1_SA_CB<7>")
	)
	(segment
		(start 184.309512 -244.510306)
		(end 184.454292 -244.365526)
		(width 0.14478)
		(layer "In6.Cu")
		(net "M_K_CPU1_SA_CB<7>")
	)
	(segment
		(start 144.487138 -249.021854)
		(end 144.498822 -249.014996)
		(width 0.0889)
		(layer "In6.Cu")
		(net "M_K_CPU1_SA_CB<7>")
	)
	(segment
		(start 147.307808 -249.968004)
		(end 148.707348 -249.968004)
		(width 0.14478)
		(layer "In6.Cu")
		(net "M_K_CPU1_SA_CB<7>")
	)
	(segment
		(start 185.005726 -244.365526)
		(end 185.150506 -244.510306)
		(width 0.14478)
		(layer "In6.Cu")
		(net "M_K_CPU1_SA_CB<7>")
	)
	(segment
		(start 188.205364 -244.510306)
		(end 189.905386 -242.810284)
		(width 0.14478)
		(layer "In6.Cu")
		(net "M_K_CPU1_SA_CB<7>")
	)
	(segment
		(start 181.783736 -244.510306)
		(end 184.309512 -244.510306)
		(width 0.14478)
		(layer "In6.Cu")
		(net "M_K_CPU1_SA_CB<7>")
	)
	(segment
		(start 186.253374 -244.510306)
		(end 188.205364 -244.510306)
		(width 0.14478)
		(layer "In6.Cu")
		(net "M_K_CPU1_SA_CB<7>")
	)
	(segment
		(start 181.638956 -243.903246)
		(end 181.638956 -244.365526)
		(width 0.14478)
		(layer "In6.Cu")
		(net "M_K_CPU1_SA_CB<7>")
	)
	(segment
		(start 158.903162 -249.080274)
		(end 163.47313 -244.510306)
		(width 0.14478)
		(layer "In6.Cu")
		(net "M_K_CPU1_SA_CB<7>")
	)
	(segment
		(start 185.150506 -244.510306)
		(end 185.41238 -244.510306)
		(width 0.14478)
		(layer "In6.Cu")
		(net "M_K_CPU1_SA_CB<7>")
	)
	(segment
		(start 145.798794 -249.968004)
		(end 147.307808 -249.968004)
		(width 0.0889)
		(layer "In6.Cu")
		(net "M_K_CPU1_SA_CB<7>")
	)
	(segment
		(start 185.55716 -243.476526)
		(end 185.70194 -243.331746)
		(width 0.14478)
		(layer "In6.Cu")
		(net "M_K_CPU1_SA_CB<7>")
	)
	(segment
		(start 189.905386 -242.810284)
		(end 194.17919 -242.810284)
		(width 0.14478)
		(layer "In6.Cu")
		(net "M_K_CPU1_SA_CB<7>")
	)
	(segment
		(start 180.942742 -244.510306)
		(end 181.087522 -244.365526)
		(width 0.14478)
		(layer "In6.Cu")
		(net "M_K_CPU1_SA_CB<7>")
	)
	(segment
		(start 184.860946 -243.331746)
		(end 185.005726 -243.476526)
		(width 0.14478)
		(layer "In6.Cu")
		(net "M_K_CPU1_SA_CB<7>")
	)
	(segment
		(start 141.068806 -249.079004)
		(end 141.164818 -249.053604)
		(width 0.0889)
		(layer "In6.Cu")
		(net "M_K_CPU1_SA_CB<7>")
	)
	(segment
		(start 185.55716 -244.365526)
		(end 185.55716 -243.476526)
		(width 0.14478)
		(layer "In6.Cu")
		(net "M_K_CPU1_SA_CB<7>")
	)
	(segment
		(start 179.984654 -244.365526)
		(end 179.984654 -243.903246)
		(width 0.14478)
		(layer "In6.Cu")
		(net "M_K_CPU1_SA_CB<7>")
	)
	(segment
		(start 181.638956 -244.365526)
		(end 181.783736 -244.510306)
		(width 0.14478)
		(layer "In6.Cu")
		(net "M_K_CPU1_SA_CB<7>")
	)
	(segment
		(start 185.963814 -243.331746)
		(end 186.108594 -243.476526)
		(width 0.14478)
		(layer "In6.Cu")
		(net "M_K_CPU1_SA_CB<7>")
	)
	(segment
		(start 181.087522 -243.903246)
		(end 181.232302 -243.758466)
		(width 0.14478)
		(layer "In6.Cu")
		(net "M_K_CPU1_SA_CB<7>")
	)
	(segment
		(start 181.232302 -243.758466)
		(end 181.494176 -243.758466)
		(width 0.14478)
		(layer "In6.Cu")
		(net "M_K_CPU1_SA_CB<7>")
	)
	(segment
		(start 140.914882 -249.344434)
		(end 141.068806 -249.079004)
		(width 0.0889)
		(layer "In6.Cu")
		(net "M_K_CPU1_SA_CB<7>")
	)
	(segment
		(start 186.108594 -244.365526)
		(end 186.253374 -244.510306)
		(width 0.14478)
		(layer "In6.Cu")
		(net "M_K_CPU1_SA_CB<7>")
	)
	(segment
		(start 180.536088 -243.903246)
		(end 180.536088 -244.365526)
		(width 0.14478)
		(layer "In6.Cu")
		(net "M_K_CPU1_SA_CB<7>")
	)
	(segment
		(start 180.129434 -243.758466)
		(end 180.391308 -243.758466)
		(width 0.14478)
		(layer "In6.Cu")
		(net "M_K_CPU1_SA_CB<7>")
	)
	(segment
		(start 181.494176 -243.758466)
		(end 181.638956 -243.903246)
		(width 0.14478)
		(layer "In6.Cu")
		(net "M_K_CPU1_SA_CB<7>")
	)
	(segment
		(start 181.087522 -244.365526)
		(end 181.087522 -243.903246)
		(width 0.14478)
		(layer "In6.Cu")
		(net "M_K_CPU1_SA_CB<7>")
	)
	(segment
		(start 143.909796 -249.014996)
		(end 143.92148 -249.021854)
		(width 0.0889)
		(layer "In6.Cu")
		(net "M_K_CPU1_SA_CB<7>")
	)
	(segment
		(start 186.108594 -243.476526)
		(end 186.108594 -244.365526)
		(width 0.14478)
		(layer "In6.Cu")
		(net "M_K_CPU1_SA_CB<7>")
	)
	(segment
		(start 180.391308 -243.758466)
		(end 180.536088 -243.903246)
		(width 0.14478)
		(layer "In6.Cu")
		(net "M_K_CPU1_SA_CB<7>")
	)
	(segment
		(start 184.454292 -243.476526)
		(end 184.599072 -243.331746)
		(width 0.14478)
		(layer "In6.Cu")
		(net "M_K_CPU1_SA_CB<7>")
	)
	(segment
		(start 144.861534 -249.021854)
		(end 145.798794 -249.968004)
		(width 0.0889)
		(layer "In6.Cu")
		(net "M_K_CPU1_SA_CB<7>")
	)
	(segment
		(start 141.667738 -249.021854)
		(end 141.67612 -249.017028)
		(width 0.0889)
		(layer "In6.Cu")
		(net "M_K_CPU1_SA_CB<7>")
	)
	(segment
		(start 180.680868 -244.510306)
		(end 180.942742 -244.510306)
		(width 0.14478)
		(layer "In6.Cu")
		(net "M_K_CPU1_SA_CB<7>")
	)
	(segment
		(start 179.839874 -244.510306)
		(end 179.984654 -244.365526)
		(width 0.14478)
		(layer "In6.Cu")
		(net "M_K_CPU1_SA_CB<7>")
	)
	(segment
		(start 185.41238 -244.510306)
		(end 185.55716 -244.365526)
		(width 0.14478)
		(layer "In6.Cu")
		(net "M_K_CPU1_SA_CB<7>")
	)
	(segment
		(start 179.984654 -243.903246)
		(end 180.129434 -243.758466)
		(width 0.14478)
		(layer "In6.Cu")
		(net "M_K_CPU1_SA_CB<7>")
	)
	(segment
		(start 149.595078 -249.080274)
		(end 158.903162 -249.080274)
		(width 0.14478)
		(layer "In6.Cu")
		(net "M_K_CPU1_SA_CB<7>")
	)
	(segment
		(start 184.599072 -243.331746)
		(end 184.860946 -243.331746)
		(width 0.14478)
		(layer "In6.Cu")
		(net "M_K_CPU1_SA_CB<7>")
	)
	(segment
		(start 180.536088 -244.365526)
		(end 180.680868 -244.510306)
		(width 0.14478)
		(layer "In6.Cu")
		(net "M_K_CPU1_SA_CB<7>")
	)
	(segment
		(start 148.707348 -249.968004)
		(end 149.595078 -249.080274)
		(width 0.14478)
		(layer "In6.Cu")
		(net "M_K_CPU1_SA_CB<7>")
	)
	(segment
		(start 184.454292 -244.365526)
		(end 184.454292 -243.476526)
		(width 0.14478)
		(layer "In6.Cu")
		(net "M_K_CPU1_SA_CB<7>")
	)
	(segment
		(start 163.47313 -244.510306)
		(end 179.839874 -244.510306)
		(width 0.14478)
		(layer "In6.Cu")
		(net "M_K_CPU1_SA_CB<7>")
	)
	(segment
		(start 194.17919 -242.810284)
		(end 194.604132 -243.235226)
		(width 0.14478)
		(layer "In6.Cu")
		(net "M_K_CPU1_SA_CB<7>")
	)
	(arc
		(start 141.164818 -249.053604)
		(mid 141.420026 -249.097081)
		(end 141.667738 -249.021854)
		(width 0.0889)
		(layer "In6.Cu")
		(net "M_K_CPU1_SA_CB<7>")
	)
	(arc
		(start 141.67612 -249.017028)
		(mid 141.859628 -248.971534)
		(end 142.04188 -249.021854)
		(width 0.0889)
		(layer "In6.Cu")
		(net "M_K_CPU1_SA_CB<7>")
	)
	(arc
		(start 142.04188 -249.021854)
		(mid 142.324836 -249.098031)
		(end 142.607792 -249.021854)
		(width 0.0889)
		(layer "In6.Cu")
		(net "M_K_CPU1_SA_CB<7>")
	)
	(arc
		(start 142.98168 -249.021854)
		(mid 143.264636 -249.098031)
		(end 143.547592 -249.021854)
		(width 0.0889)
		(layer "In6.Cu")
		(net "M_K_CPU1_SA_CB<7>")
	)
	(arc
		(start 143.931894 -249.02795)
		(mid 144.210326 -249.098048)
		(end 144.487138 -249.021854)
		(width 0.0889)
		(layer "In6.Cu")
		(net "M_K_CPU1_SA_CB<7>")
	)
	(arc
		(start 144.498822 -249.014996)
		(mid 144.681077 -248.971343)
		(end 144.861534 -249.021854)
		(width 0.0889)
		(layer "In6.Cu")
		(net "M_K_CPU1_SA_CB<7>")
	)
	(arc
		(start 142.607792 -249.021854)
		(mid 142.794736 -248.971599)
		(end 142.98168 -249.021854)
		(width 0.0889)
		(layer "In6.Cu")
		(net "M_K_CPU1_SA_CB<7>")
	)
	(arc
		(start 143.547592 -249.021854)
		(mid 143.727797 -248.971537)
		(end 143.909796 -249.014996)
		(width 0.0889)
		(layer "In6.Cu")
		(net "M_K_CPU1_SA_CB<7>")
	)
	(segment
		(start 141.857984 -248.800366)
		(end 142.324836 -248.534428)
		(width 0.10668)
		(layer "F.Cu")
		(net "M_K_CPU1_SA_CB<6>")
	)
	(segment
		(start 174.804832 -241.9604)
		(end 174.949612 -242.10518)
		(width 0.14478)
		(layer "In6.Cu")
		(net "M_K_CPU1_SA_CB<6>")
	)
	(segment
		(start 149.144736 -248.170954)
		(end 158.187136 -248.170954)
		(width 0.14478)
		(layer "In6.Cu")
		(net "M_K_CPU1_SA_CB<6>")
	)
	(segment
		(start 145.721832 -248.274078)
		(end 146.270218 -248.822464)
		(width 0.0889)
		(layer "In6.Cu")
		(net "M_K_CPU1_SA_CB<6>")
	)
	(segment
		(start 170.037506 -242.10518)
		(end 170.182286 -241.9604)
		(width 0.14478)
		(layer "In6.Cu")
		(net "M_K_CPU1_SA_CB<6>")
	)
	(segment
		(start 169.341292 -241.9604)
		(end 169.486072 -242.10518)
		(width 0.14478)
		(layer "In6.Cu")
		(net "M_K_CPU1_SA_CB<6>")
	)
	(segment
		(start 174.398178 -242.10518)
		(end 174.542958 -241.9604)
		(width 0.14478)
		(layer "In6.Cu")
		(net "M_K_CPU1_SA_CB<6>")
	)
	(segment
		(start 145.590006 -248.274078)
		(end 145.721832 -248.274078)
		(width 0.0889)
		(layer "In6.Cu")
		(net "M_K_CPU1_SA_CB<6>")
	)
	(segment
		(start 170.58894 -242.633246)
		(end 170.73372 -242.778026)
		(width 0.14478)
		(layer "In6.Cu")
		(net "M_K_CPU1_SA_CB<6>")
	)
	(segment
		(start 173.29531 -242.10518)
		(end 173.44009 -241.9604)
		(width 0.14478)
		(layer "In6.Cu")
		(net "M_K_CPU1_SA_CB<6>")
	)
	(segment
		(start 173.846744 -242.879626)
		(end 173.991524 -243.024406)
		(width 0.14478)
		(layer "In6.Cu")
		(net "M_K_CPU1_SA_CB<6>")
	)
	(segment
		(start 188.801248 -241.9604)
		(end 189.651386 -241.110262)
		(width 0.14478)
		(layer "In6.Cu")
		(net "M_K_CPU1_SA_CB<6>")
	)
	(segment
		(start 175.645826 -241.9604)
		(end 188.801248 -241.9604)
		(width 0.14478)
		(layer "In6.Cu")
		(net "M_K_CPU1_SA_CB<6>")
	)
	(segment
		(start 174.542958 -241.9604)
		(end 174.804832 -241.9604)
		(width 0.14478)
		(layer "In6.Cu")
		(net "M_K_CPU1_SA_CB<6>")
	)
	(segment
		(start 173.15053 -243.024406)
		(end 173.29531 -242.879626)
		(width 0.14478)
		(layer "In6.Cu")
		(net "M_K_CPU1_SA_CB<6>")
	)
	(segment
		(start 173.44009 -241.9604)
		(end 173.701964 -241.9604)
		(width 0.14478)
		(layer "In6.Cu")
		(net "M_K_CPU1_SA_CB<6>")
	)
	(segment
		(start 167.52951 -241.9604)
		(end 169.341292 -241.9604)
		(width 0.14478)
		(layer "In6.Cu")
		(net "M_K_CPU1_SA_CB<6>")
	)
	(segment
		(start 169.486072 -242.10518)
		(end 169.486072 -242.633246)
		(width 0.14478)
		(layer "In6.Cu")
		(net "M_K_CPU1_SA_CB<6>")
	)
	(segment
		(start 173.701964 -241.9604)
		(end 173.846744 -242.10518)
		(width 0.14478)
		(layer "In6.Cu")
		(net "M_K_CPU1_SA_CB<6>")
	)
	(segment
		(start 172.888656 -243.024406)
		(end 173.15053 -243.024406)
		(width 0.14478)
		(layer "In6.Cu")
		(net "M_K_CPU1_SA_CB<6>")
	)
	(segment
		(start 172.743876 -242.10518)
		(end 172.743876 -242.879626)
		(width 0.14478)
		(layer "In6.Cu")
		(net "M_K_CPU1_SA_CB<6>")
	)
	(segment
		(start 174.398178 -242.879626)
		(end 174.398178 -242.10518)
		(width 0.14478)
		(layer "In6.Cu")
		(net "M_K_CPU1_SA_CB<6>")
	)
	(segment
		(start 170.44416 -241.9604)
		(end 170.58894 -242.10518)
		(width 0.14478)
		(layer "In6.Cu")
		(net "M_K_CPU1_SA_CB<6>")
	)
	(segment
		(start 173.991524 -243.024406)
		(end 174.253398 -243.024406)
		(width 0.14478)
		(layer "In6.Cu")
		(net "M_K_CPU1_SA_CB<6>")
	)
	(segment
		(start 169.892726 -242.778026)
		(end 170.037506 -242.633246)
		(width 0.14478)
		(layer "In6.Cu")
		(net "M_K_CPU1_SA_CB<6>")
	)
	(segment
		(start 175.501046 -242.879626)
		(end 175.501046 -242.10518)
		(width 0.14478)
		(layer "In6.Cu")
		(net "M_K_CPU1_SA_CB<6>")
	)
	(segment
		(start 173.29531 -242.879626)
		(end 173.29531 -242.10518)
		(width 0.14478)
		(layer "In6.Cu")
		(net "M_K_CPU1_SA_CB<6>")
	)
	(segment
		(start 170.995594 -242.778026)
		(end 171.140374 -242.633246)
		(width 0.14478)
		(layer "In6.Cu")
		(net "M_K_CPU1_SA_CB<6>")
	)
	(segment
		(start 172.599096 -241.9604)
		(end 172.743876 -242.10518)
		(width 0.14478)
		(layer "In6.Cu")
		(net "M_K_CPU1_SA_CB<6>")
	)
	(segment
		(start 171.140374 -242.633246)
		(end 171.140374 -242.10518)
		(width 0.14478)
		(layer "In6.Cu")
		(net "M_K_CPU1_SA_CB<6>")
	)
	(segment
		(start 144.39138 -248.211848)
		(end 144.401794 -248.217944)
		(width 0.0889)
		(layer "In6.Cu")
		(net "M_K_CPU1_SA_CB<6>")
	)
	(segment
		(start 170.037506 -242.633246)
		(end 170.037506 -242.10518)
		(width 0.14478)
		(layer "In6.Cu")
		(net "M_K_CPU1_SA_CB<6>")
	)
	(segment
		(start 171.285154 -241.9604)
		(end 172.599096 -241.9604)
		(width 0.14478)
		(layer "In6.Cu")
		(net "M_K_CPU1_SA_CB<6>")
	)
	(segment
		(start 174.253398 -243.024406)
		(end 174.398178 -242.879626)
		(width 0.14478)
		(layer "In6.Cu")
		(net "M_K_CPU1_SA_CB<6>")
	)
	(segment
		(start 148.493226 -248.822464)
		(end 149.144736 -248.170954)
		(width 0.14478)
		(layer "In6.Cu")
		(net "M_K_CPU1_SA_CB<6>")
	)
	(segment
		(start 163.547806 -242.810284)
		(end 166.679626 -242.810284)
		(width 0.14478)
		(layer "In6.Cu")
		(net "M_K_CPU1_SA_CB<6>")
	)
	(segment
		(start 166.679626 -242.810284)
		(end 167.52951 -241.9604)
		(width 0.14478)
		(layer "In6.Cu")
		(net "M_K_CPU1_SA_CB<6>")
	)
	(segment
		(start 189.651386 -241.110262)
		(end 194.17919 -241.110262)
		(width 0.14478)
		(layer "In6.Cu")
		(net "M_K_CPU1_SA_CB<6>")
	)
	(segment
		(start 172.743876 -242.879626)
		(end 172.888656 -243.024406)
		(width 0.14478)
		(layer "In6.Cu")
		(net "M_K_CPU1_SA_CB<6>")
	)
	(segment
		(start 169.630852 -242.778026)
		(end 169.892726 -242.778026)
		(width 0.14478)
		(layer "In6.Cu")
		(net "M_K_CPU1_SA_CB<6>")
	)
	(segment
		(start 174.949612 -242.879626)
		(end 175.094392 -243.024406)
		(width 0.14478)
		(layer "In6.Cu")
		(net "M_K_CPU1_SA_CB<6>")
	)
	(segment
		(start 170.73372 -242.778026)
		(end 170.995594 -242.778026)
		(width 0.14478)
		(layer "In6.Cu")
		(net "M_K_CPU1_SA_CB<6>")
	)
	(segment
		(start 142.47876 -248.268998)
		(end 142.574772 -248.243598)
		(width 0.0889)
		(layer "In6.Cu")
		(net "M_K_CPU1_SA_CB<6>")
	)
	(segment
		(start 169.486072 -242.633246)
		(end 169.630852 -242.778026)
		(width 0.14478)
		(layer "In6.Cu")
		(net "M_K_CPU1_SA_CB<6>")
	)
	(segment
		(start 170.182286 -241.9604)
		(end 170.44416 -241.9604)
		(width 0.14478)
		(layer "In6.Cu")
		(net "M_K_CPU1_SA_CB<6>")
	)
	(segment
		(start 170.58894 -242.10518)
		(end 170.58894 -242.633246)
		(width 0.14478)
		(layer "In6.Cu")
		(net "M_K_CPU1_SA_CB<6>")
	)
	(segment
		(start 143.077692 -248.211848)
		(end 143.086074 -248.207022)
		(width 0.0889)
		(layer "In6.Cu")
		(net "M_K_CPU1_SA_CB<6>")
	)
	(segment
		(start 194.17919 -241.110262)
		(end 194.604132 -241.535204)
		(width 0.14478)
		(layer "In6.Cu")
		(net "M_K_CPU1_SA_CB<6>")
	)
	(segment
		(start 171.140374 -242.10518)
		(end 171.285154 -241.9604)
		(width 0.14478)
		(layer "In6.Cu")
		(net "M_K_CPU1_SA_CB<6>")
	)
	(segment
		(start 142.324836 -248.534428)
		(end 142.47876 -248.268998)
		(width 0.0889)
		(layer "In6.Cu")
		(net "M_K_CPU1_SA_CB<6>")
	)
	(segment
		(start 175.356266 -243.024406)
		(end 175.501046 -242.879626)
		(width 0.14478)
		(layer "In6.Cu")
		(net "M_K_CPU1_SA_CB<6>")
	)
	(segment
		(start 175.094392 -243.024406)
		(end 175.356266 -243.024406)
		(width 0.14478)
		(layer "In6.Cu")
		(net "M_K_CPU1_SA_CB<6>")
	)
	(segment
		(start 174.949612 -242.10518)
		(end 174.949612 -242.879626)
		(width 0.14478)
		(layer "In6.Cu")
		(net "M_K_CPU1_SA_CB<6>")
	)
	(segment
		(start 146.270218 -248.822464)
		(end 147.853146 -248.822464)
		(width 0.0889)
		(layer "In6.Cu")
		(net "M_K_CPU1_SA_CB<6>")
	)
	(segment
		(start 147.853146 -248.822464)
		(end 148.493226 -248.822464)
		(width 0.14478)
		(layer "In6.Cu")
		(net "M_K_CPU1_SA_CB<6>")
	)
	(segment
		(start 144.007078 -248.217944)
		(end 144.017492 -248.211848)
		(width 0.0889)
		(layer "In6.Cu")
		(net "M_K_CPU1_SA_CB<6>")
	)
	(segment
		(start 158.187136 -248.170954)
		(end 163.547806 -242.810284)
		(width 0.14478)
		(layer "In6.Cu")
		(net "M_K_CPU1_SA_CB<6>")
	)
	(segment
		(start 175.501046 -242.10518)
		(end 175.645826 -241.9604)
		(width 0.14478)
		(layer "In6.Cu")
		(net "M_K_CPU1_SA_CB<6>")
	)
	(segment
		(start 173.846744 -242.10518)
		(end 173.846744 -242.879626)
		(width 0.14478)
		(layer "In6.Cu")
		(net "M_K_CPU1_SA_CB<6>")
	)
	(arc
		(start 143.086074 -248.207022)
		(mid 143.269582 -248.161528)
		(end 143.451834 -248.211848)
		(width 0.0889)
		(layer "In6.Cu")
		(net "M_K_CPU1_SA_CB<6>")
	)
	(arc
		(start 143.451834 -248.211848)
		(mid 143.728647 -248.287991)
		(end 144.007078 -248.217944)
		(width 0.0889)
		(layer "In6.Cu")
		(net "M_K_CPU1_SA_CB<6>")
	)
	(arc
		(start 144.957546 -248.211848)
		(mid 145.137751 -248.161531)
		(end 145.31975 -248.20499)
		(width 0.0889)
		(layer "In6.Cu")
		(net "M_K_CPU1_SA_CB<6>")
	)
	(arc
		(start 142.574772 -248.243598)
		(mid 142.82998 -248.287075)
		(end 143.077692 -248.211848)
		(width 0.0889)
		(layer "In6.Cu")
		(net "M_K_CPU1_SA_CB<6>")
	)
	(arc
		(start 145.31975 -248.20499)
		(mid 145.45054 -248.256501)
		(end 145.590006 -248.274078)
		(width 0.0889)
		(layer "In6.Cu")
		(net "M_K_CPU1_SA_CB<6>")
	)
	(arc
		(start 144.401794 -248.217944)
		(mid 144.68048 -248.288164)
		(end 144.957546 -248.211848)
		(width 0.0889)
		(layer "In6.Cu")
		(net "M_K_CPU1_SA_CB<6>")
	)
	(arc
		(start 144.017492 -248.211848)
		(mid 144.204436 -248.161593)
		(end 144.39138 -248.211848)
		(width 0.0889)
		(layer "In6.Cu")
		(net "M_K_CPU1_SA_CB<6>")
	)
	(segment
		(start 140.91793 -248.800366)
		(end 141.384782 -248.534428)
		(width 0.10668)
		(layer "F.Cu")
		(net "M_K_CPU1_SA_CB<5>")
	)
	(segment
		(start 144.007078 -248.850912)
		(end 144.017492 -248.857008)
		(width 0.0889)
		(layer "In6.Cu")
		(net "M_K_CPU1_SA_CB<5>")
	)
	(segment
		(start 197.663562 -241.9604)
		(end 198.279258 -241.9604)
		(width 0.14478)
		(layer "In6.Cu")
		(net "M_K_CPU1_SA_CB<5>")
	)
	(segment
		(start 143.077692 -248.857008)
		(end 143.086074 -248.861834)
		(width 0.0889)
		(layer "In6.Cu")
		(net "M_K_CPU1_SA_CB<5>")
	)
	(segment
		(start 198.279258 -241.9604)
		(end 198.7042 -242.385342)
		(width 0.14478)
		(layer "In6.Cu")
		(net "M_K_CPU1_SA_CB<5>")
	)
	(segment
		(start 196.415914 -242.10518)
		(end 196.560694 -241.9604)
		(width 0.14478)
		(layer "In6.Cu")
		(net "M_K_CPU1_SA_CB<5>")
	)
	(segment
		(start 196.560694 -241.9604)
		(end 196.822568 -241.9604)
		(width 0.14478)
		(layer "In6.Cu")
		(net "M_K_CPU1_SA_CB<5>")
	)
	(segment
		(start 196.967348 -242.567206)
		(end 197.112128 -242.711986)
		(width 0.14478)
		(layer "In6.Cu")
		(net "M_K_CPU1_SA_CB<5>")
	)
	(segment
		(start 141.230858 -248.799858)
		(end 141.25321 -248.88317)
		(width 0.0889)
		(layer "In6.Cu")
		(net "M_K_CPU1_SA_CB<5>")
	)
	(segment
		(start 196.415914 -242.567206)
		(end 196.415914 -242.10518)
		(width 0.14478)
		(layer "In6.Cu")
		(net "M_K_CPU1_SA_CB<5>")
	)
	(segment
		(start 177.816002 -243.660422)
		(end 178.66614 -242.810284)
		(width 0.14478)
		(layer "In6.Cu")
		(net "M_K_CPU1_SA_CB<5>")
	)
	(segment
		(start 196.967348 -242.10518)
		(end 196.967348 -242.567206)
		(width 0.14478)
		(layer "In6.Cu")
		(net "M_K_CPU1_SA_CB<5>")
	)
	(segment
		(start 188.801248 -242.810284)
		(end 189.651132 -241.9604)
		(width 0.14478)
		(layer "In6.Cu")
		(net "M_K_CPU1_SA_CB<5>")
	)
	(segment
		(start 142.503398 -248.861834)
		(end 142.51178 -248.857008)
		(width 0.0889)
		(layer "In6.Cu")
		(net "M_K_CPU1_SA_CB<5>")
	)
	(segment
		(start 163.426902 -243.660422)
		(end 177.816002 -243.660422)
		(width 0.14478)
		(layer "In6.Cu")
		(net "M_K_CPU1_SA_CB<5>")
	)
	(segment
		(start 147.552156 -249.252232)
		(end 147.615148 -249.315224)
		(width 0.0889)
		(layer "In6.Cu")
		(net "M_K_CPU1_SA_CB<5>")
	)
	(segment
		(start 141.384782 -248.534428)
		(end 141.230858 -248.799858)
		(width 0.0889)
		(layer "In6.Cu")
		(net "M_K_CPU1_SA_CB<5>")
	)
	(segment
		(start 195.7197 -241.9604)
		(end 195.86448 -242.10518)
		(width 0.14478)
		(layer "In6.Cu")
		(net "M_K_CPU1_SA_CB<5>")
	)
	(segment
		(start 149.40661 -248.625614)
		(end 158.46171 -248.625614)
		(width 0.14478)
		(layer "In6.Cu")
		(net "M_K_CPU1_SA_CB<5>")
	)
	(segment
		(start 158.46171 -248.625614)
		(end 163.426902 -243.660422)
		(width 0.14478)
		(layer "In6.Cu")
		(net "M_K_CPU1_SA_CB<5>")
	)
	(segment
		(start 144.391126 -248.857008)
		(end 144.40154 -248.850912)
		(width 0.0889)
		(layer "In6.Cu")
		(net "M_K_CPU1_SA_CB<5>")
	)
	(segment
		(start 197.374002 -242.711986)
		(end 197.518782 -242.567206)
		(width 0.14478)
		(layer "In6.Cu")
		(net "M_K_CPU1_SA_CB<5>")
	)
	(segment
		(start 196.271134 -242.711986)
		(end 196.415914 -242.567206)
		(width 0.14478)
		(layer "In6.Cu")
		(net "M_K_CPU1_SA_CB<5>")
	)
	(segment
		(start 144.017492 -248.857008)
		(end 144.025874 -248.861834)
		(width 0.0889)
		(layer "In6.Cu")
		(net "M_K_CPU1_SA_CB<5>")
	)
	(segment
		(start 148.717 -249.315224)
		(end 149.40661 -248.625614)
		(width 0.14478)
		(layer "In6.Cu")
		(net "M_K_CPU1_SA_CB<5>")
	)
	(segment
		(start 189.651132 -241.9604)
		(end 195.7197 -241.9604)
		(width 0.14478)
		(layer "In6.Cu")
		(net "M_K_CPU1_SA_CB<5>")
	)
	(segment
		(start 196.00926 -242.711986)
		(end 196.271134 -242.711986)
		(width 0.14478)
		(layer "In6.Cu")
		(net "M_K_CPU1_SA_CB<5>")
	)
	(segment
		(start 197.518782 -242.567206)
		(end 197.518782 -242.10518)
		(width 0.14478)
		(layer "In6.Cu")
		(net "M_K_CPU1_SA_CB<5>")
	)
	(segment
		(start 147.911058 -249.315224)
		(end 148.717 -249.315224)
		(width 0.14478)
		(layer "In6.Cu")
		(net "M_K_CPU1_SA_CB<5>")
	)
	(segment
		(start 147.615148 -249.315224)
		(end 147.911058 -249.315224)
		(width 0.0889)
		(layer "In6.Cu")
		(net "M_K_CPU1_SA_CB<5>")
	)
	(segment
		(start 197.112128 -242.711986)
		(end 197.374002 -242.711986)
		(width 0.14478)
		(layer "In6.Cu")
		(net "M_K_CPU1_SA_CB<5>")
	)
	(segment
		(start 196.822568 -241.9604)
		(end 196.967348 -242.10518)
		(width 0.14478)
		(layer "In6.Cu")
		(net "M_K_CPU1_SA_CB<5>")
	)
	(segment
		(start 144.957292 -248.857008)
		(end 145.655792 -249.252232)
		(width 0.0889)
		(layer "In6.Cu")
		(net "M_K_CPU1_SA_CB<5>")
	)
	(segment
		(start 197.518782 -242.10518)
		(end 197.663562 -241.9604)
		(width 0.14478)
		(layer "In6.Cu")
		(net "M_K_CPU1_SA_CB<5>")
	)
	(segment
		(start 145.655792 -249.252232)
		(end 147.552156 -249.252232)
		(width 0.0889)
		(layer "In6.Cu")
		(net "M_K_CPU1_SA_CB<5>")
	)
	(segment
		(start 195.86448 -242.10518)
		(end 195.86448 -242.567206)
		(width 0.14478)
		(layer "In6.Cu")
		(net "M_K_CPU1_SA_CB<5>")
	)
	(segment
		(start 195.86448 -242.567206)
		(end 196.00926 -242.711986)
		(width 0.14478)
		(layer "In6.Cu")
		(net "M_K_CPU1_SA_CB<5>")
	)
	(segment
		(start 178.66614 -242.810284)
		(end 188.801248 -242.810284)
		(width 0.14478)
		(layer "In6.Cu")
		(net "M_K_CPU1_SA_CB<5>")
	)
	(arc
		(start 143.086074 -248.861834)
		(mid 143.269582 -248.907328)
		(end 143.451834 -248.857008)
		(width 0.0889)
		(layer "In6.Cu")
		(net "M_K_CPU1_SA_CB<5>")
	)
	(arc
		(start 143.451834 -248.857008)
		(mid 143.728647 -248.780865)
		(end 144.007078 -248.850912)
		(width 0.0889)
		(layer "In6.Cu")
		(net "M_K_CPU1_SA_CB<5>")
	)
	(arc
		(start 142.137638 -248.857008)
		(mid 142.319889 -248.907358)
		(end 142.503398 -248.861834)
		(width 0.0889)
		(layer "In6.Cu")
		(net "M_K_CPU1_SA_CB<5>")
	)
	(arc
		(start 141.25321 -248.88317)
		(mid 141.415399 -248.905905)
		(end 141.571726 -248.857008)
		(width 0.0889)
		(layer "In6.Cu")
		(net "M_K_CPU1_SA_CB<5>")
	)
	(arc
		(start 141.571726 -248.857008)
		(mid 141.854682 -248.780831)
		(end 142.137638 -248.857008)
		(width 0.0889)
		(layer "In6.Cu")
		(net "M_K_CPU1_SA_CB<5>")
	)
	(arc
		(start 144.40154 -248.850912)
		(mid 144.680226 -248.780692)
		(end 144.957292 -248.857008)
		(width 0.0889)
		(layer "In6.Cu")
		(net "M_K_CPU1_SA_CB<5>")
	)
	(arc
		(start 144.025874 -248.861834)
		(mid 144.209128 -248.907207)
		(end 144.391126 -248.857008)
		(width 0.0889)
		(layer "In6.Cu")
		(net "M_K_CPU1_SA_CB<5>")
	)
	(arc
		(start 142.51178 -248.857008)
		(mid 142.794736 -248.780831)
		(end 143.077692 -248.857008)
		(width 0.0889)
		(layer "In6.Cu")
		(net "M_K_CPU1_SA_CB<5>")
	)
	(segment
		(start 142.327884 -247.99036)
		(end 142.794736 -247.724422)
		(width 0.10668)
		(layer "F.Cu")
		(net "M_K_CPU1_SA_CB<4>")
	)
	(segment
		(start 197.872096 -240.269776)
		(end 198.288656 -240.269776)
		(width 0.14478)
		(layer "In6.Cu")
		(net "M_K_CPU1_SA_CB<4>")
	)
	(segment
		(start 197.175882 -240.414556)
		(end 197.175882 -241.035586)
		(width 0.14478)
		(layer "In6.Cu")
		(net "M_K_CPU1_SA_CB<4>")
	)
	(segment
		(start 145.81886 -248.083578)
		(end 146.092926 -248.357644)
		(width 0.0889)
		(layer "In6.Cu")
		(net "M_K_CPU1_SA_CB<4>")
	)
	(segment
		(start 163.78047 -241.9604)
		(end 163.92525 -241.81562)
		(width 0.14478)
		(layer "In6.Cu")
		(net "M_K_CPU1_SA_CB<4>")
	)
	(segment
		(start 165.579552 -241.81562)
		(end 165.724332 -241.9604)
		(width 0.14478)
		(layer "In6.Cu")
		(net "M_K_CPU1_SA_CB<4>")
	)
	(segment
		(start 164.331904 -241.355626)
		(end 164.476684 -241.500406)
		(width 0.14478)
		(layer "In6.Cu")
		(net "M_K_CPU1_SA_CB<4>")
	)
	(segment
		(start 189.641734 -240.269776)
		(end 197.031102 -240.269776)
		(width 0.14478)
		(layer "In6.Cu")
		(net "M_K_CPU1_SA_CB<4>")
	)
	(segment
		(start 146.092926 -248.357644)
		(end 147.84705 -248.357644)
		(width 0.0889)
		(layer "In6.Cu")
		(net "M_K_CPU1_SA_CB<4>")
	)
	(segment
		(start 188.79185 -241.11966)
		(end 189.641734 -240.269776)
		(width 0.14478)
		(layer "In6.Cu")
		(net "M_K_CPU1_SA_CB<4>")
	)
	(segment
		(start 142.794736 -247.724422)
		(end 142.640812 -247.989852)
		(width 0.0889)
		(layer "In6.Cu")
		(net "M_K_CPU1_SA_CB<4>")
	)
	(segment
		(start 166.843964 -241.11966)
		(end 188.79185 -241.11966)
		(width 0.14478)
		(layer "In6.Cu")
		(net "M_K_CPU1_SA_CB<4>")
	)
	(segment
		(start 198.288656 -240.269776)
		(end 198.7042 -240.68532)
		(width 0.14478)
		(layer "In6.Cu")
		(net "M_K_CPU1_SA_CB<4>")
	)
	(segment
		(start 143.921734 -248.047002)
		(end 143.932148 -248.040906)
		(width 0.0889)
		(layer "In6.Cu")
		(net "M_K_CPU1_SA_CB<4>")
	)
	(segment
		(start 164.476684 -241.81562)
		(end 164.621464 -241.9604)
		(width 0.14478)
		(layer "In6.Cu")
		(net "M_K_CPU1_SA_CB<4>")
	)
	(segment
		(start 165.028118 -241.81562)
		(end 165.028118 -241.500406)
		(width 0.14478)
		(layer "In6.Cu")
		(net "M_K_CPU1_SA_CB<4>")
	)
	(segment
		(start 164.07003 -241.355626)
		(end 164.331904 -241.355626)
		(width 0.14478)
		(layer "In6.Cu")
		(net "M_K_CPU1_SA_CB<4>")
	)
	(segment
		(start 165.579552 -241.500406)
		(end 165.579552 -241.81562)
		(width 0.14478)
		(layer "In6.Cu")
		(net "M_K_CPU1_SA_CB<4>")
	)
	(segment
		(start 165.028118 -241.500406)
		(end 165.172898 -241.355626)
		(width 0.14478)
		(layer "In6.Cu")
		(net "M_K_CPU1_SA_CB<4>")
	)
	(segment
		(start 164.621464 -241.9604)
		(end 164.883338 -241.9604)
		(width 0.14478)
		(layer "In6.Cu")
		(net "M_K_CPU1_SA_CB<4>")
	)
	(segment
		(start 164.476684 -241.500406)
		(end 164.476684 -241.81562)
		(width 0.14478)
		(layer "In6.Cu")
		(net "M_K_CPU1_SA_CB<4>")
	)
	(segment
		(start 147.84705 -248.357644)
		(end 148.295106 -248.357644)
		(width 0.14478)
		(layer "In6.Cu")
		(net "M_K_CPU1_SA_CB<4>")
	)
	(segment
		(start 165.434772 -241.355626)
		(end 165.579552 -241.500406)
		(width 0.14478)
		(layer "In6.Cu")
		(net "M_K_CPU1_SA_CB<4>")
	)
	(segment
		(start 163.92525 -241.500406)
		(end 164.07003 -241.355626)
		(width 0.14478)
		(layer "In6.Cu")
		(net "M_K_CPU1_SA_CB<4>")
	)
	(segment
		(start 145.59026 -248.083578)
		(end 145.81886 -248.083578)
		(width 0.0889)
		(layer "In6.Cu")
		(net "M_K_CPU1_SA_CB<4>")
	)
	(segment
		(start 165.172898 -241.355626)
		(end 165.434772 -241.355626)
		(width 0.14478)
		(layer "In6.Cu")
		(net "M_K_CPU1_SA_CB<4>")
	)
	(segment
		(start 143.913352 -248.051828)
		(end 143.921734 -248.047002)
		(width 0.0889)
		(layer "In6.Cu")
		(net "M_K_CPU1_SA_CB<4>")
	)
	(segment
		(start 163.56203 -241.9604)
		(end 163.78047 -241.9604)
		(width 0.14478)
		(layer "In6.Cu")
		(net "M_K_CPU1_SA_CB<4>")
	)
	(segment
		(start 197.031102 -240.269776)
		(end 197.175882 -240.414556)
		(width 0.14478)
		(layer "In6.Cu")
		(net "M_K_CPU1_SA_CB<4>")
	)
	(segment
		(start 165.724332 -241.9604)
		(end 166.003224 -241.9604)
		(width 0.14478)
		(layer "In6.Cu")
		(net "M_K_CPU1_SA_CB<4>")
	)
	(segment
		(start 197.175882 -241.035586)
		(end 197.320662 -241.180366)
		(width 0.14478)
		(layer "In6.Cu")
		(net "M_K_CPU1_SA_CB<4>")
	)
	(segment
		(start 197.320662 -241.180366)
		(end 197.582536 -241.180366)
		(width 0.14478)
		(layer "In6.Cu")
		(net "M_K_CPU1_SA_CB<4>")
	)
	(segment
		(start 164.883338 -241.9604)
		(end 165.028118 -241.81562)
		(width 0.14478)
		(layer "In6.Cu")
		(net "M_K_CPU1_SA_CB<4>")
	)
	(segment
		(start 142.640812 -247.989852)
		(end 142.663164 -248.073164)
		(width 0.0889)
		(layer "In6.Cu")
		(net "M_K_CPU1_SA_CB<4>")
	)
	(segment
		(start 157.806136 -247.716294)
		(end 163.56203 -241.9604)
		(width 0.14478)
		(layer "In6.Cu")
		(net "M_K_CPU1_SA_CB<4>")
	)
	(segment
		(start 144.487392 -248.047002)
		(end 144.495774 -248.051828)
		(width 0.0889)
		(layer "In6.Cu")
		(net "M_K_CPU1_SA_CB<4>")
	)
	(segment
		(start 163.92525 -241.81562)
		(end 163.92525 -241.500406)
		(width 0.14478)
		(layer "In6.Cu")
		(net "M_K_CPU1_SA_CB<4>")
	)
	(segment
		(start 197.727316 -240.414556)
		(end 197.872096 -240.269776)
		(width 0.14478)
		(layer "In6.Cu")
		(net "M_K_CPU1_SA_CB<4>")
	)
	(segment
		(start 148.295106 -248.357644)
		(end 148.936456 -247.716294)
		(width 0.14478)
		(layer "In6.Cu")
		(net "M_K_CPU1_SA_CB<4>")
	)
	(segment
		(start 197.582536 -241.180366)
		(end 197.727316 -241.035586)
		(width 0.14478)
		(layer "In6.Cu")
		(net "M_K_CPU1_SA_CB<4>")
	)
	(segment
		(start 197.727316 -241.035586)
		(end 197.727316 -240.414556)
		(width 0.14478)
		(layer "In6.Cu")
		(net "M_K_CPU1_SA_CB<4>")
	)
	(segment
		(start 148.936456 -247.716294)
		(end 157.806136 -247.716294)
		(width 0.14478)
		(layer "In6.Cu")
		(net "M_K_CPU1_SA_CB<4>")
	)
	(segment
		(start 166.003224 -241.9604)
		(end 166.843964 -241.11966)
		(width 0.14478)
		(layer "In6.Cu")
		(net "M_K_CPU1_SA_CB<4>")
	)
	(arc
		(start 143.932148 -248.040906)
		(mid 144.21058 -247.970808)
		(end 144.487392 -248.047002)
		(width 0.0889)
		(layer "In6.Cu")
		(net "M_K_CPU1_SA_CB<4>")
	)
	(arc
		(start 144.495774 -248.051828)
		(mid 144.679282 -248.097322)
		(end 144.861534 -248.047002)
		(width 0.0889)
		(layer "In6.Cu")
		(net "M_K_CPU1_SA_CB<4>")
	)
	(arc
		(start 142.98168 -248.047002)
		(mid 143.264636 -247.970825)
		(end 143.547592 -248.047002)
		(width 0.0889)
		(layer "In6.Cu")
		(net "M_K_CPU1_SA_CB<4>")
	)
	(arc
		(start 144.861534 -248.047002)
		(mid 145.135986 -247.970766)
		(end 145.412714 -248.038366)
		(width 0.0889)
		(layer "In6.Cu")
		(net "M_K_CPU1_SA_CB<4>")
	)
	(arc
		(start 143.547592 -248.047002)
		(mid 143.729843 -248.097352)
		(end 143.913352 -248.051828)
		(width 0.0889)
		(layer "In6.Cu")
		(net "M_K_CPU1_SA_CB<4>")
	)
	(arc
		(start 145.412714 -248.038366)
		(mid 145.498672 -248.072021)
		(end 145.59026 -248.083578)
		(width 0.0889)
		(layer "In6.Cu")
		(net "M_K_CPU1_SA_CB<4>")
	)
	(arc
		(start 142.663164 -248.073164)
		(mid 142.825353 -248.095899)
		(end 142.98168 -248.047002)
		(width 0.0889)
		(layer "In6.Cu")
		(net "M_K_CPU1_SA_CB<4>")
	)
	(segment
		(start 140.447776 -246.370348)
		(end 140.914882 -246.10441)
		(width 0.10668)
		(layer "F.Cu")
		(net "M_K_CPU1_SA_CB<3>")
	)
	(segment
		(start 166.92626 -236.850936)
		(end 169.898568 -236.850936)
		(width 0.14478)
		(layer "In6.Cu")
		(net "M_K_CPU1_SA_CB<3>")
	)
	(segment
		(start 180.454554 -237.328964)
		(end 180.617622 -237.492032)
		(width 0.14478)
		(layer "In6.Cu")
		(net "M_K_CPU1_SA_CB<3>")
	)
	(segment
		(start 174.459392 -236.860334)
		(end 174.775114 -236.860334)
		(width 0.14478)
		(layer "In6.Cu")
		(net "M_K_CPU1_SA_CB<3>")
	)
	(segment
		(start 143.921734 -245.78183)
		(end 143.932148 -245.787926)
		(width 0.0889)
		(layer "In6.Cu")
		(net "M_K_CPU1_SA_CB<3>")
	)
	(segment
		(start 145.106136 -245.864634)
		(end 147.225258 -245.864634)
		(width 0.0889)
		(layer "In6.Cu")
		(net "M_K_CPU1_SA_CB<3>")
	)
	(segment
		(start 188.236606 -237.479332)
		(end 188.236606 -237.547404)
		(width 0.14478)
		(layer "In6.Cu")
		(net "M_K_CPU1_SA_CB<3>")
	)
	(segment
		(start 190.054738 -236.478826)
		(end 190.316612 -236.478826)
		(width 0.14478)
		(layer "In6.Cu")
		(net "M_K_CPU1_SA_CB<3>")
	)
	(segment
		(start 180.224176 -237.328964)
		(end 180.454554 -237.328964)
		(width 0.14478)
		(layer "In6.Cu")
		(net "M_K_CPU1_SA_CB<3>")
	)
	(segment
		(start 181.140862 -237.710472)
		(end 181.991 -236.860334)
		(width 0.14478)
		(layer "In6.Cu")
		(net "M_K_CPU1_SA_CB<3>")
	)
	(segment
		(start 178.29276 -237.701074)
		(end 179.907438 -237.701074)
		(width 0.14478)
		(layer "In6.Cu")
		(net "M_K_CPU1_SA_CB<3>")
	)
	(segment
		(start 184.986422 -236.850936)
		(end 185.83656 -237.701074)
		(width 0.14478)
		(layer "In6.Cu")
		(net "M_K_CPU1_SA_CB<3>")
	)
	(segment
		(start 193.723006 -237.245398)
		(end 193.723006 -237.023402)
		(width 0.14478)
		(layer "In6.Cu")
		(net "M_K_CPU1_SA_CB<3>")
	)
	(segment
		(start 177.442622 -236.850936)
		(end 178.29276 -237.701074)
		(width 0.14478)
		(layer "In6.Cu")
		(net "M_K_CPU1_SA_CB<3>")
	)
	(segment
		(start 169.898568 -236.850936)
		(end 170.748706 -237.701074)
		(width 0.14478)
		(layer "In6.Cu")
		(net "M_K_CPU1_SA_CB<3>")
	)
	(segment
		(start 192.698624 -236.860334)
		(end 193.003424 -236.860334)
		(width 0.14478)
		(layer "In6.Cu")
		(net "M_K_CPU1_SA_CB<3>")
	)
	(segment
		(start 172.426122 -237.701074)
		(end 172.579792 -237.547404)
		(width 0.14478)
		(layer "In6.Cu")
		(net "M_K_CPU1_SA_CB<3>")
	)
	(segment
		(start 187.680092 -237.479332)
		(end 187.84316 -237.316264)
		(width 0.14478)
		(layer "In6.Cu")
		(net "M_K_CPU1_SA_CB<3>")
	)
	(segment
		(start 189.909958 -236.623606)
		(end 190.054738 -236.478826)
		(width 0.14478)
		(layer "In6.Cu")
		(net "M_K_CPU1_SA_CB<3>")
	)
	(segment
		(start 189.765178 -236.850936)
		(end 189.909958 -236.706156)
		(width 0.14478)
		(layer "In6.Cu")
		(net "M_K_CPU1_SA_CB<3>")
	)
	(segment
		(start 193.32956 -237.408466)
		(end 193.559938 -237.408466)
		(width 0.14478)
		(layer "In6.Cu")
		(net "M_K_CPU1_SA_CB<3>")
	)
	(segment
		(start 175.10125 -236.467904)
		(end 175.331628 -236.467904)
		(width 0.14478)
		(layer "In6.Cu")
		(net "M_K_CPU1_SA_CB<3>")
	)
	(segment
		(start 140.914882 -246.10441)
		(end 141.068806 -245.83898)
		(width 0.0889)
		(layer "In6.Cu")
		(net "M_K_CPU1_SA_CB<3>")
	)
	(segment
		(start 188.236606 -237.547404)
		(end 188.399674 -237.710472)
		(width 0.14478)
		(layer "In6.Cu")
		(net "M_K_CPU1_SA_CB<3>")
	)
	(segment
		(start 183.099964 -236.850936)
		(end 184.986422 -236.850936)
		(width 0.14478)
		(layer "In6.Cu")
		(net "M_K_CPU1_SA_CB<3>")
	)
	(segment
		(start 174.938182 -236.697266)
		(end 174.938182 -236.630972)
		(width 0.14478)
		(layer "In6.Cu")
		(net "M_K_CPU1_SA_CB<3>")
	)
	(segment
		(start 188.073538 -237.316264)
		(end 188.236606 -237.479332)
		(width 0.14478)
		(layer "In6.Cu")
		(net "M_K_CPU1_SA_CB<3>")
	)
	(segment
		(start 173.299374 -237.710472)
		(end 173.609254 -237.710472)
		(width 0.14478)
		(layer "In6.Cu")
		(net "M_K_CPU1_SA_CB<3>")
	)
	(segment
		(start 190.316612 -236.478826)
		(end 190.461392 -236.623606)
		(width 0.14478)
		(layer "In6.Cu")
		(net "M_K_CPU1_SA_CB<3>")
	)
	(segment
		(start 144.873472 -245.793768)
		(end 144.988534 -245.841266)
		(width 0.0889)
		(layer "In6.Cu")
		(net "M_K_CPU1_SA_CB<3>")
	)
	(segment
		(start 193.003424 -236.860334)
		(end 193.166492 -237.023402)
		(width 0.14478)
		(layer "In6.Cu")
		(net "M_K_CPU1_SA_CB<3>")
	)
	(segment
		(start 188.673232 -237.710472)
		(end 189.532768 -236.850936)
		(width 0.14478)
		(layer "In6.Cu")
		(net "M_K_CPU1_SA_CB<3>")
	)
	(segment
		(start 193.166492 -237.245398)
		(end 193.32956 -237.408466)
		(width 0.14478)
		(layer "In6.Cu")
		(net "M_K_CPU1_SA_CB<3>")
	)
	(segment
		(start 164.204904 -237.710472)
		(end 166.066724 -237.710472)
		(width 0.14478)
		(layer "In6.Cu")
		(net "M_K_CPU1_SA_CB<3>")
	)
	(segment
		(start 147.729448 -245.360444)
		(end 147.900898 -245.360444)
		(width 0.0889)
		(layer "In6.Cu")
		(net "M_K_CPU1_SA_CB<3>")
	)
	(segment
		(start 175.648366 -236.850936)
		(end 177.442622 -236.850936)
		(width 0.14478)
		(layer "In6.Cu")
		(net "M_K_CPU1_SA_CB<3>")
	)
	(segment
		(start 175.494696 -236.697266)
		(end 175.648366 -236.850936)
		(width 0.14478)
		(layer "In6.Cu")
		(net "M_K_CPU1_SA_CB<3>")
	)
	(segment
		(start 147.900898 -245.360444)
		(end 156.554932 -245.360444)
		(width 0.14478)
		(layer "In6.Cu")
		(net "M_K_CPU1_SA_CB<3>")
	)
	(segment
		(start 193.723006 -237.023402)
		(end 193.886074 -236.860334)
		(width 0.14478)
		(layer "In6.Cu")
		(net "M_K_CPU1_SA_CB<3>")
	)
	(segment
		(start 172.74286 -237.323884)
		(end 172.973238 -237.323884)
		(width 0.14478)
		(layer "In6.Cu")
		(net "M_K_CPU1_SA_CB<3>")
	)
	(segment
		(start 191.979042 -236.697266)
		(end 191.979042 -236.630972)
		(width 0.14478)
		(layer "In6.Cu")
		(net "M_K_CPU1_SA_CB<3>")
	)
	(segment
		(start 192.535556 -236.630972)
		(end 192.535556 -236.697266)
		(width 0.14478)
		(layer "In6.Cu")
		(net "M_K_CPU1_SA_CB<3>")
	)
	(segment
		(start 179.907438 -237.701074)
		(end 180.061108 -237.547404)
		(width 0.14478)
		(layer "In6.Cu")
		(net "M_K_CPU1_SA_CB<3>")
	)
	(segment
		(start 192.372488 -236.467904)
		(end 192.535556 -236.630972)
		(width 0.14478)
		(layer "In6.Cu")
		(net "M_K_CPU1_SA_CB<3>")
	)
	(segment
		(start 193.886074 -236.860334)
		(end 194.17919 -236.860334)
		(width 0.14478)
		(layer "In6.Cu")
		(net "M_K_CPU1_SA_CB<3>")
	)
	(segment
		(start 187.84316 -237.316264)
		(end 188.073538 -237.316264)
		(width 0.14478)
		(layer "In6.Cu")
		(net "M_K_CPU1_SA_CB<3>")
	)
	(segment
		(start 187.526422 -237.701074)
		(end 187.680092 -237.547404)
		(width 0.14478)
		(layer "In6.Cu")
		(net "M_K_CPU1_SA_CB<3>")
	)
	(segment
		(start 193.166492 -237.023402)
		(end 193.166492 -237.245398)
		(width 0.14478)
		(layer "In6.Cu")
		(net "M_K_CPU1_SA_CB<3>")
	)
	(segment
		(start 172.973238 -237.323884)
		(end 173.136306 -237.486952)
		(width 0.14478)
		(layer "In6.Cu")
		(net "M_K_CPU1_SA_CB<3>")
	)
	(segment
		(start 190.461392 -236.706156)
		(end 190.606172 -236.850936)
		(width 0.14478)
		(layer "In6.Cu")
		(net "M_K_CPU1_SA_CB<3>")
	)
	(segment
		(start 182.946294 -236.697266)
		(end 183.099964 -236.850936)
		(width 0.14478)
		(layer "In6.Cu")
		(net "M_K_CPU1_SA_CB<3>")
	)
	(segment
		(start 180.061108 -237.547404)
		(end 180.061108 -237.492032)
		(width 0.14478)
		(layer "In6.Cu")
		(net "M_K_CPU1_SA_CB<3>")
	)
	(segment
		(start 174.938182 -236.630972)
		(end 175.10125 -236.467904)
		(width 0.14478)
		(layer "In6.Cu")
		(net "M_K_CPU1_SA_CB<3>")
	)
	(segment
		(start 180.617622 -237.547404)
		(end 180.78069 -237.710472)
		(width 0.14478)
		(layer "In6.Cu")
		(net "M_K_CPU1_SA_CB<3>")
	)
	(segment
		(start 191.825372 -236.850936)
		(end 191.979042 -236.697266)
		(width 0.14478)
		(layer "In6.Cu")
		(net "M_K_CPU1_SA_CB<3>")
	)
	(segment
		(start 190.606172 -236.850936)
		(end 191.825372 -236.850936)
		(width 0.14478)
		(layer "In6.Cu")
		(net "M_K_CPU1_SA_CB<3>")
	)
	(segment
		(start 173.136306 -237.486952)
		(end 173.136306 -237.547404)
		(width 0.14478)
		(layer "In6.Cu")
		(net "M_K_CPU1_SA_CB<3>")
	)
	(segment
		(start 173.609254 -237.710472)
		(end 174.459392 -236.860334)
		(width 0.14478)
		(layer "In6.Cu")
		(net "M_K_CPU1_SA_CB<3>")
	)
	(segment
		(start 180.061108 -237.492032)
		(end 180.224176 -237.328964)
		(width 0.14478)
		(layer "In6.Cu")
		(net "M_K_CPU1_SA_CB<3>")
	)
	(segment
		(start 174.775114 -236.860334)
		(end 174.938182 -236.697266)
		(width 0.14478)
		(layer "In6.Cu")
		(net "M_K_CPU1_SA_CB<3>")
	)
	(segment
		(start 175.331628 -236.467904)
		(end 175.494696 -236.630972)
		(width 0.14478)
		(layer "In6.Cu")
		(net "M_K_CPU1_SA_CB<3>")
	)
	(segment
		(start 144.861534 -245.78183)
		(end 144.873472 -245.793768)
		(width 0.0889)
		(layer "In6.Cu")
		(net "M_K_CPU1_SA_CB<3>")
	)
	(segment
		(start 182.946294 -236.630972)
		(end 182.946294 -236.697266)
		(width 0.14478)
		(layer "In6.Cu")
		(net "M_K_CPU1_SA_CB<3>")
	)
	(segment
		(start 181.991 -236.860334)
		(end 182.226712 -236.860334)
		(width 0.14478)
		(layer "In6.Cu")
		(net "M_K_CPU1_SA_CB<3>")
	)
	(segment
		(start 192.535556 -236.697266)
		(end 192.698624 -236.860334)
		(width 0.14478)
		(layer "In6.Cu")
		(net "M_K_CPU1_SA_CB<3>")
	)
	(segment
		(start 175.494696 -236.630972)
		(end 175.494696 -236.697266)
		(width 0.14478)
		(layer "In6.Cu")
		(net "M_K_CPU1_SA_CB<3>")
	)
	(segment
		(start 144.487392 -245.78183)
		(end 144.495774 -245.777004)
		(width 0.0889)
		(layer "In6.Cu")
		(net "M_K_CPU1_SA_CB<3>")
	)
	(segment
		(start 187.680092 -237.547404)
		(end 187.680092 -237.479332)
		(width 0.14478)
		(layer "In6.Cu")
		(net "M_K_CPU1_SA_CB<3>")
	)
	(segment
		(start 172.579792 -237.547404)
		(end 172.579792 -237.486952)
		(width 0.14478)
		(layer "In6.Cu")
		(net "M_K_CPU1_SA_CB<3>")
	)
	(segment
		(start 182.552848 -236.467904)
		(end 182.783226 -236.467904)
		(width 0.14478)
		(layer "In6.Cu")
		(net "M_K_CPU1_SA_CB<3>")
	)
	(segment
		(start 170.748706 -237.701074)
		(end 172.426122 -237.701074)
		(width 0.14478)
		(layer "In6.Cu")
		(net "M_K_CPU1_SA_CB<3>")
	)
	(segment
		(start 189.909958 -236.706156)
		(end 189.909958 -236.623606)
		(width 0.14478)
		(layer "In6.Cu")
		(net "M_K_CPU1_SA_CB<3>")
	)
	(segment
		(start 141.068806 -245.83898)
		(end 141.164818 -245.81358)
		(width 0.0889)
		(layer "In6.Cu")
		(net "M_K_CPU1_SA_CB<3>")
	)
	(segment
		(start 143.913352 -245.777004)
		(end 143.921734 -245.78183)
		(width 0.0889)
		(layer "In6.Cu")
		(net "M_K_CPU1_SA_CB<3>")
	)
	(segment
		(start 182.38978 -236.697266)
		(end 182.38978 -236.630972)
		(width 0.14478)
		(layer "In6.Cu")
		(net "M_K_CPU1_SA_CB<3>")
	)
	(segment
		(start 185.83656 -237.701074)
		(end 187.526422 -237.701074)
		(width 0.14478)
		(layer "In6.Cu")
		(net "M_K_CPU1_SA_CB<3>")
	)
	(segment
		(start 182.226712 -236.860334)
		(end 182.38978 -236.697266)
		(width 0.14478)
		(layer "In6.Cu")
		(net "M_K_CPU1_SA_CB<3>")
	)
	(segment
		(start 166.066724 -237.710472)
		(end 166.92626 -236.850936)
		(width 0.14478)
		(layer "In6.Cu")
		(net "M_K_CPU1_SA_CB<3>")
	)
	(segment
		(start 189.532768 -236.850936)
		(end 189.765178 -236.850936)
		(width 0.14478)
		(layer "In6.Cu")
		(net "M_K_CPU1_SA_CB<3>")
	)
	(segment
		(start 144.988534 -245.841266)
		(end 145.106136 -245.864634)
		(width 0.0889)
		(layer "In6.Cu")
		(net "M_K_CPU1_SA_CB<3>")
	)
	(segment
		(start 180.78069 -237.710472)
		(end 181.140862 -237.710472)
		(width 0.14478)
		(layer "In6.Cu")
		(net "M_K_CPU1_SA_CB<3>")
	)
	(segment
		(start 173.136306 -237.547404)
		(end 173.299374 -237.710472)
		(width 0.14478)
		(layer "In6.Cu")
		(net "M_K_CPU1_SA_CB<3>")
	)
	(segment
		(start 194.17919 -236.860334)
		(end 194.604132 -237.285276)
		(width 0.14478)
		(layer "In6.Cu")
		(net "M_K_CPU1_SA_CB<3>")
	)
	(segment
		(start 180.617622 -237.492032)
		(end 180.617622 -237.547404)
		(width 0.14478)
		(layer "In6.Cu")
		(net "M_K_CPU1_SA_CB<3>")
	)
	(segment
		(start 172.579792 -237.486952)
		(end 172.74286 -237.323884)
		(width 0.14478)
		(layer "In6.Cu")
		(net "M_K_CPU1_SA_CB<3>")
	)
	(segment
		(start 191.979042 -236.630972)
		(end 192.14211 -236.467904)
		(width 0.14478)
		(layer "In6.Cu")
		(net "M_K_CPU1_SA_CB<3>")
	)
	(segment
		(start 192.14211 -236.467904)
		(end 192.372488 -236.467904)
		(width 0.14478)
		(layer "In6.Cu")
		(net "M_K_CPU1_SA_CB<3>")
	)
	(segment
		(start 190.461392 -236.623606)
		(end 190.461392 -236.706156)
		(width 0.14478)
		(layer "In6.Cu")
		(net "M_K_CPU1_SA_CB<3>")
	)
	(segment
		(start 156.554932 -245.360444)
		(end 164.204904 -237.710472)
		(width 0.14478)
		(layer "In6.Cu")
		(net "M_K_CPU1_SA_CB<3>")
	)
	(segment
		(start 182.783226 -236.467904)
		(end 182.946294 -236.630972)
		(width 0.14478)
		(layer "In6.Cu")
		(net "M_K_CPU1_SA_CB<3>")
	)
	(segment
		(start 182.38978 -236.630972)
		(end 182.552848 -236.467904)
		(width 0.14478)
		(layer "In6.Cu")
		(net "M_K_CPU1_SA_CB<3>")
	)
	(segment
		(start 188.399674 -237.710472)
		(end 188.673232 -237.710472)
		(width 0.14478)
		(layer "In6.Cu")
		(net "M_K_CPU1_SA_CB<3>")
	)
	(segment
		(start 193.559938 -237.408466)
		(end 193.723006 -237.245398)
		(width 0.14478)
		(layer "In6.Cu")
		(net "M_K_CPU1_SA_CB<3>")
	)
	(segment
		(start 141.667738 -245.78183)
		(end 141.67612 -245.777004)
		(width 0.0889)
		(layer "In6.Cu")
		(net "M_K_CPU1_SA_CB<3>")
	)
	(segment
		(start 147.225258 -245.864634)
		(end 147.729448 -245.360444)
		(width 0.0889)
		(layer "In6.Cu")
		(net "M_K_CPU1_SA_CB<3>")
	)
	(arc
		(start 143.932148 -245.787926)
		(mid 144.21058 -245.858024)
		(end 144.487392 -245.78183)
		(width 0.0889)
		(layer "In6.Cu")
		(net "M_K_CPU1_SA_CB<3>")
	)
	(arc
		(start 144.495774 -245.777004)
		(mid 144.679282 -245.73151)
		(end 144.861534 -245.78183)
		(width 0.0889)
		(layer "In6.Cu")
		(net "M_K_CPU1_SA_CB<3>")
	)
	(arc
		(start 141.164818 -245.81358)
		(mid 141.420026 -245.857057)
		(end 141.667738 -245.78183)
		(width 0.0889)
		(layer "In6.Cu")
		(net "M_K_CPU1_SA_CB<3>")
	)
	(arc
		(start 142.607792 -245.78183)
		(mid 142.794736 -245.731575)
		(end 142.98168 -245.78183)
		(width 0.0889)
		(layer "In6.Cu")
		(net "M_K_CPU1_SA_CB<3>")
	)
	(arc
		(start 142.04188 -245.78183)
		(mid 142.324836 -245.858007)
		(end 142.607792 -245.78183)
		(width 0.0889)
		(layer "In6.Cu")
		(net "M_K_CPU1_SA_CB<3>")
	)
	(arc
		(start 142.98168 -245.78183)
		(mid 143.264636 -245.858007)
		(end 143.547592 -245.78183)
		(width 0.0889)
		(layer "In6.Cu")
		(net "M_K_CPU1_SA_CB<3>")
	)
	(arc
		(start 141.67612 -245.777004)
		(mid 141.859628 -245.73151)
		(end 142.04188 -245.78183)
		(width 0.0889)
		(layer "In6.Cu")
		(net "M_K_CPU1_SA_CB<3>")
	)
	(arc
		(start 143.547592 -245.78183)
		(mid 143.729843 -245.73148)
		(end 143.913352 -245.777004)
		(width 0.0889)
		(layer "In6.Cu")
		(net "M_K_CPU1_SA_CB<3>")
	)
	(segment
		(start 141.857984 -245.560342)
		(end 142.324836 -245.294404)
		(width 0.10668)
		(layer "F.Cu")
		(net "M_K_CPU1_SA_CB<2>")
	)
	(segment
		(start 172.42917 -235.847382)
		(end 172.42917 -235.785152)
		(width 0.14478)
		(layer "In6.Cu")
		(net "M_K_CPU1_SA_CB<2>")
	)
	(segment
		(start 193.096896 -235.380276)
		(end 193.259964 -235.543344)
		(width 0.14478)
		(layer "In6.Cu")
		(net "M_K_CPU1_SA_CB<2>")
	)
	(segment
		(start 147.671028 -244.451124)
		(end 147.935188 -244.451124)
		(width 0.0889)
		(layer "In6.Cu")
		(net "M_K_CPU1_SA_CB<2>")
	)
	(segment
		(start 172.985684 -235.847382)
		(end 173.148752 -236.01045)
		(width 0.14478)
		(layer "In6.Cu")
		(net "M_K_CPU1_SA_CB<2>")
	)
	(segment
		(start 180.435504 -235.627164)
		(end 180.598572 -235.790232)
		(width 0.14478)
		(layer "In6.Cu")
		(net "M_K_CPU1_SA_CB<2>")
	)
	(segment
		(start 191.983868 -235.380276)
		(end 192.146936 -235.543344)
		(width 0.14478)
		(layer "In6.Cu")
		(net "M_K_CPU1_SA_CB<2>")
	)
	(segment
		(start 182.952136 -234.997244)
		(end 183.115204 -235.160312)
		(width 0.14478)
		(layer "In6.Cu")
		(net "M_K_CPU1_SA_CB<2>")
	)
	(segment
		(start 182.232554 -235.160312)
		(end 182.395622 -234.997244)
		(width 0.14478)
		(layer "In6.Cu")
		(net "M_K_CPU1_SA_CB<2>")
	)
	(segment
		(start 192.540382 -234.940348)
		(end 192.70345 -234.77728)
		(width 0.14478)
		(layer "In6.Cu")
		(net "M_K_CPU1_SA_CB<2>")
	)
	(segment
		(start 190.076328 -234.773724)
		(end 190.306706 -234.773724)
		(width 0.14478)
		(layer "In6.Cu")
		(net "M_K_CPU1_SA_CB<2>")
	)
	(segment
		(start 168.50741 -234.997244)
		(end 168.50741 -234.941872)
		(width 0.14478)
		(layer "In6.Cu")
		(net "M_K_CPU1_SA_CB<2>")
	)
	(segment
		(start 174.459392 -235.160312)
		(end 174.7393 -235.160312)
		(width 0.14478)
		(layer "In6.Cu")
		(net "M_K_CPU1_SA_CB<2>")
	)
	(segment
		(start 169.063924 -234.941872)
		(end 169.063924 -234.997244)
		(width 0.14478)
		(layer "In6.Cu")
		(net "M_K_CPU1_SA_CB<2>")
	)
	(segment
		(start 189.91326 -234.997244)
		(end 189.91326 -234.936792)
		(width 0.14478)
		(layer "In6.Cu")
		(net "M_K_CPU1_SA_CB<2>")
	)
	(segment
		(start 193.096896 -234.940348)
		(end 193.096896 -235.380276)
		(width 0.14478)
		(layer "In6.Cu")
		(net "M_K_CPU1_SA_CB<2>")
	)
	(segment
		(start 174.902368 -234.997244)
		(end 174.902368 -234.936792)
		(width 0.14478)
		(layer "In6.Cu")
		(net "M_K_CPU1_SA_CB<2>")
	)
	(segment
		(start 189.52337 -235.160312)
		(end 189.750192 -235.160312)
		(width 0.14478)
		(layer "In6.Cu")
		(net "M_K_CPU1_SA_CB<2>")
	)
	(segment
		(start 174.7393 -235.160312)
		(end 174.902368 -234.997244)
		(width 0.14478)
		(layer "In6.Cu")
		(net "M_K_CPU1_SA_CB<2>")
	)
	(segment
		(start 182.952136 -234.929172)
		(end 182.952136 -234.997244)
		(width 0.14478)
		(layer "In6.Cu")
		(net "M_K_CPU1_SA_CB<2>")
	)
	(segment
		(start 190.306706 -234.773724)
		(end 190.469774 -234.936792)
		(width 0.14478)
		(layer "In6.Cu")
		(net "M_K_CPU1_SA_CB<2>")
	)
	(segment
		(start 190.469774 -234.936792)
		(end 190.469774 -234.997244)
		(width 0.14478)
		(layer "In6.Cu")
		(net "M_K_CPU1_SA_CB<2>")
	)
	(segment
		(start 172.822616 -235.622084)
		(end 172.985684 -235.785152)
		(width 0.14478)
		(layer "In6.Cu")
		(net "M_K_CPU1_SA_CB<2>")
	)
	(segment
		(start 175.065436 -234.773724)
		(end 175.295814 -234.773724)
		(width 0.14478)
		(layer "In6.Cu")
		(net "M_K_CPU1_SA_CB<2>")
	)
	(segment
		(start 182.395622 -234.997244)
		(end 182.395622 -234.929172)
		(width 0.14478)
		(layer "In6.Cu")
		(net "M_K_CPU1_SA_CB<2>")
	)
	(segment
		(start 188.248544 -235.847382)
		(end 188.411612 -236.01045)
		(width 0.14478)
		(layer "In6.Cu")
		(net "M_K_CPU1_SA_CB<2>")
	)
	(segment
		(start 188.673232 -236.01045)
		(end 189.52337 -235.160312)
		(width 0.14478)
		(layer "In6.Cu")
		(net "M_K_CPU1_SA_CB<2>")
	)
	(segment
		(start 168.344342 -235.160312)
		(end 168.50741 -234.997244)
		(width 0.14478)
		(layer "In6.Cu")
		(net "M_K_CPU1_SA_CB<2>")
	)
	(segment
		(start 180.598572 -235.847382)
		(end 180.76164 -236.01045)
		(width 0.14478)
		(layer "In6.Cu")
		(net "M_K_CPU1_SA_CB<2>")
	)
	(segment
		(start 189.750192 -235.160312)
		(end 189.91326 -234.997244)
		(width 0.14478)
		(layer "In6.Cu")
		(net "M_K_CPU1_SA_CB<2>")
	)
	(segment
		(start 193.65341 -235.32338)
		(end 193.816478 -235.160312)
		(width 0.14478)
		(layer "In6.Cu")
		(net "M_K_CPU1_SA_CB<2>")
	)
	(segment
		(start 193.816478 -235.160312)
		(end 194.17919 -235.160312)
		(width 0.14478)
		(layer "In6.Cu")
		(net "M_K_CPU1_SA_CB<2>")
	)
	(segment
		(start 180.205126 -235.627164)
		(end 180.435504 -235.627164)
		(width 0.14478)
		(layer "In6.Cu")
		(net "M_K_CPU1_SA_CB<2>")
	)
	(segment
		(start 172.42917 -235.785152)
		(end 172.592238 -235.622084)
		(width 0.14478)
		(layer "In6.Cu")
		(net "M_K_CPU1_SA_CB<2>")
	)
	(segment
		(start 187.528962 -236.01045)
		(end 187.69203 -235.847382)
		(width 0.14478)
		(layer "In6.Cu")
		(net "M_K_CPU1_SA_CB<2>")
	)
	(segment
		(start 182.395622 -234.929172)
		(end 182.55869 -234.766104)
		(width 0.14478)
		(layer "In6.Cu")
		(net "M_K_CPU1_SA_CB<2>")
	)
	(segment
		(start 143.077692 -244.971824)
		(end 143.086074 -244.966998)
		(width 0.0889)
		(layer "In6.Cu")
		(net "M_K_CPU1_SA_CB<2>")
	)
	(segment
		(start 173.148752 -236.01045)
		(end 173.609254 -236.01045)
		(width 0.14478)
		(layer "In6.Cu")
		(net "M_K_CPU1_SA_CB<2>")
	)
	(segment
		(start 170.758104 -236.01045)
		(end 172.266102 -236.01045)
		(width 0.14478)
		(layer "In6.Cu")
		(net "M_K_CPU1_SA_CB<2>")
	)
	(segment
		(start 169.226992 -235.160312)
		(end 169.907966 -235.160312)
		(width 0.14478)
		(layer "In6.Cu")
		(net "M_K_CPU1_SA_CB<2>")
	)
	(segment
		(start 166.916862 -235.160312)
		(end 168.344342 -235.160312)
		(width 0.14478)
		(layer "In6.Cu")
		(net "M_K_CPU1_SA_CB<2>")
	)
	(segment
		(start 144.007078 -244.97792)
		(end 144.017492 -244.971824)
		(width 0.0889)
		(layer "In6.Cu")
		(net "M_K_CPU1_SA_CB<2>")
	)
	(segment
		(start 147.935188 -244.451124)
		(end 156.177996 -244.451124)
		(width 0.14478)
		(layer "In6.Cu")
		(net "M_K_CPU1_SA_CB<2>")
	)
	(segment
		(start 187.69203 -235.847382)
		(end 187.69203 -235.785152)
		(width 0.14478)
		(layer "In6.Cu")
		(net "M_K_CPU1_SA_CB<2>")
	)
	(segment
		(start 193.490342 -235.543344)
		(end 193.65341 -235.380276)
		(width 0.14478)
		(layer "In6.Cu")
		(net "M_K_CPU1_SA_CB<2>")
	)
	(segment
		(start 193.259964 -235.543344)
		(end 193.490342 -235.543344)
		(width 0.14478)
		(layer "In6.Cu")
		(net "M_K_CPU1_SA_CB<2>")
	)
	(segment
		(start 163.95573 -236.67339)
		(end 163.95573 -236.247686)
		(width 0.14478)
		(layer "In6.Cu")
		(net "M_K_CPU1_SA_CB<2>")
	)
	(segment
		(start 169.907966 -235.160312)
		(end 170.758104 -236.01045)
		(width 0.14478)
		(layer "In6.Cu")
		(net "M_K_CPU1_SA_CB<2>")
	)
	(segment
		(start 179.87899 -236.01045)
		(end 180.042058 -235.847382)
		(width 0.14478)
		(layer "In6.Cu")
		(net "M_K_CPU1_SA_CB<2>")
	)
	(segment
		(start 172.592238 -235.622084)
		(end 172.822616 -235.622084)
		(width 0.14478)
		(layer "In6.Cu")
		(net "M_K_CPU1_SA_CB<2>")
	)
	(segment
		(start 192.146936 -235.543344)
		(end 192.377314 -235.543344)
		(width 0.14478)
		(layer "In6.Cu")
		(net "M_K_CPU1_SA_CB<2>")
	)
	(segment
		(start 191.8208 -235.160312)
		(end 191.983868 -235.32338)
		(width 0.14478)
		(layer "In6.Cu")
		(net "M_K_CPU1_SA_CB<2>")
	)
	(segment
		(start 180.042058 -235.790232)
		(end 180.205126 -235.627164)
		(width 0.14478)
		(layer "In6.Cu")
		(net "M_K_CPU1_SA_CB<2>")
	)
	(segment
		(start 177.45202 -235.160312)
		(end 178.302158 -236.01045)
		(width 0.14478)
		(layer "In6.Cu")
		(net "M_K_CPU1_SA_CB<2>")
	)
	(segment
		(start 146.888708 -245.233444)
		(end 147.671028 -244.451124)
		(width 0.0889)
		(layer "In6.Cu")
		(net "M_K_CPU1_SA_CB<2>")
	)
	(segment
		(start 192.933828 -234.77728)
		(end 193.096896 -234.940348)
		(width 0.14478)
		(layer "In6.Cu")
		(net "M_K_CPU1_SA_CB<2>")
	)
	(segment
		(start 172.985684 -235.785152)
		(end 172.985684 -235.847382)
		(width 0.14478)
		(layer "In6.Cu")
		(net "M_K_CPU1_SA_CB<2>")
	)
	(segment
		(start 168.900856 -234.778804)
		(end 169.063924 -234.941872)
		(width 0.14478)
		(layer "In6.Cu")
		(net "M_K_CPU1_SA_CB<2>")
	)
	(segment
		(start 194.17919 -235.160312)
		(end 194.604132 -235.585254)
		(width 0.14478)
		(layer "In6.Cu")
		(net "M_K_CPU1_SA_CB<2>")
	)
	(segment
		(start 187.855098 -235.622084)
		(end 188.085476 -235.622084)
		(width 0.14478)
		(layer "In6.Cu")
		(net "M_K_CPU1_SA_CB<2>")
	)
	(segment
		(start 175.62195 -235.160312)
		(end 177.45202 -235.160312)
		(width 0.14478)
		(layer "In6.Cu")
		(net "M_K_CPU1_SA_CB<2>")
	)
	(segment
		(start 180.042058 -235.847382)
		(end 180.042058 -235.790232)
		(width 0.14478)
		(layer "In6.Cu")
		(net "M_K_CPU1_SA_CB<2>")
	)
	(segment
		(start 145.590006 -245.034054)
		(end 146.209766 -245.034054)
		(width 0.0889)
		(layer "In6.Cu")
		(net "M_K_CPU1_SA_CB<2>")
	)
	(segment
		(start 180.76164 -236.01045)
		(end 181.140862 -236.01045)
		(width 0.14478)
		(layer "In6.Cu")
		(net "M_K_CPU1_SA_CB<2>")
	)
	(segment
		(start 192.540382 -235.380276)
		(end 192.540382 -234.940348)
		(width 0.14478)
		(layer "In6.Cu")
		(net "M_K_CPU1_SA_CB<2>")
	)
	(segment
		(start 173.609254 -236.01045)
		(end 174.459392 -235.160312)
		(width 0.14478)
		(layer "In6.Cu")
		(net "M_K_CPU1_SA_CB<2>")
	)
	(segment
		(start 181.991 -235.160312)
		(end 182.232554 -235.160312)
		(width 0.14478)
		(layer "In6.Cu")
		(net "M_K_CPU1_SA_CB<2>")
	)
	(segment
		(start 174.902368 -234.936792)
		(end 175.065436 -234.773724)
		(width 0.14478)
		(layer "In6.Cu")
		(net "M_K_CPU1_SA_CB<2>")
	)
	(segment
		(start 192.70345 -234.77728)
		(end 192.933828 -234.77728)
		(width 0.14478)
		(layer "In6.Cu")
		(net "M_K_CPU1_SA_CB<2>")
	)
	(segment
		(start 181.140862 -236.01045)
		(end 181.991 -235.160312)
		(width 0.14478)
		(layer "In6.Cu")
		(net "M_K_CPU1_SA_CB<2>")
	)
	(segment
		(start 180.598572 -235.790232)
		(end 180.598572 -235.847382)
		(width 0.14478)
		(layer "In6.Cu")
		(net "M_K_CPU1_SA_CB<2>")
	)
	(segment
		(start 156.177996 -244.451124)
		(end 163.95573 -236.67339)
		(width 0.14478)
		(layer "In6.Cu")
		(net "M_K_CPU1_SA_CB<2>")
	)
	(segment
		(start 168.50741 -234.941872)
		(end 168.670478 -234.778804)
		(width 0.14478)
		(layer "In6.Cu")
		(net "M_K_CPU1_SA_CB<2>")
	)
	(segment
		(start 188.248544 -235.785152)
		(end 188.248544 -235.847382)
		(width 0.14478)
		(layer "In6.Cu")
		(net "M_K_CPU1_SA_CB<2>")
	)
	(segment
		(start 182.55869 -234.766104)
		(end 182.789068 -234.766104)
		(width 0.14478)
		(layer "In6.Cu")
		(net "M_K_CPU1_SA_CB<2>")
	)
	(segment
		(start 182.789068 -234.766104)
		(end 182.952136 -234.929172)
		(width 0.14478)
		(layer "In6.Cu")
		(net "M_K_CPU1_SA_CB<2>")
	)
	(segment
		(start 190.632842 -235.160312)
		(end 191.8208 -235.160312)
		(width 0.14478)
		(layer "In6.Cu")
		(net "M_K_CPU1_SA_CB<2>")
	)
	(segment
		(start 189.91326 -234.936792)
		(end 190.076328 -234.773724)
		(width 0.14478)
		(layer "In6.Cu")
		(net "M_K_CPU1_SA_CB<2>")
	)
	(segment
		(start 146.209766 -245.034054)
		(end 146.409156 -245.233444)
		(width 0.0889)
		(layer "In6.Cu")
		(net "M_K_CPU1_SA_CB<2>")
	)
	(segment
		(start 169.063924 -234.997244)
		(end 169.226992 -235.160312)
		(width 0.14478)
		(layer "In6.Cu")
		(net "M_K_CPU1_SA_CB<2>")
	)
	(segment
		(start 188.085476 -235.622084)
		(end 188.248544 -235.785152)
		(width 0.14478)
		(layer "In6.Cu")
		(net "M_K_CPU1_SA_CB<2>")
	)
	(segment
		(start 175.295814 -234.773724)
		(end 175.458882 -234.936792)
		(width 0.14478)
		(layer "In6.Cu")
		(net "M_K_CPU1_SA_CB<2>")
	)
	(segment
		(start 146.409156 -245.233444)
		(end 146.888708 -245.233444)
		(width 0.0889)
		(layer "In6.Cu")
		(net "M_K_CPU1_SA_CB<2>")
	)
	(segment
		(start 187.69203 -235.785152)
		(end 187.855098 -235.622084)
		(width 0.14478)
		(layer "In6.Cu")
		(net "M_K_CPU1_SA_CB<2>")
	)
	(segment
		(start 168.670478 -234.778804)
		(end 168.900856 -234.778804)
		(width 0.14478)
		(layer "In6.Cu")
		(net "M_K_CPU1_SA_CB<2>")
	)
	(segment
		(start 184.99582 -235.160312)
		(end 185.845958 -236.01045)
		(width 0.14478)
		(layer "In6.Cu")
		(net "M_K_CPU1_SA_CB<2>")
	)
	(segment
		(start 175.458882 -234.936792)
		(end 175.458882 -234.997244)
		(width 0.14478)
		(layer "In6.Cu")
		(net "M_K_CPU1_SA_CB<2>")
	)
	(segment
		(start 188.411612 -236.01045)
		(end 188.673232 -236.01045)
		(width 0.14478)
		(layer "In6.Cu")
		(net "M_K_CPU1_SA_CB<2>")
	)
	(segment
		(start 144.39138 -244.971824)
		(end 144.401794 -244.97792)
		(width 0.0889)
		(layer "In6.Cu")
		(net "M_K_CPU1_SA_CB<2>")
	)
	(segment
		(start 142.324836 -245.294404)
		(end 142.47876 -245.028974)
		(width 0.0889)
		(layer "In6.Cu")
		(net "M_K_CPU1_SA_CB<2>")
	)
	(segment
		(start 172.266102 -236.01045)
		(end 172.42917 -235.847382)
		(width 0.14478)
		(layer "In6.Cu")
		(net "M_K_CPU1_SA_CB<2>")
	)
	(segment
		(start 191.983868 -235.32338)
		(end 191.983868 -235.380276)
		(width 0.14478)
		(layer "In6.Cu")
		(net "M_K_CPU1_SA_CB<2>")
	)
	(segment
		(start 142.47876 -245.028974)
		(end 142.574772 -245.003574)
		(width 0.0889)
		(layer "In6.Cu")
		(net "M_K_CPU1_SA_CB<2>")
	)
	(segment
		(start 163.95573 -236.247686)
		(end 164.192966 -236.01045)
		(width 0.14478)
		(layer "In6.Cu")
		(net "M_K_CPU1_SA_CB<2>")
	)
	(segment
		(start 175.458882 -234.997244)
		(end 175.62195 -235.160312)
		(width 0.14478)
		(layer "In6.Cu")
		(net "M_K_CPU1_SA_CB<2>")
	)
	(segment
		(start 192.377314 -235.543344)
		(end 192.540382 -235.380276)
		(width 0.14478)
		(layer "In6.Cu")
		(net "M_K_CPU1_SA_CB<2>")
	)
	(segment
		(start 178.302158 -236.01045)
		(end 179.87899 -236.01045)
		(width 0.14478)
		(layer "In6.Cu")
		(net "M_K_CPU1_SA_CB<2>")
	)
	(segment
		(start 185.845958 -236.01045)
		(end 187.528962 -236.01045)
		(width 0.14478)
		(layer "In6.Cu")
		(net "M_K_CPU1_SA_CB<2>")
	)
	(segment
		(start 166.066724 -236.01045)
		(end 166.916862 -235.160312)
		(width 0.14478)
		(layer "In6.Cu")
		(net "M_K_CPU1_SA_CB<2>")
	)
	(segment
		(start 183.115204 -235.160312)
		(end 184.99582 -235.160312)
		(width 0.14478)
		(layer "In6.Cu")
		(net "M_K_CPU1_SA_CB<2>")
	)
	(segment
		(start 164.192966 -236.01045)
		(end 166.066724 -236.01045)
		(width 0.14478)
		(layer "In6.Cu")
		(net "M_K_CPU1_SA_CB<2>")
	)
	(segment
		(start 190.469774 -234.997244)
		(end 190.632842 -235.160312)
		(width 0.14478)
		(layer "In6.Cu")
		(net "M_K_CPU1_SA_CB<2>")
	)
	(segment
		(start 193.65341 -235.380276)
		(end 193.65341 -235.32338)
		(width 0.14478)
		(layer "In6.Cu")
		(net "M_K_CPU1_SA_CB<2>")
	)
	(arc
		(start 144.017492 -244.971824)
		(mid 144.204436 -244.921569)
		(end 144.39138 -244.971824)
		(width 0.0889)
		(layer "In6.Cu")
		(net "M_K_CPU1_SA_CB<2>")
	)
	(arc
		(start 144.957546 -244.971824)
		(mid 145.137751 -244.921507)
		(end 145.31975 -244.964966)
		(width 0.0889)
		(layer "In6.Cu")
		(net "M_K_CPU1_SA_CB<2>")
	)
	(arc
		(start 144.401794 -244.97792)
		(mid 144.68048 -245.04814)
		(end 144.957546 -244.971824)
		(width 0.0889)
		(layer "In6.Cu")
		(net "M_K_CPU1_SA_CB<2>")
	)
	(arc
		(start 142.574772 -245.003574)
		(mid 142.82998 -245.047051)
		(end 143.077692 -244.971824)
		(width 0.0889)
		(layer "In6.Cu")
		(net "M_K_CPU1_SA_CB<2>")
	)
	(arc
		(start 145.31975 -244.964966)
		(mid 145.45054 -245.016477)
		(end 145.590006 -245.034054)
		(width 0.0889)
		(layer "In6.Cu")
		(net "M_K_CPU1_SA_CB<2>")
	)
	(arc
		(start 143.451834 -244.971824)
		(mid 143.728647 -245.047967)
		(end 144.007078 -244.97792)
		(width 0.0889)
		(layer "In6.Cu")
		(net "M_K_CPU1_SA_CB<2>")
	)
	(arc
		(start 143.086074 -244.966998)
		(mid 143.269582 -244.921504)
		(end 143.451834 -244.971824)
		(width 0.0889)
		(layer "In6.Cu")
		(net "M_K_CPU1_SA_CB<2>")
	)
	(segment
		(start 140.91793 -245.560342)
		(end 141.384782 -245.294404)
		(width 0.10668)
		(layer "F.Cu")
		(net "M_K_CPU1_SA_CB<1>")
	)
	(segment
		(start 181.140862 -236.860334)
		(end 181.990746 -236.01045)
		(width 0.14478)
		(layer "In6.Cu")
		(net "M_K_CPU1_SA_CB<1>")
	)
	(segment
		(start 189.651132 -236.01045)
		(end 198.279258 -236.01045)
		(width 0.14478)
		(layer "In6.Cu")
		(net "M_K_CPU1_SA_CB<1>")
	)
	(segment
		(start 144.39138 -245.616984)
		(end 144.401794 -245.610888)
		(width 0.0889)
		(layer "In6.Cu")
		(net "M_K_CPU1_SA_CB<1>")
	)
	(segment
		(start 171.159424 -236.860334)
		(end 172.762418 -236.860334)
		(width 0.14478)
		(layer "In6.Cu")
		(net "M_K_CPU1_SA_CB<1>")
	)
	(segment
		(start 167.29202 -236.010196)
		(end 169.10685 -236.010196)
		(width 0.14478)
		(layer "In6.Cu")
		(net "M_K_CPU1_SA_CB<1>")
	)
	(segment
		(start 144.007078 -245.610888)
		(end 144.017492 -245.616984)
		(width 0.0889)
		(layer "In6.Cu")
		(net "M_K_CPU1_SA_CB<1>")
	)
	(segment
		(start 172.762418 -236.860334)
		(end 174.208186 -236.261402)
		(width 0.14478)
		(layer "In6.Cu")
		(net "M_K_CPU1_SA_CB<1>")
	)
	(segment
		(start 145.31975 -245.623842)
		(end 145.331434 -245.616984)
		(width 0.0889)
		(layer "In6.Cu")
		(net "M_K_CPU1_SA_CB<1>")
	)
	(segment
		(start 141.384782 -245.294404)
		(end 141.230858 -245.559834)
		(width 0.0889)
		(layer "In6.Cu")
		(net "M_K_CPU1_SA_CB<1>")
	)
	(segment
		(start 156.366464 -244.905784)
		(end 164.411914 -236.860334)
		(width 0.14478)
		(layer "In6.Cu")
		(net "M_K_CPU1_SA_CB<1>")
	)
	(segment
		(start 177.452274 -236.01045)
		(end 178.302158 -236.860334)
		(width 0.14478)
		(layer "In6.Cu")
		(net "M_K_CPU1_SA_CB<1>")
	)
	(segment
		(start 145.331434 -245.616984)
		(end 147.013168 -245.616984)
		(width 0.0889)
		(layer "In6.Cu")
		(net "M_K_CPU1_SA_CB<1>")
	)
	(segment
		(start 170.474386 -236.576616)
		(end 171.159424 -236.860334)
		(width 0.14478)
		(layer "In6.Cu")
		(net "M_K_CPU1_SA_CB<1>")
	)
	(segment
		(start 141.230858 -245.559834)
		(end 141.25321 -245.643146)
		(width 0.0889)
		(layer "In6.Cu")
		(net "M_K_CPU1_SA_CB<1>")
	)
	(segment
		(start 147.724368 -244.905784)
		(end 147.917916 -244.905784)
		(width 0.0889)
		(layer "In6.Cu")
		(net "M_K_CPU1_SA_CB<1>")
	)
	(segment
		(start 174.208186 -236.261402)
		(end 174.81423 -236.01045)
		(width 0.14478)
		(layer "In6.Cu")
		(net "M_K_CPU1_SA_CB<1>")
	)
	(segment
		(start 142.503398 -245.62181)
		(end 142.51178 -245.616984)
		(width 0.0889)
		(layer "In6.Cu")
		(net "M_K_CPU1_SA_CB<1>")
	)
	(segment
		(start 178.302158 -236.860334)
		(end 181.140862 -236.860334)
		(width 0.14478)
		(layer "In6.Cu")
		(net "M_K_CPU1_SA_CB<1>")
	)
	(segment
		(start 165.239446 -236.860334)
		(end 167.29202 -236.010196)
		(width 0.14478)
		(layer "In6.Cu")
		(net "M_K_CPU1_SA_CB<1>")
	)
	(segment
		(start 169.10685 -236.010196)
		(end 170.474386 -236.576616)
		(width 0.14478)
		(layer "In6.Cu")
		(net "M_K_CPU1_SA_CB<1>")
	)
	(segment
		(start 184.996074 -236.01045)
		(end 185.845958 -236.860334)
		(width 0.14478)
		(layer "In6.Cu")
		(net "M_K_CPU1_SA_CB<1>")
	)
	(segment
		(start 198.279258 -236.01045)
		(end 198.7042 -236.435392)
		(width 0.14478)
		(layer "In6.Cu")
		(net "M_K_CPU1_SA_CB<1>")
	)
	(segment
		(start 143.077692 -245.616984)
		(end 143.086074 -245.62181)
		(width 0.0889)
		(layer "In6.Cu")
		(net "M_K_CPU1_SA_CB<1>")
	)
	(segment
		(start 147.013168 -245.616984)
		(end 147.724368 -244.905784)
		(width 0.0889)
		(layer "In6.Cu")
		(net "M_K_CPU1_SA_CB<1>")
	)
	(segment
		(start 181.990746 -236.01045)
		(end 184.996074 -236.01045)
		(width 0.14478)
		(layer "In6.Cu")
		(net "M_K_CPU1_SA_CB<1>")
	)
	(segment
		(start 147.917916 -244.905784)
		(end 156.366464 -244.905784)
		(width 0.14478)
		(layer "In6.Cu")
		(net "M_K_CPU1_SA_CB<1>")
	)
	(segment
		(start 164.411914 -236.860334)
		(end 165.239446 -236.860334)
		(width 0.14478)
		(layer "In6.Cu")
		(net "M_K_CPU1_SA_CB<1>")
	)
	(segment
		(start 188.801248 -236.860334)
		(end 189.651132 -236.01045)
		(width 0.14478)
		(layer "In6.Cu")
		(net "M_K_CPU1_SA_CB<1>")
	)
	(segment
		(start 174.81423 -236.01045)
		(end 177.452274 -236.01045)
		(width 0.14478)
		(layer "In6.Cu")
		(net "M_K_CPU1_SA_CB<1>")
	)
	(segment
		(start 185.845958 -236.860334)
		(end 188.801248 -236.860334)
		(width 0.14478)
		(layer "In6.Cu")
		(net "M_K_CPU1_SA_CB<1>")
	)
	(arc
		(start 144.957546 -245.616984)
		(mid 145.137751 -245.667301)
		(end 145.31975 -245.623842)
		(width 0.0889)
		(layer "In6.Cu")
		(net "M_K_CPU1_SA_CB<1>")
	)
	(arc
		(start 143.451834 -245.616984)
		(mid 143.728647 -245.540841)
		(end 144.007078 -245.610888)
		(width 0.0889)
		(layer "In6.Cu")
		(net "M_K_CPU1_SA_CB<1>")
	)
	(arc
		(start 143.086074 -245.62181)
		(mid 143.269582 -245.667304)
		(end 143.451834 -245.616984)
		(width 0.0889)
		(layer "In6.Cu")
		(net "M_K_CPU1_SA_CB<1>")
	)
	(arc
		(start 144.401794 -245.610888)
		(mid 144.68048 -245.540668)
		(end 144.957546 -245.616984)
		(width 0.0889)
		(layer "In6.Cu")
		(net "M_K_CPU1_SA_CB<1>")
	)
	(arc
		(start 142.51178 -245.616984)
		(mid 142.794736 -245.540807)
		(end 143.077692 -245.616984)
		(width 0.0889)
		(layer "In6.Cu")
		(net "M_K_CPU1_SA_CB<1>")
	)
	(arc
		(start 142.137638 -245.616984)
		(mid 142.319889 -245.667334)
		(end 142.503398 -245.62181)
		(width 0.0889)
		(layer "In6.Cu")
		(net "M_K_CPU1_SA_CB<1>")
	)
	(arc
		(start 144.017492 -245.616984)
		(mid 144.204436 -245.667239)
		(end 144.39138 -245.616984)
		(width 0.0889)
		(layer "In6.Cu")
		(net "M_K_CPU1_SA_CB<1>")
	)
	(arc
		(start 141.25321 -245.643146)
		(mid 141.415399 -245.665881)
		(end 141.571726 -245.616984)
		(width 0.0889)
		(layer "In6.Cu")
		(net "M_K_CPU1_SA_CB<1>")
	)
	(arc
		(start 141.571726 -245.616984)
		(mid 141.854682 -245.540807)
		(end 142.137638 -245.616984)
		(width 0.0889)
		(layer "In6.Cu")
		(net "M_K_CPU1_SA_CB<1>")
	)
	(segment
		(start 142.327884 -244.750336)
		(end 142.794736 -244.484398)
		(width 0.10668)
		(layer "F.Cu")
		(net "M_K_CPU1_SA_CB<0>")
	)
	(segment
		(start 147.917916 -243.996464)
		(end 155.989528 -243.996464)
		(width 0.14478)
		(layer "In6.Cu")
		(net "M_K_CPU1_SA_CB<0>")
	)
	(segment
		(start 145.59026 -244.843554)
		(end 145.978118 -244.843554)
		(width 0.0889)
		(layer "In6.Cu")
		(net "M_K_CPU1_SA_CB<0>")
	)
	(segment
		(start 143.921734 -244.806978)
		(end 143.932148 -244.800882)
		(width 0.0889)
		(layer "In6.Cu")
		(net "M_K_CPU1_SA_CB<0>")
	)
	(segment
		(start 142.794736 -244.484398)
		(end 142.640812 -244.749828)
		(width 0.0889)
		(layer "In6.Cu")
		(net "M_K_CPU1_SA_CB<0>")
	)
	(segment
		(start 169.907966 -234.310174)
		(end 170.758104 -235.160312)
		(width 0.14478)
		(layer "In6.Cu")
		(net "M_K_CPU1_SA_CB<0>")
	)
	(segment
		(start 198.279258 -234.310428)
		(end 198.7042 -234.73537)
		(width 0.14478)
		(layer "In6.Cu")
		(net "M_K_CPU1_SA_CB<0>")
	)
	(segment
		(start 188.801248 -235.160312)
		(end 189.651132 -234.310428)
		(width 0.14478)
		(layer "In6.Cu")
		(net "M_K_CPU1_SA_CB<0>")
	)
	(segment
		(start 145.978118 -244.843554)
		(end 146.825208 -243.996464)
		(width 0.0889)
		(layer "In6.Cu")
		(net "M_K_CPU1_SA_CB<0>")
	)
	(segment
		(start 163.47059 -236.039406)
		(end 164.349684 -235.160312)
		(width 0.14478)
		(layer "In6.Cu")
		(net "M_K_CPU1_SA_CB<0>")
	)
	(segment
		(start 163.47059 -236.515402)
		(end 163.47059 -236.039406)
		(width 0.14478)
		(layer "In6.Cu")
		(net "M_K_CPU1_SA_CB<0>")
	)
	(segment
		(start 164.349684 -235.160312)
		(end 166.106348 -235.160312)
		(width 0.14478)
		(layer "In6.Cu")
		(net "M_K_CPU1_SA_CB<0>")
	)
	(segment
		(start 184.996074 -234.310428)
		(end 185.845958 -235.160312)
		(width 0.14478)
		(layer "In6.Cu")
		(net "M_K_CPU1_SA_CB<0>")
	)
	(segment
		(start 173.609254 -235.160312)
		(end 174.459138 -234.310428)
		(width 0.14478)
		(layer "In6.Cu")
		(net "M_K_CPU1_SA_CB<0>")
	)
	(segment
		(start 166.106348 -235.160312)
		(end 166.956486 -234.310174)
		(width 0.14478)
		(layer "In6.Cu")
		(net "M_K_CPU1_SA_CB<0>")
	)
	(segment
		(start 177.452274 -234.310428)
		(end 178.302158 -235.160312)
		(width 0.14478)
		(layer "In6.Cu")
		(net "M_K_CPU1_SA_CB<0>")
	)
	(segment
		(start 142.640812 -244.749828)
		(end 142.663164 -244.83314)
		(width 0.0889)
		(layer "In6.Cu")
		(net "M_K_CPU1_SA_CB<0>")
	)
	(segment
		(start 185.845958 -235.160312)
		(end 188.801248 -235.160312)
		(width 0.14478)
		(layer "In6.Cu")
		(net "M_K_CPU1_SA_CB<0>")
	)
	(segment
		(start 189.651132 -234.310428)
		(end 198.279258 -234.310428)
		(width 0.14478)
		(layer "In6.Cu")
		(net "M_K_CPU1_SA_CB<0>")
	)
	(segment
		(start 181.990746 -234.310428)
		(end 184.996074 -234.310428)
		(width 0.14478)
		(layer "In6.Cu")
		(net "M_K_CPU1_SA_CB<0>")
	)
	(segment
		(start 166.956486 -234.310174)
		(end 169.907966 -234.310174)
		(width 0.14478)
		(layer "In6.Cu")
		(net "M_K_CPU1_SA_CB<0>")
	)
	(segment
		(start 144.487392 -244.806978)
		(end 144.495774 -244.811804)
		(width 0.0889)
		(layer "In6.Cu")
		(net "M_K_CPU1_SA_CB<0>")
	)
	(segment
		(start 181.140862 -235.160312)
		(end 181.990746 -234.310428)
		(width 0.14478)
		(layer "In6.Cu")
		(net "M_K_CPU1_SA_CB<0>")
	)
	(segment
		(start 170.758104 -235.160312)
		(end 173.609254 -235.160312)
		(width 0.14478)
		(layer "In6.Cu")
		(net "M_K_CPU1_SA_CB<0>")
	)
	(segment
		(start 155.989528 -243.996464)
		(end 163.47059 -236.515402)
		(width 0.14478)
		(layer "In6.Cu")
		(net "M_K_CPU1_SA_CB<0>")
	)
	(segment
		(start 146.825208 -243.996464)
		(end 147.917916 -243.996464)
		(width 0.0889)
		(layer "In6.Cu")
		(net "M_K_CPU1_SA_CB<0>")
	)
	(segment
		(start 143.913352 -244.811804)
		(end 143.921734 -244.806978)
		(width 0.0889)
		(layer "In6.Cu")
		(net "M_K_CPU1_SA_CB<0>")
	)
	(segment
		(start 178.302158 -235.160312)
		(end 181.140862 -235.160312)
		(width 0.14478)
		(layer "In6.Cu")
		(net "M_K_CPU1_SA_CB<0>")
	)
	(segment
		(start 174.459138 -234.310428)
		(end 177.452274 -234.310428)
		(width 0.14478)
		(layer "In6.Cu")
		(net "M_K_CPU1_SA_CB<0>")
	)
	(arc
		(start 142.98168 -244.806978)
		(mid 143.264636 -244.730801)
		(end 143.547592 -244.806978)
		(width 0.0889)
		(layer "In6.Cu")
		(net "M_K_CPU1_SA_CB<0>")
	)
	(arc
		(start 143.547592 -244.806978)
		(mid 143.729843 -244.857328)
		(end 143.913352 -244.811804)
		(width 0.0889)
		(layer "In6.Cu")
		(net "M_K_CPU1_SA_CB<0>")
	)
	(arc
		(start 143.932148 -244.800882)
		(mid 144.21058 -244.730784)
		(end 144.487392 -244.806978)
		(width 0.0889)
		(layer "In6.Cu")
		(net "M_K_CPU1_SA_CB<0>")
	)
	(arc
		(start 144.495774 -244.811804)
		(mid 144.679282 -244.857298)
		(end 144.861534 -244.806978)
		(width 0.0889)
		(layer "In6.Cu")
		(net "M_K_CPU1_SA_CB<0>")
	)
	(arc
		(start 144.861534 -244.806978)
		(mid 145.135986 -244.730742)
		(end 145.412714 -244.798342)
		(width 0.0889)
		(layer "In6.Cu")
		(net "M_K_CPU1_SA_CB<0>")
	)
	(arc
		(start 145.412714 -244.798342)
		(mid 145.498672 -244.831997)
		(end 145.59026 -244.843554)
		(width 0.0889)
		(layer "In6.Cu")
		(net "M_K_CPU1_SA_CB<0>")
	)
	(arc
		(start 142.663164 -244.83314)
		(mid 142.825353 -244.855875)
		(end 142.98168 -244.806978)
		(width 0.0889)
		(layer "In6.Cu")
		(net "M_K_CPU1_SA_CB<0>")
	)
	(segment
		(start 140.91793 -255.280414)
		(end 141.384782 -255.014476)
		(width 0.10668)
		(layer "F.Cu")
		(net "M_K_CPU1_SA_CA<6>")
	)
	(segment
		(start 145.313146 -255.347216)
		(end 145.331434 -255.336802)
		(width 0.0889)
		(layer "In6.Cu")
		(net "M_K_CPU1_SA_CA<6>")
	)
	(segment
		(start 194.36715 -252.217428)
		(end 194.373754 -252.217428)
		(width 0.0889)
		(layer "In6.Cu")
		(net "M_K_CPU1_SA_CA<6>")
	)
	(segment
		(start 146.873468 -255.589024)
		(end 147.345908 -256.061464)
		(width 0.0889)
		(layer "In6.Cu")
		(net "M_K_CPU1_SA_CA<6>")
	)
	(segment
		(start 144.017492 -255.337056)
		(end 144.025874 -255.341882)
		(width 0.0889)
		(layer "In6.Cu")
		(net "M_K_CPU1_SA_CA<6>")
	)
	(segment
		(start 194.223894 -252.360684)
		(end 194.36715 -252.217428)
		(width 0.14478)
		(layer "In6.Cu")
		(net "M_K_CPU1_SA_CA<6>")
	)
	(segment
		(start 145.382742 -255.28778)
		(end 146.092164 -255.28778)
		(width 0.0889)
		(layer "In6.Cu")
		(net "M_K_CPU1_SA_CA<6>")
	)
	(segment
		(start 141.230858 -255.279906)
		(end 141.25321 -255.363218)
		(width 0.0889)
		(layer "In6.Cu")
		(net "M_K_CPU1_SA_CA<6>")
	)
	(segment
		(start 194.430904 -252.160278)
		(end 194.789552 -252.160278)
		(width 0.0889)
		(layer "In6.Cu")
		(net "M_K_CPU1_SA_CA<6>")
	)
	(segment
		(start 146.393408 -255.589024)
		(end 146.873468 -255.589024)
		(width 0.0889)
		(layer "In6.Cu")
		(net "M_K_CPU1_SA_CA<6>")
	)
	(segment
		(start 141.384782 -255.014476)
		(end 141.230858 -255.279906)
		(width 0.0889)
		(layer "In6.Cu")
		(net "M_K_CPU1_SA_CA<6>")
	)
	(segment
		(start 142.503398 -255.341882)
		(end 142.51178 -255.337056)
		(width 0.0889)
		(layer "In6.Cu")
		(net "M_K_CPU1_SA_CA<6>")
	)
	(segment
		(start 150.544784 -256.061464)
		(end 151.907494 -254.698754)
		(width 0.14478)
		(layer "In6.Cu")
		(net "M_K_CPU1_SA_CA<6>")
	)
	(segment
		(start 189.941962 -254.71755)
		(end 190.799466 -253.860046)
		(width 0.14478)
		(layer "In6.Cu")
		(net "M_K_CPU1_SA_CA<6>")
	)
	(segment
		(start 147.345908 -256.061464)
		(end 147.882356 -256.061464)
		(width 0.0889)
		(layer "In6.Cu")
		(net "M_K_CPU1_SA_CA<6>")
	)
	(segment
		(start 147.882356 -256.061464)
		(end 150.544784 -256.061464)
		(width 0.14478)
		(layer "In6.Cu")
		(net "M_K_CPU1_SA_CA<6>")
	)
	(segment
		(start 144.007078 -255.33096)
		(end 144.017492 -255.337056)
		(width 0.0889)
		(layer "In6.Cu")
		(net "M_K_CPU1_SA_CA<6>")
	)
	(segment
		(start 146.092164 -255.28778)
		(end 146.393408 -255.589024)
		(width 0.0889)
		(layer "In6.Cu")
		(net "M_K_CPU1_SA_CA<6>")
	)
	(segment
		(start 192.984628 -252.360684)
		(end 194.223894 -252.360684)
		(width 0.14478)
		(layer "In6.Cu")
		(net "M_K_CPU1_SA_CA<6>")
	)
	(segment
		(start 194.373754 -252.217428)
		(end 194.430904 -252.160278)
		(width 0.0889)
		(layer "In6.Cu")
		(net "M_K_CPU1_SA_CA<6>")
	)
	(segment
		(start 143.077692 -255.337056)
		(end 143.086074 -255.341882)
		(width 0.0889)
		(layer "In6.Cu")
		(net "M_K_CPU1_SA_CA<6>")
	)
	(segment
		(start 198.279004 -252.160024)
		(end 198.7042 -252.58522)
		(width 0.14478)
		(layer "In6.Cu")
		(net "M_K_CPU1_SA_CA<6>")
	)
	(segment
		(start 162.842956 -254.71755)
		(end 189.941962 -254.71755)
		(width 0.14478)
		(layer "In6.Cu")
		(net "M_K_CPU1_SA_CA<6>")
	)
	(segment
		(start 145.331434 -255.336802)
		(end 145.337022 -255.3335)
		(width 0.0889)
		(layer "In6.Cu")
		(net "M_K_CPU1_SA_CA<6>")
	)
	(segment
		(start 144.391126 -255.337056)
		(end 144.40154 -255.33096)
		(width 0.0889)
		(layer "In6.Cu")
		(net "M_K_CPU1_SA_CA<6>")
	)
	(segment
		(start 162.82416 -254.698754)
		(end 162.842956 -254.71755)
		(width 0.14478)
		(layer "In6.Cu")
		(net "M_K_CPU1_SA_CA<6>")
	)
	(segment
		(start 151.907494 -254.698754)
		(end 162.82416 -254.698754)
		(width 0.14478)
		(layer "In6.Cu")
		(net "M_K_CPU1_SA_CA<6>")
	)
	(segment
		(start 145.337022 -255.3335)
		(end 145.382742 -255.28778)
		(width 0.0889)
		(layer "In6.Cu")
		(net "M_K_CPU1_SA_CA<6>")
	)
	(segment
		(start 190.799466 -253.860046)
		(end 191.485266 -253.860046)
		(width 0.14478)
		(layer "In6.Cu")
		(net "M_K_CPU1_SA_CA<6>")
	)
	(segment
		(start 194.789552 -252.160278)
		(end 194.789806 -252.160024)
		(width 0.14478)
		(layer "In6.Cu")
		(net "M_K_CPU1_SA_CA<6>")
	)
	(segment
		(start 194.789806 -252.160024)
		(end 198.279004 -252.160024)
		(width 0.14478)
		(layer "In6.Cu")
		(net "M_K_CPU1_SA_CA<6>")
	)
	(segment
		(start 191.485266 -253.860046)
		(end 192.984628 -252.360684)
		(width 0.14478)
		(layer "In6.Cu")
		(net "M_K_CPU1_SA_CA<6>")
	)
	(arc
		(start 142.51178 -255.337056)
		(mid 142.794736 -255.260879)
		(end 143.077692 -255.337056)
		(width 0.0889)
		(layer "In6.Cu")
		(net "M_K_CPU1_SA_CA<6>")
	)
	(arc
		(start 142.137638 -255.337056)
		(mid 142.319889 -255.387406)
		(end 142.503398 -255.341882)
		(width 0.0889)
		(layer "In6.Cu")
		(net "M_K_CPU1_SA_CA<6>")
	)
	(arc
		(start 141.571726 -255.337056)
		(mid 141.854682 -255.260879)
		(end 142.137638 -255.337056)
		(width 0.0889)
		(layer "In6.Cu")
		(net "M_K_CPU1_SA_CA<6>")
	)
	(arc
		(start 143.451834 -255.337056)
		(mid 143.728647 -255.260913)
		(end 144.007078 -255.33096)
		(width 0.0889)
		(layer "In6.Cu")
		(net "M_K_CPU1_SA_CA<6>")
	)
	(arc
		(start 144.957292 -255.337056)
		(mid 145.13392 -255.387289)
		(end 145.313146 -255.347216)
		(width 0.0889)
		(layer "In6.Cu")
		(net "M_K_CPU1_SA_CA<6>")
	)
	(arc
		(start 144.40154 -255.33096)
		(mid 144.680226 -255.26074)
		(end 144.957292 -255.337056)
		(width 0.0889)
		(layer "In6.Cu")
		(net "M_K_CPU1_SA_CA<6>")
	)
	(arc
		(start 144.025874 -255.341882)
		(mid 144.209128 -255.387255)
		(end 144.391126 -255.337056)
		(width 0.0889)
		(layer "In6.Cu")
		(net "M_K_CPU1_SA_CA<6>")
	)
	(arc
		(start 143.086074 -255.341882)
		(mid 143.269582 -255.387376)
		(end 143.451834 -255.337056)
		(width 0.0889)
		(layer "In6.Cu")
		(net "M_K_CPU1_SA_CA<6>")
	)
	(arc
		(start 141.25321 -255.363218)
		(mid 141.415399 -255.385953)
		(end 141.571726 -255.337056)
		(width 0.0889)
		(layer "In6.Cu")
		(net "M_K_CPU1_SA_CA<6>")
	)
	(segment
		(start 141.857984 -255.280414)
		(end 142.324836 -255.014476)
		(width 0.10668)
		(layer "F.Cu")
		(net "M_K_CPU1_SA_CA<5>")
	)
	(segment
		(start 144.007078 -254.697992)
		(end 144.017492 -254.691896)
		(width 0.0889)
		(layer "In6.Cu")
		(net "M_K_CPU1_SA_CA<5>")
	)
	(segment
		(start 170.448224 -253.636272)
		(end 170.448224 -253.697232)
		(width 0.14478)
		(layer "In6.Cu")
		(net "M_K_CPU1_SA_CA<5>")
	)
	(segment
		(start 189.949328 -253.8603)
		(end 190.799466 -253.010162)
		(width 0.14478)
		(layer "In6.Cu")
		(net "M_K_CPU1_SA_CA<5>")
	)
	(segment
		(start 166.886636 -254.255524)
		(end 167.117014 -254.255524)
		(width 0.14478)
		(layer "In6.Cu")
		(net "M_K_CPU1_SA_CA<5>")
	)
	(segment
		(start 167.280082 -254.023368)
		(end 167.44315 -253.8603)
		(width 0.14478)
		(layer "In6.Cu")
		(net "M_K_CPU1_SA_CA<5>")
	)
	(segment
		(start 166.330122 -253.465076)
		(end 166.5605 -253.465076)
		(width 0.14478)
		(layer "In6.Cu")
		(net "M_K_CPU1_SA_CA<5>")
	)
	(segment
		(start 190.799466 -253.010162)
		(end 191.485266 -253.010162)
		(width 0.14478)
		(layer "In6.Cu")
		(net "M_K_CPU1_SA_CA<5>")
	)
	(segment
		(start 170.285156 -253.473204)
		(end 170.448224 -253.636272)
		(width 0.14478)
		(layer "In6.Cu")
		(net "M_K_CPU1_SA_CA<5>")
	)
	(segment
		(start 166.5605 -253.465076)
		(end 166.723568 -253.628144)
		(width 0.14478)
		(layer "In6.Cu")
		(net "M_K_CPU1_SA_CA<5>")
	)
	(segment
		(start 166.723568 -253.628144)
		(end 166.723568 -254.092456)
		(width 0.14478)
		(layer "In6.Cu")
		(net "M_K_CPU1_SA_CA<5>")
	)
	(segment
		(start 169.89171 -253.636272)
		(end 170.054778 -253.473204)
		(width 0.14478)
		(layer "In6.Cu")
		(net "M_K_CPU1_SA_CA<5>")
	)
	(segment
		(start 170.611292 -253.8603)
		(end 189.949328 -253.8603)
		(width 0.14478)
		(layer "In6.Cu")
		(net "M_K_CPU1_SA_CA<5>")
	)
	(segment
		(start 170.448224 -253.697232)
		(end 170.611292 -253.8603)
		(width 0.14478)
		(layer "In6.Cu")
		(net "M_K_CPU1_SA_CA<5>")
	)
	(segment
		(start 151.719026 -254.244094)
		(end 162.910012 -254.244094)
		(width 0.14478)
		(layer "In6.Cu")
		(net "M_K_CPU1_SA_CA<5>")
	)
	(segment
		(start 142.47876 -254.749046)
		(end 142.574772 -254.723646)
		(width 0.0889)
		(layer "In6.Cu")
		(net "M_K_CPU1_SA_CA<5>")
	)
	(segment
		(start 166.003986 -254.255524)
		(end 166.167054 -254.092456)
		(width 0.14478)
		(layer "In6.Cu")
		(net "M_K_CPU1_SA_CA<5>")
	)
	(segment
		(start 143.077692 -254.691896)
		(end 143.086074 -254.68707)
		(width 0.0889)
		(layer "In6.Cu")
		(net "M_K_CPU1_SA_CA<5>")
	)
	(segment
		(start 192.760092 -251.735336)
		(end 194.604132 -251.735336)
		(width 0.14478)
		(layer "In6.Cu")
		(net "M_K_CPU1_SA_CA<5>")
	)
	(segment
		(start 142.324836 -255.014476)
		(end 142.47876 -254.749046)
		(width 0.0889)
		(layer "In6.Cu")
		(net "M_K_CPU1_SA_CA<5>")
	)
	(segment
		(start 167.44315 -253.8603)
		(end 169.728642 -253.8603)
		(width 0.14478)
		(layer "In6.Cu")
		(net "M_K_CPU1_SA_CA<5>")
	)
	(segment
		(start 166.167054 -253.628144)
		(end 166.330122 -253.465076)
		(width 0.14478)
		(layer "In6.Cu")
		(net "M_K_CPU1_SA_CA<5>")
	)
	(segment
		(start 144.39138 -254.691896)
		(end 144.401794 -254.697992)
		(width 0.0889)
		(layer "In6.Cu")
		(net "M_K_CPU1_SA_CA<5>")
	)
	(segment
		(start 165.61054 -254.023368)
		(end 165.61054 -254.092456)
		(width 0.14478)
		(layer "In6.Cu")
		(net "M_K_CPU1_SA_CA<5>")
	)
	(segment
		(start 165.447472 -253.8603)
		(end 165.61054 -254.023368)
		(width 0.14478)
		(layer "In6.Cu")
		(net "M_K_CPU1_SA_CA<5>")
	)
	(segment
		(start 145.669762 -254.774446)
		(end 146.05762 -254.774446)
		(width 0.0889)
		(layer "In6.Cu")
		(net "M_K_CPU1_SA_CA<5>")
	)
	(segment
		(start 167.280082 -254.092456)
		(end 167.280082 -254.023368)
		(width 0.14478)
		(layer "In6.Cu")
		(net "M_K_CPU1_SA_CA<5>")
	)
	(segment
		(start 150.386796 -255.576324)
		(end 151.719026 -254.244094)
		(width 0.14478)
		(layer "In6.Cu")
		(net "M_K_CPU1_SA_CA<5>")
	)
	(segment
		(start 146.909028 -255.098804)
		(end 147.386548 -255.576324)
		(width 0.0889)
		(layer "In6.Cu")
		(net "M_K_CPU1_SA_CA<5>")
	)
	(segment
		(start 162.910012 -254.244094)
		(end 163.293806 -253.8603)
		(width 0.14478)
		(layer "In6.Cu")
		(net "M_K_CPU1_SA_CA<5>")
	)
	(segment
		(start 170.054778 -253.473204)
		(end 170.285156 -253.473204)
		(width 0.14478)
		(layer "In6.Cu")
		(net "M_K_CPU1_SA_CA<5>")
	)
	(segment
		(start 147.386548 -255.576324)
		(end 147.859496 -255.576324)
		(width 0.0889)
		(layer "In6.Cu")
		(net "M_K_CPU1_SA_CA<5>")
	)
	(segment
		(start 147.859496 -255.576324)
		(end 150.386796 -255.576324)
		(width 0.14478)
		(layer "In6.Cu")
		(net "M_K_CPU1_SA_CA<5>")
	)
	(segment
		(start 163.293806 -253.8603)
		(end 165.447472 -253.8603)
		(width 0.14478)
		(layer "In6.Cu")
		(net "M_K_CPU1_SA_CA<5>")
	)
	(segment
		(start 169.728642 -253.8603)
		(end 169.89171 -253.697232)
		(width 0.14478)
		(layer "In6.Cu")
		(net "M_K_CPU1_SA_CA<5>")
	)
	(segment
		(start 165.61054 -254.092456)
		(end 165.773608 -254.255524)
		(width 0.14478)
		(layer "In6.Cu")
		(net "M_K_CPU1_SA_CA<5>")
	)
	(segment
		(start 167.117014 -254.255524)
		(end 167.280082 -254.092456)
		(width 0.14478)
		(layer "In6.Cu")
		(net "M_K_CPU1_SA_CA<5>")
	)
	(segment
		(start 169.89171 -253.697232)
		(end 169.89171 -253.636272)
		(width 0.14478)
		(layer "In6.Cu")
		(net "M_K_CPU1_SA_CA<5>")
	)
	(segment
		(start 165.773608 -254.255524)
		(end 166.003986 -254.255524)
		(width 0.14478)
		(layer "In6.Cu")
		(net "M_K_CPU1_SA_CA<5>")
	)
	(segment
		(start 146.428968 -255.098804)
		(end 146.909028 -255.098804)
		(width 0.0889)
		(layer "In6.Cu")
		(net "M_K_CPU1_SA_CA<5>")
	)
	(segment
		(start 166.723568 -254.092456)
		(end 166.886636 -254.255524)
		(width 0.14478)
		(layer "In6.Cu")
		(net "M_K_CPU1_SA_CA<5>")
	)
	(segment
		(start 166.167054 -254.092456)
		(end 166.167054 -253.628144)
		(width 0.14478)
		(layer "In6.Cu")
		(net "M_K_CPU1_SA_CA<5>")
	)
	(segment
		(start 191.485266 -253.010162)
		(end 192.760092 -251.735336)
		(width 0.14478)
		(layer "In6.Cu")
		(net "M_K_CPU1_SA_CA<5>")
	)
	(segment
		(start 146.137884 -254.80772)
		(end 146.428968 -255.098804)
		(width 0.0889)
		(layer "In6.Cu")
		(net "M_K_CPU1_SA_CA<5>")
	)
	(arc
		(start 145.31975 -254.685038)
		(mid 145.489139 -254.751724)
		(end 145.669762 -254.774446)
		(width 0.0889)
		(layer "In6.Cu")
		(net "M_K_CPU1_SA_CA<5>")
	)
	(arc
		(start 144.401794 -254.697992)
		(mid 144.68048 -254.768212)
		(end 144.957546 -254.691896)
		(width 0.0889)
		(layer "In6.Cu")
		(net "M_K_CPU1_SA_CA<5>")
	)
	(arc
		(start 144.017492 -254.691896)
		(mid 144.204436 -254.641641)
		(end 144.39138 -254.691896)
		(width 0.0889)
		(layer "In6.Cu")
		(net "M_K_CPU1_SA_CA<5>")
	)
	(arc
		(start 144.957546 -254.691896)
		(mid 145.137751 -254.641579)
		(end 145.31975 -254.685038)
		(width 0.0889)
		(layer "In6.Cu")
		(net "M_K_CPU1_SA_CA<5>")
	)
	(arc
		(start 143.451834 -254.691896)
		(mid 143.728647 -254.768039)
		(end 144.007078 -254.697992)
		(width 0.0889)
		(layer "In6.Cu")
		(net "M_K_CPU1_SA_CA<5>")
	)
	(arc
		(start 146.05762 -254.774446)
		(mid 146.101055 -254.783104)
		(end 146.137884 -254.80772)
		(width 0.0889)
		(layer "In6.Cu")
		(net "M_K_CPU1_SA_CA<5>")
	)
	(arc
		(start 142.574772 -254.723646)
		(mid 142.82998 -254.767123)
		(end 143.077692 -254.691896)
		(width 0.0889)
		(layer "In6.Cu")
		(net "M_K_CPU1_SA_CA<5>")
	)
	(arc
		(start 143.086074 -254.68707)
		(mid 143.269582 -254.641576)
		(end 143.451834 -254.691896)
		(width 0.0889)
		(layer "In6.Cu")
		(net "M_K_CPU1_SA_CA<5>")
	)
	(segment
		(start 142.327884 -254.470408)
		(end 142.794736 -254.20447)
		(width 0.10668)
		(layer "F.Cu")
		(net "M_K_CPU1_SA_CA<4>")
	)
	(segment
		(start 143.913352 -254.531876)
		(end 143.921734 -254.52705)
		(width 0.0889)
		(layer "In6.Cu")
		(net "M_K_CPU1_SA_CA<4>")
	)
	(segment
		(start 194.195446 -251.088144)
		(end 194.198748 -251.084842)
		(width 0.14478)
		(layer "In6.Cu")
		(net "M_K_CPU1_SA_CA<4>")
	)
	(segment
		(start 189.949328 -253.010162)
		(end 190.799466 -252.160024)
		(width 0.14478)
		(layer "In6.Cu")
		(net "M_K_CPU1_SA_CA<4>")
	)
	(segment
		(start 142.794736 -254.20447)
		(end 142.640812 -254.4699)
		(width 0.0889)
		(layer "In6.Cu")
		(net "M_K_CPU1_SA_CA<4>")
	)
	(segment
		(start 147.381468 -255.121664)
		(end 147.893786 -255.121664)
		(width 0.0889)
		(layer "In6.Cu")
		(net "M_K_CPU1_SA_CA<4>")
	)
	(segment
		(start 151.530558 -253.789434)
		(end 162.648392 -253.789434)
		(width 0.14478)
		(layer "In6.Cu")
		(net "M_K_CPU1_SA_CA<4>")
	)
	(segment
		(start 147.114768 -254.854964)
		(end 147.381468 -255.121664)
		(width 0.0889)
		(layer "In6.Cu")
		(net "M_K_CPU1_SA_CA<4>")
	)
	(segment
		(start 190.799466 -252.160024)
		(end 191.485266 -252.160024)
		(width 0.14478)
		(layer "In6.Cu")
		(net "M_K_CPU1_SA_CA<4>")
	)
	(segment
		(start 145.59026 -254.563626)
		(end 146.24431 -254.563626)
		(width 0.0889)
		(layer "In6.Cu")
		(net "M_K_CPU1_SA_CA<4>")
	)
	(segment
		(start 142.640812 -254.4699)
		(end 142.663164 -254.553212)
		(width 0.0889)
		(layer "In6.Cu")
		(net "M_K_CPU1_SA_CA<4>")
	)
	(segment
		(start 162.648392 -253.789434)
		(end 163.427664 -253.010162)
		(width 0.14478)
		(layer "In6.Cu")
		(net "M_K_CPU1_SA_CA<4>")
	)
	(segment
		(start 191.485266 -252.160024)
		(end 192.557146 -251.088144)
		(width 0.14478)
		(layer "In6.Cu")
		(net "M_K_CPU1_SA_CA<4>")
	)
	(segment
		(start 147.893786 -255.121664)
		(end 150.198328 -255.121664)
		(width 0.14478)
		(layer "In6.Cu")
		(net "M_K_CPU1_SA_CA<4>")
	)
	(segment
		(start 194.198748 -251.084842)
		(end 194.36715 -251.253244)
		(width 0.14478)
		(layer "In6.Cu")
		(net "M_K_CPU1_SA_CA<4>")
	)
	(segment
		(start 146.535648 -254.854964)
		(end 147.114768 -254.854964)
		(width 0.0889)
		(layer "In6.Cu")
		(net "M_K_CPU1_SA_CA<4>")
	)
	(segment
		(start 194.789806 -251.31014)
		(end 198.279258 -251.31014)
		(width 0.14478)
		(layer "In6.Cu")
		(net "M_K_CPU1_SA_CA<4>")
	)
	(segment
		(start 143.921734 -254.52705)
		(end 143.932148 -254.520954)
		(width 0.0889)
		(layer "In6.Cu")
		(net "M_K_CPU1_SA_CA<4>")
	)
	(segment
		(start 150.198328 -255.121664)
		(end 151.530558 -253.789434)
		(width 0.14478)
		(layer "In6.Cu")
		(net "M_K_CPU1_SA_CA<4>")
	)
	(segment
		(start 192.557146 -251.088144)
		(end 194.195446 -251.088144)
		(width 0.14478)
		(layer "In6.Cu")
		(net "M_K_CPU1_SA_CA<4>")
	)
	(segment
		(start 144.487392 -254.52705)
		(end 144.495774 -254.531876)
		(width 0.0889)
		(layer "In6.Cu")
		(net "M_K_CPU1_SA_CA<4>")
	)
	(segment
		(start 194.373754 -251.253244)
		(end 194.430904 -251.310394)
		(width 0.0889)
		(layer "In6.Cu")
		(net "M_K_CPU1_SA_CA<4>")
	)
	(segment
		(start 146.24431 -254.563626)
		(end 146.535648 -254.854964)
		(width 0.0889)
		(layer "In6.Cu")
		(net "M_K_CPU1_SA_CA<4>")
	)
	(segment
		(start 194.789552 -251.310394)
		(end 194.789806 -251.31014)
		(width 0.14478)
		(layer "In6.Cu")
		(net "M_K_CPU1_SA_CA<4>")
	)
	(segment
		(start 194.430904 -251.310394)
		(end 194.789552 -251.310394)
		(width 0.0889)
		(layer "In6.Cu")
		(net "M_K_CPU1_SA_CA<4>")
	)
	(segment
		(start 194.36715 -251.253244)
		(end 194.373754 -251.253244)
		(width 0.0889)
		(layer "In6.Cu")
		(net "M_K_CPU1_SA_CA<4>")
	)
	(segment
		(start 198.279258 -251.31014)
		(end 198.7042 -250.885198)
		(width 0.14478)
		(layer "In6.Cu")
		(net "M_K_CPU1_SA_CA<4>")
	)
	(segment
		(start 163.427664 -253.010162)
		(end 189.949328 -253.010162)
		(width 0.14478)
		(layer "In6.Cu")
		(net "M_K_CPU1_SA_CA<4>")
	)
	(arc
		(start 144.495774 -254.531876)
		(mid 144.679282 -254.57737)
		(end 144.861534 -254.52705)
		(width 0.0889)
		(layer "In6.Cu")
		(net "M_K_CPU1_SA_CA<4>")
	)
	(arc
		(start 145.412714 -254.518414)
		(mid 145.498672 -254.552069)
		(end 145.59026 -254.563626)
		(width 0.0889)
		(layer "In6.Cu")
		(net "M_K_CPU1_SA_CA<4>")
	)
	(arc
		(start 142.663164 -254.553212)
		(mid 142.825353 -254.575947)
		(end 142.98168 -254.52705)
		(width 0.0889)
		(layer "In6.Cu")
		(net "M_K_CPU1_SA_CA<4>")
	)
	(arc
		(start 143.932148 -254.520954)
		(mid 144.21058 -254.450856)
		(end 144.487392 -254.52705)
		(width 0.0889)
		(layer "In6.Cu")
		(net "M_K_CPU1_SA_CA<4>")
	)
	(arc
		(start 144.861534 -254.52705)
		(mid 145.135986 -254.450814)
		(end 145.412714 -254.518414)
		(width 0.0889)
		(layer "In6.Cu")
		(net "M_K_CPU1_SA_CA<4>")
	)
	(arc
		(start 143.547592 -254.52705)
		(mid 143.729843 -254.5774)
		(end 143.913352 -254.531876)
		(width 0.0889)
		(layer "In6.Cu")
		(net "M_K_CPU1_SA_CA<4>")
	)
	(arc
		(start 142.98168 -254.52705)
		(mid 143.264636 -254.450873)
		(end 143.547592 -254.52705)
		(width 0.0889)
		(layer "In6.Cu")
		(net "M_K_CPU1_SA_CA<4>")
	)
	(segment
		(start 140.447776 -254.470408)
		(end 140.914882 -254.20447)
		(width 0.10668)
		(layer "F.Cu")
		(net "M_K_CPU1_SA_CA<3>")
	)
	(segment
		(start 189.949328 -252.160278)
		(end 190.799466 -251.31014)
		(width 0.14478)
		(layer "In6.Cu")
		(net "M_K_CPU1_SA_CA<3>")
	)
	(segment
		(start 194.165474 -250.473972)
		(end 194.604132 -250.035314)
		(width 0.14478)
		(layer "In6.Cu")
		(net "M_K_CPU1_SA_CA<3>")
	)
	(segment
		(start 147.490688 -254.667004)
		(end 147.859496 -254.667004)
		(width 0.0889)
		(layer "In6.Cu")
		(net "M_K_CPU1_SA_CA<3>")
	)
	(segment
		(start 151.34209 -253.334774)
		(end 162.253168 -253.334774)
		(width 0.14478)
		(layer "In6.Cu")
		(net "M_K_CPU1_SA_CA<3>")
	)
	(segment
		(start 192.386458 -250.473972)
		(end 194.165474 -250.473972)
		(width 0.14478)
		(layer "In6.Cu")
		(net "M_K_CPU1_SA_CA<3>")
	)
	(segment
		(start 146.888708 -254.065024)
		(end 147.490688 -254.667004)
		(width 0.0889)
		(layer "In6.Cu")
		(net "M_K_CPU1_SA_CA<3>")
	)
	(segment
		(start 141.667738 -253.88189)
		(end 141.67612 -253.877064)
		(width 0.0889)
		(layer "In6.Cu")
		(net "M_K_CPU1_SA_CA<3>")
	)
	(segment
		(start 145.427192 -253.882144)
		(end 145.440908 -253.87427)
		(width 0.0889)
		(layer "In6.Cu")
		(net "M_K_CPU1_SA_CA<3>")
	)
	(segment
		(start 147.859496 -254.667004)
		(end 150.00986 -254.667004)
		(width 0.14478)
		(layer "In6.Cu")
		(net "M_K_CPU1_SA_CA<3>")
	)
	(segment
		(start 141.068806 -253.93904)
		(end 141.164818 -253.91364)
		(width 0.0889)
		(layer "In6.Cu")
		(net "M_K_CPU1_SA_CA<3>")
	)
	(segment
		(start 143.92148 -253.88189)
		(end 143.931894 -253.887986)
		(width 0.0889)
		(layer "In6.Cu")
		(net "M_K_CPU1_SA_CA<3>")
	)
	(segment
		(start 140.914882 -254.20447)
		(end 141.068806 -253.93904)
		(width 0.0889)
		(layer "In6.Cu")
		(net "M_K_CPU1_SA_CA<3>")
	)
	(segment
		(start 145.800826 -253.88189)
		(end 145.98396 -254.065024)
		(width 0.0889)
		(layer "In6.Cu")
		(net "M_K_CPU1_SA_CA<3>")
	)
	(segment
		(start 144.487138 -253.88189)
		(end 144.498822 -253.875032)
		(width 0.0889)
		(layer "In6.Cu")
		(net "M_K_CPU1_SA_CA<3>")
	)
	(segment
		(start 145.98396 -254.065024)
		(end 146.888708 -254.065024)
		(width 0.0889)
		(layer "In6.Cu")
		(net "M_K_CPU1_SA_CA<3>")
	)
	(segment
		(start 145.415254 -253.889002)
		(end 145.427192 -253.882144)
		(width 0.0889)
		(layer "In6.Cu")
		(net "M_K_CPU1_SA_CA<3>")
	)
	(segment
		(start 190.799466 -251.31014)
		(end 191.55029 -251.31014)
		(width 0.14478)
		(layer "In6.Cu")
		(net "M_K_CPU1_SA_CA<3>")
	)
	(segment
		(start 191.55029 -251.31014)
		(end 192.386458 -250.473972)
		(width 0.14478)
		(layer "In6.Cu")
		(net "M_K_CPU1_SA_CA<3>")
	)
	(segment
		(start 150.00986 -254.667004)
		(end 151.34209 -253.334774)
		(width 0.14478)
		(layer "In6.Cu")
		(net "M_K_CPU1_SA_CA<3>")
	)
	(segment
		(start 163.427664 -252.160278)
		(end 189.949328 -252.160278)
		(width 0.14478)
		(layer "In6.Cu")
		(net "M_K_CPU1_SA_CA<3>")
	)
	(segment
		(start 162.253168 -253.334774)
		(end 163.427664 -252.160278)
		(width 0.14478)
		(layer "In6.Cu")
		(net "M_K_CPU1_SA_CA<3>")
	)
	(segment
		(start 143.909796 -253.875032)
		(end 143.92148 -253.88189)
		(width 0.0889)
		(layer "In6.Cu")
		(net "M_K_CPU1_SA_CA<3>")
	)
	(arc
		(start 141.164818 -253.91364)
		(mid 141.420026 -253.957117)
		(end 141.667738 -253.88189)
		(width 0.0889)
		(layer "In6.Cu")
		(net "M_K_CPU1_SA_CA<3>")
	)
	(arc
		(start 145.440908 -253.87427)
		(mid 145.621838 -253.831792)
		(end 145.800826 -253.88189)
		(width 0.0889)
		(layer "In6.Cu")
		(net "M_K_CPU1_SA_CA<3>")
	)
	(arc
		(start 142.04188 -253.88189)
		(mid 142.324836 -253.958067)
		(end 142.607792 -253.88189)
		(width 0.0889)
		(layer "In6.Cu")
		(net "M_K_CPU1_SA_CA<3>")
	)
	(arc
		(start 143.931894 -253.887986)
		(mid 144.210326 -253.958084)
		(end 144.487138 -253.88189)
		(width 0.0889)
		(layer "In6.Cu")
		(net "M_K_CPU1_SA_CA<3>")
	)
	(arc
		(start 143.547592 -253.88189)
		(mid 143.727797 -253.831573)
		(end 143.909796 -253.875032)
		(width 0.0889)
		(layer "In6.Cu")
		(net "M_K_CPU1_SA_CA<3>")
	)
	(arc
		(start 142.98168 -253.88189)
		(mid 143.264636 -253.958067)
		(end 143.547592 -253.88189)
		(width 0.0889)
		(layer "In6.Cu")
		(net "M_K_CPU1_SA_CA<3>")
	)
	(arc
		(start 144.861534 -253.88189)
		(mid 145.137466 -253.958147)
		(end 145.415254 -253.889002)
		(width 0.0889)
		(layer "In6.Cu")
		(net "M_K_CPU1_SA_CA<3>")
	)
	(arc
		(start 141.67612 -253.877064)
		(mid 141.859628 -253.83157)
		(end 142.04188 -253.88189)
		(width 0.0889)
		(layer "In6.Cu")
		(net "M_K_CPU1_SA_CA<3>")
	)
	(arc
		(start 142.607792 -253.88189)
		(mid 142.794736 -253.831635)
		(end 142.98168 -253.88189)
		(width 0.0889)
		(layer "In6.Cu")
		(net "M_K_CPU1_SA_CA<3>")
	)
	(arc
		(start 144.498822 -253.875032)
		(mid 144.681077 -253.831379)
		(end 144.861534 -253.88189)
		(width 0.0889)
		(layer "In6.Cu")
		(net "M_K_CPU1_SA_CA<3>")
	)
	(segment
		(start 140.91793 -253.660402)
		(end 141.384782 -253.394464)
		(width 0.10668)
		(layer "F.Cu")
		(net "M_K_CPU1_SA_CA<2>")
	)
	(segment
		(start 146.995388 -253.821184)
		(end 147.386548 -254.212344)
		(width 0.0889)
		(layer "In6.Cu")
		(net "M_K_CPU1_SA_CA<2>")
	)
	(segment
		(start 192.08877 -249.875294)
		(end 193.978276 -249.875294)
		(width 0.14478)
		(layer "In6.Cu")
		(net "M_K_CPU1_SA_CA<2>")
	)
	(segment
		(start 144.017492 -253.717044)
		(end 144.025874 -253.72187)
		(width 0.0889)
		(layer "In6.Cu")
		(net "M_K_CPU1_SA_CA<2>")
	)
	(segment
		(start 161.85769 -252.880114)
		(end 163.427664 -251.31014)
		(width 0.14478)
		(layer "In6.Cu")
		(net "M_K_CPU1_SA_CA<2>")
	)
	(segment
		(start 145.331434 -253.71679)
		(end 145.337022 -253.713488)
		(width 0.0889)
		(layer "In6.Cu")
		(net "M_K_CPU1_SA_CA<2>")
	)
	(segment
		(start 163.427664 -251.31014)
		(end 189.949328 -251.31014)
		(width 0.14478)
		(layer "In6.Cu")
		(net "M_K_CPU1_SA_CA<2>")
	)
	(segment
		(start 147.386548 -254.212344)
		(end 147.859496 -254.212344)
		(width 0.0889)
		(layer "In6.Cu")
		(net "M_K_CPU1_SA_CA<2>")
	)
	(segment
		(start 146.428968 -253.821184)
		(end 146.995388 -253.821184)
		(width 0.0889)
		(layer "In6.Cu")
		(net "M_K_CPU1_SA_CA<2>")
	)
	(segment
		(start 142.503398 -253.72187)
		(end 142.51178 -253.717044)
		(width 0.0889)
		(layer "In6.Cu")
		(net "M_K_CPU1_SA_CA<2>")
	)
	(segment
		(start 143.077692 -253.717044)
		(end 143.086074 -253.72187)
		(width 0.0889)
		(layer "In6.Cu")
		(net "M_K_CPU1_SA_CA<2>")
	)
	(segment
		(start 151.153622 -252.880114)
		(end 161.85769 -252.880114)
		(width 0.14478)
		(layer "In6.Cu")
		(net "M_K_CPU1_SA_CA<2>")
	)
	(segment
		(start 191.504062 -250.460002)
		(end 192.08877 -249.875294)
		(width 0.14478)
		(layer "In6.Cu")
		(net "M_K_CPU1_SA_CA<2>")
	)
	(segment
		(start 141.230858 -253.659894)
		(end 141.25321 -253.743206)
		(width 0.0889)
		(layer "In6.Cu")
		(net "M_K_CPU1_SA_CA<2>")
	)
	(segment
		(start 146.324828 -253.717044)
		(end 146.428968 -253.821184)
		(width 0.0889)
		(layer "In6.Cu")
		(net "M_K_CPU1_SA_CA<2>")
	)
	(segment
		(start 144.007078 -253.710948)
		(end 144.017492 -253.717044)
		(width 0.0889)
		(layer "In6.Cu")
		(net "M_K_CPU1_SA_CA<2>")
	)
	(segment
		(start 147.859496 -254.212344)
		(end 149.821392 -254.212344)
		(width 0.14478)
		(layer "In6.Cu")
		(net "M_K_CPU1_SA_CA<2>")
	)
	(segment
		(start 145.896838 -253.717044)
		(end 146.324828 -253.717044)
		(width 0.0889)
		(layer "In6.Cu")
		(net "M_K_CPU1_SA_CA<2>")
	)
	(segment
		(start 145.313146 -253.727204)
		(end 145.331434 -253.71679)
		(width 0.0889)
		(layer "In6.Cu")
		(net "M_K_CPU1_SA_CA<2>")
	)
	(segment
		(start 198.279512 -249.610118)
		(end 198.7042 -249.18543)
		(width 0.14478)
		(layer "In6.Cu")
		(net "M_K_CPU1_SA_CA<2>")
	)
	(segment
		(start 193.978276 -249.875294)
		(end 194.243452 -249.610118)
		(width 0.14478)
		(layer "In6.Cu")
		(net "M_K_CPU1_SA_CA<2>")
	)
	(segment
		(start 190.799466 -250.460002)
		(end 191.504062 -250.460002)
		(width 0.14478)
		(layer "In6.Cu")
		(net "M_K_CPU1_SA_CA<2>")
	)
	(segment
		(start 194.243452 -249.610118)
		(end 198.279512 -249.610118)
		(width 0.14478)
		(layer "In6.Cu")
		(net "M_K_CPU1_SA_CA<2>")
	)
	(segment
		(start 144.391126 -253.717044)
		(end 144.40154 -253.710948)
		(width 0.0889)
		(layer "In6.Cu")
		(net "M_K_CPU1_SA_CA<2>")
	)
	(segment
		(start 189.949328 -251.31014)
		(end 190.799466 -250.460002)
		(width 0.14478)
		(layer "In6.Cu")
		(net "M_K_CPU1_SA_CA<2>")
	)
	(segment
		(start 141.384782 -253.394464)
		(end 141.230858 -253.659894)
		(width 0.0889)
		(layer "In6.Cu")
		(net "M_K_CPU1_SA_CA<2>")
	)
	(segment
		(start 149.821392 -254.212344)
		(end 151.153622 -252.880114)
		(width 0.14478)
		(layer "In6.Cu")
		(net "M_K_CPU1_SA_CA<2>")
	)
	(arc
		(start 142.51178 -253.717044)
		(mid 142.794736 -253.640867)
		(end 143.077692 -253.717044)
		(width 0.0889)
		(layer "In6.Cu")
		(net "M_K_CPU1_SA_CA<2>")
	)
	(arc
		(start 144.957292 -253.717044)
		(mid 145.13392 -253.767277)
		(end 145.313146 -253.727204)
		(width 0.0889)
		(layer "In6.Cu")
		(net "M_K_CPU1_SA_CA<2>")
	)
	(arc
		(start 145.337022 -253.713488)
		(mid 145.617411 -253.640819)
		(end 145.896838 -253.717044)
		(width 0.0889)
		(layer "In6.Cu")
		(net "M_K_CPU1_SA_CA<2>")
	)
	(arc
		(start 144.025874 -253.72187)
		(mid 144.209128 -253.767243)
		(end 144.391126 -253.717044)
		(width 0.0889)
		(layer "In6.Cu")
		(net "M_K_CPU1_SA_CA<2>")
	)
	(arc
		(start 144.40154 -253.710948)
		(mid 144.680226 -253.640728)
		(end 144.957292 -253.717044)
		(width 0.0889)
		(layer "In6.Cu")
		(net "M_K_CPU1_SA_CA<2>")
	)
	(arc
		(start 142.137638 -253.717044)
		(mid 142.319889 -253.767394)
		(end 142.503398 -253.72187)
		(width 0.0889)
		(layer "In6.Cu")
		(net "M_K_CPU1_SA_CA<2>")
	)
	(arc
		(start 141.25321 -253.743206)
		(mid 141.415399 -253.765941)
		(end 141.571726 -253.717044)
		(width 0.0889)
		(layer "In6.Cu")
		(net "M_K_CPU1_SA_CA<2>")
	)
	(arc
		(start 143.086074 -253.72187)
		(mid 143.269582 -253.767364)
		(end 143.451834 -253.717044)
		(width 0.0889)
		(layer "In6.Cu")
		(net "M_K_CPU1_SA_CA<2>")
	)
	(arc
		(start 141.571726 -253.717044)
		(mid 141.854682 -253.640867)
		(end 142.137638 -253.717044)
		(width 0.0889)
		(layer "In6.Cu")
		(net "M_K_CPU1_SA_CA<2>")
	)
	(arc
		(start 143.451834 -253.717044)
		(mid 143.728647 -253.640901)
		(end 144.007078 -253.710948)
		(width 0.0889)
		(layer "In6.Cu")
		(net "M_K_CPU1_SA_CA<2>")
	)
	(segment
		(start 141.857984 -253.660402)
		(end 142.324836 -253.394464)
		(width 0.10668)
		(layer "F.Cu")
		(net "M_K_CPU1_SA_CA<1>")
	)
	(segment
		(start 191.558418 -249.610118)
		(end 192.010792 -249.157744)
		(width 0.14478)
		(layer "In6.Cu")
		(net "M_K_CPU1_SA_CA<1>")
	)
	(segment
		(start 161.462466 -252.425454)
		(end 163.427664 -250.460256)
		(width 0.14478)
		(layer "In6.Cu")
		(net "M_K_CPU1_SA_CA<1>")
	)
	(segment
		(start 167.592502 -250.460256)
		(end 189.949328 -250.460256)
		(width 0.14478)
		(layer "In6.Cu")
		(net "M_K_CPU1_SA_CA<1>")
	)
	(segment
		(start 147.214082 -253.572518)
		(end 147.399248 -253.757684)
		(width 0.0889)
		(layer "In6.Cu")
		(net "M_K_CPU1_SA_CA<1>")
	)
	(segment
		(start 190.799466 -249.610118)
		(end 191.558418 -249.610118)
		(width 0.14478)
		(layer "In6.Cu")
		(net "M_K_CPU1_SA_CA<1>")
	)
	(segment
		(start 149.632924 -253.757684)
		(end 150.965154 -252.425454)
		(width 0.14478)
		(layer "In6.Cu")
		(net "M_K_CPU1_SA_CA<1>")
	)
	(segment
		(start 166.709852 -250.068588)
		(end 166.87292 -250.231656)
		(width 0.14478)
		(layer "In6.Cu")
		(net "M_K_CPU1_SA_CA<1>")
	)
	(segment
		(start 165.92296 -250.851924)
		(end 166.153338 -250.851924)
		(width 0.14478)
		(layer "In6.Cu")
		(net "M_K_CPU1_SA_CA<1>")
	)
	(segment
		(start 167.429434 -250.688856)
		(end 167.429434 -250.623324)
		(width 0.14478)
		(layer "In6.Cu")
		(net "M_K_CPU1_SA_CA<1>")
	)
	(segment
		(start 166.316406 -250.231656)
		(end 166.479474 -250.068588)
		(width 0.14478)
		(layer "In6.Cu")
		(net "M_K_CPU1_SA_CA<1>")
	)
	(segment
		(start 189.949328 -250.460256)
		(end 190.799466 -249.610118)
		(width 0.14478)
		(layer "In6.Cu")
		(net "M_K_CPU1_SA_CA<1>")
	)
	(segment
		(start 166.87292 -250.688856)
		(end 167.035988 -250.851924)
		(width 0.14478)
		(layer "In6.Cu")
		(net "M_K_CPU1_SA_CA<1>")
	)
	(segment
		(start 142.47876 -253.129034)
		(end 142.574772 -253.103634)
		(width 0.0889)
		(layer "In6.Cu")
		(net "M_K_CPU1_SA_CA<1>")
	)
	(segment
		(start 144.39138 -253.071884)
		(end 144.401794 -253.07798)
		(width 0.0889)
		(layer "In6.Cu")
		(net "M_K_CPU1_SA_CA<1>")
	)
	(segment
		(start 165.759892 -250.623324)
		(end 165.759892 -250.688856)
		(width 0.14478)
		(layer "In6.Cu")
		(net "M_K_CPU1_SA_CA<1>")
	)
	(segment
		(start 147.870926 -253.757684)
		(end 149.632924 -253.757684)
		(width 0.14478)
		(layer "In6.Cu")
		(net "M_K_CPU1_SA_CA<1>")
	)
	(segment
		(start 147.399248 -253.757684)
		(end 147.870926 -253.757684)
		(width 0.0889)
		(layer "In6.Cu")
		(net "M_K_CPU1_SA_CA<1>")
	)
	(segment
		(start 166.87292 -250.231656)
		(end 166.87292 -250.688856)
		(width 0.14478)
		(layer "In6.Cu")
		(net "M_K_CPU1_SA_CA<1>")
	)
	(segment
		(start 167.429434 -250.623324)
		(end 167.592502 -250.460256)
		(width 0.14478)
		(layer "In6.Cu")
		(net "M_K_CPU1_SA_CA<1>")
	)
	(segment
		(start 167.035988 -250.851924)
		(end 167.266366 -250.851924)
		(width 0.14478)
		(layer "In6.Cu")
		(net "M_K_CPU1_SA_CA<1>")
	)
	(segment
		(start 145.590006 -253.134114)
		(end 146.067018 -253.134114)
		(width 0.0889)
		(layer "In6.Cu")
		(net "M_K_CPU1_SA_CA<1>")
	)
	(segment
		(start 143.077692 -253.071884)
		(end 143.086074 -253.067058)
		(width 0.0889)
		(layer "In6.Cu")
		(net "M_K_CPU1_SA_CA<1>")
	)
	(segment
		(start 165.596824 -250.460256)
		(end 165.759892 -250.623324)
		(width 0.14478)
		(layer "In6.Cu")
		(net "M_K_CPU1_SA_CA<1>")
	)
	(segment
		(start 167.266366 -250.851924)
		(end 167.429434 -250.688856)
		(width 0.14478)
		(layer "In6.Cu")
		(net "M_K_CPU1_SA_CA<1>")
	)
	(segment
		(start 166.316406 -250.688856)
		(end 166.316406 -250.231656)
		(width 0.14478)
		(layer "In6.Cu")
		(net "M_K_CPU1_SA_CA<1>")
	)
	(segment
		(start 146.067018 -253.134114)
		(end 146.505422 -253.572518)
		(width 0.0889)
		(layer "In6.Cu")
		(net "M_K_CPU1_SA_CA<1>")
	)
	(segment
		(start 193.78168 -249.157744)
		(end 194.604132 -248.335292)
		(width 0.14478)
		(layer "In6.Cu")
		(net "M_K_CPU1_SA_CA<1>")
	)
	(segment
		(start 142.324836 -253.394464)
		(end 142.47876 -253.129034)
		(width 0.0889)
		(layer "In6.Cu")
		(net "M_K_CPU1_SA_CA<1>")
	)
	(segment
		(start 192.010792 -249.157744)
		(end 193.78168 -249.157744)
		(width 0.14478)
		(layer "In6.Cu")
		(net "M_K_CPU1_SA_CA<1>")
	)
	(segment
		(start 166.479474 -250.068588)
		(end 166.709852 -250.068588)
		(width 0.14478)
		(layer "In6.Cu")
		(net "M_K_CPU1_SA_CA<1>")
	)
	(segment
		(start 146.505422 -253.572518)
		(end 147.214082 -253.572518)
		(width 0.0889)
		(layer "In6.Cu")
		(net "M_K_CPU1_SA_CA<1>")
	)
	(segment
		(start 163.427664 -250.460256)
		(end 165.596824 -250.460256)
		(width 0.14478)
		(layer "In6.Cu")
		(net "M_K_CPU1_SA_CA<1>")
	)
	(segment
		(start 166.153338 -250.851924)
		(end 166.316406 -250.688856)
		(width 0.14478)
		(layer "In6.Cu")
		(net "M_K_CPU1_SA_CA<1>")
	)
	(segment
		(start 144.007078 -253.07798)
		(end 144.017492 -253.071884)
		(width 0.0889)
		(layer "In6.Cu")
		(net "M_K_CPU1_SA_CA<1>")
	)
	(segment
		(start 150.965154 -252.425454)
		(end 161.462466 -252.425454)
		(width 0.14478)
		(layer "In6.Cu")
		(net "M_K_CPU1_SA_CA<1>")
	)
	(segment
		(start 165.759892 -250.688856)
		(end 165.92296 -250.851924)
		(width 0.14478)
		(layer "In6.Cu")
		(net "M_K_CPU1_SA_CA<1>")
	)
	(arc
		(start 143.451834 -253.071884)
		(mid 143.728647 -253.148027)
		(end 144.007078 -253.07798)
		(width 0.0889)
		(layer "In6.Cu")
		(net "M_K_CPU1_SA_CA<1>")
	)
	(arc
		(start 144.401794 -253.07798)
		(mid 144.68048 -253.1482)
		(end 144.957546 -253.071884)
		(width 0.0889)
		(layer "In6.Cu")
		(net "M_K_CPU1_SA_CA<1>")
	)
	(arc
		(start 144.957546 -253.071884)
		(mid 145.137751 -253.021567)
		(end 145.31975 -253.065026)
		(width 0.0889)
		(layer "In6.Cu")
		(net "M_K_CPU1_SA_CA<1>")
	)
	(arc
		(start 144.017492 -253.071884)
		(mid 144.204436 -253.021629)
		(end 144.39138 -253.071884)
		(width 0.0889)
		(layer "In6.Cu")
		(net "M_K_CPU1_SA_CA<1>")
	)
	(arc
		(start 142.574772 -253.103634)
		(mid 142.82998 -253.147111)
		(end 143.077692 -253.071884)
		(width 0.0889)
		(layer "In6.Cu")
		(net "M_K_CPU1_SA_CA<1>")
	)
	(arc
		(start 145.31975 -253.065026)
		(mid 145.45054 -253.116537)
		(end 145.590006 -253.134114)
		(width 0.0889)
		(layer "In6.Cu")
		(net "M_K_CPU1_SA_CA<1>")
	)
	(arc
		(start 143.086074 -253.067058)
		(mid 143.269582 -253.021564)
		(end 143.451834 -253.071884)
		(width 0.0889)
		(layer "In6.Cu")
		(net "M_K_CPU1_SA_CA<1>")
	)
	(segment
		(start 142.327884 -252.850396)
		(end 142.794736 -252.584458)
		(width 0.10668)
		(layer "F.Cu")
		(net "M_K_CPU1_SA_CA<0>")
	)
	(segment
		(start 150.776686 -251.970794)
		(end 161.067242 -251.970794)
		(width 0.14478)
		(layer "In6.Cu")
		(net "M_K_CPU1_SA_CA<0>")
	)
	(segment
		(start 191.50203 -248.760234)
		(end 191.813434 -248.44883)
		(width 0.14478)
		(layer "In6.Cu")
		(net "M_K_CPU1_SA_CA<0>")
	)
	(segment
		(start 147.876768 -253.303024)
		(end 149.444456 -253.303024)
		(width 0.14478)
		(layer "In6.Cu")
		(net "M_K_CPU1_SA_CA<0>")
	)
	(segment
		(start 198.279512 -247.910096)
		(end 198.7042 -247.485408)
		(width 0.14478)
		(layer "In6.Cu")
		(net "M_K_CPU1_SA_CA<0>")
	)
	(segment
		(start 163.427664 -249.610372)
		(end 189.949328 -249.610372)
		(width 0.14478)
		(layer "In6.Cu")
		(net "M_K_CPU1_SA_CA<0>")
	)
	(segment
		(start 142.640812 -252.849888)
		(end 142.663164 -252.9332)
		(width 0.0889)
		(layer "In6.Cu")
		(net "M_K_CPU1_SA_CA<0>")
	)
	(segment
		(start 194.243452 -247.910096)
		(end 198.279512 -247.910096)
		(width 0.14478)
		(layer "In6.Cu")
		(net "M_K_CPU1_SA_CA<0>")
	)
	(segment
		(start 193.704718 -248.44883)
		(end 194.243452 -247.910096)
		(width 0.14478)
		(layer "In6.Cu")
		(net "M_K_CPU1_SA_CA<0>")
	)
	(segment
		(start 146.298158 -252.943614)
		(end 146.657568 -253.303024)
		(width 0.0889)
		(layer "In6.Cu")
		(net "M_K_CPU1_SA_CA<0>")
	)
	(segment
		(start 143.921734 -252.907038)
		(end 143.932148 -252.900942)
		(width 0.0889)
		(layer "In6.Cu")
		(net "M_K_CPU1_SA_CA<0>")
	)
	(segment
		(start 142.794736 -252.584458)
		(end 142.640812 -252.849888)
		(width 0.0889)
		(layer "In6.Cu")
		(net "M_K_CPU1_SA_CA<0>")
	)
	(segment
		(start 149.444456 -253.303024)
		(end 150.776686 -251.970794)
		(width 0.14478)
		(layer "In6.Cu")
		(net "M_K_CPU1_SA_CA<0>")
	)
	(segment
		(start 143.913352 -252.911864)
		(end 143.921734 -252.907038)
		(width 0.0889)
		(layer "In6.Cu")
		(net "M_K_CPU1_SA_CA<0>")
	)
	(segment
		(start 146.657568 -253.303024)
		(end 147.876768 -253.303024)
		(width 0.0889)
		(layer "In6.Cu")
		(net "M_K_CPU1_SA_CA<0>")
	)
	(segment
		(start 191.813434 -248.44883)
		(end 193.704718 -248.44883)
		(width 0.14478)
		(layer "In6.Cu")
		(net "M_K_CPU1_SA_CA<0>")
	)
	(segment
		(start 189.949328 -249.610372)
		(end 190.799466 -248.760234)
		(width 0.14478)
		(layer "In6.Cu")
		(net "M_K_CPU1_SA_CA<0>")
	)
	(segment
		(start 145.59026 -252.943614)
		(end 146.298158 -252.943614)
		(width 0.0889)
		(layer "In6.Cu")
		(net "M_K_CPU1_SA_CA<0>")
	)
	(segment
		(start 161.067242 -251.970794)
		(end 163.427664 -249.610372)
		(width 0.14478)
		(layer "In6.Cu")
		(net "M_K_CPU1_SA_CA<0>")
	)
	(segment
		(start 144.487392 -252.907038)
		(end 144.495774 -252.911864)
		(width 0.0889)
		(layer "In6.Cu")
		(net "M_K_CPU1_SA_CA<0>")
	)
	(segment
		(start 190.799466 -248.760234)
		(end 191.50203 -248.760234)
		(width 0.14478)
		(layer "In6.Cu")
		(net "M_K_CPU1_SA_CA<0>")
	)
	(arc
		(start 144.861534 -252.907038)
		(mid 145.135986 -252.830802)
		(end 145.412714 -252.898402)
		(width 0.0889)
		(layer "In6.Cu")
		(net "M_K_CPU1_SA_CA<0>")
	)
	(arc
		(start 142.98168 -252.907038)
		(mid 143.264636 -252.830861)
		(end 143.547592 -252.907038)
		(width 0.0889)
		(layer "In6.Cu")
		(net "M_K_CPU1_SA_CA<0>")
	)
	(arc
		(start 143.932148 -252.900942)
		(mid 144.21058 -252.830844)
		(end 144.487392 -252.907038)
		(width 0.0889)
		(layer "In6.Cu")
		(net "M_K_CPU1_SA_CA<0>")
	)
	(arc
		(start 143.547592 -252.907038)
		(mid 143.729843 -252.957388)
		(end 143.913352 -252.911864)
		(width 0.0889)
		(layer "In6.Cu")
		(net "M_K_CPU1_SA_CA<0>")
	)
	(arc
		(start 144.495774 -252.911864)
		(mid 144.679282 -252.957358)
		(end 144.861534 -252.907038)
		(width 0.0889)
		(layer "In6.Cu")
		(net "M_K_CPU1_SA_CA<0>")
	)
	(arc
		(start 142.663164 -252.9332)
		(mid 142.825353 -252.955935)
		(end 142.98168 -252.907038)
		(width 0.0889)
		(layer "In6.Cu")
		(net "M_K_CPU1_SA_CA<0>")
	)
	(arc
		(start 145.412714 -252.898402)
		(mid 145.498672 -252.932057)
		(end 145.59026 -252.943614)
		(width 0.0889)
		(layer "In6.Cu")
		(net "M_K_CPU1_SA_CA<0>")
	)
	(segment
		(start 140.447776 -251.230384)
		(end 140.914882 -250.964446)
		(width 0.10668)
		(layer "F.Cu")
		(net "M_K_CPU1_RESET_N")
	)
	(segment
		(start 150.08479 -250.302014)
		(end 159.955738 -250.302014)
		(width 0.11684)
		(layer "In6.Cu")
		(net "M_K_CPU1_RESET_N")
	)
	(segment
		(start 146.609308 -251.634244)
		(end 147.745196 -251.634244)
		(width 0.0889)
		(layer "In6.Cu")
		(net "M_K_CPU1_RESET_N")
	)
	(segment
		(start 190.150242 -246.210328)
		(end 191.514476 -246.210328)
		(width 0.11684)
		(layer "In6.Cu")
		(net "M_K_CPU1_RESET_N")
	)
	(segment
		(start 141.068806 -250.699016)
		(end 141.164818 -250.673616)
		(width 0.0889)
		(layer "In6.Cu")
		(net "M_K_CPU1_RESET_N")
	)
	(segment
		(start 140.914882 -250.964446)
		(end 141.068806 -250.699016)
		(width 0.0889)
		(layer "In6.Cu")
		(net "M_K_CPU1_RESET_N")
	)
	(segment
		(start 143.909796 -250.635008)
		(end 143.92148 -250.641866)
		(width 0.0889)
		(layer "In6.Cu")
		(net "M_K_CPU1_RESET_N")
	)
	(segment
		(start 159.955738 -250.302014)
		(end 163.19754 -247.060212)
		(width 0.11684)
		(layer "In6.Cu")
		(net "M_K_CPU1_RESET_N")
	)
	(segment
		(start 143.92148 -250.641866)
		(end 143.931894 -250.647962)
		(width 0.0889)
		(layer "In6.Cu")
		(net "M_K_CPU1_RESET_N")
	)
	(segment
		(start 145.144744 -250.718066)
		(end 145.36674 -250.718066)
		(width 0.0889)
		(layer "In6.Cu")
		(net "M_K_CPU1_RESET_N")
	)
	(segment
		(start 163.19754 -247.060212)
		(end 189.300358 -247.060212)
		(width 0.11684)
		(layer "In6.Cu")
		(net "M_K_CPU1_RESET_N")
	)
	(segment
		(start 192.789556 -244.935248)
		(end 194.604132 -244.935248)
		(width 0.11684)
		(layer "In6.Cu")
		(net "M_K_CPU1_RESET_N")
	)
	(segment
		(start 141.667738 -250.641866)
		(end 141.67612 -250.63704)
		(width 0.0889)
		(layer "In6.Cu")
		(net "M_K_CPU1_RESET_N")
	)
	(segment
		(start 145.36674 -250.718066)
		(end 145.696178 -251.047504)
		(width 0.0889)
		(layer "In6.Cu")
		(net "M_K_CPU1_RESET_N")
	)
	(segment
		(start 148.75256 -251.634244)
		(end 150.08479 -250.302014)
		(width 0.11684)
		(layer "In6.Cu")
		(net "M_K_CPU1_RESET_N")
	)
	(segment
		(start 145.696178 -251.047504)
		(end 146.022568 -251.047504)
		(width 0.0889)
		(layer "In6.Cu")
		(net "M_K_CPU1_RESET_N")
	)
	(segment
		(start 146.022568 -251.047504)
		(end 146.609308 -251.634244)
		(width 0.0889)
		(layer "In6.Cu")
		(net "M_K_CPU1_RESET_N")
	)
	(segment
		(start 191.514476 -246.210328)
		(end 192.789556 -244.935248)
		(width 0.11684)
		(layer "In6.Cu")
		(net "M_K_CPU1_RESET_N")
	)
	(segment
		(start 144.487138 -250.641866)
		(end 144.498822 -250.635008)
		(width 0.0889)
		(layer "In6.Cu")
		(net "M_K_CPU1_RESET_N")
	)
	(segment
		(start 147.745196 -251.634244)
		(end 148.75256 -251.634244)
		(width 0.11684)
		(layer "In6.Cu")
		(net "M_K_CPU1_RESET_N")
	)
	(segment
		(start 189.300358 -247.060212)
		(end 190.150242 -246.210328)
		(width 0.11684)
		(layer "In6.Cu")
		(net "M_K_CPU1_RESET_N")
	)
	(arc
		(start 141.164818 -250.673616)
		(mid 141.420026 -250.717093)
		(end 141.667738 -250.641866)
		(width 0.0889)
		(layer "In6.Cu")
		(net "M_K_CPU1_RESET_N")
	)
	(arc
		(start 142.98168 -250.641866)
		(mid 143.264636 -250.718043)
		(end 143.547592 -250.641866)
		(width 0.0889)
		(layer "In6.Cu")
		(net "M_K_CPU1_RESET_N")
	)
	(arc
		(start 144.861534 -250.641866)
		(mid 144.998097 -250.698699)
		(end 145.144744 -250.718066)
		(width 0.0889)
		(layer "In6.Cu")
		(net "M_K_CPU1_RESET_N")
	)
	(arc
		(start 143.931894 -250.647962)
		(mid 144.210326 -250.71806)
		(end 144.487138 -250.641866)
		(width 0.0889)
		(layer "In6.Cu")
		(net "M_K_CPU1_RESET_N")
	)
	(arc
		(start 141.67612 -250.63704)
		(mid 141.859628 -250.591546)
		(end 142.04188 -250.641866)
		(width 0.0889)
		(layer "In6.Cu")
		(net "M_K_CPU1_RESET_N")
	)
	(arc
		(start 142.607792 -250.641866)
		(mid 142.794736 -250.591611)
		(end 142.98168 -250.641866)
		(width 0.0889)
		(layer "In6.Cu")
		(net "M_K_CPU1_RESET_N")
	)
	(arc
		(start 144.498822 -250.635008)
		(mid 144.681077 -250.591355)
		(end 144.861534 -250.641866)
		(width 0.0889)
		(layer "In6.Cu")
		(net "M_K_CPU1_RESET_N")
	)
	(arc
		(start 142.04188 -250.641866)
		(mid 142.324836 -250.718043)
		(end 142.607792 -250.641866)
		(width 0.0889)
		(layer "In6.Cu")
		(net "M_K_CPU1_RESET_N")
	)
	(arc
		(start 143.547592 -250.641866)
		(mid 143.727797 -250.591549)
		(end 143.909796 -250.635008)
		(width 0.0889)
		(layer "In6.Cu")
		(net "M_K_CPU1_RESET_N")
	)
	(segment
		(start 142.327884 -256.09042)
		(end 142.794736 -255.824482)
		(width 0.14732)
		(layer "F.Cu")
		(net "M_K_CPU1_CLK_DP<0>")
	)
	(segment
		(start 151.007064 -257.176524)
		(end 152.369774 -255.813814)
		(width 0.16002)
		(layer "In6.Cu")
		(net "M_K_CPU1_CLK_DP<0>")
	)
	(segment
		(start 161.016188 -256.704846)
		(end 161.716466 -256.704846)
		(width 0.16002)
		(layer "In6.Cu")
		(net "M_K_CPU1_CLK_DP<0>")
	)
	(segment
		(start 189.4967 -256.704846)
		(end 190.72987 -256.704846)
		(width 0.16002)
		(layer "In6.Cu")
		(net "M_K_CPU1_CLK_DP<0>")
	)
	(segment
		(start 193.72453 -253.710186)
		(end 194.329304 -253.710186)
		(width 0.16002)
		(layer "In6.Cu")
		(net "M_K_CPU1_CLK_DP<0>")
	)
	(segment
		(start 160.069276 -257.898646)
		(end 160.51911 -257.898646)
		(width 0.16002)
		(layer "In6.Cu")
		(net "M_K_CPU1_CLK_DP<0>")
	)
	(segment
		(start 147.508468 -257.176524)
		(end 147.53209 -257.176524)
		(width 0.09525)
		(layer "In6.Cu")
		(net "M_K_CPU1_CLK_DP<0>")
	)
	(segment
		(start 188.76264 -256.704846)
		(end 188.88964 -256.577846)
		(width 0.16002)
		(layer "In6.Cu")
		(net "M_K_CPU1_CLK_DP<0>")
	)
	(segment
		(start 152.369774 -255.813814)
		(end 158.188406 -255.813814)
		(width 0.16002)
		(layer "In6.Cu")
		(net "M_K_CPU1_CLK_DP<0>")
	)
	(segment
		(start 162.213544 -257.898646)
		(end 162.663378 -257.898646)
		(width 0.16002)
		(layer "In6.Cu")
		(net "M_K_CPU1_CLK_DP<0>")
	)
	(segment
		(start 163.160456 -256.704846)
		(end 188.76264 -256.704846)
		(width 0.16002)
		(layer "In6.Cu")
		(net "M_K_CPU1_CLK_DP<0>")
	)
	(segment
		(start 147.449286 -257.235706)
		(end 147.508468 -257.176524)
		(width 0.09525)
		(layer "In6.Cu")
		(net "M_K_CPU1_CLK_DP<0>")
	)
	(segment
		(start 147.53209 -257.176524)
		(end 151.007064 -257.176524)
		(width 0.16002)
		(layer "In6.Cu")
		(net "M_K_CPU1_CLK_DP<0>")
	)
	(segment
		(start 142.794736 -255.824482)
		(end 142.640812 -256.089912)
		(width 0.09525)
		(layer "In6.Cu")
		(net "M_K_CPU1_CLK_DP<0>")
	)
	(segment
		(start 160.51911 -257.898646)
		(end 160.67913 -257.738626)
		(width 0.16002)
		(layer "In6.Cu")
		(net "M_K_CPU1_CLK_DP<0>")
	)
	(segment
		(start 146.538442 -257.235706)
		(end 147.449286 -257.235706)
		(width 0.09525)
		(layer "In6.Cu")
		(net "M_K_CPU1_CLK_DP<0>")
	)
	(segment
		(start 162.053524 -257.738626)
		(end 162.213544 -257.898646)
		(width 0.16002)
		(layer "In6.Cu")
		(net "M_K_CPU1_CLK_DP<0>")
	)
	(segment
		(start 188.88964 -256.577846)
		(end 189.3697 -256.577846)
		(width 0.16002)
		(layer "In6.Cu")
		(net "M_K_CPU1_CLK_DP<0>")
	)
	(segment
		(start 162.053524 -257.041904)
		(end 162.053524 -257.738626)
		(width 0.16002)
		(layer "In6.Cu")
		(net "M_K_CPU1_CLK_DP<0>")
	)
	(segment
		(start 145.540984 -256.238248)
		(end 146.538442 -257.235706)
		(width 0.09525)
		(layer "In6.Cu")
		(net "M_K_CPU1_CLK_DP<0>")
	)
	(segment
		(start 190.72987 -256.704846)
		(end 193.72453 -253.710186)
		(width 0.16002)
		(layer "In6.Cu")
		(net "M_K_CPU1_CLK_DP<0>")
	)
	(segment
		(start 159.572198 -256.704846)
		(end 159.909256 -257.041904)
		(width 0.16002)
		(layer "In6.Cu")
		(net "M_K_CPU1_CLK_DP<0>")
	)
	(segment
		(start 144.485868 -256.149602)
		(end 144.49425 -256.154428)
		(width 0.09525)
		(layer "In6.Cu")
		(net "M_K_CPU1_CLK_DP<0>")
	)
	(segment
		(start 145.41119 -256.140966)
		(end 145.425922 -256.149602)
		(width 0.09525)
		(layer "In6.Cu")
		(net "M_K_CPU1_CLK_DP<0>")
	)
	(segment
		(start 161.716466 -256.704846)
		(end 162.053524 -257.041904)
		(width 0.16002)
		(layer "In6.Cu")
		(net "M_K_CPU1_CLK_DP<0>")
	)
	(segment
		(start 194.329304 -253.710186)
		(end 194.604132 -253.435358)
		(width 0.16002)
		(layer "In6.Cu")
		(net "M_K_CPU1_CLK_DP<0>")
	)
	(segment
		(start 143.914876 -256.154428)
		(end 143.923258 -256.149602)
		(width 0.09525)
		(layer "In6.Cu")
		(net "M_K_CPU1_CLK_DP<0>")
	)
	(segment
		(start 144.475454 -256.143506)
		(end 144.485868 -256.149602)
		(width 0.09525)
		(layer "In6.Cu")
		(net "M_K_CPU1_CLK_DP<0>")
	)
	(segment
		(start 160.67913 -257.738626)
		(end 160.67913 -257.041904)
		(width 0.16002)
		(layer "In6.Cu")
		(net "M_K_CPU1_CLK_DP<0>")
	)
	(segment
		(start 159.909256 -257.738626)
		(end 160.069276 -257.898646)
		(width 0.16002)
		(layer "In6.Cu")
		(net "M_K_CPU1_CLK_DP<0>")
	)
	(segment
		(start 162.823398 -257.738626)
		(end 162.823398 -257.041904)
		(width 0.16002)
		(layer "In6.Cu")
		(net "M_K_CPU1_CLK_DP<0>")
	)
	(segment
		(start 162.823398 -257.041904)
		(end 163.160456 -256.704846)
		(width 0.16002)
		(layer "In6.Cu")
		(net "M_K_CPU1_CLK_DP<0>")
	)
	(segment
		(start 159.909256 -257.041904)
		(end 159.909256 -257.738626)
		(width 0.16002)
		(layer "In6.Cu")
		(net "M_K_CPU1_CLK_DP<0>")
	)
	(segment
		(start 189.3697 -256.577846)
		(end 189.4967 -256.704846)
		(width 0.16002)
		(layer "In6.Cu")
		(net "M_K_CPU1_CLK_DP<0>")
	)
	(segment
		(start 159.079438 -256.704846)
		(end 159.572198 -256.704846)
		(width 0.16002)
		(layer "In6.Cu")
		(net "M_K_CPU1_CLK_DP<0>")
	)
	(segment
		(start 160.67913 -257.041904)
		(end 161.016188 -256.704846)
		(width 0.16002)
		(layer "In6.Cu")
		(net "M_K_CPU1_CLK_DP<0>")
	)
	(segment
		(start 162.663378 -257.898646)
		(end 162.823398 -257.738626)
		(width 0.16002)
		(layer "In6.Cu")
		(net "M_K_CPU1_CLK_DP<0>")
	)
	(segment
		(start 142.640812 -256.089912)
		(end 142.663926 -256.176526)
		(width 0.09525)
		(layer "In6.Cu")
		(net "M_K_CPU1_CLK_DP<0>")
	)
	(segment
		(start 158.188406 -255.813814)
		(end 159.079438 -256.704846)
		(width 0.16002)
		(layer "In6.Cu")
		(net "M_K_CPU1_CLK_DP<0>")
	)
	(arc
		(start 143.546068 -256.149602)
		(mid 143.729843 -256.200374)
		(end 143.914876 -256.154428)
		(width 0.09525)
		(layer "In6.Cu")
		(net "M_K_CPU1_CLK_DP<0>")
	)
	(arc
		(start 144.863058 -256.149602)
		(mid 145.135986 -256.073788)
		(end 145.41119 -256.140966)
		(width 0.09525)
		(layer "In6.Cu")
		(net "M_K_CPU1_CLK_DP<0>")
	)
	(arc
		(start 142.663926 -256.176526)
		(mid 142.826577 -256.198786)
		(end 142.983204 -256.149602)
		(width 0.09525)
		(layer "In6.Cu")
		(net "M_K_CPU1_CLK_DP<0>")
	)
	(arc
		(start 142.983204 -256.149602)
		(mid 143.264636 -256.073847)
		(end 143.546068 -256.149602)
		(width 0.09525)
		(layer "In6.Cu")
		(net "M_K_CPU1_CLK_DP<0>")
	)
	(arc
		(start 145.425922 -256.149602)
		(mid 145.486337 -256.190182)
		(end 145.540984 -256.238248)
		(width 0.09525)
		(layer "In6.Cu")
		(net "M_K_CPU1_CLK_DP<0>")
	)
	(arc
		(start 143.923258 -256.149602)
		(mid 144.198547 -256.073881)
		(end 144.475454 -256.143506)
		(width 0.09525)
		(layer "In6.Cu")
		(net "M_K_CPU1_CLK_DP<0>")
	)
	(arc
		(start 144.49425 -256.154428)
		(mid 144.679282 -256.200342)
		(end 144.863058 -256.149602)
		(width 0.09525)
		(layer "In6.Cu")
		(net "M_K_CPU1_CLK_DP<0>")
	)
	(segment
		(start 141.857984 -256.900426)
		(end 142.324836 -256.634488)
		(width 0.14732)
		(layer "F.Cu")
		(net "M_K_CPU1_CLK_DN<0>")
	)
	(segment
		(start 159.446976 -257.007106)
		(end 159.606996 -257.167126)
		(width 0.16002)
		(layer "In6.Cu")
		(net "M_K_CPU1_CLK_DN<0>")
	)
	(segment
		(start 161.591244 -257.007106)
		(end 161.751264 -257.167126)
		(width 0.16002)
		(layer "In6.Cu")
		(net "M_K_CPU1_CLK_DN<0>")
	)
	(segment
		(start 142.47876 -256.369058)
		(end 142.579598 -256.342388)
		(width 0.09525)
		(layer "In6.Cu")
		(net "M_K_CPU1_CLK_DN<0>")
	)
	(segment
		(start 160.98139 -257.863848)
		(end 160.98139 -257.167126)
		(width 0.16002)
		(layer "In6.Cu")
		(net "M_K_CPU1_CLK_DN<0>")
	)
	(segment
		(start 160.98139 -257.167126)
		(end 161.14141 -257.007106)
		(width 0.16002)
		(layer "In6.Cu")
		(net "M_K_CPU1_CLK_DN<0>")
	)
	(segment
		(start 161.751264 -257.863848)
		(end 162.088322 -258.200906)
		(width 0.16002)
		(layer "In6.Cu")
		(net "M_K_CPU1_CLK_DN<0>")
	)
	(segment
		(start 194.331336 -254.012446)
		(end 194.604132 -254.285242)
		(width 0.16002)
		(layer "In6.Cu")
		(net "M_K_CPU1_CLK_DN<0>")
	)
	(segment
		(start 147.508468 -257.478784)
		(end 147.53209 -257.478784)
		(width 0.09525)
		(layer "In6.Cu")
		(net "M_K_CPU1_CLK_DN<0>")
	)
	(segment
		(start 143.076168 -256.309368)
		(end 143.08455 -256.304542)
		(width 0.09525)
		(layer "In6.Cu")
		(net "M_K_CPU1_CLK_DN<0>")
	)
	(segment
		(start 163.285678 -257.007106)
		(end 190.855092 -257.007106)
		(width 0.16002)
		(layer "In6.Cu")
		(net "M_K_CPU1_CLK_DN<0>")
	)
	(segment
		(start 159.944054 -258.200906)
		(end 160.644332 -258.200906)
		(width 0.16002)
		(layer "In6.Cu")
		(net "M_K_CPU1_CLK_DN<0>")
	)
	(segment
		(start 147.53209 -257.478784)
		(end 151.132286 -257.478784)
		(width 0.16002)
		(layer "In6.Cu")
		(net "M_K_CPU1_CLK_DN<0>")
	)
	(segment
		(start 152.494996 -256.116074)
		(end 158.063184 -256.116074)
		(width 0.16002)
		(layer "In6.Cu")
		(net "M_K_CPU1_CLK_DN<0>")
	)
	(segment
		(start 146.461988 -257.419856)
		(end 147.44954 -257.419856)
		(width 0.09525)
		(layer "In6.Cu")
		(net "M_K_CPU1_CLK_DN<0>")
	)
	(segment
		(start 151.132286 -257.478784)
		(end 152.494996 -256.116074)
		(width 0.16002)
		(layer "In6.Cu")
		(net "M_K_CPU1_CLK_DN<0>")
	)
	(segment
		(start 144.393158 -256.309368)
		(end 144.40789 -256.318004)
		(width 0.09525)
		(layer "In6.Cu")
		(net "M_K_CPU1_CLK_DN<0>")
	)
	(segment
		(start 162.7886 -258.200906)
		(end 163.125658 -257.863848)
		(width 0.16002)
		(layer "In6.Cu")
		(net "M_K_CPU1_CLK_DN<0>")
	)
	(segment
		(start 163.125658 -257.167126)
		(end 163.285678 -257.007106)
		(width 0.16002)
		(layer "In6.Cu")
		(net "M_K_CPU1_CLK_DN<0>")
	)
	(segment
		(start 161.751264 -257.167126)
		(end 161.751264 -257.863848)
		(width 0.16002)
		(layer "In6.Cu")
		(net "M_K_CPU1_CLK_DN<0>")
	)
	(segment
		(start 161.14141 -257.007106)
		(end 161.591244 -257.007106)
		(width 0.16002)
		(layer "In6.Cu")
		(net "M_K_CPU1_CLK_DN<0>")
	)
	(segment
		(start 158.063184 -256.116074)
		(end 158.954216 -257.007106)
		(width 0.16002)
		(layer "In6.Cu")
		(net "M_K_CPU1_CLK_DN<0>")
	)
	(segment
		(start 142.324836 -256.634488)
		(end 142.47876 -256.369058)
		(width 0.09525)
		(layer "In6.Cu")
		(net "M_K_CPU1_CLK_DN<0>")
	)
	(segment
		(start 162.088322 -258.200906)
		(end 162.7886 -258.200906)
		(width 0.16002)
		(layer "In6.Cu")
		(net "M_K_CPU1_CLK_DN<0>")
	)
	(segment
		(start 193.849752 -254.012446)
		(end 194.331336 -254.012446)
		(width 0.16002)
		(layer "In6.Cu")
		(net "M_K_CPU1_CLK_DN<0>")
	)
	(segment
		(start 159.606996 -257.863848)
		(end 159.944054 -258.200906)
		(width 0.16002)
		(layer "In6.Cu")
		(net "M_K_CPU1_CLK_DN<0>")
	)
	(segment
		(start 163.125658 -257.863848)
		(end 163.125658 -257.167126)
		(width 0.16002)
		(layer "In6.Cu")
		(net "M_K_CPU1_CLK_DN<0>")
	)
	(segment
		(start 159.606996 -257.167126)
		(end 159.606996 -257.863848)
		(width 0.16002)
		(layer "In6.Cu")
		(net "M_K_CPU1_CLK_DN<0>")
	)
	(segment
		(start 160.644332 -258.200906)
		(end 160.98139 -257.863848)
		(width 0.16002)
		(layer "In6.Cu")
		(net "M_K_CPU1_CLK_DN<0>")
	)
	(segment
		(start 147.44954 -257.419856)
		(end 147.508468 -257.478784)
		(width 0.09525)
		(layer "In6.Cu")
		(net "M_K_CPU1_CLK_DN<0>")
	)
	(segment
		(start 190.855092 -257.007106)
		(end 193.849752 -254.012446)
		(width 0.16002)
		(layer "In6.Cu")
		(net "M_K_CPU1_CLK_DN<0>")
	)
	(segment
		(start 158.954216 -257.007106)
		(end 159.446976 -257.007106)
		(width 0.16002)
		(layer "In6.Cu")
		(net "M_K_CPU1_CLK_DN<0>")
	)
	(segment
		(start 145.32102 -256.30251)
		(end 145.332958 -256.309368)
		(width 0.09525)
		(layer "In6.Cu")
		(net "M_K_CPU1_CLK_DN<0>")
	)
	(segment
		(start 145.410682 -256.36855)
		(end 146.461988 -257.419856)
		(width 0.09525)
		(layer "In6.Cu")
		(net "M_K_CPU1_CLK_DN<0>")
	)
	(arc
		(start 143.453358 -256.309368)
		(mid 143.73479 -256.385123)
		(end 144.016222 -256.309368)
		(width 0.09525)
		(layer "In6.Cu")
		(net "M_K_CPU1_CLK_DN<0>")
	)
	(arc
		(start 144.40789 -256.318004)
		(mid 144.683095 -256.385268)
		(end 144.956022 -256.309368)
		(width 0.09525)
		(layer "In6.Cu")
		(net "M_K_CPU1_CLK_DN<0>")
	)
	(arc
		(start 144.016222 -256.309368)
		(mid 144.20469 -256.258691)
		(end 144.393158 -256.309368)
		(width 0.09525)
		(layer "In6.Cu")
		(net "M_K_CPU1_CLK_DN<0>")
	)
	(arc
		(start 142.579598 -256.342388)
		(mid 142.831739 -256.383958)
		(end 143.076168 -256.309368)
		(width 0.09525)
		(layer "In6.Cu")
		(net "M_K_CPU1_CLK_DN<0>")
	)
	(arc
		(start 145.332958 -256.309368)
		(mid 145.37375 -256.336424)
		(end 145.410682 -256.36855)
		(width 0.09525)
		(layer "In6.Cu")
		(net "M_K_CPU1_CLK_DN<0>")
	)
	(arc
		(start 143.08455 -256.304542)
		(mid 143.269582 -256.258628)
		(end 143.453358 -256.309368)
		(width 0.09525)
		(layer "In6.Cu")
		(net "M_K_CPU1_CLK_DN<0>")
	)
	(arc
		(start 144.956022 -256.309368)
		(mid 145.137638 -256.258631)
		(end 145.32102 -256.30251)
		(width 0.09525)
		(layer "In6.Cu")
		(net "M_K_CPU1_CLK_DN<0>")
	)
	(segment
		(start 140.91793 -250.420378)
		(end 141.384782 -250.15444)
		(width 0.10668)
		(layer "F.Cu")
		(net "M_K_CPU1_ALERT_R_N")
	)
	(segment
		(start 163.396168 -246.210328)
		(end 188.885322 -246.210328)
		(width 0.11684)
		(layer "In6.Cu")
		(net "M_K_CPU1_ALERT_R_N")
	)
	(segment
		(start 193.035428 -243.660422)
		(end 196.882258 -243.660422)
		(width 0.11684)
		(layer "In6.Cu")
		(net "M_K_CPU1_ALERT_R_N")
	)
	(segment
		(start 142.503398 -250.481846)
		(end 142.51178 -250.47702)
		(width 0.0889)
		(layer "In6.Cu")
		(net "M_K_CPU1_ALERT_R_N")
	)
	(segment
		(start 147.779486 -250.719844)
		(end 149.02942 -250.719844)
		(width 0.11684)
		(layer "In6.Cu")
		(net "M_K_CPU1_ALERT_R_N")
	)
	(segment
		(start 191.335406 -245.360444)
		(end 193.035428 -243.660422)
		(width 0.11684)
		(layer "In6.Cu")
		(net "M_K_CPU1_ALERT_R_N")
	)
	(segment
		(start 141.230858 -250.41987)
		(end 141.25321 -250.503182)
		(width 0.0889)
		(layer "In6.Cu")
		(net "M_K_CPU1_ALERT_R_N")
	)
	(segment
		(start 144.017492 -250.47702)
		(end 144.025874 -250.481846)
		(width 0.0889)
		(layer "In6.Cu")
		(net "M_K_CPU1_ALERT_R_N")
	)
	(segment
		(start 145.743168 -250.719844)
		(end 147.779486 -250.719844)
		(width 0.0889)
		(layer "In6.Cu")
		(net "M_K_CPU1_ALERT_R_N")
	)
	(segment
		(start 196.882258 -243.660422)
		(end 197.3072 -244.085364)
		(width 0.11684)
		(layer "In6.Cu")
		(net "M_K_CPU1_ALERT_R_N")
	)
	(segment
		(start 188.885322 -246.210328)
		(end 189.735206 -245.360444)
		(width 0.11684)
		(layer "In6.Cu")
		(net "M_K_CPU1_ALERT_R_N")
	)
	(segment
		(start 149.88794 -249.861324)
		(end 159.745172 -249.861324)
		(width 0.11684)
		(layer "In6.Cu")
		(net "M_K_CPU1_ALERT_R_N")
	)
	(segment
		(start 145.14449 -250.527566)
		(end 145.55089 -250.527566)
		(width 0.0889)
		(layer "In6.Cu")
		(net "M_K_CPU1_ALERT_R_N")
	)
	(segment
		(start 149.02942 -250.719844)
		(end 149.88794 -249.861324)
		(width 0.11684)
		(layer "In6.Cu")
		(net "M_K_CPU1_ALERT_R_N")
	)
	(segment
		(start 141.384782 -250.15444)
		(end 141.230858 -250.41987)
		(width 0.0889)
		(layer "In6.Cu")
		(net "M_K_CPU1_ALERT_R_N")
	)
	(segment
		(start 144.007078 -250.470924)
		(end 144.017492 -250.47702)
		(width 0.0889)
		(layer "In6.Cu")
		(net "M_K_CPU1_ALERT_R_N")
	)
	(segment
		(start 189.735206 -245.360444)
		(end 191.335406 -245.360444)
		(width 0.11684)
		(layer "In6.Cu")
		(net "M_K_CPU1_ALERT_R_N")
	)
	(segment
		(start 145.55089 -250.527566)
		(end 145.743168 -250.719844)
		(width 0.0889)
		(layer "In6.Cu")
		(net "M_K_CPU1_ALERT_R_N")
	)
	(segment
		(start 143.077692 -250.47702)
		(end 143.086074 -250.481846)
		(width 0.0889)
		(layer "In6.Cu")
		(net "M_K_CPU1_ALERT_R_N")
	)
	(segment
		(start 159.745172 -249.861324)
		(end 163.396168 -246.210328)
		(width 0.11684)
		(layer "In6.Cu")
		(net "M_K_CPU1_ALERT_R_N")
	)
	(segment
		(start 144.391126 -250.47702)
		(end 144.40154 -250.470924)
		(width 0.0889)
		(layer "In6.Cu")
		(net "M_K_CPU1_ALERT_R_N")
	)
	(arc
		(start 142.137638 -250.47702)
		(mid 142.319889 -250.52737)
		(end 142.503398 -250.481846)
		(width 0.0889)
		(layer "In6.Cu")
		(net "M_K_CPU1_ALERT_R_N")
	)
	(arc
		(start 141.571726 -250.47702)
		(mid 141.854682 -250.400843)
		(end 142.137638 -250.47702)
		(width 0.0889)
		(layer "In6.Cu")
		(net "M_K_CPU1_ALERT_R_N")
	)
	(arc
		(start 144.025874 -250.481846)
		(mid 144.209128 -250.527219)
		(end 144.391126 -250.47702)
		(width 0.0889)
		(layer "In6.Cu")
		(net "M_K_CPU1_ALERT_R_N")
	)
	(arc
		(start 141.25321 -250.503182)
		(mid 141.415399 -250.525917)
		(end 141.571726 -250.47702)
		(width 0.0889)
		(layer "In6.Cu")
		(net "M_K_CPU1_ALERT_R_N")
	)
	(arc
		(start 144.40154 -250.470924)
		(mid 144.680226 -250.400704)
		(end 144.957292 -250.47702)
		(width 0.0889)
		(layer "In6.Cu")
		(net "M_K_CPU1_ALERT_R_N")
	)
	(arc
		(start 142.51178 -250.47702)
		(mid 142.794736 -250.400843)
		(end 143.077692 -250.47702)
		(width 0.0889)
		(layer "In6.Cu")
		(net "M_K_CPU1_ALERT_R_N")
	)
	(arc
		(start 144.957292 -250.47702)
		(mid 145.047552 -250.514648)
		(end 145.14449 -250.527566)
		(width 0.0889)
		(layer "In6.Cu")
		(net "M_K_CPU1_ALERT_R_N")
	)
	(arc
		(start 143.086074 -250.481846)
		(mid 143.269582 -250.52734)
		(end 143.451834 -250.47702)
		(width 0.0889)
		(layer "In6.Cu")
		(net "M_K_CPU1_ALERT_R_N")
	)
	(arc
		(start 143.451834 -250.47702)
		(mid 143.728647 -250.400877)
		(end 144.007078 -250.470924)
		(width 0.0889)
		(layer "In6.Cu")
		(net "M_K_CPU1_ALERT_R_N")
	)
	(via
		(at 198.7042 -244.085364)
		(size 0.4826)
		(drill 0.254)
		(layers "F.Cu" "B.Cu")
		(net "M_K_CPU1_ALERT_N")
	)
	(segment
		(start 198.1073 -244.085364)
		(end 198.7042 -244.085364)
		(width 0.10668)
		(layer "B.Cu")
		(net "M_K_CPU1_ALERT_N")
	)
	(segment
		(start 390.098026 -267.34008)
		(end 390.564878 -267.606018)
		(width 0.10668)
		(layer "F.Cu")
		(net "M_K_CPU0_SB_RSP<0>")
	)
	(segment
		(start 407.981404 -266.57046)
		(end 411.897576 -270.486632)
		(width 0.11684)
		(layer "In6.Cu")
		(net "M_K_CPU0_SB_RSP<0>")
	)
	(segment
		(start 393.766294 -267.12037)
		(end 394.746226 -266.140438)
		(width 0.0889)
		(layer "In6.Cu")
		(net "M_K_CPU0_SB_RSP<0>")
	)
	(segment
		(start 411.897576 -270.486632)
		(end 413.395922 -270.486632)
		(width 0.11684)
		(layer "In6.Cu")
		(net "M_K_CPU0_SB_RSP<0>")
	)
	(segment
		(start 430.110138 -270.010128)
		(end 446.219326 -270.010128)
		(width 0.11684)
		(layer "In6.Cu")
		(net "M_K_CPU0_SB_RSP<0>")
	)
	(segment
		(start 413.395922 -270.486632)
		(end 414.546288 -270.010128)
		(width 0.11684)
		(layer "In6.Cu")
		(net "M_K_CPU0_SB_RSP<0>")
	)
	(segment
		(start 419.857682 -270.860266)
		(end 420.672514 -270.860266)
		(width 0.11684)
		(layer "In6.Cu")
		(net "M_K_CPU0_SB_RSP<0>")
	)
	(segment
		(start 393.766294 -267.598906)
		(end 393.766294 -267.12037)
		(width 0.0889)
		(layer "In6.Cu")
		(net "M_K_CPU0_SB_RSP<0>")
	)
	(segment
		(start 390.564878 -267.606018)
		(end 390.718802 -267.871448)
		(width 0.0889)
		(layer "In6.Cu")
		(net "M_K_CPU0_SB_RSP<0>")
	)
	(segment
		(start 395.552676 -266.57046)
		(end 395.980412 -266.57046)
		(width 0.0889)
		(layer "In6.Cu")
		(net "M_K_CPU0_SB_RSP<0>")
	)
	(segment
		(start 446.219326 -270.010128)
		(end 446.644268 -270.43507)
		(width 0.11684)
		(layer "In6.Cu")
		(net "M_K_CPU0_SB_RSP<0>")
	)
	(segment
		(start 417.805108 -270.010128)
		(end 419.857682 -270.860266)
		(width 0.11684)
		(layer "In6.Cu")
		(net "M_K_CPU0_SB_RSP<0>")
	)
	(segment
		(start 392.24712 -267.922502)
		(end 392.257534 -267.928598)
		(width 0.0889)
		(layer "In6.Cu")
		(net "M_K_CPU0_SB_RSP<0>")
	)
	(segment
		(start 414.546288 -270.010128)
		(end 417.805108 -270.010128)
		(width 0.11684)
		(layer "In6.Cu")
		(net "M_K_CPU0_SB_RSP<0>")
	)
	(segment
		(start 395.122654 -266.140438)
		(end 395.552676 -266.57046)
		(width 0.0889)
		(layer "In6.Cu")
		(net "M_K_CPU0_SB_RSP<0>")
	)
	(segment
		(start 425.35221 -270.010128)
		(end 427.404784 -270.860266)
		(width 0.11684)
		(layer "In6.Cu")
		(net "M_K_CPU0_SB_RSP<0>")
	)
	(segment
		(start 395.980412 -266.57046)
		(end 407.981404 -266.57046)
		(width 0.11684)
		(layer "In6.Cu")
		(net "M_K_CPU0_SB_RSP<0>")
	)
	(segment
		(start 390.718802 -267.871448)
		(end 390.814814 -267.896848)
		(width 0.0889)
		(layer "In6.Cu")
		(net "M_K_CPU0_SB_RSP<0>")
	)
	(segment
		(start 422.725088 -270.010128)
		(end 425.35221 -270.010128)
		(width 0.11684)
		(layer "In6.Cu")
		(net "M_K_CPU0_SB_RSP<0>")
	)
	(segment
		(start 428.057564 -270.860266)
		(end 430.110138 -270.010128)
		(width 0.11684)
		(layer "In6.Cu")
		(net "M_K_CPU0_SB_RSP<0>")
	)
	(segment
		(start 394.746226 -266.140438)
		(end 395.122654 -266.140438)
		(width 0.0889)
		(layer "In6.Cu")
		(net "M_K_CPU0_SB_RSP<0>")
	)
	(segment
		(start 391.317734 -267.928598)
		(end 391.326116 -267.933424)
		(width 0.0889)
		(layer "In6.Cu")
		(net "M_K_CPU0_SB_RSP<0>")
	)
	(segment
		(start 392.631422 -267.928598)
		(end 392.641836 -267.922502)
		(width 0.0889)
		(layer "In6.Cu")
		(net "M_K_CPU0_SB_RSP<0>")
	)
	(segment
		(start 420.672514 -270.860266)
		(end 422.725088 -270.010128)
		(width 0.11684)
		(layer "In6.Cu")
		(net "M_K_CPU0_SB_RSP<0>")
	)
	(segment
		(start 427.404784 -270.860266)
		(end 428.057564 -270.860266)
		(width 0.11684)
		(layer "In6.Cu")
		(net "M_K_CPU0_SB_RSP<0>")
	)
	(arc
		(start 391.326116 -267.933424)
		(mid 391.509624 -267.978918)
		(end 391.691876 -267.928598)
		(width 0.0889)
		(layer "In6.Cu")
		(net "M_K_CPU0_SB_RSP<0>")
	)
	(arc
		(start 393.503658 -267.952982)
		(mid 393.555203 -267.925215)
		(end 393.602718 -267.891006)
		(width 0.0889)
		(layer "In6.Cu")
		(net "M_K_CPU0_SB_RSP<0>")
	)
	(arc
		(start 390.814814 -267.896848)
		(mid 391.070022 -267.853371)
		(end 391.317734 -267.928598)
		(width 0.0889)
		(layer "In6.Cu")
		(net "M_K_CPU0_SB_RSP<0>")
	)
	(arc
		(start 393.602718 -267.891006)
		(mid 393.711867 -267.76029)
		(end 393.766294 -267.598906)
		(width 0.0889)
		(layer "In6.Cu")
		(net "M_K_CPU0_SB_RSP<0>")
	)
	(arc
		(start 392.641836 -267.922502)
		(mid 392.920522 -267.852282)
		(end 393.197588 -267.928598)
		(width 0.0889)
		(layer "In6.Cu")
		(net "M_K_CPU0_SB_RSP<0>")
	)
	(arc
		(start 391.691876 -267.928598)
		(mid 391.968689 -267.852455)
		(end 392.24712 -267.922502)
		(width 0.0889)
		(layer "In6.Cu")
		(net "M_K_CPU0_SB_RSP<0>")
	)
	(arc
		(start 393.384786 -267.97889)
		(mid 393.445618 -267.97234)
		(end 393.503658 -267.952982)
		(width 0.0889)
		(layer "In6.Cu")
		(net "M_K_CPU0_SB_RSP<0>")
	)
	(arc
		(start 393.197588 -267.928598)
		(mid 393.287864 -267.966103)
		(end 393.384786 -267.97889)
		(width 0.0889)
		(layer "In6.Cu")
		(net "M_K_CPU0_SB_RSP<0>")
	)
	(arc
		(start 392.257534 -267.928598)
		(mid 392.444478 -267.978853)
		(end 392.631422 -267.928598)
		(width 0.0889)
		(layer "In6.Cu")
		(net "M_K_CPU0_SB_RSP<0>")
	)
	(segment
		(start 388.688072 -264.910062)
		(end 389.154924 -265.176)
		(width 0.10668)
		(layer "F.Cu")
		(net "M_K_CPU0_SB_PAR")
	)
	(segment
		(start 418.714428 -266.610084)
		(end 419.564566 -267.460222)
		(width 0.14478)
		(layer "In6.Cu")
		(net "M_K_CPU0_SB_PAR")
	)
	(segment
		(start 389.308848 -265.44143)
		(end 389.40486 -265.46683)
		(width 0.0889)
		(layer "In6.Cu")
		(net "M_K_CPU0_SB_PAR")
	)
	(segment
		(start 389.154924 -265.176)
		(end 389.308848 -265.44143)
		(width 0.0889)
		(layer "In6.Cu")
		(net "M_K_CPU0_SB_PAR")
	)
	(segment
		(start 442.119258 -266.610084)
		(end 442.5442 -267.035026)
		(width 0.14478)
		(layer "In6.Cu")
		(net "M_K_CPU0_SB_PAR")
	)
	(segment
		(start 389.90778 -265.49858)
		(end 389.916162 -265.503406)
		(width 0.0889)
		(layer "In6.Cu")
		(net "M_K_CPU0_SB_PAR")
	)
	(segment
		(start 427.184312 -267.460222)
		(end 429.178212 -267.460222)
		(width 0.14478)
		(layer "In6.Cu")
		(net "M_K_CPU0_SB_PAR")
	)
	(segment
		(start 412.920688 -267.460222)
		(end 413.770826 -266.610084)
		(width 0.14478)
		(layer "In6.Cu")
		(net "M_K_CPU0_SB_PAR")
	)
	(segment
		(start 413.770826 -266.610084)
		(end 418.714428 -266.610084)
		(width 0.14478)
		(layer "In6.Cu")
		(net "M_K_CPU0_SB_PAR")
	)
	(segment
		(start 430.02835 -266.610084)
		(end 442.119258 -266.610084)
		(width 0.14478)
		(layer "In6.Cu")
		(net "M_K_CPU0_SB_PAR")
	)
	(segment
		(start 392.149838 -265.505438)
		(end 392.161522 -265.49858)
		(width 0.0889)
		(layer "In6.Cu")
		(net "M_K_CPU0_SB_PAR")
	)
	(segment
		(start 395.64564 -264.79373)
		(end 395.965934 -264.79373)
		(width 0.0889)
		(layer "In6.Cu")
		(net "M_K_CPU0_SB_PAR")
	)
	(segment
		(start 422.484296 -266.610084)
		(end 426.334174 -266.610084)
		(width 0.14478)
		(layer "In6.Cu")
		(net "M_K_CPU0_SB_PAR")
	)
	(segment
		(start 395.965934 -264.79373)
		(end 408.998674 -264.79373)
		(width 0.14478)
		(layer "In6.Cu")
		(net "M_K_CPU0_SB_PAR")
	)
	(segment
		(start 393.101576 -265.49858)
		(end 394.052044 -264.544302)
		(width 0.0889)
		(layer "In6.Cu")
		(net "M_K_CPU0_SB_PAR")
	)
	(segment
		(start 426.334174 -266.610084)
		(end 427.184312 -267.460222)
		(width 0.14478)
		(layer "In6.Cu")
		(net "M_K_CPU0_SB_PAR")
	)
	(segment
		(start 421.634158 -267.460222)
		(end 422.484296 -266.610084)
		(width 0.14478)
		(layer "In6.Cu")
		(net "M_K_CPU0_SB_PAR")
	)
	(segment
		(start 395.396212 -264.544302)
		(end 395.64564 -264.79373)
		(width 0.0889)
		(layer "In6.Cu")
		(net "M_K_CPU0_SB_PAR")
	)
	(segment
		(start 429.178212 -267.460222)
		(end 430.02835 -266.610084)
		(width 0.14478)
		(layer "In6.Cu")
		(net "M_K_CPU0_SB_PAR")
	)
	(segment
		(start 392.161522 -265.49858)
		(end 392.171936 -265.492484)
		(width 0.0889)
		(layer "In6.Cu")
		(net "M_K_CPU0_SB_PAR")
	)
	(segment
		(start 408.998674 -264.79373)
		(end 411.665166 -267.460222)
		(width 0.14478)
		(layer "In6.Cu")
		(net "M_K_CPU0_SB_PAR")
	)
	(segment
		(start 419.564566 -267.460222)
		(end 421.634158 -267.460222)
		(width 0.14478)
		(layer "In6.Cu")
		(net "M_K_CPU0_SB_PAR")
	)
	(segment
		(start 392.72718 -265.49858)
		(end 392.738864 -265.505438)
		(width 0.0889)
		(layer "In6.Cu")
		(net "M_K_CPU0_SB_PAR")
	)
	(segment
		(start 394.052044 -264.544302)
		(end 395.396212 -264.544302)
		(width 0.0889)
		(layer "In6.Cu")
		(net "M_K_CPU0_SB_PAR")
	)
	(segment
		(start 411.665166 -267.460222)
		(end 412.920688 -267.460222)
		(width 0.14478)
		(layer "In6.Cu")
		(net "M_K_CPU0_SB_PAR")
	)
	(arc
		(start 391.221722 -265.49858)
		(mid 391.504678 -265.422403)
		(end 391.787634 -265.49858)
		(width 0.0889)
		(layer "In6.Cu")
		(net "M_K_CPU0_SB_PAR")
	)
	(arc
		(start 390.847834 -265.49858)
		(mid 391.034778 -265.548835)
		(end 391.221722 -265.49858)
		(width 0.0889)
		(layer "In6.Cu")
		(net "M_K_CPU0_SB_PAR")
	)
	(arc
		(start 389.40486 -265.46683)
		(mid 389.660068 -265.423353)
		(end 389.90778 -265.49858)
		(width 0.0889)
		(layer "In6.Cu")
		(net "M_K_CPU0_SB_PAR")
	)
	(arc
		(start 392.171936 -265.492484)
		(mid 392.450368 -265.422386)
		(end 392.72718 -265.49858)
		(width 0.0889)
		(layer "In6.Cu")
		(net "M_K_CPU0_SB_PAR")
	)
	(arc
		(start 392.738864 -265.505438)
		(mid 392.921119 -265.549091)
		(end 393.101576 -265.49858)
		(width 0.0889)
		(layer "In6.Cu")
		(net "M_K_CPU0_SB_PAR")
	)
	(arc
		(start 389.916162 -265.503406)
		(mid 390.09967 -265.5489)
		(end 390.281922 -265.49858)
		(width 0.0889)
		(layer "In6.Cu")
		(net "M_K_CPU0_SB_PAR")
	)
	(arc
		(start 390.281922 -265.49858)
		(mid 390.564878 -265.422403)
		(end 390.847834 -265.49858)
		(width 0.0889)
		(layer "In6.Cu")
		(net "M_K_CPU0_SB_PAR")
	)
	(arc
		(start 391.787634 -265.49858)
		(mid 391.967839 -265.548897)
		(end 392.149838 -265.505438)
		(width 0.0889)
		(layer "In6.Cu")
		(net "M_K_CPU0_SB_PAR")
	)
	(segment
		(start 390.098026 -270.580104)
		(end 390.564878 -270.846042)
		(width 0.12954)
		(layer "F.Cu")
		(net "M_K_CPU0_SB_DQS_DP<9>")
	)
	(segment
		(start 444.349886 -275.808948)
		(end 446.370456 -275.808948)
		(width 0.16002)
		(layer "In6.Cu")
		(net "M_K_CPU0_SB_DQS_DP<9>")
	)
	(segment
		(start 437.864758 -275.149564)
		(end 438.204356 -274.809966)
		(width 0.16002)
		(layer "In6.Cu")
		(net "M_K_CPU0_SB_DQS_DP<9>")
	)
	(segment
		(start 440.36234 -274.809966)
		(end 440.93638 -275.384006)
		(width 0.16002)
		(layer "In6.Cu")
		(net "M_K_CPU0_SB_DQS_DP<9>")
	)
	(segment
		(start 430.660302 -274.809966)
		(end 432.623468 -274.809966)
		(width 0.16002)
		(layer "In6.Cu")
		(net "M_K_CPU0_SB_DQS_DP<9>")
	)
	(segment
		(start 432.623468 -274.809966)
		(end 433.473352 -275.65985)
		(width 0.16002)
		(layer "In6.Cu")
		(net "M_K_CPU0_SB_DQS_DP<9>")
	)
	(segment
		(start 438.204356 -274.809966)
		(end 440.36234 -274.809966)
		(width 0.16002)
		(layer "In6.Cu")
		(net "M_K_CPU0_SB_DQS_DP<9>")
	)
	(segment
		(start 433.473352 -275.65985)
		(end 435.883304 -275.65985)
		(width 0.16002)
		(layer "In6.Cu")
		(net "M_K_CPU0_SB_DQS_DP<9>")
	)
	(segment
		(start 392.84656 -270.68272)
		(end 392.84656 -270.682466)
		(width 0.09525)
		(layer "In6.Cu")
		(net "M_K_CPU0_SB_DQS_DP<9>")
	)
	(segment
		(start 395.369288 -269.311882)
		(end 395.77645 -269.311882)
		(width 0.09525)
		(layer "In6.Cu")
		(net "M_K_CPU0_SB_DQS_DP<9>")
	)
	(segment
		(start 393.03833 -270.422116)
		(end 393.223496 -270.295116)
		(width 0.09525)
		(layer "In6.Cu")
		(net "M_K_CPU0_SB_DQS_DP<9>")
	)
	(segment
		(start 412.955232 -276.000464)
		(end 413.993076 -276.000464)
		(width 0.16002)
		(layer "In6.Cu")
		(net "M_K_CPU0_SB_DQS_DP<9>")
	)
	(segment
		(start 393.269724 -270.269208)
		(end 393.629388 -270.112236)
		(width 0.09525)
		(layer "In6.Cu")
		(net "M_K_CPU0_SB_DQS_DP<9>")
	)
	(segment
		(start 428.679864 -276.000464)
		(end 429.081184 -276.000464)
		(width 0.16002)
		(layer "In6.Cu")
		(net "M_K_CPU0_SB_DQS_DP<9>")
	)
	(segment
		(start 395.835632 -269.2527)
		(end 395.859254 -269.2527)
		(width 0.09525)
		(layer "In6.Cu")
		(net "M_K_CPU0_SB_DQS_DP<9>")
	)
	(segment
		(start 395.235938 -269.178532)
		(end 395.369288 -269.311882)
		(width 0.09525)
		(layer "In6.Cu")
		(net "M_K_CPU0_SB_DQS_DP<9>")
	)
	(segment
		(start 423.116248 -274.809966)
		(end 425.079414 -274.809966)
		(width 0.16002)
		(layer "In6.Cu")
		(net "M_K_CPU0_SB_DQS_DP<9>")
	)
	(segment
		(start 393.03833 -270.421862)
		(end 393.03833 -270.422116)
		(width 0.09525)
		(layer "In6.Cu")
		(net "M_K_CPU0_SB_DQS_DP<9>")
	)
	(segment
		(start 392.84656 -270.682466)
		(end 392.846814 -270.682466)
		(width 0.09525)
		(layer "In6.Cu")
		(net "M_K_CPU0_SB_DQS_DP<9>")
	)
	(segment
		(start 391.31621 -271.171162)
		(end 391.324592 -271.175988)
		(width 0.09525)
		(layer "In6.Cu")
		(net "M_K_CPU0_SB_DQS_DP<9>")
	)
	(segment
		(start 422.77665 -275.149564)
		(end 423.116248 -274.809966)
		(width 0.16002)
		(layer "In6.Cu")
		(net "M_K_CPU0_SB_DQS_DP<9>")
	)
	(segment
		(start 418.385244 -275.65985)
		(end 420.795196 -275.65985)
		(width 0.16002)
		(layer "In6.Cu")
		(net "M_K_CPU0_SB_DQS_DP<9>")
	)
	(segment
		(start 429.932084 -275.149564)
		(end 430.320704 -275.149564)
		(width 0.16002)
		(layer "In6.Cu")
		(net "M_K_CPU0_SB_DQS_DP<9>")
	)
	(segment
		(start 436.223918 -276.000464)
		(end 436.625238 -276.000464)
		(width 0.16002)
		(layer "In6.Cu")
		(net "M_K_CPU0_SB_DQS_DP<9>")
	)
	(segment
		(start 392.618722 -271.179036)
		(end 392.6332 -271.170654)
		(width 0.09525)
		(layer "In6.Cu")
		(net "M_K_CPU0_SB_DQS_DP<9>")
	)
	(segment
		(start 437.476138 -275.149564)
		(end 437.864758 -275.149564)
		(width 0.16002)
		(layer "In6.Cu")
		(net "M_K_CPU0_SB_DQS_DP<9>")
	)
	(segment
		(start 443.147196 -275.384006)
		(end 443.771274 -276.008084)
		(width 0.16002)
		(layer "In6.Cu")
		(net "M_K_CPU0_SB_DQS_DP<9>")
	)
	(segment
		(start 393.629388 -270.112236)
		(end 394.562838 -269.178532)
		(width 0.09525)
		(layer "In6.Cu")
		(net "M_K_CPU0_SB_DQS_DP<9>")
	)
	(segment
		(start 394.562838 -269.178532)
		(end 395.235938 -269.178532)
		(width 0.09525)
		(layer "In6.Cu")
		(net "M_K_CPU0_SB_DQS_DP<9>")
	)
	(segment
		(start 417.53536 -274.809966)
		(end 418.385244 -275.65985)
		(width 0.16002)
		(layer "In6.Cu")
		(net "M_K_CPU0_SB_DQS_DP<9>")
	)
	(segment
		(start 414.843976 -275.149564)
		(end 415.232596 -275.149564)
		(width 0.16002)
		(layer "In6.Cu")
		(net "M_K_CPU0_SB_DQS_DP<9>")
	)
	(segment
		(start 390.564878 -270.846042)
		(end 390.718802 -271.111472)
		(width 0.09525)
		(layer "In6.Cu")
		(net "M_K_CPU0_SB_DQS_DP<9>")
	)
	(segment
		(start 415.232596 -275.149564)
		(end 415.572194 -274.809966)
		(width 0.16002)
		(layer "In6.Cu")
		(net "M_K_CPU0_SB_DQS_DP<9>")
	)
	(segment
		(start 395.859254 -269.2527)
		(end 406.207468 -269.2527)
		(width 0.16002)
		(layer "In6.Cu")
		(net "M_K_CPU0_SB_DQS_DP<9>")
	)
	(segment
		(start 425.929298 -275.65985)
		(end 428.33925 -275.65985)
		(width 0.16002)
		(layer "In6.Cu")
		(net "M_K_CPU0_SB_DQS_DP<9>")
	)
	(segment
		(start 393.022328 -270.433292)
		(end 393.023852 -270.431768)
		(width 0.09525)
		(layer "In6.Cu")
		(net "M_K_CPU0_SB_DQS_DP<9>")
	)
	(segment
		(start 422.38803 -275.149564)
		(end 422.77665 -275.149564)
		(width 0.16002)
		(layer "In6.Cu")
		(net "M_K_CPU0_SB_DQS_DP<9>")
	)
	(segment
		(start 436.625238 -276.000464)
		(end 437.476138 -275.149564)
		(width 0.16002)
		(layer "In6.Cu")
		(net "M_K_CPU0_SB_DQS_DP<9>")
	)
	(segment
		(start 406.207468 -269.2527)
		(end 412.955232 -276.000464)
		(width 0.16002)
		(layer "In6.Cu")
		(net "M_K_CPU0_SB_DQS_DP<9>")
	)
	(segment
		(start 429.081184 -276.000464)
		(end 429.932084 -275.149564)
		(width 0.16002)
		(layer "In6.Cu")
		(net "M_K_CPU0_SB_DQS_DP<9>")
	)
	(segment
		(start 421.13581 -276.000464)
		(end 421.53713 -276.000464)
		(width 0.16002)
		(layer "In6.Cu")
		(net "M_K_CPU0_SB_DQS_DP<9>")
	)
	(segment
		(start 428.33925 -275.65985)
		(end 428.679864 -276.000464)
		(width 0.16002)
		(layer "In6.Cu")
		(net "M_K_CPU0_SB_DQS_DP<9>")
	)
	(segment
		(start 421.53713 -276.000464)
		(end 422.38803 -275.149564)
		(width 0.16002)
		(layer "In6.Cu")
		(net "M_K_CPU0_SB_DQS_DP<9>")
	)
	(segment
		(start 425.079414 -274.809966)
		(end 425.929298 -275.65985)
		(width 0.16002)
		(layer "In6.Cu")
		(net "M_K_CPU0_SB_DQS_DP<9>")
	)
	(segment
		(start 392.6332 -271.170654)
		(end 392.669268 -271.149826)
		(width 0.09525)
		(layer "In6.Cu")
		(net "M_K_CPU0_SB_DQS_DP<9>")
	)
	(segment
		(start 395.77645 -269.311882)
		(end 395.835632 -269.2527)
		(width 0.09525)
		(layer "In6.Cu")
		(net "M_K_CPU0_SB_DQS_DP<9>")
	)
	(segment
		(start 444.15075 -276.008084)
		(end 444.349886 -275.808948)
		(width 0.16002)
		(layer "In6.Cu")
		(net "M_K_CPU0_SB_DQS_DP<9>")
	)
	(segment
		(start 420.795196 -275.65985)
		(end 421.13581 -276.000464)
		(width 0.16002)
		(layer "In6.Cu")
		(net "M_K_CPU0_SB_DQS_DP<9>")
	)
	(segment
		(start 390.718802 -271.111472)
		(end 390.81964 -271.138142)
		(width 0.09525)
		(layer "In6.Cu")
		(net "M_K_CPU0_SB_DQS_DP<9>")
	)
	(segment
		(start 415.572194 -274.809966)
		(end 417.53536 -274.809966)
		(width 0.16002)
		(layer "In6.Cu")
		(net "M_K_CPU0_SB_DQS_DP<9>")
	)
	(segment
		(start 443.771274 -276.008084)
		(end 444.15075 -276.008084)
		(width 0.16002)
		(layer "In6.Cu")
		(net "M_K_CPU0_SB_DQS_DP<9>")
	)
	(segment
		(start 440.93638 -275.384006)
		(end 443.147196 -275.384006)
		(width 0.16002)
		(layer "In6.Cu")
		(net "M_K_CPU0_SB_DQS_DP<9>")
	)
	(segment
		(start 413.993076 -276.000464)
		(end 414.843976 -275.149564)
		(width 0.16002)
		(layer "In6.Cu")
		(net "M_K_CPU0_SB_DQS_DP<9>")
	)
	(segment
		(start 446.370456 -275.808948)
		(end 446.644268 -275.535136)
		(width 0.16002)
		(layer "In6.Cu")
		(net "M_K_CPU0_SB_DQS_DP<9>")
	)
	(segment
		(start 435.883304 -275.65985)
		(end 436.223918 -276.000464)
		(width 0.16002)
		(layer "In6.Cu")
		(net "M_K_CPU0_SB_DQS_DP<9>")
	)
	(segment
		(start 392.617706 -271.179544)
		(end 392.618722 -271.179036)
		(width 0.09525)
		(layer "In6.Cu")
		(net "M_K_CPU0_SB_DQS_DP<9>")
	)
	(segment
		(start 430.320704 -275.149564)
		(end 430.660302 -274.809966)
		(width 0.16002)
		(layer "In6.Cu")
		(net "M_K_CPU0_SB_DQS_DP<9>")
	)
	(arc
		(start 392.256264 -271.171162)
		(mid 392.435923 -271.221735)
		(end 392.617706 -271.179544)
		(width 0.09525)
		(layer "In6.Cu")
		(net "M_K_CPU0_SB_DQS_DP<9>")
	)
	(arc
		(start 393.023852 -270.431768)
		(mid 393.031083 -270.426803)
		(end 393.03833 -270.421862)
		(width 0.09525)
		(layer "In6.Cu")
		(net "M_K_CPU0_SB_DQS_DP<9>")
	)
	(arc
		(start 391.6934 -271.171162)
		(mid 391.974832 -271.095407)
		(end 392.256264 -271.171162)
		(width 0.09525)
		(layer "In6.Cu")
		(net "M_K_CPU0_SB_DQS_DP<9>")
	)
	(arc
		(start 392.669268 -271.149826)
		(mid 392.781943 -271.016138)
		(end 392.82243 -270.846042)
		(width 0.09525)
		(layer "In6.Cu")
		(net "M_K_CPU0_SB_DQS_DP<9>")
	)
	(arc
		(start 393.223496 -270.295116)
		(mid 393.245993 -270.28106)
		(end 393.269724 -270.269208)
		(width 0.09525)
		(layer "In6.Cu")
		(net "M_K_CPU0_SB_DQS_DP<9>")
	)
	(arc
		(start 392.82243 -270.846042)
		(mid 392.828484 -270.763494)
		(end 392.84656 -270.68272)
		(width 0.09525)
		(layer "In6.Cu")
		(net "M_K_CPU0_SB_DQS_DP<9>")
	)
	(arc
		(start 391.324592 -271.175988)
		(mid 391.509624 -271.221902)
		(end 391.6934 -271.171162)
		(width 0.09525)
		(layer "In6.Cu")
		(net "M_K_CPU0_SB_DQS_DP<9>")
	)
	(arc
		(start 392.846814 -270.682466)
		(mid 392.91467 -270.543857)
		(end 393.022328 -270.433292)
		(width 0.09525)
		(layer "In6.Cu")
		(net "M_K_CPU0_SB_DQS_DP<9>")
	)
	(arc
		(start 390.81964 -271.138142)
		(mid 391.071781 -271.096572)
		(end 391.31621 -271.171162)
		(width 0.09525)
		(layer "In6.Cu")
		(net "M_K_CPU0_SB_DQS_DP<9>")
	)
	(segment
		(start 389.157972 -291.640006)
		(end 389.624824 -291.905944)
		(width 0.12954)
		(layer "F.Cu")
		(net "M_K_CPU0_SB_DQS_DP<8>")
	)
	(segment
		(start 405.66213 -310.247284)
		(end 405.88819 -310.247284)
		(width 0.16002)
		(layer "In6.Cu")
		(net "M_K_CPU0_SB_DQS_DP<8>")
	)
	(segment
		(start 391.31621 -291.580824)
		(end 391.324592 -291.575998)
		(width 0.09525)
		(layer "In6.Cu")
		(net "M_K_CPU0_SB_DQS_DP<8>")
	)
	(segment
		(start 404.677118 -309.906924)
		(end 405.101552 -310.331358)
		(width 0.16002)
		(layer "In6.Cu")
		(net "M_K_CPU0_SB_DQS_DP<8>")
	)
	(segment
		(start 438.298336 -314.19292)
		(end 438.615582 -314.510166)
		(width 0.16002)
		(layer "In6.Cu")
		(net "M_K_CPU0_SB_DQS_DP<8>")
	)
	(segment
		(start 405.88819 -310.247284)
		(end 406.134824 -310.493918)
		(width 0.16002)
		(layer "In6.Cu")
		(net "M_K_CPU0_SB_DQS_DP<8>")
	)
	(segment
		(start 393.771882 -293.39921)
		(end 393.772136 -293.398956)
		(width 0.09525)
		(layer "In6.Cu")
		(net "M_K_CPU0_SB_DQS_DP<8>")
	)
	(segment
		(start 395.351 -295.753282)
		(end 395.511528 -295.913048)
		(width 0.16002)
		(layer "In6.Cu")
		(net "M_K_CPU0_SB_DQS_DP<8>")
	)
	(segment
		(start 421.614092 -314.98032)
		(end 422.401492 -314.19292)
		(width 0.16002)
		(layer "In6.Cu")
		(net "M_K_CPU0_SB_DQS_DP<8>")
	)
	(segment
		(start 441.317888 -314.454032)
		(end 441.410852 -314.361068)
		(width 0.16002)
		(layer "In6.Cu")
		(net "M_K_CPU0_SB_DQS_DP<8>")
	)
	(segment
		(start 407.261822 -311.620916)
		(end 407.508456 -311.86755)
		(width 0.16002)
		(layer "In6.Cu")
		(net "M_K_CPU0_SB_DQS_DP<8>")
	)
	(segment
		(start 428.173642 -315.360304)
		(end 428.553626 -314.98032)
		(width 0.16002)
		(layer "In6.Cu")
		(net "M_K_CPU0_SB_DQS_DP<8>")
	)
	(segment
		(start 408.635454 -312.994548)
		(end 408.882088 -313.241182)
		(width 0.16002)
		(layer "In6.Cu")
		(net "M_K_CPU0_SB_DQS_DP<8>")
	)
	(segment
		(start 392.25601 -291.580824)
		(end 392.264392 -291.575998)
		(width 0.09525)
		(layer "In6.Cu")
		(net "M_K_CPU0_SB_DQS_DP<8>")
	)
	(segment
		(start 422.401492 -314.19292)
		(end 423.210228 -314.19292)
		(width 0.16002)
		(layer "In6.Cu")
		(net "M_K_CPU0_SB_DQS_DP<8>")
	)
	(segment
		(start 418.465254 -314.510166)
		(end 419.315392 -315.360304)
		(width 0.16002)
		(layer "In6.Cu")
		(net "M_K_CPU0_SB_DQS_DP<8>")
	)
	(segment
		(start 436.09768 -314.98032)
		(end 436.7022 -314.98032)
		(width 0.16002)
		(layer "In6.Cu")
		(net "M_K_CPU0_SB_DQS_DP<8>")
	)
	(segment
		(start 395.334236 -295.736518)
		(end 395.351 -295.753282)
		(width 0.09525)
		(layer "In6.Cu")
		(net "M_K_CPU0_SB_DQS_DP<8>")
	)
	(segment
		(start 392.245596 -291.58692)
		(end 392.25601 -291.580824)
		(width 0.09525)
		(layer "In6.Cu")
		(net "M_K_CPU0_SB_DQS_DP<8>")
	)
	(segment
		(start 408.409394 -312.994548)
		(end 408.635454 -312.994548)
		(width 0.16002)
		(layer "In6.Cu")
		(net "M_K_CPU0_SB_DQS_DP<8>")
	)
	(segment
		(start 390.744964 -291.575998)
		(end 390.753346 -291.580824)
		(width 0.09525)
		(layer "In6.Cu")
		(net "M_K_CPU0_SB_DQS_DP<8>")
	)
	(segment
		(start 409.783026 -314.36818)
		(end 410.009086 -314.36818)
		(width 0.16002)
		(layer "In6.Cu")
		(net "M_K_CPU0_SB_DQS_DP<8>")
	)
	(segment
		(start 394.242036 -294.336216)
		(end 394.242036 -294.561514)
		(width 0.09525)
		(layer "In6.Cu")
		(net "M_K_CPU0_SB_DQS_DP<8>")
	)
	(segment
		(start 421.009572 -314.98032)
		(end 421.614092 -314.98032)
		(width 0.16002)
		(layer "In6.Cu")
		(net "M_K_CPU0_SB_DQS_DP<8>")
	)
	(segment
		(start 406.05075 -310.804052)
		(end 406.05075 -311.280556)
		(width 0.16002)
		(layer "In6.Cu")
		(net "M_K_CPU0_SB_DQS_DP<8>")
	)
	(segment
		(start 404.761192 -309.120286)
		(end 404.761192 -309.346346)
		(width 0.16002)
		(layer "In6.Cu")
		(net "M_K_CPU0_SB_DQS_DP<8>")
	)
	(segment
		(start 440.769756 -314.454032)
		(end 441.317888 -314.454032)
		(width 0.16002)
		(layer "In6.Cu")
		(net "M_K_CPU0_SB_DQS_DP<8>")
	)
	(segment
		(start 389.624824 -291.905944)
		(end 389.4709 -291.640514)
		(width 0.09525)
		(layer "In6.Cu")
		(net "M_K_CPU0_SB_DQS_DP<8>")
	)
	(segment
		(start 428.553626 -314.98032)
		(end 429.158146 -314.98032)
		(width 0.16002)
		(layer "In6.Cu")
		(net "M_K_CPU0_SB_DQS_DP<8>")
	)
	(segment
		(start 440.047634 -314.510166)
		(end 440.196732 -314.361068)
		(width 0.16002)
		(layer "In6.Cu")
		(net "M_K_CPU0_SB_DQS_DP<8>")
	)
	(segment
		(start 409.222448 -314.452254)
		(end 409.698952 -314.452254)
		(width 0.16002)
		(layer "In6.Cu")
		(net "M_K_CPU0_SB_DQS_DP<8>")
	)
	(segment
		(start 395.334236 -295.653714)
		(end 395.334236 -295.736518)
		(width 0.09525)
		(layer "In6.Cu")
		(net "M_K_CPU0_SB_DQS_DP<8>")
	)
	(segment
		(start 407.848816 -313.078622)
		(end 408.32532 -313.078622)
		(width 0.16002)
		(layer "In6.Cu")
		(net "M_K_CPU0_SB_DQS_DP<8>")
	)
	(segment
		(start 406.134824 -310.493918)
		(end 406.134824 -310.719978)
		(width 0.16002)
		(layer "In6.Cu")
		(net "M_K_CPU0_SB_DQS_DP<8>")
	)
	(segment
		(start 406.134824 -310.719978)
		(end 406.05075 -310.804052)
		(width 0.16002)
		(layer "In6.Cu")
		(net "M_K_CPU0_SB_DQS_DP<8>")
	)
	(segment
		(start 404.761192 -309.346346)
		(end 404.677118 -309.43042)
		(width 0.16002)
		(layer "In6.Cu")
		(net "M_K_CPU0_SB_DQS_DP<8>")
	)
	(segment
		(start 436.7022 -314.98032)
		(end 437.4896 -314.19292)
		(width 0.16002)
		(layer "In6.Cu")
		(net "M_K_CPU0_SB_DQS_DP<8>")
	)
	(segment
		(start 406.951688 -311.70499)
		(end 407.035762 -311.620916)
		(width 0.16002)
		(layer "In6.Cu")
		(net "M_K_CPU0_SB_DQS_DP<8>")
	)
	(segment
		(start 407.508456 -312.09361)
		(end 407.424382 -312.177684)
		(width 0.16002)
		(layer "In6.Cu")
		(net "M_K_CPU0_SB_DQS_DP<8>")
	)
	(segment
		(start 406.05075 -311.280556)
		(end 406.475184 -311.70499)
		(width 0.16002)
		(layer "In6.Cu")
		(net "M_K_CPU0_SB_DQS_DP<8>")
	)
	(segment
		(start 426.859446 -315.360304)
		(end 428.173642 -315.360304)
		(width 0.16002)
		(layer "In6.Cu")
		(net "M_K_CPU0_SB_DQS_DP<8>")
	)
	(segment
		(start 406.475184 -311.70499)
		(end 406.951688 -311.70499)
		(width 0.16002)
		(layer "In6.Cu")
		(net "M_K_CPU0_SB_DQS_DP<8>")
	)
	(segment
		(start 407.035762 -311.620916)
		(end 407.261822 -311.620916)
		(width 0.16002)
		(layer "In6.Cu")
		(net "M_K_CPU0_SB_DQS_DP<8>")
	)
	(segment
		(start 409.698952 -314.452254)
		(end 409.783026 -314.36818)
		(width 0.16002)
		(layer "In6.Cu")
		(net "M_K_CPU0_SB_DQS_DP<8>")
	)
	(segment
		(start 420.629588 -315.360304)
		(end 421.009572 -314.98032)
		(width 0.16002)
		(layer "In6.Cu")
		(net "M_K_CPU0_SB_DQS_DP<8>")
	)
	(segment
		(start 429.945546 -314.19292)
		(end 430.754282 -314.19292)
		(width 0.16002)
		(layer "In6.Cu")
		(net "M_K_CPU0_SB_DQS_DP<8>")
	)
	(segment
		(start 405.101552 -310.331358)
		(end 405.578056 -310.331358)
		(width 0.16002)
		(layer "In6.Cu")
		(net "M_K_CPU0_SB_DQS_DP<8>")
	)
	(segment
		(start 404.677118 -309.43042)
		(end 404.677118 -309.906924)
		(width 0.16002)
		(layer "In6.Cu")
		(net "M_K_CPU0_SB_DQS_DP<8>")
	)
	(segment
		(start 415.98342 -314.510166)
		(end 418.465254 -314.510166)
		(width 0.16002)
		(layer "In6.Cu")
		(net "M_K_CPU0_SB_DQS_DP<8>")
	)
	(segment
		(start 434.404008 -315.360812)
		(end 435.717188 -315.360812)
		(width 0.16002)
		(layer "In6.Cu")
		(net "M_K_CPU0_SB_DQS_DP<8>")
	)
	(segment
		(start 408.798014 -314.02782)
		(end 409.222448 -314.452254)
		(width 0.16002)
		(layer "In6.Cu")
		(net "M_K_CPU0_SB_DQS_DP<8>")
	)
	(segment
		(start 407.508456 -311.86755)
		(end 407.508456 -312.09361)
		(width 0.16002)
		(layer "In6.Cu")
		(net "M_K_CPU0_SB_DQS_DP<8>")
	)
	(segment
		(start 437.4896 -314.19292)
		(end 438.298336 -314.19292)
		(width 0.16002)
		(layer "In6.Cu")
		(net "M_K_CPU0_SB_DQS_DP<8>")
	)
	(segment
		(start 394.242036 -294.561514)
		(end 395.334236 -295.653714)
		(width 0.09525)
		(layer "In6.Cu")
		(net "M_K_CPU0_SB_DQS_DP<8>")
	)
	(segment
		(start 408.798014 -313.551316)
		(end 408.798014 -314.02782)
		(width 0.16002)
		(layer "In6.Cu")
		(net "M_K_CPU0_SB_DQS_DP<8>")
	)
	(segment
		(start 408.32532 -313.078622)
		(end 408.409394 -312.994548)
		(width 0.16002)
		(layer "In6.Cu")
		(net "M_K_CPU0_SB_DQS_DP<8>")
	)
	(segment
		(start 414.857438 -314.19292)
		(end 415.666174 -314.19292)
		(width 0.16002)
		(layer "In6.Cu")
		(net "M_K_CPU0_SB_DQS_DP<8>")
	)
	(segment
		(start 408.882088 -313.467242)
		(end 408.798014 -313.551316)
		(width 0.16002)
		(layer "In6.Cu")
		(net "M_K_CPU0_SB_DQS_DP<8>")
	)
	(segment
		(start 392.907774 -292.222428)
		(end 393.551156 -292.86581)
		(width 0.09525)
		(layer "In6.Cu")
		(net "M_K_CPU0_SB_DQS_DP<8>")
	)
	(segment
		(start 415.666174 -314.19292)
		(end 415.98342 -314.510166)
		(width 0.16002)
		(layer "In6.Cu")
		(net "M_K_CPU0_SB_DQS_DP<8>")
	)
	(segment
		(start 410.009086 -314.36818)
		(end 410.621226 -314.98032)
		(width 0.16002)
		(layer "In6.Cu")
		(net "M_K_CPU0_SB_DQS_DP<8>")
	)
	(segment
		(start 440.196732 -314.361068)
		(end 440.676792 -314.361068)
		(width 0.16002)
		(layer "In6.Cu")
		(net "M_K_CPU0_SB_DQS_DP<8>")
	)
	(segment
		(start 423.210228 -314.19292)
		(end 423.527474 -314.510166)
		(width 0.16002)
		(layer "In6.Cu")
		(net "M_K_CPU0_SB_DQS_DP<8>")
	)
	(segment
		(start 438.615582 -314.510166)
		(end 440.047634 -314.510166)
		(width 0.16002)
		(layer "In6.Cu")
		(net "M_K_CPU0_SB_DQS_DP<8>")
	)
	(segment
		(start 440.676792 -314.361068)
		(end 440.769756 -314.454032)
		(width 0.16002)
		(layer "In6.Cu")
		(net "M_K_CPU0_SB_DQS_DP<8>")
	)
	(segment
		(start 405.578056 -310.331358)
		(end 405.66213 -310.247284)
		(width 0.16002)
		(layer "In6.Cu")
		(net "M_K_CPU0_SB_DQS_DP<8>")
	)
	(segment
		(start 423.527474 -314.510166)
		(end 426.009308 -314.510166)
		(width 0.16002)
		(layer "In6.Cu")
		(net "M_K_CPU0_SB_DQS_DP<8>")
	)
	(segment
		(start 410.621226 -314.98032)
		(end 414.070038 -314.98032)
		(width 0.16002)
		(layer "In6.Cu")
		(net "M_K_CPU0_SB_DQS_DP<8>")
	)
	(segment
		(start 426.009308 -314.510166)
		(end 426.859446 -315.360304)
		(width 0.16002)
		(layer "In6.Cu")
		(net "M_K_CPU0_SB_DQS_DP<8>")
	)
	(segment
		(start 435.717188 -315.360812)
		(end 436.09768 -314.98032)
		(width 0.16002)
		(layer "In6.Cu")
		(net "M_K_CPU0_SB_DQS_DP<8>")
	)
	(segment
		(start 389.4709 -291.640514)
		(end 389.494014 -291.5539)
		(width 0.09525)
		(layer "In6.Cu")
		(net "M_K_CPU0_SB_DQS_DP<8>")
	)
	(segment
		(start 431.071528 -314.510166)
		(end 433.553362 -314.510166)
		(width 0.16002)
		(layer "In6.Cu")
		(net "M_K_CPU0_SB_DQS_DP<8>")
	)
	(segment
		(start 414.070038 -314.98032)
		(end 414.857438 -314.19292)
		(width 0.16002)
		(layer "In6.Cu")
		(net "M_K_CPU0_SB_DQS_DP<8>")
	)
	(segment
		(start 407.424382 -312.177684)
		(end 407.424382 -312.654188)
		(width 0.16002)
		(layer "In6.Cu")
		(net "M_K_CPU0_SB_DQS_DP<8>")
	)
	(segment
		(start 419.315392 -315.360304)
		(end 420.629588 -315.360304)
		(width 0.16002)
		(layer "In6.Cu")
		(net "M_K_CPU0_SB_DQS_DP<8>")
	)
	(segment
		(start 441.410852 -314.361068)
		(end 442.270134 -314.361068)
		(width 0.16002)
		(layer "In6.Cu")
		(net "M_K_CPU0_SB_DQS_DP<8>")
	)
	(segment
		(start 408.882088 -313.241182)
		(end 408.882088 -313.467242)
		(width 0.16002)
		(layer "In6.Cu")
		(net "M_K_CPU0_SB_DQS_DP<8>")
	)
	(segment
		(start 407.424382 -312.654188)
		(end 407.848816 -313.078622)
		(width 0.16002)
		(layer "In6.Cu")
		(net "M_K_CPU0_SB_DQS_DP<8>")
	)
	(segment
		(start 430.754282 -314.19292)
		(end 431.071528 -314.510166)
		(width 0.16002)
		(layer "In6.Cu")
		(net "M_K_CPU0_SB_DQS_DP<8>")
	)
	(segment
		(start 395.511528 -299.870622)
		(end 404.761192 -309.120286)
		(width 0.16002)
		(layer "In6.Cu")
		(net "M_K_CPU0_SB_DQS_DP<8>")
	)
	(segment
		(start 393.772136 -293.398956)
		(end 393.772136 -293.455852)
		(width 0.09525)
		(layer "In6.Cu")
		(net "M_K_CPU0_SB_DQS_DP<8>")
	)
	(segment
		(start 393.978892 -293.954962)
		(end 394.15847 -294.13454)
		(width 0.09525)
		(layer "In6.Cu")
		(net "M_K_CPU0_SB_DQS_DP<8>")
	)
	(segment
		(start 395.511528 -295.913048)
		(end 395.511528 -299.870622)
		(width 0.16002)
		(layer "In6.Cu")
		(net "M_K_CPU0_SB_DQS_DP<8>")
	)
	(segment
		(start 442.270134 -314.361068)
		(end 442.5442 -314.635134)
		(width 0.16002)
		(layer "In6.Cu")
		(net "M_K_CPU0_SB_DQS_DP<8>")
	)
	(segment
		(start 429.158146 -314.98032)
		(end 429.945546 -314.19292)
		(width 0.16002)
		(layer "In6.Cu")
		(net "M_K_CPU0_SB_DQS_DP<8>")
	)
	(segment
		(start 433.553362 -314.510166)
		(end 434.404008 -315.360812)
		(width 0.16002)
		(layer "In6.Cu")
		(net "M_K_CPU0_SB_DQS_DP<8>")
	)
	(arc
		(start 391.324592 -291.575998)
		(mid 391.509624 -291.530084)
		(end 391.6934 -291.580824)
		(width 0.09525)
		(layer "In6.Cu")
		(net "M_K_CPU0_SB_DQS_DP<8>")
	)
	(arc
		(start 390.753346 -291.580824)
		(mid 391.034778 -291.656579)
		(end 391.31621 -291.580824)
		(width 0.09525)
		(layer "In6.Cu")
		(net "M_K_CPU0_SB_DQS_DP<8>")
	)
	(arc
		(start 392.632692 -291.580824)
		(mid 392.681371 -291.631014)
		(end 392.696954 -291.699188)
		(width 0.09525)
		(layer "In6.Cu")
		(net "M_K_CPU0_SB_DQS_DP<8>")
	)
	(arc
		(start 390.376156 -291.580824)
		(mid 390.559931 -291.530052)
		(end 390.744964 -291.575998)
		(width 0.09525)
		(layer "In6.Cu")
		(net "M_K_CPU0_SB_DQS_DP<8>")
	)
	(arc
		(start 393.772136 -293.455852)
		(mid 393.825935 -293.725936)
		(end 393.978892 -293.954962)
		(width 0.09525)
		(layer "In6.Cu")
		(net "M_K_CPU0_SB_DQS_DP<8>")
	)
	(arc
		(start 392.264392 -291.575998)
		(mid 392.44917 -291.530205)
		(end 392.632692 -291.580824)
		(width 0.09525)
		(layer "In6.Cu")
		(net "M_K_CPU0_SB_DQS_DP<8>")
	)
	(arc
		(start 391.6934 -291.580824)
		(mid 391.968689 -291.656545)
		(end 392.245596 -291.58692)
		(width 0.09525)
		(layer "In6.Cu")
		(net "M_K_CPU0_SB_DQS_DP<8>")
	)
	(arc
		(start 392.696954 -291.699188)
		(mid 392.745062 -291.983898)
		(end 392.907774 -292.222428)
		(width 0.09525)
		(layer "In6.Cu")
		(net "M_K_CPU0_SB_DQS_DP<8>")
	)
	(arc
		(start 389.494014 -291.5539)
		(mid 389.656665 -291.53164)
		(end 389.813292 -291.580824)
		(width 0.09525)
		(layer "In6.Cu")
		(net "M_K_CPU0_SB_DQS_DP<8>")
	)
	(arc
		(start 389.813292 -291.580824)
		(mid 390.094724 -291.656579)
		(end 390.376156 -291.580824)
		(width 0.09525)
		(layer "In6.Cu")
		(net "M_K_CPU0_SB_DQS_DP<8>")
	)
	(arc
		(start 394.15847 -294.13454)
		(mid 394.22035 -294.227055)
		(end 394.242036 -294.336216)
		(width 0.09525)
		(layer "In6.Cu")
		(net "M_K_CPU0_SB_DQS_DP<8>")
	)
	(arc
		(start 393.551156 -292.86581)
		(mid 393.71454 -293.110565)
		(end 393.771882 -293.39921)
		(width 0.09525)
		(layer "In6.Cu")
		(net "M_K_CPU0_SB_DQS_DP<8>")
	)
	(segment
		(start 389.157972 -286.780224)
		(end 389.624824 -287.045908)
		(width 0.12954)
		(layer "F.Cu")
		(net "M_K_CPU0_SB_DQS_DP<7>")
	)
	(segment
		(start 408.380438 -303.537112)
		(end 408.804872 -303.961546)
		(width 0.16002)
		(layer "In6.Cu")
		(net "M_K_CPU0_SB_DQS_DP<7>")
	)
	(segment
		(start 441.43295 -305.114452)
		(end 441.536328 -305.011074)
		(width 0.16002)
		(layer "In6.Cu")
		(net "M_K_CPU0_SB_DQS_DP<7>")
	)
	(segment
		(start 395.628622 -287.78073)
		(end 395.645386 -287.797494)
		(width 0.09525)
		(layer "In6.Cu")
		(net "M_K_CPU0_SB_DQS_DP<7>")
	)
	(segment
		(start 406.87879 -301.095664)
		(end 407.125424 -301.342298)
		(width 0.16002)
		(layer "In6.Cu")
		(net "M_K_CPU0_SB_DQS_DP<7>")
	)
	(segment
		(start 405.633174 -300.313344)
		(end 405.633174 -300.789848)
		(width 0.16002)
		(layer "In6.Cu")
		(net "M_K_CPU0_SB_DQS_DP<7>")
	)
	(segment
		(start 426.009308 -305.160172)
		(end 426.859446 -306.01031)
		(width 0.16002)
		(layer "In6.Cu")
		(net "M_K_CPU0_SB_DQS_DP<7>")
	)
	(segment
		(start 407.907744 -302.587914)
		(end 408.026362 -302.469296)
		(width 0.16002)
		(layer "In6.Cu")
		(net "M_K_CPU0_SB_DQS_DP<7>")
	)
	(segment
		(start 407.43124 -302.587914)
		(end 407.907744 -302.587914)
		(width 0.16002)
		(layer "In6.Cu")
		(net "M_K_CPU0_SB_DQS_DP<7>")
	)
	(segment
		(start 421.009572 -305.630326)
		(end 421.614092 -305.630326)
		(width 0.16002)
		(layer "In6.Cu")
		(net "M_K_CPU0_SB_DQS_DP<7>")
	)
	(segment
		(start 393.706604 -286.624522)
		(end 394.293344 -287.211262)
		(width 0.09525)
		(layer "In6.Cu")
		(net "M_K_CPU0_SB_DQS_DP<7>")
	)
	(segment
		(start 414.857438 -304.842926)
		(end 415.666174 -304.842926)
		(width 0.16002)
		(layer "In6.Cu")
		(net "M_K_CPU0_SB_DQS_DP<7>")
	)
	(segment
		(start 437.4896 -304.842926)
		(end 438.298336 -304.842926)
		(width 0.16002)
		(layer "In6.Cu")
		(net "M_K_CPU0_SB_DQS_DP<7>")
	)
	(segment
		(start 415.98342 -305.160172)
		(end 418.465254 -305.160172)
		(width 0.16002)
		(layer "In6.Cu")
		(net "M_K_CPU0_SB_DQS_DP<7>")
	)
	(segment
		(start 409.75407 -304.910744)
		(end 410.178504 -305.335178)
		(width 0.16002)
		(layer "In6.Cu")
		(net "M_K_CPU0_SB_DQS_DP<7>")
	)
	(segment
		(start 440.196732 -305.011074)
		(end 440.802268 -305.011074)
		(width 0.16002)
		(layer "In6.Cu")
		(net "M_K_CPU0_SB_DQS_DP<7>")
	)
	(segment
		(start 389.4709 -286.780478)
		(end 389.494014 -286.693864)
		(width 0.09525)
		(layer "In6.Cu")
		(net "M_K_CPU0_SB_DQS_DP<7>")
	)
	(segment
		(start 404.489158 -299.846492)
		(end 405.629618 -299.846492)
		(width 0.16002)
		(layer "In6.Cu")
		(net "M_K_CPU0_SB_DQS_DP<7>")
	)
	(segment
		(start 422.401492 -304.842926)
		(end 423.210228 -304.842926)
		(width 0.16002)
		(layer "In6.Cu")
		(net "M_K_CPU0_SB_DQS_DP<7>")
	)
	(segment
		(start 436.7022 -305.630326)
		(end 437.4896 -304.842926)
		(width 0.16002)
		(layer "In6.Cu")
		(net "M_K_CPU0_SB_DQS_DP<7>")
	)
	(segment
		(start 405.633174 -300.789848)
		(end 406.057608 -301.214282)
		(width 0.16002)
		(layer "In6.Cu")
		(net "M_K_CPU0_SB_DQS_DP<7>")
	)
	(segment
		(start 419.315392 -306.01031)
		(end 420.629588 -306.01031)
		(width 0.16002)
		(layer "In6.Cu")
		(net "M_K_CPU0_SB_DQS_DP<7>")
	)
	(segment
		(start 409.281376 -303.961546)
		(end 409.399994 -303.842928)
		(width 0.16002)
		(layer "In6.Cu")
		(net "M_K_CPU0_SB_DQS_DP<7>")
	)
	(segment
		(start 434.4035 -306.01031)
		(end 435.717696 -306.01031)
		(width 0.16002)
		(layer "In6.Cu")
		(net "M_K_CPU0_SB_DQS_DP<7>")
	)
	(segment
		(start 421.614092 -305.630326)
		(end 422.401492 -304.842926)
		(width 0.16002)
		(layer "In6.Cu")
		(net "M_K_CPU0_SB_DQS_DP<7>")
	)
	(segment
		(start 407.006806 -301.686976)
		(end 407.006806 -302.16348)
		(width 0.16002)
		(layer "In6.Cu")
		(net "M_K_CPU0_SB_DQS_DP<7>")
	)
	(segment
		(start 408.026362 -302.469296)
		(end 408.252422 -302.469296)
		(width 0.16002)
		(layer "In6.Cu")
		(net "M_K_CPU0_SB_DQS_DP<7>")
	)
	(segment
		(start 409.872688 -304.089562)
		(end 409.872688 -304.315622)
		(width 0.16002)
		(layer "In6.Cu")
		(net "M_K_CPU0_SB_DQS_DP<7>")
	)
	(segment
		(start 440.047634 -305.160172)
		(end 440.196732 -305.011074)
		(width 0.16002)
		(layer "In6.Cu")
		(net "M_K_CPU0_SB_DQS_DP<7>")
	)
	(segment
		(start 408.380438 -303.060608)
		(end 408.380438 -303.537112)
		(width 0.16002)
		(layer "In6.Cu")
		(net "M_K_CPU0_SB_DQS_DP<7>")
	)
	(segment
		(start 408.499056 -302.94199)
		(end 408.380438 -303.060608)
		(width 0.16002)
		(layer "In6.Cu")
		(net "M_K_CPU0_SB_DQS_DP<7>")
	)
	(segment
		(start 429.945546 -304.842926)
		(end 430.754282 -304.842926)
		(width 0.16002)
		(layer "In6.Cu")
		(net "M_K_CPU0_SB_DQS_DP<7>")
	)
	(segment
		(start 389.624824 -287.045908)
		(end 389.4709 -286.780478)
		(width 0.09525)
		(layer "In6.Cu")
		(net "M_K_CPU0_SB_DQS_DP<7>")
	)
	(segment
		(start 411.413452 -305.630326)
		(end 414.070038 -305.630326)
		(width 0.16002)
		(layer "In6.Cu")
		(net "M_K_CPU0_SB_DQS_DP<7>")
	)
	(segment
		(start 410.773626 -305.21656)
		(end 410.999686 -305.21656)
		(width 0.16002)
		(layer "In6.Cu")
		(net "M_K_CPU0_SB_DQS_DP<7>")
	)
	(segment
		(start 391.6934 -286.720788)
		(end 391.70229 -286.726122)
		(width 0.09525)
		(layer "In6.Cu")
		(net "M_K_CPU0_SB_DQS_DP<7>")
	)
	(segment
		(start 409.399994 -303.842928)
		(end 409.626054 -303.842928)
		(width 0.16002)
		(layer "In6.Cu")
		(net "M_K_CPU0_SB_DQS_DP<7>")
	)
	(segment
		(start 391.31621 -286.720788)
		(end 391.324592 -286.715962)
		(width 0.09525)
		(layer "In6.Cu")
		(net "M_K_CPU0_SB_DQS_DP<7>")
	)
	(segment
		(start 435.717696 -306.01031)
		(end 436.09768 -305.630326)
		(width 0.16002)
		(layer "In6.Cu")
		(net "M_K_CPU0_SB_DQS_DP<7>")
	)
	(segment
		(start 394.293344 -287.211262)
		(end 395.142466 -287.211262)
		(width 0.09525)
		(layer "In6.Cu")
		(net "M_K_CPU0_SB_DQS_DP<7>")
	)
	(segment
		(start 406.057608 -301.214282)
		(end 406.534112 -301.214282)
		(width 0.16002)
		(layer "In6.Cu")
		(net "M_K_CPU0_SB_DQS_DP<7>")
	)
	(segment
		(start 428.173642 -306.01031)
		(end 428.553626 -305.630326)
		(width 0.16002)
		(layer "In6.Cu")
		(net "M_K_CPU0_SB_DQS_DP<7>")
	)
	(segment
		(start 433.553362 -305.160172)
		(end 434.4035 -306.01031)
		(width 0.16002)
		(layer "In6.Cu")
		(net "M_K_CPU0_SB_DQS_DP<7>")
	)
	(segment
		(start 442.270134 -305.011074)
		(end 442.5442 -305.28514)
		(width 0.16002)
		(layer "In6.Cu")
		(net "M_K_CPU0_SB_DQS_DP<7>")
	)
	(segment
		(start 395.142466 -287.211262)
		(end 395.628622 -287.697418)
		(width 0.09525)
		(layer "In6.Cu")
		(net "M_K_CPU0_SB_DQS_DP<7>")
	)
	(segment
		(start 409.872688 -304.315622)
		(end 409.75407 -304.43424)
		(width 0.16002)
		(layer "In6.Cu")
		(net "M_K_CPU0_SB_DQS_DP<7>")
	)
	(segment
		(start 407.006806 -302.16348)
		(end 407.43124 -302.587914)
		(width 0.16002)
		(layer "In6.Cu")
		(net "M_K_CPU0_SB_DQS_DP<7>")
	)
	(segment
		(start 423.210228 -304.842926)
		(end 423.527474 -305.160172)
		(width 0.16002)
		(layer "In6.Cu")
		(net "M_K_CPU0_SB_DQS_DP<7>")
	)
	(segment
		(start 409.626054 -303.842928)
		(end 409.872688 -304.089562)
		(width 0.16002)
		(layer "In6.Cu")
		(net "M_K_CPU0_SB_DQS_DP<7>")
	)
	(segment
		(start 405.751792 -299.968666)
		(end 405.751792 -300.194726)
		(width 0.16002)
		(layer "In6.Cu")
		(net "M_K_CPU0_SB_DQS_DP<7>")
	)
	(segment
		(start 395.645386 -287.797494)
		(end 401.375118 -293.527226)
		(width 0.16002)
		(layer "In6.Cu")
		(net "M_K_CPU0_SB_DQS_DP<7>")
	)
	(segment
		(start 405.751792 -300.194726)
		(end 405.633174 -300.313344)
		(width 0.16002)
		(layer "In6.Cu")
		(net "M_K_CPU0_SB_DQS_DP<7>")
	)
	(segment
		(start 423.527474 -305.160172)
		(end 426.009308 -305.160172)
		(width 0.16002)
		(layer "In6.Cu")
		(net "M_K_CPU0_SB_DQS_DP<7>")
	)
	(segment
		(start 405.629618 -299.846492)
		(end 405.751792 -299.968666)
		(width 0.16002)
		(layer "In6.Cu")
		(net "M_K_CPU0_SB_DQS_DP<7>")
	)
	(segment
		(start 428.553626 -305.630326)
		(end 429.158146 -305.630326)
		(width 0.16002)
		(layer "In6.Cu")
		(net "M_K_CPU0_SB_DQS_DP<7>")
	)
	(segment
		(start 408.499056 -302.71593)
		(end 408.499056 -302.94199)
		(width 0.16002)
		(layer "In6.Cu")
		(net "M_K_CPU0_SB_DQS_DP<7>")
	)
	(segment
		(start 407.125424 -301.568358)
		(end 407.006806 -301.686976)
		(width 0.16002)
		(layer "In6.Cu")
		(net "M_K_CPU0_SB_DQS_DP<7>")
	)
	(segment
		(start 431.071528 -305.160172)
		(end 433.553362 -305.160172)
		(width 0.16002)
		(layer "In6.Cu")
		(net "M_K_CPU0_SB_DQS_DP<7>")
	)
	(segment
		(start 409.75407 -304.43424)
		(end 409.75407 -304.910744)
		(width 0.16002)
		(layer "In6.Cu")
		(net "M_K_CPU0_SB_DQS_DP<7>")
	)
	(segment
		(start 426.859446 -306.01031)
		(end 428.173642 -306.01031)
		(width 0.16002)
		(layer "In6.Cu")
		(net "M_K_CPU0_SB_DQS_DP<7>")
	)
	(segment
		(start 401.375118 -296.732452)
		(end 404.489158 -299.846492)
		(width 0.16002)
		(layer "In6.Cu")
		(net "M_K_CPU0_SB_DQS_DP<7>")
	)
	(segment
		(start 395.628622 -287.697418)
		(end 395.628622 -287.78073)
		(width 0.09525)
		(layer "In6.Cu")
		(net "M_K_CPU0_SB_DQS_DP<7>")
	)
	(segment
		(start 438.615582 -305.160172)
		(end 440.047634 -305.160172)
		(width 0.16002)
		(layer "In6.Cu")
		(net "M_K_CPU0_SB_DQS_DP<7>")
	)
	(segment
		(start 406.534112 -301.214282)
		(end 406.65273 -301.095664)
		(width 0.16002)
		(layer "In6.Cu")
		(net "M_K_CPU0_SB_DQS_DP<7>")
	)
	(segment
		(start 410.178504 -305.335178)
		(end 410.655008 -305.335178)
		(width 0.16002)
		(layer "In6.Cu")
		(net "M_K_CPU0_SB_DQS_DP<7>")
	)
	(segment
		(start 436.09768 -305.630326)
		(end 436.7022 -305.630326)
		(width 0.16002)
		(layer "In6.Cu")
		(net "M_K_CPU0_SB_DQS_DP<7>")
	)
	(segment
		(start 430.754282 -304.842926)
		(end 431.071528 -305.160172)
		(width 0.16002)
		(layer "In6.Cu")
		(net "M_K_CPU0_SB_DQS_DP<7>")
	)
	(segment
		(start 406.65273 -301.095664)
		(end 406.87879 -301.095664)
		(width 0.16002)
		(layer "In6.Cu")
		(net "M_K_CPU0_SB_DQS_DP<7>")
	)
	(segment
		(start 429.158146 -305.630326)
		(end 429.945546 -304.842926)
		(width 0.16002)
		(layer "In6.Cu")
		(net "M_K_CPU0_SB_DQS_DP<7>")
	)
	(segment
		(start 407.125424 -301.342298)
		(end 407.125424 -301.568358)
		(width 0.16002)
		(layer "In6.Cu")
		(net "M_K_CPU0_SB_DQS_DP<7>")
	)
	(segment
		(start 418.465254 -305.160172)
		(end 419.315392 -306.01031)
		(width 0.16002)
		(layer "In6.Cu")
		(net "M_K_CPU0_SB_DQS_DP<7>")
	)
	(segment
		(start 415.666174 -304.842926)
		(end 415.98342 -305.160172)
		(width 0.16002)
		(layer "In6.Cu")
		(net "M_K_CPU0_SB_DQS_DP<7>")
	)
	(segment
		(start 410.655008 -305.335178)
		(end 410.773626 -305.21656)
		(width 0.16002)
		(layer "In6.Cu")
		(net "M_K_CPU0_SB_DQS_DP<7>")
	)
	(segment
		(start 414.070038 -305.630326)
		(end 414.857438 -304.842926)
		(width 0.16002)
		(layer "In6.Cu")
		(net "M_K_CPU0_SB_DQS_DP<7>")
	)
	(segment
		(start 410.999686 -305.21656)
		(end 411.413452 -305.630326)
		(width 0.16002)
		(layer "In6.Cu")
		(net "M_K_CPU0_SB_DQS_DP<7>")
	)
	(segment
		(start 441.536328 -305.011074)
		(end 442.270134 -305.011074)
		(width 0.16002)
		(layer "In6.Cu")
		(net "M_K_CPU0_SB_DQS_DP<7>")
	)
	(segment
		(start 392.611356 -286.624522)
		(end 393.706604 -286.624522)
		(width 0.09525)
		(layer "In6.Cu")
		(net "M_K_CPU0_SB_DQS_DP<7>")
	)
	(segment
		(start 438.298336 -304.842926)
		(end 438.615582 -305.160172)
		(width 0.16002)
		(layer "In6.Cu")
		(net "M_K_CPU0_SB_DQS_DP<7>")
	)
	(segment
		(start 440.905646 -305.114452)
		(end 441.43295 -305.114452)
		(width 0.16002)
		(layer "In6.Cu")
		(net "M_K_CPU0_SB_DQS_DP<7>")
	)
	(segment
		(start 408.804872 -303.961546)
		(end 409.281376 -303.961546)
		(width 0.16002)
		(layer "In6.Cu")
		(net "M_K_CPU0_SB_DQS_DP<7>")
	)
	(segment
		(start 390.744964 -286.715962)
		(end 390.753346 -286.720788)
		(width 0.09525)
		(layer "In6.Cu")
		(net "M_K_CPU0_SB_DQS_DP<7>")
	)
	(segment
		(start 420.629588 -306.01031)
		(end 421.009572 -305.630326)
		(width 0.16002)
		(layer "In6.Cu")
		(net "M_K_CPU0_SB_DQS_DP<7>")
	)
	(segment
		(start 440.802268 -305.011074)
		(end 440.905646 -305.114452)
		(width 0.16002)
		(layer "In6.Cu")
		(net "M_K_CPU0_SB_DQS_DP<7>")
	)
	(segment
		(start 401.375118 -293.527226)
		(end 401.375118 -296.732452)
		(width 0.16002)
		(layer "In6.Cu")
		(net "M_K_CPU0_SB_DQS_DP<7>")
	)
	(segment
		(start 408.252422 -302.469296)
		(end 408.499056 -302.71593)
		(width 0.16002)
		(layer "In6.Cu")
		(net "M_K_CPU0_SB_DQS_DP<7>")
	)
	(arc
		(start 390.753346 -286.720788)
		(mid 391.034778 -286.796577)
		(end 391.31621 -286.720788)
		(width 0.09525)
		(layer "In6.Cu")
		(net "M_K_CPU0_SB_DQS_DP<7>")
	)
	(arc
		(start 389.494014 -286.693864)
		(mid 389.656665 -286.671604)
		(end 389.813292 -286.720788)
		(width 0.09525)
		(layer "In6.Cu")
		(net "M_K_CPU0_SB_DQS_DP<7>")
	)
	(arc
		(start 391.70229 -286.726122)
		(mid 391.965771 -286.796629)
		(end 392.231372 -286.734504)
		(width 0.09525)
		(layer "In6.Cu")
		(net "M_K_CPU0_SB_DQS_DP<7>")
	)
	(arc
		(start 392.25601 -286.721042)
		(mid 392.257405 -286.720277)
		(end 392.258804 -286.719518)
		(width 0.09525)
		(layer "In6.Cu")
		(net "M_K_CPU0_SB_DQS_DP<7>")
	)
	(arc
		(start 392.231372 -286.734504)
		(mid 392.243777 -286.72793)
		(end 392.25601 -286.721042)
		(width 0.09525)
		(layer "In6.Cu")
		(net "M_K_CPU0_SB_DQS_DP<7>")
	)
	(arc
		(start 391.324592 -286.715962)
		(mid 391.509624 -286.670048)
		(end 391.6934 -286.720788)
		(width 0.09525)
		(layer "In6.Cu")
		(net "M_K_CPU0_SB_DQS_DP<7>")
	)
	(arc
		(start 389.813292 -286.720788)
		(mid 390.094724 -286.796577)
		(end 390.376156 -286.720788)
		(width 0.09525)
		(layer "In6.Cu")
		(net "M_K_CPU0_SB_DQS_DP<7>")
	)
	(arc
		(start 392.25855 -286.718756)
		(mid 392.42879 -286.648572)
		(end 392.611356 -286.624522)
		(width 0.09525)
		(layer "In6.Cu")
		(net "M_K_CPU0_SB_DQS_DP<7>")
	)
	(arc
		(start 392.258804 -286.719518)
		(mid 392.258676 -286.719137)
		(end 392.25855 -286.718756)
		(width 0.09525)
		(layer "In6.Cu")
		(net "M_K_CPU0_SB_DQS_DP<7>")
	)
	(arc
		(start 390.376156 -286.720788)
		(mid 390.559931 -286.670016)
		(end 390.744964 -286.715962)
		(width 0.09525)
		(layer "In6.Cu")
		(net "M_K_CPU0_SB_DQS_DP<7>")
	)
	(segment
		(start 389.157972 -281.920188)
		(end 389.624824 -282.186126)
		(width 0.12954)
		(layer "F.Cu")
		(net "M_K_CPU0_SB_DQS_DP<6>")
	)
	(segment
		(start 393.183872 -281.867356)
		(end 393.34059 -281.802332)
		(width 0.09525)
		(layer "In6.Cu")
		(net "M_K_CPU0_SB_DQS_DP<6>")
	)
	(segment
		(start 433.553362 -295.810178)
		(end 434.4035 -296.660316)
		(width 0.16002)
		(layer "In6.Cu")
		(net "M_K_CPU0_SB_DQS_DP<6>")
	)
	(segment
		(start 438.615582 -295.810178)
		(end 440.047634 -295.810178)
		(width 0.16002)
		(layer "In6.Cu")
		(net "M_K_CPU0_SB_DQS_DP<6>")
	)
	(segment
		(start 441.554108 -295.66108)
		(end 442.270134 -295.66108)
		(width 0.16002)
		(layer "In6.Cu")
		(net "M_K_CPU0_SB_DQS_DP<6>")
	)
	(segment
		(start 412.01721 -296.151046)
		(end 412.24327 -296.151046)
		(width 0.16002)
		(layer "In6.Cu")
		(net "M_K_CPU0_SB_DQS_DP<6>")
	)
	(segment
		(start 395.835632 -282.12034)
		(end 395.859254 -282.12034)
		(width 0.09525)
		(layer "In6.Cu")
		(net "M_K_CPU0_SB_DQS_DP<6>")
	)
	(segment
		(start 394.440664 -281.802332)
		(end 394.51661 -281.833828)
		(width 0.09525)
		(layer "In6.Cu")
		(net "M_K_CPU0_SB_DQS_DP<6>")
	)
	(segment
		(start 390.744964 -281.85618)
		(end 390.753346 -281.861006)
		(width 0.09525)
		(layer "In6.Cu")
		(net "M_K_CPU0_SB_DQS_DP<6>")
	)
	(segment
		(start 398.212564 -282.12034)
		(end 409.743402 -293.651178)
		(width 0.16002)
		(layer "In6.Cu")
		(net "M_K_CPU0_SB_DQS_DP<6>")
	)
	(segment
		(start 416.567366 -296.155872)
		(end 417.166044 -296.155872)
		(width 0.16002)
		(layer "In6.Cu")
		(net "M_K_CPU0_SB_DQS_DP<6>")
	)
	(segment
		(start 410.982414 -295.38549)
		(end 410.982414 -295.861994)
		(width 0.16002)
		(layer "In6.Cu")
		(net "M_K_CPU0_SB_DQS_DP<6>")
	)
	(segment
		(start 395.859254 -282.12034)
		(end 398.212564 -282.12034)
		(width 0.16002)
		(layer "In6.Cu")
		(net "M_K_CPU0_SB_DQS_DP<6>")
	)
	(segment
		(start 389.4709 -281.920696)
		(end 389.494014 -281.834082)
		(width 0.09525)
		(layer "In6.Cu")
		(net "M_K_CPU0_SB_DQS_DP<6>")
	)
	(segment
		(start 430.754282 -295.492932)
		(end 431.071528 -295.810178)
		(width 0.16002)
		(layer "In6.Cu")
		(net "M_K_CPU0_SB_DQS_DP<6>")
	)
	(segment
		(start 431.071528 -295.810178)
		(end 433.553362 -295.810178)
		(width 0.16002)
		(layer "In6.Cu")
		(net "M_K_CPU0_SB_DQS_DP<6>")
	)
	(segment
		(start 438.298336 -295.492932)
		(end 438.615582 -295.810178)
		(width 0.16002)
		(layer "In6.Cu")
		(net "M_K_CPU0_SB_DQS_DP<6>")
	)
	(segment
		(start 440.047634 -295.810178)
		(end 440.196732 -295.66108)
		(width 0.16002)
		(layer "In6.Cu")
		(net "M_K_CPU0_SB_DQS_DP<6>")
	)
	(segment
		(start 426.009308 -295.810178)
		(end 426.859446 -296.660316)
		(width 0.16002)
		(layer "In6.Cu")
		(net "M_K_CPU0_SB_DQS_DP<6>")
	)
	(segment
		(start 411.88259 -296.285666)
		(end 412.01721 -296.151046)
		(width 0.16002)
		(layer "In6.Cu")
		(net "M_K_CPU0_SB_DQS_DP<6>")
	)
	(segment
		(start 410.982414 -295.861994)
		(end 411.406086 -296.285666)
		(width 0.16002)
		(layer "In6.Cu")
		(net "M_K_CPU0_SB_DQS_DP<6>")
	)
	(segment
		(start 417.663122 -295.492932)
		(end 418.148008 -295.492932)
		(width 0.16002)
		(layer "In6.Cu")
		(net "M_K_CPU0_SB_DQS_DP<6>")
	)
	(segment
		(start 409.743402 -293.877238)
		(end 409.608782 -294.011858)
		(width 0.16002)
		(layer "In6.Cu")
		(net "M_K_CPU0_SB_DQS_DP<6>")
	)
	(segment
		(start 442.270134 -295.66108)
		(end 442.5442 -295.935146)
		(width 0.16002)
		(layer "In6.Cu")
		(net "M_K_CPU0_SB_DQS_DP<6>")
	)
	(segment
		(start 440.196732 -295.66108)
		(end 440.820048 -295.66108)
		(width 0.16002)
		(layer "In6.Cu")
		(net "M_K_CPU0_SB_DQS_DP<6>")
	)
	(segment
		(start 429.158146 -296.280332)
		(end 429.945546 -295.492932)
		(width 0.16002)
		(layer "In6.Cu")
		(net "M_K_CPU0_SB_DQS_DP<6>")
	)
	(segment
		(start 421.614092 -296.280332)
		(end 422.401492 -295.492932)
		(width 0.16002)
		(layer "In6.Cu")
		(net "M_K_CPU0_SB_DQS_DP<6>")
	)
	(segment
		(start 423.527474 -295.810178)
		(end 426.009308 -295.810178)
		(width 0.16002)
		(layer "In6.Cu")
		(net "M_K_CPU0_SB_DQS_DP<6>")
	)
	(segment
		(start 392.6332 -281.861006)
		(end 392.648186 -281.869134)
		(width 0.09525)
		(layer "In6.Cu")
		(net "M_K_CPU0_SB_DQS_DP<6>")
	)
	(segment
		(start 416.230308 -295.652952)
		(end 416.230308 -295.818814)
		(width 0.16002)
		(layer "In6.Cu")
		(net "M_K_CPU0_SB_DQS_DP<6>")
	)
	(segment
		(start 391.31621 -281.861006)
		(end 391.324592 -281.85618)
		(width 0.09525)
		(layer "In6.Cu")
		(net "M_K_CPU0_SB_DQS_DP<6>")
	)
	(segment
		(start 437.4896 -295.492932)
		(end 438.298336 -295.492932)
		(width 0.16002)
		(layer "In6.Cu")
		(net "M_K_CPU0_SB_DQS_DP<6>")
	)
	(segment
		(start 394.744194 -282.061412)
		(end 395.776704 -282.061412)
		(width 0.09525)
		(layer "In6.Cu")
		(net "M_K_CPU0_SB_DQS_DP<6>")
	)
	(segment
		(start 410.869638 -294.777414)
		(end 411.117034 -295.02481)
		(width 0.16002)
		(layer "In6.Cu")
		(net "M_K_CPU0_SB_DQS_DP<6>")
	)
	(segment
		(start 392.632692 -281.861006)
		(end 392.6332 -281.861006)
		(width 0.09525)
		(layer "In6.Cu")
		(net "M_K_CPU0_SB_DQS_DP<6>")
	)
	(segment
		(start 416.230308 -295.818814)
		(end 416.567366 -296.155872)
		(width 0.16002)
		(layer "In6.Cu")
		(net "M_K_CPU0_SB_DQS_DP<6>")
	)
	(segment
		(start 411.117034 -295.25087)
		(end 410.982414 -295.38549)
		(width 0.16002)
		(layer "In6.Cu")
		(net "M_K_CPU0_SB_DQS_DP<6>")
	)
	(segment
		(start 389.624824 -282.186126)
		(end 389.4709 -281.920696)
		(width 0.09525)
		(layer "In6.Cu")
		(net "M_K_CPU0_SB_DQS_DP<6>")
	)
	(segment
		(start 411.406086 -296.285666)
		(end 411.88259 -296.285666)
		(width 0.16002)
		(layer "In6.Cu")
		(net "M_K_CPU0_SB_DQS_DP<6>")
	)
	(segment
		(start 409.608782 -294.488362)
		(end 410.032454 -294.912034)
		(width 0.16002)
		(layer "In6.Cu")
		(net "M_K_CPU0_SB_DQS_DP<6>")
	)
	(segment
		(start 418.148008 -295.492932)
		(end 419.315392 -296.660316)
		(width 0.16002)
		(layer "In6.Cu")
		(net "M_K_CPU0_SB_DQS_DP<6>")
	)
	(segment
		(start 410.032454 -294.912034)
		(end 410.508958 -294.912034)
		(width 0.16002)
		(layer "In6.Cu")
		(net "M_K_CPU0_SB_DQS_DP<6>")
	)
	(segment
		(start 435.717696 -296.660316)
		(end 436.09768 -296.280332)
		(width 0.16002)
		(layer "In6.Cu")
		(net "M_K_CPU0_SB_DQS_DP<6>")
	)
	(segment
		(start 429.945546 -295.492932)
		(end 430.754282 -295.492932)
		(width 0.16002)
		(layer "In6.Cu")
		(net "M_K_CPU0_SB_DQS_DP<6>")
	)
	(segment
		(start 422.401492 -295.492932)
		(end 423.210228 -295.492932)
		(width 0.16002)
		(layer "In6.Cu")
		(net "M_K_CPU0_SB_DQS_DP<6>")
	)
	(segment
		(start 428.553626 -296.280332)
		(end 429.158146 -296.280332)
		(width 0.16002)
		(layer "In6.Cu")
		(net "M_K_CPU0_SB_DQS_DP<6>")
	)
	(segment
		(start 426.859446 -296.660316)
		(end 428.173642 -296.660316)
		(width 0.16002)
		(layer "In6.Cu")
		(net "M_K_CPU0_SB_DQS_DP<6>")
	)
	(segment
		(start 423.210228 -295.492932)
		(end 423.527474 -295.810178)
		(width 0.16002)
		(layer "In6.Cu")
		(net "M_K_CPU0_SB_DQS_DP<6>")
	)
	(segment
		(start 440.820048 -295.66108)
		(end 440.947048 -295.78808)
		(width 0.16002)
		(layer "In6.Cu")
		(net "M_K_CPU0_SB_DQS_DP<6>")
	)
	(segment
		(start 412.372556 -296.280332)
		(end 414.070038 -296.280332)
		(width 0.16002)
		(layer "In6.Cu")
		(net "M_K_CPU0_SB_DQS_DP<6>")
	)
	(segment
		(start 420.629588 -296.660316)
		(end 421.009572 -296.280332)
		(width 0.16002)
		(layer "In6.Cu")
		(net "M_K_CPU0_SB_DQS_DP<6>")
	)
	(segment
		(start 417.166044 -296.155872)
		(end 417.503102 -295.818814)
		(width 0.16002)
		(layer "In6.Cu")
		(net "M_K_CPU0_SB_DQS_DP<6>")
	)
	(segment
		(start 412.24327 -296.151046)
		(end 412.372556 -296.280332)
		(width 0.16002)
		(layer "In6.Cu")
		(net "M_K_CPU0_SB_DQS_DP<6>")
	)
	(segment
		(start 441.427108 -295.78808)
		(end 441.554108 -295.66108)
		(width 0.16002)
		(layer "In6.Cu")
		(net "M_K_CPU0_SB_DQS_DP<6>")
	)
	(segment
		(start 411.117034 -295.02481)
		(end 411.117034 -295.25087)
		(width 0.16002)
		(layer "In6.Cu")
		(net "M_K_CPU0_SB_DQS_DP<6>")
	)
	(segment
		(start 436.09768 -296.280332)
		(end 436.7022 -296.280332)
		(width 0.16002)
		(layer "In6.Cu")
		(net "M_K_CPU0_SB_DQS_DP<6>")
	)
	(segment
		(start 410.508958 -294.912034)
		(end 410.643578 -294.777414)
		(width 0.16002)
		(layer "In6.Cu")
		(net "M_K_CPU0_SB_DQS_DP<6>")
	)
	(segment
		(start 417.503102 -295.652952)
		(end 417.663122 -295.492932)
		(width 0.16002)
		(layer "In6.Cu")
		(net "M_K_CPU0_SB_DQS_DP<6>")
	)
	(segment
		(start 428.173642 -296.660316)
		(end 428.553626 -296.280332)
		(width 0.16002)
		(layer "In6.Cu")
		(net "M_K_CPU0_SB_DQS_DP<6>")
	)
	(segment
		(start 440.947048 -295.78808)
		(end 441.427108 -295.78808)
		(width 0.16002)
		(layer "In6.Cu")
		(net "M_K_CPU0_SB_DQS_DP<6>")
	)
	(segment
		(start 414.070038 -296.280332)
		(end 414.857438 -295.492932)
		(width 0.16002)
		(layer "In6.Cu")
		(net "M_K_CPU0_SB_DQS_DP<6>")
	)
	(segment
		(start 394.51661 -281.833828)
		(end 394.744194 -282.061412)
		(width 0.09525)
		(layer "In6.Cu")
		(net "M_K_CPU0_SB_DQS_DP<6>")
	)
	(segment
		(start 392.25601 -281.861006)
		(end 392.264392 -281.85618)
		(width 0.09525)
		(layer "In6.Cu")
		(net "M_K_CPU0_SB_DQS_DP<6>")
	)
	(segment
		(start 416.070288 -295.492932)
		(end 416.230308 -295.652952)
		(width 0.16002)
		(layer "In6.Cu")
		(net "M_K_CPU0_SB_DQS_DP<6>")
	)
	(segment
		(start 410.643578 -294.777414)
		(end 410.869638 -294.777414)
		(width 0.16002)
		(layer "In6.Cu")
		(net "M_K_CPU0_SB_DQS_DP<6>")
	)
	(segment
		(start 392.245596 -281.867102)
		(end 392.25601 -281.861006)
		(width 0.09525)
		(layer "In6.Cu")
		(net "M_K_CPU0_SB_DQS_DP<6>")
	)
	(segment
		(start 393.34059 -281.802332)
		(end 394.440664 -281.802332)
		(width 0.09525)
		(layer "In6.Cu")
		(net "M_K_CPU0_SB_DQS_DP<6>")
	)
	(segment
		(start 419.315392 -296.660316)
		(end 420.629588 -296.660316)
		(width 0.16002)
		(layer "In6.Cu")
		(net "M_K_CPU0_SB_DQS_DP<6>")
	)
	(segment
		(start 434.4035 -296.660316)
		(end 435.717696 -296.660316)
		(width 0.16002)
		(layer "In6.Cu")
		(net "M_K_CPU0_SB_DQS_DP<6>")
	)
	(segment
		(start 409.743402 -293.651178)
		(end 409.743402 -293.877238)
		(width 0.16002)
		(layer "In6.Cu")
		(net "M_K_CPU0_SB_DQS_DP<6>")
	)
	(segment
		(start 409.608782 -294.011858)
		(end 409.608782 -294.488362)
		(width 0.16002)
		(layer "In6.Cu")
		(net "M_K_CPU0_SB_DQS_DP<6>")
	)
	(segment
		(start 436.7022 -296.280332)
		(end 437.4896 -295.492932)
		(width 0.16002)
		(layer "In6.Cu")
		(net "M_K_CPU0_SB_DQS_DP<6>")
	)
	(segment
		(start 414.857438 -295.492932)
		(end 416.070288 -295.492932)
		(width 0.16002)
		(layer "In6.Cu")
		(net "M_K_CPU0_SB_DQS_DP<6>")
	)
	(segment
		(start 395.776704 -282.061412)
		(end 395.835632 -282.12034)
		(width 0.09525)
		(layer "In6.Cu")
		(net "M_K_CPU0_SB_DQS_DP<6>")
	)
	(segment
		(start 421.009572 -296.280332)
		(end 421.614092 -296.280332)
		(width 0.16002)
		(layer "In6.Cu")
		(net "M_K_CPU0_SB_DQS_DP<6>")
	)
	(segment
		(start 417.503102 -295.818814)
		(end 417.503102 -295.652952)
		(width 0.16002)
		(layer "In6.Cu")
		(net "M_K_CPU0_SB_DQS_DP<6>")
	)
	(arc
		(start 389.494014 -281.834082)
		(mid 389.656665 -281.811822)
		(end 389.813292 -281.861006)
		(width 0.09525)
		(layer "In6.Cu")
		(net "M_K_CPU0_SB_DQS_DP<6>")
	)
	(arc
		(start 390.753346 -281.861006)
		(mid 391.034778 -281.936761)
		(end 391.31621 -281.861006)
		(width 0.09525)
		(layer "In6.Cu")
		(net "M_K_CPU0_SB_DQS_DP<6>")
	)
	(arc
		(start 390.376156 -281.861006)
		(mid 390.559931 -281.810234)
		(end 390.744964 -281.85618)
		(width 0.09525)
		(layer "In6.Cu")
		(net "M_K_CPU0_SB_DQS_DP<6>")
	)
	(arc
		(start 392.264392 -281.85618)
		(mid 392.44917 -281.810387)
		(end 392.632692 -281.861006)
		(width 0.09525)
		(layer "In6.Cu")
		(net "M_K_CPU0_SB_DQS_DP<6>")
	)
	(arc
		(start 391.324592 -281.85618)
		(mid 391.509624 -281.810266)
		(end 391.6934 -281.861006)
		(width 0.09525)
		(layer "In6.Cu")
		(net "M_K_CPU0_SB_DQS_DP<6>")
	)
	(arc
		(start 391.6934 -281.861006)
		(mid 391.968689 -281.936727)
		(end 392.245596 -281.867102)
		(width 0.09525)
		(layer "In6.Cu")
		(net "M_K_CPU0_SB_DQS_DP<6>")
	)
	(arc
		(start 389.813292 -281.861006)
		(mid 390.094724 -281.936761)
		(end 390.376156 -281.861006)
		(width 0.09525)
		(layer "In6.Cu")
		(net "M_K_CPU0_SB_DQS_DP<6>")
	)
	(arc
		(start 392.648186 -281.869134)
		(mid 392.916253 -281.936403)
		(end 393.183872 -281.867356)
		(width 0.09525)
		(layer "In6.Cu")
		(net "M_K_CPU0_SB_DQS_DP<6>")
	)
	(segment
		(start 389.157972 -277.060152)
		(end 389.624824 -277.32609)
		(width 0.12954)
		(layer "F.Cu")
		(net "M_K_CPU0_SB_DQS_DP<5>")
	)
	(segment
		(start 414.070038 -286.930338)
		(end 414.857438 -286.142938)
		(width 0.16002)
		(layer "In6.Cu")
		(net "M_K_CPU0_SB_DQS_DP<5>")
	)
	(segment
		(start 414.857438 -286.142938)
		(end 415.519108 -286.142938)
		(width 0.16002)
		(layer "In6.Cu")
		(net "M_K_CPU0_SB_DQS_DP<5>")
	)
	(segment
		(start 428.173642 -287.310322)
		(end 428.553626 -286.930338)
		(width 0.16002)
		(layer "In6.Cu")
		(net "M_K_CPU0_SB_DQS_DP<5>")
	)
	(segment
		(start 416.861498 -286.788352)
		(end 417.460176 -286.788352)
		(width 0.16002)
		(layer "In6.Cu")
		(net "M_K_CPU0_SB_DQS_DP<5>")
	)
	(segment
		(start 394.719048 -275.863558)
		(end 394.834872 -275.815552)
		(width 0.09525)
		(layer "In6.Cu")
		(net "M_K_CPU0_SB_DQS_DP<5>")
	)
	(segment
		(start 392.632692 -277.00097)
		(end 392.643106 -277.007066)
		(width 0.09525)
		(layer "In6.Cu")
		(net "M_K_CPU0_SB_DQS_DP<5>")
	)
	(segment
		(start 417.957254 -286.142938)
		(end 418.148008 -286.142938)
		(width 0.16002)
		(layer "In6.Cu")
		(net "M_K_CPU0_SB_DQS_DP<5>")
	)
	(segment
		(start 433.553362 -286.460184)
		(end 434.4035 -287.310322)
		(width 0.16002)
		(layer "In6.Cu")
		(net "M_K_CPU0_SB_DQS_DP<5>")
	)
	(segment
		(start 417.797234 -286.302958)
		(end 417.957254 -286.142938)
		(width 0.16002)
		(layer "In6.Cu")
		(net "M_K_CPU0_SB_DQS_DP<5>")
	)
	(segment
		(start 395.859254 -276.118066)
		(end 400.91233 -276.118066)
		(width 0.16002)
		(layer "In6.Cu")
		(net "M_K_CPU0_SB_DQS_DP<5>")
	)
	(segment
		(start 428.553626 -286.930338)
		(end 429.158146 -286.930338)
		(width 0.16002)
		(layer "In6.Cu")
		(net "M_K_CPU0_SB_DQS_DP<5>")
	)
	(segment
		(start 434.4035 -287.310322)
		(end 435.717696 -287.310322)
		(width 0.16002)
		(layer "In6.Cu")
		(net "M_K_CPU0_SB_DQS_DP<5>")
	)
	(segment
		(start 392.245596 -277.007066)
		(end 392.25601 -277.00097)
		(width 0.09525)
		(layer "In6.Cu")
		(net "M_K_CPU0_SB_DQS_DP<5>")
	)
	(segment
		(start 389.4709 -277.06066)
		(end 389.494014 -276.974046)
		(width 0.09525)
		(layer "In6.Cu")
		(net "M_K_CPU0_SB_DQS_DP<5>")
	)
	(segment
		(start 389.624824 -277.32609)
		(end 389.4709 -277.06066)
		(width 0.09525)
		(layer "In6.Cu")
		(net "M_K_CPU0_SB_DQS_DP<5>")
	)
	(segment
		(start 440.047634 -286.460184)
		(end 440.196732 -286.311086)
		(width 0.16002)
		(layer "In6.Cu")
		(net "M_K_CPU0_SB_DQS_DP<5>")
	)
	(segment
		(start 423.527474 -286.460184)
		(end 426.009308 -286.460184)
		(width 0.16002)
		(layer "In6.Cu")
		(net "M_K_CPU0_SB_DQS_DP<5>")
	)
	(segment
		(start 416.52444 -285.657544)
		(end 416.52444 -286.451294)
		(width 0.16002)
		(layer "In6.Cu")
		(net "M_K_CPU0_SB_DQS_DP<5>")
	)
	(segment
		(start 440.830208 -286.311086)
		(end 440.957208 -286.438086)
		(width 0.16002)
		(layer "In6.Cu")
		(net "M_K_CPU0_SB_DQS_DP<5>")
	)
	(segment
		(start 422.401492 -286.142938)
		(end 423.210228 -286.142938)
		(width 0.16002)
		(layer "In6.Cu")
		(net "M_K_CPU0_SB_DQS_DP<5>")
	)
	(segment
		(start 421.614092 -286.930338)
		(end 422.401492 -286.142938)
		(width 0.16002)
		(layer "In6.Cu")
		(net "M_K_CPU0_SB_DQS_DP<5>")
	)
	(segment
		(start 394.834872 -275.815552)
		(end 395.092174 -275.815552)
		(width 0.09525)
		(layer "In6.Cu")
		(net "M_K_CPU0_SB_DQS_DP<5>")
	)
	(segment
		(start 440.196732 -286.311086)
		(end 440.830208 -286.311086)
		(width 0.16002)
		(layer "In6.Cu")
		(net "M_K_CPU0_SB_DQS_DP<5>")
	)
	(segment
		(start 395.776704 -276.059138)
		(end 395.835632 -276.118066)
		(width 0.09525)
		(layer "In6.Cu")
		(net "M_K_CPU0_SB_DQS_DP<5>")
	)
	(segment
		(start 421.009572 -286.930338)
		(end 421.614092 -286.930338)
		(width 0.16002)
		(layer "In6.Cu")
		(net "M_K_CPU0_SB_DQS_DP<5>")
	)
	(segment
		(start 390.744964 -276.996144)
		(end 390.753346 -277.00097)
		(width 0.09525)
		(layer "In6.Cu")
		(net "M_K_CPU0_SB_DQS_DP<5>")
	)
	(segment
		(start 400.91233 -276.118066)
		(end 411.724602 -286.930338)
		(width 0.16002)
		(layer "In6.Cu")
		(net "M_K_CPU0_SB_DQS_DP<5>")
	)
	(segment
		(start 435.717696 -287.310322)
		(end 436.09768 -286.930338)
		(width 0.16002)
		(layer "In6.Cu")
		(net "M_K_CPU0_SB_DQS_DP<5>")
	)
	(segment
		(start 416.016186 -285.497524)
		(end 416.36442 -285.497524)
		(width 0.16002)
		(layer "In6.Cu")
		(net "M_K_CPU0_SB_DQS_DP<5>")
	)
	(segment
		(start 426.009308 -286.460184)
		(end 426.859446 -287.310322)
		(width 0.16002)
		(layer "In6.Cu")
		(net "M_K_CPU0_SB_DQS_DP<5>")
	)
	(segment
		(start 395.835632 -276.118066)
		(end 395.859254 -276.118066)
		(width 0.09525)
		(layer "In6.Cu")
		(net "M_K_CPU0_SB_DQS_DP<5>")
	)
	(segment
		(start 441.564268 -286.311086)
		(end 442.270134 -286.311086)
		(width 0.16002)
		(layer "In6.Cu")
		(net "M_K_CPU0_SB_DQS_DP<5>")
	)
	(segment
		(start 415.519108 -286.142938)
		(end 415.856166 -285.80588)
		(width 0.16002)
		(layer "In6.Cu")
		(net "M_K_CPU0_SB_DQS_DP<5>")
	)
	(segment
		(start 416.52444 -286.451294)
		(end 416.861498 -286.788352)
		(width 0.16002)
		(layer "In6.Cu")
		(net "M_K_CPU0_SB_DQS_DP<5>")
	)
	(segment
		(start 431.071528 -286.460184)
		(end 433.553362 -286.460184)
		(width 0.16002)
		(layer "In6.Cu")
		(net "M_K_CPU0_SB_DQS_DP<5>")
	)
	(segment
		(start 393.94511 -276.638004)
		(end 394.719048 -275.863558)
		(width 0.09525)
		(layer "In6.Cu")
		(net "M_K_CPU0_SB_DQS_DP<5>")
	)
	(segment
		(start 417.460176 -286.788352)
		(end 417.797234 -286.451294)
		(width 0.16002)
		(layer "In6.Cu")
		(net "M_K_CPU0_SB_DQS_DP<5>")
	)
	(segment
		(start 438.298336 -286.142938)
		(end 438.615582 -286.460184)
		(width 0.16002)
		(layer "In6.Cu")
		(net "M_K_CPU0_SB_DQS_DP<5>")
	)
	(segment
		(start 423.210228 -286.142938)
		(end 423.527474 -286.460184)
		(width 0.16002)
		(layer "In6.Cu")
		(net "M_K_CPU0_SB_DQS_DP<5>")
	)
	(segment
		(start 411.724602 -286.930338)
		(end 414.070038 -286.930338)
		(width 0.16002)
		(layer "In6.Cu")
		(net "M_K_CPU0_SB_DQS_DP<5>")
	)
	(segment
		(start 395.33576 -276.059138)
		(end 395.776704 -276.059138)
		(width 0.09525)
		(layer "In6.Cu")
		(net "M_K_CPU0_SB_DQS_DP<5>")
	)
	(segment
		(start 426.859446 -287.310322)
		(end 428.173642 -287.310322)
		(width 0.16002)
		(layer "In6.Cu")
		(net "M_K_CPU0_SB_DQS_DP<5>")
	)
	(segment
		(start 415.856166 -285.80588)
		(end 415.856166 -285.657544)
		(width 0.16002)
		(layer "In6.Cu")
		(net "M_K_CPU0_SB_DQS_DP<5>")
	)
	(segment
		(start 419.315392 -287.310322)
		(end 420.629588 -287.310322)
		(width 0.16002)
		(layer "In6.Cu")
		(net "M_K_CPU0_SB_DQS_DP<5>")
	)
	(segment
		(start 416.36442 -285.497524)
		(end 416.52444 -285.657544)
		(width 0.16002)
		(layer "In6.Cu")
		(net "M_K_CPU0_SB_DQS_DP<5>")
	)
	(segment
		(start 395.092174 -275.815552)
		(end 395.33576 -276.059138)
		(width 0.09525)
		(layer "In6.Cu")
		(net "M_K_CPU0_SB_DQS_DP<5>")
	)
	(segment
		(start 442.270134 -286.311086)
		(end 442.5442 -286.585152)
		(width 0.16002)
		(layer "In6.Cu")
		(net "M_K_CPU0_SB_DQS_DP<5>")
	)
	(segment
		(start 415.856166 -285.657544)
		(end 416.016186 -285.497524)
		(width 0.16002)
		(layer "In6.Cu")
		(net "M_K_CPU0_SB_DQS_DP<5>")
	)
	(segment
		(start 438.615582 -286.460184)
		(end 440.047634 -286.460184)
		(width 0.16002)
		(layer "In6.Cu")
		(net "M_K_CPU0_SB_DQS_DP<5>")
	)
	(segment
		(start 391.31621 -277.00097)
		(end 391.324592 -276.996144)
		(width 0.09525)
		(layer "In6.Cu")
		(net "M_K_CPU0_SB_DQS_DP<5>")
	)
	(segment
		(start 393.310618 -276.912578)
		(end 393.351512 -276.871684)
		(width 0.09525)
		(layer "In6.Cu")
		(net "M_K_CPU0_SB_DQS_DP<5>")
	)
	(segment
		(start 441.437268 -286.438086)
		(end 441.564268 -286.311086)
		(width 0.16002)
		(layer "In6.Cu")
		(net "M_K_CPU0_SB_DQS_DP<5>")
	)
	(segment
		(start 436.7022 -286.930338)
		(end 437.4896 -286.142938)
		(width 0.16002)
		(layer "In6.Cu")
		(net "M_K_CPU0_SB_DQS_DP<5>")
	)
	(segment
		(start 418.148008 -286.142938)
		(end 419.315392 -287.310322)
		(width 0.16002)
		(layer "In6.Cu")
		(net "M_K_CPU0_SB_DQS_DP<5>")
	)
	(segment
		(start 420.629588 -287.310322)
		(end 421.009572 -286.930338)
		(width 0.16002)
		(layer "In6.Cu")
		(net "M_K_CPU0_SB_DQS_DP<5>")
	)
	(segment
		(start 436.09768 -286.930338)
		(end 436.7022 -286.930338)
		(width 0.16002)
		(layer "In6.Cu")
		(net "M_K_CPU0_SB_DQS_DP<5>")
	)
	(segment
		(start 429.158146 -286.930338)
		(end 429.945546 -286.142938)
		(width 0.16002)
		(layer "In6.Cu")
		(net "M_K_CPU0_SB_DQS_DP<5>")
	)
	(segment
		(start 429.945546 -286.142938)
		(end 430.754282 -286.142938)
		(width 0.16002)
		(layer "In6.Cu")
		(net "M_K_CPU0_SB_DQS_DP<5>")
	)
	(segment
		(start 437.4896 -286.142938)
		(end 438.298336 -286.142938)
		(width 0.16002)
		(layer "In6.Cu")
		(net "M_K_CPU0_SB_DQS_DP<5>")
	)
	(segment
		(start 440.957208 -286.438086)
		(end 441.437268 -286.438086)
		(width 0.16002)
		(layer "In6.Cu")
		(net "M_K_CPU0_SB_DQS_DP<5>")
	)
	(segment
		(start 417.797234 -286.451294)
		(end 417.797234 -286.302958)
		(width 0.16002)
		(layer "In6.Cu")
		(net "M_K_CPU0_SB_DQS_DP<5>")
	)
	(segment
		(start 430.754282 -286.142938)
		(end 431.071528 -286.460184)
		(width 0.16002)
		(layer "In6.Cu")
		(net "M_K_CPU0_SB_DQS_DP<5>")
	)
	(segment
		(start 392.25601 -277.00097)
		(end 392.264392 -276.996144)
		(width 0.09525)
		(layer "In6.Cu")
		(net "M_K_CPU0_SB_DQS_DP<5>")
	)
	(arc
		(start 392.643106 -277.007066)
		(mid 392.920377 -277.076865)
		(end 393.196064 -277.00097)
		(width 0.09525)
		(layer "In6.Cu")
		(net "M_K_CPU0_SB_DQS_DP<5>")
	)
	(arc
		(start 393.634214 -276.74824)
		(mid 393.798096 -276.716916)
		(end 393.94511 -276.638004)
		(width 0.09525)
		(layer "In6.Cu")
		(net "M_K_CPU0_SB_DQS_DP<5>")
	)
	(arc
		(start 392.264392 -276.996144)
		(mid 392.44917 -276.950351)
		(end 392.632692 -277.00097)
		(width 0.09525)
		(layer "In6.Cu")
		(net "M_K_CPU0_SB_DQS_DP<5>")
	)
	(arc
		(start 390.753346 -277.00097)
		(mid 391.034778 -277.076725)
		(end 391.31621 -277.00097)
		(width 0.09525)
		(layer "In6.Cu")
		(net "M_K_CPU0_SB_DQS_DP<5>")
	)
	(arc
		(start 391.324592 -276.996144)
		(mid 391.509624 -276.95023)
		(end 391.6934 -277.00097)
		(width 0.09525)
		(layer "In6.Cu")
		(net "M_K_CPU0_SB_DQS_DP<5>")
	)
	(arc
		(start 393.196064 -277.00097)
		(mid 393.256199 -276.960479)
		(end 393.310618 -276.912578)
		(width 0.09525)
		(layer "In6.Cu")
		(net "M_K_CPU0_SB_DQS_DP<5>")
	)
	(arc
		(start 391.6934 -277.00097)
		(mid 391.968689 -277.076691)
		(end 392.245596 -277.007066)
		(width 0.09525)
		(layer "In6.Cu")
		(net "M_K_CPU0_SB_DQS_DP<5>")
	)
	(arc
		(start 390.376156 -277.00097)
		(mid 390.559931 -276.950198)
		(end 390.744964 -276.996144)
		(width 0.09525)
		(layer "In6.Cu")
		(net "M_K_CPU0_SB_DQS_DP<5>")
	)
	(arc
		(start 389.813292 -277.00097)
		(mid 390.094724 -277.076725)
		(end 390.376156 -277.00097)
		(width 0.09525)
		(layer "In6.Cu")
		(net "M_K_CPU0_SB_DQS_DP<5>")
	)
	(arc
		(start 389.494014 -276.974046)
		(mid 389.656665 -276.951786)
		(end 389.813292 -277.00097)
		(width 0.09525)
		(layer "In6.Cu")
		(net "M_K_CPU0_SB_DQS_DP<5>")
	)
	(arc
		(start 393.351512 -276.871684)
		(mid 393.481195 -276.783245)
		(end 393.634214 -276.74824)
		(width 0.09525)
		(layer "In6.Cu")
		(net "M_K_CPU0_SB_DQS_DP<5>")
	)
	(segment
		(start 389.157972 -272.200116)
		(end 389.624824 -272.466054)
		(width 0.12954)
		(layer "F.Cu")
		(net "M_K_CPU0_SB_DQS_DP<4>")
	)
	(segment
		(start 410.971492 -275.781516)
		(end 411.218888 -276.028912)
		(width 0.16002)
		(layer "In6.Cu")
		(net "M_K_CPU0_SB_DQS_DP<4>")
	)
	(segment
		(start 415.98342 -277.11019)
		(end 418.465254 -277.11019)
		(width 0.16002)
		(layer "In6.Cu")
		(net "M_K_CPU0_SB_DQS_DP<4>")
	)
	(segment
		(start 395.835632 -270.4465)
		(end 395.859254 -270.4465)
		(width 0.09525)
		(layer "In6.Cu")
		(net "M_K_CPU0_SB_DQS_DP<4>")
	)
	(segment
		(start 411.218888 -276.028912)
		(end 411.218888 -276.254718)
		(width 0.16002)
		(layer "In6.Cu")
		(net "M_K_CPU0_SB_DQS_DP<4>")
	)
	(segment
		(start 410.18841 -275.86178)
		(end 410.66466 -275.86178)
		(width 0.16002)
		(layer "In6.Cu")
		(net "M_K_CPU0_SB_DQS_DP<4>")
	)
	(segment
		(start 409.764738 -275.438108)
		(end 410.18841 -275.86178)
		(width 0.16002)
		(layer "In6.Cu")
		(net "M_K_CPU0_SB_DQS_DP<4>")
	)
	(segment
		(start 421.009572 -277.580344)
		(end 421.614092 -277.580344)
		(width 0.16002)
		(layer "In6.Cu")
		(net "M_K_CPU0_SB_DQS_DP<4>")
	)
	(segment
		(start 421.614092 -277.580344)
		(end 422.401492 -276.792944)
		(width 0.16002)
		(layer "In6.Cu")
		(net "M_K_CPU0_SB_DQS_DP<4>")
	)
	(segment
		(start 429.158146 -277.580344)
		(end 429.945546 -276.792944)
		(width 0.16002)
		(layer "In6.Cu")
		(net "M_K_CPU0_SB_DQS_DP<4>")
	)
	(segment
		(start 411.13837 -276.335236)
		(end 411.13837 -276.81174)
		(width 0.16002)
		(layer "In6.Cu")
		(net "M_K_CPU0_SB_DQS_DP<4>")
	)
	(segment
		(start 419.315392 -277.960328)
		(end 420.629588 -277.960328)
		(width 0.16002)
		(layer "In6.Cu")
		(net "M_K_CPU0_SB_DQS_DP<4>")
	)
	(segment
		(start 391.31621 -272.140934)
		(end 391.324592 -272.136108)
		(width 0.09525)
		(layer "In6.Cu")
		(net "M_K_CPU0_SB_DQS_DP<4>")
	)
	(segment
		(start 392.245596 -272.14703)
		(end 392.25601 -272.140934)
		(width 0.09525)
		(layer "In6.Cu")
		(net "M_K_CPU0_SB_DQS_DP<4>")
	)
	(segment
		(start 408.471624 -273.507454)
		(end 408.391106 -273.587972)
		(width 0.16002)
		(layer "In6.Cu")
		(net "M_K_CPU0_SB_DQS_DP<4>")
	)
	(segment
		(start 407.917396 -273.114516)
		(end 407.997914 -273.034252)
		(width 0.16002)
		(layer "In6.Cu")
		(net "M_K_CPU0_SB_DQS_DP<4>")
	)
	(segment
		(start 408.471624 -273.281648)
		(end 408.471624 -273.507454)
		(width 0.16002)
		(layer "In6.Cu")
		(net "M_K_CPU0_SB_DQS_DP<4>")
	)
	(segment
		(start 393.311126 -272.05178)
		(end 393.474448 -271.888458)
		(width 0.09525)
		(layer "In6.Cu")
		(net "M_K_CPU0_SB_DQS_DP<4>")
	)
	(segment
		(start 410.66466 -275.86178)
		(end 410.745178 -275.781516)
		(width 0.16002)
		(layer "In6.Cu")
		(net "M_K_CPU0_SB_DQS_DP<4>")
	)
	(segment
		(start 392.25601 -272.140934)
		(end 392.27379 -272.130774)
		(width 0.09525)
		(layer "In6.Cu")
		(net "M_K_CPU0_SB_DQS_DP<4>")
	)
	(segment
		(start 435.717696 -277.960328)
		(end 436.09768 -277.580344)
		(width 0.16002)
		(layer "In6.Cu")
		(net "M_K_CPU0_SB_DQS_DP<4>")
	)
	(segment
		(start 394.616178 -270.387572)
		(end 395.776704 -270.387572)
		(width 0.09525)
		(layer "In6.Cu")
		(net "M_K_CPU0_SB_DQS_DP<4>")
	)
	(segment
		(start 429.945546 -276.792944)
		(end 430.754282 -276.792944)
		(width 0.16002)
		(layer "In6.Cu")
		(net "M_K_CPU0_SB_DQS_DP<4>")
	)
	(segment
		(start 409.764738 -274.961604)
		(end 409.764738 -275.438108)
		(width 0.16002)
		(layer "In6.Cu")
		(net "M_K_CPU0_SB_DQS_DP<4>")
	)
	(segment
		(start 408.224228 -273.034252)
		(end 408.471624 -273.281648)
		(width 0.16002)
		(layer "In6.Cu")
		(net "M_K_CPU0_SB_DQS_DP<4>")
	)
	(segment
		(start 440.911488 -277.088092)
		(end 441.391548 -277.088092)
		(width 0.16002)
		(layer "In6.Cu")
		(net "M_K_CPU0_SB_DQS_DP<4>")
	)
	(segment
		(start 423.527474 -277.11019)
		(end 426.009308 -277.11019)
		(width 0.16002)
		(layer "In6.Cu")
		(net "M_K_CPU0_SB_DQS_DP<4>")
	)
	(segment
		(start 414.857438 -276.792944)
		(end 415.666174 -276.792944)
		(width 0.16002)
		(layer "In6.Cu")
		(net "M_K_CPU0_SB_DQS_DP<4>")
	)
	(segment
		(start 395.859254 -270.4465)
		(end 404.77313 -270.4465)
		(width 0.16002)
		(layer "In6.Cu")
		(net "M_K_CPU0_SB_DQS_DP<4>")
	)
	(segment
		(start 407.997914 -273.034252)
		(end 408.224228 -273.034252)
		(width 0.16002)
		(layer "In6.Cu")
		(net "M_K_CPU0_SB_DQS_DP<4>")
	)
	(segment
		(start 426.009308 -277.11019)
		(end 426.859446 -277.960328)
		(width 0.16002)
		(layer "In6.Cu")
		(net "M_K_CPU0_SB_DQS_DP<4>")
	)
	(segment
		(start 395.776704 -270.387572)
		(end 395.835632 -270.4465)
		(width 0.09525)
		(layer "In6.Cu")
		(net "M_K_CPU0_SB_DQS_DP<4>")
	)
	(segment
		(start 407.441146 -273.114516)
		(end 407.917396 -273.114516)
		(width 0.16002)
		(layer "In6.Cu")
		(net "M_K_CPU0_SB_DQS_DP<4>")
	)
	(segment
		(start 437.4896 -276.792944)
		(end 438.298336 -276.792944)
		(width 0.16002)
		(layer "In6.Cu")
		(net "M_K_CPU0_SB_DQS_DP<4>")
	)
	(segment
		(start 410.745178 -275.781516)
		(end 410.971492 -275.781516)
		(width 0.16002)
		(layer "In6.Cu")
		(net "M_K_CPU0_SB_DQS_DP<4>")
	)
	(segment
		(start 392.6332 -272.140426)
		(end 392.647932 -272.149062)
		(width 0.09525)
		(layer "In6.Cu")
		(net "M_K_CPU0_SB_DQS_DP<4>")
	)
	(segment
		(start 420.629588 -277.960328)
		(end 421.009572 -277.580344)
		(width 0.16002)
		(layer "In6.Cu")
		(net "M_K_CPU0_SB_DQS_DP<4>")
	)
	(segment
		(start 431.071528 -277.11019)
		(end 433.553362 -277.11019)
		(width 0.16002)
		(layer "In6.Cu")
		(net "M_K_CPU0_SB_DQS_DP<4>")
	)
	(segment
		(start 406.067514 -271.740884)
		(end 406.543764 -271.740884)
		(width 0.16002)
		(layer "In6.Cu")
		(net "M_K_CPU0_SB_DQS_DP<4>")
	)
	(segment
		(start 406.850596 -271.66062)
		(end 407.097992 -271.908016)
		(width 0.16002)
		(layer "In6.Cu")
		(net "M_K_CPU0_SB_DQS_DP<4>")
	)
	(segment
		(start 423.210228 -276.792944)
		(end 423.527474 -277.11019)
		(width 0.16002)
		(layer "In6.Cu")
		(net "M_K_CPU0_SB_DQS_DP<4>")
	)
	(segment
		(start 441.391548 -277.088092)
		(end 441.518548 -276.961092)
		(width 0.16002)
		(layer "In6.Cu")
		(net "M_K_CPU0_SB_DQS_DP<4>")
	)
	(segment
		(start 418.465254 -277.11019)
		(end 419.315392 -277.960328)
		(width 0.16002)
		(layer "In6.Cu")
		(net "M_K_CPU0_SB_DQS_DP<4>")
	)
	(segment
		(start 406.543764 -271.740884)
		(end 406.624282 -271.66062)
		(width 0.16002)
		(layer "In6.Cu")
		(net "M_K_CPU0_SB_DQS_DP<4>")
	)
	(segment
		(start 428.553626 -277.580344)
		(end 429.158146 -277.580344)
		(width 0.16002)
		(layer "In6.Cu")
		(net "M_K_CPU0_SB_DQS_DP<4>")
	)
	(segment
		(start 409.291028 -274.488148)
		(end 409.371546 -274.407884)
		(width 0.16002)
		(layer "In6.Cu")
		(net "M_K_CPU0_SB_DQS_DP<4>")
	)
	(segment
		(start 434.4035 -277.960328)
		(end 435.717696 -277.960328)
		(width 0.16002)
		(layer "In6.Cu")
		(net "M_K_CPU0_SB_DQS_DP<4>")
	)
	(segment
		(start 411.906974 -277.580344)
		(end 414.070038 -277.580344)
		(width 0.16002)
		(layer "In6.Cu")
		(net "M_K_CPU0_SB_DQS_DP<4>")
	)
	(segment
		(start 408.814778 -274.488148)
		(end 409.291028 -274.488148)
		(width 0.16002)
		(layer "In6.Cu")
		(net "M_K_CPU0_SB_DQS_DP<4>")
	)
	(segment
		(start 430.754282 -276.792944)
		(end 431.071528 -277.11019)
		(width 0.16002)
		(layer "In6.Cu")
		(net "M_K_CPU0_SB_DQS_DP<4>")
	)
	(segment
		(start 404.77313 -270.4465)
		(end 406.067514 -271.740884)
		(width 0.16002)
		(layer "In6.Cu")
		(net "M_K_CPU0_SB_DQS_DP<4>")
	)
	(segment
		(start 414.070038 -277.580344)
		(end 414.857438 -276.792944)
		(width 0.16002)
		(layer "In6.Cu")
		(net "M_K_CPU0_SB_DQS_DP<4>")
	)
	(segment
		(start 428.173642 -277.960328)
		(end 428.553626 -277.580344)
		(width 0.16002)
		(layer "In6.Cu")
		(net "M_K_CPU0_SB_DQS_DP<4>")
	)
	(segment
		(start 440.196732 -276.961092)
		(end 440.784488 -276.961092)
		(width 0.16002)
		(layer "In6.Cu")
		(net "M_K_CPU0_SB_DQS_DP<4>")
	)
	(segment
		(start 393.728448 -271.275302)
		(end 394.616178 -270.387572)
		(width 0.09525)
		(layer "In6.Cu")
		(net "M_K_CPU0_SB_DQS_DP<4>")
	)
	(segment
		(start 390.744964 -272.136108)
		(end 390.753346 -272.140934)
		(width 0.09525)
		(layer "In6.Cu")
		(net "M_K_CPU0_SB_DQS_DP<4>")
	)
	(segment
		(start 389.4709 -272.200624)
		(end 389.494014 -272.11401)
		(width 0.09525)
		(layer "In6.Cu")
		(net "M_K_CPU0_SB_DQS_DP<4>")
	)
	(segment
		(start 409.371546 -274.407884)
		(end 409.59786 -274.407884)
		(width 0.16002)
		(layer "In6.Cu")
		(net "M_K_CPU0_SB_DQS_DP<4>")
	)
	(segment
		(start 441.518548 -276.961092)
		(end 442.270134 -276.961092)
		(width 0.16002)
		(layer "In6.Cu")
		(net "M_K_CPU0_SB_DQS_DP<4>")
	)
	(segment
		(start 408.391106 -274.064476)
		(end 408.814778 -274.488148)
		(width 0.16002)
		(layer "In6.Cu")
		(net "M_K_CPU0_SB_DQS_DP<4>")
	)
	(segment
		(start 436.09768 -277.580344)
		(end 436.7022 -277.580344)
		(width 0.16002)
		(layer "In6.Cu")
		(net "M_K_CPU0_SB_DQS_DP<4>")
	)
	(segment
		(start 389.624824 -272.466054)
		(end 389.4709 -272.200624)
		(width 0.09525)
		(layer "In6.Cu")
		(net "M_K_CPU0_SB_DQS_DP<4>")
	)
	(segment
		(start 438.615582 -277.11019)
		(end 440.047634 -277.11019)
		(width 0.16002)
		(layer "In6.Cu")
		(net "M_K_CPU0_SB_DQS_DP<4>")
	)
	(segment
		(start 411.13837 -276.81174)
		(end 411.906974 -277.580344)
		(width 0.16002)
		(layer "In6.Cu")
		(net "M_K_CPU0_SB_DQS_DP<4>")
	)
	(segment
		(start 442.270134 -276.961092)
		(end 442.5442 -277.235158)
		(width 0.16002)
		(layer "In6.Cu")
		(net "M_K_CPU0_SB_DQS_DP<4>")
	)
	(segment
		(start 440.784488 -276.961092)
		(end 440.911488 -277.088092)
		(width 0.16002)
		(layer "In6.Cu")
		(net "M_K_CPU0_SB_DQS_DP<4>")
	)
	(segment
		(start 409.845256 -274.65528)
		(end 409.845256 -274.881086)
		(width 0.16002)
		(layer "In6.Cu")
		(net "M_K_CPU0_SB_DQS_DP<4>")
	)
	(segment
		(start 422.401492 -276.792944)
		(end 423.210228 -276.792944)
		(width 0.16002)
		(layer "In6.Cu")
		(net "M_K_CPU0_SB_DQS_DP<4>")
	)
	(segment
		(start 407.017474 -272.690844)
		(end 407.441146 -273.114516)
		(width 0.16002)
		(layer "In6.Cu")
		(net "M_K_CPU0_SB_DQS_DP<4>")
	)
	(segment
		(start 407.017474 -272.21434)
		(end 407.017474 -272.690844)
		(width 0.16002)
		(layer "In6.Cu")
		(net "M_K_CPU0_SB_DQS_DP<4>")
	)
	(segment
		(start 411.218888 -276.254718)
		(end 411.13837 -276.335236)
		(width 0.16002)
		(layer "In6.Cu")
		(net "M_K_CPU0_SB_DQS_DP<4>")
	)
	(segment
		(start 415.666174 -276.792944)
		(end 415.98342 -277.11019)
		(width 0.16002)
		(layer "In6.Cu")
		(net "M_K_CPU0_SB_DQS_DP<4>")
	)
	(segment
		(start 438.298336 -276.792944)
		(end 438.615582 -277.11019)
		(width 0.16002)
		(layer "In6.Cu")
		(net "M_K_CPU0_SB_DQS_DP<4>")
	)
	(segment
		(start 407.097992 -271.908016)
		(end 407.097992 -272.133822)
		(width 0.16002)
		(layer "In6.Cu")
		(net "M_K_CPU0_SB_DQS_DP<4>")
	)
	(segment
		(start 408.391106 -273.587972)
		(end 408.391106 -274.064476)
		(width 0.16002)
		(layer "In6.Cu")
		(net "M_K_CPU0_SB_DQS_DP<4>")
	)
	(segment
		(start 406.624282 -271.66062)
		(end 406.850596 -271.66062)
		(width 0.16002)
		(layer "In6.Cu")
		(net "M_K_CPU0_SB_DQS_DP<4>")
	)
	(segment
		(start 409.845256 -274.881086)
		(end 409.764738 -274.961604)
		(width 0.16002)
		(layer "In6.Cu")
		(net "M_K_CPU0_SB_DQS_DP<4>")
	)
	(segment
		(start 426.859446 -277.960328)
		(end 428.173642 -277.960328)
		(width 0.16002)
		(layer "In6.Cu")
		(net "M_K_CPU0_SB_DQS_DP<4>")
	)
	(segment
		(start 436.7022 -277.580344)
		(end 437.4896 -276.792944)
		(width 0.16002)
		(layer "In6.Cu")
		(net "M_K_CPU0_SB_DQS_DP<4>")
	)
	(segment
		(start 409.59786 -274.407884)
		(end 409.845256 -274.65528)
		(width 0.16002)
		(layer "In6.Cu")
		(net "M_K_CPU0_SB_DQS_DP<4>")
	)
	(segment
		(start 407.097992 -272.133822)
		(end 407.017474 -272.21434)
		(width 0.16002)
		(layer "In6.Cu")
		(net "M_K_CPU0_SB_DQS_DP<4>")
	)
	(segment
		(start 433.553362 -277.11019)
		(end 434.4035 -277.960328)
		(width 0.16002)
		(layer "In6.Cu")
		(net "M_K_CPU0_SB_DQS_DP<4>")
	)
	(segment
		(start 440.047634 -277.11019)
		(end 440.196732 -276.961092)
		(width 0.16002)
		(layer "In6.Cu")
		(net "M_K_CPU0_SB_DQS_DP<4>")
	)
	(arc
		(start 391.324592 -272.136108)
		(mid 391.509624 -272.090194)
		(end 391.6934 -272.140934)
		(width 0.09525)
		(layer "In6.Cu")
		(net "M_K_CPU0_SB_DQS_DP<4>")
	)
	(arc
		(start 391.6934 -272.140934)
		(mid 391.968689 -272.216655)
		(end 392.245596 -272.14703)
		(width 0.09525)
		(layer "In6.Cu")
		(net "M_K_CPU0_SB_DQS_DP<4>")
	)
	(arc
		(start 389.494014 -272.11401)
		(mid 389.656665 -272.09175)
		(end 389.813292 -272.140934)
		(width 0.09525)
		(layer "In6.Cu")
		(net "M_K_CPU0_SB_DQS_DP<4>")
	)
	(arc
		(start 392.647932 -272.149062)
		(mid 392.923137 -272.216265)
		(end 393.196064 -272.140426)
		(width 0.09525)
		(layer "In6.Cu")
		(net "M_K_CPU0_SB_DQS_DP<4>")
	)
	(arc
		(start 390.376156 -272.140934)
		(mid 390.559931 -272.090162)
		(end 390.744964 -272.136108)
		(width 0.09525)
		(layer "In6.Cu")
		(net "M_K_CPU0_SB_DQS_DP<4>")
	)
	(arc
		(start 393.633198 -271.505172)
		(mid 393.657946 -271.380754)
		(end 393.728448 -271.275302)
		(width 0.09525)
		(layer "In6.Cu")
		(net "M_K_CPU0_SB_DQS_DP<4>")
	)
	(arc
		(start 389.813292 -272.140934)
		(mid 390.094724 -272.216689)
		(end 390.376156 -272.140934)
		(width 0.09525)
		(layer "In6.Cu")
		(net "M_K_CPU0_SB_DQS_DP<4>")
	)
	(arc
		(start 393.196064 -272.140426)
		(mid 393.256485 -272.099853)
		(end 393.311126 -272.05178)
		(width 0.09525)
		(layer "In6.Cu")
		(net "M_K_CPU0_SB_DQS_DP<4>")
	)
	(arc
		(start 390.753346 -272.140934)
		(mid 391.034778 -272.216689)
		(end 391.31621 -272.140934)
		(width 0.09525)
		(layer "In6.Cu")
		(net "M_K_CPU0_SB_DQS_DP<4>")
	)
	(arc
		(start 392.27379 -272.130774)
		(mid 392.454737 -272.089844)
		(end 392.6332 -272.140426)
		(width 0.09525)
		(layer "In6.Cu")
		(net "M_K_CPU0_SB_DQS_DP<4>")
	)
	(arc
		(start 393.474448 -271.888458)
		(mid 393.591949 -271.712605)
		(end 393.633198 -271.505172)
		(width 0.09525)
		(layer "In6.Cu")
		(net "M_K_CPU0_SB_DQS_DP<4>")
	)
	(segment
		(start 390.098026 -290.019994)
		(end 390.564878 -290.285932)
		(width 0.12954)
		(layer "F.Cu")
		(net "M_K_CPU0_SB_DQS_DP<3>")
	)
	(segment
		(start 410.728668 -313.40044)
		(end 396.724378 -299.39615)
		(width 0.16002)
		(layer "In6.Cu")
		(net "M_K_CPU0_SB_DQS_DP<3>")
	)
	(segment
		(start 433.473352 -313.059826)
		(end 432.623468 -312.209942)
		(width 0.16002)
		(layer "In6.Cu")
		(net "M_K_CPU0_SB_DQS_DP<3>")
	)
	(segment
		(start 422.77665 -312.54954)
		(end 422.38803 -312.54954)
		(width 0.16002)
		(layer "In6.Cu")
		(net "M_K_CPU0_SB_DQS_DP<3>")
	)
	(segment
		(start 390.718802 -290.551362)
		(end 390.564878 -290.285932)
		(width 0.09525)
		(layer "In6.Cu")
		(net "M_K_CPU0_SB_DQS_DP<3>")
	)
	(segment
		(start 421.13581 -313.40044)
		(end 420.795196 -313.059826)
		(width 0.16002)
		(layer "In6.Cu")
		(net "M_K_CPU0_SB_DQS_DP<3>")
	)
	(segment
		(start 391.324592 -290.615878)
		(end 391.31621 -290.611052)
		(width 0.09525)
		(layer "In6.Cu")
		(net "M_K_CPU0_SB_DQS_DP<3>")
	)
	(segment
		(start 443.771274 -313.40806)
		(end 443.147196 -312.783982)
		(width 0.16002)
		(layer "In6.Cu")
		(net "M_K_CPU0_SB_DQS_DP<3>")
	)
	(segment
		(start 430.660302 -312.209942)
		(end 430.320704 -312.54954)
		(width 0.16002)
		(layer "In6.Cu")
		(net "M_K_CPU0_SB_DQS_DP<3>")
	)
	(segment
		(start 436.625238 -313.40044)
		(end 436.223918 -313.40044)
		(width 0.16002)
		(layer "In6.Cu")
		(net "M_K_CPU0_SB_DQS_DP<3>")
	)
	(segment
		(start 440.36234 -312.209942)
		(end 438.204356 -312.209942)
		(width 0.16002)
		(layer "In6.Cu")
		(net "M_K_CPU0_SB_DQS_DP<3>")
	)
	(segment
		(start 396.724378 -295.204388)
		(end 395.06017 -293.540942)
		(width 0.16002)
		(layer "In6.Cu")
		(net "M_K_CPU0_SB_DQS_DP<3>")
	)
	(segment
		(start 421.53713 -313.40044)
		(end 421.13581 -313.40044)
		(width 0.16002)
		(layer "In6.Cu")
		(net "M_K_CPU0_SB_DQS_DP<3>")
	)
	(segment
		(start 393.691618 -291.385752)
		(end 393.452604 -290.840922)
		(width 0.09525)
		(layer "In6.Cu")
		(net "M_K_CPU0_SB_DQS_DP<3>")
	)
	(segment
		(start 396.724378 -299.39615)
		(end 396.724378 -295.204388)
		(width 0.16002)
		(layer "In6.Cu")
		(net "M_K_CPU0_SB_DQS_DP<3>")
	)
	(segment
		(start 423.116248 -312.209942)
		(end 422.77665 -312.54954)
		(width 0.16002)
		(layer "In6.Cu")
		(net "M_K_CPU0_SB_DQS_DP<3>")
	)
	(segment
		(start 438.204356 -312.209942)
		(end 437.864758 -312.54954)
		(width 0.16002)
		(layer "In6.Cu")
		(net "M_K_CPU0_SB_DQS_DP<3>")
	)
	(segment
		(start 415.572194 -312.209942)
		(end 415.232596 -312.54954)
		(width 0.16002)
		(layer "In6.Cu")
		(net "M_K_CPU0_SB_DQS_DP<3>")
	)
	(segment
		(start 392.647932 -290.602416)
		(end 392.6332 -290.611052)
		(width 0.09525)
		(layer "In6.Cu")
		(net "M_K_CPU0_SB_DQS_DP<3>")
	)
	(segment
		(start 444.15075 -313.40806)
		(end 443.771274 -313.40806)
		(width 0.16002)
		(layer "In6.Cu")
		(net "M_K_CPU0_SB_DQS_DP<3>")
	)
	(segment
		(start 430.320704 -312.54954)
		(end 429.932084 -312.54954)
		(width 0.16002)
		(layer "In6.Cu")
		(net "M_K_CPU0_SB_DQS_DP<3>")
	)
	(segment
		(start 425.079414 -312.209942)
		(end 423.116248 -312.209942)
		(width 0.16002)
		(layer "In6.Cu")
		(net "M_K_CPU0_SB_DQS_DP<3>")
	)
	(segment
		(start 395.043406 -293.524178)
		(end 394.960094 -293.524686)
		(width 0.09525)
		(layer "In6.Cu")
		(net "M_K_CPU0_SB_DQS_DP<3>")
	)
	(segment
		(start 440.93638 -312.783982)
		(end 440.36234 -312.209942)
		(width 0.16002)
		(layer "In6.Cu")
		(net "M_K_CPU0_SB_DQS_DP<3>")
	)
	(segment
		(start 437.864758 -312.54954)
		(end 437.476138 -312.54954)
		(width 0.16002)
		(layer "In6.Cu")
		(net "M_K_CPU0_SB_DQS_DP<3>")
	)
	(segment
		(start 393.452604 -290.840922)
		(end 393.310618 -290.698936)
		(width 0.09525)
		(layer "In6.Cu")
		(net "M_K_CPU0_SB_DQS_DP<3>")
	)
	(segment
		(start 394.960094 -293.524686)
		(end 394.335254 -292.901116)
		(width 0.09525)
		(layer "In6.Cu")
		(net "M_K_CPU0_SB_DQS_DP<3>")
	)
	(segment
		(start 414.843976 -312.54954)
		(end 413.993076 -313.40044)
		(width 0.16002)
		(layer "In6.Cu")
		(net "M_K_CPU0_SB_DQS_DP<3>")
	)
	(segment
		(start 429.932084 -312.54954)
		(end 429.081184 -313.40044)
		(width 0.16002)
		(layer "In6.Cu")
		(net "M_K_CPU0_SB_DQS_DP<3>")
	)
	(segment
		(start 422.38803 -312.54954)
		(end 421.53713 -313.40044)
		(width 0.16002)
		(layer "In6.Cu")
		(net "M_K_CPU0_SB_DQS_DP<3>")
	)
	(segment
		(start 436.223918 -313.40044)
		(end 435.883304 -313.059826)
		(width 0.16002)
		(layer "In6.Cu")
		(net "M_K_CPU0_SB_DQS_DP<3>")
	)
	(segment
		(start 432.623468 -312.209942)
		(end 430.660302 -312.209942)
		(width 0.16002)
		(layer "In6.Cu")
		(net "M_K_CPU0_SB_DQS_DP<3>")
	)
	(segment
		(start 418.385244 -313.059826)
		(end 417.53536 -312.209942)
		(width 0.16002)
		(layer "In6.Cu")
		(net "M_K_CPU0_SB_DQS_DP<3>")
	)
	(segment
		(start 444.349886 -313.208924)
		(end 444.15075 -313.40806)
		(width 0.16002)
		(layer "In6.Cu")
		(net "M_K_CPU0_SB_DQS_DP<3>")
	)
	(segment
		(start 413.993076 -313.40044)
		(end 410.728668 -313.40044)
		(width 0.16002)
		(layer "In6.Cu")
		(net "M_K_CPU0_SB_DQS_DP<3>")
	)
	(segment
		(start 420.795196 -313.059826)
		(end 418.385244 -313.059826)
		(width 0.16002)
		(layer "In6.Cu")
		(net "M_K_CPU0_SB_DQS_DP<3>")
	)
	(segment
		(start 437.476138 -312.54954)
		(end 436.625238 -313.40044)
		(width 0.16002)
		(layer "In6.Cu")
		(net "M_K_CPU0_SB_DQS_DP<3>")
	)
	(segment
		(start 395.06017 -293.540942)
		(end 395.043406 -293.524178)
		(width 0.09525)
		(layer "In6.Cu")
		(net "M_K_CPU0_SB_DQS_DP<3>")
	)
	(segment
		(start 428.679864 -313.40044)
		(end 428.33925 -313.059826)
		(width 0.16002)
		(layer "In6.Cu")
		(net "M_K_CPU0_SB_DQS_DP<3>")
	)
	(segment
		(start 429.081184 -313.40044)
		(end 428.679864 -313.40044)
		(width 0.16002)
		(layer "In6.Cu")
		(net "M_K_CPU0_SB_DQS_DP<3>")
	)
	(segment
		(start 415.232596 -312.54954)
		(end 414.843976 -312.54954)
		(width 0.16002)
		(layer "In6.Cu")
		(net "M_K_CPU0_SB_DQS_DP<3>")
	)
	(segment
		(start 443.147196 -312.783982)
		(end 440.93638 -312.783982)
		(width 0.16002)
		(layer "In6.Cu")
		(net "M_K_CPU0_SB_DQS_DP<3>")
	)
	(segment
		(start 425.929298 -313.059826)
		(end 425.079414 -312.209942)
		(width 0.16002)
		(layer "In6.Cu")
		(net "M_K_CPU0_SB_DQS_DP<3>")
	)
	(segment
		(start 417.53536 -312.209942)
		(end 415.572194 -312.209942)
		(width 0.16002)
		(layer "In6.Cu")
		(net "M_K_CPU0_SB_DQS_DP<3>")
	)
	(segment
		(start 428.33925 -313.059826)
		(end 425.929298 -313.059826)
		(width 0.16002)
		(layer "In6.Cu")
		(net "M_K_CPU0_SB_DQS_DP<3>")
	)
	(segment
		(start 390.81964 -290.578032)
		(end 390.718802 -290.551362)
		(width 0.09525)
		(layer "In6.Cu")
		(net "M_K_CPU0_SB_DQS_DP<3>")
	)
	(segment
		(start 435.883304 -313.059826)
		(end 433.473352 -313.059826)
		(width 0.16002)
		(layer "In6.Cu")
		(net "M_K_CPU0_SB_DQS_DP<3>")
	)
	(segment
		(start 394.335254 -292.029388)
		(end 393.691618 -291.385752)
		(width 0.09525)
		(layer "In6.Cu")
		(net "M_K_CPU0_SB_DQS_DP<3>")
	)
	(segment
		(start 446.370456 -313.208924)
		(end 444.349886 -313.208924)
		(width 0.16002)
		(layer "In6.Cu")
		(net "M_K_CPU0_SB_DQS_DP<3>")
	)
	(segment
		(start 394.335254 -292.901116)
		(end 394.335254 -292.029388)
		(width 0.09525)
		(layer "In6.Cu")
		(net "M_K_CPU0_SB_DQS_DP<3>")
	)
	(segment
		(start 446.644268 -312.935112)
		(end 446.370456 -313.208924)
		(width 0.16002)
		(layer "In6.Cu")
		(net "M_K_CPU0_SB_DQS_DP<3>")
	)
	(arc
		(start 391.6934 -290.611052)
		(mid 391.509625 -290.661824)
		(end 391.324592 -290.615878)
		(width 0.09525)
		(layer "In6.Cu")
		(net "M_K_CPU0_SB_DQS_DP<3>")
	)
	(arc
		(start 390.839452 -290.570158)
		(mid 390.829509 -290.574001)
		(end 390.81964 -290.578032)
		(width 0.09525)
		(layer "In6.Cu")
		(net "M_K_CPU0_SB_DQS_DP<3>")
	)
	(arc
		(start 393.19581 -290.611052)
		(mid 392.922993 -290.53524)
		(end 392.647932 -290.602416)
		(width 0.09525)
		(layer "In6.Cu")
		(net "M_K_CPU0_SB_DQS_DP<3>")
	)
	(arc
		(start 392.256264 -290.611052)
		(mid 391.974832 -290.535297)
		(end 391.6934 -290.611052)
		(width 0.09525)
		(layer "In6.Cu")
		(net "M_K_CPU0_SB_DQS_DP<3>")
	)
	(arc
		(start 392.6332 -290.611052)
		(mid 392.444732 -290.661729)
		(end 392.256264 -290.611052)
		(width 0.09525)
		(layer "In6.Cu")
		(net "M_K_CPU0_SB_DQS_DP<3>")
	)
	(arc
		(start 393.282424 -290.672774)
		(mid 393.240587 -290.63985)
		(end 393.19581 -290.611052)
		(width 0.09525)
		(layer "In6.Cu")
		(net "M_K_CPU0_SB_DQS_DP<3>")
	)
	(arc
		(start 393.310618 -290.698936)
		(mid 393.296748 -290.685611)
		(end 393.282424 -290.672774)
		(width 0.09525)
		(layer "In6.Cu")
		(net "M_K_CPU0_SB_DQS_DP<3>")
	)
	(arc
		(start 391.31621 -290.611052)
		(mid 391.082415 -290.537185)
		(end 390.839452 -290.570158)
		(width 0.09525)
		(layer "In6.Cu")
		(net "M_K_CPU0_SB_DQS_DP<3>")
	)
	(segment
		(start 390.098026 -285.160212)
		(end 390.564878 -285.42615)
		(width 0.12954)
		(layer "F.Cu")
		(net "M_K_CPU0_SB_DQS_DP<2>")
	)
	(segment
		(start 414.843976 -303.199546)
		(end 415.232596 -303.199546)
		(width 0.16002)
		(layer "In6.Cu")
		(net "M_K_CPU0_SB_DQS_DP<2>")
	)
	(segment
		(start 430.320704 -303.199546)
		(end 430.660302 -302.859948)
		(width 0.16002)
		(layer "In6.Cu")
		(net "M_K_CPU0_SB_DQS_DP<2>")
	)
	(segment
		(start 437.864758 -303.199546)
		(end 438.204356 -302.859948)
		(width 0.16002)
		(layer "In6.Cu")
		(net "M_K_CPU0_SB_DQS_DP<2>")
	)
	(segment
		(start 432.623468 -302.859948)
		(end 433.473352 -303.709832)
		(width 0.16002)
		(layer "In6.Cu")
		(net "M_K_CPU0_SB_DQS_DP<2>")
	)
	(segment
		(start 436.625238 -304.050446)
		(end 437.476138 -303.199546)
		(width 0.16002)
		(layer "In6.Cu")
		(net "M_K_CPU0_SB_DQS_DP<2>")
	)
	(segment
		(start 446.370456 -303.85893)
		(end 446.644268 -303.585118)
		(width 0.16002)
		(layer "In6.Cu")
		(net "M_K_CPU0_SB_DQS_DP<2>")
	)
	(segment
		(start 415.572194 -302.859948)
		(end 417.53536 -302.859948)
		(width 0.16002)
		(layer "In6.Cu")
		(net "M_K_CPU0_SB_DQS_DP<2>")
	)
	(segment
		(start 395.859254 -286.61741)
		(end 396.21079 -286.61741)
		(width 0.16002)
		(layer "In6.Cu")
		(net "M_K_CPU0_SB_DQS_DP<2>")
	)
	(segment
		(start 420.795196 -303.709832)
		(end 421.13581 -304.050446)
		(width 0.16002)
		(layer "In6.Cu")
		(net "M_K_CPU0_SB_DQS_DP<2>")
	)
	(segment
		(start 406.14092 -298.61256)
		(end 411.578806 -304.050446)
		(width 0.16002)
		(layer "In6.Cu")
		(net "M_K_CPU0_SB_DQS_DP<2>")
	)
	(segment
		(start 429.932084 -303.199546)
		(end 430.320704 -303.199546)
		(width 0.16002)
		(layer "In6.Cu")
		(net "M_K_CPU0_SB_DQS_DP<2>")
	)
	(segment
		(start 422.38803 -303.199546)
		(end 422.77665 -303.199546)
		(width 0.16002)
		(layer "In6.Cu")
		(net "M_K_CPU0_SB_DQS_DP<2>")
	)
	(segment
		(start 391.31621 -285.75127)
		(end 391.324592 -285.756096)
		(width 0.09525)
		(layer "In6.Cu")
		(net "M_K_CPU0_SB_DQS_DP<2>")
	)
	(segment
		(start 402.60905 -293.01567)
		(end 402.60905 -296.22115)
		(width 0.16002)
		(layer "In6.Cu")
		(net "M_K_CPU0_SB_DQS_DP<2>")
	)
	(segment
		(start 413.993076 -304.050446)
		(end 414.843976 -303.199546)
		(width 0.16002)
		(layer "In6.Cu")
		(net "M_K_CPU0_SB_DQS_DP<2>")
	)
	(segment
		(start 440.93638 -303.433988)
		(end 443.147196 -303.433988)
		(width 0.16002)
		(layer "In6.Cu")
		(net "M_K_CPU0_SB_DQS_DP<2>")
	)
	(segment
		(start 395.835632 -286.61741)
		(end 395.859254 -286.61741)
		(width 0.09525)
		(layer "In6.Cu")
		(net "M_K_CPU0_SB_DQS_DP<2>")
	)
	(segment
		(start 405.00046 -298.61256)
		(end 406.14092 -298.61256)
		(width 0.16002)
		(layer "In6.Cu")
		(net "M_K_CPU0_SB_DQS_DP<2>")
	)
	(segment
		(start 393.850368 -285.802832)
		(end 394.572998 -286.525462)
		(width 0.09525)
		(layer "In6.Cu")
		(net "M_K_CPU0_SB_DQS_DP<2>")
	)
	(segment
		(start 444.15075 -304.058066)
		(end 444.349886 -303.85893)
		(width 0.16002)
		(layer "In6.Cu")
		(net "M_K_CPU0_SB_DQS_DP<2>")
	)
	(segment
		(start 421.13581 -304.050446)
		(end 421.53713 -304.050446)
		(width 0.16002)
		(layer "In6.Cu")
		(net "M_K_CPU0_SB_DQS_DP<2>")
	)
	(segment
		(start 425.929298 -303.709832)
		(end 428.33925 -303.709832)
		(width 0.16002)
		(layer "In6.Cu")
		(net "M_K_CPU0_SB_DQS_DP<2>")
	)
	(segment
		(start 429.081184 -304.050446)
		(end 429.932084 -303.199546)
		(width 0.16002)
		(layer "In6.Cu")
		(net "M_K_CPU0_SB_DQS_DP<2>")
	)
	(segment
		(start 443.771274 -304.058066)
		(end 444.15075 -304.058066)
		(width 0.16002)
		(layer "In6.Cu")
		(net "M_K_CPU0_SB_DQS_DP<2>")
	)
	(segment
		(start 437.476138 -303.199546)
		(end 437.864758 -303.199546)
		(width 0.16002)
		(layer "In6.Cu")
		(net "M_K_CPU0_SB_DQS_DP<2>")
	)
	(segment
		(start 435.883304 -303.709832)
		(end 436.223918 -304.050446)
		(width 0.16002)
		(layer "In6.Cu")
		(net "M_K_CPU0_SB_DQS_DP<2>")
	)
	(segment
		(start 390.564878 -285.42615)
		(end 390.718802 -285.69158)
		(width 0.09525)
		(layer "In6.Cu")
		(net "M_K_CPU0_SB_DQS_DP<2>")
	)
	(segment
		(start 436.223918 -304.050446)
		(end 436.625238 -304.050446)
		(width 0.16002)
		(layer "In6.Cu")
		(net "M_K_CPU0_SB_DQS_DP<2>")
	)
	(segment
		(start 395.77645 -286.676592)
		(end 395.835632 -286.61741)
		(width 0.09525)
		(layer "In6.Cu")
		(net "M_K_CPU0_SB_DQS_DP<2>")
	)
	(segment
		(start 433.473352 -303.709832)
		(end 435.883304 -303.709832)
		(width 0.16002)
		(layer "In6.Cu")
		(net "M_K_CPU0_SB_DQS_DP<2>")
	)
	(segment
		(start 393.384786 -285.802832)
		(end 393.850368 -285.802832)
		(width 0.09525)
		(layer "In6.Cu")
		(net "M_K_CPU0_SB_DQS_DP<2>")
	)
	(segment
		(start 438.204356 -302.859948)
		(end 440.36234 -302.859948)
		(width 0.16002)
		(layer "In6.Cu")
		(net "M_K_CPU0_SB_DQS_DP<2>")
	)
	(segment
		(start 430.660302 -302.859948)
		(end 432.623468 -302.859948)
		(width 0.16002)
		(layer "In6.Cu")
		(net "M_K_CPU0_SB_DQS_DP<2>")
	)
	(segment
		(start 421.53713 -304.050446)
		(end 422.38803 -303.199546)
		(width 0.16002)
		(layer "In6.Cu")
		(net "M_K_CPU0_SB_DQS_DP<2>")
	)
	(segment
		(start 425.079414 -302.859948)
		(end 425.929298 -303.709832)
		(width 0.16002)
		(layer "In6.Cu")
		(net "M_K_CPU0_SB_DQS_DP<2>")
	)
	(segment
		(start 394.572998 -286.525462)
		(end 395.397228 -286.525462)
		(width 0.09525)
		(layer "In6.Cu")
		(net "M_K_CPU0_SB_DQS_DP<2>")
	)
	(segment
		(start 417.53536 -302.859948)
		(end 418.385244 -303.709832)
		(width 0.16002)
		(layer "In6.Cu")
		(net "M_K_CPU0_SB_DQS_DP<2>")
	)
	(segment
		(start 390.718802 -285.69158)
		(end 390.81964 -285.71825)
		(width 0.09525)
		(layer "In6.Cu")
		(net "M_K_CPU0_SB_DQS_DP<2>")
	)
	(segment
		(start 443.147196 -303.433988)
		(end 443.771274 -304.058066)
		(width 0.16002)
		(layer "In6.Cu")
		(net "M_K_CPU0_SB_DQS_DP<2>")
	)
	(segment
		(start 411.578806 -304.050446)
		(end 413.993076 -304.050446)
		(width 0.16002)
		(layer "In6.Cu")
		(net "M_K_CPU0_SB_DQS_DP<2>")
	)
	(segment
		(start 395.397228 -286.525462)
		(end 395.548358 -286.676592)
		(width 0.09525)
		(layer "In6.Cu")
		(net "M_K_CPU0_SB_DQS_DP<2>")
	)
	(segment
		(start 423.116248 -302.859948)
		(end 425.079414 -302.859948)
		(width 0.16002)
		(layer "In6.Cu")
		(net "M_K_CPU0_SB_DQS_DP<2>")
	)
	(segment
		(start 418.385244 -303.709832)
		(end 420.795196 -303.709832)
		(width 0.16002)
		(layer "In6.Cu")
		(net "M_K_CPU0_SB_DQS_DP<2>")
	)
	(segment
		(start 395.548358 -286.676592)
		(end 395.77645 -286.676592)
		(width 0.09525)
		(layer "In6.Cu")
		(net "M_K_CPU0_SB_DQS_DP<2>")
	)
	(segment
		(start 402.60905 -296.22115)
		(end 405.00046 -298.61256)
		(width 0.16002)
		(layer "In6.Cu")
		(net "M_K_CPU0_SB_DQS_DP<2>")
	)
	(segment
		(start 428.679864 -304.050446)
		(end 429.081184 -304.050446)
		(width 0.16002)
		(layer "In6.Cu")
		(net "M_K_CPU0_SB_DQS_DP<2>")
	)
	(segment
		(start 396.21079 -286.61741)
		(end 402.60905 -293.01567)
		(width 0.16002)
		(layer "In6.Cu")
		(net "M_K_CPU0_SB_DQS_DP<2>")
	)
	(segment
		(start 440.36234 -302.859948)
		(end 440.93638 -303.433988)
		(width 0.16002)
		(layer "In6.Cu")
		(net "M_K_CPU0_SB_DQS_DP<2>")
	)
	(segment
		(start 422.77665 -303.199546)
		(end 423.116248 -302.859948)
		(width 0.16002)
		(layer "In6.Cu")
		(net "M_K_CPU0_SB_DQS_DP<2>")
	)
	(segment
		(start 444.349886 -303.85893)
		(end 446.370456 -303.85893)
		(width 0.16002)
		(layer "In6.Cu")
		(net "M_K_CPU0_SB_DQS_DP<2>")
	)
	(segment
		(start 392.6332 -285.75127)
		(end 392.647932 -285.742634)
		(width 0.09525)
		(layer "In6.Cu")
		(net "M_K_CPU0_SB_DQS_DP<2>")
	)
	(segment
		(start 415.232596 -303.199546)
		(end 415.572194 -302.859948)
		(width 0.16002)
		(layer "In6.Cu")
		(net "M_K_CPU0_SB_DQS_DP<2>")
	)
	(segment
		(start 428.33925 -303.709832)
		(end 428.679864 -304.050446)
		(width 0.16002)
		(layer "In6.Cu")
		(net "M_K_CPU0_SB_DQS_DP<2>")
	)
	(arc
		(start 391.6934 -285.75127)
		(mid 391.974832 -285.675515)
		(end 392.256264 -285.75127)
		(width 0.09525)
		(layer "In6.Cu")
		(net "M_K_CPU0_SB_DQS_DP<2>")
	)
	(arc
		(start 391.324592 -285.756096)
		(mid 391.509624 -285.80201)
		(end 391.6934 -285.75127)
		(width 0.09525)
		(layer "In6.Cu")
		(net "M_K_CPU0_SB_DQS_DP<2>")
	)
	(arc
		(start 392.256264 -285.75127)
		(mid 392.444732 -285.801947)
		(end 392.6332 -285.75127)
		(width 0.09525)
		(layer "In6.Cu")
		(net "M_K_CPU0_SB_DQS_DP<2>")
	)
	(arc
		(start 392.647932 -285.742634)
		(mid 392.923137 -285.67537)
		(end 393.196064 -285.75127)
		(width 0.09525)
		(layer "In6.Cu")
		(net "M_K_CPU0_SB_DQS_DP<2>")
	)
	(arc
		(start 393.196064 -285.75127)
		(mid 393.28701 -285.789571)
		(end 393.384786 -285.802832)
		(width 0.09525)
		(layer "In6.Cu")
		(net "M_K_CPU0_SB_DQS_DP<2>")
	)
	(arc
		(start 390.81964 -285.71825)
		(mid 391.071781 -285.67668)
		(end 391.31621 -285.75127)
		(width 0.09525)
		(layer "In6.Cu")
		(net "M_K_CPU0_SB_DQS_DP<2>")
	)
	(segment
		(start 390.098026 -280.300176)
		(end 390.564878 -280.566114)
		(width 0.12954)
		(layer "F.Cu")
		(net "M_K_CPU0_SB_DQS_DP<1>")
	)
	(segment
		(start 435.883304 -294.359838)
		(end 436.223918 -294.700452)
		(width 0.16002)
		(layer "In6.Cu")
		(net "M_K_CPU0_SB_DQS_DP<1>")
	)
	(segment
		(start 443.771274 -294.708072)
		(end 444.15075 -294.708072)
		(width 0.16002)
		(layer "In6.Cu")
		(net "M_K_CPU0_SB_DQS_DP<1>")
	)
	(segment
		(start 395.290294 -280.556716)
		(end 395.541754 -280.808176)
		(width 0.09525)
		(layer "In6.Cu")
		(net "M_K_CPU0_SB_DQS_DP<1>")
	)
	(segment
		(start 440.93638 -294.083994)
		(end 443.147196 -294.083994)
		(width 0.16002)
		(layer "In6.Cu")
		(net "M_K_CPU0_SB_DQS_DP<1>")
	)
	(segment
		(start 395.625828 -280.808176)
		(end 395.642592 -280.82494)
		(width 0.09525)
		(layer "In6.Cu")
		(net "M_K_CPU0_SB_DQS_DP<1>")
	)
	(segment
		(start 423.116248 -293.509954)
		(end 425.079414 -293.509954)
		(width 0.16002)
		(layer "In6.Cu")
		(net "M_K_CPU0_SB_DQS_DP<1>")
	)
	(segment
		(start 436.625238 -294.700452)
		(end 437.476138 -293.849552)
		(width 0.16002)
		(layer "In6.Cu")
		(net "M_K_CPU0_SB_DQS_DP<1>")
	)
	(segment
		(start 395.75867 -280.941272)
		(end 398.73174 -280.941272)
		(width 0.16002)
		(layer "In6.Cu")
		(net "M_K_CPU0_SB_DQS_DP<1>")
	)
	(segment
		(start 437.476138 -293.849552)
		(end 437.864758 -293.849552)
		(width 0.16002)
		(layer "In6.Cu")
		(net "M_K_CPU0_SB_DQS_DP<1>")
	)
	(segment
		(start 429.932084 -293.849552)
		(end 430.320704 -293.849552)
		(width 0.16002)
		(layer "In6.Cu")
		(net "M_K_CPU0_SB_DQS_DP<1>")
	)
	(segment
		(start 418.139118 -293.849552)
		(end 418.649404 -294.359838)
		(width 0.16002)
		(layer "In6.Cu")
		(net "M_K_CPU0_SB_DQS_DP<1>")
	)
	(segment
		(start 421.13581 -294.700452)
		(end 421.53713 -294.700452)
		(width 0.16002)
		(layer "In6.Cu")
		(net "M_K_CPU0_SB_DQS_DP<1>")
	)
	(segment
		(start 390.564878 -280.566114)
		(end 390.718802 -280.831544)
		(width 0.09525)
		(layer "In6.Cu")
		(net "M_K_CPU0_SB_DQS_DP<1>")
	)
	(segment
		(start 438.204356 -293.509954)
		(end 440.36234 -293.509954)
		(width 0.16002)
		(layer "In6.Cu")
		(net "M_K_CPU0_SB_DQS_DP<1>")
	)
	(segment
		(start 440.36234 -293.509954)
		(end 440.93638 -294.083994)
		(width 0.16002)
		(layer "In6.Cu")
		(net "M_K_CPU0_SB_DQS_DP<1>")
	)
	(segment
		(start 393.964668 -280.556716)
		(end 395.290294 -280.556716)
		(width 0.09525)
		(layer "In6.Cu")
		(net "M_K_CPU0_SB_DQS_DP<1>")
	)
	(segment
		(start 430.320704 -293.849552)
		(end 430.660302 -293.509954)
		(width 0.16002)
		(layer "In6.Cu")
		(net "M_K_CPU0_SB_DQS_DP<1>")
	)
	(segment
		(start 444.15075 -294.708072)
		(end 444.349886 -294.508936)
		(width 0.16002)
		(layer "In6.Cu")
		(net "M_K_CPU0_SB_DQS_DP<1>")
	)
	(segment
		(start 428.33925 -294.359838)
		(end 428.679864 -294.700452)
		(width 0.16002)
		(layer "In6.Cu")
		(net "M_K_CPU0_SB_DQS_DP<1>")
	)
	(segment
		(start 412.49092 -294.700452)
		(end 413.993076 -294.700452)
		(width 0.16002)
		(layer "In6.Cu")
		(net "M_K_CPU0_SB_DQS_DP<1>")
	)
	(segment
		(start 428.679864 -294.700452)
		(end 429.081184 -294.700452)
		(width 0.16002)
		(layer "In6.Cu")
		(net "M_K_CPU0_SB_DQS_DP<1>")
	)
	(segment
		(start 391.31621 -280.891234)
		(end 391.324592 -280.89606)
		(width 0.09525)
		(layer "In6.Cu")
		(net "M_K_CPU0_SB_DQS_DP<1>")
	)
	(segment
		(start 418.649404 -294.359838)
		(end 420.795196 -294.359838)
		(width 0.16002)
		(layer "In6.Cu")
		(net "M_K_CPU0_SB_DQS_DP<1>")
	)
	(segment
		(start 446.370456 -294.508936)
		(end 446.644268 -294.235124)
		(width 0.16002)
		(layer "In6.Cu")
		(net "M_K_CPU0_SB_DQS_DP<1>")
	)
	(segment
		(start 429.081184 -294.700452)
		(end 429.932084 -293.849552)
		(width 0.16002)
		(layer "In6.Cu")
		(net "M_K_CPU0_SB_DQS_DP<1>")
	)
	(segment
		(start 393.621514 -280.89987)
		(end 393.964668 -280.556716)
		(width 0.09525)
		(layer "In6.Cu")
		(net "M_K_CPU0_SB_DQS_DP<1>")
	)
	(segment
		(start 437.864758 -293.849552)
		(end 438.204356 -293.509954)
		(width 0.16002)
		(layer "In6.Cu")
		(net "M_K_CPU0_SB_DQS_DP<1>")
	)
	(segment
		(start 425.079414 -293.509954)
		(end 425.929298 -294.359838)
		(width 0.16002)
		(layer "In6.Cu")
		(net "M_K_CPU0_SB_DQS_DP<1>")
	)
	(segment
		(start 433.473352 -294.359838)
		(end 435.883304 -294.359838)
		(width 0.16002)
		(layer "In6.Cu")
		(net "M_K_CPU0_SB_DQS_DP<1>")
	)
	(segment
		(start 420.795196 -294.359838)
		(end 421.13581 -294.700452)
		(width 0.16002)
		(layer "In6.Cu")
		(net "M_K_CPU0_SB_DQS_DP<1>")
	)
	(segment
		(start 413.993076 -294.700452)
		(end 414.843976 -293.849552)
		(width 0.16002)
		(layer "In6.Cu")
		(net "M_K_CPU0_SB_DQS_DP<1>")
	)
	(segment
		(start 390.718802 -280.831544)
		(end 390.81964 -280.858214)
		(width 0.09525)
		(layer "In6.Cu")
		(net "M_K_CPU0_SB_DQS_DP<1>")
	)
	(segment
		(start 436.223918 -294.700452)
		(end 436.625238 -294.700452)
		(width 0.16002)
		(layer "In6.Cu")
		(net "M_K_CPU0_SB_DQS_DP<1>")
	)
	(segment
		(start 393.384786 -280.942796)
		(end 393.518136 -280.942796)
		(width 0.09525)
		(layer "In6.Cu")
		(net "M_K_CPU0_SB_DQS_DP<1>")
	)
	(segment
		(start 444.349886 -294.508936)
		(end 446.370456 -294.508936)
		(width 0.16002)
		(layer "In6.Cu")
		(net "M_K_CPU0_SB_DQS_DP<1>")
	)
	(segment
		(start 432.623468 -293.509954)
		(end 433.473352 -294.359838)
		(width 0.16002)
		(layer "In6.Cu")
		(net "M_K_CPU0_SB_DQS_DP<1>")
	)
	(segment
		(start 395.642592 -280.82494)
		(end 395.75867 -280.941272)
		(width 0.16002)
		(layer "In6.Cu")
		(net "M_K_CPU0_SB_DQS_DP<1>")
	)
	(segment
		(start 425.929298 -294.359838)
		(end 428.33925 -294.359838)
		(width 0.16002)
		(layer "In6.Cu")
		(net "M_K_CPU0_SB_DQS_DP<1>")
	)
	(segment
		(start 443.147196 -294.083994)
		(end 443.771274 -294.708072)
		(width 0.16002)
		(layer "In6.Cu")
		(net "M_K_CPU0_SB_DQS_DP<1>")
	)
	(segment
		(start 393.518136 -280.942796)
		(end 393.621514 -280.89987)
		(width 0.09525)
		(layer "In6.Cu")
		(net "M_K_CPU0_SB_DQS_DP<1>")
	)
	(segment
		(start 422.77665 -293.849552)
		(end 423.116248 -293.509954)
		(width 0.16002)
		(layer "In6.Cu")
		(net "M_K_CPU0_SB_DQS_DP<1>")
	)
	(segment
		(start 414.843976 -293.849552)
		(end 418.139118 -293.849552)
		(width 0.16002)
		(layer "In6.Cu")
		(net "M_K_CPU0_SB_DQS_DP<1>")
	)
	(segment
		(start 392.6332 -280.891234)
		(end 392.647932 -280.882598)
		(width 0.09525)
		(layer "In6.Cu")
		(net "M_K_CPU0_SB_DQS_DP<1>")
	)
	(segment
		(start 395.541754 -280.808176)
		(end 395.625828 -280.808176)
		(width 0.09525)
		(layer "In6.Cu")
		(net "M_K_CPU0_SB_DQS_DP<1>")
	)
	(segment
		(start 398.73174 -280.941272)
		(end 412.49092 -294.700452)
		(width 0.16002)
		(layer "In6.Cu")
		(net "M_K_CPU0_SB_DQS_DP<1>")
	)
	(segment
		(start 422.38803 -293.849552)
		(end 422.77665 -293.849552)
		(width 0.16002)
		(layer "In6.Cu")
		(net "M_K_CPU0_SB_DQS_DP<1>")
	)
	(segment
		(start 421.53713 -294.700452)
		(end 422.38803 -293.849552)
		(width 0.16002)
		(layer "In6.Cu")
		(net "M_K_CPU0_SB_DQS_DP<1>")
	)
	(segment
		(start 430.660302 -293.509954)
		(end 432.623468 -293.509954)
		(width 0.16002)
		(layer "In6.Cu")
		(net "M_K_CPU0_SB_DQS_DP<1>")
	)
	(arc
		(start 391.324592 -280.89606)
		(mid 391.509624 -280.941974)
		(end 391.6934 -280.891234)
		(width 0.09525)
		(layer "In6.Cu")
		(net "M_K_CPU0_SB_DQS_DP<1>")
	)
	(arc
		(start 392.256264 -280.891234)
		(mid 392.444732 -280.941911)
		(end 392.6332 -280.891234)
		(width 0.09525)
		(layer "In6.Cu")
		(net "M_K_CPU0_SB_DQS_DP<1>")
	)
	(arc
		(start 393.196064 -280.891234)
		(mid 393.28701 -280.929535)
		(end 393.384786 -280.942796)
		(width 0.09525)
		(layer "In6.Cu")
		(net "M_K_CPU0_SB_DQS_DP<1>")
	)
	(arc
		(start 391.6934 -280.891234)
		(mid 391.974832 -280.815479)
		(end 392.256264 -280.891234)
		(width 0.09525)
		(layer "In6.Cu")
		(net "M_K_CPU0_SB_DQS_DP<1>")
	)
	(arc
		(start 392.647932 -280.882598)
		(mid 392.923137 -280.815334)
		(end 393.196064 -280.891234)
		(width 0.09525)
		(layer "In6.Cu")
		(net "M_K_CPU0_SB_DQS_DP<1>")
	)
	(arc
		(start 390.81964 -280.858214)
		(mid 391.071781 -280.816644)
		(end 391.31621 -280.891234)
		(width 0.09525)
		(layer "In6.Cu")
		(net "M_K_CPU0_SB_DQS_DP<1>")
	)
	(segment
		(start 390.098026 -275.44014)
		(end 390.564878 -275.706078)
		(width 0.12954)
		(layer "F.Cu")
		(net "M_K_CPU0_SB_DQS_DP<0>")
	)
	(segment
		(start 435.883304 -285.009844)
		(end 436.223918 -285.350458)
		(width 0.16002)
		(layer "In6.Cu")
		(net "M_K_CPU0_SB_DQS_DP<0>")
	)
	(segment
		(start 391.31621 -276.031198)
		(end 391.324592 -276.036024)
		(width 0.09525)
		(layer "In6.Cu")
		(net "M_K_CPU0_SB_DQS_DP<0>")
	)
	(segment
		(start 394.585444 -275.037804)
		(end 395.125956 -275.037804)
		(width 0.09525)
		(layer "In6.Cu")
		(net "M_K_CPU0_SB_DQS_DP<0>")
	)
	(segment
		(start 429.081184 -285.350458)
		(end 429.932084 -284.499558)
		(width 0.16002)
		(layer "In6.Cu")
		(net "M_K_CPU0_SB_DQS_DP<0>")
	)
	(segment
		(start 421.53713 -285.350458)
		(end 421.986202 -284.901386)
		(width 0.16002)
		(layer "In6.Cu")
		(net "M_K_CPU0_SB_DQS_DP<0>")
	)
	(segment
		(start 428.33925 -285.009844)
		(end 428.679864 -285.350458)
		(width 0.16002)
		(layer "In6.Cu")
		(net "M_K_CPU0_SB_DQS_DP<0>")
	)
	(segment
		(start 420.795196 -285.009844)
		(end 421.13581 -285.350458)
		(width 0.16002)
		(layer "In6.Cu")
		(net "M_K_CPU0_SB_DQS_DP<0>")
	)
	(segment
		(start 395.859254 -274.897596)
		(end 401.396962 -274.897596)
		(width 0.16002)
		(layer "In6.Cu")
		(net "M_K_CPU0_SB_DQS_DP<0>")
	)
	(segment
		(start 415.31159 -284.499558)
		(end 415.527236 -284.283912)
		(width 0.16002)
		(layer "In6.Cu")
		(net "M_K_CPU0_SB_DQS_DP<0>")
	)
	(segment
		(start 401.396962 -274.897596)
		(end 411.849824 -285.350458)
		(width 0.16002)
		(layer "In6.Cu")
		(net "M_K_CPU0_SB_DQS_DP<0>")
	)
	(segment
		(start 440.93638 -284.734)
		(end 443.147196 -284.734)
		(width 0.16002)
		(layer "In6.Cu")
		(net "M_K_CPU0_SB_DQS_DP<0>")
	)
	(segment
		(start 392.6332 -276.031198)
		(end 392.647932 -276.022562)
		(width 0.09525)
		(layer "In6.Cu")
		(net "M_K_CPU0_SB_DQS_DP<0>")
	)
	(segment
		(start 433.473352 -285.009844)
		(end 435.883304 -285.009844)
		(width 0.16002)
		(layer "In6.Cu")
		(net "M_K_CPU0_SB_DQS_DP<0>")
	)
	(segment
		(start 423.77614 -284.15996)
		(end 425.079414 -284.15996)
		(width 0.16002)
		(layer "In6.Cu")
		(net "M_K_CPU0_SB_DQS_DP<0>")
	)
	(segment
		(start 438.204356 -284.15996)
		(end 440.36234 -284.15996)
		(width 0.16002)
		(layer "In6.Cu")
		(net "M_K_CPU0_SB_DQS_DP<0>")
	)
	(segment
		(start 446.370456 -285.158942)
		(end 446.644268 -284.88513)
		(width 0.16002)
		(layer "In6.Cu")
		(net "M_K_CPU0_SB_DQS_DP<0>")
	)
	(segment
		(start 395.125956 -275.037804)
		(end 395.206982 -274.956778)
		(width 0.09525)
		(layer "In6.Cu")
		(net "M_K_CPU0_SB_DQS_DP<0>")
	)
	(segment
		(start 436.223918 -285.350458)
		(end 436.625238 -285.350458)
		(width 0.16002)
		(layer "In6.Cu")
		(net "M_K_CPU0_SB_DQS_DP<0>")
	)
	(segment
		(start 390.718802 -275.971508)
		(end 390.81964 -275.998178)
		(width 0.09525)
		(layer "In6.Cu")
		(net "M_K_CPU0_SB_DQS_DP<0>")
	)
	(segment
		(start 429.932084 -284.499558)
		(end 430.320704 -284.499558)
		(width 0.16002)
		(layer "In6.Cu")
		(net "M_K_CPU0_SB_DQS_DP<0>")
	)
	(segment
		(start 428.679864 -285.350458)
		(end 429.081184 -285.350458)
		(width 0.16002)
		(layer "In6.Cu")
		(net "M_K_CPU0_SB_DQS_DP<0>")
	)
	(segment
		(start 417.654486 -284.283912)
		(end 419.40734 -285.009844)
		(width 0.16002)
		(layer "In6.Cu")
		(net "M_K_CPU0_SB_DQS_DP<0>")
	)
	(segment
		(start 444.349886 -285.158942)
		(end 446.370456 -285.158942)
		(width 0.16002)
		(layer "In6.Cu")
		(net "M_K_CPU0_SB_DQS_DP<0>")
	)
	(segment
		(start 421.986202 -284.901386)
		(end 423.77614 -284.15996)
		(width 0.16002)
		(layer "In6.Cu")
		(net "M_K_CPU0_SB_DQS_DP<0>")
	)
	(segment
		(start 419.40734 -285.009844)
		(end 420.795196 -285.009844)
		(width 0.16002)
		(layer "In6.Cu")
		(net "M_K_CPU0_SB_DQS_DP<0>")
	)
	(segment
		(start 437.476138 -284.499558)
		(end 437.864758 -284.499558)
		(width 0.16002)
		(layer "In6.Cu")
		(net "M_K_CPU0_SB_DQS_DP<0>")
	)
	(segment
		(start 436.625238 -285.350458)
		(end 437.476138 -284.499558)
		(width 0.16002)
		(layer "In6.Cu")
		(net "M_K_CPU0_SB_DQS_DP<0>")
	)
	(segment
		(start 415.527236 -284.283912)
		(end 417.654486 -284.283912)
		(width 0.16002)
		(layer "In6.Cu")
		(net "M_K_CPU0_SB_DQS_DP<0>")
	)
	(segment
		(start 395.77645 -274.956778)
		(end 395.835632 -274.897596)
		(width 0.09525)
		(layer "In6.Cu")
		(net "M_K_CPU0_SB_DQS_DP<0>")
	)
	(segment
		(start 425.079414 -284.15996)
		(end 425.929298 -285.009844)
		(width 0.16002)
		(layer "In6.Cu")
		(net "M_K_CPU0_SB_DQS_DP<0>")
	)
	(segment
		(start 390.564878 -275.706078)
		(end 390.718802 -275.971508)
		(width 0.09525)
		(layer "In6.Cu")
		(net "M_K_CPU0_SB_DQS_DP<0>")
	)
	(segment
		(start 413.993076 -285.350458)
		(end 414.843976 -284.499558)
		(width 0.16002)
		(layer "In6.Cu")
		(net "M_K_CPU0_SB_DQS_DP<0>")
	)
	(segment
		(start 443.771274 -285.358078)
		(end 444.15075 -285.358078)
		(width 0.16002)
		(layer "In6.Cu")
		(net "M_K_CPU0_SB_DQS_DP<0>")
	)
	(segment
		(start 393.650978 -275.97227)
		(end 394.585444 -275.037804)
		(width 0.09525)
		(layer "In6.Cu")
		(net "M_K_CPU0_SB_DQS_DP<0>")
	)
	(segment
		(start 421.13581 -285.350458)
		(end 421.53713 -285.350458)
		(width 0.16002)
		(layer "In6.Cu")
		(net "M_K_CPU0_SB_DQS_DP<0>")
	)
	(segment
		(start 411.849824 -285.350458)
		(end 413.993076 -285.350458)
		(width 0.16002)
		(layer "In6.Cu")
		(net "M_K_CPU0_SB_DQS_DP<0>")
	)
	(segment
		(start 395.835632 -274.897596)
		(end 395.859254 -274.897596)
		(width 0.09525)
		(layer "In6.Cu")
		(net "M_K_CPU0_SB_DQS_DP<0>")
	)
	(segment
		(start 430.660302 -284.15996)
		(end 432.623468 -284.15996)
		(width 0.16002)
		(layer "In6.Cu")
		(net "M_K_CPU0_SB_DQS_DP<0>")
	)
	(segment
		(start 425.929298 -285.009844)
		(end 428.33925 -285.009844)
		(width 0.16002)
		(layer "In6.Cu")
		(net "M_K_CPU0_SB_DQS_DP<0>")
	)
	(segment
		(start 443.147196 -284.734)
		(end 443.771274 -285.358078)
		(width 0.16002)
		(layer "In6.Cu")
		(net "M_K_CPU0_SB_DQS_DP<0>")
	)
	(segment
		(start 430.320704 -284.499558)
		(end 430.660302 -284.15996)
		(width 0.16002)
		(layer "In6.Cu")
		(net "M_K_CPU0_SB_DQS_DP<0>")
	)
	(segment
		(start 444.15075 -285.358078)
		(end 444.349886 -285.158942)
		(width 0.16002)
		(layer "In6.Cu")
		(net "M_K_CPU0_SB_DQS_DP<0>")
	)
	(segment
		(start 437.864758 -284.499558)
		(end 438.204356 -284.15996)
		(width 0.16002)
		(layer "In6.Cu")
		(net "M_K_CPU0_SB_DQS_DP<0>")
	)
	(segment
		(start 432.623468 -284.15996)
		(end 433.473352 -285.009844)
		(width 0.16002)
		(layer "In6.Cu")
		(net "M_K_CPU0_SB_DQS_DP<0>")
	)
	(segment
		(start 395.206982 -274.956778)
		(end 395.77645 -274.956778)
		(width 0.09525)
		(layer "In6.Cu")
		(net "M_K_CPU0_SB_DQS_DP<0>")
	)
	(segment
		(start 440.36234 -284.15996)
		(end 440.93638 -284.734)
		(width 0.16002)
		(layer "In6.Cu")
		(net "M_K_CPU0_SB_DQS_DP<0>")
	)
	(segment
		(start 414.843976 -284.499558)
		(end 415.31159 -284.499558)
		(width 0.16002)
		(layer "In6.Cu")
		(net "M_K_CPU0_SB_DQS_DP<0>")
	)
	(arc
		(start 392.256264 -276.031198)
		(mid 392.444732 -276.081875)
		(end 392.6332 -276.031198)
		(width 0.09525)
		(layer "In6.Cu")
		(net "M_K_CPU0_SB_DQS_DP<0>")
	)
	(arc
		(start 393.196064 -276.031198)
		(mid 393.37768 -276.081935)
		(end 393.561062 -276.038056)
		(width 0.09525)
		(layer "In6.Cu")
		(net "M_K_CPU0_SB_DQS_DP<0>")
	)
	(arc
		(start 391.324592 -276.036024)
		(mid 391.509624 -276.081938)
		(end 391.6934 -276.031198)
		(width 0.09525)
		(layer "In6.Cu")
		(net "M_K_CPU0_SB_DQS_DP<0>")
	)
	(arc
		(start 393.561062 -276.038056)
		(mid 393.608471 -276.008513)
		(end 393.650978 -275.97227)
		(width 0.09525)
		(layer "In6.Cu")
		(net "M_K_CPU0_SB_DQS_DP<0>")
	)
	(arc
		(start 391.6934 -276.031198)
		(mid 391.974832 -275.955443)
		(end 392.256264 -276.031198)
		(width 0.09525)
		(layer "In6.Cu")
		(net "M_K_CPU0_SB_DQS_DP<0>")
	)
	(arc
		(start 390.81964 -275.998178)
		(mid 390.829508 -275.994147)
		(end 390.839452 -275.990304)
		(width 0.09525)
		(layer "In6.Cu")
		(net "M_K_CPU0_SB_DQS_DP<0>")
	)
	(arc
		(start 390.839452 -275.990304)
		(mid 391.082416 -275.957317)
		(end 391.31621 -276.031198)
		(width 0.09525)
		(layer "In6.Cu")
		(net "M_K_CPU0_SB_DQS_DP<0>")
	)
	(arc
		(start 392.647932 -276.022562)
		(mid 392.923137 -275.955298)
		(end 393.196064 -276.031198)
		(width 0.09525)
		(layer "In6.Cu")
		(net "M_K_CPU0_SB_DQS_DP<0>")
	)
	(segment
		(start 390.567926 -271.39011)
		(end 391.034778 -271.656048)
		(width 0.12954)
		(layer "F.Cu")
		(net "M_K_CPU0_SB_DQS_DN<9>")
	)
	(segment
		(start 433.34813 -275.96211)
		(end 435.758082 -275.96211)
		(width 0.16002)
		(layer "In6.Cu")
		(net "M_K_CPU0_SB_DQS_DN<9>")
	)
	(segment
		(start 438.329578 -275.112226)
		(end 440.237118 -275.112226)
		(width 0.16002)
		(layer "In6.Cu")
		(net "M_K_CPU0_SB_DQS_DN<9>")
	)
	(segment
		(start 414.118298 -276.302724)
		(end 414.969198 -275.451824)
		(width 0.16002)
		(layer "In6.Cu")
		(net "M_K_CPU0_SB_DQS_DN<9>")
	)
	(segment
		(start 392.72591 -271.33042)
		(end 392.769852 -271.304766)
		(width 0.09525)
		(layer "In6.Cu")
		(net "M_K_CPU0_SB_DQS_DN<9>")
	)
	(segment
		(start 395.292834 -269.496032)
		(end 395.776704 -269.496032)
		(width 0.09525)
		(layer "In6.Cu")
		(net "M_K_CPU0_SB_DQS_DN<9>")
	)
	(segment
		(start 435.758082 -275.96211)
		(end 436.098696 -276.302724)
		(width 0.16002)
		(layer "In6.Cu")
		(net "M_K_CPU0_SB_DQS_DN<9>")
	)
	(segment
		(start 430.445926 -275.451824)
		(end 430.785524 -275.112226)
		(width 0.16002)
		(layer "In6.Cu")
		(net "M_K_CPU0_SB_DQS_DN<9>")
	)
	(segment
		(start 445.082168 -276.238208)
		(end 445.562228 -276.238208)
		(width 0.16002)
		(layer "In6.Cu")
		(net "M_K_CPU0_SB_DQS_DN<9>")
	)
	(segment
		(start 444.275972 -276.310344)
		(end 444.475108 -276.111208)
		(width 0.16002)
		(layer "In6.Cu")
		(net "M_K_CPU0_SB_DQS_DN<9>")
	)
	(segment
		(start 444.475108 -276.111208)
		(end 444.955168 -276.111208)
		(width 0.16002)
		(layer "In6.Cu")
		(net "M_K_CPU0_SB_DQS_DN<9>")
	)
	(segment
		(start 440.237118 -275.112226)
		(end 440.811158 -275.686266)
		(width 0.16002)
		(layer "In6.Cu")
		(net "M_K_CPU0_SB_DQS_DN<9>")
	)
	(segment
		(start 415.697416 -275.112226)
		(end 417.410138 -275.112226)
		(width 0.16002)
		(layer "In6.Cu")
		(net "M_K_CPU0_SB_DQS_DN<9>")
	)
	(segment
		(start 446.370456 -276.111208)
		(end 446.644268 -276.38502)
		(width 0.16002)
		(layer "In6.Cu")
		(net "M_K_CPU0_SB_DQS_DN<9>")
	)
	(segment
		(start 417.410138 -275.112226)
		(end 418.260022 -275.96211)
		(width 0.16002)
		(layer "In6.Cu")
		(net "M_K_CPU0_SB_DQS_DN<9>")
	)
	(segment
		(start 391.034778 -271.656048)
		(end 390.880854 -271.390618)
		(width 0.09525)
		(layer "In6.Cu")
		(net "M_K_CPU0_SB_DQS_DN<9>")
	)
	(segment
		(start 394.639292 -269.362682)
		(end 395.159484 -269.362682)
		(width 0.09525)
		(layer "In6.Cu")
		(net "M_K_CPU0_SB_DQS_DN<9>")
	)
	(segment
		(start 422.513252 -275.451824)
		(end 422.901872 -275.451824)
		(width 0.16002)
		(layer "In6.Cu")
		(net "M_K_CPU0_SB_DQS_DN<9>")
	)
	(segment
		(start 444.955168 -276.111208)
		(end 445.082168 -276.238208)
		(width 0.16002)
		(layer "In6.Cu")
		(net "M_K_CPU0_SB_DQS_DN<9>")
	)
	(segment
		(start 437.98998 -275.451824)
		(end 438.329578 -275.112226)
		(width 0.16002)
		(layer "In6.Cu")
		(net "M_K_CPU0_SB_DQS_DN<9>")
	)
	(segment
		(start 422.901872 -275.451824)
		(end 423.24147 -275.112226)
		(width 0.16002)
		(layer "In6.Cu")
		(net "M_K_CPU0_SB_DQS_DN<9>")
	)
	(segment
		(start 428.554642 -276.302724)
		(end 429.206406 -276.302724)
		(width 0.16002)
		(layer "In6.Cu")
		(net "M_K_CPU0_SB_DQS_DN<9>")
	)
	(segment
		(start 440.811158 -275.686266)
		(end 443.021974 -275.686266)
		(width 0.16002)
		(layer "In6.Cu")
		(net "M_K_CPU0_SB_DQS_DN<9>")
	)
	(segment
		(start 393.343892 -270.437864)
		(end 393.735052 -270.267176)
		(width 0.09525)
		(layer "In6.Cu")
		(net "M_K_CPU0_SB_DQS_DN<9>")
	)
	(segment
		(start 395.776704 -269.496032)
		(end 395.835632 -269.55496)
		(width 0.09525)
		(layer "In6.Cu")
		(net "M_K_CPU0_SB_DQS_DN<9>")
	)
	(segment
		(start 429.206406 -276.302724)
		(end 430.057306 -275.451824)
		(width 0.16002)
		(layer "In6.Cu")
		(net "M_K_CPU0_SB_DQS_DN<9>")
	)
	(segment
		(start 443.646052 -276.310344)
		(end 444.275972 -276.310344)
		(width 0.16002)
		(layer "In6.Cu")
		(net "M_K_CPU0_SB_DQS_DN<9>")
	)
	(segment
		(start 415.357818 -275.451824)
		(end 415.697416 -275.112226)
		(width 0.16002)
		(layer "In6.Cu")
		(net "M_K_CPU0_SB_DQS_DN<9>")
	)
	(segment
		(start 406.082246 -269.55496)
		(end 412.83001 -276.302724)
		(width 0.16002)
		(layer "In6.Cu")
		(net "M_K_CPU0_SB_DQS_DN<9>")
	)
	(segment
		(start 423.24147 -275.112226)
		(end 424.954192 -275.112226)
		(width 0.16002)
		(layer "In6.Cu")
		(net "M_K_CPU0_SB_DQS_DN<9>")
	)
	(segment
		(start 392.704066 -271.34312)
		(end 392.711686 -271.338802)
		(width 0.09525)
		(layer "In6.Cu")
		(net "M_K_CPU0_SB_DQS_DN<9>")
	)
	(segment
		(start 443.021974 -275.686266)
		(end 443.646052 -276.310344)
		(width 0.16002)
		(layer "In6.Cu")
		(net "M_K_CPU0_SB_DQS_DN<9>")
	)
	(segment
		(start 420.669974 -275.96211)
		(end 421.010588 -276.302724)
		(width 0.16002)
		(layer "In6.Cu")
		(net "M_K_CPU0_SB_DQS_DN<9>")
	)
	(segment
		(start 390.880854 -271.390618)
		(end 390.903968 -271.304004)
		(width 0.09525)
		(layer "In6.Cu")
		(net "M_K_CPU0_SB_DQS_DN<9>")
	)
	(segment
		(start 395.835632 -269.55496)
		(end 395.859254 -269.55496)
		(width 0.09525)
		(layer "In6.Cu")
		(net "M_K_CPU0_SB_DQS_DN<9>")
	)
	(segment
		(start 392.711686 -271.338802)
		(end 392.712448 -271.338294)
		(width 0.09525)
		(layer "In6.Cu")
		(net "M_K_CPU0_SB_DQS_DN<9>")
	)
	(segment
		(start 430.057306 -275.451824)
		(end 430.445926 -275.451824)
		(width 0.16002)
		(layer "In6.Cu")
		(net "M_K_CPU0_SB_DQS_DN<9>")
	)
	(segment
		(start 428.214028 -275.96211)
		(end 428.554642 -276.302724)
		(width 0.16002)
		(layer "In6.Cu")
		(net "M_K_CPU0_SB_DQS_DN<9>")
	)
	(segment
		(start 436.098696 -276.302724)
		(end 436.75046 -276.302724)
		(width 0.16002)
		(layer "In6.Cu")
		(net "M_K_CPU0_SB_DQS_DN<9>")
	)
	(segment
		(start 393.142216 -270.574262)
		(end 393.14247 -270.574008)
		(width 0.09525)
		(layer "In6.Cu")
		(net "M_K_CPU0_SB_DQS_DN<9>")
	)
	(segment
		(start 395.159484 -269.362682)
		(end 395.292834 -269.496032)
		(width 0.09525)
		(layer "In6.Cu")
		(net "M_K_CPU0_SB_DQS_DN<9>")
	)
	(segment
		(start 392.712448 -271.338294)
		(end 392.72591 -271.33042)
		(width 0.09525)
		(layer "In6.Cu")
		(net "M_K_CPU0_SB_DQS_DN<9>")
	)
	(segment
		(start 395.859254 -269.55496)
		(end 406.082246 -269.55496)
		(width 0.16002)
		(layer "In6.Cu")
		(net "M_K_CPU0_SB_DQS_DN<9>")
	)
	(segment
		(start 432.498246 -275.112226)
		(end 433.34813 -275.96211)
		(width 0.16002)
		(layer "In6.Cu")
		(net "M_K_CPU0_SB_DQS_DN<9>")
	)
	(segment
		(start 430.785524 -275.112226)
		(end 432.498246 -275.112226)
		(width 0.16002)
		(layer "In6.Cu")
		(net "M_K_CPU0_SB_DQS_DN<9>")
	)
	(segment
		(start 445.562228 -276.238208)
		(end 445.689228 -276.111208)
		(width 0.16002)
		(layer "In6.Cu")
		(net "M_K_CPU0_SB_DQS_DN<9>")
	)
	(segment
		(start 424.954192 -275.112226)
		(end 425.804076 -275.96211)
		(width 0.16002)
		(layer "In6.Cu")
		(net "M_K_CPU0_SB_DQS_DN<9>")
	)
	(segment
		(start 421.010588 -276.302724)
		(end 421.662352 -276.302724)
		(width 0.16002)
		(layer "In6.Cu")
		(net "M_K_CPU0_SB_DQS_DN<9>")
	)
	(segment
		(start 392.154918 -271.326102)
		(end 392.1633 -271.330928)
		(width 0.09525)
		(layer "In6.Cu")
		(net "M_K_CPU0_SB_DQS_DN<9>")
	)
	(segment
		(start 445.689228 -276.111208)
		(end 446.370456 -276.111208)
		(width 0.16002)
		(layer "In6.Cu")
		(net "M_K_CPU0_SB_DQS_DN<9>")
	)
	(segment
		(start 418.260022 -275.96211)
		(end 420.669974 -275.96211)
		(width 0.16002)
		(layer "In6.Cu")
		(net "M_K_CPU0_SB_DQS_DN<9>")
	)
	(segment
		(start 436.75046 -276.302724)
		(end 437.60136 -275.451824)
		(width 0.16002)
		(layer "In6.Cu")
		(net "M_K_CPU0_SB_DQS_DN<9>")
	)
	(segment
		(start 437.60136 -275.451824)
		(end 437.98998 -275.451824)
		(width 0.16002)
		(layer "In6.Cu")
		(net "M_K_CPU0_SB_DQS_DN<9>")
	)
	(segment
		(start 393.735052 -270.267176)
		(end 394.639292 -269.362682)
		(width 0.09525)
		(layer "In6.Cu")
		(net "M_K_CPU0_SB_DQS_DN<9>")
	)
	(segment
		(start 425.804076 -275.96211)
		(end 428.214028 -275.96211)
		(width 0.16002)
		(layer "In6.Cu")
		(net "M_K_CPU0_SB_DQS_DN<9>")
	)
	(segment
		(start 414.969198 -275.451824)
		(end 415.357818 -275.451824)
		(width 0.16002)
		(layer "In6.Cu")
		(net "M_K_CPU0_SB_DQS_DN<9>")
	)
	(segment
		(start 412.83001 -276.302724)
		(end 414.118298 -276.302724)
		(width 0.16002)
		(layer "In6.Cu")
		(net "M_K_CPU0_SB_DQS_DN<9>")
	)
	(segment
		(start 421.662352 -276.302724)
		(end 422.513252 -275.451824)
		(width 0.16002)
		(layer "In6.Cu")
		(net "M_K_CPU0_SB_DQS_DN<9>")
	)
	(segment
		(start 393.14247 -270.574008)
		(end 393.328144 -270.446754)
		(width 0.09525)
		(layer "In6.Cu")
		(net "M_K_CPU0_SB_DQS_DN<9>")
	)
	(arc
		(start 393.02309 -270.736314)
		(mid 393.068938 -270.645213)
		(end 393.142216 -270.574262)
		(width 0.09525)
		(layer "In6.Cu")
		(net "M_K_CPU0_SB_DQS_DN<9>")
	)
	(arc
		(start 391.78611 -271.330928)
		(mid 391.969885 -271.280156)
		(end 392.154918 -271.326102)
		(width 0.09525)
		(layer "In6.Cu")
		(net "M_K_CPU0_SB_DQS_DN<9>")
	)
	(arc
		(start 393.007088 -270.846042)
		(mid 393.011031 -270.790585)
		(end 393.02309 -270.736314)
		(width 0.09525)
		(layer "In6.Cu")
		(net "M_K_CPU0_SB_DQS_DN<9>")
	)
	(arc
		(start 392.769852 -271.304766)
		(mid 392.944273 -271.104263)
		(end 393.007088 -270.846042)
		(width 0.09525)
		(layer "In6.Cu")
		(net "M_K_CPU0_SB_DQS_DN<9>")
	)
	(arc
		(start 391.223246 -271.330928)
		(mid 391.504678 -271.406683)
		(end 391.78611 -271.330928)
		(width 0.09525)
		(layer "In6.Cu")
		(net "M_K_CPU0_SB_DQS_DN<9>")
	)
	(arc
		(start 393.328144 -270.446754)
		(mid 393.335805 -270.44193)
		(end 393.343892 -270.437864)
		(width 0.09525)
		(layer "In6.Cu")
		(net "M_K_CPU0_SB_DQS_DN<9>")
	)
	(arc
		(start 392.1633 -271.330928)
		(mid 392.432113 -271.406541)
		(end 392.704066 -271.34312)
		(width 0.09525)
		(layer "In6.Cu")
		(net "M_K_CPU0_SB_DQS_DN<9>")
	)
	(arc
		(start 390.903968 -271.304004)
		(mid 391.066619 -271.281744)
		(end 391.223246 -271.330928)
		(width 0.09525)
		(layer "In6.Cu")
		(net "M_K_CPU0_SB_DQS_DN<9>")
	)
	(segment
		(start 388.688072 -290.83)
		(end 389.154924 -291.095938)
		(width 0.12954)
		(layer "F.Cu")
		(net "M_K_CPU0_SB_DQS_DN<8>")
	)
	(segment
		(start 421.48887 -314.67806)
		(end 422.27627 -313.89066)
		(width 0.16002)
		(layer "In6.Cu")
		(net "M_K_CPU0_SB_DQS_DN<8>")
	)
	(segment
		(start 418.590476 -314.207906)
		(end 419.440614 -315.058044)
		(width 0.16002)
		(layer "In6.Cu")
		(net "M_K_CPU0_SB_DQS_DN<8>")
	)
	(segment
		(start 440.07151 -314.058808)
		(end 442.270388 -314.058808)
		(width 0.16002)
		(layer "In6.Cu")
		(net "M_K_CPU0_SB_DQS_DN<8>")
	)
	(segment
		(start 426.13453 -314.207906)
		(end 426.984668 -315.058044)
		(width 0.16002)
		(layer "In6.Cu")
		(net "M_K_CPU0_SB_DQS_DN<8>")
	)
	(segment
		(start 406.600406 -311.40273)
		(end 406.826466 -311.40273)
		(width 0.16002)
		(layer "In6.Cu")
		(net "M_K_CPU0_SB_DQS_DN<8>")
	)
	(segment
		(start 405.536908 -309.945024)
		(end 406.013412 -309.945024)
		(width 0.16002)
		(layer "In6.Cu")
		(net "M_K_CPU0_SB_DQS_DN<8>")
	)
	(segment
		(start 423.652696 -314.207906)
		(end 426.13453 -314.207906)
		(width 0.16002)
		(layer "In6.Cu")
		(net "M_K_CPU0_SB_DQS_DN<8>")
	)
	(segment
		(start 434.52923 -315.058552)
		(end 435.591966 -315.058552)
		(width 0.16002)
		(layer "In6.Cu")
		(net "M_K_CPU0_SB_DQS_DN<8>")
	)
	(segment
		(start 429.820324 -313.89066)
		(end 430.879504 -313.89066)
		(width 0.16002)
		(layer "In6.Cu")
		(net "M_K_CPU0_SB_DQS_DN<8>")
	)
	(segment
		(start 409.184348 -313.11596)
		(end 409.184348 -313.592464)
		(width 0.16002)
		(layer "In6.Cu")
		(net "M_K_CPU0_SB_DQS_DN<8>")
	)
	(segment
		(start 407.387044 -311.318656)
		(end 407.810716 -311.742328)
		(width 0.16002)
		(layer "In6.Cu")
		(net "M_K_CPU0_SB_DQS_DN<8>")
	)
	(segment
		(start 406.35301 -310.929274)
		(end 406.35301 -311.155334)
		(width 0.16002)
		(layer "In6.Cu")
		(net "M_K_CPU0_SB_DQS_DN<8>")
	)
	(segment
		(start 428.428404 -314.67806)
		(end 429.032924 -314.67806)
		(width 0.16002)
		(layer "In6.Cu")
		(net "M_K_CPU0_SB_DQS_DN<8>")
	)
	(segment
		(start 437.364378 -313.89066)
		(end 438.423558 -313.89066)
		(width 0.16002)
		(layer "In6.Cu")
		(net "M_K_CPU0_SB_DQS_DN<8>")
	)
	(segment
		(start 395.56436 -295.53916)
		(end 395.813788 -295.787318)
		(width 0.16002)
		(layer "In6.Cu")
		(net "M_K_CPU0_SB_DQS_DN<8>")
	)
	(segment
		(start 406.35301 -311.155334)
		(end 406.600406 -311.40273)
		(width 0.16002)
		(layer "In6.Cu")
		(net "M_K_CPU0_SB_DQS_DN<8>")
	)
	(segment
		(start 389.308848 -291.361368)
		(end 389.409686 -291.388038)
		(width 0.09525)
		(layer "In6.Cu")
		(net "M_K_CPU0_SB_DQS_DN<8>")
	)
	(segment
		(start 407.810716 -312.218832)
		(end 407.726642 -312.302906)
		(width 0.16002)
		(layer "In6.Cu")
		(net "M_K_CPU0_SB_DQS_DN<8>")
	)
	(segment
		(start 407.726642 -312.302906)
		(end 407.726642 -312.528966)
		(width 0.16002)
		(layer "In6.Cu")
		(net "M_K_CPU0_SB_DQS_DN<8>")
	)
	(segment
		(start 409.184348 -313.592464)
		(end 409.100274 -313.676538)
		(width 0.16002)
		(layer "In6.Cu")
		(net "M_K_CPU0_SB_DQS_DN<8>")
	)
	(segment
		(start 389.906256 -291.421058)
		(end 389.914638 -291.425884)
		(width 0.09525)
		(layer "In6.Cu")
		(net "M_K_CPU0_SB_DQS_DN<8>")
	)
	(segment
		(start 436.576978 -314.67806)
		(end 437.364378 -313.89066)
		(width 0.16002)
		(layer "In6.Cu")
		(net "M_K_CPU0_SB_DQS_DN<8>")
	)
	(segment
		(start 409.100274 -313.902598)
		(end 409.34767 -314.149994)
		(width 0.16002)
		(layer "In6.Cu")
		(net "M_K_CPU0_SB_DQS_DN<8>")
	)
	(segment
		(start 414.732216 -313.89066)
		(end 415.791396 -313.89066)
		(width 0.16002)
		(layer "In6.Cu")
		(net "M_K_CPU0_SB_DQS_DN<8>")
	)
	(segment
		(start 439.922412 -314.207906)
		(end 440.07151 -314.058808)
		(width 0.16002)
		(layer "In6.Cu")
		(net "M_K_CPU0_SB_DQS_DN<8>")
	)
	(segment
		(start 409.657804 -314.06592)
		(end 410.134308 -314.06592)
		(width 0.16002)
		(layer "In6.Cu")
		(net "M_K_CPU0_SB_DQS_DN<8>")
	)
	(segment
		(start 438.740804 -314.207906)
		(end 439.922412 -314.207906)
		(width 0.16002)
		(layer "In6.Cu")
		(net "M_K_CPU0_SB_DQS_DN<8>")
	)
	(segment
		(start 395.463776 -295.52265)
		(end 395.46403 -295.52265)
		(width 0.09525)
		(layer "In6.Cu")
		(net "M_K_CPU0_SB_DQS_DN<8>")
	)
	(segment
		(start 394.109194 -293.82466)
		(end 394.288772 -294.004238)
		(width 0.09525)
		(layer "In6.Cu")
		(net "M_K_CPU0_SB_DQS_DN<8>")
	)
	(segment
		(start 404.979378 -309.781702)
		(end 405.226774 -310.029098)
		(width 0.16002)
		(layer "In6.Cu")
		(net "M_K_CPU0_SB_DQS_DN<8>")
	)
	(segment
		(start 435.972458 -314.67806)
		(end 436.576978 -314.67806)
		(width 0.16002)
		(layer "In6.Cu")
		(net "M_K_CPU0_SB_DQS_DN<8>")
	)
	(segment
		(start 435.591966 -315.058552)
		(end 435.972458 -314.67806)
		(width 0.16002)
		(layer "In6.Cu")
		(net "M_K_CPU0_SB_DQS_DN<8>")
	)
	(segment
		(start 416.108642 -314.207906)
		(end 418.590476 -314.207906)
		(width 0.16002)
		(layer "In6.Cu")
		(net "M_K_CPU0_SB_DQS_DN<8>")
	)
	(segment
		(start 389.154924 -291.095938)
		(end 389.308848 -291.361368)
		(width 0.09525)
		(layer "In6.Cu")
		(net "M_K_CPU0_SB_DQS_DN<8>")
	)
	(segment
		(start 404.979378 -309.555642)
		(end 404.979378 -309.781702)
		(width 0.16002)
		(layer "In6.Cu")
		(net "M_K_CPU0_SB_DQS_DN<8>")
	)
	(segment
		(start 431.19675 -314.207906)
		(end 433.678584 -314.207906)
		(width 0.16002)
		(layer "In6.Cu")
		(net "M_K_CPU0_SB_DQS_DN<8>")
	)
	(segment
		(start 406.91054 -311.318656)
		(end 407.387044 -311.318656)
		(width 0.16002)
		(layer "In6.Cu")
		(net "M_K_CPU0_SB_DQS_DN<8>")
	)
	(segment
		(start 410.134308 -314.06592)
		(end 410.746448 -314.67806)
		(width 0.16002)
		(layer "In6.Cu")
		(net "M_K_CPU0_SB_DQS_DN<8>")
	)
	(segment
		(start 409.34767 -314.149994)
		(end 409.57373 -314.149994)
		(width 0.16002)
		(layer "In6.Cu")
		(net "M_K_CPU0_SB_DQS_DN<8>")
	)
	(segment
		(start 395.547596 -295.522396)
		(end 395.56436 -295.53916)
		(width 0.09525)
		(layer "In6.Cu")
		(net "M_K_CPU0_SB_DQS_DN<8>")
	)
	(segment
		(start 406.826466 -311.40273)
		(end 406.91054 -311.318656)
		(width 0.16002)
		(layer "In6.Cu")
		(net "M_K_CPU0_SB_DQS_DN<8>")
	)
	(segment
		(start 407.974038 -312.776362)
		(end 408.200098 -312.776362)
		(width 0.16002)
		(layer "In6.Cu")
		(net "M_K_CPU0_SB_DQS_DN<8>")
	)
	(segment
		(start 406.013412 -309.945024)
		(end 406.437084 -310.368696)
		(width 0.16002)
		(layer "In6.Cu")
		(net "M_K_CPU0_SB_DQS_DN<8>")
	)
	(segment
		(start 394.426186 -294.335962)
		(end 394.426186 -294.48506)
		(width 0.09525)
		(layer "In6.Cu")
		(net "M_K_CPU0_SB_DQS_DN<8>")
	)
	(segment
		(start 406.437084 -310.8452)
		(end 406.35301 -310.929274)
		(width 0.16002)
		(layer "In6.Cu")
		(net "M_K_CPU0_SB_DQS_DN<8>")
	)
	(segment
		(start 406.437084 -310.368696)
		(end 406.437084 -310.8452)
		(width 0.16002)
		(layer "In6.Cu")
		(net "M_K_CPU0_SB_DQS_DN<8>")
	)
	(segment
		(start 409.57373 -314.149994)
		(end 409.657804 -314.06592)
		(width 0.16002)
		(layer "In6.Cu")
		(net "M_K_CPU0_SB_DQS_DN<8>")
	)
	(segment
		(start 395.46403 -295.52265)
		(end 395.547596 -295.522396)
		(width 0.09525)
		(layer "In6.Cu")
		(net "M_K_CPU0_SB_DQS_DN<8>")
	)
	(segment
		(start 430.879504 -313.89066)
		(end 431.19675 -314.207906)
		(width 0.16002)
		(layer "In6.Cu")
		(net "M_K_CPU0_SB_DQS_DN<8>")
	)
	(segment
		(start 433.678584 -314.207906)
		(end 434.52923 -315.058552)
		(width 0.16002)
		(layer "In6.Cu")
		(net "M_K_CPU0_SB_DQS_DN<8>")
	)
	(segment
		(start 428.04842 -315.058044)
		(end 428.428404 -314.67806)
		(width 0.16002)
		(layer "In6.Cu")
		(net "M_K_CPU0_SB_DQS_DN<8>")
	)
	(segment
		(start 395.813788 -295.787318)
		(end 395.813788 -299.7454)
		(width 0.16002)
		(layer "In6.Cu")
		(net "M_K_CPU0_SB_DQS_DN<8>")
	)
	(segment
		(start 442.270388 -314.058808)
		(end 442.5442 -313.784996)
		(width 0.16002)
		(layer "In6.Cu")
		(net "M_K_CPU0_SB_DQS_DN<8>")
	)
	(segment
		(start 407.810716 -311.742328)
		(end 407.810716 -312.218832)
		(width 0.16002)
		(layer "In6.Cu")
		(net "M_K_CPU0_SB_DQS_DN<8>")
	)
	(segment
		(start 408.200098 -312.776362)
		(end 408.284172 -312.692288)
		(width 0.16002)
		(layer "In6.Cu")
		(net "M_K_CPU0_SB_DQS_DN<8>")
	)
	(segment
		(start 392.725656 -291.421058)
		(end 392.725402 -291.421566)
		(width 0.09525)
		(layer "In6.Cu")
		(net "M_K_CPU0_SB_DQS_DN<8>")
	)
	(segment
		(start 423.33545 -313.89066)
		(end 423.652696 -314.207906)
		(width 0.16002)
		(layer "In6.Cu")
		(net "M_K_CPU0_SB_DQS_DN<8>")
	)
	(segment
		(start 405.226774 -310.029098)
		(end 405.452834 -310.029098)
		(width 0.16002)
		(layer "In6.Cu")
		(net "M_K_CPU0_SB_DQS_DN<8>")
	)
	(segment
		(start 409.100274 -313.676538)
		(end 409.100274 -313.902598)
		(width 0.16002)
		(layer "In6.Cu")
		(net "M_K_CPU0_SB_DQS_DN<8>")
	)
	(segment
		(start 415.791396 -313.89066)
		(end 416.108642 -314.207906)
		(width 0.16002)
		(layer "In6.Cu")
		(net "M_K_CPU0_SB_DQS_DN<8>")
	)
	(segment
		(start 405.452834 -310.029098)
		(end 405.536908 -309.945024)
		(width 0.16002)
		(layer "In6.Cu")
		(net "M_K_CPU0_SB_DQS_DN<8>")
	)
	(segment
		(start 413.944816 -314.67806)
		(end 414.732216 -313.89066)
		(width 0.16002)
		(layer "In6.Cu")
		(net "M_K_CPU0_SB_DQS_DN<8>")
	)
	(segment
		(start 405.063452 -309.471568)
		(end 404.979378 -309.555642)
		(width 0.16002)
		(layer "In6.Cu")
		(net "M_K_CPU0_SB_DQS_DN<8>")
	)
	(segment
		(start 420.88435 -314.67806)
		(end 421.48887 -314.67806)
		(width 0.16002)
		(layer "In6.Cu")
		(net "M_K_CPU0_SB_DQS_DN<8>")
	)
	(segment
		(start 405.063452 -308.995064)
		(end 405.063452 -309.471568)
		(width 0.16002)
		(layer "In6.Cu")
		(net "M_K_CPU0_SB_DQS_DN<8>")
	)
	(segment
		(start 392.151108 -291.427916)
		(end 392.163046 -291.421058)
		(width 0.09525)
		(layer "In6.Cu")
		(net "M_K_CPU0_SB_DQS_DN<8>")
	)
	(segment
		(start 420.504366 -315.058044)
		(end 420.88435 -314.67806)
		(width 0.16002)
		(layer "In6.Cu")
		(net "M_K_CPU0_SB_DQS_DN<8>")
	)
	(segment
		(start 429.032924 -314.67806)
		(end 429.820324 -313.89066)
		(width 0.16002)
		(layer "In6.Cu")
		(net "M_K_CPU0_SB_DQS_DN<8>")
	)
	(segment
		(start 393.036044 -292.090094)
		(end 393.681458 -292.735508)
		(width 0.09525)
		(layer "In6.Cu")
		(net "M_K_CPU0_SB_DQS_DN<8>")
	)
	(segment
		(start 408.284172 -312.692288)
		(end 408.760676 -312.692288)
		(width 0.16002)
		(layer "In6.Cu")
		(net "M_K_CPU0_SB_DQS_DN<8>")
	)
	(segment
		(start 438.423558 -313.89066)
		(end 438.740804 -314.207906)
		(width 0.16002)
		(layer "In6.Cu")
		(net "M_K_CPU0_SB_DQS_DN<8>")
	)
	(segment
		(start 395.813788 -299.7454)
		(end 405.063452 -308.995064)
		(width 0.16002)
		(layer "In6.Cu")
		(net "M_K_CPU0_SB_DQS_DN<8>")
	)
	(segment
		(start 407.726642 -312.528966)
		(end 407.974038 -312.776362)
		(width 0.16002)
		(layer "In6.Cu")
		(net "M_K_CPU0_SB_DQS_DN<8>")
	)
	(segment
		(start 408.760676 -312.692288)
		(end 409.184348 -313.11596)
		(width 0.16002)
		(layer "In6.Cu")
		(net "M_K_CPU0_SB_DQS_DN<8>")
	)
	(segment
		(start 394.426186 -294.48506)
		(end 395.463776 -295.52265)
		(width 0.09525)
		(layer "In6.Cu")
		(net "M_K_CPU0_SB_DQS_DN<8>")
	)
	(segment
		(start 422.27627 -313.89066)
		(end 423.33545 -313.89066)
		(width 0.16002)
		(layer "In6.Cu")
		(net "M_K_CPU0_SB_DQS_DN<8>")
	)
	(segment
		(start 419.440614 -315.058044)
		(end 420.504366 -315.058044)
		(width 0.16002)
		(layer "In6.Cu")
		(net "M_K_CPU0_SB_DQS_DN<8>")
	)
	(segment
		(start 410.746448 -314.67806)
		(end 413.944816 -314.67806)
		(width 0.16002)
		(layer "In6.Cu")
		(net "M_K_CPU0_SB_DQS_DN<8>")
	)
	(segment
		(start 392.163046 -291.421058)
		(end 392.17346 -291.414962)
		(width 0.09525)
		(layer "In6.Cu")
		(net "M_K_CPU0_SB_DQS_DN<8>")
	)
	(segment
		(start 393.956286 -293.39921)
		(end 393.956286 -293.455598)
		(width 0.09525)
		(layer "In6.Cu")
		(net "M_K_CPU0_SB_DQS_DN<8>")
	)
	(segment
		(start 426.984668 -315.058044)
		(end 428.04842 -315.058044)
		(width 0.16002)
		(layer "In6.Cu")
		(net "M_K_CPU0_SB_DQS_DN<8>")
	)
	(arc
		(start 390.283446 -291.421058)
		(mid 390.564878 -291.345303)
		(end 390.84631 -291.421058)
		(width 0.09525)
		(layer "In6.Cu")
		(net "M_K_CPU0_SB_DQS_DN<8>")
	)
	(arc
		(start 393.681458 -292.735508)
		(mid 393.884871 -293.040031)
		(end 393.956286 -293.39921)
		(width 0.09525)
		(layer "In6.Cu")
		(net "M_K_CPU0_SB_DQS_DN<8>")
	)
	(arc
		(start 389.409686 -291.388038)
		(mid 389.419554 -291.384007)
		(end 389.429498 -291.380164)
		(width 0.09525)
		(layer "In6.Cu")
		(net "M_K_CPU0_SB_DQS_DN<8>")
	)
	(arc
		(start 389.914638 -291.425884)
		(mid 390.09967 -291.471798)
		(end 390.283446 -291.421058)
		(width 0.09525)
		(layer "In6.Cu")
		(net "M_K_CPU0_SB_DQS_DN<8>")
	)
	(arc
		(start 393.956286 -293.455598)
		(mid 393.996019 -293.655347)
		(end 394.109194 -293.82466)
		(width 0.09525)
		(layer "In6.Cu")
		(net "M_K_CPU0_SB_DQS_DN<8>")
	)
	(arc
		(start 392.881104 -291.708078)
		(mid 392.916527 -291.916132)
		(end 393.036044 -292.090094)
		(width 0.09525)
		(layer "In6.Cu")
		(net "M_K_CPU0_SB_DQS_DN<8>")
	)
	(arc
		(start 390.84631 -291.421058)
		(mid 391.034778 -291.471735)
		(end 391.223246 -291.421058)
		(width 0.09525)
		(layer "In6.Cu")
		(net "M_K_CPU0_SB_DQS_DN<8>")
	)
	(arc
		(start 392.725402 -291.421566)
		(mid 392.843386 -291.543011)
		(end 392.881104 -291.708078)
		(width 0.09525)
		(layer "In6.Cu")
		(net "M_K_CPU0_SB_DQS_DN<8>")
	)
	(arc
		(start 394.288772 -294.004238)
		(mid 394.390466 -294.156434)
		(end 394.426186 -294.335962)
		(width 0.09525)
		(layer "In6.Cu")
		(net "M_K_CPU0_SB_DQS_DN<8>")
	)
	(arc
		(start 391.78611 -291.421058)
		(mid 391.967726 -291.471795)
		(end 392.151108 -291.427916)
		(width 0.09525)
		(layer "In6.Cu")
		(net "M_K_CPU0_SB_DQS_DN<8>")
	)
	(arc
		(start 391.223246 -291.421058)
		(mid 391.504678 -291.345303)
		(end 391.78611 -291.421058)
		(width 0.09525)
		(layer "In6.Cu")
		(net "M_K_CPU0_SB_DQS_DN<8>")
	)
	(arc
		(start 389.429498 -291.380164)
		(mid 389.672462 -291.347177)
		(end 389.906256 -291.421058)
		(width 0.09525)
		(layer "In6.Cu")
		(net "M_K_CPU0_SB_DQS_DN<8>")
	)
	(arc
		(start 392.17346 -291.414962)
		(mid 392.450368 -291.345285)
		(end 392.725656 -291.421058)
		(width 0.09525)
		(layer "In6.Cu")
		(net "M_K_CPU0_SB_DQS_DN<8>")
	)
	(segment
		(start 388.688072 -285.970218)
		(end 389.154924 -286.236156)
		(width 0.12954)
		(layer "F.Cu")
		(net "M_K_CPU0_SB_DQS_DN<7>")
	)
	(segment
		(start 407.90114 -302.167036)
		(end 408.377644 -302.167036)
		(width 0.16002)
		(layer "In6.Cu")
		(net "M_K_CPU0_SB_DQS_DN<7>")
	)
	(segment
		(start 435.592474 -305.70805)
		(end 435.972458 -305.328066)
		(width 0.16002)
		(layer "In6.Cu")
		(net "M_K_CPU0_SB_DQS_DN<7>")
	)
	(segment
		(start 428.04842 -305.70805)
		(end 428.428404 -305.328066)
		(width 0.16002)
		(layer "In6.Cu")
		(net "M_K_CPU0_SB_DQS_DN<7>")
	)
	(segment
		(start 410.648404 -304.9143)
		(end 411.124908 -304.9143)
		(width 0.16002)
		(layer "In6.Cu")
		(net "M_K_CPU0_SB_DQS_DN<7>")
	)
	(segment
		(start 407.556462 -302.285654)
		(end 407.782522 -302.285654)
		(width 0.16002)
		(layer "In6.Cu")
		(net "M_K_CPU0_SB_DQS_DN<7>")
	)
	(segment
		(start 395.84249 -287.566862)
		(end 395.859254 -287.583626)
		(width 0.09525)
		(layer "In6.Cu")
		(net "M_K_CPU0_SB_DQS_DN<7>")
	)
	(segment
		(start 410.174948 -303.96434)
		(end 410.174948 -304.440844)
		(width 0.16002)
		(layer "In6.Cu")
		(net "M_K_CPU0_SB_DQS_DN<7>")
	)
	(segment
		(start 409.156154 -303.659286)
		(end 409.274772 -303.540668)
		(width 0.16002)
		(layer "In6.Cu")
		(net "M_K_CPU0_SB_DQS_DN<7>")
	)
	(segment
		(start 439.922412 -304.857912)
		(end 440.07151 -304.708814)
		(width 0.16002)
		(layer "In6.Cu")
		(net "M_K_CPU0_SB_DQS_DN<7>")
	)
	(segment
		(start 410.174948 -304.440844)
		(end 410.05633 -304.559462)
		(width 0.16002)
		(layer "In6.Cu")
		(net "M_K_CPU0_SB_DQS_DN<7>")
	)
	(segment
		(start 434.528722 -305.70805)
		(end 435.592474 -305.70805)
		(width 0.16002)
		(layer "In6.Cu")
		(net "M_K_CPU0_SB_DQS_DN<7>")
	)
	(segment
		(start 436.576978 -305.328066)
		(end 437.364378 -304.540666)
		(width 0.16002)
		(layer "In6.Cu")
		(net "M_K_CPU0_SB_DQS_DN<7>")
	)
	(segment
		(start 406.527508 -300.793404)
		(end 407.004012 -300.793404)
		(width 0.16002)
		(layer "In6.Cu")
		(net "M_K_CPU0_SB_DQS_DN<7>")
	)
	(segment
		(start 429.820324 -304.540666)
		(end 430.879504 -304.540666)
		(width 0.16002)
		(layer "In6.Cu")
		(net "M_K_CPU0_SB_DQS_DN<7>")
	)
	(segment
		(start 394.369798 -287.027112)
		(end 395.21892 -287.027112)
		(width 0.09525)
		(layer "In6.Cu")
		(net "M_K_CPU0_SB_DQS_DN<7>")
	)
	(segment
		(start 389.308848 -286.501586)
		(end 389.409686 -286.528256)
		(width 0.09525)
		(layer "In6.Cu")
		(net "M_K_CPU0_SB_DQS_DN<7>")
	)
	(segment
		(start 419.440614 -305.70805)
		(end 420.504366 -305.70805)
		(width 0.16002)
		(layer "In6.Cu")
		(net "M_K_CPU0_SB_DQS_DN<7>")
	)
	(segment
		(start 392.61161 -286.440372)
		(end 393.783058 -286.440372)
		(width 0.09525)
		(layer "In6.Cu")
		(net "M_K_CPU0_SB_DQS_DN<7>")
	)
	(segment
		(start 405.75484 -299.544232)
		(end 406.054052 -299.843444)
		(width 0.16002)
		(layer "In6.Cu")
		(net "M_K_CPU0_SB_DQS_DN<7>")
	)
	(segment
		(start 392.14679 -286.57042)
		(end 392.163046 -286.561022)
		(width 0.09525)
		(layer "In6.Cu")
		(net "M_K_CPU0_SB_DQS_DN<7>")
	)
	(segment
		(start 420.88435 -305.328066)
		(end 421.48887 -305.328066)
		(width 0.16002)
		(layer "In6.Cu")
		(net "M_K_CPU0_SB_DQS_DN<7>")
	)
	(segment
		(start 389.154924 -286.236156)
		(end 389.308848 -286.501586)
		(width 0.09525)
		(layer "In6.Cu")
		(net "M_K_CPU0_SB_DQS_DN<7>")
	)
	(segment
		(start 408.930094 -303.659286)
		(end 409.156154 -303.659286)
		(width 0.16002)
		(layer "In6.Cu")
		(net "M_K_CPU0_SB_DQS_DN<7>")
	)
	(segment
		(start 410.05633 -304.785522)
		(end 410.303726 -305.032918)
		(width 0.16002)
		(layer "In6.Cu")
		(net "M_K_CPU0_SB_DQS_DN<7>")
	)
	(segment
		(start 406.054052 -299.843444)
		(end 406.054052 -300.319948)
		(width 0.16002)
		(layer "In6.Cu")
		(net "M_K_CPU0_SB_DQS_DN<7>")
	)
	(segment
		(start 405.935434 -300.438566)
		(end 405.935434 -300.664626)
		(width 0.16002)
		(layer "In6.Cu")
		(net "M_K_CPU0_SB_DQS_DN<7>")
	)
	(segment
		(start 395.21892 -287.027112)
		(end 395.75867 -287.566862)
		(width 0.09525)
		(layer "In6.Cu")
		(net "M_K_CPU0_SB_DQS_DN<7>")
	)
	(segment
		(start 401.677378 -293.40175)
		(end 401.677378 -296.60723)
		(width 0.16002)
		(layer "In6.Cu")
		(net "M_K_CPU0_SB_DQS_DN<7>")
	)
	(segment
		(start 406.40889 -300.912022)
		(end 406.527508 -300.793404)
		(width 0.16002)
		(layer "In6.Cu")
		(net "M_K_CPU0_SB_DQS_DN<7>")
	)
	(segment
		(start 407.309066 -301.812198)
		(end 407.309066 -302.038258)
		(width 0.16002)
		(layer "In6.Cu")
		(net "M_K_CPU0_SB_DQS_DN<7>")
	)
	(segment
		(start 435.972458 -305.328066)
		(end 436.576978 -305.328066)
		(width 0.16002)
		(layer "In6.Cu")
		(net "M_K_CPU0_SB_DQS_DN<7>")
	)
	(segment
		(start 423.33545 -304.540666)
		(end 423.652696 -304.857912)
		(width 0.16002)
		(layer "In6.Cu")
		(net "M_K_CPU0_SB_DQS_DN<7>")
	)
	(segment
		(start 438.423558 -304.540666)
		(end 438.740804 -304.857912)
		(width 0.16002)
		(layer "In6.Cu")
		(net "M_K_CPU0_SB_DQS_DN<7>")
	)
	(segment
		(start 393.783058 -286.440372)
		(end 394.369798 -287.027112)
		(width 0.09525)
		(layer "In6.Cu")
		(net "M_K_CPU0_SB_DQS_DN<7>")
	)
	(segment
		(start 416.108642 -304.857912)
		(end 418.590476 -304.857912)
		(width 0.16002)
		(layer "In6.Cu")
		(net "M_K_CPU0_SB_DQS_DN<7>")
	)
	(segment
		(start 407.004012 -300.793404)
		(end 407.427684 -301.217076)
		(width 0.16002)
		(layer "In6.Cu")
		(net "M_K_CPU0_SB_DQS_DN<7>")
	)
	(segment
		(start 438.740804 -304.857912)
		(end 439.922412 -304.857912)
		(width 0.16002)
		(layer "In6.Cu")
		(net "M_K_CPU0_SB_DQS_DN<7>")
	)
	(segment
		(start 430.879504 -304.540666)
		(end 431.19675 -304.857912)
		(width 0.16002)
		(layer "In6.Cu")
		(net "M_K_CPU0_SB_DQS_DN<7>")
	)
	(segment
		(start 426.13453 -304.857912)
		(end 426.984668 -305.70805)
		(width 0.16002)
		(layer "In6.Cu")
		(net "M_K_CPU0_SB_DQS_DN<7>")
	)
	(segment
		(start 406.054052 -300.319948)
		(end 405.935434 -300.438566)
		(width 0.16002)
		(layer "In6.Cu")
		(net "M_K_CPU0_SB_DQS_DN<7>")
	)
	(segment
		(start 421.48887 -305.328066)
		(end 422.27627 -304.540666)
		(width 0.16002)
		(layer "In6.Cu")
		(net "M_K_CPU0_SB_DQS_DN<7>")
	)
	(segment
		(start 426.984668 -305.70805)
		(end 428.04842 -305.70805)
		(width 0.16002)
		(layer "In6.Cu")
		(net "M_K_CPU0_SB_DQS_DN<7>")
	)
	(segment
		(start 408.801316 -302.590708)
		(end 408.801316 -303.067212)
		(width 0.16002)
		(layer "In6.Cu")
		(net "M_K_CPU0_SB_DQS_DN<7>")
	)
	(segment
		(start 395.75867 -287.566862)
		(end 395.84249 -287.566862)
		(width 0.09525)
		(layer "In6.Cu")
		(net "M_K_CPU0_SB_DQS_DN<7>")
	)
	(segment
		(start 409.274772 -303.540668)
		(end 409.751276 -303.540668)
		(width 0.16002)
		(layer "In6.Cu")
		(net "M_K_CPU0_SB_DQS_DN<7>")
	)
	(segment
		(start 433.678584 -304.857912)
		(end 434.528722 -305.70805)
		(width 0.16002)
		(layer "In6.Cu")
		(net "M_K_CPU0_SB_DQS_DN<7>")
	)
	(segment
		(start 408.801316 -303.067212)
		(end 408.682698 -303.18583)
		(width 0.16002)
		(layer "In6.Cu")
		(net "M_K_CPU0_SB_DQS_DN<7>")
	)
	(segment
		(start 410.303726 -305.032918)
		(end 410.529786 -305.032918)
		(width 0.16002)
		(layer "In6.Cu")
		(net "M_K_CPU0_SB_DQS_DN<7>")
	)
	(segment
		(start 415.791396 -304.540666)
		(end 416.108642 -304.857912)
		(width 0.16002)
		(layer "In6.Cu")
		(net "M_K_CPU0_SB_DQS_DN<7>")
	)
	(segment
		(start 405.935434 -300.664626)
		(end 406.18283 -300.912022)
		(width 0.16002)
		(layer "In6.Cu")
		(net "M_K_CPU0_SB_DQS_DN<7>")
	)
	(segment
		(start 401.677378 -296.60723)
		(end 404.61438 -299.544232)
		(width 0.16002)
		(layer "In6.Cu")
		(net "M_K_CPU0_SB_DQS_DN<7>")
	)
	(segment
		(start 407.309066 -302.038258)
		(end 407.556462 -302.285654)
		(width 0.16002)
		(layer "In6.Cu")
		(net "M_K_CPU0_SB_DQS_DN<7>")
	)
	(segment
		(start 406.18283 -300.912022)
		(end 406.40889 -300.912022)
		(width 0.16002)
		(layer "In6.Cu")
		(net "M_K_CPU0_SB_DQS_DN<7>")
	)
	(segment
		(start 410.529786 -305.032918)
		(end 410.648404 -304.9143)
		(width 0.16002)
		(layer "In6.Cu")
		(net "M_K_CPU0_SB_DQS_DN<7>")
	)
	(segment
		(start 389.906256 -286.561276)
		(end 389.914638 -286.566102)
		(width 0.09525)
		(layer "In6.Cu")
		(net "M_K_CPU0_SB_DQS_DN<7>")
	)
	(segment
		(start 410.05633 -304.559462)
		(end 410.05633 -304.785522)
		(width 0.16002)
		(layer "In6.Cu")
		(net "M_K_CPU0_SB_DQS_DN<7>")
	)
	(segment
		(start 429.032924 -305.328066)
		(end 429.820324 -304.540666)
		(width 0.16002)
		(layer "In6.Cu")
		(net "M_K_CPU0_SB_DQS_DN<7>")
	)
	(segment
		(start 413.944816 -305.328066)
		(end 414.732216 -304.540666)
		(width 0.16002)
		(layer "In6.Cu")
		(net "M_K_CPU0_SB_DQS_DN<7>")
	)
	(segment
		(start 420.504366 -305.70805)
		(end 420.88435 -305.328066)
		(width 0.16002)
		(layer "In6.Cu")
		(net "M_K_CPU0_SB_DQS_DN<7>")
	)
	(segment
		(start 407.427684 -301.69358)
		(end 407.309066 -301.812198)
		(width 0.16002)
		(layer "In6.Cu")
		(net "M_K_CPU0_SB_DQS_DN<7>")
	)
	(segment
		(start 409.751276 -303.540668)
		(end 410.174948 -303.96434)
		(width 0.16002)
		(layer "In6.Cu")
		(net "M_K_CPU0_SB_DQS_DN<7>")
	)
	(segment
		(start 431.19675 -304.857912)
		(end 433.678584 -304.857912)
		(width 0.16002)
		(layer "In6.Cu")
		(net "M_K_CPU0_SB_DQS_DN<7>")
	)
	(segment
		(start 407.782522 -302.285654)
		(end 407.90114 -302.167036)
		(width 0.16002)
		(layer "In6.Cu")
		(net "M_K_CPU0_SB_DQS_DN<7>")
	)
	(segment
		(start 411.124908 -304.9143)
		(end 411.538674 -305.328066)
		(width 0.16002)
		(layer "In6.Cu")
		(net "M_K_CPU0_SB_DQS_DN<7>")
	)
	(segment
		(start 423.652696 -304.857912)
		(end 426.13453 -304.857912)
		(width 0.16002)
		(layer "In6.Cu")
		(net "M_K_CPU0_SB_DQS_DN<7>")
	)
	(segment
		(start 418.590476 -304.857912)
		(end 419.440614 -305.70805)
		(width 0.16002)
		(layer "In6.Cu")
		(net "M_K_CPU0_SB_DQS_DN<7>")
	)
	(segment
		(start 440.07151 -304.708814)
		(end 442.270388 -304.708814)
		(width 0.16002)
		(layer "In6.Cu")
		(net "M_K_CPU0_SB_DQS_DN<7>")
	)
	(segment
		(start 442.270388 -304.708814)
		(end 442.5442 -304.435002)
		(width 0.16002)
		(layer "In6.Cu")
		(net "M_K_CPU0_SB_DQS_DN<7>")
	)
	(segment
		(start 437.364378 -304.540666)
		(end 438.423558 -304.540666)
		(width 0.16002)
		(layer "In6.Cu")
		(net "M_K_CPU0_SB_DQS_DN<7>")
	)
	(segment
		(start 407.427684 -301.217076)
		(end 407.427684 -301.69358)
		(width 0.16002)
		(layer "In6.Cu")
		(net "M_K_CPU0_SB_DQS_DN<7>")
	)
	(segment
		(start 414.732216 -304.540666)
		(end 415.791396 -304.540666)
		(width 0.16002)
		(layer "In6.Cu")
		(net "M_K_CPU0_SB_DQS_DN<7>")
	)
	(segment
		(start 408.377644 -302.167036)
		(end 408.801316 -302.590708)
		(width 0.16002)
		(layer "In6.Cu")
		(net "M_K_CPU0_SB_DQS_DN<7>")
	)
	(segment
		(start 422.27627 -304.540666)
		(end 423.33545 -304.540666)
		(width 0.16002)
		(layer "In6.Cu")
		(net "M_K_CPU0_SB_DQS_DN<7>")
	)
	(segment
		(start 428.428404 -305.328066)
		(end 429.032924 -305.328066)
		(width 0.16002)
		(layer "In6.Cu")
		(net "M_K_CPU0_SB_DQS_DN<7>")
	)
	(segment
		(start 395.859254 -287.583626)
		(end 401.677378 -293.40175)
		(width 0.16002)
		(layer "In6.Cu")
		(net "M_K_CPU0_SB_DQS_DN<7>")
	)
	(segment
		(start 404.61438 -299.544232)
		(end 405.75484 -299.544232)
		(width 0.16002)
		(layer "In6.Cu")
		(net "M_K_CPU0_SB_DQS_DN<7>")
	)
	(segment
		(start 411.538674 -305.328066)
		(end 413.944816 -305.328066)
		(width 0.16002)
		(layer "In6.Cu")
		(net "M_K_CPU0_SB_DQS_DN<7>")
	)
	(segment
		(start 408.682698 -303.18583)
		(end 408.682698 -303.41189)
		(width 0.16002)
		(layer "In6.Cu")
		(net "M_K_CPU0_SB_DQS_DN<7>")
	)
	(segment
		(start 408.682698 -303.41189)
		(end 408.930094 -303.659286)
		(width 0.16002)
		(layer "In6.Cu")
		(net "M_K_CPU0_SB_DQS_DN<7>")
	)
	(arc
		(start 390.84631 -286.561276)
		(mid 391.034778 -286.611953)
		(end 391.223246 -286.561276)
		(width 0.09525)
		(layer "In6.Cu")
		(net "M_K_CPU0_SB_DQS_DN<7>")
	)
	(arc
		(start 392.163046 -286.561022)
		(mid 392.379351 -286.471026)
		(end 392.61161 -286.440372)
		(width 0.09525)
		(layer "In6.Cu")
		(net "M_K_CPU0_SB_DQS_DN<7>")
	)
	(arc
		(start 390.283446 -286.561276)
		(mid 390.564878 -286.485487)
		(end 390.84631 -286.561276)
		(width 0.09525)
		(layer "In6.Cu")
		(net "M_K_CPU0_SB_DQS_DN<7>")
	)
	(arc
		(start 389.914638 -286.566102)
		(mid 390.09967 -286.612016)
		(end 390.283446 -286.561276)
		(width 0.09525)
		(layer "In6.Cu")
		(net "M_K_CPU0_SB_DQS_DN<7>")
	)
	(arc
		(start 391.78611 -286.561276)
		(mid 391.965284 -286.611959)
		(end 392.14679 -286.57042)
		(width 0.09525)
		(layer "In6.Cu")
		(net "M_K_CPU0_SB_DQS_DN<7>")
	)
	(arc
		(start 391.223246 -286.561276)
		(mid 391.504678 -286.485487)
		(end 391.78611 -286.561276)
		(width 0.09525)
		(layer "In6.Cu")
		(net "M_K_CPU0_SB_DQS_DN<7>")
	)
	(arc
		(start 389.409686 -286.528256)
		(mid 389.661826 -286.486667)
		(end 389.906256 -286.561276)
		(width 0.09525)
		(layer "In6.Cu")
		(net "M_K_CPU0_SB_DQS_DN<7>")
	)
	(segment
		(start 388.688072 -281.110182)
		(end 389.154924 -281.37612)
		(width 0.12954)
		(layer "F.Cu")
		(net "M_K_CPU0_SB_DQS_DN<6>")
	)
	(segment
		(start 394.820648 -281.877262)
		(end 395.77645 -281.877262)
		(width 0.09525)
		(layer "In6.Cu")
		(net "M_K_CPU0_SB_DQS_DN<6>")
	)
	(segment
		(start 433.678584 -295.507918)
		(end 434.528722 -296.358056)
		(width 0.16002)
		(layer "In6.Cu")
		(net "M_K_CPU0_SB_DQS_DN<6>")
	)
	(segment
		(start 419.440614 -296.358056)
		(end 420.504366 -296.358056)
		(width 0.16002)
		(layer "In6.Cu")
		(net "M_K_CPU0_SB_DQS_DN<6>")
	)
	(segment
		(start 411.757368 -295.983406)
		(end 411.891988 -295.848786)
		(width 0.16002)
		(layer "In6.Cu")
		(net "M_K_CPU0_SB_DQS_DN<6>")
	)
	(segment
		(start 389.154924 -281.37612)
		(end 389.308848 -281.64155)
		(width 0.09525)
		(layer "In6.Cu")
		(net "M_K_CPU0_SB_DQS_DN<6>")
	)
	(segment
		(start 394.477494 -281.618182)
		(end 394.621004 -281.677618)
		(width 0.09525)
		(layer "In6.Cu")
		(net "M_K_CPU0_SB_DQS_DN<6>")
	)
	(segment
		(start 423.652696 -295.507918)
		(end 426.13453 -295.507918)
		(width 0.16002)
		(layer "In6.Cu")
		(net "M_K_CPU0_SB_DQS_DN<6>")
	)
	(segment
		(start 414.732216 -295.190672)
		(end 416.19551 -295.190672)
		(width 0.16002)
		(layer "In6.Cu")
		(net "M_K_CPU0_SB_DQS_DN<6>")
	)
	(segment
		(start 438.423558 -295.190672)
		(end 438.740804 -295.507918)
		(width 0.16002)
		(layer "In6.Cu")
		(net "M_K_CPU0_SB_DQS_DN<6>")
	)
	(segment
		(start 429.032924 -295.978072)
		(end 429.820324 -295.190672)
		(width 0.16002)
		(layer "In6.Cu")
		(net "M_K_CPU0_SB_DQS_DN<6>")
	)
	(segment
		(start 416.19551 -295.190672)
		(end 416.532568 -295.52773)
		(width 0.16002)
		(layer "In6.Cu")
		(net "M_K_CPU0_SB_DQS_DN<6>")
	)
	(segment
		(start 410.157676 -294.609774)
		(end 410.383736 -294.609774)
		(width 0.16002)
		(layer "In6.Cu")
		(net "M_K_CPU0_SB_DQS_DN<6>")
	)
	(segment
		(start 410.383736 -294.609774)
		(end 410.518356 -294.475154)
		(width 0.16002)
		(layer "In6.Cu")
		(net "M_K_CPU0_SB_DQS_DN<6>")
	)
	(segment
		(start 422.27627 -295.190672)
		(end 423.33545 -295.190672)
		(width 0.16002)
		(layer "In6.Cu")
		(net "M_K_CPU0_SB_DQS_DN<6>")
	)
	(segment
		(start 389.906256 -281.70124)
		(end 389.914638 -281.706066)
		(width 0.09525)
		(layer "In6.Cu")
		(net "M_K_CPU0_SB_DQS_DN<6>")
	)
	(segment
		(start 416.692588 -295.853612)
		(end 417.040822 -295.853612)
		(width 0.16002)
		(layer "In6.Cu")
		(net "M_K_CPU0_SB_DQS_DN<6>")
	)
	(segment
		(start 438.740804 -295.507918)
		(end 439.922412 -295.507918)
		(width 0.16002)
		(layer "In6.Cu")
		(net "M_K_CPU0_SB_DQS_DN<6>")
	)
	(segment
		(start 434.528722 -296.358056)
		(end 435.592474 -296.358056)
		(width 0.16002)
		(layer "In6.Cu")
		(net "M_K_CPU0_SB_DQS_DN<6>")
	)
	(segment
		(start 420.88435 -295.978072)
		(end 421.48887 -295.978072)
		(width 0.16002)
		(layer "In6.Cu")
		(net "M_K_CPU0_SB_DQS_DN<6>")
	)
	(segment
		(start 409.911042 -294.36314)
		(end 410.157676 -294.609774)
		(width 0.16002)
		(layer "In6.Cu")
		(net "M_K_CPU0_SB_DQS_DN<6>")
	)
	(segment
		(start 426.984668 -296.358056)
		(end 428.04842 -296.358056)
		(width 0.16002)
		(layer "In6.Cu")
		(net "M_K_CPU0_SB_DQS_DN<6>")
	)
	(segment
		(start 410.045662 -294.00246)
		(end 409.911042 -294.13708)
		(width 0.16002)
		(layer "In6.Cu")
		(net "M_K_CPU0_SB_DQS_DN<6>")
	)
	(segment
		(start 410.045662 -293.525956)
		(end 410.045662 -294.00246)
		(width 0.16002)
		(layer "In6.Cu")
		(net "M_K_CPU0_SB_DQS_DN<6>")
	)
	(segment
		(start 421.48887 -295.978072)
		(end 422.27627 -295.190672)
		(width 0.16002)
		(layer "In6.Cu")
		(net "M_K_CPU0_SB_DQS_DN<6>")
	)
	(segment
		(start 392.725656 -281.70124)
		(end 392.737594 -281.708098)
		(width 0.09525)
		(layer "In6.Cu")
		(net "M_K_CPU0_SB_DQS_DN<6>")
	)
	(segment
		(start 440.07151 -295.35882)
		(end 442.270388 -295.35882)
		(width 0.16002)
		(layer "In6.Cu")
		(net "M_K_CPU0_SB_DQS_DN<6>")
	)
	(segment
		(start 398.337786 -281.81808)
		(end 410.045662 -293.525956)
		(width 0.16002)
		(layer "In6.Cu")
		(net "M_K_CPU0_SB_DQS_DN<6>")
	)
	(segment
		(start 393.1031 -281.70124)
		(end 393.30376 -281.618182)
		(width 0.09525)
		(layer "In6.Cu")
		(net "M_K_CPU0_SB_DQS_DN<6>")
	)
	(segment
		(start 416.532568 -295.52773)
		(end 416.532568 -295.693592)
		(width 0.16002)
		(layer "In6.Cu")
		(net "M_K_CPU0_SB_DQS_DN<6>")
	)
	(segment
		(start 428.04842 -296.358056)
		(end 428.428404 -295.978072)
		(width 0.16002)
		(layer "In6.Cu")
		(net "M_K_CPU0_SB_DQS_DN<6>")
	)
	(segment
		(start 417.5379 -295.190672)
		(end 418.27323 -295.190672)
		(width 0.16002)
		(layer "In6.Cu")
		(net "M_K_CPU0_SB_DQS_DN<6>")
	)
	(segment
		(start 435.972458 -295.978072)
		(end 436.576978 -295.978072)
		(width 0.16002)
		(layer "In6.Cu")
		(net "M_K_CPU0_SB_DQS_DN<6>")
	)
	(segment
		(start 411.531308 -295.983406)
		(end 411.757368 -295.983406)
		(width 0.16002)
		(layer "In6.Cu")
		(net "M_K_CPU0_SB_DQS_DN<6>")
	)
	(segment
		(start 410.518356 -294.475154)
		(end 410.99486 -294.475154)
		(width 0.16002)
		(layer "In6.Cu")
		(net "M_K_CPU0_SB_DQS_DN<6>")
	)
	(segment
		(start 417.040822 -295.853612)
		(end 417.200842 -295.693592)
		(width 0.16002)
		(layer "In6.Cu")
		(net "M_K_CPU0_SB_DQS_DN<6>")
	)
	(segment
		(start 417.200842 -295.693592)
		(end 417.200842 -295.52773)
		(width 0.16002)
		(layer "In6.Cu")
		(net "M_K_CPU0_SB_DQS_DN<6>")
	)
	(segment
		(start 395.835632 -281.81808)
		(end 395.859254 -281.81808)
		(width 0.09525)
		(layer "In6.Cu")
		(net "M_K_CPU0_SB_DQS_DN<6>")
	)
	(segment
		(start 411.284674 -295.510712)
		(end 411.284674 -295.736772)
		(width 0.16002)
		(layer "In6.Cu")
		(net "M_K_CPU0_SB_DQS_DN<6>")
	)
	(segment
		(start 430.879504 -295.190672)
		(end 431.19675 -295.507918)
		(width 0.16002)
		(layer "In6.Cu")
		(net "M_K_CPU0_SB_DQS_DN<6>")
	)
	(segment
		(start 437.364378 -295.190672)
		(end 438.423558 -295.190672)
		(width 0.16002)
		(layer "In6.Cu")
		(net "M_K_CPU0_SB_DQS_DN<6>")
	)
	(segment
		(start 409.911042 -294.13708)
		(end 409.911042 -294.36314)
		(width 0.16002)
		(layer "In6.Cu")
		(net "M_K_CPU0_SB_DQS_DN<6>")
	)
	(segment
		(start 393.30376 -281.618182)
		(end 394.477494 -281.618182)
		(width 0.09525)
		(layer "In6.Cu")
		(net "M_K_CPU0_SB_DQS_DN<6>")
	)
	(segment
		(start 442.270388 -295.35882)
		(end 442.5442 -295.085008)
		(width 0.16002)
		(layer "In6.Cu")
		(net "M_K_CPU0_SB_DQS_DN<6>")
	)
	(segment
		(start 429.820324 -295.190672)
		(end 430.879504 -295.190672)
		(width 0.16002)
		(layer "In6.Cu")
		(net "M_K_CPU0_SB_DQS_DN<6>")
	)
	(segment
		(start 411.284674 -295.736772)
		(end 411.531308 -295.983406)
		(width 0.16002)
		(layer "In6.Cu")
		(net "M_K_CPU0_SB_DQS_DN<6>")
	)
	(segment
		(start 426.13453 -295.507918)
		(end 426.984668 -296.358056)
		(width 0.16002)
		(layer "In6.Cu")
		(net "M_K_CPU0_SB_DQS_DN<6>")
	)
	(segment
		(start 392.163046 -281.70124)
		(end 392.17346 -281.695144)
		(width 0.09525)
		(layer "In6.Cu")
		(net "M_K_CPU0_SB_DQS_DN<6>")
	)
	(segment
		(start 439.922412 -295.507918)
		(end 440.07151 -295.35882)
		(width 0.16002)
		(layer "In6.Cu")
		(net "M_K_CPU0_SB_DQS_DN<6>")
	)
	(segment
		(start 417.200842 -295.52773)
		(end 417.5379 -295.190672)
		(width 0.16002)
		(layer "In6.Cu")
		(net "M_K_CPU0_SB_DQS_DN<6>")
	)
	(segment
		(start 410.99486 -294.475154)
		(end 411.419294 -294.899588)
		(width 0.16002)
		(layer "In6.Cu")
		(net "M_K_CPU0_SB_DQS_DN<6>")
	)
	(segment
		(start 412.497778 -295.978072)
		(end 413.944816 -295.978072)
		(width 0.16002)
		(layer "In6.Cu")
		(net "M_K_CPU0_SB_DQS_DN<6>")
	)
	(segment
		(start 395.859254 -281.81808)
		(end 398.337786 -281.81808)
		(width 0.16002)
		(layer "In6.Cu")
		(net "M_K_CPU0_SB_DQS_DN<6>")
	)
	(segment
		(start 428.428404 -295.978072)
		(end 429.032924 -295.978072)
		(width 0.16002)
		(layer "In6.Cu")
		(net "M_K_CPU0_SB_DQS_DN<6>")
	)
	(segment
		(start 392.151108 -281.708098)
		(end 392.163046 -281.70124)
		(width 0.09525)
		(layer "In6.Cu")
		(net "M_K_CPU0_SB_DQS_DN<6>")
	)
	(segment
		(start 413.944816 -295.978072)
		(end 414.732216 -295.190672)
		(width 0.16002)
		(layer "In6.Cu")
		(net "M_K_CPU0_SB_DQS_DN<6>")
	)
	(segment
		(start 411.419294 -295.376092)
		(end 411.284674 -295.510712)
		(width 0.16002)
		(layer "In6.Cu")
		(net "M_K_CPU0_SB_DQS_DN<6>")
	)
	(segment
		(start 423.33545 -295.190672)
		(end 423.652696 -295.507918)
		(width 0.16002)
		(layer "In6.Cu")
		(net "M_K_CPU0_SB_DQS_DN<6>")
	)
	(segment
		(start 436.576978 -295.978072)
		(end 437.364378 -295.190672)
		(width 0.16002)
		(layer "In6.Cu")
		(net "M_K_CPU0_SB_DQS_DN<6>")
	)
	(segment
		(start 431.19675 -295.507918)
		(end 433.678584 -295.507918)
		(width 0.16002)
		(layer "In6.Cu")
		(net "M_K_CPU0_SB_DQS_DN<6>")
	)
	(segment
		(start 412.368492 -295.848786)
		(end 412.497778 -295.978072)
		(width 0.16002)
		(layer "In6.Cu")
		(net "M_K_CPU0_SB_DQS_DN<6>")
	)
	(segment
		(start 418.27323 -295.190672)
		(end 419.440614 -296.358056)
		(width 0.16002)
		(layer "In6.Cu")
		(net "M_K_CPU0_SB_DQS_DN<6>")
	)
	(segment
		(start 435.592474 -296.358056)
		(end 435.972458 -295.978072)
		(width 0.16002)
		(layer "In6.Cu")
		(net "M_K_CPU0_SB_DQS_DN<6>")
	)
	(segment
		(start 394.621004 -281.677618)
		(end 394.820648 -281.877262)
		(width 0.09525)
		(layer "In6.Cu")
		(net "M_K_CPU0_SB_DQS_DN<6>")
	)
	(segment
		(start 411.419294 -294.899588)
		(end 411.419294 -295.376092)
		(width 0.16002)
		(layer "In6.Cu")
		(net "M_K_CPU0_SB_DQS_DN<6>")
	)
	(segment
		(start 416.532568 -295.693592)
		(end 416.692588 -295.853612)
		(width 0.16002)
		(layer "In6.Cu")
		(net "M_K_CPU0_SB_DQS_DN<6>")
	)
	(segment
		(start 395.77645 -281.877262)
		(end 395.835632 -281.81808)
		(width 0.09525)
		(layer "In6.Cu")
		(net "M_K_CPU0_SB_DQS_DN<6>")
	)
	(segment
		(start 389.308848 -281.64155)
		(end 389.409686 -281.66822)
		(width 0.09525)
		(layer "In6.Cu")
		(net "M_K_CPU0_SB_DQS_DN<6>")
	)
	(segment
		(start 411.891988 -295.848786)
		(end 412.368492 -295.848786)
		(width 0.16002)
		(layer "In6.Cu")
		(net "M_K_CPU0_SB_DQS_DN<6>")
	)
	(segment
		(start 420.504366 -296.358056)
		(end 420.88435 -295.978072)
		(width 0.16002)
		(layer "In6.Cu")
		(net "M_K_CPU0_SB_DQS_DN<6>")
	)
	(arc
		(start 389.914638 -281.706066)
		(mid 390.09967 -281.75198)
		(end 390.283446 -281.70124)
		(width 0.09525)
		(layer "In6.Cu")
		(net "M_K_CPU0_SB_DQS_DN<6>")
	)
	(arc
		(start 391.78611 -281.70124)
		(mid 391.967726 -281.751977)
		(end 392.151108 -281.708098)
		(width 0.09525)
		(layer "In6.Cu")
		(net "M_K_CPU0_SB_DQS_DN<6>")
	)
	(arc
		(start 392.737594 -281.708098)
		(mid 392.921229 -281.752048)
		(end 393.1031 -281.70124)
		(width 0.09525)
		(layer "In6.Cu")
		(net "M_K_CPU0_SB_DQS_DN<6>")
	)
	(arc
		(start 389.409686 -281.66822)
		(mid 389.661827 -281.62665)
		(end 389.906256 -281.70124)
		(width 0.09525)
		(layer "In6.Cu")
		(net "M_K_CPU0_SB_DQS_DN<6>")
	)
	(arc
		(start 390.84631 -281.70124)
		(mid 391.034778 -281.751917)
		(end 391.223246 -281.70124)
		(width 0.09525)
		(layer "In6.Cu")
		(net "M_K_CPU0_SB_DQS_DN<6>")
	)
	(arc
		(start 390.283446 -281.70124)
		(mid 390.564878 -281.625485)
		(end 390.84631 -281.70124)
		(width 0.09525)
		(layer "In6.Cu")
		(net "M_K_CPU0_SB_DQS_DN<6>")
	)
	(arc
		(start 391.223246 -281.70124)
		(mid 391.504678 -281.625485)
		(end 391.78611 -281.70124)
		(width 0.09525)
		(layer "In6.Cu")
		(net "M_K_CPU0_SB_DQS_DN<6>")
	)
	(arc
		(start 392.17346 -281.695144)
		(mid 392.450368 -281.625467)
		(end 392.725656 -281.70124)
		(width 0.09525)
		(layer "In6.Cu")
		(net "M_K_CPU0_SB_DQS_DN<6>")
	)
	(segment
		(start 388.688072 -276.250146)
		(end 389.154924 -276.516084)
		(width 0.12954)
		(layer "F.Cu")
		(net "M_K_CPU0_SB_DQS_DN<5>")
	)
	(segment
		(start 428.04842 -287.008062)
		(end 428.428404 -286.628078)
		(width 0.16002)
		(layer "In6.Cu")
		(net "M_K_CPU0_SB_DQS_DN<5>")
	)
	(segment
		(start 417.832032 -285.840678)
		(end 418.27323 -285.840678)
		(width 0.16002)
		(layer "In6.Cu")
		(net "M_K_CPU0_SB_DQS_DN<5>")
	)
	(segment
		(start 392.163046 -276.841204)
		(end 392.17346 -276.835108)
		(width 0.09525)
		(layer "In6.Cu")
		(net "M_K_CPU0_SB_DQS_DN<5>")
	)
	(segment
		(start 423.33545 -285.840678)
		(end 423.652696 -286.157924)
		(width 0.16002)
		(layer "In6.Cu")
		(net "M_K_CPU0_SB_DQS_DN<5>")
	)
	(segment
		(start 430.879504 -285.840678)
		(end 431.19675 -286.157924)
		(width 0.16002)
		(layer "In6.Cu")
		(net "M_K_CPU0_SB_DQS_DN<5>")
	)
	(segment
		(start 417.334954 -286.486092)
		(end 417.494974 -286.326072)
		(width 0.16002)
		(layer "In6.Cu")
		(net "M_K_CPU0_SB_DQS_DN<5>")
	)
	(segment
		(start 417.494974 -286.326072)
		(end 417.494974 -286.177736)
		(width 0.16002)
		(layer "In6.Cu")
		(net "M_K_CPU0_SB_DQS_DN<5>")
	)
	(segment
		(start 392.151108 -276.848062)
		(end 392.163046 -276.841204)
		(width 0.09525)
		(layer "In6.Cu")
		(net "M_K_CPU0_SB_DQS_DN<5>")
	)
	(segment
		(start 423.652696 -286.157924)
		(end 426.13453 -286.157924)
		(width 0.16002)
		(layer "In6.Cu")
		(net "M_K_CPU0_SB_DQS_DN<5>")
	)
	(segment
		(start 422.27627 -285.840678)
		(end 423.33545 -285.840678)
		(width 0.16002)
		(layer "In6.Cu")
		(net "M_K_CPU0_SB_DQS_DN<5>")
	)
	(segment
		(start 395.168628 -275.631402)
		(end 395.412214 -275.874988)
		(width 0.09525)
		(layer "In6.Cu")
		(net "M_K_CPU0_SB_DQS_DN<5>")
	)
	(segment
		(start 429.820324 -285.840678)
		(end 430.879504 -285.840678)
		(width 0.16002)
		(layer "In6.Cu")
		(net "M_K_CPU0_SB_DQS_DN<5>")
	)
	(segment
		(start 442.270388 -286.008826)
		(end 442.5442 -285.735014)
		(width 0.16002)
		(layer "In6.Cu")
		(net "M_K_CPU0_SB_DQS_DN<5>")
	)
	(segment
		(start 436.576978 -286.628078)
		(end 437.364378 -285.840678)
		(width 0.16002)
		(layer "In6.Cu")
		(net "M_K_CPU0_SB_DQS_DN<5>")
	)
	(segment
		(start 415.393886 -285.840678)
		(end 415.553906 -285.680658)
		(width 0.16002)
		(layer "In6.Cu")
		(net "M_K_CPU0_SB_DQS_DN<5>")
	)
	(segment
		(start 393.824714 -276.497542)
		(end 394.614654 -275.707348)
		(width 0.09525)
		(layer "In6.Cu")
		(net "M_K_CPU0_SB_DQS_DN<5>")
	)
	(segment
		(start 439.922412 -286.157924)
		(end 440.07151 -286.008826)
		(width 0.16002)
		(layer "In6.Cu")
		(net "M_K_CPU0_SB_DQS_DN<5>")
	)
	(segment
		(start 420.88435 -286.628078)
		(end 421.48887 -286.628078)
		(width 0.16002)
		(layer "In6.Cu")
		(net "M_K_CPU0_SB_DQS_DN<5>")
	)
	(segment
		(start 415.553906 -285.532322)
		(end 415.890964 -285.195264)
		(width 0.16002)
		(layer "In6.Cu")
		(net "M_K_CPU0_SB_DQS_DN<5>")
	)
	(segment
		(start 395.412214 -275.874988)
		(end 395.77645 -275.874988)
		(width 0.09525)
		(layer "In6.Cu")
		(net "M_K_CPU0_SB_DQS_DN<5>")
	)
	(segment
		(start 395.859254 -275.815806)
		(end 401.037552 -275.815806)
		(width 0.16002)
		(layer "In6.Cu")
		(net "M_K_CPU0_SB_DQS_DN<5>")
	)
	(segment
		(start 416.8267 -285.532322)
		(end 416.8267 -286.326072)
		(width 0.16002)
		(layer "In6.Cu")
		(net "M_K_CPU0_SB_DQS_DN<5>")
	)
	(segment
		(start 421.48887 -286.628078)
		(end 422.27627 -285.840678)
		(width 0.16002)
		(layer "In6.Cu")
		(net "M_K_CPU0_SB_DQS_DN<5>")
	)
	(segment
		(start 419.440614 -287.008062)
		(end 420.504366 -287.008062)
		(width 0.16002)
		(layer "In6.Cu")
		(net "M_K_CPU0_SB_DQS_DN<5>")
	)
	(segment
		(start 415.553906 -285.680658)
		(end 415.553906 -285.532322)
		(width 0.16002)
		(layer "In6.Cu")
		(net "M_K_CPU0_SB_DQS_DN<5>")
	)
	(segment
		(start 394.798296 -275.631402)
		(end 395.168628 -275.631402)
		(width 0.09525)
		(layer "In6.Cu")
		(net "M_K_CPU0_SB_DQS_DN<5>")
	)
	(segment
		(start 395.835632 -275.815806)
		(end 395.859254 -275.815806)
		(width 0.09525)
		(layer "In6.Cu")
		(net "M_K_CPU0_SB_DQS_DN<5>")
	)
	(segment
		(start 426.13453 -286.157924)
		(end 426.984668 -287.008062)
		(width 0.16002)
		(layer "In6.Cu")
		(net "M_K_CPU0_SB_DQS_DN<5>")
	)
	(segment
		(start 420.504366 -287.008062)
		(end 420.88435 -286.628078)
		(width 0.16002)
		(layer "In6.Cu")
		(net "M_K_CPU0_SB_DQS_DN<5>")
	)
	(segment
		(start 395.77645 -275.874988)
		(end 395.835632 -275.815806)
		(width 0.09525)
		(layer "In6.Cu")
		(net "M_K_CPU0_SB_DQS_DN<5>")
	)
	(segment
		(start 389.154924 -276.516084)
		(end 389.308848 -276.781514)
		(width 0.09525)
		(layer "In6.Cu")
		(net "M_K_CPU0_SB_DQS_DN<5>")
	)
	(segment
		(start 389.308848 -276.781514)
		(end 389.409686 -276.808184)
		(width 0.09525)
		(layer "In6.Cu")
		(net "M_K_CPU0_SB_DQS_DN<5>")
	)
	(segment
		(start 418.27323 -285.840678)
		(end 419.440614 -287.008062)
		(width 0.16002)
		(layer "In6.Cu")
		(net "M_K_CPU0_SB_DQS_DN<5>")
	)
	(segment
		(start 438.423558 -285.840678)
		(end 438.740804 -286.157924)
		(width 0.16002)
		(layer "In6.Cu")
		(net "M_K_CPU0_SB_DQS_DN<5>")
	)
	(segment
		(start 413.944816 -286.628078)
		(end 414.732216 -285.840678)
		(width 0.16002)
		(layer "In6.Cu")
		(net "M_K_CPU0_SB_DQS_DN<5>")
	)
	(segment
		(start 415.890964 -285.195264)
		(end 416.489642 -285.195264)
		(width 0.16002)
		(layer "In6.Cu")
		(net "M_K_CPU0_SB_DQS_DN<5>")
	)
	(segment
		(start 440.07151 -286.008826)
		(end 442.270388 -286.008826)
		(width 0.16002)
		(layer "In6.Cu")
		(net "M_K_CPU0_SB_DQS_DN<5>")
	)
	(segment
		(start 431.19675 -286.157924)
		(end 433.678584 -286.157924)
		(width 0.16002)
		(layer "In6.Cu")
		(net "M_K_CPU0_SB_DQS_DN<5>")
	)
	(segment
		(start 411.849824 -286.628078)
		(end 413.944816 -286.628078)
		(width 0.16002)
		(layer "In6.Cu")
		(net "M_K_CPU0_SB_DQS_DN<5>")
	)
	(segment
		(start 426.984668 -287.008062)
		(end 428.04842 -287.008062)
		(width 0.16002)
		(layer "In6.Cu")
		(net "M_K_CPU0_SB_DQS_DN<5>")
	)
	(segment
		(start 417.494974 -286.177736)
		(end 417.832032 -285.840678)
		(width 0.16002)
		(layer "In6.Cu")
		(net "M_K_CPU0_SB_DQS_DN<5>")
	)
	(segment
		(start 435.592474 -287.008062)
		(end 435.972458 -286.628078)
		(width 0.16002)
		(layer "In6.Cu")
		(net "M_K_CPU0_SB_DQS_DN<5>")
	)
	(segment
		(start 428.428404 -286.628078)
		(end 429.032924 -286.628078)
		(width 0.16002)
		(layer "In6.Cu")
		(net "M_K_CPU0_SB_DQS_DN<5>")
	)
	(segment
		(start 434.528722 -287.008062)
		(end 435.592474 -287.008062)
		(width 0.16002)
		(layer "In6.Cu")
		(net "M_K_CPU0_SB_DQS_DN<5>")
	)
	(segment
		(start 414.732216 -285.840678)
		(end 415.393886 -285.840678)
		(width 0.16002)
		(layer "In6.Cu")
		(net "M_K_CPU0_SB_DQS_DN<5>")
	)
	(segment
		(start 394.614654 -275.707348)
		(end 394.798296 -275.631402)
		(width 0.09525)
		(layer "In6.Cu")
		(net "M_K_CPU0_SB_DQS_DN<5>")
	)
	(segment
		(start 416.8267 -286.326072)
		(end 416.98672 -286.486092)
		(width 0.16002)
		(layer "In6.Cu")
		(net "M_K_CPU0_SB_DQS_DN<5>")
	)
	(segment
		(start 433.678584 -286.157924)
		(end 434.528722 -287.008062)
		(width 0.16002)
		(layer "In6.Cu")
		(net "M_K_CPU0_SB_DQS_DN<5>")
	)
	(segment
		(start 416.489642 -285.195264)
		(end 416.8267 -285.532322)
		(width 0.16002)
		(layer "In6.Cu")
		(net "M_K_CPU0_SB_DQS_DN<5>")
	)
	(segment
		(start 393.180316 -276.782276)
		(end 393.22121 -276.741382)
		(width 0.09525)
		(layer "In6.Cu")
		(net "M_K_CPU0_SB_DQS_DN<5>")
	)
	(segment
		(start 437.364378 -285.840678)
		(end 438.423558 -285.840678)
		(width 0.16002)
		(layer "In6.Cu")
		(net "M_K_CPU0_SB_DQS_DN<5>")
	)
	(segment
		(start 435.972458 -286.628078)
		(end 436.576978 -286.628078)
		(width 0.16002)
		(layer "In6.Cu")
		(net "M_K_CPU0_SB_DQS_DN<5>")
	)
	(segment
		(start 392.725656 -276.841204)
		(end 392.737594 -276.848062)
		(width 0.09525)
		(layer "In6.Cu")
		(net "M_K_CPU0_SB_DQS_DN<5>")
	)
	(segment
		(start 389.906256 -276.841204)
		(end 389.914638 -276.84603)
		(width 0.09525)
		(layer "In6.Cu")
		(net "M_K_CPU0_SB_DQS_DN<5>")
	)
	(segment
		(start 401.037552 -275.815806)
		(end 411.849824 -286.628078)
		(width 0.16002)
		(layer "In6.Cu")
		(net "M_K_CPU0_SB_DQS_DN<5>")
	)
	(segment
		(start 438.740804 -286.157924)
		(end 439.922412 -286.157924)
		(width 0.16002)
		(layer "In6.Cu")
		(net "M_K_CPU0_SB_DQS_DN<5>")
	)
	(segment
		(start 429.032924 -286.628078)
		(end 429.820324 -285.840678)
		(width 0.16002)
		(layer "In6.Cu")
		(net "M_K_CPU0_SB_DQS_DN<5>")
	)
	(segment
		(start 416.98672 -286.486092)
		(end 417.334954 -286.486092)
		(width 0.16002)
		(layer "In6.Cu")
		(net "M_K_CPU0_SB_DQS_DN<5>")
	)
	(arc
		(start 390.283446 -276.841204)
		(mid 390.564878 -276.765449)
		(end 390.84631 -276.841204)
		(width 0.09525)
		(layer "In6.Cu")
		(net "M_K_CPU0_SB_DQS_DN<5>")
	)
	(arc
		(start 392.17346 -276.835108)
		(mid 392.450368 -276.765431)
		(end 392.725656 -276.841204)
		(width 0.09525)
		(layer "In6.Cu")
		(net "M_K_CPU0_SB_DQS_DN<5>")
	)
	(arc
		(start 393.627356 -276.56409)
		(mid 393.730847 -276.545101)
		(end 393.824714 -276.497542)
		(width 0.09525)
		(layer "In6.Cu")
		(net "M_K_CPU0_SB_DQS_DN<5>")
	)
	(arc
		(start 391.78611 -276.841204)
		(mid 391.967726 -276.891941)
		(end 392.151108 -276.848062)
		(width 0.09525)
		(layer "In6.Cu")
		(net "M_K_CPU0_SB_DQS_DN<5>")
	)
	(arc
		(start 393.22121 -276.741382)
		(mid 393.407519 -276.614339)
		(end 393.627356 -276.56409)
		(width 0.09525)
		(layer "In6.Cu")
		(net "M_K_CPU0_SB_DQS_DN<5>")
	)
	(arc
		(start 391.223246 -276.841204)
		(mid 391.504678 -276.765449)
		(end 391.78611 -276.841204)
		(width 0.09525)
		(layer "In6.Cu")
		(net "M_K_CPU0_SB_DQS_DN<5>")
	)
	(arc
		(start 393.1031 -276.841204)
		(mid 393.143624 -276.814249)
		(end 393.180316 -276.782276)
		(width 0.09525)
		(layer "In6.Cu")
		(net "M_K_CPU0_SB_DQS_DN<5>")
	)
	(arc
		(start 392.737594 -276.848062)
		(mid 392.921229 -276.892012)
		(end 393.1031 -276.841204)
		(width 0.09525)
		(layer "In6.Cu")
		(net "M_K_CPU0_SB_DQS_DN<5>")
	)
	(arc
		(start 390.84631 -276.841204)
		(mid 391.034778 -276.891881)
		(end 391.223246 -276.841204)
		(width 0.09525)
		(layer "In6.Cu")
		(net "M_K_CPU0_SB_DQS_DN<5>")
	)
	(arc
		(start 389.409686 -276.808184)
		(mid 389.661827 -276.766614)
		(end 389.906256 -276.841204)
		(width 0.09525)
		(layer "In6.Cu")
		(net "M_K_CPU0_SB_DQS_DN<5>")
	)
	(arc
		(start 389.914638 -276.84603)
		(mid 390.09967 -276.891944)
		(end 390.283446 -276.841204)
		(width 0.09525)
		(layer "In6.Cu")
		(net "M_K_CPU0_SB_DQS_DN<5>")
	)
	(segment
		(start 388.688072 -271.39011)
		(end 389.154924 -271.656048)
		(width 0.12954)
		(layer "F.Cu")
		(net "M_K_CPU0_SB_DQS_DN<4>")
	)
	(segment
		(start 442.270388 -276.658832)
		(end 442.5442 -276.38502)
		(width 0.16002)
		(layer "In6.Cu")
		(net "M_K_CPU0_SB_DQS_DN<4>")
	)
	(segment
		(start 407.792428 -272.812256)
		(end 407.872946 -272.731992)
		(width 0.16002)
		(layer "In6.Cu")
		(net "M_K_CPU0_SB_DQS_DN<4>")
	)
	(segment
		(start 407.872946 -272.731992)
		(end 408.34945 -272.731992)
		(width 0.16002)
		(layer "In6.Cu")
		(net "M_K_CPU0_SB_DQS_DN<4>")
	)
	(segment
		(start 411.521148 -275.90369)
		(end 411.521148 -276.37994)
		(width 0.16002)
		(layer "In6.Cu")
		(net "M_K_CPU0_SB_DQS_DN<4>")
	)
	(segment
		(start 408.34945 -272.731992)
		(end 408.773884 -273.156426)
		(width 0.16002)
		(layer "In6.Cu")
		(net "M_K_CPU0_SB_DQS_DN<4>")
	)
	(segment
		(start 407.400252 -272.259044)
		(end 407.319734 -272.339562)
		(width 0.16002)
		(layer "In6.Cu")
		(net "M_K_CPU0_SB_DQS_DN<4>")
	)
	(segment
		(start 412.032196 -277.278084)
		(end 413.944816 -277.278084)
		(width 0.16002)
		(layer "In6.Cu")
		(net "M_K_CPU0_SB_DQS_DN<4>")
	)
	(segment
		(start 409.246578 -274.105624)
		(end 409.723082 -274.105624)
		(width 0.16002)
		(layer "In6.Cu")
		(net "M_K_CPU0_SB_DQS_DN<4>")
	)
	(segment
		(start 395.77645 -270.203422)
		(end 395.835632 -270.14424)
		(width 0.09525)
		(layer "In6.Cu")
		(net "M_K_CPU0_SB_DQS_DN<4>")
	)
	(segment
		(start 408.693366 -273.713194)
		(end 408.693366 -273.939254)
		(width 0.16002)
		(layer "In6.Cu")
		(net "M_K_CPU0_SB_DQS_DN<4>")
	)
	(segment
		(start 428.428404 -277.278084)
		(end 429.032924 -277.278084)
		(width 0.16002)
		(layer "In6.Cu")
		(net "M_K_CPU0_SB_DQS_DN<4>")
	)
	(segment
		(start 393.18057 -271.921478)
		(end 393.344146 -271.758156)
		(width 0.09525)
		(layer "In6.Cu")
		(net "M_K_CPU0_SB_DQS_DN<4>")
	)
	(segment
		(start 428.04842 -277.658068)
		(end 428.428404 -277.278084)
		(width 0.16002)
		(layer "In6.Cu")
		(net "M_K_CPU0_SB_DQS_DN<4>")
	)
	(segment
		(start 407.319734 -272.565622)
		(end 407.566368 -272.812256)
		(width 0.16002)
		(layer "In6.Cu")
		(net "M_K_CPU0_SB_DQS_DN<4>")
	)
	(segment
		(start 410.539692 -275.55952)
		(end 410.62021 -275.479256)
		(width 0.16002)
		(layer "In6.Cu")
		(net "M_K_CPU0_SB_DQS_DN<4>")
	)
	(segment
		(start 410.147516 -274.530058)
		(end 410.147516 -275.006308)
		(width 0.16002)
		(layer "In6.Cu")
		(net "M_K_CPU0_SB_DQS_DN<4>")
	)
	(segment
		(start 429.820324 -276.490684)
		(end 430.879504 -276.490684)
		(width 0.16002)
		(layer "In6.Cu")
		(net "M_K_CPU0_SB_DQS_DN<4>")
	)
	(segment
		(start 408.94 -274.185888)
		(end 409.16606 -274.185888)
		(width 0.16002)
		(layer "In6.Cu")
		(net "M_K_CPU0_SB_DQS_DN<4>")
	)
	(segment
		(start 426.984668 -277.658068)
		(end 428.04842 -277.658068)
		(width 0.16002)
		(layer "In6.Cu")
		(net "M_K_CPU0_SB_DQS_DN<4>")
	)
	(segment
		(start 414.732216 -276.490684)
		(end 415.791396 -276.490684)
		(width 0.16002)
		(layer "In6.Cu")
		(net "M_K_CPU0_SB_DQS_DN<4>")
	)
	(segment
		(start 413.944816 -277.278084)
		(end 414.732216 -276.490684)
		(width 0.16002)
		(layer "In6.Cu")
		(net "M_K_CPU0_SB_DQS_DN<4>")
	)
	(segment
		(start 426.13453 -276.80793)
		(end 426.984668 -277.658068)
		(width 0.16002)
		(layer "In6.Cu")
		(net "M_K_CPU0_SB_DQS_DN<4>")
	)
	(segment
		(start 423.652696 -276.80793)
		(end 426.13453 -276.80793)
		(width 0.16002)
		(layer "In6.Cu")
		(net "M_K_CPU0_SB_DQS_DN<4>")
	)
	(segment
		(start 408.773884 -273.156426)
		(end 408.773884 -273.632676)
		(width 0.16002)
		(layer "In6.Cu")
		(net "M_K_CPU0_SB_DQS_DN<4>")
	)
	(segment
		(start 418.590476 -276.80793)
		(end 419.440614 -277.658068)
		(width 0.16002)
		(layer "In6.Cu")
		(net "M_K_CPU0_SB_DQS_DN<4>")
	)
	(segment
		(start 420.88435 -277.278084)
		(end 421.48887 -277.278084)
		(width 0.16002)
		(layer "In6.Cu")
		(net "M_K_CPU0_SB_DQS_DN<4>")
	)
	(segment
		(start 421.48887 -277.278084)
		(end 422.27627 -276.490684)
		(width 0.16002)
		(layer "In6.Cu")
		(net "M_K_CPU0_SB_DQS_DN<4>")
	)
	(segment
		(start 422.27627 -276.490684)
		(end 423.33545 -276.490684)
		(width 0.16002)
		(layer "In6.Cu")
		(net "M_K_CPU0_SB_DQS_DN<4>")
	)
	(segment
		(start 431.19675 -276.80793)
		(end 433.678584 -276.80793)
		(width 0.16002)
		(layer "In6.Cu")
		(net "M_K_CPU0_SB_DQS_DN<4>")
	)
	(segment
		(start 438.423558 -276.490684)
		(end 438.740804 -276.80793)
		(width 0.16002)
		(layer "In6.Cu")
		(net "M_K_CPU0_SB_DQS_DN<4>")
	)
	(segment
		(start 389.308848 -271.921478)
		(end 389.409686 -271.948148)
		(width 0.09525)
		(layer "In6.Cu")
		(net "M_K_CPU0_SB_DQS_DN<4>")
	)
	(segment
		(start 419.440614 -277.658068)
		(end 420.504366 -277.658068)
		(width 0.16002)
		(layer "In6.Cu")
		(net "M_K_CPU0_SB_DQS_DN<4>")
	)
	(segment
		(start 410.313632 -275.55952)
		(end 410.539692 -275.55952)
		(width 0.16002)
		(layer "In6.Cu")
		(net "M_K_CPU0_SB_DQS_DN<4>")
	)
	(segment
		(start 392.154918 -271.985994)
		(end 392.1633 -271.981168)
		(width 0.09525)
		(layer "In6.Cu")
		(net "M_K_CPU0_SB_DQS_DN<4>")
	)
	(segment
		(start 435.972458 -277.278084)
		(end 436.576978 -277.278084)
		(width 0.16002)
		(layer "In6.Cu")
		(net "M_K_CPU0_SB_DQS_DN<4>")
	)
	(segment
		(start 411.521148 -276.37994)
		(end 411.44063 -276.460458)
		(width 0.16002)
		(layer "In6.Cu")
		(net "M_K_CPU0_SB_DQS_DN<4>")
	)
	(segment
		(start 440.07151 -276.658832)
		(end 442.270388 -276.658832)
		(width 0.16002)
		(layer "In6.Cu")
		(net "M_K_CPU0_SB_DQS_DN<4>")
	)
	(segment
		(start 439.922412 -276.80793)
		(end 440.07151 -276.658832)
		(width 0.16002)
		(layer "In6.Cu")
		(net "M_K_CPU0_SB_DQS_DN<4>")
	)
	(segment
		(start 406.418796 -271.438624)
		(end 406.499314 -271.35836)
		(width 0.16002)
		(layer "In6.Cu")
		(net "M_K_CPU0_SB_DQS_DN<4>")
	)
	(segment
		(start 404.898352 -270.14424)
		(end 406.192736 -271.438624)
		(width 0.16002)
		(layer "In6.Cu")
		(net "M_K_CPU0_SB_DQS_DN<4>")
	)
	(segment
		(start 389.906256 -271.981168)
		(end 389.914638 -271.985994)
		(width 0.09525)
		(layer "In6.Cu")
		(net "M_K_CPU0_SB_DQS_DN<4>")
	)
	(segment
		(start 411.096714 -275.479256)
		(end 411.521148 -275.90369)
		(width 0.16002)
		(layer "In6.Cu")
		(net "M_K_CPU0_SB_DQS_DN<4>")
	)
	(segment
		(start 393.598146 -271.145)
		(end 394.539724 -270.203422)
		(width 0.09525)
		(layer "In6.Cu")
		(net "M_K_CPU0_SB_DQS_DN<4>")
	)
	(segment
		(start 436.576978 -277.278084)
		(end 437.364378 -276.490684)
		(width 0.16002)
		(layer "In6.Cu")
		(net "M_K_CPU0_SB_DQS_DN<4>")
	)
	(segment
		(start 430.879504 -276.490684)
		(end 431.19675 -276.80793)
		(width 0.16002)
		(layer "In6.Cu")
		(net "M_K_CPU0_SB_DQS_DN<4>")
	)
	(segment
		(start 408.693366 -273.939254)
		(end 408.94 -274.185888)
		(width 0.16002)
		(layer "In6.Cu")
		(net "M_K_CPU0_SB_DQS_DN<4>")
	)
	(segment
		(start 416.108642 -276.80793)
		(end 418.590476 -276.80793)
		(width 0.16002)
		(layer "In6.Cu")
		(net "M_K_CPU0_SB_DQS_DN<4>")
	)
	(segment
		(start 389.154924 -271.656048)
		(end 389.308848 -271.921478)
		(width 0.09525)
		(layer "In6.Cu")
		(net "M_K_CPU0_SB_DQS_DN<4>")
	)
	(segment
		(start 435.592474 -277.658068)
		(end 435.972458 -277.278084)
		(width 0.16002)
		(layer "In6.Cu")
		(net "M_K_CPU0_SB_DQS_DN<4>")
	)
	(segment
		(start 406.192736 -271.438624)
		(end 406.418796 -271.438624)
		(width 0.16002)
		(layer "In6.Cu")
		(net "M_K_CPU0_SB_DQS_DN<4>")
	)
	(segment
		(start 420.504366 -277.658068)
		(end 420.88435 -277.278084)
		(width 0.16002)
		(layer "In6.Cu")
		(net "M_K_CPU0_SB_DQS_DN<4>")
	)
	(segment
		(start 407.400252 -271.782794)
		(end 407.400252 -272.259044)
		(width 0.16002)
		(layer "In6.Cu")
		(net "M_K_CPU0_SB_DQS_DN<4>")
	)
	(segment
		(start 437.364378 -276.490684)
		(end 438.423558 -276.490684)
		(width 0.16002)
		(layer "In6.Cu")
		(net "M_K_CPU0_SB_DQS_DN<4>")
	)
	(segment
		(start 407.319734 -272.339562)
		(end 407.319734 -272.565622)
		(width 0.16002)
		(layer "In6.Cu")
		(net "M_K_CPU0_SB_DQS_DN<4>")
	)
	(segment
		(start 433.678584 -276.80793)
		(end 434.528722 -277.658068)
		(width 0.16002)
		(layer "In6.Cu")
		(net "M_K_CPU0_SB_DQS_DN<4>")
	)
	(segment
		(start 408.773884 -273.632676)
		(end 408.693366 -273.713194)
		(width 0.16002)
		(layer "In6.Cu")
		(net "M_K_CPU0_SB_DQS_DN<4>")
	)
	(segment
		(start 438.740804 -276.80793)
		(end 439.922412 -276.80793)
		(width 0.16002)
		(layer "In6.Cu")
		(net "M_K_CPU0_SB_DQS_DN<4>")
	)
	(segment
		(start 406.499314 -271.35836)
		(end 406.975818 -271.35836)
		(width 0.16002)
		(layer "In6.Cu")
		(net "M_K_CPU0_SB_DQS_DN<4>")
	)
	(segment
		(start 423.33545 -276.490684)
		(end 423.652696 -276.80793)
		(width 0.16002)
		(layer "In6.Cu")
		(net "M_K_CPU0_SB_DQS_DN<4>")
	)
	(segment
		(start 410.62021 -275.479256)
		(end 411.096714 -275.479256)
		(width 0.16002)
		(layer "In6.Cu")
		(net "M_K_CPU0_SB_DQS_DN<4>")
	)
	(segment
		(start 410.147516 -275.006308)
		(end 410.066998 -275.086826)
		(width 0.16002)
		(layer "In6.Cu")
		(net "M_K_CPU0_SB_DQS_DN<4>")
	)
	(segment
		(start 409.16606 -274.185888)
		(end 409.246578 -274.105624)
		(width 0.16002)
		(layer "In6.Cu")
		(net "M_K_CPU0_SB_DQS_DN<4>")
	)
	(segment
		(start 406.975818 -271.35836)
		(end 407.400252 -271.782794)
		(width 0.16002)
		(layer "In6.Cu")
		(net "M_K_CPU0_SB_DQS_DN<4>")
	)
	(segment
		(start 434.528722 -277.658068)
		(end 435.592474 -277.658068)
		(width 0.16002)
		(layer "In6.Cu")
		(net "M_K_CPU0_SB_DQS_DN<4>")
	)
	(segment
		(start 394.539724 -270.203422)
		(end 395.77645 -270.203422)
		(width 0.09525)
		(layer "In6.Cu")
		(net "M_K_CPU0_SB_DQS_DN<4>")
	)
	(segment
		(start 392.1633 -271.981168)
		(end 392.182604 -271.969992)
		(width 0.09525)
		(layer "In6.Cu")
		(net "M_K_CPU0_SB_DQS_DN<4>")
	)
	(segment
		(start 411.44063 -276.686518)
		(end 412.032196 -277.278084)
		(width 0.16002)
		(layer "In6.Cu")
		(net "M_K_CPU0_SB_DQS_DN<4>")
	)
	(segment
		(start 395.835632 -270.14424)
		(end 395.859254 -270.14424)
		(width 0.09525)
		(layer "In6.Cu")
		(net "M_K_CPU0_SB_DQS_DN<4>")
	)
	(segment
		(start 410.066998 -275.086826)
		(end 410.066998 -275.312886)
		(width 0.16002)
		(layer "In6.Cu")
		(net "M_K_CPU0_SB_DQS_DN<4>")
	)
	(segment
		(start 395.859254 -270.14424)
		(end 404.898352 -270.14424)
		(width 0.16002)
		(layer "In6.Cu")
		(net "M_K_CPU0_SB_DQS_DN<4>")
	)
	(segment
		(start 393.180824 -271.921478)
		(end 393.18057 -271.921478)
		(width 0.09525)
		(layer "In6.Cu")
		(net "M_K_CPU0_SB_DQS_DN<4>")
	)
	(segment
		(start 429.032924 -277.278084)
		(end 429.820324 -276.490684)
		(width 0.16002)
		(layer "In6.Cu")
		(net "M_K_CPU0_SB_DQS_DN<4>")
	)
	(segment
		(start 411.44063 -276.460458)
		(end 411.44063 -276.686518)
		(width 0.16002)
		(layer "In6.Cu")
		(net "M_K_CPU0_SB_DQS_DN<4>")
	)
	(segment
		(start 407.566368 -272.812256)
		(end 407.792428 -272.812256)
		(width 0.16002)
		(layer "In6.Cu")
		(net "M_K_CPU0_SB_DQS_DN<4>")
	)
	(segment
		(start 415.791396 -276.490684)
		(end 416.108642 -276.80793)
		(width 0.16002)
		(layer "In6.Cu")
		(net "M_K_CPU0_SB_DQS_DN<4>")
	)
	(segment
		(start 409.723082 -274.105624)
		(end 410.147516 -274.530058)
		(width 0.16002)
		(layer "In6.Cu")
		(net "M_K_CPU0_SB_DQS_DN<4>")
	)
	(segment
		(start 410.066998 -275.312886)
		(end 410.313632 -275.55952)
		(width 0.16002)
		(layer "In6.Cu")
		(net "M_K_CPU0_SB_DQS_DN<4>")
	)
	(arc
		(start 391.223246 -271.981168)
		(mid 391.504678 -271.905413)
		(end 391.78611 -271.981168)
		(width 0.09525)
		(layer "In6.Cu")
		(net "M_K_CPU0_SB_DQS_DN<4>")
	)
	(arc
		(start 392.182604 -271.969992)
		(mid 392.455506 -271.905221)
		(end 392.725656 -271.98066)
		(width 0.09525)
		(layer "In6.Cu")
		(net "M_K_CPU0_SB_DQS_DN<4>")
	)
	(arc
		(start 389.429498 -271.940274)
		(mid 389.672462 -271.907287)
		(end 389.906256 -271.981168)
		(width 0.09525)
		(layer "In6.Cu")
		(net "M_K_CPU0_SB_DQS_DN<4>")
	)
	(arc
		(start 390.84631 -271.981168)
		(mid 391.034778 -272.031845)
		(end 391.223246 -271.981168)
		(width 0.09525)
		(layer "In6.Cu")
		(net "M_K_CPU0_SB_DQS_DN<4>")
	)
	(arc
		(start 389.914638 -271.985994)
		(mid 390.09967 -272.031908)
		(end 390.283446 -271.981168)
		(width 0.09525)
		(layer "In6.Cu")
		(net "M_K_CPU0_SB_DQS_DN<4>")
	)
	(arc
		(start 393.1031 -271.98066)
		(mid 393.14388 -271.95359)
		(end 393.180824 -271.921478)
		(width 0.09525)
		(layer "In6.Cu")
		(net "M_K_CPU0_SB_DQS_DN<4>")
	)
	(arc
		(start 389.409686 -271.948148)
		(mid 389.419554 -271.944117)
		(end 389.429498 -271.940274)
		(width 0.09525)
		(layer "In6.Cu")
		(net "M_K_CPU0_SB_DQS_DN<4>")
	)
	(arc
		(start 392.725656 -271.98066)
		(mid 392.914378 -272.031396)
		(end 393.1031 -271.98066)
		(width 0.09525)
		(layer "In6.Cu")
		(net "M_K_CPU0_SB_DQS_DN<4>")
	)
	(arc
		(start 393.448794 -271.505172)
		(mid 393.487677 -271.310254)
		(end 393.598146 -271.145)
		(width 0.09525)
		(layer "In6.Cu")
		(net "M_K_CPU0_SB_DQS_DN<4>")
	)
	(arc
		(start 393.344146 -271.758156)
		(mid 393.421619 -271.642071)
		(end 393.448794 -271.505172)
		(width 0.09525)
		(layer "In6.Cu")
		(net "M_K_CPU0_SB_DQS_DN<4>")
	)
	(arc
		(start 391.78611 -271.981168)
		(mid 391.969885 -272.03194)
		(end 392.154918 -271.985994)
		(width 0.09525)
		(layer "In6.Cu")
		(net "M_K_CPU0_SB_DQS_DN<4>")
	)
	(arc
		(start 390.283446 -271.981168)
		(mid 390.564878 -271.905413)
		(end 390.84631 -271.981168)
		(width 0.09525)
		(layer "In6.Cu")
		(net "M_K_CPU0_SB_DQS_DN<4>")
	)
	(segment
		(start 390.567926 -290.83)
		(end 391.034778 -291.095938)
		(width 0.12954)
		(layer "F.Cu")
		(net "M_K_CPU0_SB_DQS_DN<3>")
	)
	(segment
		(start 432.498246 -312.512202)
		(end 430.785524 -312.512202)
		(width 0.16002)
		(layer "In6.Cu")
		(net "M_K_CPU0_SB_DQS_DN<3>")
	)
	(segment
		(start 414.118298 -313.7027)
		(end 410.603446 -313.7027)
		(width 0.16002)
		(layer "In6.Cu")
		(net "M_K_CPU0_SB_DQS_DN<3>")
	)
	(segment
		(start 443.646052 -313.71032)
		(end 443.021974 -313.086242)
		(width 0.16002)
		(layer "In6.Cu")
		(net "M_K_CPU0_SB_DQS_DN<3>")
	)
	(segment
		(start 421.010588 -313.7027)
		(end 420.669974 -313.362086)
		(width 0.16002)
		(layer "In6.Cu")
		(net "M_K_CPU0_SB_DQS_DN<3>")
	)
	(segment
		(start 437.98998 -312.8518)
		(end 437.60136 -312.8518)
		(width 0.16002)
		(layer "In6.Cu")
		(net "M_K_CPU0_SB_DQS_DN<3>")
	)
	(segment
		(start 428.554642 -313.7027)
		(end 428.214028 -313.362086)
		(width 0.16002)
		(layer "In6.Cu")
		(net "M_K_CPU0_SB_DQS_DN<3>")
	)
	(segment
		(start 430.785524 -312.512202)
		(end 430.445926 -312.8518)
		(width 0.16002)
		(layer "In6.Cu")
		(net "M_K_CPU0_SB_DQS_DN<3>")
	)
	(segment
		(start 392.1633 -290.770818)
		(end 392.154918 -290.765992)
		(width 0.09525)
		(layer "In6.Cu")
		(net "M_K_CPU0_SB_DQS_DN<3>")
	)
	(segment
		(start 417.410138 -312.512202)
		(end 415.697416 -312.512202)
		(width 0.16002)
		(layer "In6.Cu")
		(net "M_K_CPU0_SB_DQS_DN<3>")
	)
	(segment
		(start 437.60136 -312.8518)
		(end 436.75046 -313.7027)
		(width 0.16002)
		(layer "In6.Cu")
		(net "M_K_CPU0_SB_DQS_DN<3>")
	)
	(segment
		(start 394.151104 -292.97757)
		(end 394.151104 -292.105842)
		(width 0.09525)
		(layer "In6.Cu")
		(net "M_K_CPU0_SB_DQS_DN<3>")
	)
	(segment
		(start 446.644268 -313.784996)
		(end 446.370456 -313.511184)
		(width 0.16002)
		(layer "In6.Cu")
		(net "M_K_CPU0_SB_DQS_DN<3>")
	)
	(segment
		(start 433.34813 -313.362086)
		(end 432.498246 -312.512202)
		(width 0.16002)
		(layer "In6.Cu")
		(net "M_K_CPU0_SB_DQS_DN<3>")
	)
	(segment
		(start 396.422118 -295.329864)
		(end 394.847064 -293.755572)
		(width 0.16002)
		(layer "In6.Cu")
		(net "M_K_CPU0_SB_DQS_DN<3>")
	)
	(segment
		(start 435.758082 -313.362086)
		(end 433.34813 -313.362086)
		(width 0.16002)
		(layer "In6.Cu")
		(net "M_K_CPU0_SB_DQS_DN<3>")
	)
	(segment
		(start 396.422118 -299.521372)
		(end 396.422118 -295.329864)
		(width 0.16002)
		(layer "In6.Cu")
		(net "M_K_CPU0_SB_DQS_DN<3>")
	)
	(segment
		(start 423.24147 -312.512202)
		(end 422.901872 -312.8518)
		(width 0.16002)
		(layer "In6.Cu")
		(net "M_K_CPU0_SB_DQS_DN<3>")
	)
	(segment
		(start 444.475108 -313.511184)
		(end 444.275972 -313.71032)
		(width 0.16002)
		(layer "In6.Cu")
		(net "M_K_CPU0_SB_DQS_DN<3>")
	)
	(segment
		(start 392.734292 -290.765992)
		(end 392.72591 -290.770818)
		(width 0.09525)
		(layer "In6.Cu")
		(net "M_K_CPU0_SB_DQS_DN<3>")
	)
	(segment
		(start 392.72591 -290.770818)
		(end 392.715496 -290.776914)
		(width 0.09525)
		(layer "In6.Cu")
		(net "M_K_CPU0_SB_DQS_DN<3>")
	)
	(segment
		(start 394.830046 -293.655496)
		(end 394.829792 -293.654988)
		(width 0.09525)
		(layer "In6.Cu")
		(net "M_K_CPU0_SB_DQS_DN<3>")
	)
	(segment
		(start 394.829792 -293.654988)
		(end 394.151104 -292.97757)
		(width 0.09525)
		(layer "In6.Cu")
		(net "M_K_CPU0_SB_DQS_DN<3>")
	)
	(segment
		(start 420.669974 -313.362086)
		(end 418.260022 -313.362086)
		(width 0.16002)
		(layer "In6.Cu")
		(net "M_K_CPU0_SB_DQS_DN<3>")
	)
	(segment
		(start 438.329578 -312.512202)
		(end 437.98998 -312.8518)
		(width 0.16002)
		(layer "In6.Cu")
		(net "M_K_CPU0_SB_DQS_DN<3>")
	)
	(segment
		(start 445.62268 -313.613292)
		(end 445.092836 -313.613292)
		(width 0.16002)
		(layer "In6.Cu")
		(net "M_K_CPU0_SB_DQS_DN<3>")
	)
	(segment
		(start 444.990728 -313.511184)
		(end 444.475108 -313.511184)
		(width 0.16002)
		(layer "In6.Cu")
		(net "M_K_CPU0_SB_DQS_DN<3>")
	)
	(segment
		(start 422.901872 -312.8518)
		(end 422.513252 -312.8518)
		(width 0.16002)
		(layer "In6.Cu")
		(net "M_K_CPU0_SB_DQS_DN<3>")
	)
	(segment
		(start 446.370456 -313.511184)
		(end 445.724788 -313.511184)
		(width 0.16002)
		(layer "In6.Cu")
		(net "M_K_CPU0_SB_DQS_DN<3>")
	)
	(segment
		(start 440.811158 -313.086242)
		(end 440.237118 -312.512202)
		(width 0.16002)
		(layer "In6.Cu")
		(net "M_K_CPU0_SB_DQS_DN<3>")
	)
	(segment
		(start 445.724788 -313.511184)
		(end 445.62268 -313.613292)
		(width 0.16002)
		(layer "In6.Cu")
		(net "M_K_CPU0_SB_DQS_DN<3>")
	)
	(segment
		(start 415.697416 -312.512202)
		(end 415.357818 -312.8518)
		(width 0.16002)
		(layer "In6.Cu")
		(net "M_K_CPU0_SB_DQS_DN<3>")
	)
	(segment
		(start 394.847064 -293.755572)
		(end 394.8303 -293.738808)
		(width 0.09525)
		(layer "In6.Cu")
		(net "M_K_CPU0_SB_DQS_DN<3>")
	)
	(segment
		(start 393.297664 -290.94684)
		(end 393.18057 -290.829746)
		(width 0.09525)
		(layer "In6.Cu")
		(net "M_K_CPU0_SB_DQS_DN<3>")
	)
	(segment
		(start 430.445926 -312.8518)
		(end 430.057306 -312.8518)
		(width 0.16002)
		(layer "In6.Cu")
		(net "M_K_CPU0_SB_DQS_DN<3>")
	)
	(segment
		(start 444.275972 -313.71032)
		(end 443.646052 -313.71032)
		(width 0.16002)
		(layer "In6.Cu")
		(net "M_K_CPU0_SB_DQS_DN<3>")
	)
	(segment
		(start 425.804076 -313.362086)
		(end 424.954192 -312.512202)
		(width 0.16002)
		(layer "In6.Cu")
		(net "M_K_CPU0_SB_DQS_DN<3>")
	)
	(segment
		(start 414.969198 -312.8518)
		(end 414.118298 -313.7027)
		(width 0.16002)
		(layer "In6.Cu")
		(net "M_K_CPU0_SB_DQS_DN<3>")
	)
	(segment
		(start 390.880854 -290.830508)
		(end 391.034778 -291.095938)
		(width 0.09525)
		(layer "In6.Cu")
		(net "M_K_CPU0_SB_DQS_DN<3>")
	)
	(segment
		(start 394.8303 -293.738808)
		(end 394.830046 -293.655496)
		(width 0.09525)
		(layer "In6.Cu")
		(net "M_K_CPU0_SB_DQS_DN<3>")
	)
	(segment
		(start 440.237118 -312.512202)
		(end 438.329578 -312.512202)
		(width 0.16002)
		(layer "In6.Cu")
		(net "M_K_CPU0_SB_DQS_DN<3>")
	)
	(segment
		(start 430.057306 -312.8518)
		(end 429.206406 -313.7027)
		(width 0.16002)
		(layer "In6.Cu")
		(net "M_K_CPU0_SB_DQS_DN<3>")
	)
	(segment
		(start 390.903968 -290.743894)
		(end 390.880854 -290.830508)
		(width 0.09525)
		(layer "In6.Cu")
		(net "M_K_CPU0_SB_DQS_DN<3>")
	)
	(segment
		(start 436.75046 -313.7027)
		(end 436.098696 -313.7027)
		(width 0.16002)
		(layer "In6.Cu")
		(net "M_K_CPU0_SB_DQS_DN<3>")
	)
	(segment
		(start 421.662352 -313.7027)
		(end 421.010588 -313.7027)
		(width 0.16002)
		(layer "In6.Cu")
		(net "M_K_CPU0_SB_DQS_DN<3>")
	)
	(segment
		(start 428.214028 -313.362086)
		(end 425.804076 -313.362086)
		(width 0.16002)
		(layer "In6.Cu")
		(net "M_K_CPU0_SB_DQS_DN<3>")
	)
	(segment
		(start 422.513252 -312.8518)
		(end 421.662352 -313.7027)
		(width 0.16002)
		(layer "In6.Cu")
		(net "M_K_CPU0_SB_DQS_DN<3>")
	)
	(segment
		(start 429.206406 -313.7027)
		(end 428.554642 -313.7027)
		(width 0.16002)
		(layer "In6.Cu")
		(net "M_K_CPU0_SB_DQS_DN<3>")
	)
	(segment
		(start 436.098696 -313.7027)
		(end 435.758082 -313.362086)
		(width 0.16002)
		(layer "In6.Cu")
		(net "M_K_CPU0_SB_DQS_DN<3>")
	)
	(segment
		(start 443.021974 -313.086242)
		(end 440.811158 -313.086242)
		(width 0.16002)
		(layer "In6.Cu")
		(net "M_K_CPU0_SB_DQS_DN<3>")
	)
	(segment
		(start 424.954192 -312.512202)
		(end 423.24147 -312.512202)
		(width 0.16002)
		(layer "In6.Cu")
		(net "M_K_CPU0_SB_DQS_DN<3>")
	)
	(segment
		(start 393.536678 -291.49167)
		(end 393.297664 -290.94684)
		(width 0.09525)
		(layer "In6.Cu")
		(net "M_K_CPU0_SB_DQS_DN<3>")
	)
	(segment
		(start 410.603446 -313.7027)
		(end 396.422118 -299.521372)
		(width 0.16002)
		(layer "In6.Cu")
		(net "M_K_CPU0_SB_DQS_DN<3>")
	)
	(segment
		(start 445.092836 -313.613292)
		(end 444.990728 -313.511184)
		(width 0.16002)
		(layer "In6.Cu")
		(net "M_K_CPU0_SB_DQS_DN<3>")
	)
	(segment
		(start 415.357818 -312.8518)
		(end 414.969198 -312.8518)
		(width 0.16002)
		(layer "In6.Cu")
		(net "M_K_CPU0_SB_DQS_DN<3>")
	)
	(segment
		(start 418.260022 -313.362086)
		(end 417.410138 -312.512202)
		(width 0.16002)
		(layer "In6.Cu")
		(net "M_K_CPU0_SB_DQS_DN<3>")
	)
	(segment
		(start 394.151104 -292.105842)
		(end 393.536678 -291.49167)
		(width 0.09525)
		(layer "In6.Cu")
		(net "M_K_CPU0_SB_DQS_DN<3>")
	)
	(arc
		(start 392.715496 -290.776914)
		(mid 392.438588 -290.846591)
		(end 392.1633 -290.770818)
		(width 0.09525)
		(layer "In6.Cu")
		(net "M_K_CPU0_SB_DQS_DN<3>")
	)
	(arc
		(start 392.154918 -290.765992)
		(mid 391.969886 -290.720078)
		(end 391.78611 -290.770818)
		(width 0.09525)
		(layer "In6.Cu")
		(net "M_K_CPU0_SB_DQS_DN<3>")
	)
	(arc
		(start 391.223246 -290.770818)
		(mid 391.066619 -290.721632)
		(end 390.903968 -290.743894)
		(width 0.09525)
		(layer "In6.Cu")
		(net "M_K_CPU0_SB_DQS_DN<3>")
	)
	(arc
		(start 391.78611 -290.770818)
		(mid 391.504678 -290.846573)
		(end 391.223246 -290.770818)
		(width 0.09525)
		(layer "In6.Cu")
		(net "M_K_CPU0_SB_DQS_DN<3>")
	)
	(arc
		(start 393.1031 -290.770818)
		(mid 392.919325 -290.720046)
		(end 392.734292 -290.765992)
		(width 0.09525)
		(layer "In6.Cu")
		(net "M_K_CPU0_SB_DQS_DN<3>")
	)
	(arc
		(start 393.18057 -290.829746)
		(mid 393.143753 -290.79776)
		(end 393.1031 -290.770818)
		(width 0.09525)
		(layer "In6.Cu")
		(net "M_K_CPU0_SB_DQS_DN<3>")
	)
	(segment
		(start 390.567926 -285.970218)
		(end 391.034778 -286.236156)
		(width 0.12954)
		(layer "F.Cu")
		(net "M_K_CPU0_SB_DQS_DN<2>")
	)
	(segment
		(start 411.453584 -304.352706)
		(end 414.118298 -304.352706)
		(width 0.16002)
		(layer "In6.Cu")
		(net "M_K_CPU0_SB_DQS_DN<2>")
	)
	(segment
		(start 393.773914 -285.986982)
		(end 394.496544 -286.709612)
		(width 0.09525)
		(layer "In6.Cu")
		(net "M_K_CPU0_SB_DQS_DN<2>")
	)
	(segment
		(start 435.758082 -304.012092)
		(end 436.098696 -304.352706)
		(width 0.16002)
		(layer "In6.Cu")
		(net "M_K_CPU0_SB_DQS_DN<2>")
	)
	(segment
		(start 395.859254 -286.91967)
		(end 396.085568 -286.91967)
		(width 0.16002)
		(layer "In6.Cu")
		(net "M_K_CPU0_SB_DQS_DN<2>")
	)
	(segment
		(start 432.498246 -303.162208)
		(end 433.34813 -304.012092)
		(width 0.16002)
		(layer "In6.Cu")
		(net "M_K_CPU0_SB_DQS_DN<2>")
	)
	(segment
		(start 440.237118 -303.162208)
		(end 440.811158 -303.736248)
		(width 0.16002)
		(layer "In6.Cu")
		(net "M_K_CPU0_SB_DQS_DN<2>")
	)
	(segment
		(start 445.724788 -304.28819)
		(end 445.851788 -304.16119)
		(width 0.16002)
		(layer "In6.Cu")
		(net "M_K_CPU0_SB_DQS_DN<2>")
	)
	(segment
		(start 395.320774 -286.709612)
		(end 395.471904 -286.860742)
		(width 0.09525)
		(layer "In6.Cu")
		(net "M_K_CPU0_SB_DQS_DN<2>")
	)
	(segment
		(start 424.954192 -303.162208)
		(end 425.804076 -304.012092)
		(width 0.16002)
		(layer "In6.Cu")
		(net "M_K_CPU0_SB_DQS_DN<2>")
	)
	(segment
		(start 414.969198 -303.501806)
		(end 415.357818 -303.501806)
		(width 0.16002)
		(layer "In6.Cu")
		(net "M_K_CPU0_SB_DQS_DN<2>")
	)
	(segment
		(start 421.010588 -304.352706)
		(end 421.662352 -304.352706)
		(width 0.16002)
		(layer "In6.Cu")
		(net "M_K_CPU0_SB_DQS_DN<2>")
	)
	(segment
		(start 444.475108 -304.16119)
		(end 445.117728 -304.16119)
		(width 0.16002)
		(layer "In6.Cu")
		(net "M_K_CPU0_SB_DQS_DN<2>")
	)
	(segment
		(start 430.445926 -303.501806)
		(end 430.785524 -303.162208)
		(width 0.16002)
		(layer "In6.Cu")
		(net "M_K_CPU0_SB_DQS_DN<2>")
	)
	(segment
		(start 437.98998 -303.501806)
		(end 438.329578 -303.162208)
		(width 0.16002)
		(layer "In6.Cu")
		(net "M_K_CPU0_SB_DQS_DN<2>")
	)
	(segment
		(start 414.118298 -304.352706)
		(end 414.969198 -303.501806)
		(width 0.16002)
		(layer "In6.Cu")
		(net "M_K_CPU0_SB_DQS_DN<2>")
	)
	(segment
		(start 436.75046 -304.352706)
		(end 437.60136 -303.501806)
		(width 0.16002)
		(layer "In6.Cu")
		(net "M_K_CPU0_SB_DQS_DN<2>")
	)
	(segment
		(start 402.30679 -293.140892)
		(end 402.30679 -296.346372)
		(width 0.16002)
		(layer "In6.Cu")
		(net "M_K_CPU0_SB_DQS_DN<2>")
	)
	(segment
		(start 417.410138 -303.162208)
		(end 418.260022 -304.012092)
		(width 0.16002)
		(layer "In6.Cu")
		(net "M_K_CPU0_SB_DQS_DN<2>")
	)
	(segment
		(start 392.154918 -285.90621)
		(end 392.1633 -285.911036)
		(width 0.09525)
		(layer "In6.Cu")
		(net "M_K_CPU0_SB_DQS_DN<2>")
	)
	(segment
		(start 395.835632 -286.91967)
		(end 395.859254 -286.91967)
		(width 0.09525)
		(layer "In6.Cu")
		(net "M_K_CPU0_SB_DQS_DN<2>")
	)
	(segment
		(start 420.669974 -304.012092)
		(end 421.010588 -304.352706)
		(width 0.16002)
		(layer "In6.Cu")
		(net "M_K_CPU0_SB_DQS_DN<2>")
	)
	(segment
		(start 421.662352 -304.352706)
		(end 422.513252 -303.501806)
		(width 0.16002)
		(layer "In6.Cu")
		(net "M_K_CPU0_SB_DQS_DN<2>")
	)
	(segment
		(start 422.513252 -303.501806)
		(end 422.901872 -303.501806)
		(width 0.16002)
		(layer "In6.Cu")
		(net "M_K_CPU0_SB_DQS_DN<2>")
	)
	(segment
		(start 428.554642 -304.352706)
		(end 429.206406 -304.352706)
		(width 0.16002)
		(layer "In6.Cu")
		(net "M_K_CPU0_SB_DQS_DN<2>")
	)
	(segment
		(start 395.471904 -286.860742)
		(end 395.776704 -286.860742)
		(width 0.09525)
		(layer "In6.Cu")
		(net "M_K_CPU0_SB_DQS_DN<2>")
	)
	(segment
		(start 440.811158 -303.736248)
		(end 443.021974 -303.736248)
		(width 0.16002)
		(layer "In6.Cu")
		(net "M_K_CPU0_SB_DQS_DN<2>")
	)
	(segment
		(start 394.496544 -286.709612)
		(end 395.320774 -286.709612)
		(width 0.09525)
		(layer "In6.Cu")
		(net "M_K_CPU0_SB_DQS_DN<2>")
	)
	(segment
		(start 396.085568 -286.91967)
		(end 402.30679 -293.140892)
		(width 0.16002)
		(layer "In6.Cu")
		(net "M_K_CPU0_SB_DQS_DN<2>")
	)
	(segment
		(start 437.60136 -303.501806)
		(end 437.98998 -303.501806)
		(width 0.16002)
		(layer "In6.Cu")
		(net "M_K_CPU0_SB_DQS_DN<2>")
	)
	(segment
		(start 443.021974 -303.736248)
		(end 443.646052 -304.360326)
		(width 0.16002)
		(layer "In6.Cu")
		(net "M_K_CPU0_SB_DQS_DN<2>")
	)
	(segment
		(start 392.72591 -285.911036)
		(end 392.734292 -285.90621)
		(width 0.09525)
		(layer "In6.Cu")
		(net "M_K_CPU0_SB_DQS_DN<2>")
	)
	(segment
		(start 438.329578 -303.162208)
		(end 440.237118 -303.162208)
		(width 0.16002)
		(layer "In6.Cu")
		(net "M_K_CPU0_SB_DQS_DN<2>")
	)
	(segment
		(start 390.880854 -285.970726)
		(end 390.903968 -285.884112)
		(width 0.09525)
		(layer "In6.Cu")
		(net "M_K_CPU0_SB_DQS_DN<2>")
	)
	(segment
		(start 418.260022 -304.012092)
		(end 420.669974 -304.012092)
		(width 0.16002)
		(layer "In6.Cu")
		(net "M_K_CPU0_SB_DQS_DN<2>")
	)
	(segment
		(start 433.34813 -304.012092)
		(end 435.758082 -304.012092)
		(width 0.16002)
		(layer "In6.Cu")
		(net "M_K_CPU0_SB_DQS_DN<2>")
	)
	(segment
		(start 425.804076 -304.012092)
		(end 428.214028 -304.012092)
		(width 0.16002)
		(layer "In6.Cu")
		(net "M_K_CPU0_SB_DQS_DN<2>")
	)
	(segment
		(start 430.057306 -303.501806)
		(end 430.445926 -303.501806)
		(width 0.16002)
		(layer "In6.Cu")
		(net "M_K_CPU0_SB_DQS_DN<2>")
	)
	(segment
		(start 445.117728 -304.16119)
		(end 445.244728 -304.28819)
		(width 0.16002)
		(layer "In6.Cu")
		(net "M_K_CPU0_SB_DQS_DN<2>")
	)
	(segment
		(start 446.370456 -304.16119)
		(end 446.644268 -304.435002)
		(width 0.16002)
		(layer "In6.Cu")
		(net "M_K_CPU0_SB_DQS_DN<2>")
	)
	(segment
		(start 422.901872 -303.501806)
		(end 423.24147 -303.162208)
		(width 0.16002)
		(layer "In6.Cu")
		(net "M_K_CPU0_SB_DQS_DN<2>")
	)
	(segment
		(start 423.24147 -303.162208)
		(end 424.954192 -303.162208)
		(width 0.16002)
		(layer "In6.Cu")
		(net "M_K_CPU0_SB_DQS_DN<2>")
	)
	(segment
		(start 436.098696 -304.352706)
		(end 436.75046 -304.352706)
		(width 0.16002)
		(layer "In6.Cu")
		(net "M_K_CPU0_SB_DQS_DN<2>")
	)
	(segment
		(start 415.357818 -303.501806)
		(end 415.697416 -303.162208)
		(width 0.16002)
		(layer "In6.Cu")
		(net "M_K_CPU0_SB_DQS_DN<2>")
	)
	(segment
		(start 429.206406 -304.352706)
		(end 430.057306 -303.501806)
		(width 0.16002)
		(layer "In6.Cu")
		(net "M_K_CPU0_SB_DQS_DN<2>")
	)
	(segment
		(start 443.646052 -304.360326)
		(end 444.275972 -304.360326)
		(width 0.16002)
		(layer "In6.Cu")
		(net "M_K_CPU0_SB_DQS_DN<2>")
	)
	(segment
		(start 430.785524 -303.162208)
		(end 432.498246 -303.162208)
		(width 0.16002)
		(layer "In6.Cu")
		(net "M_K_CPU0_SB_DQS_DN<2>")
	)
	(segment
		(start 391.034778 -286.236156)
		(end 390.880854 -285.970726)
		(width 0.09525)
		(layer "In6.Cu")
		(net "M_K_CPU0_SB_DQS_DN<2>")
	)
	(segment
		(start 395.776704 -286.860742)
		(end 395.835632 -286.91967)
		(width 0.09525)
		(layer "In6.Cu")
		(net "M_K_CPU0_SB_DQS_DN<2>")
	)
	(segment
		(start 402.30679 -296.346372)
		(end 404.875238 -298.91482)
		(width 0.16002)
		(layer "In6.Cu")
		(net "M_K_CPU0_SB_DQS_DN<2>")
	)
	(segment
		(start 393.384786 -285.986982)
		(end 393.773914 -285.986982)
		(width 0.09525)
		(layer "In6.Cu")
		(net "M_K_CPU0_SB_DQS_DN<2>")
	)
	(segment
		(start 415.697416 -303.162208)
		(end 417.410138 -303.162208)
		(width 0.16002)
		(layer "In6.Cu")
		(net "M_K_CPU0_SB_DQS_DN<2>")
	)
	(segment
		(start 404.875238 -298.91482)
		(end 406.015698 -298.91482)
		(width 0.16002)
		(layer "In6.Cu")
		(net "M_K_CPU0_SB_DQS_DN<2>")
	)
	(segment
		(start 445.244728 -304.28819)
		(end 445.724788 -304.28819)
		(width 0.16002)
		(layer "In6.Cu")
		(net "M_K_CPU0_SB_DQS_DN<2>")
	)
	(segment
		(start 444.275972 -304.360326)
		(end 444.475108 -304.16119)
		(width 0.16002)
		(layer "In6.Cu")
		(net "M_K_CPU0_SB_DQS_DN<2>")
	)
	(segment
		(start 428.214028 -304.012092)
		(end 428.554642 -304.352706)
		(width 0.16002)
		(layer "In6.Cu")
		(net "M_K_CPU0_SB_DQS_DN<2>")
	)
	(segment
		(start 445.851788 -304.16119)
		(end 446.370456 -304.16119)
		(width 0.16002)
		(layer "In6.Cu")
		(net "M_K_CPU0_SB_DQS_DN<2>")
	)
	(segment
		(start 392.715496 -285.917132)
		(end 392.72591 -285.911036)
		(width 0.09525)
		(layer "In6.Cu")
		(net "M_K_CPU0_SB_DQS_DN<2>")
	)
	(segment
		(start 406.015698 -298.91482)
		(end 411.453584 -304.352706)
		(width 0.16002)
		(layer "In6.Cu")
		(net "M_K_CPU0_SB_DQS_DN<2>")
	)
	(arc
		(start 392.734292 -285.90621)
		(mid 392.919324 -285.860296)
		(end 393.1031 -285.911036)
		(width 0.09525)
		(layer "In6.Cu")
		(net "M_K_CPU0_SB_DQS_DN<2>")
	)
	(arc
		(start 392.1633 -285.911036)
		(mid 392.438589 -285.986757)
		(end 392.715496 -285.917132)
		(width 0.09525)
		(layer "In6.Cu")
		(net "M_K_CPU0_SB_DQS_DN<2>")
	)
	(arc
		(start 391.223246 -285.911036)
		(mid 391.504678 -285.986791)
		(end 391.78611 -285.911036)
		(width 0.09525)
		(layer "In6.Cu")
		(net "M_K_CPU0_SB_DQS_DN<2>")
	)
	(arc
		(start 391.78611 -285.911036)
		(mid 391.969885 -285.860264)
		(end 392.154918 -285.90621)
		(width 0.09525)
		(layer "In6.Cu")
		(net "M_K_CPU0_SB_DQS_DN<2>")
	)
	(arc
		(start 393.1031 -285.911036)
		(mid 393.238922 -285.967616)
		(end 393.384786 -285.986982)
		(width 0.09525)
		(layer "In6.Cu")
		(net "M_K_CPU0_SB_DQS_DN<2>")
	)
	(arc
		(start 390.903968 -285.884112)
		(mid 391.066619 -285.861852)
		(end 391.223246 -285.911036)
		(width 0.09525)
		(layer "In6.Cu")
		(net "M_K_CPU0_SB_DQS_DN<2>")
	)
	(segment
		(start 390.567926 -281.110182)
		(end 391.034778 -281.37612)
		(width 0.12954)
		(layer "F.Cu")
		(net "M_K_CPU0_SB_DQS_DN<1>")
	)
	(segment
		(start 433.34813 -294.662098)
		(end 435.758082 -294.662098)
		(width 0.16002)
		(layer "In6.Cu")
		(net "M_K_CPU0_SB_DQS_DN<1>")
	)
	(segment
		(start 436.75046 -295.002712)
		(end 437.60136 -294.151812)
		(width 0.16002)
		(layer "In6.Cu")
		(net "M_K_CPU0_SB_DQS_DN<1>")
	)
	(segment
		(start 430.057306 -294.151812)
		(end 430.445926 -294.151812)
		(width 0.16002)
		(layer "In6.Cu")
		(net "M_K_CPU0_SB_DQS_DN<1>")
	)
	(segment
		(start 393.384786 -281.126946)
		(end 393.554966 -281.126946)
		(width 0.09525)
		(layer "In6.Cu")
		(net "M_K_CPU0_SB_DQS_DN<1>")
	)
	(segment
		(start 412.365698 -295.002712)
		(end 414.118298 -295.002712)
		(width 0.16002)
		(layer "In6.Cu")
		(net "M_K_CPU0_SB_DQS_DN<1>")
	)
	(segment
		(start 445.671448 -294.938196)
		(end 445.798448 -294.811196)
		(width 0.16002)
		(layer "In6.Cu")
		(net "M_K_CPU0_SB_DQS_DN<1>")
	)
	(segment
		(start 418.013896 -294.151812)
		(end 418.524182 -294.662098)
		(width 0.16002)
		(layer "In6.Cu")
		(net "M_K_CPU0_SB_DQS_DN<1>")
	)
	(segment
		(start 418.524182 -294.662098)
		(end 420.669974 -294.662098)
		(width 0.16002)
		(layer "In6.Cu")
		(net "M_K_CPU0_SB_DQS_DN<1>")
	)
	(segment
		(start 394.041122 -280.740866)
		(end 395.21384 -280.740866)
		(width 0.09525)
		(layer "In6.Cu")
		(net "M_K_CPU0_SB_DQS_DN<1>")
	)
	(segment
		(start 438.329578 -293.812214)
		(end 440.237118 -293.812214)
		(width 0.16002)
		(layer "In6.Cu")
		(net "M_K_CPU0_SB_DQS_DN<1>")
	)
	(segment
		(start 395.428724 -281.038554)
		(end 395.633194 -281.243532)
		(width 0.16002)
		(layer "In6.Cu")
		(net "M_K_CPU0_SB_DQS_DN<1>")
	)
	(segment
		(start 390.880854 -281.11069)
		(end 390.903968 -281.024076)
		(width 0.09525)
		(layer "In6.Cu")
		(net "M_K_CPU0_SB_DQS_DN<1>")
	)
	(segment
		(start 428.214028 -294.662098)
		(end 428.554642 -295.002712)
		(width 0.16002)
		(layer "In6.Cu")
		(net "M_K_CPU0_SB_DQS_DN<1>")
	)
	(segment
		(start 429.206406 -295.002712)
		(end 430.057306 -294.151812)
		(width 0.16002)
		(layer "In6.Cu")
		(net "M_K_CPU0_SB_DQS_DN<1>")
	)
	(segment
		(start 437.98998 -294.151812)
		(end 438.329578 -293.812214)
		(width 0.16002)
		(layer "In6.Cu")
		(net "M_K_CPU0_SB_DQS_DN<1>")
	)
	(segment
		(start 414.118298 -295.002712)
		(end 414.969198 -294.151812)
		(width 0.16002)
		(layer "In6.Cu")
		(net "M_K_CPU0_SB_DQS_DN<1>")
	)
	(segment
		(start 430.785524 -293.812214)
		(end 432.498246 -293.812214)
		(width 0.16002)
		(layer "In6.Cu")
		(net "M_K_CPU0_SB_DQS_DN<1>")
	)
	(segment
		(start 440.811158 -294.386254)
		(end 443.021974 -294.386254)
		(width 0.16002)
		(layer "In6.Cu")
		(net "M_K_CPU0_SB_DQS_DN<1>")
	)
	(segment
		(start 425.804076 -294.662098)
		(end 428.214028 -294.662098)
		(width 0.16002)
		(layer "In6.Cu")
		(net "M_K_CPU0_SB_DQS_DN<1>")
	)
	(segment
		(start 414.969198 -294.151812)
		(end 418.013896 -294.151812)
		(width 0.16002)
		(layer "In6.Cu")
		(net "M_K_CPU0_SB_DQS_DN<1>")
	)
	(segment
		(start 392.154918 -281.046174)
		(end 392.1633 -281.051)
		(width 0.09525)
		(layer "In6.Cu")
		(net "M_K_CPU0_SB_DQS_DN<1>")
	)
	(segment
		(start 440.237118 -293.812214)
		(end 440.811158 -294.386254)
		(width 0.16002)
		(layer "In6.Cu")
		(net "M_K_CPU0_SB_DQS_DN<1>")
	)
	(segment
		(start 398.606518 -281.243532)
		(end 412.365698 -295.002712)
		(width 0.16002)
		(layer "In6.Cu")
		(net "M_K_CPU0_SB_DQS_DN<1>")
	)
	(segment
		(start 444.275972 -295.010332)
		(end 444.475108 -294.811196)
		(width 0.16002)
		(layer "In6.Cu")
		(net "M_K_CPU0_SB_DQS_DN<1>")
	)
	(segment
		(start 428.554642 -295.002712)
		(end 429.206406 -295.002712)
		(width 0.16002)
		(layer "In6.Cu")
		(net "M_K_CPU0_SB_DQS_DN<1>")
	)
	(segment
		(start 395.21384 -280.740866)
		(end 395.41196 -280.938986)
		(width 0.09525)
		(layer "In6.Cu")
		(net "M_K_CPU0_SB_DQS_DN<1>")
	)
	(segment
		(start 430.445926 -294.151812)
		(end 430.785524 -293.812214)
		(width 0.16002)
		(layer "In6.Cu")
		(net "M_K_CPU0_SB_DQS_DN<1>")
	)
	(segment
		(start 393.725908 -281.05608)
		(end 394.041122 -280.740866)
		(width 0.09525)
		(layer "In6.Cu")
		(net "M_K_CPU0_SB_DQS_DN<1>")
	)
	(segment
		(start 435.758082 -294.662098)
		(end 436.098696 -295.002712)
		(width 0.16002)
		(layer "In6.Cu")
		(net "M_K_CPU0_SB_DQS_DN<1>")
	)
	(segment
		(start 432.498246 -293.812214)
		(end 433.34813 -294.662098)
		(width 0.16002)
		(layer "In6.Cu")
		(net "M_K_CPU0_SB_DQS_DN<1>")
	)
	(segment
		(start 420.669974 -294.662098)
		(end 421.010588 -295.002712)
		(width 0.16002)
		(layer "In6.Cu")
		(net "M_K_CPU0_SB_DQS_DN<1>")
	)
	(segment
		(start 436.098696 -295.002712)
		(end 436.75046 -295.002712)
		(width 0.16002)
		(layer "In6.Cu")
		(net "M_K_CPU0_SB_DQS_DN<1>")
	)
	(segment
		(start 392.715496 -281.057096)
		(end 392.72591 -281.051)
		(width 0.09525)
		(layer "In6.Cu")
		(net "M_K_CPU0_SB_DQS_DN<1>")
	)
	(segment
		(start 422.513252 -294.151812)
		(end 422.901872 -294.151812)
		(width 0.16002)
		(layer "In6.Cu")
		(net "M_K_CPU0_SB_DQS_DN<1>")
	)
	(segment
		(start 422.901872 -294.151812)
		(end 423.24147 -293.812214)
		(width 0.16002)
		(layer "In6.Cu")
		(net "M_K_CPU0_SB_DQS_DN<1>")
	)
	(segment
		(start 393.554966 -281.126946)
		(end 393.725908 -281.05608)
		(width 0.09525)
		(layer "In6.Cu")
		(net "M_K_CPU0_SB_DQS_DN<1>")
	)
	(segment
		(start 395.633194 -281.243532)
		(end 398.606518 -281.243532)
		(width 0.16002)
		(layer "In6.Cu")
		(net "M_K_CPU0_SB_DQS_DN<1>")
	)
	(segment
		(start 445.798448 -294.811196)
		(end 446.370456 -294.811196)
		(width 0.16002)
		(layer "In6.Cu")
		(net "M_K_CPU0_SB_DQS_DN<1>")
	)
	(segment
		(start 421.010588 -295.002712)
		(end 421.662352 -295.002712)
		(width 0.16002)
		(layer "In6.Cu")
		(net "M_K_CPU0_SB_DQS_DN<1>")
	)
	(segment
		(start 392.72591 -281.051)
		(end 392.734292 -281.046174)
		(width 0.09525)
		(layer "In6.Cu")
		(net "M_K_CPU0_SB_DQS_DN<1>")
	)
	(segment
		(start 443.021974 -294.386254)
		(end 443.646052 -295.010332)
		(width 0.16002)
		(layer "In6.Cu")
		(net "M_K_CPU0_SB_DQS_DN<1>")
	)
	(segment
		(start 445.064388 -294.811196)
		(end 445.191388 -294.938196)
		(width 0.16002)
		(layer "In6.Cu")
		(net "M_K_CPU0_SB_DQS_DN<1>")
	)
	(segment
		(start 395.41196 -280.938986)
		(end 395.41196 -281.02179)
		(width 0.09525)
		(layer "In6.Cu")
		(net "M_K_CPU0_SB_DQS_DN<1>")
	)
	(segment
		(start 445.191388 -294.938196)
		(end 445.671448 -294.938196)
		(width 0.16002)
		(layer "In6.Cu")
		(net "M_K_CPU0_SB_DQS_DN<1>")
	)
	(segment
		(start 444.475108 -294.811196)
		(end 445.064388 -294.811196)
		(width 0.16002)
		(layer "In6.Cu")
		(net "M_K_CPU0_SB_DQS_DN<1>")
	)
	(segment
		(start 446.370456 -294.811196)
		(end 446.644268 -295.085008)
		(width 0.16002)
		(layer "In6.Cu")
		(net "M_K_CPU0_SB_DQS_DN<1>")
	)
	(segment
		(start 424.954192 -293.812214)
		(end 425.804076 -294.662098)
		(width 0.16002)
		(layer "In6.Cu")
		(net "M_K_CPU0_SB_DQS_DN<1>")
	)
	(segment
		(start 423.24147 -293.812214)
		(end 424.954192 -293.812214)
		(width 0.16002)
		(layer "In6.Cu")
		(net "M_K_CPU0_SB_DQS_DN<1>")
	)
	(segment
		(start 395.41196 -281.02179)
		(end 395.428724 -281.038554)
		(width 0.09525)
		(layer "In6.Cu")
		(net "M_K_CPU0_SB_DQS_DN<1>")
	)
	(segment
		(start 437.60136 -294.151812)
		(end 437.98998 -294.151812)
		(width 0.16002)
		(layer "In6.Cu")
		(net "M_K_CPU0_SB_DQS_DN<1>")
	)
	(segment
		(start 391.034778 -281.37612)
		(end 390.880854 -281.11069)
		(width 0.09525)
		(layer "In6.Cu")
		(net "M_K_CPU0_SB_DQS_DN<1>")
	)
	(segment
		(start 421.662352 -295.002712)
		(end 422.513252 -294.151812)
		(width 0.16002)
		(layer "In6.Cu")
		(net "M_K_CPU0_SB_DQS_DN<1>")
	)
	(segment
		(start 443.646052 -295.010332)
		(end 444.275972 -295.010332)
		(width 0.16002)
		(layer "In6.Cu")
		(net "M_K_CPU0_SB_DQS_DN<1>")
	)
	(arc
		(start 390.903968 -281.024076)
		(mid 391.066619 -281.001816)
		(end 391.223246 -281.051)
		(width 0.09525)
		(layer "In6.Cu")
		(net "M_K_CPU0_SB_DQS_DN<1>")
	)
	(arc
		(start 393.1031 -281.051)
		(mid 393.238922 -281.10758)
		(end 393.384786 -281.126946)
		(width 0.09525)
		(layer "In6.Cu")
		(net "M_K_CPU0_SB_DQS_DN<1>")
	)
	(arc
		(start 392.734292 -281.046174)
		(mid 392.919324 -281.00026)
		(end 393.1031 -281.051)
		(width 0.09525)
		(layer "In6.Cu")
		(net "M_K_CPU0_SB_DQS_DN<1>")
	)
	(arc
		(start 392.1633 -281.051)
		(mid 392.438589 -281.126721)
		(end 392.715496 -281.057096)
		(width 0.09525)
		(layer "In6.Cu")
		(net "M_K_CPU0_SB_DQS_DN<1>")
	)
	(arc
		(start 391.223246 -281.051)
		(mid 391.504678 -281.126755)
		(end 391.78611 -281.051)
		(width 0.09525)
		(layer "In6.Cu")
		(net "M_K_CPU0_SB_DQS_DN<1>")
	)
	(arc
		(start 391.78611 -281.051)
		(mid 391.969885 -281.000228)
		(end 392.154918 -281.046174)
		(width 0.09525)
		(layer "In6.Cu")
		(net "M_K_CPU0_SB_DQS_DN<1>")
	)
	(segment
		(start 390.567926 -276.250146)
		(end 391.034778 -276.516084)
		(width 0.12954)
		(layer "F.Cu")
		(net "M_K_CPU0_SB_DQS_DN<0>")
	)
	(segment
		(start 444.275972 -285.660338)
		(end 444.475108 -285.461202)
		(width 0.16002)
		(layer "In6.Cu")
		(net "M_K_CPU0_SB_DQS_DN<0>")
	)
	(segment
		(start 445.699388 -285.588202)
		(end 445.826388 -285.461202)
		(width 0.16002)
		(layer "In6.Cu")
		(net "M_K_CPU0_SB_DQS_DN<0>")
	)
	(segment
		(start 415.436812 -284.801818)
		(end 415.652458 -284.586172)
		(width 0.16002)
		(layer "In6.Cu")
		(net "M_K_CPU0_SB_DQS_DN<0>")
	)
	(segment
		(start 437.98998 -284.801818)
		(end 438.329578 -284.46222)
		(width 0.16002)
		(layer "In6.Cu")
		(net "M_K_CPU0_SB_DQS_DN<0>")
	)
	(segment
		(start 394.661898 -275.221954)
		(end 395.20241 -275.221954)
		(width 0.09525)
		(layer "In6.Cu")
		(net "M_K_CPU0_SB_DQS_DN<0>")
	)
	(segment
		(start 430.785524 -284.46222)
		(end 432.498246 -284.46222)
		(width 0.16002)
		(layer "In6.Cu")
		(net "M_K_CPU0_SB_DQS_DN<0>")
	)
	(segment
		(start 401.27174 -275.199856)
		(end 411.724602 -285.652718)
		(width 0.16002)
		(layer "In6.Cu")
		(net "M_K_CPU0_SB_DQS_DN<0>")
	)
	(segment
		(start 428.554642 -285.652718)
		(end 429.206406 -285.652718)
		(width 0.16002)
		(layer "In6.Cu")
		(net "M_K_CPU0_SB_DQS_DN<0>")
	)
	(segment
		(start 421.010588 -285.652718)
		(end 421.662352 -285.652718)
		(width 0.16002)
		(layer "In6.Cu")
		(net "M_K_CPU0_SB_DQS_DN<0>")
	)
	(segment
		(start 433.34813 -285.312104)
		(end 435.758082 -285.312104)
		(width 0.16002)
		(layer "In6.Cu")
		(net "M_K_CPU0_SB_DQS_DN<0>")
	)
	(segment
		(start 443.646052 -285.660338)
		(end 444.275972 -285.660338)
		(width 0.16002)
		(layer "In6.Cu")
		(net "M_K_CPU0_SB_DQS_DN<0>")
	)
	(segment
		(start 395.283436 -275.140928)
		(end 395.776704 -275.140928)
		(width 0.09525)
		(layer "In6.Cu")
		(net "M_K_CPU0_SB_DQS_DN<0>")
	)
	(segment
		(start 424.954192 -284.46222)
		(end 425.804076 -285.312104)
		(width 0.16002)
		(layer "In6.Cu")
		(net "M_K_CPU0_SB_DQS_DN<0>")
	)
	(segment
		(start 445.219328 -285.588202)
		(end 445.699388 -285.588202)
		(width 0.16002)
		(layer "In6.Cu")
		(net "M_K_CPU0_SB_DQS_DN<0>")
	)
	(segment
		(start 436.098696 -285.652718)
		(end 436.75046 -285.652718)
		(width 0.16002)
		(layer "In6.Cu")
		(net "M_K_CPU0_SB_DQS_DN<0>")
	)
	(segment
		(start 411.724602 -285.652718)
		(end 414.118298 -285.652718)
		(width 0.16002)
		(layer "In6.Cu")
		(net "M_K_CPU0_SB_DQS_DN<0>")
	)
	(segment
		(start 425.804076 -285.312104)
		(end 428.214028 -285.312104)
		(width 0.16002)
		(layer "In6.Cu")
		(net "M_K_CPU0_SB_DQS_DN<0>")
	)
	(segment
		(start 437.60136 -284.801818)
		(end 437.98998 -284.801818)
		(width 0.16002)
		(layer "In6.Cu")
		(net "M_K_CPU0_SB_DQS_DN<0>")
	)
	(segment
		(start 391.034778 -276.516084)
		(end 390.880854 -276.250654)
		(width 0.09525)
		(layer "In6.Cu")
		(net "M_K_CPU0_SB_DQS_DN<0>")
	)
	(segment
		(start 395.20241 -275.221954)
		(end 395.283436 -275.140928)
		(width 0.09525)
		(layer "In6.Cu")
		(net "M_K_CPU0_SB_DQS_DN<0>")
	)
	(segment
		(start 417.594288 -284.586172)
		(end 419.347142 -285.312104)
		(width 0.16002)
		(layer "In6.Cu")
		(net "M_K_CPU0_SB_DQS_DN<0>")
	)
	(segment
		(start 393.781026 -276.10308)
		(end 394.661898 -275.221954)
		(width 0.09525)
		(layer "In6.Cu")
		(net "M_K_CPU0_SB_DQS_DN<0>")
	)
	(segment
		(start 414.969198 -284.801818)
		(end 415.436812 -284.801818)
		(width 0.16002)
		(layer "In6.Cu")
		(net "M_K_CPU0_SB_DQS_DN<0>")
	)
	(segment
		(start 440.237118 -284.46222)
		(end 440.811158 -285.03626)
		(width 0.16002)
		(layer "In6.Cu")
		(net "M_K_CPU0_SB_DQS_DN<0>")
	)
	(segment
		(start 415.652458 -284.586172)
		(end 417.594288 -284.586172)
		(width 0.16002)
		(layer "In6.Cu")
		(net "M_K_CPU0_SB_DQS_DN<0>")
	)
	(segment
		(start 438.329578 -284.46222)
		(end 440.237118 -284.46222)
		(width 0.16002)
		(layer "In6.Cu")
		(net "M_K_CPU0_SB_DQS_DN<0>")
	)
	(segment
		(start 432.498246 -284.46222)
		(end 433.34813 -285.312104)
		(width 0.16002)
		(layer "In6.Cu")
		(net "M_K_CPU0_SB_DQS_DN<0>")
	)
	(segment
		(start 445.092328 -285.461202)
		(end 445.219328 -285.588202)
		(width 0.16002)
		(layer "In6.Cu")
		(net "M_K_CPU0_SB_DQS_DN<0>")
	)
	(segment
		(start 444.475108 -285.461202)
		(end 445.092328 -285.461202)
		(width 0.16002)
		(layer "In6.Cu")
		(net "M_K_CPU0_SB_DQS_DN<0>")
	)
	(segment
		(start 429.206406 -285.652718)
		(end 430.057306 -284.801818)
		(width 0.16002)
		(layer "In6.Cu")
		(net "M_K_CPU0_SB_DQS_DN<0>")
	)
	(segment
		(start 445.826388 -285.461202)
		(end 446.370456 -285.461202)
		(width 0.16002)
		(layer "In6.Cu")
		(net "M_K_CPU0_SB_DQS_DN<0>")
	)
	(segment
		(start 428.214028 -285.312104)
		(end 428.554642 -285.652718)
		(width 0.16002)
		(layer "In6.Cu")
		(net "M_K_CPU0_SB_DQS_DN<0>")
	)
	(segment
		(start 435.758082 -285.312104)
		(end 436.098696 -285.652718)
		(width 0.16002)
		(layer "In6.Cu")
		(net "M_K_CPU0_SB_DQS_DN<0>")
	)
	(segment
		(start 436.75046 -285.652718)
		(end 437.60136 -284.801818)
		(width 0.16002)
		(layer "In6.Cu")
		(net "M_K_CPU0_SB_DQS_DN<0>")
	)
	(segment
		(start 392.715496 -276.19706)
		(end 392.72591 -276.190964)
		(width 0.09525)
		(layer "In6.Cu")
		(net "M_K_CPU0_SB_DQS_DN<0>")
	)
	(segment
		(start 421.662352 -285.652718)
		(end 422.157398 -285.157672)
		(width 0.16002)
		(layer "In6.Cu")
		(net "M_K_CPU0_SB_DQS_DN<0>")
	)
	(segment
		(start 392.154918 -276.186138)
		(end 392.1633 -276.190964)
		(width 0.09525)
		(layer "In6.Cu")
		(net "M_K_CPU0_SB_DQS_DN<0>")
	)
	(segment
		(start 392.72591 -276.190964)
		(end 392.734292 -276.186138)
		(width 0.09525)
		(layer "In6.Cu")
		(net "M_K_CPU0_SB_DQS_DN<0>")
	)
	(segment
		(start 423.836338 -284.46222)
		(end 424.954192 -284.46222)
		(width 0.16002)
		(layer "In6.Cu")
		(net "M_K_CPU0_SB_DQS_DN<0>")
	)
	(segment
		(start 443.021974 -285.03626)
		(end 443.646052 -285.660338)
		(width 0.16002)
		(layer "In6.Cu")
		(net "M_K_CPU0_SB_DQS_DN<0>")
	)
	(segment
		(start 420.669974 -285.312104)
		(end 421.010588 -285.652718)
		(width 0.16002)
		(layer "In6.Cu")
		(net "M_K_CPU0_SB_DQS_DN<0>")
	)
	(segment
		(start 395.776704 -275.140928)
		(end 395.835632 -275.199856)
		(width 0.09525)
		(layer "In6.Cu")
		(net "M_K_CPU0_SB_DQS_DN<0>")
	)
	(segment
		(start 430.445926 -284.801818)
		(end 430.785524 -284.46222)
		(width 0.16002)
		(layer "In6.Cu")
		(net "M_K_CPU0_SB_DQS_DN<0>")
	)
	(segment
		(start 395.859254 -275.199856)
		(end 401.27174 -275.199856)
		(width 0.16002)
		(layer "In6.Cu")
		(net "M_K_CPU0_SB_DQS_DN<0>")
	)
	(segment
		(start 419.347142 -285.312104)
		(end 420.669974 -285.312104)
		(width 0.16002)
		(layer "In6.Cu")
		(net "M_K_CPU0_SB_DQS_DN<0>")
	)
	(segment
		(start 414.118298 -285.652718)
		(end 414.969198 -284.801818)
		(width 0.16002)
		(layer "In6.Cu")
		(net "M_K_CPU0_SB_DQS_DN<0>")
	)
	(segment
		(start 422.157398 -285.157672)
		(end 423.836338 -284.46222)
		(width 0.16002)
		(layer "In6.Cu")
		(net "M_K_CPU0_SB_DQS_DN<0>")
	)
	(segment
		(start 446.370456 -285.461202)
		(end 446.644268 -285.735014)
		(width 0.16002)
		(layer "In6.Cu")
		(net "M_K_CPU0_SB_DQS_DN<0>")
	)
	(segment
		(start 390.880854 -276.250654)
		(end 390.903968 -276.16404)
		(width 0.09525)
		(layer "In6.Cu")
		(net "M_K_CPU0_SB_DQS_DN<0>")
	)
	(segment
		(start 440.811158 -285.03626)
		(end 443.021974 -285.03626)
		(width 0.16002)
		(layer "In6.Cu")
		(net "M_K_CPU0_SB_DQS_DN<0>")
	)
	(segment
		(start 430.057306 -284.801818)
		(end 430.445926 -284.801818)
		(width 0.16002)
		(layer "In6.Cu")
		(net "M_K_CPU0_SB_DQS_DN<0>")
	)
	(segment
		(start 395.835632 -275.199856)
		(end 395.859254 -275.199856)
		(width 0.09525)
		(layer "In6.Cu")
		(net "M_K_CPU0_SB_DQS_DN<0>")
	)
	(arc
		(start 393.758928 -276.123908)
		(mid 393.770115 -276.113641)
		(end 393.781026 -276.10308)
		(width 0.09525)
		(layer "In6.Cu")
		(net "M_K_CPU0_SB_DQS_DN<0>")
	)
	(arc
		(start 393.647676 -276.201378)
		(mid 393.705658 -276.166025)
		(end 393.758928 -276.123908)
		(width 0.09525)
		(layer "In6.Cu")
		(net "M_K_CPU0_SB_DQS_DN<0>")
	)
	(arc
		(start 391.78611 -276.190964)
		(mid 391.969885 -276.140192)
		(end 392.154918 -276.186138)
		(width 0.09525)
		(layer "In6.Cu")
		(net "M_K_CPU0_SB_DQS_DN<0>")
	)
	(arc
		(start 392.734292 -276.186138)
		(mid 392.919324 -276.140224)
		(end 393.1031 -276.190964)
		(width 0.09525)
		(layer "In6.Cu")
		(net "M_K_CPU0_SB_DQS_DN<0>")
	)
	(arc
		(start 390.903968 -276.16404)
		(mid 391.066619 -276.14178)
		(end 391.223246 -276.190964)
		(width 0.09525)
		(layer "In6.Cu")
		(net "M_K_CPU0_SB_DQS_DN<0>")
	)
	(arc
		(start 392.1633 -276.190964)
		(mid 392.438589 -276.266685)
		(end 392.715496 -276.19706)
		(width 0.09525)
		(layer "In6.Cu")
		(net "M_K_CPU0_SB_DQS_DN<0>")
	)
	(arc
		(start 393.1031 -276.190964)
		(mid 393.374042 -276.266744)
		(end 393.647676 -276.201378)
		(width 0.09525)
		(layer "In6.Cu")
		(net "M_K_CPU0_SB_DQS_DN<0>")
	)
	(arc
		(start 391.223246 -276.190964)
		(mid 391.504678 -276.266719)
		(end 391.78611 -276.190964)
		(width 0.09525)
		(layer "In6.Cu")
		(net "M_K_CPU0_SB_DQS_DN<0>")
	)
	(segment
		(start 388.688072 -279.49017)
		(end 389.154924 -279.756108)
		(width 0.10668)
		(layer "F.Cu")
		(net "M_K_CPU0_SB_DQ<9>")
	)
	(segment
		(start 422.577006 -292.11016)
		(end 425.601638 -292.11016)
		(width 0.14478)
		(layer "In6.Cu")
		(net "M_K_CPU0_SB_DQ<9>")
	)
	(segment
		(start 393.44473 -279.928828)
		(end 395.128496 -279.928828)
		(width 0.0889)
		(layer "In6.Cu")
		(net "M_K_CPU0_SB_DQ<9>")
	)
	(segment
		(start 412.18866 -292.960044)
		(end 413.439864 -292.960044)
		(width 0.14478)
		(layer "In6.Cu")
		(net "M_K_CPU0_SB_DQ<9>")
	)
	(segment
		(start 421.727122 -292.960044)
		(end 422.577006 -292.11016)
		(width 0.14478)
		(layer "In6.Cu")
		(net "M_K_CPU0_SB_DQ<9>")
	)
	(segment
		(start 392.161522 -280.078688)
		(end 392.171936 -280.072592)
		(width 0.0889)
		(layer "In6.Cu")
		(net "M_K_CPU0_SB_DQ<9>")
	)
	(segment
		(start 418.057584 -292.11016)
		(end 418.907468 -292.960044)
		(width 0.14478)
		(layer "In6.Cu")
		(net "M_K_CPU0_SB_DQ<9>")
	)
	(segment
		(start 392.72718 -280.078688)
		(end 392.738864 -280.085546)
		(width 0.0889)
		(layer "In6.Cu")
		(net "M_K_CPU0_SB_DQ<9>")
	)
	(segment
		(start 418.907468 -292.960044)
		(end 421.727122 -292.960044)
		(width 0.14478)
		(layer "In6.Cu")
		(net "M_K_CPU0_SB_DQ<9>")
	)
	(segment
		(start 433.145692 -292.11016)
		(end 433.995576 -292.960044)
		(width 0.14478)
		(layer "In6.Cu")
		(net "M_K_CPU0_SB_DQ<9>")
	)
	(segment
		(start 437.123586 -292.109906)
		(end 446.219072 -292.109906)
		(width 0.14478)
		(layer "In6.Cu")
		(net "M_K_CPU0_SB_DQ<9>")
	)
	(segment
		(start 389.90778 -280.078688)
		(end 389.916162 -280.083514)
		(width 0.0889)
		(layer "In6.Cu")
		(net "M_K_CPU0_SB_DQ<9>")
	)
	(segment
		(start 392.149838 -280.085546)
		(end 392.161522 -280.078688)
		(width 0.0889)
		(layer "In6.Cu")
		(net "M_K_CPU0_SB_DQ<9>")
	)
	(segment
		(start 433.995576 -292.960044)
		(end 436.273448 -292.960044)
		(width 0.14478)
		(layer "In6.Cu")
		(net "M_K_CPU0_SB_DQ<9>")
	)
	(segment
		(start 429.271176 -292.960044)
		(end 430.12106 -292.11016)
		(width 0.14478)
		(layer "In6.Cu")
		(net "M_K_CPU0_SB_DQ<9>")
	)
	(segment
		(start 436.273448 -292.960044)
		(end 437.123586 -292.109906)
		(width 0.14478)
		(layer "In6.Cu")
		(net "M_K_CPU0_SB_DQ<9>")
	)
	(segment
		(start 414.289748 -292.11016)
		(end 418.057584 -292.11016)
		(width 0.14478)
		(layer "In6.Cu")
		(net "M_K_CPU0_SB_DQ<9>")
	)
	(segment
		(start 398.974056 -279.74544)
		(end 412.18866 -292.960044)
		(width 0.14478)
		(layer "In6.Cu")
		(net "M_K_CPU0_SB_DQ<9>")
	)
	(segment
		(start 425.601638 -292.11016)
		(end 426.451522 -292.960044)
		(width 0.14478)
		(layer "In6.Cu")
		(net "M_K_CPU0_SB_DQ<9>")
	)
	(segment
		(start 430.12106 -292.11016)
		(end 433.145692 -292.11016)
		(width 0.14478)
		(layer "In6.Cu")
		(net "M_K_CPU0_SB_DQ<9>")
	)
	(segment
		(start 389.154924 -279.756108)
		(end 389.308848 -280.021538)
		(width 0.0889)
		(layer "In6.Cu")
		(net "M_K_CPU0_SB_DQ<9>")
	)
	(segment
		(start 389.308848 -280.021538)
		(end 389.40486 -280.046938)
		(width 0.0889)
		(layer "In6.Cu")
		(net "M_K_CPU0_SB_DQ<9>")
	)
	(segment
		(start 395.771116 -279.74544)
		(end 398.974056 -279.74544)
		(width 0.14478)
		(layer "In6.Cu")
		(net "M_K_CPU0_SB_DQ<9>")
	)
	(segment
		(start 395.128496 -279.928828)
		(end 395.311884 -279.74544)
		(width 0.0889)
		(layer "In6.Cu")
		(net "M_K_CPU0_SB_DQ<9>")
	)
	(segment
		(start 393.101576 -280.078688)
		(end 393.285726 -279.971754)
		(width 0.0889)
		(layer "In6.Cu")
		(net "M_K_CPU0_SB_DQ<9>")
	)
	(segment
		(start 446.219072 -292.109906)
		(end 446.644268 -292.535102)
		(width 0.14478)
		(layer "In6.Cu")
		(net "M_K_CPU0_SB_DQ<9>")
	)
	(segment
		(start 426.451522 -292.960044)
		(end 429.271176 -292.960044)
		(width 0.14478)
		(layer "In6.Cu")
		(net "M_K_CPU0_SB_DQ<9>")
	)
	(segment
		(start 395.311884 -279.74544)
		(end 395.771116 -279.74544)
		(width 0.0889)
		(layer "In6.Cu")
		(net "M_K_CPU0_SB_DQ<9>")
	)
	(segment
		(start 413.439864 -292.960044)
		(end 414.289748 -292.11016)
		(width 0.14478)
		(layer "In6.Cu")
		(net "M_K_CPU0_SB_DQ<9>")
	)
	(arc
		(start 393.285726 -279.971754)
		(mid 393.362383 -279.93974)
		(end 393.44473 -279.928828)
		(width 0.0889)
		(layer "In6.Cu")
		(net "M_K_CPU0_SB_DQ<9>")
	)
	(arc
		(start 390.847834 -280.078688)
		(mid 391.034778 -280.128943)
		(end 391.221722 -280.078688)
		(width 0.0889)
		(layer "In6.Cu")
		(net "M_K_CPU0_SB_DQ<9>")
	)
	(arc
		(start 392.171936 -280.072592)
		(mid 392.450368 -280.002494)
		(end 392.72718 -280.078688)
		(width 0.0889)
		(layer "In6.Cu")
		(net "M_K_CPU0_SB_DQ<9>")
	)
	(arc
		(start 390.281922 -280.078688)
		(mid 390.564878 -280.002511)
		(end 390.847834 -280.078688)
		(width 0.0889)
		(layer "In6.Cu")
		(net "M_K_CPU0_SB_DQ<9>")
	)
	(arc
		(start 391.221722 -280.078688)
		(mid 391.504678 -280.002511)
		(end 391.787634 -280.078688)
		(width 0.0889)
		(layer "In6.Cu")
		(net "M_K_CPU0_SB_DQ<9>")
	)
	(arc
		(start 389.916162 -280.083514)
		(mid 390.09967 -280.129008)
		(end 390.281922 -280.078688)
		(width 0.0889)
		(layer "In6.Cu")
		(net "M_K_CPU0_SB_DQ<9>")
	)
	(arc
		(start 391.787634 -280.078688)
		(mid 391.967839 -280.129005)
		(end 392.149838 -280.085546)
		(width 0.0889)
		(layer "In6.Cu")
		(net "M_K_CPU0_SB_DQ<9>")
	)
	(arc
		(start 389.40486 -280.046938)
		(mid 389.660068 -280.003461)
		(end 389.90778 -280.078688)
		(width 0.0889)
		(layer "In6.Cu")
		(net "M_K_CPU0_SB_DQ<9>")
	)
	(arc
		(start 392.738864 -280.085546)
		(mid 392.921119 -280.129199)
		(end 393.101576 -280.078688)
		(width 0.0889)
		(layer "In6.Cu")
		(net "M_K_CPU0_SB_DQ<9>")
	)
	(segment
		(start 390.098026 -278.680164)
		(end 390.564878 -278.946102)
		(width 0.10668)
		(layer "F.Cu")
		(net "M_K_CPU0_SB_DQ<8>")
	)
	(segment
		(start 444.222886 -290.861242)
		(end 444.222886 -290.573206)
		(width 0.14478)
		(layer "In6.Cu")
		(net "M_K_CPU0_SB_DQ<8>")
	)
	(segment
		(start 445.172846 -291.02431)
		(end 445.335914 -290.861242)
		(width 0.14478)
		(layer "In6.Cu")
		(net "M_K_CPU0_SB_DQ<8>")
	)
	(segment
		(start 426.451522 -291.260022)
		(end 429.271176 -291.260022)
		(width 0.14478)
		(layer "In6.Cu")
		(net "M_K_CPU0_SB_DQ<8>")
	)
	(segment
		(start 446.219326 -290.410138)
		(end 446.644268 -290.83508)
		(width 0.14478)
		(layer "In6.Cu")
		(net "M_K_CPU0_SB_DQ<8>")
	)
	(segment
		(start 412.201614 -291.260022)
		(end 413.454596 -291.260022)
		(width 0.14478)
		(layer "In6.Cu")
		(net "M_K_CPU0_SB_DQ<8>")
	)
	(segment
		(start 429.271176 -291.260022)
		(end 430.12106 -290.410138)
		(width 0.14478)
		(layer "In6.Cu")
		(net "M_K_CPU0_SB_DQ<8>")
	)
	(segment
		(start 390.564878 -278.946102)
		(end 390.718802 -279.211532)
		(width 0.0889)
		(layer "In6.Cu")
		(net "M_K_CPU0_SB_DQ<8>")
	)
	(segment
		(start 413.454596 -291.260022)
		(end 414.30448 -290.410138)
		(width 0.14478)
		(layer "In6.Cu")
		(net "M_K_CPU0_SB_DQ<8>")
	)
	(segment
		(start 395.249654 -278.65197)
		(end 395.290548 -278.611076)
		(width 0.0889)
		(layer "In6.Cu")
		(net "M_K_CPU0_SB_DQ<8>")
	)
	(segment
		(start 392.631422 -279.268682)
		(end 392.641836 -279.262586)
		(width 0.0889)
		(layer "In6.Cu")
		(net "M_K_CPU0_SB_DQ<8>")
	)
	(segment
		(start 444.7794 -290.861242)
		(end 444.942468 -291.02431)
		(width 0.14478)
		(layer "In6.Cu")
		(net "M_K_CPU0_SB_DQ<8>")
	)
	(segment
		(start 443.666372 -290.573206)
		(end 443.666372 -290.861242)
		(width 0.14478)
		(layer "In6.Cu")
		(net "M_K_CPU0_SB_DQ<8>")
	)
	(segment
		(start 418.057584 -290.410138)
		(end 418.907468 -291.260022)
		(width 0.14478)
		(layer "In6.Cu")
		(net "M_K_CPU0_SB_DQ<8>")
	)
	(segment
		(start 443.503304 -290.410138)
		(end 443.666372 -290.573206)
		(width 0.14478)
		(layer "In6.Cu")
		(net "M_K_CPU0_SB_DQ<8>")
	)
	(segment
		(start 418.907468 -291.260022)
		(end 421.658542 -291.260022)
		(width 0.14478)
		(layer "In6.Cu")
		(net "M_K_CPU0_SB_DQ<8>")
	)
	(segment
		(start 390.718802 -279.211532)
		(end 390.814814 -279.236932)
		(width 0.0889)
		(layer "In6.Cu")
		(net "M_K_CPU0_SB_DQ<8>")
	)
	(segment
		(start 421.658542 -291.260022)
		(end 422.508426 -290.410138)
		(width 0.14478)
		(layer "In6.Cu")
		(net "M_K_CPU0_SB_DQ<8>")
	)
	(segment
		(start 445.335914 -290.573206)
		(end 445.498982 -290.410138)
		(width 0.14478)
		(layer "In6.Cu")
		(net "M_K_CPU0_SB_DQ<8>")
	)
	(segment
		(start 391.317734 -279.268682)
		(end 391.326116 -279.273508)
		(width 0.0889)
		(layer "In6.Cu")
		(net "M_K_CPU0_SB_DQ<8>")
	)
	(segment
		(start 437.16194 -290.410138)
		(end 443.503304 -290.410138)
		(width 0.14478)
		(layer "In6.Cu")
		(net "M_K_CPU0_SB_DQ<8>")
	)
	(segment
		(start 433.995576 -291.260022)
		(end 436.312056 -291.260022)
		(width 0.14478)
		(layer "In6.Cu")
		(net "M_K_CPU0_SB_DQ<8>")
	)
	(segment
		(start 399.552668 -278.611076)
		(end 412.201614 -291.260022)
		(width 0.14478)
		(layer "In6.Cu")
		(net "M_K_CPU0_SB_DQ<8>")
	)
	(segment
		(start 395.290548 -278.611076)
		(end 395.957552 -278.611076)
		(width 0.0889)
		(layer "In6.Cu")
		(net "M_K_CPU0_SB_DQ<8>")
	)
	(segment
		(start 422.508426 -290.410138)
		(end 425.601638 -290.410138)
		(width 0.14478)
		(layer "In6.Cu")
		(net "M_K_CPU0_SB_DQ<8>")
	)
	(segment
		(start 433.145692 -290.410138)
		(end 433.995576 -291.260022)
		(width 0.14478)
		(layer "In6.Cu")
		(net "M_K_CPU0_SB_DQ<8>")
	)
	(segment
		(start 425.601638 -290.410138)
		(end 426.451522 -291.260022)
		(width 0.14478)
		(layer "In6.Cu")
		(net "M_K_CPU0_SB_DQ<8>")
	)
	(segment
		(start 392.24712 -279.262586)
		(end 392.257534 -279.268682)
		(width 0.0889)
		(layer "In6.Cu")
		(net "M_K_CPU0_SB_DQ<8>")
	)
	(segment
		(start 444.222886 -290.573206)
		(end 444.385954 -290.410138)
		(width 0.14478)
		(layer "In6.Cu")
		(net "M_K_CPU0_SB_DQ<8>")
	)
	(segment
		(start 443.82944 -291.02431)
		(end 444.059818 -291.02431)
		(width 0.14478)
		(layer "In6.Cu")
		(net "M_K_CPU0_SB_DQ<8>")
	)
	(segment
		(start 393.559792 -279.27554)
		(end 393.63269 -279.209754)
		(width 0.0889)
		(layer "In6.Cu")
		(net "M_K_CPU0_SB_DQ<8>")
	)
	(segment
		(start 436.312056 -291.260022)
		(end 437.16194 -290.410138)
		(width 0.14478)
		(layer "In6.Cu")
		(net "M_K_CPU0_SB_DQ<8>")
	)
	(segment
		(start 444.942468 -291.02431)
		(end 445.172846 -291.02431)
		(width 0.14478)
		(layer "In6.Cu")
		(net "M_K_CPU0_SB_DQ<8>")
	)
	(segment
		(start 444.385954 -290.410138)
		(end 444.616332 -290.410138)
		(width 0.14478)
		(layer "In6.Cu")
		(net "M_K_CPU0_SB_DQ<8>")
	)
	(segment
		(start 393.63269 -279.209754)
		(end 394.152628 -278.689816)
		(width 0.0889)
		(layer "In6.Cu")
		(net "M_K_CPU0_SB_DQ<8>")
	)
	(segment
		(start 394.244068 -278.65197)
		(end 395.249654 -278.65197)
		(width 0.0889)
		(layer "In6.Cu")
		(net "M_K_CPU0_SB_DQ<8>")
	)
	(segment
		(start 430.12106 -290.410138)
		(end 433.145692 -290.410138)
		(width 0.14478)
		(layer "In6.Cu")
		(net "M_K_CPU0_SB_DQ<8>")
	)
	(segment
		(start 443.666372 -290.861242)
		(end 443.82944 -291.02431)
		(width 0.14478)
		(layer "In6.Cu")
		(net "M_K_CPU0_SB_DQ<8>")
	)
	(segment
		(start 445.335914 -290.861242)
		(end 445.335914 -290.573206)
		(width 0.14478)
		(layer "In6.Cu")
		(net "M_K_CPU0_SB_DQ<8>")
	)
	(segment
		(start 444.059818 -291.02431)
		(end 444.222886 -290.861242)
		(width 0.14478)
		(layer "In6.Cu")
		(net "M_K_CPU0_SB_DQ<8>")
	)
	(segment
		(start 414.30448 -290.410138)
		(end 418.057584 -290.410138)
		(width 0.14478)
		(layer "In6.Cu")
		(net "M_K_CPU0_SB_DQ<8>")
	)
	(segment
		(start 445.498982 -290.410138)
		(end 446.219326 -290.410138)
		(width 0.14478)
		(layer "In6.Cu")
		(net "M_K_CPU0_SB_DQ<8>")
	)
	(segment
		(start 444.7794 -290.573206)
		(end 444.7794 -290.861242)
		(width 0.14478)
		(layer "In6.Cu")
		(net "M_K_CPU0_SB_DQ<8>")
	)
	(segment
		(start 395.957552 -278.611076)
		(end 399.552668 -278.611076)
		(width 0.14478)
		(layer "In6.Cu")
		(net "M_K_CPU0_SB_DQ<8>")
	)
	(segment
		(start 444.616332 -290.410138)
		(end 444.7794 -290.573206)
		(width 0.14478)
		(layer "In6.Cu")
		(net "M_K_CPU0_SB_DQ<8>")
	)
	(arc
		(start 391.691876 -279.268682)
		(mid 391.968689 -279.192539)
		(end 392.24712 -279.262586)
		(width 0.0889)
		(layer "In6.Cu")
		(net "M_K_CPU0_SB_DQ<8>")
	)
	(arc
		(start 393.197588 -279.268682)
		(mid 393.377793 -279.318999)
		(end 393.559792 -279.27554)
		(width 0.0889)
		(layer "In6.Cu")
		(net "M_K_CPU0_SB_DQ<8>")
	)
	(arc
		(start 392.257534 -279.268682)
		(mid 392.444478 -279.318937)
		(end 392.631422 -279.268682)
		(width 0.0889)
		(layer "In6.Cu")
		(net "M_K_CPU0_SB_DQ<8>")
	)
	(arc
		(start 390.814814 -279.236932)
		(mid 391.070022 -279.193455)
		(end 391.317734 -279.268682)
		(width 0.0889)
		(layer "In6.Cu")
		(net "M_K_CPU0_SB_DQ<8>")
	)
	(arc
		(start 392.641836 -279.262586)
		(mid 392.920522 -279.192366)
		(end 393.197588 -279.268682)
		(width 0.0889)
		(layer "In6.Cu")
		(net "M_K_CPU0_SB_DQ<8>")
	)
	(arc
		(start 391.326116 -279.273508)
		(mid 391.509624 -279.319002)
		(end 391.691876 -279.268682)
		(width 0.0889)
		(layer "In6.Cu")
		(net "M_K_CPU0_SB_DQ<8>")
	)
	(arc
		(start 394.152628 -278.689816)
		(mid 394.194581 -278.661784)
		(end 394.244068 -278.65197)
		(width 0.0889)
		(layer "In6.Cu")
		(net "M_K_CPU0_SB_DQ<8>")
	)
	(segment
		(start 389.157972 -278.680164)
		(end 389.624824 -278.946102)
		(width 0.10668)
		(layer "F.Cu")
		(net "M_K_CPU0_SB_DQ<7>")
	)
	(segment
		(start 440.964066 -289.848036)
		(end 441.10783 -289.704272)
		(width 0.14478)
		(layer "In6.Cu")
		(net "M_K_CPU0_SB_DQ<7>")
	)
	(segment
		(start 424.805094 -289.27171)
		(end 425.073064 -289.27171)
		(width 0.14478)
		(layer "In6.Cu")
		(net "M_K_CPU0_SB_DQ<7>")
	)
	(segment
		(start 432.26736 -289.186112)
		(end 432.529234 -289.186112)
		(width 0.14478)
		(layer "In6.Cu")
		(net "M_K_CPU0_SB_DQ<7>")
	)
	(segment
		(start 432.12258 -289.415474)
		(end 432.12258 -289.330892)
		(width 0.14478)
		(layer "In6.Cu")
		(net "M_K_CPU0_SB_DQ<7>")
	)
	(segment
		(start 418.122608 -289.560254)
		(end 418.972746 -290.410392)
		(width 0.14478)
		(layer "In6.Cu")
		(net "M_K_CPU0_SB_DQ<7>")
	)
	(segment
		(start 421.634158 -290.410392)
		(end 422.484296 -289.560254)
		(width 0.14478)
		(layer "In6.Cu")
		(net "M_K_CPU0_SB_DQ<7>")
	)
	(segment
		(start 415.76117 -289.27171)
		(end 416.02914 -289.27171)
		(width 0.14478)
		(layer "In6.Cu")
		(net "M_K_CPU0_SB_DQ<7>")
	)
	(segment
		(start 389.4709 -278.680672)
		(end 389.493252 -278.59736)
		(width 0.0889)
		(layer "In6.Cu")
		(net "M_K_CPU0_SB_DQ<7>")
	)
	(segment
		(start 432.818794 -289.560254)
		(end 433.142644 -289.560254)
		(width 0.14478)
		(layer "In6.Cu")
		(net "M_K_CPU0_SB_DQ<7>")
	)
	(segment
		(start 418.972746 -290.410392)
		(end 420.536624 -290.410392)
		(width 0.14478)
		(layer "In6.Cu")
		(net "M_K_CPU0_SB_DQ<7>")
	)
	(segment
		(start 441.5155 -289.272472)
		(end 441.659264 -289.416236)
		(width 0.14478)
		(layer "In6.Cu")
		(net "M_K_CPU0_SB_DQ<7>")
	)
	(segment
		(start 433.992528 -290.410138)
		(end 436.35168 -290.410138)
		(width 0.14478)
		(layer "In6.Cu")
		(net "M_K_CPU0_SB_DQ<7>")
	)
	(segment
		(start 441.10783 -289.704272)
		(end 441.10783 -289.416236)
		(width 0.14478)
		(layer "In6.Cu")
		(net "M_K_CPU0_SB_DQ<7>")
	)
	(segment
		(start 416.317684 -289.560254)
		(end 416.585654 -289.560254)
		(width 0.14478)
		(layer "In6.Cu")
		(net "M_K_CPU0_SB_DQ<7>")
	)
	(segment
		(start 417.142168 -289.27171)
		(end 417.430712 -289.560254)
		(width 0.14478)
		(layer "In6.Cu")
		(net "M_K_CPU0_SB_DQ<7>")
	)
	(segment
		(start 440.004962 -289.41649)
		(end 440.004962 -289.416236)
		(width 0.14478)
		(layer "In6.Cu")
		(net "M_K_CPU0_SB_DQ<7>")
	)
	(segment
		(start 420.862506 -290.08451)
		(end 421.093138 -290.08451)
		(width 0.14478)
		(layer "In6.Cu")
		(net "M_K_CPU0_SB_DQ<7>")
	)
	(segment
		(start 440.004962 -289.416236)
		(end 440.148726 -289.272472)
		(width 0.14478)
		(layer "In6.Cu")
		(net "M_K_CPU0_SB_DQ<7>")
	)
	(segment
		(start 389.624824 -278.946102)
		(end 389.4709 -278.680672)
		(width 0.0889)
		(layer "In6.Cu")
		(net "M_K_CPU0_SB_DQ<7>")
	)
	(segment
		(start 426.5168 -290.410392)
		(end 429.178212 -290.410392)
		(width 0.14478)
		(layer "In6.Cu")
		(net "M_K_CPU0_SB_DQ<7>")
	)
	(segment
		(start 425.073064 -289.27171)
		(end 425.361608 -289.560254)
		(width 0.14478)
		(layer "In6.Cu")
		(net "M_K_CPU0_SB_DQ<7>")
	)
	(segment
		(start 441.659264 -289.41649)
		(end 441.803028 -289.560254)
		(width 0.14478)
		(layer "In6.Cu")
		(net "M_K_CPU0_SB_DQ<7>")
	)
	(segment
		(start 424.51655 -289.560254)
		(end 424.805094 -289.27171)
		(width 0.14478)
		(layer "In6.Cu")
		(net "M_K_CPU0_SB_DQ<7>")
	)
	(segment
		(start 430.02835 -289.560254)
		(end 431.9778 -289.560254)
		(width 0.14478)
		(layer "In6.Cu")
		(net "M_K_CPU0_SB_DQ<7>")
	)
	(segment
		(start 425.666662 -289.560254)
		(end 426.5168 -290.410392)
		(width 0.14478)
		(layer "In6.Cu")
		(net "M_K_CPU0_SB_DQ<7>")
	)
	(segment
		(start 392.631168 -278.623522)
		(end 392.641582 -278.629618)
		(width 0.0889)
		(layer "In6.Cu")
		(net "M_K_CPU0_SB_DQ<7>")
	)
	(segment
		(start 440.148726 -289.272472)
		(end 440.412632 -289.272472)
		(width 0.14478)
		(layer "In6.Cu")
		(net "M_K_CPU0_SB_DQ<7>")
	)
	(segment
		(start 440.556396 -289.704272)
		(end 440.70016 -289.848036)
		(width 0.14478)
		(layer "In6.Cu")
		(net "M_K_CPU0_SB_DQ<7>")
	)
	(segment
		(start 438.432194 -289.560254)
		(end 439.861198 -289.560254)
		(width 0.14478)
		(layer "In6.Cu")
		(net "M_K_CPU0_SB_DQ<7>")
	)
	(segment
		(start 429.178212 -290.410392)
		(end 430.02835 -289.560254)
		(width 0.14478)
		(layer "In6.Cu")
		(net "M_K_CPU0_SB_DQ<7>")
	)
	(segment
		(start 439.861198 -289.560254)
		(end 440.004962 -289.41649)
		(width 0.14478)
		(layer "In6.Cu")
		(net "M_K_CPU0_SB_DQ<7>")
	)
	(segment
		(start 415.472626 -289.560254)
		(end 415.76117 -289.27171)
		(width 0.14478)
		(layer "In6.Cu")
		(net "M_K_CPU0_SB_DQ<7>")
	)
	(segment
		(start 432.12258 -289.330892)
		(end 432.26736 -289.186112)
		(width 0.14478)
		(layer "In6.Cu")
		(net "M_K_CPU0_SB_DQ<7>")
	)
	(segment
		(start 440.556396 -289.416236)
		(end 440.556396 -289.704272)
		(width 0.14478)
		(layer "In6.Cu")
		(net "M_K_CPU0_SB_DQ<7>")
	)
	(segment
		(start 413.491172 -290.410392)
		(end 414.34131 -289.560254)
		(width 0.14478)
		(layer "In6.Cu")
		(net "M_K_CPU0_SB_DQ<7>")
	)
	(segment
		(start 441.803028 -289.560254)
		(end 442.119258 -289.560254)
		(width 0.14478)
		(layer "In6.Cu")
		(net "M_K_CPU0_SB_DQ<7>")
	)
	(segment
		(start 395.168628 -278.235918)
		(end 395.34973 -278.054816)
		(width 0.0889)
		(layer "In6.Cu")
		(net "M_K_CPU0_SB_DQ<7>")
	)
	(segment
		(start 395.34973 -278.054816)
		(end 395.98219 -278.054816)
		(width 0.0889)
		(layer "In6.Cu")
		(net "M_K_CPU0_SB_DQ<7>")
	)
	(segment
		(start 437.587136 -289.560254)
		(end 437.87568 -289.27171)
		(width 0.14478)
		(layer "In6.Cu")
		(net "M_K_CPU0_SB_DQ<7>")
	)
	(segment
		(start 436.35168 -290.410138)
		(end 437.201564 -289.560254)
		(width 0.14478)
		(layer "In6.Cu")
		(net "M_K_CPU0_SB_DQ<7>")
	)
	(segment
		(start 392.257534 -278.623522)
		(end 392.265916 -278.618696)
		(width 0.0889)
		(layer "In6.Cu")
		(net "M_K_CPU0_SB_DQ<7>")
	)
	(segment
		(start 416.874198 -289.27171)
		(end 417.142168 -289.27171)
		(width 0.14478)
		(layer "In6.Cu")
		(net "M_K_CPU0_SB_DQ<7>")
	)
	(segment
		(start 412.408878 -290.410392)
		(end 413.491172 -290.410392)
		(width 0.14478)
		(layer "In6.Cu")
		(net "M_K_CPU0_SB_DQ<7>")
	)
	(segment
		(start 416.585654 -289.560254)
		(end 416.874198 -289.27171)
		(width 0.14478)
		(layer "In6.Cu")
		(net "M_K_CPU0_SB_DQ<7>")
	)
	(segment
		(start 441.659264 -289.416236)
		(end 441.659264 -289.41649)
		(width 0.14478)
		(layer "In6.Cu")
		(net "M_K_CPU0_SB_DQ<7>")
	)
	(segment
		(start 422.484296 -289.560254)
		(end 424.51655 -289.560254)
		(width 0.14478)
		(layer "In6.Cu")
		(net "M_K_CPU0_SB_DQ<7>")
	)
	(segment
		(start 432.674014 -289.330892)
		(end 432.674014 -289.415474)
		(width 0.14478)
		(layer "In6.Cu")
		(net "M_K_CPU0_SB_DQ<7>")
	)
	(segment
		(start 416.02914 -289.27171)
		(end 416.317684 -289.560254)
		(width 0.14478)
		(layer "In6.Cu")
		(net "M_K_CPU0_SB_DQ<7>")
	)
	(segment
		(start 432.674014 -289.415474)
		(end 432.818794 -289.560254)
		(width 0.14478)
		(layer "In6.Cu")
		(net "M_K_CPU0_SB_DQ<7>")
	)
	(segment
		(start 417.430712 -289.560254)
		(end 418.122608 -289.560254)
		(width 0.14478)
		(layer "In6.Cu")
		(net "M_K_CPU0_SB_DQ<7>")
	)
	(segment
		(start 391.317734 -278.623522)
		(end 391.326116 -278.618696)
		(width 0.0889)
		(layer "In6.Cu")
		(net "M_K_CPU0_SB_DQ<7>")
	)
	(segment
		(start 440.412632 -289.272472)
		(end 440.556396 -289.416236)
		(width 0.14478)
		(layer "In6.Cu")
		(net "M_K_CPU0_SB_DQ<7>")
	)
	(segment
		(start 437.201564 -289.560254)
		(end 437.587136 -289.560254)
		(width 0.14478)
		(layer "In6.Cu")
		(net "M_K_CPU0_SB_DQ<7>")
	)
	(segment
		(start 421.41902 -290.410392)
		(end 421.634158 -290.410392)
		(width 0.14478)
		(layer "In6.Cu")
		(net "M_K_CPU0_SB_DQ<7>")
	)
	(segment
		(start 431.9778 -289.560254)
		(end 432.12258 -289.415474)
		(width 0.14478)
		(layer "In6.Cu")
		(net "M_K_CPU0_SB_DQ<7>")
	)
	(segment
		(start 441.251594 -289.272472)
		(end 441.5155 -289.272472)
		(width 0.14478)
		(layer "In6.Cu")
		(net "M_K_CPU0_SB_DQ<7>")
	)
	(segment
		(start 420.536624 -290.410392)
		(end 420.862506 -290.08451)
		(width 0.14478)
		(layer "In6.Cu")
		(net "M_K_CPU0_SB_DQ<7>")
	)
	(segment
		(start 421.093138 -290.08451)
		(end 421.41902 -290.410392)
		(width 0.14478)
		(layer "In6.Cu")
		(net "M_K_CPU0_SB_DQ<7>")
	)
	(segment
		(start 395.98219 -278.054816)
		(end 400.053302 -278.054816)
		(width 0.14478)
		(layer "In6.Cu")
		(net "M_K_CPU0_SB_DQ<7>")
	)
	(segment
		(start 437.87568 -289.27171)
		(end 438.14365 -289.27171)
		(width 0.14478)
		(layer "In6.Cu")
		(net "M_K_CPU0_SB_DQ<7>")
	)
	(segment
		(start 441.10783 -289.416236)
		(end 441.251594 -289.272472)
		(width 0.14478)
		(layer "In6.Cu")
		(net "M_K_CPU0_SB_DQ<7>")
	)
	(segment
		(start 432.529234 -289.186112)
		(end 432.674014 -289.330892)
		(width 0.14478)
		(layer "In6.Cu")
		(net "M_K_CPU0_SB_DQ<7>")
	)
	(segment
		(start 392.24712 -278.629618)
		(end 392.257534 -278.623522)
		(width 0.0889)
		(layer "In6.Cu")
		(net "M_K_CPU0_SB_DQ<7>")
	)
	(segment
		(start 390.74344 -278.618696)
		(end 390.751822 -278.623522)
		(width 0.0889)
		(layer "In6.Cu")
		(net "M_K_CPU0_SB_DQ<7>")
	)
	(segment
		(start 433.142644 -289.560254)
		(end 433.992528 -290.410138)
		(width 0.14478)
		(layer "In6.Cu")
		(net "M_K_CPU0_SB_DQ<7>")
	)
	(segment
		(start 400.053302 -278.054816)
		(end 412.408878 -290.410392)
		(width 0.14478)
		(layer "In6.Cu")
		(net "M_K_CPU0_SB_DQ<7>")
	)
	(segment
		(start 394.740384 -278.235918)
		(end 395.168628 -278.235918)
		(width 0.0889)
		(layer "In6.Cu")
		(net "M_K_CPU0_SB_DQ<7>")
	)
	(segment
		(start 442.119258 -289.560254)
		(end 442.5442 -289.985196)
		(width 0.14478)
		(layer "In6.Cu")
		(net "M_K_CPU0_SB_DQ<7>")
	)
	(segment
		(start 440.70016 -289.848036)
		(end 440.964066 -289.848036)
		(width 0.14478)
		(layer "In6.Cu")
		(net "M_K_CPU0_SB_DQ<7>")
	)
	(segment
		(start 425.361608 -289.560254)
		(end 425.666662 -289.560254)
		(width 0.14478)
		(layer "In6.Cu")
		(net "M_K_CPU0_SB_DQ<7>")
	)
	(segment
		(start 438.14365 -289.27171)
		(end 438.432194 -289.560254)
		(width 0.14478)
		(layer "In6.Cu")
		(net "M_K_CPU0_SB_DQ<7>")
	)
	(segment
		(start 414.34131 -289.560254)
		(end 415.472626 -289.560254)
		(width 0.14478)
		(layer "In6.Cu")
		(net "M_K_CPU0_SB_DQ<7>")
	)
	(arc
		(start 389.493252 -278.59736)
		(mid 389.655441 -278.574625)
		(end 389.811768 -278.623522)
		(width 0.0889)
		(layer "In6.Cu")
		(net "M_K_CPU0_SB_DQ<7>")
	)
	(arc
		(start 393.197334 -278.623522)
		(mid 393.941525 -278.320917)
		(end 394.740384 -278.235918)
		(width 0.0889)
		(layer "In6.Cu")
		(net "M_K_CPU0_SB_DQ<7>")
	)
	(arc
		(start 391.691876 -278.623522)
		(mid 391.968689 -278.699665)
		(end 392.24712 -278.629618)
		(width 0.0889)
		(layer "In6.Cu")
		(net "M_K_CPU0_SB_DQ<7>")
	)
	(arc
		(start 389.811768 -278.623522)
		(mid 390.094724 -278.699699)
		(end 390.37768 -278.623522)
		(width 0.0889)
		(layer "In6.Cu")
		(net "M_K_CPU0_SB_DQ<7>")
	)
	(arc
		(start 390.751822 -278.623522)
		(mid 391.034778 -278.699699)
		(end 391.317734 -278.623522)
		(width 0.0889)
		(layer "In6.Cu")
		(net "M_K_CPU0_SB_DQ<7>")
	)
	(arc
		(start 392.641582 -278.629618)
		(mid 392.920268 -278.699838)
		(end 393.197334 -278.623522)
		(width 0.0889)
		(layer "In6.Cu")
		(net "M_K_CPU0_SB_DQ<7>")
	)
	(arc
		(start 390.37768 -278.623522)
		(mid 390.559931 -278.573172)
		(end 390.74344 -278.618696)
		(width 0.0889)
		(layer "In6.Cu")
		(net "M_K_CPU0_SB_DQ<7>")
	)
	(arc
		(start 392.265916 -278.618696)
		(mid 392.44917 -278.573323)
		(end 392.631168 -278.623522)
		(width 0.0889)
		(layer "In6.Cu")
		(net "M_K_CPU0_SB_DQ<7>")
	)
	(arc
		(start 391.326116 -278.618696)
		(mid 391.509624 -278.573202)
		(end 391.691876 -278.623522)
		(width 0.0889)
		(layer "In6.Cu")
		(net "M_K_CPU0_SB_DQ<7>")
	)
	(segment
		(start 390.567926 -277.870158)
		(end 391.034778 -278.136096)
		(width 0.10668)
		(layer "F.Cu")
		(net "M_K_CPU0_SB_DQ<6>")
	)
	(segment
		(start 438.181496 -287.56991)
		(end 438.447688 -287.56991)
		(width 0.14478)
		(layer "In6.Cu")
		(net "M_K_CPU0_SB_DQ<6>")
	)
	(segment
		(start 429.178212 -288.71037)
		(end 430.02835 -287.860232)
		(width 0.14478)
		(layer "In6.Cu")
		(net "M_K_CPU0_SB_DQ<6>")
	)
	(segment
		(start 439.57748 -288.005012)
		(end 439.57748 -288.091372)
		(width 0.14478)
		(layer "In6.Cu")
		(net "M_K_CPU0_SB_DQ<6>")
	)
	(segment
		(start 438.73801 -287.860232)
		(end 439.4327 -287.860232)
		(width 0.14478)
		(layer "In6.Cu")
		(net "M_K_CPU0_SB_DQ<6>")
	)
	(segment
		(start 441.376562 -287.484312)
		(end 441.638436 -287.484312)
		(width 0.14478)
		(layer "In6.Cu")
		(net "M_K_CPU0_SB_DQ<6>")
	)
	(segment
		(start 423.224198 -287.56991)
		(end 423.51452 -287.860232)
		(width 0.14478)
		(layer "In6.Cu")
		(net "M_K_CPU0_SB_DQ<6>")
	)
	(segment
		(start 414.669986 -287.860232)
		(end 418.352224 -287.860232)
		(width 0.14478)
		(layer "In6.Cu")
		(net "M_K_CPU0_SB_DQ<6>")
	)
	(segment
		(start 420.61892 -288.71037)
		(end 420.92118 -288.40811)
		(width 0.14478)
		(layer "In6.Cu")
		(net "M_K_CPU0_SB_DQ<6>")
	)
	(segment
		(start 412.202884 -288.40811)
		(end 412.505144 -288.71037)
		(width 0.14478)
		(layer "In6.Cu")
		(net "M_K_CPU0_SB_DQ<6>")
	)
	(segment
		(start 439.72226 -288.236152)
		(end 439.984134 -288.236152)
		(width 0.14478)
		(layer "In6.Cu")
		(net "M_K_CPU0_SB_DQ<6>")
	)
	(segment
		(start 425.463716 -287.860232)
		(end 425.55287 -287.860232)
		(width 0.14478)
		(layer "In6.Cu")
		(net "M_K_CPU0_SB_DQ<6>")
	)
	(segment
		(start 441.638436 -287.484312)
		(end 441.783216 -287.629092)
		(width 0.14478)
		(layer "In6.Cu")
		(net "M_K_CPU0_SB_DQ<6>")
	)
	(segment
		(start 422.484296 -287.860232)
		(end 422.667684 -287.860232)
		(width 0.14478)
		(layer "In6.Cu")
		(net "M_K_CPU0_SB_DQ<6>")
	)
	(segment
		(start 440.128914 -287.629092)
		(end 440.273694 -287.484312)
		(width 0.14478)
		(layer "In6.Cu")
		(net "M_K_CPU0_SB_DQ<6>")
	)
	(segment
		(start 391.034778 -278.136096)
		(end 390.880854 -277.870666)
		(width 0.0889)
		(layer "In6.Cu")
		(net "M_K_CPU0_SB_DQ<6>")
	)
	(segment
		(start 441.783216 -287.715452)
		(end 441.927996 -287.860232)
		(width 0.14478)
		(layer "In6.Cu")
		(net "M_K_CPU0_SB_DQ<6>")
	)
	(segment
		(start 433.80152 -288.710116)
		(end 435.541166 -288.710116)
		(width 0.14478)
		(layer "In6.Cu")
		(net "M_K_CPU0_SB_DQ<6>")
	)
	(segment
		(start 424.61688 -287.860232)
		(end 424.907202 -287.56991)
		(width 0.14478)
		(layer "In6.Cu")
		(net "M_K_CPU0_SB_DQ<6>")
	)
	(segment
		(start 424.907202 -287.56991)
		(end 425.173394 -287.56991)
		(width 0.14478)
		(layer "In6.Cu")
		(net "M_K_CPU0_SB_DQ<6>")
	)
	(segment
		(start 441.927996 -287.860232)
		(end 442.119258 -287.860232)
		(width 0.14478)
		(layer "In6.Cu")
		(net "M_K_CPU0_SB_DQ<6>")
	)
	(segment
		(start 412.505144 -288.71037)
		(end 412.759398 -288.71037)
		(width 0.14478)
		(layer "In6.Cu")
		(net "M_K_CPU0_SB_DQ<6>")
	)
	(segment
		(start 418.352224 -287.860232)
		(end 419.202362 -288.71037)
		(width 0.14478)
		(layer "In6.Cu")
		(net "M_K_CPU0_SB_DQ<6>")
	)
	(segment
		(start 411.75305 -288.40811)
		(end 412.202884 -288.40811)
		(width 0.14478)
		(layer "In6.Cu")
		(net "M_K_CPU0_SB_DQ<6>")
	)
	(segment
		(start 439.57748 -288.091372)
		(end 439.72226 -288.236152)
		(width 0.14478)
		(layer "In6.Cu")
		(net "M_K_CPU0_SB_DQ<6>")
	)
	(segment
		(start 390.880854 -277.870666)
		(end 390.903206 -277.787354)
		(width 0.0889)
		(layer "In6.Cu")
		(net "M_K_CPU0_SB_DQ<6>")
	)
	(segment
		(start 435.817772 -288.43351)
		(end 436.09768 -288.43351)
		(width 0.14478)
		(layer "In6.Cu")
		(net "M_K_CPU0_SB_DQ<6>")
	)
	(segment
		(start 413.819848 -288.71037)
		(end 414.669986 -287.860232)
		(width 0.14478)
		(layer "In6.Cu")
		(net "M_K_CPU0_SB_DQ<6>")
	)
	(segment
		(start 421.477694 -288.71037)
		(end 421.634158 -288.71037)
		(width 0.14478)
		(layer "In6.Cu")
		(net "M_K_CPU0_SB_DQ<6>")
	)
	(segment
		(start 436.09768 -288.43351)
		(end 436.374286 -288.710116)
		(width 0.14478)
		(layer "In6.Cu")
		(net "M_K_CPU0_SB_DQ<6>")
	)
	(segment
		(start 436.374286 -288.710116)
		(end 436.606188 -288.710116)
		(width 0.14478)
		(layer "In6.Cu")
		(net "M_K_CPU0_SB_DQ<6>")
	)
	(segment
		(start 427.855126 -288.71037)
		(end 428.131986 -288.43351)
		(width 0.14478)
		(layer "In6.Cu")
		(net "M_K_CPU0_SB_DQ<6>")
	)
	(segment
		(start 440.680348 -288.091372)
		(end 440.825128 -288.236152)
		(width 0.14478)
		(layer "In6.Cu")
		(net "M_K_CPU0_SB_DQ<6>")
	)
	(segment
		(start 394.298424 -276.99335)
		(end 395.508734 -276.99335)
		(width 0.0889)
		(layer "In6.Cu")
		(net "M_K_CPU0_SB_DQ<6>")
	)
	(segment
		(start 425.55287 -287.860232)
		(end 426.403008 -288.71037)
		(width 0.14478)
		(layer "In6.Cu")
		(net "M_K_CPU0_SB_DQ<6>")
	)
	(segment
		(start 395.66088 -277.145496)
		(end 395.938502 -277.145496)
		(width 0.0889)
		(layer "In6.Cu")
		(net "M_K_CPU0_SB_DQ<6>")
	)
	(segment
		(start 421.634158 -288.71037)
		(end 422.484296 -287.860232)
		(width 0.14478)
		(layer "In6.Cu")
		(net "M_K_CPU0_SB_DQ<6>")
	)
	(segment
		(start 412.759398 -288.71037)
		(end 413.061658 -288.40811)
		(width 0.14478)
		(layer "In6.Cu")
		(net "M_K_CPU0_SB_DQ<6>")
	)
	(segment
		(start 400.490436 -277.145496)
		(end 411.75305 -288.40811)
		(width 0.14478)
		(layer "In6.Cu")
		(net "M_K_CPU0_SB_DQ<6>")
	)
	(segment
		(start 441.087002 -288.236152)
		(end 441.231782 -288.091372)
		(width 0.14478)
		(layer "In6.Cu")
		(net "M_K_CPU0_SB_DQ<6>")
	)
	(segment
		(start 440.273694 -287.484312)
		(end 440.535568 -287.484312)
		(width 0.14478)
		(layer "In6.Cu")
		(net "M_K_CPU0_SB_DQ<6>")
	)
	(segment
		(start 395.508734 -276.99335)
		(end 395.66088 -277.145496)
		(width 0.0889)
		(layer "In6.Cu")
		(net "M_K_CPU0_SB_DQ<6>")
	)
	(segment
		(start 423.51452 -287.860232)
		(end 424.61688 -287.860232)
		(width 0.14478)
		(layer "In6.Cu")
		(net "M_K_CPU0_SB_DQ<6>")
	)
	(segment
		(start 432.951636 -287.860232)
		(end 433.80152 -288.710116)
		(width 0.14478)
		(layer "In6.Cu")
		(net "M_K_CPU0_SB_DQ<6>")
	)
	(segment
		(start 437.456072 -287.860232)
		(end 437.891174 -287.860232)
		(width 0.14478)
		(layer "In6.Cu")
		(net "M_K_CPU0_SB_DQ<6>")
	)
	(segment
		(start 413.315912 -288.40811)
		(end 413.618172 -288.71037)
		(width 0.14478)
		(layer "In6.Cu")
		(net "M_K_CPU0_SB_DQ<6>")
	)
	(segment
		(start 442.119258 -287.860232)
		(end 442.5442 -288.285174)
		(width 0.14478)
		(layer "In6.Cu")
		(net "M_K_CPU0_SB_DQ<6>")
	)
	(segment
		(start 422.958006 -287.56991)
		(end 423.224198 -287.56991)
		(width 0.14478)
		(layer "In6.Cu")
		(net "M_K_CPU0_SB_DQ<6>")
	)
	(segment
		(start 441.783216 -287.629092)
		(end 441.783216 -287.715452)
		(width 0.14478)
		(layer "In6.Cu")
		(net "M_K_CPU0_SB_DQ<6>")
	)
	(segment
		(start 441.231782 -287.629092)
		(end 441.376562 -287.484312)
		(width 0.14478)
		(layer "In6.Cu")
		(net "M_K_CPU0_SB_DQ<6>")
	)
	(segment
		(start 435.541166 -288.710116)
		(end 435.817772 -288.43351)
		(width 0.14478)
		(layer "In6.Cu")
		(net "M_K_CPU0_SB_DQ<6>")
	)
	(segment
		(start 420.92118 -288.40811)
		(end 421.175434 -288.40811)
		(width 0.14478)
		(layer "In6.Cu")
		(net "M_K_CPU0_SB_DQ<6>")
	)
	(segment
		(start 438.447688 -287.56991)
		(end 438.73801 -287.860232)
		(width 0.14478)
		(layer "In6.Cu")
		(net "M_K_CPU0_SB_DQ<6>")
	)
	(segment
		(start 428.131986 -288.43351)
		(end 428.41164 -288.43351)
		(width 0.14478)
		(layer "In6.Cu")
		(net "M_K_CPU0_SB_DQ<6>")
	)
	(segment
		(start 419.202362 -288.71037)
		(end 420.61892 -288.71037)
		(width 0.14478)
		(layer "In6.Cu")
		(net "M_K_CPU0_SB_DQ<6>")
	)
	(segment
		(start 439.4327 -287.860232)
		(end 439.57748 -288.005012)
		(width 0.14478)
		(layer "In6.Cu")
		(net "M_K_CPU0_SB_DQ<6>")
	)
	(segment
		(start 441.231782 -288.091372)
		(end 441.231782 -287.629092)
		(width 0.14478)
		(layer "In6.Cu")
		(net "M_K_CPU0_SB_DQ<6>")
	)
	(segment
		(start 425.173394 -287.56991)
		(end 425.463716 -287.860232)
		(width 0.14478)
		(layer "In6.Cu")
		(net "M_K_CPU0_SB_DQ<6>")
	)
	(segment
		(start 392.161776 -277.813516)
		(end 392.17219 -277.819612)
		(width 0.0889)
		(layer "In6.Cu")
		(net "M_K_CPU0_SB_DQ<6>")
	)
	(segment
		(start 430.02835 -287.860232)
		(end 432.951636 -287.860232)
		(width 0.14478)
		(layer "In6.Cu")
		(net "M_K_CPU0_SB_DQ<6>")
	)
	(segment
		(start 428.41164 -288.43351)
		(end 428.6885 -288.71037)
		(width 0.14478)
		(layer "In6.Cu")
		(net "M_K_CPU0_SB_DQ<6>")
	)
	(segment
		(start 413.618172 -288.71037)
		(end 413.819848 -288.71037)
		(width 0.14478)
		(layer "In6.Cu")
		(net "M_K_CPU0_SB_DQ<6>")
	)
	(segment
		(start 395.938502 -277.145496)
		(end 400.490436 -277.145496)
		(width 0.14478)
		(layer "In6.Cu")
		(net "M_K_CPU0_SB_DQ<6>")
	)
	(segment
		(start 393.795504 -277.74646)
		(end 393.880848 -277.667466)
		(width 0.0889)
		(layer "In6.Cu")
		(net "M_K_CPU0_SB_DQ<6>")
	)
	(segment
		(start 440.128914 -288.091372)
		(end 440.128914 -287.629092)
		(width 0.14478)
		(layer "In6.Cu")
		(net "M_K_CPU0_SB_DQ<6>")
	)
	(segment
		(start 428.6885 -288.71037)
		(end 429.178212 -288.71037)
		(width 0.14478)
		(layer "In6.Cu")
		(net "M_K_CPU0_SB_DQ<6>")
	)
	(segment
		(start 413.061658 -288.40811)
		(end 413.315912 -288.40811)
		(width 0.14478)
		(layer "In6.Cu")
		(net "M_K_CPU0_SB_DQ<6>")
	)
	(segment
		(start 437.891174 -287.860232)
		(end 438.181496 -287.56991)
		(width 0.14478)
		(layer "In6.Cu")
		(net "M_K_CPU0_SB_DQ<6>")
	)
	(segment
		(start 392.153394 -277.80869)
		(end 392.161776 -277.813516)
		(width 0.0889)
		(layer "In6.Cu")
		(net "M_K_CPU0_SB_DQ<6>")
	)
	(segment
		(start 422.667684 -287.860232)
		(end 422.958006 -287.56991)
		(width 0.14478)
		(layer "In6.Cu")
		(net "M_K_CPU0_SB_DQ<6>")
	)
	(segment
		(start 436.606188 -288.710116)
		(end 437.456072 -287.860232)
		(width 0.14478)
		(layer "In6.Cu")
		(net "M_K_CPU0_SB_DQ<6>")
	)
	(segment
		(start 440.680348 -287.629092)
		(end 440.680348 -288.091372)
		(width 0.14478)
		(layer "In6.Cu")
		(net "M_K_CPU0_SB_DQ<6>")
	)
	(segment
		(start 439.984134 -288.236152)
		(end 440.128914 -288.091372)
		(width 0.14478)
		(layer "In6.Cu")
		(net "M_K_CPU0_SB_DQ<6>")
	)
	(segment
		(start 421.175434 -288.40811)
		(end 421.477694 -288.71037)
		(width 0.14478)
		(layer "In6.Cu")
		(net "M_K_CPU0_SB_DQ<6>")
	)
	(segment
		(start 440.825128 -288.236152)
		(end 441.087002 -288.236152)
		(width 0.14478)
		(layer "In6.Cu")
		(net "M_K_CPU0_SB_DQ<6>")
	)
	(segment
		(start 392.727434 -277.813516)
		(end 392.735816 -277.80869)
		(width 0.0889)
		(layer "In6.Cu")
		(net "M_K_CPU0_SB_DQ<6>")
	)
	(segment
		(start 426.403008 -288.71037)
		(end 427.855126 -288.71037)
		(width 0.14478)
		(layer "In6.Cu")
		(net "M_K_CPU0_SB_DQ<6>")
	)
	(segment
		(start 440.535568 -287.484312)
		(end 440.680348 -287.629092)
		(width 0.14478)
		(layer "In6.Cu")
		(net "M_K_CPU0_SB_DQ<6>")
	)
	(arc
		(start 391.221722 -277.813516)
		(mid 391.504678 -277.889693)
		(end 391.787634 -277.813516)
		(width 0.0889)
		(layer "In6.Cu")
		(net "M_K_CPU0_SB_DQ<6>")
	)
	(arc
		(start 394.007594 -277.351744)
		(mid 394.03034 -277.216088)
		(end 394.11021 -277.104094)
		(width 0.0889)
		(layer "In6.Cu")
		(net "M_K_CPU0_SB_DQ<6>")
	)
	(arc
		(start 392.735816 -277.80869)
		(mid 392.919324 -277.763196)
		(end 393.101576 -277.813516)
		(width 0.0889)
		(layer "In6.Cu")
		(net "M_K_CPU0_SB_DQ<6>")
	)
	(arc
		(start 390.903206 -277.787354)
		(mid 391.065395 -277.764619)
		(end 391.221722 -277.813516)
		(width 0.0889)
		(layer "In6.Cu")
		(net "M_K_CPU0_SB_DQ<6>")
	)
	(arc
		(start 393.880848 -277.667466)
		(mid 393.97967 -277.523846)
		(end 394.007594 -277.351744)
		(width 0.0889)
		(layer "In6.Cu")
		(net "M_K_CPU0_SB_DQ<6>")
	)
	(arc
		(start 394.11021 -277.104094)
		(mid 394.198972 -277.039638)
		(end 394.298424 -276.99335)
		(width 0.0889)
		(layer "In6.Cu")
		(net "M_K_CPU0_SB_DQ<6>")
	)
	(arc
		(start 392.17219 -277.819612)
		(mid 392.450622 -277.88971)
		(end 392.727434 -277.813516)
		(width 0.0889)
		(layer "In6.Cu")
		(net "M_K_CPU0_SB_DQ<6>")
	)
	(arc
		(start 391.787634 -277.813516)
		(mid 391.969885 -277.763166)
		(end 392.153394 -277.80869)
		(width 0.0889)
		(layer "In6.Cu")
		(net "M_K_CPU0_SB_DQ<6>")
	)
	(arc
		(start 393.101576 -277.813516)
		(mid 393.262195 -277.878518)
		(end 393.43457 -277.896066)
		(width 0.0889)
		(layer "In6.Cu")
		(net "M_K_CPU0_SB_DQ<6>")
	)
	(arc
		(start 393.43457 -277.896066)
		(mid 393.628392 -277.853483)
		(end 393.795504 -277.74646)
		(width 0.0889)
		(layer "In6.Cu")
		(net "M_K_CPU0_SB_DQ<6>")
	)
	(segment
		(start 388.688072 -277.870158)
		(end 389.154924 -278.136096)
		(width 0.10668)
		(layer "F.Cu")
		(net "M_K_CPU0_SB_DQ<5>")
	)
	(segment
		(start 395.394434 -277.50643)
		(end 395.48816 -277.600156)
		(width 0.0889)
		(layer "In6.Cu")
		(net "M_K_CPU0_SB_DQ<5>")
	)
	(segment
		(start 415.144712 -288.71037)
		(end 417.658296 -288.71037)
		(width 0.14478)
		(layer "In6.Cu")
		(net "M_K_CPU0_SB_DQ<5>")
	)
	(segment
		(start 394.75537 -277.50643)
		(end 395.394434 -277.50643)
		(width 0.0889)
		(layer "In6.Cu")
		(net "M_K_CPU0_SB_DQ<5>")
	)
	(segment
		(start 430.12106 -288.71037)
		(end 432.99126 -288.71037)
		(width 0.14478)
		(layer "In6.Cu")
		(net "M_K_CPU0_SB_DQ<5>")
	)
	(segment
		(start 389.90778 -278.458676)
		(end 389.916162 -278.463502)
		(width 0.0889)
		(layer "In6.Cu")
		(net "M_K_CPU0_SB_DQ<5>")
	)
	(segment
		(start 425.601638 -288.71037)
		(end 426.451522 -289.560254)
		(width 0.14478)
		(layer "In6.Cu")
		(net "M_K_CPU0_SB_DQ<5>")
	)
	(segment
		(start 435.771798 -289.560254)
		(end 437.823864 -288.71037)
		(width 0.14478)
		(layer "In6.Cu")
		(net "M_K_CPU0_SB_DQ<5>")
	)
	(segment
		(start 392.149838 -278.465534)
		(end 392.161522 -278.458676)
		(width 0.0889)
		(layer "In6.Cu")
		(net "M_K_CPU0_SB_DQ<5>")
	)
	(segment
		(start 417.658296 -288.71037)
		(end 419.710108 -289.560254)
		(width 0.14478)
		(layer "In6.Cu")
		(net "M_K_CPU0_SB_DQ<5>")
	)
	(segment
		(start 422.577006 -288.71037)
		(end 425.601638 -288.71037)
		(width 0.14478)
		(layer "In6.Cu")
		(net "M_K_CPU0_SB_DQ<5>")
	)
	(segment
		(start 395.48816 -277.600156)
		(end 395.943074 -277.600156)
		(width 0.0889)
		(layer "In6.Cu")
		(net "M_K_CPU0_SB_DQ<5>")
	)
	(segment
		(start 392.161522 -278.458676)
		(end 392.171936 -278.45258)
		(width 0.0889)
		(layer "In6.Cu")
		(net "M_K_CPU0_SB_DQ<5>")
	)
	(segment
		(start 393.101576 -278.458676)
		(end 394.75537 -277.50643)
		(width 0.0889)
		(layer "In6.Cu")
		(net "M_K_CPU0_SB_DQ<5>")
	)
	(segment
		(start 395.943074 -277.600156)
		(end 400.242024 -277.600156)
		(width 0.14478)
		(layer "In6.Cu")
		(net "M_K_CPU0_SB_DQ<5>")
	)
	(segment
		(start 412.202122 -289.560254)
		(end 413.0929 -289.560254)
		(width 0.14478)
		(layer "In6.Cu")
		(net "M_K_CPU0_SB_DQ<5>")
	)
	(segment
		(start 389.308848 -278.401526)
		(end 389.40486 -278.426926)
		(width 0.0889)
		(layer "In6.Cu")
		(net "M_K_CPU0_SB_DQ<5>")
	)
	(segment
		(start 419.710108 -289.560254)
		(end 421.727122 -289.560254)
		(width 0.14478)
		(layer "In6.Cu")
		(net "M_K_CPU0_SB_DQ<5>")
	)
	(segment
		(start 421.727122 -289.560254)
		(end 422.577006 -288.71037)
		(width 0.14478)
		(layer "In6.Cu")
		(net "M_K_CPU0_SB_DQ<5>")
	)
	(segment
		(start 429.271176 -289.560254)
		(end 430.12106 -288.71037)
		(width 0.14478)
		(layer "In6.Cu")
		(net "M_K_CPU0_SB_DQ<5>")
	)
	(segment
		(start 400.242024 -277.600156)
		(end 412.202122 -289.560254)
		(width 0.14478)
		(layer "In6.Cu")
		(net "M_K_CPU0_SB_DQ<5>")
	)
	(segment
		(start 392.72718 -278.458676)
		(end 392.738864 -278.465534)
		(width 0.0889)
		(layer "In6.Cu")
		(net "M_K_CPU0_SB_DQ<5>")
	)
	(segment
		(start 389.154924 -278.136096)
		(end 389.308848 -278.401526)
		(width 0.0889)
		(layer "In6.Cu")
		(net "M_K_CPU0_SB_DQ<5>")
	)
	(segment
		(start 432.99126 -288.71037)
		(end 433.841144 -289.560254)
		(width 0.14478)
		(layer "In6.Cu")
		(net "M_K_CPU0_SB_DQ<5>")
	)
	(segment
		(start 426.451522 -289.560254)
		(end 429.271176 -289.560254)
		(width 0.14478)
		(layer "In6.Cu")
		(net "M_K_CPU0_SB_DQ<5>")
	)
	(segment
		(start 433.841144 -289.560254)
		(end 435.771798 -289.560254)
		(width 0.14478)
		(layer "In6.Cu")
		(net "M_K_CPU0_SB_DQ<5>")
	)
	(segment
		(start 444.50889 -288.71037)
		(end 446.644268 -289.135058)
		(width 0.14478)
		(layer "In6.Cu")
		(net "M_K_CPU0_SB_DQ<5>")
	)
	(segment
		(start 413.0929 -289.560254)
		(end 415.144712 -288.71037)
		(width 0.14478)
		(layer "In6.Cu")
		(net "M_K_CPU0_SB_DQ<5>")
	)
	(segment
		(start 437.823864 -288.71037)
		(end 444.50889 -288.71037)
		(width 0.14478)
		(layer "In6.Cu")
		(net "M_K_CPU0_SB_DQ<5>")
	)
	(arc
		(start 389.916162 -278.463502)
		(mid 390.09967 -278.508996)
		(end 390.281922 -278.458676)
		(width 0.0889)
		(layer "In6.Cu")
		(net "M_K_CPU0_SB_DQ<5>")
	)
	(arc
		(start 392.171936 -278.45258)
		(mid 392.450368 -278.382482)
		(end 392.72718 -278.458676)
		(width 0.0889)
		(layer "In6.Cu")
		(net "M_K_CPU0_SB_DQ<5>")
	)
	(arc
		(start 392.738864 -278.465534)
		(mid 392.921119 -278.509187)
		(end 393.101576 -278.458676)
		(width 0.0889)
		(layer "In6.Cu")
		(net "M_K_CPU0_SB_DQ<5>")
	)
	(arc
		(start 391.787634 -278.458676)
		(mid 391.967839 -278.508993)
		(end 392.149838 -278.465534)
		(width 0.0889)
		(layer "In6.Cu")
		(net "M_K_CPU0_SB_DQ<5>")
	)
	(arc
		(start 390.281922 -278.458676)
		(mid 390.564878 -278.382499)
		(end 390.847834 -278.458676)
		(width 0.0889)
		(layer "In6.Cu")
		(net "M_K_CPU0_SB_DQ<5>")
	)
	(arc
		(start 389.40486 -278.426926)
		(mid 389.660068 -278.383449)
		(end 389.90778 -278.458676)
		(width 0.0889)
		(layer "In6.Cu")
		(net "M_K_CPU0_SB_DQ<5>")
	)
	(arc
		(start 391.221722 -278.458676)
		(mid 391.504678 -278.382499)
		(end 391.787634 -278.458676)
		(width 0.0889)
		(layer "In6.Cu")
		(net "M_K_CPU0_SB_DQ<5>")
	)
	(arc
		(start 390.847834 -278.458676)
		(mid 391.034778 -278.508931)
		(end 391.221722 -278.458676)
		(width 0.0889)
		(layer "In6.Cu")
		(net "M_K_CPU0_SB_DQ<5>")
	)
	(segment
		(start 390.098026 -277.060152)
		(end 390.564878 -277.32609)
		(width 0.10668)
		(layer "F.Cu")
		(net "M_K_CPU0_SB_DQ<4>")
	)
	(segment
		(start 413.983932 -287.860232)
		(end 414.441132 -287.403032)
		(width 0.14478)
		(layer "In6.Cu")
		(net "M_K_CPU0_SB_DQ<4>")
	)
	(segment
		(start 395.331188 -276.690836)
		(end 395.971776 -276.690836)
		(width 0.0889)
		(layer "In6.Cu")
		(net "M_K_CPU0_SB_DQ<4>")
	)
	(segment
		(start 445.499236 -287.385252)
		(end 445.499236 -287.164272)
		(width 0.14478)
		(layer "In6.Cu")
		(net "M_K_CPU0_SB_DQ<4>")
	)
	(segment
		(start 444.947802 -287.385252)
		(end 445.092582 -287.530032)
		(width 0.14478)
		(layer "In6.Cu")
		(net "M_K_CPU0_SB_DQ<4>")
	)
	(segment
		(start 392.24712 -277.642574)
		(end 392.257534 -277.64867)
		(width 0.0889)
		(layer "In6.Cu")
		(net "M_K_CPU0_SB_DQ<4>")
	)
	(segment
		(start 422.567608 -287.019746)
		(end 425.390564 -287.019746)
		(width 0.14478)
		(layer "In6.Cu")
		(net "M_K_CPU0_SB_DQ<4>")
	)
	(segment
		(start 393.789154 -277.25751)
		(end 393.876276 -277.054056)
		(width 0.0889)
		(layer "In6.Cu")
		(net "M_K_CPU0_SB_DQ<4>")
	)
	(segment
		(start 444.947802 -287.164272)
		(end 444.947802 -287.385252)
		(width 0.14478)
		(layer "In6.Cu")
		(net "M_K_CPU0_SB_DQ<4>")
	)
	(segment
		(start 400.678904 -276.690836)
		(end 411.8483 -287.860232)
		(width 0.14478)
		(layer "In6.Cu")
		(net "M_K_CPU0_SB_DQ<4>")
	)
	(segment
		(start 418.563552 -287.403032)
		(end 419.03015 -287.86963)
		(width 0.14478)
		(layer "In6.Cu")
		(net "M_K_CPU0_SB_DQ<4>")
	)
	(segment
		(start 429.261778 -287.86963)
		(end 430.111662 -287.019746)
		(width 0.14478)
		(layer "In6.Cu")
		(net "M_K_CPU0_SB_DQ<4>")
	)
	(segment
		(start 390.718802 -277.59152)
		(end 390.814814 -277.61692)
		(width 0.0889)
		(layer "In6.Cu")
		(net "M_K_CPU0_SB_DQ<4>")
	)
	(segment
		(start 411.8483 -287.860232)
		(end 413.983932 -287.860232)
		(width 0.14478)
		(layer "In6.Cu")
		(net "M_K_CPU0_SB_DQ<4>")
	)
	(segment
		(start 391.317734 -277.64867)
		(end 391.326116 -277.653496)
		(width 0.0889)
		(layer "In6.Cu")
		(net "M_K_CPU0_SB_DQ<4>")
	)
	(segment
		(start 433.796694 -287.86963)
		(end 436.642002 -287.86963)
		(width 0.14478)
		(layer "In6.Cu")
		(net "M_K_CPU0_SB_DQ<4>")
	)
	(segment
		(start 445.499236 -287.164272)
		(end 445.644016 -287.019492)
		(width 0.14478)
		(layer "In6.Cu")
		(net "M_K_CPU0_SB_DQ<4>")
	)
	(segment
		(start 436.642002 -287.86963)
		(end 437.49214 -287.019492)
		(width 0.14478)
		(layer "In6.Cu")
		(net "M_K_CPU0_SB_DQ<4>")
	)
	(segment
		(start 425.390564 -287.019746)
		(end 426.240448 -287.86963)
		(width 0.14478)
		(layer "In6.Cu")
		(net "M_K_CPU0_SB_DQ<4>")
	)
	(segment
		(start 392.631422 -277.64867)
		(end 392.641836 -277.642574)
		(width 0.0889)
		(layer "In6.Cu")
		(net "M_K_CPU0_SB_DQ<4>")
	)
	(segment
		(start 437.49214 -287.019492)
		(end 444.803022 -287.019492)
		(width 0.14478)
		(layer "In6.Cu")
		(net "M_K_CPU0_SB_DQ<4>")
	)
	(segment
		(start 446.228724 -287.019492)
		(end 446.644268 -287.435036)
		(width 0.14478)
		(layer "In6.Cu")
		(net "M_K_CPU0_SB_DQ<4>")
	)
	(segment
		(start 445.354456 -287.530032)
		(end 445.499236 -287.385252)
		(width 0.14478)
		(layer "In6.Cu")
		(net "M_K_CPU0_SB_DQ<4>")
	)
	(segment
		(start 390.564878 -277.32609)
		(end 390.718802 -277.59152)
		(width 0.0889)
		(layer "In6.Cu")
		(net "M_K_CPU0_SB_DQ<4>")
	)
	(segment
		(start 430.111662 -287.019746)
		(end 432.94681 -287.019746)
		(width 0.14478)
		(layer "In6.Cu")
		(net "M_K_CPU0_SB_DQ<4>")
	)
	(segment
		(start 395.971776 -276.690836)
		(end 400.678904 -276.690836)
		(width 0.14478)
		(layer "In6.Cu")
		(net "M_K_CPU0_SB_DQ<4>")
	)
	(segment
		(start 432.94681 -287.019746)
		(end 433.796694 -287.86963)
		(width 0.14478)
		(layer "In6.Cu")
		(net "M_K_CPU0_SB_DQ<4>")
	)
	(segment
		(start 444.803022 -287.019492)
		(end 444.947802 -287.164272)
		(width 0.14478)
		(layer "In6.Cu")
		(net "M_K_CPU0_SB_DQ<4>")
	)
	(segment
		(start 445.092582 -287.530032)
		(end 445.354456 -287.530032)
		(width 0.14478)
		(layer "In6.Cu")
		(net "M_K_CPU0_SB_DQ<4>")
	)
	(segment
		(start 445.644016 -287.019492)
		(end 446.228724 -287.019492)
		(width 0.14478)
		(layer "In6.Cu")
		(net "M_K_CPU0_SB_DQ<4>")
	)
	(segment
		(start 419.03015 -287.86963)
		(end 421.717724 -287.86963)
		(width 0.14478)
		(layer "In6.Cu")
		(net "M_K_CPU0_SB_DQ<4>")
	)
	(segment
		(start 395.310614 -276.71141)
		(end 395.331188 -276.690836)
		(width 0.0889)
		(layer "In6.Cu")
		(net "M_K_CPU0_SB_DQ<4>")
	)
	(segment
		(start 421.717724 -287.86963)
		(end 422.567608 -287.019746)
		(width 0.14478)
		(layer "In6.Cu")
		(net "M_K_CPU0_SB_DQ<4>")
	)
	(segment
		(start 426.240448 -287.86963)
		(end 429.261778 -287.86963)
		(width 0.14478)
		(layer "In6.Cu")
		(net "M_K_CPU0_SB_DQ<4>")
	)
	(segment
		(start 414.441132 -287.403032)
		(end 418.563552 -287.403032)
		(width 0.14478)
		(layer "In6.Cu")
		(net "M_K_CPU0_SB_DQ<4>")
	)
	(segment
		(start 394.412978 -276.71141)
		(end 395.310614 -276.71141)
		(width 0.0889)
		(layer "In6.Cu")
		(net "M_K_CPU0_SB_DQ<4>")
	)
	(arc
		(start 391.326116 -277.653496)
		(mid 391.509624 -277.69899)
		(end 391.691876 -277.64867)
		(width 0.0889)
		(layer "In6.Cu")
		(net "M_K_CPU0_SB_DQ<4>")
	)
	(arc
		(start 393.930124 -276.96922)
		(mid 393.977959 -276.918503)
		(end 394.028676 -276.870668)
		(width 0.0889)
		(layer "In6.Cu")
		(net "M_K_CPU0_SB_DQ<4>")
	)
	(arc
		(start 390.814814 -277.61692)
		(mid 391.070022 -277.573443)
		(end 391.317734 -277.64867)
		(width 0.0889)
		(layer "In6.Cu")
		(net "M_K_CPU0_SB_DQ<4>")
	)
	(arc
		(start 393.876276 -277.054056)
		(mid 393.899791 -277.009476)
		(end 393.930124 -276.96922)
		(width 0.0889)
		(layer "In6.Cu")
		(net "M_K_CPU0_SB_DQ<4>")
	)
	(arc
		(start 393.761722 -277.35657)
		(mid 393.772113 -277.306119)
		(end 393.789154 -277.25751)
		(width 0.0889)
		(layer "In6.Cu")
		(net "M_K_CPU0_SB_DQ<4>")
	)
	(arc
		(start 392.641836 -277.642574)
		(mid 392.915229 -277.572321)
		(end 393.188444 -277.643336)
		(width 0.0889)
		(layer "In6.Cu")
		(net "M_K_CPU0_SB_DQ<4>")
	)
	(arc
		(start 393.188444 -277.643336)
		(mid 393.550829 -277.651284)
		(end 393.761722 -277.35657)
		(width 0.0889)
		(layer "In6.Cu")
		(net "M_K_CPU0_SB_DQ<4>")
	)
	(arc
		(start 394.028676 -276.870668)
		(mid 394.207396 -276.758618)
		(end 394.412978 -276.71141)
		(width 0.0889)
		(layer "In6.Cu")
		(net "M_K_CPU0_SB_DQ<4>")
	)
	(arc
		(start 391.691876 -277.64867)
		(mid 391.968689 -277.572527)
		(end 392.24712 -277.642574)
		(width 0.0889)
		(layer "In6.Cu")
		(net "M_K_CPU0_SB_DQ<4>")
	)
	(arc
		(start 392.257534 -277.64867)
		(mid 392.444478 -277.698925)
		(end 392.631422 -277.64867)
		(width 0.0889)
		(layer "In6.Cu")
		(net "M_K_CPU0_SB_DQ<4>")
	)
	(segment
		(start 389.157972 -275.44014)
		(end 389.624824 -275.706078)
		(width 0.10668)
		(layer "F.Cu")
		(net "M_K_CPU0_SB_DQ<3>")
	)
	(segment
		(start 417.342828 -283.600652)
		(end 417.61537 -283.32811)
		(width 0.14478)
		(layer "In6.Cu")
		(net "M_K_CPU0_SB_DQ<3>")
	)
	(segment
		(start 433.139596 -283.53893)
		(end 434.051456 -284.45079)
		(width 0.14478)
		(layer "In6.Cu")
		(net "M_K_CPU0_SB_DQ<3>")
	)
	(segment
		(start 437.516524 -283.61005)
		(end 437.798464 -283.32811)
		(width 0.14478)
		(layer "In6.Cu")
		(net "M_K_CPU0_SB_DQ<3>")
	)
	(segment
		(start 422.961308 -283.30271)
		(end 423.25925 -283.600652)
		(width 0.14478)
		(layer "In6.Cu")
		(net "M_K_CPU0_SB_DQ<3>")
	)
	(segment
		(start 421.637968 -283.61005)
		(end 422.404794 -283.61005)
		(width 0.14478)
		(layer "In6.Cu")
		(net "M_K_CPU0_SB_DQ<3>")
	)
	(segment
		(start 418.701474 -283.631132)
		(end 418.616638 -283.715968)
		(width 0.14478)
		(layer "In6.Cu")
		(net "M_K_CPU0_SB_DQ<3>")
	)
	(segment
		(start 430.228756 -283.61005)
		(end 430.536096 -283.30271)
		(width 0.14478)
		(layer "In6.Cu")
		(net "M_K_CPU0_SB_DQ<3>")
	)
	(segment
		(start 441.372498 -283.32811)
		(end 441.647072 -283.32811)
		(width 0.14478)
		(layer "In6.Cu")
		(net "M_K_CPU0_SB_DQ<3>")
	)
	(segment
		(start 416.776916 -283.32811)
		(end 417.049458 -283.600652)
		(width 0.14478)
		(layer "In6.Cu")
		(net "M_K_CPU0_SB_DQ<3>")
	)
	(segment
		(start 392.631168 -275.383498)
		(end 392.641582 -275.389594)
		(width 0.0889)
		(layer "In6.Cu")
		(net "M_K_CPU0_SB_DQ<3>")
	)
	(segment
		(start 428.006256 -284.45079)
		(end 428.151036 -284.30601)
		(width 0.14478)
		(layer "In6.Cu")
		(net "M_K_CPU0_SB_DQ<3>")
	)
	(segment
		(start 419.006782 -284.106112)
		(end 419.091618 -284.021276)
		(width 0.14478)
		(layer "In6.Cu")
		(net "M_K_CPU0_SB_DQ<3>")
	)
	(segment
		(start 394.005308 -274.981416)
		(end 394.691108 -274.295616)
		(width 0.0889)
		(layer "In6.Cu")
		(net "M_K_CPU0_SB_DQ<3>")
	)
	(segment
		(start 393.758674 -275.106892)
		(end 393.921996 -275.039582)
		(width 0.0889)
		(layer "In6.Cu")
		(net "M_K_CPU0_SB_DQ<3>")
	)
	(segment
		(start 401.600924 -274.30349)
		(end 411.757622 -284.460188)
		(width 0.14478)
		(layer "In6.Cu")
		(net "M_K_CPU0_SB_DQ<3>")
	)
	(segment
		(start 419.296342 -284.021276)
		(end 419.725856 -284.45079)
		(width 0.14478)
		(layer "In6.Cu")
		(net "M_K_CPU0_SB_DQ<3>")
	)
	(segment
		(start 394.782548 -274.25777)
		(end 395.644116 -274.25777)
		(width 0.0889)
		(layer "In6.Cu")
		(net "M_K_CPU0_SB_DQ<3>")
	)
	(segment
		(start 422.712134 -283.30271)
		(end 422.961308 -283.30271)
		(width 0.14478)
		(layer "In6.Cu")
		(net "M_K_CPU0_SB_DQ<3>")
	)
	(segment
		(start 413.071564 -284.16631)
		(end 413.365442 -284.460188)
		(width 0.14478)
		(layer "In6.Cu")
		(net "M_K_CPU0_SB_DQ<3>")
	)
	(segment
		(start 442.119258 -283.61005)
		(end 442.5442 -284.034992)
		(width 0.14478)
		(layer "In6.Cu")
		(net "M_K_CPU0_SB_DQ<3>")
	)
	(segment
		(start 430.536096 -283.30271)
		(end 430.78527 -283.30271)
		(width 0.14478)
		(layer "In6.Cu")
		(net "M_K_CPU0_SB_DQ<3>")
	)
	(segment
		(start 395.689836 -274.30349)
		(end 396.000224 -274.30349)
		(width 0.0889)
		(layer "In6.Cu")
		(net "M_K_CPU0_SB_DQ<3>")
	)
	(segment
		(start 431.951892 -283.600652)
		(end 432.249834 -283.30271)
		(width 0.14478)
		(layer "In6.Cu")
		(net "M_K_CPU0_SB_DQ<3>")
	)
	(segment
		(start 438.34558 -283.600652)
		(end 439.986928 -283.600652)
		(width 0.14478)
		(layer "In6.Cu")
		(net "M_K_CPU0_SB_DQ<3>")
	)
	(segment
		(start 437.798464 -283.32811)
		(end 438.073038 -283.32811)
		(width 0.14478)
		(layer "In6.Cu")
		(net "M_K_CPU0_SB_DQ<3>")
	)
	(segment
		(start 441.929012 -283.61005)
		(end 442.119258 -283.61005)
		(width 0.14478)
		(layer "In6.Cu")
		(net "M_K_CPU0_SB_DQ<3>")
	)
	(segment
		(start 440.25947 -283.32811)
		(end 440.534044 -283.32811)
		(width 0.14478)
		(layer "In6.Cu")
		(net "M_K_CPU0_SB_DQ<3>")
	)
	(segment
		(start 417.049458 -283.600652)
		(end 417.342828 -283.600652)
		(width 0.14478)
		(layer "In6.Cu")
		(net "M_K_CPU0_SB_DQ<3>")
	)
	(segment
		(start 430.78527 -283.30271)
		(end 431.083212 -283.600652)
		(width 0.14478)
		(layer "In6.Cu")
		(net "M_K_CPU0_SB_DQ<3>")
	)
	(segment
		(start 429.933862 -283.61005)
		(end 430.228756 -283.61005)
		(width 0.14478)
		(layer "In6.Cu")
		(net "M_K_CPU0_SB_DQ<3>")
	)
	(segment
		(start 426.571664 -283.9974)
		(end 426.649896 -284.186376)
		(width 0.14478)
		(layer "In6.Cu")
		(net "M_K_CPU0_SB_DQ<3>")
	)
	(segment
		(start 393.921996 -275.039582)
		(end 394.005308 -274.981416)
		(width 0.0889)
		(layer "In6.Cu")
		(net "M_K_CPU0_SB_DQ<3>")
	)
	(segment
		(start 441.090558 -283.61005)
		(end 441.372498 -283.32811)
		(width 0.14478)
		(layer "In6.Cu")
		(net "M_K_CPU0_SB_DQ<3>")
	)
	(segment
		(start 428.55769 -284.088332)
		(end 428.70247 -284.233112)
		(width 0.14478)
		(layer "In6.Cu")
		(net "M_K_CPU0_SB_DQ<3>")
	)
	(segment
		(start 414.601914 -283.61005)
		(end 415.107374 -283.61005)
		(width 0.14478)
		(layer "In6.Cu")
		(net "M_K_CPU0_SB_DQ<3>")
	)
	(segment
		(start 426.50791 -283.773118)
		(end 426.586396 -283.962094)
		(width 0.14478)
		(layer "In6.Cu")
		(net "M_K_CPU0_SB_DQ<3>")
	)
	(segment
		(start 428.70247 -284.233112)
		(end 428.70247 -284.30601)
		(width 0.14478)
		(layer "In6.Cu")
		(net "M_K_CPU0_SB_DQ<3>")
	)
	(segment
		(start 392.257534 -275.383498)
		(end 392.265916 -275.378672)
		(width 0.0889)
		(layer "In6.Cu")
		(net "M_K_CPU0_SB_DQ<3>")
	)
	(segment
		(start 438.073038 -283.32811)
		(end 438.34558 -283.600652)
		(width 0.14478)
		(layer "In6.Cu")
		(net "M_K_CPU0_SB_DQ<3>")
	)
	(segment
		(start 415.107374 -283.61005)
		(end 415.389314 -283.32811)
		(width 0.14478)
		(layer "In6.Cu")
		(net "M_K_CPU0_SB_DQ<3>")
	)
	(segment
		(start 423.25925 -283.600652)
		(end 425.235624 -283.600652)
		(width 0.14478)
		(layer "In6.Cu")
		(net "M_K_CPU0_SB_DQ<3>")
	)
	(segment
		(start 419.725856 -284.45079)
		(end 420.797228 -284.45079)
		(width 0.14478)
		(layer "In6.Cu")
		(net "M_K_CPU0_SB_DQ<3>")
	)
	(segment
		(start 416.2298 -283.600652)
		(end 416.502342 -283.32811)
		(width 0.14478)
		(layer "In6.Cu")
		(net "M_K_CPU0_SB_DQ<3>")
	)
	(segment
		(start 415.389314 -283.32811)
		(end 415.663888 -283.32811)
		(width 0.14478)
		(layer "In6.Cu")
		(net "M_K_CPU0_SB_DQ<3>")
	)
	(segment
		(start 418.603176 -283.32811)
		(end 418.701474 -283.426408)
		(width 0.14478)
		(layer "In6.Cu")
		(net "M_K_CPU0_SB_DQ<3>")
	)
	(segment
		(start 428.295816 -284.088332)
		(end 428.55769 -284.088332)
		(width 0.14478)
		(layer "In6.Cu")
		(net "M_K_CPU0_SB_DQ<3>")
	)
	(segment
		(start 425.873164 -283.864558)
		(end 426.06214 -283.786326)
		(width 0.14478)
		(layer "In6.Cu")
		(net "M_K_CPU0_SB_DQ<3>")
	)
	(segment
		(start 441.647072 -283.32811)
		(end 441.929012 -283.61005)
		(width 0.14478)
		(layer "In6.Cu")
		(net "M_K_CPU0_SB_DQ<3>")
	)
	(segment
		(start 419.091618 -284.021276)
		(end 419.296342 -284.021276)
		(width 0.14478)
		(layer "In6.Cu")
		(net "M_K_CPU0_SB_DQ<3>")
	)
	(segment
		(start 392.24712 -275.389594)
		(end 392.257534 -275.383498)
		(width 0.0889)
		(layer "In6.Cu")
		(net "M_K_CPU0_SB_DQ<3>")
	)
	(segment
		(start 396.000224 -274.30349)
		(end 401.600924 -274.30349)
		(width 0.14478)
		(layer "In6.Cu")
		(net "M_K_CPU0_SB_DQ<3>")
	)
	(segment
		(start 432.735228 -283.53893)
		(end 433.139596 -283.53893)
		(width 0.14478)
		(layer "In6.Cu")
		(net "M_K_CPU0_SB_DQ<3>")
	)
	(segment
		(start 440.815984 -283.61005)
		(end 441.090558 -283.61005)
		(width 0.14478)
		(layer "In6.Cu")
		(net "M_K_CPU0_SB_DQ<3>")
	)
	(segment
		(start 393.41171 -275.26869)
		(end 393.758674 -275.106892)
		(width 0.0889)
		(layer "In6.Cu")
		(net "M_K_CPU0_SB_DQ<3>")
	)
	(segment
		(start 432.249834 -283.30271)
		(end 432.499008 -283.30271)
		(width 0.14478)
		(layer "In6.Cu")
		(net "M_K_CPU0_SB_DQ<3>")
	)
	(segment
		(start 415.93643 -283.600652)
		(end 416.2298 -283.600652)
		(width 0.14478)
		(layer "In6.Cu")
		(net "M_K_CPU0_SB_DQ<3>")
	)
	(segment
		(start 418.802058 -284.106112)
		(end 419.006782 -284.106112)
		(width 0.14478)
		(layer "In6.Cu")
		(net "M_K_CPU0_SB_DQ<3>")
	)
	(segment
		(start 418.701474 -283.426408)
		(end 418.701474 -283.631132)
		(width 0.14478)
		(layer "In6.Cu")
		(net "M_K_CPU0_SB_DQ<3>")
	)
	(segment
		(start 428.151036 -284.233112)
		(end 428.295816 -284.088332)
		(width 0.14478)
		(layer "In6.Cu")
		(net "M_K_CPU0_SB_DQ<3>")
	)
	(segment
		(start 413.751776 -284.460188)
		(end 414.601914 -283.61005)
		(width 0.14478)
		(layer "In6.Cu")
		(net "M_K_CPU0_SB_DQ<3>")
	)
	(segment
		(start 422.404794 -283.61005)
		(end 422.712134 -283.30271)
		(width 0.14478)
		(layer "In6.Cu")
		(net "M_K_CPU0_SB_DQ<3>")
	)
	(segment
		(start 418.616638 -283.715968)
		(end 418.616638 -283.920692)
		(width 0.14478)
		(layer "In6.Cu")
		(net "M_K_CPU0_SB_DQ<3>")
	)
	(segment
		(start 426.586396 -283.962094)
		(end 426.571664 -283.9974)
		(width 0.14478)
		(layer "In6.Cu")
		(net "M_K_CPU0_SB_DQ<3>")
	)
	(segment
		(start 413.365442 -284.460188)
		(end 413.751776 -284.460188)
		(width 0.14478)
		(layer "In6.Cu")
		(net "M_K_CPU0_SB_DQ<3>")
	)
	(segment
		(start 395.644116 -274.25777)
		(end 395.689836 -274.30349)
		(width 0.0889)
		(layer "In6.Cu")
		(net "M_K_CPU0_SB_DQ<3>")
	)
	(segment
		(start 389.624824 -275.706078)
		(end 389.4709 -275.440648)
		(width 0.0889)
		(layer "In6.Cu")
		(net "M_K_CPU0_SB_DQ<3>")
	)
	(segment
		(start 415.663888 -283.32811)
		(end 415.93643 -283.600652)
		(width 0.14478)
		(layer "In6.Cu")
		(net "M_K_CPU0_SB_DQ<3>")
	)
	(segment
		(start 426.265594 -283.672788)
		(end 426.50791 -283.773118)
		(width 0.14478)
		(layer "In6.Cu")
		(net "M_K_CPU0_SB_DQ<3>")
	)
	(segment
		(start 416.502342 -283.32811)
		(end 416.776916 -283.32811)
		(width 0.14478)
		(layer "In6.Cu")
		(net "M_K_CPU0_SB_DQ<3>")
	)
	(segment
		(start 394.691108 -274.295616)
		(end 394.782548 -274.25777)
		(width 0.0889)
		(layer "In6.Cu")
		(net "M_K_CPU0_SB_DQ<3>")
	)
	(segment
		(start 420.797228 -284.45079)
		(end 421.637968 -283.61005)
		(width 0.14478)
		(layer "In6.Cu")
		(net "M_K_CPU0_SB_DQ<3>")
	)
	(segment
		(start 428.151036 -284.30601)
		(end 428.151036 -284.233112)
		(width 0.14478)
		(layer "In6.Cu")
		(net "M_K_CPU0_SB_DQ<3>")
	)
	(segment
		(start 432.499008 -283.30271)
		(end 432.735228 -283.53893)
		(width 0.14478)
		(layer "In6.Cu")
		(net "M_K_CPU0_SB_DQ<3>")
	)
	(segment
		(start 431.083212 -283.600652)
		(end 431.951892 -283.600652)
		(width 0.14478)
		(layer "In6.Cu")
		(net "M_K_CPU0_SB_DQ<3>")
	)
	(segment
		(start 427.288198 -284.45079)
		(end 428.006256 -284.45079)
		(width 0.14478)
		(layer "In6.Cu")
		(net "M_K_CPU0_SB_DQ<3>")
	)
	(segment
		(start 429.093122 -284.45079)
		(end 429.933862 -283.61005)
		(width 0.14478)
		(layer "In6.Cu")
		(net "M_K_CPU0_SB_DQ<3>")
	)
	(segment
		(start 418.616638 -283.920692)
		(end 418.802058 -284.106112)
		(width 0.14478)
		(layer "In6.Cu")
		(net "M_K_CPU0_SB_DQ<3>")
	)
	(segment
		(start 412.808928 -284.16631)
		(end 413.071564 -284.16631)
		(width 0.14478)
		(layer "In6.Cu")
		(net "M_K_CPU0_SB_DQ<3>")
	)
	(segment
		(start 428.70247 -284.30601)
		(end 428.84725 -284.45079)
		(width 0.14478)
		(layer "In6.Cu")
		(net "M_K_CPU0_SB_DQ<3>")
	)
	(segment
		(start 426.076872 -283.75102)
		(end 426.265594 -283.672788)
		(width 0.14478)
		(layer "In6.Cu")
		(net "M_K_CPU0_SB_DQ<3>")
	)
	(segment
		(start 389.4709 -275.440648)
		(end 389.493252 -275.357336)
		(width 0.0889)
		(layer "In6.Cu")
		(net "M_K_CPU0_SB_DQ<3>")
	)
	(segment
		(start 426.06214 -283.786326)
		(end 426.076872 -283.75102)
		(width 0.14478)
		(layer "In6.Cu")
		(net "M_K_CPU0_SB_DQ<3>")
	)
	(segment
		(start 428.84725 -284.45079)
		(end 429.093122 -284.45079)
		(width 0.14478)
		(layer "In6.Cu")
		(net "M_K_CPU0_SB_DQ<3>")
	)
	(segment
		(start 412.51505 -284.460188)
		(end 412.808928 -284.16631)
		(width 0.14478)
		(layer "In6.Cu")
		(net "M_K_CPU0_SB_DQ<3>")
	)
	(segment
		(start 411.757622 -284.460188)
		(end 412.51505 -284.460188)
		(width 0.14478)
		(layer "In6.Cu")
		(net "M_K_CPU0_SB_DQ<3>")
	)
	(segment
		(start 426.649896 -284.186376)
		(end 427.288198 -284.45079)
		(width 0.14478)
		(layer "In6.Cu")
		(net "M_K_CPU0_SB_DQ<3>")
	)
	(segment
		(start 393.197334 -275.383498)
		(end 393.41171 -275.26869)
		(width 0.0889)
		(layer "In6.Cu")
		(net "M_K_CPU0_SB_DQ<3>")
	)
	(segment
		(start 436.088282 -284.45079)
		(end 436.929022 -283.61005)
		(width 0.14478)
		(layer "In6.Cu")
		(net "M_K_CPU0_SB_DQ<3>")
	)
	(segment
		(start 434.051456 -284.45079)
		(end 436.088282 -284.45079)
		(width 0.14478)
		(layer "In6.Cu")
		(net "M_K_CPU0_SB_DQ<3>")
	)
	(segment
		(start 436.929022 -283.61005)
		(end 437.516524 -283.61005)
		(width 0.14478)
		(layer "In6.Cu")
		(net "M_K_CPU0_SB_DQ<3>")
	)
	(segment
		(start 439.986928 -283.600652)
		(end 440.25947 -283.32811)
		(width 0.14478)
		(layer "In6.Cu")
		(net "M_K_CPU0_SB_DQ<3>")
	)
	(segment
		(start 425.235624 -283.600652)
		(end 425.873164 -283.864558)
		(width 0.14478)
		(layer "In6.Cu")
		(net "M_K_CPU0_SB_DQ<3>")
	)
	(segment
		(start 417.61537 -283.32811)
		(end 418.603176 -283.32811)
		(width 0.14478)
		(layer "In6.Cu")
		(net "M_K_CPU0_SB_DQ<3>")
	)
	(segment
		(start 391.317734 -275.383498)
		(end 391.326116 -275.378672)
		(width 0.0889)
		(layer "In6.Cu")
		(net "M_K_CPU0_SB_DQ<3>")
	)
	(segment
		(start 390.74344 -275.378672)
		(end 390.751822 -275.383498)
		(width 0.0889)
		(layer "In6.Cu")
		(net "M_K_CPU0_SB_DQ<3>")
	)
	(segment
		(start 440.534044 -283.32811)
		(end 440.815984 -283.61005)
		(width 0.14478)
		(layer "In6.Cu")
		(net "M_K_CPU0_SB_DQ<3>")
	)
	(arc
		(start 389.811768 -275.383498)
		(mid 390.094724 -275.459675)
		(end 390.37768 -275.383498)
		(width 0.0889)
		(layer "In6.Cu")
		(net "M_K_CPU0_SB_DQ<3>")
	)
	(arc
		(start 389.493252 -275.357336)
		(mid 389.655441 -275.334601)
		(end 389.811768 -275.383498)
		(width 0.0889)
		(layer "In6.Cu")
		(net "M_K_CPU0_SB_DQ<3>")
	)
	(arc
		(start 392.641582 -275.389594)
		(mid 392.920268 -275.459814)
		(end 393.197334 -275.383498)
		(width 0.0889)
		(layer "In6.Cu")
		(net "M_K_CPU0_SB_DQ<3>")
	)
	(arc
		(start 390.751822 -275.383498)
		(mid 391.034778 -275.459675)
		(end 391.317734 -275.383498)
		(width 0.0889)
		(layer "In6.Cu")
		(net "M_K_CPU0_SB_DQ<3>")
	)
	(arc
		(start 391.691876 -275.383498)
		(mid 391.968689 -275.459641)
		(end 392.24712 -275.389594)
		(width 0.0889)
		(layer "In6.Cu")
		(net "M_K_CPU0_SB_DQ<3>")
	)
	(arc
		(start 392.265916 -275.378672)
		(mid 392.44917 -275.333299)
		(end 392.631168 -275.383498)
		(width 0.0889)
		(layer "In6.Cu")
		(net "M_K_CPU0_SB_DQ<3>")
	)
	(arc
		(start 390.37768 -275.383498)
		(mid 390.559931 -275.333148)
		(end 390.74344 -275.378672)
		(width 0.0889)
		(layer "In6.Cu")
		(net "M_K_CPU0_SB_DQ<3>")
	)
	(arc
		(start 391.326116 -275.378672)
		(mid 391.509624 -275.333178)
		(end 391.691876 -275.383498)
		(width 0.0889)
		(layer "In6.Cu")
		(net "M_K_CPU0_SB_DQ<3>")
	)
	(segment
		(start 389.157972 -293.260018)
		(end 389.624824 -293.525956)
		(width 0.10668)
		(layer "F.Cu")
		(net "M_K_CPU0_SB_DQ<31>")
	)
	(segment
		(start 402.4122 -309.616856)
		(end 402.4122 -309.847488)
		(width 0.14478)
		(layer "In6.Cu")
		(net "M_K_CPU0_SB_DQ<31>")
	)
	(segment
		(start 391.317734 -293.203376)
		(end 391.326116 -293.19855)
		(width 0.0889)
		(layer "In6.Cu")
		(net "M_K_CPU0_SB_DQ<31>")
	)
	(segment
		(start 401.677632 -309.794656)
		(end 402.0185 -309.453788)
		(width 0.14478)
		(layer "In6.Cu")
		(net "M_K_CPU0_SB_DQ<31>")
	)
	(segment
		(start 408.191462 -316.594998)
		(end 412.69412 -318.46012)
		(width 0.14478)
		(layer "In6.Cu")
		(net "M_K_CPU0_SB_DQ<31>")
	)
	(segment
		(start 392.12266 -293.990522)
		(end 392.161776 -294.013382)
		(width 0.0889)
		(layer "In6.Cu")
		(net "M_K_CPU0_SB_DQ<31>")
	)
	(segment
		(start 391.691876 -293.203376)
		(end 391.722356 -293.221156)
		(width 0.0889)
		(layer "In6.Cu")
		(net "M_K_CPU0_SB_DQ<31>")
	)
	(segment
		(start 401.6248 -309.060088)
		(end 401.283932 -309.400956)
		(width 0.14478)
		(layer "In6.Cu")
		(net "M_K_CPU0_SB_DQ<31>")
	)
	(segment
		(start 401.6248 -308.829456)
		(end 401.6248 -309.060088)
		(width 0.14478)
		(layer "In6.Cu")
		(net "M_K_CPU0_SB_DQ<31>")
	)
	(segment
		(start 442.119258 -318.46012)
		(end 442.5442 -318.035178)
		(width 0.14478)
		(layer "In6.Cu")
		(net "M_K_CPU0_SB_DQ<31>")
	)
	(segment
		(start 400.6596 -309.007256)
		(end 400.890232 -309.007256)
		(width 0.14478)
		(layer "In6.Cu")
		(net "M_K_CPU0_SB_DQ<31>")
	)
	(segment
		(start 400.890232 -309.007256)
		(end 401.2311 -308.666388)
		(width 0.14478)
		(layer "In6.Cu")
		(net "M_K_CPU0_SB_DQ<31>")
	)
	(segment
		(start 392.816334 -295.144444)
		(end 392.816334 -295.156636)
		(width 0.0889)
		(layer "In6.Cu")
		(net "M_K_CPU0_SB_DQ<31>")
	)
	(segment
		(start 400.8374 -308.042056)
		(end 400.8374 -308.272688)
		(width 0.14478)
		(layer "In6.Cu")
		(net "M_K_CPU0_SB_DQ<31>")
	)
	(segment
		(start 400.674332 -307.878988)
		(end 400.8374 -308.042056)
		(width 0.14478)
		(layer "In6.Cu")
		(net "M_K_CPU0_SB_DQ<31>")
	)
	(segment
		(start 399.709132 -308.056788)
		(end 399.8722 -308.219856)
		(width 0.14478)
		(layer "In6.Cu")
		(net "M_K_CPU0_SB_DQ<31>")
	)
	(segment
		(start 393.259056 -296.196004)
		(end 393.259056 -296.520362)
		(width 0.0889)
		(layer "In6.Cu")
		(net "M_K_CPU0_SB_DQ<31>")
	)
	(segment
		(start 401.283932 -309.400956)
		(end 401.283932 -309.631588)
		(width 0.14478)
		(layer "In6.Cu")
		(net "M_K_CPU0_SB_DQ<31>")
	)
	(segment
		(start 412.69412 -318.46012)
		(end 442.119258 -318.46012)
		(width 0.14478)
		(layer "In6.Cu")
		(net "M_K_CPU0_SB_DQ<31>")
	)
	(segment
		(start 389.624824 -293.525956)
		(end 389.4709 -293.260526)
		(width 0.0889)
		(layer "In6.Cu")
		(net "M_K_CPU0_SB_DQ<31>")
	)
	(segment
		(start 393.259056 -296.520362)
		(end 393.259056 -301.606712)
		(width 0.14478)
		(layer "In6.Cu")
		(net "M_K_CPU0_SB_DQ<31>")
	)
	(segment
		(start 400.102832 -308.219856)
		(end 400.4437 -307.878988)
		(width 0.14478)
		(layer "In6.Cu")
		(net "M_K_CPU0_SB_DQ<31>")
	)
	(segment
		(start 401.283932 -309.631588)
		(end 401.447 -309.794656)
		(width 0.14478)
		(layer "In6.Cu")
		(net "M_K_CPU0_SB_DQ<31>")
	)
	(segment
		(start 392.59256 -294.800528)
		(end 392.631676 -294.823388)
		(width 0.0889)
		(layer "In6.Cu")
		(net "M_K_CPU0_SB_DQ<31>")
	)
	(segment
		(start 393.283186 -296.171874)
		(end 393.259056 -296.196004)
		(width 0.0889)
		(layer "In6.Cu")
		(net "M_K_CPU0_SB_DQ<31>")
	)
	(segment
		(start 400.496532 -308.844188)
		(end 400.6596 -309.007256)
		(width 0.14478)
		(layer "In6.Cu")
		(net "M_K_CPU0_SB_DQ<31>")
	)
	(segment
		(start 402.249132 -309.453788)
		(end 402.4122 -309.616856)
		(width 0.14478)
		(layer "In6.Cu")
		(net "M_K_CPU0_SB_DQ<31>")
	)
	(segment
		(start 393.259056 -301.606712)
		(end 399.0848 -307.432456)
		(width 0.14478)
		(layer "In6.Cu")
		(net "M_K_CPU0_SB_DQ<31>")
	)
	(segment
		(start 399.709132 -307.826156)
		(end 399.709132 -308.056788)
		(width 0.14478)
		(layer "In6.Cu")
		(net "M_K_CPU0_SB_DQ<31>")
	)
	(segment
		(start 400.4437 -307.878988)
		(end 400.674332 -307.878988)
		(width 0.14478)
		(layer "In6.Cu")
		(net "M_K_CPU0_SB_DQ<31>")
	)
	(segment
		(start 402.0185 -309.453788)
		(end 402.249132 -309.453788)
		(width 0.14478)
		(layer "In6.Cu")
		(net "M_K_CPU0_SB_DQ<31>")
	)
	(segment
		(start 399.0848 -307.432456)
		(end 399.315432 -307.432456)
		(width 0.14478)
		(layer "In6.Cu")
		(net "M_K_CPU0_SB_DQ<31>")
	)
	(segment
		(start 399.6563 -307.091588)
		(end 399.886932 -307.091588)
		(width 0.14478)
		(layer "In6.Cu")
		(net "M_K_CPU0_SB_DQ<31>")
	)
	(segment
		(start 390.74344 -293.19855)
		(end 390.751822 -293.203376)
		(width 0.0889)
		(layer "In6.Cu")
		(net "M_K_CPU0_SB_DQ<31>")
	)
	(segment
		(start 389.4709 -293.260526)
		(end 389.493252 -293.177214)
		(width 0.0889)
		(layer "In6.Cu")
		(net "M_K_CPU0_SB_DQ<31>")
	)
	(segment
		(start 401.447 -309.794656)
		(end 401.677632 -309.794656)
		(width 0.14478)
		(layer "In6.Cu")
		(net "M_K_CPU0_SB_DQ<31>")
	)
	(segment
		(start 399.8722 -308.219856)
		(end 400.102832 -308.219856)
		(width 0.14478)
		(layer "In6.Cu")
		(net "M_K_CPU0_SB_DQ<31>")
	)
	(segment
		(start 402.071332 -310.474868)
		(end 408.191462 -316.594998)
		(width 0.14478)
		(layer "In6.Cu")
		(net "M_K_CPU0_SB_DQ<31>")
	)
	(segment
		(start 400.05 -307.485288)
		(end 399.709132 -307.826156)
		(width 0.14478)
		(layer "In6.Cu")
		(net "M_K_CPU0_SB_DQ<31>")
	)
	(segment
		(start 399.315432 -307.432456)
		(end 399.6563 -307.091588)
		(width 0.14478)
		(layer "In6.Cu")
		(net "M_K_CPU0_SB_DQ<31>")
	)
	(segment
		(start 393.283186 -295.955974)
		(end 393.283186 -296.171874)
		(width 0.0889)
		(layer "In6.Cu")
		(net "M_K_CPU0_SB_DQ<31>")
	)
	(segment
		(start 400.496532 -308.613556)
		(end 400.496532 -308.844188)
		(width 0.14478)
		(layer "In6.Cu")
		(net "M_K_CPU0_SB_DQ<31>")
	)
	(segment
		(start 402.071332 -310.188356)
		(end 402.071332 -310.474868)
		(width 0.14478)
		(layer "In6.Cu")
		(net "M_K_CPU0_SB_DQ<31>")
	)
	(segment
		(start 402.4122 -309.847488)
		(end 402.071332 -310.188356)
		(width 0.14478)
		(layer "In6.Cu")
		(net "M_K_CPU0_SB_DQ<31>")
	)
	(segment
		(start 400.05 -307.254656)
		(end 400.05 -307.485288)
		(width 0.14478)
		(layer "In6.Cu")
		(net "M_K_CPU0_SB_DQ<31>")
	)
	(segment
		(start 399.886932 -307.091588)
		(end 400.05 -307.254656)
		(width 0.14478)
		(layer "In6.Cu")
		(net "M_K_CPU0_SB_DQ<31>")
	)
	(segment
		(start 401.461732 -308.666388)
		(end 401.6248 -308.829456)
		(width 0.14478)
		(layer "In6.Cu")
		(net "M_K_CPU0_SB_DQ<31>")
	)
	(segment
		(start 401.2311 -308.666388)
		(end 401.461732 -308.666388)
		(width 0.14478)
		(layer "In6.Cu")
		(net "M_K_CPU0_SB_DQ<31>")
	)
	(segment
		(start 400.8374 -308.272688)
		(end 400.496532 -308.613556)
		(width 0.14478)
		(layer "In6.Cu")
		(net "M_K_CPU0_SB_DQ<31>")
	)
	(segment
		(start 392.161776 -294.013382)
		(end 392.192256 -294.031162)
		(width 0.0889)
		(layer "In6.Cu")
		(net "M_K_CPU0_SB_DQ<31>")
	)
	(arc
		(start 392.816334 -295.156636)
		(mid 392.880849 -295.418855)
		(end 393.059666 -295.621202)
		(width 0.0889)
		(layer "In6.Cu")
		(net "M_K_CPU0_SB_DQ<31>")
	)
	(arc
		(start 390.37768 -293.203376)
		(mid 390.559931 -293.153026)
		(end 390.74344 -293.19855)
		(width 0.0889)
		(layer "In6.Cu")
		(net "M_K_CPU0_SB_DQ<31>")
	)
	(arc
		(start 389.811768 -293.203376)
		(mid 390.094724 -293.279553)
		(end 390.37768 -293.203376)
		(width 0.0889)
		(layer "In6.Cu")
		(net "M_K_CPU0_SB_DQ<31>")
	)
	(arc
		(start 393.172696 -295.698164)
		(mid 393.252759 -295.81643)
		(end 393.283186 -295.955974)
		(width 0.0889)
		(layer "In6.Cu")
		(net "M_K_CPU0_SB_DQ<31>")
	)
	(arc
		(start 389.493252 -293.177214)
		(mid 389.655441 -293.154479)
		(end 389.811768 -293.203376)
		(width 0.0889)
		(layer "In6.Cu")
		(net "M_K_CPU0_SB_DQ<31>")
	)
	(arc
		(start 391.879328 -293.525956)
		(mid 391.943843 -293.788175)
		(end 392.12266 -293.990522)
		(width 0.0889)
		(layer "In6.Cu")
		(net "M_K_CPU0_SB_DQ<31>")
	)
	(arc
		(start 392.192256 -294.031162)
		(mid 392.307683 -294.164538)
		(end 392.349228 -294.335962)
		(width 0.0889)
		(layer "In6.Cu")
		(net "M_K_CPU0_SB_DQ<31>")
	)
	(arc
		(start 390.751822 -293.203376)
		(mid 391.034778 -293.279553)
		(end 391.317734 -293.203376)
		(width 0.0889)
		(layer "In6.Cu")
		(net "M_K_CPU0_SB_DQ<31>")
	)
	(arc
		(start 393.059666 -295.621202)
		(mid 393.119824 -295.654334)
		(end 393.172696 -295.698164)
		(width 0.0889)
		(layer "In6.Cu")
		(net "M_K_CPU0_SB_DQ<31>")
	)
	(arc
		(start 391.722356 -293.221156)
		(mid 391.837783 -293.354532)
		(end 391.879328 -293.525956)
		(width 0.0889)
		(layer "In6.Cu")
		(net "M_K_CPU0_SB_DQ<31>")
	)
	(arc
		(start 392.349228 -294.335962)
		(mid 392.413743 -294.598181)
		(end 392.59256 -294.800528)
		(width 0.0889)
		(layer "In6.Cu")
		(net "M_K_CPU0_SB_DQ<31>")
	)
	(arc
		(start 391.326116 -293.19855)
		(mid 391.509624 -293.153056)
		(end 391.691876 -293.203376)
		(width 0.0889)
		(layer "In6.Cu")
		(net "M_K_CPU0_SB_DQ<31>")
	)
	(arc
		(start 392.631676 -294.823388)
		(mid 392.766906 -294.959248)
		(end 392.816334 -295.144444)
		(width 0.0889)
		(layer "In6.Cu")
		(net "M_K_CPU0_SB_DQ<31>")
	)
	(segment
		(start 390.567926 -292.450012)
		(end 391.034778 -292.71595)
		(width 0.10668)
		(layer "F.Cu")
		(net "M_K_CPU0_SB_DQ<30>")
	)
	(segment
		(start 396.337028 -303.082706)
		(end 396.337028 -303.313338)
		(width 0.14478)
		(layer "In6.Cu")
		(net "M_K_CPU0_SB_DQ<30>")
	)
	(segment
		(start 398.642332 -304.714402)
		(end 398.872964 -304.714402)
		(width 0.14478)
		(layer "In6.Cu")
		(net "M_K_CPU0_SB_DQ<30>")
	)
	(segment
		(start 408.566874 -315.349128)
		(end 411.973268 -316.760098)
		(width 0.14478)
		(layer "In6.Cu")
		(net "M_K_CPU0_SB_DQ<30>")
	)
	(segment
		(start 397.911828 -304.888138)
		(end 398.074896 -305.051206)
		(width 0.14478)
		(layer "In6.Cu")
		(net "M_K_CPU0_SB_DQ<30>")
	)
	(segment
		(start 393.753086 -295.230042)
		(end 394.208254 -295.68521)
		(width 0.0889)
		(layer "In6.Cu")
		(net "M_K_CPU0_SB_DQ<30>")
	)
	(segment
		(start 395.943328 -302.689006)
		(end 396.280132 -302.352202)
		(width 0.14478)
		(layer "In6.Cu")
		(net "M_K_CPU0_SB_DQ<30>")
	)
	(segment
		(start 398.872964 -304.714402)
		(end 399.036032 -304.87747)
		(width 0.14478)
		(layer "In6.Cu")
		(net "M_K_CPU0_SB_DQ<30>")
	)
	(segment
		(start 395.099032 -301.171102)
		(end 394.762228 -301.507906)
		(width 0.14478)
		(layer "In6.Cu")
		(net "M_K_CPU0_SB_DQ<30>")
	)
	(segment
		(start 392.63193 -293.203376)
		(end 392.66241 -293.221156)
		(width 0.0889)
		(layer "In6.Cu")
		(net "M_K_CPU0_SB_DQ<30>")
	)
	(segment
		(start 442.119258 -316.760098)
		(end 442.5442 -316.335156)
		(width 0.14478)
		(layer "In6.Cu")
		(net "M_K_CPU0_SB_DQ<30>")
	)
	(segment
		(start 397.067532 -303.139602)
		(end 397.298164 -303.139602)
		(width 0.14478)
		(layer "In6.Cu")
		(net "M_K_CPU0_SB_DQ<30>")
	)
	(segment
		(start 396.730728 -303.476406)
		(end 397.067532 -303.139602)
		(width 0.14478)
		(layer "In6.Cu")
		(net "M_K_CPU0_SB_DQ<30>")
	)
	(segment
		(start 393.062714 -293.990522)
		(end 393.10183 -294.013382)
		(width 0.0889)
		(layer "In6.Cu")
		(net "M_K_CPU0_SB_DQ<30>")
	)
	(segment
		(start 390.880854 -292.45052)
		(end 390.903206 -292.367208)
		(width 0.0889)
		(layer "In6.Cu")
		(net "M_K_CPU0_SB_DQ<30>")
	)
	(segment
		(start 395.155928 -301.901606)
		(end 395.492732 -301.564802)
		(width 0.14478)
		(layer "In6.Cu")
		(net "M_K_CPU0_SB_DQ<30>")
	)
	(segment
		(start 398.074896 -305.051206)
		(end 398.305528 -305.051206)
		(width 0.14478)
		(layer "In6.Cu")
		(net "M_K_CPU0_SB_DQ<30>")
	)
	(segment
		(start 394.208254 -296.540428)
		(end 394.208254 -300.049692)
		(width 0.14478)
		(layer "In6.Cu")
		(net "M_K_CPU0_SB_DQ<30>")
	)
	(segment
		(start 411.973268 -316.760098)
		(end 442.119258 -316.760098)
		(width 0.14478)
		(layer "In6.Cu")
		(net "M_K_CPU0_SB_DQ<30>")
	)
	(segment
		(start 395.886432 -301.72787)
		(end 395.886432 -301.958502)
		(width 0.14478)
		(layer "In6.Cu")
		(net "M_K_CPU0_SB_DQ<30>")
	)
	(segment
		(start 395.492732 -301.564802)
		(end 395.723364 -301.564802)
		(width 0.14478)
		(layer "In6.Cu")
		(net "M_K_CPU0_SB_DQ<30>")
	)
	(segment
		(start 398.248632 -304.320702)
		(end 397.911828 -304.657506)
		(width 0.14478)
		(layer "In6.Cu")
		(net "M_K_CPU0_SB_DQ<30>")
	)
	(segment
		(start 394.762228 -301.738538)
		(end 394.925296 -301.901606)
		(width 0.14478)
		(layer "In6.Cu")
		(net "M_K_CPU0_SB_DQ<30>")
	)
	(segment
		(start 395.723364 -301.564802)
		(end 395.886432 -301.72787)
		(width 0.14478)
		(layer "In6.Cu")
		(net "M_K_CPU0_SB_DQ<30>")
	)
	(segment
		(start 396.280132 -302.352202)
		(end 396.510764 -302.352202)
		(width 0.14478)
		(layer "In6.Cu")
		(net "M_K_CPU0_SB_DQ<30>")
	)
	(segment
		(start 399.036032 -304.87747)
		(end 399.036032 -305.108102)
		(width 0.14478)
		(layer "In6.Cu")
		(net "M_K_CPU0_SB_DQ<30>")
	)
	(segment
		(start 392.16203 -292.39337)
		(end 392.19251 -292.41115)
		(width 0.0889)
		(layer "In6.Cu")
		(net "M_K_CPU0_SB_DQ<30>")
	)
	(segment
		(start 396.673832 -302.51527)
		(end 396.673832 -302.745902)
		(width 0.14478)
		(layer "In6.Cu")
		(net "M_K_CPU0_SB_DQ<30>")
	)
	(segment
		(start 398.862296 -305.838606)
		(end 399.092928 -305.838606)
		(width 0.14478)
		(layer "In6.Cu")
		(net "M_K_CPU0_SB_DQ<30>")
	)
	(segment
		(start 399.660364 -305.501802)
		(end 403.369018 -309.210456)
		(width 0.14478)
		(layer "In6.Cu")
		(net "M_K_CPU0_SB_DQ<30>")
	)
	(segment
		(start 397.287496 -304.263806)
		(end 397.518128 -304.263806)
		(width 0.14478)
		(layer "In6.Cu")
		(net "M_K_CPU0_SB_DQ<30>")
	)
	(segment
		(start 394.925296 -301.901606)
		(end 395.155928 -301.901606)
		(width 0.14478)
		(layer "In6.Cu")
		(net "M_K_CPU0_SB_DQ<30>")
	)
	(segment
		(start 391.034778 -292.71595)
		(end 390.880854 -292.45052)
		(width 0.0889)
		(layer "In6.Cu")
		(net "M_K_CPU0_SB_DQ<30>")
	)
	(segment
		(start 396.500096 -303.476406)
		(end 396.730728 -303.476406)
		(width 0.14478)
		(layer "In6.Cu")
		(net "M_K_CPU0_SB_DQ<30>")
	)
	(segment
		(start 398.085564 -303.927002)
		(end 398.248632 -304.09007)
		(width 0.14478)
		(layer "In6.Cu")
		(net "M_K_CPU0_SB_DQ<30>")
	)
	(segment
		(start 393.532614 -294.800528)
		(end 393.57173 -294.823388)
		(width 0.0889)
		(layer "In6.Cu")
		(net "M_K_CPU0_SB_DQ<30>")
	)
	(segment
		(start 397.461232 -303.30267)
		(end 397.461232 -303.533302)
		(width 0.14478)
		(layer "In6.Cu")
		(net "M_K_CPU0_SB_DQ<30>")
	)
	(segment
		(start 398.248632 -304.09007)
		(end 398.248632 -304.320702)
		(width 0.14478)
		(layer "In6.Cu")
		(net "M_K_CPU0_SB_DQ<30>")
	)
	(segment
		(start 397.124428 -303.870106)
		(end 397.124428 -304.100738)
		(width 0.14478)
		(layer "In6.Cu")
		(net "M_K_CPU0_SB_DQ<30>")
	)
	(segment
		(start 396.510764 -302.352202)
		(end 396.673832 -302.51527)
		(width 0.14478)
		(layer "In6.Cu")
		(net "M_K_CPU0_SB_DQ<30>")
	)
	(segment
		(start 393.10183 -294.013382)
		(end 393.13231 -294.031162)
		(width 0.0889)
		(layer "In6.Cu")
		(net "M_K_CPU0_SB_DQ<30>")
	)
	(segment
		(start 399.036032 -305.108102)
		(end 398.699228 -305.444906)
		(width 0.14478)
		(layer "In6.Cu")
		(net "M_K_CPU0_SB_DQ<30>")
	)
	(segment
		(start 393.753086 -294.986964)
		(end 393.753086 -295.230042)
		(width 0.0889)
		(layer "In6.Cu")
		(net "M_K_CPU0_SB_DQ<30>")
	)
	(segment
		(start 392.592814 -293.180516)
		(end 392.63193 -293.203376)
		(width 0.0889)
		(layer "In6.Cu")
		(net "M_K_CPU0_SB_DQ<30>")
	)
	(segment
		(start 395.712696 -302.689006)
		(end 395.943328 -302.689006)
		(width 0.14478)
		(layer "In6.Cu")
		(net "M_K_CPU0_SB_DQ<30>")
	)
	(segment
		(start 398.305528 -305.051206)
		(end 398.642332 -304.714402)
		(width 0.14478)
		(layer "In6.Cu")
		(net "M_K_CPU0_SB_DQ<30>")
	)
	(segment
		(start 399.092928 -305.838606)
		(end 399.429732 -305.501802)
		(width 0.14478)
		(layer "In6.Cu")
		(net "M_K_CPU0_SB_DQ<30>")
	)
	(segment
		(start 394.208254 -300.049692)
		(end 395.099032 -300.94047)
		(width 0.14478)
		(layer "In6.Cu")
		(net "M_K_CPU0_SB_DQ<30>")
	)
	(segment
		(start 398.699228 -305.444906)
		(end 398.699228 -305.675538)
		(width 0.14478)
		(layer "In6.Cu")
		(net "M_K_CPU0_SB_DQ<30>")
	)
	(segment
		(start 396.673832 -302.745902)
		(end 396.337028 -303.082706)
		(width 0.14478)
		(layer "In6.Cu")
		(net "M_K_CPU0_SB_DQ<30>")
	)
	(segment
		(start 395.886432 -301.958502)
		(end 395.549628 -302.295306)
		(width 0.14478)
		(layer "In6.Cu")
		(net "M_K_CPU0_SB_DQ<30>")
	)
	(segment
		(start 403.369018 -310.151272)
		(end 408.566874 -315.349128)
		(width 0.14478)
		(layer "In6.Cu")
		(net "M_K_CPU0_SB_DQ<30>")
	)
	(segment
		(start 399.429732 -305.501802)
		(end 399.660364 -305.501802)
		(width 0.14478)
		(layer "In6.Cu")
		(net "M_K_CPU0_SB_DQ<30>")
	)
	(segment
		(start 397.461232 -303.533302)
		(end 397.124428 -303.870106)
		(width 0.14478)
		(layer "In6.Cu")
		(net "M_K_CPU0_SB_DQ<30>")
	)
	(segment
		(start 397.911828 -304.657506)
		(end 397.911828 -304.888138)
		(width 0.14478)
		(layer "In6.Cu")
		(net "M_K_CPU0_SB_DQ<30>")
	)
	(segment
		(start 395.549628 -302.525938)
		(end 395.712696 -302.689006)
		(width 0.14478)
		(layer "In6.Cu")
		(net "M_K_CPU0_SB_DQ<30>")
	)
	(segment
		(start 397.124428 -304.100738)
		(end 397.287496 -304.263806)
		(width 0.14478)
		(layer "In6.Cu")
		(net "M_K_CPU0_SB_DQ<30>")
	)
	(segment
		(start 397.854932 -303.927002)
		(end 398.085564 -303.927002)
		(width 0.14478)
		(layer "In6.Cu")
		(net "M_K_CPU0_SB_DQ<30>")
	)
	(segment
		(start 394.208254 -295.68521)
		(end 394.208254 -296.540428)
		(width 0.0889)
		(layer "In6.Cu")
		(net "M_K_CPU0_SB_DQ<30>")
	)
	(segment
		(start 398.699228 -305.675538)
		(end 398.862296 -305.838606)
		(width 0.14478)
		(layer "In6.Cu")
		(net "M_K_CPU0_SB_DQ<30>")
	)
	(segment
		(start 393.648438 -294.882316)
		(end 393.753086 -294.986964)
		(width 0.0889)
		(layer "In6.Cu")
		(net "M_K_CPU0_SB_DQ<30>")
	)
	(segment
		(start 397.518128 -304.263806)
		(end 397.854932 -303.927002)
		(width 0.14478)
		(layer "In6.Cu")
		(net "M_K_CPU0_SB_DQ<30>")
	)
	(segment
		(start 394.762228 -301.507906)
		(end 394.762228 -301.738538)
		(width 0.14478)
		(layer "In6.Cu")
		(net "M_K_CPU0_SB_DQ<30>")
	)
	(segment
		(start 396.337028 -303.313338)
		(end 396.500096 -303.476406)
		(width 0.14478)
		(layer "In6.Cu")
		(net "M_K_CPU0_SB_DQ<30>")
	)
	(segment
		(start 395.099032 -300.94047)
		(end 395.099032 -301.171102)
		(width 0.14478)
		(layer "In6.Cu")
		(net "M_K_CPU0_SB_DQ<30>")
	)
	(segment
		(start 403.369018 -309.210456)
		(end 403.369018 -310.151272)
		(width 0.14478)
		(layer "In6.Cu")
		(net "M_K_CPU0_SB_DQ<30>")
	)
	(segment
		(start 397.298164 -303.139602)
		(end 397.461232 -303.30267)
		(width 0.14478)
		(layer "In6.Cu")
		(net "M_K_CPU0_SB_DQ<30>")
	)
	(segment
		(start 395.549628 -302.295306)
		(end 395.549628 -302.525938)
		(width 0.14478)
		(layer "In6.Cu")
		(net "M_K_CPU0_SB_DQ<30>")
	)
	(arc
		(start 392.819382 -293.525956)
		(mid 392.883897 -293.788175)
		(end 393.062714 -293.990522)
		(width 0.0889)
		(layer "In6.Cu")
		(net "M_K_CPU0_SB_DQ<30>")
	)
	(arc
		(start 392.349482 -292.71595)
		(mid 392.413997 -292.978169)
		(end 392.592814 -293.180516)
		(width 0.0889)
		(layer "In6.Cu")
		(net "M_K_CPU0_SB_DQ<30>")
	)
	(arc
		(start 391.787634 -292.39337)
		(mid 391.974832 -292.342988)
		(end 392.16203 -292.39337)
		(width 0.0889)
		(layer "In6.Cu")
		(net "M_K_CPU0_SB_DQ<30>")
	)
	(arc
		(start 392.66241 -293.221156)
		(mid 392.777837 -293.354532)
		(end 392.819382 -293.525956)
		(width 0.0889)
		(layer "In6.Cu")
		(net "M_K_CPU0_SB_DQ<30>")
	)
	(arc
		(start 393.289282 -294.335962)
		(mid 393.353797 -294.598181)
		(end 393.532614 -294.800528)
		(width 0.0889)
		(layer "In6.Cu")
		(net "M_K_CPU0_SB_DQ<30>")
	)
	(arc
		(start 390.903206 -292.367208)
		(mid 391.065395 -292.344473)
		(end 391.221722 -292.39337)
		(width 0.0889)
		(layer "In6.Cu")
		(net "M_K_CPU0_SB_DQ<30>")
	)
	(arc
		(start 392.19251 -292.41115)
		(mid 392.307937 -292.544526)
		(end 392.349482 -292.71595)
		(width 0.0889)
		(layer "In6.Cu")
		(net "M_K_CPU0_SB_DQ<30>")
	)
	(arc
		(start 391.221722 -292.39337)
		(mid 391.504678 -292.469547)
		(end 391.787634 -292.39337)
		(width 0.0889)
		(layer "In6.Cu")
		(net "M_K_CPU0_SB_DQ<30>")
	)
	(arc
		(start 393.13231 -294.031162)
		(mid 393.247737 -294.164538)
		(end 393.289282 -294.335962)
		(width 0.0889)
		(layer "In6.Cu")
		(net "M_K_CPU0_SB_DQ<30>")
	)
	(arc
		(start 393.57173 -294.823388)
		(mid 393.611995 -294.850363)
		(end 393.648438 -294.882316)
		(width 0.0889)
		(layer "In6.Cu")
		(net "M_K_CPU0_SB_DQ<30>")
	)
	(segment
		(start 390.567926 -274.630134)
		(end 391.034778 -274.896072)
		(width 0.10668)
		(layer "F.Cu")
		(net "M_K_CPU0_SB_DQ<2>")
	)
	(segment
		(start 407.110946 -278.095202)
		(end 407.288746 -278.273002)
		(width 0.14478)
		(layer "In6.Cu")
		(net "M_K_CPU0_SB_DQ<2>")
	)
	(segment
		(start 418.27196 -281.910028)
		(end 418.647372 -281.910028)
		(width 0.14478)
		(layer "In6.Cu")
		(net "M_K_CPU0_SB_DQ<2>")
	)
	(segment
		(start 441.797694 -281.672792)
		(end 441.797694 -281.765248)
		(width 0.14478)
		(layer "In6.Cu")
		(net "M_K_CPU0_SB_DQ<2>")
	)
	(segment
		(start 440.143392 -281.765248)
		(end 440.143392 -281.672792)
		(width 0.14478)
		(layer "In6.Cu")
		(net "M_K_CPU0_SB_DQ<2>")
	)
	(segment
		(start 436.90921 -281.910028)
		(end 437.848248 -281.910028)
		(width 0.14478)
		(layer "In6.Cu")
		(net "M_K_CPU0_SB_DQ<2>")
	)
	(segment
		(start 442.119258 -281.910028)
		(end 442.5442 -282.33497)
		(width 0.14478)
		(layer "In6.Cu")
		(net "M_K_CPU0_SB_DQ<2>")
	)
	(segment
		(start 404.139146 -275.555202)
		(end 404.316946 -275.733002)
		(width 0.14478)
		(layer "In6.Cu")
		(net "M_K_CPU0_SB_DQ<2>")
	)
	(segment
		(start 417.715446 -281.62631)
		(end 417.988242 -281.62631)
		(width 0.14478)
		(layer "In6.Cu")
		(net "M_K_CPU0_SB_DQ<2>")
	)
	(segment
		(start 424.504866 -281.910028)
		(end 424.788584 -281.62631)
		(width 0.14478)
		(layer "In6.Cu")
		(net "M_K_CPU0_SB_DQ<2>")
	)
	(segment
		(start 429.178212 -282.760166)
		(end 430.02835 -281.910028)
		(width 0.14478)
		(layer "In6.Cu")
		(net "M_K_CPU0_SB_DQ<2>")
	)
	(segment
		(start 437.848248 -281.910028)
		(end 438.131966 -281.62631)
		(width 0.14478)
		(layer "In6.Cu")
		(net "M_K_CPU0_SB_DQ<2>")
	)
	(segment
		(start 414.940242 -281.910028)
		(end 415.205672 -281.910028)
		(width 0.14478)
		(layer "In6.Cu")
		(net "M_K_CPU0_SB_DQ<2>")
	)
	(segment
		(start 406.679146 -278.095202)
		(end 407.110946 -278.095202)
		(width 0.14478)
		(layer "In6.Cu")
		(net "M_K_CPU0_SB_DQ<2>")
	)
	(segment
		(start 407.898346 -278.882602)
		(end 408.076146 -279.060402)
		(width 0.14478)
		(layer "In6.Cu")
		(net "M_K_CPU0_SB_DQ<2>")
	)
	(segment
		(start 408.076146 -279.492202)
		(end 408.253946 -279.670002)
		(width 0.14478)
		(layer "In6.Cu")
		(net "M_K_CPU0_SB_DQ<2>")
	)
	(segment
		(start 405.104346 -276.520402)
		(end 405.536146 -276.520402)
		(width 0.14478)
		(layer "In6.Cu")
		(net "M_K_CPU0_SB_DQ<2>")
	)
	(segment
		(start 419.49751 -282.760166)
		(end 420.963598 -282.760166)
		(width 0.14478)
		(layer "In6.Cu")
		(net "M_K_CPU0_SB_DQ<2>")
	)
	(segment
		(start 436.059072 -282.760166)
		(end 436.90921 -281.910028)
		(width 0.14478)
		(layer "In6.Cu")
		(net "M_K_CPU0_SB_DQ<2>")
	)
	(segment
		(start 424.788584 -281.62631)
		(end 425.06138 -281.62631)
		(width 0.14478)
		(layer "In6.Cu")
		(net "M_K_CPU0_SB_DQ<2>")
	)
	(segment
		(start 422.701212 -281.65171)
		(end 422.95953 -281.910028)
		(width 0.14478)
		(layer "In6.Cu")
		(net "M_K_CPU0_SB_DQ<2>")
	)
	(segment
		(start 441.797694 -281.765248)
		(end 441.942474 -281.910028)
		(width 0.14478)
		(layer "In6.Cu")
		(net "M_K_CPU0_SB_DQ<2>")
	)
	(segment
		(start 402.742146 -274.158202)
		(end 403.173946 -274.158202)
		(width 0.14478)
		(layer "In6.Cu")
		(net "M_K_CPU0_SB_DQ<2>")
	)
	(segment
		(start 407.466546 -278.882602)
		(end 407.898346 -278.882602)
		(width 0.14478)
		(layer "In6.Cu")
		(net "M_K_CPU0_SB_DQ<2>")
	)
	(segment
		(start 440.550046 -281.528012)
		(end 440.694826 -281.672792)
		(width 0.14478)
		(layer "In6.Cu")
		(net "M_K_CPU0_SB_DQ<2>")
	)
	(segment
		(start 415.762186 -281.62631)
		(end 416.045904 -281.910028)
		(width 0.14478)
		(layer "In6.Cu")
		(net "M_K_CPU0_SB_DQ<2>")
	)
	(segment
		(start 438.404762 -281.62631)
		(end 438.68848 -281.910028)
		(width 0.14478)
		(layer "In6.Cu")
		(net "M_K_CPU0_SB_DQ<2>")
	)
	(segment
		(start 392.153394 -274.568666)
		(end 392.161776 -274.573492)
		(width 0.0889)
		(layer "In6.Cu")
		(net "M_K_CPU0_SB_DQ<2>")
	)
	(segment
		(start 439.821828 -281.857958)
		(end 439.873898 -281.910028)
		(width 0.14478)
		(layer "In6.Cu")
		(net "M_K_CPU0_SB_DQ<2>")
	)
	(segment
		(start 407.288746 -278.273002)
		(end 407.288746 -278.704802)
		(width 0.14478)
		(layer "In6.Cu")
		(net "M_K_CPU0_SB_DQ<2>")
	)
	(segment
		(start 434.060854 -282.760166)
		(end 436.059072 -282.760166)
		(width 0.14478)
		(layer "In6.Cu")
		(net "M_K_CPU0_SB_DQ<2>")
	)
	(segment
		(start 426.140118 -281.910028)
		(end 426.990256 -282.760166)
		(width 0.14478)
		(layer "In6.Cu")
		(net "M_K_CPU0_SB_DQ<2>")
	)
	(segment
		(start 417.431728 -281.910028)
		(end 417.715446 -281.62631)
		(width 0.14478)
		(layer "In6.Cu")
		(net "M_K_CPU0_SB_DQ<2>")
	)
	(segment
		(start 417.158932 -281.910028)
		(end 417.431728 -281.910028)
		(width 0.14478)
		(layer "In6.Cu")
		(net "M_K_CPU0_SB_DQ<2>")
	)
	(segment
		(start 403.351746 -274.336002)
		(end 403.351746 -274.767802)
		(width 0.14478)
		(layer "In6.Cu")
		(net "M_K_CPU0_SB_DQ<2>")
	)
	(segment
		(start 439.617104 -281.857704)
		(end 439.821828 -281.857958)
		(width 0.14478)
		(layer "In6.Cu")
		(net "M_K_CPU0_SB_DQ<2>")
	)
	(segment
		(start 405.713946 -276.698202)
		(end 405.713946 -277.130002)
		(width 0.14478)
		(layer "In6.Cu")
		(net "M_K_CPU0_SB_DQ<2>")
	)
	(segment
		(start 405.713946 -277.130002)
		(end 405.891746 -277.307802)
		(width 0.14478)
		(layer "In6.Cu")
		(net "M_K_CPU0_SB_DQ<2>")
	)
	(segment
		(start 425.345098 -281.910028)
		(end 426.140118 -281.910028)
		(width 0.14478)
		(layer "In6.Cu")
		(net "M_K_CPU0_SB_DQ<2>")
	)
	(segment
		(start 414.090104 -282.760166)
		(end 414.940242 -281.910028)
		(width 0.14478)
		(layer "In6.Cu")
		(net "M_K_CPU0_SB_DQ<2>")
	)
	(segment
		(start 430.02835 -281.910028)
		(end 433.210716 -281.910028)
		(width 0.14478)
		(layer "In6.Cu")
		(net "M_K_CPU0_SB_DQ<2>")
	)
	(segment
		(start 425.06138 -281.62631)
		(end 425.345098 -281.910028)
		(width 0.14478)
		(layer "In6.Cu")
		(net "M_K_CPU0_SB_DQ<2>")
	)
	(segment
		(start 403.529546 -274.945602)
		(end 403.961346 -274.945602)
		(width 0.14478)
		(layer "In6.Cu")
		(net "M_K_CPU0_SB_DQ<2>")
	)
	(segment
		(start 393.101576 -274.573492)
		(end 393.170156 -274.61337)
		(width 0.0889)
		(layer "In6.Cu")
		(net "M_K_CPU0_SB_DQ<2>")
	)
	(segment
		(start 395.25956 -273.64563)
		(end 395.51102 -273.39417)
		(width 0.0889)
		(layer "In6.Cu")
		(net "M_K_CPU0_SB_DQ<2>")
	)
	(segment
		(start 402.564346 -273.980402)
		(end 402.742146 -274.158202)
		(width 0.14478)
		(layer "In6.Cu")
		(net "M_K_CPU0_SB_DQ<2>")
	)
	(segment
		(start 403.173946 -274.158202)
		(end 403.351746 -274.336002)
		(width 0.14478)
		(layer "In6.Cu")
		(net "M_K_CPU0_SB_DQ<2>")
	)
	(segment
		(start 439.56478 -281.910028)
		(end 439.617104 -281.857704)
		(width 0.14478)
		(layer "In6.Cu")
		(net "M_K_CPU0_SB_DQ<2>")
	)
	(segment
		(start 438.131966 -281.62631)
		(end 438.404762 -281.62631)
		(width 0.14478)
		(layer "In6.Cu")
		(net "M_K_CPU0_SB_DQ<2>")
	)
	(segment
		(start 439.873898 -281.910028)
		(end 439.998612 -281.910028)
		(width 0.14478)
		(layer "In6.Cu")
		(net "M_K_CPU0_SB_DQ<2>")
	)
	(segment
		(start 440.143392 -281.672792)
		(end 440.288172 -281.528012)
		(width 0.14478)
		(layer "In6.Cu")
		(net "M_K_CPU0_SB_DQ<2>")
	)
	(segment
		(start 426.990256 -282.760166)
		(end 429.178212 -282.760166)
		(width 0.14478)
		(layer "In6.Cu")
		(net "M_K_CPU0_SB_DQ<2>")
	)
	(segment
		(start 408.253946 -279.670002)
		(end 408.685746 -279.670002)
		(width 0.14478)
		(layer "In6.Cu")
		(net "M_K_CPU0_SB_DQ<2>")
	)
	(segment
		(start 415.48939 -281.62631)
		(end 415.762186 -281.62631)
		(width 0.14478)
		(layer "In6.Cu")
		(net "M_K_CPU0_SB_DQ<2>")
	)
	(segment
		(start 402.564346 -273.548602)
		(end 402.564346 -273.980402)
		(width 0.14478)
		(layer "In6.Cu")
		(net "M_K_CPU0_SB_DQ<2>")
	)
	(segment
		(start 408.863546 -279.847802)
		(end 408.863546 -280.279602)
		(width 0.14478)
		(layer "In6.Cu")
		(net "M_K_CPU0_SB_DQ<2>")
	)
	(segment
		(start 408.685746 -279.670002)
		(end 408.863546 -279.847802)
		(width 0.14478)
		(layer "In6.Cu")
		(net "M_K_CPU0_SB_DQ<2>")
	)
	(segment
		(start 433.210716 -281.910028)
		(end 434.060854 -282.760166)
		(width 0.14478)
		(layer "In6.Cu")
		(net "M_K_CPU0_SB_DQ<2>")
	)
	(segment
		(start 422.95953 -281.910028)
		(end 424.504866 -281.910028)
		(width 0.14478)
		(layer "In6.Cu")
		(net "M_K_CPU0_SB_DQ<2>")
	)
	(segment
		(start 416.045904 -281.910028)
		(end 416.3187 -281.910028)
		(width 0.14478)
		(layer "In6.Cu")
		(net "M_K_CPU0_SB_DQ<2>")
	)
	(segment
		(start 408.076146 -279.060402)
		(end 408.076146 -279.492202)
		(width 0.14478)
		(layer "In6.Cu")
		(net "M_K_CPU0_SB_DQ<2>")
	)
	(segment
		(start 404.926546 -276.342602)
		(end 405.104346 -276.520402)
		(width 0.14478)
		(layer "In6.Cu")
		(net "M_K_CPU0_SB_DQ<2>")
	)
	(segment
		(start 415.205672 -281.910028)
		(end 415.48939 -281.62631)
		(width 0.14478)
		(layer "In6.Cu")
		(net "M_K_CPU0_SB_DQ<2>")
	)
	(segment
		(start 420.963598 -282.760166)
		(end 421.813736 -281.910028)
		(width 0.14478)
		(layer "In6.Cu")
		(net "M_K_CPU0_SB_DQ<2>")
	)
	(segment
		(start 438.68848 -281.910028)
		(end 439.56478 -281.910028)
		(width 0.14478)
		(layer "In6.Cu")
		(net "M_K_CPU0_SB_DQ<2>")
	)
	(segment
		(start 440.288172 -281.528012)
		(end 440.550046 -281.528012)
		(width 0.14478)
		(layer "In6.Cu")
		(net "M_K_CPU0_SB_DQ<2>")
	)
	(segment
		(start 404.316946 -275.733002)
		(end 404.748746 -275.733002)
		(width 0.14478)
		(layer "In6.Cu")
		(net "M_K_CPU0_SB_DQ<2>")
	)
	(segment
		(start 402.409914 -273.39417)
		(end 402.564346 -273.548602)
		(width 0.14478)
		(layer "In6.Cu")
		(net "M_K_CPU0_SB_DQ<2>")
	)
	(segment
		(start 406.323546 -277.307802)
		(end 406.501346 -277.485602)
		(width 0.14478)
		(layer "In6.Cu")
		(net "M_K_CPU0_SB_DQ<2>")
	)
	(segment
		(start 390.880854 -274.630642)
		(end 390.903206 -274.54733)
		(width 0.0889)
		(layer "In6.Cu")
		(net "M_K_CPU0_SB_DQ<2>")
	)
	(segment
		(start 407.288746 -278.704802)
		(end 407.466546 -278.882602)
		(width 0.14478)
		(layer "In6.Cu")
		(net "M_K_CPU0_SB_DQ<2>")
	)
	(segment
		(start 395.988286 -273.39417)
		(end 402.409914 -273.39417)
		(width 0.14478)
		(layer "In6.Cu")
		(net "M_K_CPU0_SB_DQ<2>")
	)
	(segment
		(start 416.602418 -281.62631)
		(end 416.875214 -281.62631)
		(width 0.14478)
		(layer "In6.Cu")
		(net "M_K_CPU0_SB_DQ<2>")
	)
	(segment
		(start 422.403016 -281.65171)
		(end 422.701212 -281.65171)
		(width 0.14478)
		(layer "In6.Cu")
		(net "M_K_CPU0_SB_DQ<2>")
	)
	(segment
		(start 393.72413 -274.541234)
		(end 394.581888 -273.683476)
		(width 0.0889)
		(layer "In6.Cu")
		(net "M_K_CPU0_SB_DQ<2>")
	)
	(segment
		(start 441.24626 -281.672792)
		(end 441.39104 -281.528012)
		(width 0.14478)
		(layer "In6.Cu")
		(net "M_K_CPU0_SB_DQ<2>")
	)
	(segment
		(start 422.144698 -281.910028)
		(end 422.403016 -281.65171)
		(width 0.14478)
		(layer "In6.Cu")
		(net "M_K_CPU0_SB_DQ<2>")
	)
	(segment
		(start 392.727434 -274.573492)
		(end 392.735816 -274.568666)
		(width 0.0889)
		(layer "In6.Cu")
		(net "M_K_CPU0_SB_DQ<2>")
	)
	(segment
		(start 440.694826 -281.672792)
		(end 440.694826 -282.147264)
		(width 0.14478)
		(layer "In6.Cu")
		(net "M_K_CPU0_SB_DQ<2>")
	)
	(segment
		(start 404.748746 -275.733002)
		(end 404.926546 -275.910802)
		(width 0.14478)
		(layer "In6.Cu")
		(net "M_K_CPU0_SB_DQ<2>")
	)
	(segment
		(start 441.652914 -281.528012)
		(end 441.797694 -281.672792)
		(width 0.14478)
		(layer "In6.Cu")
		(net "M_K_CPU0_SB_DQ<2>")
	)
	(segment
		(start 394.673328 -273.64563)
		(end 395.25956 -273.64563)
		(width 0.0889)
		(layer "In6.Cu")
		(net "M_K_CPU0_SB_DQ<2>")
	)
	(segment
		(start 441.942474 -281.910028)
		(end 442.119258 -281.910028)
		(width 0.14478)
		(layer "In6.Cu")
		(net "M_K_CPU0_SB_DQ<2>")
	)
	(segment
		(start 403.351746 -274.767802)
		(end 403.529546 -274.945602)
		(width 0.14478)
		(layer "In6.Cu")
		(net "M_K_CPU0_SB_DQ<2>")
	)
	(segment
		(start 411.77591 -282.760166)
		(end 414.090104 -282.760166)
		(width 0.14478)
		(layer "In6.Cu")
		(net "M_K_CPU0_SB_DQ<2>")
	)
	(segment
		(start 440.694826 -282.147264)
		(end 440.839606 -282.292044)
		(width 0.14478)
		(layer "In6.Cu")
		(net "M_K_CPU0_SB_DQ<2>")
	)
	(segment
		(start 392.161776 -274.573492)
		(end 392.17219 -274.579588)
		(width 0.0889)
		(layer "In6.Cu")
		(net "M_K_CPU0_SB_DQ<2>")
	)
	(segment
		(start 391.034778 -274.896072)
		(end 390.880854 -274.630642)
		(width 0.0889)
		(layer "In6.Cu")
		(net "M_K_CPU0_SB_DQ<2>")
	)
	(segment
		(start 403.961346 -274.945602)
		(end 404.139146 -275.123402)
		(width 0.14478)
		(layer "In6.Cu")
		(net "M_K_CPU0_SB_DQ<2>")
	)
	(segment
		(start 418.647372 -281.910028)
		(end 419.49751 -282.760166)
		(width 0.14478)
		(layer "In6.Cu")
		(net "M_K_CPU0_SB_DQ<2>")
	)
	(segment
		(start 405.891746 -277.307802)
		(end 406.323546 -277.307802)
		(width 0.14478)
		(layer "In6.Cu")
		(net "M_K_CPU0_SB_DQ<2>")
	)
	(segment
		(start 441.24626 -282.147264)
		(end 441.24626 -281.672792)
		(width 0.14478)
		(layer "In6.Cu")
		(net "M_K_CPU0_SB_DQ<2>")
	)
	(segment
		(start 408.863546 -280.279602)
		(end 409.041346 -280.457402)
		(width 0.14478)
		(layer "In6.Cu")
		(net "M_K_CPU0_SB_DQ<2>")
	)
	(segment
		(start 395.51102 -273.39417)
		(end 395.988286 -273.39417)
		(width 0.0889)
		(layer "In6.Cu")
		(net "M_K_CPU0_SB_DQ<2>")
	)
	(segment
		(start 404.926546 -275.910802)
		(end 404.926546 -276.342602)
		(width 0.14478)
		(layer "In6.Cu")
		(net "M_K_CPU0_SB_DQ<2>")
	)
	(segment
		(start 405.536146 -276.520402)
		(end 405.713946 -276.698202)
		(width 0.14478)
		(layer "In6.Cu")
		(net "M_K_CPU0_SB_DQ<2>")
	)
	(segment
		(start 416.3187 -281.910028)
		(end 416.602418 -281.62631)
		(width 0.14478)
		(layer "In6.Cu")
		(net "M_K_CPU0_SB_DQ<2>")
	)
	(segment
		(start 439.998612 -281.910028)
		(end 440.143392 -281.765248)
		(width 0.14478)
		(layer "In6.Cu")
		(net "M_K_CPU0_SB_DQ<2>")
	)
	(segment
		(start 404.139146 -275.123402)
		(end 404.139146 -275.555202)
		(width 0.14478)
		(layer "In6.Cu")
		(net "M_K_CPU0_SB_DQ<2>")
	)
	(segment
		(start 416.875214 -281.62631)
		(end 417.158932 -281.910028)
		(width 0.14478)
		(layer "In6.Cu")
		(net "M_K_CPU0_SB_DQ<2>")
	)
	(segment
		(start 441.10148 -282.292044)
		(end 441.24626 -282.147264)
		(width 0.14478)
		(layer "In6.Cu")
		(net "M_K_CPU0_SB_DQ<2>")
	)
	(segment
		(start 409.041346 -280.457402)
		(end 409.473146 -280.457402)
		(width 0.14478)
		(layer "In6.Cu")
		(net "M_K_CPU0_SB_DQ<2>")
	)
	(segment
		(start 406.501346 -277.917402)
		(end 406.679146 -278.095202)
		(width 0.14478)
		(layer "In6.Cu")
		(net "M_K_CPU0_SB_DQ<2>")
	)
	(segment
		(start 409.473146 -280.457402)
		(end 411.77591 -282.760166)
		(width 0.14478)
		(layer "In6.Cu")
		(net "M_K_CPU0_SB_DQ<2>")
	)
	(segment
		(start 417.988242 -281.62631)
		(end 418.27196 -281.910028)
		(width 0.14478)
		(layer "In6.Cu")
		(net "M_K_CPU0_SB_DQ<2>")
	)
	(segment
		(start 441.39104 -281.528012)
		(end 441.652914 -281.528012)
		(width 0.14478)
		(layer "In6.Cu")
		(net "M_K_CPU0_SB_DQ<2>")
	)
	(segment
		(start 421.813736 -281.910028)
		(end 422.144698 -281.910028)
		(width 0.14478)
		(layer "In6.Cu")
		(net "M_K_CPU0_SB_DQ<2>")
	)
	(segment
		(start 406.501346 -277.485602)
		(end 406.501346 -277.917402)
		(width 0.14478)
		(layer "In6.Cu")
		(net "M_K_CPU0_SB_DQ<2>")
	)
	(segment
		(start 440.839606 -282.292044)
		(end 441.10148 -282.292044)
		(width 0.14478)
		(layer "In6.Cu")
		(net "M_K_CPU0_SB_DQ<2>")
	)
	(arc
		(start 391.787634 -274.573492)
		(mid 391.969885 -274.523142)
		(end 392.153394 -274.568666)
		(width 0.0889)
		(layer "In6.Cu")
		(net "M_K_CPU0_SB_DQ<2>")
	)
	(arc
		(start 392.735816 -274.568666)
		(mid 392.919324 -274.523172)
		(end 393.101576 -274.573492)
		(width 0.0889)
		(layer "In6.Cu")
		(net "M_K_CPU0_SB_DQ<2>")
	)
	(arc
		(start 392.17219 -274.579588)
		(mid 392.450622 -274.649686)
		(end 392.727434 -274.573492)
		(width 0.0889)
		(layer "In6.Cu")
		(net "M_K_CPU0_SB_DQ<2>")
	)
	(arc
		(start 390.903206 -274.54733)
		(mid 391.065395 -274.524595)
		(end 391.221722 -274.573492)
		(width 0.0889)
		(layer "In6.Cu")
		(net "M_K_CPU0_SB_DQ<2>")
	)
	(arc
		(start 391.221722 -274.573492)
		(mid 391.504678 -274.649669)
		(end 391.787634 -274.573492)
		(width 0.0889)
		(layer "In6.Cu")
		(net "M_K_CPU0_SB_DQ<2>")
	)
	(arc
		(start 394.581888 -273.683476)
		(mid 394.623841 -273.655444)
		(end 394.673328 -273.64563)
		(width 0.0889)
		(layer "In6.Cu")
		(net "M_K_CPU0_SB_DQ<2>")
	)
	(arc
		(start 393.170156 -274.61337)
		(mid 393.459416 -274.671548)
		(end 393.72413 -274.541234)
		(width 0.0889)
		(layer "In6.Cu")
		(net "M_K_CPU0_SB_DQ<2>")
	)
	(segment
		(start 388.688072 -292.450012)
		(end 389.154924 -292.71595)
		(width 0.10668)
		(layer "F.Cu")
		(net "M_K_CPU0_SB_DQ<29>")
	)
	(segment
		(start 392.727434 -294.658542)
		(end 392.76655 -294.681402)
		(width 0.0889)
		(layer "In6.Cu")
		(net "M_K_CPU0_SB_DQ<29>")
	)
	(segment
		(start 392.227054 -293.830756)
		(end 392.257534 -293.848536)
		(width 0.0889)
		(layer "In6.Cu")
		(net "M_K_CPU0_SB_DQ<29>")
	)
	(segment
		(start 411.993334 -317.610236)
		(end 444.587122 -317.610236)
		(width 0.14478)
		(layer "In6.Cu")
		(net "M_K_CPU0_SB_DQ<29>")
	)
	(segment
		(start 408.486356 -316.15761)
		(end 411.993334 -317.610236)
		(width 0.14478)
		(layer "In6.Cu")
		(net "M_K_CPU0_SB_DQ<29>")
	)
	(segment
		(start 393.751054 -301.432214)
		(end 398.68475 -306.36591)
		(width 0.14478)
		(layer "In6.Cu")
		(net "M_K_CPU0_SB_DQ<29>")
	)
	(segment
		(start 445.306704 -318.013842)
		(end 445.306704 -317.773304)
		(width 0.14478)
		(layer "In6.Cu")
		(net "M_K_CPU0_SB_DQ<29>")
	)
	(segment
		(start 399.821654 -306.36591)
		(end 402.911564 -309.45582)
		(width 0.14478)
		(layer "In6.Cu")
		(net "M_K_CPU0_SB_DQ<29>")
	)
	(segment
		(start 392.257534 -293.848536)
		(end 392.29665 -293.871396)
		(width 0.0889)
		(layer "In6.Cu")
		(net "M_K_CPU0_SB_DQ<29>")
	)
	(segment
		(start 446.219072 -317.610236)
		(end 446.644268 -317.18504)
		(width 0.14478)
		(layer "In6.Cu")
		(net "M_K_CPU0_SB_DQ<29>")
	)
	(segment
		(start 445.306704 -317.773304)
		(end 445.469772 -317.610236)
		(width 0.14478)
		(layer "In6.Cu")
		(net "M_K_CPU0_SB_DQ<29>")
	)
	(segment
		(start 393.68603 -296.185336)
		(end 393.748514 -296.252646)
		(width 0.0889)
		(layer "In6.Cu")
		(net "M_K_CPU0_SB_DQ<29>")
	)
	(segment
		(start 398.68475 -306.36591)
		(end 399.821654 -306.36591)
		(width 0.14478)
		(layer "In6.Cu")
		(net "M_K_CPU0_SB_DQ<29>")
	)
	(segment
		(start 393.748514 -296.252646)
		(end 393.751054 -296.508932)
		(width 0.0889)
		(layer "In6.Cu")
		(net "M_K_CPU0_SB_DQ<29>")
	)
	(segment
		(start 444.75019 -317.773304)
		(end 444.75019 -318.013842)
		(width 0.14478)
		(layer "In6.Cu")
		(net "M_K_CPU0_SB_DQ<29>")
	)
	(segment
		(start 444.913258 -318.17691)
		(end 445.143636 -318.17691)
		(width 0.14478)
		(layer "In6.Cu")
		(net "M_K_CPU0_SB_DQ<29>")
	)
	(segment
		(start 393.751054 -296.508932)
		(end 393.751054 -301.432214)
		(width 0.14478)
		(layer "In6.Cu")
		(net "M_K_CPU0_SB_DQ<29>")
	)
	(segment
		(start 402.911564 -310.582818)
		(end 408.486356 -316.15761)
		(width 0.14478)
		(layer "In6.Cu")
		(net "M_K_CPU0_SB_DQ<29>")
	)
	(segment
		(start 444.75019 -318.013842)
		(end 444.913258 -318.17691)
		(width 0.14478)
		(layer "In6.Cu")
		(net "M_K_CPU0_SB_DQ<29>")
	)
	(segment
		(start 392.696954 -294.640762)
		(end 392.727434 -294.658542)
		(width 0.0889)
		(layer "In6.Cu")
		(net "M_K_CPU0_SB_DQ<29>")
	)
	(segment
		(start 402.911564 -309.45582)
		(end 402.911564 -310.582818)
		(width 0.14478)
		(layer "In6.Cu")
		(net "M_K_CPU0_SB_DQ<29>")
	)
	(segment
		(start 391.787634 -293.03853)
		(end 391.82675 -293.06139)
		(width 0.0889)
		(layer "In6.Cu")
		(net "M_K_CPU0_SB_DQ<29>")
	)
	(segment
		(start 389.308848 -292.98138)
		(end 389.40486 -293.00678)
		(width 0.0889)
		(layer "In6.Cu")
		(net "M_K_CPU0_SB_DQ<29>")
	)
	(segment
		(start 444.587122 -317.610236)
		(end 444.75019 -317.773304)
		(width 0.14478)
		(layer "In6.Cu")
		(net "M_K_CPU0_SB_DQ<29>")
	)
	(segment
		(start 445.469772 -317.610236)
		(end 446.219072 -317.610236)
		(width 0.14478)
		(layer "In6.Cu")
		(net "M_K_CPU0_SB_DQ<29>")
	)
	(segment
		(start 389.90778 -293.03853)
		(end 389.916162 -293.043356)
		(width 0.0889)
		(layer "In6.Cu")
		(net "M_K_CPU0_SB_DQ<29>")
	)
	(segment
		(start 389.154924 -292.71595)
		(end 389.308848 -292.98138)
		(width 0.0889)
		(layer "In6.Cu")
		(net "M_K_CPU0_SB_DQ<29>")
	)
	(segment
		(start 445.143636 -318.17691)
		(end 445.306704 -318.013842)
		(width 0.14478)
		(layer "In6.Cu")
		(net "M_K_CPU0_SB_DQ<29>")
	)
	(arc
		(start 393.169394 -295.444672)
		(mid 393.208387 -295.466045)
		(end 393.245594 -295.490392)
		(width 0.0889)
		(layer "In6.Cu")
		(net "M_K_CPU0_SB_DQ<29>")
	)
	(arc
		(start 393.245594 -295.490392)
		(mid 393.283464 -295.519719)
		(end 393.318746 -295.552114)
		(width 0.0889)
		(layer "In6.Cu")
		(net "M_K_CPU0_SB_DQ<29>")
	)
	(arc
		(start 393.318746 -295.552114)
		(mid 393.434409 -295.701134)
		(end 393.5095 -295.874186)
		(width 0.0889)
		(layer "In6.Cu")
		(net "M_K_CPU0_SB_DQ<29>")
	)
	(arc
		(start 391.82675 -293.06139)
		(mid 392.005563 -293.26374)
		(end 392.070082 -293.525956)
		(width 0.0889)
		(layer "In6.Cu")
		(net "M_K_CPU0_SB_DQ<29>")
	)
	(arc
		(start 391.221722 -293.03853)
		(mid 391.504678 -292.962353)
		(end 391.787634 -293.03853)
		(width 0.0889)
		(layer "In6.Cu")
		(net "M_K_CPU0_SB_DQ<29>")
	)
	(arc
		(start 390.281922 -293.03853)
		(mid 390.564878 -292.962353)
		(end 390.847834 -293.03853)
		(width 0.0889)
		(layer "In6.Cu")
		(net "M_K_CPU0_SB_DQ<29>")
	)
	(arc
		(start 389.916162 -293.043356)
		(mid 390.09967 -293.08885)
		(end 390.281922 -293.03853)
		(width 0.0889)
		(layer "In6.Cu")
		(net "M_K_CPU0_SB_DQ<29>")
	)
	(arc
		(start 390.847834 -293.03853)
		(mid 391.034778 -293.088785)
		(end 391.221722 -293.03853)
		(width 0.0889)
		(layer "In6.Cu")
		(net "M_K_CPU0_SB_DQ<29>")
	)
	(arc
		(start 392.539982 -294.335962)
		(mid 392.581531 -294.507384)
		(end 392.696954 -294.640762)
		(width 0.0889)
		(layer "In6.Cu")
		(net "M_K_CPU0_SB_DQ<29>")
	)
	(arc
		(start 392.29665 -293.871396)
		(mid 392.475463 -294.073746)
		(end 392.539982 -294.335962)
		(width 0.0889)
		(layer "In6.Cu")
		(net "M_K_CPU0_SB_DQ<29>")
	)
	(arc
		(start 392.070082 -293.525956)
		(mid 392.111631 -293.697378)
		(end 392.227054 -293.830756)
		(width 0.0889)
		(layer "In6.Cu")
		(net "M_K_CPU0_SB_DQ<29>")
	)
	(arc
		(start 389.40486 -293.00678)
		(mid 389.660068 -292.963303)
		(end 389.90778 -293.03853)
		(width 0.0889)
		(layer "In6.Cu")
		(net "M_K_CPU0_SB_DQ<29>")
	)
	(arc
		(start 392.76655 -294.681402)
		(mid 392.956866 -294.878532)
		(end 393.016486 -295.145968)
		(width 0.0889)
		(layer "In6.Cu")
		(net "M_K_CPU0_SB_DQ<29>")
	)
	(arc
		(start 393.016486 -295.145968)
		(mid 393.052563 -295.315989)
		(end 393.169394 -295.444672)
		(width 0.0889)
		(layer "In6.Cu")
		(net "M_K_CPU0_SB_DQ<29>")
	)
	(arc
		(start 393.5095 -295.874186)
		(mid 393.57964 -296.040043)
		(end 393.68603 -296.185336)
		(width 0.0889)
		(layer "In6.Cu")
		(net "M_K_CPU0_SB_DQ<29>")
	)
	(segment
		(start 390.098026 -291.640006)
		(end 390.564878 -291.905944)
		(width 0.10668)
		(layer "F.Cu")
		(net "M_K_CPU0_SB_DQ<28>")
	)
	(segment
		(start 394.690854 -299.88891)
		(end 403.919944 -309.118)
		(width 0.14478)
		(layer "In6.Cu")
		(net "M_K_CPU0_SB_DQ<28>")
	)
	(segment
		(start 393.846304 -294.708072)
		(end 393.860274 -294.708072)
		(width 0.0889)
		(layer "In6.Cu")
		(net "M_K_CPU0_SB_DQ<28>")
	)
	(segment
		(start 445.631062 -315.910214)
		(end 446.219072 -315.910214)
		(width 0.14478)
		(layer "In6.Cu")
		(net "M_K_CPU0_SB_DQ<28>")
	)
	(segment
		(start 444.518034 -315.910214)
		(end 444.748412 -315.910214)
		(width 0.14478)
		(layer "In6.Cu")
		(net "M_K_CPU0_SB_DQ<28>")
	)
	(segment
		(start 392.257788 -292.228524)
		(end 392.296904 -292.251384)
		(width 0.0889)
		(layer "In6.Cu")
		(net "M_K_CPU0_SB_DQ<28>")
	)
	(segment
		(start 444.354966 -316.073282)
		(end 444.518034 -315.910214)
		(width 0.14478)
		(layer "In6.Cu")
		(net "M_K_CPU0_SB_DQ<28>")
	)
	(segment
		(start 445.467994 -316.073282)
		(end 445.631062 -315.910214)
		(width 0.14478)
		(layer "In6.Cu")
		(net "M_K_CPU0_SB_DQ<28>")
	)
	(segment
		(start 394.050266 -294.898064)
		(end 394.050266 -294.943784)
		(width 0.0889)
		(layer "In6.Cu")
		(net "M_K_CPU0_SB_DQ<28>")
	)
	(segment
		(start 390.564878 -291.905944)
		(end 390.718802 -292.171374)
		(width 0.0889)
		(layer "In6.Cu")
		(net "M_K_CPU0_SB_DQ<28>")
	)
	(segment
		(start 444.354966 -316.642242)
		(end 444.354966 -316.073282)
		(width 0.14478)
		(layer "In6.Cu")
		(net "M_K_CPU0_SB_DQ<28>")
	)
	(segment
		(start 443.96152 -316.80531)
		(end 444.191898 -316.80531)
		(width 0.14478)
		(layer "In6.Cu")
		(net "M_K_CPU0_SB_DQ<28>")
	)
	(segment
		(start 392.697208 -293.02075)
		(end 392.727688 -293.03853)
		(width 0.0889)
		(layer "In6.Cu")
		(net "M_K_CPU0_SB_DQ<28>")
	)
	(segment
		(start 394.690854 -295.584372)
		(end 394.690854 -296.517568)
		(width 0.0889)
		(layer "In6.Cu")
		(net "M_K_CPU0_SB_DQ<28>")
	)
	(segment
		(start 392.727688 -293.03853)
		(end 392.766804 -293.06139)
		(width 0.0889)
		(layer "In6.Cu")
		(net "M_K_CPU0_SB_DQ<28>")
	)
	(segment
		(start 393.860274 -294.708072)
		(end 394.050266 -294.898064)
		(width 0.0889)
		(layer "In6.Cu")
		(net "M_K_CPU0_SB_DQ<28>")
	)
	(segment
		(start 394.690854 -296.517568)
		(end 394.690854 -299.88891)
		(width 0.14478)
		(layer "In6.Cu")
		(net "M_K_CPU0_SB_DQ<28>")
	)
	(segment
		(start 444.191898 -316.80531)
		(end 444.354966 -316.642242)
		(width 0.14478)
		(layer "In6.Cu")
		(net "M_K_CPU0_SB_DQ<28>")
	)
	(segment
		(start 403.919944 -309.963058)
		(end 408.903424 -314.946538)
		(width 0.14478)
		(layer "In6.Cu")
		(net "M_K_CPU0_SB_DQ<28>")
	)
	(segment
		(start 444.748412 -315.910214)
		(end 444.91148 -316.073282)
		(width 0.14478)
		(layer "In6.Cu")
		(net "M_K_CPU0_SB_DQ<28>")
	)
	(segment
		(start 408.903424 -314.946538)
		(end 411.253432 -315.919866)
		(width 0.14478)
		(layer "In6.Cu")
		(net "M_K_CPU0_SB_DQ<28>")
	)
	(segment
		(start 444.91148 -316.073282)
		(end 444.91148 -316.642242)
		(width 0.14478)
		(layer "In6.Cu")
		(net "M_K_CPU0_SB_DQ<28>")
	)
	(segment
		(start 411.253432 -315.919866)
		(end 443.645036 -315.919866)
		(width 0.14478)
		(layer "In6.Cu")
		(net "M_K_CPU0_SB_DQ<28>")
	)
	(segment
		(start 393.197588 -293.848536)
		(end 393.236704 -293.871396)
		(width 0.0889)
		(layer "In6.Cu")
		(net "M_K_CPU0_SB_DQ<28>")
	)
	(segment
		(start 444.91148 -316.642242)
		(end 445.074548 -316.80531)
		(width 0.14478)
		(layer "In6.Cu")
		(net "M_K_CPU0_SB_DQ<28>")
	)
	(segment
		(start 443.645036 -315.919866)
		(end 443.798452 -316.073282)
		(width 0.14478)
		(layer "In6.Cu")
		(net "M_K_CPU0_SB_DQ<28>")
	)
	(segment
		(start 393.167108 -293.830756)
		(end 393.197588 -293.848536)
		(width 0.0889)
		(layer "In6.Cu")
		(net "M_K_CPU0_SB_DQ<28>")
	)
	(segment
		(start 403.919944 -309.118)
		(end 403.919944 -309.963058)
		(width 0.14478)
		(layer "In6.Cu")
		(net "M_K_CPU0_SB_DQ<28>")
	)
	(segment
		(start 443.798452 -316.642242)
		(end 443.96152 -316.80531)
		(width 0.14478)
		(layer "In6.Cu")
		(net "M_K_CPU0_SB_DQ<28>")
	)
	(segment
		(start 394.050266 -294.943784)
		(end 394.690854 -295.584372)
		(width 0.0889)
		(layer "In6.Cu")
		(net "M_K_CPU0_SB_DQ<28>")
	)
	(segment
		(start 445.467994 -316.642242)
		(end 445.467994 -316.073282)
		(width 0.14478)
		(layer "In6.Cu")
		(net "M_K_CPU0_SB_DQ<28>")
	)
	(segment
		(start 445.304926 -316.80531)
		(end 445.467994 -316.642242)
		(width 0.14478)
		(layer "In6.Cu")
		(net "M_K_CPU0_SB_DQ<28>")
	)
	(segment
		(start 446.219072 -315.910214)
		(end 446.644268 -315.485018)
		(width 0.14478)
		(layer "In6.Cu")
		(net "M_K_CPU0_SB_DQ<28>")
	)
	(segment
		(start 443.798452 -316.073282)
		(end 443.798452 -316.642242)
		(width 0.14478)
		(layer "In6.Cu")
		(net "M_K_CPU0_SB_DQ<28>")
	)
	(segment
		(start 390.718802 -292.171374)
		(end 390.814814 -292.196774)
		(width 0.0889)
		(layer "In6.Cu")
		(net "M_K_CPU0_SB_DQ<28>")
	)
	(segment
		(start 391.317734 -292.228524)
		(end 391.326116 -292.23335)
		(width 0.0889)
		(layer "In6.Cu")
		(net "M_K_CPU0_SB_DQ<28>")
	)
	(segment
		(start 445.074548 -316.80531)
		(end 445.304926 -316.80531)
		(width 0.14478)
		(layer "In6.Cu")
		(net "M_K_CPU0_SB_DQ<28>")
	)
	(arc
		(start 391.691876 -292.228524)
		(mid 391.974832 -292.152347)
		(end 392.257788 -292.228524)
		(width 0.0889)
		(layer "In6.Cu")
		(net "M_K_CPU0_SB_DQ<28>")
	)
	(arc
		(start 392.296904 -292.251384)
		(mid 392.475717 -292.453734)
		(end 392.540236 -292.71595)
		(width 0.0889)
		(layer "In6.Cu")
		(net "M_K_CPU0_SB_DQ<28>")
	)
	(arc
		(start 392.540236 -292.71595)
		(mid 392.581785 -292.887372)
		(end 392.697208 -293.02075)
		(width 0.0889)
		(layer "In6.Cu")
		(net "M_K_CPU0_SB_DQ<28>")
	)
	(arc
		(start 390.814814 -292.196774)
		(mid 391.070022 -292.153297)
		(end 391.317734 -292.228524)
		(width 0.0889)
		(layer "In6.Cu")
		(net "M_K_CPU0_SB_DQ<28>")
	)
	(arc
		(start 393.642596 -294.64381)
		(mid 393.741794 -294.684362)
		(end 393.846304 -294.708072)
		(width 0.0889)
		(layer "In6.Cu")
		(net "M_K_CPU0_SB_DQ<28>")
	)
	(arc
		(start 391.326116 -292.23335)
		(mid 391.509624 -292.278844)
		(end 391.691876 -292.228524)
		(width 0.0889)
		(layer "In6.Cu")
		(net "M_K_CPU0_SB_DQ<28>")
	)
	(arc
		(start 392.766804 -293.06139)
		(mid 392.945617 -293.26374)
		(end 393.010136 -293.525956)
		(width 0.0889)
		(layer "In6.Cu")
		(net "M_K_CPU0_SB_DQ<28>")
	)
	(arc
		(start 393.480036 -294.335962)
		(mid 393.519509 -294.503352)
		(end 393.629642 -294.635428)
		(width 0.0889)
		(layer "In6.Cu")
		(net "M_K_CPU0_SB_DQ<28>")
	)
	(arc
		(start 393.236704 -293.871396)
		(mid 393.415517 -294.073746)
		(end 393.480036 -294.335962)
		(width 0.0889)
		(layer "In6.Cu")
		(net "M_K_CPU0_SB_DQ<28>")
	)
	(arc
		(start 393.629642 -294.635428)
		(mid 393.635935 -294.639904)
		(end 393.642596 -294.64381)
		(width 0.0889)
		(layer "In6.Cu")
		(net "M_K_CPU0_SB_DQ<28>")
	)
	(arc
		(start 393.010136 -293.525956)
		(mid 393.051685 -293.697378)
		(end 393.167108 -293.830756)
		(width 0.0889)
		(layer "In6.Cu")
		(net "M_K_CPU0_SB_DQ<28>")
	)
	(segment
		(start 389.157972 -290.019994)
		(end 389.624824 -290.285932)
		(width 0.10668)
		(layer "F.Cu")
		(net "M_K_CPU0_SB_DQ<27>")
	)
	(segment
		(start 406.147016 -307.333904)
		(end 406.377648 -307.333904)
		(width 0.14478)
		(layer "In6.Cu")
		(net "M_K_CPU0_SB_DQ<27>")
	)
	(segment
		(start 405.753316 -306.709572)
		(end 405.753316 -306.940204)
		(width 0.14478)
		(layer "In6.Cu")
		(net "M_K_CPU0_SB_DQ<27>")
	)
	(segment
		(start 404.34768 -305.98364)
		(end 404.572216 -305.759104)
		(width 0.14478)
		(layer "In6.Cu")
		(net "M_K_CPU0_SB_DQ<27>")
	)
	(segment
		(start 426.705776 -312.500518)
		(end 428.976028 -312.500518)
		(width 0.14478)
		(layer "In6.Cu")
		(net "M_K_CPU0_SB_DQ<27>")
	)
	(segment
		(start 393.443714 -289.78225)
		(end 393.916154 -290.25469)
		(width 0.0889)
		(layer "In6.Cu")
		(net "M_K_CPU0_SB_DQ<27>")
	)
	(segment
		(start 393.916154 -290.25469)
		(end 393.916154 -291.17163)
		(width 0.0889)
		(layer "In6.Cu")
		(net "M_K_CPU0_SB_DQ<27>")
	)
	(segment
		(start 405.590248 -306.546504)
		(end 405.753316 -306.709572)
		(width 0.14478)
		(layer "In6.Cu")
		(net "M_K_CPU0_SB_DQ<27>")
	)
	(segment
		(start 404.965916 -305.922172)
		(end 404.965916 -306.152804)
		(width 0.14478)
		(layer "In6.Cu")
		(net "M_K_CPU0_SB_DQ<27>")
	)
	(segment
		(start 393.916154 -291.17163)
		(end 394.619734 -291.87521)
		(width 0.0889)
		(layer "In6.Cu")
		(net "M_K_CPU0_SB_DQ<27>")
	)
	(segment
		(start 404.74138 -306.607972)
		(end 404.904448 -306.77104)
		(width 0.14478)
		(layer "In6.Cu")
		(net "M_K_CPU0_SB_DQ<27>")
	)
	(segment
		(start 390.74344 -289.958526)
		(end 390.751822 -289.963352)
		(width 0.0889)
		(layer "In6.Cu")
		(net "M_K_CPU0_SB_DQ<27>")
	)
	(segment
		(start 404.965916 -306.152804)
		(end 404.74138 -306.37734)
		(width 0.14478)
		(layer "In6.Cu")
		(net "M_K_CPU0_SB_DQ<27>")
	)
	(segment
		(start 404.117048 -305.98364)
		(end 404.34768 -305.98364)
		(width 0.14478)
		(layer "In6.Cu")
		(net "M_K_CPU0_SB_DQ<27>")
	)
	(segment
		(start 392.58748 -289.78225)
		(end 393.443714 -289.78225)
		(width 0.0889)
		(layer "In6.Cu")
		(net "M_K_CPU0_SB_DQ<27>")
	)
	(segment
		(start 421.431974 -312.500518)
		(end 422.282112 -311.65038)
		(width 0.14478)
		(layer "In6.Cu")
		(net "M_K_CPU0_SB_DQ<27>")
	)
	(segment
		(start 391.317734 -289.963352)
		(end 391.326116 -289.958526)
		(width 0.0889)
		(layer "In6.Cu")
		(net "M_K_CPU0_SB_DQ<27>")
	)
	(segment
		(start 404.178516 -305.365404)
		(end 403.95398 -305.58994)
		(width 0.14478)
		(layer "In6.Cu")
		(net "M_K_CPU0_SB_DQ<27>")
	)
	(segment
		(start 394.852398 -292.829234)
		(end 395.158214 -292.829234)
		(width 0.0889)
		(layer "In6.Cu")
		(net "M_K_CPU0_SB_DQ<27>")
	)
	(segment
		(start 404.015448 -304.971704)
		(end 404.178516 -305.134772)
		(width 0.14478)
		(layer "In6.Cu")
		(net "M_K_CPU0_SB_DQ<27>")
	)
	(segment
		(start 404.572216 -305.759104)
		(end 404.802848 -305.759104)
		(width 0.14478)
		(layer "In6.Cu")
		(net "M_K_CPU0_SB_DQ<27>")
	)
	(segment
		(start 434.101748 -312.500264)
		(end 436.580534 -312.500264)
		(width 0.14478)
		(layer "In6.Cu")
		(net "M_K_CPU0_SB_DQ<27>")
	)
	(segment
		(start 418.735002 -312.500518)
		(end 421.431974 -312.500518)
		(width 0.14478)
		(layer "In6.Cu")
		(net "M_K_CPU0_SB_DQ<27>")
	)
	(segment
		(start 414.755838 -311.65038)
		(end 417.884864 -311.65038)
		(width 0.14478)
		(layer "In6.Cu")
		(net "M_K_CPU0_SB_DQ<27>")
	)
	(segment
		(start 395.779752 -293.450772)
		(end 397.307054 -294.978074)
		(width 0.14478)
		(layer "In6.Cu")
		(net "M_K_CPU0_SB_DQ<27>")
	)
	(segment
		(start 406.31618 -307.95214)
		(end 406.31618 -308.182772)
		(width 0.14478)
		(layer "In6.Cu")
		(net "M_K_CPU0_SB_DQ<27>")
	)
	(segment
		(start 429.826166 -311.65038)
		(end 433.251864 -311.65038)
		(width 0.14478)
		(layer "In6.Cu")
		(net "M_K_CPU0_SB_DQ<27>")
	)
	(segment
		(start 437.430418 -311.65038)
		(end 442.109606 -311.65038)
		(width 0.14478)
		(layer "In6.Cu")
		(net "M_K_CPU0_SB_DQ<27>")
	)
	(segment
		(start 397.307054 -294.978074)
		(end 397.307054 -299.173646)
		(width 0.14478)
		(layer "In6.Cu")
		(net "M_K_CPU0_SB_DQ<27>")
	)
	(segment
		(start 405.359616 -306.546504)
		(end 405.590248 -306.546504)
		(width 0.14478)
		(layer "In6.Cu")
		(net "M_K_CPU0_SB_DQ<27>")
	)
	(segment
		(start 405.13508 -306.77104)
		(end 405.359616 -306.546504)
		(width 0.14478)
		(layer "In6.Cu")
		(net "M_K_CPU0_SB_DQ<27>")
	)
	(segment
		(start 405.691848 -307.55844)
		(end 405.92248 -307.55844)
		(width 0.14478)
		(layer "In6.Cu")
		(net "M_K_CPU0_SB_DQ<27>")
	)
	(segment
		(start 405.753316 -306.940204)
		(end 405.52878 -307.16474)
		(width 0.14478)
		(layer "In6.Cu")
		(net "M_K_CPU0_SB_DQ<27>")
	)
	(segment
		(start 410.643578 -312.51017)
		(end 413.896048 -312.51017)
		(width 0.14478)
		(layer "In6.Cu")
		(net "M_K_CPU0_SB_DQ<27>")
	)
	(segment
		(start 404.178516 -305.134772)
		(end 404.178516 -305.365404)
		(width 0.14478)
		(layer "In6.Cu")
		(net "M_K_CPU0_SB_DQ<27>")
	)
	(segment
		(start 403.95398 -305.820572)
		(end 404.117048 -305.98364)
		(width 0.14478)
		(layer "In6.Cu")
		(net "M_K_CPU0_SB_DQ<27>")
	)
	(segment
		(start 442.109606 -311.65038)
		(end 442.5442 -312.084974)
		(width 0.14478)
		(layer "In6.Cu")
		(net "M_K_CPU0_SB_DQ<27>")
	)
	(segment
		(start 403.95398 -305.58994)
		(end 403.95398 -305.820572)
		(width 0.14478)
		(layer "In6.Cu")
		(net "M_K_CPU0_SB_DQ<27>")
	)
	(segment
		(start 404.904448 -306.77104)
		(end 405.13508 -306.77104)
		(width 0.14478)
		(layer "In6.Cu")
		(net "M_K_CPU0_SB_DQ<27>")
	)
	(segment
		(start 413.896048 -312.51017)
		(end 414.755838 -311.65038)
		(width 0.14478)
		(layer "In6.Cu")
		(net "M_K_CPU0_SB_DQ<27>")
	)
	(segment
		(start 389.624824 -290.285932)
		(end 389.4709 -290.020502)
		(width 0.0889)
		(layer "In6.Cu")
		(net "M_K_CPU0_SB_DQ<27>")
	)
	(segment
		(start 389.4709 -290.020502)
		(end 389.493252 -289.93719)
		(width 0.0889)
		(layer "In6.Cu")
		(net "M_K_CPU0_SB_DQ<27>")
	)
	(segment
		(start 406.31618 -308.182772)
		(end 410.643578 -312.51017)
		(width 0.14478)
		(layer "In6.Cu")
		(net "M_K_CPU0_SB_DQ<27>")
	)
	(segment
		(start 406.540716 -307.496972)
		(end 406.540716 -307.727604)
		(width 0.14478)
		(layer "In6.Cu")
		(net "M_K_CPU0_SB_DQ<27>")
	)
	(segment
		(start 403.56028 -305.19624)
		(end 403.784816 -304.971704)
		(width 0.14478)
		(layer "In6.Cu")
		(net "M_K_CPU0_SB_DQ<27>")
	)
	(segment
		(start 433.251864 -311.65038)
		(end 434.101748 -312.500264)
		(width 0.14478)
		(layer "In6.Cu")
		(net "M_K_CPU0_SB_DQ<27>")
	)
	(segment
		(start 428.976028 -312.500518)
		(end 429.826166 -311.65038)
		(width 0.14478)
		(layer "In6.Cu")
		(net "M_K_CPU0_SB_DQ<27>")
	)
	(segment
		(start 392.24712 -289.969448)
		(end 392.58748 -289.78225)
		(width 0.0889)
		(layer "In6.Cu")
		(net "M_K_CPU0_SB_DQ<27>")
	)
	(segment
		(start 403.329648 -305.19624)
		(end 403.56028 -305.19624)
		(width 0.14478)
		(layer "In6.Cu")
		(net "M_K_CPU0_SB_DQ<27>")
	)
	(segment
		(start 422.282112 -311.65038)
		(end 425.855638 -311.65038)
		(width 0.14478)
		(layer "In6.Cu")
		(net "M_K_CPU0_SB_DQ<27>")
	)
	(segment
		(start 405.52878 -307.16474)
		(end 405.52878 -307.395372)
		(width 0.14478)
		(layer "In6.Cu")
		(net "M_K_CPU0_SB_DQ<27>")
	)
	(segment
		(start 394.619734 -292.59657)
		(end 394.852398 -292.829234)
		(width 0.0889)
		(layer "In6.Cu")
		(net "M_K_CPU0_SB_DQ<27>")
	)
	(segment
		(start 405.92248 -307.55844)
		(end 406.147016 -307.333904)
		(width 0.14478)
		(layer "In6.Cu")
		(net "M_K_CPU0_SB_DQ<27>")
	)
	(segment
		(start 406.540716 -307.727604)
		(end 406.31618 -307.95214)
		(width 0.14478)
		(layer "In6.Cu")
		(net "M_K_CPU0_SB_DQ<27>")
	)
	(segment
		(start 403.784816 -304.971704)
		(end 404.015448 -304.971704)
		(width 0.14478)
		(layer "In6.Cu")
		(net "M_K_CPU0_SB_DQ<27>")
	)
	(segment
		(start 394.619734 -291.87521)
		(end 394.619734 -292.59657)
		(width 0.0889)
		(layer "In6.Cu")
		(net "M_K_CPU0_SB_DQ<27>")
	)
	(segment
		(start 404.802848 -305.759104)
		(end 404.965916 -305.922172)
		(width 0.14478)
		(layer "In6.Cu")
		(net "M_K_CPU0_SB_DQ<27>")
	)
	(segment
		(start 425.855638 -311.65038)
		(end 426.705776 -312.500518)
		(width 0.14478)
		(layer "In6.Cu")
		(net "M_K_CPU0_SB_DQ<27>")
	)
	(segment
		(start 404.74138 -306.37734)
		(end 404.74138 -306.607972)
		(width 0.14478)
		(layer "In6.Cu")
		(net "M_K_CPU0_SB_DQ<27>")
	)
	(segment
		(start 417.884864 -311.65038)
		(end 418.735002 -312.500518)
		(width 0.14478)
		(layer "In6.Cu")
		(net "M_K_CPU0_SB_DQ<27>")
	)
	(segment
		(start 406.377648 -307.333904)
		(end 406.540716 -307.496972)
		(width 0.14478)
		(layer "In6.Cu")
		(net "M_K_CPU0_SB_DQ<27>")
	)
	(segment
		(start 395.158214 -292.829234)
		(end 395.779752 -293.450772)
		(width 0.0889)
		(layer "In6.Cu")
		(net "M_K_CPU0_SB_DQ<27>")
	)
	(segment
		(start 405.52878 -307.395372)
		(end 405.691848 -307.55844)
		(width 0.14478)
		(layer "In6.Cu")
		(net "M_K_CPU0_SB_DQ<27>")
	)
	(segment
		(start 397.307054 -299.173646)
		(end 403.329648 -305.19624)
		(width 0.14478)
		(layer "In6.Cu")
		(net "M_K_CPU0_SB_DQ<27>")
	)
	(segment
		(start 436.580534 -312.500264)
		(end 437.430418 -311.65038)
		(width 0.14478)
		(layer "In6.Cu")
		(net "M_K_CPU0_SB_DQ<27>")
	)
	(arc
		(start 389.493252 -289.93719)
		(mid 389.655441 -289.914455)
		(end 389.811768 -289.963352)
		(width 0.0889)
		(layer "In6.Cu")
		(net "M_K_CPU0_SB_DQ<27>")
	)
	(arc
		(start 391.326116 -289.958526)
		(mid 391.509624 -289.913032)
		(end 391.691876 -289.963352)
		(width 0.0889)
		(layer "In6.Cu")
		(net "M_K_CPU0_SB_DQ<27>")
	)
	(arc
		(start 391.691876 -289.963352)
		(mid 391.968689 -290.039495)
		(end 392.24712 -289.969448)
		(width 0.0889)
		(layer "In6.Cu")
		(net "M_K_CPU0_SB_DQ<27>")
	)
	(arc
		(start 390.751822 -289.963352)
		(mid 391.034778 -290.039529)
		(end 391.317734 -289.963352)
		(width 0.0889)
		(layer "In6.Cu")
		(net "M_K_CPU0_SB_DQ<27>")
	)
	(arc
		(start 390.37768 -289.963352)
		(mid 390.559931 -289.913002)
		(end 390.74344 -289.958526)
		(width 0.0889)
		(layer "In6.Cu")
		(net "M_K_CPU0_SB_DQ<27>")
	)
	(arc
		(start 389.811768 -289.963352)
		(mid 390.094724 -290.039529)
		(end 390.37768 -289.963352)
		(width 0.0889)
		(layer "In6.Cu")
		(net "M_K_CPU0_SB_DQ<27>")
	)
	(segment
		(start 390.567926 -289.209988)
		(end 391.034778 -289.475926)
		(width 0.10668)
		(layer "F.Cu")
		(net "M_K_CPU0_SB_DQ<26>")
	)
	(segment
		(start 400.202654 -300.024038)
		(end 399.979388 -300.247304)
		(width 0.14478)
		(layer "In6.Cu")
		(net "M_K_CPU0_SB_DQ<26>")
	)
	(segment
		(start 401.3835 -301.205138)
		(end 401.614132 -301.205138)
		(width 0.14478)
		(layer "In6.Cu")
		(net "M_K_CPU0_SB_DQ<26>")
	)
	(segment
		(start 394.345414 -290.09213)
		(end 394.345414 -290.729924)
		(width 0.0889)
		(layer "In6.Cu")
		(net "M_K_CPU0_SB_DQ<26>")
	)
	(segment
		(start 402.9583 -302.779938)
		(end 403.188932 -302.779938)
		(width 0.14478)
		(layer "In6.Cu")
		(net "M_K_CPU0_SB_DQ<26>")
	)
	(segment
		(start 402.1709 -301.992538)
		(end 402.401532 -301.992538)
		(width 0.14478)
		(layer "In6.Cu")
		(net "M_K_CPU0_SB_DQ<26>")
	)
	(segment
		(start 399.415 -299.006006)
		(end 399.415254 -299.236638)
		(width 0.14478)
		(layer "In6.Cu")
		(net "M_K_CPU0_SB_DQ<26>")
	)
	(segment
		(start 402.341588 -302.609504)
		(end 402.341588 -302.840136)
		(width 0.14478)
		(layer "In6.Cu")
		(net "M_K_CPU0_SB_DQ<26>")
	)
	(segment
		(start 398.798034 -299.066204)
		(end 399.0213 -298.842938)
		(width 0.14478)
		(layer "In6.Cu")
		(net "M_K_CPU0_SB_DQ<26>")
	)
	(segment
		(start 398.56791 -299.066458)
		(end 398.798034 -299.066204)
		(width 0.14478)
		(layer "In6.Cu")
		(net "M_K_CPU0_SB_DQ<26>")
	)
	(segment
		(start 418.972746 -310.810148)
		(end 421.634158 -310.810148)
		(width 0.14478)
		(layer "In6.Cu")
		(net "M_K_CPU0_SB_DQ<26>")
	)
	(segment
		(start 399.251932 -298.842938)
		(end 399.415 -299.006006)
		(width 0.14478)
		(layer "In6.Cu")
		(net "M_K_CPU0_SB_DQ<26>")
	)
	(segment
		(start 401.71751 -302.216058)
		(end 401.947634 -302.215804)
		(width 0.14478)
		(layer "In6.Cu")
		(net "M_K_CPU0_SB_DQ<26>")
	)
	(segment
		(start 402.564854 -302.386238)
		(end 402.341588 -302.609504)
		(width 0.14478)
		(layer "In6.Cu")
		(net "M_K_CPU0_SB_DQ<26>")
	)
	(segment
		(start 436.624984 -310.809894)
		(end 437.474868 -309.96001)
		(width 0.14478)
		(layer "In6.Cu")
		(net "M_K_CPU0_SB_DQ<26>")
	)
	(segment
		(start 399.979388 -300.477936)
		(end 400.14271 -300.641258)
		(width 0.14478)
		(layer "In6.Cu")
		(net "M_K_CPU0_SB_DQ<26>")
	)
	(segment
		(start 402.5646 -302.155606)
		(end 402.564854 -302.386238)
		(width 0.14478)
		(layer "In6.Cu")
		(net "M_K_CPU0_SB_DQ<26>")
	)
	(segment
		(start 400.9898 -300.580806)
		(end 400.990054 -300.811438)
		(width 0.14478)
		(layer "In6.Cu")
		(net "M_K_CPU0_SB_DQ<26>")
	)
	(segment
		(start 441.13323 -309.577232)
		(end 441.395104 -309.577232)
		(width 0.14478)
		(layer "In6.Cu")
		(net "M_K_CPU0_SB_DQ<26>")
	)
	(segment
		(start 441.395104 -309.577232)
		(end 441.539884 -309.722012)
		(width 0.14478)
		(layer "In6.Cu")
		(net "M_K_CPU0_SB_DQ<26>")
	)
	(segment
		(start 400.039332 -299.630338)
		(end 400.2024 -299.793406)
		(width 0.14478)
		(layer "In6.Cu")
		(net "M_K_CPU0_SB_DQ<26>")
	)
	(segment
		(start 394.345414 -290.729924)
		(end 395.733016 -292.117526)
		(width 0.0889)
		(layer "In6.Cu")
		(net "M_K_CPU0_SB_DQ<26>")
	)
	(segment
		(start 414.090104 -310.810148)
		(end 414.940242 -309.96001)
		(width 0.14478)
		(layer "In6.Cu")
		(net "M_K_CPU0_SB_DQ<26>")
	)
	(segment
		(start 401.7772 -301.368206)
		(end 401.777454 -301.598838)
		(width 0.14478)
		(layer "In6.Cu")
		(net "M_K_CPU0_SB_DQ<26>")
	)
	(segment
		(start 403.188932 -302.779938)
		(end 403.352 -302.943006)
		(width 0.14478)
		(layer "In6.Cu")
		(net "M_K_CPU0_SB_DQ<26>")
	)
	(segment
		(start 440.84367 -309.96001)
		(end 440.98845 -309.81523)
		(width 0.14478)
		(layer "In6.Cu")
		(net "M_K_CPU0_SB_DQ<26>")
	)
	(segment
		(start 422.484296 -309.96001)
		(end 425.666662 -309.96001)
		(width 0.14478)
		(layer "In6.Cu")
		(net "M_K_CPU0_SB_DQ<26>")
	)
	(segment
		(start 399.35531 -299.853858)
		(end 399.585434 -299.853604)
		(width 0.14478)
		(layer "In6.Cu")
		(net "M_K_CPU0_SB_DQ<26>")
	)
	(segment
		(start 398.6276 -298.218606)
		(end 398.627854 -298.449238)
		(width 0.14478)
		(layer "In6.Cu")
		(net "M_K_CPU0_SB_DQ<26>")
	)
	(segment
		(start 414.940242 -309.96001)
		(end 418.122608 -309.96001)
		(width 0.14478)
		(layer "In6.Cu")
		(net "M_K_CPU0_SB_DQ<26>")
	)
	(segment
		(start 403.128988 -303.396904)
		(end 403.128988 -303.627536)
		(width 0.14478)
		(layer "In6.Cu")
		(net "M_K_CPU0_SB_DQ<26>")
	)
	(segment
		(start 402.401532 -301.992538)
		(end 402.5646 -302.155606)
		(width 0.14478)
		(layer "In6.Cu")
		(net "M_K_CPU0_SB_DQ<26>")
	)
	(segment
		(start 399.415254 -299.236638)
		(end 399.191988 -299.459904)
		(width 0.14478)
		(layer "In6.Cu")
		(net "M_K_CPU0_SB_DQ<26>")
	)
	(segment
		(start 432.971448 -309.96001)
		(end 433.821332 -310.809894)
		(width 0.14478)
		(layer "In6.Cu")
		(net "M_K_CPU0_SB_DQ<26>")
	)
	(segment
		(start 402.735034 -303.003204)
		(end 402.9583 -302.779938)
		(width 0.14478)
		(layer "In6.Cu")
		(net "M_K_CPU0_SB_DQ<26>")
	)
	(segment
		(start 401.160234 -301.428404)
		(end 401.3835 -301.205138)
		(width 0.14478)
		(layer "In6.Cu")
		(net "M_K_CPU0_SB_DQ<26>")
	)
	(segment
		(start 441.684664 -309.96001)
		(end 442.119258 -309.96001)
		(width 0.14478)
		(layer "In6.Cu")
		(net "M_K_CPU0_SB_DQ<26>")
	)
	(segment
		(start 392.153394 -289.14852)
		(end 392.32713 -289.245294)
		(width 0.0889)
		(layer "In6.Cu")
		(net "M_K_CPU0_SB_DQ<26>")
	)
	(segment
		(start 399.8087 -299.630338)
		(end 400.039332 -299.630338)
		(width 0.14478)
		(layer "In6.Cu")
		(net "M_K_CPU0_SB_DQ<26>")
	)
	(segment
		(start 399.979388 -300.247304)
		(end 399.979388 -300.477936)
		(width 0.14478)
		(layer "In6.Cu")
		(net "M_K_CPU0_SB_DQ<26>")
	)
	(segment
		(start 401.947634 -302.215804)
		(end 402.1709 -301.992538)
		(width 0.14478)
		(layer "In6.Cu")
		(net "M_K_CPU0_SB_DQ<26>")
	)
	(segment
		(start 441.539884 -309.81523)
		(end 441.684664 -309.96001)
		(width 0.14478)
		(layer "In6.Cu")
		(net "M_K_CPU0_SB_DQ<26>")
	)
	(segment
		(start 399.0213 -298.842938)
		(end 399.251932 -298.842938)
		(width 0.14478)
		(layer "In6.Cu")
		(net "M_K_CPU0_SB_DQ<26>")
	)
	(segment
		(start 401.554188 -302.052736)
		(end 401.71751 -302.216058)
		(width 0.14478)
		(layer "In6.Cu")
		(net "M_K_CPU0_SB_DQ<26>")
	)
	(segment
		(start 402.341588 -302.840136)
		(end 402.50491 -303.003458)
		(width 0.14478)
		(layer "In6.Cu")
		(net "M_K_CPU0_SB_DQ<26>")
	)
	(segment
		(start 391.034778 -289.475926)
		(end 390.880854 -289.210496)
		(width 0.0889)
		(layer "In6.Cu")
		(net "M_K_CPU0_SB_DQ<26>")
	)
	(segment
		(start 398.404588 -298.672504)
		(end 398.404588 -298.903136)
		(width 0.14478)
		(layer "In6.Cu")
		(net "M_K_CPU0_SB_DQ<26>")
	)
	(segment
		(start 403.352254 -303.173638)
		(end 403.128988 -303.396904)
		(width 0.14478)
		(layer "In6.Cu")
		(net "M_K_CPU0_SB_DQ<26>")
	)
	(segment
		(start 400.766788 -301.034704)
		(end 400.766788 -301.265336)
		(width 0.14478)
		(layer "In6.Cu")
		(net "M_K_CPU0_SB_DQ<26>")
	)
	(segment
		(start 399.191988 -299.690536)
		(end 399.35531 -299.853858)
		(width 0.14478)
		(layer "In6.Cu")
		(net "M_K_CPU0_SB_DQ<26>")
	)
	(segment
		(start 421.634158 -310.810148)
		(end 422.484296 -309.96001)
		(width 0.14478)
		(layer "In6.Cu")
		(net "M_K_CPU0_SB_DQ<26>")
	)
	(segment
		(start 437.474868 -309.96001)
		(end 440.84367 -309.96001)
		(width 0.14478)
		(layer "In6.Cu")
		(net "M_K_CPU0_SB_DQ<26>")
	)
	(segment
		(start 433.821332 -310.809894)
		(end 436.624984 -310.809894)
		(width 0.14478)
		(layer "In6.Cu")
		(net "M_K_CPU0_SB_DQ<26>")
	)
	(segment
		(start 403.128988 -303.627536)
		(end 403.29231 -303.790858)
		(width 0.14478)
		(layer "In6.Cu")
		(net "M_K_CPU0_SB_DQ<26>")
	)
	(segment
		(start 418.122608 -309.96001)
		(end 418.972746 -310.810148)
		(width 0.14478)
		(layer "In6.Cu")
		(net "M_K_CPU0_SB_DQ<26>")
	)
	(segment
		(start 400.2024 -299.793406)
		(end 400.202654 -300.024038)
		(width 0.14478)
		(layer "In6.Cu")
		(net "M_K_CPU0_SB_DQ<26>")
	)
	(segment
		(start 425.666662 -309.96001)
		(end 426.5168 -310.810148)
		(width 0.14478)
		(layer "In6.Cu")
		(net "M_K_CPU0_SB_DQ<26>")
	)
	(segment
		(start 401.777454 -301.598838)
		(end 401.554188 -301.822104)
		(width 0.14478)
		(layer "In6.Cu")
		(net "M_K_CPU0_SB_DQ<26>")
	)
	(segment
		(start 403.352 -302.943006)
		(end 403.352254 -303.173638)
		(width 0.14478)
		(layer "In6.Cu")
		(net "M_K_CPU0_SB_DQ<26>")
	)
	(segment
		(start 398.627854 -298.449238)
		(end 398.404588 -298.672504)
		(width 0.14478)
		(layer "In6.Cu")
		(net "M_K_CPU0_SB_DQ<26>")
	)
	(segment
		(start 400.93011 -301.428658)
		(end 401.160234 -301.428404)
		(width 0.14478)
		(layer "In6.Cu")
		(net "M_K_CPU0_SB_DQ<26>")
	)
	(segment
		(start 441.539884 -309.722012)
		(end 441.539884 -309.81523)
		(width 0.14478)
		(layer "In6.Cu")
		(net "M_K_CPU0_SB_DQ<26>")
	)
	(segment
		(start 398.297654 -297.88866)
		(end 398.6276 -298.218606)
		(width 0.14478)
		(layer "In6.Cu")
		(net "M_K_CPU0_SB_DQ<26>")
	)
	(segment
		(start 403.29231 -303.790858)
		(end 403.522434 -303.790604)
		(width 0.14478)
		(layer "In6.Cu")
		(net "M_K_CPU0_SB_DQ<26>")
	)
	(segment
		(start 440.98845 -309.81523)
		(end 440.98845 -309.722012)
		(width 0.14478)
		(layer "In6.Cu")
		(net "M_K_CPU0_SB_DQ<26>")
	)
	(segment
		(start 403.522434 -303.790604)
		(end 403.7457 -303.567338)
		(width 0.14478)
		(layer "In6.Cu")
		(net "M_K_CPU0_SB_DQ<26>")
	)
	(segment
		(start 392.370564 -289.25647)
		(end 393.462764 -289.25647)
		(width 0.0889)
		(layer "In6.Cu")
		(net "M_K_CPU0_SB_DQ<26>")
	)
	(segment
		(start 393.543028 -289.289744)
		(end 394.345414 -290.09213)
		(width 0.0889)
		(layer "In6.Cu")
		(net "M_K_CPU0_SB_DQ<26>")
	)
	(segment
		(start 400.990054 -300.811438)
		(end 400.766788 -301.034704)
		(width 0.14478)
		(layer "In6.Cu")
		(net "M_K_CPU0_SB_DQ<26>")
	)
	(segment
		(start 401.554188 -301.822104)
		(end 401.554188 -302.052736)
		(width 0.14478)
		(layer "In6.Cu")
		(net "M_K_CPU0_SB_DQ<26>")
	)
	(segment
		(start 400.14271 -300.641258)
		(end 400.372834 -300.641004)
		(width 0.14478)
		(layer "In6.Cu")
		(net "M_K_CPU0_SB_DQ<26>")
	)
	(segment
		(start 399.585434 -299.853604)
		(end 399.8087 -299.630338)
		(width 0.14478)
		(layer "In6.Cu")
		(net "M_K_CPU0_SB_DQ<26>")
	)
	(segment
		(start 429.178212 -310.810148)
		(end 430.02835 -309.96001)
		(width 0.14478)
		(layer "In6.Cu")
		(net "M_K_CPU0_SB_DQ<26>")
	)
	(segment
		(start 402.50491 -303.003458)
		(end 402.735034 -303.003204)
		(width 0.14478)
		(layer "In6.Cu")
		(net "M_K_CPU0_SB_DQ<26>")
	)
	(segment
		(start 403.7457 -303.567338)
		(end 403.976332 -303.567338)
		(width 0.14478)
		(layer "In6.Cu")
		(net "M_K_CPU0_SB_DQ<26>")
	)
	(segment
		(start 390.880854 -289.210496)
		(end 390.903206 -289.127184)
		(width 0.0889)
		(layer "In6.Cu")
		(net "M_K_CPU0_SB_DQ<26>")
	)
	(segment
		(start 400.372834 -300.641004)
		(end 400.5961 -300.417738)
		(width 0.14478)
		(layer "In6.Cu")
		(net "M_K_CPU0_SB_DQ<26>")
	)
	(segment
		(start 400.826732 -300.417738)
		(end 400.9898 -300.580806)
		(width 0.14478)
		(layer "In6.Cu")
		(net "M_K_CPU0_SB_DQ<26>")
	)
	(segment
		(start 398.404588 -298.903136)
		(end 398.56791 -299.066458)
		(width 0.14478)
		(layer "In6.Cu")
		(net "M_K_CPU0_SB_DQ<26>")
	)
	(segment
		(start 430.02835 -309.96001)
		(end 432.971448 -309.96001)
		(width 0.14478)
		(layer "In6.Cu")
		(net "M_K_CPU0_SB_DQ<26>")
	)
	(segment
		(start 400.5961 -300.417738)
		(end 400.826732 -300.417738)
		(width 0.14478)
		(layer "In6.Cu")
		(net "M_K_CPU0_SB_DQ<26>")
	)
	(segment
		(start 401.614132 -301.205138)
		(end 401.7772 -301.368206)
		(width 0.14478)
		(layer "In6.Cu")
		(net "M_K_CPU0_SB_DQ<26>")
	)
	(segment
		(start 400.766788 -301.265336)
		(end 400.93011 -301.428658)
		(width 0.14478)
		(layer "In6.Cu")
		(net "M_K_CPU0_SB_DQ<26>")
	)
	(segment
		(start 398.297654 -294.682164)
		(end 398.297654 -297.88866)
		(width 0.14478)
		(layer "In6.Cu")
		(net "M_K_CPU0_SB_DQ<26>")
	)
	(segment
		(start 411.219142 -310.810148)
		(end 414.090104 -310.810148)
		(width 0.14478)
		(layer "In6.Cu")
		(net "M_K_CPU0_SB_DQ<26>")
	)
	(segment
		(start 440.98845 -309.722012)
		(end 441.13323 -309.577232)
		(width 0.14478)
		(layer "In6.Cu")
		(net "M_K_CPU0_SB_DQ<26>")
	)
	(segment
		(start 395.733016 -292.117526)
		(end 398.297654 -294.682164)
		(width 0.14478)
		(layer "In6.Cu")
		(net "M_K_CPU0_SB_DQ<26>")
	)
	(segment
		(start 403.976332 -303.567338)
		(end 411.219142 -310.810148)
		(width 0.14478)
		(layer "In6.Cu")
		(net "M_K_CPU0_SB_DQ<26>")
	)
	(segment
		(start 399.191988 -299.459904)
		(end 399.191988 -299.690536)
		(width 0.14478)
		(layer "In6.Cu")
		(net "M_K_CPU0_SB_DQ<26>")
	)
	(segment
		(start 426.5168 -310.810148)
		(end 429.178212 -310.810148)
		(width 0.14478)
		(layer "In6.Cu")
		(net "M_K_CPU0_SB_DQ<26>")
	)
	(segment
		(start 442.119258 -309.96001)
		(end 442.5442 -310.384952)
		(width 0.14478)
		(layer "In6.Cu")
		(net "M_K_CPU0_SB_DQ<26>")
	)
	(arc
		(start 390.903206 -289.127184)
		(mid 391.065395 -289.104449)
		(end 391.221722 -289.153346)
		(width 0.0889)
		(layer "In6.Cu")
		(net "M_K_CPU0_SB_DQ<26>")
	)
	(arc
		(start 391.221722 -289.153346)
		(mid 391.504678 -289.229523)
		(end 391.787634 -289.153346)
		(width 0.0889)
		(layer "In6.Cu")
		(net "M_K_CPU0_SB_DQ<26>")
	)
	(arc
		(start 392.32713 -289.245294)
		(mid 392.348134 -289.253649)
		(end 392.370564 -289.25647)
		(width 0.0889)
		(layer "In6.Cu")
		(net "M_K_CPU0_SB_DQ<26>")
	)
	(arc
		(start 393.462764 -289.25647)
		(mid 393.506199 -289.265128)
		(end 393.543028 -289.289744)
		(width 0.0889)
		(layer "In6.Cu")
		(net "M_K_CPU0_SB_DQ<26>")
	)
	(arc
		(start 391.787634 -289.153346)
		(mid 391.969885 -289.102996)
		(end 392.153394 -289.14852)
		(width 0.0889)
		(layer "In6.Cu")
		(net "M_K_CPU0_SB_DQ<26>")
	)
	(segment
		(start 388.688072 -289.209988)
		(end 389.154924 -289.475926)
		(width 0.10668)
		(layer "F.Cu")
		(net "M_K_CPU0_SB_DQ<25>")
	)
	(segment
		(start 389.154924 -289.475926)
		(end 389.308848 -289.741356)
		(width 0.0889)
		(layer "In6.Cu")
		(net "M_K_CPU0_SB_DQ<25>")
	)
	(segment
		(start 426.550582 -311.660032)
		(end 429.06442 -311.660032)
		(width 0.14478)
		(layer "In6.Cu")
		(net "M_K_CPU0_SB_DQ<25>")
	)
	(segment
		(start 395.570456 -292.500304)
		(end 395.570456 -292.598348)
		(width 0.0889)
		(layer "In6.Cu")
		(net "M_K_CPU0_SB_DQ<25>")
	)
	(segment
		(start 392.149838 -289.805364)
		(end 392.537442 -289.57651)
		(width 0.0889)
		(layer "In6.Cu")
		(net "M_K_CPU0_SB_DQ<25>")
	)
	(segment
		(start 413.976312 -311.660032)
		(end 414.826196 -310.810148)
		(width 0.14478)
		(layer "In6.Cu")
		(net "M_K_CPU0_SB_DQ<25>")
	)
	(segment
		(start 394.119354 -290.170362)
		(end 394.119354 -291.049202)
		(width 0.0889)
		(layer "In6.Cu")
		(net "M_K_CPU0_SB_DQ<25>")
	)
	(segment
		(start 392.537442 -289.57651)
		(end 393.525502 -289.57651)
		(width 0.0889)
		(layer "In6.Cu")
		(net "M_K_CPU0_SB_DQ<25>")
	)
	(segment
		(start 422.37025 -310.810148)
		(end 425.700698 -310.810148)
		(width 0.14478)
		(layer "In6.Cu")
		(net "M_K_CPU0_SB_DQ<25>")
	)
	(segment
		(start 397.815054 -294.842946)
		(end 397.815054 -299.038264)
		(width 0.14478)
		(layer "In6.Cu")
		(net "M_K_CPU0_SB_DQ<25>")
	)
	(segment
		(start 395.570456 -292.598348)
		(end 395.823694 -292.851586)
		(width 0.0889)
		(layer "In6.Cu")
		(net "M_K_CPU0_SB_DQ<25>")
	)
	(segment
		(start 404.012908 -304.28311)
		(end 411.38983 -311.660032)
		(width 0.14478)
		(layer "In6.Cu")
		(net "M_K_CPU0_SB_DQ<25>")
	)
	(segment
		(start 393.525502 -289.57651)
		(end 394.119354 -290.170362)
		(width 0.0889)
		(layer "In6.Cu")
		(net "M_K_CPU0_SB_DQ<25>")
	)
	(segment
		(start 418.156644 -310.810148)
		(end 419.006528 -311.660032)
		(width 0.14478)
		(layer "In6.Cu")
		(net "M_K_CPU0_SB_DQ<25>")
	)
	(segment
		(start 403.0599 -304.28311)
		(end 404.012908 -304.28311)
		(width 0.14478)
		(layer "In6.Cu")
		(net "M_K_CPU0_SB_DQ<25>")
	)
	(segment
		(start 429.914304 -310.810148)
		(end 433.084732 -310.810148)
		(width 0.14478)
		(layer "In6.Cu")
		(net "M_K_CPU0_SB_DQ<25>")
	)
	(segment
		(start 397.815054 -299.038264)
		(end 403.0599 -304.28311)
		(width 0.14478)
		(layer "In6.Cu")
		(net "M_K_CPU0_SB_DQ<25>")
	)
	(segment
		(start 419.006528 -311.660032)
		(end 421.520366 -311.660032)
		(width 0.14478)
		(layer "In6.Cu")
		(net "M_K_CPU0_SB_DQ<25>")
	)
	(segment
		(start 446.219326 -310.809894)
		(end 446.644268 -311.234836)
		(width 0.14478)
		(layer "In6.Cu")
		(net "M_K_CPU0_SB_DQ<25>")
	)
	(segment
		(start 433.934362 -311.659778)
		(end 436.597806 -311.659778)
		(width 0.14478)
		(layer "In6.Cu")
		(net "M_K_CPU0_SB_DQ<25>")
	)
	(segment
		(start 411.38983 -311.660032)
		(end 413.976312 -311.660032)
		(width 0.14478)
		(layer "In6.Cu")
		(net "M_K_CPU0_SB_DQ<25>")
	)
	(segment
		(start 395.823694 -292.851586)
		(end 397.815054 -294.842946)
		(width 0.14478)
		(layer "In6.Cu")
		(net "M_K_CPU0_SB_DQ<25>")
	)
	(segment
		(start 436.597806 -311.659778)
		(end 437.44769 -310.809894)
		(width 0.14478)
		(layer "In6.Cu")
		(net "M_K_CPU0_SB_DQ<25>")
	)
	(segment
		(start 429.06442 -311.660032)
		(end 429.914304 -310.810148)
		(width 0.14478)
		(layer "In6.Cu")
		(net "M_K_CPU0_SB_DQ<25>")
	)
	(segment
		(start 389.308848 -289.741356)
		(end 389.40486 -289.766756)
		(width 0.0889)
		(layer "In6.Cu")
		(net "M_K_CPU0_SB_DQ<25>")
	)
	(segment
		(start 389.90778 -289.798506)
		(end 389.916162 -289.803332)
		(width 0.0889)
		(layer "In6.Cu")
		(net "M_K_CPU0_SB_DQ<25>")
	)
	(segment
		(start 437.44769 -310.809894)
		(end 446.219326 -310.809894)
		(width 0.14478)
		(layer "In6.Cu")
		(net "M_K_CPU0_SB_DQ<25>")
	)
	(segment
		(start 425.700698 -310.810148)
		(end 426.550582 -311.660032)
		(width 0.14478)
		(layer "In6.Cu")
		(net "M_K_CPU0_SB_DQ<25>")
	)
	(segment
		(start 421.520366 -311.660032)
		(end 422.37025 -310.810148)
		(width 0.14478)
		(layer "In6.Cu")
		(net "M_K_CPU0_SB_DQ<25>")
	)
	(segment
		(start 446.644268 -311.234836)
		(end 446.644268 -311.23509)
		(width 0.14478)
		(layer "In6.Cu")
		(net "M_K_CPU0_SB_DQ<25>")
	)
	(segment
		(start 414.826196 -310.810148)
		(end 418.156644 -310.810148)
		(width 0.14478)
		(layer "In6.Cu")
		(net "M_K_CPU0_SB_DQ<25>")
	)
	(segment
		(start 394.119354 -291.049202)
		(end 395.570456 -292.500304)
		(width 0.0889)
		(layer "In6.Cu")
		(net "M_K_CPU0_SB_DQ<25>")
	)
	(segment
		(start 433.084732 -310.810148)
		(end 433.934362 -311.659778)
		(width 0.14478)
		(layer "In6.Cu")
		(net "M_K_CPU0_SB_DQ<25>")
	)
	(arc
		(start 391.787634 -289.798506)
		(mid 391.967839 -289.848823)
		(end 392.149838 -289.805364)
		(width 0.0889)
		(layer "In6.Cu")
		(net "M_K_CPU0_SB_DQ<25>")
	)
	(arc
		(start 389.916162 -289.803332)
		(mid 390.09967 -289.848826)
		(end 390.281922 -289.798506)
		(width 0.0889)
		(layer "In6.Cu")
		(net "M_K_CPU0_SB_DQ<25>")
	)
	(arc
		(start 390.847834 -289.798506)
		(mid 391.034778 -289.848761)
		(end 391.221722 -289.798506)
		(width 0.0889)
		(layer "In6.Cu")
		(net "M_K_CPU0_SB_DQ<25>")
	)
	(arc
		(start 390.281922 -289.798506)
		(mid 390.564878 -289.722329)
		(end 390.847834 -289.798506)
		(width 0.0889)
		(layer "In6.Cu")
		(net "M_K_CPU0_SB_DQ<25>")
	)
	(arc
		(start 389.40486 -289.766756)
		(mid 389.660068 -289.723279)
		(end 389.90778 -289.798506)
		(width 0.0889)
		(layer "In6.Cu")
		(net "M_K_CPU0_SB_DQ<25>")
	)
	(arc
		(start 391.221722 -289.798506)
		(mid 391.504678 -289.722329)
		(end 391.787634 -289.798506)
		(width 0.0889)
		(layer "In6.Cu")
		(net "M_K_CPU0_SB_DQ<25>")
	)
	(segment
		(start 390.098026 -288.399982)
		(end 390.564878 -288.66592)
		(width 0.10668)
		(layer "F.Cu")
		(net "M_K_CPU0_SB_DQ<24>")
	)
	(segment
		(start 445.651128 -309.930292)
		(end 445.651128 -309.254652)
		(width 0.14478)
		(layer "In6.Cu")
		(net "M_K_CPU0_SB_DQ<24>")
	)
	(segment
		(start 437.466486 -309.109872)
		(end 443.852046 -309.109872)
		(width 0.14478)
		(layer "In6.Cu")
		(net "M_K_CPU0_SB_DQ<24>")
	)
	(segment
		(start 411.080458 -309.96001)
		(end 414.183068 -309.96001)
		(width 0.14478)
		(layer "In6.Cu")
		(net "M_K_CPU0_SB_DQ<24>")
	)
	(segment
		(start 443.996826 -309.254652)
		(end 443.996826 -309.930292)
		(width 0.14478)
		(layer "In6.Cu")
		(net "M_K_CPU0_SB_DQ<24>")
	)
	(segment
		(start 398.754854 -297.634406)
		(end 411.080458 -309.96001)
		(width 0.14478)
		(layer "In6.Cu")
		(net "M_K_CPU0_SB_DQ<24>")
	)
	(segment
		(start 444.54826 -309.930292)
		(end 444.54826 -309.254652)
		(width 0.14478)
		(layer "In6.Cu")
		(net "M_K_CPU0_SB_DQ<24>")
	)
	(segment
		(start 421.727122 -309.96001)
		(end 422.577006 -309.110126)
		(width 0.14478)
		(layer "In6.Cu")
		(net "M_K_CPU0_SB_DQ<24>")
	)
	(segment
		(start 414.183068 -309.96001)
		(end 415.032952 -309.110126)
		(width 0.14478)
		(layer "In6.Cu")
		(net "M_K_CPU0_SB_DQ<24>")
	)
	(segment
		(start 444.69304 -309.109872)
		(end 444.954914 -309.109872)
		(width 0.14478)
		(layer "In6.Cu")
		(net "M_K_CPU0_SB_DQ<24>")
	)
	(segment
		(start 436.616602 -309.959756)
		(end 437.466486 -309.109872)
		(width 0.14478)
		(layer "In6.Cu")
		(net "M_K_CPU0_SB_DQ<24>")
	)
	(segment
		(start 422.577006 -309.110126)
		(end 425.601638 -309.110126)
		(width 0.14478)
		(layer "In6.Cu")
		(net "M_K_CPU0_SB_DQ<24>")
	)
	(segment
		(start 418.057584 -309.110126)
		(end 418.907468 -309.96001)
		(width 0.14478)
		(layer "In6.Cu")
		(net "M_K_CPU0_SB_DQ<24>")
	)
	(segment
		(start 394.793724 -290.21151)
		(end 394.88364 -290.21151)
		(width 0.0889)
		(layer "In6.Cu")
		(net "M_K_CPU0_SB_DQ<24>")
	)
	(segment
		(start 445.099694 -309.930292)
		(end 445.244474 -310.075072)
		(width 0.14478)
		(layer "In6.Cu")
		(net "M_K_CPU0_SB_DQ<24>")
	)
	(segment
		(start 445.244474 -310.075072)
		(end 445.506348 -310.075072)
		(width 0.14478)
		(layer "In6.Cu")
		(net "M_K_CPU0_SB_DQ<24>")
	)
	(segment
		(start 390.564878 -288.66592)
		(end 390.718802 -288.93135)
		(width 0.0889)
		(layer "In6.Cu")
		(net "M_K_CPU0_SB_DQ<24>")
	)
	(segment
		(start 395.498574 -290.826444)
		(end 395.498574 -291.239956)
		(width 0.0889)
		(layer "In6.Cu")
		(net "M_K_CPU0_SB_DQ<24>")
	)
	(segment
		(start 426.451522 -309.96001)
		(end 429.271176 -309.96001)
		(width 0.14478)
		(layer "In6.Cu")
		(net "M_K_CPU0_SB_DQ<24>")
	)
	(segment
		(start 415.032952 -309.110126)
		(end 418.057584 -309.110126)
		(width 0.14478)
		(layer "In6.Cu")
		(net "M_K_CPU0_SB_DQ<24>")
	)
	(segment
		(start 418.907468 -309.96001)
		(end 421.727122 -309.96001)
		(width 0.14478)
		(layer "In6.Cu")
		(net "M_K_CPU0_SB_DQ<24>")
	)
	(segment
		(start 444.54826 -309.254652)
		(end 444.69304 -309.109872)
		(width 0.14478)
		(layer "In6.Cu")
		(net "M_K_CPU0_SB_DQ<24>")
	)
	(segment
		(start 390.718802 -288.93135)
		(end 390.814814 -288.95675)
		(width 0.0889)
		(layer "In6.Cu")
		(net "M_K_CPU0_SB_DQ<24>")
	)
	(segment
		(start 445.506348 -310.075072)
		(end 445.651128 -309.930292)
		(width 0.14478)
		(layer "In6.Cu")
		(net "M_K_CPU0_SB_DQ<24>")
	)
	(segment
		(start 445.651128 -309.254652)
		(end 445.795908 -309.109872)
		(width 0.14478)
		(layer "In6.Cu")
		(net "M_K_CPU0_SB_DQ<24>")
	)
	(segment
		(start 430.12106 -309.110126)
		(end 432.908456 -309.110126)
		(width 0.14478)
		(layer "In6.Cu")
		(net "M_K_CPU0_SB_DQ<24>")
	)
	(segment
		(start 393.65936 -289.077146)
		(end 394.793724 -290.21151)
		(width 0.0889)
		(layer "In6.Cu")
		(net "M_K_CPU0_SB_DQ<24>")
	)
	(segment
		(start 446.219326 -309.109872)
		(end 446.644268 -309.534814)
		(width 0.14478)
		(layer "In6.Cu")
		(net "M_K_CPU0_SB_DQ<24>")
	)
	(segment
		(start 432.908456 -309.110126)
		(end 433.758086 -309.959756)
		(width 0.14478)
		(layer "In6.Cu")
		(net "M_K_CPU0_SB_DQ<24>")
	)
	(segment
		(start 444.954914 -309.109872)
		(end 445.099694 -309.254652)
		(width 0.14478)
		(layer "In6.Cu")
		(net "M_K_CPU0_SB_DQ<24>")
	)
	(segment
		(start 446.644268 -309.534814)
		(end 446.644268 -309.535068)
		(width 0.14478)
		(layer "In6.Cu")
		(net "M_K_CPU0_SB_DQ<24>")
	)
	(segment
		(start 444.141606 -310.075072)
		(end 444.40348 -310.075072)
		(width 0.14478)
		(layer "In6.Cu")
		(net "M_K_CPU0_SB_DQ<24>")
	)
	(segment
		(start 391.317734 -288.9885)
		(end 391.326116 -288.993326)
		(width 0.0889)
		(layer "In6.Cu")
		(net "M_K_CPU0_SB_DQ<24>")
	)
	(segment
		(start 445.099694 -309.254652)
		(end 445.099694 -309.930292)
		(width 0.14478)
		(layer "In6.Cu")
		(net "M_K_CPU0_SB_DQ<24>")
	)
	(segment
		(start 395.771624 -291.513006)
		(end 398.754854 -294.496236)
		(width 0.14478)
		(layer "In6.Cu")
		(net "M_K_CPU0_SB_DQ<24>")
	)
	(segment
		(start 445.795908 -309.109872)
		(end 446.219326 -309.109872)
		(width 0.14478)
		(layer "In6.Cu")
		(net "M_K_CPU0_SB_DQ<24>")
	)
	(segment
		(start 394.88364 -290.21151)
		(end 395.498574 -290.826444)
		(width 0.0889)
		(layer "In6.Cu")
		(net "M_K_CPU0_SB_DQ<24>")
	)
	(segment
		(start 425.601638 -309.110126)
		(end 426.451522 -309.96001)
		(width 0.14478)
		(layer "In6.Cu")
		(net "M_K_CPU0_SB_DQ<24>")
	)
	(segment
		(start 398.754854 -294.496236)
		(end 398.754854 -297.634406)
		(width 0.14478)
		(layer "In6.Cu")
		(net "M_K_CPU0_SB_DQ<24>")
	)
	(segment
		(start 444.40348 -310.075072)
		(end 444.54826 -309.930292)
		(width 0.14478)
		(layer "In6.Cu")
		(net "M_K_CPU0_SB_DQ<24>")
	)
	(segment
		(start 392.484864 -289.043872)
		(end 393.579096 -289.043872)
		(width 0.0889)
		(layer "In6.Cu")
		(net "M_K_CPU0_SB_DQ<24>")
	)
	(segment
		(start 395.498574 -291.239956)
		(end 395.771624 -291.513006)
		(width 0.0889)
		(layer "In6.Cu")
		(net "M_K_CPU0_SB_DQ<24>")
	)
	(segment
		(start 433.758086 -309.959756)
		(end 436.616602 -309.959756)
		(width 0.14478)
		(layer "In6.Cu")
		(net "M_K_CPU0_SB_DQ<24>")
	)
	(segment
		(start 443.852046 -309.109872)
		(end 443.996826 -309.254652)
		(width 0.14478)
		(layer "In6.Cu")
		(net "M_K_CPU0_SB_DQ<24>")
	)
	(segment
		(start 443.996826 -309.930292)
		(end 444.141606 -310.075072)
		(width 0.14478)
		(layer "In6.Cu")
		(net "M_K_CPU0_SB_DQ<24>")
	)
	(segment
		(start 429.271176 -309.96001)
		(end 430.12106 -309.110126)
		(width 0.14478)
		(layer "In6.Cu")
		(net "M_K_CPU0_SB_DQ<24>")
	)
	(arc
		(start 391.691876 -288.9885)
		(mid 391.968689 -288.912357)
		(end 392.24712 -288.982404)
		(width 0.0889)
		(layer "In6.Cu")
		(net "M_K_CPU0_SB_DQ<24>")
	)
	(arc
		(start 391.326116 -288.993326)
		(mid 391.509624 -289.03882)
		(end 391.691876 -288.9885)
		(width 0.0889)
		(layer "In6.Cu")
		(net "M_K_CPU0_SB_DQ<24>")
	)
	(arc
		(start 390.814814 -288.95675)
		(mid 391.070022 -288.913273)
		(end 391.317734 -288.9885)
		(width 0.0889)
		(layer "In6.Cu")
		(net "M_K_CPU0_SB_DQ<24>")
	)
	(arc
		(start 392.24712 -288.982404)
		(mid 392.362091 -289.028212)
		(end 392.484864 -289.043872)
		(width 0.0889)
		(layer "In6.Cu")
		(net "M_K_CPU0_SB_DQ<24>")
	)
	(arc
		(start 393.579096 -289.043872)
		(mid 393.622531 -289.05253)
		(end 393.65936 -289.077146)
		(width 0.0889)
		(layer "In6.Cu")
		(net "M_K_CPU0_SB_DQ<24>")
	)
	(segment
		(start 389.157972 -288.399982)
		(end 389.624824 -288.66592)
		(width 0.10668)
		(layer "F.Cu")
		(net "M_K_CPU0_SB_DQ<23>")
	)
	(segment
		(start 442.119258 -308.260242)
		(end 442.5442 -308.685184)
		(width 0.14478)
		(layer "In6.Cu")
		(net "M_K_CPU0_SB_DQ<23>")
	)
	(segment
		(start 430.02835 -308.260242)
		(end 432.866292 -308.260242)
		(width 0.14478)
		(layer "In6.Cu")
		(net "M_K_CPU0_SB_DQ<23>")
	)
	(segment
		(start 441.239402 -308.394354)
		(end 441.239402 -308.12613)
		(width 0.14478)
		(layer "In6.Cu")
		(net "M_K_CPU0_SB_DQ<23>")
	)
	(segment
		(start 416.394138 -307.96611)
		(end 416.68827 -308.260242)
		(width 0.14478)
		(layer "In6.Cu")
		(net "M_K_CPU0_SB_DQ<23>")
	)
	(segment
		(start 413.433514 -308.80431)
		(end 413.739584 -309.11038)
		(width 0.14478)
		(layer "In6.Cu")
		(net "M_K_CPU0_SB_DQ<23>")
	)
	(segment
		(start 413.739584 -309.11038)
		(end 414.090104 -309.11038)
		(width 0.14478)
		(layer "In6.Cu")
		(net "M_K_CPU0_SB_DQ<23>")
	)
	(segment
		(start 416.950652 -308.260242)
		(end 417.244784 -307.96611)
		(width 0.14478)
		(layer "In6.Cu")
		(net "M_K_CPU0_SB_DQ<23>")
	)
	(segment
		(start 417.244784 -307.96611)
		(end 417.507166 -307.96611)
		(width 0.14478)
		(layer "In6.Cu")
		(net "M_K_CPU0_SB_DQ<23>")
	)
	(segment
		(start 418.122608 -308.260242)
		(end 418.972746 -309.11038)
		(width 0.14478)
		(layer "In6.Cu")
		(net "M_K_CPU0_SB_DQ<23>")
	)
	(segment
		(start 389.624824 -288.66592)
		(end 389.4709 -288.40049)
		(width 0.0889)
		(layer "In6.Cu")
		(net "M_K_CPU0_SB_DQ<23>")
	)
	(segment
		(start 425.666662 -308.260242)
		(end 426.5168 -309.11038)
		(width 0.14478)
		(layer "In6.Cu")
		(net "M_K_CPU0_SB_DQ<23>")
	)
	(segment
		(start 414.940242 -308.260242)
		(end 415.837624 -308.260242)
		(width 0.14478)
		(layer "In6.Cu")
		(net "M_K_CPU0_SB_DQ<23>")
	)
	(segment
		(start 441.790836 -308.126384)
		(end 441.924694 -308.260242)
		(width 0.14478)
		(layer "In6.Cu")
		(net "M_K_CPU0_SB_DQ<23>")
	)
	(segment
		(start 422.484296 -308.260242)
		(end 425.666662 -308.260242)
		(width 0.14478)
		(layer "In6.Cu")
		(net "M_K_CPU0_SB_DQ<23>")
	)
	(segment
		(start 441.790836 -308.12613)
		(end 441.790836 -308.126384)
		(width 0.14478)
		(layer "In6.Cu")
		(net "M_K_CPU0_SB_DQ<23>")
	)
	(segment
		(start 441.239402 -308.12613)
		(end 441.37326 -307.992272)
		(width 0.14478)
		(layer "In6.Cu")
		(net "M_K_CPU0_SB_DQ<23>")
	)
	(segment
		(start 392.716004 -288.15919)
		(end 393.504928 -288.15919)
		(width 0.0889)
		(layer "In6.Cu")
		(net "M_K_CPU0_SB_DQ<23>")
	)
	(segment
		(start 440.136534 -308.126384)
		(end 440.136534 -308.12613)
		(width 0.14478)
		(layer "In6.Cu")
		(net "M_K_CPU0_SB_DQ<23>")
	)
	(segment
		(start 440.270392 -307.992272)
		(end 440.55411 -307.992272)
		(width 0.14478)
		(layer "In6.Cu")
		(net "M_K_CPU0_SB_DQ<23>")
	)
	(segment
		(start 433.715922 -309.109872)
		(end 436.55742 -309.109872)
		(width 0.14478)
		(layer "In6.Cu")
		(net "M_K_CPU0_SB_DQ<23>")
	)
	(segment
		(start 394.901674 -289.93211)
		(end 395.040104 -289.93211)
		(width 0.0889)
		(layer "In6.Cu")
		(net "M_K_CPU0_SB_DQ<23>")
	)
	(segment
		(start 416.68827 -308.260242)
		(end 416.950652 -308.260242)
		(width 0.14478)
		(layer "In6.Cu")
		(net "M_K_CPU0_SB_DQ<23>")
	)
	(segment
		(start 412.626556 -309.11038)
		(end 412.877 -309.11038)
		(width 0.14478)
		(layer "In6.Cu")
		(net "M_K_CPU0_SB_DQ<23>")
	)
	(segment
		(start 432.866292 -308.260242)
		(end 433.715922 -309.109872)
		(width 0.14478)
		(layer "In6.Cu")
		(net "M_K_CPU0_SB_DQ<23>")
	)
	(segment
		(start 393.883134 -288.91357)
		(end 394.901674 -289.93211)
		(width 0.0889)
		(layer "In6.Cu")
		(net "M_K_CPU0_SB_DQ<23>")
	)
	(segment
		(start 440.136534 -308.12613)
		(end 440.270392 -307.992272)
		(width 0.14478)
		(layer "In6.Cu")
		(net "M_K_CPU0_SB_DQ<23>")
	)
	(segment
		(start 391.317734 -288.343594)
		(end 391.326116 -288.338768)
		(width 0.0889)
		(layer "In6.Cu")
		(net "M_K_CPU0_SB_DQ<23>")
	)
	(segment
		(start 418.972746 -309.11038)
		(end 421.634158 -309.11038)
		(width 0.14478)
		(layer "In6.Cu")
		(net "M_K_CPU0_SB_DQ<23>")
	)
	(segment
		(start 411.017974 -309.11038)
		(end 411.763972 -309.11038)
		(width 0.14478)
		(layer "In6.Cu")
		(net "M_K_CPU0_SB_DQ<23>")
	)
	(segment
		(start 416.131756 -307.96611)
		(end 416.394138 -307.96611)
		(width 0.14478)
		(layer "In6.Cu")
		(net "M_K_CPU0_SB_DQ<23>")
	)
	(segment
		(start 440.55411 -307.992272)
		(end 440.687968 -308.12613)
		(width 0.14478)
		(layer "In6.Cu")
		(net "M_K_CPU0_SB_DQ<23>")
	)
	(segment
		(start 441.656978 -307.992272)
		(end 441.790836 -308.12613)
		(width 0.14478)
		(layer "In6.Cu")
		(net "M_K_CPU0_SB_DQ<23>")
	)
	(segment
		(start 412.877 -309.11038)
		(end 413.18307 -308.80431)
		(width 0.14478)
		(layer "In6.Cu")
		(net "M_K_CPU0_SB_DQ<23>")
	)
	(segment
		(start 389.4709 -288.40049)
		(end 389.492998 -288.317432)
		(width 0.0889)
		(layer "In6.Cu")
		(net "M_K_CPU0_SB_DQ<23>")
	)
	(segment
		(start 415.837624 -308.260242)
		(end 416.131756 -307.96611)
		(width 0.14478)
		(layer "In6.Cu")
		(net "M_K_CPU0_SB_DQ<23>")
	)
	(segment
		(start 440.821826 -308.528212)
		(end 441.105544 -308.528212)
		(width 0.14478)
		(layer "In6.Cu")
		(net "M_K_CPU0_SB_DQ<23>")
	)
	(segment
		(start 426.5168 -309.11038)
		(end 429.178212 -309.11038)
		(width 0.14478)
		(layer "In6.Cu")
		(net "M_K_CPU0_SB_DQ<23>")
	)
	(segment
		(start 421.634158 -309.11038)
		(end 422.484296 -308.260242)
		(width 0.14478)
		(layer "In6.Cu")
		(net "M_K_CPU0_SB_DQ<23>")
	)
	(segment
		(start 417.507166 -307.96611)
		(end 417.801298 -308.260242)
		(width 0.14478)
		(layer "In6.Cu")
		(net "M_K_CPU0_SB_DQ<23>")
	)
	(segment
		(start 393.883134 -288.537396)
		(end 393.883134 -288.91357)
		(width 0.0889)
		(layer "In6.Cu")
		(net "M_K_CPU0_SB_DQ<23>")
	)
	(segment
		(start 395.78534 -290.677346)
		(end 399.313654 -294.20566)
		(width 0.14478)
		(layer "In6.Cu")
		(net "M_K_CPU0_SB_DQ<23>")
	)
	(segment
		(start 417.801298 -308.260242)
		(end 418.122608 -308.260242)
		(width 0.14478)
		(layer "In6.Cu")
		(net "M_K_CPU0_SB_DQ<23>")
	)
	(segment
		(start 393.504928 -288.15919)
		(end 393.883134 -288.537396)
		(width 0.0889)
		(layer "In6.Cu")
		(net "M_K_CPU0_SB_DQ<23>")
	)
	(segment
		(start 399.313654 -297.40606)
		(end 411.017974 -309.11038)
		(width 0.14478)
		(layer "In6.Cu")
		(net "M_K_CPU0_SB_DQ<23>")
	)
	(segment
		(start 440.687968 -308.394354)
		(end 440.821826 -308.528212)
		(width 0.14478)
		(layer "In6.Cu")
		(net "M_K_CPU0_SB_DQ<23>")
	)
	(segment
		(start 412.320486 -308.80431)
		(end 412.626556 -309.11038)
		(width 0.14478)
		(layer "In6.Cu")
		(net "M_K_CPU0_SB_DQ<23>")
	)
	(segment
		(start 414.090104 -309.11038)
		(end 414.940242 -308.260242)
		(width 0.14478)
		(layer "In6.Cu")
		(net "M_K_CPU0_SB_DQ<23>")
	)
	(segment
		(start 441.105544 -308.528212)
		(end 441.239402 -308.394354)
		(width 0.14478)
		(layer "In6.Cu")
		(net "M_K_CPU0_SB_DQ<23>")
	)
	(segment
		(start 413.18307 -308.80431)
		(end 413.433514 -308.80431)
		(width 0.14478)
		(layer "In6.Cu")
		(net "M_K_CPU0_SB_DQ<23>")
	)
	(segment
		(start 440.002676 -308.260242)
		(end 440.136534 -308.126384)
		(width 0.14478)
		(layer "In6.Cu")
		(net "M_K_CPU0_SB_DQ<23>")
	)
	(segment
		(start 437.40705 -308.260242)
		(end 440.002676 -308.260242)
		(width 0.14478)
		(layer "In6.Cu")
		(net "M_K_CPU0_SB_DQ<23>")
	)
	(segment
		(start 429.178212 -309.11038)
		(end 430.02835 -308.260242)
		(width 0.14478)
		(layer "In6.Cu")
		(net "M_K_CPU0_SB_DQ<23>")
	)
	(segment
		(start 395.040104 -289.93211)
		(end 395.78534 -290.677346)
		(width 0.0889)
		(layer "In6.Cu")
		(net "M_K_CPU0_SB_DQ<23>")
	)
	(segment
		(start 399.313654 -294.20566)
		(end 399.313654 -297.40606)
		(width 0.14478)
		(layer "In6.Cu")
		(net "M_K_CPU0_SB_DQ<23>")
	)
	(segment
		(start 390.74344 -288.338768)
		(end 390.751822 -288.343594)
		(width 0.0889)
		(layer "In6.Cu")
		(net "M_K_CPU0_SB_DQ<23>")
	)
	(segment
		(start 436.55742 -309.109872)
		(end 437.40705 -308.260242)
		(width 0.14478)
		(layer "In6.Cu")
		(net "M_K_CPU0_SB_DQ<23>")
	)
	(segment
		(start 441.37326 -307.992272)
		(end 441.656978 -307.992272)
		(width 0.14478)
		(layer "In6.Cu")
		(net "M_K_CPU0_SB_DQ<23>")
	)
	(segment
		(start 411.763972 -309.11038)
		(end 412.070042 -308.80431)
		(width 0.14478)
		(layer "In6.Cu")
		(net "M_K_CPU0_SB_DQ<23>")
	)
	(segment
		(start 412.070042 -308.80431)
		(end 412.320486 -308.80431)
		(width 0.14478)
		(layer "In6.Cu")
		(net "M_K_CPU0_SB_DQ<23>")
	)
	(segment
		(start 440.687968 -308.12613)
		(end 440.687968 -308.394354)
		(width 0.14478)
		(layer "In6.Cu")
		(net "M_K_CPU0_SB_DQ<23>")
	)
	(segment
		(start 392.24712 -288.34969)
		(end 392.484102 -288.21888)
		(width 0.0889)
		(layer "In6.Cu")
		(net "M_K_CPU0_SB_DQ<23>")
	)
	(segment
		(start 441.924694 -308.260242)
		(end 442.119258 -308.260242)
		(width 0.14478)
		(layer "In6.Cu")
		(net "M_K_CPU0_SB_DQ<23>")
	)
	(arc
		(start 392.484102 -288.21888)
		(mid 392.59627 -288.174327)
		(end 392.716004 -288.15919)
		(width 0.0889)
		(layer "In6.Cu")
		(net "M_K_CPU0_SB_DQ<23>")
	)
	(arc
		(start 390.37768 -288.343594)
		(mid 390.559931 -288.29321)
		(end 390.74344 -288.338768)
		(width 0.0889)
		(layer "In6.Cu")
		(net "M_K_CPU0_SB_DQ<23>")
	)
	(arc
		(start 390.751822 -288.343594)
		(mid 391.034778 -288.419771)
		(end 391.317734 -288.343594)
		(width 0.0889)
		(layer "In6.Cu")
		(net "M_K_CPU0_SB_DQ<23>")
	)
	(arc
		(start 389.811768 -288.343594)
		(mid 390.094724 -288.419771)
		(end 390.37768 -288.343594)
		(width 0.0889)
		(layer "In6.Cu")
		(net "M_K_CPU0_SB_DQ<23>")
	)
	(arc
		(start 391.326116 -288.338768)
		(mid 391.509624 -288.293243)
		(end 391.691876 -288.343594)
		(width 0.0889)
		(layer "In6.Cu")
		(net "M_K_CPU0_SB_DQ<23>")
	)
	(arc
		(start 389.492998 -288.317432)
		(mid 389.655329 -288.294583)
		(end 389.811768 -288.343594)
		(width 0.0889)
		(layer "In6.Cu")
		(net "M_K_CPU0_SB_DQ<23>")
	)
	(arc
		(start 391.691876 -288.343594)
		(mid 391.968689 -288.419737)
		(end 392.24712 -288.34969)
		(width 0.0889)
		(layer "In6.Cu")
		(net "M_K_CPU0_SB_DQ<23>")
	)
	(segment
		(start 390.567926 -287.59023)
		(end 391.034778 -287.856168)
		(width 0.10668)
		(layer "F.Cu")
		(net "M_K_CPU0_SB_DQ<22>")
	)
	(segment
		(start 421.634158 -307.410358)
		(end 422.484296 -306.56022)
		(width 0.14478)
		(layer "In6.Cu")
		(net "M_K_CPU0_SB_DQ<22>")
	)
	(segment
		(start 392.561826 -287.64103)
		(end 393.988798 -287.64103)
		(width 0.0889)
		(layer "In6.Cu")
		(net "M_K_CPU0_SB_DQ<22>")
	)
	(segment
		(start 440.597036 -306.769008)
		(end 440.741816 -306.913788)
		(width 0.14478)
		(layer "In6.Cu")
		(net "M_K_CPU0_SB_DQ<22>")
	)
	(segment
		(start 395.719808 -289.32505)
		(end 400.228054 -293.833296)
		(width 0.14478)
		(layer "In6.Cu")
		(net "M_K_CPU0_SB_DQ<22>")
	)
	(segment
		(start 418.972746 -307.410358)
		(end 421.634158 -307.410358)
		(width 0.14478)
		(layer "In6.Cu")
		(net "M_K_CPU0_SB_DQ<22>")
	)
	(segment
		(start 416.409886 -306.56022)
		(end 416.680396 -306.28971)
		(width 0.14478)
		(layer "In6.Cu")
		(net "M_K_CPU0_SB_DQ<22>")
	)
	(segment
		(start 441.00369 -306.913788)
		(end 441.14847 -306.769008)
		(width 0.14478)
		(layer "In6.Cu")
		(net "M_K_CPU0_SB_DQ<22>")
	)
	(segment
		(start 438.327546 -306.196492)
		(end 438.472326 -306.341272)
		(width 0.14478)
		(layer "In6.Cu")
		(net "M_K_CPU0_SB_DQ<22>")
	)
	(segment
		(start 438.472326 -306.41544)
		(end 438.617106 -306.56022)
		(width 0.14478)
		(layer "In6.Cu")
		(net "M_K_CPU0_SB_DQ<22>")
	)
	(segment
		(start 411.155388 -306.732432)
		(end 411.417262 -306.732432)
		(width 0.14478)
		(layer "In6.Cu")
		(net "M_K_CPU0_SB_DQ<22>")
	)
	(segment
		(start 426.5168 -307.410358)
		(end 429.178212 -307.410358)
		(width 0.14478)
		(layer "In6.Cu")
		(net "M_K_CPU0_SB_DQ<22>")
	)
	(segment
		(start 437.920892 -306.41544)
		(end 437.920892 -306.341272)
		(width 0.14478)
		(layer "In6.Cu")
		(net "M_K_CPU0_SB_DQ<22>")
	)
	(segment
		(start 417.23691 -306.56022)
		(end 418.122608 -306.56022)
		(width 0.14478)
		(layer "In6.Cu")
		(net "M_K_CPU0_SB_DQ<22>")
	)
	(segment
		(start 394.069062 -287.674304)
		(end 395.719808 -289.32505)
		(width 0.0889)
		(layer "In6.Cu")
		(net "M_K_CPU0_SB_DQ<22>")
	)
	(segment
		(start 410.604716 -307.410358)
		(end 410.865828 -307.410358)
		(width 0.14478)
		(layer "In6.Cu")
		(net "M_K_CPU0_SB_DQ<22>")
	)
	(segment
		(start 437.776112 -306.56022)
		(end 437.920892 -306.41544)
		(width 0.14478)
		(layer "In6.Cu")
		(net "M_K_CPU0_SB_DQ<22>")
	)
	(segment
		(start 411.562042 -306.877212)
		(end 411.562042 -307.265578)
		(width 0.14478)
		(layer "In6.Cu")
		(net "M_K_CPU0_SB_DQ<22>")
	)
	(segment
		(start 440.045602 -306.41544)
		(end 440.045602 -306.351432)
		(width 0.14478)
		(layer "In6.Cu")
		(net "M_K_CPU0_SB_DQ<22>")
	)
	(segment
		(start 432.776884 -306.56022)
		(end 433.626514 -307.40985)
		(width 0.14478)
		(layer "In6.Cu")
		(net "M_K_CPU0_SB_DQ<22>")
	)
	(segment
		(start 412.258256 -306.732432)
		(end 412.52013 -306.732432)
		(width 0.14478)
		(layer "In6.Cu")
		(net "M_K_CPU0_SB_DQ<22>")
	)
	(segment
		(start 438.617106 -306.56022)
		(end 439.900822 -306.56022)
		(width 0.14478)
		(layer "In6.Cu")
		(net "M_K_CPU0_SB_DQ<22>")
	)
	(segment
		(start 411.968696 -307.410358)
		(end 412.113476 -307.265578)
		(width 0.14478)
		(layer "In6.Cu")
		(net "M_K_CPU0_SB_DQ<22>")
	)
	(segment
		(start 412.66491 -306.877212)
		(end 412.66491 -307.265578)
		(width 0.14478)
		(layer "In6.Cu")
		(net "M_K_CPU0_SB_DQ<22>")
	)
	(segment
		(start 412.52013 -306.732432)
		(end 412.66491 -306.877212)
		(width 0.14478)
		(layer "In6.Cu")
		(net "M_K_CPU0_SB_DQ<22>")
	)
	(segment
		(start 412.113476 -306.877212)
		(end 412.258256 -306.732432)
		(width 0.14478)
		(layer "In6.Cu")
		(net "M_K_CPU0_SB_DQ<22>")
	)
	(segment
		(start 440.190382 -306.206652)
		(end 440.452256 -306.206652)
		(width 0.14478)
		(layer "In6.Cu")
		(net "M_K_CPU0_SB_DQ<22>")
	)
	(segment
		(start 400.228054 -297.033696)
		(end 410.604716 -307.410358)
		(width 0.14478)
		(layer "In6.Cu")
		(net "M_K_CPU0_SB_DQ<22>")
	)
	(segment
		(start 392.153394 -287.528762)
		(end 392.161776 -287.533588)
		(width 0.0889)
		(layer "In6.Cu")
		(net "M_K_CPU0_SB_DQ<22>")
	)
	(segment
		(start 400.228054 -293.833296)
		(end 400.228054 -297.033696)
		(width 0.14478)
		(layer "In6.Cu")
		(net "M_K_CPU0_SB_DQ<22>")
	)
	(segment
		(start 433.626514 -307.40985)
		(end 436.730648 -307.40985)
		(width 0.14478)
		(layer "In6.Cu")
		(net "M_K_CPU0_SB_DQ<22>")
	)
	(segment
		(start 414.940242 -306.56022)
		(end 415.296858 -306.56022)
		(width 0.14478)
		(layer "In6.Cu")
		(net "M_K_CPU0_SB_DQ<22>")
	)
	(segment
		(start 425.07535 -306.26431)
		(end 425.82719 -307.01615)
		(width 0.14478)
		(layer "In6.Cu")
		(net "M_K_CPU0_SB_DQ<22>")
	)
	(segment
		(start 436.730648 -307.40985)
		(end 437.580278 -306.56022)
		(width 0.14478)
		(layer "In6.Cu")
		(net "M_K_CPU0_SB_DQ<22>")
	)
	(segment
		(start 411.562042 -307.265578)
		(end 411.706822 -307.410358)
		(width 0.14478)
		(layer "In6.Cu")
		(net "M_K_CPU0_SB_DQ<22>")
	)
	(segment
		(start 426.122592 -307.01615)
		(end 426.5168 -307.410358)
		(width 0.14478)
		(layer "In6.Cu")
		(net "M_K_CPU0_SB_DQ<22>")
	)
	(segment
		(start 415.853372 -306.28971)
		(end 416.123882 -306.56022)
		(width 0.14478)
		(layer "In6.Cu")
		(net "M_K_CPU0_SB_DQ<22>")
	)
	(segment
		(start 437.920892 -306.341272)
		(end 438.065672 -306.196492)
		(width 0.14478)
		(layer "In6.Cu")
		(net "M_K_CPU0_SB_DQ<22>")
	)
	(segment
		(start 416.680396 -306.28971)
		(end 416.9664 -306.28971)
		(width 0.14478)
		(layer "In6.Cu")
		(net "M_K_CPU0_SB_DQ<22>")
	)
	(segment
		(start 437.580278 -306.56022)
		(end 437.776112 -306.56022)
		(width 0.14478)
		(layer "In6.Cu")
		(net "M_K_CPU0_SB_DQ<22>")
	)
	(segment
		(start 440.452256 -306.206652)
		(end 440.597036 -306.351432)
		(width 0.14478)
		(layer "In6.Cu")
		(net "M_K_CPU0_SB_DQ<22>")
	)
	(segment
		(start 424.814746 -306.26431)
		(end 425.07535 -306.26431)
		(width 0.14478)
		(layer "In6.Cu")
		(net "M_K_CPU0_SB_DQ<22>")
	)
	(segment
		(start 414.090104 -307.410358)
		(end 414.940242 -306.56022)
		(width 0.14478)
		(layer "In6.Cu")
		(net "M_K_CPU0_SB_DQ<22>")
	)
	(segment
		(start 441.14847 -306.769008)
		(end 441.14847 -306.351432)
		(width 0.14478)
		(layer "In6.Cu")
		(net "M_K_CPU0_SB_DQ<22>")
	)
	(segment
		(start 424.518836 -306.56022)
		(end 424.814746 -306.26431)
		(width 0.14478)
		(layer "In6.Cu")
		(net "M_K_CPU0_SB_DQ<22>")
	)
	(segment
		(start 390.880854 -287.590738)
		(end 390.903206 -287.507426)
		(width 0.0889)
		(layer "In6.Cu")
		(net "M_K_CPU0_SB_DQ<22>")
	)
	(segment
		(start 415.296858 -306.56022)
		(end 415.567368 -306.28971)
		(width 0.14478)
		(layer "In6.Cu")
		(net "M_K_CPU0_SB_DQ<22>")
	)
	(segment
		(start 416.9664 -306.28971)
		(end 417.23691 -306.56022)
		(width 0.14478)
		(layer "In6.Cu")
		(net "M_K_CPU0_SB_DQ<22>")
	)
	(segment
		(start 415.567368 -306.28971)
		(end 415.853372 -306.28971)
		(width 0.14478)
		(layer "In6.Cu")
		(net "M_K_CPU0_SB_DQ<22>")
	)
	(segment
		(start 410.865828 -307.410358)
		(end 411.010608 -307.265578)
		(width 0.14478)
		(layer "In6.Cu")
		(net "M_K_CPU0_SB_DQ<22>")
	)
	(segment
		(start 418.122608 -306.56022)
		(end 418.972746 -307.410358)
		(width 0.14478)
		(layer "In6.Cu")
		(net "M_K_CPU0_SB_DQ<22>")
	)
	(segment
		(start 411.706822 -307.410358)
		(end 411.968696 -307.410358)
		(width 0.14478)
		(layer "In6.Cu")
		(net "M_K_CPU0_SB_DQ<22>")
	)
	(segment
		(start 441.699904 -306.351432)
		(end 441.699904 -306.41544)
		(width 0.14478)
		(layer "In6.Cu")
		(net "M_K_CPU0_SB_DQ<22>")
	)
	(segment
		(start 440.045602 -306.351432)
		(end 440.190382 -306.206652)
		(width 0.14478)
		(layer "In6.Cu")
		(net "M_K_CPU0_SB_DQ<22>")
	)
	(segment
		(start 429.178212 -307.410358)
		(end 430.02835 -306.56022)
		(width 0.14478)
		(layer "In6.Cu")
		(net "M_K_CPU0_SB_DQ<22>")
	)
	(segment
		(start 411.010608 -307.265578)
		(end 411.010608 -306.877212)
		(width 0.14478)
		(layer "In6.Cu")
		(net "M_K_CPU0_SB_DQ<22>")
	)
	(segment
		(start 411.417262 -306.732432)
		(end 411.562042 -306.877212)
		(width 0.14478)
		(layer "In6.Cu")
		(net "M_K_CPU0_SB_DQ<22>")
	)
	(segment
		(start 441.844684 -306.56022)
		(end 442.119258 -306.56022)
		(width 0.14478)
		(layer "In6.Cu")
		(net "M_K_CPU0_SB_DQ<22>")
	)
	(segment
		(start 442.119258 -306.56022)
		(end 442.5442 -306.985162)
		(width 0.14478)
		(layer "In6.Cu")
		(net "M_K_CPU0_SB_DQ<22>")
	)
	(segment
		(start 425.82719 -307.01615)
		(end 426.122592 -307.01615)
		(width 0.14478)
		(layer "In6.Cu")
		(net "M_K_CPU0_SB_DQ<22>")
	)
	(segment
		(start 412.113476 -307.265578)
		(end 412.113476 -306.877212)
		(width 0.14478)
		(layer "In6.Cu")
		(net "M_K_CPU0_SB_DQ<22>")
	)
	(segment
		(start 416.123882 -306.56022)
		(end 416.409886 -306.56022)
		(width 0.14478)
		(layer "In6.Cu")
		(net "M_K_CPU0_SB_DQ<22>")
	)
	(segment
		(start 411.010608 -306.877212)
		(end 411.155388 -306.732432)
		(width 0.14478)
		(layer "In6.Cu")
		(net "M_K_CPU0_SB_DQ<22>")
	)
	(segment
		(start 438.065672 -306.196492)
		(end 438.327546 -306.196492)
		(width 0.14478)
		(layer "In6.Cu")
		(net "M_K_CPU0_SB_DQ<22>")
	)
	(segment
		(start 391.034778 -287.856168)
		(end 390.880854 -287.590738)
		(width 0.0889)
		(layer "In6.Cu")
		(net "M_K_CPU0_SB_DQ<22>")
	)
	(segment
		(start 412.66491 -307.265578)
		(end 412.80969 -307.410358)
		(width 0.14478)
		(layer "In6.Cu")
		(net "M_K_CPU0_SB_DQ<22>")
	)
	(segment
		(start 441.14847 -306.351432)
		(end 441.29325 -306.206652)
		(width 0.14478)
		(layer "In6.Cu")
		(net "M_K_CPU0_SB_DQ<22>")
	)
	(segment
		(start 441.555124 -306.206652)
		(end 441.699904 -306.351432)
		(width 0.14478)
		(layer "In6.Cu")
		(net "M_K_CPU0_SB_DQ<22>")
	)
	(segment
		(start 440.741816 -306.913788)
		(end 441.00369 -306.913788)
		(width 0.14478)
		(layer "In6.Cu")
		(net "M_K_CPU0_SB_DQ<22>")
	)
	(segment
		(start 422.484296 -306.56022)
		(end 424.518836 -306.56022)
		(width 0.14478)
		(layer "In6.Cu")
		(net "M_K_CPU0_SB_DQ<22>")
	)
	(segment
		(start 430.02835 -306.56022)
		(end 432.776884 -306.56022)
		(width 0.14478)
		(layer "In6.Cu")
		(net "M_K_CPU0_SB_DQ<22>")
	)
	(segment
		(start 440.597036 -306.351432)
		(end 440.597036 -306.769008)
		(width 0.14478)
		(layer "In6.Cu")
		(net "M_K_CPU0_SB_DQ<22>")
	)
	(segment
		(start 441.29325 -306.206652)
		(end 441.555124 -306.206652)
		(width 0.14478)
		(layer "In6.Cu")
		(net "M_K_CPU0_SB_DQ<22>")
	)
	(segment
		(start 438.472326 -306.341272)
		(end 438.472326 -306.41544)
		(width 0.14478)
		(layer "In6.Cu")
		(net "M_K_CPU0_SB_DQ<22>")
	)
	(segment
		(start 439.900822 -306.56022)
		(end 440.045602 -306.41544)
		(width 0.14478)
		(layer "In6.Cu")
		(net "M_K_CPU0_SB_DQ<22>")
	)
	(segment
		(start 412.80969 -307.410358)
		(end 414.090104 -307.410358)
		(width 0.14478)
		(layer "In6.Cu")
		(net "M_K_CPU0_SB_DQ<22>")
	)
	(segment
		(start 441.699904 -306.41544)
		(end 441.844684 -306.56022)
		(width 0.14478)
		(layer "In6.Cu")
		(net "M_K_CPU0_SB_DQ<22>")
	)
	(arc
		(start 393.988798 -287.64103)
		(mid 394.032233 -287.649688)
		(end 394.069062 -287.674304)
		(width 0.0889)
		(layer "In6.Cu")
		(net "M_K_CPU0_SB_DQ<22>")
	)
	(arc
		(start 391.221722 -287.533588)
		(mid 391.504678 -287.609731)
		(end 391.787634 -287.533588)
		(width 0.0889)
		(layer "In6.Cu")
		(net "M_K_CPU0_SB_DQ<22>")
	)
	(arc
		(start 391.787634 -287.533588)
		(mid 391.969885 -287.483238)
		(end 392.153394 -287.528762)
		(width 0.0889)
		(layer "In6.Cu")
		(net "M_K_CPU0_SB_DQ<22>")
	)
	(arc
		(start 390.903206 -287.507426)
		(mid 391.065395 -287.484691)
		(end 391.221722 -287.533588)
		(width 0.0889)
		(layer "In6.Cu")
		(net "M_K_CPU0_SB_DQ<22>")
	)
	(arc
		(start 392.161776 -287.533588)
		(mid 392.354705 -287.613744)
		(end 392.561826 -287.64103)
		(width 0.0889)
		(layer "In6.Cu")
		(net "M_K_CPU0_SB_DQ<22>")
	)
	(segment
		(start 388.688072 -287.59023)
		(end 389.154924 -287.856168)
		(width 0.10668)
		(layer "F.Cu")
		(net "M_K_CPU0_SB_DQ<21>")
	)
	(segment
		(start 444.507874 -307.410104)
		(end 446.644268 -307.835046)
		(width 0.14478)
		(layer "In6.Cu")
		(net "M_K_CPU0_SB_DQ<21>")
	)
	(segment
		(start 410.810964 -308.260242)
		(end 413.402272 -308.260242)
		(width 0.14478)
		(layer "In6.Cu")
		(net "M_K_CPU0_SB_DQ<21>")
	)
	(segment
		(start 393.583414 -287.93567)
		(end 394.099034 -288.45129)
		(width 0.0889)
		(layer "In6.Cu")
		(net "M_K_CPU0_SB_DQ<21>")
	)
	(segment
		(start 421.031924 -308.260242)
		(end 423.08399 -307.410358)
		(width 0.14478)
		(layer "In6.Cu")
		(net "M_K_CPU0_SB_DQ<21>")
	)
	(segment
		(start 389.90778 -288.178494)
		(end 389.916162 -288.18332)
		(width 0.0889)
		(layer "In6.Cu")
		(net "M_K_CPU0_SB_DQ<21>")
	)
	(segment
		(start 430.505108 -307.410358)
		(end 432.337972 -307.410358)
		(width 0.14478)
		(layer "In6.Cu")
		(net "M_K_CPU0_SB_DQ<21>")
	)
	(segment
		(start 415.454084 -307.410358)
		(end 417.533836 -307.410358)
		(width 0.14478)
		(layer "In6.Cu")
		(net "M_K_CPU0_SB_DQ<21>")
	)
	(segment
		(start 426.955966 -308.260242)
		(end 428.453296 -308.260242)
		(width 0.14478)
		(layer "In6.Cu")
		(net "M_K_CPU0_SB_DQ<21>")
	)
	(segment
		(start 423.08399 -307.410358)
		(end 424.904154 -307.410358)
		(width 0.14478)
		(layer "In6.Cu")
		(net "M_K_CPU0_SB_DQ<21>")
	)
	(segment
		(start 419.585648 -308.260242)
		(end 421.031924 -308.260242)
		(width 0.14478)
		(layer "In6.Cu")
		(net "M_K_CPU0_SB_DQ<21>")
	)
	(segment
		(start 434.389276 -308.259988)
		(end 436.171086 -308.259988)
		(width 0.14478)
		(layer "In6.Cu")
		(net "M_K_CPU0_SB_DQ<21>")
	)
	(segment
		(start 424.904154 -307.410358)
		(end 426.955966 -308.260242)
		(width 0.14478)
		(layer "In6.Cu")
		(net "M_K_CPU0_SB_DQ<21>")
	)
	(segment
		(start 428.453296 -308.260242)
		(end 430.505108 -307.410358)
		(width 0.14478)
		(layer "In6.Cu")
		(net "M_K_CPU0_SB_DQ<21>")
	)
	(segment
		(start 399.770854 -294.019478)
		(end 399.770854 -297.220132)
		(width 0.14478)
		(layer "In6.Cu")
		(net "M_K_CPU0_SB_DQ<21>")
	)
	(segment
		(start 394.838174 -289.57651)
		(end 395.327886 -289.57651)
		(width 0.0889)
		(layer "In6.Cu")
		(net "M_K_CPU0_SB_DQ<21>")
	)
	(segment
		(start 389.154924 -287.856168)
		(end 389.308848 -288.121598)
		(width 0.0889)
		(layer "In6.Cu")
		(net "M_K_CPU0_SB_DQ<21>")
	)
	(segment
		(start 413.402272 -308.260242)
		(end 415.454084 -307.410358)
		(width 0.14478)
		(layer "In6.Cu")
		(net "M_K_CPU0_SB_DQ<21>")
	)
	(segment
		(start 436.171086 -308.259988)
		(end 438.222898 -307.410104)
		(width 0.14478)
		(layer "In6.Cu")
		(net "M_K_CPU0_SB_DQ<21>")
	)
	(segment
		(start 392.614912 -287.93567)
		(end 393.583414 -287.93567)
		(width 0.0889)
		(layer "In6.Cu")
		(net "M_K_CPU0_SB_DQ<21>")
	)
	(segment
		(start 432.337972 -307.410358)
		(end 434.389276 -308.259988)
		(width 0.14478)
		(layer "In6.Cu")
		(net "M_K_CPU0_SB_DQ<21>")
	)
	(segment
		(start 389.308848 -288.121598)
		(end 389.404606 -288.146998)
		(width 0.0889)
		(layer "In6.Cu")
		(net "M_K_CPU0_SB_DQ<21>")
	)
	(segment
		(start 394.099034 -288.45129)
		(end 394.099034 -288.83737)
		(width 0.0889)
		(layer "In6.Cu")
		(net "M_K_CPU0_SB_DQ<21>")
	)
	(segment
		(start 438.222898 -307.410104)
		(end 444.507874 -307.410104)
		(width 0.14478)
		(layer "In6.Cu")
		(net "M_K_CPU0_SB_DQ<21>")
	)
	(segment
		(start 395.327886 -289.57651)
		(end 395.803882 -290.052506)
		(width 0.0889)
		(layer "In6.Cu")
		(net "M_K_CPU0_SB_DQ<21>")
	)
	(segment
		(start 394.099034 -288.83737)
		(end 394.838174 -289.57651)
		(width 0.0889)
		(layer "In6.Cu")
		(net "M_K_CPU0_SB_DQ<21>")
	)
	(segment
		(start 395.803882 -290.052506)
		(end 399.770854 -294.019478)
		(width 0.14478)
		(layer "In6.Cu")
		(net "M_K_CPU0_SB_DQ<21>")
	)
	(segment
		(start 399.770854 -297.220132)
		(end 410.810964 -308.260242)
		(width 0.14478)
		(layer "In6.Cu")
		(net "M_K_CPU0_SB_DQ<21>")
	)
	(segment
		(start 417.533836 -307.410358)
		(end 419.585648 -308.260242)
		(width 0.14478)
		(layer "In6.Cu")
		(net "M_K_CPU0_SB_DQ<21>")
	)
	(arc
		(start 390.281922 -288.178494)
		(mid 390.564878 -288.102317)
		(end 390.847834 -288.178494)
		(width 0.0889)
		(layer "In6.Cu")
		(net "M_K_CPU0_SB_DQ<21>")
	)
	(arc
		(start 390.847834 -288.178494)
		(mid 391.034778 -288.228783)
		(end 391.221722 -288.178494)
		(width 0.0889)
		(layer "In6.Cu")
		(net "M_K_CPU0_SB_DQ<21>")
	)
	(arc
		(start 389.916162 -288.18332)
		(mid 390.09967 -288.228845)
		(end 390.281922 -288.178494)
		(width 0.0889)
		(layer "In6.Cu")
		(net "M_K_CPU0_SB_DQ<21>")
	)
	(arc
		(start 389.404606 -288.146998)
		(mid 389.659928 -288.103298)
		(end 389.90778 -288.178494)
		(width 0.0889)
		(layer "In6.Cu")
		(net "M_K_CPU0_SB_DQ<21>")
	)
	(arc
		(start 392.235436 -288.115248)
		(mid 392.40502 -287.982895)
		(end 392.614912 -287.93567)
		(width 0.0889)
		(layer "In6.Cu")
		(net "M_K_CPU0_SB_DQ<21>")
	)
	(arc
		(start 391.221722 -288.178494)
		(mid 391.504678 -288.102317)
		(end 391.787634 -288.178494)
		(width 0.0889)
		(layer "In6.Cu")
		(net "M_K_CPU0_SB_DQ<21>")
	)
	(arc
		(start 392.149838 -288.185352)
		(mid 392.196113 -288.154543)
		(end 392.235436 -288.115248)
		(width 0.0889)
		(layer "In6.Cu")
		(net "M_K_CPU0_SB_DQ<21>")
	)
	(arc
		(start 391.787634 -288.178494)
		(mid 391.967839 -288.228845)
		(end 392.149838 -288.185352)
		(width 0.0889)
		(layer "In6.Cu")
		(net "M_K_CPU0_SB_DQ<21>")
	)
	(segment
		(start 390.098026 -286.780224)
		(end 390.564878 -287.045908)
		(width 0.10668)
		(layer "F.Cu")
		(net "M_K_CPU0_SB_DQ<20>")
	)
	(segment
		(start 394.145008 -287.419034)
		(end 394.801344 -288.07537)
		(width 0.0889)
		(layer "In6.Cu")
		(net "M_K_CPU0_SB_DQ<20>")
	)
	(segment
		(start 395.113256 -288.07537)
		(end 395.83868 -288.800794)
		(width 0.0889)
		(layer "In6.Cu")
		(net "M_K_CPU0_SB_DQ<20>")
	)
	(segment
		(start 421.717724 -306.569618)
		(end 422.567608 -305.719734)
		(width 0.14478)
		(layer "In6.Cu")
		(net "M_K_CPU0_SB_DQ<20>")
	)
	(segment
		(start 390.718802 -287.311338)
		(end 390.814814 -287.336738)
		(width 0.0889)
		(layer "In6.Cu")
		(net "M_K_CPU0_SB_DQ<20>")
	)
	(segment
		(start 395.83868 -288.800794)
		(end 400.736054 -293.698168)
		(width 0.14478)
		(layer "In6.Cu")
		(net "M_K_CPU0_SB_DQ<20>")
	)
	(segment
		(start 445.193928 -306.36591)
		(end 445.424306 -306.36591)
		(width 0.14478)
		(layer "In6.Cu")
		(net "M_K_CPU0_SB_DQ<20>")
	)
	(segment
		(start 436.742586 -306.569618)
		(end 437.59247 -305.719734)
		(width 0.14478)
		(layer "In6.Cu")
		(net "M_K_CPU0_SB_DQ<20>")
	)
	(segment
		(start 400.736054 -296.898568)
		(end 410.061918 -306.224432)
		(width 0.14478)
		(layer "In6.Cu")
		(net "M_K_CPU0_SB_DQ<20>")
	)
	(segment
		(start 413.01289 -306.224432)
		(end 413.348678 -306.56022)
		(width 0.14478)
		(layer "In6.Cu")
		(net "M_K_CPU0_SB_DQ<20>")
	)
	(segment
		(start 445.587374 -306.202842)
		(end 445.587374 -305.87315)
		(width 0.14478)
		(layer "In6.Cu")
		(net "M_K_CPU0_SB_DQ<20>")
	)
	(segment
		(start 391.317734 -287.368488)
		(end 391.326116 -287.373314)
		(width 0.0889)
		(layer "In6.Cu")
		(net "M_K_CPU0_SB_DQ<20>")
	)
	(segment
		(start 415.023554 -305.719734)
		(end 418.066982 -305.719734)
		(width 0.14478)
		(layer "In6.Cu")
		(net "M_K_CPU0_SB_DQ<20>")
	)
	(segment
		(start 445.750442 -305.710082)
		(end 446.219326 -305.710082)
		(width 0.14478)
		(layer "In6.Cu")
		(net "M_K_CPU0_SB_DQ<20>")
	)
	(segment
		(start 445.424306 -306.36591)
		(end 445.587374 -306.202842)
		(width 0.14478)
		(layer "In6.Cu")
		(net "M_K_CPU0_SB_DQ<20>")
	)
	(segment
		(start 422.567608 -305.719734)
		(end 425.454572 -305.719734)
		(width 0.14478)
		(layer "In6.Cu")
		(net "M_K_CPU0_SB_DQ<20>")
	)
	(segment
		(start 446.219326 -305.710082)
		(end 446.644268 -306.135024)
		(width 0.14478)
		(layer "In6.Cu")
		(net "M_K_CPU0_SB_DQ<20>")
	)
	(segment
		(start 429.261524 -306.569872)
		(end 430.111662 -305.719734)
		(width 0.14478)
		(layer "In6.Cu")
		(net "M_K_CPU0_SB_DQ<20>")
	)
	(segment
		(start 410.061918 -306.224432)
		(end 413.01289 -306.224432)
		(width 0.14478)
		(layer "In6.Cu")
		(net "M_K_CPU0_SB_DQ<20>")
	)
	(segment
		(start 390.564878 -287.045908)
		(end 390.718802 -287.311338)
		(width 0.0889)
		(layer "In6.Cu")
		(net "M_K_CPU0_SB_DQ<20>")
	)
	(segment
		(start 418.916866 -306.569618)
		(end 421.717724 -306.569618)
		(width 0.14478)
		(layer "In6.Cu")
		(net "M_K_CPU0_SB_DQ<20>")
	)
	(segment
		(start 400.736054 -293.698168)
		(end 400.736054 -296.898568)
		(width 0.14478)
		(layer "In6.Cu")
		(net "M_K_CPU0_SB_DQ<20>")
	)
	(segment
		(start 426.30471 -306.569872)
		(end 429.261524 -306.569872)
		(width 0.14478)
		(layer "In6.Cu")
		(net "M_K_CPU0_SB_DQ<20>")
	)
	(segment
		(start 413.348678 -306.56022)
		(end 414.183068 -306.56022)
		(width 0.14478)
		(layer "In6.Cu")
		(net "M_K_CPU0_SB_DQ<20>")
	)
	(segment
		(start 437.59247 -305.719734)
		(end 444.877444 -305.719734)
		(width 0.14478)
		(layer "In6.Cu")
		(net "M_K_CPU0_SB_DQ<20>")
	)
	(segment
		(start 425.454572 -305.719734)
		(end 426.30471 -306.569872)
		(width 0.14478)
		(layer "In6.Cu")
		(net "M_K_CPU0_SB_DQ<20>")
	)
	(segment
		(start 414.183068 -306.56022)
		(end 415.023554 -305.719734)
		(width 0.14478)
		(layer "In6.Cu")
		(net "M_K_CPU0_SB_DQ<20>")
	)
	(segment
		(start 432.906678 -305.719734)
		(end 433.756562 -306.569618)
		(width 0.14478)
		(layer "In6.Cu")
		(net "M_K_CPU0_SB_DQ<20>")
	)
	(segment
		(start 445.03086 -305.87315)
		(end 445.03086 -306.202842)
		(width 0.14478)
		(layer "In6.Cu")
		(net "M_K_CPU0_SB_DQ<20>")
	)
	(segment
		(start 392.24712 -287.362392)
		(end 392.257534 -287.368488)
		(width 0.0889)
		(layer "In6.Cu")
		(net "M_K_CPU0_SB_DQ<20>")
	)
	(segment
		(start 445.587374 -305.87315)
		(end 445.750442 -305.710082)
		(width 0.14478)
		(layer "In6.Cu")
		(net "M_K_CPU0_SB_DQ<20>")
	)
	(segment
		(start 418.066982 -305.719734)
		(end 418.916866 -306.569618)
		(width 0.14478)
		(layer "In6.Cu")
		(net "M_K_CPU0_SB_DQ<20>")
	)
	(segment
		(start 394.801344 -288.07537)
		(end 395.113256 -288.07537)
		(width 0.0889)
		(layer "In6.Cu")
		(net "M_K_CPU0_SB_DQ<20>")
	)
	(segment
		(start 433.756562 -306.569618)
		(end 436.742586 -306.569618)
		(width 0.14478)
		(layer "In6.Cu")
		(net "M_K_CPU0_SB_DQ<20>")
	)
	(segment
		(start 430.111662 -305.719734)
		(end 432.906678 -305.719734)
		(width 0.14478)
		(layer "In6.Cu")
		(net "M_K_CPU0_SB_DQ<20>")
	)
	(segment
		(start 445.03086 -306.202842)
		(end 445.193928 -306.36591)
		(width 0.14478)
		(layer "In6.Cu")
		(net "M_K_CPU0_SB_DQ<20>")
	)
	(segment
		(start 444.877444 -305.719734)
		(end 445.03086 -305.87315)
		(width 0.14478)
		(layer "In6.Cu")
		(net "M_K_CPU0_SB_DQ<20>")
	)
	(segment
		(start 392.444478 -287.419034)
		(end 394.145008 -287.419034)
		(width 0.0889)
		(layer "In6.Cu")
		(net "M_K_CPU0_SB_DQ<20>")
	)
	(arc
		(start 392.257534 -287.368488)
		(mid 392.347652 -287.406163)
		(end 392.444478 -287.419034)
		(width 0.0889)
		(layer "In6.Cu")
		(net "M_K_CPU0_SB_DQ<20>")
	)
	(arc
		(start 390.814814 -287.336738)
		(mid 391.070022 -287.293281)
		(end 391.317734 -287.368488)
		(width 0.0889)
		(layer "In6.Cu")
		(net "M_K_CPU0_SB_DQ<20>")
	)
	(arc
		(start 391.326116 -287.373314)
		(mid 391.509624 -287.418808)
		(end 391.691876 -287.368488)
		(width 0.0889)
		(layer "In6.Cu")
		(net "M_K_CPU0_SB_DQ<20>")
	)
	(arc
		(start 391.691876 -287.368488)
		(mid 391.968689 -287.292379)
		(end 392.24712 -287.362392)
		(width 0.0889)
		(layer "In6.Cu")
		(net "M_K_CPU0_SB_DQ<20>")
	)
	(segment
		(start 388.688072 -274.630134)
		(end 389.154924 -274.896072)
		(width 0.10668)
		(layer "F.Cu")
		(net "M_K_CPU0_SB_DQ<1>")
	)
	(segment
		(start 392.149838 -275.22551)
		(end 392.161522 -275.218652)
		(width 0.0889)
		(layer "In6.Cu")
		(net "M_K_CPU0_SB_DQ<1>")
	)
	(segment
		(start 444.507874 -282.760166)
		(end 446.644268 -283.185108)
		(width 0.14478)
		(layer "In6.Cu")
		(net "M_K_CPU0_SB_DQ<1>")
	)
	(segment
		(start 432.75123 -282.760166)
		(end 434.803042 -283.61005)
		(width 0.14478)
		(layer "In6.Cu")
		(net "M_K_CPU0_SB_DQ<1>")
	)
	(segment
		(start 393.101576 -275.218652)
		(end 393.495022 -274.98675)
		(width 0.0889)
		(layer "In6.Cu")
		(net "M_K_CPU0_SB_DQ<1>")
	)
	(segment
		(start 427.301406 -283.61005)
		(end 428.493428 -283.61005)
		(width 0.14478)
		(layer "In6.Cu")
		(net "M_K_CPU0_SB_DQ<1>")
	)
	(segment
		(start 418.786564 -282.760166)
		(end 419.636448 -283.61005)
		(width 0.14478)
		(layer "In6.Cu")
		(net "M_K_CPU0_SB_DQ<1>")
	)
	(segment
		(start 401.789392 -273.84883)
		(end 411.550612 -283.61005)
		(width 0.14478)
		(layer "In6.Cu")
		(net "M_K_CPU0_SB_DQ<1>")
	)
	(segment
		(start 421.623998 -282.760166)
		(end 425.249594 -282.760166)
		(width 0.14478)
		(layer "In6.Cu")
		(net "M_K_CPU0_SB_DQ<1>")
	)
	(segment
		(start 434.803042 -283.61005)
		(end 435.457854 -283.61005)
		(width 0.14478)
		(layer "In6.Cu")
		(net "M_K_CPU0_SB_DQ<1>")
	)
	(segment
		(start 435.457854 -283.61005)
		(end 437.509666 -282.760166)
		(width 0.14478)
		(layer "In6.Cu")
		(net "M_K_CPU0_SB_DQ<1>")
	)
	(segment
		(start 411.550612 -283.61005)
		(end 413.89046 -283.61005)
		(width 0.14478)
		(layer "In6.Cu")
		(net "M_K_CPU0_SB_DQ<1>")
	)
	(segment
		(start 430.54524 -282.760166)
		(end 432.75123 -282.760166)
		(width 0.14478)
		(layer "In6.Cu")
		(net "M_K_CPU0_SB_DQ<1>")
	)
	(segment
		(start 419.636448 -283.61005)
		(end 420.774114 -283.61005)
		(width 0.14478)
		(layer "In6.Cu")
		(net "M_K_CPU0_SB_DQ<1>")
	)
	(segment
		(start 413.89046 -283.61005)
		(end 414.740344 -282.760166)
		(width 0.14478)
		(layer "In6.Cu")
		(net "M_K_CPU0_SB_DQ<1>")
	)
	(segment
		(start 392.72718 -275.218652)
		(end 392.738864 -275.22551)
		(width 0.0889)
		(layer "In6.Cu")
		(net "M_K_CPU0_SB_DQ<1>")
	)
	(segment
		(start 389.308848 -275.161502)
		(end 389.40486 -275.186902)
		(width 0.0889)
		(layer "In6.Cu")
		(net "M_K_CPU0_SB_DQ<1>")
	)
	(segment
		(start 428.493428 -283.61005)
		(end 430.54524 -282.760166)
		(width 0.14478)
		(layer "In6.Cu")
		(net "M_K_CPU0_SB_DQ<1>")
	)
	(segment
		(start 395.502384 -273.84883)
		(end 396.000986 -273.84883)
		(width 0.0889)
		(layer "In6.Cu")
		(net "M_K_CPU0_SB_DQ<1>")
	)
	(segment
		(start 389.90778 -275.218652)
		(end 389.916162 -275.223478)
		(width 0.0889)
		(layer "In6.Cu")
		(net "M_K_CPU0_SB_DQ<1>")
	)
	(segment
		(start 420.774114 -283.61005)
		(end 421.623998 -282.760166)
		(width 0.14478)
		(layer "In6.Cu")
		(net "M_K_CPU0_SB_DQ<1>")
	)
	(segment
		(start 392.161522 -275.218652)
		(end 392.171936 -275.212556)
		(width 0.0889)
		(layer "In6.Cu")
		(net "M_K_CPU0_SB_DQ<1>")
	)
	(segment
		(start 395.342364 -274.00885)
		(end 395.502384 -273.84883)
		(width 0.0889)
		(layer "In6.Cu")
		(net "M_K_CPU0_SB_DQ<1>")
	)
	(segment
		(start 425.249594 -282.760166)
		(end 427.301406 -283.61005)
		(width 0.14478)
		(layer "In6.Cu")
		(net "M_K_CPU0_SB_DQ<1>")
	)
	(segment
		(start 393.915646 -274.776438)
		(end 394.683234 -274.00885)
		(width 0.0889)
		(layer "In6.Cu")
		(net "M_K_CPU0_SB_DQ<1>")
	)
	(segment
		(start 393.834112 -274.837144)
		(end 393.915646 -274.776438)
		(width 0.0889)
		(layer "In6.Cu")
		(net "M_K_CPU0_SB_DQ<1>")
	)
	(segment
		(start 393.495022 -274.98675)
		(end 393.834112 -274.837144)
		(width 0.0889)
		(layer "In6.Cu")
		(net "M_K_CPU0_SB_DQ<1>")
	)
	(segment
		(start 437.509666 -282.760166)
		(end 444.507874 -282.760166)
		(width 0.14478)
		(layer "In6.Cu")
		(net "M_K_CPU0_SB_DQ<1>")
	)
	(segment
		(start 389.154924 -274.896072)
		(end 389.308848 -275.161502)
		(width 0.0889)
		(layer "In6.Cu")
		(net "M_K_CPU0_SB_DQ<1>")
	)
	(segment
		(start 394.683234 -274.00885)
		(end 395.342364 -274.00885)
		(width 0.0889)
		(layer "In6.Cu")
		(net "M_K_CPU0_SB_DQ<1>")
	)
	(segment
		(start 396.000986 -273.84883)
		(end 401.789392 -273.84883)
		(width 0.14478)
		(layer "In6.Cu")
		(net "M_K_CPU0_SB_DQ<1>")
	)
	(segment
		(start 414.740344 -282.760166)
		(end 418.786564 -282.760166)
		(width 0.14478)
		(layer "In6.Cu")
		(net "M_K_CPU0_SB_DQ<1>")
	)
	(arc
		(start 392.738864 -275.22551)
		(mid 392.921119 -275.269163)
		(end 393.101576 -275.218652)
		(width 0.0889)
		(layer "In6.Cu")
		(net "M_K_CPU0_SB_DQ<1>")
	)
	(arc
		(start 389.40486 -275.186902)
		(mid 389.660068 -275.143425)
		(end 389.90778 -275.218652)
		(width 0.0889)
		(layer "In6.Cu")
		(net "M_K_CPU0_SB_DQ<1>")
	)
	(arc
		(start 390.847834 -275.218652)
		(mid 391.034778 -275.268907)
		(end 391.221722 -275.218652)
		(width 0.0889)
		(layer "In6.Cu")
		(net "M_K_CPU0_SB_DQ<1>")
	)
	(arc
		(start 392.171936 -275.212556)
		(mid 392.450368 -275.142458)
		(end 392.72718 -275.218652)
		(width 0.0889)
		(layer "In6.Cu")
		(net "M_K_CPU0_SB_DQ<1>")
	)
	(arc
		(start 391.787634 -275.218652)
		(mid 391.967839 -275.268969)
		(end 392.149838 -275.22551)
		(width 0.0889)
		(layer "In6.Cu")
		(net "M_K_CPU0_SB_DQ<1>")
	)
	(arc
		(start 389.916162 -275.223478)
		(mid 390.09967 -275.268972)
		(end 390.281922 -275.218652)
		(width 0.0889)
		(layer "In6.Cu")
		(net "M_K_CPU0_SB_DQ<1>")
	)
	(arc
		(start 390.281922 -275.218652)
		(mid 390.564878 -275.142475)
		(end 390.847834 -275.218652)
		(width 0.0889)
		(layer "In6.Cu")
		(net "M_K_CPU0_SB_DQ<1>")
	)
	(arc
		(start 391.221722 -275.218652)
		(mid 391.504678 -275.142475)
		(end 391.787634 -275.218652)
		(width 0.0889)
		(layer "In6.Cu")
		(net "M_K_CPU0_SB_DQ<1>")
	)
	(segment
		(start 389.157972 -285.160212)
		(end 389.624824 -285.42615)
		(width 0.10668)
		(layer "F.Cu")
		(net "M_K_CPU0_SB_DQ<19>")
	)
	(segment
		(start 404.438612 -296.11447)
		(end 404.601934 -296.277792)
		(width 0.14478)
		(layer "In6.Cu")
		(net "M_K_CPU0_SB_DQ<19>")
	)
	(segment
		(start 390.74344 -285.098744)
		(end 390.751822 -285.10357)
		(width 0.0889)
		(layer "In6.Cu")
		(net "M_K_CPU0_SB_DQ<19>")
	)
	(segment
		(start 389.624824 -285.42615)
		(end 389.4709 -285.16072)
		(width 0.0889)
		(layer "In6.Cu")
		(net "M_K_CPU0_SB_DQ<19>")
	)
	(segment
		(start 429.830484 -302.30064)
		(end 433.178458 -302.30064)
		(width 0.14478)
		(layer "In6.Cu")
		(net "M_K_CPU0_SB_DQ<19>")
	)
	(segment
		(start 404.6601 -297.23715)
		(end 404.99538 -296.90187)
		(width 0.14478)
		(layer "In6.Cu")
		(net "M_K_CPU0_SB_DQ<19>")
	)
	(segment
		(start 416.677094 -301.99711)
		(end 416.92068 -301.99711)
		(width 0.14478)
		(layer "In6.Cu")
		(net "M_K_CPU0_SB_DQ<19>")
	)
	(segment
		(start 393.384786 -285.053024)
		(end 394.12164 -285.053024)
		(width 0.0889)
		(layer "In6.Cu")
		(net "M_K_CPU0_SB_DQ<19>")
	)
	(segment
		(start 392.257534 -285.10357)
		(end 392.265916 -285.098744)
		(width 0.0889)
		(layer "In6.Cu")
		(net "M_K_CPU0_SB_DQ<19>")
	)
	(segment
		(start 436.63108 -303.150524)
		(end 437.480964 -302.30064)
		(width 0.14478)
		(layer "In6.Cu")
		(net "M_K_CPU0_SB_DQ<19>")
	)
	(segment
		(start 392.24712 -285.109666)
		(end 392.257534 -285.10357)
		(width 0.0889)
		(layer "In6.Cu")
		(net "M_K_CPU0_SB_DQ<19>")
	)
	(segment
		(start 405.389334 -297.065192)
		(end 405.38908 -297.295316)
		(width 0.14478)
		(layer "In6.Cu")
		(net "M_K_CPU0_SB_DQ<19>")
	)
	(segment
		(start 406.013412 -297.68927)
		(end 411.484318 -303.160176)
		(width 0.14478)
		(layer "In6.Cu")
		(net "M_K_CPU0_SB_DQ<19>")
	)
	(segment
		(start 396.395448 -286.01162)
		(end 403.230334 -292.846506)
		(width 0.14478)
		(layer "In6.Cu")
		(net "M_K_CPU0_SB_DQ<19>")
	)
	(segment
		(start 403.814534 -295.490392)
		(end 403.81428 -295.720516)
		(width 0.14478)
		(layer "In6.Cu")
		(net "M_K_CPU0_SB_DQ<19>")
	)
	(segment
		(start 395.816836 -286.01162)
		(end 396.395448 -286.01162)
		(width 0.14478)
		(layer "In6.Cu")
		(net "M_K_CPU0_SB_DQ<19>")
	)
	(segment
		(start 404.2664 -297.073828)
		(end 404.429468 -297.236896)
		(width 0.14478)
		(layer "In6.Cu")
		(net "M_K_CPU0_SB_DQ<19>")
	)
	(segment
		(start 415.564066 -301.99711)
		(end 415.807652 -301.99711)
		(width 0.14478)
		(layer "In6.Cu")
		(net "M_K_CPU0_SB_DQ<19>")
	)
	(segment
		(start 413.715454 -302.310038)
		(end 414.13811 -302.310038)
		(width 0.14478)
		(layer "In6.Cu")
		(net "M_K_CPU0_SB_DQ<19>")
	)
	(segment
		(start 395.135862 -285.60903)
		(end 395.538452 -286.01162)
		(width 0.0889)
		(layer "In6.Cu")
		(net "M_K_CPU0_SB_DQ<19>")
	)
	(segment
		(start 414.13811 -302.310038)
		(end 414.451038 -301.99711)
		(width 0.14478)
		(layer "In6.Cu")
		(net "M_K_CPU0_SB_DQ<19>")
	)
	(segment
		(start 421.3479 -303.150778)
		(end 422.198038 -302.30064)
		(width 0.14478)
		(layer "In6.Cu")
		(net "M_K_CPU0_SB_DQ<19>")
	)
	(segment
		(start 404.20798 -296.11447)
		(end 404.438612 -296.11447)
		(width 0.14478)
		(layer "In6.Cu")
		(net "M_K_CPU0_SB_DQ<19>")
	)
	(segment
		(start 426.507402 -303.150778)
		(end 428.980346 -303.150778)
		(width 0.14478)
		(layer "In6.Cu")
		(net "M_K_CPU0_SB_DQ<19>")
	)
	(segment
		(start 433.178458 -302.30064)
		(end 434.028342 -303.150524)
		(width 0.14478)
		(layer "In6.Cu")
		(net "M_K_CPU0_SB_DQ<19>")
	)
	(segment
		(start 405.78278 -297.68927)
		(end 406.013412 -297.68927)
		(width 0.14478)
		(layer "In6.Cu")
		(net "M_K_CPU0_SB_DQ<19>")
	)
	(segment
		(start 392.631168 -285.10357)
		(end 392.641582 -285.109666)
		(width 0.0889)
		(layer "In6.Cu")
		(net "M_K_CPU0_SB_DQ<19>")
	)
	(segment
		(start 415.251138 -302.310038)
		(end 415.564066 -301.99711)
		(width 0.14478)
		(layer "In6.Cu")
		(net "M_K_CPU0_SB_DQ<19>")
	)
	(segment
		(start 414.694624 -301.99711)
		(end 415.007552 -302.310038)
		(width 0.14478)
		(layer "In6.Cu")
		(net "M_K_CPU0_SB_DQ<19>")
	)
	(segment
		(start 434.028342 -303.150524)
		(end 436.63108 -303.150524)
		(width 0.14478)
		(layer "In6.Cu")
		(net "M_K_CPU0_SB_DQ<19>")
	)
	(segment
		(start 395.538452 -286.01162)
		(end 395.816836 -286.01162)
		(width 0.0889)
		(layer "In6.Cu")
		(net "M_K_CPU0_SB_DQ<19>")
	)
	(segment
		(start 403.47646 -296.058336)
		(end 403.47646 -296.288968)
		(width 0.14478)
		(layer "In6.Cu")
		(net "M_K_CPU0_SB_DQ<19>")
	)
	(segment
		(start 394.12164 -285.053024)
		(end 394.677646 -285.60903)
		(width 0.0889)
		(layer "In6.Cu")
		(net "M_K_CPU0_SB_DQ<19>")
	)
	(segment
		(start 403.87016 -296.45229)
		(end 404.20798 -296.11447)
		(width 0.14478)
		(layer "In6.Cu")
		(net "M_K_CPU0_SB_DQ<19>")
	)
	(segment
		(start 416.111182 -302.30064)
		(end 416.373564 -302.30064)
		(width 0.14478)
		(layer "In6.Cu")
		(net "M_K_CPU0_SB_DQ<19>")
	)
	(segment
		(start 405.454104 -298.017946)
		(end 405.78278 -297.68927)
		(width 0.14478)
		(layer "In6.Cu")
		(net "M_K_CPU0_SB_DQ<19>")
	)
	(segment
		(start 389.4709 -285.16072)
		(end 389.493252 -285.077408)
		(width 0.0889)
		(layer "In6.Cu")
		(net "M_K_CPU0_SB_DQ<19>")
	)
	(segment
		(start 412.865316 -303.160176)
		(end 413.715454 -302.310038)
		(width 0.14478)
		(layer "In6.Cu")
		(net "M_K_CPU0_SB_DQ<19>")
	)
	(segment
		(start 405.223472 -298.017692)
		(end 405.454104 -298.017946)
		(width 0.14478)
		(layer "In6.Cu")
		(net "M_K_CPU0_SB_DQ<19>")
	)
	(segment
		(start 403.230334 -292.846506)
		(end 403.230334 -294.906192)
		(width 0.14478)
		(layer "In6.Cu")
		(net "M_K_CPU0_SB_DQ<19>")
	)
	(segment
		(start 403.639528 -296.452036)
		(end 403.87016 -296.45229)
		(width 0.14478)
		(layer "In6.Cu")
		(net "M_K_CPU0_SB_DQ<19>")
	)
	(segment
		(start 405.226012 -296.90187)
		(end 405.389334 -297.065192)
		(width 0.14478)
		(layer "In6.Cu")
		(net "M_K_CPU0_SB_DQ<19>")
	)
	(segment
		(start 418.11321 -302.30064)
		(end 418.963348 -303.150778)
		(width 0.14478)
		(layer "In6.Cu")
		(net "M_K_CPU0_SB_DQ<19>")
	)
	(segment
		(start 414.451038 -301.99711)
		(end 414.694624 -301.99711)
		(width 0.14478)
		(layer "In6.Cu")
		(net "M_K_CPU0_SB_DQ<19>")
	)
	(segment
		(start 404.601934 -296.277792)
		(end 404.60168 -296.507916)
		(width 0.14478)
		(layer "In6.Cu")
		(net "M_K_CPU0_SB_DQ<19>")
	)
	(segment
		(start 405.060404 -297.854624)
		(end 405.223472 -298.017692)
		(width 0.14478)
		(layer "In6.Cu")
		(net "M_K_CPU0_SB_DQ<19>")
	)
	(segment
		(start 442.10986 -302.30064)
		(end 442.5442 -302.73498)
		(width 0.14478)
		(layer "In6.Cu")
		(net "M_K_CPU0_SB_DQ<19>")
	)
	(segment
		(start 416.373564 -302.30064)
		(end 416.677094 -301.99711)
		(width 0.14478)
		(layer "In6.Cu")
		(net "M_K_CPU0_SB_DQ<19>")
	)
	(segment
		(start 418.963348 -303.150778)
		(end 421.3479 -303.150778)
		(width 0.14478)
		(layer "In6.Cu")
		(net "M_K_CPU0_SB_DQ<19>")
	)
	(segment
		(start 404.429468 -297.236896)
		(end 404.6601 -297.23715)
		(width 0.14478)
		(layer "In6.Cu")
		(net "M_K_CPU0_SB_DQ<19>")
	)
	(segment
		(start 422.198038 -302.30064)
		(end 425.657264 -302.30064)
		(width 0.14478)
		(layer "In6.Cu")
		(net "M_K_CPU0_SB_DQ<19>")
	)
	(segment
		(start 403.81428 -295.720516)
		(end 403.47646 -296.058336)
		(width 0.14478)
		(layer "In6.Cu")
		(net "M_K_CPU0_SB_DQ<19>")
	)
	(segment
		(start 437.480964 -302.30064)
		(end 442.10986 -302.30064)
		(width 0.14478)
		(layer "In6.Cu")
		(net "M_K_CPU0_SB_DQ<19>")
	)
	(segment
		(start 411.484318 -303.160176)
		(end 412.865316 -303.160176)
		(width 0.14478)
		(layer "In6.Cu")
		(net "M_K_CPU0_SB_DQ<19>")
	)
	(segment
		(start 405.060404 -297.623992)
		(end 405.060404 -297.854624)
		(width 0.14478)
		(layer "In6.Cu")
		(net "M_K_CPU0_SB_DQ<19>")
	)
	(segment
		(start 415.807652 -301.99711)
		(end 416.111182 -302.30064)
		(width 0.14478)
		(layer "In6.Cu")
		(net "M_K_CPU0_SB_DQ<19>")
	)
	(segment
		(start 417.22421 -302.30064)
		(end 418.11321 -302.30064)
		(width 0.14478)
		(layer "In6.Cu")
		(net "M_K_CPU0_SB_DQ<19>")
	)
	(segment
		(start 404.99538 -296.90187)
		(end 405.226012 -296.90187)
		(width 0.14478)
		(layer "In6.Cu")
		(net "M_K_CPU0_SB_DQ<19>")
	)
	(segment
		(start 404.2664 -296.843196)
		(end 404.2664 -297.073828)
		(width 0.14478)
		(layer "In6.Cu")
		(net "M_K_CPU0_SB_DQ<19>")
	)
	(segment
		(start 405.38908 -297.295316)
		(end 405.060404 -297.623992)
		(width 0.14478)
		(layer "In6.Cu")
		(net "M_K_CPU0_SB_DQ<19>")
	)
	(segment
		(start 391.317734 -285.10357)
		(end 391.326116 -285.098744)
		(width 0.0889)
		(layer "In6.Cu")
		(net "M_K_CPU0_SB_DQ<19>")
	)
	(segment
		(start 403.47646 -296.288968)
		(end 403.639528 -296.452036)
		(width 0.14478)
		(layer "In6.Cu")
		(net "M_K_CPU0_SB_DQ<19>")
	)
	(segment
		(start 404.60168 -296.507916)
		(end 404.2664 -296.843196)
		(width 0.14478)
		(layer "In6.Cu")
		(net "M_K_CPU0_SB_DQ<19>")
	)
	(segment
		(start 415.007552 -302.310038)
		(end 415.251138 -302.310038)
		(width 0.14478)
		(layer "In6.Cu")
		(net "M_K_CPU0_SB_DQ<19>")
	)
	(segment
		(start 425.657264 -302.30064)
		(end 426.507402 -303.150778)
		(width 0.14478)
		(layer "In6.Cu")
		(net "M_K_CPU0_SB_DQ<19>")
	)
	(segment
		(start 416.92068 -301.99711)
		(end 417.22421 -302.30064)
		(width 0.14478)
		(layer "In6.Cu")
		(net "M_K_CPU0_SB_DQ<19>")
	)
	(segment
		(start 428.980346 -303.150778)
		(end 429.830484 -302.30064)
		(width 0.14478)
		(layer "In6.Cu")
		(net "M_K_CPU0_SB_DQ<19>")
	)
	(segment
		(start 394.677646 -285.60903)
		(end 395.135862 -285.60903)
		(width 0.0889)
		(layer "In6.Cu")
		(net "M_K_CPU0_SB_DQ<19>")
	)
	(segment
		(start 403.230334 -294.906192)
		(end 403.814534 -295.490392)
		(width 0.14478)
		(layer "In6.Cu")
		(net "M_K_CPU0_SB_DQ<19>")
	)
	(arc
		(start 390.37768 -285.10357)
		(mid 390.559931 -285.05322)
		(end 390.74344 -285.098744)
		(width 0.0889)
		(layer "In6.Cu")
		(net "M_K_CPU0_SB_DQ<19>")
	)
	(arc
		(start 392.641582 -285.109666)
		(mid 392.920268 -285.179886)
		(end 393.197334 -285.10357)
		(width 0.0889)
		(layer "In6.Cu")
		(net "M_K_CPU0_SB_DQ<19>")
	)
	(arc
		(start 390.751822 -285.10357)
		(mid 391.034778 -285.179747)
		(end 391.317734 -285.10357)
		(width 0.0889)
		(layer "In6.Cu")
		(net "M_K_CPU0_SB_DQ<19>")
	)
	(arc
		(start 391.691876 -285.10357)
		(mid 391.968689 -285.179713)
		(end 392.24712 -285.109666)
		(width 0.0889)
		(layer "In6.Cu")
		(net "M_K_CPU0_SB_DQ<19>")
	)
	(arc
		(start 393.197334 -285.10357)
		(mid 393.287713 -285.065883)
		(end 393.384786 -285.053024)
		(width 0.0889)
		(layer "In6.Cu")
		(net "M_K_CPU0_SB_DQ<19>")
	)
	(arc
		(start 389.811768 -285.10357)
		(mid 390.094724 -285.179747)
		(end 390.37768 -285.10357)
		(width 0.0889)
		(layer "In6.Cu")
		(net "M_K_CPU0_SB_DQ<19>")
	)
	(arc
		(start 391.326116 -285.098744)
		(mid 391.509624 -285.05325)
		(end 391.691876 -285.10357)
		(width 0.0889)
		(layer "In6.Cu")
		(net "M_K_CPU0_SB_DQ<19>")
	)
	(arc
		(start 389.493252 -285.077408)
		(mid 389.655441 -285.054673)
		(end 389.811768 -285.10357)
		(width 0.0889)
		(layer "In6.Cu")
		(net "M_K_CPU0_SB_DQ<19>")
	)
	(arc
		(start 392.265916 -285.098744)
		(mid 392.44917 -285.053371)
		(end 392.631168 -285.10357)
		(width 0.0889)
		(layer "In6.Cu")
		(net "M_K_CPU0_SB_DQ<19>")
	)
	(segment
		(start 390.567926 -284.350206)
		(end 391.034778 -284.616144)
		(width 0.10668)
		(layer "F.Cu")
		(net "M_K_CPU0_SB_DQ<18>")
	)
	(segment
		(start 406.667716 -297.057064)
		(end 406.831038 -297.220386)
		(width 0.14478)
		(layer "In6.Cu")
		(net "M_K_CPU0_SB_DQ<18>")
	)
	(segment
		(start 406.273762 -296.432732)
		(end 406.45842 -296.248074)
		(width 0.14478)
		(layer "In6.Cu")
		(net "M_K_CPU0_SB_DQ<18>")
	)
	(segment
		(start 391.034778 -284.616144)
		(end 390.880854 -284.350714)
		(width 0.0889)
		(layer "In6.Cu")
		(net "M_K_CPU0_SB_DQ<18>")
	)
	(segment
		(start 394.14196 -284.369764)
		(end 394.846302 -285.074106)
		(width 0.0889)
		(layer "In6.Cu")
		(net "M_K_CPU0_SB_DQ<18>")
	)
	(segment
		(start 392.153394 -284.288738)
		(end 392.161776 -284.293564)
		(width 0.0889)
		(layer "In6.Cu")
		(net "M_K_CPU0_SB_DQ<18>")
	)
	(segment
		(start 405.67102 -295.460674)
		(end 405.901652 -295.460674)
		(width 0.14478)
		(layer "In6.Cu")
		(net "M_K_CPU0_SB_DQ<18>")
	)
	(segment
		(start 409.029916 -299.419264)
		(end 409.193238 -299.582586)
		(width 0.14478)
		(layer "In6.Cu")
		(net "M_K_CPU0_SB_DQ<18>")
	)
	(segment
		(start 407.639774 -297.429174)
		(end 407.455116 -297.613832)
		(width 0.14478)
		(layer "In6.Cu")
		(net "M_K_CPU0_SB_DQ<18>")
	)
	(segment
		(start 408.263852 -297.822874)
		(end 408.42692 -297.985942)
		(width 0.14478)
		(layer "In6.Cu")
		(net "M_K_CPU0_SB_DQ<18>")
	)
	(segment
		(start 406.852374 -296.641774)
		(end 406.667716 -296.826432)
		(width 0.14478)
		(layer "In6.Cu")
		(net "M_K_CPU0_SB_DQ<18>")
	)
	(segment
		(start 407.24582 -297.035474)
		(end 407.476452 -297.035474)
		(width 0.14478)
		(layer "In6.Cu")
		(net "M_K_CPU0_SB_DQ<18>")
	)
	(segment
		(start 409.214574 -299.003974)
		(end 409.029916 -299.188632)
		(width 0.14478)
		(layer "In6.Cu")
		(net "M_K_CPU0_SB_DQ<18>")
	)
	(segment
		(start 408.82062 -298.610274)
		(end 409.051252 -298.610274)
		(width 0.14478)
		(layer "In6.Cu")
		(net "M_K_CPU0_SB_DQ<18>")
	)
	(segment
		(start 417.977828 -300.465236)
		(end 418.972746 -301.460154)
		(width 0.14478)
		(layer "In6.Cu")
		(net "M_K_CPU0_SB_DQ<18>")
	)
	(segment
		(start 433.210716 -300.610016)
		(end 434.0606 -301.4599)
		(width 0.14478)
		(layer "In6.Cu")
		(net "M_K_CPU0_SB_DQ<18>")
	)
	(segment
		(start 417.426394 -300.412912)
		(end 417.571174 -300.268132)
		(width 0.14478)
		(layer "In6.Cu")
		(net "M_K_CPU0_SB_DQ<18>")
	)
	(segment
		(start 410.39542 -300.185074)
		(end 410.626052 -300.185074)
		(width 0.14478)
		(layer "In6.Cu")
		(net "M_K_CPU0_SB_DQ<18>")
	)
	(segment
		(start 406.45842 -296.248074)
		(end 406.689052 -296.248074)
		(width 0.14478)
		(layer "In6.Cu")
		(net "M_K_CPU0_SB_DQ<18>")
	)
	(segment
		(start 417.977828 -300.412912)
		(end 417.977828 -300.465236)
		(width 0.14478)
		(layer "In6.Cu")
		(net "M_K_CPU0_SB_DQ<18>")
	)
	(segment
		(start 405.092916 -295.482264)
		(end 405.256238 -295.645586)
		(width 0.14478)
		(layer "In6.Cu")
		(net "M_K_CPU0_SB_DQ<18>")
	)
	(segment
		(start 407.618438 -298.007786)
		(end 407.848562 -298.007532)
		(width 0.14478)
		(layer "In6.Cu")
		(net "M_K_CPU0_SB_DQ<18>")
	)
	(segment
		(start 406.043638 -296.432986)
		(end 406.273762 -296.432732)
		(width 0.14478)
		(layer "In6.Cu")
		(net "M_K_CPU0_SB_DQ<18>")
	)
	(segment
		(start 413.278828 -301.460154)
		(end 414.128966 -300.610016)
		(width 0.14478)
		(layer "In6.Cu")
		(net "M_K_CPU0_SB_DQ<18>")
	)
	(segment
		(start 407.848562 -298.007532)
		(end 408.03322 -297.822874)
		(width 0.14478)
		(layer "In6.Cu")
		(net "M_K_CPU0_SB_DQ<18>")
	)
	(segment
		(start 406.831038 -297.220386)
		(end 407.061162 -297.220132)
		(width 0.14478)
		(layer "In6.Cu")
		(net "M_K_CPU0_SB_DQ<18>")
	)
	(segment
		(start 434.0606 -301.4599)
		(end 436.769764 -301.4599)
		(width 0.14478)
		(layer "In6.Cu")
		(net "M_K_CPU0_SB_DQ<18>")
	)
	(segment
		(start 404.139654 -293.698676)
		(end 404.48992 -294.048942)
		(width 0.14478)
		(layer "In6.Cu")
		(net "M_K_CPU0_SB_DQ<18>")
	)
	(segment
		(start 393.384786 -284.369764)
		(end 394.14196 -284.369764)
		(width 0.0889)
		(layer "In6.Cu")
		(net "M_K_CPU0_SB_DQ<18>")
	)
	(segment
		(start 405.27732 -294.836342)
		(end 405.277574 -295.066974)
		(width 0.14478)
		(layer "In6.Cu")
		(net "M_K_CPU0_SB_DQ<18>")
	)
	(segment
		(start 429.811942 -300.610016)
		(end 433.210716 -300.610016)
		(width 0.14478)
		(layer "In6.Cu")
		(net "M_K_CPU0_SB_DQ<18>")
	)
	(segment
		(start 408.427174 -298.216574)
		(end 408.242516 -298.401232)
		(width 0.14478)
		(layer "In6.Cu")
		(net "M_K_CPU0_SB_DQ<18>")
	)
	(segment
		(start 425.666662 -300.610016)
		(end 426.5168 -301.460154)
		(width 0.14478)
		(layer "In6.Cu")
		(net "M_K_CPU0_SB_DQ<18>")
	)
	(segment
		(start 406.064974 -295.854374)
		(end 405.880316 -296.039032)
		(width 0.14478)
		(layer "In6.Cu")
		(net "M_K_CPU0_SB_DQ<18>")
	)
	(segment
		(start 437.619648 -300.610016)
		(end 442.119258 -300.610016)
		(width 0.14478)
		(layer "In6.Cu")
		(net "M_K_CPU0_SB_DQ<18>")
	)
	(segment
		(start 406.06472 -295.623742)
		(end 406.064974 -295.854374)
		(width 0.14478)
		(layer "In6.Cu")
		(net "M_K_CPU0_SB_DQ<18>")
	)
	(segment
		(start 405.880316 -296.269664)
		(end 406.043638 -296.432986)
		(width 0.14478)
		(layer "In6.Cu")
		(net "M_K_CPU0_SB_DQ<18>")
	)
	(segment
		(start 406.667716 -296.826432)
		(end 406.667716 -297.057064)
		(width 0.14478)
		(layer "In6.Cu")
		(net "M_K_CPU0_SB_DQ<18>")
	)
	(segment
		(start 394.846302 -285.074106)
		(end 395.82217 -285.074106)
		(width 0.0889)
		(layer "In6.Cu")
		(net "M_K_CPU0_SB_DQ<18>")
	)
	(segment
		(start 395.82217 -285.074106)
		(end 396.74419 -285.074106)
		(width 0.14478)
		(layer "In6.Cu")
		(net "M_K_CPU0_SB_DQ<18>")
	)
	(segment
		(start 410.001974 -299.791374)
		(end 409.817316 -299.976032)
		(width 0.14478)
		(layer "In6.Cu")
		(net "M_K_CPU0_SB_DQ<18>")
	)
	(segment
		(start 421.30599 -301.460154)
		(end 422.156128 -300.610016)
		(width 0.14478)
		(layer "In6.Cu")
		(net "M_K_CPU0_SB_DQ<18>")
	)
	(segment
		(start 396.74419 -285.074106)
		(end 404.139654 -292.46957)
		(width 0.14478)
		(layer "In6.Cu")
		(net "M_K_CPU0_SB_DQ<18>")
	)
	(segment
		(start 409.838652 -299.397674)
		(end 410.00172 -299.560742)
		(width 0.14478)
		(layer "In6.Cu")
		(net "M_K_CPU0_SB_DQ<18>")
	)
	(segment
		(start 416.87496 -300.80712)
		(end 417.01974 -300.9519)
		(width 0.14478)
		(layer "In6.Cu")
		(net "M_K_CPU0_SB_DQ<18>")
	)
	(segment
		(start 409.980638 -300.369986)
		(end 410.210762 -300.369732)
		(width 0.14478)
		(layer "In6.Cu")
		(net "M_K_CPU0_SB_DQ<18>")
	)
	(segment
		(start 428.961804 -301.460154)
		(end 429.811942 -300.610016)
		(width 0.14478)
		(layer "In6.Cu")
		(net "M_K_CPU0_SB_DQ<18>")
	)
	(segment
		(start 417.281614 -300.9519)
		(end 417.426394 -300.80712)
		(width 0.14478)
		(layer "In6.Cu")
		(net "M_K_CPU0_SB_DQ<18>")
	)
	(segment
		(start 409.21432 -298.773342)
		(end 409.214574 -299.003974)
		(width 0.14478)
		(layer "In6.Cu")
		(net "M_K_CPU0_SB_DQ<18>")
	)
	(segment
		(start 409.051252 -298.610274)
		(end 409.21432 -298.773342)
		(width 0.14478)
		(layer "In6.Cu")
		(net "M_K_CPU0_SB_DQ<18>")
	)
	(segment
		(start 405.277574 -295.066974)
		(end 405.092916 -295.251632)
		(width 0.14478)
		(layer "In6.Cu")
		(net "M_K_CPU0_SB_DQ<18>")
	)
	(segment
		(start 411.901132 -301.460154)
		(end 413.278828 -301.460154)
		(width 0.14478)
		(layer "In6.Cu")
		(net "M_K_CPU0_SB_DQ<18>")
	)
	(segment
		(start 392.727434 -284.293564)
		(end 392.735816 -284.288738)
		(width 0.0889)
		(layer "In6.Cu")
		(net "M_K_CPU0_SB_DQ<18>")
	)
	(segment
		(start 404.305516 -294.464232)
		(end 404.305516 -294.694864)
		(width 0.14478)
		(layer "In6.Cu")
		(net "M_K_CPU0_SB_DQ<18>")
	)
	(segment
		(start 409.193238 -299.582586)
		(end 409.423362 -299.582332)
		(width 0.14478)
		(layer "In6.Cu")
		(net "M_K_CPU0_SB_DQ<18>")
	)
	(segment
		(start 390.880854 -284.350714)
		(end 390.903206 -284.267402)
		(width 0.0889)
		(layer "In6.Cu")
		(net "M_K_CPU0_SB_DQ<18>")
	)
	(segment
		(start 414.128966 -300.610016)
		(end 416.73018 -300.610016)
		(width 0.14478)
		(layer "In6.Cu")
		(net "M_K_CPU0_SB_DQ<18>")
	)
	(segment
		(start 405.486362 -295.645332)
		(end 405.67102 -295.460674)
		(width 0.14478)
		(layer "In6.Cu")
		(net "M_K_CPU0_SB_DQ<18>")
	)
	(segment
		(start 405.880316 -296.039032)
		(end 405.880316 -296.269664)
		(width 0.14478)
		(layer "In6.Cu")
		(net "M_K_CPU0_SB_DQ<18>")
	)
	(segment
		(start 408.242516 -298.401232)
		(end 408.242516 -298.631864)
		(width 0.14478)
		(layer "In6.Cu")
		(net "M_K_CPU0_SB_DQ<18>")
	)
	(segment
		(start 417.833048 -300.268132)
		(end 417.977828 -300.412912)
		(width 0.14478)
		(layer "In6.Cu")
		(net "M_K_CPU0_SB_DQ<18>")
	)
	(segment
		(start 410.210762 -300.369732)
		(end 410.39542 -300.185074)
		(width 0.14478)
		(layer "In6.Cu")
		(net "M_K_CPU0_SB_DQ<18>")
	)
	(segment
		(start 405.092916 -295.251632)
		(end 405.092916 -295.482264)
		(width 0.14478)
		(layer "In6.Cu")
		(net "M_K_CPU0_SB_DQ<18>")
	)
	(segment
		(start 416.73018 -300.610016)
		(end 416.87496 -300.754796)
		(width 0.14478)
		(layer "In6.Cu")
		(net "M_K_CPU0_SB_DQ<18>")
	)
	(segment
		(start 407.455116 -297.844464)
		(end 407.618438 -298.007786)
		(width 0.14478)
		(layer "In6.Cu")
		(net "M_K_CPU0_SB_DQ<18>")
	)
	(segment
		(start 404.88362 -294.673274)
		(end 405.114252 -294.673274)
		(width 0.14478)
		(layer "In6.Cu")
		(net "M_K_CPU0_SB_DQ<18>")
	)
	(segment
		(start 416.87496 -300.754796)
		(end 416.87496 -300.80712)
		(width 0.14478)
		(layer "In6.Cu")
		(net "M_K_CPU0_SB_DQ<18>")
	)
	(segment
		(start 408.635962 -298.794932)
		(end 408.82062 -298.610274)
		(width 0.14478)
		(layer "In6.Cu")
		(net "M_K_CPU0_SB_DQ<18>")
	)
	(segment
		(start 404.139654 -292.46957)
		(end 404.139654 -293.698676)
		(width 0.14478)
		(layer "In6.Cu")
		(net "M_K_CPU0_SB_DQ<18>")
	)
	(segment
		(start 406.85212 -296.411142)
		(end 406.852374 -296.641774)
		(width 0.14478)
		(layer "In6.Cu")
		(net "M_K_CPU0_SB_DQ<18>")
	)
	(segment
		(start 408.242516 -298.631864)
		(end 408.405838 -298.795186)
		(width 0.14478)
		(layer "In6.Cu")
		(net "M_K_CPU0_SB_DQ<18>")
	)
	(segment
		(start 407.63952 -297.198542)
		(end 407.639774 -297.429174)
		(width 0.14478)
		(layer "In6.Cu")
		(net "M_K_CPU0_SB_DQ<18>")
	)
	(segment
		(start 426.5168 -301.460154)
		(end 428.961804 -301.460154)
		(width 0.14478)
		(layer "In6.Cu")
		(net "M_K_CPU0_SB_DQ<18>")
	)
	(segment
		(start 408.42692 -297.985942)
		(end 408.427174 -298.216574)
		(width 0.14478)
		(layer "In6.Cu")
		(net "M_K_CPU0_SB_DQ<18>")
	)
	(segment
		(start 409.817316 -299.976032)
		(end 409.817316 -300.206664)
		(width 0.14478)
		(layer "In6.Cu")
		(net "M_K_CPU0_SB_DQ<18>")
	)
	(segment
		(start 405.256238 -295.645586)
		(end 405.486362 -295.645332)
		(width 0.14478)
		(layer "In6.Cu")
		(net "M_K_CPU0_SB_DQ<18>")
	)
	(segment
		(start 404.48992 -294.048942)
		(end 404.490174 -294.279574)
		(width 0.14478)
		(layer "In6.Cu")
		(net "M_K_CPU0_SB_DQ<18>")
	)
	(segment
		(start 436.769764 -301.4599)
		(end 437.619648 -300.610016)
		(width 0.14478)
		(layer "In6.Cu")
		(net "M_K_CPU0_SB_DQ<18>")
	)
	(segment
		(start 407.455116 -297.613832)
		(end 407.455116 -297.844464)
		(width 0.14478)
		(layer "In6.Cu")
		(net "M_K_CPU0_SB_DQ<18>")
	)
	(segment
		(start 422.156128 -300.610016)
		(end 425.666662 -300.610016)
		(width 0.14478)
		(layer "In6.Cu")
		(net "M_K_CPU0_SB_DQ<18>")
	)
	(segment
		(start 405.901652 -295.460674)
		(end 406.06472 -295.623742)
		(width 0.14478)
		(layer "In6.Cu")
		(net "M_K_CPU0_SB_DQ<18>")
	)
	(segment
		(start 407.061162 -297.220132)
		(end 407.24582 -297.035474)
		(width 0.14478)
		(layer "In6.Cu")
		(net "M_K_CPU0_SB_DQ<18>")
	)
	(segment
		(start 417.01974 -300.9519)
		(end 417.281614 -300.9519)
		(width 0.14478)
		(layer "In6.Cu")
		(net "M_K_CPU0_SB_DQ<18>")
	)
	(segment
		(start 410.00172 -299.560742)
		(end 410.001974 -299.791374)
		(width 0.14478)
		(layer "In6.Cu")
		(net "M_K_CPU0_SB_DQ<18>")
	)
	(segment
		(start 405.114252 -294.673274)
		(end 405.27732 -294.836342)
		(width 0.14478)
		(layer "In6.Cu")
		(net "M_K_CPU0_SB_DQ<18>")
	)
	(segment
		(start 392.161776 -284.293564)
		(end 392.17219 -284.29966)
		(width 0.0889)
		(layer "In6.Cu")
		(net "M_K_CPU0_SB_DQ<18>")
	)
	(segment
		(start 406.689052 -296.248074)
		(end 406.85212 -296.411142)
		(width 0.14478)
		(layer "In6.Cu")
		(net "M_K_CPU0_SB_DQ<18>")
	)
	(segment
		(start 417.571174 -300.268132)
		(end 417.833048 -300.268132)
		(width 0.14478)
		(layer "In6.Cu")
		(net "M_K_CPU0_SB_DQ<18>")
	)
	(segment
		(start 404.490174 -294.279574)
		(end 404.305516 -294.464232)
		(width 0.14478)
		(layer "In6.Cu")
		(net "M_K_CPU0_SB_DQ<18>")
	)
	(segment
		(start 404.305516 -294.694864)
		(end 404.468838 -294.858186)
		(width 0.14478)
		(layer "In6.Cu")
		(net "M_K_CPU0_SB_DQ<18>")
	)
	(segment
		(start 418.972746 -301.460154)
		(end 421.30599 -301.460154)
		(width 0.14478)
		(layer "In6.Cu")
		(net "M_K_CPU0_SB_DQ<18>")
	)
	(segment
		(start 407.476452 -297.035474)
		(end 407.63952 -297.198542)
		(width 0.14478)
		(layer "In6.Cu")
		(net "M_K_CPU0_SB_DQ<18>")
	)
	(segment
		(start 417.426394 -300.80712)
		(end 417.426394 -300.412912)
		(width 0.14478)
		(layer "In6.Cu")
		(net "M_K_CPU0_SB_DQ<18>")
	)
	(segment
		(start 409.029916 -299.188632)
		(end 409.029916 -299.419264)
		(width 0.14478)
		(layer "In6.Cu")
		(net "M_K_CPU0_SB_DQ<18>")
	)
	(segment
		(start 410.626052 -300.185074)
		(end 411.901132 -301.460154)
		(width 0.14478)
		(layer "In6.Cu")
		(net "M_K_CPU0_SB_DQ<18>")
	)
	(segment
		(start 404.468838 -294.858186)
		(end 404.698962 -294.857932)
		(width 0.14478)
		(layer "In6.Cu")
		(net "M_K_CPU0_SB_DQ<18>")
	)
	(segment
		(start 409.423362 -299.582332)
		(end 409.60802 -299.397674)
		(width 0.14478)
		(layer "In6.Cu")
		(net "M_K_CPU0_SB_DQ<18>")
	)
	(segment
		(start 408.03322 -297.822874)
		(end 408.263852 -297.822874)
		(width 0.14478)
		(layer "In6.Cu")
		(net "M_K_CPU0_SB_DQ<18>")
	)
	(segment
		(start 408.405838 -298.795186)
		(end 408.635962 -298.794932)
		(width 0.14478)
		(layer "In6.Cu")
		(net "M_K_CPU0_SB_DQ<18>")
	)
	(segment
		(start 409.60802 -299.397674)
		(end 409.838652 -299.397674)
		(width 0.14478)
		(layer "In6.Cu")
		(net "M_K_CPU0_SB_DQ<18>")
	)
	(segment
		(start 409.817316 -300.206664)
		(end 409.980638 -300.369986)
		(width 0.14478)
		(layer "In6.Cu")
		(net "M_K_CPU0_SB_DQ<18>")
	)
	(segment
		(start 404.698962 -294.857932)
		(end 404.88362 -294.673274)
		(width 0.14478)
		(layer "In6.Cu")
		(net "M_K_CPU0_SB_DQ<18>")
	)
	(segment
		(start 442.119258 -300.610016)
		(end 442.5442 -301.034958)
		(width 0.14478)
		(layer "In6.Cu")
		(net "M_K_CPU0_SB_DQ<18>")
	)
	(arc
		(start 390.903206 -284.267402)
		(mid 391.065395 -284.244667)
		(end 391.221722 -284.293564)
		(width 0.0889)
		(layer "In6.Cu")
		(net "M_K_CPU0_SB_DQ<18>")
	)
	(arc
		(start 391.221722 -284.293564)
		(mid 391.504678 -284.369741)
		(end 391.787634 -284.293564)
		(width 0.0889)
		(layer "In6.Cu")
		(net "M_K_CPU0_SB_DQ<18>")
	)
	(arc
		(start 391.787634 -284.293564)
		(mid 391.969885 -284.243214)
		(end 392.153394 -284.288738)
		(width 0.0889)
		(layer "In6.Cu")
		(net "M_K_CPU0_SB_DQ<18>")
	)
	(arc
		(start 392.17219 -284.29966)
		(mid 392.450622 -284.369758)
		(end 392.727434 -284.293564)
		(width 0.0889)
		(layer "In6.Cu")
		(net "M_K_CPU0_SB_DQ<18>")
	)
	(arc
		(start 392.735816 -284.288738)
		(mid 392.919324 -284.243244)
		(end 393.101576 -284.293564)
		(width 0.0889)
		(layer "In6.Cu")
		(net "M_K_CPU0_SB_DQ<18>")
	)
	(arc
		(start 393.101576 -284.293564)
		(mid 393.238139 -284.350397)
		(end 393.384786 -284.369764)
		(width 0.0889)
		(layer "In6.Cu")
		(net "M_K_CPU0_SB_DQ<18>")
	)
	(segment
		(start 388.688072 -284.350206)
		(end 389.154924 -284.616144)
		(width 0.10668)
		(layer "F.Cu")
		(net "M_K_CPU0_SB_DQ<17>")
	)
	(segment
		(start 433.145692 -301.460154)
		(end 433.995576 -302.310038)
		(width 0.14478)
		(layer "In6.Cu")
		(net "M_K_CPU0_SB_DQ<17>")
	)
	(segment
		(start 403.684994 -292.658038)
		(end 403.684994 -294.717724)
		(width 0.14478)
		(layer "In6.Cu")
		(net "M_K_CPU0_SB_DQ<17>")
	)
	(segment
		(start 421.416226 -302.310038)
		(end 422.26611 -301.460154)
		(width 0.14478)
		(layer "In6.Cu")
		(net "M_K_CPU0_SB_DQ<17>")
	)
	(segment
		(start 433.995576 -302.310038)
		(end 433.99583 -302.309784)
		(width 0.14478)
		(layer "In6.Cu")
		(net "M_K_CPU0_SB_DQ<17>")
	)
	(segment
		(start 389.154924 -284.616144)
		(end 389.308848 -284.881574)
		(width 0.0889)
		(layer "In6.Cu")
		(net "M_K_CPU0_SB_DQ<17>")
	)
	(segment
		(start 443.992508 -301.914052)
		(end 443.992508 -301.60468)
		(width 0.14478)
		(layer "In6.Cu")
		(net "M_K_CPU0_SB_DQ<17>")
	)
	(segment
		(start 444.137288 -301.4599)
		(end 444.505588 -301.4599)
		(width 0.14478)
		(layer "In6.Cu")
		(net "M_K_CPU0_SB_DQ<17>")
	)
	(segment
		(start 443.296294 -301.4599)
		(end 443.441074 -301.60468)
		(width 0.14478)
		(layer "In6.Cu")
		(net "M_K_CPU0_SB_DQ<17>")
	)
	(segment
		(start 411.277308 -302.310038)
		(end 413.072072 -302.310038)
		(width 0.14478)
		(layer "In6.Cu")
		(net "M_K_CPU0_SB_DQ<17>")
	)
	(segment
		(start 443.441074 -301.914052)
		(end 443.585854 -302.058832)
		(width 0.14478)
		(layer "In6.Cu")
		(net "M_K_CPU0_SB_DQ<17>")
	)
	(segment
		(start 425.601638 -301.460154)
		(end 426.451522 -302.310038)
		(width 0.14478)
		(layer "In6.Cu")
		(net "M_K_CPU0_SB_DQ<17>")
	)
	(segment
		(start 389.90778 -284.938724)
		(end 389.916162 -284.94355)
		(width 0.0889)
		(layer "In6.Cu")
		(net "M_K_CPU0_SB_DQ<17>")
	)
	(segment
		(start 443.992508 -301.60468)
		(end 444.137288 -301.4599)
		(width 0.14478)
		(layer "In6.Cu")
		(net "M_K_CPU0_SB_DQ<17>")
	)
	(segment
		(start 437.613298 -301.4599)
		(end 443.296294 -301.4599)
		(width 0.14478)
		(layer "In6.Cu")
		(net "M_K_CPU0_SB_DQ<17>")
	)
	(segment
		(start 413.072072 -302.310038)
		(end 413.921956 -301.460154)
		(width 0.14478)
		(layer "In6.Cu")
		(net "M_K_CPU0_SB_DQ<17>")
	)
	(segment
		(start 389.308848 -284.881574)
		(end 389.40486 -284.906974)
		(width 0.0889)
		(layer "In6.Cu")
		(net "M_K_CPU0_SB_DQ<17>")
	)
	(segment
		(start 429.023272 -302.310038)
		(end 429.873156 -301.460154)
		(width 0.14478)
		(layer "In6.Cu")
		(net "M_K_CPU0_SB_DQ<17>")
	)
	(segment
		(start 419.179248 -302.310038)
		(end 421.416226 -302.310038)
		(width 0.14478)
		(layer "In6.Cu")
		(net "M_K_CPU0_SB_DQ<17>")
	)
	(segment
		(start 422.26611 -301.460154)
		(end 425.601638 -301.460154)
		(width 0.14478)
		(layer "In6.Cu")
		(net "M_K_CPU0_SB_DQ<17>")
	)
	(segment
		(start 392.72718 -284.938724)
		(end 392.738864 -284.945582)
		(width 0.0889)
		(layer "In6.Cu")
		(net "M_K_CPU0_SB_DQ<17>")
	)
	(segment
		(start 394.26134 -284.862524)
		(end 394.748766 -285.34995)
		(width 0.0889)
		(layer "In6.Cu")
		(net "M_K_CPU0_SB_DQ<17>")
	)
	(segment
		(start 395.741144 -285.54553)
		(end 396.572486 -285.54553)
		(width 0.14478)
		(layer "In6.Cu")
		(net "M_K_CPU0_SB_DQ<17>")
	)
	(segment
		(start 426.451522 -302.310038)
		(end 429.023272 -302.310038)
		(width 0.14478)
		(layer "In6.Cu")
		(net "M_K_CPU0_SB_DQ<17>")
	)
	(segment
		(start 394.748766 -285.34995)
		(end 395.545564 -285.34995)
		(width 0.0889)
		(layer "In6.Cu")
		(net "M_K_CPU0_SB_DQ<17>")
	)
	(segment
		(start 433.99583 -302.309784)
		(end 436.763414 -302.309784)
		(width 0.14478)
		(layer "In6.Cu")
		(net "M_K_CPU0_SB_DQ<17>")
	)
	(segment
		(start 443.585854 -302.058832)
		(end 443.847728 -302.058832)
		(width 0.14478)
		(layer "In6.Cu")
		(net "M_K_CPU0_SB_DQ<17>")
	)
	(segment
		(start 403.684994 -294.717724)
		(end 411.277308 -302.310038)
		(width 0.14478)
		(layer "In6.Cu")
		(net "M_K_CPU0_SB_DQ<17>")
	)
	(segment
		(start 392.161522 -284.938724)
		(end 392.171936 -284.932628)
		(width 0.0889)
		(layer "In6.Cu")
		(net "M_K_CPU0_SB_DQ<17>")
	)
	(segment
		(start 418.329364 -301.460154)
		(end 419.179248 -302.310038)
		(width 0.14478)
		(layer "In6.Cu")
		(net "M_K_CPU0_SB_DQ<17>")
	)
	(segment
		(start 429.873156 -301.460154)
		(end 433.145692 -301.460154)
		(width 0.14478)
		(layer "In6.Cu")
		(net "M_K_CPU0_SB_DQ<17>")
	)
	(segment
		(start 443.847728 -302.058832)
		(end 443.992508 -301.914052)
		(width 0.14478)
		(layer "In6.Cu")
		(net "M_K_CPU0_SB_DQ<17>")
	)
	(segment
		(start 413.921956 -301.460154)
		(end 418.329364 -301.460154)
		(width 0.14478)
		(layer "In6.Cu")
		(net "M_K_CPU0_SB_DQ<17>")
	)
	(segment
		(start 443.441074 -301.60468)
		(end 443.441074 -301.914052)
		(width 0.14478)
		(layer "In6.Cu")
		(net "M_K_CPU0_SB_DQ<17>")
	)
	(segment
		(start 395.545564 -285.34995)
		(end 395.741144 -285.54553)
		(width 0.0889)
		(layer "In6.Cu")
		(net "M_K_CPU0_SB_DQ<17>")
	)
	(segment
		(start 444.505588 -301.4599)
		(end 446.644268 -301.885096)
		(width 0.14478)
		(layer "In6.Cu")
		(net "M_K_CPU0_SB_DQ<17>")
	)
	(segment
		(start 436.763414 -302.309784)
		(end 437.613298 -301.4599)
		(width 0.14478)
		(layer "In6.Cu")
		(net "M_K_CPU0_SB_DQ<17>")
	)
	(segment
		(start 392.149838 -284.945582)
		(end 392.161522 -284.938724)
		(width 0.0889)
		(layer "In6.Cu")
		(net "M_K_CPU0_SB_DQ<17>")
	)
	(segment
		(start 396.572486 -285.54553)
		(end 403.684994 -292.658038)
		(width 0.14478)
		(layer "In6.Cu")
		(net "M_K_CPU0_SB_DQ<17>")
	)
	(segment
		(start 393.384786 -284.862524)
		(end 394.26134 -284.862524)
		(width 0.0889)
		(layer "In6.Cu")
		(net "M_K_CPU0_SB_DQ<17>")
	)
	(arc
		(start 389.916162 -284.94355)
		(mid 390.09967 -284.989044)
		(end 390.281922 -284.938724)
		(width 0.0889)
		(layer "In6.Cu")
		(net "M_K_CPU0_SB_DQ<17>")
	)
	(arc
		(start 390.281922 -284.938724)
		(mid 390.564878 -284.862547)
		(end 390.847834 -284.938724)
		(width 0.0889)
		(layer "In6.Cu")
		(net "M_K_CPU0_SB_DQ<17>")
	)
	(arc
		(start 389.40486 -284.906974)
		(mid 389.660068 -284.863497)
		(end 389.90778 -284.938724)
		(width 0.0889)
		(layer "In6.Cu")
		(net "M_K_CPU0_SB_DQ<17>")
	)
	(arc
		(start 392.738864 -284.945582)
		(mid 392.921119 -284.989235)
		(end 393.101576 -284.938724)
		(width 0.0889)
		(layer "In6.Cu")
		(net "M_K_CPU0_SB_DQ<17>")
	)
	(arc
		(start 390.847834 -284.938724)
		(mid 391.034778 -284.988979)
		(end 391.221722 -284.938724)
		(width 0.0889)
		(layer "In6.Cu")
		(net "M_K_CPU0_SB_DQ<17>")
	)
	(arc
		(start 391.221722 -284.938724)
		(mid 391.504678 -284.862547)
		(end 391.787634 -284.938724)
		(width 0.0889)
		(layer "In6.Cu")
		(net "M_K_CPU0_SB_DQ<17>")
	)
	(arc
		(start 391.787634 -284.938724)
		(mid 391.967839 -284.989041)
		(end 392.149838 -284.945582)
		(width 0.0889)
		(layer "In6.Cu")
		(net "M_K_CPU0_SB_DQ<17>")
	)
	(arc
		(start 392.171936 -284.932628)
		(mid 392.450368 -284.86253)
		(end 392.72718 -284.938724)
		(width 0.0889)
		(layer "In6.Cu")
		(net "M_K_CPU0_SB_DQ<17>")
	)
	(arc
		(start 393.101576 -284.938724)
		(mid 393.238135 -284.881866)
		(end 393.384786 -284.862524)
		(width 0.0889)
		(layer "In6.Cu")
		(net "M_K_CPU0_SB_DQ<17>")
	)
	(segment
		(start 390.098026 -283.5402)
		(end 390.564878 -283.806138)
		(width 0.10668)
		(layer "F.Cu")
		(net "M_K_CPU0_SB_DQ<16>")
	)
	(segment
		(start 437.695594 -299.759878)
		(end 443.734698 -299.759878)
		(width 0.14478)
		(layer "In6.Cu")
		(net "M_K_CPU0_SB_DQ<16>")
	)
	(segment
		(start 390.564878 -283.806138)
		(end 390.718802 -284.071568)
		(width 0.0889)
		(layer "In6.Cu")
		(net "M_K_CPU0_SB_DQ<16>")
	)
	(segment
		(start 414.335468 -299.760132)
		(end 414.610042 -299.760132)
		(width 0.14478)
		(layer "In6.Cu")
		(net "M_K_CPU0_SB_DQ<16>")
	)
	(segment
		(start 394.833348 -284.725364)
		(end 395.462506 -284.725364)
		(width 0.0889)
		(layer "In6.Cu")
		(net "M_K_CPU0_SB_DQ<16>")
	)
	(segment
		(start 443.897766 -300.462442)
		(end 444.060834 -300.62551)
		(width 0.14478)
		(layer "In6.Cu")
		(net "M_K_CPU0_SB_DQ<16>")
	)
	(segment
		(start 413.485584 -300.610016)
		(end 414.335468 -299.760132)
		(width 0.14478)
		(layer "In6.Cu")
		(net "M_K_CPU0_SB_DQ<16>")
	)
	(segment
		(start 395.845284 -284.61335)
		(end 396.943326 -284.61335)
		(width 0.14478)
		(layer "In6.Cu")
		(net "M_K_CPU0_SB_DQ<16>")
	)
	(segment
		(start 394.287248 -284.179264)
		(end 394.833348 -284.725364)
		(width 0.0889)
		(layer "In6.Cu")
		(net "M_K_CPU0_SB_DQ<16>")
	)
	(segment
		(start 415.161476 -300.039532)
		(end 415.301176 -299.899832)
		(width 0.14478)
		(layer "In6.Cu")
		(net "M_K_CPU0_SB_DQ<16>")
	)
	(segment
		(start 404.594314 -293.510208)
		(end 411.694122 -300.610016)
		(width 0.14478)
		(layer "In6.Cu")
		(net "M_K_CPU0_SB_DQ<16>")
	)
	(segment
		(start 445.40424 -300.62551)
		(end 445.567308 -300.462442)
		(width 0.14478)
		(layer "In6.Cu")
		(net "M_K_CPU0_SB_DQ<16>")
	)
	(segment
		(start 445.730376 -299.759878)
		(end 446.219072 -299.759878)
		(width 0.14478)
		(layer "In6.Cu")
		(net "M_K_CPU0_SB_DQ<16>")
	)
	(segment
		(start 426.451522 -300.610016)
		(end 429.115728 -300.610016)
		(width 0.14478)
		(layer "In6.Cu")
		(net "M_K_CPU0_SB_DQ<16>")
	)
	(segment
		(start 446.219072 -299.759878)
		(end 446.644268 -300.185074)
		(width 0.14478)
		(layer "In6.Cu")
		(net "M_K_CPU0_SB_DQ<16>")
	)
	(segment
		(start 415.440876 -299.480732)
		(end 415.71291 -299.480732)
		(width 0.14478)
		(layer "In6.Cu")
		(net "M_K_CPU0_SB_DQ<16>")
	)
	(segment
		(start 396.943326 -284.61335)
		(end 404.594314 -292.264338)
		(width 0.14478)
		(layer "In6.Cu")
		(net "M_K_CPU0_SB_DQ<16>")
	)
	(segment
		(start 444.45428 -299.922946)
		(end 444.617348 -299.759878)
		(width 0.14478)
		(layer "In6.Cu")
		(net "M_K_CPU0_SB_DQ<16>")
	)
	(segment
		(start 415.301176 -299.899832)
		(end 415.301176 -299.620432)
		(width 0.14478)
		(layer "In6.Cu")
		(net "M_K_CPU0_SB_DQ<16>")
	)
	(segment
		(start 393.38504 -284.179264)
		(end 394.287248 -284.179264)
		(width 0.0889)
		(layer "In6.Cu")
		(net "M_K_CPU0_SB_DQ<16>")
	)
	(segment
		(start 418.907468 -300.610016)
		(end 421.396922 -300.610016)
		(width 0.14478)
		(layer "In6.Cu")
		(net "M_K_CPU0_SB_DQ<16>")
	)
	(segment
		(start 392.24712 -284.122622)
		(end 392.257534 -284.128718)
		(width 0.0889)
		(layer "In6.Cu")
		(net "M_K_CPU0_SB_DQ<16>")
	)
	(segment
		(start 393.384786 -284.17901)
		(end 393.38504 -284.179264)
		(width 0.0889)
		(layer "In6.Cu")
		(net "M_K_CPU0_SB_DQ<16>")
	)
	(segment
		(start 392.631422 -284.128718)
		(end 392.641836 -284.122622)
		(width 0.0889)
		(layer "In6.Cu")
		(net "M_K_CPU0_SB_DQ<16>")
	)
	(segment
		(start 444.617348 -299.759878)
		(end 444.847726 -299.759878)
		(width 0.14478)
		(layer "In6.Cu")
		(net "M_K_CPU0_SB_DQ<16>")
	)
	(segment
		(start 429.965612 -299.760132)
		(end 433.168044 -299.760132)
		(width 0.14478)
		(layer "In6.Cu")
		(net "M_K_CPU0_SB_DQ<16>")
	)
	(segment
		(start 444.060834 -300.62551)
		(end 444.291212 -300.62551)
		(width 0.14478)
		(layer "In6.Cu")
		(net "M_K_CPU0_SB_DQ<16>")
	)
	(segment
		(start 395.462506 -284.725364)
		(end 395.57452 -284.61335)
		(width 0.0889)
		(layer "In6.Cu")
		(net "M_K_CPU0_SB_DQ<16>")
	)
	(segment
		(start 445.010794 -299.922946)
		(end 445.010794 -300.462442)
		(width 0.14478)
		(layer "In6.Cu")
		(net "M_K_CPU0_SB_DQ<16>")
	)
	(segment
		(start 414.889442 -300.039532)
		(end 415.161476 -300.039532)
		(width 0.14478)
		(layer "In6.Cu")
		(net "M_K_CPU0_SB_DQ<16>")
	)
	(segment
		(start 414.610042 -299.760132)
		(end 414.889442 -300.039532)
		(width 0.14478)
		(layer "In6.Cu")
		(net "M_K_CPU0_SB_DQ<16>")
	)
	(segment
		(start 436.84571 -300.609762)
		(end 437.695594 -299.759878)
		(width 0.14478)
		(layer "In6.Cu")
		(net "M_K_CPU0_SB_DQ<16>")
	)
	(segment
		(start 443.897766 -299.922946)
		(end 443.897766 -300.462442)
		(width 0.14478)
		(layer "In6.Cu")
		(net "M_K_CPU0_SB_DQ<16>")
	)
	(segment
		(start 415.71291 -299.480732)
		(end 415.99231 -299.760132)
		(width 0.14478)
		(layer "In6.Cu")
		(net "M_K_CPU0_SB_DQ<16>")
	)
	(segment
		(start 411.694122 -300.610016)
		(end 413.485584 -300.610016)
		(width 0.14478)
		(layer "In6.Cu")
		(net "M_K_CPU0_SB_DQ<16>")
	)
	(segment
		(start 421.396922 -300.610016)
		(end 422.246806 -299.760132)
		(width 0.14478)
		(layer "In6.Cu")
		(net "M_K_CPU0_SB_DQ<16>")
	)
	(segment
		(start 445.010794 -300.462442)
		(end 445.173862 -300.62551)
		(width 0.14478)
		(layer "In6.Cu")
		(net "M_K_CPU0_SB_DQ<16>")
	)
	(segment
		(start 415.301176 -299.620432)
		(end 415.440876 -299.480732)
		(width 0.14478)
		(layer "In6.Cu")
		(net "M_K_CPU0_SB_DQ<16>")
	)
	(segment
		(start 415.99231 -299.760132)
		(end 418.057584 -299.760132)
		(width 0.14478)
		(layer "In6.Cu")
		(net "M_K_CPU0_SB_DQ<16>")
	)
	(segment
		(start 390.718802 -284.071568)
		(end 390.814814 -284.096968)
		(width 0.0889)
		(layer "In6.Cu")
		(net "M_K_CPU0_SB_DQ<16>")
	)
	(segment
		(start 443.734698 -299.759878)
		(end 443.897766 -299.922946)
		(width 0.14478)
		(layer "In6.Cu")
		(net "M_K_CPU0_SB_DQ<16>")
	)
	(segment
		(start 395.57452 -284.61335)
		(end 395.845284 -284.61335)
		(width 0.0889)
		(layer "In6.Cu")
		(net "M_K_CPU0_SB_DQ<16>")
	)
	(segment
		(start 444.291212 -300.62551)
		(end 444.45428 -300.462442)
		(width 0.14478)
		(layer "In6.Cu")
		(net "M_K_CPU0_SB_DQ<16>")
	)
	(segment
		(start 444.45428 -300.462442)
		(end 444.45428 -299.922946)
		(width 0.14478)
		(layer "In6.Cu")
		(net "M_K_CPU0_SB_DQ<16>")
	)
	(segment
		(start 444.847726 -299.759878)
		(end 445.010794 -299.922946)
		(width 0.14478)
		(layer "In6.Cu")
		(net "M_K_CPU0_SB_DQ<16>")
	)
	(segment
		(start 434.017674 -300.609762)
		(end 436.84571 -300.609762)
		(width 0.14478)
		(layer "In6.Cu")
		(net "M_K_CPU0_SB_DQ<16>")
	)
	(segment
		(start 418.057584 -299.760132)
		(end 418.907468 -300.610016)
		(width 0.14478)
		(layer "In6.Cu")
		(net "M_K_CPU0_SB_DQ<16>")
	)
	(segment
		(start 404.594314 -292.264338)
		(end 404.594314 -293.510208)
		(width 0.14478)
		(layer "In6.Cu")
		(net "M_K_CPU0_SB_DQ<16>")
	)
	(segment
		(start 425.601638 -299.760132)
		(end 426.451522 -300.610016)
		(width 0.14478)
		(layer "In6.Cu")
		(net "M_K_CPU0_SB_DQ<16>")
	)
	(segment
		(start 433.168044 -299.760132)
		(end 434.017674 -300.609762)
		(width 0.14478)
		(layer "In6.Cu")
		(net "M_K_CPU0_SB_DQ<16>")
	)
	(segment
		(start 429.115728 -300.610016)
		(end 429.965612 -299.760132)
		(width 0.14478)
		(layer "In6.Cu")
		(net "M_K_CPU0_SB_DQ<16>")
	)
	(segment
		(start 445.173862 -300.62551)
		(end 445.40424 -300.62551)
		(width 0.14478)
		(layer "In6.Cu")
		(net "M_K_CPU0_SB_DQ<16>")
	)
	(segment
		(start 422.246806 -299.760132)
		(end 425.601638 -299.760132)
		(width 0.14478)
		(layer "In6.Cu")
		(net "M_K_CPU0_SB_DQ<16>")
	)
	(segment
		(start 391.317734 -284.128718)
		(end 391.326116 -284.133544)
		(width 0.0889)
		(layer "In6.Cu")
		(net "M_K_CPU0_SB_DQ<16>")
	)
	(segment
		(start 445.567308 -299.922946)
		(end 445.730376 -299.759878)
		(width 0.14478)
		(layer "In6.Cu")
		(net "M_K_CPU0_SB_DQ<16>")
	)
	(segment
		(start 445.567308 -300.462442)
		(end 445.567308 -299.922946)
		(width 0.14478)
		(layer "In6.Cu")
		(net "M_K_CPU0_SB_DQ<16>")
	)
	(arc
		(start 390.814814 -284.096968)
		(mid 391.070022 -284.053491)
		(end 391.317734 -284.128718)
		(width 0.0889)
		(layer "In6.Cu")
		(net "M_K_CPU0_SB_DQ<16>")
	)
	(arc
		(start 392.641836 -284.122622)
		(mid 392.920522 -284.052402)
		(end 393.197588 -284.128718)
		(width 0.0889)
		(layer "In6.Cu")
		(net "M_K_CPU0_SB_DQ<16>")
	)
	(arc
		(start 391.691876 -284.128718)
		(mid 391.968689 -284.052575)
		(end 392.24712 -284.122622)
		(width 0.0889)
		(layer "In6.Cu")
		(net "M_K_CPU0_SB_DQ<16>")
	)
	(arc
		(start 391.326116 -284.133544)
		(mid 391.509624 -284.179038)
		(end 391.691876 -284.128718)
		(width 0.0889)
		(layer "In6.Cu")
		(net "M_K_CPU0_SB_DQ<16>")
	)
	(arc
		(start 393.197588 -284.128718)
		(mid 393.287864 -284.166223)
		(end 393.384786 -284.17901)
		(width 0.0889)
		(layer "In6.Cu")
		(net "M_K_CPU0_SB_DQ<16>")
	)
	(arc
		(start 392.257534 -284.128718)
		(mid 392.444478 -284.178973)
		(end 392.631422 -284.128718)
		(width 0.0889)
		(layer "In6.Cu")
		(net "M_K_CPU0_SB_DQ<16>")
	)
	(segment
		(start 389.157972 -283.5402)
		(end 389.624824 -283.806138)
		(width 0.10668)
		(layer "F.Cu")
		(net "M_K_CPU0_SB_DQ<15>")
	)
	(segment
		(start 430.02835 -298.910248)
		(end 433.138326 -298.910248)
		(width 0.14478)
		(layer "In6.Cu")
		(net "M_K_CPU0_SB_DQ<15>")
	)
	(segment
		(start 426.5168 -299.760386)
		(end 429.178212 -299.760386)
		(width 0.14478)
		(layer "In6.Cu")
		(net "M_K_CPU0_SB_DQ<15>")
	)
	(segment
		(start 441.789566 -298.910248)
		(end 442.119258 -298.910248)
		(width 0.14478)
		(layer "In6.Cu")
		(net "M_K_CPU0_SB_DQ<15>")
	)
	(segment
		(start 409.131008 -297.26001)
		(end 409.520644 -297.26001)
		(width 0.14478)
		(layer "In6.Cu")
		(net "M_K_CPU0_SB_DQ<15>")
	)
	(segment
		(start 408.932126 -297.061128)
		(end 409.131008 -297.26001)
		(width 0.14478)
		(layer "In6.Cu")
		(net "M_K_CPU0_SB_DQ<15>")
	)
	(segment
		(start 413.548068 -299.760386)
		(end 414.398206 -298.910248)
		(width 0.14478)
		(layer "In6.Cu")
		(net "M_K_CPU0_SB_DQ<15>")
	)
	(segment
		(start 436.778146 -299.759878)
		(end 437.627776 -298.910248)
		(width 0.14478)
		(layer "In6.Cu")
		(net "M_K_CPU0_SB_DQ<15>")
	)
	(segment
		(start 409.520644 -297.26001)
		(end 409.719526 -297.458892)
		(width 0.14478)
		(layer "In6.Cu")
		(net "M_K_CPU0_SB_DQ<15>")
	)
	(segment
		(start 440.676538 -298.910248)
		(end 440.941714 -298.910248)
		(width 0.14478)
		(layer "In6.Cu")
		(net "M_K_CPU0_SB_DQ<15>")
	)
	(segment
		(start 441.498228 -298.61891)
		(end 441.789566 -298.910248)
		(width 0.14478)
		(layer "In6.Cu")
		(net "M_K_CPU0_SB_DQ<15>")
	)
	(segment
		(start 406.569926 -294.698928)
		(end 406.768808 -294.89781)
		(width 0.14478)
		(layer "In6.Cu")
		(net "M_K_CPU0_SB_DQ<15>")
	)
	(segment
		(start 411.689804 -299.760386)
		(end 413.548068 -299.760386)
		(width 0.14478)
		(layer "In6.Cu")
		(net "M_K_CPU0_SB_DQ<15>")
	)
	(segment
		(start 395.79296 -284.05709)
		(end 397.173958 -284.05709)
		(width 0.14478)
		(layer "In6.Cu")
		(net "M_K_CPU0_SB_DQ<15>")
	)
	(segment
		(start 397.173958 -284.05709)
		(end 405.201374 -292.084506)
		(width 0.14478)
		(layer "In6.Cu")
		(net "M_K_CPU0_SB_DQ<15>")
	)
	(segment
		(start 389.624824 -283.806138)
		(end 389.4709 -283.540708)
		(width 0.0889)
		(layer "In6.Cu")
		(net "M_K_CPU0_SB_DQ<15>")
	)
	(segment
		(start 405.782526 -293.521892)
		(end 405.782526 -293.911528)
		(width 0.14478)
		(layer "In6.Cu")
		(net "M_K_CPU0_SB_DQ<15>")
	)
	(segment
		(start 407.556208 -295.68521)
		(end 407.945844 -295.68521)
		(width 0.14478)
		(layer "In6.Cu")
		(net "M_K_CPU0_SB_DQ<15>")
	)
	(segment
		(start 410.506926 -298.246292)
		(end 410.506926 -298.635928)
		(width 0.14478)
		(layer "In6.Cu")
		(net "M_K_CPU0_SB_DQ<15>")
	)
	(segment
		(start 390.74344 -283.478732)
		(end 390.751822 -283.483558)
		(width 0.0889)
		(layer "In6.Cu")
		(net "M_K_CPU0_SB_DQ<15>")
	)
	(segment
		(start 392.631168 -283.483558)
		(end 392.641582 -283.489654)
		(width 0.0889)
		(layer "In6.Cu")
		(net "M_K_CPU0_SB_DQ<15>")
	)
	(segment
		(start 414.398206 -298.910248)
		(end 418.122608 -298.910248)
		(width 0.14478)
		(layer "In6.Cu")
		(net "M_K_CPU0_SB_DQ<15>")
	)
	(segment
		(start 407.158444 -294.89781)
		(end 407.357326 -295.096692)
		(width 0.14478)
		(layer "In6.Cu")
		(net "M_K_CPU0_SB_DQ<15>")
	)
	(segment
		(start 410.308044 -298.04741)
		(end 410.506926 -298.246292)
		(width 0.14478)
		(layer "In6.Cu")
		(net "M_K_CPU0_SB_DQ<15>")
	)
	(segment
		(start 406.371044 -294.11041)
		(end 406.569926 -294.309292)
		(width 0.14478)
		(layer "In6.Cu")
		(net "M_K_CPU0_SB_DQ<15>")
	)
	(segment
		(start 394.87348 -283.889958)
		(end 395.192758 -283.889958)
		(width 0.0889)
		(layer "In6.Cu")
		(net "M_K_CPU0_SB_DQ<15>")
	)
	(segment
		(start 405.981408 -294.11041)
		(end 406.371044 -294.11041)
		(width 0.14478)
		(layer "In6.Cu")
		(net "M_K_CPU0_SB_DQ<15>")
	)
	(segment
		(start 418.972746 -299.760386)
		(end 421.436038 -299.760386)
		(width 0.14478)
		(layer "In6.Cu")
		(net "M_K_CPU0_SB_DQ<15>")
	)
	(segment
		(start 418.122608 -298.910248)
		(end 418.972746 -299.760386)
		(width 0.14478)
		(layer "In6.Cu")
		(net "M_K_CPU0_SB_DQ<15>")
	)
	(segment
		(start 391.317734 -283.483558)
		(end 391.326116 -283.478732)
		(width 0.0889)
		(layer "In6.Cu")
		(net "M_K_CPU0_SB_DQ<15>")
	)
	(segment
		(start 425.666662 -298.910248)
		(end 426.5168 -299.760386)
		(width 0.14478)
		(layer "In6.Cu")
		(net "M_K_CPU0_SB_DQ<15>")
	)
	(segment
		(start 422.286176 -298.910248)
		(end 425.666662 -298.910248)
		(width 0.14478)
		(layer "In6.Cu")
		(net "M_K_CPU0_SB_DQ<15>")
	)
	(segment
		(start 437.627776 -298.910248)
		(end 439.828686 -298.910248)
		(width 0.14478)
		(layer "In6.Cu")
		(net "M_K_CPU0_SB_DQ<15>")
	)
	(segment
		(start 407.945844 -295.68521)
		(end 408.144726 -295.884092)
		(width 0.14478)
		(layer "In6.Cu")
		(net "M_K_CPU0_SB_DQ<15>")
	)
	(segment
		(start 409.719526 -297.458892)
		(end 409.719526 -297.848528)
		(width 0.14478)
		(layer "In6.Cu")
		(net "M_K_CPU0_SB_DQ<15>")
	)
	(segment
		(start 405.201374 -292.94074)
		(end 405.782526 -293.521892)
		(width 0.14478)
		(layer "In6.Cu")
		(net "M_K_CPU0_SB_DQ<15>")
	)
	(segment
		(start 421.436038 -299.760386)
		(end 422.286176 -298.910248)
		(width 0.14478)
		(layer "In6.Cu")
		(net "M_K_CPU0_SB_DQ<15>")
	)
	(segment
		(start 407.357326 -295.486328)
		(end 407.556208 -295.68521)
		(width 0.14478)
		(layer "In6.Cu")
		(net "M_K_CPU0_SB_DQ<15>")
	)
	(segment
		(start 442.119258 -298.910248)
		(end 442.5442 -299.33519)
		(width 0.14478)
		(layer "In6.Cu")
		(net "M_K_CPU0_SB_DQ<15>")
	)
	(segment
		(start 405.782526 -293.911528)
		(end 405.981408 -294.11041)
		(width 0.14478)
		(layer "In6.Cu")
		(net "M_K_CPU0_SB_DQ<15>")
	)
	(segment
		(start 408.343608 -296.47261)
		(end 408.733244 -296.47261)
		(width 0.14478)
		(layer "In6.Cu")
		(net "M_K_CPU0_SB_DQ<15>")
	)
	(segment
		(start 395.35989 -284.05709)
		(end 395.79296 -284.05709)
		(width 0.0889)
		(layer "In6.Cu")
		(net "M_K_CPU0_SB_DQ<15>")
	)
	(segment
		(start 405.201374 -292.084506)
		(end 405.201374 -292.94074)
		(width 0.14478)
		(layer "In6.Cu")
		(net "M_K_CPU0_SB_DQ<15>")
	)
	(segment
		(start 440.941714 -298.910248)
		(end 441.233052 -298.61891)
		(width 0.14478)
		(layer "In6.Cu")
		(net "M_K_CPU0_SB_DQ<15>")
	)
	(segment
		(start 395.192758 -283.889958)
		(end 395.35989 -284.05709)
		(width 0.0889)
		(layer "In6.Cu")
		(net "M_K_CPU0_SB_DQ<15>")
	)
	(segment
		(start 410.764228 -298.83481)
		(end 411.689804 -299.760386)
		(width 0.14478)
		(layer "In6.Cu")
		(net "M_K_CPU0_SB_DQ<15>")
	)
	(segment
		(start 406.768808 -294.89781)
		(end 407.158444 -294.89781)
		(width 0.14478)
		(layer "In6.Cu")
		(net "M_K_CPU0_SB_DQ<15>")
	)
	(segment
		(start 440.3852 -298.61891)
		(end 440.676538 -298.910248)
		(width 0.14478)
		(layer "In6.Cu")
		(net "M_K_CPU0_SB_DQ<15>")
	)
	(segment
		(start 409.918408 -298.04741)
		(end 410.308044 -298.04741)
		(width 0.14478)
		(layer "In6.Cu")
		(net "M_K_CPU0_SB_DQ<15>")
	)
	(segment
		(start 408.932126 -296.671492)
		(end 408.932126 -297.061128)
		(width 0.14478)
		(layer "In6.Cu")
		(net "M_K_CPU0_SB_DQ<15>")
	)
	(segment
		(start 392.24712 -283.489654)
		(end 392.257534 -283.483558)
		(width 0.0889)
		(layer "In6.Cu")
		(net "M_K_CPU0_SB_DQ<15>")
	)
	(segment
		(start 406.569926 -294.309292)
		(end 406.569926 -294.698928)
		(width 0.14478)
		(layer "In6.Cu")
		(net "M_K_CPU0_SB_DQ<15>")
	)
	(segment
		(start 394.416534 -283.433012)
		(end 394.87348 -283.889958)
		(width 0.0889)
		(layer "In6.Cu")
		(net "M_K_CPU0_SB_DQ<15>")
	)
	(segment
		(start 433.138326 -298.910248)
		(end 433.987956 -299.759878)
		(width 0.14478)
		(layer "In6.Cu")
		(net "M_K_CPU0_SB_DQ<15>")
	)
	(segment
		(start 409.719526 -297.848528)
		(end 409.918408 -298.04741)
		(width 0.14478)
		(layer "In6.Cu")
		(net "M_K_CPU0_SB_DQ<15>")
	)
	(segment
		(start 433.987956 -299.759878)
		(end 436.778146 -299.759878)
		(width 0.14478)
		(layer "In6.Cu")
		(net "M_K_CPU0_SB_DQ<15>")
	)
	(segment
		(start 407.357326 -295.096692)
		(end 407.357326 -295.486328)
		(width 0.14478)
		(layer "In6.Cu")
		(net "M_K_CPU0_SB_DQ<15>")
	)
	(segment
		(start 429.178212 -299.760386)
		(end 430.02835 -298.910248)
		(width 0.14478)
		(layer "In6.Cu")
		(net "M_K_CPU0_SB_DQ<15>")
	)
	(segment
		(start 392.257534 -283.483558)
		(end 392.265916 -283.478732)
		(width 0.0889)
		(layer "In6.Cu")
		(net "M_K_CPU0_SB_DQ<15>")
	)
	(segment
		(start 408.733244 -296.47261)
		(end 408.932126 -296.671492)
		(width 0.14478)
		(layer "In6.Cu")
		(net "M_K_CPU0_SB_DQ<15>")
	)
	(segment
		(start 440.120024 -298.61891)
		(end 440.3852 -298.61891)
		(width 0.14478)
		(layer "In6.Cu")
		(net "M_K_CPU0_SB_DQ<15>")
	)
	(segment
		(start 410.506926 -298.635928)
		(end 410.705808 -298.83481)
		(width 0.14478)
		(layer "In6.Cu")
		(net "M_K_CPU0_SB_DQ<15>")
	)
	(segment
		(start 389.4709 -283.540708)
		(end 389.493252 -283.457396)
		(width 0.0889)
		(layer "In6.Cu")
		(net "M_K_CPU0_SB_DQ<15>")
	)
	(segment
		(start 441.233052 -298.61891)
		(end 441.498228 -298.61891)
		(width 0.14478)
		(layer "In6.Cu")
		(net "M_K_CPU0_SB_DQ<15>")
	)
	(segment
		(start 408.144726 -296.273728)
		(end 408.343608 -296.47261)
		(width 0.14478)
		(layer "In6.Cu")
		(net "M_K_CPU0_SB_DQ<15>")
	)
	(segment
		(start 393.384786 -283.433012)
		(end 394.416534 -283.433012)
		(width 0.0889)
		(layer "In6.Cu")
		(net "M_K_CPU0_SB_DQ<15>")
	)
	(segment
		(start 410.705808 -298.83481)
		(end 410.764228 -298.83481)
		(width 0.14478)
		(layer "In6.Cu")
		(net "M_K_CPU0_SB_DQ<15>")
	)
	(segment
		(start 408.144726 -295.884092)
		(end 408.144726 -296.273728)
		(width 0.14478)
		(layer "In6.Cu")
		(net "M_K_CPU0_SB_DQ<15>")
	)
	(segment
		(start 439.828686 -298.910248)
		(end 440.120024 -298.61891)
		(width 0.14478)
		(layer "In6.Cu")
		(net "M_K_CPU0_SB_DQ<15>")
	)
	(arc
		(start 393.197334 -283.483558)
		(mid 393.287713 -283.445871)
		(end 393.384786 -283.433012)
		(width 0.0889)
		(layer "In6.Cu")
		(net "M_K_CPU0_SB_DQ<15>")
	)
	(arc
		(start 392.265916 -283.478732)
		(mid 392.44917 -283.433359)
		(end 392.631168 -283.483558)
		(width 0.0889)
		(layer "In6.Cu")
		(net "M_K_CPU0_SB_DQ<15>")
	)
	(arc
		(start 390.751822 -283.483558)
		(mid 391.034778 -283.559735)
		(end 391.317734 -283.483558)
		(width 0.0889)
		(layer "In6.Cu")
		(net "M_K_CPU0_SB_DQ<15>")
	)
	(arc
		(start 389.493252 -283.457396)
		(mid 389.655441 -283.434661)
		(end 389.811768 -283.483558)
		(width 0.0889)
		(layer "In6.Cu")
		(net "M_K_CPU0_SB_DQ<15>")
	)
	(arc
		(start 391.691876 -283.483558)
		(mid 391.968689 -283.559701)
		(end 392.24712 -283.489654)
		(width 0.0889)
		(layer "In6.Cu")
		(net "M_K_CPU0_SB_DQ<15>")
	)
	(arc
		(start 392.641582 -283.489654)
		(mid 392.920268 -283.559874)
		(end 393.197334 -283.483558)
		(width 0.0889)
		(layer "In6.Cu")
		(net "M_K_CPU0_SB_DQ<15>")
	)
	(arc
		(start 389.811768 -283.483558)
		(mid 390.094724 -283.559735)
		(end 390.37768 -283.483558)
		(width 0.0889)
		(layer "In6.Cu")
		(net "M_K_CPU0_SB_DQ<15>")
	)
	(arc
		(start 390.37768 -283.483558)
		(mid 390.559931 -283.433208)
		(end 390.74344 -283.478732)
		(width 0.0889)
		(layer "In6.Cu")
		(net "M_K_CPU0_SB_DQ<15>")
	)
	(arc
		(start 391.326116 -283.478732)
		(mid 391.509624 -283.433238)
		(end 391.691876 -283.483558)
		(width 0.0889)
		(layer "In6.Cu")
		(net "M_K_CPU0_SB_DQ<15>")
	)
	(segment
		(start 390.567926 -282.730194)
		(end 391.034778 -282.996132)
		(width 0.10668)
		(layer "F.Cu")
		(net "M_K_CPU0_SB_DQ<14>")
	)
	(segment
		(start 436.877714 -298.06011)
		(end 437.727598 -297.210226)
		(width 0.14478)
		(layer "In6.Cu")
		(net "M_K_CPU0_SB_DQ<14>")
	)
	(segment
		(start 407.260806 -292.687248)
		(end 407.446226 -292.872668)
		(width 0.14478)
		(layer "In6.Cu")
		(net "M_K_CPU0_SB_DQ<14>")
	)
	(segment
		(start 406.542748 -292.995604)
		(end 406.747472 -292.995858)
		(width 0.14478)
		(layer "In6.Cu")
		(net "M_K_CPU0_SB_DQ<14>")
	)
	(segment
		(start 393.384786 -282.756102)
		(end 394.441426 -282.756102)
		(width 0.0889)
		(layer "In6.Cu")
		(net "M_K_CPU0_SB_DQ<14>")
	)
	(segment
		(start 411.607508 -298.060364)
		(end 414.064196 -298.060364)
		(width 0.14478)
		(layer "In6.Cu")
		(net "M_K_CPU0_SB_DQ<14>")
	)
	(segment
		(start 395.753844 -283.14777)
		(end 397.550894 -283.14777)
		(width 0.14478)
		(layer "In6.Cu")
		(net "M_K_CPU0_SB_DQ<14>")
	)
	(segment
		(start 441.608972 -297.210226)
		(end 442.119258 -297.210226)
		(width 0.14478)
		(layer "In6.Cu")
		(net "M_K_CPU0_SB_DQ<14>")
	)
	(segment
		(start 407.056082 -292.687248)
		(end 407.260806 -292.687248)
		(width 0.14478)
		(layer "In6.Cu")
		(net "M_K_CPU0_SB_DQ<14>")
	)
	(segment
		(start 440.361324 -296.971212)
		(end 440.361324 -297.44924)
		(width 0.14478)
		(layer "In6.Cu")
		(net "M_K_CPU0_SB_DQ<14>")
	)
	(segment
		(start 421.634158 -298.060364)
		(end 422.484296 -297.210226)
		(width 0.14478)
		(layer "In6.Cu")
		(net "M_K_CPU0_SB_DQ<14>")
	)
	(segment
		(start 407.917904 -294.16629)
		(end 407.917904 -294.37076)
		(width 0.14478)
		(layer "In6.Cu")
		(net "M_K_CPU0_SB_DQ<14>")
	)
	(segment
		(start 441.464192 -297.065446)
		(end 441.608972 -297.210226)
		(width 0.14478)
		(layer "In6.Cu")
		(net "M_K_CPU0_SB_DQ<14>")
	)
	(segment
		(start 391.034778 -282.996132)
		(end 390.880854 -282.730702)
		(width 0.0889)
		(layer "In6.Cu")
		(net "M_K_CPU0_SB_DQ<14>")
	)
	(segment
		(start 408.041094 -293.467536)
		(end 408.226514 -293.652956)
		(width 0.14478)
		(layer "In6.Cu")
		(net "M_K_CPU0_SB_DQ<14>")
	)
	(segment
		(start 418.122608 -297.210226)
		(end 418.972746 -298.060364)
		(width 0.14478)
		(layer "In6.Cu")
		(net "M_K_CPU0_SB_DQ<14>")
	)
	(segment
		(start 440.506104 -297.59402)
		(end 440.767978 -297.59402)
		(width 0.14478)
		(layer "In6.Cu")
		(net "M_K_CPU0_SB_DQ<14>")
	)
	(segment
		(start 408.226514 -293.652956)
		(end 408.226514 -293.85768)
		(width 0.14478)
		(layer "In6.Cu")
		(net "M_K_CPU0_SB_DQ<14>")
	)
	(segment
		(start 407.83637 -293.467536)
		(end 408.041094 -293.467536)
		(width 0.14478)
		(layer "In6.Cu")
		(net "M_K_CPU0_SB_DQ<14>")
	)
	(segment
		(start 418.972746 -298.060364)
		(end 421.634158 -298.060364)
		(width 0.14478)
		(layer "In6.Cu")
		(net "M_K_CPU0_SB_DQ<14>")
	)
	(segment
		(start 406.152858 -291.749734)
		(end 406.152858 -292.605714)
		(width 0.14478)
		(layer "In6.Cu")
		(net "M_K_CPU0_SB_DQ<14>")
	)
	(segment
		(start 429.178212 -298.060364)
		(end 430.02835 -297.210226)
		(width 0.14478)
		(layer "In6.Cu")
		(net "M_K_CPU0_SB_DQ<14>")
	)
	(segment
		(start 440.216544 -296.826432)
		(end 440.361324 -296.971212)
		(width 0.14478)
		(layer "In6.Cu")
		(net "M_K_CPU0_SB_DQ<14>")
	)
	(segment
		(start 394.833094 -283.14777)
		(end 395.753844 -283.14777)
		(width 0.0889)
		(layer "In6.Cu")
		(net "M_K_CPU0_SB_DQ<14>")
	)
	(segment
		(start 407.323036 -293.775892)
		(end 407.52776 -293.776146)
		(width 0.14478)
		(layer "In6.Cu")
		(net "M_K_CPU0_SB_DQ<14>")
	)
	(segment
		(start 439.66511 -297.210226)
		(end 439.80989 -297.065446)
		(width 0.14478)
		(layer "In6.Cu")
		(net "M_K_CPU0_SB_DQ<14>")
	)
	(segment
		(start 440.912758 -297.44924)
		(end 440.912758 -296.971212)
		(width 0.14478)
		(layer "In6.Cu")
		(net "M_K_CPU0_SB_DQ<14>")
	)
	(segment
		(start 422.484296 -297.210226)
		(end 425.37253 -297.210226)
		(width 0.14478)
		(layer "In6.Cu")
		(net "M_K_CPU0_SB_DQ<14>")
	)
	(segment
		(start 414.064196 -298.060364)
		(end 414.914334 -297.210226)
		(width 0.14478)
		(layer "In6.Cu")
		(net "M_K_CPU0_SB_DQ<14>")
	)
	(segment
		(start 407.137616 -293.386002)
		(end 407.137616 -293.590472)
		(width 0.14478)
		(layer "In6.Cu")
		(net "M_K_CPU0_SB_DQ<14>")
	)
	(segment
		(start 408.226514 -293.85768)
		(end 407.917904 -294.16629)
		(width 0.14478)
		(layer "In6.Cu")
		(net "M_K_CPU0_SB_DQ<14>")
	)
	(segment
		(start 433.74564 -298.06011)
		(end 436.877714 -298.06011)
		(width 0.14478)
		(layer "In6.Cu")
		(net "M_K_CPU0_SB_DQ<14>")
	)
	(segment
		(start 392.153394 -282.668726)
		(end 392.161776 -282.673552)
		(width 0.0889)
		(layer "In6.Cu")
		(net "M_K_CPU0_SB_DQ<14>")
	)
	(segment
		(start 414.914334 -297.210226)
		(end 418.122608 -297.210226)
		(width 0.14478)
		(layer "In6.Cu")
		(net "M_K_CPU0_SB_DQ<14>")
	)
	(segment
		(start 392.727434 -282.673552)
		(end 392.735816 -282.668726)
		(width 0.0889)
		(layer "In6.Cu")
		(net "M_K_CPU0_SB_DQ<14>")
	)
	(segment
		(start 430.02835 -297.210226)
		(end 432.895756 -297.210226)
		(width 0.14478)
		(layer "In6.Cu")
		(net "M_K_CPU0_SB_DQ<14>")
	)
	(segment
		(start 439.80989 -296.971212)
		(end 439.95467 -296.826432)
		(width 0.14478)
		(layer "In6.Cu")
		(net "M_K_CPU0_SB_DQ<14>")
	)
	(segment
		(start 439.80989 -297.065446)
		(end 439.80989 -296.971212)
		(width 0.14478)
		(layer "In6.Cu")
		(net "M_K_CPU0_SB_DQ<14>")
	)
	(segment
		(start 441.057538 -296.826432)
		(end 441.319412 -296.826432)
		(width 0.14478)
		(layer "In6.Cu")
		(net "M_K_CPU0_SB_DQ<14>")
	)
	(segment
		(start 440.361324 -297.44924)
		(end 440.506104 -297.59402)
		(width 0.14478)
		(layer "In6.Cu")
		(net "M_K_CPU0_SB_DQ<14>")
	)
	(segment
		(start 442.119258 -297.210226)
		(end 442.5442 -297.635168)
		(width 0.14478)
		(layer "In6.Cu")
		(net "M_K_CPU0_SB_DQ<14>")
	)
	(segment
		(start 439.95467 -296.826432)
		(end 440.216544 -296.826432)
		(width 0.14478)
		(layer "In6.Cu")
		(net "M_K_CPU0_SB_DQ<14>")
	)
	(segment
		(start 407.917904 -294.37076)
		(end 411.607508 -298.060364)
		(width 0.14478)
		(layer "In6.Cu")
		(net "M_K_CPU0_SB_DQ<14>")
	)
	(segment
		(start 394.441426 -282.756102)
		(end 394.833094 -283.14777)
		(width 0.0889)
		(layer "In6.Cu")
		(net "M_K_CPU0_SB_DQ<14>")
	)
	(segment
		(start 440.767978 -297.59402)
		(end 440.912758 -297.44924)
		(width 0.14478)
		(layer "In6.Cu")
		(net "M_K_CPU0_SB_DQ<14>")
	)
	(segment
		(start 440.912758 -296.971212)
		(end 441.057538 -296.826432)
		(width 0.14478)
		(layer "In6.Cu")
		(net "M_K_CPU0_SB_DQ<14>")
	)
	(segment
		(start 441.319412 -296.826432)
		(end 441.464192 -296.971212)
		(width 0.14478)
		(layer "In6.Cu")
		(net "M_K_CPU0_SB_DQ<14>")
	)
	(segment
		(start 407.446226 -293.077392)
		(end 407.137616 -293.386002)
		(width 0.14478)
		(layer "In6.Cu")
		(net "M_K_CPU0_SB_DQ<14>")
	)
	(segment
		(start 392.161776 -282.673552)
		(end 392.17219 -282.679648)
		(width 0.0889)
		(layer "In6.Cu")
		(net "M_K_CPU0_SB_DQ<14>")
	)
	(segment
		(start 407.52776 -293.776146)
		(end 407.83637 -293.467536)
		(width 0.14478)
		(layer "In6.Cu")
		(net "M_K_CPU0_SB_DQ<14>")
	)
	(segment
		(start 437.727598 -297.210226)
		(end 439.66511 -297.210226)
		(width 0.14478)
		(layer "In6.Cu")
		(net "M_K_CPU0_SB_DQ<14>")
	)
	(segment
		(start 426.222668 -298.060364)
		(end 429.178212 -298.060364)
		(width 0.14478)
		(layer "In6.Cu")
		(net "M_K_CPU0_SB_DQ<14>")
	)
	(segment
		(start 406.152858 -292.605714)
		(end 406.542748 -292.995604)
		(width 0.14478)
		(layer "In6.Cu")
		(net "M_K_CPU0_SB_DQ<14>")
	)
	(segment
		(start 397.550894 -283.14777)
		(end 406.152858 -291.749734)
		(width 0.14478)
		(layer "In6.Cu")
		(net "M_K_CPU0_SB_DQ<14>")
	)
	(segment
		(start 425.37253 -297.210226)
		(end 426.222668 -298.060364)
		(width 0.14478)
		(layer "In6.Cu")
		(net "M_K_CPU0_SB_DQ<14>")
	)
	(segment
		(start 406.747472 -292.995858)
		(end 407.056082 -292.687248)
		(width 0.14478)
		(layer "In6.Cu")
		(net "M_K_CPU0_SB_DQ<14>")
	)
	(segment
		(start 407.446226 -292.872668)
		(end 407.446226 -293.077392)
		(width 0.14478)
		(layer "In6.Cu")
		(net "M_K_CPU0_SB_DQ<14>")
	)
	(segment
		(start 407.137616 -293.590472)
		(end 407.323036 -293.775892)
		(width 0.14478)
		(layer "In6.Cu")
		(net "M_K_CPU0_SB_DQ<14>")
	)
	(segment
		(start 390.880854 -282.730702)
		(end 390.903206 -282.64739)
		(width 0.0889)
		(layer "In6.Cu")
		(net "M_K_CPU0_SB_DQ<14>")
	)
	(segment
		(start 441.464192 -296.971212)
		(end 441.464192 -297.065446)
		(width 0.14478)
		(layer "In6.Cu")
		(net "M_K_CPU0_SB_DQ<14>")
	)
	(segment
		(start 432.895756 -297.210226)
		(end 433.74564 -298.06011)
		(width 0.14478)
		(layer "In6.Cu")
		(net "M_K_CPU0_SB_DQ<14>")
	)
	(arc
		(start 393.101576 -282.673552)
		(mid 393.23816 -282.732048)
		(end 393.384786 -282.756102)
		(width 0.0889)
		(layer "In6.Cu")
		(net "M_K_CPU0_SB_DQ<14>")
	)
	(arc
		(start 392.17219 -282.679648)
		(mid 392.450622 -282.749746)
		(end 392.727434 -282.673552)
		(width 0.0889)
		(layer "In6.Cu")
		(net "M_K_CPU0_SB_DQ<14>")
	)
	(arc
		(start 391.221722 -282.673552)
		(mid 391.504678 -282.749729)
		(end 391.787634 -282.673552)
		(width 0.0889)
		(layer "In6.Cu")
		(net "M_K_CPU0_SB_DQ<14>")
	)
	(arc
		(start 390.903206 -282.64739)
		(mid 391.065395 -282.624655)
		(end 391.221722 -282.673552)
		(width 0.0889)
		(layer "In6.Cu")
		(net "M_K_CPU0_SB_DQ<14>")
	)
	(arc
		(start 391.787634 -282.673552)
		(mid 391.969885 -282.623202)
		(end 392.153394 -282.668726)
		(width 0.0889)
		(layer "In6.Cu")
		(net "M_K_CPU0_SB_DQ<14>")
	)
	(arc
		(start 392.735816 -282.668726)
		(mid 392.919324 -282.623232)
		(end 393.101576 -282.673552)
		(width 0.0889)
		(layer "In6.Cu")
		(net "M_K_CPU0_SB_DQ<14>")
	)
	(segment
		(start 388.688072 -282.730194)
		(end 389.154924 -282.996132)
		(width 0.10668)
		(layer "F.Cu")
		(net "M_K_CPU0_SB_DQ<13>")
	)
	(segment
		(start 426.928026 -298.910248)
		(end 428.689008 -298.910248)
		(width 0.14478)
		(layer "In6.Cu")
		(net "M_K_CPU0_SB_DQ<13>")
	)
	(segment
		(start 411.81401 -298.910248)
		(end 413.20974 -298.910248)
		(width 0.14478)
		(layer "In6.Cu")
		(net "M_K_CPU0_SB_DQ<13>")
	)
	(segment
		(start 413.20974 -298.910248)
		(end 415.261552 -298.060364)
		(width 0.14478)
		(layer "In6.Cu")
		(net "M_K_CPU0_SB_DQ<13>")
	)
	(segment
		(start 389.308848 -283.261562)
		(end 389.40486 -283.286962)
		(width 0.0889)
		(layer "In6.Cu")
		(net "M_K_CPU0_SB_DQ<13>")
	)
	(segment
		(start 389.154924 -282.996132)
		(end 389.308848 -283.261562)
		(width 0.0889)
		(layer "In6.Cu")
		(net "M_K_CPU0_SB_DQ<13>")
	)
	(segment
		(start 389.90778 -283.318712)
		(end 389.916162 -283.323538)
		(width 0.0889)
		(layer "In6.Cu")
		(net "M_K_CPU0_SB_DQ<13>")
	)
	(segment
		(start 419.466268 -298.910248)
		(end 421.00373 -298.910248)
		(width 0.14478)
		(layer "In6.Cu")
		(net "M_K_CPU0_SB_DQ<13>")
	)
	(segment
		(start 438.346088 -298.06011)
		(end 446.219326 -298.06011)
		(width 0.14478)
		(layer "In6.Cu")
		(net "M_K_CPU0_SB_DQ<13>")
	)
	(segment
		(start 397.362426 -283.60243)
		(end 405.656034 -291.896038)
		(width 0.14478)
		(layer "In6.Cu")
		(net "M_K_CPU0_SB_DQ<13>")
	)
	(segment
		(start 432.517042 -298.060364)
		(end 434.568346 -298.909994)
		(width 0.14478)
		(layer "In6.Cu")
		(net "M_K_CPU0_SB_DQ<13>")
	)
	(segment
		(start 392.149838 -283.32557)
		(end 392.161522 -283.318712)
		(width 0.0889)
		(layer "In6.Cu")
		(net "M_K_CPU0_SB_DQ<13>")
	)
	(segment
		(start 428.689008 -298.910248)
		(end 430.74082 -298.060364)
		(width 0.14478)
		(layer "In6.Cu")
		(net "M_K_CPU0_SB_DQ<13>")
	)
	(segment
		(start 395.513814 -283.60243)
		(end 395.816836 -283.60243)
		(width 0.0889)
		(layer "In6.Cu")
		(net "M_K_CPU0_SB_DQ<13>")
	)
	(segment
		(start 415.261552 -298.060364)
		(end 417.414456 -298.060364)
		(width 0.14478)
		(layer "In6.Cu")
		(net "M_K_CPU0_SB_DQ<13>")
	)
	(segment
		(start 417.414456 -298.060364)
		(end 419.466268 -298.910248)
		(width 0.14478)
		(layer "In6.Cu")
		(net "M_K_CPU0_SB_DQ<13>")
	)
	(segment
		(start 395.318234 -283.40685)
		(end 395.513814 -283.60243)
		(width 0.0889)
		(layer "In6.Cu")
		(net "M_K_CPU0_SB_DQ<13>")
	)
	(segment
		(start 392.161522 -283.318712)
		(end 392.171936 -283.312616)
		(width 0.0889)
		(layer "In6.Cu")
		(net "M_K_CPU0_SB_DQ<13>")
	)
	(segment
		(start 421.00373 -298.910248)
		(end 423.055542 -298.060364)
		(width 0.14478)
		(layer "In6.Cu")
		(net "M_K_CPU0_SB_DQ<13>")
	)
	(segment
		(start 446.219326 -298.06011)
		(end 446.644268 -298.485052)
		(width 0.14478)
		(layer "In6.Cu")
		(net "M_K_CPU0_SB_DQ<13>")
	)
	(segment
		(start 393.384786 -283.242512)
		(end 394.539216 -283.242512)
		(width 0.0889)
		(layer "In6.Cu")
		(net "M_K_CPU0_SB_DQ<13>")
	)
	(segment
		(start 436.294276 -298.909994)
		(end 438.346088 -298.06011)
		(width 0.14478)
		(layer "In6.Cu")
		(net "M_K_CPU0_SB_DQ<13>")
	)
	(segment
		(start 423.055542 -298.060364)
		(end 424.876214 -298.060364)
		(width 0.14478)
		(layer "In6.Cu")
		(net "M_K_CPU0_SB_DQ<13>")
	)
	(segment
		(start 430.74082 -298.060364)
		(end 432.517042 -298.060364)
		(width 0.14478)
		(layer "In6.Cu")
		(net "M_K_CPU0_SB_DQ<13>")
	)
	(segment
		(start 434.568346 -298.909994)
		(end 436.294276 -298.909994)
		(width 0.14478)
		(layer "In6.Cu")
		(net "M_K_CPU0_SB_DQ<13>")
	)
	(segment
		(start 394.539216 -283.242512)
		(end 394.703554 -283.40685)
		(width 0.0889)
		(layer "In6.Cu")
		(net "M_K_CPU0_SB_DQ<13>")
	)
	(segment
		(start 405.656034 -291.896038)
		(end 405.656034 -292.752272)
		(width 0.14478)
		(layer "In6.Cu")
		(net "M_K_CPU0_SB_DQ<13>")
	)
	(segment
		(start 392.72718 -283.318712)
		(end 392.738864 -283.32557)
		(width 0.0889)
		(layer "In6.Cu")
		(net "M_K_CPU0_SB_DQ<13>")
	)
	(segment
		(start 424.876214 -298.060364)
		(end 426.928026 -298.910248)
		(width 0.14478)
		(layer "In6.Cu")
		(net "M_K_CPU0_SB_DQ<13>")
	)
	(segment
		(start 394.703554 -283.40685)
		(end 395.318234 -283.40685)
		(width 0.0889)
		(layer "In6.Cu")
		(net "M_K_CPU0_SB_DQ<13>")
	)
	(segment
		(start 395.816836 -283.60243)
		(end 397.362426 -283.60243)
		(width 0.14478)
		(layer "In6.Cu")
		(net "M_K_CPU0_SB_DQ<13>")
	)
	(segment
		(start 405.656034 -292.752272)
		(end 411.81401 -298.910248)
		(width 0.14478)
		(layer "In6.Cu")
		(net "M_K_CPU0_SB_DQ<13>")
	)
	(arc
		(start 392.171936 -283.312616)
		(mid 392.450368 -283.242518)
		(end 392.72718 -283.318712)
		(width 0.0889)
		(layer "In6.Cu")
		(net "M_K_CPU0_SB_DQ<13>")
	)
	(arc
		(start 389.40486 -283.286962)
		(mid 389.660068 -283.243485)
		(end 389.90778 -283.318712)
		(width 0.0889)
		(layer "In6.Cu")
		(net "M_K_CPU0_SB_DQ<13>")
	)
	(arc
		(start 389.916162 -283.323538)
		(mid 390.09967 -283.369032)
		(end 390.281922 -283.318712)
		(width 0.0889)
		(layer "In6.Cu")
		(net "M_K_CPU0_SB_DQ<13>")
	)
	(arc
		(start 390.847834 -283.318712)
		(mid 391.034778 -283.368967)
		(end 391.221722 -283.318712)
		(width 0.0889)
		(layer "In6.Cu")
		(net "M_K_CPU0_SB_DQ<13>")
	)
	(arc
		(start 391.221722 -283.318712)
		(mid 391.504678 -283.242535)
		(end 391.787634 -283.318712)
		(width 0.0889)
		(layer "In6.Cu")
		(net "M_K_CPU0_SB_DQ<13>")
	)
	(arc
		(start 390.281922 -283.318712)
		(mid 390.564878 -283.242535)
		(end 390.847834 -283.318712)
		(width 0.0889)
		(layer "In6.Cu")
		(net "M_K_CPU0_SB_DQ<13>")
	)
	(arc
		(start 393.101576 -283.318712)
		(mid 393.238135 -283.261854)
		(end 393.384786 -283.242512)
		(width 0.0889)
		(layer "In6.Cu")
		(net "M_K_CPU0_SB_DQ<13>")
	)
	(arc
		(start 392.738864 -283.32557)
		(mid 392.921119 -283.369223)
		(end 393.101576 -283.318712)
		(width 0.0889)
		(layer "In6.Cu")
		(net "M_K_CPU0_SB_DQ<13>")
	)
	(arc
		(start 391.787634 -283.318712)
		(mid 391.967839 -283.369029)
		(end 392.149838 -283.32557)
		(width 0.0889)
		(layer "In6.Cu")
		(net "M_K_CPU0_SB_DQ<13>")
	)
	(segment
		(start 390.098026 -281.920188)
		(end 390.564878 -282.186126)
		(width 0.10668)
		(layer "F.Cu")
		(net "M_K_CPU0_SB_DQ<12>")
	)
	(segment
		(start 445.171322 -296.523156)
		(end 445.171322 -296.830242)
		(width 0.14478)
		(layer "In6.Cu")
		(net "M_K_CPU0_SB_DQ<12>")
	)
	(segment
		(start 390.718802 -282.451556)
		(end 390.814814 -282.476956)
		(width 0.0889)
		(layer "In6.Cu")
		(net "M_K_CPU0_SB_DQ<12>")
	)
	(segment
		(start 445.33439 -296.99331)
		(end 445.564768 -296.99331)
		(width 0.14478)
		(layer "In6.Cu")
		(net "M_K_CPU0_SB_DQ<12>")
	)
	(segment
		(start 430.111662 -296.36974)
		(end 432.929538 -296.36974)
		(width 0.14478)
		(layer "In6.Cu")
		(net "M_K_CPU0_SB_DQ<12>")
	)
	(segment
		(start 433.779422 -297.219624)
		(end 436.72252 -297.219624)
		(width 0.14478)
		(layer "In6.Cu")
		(net "M_K_CPU0_SB_DQ<12>")
	)
	(segment
		(start 445.171322 -296.830242)
		(end 445.33439 -296.99331)
		(width 0.14478)
		(layer "In6.Cu")
		(net "M_K_CPU0_SB_DQ<12>")
	)
	(segment
		(start 411.753558 -297.491912)
		(end 413.901382 -297.491912)
		(width 0.14478)
		(layer "In6.Cu")
		(net "M_K_CPU0_SB_DQ<12>")
	)
	(segment
		(start 395.748256 -282.69311)
		(end 397.968978 -282.69311)
		(width 0.14478)
		(layer "In6.Cu")
		(net "M_K_CPU0_SB_DQ<12>")
	)
	(segment
		(start 392.631422 -282.508706)
		(end 392.641836 -282.50261)
		(width 0.0889)
		(layer "In6.Cu")
		(net "M_K_CPU0_SB_DQ<12>")
	)
	(segment
		(start 446.219326 -296.360088)
		(end 446.644268 -296.78503)
		(width 0.14478)
		(layer "In6.Cu")
		(net "M_K_CPU0_SB_DQ<12>")
	)
	(segment
		(start 413.901382 -297.491912)
		(end 414.655762 -296.737532)
		(width 0.14478)
		(layer "In6.Cu")
		(net "M_K_CPU0_SB_DQ<12>")
	)
	(segment
		(start 429.261778 -297.219624)
		(end 430.111662 -296.36974)
		(width 0.14478)
		(layer "In6.Cu")
		(net "M_K_CPU0_SB_DQ<12>")
	)
	(segment
		(start 408.807158 -294.545512)
		(end 411.753558 -297.491912)
		(width 0.14478)
		(layer "In6.Cu")
		(net "M_K_CPU0_SB_DQ<12>")
	)
	(segment
		(start 393.966192 -282.35021)
		(end 395.214602 -282.35021)
		(width 0.0889)
		(layer "In6.Cu")
		(net "M_K_CPU0_SB_DQ<12>")
	)
	(segment
		(start 421.717724 -297.219624)
		(end 422.567608 -296.36974)
		(width 0.14478)
		(layer "In6.Cu")
		(net "M_K_CPU0_SB_DQ<12>")
	)
	(segment
		(start 390.564878 -282.186126)
		(end 390.718802 -282.451556)
		(width 0.0889)
		(layer "In6.Cu")
		(net "M_K_CPU0_SB_DQ<12>")
	)
	(segment
		(start 432.929538 -296.36974)
		(end 433.779422 -297.219624)
		(width 0.14478)
		(layer "In6.Cu")
		(net "M_K_CPU0_SB_DQ<12>")
	)
	(segment
		(start 445.890904 -296.360088)
		(end 446.219326 -296.360088)
		(width 0.14478)
		(layer "In6.Cu")
		(net "M_K_CPU0_SB_DQ<12>")
	)
	(segment
		(start 408.807158 -293.53129)
		(end 408.807158 -294.545512)
		(width 0.14478)
		(layer "In6.Cu")
		(net "M_K_CPU0_SB_DQ<12>")
	)
	(segment
		(start 437.572658 -296.369486)
		(end 445.017652 -296.369486)
		(width 0.14478)
		(layer "In6.Cu")
		(net "M_K_CPU0_SB_DQ<12>")
	)
	(segment
		(start 392.24712 -282.50261)
		(end 392.257534 -282.508706)
		(width 0.0889)
		(layer "In6.Cu")
		(net "M_K_CPU0_SB_DQ<12>")
	)
	(segment
		(start 395.557502 -282.69311)
		(end 395.748256 -282.69311)
		(width 0.0889)
		(layer "In6.Cu")
		(net "M_K_CPU0_SB_DQ<12>")
	)
	(segment
		(start 445.017652 -296.369486)
		(end 445.171322 -296.523156)
		(width 0.14478)
		(layer "In6.Cu")
		(net "M_K_CPU0_SB_DQ<12>")
	)
	(segment
		(start 397.968978 -282.69311)
		(end 408.807158 -293.53129)
		(width 0.14478)
		(layer "In6.Cu")
		(net "M_K_CPU0_SB_DQ<12>")
	)
	(segment
		(start 414.655762 -296.737532)
		(end 418.434774 -296.737532)
		(width 0.14478)
		(layer "In6.Cu")
		(net "M_K_CPU0_SB_DQ<12>")
	)
	(segment
		(start 391.317734 -282.508706)
		(end 391.326116 -282.513532)
		(width 0.0889)
		(layer "In6.Cu")
		(net "M_K_CPU0_SB_DQ<12>")
	)
	(segment
		(start 425.355004 -296.36974)
		(end 426.204888 -297.219624)
		(width 0.14478)
		(layer "In6.Cu")
		(net "M_K_CPU0_SB_DQ<12>")
	)
	(segment
		(start 445.727836 -296.523156)
		(end 445.890904 -296.360088)
		(width 0.14478)
		(layer "In6.Cu")
		(net "M_K_CPU0_SB_DQ<12>")
	)
	(segment
		(start 418.916866 -297.219624)
		(end 421.717724 -297.219624)
		(width 0.14478)
		(layer "In6.Cu")
		(net "M_K_CPU0_SB_DQ<12>")
	)
	(segment
		(start 436.72252 -297.219624)
		(end 437.572658 -296.369486)
		(width 0.14478)
		(layer "In6.Cu")
		(net "M_K_CPU0_SB_DQ<12>")
	)
	(segment
		(start 426.204888 -297.219624)
		(end 429.261778 -297.219624)
		(width 0.14478)
		(layer "In6.Cu")
		(net "M_K_CPU0_SB_DQ<12>")
	)
	(segment
		(start 422.567608 -296.36974)
		(end 425.355004 -296.36974)
		(width 0.14478)
		(layer "In6.Cu")
		(net "M_K_CPU0_SB_DQ<12>")
	)
	(segment
		(start 445.564768 -296.99331)
		(end 445.727836 -296.830242)
		(width 0.14478)
		(layer "In6.Cu")
		(net "M_K_CPU0_SB_DQ<12>")
	)
	(segment
		(start 395.214602 -282.35021)
		(end 395.557502 -282.69311)
		(width 0.0889)
		(layer "In6.Cu")
		(net "M_K_CPU0_SB_DQ<12>")
	)
	(segment
		(start 418.434774 -296.737532)
		(end 418.916866 -297.219624)
		(width 0.14478)
		(layer "In6.Cu")
		(net "M_K_CPU0_SB_DQ<12>")
	)
	(segment
		(start 445.727836 -296.830242)
		(end 445.727836 -296.523156)
		(width 0.14478)
		(layer "In6.Cu")
		(net "M_K_CPU0_SB_DQ<12>")
	)
	(arc
		(start 393.478258 -282.552648)
		(mid 393.575074 -282.536692)
		(end 393.654788 -282.479496)
		(width 0.0889)
		(layer "In6.Cu")
		(net "M_K_CPU0_SB_DQ<12>")
	)
	(arc
		(start 393.384786 -282.552648)
		(mid 393.431522 -282.551117)
		(end 393.478258 -282.552648)
		(width 0.0889)
		(layer "In6.Cu")
		(net "M_K_CPU0_SB_DQ<12>")
	)
	(arc
		(start 391.691876 -282.508706)
		(mid 391.968689 -282.432563)
		(end 392.24712 -282.50261)
		(width 0.0889)
		(layer "In6.Cu")
		(net "M_K_CPU0_SB_DQ<12>")
	)
	(arc
		(start 392.641836 -282.50261)
		(mid 392.920522 -282.43239)
		(end 393.197588 -282.508706)
		(width 0.0889)
		(layer "In6.Cu")
		(net "M_K_CPU0_SB_DQ<12>")
	)
	(arc
		(start 391.326116 -282.513532)
		(mid 391.509624 -282.559026)
		(end 391.691876 -282.508706)
		(width 0.0889)
		(layer "In6.Cu")
		(net "M_K_CPU0_SB_DQ<12>")
	)
	(arc
		(start 393.654788 -282.479496)
		(mid 393.795429 -282.378556)
		(end 393.966192 -282.35021)
		(width 0.0889)
		(layer "In6.Cu")
		(net "M_K_CPU0_SB_DQ<12>")
	)
	(arc
		(start 393.197588 -282.508706)
		(mid 393.287917 -282.54459)
		(end 393.384786 -282.552648)
		(width 0.0889)
		(layer "In6.Cu")
		(net "M_K_CPU0_SB_DQ<12>")
	)
	(arc
		(start 390.814814 -282.476956)
		(mid 391.070022 -282.433479)
		(end 391.317734 -282.508706)
		(width 0.0889)
		(layer "In6.Cu")
		(net "M_K_CPU0_SB_DQ<12>")
	)
	(arc
		(start 392.257534 -282.508706)
		(mid 392.444478 -282.558961)
		(end 392.631422 -282.508706)
		(width 0.0889)
		(layer "In6.Cu")
		(net "M_K_CPU0_SB_DQ<12>")
	)
	(segment
		(start 389.157972 -280.300176)
		(end 389.624824 -280.566114)
		(width 0.10668)
		(layer "F.Cu")
		(net "M_K_CPU0_SB_DQ<11>")
	)
	(segment
		(start 429.326548 -293.63797)
		(end 430.004474 -292.960044)
		(width 0.14478)
		(layer "In6.Cu")
		(net "M_K_CPU0_SB_DQ<11>")
	)
	(segment
		(start 424.991022 -292.67531)
		(end 425.186602 -292.87089)
		(width 0.14478)
		(layer "In6.Cu")
		(net "M_K_CPU0_SB_DQ<11>")
	)
	(segment
		(start 416.364166 -293.22395)
		(end 416.495992 -293.092124)
		(width 0.14478)
		(layer "In6.Cu")
		(net "M_K_CPU0_SB_DQ<11>")
	)
	(segment
		(start 440.842146 -293.161212)
		(end 440.986926 -293.305992)
		(width 0.14478)
		(layer "In6.Cu")
		(net "M_K_CPU0_SB_DQ<11>")
	)
	(segment
		(start 432.825652 -292.84041)
		(end 433.091082 -292.84041)
		(width 0.14478)
		(layer "In6.Cu")
		(net "M_K_CPU0_SB_DQ<11>")
	)
	(segment
		(start 416.495992 -293.092124)
		(end 416.495992 -292.827964)
		(width 0.14478)
		(layer "In6.Cu")
		(net "M_K_CPU0_SB_DQ<11>")
	)
	(segment
		(start 438.380632 -292.950646)
		(end 439.479944 -292.950646)
		(width 0.14478)
		(layer "In6.Cu")
		(net "M_K_CPU0_SB_DQ<11>")
	)
	(segment
		(start 416.92068 -292.696138)
		(end 417.052506 -292.827964)
		(width 0.14478)
		(layer "In6.Cu")
		(net "M_K_CPU0_SB_DQ<11>")
	)
	(segment
		(start 441.39358 -292.721792)
		(end 441.53836 -292.577012)
		(width 0.14478)
		(layer "In6.Cu")
		(net "M_K_CPU0_SB_DQ<11>")
	)
	(segment
		(start 428.313088 -293.51351)
		(end 428.57293 -293.51351)
		(width 0.14478)
		(layer "In6.Cu")
		(net "M_K_CPU0_SB_DQ<11>")
	)
	(segment
		(start 438.079896 -292.64991)
		(end 438.380632 -292.950646)
		(width 0.14478)
		(layer "In6.Cu")
		(net "M_K_CPU0_SB_DQ<11>")
	)
	(segment
		(start 414.083246 -292.960044)
		(end 414.70199 -292.960044)
		(width 0.14478)
		(layer "In6.Cu")
		(net "M_K_CPU0_SB_DQ<11>")
	)
	(segment
		(start 413.233108 -293.810182)
		(end 414.083246 -292.960044)
		(width 0.14478)
		(layer "In6.Cu")
		(net "M_K_CPU0_SB_DQ<11>")
	)
	(segment
		(start 417.052506 -292.827964)
		(end 417.052506 -293.092124)
		(width 0.14478)
		(layer "In6.Cu")
		(net "M_K_CPU0_SB_DQ<11>")
	)
	(segment
		(start 395.759686 -280.2001)
		(end 398.785588 -280.2001)
		(width 0.14478)
		(layer "In6.Cu")
		(net "M_K_CPU0_SB_DQ<11>")
	)
	(segment
		(start 422.668954 -292.960044)
		(end 422.979088 -292.64991)
		(width 0.14478)
		(layer "In6.Cu")
		(net "M_K_CPU0_SB_DQ<11>")
	)
	(segment
		(start 420.772844 -293.53891)
		(end 421.058086 -293.53891)
		(width 0.14478)
		(layer "In6.Cu")
		(net "M_K_CPU0_SB_DQ<11>")
	)
	(segment
		(start 441.736226 -292.577012)
		(end 442.5442 -293.384986)
		(width 0.14478)
		(layer "In6.Cu")
		(net "M_K_CPU0_SB_DQ<11>")
	)
	(segment
		(start 441.53836 -292.577012)
		(end 441.736226 -292.577012)
		(width 0.14478)
		(layer "In6.Cu")
		(net "M_K_CPU0_SB_DQ<11>")
	)
	(segment
		(start 417.052506 -293.092124)
		(end 417.184332 -293.22395)
		(width 0.14478)
		(layer "In6.Cu")
		(net "M_K_CPU0_SB_DQ<11>")
	)
	(segment
		(start 415.258504 -292.67531)
		(end 415.543238 -292.960044)
		(width 0.14478)
		(layer "In6.Cu")
		(net "M_K_CPU0_SB_DQ<11>")
	)
	(segment
		(start 430.004474 -292.960044)
		(end 430.276762 -292.960044)
		(width 0.14478)
		(layer "In6.Cu")
		(net "M_K_CPU0_SB_DQ<11>")
	)
	(segment
		(start 437.523382 -292.960044)
		(end 437.833516 -292.64991)
		(width 0.14478)
		(layer "In6.Cu")
		(net "M_K_CPU0_SB_DQ<11>")
	)
	(segment
		(start 431.083212 -292.950646)
		(end 432.113436 -292.950646)
		(width 0.14478)
		(layer "In6.Cu")
		(net "M_K_CPU0_SB_DQ<11>")
	)
	(segment
		(start 412.39567 -293.810182)
		(end 413.233108 -293.810182)
		(width 0.14478)
		(layer "In6.Cu")
		(net "M_K_CPU0_SB_DQ<11>")
	)
	(segment
		(start 422.979088 -292.64991)
		(end 423.225468 -292.64991)
		(width 0.14478)
		(layer "In6.Cu")
		(net "M_K_CPU0_SB_DQ<11>")
	)
	(segment
		(start 426.507402 -293.800784)
		(end 428.025814 -293.800784)
		(width 0.14478)
		(layer "In6.Cu")
		(net "M_K_CPU0_SB_DQ<11>")
	)
	(segment
		(start 440.986926 -293.305992)
		(end 441.2488 -293.305992)
		(width 0.14478)
		(layer "In6.Cu")
		(net "M_K_CPU0_SB_DQ<11>")
	)
	(segment
		(start 389.624824 -280.566114)
		(end 389.4709 -280.300684)
		(width 0.0889)
		(layer "In6.Cu")
		(net "M_K_CPU0_SB_DQ<11>")
	)
	(segment
		(start 424.443906 -292.950646)
		(end 424.719242 -292.67531)
		(width 0.14478)
		(layer "In6.Cu")
		(net "M_K_CPU0_SB_DQ<11>")
	)
	(segment
		(start 434.051202 -293.80053)
		(end 436.298848 -293.80053)
		(width 0.14478)
		(layer "In6.Cu")
		(net "M_K_CPU0_SB_DQ<11>")
	)
	(segment
		(start 424.719242 -292.67531)
		(end 424.991022 -292.67531)
		(width 0.14478)
		(layer "In6.Cu")
		(net "M_K_CPU0_SB_DQ<11>")
	)
	(segment
		(start 392.631168 -280.243534)
		(end 392.641582 -280.24963)
		(width 0.0889)
		(layer "In6.Cu")
		(net "M_K_CPU0_SB_DQ<11>")
	)
	(segment
		(start 414.70199 -292.960044)
		(end 414.986724 -292.67531)
		(width 0.14478)
		(layer "In6.Cu")
		(net "M_K_CPU0_SB_DQ<11>")
	)
	(segment
		(start 390.74344 -280.238708)
		(end 390.751822 -280.243534)
		(width 0.0889)
		(layer "In6.Cu")
		(net "M_K_CPU0_SB_DQ<11>")
	)
	(segment
		(start 421.805354 -293.61257)
		(end 422.45788 -292.960044)
		(width 0.14478)
		(layer "In6.Cu")
		(net "M_K_CPU0_SB_DQ<11>")
	)
	(segment
		(start 416.071304 -293.22395)
		(end 416.364166 -293.22395)
		(width 0.14478)
		(layer "In6.Cu")
		(net "M_K_CPU0_SB_DQ<11>")
	)
	(segment
		(start 433.091082 -292.84041)
		(end 434.051202 -293.80053)
		(width 0.14478)
		(layer "In6.Cu")
		(net "M_K_CPU0_SB_DQ<11>")
	)
	(segment
		(start 428.025814 -293.800784)
		(end 428.313088 -293.51351)
		(width 0.14478)
		(layer "In6.Cu")
		(net "M_K_CPU0_SB_DQ<11>")
	)
	(segment
		(start 421.131746 -293.61257)
		(end 421.805354 -293.61257)
		(width 0.14478)
		(layer "In6.Cu")
		(net "M_K_CPU0_SB_DQ<11>")
	)
	(segment
		(start 437.139334 -292.960044)
		(end 437.523382 -292.960044)
		(width 0.14478)
		(layer "In6.Cu")
		(net "M_K_CPU0_SB_DQ<11>")
	)
	(segment
		(start 393.286742 -280.2001)
		(end 395.759686 -280.2001)
		(width 0.0889)
		(layer "In6.Cu")
		(net "M_K_CPU0_SB_DQ<11>")
	)
	(segment
		(start 428.69739 -293.63797)
		(end 429.326548 -293.63797)
		(width 0.14478)
		(layer "In6.Cu")
		(net "M_K_CPU0_SB_DQ<11>")
	)
	(segment
		(start 432.660552 -292.67531)
		(end 432.825652 -292.84041)
		(width 0.14478)
		(layer "In6.Cu")
		(net "M_K_CPU0_SB_DQ<11>")
	)
	(segment
		(start 432.113436 -292.950646)
		(end 432.388772 -292.67531)
		(width 0.14478)
		(layer "In6.Cu")
		(net "M_K_CPU0_SB_DQ<11>")
	)
	(segment
		(start 421.058086 -293.53891)
		(end 421.131746 -293.61257)
		(width 0.14478)
		(layer "In6.Cu")
		(net "M_K_CPU0_SB_DQ<11>")
	)
	(segment
		(start 417.184332 -293.22395)
		(end 417.477194 -293.22395)
		(width 0.14478)
		(layer "In6.Cu")
		(net "M_K_CPU0_SB_DQ<11>")
	)
	(segment
		(start 441.39358 -293.161212)
		(end 441.39358 -292.721792)
		(width 0.14478)
		(layer "In6.Cu")
		(net "M_K_CPU0_SB_DQ<11>")
	)
	(segment
		(start 416.495992 -292.827964)
		(end 416.627818 -292.696138)
		(width 0.14478)
		(layer "In6.Cu")
		(net "M_K_CPU0_SB_DQ<11>")
	)
	(segment
		(start 418.963348 -293.800784)
		(end 420.51097 -293.800784)
		(width 0.14478)
		(layer "In6.Cu")
		(net "M_K_CPU0_SB_DQ<11>")
	)
	(segment
		(start 432.388772 -292.67531)
		(end 432.660552 -292.67531)
		(width 0.14478)
		(layer "In6.Cu")
		(net "M_K_CPU0_SB_DQ<11>")
	)
	(segment
		(start 417.60902 -293.09187)
		(end 417.740846 -292.960044)
		(width 0.14478)
		(layer "In6.Cu")
		(net "M_K_CPU0_SB_DQ<11>")
	)
	(segment
		(start 416.627818 -292.696138)
		(end 416.92068 -292.696138)
		(width 0.14478)
		(layer "In6.Cu")
		(net "M_K_CPU0_SB_DQ<11>")
	)
	(segment
		(start 417.477194 -293.22395)
		(end 417.60902 -293.092124)
		(width 0.14478)
		(layer "In6.Cu")
		(net "M_K_CPU0_SB_DQ<11>")
	)
	(segment
		(start 415.939478 -293.092124)
		(end 416.071304 -293.22395)
		(width 0.14478)
		(layer "In6.Cu")
		(net "M_K_CPU0_SB_DQ<11>")
	)
	(segment
		(start 417.60902 -293.092124)
		(end 417.60902 -293.09187)
		(width 0.14478)
		(layer "In6.Cu")
		(net "M_K_CPU0_SB_DQ<11>")
	)
	(segment
		(start 430.833276 -292.70071)
		(end 431.083212 -292.950646)
		(width 0.14478)
		(layer "In6.Cu")
		(net "M_K_CPU0_SB_DQ<11>")
	)
	(segment
		(start 439.479944 -292.950646)
		(end 439.853578 -292.577012)
		(width 0.14478)
		(layer "In6.Cu")
		(net "M_K_CPU0_SB_DQ<11>")
	)
	(segment
		(start 415.543238 -292.960044)
		(end 415.807652 -292.960044)
		(width 0.14478)
		(layer "In6.Cu")
		(net "M_K_CPU0_SB_DQ<11>")
	)
	(segment
		(start 440.842146 -292.721792)
		(end 440.842146 -293.161212)
		(width 0.14478)
		(layer "In6.Cu")
		(net "M_K_CPU0_SB_DQ<11>")
	)
	(segment
		(start 418.122608 -292.960044)
		(end 418.963348 -293.800784)
		(width 0.14478)
		(layer "In6.Cu")
		(net "M_K_CPU0_SB_DQ<11>")
	)
	(segment
		(start 414.986724 -292.67531)
		(end 415.258504 -292.67531)
		(width 0.14478)
		(layer "In6.Cu")
		(net "M_K_CPU0_SB_DQ<11>")
	)
	(segment
		(start 392.24712 -280.24963)
		(end 392.257534 -280.243534)
		(width 0.0889)
		(layer "In6.Cu")
		(net "M_K_CPU0_SB_DQ<11>")
	)
	(segment
		(start 428.57293 -293.51351)
		(end 428.69739 -293.63797)
		(width 0.14478)
		(layer "In6.Cu")
		(net "M_K_CPU0_SB_DQ<11>")
	)
	(segment
		(start 423.225468 -292.64991)
		(end 423.526204 -292.950646)
		(width 0.14478)
		(layer "In6.Cu")
		(net "M_K_CPU0_SB_DQ<11>")
	)
	(segment
		(start 389.4709 -280.300684)
		(end 389.493252 -280.217372)
		(width 0.0889)
		(layer "In6.Cu")
		(net "M_K_CPU0_SB_DQ<11>")
	)
	(segment
		(start 441.2488 -293.305992)
		(end 441.39358 -293.161212)
		(width 0.14478)
		(layer "In6.Cu")
		(net "M_K_CPU0_SB_DQ<11>")
	)
	(segment
		(start 420.51097 -293.800784)
		(end 420.772844 -293.53891)
		(width 0.14478)
		(layer "In6.Cu")
		(net "M_K_CPU0_SB_DQ<11>")
	)
	(segment
		(start 392.257534 -280.243534)
		(end 392.265916 -280.238708)
		(width 0.0889)
		(layer "In6.Cu")
		(net "M_K_CPU0_SB_DQ<11>")
	)
	(segment
		(start 415.939478 -293.09187)
		(end 415.939478 -293.092124)
		(width 0.14478)
		(layer "In6.Cu")
		(net "M_K_CPU0_SB_DQ<11>")
	)
	(segment
		(start 430.536096 -292.70071)
		(end 430.833276 -292.70071)
		(width 0.14478)
		(layer "In6.Cu")
		(net "M_K_CPU0_SB_DQ<11>")
	)
	(segment
		(start 439.853578 -292.577012)
		(end 440.697366 -292.577012)
		(width 0.14478)
		(layer "In6.Cu")
		(net "M_K_CPU0_SB_DQ<11>")
	)
	(segment
		(start 393.197334 -280.243534)
		(end 393.25931 -280.207466)
		(width 0.0889)
		(layer "In6.Cu")
		(net "M_K_CPU0_SB_DQ<11>")
	)
	(segment
		(start 422.45788 -292.960044)
		(end 422.668954 -292.960044)
		(width 0.14478)
		(layer "In6.Cu")
		(net "M_K_CPU0_SB_DQ<11>")
	)
	(segment
		(start 423.526204 -292.950646)
		(end 424.443906 -292.950646)
		(width 0.14478)
		(layer "In6.Cu")
		(net "M_K_CPU0_SB_DQ<11>")
	)
	(segment
		(start 415.807652 -292.960044)
		(end 415.939478 -293.09187)
		(width 0.14478)
		(layer "In6.Cu")
		(net "M_K_CPU0_SB_DQ<11>")
	)
	(segment
		(start 425.186602 -292.87089)
		(end 425.577508 -292.87089)
		(width 0.14478)
		(layer "In6.Cu")
		(net "M_K_CPU0_SB_DQ<11>")
	)
	(segment
		(start 391.317734 -280.243534)
		(end 391.326116 -280.238708)
		(width 0.0889)
		(layer "In6.Cu")
		(net "M_K_CPU0_SB_DQ<11>")
	)
	(segment
		(start 440.697366 -292.577012)
		(end 440.842146 -292.721792)
		(width 0.14478)
		(layer "In6.Cu")
		(net "M_K_CPU0_SB_DQ<11>")
	)
	(segment
		(start 417.740846 -292.960044)
		(end 418.122608 -292.960044)
		(width 0.14478)
		(layer "In6.Cu")
		(net "M_K_CPU0_SB_DQ<11>")
	)
	(segment
		(start 437.833516 -292.64991)
		(end 438.079896 -292.64991)
		(width 0.14478)
		(layer "In6.Cu")
		(net "M_K_CPU0_SB_DQ<11>")
	)
	(segment
		(start 425.577508 -292.87089)
		(end 426.507402 -293.800784)
		(width 0.14478)
		(layer "In6.Cu")
		(net "M_K_CPU0_SB_DQ<11>")
	)
	(segment
		(start 436.298848 -293.80053)
		(end 437.139334 -292.960044)
		(width 0.14478)
		(layer "In6.Cu")
		(net "M_K_CPU0_SB_DQ<11>")
	)
	(segment
		(start 398.785588 -280.2001)
		(end 412.39567 -293.810182)
		(width 0.14478)
		(layer "In6.Cu")
		(net "M_K_CPU0_SB_DQ<11>")
	)
	(segment
		(start 430.276762 -292.960044)
		(end 430.536096 -292.70071)
		(width 0.14478)
		(layer "In6.Cu")
		(net "M_K_CPU0_SB_DQ<11>")
	)
	(arc
		(start 392.641582 -280.24963)
		(mid 392.920268 -280.31985)
		(end 393.197334 -280.243534)
		(width 0.0889)
		(layer "In6.Cu")
		(net "M_K_CPU0_SB_DQ<11>")
	)
	(arc
		(start 390.751822 -280.243534)
		(mid 391.034778 -280.319711)
		(end 391.317734 -280.243534)
		(width 0.0889)
		(layer "In6.Cu")
		(net "M_K_CPU0_SB_DQ<11>")
	)
	(arc
		(start 391.326116 -280.238708)
		(mid 391.509624 -280.193214)
		(end 391.691876 -280.243534)
		(width 0.0889)
		(layer "In6.Cu")
		(net "M_K_CPU0_SB_DQ<11>")
	)
	(arc
		(start 389.493252 -280.217372)
		(mid 389.655441 -280.194637)
		(end 389.811768 -280.243534)
		(width 0.0889)
		(layer "In6.Cu")
		(net "M_K_CPU0_SB_DQ<11>")
	)
	(arc
		(start 392.265916 -280.238708)
		(mid 392.44917 -280.193335)
		(end 392.631168 -280.243534)
		(width 0.0889)
		(layer "In6.Cu")
		(net "M_K_CPU0_SB_DQ<11>")
	)
	(arc
		(start 390.37768 -280.243534)
		(mid 390.559931 -280.193184)
		(end 390.74344 -280.238708)
		(width 0.0889)
		(layer "In6.Cu")
		(net "M_K_CPU0_SB_DQ<11>")
	)
	(arc
		(start 391.691876 -280.243534)
		(mid 391.968689 -280.319677)
		(end 392.24712 -280.24963)
		(width 0.0889)
		(layer "In6.Cu")
		(net "M_K_CPU0_SB_DQ<11>")
	)
	(arc
		(start 389.811768 -280.243534)
		(mid 390.094724 -280.319711)
		(end 390.37768 -280.243534)
		(width 0.0889)
		(layer "In6.Cu")
		(net "M_K_CPU0_SB_DQ<11>")
	)
	(arc
		(start 393.25931 -280.207466)
		(mid 393.272533 -280.201933)
		(end 393.286742 -280.2001)
		(width 0.0889)
		(layer "In6.Cu")
		(net "M_K_CPU0_SB_DQ<11>")
	)
	(segment
		(start 390.567926 -279.49017)
		(end 391.034778 -279.756108)
		(width 0.10668)
		(layer "F.Cu")
		(net "M_K_CPU0_SB_DQ<10>")
	)
	(segment
		(start 417.860226 -291.260022)
		(end 418.122608 -291.260022)
		(width 0.14478)
		(layer "In6.Cu")
		(net "M_K_CPU0_SB_DQ<10>")
	)
	(segment
		(start 441.936886 -291.260022)
		(end 442.119258 -291.260022)
		(width 0.14478)
		(layer "In6.Cu")
		(net "M_K_CPU0_SB_DQ<10>")
	)
	(segment
		(start 417.0172 -291.260022)
		(end 417.303712 -290.97351)
		(width 0.14478)
		(layer "In6.Cu")
		(net "M_K_CPU0_SB_DQ<10>")
	)
	(segment
		(start 440.511946 -290.94811)
		(end 440.823858 -291.260022)
		(width 0.14478)
		(layer "In6.Cu")
		(net "M_K_CPU0_SB_DQ<10>")
	)
	(segment
		(start 410.194252 -289.895788)
		(end 410.387292 -290.088828)
		(width 0.14478)
		(layer "In6.Cu")
		(net "M_K_CPU0_SB_DQ<10>")
	)
	(segment
		(start 395.8717 -279.065736)
		(end 399.3642 -279.065736)
		(width 0.14478)
		(layer "In6.Cu")
		(net "M_K_CPU0_SB_DQ<10>")
	)
	(segment
		(start 441.380372 -290.94811)
		(end 441.624974 -290.94811)
		(width 0.14478)
		(layer "In6.Cu")
		(net "M_K_CPU0_SB_DQ<10>")
	)
	(segment
		(start 432.79441 -291.260022)
		(end 433.210716 -291.260022)
		(width 0.14478)
		(layer "In6.Cu")
		(net "M_K_CPU0_SB_DQ<10>")
	)
	(segment
		(start 417.303712 -290.97351)
		(end 417.573714 -290.97351)
		(width 0.14478)
		(layer "In6.Cu")
		(net "M_K_CPU0_SB_DQ<10>")
	)
	(segment
		(start 391.034778 -279.756108)
		(end 390.880854 -279.490678)
		(width 0.0889)
		(layer "In6.Cu")
		(net "M_K_CPU0_SB_DQ<10>")
	)
	(segment
		(start 418.972746 -292.11016)
		(end 421.57015 -292.11016)
		(width 0.14478)
		(layer "In6.Cu")
		(net "M_K_CPU0_SB_DQ<10>")
	)
	(segment
		(start 392.153394 -279.428702)
		(end 392.161776 -279.433528)
		(width 0.0889)
		(layer "In6.Cu")
		(net "M_K_CPU0_SB_DQ<10>")
	)
	(segment
		(start 433.210716 -291.260022)
		(end 434.0606 -292.109906)
		(width 0.14478)
		(layer "In6.Cu")
		(net "M_K_CPU0_SB_DQ<10>")
	)
	(segment
		(start 403.300692 -283.002228)
		(end 403.300692 -283.403548)
		(width 0.14478)
		(layer "In6.Cu")
		(net "M_K_CPU0_SB_DQ<10>")
	)
	(segment
		(start 400.938492 -281.041348)
		(end 401.131532 -281.234388)
		(width 0.14478)
		(layer "In6.Cu")
		(net "M_K_CPU0_SB_DQ<10>")
	)
	(segment
		(start 426.5168 -292.11016)
		(end 429.178212 -292.11016)
		(width 0.14478)
		(layer "In6.Cu")
		(net "M_K_CPU0_SB_DQ<10>")
	)
	(segment
		(start 403.493732 -283.596588)
		(end 403.895052 -283.596588)
		(width 0.14478)
		(layer "In6.Cu")
		(net "M_K_CPU0_SB_DQ<10>")
	)
	(segment
		(start 429.178212 -292.11016)
		(end 430.02835 -291.260022)
		(width 0.14478)
		(layer "In6.Cu")
		(net "M_K_CPU0_SB_DQ<10>")
	)
	(segment
		(start 409.406852 -289.108388)
		(end 409.599892 -289.301428)
		(width 0.14478)
		(layer "In6.Cu")
		(net "M_K_CPU0_SB_DQ<10>")
	)
	(segment
		(start 430.02835 -291.260022)
		(end 431.953416 -291.260022)
		(width 0.14478)
		(layer "In6.Cu")
		(net "M_K_CPU0_SB_DQ<10>")
	)
	(segment
		(start 425.666662 -291.260022)
		(end 426.5168 -292.11016)
		(width 0.14478)
		(layer "In6.Cu")
		(net "M_K_CPU0_SB_DQ<10>")
	)
	(segment
		(start 400.151092 -280.253948)
		(end 400.344132 -280.446988)
		(width 0.14478)
		(layer "In6.Cu")
		(net "M_K_CPU0_SB_DQ<10>")
	)
	(segment
		(start 415.077656 -290.97351)
		(end 415.347658 -290.97351)
		(width 0.14478)
		(layer "In6.Cu")
		(net "M_K_CPU0_SB_DQ<10>")
	)
	(segment
		(start 440.823858 -291.260022)
		(end 441.06846 -291.260022)
		(width 0.14478)
		(layer "In6.Cu")
		(net "M_K_CPU0_SB_DQ<10>")
	)
	(segment
		(start 407.832052 -287.533588)
		(end 408.025092 -287.726628)
		(width 0.14478)
		(layer "In6.Cu")
		(net "M_K_CPU0_SB_DQ<10>")
	)
	(segment
		(start 402.513292 -282.616148)
		(end 402.706332 -282.809188)
		(width 0.14478)
		(layer "In6.Cu")
		(net "M_K_CPU0_SB_DQ<10>")
	)
	(segment
		(start 407.430732 -287.533588)
		(end 407.832052 -287.533588)
		(width 0.14478)
		(layer "In6.Cu")
		(net "M_K_CPU0_SB_DQ<10>")
	)
	(segment
		(start 414.791144 -291.260022)
		(end 415.077656 -290.97351)
		(width 0.14478)
		(layer "In6.Cu")
		(net "M_K_CPU0_SB_DQ<10>")
	)
	(segment
		(start 432.098196 -291.017452)
		(end 432.242976 -290.872672)
		(width 0.14478)
		(layer "In6.Cu")
		(net "M_K_CPU0_SB_DQ<10>")
	)
	(segment
		(start 410.764228 -290.683188)
		(end 412.1912 -292.11016)
		(width 0.14478)
		(layer "In6.Cu")
		(net "M_K_CPU0_SB_DQ<10>")
	)
	(segment
		(start 401.532852 -281.234388)
		(end 401.725892 -281.427428)
		(width 0.14478)
		(layer "In6.Cu")
		(net "M_K_CPU0_SB_DQ<10>")
	)
	(segment
		(start 409.005532 -289.108388)
		(end 409.406852 -289.108388)
		(width 0.14478)
		(layer "In6.Cu")
		(net "M_K_CPU0_SB_DQ<10>")
	)
	(segment
		(start 408.025092 -287.726628)
		(end 408.025092 -288.127948)
		(width 0.14478)
		(layer "In6.Cu")
		(net "M_K_CPU0_SB_DQ<10>")
	)
	(segment
		(start 416.190684 -290.97351)
		(end 416.460686 -290.97351)
		(width 0.14478)
		(layer "In6.Cu")
		(net "M_K_CPU0_SB_DQ<10>")
	)
	(segment
		(start 400.745452 -280.446988)
		(end 400.938492 -280.640028)
		(width 0.14478)
		(layer "In6.Cu")
		(net "M_K_CPU0_SB_DQ<10>")
	)
	(segment
		(start 432.50485 -290.872672)
		(end 432.64963 -291.017452)
		(width 0.14478)
		(layer "In6.Cu")
		(net "M_K_CPU0_SB_DQ<10>")
	)
	(segment
		(start 437.966866 -290.97351)
		(end 438.236868 -290.97351)
		(width 0.14478)
		(layer "In6.Cu")
		(net "M_K_CPU0_SB_DQ<10>")
	)
	(segment
		(start 400.344132 -280.446988)
		(end 400.745452 -280.446988)
		(width 0.14478)
		(layer "In6.Cu")
		(net "M_K_CPU0_SB_DQ<10>")
	)
	(segment
		(start 412.1912 -292.11016)
		(end 413.646366 -292.11016)
		(width 0.14478)
		(layer "In6.Cu")
		(net "M_K_CPU0_SB_DQ<10>")
	)
	(segment
		(start 439.955432 -291.260022)
		(end 440.267344 -290.94811)
		(width 0.14478)
		(layer "In6.Cu")
		(net "M_K_CPU0_SB_DQ<10>")
	)
	(segment
		(start 392.727434 -279.433528)
		(end 392.735816 -279.428702)
		(width 0.0889)
		(layer "In6.Cu")
		(net "M_K_CPU0_SB_DQ<10>")
	)
	(segment
		(start 401.918932 -282.021788)
		(end 402.320252 -282.021788)
		(width 0.14478)
		(layer "In6.Cu")
		(net "M_K_CPU0_SB_DQ<10>")
	)
	(segment
		(start 406.450292 -286.151828)
		(end 406.450292 -286.553148)
		(width 0.14478)
		(layer "In6.Cu")
		(net "M_K_CPU0_SB_DQ<10>")
	)
	(segment
		(start 394.333222 -278.91359)
		(end 395.226794 -278.91359)
		(width 0.0889)
		(layer "In6.Cu")
		(net "M_K_CPU0_SB_DQ<10>")
	)
	(segment
		(start 401.725892 -281.828748)
		(end 401.918932 -282.021788)
		(width 0.14478)
		(layer "In6.Cu")
		(net "M_K_CPU0_SB_DQ<10>")
	)
	(segment
		(start 402.513292 -282.214828)
		(end 402.513292 -282.616148)
		(width 0.14478)
		(layer "In6.Cu")
		(net "M_K_CPU0_SB_DQ<10>")
	)
	(segment
		(start 405.855932 -285.958788)
		(end 406.257252 -285.958788)
		(width 0.14478)
		(layer "In6.Cu")
		(net "M_K_CPU0_SB_DQ<10>")
	)
	(segment
		(start 403.107652 -282.809188)
		(end 403.300692 -283.002228)
		(width 0.14478)
		(layer "In6.Cu")
		(net "M_K_CPU0_SB_DQ<10>")
	)
	(segment
		(start 408.619452 -288.320988)
		(end 408.812492 -288.514028)
		(width 0.14478)
		(layer "In6.Cu")
		(net "M_K_CPU0_SB_DQ<10>")
	)
	(segment
		(start 436.285132 -292.109906)
		(end 437.135016 -291.260022)
		(width 0.14478)
		(layer "In6.Cu")
		(net "M_K_CPU0_SB_DQ<10>")
	)
	(segment
		(start 395.226794 -278.91359)
		(end 395.37894 -279.065736)
		(width 0.0889)
		(layer "In6.Cu")
		(net "M_K_CPU0_SB_DQ<10>")
	)
	(segment
		(start 441.06846 -291.260022)
		(end 441.380372 -290.94811)
		(width 0.14478)
		(layer "In6.Cu")
		(net "M_K_CPU0_SB_DQ<10>")
	)
	(segment
		(start 404.088092 -284.190948)
		(end 404.281132 -284.383988)
		(width 0.14478)
		(layer "In6.Cu")
		(net "M_K_CPU0_SB_DQ<10>")
	)
	(segment
		(start 400.151092 -279.852628)
		(end 400.151092 -280.253948)
		(width 0.14478)
		(layer "In6.Cu")
		(net "M_K_CPU0_SB_DQ<10>")
	)
	(segment
		(start 399.3642 -279.065736)
		(end 400.151092 -279.852628)
		(width 0.14478)
		(layer "In6.Cu")
		(net "M_K_CPU0_SB_DQ<10>")
	)
	(segment
		(start 409.599892 -289.301428)
		(end 409.599892 -289.702748)
		(width 0.14478)
		(layer "In6.Cu")
		(net "M_K_CPU0_SB_DQ<10>")
	)
	(segment
		(start 432.64963 -291.115242)
		(end 432.79441 -291.260022)
		(width 0.14478)
		(layer "In6.Cu")
		(net "M_K_CPU0_SB_DQ<10>")
	)
	(segment
		(start 410.387292 -290.088828)
		(end 410.387292 -290.490148)
		(width 0.14478)
		(layer "In6.Cu")
		(net "M_K_CPU0_SB_DQ<10>")
	)
	(segment
		(start 407.237692 -286.939228)
		(end 407.237692 -287.340548)
		(width 0.14478)
		(layer "In6.Cu")
		(net "M_K_CPU0_SB_DQ<10>")
	)
	(segment
		(start 437.135016 -291.260022)
		(end 437.680354 -291.260022)
		(width 0.14478)
		(layer "In6.Cu")
		(net "M_K_CPU0_SB_DQ<10>")
	)
	(segment
		(start 401.131532 -281.234388)
		(end 401.532852 -281.234388)
		(width 0.14478)
		(layer "In6.Cu")
		(net "M_K_CPU0_SB_DQ<10>")
	)
	(segment
		(start 413.646366 -292.11016)
		(end 414.496504 -291.260022)
		(width 0.14478)
		(layer "In6.Cu")
		(net "M_K_CPU0_SB_DQ<10>")
	)
	(segment
		(start 440.267344 -290.94811)
		(end 440.511946 -290.94811)
		(width 0.14478)
		(layer "In6.Cu")
		(net "M_K_CPU0_SB_DQ<10>")
	)
	(segment
		(start 405.662892 -285.765748)
		(end 405.855932 -285.958788)
		(width 0.14478)
		(layer "In6.Cu")
		(net "M_K_CPU0_SB_DQ<10>")
	)
	(segment
		(start 410.387292 -290.490148)
		(end 410.580332 -290.683188)
		(width 0.14478)
		(layer "In6.Cu")
		(net "M_K_CPU0_SB_DQ<10>")
	)
	(segment
		(start 434.0606 -292.109906)
		(end 436.285132 -292.109906)
		(width 0.14478)
		(layer "In6.Cu")
		(net "M_K_CPU0_SB_DQ<10>")
	)
	(segment
		(start 392.161776 -279.433528)
		(end 392.17219 -279.439624)
		(width 0.0889)
		(layer "In6.Cu")
		(net "M_K_CPU0_SB_DQ<10>")
	)
	(segment
		(start 421.57015 -292.11016)
		(end 422.420288 -291.260022)
		(width 0.14478)
		(layer "In6.Cu")
		(net "M_K_CPU0_SB_DQ<10>")
	)
	(segment
		(start 441.624974 -290.94811)
		(end 441.936886 -291.260022)
		(width 0.14478)
		(layer "In6.Cu")
		(net "M_K_CPU0_SB_DQ<10>")
	)
	(segment
		(start 418.122608 -291.260022)
		(end 418.972746 -292.11016)
		(width 0.14478)
		(layer "In6.Cu")
		(net "M_K_CPU0_SB_DQ<10>")
	)
	(segment
		(start 417.573714 -290.97351)
		(end 417.860226 -291.260022)
		(width 0.14478)
		(layer "In6.Cu")
		(net "M_K_CPU0_SB_DQ<10>")
	)
	(segment
		(start 408.812492 -288.915348)
		(end 409.005532 -289.108388)
		(width 0.14478)
		(layer "In6.Cu")
		(net "M_K_CPU0_SB_DQ<10>")
	)
	(segment
		(start 404.088092 -283.789628)
		(end 404.088092 -284.190948)
		(width 0.14478)
		(layer "In6.Cu")
		(net "M_K_CPU0_SB_DQ<10>")
	)
	(segment
		(start 404.281132 -284.383988)
		(end 404.682452 -284.383988)
		(width 0.14478)
		(layer "In6.Cu")
		(net "M_K_CPU0_SB_DQ<10>")
	)
	(segment
		(start 406.257252 -285.958788)
		(end 406.450292 -286.151828)
		(width 0.14478)
		(layer "In6.Cu")
		(net "M_K_CPU0_SB_DQ<10>")
	)
	(segment
		(start 437.680354 -291.260022)
		(end 437.966866 -290.97351)
		(width 0.14478)
		(layer "In6.Cu")
		(net "M_K_CPU0_SB_DQ<10>")
	)
	(segment
		(start 401.725892 -281.427428)
		(end 401.725892 -281.828748)
		(width 0.14478)
		(layer "In6.Cu")
		(net "M_K_CPU0_SB_DQ<10>")
	)
	(segment
		(start 407.044652 -286.746188)
		(end 407.237692 -286.939228)
		(width 0.14478)
		(layer "In6.Cu")
		(net "M_K_CPU0_SB_DQ<10>")
	)
	(segment
		(start 406.450292 -286.553148)
		(end 406.643332 -286.746188)
		(width 0.14478)
		(layer "In6.Cu")
		(net "M_K_CPU0_SB_DQ<10>")
	)
	(segment
		(start 403.300692 -283.403548)
		(end 403.493732 -283.596588)
		(width 0.14478)
		(layer "In6.Cu")
		(net "M_K_CPU0_SB_DQ<10>")
	)
	(segment
		(start 403.895052 -283.596588)
		(end 404.088092 -283.789628)
		(width 0.14478)
		(layer "In6.Cu")
		(net "M_K_CPU0_SB_DQ<10>")
	)
	(segment
		(start 409.599892 -289.702748)
		(end 409.792932 -289.895788)
		(width 0.14478)
		(layer "In6.Cu")
		(net "M_K_CPU0_SB_DQ<10>")
	)
	(segment
		(start 438.236868 -290.97351)
		(end 438.52338 -291.260022)
		(width 0.14478)
		(layer "In6.Cu")
		(net "M_K_CPU0_SB_DQ<10>")
	)
	(segment
		(start 438.52338 -291.260022)
		(end 439.955432 -291.260022)
		(width 0.14478)
		(layer "In6.Cu")
		(net "M_K_CPU0_SB_DQ<10>")
	)
	(segment
		(start 400.938492 -280.640028)
		(end 400.938492 -281.041348)
		(width 0.14478)
		(layer "In6.Cu")
		(net "M_K_CPU0_SB_DQ<10>")
	)
	(segment
		(start 402.320252 -282.021788)
		(end 402.513292 -282.214828)
		(width 0.14478)
		(layer "In6.Cu")
		(net "M_K_CPU0_SB_DQ<10>")
	)
	(segment
		(start 415.904172 -291.260022)
		(end 416.190684 -290.97351)
		(width 0.14478)
		(layer "In6.Cu")
		(net "M_K_CPU0_SB_DQ<10>")
	)
	(segment
		(start 431.953416 -291.260022)
		(end 432.098196 -291.115242)
		(width 0.14478)
		(layer "In6.Cu")
		(net "M_K_CPU0_SB_DQ<10>")
	)
	(segment
		(start 415.63417 -291.260022)
		(end 415.904172 -291.260022)
		(width 0.14478)
		(layer "In6.Cu")
		(net "M_K_CPU0_SB_DQ<10>")
	)
	(segment
		(start 407.237692 -287.340548)
		(end 407.430732 -287.533588)
		(width 0.14478)
		(layer "In6.Cu")
		(net "M_K_CPU0_SB_DQ<10>")
	)
	(segment
		(start 432.242976 -290.872672)
		(end 432.50485 -290.872672)
		(width 0.14478)
		(layer "In6.Cu")
		(net "M_K_CPU0_SB_DQ<10>")
	)
	(segment
		(start 432.64963 -291.017452)
		(end 432.64963 -291.115242)
		(width 0.14478)
		(layer "In6.Cu")
		(net "M_K_CPU0_SB_DQ<10>")
	)
	(segment
		(start 395.37894 -279.065736)
		(end 395.8717 -279.065736)
		(width 0.0889)
		(layer "In6.Cu")
		(net "M_K_CPU0_SB_DQ<10>")
	)
	(segment
		(start 404.875492 -284.978348)
		(end 405.068532 -285.171388)
		(width 0.14478)
		(layer "In6.Cu")
		(net "M_K_CPU0_SB_DQ<10>")
	)
	(segment
		(start 390.880854 -279.490678)
		(end 390.903206 -279.407366)
		(width 0.0889)
		(layer "In6.Cu")
		(net "M_K_CPU0_SB_DQ<10>")
	)
	(segment
		(start 404.682452 -284.383988)
		(end 404.875492 -284.577028)
		(width 0.14478)
		(layer "In6.Cu")
		(net "M_K_CPU0_SB_DQ<10>")
	)
	(segment
		(start 405.469852 -285.171388)
		(end 405.662892 -285.364428)
		(width 0.14478)
		(layer "In6.Cu")
		(net "M_K_CPU0_SB_DQ<10>")
	)
	(segment
		(start 406.643332 -286.746188)
		(end 407.044652 -286.746188)
		(width 0.14478)
		(layer "In6.Cu")
		(net "M_K_CPU0_SB_DQ<10>")
	)
	(segment
		(start 408.218132 -288.320988)
		(end 408.619452 -288.320988)
		(width 0.14478)
		(layer "In6.Cu")
		(net "M_K_CPU0_SB_DQ<10>")
	)
	(segment
		(start 415.347658 -290.97351)
		(end 415.63417 -291.260022)
		(width 0.14478)
		(layer "In6.Cu")
		(net "M_K_CPU0_SB_DQ<10>")
	)
	(segment
		(start 432.098196 -291.115242)
		(end 432.098196 -291.017452)
		(width 0.14478)
		(layer "In6.Cu")
		(net "M_K_CPU0_SB_DQ<10>")
	)
	(segment
		(start 408.025092 -288.127948)
		(end 408.218132 -288.320988)
		(width 0.14478)
		(layer "In6.Cu")
		(net "M_K_CPU0_SB_DQ<10>")
	)
	(segment
		(start 393.852908 -279.34031)
		(end 394.241782 -278.951436)
		(width 0.0889)
		(layer "In6.Cu")
		(net "M_K_CPU0_SB_DQ<10>")
	)
	(segment
		(start 404.875492 -284.577028)
		(end 404.875492 -284.978348)
		(width 0.14478)
		(layer "In6.Cu")
		(net "M_K_CPU0_SB_DQ<10>")
	)
	(segment
		(start 416.747198 -291.260022)
		(end 417.0172 -291.260022)
		(width 0.14478)
		(layer "In6.Cu")
		(net "M_K_CPU0_SB_DQ<10>")
	)
	(segment
		(start 416.460686 -290.97351)
		(end 416.747198 -291.260022)
		(width 0.14478)
		(layer "In6.Cu")
		(net "M_K_CPU0_SB_DQ<10>")
	)
	(segment
		(start 405.662892 -285.364428)
		(end 405.662892 -285.765748)
		(width 0.14478)
		(layer "In6.Cu")
		(net "M_K_CPU0_SB_DQ<10>")
	)
	(segment
		(start 408.812492 -288.514028)
		(end 408.812492 -288.915348)
		(width 0.14478)
		(layer "In6.Cu")
		(net "M_K_CPU0_SB_DQ<10>")
	)
	(segment
		(start 414.496504 -291.260022)
		(end 414.791144 -291.260022)
		(width 0.14478)
		(layer "In6.Cu")
		(net "M_K_CPU0_SB_DQ<10>")
	)
	(segment
		(start 409.792932 -289.895788)
		(end 410.194252 -289.895788)
		(width 0.14478)
		(layer "In6.Cu")
		(net "M_K_CPU0_SB_DQ<10>")
	)
	(segment
		(start 405.068532 -285.171388)
		(end 405.469852 -285.171388)
		(width 0.14478)
		(layer "In6.Cu")
		(net "M_K_CPU0_SB_DQ<10>")
	)
	(segment
		(start 442.119258 -291.260022)
		(end 442.5442 -291.684964)
		(width 0.14478)
		(layer "In6.Cu")
		(net "M_K_CPU0_SB_DQ<10>")
	)
	(segment
		(start 402.706332 -282.809188)
		(end 403.107652 -282.809188)
		(width 0.14478)
		(layer "In6.Cu")
		(net "M_K_CPU0_SB_DQ<10>")
	)
	(segment
		(start 410.580332 -290.683188)
		(end 410.764228 -290.683188)
		(width 0.14478)
		(layer "In6.Cu")
		(net "M_K_CPU0_SB_DQ<10>")
	)
	(segment
		(start 422.420288 -291.260022)
		(end 425.666662 -291.260022)
		(width 0.14478)
		(layer "In6.Cu")
		(net "M_K_CPU0_SB_DQ<10>")
	)
	(arc
		(start 391.787634 -279.433528)
		(mid 391.969885 -279.383178)
		(end 392.153394 -279.428702)
		(width 0.0889)
		(layer "In6.Cu")
		(net "M_K_CPU0_SB_DQ<10>")
	)
	(arc
		(start 392.735816 -279.428702)
		(mid 392.919324 -279.383208)
		(end 393.101576 -279.433528)
		(width 0.0889)
		(layer "In6.Cu")
		(net "M_K_CPU0_SB_DQ<10>")
	)
	(arc
		(start 391.221722 -279.433528)
		(mid 391.504678 -279.509705)
		(end 391.787634 -279.433528)
		(width 0.0889)
		(layer "In6.Cu")
		(net "M_K_CPU0_SB_DQ<10>")
	)
	(arc
		(start 390.903206 -279.407366)
		(mid 391.065395 -279.384631)
		(end 391.221722 -279.433528)
		(width 0.0889)
		(layer "In6.Cu")
		(net "M_K_CPU0_SB_DQ<10>")
	)
	(arc
		(start 393.101576 -279.433528)
		(mid 393.49291 -279.513307)
		(end 393.852908 -279.34031)
		(width 0.0889)
		(layer "In6.Cu")
		(net "M_K_CPU0_SB_DQ<10>")
	)
	(arc
		(start 392.17219 -279.439624)
		(mid 392.450622 -279.509722)
		(end 392.727434 -279.433528)
		(width 0.0889)
		(layer "In6.Cu")
		(net "M_K_CPU0_SB_DQ<10>")
	)
	(arc
		(start 394.241782 -278.951436)
		(mid 394.283735 -278.923404)
		(end 394.333222 -278.91359)
		(width 0.0889)
		(layer "In6.Cu")
		(net "M_K_CPU0_SB_DQ<10>")
	)
	(segment
		(start 390.098026 -273.820128)
		(end 390.564878 -274.086066)
		(width 0.10668)
		(layer "F.Cu")
		(net "M_K_CPU0_SB_DQ<0>")
	)
	(segment
		(start 422.002966 -281.060144)
		(end 425.951142 -281.060144)
		(width 0.14478)
		(layer "In6.Cu")
		(net "M_K_CPU0_SB_DQ<0>")
	)
	(segment
		(start 436.131716 -281.910028)
		(end 436.9816 -281.060144)
		(width 0.14478)
		(layer "In6.Cu")
		(net "M_K_CPU0_SB_DQ<0>")
	)
	(segment
		(start 444.720218 -281.830272)
		(end 444.982092 -281.830272)
		(width 0.14478)
		(layer "In6.Cu")
		(net "M_K_CPU0_SB_DQ<0>")
	)
	(segment
		(start 395.114018 -273.39417)
		(end 395.568678 -272.93951)
		(width 0.0889)
		(layer "In6.Cu")
		(net "M_K_CPU0_SB_DQ<0>")
	)
	(segment
		(start 445.126872 -281.204924)
		(end 445.271652 -281.060144)
		(width 0.14478)
		(layer "In6.Cu")
		(net "M_K_CPU0_SB_DQ<0>")
	)
	(segment
		(start 415.032952 -281.060144)
		(end 418.508688 -281.060144)
		(width 0.14478)
		(layer "In6.Cu")
		(net "M_K_CPU0_SB_DQ<0>")
	)
	(segment
		(start 444.430658 -281.060144)
		(end 444.575438 -281.204924)
		(width 0.14478)
		(layer "In6.Cu")
		(net "M_K_CPU0_SB_DQ<0>")
	)
	(segment
		(start 402.6408 -272.93951)
		(end 411.611318 -281.910028)
		(width 0.14478)
		(layer "In6.Cu")
		(net "M_K_CPU0_SB_DQ<0>")
	)
	(segment
		(start 395.568678 -272.93951)
		(end 395.977364 -272.93951)
		(width 0.0889)
		(layer "In6.Cu")
		(net "M_K_CPU0_SB_DQ<0>")
	)
	(segment
		(start 436.9816 -281.060144)
		(end 444.430658 -281.060144)
		(width 0.14478)
		(layer "In6.Cu")
		(net "M_K_CPU0_SB_DQ<0>")
	)
	(segment
		(start 425.951142 -281.060144)
		(end 426.801026 -281.910028)
		(width 0.14478)
		(layer "In6.Cu")
		(net "M_K_CPU0_SB_DQ<0>")
	)
	(segment
		(start 418.508688 -281.060144)
		(end 419.358572 -281.910028)
		(width 0.14478)
		(layer "In6.Cu")
		(net "M_K_CPU0_SB_DQ<0>")
	)
	(segment
		(start 426.801026 -281.910028)
		(end 429.271176 -281.910028)
		(width 0.14478)
		(layer "In6.Cu")
		(net "M_K_CPU0_SB_DQ<0>")
	)
	(segment
		(start 445.126872 -281.685492)
		(end 445.126872 -281.204924)
		(width 0.14478)
		(layer "In6.Cu")
		(net "M_K_CPU0_SB_DQ<0>")
	)
	(segment
		(start 445.271652 -281.060144)
		(end 446.219326 -281.060144)
		(width 0.14478)
		(layer "In6.Cu")
		(net "M_K_CPU0_SB_DQ<0>")
	)
	(segment
		(start 430.12106 -281.060144)
		(end 433.145692 -281.060144)
		(width 0.14478)
		(layer "In6.Cu")
		(net "M_K_CPU0_SB_DQ<0>")
	)
	(segment
		(start 444.575438 -281.685492)
		(end 444.720218 -281.830272)
		(width 0.14478)
		(layer "In6.Cu")
		(net "M_K_CPU0_SB_DQ<0>")
	)
	(segment
		(start 446.219326 -281.060144)
		(end 446.644268 -281.485086)
		(width 0.14478)
		(layer "In6.Cu")
		(net "M_K_CPU0_SB_DQ<0>")
	)
	(segment
		(start 433.145692 -281.060144)
		(end 433.995576 -281.910028)
		(width 0.14478)
		(layer "In6.Cu")
		(net "M_K_CPU0_SB_DQ<0>")
	)
	(segment
		(start 419.358572 -281.910028)
		(end 421.153082 -281.910028)
		(width 0.14478)
		(layer "In6.Cu")
		(net "M_K_CPU0_SB_DQ<0>")
	)
	(segment
		(start 395.977364 -272.93951)
		(end 402.6408 -272.93951)
		(width 0.14478)
		(layer "In6.Cu")
		(net "M_K_CPU0_SB_DQ<0>")
	)
	(segment
		(start 390.718802 -274.351496)
		(end 390.814814 -274.376896)
		(width 0.0889)
		(layer "In6.Cu")
		(net "M_K_CPU0_SB_DQ<0>")
	)
	(segment
		(start 429.271176 -281.910028)
		(end 430.12106 -281.060144)
		(width 0.14478)
		(layer "In6.Cu")
		(net "M_K_CPU0_SB_DQ<0>")
	)
	(segment
		(start 392.24712 -274.40255)
		(end 392.257534 -274.408646)
		(width 0.0889)
		(layer "In6.Cu")
		(net "M_K_CPU0_SB_DQ<0>")
	)
	(segment
		(start 393.559792 -274.415504)
		(end 394.54582 -273.432016)
		(width 0.0889)
		(layer "In6.Cu")
		(net "M_K_CPU0_SB_DQ<0>")
	)
	(segment
		(start 444.575438 -281.204924)
		(end 444.575438 -281.685492)
		(width 0.14478)
		(layer "In6.Cu")
		(net "M_K_CPU0_SB_DQ<0>")
	)
	(segment
		(start 433.995576 -281.910028)
		(end 436.131716 -281.910028)
		(width 0.14478)
		(layer "In6.Cu")
		(net "M_K_CPU0_SB_DQ<0>")
	)
	(segment
		(start 391.317734 -274.408646)
		(end 391.326116 -274.413472)
		(width 0.0889)
		(layer "In6.Cu")
		(net "M_K_CPU0_SB_DQ<0>")
	)
	(segment
		(start 421.153082 -281.910028)
		(end 422.002966 -281.060144)
		(width 0.14478)
		(layer "In6.Cu")
		(net "M_K_CPU0_SB_DQ<0>")
	)
	(segment
		(start 390.564878 -274.086066)
		(end 390.718802 -274.351496)
		(width 0.0889)
		(layer "In6.Cu")
		(net "M_K_CPU0_SB_DQ<0>")
	)
	(segment
		(start 414.183068 -281.910028)
		(end 415.032952 -281.060144)
		(width 0.14478)
		(layer "In6.Cu")
		(net "M_K_CPU0_SB_DQ<0>")
	)
	(segment
		(start 394.63726 -273.39417)
		(end 395.114018 -273.39417)
		(width 0.0889)
		(layer "In6.Cu")
		(net "M_K_CPU0_SB_DQ<0>")
	)
	(segment
		(start 392.631422 -274.408646)
		(end 392.641836 -274.40255)
		(width 0.0889)
		(layer "In6.Cu")
		(net "M_K_CPU0_SB_DQ<0>")
	)
	(segment
		(start 411.611318 -281.910028)
		(end 414.183068 -281.910028)
		(width 0.14478)
		(layer "In6.Cu")
		(net "M_K_CPU0_SB_DQ<0>")
	)
	(segment
		(start 444.982092 -281.830272)
		(end 445.126872 -281.685492)
		(width 0.14478)
		(layer "In6.Cu")
		(net "M_K_CPU0_SB_DQ<0>")
	)
	(arc
		(start 392.257534 -274.408646)
		(mid 392.444478 -274.458901)
		(end 392.631422 -274.408646)
		(width 0.0889)
		(layer "In6.Cu")
		(net "M_K_CPU0_SB_DQ<0>")
	)
	(arc
		(start 394.54582 -273.432016)
		(mid 394.587773 -273.403984)
		(end 394.63726 -273.39417)
		(width 0.0889)
		(layer "In6.Cu")
		(net "M_K_CPU0_SB_DQ<0>")
	)
	(arc
		(start 391.326116 -274.413472)
		(mid 391.509624 -274.458966)
		(end 391.691876 -274.408646)
		(width 0.0889)
		(layer "In6.Cu")
		(net "M_K_CPU0_SB_DQ<0>")
	)
	(arc
		(start 393.197588 -274.408646)
		(mid 393.377793 -274.458963)
		(end 393.559792 -274.415504)
		(width 0.0889)
		(layer "In6.Cu")
		(net "M_K_CPU0_SB_DQ<0>")
	)
	(arc
		(start 391.691876 -274.408646)
		(mid 391.968689 -274.332503)
		(end 392.24712 -274.40255)
		(width 0.0889)
		(layer "In6.Cu")
		(net "M_K_CPU0_SB_DQ<0>")
	)
	(arc
		(start 392.641836 -274.40255)
		(mid 392.920522 -274.33233)
		(end 393.197588 -274.408646)
		(width 0.0889)
		(layer "In6.Cu")
		(net "M_K_CPU0_SB_DQ<0>")
	)
	(arc
		(start 390.814814 -274.376896)
		(mid 391.070022 -274.333419)
		(end 391.317734 -274.408646)
		(width 0.0889)
		(layer "In6.Cu")
		(net "M_K_CPU0_SB_DQ<0>")
	)
	(segment
		(start 390.567926 -266.530074)
		(end 391.034778 -266.796012)
		(width 0.10668)
		(layer "F.Cu")
		(net "M_K_CPU0_SB_CS_N<1>")
	)
	(segment
		(start 421.634158 -269.160244)
		(end 422.484296 -268.310106)
		(width 0.14478)
		(layer "In6.Cu")
		(net "M_K_CPU0_SB_CS_N<1>")
	)
	(segment
		(start 436.276242 -268.08557)
		(end 436.43931 -267.922502)
		(width 0.14478)
		(layer "In6.Cu")
		(net "M_K_CPU0_SB_CS_N<1>")
	)
	(segment
		(start 435.55666 -268.310106)
		(end 435.719728 -268.473174)
		(width 0.14478)
		(layer "In6.Cu")
		(net "M_K_CPU0_SB_CS_N<1>")
	)
	(segment
		(start 436.669688 -267.922502)
		(end 436.832756 -268.08557)
		(width 0.14478)
		(layer "In6.Cu")
		(net "M_K_CPU0_SB_CS_N<1>")
	)
	(segment
		(start 392.153394 -266.468606)
		(end 392.161776 -266.473432)
		(width 0.0889)
		(layer "In6.Cu")
		(net "M_K_CPU0_SB_CS_N<1>")
	)
	(segment
		(start 394.32992 -265.550904)
		(end 395.661388 -265.550904)
		(width 0.0889)
		(layer "In6.Cu")
		(net "M_K_CPU0_SB_CS_N<1>")
	)
	(segment
		(start 436.995824 -268.69771)
		(end 437.226202 -268.69771)
		(width 0.14478)
		(layer "In6.Cu")
		(net "M_K_CPU0_SB_CS_N<1>")
	)
	(segment
		(start 429.178212 -269.160244)
		(end 430.02835 -268.310106)
		(width 0.14478)
		(layer "In6.Cu")
		(net "M_K_CPU0_SB_CS_N<1>")
	)
	(segment
		(start 437.226202 -268.69771)
		(end 437.38927 -268.534642)
		(width 0.14478)
		(layer "In6.Cu")
		(net "M_K_CPU0_SB_CS_N<1>")
	)
	(segment
		(start 395.813534 -265.70305)
		(end 408.43454 -265.70305)
		(width 0.14478)
		(layer "In6.Cu")
		(net "M_K_CPU0_SB_CS_N<1>")
	)
	(segment
		(start 438.665366 -268.310106)
		(end 442.119258 -268.310106)
		(width 0.14478)
		(layer "In6.Cu")
		(net "M_K_CPU0_SB_CS_N<1>")
	)
	(segment
		(start 435.719728 -268.534642)
		(end 435.882796 -268.69771)
		(width 0.14478)
		(layer "In6.Cu")
		(net "M_K_CPU0_SB_CS_N<1>")
	)
	(segment
		(start 437.552338 -267.922502)
		(end 437.782716 -267.922502)
		(width 0.14478)
		(layer "In6.Cu")
		(net "M_K_CPU0_SB_CS_N<1>")
	)
	(segment
		(start 436.43931 -267.922502)
		(end 436.669688 -267.922502)
		(width 0.14478)
		(layer "In6.Cu")
		(net "M_K_CPU0_SB_CS_N<1>")
	)
	(segment
		(start 438.33923 -268.69771)
		(end 438.502298 -268.534642)
		(width 0.14478)
		(layer "In6.Cu")
		(net "M_K_CPU0_SB_CS_N<1>")
	)
	(segment
		(start 430.02835 -268.310106)
		(end 435.55666 -268.310106)
		(width 0.14478)
		(layer "In6.Cu")
		(net "M_K_CPU0_SB_CS_N<1>")
	)
	(segment
		(start 437.38927 -268.534642)
		(end 437.38927 -268.08557)
		(width 0.14478)
		(layer "In6.Cu")
		(net "M_K_CPU0_SB_CS_N<1>")
	)
	(segment
		(start 393.101576 -266.473432)
		(end 393.407392 -266.473432)
		(width 0.0889)
		(layer "In6.Cu")
		(net "M_K_CPU0_SB_CS_N<1>")
	)
	(segment
		(start 437.782716 -267.922502)
		(end 437.945784 -268.08557)
		(width 0.14478)
		(layer "In6.Cu")
		(net "M_K_CPU0_SB_CS_N<1>")
	)
	(segment
		(start 426.30725 -268.310106)
		(end 427.157388 -269.160244)
		(width 0.14478)
		(layer "In6.Cu")
		(net "M_K_CPU0_SB_CS_N<1>")
	)
	(segment
		(start 436.832756 -268.534642)
		(end 436.995824 -268.69771)
		(width 0.14478)
		(layer "In6.Cu")
		(net "M_K_CPU0_SB_CS_N<1>")
	)
	(segment
		(start 418.789104 -268.310106)
		(end 419.639242 -269.160244)
		(width 0.14478)
		(layer "In6.Cu")
		(net "M_K_CPU0_SB_CS_N<1>")
	)
	(segment
		(start 437.945784 -268.08557)
		(end 437.945784 -268.534642)
		(width 0.14478)
		(layer "In6.Cu")
		(net "M_K_CPU0_SB_CS_N<1>")
	)
	(segment
		(start 413.12592 -269.160244)
		(end 413.976058 -268.310106)
		(width 0.14478)
		(layer "In6.Cu")
		(net "M_K_CPU0_SB_CS_N<1>")
	)
	(segment
		(start 438.502298 -268.473174)
		(end 438.665366 -268.310106)
		(width 0.14478)
		(layer "In6.Cu")
		(net "M_K_CPU0_SB_CS_N<1>")
	)
	(segment
		(start 435.882796 -268.69771)
		(end 436.113174 -268.69771)
		(width 0.14478)
		(layer "In6.Cu")
		(net "M_K_CPU0_SB_CS_N<1>")
	)
	(segment
		(start 436.113174 -268.69771)
		(end 436.276242 -268.534642)
		(width 0.14478)
		(layer "In6.Cu")
		(net "M_K_CPU0_SB_CS_N<1>")
	)
	(segment
		(start 419.639242 -269.160244)
		(end 421.634158 -269.160244)
		(width 0.14478)
		(layer "In6.Cu")
		(net "M_K_CPU0_SB_CS_N<1>")
	)
	(segment
		(start 391.034778 -266.796012)
		(end 390.880854 -266.530582)
		(width 0.0889)
		(layer "In6.Cu")
		(net "M_K_CPU0_SB_CS_N<1>")
	)
	(segment
		(start 427.157388 -269.160244)
		(end 429.178212 -269.160244)
		(width 0.14478)
		(layer "In6.Cu")
		(net "M_K_CPU0_SB_CS_N<1>")
	)
	(segment
		(start 435.719728 -268.473174)
		(end 435.719728 -268.534642)
		(width 0.14478)
		(layer "In6.Cu")
		(net "M_K_CPU0_SB_CS_N<1>")
	)
	(segment
		(start 395.661388 -265.550904)
		(end 395.813534 -265.70305)
		(width 0.0889)
		(layer "In6.Cu")
		(net "M_K_CPU0_SB_CS_N<1>")
	)
	(segment
		(start 392.727434 -266.473432)
		(end 392.735816 -266.468606)
		(width 0.0889)
		(layer "In6.Cu")
		(net "M_K_CPU0_SB_CS_N<1>")
	)
	(segment
		(start 436.276242 -268.534642)
		(end 436.276242 -268.08557)
		(width 0.14478)
		(layer "In6.Cu")
		(net "M_K_CPU0_SB_CS_N<1>")
	)
	(segment
		(start 413.976058 -268.310106)
		(end 418.789104 -268.310106)
		(width 0.14478)
		(layer "In6.Cu")
		(net "M_K_CPU0_SB_CS_N<1>")
	)
	(segment
		(start 390.880854 -266.530582)
		(end 390.903206 -266.44727)
		(width 0.0889)
		(layer "In6.Cu")
		(net "M_K_CPU0_SB_CS_N<1>")
	)
	(segment
		(start 393.407392 -266.473432)
		(end 394.32992 -265.550904)
		(width 0.0889)
		(layer "In6.Cu")
		(net "M_K_CPU0_SB_CS_N<1>")
	)
	(segment
		(start 437.945784 -268.534642)
		(end 438.108852 -268.69771)
		(width 0.14478)
		(layer "In6.Cu")
		(net "M_K_CPU0_SB_CS_N<1>")
	)
	(segment
		(start 392.161776 -266.473432)
		(end 392.17219 -266.479528)
		(width 0.0889)
		(layer "In6.Cu")
		(net "M_K_CPU0_SB_CS_N<1>")
	)
	(segment
		(start 438.108852 -268.69771)
		(end 438.33923 -268.69771)
		(width 0.14478)
		(layer "In6.Cu")
		(net "M_K_CPU0_SB_CS_N<1>")
	)
	(segment
		(start 408.43454 -265.70305)
		(end 411.891734 -269.160244)
		(width 0.14478)
		(layer "In6.Cu")
		(net "M_K_CPU0_SB_CS_N<1>")
	)
	(segment
		(start 436.832756 -268.08557)
		(end 436.832756 -268.534642)
		(width 0.14478)
		(layer "In6.Cu")
		(net "M_K_CPU0_SB_CS_N<1>")
	)
	(segment
		(start 437.38927 -268.08557)
		(end 437.552338 -267.922502)
		(width 0.14478)
		(layer "In6.Cu")
		(net "M_K_CPU0_SB_CS_N<1>")
	)
	(segment
		(start 442.119258 -268.310106)
		(end 442.5442 -268.735048)
		(width 0.14478)
		(layer "In6.Cu")
		(net "M_K_CPU0_SB_CS_N<1>")
	)
	(segment
		(start 422.484296 -268.310106)
		(end 426.30725 -268.310106)
		(width 0.14478)
		(layer "In6.Cu")
		(net "M_K_CPU0_SB_CS_N<1>")
	)
	(segment
		(start 438.502298 -268.534642)
		(end 438.502298 -268.473174)
		(width 0.14478)
		(layer "In6.Cu")
		(net "M_K_CPU0_SB_CS_N<1>")
	)
	(segment
		(start 411.891734 -269.160244)
		(end 413.12592 -269.160244)
		(width 0.14478)
		(layer "In6.Cu")
		(net "M_K_CPU0_SB_CS_N<1>")
	)
	(arc
		(start 391.221722 -266.473432)
		(mid 391.504678 -266.549609)
		(end 391.787634 -266.473432)
		(width 0.0889)
		(layer "In6.Cu")
		(net "M_K_CPU0_SB_CS_N<1>")
	)
	(arc
		(start 392.17219 -266.479528)
		(mid 392.450622 -266.549626)
		(end 392.727434 -266.473432)
		(width 0.0889)
		(layer "In6.Cu")
		(net "M_K_CPU0_SB_CS_N<1>")
	)
	(arc
		(start 391.787634 -266.473432)
		(mid 391.969885 -266.423082)
		(end 392.153394 -266.468606)
		(width 0.0889)
		(layer "In6.Cu")
		(net "M_K_CPU0_SB_CS_N<1>")
	)
	(arc
		(start 392.735816 -266.468606)
		(mid 392.919324 -266.423112)
		(end 393.101576 -266.473432)
		(width 0.0889)
		(layer "In6.Cu")
		(net "M_K_CPU0_SB_CS_N<1>")
	)
	(arc
		(start 390.903206 -266.44727)
		(mid 391.065395 -266.424535)
		(end 391.221722 -266.473432)
		(width 0.0889)
		(layer "In6.Cu")
		(net "M_K_CPU0_SB_CS_N<1>")
	)
	(segment
		(start 389.157972 -265.720068)
		(end 389.624824 -265.986006)
		(width 0.10668)
		(layer "F.Cu")
		(net "M_K_CPU0_SB_CS_N<0>")
	)
	(segment
		(start 422.577006 -267.460222)
		(end 426.346366 -267.460222)
		(width 0.14478)
		(layer "In6.Cu")
		(net "M_K_CPU0_SB_CS_N<0>")
	)
	(segment
		(start 418.726112 -267.460222)
		(end 419.575996 -268.310106)
		(width 0.14478)
		(layer "In6.Cu")
		(net "M_K_CPU0_SB_CS_N<0>")
	)
	(segment
		(start 413.036004 -268.310106)
		(end 413.885888 -267.460222)
		(width 0.14478)
		(layer "In6.Cu")
		(net "M_K_CPU0_SB_CS_N<0>")
	)
	(segment
		(start 429.271176 -268.310106)
		(end 430.12106 -267.460222)
		(width 0.14478)
		(layer "In6.Cu")
		(net "M_K_CPU0_SB_CS_N<0>")
	)
	(segment
		(start 426.346366 -267.460222)
		(end 427.19625 -268.310106)
		(width 0.14478)
		(layer "In6.Cu")
		(net "M_K_CPU0_SB_CS_N<0>")
	)
	(segment
		(start 390.74344 -265.6586)
		(end 390.751822 -265.663426)
		(width 0.0889)
		(layer "In6.Cu")
		(net "M_K_CPU0_SB_CS_N<0>")
	)
	(segment
		(start 393.197334 -265.663426)
		(end 393.892532 -265.27379)
		(width 0.0889)
		(layer "In6.Cu")
		(net "M_K_CPU0_SB_CS_N<0>")
	)
	(segment
		(start 430.12106 -267.460222)
		(end 446.219326 -267.460222)
		(width 0.14478)
		(layer "In6.Cu")
		(net "M_K_CPU0_SB_CS_N<0>")
	)
	(segment
		(start 389.624824 -265.986006)
		(end 389.4709 -265.720576)
		(width 0.0889)
		(layer "In6.Cu")
		(net "M_K_CPU0_SB_CS_N<0>")
	)
	(segment
		(start 395.948916 -265.24839)
		(end 408.665934 -265.24839)
		(width 0.14478)
		(layer "In6.Cu")
		(net "M_K_CPU0_SB_CS_N<0>")
	)
	(segment
		(start 389.4709 -265.720576)
		(end 389.493252 -265.637264)
		(width 0.0889)
		(layer "In6.Cu")
		(net "M_K_CPU0_SB_CS_N<0>")
	)
	(segment
		(start 408.665934 -265.24839)
		(end 411.72765 -268.310106)
		(width 0.14478)
		(layer "In6.Cu")
		(net "M_K_CPU0_SB_CS_N<0>")
	)
	(segment
		(start 421.727122 -268.310106)
		(end 422.577006 -267.460222)
		(width 0.14478)
		(layer "In6.Cu")
		(net "M_K_CPU0_SB_CS_N<0>")
	)
	(segment
		(start 411.72765 -268.310106)
		(end 413.036004 -268.310106)
		(width 0.14478)
		(layer "In6.Cu")
		(net "M_K_CPU0_SB_CS_N<0>")
	)
	(segment
		(start 419.575996 -268.310106)
		(end 421.727122 -268.310106)
		(width 0.14478)
		(layer "In6.Cu")
		(net "M_K_CPU0_SB_CS_N<0>")
	)
	(segment
		(start 392.631168 -265.663426)
		(end 392.641582 -265.669522)
		(width 0.0889)
		(layer "In6.Cu")
		(net "M_K_CPU0_SB_CS_N<0>")
	)
	(segment
		(start 427.19625 -268.310106)
		(end 429.271176 -268.310106)
		(width 0.14478)
		(layer "In6.Cu")
		(net "M_K_CPU0_SB_CS_N<0>")
	)
	(segment
		(start 446.219326 -267.460222)
		(end 446.644268 -267.885164)
		(width 0.14478)
		(layer "In6.Cu")
		(net "M_K_CPU0_SB_CS_N<0>")
	)
	(segment
		(start 413.885888 -267.460222)
		(end 418.726112 -267.460222)
		(width 0.14478)
		(layer "In6.Cu")
		(net "M_K_CPU0_SB_CS_N<0>")
	)
	(segment
		(start 391.317734 -265.663426)
		(end 391.326116 -265.6586)
		(width 0.0889)
		(layer "In6.Cu")
		(net "M_K_CPU0_SB_CS_N<0>")
	)
	(segment
		(start 392.24712 -265.669522)
		(end 392.257534 -265.663426)
		(width 0.0889)
		(layer "In6.Cu")
		(net "M_K_CPU0_SB_CS_N<0>")
	)
	(segment
		(start 393.892532 -265.27379)
		(end 395.164818 -265.27379)
		(width 0.0889)
		(layer "In6.Cu")
		(net "M_K_CPU0_SB_CS_N<0>")
	)
	(segment
		(start 392.257534 -265.663426)
		(end 392.265916 -265.6586)
		(width 0.0889)
		(layer "In6.Cu")
		(net "M_K_CPU0_SB_CS_N<0>")
	)
	(segment
		(start 395.190218 -265.24839)
		(end 395.948916 -265.24839)
		(width 0.0889)
		(layer "In6.Cu")
		(net "M_K_CPU0_SB_CS_N<0>")
	)
	(segment
		(start 395.164818 -265.27379)
		(end 395.190218 -265.24839)
		(width 0.0889)
		(layer "In6.Cu")
		(net "M_K_CPU0_SB_CS_N<0>")
	)
	(arc
		(start 391.691876 -265.663426)
		(mid 391.968689 -265.739569)
		(end 392.24712 -265.669522)
		(width 0.0889)
		(layer "In6.Cu")
		(net "M_K_CPU0_SB_CS_N<0>")
	)
	(arc
		(start 390.37768 -265.663426)
		(mid 390.559931 -265.613076)
		(end 390.74344 -265.6586)
		(width 0.0889)
		(layer "In6.Cu")
		(net "M_K_CPU0_SB_CS_N<0>")
	)
	(arc
		(start 391.326116 -265.6586)
		(mid 391.509624 -265.613106)
		(end 391.691876 -265.663426)
		(width 0.0889)
		(layer "In6.Cu")
		(net "M_K_CPU0_SB_CS_N<0>")
	)
	(arc
		(start 389.811768 -265.663426)
		(mid 390.094724 -265.739603)
		(end 390.37768 -265.663426)
		(width 0.0889)
		(layer "In6.Cu")
		(net "M_K_CPU0_SB_CS_N<0>")
	)
	(arc
		(start 392.265916 -265.6586)
		(mid 392.44917 -265.613227)
		(end 392.631168 -265.663426)
		(width 0.0889)
		(layer "In6.Cu")
		(net "M_K_CPU0_SB_CS_N<0>")
	)
	(arc
		(start 389.493252 -265.637264)
		(mid 389.655441 -265.614529)
		(end 389.811768 -265.663426)
		(width 0.0889)
		(layer "In6.Cu")
		(net "M_K_CPU0_SB_CS_N<0>")
	)
	(arc
		(start 392.641582 -265.669522)
		(mid 392.920268 -265.739742)
		(end 393.197334 -265.663426)
		(width 0.0889)
		(layer "In6.Cu")
		(net "M_K_CPU0_SB_CS_N<0>")
	)
	(arc
		(start 390.751822 -265.663426)
		(mid 391.034778 -265.739603)
		(end 391.317734 -265.663426)
		(width 0.0889)
		(layer "In6.Cu")
		(net "M_K_CPU0_SB_CS_N<0>")
	)
	(segment
		(start 389.157972 -270.580104)
		(end 389.624824 -270.846042)
		(width 0.10668)
		(layer "F.Cu")
		(net "M_K_CPU0_SB_CB<7>")
	)
	(segment
		(start 395.983206 -268.67993)
		(end 406.4635 -268.67993)
		(width 0.14478)
		(layer "In6.Cu")
		(net "M_K_CPU0_SB_CB<7>")
	)
	(segment
		(start 416.425634 -273.410172)
		(end 416.656012 -273.410172)
		(width 0.14478)
		(layer "In6.Cu")
		(net "M_K_CPU0_SB_CB<7>")
	)
	(segment
		(start 437.770524 -273.554698)
		(end 437.770524 -273.974052)
		(width 0.14478)
		(layer "In6.Cu")
		(net "M_K_CPU0_SB_CB<7>")
	)
	(segment
		(start 437.36387 -273.409918)
		(end 437.625744 -273.409918)
		(width 0.14478)
		(layer "In6.Cu")
		(net "M_K_CPU0_SB_CB<7>")
	)
	(segment
		(start 417.538662 -273.410172)
		(end 418.427916 -273.410172)
		(width 0.14478)
		(layer "In6.Cu")
		(net "M_K_CPU0_SB_CB<7>")
	)
	(segment
		(start 416.81908 -274.046442)
		(end 416.982148 -274.20951)
		(width 0.14478)
		(layer "In6.Cu")
		(net "M_K_CPU0_SB_CB<7>")
	)
	(segment
		(start 392.257788 -270.523462)
		(end 392.296904 -270.500602)
		(width 0.0889)
		(layer "In6.Cu")
		(net "M_K_CPU0_SB_CB<7>")
	)
	(segment
		(start 395.261338 -268.832838)
		(end 395.414246 -268.67993)
		(width 0.0889)
		(layer "In6.Cu")
		(net "M_K_CPU0_SB_CB<7>")
	)
	(segment
		(start 393.093448 -269.70863)
		(end 393.10183 -269.713456)
		(width 0.0889)
		(layer "In6.Cu")
		(net "M_K_CPU0_SB_CB<7>")
	)
	(segment
		(start 414.183068 -274.260056)
		(end 415.032952 -273.410172)
		(width 0.14478)
		(layer "In6.Cu")
		(net "M_K_CPU0_SB_CB<7>")
	)
	(segment
		(start 436.667656 -273.554698)
		(end 436.667656 -273.974052)
		(width 0.14478)
		(layer "In6.Cu")
		(net "M_K_CPU0_SB_CB<7>")
	)
	(segment
		(start 437.915304 -274.118832)
		(end 438.177178 -274.118832)
		(width 0.14478)
		(layer "In6.Cu")
		(net "M_K_CPU0_SB_CB<7>")
	)
	(segment
		(start 437.21909 -273.974052)
		(end 437.21909 -273.554698)
		(width 0.14478)
		(layer "In6.Cu")
		(net "M_K_CPU0_SB_CB<7>")
	)
	(segment
		(start 425.601638 -273.410172)
		(end 426.451522 -274.260056)
		(width 0.14478)
		(layer "In6.Cu")
		(net "M_K_CPU0_SB_CB<7>")
	)
	(segment
		(start 415.706052 -274.046442)
		(end 415.86912 -274.20951)
		(width 0.14478)
		(layer "In6.Cu")
		(net "M_K_CPU0_SB_CB<7>")
	)
	(segment
		(start 436.667656 -273.974052)
		(end 436.812436 -274.118832)
		(width 0.14478)
		(layer "In6.Cu")
		(net "M_K_CPU0_SB_CB<7>")
	)
	(segment
		(start 416.262566 -273.57324)
		(end 416.425634 -273.410172)
		(width 0.14478)
		(layer "In6.Cu")
		(net "M_K_CPU0_SB_CB<7>")
	)
	(segment
		(start 437.625744 -273.409918)
		(end 437.770524 -273.554698)
		(width 0.14478)
		(layer "In6.Cu")
		(net "M_K_CPU0_SB_CB<7>")
	)
	(segment
		(start 421.727122 -274.260056)
		(end 422.577006 -273.410172)
		(width 0.14478)
		(layer "In6.Cu")
		(net "M_K_CPU0_SB_CB<7>")
	)
	(segment
		(start 389.4709 -270.580612)
		(end 389.493252 -270.4973)
		(width 0.0889)
		(layer "In6.Cu")
		(net "M_K_CPU0_SB_CB<7>")
	)
	(segment
		(start 430.121314 -273.409918)
		(end 436.522876 -273.409918)
		(width 0.14478)
		(layer "In6.Cu")
		(net "M_K_CPU0_SB_CB<7>")
	)
	(segment
		(start 440.706256 -273.409918)
		(end 441.981336 -274.684998)
		(width 0.14478)
		(layer "In6.Cu")
		(net "M_K_CPU0_SB_CB<7>")
	)
	(segment
		(start 438.321958 -273.554698)
		(end 438.466738 -273.409918)
		(width 0.14478)
		(layer "In6.Cu")
		(net "M_K_CPU0_SB_CB<7>")
	)
	(segment
		(start 417.212526 -274.20951)
		(end 417.375594 -274.046442)
		(width 0.14478)
		(layer "In6.Cu")
		(net "M_K_CPU0_SB_CB<7>")
	)
	(segment
		(start 392.69797 -269.730728)
		(end 392.727688 -269.713456)
		(width 0.0889)
		(layer "In6.Cu")
		(net "M_K_CPU0_SB_CB<7>")
	)
	(segment
		(start 437.770524 -273.974052)
		(end 437.915304 -274.118832)
		(width 0.14478)
		(layer "In6.Cu")
		(net "M_K_CPU0_SB_CB<7>")
	)
	(segment
		(start 415.032952 -273.410172)
		(end 415.542984 -273.410172)
		(width 0.14478)
		(layer "In6.Cu")
		(net "M_K_CPU0_SB_CB<7>")
	)
	(segment
		(start 438.321958 -273.974052)
		(end 438.321958 -273.554698)
		(width 0.14478)
		(layer "In6.Cu")
		(net "M_K_CPU0_SB_CB<7>")
	)
	(segment
		(start 415.86912 -274.20951)
		(end 416.099498 -274.20951)
		(width 0.14478)
		(layer "In6.Cu")
		(net "M_K_CPU0_SB_CB<7>")
	)
	(segment
		(start 412.043626 -274.260056)
		(end 414.183068 -274.260056)
		(width 0.14478)
		(layer "In6.Cu")
		(net "M_K_CPU0_SB_CB<7>")
	)
	(segment
		(start 441.981336 -274.684998)
		(end 442.5442 -274.684998)
		(width 0.14478)
		(layer "In6.Cu")
		(net "M_K_CPU0_SB_CB<7>")
	)
	(segment
		(start 437.21909 -273.554698)
		(end 437.36387 -273.409918)
		(width 0.14478)
		(layer "In6.Cu")
		(net "M_K_CPU0_SB_CB<7>")
	)
	(segment
		(start 418.427916 -273.410172)
		(end 419.2778 -274.260056)
		(width 0.14478)
		(layer "In6.Cu")
		(net "M_K_CPU0_SB_CB<7>")
	)
	(segment
		(start 395.414246 -268.67993)
		(end 395.983206 -268.67993)
		(width 0.0889)
		(layer "In6.Cu")
		(net "M_K_CPU0_SB_CB<7>")
	)
	(segment
		(start 419.2778 -274.260056)
		(end 421.727122 -274.260056)
		(width 0.14478)
		(layer "In6.Cu")
		(net "M_K_CPU0_SB_CB<7>")
	)
	(segment
		(start 416.262566 -274.046442)
		(end 416.262566 -273.57324)
		(width 0.14478)
		(layer "In6.Cu")
		(net "M_K_CPU0_SB_CB<7>")
	)
	(segment
		(start 393.783312 -269.624556)
		(end 394.57503 -268.832838)
		(width 0.0889)
		(layer "In6.Cu")
		(net "M_K_CPU0_SB_CB<7>")
	)
	(segment
		(start 422.577006 -273.410172)
		(end 425.601638 -273.410172)
		(width 0.14478)
		(layer "In6.Cu")
		(net "M_K_CPU0_SB_CB<7>")
	)
	(segment
		(start 436.812436 -274.118832)
		(end 437.07431 -274.118832)
		(width 0.14478)
		(layer "In6.Cu")
		(net "M_K_CPU0_SB_CB<7>")
	)
	(segment
		(start 416.099498 -274.20951)
		(end 416.262566 -274.046442)
		(width 0.14478)
		(layer "In6.Cu")
		(net "M_K_CPU0_SB_CB<7>")
	)
	(segment
		(start 390.74344 -270.518636)
		(end 390.751822 -270.523462)
		(width 0.0889)
		(layer "In6.Cu")
		(net "M_K_CPU0_SB_CB<7>")
	)
	(segment
		(start 415.706052 -273.57324)
		(end 415.706052 -274.046442)
		(width 0.14478)
		(layer "In6.Cu")
		(net "M_K_CPU0_SB_CB<7>")
	)
	(segment
		(start 394.57503 -268.832838)
		(end 395.261338 -268.832838)
		(width 0.0889)
		(layer "In6.Cu")
		(net "M_K_CPU0_SB_CB<7>")
	)
	(segment
		(start 416.81908 -273.57324)
		(end 416.81908 -274.046442)
		(width 0.14478)
		(layer "In6.Cu")
		(net "M_K_CPU0_SB_CB<7>")
	)
	(segment
		(start 438.177178 -274.118832)
		(end 438.321958 -273.974052)
		(width 0.14478)
		(layer "In6.Cu")
		(net "M_K_CPU0_SB_CB<7>")
	)
	(segment
		(start 392.697208 -269.731236)
		(end 392.69797 -269.730728)
		(width 0.0889)
		(layer "In6.Cu")
		(net "M_K_CPU0_SB_CB<7>")
	)
	(segment
		(start 436.522876 -273.409918)
		(end 436.667656 -273.554698)
		(width 0.14478)
		(layer "In6.Cu")
		(net "M_K_CPU0_SB_CB<7>")
	)
	(segment
		(start 429.271176 -274.260056)
		(end 430.121314 -273.409918)
		(width 0.14478)
		(layer "In6.Cu")
		(net "M_K_CPU0_SB_CB<7>")
	)
	(segment
		(start 416.982148 -274.20951)
		(end 417.212526 -274.20951)
		(width 0.14478)
		(layer "In6.Cu")
		(net "M_K_CPU0_SB_CB<7>")
	)
	(segment
		(start 438.466738 -273.409918)
		(end 440.706256 -273.409918)
		(width 0.14478)
		(layer "In6.Cu")
		(net "M_K_CPU0_SB_CB<7>")
	)
	(segment
		(start 406.4635 -268.67993)
		(end 412.043626 -274.260056)
		(width 0.14478)
		(layer "In6.Cu")
		(net "M_K_CPU0_SB_CB<7>")
	)
	(segment
		(start 416.656012 -273.410172)
		(end 416.81908 -273.57324)
		(width 0.14478)
		(layer "In6.Cu")
		(net "M_K_CPU0_SB_CB<7>")
	)
	(segment
		(start 417.375594 -274.046442)
		(end 417.375594 -273.57324)
		(width 0.14478)
		(layer "In6.Cu")
		(net "M_K_CPU0_SB_CB<7>")
	)
	(segment
		(start 389.624824 -270.846042)
		(end 389.4709 -270.580612)
		(width 0.0889)
		(layer "In6.Cu")
		(net "M_K_CPU0_SB_CB<7>")
	)
	(segment
		(start 415.542984 -273.410172)
		(end 415.706052 -273.57324)
		(width 0.14478)
		(layer "In6.Cu")
		(net "M_K_CPU0_SB_CB<7>")
	)
	(segment
		(start 391.317734 -270.523462)
		(end 391.326116 -270.518636)
		(width 0.0889)
		(layer "In6.Cu")
		(net "M_K_CPU0_SB_CB<7>")
	)
	(segment
		(start 426.451522 -274.260056)
		(end 429.271176 -274.260056)
		(width 0.14478)
		(layer "In6.Cu")
		(net "M_K_CPU0_SB_CB<7>")
	)
	(segment
		(start 417.375594 -273.57324)
		(end 417.538662 -273.410172)
		(width 0.14478)
		(layer "In6.Cu")
		(net "M_K_CPU0_SB_CB<7>")
	)
	(segment
		(start 437.07431 -274.118832)
		(end 437.21909 -273.974052)
		(width 0.14478)
		(layer "In6.Cu")
		(net "M_K_CPU0_SB_CB<7>")
	)
	(arc
		(start 390.751822 -270.523462)
		(mid 391.034778 -270.599639)
		(end 391.317734 -270.523462)
		(width 0.0889)
		(layer "In6.Cu")
		(net "M_K_CPU0_SB_CB<7>")
	)
	(arc
		(start 392.296904 -270.500602)
		(mid 392.475717 -270.298252)
		(end 392.540236 -270.036036)
		(width 0.0889)
		(layer "In6.Cu")
		(net "M_K_CPU0_SB_CB<7>")
	)
	(arc
		(start 389.811768 -270.523462)
		(mid 390.094724 -270.599639)
		(end 390.37768 -270.523462)
		(width 0.0889)
		(layer "In6.Cu")
		(net "M_K_CPU0_SB_CB<7>")
	)
	(arc
		(start 391.326116 -270.518636)
		(mid 391.509624 -270.473142)
		(end 391.691876 -270.523462)
		(width 0.0889)
		(layer "In6.Cu")
		(net "M_K_CPU0_SB_CB<7>")
	)
	(arc
		(start 389.493252 -270.4973)
		(mid 389.655441 -270.474565)
		(end 389.811768 -270.523462)
		(width 0.0889)
		(layer "In6.Cu")
		(net "M_K_CPU0_SB_CB<7>")
	)
	(arc
		(start 390.37768 -270.523462)
		(mid 390.559931 -270.473112)
		(end 390.74344 -270.518636)
		(width 0.0889)
		(layer "In6.Cu")
		(net "M_K_CPU0_SB_CB<7>")
	)
	(arc
		(start 392.727688 -269.713456)
		(mid 392.909939 -269.663106)
		(end 393.093448 -269.70863)
		(width 0.0889)
		(layer "In6.Cu")
		(net "M_K_CPU0_SB_CB<7>")
	)
	(arc
		(start 393.10183 -269.713456)
		(mid 393.45769 -269.784898)
		(end 393.783312 -269.624556)
		(width 0.0889)
		(layer "In6.Cu")
		(net "M_K_CPU0_SB_CB<7>")
	)
	(arc
		(start 392.540236 -270.036036)
		(mid 392.581785 -269.864614)
		(end 392.697208 -269.731236)
		(width 0.0889)
		(layer "In6.Cu")
		(net "M_K_CPU0_SB_CB<7>")
	)
	(arc
		(start 391.691876 -270.523462)
		(mid 391.974832 -270.599639)
		(end 392.257788 -270.523462)
		(width 0.0889)
		(layer "In6.Cu")
		(net "M_K_CPU0_SB_CB<7>")
	)
	(segment
		(start 390.567926 -269.770098)
		(end 391.034778 -270.036036)
		(width 0.10668)
		(layer "F.Cu")
		(net "M_K_CPU0_SB_CB<6>")
	)
	(segment
		(start 433.32019 -271.930368)
		(end 433.46497 -272.075148)
		(width 0.14478)
		(layer "In6.Cu")
		(net "M_K_CPU0_SB_CB<6>")
	)
	(segment
		(start 433.726844 -272.075148)
		(end 433.871624 -271.930368)
		(width 0.14478)
		(layer "In6.Cu")
		(net "M_K_CPU0_SB_CB<6>")
	)
	(segment
		(start 433.46497 -272.075148)
		(end 433.726844 -272.075148)
		(width 0.14478)
		(layer "In6.Cu")
		(net "M_K_CPU0_SB_CB<6>")
	)
	(segment
		(start 430.12106 -271.71015)
		(end 432.072542 -271.71015)
		(width 0.14478)
		(layer "In6.Cu")
		(net "M_K_CPU0_SB_CB<6>")
	)
	(segment
		(start 438.399936 -271.56537)
		(end 438.544716 -271.71015)
		(width 0.14478)
		(layer "In6.Cu")
		(net "M_K_CPU0_SB_CB<6>")
	)
	(segment
		(start 434.423058 -271.489932)
		(end 434.423058 -271.56537)
		(width 0.14478)
		(layer "In6.Cu")
		(net "M_K_CPU0_SB_CB<6>")
	)
	(segment
		(start 438.255156 -271.334992)
		(end 438.399936 -271.479772)
		(width 0.14478)
		(layer "In6.Cu")
		(net "M_K_CPU0_SB_CB<6>")
	)
	(segment
		(start 433.32019 -271.489932)
		(end 433.32019 -271.930368)
		(width 0.14478)
		(layer "In6.Cu")
		(net "M_K_CPU0_SB_CB<6>")
	)
	(segment
		(start 440.235594 -271.327372)
		(end 440.497468 -271.327372)
		(width 0.14478)
		(layer "In6.Cu")
		(net "M_K_CPU0_SB_CB<6>")
	)
	(segment
		(start 432.362102 -272.075148)
		(end 432.623976 -272.075148)
		(width 0.14478)
		(layer "In6.Cu")
		(net "M_K_CPU0_SB_CB<6>")
	)
	(segment
		(start 425.601638 -271.71015)
		(end 426.451522 -272.560034)
		(width 0.14478)
		(layer "In6.Cu")
		(net "M_K_CPU0_SB_CB<6>")
	)
	(segment
		(start 437.441848 -272.085308)
		(end 437.703722 -272.085308)
		(width 0.14478)
		(layer "In6.Cu")
		(net "M_K_CPU0_SB_CB<6>")
	)
	(segment
		(start 436.745634 -271.940528)
		(end 436.745634 -271.479772)
		(width 0.14478)
		(layer "In6.Cu")
		(net "M_K_CPU0_SB_CB<6>")
	)
	(segment
		(start 432.217322 -271.85493)
		(end 432.217322 -271.930368)
		(width 0.14478)
		(layer "In6.Cu")
		(net "M_K_CPU0_SB_CB<6>")
	)
	(segment
		(start 439.53938 -271.948148)
		(end 439.68416 -272.092928)
		(width 0.14478)
		(layer "In6.Cu")
		(net "M_K_CPU0_SB_CB<6>")
	)
	(segment
		(start 437.297068 -271.940528)
		(end 437.441848 -272.085308)
		(width 0.14478)
		(layer "In6.Cu")
		(net "M_K_CPU0_SB_CB<6>")
	)
	(segment
		(start 422.577006 -271.71015)
		(end 425.601638 -271.71015)
		(width 0.14478)
		(layer "In6.Cu")
		(net "M_K_CPU0_SB_CB<6>")
	)
	(segment
		(start 434.567838 -271.71015)
		(end 435.497986 -271.71015)
		(width 0.14478)
		(layer "In6.Cu")
		(net "M_K_CPU0_SB_CB<6>")
	)
	(segment
		(start 421.727122 -272.560034)
		(end 422.577006 -271.71015)
		(width 0.14478)
		(layer "In6.Cu")
		(net "M_K_CPU0_SB_CB<6>")
	)
	(segment
		(start 418.07384 -271.71015)
		(end 418.923724 -272.560034)
		(width 0.14478)
		(layer "In6.Cu")
		(net "M_K_CPU0_SB_CB<6>")
	)
	(segment
		(start 440.642248 -271.56537)
		(end 440.787028 -271.71015)
		(width 0.14478)
		(layer "In6.Cu")
		(net "M_K_CPU0_SB_CB<6>")
	)
	(segment
		(start 436.04942 -271.334992)
		(end 436.1942 -271.479772)
		(width 0.14478)
		(layer "In6.Cu")
		(net "M_K_CPU0_SB_CB<6>")
	)
	(segment
		(start 432.623976 -272.075148)
		(end 432.768756 -271.930368)
		(width 0.14478)
		(layer "In6.Cu")
		(net "M_K_CPU0_SB_CB<6>")
	)
	(segment
		(start 418.923724 -272.560034)
		(end 421.727122 -272.560034)
		(width 0.14478)
		(layer "In6.Cu")
		(net "M_K_CPU0_SB_CB<6>")
	)
	(segment
		(start 441.269374 -271.71015)
		(end 442.5442 -272.984976)
		(width 0.14478)
		(layer "In6.Cu")
		(net "M_K_CPU0_SB_CB<6>")
	)
	(segment
		(start 390.880854 -269.770606)
		(end 390.903206 -269.687294)
		(width 0.0889)
		(layer "In6.Cu")
		(net "M_K_CPU0_SB_CB<6>")
	)
	(segment
		(start 439.946034 -272.092928)
		(end 440.090814 -271.948148)
		(width 0.14478)
		(layer "In6.Cu")
		(net "M_K_CPU0_SB_CB<6>")
	)
	(segment
		(start 437.993282 -271.334992)
		(end 438.255156 -271.334992)
		(width 0.14478)
		(layer "In6.Cu")
		(net "M_K_CPU0_SB_CB<6>")
	)
	(segment
		(start 412.05658 -272.560034)
		(end 414.183068 -272.560034)
		(width 0.14478)
		(layer "In6.Cu")
		(net "M_K_CPU0_SB_CB<6>")
	)
	(segment
		(start 437.848502 -271.479772)
		(end 437.993282 -271.334992)
		(width 0.14478)
		(layer "In6.Cu")
		(net "M_K_CPU0_SB_CB<6>")
	)
	(segment
		(start 434.016404 -271.345152)
		(end 434.278278 -271.345152)
		(width 0.14478)
		(layer "In6.Cu")
		(net "M_K_CPU0_SB_CB<6>")
	)
	(segment
		(start 429.271176 -272.560034)
		(end 430.12106 -271.71015)
		(width 0.14478)
		(layer "In6.Cu")
		(net "M_K_CPU0_SB_CB<6>")
	)
	(segment
		(start 393.2301 -268.887448)
		(end 393.625832 -268.723364)
		(width 0.0889)
		(layer "In6.Cu")
		(net "M_K_CPU0_SB_CB<6>")
	)
	(segment
		(start 440.787028 -271.71015)
		(end 441.269374 -271.71015)
		(width 0.14478)
		(layer "In6.Cu")
		(net "M_K_CPU0_SB_CB<6>")
	)
	(segment
		(start 391.034778 -270.036036)
		(end 390.880854 -269.770606)
		(width 0.0889)
		(layer "In6.Cu")
		(net "M_K_CPU0_SB_CB<6>")
	)
	(segment
		(start 440.497468 -271.327372)
		(end 440.642248 -271.472152)
		(width 0.14478)
		(layer "In6.Cu")
		(net "M_K_CPU0_SB_CB<6>")
	)
	(segment
		(start 392.226038 -268.921738)
		(end 392.257788 -268.90345)
		(width 0.0889)
		(layer "In6.Cu")
		(net "M_K_CPU0_SB_CB<6>")
	)
	(segment
		(start 440.642248 -271.472152)
		(end 440.642248 -271.56537)
		(width 0.14478)
		(layer "In6.Cu")
		(net "M_K_CPU0_SB_CB<6>")
	)
	(segment
		(start 439.3946 -271.71015)
		(end 439.53938 -271.85493)
		(width 0.14478)
		(layer "In6.Cu")
		(net "M_K_CPU0_SB_CB<6>")
	)
	(segment
		(start 435.497986 -271.71015)
		(end 435.642766 -271.56537)
		(width 0.14478)
		(layer "In6.Cu")
		(net "M_K_CPU0_SB_CB<6>")
	)
	(segment
		(start 415.032952 -271.71015)
		(end 418.07384 -271.71015)
		(width 0.14478)
		(layer "In6.Cu")
		(net "M_K_CPU0_SB_CB<6>")
	)
	(segment
		(start 426.451522 -272.560034)
		(end 429.271176 -272.560034)
		(width 0.14478)
		(layer "In6.Cu")
		(net "M_K_CPU0_SB_CB<6>")
	)
	(segment
		(start 436.890414 -271.334992)
		(end 437.152288 -271.334992)
		(width 0.14478)
		(layer "In6.Cu")
		(net "M_K_CPU0_SB_CB<6>")
	)
	(segment
		(start 434.278278 -271.345152)
		(end 434.423058 -271.489932)
		(width 0.14478)
		(layer "In6.Cu")
		(net "M_K_CPU0_SB_CB<6>")
	)
	(segment
		(start 391.787634 -269.713456)
		(end 391.82675 -269.690596)
		(width 0.0889)
		(layer "In6.Cu")
		(net "M_K_CPU0_SB_CB<6>")
	)
	(segment
		(start 432.913536 -271.345152)
		(end 433.17541 -271.345152)
		(width 0.14478)
		(layer "In6.Cu")
		(net "M_K_CPU0_SB_CB<6>")
	)
	(segment
		(start 438.544716 -271.71015)
		(end 439.3946 -271.71015)
		(width 0.14478)
		(layer "In6.Cu")
		(net "M_K_CPU0_SB_CB<6>")
	)
	(segment
		(start 435.642766 -271.479772)
		(end 435.787546 -271.334992)
		(width 0.14478)
		(layer "In6.Cu")
		(net "M_K_CPU0_SB_CB<6>")
	)
	(segment
		(start 440.090814 -271.472152)
		(end 440.235594 -271.327372)
		(width 0.14478)
		(layer "In6.Cu")
		(net "M_K_CPU0_SB_CB<6>")
	)
	(segment
		(start 432.072542 -271.71015)
		(end 432.217322 -271.85493)
		(width 0.14478)
		(layer "In6.Cu")
		(net "M_K_CPU0_SB_CB<6>")
	)
	(segment
		(start 436.600854 -272.085308)
		(end 436.745634 -271.940528)
		(width 0.14478)
		(layer "In6.Cu")
		(net "M_K_CPU0_SB_CB<6>")
	)
	(segment
		(start 435.642766 -271.56537)
		(end 435.642766 -271.479772)
		(width 0.14478)
		(layer "In6.Cu")
		(net "M_K_CPU0_SB_CB<6>")
	)
	(segment
		(start 437.152288 -271.334992)
		(end 437.297068 -271.479772)
		(width 0.14478)
		(layer "In6.Cu")
		(net "M_K_CPU0_SB_CB<6>")
	)
	(segment
		(start 434.423058 -271.56537)
		(end 434.567838 -271.71015)
		(width 0.14478)
		(layer "In6.Cu")
		(net "M_K_CPU0_SB_CB<6>")
	)
	(segment
		(start 436.33898 -272.085308)
		(end 436.600854 -272.085308)
		(width 0.14478)
		(layer "In6.Cu")
		(net "M_K_CPU0_SB_CB<6>")
	)
	(segment
		(start 433.871624 -271.489932)
		(end 434.016404 -271.345152)
		(width 0.14478)
		(layer "In6.Cu")
		(net "M_K_CPU0_SB_CB<6>")
	)
	(segment
		(start 407.267156 -267.77061)
		(end 412.05658 -272.560034)
		(width 0.14478)
		(layer "In6.Cu")
		(net "M_K_CPU0_SB_CB<6>")
	)
	(segment
		(start 436.745634 -271.479772)
		(end 436.890414 -271.334992)
		(width 0.14478)
		(layer "In6.Cu")
		(net "M_K_CPU0_SB_CB<6>")
	)
	(segment
		(start 432.768756 -271.930368)
		(end 432.768756 -271.489932)
		(width 0.14478)
		(layer "In6.Cu")
		(net "M_K_CPU0_SB_CB<6>")
	)
	(segment
		(start 435.787546 -271.334992)
		(end 436.04942 -271.334992)
		(width 0.14478)
		(layer "In6.Cu")
		(net "M_K_CPU0_SB_CB<6>")
	)
	(segment
		(start 433.17541 -271.345152)
		(end 433.32019 -271.489932)
		(width 0.14478)
		(layer "In6.Cu")
		(net "M_K_CPU0_SB_CB<6>")
	)
	(segment
		(start 393.625832 -268.723364)
		(end 394.578586 -267.77061)
		(width 0.0889)
		(layer "In6.Cu")
		(net "M_K_CPU0_SB_CB<6>")
	)
	(segment
		(start 436.1942 -271.479772)
		(end 436.1942 -271.940528)
		(width 0.14478)
		(layer "In6.Cu")
		(net "M_K_CPU0_SB_CB<6>")
	)
	(segment
		(start 436.1942 -271.940528)
		(end 436.33898 -272.085308)
		(width 0.14478)
		(layer "In6.Cu")
		(net "M_K_CPU0_SB_CB<6>")
	)
	(segment
		(start 439.53938 -271.85493)
		(end 439.53938 -271.948148)
		(width 0.14478)
		(layer "In6.Cu")
		(net "M_K_CPU0_SB_CB<6>")
	)
	(segment
		(start 432.768756 -271.489932)
		(end 432.913536 -271.345152)
		(width 0.14478)
		(layer "In6.Cu")
		(net "M_K_CPU0_SB_CB<6>")
	)
	(segment
		(start 437.297068 -271.479772)
		(end 437.297068 -271.940528)
		(width 0.14478)
		(layer "In6.Cu")
		(net "M_K_CPU0_SB_CB<6>")
	)
	(segment
		(start 392.257788 -268.90345)
		(end 392.26617 -268.898624)
		(width 0.0889)
		(layer "In6.Cu")
		(net "M_K_CPU0_SB_CB<6>")
	)
	(segment
		(start 414.183068 -272.560034)
		(end 415.032952 -271.71015)
		(width 0.14478)
		(layer "In6.Cu")
		(net "M_K_CPU0_SB_CB<6>")
	)
	(segment
		(start 432.217322 -271.930368)
		(end 432.362102 -272.075148)
		(width 0.14478)
		(layer "In6.Cu")
		(net "M_K_CPU0_SB_CB<6>")
	)
	(segment
		(start 439.68416 -272.092928)
		(end 439.946034 -272.092928)
		(width 0.14478)
		(layer "In6.Cu")
		(net "M_K_CPU0_SB_CB<6>")
	)
	(segment
		(start 433.871624 -271.930368)
		(end 433.871624 -271.489932)
		(width 0.14478)
		(layer "In6.Cu")
		(net "M_K_CPU0_SB_CB<6>")
	)
	(segment
		(start 395.996922 -267.77061)
		(end 407.267156 -267.77061)
		(width 0.14478)
		(layer "In6.Cu")
		(net "M_K_CPU0_SB_CB<6>")
	)
	(segment
		(start 440.090814 -271.948148)
		(end 440.090814 -271.472152)
		(width 0.14478)
		(layer "In6.Cu")
		(net "M_K_CPU0_SB_CB<6>")
	)
	(segment
		(start 394.578586 -267.77061)
		(end 395.996922 -267.77061)
		(width 0.0889)
		(layer "In6.Cu")
		(net "M_K_CPU0_SB_CB<6>")
	)
	(segment
		(start 437.848502 -271.940528)
		(end 437.848502 -271.479772)
		(width 0.14478)
		(layer "In6.Cu")
		(net "M_K_CPU0_SB_CB<6>")
	)
	(segment
		(start 437.703722 -272.085308)
		(end 437.848502 -271.940528)
		(width 0.14478)
		(layer "In6.Cu")
		(net "M_K_CPU0_SB_CB<6>")
	)
	(segment
		(start 438.399936 -271.479772)
		(end 438.399936 -271.56537)
		(width 0.14478)
		(layer "In6.Cu")
		(net "M_K_CPU0_SB_CB<6>")
	)
	(arc
		(start 392.63193 -268.90345)
		(mid 392.914886 -268.979627)
		(end 393.197842 -268.90345)
		(width 0.0889)
		(layer "In6.Cu")
		(net "M_K_CPU0_SB_CB<6>")
	)
	(arc
		(start 391.82675 -269.690596)
		(mid 392.005563 -269.488246)
		(end 392.070082 -269.22603)
		(width 0.0889)
		(layer "In6.Cu")
		(net "M_K_CPU0_SB_CB<6>")
	)
	(arc
		(start 390.903206 -269.687294)
		(mid 391.065395 -269.664559)
		(end 391.221722 -269.713456)
		(width 0.0889)
		(layer "In6.Cu")
		(net "M_K_CPU0_SB_CB<6>")
	)
	(arc
		(start 392.26617 -268.898624)
		(mid 392.449678 -268.85313)
		(end 392.63193 -268.90345)
		(width 0.0889)
		(layer "In6.Cu")
		(net "M_K_CPU0_SB_CB<6>")
	)
	(arc
		(start 392.070082 -269.22603)
		(mid 392.111337 -269.055059)
		(end 392.226038 -268.921738)
		(width 0.0889)
		(layer "In6.Cu")
		(net "M_K_CPU0_SB_CB<6>")
	)
	(arc
		(start 391.221722 -269.713456)
		(mid 391.504678 -269.789633)
		(end 391.787634 -269.713456)
		(width 0.0889)
		(layer "In6.Cu")
		(net "M_K_CPU0_SB_CB<6>")
	)
	(arc
		(start 393.197842 -268.90345)
		(mid 393.213709 -268.894922)
		(end 393.2301 -268.887448)
		(width 0.0889)
		(layer "In6.Cu")
		(net "M_K_CPU0_SB_CB<6>")
	)
	(segment
		(start 388.688072 -269.770098)
		(end 389.154924 -270.036036)
		(width 0.10668)
		(layer "F.Cu")
		(net "M_K_CPU0_SB_CB<5>")
	)
	(segment
		(start 406.77084 -268.22527)
		(end 411.955742 -273.410172)
		(width 0.14478)
		(layer "In6.Cu")
		(net "M_K_CPU0_SB_CB<5>")
	)
	(segment
		(start 418.238432 -272.560034)
		(end 419.08857 -273.410172)
		(width 0.14478)
		(layer "In6.Cu")
		(net "M_K_CPU0_SB_CB<5>")
	)
	(segment
		(start 425.666662 -272.560034)
		(end 426.5168 -273.410172)
		(width 0.14478)
		(layer "In6.Cu")
		(net "M_K_CPU0_SB_CB<5>")
	)
	(segment
		(start 414.940242 -272.560034)
		(end 418.238432 -272.560034)
		(width 0.14478)
		(layer "In6.Cu")
		(net "M_K_CPU0_SB_CB<5>")
	)
	(segment
		(start 392.153394 -270.363442)
		(end 392.161776 -270.358616)
		(width 0.0889)
		(layer "In6.Cu")
		(net "M_K_CPU0_SB_CB<5>")
	)
	(segment
		(start 394.54963 -268.58849)
		(end 395.155674 -268.58849)
		(width 0.0889)
		(layer "In6.Cu")
		(net "M_K_CPU0_SB_CB<5>")
	)
	(segment
		(start 429.178212 -273.410172)
		(end 430.02835 -272.560034)
		(width 0.14478)
		(layer "In6.Cu")
		(net "M_K_CPU0_SB_CB<5>")
	)
	(segment
		(start 441.71997 -273.410172)
		(end 446.219326 -273.410172)
		(width 0.14478)
		(layer "In6.Cu")
		(net "M_K_CPU0_SB_CB<5>")
	)
	(segment
		(start 414.090104 -273.410172)
		(end 414.940242 -272.560034)
		(width 0.14478)
		(layer "In6.Cu")
		(net "M_K_CPU0_SB_CB<5>")
	)
	(segment
		(start 426.5168 -273.410172)
		(end 429.178212 -273.410172)
		(width 0.14478)
		(layer "In6.Cu")
		(net "M_K_CPU0_SB_CB<5>")
	)
	(segment
		(start 421.634158 -273.410172)
		(end 422.484296 -272.560034)
		(width 0.14478)
		(layer "In6.Cu")
		(net "M_K_CPU0_SB_CB<5>")
	)
	(segment
		(start 422.484296 -272.560034)
		(end 425.666662 -272.560034)
		(width 0.14478)
		(layer "In6.Cu")
		(net "M_K_CPU0_SB_CB<5>")
	)
	(segment
		(start 430.02835 -272.560034)
		(end 440.869832 -272.560034)
		(width 0.14478)
		(layer "In6.Cu")
		(net "M_K_CPU0_SB_CB<5>")
	)
	(segment
		(start 419.08857 -273.410172)
		(end 421.634158 -273.410172)
		(width 0.14478)
		(layer "In6.Cu")
		(net "M_K_CPU0_SB_CB<5>")
	)
	(segment
		(start 389.154924 -270.036036)
		(end 389.308848 -270.301466)
		(width 0.0889)
		(layer "In6.Cu")
		(net "M_K_CPU0_SB_CB<5>")
	)
	(segment
		(start 389.308848 -270.301466)
		(end 389.40486 -270.326866)
		(width 0.0889)
		(layer "In6.Cu")
		(net "M_K_CPU0_SB_CB<5>")
	)
	(segment
		(start 393.648438 -269.489682)
		(end 394.54963 -268.58849)
		(width 0.0889)
		(layer "In6.Cu")
		(net "M_K_CPU0_SB_CB<5>")
	)
	(segment
		(start 395.518894 -268.22527)
		(end 395.97457 -268.22527)
		(width 0.0889)
		(layer "In6.Cu")
		(net "M_K_CPU0_SB_CB<5>")
	)
	(segment
		(start 393.197842 -269.54861)
		(end 393.206224 -269.553436)
		(width 0.0889)
		(layer "In6.Cu")
		(net "M_K_CPU0_SB_CB<5>")
	)
	(segment
		(start 389.90778 -270.358616)
		(end 389.916162 -270.363442)
		(width 0.0889)
		(layer "In6.Cu")
		(net "M_K_CPU0_SB_CB<5>")
	)
	(segment
		(start 411.955742 -273.410172)
		(end 414.090104 -273.410172)
		(width 0.14478)
		(layer "In6.Cu")
		(net "M_K_CPU0_SB_CB<5>")
	)
	(segment
		(start 392.161776 -270.358616)
		(end 392.193526 -270.340328)
		(width 0.0889)
		(layer "In6.Cu")
		(net "M_K_CPU0_SB_CB<5>")
	)
	(segment
		(start 392.592814 -269.57147)
		(end 392.63193 -269.54861)
		(width 0.0889)
		(layer "In6.Cu")
		(net "M_K_CPU0_SB_CB<5>")
	)
	(segment
		(start 395.155674 -268.58849)
		(end 395.518894 -268.22527)
		(width 0.0889)
		(layer "In6.Cu")
		(net "M_K_CPU0_SB_CB<5>")
	)
	(segment
		(start 446.219326 -273.410172)
		(end 446.644268 -273.835114)
		(width 0.14478)
		(layer "In6.Cu")
		(net "M_K_CPU0_SB_CB<5>")
	)
	(segment
		(start 440.869832 -272.560034)
		(end 441.71997 -273.410172)
		(width 0.14478)
		(layer "In6.Cu")
		(net "M_K_CPU0_SB_CB<5>")
	)
	(segment
		(start 395.97457 -268.22527)
		(end 406.77084 -268.22527)
		(width 0.14478)
		(layer "In6.Cu")
		(net "M_K_CPU0_SB_CB<5>")
	)
	(arc
		(start 393.571984 -269.54861)
		(mid 393.612129 -269.521634)
		(end 393.648438 -269.489682)
		(width 0.0889)
		(layer "In6.Cu")
		(net "M_K_CPU0_SB_CB<5>")
	)
	(arc
		(start 390.281922 -270.358616)
		(mid 390.564878 -270.282439)
		(end 390.847834 -270.358616)
		(width 0.0889)
		(layer "In6.Cu")
		(net "M_K_CPU0_SB_CB<5>")
	)
	(arc
		(start 392.349482 -270.036036)
		(mid 392.413997 -269.773817)
		(end 392.592814 -269.57147)
		(width 0.0889)
		(layer "In6.Cu")
		(net "M_K_CPU0_SB_CB<5>")
	)
	(arc
		(start 393.206224 -269.553436)
		(mid 393.389732 -269.59893)
		(end 393.571984 -269.54861)
		(width 0.0889)
		(layer "In6.Cu")
		(net "M_K_CPU0_SB_CB<5>")
	)
	(arc
		(start 389.916162 -270.363442)
		(mid 390.09967 -270.408936)
		(end 390.281922 -270.358616)
		(width 0.0889)
		(layer "In6.Cu")
		(net "M_K_CPU0_SB_CB<5>")
	)
	(arc
		(start 392.63193 -269.54861)
		(mid 392.914886 -269.472433)
		(end 393.197842 -269.54861)
		(width 0.0889)
		(layer "In6.Cu")
		(net "M_K_CPU0_SB_CB<5>")
	)
	(arc
		(start 391.787634 -270.358616)
		(mid 391.969885 -270.408966)
		(end 392.153394 -270.363442)
		(width 0.0889)
		(layer "In6.Cu")
		(net "M_K_CPU0_SB_CB<5>")
	)
	(arc
		(start 390.847834 -270.358616)
		(mid 391.034778 -270.408871)
		(end 391.221722 -270.358616)
		(width 0.0889)
		(layer "In6.Cu")
		(net "M_K_CPU0_SB_CB<5>")
	)
	(arc
		(start 392.193526 -270.340328)
		(mid 392.308202 -270.206994)
		(end 392.349482 -270.036036)
		(width 0.0889)
		(layer "In6.Cu")
		(net "M_K_CPU0_SB_CB<5>")
	)
	(arc
		(start 391.221722 -270.358616)
		(mid 391.504678 -270.282439)
		(end 391.787634 -270.358616)
		(width 0.0889)
		(layer "In6.Cu")
		(net "M_K_CPU0_SB_CB<5>")
	)
	(arc
		(start 389.40486 -270.326866)
		(mid 389.660068 -270.283389)
		(end 389.90778 -270.358616)
		(width 0.0889)
		(layer "In6.Cu")
		(net "M_K_CPU0_SB_CB<5>")
	)
	(segment
		(start 390.098026 -268.960092)
		(end 390.564878 -269.22603)
		(width 0.10668)
		(layer "F.Cu")
		(net "M_K_CPU0_SB_CB<4>")
	)
	(segment
		(start 443.800738 -271.373092)
		(end 443.800738 -271.004792)
		(width 0.14478)
		(layer "In6.Cu")
		(net "M_K_CPU0_SB_CB<4>")
	)
	(segment
		(start 417.884356 -270.860012)
		(end 418.73424 -271.709896)
		(width 0.14478)
		(layer "In6.Cu")
		(net "M_K_CPU0_SB_CB<4>")
	)
	(segment
		(start 415.15792 -270.860012)
		(end 417.884356 -270.860012)
		(width 0.14478)
		(layer "In6.Cu")
		(net "M_K_CPU0_SB_CB<4>")
	)
	(segment
		(start 414.308036 -271.709896)
		(end 415.15792 -270.860012)
		(width 0.14478)
		(layer "In6.Cu")
		(net "M_K_CPU0_SB_CB<4>")
	)
	(segment
		(start 443.249304 -271.373092)
		(end 443.394084 -271.517872)
		(width 0.14478)
		(layer "In6.Cu")
		(net "M_K_CPU0_SB_CB<4>")
	)
	(segment
		(start 422.691306 -270.860012)
		(end 425.45127 -270.860012)
		(width 0.14478)
		(layer "In6.Cu")
		(net "M_K_CPU0_SB_CB<4>")
	)
	(segment
		(start 444.903606 -271.004792)
		(end 445.048386 -270.860012)
		(width 0.14478)
		(layer "In6.Cu")
		(net "M_K_CPU0_SB_CB<4>")
	)
	(segment
		(start 443.655958 -271.517872)
		(end 443.800738 -271.373092)
		(width 0.14478)
		(layer "In6.Cu")
		(net "M_K_CPU0_SB_CB<4>")
	)
	(segment
		(start 391.317734 -269.54861)
		(end 391.326116 -269.553436)
		(width 0.0889)
		(layer "In6.Cu")
		(net "M_K_CPU0_SB_CB<4>")
	)
	(segment
		(start 414.08985 -271.71015)
		(end 414.090104 -271.709896)
		(width 0.14478)
		(layer "In6.Cu")
		(net "M_K_CPU0_SB_CB<4>")
	)
	(segment
		(start 444.352172 -271.004792)
		(end 444.352172 -271.373092)
		(width 0.14478)
		(layer "In6.Cu")
		(net "M_K_CPU0_SB_CB<4>")
	)
	(segment
		(start 443.394084 -271.517872)
		(end 443.655958 -271.517872)
		(width 0.14478)
		(layer "In6.Cu")
		(net "M_K_CPU0_SB_CB<4>")
	)
	(segment
		(start 444.496952 -271.517872)
		(end 444.758826 -271.517872)
		(width 0.14478)
		(layer "In6.Cu")
		(net "M_K_CPU0_SB_CB<4>")
	)
	(segment
		(start 418.73424 -271.709896)
		(end 421.841422 -271.709896)
		(width 0.14478)
		(layer "In6.Cu")
		(net "M_K_CPU0_SB_CB<4>")
	)
	(segment
		(start 393.390374 -268.613382)
		(end 393.502134 -268.538706)
		(width 0.0889)
		(layer "In6.Cu")
		(net "M_K_CPU0_SB_CB<4>")
	)
	(segment
		(start 391.691876 -269.54861)
		(end 391.722356 -269.53083)
		(width 0.0889)
		(layer "In6.Cu")
		(net "M_K_CPU0_SB_CB<4>")
	)
	(segment
		(start 425.45127 -270.860012)
		(end 426.301154 -271.709896)
		(width 0.14478)
		(layer "In6.Cu")
		(net "M_K_CPU0_SB_CB<4>")
	)
	(segment
		(start 443.249304 -271.004792)
		(end 443.249304 -271.373092)
		(width 0.14478)
		(layer "In6.Cu")
		(net "M_K_CPU0_SB_CB<4>")
	)
	(segment
		(start 426.301154 -271.709896)
		(end 429.393096 -271.709896)
		(width 0.14478)
		(layer "In6.Cu")
		(net "M_K_CPU0_SB_CB<4>")
	)
	(segment
		(start 390.718802 -269.49146)
		(end 390.814814 -269.51686)
		(width 0.0889)
		(layer "In6.Cu")
		(net "M_K_CPU0_SB_CB<4>")
	)
	(segment
		(start 444.207392 -270.860012)
		(end 444.352172 -271.004792)
		(width 0.14478)
		(layer "In6.Cu")
		(net "M_K_CPU0_SB_CB<4>")
	)
	(segment
		(start 443.945518 -270.860012)
		(end 444.207392 -270.860012)
		(width 0.14478)
		(layer "In6.Cu")
		(net "M_K_CPU0_SB_CB<4>")
	)
	(segment
		(start 392.12266 -268.761464)
		(end 392.161776 -268.738604)
		(width 0.0889)
		(layer "In6.Cu")
		(net "M_K_CPU0_SB_CB<4>")
	)
	(segment
		(start 430.24298 -270.860012)
		(end 443.104524 -270.860012)
		(width 0.14478)
		(layer "In6.Cu")
		(net "M_K_CPU0_SB_CB<4>")
	)
	(segment
		(start 393.17295 -268.703552)
		(end 393.390374 -268.613382)
		(width 0.0889)
		(layer "In6.Cu")
		(net "M_K_CPU0_SB_CB<4>")
	)
	(segment
		(start 445.369188 -270.860012)
		(end 446.644268 -272.135092)
		(width 0.14478)
		(layer "In6.Cu")
		(net "M_K_CPU0_SB_CB<4>")
	)
	(segment
		(start 394.72489 -267.31595)
		(end 395.914626 -267.31595)
		(width 0.0889)
		(layer "In6.Cu")
		(net "M_K_CPU0_SB_CB<4>")
	)
	(segment
		(start 414.090104 -271.709896)
		(end 414.308036 -271.709896)
		(width 0.14478)
		(layer "In6.Cu")
		(net "M_K_CPU0_SB_CB<4>")
	)
	(segment
		(start 407.634948 -267.31595)
		(end 412.029148 -271.71015)
		(width 0.14478)
		(layer "In6.Cu")
		(net "M_K_CPU0_SB_CB<4>")
	)
	(segment
		(start 443.800738 -271.004792)
		(end 443.945518 -270.860012)
		(width 0.14478)
		(layer "In6.Cu")
		(net "M_K_CPU0_SB_CB<4>")
	)
	(segment
		(start 444.352172 -271.373092)
		(end 444.496952 -271.517872)
		(width 0.14478)
		(layer "In6.Cu")
		(net "M_K_CPU0_SB_CB<4>")
	)
	(segment
		(start 444.758826 -271.517872)
		(end 444.903606 -271.373092)
		(width 0.14478)
		(layer "In6.Cu")
		(net "M_K_CPU0_SB_CB<4>")
	)
	(segment
		(start 429.393096 -271.709896)
		(end 430.24298 -270.860012)
		(width 0.14478)
		(layer "In6.Cu")
		(net "M_K_CPU0_SB_CB<4>")
	)
	(segment
		(start 390.564878 -269.22603)
		(end 390.718802 -269.49146)
		(width 0.0889)
		(layer "In6.Cu")
		(net "M_K_CPU0_SB_CB<4>")
	)
	(segment
		(start 443.104524 -270.860012)
		(end 443.249304 -271.004792)
		(width 0.14478)
		(layer "In6.Cu")
		(net "M_K_CPU0_SB_CB<4>")
	)
	(segment
		(start 421.841422 -271.709896)
		(end 422.691306 -270.860012)
		(width 0.14478)
		(layer "In6.Cu")
		(net "M_K_CPU0_SB_CB<4>")
	)
	(segment
		(start 393.502134 -268.538706)
		(end 394.72489 -267.31595)
		(width 0.0889)
		(layer "In6.Cu")
		(net "M_K_CPU0_SB_CB<4>")
	)
	(segment
		(start 445.048386 -270.860012)
		(end 445.369188 -270.860012)
		(width 0.14478)
		(layer "In6.Cu")
		(net "M_K_CPU0_SB_CB<4>")
	)
	(segment
		(start 412.029148 -271.71015)
		(end 414.08985 -271.71015)
		(width 0.14478)
		(layer "In6.Cu")
		(net "M_K_CPU0_SB_CB<4>")
	)
	(segment
		(start 444.903606 -271.373092)
		(end 444.903606 -271.004792)
		(width 0.14478)
		(layer "In6.Cu")
		(net "M_K_CPU0_SB_CB<4>")
	)
	(segment
		(start 395.914626 -267.31595)
		(end 407.634948 -267.31595)
		(width 0.14478)
		(layer "In6.Cu")
		(net "M_K_CPU0_SB_CB<4>")
	)
	(arc
		(start 391.326116 -269.553436)
		(mid 391.509624 -269.59893)
		(end 391.691876 -269.54861)
		(width 0.0889)
		(layer "In6.Cu")
		(net "M_K_CPU0_SB_CB<4>")
	)
	(arc
		(start 392.161776 -268.738604)
		(mid 392.444732 -268.662427)
		(end 392.727688 -268.738604)
		(width 0.0889)
		(layer "In6.Cu")
		(net "M_K_CPU0_SB_CB<4>")
	)
	(arc
		(start 391.722356 -269.53083)
		(mid 391.837783 -269.397454)
		(end 391.879328 -269.22603)
		(width 0.0889)
		(layer "In6.Cu")
		(net "M_K_CPU0_SB_CB<4>")
	)
	(arc
		(start 391.879328 -269.22603)
		(mid 391.943843 -268.963811)
		(end 392.12266 -268.761464)
		(width 0.0889)
		(layer "In6.Cu")
		(net "M_K_CPU0_SB_CB<4>")
	)
	(arc
		(start 390.814814 -269.51686)
		(mid 391.070022 -269.473383)
		(end 391.317734 -269.54861)
		(width 0.0889)
		(layer "In6.Cu")
		(net "M_K_CPU0_SB_CB<4>")
	)
	(arc
		(start 393.093448 -268.74343)
		(mid 393.132407 -268.721911)
		(end 393.17295 -268.703552)
		(width 0.0889)
		(layer "In6.Cu")
		(net "M_K_CPU0_SB_CB<4>")
	)
	(arc
		(start 392.727688 -268.738604)
		(mid 392.909939 -268.788954)
		(end 393.093448 -268.74343)
		(width 0.0889)
		(layer "In6.Cu")
		(net "M_K_CPU0_SB_CB<4>")
	)
	(segment
		(start 389.157972 -273.820128)
		(end 389.624824 -274.086066)
		(width 0.10668)
		(layer "F.Cu")
		(net "M_K_CPU0_SB_CB<3>")
	)
	(segment
		(start 404.601426 -274.035774)
		(end 404.83155 -274.03552)
		(width 0.14478)
		(layer "In6.Cu")
		(net "M_K_CPU0_SB_CB<3>")
	)
	(segment
		(start 392.24712 -273.769582)
		(end 392.257534 -273.763486)
		(width 0.0889)
		(layer "In6.Cu")
		(net "M_K_CPU0_SB_CB<3>")
	)
	(segment
		(start 405.225504 -274.659852)
		(end 405.388826 -274.823174)
		(width 0.14478)
		(layer "In6.Cu")
		(net "M_K_CPU0_SB_CB<3>")
	)
	(segment
		(start 406.170892 -275.420582)
		(end 406.170638 -275.650706)
		(width 0.14478)
		(layer "In6.Cu")
		(net "M_K_CPU0_SB_CB<3>")
	)
	(segment
		(start 395.440154 -272.49247)
		(end 395.549374 -272.38325)
		(width 0.0889)
		(layer "In6.Cu")
		(net "M_K_CPU0_SB_CB<3>")
	)
	(segment
		(start 404.83155 -274.03552)
		(end 404.992586 -273.874484)
		(width 0.14478)
		(layer "In6.Cu")
		(net "M_K_CPU0_SB_CB<3>")
	)
	(segment
		(start 406.33396 -275.814028)
		(end 406.564592 -275.814028)
		(width 0.14478)
		(layer "In6.Cu")
		(net "M_K_CPU0_SB_CB<3>")
	)
	(segment
		(start 403.814026 -273.248374)
		(end 404.04415 -273.24812)
		(width 0.14478)
		(layer "In6.Cu")
		(net "M_K_CPU0_SB_CB<3>")
	)
	(segment
		(start 392.257534 -273.763486)
		(end 392.265916 -273.75866)
		(width 0.0889)
		(layer "In6.Cu")
		(net "M_K_CPU0_SB_CB<3>")
	)
	(segment
		(start 406.97912 -275.630386)
		(end 407.338022 -275.989288)
		(width 0.14478)
		(layer "In6.Cu")
		(net "M_K_CPU0_SB_CB<3>")
	)
	(segment
		(start 414.940242 -280.210006)
		(end 418.471096 -280.210006)
		(width 0.14478)
		(layer "In6.Cu")
		(net "M_K_CPU0_SB_CB<3>")
	)
	(segment
		(start 430.02835 -280.210006)
		(end 433.145438 -280.210006)
		(width 0.14478)
		(layer "In6.Cu")
		(net "M_K_CPU0_SB_CB<3>")
	)
	(segment
		(start 404.438104 -273.872452)
		(end 404.601426 -274.035774)
		(width 0.14478)
		(layer "In6.Cu")
		(net "M_K_CPU0_SB_CB<3>")
	)
	(segment
		(start 422.065704 -280.210006)
		(end 425.91355 -280.210006)
		(width 0.14478)
		(layer "In6.Cu")
		(net "M_K_CPU0_SB_CB<3>")
	)
	(segment
		(start 405.388826 -274.823174)
		(end 405.61895 -274.82292)
		(width 0.14478)
		(layer "In6.Cu")
		(net "M_K_CPU0_SB_CB<3>")
	)
	(segment
		(start 406.748488 -275.630132)
		(end 406.97912 -275.630386)
		(width 0.14478)
		(layer "In6.Cu")
		(net "M_K_CPU0_SB_CB<3>")
	)
	(segment
		(start 405.225504 -274.42922)
		(end 405.225504 -274.659852)
		(width 0.14478)
		(layer "In6.Cu")
		(net "M_K_CPU0_SB_CB<3>")
	)
	(segment
		(start 406.354788 -275.236686)
		(end 406.170892 -275.420582)
		(width 0.14478)
		(layer "In6.Cu")
		(net "M_K_CPU0_SB_CB<3>")
	)
	(segment
		(start 404.992586 -273.874484)
		(end 405.223218 -273.874484)
		(width 0.14478)
		(layer "In6.Cu")
		(net "M_K_CPU0_SB_CB<3>")
	)
	(segment
		(start 436.874412 -280.210006)
		(end 442.119258 -280.210006)
		(width 0.14478)
		(layer "In6.Cu")
		(net "M_K_CPU0_SB_CB<3>")
	)
	(segment
		(start 403.610064 -272.38325)
		(end 403.759924 -272.53311)
		(width 0.14478)
		(layer "In6.Cu")
		(net "M_K_CPU0_SB_CB<3>")
	)
	(segment
		(start 429.178212 -281.060144)
		(end 430.02835 -280.210006)
		(width 0.14478)
		(layer "In6.Cu")
		(net "M_K_CPU0_SB_CB<3>")
	)
	(segment
		(start 406.564592 -275.814028)
		(end 406.748488 -275.630132)
		(width 0.14478)
		(layer "In6.Cu")
		(net "M_K_CPU0_SB_CB<3>")
	)
	(segment
		(start 405.386286 -274.037552)
		(end 405.38654 -274.268184)
		(width 0.14478)
		(layer "In6.Cu")
		(net "M_K_CPU0_SB_CB<3>")
	)
	(segment
		(start 403.650704 -273.085052)
		(end 403.814026 -273.248374)
		(width 0.14478)
		(layer "In6.Cu")
		(net "M_K_CPU0_SB_CB<3>")
	)
	(segment
		(start 405.38654 -274.268184)
		(end 405.225504 -274.42922)
		(width 0.14478)
		(layer "In6.Cu")
		(net "M_K_CPU0_SB_CB<3>")
	)
	(segment
		(start 403.650704 -272.85442)
		(end 403.650704 -273.085052)
		(width 0.14478)
		(layer "In6.Cu")
		(net "M_K_CPU0_SB_CB<3>")
	)
	(segment
		(start 426.763688 -281.060144)
		(end 429.178212 -281.060144)
		(width 0.14478)
		(layer "In6.Cu")
		(net "M_K_CPU0_SB_CB<3>")
	)
	(segment
		(start 404.04415 -273.24812)
		(end 404.205186 -273.087084)
		(width 0.14478)
		(layer "In6.Cu")
		(net "M_K_CPU0_SB_CB<3>")
	)
	(segment
		(start 406.010618 -274.661884)
		(end 406.354788 -275.006054)
		(width 0.14478)
		(layer "In6.Cu")
		(net "M_K_CPU0_SB_CB<3>")
	)
	(segment
		(start 392.631168 -273.763486)
		(end 392.641582 -273.769582)
		(width 0.0889)
		(layer "In6.Cu")
		(net "M_K_CPU0_SB_CB<3>")
	)
	(segment
		(start 395.549374 -272.38325)
		(end 396.00886 -272.38325)
		(width 0.0889)
		(layer "In6.Cu")
		(net "M_K_CPU0_SB_CB<3>")
	)
	(segment
		(start 405.223218 -273.874484)
		(end 405.386286 -274.037552)
		(width 0.14478)
		(layer "In6.Cu")
		(net "M_K_CPU0_SB_CB<3>")
	)
	(segment
		(start 407.338022 -275.989288)
		(end 407.338022 -276.823424)
		(width 0.14478)
		(layer "In6.Cu")
		(net "M_K_CPU0_SB_CB<3>")
	)
	(segment
		(start 389.624824 -274.086066)
		(end 389.4709 -273.820636)
		(width 0.0889)
		(layer "In6.Cu")
		(net "M_K_CPU0_SB_CB<3>")
	)
	(segment
		(start 419.321234 -281.060144)
		(end 421.215566 -281.060144)
		(width 0.14478)
		(layer "In6.Cu")
		(net "M_K_CPU0_SB_CB<3>")
	)
	(segment
		(start 390.74344 -273.75866)
		(end 390.751822 -273.763486)
		(width 0.0889)
		(layer "In6.Cu")
		(net "M_K_CPU0_SB_CB<3>")
	)
	(segment
		(start 404.598886 -273.250152)
		(end 404.59914 -273.480784)
		(width 0.14478)
		(layer "In6.Cu")
		(net "M_K_CPU0_SB_CB<3>")
	)
	(segment
		(start 406.354788 -275.006054)
		(end 406.354788 -275.236686)
		(width 0.14478)
		(layer "In6.Cu")
		(net "M_K_CPU0_SB_CB<3>")
	)
	(segment
		(start 404.205186 -273.087084)
		(end 404.435818 -273.087084)
		(width 0.14478)
		(layer "In6.Cu")
		(net "M_K_CPU0_SB_CB<3>")
	)
	(segment
		(start 421.215566 -281.060144)
		(end 422.065704 -280.210006)
		(width 0.14478)
		(layer "In6.Cu")
		(net "M_K_CPU0_SB_CB<3>")
	)
	(segment
		(start 405.779986 -274.661884)
		(end 406.010618 -274.661884)
		(width 0.14478)
		(layer "In6.Cu")
		(net "M_K_CPU0_SB_CB<3>")
	)
	(segment
		(start 403.759924 -272.53311)
		(end 403.759924 -272.7452)
		(width 0.14478)
		(layer "In6.Cu")
		(net "M_K_CPU0_SB_CB<3>")
	)
	(segment
		(start 389.4709 -273.820636)
		(end 389.493252 -273.737324)
		(width 0.0889)
		(layer "In6.Cu")
		(net "M_K_CPU0_SB_CB<3>")
	)
	(segment
		(start 404.59914 -273.480784)
		(end 404.438104 -273.64182)
		(width 0.14478)
		(layer "In6.Cu")
		(net "M_K_CPU0_SB_CB<3>")
	)
	(segment
		(start 404.435818 -273.087084)
		(end 404.598886 -273.250152)
		(width 0.14478)
		(layer "In6.Cu")
		(net "M_K_CPU0_SB_CB<3>")
	)
	(segment
		(start 406.170638 -275.650706)
		(end 406.33396 -275.814028)
		(width 0.14478)
		(layer "In6.Cu")
		(net "M_K_CPU0_SB_CB<3>")
	)
	(segment
		(start 405.61895 -274.82292)
		(end 405.779986 -274.661884)
		(width 0.14478)
		(layer "In6.Cu")
		(net "M_K_CPU0_SB_CB<3>")
	)
	(segment
		(start 442.119258 -280.210006)
		(end 442.5442 -280.634948)
		(width 0.14478)
		(layer "In6.Cu")
		(net "M_K_CPU0_SB_CB<3>")
	)
	(segment
		(start 418.471096 -280.210006)
		(end 419.321234 -281.060144)
		(width 0.14478)
		(layer "In6.Cu")
		(net "M_K_CPU0_SB_CB<3>")
	)
	(segment
		(start 393.7381 -273.668744)
		(end 394.914374 -272.49247)
		(width 0.0889)
		(layer "In6.Cu")
		(net "M_K_CPU0_SB_CB<3>")
	)
	(segment
		(start 433.995576 -281.060144)
		(end 436.024274 -281.060144)
		(width 0.14478)
		(layer "In6.Cu")
		(net "M_K_CPU0_SB_CB<3>")
	)
	(segment
		(start 407.338022 -276.823424)
		(end 411.574742 -281.060144)
		(width 0.14478)
		(layer "In6.Cu")
		(net "M_K_CPU0_SB_CB<3>")
	)
	(segment
		(start 414.090104 -281.060144)
		(end 414.940242 -280.210006)
		(width 0.14478)
		(layer "In6.Cu")
		(net "M_K_CPU0_SB_CB<3>")
	)
	(segment
		(start 404.438104 -273.64182)
		(end 404.438104 -273.872452)
		(width 0.14478)
		(layer "In6.Cu")
		(net "M_K_CPU0_SB_CB<3>")
	)
	(segment
		(start 403.759924 -272.7452)
		(end 403.650704 -272.85442)
		(width 0.14478)
		(layer "In6.Cu")
		(net "M_K_CPU0_SB_CB<3>")
	)
	(segment
		(start 425.91355 -280.210006)
		(end 426.763688 -281.060144)
		(width 0.14478)
		(layer "In6.Cu")
		(net "M_K_CPU0_SB_CB<3>")
	)
	(segment
		(start 394.914374 -272.49247)
		(end 395.440154 -272.49247)
		(width 0.0889)
		(layer "In6.Cu")
		(net "M_K_CPU0_SB_CB<3>")
	)
	(segment
		(start 433.145438 -280.210006)
		(end 433.995576 -281.060144)
		(width 0.14478)
		(layer "In6.Cu")
		(net "M_K_CPU0_SB_CB<3>")
	)
	(segment
		(start 411.574742 -281.060144)
		(end 414.090104 -281.060144)
		(width 0.14478)
		(layer "In6.Cu")
		(net "M_K_CPU0_SB_CB<3>")
	)
	(segment
		(start 391.317734 -273.763486)
		(end 391.326116 -273.75866)
		(width 0.0889)
		(layer "In6.Cu")
		(net "M_K_CPU0_SB_CB<3>")
	)
	(segment
		(start 436.024274 -281.060144)
		(end 436.874412 -280.210006)
		(width 0.14478)
		(layer "In6.Cu")
		(net "M_K_CPU0_SB_CB<3>")
	)
	(segment
		(start 396.00886 -272.38325)
		(end 403.610064 -272.38325)
		(width 0.14478)
		(layer "In6.Cu")
		(net "M_K_CPU0_SB_CB<3>")
	)
	(arc
		(start 392.641582 -273.769582)
		(mid 392.920268 -273.839802)
		(end 393.197334 -273.763486)
		(width 0.0889)
		(layer "In6.Cu")
		(net "M_K_CPU0_SB_CB<3>")
	)
	(arc
		(start 391.326116 -273.75866)
		(mid 391.509624 -273.713166)
		(end 391.691876 -273.763486)
		(width 0.0889)
		(layer "In6.Cu")
		(net "M_K_CPU0_SB_CB<3>")
	)
	(arc
		(start 393.433046 -273.70659)
		(mid 393.539853 -273.709409)
		(end 393.64666 -273.70659)
		(width 0.0889)
		(layer "In6.Cu")
		(net "M_K_CPU0_SB_CB<3>")
	)
	(arc
		(start 389.811768 -273.763486)
		(mid 390.094724 -273.839663)
		(end 390.37768 -273.763486)
		(width 0.0889)
		(layer "In6.Cu")
		(net "M_K_CPU0_SB_CB<3>")
	)
	(arc
		(start 392.265916 -273.75866)
		(mid 392.44917 -273.713287)
		(end 392.631168 -273.763486)
		(width 0.0889)
		(layer "In6.Cu")
		(net "M_K_CPU0_SB_CB<3>")
	)
	(arc
		(start 390.37768 -273.763486)
		(mid 390.559931 -273.713136)
		(end 390.74344 -273.75866)
		(width 0.0889)
		(layer "In6.Cu")
		(net "M_K_CPU0_SB_CB<3>")
	)
	(arc
		(start 389.493252 -273.737324)
		(mid 389.655441 -273.714589)
		(end 389.811768 -273.763486)
		(width 0.0889)
		(layer "In6.Cu")
		(net "M_K_CPU0_SB_CB<3>")
	)
	(arc
		(start 393.64666 -273.70659)
		(mid 393.695619 -273.695497)
		(end 393.7381 -273.668744)
		(width 0.0889)
		(layer "In6.Cu")
		(net "M_K_CPU0_SB_CB<3>")
	)
	(arc
		(start 393.197334 -273.763486)
		(mid 393.311044 -273.717866)
		(end 393.433046 -273.70659)
		(width 0.0889)
		(layer "In6.Cu")
		(net "M_K_CPU0_SB_CB<3>")
	)
	(arc
		(start 391.691876 -273.763486)
		(mid 391.968689 -273.839629)
		(end 392.24712 -273.769582)
		(width 0.0889)
		(layer "In6.Cu")
		(net "M_K_CPU0_SB_CB<3>")
	)
	(arc
		(start 390.751822 -273.763486)
		(mid 391.034778 -273.839663)
		(end 391.317734 -273.763486)
		(width 0.0889)
		(layer "In6.Cu")
		(net "M_K_CPU0_SB_CB<3>")
	)
	(segment
		(start 390.567926 -273.010122)
		(end 391.034778 -273.27606)
		(width 0.10668)
		(layer "F.Cu")
		(net "M_K_CPU0_SB_CB<2>")
	)
	(segment
		(start 422.484296 -278.509984)
		(end 425.495974 -278.509984)
		(width 0.14478)
		(layer "In6.Cu")
		(net "M_K_CPU0_SB_CB<2>")
	)
	(segment
		(start 409.0162 -276.950424)
		(end 409.303474 -276.66315)
		(width 0.14478)
		(layer "In6.Cu")
		(net "M_K_CPU0_SB_CB<2>")
	)
	(segment
		(start 436.454042 -279.360122)
		(end 437.30418 -278.509984)
		(width 0.14478)
		(layer "In6.Cu")
		(net "M_K_CPU0_SB_CB<2>")
	)
	(segment
		(start 410.090874 -277.45055)
		(end 410.321506 -277.45055)
		(width 0.14478)
		(layer "In6.Cu")
		(net "M_K_CPU0_SB_CB<2>")
	)
	(segment
		(start 439.619136 -278.509984)
		(end 439.763916 -278.365204)
		(width 0.14478)
		(layer "In6.Cu")
		(net "M_K_CPU0_SB_CB<2>")
	)
	(segment
		(start 440.31535 -278.284432)
		(end 440.31535 -278.735536)
		(width 0.14478)
		(layer "In6.Cu")
		(net "M_K_CPU0_SB_CB<2>")
	)
	(segment
		(start 440.722004 -278.880316)
		(end 440.866784 -278.735536)
		(width 0.14478)
		(layer "In6.Cu")
		(net "M_K_CPU0_SB_CB<2>")
	)
	(segment
		(start 408.909774 -276.038818)
		(end 408.909774 -276.26945)
		(width 0.14478)
		(layer "In6.Cu")
		(net "M_K_CPU0_SB_CB<2>")
	)
	(segment
		(start 408.785568 -276.950424)
		(end 409.0162 -276.950424)
		(width 0.14478)
		(layer "In6.Cu")
		(net "M_K_CPU0_SB_CB<2>")
	)
	(segment
		(start 414.723834 -278.509984)
		(end 418.286184 -278.509984)
		(width 0.14478)
		(layer "In6.Cu")
		(net "M_K_CPU0_SB_CB<2>")
	)
	(segment
		(start 395.134846 -271.75587)
		(end 395.416786 -271.47393)
		(width 0.0889)
		(layer "In6.Cu")
		(net "M_K_CPU0_SB_CB<2>")
	)
	(segment
		(start 440.17057 -278.139652)
		(end 440.31535 -278.284432)
		(width 0.14478)
		(layer "In6.Cu")
		(net "M_K_CPU0_SB_CB<2>")
	)
	(segment
		(start 439.908696 -278.139652)
		(end 440.17057 -278.139652)
		(width 0.14478)
		(layer "In6.Cu")
		(net "M_K_CPU0_SB_CB<2>")
	)
	(segment
		(start 439.763916 -278.365204)
		(end 439.763916 -278.284432)
		(width 0.14478)
		(layer "In6.Cu")
		(net "M_K_CPU0_SB_CB<2>")
	)
	(segment
		(start 409.697174 -277.05685)
		(end 409.4099 -277.344124)
		(width 0.14478)
		(layer "In6.Cu")
		(net "M_K_CPU0_SB_CB<2>")
	)
	(segment
		(start 410.1973 -278.131524)
		(end 410.1973 -278.362156)
		(width 0.14478)
		(layer "In6.Cu")
		(net "M_K_CPU0_SB_CB<2>")
	)
	(segment
		(start 410.321506 -277.45055)
		(end 410.484574 -277.613618)
		(width 0.14478)
		(layer "In6.Cu")
		(net "M_K_CPU0_SB_CB<2>")
	)
	(segment
		(start 394.949426 -271.75587)
		(end 395.134846 -271.75587)
		(width 0.0889)
		(layer "In6.Cu")
		(net "M_K_CPU0_SB_CB<2>")
	)
	(segment
		(start 409.303474 -276.66315)
		(end 409.534106 -276.66315)
		(width 0.14478)
		(layer "In6.Cu")
		(net "M_K_CPU0_SB_CB<2>")
	)
	(segment
		(start 429.760126 -278.509984)
		(end 433.080668 -278.509984)
		(width 0.14478)
		(layer "In6.Cu")
		(net "M_K_CPU0_SB_CB<2>")
	)
	(segment
		(start 390.880854 -273.01063)
		(end 390.903206 -272.927318)
		(width 0.0889)
		(layer "In6.Cu")
		(net "M_K_CPU0_SB_CB<2>")
	)
	(segment
		(start 410.484574 -277.613618)
		(end 410.484574 -277.84425)
		(width 0.14478)
		(layer "In6.Cu")
		(net "M_K_CPU0_SB_CB<2>")
	)
	(segment
		(start 392.727434 -272.95348)
		(end 392.735816 -272.948654)
		(width 0.0889)
		(layer "In6.Cu")
		(net "M_K_CPU0_SB_CB<2>")
	)
	(segment
		(start 440.46013 -278.880316)
		(end 440.722004 -278.880316)
		(width 0.14478)
		(layer "In6.Cu")
		(net "M_K_CPU0_SB_CB<2>")
	)
	(segment
		(start 409.534106 -276.66315)
		(end 409.697174 -276.826218)
		(width 0.14478)
		(layer "In6.Cu")
		(net "M_K_CPU0_SB_CB<2>")
	)
	(segment
		(start 441.562998 -278.509984)
		(end 442.119004 -278.509984)
		(width 0.14478)
		(layer "In6.Cu")
		(net "M_K_CPU0_SB_CB<2>")
	)
	(segment
		(start 428.909988 -279.360122)
		(end 429.760126 -278.509984)
		(width 0.14478)
		(layer "In6.Cu")
		(net "M_K_CPU0_SB_CB<2>")
	)
	(segment
		(start 440.31535 -278.735536)
		(end 440.46013 -278.880316)
		(width 0.14478)
		(layer "In6.Cu")
		(net "M_K_CPU0_SB_CB<2>")
	)
	(segment
		(start 439.763916 -278.284432)
		(end 439.908696 -278.139652)
		(width 0.14478)
		(layer "In6.Cu")
		(net "M_K_CPU0_SB_CB<2>")
	)
	(segment
		(start 419.136322 -279.360122)
		(end 421.634158 -279.360122)
		(width 0.14478)
		(layer "In6.Cu")
		(net "M_K_CPU0_SB_CB<2>")
	)
	(segment
		(start 440.866784 -278.284432)
		(end 441.011564 -278.139652)
		(width 0.14478)
		(layer "In6.Cu")
		(net "M_K_CPU0_SB_CB<2>")
	)
	(segment
		(start 408.909774 -276.26945)
		(end 408.6225 -276.556724)
		(width 0.14478)
		(layer "In6.Cu")
		(net "M_K_CPU0_SB_CB<2>")
	)
	(segment
		(start 392.153394 -272.948654)
		(end 392.161776 -272.95348)
		(width 0.0889)
		(layer "In6.Cu")
		(net "M_K_CPU0_SB_CB<2>")
	)
	(segment
		(start 410.484574 -277.84425)
		(end 410.1973 -278.131524)
		(width 0.14478)
		(layer "In6.Cu")
		(net "M_K_CPU0_SB_CB<2>")
	)
	(segment
		(start 410.1973 -278.362156)
		(end 411.195266 -279.360122)
		(width 0.14478)
		(layer "In6.Cu")
		(net "M_K_CPU0_SB_CB<2>")
	)
	(segment
		(start 409.8036 -277.737824)
		(end 410.090874 -277.45055)
		(width 0.14478)
		(layer "In6.Cu")
		(net "M_K_CPU0_SB_CB<2>")
	)
	(segment
		(start 392.161776 -272.95348)
		(end 392.17219 -272.959576)
		(width 0.0889)
		(layer "In6.Cu")
		(net "M_K_CPU0_SB_CB<2>")
	)
	(segment
		(start 408.6225 -276.556724)
		(end 408.6225 -276.787356)
		(width 0.14478)
		(layer "In6.Cu")
		(net "M_K_CPU0_SB_CB<2>")
	)
	(segment
		(start 442.119004 -278.509984)
		(end 442.5442 -278.93518)
		(width 0.14478)
		(layer "In6.Cu")
		(net "M_K_CPU0_SB_CB<2>")
	)
	(segment
		(start 421.634158 -279.360122)
		(end 422.484296 -278.509984)
		(width 0.14478)
		(layer "In6.Cu")
		(net "M_K_CPU0_SB_CB<2>")
	)
	(segment
		(start 426.346112 -279.360122)
		(end 428.909988 -279.360122)
		(width 0.14478)
		(layer "In6.Cu")
		(net "M_K_CPU0_SB_CB<2>")
	)
	(segment
		(start 441.273438 -278.139652)
		(end 441.418218 -278.284432)
		(width 0.14478)
		(layer "In6.Cu")
		(net "M_K_CPU0_SB_CB<2>")
	)
	(segment
		(start 433.930806 -279.360122)
		(end 436.454042 -279.360122)
		(width 0.14478)
		(layer "In6.Cu")
		(net "M_K_CPU0_SB_CB<2>")
	)
	(segment
		(start 437.30418 -278.509984)
		(end 439.619136 -278.509984)
		(width 0.14478)
		(layer "In6.Cu")
		(net "M_K_CPU0_SB_CB<2>")
	)
	(segment
		(start 395.971776 -271.47393)
		(end 404.344886 -271.47393)
		(width 0.14478)
		(layer "In6.Cu")
		(net "M_K_CPU0_SB_CB<2>")
	)
	(segment
		(start 409.4099 -277.574756)
		(end 409.572968 -277.737824)
		(width 0.14478)
		(layer "In6.Cu")
		(net "M_K_CPU0_SB_CB<2>")
	)
	(segment
		(start 441.418218 -278.284432)
		(end 441.418218 -278.365204)
		(width 0.14478)
		(layer "In6.Cu")
		(net "M_K_CPU0_SB_CB<2>")
	)
	(segment
		(start 425.495974 -278.509984)
		(end 426.346112 -279.360122)
		(width 0.14478)
		(layer "In6.Cu")
		(net "M_K_CPU0_SB_CB<2>")
	)
	(segment
		(start 408.6225 -276.787356)
		(end 408.785568 -276.950424)
		(width 0.14478)
		(layer "In6.Cu")
		(net "M_K_CPU0_SB_CB<2>")
	)
	(segment
		(start 441.418218 -278.365204)
		(end 441.562998 -278.509984)
		(width 0.14478)
		(layer "In6.Cu")
		(net "M_K_CPU0_SB_CB<2>")
	)
	(segment
		(start 393.849098 -272.856198)
		(end 394.949426 -271.75587)
		(width 0.0889)
		(layer "In6.Cu")
		(net "M_K_CPU0_SB_CB<2>")
	)
	(segment
		(start 433.080668 -278.509984)
		(end 433.930806 -279.360122)
		(width 0.14478)
		(layer "In6.Cu")
		(net "M_K_CPU0_SB_CB<2>")
	)
	(segment
		(start 411.195266 -279.360122)
		(end 413.873696 -279.360122)
		(width 0.14478)
		(layer "In6.Cu")
		(net "M_K_CPU0_SB_CB<2>")
	)
	(segment
		(start 413.873696 -279.360122)
		(end 414.723834 -278.509984)
		(width 0.14478)
		(layer "In6.Cu")
		(net "M_K_CPU0_SB_CB<2>")
	)
	(segment
		(start 395.416786 -271.47393)
		(end 395.971776 -271.47393)
		(width 0.0889)
		(layer "In6.Cu")
		(net "M_K_CPU0_SB_CB<2>")
	)
	(segment
		(start 391.034778 -273.27606)
		(end 390.880854 -273.01063)
		(width 0.0889)
		(layer "In6.Cu")
		(net "M_K_CPU0_SB_CB<2>")
	)
	(segment
		(start 409.572968 -277.737824)
		(end 409.8036 -277.737824)
		(width 0.14478)
		(layer "In6.Cu")
		(net "M_K_CPU0_SB_CB<2>")
	)
	(segment
		(start 409.4099 -277.344124)
		(end 409.4099 -277.574756)
		(width 0.14478)
		(layer "In6.Cu")
		(net "M_K_CPU0_SB_CB<2>")
	)
	(segment
		(start 404.344886 -271.47393)
		(end 408.909774 -276.038818)
		(width 0.14478)
		(layer "In6.Cu")
		(net "M_K_CPU0_SB_CB<2>")
	)
	(segment
		(start 440.866784 -278.735536)
		(end 440.866784 -278.284432)
		(width 0.14478)
		(layer "In6.Cu")
		(net "M_K_CPU0_SB_CB<2>")
	)
	(segment
		(start 441.011564 -278.139652)
		(end 441.273438 -278.139652)
		(width 0.14478)
		(layer "In6.Cu")
		(net "M_K_CPU0_SB_CB<2>")
	)
	(segment
		(start 409.697174 -276.826218)
		(end 409.697174 -277.05685)
		(width 0.14478)
		(layer "In6.Cu")
		(net "M_K_CPU0_SB_CB<2>")
	)
	(segment
		(start 418.286184 -278.509984)
		(end 419.136322 -279.360122)
		(width 0.14478)
		(layer "In6.Cu")
		(net "M_K_CPU0_SB_CB<2>")
	)
	(arc
		(start 391.221722 -272.95348)
		(mid 391.504678 -273.029657)
		(end 391.787634 -272.95348)
		(width 0.0889)
		(layer "In6.Cu")
		(net "M_K_CPU0_SB_CB<2>")
	)
	(arc
		(start 390.903206 -272.927318)
		(mid 391.065395 -272.904583)
		(end 391.221722 -272.95348)
		(width 0.0889)
		(layer "In6.Cu")
		(net "M_K_CPU0_SB_CB<2>")
	)
	(arc
		(start 393.101576 -272.95348)
		(mid 393.252725 -273.015895)
		(end 393.415012 -273.03603)
		(width 0.0889)
		(layer "In6.Cu")
		(net "M_K_CPU0_SB_CB<2>")
	)
	(arc
		(start 393.415012 -273.03603)
		(mid 393.649948 -272.989298)
		(end 393.849098 -272.856198)
		(width 0.0889)
		(layer "In6.Cu")
		(net "M_K_CPU0_SB_CB<2>")
	)
	(arc
		(start 392.17219 -272.959576)
		(mid 392.450622 -273.029674)
		(end 392.727434 -272.95348)
		(width 0.0889)
		(layer "In6.Cu")
		(net "M_K_CPU0_SB_CB<2>")
	)
	(arc
		(start 391.787634 -272.95348)
		(mid 391.969885 -272.90313)
		(end 392.153394 -272.948654)
		(width 0.0889)
		(layer "In6.Cu")
		(net "M_K_CPU0_SB_CB<2>")
	)
	(arc
		(start 392.735816 -272.948654)
		(mid 392.919324 -272.90316)
		(end 393.101576 -272.95348)
		(width 0.0889)
		(layer "In6.Cu")
		(net "M_K_CPU0_SB_CB<2>")
	)
	(segment
		(start 388.688072 -273.010122)
		(end 389.154924 -273.27606)
		(width 0.10668)
		(layer "F.Cu")
		(net "M_K_CPU0_SB_CB<1>")
	)
	(segment
		(start 407.792682 -275.80082)
		(end 407.792682 -276.617684)
		(width 0.14478)
		(layer "In6.Cu")
		(net "M_K_CPU0_SB_CB<1>")
	)
	(segment
		(start 419.662356 -280.210006)
		(end 420.873682 -280.210006)
		(width 0.14478)
		(layer "In6.Cu")
		(net "M_K_CPU0_SB_CB<1>")
	)
	(segment
		(start 393.101576 -273.59864)
		(end 393.264644 -273.49831)
		(width 0.0889)
		(layer "In6.Cu")
		(net "M_K_CPU0_SB_CB<1>")
	)
	(segment
		(start 427.151038 -280.210006)
		(end 428.720504 -280.210006)
		(width 0.14478)
		(layer "In6.Cu")
		(net "M_K_CPU0_SB_CB<1>")
	)
	(segment
		(start 403.920452 -271.92859)
		(end 407.792682 -275.80082)
		(width 0.14478)
		(layer "In6.Cu")
		(net "M_K_CPU0_SB_CB<1>")
	)
	(segment
		(start 389.90778 -273.59864)
		(end 389.916162 -273.603466)
		(width 0.0889)
		(layer "In6.Cu")
		(net "M_K_CPU0_SB_CB<1>")
	)
	(segment
		(start 392.161522 -273.59864)
		(end 392.171936 -273.592544)
		(width 0.0889)
		(layer "In6.Cu")
		(net "M_K_CPU0_SB_CB<1>")
	)
	(segment
		(start 420.873682 -280.210006)
		(end 422.925494 -279.360122)
		(width 0.14478)
		(layer "In6.Cu")
		(net "M_K_CPU0_SB_CB<1>")
	)
	(segment
		(start 428.720504 -280.210006)
		(end 429.570388 -279.360122)
		(width 0.14478)
		(layer "In6.Cu")
		(net "M_K_CPU0_SB_CB<1>")
	)
	(segment
		(start 422.925494 -279.360122)
		(end 425.099226 -279.360122)
		(width 0.14478)
		(layer "In6.Cu")
		(net "M_K_CPU0_SB_CB<1>")
	)
	(segment
		(start 411.385004 -280.210006)
		(end 413.477964 -280.210006)
		(width 0.14478)
		(layer "In6.Cu")
		(net "M_K_CPU0_SB_CB<1>")
	)
	(segment
		(start 437.705754 -279.360122)
		(end 444.507874 -279.360122)
		(width 0.14478)
		(layer "In6.Cu")
		(net "M_K_CPU0_SB_CB<1>")
	)
	(segment
		(start 413.477964 -280.210006)
		(end 415.529776 -279.360122)
		(width 0.14478)
		(layer "In6.Cu")
		(net "M_K_CPU0_SB_CB<1>")
	)
	(segment
		(start 425.099226 -279.360122)
		(end 427.151038 -280.210006)
		(width 0.14478)
		(layer "In6.Cu")
		(net "M_K_CPU0_SB_CB<1>")
	)
	(segment
		(start 415.529776 -279.360122)
		(end 417.610544 -279.360122)
		(width 0.14478)
		(layer "In6.Cu")
		(net "M_K_CPU0_SB_CB<1>")
	)
	(segment
		(start 435.653942 -280.210006)
		(end 437.705754 -279.360122)
		(width 0.14478)
		(layer "In6.Cu")
		(net "M_K_CPU0_SB_CB<1>")
	)
	(segment
		(start 392.149838 -273.605498)
		(end 392.161522 -273.59864)
		(width 0.0889)
		(layer "In6.Cu")
		(net "M_K_CPU0_SB_CB<1>")
	)
	(segment
		(start 395.213078 -272.14957)
		(end 395.434058 -271.92859)
		(width 0.0889)
		(layer "In6.Cu")
		(net "M_K_CPU0_SB_CB<1>")
	)
	(segment
		(start 417.610544 -279.360122)
		(end 419.662356 -280.210006)
		(width 0.14478)
		(layer "In6.Cu")
		(net "M_K_CPU0_SB_CB<1>")
	)
	(segment
		(start 393.621006 -273.49831)
		(end 394.969746 -272.14957)
		(width 0.0889)
		(layer "In6.Cu")
		(net "M_K_CPU0_SB_CB<1>")
	)
	(segment
		(start 392.72718 -273.59864)
		(end 392.738864 -273.605498)
		(width 0.0889)
		(layer "In6.Cu")
		(net "M_K_CPU0_SB_CB<1>")
	)
	(segment
		(start 444.507874 -279.360122)
		(end 446.644268 -279.785064)
		(width 0.14478)
		(layer "In6.Cu")
		(net "M_K_CPU0_SB_CB<1>")
	)
	(segment
		(start 432.728116 -279.360122)
		(end 434.779928 -280.210006)
		(width 0.14478)
		(layer "In6.Cu")
		(net "M_K_CPU0_SB_CB<1>")
	)
	(segment
		(start 407.792682 -276.617684)
		(end 411.385004 -280.210006)
		(width 0.14478)
		(layer "In6.Cu")
		(net "M_K_CPU0_SB_CB<1>")
	)
	(segment
		(start 429.570388 -279.360122)
		(end 432.728116 -279.360122)
		(width 0.14478)
		(layer "In6.Cu")
		(net "M_K_CPU0_SB_CB<1>")
	)
	(segment
		(start 394.969746 -272.14957)
		(end 395.213078 -272.14957)
		(width 0.0889)
		(layer "In6.Cu")
		(net "M_K_CPU0_SB_CB<1>")
	)
	(segment
		(start 389.154924 -273.27606)
		(end 389.308848 -273.54149)
		(width 0.0889)
		(layer "In6.Cu")
		(net "M_K_CPU0_SB_CB<1>")
	)
	(segment
		(start 395.954504 -271.92859)
		(end 403.920452 -271.92859)
		(width 0.14478)
		(layer "In6.Cu")
		(net "M_K_CPU0_SB_CB<1>")
	)
	(segment
		(start 389.308848 -273.54149)
		(end 389.40486 -273.56689)
		(width 0.0889)
		(layer "In6.Cu")
		(net "M_K_CPU0_SB_CB<1>")
	)
	(segment
		(start 393.264644 -273.49831)
		(end 393.621006 -273.49831)
		(width 0.0889)
		(layer "In6.Cu")
		(net "M_K_CPU0_SB_CB<1>")
	)
	(segment
		(start 434.779928 -280.210006)
		(end 435.653942 -280.210006)
		(width 0.14478)
		(layer "In6.Cu")
		(net "M_K_CPU0_SB_CB<1>")
	)
	(segment
		(start 395.434058 -271.92859)
		(end 395.954504 -271.92859)
		(width 0.0889)
		(layer "In6.Cu")
		(net "M_K_CPU0_SB_CB<1>")
	)
	(arc
		(start 390.847834 -273.59864)
		(mid 391.034778 -273.648895)
		(end 391.221722 -273.59864)
		(width 0.0889)
		(layer "In6.Cu")
		(net "M_K_CPU0_SB_CB<1>")
	)
	(arc
		(start 389.40486 -273.56689)
		(mid 389.660068 -273.523413)
		(end 389.90778 -273.59864)
		(width 0.0889)
		(layer "In6.Cu")
		(net "M_K_CPU0_SB_CB<1>")
	)
	(arc
		(start 391.221722 -273.59864)
		(mid 391.504678 -273.522463)
		(end 391.787634 -273.59864)
		(width 0.0889)
		(layer "In6.Cu")
		(net "M_K_CPU0_SB_CB<1>")
	)
	(arc
		(start 392.738864 -273.605498)
		(mid 392.921119 -273.649151)
		(end 393.101576 -273.59864)
		(width 0.0889)
		(layer "In6.Cu")
		(net "M_K_CPU0_SB_CB<1>")
	)
	(arc
		(start 392.171936 -273.592544)
		(mid 392.450368 -273.522446)
		(end 392.72718 -273.59864)
		(width 0.0889)
		(layer "In6.Cu")
		(net "M_K_CPU0_SB_CB<1>")
	)
	(arc
		(start 389.916162 -273.603466)
		(mid 390.09967 -273.64896)
		(end 390.281922 -273.59864)
		(width 0.0889)
		(layer "In6.Cu")
		(net "M_K_CPU0_SB_CB<1>")
	)
	(arc
		(start 391.787634 -273.59864)
		(mid 391.967839 -273.648957)
		(end 392.149838 -273.605498)
		(width 0.0889)
		(layer "In6.Cu")
		(net "M_K_CPU0_SB_CB<1>")
	)
	(arc
		(start 390.281922 -273.59864)
		(mid 390.564878 -273.522463)
		(end 390.847834 -273.59864)
		(width 0.0889)
		(layer "In6.Cu")
		(net "M_K_CPU0_SB_CB<1>")
	)
	(segment
		(start 390.098026 -272.200116)
		(end 390.564878 -272.466054)
		(width 0.10668)
		(layer "F.Cu")
		(net "M_K_CPU0_SB_CB<0>")
	)
	(segment
		(start 390.564878 -272.466054)
		(end 390.718802 -272.731484)
		(width 0.0889)
		(layer "In6.Cu")
		(net "M_K_CPU0_SB_CB<0>")
	)
	(segment
		(start 437.469534 -277.669244)
		(end 444.960502 -277.669244)
		(width 0.14478)
		(layer "In6.Cu")
		(net "M_K_CPU0_SB_CB<0>")
	)
	(segment
		(start 412.024322 -278.509984)
		(end 414.06318 -278.509984)
		(width 0.14478)
		(layer "In6.Cu")
		(net "M_K_CPU0_SB_CB<0>")
	)
	(segment
		(start 445.105282 -277.814024)
		(end 445.105282 -278.157432)
		(width 0.14478)
		(layer "In6.Cu")
		(net "M_K_CPU0_SB_CB<0>")
	)
	(segment
		(start 418.172138 -277.669498)
		(end 419.022022 -278.519382)
		(width 0.14478)
		(layer "In6.Cu")
		(net "M_K_CPU0_SB_CB<0>")
	)
	(segment
		(start 445.105282 -278.157432)
		(end 445.250062 -278.302212)
		(width 0.14478)
		(layer "In6.Cu")
		(net "M_K_CPU0_SB_CB<0>")
	)
	(segment
		(start 393.817094 -272.01241)
		(end 394.810234 -271.01927)
		(width 0.0889)
		(layer "In6.Cu")
		(net "M_K_CPU0_SB_CB<0>")
	)
	(segment
		(start 395.914626 -271.01927)
		(end 404.533608 -271.01927)
		(width 0.14478)
		(layer "In6.Cu")
		(net "M_K_CPU0_SB_CB<0>")
	)
	(segment
		(start 404.533608 -271.01927)
		(end 412.024322 -278.509984)
		(width 0.14478)
		(layer "In6.Cu")
		(net "M_K_CPU0_SB_CB<0>")
	)
	(segment
		(start 445.250062 -278.302212)
		(end 445.511936 -278.302212)
		(width 0.14478)
		(layer "In6.Cu")
		(net "M_K_CPU0_SB_CB<0>")
	)
	(segment
		(start 394.810234 -271.01927)
		(end 395.914626 -271.01927)
		(width 0.0889)
		(layer "In6.Cu")
		(net "M_K_CPU0_SB_CB<0>")
	)
	(segment
		(start 421.717724 -278.519382)
		(end 422.567608 -277.669498)
		(width 0.14478)
		(layer "In6.Cu")
		(net "M_K_CPU0_SB_CB<0>")
	)
	(segment
		(start 393.650724 -272.722594)
		(end 393.817094 -272.556224)
		(width 0.0889)
		(layer "In6.Cu")
		(net "M_K_CPU0_SB_CB<0>")
	)
	(segment
		(start 425.397676 -277.669498)
		(end 426.24756 -278.519382)
		(width 0.14478)
		(layer "In6.Cu")
		(net "M_K_CPU0_SB_CB<0>")
	)
	(segment
		(start 445.656716 -278.157432)
		(end 445.656716 -277.814024)
		(width 0.14478)
		(layer "In6.Cu")
		(net "M_K_CPU0_SB_CB<0>")
	)
	(segment
		(start 390.718802 -272.731484)
		(end 390.814814 -272.756884)
		(width 0.0889)
		(layer "In6.Cu")
		(net "M_K_CPU0_SB_CB<0>")
	)
	(segment
		(start 446.22847 -277.669244)
		(end 446.644268 -278.085042)
		(width 0.14478)
		(layer "In6.Cu")
		(net "M_K_CPU0_SB_CB<0>")
	)
	(segment
		(start 445.511936 -278.302212)
		(end 445.656716 -278.157432)
		(width 0.14478)
		(layer "In6.Cu")
		(net "M_K_CPU0_SB_CB<0>")
	)
	(segment
		(start 414.903666 -277.669498)
		(end 418.172138 -277.669498)
		(width 0.14478)
		(layer "In6.Cu")
		(net "M_K_CPU0_SB_CB<0>")
	)
	(segment
		(start 432.910742 -277.669498)
		(end 433.760626 -278.519382)
		(width 0.14478)
		(layer "In6.Cu")
		(net "M_K_CPU0_SB_CB<0>")
	)
	(segment
		(start 392.631422 -272.788634)
		(end 392.641836 -272.782538)
		(width 0.0889)
		(layer "In6.Cu")
		(net "M_K_CPU0_SB_CB<0>")
	)
	(segment
		(start 436.619396 -278.519382)
		(end 437.469534 -277.669244)
		(width 0.14478)
		(layer "In6.Cu")
		(net "M_K_CPU0_SB_CB<0>")
	)
	(segment
		(start 392.24712 -272.782538)
		(end 392.257534 -272.788634)
		(width 0.0889)
		(layer "In6.Cu")
		(net "M_K_CPU0_SB_CB<0>")
	)
	(segment
		(start 391.317734 -272.788634)
		(end 391.326116 -272.79346)
		(width 0.0889)
		(layer "In6.Cu")
		(net "M_K_CPU0_SB_CB<0>")
	)
	(segment
		(start 445.801496 -277.669244)
		(end 446.22847 -277.669244)
		(width 0.14478)
		(layer "In6.Cu")
		(net "M_K_CPU0_SB_CB<0>")
	)
	(segment
		(start 429.090582 -278.519382)
		(end 429.940466 -277.669498)
		(width 0.14478)
		(layer "In6.Cu")
		(net "M_K_CPU0_SB_CB<0>")
	)
	(segment
		(start 422.567608 -277.669498)
		(end 425.397676 -277.669498)
		(width 0.14478)
		(layer "In6.Cu")
		(net "M_K_CPU0_SB_CB<0>")
	)
	(segment
		(start 393.817094 -272.556224)
		(end 393.817094 -272.01241)
		(width 0.0889)
		(layer "In6.Cu")
		(net "M_K_CPU0_SB_CB<0>")
	)
	(segment
		(start 433.760626 -278.519382)
		(end 436.619396 -278.519382)
		(width 0.14478)
		(layer "In6.Cu")
		(net "M_K_CPU0_SB_CB<0>")
	)
	(segment
		(start 426.24756 -278.519382)
		(end 429.090582 -278.519382)
		(width 0.14478)
		(layer "In6.Cu")
		(net "M_K_CPU0_SB_CB<0>")
	)
	(segment
		(start 444.960502 -277.669244)
		(end 445.105282 -277.814024)
		(width 0.14478)
		(layer "In6.Cu")
		(net "M_K_CPU0_SB_CB<0>")
	)
	(segment
		(start 445.656716 -277.814024)
		(end 445.801496 -277.669244)
		(width 0.14478)
		(layer "In6.Cu")
		(net "M_K_CPU0_SB_CB<0>")
	)
	(segment
		(start 414.06318 -278.509984)
		(end 414.903666 -277.669498)
		(width 0.14478)
		(layer "In6.Cu")
		(net "M_K_CPU0_SB_CB<0>")
	)
	(segment
		(start 429.940466 -277.669498)
		(end 432.910742 -277.669498)
		(width 0.14478)
		(layer "In6.Cu")
		(net "M_K_CPU0_SB_CB<0>")
	)
	(segment
		(start 419.022022 -278.519382)
		(end 421.717724 -278.519382)
		(width 0.14478)
		(layer "In6.Cu")
		(net "M_K_CPU0_SB_CB<0>")
	)
	(arc
		(start 392.641836 -272.782538)
		(mid 392.920522 -272.712318)
		(end 393.197588 -272.788634)
		(width 0.0889)
		(layer "In6.Cu")
		(net "M_K_CPU0_SB_CB<0>")
	)
	(arc
		(start 390.814814 -272.756884)
		(mid 391.070022 -272.713407)
		(end 391.317734 -272.788634)
		(width 0.0889)
		(layer "In6.Cu")
		(net "M_K_CPU0_SB_CB<0>")
	)
	(arc
		(start 391.326116 -272.79346)
		(mid 391.509624 -272.838954)
		(end 391.691876 -272.788634)
		(width 0.0889)
		(layer "In6.Cu")
		(net "M_K_CPU0_SB_CB<0>")
	)
	(arc
		(start 391.691876 -272.788634)
		(mid 391.968689 -272.712491)
		(end 392.24712 -272.782538)
		(width 0.0889)
		(layer "In6.Cu")
		(net "M_K_CPU0_SB_CB<0>")
	)
	(arc
		(start 393.559792 -272.795492)
		(mid 393.608668 -272.7633)
		(end 393.650724 -272.722594)
		(width 0.0889)
		(layer "In6.Cu")
		(net "M_K_CPU0_SB_CB<0>")
	)
	(arc
		(start 393.197588 -272.788634)
		(mid 393.377793 -272.838951)
		(end 393.559792 -272.795492)
		(width 0.0889)
		(layer "In6.Cu")
		(net "M_K_CPU0_SB_CB<0>")
	)
	(arc
		(start 392.257534 -272.788634)
		(mid 392.444478 -272.838889)
		(end 392.631422 -272.788634)
		(width 0.0889)
		(layer "In6.Cu")
		(net "M_K_CPU0_SB_CB<0>")
	)
	(segment
		(start 390.098026 -264.100056)
		(end 390.564878 -264.365994)
		(width 0.10668)
		(layer "F.Cu")
		(net "M_K_CPU0_SB_CA<6>")
	)
	(segment
		(start 394.005562 -264.33907)
		(end 395.954504 -264.33907)
		(width 0.0889)
		(layer "In6.Cu")
		(net "M_K_CPU0_SB_CA<6>")
	)
	(segment
		(start 393.630658 -264.657586)
		(end 393.909296 -264.378948)
		(width 0.0889)
		(layer "In6.Cu")
		(net "M_K_CPU0_SB_CA<6>")
	)
	(segment
		(start 390.718802 -264.631424)
		(end 390.814814 -264.656824)
		(width 0.0889)
		(layer "In6.Cu")
		(net "M_K_CPU0_SB_CA<6>")
	)
	(segment
		(start 418.702744 -265.7602)
		(end 419.552628 -266.610084)
		(width 0.14478)
		(layer "In6.Cu")
		(net "M_K_CPU0_SB_CA<6>")
	)
	(segment
		(start 419.552628 -266.610084)
		(end 421.727122 -266.610084)
		(width 0.14478)
		(layer "In6.Cu")
		(net "M_K_CPU0_SB_CA<6>")
	)
	(segment
		(start 391.317734 -264.688574)
		(end 391.326116 -264.6934)
		(width 0.0889)
		(layer "In6.Cu")
		(net "M_K_CPU0_SB_CA<6>")
	)
	(segment
		(start 426.348398 -265.7602)
		(end 427.198282 -266.610084)
		(width 0.14478)
		(layer "In6.Cu")
		(net "M_K_CPU0_SB_CA<6>")
	)
	(segment
		(start 429.271176 -266.610084)
		(end 430.12106 -265.7602)
		(width 0.14478)
		(layer "In6.Cu")
		(net "M_K_CPU0_SB_CA<6>")
	)
	(segment
		(start 422.577006 -265.7602)
		(end 426.348398 -265.7602)
		(width 0.14478)
		(layer "In6.Cu")
		(net "M_K_CPU0_SB_CA<6>")
	)
	(segment
		(start 413.833564 -265.7602)
		(end 418.702744 -265.7602)
		(width 0.14478)
		(layer "In6.Cu")
		(net "M_K_CPU0_SB_CA<6>")
	)
	(segment
		(start 390.564878 -264.365994)
		(end 390.718802 -264.631424)
		(width 0.0889)
		(layer "In6.Cu")
		(net "M_K_CPU0_SB_CA<6>")
	)
	(segment
		(start 392.24712 -264.682478)
		(end 392.257534 -264.688574)
		(width 0.0889)
		(layer "In6.Cu")
		(net "M_K_CPU0_SB_CA<6>")
	)
	(segment
		(start 446.219326 -265.7602)
		(end 446.644268 -266.185142)
		(width 0.14478)
		(layer "In6.Cu")
		(net "M_K_CPU0_SB_CA<6>")
	)
	(segment
		(start 412.034482 -266.610084)
		(end 412.98368 -266.610084)
		(width 0.14478)
		(layer "In6.Cu")
		(net "M_K_CPU0_SB_CA<6>")
	)
	(segment
		(start 430.12106 -265.7602)
		(end 446.219326 -265.7602)
		(width 0.14478)
		(layer "In6.Cu")
		(net "M_K_CPU0_SB_CA<6>")
	)
	(segment
		(start 427.198282 -266.610084)
		(end 429.271176 -266.610084)
		(width 0.14478)
		(layer "In6.Cu")
		(net "M_K_CPU0_SB_CA<6>")
	)
	(segment
		(start 412.98368 -266.610084)
		(end 413.833564 -265.7602)
		(width 0.14478)
		(layer "In6.Cu")
		(net "M_K_CPU0_SB_CA<6>")
	)
	(segment
		(start 395.954504 -264.33907)
		(end 409.763468 -264.33907)
		(width 0.14478)
		(layer "In6.Cu")
		(net "M_K_CPU0_SB_CA<6>")
	)
	(segment
		(start 421.727122 -266.610084)
		(end 422.577006 -265.7602)
		(width 0.14478)
		(layer "In6.Cu")
		(net "M_K_CPU0_SB_CA<6>")
	)
	(segment
		(start 392.631422 -264.688574)
		(end 392.641836 -264.682478)
		(width 0.0889)
		(layer "In6.Cu")
		(net "M_K_CPU0_SB_CA<6>")
	)
	(segment
		(start 409.763468 -264.33907)
		(end 412.034482 -266.610084)
		(width 0.14478)
		(layer "In6.Cu")
		(net "M_K_CPU0_SB_CA<6>")
	)
	(arc
		(start 393.197588 -264.688574)
		(mid 393.276215 -264.721331)
		(end 393.360656 -264.732516)
		(width 0.0889)
		(layer "In6.Cu")
		(net "M_K_CPU0_SB_CA<6>")
	)
	(arc
		(start 391.691876 -264.688574)
		(mid 391.968689 -264.612431)
		(end 392.24712 -264.682478)
		(width 0.0889)
		(layer "In6.Cu")
		(net "M_K_CPU0_SB_CA<6>")
	)
	(arc
		(start 390.814814 -264.656824)
		(mid 391.070022 -264.613347)
		(end 391.317734 -264.688574)
		(width 0.0889)
		(layer "In6.Cu")
		(net "M_K_CPU0_SB_CA<6>")
	)
	(arc
		(start 393.360656 -264.732516)
		(mid 393.453094 -264.727163)
		(end 393.544298 -264.71118)
		(width 0.0889)
		(layer "In6.Cu")
		(net "M_K_CPU0_SB_CA<6>")
	)
	(arc
		(start 392.257534 -264.688574)
		(mid 392.444478 -264.738829)
		(end 392.631422 -264.688574)
		(width 0.0889)
		(layer "In6.Cu")
		(net "M_K_CPU0_SB_CA<6>")
	)
	(arc
		(start 393.909296 -264.378948)
		(mid 393.953463 -264.349436)
		(end 394.005562 -264.33907)
		(width 0.0889)
		(layer "In6.Cu")
		(net "M_K_CPU0_SB_CA<6>")
	)
	(arc
		(start 393.544298 -264.71118)
		(mid 393.591871 -264.691455)
		(end 393.630658 -264.657586)
		(width 0.0889)
		(layer "In6.Cu")
		(net "M_K_CPU0_SB_CA<6>")
	)
	(arc
		(start 391.326116 -264.6934)
		(mid 391.509624 -264.738894)
		(end 391.691876 -264.688574)
		(width 0.0889)
		(layer "In6.Cu")
		(net "M_K_CPU0_SB_CA<6>")
	)
	(arc
		(start 392.641836 -264.682478)
		(mid 392.920522 -264.612258)
		(end 393.197588 -264.688574)
		(width 0.0889)
		(layer "In6.Cu")
		(net "M_K_CPU0_SB_CA<6>")
	)
	(segment
		(start 389.157972 -264.100056)
		(end 389.624824 -264.365994)
		(width 0.10668)
		(layer "F.Cu")
		(net "M_K_CPU0_SB_CA<5>")
	)
	(segment
		(start 437.25465 -265.131042)
		(end 437.417718 -265.29411)
		(width 0.14478)
		(layer "In6.Cu")
		(net "M_K_CPU0_SB_CA<5>")
	)
	(segment
		(start 421.634158 -265.7602)
		(end 422.484296 -264.910062)
		(width 0.14478)
		(layer "In6.Cu")
		(net "M_K_CPU0_SB_CA<5>")
	)
	(segment
		(start 436.861204 -264.526014)
		(end 437.091582 -264.526014)
		(width 0.14478)
		(layer "In6.Cu")
		(net "M_K_CPU0_SB_CA<5>")
	)
	(segment
		(start 426.336206 -264.910062)
		(end 427.186344 -265.7602)
		(width 0.14478)
		(layer "In6.Cu")
		(net "M_K_CPU0_SB_CA<5>")
	)
	(segment
		(start 436.141622 -265.131042)
		(end 436.30469 -265.29411)
		(width 0.14478)
		(layer "In6.Cu")
		(net "M_K_CPU0_SB_CA<5>")
	)
	(segment
		(start 436.535068 -265.29411)
		(end 436.698136 -265.131042)
		(width 0.14478)
		(layer "In6.Cu")
		(net "M_K_CPU0_SB_CA<5>")
	)
	(segment
		(start 392.24712 -264.04951)
		(end 392.257534 -264.043414)
		(width 0.0889)
		(layer "In6.Cu")
		(net "M_K_CPU0_SB_CA<5>")
	)
	(segment
		(start 395.294612 -263.992868)
		(end 395.40307 -263.88441)
		(width 0.0889)
		(layer "In6.Cu")
		(net "M_K_CPU0_SB_CA<5>")
	)
	(segment
		(start 413.896302 -264.910062)
		(end 418.665152 -264.910062)
		(width 0.14478)
		(layer "In6.Cu")
		(net "M_K_CPU0_SB_CA<5>")
	)
	(segment
		(start 393.197334 -264.043414)
		(end 393.284202 -263.992868)
		(width 0.0889)
		(layer "In6.Cu")
		(net "M_K_CPU0_SB_CA<5>")
	)
	(segment
		(start 435.978554 -264.910062)
		(end 436.141622 -265.07313)
		(width 0.14478)
		(layer "In6.Cu")
		(net "M_K_CPU0_SB_CA<5>")
	)
	(segment
		(start 392.257534 -264.043414)
		(end 392.265916 -264.038588)
		(width 0.0889)
		(layer "In6.Cu")
		(net "M_K_CPU0_SB_CA<5>")
	)
	(segment
		(start 437.25465 -264.689082)
		(end 437.25465 -265.131042)
		(width 0.14478)
		(layer "In6.Cu")
		(net "M_K_CPU0_SB_CA<5>")
	)
	(segment
		(start 437.091582 -264.526014)
		(end 437.25465 -264.689082)
		(width 0.14478)
		(layer "In6.Cu")
		(net "M_K_CPU0_SB_CA<5>")
	)
	(segment
		(start 437.417718 -265.29411)
		(end 437.648096 -265.29411)
		(width 0.14478)
		(layer "In6.Cu")
		(net "M_K_CPU0_SB_CA<5>")
	)
	(segment
		(start 436.30469 -265.29411)
		(end 436.535068 -265.29411)
		(width 0.14478)
		(layer "In6.Cu")
		(net "M_K_CPU0_SB_CA<5>")
	)
	(segment
		(start 436.698136 -265.131042)
		(end 436.698136 -264.689082)
		(width 0.14478)
		(layer "In6.Cu")
		(net "M_K_CPU0_SB_CA<5>")
	)
	(segment
		(start 422.484296 -264.910062)
		(end 426.336206 -264.910062)
		(width 0.14478)
		(layer "In6.Cu")
		(net "M_K_CPU0_SB_CA<5>")
	)
	(segment
		(start 430.02835 -264.910062)
		(end 435.978554 -264.910062)
		(width 0.14478)
		(layer "In6.Cu")
		(net "M_K_CPU0_SB_CA<5>")
	)
	(segment
		(start 436.141622 -265.07313)
		(end 436.141622 -265.131042)
		(width 0.14478)
		(layer "In6.Cu")
		(net "M_K_CPU0_SB_CA<5>")
	)
	(segment
		(start 427.186344 -265.7602)
		(end 429.178212 -265.7602)
		(width 0.14478)
		(layer "In6.Cu")
		(net "M_K_CPU0_SB_CA<5>")
	)
	(segment
		(start 419.51529 -265.7602)
		(end 421.634158 -265.7602)
		(width 0.14478)
		(layer "In6.Cu")
		(net "M_K_CPU0_SB_CA<5>")
	)
	(segment
		(start 437.811164 -265.07313)
		(end 437.974232 -264.910062)
		(width 0.14478)
		(layer "In6.Cu")
		(net "M_K_CPU0_SB_CA<5>")
	)
	(segment
		(start 418.665152 -264.910062)
		(end 419.51529 -265.7602)
		(width 0.14478)
		(layer "In6.Cu")
		(net "M_K_CPU0_SB_CA<5>")
	)
	(segment
		(start 395.40307 -263.88441)
		(end 395.977364 -263.88441)
		(width 0.0889)
		(layer "In6.Cu")
		(net "M_K_CPU0_SB_CA<5>")
	)
	(segment
		(start 437.648096 -265.29411)
		(end 437.811164 -265.131042)
		(width 0.14478)
		(layer "In6.Cu")
		(net "M_K_CPU0_SB_CA<5>")
	)
	(segment
		(start 436.698136 -264.689082)
		(end 436.861204 -264.526014)
		(width 0.14478)
		(layer "In6.Cu")
		(net "M_K_CPU0_SB_CA<5>")
	)
	(segment
		(start 429.178212 -265.7602)
		(end 430.02835 -264.910062)
		(width 0.14478)
		(layer "In6.Cu")
		(net "M_K_CPU0_SB_CA<5>")
	)
	(segment
		(start 410.223208 -263.88441)
		(end 412.098998 -265.7602)
		(width 0.14478)
		(layer "In6.Cu")
		(net "M_K_CPU0_SB_CA<5>")
	)
	(segment
		(start 392.631168 -264.043414)
		(end 392.641582 -264.04951)
		(width 0.0889)
		(layer "In6.Cu")
		(net "M_K_CPU0_SB_CA<5>")
	)
	(segment
		(start 391.317734 -264.043414)
		(end 391.326116 -264.038588)
		(width 0.0889)
		(layer "In6.Cu")
		(net "M_K_CPU0_SB_CA<5>")
	)
	(segment
		(start 412.098998 -265.7602)
		(end 413.046164 -265.7602)
		(width 0.14478)
		(layer "In6.Cu")
		(net "M_K_CPU0_SB_CA<5>")
	)
	(segment
		(start 390.74344 -264.038588)
		(end 390.751822 -264.043414)
		(width 0.0889)
		(layer "In6.Cu")
		(net "M_K_CPU0_SB_CA<5>")
	)
	(segment
		(start 395.977364 -263.88441)
		(end 410.223208 -263.88441)
		(width 0.14478)
		(layer "In6.Cu")
		(net "M_K_CPU0_SB_CA<5>")
	)
	(segment
		(start 389.624824 -264.365994)
		(end 389.4709 -264.100564)
		(width 0.0889)
		(layer "In6.Cu")
		(net "M_K_CPU0_SB_CA<5>")
	)
	(segment
		(start 437.811164 -265.131042)
		(end 437.811164 -265.07313)
		(width 0.14478)
		(layer "In6.Cu")
		(net "M_K_CPU0_SB_CA<5>")
	)
	(segment
		(start 393.284202 -263.992868)
		(end 395.294612 -263.992868)
		(width 0.0889)
		(layer "In6.Cu")
		(net "M_K_CPU0_SB_CA<5>")
	)
	(segment
		(start 413.046164 -265.7602)
		(end 413.896302 -264.910062)
		(width 0.14478)
		(layer "In6.Cu")
		(net "M_K_CPU0_SB_CA<5>")
	)
	(segment
		(start 442.119258 -264.910062)
		(end 442.5442 -265.335004)
		(width 0.14478)
		(layer "In6.Cu")
		(net "M_K_CPU0_SB_CA<5>")
	)
	(segment
		(start 437.974232 -264.910062)
		(end 442.119258 -264.910062)
		(width 0.14478)
		(layer "In6.Cu")
		(net "M_K_CPU0_SB_CA<5>")
	)
	(segment
		(start 389.4709 -264.100564)
		(end 389.493252 -264.017252)
		(width 0.0889)
		(layer "In6.Cu")
		(net "M_K_CPU0_SB_CA<5>")
	)
	(arc
		(start 389.811768 -264.043414)
		(mid 390.094724 -264.119591)
		(end 390.37768 -264.043414)
		(width 0.0889)
		(layer "In6.Cu")
		(net "M_K_CPU0_SB_CA<5>")
	)
	(arc
		(start 390.751822 -264.043414)
		(mid 391.034778 -264.119591)
		(end 391.317734 -264.043414)
		(width 0.0889)
		(layer "In6.Cu")
		(net "M_K_CPU0_SB_CA<5>")
	)
	(arc
		(start 389.493252 -264.017252)
		(mid 389.655441 -263.994517)
		(end 389.811768 -264.043414)
		(width 0.0889)
		(layer "In6.Cu")
		(net "M_K_CPU0_SB_CA<5>")
	)
	(arc
		(start 390.37768 -264.043414)
		(mid 390.559931 -263.993064)
		(end 390.74344 -264.038588)
		(width 0.0889)
		(layer "In6.Cu")
		(net "M_K_CPU0_SB_CA<5>")
	)
	(arc
		(start 391.326116 -264.038588)
		(mid 391.509624 -263.993094)
		(end 391.691876 -264.043414)
		(width 0.0889)
		(layer "In6.Cu")
		(net "M_K_CPU0_SB_CA<5>")
	)
	(arc
		(start 392.265916 -264.038588)
		(mid 392.44917 -263.993215)
		(end 392.631168 -264.043414)
		(width 0.0889)
		(layer "In6.Cu")
		(net "M_K_CPU0_SB_CA<5>")
	)
	(arc
		(start 392.641582 -264.04951)
		(mid 392.920268 -264.11973)
		(end 393.197334 -264.043414)
		(width 0.0889)
		(layer "In6.Cu")
		(net "M_K_CPU0_SB_CA<5>")
	)
	(arc
		(start 391.691876 -264.043414)
		(mid 391.968689 -264.119557)
		(end 392.24712 -264.04951)
		(width 0.0889)
		(layer "In6.Cu")
		(net "M_K_CPU0_SB_CA<5>")
	)
	(segment
		(start 388.688072 -263.29005)
		(end 389.154924 -263.555988)
		(width 0.10668)
		(layer "F.Cu")
		(net "M_K_CPU0_SB_CA<4>")
	)
	(segment
		(start 389.308848 -263.821418)
		(end 389.40486 -263.846818)
		(width 0.0889)
		(layer "In6.Cu")
		(net "M_K_CPU0_SB_CA<4>")
	)
	(segment
		(start 392.72718 -263.878568)
		(end 392.738864 -263.885426)
		(width 0.0889)
		(layer "In6.Cu")
		(net "M_K_CPU0_SB_CA<4>")
	)
	(segment
		(start 418.704776 -264.060178)
		(end 419.55466 -264.910062)
		(width 0.14478)
		(layer "In6.Cu")
		(net "M_K_CPU0_SB_CA<4>")
	)
	(segment
		(start 426.299122 -264.060178)
		(end 427.149006 -264.910062)
		(width 0.14478)
		(layer "In6.Cu")
		(net "M_K_CPU0_SB_CA<4>")
	)
	(segment
		(start 389.90778 -263.878568)
		(end 389.916162 -263.883394)
		(width 0.0889)
		(layer "In6.Cu")
		(net "M_K_CPU0_SB_CA<4>")
	)
	(segment
		(start 395.463014 -263.42975)
		(end 395.95171 -263.42975)
		(width 0.0889)
		(layer "In6.Cu")
		(net "M_K_CPU0_SB_CA<4>")
	)
	(segment
		(start 412.905956 -264.910062)
		(end 413.75584 -264.060178)
		(width 0.14478)
		(layer "In6.Cu")
		(net "M_K_CPU0_SB_CA<4>")
	)
	(segment
		(start 446.219326 -264.060178)
		(end 446.644268 -264.48512)
		(width 0.14478)
		(layer "In6.Cu")
		(net "M_K_CPU0_SB_CA<4>")
	)
	(segment
		(start 430.12106 -264.060178)
		(end 446.219326 -264.060178)
		(width 0.14478)
		(layer "In6.Cu")
		(net "M_K_CPU0_SB_CA<4>")
	)
	(segment
		(start 410.454094 -263.42975)
		(end 411.934406 -264.910062)
		(width 0.14478)
		(layer "In6.Cu")
		(net "M_K_CPU0_SB_CA<4>")
	)
	(segment
		(start 419.55466 -264.910062)
		(end 421.727122 -264.910062)
		(width 0.14478)
		(layer "In6.Cu")
		(net "M_K_CPU0_SB_CA<4>")
	)
	(segment
		(start 392.149838 -263.885426)
		(end 392.161522 -263.878568)
		(width 0.0889)
		(layer "In6.Cu")
		(net "M_K_CPU0_SB_CA<4>")
	)
	(segment
		(start 413.75584 -264.060178)
		(end 418.704776 -264.060178)
		(width 0.14478)
		(layer "In6.Cu")
		(net "M_K_CPU0_SB_CA<4>")
	)
	(segment
		(start 395.95171 -263.42975)
		(end 410.454094 -263.42975)
		(width 0.14478)
		(layer "In6.Cu")
		(net "M_K_CPU0_SB_CA<4>")
	)
	(segment
		(start 395.113256 -263.779508)
		(end 395.463014 -263.42975)
		(width 0.0889)
		(layer "In6.Cu")
		(net "M_K_CPU0_SB_CA<4>")
	)
	(segment
		(start 422.577006 -264.060178)
		(end 426.299122 -264.060178)
		(width 0.14478)
		(layer "In6.Cu")
		(net "M_K_CPU0_SB_CA<4>")
	)
	(segment
		(start 429.271176 -264.910062)
		(end 430.12106 -264.060178)
		(width 0.14478)
		(layer "In6.Cu")
		(net "M_K_CPU0_SB_CA<4>")
	)
	(segment
		(start 421.727122 -264.910062)
		(end 422.577006 -264.060178)
		(width 0.14478)
		(layer "In6.Cu")
		(net "M_K_CPU0_SB_CA<4>")
	)
	(segment
		(start 393.101576 -263.878568)
		(end 393.264644 -263.783826)
		(width 0.0889)
		(layer "In6.Cu")
		(net "M_K_CPU0_SB_CA<4>")
	)
	(segment
		(start 389.154924 -263.555988)
		(end 389.308848 -263.821418)
		(width 0.0889)
		(layer "In6.Cu")
		(net "M_K_CPU0_SB_CA<4>")
	)
	(segment
		(start 393.268962 -263.779508)
		(end 395.113256 -263.779508)
		(width 0.0889)
		(layer "In6.Cu")
		(net "M_K_CPU0_SB_CA<4>")
	)
	(segment
		(start 393.264644 -263.783826)
		(end 393.268962 -263.779508)
		(width 0.0889)
		(layer "In6.Cu")
		(net "M_K_CPU0_SB_CA<4>")
	)
	(segment
		(start 411.934406 -264.910062)
		(end 412.905956 -264.910062)
		(width 0.14478)
		(layer "In6.Cu")
		(net "M_K_CPU0_SB_CA<4>")
	)
	(segment
		(start 392.161522 -263.878568)
		(end 392.171936 -263.872472)
		(width 0.0889)
		(layer "In6.Cu")
		(net "M_K_CPU0_SB_CA<4>")
	)
	(segment
		(start 427.149006 -264.910062)
		(end 429.271176 -264.910062)
		(width 0.14478)
		(layer "In6.Cu")
		(net "M_K_CPU0_SB_CA<4>")
	)
	(arc
		(start 390.847834 -263.878568)
		(mid 391.034778 -263.928823)
		(end 391.221722 -263.878568)
		(width 0.0889)
		(layer "In6.Cu")
		(net "M_K_CPU0_SB_CA<4>")
	)
	(arc
		(start 391.221722 -263.878568)
		(mid 391.504678 -263.802391)
		(end 391.787634 -263.878568)
		(width 0.0889)
		(layer "In6.Cu")
		(net "M_K_CPU0_SB_CA<4>")
	)
	(arc
		(start 389.916162 -263.883394)
		(mid 390.09967 -263.928888)
		(end 390.281922 -263.878568)
		(width 0.0889)
		(layer "In6.Cu")
		(net "M_K_CPU0_SB_CA<4>")
	)
	(arc
		(start 392.738864 -263.885426)
		(mid 392.921119 -263.929079)
		(end 393.101576 -263.878568)
		(width 0.0889)
		(layer "In6.Cu")
		(net "M_K_CPU0_SB_CA<4>")
	)
	(arc
		(start 392.171936 -263.872472)
		(mid 392.450368 -263.802374)
		(end 392.72718 -263.878568)
		(width 0.0889)
		(layer "In6.Cu")
		(net "M_K_CPU0_SB_CA<4>")
	)
	(arc
		(start 390.281922 -263.878568)
		(mid 390.564878 -263.802391)
		(end 390.847834 -263.878568)
		(width 0.0889)
		(layer "In6.Cu")
		(net "M_K_CPU0_SB_CA<4>")
	)
	(arc
		(start 389.40486 -263.846818)
		(mid 389.660068 -263.803341)
		(end 389.90778 -263.878568)
		(width 0.0889)
		(layer "In6.Cu")
		(net "M_K_CPU0_SB_CA<4>")
	)
	(arc
		(start 391.787634 -263.878568)
		(mid 391.967839 -263.928885)
		(end 392.149838 -263.885426)
		(width 0.0889)
		(layer "In6.Cu")
		(net "M_K_CPU0_SB_CA<4>")
	)
	(segment
		(start 390.567926 -263.29005)
		(end 391.034778 -263.555988)
		(width 0.10668)
		(layer "F.Cu")
		(net "M_K_CPU0_SB_CA<3>")
	)
	(segment
		(start 421.634158 -264.060178)
		(end 422.484296 -263.21004)
		(width 0.14478)
		(layer "In6.Cu")
		(net "M_K_CPU0_SB_CA<3>")
	)
	(segment
		(start 436.514748 -263.429242)
		(end 436.514748 -262.990838)
		(width 0.14478)
		(layer "In6.Cu")
		(net "M_K_CPU0_SB_CA<3>")
	)
	(segment
		(start 442.119258 -263.21004)
		(end 442.5442 -263.634982)
		(width 0.14478)
		(layer "In6.Cu")
		(net "M_K_CPU0_SB_CA<3>")
	)
	(segment
		(start 437.071262 -262.990838)
		(end 437.071262 -263.429242)
		(width 0.14478)
		(layer "In6.Cu")
		(net "M_K_CPU0_SB_CA<3>")
	)
	(segment
		(start 437.071262 -263.429242)
		(end 437.23433 -263.59231)
		(width 0.14478)
		(layer "In6.Cu")
		(net "M_K_CPU0_SB_CA<3>")
	)
	(segment
		(start 429.178212 -264.060178)
		(end 430.02835 -263.21004)
		(width 0.14478)
		(layer "In6.Cu")
		(net "M_K_CPU0_SB_CA<3>")
	)
	(segment
		(start 392.727434 -263.233408)
		(end 392.735816 -263.228582)
		(width 0.0889)
		(layer "In6.Cu")
		(net "M_K_CPU0_SB_CA<3>")
	)
	(segment
		(start 438.18429 -263.046972)
		(end 438.347358 -263.21004)
		(width 0.14478)
		(layer "In6.Cu")
		(net "M_K_CPU0_SB_CA<3>")
	)
	(segment
		(start 394.076174 -262.92429)
		(end 395.523974 -262.92429)
		(width 0.0889)
		(layer "In6.Cu")
		(net "M_K_CPU0_SB_CA<3>")
	)
	(segment
		(start 436.35168 -263.59231)
		(end 436.514748 -263.429242)
		(width 0.14478)
		(layer "In6.Cu")
		(net "M_K_CPU0_SB_CA<3>")
	)
	(segment
		(start 410.977842 -262.97509)
		(end 412.06293 -264.060178)
		(width 0.14478)
		(layer "In6.Cu")
		(net "M_K_CPU0_SB_CA<3>")
	)
	(segment
		(start 433.512214 -263.21004)
		(end 435.795166 -263.21004)
		(width 0.14478)
		(layer "In6.Cu")
		(net "M_K_CPU0_SB_CA<3>")
	)
	(segment
		(start 437.627776 -262.990838)
		(end 437.790844 -262.82777)
		(width 0.14478)
		(layer "In6.Cu")
		(net "M_K_CPU0_SB_CA<3>")
	)
	(segment
		(start 432.9557 -263.52119)
		(end 433.201064 -263.52119)
		(width 0.14478)
		(layer "In6.Cu")
		(net "M_K_CPU0_SB_CA<3>")
	)
	(segment
		(start 413.742378 -263.21004)
		(end 418.616384 -263.21004)
		(width 0.14478)
		(layer "In6.Cu")
		(net "M_K_CPU0_SB_CA<3>")
	)
	(segment
		(start 438.021222 -262.82777)
		(end 438.18429 -262.990838)
		(width 0.14478)
		(layer "In6.Cu")
		(net "M_K_CPU0_SB_CA<3>")
	)
	(segment
		(start 441.111386 -263.21004)
		(end 442.119258 -263.21004)
		(width 0.14478)
		(layer "In6.Cu")
		(net "M_K_CPU0_SB_CA<3>")
	)
	(segment
		(start 435.958234 -263.373108)
		(end 435.958234 -263.429242)
		(width 0.14478)
		(layer "In6.Cu")
		(net "M_K_CPU0_SB_CA<3>")
	)
	(segment
		(start 438.18429 -262.990838)
		(end 438.18429 -263.046972)
		(width 0.14478)
		(layer "In6.Cu")
		(net "M_K_CPU0_SB_CA<3>")
	)
	(segment
		(start 436.677816 -262.82777)
		(end 436.908194 -262.82777)
		(width 0.14478)
		(layer "In6.Cu")
		(net "M_K_CPU0_SB_CA<3>")
	)
	(segment
		(start 440.800236 -262.89889)
		(end 441.111386 -263.21004)
		(width 0.14478)
		(layer "In6.Cu")
		(net "M_K_CPU0_SB_CA<3>")
	)
	(segment
		(start 435.795166 -263.21004)
		(end 435.958234 -263.373108)
		(width 0.14478)
		(layer "In6.Cu")
		(net "M_K_CPU0_SB_CA<3>")
	)
	(segment
		(start 390.880854 -263.290558)
		(end 390.903206 -263.207246)
		(width 0.0889)
		(layer "In6.Cu")
		(net "M_K_CPU0_SB_CA<3>")
	)
	(segment
		(start 418.616384 -263.21004)
		(end 419.466522 -264.060178)
		(width 0.14478)
		(layer "In6.Cu")
		(net "M_K_CPU0_SB_CA<3>")
	)
	(segment
		(start 440.243722 -263.21004)
		(end 440.554872 -262.89889)
		(width 0.14478)
		(layer "In6.Cu")
		(net "M_K_CPU0_SB_CA<3>")
	)
	(segment
		(start 436.514748 -262.990838)
		(end 436.677816 -262.82777)
		(width 0.14478)
		(layer "In6.Cu")
		(net "M_K_CPU0_SB_CA<3>")
	)
	(segment
		(start 437.790844 -262.82777)
		(end 438.021222 -262.82777)
		(width 0.14478)
		(layer "In6.Cu")
		(net "M_K_CPU0_SB_CA<3>")
	)
	(segment
		(start 427.188376 -264.060178)
		(end 429.178212 -264.060178)
		(width 0.14478)
		(layer "In6.Cu")
		(net "M_K_CPU0_SB_CA<3>")
	)
	(segment
		(start 432.64455 -263.21004)
		(end 432.9557 -263.52119)
		(width 0.14478)
		(layer "In6.Cu")
		(net "M_K_CPU0_SB_CA<3>")
	)
	(segment
		(start 392.161776 -263.233408)
		(end 392.17219 -263.239504)
		(width 0.0889)
		(layer "In6.Cu")
		(net "M_K_CPU0_SB_CA<3>")
	)
	(segment
		(start 422.484296 -263.21004)
		(end 426.338238 -263.21004)
		(width 0.14478)
		(layer "In6.Cu")
		(net "M_K_CPU0_SB_CA<3>")
	)
	(segment
		(start 412.89224 -264.060178)
		(end 413.742378 -263.21004)
		(width 0.14478)
		(layer "In6.Cu")
		(net "M_K_CPU0_SB_CA<3>")
	)
	(segment
		(start 393.101576 -263.233408)
		(end 393.121896 -263.245092)
		(width 0.0889)
		(layer "In6.Cu")
		(net "M_K_CPU0_SB_CA<3>")
	)
	(segment
		(start 437.627776 -263.429242)
		(end 437.627776 -262.990838)
		(width 0.14478)
		(layer "In6.Cu")
		(net "M_K_CPU0_SB_CA<3>")
	)
	(segment
		(start 412.06293 -264.060178)
		(end 412.89224 -264.060178)
		(width 0.14478)
		(layer "In6.Cu")
		(net "M_K_CPU0_SB_CA<3>")
	)
	(segment
		(start 437.23433 -263.59231)
		(end 437.464708 -263.59231)
		(width 0.14478)
		(layer "In6.Cu")
		(net "M_K_CPU0_SB_CA<3>")
	)
	(segment
		(start 419.466522 -264.060178)
		(end 421.634158 -264.060178)
		(width 0.14478)
		(layer "In6.Cu")
		(net "M_K_CPU0_SB_CA<3>")
	)
	(segment
		(start 430.02835 -263.21004)
		(end 432.64455 -263.21004)
		(width 0.14478)
		(layer "In6.Cu")
		(net "M_K_CPU0_SB_CA<3>")
	)
	(segment
		(start 437.464708 -263.59231)
		(end 437.627776 -263.429242)
		(width 0.14478)
		(layer "In6.Cu")
		(net "M_K_CPU0_SB_CA<3>")
	)
	(segment
		(start 426.338238 -263.21004)
		(end 427.188376 -264.060178)
		(width 0.14478)
		(layer "In6.Cu")
		(net "M_K_CPU0_SB_CA<3>")
	)
	(segment
		(start 438.347358 -263.21004)
		(end 440.243722 -263.21004)
		(width 0.14478)
		(layer "In6.Cu")
		(net "M_K_CPU0_SB_CA<3>")
	)
	(segment
		(start 393.384786 -263.315958)
		(end 393.446762 -263.315958)
		(width 0.0889)
		(layer "In6.Cu")
		(net "M_K_CPU0_SB_CA<3>")
	)
	(segment
		(start 392.153394 -263.228582)
		(end 392.161776 -263.233408)
		(width 0.0889)
		(layer "In6.Cu")
		(net "M_K_CPU0_SB_CA<3>")
	)
	(segment
		(start 436.121302 -263.59231)
		(end 436.35168 -263.59231)
		(width 0.14478)
		(layer "In6.Cu")
		(net "M_K_CPU0_SB_CA<3>")
	)
	(segment
		(start 393.852654 -263.14781)
		(end 394.076174 -262.92429)
		(width 0.0889)
		(layer "In6.Cu")
		(net "M_K_CPU0_SB_CA<3>")
	)
	(segment
		(start 440.554872 -262.89889)
		(end 440.800236 -262.89889)
		(width 0.14478)
		(layer "In6.Cu")
		(net "M_K_CPU0_SB_CA<3>")
	)
	(segment
		(start 395.966188 -262.97509)
		(end 410.977842 -262.97509)
		(width 0.14478)
		(layer "In6.Cu")
		(net "M_K_CPU0_SB_CA<3>")
	)
	(segment
		(start 436.908194 -262.82777)
		(end 437.071262 -262.990838)
		(width 0.14478)
		(layer "In6.Cu")
		(net "M_K_CPU0_SB_CA<3>")
	)
	(segment
		(start 395.574774 -262.97509)
		(end 395.966188 -262.97509)
		(width 0.0889)
		(layer "In6.Cu")
		(net "M_K_CPU0_SB_CA<3>")
	)
	(segment
		(start 395.523974 -262.92429)
		(end 395.574774 -262.97509)
		(width 0.0889)
		(layer "In6.Cu")
		(net "M_K_CPU0_SB_CA<3>")
	)
	(segment
		(start 435.958234 -263.429242)
		(end 436.121302 -263.59231)
		(width 0.14478)
		(layer "In6.Cu")
		(net "M_K_CPU0_SB_CA<3>")
	)
	(segment
		(start 433.201064 -263.52119)
		(end 433.512214 -263.21004)
		(width 0.14478)
		(layer "In6.Cu")
		(net "M_K_CPU0_SB_CA<3>")
	)
	(segment
		(start 391.034778 -263.555988)
		(end 390.880854 -263.290558)
		(width 0.0889)
		(layer "In6.Cu")
		(net "M_K_CPU0_SB_CA<3>")
	)
	(arc
		(start 390.903206 -263.207246)
		(mid 391.065395 -263.184511)
		(end 391.221722 -263.233408)
		(width 0.0889)
		(layer "In6.Cu")
		(net "M_K_CPU0_SB_CA<3>")
	)
	(arc
		(start 392.17219 -263.239504)
		(mid 392.450622 -263.309602)
		(end 392.727434 -263.233408)
		(width 0.0889)
		(layer "In6.Cu")
		(net "M_K_CPU0_SB_CA<3>")
	)
	(arc
		(start 392.735816 -263.228582)
		(mid 392.919324 -263.183088)
		(end 393.101576 -263.233408)
		(width 0.0889)
		(layer "In6.Cu")
		(net "M_K_CPU0_SB_CA<3>")
	)
	(arc
		(start 393.446762 -263.315958)
		(mid 393.666438 -263.272262)
		(end 393.852654 -263.14781)
		(width 0.0889)
		(layer "In6.Cu")
		(net "M_K_CPU0_SB_CA<3>")
	)
	(arc
		(start 391.221722 -263.233408)
		(mid 391.504678 -263.309585)
		(end 391.787634 -263.233408)
		(width 0.0889)
		(layer "In6.Cu")
		(net "M_K_CPU0_SB_CA<3>")
	)
	(arc
		(start 391.787634 -263.233408)
		(mid 391.969885 -263.183058)
		(end 392.153394 -263.228582)
		(width 0.0889)
		(layer "In6.Cu")
		(net "M_K_CPU0_SB_CA<3>")
	)
	(arc
		(start 393.121896 -263.245092)
		(mid 393.248653 -263.297923)
		(end 393.384786 -263.315958)
		(width 0.0889)
		(layer "In6.Cu")
		(net "M_K_CPU0_SB_CA<3>")
	)
	(segment
		(start 390.098026 -262.480044)
		(end 390.564878 -262.745982)
		(width 0.10668)
		(layer "F.Cu")
		(net "M_K_CPU0_SB_CA<2>")
	)
	(segment
		(start 418.7063 -262.360156)
		(end 419.556184 -263.21004)
		(width 0.14478)
		(layer "In6.Cu")
		(net "M_K_CPU0_SB_CA<2>")
	)
	(segment
		(start 412.929324 -263.21004)
		(end 413.779208 -262.360156)
		(width 0.14478)
		(layer "In6.Cu")
		(net "M_K_CPU0_SB_CA<2>")
	)
	(segment
		(start 392.631422 -263.068562)
		(end 392.641836 -263.062466)
		(width 0.0889)
		(layer "In6.Cu")
		(net "M_K_CPU0_SB_CA<2>")
	)
	(segment
		(start 390.564878 -262.745982)
		(end 390.718802 -263.011412)
		(width 0.0889)
		(layer "In6.Cu")
		(net "M_K_CPU0_SB_CA<2>")
	)
	(segment
		(start 392.24712 -263.062466)
		(end 392.257534 -263.068562)
		(width 0.0889)
		(layer "In6.Cu")
		(net "M_K_CPU0_SB_CA<2>")
	)
	(segment
		(start 419.556184 -263.21004)
		(end 421.727122 -263.21004)
		(width 0.14478)
		(layer "In6.Cu")
		(net "M_K_CPU0_SB_CA<2>")
	)
	(segment
		(start 413.779208 -262.360156)
		(end 418.7063 -262.360156)
		(width 0.14478)
		(layer "In6.Cu")
		(net "M_K_CPU0_SB_CA<2>")
	)
	(segment
		(start 393.384786 -263.112504)
		(end 393.481814 -263.106154)
		(width 0.0889)
		(layer "In6.Cu")
		(net "M_K_CPU0_SB_CA<2>")
	)
	(segment
		(start 427.15053 -263.21004)
		(end 429.271176 -263.21004)
		(width 0.14478)
		(layer "In6.Cu")
		(net "M_K_CPU0_SB_CA<2>")
	)
	(segment
		(start 422.577006 -262.360156)
		(end 426.300646 -262.360156)
		(width 0.14478)
		(layer "In6.Cu")
		(net "M_K_CPU0_SB_CA<2>")
	)
	(segment
		(start 446.219326 -262.360156)
		(end 446.644268 -262.785098)
		(width 0.14478)
		(layer "In6.Cu")
		(net "M_K_CPU0_SB_CA<2>")
	)
	(segment
		(start 430.12106 -262.360156)
		(end 446.219326 -262.360156)
		(width 0.14478)
		(layer "In6.Cu")
		(net "M_K_CPU0_SB_CA<2>")
	)
	(segment
		(start 411.442916 -262.52043)
		(end 412.132526 -263.21004)
		(width 0.14478)
		(layer "In6.Cu")
		(net "M_K_CPU0_SB_CA<2>")
	)
	(segment
		(start 390.718802 -263.011412)
		(end 390.814814 -263.036812)
		(width 0.0889)
		(layer "In6.Cu")
		(net "M_K_CPU0_SB_CA<2>")
	)
	(segment
		(start 393.710414 -263.002522)
		(end 393.991846 -262.72109)
		(width 0.0889)
		(layer "In6.Cu")
		(net "M_K_CPU0_SB_CA<2>")
	)
	(segment
		(start 429.271176 -263.21004)
		(end 430.12106 -262.360156)
		(width 0.14478)
		(layer "In6.Cu")
		(net "M_K_CPU0_SB_CA<2>")
	)
	(segment
		(start 391.317734 -263.068562)
		(end 391.326116 -263.073388)
		(width 0.0889)
		(layer "In6.Cu")
		(net "M_K_CPU0_SB_CA<2>")
	)
	(segment
		(start 395.270228 -262.72109)
		(end 395.470888 -262.52043)
		(width 0.0889)
		(layer "In6.Cu")
		(net "M_K_CPU0_SB_CA<2>")
	)
	(segment
		(start 421.727122 -263.21004)
		(end 422.577006 -262.360156)
		(width 0.14478)
		(layer "In6.Cu")
		(net "M_K_CPU0_SB_CA<2>")
	)
	(segment
		(start 412.132526 -263.21004)
		(end 412.929324 -263.21004)
		(width 0.14478)
		(layer "In6.Cu")
		(net "M_K_CPU0_SB_CA<2>")
	)
	(segment
		(start 426.300646 -262.360156)
		(end 427.15053 -263.21004)
		(width 0.14478)
		(layer "In6.Cu")
		(net "M_K_CPU0_SB_CA<2>")
	)
	(segment
		(start 393.991846 -262.72109)
		(end 395.270228 -262.72109)
		(width 0.0889)
		(layer "In6.Cu")
		(net "M_K_CPU0_SB_CA<2>")
	)
	(segment
		(start 395.977618 -262.52043)
		(end 411.442916 -262.52043)
		(width 0.14478)
		(layer "In6.Cu")
		(net "M_K_CPU0_SB_CA<2>")
	)
	(segment
		(start 395.470888 -262.52043)
		(end 395.977618 -262.52043)
		(width 0.0889)
		(layer "In6.Cu")
		(net "M_K_CPU0_SB_CA<2>")
	)
	(arc
		(start 393.481814 -263.106154)
		(mid 393.605549 -263.075143)
		(end 393.710414 -263.002522)
		(width 0.0889)
		(layer "In6.Cu")
		(net "M_K_CPU0_SB_CA<2>")
	)
	(arc
		(start 390.814814 -263.036812)
		(mid 391.070022 -262.993335)
		(end 391.317734 -263.068562)
		(width 0.0889)
		(layer "In6.Cu")
		(net "M_K_CPU0_SB_CA<2>")
	)
	(arc
		(start 391.691876 -263.068562)
		(mid 391.968689 -262.992419)
		(end 392.24712 -263.062466)
		(width 0.0889)
		(layer "In6.Cu")
		(net "M_K_CPU0_SB_CA<2>")
	)
	(arc
		(start 391.326116 -263.073388)
		(mid 391.509624 -263.118882)
		(end 391.691876 -263.068562)
		(width 0.0889)
		(layer "In6.Cu")
		(net "M_K_CPU0_SB_CA<2>")
	)
	(arc
		(start 393.197588 -263.068562)
		(mid 393.287917 -263.104446)
		(end 393.384786 -263.112504)
		(width 0.0889)
		(layer "In6.Cu")
		(net "M_K_CPU0_SB_CA<2>")
	)
	(arc
		(start 392.257534 -263.068562)
		(mid 392.444478 -263.118817)
		(end 392.631422 -263.068562)
		(width 0.0889)
		(layer "In6.Cu")
		(net "M_K_CPU0_SB_CA<2>")
	)
	(arc
		(start 392.641836 -263.062466)
		(mid 392.920522 -262.992246)
		(end 393.197588 -263.068562)
		(width 0.0889)
		(layer "In6.Cu")
		(net "M_K_CPU0_SB_CA<2>")
	)
	(segment
		(start 389.157972 -262.480044)
		(end 389.624824 -262.745982)
		(width 0.10668)
		(layer "F.Cu")
		(net "M_K_CPU0_SB_CA<1>")
	)
	(segment
		(start 389.624824 -262.745982)
		(end 389.4709 -262.480552)
		(width 0.0889)
		(layer "In6.Cu")
		(net "M_K_CPU0_SB_CA<1>")
	)
	(segment
		(start 395.983206 -262.06577)
		(end 413.159194 -262.06577)
		(width 0.14478)
		(layer "In6.Cu")
		(net "M_K_CPU0_SB_CA<1>")
	)
	(segment
		(start 436.030878 -261.510018)
		(end 436.193946 -261.673086)
		(width 0.14478)
		(layer "In6.Cu")
		(net "M_K_CPU0_SB_CA<1>")
	)
	(segment
		(start 421.634158 -262.360156)
		(end 422.484296 -261.510018)
		(width 0.14478)
		(layer "In6.Cu")
		(net "M_K_CPU0_SB_CA<1>")
	)
	(segment
		(start 389.4709 -262.480552)
		(end 389.493252 -262.39724)
		(width 0.0889)
		(layer "In6.Cu")
		(net "M_K_CPU0_SB_CA<1>")
	)
	(segment
		(start 429.178212 -262.360156)
		(end 430.02835 -261.510018)
		(width 0.14478)
		(layer "In6.Cu")
		(net "M_K_CPU0_SB_CA<1>")
	)
	(segment
		(start 430.02835 -261.510018)
		(end 436.030878 -261.510018)
		(width 0.14478)
		(layer "In6.Cu")
		(net "M_K_CPU0_SB_CA<1>")
	)
	(segment
		(start 436.75046 -261.292594)
		(end 436.913528 -261.129526)
		(width 0.14478)
		(layer "In6.Cu")
		(net "M_K_CPU0_SB_CA<1>")
	)
	(segment
		(start 438.026556 -261.129526)
		(end 438.256934 -261.129526)
		(width 0.14478)
		(layer "In6.Cu")
		(net "M_K_CPU0_SB_CA<1>")
	)
	(segment
		(start 392.631168 -262.423402)
		(end 392.641582 -262.429498)
		(width 0.0889)
		(layer "In6.Cu")
		(net "M_K_CPU0_SB_CA<1>")
	)
	(segment
		(start 393.283948 -262.37311)
		(end 395.206982 -262.37311)
		(width 0.0889)
		(layer "In6.Cu")
		(net "M_K_CPU0_SB_CA<1>")
	)
	(segment
		(start 392.257534 -262.423402)
		(end 392.265916 -262.418576)
		(width 0.0889)
		(layer "In6.Cu")
		(net "M_K_CPU0_SB_CA<1>")
	)
	(segment
		(start 418.796216 -261.510018)
		(end 419.646354 -262.360156)
		(width 0.14478)
		(layer "In6.Cu")
		(net "M_K_CPU0_SB_CA<1>")
	)
	(segment
		(start 393.197334 -262.423402)
		(end 393.283948 -262.37311)
		(width 0.0889)
		(layer "In6.Cu")
		(net "M_K_CPU0_SB_CA<1>")
	)
	(segment
		(start 437.470042 -261.89051)
		(end 437.70042 -261.89051)
		(width 0.14478)
		(layer "In6.Cu")
		(net "M_K_CPU0_SB_CA<1>")
	)
	(segment
		(start 390.74344 -262.418576)
		(end 390.751822 -262.423402)
		(width 0.0889)
		(layer "In6.Cu")
		(net "M_K_CPU0_SB_CA<1>")
	)
	(segment
		(start 436.913528 -261.129526)
		(end 437.143906 -261.129526)
		(width 0.14478)
		(layer "In6.Cu")
		(net "M_K_CPU0_SB_CA<1>")
	)
	(segment
		(start 438.58307 -261.510018)
		(end 442.119258 -261.510018)
		(width 0.14478)
		(layer "In6.Cu")
		(net "M_K_CPU0_SB_CA<1>")
	)
	(segment
		(start 436.193946 -261.673086)
		(end 436.193946 -261.727442)
		(width 0.14478)
		(layer "In6.Cu")
		(net "M_K_CPU0_SB_CA<1>")
	)
	(segment
		(start 395.206982 -262.37311)
		(end 395.514322 -262.06577)
		(width 0.0889)
		(layer "In6.Cu")
		(net "M_K_CPU0_SB_CA<1>")
	)
	(segment
		(start 437.70042 -261.89051)
		(end 437.863488 -261.727442)
		(width 0.14478)
		(layer "In6.Cu")
		(net "M_K_CPU0_SB_CA<1>")
	)
	(segment
		(start 395.514322 -262.06577)
		(end 395.983206 -262.06577)
		(width 0.0889)
		(layer "In6.Cu")
		(net "M_K_CPU0_SB_CA<1>")
	)
	(segment
		(start 427.1391 -262.360156)
		(end 429.178212 -262.360156)
		(width 0.14478)
		(layer "In6.Cu")
		(net "M_K_CPU0_SB_CA<1>")
	)
	(segment
		(start 437.306974 -261.292594)
		(end 437.306974 -261.727442)
		(width 0.14478)
		(layer "In6.Cu")
		(net "M_K_CPU0_SB_CA<1>")
	)
	(segment
		(start 437.143906 -261.129526)
		(end 437.306974 -261.292594)
		(width 0.14478)
		(layer "In6.Cu")
		(net "M_K_CPU0_SB_CA<1>")
	)
	(segment
		(start 422.484296 -261.510018)
		(end 426.288962 -261.510018)
		(width 0.14478)
		(layer "In6.Cu")
		(net "M_K_CPU0_SB_CA<1>")
	)
	(segment
		(start 436.75046 -261.727442)
		(end 436.75046 -261.292594)
		(width 0.14478)
		(layer "In6.Cu")
		(net "M_K_CPU0_SB_CA<1>")
	)
	(segment
		(start 437.863488 -261.727442)
		(end 437.863488 -261.292594)
		(width 0.14478)
		(layer "In6.Cu")
		(net "M_K_CPU0_SB_CA<1>")
	)
	(segment
		(start 438.420002 -261.34695)
		(end 438.58307 -261.510018)
		(width 0.14478)
		(layer "In6.Cu")
		(net "M_K_CPU0_SB_CA<1>")
	)
	(segment
		(start 419.646354 -262.360156)
		(end 421.634158 -262.360156)
		(width 0.14478)
		(layer "In6.Cu")
		(net "M_K_CPU0_SB_CA<1>")
	)
	(segment
		(start 436.193946 -261.727442)
		(end 436.357014 -261.89051)
		(width 0.14478)
		(layer "In6.Cu")
		(net "M_K_CPU0_SB_CA<1>")
	)
	(segment
		(start 438.420002 -261.292594)
		(end 438.420002 -261.34695)
		(width 0.14478)
		(layer "In6.Cu")
		(net "M_K_CPU0_SB_CA<1>")
	)
	(segment
		(start 442.119258 -261.510018)
		(end 442.5442 -261.93496)
		(width 0.14478)
		(layer "In6.Cu")
		(net "M_K_CPU0_SB_CA<1>")
	)
	(segment
		(start 436.587392 -261.89051)
		(end 436.75046 -261.727442)
		(width 0.14478)
		(layer "In6.Cu")
		(net "M_K_CPU0_SB_CA<1>")
	)
	(segment
		(start 437.306974 -261.727442)
		(end 437.470042 -261.89051)
		(width 0.14478)
		(layer "In6.Cu")
		(net "M_K_CPU0_SB_CA<1>")
	)
	(segment
		(start 413.159194 -262.06577)
		(end 413.714946 -261.510018)
		(width 0.14478)
		(layer "In6.Cu")
		(net "M_K_CPU0_SB_CA<1>")
	)
	(segment
		(start 392.24712 -262.429498)
		(end 392.257534 -262.423402)
		(width 0.0889)
		(layer "In6.Cu")
		(net "M_K_CPU0_SB_CA<1>")
	)
	(segment
		(start 391.317734 -262.423402)
		(end 391.326116 -262.418576)
		(width 0.0889)
		(layer "In6.Cu")
		(net "M_K_CPU0_SB_CA<1>")
	)
	(segment
		(start 436.357014 -261.89051)
		(end 436.587392 -261.89051)
		(width 0.14478)
		(layer "In6.Cu")
		(net "M_K_CPU0_SB_CA<1>")
	)
	(segment
		(start 438.256934 -261.129526)
		(end 438.420002 -261.292594)
		(width 0.14478)
		(layer "In6.Cu")
		(net "M_K_CPU0_SB_CA<1>")
	)
	(segment
		(start 413.714946 -261.510018)
		(end 418.796216 -261.510018)
		(width 0.14478)
		(layer "In6.Cu")
		(net "M_K_CPU0_SB_CA<1>")
	)
	(segment
		(start 426.288962 -261.510018)
		(end 427.1391 -262.360156)
		(width 0.14478)
		(layer "In6.Cu")
		(net "M_K_CPU0_SB_CA<1>")
	)
	(segment
		(start 437.863488 -261.292594)
		(end 438.026556 -261.129526)
		(width 0.14478)
		(layer "In6.Cu")
		(net "M_K_CPU0_SB_CA<1>")
	)
	(arc
		(start 392.265916 -262.418576)
		(mid 392.44917 -262.373203)
		(end 392.631168 -262.423402)
		(width 0.0889)
		(layer "In6.Cu")
		(net "M_K_CPU0_SB_CA<1>")
	)
	(arc
		(start 389.811768 -262.423402)
		(mid 390.094724 -262.499579)
		(end 390.37768 -262.423402)
		(width 0.0889)
		(layer "In6.Cu")
		(net "M_K_CPU0_SB_CA<1>")
	)
	(arc
		(start 390.37768 -262.423402)
		(mid 390.559931 -262.373052)
		(end 390.74344 -262.418576)
		(width 0.0889)
		(layer "In6.Cu")
		(net "M_K_CPU0_SB_CA<1>")
	)
	(arc
		(start 391.691876 -262.423402)
		(mid 391.968689 -262.499545)
		(end 392.24712 -262.429498)
		(width 0.0889)
		(layer "In6.Cu")
		(net "M_K_CPU0_SB_CA<1>")
	)
	(arc
		(start 392.641582 -262.429498)
		(mid 392.920268 -262.499718)
		(end 393.197334 -262.423402)
		(width 0.0889)
		(layer "In6.Cu")
		(net "M_K_CPU0_SB_CA<1>")
	)
	(arc
		(start 391.326116 -262.418576)
		(mid 391.509624 -262.373082)
		(end 391.691876 -262.423402)
		(width 0.0889)
		(layer "In6.Cu")
		(net "M_K_CPU0_SB_CA<1>")
	)
	(arc
		(start 390.751822 -262.423402)
		(mid 391.034778 -262.499579)
		(end 391.317734 -262.423402)
		(width 0.0889)
		(layer "In6.Cu")
		(net "M_K_CPU0_SB_CA<1>")
	)
	(arc
		(start 389.493252 -262.39724)
		(mid 389.655441 -262.374505)
		(end 389.811768 -262.423402)
		(width 0.0889)
		(layer "In6.Cu")
		(net "M_K_CPU0_SB_CA<1>")
	)
	(segment
		(start 388.688072 -261.670038)
		(end 389.154924 -261.935976)
		(width 0.10668)
		(layer "F.Cu")
		(net "M_K_CPU0_SB_CA<0>")
	)
	(segment
		(start 393.101576 -262.258556)
		(end 393.308332 -262.138414)
		(width 0.0889)
		(layer "In6.Cu")
		(net "M_K_CPU0_SB_CA<0>")
	)
	(segment
		(start 393.312396 -262.13435)
		(end 395.025626 -262.13435)
		(width 0.0889)
		(layer "In6.Cu")
		(net "M_K_CPU0_SB_CA<0>")
	)
	(segment
		(start 446.219326 -260.660134)
		(end 446.644268 -261.085076)
		(width 0.14478)
		(layer "In6.Cu")
		(net "M_K_CPU0_SB_CA<0>")
	)
	(segment
		(start 392.72718 -262.258556)
		(end 392.738864 -262.265414)
		(width 0.0889)
		(layer "In6.Cu")
		(net "M_K_CPU0_SB_CA<0>")
	)
	(segment
		(start 392.161522 -262.258556)
		(end 392.171936 -262.25246)
		(width 0.0889)
		(layer "In6.Cu")
		(net "M_K_CPU0_SB_CA<0>")
	)
	(segment
		(start 389.90778 -262.258556)
		(end 389.916162 -262.263382)
		(width 0.0889)
		(layer "In6.Cu")
		(net "M_K_CPU0_SB_CA<0>")
	)
	(segment
		(start 411.715204 -260.660134)
		(end 446.219326 -260.660134)
		(width 0.14478)
		(layer "In6.Cu")
		(net "M_K_CPU0_SB_CA<0>")
	)
	(segment
		(start 389.308848 -262.201406)
		(end 389.40486 -262.226806)
		(width 0.0889)
		(layer "In6.Cu")
		(net "M_K_CPU0_SB_CA<0>")
	)
	(segment
		(start 389.154924 -261.935976)
		(end 389.308848 -262.201406)
		(width 0.0889)
		(layer "In6.Cu")
		(net "M_K_CPU0_SB_CA<0>")
	)
	(segment
		(start 392.149838 -262.265414)
		(end 392.161522 -262.258556)
		(width 0.0889)
		(layer "In6.Cu")
		(net "M_K_CPU0_SB_CA<0>")
	)
	(segment
		(start 395.025626 -262.13435)
		(end 395.548866 -261.61111)
		(width 0.0889)
		(layer "In6.Cu")
		(net "M_K_CPU0_SB_CA<0>")
	)
	(segment
		(start 410.764228 -261.61111)
		(end 411.715204 -260.660134)
		(width 0.14478)
		(layer "In6.Cu")
		(net "M_K_CPU0_SB_CA<0>")
	)
	(segment
		(start 395.968982 -261.61111)
		(end 410.764228 -261.61111)
		(width 0.14478)
		(layer "In6.Cu")
		(net "M_K_CPU0_SB_CA<0>")
	)
	(segment
		(start 393.308332 -262.138414)
		(end 393.312396 -262.13435)
		(width 0.0889)
		(layer "In6.Cu")
		(net "M_K_CPU0_SB_CA<0>")
	)
	(segment
		(start 395.548866 -261.61111)
		(end 395.968982 -261.61111)
		(width 0.0889)
		(layer "In6.Cu")
		(net "M_K_CPU0_SB_CA<0>")
	)
	(arc
		(start 390.281922 -262.258556)
		(mid 390.564878 -262.182379)
		(end 390.847834 -262.258556)
		(width 0.0889)
		(layer "In6.Cu")
		(net "M_K_CPU0_SB_CA<0>")
	)
	(arc
		(start 392.738864 -262.265414)
		(mid 392.921119 -262.309067)
		(end 393.101576 -262.258556)
		(width 0.0889)
		(layer "In6.Cu")
		(net "M_K_CPU0_SB_CA<0>")
	)
	(arc
		(start 391.787634 -262.258556)
		(mid 391.967839 -262.308873)
		(end 392.149838 -262.265414)
		(width 0.0889)
		(layer "In6.Cu")
		(net "M_K_CPU0_SB_CA<0>")
	)
	(arc
		(start 390.847834 -262.258556)
		(mid 391.034778 -262.308811)
		(end 391.221722 -262.258556)
		(width 0.0889)
		(layer "In6.Cu")
		(net "M_K_CPU0_SB_CA<0>")
	)
	(arc
		(start 391.221722 -262.258556)
		(mid 391.504678 -262.182379)
		(end 391.787634 -262.258556)
		(width 0.0889)
		(layer "In6.Cu")
		(net "M_K_CPU0_SB_CA<0>")
	)
	(arc
		(start 389.40486 -262.226806)
		(mid 389.660068 -262.183329)
		(end 389.90778 -262.258556)
		(width 0.0889)
		(layer "In6.Cu")
		(net "M_K_CPU0_SB_CA<0>")
	)
	(arc
		(start 392.171936 -262.25246)
		(mid 392.450368 -262.182362)
		(end 392.72718 -262.258556)
		(width 0.0889)
		(layer "In6.Cu")
		(net "M_K_CPU0_SB_CA<0>")
	)
	(arc
		(start 389.916162 -262.263382)
		(mid 390.09967 -262.308876)
		(end 390.281922 -262.258556)
		(width 0.0889)
		(layer "In6.Cu")
		(net "M_K_CPU0_SB_CA<0>")
	)
	(segment
		(start 388.688072 -266.530074)
		(end 389.154924 -266.796012)
		(width 0.10668)
		(layer "F.Cu")
		(net "M_K_CPU0_SA_RSP<0>")
	)
	(segment
		(start 392.149838 -267.12545)
		(end 392.161522 -267.118592)
		(width 0.0889)
		(layer "In6.Cu")
		(net "M_K_CPU0_SA_RSP<0>")
	)
	(segment
		(start 394.401548 -265.81862)
		(end 395.29258 -265.81862)
		(width 0.0889)
		(layer "In6.Cu")
		(net "M_K_CPU0_SA_RSP<0>")
	)
	(segment
		(start 428.660814 -270.010382)
		(end 430.713388 -269.160244)
		(width 0.11684)
		(layer "In6.Cu")
		(net "M_K_CPU0_SA_RSP<0>")
	)
	(segment
		(start 395.29258 -265.81862)
		(end 395.6177 -266.14374)
		(width 0.0889)
		(layer "In6.Cu")
		(net "M_K_CPU0_SA_RSP<0>")
	)
	(segment
		(start 389.154924 -266.796012)
		(end 389.308848 -267.061442)
		(width 0.0889)
		(layer "In6.Cu")
		(net "M_K_CPU0_SA_RSP<0>")
	)
	(segment
		(start 421.000428 -270.010382)
		(end 423.053002 -269.160244)
		(width 0.11684)
		(layer "In6.Cu")
		(net "M_K_CPU0_SA_RSP<0>")
	)
	(segment
		(start 446.219326 -269.160244)
		(end 446.644268 -269.585186)
		(width 0.11684)
		(layer "In6.Cu")
		(net "M_K_CPU0_SA_RSP<0>")
	)
	(segment
		(start 423.053002 -269.160244)
		(end 425.322746 -269.160244)
		(width 0.11684)
		(layer "In6.Cu")
		(net "M_K_CPU0_SA_RSP<0>")
	)
	(segment
		(start 389.90778 -267.118592)
		(end 389.916162 -267.123418)
		(width 0.0889)
		(layer "In6.Cu")
		(net "M_K_CPU0_SA_RSP<0>")
	)
	(segment
		(start 395.965934 -266.14374)
		(end 408.164284 -266.14374)
		(width 0.11684)
		(layer "In6.Cu")
		(net "M_K_CPU0_SA_RSP<0>")
	)
	(segment
		(start 389.308848 -267.061442)
		(end 389.40486 -267.086842)
		(width 0.0889)
		(layer "In6.Cu")
		(net "M_K_CPU0_SA_RSP<0>")
	)
	(segment
		(start 417.795964 -269.160244)
		(end 419.848538 -270.010382)
		(width 0.11684)
		(layer "In6.Cu")
		(net "M_K_CPU0_SA_RSP<0>")
	)
	(segment
		(start 427.37532 -270.010382)
		(end 428.660814 -270.010382)
		(width 0.11684)
		(layer "In6.Cu")
		(net "M_K_CPU0_SA_RSP<0>")
	)
	(segment
		(start 393.101576 -267.118592)
		(end 394.401548 -265.81862)
		(width 0.0889)
		(layer "In6.Cu")
		(net "M_K_CPU0_SA_RSP<0>")
	)
	(segment
		(start 412.030926 -270.010382)
		(end 413.113728 -270.010382)
		(width 0.11684)
		(layer "In6.Cu")
		(net "M_K_CPU0_SA_RSP<0>")
	)
	(segment
		(start 413.113728 -270.010382)
		(end 415.166302 -269.160244)
		(width 0.11684)
		(layer "In6.Cu")
		(net "M_K_CPU0_SA_RSP<0>")
	)
	(segment
		(start 392.72718 -267.118592)
		(end 392.738864 -267.12545)
		(width 0.0889)
		(layer "In6.Cu")
		(net "M_K_CPU0_SA_RSP<0>")
	)
	(segment
		(start 415.166302 -269.160244)
		(end 417.795964 -269.160244)
		(width 0.11684)
		(layer "In6.Cu")
		(net "M_K_CPU0_SA_RSP<0>")
	)
	(segment
		(start 419.848538 -270.010382)
		(end 421.000428 -270.010382)
		(width 0.11684)
		(layer "In6.Cu")
		(net "M_K_CPU0_SA_RSP<0>")
	)
	(segment
		(start 430.713388 -269.160244)
		(end 446.219326 -269.160244)
		(width 0.11684)
		(layer "In6.Cu")
		(net "M_K_CPU0_SA_RSP<0>")
	)
	(segment
		(start 425.322746 -269.160244)
		(end 427.37532 -270.010382)
		(width 0.11684)
		(layer "In6.Cu")
		(net "M_K_CPU0_SA_RSP<0>")
	)
	(segment
		(start 395.6177 -266.14374)
		(end 395.965934 -266.14374)
		(width 0.0889)
		(layer "In6.Cu")
		(net "M_K_CPU0_SA_RSP<0>")
	)
	(segment
		(start 408.164284 -266.14374)
		(end 412.030926 -270.010382)
		(width 0.11684)
		(layer "In6.Cu")
		(net "M_K_CPU0_SA_RSP<0>")
	)
	(segment
		(start 392.161522 -267.118592)
		(end 392.171936 -267.112496)
		(width 0.0889)
		(layer "In6.Cu")
		(net "M_K_CPU0_SA_RSP<0>")
	)
	(arc
		(start 391.221722 -267.118592)
		(mid 391.504678 -267.042415)
		(end 391.787634 -267.118592)
		(width 0.0889)
		(layer "In6.Cu")
		(net "M_K_CPU0_SA_RSP<0>")
	)
	(arc
		(start 390.847834 -267.118592)
		(mid 391.034778 -267.168847)
		(end 391.221722 -267.118592)
		(width 0.0889)
		(layer "In6.Cu")
		(net "M_K_CPU0_SA_RSP<0>")
	)
	(arc
		(start 390.281922 -267.118592)
		(mid 390.564878 -267.042415)
		(end 390.847834 -267.118592)
		(width 0.0889)
		(layer "In6.Cu")
		(net "M_K_CPU0_SA_RSP<0>")
	)
	(arc
		(start 392.738864 -267.12545)
		(mid 392.921119 -267.169103)
		(end 393.101576 -267.118592)
		(width 0.0889)
		(layer "In6.Cu")
		(net "M_K_CPU0_SA_RSP<0>")
	)
	(arc
		(start 389.40486 -267.086842)
		(mid 389.660068 -267.043365)
		(end 389.90778 -267.118592)
		(width 0.0889)
		(layer "In6.Cu")
		(net "M_K_CPU0_SA_RSP<0>")
	)
	(arc
		(start 389.916162 -267.123418)
		(mid 390.09967 -267.168912)
		(end 390.281922 -267.118592)
		(width 0.0889)
		(layer "In6.Cu")
		(net "M_K_CPU0_SA_RSP<0>")
	)
	(arc
		(start 391.787634 -267.118592)
		(mid 391.967839 -267.168909)
		(end 392.149838 -267.12545)
		(width 0.0889)
		(layer "In6.Cu")
		(net "M_K_CPU0_SA_RSP<0>")
	)
	(arc
		(start 392.171936 -267.112496)
		(mid 392.450368 -267.042398)
		(end 392.72718 -267.118592)
		(width 0.0889)
		(layer "In6.Cu")
		(net "M_K_CPU0_SA_RSP<0>")
	)
	(segment
		(start 388.387844 -256.090166)
		(end 388.85495 -255.824228)
		(width 0.10668)
		(layer "F.Cu")
		(net "M_K_CPU0_SA_PAR")
	)
	(segment
		(start 388.85495 -255.824228)
		(end 389.008874 -255.558798)
		(width 0.0889)
		(layer "In6.Cu")
		(net "M_K_CPU0_SA_PAR")
	)
	(segment
		(start 445.369188 -253.009908)
		(end 446.644268 -254.284988)
		(width 0.14478)
		(layer "In6.Cu")
		(net "M_K_CPU0_SA_PAR")
	)
	(segment
		(start 437.705754 -255.74371)
		(end 438.739534 -254.70993)
		(width 0.14478)
		(layer "In6.Cu")
		(net "M_K_CPU0_SA_PAR")
	)
	(segment
		(start 392.952224 -255.65227)
		(end 393.683236 -255.65227)
		(width 0.0889)
		(layer "In6.Cu")
		(net "M_K_CPU0_SA_PAR")
	)
	(segment
		(start 391.849864 -255.49479)
		(end 391.861548 -255.501648)
		(width 0.0889)
		(layer "In6.Cu")
		(net "M_K_CPU0_SA_PAR")
	)
	(segment
		(start 398.67332 -256.51587)
		(end 400.03603 -255.15316)
		(width 0.14478)
		(layer "In6.Cu")
		(net "M_K_CPU0_SA_PAR")
	)
	(segment
		(start 389.008874 -255.558798)
		(end 389.104886 -255.533398)
		(width 0.0889)
		(layer "In6.Cu")
		(net "M_K_CPU0_SA_PAR")
	)
	(segment
		(start 389.607806 -255.501648)
		(end 389.616188 -255.496822)
		(width 0.0889)
		(layer "In6.Cu")
		(net "M_K_CPU0_SA_PAR")
	)
	(segment
		(start 395.816836 -256.51587)
		(end 398.67332 -256.51587)
		(width 0.14478)
		(layer "In6.Cu")
		(net "M_K_CPU0_SA_PAR")
	)
	(segment
		(start 393.683236 -255.65227)
		(end 394.546836 -256.51587)
		(width 0.0889)
		(layer "In6.Cu")
		(net "M_K_CPU0_SA_PAR")
	)
	(segment
		(start 394.546836 -256.51587)
		(end 395.816836 -256.51587)
		(width 0.0889)
		(layer "In6.Cu")
		(net "M_K_CPU0_SA_PAR")
	)
	(segment
		(start 406.992836 -255.74371)
		(end 437.705754 -255.74371)
		(width 0.14478)
		(layer "In6.Cu")
		(net "M_K_CPU0_SA_PAR")
	)
	(segment
		(start 406.402286 -255.15316)
		(end 406.992836 -255.74371)
		(width 0.14478)
		(layer "In6.Cu")
		(net "M_K_CPU0_SA_PAR")
	)
	(segment
		(start 441.125356 -253.009908)
		(end 445.369188 -253.009908)
		(width 0.14478)
		(layer "In6.Cu")
		(net "M_K_CPU0_SA_PAR")
	)
	(segment
		(start 438.739534 -254.70993)
		(end 439.425334 -254.70993)
		(width 0.14478)
		(layer "In6.Cu")
		(net "M_K_CPU0_SA_PAR")
	)
	(segment
		(start 392.801602 -255.501648)
		(end 392.952224 -255.65227)
		(width 0.0889)
		(layer "In6.Cu")
		(net "M_K_CPU0_SA_PAR")
	)
	(segment
		(start 439.425334 -254.70993)
		(end 441.125356 -253.009908)
		(width 0.14478)
		(layer "In6.Cu")
		(net "M_K_CPU0_SA_PAR")
	)
	(segment
		(start 400.03603 -255.15316)
		(end 406.402286 -255.15316)
		(width 0.14478)
		(layer "In6.Cu")
		(net "M_K_CPU0_SA_PAR")
	)
	(segment
		(start 391.861548 -255.501648)
		(end 391.871962 -255.507744)
		(width 0.0889)
		(layer "In6.Cu")
		(net "M_K_CPU0_SA_PAR")
	)
	(segment
		(start 392.427206 -255.501648)
		(end 392.43889 -255.49479)
		(width 0.0889)
		(layer "In6.Cu")
		(net "M_K_CPU0_SA_PAR")
	)
	(arc
		(start 392.43889 -255.49479)
		(mid 392.621145 -255.451137)
		(end 392.801602 -255.501648)
		(width 0.0889)
		(layer "In6.Cu")
		(net "M_K_CPU0_SA_PAR")
	)
	(arc
		(start 389.616188 -255.496822)
		(mid 389.799696 -255.451328)
		(end 389.981948 -255.501648)
		(width 0.0889)
		(layer "In6.Cu")
		(net "M_K_CPU0_SA_PAR")
	)
	(arc
		(start 389.981948 -255.501648)
		(mid 390.264904 -255.577825)
		(end 390.54786 -255.501648)
		(width 0.0889)
		(layer "In6.Cu")
		(net "M_K_CPU0_SA_PAR")
	)
	(arc
		(start 389.104886 -255.533398)
		(mid 389.360094 -255.576875)
		(end 389.607806 -255.501648)
		(width 0.0889)
		(layer "In6.Cu")
		(net "M_K_CPU0_SA_PAR")
	)
	(arc
		(start 390.921748 -255.501648)
		(mid 391.204704 -255.577825)
		(end 391.48766 -255.501648)
		(width 0.0889)
		(layer "In6.Cu")
		(net "M_K_CPU0_SA_PAR")
	)
	(arc
		(start 390.54786 -255.501648)
		(mid 390.734804 -255.451393)
		(end 390.921748 -255.501648)
		(width 0.0889)
		(layer "In6.Cu")
		(net "M_K_CPU0_SA_PAR")
	)
	(arc
		(start 391.871962 -255.507744)
		(mid 392.150394 -255.577842)
		(end 392.427206 -255.501648)
		(width 0.0889)
		(layer "In6.Cu")
		(net "M_K_CPU0_SA_PAR")
	)
	(arc
		(start 391.48766 -255.501648)
		(mid 391.667865 -255.451331)
		(end 391.849864 -255.49479)
		(width 0.0889)
		(layer "In6.Cu")
		(net "M_K_CPU0_SA_PAR")
	)
	(segment
		(start 388.387844 -247.990106)
		(end 388.85495 -247.724168)
		(width 0.12954)
		(layer "F.Cu")
		(net "M_K_CPU0_SA_DQS_DP<9>")
	)
	(segment
		(start 414.070038 -240.180368)
		(end 414.857438 -239.392968)
		(width 0.16002)
		(layer "In6.Cu")
		(net "M_K_CPU0_SA_DQS_DP<9>")
	)
	(segment
		(start 393.820142 -247.457976)
		(end 393.820142 -247.45823)
		(width 0.09525)
		(layer "In6.Cu")
		(net "M_K_CPU0_SA_DQS_DP<9>")
	)
	(segment
		(start 440.196732 -239.561116)
		(end 442.270134 -239.561116)
		(width 0.16002)
		(layer "In6.Cu")
		(net "M_K_CPU0_SA_DQS_DP<9>")
	)
	(segment
		(start 393.820142 -247.45823)
		(end 393.985242 -247.623076)
		(width 0.09525)
		(layer "In6.Cu")
		(net "M_K_CPU0_SA_DQS_DP<9>")
	)
	(segment
		(start 416.48126 -239.710214)
		(end 416.64128 -239.870234)
		(width 0.16002)
		(layer "In6.Cu")
		(net "M_K_CPU0_SA_DQS_DP<9>")
	)
	(segment
		(start 415.98342 -239.710214)
		(end 416.48126 -239.710214)
		(width 0.16002)
		(layer "In6.Cu")
		(net "M_K_CPU0_SA_DQS_DP<9>")
	)
	(segment
		(start 393.347702 -247.409462)
		(end 393.365736 -247.399048)
		(width 0.09525)
		(layer "In6.Cu")
		(net "M_K_CPU0_SA_DQS_DP<9>")
	)
	(segment
		(start 418.465254 -239.710214)
		(end 419.315392 -240.560352)
		(width 0.16002)
		(layer "In6.Cu")
		(net "M_K_CPU0_SA_DQS_DP<9>")
	)
	(segment
		(start 440.047634 -239.710214)
		(end 440.196732 -239.561116)
		(width 0.16002)
		(layer "In6.Cu")
		(net "M_K_CPU0_SA_DQS_DP<9>")
	)
	(segment
		(start 432.93538 -240.524792)
		(end 433.272438 -240.187734)
		(width 0.16002)
		(layer "In6.Cu")
		(net "M_K_CPU0_SA_DQS_DP<9>")
	)
	(segment
		(start 423.527474 -239.710214)
		(end 424.255438 -239.710214)
		(width 0.16002)
		(layer "In6.Cu")
		(net "M_K_CPU0_SA_DQS_DP<9>")
	)
	(segment
		(start 424.415458 -239.870234)
		(end 424.415458 -240.192814)
		(width 0.16002)
		(layer "In6.Cu")
		(net "M_K_CPU0_SA_DQS_DP<9>")
	)
	(segment
		(start 429.158146 -240.180368)
		(end 429.945546 -239.392968)
		(width 0.16002)
		(layer "In6.Cu")
		(net "M_K_CPU0_SA_DQS_DP<9>")
	)
	(segment
		(start 432.336702 -240.524792)
		(end 432.93538 -240.524792)
		(width 0.16002)
		(layer "In6.Cu")
		(net "M_K_CPU0_SA_DQS_DP<9>")
	)
	(segment
		(start 427.133258 -240.560352)
		(end 428.173642 -240.560352)
		(width 0.16002)
		(layer "In6.Cu")
		(net "M_K_CPU0_SA_DQS_DP<9>")
	)
	(segment
		(start 435.717696 -240.560352)
		(end 436.09768 -240.180368)
		(width 0.16002)
		(layer "In6.Cu")
		(net "M_K_CPU0_SA_DQS_DP<9>")
	)
	(segment
		(start 405.365458 -247.146572)
		(end 412.331662 -240.180368)
		(width 0.16002)
		(layer "In6.Cu")
		(net "M_K_CPU0_SA_DQS_DP<9>")
	)
	(segment
		(start 417.914074 -239.870234)
		(end 418.074094 -239.710214)
		(width 0.16002)
		(layer "In6.Cu")
		(net "M_K_CPU0_SA_DQS_DP<9>")
	)
	(segment
		(start 421.614092 -240.180368)
		(end 422.401492 -239.392968)
		(width 0.16002)
		(layer "In6.Cu")
		(net "M_K_CPU0_SA_DQS_DP<9>")
	)
	(segment
		(start 420.629588 -240.560352)
		(end 421.009572 -240.180368)
		(width 0.16002)
		(layer "In6.Cu")
		(net "M_K_CPU0_SA_DQS_DP<9>")
	)
	(segment
		(start 429.945546 -239.392968)
		(end 430.754282 -239.392968)
		(width 0.16002)
		(layer "In6.Cu")
		(net "M_K_CPU0_SA_DQS_DP<9>")
	)
	(segment
		(start 433.272438 -239.870234)
		(end 433.432458 -239.710214)
		(width 0.16002)
		(layer "In6.Cu")
		(net "M_K_CPU0_SA_DQS_DP<9>")
	)
	(segment
		(start 416.64128 -239.870234)
		(end 416.64128 -240.169954)
		(width 0.16002)
		(layer "In6.Cu")
		(net "M_K_CPU0_SA_DQS_DP<9>")
	)
	(segment
		(start 425.848272 -239.710214)
		(end 426.28312 -239.710214)
		(width 0.16002)
		(layer "In6.Cu")
		(net "M_K_CPU0_SA_DQS_DP<9>")
	)
	(segment
		(start 430.754282 -239.392968)
		(end 431.071528 -239.710214)
		(width 0.16002)
		(layer "In6.Cu")
		(net "M_K_CPU0_SA_DQS_DP<9>")
	)
	(segment
		(start 396.103348 -247.682004)
		(end 396.63878 -247.146572)
		(width 0.16002)
		(layer "In6.Cu")
		(net "M_K_CPU0_SA_DQS_DP<9>")
	)
	(segment
		(start 433.272438 -240.187734)
		(end 433.272438 -239.870234)
		(width 0.16002)
		(layer "In6.Cu")
		(net "M_K_CPU0_SA_DQS_DP<9>")
	)
	(segment
		(start 391.863072 -247.399048)
		(end 391.873486 -247.405144)
		(width 0.09525)
		(layer "In6.Cu")
		(net "M_K_CPU0_SA_DQS_DP<9>")
	)
	(segment
		(start 442.270134 -239.561116)
		(end 442.5442 -239.835182)
		(width 0.16002)
		(layer "In6.Cu")
		(net "M_K_CPU0_SA_DQS_DP<9>")
	)
	(segment
		(start 417.577016 -240.507012)
		(end 417.914074 -240.169954)
		(width 0.16002)
		(layer "In6.Cu")
		(net "M_K_CPU0_SA_DQS_DP<9>")
	)
	(segment
		(start 414.857438 -239.392968)
		(end 415.666174 -239.392968)
		(width 0.16002)
		(layer "In6.Cu")
		(net "M_K_CPU0_SA_DQS_DP<9>")
	)
	(segment
		(start 422.401492 -239.392968)
		(end 423.210228 -239.392968)
		(width 0.16002)
		(layer "In6.Cu")
		(net "M_K_CPU0_SA_DQS_DP<9>")
	)
	(segment
		(start 416.978338 -240.507012)
		(end 417.577016 -240.507012)
		(width 0.16002)
		(layer "In6.Cu")
		(net "M_K_CPU0_SA_DQS_DP<9>")
	)
	(segment
		(start 433.836826 -239.710214)
		(end 434.686964 -240.560352)
		(width 0.16002)
		(layer "In6.Cu")
		(net "M_K_CPU0_SA_DQS_DP<9>")
	)
	(segment
		(start 418.074094 -239.710214)
		(end 418.465254 -239.710214)
		(width 0.16002)
		(layer "In6.Cu")
		(net "M_K_CPU0_SA_DQS_DP<9>")
	)
	(segment
		(start 416.64128 -240.169954)
		(end 416.978338 -240.507012)
		(width 0.16002)
		(layer "In6.Cu")
		(net "M_K_CPU0_SA_DQS_DP<9>")
	)
	(segment
		(start 389.008874 -247.458738)
		(end 389.109712 -247.432068)
		(width 0.09525)
		(layer "In6.Cu")
		(net "M_K_CPU0_SA_DQS_DP<9>")
	)
	(segment
		(start 428.173642 -240.560352)
		(end 428.553626 -240.180368)
		(width 0.16002)
		(layer "In6.Cu")
		(net "M_K_CPU0_SA_DQS_DP<9>")
	)
	(segment
		(start 388.85495 -247.724168)
		(end 389.008874 -247.458738)
		(width 0.09525)
		(layer "In6.Cu")
		(net "M_K_CPU0_SA_DQS_DP<9>")
	)
	(segment
		(start 431.071528 -239.710214)
		(end 431.839624 -239.710214)
		(width 0.16002)
		(layer "In6.Cu")
		(net "M_K_CPU0_SA_DQS_DP<9>")
	)
	(segment
		(start 425.688252 -239.870234)
		(end 425.848272 -239.710214)
		(width 0.16002)
		(layer "In6.Cu")
		(net "M_K_CPU0_SA_DQS_DP<9>")
	)
	(segment
		(start 423.210228 -239.392968)
		(end 423.527474 -239.710214)
		(width 0.16002)
		(layer "In6.Cu")
		(net "M_K_CPU0_SA_DQS_DP<9>")
	)
	(segment
		(start 419.315392 -240.560352)
		(end 420.629588 -240.560352)
		(width 0.16002)
		(layer "In6.Cu")
		(net "M_K_CPU0_SA_DQS_DP<9>")
	)
	(segment
		(start 438.615582 -239.710214)
		(end 440.047634 -239.710214)
		(width 0.16002)
		(layer "In6.Cu")
		(net "M_K_CPU0_SA_DQS_DP<9>")
	)
	(segment
		(start 428.553626 -240.180368)
		(end 429.158146 -240.180368)
		(width 0.16002)
		(layer "In6.Cu")
		(net "M_K_CPU0_SA_DQS_DP<9>")
	)
	(segment
		(start 392.425682 -247.399048)
		(end 392.43762 -247.39219)
		(width 0.09525)
		(layer "In6.Cu")
		(net "M_K_CPU0_SA_DQS_DP<9>")
	)
	(segment
		(start 391.851134 -247.39219)
		(end 391.863072 -247.399048)
		(width 0.09525)
		(layer "In6.Cu")
		(net "M_K_CPU0_SA_DQS_DP<9>")
	)
	(segment
		(start 395.662404 -247.682004)
		(end 395.686026 -247.682004)
		(width 0.09525)
		(layer "In6.Cu")
		(net "M_K_CPU0_SA_DQS_DP<9>")
	)
	(segment
		(start 425.688252 -240.192814)
		(end 425.688252 -239.870234)
		(width 0.16002)
		(layer "In6.Cu")
		(net "M_K_CPU0_SA_DQS_DP<9>")
	)
	(segment
		(start 425.351194 -240.529872)
		(end 425.688252 -240.192814)
		(width 0.16002)
		(layer "In6.Cu")
		(net "M_K_CPU0_SA_DQS_DP<9>")
	)
	(segment
		(start 431.839624 -239.710214)
		(end 431.999644 -239.870234)
		(width 0.16002)
		(layer "In6.Cu")
		(net "M_K_CPU0_SA_DQS_DP<9>")
	)
	(segment
		(start 395.603476 -247.623076)
		(end 395.662404 -247.682004)
		(width 0.09525)
		(layer "In6.Cu")
		(net "M_K_CPU0_SA_DQS_DP<9>")
	)
	(segment
		(start 426.28312 -239.710214)
		(end 427.133258 -240.560352)
		(width 0.16002)
		(layer "In6.Cu")
		(net "M_K_CPU0_SA_DQS_DP<9>")
	)
	(segment
		(start 424.415458 -240.192814)
		(end 424.752516 -240.529872)
		(width 0.16002)
		(layer "In6.Cu")
		(net "M_K_CPU0_SA_DQS_DP<9>")
	)
	(segment
		(start 393.365736 -247.399048)
		(end 393.374118 -247.394222)
		(width 0.09525)
		(layer "In6.Cu")
		(net "M_K_CPU0_SA_DQS_DP<9>")
	)
	(segment
		(start 434.686964 -240.560352)
		(end 435.717696 -240.560352)
		(width 0.16002)
		(layer "In6.Cu")
		(net "M_K_CPU0_SA_DQS_DP<9>")
	)
	(segment
		(start 421.009572 -240.180368)
		(end 421.614092 -240.180368)
		(width 0.16002)
		(layer "In6.Cu")
		(net "M_K_CPU0_SA_DQS_DP<9>")
	)
	(segment
		(start 412.331662 -240.180368)
		(end 414.070038 -240.180368)
		(width 0.16002)
		(layer "In6.Cu")
		(net "M_K_CPU0_SA_DQS_DP<9>")
	)
	(segment
		(start 415.666174 -239.392968)
		(end 415.98342 -239.710214)
		(width 0.16002)
		(layer "In6.Cu")
		(net "M_K_CPU0_SA_DQS_DP<9>")
	)
	(segment
		(start 424.752516 -240.529872)
		(end 425.351194 -240.529872)
		(width 0.16002)
		(layer "In6.Cu")
		(net "M_K_CPU0_SA_DQS_DP<9>")
	)
	(segment
		(start 433.432458 -239.710214)
		(end 433.836826 -239.710214)
		(width 0.16002)
		(layer "In6.Cu")
		(net "M_K_CPU0_SA_DQS_DP<9>")
	)
	(segment
		(start 436.09768 -240.180368)
		(end 436.7022 -240.180368)
		(width 0.16002)
		(layer "In6.Cu")
		(net "M_K_CPU0_SA_DQS_DP<9>")
	)
	(segment
		(start 431.999644 -240.187734)
		(end 432.336702 -240.524792)
		(width 0.16002)
		(layer "In6.Cu")
		(net "M_K_CPU0_SA_DQS_DP<9>")
	)
	(segment
		(start 436.7022 -240.180368)
		(end 437.4896 -239.392968)
		(width 0.16002)
		(layer "In6.Cu")
		(net "M_K_CPU0_SA_DQS_DP<9>")
	)
	(segment
		(start 417.914074 -240.169954)
		(end 417.914074 -239.870234)
		(width 0.16002)
		(layer "In6.Cu")
		(net "M_K_CPU0_SA_DQS_DP<9>")
	)
	(segment
		(start 396.63878 -247.146572)
		(end 405.365458 -247.146572)
		(width 0.16002)
		(layer "In6.Cu")
		(net "M_K_CPU0_SA_DQS_DP<9>")
	)
	(segment
		(start 393.985242 -247.623076)
		(end 395.603476 -247.623076)
		(width 0.09525)
		(layer "In6.Cu")
		(net "M_K_CPU0_SA_DQS_DP<9>")
	)
	(segment
		(start 424.255438 -239.710214)
		(end 424.415458 -239.870234)
		(width 0.16002)
		(layer "In6.Cu")
		(net "M_K_CPU0_SA_DQS_DP<9>")
	)
	(segment
		(start 395.686026 -247.682004)
		(end 396.103348 -247.682004)
		(width 0.16002)
		(layer "In6.Cu")
		(net "M_K_CPU0_SA_DQS_DP<9>")
	)
	(segment
		(start 389.606282 -247.399048)
		(end 389.614664 -247.394222)
		(width 0.09525)
		(layer "In6.Cu")
		(net "M_K_CPU0_SA_DQS_DP<9>")
	)
	(segment
		(start 437.4896 -239.392968)
		(end 438.298336 -239.392968)
		(width 0.16002)
		(layer "In6.Cu")
		(net "M_K_CPU0_SA_DQS_DP<9>")
	)
	(segment
		(start 438.298336 -239.392968)
		(end 438.615582 -239.710214)
		(width 0.16002)
		(layer "In6.Cu")
		(net "M_K_CPU0_SA_DQS_DP<9>")
	)
	(segment
		(start 431.999644 -239.870234)
		(end 431.999644 -240.187734)
		(width 0.16002)
		(layer "In6.Cu")
		(net "M_K_CPU0_SA_DQS_DP<9>")
	)
	(arc
		(start 391.486136 -247.399048)
		(mid 391.667752 -247.348311)
		(end 391.851134 -247.39219)
		(width 0.09525)
		(layer "In6.Cu")
		(net "M_K_CPU0_SA_DQS_DP<9>")
	)
	(arc
		(start 392.43762 -247.39219)
		(mid 392.621255 -247.34824)
		(end 392.803126 -247.399048)
		(width 0.09525)
		(layer "In6.Cu")
		(net "M_K_CPU0_SA_DQS_DP<9>")
	)
	(arc
		(start 391.873486 -247.405144)
		(mid 392.150394 -247.474821)
		(end 392.425682 -247.399048)
		(width 0.09525)
		(layer "In6.Cu")
		(net "M_K_CPU0_SA_DQS_DP<9>")
	)
	(arc
		(start 389.983472 -247.399048)
		(mid 390.264904 -247.474803)
		(end 390.546336 -247.399048)
		(width 0.09525)
		(layer "In6.Cu")
		(net "M_K_CPU0_SA_DQS_DP<9>")
	)
	(arc
		(start 389.109712 -247.432068)
		(mid 389.11958 -247.436099)
		(end 389.129524 -247.439942)
		(width 0.09525)
		(layer "In6.Cu")
		(net "M_K_CPU0_SA_DQS_DP<9>")
	)
	(arc
		(start 390.546336 -247.399048)
		(mid 390.734804 -247.348371)
		(end 390.923272 -247.399048)
		(width 0.09525)
		(layer "In6.Cu")
		(net "M_K_CPU0_SA_DQS_DP<9>")
	)
	(arc
		(start 393.374118 -247.394222)
		(mid 393.558896 -247.348429)
		(end 393.742418 -247.399048)
		(width 0.09525)
		(layer "In6.Cu")
		(net "M_K_CPU0_SA_DQS_DP<9>")
	)
	(arc
		(start 389.129524 -247.439942)
		(mid 389.372488 -247.472929)
		(end 389.606282 -247.399048)
		(width 0.09525)
		(layer "In6.Cu")
		(net "M_K_CPU0_SA_DQS_DP<9>")
	)
	(arc
		(start 389.614664 -247.394222)
		(mid 389.799696 -247.348308)
		(end 389.983472 -247.399048)
		(width 0.09525)
		(layer "In6.Cu")
		(net "M_K_CPU0_SA_DQS_DP<9>")
	)
	(arc
		(start 390.923272 -247.399048)
		(mid 391.204704 -247.474803)
		(end 391.486136 -247.399048)
		(width 0.09525)
		(layer "In6.Cu")
		(net "M_K_CPU0_SA_DQS_DP<9>")
	)
	(arc
		(start 393.742418 -247.399048)
		(mid 393.783199 -247.425981)
		(end 393.820142 -247.457976)
		(width 0.09525)
		(layer "In6.Cu")
		(net "M_K_CPU0_SA_DQS_DP<9>")
	)
	(arc
		(start 392.803126 -247.399048)
		(mid 393.074068 -247.474828)
		(end 393.347702 -247.409462)
		(width 0.09525)
		(layer "In6.Cu")
		(net "M_K_CPU0_SA_DQS_DP<9>")
	)
	(segment
		(start 388.387844 -243.13007)
		(end 388.85495 -242.864132)
		(width 0.12954)
		(layer "F.Cu")
		(net "M_K_CPU0_SA_DQS_DP<8>")
	)
	(segment
		(start 415.666174 -230.042974)
		(end 414.857438 -230.042974)
		(width 0.16002)
		(layer "In6.Cu")
		(net "M_K_CPU0_SA_DQS_DP<8>")
	)
	(segment
		(start 417.75126 -230.001572)
		(end 417.403026 -230.001572)
		(width 0.16002)
		(layer "In6.Cu")
		(net "M_K_CPU0_SA_DQS_DP<8>")
	)
	(segment
		(start 392.432794 -242.534186)
		(end 392.431016 -242.535202)
		(width 0.09525)
		(layer "In6.Cu")
		(net "M_K_CPU0_SA_DQS_DP<8>")
	)
	(segment
		(start 417.91128 -230.161592)
		(end 417.75126 -230.001572)
		(width 0.16002)
		(layer "In6.Cu")
		(net "M_K_CPU0_SA_DQS_DP<8>")
	)
	(segment
		(start 429.158146 -230.830374)
		(end 428.553626 -230.830374)
		(width 0.16002)
		(layer "In6.Cu")
		(net "M_K_CPU0_SA_DQS_DP<8>")
	)
	(segment
		(start 392.434826 -242.532916)
		(end 392.432794 -242.534186)
		(width 0.09525)
		(layer "In6.Cu")
		(net "M_K_CPU0_SA_DQS_DP<8>")
	)
	(segment
		(start 414.070038 -230.830374)
		(end 411.443424 -230.830374)
		(width 0.16002)
		(layer "In6.Cu")
		(net "M_K_CPU0_SA_DQS_DP<8>")
	)
	(segment
		(start 418.810186 -230.705152)
		(end 418.248338 -230.705152)
		(width 0.16002)
		(layer "In6.Cu")
		(net "M_K_CPU0_SA_DQS_DP<8>")
	)
	(segment
		(start 392.431016 -242.535202)
		(end 392.430254 -242.53571)
		(width 0.09525)
		(layer "In6.Cu")
		(net "M_K_CPU0_SA_DQS_DP<8>")
	)
	(segment
		(start 417.243006 -230.368094)
		(end 416.905948 -230.705152)
		(width 0.16002)
		(layer "In6.Cu")
		(net "M_K_CPU0_SA_DQS_DP<8>")
	)
	(segment
		(start 426.859446 -231.210358)
		(end 426.009308 -230.36022)
		(width 0.16002)
		(layer "In6.Cu")
		(net "M_K_CPU0_SA_DQS_DP<8>")
	)
	(segment
		(start 389.109712 -242.572032)
		(end 389.008874 -242.598702)
		(width 0.09525)
		(layer "In6.Cu")
		(net "M_K_CPU0_SA_DQS_DP<8>")
	)
	(segment
		(start 395.776704 -241.454432)
		(end 395.518894 -241.454432)
		(width 0.09525)
		(layer "In6.Cu")
		(net "M_K_CPU0_SA_DQS_DP<8>")
	)
	(segment
		(start 391.873486 -242.545108)
		(end 391.863072 -242.539012)
		(width 0.09525)
		(layer "In6.Cu")
		(net "M_K_CPU0_SA_DQS_DP<8>")
	)
	(segment
		(start 416.905948 -230.705152)
		(end 416.328352 -230.705152)
		(width 0.16002)
		(layer "In6.Cu")
		(net "M_K_CPU0_SA_DQS_DP<8>")
	)
	(segment
		(start 394.835126 -242.1382)
		(end 394.10132 -242.1382)
		(width 0.09525)
		(layer "In6.Cu")
		(net "M_K_CPU0_SA_DQS_DP<8>")
	)
	(segment
		(start 409.848558 -232.852468)
		(end 409.848558 -233.328972)
		(width 0.16002)
		(layer "In6.Cu")
		(net "M_K_CPU0_SA_DQS_DP<8>")
	)
	(segment
		(start 414.857438 -230.042974)
		(end 414.070038 -230.830374)
		(width 0.16002)
		(layer "In6.Cu")
		(net "M_K_CPU0_SA_DQS_DP<8>")
	)
	(segment
		(start 408.620976 -233.652822)
		(end 408.337258 -233.93654)
		(width 0.16002)
		(layer "In6.Cu")
		(net "M_K_CPU0_SA_DQS_DP<8>")
	)
	(segment
		(start 411.443424 -230.830374)
		(end 411.121606 -231.152192)
		(width 0.16002)
		(layer "In6.Cu")
		(net "M_K_CPU0_SA_DQS_DP<8>")
	)
	(segment
		(start 409.747974 -232.525824)
		(end 409.747974 -232.751884)
		(width 0.16002)
		(layer "In6.Cu")
		(net "M_K_CPU0_SA_DQS_DP<8>")
	)
	(segment
		(start 395.518894 -241.454432)
		(end 394.835126 -242.1382)
		(width 0.09525)
		(layer "In6.Cu")
		(net "M_K_CPU0_SA_DQS_DP<8>")
	)
	(segment
		(start 438.298336 -230.042974)
		(end 437.4896 -230.042974)
		(width 0.16002)
		(layer "In6.Cu")
		(net "M_K_CPU0_SA_DQS_DP<8>")
	)
	(segment
		(start 436.09768 -230.830374)
		(end 435.717696 -231.210358)
		(width 0.16002)
		(layer "In6.Cu")
		(net "M_K_CPU0_SA_DQS_DP<8>")
	)
	(segment
		(start 411.121606 -231.152192)
		(end 411.121606 -231.378252)
		(width 0.16002)
		(layer "In6.Cu")
		(net "M_K_CPU0_SA_DQS_DP<8>")
	)
	(segment
		(start 420.629588 -231.210358)
		(end 419.315392 -231.210358)
		(width 0.16002)
		(layer "In6.Cu")
		(net "M_K_CPU0_SA_DQS_DP<8>")
	)
	(segment
		(start 410.797756 -232.379774)
		(end 410.321252 -232.379774)
		(width 0.16002)
		(layer "In6.Cu")
		(net "M_K_CPU0_SA_DQS_DP<8>")
	)
	(segment
		(start 409.848558 -233.328972)
		(end 409.424124 -233.753406)
		(width 0.16002)
		(layer "In6.Cu")
		(net "M_K_CPU0_SA_DQS_DP<8>")
	)
	(segment
		(start 423.527474 -230.36022)
		(end 423.210228 -230.042974)
		(width 0.16002)
		(layer "In6.Cu")
		(net "M_K_CPU0_SA_DQS_DP<8>")
	)
	(segment
		(start 435.717696 -231.210358)
		(end 434.4035 -231.210358)
		(width 0.16002)
		(layer "In6.Cu")
		(net "M_K_CPU0_SA_DQS_DP<8>")
	)
	(segment
		(start 391.863072 -242.539012)
		(end 391.851134 -242.532154)
		(width 0.09525)
		(layer "In6.Cu")
		(net "M_K_CPU0_SA_DQS_DP<8>")
	)
	(segment
		(start 419.315392 -231.210358)
		(end 418.810186 -230.705152)
		(width 0.16002)
		(layer "In6.Cu")
		(net "M_K_CPU0_SA_DQS_DP<8>")
	)
	(segment
		(start 417.243006 -230.161592)
		(end 417.243006 -230.368094)
		(width 0.16002)
		(layer "In6.Cu")
		(net "M_K_CPU0_SA_DQS_DP<8>")
	)
	(segment
		(start 411.22219 -231.95534)
		(end 410.797756 -232.379774)
		(width 0.16002)
		(layer "In6.Cu")
		(net "M_K_CPU0_SA_DQS_DP<8>")
	)
	(segment
		(start 436.7022 -230.830374)
		(end 436.09768 -230.830374)
		(width 0.16002)
		(layer "In6.Cu")
		(net "M_K_CPU0_SA_DQS_DP<8>")
	)
	(segment
		(start 442.5442 -230.485188)
		(end 442.270134 -230.211122)
		(width 0.16002)
		(layer "In6.Cu")
		(net "M_K_CPU0_SA_DQS_DP<8>")
	)
	(segment
		(start 431.071528 -230.36022)
		(end 430.657762 -229.946454)
		(width 0.16002)
		(layer "In6.Cu")
		(net "M_K_CPU0_SA_DQS_DP<8>")
	)
	(segment
		(start 440.196732 -230.211122)
		(end 440.047634 -230.36022)
		(width 0.16002)
		(layer "In6.Cu")
		(net "M_K_CPU0_SA_DQS_DP<8>")
	)
	(segment
		(start 408.847036 -233.652822)
		(end 408.620976 -233.652822)
		(width 0.16002)
		(layer "In6.Cu")
		(net "M_K_CPU0_SA_DQS_DP<8>")
	)
	(segment
		(start 411.22219 -231.478836)
		(end 411.22219 -231.95534)
		(width 0.16002)
		(layer "In6.Cu")
		(net "M_K_CPU0_SA_DQS_DP<8>")
	)
	(segment
		(start 408.337258 -233.93654)
		(end 408.337258 -235.942632)
		(width 0.16002)
		(layer "In6.Cu")
		(net "M_K_CPU0_SA_DQS_DP<8>")
	)
	(segment
		(start 389.008874 -242.598702)
		(end 388.85495 -242.864132)
		(width 0.09525)
		(layer "In6.Cu")
		(net "M_K_CPU0_SA_DQS_DP<8>")
	)
	(segment
		(start 392.430254 -242.53571)
		(end 392.425682 -242.539012)
		(width 0.09525)
		(layer "In6.Cu")
		(net "M_K_CPU0_SA_DQS_DP<8>")
	)
	(segment
		(start 408.337258 -235.942632)
		(end 402.76653 -241.51336)
		(width 0.16002)
		(layer "In6.Cu")
		(net "M_K_CPU0_SA_DQS_DP<8>")
	)
	(segment
		(start 418.248338 -230.705152)
		(end 417.91128 -230.368094)
		(width 0.16002)
		(layer "In6.Cu")
		(net "M_K_CPU0_SA_DQS_DP<8>")
	)
	(segment
		(start 421.009572 -230.830374)
		(end 420.629588 -231.210358)
		(width 0.16002)
		(layer "In6.Cu")
		(net "M_K_CPU0_SA_DQS_DP<8>")
	)
	(segment
		(start 393.624816 -242.614704)
		(end 393.084558 -242.614704)
		(width 0.09525)
		(layer "In6.Cu")
		(net "M_K_CPU0_SA_DQS_DP<8>")
	)
	(segment
		(start 417.91128 -230.368094)
		(end 417.91128 -230.161592)
		(width 0.16002)
		(layer "In6.Cu")
		(net "M_K_CPU0_SA_DQS_DP<8>")
	)
	(segment
		(start 389.614664 -242.534186)
		(end 389.606282 -242.539012)
		(width 0.09525)
		(layer "In6.Cu")
		(net "M_K_CPU0_SA_DQS_DP<8>")
	)
	(segment
		(start 422.401492 -230.042974)
		(end 421.614092 -230.830374)
		(width 0.16002)
		(layer "In6.Cu")
		(net "M_K_CPU0_SA_DQS_DP<8>")
	)
	(segment
		(start 409.424124 -233.753406)
		(end 408.94762 -233.753406)
		(width 0.16002)
		(layer "In6.Cu")
		(net "M_K_CPU0_SA_DQS_DP<8>")
	)
	(segment
		(start 394.10132 -242.1382)
		(end 393.624816 -242.614704)
		(width 0.09525)
		(layer "In6.Cu")
		(net "M_K_CPU0_SA_DQS_DP<8>")
	)
	(segment
		(start 428.553626 -230.830374)
		(end 428.173642 -231.210358)
		(width 0.16002)
		(layer "In6.Cu")
		(net "M_K_CPU0_SA_DQS_DP<8>")
	)
	(segment
		(start 423.210228 -230.042974)
		(end 422.401492 -230.042974)
		(width 0.16002)
		(layer "In6.Cu")
		(net "M_K_CPU0_SA_DQS_DP<8>")
	)
	(segment
		(start 426.009308 -230.36022)
		(end 423.527474 -230.36022)
		(width 0.16002)
		(layer "In6.Cu")
		(net "M_K_CPU0_SA_DQS_DP<8>")
	)
	(segment
		(start 434.4035 -231.210358)
		(end 433.553362 -230.36022)
		(width 0.16002)
		(layer "In6.Cu")
		(net "M_K_CPU0_SA_DQS_DP<8>")
	)
	(segment
		(start 440.047634 -230.36022)
		(end 438.615582 -230.36022)
		(width 0.16002)
		(layer "In6.Cu")
		(net "M_K_CPU0_SA_DQS_DP<8>")
	)
	(segment
		(start 416.328352 -230.705152)
		(end 415.666174 -230.042974)
		(width 0.16002)
		(layer "In6.Cu")
		(net "M_K_CPU0_SA_DQS_DP<8>")
	)
	(segment
		(start 408.94762 -233.753406)
		(end 408.847036 -233.652822)
		(width 0.16002)
		(layer "In6.Cu")
		(net "M_K_CPU0_SA_DQS_DP<8>")
	)
	(segment
		(start 411.121606 -231.378252)
		(end 411.22219 -231.478836)
		(width 0.16002)
		(layer "In6.Cu")
		(net "M_K_CPU0_SA_DQS_DP<8>")
	)
	(segment
		(start 395.835632 -241.51336)
		(end 395.776704 -241.454432)
		(width 0.09525)
		(layer "In6.Cu")
		(net "M_K_CPU0_SA_DQS_DP<8>")
	)
	(segment
		(start 410.321252 -232.379774)
		(end 410.220668 -232.27919)
		(width 0.16002)
		(layer "In6.Cu")
		(net "M_K_CPU0_SA_DQS_DP<8>")
	)
	(segment
		(start 402.76653 -241.51336)
		(end 395.859254 -241.51336)
		(width 0.16002)
		(layer "In6.Cu")
		(net "M_K_CPU0_SA_DQS_DP<8>")
	)
	(segment
		(start 410.220668 -232.27919)
		(end 409.994608 -232.27919)
		(width 0.16002)
		(layer "In6.Cu")
		(net "M_K_CPU0_SA_DQS_DP<8>")
	)
	(segment
		(start 437.4896 -230.042974)
		(end 436.7022 -230.830374)
		(width 0.16002)
		(layer "In6.Cu")
		(net "M_K_CPU0_SA_DQS_DP<8>")
	)
	(segment
		(start 430.042066 -229.946454)
		(end 429.158146 -230.830374)
		(width 0.16002)
		(layer "In6.Cu")
		(net "M_K_CPU0_SA_DQS_DP<8>")
	)
	(segment
		(start 428.173642 -231.210358)
		(end 426.859446 -231.210358)
		(width 0.16002)
		(layer "In6.Cu")
		(net "M_K_CPU0_SA_DQS_DP<8>")
	)
	(segment
		(start 395.859254 -241.51336)
		(end 395.835632 -241.51336)
		(width 0.09525)
		(layer "In6.Cu")
		(net "M_K_CPU0_SA_DQS_DP<8>")
	)
	(segment
		(start 438.615582 -230.36022)
		(end 438.298336 -230.042974)
		(width 0.16002)
		(layer "In6.Cu")
		(net "M_K_CPU0_SA_DQS_DP<8>")
	)
	(segment
		(start 430.657762 -229.946454)
		(end 430.042066 -229.946454)
		(width 0.16002)
		(layer "In6.Cu")
		(net "M_K_CPU0_SA_DQS_DP<8>")
	)
	(segment
		(start 409.994608 -232.27919)
		(end 409.747974 -232.525824)
		(width 0.16002)
		(layer "In6.Cu")
		(net "M_K_CPU0_SA_DQS_DP<8>")
	)
	(segment
		(start 417.403026 -230.001572)
		(end 417.243006 -230.161592)
		(width 0.16002)
		(layer "In6.Cu")
		(net "M_K_CPU0_SA_DQS_DP<8>")
	)
	(segment
		(start 442.270134 -230.211122)
		(end 440.196732 -230.211122)
		(width 0.16002)
		(layer "In6.Cu")
		(net "M_K_CPU0_SA_DQS_DP<8>")
	)
	(segment
		(start 409.747974 -232.751884)
		(end 409.848558 -232.852468)
		(width 0.16002)
		(layer "In6.Cu")
		(net "M_K_CPU0_SA_DQS_DP<8>")
	)
	(segment
		(start 421.614092 -230.830374)
		(end 421.009572 -230.830374)
		(width 0.16002)
		(layer "In6.Cu")
		(net "M_K_CPU0_SA_DQS_DP<8>")
	)
	(segment
		(start 433.553362 -230.36022)
		(end 431.071528 -230.36022)
		(width 0.16002)
		(layer "In6.Cu")
		(net "M_K_CPU0_SA_DQS_DP<8>")
	)
	(arc
		(start 389.983472 -242.539012)
		(mid 389.799697 -242.48824)
		(end 389.614664 -242.534186)
		(width 0.09525)
		(layer "In6.Cu")
		(net "M_K_CPU0_SA_DQS_DP<8>")
	)
	(arc
		(start 392.425682 -242.539012)
		(mid 392.150393 -242.614733)
		(end 391.873486 -242.545108)
		(width 0.09525)
		(layer "In6.Cu")
		(net "M_K_CPU0_SA_DQS_DP<8>")
	)
	(arc
		(start 390.546336 -242.539012)
		(mid 390.264904 -242.614767)
		(end 389.983472 -242.539012)
		(width 0.09525)
		(layer "In6.Cu")
		(net "M_K_CPU0_SA_DQS_DP<8>")
	)
	(arc
		(start 389.129524 -242.579906)
		(mid 389.119581 -242.576063)
		(end 389.109712 -242.572032)
		(width 0.09525)
		(layer "In6.Cu")
		(net "M_K_CPU0_SA_DQS_DP<8>")
	)
	(arc
		(start 390.923272 -242.539012)
		(mid 390.734804 -242.488335)
		(end 390.546336 -242.539012)
		(width 0.09525)
		(layer "In6.Cu")
		(net "M_K_CPU0_SA_DQS_DP<8>")
	)
	(arc
		(start 391.486136 -242.539012)
		(mid 391.204704 -242.614767)
		(end 390.923272 -242.539012)
		(width 0.09525)
		(layer "In6.Cu")
		(net "M_K_CPU0_SA_DQS_DP<8>")
	)
	(arc
		(start 389.606282 -242.539012)
		(mid 389.372487 -242.612879)
		(end 389.129524 -242.579906)
		(width 0.09525)
		(layer "In6.Cu")
		(net "M_K_CPU0_SA_DQS_DP<8>")
	)
	(arc
		(start 392.803126 -242.538504)
		(mid 392.619694 -242.487558)
		(end 392.434826 -242.532916)
		(width 0.09525)
		(layer "In6.Cu")
		(net "M_K_CPU0_SA_DQS_DP<8>")
	)
	(arc
		(start 393.084558 -242.614704)
		(mid 392.938807 -242.59521)
		(end 392.803126 -242.538504)
		(width 0.09525)
		(layer "In6.Cu")
		(net "M_K_CPU0_SA_DQS_DP<8>")
	)
	(arc
		(start 391.851134 -242.532154)
		(mid 391.667753 -242.488323)
		(end 391.486136 -242.539012)
		(width 0.09525)
		(layer "In6.Cu")
		(net "M_K_CPU0_SA_DQS_DP<8>")
	)
	(segment
		(start 388.387844 -238.270034)
		(end 388.85495 -238.004096)
		(width 0.12954)
		(layer "F.Cu")
		(net "M_K_CPU0_SA_DQS_DP<7>")
	)
	(segment
		(start 434.403246 -221.86011)
		(end 435.71795 -221.86011)
		(width 0.16002)
		(layer "In6.Cu")
		(net "M_K_CPU0_SA_DQS_DP<7>")
	)
	(segment
		(start 433.553362 -221.010226)
		(end 434.403246 -221.86011)
		(width 0.16002)
		(layer "In6.Cu")
		(net "M_K_CPU0_SA_DQS_DP<7>")
	)
	(segment
		(start 437.4896 -220.69298)
		(end 438.298336 -220.69298)
		(width 0.16002)
		(layer "In6.Cu")
		(net "M_K_CPU0_SA_DQS_DP<7>")
	)
	(segment
		(start 429.158146 -221.48038)
		(end 429.945546 -220.69298)
		(width 0.16002)
		(layer "In6.Cu")
		(net "M_K_CPU0_SA_DQS_DP<7>")
	)
	(segment
		(start 395.776704 -235.815632)
		(end 395.835632 -235.87456)
		(width 0.09525)
		(layer "In6.Cu")
		(net "M_K_CPU0_SA_DQS_DP<7>")
	)
	(segment
		(start 401.136866 -233.188764)
		(end 401.542504 -233.594402)
		(width 0.16002)
		(layer "In6.Cu")
		(net "M_K_CPU0_SA_DQS_DP<7>")
	)
	(segment
		(start 415.98342 -221.010226)
		(end 418.465254 -221.010226)
		(width 0.16002)
		(layer "In6.Cu")
		(net "M_K_CPU0_SA_DQS_DP<7>")
	)
	(segment
		(start 420.629842 -221.86011)
		(end 421.009572 -221.48038)
		(width 0.16002)
		(layer "In6.Cu")
		(net "M_K_CPU0_SA_DQS_DP<7>")
	)
	(segment
		(start 394.290296 -236.51464)
		(end 394.54328 -236.261656)
		(width 0.09525)
		(layer "In6.Cu")
		(net "M_K_CPU0_SA_DQS_DP<7>")
	)
	(segment
		(start 435.71795 -221.86011)
		(end 436.09768 -221.48038)
		(width 0.16002)
		(layer "In6.Cu")
		(net "M_K_CPU0_SA_DQS_DP<7>")
	)
	(segment
		(start 436.09768 -221.48038)
		(end 436.7022 -221.48038)
		(width 0.16002)
		(layer "In6.Cu")
		(net "M_K_CPU0_SA_DQS_DP<7>")
	)
	(segment
		(start 428.173896 -221.86011)
		(end 428.553626 -221.48038)
		(width 0.16002)
		(layer "In6.Cu")
		(net "M_K_CPU0_SA_DQS_DP<7>")
	)
	(segment
		(start 410.224478 -223.875092)
		(end 410.224478 -223.194372)
		(width 0.16002)
		(layer "In6.Cu")
		(net "M_K_CPU0_SA_DQS_DP<7>")
	)
	(segment
		(start 398.22501 -235.87456)
		(end 399.537174 -234.562396)
		(width 0.16002)
		(layer "In6.Cu")
		(net "M_K_CPU0_SA_DQS_DP<7>")
	)
	(segment
		(start 415.666174 -220.69298)
		(end 415.98342 -221.010226)
		(width 0.16002)
		(layer "In6.Cu")
		(net "M_K_CPU0_SA_DQS_DP<7>")
	)
	(segment
		(start 414.070038 -221.48038)
		(end 414.857438 -220.69298)
		(width 0.16002)
		(layer "In6.Cu")
		(net "M_K_CPU0_SA_DQS_DP<7>")
	)
	(segment
		(start 401.542504 -233.594402)
		(end 402.019008 -233.594402)
		(width 0.16002)
		(layer "In6.Cu")
		(net "M_K_CPU0_SA_DQS_DP<7>")
	)
	(segment
		(start 400.645376 -234.968034)
		(end 401.06981 -234.5436)
		(width 0.16002)
		(layer "In6.Cu")
		(net "M_K_CPU0_SA_DQS_DP<7>")
	)
	(segment
		(start 410.224478 -223.194372)
		(end 411.93847 -221.48038)
		(width 0.16002)
		(layer "In6.Cu")
		(net "M_K_CPU0_SA_DQS_DP<7>")
	)
	(segment
		(start 388.85495 -238.004096)
		(end 389.008874 -237.738666)
		(width 0.09525)
		(layer "In6.Cu")
		(net "M_K_CPU0_SA_DQS_DP<7>")
	)
	(segment
		(start 430.754282 -220.69298)
		(end 431.071528 -221.010226)
		(width 0.16002)
		(layer "In6.Cu")
		(net "M_K_CPU0_SA_DQS_DP<7>")
	)
	(segment
		(start 436.7022 -221.48038)
		(end 437.4896 -220.69298)
		(width 0.16002)
		(layer "In6.Cu")
		(net "M_K_CPU0_SA_DQS_DP<7>")
	)
	(segment
		(start 411.93847 -221.48038)
		(end 414.070038 -221.48038)
		(width 0.16002)
		(layer "In6.Cu")
		(net "M_K_CPU0_SA_DQS_DP<7>")
	)
	(segment
		(start 402.037804 -232.061766)
		(end 410.224478 -223.875092)
		(width 0.16002)
		(layer "In6.Cu")
		(net "M_K_CPU0_SA_DQS_DP<7>")
	)
	(segment
		(start 389.008874 -237.738666)
		(end 389.109712 -237.711996)
		(width 0.09525)
		(layer "In6.Cu")
		(net "M_K_CPU0_SA_DQS_DP<7>")
	)
	(segment
		(start 400.910806 -233.188764)
		(end 401.136866 -233.188764)
		(width 0.16002)
		(layer "In6.Cu")
		(net "M_K_CPU0_SA_DQS_DP<7>")
	)
	(segment
		(start 421.614092 -221.48038)
		(end 422.401492 -220.69298)
		(width 0.16002)
		(layer "In6.Cu")
		(net "M_K_CPU0_SA_DQS_DP<7>")
	)
	(segment
		(start 402.443442 -232.693464)
		(end 402.037804 -232.287826)
		(width 0.16002)
		(layer "In6.Cu")
		(net "M_K_CPU0_SA_DQS_DP<7>")
	)
	(segment
		(start 426.009308 -221.010226)
		(end 426.859192 -221.86011)
		(width 0.16002)
		(layer "In6.Cu")
		(net "M_K_CPU0_SA_DQS_DP<7>")
	)
	(segment
		(start 438.298336 -220.69298)
		(end 438.615582 -221.010226)
		(width 0.16002)
		(layer "In6.Cu")
		(net "M_K_CPU0_SA_DQS_DP<7>")
	)
	(segment
		(start 422.401492 -220.69298)
		(end 423.210228 -220.69298)
		(width 0.16002)
		(layer "In6.Cu")
		(net "M_K_CPU0_SA_DQS_DP<7>")
	)
	(segment
		(start 419.315138 -221.86011)
		(end 420.629842 -221.86011)
		(width 0.16002)
		(layer "In6.Cu")
		(net "M_K_CPU0_SA_DQS_DP<7>")
	)
	(segment
		(start 399.763234 -234.562396)
		(end 400.168872 -234.968034)
		(width 0.16002)
		(layer "In6.Cu")
		(net "M_K_CPU0_SA_DQS_DP<7>")
	)
	(segment
		(start 431.071528 -221.010226)
		(end 433.553362 -221.010226)
		(width 0.16002)
		(layer "In6.Cu")
		(net "M_K_CPU0_SA_DQS_DP<7>")
	)
	(segment
		(start 394.290296 -236.792516)
		(end 394.290296 -236.51464)
		(width 0.09525)
		(layer "In6.Cu")
		(net "M_K_CPU0_SA_DQS_DP<7>")
	)
	(segment
		(start 421.009572 -221.48038)
		(end 421.614092 -221.48038)
		(width 0.16002)
		(layer "In6.Cu")
		(net "M_K_CPU0_SA_DQS_DP<7>")
	)
	(segment
		(start 429.945546 -220.69298)
		(end 430.754282 -220.69298)
		(width 0.16002)
		(layer "In6.Cu")
		(net "M_K_CPU0_SA_DQS_DP<7>")
	)
	(segment
		(start 391.851134 -237.672118)
		(end 391.863072 -237.678976)
		(width 0.09525)
		(layer "In6.Cu")
		(net "M_K_CPU0_SA_DQS_DP<7>")
	)
	(segment
		(start 392.425682 -237.678976)
		(end 392.43762 -237.672118)
		(width 0.09525)
		(layer "In6.Cu")
		(net "M_K_CPU0_SA_DQS_DP<7>")
	)
	(segment
		(start 395.533626 -235.815632)
		(end 395.776704 -235.815632)
		(width 0.09525)
		(layer "In6.Cu")
		(net "M_K_CPU0_SA_DQS_DP<7>")
	)
	(segment
		(start 391.863072 -237.678976)
		(end 391.873486 -237.685072)
		(width 0.09525)
		(layer "In6.Cu")
		(net "M_K_CPU0_SA_DQS_DP<7>")
	)
	(segment
		(start 423.527474 -221.010226)
		(end 426.009308 -221.010226)
		(width 0.16002)
		(layer "In6.Cu")
		(net "M_K_CPU0_SA_DQS_DP<7>")
	)
	(segment
		(start 399.537174 -234.562396)
		(end 399.763234 -234.562396)
		(width 0.16002)
		(layer "In6.Cu")
		(net "M_K_CPU0_SA_DQS_DP<7>")
	)
	(segment
		(start 395.859254 -235.87456)
		(end 398.22501 -235.87456)
		(width 0.16002)
		(layer "In6.Cu")
		(net "M_K_CPU0_SA_DQS_DP<7>")
	)
	(segment
		(start 440.196732 -220.861128)
		(end 442.270388 -220.861128)
		(width 0.16002)
		(layer "In6.Cu")
		(net "M_K_CPU0_SA_DQS_DP<7>")
	)
	(segment
		(start 428.553626 -221.48038)
		(end 429.158146 -221.48038)
		(width 0.16002)
		(layer "In6.Cu")
		(net "M_K_CPU0_SA_DQS_DP<7>")
	)
	(segment
		(start 402.037804 -232.287826)
		(end 402.037804 -232.061766)
		(width 0.16002)
		(layer "In6.Cu")
		(net "M_K_CPU0_SA_DQS_DP<7>")
	)
	(segment
		(start 395.835632 -235.87456)
		(end 395.859254 -235.87456)
		(width 0.09525)
		(layer "In6.Cu")
		(net "M_K_CPU0_SA_DQS_DP<7>")
	)
	(segment
		(start 423.210228 -220.69298)
		(end 423.527474 -221.010226)
		(width 0.16002)
		(layer "In6.Cu")
		(net "M_K_CPU0_SA_DQS_DP<7>")
	)
	(segment
		(start 395.087602 -236.261656)
		(end 395.533626 -235.815632)
		(width 0.09525)
		(layer "In6.Cu")
		(net "M_K_CPU0_SA_DQS_DP<7>")
	)
	(segment
		(start 418.465254 -221.010226)
		(end 419.315138 -221.86011)
		(width 0.16002)
		(layer "In6.Cu")
		(net "M_K_CPU0_SA_DQS_DP<7>")
	)
	(segment
		(start 400.664172 -233.435398)
		(end 400.910806 -233.188764)
		(width 0.16002)
		(layer "In6.Cu")
		(net "M_K_CPU0_SA_DQS_DP<7>")
	)
	(segment
		(start 400.168872 -234.968034)
		(end 400.645376 -234.968034)
		(width 0.16002)
		(layer "In6.Cu")
		(net "M_K_CPU0_SA_DQS_DP<7>")
	)
	(segment
		(start 426.859192 -221.86011)
		(end 428.173896 -221.86011)
		(width 0.16002)
		(layer "In6.Cu")
		(net "M_K_CPU0_SA_DQS_DP<7>")
	)
	(segment
		(start 402.443442 -233.169968)
		(end 402.443442 -232.693464)
		(width 0.16002)
		(layer "In6.Cu")
		(net "M_K_CPU0_SA_DQS_DP<7>")
	)
	(segment
		(start 393.493752 -237.58906)
		(end 394.290296 -236.792516)
		(width 0.09525)
		(layer "In6.Cu")
		(net "M_K_CPU0_SA_DQS_DP<7>")
	)
	(segment
		(start 394.54328 -236.261656)
		(end 395.087602 -236.261656)
		(width 0.09525)
		(layer "In6.Cu")
		(net "M_K_CPU0_SA_DQS_DP<7>")
	)
	(segment
		(start 414.857438 -220.69298)
		(end 415.666174 -220.69298)
		(width 0.16002)
		(layer "In6.Cu")
		(net "M_K_CPU0_SA_DQS_DP<7>")
	)
	(segment
		(start 440.047634 -221.010226)
		(end 440.196732 -220.861128)
		(width 0.16002)
		(layer "In6.Cu")
		(net "M_K_CPU0_SA_DQS_DP<7>")
	)
	(segment
		(start 401.06981 -234.5436)
		(end 401.06981 -234.067096)
		(width 0.16002)
		(layer "In6.Cu")
		(net "M_K_CPU0_SA_DQS_DP<7>")
	)
	(segment
		(start 402.019008 -233.594402)
		(end 402.443442 -233.169968)
		(width 0.16002)
		(layer "In6.Cu")
		(net "M_K_CPU0_SA_DQS_DP<7>")
	)
	(segment
		(start 400.664172 -233.661458)
		(end 400.664172 -233.435398)
		(width 0.16002)
		(layer "In6.Cu")
		(net "M_K_CPU0_SA_DQS_DP<7>")
	)
	(segment
		(start 389.606282 -237.678976)
		(end 389.614664 -237.67415)
		(width 0.09525)
		(layer "In6.Cu")
		(net "M_K_CPU0_SA_DQS_DP<7>")
	)
	(segment
		(start 438.615582 -221.010226)
		(end 440.047634 -221.010226)
		(width 0.16002)
		(layer "In6.Cu")
		(net "M_K_CPU0_SA_DQS_DP<7>")
	)
	(segment
		(start 401.06981 -234.067096)
		(end 400.664172 -233.661458)
		(width 0.16002)
		(layer "In6.Cu")
		(net "M_K_CPU0_SA_DQS_DP<7>")
	)
	(segment
		(start 442.270388 -220.861128)
		(end 442.5442 -221.13494)
		(width 0.16002)
		(layer "In6.Cu")
		(net "M_K_CPU0_SA_DQS_DP<7>")
	)
	(arc
		(start 392.803126 -237.678976)
		(mid 393.1637 -237.751417)
		(end 393.493752 -237.58906)
		(width 0.09525)
		(layer "In6.Cu")
		(net "M_K_CPU0_SA_DQS_DP<7>")
	)
	(arc
		(start 389.614664 -237.67415)
		(mid 389.799696 -237.628236)
		(end 389.983472 -237.678976)
		(width 0.09525)
		(layer "In6.Cu")
		(net "M_K_CPU0_SA_DQS_DP<7>")
	)
	(arc
		(start 390.546336 -237.678976)
		(mid 390.734804 -237.628299)
		(end 390.923272 -237.678976)
		(width 0.09525)
		(layer "In6.Cu")
		(net "M_K_CPU0_SA_DQS_DP<7>")
	)
	(arc
		(start 391.873486 -237.685072)
		(mid 392.150394 -237.754749)
		(end 392.425682 -237.678976)
		(width 0.09525)
		(layer "In6.Cu")
		(net "M_K_CPU0_SA_DQS_DP<7>")
	)
	(arc
		(start 391.486136 -237.678976)
		(mid 391.667752 -237.628239)
		(end 391.851134 -237.672118)
		(width 0.09525)
		(layer "In6.Cu")
		(net "M_K_CPU0_SA_DQS_DP<7>")
	)
	(arc
		(start 392.43762 -237.672118)
		(mid 392.621255 -237.628168)
		(end 392.803126 -237.678976)
		(width 0.09525)
		(layer "In6.Cu")
		(net "M_K_CPU0_SA_DQS_DP<7>")
	)
	(arc
		(start 390.923272 -237.678976)
		(mid 391.204704 -237.754731)
		(end 391.486136 -237.678976)
		(width 0.09525)
		(layer "In6.Cu")
		(net "M_K_CPU0_SA_DQS_DP<7>")
	)
	(arc
		(start 389.983472 -237.678976)
		(mid 390.264904 -237.754731)
		(end 390.546336 -237.678976)
		(width 0.09525)
		(layer "In6.Cu")
		(net "M_K_CPU0_SA_DQS_DP<7>")
	)
	(arc
		(start 389.109712 -237.711996)
		(mid 389.361853 -237.753566)
		(end 389.606282 -237.678976)
		(width 0.09525)
		(layer "In6.Cu")
		(net "M_K_CPU0_SA_DQS_DP<7>")
	)
	(segment
		(start 388.387844 -233.409998)
		(end 388.85495 -233.14406)
		(width 0.12954)
		(layer "F.Cu")
		(net "M_K_CPU0_SA_DQS_DP<6>")
	)
	(segment
		(start 404.34514 -219.595192)
		(end 404.592536 -219.347796)
		(width 0.16002)
		(layer "In6.Cu")
		(net "M_K_CPU0_SA_DQS_DP<6>")
	)
	(segment
		(start 404.346918 -219.82303)
		(end 404.34514 -219.821252)
		(width 0.16002)
		(layer "In6.Cu")
		(net "M_K_CPU0_SA_DQS_DP<6>")
	)
	(segment
		(start 426.009308 -211.660232)
		(end 426.859192 -212.510116)
		(width 0.16002)
		(layer "In6.Cu")
		(net "M_K_CPU0_SA_DQS_DP<6>")
	)
	(segment
		(start 389.606282 -232.81894)
		(end 389.614664 -232.814114)
		(width 0.09525)
		(layer "In6.Cu")
		(net "M_K_CPU0_SA_DQS_DP<6>")
	)
	(segment
		(start 415.666174 -211.342986)
		(end 415.98342 -211.660232)
		(width 0.16002)
		(layer "In6.Cu")
		(net "M_K_CPU0_SA_DQS_DP<6>")
	)
	(segment
		(start 420.629842 -212.510116)
		(end 421.009572 -212.130386)
		(width 0.16002)
		(layer "In6.Cu")
		(net "M_K_CPU0_SA_DQS_DP<6>")
	)
	(segment
		(start 395.75867 -230.29164)
		(end 395.84249 -230.29164)
		(width 0.09525)
		(layer "In6.Cu")
		(net "M_K_CPU0_SA_DQS_DP<6>")
	)
	(segment
		(start 407.092404 -217.073988)
		(end 407.092404 -216.847928)
		(width 0.16002)
		(layer "In6.Cu")
		(net "M_K_CPU0_SA_DQS_DP<6>")
	)
	(segment
		(start 407.3398 -216.600532)
		(end 407.56586 -216.600532)
		(width 0.16002)
		(layer "In6.Cu")
		(net "M_K_CPU0_SA_DQS_DP<6>")
	)
	(segment
		(start 421.009572 -212.130386)
		(end 421.614092 -212.130386)
		(width 0.16002)
		(layer "In6.Cu")
		(net "M_K_CPU0_SA_DQS_DP<6>")
	)
	(segment
		(start 395.84249 -230.29164)
		(end 395.859254 -230.274876)
		(width 0.09525)
		(layer "In6.Cu")
		(net "M_K_CPU0_SA_DQS_DP<6>")
	)
	(segment
		(start 395.00429 -230.643938)
		(end 395.406372 -230.643938)
		(width 0.09525)
		(layer "In6.Cu")
		(net "M_K_CPU0_SA_DQS_DP<6>")
	)
	(segment
		(start 397.874998 -228.259132)
		(end 397.874998 -228.258878)
		(width 0.16002)
		(layer "In6.Cu")
		(net "M_K_CPU0_SA_DQS_DP<6>")
	)
	(segment
		(start 395.406372 -230.643938)
		(end 395.75867 -230.29164)
		(width 0.09525)
		(layer "In6.Cu")
		(net "M_K_CPU0_SA_DQS_DP<6>")
	)
	(segment
		(start 405.296878 -219.349574)
		(end 405.72055 -218.925902)
		(width 0.16002)
		(layer "In6.Cu")
		(net "M_K_CPU0_SA_DQS_DP<6>")
	)
	(segment
		(start 408.94127 -215.228678)
		(end 409.417774 -215.228678)
		(width 0.16002)
		(layer "In6.Cu")
		(net "M_K_CPU0_SA_DQS_DP<6>")
	)
	(segment
		(start 410.314902 -213.855046)
		(end 410.791406 -213.855046)
		(width 0.16002)
		(layer "In6.Cu")
		(net "M_K_CPU0_SA_DQS_DP<6>")
	)
	(segment
		(start 428.553626 -212.130386)
		(end 429.158146 -212.130386)
		(width 0.16002)
		(layer "In6.Cu")
		(net "M_K_CPU0_SA_DQS_DP<6>")
	)
	(segment
		(start 431.071528 -211.660232)
		(end 433.553362 -211.660232)
		(width 0.16002)
		(layer "In6.Cu")
		(net "M_K_CPU0_SA_DQS_DP<6>")
	)
	(segment
		(start 406.67051 -217.975942)
		(end 407.094182 -217.55227)
		(width 0.16002)
		(layer "In6.Cu")
		(net "M_K_CPU0_SA_DQS_DP<6>")
	)
	(segment
		(start 415.98342 -211.660232)
		(end 418.465254 -211.660232)
		(width 0.16002)
		(layer "In6.Cu")
		(net "M_K_CPU0_SA_DQS_DP<6>")
	)
	(segment
		(start 407.56586 -216.600532)
		(end 407.567638 -216.60231)
		(width 0.16002)
		(layer "In6.Cu")
		(net "M_K_CPU0_SA_DQS_DP<6>")
	)
	(segment
		(start 422.401492 -211.342986)
		(end 423.210228 -211.342986)
		(width 0.16002)
		(layer "In6.Cu")
		(net "M_K_CPU0_SA_DQS_DP<6>")
	)
	(segment
		(start 407.094182 -217.55227)
		(end 407.094182 -217.075766)
		(width 0.16002)
		(layer "In6.Cu")
		(net "M_K_CPU0_SA_DQS_DP<6>")
	)
	(segment
		(start 404.34514 -219.821252)
		(end 404.34514 -219.595192)
		(width 0.16002)
		(layer "In6.Cu")
		(net "M_K_CPU0_SA_DQS_DP<6>")
	)
	(segment
		(start 408.713432 -215.2269)
		(end 408.939492 -215.2269)
		(width 0.16002)
		(layer "In6.Cu")
		(net "M_K_CPU0_SA_DQS_DP<6>")
	)
	(segment
		(start 409.841446 -214.805006)
		(end 409.841446 -214.328502)
		(width 0.16002)
		(layer "In6.Cu")
		(net "M_K_CPU0_SA_DQS_DP<6>")
	)
	(segment
		(start 391.863326 -232.81894)
		(end 391.87374 -232.825036)
		(width 0.09525)
		(layer "In6.Cu")
		(net "M_K_CPU0_SA_DQS_DP<6>")
	)
	(segment
		(start 430.662588 -211.251292)
		(end 431.071528 -211.660232)
		(width 0.16002)
		(layer "In6.Cu")
		(net "M_K_CPU0_SA_DQS_DP<6>")
	)
	(segment
		(start 411.2133 -212.953092)
		(end 411.2133 -212.727032)
		(width 0.16002)
		(layer "In6.Cu")
		(net "M_K_CPU0_SA_DQS_DP<6>")
	)
	(segment
		(start 428.173896 -212.510116)
		(end 428.553626 -212.130386)
		(width 0.16002)
		(layer "In6.Cu")
		(net "M_K_CPU0_SA_DQS_DP<6>")
	)
	(segment
		(start 408.466036 -215.700356)
		(end 408.466036 -215.474296)
		(width 0.16002)
		(layer "In6.Cu")
		(net "M_K_CPU0_SA_DQS_DP<6>")
	)
	(segment
		(start 407.567638 -216.60231)
		(end 408.044142 -216.60231)
		(width 0.16002)
		(layer "In6.Cu")
		(net "M_K_CPU0_SA_DQS_DP<6>")
	)
	(segment
		(start 408.466036 -215.474296)
		(end 408.713432 -215.2269)
		(width 0.16002)
		(layer "In6.Cu")
		(net "M_K_CPU0_SA_DQS_DP<6>")
	)
	(segment
		(start 407.094182 -217.075766)
		(end 407.092404 -217.073988)
		(width 0.16002)
		(layer "In6.Cu")
		(net "M_K_CPU0_SA_DQS_DP<6>")
	)
	(segment
		(start 438.615582 -211.660232)
		(end 440.047634 -211.660232)
		(width 0.16002)
		(layer "In6.Cu")
		(net "M_K_CPU0_SA_DQS_DP<6>")
	)
	(segment
		(start 410.313124 -213.853268)
		(end 410.314902 -213.855046)
		(width 0.16002)
		(layer "In6.Cu")
		(net "M_K_CPU0_SA_DQS_DP<6>")
	)
	(segment
		(start 405.72055 -218.925902)
		(end 405.72055 -218.449398)
		(width 0.16002)
		(layer "In6.Cu")
		(net "M_K_CPU0_SA_DQS_DP<6>")
	)
	(segment
		(start 418.465254 -211.660232)
		(end 419.315138 -212.510116)
		(width 0.16002)
		(layer "In6.Cu")
		(net "M_K_CPU0_SA_DQS_DP<6>")
	)
	(segment
		(start 404.045674 -220.600778)
		(end 404.346918 -220.299534)
		(width 0.16002)
		(layer "In6.Cu")
		(net "M_K_CPU0_SA_DQS_DP<6>")
	)
	(segment
		(start 421.614092 -212.130386)
		(end 422.401492 -211.342986)
		(width 0.16002)
		(layer "In6.Cu")
		(net "M_K_CPU0_SA_DQS_DP<6>")
	)
	(segment
		(start 409.417774 -215.228678)
		(end 409.841446 -214.805006)
		(width 0.16002)
		(layer "In6.Cu")
		(net "M_K_CPU0_SA_DQS_DP<6>")
	)
	(segment
		(start 404.592536 -219.347796)
		(end 404.818596 -219.347796)
		(width 0.16002)
		(layer "In6.Cu")
		(net "M_K_CPU0_SA_DQS_DP<6>")
	)
	(segment
		(start 408.467814 -215.702134)
		(end 408.466036 -215.700356)
		(width 0.16002)
		(layer "In6.Cu")
		(net "M_K_CPU0_SA_DQS_DP<6>")
	)
	(segment
		(start 391.854944 -232.814114)
		(end 391.863326 -232.81894)
		(width 0.09525)
		(layer "In6.Cu")
		(net "M_K_CPU0_SA_DQS_DP<6>")
	)
	(segment
		(start 393.481052 -232.730294)
		(end 394.122656 -232.08869)
		(width 0.09525)
		(layer "In6.Cu")
		(net "M_K_CPU0_SA_DQS_DP<6>")
	)
	(segment
		(start 389.008874 -232.87863)
		(end 389.109712 -232.85196)
		(width 0.09525)
		(layer "In6.Cu")
		(net "M_K_CPU0_SA_DQS_DP<6>")
	)
	(segment
		(start 407.092404 -216.847928)
		(end 407.3398 -216.600532)
		(width 0.16002)
		(layer "In6.Cu")
		(net "M_K_CPU0_SA_DQS_DP<6>")
	)
	(segment
		(start 426.859192 -212.510116)
		(end 428.173896 -212.510116)
		(width 0.16002)
		(layer "In6.Cu")
		(net "M_K_CPU0_SA_DQS_DP<6>")
	)
	(segment
		(start 434.403246 -212.510116)
		(end 435.71795 -212.510116)
		(width 0.16002)
		(layer "In6.Cu")
		(net "M_K_CPU0_SA_DQS_DP<6>")
	)
	(segment
		(start 411.688534 -212.481414)
		(end 412.165038 -212.481414)
		(width 0.16002)
		(layer "In6.Cu")
		(net "M_K_CPU0_SA_DQS_DP<6>")
	)
	(segment
		(start 437.4896 -211.342986)
		(end 438.298336 -211.342986)
		(width 0.16002)
		(layer "In6.Cu")
		(net "M_K_CPU0_SA_DQS_DP<6>")
	)
	(segment
		(start 409.839668 -214.326724)
		(end 409.839668 -214.100664)
		(width 0.16002)
		(layer "In6.Cu")
		(net "M_K_CPU0_SA_DQS_DP<6>")
	)
	(segment
		(start 409.839668 -214.100664)
		(end 410.087064 -213.853268)
		(width 0.16002)
		(layer "In6.Cu")
		(net "M_K_CPU0_SA_DQS_DP<6>")
	)
	(segment
		(start 411.686756 -212.479636)
		(end 411.688534 -212.481414)
		(width 0.16002)
		(layer "In6.Cu")
		(net "M_K_CPU0_SA_DQS_DP<6>")
	)
	(segment
		(start 409.841446 -214.328502)
		(end 409.839668 -214.326724)
		(width 0.16002)
		(layer "In6.Cu")
		(net "M_K_CPU0_SA_DQS_DP<6>")
	)
	(segment
		(start 430.03724 -211.251292)
		(end 430.662588 -211.251292)
		(width 0.16002)
		(layer "In6.Cu")
		(net "M_K_CPU0_SA_DQS_DP<6>")
	)
	(segment
		(start 394.122656 -232.08869)
		(end 394.122656 -231.525572)
		(width 0.09525)
		(layer "In6.Cu")
		(net "M_K_CPU0_SA_DQS_DP<6>")
	)
	(segment
		(start 412.165038 -212.481414)
		(end 412.516066 -212.130386)
		(width 0.16002)
		(layer "In6.Cu")
		(net "M_K_CPU0_SA_DQS_DP<6>")
	)
	(segment
		(start 408.044142 -216.60231)
		(end 408.467814 -216.178638)
		(width 0.16002)
		(layer "In6.Cu")
		(net "M_K_CPU0_SA_DQS_DP<6>")
	)
	(segment
		(start 406.192228 -217.974164)
		(end 406.194006 -217.975942)
		(width 0.16002)
		(layer "In6.Cu")
		(net "M_K_CPU0_SA_DQS_DP<6>")
	)
	(segment
		(start 436.7022 -212.130386)
		(end 437.4896 -211.342986)
		(width 0.16002)
		(layer "In6.Cu")
		(net "M_K_CPU0_SA_DQS_DP<6>")
	)
	(segment
		(start 405.966168 -217.974164)
		(end 406.192228 -217.974164)
		(width 0.16002)
		(layer "In6.Cu")
		(net "M_K_CPU0_SA_DQS_DP<6>")
	)
	(segment
		(start 397.874998 -228.258878)
		(end 404.045674 -222.088202)
		(width 0.16002)
		(layer "In6.Cu")
		(net "M_K_CPU0_SA_DQS_DP<6>")
	)
	(segment
		(start 411.2133 -212.727032)
		(end 411.460696 -212.479636)
		(width 0.16002)
		(layer "In6.Cu")
		(net "M_K_CPU0_SA_DQS_DP<6>")
	)
	(segment
		(start 435.71795 -212.510116)
		(end 436.09768 -212.130386)
		(width 0.16002)
		(layer "In6.Cu")
		(net "M_K_CPU0_SA_DQS_DP<6>")
	)
	(segment
		(start 408.467814 -216.178638)
		(end 408.467814 -215.702134)
		(width 0.16002)
		(layer "In6.Cu")
		(net "M_K_CPU0_SA_DQS_DP<6>")
	)
	(segment
		(start 410.791406 -213.855046)
		(end 411.215078 -213.431374)
		(width 0.16002)
		(layer "In6.Cu")
		(net "M_K_CPU0_SA_DQS_DP<6>")
	)
	(segment
		(start 405.718772 -218.22156)
		(end 405.966168 -217.974164)
		(width 0.16002)
		(layer "In6.Cu")
		(net "M_K_CPU0_SA_DQS_DP<6>")
	)
	(segment
		(start 411.460696 -212.479636)
		(end 411.686756 -212.479636)
		(width 0.16002)
		(layer "In6.Cu")
		(net "M_K_CPU0_SA_DQS_DP<6>")
	)
	(segment
		(start 423.527474 -211.660232)
		(end 426.009308 -211.660232)
		(width 0.16002)
		(layer "In6.Cu")
		(net "M_K_CPU0_SA_DQS_DP<6>")
	)
	(segment
		(start 410.087064 -213.853268)
		(end 410.313124 -213.853268)
		(width 0.16002)
		(layer "In6.Cu")
		(net "M_K_CPU0_SA_DQS_DP<6>")
	)
	(segment
		(start 423.210228 -211.342986)
		(end 423.527474 -211.660232)
		(width 0.16002)
		(layer "In6.Cu")
		(net "M_K_CPU0_SA_DQS_DP<6>")
	)
	(segment
		(start 436.09768 -212.130386)
		(end 436.7022 -212.130386)
		(width 0.16002)
		(layer "In6.Cu")
		(net "M_K_CPU0_SA_DQS_DP<6>")
	)
	(segment
		(start 404.820374 -219.349574)
		(end 405.296878 -219.349574)
		(width 0.16002)
		(layer "In6.Cu")
		(net "M_K_CPU0_SA_DQS_DP<6>")
	)
	(segment
		(start 419.315138 -212.510116)
		(end 420.629842 -212.510116)
		(width 0.16002)
		(layer "In6.Cu")
		(net "M_K_CPU0_SA_DQS_DP<6>")
	)
	(segment
		(start 411.215078 -212.95487)
		(end 411.2133 -212.953092)
		(width 0.16002)
		(layer "In6.Cu")
		(net "M_K_CPU0_SA_DQS_DP<6>")
	)
	(segment
		(start 388.85495 -233.14406)
		(end 389.008874 -232.87863)
		(width 0.09525)
		(layer "In6.Cu")
		(net "M_K_CPU0_SA_DQS_DP<6>")
	)
	(segment
		(start 411.215078 -213.431374)
		(end 411.215078 -212.95487)
		(width 0.16002)
		(layer "In6.Cu")
		(net "M_K_CPU0_SA_DQS_DP<6>")
	)
	(segment
		(start 429.158146 -212.130386)
		(end 430.03724 -211.251292)
		(width 0.16002)
		(layer "In6.Cu")
		(net "M_K_CPU0_SA_DQS_DP<6>")
	)
	(segment
		(start 393.351258 -232.827576)
		(end 393.36599 -232.81894)
		(width 0.09525)
		(layer "In6.Cu")
		(net "M_K_CPU0_SA_DQS_DP<6>")
	)
	(segment
		(start 440.196732 -211.511134)
		(end 442.270388 -211.511134)
		(width 0.16002)
		(layer "In6.Cu")
		(net "M_K_CPU0_SA_DQS_DP<6>")
	)
	(segment
		(start 404.818596 -219.347796)
		(end 404.820374 -219.349574)
		(width 0.16002)
		(layer "In6.Cu")
		(net "M_K_CPU0_SA_DQS_DP<6>")
	)
	(segment
		(start 442.270388 -211.511134)
		(end 442.5442 -211.784946)
		(width 0.16002)
		(layer "In6.Cu")
		(net "M_K_CPU0_SA_DQS_DP<6>")
	)
	(segment
		(start 404.346918 -220.299534)
		(end 404.346918 -219.82303)
		(width 0.16002)
		(layer "In6.Cu")
		(net "M_K_CPU0_SA_DQS_DP<6>")
	)
	(segment
		(start 440.047634 -211.660232)
		(end 440.196732 -211.511134)
		(width 0.16002)
		(layer "In6.Cu")
		(net "M_K_CPU0_SA_DQS_DP<6>")
	)
	(segment
		(start 392.425936 -232.81894)
		(end 392.434318 -232.814114)
		(width 0.09525)
		(layer "In6.Cu")
		(net "M_K_CPU0_SA_DQS_DP<6>")
	)
	(segment
		(start 412.516066 -212.130386)
		(end 414.070038 -212.130386)
		(width 0.16002)
		(layer "In6.Cu")
		(net "M_K_CPU0_SA_DQS_DP<6>")
	)
	(segment
		(start 406.194006 -217.975942)
		(end 406.67051 -217.975942)
		(width 0.16002)
		(layer "In6.Cu")
		(net "M_K_CPU0_SA_DQS_DP<6>")
	)
	(segment
		(start 405.718772 -218.44762)
		(end 405.718772 -218.22156)
		(width 0.16002)
		(layer "In6.Cu")
		(net "M_K_CPU0_SA_DQS_DP<6>")
	)
	(segment
		(start 408.939492 -215.2269)
		(end 408.94127 -215.228678)
		(width 0.16002)
		(layer "In6.Cu")
		(net "M_K_CPU0_SA_DQS_DP<6>")
	)
	(segment
		(start 394.122656 -231.525572)
		(end 395.00429 -230.643938)
		(width 0.09525)
		(layer "In6.Cu")
		(net "M_K_CPU0_SA_DQS_DP<6>")
	)
	(segment
		(start 433.553362 -211.660232)
		(end 434.403246 -212.510116)
		(width 0.16002)
		(layer "In6.Cu")
		(net "M_K_CPU0_SA_DQS_DP<6>")
	)
	(segment
		(start 438.298336 -211.342986)
		(end 438.615582 -211.660232)
		(width 0.16002)
		(layer "In6.Cu")
		(net "M_K_CPU0_SA_DQS_DP<6>")
	)
	(segment
		(start 404.045674 -222.088202)
		(end 404.045674 -220.600778)
		(width 0.16002)
		(layer "In6.Cu")
		(net "M_K_CPU0_SA_DQS_DP<6>")
	)
	(segment
		(start 405.72055 -218.449398)
		(end 405.718772 -218.44762)
		(width 0.16002)
		(layer "In6.Cu")
		(net "M_K_CPU0_SA_DQS_DP<6>")
	)
	(segment
		(start 395.859254 -230.274876)
		(end 397.874998 -228.259132)
		(width 0.16002)
		(layer "In6.Cu")
		(net "M_K_CPU0_SA_DQS_DP<6>")
	)
	(segment
		(start 414.070038 -212.130386)
		(end 414.857438 -211.342986)
		(width 0.16002)
		(layer "In6.Cu")
		(net "M_K_CPU0_SA_DQS_DP<6>")
	)
	(segment
		(start 414.857438 -211.342986)
		(end 415.666174 -211.342986)
		(width 0.16002)
		(layer "In6.Cu")
		(net "M_K_CPU0_SA_DQS_DP<6>")
	)
	(arc
		(start 390.546336 -232.81894)
		(mid 390.734804 -232.768263)
		(end 390.923272 -232.81894)
		(width 0.09525)
		(layer "In6.Cu")
		(net "M_K_CPU0_SA_DQS_DP<6>")
	)
	(arc
		(start 393.36599 -232.81894)
		(mid 393.426405 -232.77836)
		(end 393.481052 -232.730294)
		(width 0.09525)
		(layer "In6.Cu")
		(net "M_K_CPU0_SA_DQS_DP<6>")
	)
	(arc
		(start 392.434318 -232.814114)
		(mid 392.61935 -232.7682)
		(end 392.803126 -232.81894)
		(width 0.09525)
		(layer "In6.Cu")
		(net "M_K_CPU0_SA_DQS_DP<6>")
	)
	(arc
		(start 389.614664 -232.814114)
		(mid 389.799696 -232.7682)
		(end 389.983472 -232.81894)
		(width 0.09525)
		(layer "In6.Cu")
		(net "M_K_CPU0_SA_DQS_DP<6>")
	)
	(arc
		(start 391.87374 -232.825036)
		(mid 392.150648 -232.894713)
		(end 392.425936 -232.81894)
		(width 0.09525)
		(layer "In6.Cu")
		(net "M_K_CPU0_SA_DQS_DP<6>")
	)
	(arc
		(start 389.109712 -232.85196)
		(mid 389.361853 -232.89353)
		(end 389.606282 -232.81894)
		(width 0.09525)
		(layer "In6.Cu")
		(net "M_K_CPU0_SA_DQS_DP<6>")
	)
	(arc
		(start 392.803126 -232.81894)
		(mid 393.076054 -232.894754)
		(end 393.351258 -232.827576)
		(width 0.09525)
		(layer "In6.Cu")
		(net "M_K_CPU0_SA_DQS_DP<6>")
	)
	(arc
		(start 391.486136 -232.81894)
		(mid 391.669911 -232.768168)
		(end 391.854944 -232.814114)
		(width 0.09525)
		(layer "In6.Cu")
		(net "M_K_CPU0_SA_DQS_DP<6>")
	)
	(arc
		(start 390.923272 -232.81894)
		(mid 391.204704 -232.894695)
		(end 391.486136 -232.81894)
		(width 0.09525)
		(layer "In6.Cu")
		(net "M_K_CPU0_SA_DQS_DP<6>")
	)
	(arc
		(start 389.983472 -232.81894)
		(mid 390.264904 -232.894695)
		(end 390.546336 -232.81894)
		(width 0.09525)
		(layer "In6.Cu")
		(net "M_K_CPU0_SA_DQS_DP<6>")
	)
	(segment
		(start 388.387844 -228.550216)
		(end 388.85495 -228.284278)
		(width 0.12954)
		(layer "F.Cu")
		(net "M_K_CPU0_SA_DQS_DP<5>")
	)
	(segment
		(start 399.348198 -216.171272)
		(end 399.772632 -215.746838)
		(width 0.16002)
		(layer "In6.Cu")
		(net "M_K_CPU0_SA_DQS_DP<5>")
	)
	(segment
		(start 399.671794 -215.169496)
		(end 399.671794 -214.943436)
		(width 0.16002)
		(layer "In6.Cu")
		(net "M_K_CPU0_SA_DQS_DP<5>")
	)
	(segment
		(start 430.754282 -201.992992)
		(end 431.071528 -202.310238)
		(width 0.16002)
		(layer "In6.Cu")
		(net "M_K_CPU0_SA_DQS_DP<5>")
	)
	(segment
		(start 399.772632 -215.746838)
		(end 399.772632 -215.270334)
		(width 0.16002)
		(layer "In6.Cu")
		(net "M_K_CPU0_SA_DQS_DP<5>")
	)
	(segment
		(start 394.585698 -222.788988)
		(end 394.62964 -222.788988)
		(width 0.09525)
		(layer "In6.Cu")
		(net "M_K_CPU0_SA_DQS_DP<5>")
	)
	(segment
		(start 403.893528 -211.625942)
		(end 403.893528 -211.149438)
		(width 0.16002)
		(layer "In6.Cu")
		(net "M_K_CPU0_SA_DQS_DP<5>")
	)
	(segment
		(start 393.836144 -223.909128)
		(end 393.874244 -223.88703)
		(width 0.09525)
		(layer "In6.Cu")
		(net "M_K_CPU0_SA_DQS_DP<5>")
	)
	(segment
		(start 400.144488 -214.696802)
		(end 400.245326 -214.79764)
		(width 0.16002)
		(layer "In6.Cu")
		(net "M_K_CPU0_SA_DQS_DP<5>")
	)
	(segment
		(start 421.009572 -202.780392)
		(end 421.614092 -202.780392)
		(width 0.16002)
		(layer "In6.Cu")
		(net "M_K_CPU0_SA_DQS_DP<5>")
	)
	(segment
		(start 405.166322 -209.448908)
		(end 411.834838 -202.780392)
		(width 0.16002)
		(layer "In6.Cu")
		(net "M_K_CPU0_SA_DQS_DP<5>")
	)
	(segment
		(start 414.857438 -201.992992)
		(end 415.666174 -201.992992)
		(width 0.16002)
		(layer "In6.Cu")
		(net "M_K_CPU0_SA_DQS_DP<5>")
	)
	(segment
		(start 415.98342 -202.310238)
		(end 418.465254 -202.310238)
		(width 0.16002)
		(layer "In6.Cu")
		(net "M_K_CPU0_SA_DQS_DP<5>")
	)
	(segment
		(start 418.465254 -202.310238)
		(end 419.315138 -203.160122)
		(width 0.16002)
		(layer "In6.Cu")
		(net "M_K_CPU0_SA_DQS_DP<5>")
	)
	(segment
		(start 435.71795 -203.160122)
		(end 436.09768 -202.780392)
		(width 0.16002)
		(layer "In6.Cu")
		(net "M_K_CPU0_SA_DQS_DP<5>")
	)
	(segment
		(start 400.245326 -214.79764)
		(end 400.72183 -214.79764)
		(width 0.16002)
		(layer "In6.Cu")
		(net "M_K_CPU0_SA_DQS_DP<5>")
	)
	(segment
		(start 399.671794 -214.943436)
		(end 399.918428 -214.696802)
		(width 0.16002)
		(layer "In6.Cu")
		(net "M_K_CPU0_SA_DQS_DP<5>")
	)
	(segment
		(start 404.366222 -210.676744)
		(end 404.842726 -210.676744)
		(width 0.16002)
		(layer "In6.Cu")
		(net "M_K_CPU0_SA_DQS_DP<5>")
	)
	(segment
		(start 402.99259 -212.050376)
		(end 403.469094 -212.050376)
		(width 0.16002)
		(layer "In6.Cu")
		(net "M_K_CPU0_SA_DQS_DP<5>")
	)
	(segment
		(start 402.519896 -212.52307)
		(end 402.419058 -212.422232)
		(width 0.16002)
		(layer "In6.Cu")
		(net "M_K_CPU0_SA_DQS_DP<5>")
	)
	(segment
		(start 405.166322 -209.674968)
		(end 405.166322 -209.448908)
		(width 0.16002)
		(layer "In6.Cu")
		(net "M_K_CPU0_SA_DQS_DP<5>")
	)
	(segment
		(start 401.045426 -213.569804)
		(end 401.29206 -213.32317)
		(width 0.16002)
		(layer "In6.Cu")
		(net "M_K_CPU0_SA_DQS_DP<5>")
	)
	(segment
		(start 396.494508 -220.924374)
		(end 396.494762 -220.924374)
		(width 0.16002)
		(layer "In6.Cu")
		(net "M_K_CPU0_SA_DQS_DP<5>")
	)
	(segment
		(start 426.009308 -202.310238)
		(end 426.859192 -203.160122)
		(width 0.16002)
		(layer "In6.Cu")
		(net "M_K_CPU0_SA_DQS_DP<5>")
	)
	(segment
		(start 404.265384 -210.575906)
		(end 404.366222 -210.676744)
		(width 0.16002)
		(layer "In6.Cu")
		(net "M_K_CPU0_SA_DQS_DP<5>")
	)
	(segment
		(start 399.918428 -214.696802)
		(end 400.144488 -214.696802)
		(width 0.16002)
		(layer "In6.Cu")
		(net "M_K_CPU0_SA_DQS_DP<5>")
	)
	(segment
		(start 398.068038 -216.547192)
		(end 398.544796 -216.070434)
		(width 0.16002)
		(layer "In6.Cu")
		(net "M_K_CPU0_SA_DQS_DP<5>")
	)
	(segment
		(start 403.469094 -212.050376)
		(end 403.893528 -211.625942)
		(width 0.16002)
		(layer "In6.Cu")
		(net "M_K_CPU0_SA_DQS_DP<5>")
	)
	(segment
		(start 402.095462 -213.424008)
		(end 402.519896 -212.999574)
		(width 0.16002)
		(layer "In6.Cu")
		(net "M_K_CPU0_SA_DQS_DP<5>")
	)
	(segment
		(start 437.4896 -201.992992)
		(end 438.298336 -201.992992)
		(width 0.16002)
		(layer "In6.Cu")
		(net "M_K_CPU0_SA_DQS_DP<5>")
	)
	(segment
		(start 436.09768 -202.780392)
		(end 436.7022 -202.780392)
		(width 0.16002)
		(layer "In6.Cu")
		(net "M_K_CPU0_SA_DQS_DP<5>")
	)
	(segment
		(start 402.419058 -212.422232)
		(end 402.419058 -212.196172)
		(width 0.16002)
		(layer "In6.Cu")
		(net "M_K_CPU0_SA_DQS_DP<5>")
	)
	(segment
		(start 436.7022 -202.780392)
		(end 437.4896 -201.992992)
		(width 0.16002)
		(layer "In6.Cu")
		(net "M_K_CPU0_SA_DQS_DP<5>")
	)
	(segment
		(start 394.646404 -222.772224)
		(end 396.494508 -220.924374)
		(width 0.16002)
		(layer "In6.Cu")
		(net "M_K_CPU0_SA_DQS_DP<5>")
	)
	(segment
		(start 394.117068 -223.424242)
		(end 394.11656 -223.423734)
		(width 0.09525)
		(layer "In6.Cu")
		(net "M_K_CPU0_SA_DQS_DP<5>")
	)
	(segment
		(start 421.614092 -202.780392)
		(end 422.401492 -201.992992)
		(width 0.16002)
		(layer "In6.Cu")
		(net "M_K_CPU0_SA_DQS_DP<5>")
	)
	(segment
		(start 394.11656 -223.218756)
		(end 394.518388 -222.816928)
		(width 0.09525)
		(layer "In6.Cu")
		(net "M_K_CPU0_SA_DQS_DP<5>")
	)
	(segment
		(start 419.315138 -203.160122)
		(end 420.629842 -203.160122)
		(width 0.16002)
		(layer "In6.Cu")
		(net "M_K_CPU0_SA_DQS_DP<5>")
	)
	(segment
		(start 438.298336 -201.992992)
		(end 438.615582 -202.310238)
		(width 0.16002)
		(layer "In6.Cu")
		(net "M_K_CPU0_SA_DQS_DP<5>")
	)
	(segment
		(start 400.72183 -214.79764)
		(end 401.146264 -214.373206)
		(width 0.16002)
		(layer "In6.Cu")
		(net "M_K_CPU0_SA_DQS_DP<5>")
	)
	(segment
		(start 394.11656 -223.423734)
		(end 394.11656 -223.218756)
		(width 0.09525)
		(layer "In6.Cu")
		(net "M_K_CPU0_SA_DQS_DP<5>")
	)
	(segment
		(start 402.419058 -212.196172)
		(end 402.665692 -211.949538)
		(width 0.16002)
		(layer "In6.Cu")
		(net "M_K_CPU0_SA_DQS_DP<5>")
	)
	(segment
		(start 398.068038 -219.351098)
		(end 398.068038 -216.547192)
		(width 0.16002)
		(layer "In6.Cu")
		(net "M_K_CPU0_SA_DQS_DP<5>")
	)
	(segment
		(start 402.519896 -212.999574)
		(end 402.519896 -212.52307)
		(width 0.16002)
		(layer "In6.Cu")
		(net "M_K_CPU0_SA_DQS_DP<5>")
	)
	(segment
		(start 438.615582 -202.310238)
		(end 440.047634 -202.310238)
		(width 0.16002)
		(layer "In6.Cu")
		(net "M_K_CPU0_SA_DQS_DP<5>")
	)
	(segment
		(start 393.804648 -223.927416)
		(end 393.836144 -223.909128)
		(width 0.09525)
		(layer "In6.Cu")
		(net "M_K_CPU0_SA_DQS_DP<5>")
	)
	(segment
		(start 402.891752 -211.949538)
		(end 402.99259 -212.050376)
		(width 0.16002)
		(layer "In6.Cu")
		(net "M_K_CPU0_SA_DQS_DP<5>")
	)
	(segment
		(start 402.665692 -211.949538)
		(end 402.891752 -211.949538)
		(width 0.16002)
		(layer "In6.Cu")
		(net "M_K_CPU0_SA_DQS_DP<5>")
	)
	(segment
		(start 401.51812 -213.32317)
		(end 401.618958 -213.424008)
		(width 0.16002)
		(layer "In6.Cu")
		(net "M_K_CPU0_SA_DQS_DP<5>")
	)
	(segment
		(start 428.553626 -202.780392)
		(end 429.158146 -202.780392)
		(width 0.16002)
		(layer "In6.Cu")
		(net "M_K_CPU0_SA_DQS_DP<5>")
	)
	(segment
		(start 431.071528 -202.310238)
		(end 433.553362 -202.310238)
		(width 0.16002)
		(layer "In6.Cu")
		(net "M_K_CPU0_SA_DQS_DP<5>")
	)
	(segment
		(start 388.85495 -228.284278)
		(end 389.008874 -228.018848)
		(width 0.09525)
		(layer "In6.Cu")
		(net "M_K_CPU0_SA_DQS_DP<5>")
	)
	(segment
		(start 401.146264 -214.373206)
		(end 401.146264 -213.896702)
		(width 0.16002)
		(layer "In6.Cu")
		(net "M_K_CPU0_SA_DQS_DP<5>")
	)
	(segment
		(start 428.173896 -203.160122)
		(end 428.553626 -202.780392)
		(width 0.16002)
		(layer "In6.Cu")
		(net "M_K_CPU0_SA_DQS_DP<5>")
	)
	(segment
		(start 405.26716 -210.25231)
		(end 405.26716 -209.775806)
		(width 0.16002)
		(layer "In6.Cu")
		(net "M_K_CPU0_SA_DQS_DP<5>")
	)
	(segment
		(start 420.629842 -203.160122)
		(end 421.009572 -202.780392)
		(width 0.16002)
		(layer "In6.Cu")
		(net "M_K_CPU0_SA_DQS_DP<5>")
	)
	(segment
		(start 389.606282 -227.959158)
		(end 389.614664 -227.954332)
		(width 0.09525)
		(layer "In6.Cu")
		(net "M_K_CPU0_SA_DQS_DP<5>")
	)
	(segment
		(start 398.544796 -216.070434)
		(end 398.770856 -216.070434)
		(width 0.16002)
		(layer "In6.Cu")
		(net "M_K_CPU0_SA_DQS_DP<5>")
	)
	(segment
		(start 401.29206 -213.32317)
		(end 401.51812 -213.32317)
		(width 0.16002)
		(layer "In6.Cu")
		(net "M_K_CPU0_SA_DQS_DP<5>")
	)
	(segment
		(start 442.270388 -202.16114)
		(end 442.5442 -202.434952)
		(width 0.16002)
		(layer "In6.Cu")
		(net "M_K_CPU0_SA_DQS_DP<5>")
	)
	(segment
		(start 393.647168 -225.916236)
		(end 393.647168 -224.234248)
		(width 0.09525)
		(layer "In6.Cu")
		(net "M_K_CPU0_SA_DQS_DP<5>")
	)
	(segment
		(start 391.674858 -227.90785)
		(end 391.900918 -227.90785)
		(width 0.09525)
		(layer "In6.Cu")
		(net "M_K_CPU0_SA_DQS_DP<5>")
	)
	(segment
		(start 401.045426 -213.795864)
		(end 401.045426 -213.569804)
		(width 0.16002)
		(layer "In6.Cu")
		(net "M_K_CPU0_SA_DQS_DP<5>")
	)
	(segment
		(start 405.26716 -209.775806)
		(end 405.166322 -209.674968)
		(width 0.16002)
		(layer "In6.Cu")
		(net "M_K_CPU0_SA_DQS_DP<5>")
	)
	(segment
		(start 404.039324 -210.575906)
		(end 404.265384 -210.575906)
		(width 0.16002)
		(layer "In6.Cu")
		(net "M_K_CPU0_SA_DQS_DP<5>")
	)
	(segment
		(start 399.772632 -215.270334)
		(end 399.671794 -215.169496)
		(width 0.16002)
		(layer "In6.Cu")
		(net "M_K_CPU0_SA_DQS_DP<5>")
	)
	(segment
		(start 423.210228 -201.992992)
		(end 423.527474 -202.310238)
		(width 0.16002)
		(layer "In6.Cu")
		(net "M_K_CPU0_SA_DQS_DP<5>")
	)
	(segment
		(start 403.79269 -210.82254)
		(end 404.039324 -210.575906)
		(width 0.16002)
		(layer "In6.Cu")
		(net "M_K_CPU0_SA_DQS_DP<5>")
	)
	(segment
		(start 426.859192 -203.160122)
		(end 428.173896 -203.160122)
		(width 0.16002)
		(layer "In6.Cu")
		(net "M_K_CPU0_SA_DQS_DP<5>")
	)
	(segment
		(start 396.494762 -220.924374)
		(end 398.068038 -219.351098)
		(width 0.16002)
		(layer "In6.Cu")
		(net "M_K_CPU0_SA_DQS_DP<5>")
	)
	(segment
		(start 392.693144 -227.234242)
		(end 392.848592 -227.166678)
		(width 0.09525)
		(layer "In6.Cu")
		(net "M_K_CPU0_SA_DQS_DP<5>")
	)
	(segment
		(start 403.893528 -211.149438)
		(end 403.79269 -211.0486)
		(width 0.16002)
		(layer "In6.Cu")
		(net "M_K_CPU0_SA_DQS_DP<5>")
	)
	(segment
		(start 404.842726 -210.676744)
		(end 405.26716 -210.25231)
		(width 0.16002)
		(layer "In6.Cu")
		(net "M_K_CPU0_SA_DQS_DP<5>")
	)
	(segment
		(start 440.047634 -202.310238)
		(end 440.196732 -202.16114)
		(width 0.16002)
		(layer "In6.Cu")
		(net "M_K_CPU0_SA_DQS_DP<5>")
	)
	(segment
		(start 394.62964 -222.788988)
		(end 394.646404 -222.772224)
		(width 0.09525)
		(layer "In6.Cu")
		(net "M_K_CPU0_SA_DQS_DP<5>")
	)
	(segment
		(start 401.146264 -213.896702)
		(end 401.045426 -213.795864)
		(width 0.16002)
		(layer "In6.Cu")
		(net "M_K_CPU0_SA_DQS_DP<5>")
	)
	(segment
		(start 415.666174 -201.992992)
		(end 415.98342 -202.310238)
		(width 0.16002)
		(layer "In6.Cu")
		(net "M_K_CPU0_SA_DQS_DP<5>")
	)
	(segment
		(start 389.008874 -228.018848)
		(end 389.109712 -227.992178)
		(width 0.09525)
		(layer "In6.Cu")
		(net "M_K_CPU0_SA_DQS_DP<5>")
	)
	(segment
		(start 433.553362 -202.310238)
		(end 434.403246 -203.160122)
		(width 0.16002)
		(layer "In6.Cu")
		(net "M_K_CPU0_SA_DQS_DP<5>")
	)
	(segment
		(start 429.945546 -201.992992)
		(end 430.754282 -201.992992)
		(width 0.16002)
		(layer "In6.Cu")
		(net "M_K_CPU0_SA_DQS_DP<5>")
	)
	(segment
		(start 422.401492 -201.992992)
		(end 423.210228 -201.992992)
		(width 0.16002)
		(layer "In6.Cu")
		(net "M_K_CPU0_SA_DQS_DP<5>")
	)
	(segment
		(start 401.618958 -213.424008)
		(end 402.095462 -213.424008)
		(width 0.16002)
		(layer "In6.Cu")
		(net "M_K_CPU0_SA_DQS_DP<5>")
	)
	(segment
		(start 403.79269 -211.0486)
		(end 403.79269 -210.82254)
		(width 0.16002)
		(layer "In6.Cu")
		(net "M_K_CPU0_SA_DQS_DP<5>")
	)
	(segment
		(start 398.770856 -216.070434)
		(end 398.871694 -216.171272)
		(width 0.16002)
		(layer "In6.Cu")
		(net "M_K_CPU0_SA_DQS_DP<5>")
	)
	(segment
		(start 440.196732 -202.16114)
		(end 442.270388 -202.16114)
		(width 0.16002)
		(layer "In6.Cu")
		(net "M_K_CPU0_SA_DQS_DP<5>")
	)
	(segment
		(start 398.871694 -216.171272)
		(end 399.348198 -216.171272)
		(width 0.16002)
		(layer "In6.Cu")
		(net "M_K_CPU0_SA_DQS_DP<5>")
	)
	(segment
		(start 414.070038 -202.780392)
		(end 414.857438 -201.992992)
		(width 0.16002)
		(layer "In6.Cu")
		(net "M_K_CPU0_SA_DQS_DP<5>")
	)
	(segment
		(start 411.834838 -202.780392)
		(end 414.070038 -202.780392)
		(width 0.16002)
		(layer "In6.Cu")
		(net "M_K_CPU0_SA_DQS_DP<5>")
	)
	(segment
		(start 423.527474 -202.310238)
		(end 426.009308 -202.310238)
		(width 0.16002)
		(layer "In6.Cu")
		(net "M_K_CPU0_SA_DQS_DP<5>")
	)
	(segment
		(start 429.158146 -202.780392)
		(end 429.945546 -201.992992)
		(width 0.16002)
		(layer "In6.Cu")
		(net "M_K_CPU0_SA_DQS_DP<5>")
	)
	(segment
		(start 434.403246 -203.160122)
		(end 435.71795 -203.160122)
		(width 0.16002)
		(layer "In6.Cu")
		(net "M_K_CPU0_SA_DQS_DP<5>")
	)
	(arc
		(start 392.28522 -227.7618)
		(mid 392.465191 -227.562582)
		(end 392.598402 -227.329492)
		(width 0.09525)
		(layer "In6.Cu")
		(net "M_K_CPU0_SA_DQS_DP<5>")
	)
	(arc
		(start 391.486136 -227.959158)
		(mid 391.577102 -227.921005)
		(end 391.674858 -227.90785)
		(width 0.09525)
		(layer "In6.Cu")
		(net "M_K_CPU0_SA_DQS_DP<5>")
	)
	(arc
		(start 389.109712 -227.992178)
		(mid 389.11958 -227.996209)
		(end 389.129524 -228.000052)
		(width 0.09525)
		(layer "In6.Cu")
		(net "M_K_CPU0_SA_DQS_DP<5>")
	)
	(arc
		(start 393.874244 -223.88703)
		(mid 394.052694 -223.68556)
		(end 394.117068 -223.424242)
		(width 0.09525)
		(layer "In6.Cu")
		(net "M_K_CPU0_SA_DQS_DP<5>")
	)
	(arc
		(start 391.900918 -227.90785)
		(mid 392.106489 -227.870144)
		(end 392.28522 -227.7618)
		(width 0.09525)
		(layer "In6.Cu")
		(net "M_K_CPU0_SA_DQS_DP<5>")
	)
	(arc
		(start 394.518388 -222.816928)
		(mid 394.549256 -222.796239)
		(end 394.585698 -222.788988)
		(width 0.09525)
		(layer "In6.Cu")
		(net "M_K_CPU0_SA_DQS_DP<5>")
	)
	(arc
		(start 389.983472 -227.959158)
		(mid 390.264904 -228.034913)
		(end 390.546336 -227.959158)
		(width 0.09525)
		(layer "In6.Cu")
		(net "M_K_CPU0_SA_DQS_DP<5>")
	)
	(arc
		(start 393.38504 -226.330256)
		(mid 393.563481 -226.153244)
		(end 393.647168 -225.916236)
		(width 0.09525)
		(layer "In6.Cu")
		(net "M_K_CPU0_SA_DQS_DP<5>")
	)
	(arc
		(start 393.647168 -224.234248)
		(mid 393.688833 -224.061801)
		(end 393.804648 -223.927416)
		(width 0.09525)
		(layer "In6.Cu")
		(net "M_K_CPU0_SA_DQS_DP<5>")
	)
	(arc
		(start 390.546336 -227.959158)
		(mid 390.734804 -227.908481)
		(end 390.923272 -227.959158)
		(width 0.09525)
		(layer "In6.Cu")
		(net "M_K_CPU0_SA_DQS_DP<5>")
	)
	(arc
		(start 392.598402 -227.329492)
		(mid 392.636701 -227.272835)
		(end 392.693144 -227.234242)
		(width 0.09525)
		(layer "In6.Cu")
		(net "M_K_CPU0_SA_DQS_DP<5>")
	)
	(arc
		(start 390.923272 -227.959158)
		(mid 391.204704 -228.034913)
		(end 391.486136 -227.959158)
		(width 0.09525)
		(layer "In6.Cu")
		(net "M_K_CPU0_SA_DQS_DP<5>")
	)
	(arc
		(start 389.614664 -227.954332)
		(mid 389.799696 -227.908418)
		(end 389.983472 -227.959158)
		(width 0.09525)
		(layer "In6.Cu")
		(net "M_K_CPU0_SA_DQS_DP<5>")
	)
	(arc
		(start 392.848592 -227.166678)
		(mid 393.08581 -226.970812)
		(end 393.182348 -226.678744)
		(width 0.09525)
		(layer "In6.Cu")
		(net "M_K_CPU0_SA_DQS_DP<5>")
	)
	(arc
		(start 389.129524 -228.000052)
		(mid 389.372488 -228.033039)
		(end 389.606282 -227.959158)
		(width 0.09525)
		(layer "In6.Cu")
		(net "M_K_CPU0_SA_DQS_DP<5>")
	)
	(arc
		(start 393.182348 -226.678744)
		(mid 393.240262 -226.479225)
		(end 393.38504 -226.330256)
		(width 0.09525)
		(layer "In6.Cu")
		(net "M_K_CPU0_SA_DQS_DP<5>")
	)
	(segment
		(start 390.267952 -246.370094)
		(end 390.734804 -246.104156)
		(width 0.12954)
		(layer "F.Cu")
		(net "M_K_CPU0_SA_DQS_DP<4>")
	)
	(segment
		(start 391.863326 -246.429276)
		(end 391.87374 -246.42318)
		(width 0.09525)
		(layer "In6.Cu")
		(net "M_K_CPU0_SA_DQS_DP<4>")
	)
	(segment
		(start 443.147196 -237.98403)
		(end 443.771274 -238.608108)
		(width 0.16002)
		(layer "In6.Cu")
		(net "M_K_CPU0_SA_DQS_DP<4>")
	)
	(segment
		(start 393.52982 -246.466614)
		(end 394.205968 -246.466614)
		(width 0.09525)
		(layer "In6.Cu")
		(net "M_K_CPU0_SA_DQS_DP<4>")
	)
	(segment
		(start 423.116248 -237.40999)
		(end 425.079414 -237.40999)
		(width 0.16002)
		(layer "In6.Cu")
		(net "M_K_CPU0_SA_DQS_DP<4>")
	)
	(segment
		(start 443.771274 -238.608108)
		(end 444.15075 -238.608108)
		(width 0.16002)
		(layer "In6.Cu")
		(net "M_K_CPU0_SA_DQS_DP<4>")
	)
	(segment
		(start 429.932084 -237.749588)
		(end 430.320704 -237.749588)
		(width 0.16002)
		(layer "In6.Cu")
		(net "M_K_CPU0_SA_DQS_DP<4>")
	)
	(segment
		(start 422.77665 -237.749588)
		(end 423.116248 -237.40999)
		(width 0.16002)
		(layer "In6.Cu")
		(net "M_K_CPU0_SA_DQS_DP<4>")
	)
	(segment
		(start 446.370456 -238.408972)
		(end 446.644268 -238.13516)
		(width 0.16002)
		(layer "In6.Cu")
		(net "M_K_CPU0_SA_DQS_DP<4>")
	)
	(segment
		(start 428.33925 -238.259874)
		(end 428.679864 -238.600488)
		(width 0.16002)
		(layer "In6.Cu")
		(net "M_K_CPU0_SA_DQS_DP<4>")
	)
	(segment
		(start 444.349886 -238.408972)
		(end 445.102488 -238.408972)
		(width 0.16002)
		(layer "In6.Cu")
		(net "M_K_CPU0_SA_DQS_DP<4>")
	)
	(segment
		(start 418.385244 -238.259874)
		(end 420.795196 -238.259874)
		(width 0.16002)
		(layer "In6.Cu")
		(net "M_K_CPU0_SA_DQS_DP<4>")
	)
	(segment
		(start 395.628622 -246.431816)
		(end 395.645386 -246.415052)
		(width 0.09525)
		(layer "In6.Cu")
		(net "M_K_CPU0_SA_DQS_DP<4>")
	)
	(segment
		(start 432.623468 -237.40999)
		(end 433.473352 -238.259874)
		(width 0.16002)
		(layer "In6.Cu")
		(net "M_K_CPU0_SA_DQS_DP<4>")
	)
	(segment
		(start 425.929298 -238.259874)
		(end 428.33925 -238.259874)
		(width 0.16002)
		(layer "In6.Cu")
		(net "M_K_CPU0_SA_DQS_DP<4>")
	)
	(segment
		(start 417.53536 -237.40999)
		(end 418.385244 -238.259874)
		(width 0.16002)
		(layer "In6.Cu")
		(net "M_K_CPU0_SA_DQS_DP<4>")
	)
	(segment
		(start 445.102488 -238.408972)
		(end 445.229488 -238.281972)
		(width 0.16002)
		(layer "In6.Cu")
		(net "M_K_CPU0_SA_DQS_DP<4>")
	)
	(segment
		(start 430.320704 -237.749588)
		(end 430.660302 -237.40999)
		(width 0.16002)
		(layer "In6.Cu")
		(net "M_K_CPU0_SA_DQS_DP<4>")
	)
	(segment
		(start 445.836548 -238.408972)
		(end 446.370456 -238.408972)
		(width 0.16002)
		(layer "In6.Cu")
		(net "M_K_CPU0_SA_DQS_DP<4>")
	)
	(segment
		(start 437.864758 -237.749588)
		(end 438.204356 -237.40999)
		(width 0.16002)
		(layer "In6.Cu")
		(net "M_K_CPU0_SA_DQS_DP<4>")
	)
	(segment
		(start 433.473352 -238.259874)
		(end 435.883304 -238.259874)
		(width 0.16002)
		(layer "In6.Cu")
		(net "M_K_CPU0_SA_DQS_DP<4>")
	)
	(segment
		(start 414.843976 -237.749588)
		(end 415.232596 -237.749588)
		(width 0.16002)
		(layer "In6.Cu")
		(net "M_K_CPU0_SA_DQS_DP<4>")
	)
	(segment
		(start 394.500354 -246.761)
		(end 395.38275 -246.761)
		(width 0.09525)
		(layer "In6.Cu")
		(net "M_K_CPU0_SA_DQS_DP<4>")
	)
	(segment
		(start 428.679864 -238.600488)
		(end 429.081184 -238.600488)
		(width 0.16002)
		(layer "In6.Cu")
		(net "M_K_CPU0_SA_DQS_DP<4>")
	)
	(segment
		(start 413.993076 -238.600488)
		(end 414.843976 -237.749588)
		(width 0.16002)
		(layer "In6.Cu")
		(net "M_K_CPU0_SA_DQS_DP<4>")
	)
	(segment
		(start 391.854944 -246.434102)
		(end 391.863326 -246.429276)
		(width 0.09525)
		(layer "In6.Cu")
		(net "M_K_CPU0_SA_DQS_DP<4>")
	)
	(segment
		(start 415.572194 -237.40999)
		(end 417.53536 -237.40999)
		(width 0.16002)
		(layer "In6.Cu")
		(net "M_K_CPU0_SA_DQS_DP<4>")
	)
	(segment
		(start 440.36234 -237.40999)
		(end 440.93638 -237.98403)
		(width 0.16002)
		(layer "In6.Cu")
		(net "M_K_CPU0_SA_DQS_DP<4>")
	)
	(segment
		(start 395.38275 -246.761)
		(end 395.628622 -246.515128)
		(width 0.09525)
		(layer "In6.Cu")
		(net "M_K_CPU0_SA_DQS_DP<4>")
	)
	(segment
		(start 444.15075 -238.608108)
		(end 444.349886 -238.408972)
		(width 0.16002)
		(layer "In6.Cu")
		(net "M_K_CPU0_SA_DQS_DP<4>")
	)
	(segment
		(start 392.425936 -246.429276)
		(end 392.434318 -246.434102)
		(width 0.09525)
		(layer "In6.Cu")
		(net "M_K_CPU0_SA_DQS_DP<4>")
	)
	(segment
		(start 437.476138 -237.749588)
		(end 437.864758 -237.749588)
		(width 0.16002)
		(layer "In6.Cu")
		(net "M_K_CPU0_SA_DQS_DP<4>")
	)
	(segment
		(start 422.38803 -237.749588)
		(end 422.77665 -237.749588)
		(width 0.16002)
		(layer "In6.Cu")
		(net "M_K_CPU0_SA_DQS_DP<4>")
	)
	(segment
		(start 415.232596 -237.749588)
		(end 415.572194 -237.40999)
		(width 0.16002)
		(layer "In6.Cu")
		(net "M_K_CPU0_SA_DQS_DP<4>")
	)
	(segment
		(start 394.205968 -246.466614)
		(end 394.500354 -246.761)
		(width 0.09525)
		(layer "In6.Cu")
		(net "M_K_CPU0_SA_DQS_DP<4>")
	)
	(segment
		(start 421.13581 -238.600488)
		(end 421.53713 -238.600488)
		(width 0.16002)
		(layer "In6.Cu")
		(net "M_K_CPU0_SA_DQS_DP<4>")
	)
	(segment
		(start 445.229488 -238.281972)
		(end 445.709548 -238.281972)
		(width 0.16002)
		(layer "In6.Cu")
		(net "M_K_CPU0_SA_DQS_DP<4>")
	)
	(segment
		(start 436.625238 -238.600488)
		(end 437.476138 -237.749588)
		(width 0.16002)
		(layer "In6.Cu")
		(net "M_K_CPU0_SA_DQS_DP<4>")
	)
	(segment
		(start 421.53713 -238.600488)
		(end 422.38803 -237.749588)
		(width 0.16002)
		(layer "In6.Cu")
		(net "M_K_CPU0_SA_DQS_DP<4>")
	)
	(segment
		(start 435.883304 -238.259874)
		(end 436.223918 -238.600488)
		(width 0.16002)
		(layer "In6.Cu")
		(net "M_K_CPU0_SA_DQS_DP<4>")
	)
	(segment
		(start 390.58088 -246.369586)
		(end 390.603994 -246.4562)
		(width 0.09525)
		(layer "In6.Cu")
		(net "M_K_CPU0_SA_DQS_DP<4>")
	)
	(segment
		(start 396.117826 -245.942612)
		(end 404.866602 -245.942612)
		(width 0.16002)
		(layer "In6.Cu")
		(net "M_K_CPU0_SA_DQS_DP<4>")
	)
	(segment
		(start 395.628622 -246.515128)
		(end 395.628622 -246.431816)
		(width 0.09525)
		(layer "In6.Cu")
		(net "M_K_CPU0_SA_DQS_DP<4>")
	)
	(segment
		(start 440.93638 -237.98403)
		(end 443.147196 -237.98403)
		(width 0.16002)
		(layer "In6.Cu")
		(net "M_K_CPU0_SA_DQS_DP<4>")
	)
	(segment
		(start 395.645386 -246.415052)
		(end 396.117826 -245.942612)
		(width 0.16002)
		(layer "In6.Cu")
		(net "M_K_CPU0_SA_DQS_DP<4>")
	)
	(segment
		(start 445.709548 -238.281972)
		(end 445.836548 -238.408972)
		(width 0.16002)
		(layer "In6.Cu")
		(net "M_K_CPU0_SA_DQS_DP<4>")
	)
	(segment
		(start 438.204356 -237.40999)
		(end 440.36234 -237.40999)
		(width 0.16002)
		(layer "In6.Cu")
		(net "M_K_CPU0_SA_DQS_DP<4>")
	)
	(segment
		(start 412.208726 -238.600488)
		(end 413.993076 -238.600488)
		(width 0.16002)
		(layer "In6.Cu")
		(net "M_K_CPU0_SA_DQS_DP<4>")
	)
	(segment
		(start 436.223918 -238.600488)
		(end 436.625238 -238.600488)
		(width 0.16002)
		(layer "In6.Cu")
		(net "M_K_CPU0_SA_DQS_DP<4>")
	)
	(segment
		(start 420.795196 -238.259874)
		(end 421.13581 -238.600488)
		(width 0.16002)
		(layer "In6.Cu")
		(net "M_K_CPU0_SA_DQS_DP<4>")
	)
	(segment
		(start 425.079414 -237.40999)
		(end 425.929298 -238.259874)
		(width 0.16002)
		(layer "In6.Cu")
		(net "M_K_CPU0_SA_DQS_DP<4>")
	)
	(segment
		(start 429.081184 -238.600488)
		(end 429.932084 -237.749588)
		(width 0.16002)
		(layer "In6.Cu")
		(net "M_K_CPU0_SA_DQS_DP<4>")
	)
	(segment
		(start 404.866602 -245.942612)
		(end 412.208726 -238.600488)
		(width 0.16002)
		(layer "In6.Cu")
		(net "M_K_CPU0_SA_DQS_DP<4>")
	)
	(segment
		(start 430.660302 -237.40999)
		(end 432.623468 -237.40999)
		(width 0.16002)
		(layer "In6.Cu")
		(net "M_K_CPU0_SA_DQS_DP<4>")
	)
	(segment
		(start 390.734804 -246.104156)
		(end 390.58088 -246.369586)
		(width 0.09525)
		(layer "In6.Cu")
		(net "M_K_CPU0_SA_DQS_DP<4>")
	)
	(arc
		(start 392.434318 -246.434102)
		(mid 392.61935 -246.480016)
		(end 392.803126 -246.429276)
		(width 0.09525)
		(layer "In6.Cu")
		(net "M_K_CPU0_SA_DQS_DP<4>")
	)
	(arc
		(start 393.351258 -246.42064)
		(mid 393.437679 -246.454743)
		(end 393.52982 -246.466614)
		(width 0.09525)
		(layer "In6.Cu")
		(net "M_K_CPU0_SA_DQS_DP<4>")
	)
	(arc
		(start 391.87374 -246.42318)
		(mid 392.150648 -246.353503)
		(end 392.425936 -246.429276)
		(width 0.09525)
		(layer "In6.Cu")
		(net "M_K_CPU0_SA_DQS_DP<4>")
	)
	(arc
		(start 391.486136 -246.429276)
		(mid 391.669911 -246.480048)
		(end 391.854944 -246.434102)
		(width 0.09525)
		(layer "In6.Cu")
		(net "M_K_CPU0_SA_DQS_DP<4>")
	)
	(arc
		(start 392.803126 -246.429276)
		(mid 393.076054 -246.353462)
		(end 393.351258 -246.42064)
		(width 0.09525)
		(layer "In6.Cu")
		(net "M_K_CPU0_SA_DQS_DP<4>")
	)
	(arc
		(start 390.603994 -246.4562)
		(mid 390.766645 -246.47846)
		(end 390.923272 -246.429276)
		(width 0.09525)
		(layer "In6.Cu")
		(net "M_K_CPU0_SA_DQS_DP<4>")
	)
	(arc
		(start 390.923272 -246.429276)
		(mid 391.204704 -246.353521)
		(end 391.486136 -246.429276)
		(width 0.09525)
		(layer "In6.Cu")
		(net "M_K_CPU0_SA_DQS_DP<4>")
	)
	(segment
		(start 390.267952 -241.510058)
		(end 390.734804 -241.24412)
		(width 0.12954)
		(layer "F.Cu")
		(net "M_K_CPU0_SA_DQS_DP<3>")
	)
	(segment
		(start 436.223918 -229.250494)
		(end 436.625238 -229.250494)
		(width 0.16002)
		(layer "In6.Cu")
		(net "M_K_CPU0_SA_DQS_DP<3>")
	)
	(segment
		(start 423.116248 -228.059996)
		(end 425.079414 -228.059996)
		(width 0.16002)
		(layer "In6.Cu")
		(net "M_K_CPU0_SA_DQS_DP<3>")
	)
	(segment
		(start 421.53713 -229.250494)
		(end 422.38803 -228.399594)
		(width 0.16002)
		(layer "In6.Cu")
		(net "M_K_CPU0_SA_DQS_DP<3>")
	)
	(segment
		(start 413.993076 -229.250494)
		(end 414.843976 -228.399594)
		(width 0.16002)
		(layer "In6.Cu")
		(net "M_K_CPU0_SA_DQS_DP<3>")
	)
	(segment
		(start 390.58088 -241.50955)
		(end 390.603994 -241.596164)
		(width 0.09525)
		(layer "In6.Cu")
		(net "M_K_CPU0_SA_DQS_DP<3>")
	)
	(segment
		(start 437.476138 -228.399594)
		(end 437.864758 -228.399594)
		(width 0.16002)
		(layer "In6.Cu")
		(net "M_K_CPU0_SA_DQS_DP<3>")
	)
	(segment
		(start 445.021208 -229.058978)
		(end 445.148208 -228.931978)
		(width 0.16002)
		(layer "In6.Cu")
		(net "M_K_CPU0_SA_DQS_DP<3>")
	)
	(segment
		(start 422.77665 -228.399594)
		(end 423.116248 -228.059996)
		(width 0.16002)
		(layer "In6.Cu")
		(net "M_K_CPU0_SA_DQS_DP<3>")
	)
	(segment
		(start 393.884658 -241.493294)
		(end 394.448792 -240.92916)
		(width 0.09525)
		(layer "In6.Cu")
		(net "M_K_CPU0_SA_DQS_DP<3>")
	)
	(segment
		(start 390.734804 -241.24412)
		(end 390.58088 -241.50955)
		(width 0.09525)
		(layer "In6.Cu")
		(net "M_K_CPU0_SA_DQS_DP<3>")
	)
	(segment
		(start 425.079414 -228.059996)
		(end 425.929298 -228.90988)
		(width 0.16002)
		(layer "In6.Cu")
		(net "M_K_CPU0_SA_DQS_DP<3>")
	)
	(segment
		(start 437.864758 -228.399594)
		(end 438.204356 -228.059996)
		(width 0.16002)
		(layer "In6.Cu")
		(net "M_K_CPU0_SA_DQS_DP<3>")
	)
	(segment
		(start 435.883304 -228.90988)
		(end 436.223918 -229.250494)
		(width 0.16002)
		(layer "In6.Cu")
		(net "M_K_CPU0_SA_DQS_DP<3>")
	)
	(segment
		(start 445.628268 -228.931978)
		(end 445.755268 -229.058978)
		(width 0.16002)
		(layer "In6.Cu")
		(net "M_K_CPU0_SA_DQS_DP<3>")
	)
	(segment
		(start 430.320704 -228.399594)
		(end 430.660302 -228.059996)
		(width 0.16002)
		(layer "In6.Cu")
		(net "M_K_CPU0_SA_DQS_DP<3>")
	)
	(segment
		(start 407.148538 -233.420666)
		(end 411.31871 -229.250494)
		(width 0.16002)
		(layer "In6.Cu")
		(net "M_K_CPU0_SA_DQS_DP<3>")
	)
	(segment
		(start 421.13581 -229.250494)
		(end 421.53713 -229.250494)
		(width 0.16002)
		(layer "In6.Cu")
		(net "M_K_CPU0_SA_DQS_DP<3>")
	)
	(segment
		(start 415.572194 -228.059996)
		(end 417.53536 -228.059996)
		(width 0.16002)
		(layer "In6.Cu")
		(net "M_K_CPU0_SA_DQS_DP<3>")
	)
	(segment
		(start 428.33925 -228.90988)
		(end 428.679864 -229.250494)
		(width 0.16002)
		(layer "In6.Cu")
		(net "M_K_CPU0_SA_DQS_DP<3>")
	)
	(segment
		(start 446.370456 -229.058978)
		(end 446.644268 -228.785166)
		(width 0.16002)
		(layer "In6.Cu")
		(net "M_K_CPU0_SA_DQS_DP<3>")
	)
	(segment
		(start 445.755268 -229.058978)
		(end 446.370456 -229.058978)
		(width 0.16002)
		(layer "In6.Cu")
		(net "M_K_CPU0_SA_DQS_DP<3>")
	)
	(segment
		(start 418.385244 -228.90988)
		(end 420.795196 -228.90988)
		(width 0.16002)
		(layer "In6.Cu")
		(net "M_K_CPU0_SA_DQS_DP<3>")
	)
	(segment
		(start 394.448792 -240.92916)
		(end 394.95984 -240.92916)
		(width 0.09525)
		(layer "In6.Cu")
		(net "M_K_CPU0_SA_DQS_DP<3>")
	)
	(segment
		(start 425.929298 -228.90988)
		(end 428.33925 -228.90988)
		(width 0.16002)
		(layer "In6.Cu")
		(net "M_K_CPU0_SA_DQS_DP<3>")
	)
	(segment
		(start 420.795196 -228.90988)
		(end 421.13581 -229.250494)
		(width 0.16002)
		(layer "In6.Cu")
		(net "M_K_CPU0_SA_DQS_DP<3>")
	)
	(segment
		(start 430.660302 -228.059996)
		(end 432.623468 -228.059996)
		(width 0.16002)
		(layer "In6.Cu")
		(net "M_K_CPU0_SA_DQS_DP<3>")
	)
	(segment
		(start 436.625238 -229.250494)
		(end 437.476138 -228.399594)
		(width 0.16002)
		(layer "In6.Cu")
		(net "M_K_CPU0_SA_DQS_DP<3>")
	)
	(segment
		(start 411.31871 -229.250494)
		(end 413.993076 -229.250494)
		(width 0.16002)
		(layer "In6.Cu")
		(net "M_K_CPU0_SA_DQS_DP<3>")
	)
	(segment
		(start 440.93638 -228.634036)
		(end 443.147196 -228.634036)
		(width 0.16002)
		(layer "In6.Cu")
		(net "M_K_CPU0_SA_DQS_DP<3>")
	)
	(segment
		(start 428.679864 -229.250494)
		(end 429.081184 -229.250494)
		(width 0.16002)
		(layer "In6.Cu")
		(net "M_K_CPU0_SA_DQS_DP<3>")
	)
	(segment
		(start 444.349886 -229.058978)
		(end 445.021208 -229.058978)
		(width 0.16002)
		(layer "In6.Cu")
		(net "M_K_CPU0_SA_DQS_DP<3>")
	)
	(segment
		(start 429.932084 -228.399594)
		(end 430.320704 -228.399594)
		(width 0.16002)
		(layer "In6.Cu")
		(net "M_K_CPU0_SA_DQS_DP<3>")
	)
	(segment
		(start 407.148538 -235.450126)
		(end 407.148538 -233.420666)
		(width 0.16002)
		(layer "In6.Cu")
		(net "M_K_CPU0_SA_DQS_DP<3>")
	)
	(segment
		(start 429.081184 -229.250494)
		(end 429.932084 -228.399594)
		(width 0.16002)
		(layer "In6.Cu")
		(net "M_K_CPU0_SA_DQS_DP<3>")
	)
	(segment
		(start 402.274024 -240.32464)
		(end 407.148538 -235.450126)
		(width 0.16002)
		(layer "In6.Cu")
		(net "M_K_CPU0_SA_DQS_DP<3>")
	)
	(segment
		(start 438.204356 -228.059996)
		(end 440.36234 -228.059996)
		(width 0.16002)
		(layer "In6.Cu")
		(net "M_K_CPU0_SA_DQS_DP<3>")
	)
	(segment
		(start 415.232596 -228.399594)
		(end 415.572194 -228.059996)
		(width 0.16002)
		(layer "In6.Cu")
		(net "M_K_CPU0_SA_DQS_DP<3>")
	)
	(segment
		(start 391.854944 -241.574066)
		(end 391.863326 -241.56924)
		(width 0.09525)
		(layer "In6.Cu")
		(net "M_K_CPU0_SA_DQS_DP<3>")
	)
	(segment
		(start 445.148208 -228.931978)
		(end 445.628268 -228.931978)
		(width 0.16002)
		(layer "In6.Cu")
		(net "M_K_CPU0_SA_DQS_DP<3>")
	)
	(segment
		(start 417.53536 -228.059996)
		(end 418.385244 -228.90988)
		(width 0.16002)
		(layer "In6.Cu")
		(net "M_K_CPU0_SA_DQS_DP<3>")
	)
	(segment
		(start 433.473352 -228.90988)
		(end 435.883304 -228.90988)
		(width 0.16002)
		(layer "In6.Cu")
		(net "M_K_CPU0_SA_DQS_DP<3>")
	)
	(segment
		(start 395.505178 -240.383822)
		(end 395.77645 -240.383822)
		(width 0.09525)
		(layer "In6.Cu")
		(net "M_K_CPU0_SA_DQS_DP<3>")
	)
	(segment
		(start 440.36234 -228.059996)
		(end 440.93638 -228.634036)
		(width 0.16002)
		(layer "In6.Cu")
		(net "M_K_CPU0_SA_DQS_DP<3>")
	)
	(segment
		(start 391.863326 -241.56924)
		(end 391.87374 -241.563144)
		(width 0.09525)
		(layer "In6.Cu")
		(net "M_K_CPU0_SA_DQS_DP<3>")
	)
	(segment
		(start 395.859254 -240.32464)
		(end 402.274024 -240.32464)
		(width 0.16002)
		(layer "In6.Cu")
		(net "M_K_CPU0_SA_DQS_DP<3>")
	)
	(segment
		(start 443.147196 -228.634036)
		(end 443.771274 -229.258114)
		(width 0.16002)
		(layer "In6.Cu")
		(net "M_K_CPU0_SA_DQS_DP<3>")
	)
	(segment
		(start 394.95984 -240.92916)
		(end 395.505178 -240.383822)
		(width 0.09525)
		(layer "In6.Cu")
		(net "M_K_CPU0_SA_DQS_DP<3>")
	)
	(segment
		(start 414.843976 -228.399594)
		(end 415.232596 -228.399594)
		(width 0.16002)
		(layer "In6.Cu")
		(net "M_K_CPU0_SA_DQS_DP<3>")
	)
	(segment
		(start 422.38803 -228.399594)
		(end 422.77665 -228.399594)
		(width 0.16002)
		(layer "In6.Cu")
		(net "M_K_CPU0_SA_DQS_DP<3>")
	)
	(segment
		(start 444.15075 -229.258114)
		(end 444.349886 -229.058978)
		(width 0.16002)
		(layer "In6.Cu")
		(net "M_K_CPU0_SA_DQS_DP<3>")
	)
	(segment
		(start 395.77645 -240.383822)
		(end 395.835632 -240.32464)
		(width 0.09525)
		(layer "In6.Cu")
		(net "M_K_CPU0_SA_DQS_DP<3>")
	)
	(segment
		(start 392.425936 -241.56924)
		(end 392.434318 -241.574066)
		(width 0.09525)
		(layer "In6.Cu")
		(net "M_K_CPU0_SA_DQS_DP<3>")
	)
	(segment
		(start 393.084812 -241.493294)
		(end 393.884658 -241.493294)
		(width 0.09525)
		(layer "In6.Cu")
		(net "M_K_CPU0_SA_DQS_DP<3>")
	)
	(segment
		(start 432.623468 -228.059996)
		(end 433.473352 -228.90988)
		(width 0.16002)
		(layer "In6.Cu")
		(net "M_K_CPU0_SA_DQS_DP<3>")
	)
	(segment
		(start 395.835632 -240.32464)
		(end 395.859254 -240.32464)
		(width 0.09525)
		(layer "In6.Cu")
		(net "M_K_CPU0_SA_DQS_DP<3>")
	)
	(segment
		(start 443.771274 -229.258114)
		(end 444.15075 -229.258114)
		(width 0.16002)
		(layer "In6.Cu")
		(net "M_K_CPU0_SA_DQS_DP<3>")
	)
	(arc
		(start 392.803126 -241.56924)
		(mid 392.938948 -241.51266)
		(end 393.084812 -241.493294)
		(width 0.09525)
		(layer "In6.Cu")
		(net "M_K_CPU0_SA_DQS_DP<3>")
	)
	(arc
		(start 391.486136 -241.56924)
		(mid 391.669911 -241.620012)
		(end 391.854944 -241.574066)
		(width 0.09525)
		(layer "In6.Cu")
		(net "M_K_CPU0_SA_DQS_DP<3>")
	)
	(arc
		(start 391.87374 -241.563144)
		(mid 392.150648 -241.493467)
		(end 392.425936 -241.56924)
		(width 0.09525)
		(layer "In6.Cu")
		(net "M_K_CPU0_SA_DQS_DP<3>")
	)
	(arc
		(start 390.923272 -241.56924)
		(mid 391.204704 -241.493485)
		(end 391.486136 -241.56924)
		(width 0.09525)
		(layer "In6.Cu")
		(net "M_K_CPU0_SA_DQS_DP<3>")
	)
	(arc
		(start 392.434318 -241.574066)
		(mid 392.61935 -241.61998)
		(end 392.803126 -241.56924)
		(width 0.09525)
		(layer "In6.Cu")
		(net "M_K_CPU0_SA_DQS_DP<3>")
	)
	(arc
		(start 390.603994 -241.596164)
		(mid 390.766645 -241.618424)
		(end 390.923272 -241.56924)
		(width 0.09525)
		(layer "In6.Cu")
		(net "M_K_CPU0_SA_DQS_DP<3>")
	)
	(segment
		(start 390.267952 -236.650022)
		(end 390.734804 -236.384084)
		(width 0.12954)
		(layer "F.Cu")
		(net "M_K_CPU0_SA_DQS_DP<2>")
	)
	(segment
		(start 429.081184 -219.9005)
		(end 429.932084 -219.0496)
		(width 0.16002)
		(layer "In6.Cu")
		(net "M_K_CPU0_SA_DQS_DP<2>")
	)
	(segment
		(start 443.147196 -219.284042)
		(end 443.771274 -219.90812)
		(width 0.16002)
		(layer "In6.Cu")
		(net "M_K_CPU0_SA_DQS_DP<2>")
	)
	(segment
		(start 445.572388 -219.581984)
		(end 445.699388 -219.708984)
		(width 0.16002)
		(layer "In6.Cu")
		(net "M_K_CPU0_SA_DQS_DP<2>")
	)
	(segment
		(start 394.495274 -235.47197)
		(end 394.792962 -235.47197)
		(width 0.09525)
		(layer "In6.Cu")
		(net "M_K_CPU0_SA_DQS_DP<2>")
	)
	(segment
		(start 420.795196 -219.559886)
		(end 421.13581 -219.9005)
		(width 0.16002)
		(layer "In6.Cu")
		(net "M_K_CPU0_SA_DQS_DP<2>")
	)
	(segment
		(start 415.572194 -218.710002)
		(end 417.53536 -218.710002)
		(width 0.16002)
		(layer "In6.Cu")
		(net "M_K_CPU0_SA_DQS_DP<2>")
	)
	(segment
		(start 397.737838 -234.69854)
		(end 409.048458 -223.38792)
		(width 0.16002)
		(layer "In6.Cu")
		(net "M_K_CPU0_SA_DQS_DP<2>")
	)
	(segment
		(start 444.349886 -219.708984)
		(end 444.965328 -219.708984)
		(width 0.16002)
		(layer "In6.Cu")
		(net "M_K_CPU0_SA_DQS_DP<2>")
	)
	(segment
		(start 425.929298 -219.559886)
		(end 428.33925 -219.559886)
		(width 0.16002)
		(layer "In6.Cu")
		(net "M_K_CPU0_SA_DQS_DP<2>")
	)
	(segment
		(start 436.625238 -219.9005)
		(end 437.476138 -219.0496)
		(width 0.16002)
		(layer "In6.Cu")
		(net "M_K_CPU0_SA_DQS_DP<2>")
	)
	(segment
		(start 395.835632 -234.69854)
		(end 395.859254 -234.69854)
		(width 0.09525)
		(layer "In6.Cu")
		(net "M_K_CPU0_SA_DQS_DP<2>")
	)
	(segment
		(start 395.50721 -234.757722)
		(end 395.77645 -234.757722)
		(width 0.09525)
		(layer "In6.Cu")
		(net "M_K_CPU0_SA_DQS_DP<2>")
	)
	(segment
		(start 435.883304 -219.559886)
		(end 436.223918 -219.9005)
		(width 0.16002)
		(layer "In6.Cu")
		(net "M_K_CPU0_SA_DQS_DP<2>")
	)
	(segment
		(start 445.699388 -219.708984)
		(end 446.370456 -219.708984)
		(width 0.16002)
		(layer "In6.Cu")
		(net "M_K_CPU0_SA_DQS_DP<2>")
	)
	(segment
		(start 390.734804 -236.384084)
		(end 390.58088 -236.649514)
		(width 0.09525)
		(layer "In6.Cu")
		(net "M_K_CPU0_SA_DQS_DP<2>")
	)
	(segment
		(start 440.93638 -219.284042)
		(end 443.147196 -219.284042)
		(width 0.16002)
		(layer "In6.Cu")
		(net "M_K_CPU0_SA_DQS_DP<2>")
	)
	(segment
		(start 445.092328 -219.581984)
		(end 445.572388 -219.581984)
		(width 0.16002)
		(layer "In6.Cu")
		(net "M_K_CPU0_SA_DQS_DP<2>")
	)
	(segment
		(start 394.792962 -235.47197)
		(end 395.50721 -234.757722)
		(width 0.09525)
		(layer "In6.Cu")
		(net "M_K_CPU0_SA_DQS_DP<2>")
	)
	(segment
		(start 429.932084 -219.0496)
		(end 430.320704 -219.0496)
		(width 0.16002)
		(layer "In6.Cu")
		(net "M_K_CPU0_SA_DQS_DP<2>")
	)
	(segment
		(start 413.993076 -219.9005)
		(end 414.843976 -219.0496)
		(width 0.16002)
		(layer "In6.Cu")
		(net "M_K_CPU0_SA_DQS_DP<2>")
	)
	(segment
		(start 432.623468 -218.710002)
		(end 433.473352 -219.559886)
		(width 0.16002)
		(layer "In6.Cu")
		(net "M_K_CPU0_SA_DQS_DP<2>")
	)
	(segment
		(start 430.660302 -218.710002)
		(end 432.623468 -218.710002)
		(width 0.16002)
		(layer "In6.Cu")
		(net "M_K_CPU0_SA_DQS_DP<2>")
	)
	(segment
		(start 437.476138 -219.0496)
		(end 437.864758 -219.0496)
		(width 0.16002)
		(layer "In6.Cu")
		(net "M_K_CPU0_SA_DQS_DP<2>")
	)
	(segment
		(start 433.473352 -219.559886)
		(end 435.883304 -219.559886)
		(width 0.16002)
		(layer "In6.Cu")
		(net "M_K_CPU0_SA_DQS_DP<2>")
	)
	(segment
		(start 421.13581 -219.9005)
		(end 421.53713 -219.9005)
		(width 0.16002)
		(layer "In6.Cu")
		(net "M_K_CPU0_SA_DQS_DP<2>")
	)
	(segment
		(start 422.38803 -219.0496)
		(end 422.77665 -219.0496)
		(width 0.16002)
		(layer "In6.Cu")
		(net "M_K_CPU0_SA_DQS_DP<2>")
	)
	(segment
		(start 392.425936 -236.709204)
		(end 392.434318 -236.71403)
		(width 0.09525)
		(layer "In6.Cu")
		(net "M_K_CPU0_SA_DQS_DP<2>")
	)
	(segment
		(start 409.048458 -223.38792)
		(end 409.048458 -222.7072)
		(width 0.16002)
		(layer "In6.Cu")
		(net "M_K_CPU0_SA_DQS_DP<2>")
	)
	(segment
		(start 446.370456 -219.708984)
		(end 446.644268 -219.435172)
		(width 0.16002)
		(layer "In6.Cu")
		(net "M_K_CPU0_SA_DQS_DP<2>")
	)
	(segment
		(start 428.33925 -219.559886)
		(end 428.679864 -219.9005)
		(width 0.16002)
		(layer "In6.Cu")
		(net "M_K_CPU0_SA_DQS_DP<2>")
	)
	(segment
		(start 415.232596 -219.0496)
		(end 415.572194 -218.710002)
		(width 0.16002)
		(layer "In6.Cu")
		(net "M_K_CPU0_SA_DQS_DP<2>")
	)
	(segment
		(start 395.859254 -234.69854)
		(end 397.737838 -234.69854)
		(width 0.16002)
		(layer "In6.Cu")
		(net "M_K_CPU0_SA_DQS_DP<2>")
	)
	(segment
		(start 417.53536 -218.710002)
		(end 418.385244 -219.559886)
		(width 0.16002)
		(layer "In6.Cu")
		(net "M_K_CPU0_SA_DQS_DP<2>")
	)
	(segment
		(start 437.864758 -219.0496)
		(end 438.204356 -218.710002)
		(width 0.16002)
		(layer "In6.Cu")
		(net "M_K_CPU0_SA_DQS_DP<2>")
	)
	(segment
		(start 425.079414 -218.710002)
		(end 425.929298 -219.559886)
		(width 0.16002)
		(layer "In6.Cu")
		(net "M_K_CPU0_SA_DQS_DP<2>")
	)
	(segment
		(start 423.116248 -218.710002)
		(end 425.079414 -218.710002)
		(width 0.16002)
		(layer "In6.Cu")
		(net "M_K_CPU0_SA_DQS_DP<2>")
	)
	(segment
		(start 421.53713 -219.9005)
		(end 422.38803 -219.0496)
		(width 0.16002)
		(layer "In6.Cu")
		(net "M_K_CPU0_SA_DQS_DP<2>")
	)
	(segment
		(start 444.15075 -219.90812)
		(end 444.349886 -219.708984)
		(width 0.16002)
		(layer "In6.Cu")
		(net "M_K_CPU0_SA_DQS_DP<2>")
	)
	(segment
		(start 436.223918 -219.9005)
		(end 436.625238 -219.9005)
		(width 0.16002)
		(layer "In6.Cu")
		(net "M_K_CPU0_SA_DQS_DP<2>")
	)
	(segment
		(start 428.679864 -219.9005)
		(end 429.081184 -219.9005)
		(width 0.16002)
		(layer "In6.Cu")
		(net "M_K_CPU0_SA_DQS_DP<2>")
	)
	(segment
		(start 430.320704 -219.0496)
		(end 430.660302 -218.710002)
		(width 0.16002)
		(layer "In6.Cu")
		(net "M_K_CPU0_SA_DQS_DP<2>")
	)
	(segment
		(start 444.965328 -219.708984)
		(end 445.092328 -219.581984)
		(width 0.16002)
		(layer "In6.Cu")
		(net "M_K_CPU0_SA_DQS_DP<2>")
	)
	(segment
		(start 393.084812 -236.633258)
		(end 393.333986 -236.633258)
		(width 0.09525)
		(layer "In6.Cu")
		(net "M_K_CPU0_SA_DQS_DP<2>")
	)
	(segment
		(start 418.385244 -219.559886)
		(end 420.795196 -219.559886)
		(width 0.16002)
		(layer "In6.Cu")
		(net "M_K_CPU0_SA_DQS_DP<2>")
	)
	(segment
		(start 409.048458 -222.7072)
		(end 411.855158 -219.9005)
		(width 0.16002)
		(layer "In6.Cu")
		(net "M_K_CPU0_SA_DQS_DP<2>")
	)
	(segment
		(start 414.843976 -219.0496)
		(end 415.232596 -219.0496)
		(width 0.16002)
		(layer "In6.Cu")
		(net "M_K_CPU0_SA_DQS_DP<2>")
	)
	(segment
		(start 438.204356 -218.710002)
		(end 440.36234 -218.710002)
		(width 0.16002)
		(layer "In6.Cu")
		(net "M_K_CPU0_SA_DQS_DP<2>")
	)
	(segment
		(start 411.855158 -219.9005)
		(end 413.993076 -219.9005)
		(width 0.16002)
		(layer "In6.Cu")
		(net "M_K_CPU0_SA_DQS_DP<2>")
	)
	(segment
		(start 440.36234 -218.710002)
		(end 440.93638 -219.284042)
		(width 0.16002)
		(layer "In6.Cu")
		(net "M_K_CPU0_SA_DQS_DP<2>")
	)
	(segment
		(start 393.333986 -236.633258)
		(end 394.495274 -235.47197)
		(width 0.09525)
		(layer "In6.Cu")
		(net "M_K_CPU0_SA_DQS_DP<2>")
	)
	(segment
		(start 395.77645 -234.757722)
		(end 395.835632 -234.69854)
		(width 0.09525)
		(layer "In6.Cu")
		(net "M_K_CPU0_SA_DQS_DP<2>")
	)
	(segment
		(start 422.77665 -219.0496)
		(end 423.116248 -218.710002)
		(width 0.16002)
		(layer "In6.Cu")
		(net "M_K_CPU0_SA_DQS_DP<2>")
	)
	(segment
		(start 391.854944 -236.71403)
		(end 391.863326 -236.709204)
		(width 0.09525)
		(layer "In6.Cu")
		(net "M_K_CPU0_SA_DQS_DP<2>")
	)
	(segment
		(start 390.58088 -236.649514)
		(end 390.603994 -236.736128)
		(width 0.09525)
		(layer "In6.Cu")
		(net "M_K_CPU0_SA_DQS_DP<2>")
	)
	(segment
		(start 443.771274 -219.90812)
		(end 444.15075 -219.90812)
		(width 0.16002)
		(layer "In6.Cu")
		(net "M_K_CPU0_SA_DQS_DP<2>")
	)
	(segment
		(start 391.863326 -236.709204)
		(end 391.87374 -236.703108)
		(width 0.09525)
		(layer "In6.Cu")
		(net "M_K_CPU0_SA_DQS_DP<2>")
	)
	(arc
		(start 390.603994 -236.736128)
		(mid 390.766645 -236.758388)
		(end 390.923272 -236.709204)
		(width 0.09525)
		(layer "In6.Cu")
		(net "M_K_CPU0_SA_DQS_DP<2>")
	)
	(arc
		(start 391.87374 -236.703108)
		(mid 392.150648 -236.633431)
		(end 392.425936 -236.709204)
		(width 0.09525)
		(layer "In6.Cu")
		(net "M_K_CPU0_SA_DQS_DP<2>")
	)
	(arc
		(start 392.803126 -236.709204)
		(mid 392.938948 -236.652624)
		(end 393.084812 -236.633258)
		(width 0.09525)
		(layer "In6.Cu")
		(net "M_K_CPU0_SA_DQS_DP<2>")
	)
	(arc
		(start 392.434318 -236.71403)
		(mid 392.61935 -236.759944)
		(end 392.803126 -236.709204)
		(width 0.09525)
		(layer "In6.Cu")
		(net "M_K_CPU0_SA_DQS_DP<2>")
	)
	(arc
		(start 390.923272 -236.709204)
		(mid 391.204704 -236.633449)
		(end 391.486136 -236.709204)
		(width 0.09525)
		(layer "In6.Cu")
		(net "M_K_CPU0_SA_DQS_DP<2>")
	)
	(arc
		(start 391.486136 -236.709204)
		(mid 391.669911 -236.759976)
		(end 391.854944 -236.71403)
		(width 0.09525)
		(layer "In6.Cu")
		(net "M_K_CPU0_SA_DQS_DP<2>")
	)
	(segment
		(start 390.267952 -231.789986)
		(end 390.734804 -231.524048)
		(width 0.12954)
		(layer "F.Cu")
		(net "M_K_CPU0_SA_DQS_DP<1>")
	)
	(segment
		(start 440.36234 -209.360008)
		(end 440.93638 -209.934048)
		(width 0.16002)
		(layer "In6.Cu")
		(net "M_K_CPU0_SA_DQS_DP<1>")
	)
	(segment
		(start 435.883304 -210.209892)
		(end 436.223918 -210.550506)
		(width 0.16002)
		(layer "In6.Cu")
		(net "M_K_CPU0_SA_DQS_DP<1>")
	)
	(segment
		(start 417.874958 -209.699606)
		(end 418.385244 -210.209892)
		(width 0.16002)
		(layer "In6.Cu")
		(net "M_K_CPU0_SA_DQS_DP<1>")
	)
	(segment
		(start 395.628622 -228.898196)
		(end 395.628622 -228.814884)
		(width 0.09525)
		(layer "In6.Cu")
		(net "M_K_CPU0_SA_DQS_DP<1>")
	)
	(segment
		(start 429.081184 -210.550506)
		(end 429.932084 -209.699606)
		(width 0.16002)
		(layer "In6.Cu")
		(net "M_K_CPU0_SA_DQS_DP<1>")
	)
	(segment
		(start 395.645386 -228.79812)
		(end 402.850858 -221.592648)
		(width 0.16002)
		(layer "In6.Cu")
		(net "M_K_CPU0_SA_DQS_DP<1>")
	)
	(segment
		(start 390.58088 -231.789478)
		(end 390.603994 -231.876092)
		(width 0.09525)
		(layer "In6.Cu")
		(net "M_K_CPU0_SA_DQS_DP<1>")
	)
	(segment
		(start 422.38803 -209.699606)
		(end 422.77665 -209.699606)
		(width 0.16002)
		(layer "In6.Cu")
		(net "M_K_CPU0_SA_DQS_DP<1>")
	)
	(segment
		(start 443.147196 -209.934048)
		(end 443.771274 -210.558126)
		(width 0.16002)
		(layer "In6.Cu")
		(net "M_K_CPU0_SA_DQS_DP<1>")
	)
	(segment
		(start 438.204356 -209.360008)
		(end 440.36234 -209.360008)
		(width 0.16002)
		(layer "In6.Cu")
		(net "M_K_CPU0_SA_DQS_DP<1>")
	)
	(segment
		(start 430.320704 -209.699606)
		(end 430.660302 -209.360008)
		(width 0.16002)
		(layer "In6.Cu")
		(net "M_K_CPU0_SA_DQS_DP<1>")
	)
	(segment
		(start 445.689228 -210.35899)
		(end 446.370456 -210.35899)
		(width 0.16002)
		(layer "In6.Cu")
		(net "M_K_CPU0_SA_DQS_DP<1>")
	)
	(segment
		(start 428.679864 -210.550506)
		(end 429.081184 -210.550506)
		(width 0.16002)
		(layer "In6.Cu")
		(net "M_K_CPU0_SA_DQS_DP<1>")
	)
	(segment
		(start 432.623468 -209.360008)
		(end 433.473352 -210.209892)
		(width 0.16002)
		(layer "In6.Cu")
		(net "M_K_CPU0_SA_DQS_DP<1>")
	)
	(segment
		(start 395.628622 -228.814884)
		(end 395.645386 -228.79812)
		(width 0.09525)
		(layer "In6.Cu")
		(net "M_K_CPU0_SA_DQS_DP<1>")
	)
	(segment
		(start 411.732984 -210.550506)
		(end 413.993076 -210.550506)
		(width 0.16002)
		(layer "In6.Cu")
		(net "M_K_CPU0_SA_DQS_DP<1>")
	)
	(segment
		(start 436.625238 -210.550506)
		(end 437.476138 -209.699606)
		(width 0.16002)
		(layer "In6.Cu")
		(net "M_K_CPU0_SA_DQS_DP<1>")
	)
	(segment
		(start 428.33925 -210.209892)
		(end 428.679864 -210.550506)
		(width 0.16002)
		(layer "In6.Cu")
		(net "M_K_CPU0_SA_DQS_DP<1>")
	)
	(segment
		(start 446.370456 -210.35899)
		(end 446.644268 -210.085178)
		(width 0.16002)
		(layer "In6.Cu")
		(net "M_K_CPU0_SA_DQS_DP<1>")
	)
	(segment
		(start 436.223918 -210.550506)
		(end 436.625238 -210.550506)
		(width 0.16002)
		(layer "In6.Cu")
		(net "M_K_CPU0_SA_DQS_DP<1>")
	)
	(segment
		(start 440.93638 -209.934048)
		(end 443.147196 -209.934048)
		(width 0.16002)
		(layer "In6.Cu")
		(net "M_K_CPU0_SA_DQS_DP<1>")
	)
	(segment
		(start 392.425936 -231.849168)
		(end 392.434318 -231.853994)
		(width 0.09525)
		(layer "In6.Cu")
		(net "M_K_CPU0_SA_DQS_DP<1>")
	)
	(segment
		(start 391.854944 -231.853994)
		(end 391.863326 -231.849168)
		(width 0.09525)
		(layer "In6.Cu")
		(net "M_K_CPU0_SA_DQS_DP<1>")
	)
	(segment
		(start 437.864758 -209.699606)
		(end 438.204356 -209.360008)
		(width 0.16002)
		(layer "In6.Cu")
		(net "M_K_CPU0_SA_DQS_DP<1>")
	)
	(segment
		(start 445.058546 -210.255612)
		(end 445.58585 -210.255612)
		(width 0.16002)
		(layer "In6.Cu")
		(net "M_K_CPU0_SA_DQS_DP<1>")
	)
	(segment
		(start 394.462762 -229.62616)
		(end 394.900658 -229.62616)
		(width 0.09525)
		(layer "In6.Cu")
		(net "M_K_CPU0_SA_DQS_DP<1>")
	)
	(segment
		(start 430.660302 -209.360008)
		(end 432.623468 -209.360008)
		(width 0.16002)
		(layer "In6.Cu")
		(net "M_K_CPU0_SA_DQS_DP<1>")
	)
	(segment
		(start 421.13581 -210.550506)
		(end 421.53713 -210.550506)
		(width 0.16002)
		(layer "In6.Cu")
		(net "M_K_CPU0_SA_DQS_DP<1>")
	)
	(segment
		(start 418.385244 -210.209892)
		(end 420.795196 -210.209892)
		(width 0.16002)
		(layer "In6.Cu")
		(net "M_K_CPU0_SA_DQS_DP<1>")
	)
	(segment
		(start 391.863326 -231.849168)
		(end 391.87374 -231.843072)
		(width 0.09525)
		(layer "In6.Cu")
		(net "M_K_CPU0_SA_DQS_DP<1>")
	)
	(segment
		(start 425.929298 -210.209892)
		(end 428.33925 -210.209892)
		(width 0.16002)
		(layer "In6.Cu")
		(net "M_K_CPU0_SA_DQS_DP<1>")
	)
	(segment
		(start 444.955168 -210.35899)
		(end 445.058546 -210.255612)
		(width 0.16002)
		(layer "In6.Cu")
		(net "M_K_CPU0_SA_DQS_DP<1>")
	)
	(segment
		(start 394.017246 -230.071676)
		(end 394.462762 -229.62616)
		(width 0.09525)
		(layer "In6.Cu")
		(net "M_K_CPU0_SA_DQS_DP<1>")
	)
	(segment
		(start 443.771274 -210.558126)
		(end 444.15075 -210.558126)
		(width 0.16002)
		(layer "In6.Cu")
		(net "M_K_CPU0_SA_DQS_DP<1>")
	)
	(segment
		(start 422.77665 -209.699606)
		(end 423.116248 -209.360008)
		(width 0.16002)
		(layer "In6.Cu")
		(net "M_K_CPU0_SA_DQS_DP<1>")
	)
	(segment
		(start 390.734804 -231.524048)
		(end 390.58088 -231.789478)
		(width 0.09525)
		(layer "In6.Cu")
		(net "M_K_CPU0_SA_DQS_DP<1>")
	)
	(segment
		(start 429.932084 -209.699606)
		(end 430.320704 -209.699606)
		(width 0.16002)
		(layer "In6.Cu")
		(net "M_K_CPU0_SA_DQS_DP<1>")
	)
	(segment
		(start 402.850858 -221.592648)
		(end 402.850858 -219.432632)
		(width 0.16002)
		(layer "In6.Cu")
		(net "M_K_CPU0_SA_DQS_DP<1>")
	)
	(segment
		(start 444.15075 -210.558126)
		(end 444.349886 -210.35899)
		(width 0.16002)
		(layer "In6.Cu")
		(net "M_K_CPU0_SA_DQS_DP<1>")
	)
	(segment
		(start 392.880596 -231.79024)
		(end 393.045188 -231.625648)
		(width 0.09525)
		(layer "In6.Cu")
		(net "M_K_CPU0_SA_DQS_DP<1>")
	)
	(segment
		(start 445.58585 -210.255612)
		(end 445.689228 -210.35899)
		(width 0.16002)
		(layer "In6.Cu")
		(net "M_K_CPU0_SA_DQS_DP<1>")
	)
	(segment
		(start 444.349886 -210.35899)
		(end 444.955168 -210.35899)
		(width 0.16002)
		(layer "In6.Cu")
		(net "M_K_CPU0_SA_DQS_DP<1>")
	)
	(segment
		(start 420.795196 -210.209892)
		(end 421.13581 -210.550506)
		(width 0.16002)
		(layer "In6.Cu")
		(net "M_K_CPU0_SA_DQS_DP<1>")
	)
	(segment
		(start 425.079414 -209.360008)
		(end 425.929298 -210.209892)
		(width 0.16002)
		(layer "In6.Cu")
		(net "M_K_CPU0_SA_DQS_DP<1>")
	)
	(segment
		(start 423.116248 -209.360008)
		(end 425.079414 -209.360008)
		(width 0.16002)
		(layer "In6.Cu")
		(net "M_K_CPU0_SA_DQS_DP<1>")
	)
	(segment
		(start 394.900658 -229.62616)
		(end 395.628622 -228.898196)
		(width 0.09525)
		(layer "In6.Cu")
		(net "M_K_CPU0_SA_DQS_DP<1>")
	)
	(segment
		(start 414.843976 -209.699606)
		(end 417.874958 -209.699606)
		(width 0.16002)
		(layer "In6.Cu")
		(net "M_K_CPU0_SA_DQS_DP<1>")
	)
	(segment
		(start 393.045188 -231.625648)
		(end 393.166854 -231.625648)
		(width 0.09525)
		(layer "In6.Cu")
		(net "M_K_CPU0_SA_DQS_DP<1>")
	)
	(segment
		(start 421.53713 -210.550506)
		(end 422.38803 -209.699606)
		(width 0.16002)
		(layer "In6.Cu")
		(net "M_K_CPU0_SA_DQS_DP<1>")
	)
	(segment
		(start 437.476138 -209.699606)
		(end 437.864758 -209.699606)
		(width 0.16002)
		(layer "In6.Cu")
		(net "M_K_CPU0_SA_DQS_DP<1>")
	)
	(segment
		(start 433.473352 -210.209892)
		(end 435.883304 -210.209892)
		(width 0.16002)
		(layer "In6.Cu")
		(net "M_K_CPU0_SA_DQS_DP<1>")
	)
	(segment
		(start 402.850858 -219.432632)
		(end 411.732984 -210.550506)
		(width 0.16002)
		(layer "In6.Cu")
		(net "M_K_CPU0_SA_DQS_DP<1>")
	)
	(segment
		(start 394.017246 -230.775256)
		(end 394.017246 -230.071676)
		(width 0.09525)
		(layer "In6.Cu")
		(net "M_K_CPU0_SA_DQS_DP<1>")
	)
	(segment
		(start 413.993076 -210.550506)
		(end 414.843976 -209.699606)
		(width 0.16002)
		(layer "In6.Cu")
		(net "M_K_CPU0_SA_DQS_DP<1>")
	)
	(segment
		(start 393.166854 -231.625648)
		(end 394.017246 -230.775256)
		(width 0.09525)
		(layer "In6.Cu")
		(net "M_K_CPU0_SA_DQS_DP<1>")
	)
	(arc
		(start 390.603994 -231.876092)
		(mid 390.766645 -231.898352)
		(end 390.923272 -231.849168)
		(width 0.09525)
		(layer "In6.Cu")
		(net "M_K_CPU0_SA_DQS_DP<1>")
	)
	(arc
		(start 390.923272 -231.849168)
		(mid 391.204704 -231.773413)
		(end 391.486136 -231.849168)
		(width 0.09525)
		(layer "In6.Cu")
		(net "M_K_CPU0_SA_DQS_DP<1>")
	)
	(arc
		(start 391.486136 -231.849168)
		(mid 391.669911 -231.89994)
		(end 391.854944 -231.853994)
		(width 0.09525)
		(layer "In6.Cu")
		(net "M_K_CPU0_SA_DQS_DP<1>")
	)
	(arc
		(start 392.434318 -231.853994)
		(mid 392.61935 -231.899908)
		(end 392.803126 -231.849168)
		(width 0.09525)
		(layer "In6.Cu")
		(net "M_K_CPU0_SA_DQS_DP<1>")
	)
	(arc
		(start 392.803126 -231.849168)
		(mid 392.843769 -231.822214)
		(end 392.880596 -231.79024)
		(width 0.09525)
		(layer "In6.Cu")
		(net "M_K_CPU0_SA_DQS_DP<1>")
	)
	(arc
		(start 391.87374 -231.843072)
		(mid 392.150648 -231.773395)
		(end 392.425936 -231.849168)
		(width 0.09525)
		(layer "In6.Cu")
		(net "M_K_CPU0_SA_DQS_DP<1>")
	)
	(segment
		(start 390.267952 -226.930204)
		(end 390.734804 -226.664266)
		(width 0.12954)
		(layer "F.Cu")
		(net "M_K_CPU0_SA_DQS_DP<0>")
	)
	(segment
		(start 414.843976 -200.349612)
		(end 413.993076 -201.200512)
		(width 0.16002)
		(layer "In6.Cu")
		(net "M_K_CPU0_SA_DQS_DP<0>")
	)
	(segment
		(start 425.079414 -200.010014)
		(end 423.116248 -200.010014)
		(width 0.16002)
		(layer "In6.Cu")
		(net "M_K_CPU0_SA_DQS_DP<0>")
	)
	(segment
		(start 445.770508 -201.008996)
		(end 445.677544 -200.916032)
		(width 0.16002)
		(layer "In6.Cu")
		(net "M_K_CPU0_SA_DQS_DP<0>")
	)
	(segment
		(start 396.894558 -218.82227)
		(end 393.968986 -221.747842)
		(width 0.16002)
		(layer "In6.Cu")
		(net "M_K_CPU0_SA_DQS_DP<0>")
	)
	(segment
		(start 430.660302 -200.010014)
		(end 430.320704 -200.349612)
		(width 0.16002)
		(layer "In6.Cu")
		(net "M_K_CPU0_SA_DQS_DP<0>")
	)
	(segment
		(start 440.36234 -200.010014)
		(end 438.204356 -200.010014)
		(width 0.16002)
		(layer "In6.Cu")
		(net "M_K_CPU0_SA_DQS_DP<0>")
	)
	(segment
		(start 436.223918 -201.200512)
		(end 435.883304 -200.859898)
		(width 0.16002)
		(layer "In6.Cu")
		(net "M_K_CPU0_SA_DQS_DP<0>")
	)
	(segment
		(start 392.80338 -224.719134)
		(end 392.835892 -224.73793)
		(width 0.09525)
		(layer "In6.Cu")
		(net "M_K_CPU0_SA_DQS_DP<0>")
	)
	(segment
		(start 392.835892 -225.350578)
		(end 392.80338 -225.369374)
		(width 0.09525)
		(layer "In6.Cu")
		(net "M_K_CPU0_SA_DQS_DP<0>")
	)
	(segment
		(start 390.603994 -227.01631)
		(end 390.58088 -226.929696)
		(width 0.09525)
		(layer "In6.Cu")
		(net "M_K_CPU0_SA_DQS_DP<0>")
	)
	(segment
		(start 392.76528 -224.697036)
		(end 392.80338 -224.719134)
		(width 0.09525)
		(layer "In6.Cu")
		(net "M_K_CPU0_SA_DQS_DP<0>")
	)
	(segment
		(start 437.864758 -200.349612)
		(end 437.476138 -200.349612)
		(width 0.16002)
		(layer "In6.Cu")
		(net "M_K_CPU0_SA_DQS_DP<0>")
	)
	(segment
		(start 445.129412 -200.916032)
		(end 445.036448 -201.008996)
		(width 0.16002)
		(layer "In6.Cu")
		(net "M_K_CPU0_SA_DQS_DP<0>")
	)
	(segment
		(start 422.38803 -200.349612)
		(end 421.53713 -201.200512)
		(width 0.16002)
		(layer "In6.Cu")
		(net "M_K_CPU0_SA_DQS_DP<0>")
	)
	(segment
		(start 418.385244 -200.859898)
		(end 417.53536 -200.010014)
		(width 0.16002)
		(layer "In6.Cu")
		(net "M_K_CPU0_SA_DQS_DP<0>")
	)
	(segment
		(start 446.644268 -200.735184)
		(end 446.370456 -201.008996)
		(width 0.16002)
		(layer "In6.Cu")
		(net "M_K_CPU0_SA_DQS_DP<0>")
	)
	(segment
		(start 393.952222 -221.848426)
		(end 393.46251 -222.338138)
		(width 0.09525)
		(layer "In6.Cu")
		(net "M_K_CPU0_SA_DQS_DP<0>")
	)
	(segment
		(start 415.572194 -200.010014)
		(end 415.232596 -200.349612)
		(width 0.16002)
		(layer "In6.Cu")
		(net "M_K_CPU0_SA_DQS_DP<0>")
	)
	(segment
		(start 437.476138 -200.349612)
		(end 436.625238 -201.200512)
		(width 0.16002)
		(layer "In6.Cu")
		(net "M_K_CPU0_SA_DQS_DP<0>")
	)
	(segment
		(start 413.993076 -201.200512)
		(end 411.613096 -201.200512)
		(width 0.16002)
		(layer "In6.Cu")
		(net "M_K_CPU0_SA_DQS_DP<0>")
	)
	(segment
		(start 392.364976 -226.161092)
		(end 392.33348 -226.17938)
		(width 0.09525)
		(layer "In6.Cu")
		(net "M_K_CPU0_SA_DQS_DP<0>")
	)
	(segment
		(start 422.77665 -200.349612)
		(end 422.38803 -200.349612)
		(width 0.16002)
		(layer "In6.Cu")
		(net "M_K_CPU0_SA_DQS_DP<0>")
	)
	(segment
		(start 392.80338 -225.369374)
		(end 392.76528 -225.391472)
		(width 0.09525)
		(layer "In6.Cu")
		(net "M_K_CPU0_SA_DQS_DP<0>")
	)
	(segment
		(start 417.53536 -200.010014)
		(end 415.572194 -200.010014)
		(width 0.16002)
		(layer "In6.Cu")
		(net "M_K_CPU0_SA_DQS_DP<0>")
	)
	(segment
		(start 440.93638 -200.584054)
		(end 440.36234 -200.010014)
		(width 0.16002)
		(layer "In6.Cu")
		(net "M_K_CPU0_SA_DQS_DP<0>")
	)
	(segment
		(start 429.932084 -200.349612)
		(end 429.081184 -201.200512)
		(width 0.16002)
		(layer "In6.Cu")
		(net "M_K_CPU0_SA_DQS_DP<0>")
	)
	(segment
		(start 421.53713 -201.200512)
		(end 421.13581 -201.200512)
		(width 0.16002)
		(layer "In6.Cu")
		(net "M_K_CPU0_SA_DQS_DP<0>")
	)
	(segment
		(start 429.081184 -201.200512)
		(end 428.679864 -201.200512)
		(width 0.16002)
		(layer "In6.Cu")
		(net "M_K_CPU0_SA_DQS_DP<0>")
	)
	(segment
		(start 430.320704 -200.349612)
		(end 429.932084 -200.349612)
		(width 0.16002)
		(layer "In6.Cu")
		(net "M_K_CPU0_SA_DQS_DP<0>")
	)
	(segment
		(start 396.894558 -215.91905)
		(end 396.894558 -218.82227)
		(width 0.16002)
		(layer "In6.Cu")
		(net "M_K_CPU0_SA_DQS_DP<0>")
	)
	(segment
		(start 421.13581 -201.200512)
		(end 420.795196 -200.859898)
		(width 0.16002)
		(layer "In6.Cu")
		(net "M_K_CPU0_SA_DQS_DP<0>")
	)
	(segment
		(start 445.036448 -201.008996)
		(end 444.349886 -201.008996)
		(width 0.16002)
		(layer "In6.Cu")
		(net "M_K_CPU0_SA_DQS_DP<0>")
	)
	(segment
		(start 444.15075 -201.208132)
		(end 443.771274 -201.208132)
		(width 0.16002)
		(layer "In6.Cu")
		(net "M_K_CPU0_SA_DQS_DP<0>")
	)
	(segment
		(start 392.80338 -223.749362)
		(end 392.76528 -223.77146)
		(width 0.09525)
		(layer "In6.Cu")
		(net "M_K_CPU0_SA_DQS_DP<0>")
	)
	(segment
		(start 393.968986 -221.747842)
		(end 393.952222 -221.764606)
		(width 0.09525)
		(layer "In6.Cu")
		(net "M_K_CPU0_SA_DQS_DP<0>")
	)
	(segment
		(start 393.27328 -222.939356)
		(end 393.238228 -222.95993)
		(width 0.09525)
		(layer "In6.Cu")
		(net "M_K_CPU0_SA_DQS_DP<0>")
	)
	(segment
		(start 391.863326 -226.989386)
		(end 391.854944 -226.994212)
		(width 0.09525)
		(layer "In6.Cu")
		(net "M_K_CPU0_SA_DQS_DP<0>")
	)
	(segment
		(start 445.677544 -200.916032)
		(end 445.129412 -200.916032)
		(width 0.16002)
		(layer "In6.Cu")
		(net "M_K_CPU0_SA_DQS_DP<0>")
	)
	(segment
		(start 443.147196 -200.584054)
		(end 440.93638 -200.584054)
		(width 0.16002)
		(layer "In6.Cu")
		(net "M_K_CPU0_SA_DQS_DP<0>")
	)
	(segment
		(start 428.33925 -200.859898)
		(end 425.929298 -200.859898)
		(width 0.16002)
		(layer "In6.Cu")
		(net "M_K_CPU0_SA_DQS_DP<0>")
	)
	(segment
		(start 391.895838 -226.97059)
		(end 391.863326 -226.989386)
		(width 0.09525)
		(layer "In6.Cu")
		(net "M_K_CPU0_SA_DQS_DP<0>")
	)
	(segment
		(start 433.473352 -200.859898)
		(end 432.623468 -200.010014)
		(width 0.16002)
		(layer "In6.Cu")
		(net "M_K_CPU0_SA_DQS_DP<0>")
	)
	(segment
		(start 393.46251 -222.338138)
		(end 393.46251 -222.614236)
		(width 0.09525)
		(layer "In6.Cu")
		(net "M_K_CPU0_SA_DQS_DP<0>")
	)
	(segment
		(start 415.232596 -200.349612)
		(end 414.843976 -200.349612)
		(width 0.16002)
		(layer "In6.Cu")
		(net "M_K_CPU0_SA_DQS_DP<0>")
	)
	(segment
		(start 425.929298 -200.859898)
		(end 425.079414 -200.010014)
		(width 0.16002)
		(layer "In6.Cu")
		(net "M_K_CPU0_SA_DQS_DP<0>")
	)
	(segment
		(start 392.835892 -223.730566)
		(end 392.80338 -223.749362)
		(width 0.09525)
		(layer "In6.Cu")
		(net "M_K_CPU0_SA_DQS_DP<0>")
	)
	(segment
		(start 432.623468 -200.010014)
		(end 430.660302 -200.010014)
		(width 0.16002)
		(layer "In6.Cu")
		(net "M_K_CPU0_SA_DQS_DP<0>")
	)
	(segment
		(start 446.370456 -201.008996)
		(end 445.770508 -201.008996)
		(width 0.16002)
		(layer "In6.Cu")
		(net "M_K_CPU0_SA_DQS_DP<0>")
	)
	(segment
		(start 444.349886 -201.008996)
		(end 444.15075 -201.208132)
		(width 0.16002)
		(layer "In6.Cu")
		(net "M_K_CPU0_SA_DQS_DP<0>")
	)
	(segment
		(start 411.613096 -201.200512)
		(end 396.894558 -215.91905)
		(width 0.16002)
		(layer "In6.Cu")
		(net "M_K_CPU0_SA_DQS_DP<0>")
	)
	(segment
		(start 392.33348 -226.17938)
		(end 392.29538 -226.201478)
		(width 0.09525)
		(layer "In6.Cu")
		(net "M_K_CPU0_SA_DQS_DP<0>")
	)
	(segment
		(start 420.795196 -200.859898)
		(end 418.385244 -200.859898)
		(width 0.16002)
		(layer "In6.Cu")
		(net "M_K_CPU0_SA_DQS_DP<0>")
	)
	(segment
		(start 393.952222 -221.764606)
		(end 393.952222 -221.848426)
		(width 0.09525)
		(layer "In6.Cu")
		(net "M_K_CPU0_SA_DQS_DP<0>")
	)
	(segment
		(start 428.679864 -201.200512)
		(end 428.33925 -200.859898)
		(width 0.16002)
		(layer "In6.Cu")
		(net "M_K_CPU0_SA_DQS_DP<0>")
	)
	(segment
		(start 435.883304 -200.859898)
		(end 433.473352 -200.859898)
		(width 0.16002)
		(layer "In6.Cu")
		(net "M_K_CPU0_SA_DQS_DP<0>")
	)
	(segment
		(start 390.58088 -226.929696)
		(end 390.734804 -226.664266)
		(width 0.09525)
		(layer "In6.Cu")
		(net "M_K_CPU0_SA_DQS_DP<0>")
	)
	(segment
		(start 393.305792 -222.92056)
		(end 393.27328 -222.939356)
		(width 0.09525)
		(layer "In6.Cu")
		(net "M_K_CPU0_SA_DQS_DP<0>")
	)
	(segment
		(start 438.204356 -200.010014)
		(end 437.864758 -200.349612)
		(width 0.16002)
		(layer "In6.Cu")
		(net "M_K_CPU0_SA_DQS_DP<0>")
	)
	(segment
		(start 443.771274 -201.208132)
		(end 443.147196 -200.584054)
		(width 0.16002)
		(layer "In6.Cu")
		(net "M_K_CPU0_SA_DQS_DP<0>")
	)
	(segment
		(start 436.625238 -201.200512)
		(end 436.223918 -201.200512)
		(width 0.16002)
		(layer "In6.Cu")
		(net "M_K_CPU0_SA_DQS_DP<0>")
	)
	(segment
		(start 423.116248 -200.010014)
		(end 422.77665 -200.349612)
		(width 0.16002)
		(layer "In6.Cu")
		(net "M_K_CPU0_SA_DQS_DP<0>")
	)
	(arc
		(start 392.99261 -223.424242)
		(mid 392.951153 -223.596282)
		(end 392.835892 -223.730566)
		(width 0.09525)
		(layer "In6.Cu")
		(net "M_K_CPU0_SA_DQS_DP<0>")
	)
	(arc
		(start 391.486136 -226.989386)
		(mid 391.204704 -226.913631)
		(end 390.923272 -226.989386)
		(width 0.09525)
		(layer "In6.Cu")
		(net "M_K_CPU0_SA_DQS_DP<0>")
	)
	(arc
		(start 392.76528 -223.77146)
		(mid 392.52243 -224.234248)
		(end 392.76528 -224.697036)
		(width 0.09525)
		(layer "In6.Cu")
		(net "M_K_CPU0_SA_DQS_DP<0>")
	)
	(arc
		(start 393.46251 -222.614236)
		(mid 393.421053 -222.786276)
		(end 393.305792 -222.92056)
		(width 0.09525)
		(layer "In6.Cu")
		(net "M_K_CPU0_SA_DQS_DP<0>")
	)
	(arc
		(start 392.835892 -224.73793)
		(mid 392.992624 -225.044254)
		(end 392.835892 -225.350578)
		(width 0.09525)
		(layer "In6.Cu")
		(net "M_K_CPU0_SA_DQS_DP<0>")
	)
	(arc
		(start 393.238228 -222.95993)
		(mid 393.057837 -223.161629)
		(end 392.99261 -223.424242)
		(width 0.09525)
		(layer "In6.Cu")
		(net "M_K_CPU0_SA_DQS_DP<0>")
	)
	(arc
		(start 392.522456 -225.85426)
		(mid 392.480791 -226.026707)
		(end 392.364976 -226.161092)
		(width 0.09525)
		(layer "In6.Cu")
		(net "M_K_CPU0_SA_DQS_DP<0>")
	)
	(arc
		(start 391.854944 -226.994212)
		(mid 391.669912 -227.040126)
		(end 391.486136 -226.989386)
		(width 0.09525)
		(layer "In6.Cu")
		(net "M_K_CPU0_SA_DQS_DP<0>")
	)
	(arc
		(start 392.052556 -226.664266)
		(mid 392.011099 -226.836306)
		(end 391.895838 -226.97059)
		(width 0.09525)
		(layer "In6.Cu")
		(net "M_K_CPU0_SA_DQS_DP<0>")
	)
	(arc
		(start 392.29538 -226.201478)
		(mid 392.11693 -226.402948)
		(end 392.052556 -226.664266)
		(width 0.09525)
		(layer "In6.Cu")
		(net "M_K_CPU0_SA_DQS_DP<0>")
	)
	(arc
		(start 390.923272 -226.989386)
		(mid 390.766645 -227.038572)
		(end 390.603994 -227.01631)
		(width 0.09525)
		(layer "In6.Cu")
		(net "M_K_CPU0_SA_DQS_DP<0>")
	)
	(arc
		(start 392.76528 -225.391472)
		(mid 392.58683 -225.592942)
		(end 392.522456 -225.85426)
		(width 0.09525)
		(layer "In6.Cu")
		(net "M_K_CPU0_SA_DQS_DP<0>")
	)
	(segment
		(start 388.857998 -247.1801)
		(end 389.32485 -246.914162)
		(width 0.12954)
		(layer "F.Cu")
		(net "M_K_CPU0_SA_DQS_DN<9>")
	)
	(segment
		(start 432.810158 -240.222532)
		(end 432.970178 -240.062512)
		(width 0.16002)
		(layer "In6.Cu")
		(net "M_K_CPU0_SA_DQS_DN<9>")
	)
	(segment
		(start 417.451794 -240.204752)
		(end 417.611814 -240.044732)
		(width 0.16002)
		(layer "In6.Cu")
		(net "M_K_CPU0_SA_DQS_DN<9>")
	)
	(segment
		(start 419.440614 -240.258092)
		(end 420.504366 -240.258092)
		(width 0.16002)
		(layer "In6.Cu")
		(net "M_K_CPU0_SA_DQS_DN<9>")
	)
	(segment
		(start 441.404248 -239.131856)
		(end 441.531248 -239.258856)
		(width 0.16002)
		(layer "In6.Cu")
		(net "M_K_CPU0_SA_DQS_DN<9>")
	)
	(segment
		(start 413.944816 -239.878108)
		(end 414.732216 -239.090708)
		(width 0.16002)
		(layer "In6.Cu")
		(net "M_K_CPU0_SA_DQS_DN<9>")
	)
	(segment
		(start 429.820324 -239.090708)
		(end 430.879504 -239.090708)
		(width 0.16002)
		(layer "In6.Cu")
		(net "M_K_CPU0_SA_DQS_DN<9>")
	)
	(segment
		(start 439.922412 -239.407954)
		(end 440.07151 -239.258856)
		(width 0.16002)
		(layer "In6.Cu")
		(net "M_K_CPU0_SA_DQS_DN<9>")
	)
	(segment
		(start 396.513558 -246.844312)
		(end 405.240236 -246.844312)
		(width 0.16002)
		(layer "In6.Cu")
		(net "M_K_CPU0_SA_DQS_DN<9>")
	)
	(segment
		(start 442.270388 -239.258856)
		(end 442.5442 -238.985044)
		(width 0.16002)
		(layer "In6.Cu")
		(net "M_K_CPU0_SA_DQS_DN<9>")
	)
	(segment
		(start 389.32485 -246.914162)
		(end 389.170926 -247.179592)
		(width 0.09525)
		(layer "In6.Cu")
		(net "M_K_CPU0_SA_DQS_DN<9>")
	)
	(segment
		(start 390.44499 -247.244108)
		(end 390.453372 -247.239282)
		(width 0.09525)
		(layer "In6.Cu")
		(net "M_K_CPU0_SA_DQS_DN<9>")
	)
	(segment
		(start 392.332718 -247.239282)
		(end 392.343132 -247.233186)
		(width 0.09525)
		(layer "In6.Cu")
		(net "M_K_CPU0_SA_DQS_DN<9>")
	)
	(segment
		(start 394.061696 -247.438926)
		(end 395.603222 -247.438926)
		(width 0.09525)
		(layer "In6.Cu")
		(net "M_K_CPU0_SA_DQS_DN<9>")
	)
	(segment
		(start 424.717718 -240.067592)
		(end 424.877738 -240.227612)
		(width 0.16002)
		(layer "In6.Cu")
		(net "M_K_CPU0_SA_DQS_DN<9>")
	)
	(segment
		(start 422.27627 -239.090708)
		(end 423.33545 -239.090708)
		(width 0.16002)
		(layer "In6.Cu")
		(net "M_K_CPU0_SA_DQS_DN<9>")
	)
	(segment
		(start 395.603222 -247.438926)
		(end 395.662404 -247.379744)
		(width 0.09525)
		(layer "In6.Cu")
		(net "M_K_CPU0_SA_DQS_DN<9>")
	)
	(segment
		(start 438.740804 -239.407954)
		(end 439.922412 -239.407954)
		(width 0.16002)
		(layer "In6.Cu")
		(net "M_K_CPU0_SA_DQS_DN<9>")
	)
	(segment
		(start 432.970178 -239.745012)
		(end 433.307236 -239.407954)
		(width 0.16002)
		(layer "In6.Cu")
		(net "M_K_CPU0_SA_DQS_DN<9>")
	)
	(segment
		(start 395.686026 -247.379744)
		(end 395.978126 -247.379744)
		(width 0.16002)
		(layer "In6.Cu")
		(net "M_K_CPU0_SA_DQS_DN<9>")
	)
	(segment
		(start 415.791396 -239.090708)
		(end 416.108642 -239.407954)
		(width 0.16002)
		(layer "In6.Cu")
		(net "M_K_CPU0_SA_DQS_DN<9>")
	)
	(segment
		(start 432.461924 -240.222532)
		(end 432.810158 -240.222532)
		(width 0.16002)
		(layer "In6.Cu")
		(net "M_K_CPU0_SA_DQS_DN<9>")
	)
	(segment
		(start 431.964846 -239.407954)
		(end 432.301904 -239.745012)
		(width 0.16002)
		(layer "In6.Cu")
		(net "M_K_CPU0_SA_DQS_DN<9>")
	)
	(segment
		(start 435.972458 -239.878108)
		(end 436.576978 -239.878108)
		(width 0.16002)
		(layer "In6.Cu")
		(net "M_K_CPU0_SA_DQS_DN<9>")
	)
	(segment
		(start 416.94354 -240.044732)
		(end 417.10356 -240.204752)
		(width 0.16002)
		(layer "In6.Cu")
		(net "M_K_CPU0_SA_DQS_DN<9>")
	)
	(segment
		(start 424.877738 -240.227612)
		(end 425.225972 -240.227612)
		(width 0.16002)
		(layer "In6.Cu")
		(net "M_K_CPU0_SA_DQS_DN<9>")
	)
	(segment
		(start 440.924188 -239.131856)
		(end 441.404248 -239.131856)
		(width 0.16002)
		(layer "In6.Cu")
		(net "M_K_CPU0_SA_DQS_DN<9>")
	)
	(segment
		(start 416.606482 -239.407954)
		(end 416.94354 -239.745012)
		(width 0.16002)
		(layer "In6.Cu")
		(net "M_K_CPU0_SA_DQS_DN<9>")
	)
	(segment
		(start 416.94354 -239.745012)
		(end 416.94354 -240.044732)
		(width 0.16002)
		(layer "In6.Cu")
		(net "M_K_CPU0_SA_DQS_DN<9>")
	)
	(segment
		(start 393.273026 -247.239282)
		(end 393.287758 -247.230646)
		(width 0.09525)
		(layer "In6.Cu")
		(net "M_K_CPU0_SA_DQS_DN<9>")
	)
	(segment
		(start 440.07151 -239.258856)
		(end 440.797188 -239.258856)
		(width 0.16002)
		(layer "In6.Cu")
		(net "M_K_CPU0_SA_DQS_DN<9>")
	)
	(segment
		(start 417.611814 -239.745012)
		(end 417.948872 -239.407954)
		(width 0.16002)
		(layer "In6.Cu")
		(net "M_K_CPU0_SA_DQS_DN<9>")
	)
	(segment
		(start 428.428404 -239.878108)
		(end 429.032924 -239.878108)
		(width 0.16002)
		(layer "In6.Cu")
		(net "M_K_CPU0_SA_DQS_DN<9>")
	)
	(segment
		(start 426.408342 -239.407954)
		(end 427.25848 -240.258092)
		(width 0.16002)
		(layer "In6.Cu")
		(net "M_K_CPU0_SA_DQS_DN<9>")
	)
	(segment
		(start 432.301904 -239.745012)
		(end 432.301904 -240.062512)
		(width 0.16002)
		(layer "In6.Cu")
		(net "M_K_CPU0_SA_DQS_DN<9>")
	)
	(segment
		(start 425.72305 -239.407954)
		(end 426.408342 -239.407954)
		(width 0.16002)
		(layer "In6.Cu")
		(net "M_K_CPU0_SA_DQS_DN<9>")
	)
	(segment
		(start 423.652696 -239.407954)
		(end 424.38066 -239.407954)
		(width 0.16002)
		(layer "In6.Cu")
		(net "M_K_CPU0_SA_DQS_DN<9>")
	)
	(segment
		(start 423.33545 -239.090708)
		(end 423.652696 -239.407954)
		(width 0.16002)
		(layer "In6.Cu")
		(net "M_K_CPU0_SA_DQS_DN<9>")
	)
	(segment
		(start 417.948872 -239.407954)
		(end 418.590476 -239.407954)
		(width 0.16002)
		(layer "In6.Cu")
		(net "M_K_CPU0_SA_DQS_DN<9>")
	)
	(segment
		(start 395.978126 -247.379744)
		(end 396.513558 -246.844312)
		(width 0.16002)
		(layer "In6.Cu")
		(net "M_K_CPU0_SA_DQS_DN<9>")
	)
	(segment
		(start 414.732216 -239.090708)
		(end 415.791396 -239.090708)
		(width 0.16002)
		(layer "In6.Cu")
		(net "M_K_CPU0_SA_DQS_DN<9>")
	)
	(segment
		(start 425.385992 -239.745012)
		(end 425.72305 -239.407954)
		(width 0.16002)
		(layer "In6.Cu")
		(net "M_K_CPU0_SA_DQS_DN<9>")
	)
	(segment
		(start 431.19675 -239.407954)
		(end 431.964846 -239.407954)
		(width 0.16002)
		(layer "In6.Cu")
		(net "M_K_CPU0_SA_DQS_DN<9>")
	)
	(segment
		(start 405.240236 -246.844312)
		(end 412.20644 -239.878108)
		(width 0.16002)
		(layer "In6.Cu")
		(net "M_K_CPU0_SA_DQS_DN<9>")
	)
	(segment
		(start 429.032924 -239.878108)
		(end 429.820324 -239.090708)
		(width 0.16002)
		(layer "In6.Cu")
		(net "M_K_CPU0_SA_DQS_DN<9>")
	)
	(segment
		(start 437.364378 -239.090708)
		(end 438.423558 -239.090708)
		(width 0.16002)
		(layer "In6.Cu")
		(net "M_K_CPU0_SA_DQS_DN<9>")
	)
	(segment
		(start 425.385992 -240.067592)
		(end 425.385992 -239.745012)
		(width 0.16002)
		(layer "In6.Cu")
		(net "M_K_CPU0_SA_DQS_DN<9>")
	)
	(segment
		(start 395.662404 -247.379744)
		(end 395.686026 -247.379744)
		(width 0.09525)
		(layer "In6.Cu")
		(net "M_K_CPU0_SA_DQS_DN<9>")
	)
	(segment
		(start 424.717718 -239.745012)
		(end 424.717718 -240.067592)
		(width 0.16002)
		(layer "In6.Cu")
		(net "M_K_CPU0_SA_DQS_DN<9>")
	)
	(segment
		(start 428.04842 -240.258092)
		(end 428.428404 -239.878108)
		(width 0.16002)
		(layer "In6.Cu")
		(net "M_K_CPU0_SA_DQS_DN<9>")
	)
	(segment
		(start 435.592474 -240.258092)
		(end 435.972458 -239.878108)
		(width 0.16002)
		(layer "In6.Cu")
		(net "M_K_CPU0_SA_DQS_DN<9>")
	)
	(segment
		(start 391.956036 -247.239282)
		(end 391.964418 -247.244108)
		(width 0.09525)
		(layer "In6.Cu")
		(net "M_K_CPU0_SA_DQS_DN<9>")
	)
	(segment
		(start 434.812186 -240.258092)
		(end 435.592474 -240.258092)
		(width 0.16002)
		(layer "In6.Cu")
		(net "M_K_CPU0_SA_DQS_DN<9>")
	)
	(segment
		(start 417.10356 -240.204752)
		(end 417.451794 -240.204752)
		(width 0.16002)
		(layer "In6.Cu")
		(net "M_K_CPU0_SA_DQS_DN<9>")
	)
	(segment
		(start 432.970178 -240.062512)
		(end 432.970178 -239.745012)
		(width 0.16002)
		(layer "In6.Cu")
		(net "M_K_CPU0_SA_DQS_DN<9>")
	)
	(segment
		(start 438.423558 -239.090708)
		(end 438.740804 -239.407954)
		(width 0.16002)
		(layer "In6.Cu")
		(net "M_K_CPU0_SA_DQS_DN<9>")
	)
	(segment
		(start 432.301904 -240.062512)
		(end 432.461924 -240.222532)
		(width 0.16002)
		(layer "In6.Cu")
		(net "M_K_CPU0_SA_DQS_DN<9>")
	)
	(segment
		(start 424.38066 -239.407954)
		(end 424.717718 -239.745012)
		(width 0.16002)
		(layer "In6.Cu")
		(net "M_K_CPU0_SA_DQS_DN<9>")
	)
	(segment
		(start 430.879504 -239.090708)
		(end 431.19675 -239.407954)
		(width 0.16002)
		(layer "In6.Cu")
		(net "M_K_CPU0_SA_DQS_DN<9>")
	)
	(segment
		(start 391.016236 -247.239282)
		(end 391.024618 -247.244108)
		(width 0.09525)
		(layer "In6.Cu")
		(net "M_K_CPU0_SA_DQS_DN<9>")
	)
	(segment
		(start 393.950444 -247.327674)
		(end 394.061696 -247.438926)
		(width 0.09525)
		(layer "In6.Cu")
		(net "M_K_CPU0_SA_DQS_DN<9>")
	)
	(segment
		(start 416.108642 -239.407954)
		(end 416.606482 -239.407954)
		(width 0.16002)
		(layer "In6.Cu")
		(net "M_K_CPU0_SA_DQS_DN<9>")
	)
	(segment
		(start 389.170926 -247.179592)
		(end 389.19404 -247.266206)
		(width 0.09525)
		(layer "In6.Cu")
		(net "M_K_CPU0_SA_DQS_DN<9>")
	)
	(segment
		(start 393.258548 -247.247664)
		(end 393.273026 -247.239282)
		(width 0.09525)
		(layer "In6.Cu")
		(net "M_K_CPU0_SA_DQS_DN<9>")
	)
	(segment
		(start 420.504366 -240.258092)
		(end 420.88435 -239.878108)
		(width 0.16002)
		(layer "In6.Cu")
		(net "M_K_CPU0_SA_DQS_DN<9>")
	)
	(segment
		(start 433.307236 -239.407954)
		(end 433.962048 -239.407954)
		(width 0.16002)
		(layer "In6.Cu")
		(net "M_K_CPU0_SA_DQS_DN<9>")
	)
	(segment
		(start 420.88435 -239.878108)
		(end 421.48887 -239.878108)
		(width 0.16002)
		(layer "In6.Cu")
		(net "M_K_CPU0_SA_DQS_DN<9>")
	)
	(segment
		(start 433.962048 -239.407954)
		(end 434.812186 -240.258092)
		(width 0.16002)
		(layer "In6.Cu")
		(net "M_K_CPU0_SA_DQS_DN<9>")
	)
	(segment
		(start 417.611814 -240.044732)
		(end 417.611814 -239.745012)
		(width 0.16002)
		(layer "In6.Cu")
		(net "M_K_CPU0_SA_DQS_DN<9>")
	)
	(segment
		(start 391.945622 -247.233186)
		(end 391.956036 -247.239282)
		(width 0.09525)
		(layer "In6.Cu")
		(net "M_K_CPU0_SA_DQS_DN<9>")
	)
	(segment
		(start 418.590476 -239.407954)
		(end 419.440614 -240.258092)
		(width 0.16002)
		(layer "In6.Cu")
		(net "M_K_CPU0_SA_DQS_DN<9>")
	)
	(segment
		(start 425.225972 -240.227612)
		(end 425.385992 -240.067592)
		(width 0.16002)
		(layer "In6.Cu")
		(net "M_K_CPU0_SA_DQS_DN<9>")
	)
	(segment
		(start 436.576978 -239.878108)
		(end 437.364378 -239.090708)
		(width 0.16002)
		(layer "In6.Cu")
		(net "M_K_CPU0_SA_DQS_DN<9>")
	)
	(segment
		(start 412.20644 -239.878108)
		(end 413.944816 -239.878108)
		(width 0.16002)
		(layer "In6.Cu")
		(net "M_K_CPU0_SA_DQS_DN<9>")
	)
	(segment
		(start 427.25848 -240.258092)
		(end 428.04842 -240.258092)
		(width 0.16002)
		(layer "In6.Cu")
		(net "M_K_CPU0_SA_DQS_DN<9>")
	)
	(segment
		(start 441.531248 -239.258856)
		(end 442.270388 -239.258856)
		(width 0.16002)
		(layer "In6.Cu")
		(net "M_K_CPU0_SA_DQS_DN<9>")
	)
	(segment
		(start 440.797188 -239.258856)
		(end 440.924188 -239.131856)
		(width 0.16002)
		(layer "In6.Cu")
		(net "M_K_CPU0_SA_DQS_DN<9>")
	)
	(segment
		(start 421.48887 -239.878108)
		(end 422.27627 -239.090708)
		(width 0.16002)
		(layer "In6.Cu")
		(net "M_K_CPU0_SA_DQS_DN<9>")
	)
	(arc
		(start 391.964418 -247.244108)
		(mid 392.149196 -247.289901)
		(end 392.332718 -247.239282)
		(width 0.09525)
		(layer "In6.Cu")
		(net "M_K_CPU0_SA_DQS_DN<9>")
	)
	(arc
		(start 389.19404 -247.266206)
		(mid 389.356691 -247.288466)
		(end 389.513318 -247.239282)
		(width 0.09525)
		(layer "In6.Cu")
		(net "M_K_CPU0_SA_DQS_DN<9>")
	)
	(arc
		(start 392.343132 -247.233186)
		(mid 392.620294 -247.163386)
		(end 392.895836 -247.239282)
		(width 0.09525)
		(layer "In6.Cu")
		(net "M_K_CPU0_SA_DQS_DN<9>")
	)
	(arc
		(start 391.024618 -247.244108)
		(mid 391.20965 -247.290022)
		(end 391.393426 -247.239282)
		(width 0.09525)
		(layer "In6.Cu")
		(net "M_K_CPU0_SA_DQS_DN<9>")
	)
	(arc
		(start 389.513318 -247.239282)
		(mid 389.79475 -247.163527)
		(end 390.076182 -247.239282)
		(width 0.09525)
		(layer "In6.Cu")
		(net "M_K_CPU0_SA_DQS_DN<9>")
	)
	(arc
		(start 390.453372 -247.239282)
		(mid 390.734804 -247.163527)
		(end 391.016236 -247.239282)
		(width 0.09525)
		(layer "In6.Cu")
		(net "M_K_CPU0_SA_DQS_DN<9>")
	)
	(arc
		(start 393.835382 -247.239282)
		(mid 393.895786 -247.279738)
		(end 393.950444 -247.327674)
		(width 0.09525)
		(layer "In6.Cu")
		(net "M_K_CPU0_SA_DQS_DN<9>")
	)
	(arc
		(start 390.076182 -247.239282)
		(mid 390.259957 -247.290054)
		(end 390.44499 -247.244108)
		(width 0.09525)
		(layer "In6.Cu")
		(net "M_K_CPU0_SA_DQS_DN<9>")
	)
	(arc
		(start 392.895836 -247.239282)
		(mid 393.076115 -247.290113)
		(end 393.258548 -247.247664)
		(width 0.09525)
		(layer "In6.Cu")
		(net "M_K_CPU0_SA_DQS_DN<9>")
	)
	(arc
		(start 391.393426 -247.239282)
		(mid 391.668715 -247.163561)
		(end 391.945622 -247.233186)
		(width 0.09525)
		(layer "In6.Cu")
		(net "M_K_CPU0_SA_DQS_DN<9>")
	)
	(arc
		(start 393.287758 -247.230646)
		(mid 393.562709 -247.163503)
		(end 393.835382 -247.239282)
		(width 0.09525)
		(layer "In6.Cu")
		(net "M_K_CPU0_SA_DQS_DN<9>")
	)
	(segment
		(start 388.857998 -242.320064)
		(end 389.32485 -242.054126)
		(width 0.12954)
		(layer "F.Cu")
		(net "M_K_CPU0_SA_DQS_DN<8>")
	)
	(segment
		(start 408.034998 -233.811318)
		(end 408.034998 -235.81741)
		(width 0.16002)
		(layer "In6.Cu")
		(net "M_K_CPU0_SA_DQS_DN<8>")
	)
	(segment
		(start 395.859254 -241.2111)
		(end 395.835632 -241.2111)
		(width 0.09525)
		(layer "In6.Cu")
		(net "M_K_CPU0_SA_DQS_DN<8>")
	)
	(segment
		(start 441.566808 -229.908862)
		(end 441.439808 -229.781862)
		(width 0.16002)
		(layer "In6.Cu")
		(net "M_K_CPU0_SA_DQS_DN<8>")
	)
	(segment
		(start 411.318202 -230.528114)
		(end 410.819346 -231.02697)
		(width 0.16002)
		(layer "In6.Cu")
		(net "M_K_CPU0_SA_DQS_DN<8>")
	)
	(segment
		(start 439.922412 -230.05796)
		(end 438.740804 -230.05796)
		(width 0.16002)
		(layer "In6.Cu")
		(net "M_K_CPU0_SA_DQS_DN<8>")
	)
	(segment
		(start 437.364378 -229.740714)
		(end 436.576978 -230.528114)
		(width 0.16002)
		(layer "In6.Cu")
		(net "M_K_CPU0_SA_DQS_DN<8>")
	)
	(segment
		(start 389.170926 -242.319556)
		(end 389.32485 -242.054126)
		(width 0.09525)
		(layer "In6.Cu")
		(net "M_K_CPU0_SA_DQS_DN<8>")
	)
	(segment
		(start 413.944816 -230.528114)
		(end 411.318202 -230.528114)
		(width 0.16002)
		(layer "In6.Cu")
		(net "M_K_CPU0_SA_DQS_DN<8>")
	)
	(segment
		(start 418.21354 -230.242872)
		(end 418.21354 -230.03637)
		(width 0.16002)
		(layer "In6.Cu")
		(net "M_K_CPU0_SA_DQS_DN<8>")
	)
	(segment
		(start 417.876482 -229.699312)
		(end 417.277804 -229.699312)
		(width 0.16002)
		(layer "In6.Cu")
		(net "M_K_CPU0_SA_DQS_DN<8>")
	)
	(segment
		(start 419.440614 -230.908098)
		(end 418.935408 -230.402892)
		(width 0.16002)
		(layer "In6.Cu")
		(net "M_K_CPU0_SA_DQS_DN<8>")
	)
	(segment
		(start 392.343132 -242.37315)
		(end 392.338052 -242.376198)
		(width 0.09525)
		(layer "In6.Cu")
		(net "M_K_CPU0_SA_DQS_DN<8>")
	)
	(segment
		(start 409.546298 -232.97769)
		(end 409.546298 -233.20375)
		(width 0.16002)
		(layer "In6.Cu")
		(net "M_K_CPU0_SA_DQS_DN<8>")
	)
	(segment
		(start 430.782984 -229.644194)
		(end 429.916844 -229.644194)
		(width 0.16002)
		(layer "In6.Cu")
		(net "M_K_CPU0_SA_DQS_DN<8>")
	)
	(segment
		(start 442.270388 -229.908862)
		(end 441.566808 -229.908862)
		(width 0.16002)
		(layer "In6.Cu")
		(net "M_K_CPU0_SA_DQS_DN<8>")
	)
	(segment
		(start 433.678584 -230.05796)
		(end 431.19675 -230.05796)
		(width 0.16002)
		(layer "In6.Cu")
		(net "M_K_CPU0_SA_DQS_DN<8>")
	)
	(segment
		(start 393.548362 -242.430554)
		(end 393.084812 -242.430554)
		(width 0.09525)
		(layer "In6.Cu")
		(net "M_K_CPU0_SA_DQS_DN<8>")
	)
	(segment
		(start 429.916844 -229.644194)
		(end 429.032924 -230.528114)
		(width 0.16002)
		(layer "In6.Cu")
		(net "M_K_CPU0_SA_DQS_DN<8>")
	)
	(segment
		(start 410.446474 -232.077514)
		(end 410.34589 -231.97693)
		(width 0.16002)
		(layer "In6.Cu")
		(net "M_K_CPU0_SA_DQS_DN<8>")
	)
	(segment
		(start 391.964418 -242.384072)
		(end 391.956036 -242.379246)
		(width 0.09525)
		(layer "In6.Cu")
		(net "M_K_CPU0_SA_DQS_DN<8>")
	)
	(segment
		(start 416.780726 -230.402892)
		(end 416.453574 -230.402892)
		(width 0.16002)
		(layer "In6.Cu")
		(net "M_K_CPU0_SA_DQS_DN<8>")
	)
	(segment
		(start 417.277804 -229.699312)
		(end 416.940746 -230.03637)
		(width 0.16002)
		(layer "In6.Cu")
		(net "M_K_CPU0_SA_DQS_DN<8>")
	)
	(segment
		(start 441.439808 -229.781862)
		(end 440.959748 -229.781862)
		(width 0.16002)
		(layer "In6.Cu")
		(net "M_K_CPU0_SA_DQS_DN<8>")
	)
	(segment
		(start 418.37356 -230.402892)
		(end 418.21354 -230.242872)
		(width 0.16002)
		(layer "In6.Cu")
		(net "M_K_CPU0_SA_DQS_DN<8>")
	)
	(segment
		(start 435.972458 -230.528114)
		(end 435.592474 -230.908098)
		(width 0.16002)
		(layer "In6.Cu")
		(net "M_K_CPU0_SA_DQS_DN<8>")
	)
	(segment
		(start 409.445714 -232.877106)
		(end 409.546298 -232.97769)
		(width 0.16002)
		(layer "In6.Cu")
		(net "M_K_CPU0_SA_DQS_DN<8>")
	)
	(segment
		(start 394.758672 -241.95405)
		(end 394.024866 -241.95405)
		(width 0.09525)
		(layer "In6.Cu")
		(net "M_K_CPU0_SA_DQS_DN<8>")
	)
	(segment
		(start 429.032924 -230.528114)
		(end 428.428404 -230.528114)
		(width 0.16002)
		(layer "In6.Cu")
		(net "M_K_CPU0_SA_DQS_DN<8>")
	)
	(segment
		(start 395.835632 -241.2111)
		(end 395.77645 -241.270282)
		(width 0.09525)
		(layer "In6.Cu")
		(net "M_K_CPU0_SA_DQS_DN<8>")
	)
	(segment
		(start 409.869386 -231.97693)
		(end 409.445714 -232.400602)
		(width 0.16002)
		(layer "In6.Cu")
		(net "M_K_CPU0_SA_DQS_DN<8>")
	)
	(segment
		(start 418.21354 -230.03637)
		(end 417.876482 -229.699312)
		(width 0.16002)
		(layer "In6.Cu")
		(net "M_K_CPU0_SA_DQS_DN<8>")
	)
	(segment
		(start 390.453372 -242.379246)
		(end 390.44499 -242.384072)
		(width 0.09525)
		(layer "In6.Cu")
		(net "M_K_CPU0_SA_DQS_DN<8>")
	)
	(segment
		(start 426.984668 -230.908098)
		(end 426.13453 -230.05796)
		(width 0.16002)
		(layer "In6.Cu")
		(net "M_K_CPU0_SA_DQS_DN<8>")
	)
	(segment
		(start 395.77645 -241.270282)
		(end 395.44244 -241.270282)
		(width 0.09525)
		(layer "In6.Cu")
		(net "M_K_CPU0_SA_DQS_DN<8>")
	)
	(segment
		(start 416.940746 -230.242872)
		(end 416.780726 -230.402892)
		(width 0.16002)
		(layer "In6.Cu")
		(net "M_K_CPU0_SA_DQS_DN<8>")
	)
	(segment
		(start 431.19675 -230.05796)
		(end 430.782984 -229.644194)
		(width 0.16002)
		(layer "In6.Cu")
		(net "M_K_CPU0_SA_DQS_DN<8>")
	)
	(segment
		(start 410.819346 -231.503474)
		(end 410.91993 -231.604058)
		(width 0.16002)
		(layer "In6.Cu")
		(net "M_K_CPU0_SA_DQS_DN<8>")
	)
	(segment
		(start 442.5442 -229.63505)
		(end 442.270388 -229.908862)
		(width 0.16002)
		(layer "In6.Cu")
		(net "M_K_CPU0_SA_DQS_DN<8>")
	)
	(segment
		(start 423.33545 -229.740714)
		(end 422.27627 -229.740714)
		(width 0.16002)
		(layer "In6.Cu")
		(net "M_K_CPU0_SA_DQS_DN<8>")
	)
	(segment
		(start 410.34589 -231.97693)
		(end 409.869386 -231.97693)
		(width 0.16002)
		(layer "In6.Cu")
		(net "M_K_CPU0_SA_DQS_DN<8>")
	)
	(segment
		(start 394.024866 -241.95405)
		(end 393.548362 -242.430554)
		(width 0.09525)
		(layer "In6.Cu")
		(net "M_K_CPU0_SA_DQS_DN<8>")
	)
	(segment
		(start 402.641308 -241.2111)
		(end 395.859254 -241.2111)
		(width 0.16002)
		(layer "In6.Cu")
		(net "M_K_CPU0_SA_DQS_DN<8>")
	)
	(segment
		(start 409.546298 -233.20375)
		(end 409.298902 -233.451146)
		(width 0.16002)
		(layer "In6.Cu")
		(net "M_K_CPU0_SA_DQS_DN<8>")
	)
	(segment
		(start 426.13453 -230.05796)
		(end 423.652696 -230.05796)
		(width 0.16002)
		(layer "In6.Cu")
		(net "M_K_CPU0_SA_DQS_DN<8>")
	)
	(segment
		(start 422.27627 -229.740714)
		(end 421.48887 -230.528114)
		(width 0.16002)
		(layer "In6.Cu")
		(net "M_K_CPU0_SA_DQS_DN<8>")
	)
	(segment
		(start 389.19404 -242.40617)
		(end 389.170926 -242.319556)
		(width 0.09525)
		(layer "In6.Cu")
		(net "M_K_CPU0_SA_DQS_DN<8>")
	)
	(segment
		(start 420.504366 -230.908098)
		(end 419.440614 -230.908098)
		(width 0.16002)
		(layer "In6.Cu")
		(net "M_K_CPU0_SA_DQS_DN<8>")
	)
	(segment
		(start 409.072842 -233.451146)
		(end 408.972258 -233.350562)
		(width 0.16002)
		(layer "In6.Cu")
		(net "M_K_CPU0_SA_DQS_DN<8>")
	)
	(segment
		(start 415.791396 -229.740714)
		(end 414.732216 -229.740714)
		(width 0.16002)
		(layer "In6.Cu")
		(net "M_K_CPU0_SA_DQS_DN<8>")
	)
	(segment
		(start 392.338052 -242.376198)
		(end 392.332718 -242.379246)
		(width 0.09525)
		(layer "In6.Cu")
		(net "M_K_CPU0_SA_DQS_DN<8>")
	)
	(segment
		(start 395.44244 -241.270282)
		(end 394.758672 -241.95405)
		(width 0.09525)
		(layer "In6.Cu")
		(net "M_K_CPU0_SA_DQS_DN<8>")
	)
	(segment
		(start 428.04842 -230.908098)
		(end 426.984668 -230.908098)
		(width 0.16002)
		(layer "In6.Cu")
		(net "M_K_CPU0_SA_DQS_DN<8>")
	)
	(segment
		(start 391.024618 -242.384072)
		(end 391.016236 -242.379246)
		(width 0.09525)
		(layer "In6.Cu")
		(net "M_K_CPU0_SA_DQS_DN<8>")
	)
	(segment
		(start 438.423558 -229.740714)
		(end 437.364378 -229.740714)
		(width 0.16002)
		(layer "In6.Cu")
		(net "M_K_CPU0_SA_DQS_DN<8>")
	)
	(segment
		(start 391.956036 -242.379246)
		(end 391.945622 -242.37315)
		(width 0.09525)
		(layer "In6.Cu")
		(net "M_K_CPU0_SA_DQS_DN<8>")
	)
	(segment
		(start 438.740804 -230.05796)
		(end 438.423558 -229.740714)
		(width 0.16002)
		(layer "In6.Cu")
		(net "M_K_CPU0_SA_DQS_DN<8>")
	)
	(segment
		(start 420.88435 -230.528114)
		(end 420.504366 -230.908098)
		(width 0.16002)
		(layer "In6.Cu")
		(net "M_K_CPU0_SA_DQS_DN<8>")
	)
	(segment
		(start 409.298902 -233.451146)
		(end 409.072842 -233.451146)
		(width 0.16002)
		(layer "In6.Cu")
		(net "M_K_CPU0_SA_DQS_DN<8>")
	)
	(segment
		(start 408.495754 -233.350562)
		(end 408.034998 -233.811318)
		(width 0.16002)
		(layer "In6.Cu")
		(net "M_K_CPU0_SA_DQS_DN<8>")
	)
	(segment
		(start 409.445714 -232.400602)
		(end 409.445714 -232.877106)
		(width 0.16002)
		(layer "In6.Cu")
		(net "M_K_CPU0_SA_DQS_DN<8>")
	)
	(segment
		(start 418.935408 -230.402892)
		(end 418.37356 -230.402892)
		(width 0.16002)
		(layer "In6.Cu")
		(net "M_K_CPU0_SA_DQS_DN<8>")
	)
	(segment
		(start 408.972258 -233.350562)
		(end 408.495754 -233.350562)
		(width 0.16002)
		(layer "In6.Cu")
		(net "M_K_CPU0_SA_DQS_DN<8>")
	)
	(segment
		(start 410.672534 -232.077514)
		(end 410.446474 -232.077514)
		(width 0.16002)
		(layer "In6.Cu")
		(net "M_K_CPU0_SA_DQS_DN<8>")
	)
	(segment
		(start 421.48887 -230.528114)
		(end 420.88435 -230.528114)
		(width 0.16002)
		(layer "In6.Cu")
		(net "M_K_CPU0_SA_DQS_DN<8>")
	)
	(segment
		(start 436.576978 -230.528114)
		(end 435.972458 -230.528114)
		(width 0.16002)
		(layer "In6.Cu")
		(net "M_K_CPU0_SA_DQS_DN<8>")
	)
	(segment
		(start 428.428404 -230.528114)
		(end 428.04842 -230.908098)
		(width 0.16002)
		(layer "In6.Cu")
		(net "M_K_CPU0_SA_DQS_DN<8>")
	)
	(segment
		(start 408.034998 -235.81741)
		(end 402.641308 -241.2111)
		(width 0.16002)
		(layer "In6.Cu")
		(net "M_K_CPU0_SA_DQS_DN<8>")
	)
	(segment
		(start 440.07151 -229.908862)
		(end 439.922412 -230.05796)
		(width 0.16002)
		(layer "In6.Cu")
		(net "M_K_CPU0_SA_DQS_DN<8>")
	)
	(segment
		(start 410.819346 -231.02697)
		(end 410.819346 -231.503474)
		(width 0.16002)
		(layer "In6.Cu")
		(net "M_K_CPU0_SA_DQS_DN<8>")
	)
	(segment
		(start 414.732216 -229.740714)
		(end 413.944816 -230.528114)
		(width 0.16002)
		(layer "In6.Cu")
		(net "M_K_CPU0_SA_DQS_DN<8>")
	)
	(segment
		(start 416.940746 -230.03637)
		(end 416.940746 -230.242872)
		(width 0.16002)
		(layer "In6.Cu")
		(net "M_K_CPU0_SA_DQS_DN<8>")
	)
	(segment
		(start 440.832748 -229.908862)
		(end 440.07151 -229.908862)
		(width 0.16002)
		(layer "In6.Cu")
		(net "M_K_CPU0_SA_DQS_DN<8>")
	)
	(segment
		(start 434.528722 -230.908098)
		(end 433.678584 -230.05796)
		(width 0.16002)
		(layer "In6.Cu")
		(net "M_K_CPU0_SA_DQS_DN<8>")
	)
	(segment
		(start 423.652696 -230.05796)
		(end 423.33545 -229.740714)
		(width 0.16002)
		(layer "In6.Cu")
		(net "M_K_CPU0_SA_DQS_DN<8>")
	)
	(segment
		(start 440.959748 -229.781862)
		(end 440.832748 -229.908862)
		(width 0.16002)
		(layer "In6.Cu")
		(net "M_K_CPU0_SA_DQS_DN<8>")
	)
	(segment
		(start 435.592474 -230.908098)
		(end 434.528722 -230.908098)
		(width 0.16002)
		(layer "In6.Cu")
		(net "M_K_CPU0_SA_DQS_DN<8>")
	)
	(segment
		(start 410.91993 -231.830118)
		(end 410.672534 -232.077514)
		(width 0.16002)
		(layer "In6.Cu")
		(net "M_K_CPU0_SA_DQS_DN<8>")
	)
	(segment
		(start 410.91993 -231.604058)
		(end 410.91993 -231.830118)
		(width 0.16002)
		(layer "In6.Cu")
		(net "M_K_CPU0_SA_DQS_DN<8>")
	)
	(segment
		(start 416.453574 -230.402892)
		(end 415.791396 -229.740714)
		(width 0.16002)
		(layer "In6.Cu")
		(net "M_K_CPU0_SA_DQS_DN<8>")
	)
	(arc
		(start 390.076182 -242.379246)
		(mid 389.79475 -242.303491)
		(end 389.513318 -242.379246)
		(width 0.09525)
		(layer "In6.Cu")
		(net "M_K_CPU0_SA_DQS_DN<8>")
	)
	(arc
		(start 391.016236 -242.379246)
		(mid 390.734804 -242.303491)
		(end 390.453372 -242.379246)
		(width 0.09525)
		(layer "In6.Cu")
		(net "M_K_CPU0_SA_DQS_DN<8>")
	)
	(arc
		(start 392.895836 -242.379246)
		(mid 392.620293 -242.303397)
		(end 392.343132 -242.37315)
		(width 0.09525)
		(layer "In6.Cu")
		(net "M_K_CPU0_SA_DQS_DN<8>")
	)
	(arc
		(start 390.44499 -242.384072)
		(mid 390.259958 -242.429986)
		(end 390.076182 -242.379246)
		(width 0.09525)
		(layer "In6.Cu")
		(net "M_K_CPU0_SA_DQS_DN<8>")
	)
	(arc
		(start 391.393426 -242.379246)
		(mid 391.209651 -242.430018)
		(end 391.024618 -242.384072)
		(width 0.09525)
		(layer "In6.Cu")
		(net "M_K_CPU0_SA_DQS_DN<8>")
	)
	(arc
		(start 391.945622 -242.37315)
		(mid 391.668714 -242.303473)
		(end 391.393426 -242.379246)
		(width 0.09525)
		(layer "In6.Cu")
		(net "M_K_CPU0_SA_DQS_DN<8>")
	)
	(arc
		(start 392.332718 -242.379246)
		(mid 392.149197 -242.42989)
		(end 391.964418 -242.384072)
		(width 0.09525)
		(layer "In6.Cu")
		(net "M_K_CPU0_SA_DQS_DN<8>")
	)
	(arc
		(start 389.513318 -242.379246)
		(mid 389.356691 -242.428432)
		(end 389.19404 -242.40617)
		(width 0.09525)
		(layer "In6.Cu")
		(net "M_K_CPU0_SA_DQS_DN<8>")
	)
	(arc
		(start 393.084812 -242.430554)
		(mid 392.986935 -242.417392)
		(end 392.895836 -242.379246)
		(width 0.09525)
		(layer "In6.Cu")
		(net "M_K_CPU0_SA_DQS_DN<8>")
	)
	(segment
		(start 388.857998 -237.460028)
		(end 389.32485 -237.19409)
		(width 0.12954)
		(layer "F.Cu")
		(net "M_K_CPU0_SA_DQS_DN<7>")
	)
	(segment
		(start 437.364378 -220.39072)
		(end 438.423558 -220.39072)
		(width 0.16002)
		(layer "In6.Cu")
		(net "M_K_CPU0_SA_DQS_DN<7>")
	)
	(segment
		(start 394.466826 -236.077506)
		(end 395.011148 -236.077506)
		(width 0.09525)
		(layer "In6.Cu")
		(net "M_K_CPU0_SA_DQS_DN<7>")
	)
	(segment
		(start 436.576978 -221.17812)
		(end 437.364378 -220.39072)
		(width 0.16002)
		(layer "In6.Cu")
		(net "M_K_CPU0_SA_DQS_DN<7>")
	)
	(segment
		(start 394.106146 -236.438186)
		(end 394.466826 -236.077506)
		(width 0.09525)
		(layer "In6.Cu")
		(net "M_K_CPU0_SA_DQS_DN<7>")
	)
	(segment
		(start 421.48887 -221.17812)
		(end 422.27627 -220.39072)
		(width 0.16002)
		(layer "In6.Cu")
		(net "M_K_CPU0_SA_DQS_DN<7>")
	)
	(segment
		(start 391.945622 -237.513114)
		(end 391.956036 -237.51921)
		(width 0.09525)
		(layer "In6.Cu")
		(net "M_K_CPU0_SA_DQS_DN<7>")
	)
	(segment
		(start 394.106146 -236.716062)
		(end 394.106146 -236.438186)
		(width 0.09525)
		(layer "In6.Cu")
		(net "M_K_CPU0_SA_DQS_DN<7>")
	)
	(segment
		(start 389.32485 -237.19409)
		(end 389.170926 -237.45952)
		(width 0.09525)
		(layer "In6.Cu")
		(net "M_K_CPU0_SA_DQS_DN<7>")
	)
	(segment
		(start 429.032924 -221.17812)
		(end 429.820324 -220.39072)
		(width 0.16002)
		(layer "In6.Cu")
		(net "M_K_CPU0_SA_DQS_DN<7>")
	)
	(segment
		(start 414.732216 -220.39072)
		(end 415.791396 -220.39072)
		(width 0.16002)
		(layer "In6.Cu")
		(net "M_K_CPU0_SA_DQS_DN<7>")
	)
	(segment
		(start 434.528468 -221.55785)
		(end 435.592728 -221.55785)
		(width 0.16002)
		(layer "In6.Cu")
		(net "M_K_CPU0_SA_DQS_DN<7>")
	)
	(segment
		(start 391.016236 -237.51921)
		(end 391.024618 -237.524036)
		(width 0.09525)
		(layer "In6.Cu")
		(net "M_K_CPU0_SA_DQS_DN<7>")
	)
	(segment
		(start 392.332718 -237.51921)
		(end 392.333226 -237.51921)
		(width 0.09525)
		(layer "In6.Cu")
		(net "M_K_CPU0_SA_DQS_DN<7>")
	)
	(segment
		(start 428.048674 -221.55785)
		(end 428.428404 -221.17812)
		(width 0.16002)
		(layer "In6.Cu")
		(net "M_K_CPU0_SA_DQS_DN<7>")
	)
	(segment
		(start 395.457172 -235.631482)
		(end 395.77645 -235.631482)
		(width 0.09525)
		(layer "In6.Cu")
		(net "M_K_CPU0_SA_DQS_DN<7>")
	)
	(segment
		(start 400.785584 -232.886504)
		(end 401.262088 -232.886504)
		(width 0.16002)
		(layer "In6.Cu")
		(net "M_K_CPU0_SA_DQS_DN<7>")
	)
	(segment
		(start 400.361912 -233.78668)
		(end 400.361912 -233.310176)
		(width 0.16002)
		(layer "In6.Cu")
		(net "M_K_CPU0_SA_DQS_DN<7>")
	)
	(segment
		(start 415.791396 -220.39072)
		(end 416.108642 -220.707966)
		(width 0.16002)
		(layer "In6.Cu")
		(net "M_K_CPU0_SA_DQS_DN<7>")
	)
	(segment
		(start 440.07151 -220.558868)
		(end 440.787028 -220.558868)
		(width 0.16002)
		(layer "In6.Cu")
		(net "M_K_CPU0_SA_DQS_DN<7>")
	)
	(segment
		(start 402.141182 -233.044746)
		(end 402.141182 -232.818686)
		(width 0.16002)
		(layer "In6.Cu")
		(net "M_K_CPU0_SA_DQS_DN<7>")
	)
	(segment
		(start 423.652696 -220.707966)
		(end 426.13453 -220.707966)
		(width 0.16002)
		(layer "In6.Cu")
		(net "M_K_CPU0_SA_DQS_DN<7>")
	)
	(segment
		(start 435.972458 -221.17812)
		(end 436.576978 -221.17812)
		(width 0.16002)
		(layer "In6.Cu")
		(net "M_K_CPU0_SA_DQS_DN<7>")
	)
	(segment
		(start 389.170926 -237.45952)
		(end 389.19404 -237.546134)
		(width 0.09525)
		(layer "In6.Cu")
		(net "M_K_CPU0_SA_DQS_DN<7>")
	)
	(segment
		(start 390.44499 -237.524036)
		(end 390.453372 -237.51921)
		(width 0.09525)
		(layer "In6.Cu")
		(net "M_K_CPU0_SA_DQS_DN<7>")
	)
	(segment
		(start 400.520154 -234.665774)
		(end 400.76755 -234.418378)
		(width 0.16002)
		(layer "In6.Cu")
		(net "M_K_CPU0_SA_DQS_DN<7>")
	)
	(segment
		(start 400.76755 -234.192318)
		(end 400.361912 -233.78668)
		(width 0.16002)
		(layer "In6.Cu")
		(net "M_K_CPU0_SA_DQS_DN<7>")
	)
	(segment
		(start 400.361912 -233.310176)
		(end 400.785584 -232.886504)
		(width 0.16002)
		(layer "In6.Cu")
		(net "M_K_CPU0_SA_DQS_DN<7>")
	)
	(segment
		(start 435.592728 -221.55785)
		(end 435.972458 -221.17812)
		(width 0.16002)
		(layer "In6.Cu")
		(net "M_K_CPU0_SA_DQS_DN<7>")
	)
	(segment
		(start 391.956036 -237.51921)
		(end 391.964418 -237.524036)
		(width 0.09525)
		(layer "In6.Cu")
		(net "M_K_CPU0_SA_DQS_DN<7>")
	)
	(segment
		(start 400.76755 -234.418378)
		(end 400.76755 -234.192318)
		(width 0.16002)
		(layer "In6.Cu")
		(net "M_K_CPU0_SA_DQS_DN<7>")
	)
	(segment
		(start 399.411952 -234.260136)
		(end 399.888456 -234.260136)
		(width 0.16002)
		(layer "In6.Cu")
		(net "M_K_CPU0_SA_DQS_DN<7>")
	)
	(segment
		(start 419.44036 -221.55785)
		(end 420.50462 -221.55785)
		(width 0.16002)
		(layer "In6.Cu")
		(net "M_K_CPU0_SA_DQS_DN<7>")
	)
	(segment
		(start 420.50462 -221.55785)
		(end 420.88435 -221.17812)
		(width 0.16002)
		(layer "In6.Cu")
		(net "M_K_CPU0_SA_DQS_DN<7>")
	)
	(segment
		(start 398.099788 -235.5723)
		(end 399.411952 -234.260136)
		(width 0.16002)
		(layer "In6.Cu")
		(net "M_K_CPU0_SA_DQS_DN<7>")
	)
	(segment
		(start 440.914028 -220.431868)
		(end 441.394088 -220.431868)
		(width 0.16002)
		(layer "In6.Cu")
		(net "M_K_CPU0_SA_DQS_DN<7>")
	)
	(segment
		(start 413.944816 -221.17812)
		(end 414.732216 -220.39072)
		(width 0.16002)
		(layer "In6.Cu")
		(net "M_K_CPU0_SA_DQS_DN<7>")
	)
	(segment
		(start 426.984414 -221.55785)
		(end 428.048674 -221.55785)
		(width 0.16002)
		(layer "In6.Cu")
		(net "M_K_CPU0_SA_DQS_DN<7>")
	)
	(segment
		(start 428.428404 -221.17812)
		(end 429.032924 -221.17812)
		(width 0.16002)
		(layer "In6.Cu")
		(net "M_K_CPU0_SA_DQS_DN<7>")
	)
	(segment
		(start 423.33545 -220.39072)
		(end 423.652696 -220.707966)
		(width 0.16002)
		(layer "In6.Cu")
		(net "M_K_CPU0_SA_DQS_DN<7>")
	)
	(segment
		(start 393.36345 -237.458758)
		(end 394.106146 -236.716062)
		(width 0.09525)
		(layer "In6.Cu")
		(net "M_K_CPU0_SA_DQS_DN<7>")
	)
	(segment
		(start 400.294094 -234.665774)
		(end 400.520154 -234.665774)
		(width 0.16002)
		(layer "In6.Cu")
		(net "M_K_CPU0_SA_DQS_DN<7>")
	)
	(segment
		(start 395.859254 -235.5723)
		(end 398.099788 -235.5723)
		(width 0.16002)
		(layer "In6.Cu")
		(net "M_K_CPU0_SA_DQS_DN<7>")
	)
	(segment
		(start 441.394088 -220.431868)
		(end 441.521088 -220.558868)
		(width 0.16002)
		(layer "In6.Cu")
		(net "M_K_CPU0_SA_DQS_DN<7>")
	)
	(segment
		(start 402.141182 -232.818686)
		(end 401.735544 -232.413048)
		(width 0.16002)
		(layer "In6.Cu")
		(net "M_K_CPU0_SA_DQS_DN<7>")
	)
	(segment
		(start 395.77645 -235.631482)
		(end 395.835632 -235.5723)
		(width 0.09525)
		(layer "In6.Cu")
		(net "M_K_CPU0_SA_DQS_DN<7>")
	)
	(segment
		(start 411.813248 -221.17812)
		(end 413.944816 -221.17812)
		(width 0.16002)
		(layer "In6.Cu")
		(net "M_K_CPU0_SA_DQS_DN<7>")
	)
	(segment
		(start 416.108642 -220.707966)
		(end 418.590476 -220.707966)
		(width 0.16002)
		(layer "In6.Cu")
		(net "M_K_CPU0_SA_DQS_DN<7>")
	)
	(segment
		(start 438.740804 -220.707966)
		(end 439.922412 -220.707966)
		(width 0.16002)
		(layer "In6.Cu")
		(net "M_K_CPU0_SA_DQS_DN<7>")
	)
	(segment
		(start 429.820324 -220.39072)
		(end 430.879504 -220.39072)
		(width 0.16002)
		(layer "In6.Cu")
		(net "M_K_CPU0_SA_DQS_DN<7>")
	)
	(segment
		(start 418.590476 -220.707966)
		(end 419.44036 -221.55785)
		(width 0.16002)
		(layer "In6.Cu")
		(net "M_K_CPU0_SA_DQS_DN<7>")
	)
	(segment
		(start 420.88435 -221.17812)
		(end 421.48887 -221.17812)
		(width 0.16002)
		(layer "In6.Cu")
		(net "M_K_CPU0_SA_DQS_DN<7>")
	)
	(segment
		(start 401.262088 -232.886504)
		(end 401.667726 -233.292142)
		(width 0.16002)
		(layer "In6.Cu")
		(net "M_K_CPU0_SA_DQS_DN<7>")
	)
	(segment
		(start 433.678584 -220.707966)
		(end 434.528468 -221.55785)
		(width 0.16002)
		(layer "In6.Cu")
		(net "M_K_CPU0_SA_DQS_DN<7>")
	)
	(segment
		(start 426.13453 -220.707966)
		(end 426.984414 -221.55785)
		(width 0.16002)
		(layer "In6.Cu")
		(net "M_K_CPU0_SA_DQS_DN<7>")
	)
	(segment
		(start 392.333226 -237.51921)
		(end 392.348212 -237.511082)
		(width 0.09525)
		(layer "In6.Cu")
		(net "M_K_CPU0_SA_DQS_DN<7>")
	)
	(segment
		(start 399.888456 -234.260136)
		(end 400.294094 -234.665774)
		(width 0.16002)
		(layer "In6.Cu")
		(net "M_K_CPU0_SA_DQS_DN<7>")
	)
	(segment
		(start 438.423558 -220.39072)
		(end 438.740804 -220.707966)
		(width 0.16002)
		(layer "In6.Cu")
		(net "M_K_CPU0_SA_DQS_DN<7>")
	)
	(segment
		(start 440.787028 -220.558868)
		(end 440.914028 -220.431868)
		(width 0.16002)
		(layer "In6.Cu")
		(net "M_K_CPU0_SA_DQS_DN<7>")
	)
	(segment
		(start 409.922218 -223.74987)
		(end 409.922218 -223.06915)
		(width 0.16002)
		(layer "In6.Cu")
		(net "M_K_CPU0_SA_DQS_DN<7>")
	)
	(segment
		(start 422.27627 -220.39072)
		(end 423.33545 -220.39072)
		(width 0.16002)
		(layer "In6.Cu")
		(net "M_K_CPU0_SA_DQS_DN<7>")
	)
	(segment
		(start 401.735544 -232.413048)
		(end 401.735544 -231.936544)
		(width 0.16002)
		(layer "In6.Cu")
		(net "M_K_CPU0_SA_DQS_DN<7>")
	)
	(segment
		(start 401.735544 -231.936544)
		(end 409.922218 -223.74987)
		(width 0.16002)
		(layer "In6.Cu")
		(net "M_K_CPU0_SA_DQS_DN<7>")
	)
	(segment
		(start 442.270388 -220.558868)
		(end 442.5442 -220.285056)
		(width 0.16002)
		(layer "In6.Cu")
		(net "M_K_CPU0_SA_DQS_DN<7>")
	)
	(segment
		(start 441.521088 -220.558868)
		(end 442.270388 -220.558868)
		(width 0.16002)
		(layer "In6.Cu")
		(net "M_K_CPU0_SA_DQS_DN<7>")
	)
	(segment
		(start 395.011148 -236.077506)
		(end 395.457172 -235.631482)
		(width 0.09525)
		(layer "In6.Cu")
		(net "M_K_CPU0_SA_DQS_DN<7>")
	)
	(segment
		(start 401.667726 -233.292142)
		(end 401.893786 -233.292142)
		(width 0.16002)
		(layer "In6.Cu")
		(net "M_K_CPU0_SA_DQS_DN<7>")
	)
	(segment
		(start 430.879504 -220.39072)
		(end 431.19675 -220.707966)
		(width 0.16002)
		(layer "In6.Cu")
		(net "M_K_CPU0_SA_DQS_DN<7>")
	)
	(segment
		(start 431.19675 -220.707966)
		(end 433.678584 -220.707966)
		(width 0.16002)
		(layer "In6.Cu")
		(net "M_K_CPU0_SA_DQS_DN<7>")
	)
	(segment
		(start 401.893786 -233.292142)
		(end 402.141182 -233.044746)
		(width 0.16002)
		(layer "In6.Cu")
		(net "M_K_CPU0_SA_DQS_DN<7>")
	)
	(segment
		(start 409.922218 -223.06915)
		(end 411.813248 -221.17812)
		(width 0.16002)
		(layer "In6.Cu")
		(net "M_K_CPU0_SA_DQS_DN<7>")
	)
	(segment
		(start 395.835632 -235.5723)
		(end 395.859254 -235.5723)
		(width 0.09525)
		(layer "In6.Cu")
		(net "M_K_CPU0_SA_DQS_DN<7>")
	)
	(segment
		(start 439.922412 -220.707966)
		(end 440.07151 -220.558868)
		(width 0.16002)
		(layer "In6.Cu")
		(net "M_K_CPU0_SA_DQS_DN<7>")
	)
	(arc
		(start 392.348212 -237.511082)
		(mid 392.622989 -237.443875)
		(end 392.895582 -237.519464)
		(width 0.09525)
		(layer "In6.Cu")
		(net "M_K_CPU0_SA_DQS_DN<7>")
	)
	(arc
		(start 391.393426 -237.51921)
		(mid 391.668715 -237.443489)
		(end 391.945622 -237.513114)
		(width 0.09525)
		(layer "In6.Cu")
		(net "M_K_CPU0_SA_DQS_DN<7>")
	)
	(arc
		(start 390.076182 -237.51921)
		(mid 390.259957 -237.569982)
		(end 390.44499 -237.524036)
		(width 0.09525)
		(layer "In6.Cu")
		(net "M_K_CPU0_SA_DQS_DN<7>")
	)
	(arc
		(start 389.19404 -237.546134)
		(mid 389.356691 -237.568394)
		(end 389.513318 -237.51921)
		(width 0.09525)
		(layer "In6.Cu")
		(net "M_K_CPU0_SA_DQS_DN<7>")
	)
	(arc
		(start 390.453372 -237.51921)
		(mid 390.734804 -237.443455)
		(end 391.016236 -237.51921)
		(width 0.09525)
		(layer "In6.Cu")
		(net "M_K_CPU0_SA_DQS_DN<7>")
	)
	(arc
		(start 392.895582 -237.519464)
		(mid 393.139866 -237.568724)
		(end 393.36345 -237.458758)
		(width 0.09525)
		(layer "In6.Cu")
		(net "M_K_CPU0_SA_DQS_DN<7>")
	)
	(arc
		(start 391.024618 -237.524036)
		(mid 391.20965 -237.56995)
		(end 391.393426 -237.51921)
		(width 0.09525)
		(layer "In6.Cu")
		(net "M_K_CPU0_SA_DQS_DN<7>")
	)
	(arc
		(start 391.964418 -237.524036)
		(mid 392.149196 -237.569829)
		(end 392.332718 -237.51921)
		(width 0.09525)
		(layer "In6.Cu")
		(net "M_K_CPU0_SA_DQS_DN<7>")
	)
	(arc
		(start 389.513318 -237.51921)
		(mid 389.79475 -237.443455)
		(end 390.076182 -237.51921)
		(width 0.09525)
		(layer "In6.Cu")
		(net "M_K_CPU0_SA_DQS_DN<7>")
	)
	(segment
		(start 388.857998 -232.599992)
		(end 389.32485 -232.334054)
		(width 0.12954)
		(layer "F.Cu")
		(net "M_K_CPU0_SA_DQS_DN<6>")
	)
	(segment
		(start 395.645386 -230.061008)
		(end 403.743414 -221.96298)
		(width 0.16002)
		(layer "In6.Cu")
		(net "M_K_CPU0_SA_DQS_DN<6>")
	)
	(segment
		(start 414.732216 -211.040726)
		(end 415.791396 -211.040726)
		(width 0.16002)
		(layer "In6.Cu")
		(net "M_K_CPU0_SA_DQS_DN<6>")
	)
	(segment
		(start 406.545288 -217.673682)
		(end 406.791922 -217.427048)
		(width 0.16002)
		(layer "In6.Cu")
		(net "M_K_CPU0_SA_DQS_DN<6>")
	)
	(segment
		(start 404.044658 -219.948252)
		(end 404.04288 -219.946474)
		(width 0.16002)
		(layer "In6.Cu")
		(net "M_K_CPU0_SA_DQS_DN<6>")
	)
	(segment
		(start 407.69286 -216.30005)
		(end 407.91892 -216.30005)
		(width 0.16002)
		(layer "In6.Cu")
		(net "M_K_CPU0_SA_DQS_DN<6>")
	)
	(segment
		(start 410.912818 -213.080092)
		(end 410.91104 -213.078314)
		(width 0.16002)
		(layer "In6.Cu")
		(net "M_K_CPU0_SA_DQS_DN<6>")
	)
	(segment
		(start 403.743414 -221.96298)
		(end 403.743414 -220.475556)
		(width 0.16002)
		(layer "In6.Cu")
		(net "M_K_CPU0_SA_DQS_DN<6>")
	)
	(segment
		(start 410.440124 -213.552786)
		(end 410.666184 -213.552786)
		(width 0.16002)
		(layer "In6.Cu")
		(net "M_K_CPU0_SA_DQS_DN<6>")
	)
	(segment
		(start 409.537408 -214.451946)
		(end 409.537408 -213.975442)
		(width 0.16002)
		(layer "In6.Cu")
		(net "M_K_CPU0_SA_DQS_DN<6>")
	)
	(segment
		(start 429.032924 -211.828126)
		(end 429.912018 -210.949032)
		(width 0.16002)
		(layer "In6.Cu")
		(net "M_K_CPU0_SA_DQS_DN<6>")
	)
	(segment
		(start 429.912018 -210.949032)
		(end 430.78781 -210.949032)
		(width 0.16002)
		(layer "In6.Cu")
		(net "M_K_CPU0_SA_DQS_DN<6>")
	)
	(segment
		(start 404.04288 -219.946474)
		(end 404.04288 -219.46997)
		(width 0.16002)
		(layer "In6.Cu")
		(net "M_K_CPU0_SA_DQS_DN<6>")
	)
	(segment
		(start 438.423558 -211.040726)
		(end 438.740804 -211.357972)
		(width 0.16002)
		(layer "In6.Cu")
		(net "M_K_CPU0_SA_DQS_DN<6>")
	)
	(segment
		(start 420.88435 -211.828126)
		(end 421.48887 -211.828126)
		(width 0.16002)
		(layer "In6.Cu")
		(net "M_K_CPU0_SA_DQS_DN<6>")
	)
	(segment
		(start 426.13453 -211.357972)
		(end 426.984414 -212.207856)
		(width 0.16002)
		(layer "In6.Cu")
		(net "M_K_CPU0_SA_DQS_DN<6>")
	)
	(segment
		(start 408.163776 -215.825578)
		(end 408.163776 -215.349074)
		(width 0.16002)
		(layer "In6.Cu")
		(net "M_K_CPU0_SA_DQS_DN<6>")
	)
	(segment
		(start 428.048674 -212.207856)
		(end 428.428404 -211.828126)
		(width 0.16002)
		(layer "In6.Cu")
		(net "M_K_CPU0_SA_DQS_DN<6>")
	)
	(segment
		(start 411.335474 -212.177376)
		(end 411.811978 -212.177376)
		(width 0.16002)
		(layer "In6.Cu")
		(net "M_K_CPU0_SA_DQS_DN<6>")
	)
	(segment
		(start 404.044658 -220.174312)
		(end 404.044658 -219.948252)
		(width 0.16002)
		(layer "In6.Cu")
		(net "M_K_CPU0_SA_DQS_DN<6>")
	)
	(segment
		(start 392.332972 -232.659174)
		(end 392.343386 -232.653078)
		(width 0.09525)
		(layer "In6.Cu")
		(net "M_K_CPU0_SA_DQS_DN<6>")
	)
	(segment
		(start 408.58821 -214.92464)
		(end 409.064714 -214.92464)
		(width 0.16002)
		(layer "In6.Cu")
		(net "M_K_CPU0_SA_DQS_DN<6>")
	)
	(segment
		(start 433.678584 -211.357972)
		(end 434.528468 -212.207856)
		(width 0.16002)
		(layer "In6.Cu")
		(net "M_K_CPU0_SA_DQS_DN<6>")
	)
	(segment
		(start 410.438346 -213.551008)
		(end 410.440124 -213.552786)
		(width 0.16002)
		(layer "In6.Cu")
		(net "M_K_CPU0_SA_DQS_DN<6>")
	)
	(segment
		(start 412.039816 -212.179154)
		(end 412.390844 -211.828126)
		(width 0.16002)
		(layer "In6.Cu")
		(net "M_K_CPU0_SA_DQS_DN<6>")
	)
	(segment
		(start 440.07151 -211.208874)
		(end 440.822588 -211.208874)
		(width 0.16002)
		(layer "In6.Cu")
		(net "M_K_CPU0_SA_DQS_DN<6>")
	)
	(segment
		(start 410.91104 -212.60181)
		(end 411.335474 -212.177376)
		(width 0.16002)
		(layer "In6.Cu")
		(net "M_K_CPU0_SA_DQS_DN<6>")
	)
	(segment
		(start 409.537408 -213.975442)
		(end 409.961842 -213.551008)
		(width 0.16002)
		(layer "In6.Cu")
		(net "M_K_CPU0_SA_DQS_DN<6>")
	)
	(segment
		(start 409.539186 -214.679784)
		(end 409.539186 -214.453724)
		(width 0.16002)
		(layer "In6.Cu")
		(net "M_K_CPU0_SA_DQS_DN<6>")
	)
	(segment
		(start 393.938506 -231.449118)
		(end 394.927836 -230.459788)
		(width 0.09525)
		(layer "In6.Cu")
		(net "M_K_CPU0_SA_DQS_DN<6>")
	)
	(segment
		(start 441.449206 -211.101432)
		(end 441.556648 -211.208874)
		(width 0.16002)
		(layer "In6.Cu")
		(net "M_K_CPU0_SA_DQS_DN<6>")
	)
	(segment
		(start 406.31745 -217.671904)
		(end 406.319228 -217.673682)
		(width 0.16002)
		(layer "In6.Cu")
		(net "M_K_CPU0_SA_DQS_DN<6>")
	)
	(segment
		(start 389.170926 -232.599484)
		(end 389.19404 -232.686098)
		(width 0.09525)
		(layer "In6.Cu")
		(net "M_K_CPU0_SA_DQS_DN<6>")
	)
	(segment
		(start 403.743414 -220.475556)
		(end 404.044658 -220.174312)
		(width 0.16002)
		(layer "In6.Cu")
		(net "M_K_CPU0_SA_DQS_DN<6>")
	)
	(segment
		(start 434.528468 -212.207856)
		(end 435.592728 -212.207856)
		(width 0.16002)
		(layer "In6.Cu")
		(net "M_K_CPU0_SA_DQS_DN<6>")
	)
	(segment
		(start 423.33545 -211.040726)
		(end 423.652696 -211.357972)
		(width 0.16002)
		(layer "In6.Cu")
		(net "M_K_CPU0_SA_DQS_DN<6>")
	)
	(segment
		(start 391.945622 -232.653078)
		(end 391.956036 -232.659174)
		(width 0.09525)
		(layer "In6.Cu")
		(net "M_K_CPU0_SA_DQS_DN<6>")
	)
	(segment
		(start 435.972458 -211.828126)
		(end 436.576978 -211.828126)
		(width 0.16002)
		(layer "In6.Cu")
		(net "M_K_CPU0_SA_DQS_DN<6>")
	)
	(segment
		(start 395.628622 -230.077772)
		(end 395.645386 -230.061008)
		(width 0.09525)
		(layer "In6.Cu")
		(net "M_K_CPU0_SA_DQS_DN<6>")
	)
	(segment
		(start 409.539186 -214.453724)
		(end 409.537408 -214.451946)
		(width 0.16002)
		(layer "In6.Cu")
		(net "M_K_CPU0_SA_DQS_DN<6>")
	)
	(segment
		(start 412.390844 -211.828126)
		(end 413.944816 -211.828126)
		(width 0.16002)
		(layer "In6.Cu")
		(net "M_K_CPU0_SA_DQS_DN<6>")
	)
	(segment
		(start 441.556648 -211.208874)
		(end 442.270388 -211.208874)
		(width 0.16002)
		(layer "In6.Cu")
		(net "M_K_CPU0_SA_DQS_DN<6>")
	)
	(segment
		(start 439.922412 -211.357972)
		(end 440.07151 -211.208874)
		(width 0.16002)
		(layer "In6.Cu")
		(net "M_K_CPU0_SA_DQS_DN<6>")
	)
	(segment
		(start 390.44499 -232.664)
		(end 390.453372 -232.659174)
		(width 0.09525)
		(layer "In6.Cu")
		(net "M_K_CPU0_SA_DQS_DN<6>")
	)
	(segment
		(start 407.214578 -216.298272)
		(end 407.691082 -216.298272)
		(width 0.16002)
		(layer "In6.Cu")
		(net "M_K_CPU0_SA_DQS_DN<6>")
	)
	(segment
		(start 405.41829 -218.57462)
		(end 405.416512 -218.572842)
		(width 0.16002)
		(layer "In6.Cu")
		(net "M_K_CPU0_SA_DQS_DN<6>")
	)
	(segment
		(start 406.791922 -217.427048)
		(end 406.791922 -217.200988)
		(width 0.16002)
		(layer "In6.Cu")
		(net "M_K_CPU0_SA_DQS_DN<6>")
	)
	(segment
		(start 404.943818 -219.045536)
		(end 404.945596 -219.047314)
		(width 0.16002)
		(layer "In6.Cu")
		(net "M_K_CPU0_SA_DQS_DN<6>")
	)
	(segment
		(start 415.791396 -211.040726)
		(end 416.108642 -211.357972)
		(width 0.16002)
		(layer "In6.Cu")
		(net "M_K_CPU0_SA_DQS_DN<6>")
	)
	(segment
		(start 409.961842 -213.551008)
		(end 410.438346 -213.551008)
		(width 0.16002)
		(layer "In6.Cu")
		(net "M_K_CPU0_SA_DQS_DN<6>")
	)
	(segment
		(start 410.666184 -213.552786)
		(end 410.912818 -213.306152)
		(width 0.16002)
		(layer "In6.Cu")
		(net "M_K_CPU0_SA_DQS_DN<6>")
	)
	(segment
		(start 411.813756 -212.179154)
		(end 412.039816 -212.179154)
		(width 0.16002)
		(layer "In6.Cu")
		(net "M_K_CPU0_SA_DQS_DN<6>")
	)
	(segment
		(start 430.78781 -210.949032)
		(end 431.19675 -211.357972)
		(width 0.16002)
		(layer "In6.Cu")
		(net "M_K_CPU0_SA_DQS_DN<6>")
	)
	(segment
		(start 395.329918 -230.459788)
		(end 395.628622 -230.161084)
		(width 0.09525)
		(layer "In6.Cu")
		(net "M_K_CPU0_SA_DQS_DN<6>")
	)
	(segment
		(start 409.066492 -214.926418)
		(end 409.292552 -214.926418)
		(width 0.16002)
		(layer "In6.Cu")
		(net "M_K_CPU0_SA_DQS_DN<6>")
	)
	(segment
		(start 416.108642 -211.357972)
		(end 418.590476 -211.357972)
		(width 0.16002)
		(layer "In6.Cu")
		(net "M_K_CPU0_SA_DQS_DN<6>")
	)
	(segment
		(start 404.467314 -219.045536)
		(end 404.943818 -219.045536)
		(width 0.16002)
		(layer "In6.Cu")
		(net "M_K_CPU0_SA_DQS_DN<6>")
	)
	(segment
		(start 413.944816 -211.828126)
		(end 414.732216 -211.040726)
		(width 0.16002)
		(layer "In6.Cu")
		(net "M_K_CPU0_SA_DQS_DN<6>")
	)
	(segment
		(start 393.350496 -232.599992)
		(end 393.938506 -232.011982)
		(width 0.09525)
		(layer "In6.Cu")
		(net "M_K_CPU0_SA_DQS_DN<6>")
	)
	(segment
		(start 418.590476 -211.357972)
		(end 419.44036 -212.207856)
		(width 0.16002)
		(layer "In6.Cu")
		(net "M_K_CPU0_SA_DQS_DN<6>")
	)
	(segment
		(start 409.292552 -214.926418)
		(end 409.539186 -214.679784)
		(width 0.16002)
		(layer "In6.Cu")
		(net "M_K_CPU0_SA_DQS_DN<6>")
	)
	(segment
		(start 393.938506 -232.011982)
		(end 393.938506 -231.449118)
		(width 0.09525)
		(layer "In6.Cu")
		(net "M_K_CPU0_SA_DQS_DN<6>")
	)
	(segment
		(start 405.416512 -218.096338)
		(end 405.840946 -217.671904)
		(width 0.16002)
		(layer "In6.Cu")
		(net "M_K_CPU0_SA_DQS_DN<6>")
	)
	(segment
		(start 406.319228 -217.673682)
		(end 406.545288 -217.673682)
		(width 0.16002)
		(layer "In6.Cu")
		(net "M_K_CPU0_SA_DQS_DN<6>")
	)
	(segment
		(start 423.652696 -211.357972)
		(end 426.13453 -211.357972)
		(width 0.16002)
		(layer "In6.Cu")
		(net "M_K_CPU0_SA_DQS_DN<6>")
	)
	(segment
		(start 431.19675 -211.357972)
		(end 433.678584 -211.357972)
		(width 0.16002)
		(layer "In6.Cu")
		(net "M_K_CPU0_SA_DQS_DN<6>")
	)
	(segment
		(start 410.91104 -213.078314)
		(end 410.91104 -212.60181)
		(width 0.16002)
		(layer "In6.Cu")
		(net "M_K_CPU0_SA_DQS_DN<6>")
	)
	(segment
		(start 405.416512 -218.572842)
		(end 405.416512 -218.096338)
		(width 0.16002)
		(layer "In6.Cu")
		(net "M_K_CPU0_SA_DQS_DN<6>")
	)
	(segment
		(start 405.41829 -218.80068)
		(end 405.41829 -218.57462)
		(width 0.16002)
		(layer "In6.Cu")
		(net "M_K_CPU0_SA_DQS_DN<6>")
	)
	(segment
		(start 442.270388 -211.208874)
		(end 442.5442 -210.935062)
		(width 0.16002)
		(layer "In6.Cu")
		(net "M_K_CPU0_SA_DQS_DN<6>")
	)
	(segment
		(start 421.48887 -211.828126)
		(end 422.27627 -211.040726)
		(width 0.16002)
		(layer "In6.Cu")
		(net "M_K_CPU0_SA_DQS_DN<6>")
	)
	(segment
		(start 438.740804 -211.357972)
		(end 439.922412 -211.357972)
		(width 0.16002)
		(layer "In6.Cu")
		(net "M_K_CPU0_SA_DQS_DN<6>")
	)
	(segment
		(start 428.428404 -211.828126)
		(end 429.032924 -211.828126)
		(width 0.16002)
		(layer "In6.Cu")
		(net "M_K_CPU0_SA_DQS_DN<6>")
	)
	(segment
		(start 407.91892 -216.30005)
		(end 408.165554 -216.053416)
		(width 0.16002)
		(layer "In6.Cu")
		(net "M_K_CPU0_SA_DQS_DN<6>")
	)
	(segment
		(start 389.32485 -232.334054)
		(end 389.170926 -232.599484)
		(width 0.09525)
		(layer "In6.Cu")
		(net "M_K_CPU0_SA_DQS_DN<6>")
	)
	(segment
		(start 435.592728 -212.207856)
		(end 435.972458 -211.828126)
		(width 0.16002)
		(layer "In6.Cu")
		(net "M_K_CPU0_SA_DQS_DN<6>")
	)
	(segment
		(start 405.171656 -219.047314)
		(end 405.41829 -218.80068)
		(width 0.16002)
		(layer "In6.Cu")
		(net "M_K_CPU0_SA_DQS_DN<6>")
	)
	(segment
		(start 408.163776 -215.349074)
		(end 408.58821 -214.92464)
		(width 0.16002)
		(layer "In6.Cu")
		(net "M_K_CPU0_SA_DQS_DN<6>")
	)
	(segment
		(start 409.064714 -214.92464)
		(end 409.066492 -214.926418)
		(width 0.16002)
		(layer "In6.Cu")
		(net "M_K_CPU0_SA_DQS_DN<6>")
	)
	(segment
		(start 410.912818 -213.306152)
		(end 410.912818 -213.080092)
		(width 0.16002)
		(layer "In6.Cu")
		(net "M_K_CPU0_SA_DQS_DN<6>")
	)
	(segment
		(start 405.840946 -217.671904)
		(end 406.31745 -217.671904)
		(width 0.16002)
		(layer "In6.Cu")
		(net "M_K_CPU0_SA_DQS_DN<6>")
	)
	(segment
		(start 440.822588 -211.208874)
		(end 440.93003 -211.101432)
		(width 0.16002)
		(layer "In6.Cu")
		(net "M_K_CPU0_SA_DQS_DN<6>")
	)
	(segment
		(start 419.44036 -212.207856)
		(end 420.50462 -212.207856)
		(width 0.16002)
		(layer "In6.Cu")
		(net "M_K_CPU0_SA_DQS_DN<6>")
	)
	(segment
		(start 436.576978 -211.828126)
		(end 437.364378 -211.040726)
		(width 0.16002)
		(layer "In6.Cu")
		(net "M_K_CPU0_SA_DQS_DN<6>")
	)
	(segment
		(start 426.984414 -212.207856)
		(end 428.048674 -212.207856)
		(width 0.16002)
		(layer "In6.Cu")
		(net "M_K_CPU0_SA_DQS_DN<6>")
	)
	(segment
		(start 440.93003 -211.101432)
		(end 441.449206 -211.101432)
		(width 0.16002)
		(layer "In6.Cu")
		(net "M_K_CPU0_SA_DQS_DN<6>")
	)
	(segment
		(start 393.350496 -232.599484)
		(end 393.350496 -232.599992)
		(width 0.09525)
		(layer "In6.Cu")
		(net "M_K_CPU0_SA_DQS_DN<6>")
	)
	(segment
		(start 406.791922 -217.200988)
		(end 406.790144 -217.19921)
		(width 0.16002)
		(layer "In6.Cu")
		(net "M_K_CPU0_SA_DQS_DN<6>")
	)
	(segment
		(start 420.50462 -212.207856)
		(end 420.88435 -211.828126)
		(width 0.16002)
		(layer "In6.Cu")
		(net "M_K_CPU0_SA_DQS_DN<6>")
	)
	(segment
		(start 393.261088 -232.666032)
		(end 393.273026 -232.659174)
		(width 0.09525)
		(layer "In6.Cu")
		(net "M_K_CPU0_SA_DQS_DN<6>")
	)
	(segment
		(start 391.016236 -232.659174)
		(end 391.024618 -232.664)
		(width 0.09525)
		(layer "In6.Cu")
		(net "M_K_CPU0_SA_DQS_DN<6>")
	)
	(segment
		(start 394.927836 -230.459788)
		(end 395.329918 -230.459788)
		(width 0.09525)
		(layer "In6.Cu")
		(net "M_K_CPU0_SA_DQS_DN<6>")
	)
	(segment
		(start 408.165554 -215.827356)
		(end 408.163776 -215.825578)
		(width 0.16002)
		(layer "In6.Cu")
		(net "M_K_CPU0_SA_DQS_DN<6>")
	)
	(segment
		(start 406.790144 -217.19921)
		(end 406.790144 -216.722706)
		(width 0.16002)
		(layer "In6.Cu")
		(net "M_K_CPU0_SA_DQS_DN<6>")
	)
	(segment
		(start 395.628622 -230.161084)
		(end 395.628622 -230.077772)
		(width 0.09525)
		(layer "In6.Cu")
		(net "M_K_CPU0_SA_DQS_DN<6>")
	)
	(segment
		(start 407.691082 -216.298272)
		(end 407.69286 -216.30005)
		(width 0.16002)
		(layer "In6.Cu")
		(net "M_K_CPU0_SA_DQS_DN<6>")
	)
	(segment
		(start 406.790144 -216.722706)
		(end 407.214578 -216.298272)
		(width 0.16002)
		(layer "In6.Cu")
		(net "M_K_CPU0_SA_DQS_DN<6>")
	)
	(segment
		(start 408.165554 -216.053416)
		(end 408.165554 -215.827356)
		(width 0.16002)
		(layer "In6.Cu")
		(net "M_K_CPU0_SA_DQS_DN<6>")
	)
	(segment
		(start 437.364378 -211.040726)
		(end 438.423558 -211.040726)
		(width 0.16002)
		(layer "In6.Cu")
		(net "M_K_CPU0_SA_DQS_DN<6>")
	)
	(segment
		(start 404.04288 -219.46997)
		(end 404.467314 -219.045536)
		(width 0.16002)
		(layer "In6.Cu")
		(net "M_K_CPU0_SA_DQS_DN<6>")
	)
	(segment
		(start 422.27627 -211.040726)
		(end 423.33545 -211.040726)
		(width 0.16002)
		(layer "In6.Cu")
		(net "M_K_CPU0_SA_DQS_DN<6>")
	)
	(segment
		(start 404.945596 -219.047314)
		(end 405.171656 -219.047314)
		(width 0.16002)
		(layer "In6.Cu")
		(net "M_K_CPU0_SA_DQS_DN<6>")
	)
	(segment
		(start 411.811978 -212.177376)
		(end 411.813756 -212.179154)
		(width 0.16002)
		(layer "In6.Cu")
		(net "M_K_CPU0_SA_DQS_DN<6>")
	)
	(arc
		(start 391.393426 -232.659174)
		(mid 391.668715 -232.583453)
		(end 391.945622 -232.653078)
		(width 0.09525)
		(layer "In6.Cu")
		(net "M_K_CPU0_SA_DQS_DN<6>")
	)
	(arc
		(start 390.453372 -232.659174)
		(mid 390.734804 -232.583419)
		(end 391.016236 -232.659174)
		(width 0.09525)
		(layer "In6.Cu")
		(net "M_K_CPU0_SA_DQS_DN<6>")
	)
	(arc
		(start 392.89609 -232.659174)
		(mid 393.077706 -232.709911)
		(end 393.261088 -232.666032)
		(width 0.09525)
		(layer "In6.Cu")
		(net "M_K_CPU0_SA_DQS_DN<6>")
	)
	(arc
		(start 391.024618 -232.664)
		(mid 391.20965 -232.709914)
		(end 391.393426 -232.659174)
		(width 0.09525)
		(layer "In6.Cu")
		(net "M_K_CPU0_SA_DQS_DN<6>")
	)
	(arc
		(start 393.273026 -232.659174)
		(mid 393.31372 -232.63187)
		(end 393.350496 -232.599484)
		(width 0.09525)
		(layer "In6.Cu")
		(net "M_K_CPU0_SA_DQS_DN<6>")
	)
	(arc
		(start 391.956036 -232.659174)
		(mid 392.144504 -232.709851)
		(end 392.332972 -232.659174)
		(width 0.09525)
		(layer "In6.Cu")
		(net "M_K_CPU0_SA_DQS_DN<6>")
	)
	(arc
		(start 390.076182 -232.659174)
		(mid 390.259957 -232.709946)
		(end 390.44499 -232.664)
		(width 0.09525)
		(layer "In6.Cu")
		(net "M_K_CPU0_SA_DQS_DN<6>")
	)
	(arc
		(start 392.343386 -232.653078)
		(mid 392.620548 -232.583278)
		(end 392.89609 -232.659174)
		(width 0.09525)
		(layer "In6.Cu")
		(net "M_K_CPU0_SA_DQS_DN<6>")
	)
	(arc
		(start 389.19404 -232.686098)
		(mid 389.356691 -232.708358)
		(end 389.513318 -232.659174)
		(width 0.09525)
		(layer "In6.Cu")
		(net "M_K_CPU0_SA_DQS_DN<6>")
	)
	(arc
		(start 389.513318 -232.659174)
		(mid 389.79475 -232.583419)
		(end 390.076182 -232.659174)
		(width 0.09525)
		(layer "In6.Cu")
		(net "M_K_CPU0_SA_DQS_DN<6>")
	)
	(segment
		(start 388.857998 -227.74021)
		(end 389.32485 -227.474272)
		(width 0.12954)
		(layer "F.Cu")
		(net "M_K_CPU0_SA_DQS_DN<5>")
	)
	(segment
		(start 400.844004 -214.021924)
		(end 400.844004 -214.247984)
		(width 0.16002)
		(layer "In6.Cu")
		(net "M_K_CPU0_SA_DQS_DN<5>")
	)
	(segment
		(start 420.88435 -202.478132)
		(end 420.50462 -202.857862)
		(width 0.16002)
		(layer "In6.Cu")
		(net "M_K_CPU0_SA_DQS_DN<5>")
	)
	(segment
		(start 398.419574 -215.768174)
		(end 397.765778 -216.42197)
		(width 0.16002)
		(layer "In6.Cu")
		(net "M_K_CPU0_SA_DQS_DN<5>")
	)
	(segment
		(start 398.896078 -215.768174)
		(end 398.419574 -215.768174)
		(width 0.16002)
		(layer "In6.Cu")
		(net "M_K_CPU0_SA_DQS_DN<5>")
	)
	(segment
		(start 435.592728 -202.857862)
		(end 434.528468 -202.857862)
		(width 0.16002)
		(layer "In6.Cu")
		(net "M_K_CPU0_SA_DQS_DN<5>")
	)
	(segment
		(start 420.50462 -202.857862)
		(end 419.44036 -202.857862)
		(width 0.16002)
		(layer "In6.Cu")
		(net "M_K_CPU0_SA_DQS_DN<5>")
	)
	(segment
		(start 394.415772 -222.57512)
		(end 394.415772 -222.61957)
		(width 0.09525)
		(layer "In6.Cu")
		(net "M_K_CPU0_SA_DQS_DN<5>")
	)
	(segment
		(start 422.27627 -201.690732)
		(end 421.48887 -202.478132)
		(width 0.16002)
		(layer "In6.Cu")
		(net "M_K_CPU0_SA_DQS_DN<5>")
	)
	(segment
		(start 402.217636 -212.648292)
		(end 402.217636 -212.874352)
		(width 0.16002)
		(layer "In6.Cu")
		(net "M_K_CPU0_SA_DQS_DN<5>")
	)
	(segment
		(start 403.49043 -211.173822)
		(end 403.591268 -211.27466)
		(width 0.16002)
		(layer "In6.Cu")
		(net "M_K_CPU0_SA_DQS_DN<5>")
	)
	(segment
		(start 433.678584 -202.007978)
		(end 431.19675 -202.007978)
		(width 0.16002)
		(layer "In6.Cu")
		(net "M_K_CPU0_SA_DQS_DN<5>")
	)
	(segment
		(start 439.922412 -202.007978)
		(end 438.740804 -202.007978)
		(width 0.16002)
		(layer "In6.Cu")
		(net "M_K_CPU0_SA_DQS_DN<5>")
	)
	(segment
		(start 438.423558 -201.690732)
		(end 437.364378 -201.690732)
		(width 0.16002)
		(layer "In6.Cu")
		(net "M_K_CPU0_SA_DQS_DN<5>")
	)
	(segment
		(start 403.914102 -210.273646)
		(end 403.49043 -210.697318)
		(width 0.16002)
		(layer "In6.Cu")
		(net "M_K_CPU0_SA_DQS_DN<5>")
	)
	(segment
		(start 403.117812 -211.748116)
		(end 403.016974 -211.647278)
		(width 0.16002)
		(layer "In6.Cu")
		(net "M_K_CPU0_SA_DQS_DN<5>")
	)
	(segment
		(start 399.793206 -214.394542)
		(end 399.369534 -214.818214)
		(width 0.16002)
		(layer "In6.Cu")
		(net "M_K_CPU0_SA_DQS_DN<5>")
	)
	(segment
		(start 404.491444 -210.374484)
		(end 404.390606 -210.273646)
		(width 0.16002)
		(layer "In6.Cu")
		(net "M_K_CPU0_SA_DQS_DN<5>")
	)
	(segment
		(start 400.743166 -213.444582)
		(end 400.743166 -213.921086)
		(width 0.16002)
		(layer "In6.Cu")
		(net "M_K_CPU0_SA_DQS_DN<5>")
	)
	(segment
		(start 415.791396 -201.690732)
		(end 414.732216 -201.690732)
		(width 0.16002)
		(layer "In6.Cu")
		(net "M_K_CPU0_SA_DQS_DN<5>")
	)
	(segment
		(start 434.528468 -202.857862)
		(end 433.678584 -202.007978)
		(width 0.16002)
		(layer "In6.Cu")
		(net "M_K_CPU0_SA_DQS_DN<5>")
	)
	(segment
		(start 414.732216 -201.690732)
		(end 413.944816 -202.478132)
		(width 0.16002)
		(layer "In6.Cu")
		(net "M_K_CPU0_SA_DQS_DN<5>")
	)
	(segment
		(start 402.217636 -212.874352)
		(end 401.97024 -213.121748)
		(width 0.16002)
		(layer "In6.Cu")
		(net "M_K_CPU0_SA_DQS_DN<5>")
	)
	(segment
		(start 392.775186 -226.997768)
		(end 392.619738 -227.065332)
		(width 0.09525)
		(layer "In6.Cu")
		(net "M_K_CPU0_SA_DQS_DN<5>")
	)
	(segment
		(start 429.032924 -202.478132)
		(end 428.428404 -202.478132)
		(width 0.16002)
		(layer "In6.Cu")
		(net "M_K_CPU0_SA_DQS_DN<5>")
	)
	(segment
		(start 419.44036 -202.857862)
		(end 418.590476 -202.007978)
		(width 0.16002)
		(layer "In6.Cu")
		(net "M_K_CPU0_SA_DQS_DN<5>")
	)
	(segment
		(start 416.108642 -202.007978)
		(end 415.791396 -201.690732)
		(width 0.16002)
		(layer "In6.Cu")
		(net "M_K_CPU0_SA_DQS_DN<5>")
	)
	(segment
		(start 435.972458 -202.478132)
		(end 435.592728 -202.857862)
		(width 0.16002)
		(layer "In6.Cu")
		(net "M_K_CPU0_SA_DQS_DN<5>")
	)
	(segment
		(start 401.166838 -213.02091)
		(end 400.743166 -213.444582)
		(width 0.16002)
		(layer "In6.Cu")
		(net "M_K_CPU0_SA_DQS_DN<5>")
	)
	(segment
		(start 394.432536 -222.558356)
		(end 394.415772 -222.57512)
		(width 0.09525)
		(layer "In6.Cu")
		(net "M_K_CPU0_SA_DQS_DN<5>")
	)
	(segment
		(start 426.13453 -202.007978)
		(end 423.652696 -202.007978)
		(width 0.16002)
		(layer "In6.Cu")
		(net "M_K_CPU0_SA_DQS_DN<5>")
	)
	(segment
		(start 403.016974 -211.647278)
		(end 402.54047 -211.647278)
		(width 0.16002)
		(layer "In6.Cu")
		(net "M_K_CPU0_SA_DQS_DN<5>")
	)
	(segment
		(start 399.369534 -215.294718)
		(end 399.470372 -215.395556)
		(width 0.16002)
		(layer "In6.Cu")
		(net "M_K_CPU0_SA_DQS_DN<5>")
	)
	(segment
		(start 393.743434 -223.749362)
		(end 393.705334 -223.77146)
		(width 0.09525)
		(layer "In6.Cu")
		(net "M_K_CPU0_SA_DQS_DN<5>")
	)
	(segment
		(start 428.428404 -202.478132)
		(end 428.048674 -202.857862)
		(width 0.16002)
		(layer "In6.Cu")
		(net "M_K_CPU0_SA_DQS_DN<5>")
	)
	(segment
		(start 403.343872 -211.748116)
		(end 403.117812 -211.748116)
		(width 0.16002)
		(layer "In6.Cu")
		(net "M_K_CPU0_SA_DQS_DN<5>")
	)
	(segment
		(start 403.591268 -211.27466)
		(end 403.591268 -211.50072)
		(width 0.16002)
		(layer "In6.Cu")
		(net "M_K_CPU0_SA_DQS_DN<5>")
	)
	(segment
		(start 442.270388 -201.85888)
		(end 441.429648 -201.85888)
		(width 0.16002)
		(layer "In6.Cu")
		(net "M_K_CPU0_SA_DQS_DN<5>")
	)
	(segment
		(start 391.900918 -227.7237)
		(end 391.674858 -227.7237)
		(width 0.09525)
		(layer "In6.Cu")
		(net "M_K_CPU0_SA_DQS_DN<5>")
	)
	(segment
		(start 423.652696 -202.007978)
		(end 423.33545 -201.690732)
		(width 0.16002)
		(layer "In6.Cu")
		(net "M_K_CPU0_SA_DQS_DN<5>")
	)
	(segment
		(start 411.709616 -202.478132)
		(end 404.864062 -209.323686)
		(width 0.16002)
		(layer "In6.Cu")
		(net "M_K_CPU0_SA_DQS_DN<5>")
	)
	(segment
		(start 402.116798 -212.547454)
		(end 402.217636 -212.648292)
		(width 0.16002)
		(layer "In6.Cu")
		(net "M_K_CPU0_SA_DQS_DN<5>")
	)
	(segment
		(start 393.463018 -224.253552)
		(end 393.463018 -225.904552)
		(width 0.09525)
		(layer "In6.Cu")
		(net "M_K_CPU0_SA_DQS_DN<5>")
	)
	(segment
		(start 393.46251 -224.234248)
		(end 393.46251 -224.253044)
		(width 0.09525)
		(layer "In6.Cu")
		(net "M_K_CPU0_SA_DQS_DN<5>")
	)
	(segment
		(start 438.740804 -202.007978)
		(end 438.423558 -201.690732)
		(width 0.16002)
		(layer "In6.Cu")
		(net "M_K_CPU0_SA_DQS_DN<5>")
	)
	(segment
		(start 423.33545 -201.690732)
		(end 422.27627 -201.690732)
		(width 0.16002)
		(layer "In6.Cu")
		(net "M_K_CPU0_SA_DQS_DN<5>")
	)
	(segment
		(start 404.864062 -209.323686)
		(end 404.864062 -209.80019)
		(width 0.16002)
		(layer "In6.Cu")
		(net "M_K_CPU0_SA_DQS_DN<5>")
	)
	(segment
		(start 441.34786 -201.777092)
		(end 440.777376 -201.777092)
		(width 0.16002)
		(layer "In6.Cu")
		(net "M_K_CPU0_SA_DQS_DN<5>")
	)
	(segment
		(start 394.387832 -222.68688)
		(end 393.93241 -223.142302)
		(width 0.09525)
		(layer "In6.Cu")
		(net "M_K_CPU0_SA_DQS_DN<5>")
	)
	(segment
		(start 397.765778 -219.225876)
		(end 394.432536 -222.558356)
		(width 0.16002)
		(layer "In6.Cu")
		(net "M_K_CPU0_SA_DQS_DN<5>")
	)
	(segment
		(start 441.429648 -201.85888)
		(end 441.34786 -201.777092)
		(width 0.16002)
		(layer "In6.Cu")
		(net "M_K_CPU0_SA_DQS_DN<5>")
	)
	(segment
		(start 400.844004 -214.247984)
		(end 400.596608 -214.49538)
		(width 0.16002)
		(layer "In6.Cu")
		(net "M_K_CPU0_SA_DQS_DN<5>")
	)
	(segment
		(start 431.19675 -202.007978)
		(end 430.879504 -201.690732)
		(width 0.16002)
		(layer "In6.Cu")
		(net "M_K_CPU0_SA_DQS_DN<5>")
	)
	(segment
		(start 442.5442 -201.585068)
		(end 442.270388 -201.85888)
		(width 0.16002)
		(layer "In6.Cu")
		(net "M_K_CPU0_SA_DQS_DN<5>")
	)
	(segment
		(start 399.369534 -214.818214)
		(end 399.369534 -215.294718)
		(width 0.16002)
		(layer "In6.Cu")
		(net "M_K_CPU0_SA_DQS_DN<5>")
	)
	(segment
		(start 429.820324 -201.690732)
		(end 429.032924 -202.478132)
		(width 0.16002)
		(layer "In6.Cu")
		(net "M_K_CPU0_SA_DQS_DN<5>")
	)
	(segment
		(start 399.470372 -215.621616)
		(end 399.222976 -215.869012)
		(width 0.16002)
		(layer "In6.Cu")
		(net "M_K_CPU0_SA_DQS_DN<5>")
	)
	(segment
		(start 400.370548 -214.49538)
		(end 400.26971 -214.394542)
		(width 0.16002)
		(layer "In6.Cu")
		(net "M_K_CPU0_SA_DQS_DN<5>")
	)
	(segment
		(start 401.643342 -213.02091)
		(end 401.166838 -213.02091)
		(width 0.16002)
		(layer "In6.Cu")
		(net "M_K_CPU0_SA_DQS_DN<5>")
	)
	(segment
		(start 413.944816 -202.478132)
		(end 411.709616 -202.478132)
		(width 0.16002)
		(layer "In6.Cu")
		(net "M_K_CPU0_SA_DQS_DN<5>")
	)
	(segment
		(start 437.364378 -201.690732)
		(end 436.576978 -202.478132)
		(width 0.16002)
		(layer "In6.Cu")
		(net "M_K_CPU0_SA_DQS_DN<5>")
	)
	(segment
		(start 440.695588 -201.85888)
		(end 440.07151 -201.85888)
		(width 0.16002)
		(layer "In6.Cu")
		(net "M_K_CPU0_SA_DQS_DN<5>")
	)
	(segment
		(start 389.170926 -227.739702)
		(end 389.32485 -227.474272)
		(width 0.09525)
		(layer "In6.Cu")
		(net "M_K_CPU0_SA_DQS_DN<5>")
	)
	(segment
		(start 397.765778 -216.42197)
		(end 397.765778 -219.225876)
		(width 0.16002)
		(layer "In6.Cu")
		(net "M_K_CPU0_SA_DQS_DN<5>")
	)
	(segment
		(start 391.024618 -227.804218)
		(end 391.016236 -227.799392)
		(width 0.09525)
		(layer "In6.Cu")
		(net "M_K_CPU0_SA_DQS_DN<5>")
	)
	(segment
		(start 393.77493 -223.731074)
		(end 393.743434 -223.749362)
		(width 0.09525)
		(layer "In6.Cu")
		(net "M_K_CPU0_SA_DQS_DN<5>")
	)
	(segment
		(start 393.93241 -223.142302)
		(end 393.93241 -223.424242)
		(width 0.09525)
		(layer "In6.Cu")
		(net "M_K_CPU0_SA_DQS_DN<5>")
	)
	(segment
		(start 440.777376 -201.777092)
		(end 440.695588 -201.85888)
		(width 0.16002)
		(layer "In6.Cu")
		(net "M_K_CPU0_SA_DQS_DN<5>")
	)
	(segment
		(start 403.49043 -210.697318)
		(end 403.49043 -211.173822)
		(width 0.16002)
		(layer "In6.Cu")
		(net "M_K_CPU0_SA_DQS_DN<5>")
	)
	(segment
		(start 401.74418 -213.121748)
		(end 401.643342 -213.02091)
		(width 0.16002)
		(layer "In6.Cu")
		(net "M_K_CPU0_SA_DQS_DN<5>")
	)
	(segment
		(start 399.470372 -215.395556)
		(end 399.470372 -215.621616)
		(width 0.16002)
		(layer "In6.Cu")
		(net "M_K_CPU0_SA_DQS_DN<5>")
	)
	(segment
		(start 402.54047 -211.647278)
		(end 402.116798 -212.07095)
		(width 0.16002)
		(layer "In6.Cu")
		(net "M_K_CPU0_SA_DQS_DN<5>")
	)
	(segment
		(start 402.116798 -212.07095)
		(end 402.116798 -212.547454)
		(width 0.16002)
		(layer "In6.Cu")
		(net "M_K_CPU0_SA_DQS_DN<5>")
	)
	(segment
		(start 428.048674 -202.857862)
		(end 426.984414 -202.857862)
		(width 0.16002)
		(layer "In6.Cu")
		(net "M_K_CPU0_SA_DQS_DN<5>")
	)
	(segment
		(start 430.879504 -201.690732)
		(end 429.820324 -201.690732)
		(width 0.16002)
		(layer "In6.Cu")
		(net "M_K_CPU0_SA_DQS_DN<5>")
	)
	(segment
		(start 418.590476 -202.007978)
		(end 416.108642 -202.007978)
		(width 0.16002)
		(layer "In6.Cu")
		(net "M_K_CPU0_SA_DQS_DN<5>")
	)
	(segment
		(start 440.07151 -201.85888)
		(end 439.922412 -202.007978)
		(width 0.16002)
		(layer "In6.Cu")
		(net "M_K_CPU0_SA_DQS_DN<5>")
	)
	(segment
		(start 399.222976 -215.869012)
		(end 398.996916 -215.869012)
		(width 0.16002)
		(layer "In6.Cu")
		(net "M_K_CPU0_SA_DQS_DN<5>")
	)
	(segment
		(start 400.743166 -213.921086)
		(end 400.844004 -214.021924)
		(width 0.16002)
		(layer "In6.Cu")
		(net "M_K_CPU0_SA_DQS_DN<5>")
	)
	(segment
		(start 404.717504 -210.374484)
		(end 404.491444 -210.374484)
		(width 0.16002)
		(layer "In6.Cu")
		(net "M_K_CPU0_SA_DQS_DN<5>")
	)
	(segment
		(start 398.996916 -215.869012)
		(end 398.896078 -215.768174)
		(width 0.16002)
		(layer "In6.Cu")
		(net "M_K_CPU0_SA_DQS_DN<5>")
	)
	(segment
		(start 400.26971 -214.394542)
		(end 399.793206 -214.394542)
		(width 0.16002)
		(layer "In6.Cu")
		(net "M_K_CPU0_SA_DQS_DN<5>")
	)
	(segment
		(start 436.576978 -202.478132)
		(end 435.972458 -202.478132)
		(width 0.16002)
		(layer "In6.Cu")
		(net "M_K_CPU0_SA_DQS_DN<5>")
	)
	(segment
		(start 426.984414 -202.857862)
		(end 426.13453 -202.007978)
		(width 0.16002)
		(layer "In6.Cu")
		(net "M_K_CPU0_SA_DQS_DN<5>")
	)
	(segment
		(start 401.97024 -213.121748)
		(end 401.74418 -213.121748)
		(width 0.16002)
		(layer "In6.Cu")
		(net "M_K_CPU0_SA_DQS_DN<5>")
	)
	(segment
		(start 404.390606 -210.273646)
		(end 403.914102 -210.273646)
		(width 0.16002)
		(layer "In6.Cu")
		(net "M_K_CPU0_SA_DQS_DN<5>")
	)
	(segment
		(start 403.591268 -211.50072)
		(end 403.343872 -211.748116)
		(width 0.16002)
		(layer "In6.Cu")
		(net "M_K_CPU0_SA_DQS_DN<5>")
	)
	(segment
		(start 404.9649 -210.127088)
		(end 404.717504 -210.374484)
		(width 0.16002)
		(layer "In6.Cu")
		(net "M_K_CPU0_SA_DQS_DN<5>")
	)
	(segment
		(start 400.596608 -214.49538)
		(end 400.370548 -214.49538)
		(width 0.16002)
		(layer "In6.Cu")
		(net "M_K_CPU0_SA_DQS_DN<5>")
	)
	(segment
		(start 421.48887 -202.478132)
		(end 420.88435 -202.478132)
		(width 0.16002)
		(layer "In6.Cu")
		(net "M_K_CPU0_SA_DQS_DN<5>")
	)
	(segment
		(start 404.864062 -209.80019)
		(end 404.9649 -209.901028)
		(width 0.16002)
		(layer "In6.Cu")
		(net "M_K_CPU0_SA_DQS_DN<5>")
	)
	(segment
		(start 389.19404 -227.826316)
		(end 389.170926 -227.739702)
		(width 0.09525)
		(layer "In6.Cu")
		(net "M_K_CPU0_SA_DQS_DN<5>")
	)
	(segment
		(start 393.46251 -224.253044)
		(end 393.463018 -224.253552)
		(width 0.09525)
		(layer "In6.Cu")
		(net "M_K_CPU0_SA_DQS_DN<5>")
	)
	(segment
		(start 390.453372 -227.799392)
		(end 390.44499 -227.804218)
		(width 0.09525)
		(layer "In6.Cu")
		(net "M_K_CPU0_SA_DQS_DN<5>")
	)
	(segment
		(start 404.9649 -209.901028)
		(end 404.9649 -210.127088)
		(width 0.16002)
		(layer "In6.Cu")
		(net "M_K_CPU0_SA_DQS_DN<5>")
	)
	(arc
		(start 392.998198 -226.671632)
		(mid 392.933647 -226.866801)
		(end 392.775186 -226.997768)
		(width 0.09525)
		(layer "In6.Cu")
		(net "M_K_CPU0_SA_DQS_DN<5>")
	)
	(arc
		(start 392.619738 -227.065332)
		(mid 392.506387 -227.142481)
		(end 392.429238 -227.255832)
		(width 0.09525)
		(layer "In6.Cu")
		(net "M_K_CPU0_SA_DQS_DN<5>")
	)
	(arc
		(start 392.429238 -227.255832)
		(mid 392.315793 -227.454397)
		(end 392.162538 -227.624132)
		(width 0.09525)
		(layer "In6.Cu")
		(net "M_K_CPU0_SA_DQS_DN<5>")
	)
	(arc
		(start 394.415772 -222.61957)
		(mid 394.408506 -222.656006)
		(end 394.387832 -222.68688)
		(width 0.09525)
		(layer "In6.Cu")
		(net "M_K_CPU0_SA_DQS_DN<5>")
	)
	(arc
		(start 389.513318 -227.799392)
		(mid 389.356691 -227.848578)
		(end 389.19404 -227.826316)
		(width 0.09525)
		(layer "In6.Cu")
		(net "M_K_CPU0_SA_DQS_DN<5>")
	)
	(arc
		(start 393.463018 -225.904552)
		(mid 393.405282 -226.05862)
		(end 393.287758 -226.173792)
		(width 0.09525)
		(layer "In6.Cu")
		(net "M_K_CPU0_SA_DQS_DN<5>")
	)
	(arc
		(start 393.287758 -226.173792)
		(mid 393.080981 -226.386649)
		(end 392.998198 -226.671632)
		(width 0.09525)
		(layer "In6.Cu")
		(net "M_K_CPU0_SA_DQS_DN<5>")
	)
	(arc
		(start 391.674858 -227.7237)
		(mid 391.52915 -227.742968)
		(end 391.393426 -227.799392)
		(width 0.09525)
		(layer "In6.Cu")
		(net "M_K_CPU0_SA_DQS_DN<5>")
	)
	(arc
		(start 391.016236 -227.799392)
		(mid 390.734804 -227.723637)
		(end 390.453372 -227.799392)
		(width 0.09525)
		(layer "In6.Cu")
		(net "M_K_CPU0_SA_DQS_DN<5>")
	)
	(arc
		(start 391.393426 -227.799392)
		(mid 391.209651 -227.850164)
		(end 391.024618 -227.804218)
		(width 0.09525)
		(layer "In6.Cu")
		(net "M_K_CPU0_SA_DQS_DN<5>")
	)
	(arc
		(start 390.44499 -227.804218)
		(mid 390.259958 -227.850132)
		(end 390.076182 -227.799392)
		(width 0.09525)
		(layer "In6.Cu")
		(net "M_K_CPU0_SA_DQS_DN<5>")
	)
	(arc
		(start 393.705334 -223.77146)
		(mid 393.526884 -223.97293)
		(end 393.46251 -224.234248)
		(width 0.09525)
		(layer "In6.Cu")
		(net "M_K_CPU0_SA_DQS_DN<5>")
	)
	(arc
		(start 393.93241 -223.424242)
		(mid 393.890745 -223.596689)
		(end 393.77493 -223.731074)
		(width 0.09525)
		(layer "In6.Cu")
		(net "M_K_CPU0_SA_DQS_DN<5>")
	)
	(arc
		(start 390.076182 -227.799392)
		(mid 389.79475 -227.723637)
		(end 389.513318 -227.799392)
		(width 0.09525)
		(layer "In6.Cu")
		(net "M_K_CPU0_SA_DQS_DN<5>")
	)
	(arc
		(start 392.162538 -227.624132)
		(mid 392.040883 -227.697975)
		(end 391.900918 -227.7237)
		(width 0.09525)
		(layer "In6.Cu")
		(net "M_K_CPU0_SA_DQS_DN<5>")
	)
	(segment
		(start 389.798052 -247.1801)
		(end 390.264904 -246.914162)
		(width 0.12954)
		(layer "F.Cu")
		(net "M_K_CPU0_SA_DQS_DN<4>")
	)
	(segment
		(start 395.859254 -246.62892)
		(end 396.243302 -246.244872)
		(width 0.16002)
		(layer "In6.Cu")
		(net "M_K_CPU0_SA_DQS_DN<4>")
	)
	(segment
		(start 440.811158 -238.28629)
		(end 443.021974 -238.28629)
		(width 0.16002)
		(layer "In6.Cu")
		(net "M_K_CPU0_SA_DQS_DN<4>")
	)
	(segment
		(start 435.758082 -238.562134)
		(end 436.098696 -238.902748)
		(width 0.16002)
		(layer "In6.Cu")
		(net "M_K_CPU0_SA_DQS_DN<4>")
	)
	(segment
		(start 390.264904 -246.914162)
		(end 390.418828 -246.648732)
		(width 0.09525)
		(layer "In6.Cu")
		(net "M_K_CPU0_SA_DQS_DN<4>")
	)
	(segment
		(start 438.329578 -237.71225)
		(end 440.237118 -237.71225)
		(width 0.16002)
		(layer "In6.Cu")
		(net "M_K_CPU0_SA_DQS_DN<4>")
	)
	(segment
		(start 436.098696 -238.902748)
		(end 436.75046 -238.902748)
		(width 0.16002)
		(layer "In6.Cu")
		(net "M_K_CPU0_SA_DQS_DN<4>")
	)
	(segment
		(start 430.445926 -238.051848)
		(end 430.785524 -237.71225)
		(width 0.16002)
		(layer "In6.Cu")
		(net "M_K_CPU0_SA_DQS_DN<4>")
	)
	(segment
		(start 444.475108 -238.711232)
		(end 446.370456 -238.711232)
		(width 0.16002)
		(layer "In6.Cu")
		(net "M_K_CPU0_SA_DQS_DN<4>")
	)
	(segment
		(start 404.991824 -246.244872)
		(end 412.333948 -238.902748)
		(width 0.16002)
		(layer "In6.Cu")
		(net "M_K_CPU0_SA_DQS_DN<4>")
	)
	(segment
		(start 395.459204 -246.94515)
		(end 395.75867 -246.645684)
		(width 0.09525)
		(layer "In6.Cu")
		(net "M_K_CPU0_SA_DQS_DN<4>")
	)
	(segment
		(start 394.4239 -246.94515)
		(end 395.459204 -246.94515)
		(width 0.09525)
		(layer "In6.Cu")
		(net "M_K_CPU0_SA_DQS_DN<4>")
	)
	(segment
		(start 392.332972 -246.589042)
		(end 392.343386 -246.595138)
		(width 0.09525)
		(layer "In6.Cu")
		(net "M_K_CPU0_SA_DQS_DN<4>")
	)
	(segment
		(start 430.057306 -238.051848)
		(end 430.445926 -238.051848)
		(width 0.16002)
		(layer "In6.Cu")
		(net "M_K_CPU0_SA_DQS_DN<4>")
	)
	(segment
		(start 414.118298 -238.902748)
		(end 414.969198 -238.051848)
		(width 0.16002)
		(layer "In6.Cu")
		(net "M_K_CPU0_SA_DQS_DN<4>")
	)
	(segment
		(start 440.237118 -237.71225)
		(end 440.811158 -238.28629)
		(width 0.16002)
		(layer "In6.Cu")
		(net "M_K_CPU0_SA_DQS_DN<4>")
	)
	(segment
		(start 446.370456 -238.711232)
		(end 446.644268 -238.985044)
		(width 0.16002)
		(layer "In6.Cu")
		(net "M_K_CPU0_SA_DQS_DN<4>")
	)
	(segment
		(start 437.98998 -238.051848)
		(end 438.329578 -237.71225)
		(width 0.16002)
		(layer "In6.Cu")
		(net "M_K_CPU0_SA_DQS_DN<4>")
	)
	(segment
		(start 432.498246 -237.71225)
		(end 433.34813 -238.562134)
		(width 0.16002)
		(layer "In6.Cu")
		(net "M_K_CPU0_SA_DQS_DN<4>")
	)
	(segment
		(start 391.945622 -246.595138)
		(end 391.956036 -246.589042)
		(width 0.09525)
		(layer "In6.Cu")
		(net "M_K_CPU0_SA_DQS_DN<4>")
	)
	(segment
		(start 425.804076 -238.562134)
		(end 428.214028 -238.562134)
		(width 0.16002)
		(layer "In6.Cu")
		(net "M_K_CPU0_SA_DQS_DN<4>")
	)
	(segment
		(start 443.646052 -238.910368)
		(end 444.275972 -238.910368)
		(width 0.16002)
		(layer "In6.Cu")
		(net "M_K_CPU0_SA_DQS_DN<4>")
	)
	(segment
		(start 395.75867 -246.645684)
		(end 395.84249 -246.645684)
		(width 0.09525)
		(layer "In6.Cu")
		(net "M_K_CPU0_SA_DQS_DN<4>")
	)
	(segment
		(start 412.333948 -238.902748)
		(end 414.118298 -238.902748)
		(width 0.16002)
		(layer "In6.Cu")
		(net "M_K_CPU0_SA_DQS_DN<4>")
	)
	(segment
		(start 429.206406 -238.902748)
		(end 430.057306 -238.051848)
		(width 0.16002)
		(layer "In6.Cu")
		(net "M_K_CPU0_SA_DQS_DN<4>")
	)
	(segment
		(start 390.418828 -246.648732)
		(end 390.519666 -246.622062)
		(width 0.09525)
		(layer "In6.Cu")
		(net "M_K_CPU0_SA_DQS_DN<4>")
	)
	(segment
		(start 430.785524 -237.71225)
		(end 432.498246 -237.71225)
		(width 0.16002)
		(layer "In6.Cu")
		(net "M_K_CPU0_SA_DQS_DN<4>")
	)
	(segment
		(start 424.954192 -237.71225)
		(end 425.804076 -238.562134)
		(width 0.16002)
		(layer "In6.Cu")
		(net "M_K_CPU0_SA_DQS_DN<4>")
	)
	(segment
		(start 444.275972 -238.910368)
		(end 444.475108 -238.711232)
		(width 0.16002)
		(layer "In6.Cu")
		(net "M_K_CPU0_SA_DQS_DN<4>")
	)
	(segment
		(start 417.410138 -237.71225)
		(end 418.260022 -238.562134)
		(width 0.16002)
		(layer "In6.Cu")
		(net "M_K_CPU0_SA_DQS_DN<4>")
	)
	(segment
		(start 396.243302 -246.244872)
		(end 404.991824 -246.244872)
		(width 0.16002)
		(layer "In6.Cu")
		(net "M_K_CPU0_SA_DQS_DN<4>")
	)
	(segment
		(start 421.010588 -238.902748)
		(end 421.662352 -238.902748)
		(width 0.16002)
		(layer "In6.Cu")
		(net "M_K_CPU0_SA_DQS_DN<4>")
	)
	(segment
		(start 428.214028 -238.562134)
		(end 428.554642 -238.902748)
		(width 0.16002)
		(layer "In6.Cu")
		(net "M_K_CPU0_SA_DQS_DN<4>")
	)
	(segment
		(start 414.969198 -238.051848)
		(end 415.357818 -238.051848)
		(width 0.16002)
		(layer "In6.Cu")
		(net "M_K_CPU0_SA_DQS_DN<4>")
	)
	(segment
		(start 415.357818 -238.051848)
		(end 415.697416 -237.71225)
		(width 0.16002)
		(layer "In6.Cu")
		(net "M_K_CPU0_SA_DQS_DN<4>")
	)
	(segment
		(start 428.554642 -238.902748)
		(end 429.206406 -238.902748)
		(width 0.16002)
		(layer "In6.Cu")
		(net "M_K_CPU0_SA_DQS_DN<4>")
	)
	(segment
		(start 391.016236 -246.589042)
		(end 391.024618 -246.584216)
		(width 0.09525)
		(layer "In6.Cu")
		(net "M_K_CPU0_SA_DQS_DN<4>")
	)
	(segment
		(start 433.34813 -238.562134)
		(end 435.758082 -238.562134)
		(width 0.16002)
		(layer "In6.Cu")
		(net "M_K_CPU0_SA_DQS_DN<4>")
	)
	(segment
		(start 415.697416 -237.71225)
		(end 417.410138 -237.71225)
		(width 0.16002)
		(layer "In6.Cu")
		(net "M_K_CPU0_SA_DQS_DN<4>")
	)
	(segment
		(start 393.52982 -246.650764)
		(end 394.129514 -246.650764)
		(width 0.09525)
		(layer "In6.Cu")
		(net "M_K_CPU0_SA_DQS_DN<4>")
	)
	(segment
		(start 436.75046 -238.902748)
		(end 437.60136 -238.051848)
		(width 0.16002)
		(layer "In6.Cu")
		(net "M_K_CPU0_SA_DQS_DN<4>")
	)
	(segment
		(start 422.513252 -238.051848)
		(end 422.901872 -238.051848)
		(width 0.16002)
		(layer "In6.Cu")
		(net "M_K_CPU0_SA_DQS_DN<4>")
	)
	(segment
		(start 395.84249 -246.645684)
		(end 395.859254 -246.62892)
		(width 0.09525)
		(layer "In6.Cu")
		(net "M_K_CPU0_SA_DQS_DN<4>")
	)
	(segment
		(start 418.260022 -238.562134)
		(end 420.669974 -238.562134)
		(width 0.16002)
		(layer "In6.Cu")
		(net "M_K_CPU0_SA_DQS_DN<4>")
	)
	(segment
		(start 443.021974 -238.28629)
		(end 443.646052 -238.910368)
		(width 0.16002)
		(layer "In6.Cu")
		(net "M_K_CPU0_SA_DQS_DN<4>")
	)
	(segment
		(start 421.662352 -238.902748)
		(end 422.513252 -238.051848)
		(width 0.16002)
		(layer "In6.Cu")
		(net "M_K_CPU0_SA_DQS_DN<4>")
	)
	(segment
		(start 422.901872 -238.051848)
		(end 423.24147 -237.71225)
		(width 0.16002)
		(layer "In6.Cu")
		(net "M_K_CPU0_SA_DQS_DN<4>")
	)
	(segment
		(start 394.129514 -246.650764)
		(end 394.4239 -246.94515)
		(width 0.09525)
		(layer "In6.Cu")
		(net "M_K_CPU0_SA_DQS_DN<4>")
	)
	(segment
		(start 437.60136 -238.051848)
		(end 437.98998 -238.051848)
		(width 0.16002)
		(layer "In6.Cu")
		(net "M_K_CPU0_SA_DQS_DN<4>")
	)
	(segment
		(start 423.24147 -237.71225)
		(end 424.954192 -237.71225)
		(width 0.16002)
		(layer "In6.Cu")
		(net "M_K_CPU0_SA_DQS_DN<4>")
	)
	(segment
		(start 420.669974 -238.562134)
		(end 421.010588 -238.902748)
		(width 0.16002)
		(layer "In6.Cu")
		(net "M_K_CPU0_SA_DQS_DN<4>")
	)
	(arc
		(start 392.89609 -246.589042)
		(mid 393.077706 -246.538305)
		(end 393.261088 -246.582184)
		(width 0.09525)
		(layer "In6.Cu")
		(net "M_K_CPU0_SA_DQS_DN<4>")
	)
	(arc
		(start 392.343386 -246.595138)
		(mid 392.620548 -246.664938)
		(end 392.89609 -246.589042)
		(width 0.09525)
		(layer "In6.Cu")
		(net "M_K_CPU0_SA_DQS_DN<4>")
	)
	(arc
		(start 390.519666 -246.622062)
		(mid 390.529534 -246.626093)
		(end 390.539478 -246.629936)
		(width 0.09525)
		(layer "In6.Cu")
		(net "M_K_CPU0_SA_DQS_DN<4>")
	)
	(arc
		(start 393.261088 -246.582184)
		(mid 393.391148 -246.633346)
		(end 393.52982 -246.650764)
		(width 0.09525)
		(layer "In6.Cu")
		(net "M_K_CPU0_SA_DQS_DN<4>")
	)
	(arc
		(start 391.024618 -246.584216)
		(mid 391.20965 -246.538302)
		(end 391.393426 -246.589042)
		(width 0.09525)
		(layer "In6.Cu")
		(net "M_K_CPU0_SA_DQS_DN<4>")
	)
	(arc
		(start 390.539478 -246.629936)
		(mid 390.782442 -246.662923)
		(end 391.016236 -246.589042)
		(width 0.09525)
		(layer "In6.Cu")
		(net "M_K_CPU0_SA_DQS_DN<4>")
	)
	(arc
		(start 391.956036 -246.589042)
		(mid 392.144504 -246.538365)
		(end 392.332972 -246.589042)
		(width 0.09525)
		(layer "In6.Cu")
		(net "M_K_CPU0_SA_DQS_DN<4>")
	)
	(arc
		(start 391.393426 -246.589042)
		(mid 391.668715 -246.664763)
		(end 391.945622 -246.595138)
		(width 0.09525)
		(layer "In6.Cu")
		(net "M_K_CPU0_SA_DQS_DN<4>")
	)
	(segment
		(start 389.798052 -242.320064)
		(end 390.264904 -242.054126)
		(width 0.12954)
		(layer "F.Cu")
		(net "M_K_CPU0_SA_DQS_DN<3>")
	)
	(segment
		(start 443.021974 -228.936296)
		(end 443.646052 -229.560374)
		(width 0.16002)
		(layer "In6.Cu")
		(net "M_K_CPU0_SA_DQS_DN<3>")
	)
	(segment
		(start 430.785524 -228.362256)
		(end 432.498246 -228.362256)
		(width 0.16002)
		(layer "In6.Cu")
		(net "M_K_CPU0_SA_DQS_DN<3>")
	)
	(segment
		(start 391.016236 -241.729006)
		(end 391.024618 -241.72418)
		(width 0.09525)
		(layer "In6.Cu")
		(net "M_K_CPU0_SA_DQS_DN<3>")
	)
	(segment
		(start 435.758082 -229.21214)
		(end 436.098696 -229.552754)
		(width 0.16002)
		(layer "In6.Cu")
		(net "M_K_CPU0_SA_DQS_DN<3>")
	)
	(segment
		(start 422.901872 -228.701854)
		(end 423.24147 -228.362256)
		(width 0.16002)
		(layer "In6.Cu")
		(net "M_K_CPU0_SA_DQS_DN<3>")
	)
	(segment
		(start 421.662352 -229.552754)
		(end 422.513252 -228.701854)
		(width 0.16002)
		(layer "In6.Cu")
		(net "M_K_CPU0_SA_DQS_DN<3>")
	)
	(segment
		(start 433.34813 -229.21214)
		(end 435.758082 -229.21214)
		(width 0.16002)
		(layer "In6.Cu")
		(net "M_K_CPU0_SA_DQS_DN<3>")
	)
	(segment
		(start 394.525246 -241.11331)
		(end 395.036294 -241.11331)
		(width 0.09525)
		(layer "In6.Cu")
		(net "M_K_CPU0_SA_DQS_DN<3>")
	)
	(segment
		(start 446.370456 -229.361238)
		(end 446.644268 -229.63505)
		(width 0.16002)
		(layer "In6.Cu")
		(net "M_K_CPU0_SA_DQS_DN<3>")
	)
	(segment
		(start 391.945622 -241.735102)
		(end 391.956036 -241.729006)
		(width 0.09525)
		(layer "In6.Cu")
		(net "M_K_CPU0_SA_DQS_DN<3>")
	)
	(segment
		(start 417.410138 -228.362256)
		(end 418.260022 -229.21214)
		(width 0.16002)
		(layer "In6.Cu")
		(net "M_K_CPU0_SA_DQS_DN<3>")
	)
	(segment
		(start 429.206406 -229.552754)
		(end 430.057306 -228.701854)
		(width 0.16002)
		(layer "In6.Cu")
		(net "M_K_CPU0_SA_DQS_DN<3>")
	)
	(segment
		(start 395.036294 -241.11331)
		(end 395.581632 -240.567972)
		(width 0.09525)
		(layer "In6.Cu")
		(net "M_K_CPU0_SA_DQS_DN<3>")
	)
	(segment
		(start 414.118298 -229.552754)
		(end 414.969198 -228.701854)
		(width 0.16002)
		(layer "In6.Cu")
		(net "M_K_CPU0_SA_DQS_DN<3>")
	)
	(segment
		(start 415.357818 -228.701854)
		(end 415.697416 -228.362256)
		(width 0.16002)
		(layer "In6.Cu")
		(net "M_K_CPU0_SA_DQS_DN<3>")
	)
	(segment
		(start 425.804076 -229.21214)
		(end 428.214028 -229.21214)
		(width 0.16002)
		(layer "In6.Cu")
		(net "M_K_CPU0_SA_DQS_DN<3>")
	)
	(segment
		(start 390.264904 -242.054126)
		(end 390.418828 -241.788696)
		(width 0.09525)
		(layer "In6.Cu")
		(net "M_K_CPU0_SA_DQS_DN<3>")
	)
	(segment
		(start 407.450798 -235.575348)
		(end 407.450798 -233.545888)
		(width 0.16002)
		(layer "In6.Cu")
		(net "M_K_CPU0_SA_DQS_DN<3>")
	)
	(segment
		(start 440.237118 -228.362256)
		(end 440.811158 -228.936296)
		(width 0.16002)
		(layer "In6.Cu")
		(net "M_K_CPU0_SA_DQS_DN<3>")
	)
	(segment
		(start 444.275972 -229.560374)
		(end 444.475108 -229.361238)
		(width 0.16002)
		(layer "In6.Cu")
		(net "M_K_CPU0_SA_DQS_DN<3>")
	)
	(segment
		(start 443.646052 -229.560374)
		(end 444.275972 -229.560374)
		(width 0.16002)
		(layer "In6.Cu")
		(net "M_K_CPU0_SA_DQS_DN<3>")
	)
	(segment
		(start 393.084812 -241.677444)
		(end 393.961112 -241.677444)
		(width 0.09525)
		(layer "In6.Cu")
		(net "M_K_CPU0_SA_DQS_DN<3>")
	)
	(segment
		(start 402.399246 -240.6269)
		(end 407.450798 -235.575348)
		(width 0.16002)
		(layer "In6.Cu")
		(net "M_K_CPU0_SA_DQS_DN<3>")
	)
	(segment
		(start 422.513252 -228.701854)
		(end 422.901872 -228.701854)
		(width 0.16002)
		(layer "In6.Cu")
		(net "M_K_CPU0_SA_DQS_DN<3>")
	)
	(segment
		(start 436.75046 -229.552754)
		(end 437.60136 -228.701854)
		(width 0.16002)
		(layer "In6.Cu")
		(net "M_K_CPU0_SA_DQS_DN<3>")
	)
	(segment
		(start 437.98998 -228.701854)
		(end 438.329578 -228.362256)
		(width 0.16002)
		(layer "In6.Cu")
		(net "M_K_CPU0_SA_DQS_DN<3>")
	)
	(segment
		(start 437.60136 -228.701854)
		(end 437.98998 -228.701854)
		(width 0.16002)
		(layer "In6.Cu")
		(net "M_K_CPU0_SA_DQS_DN<3>")
	)
	(segment
		(start 395.776704 -240.567972)
		(end 395.835632 -240.6269)
		(width 0.09525)
		(layer "In6.Cu")
		(net "M_K_CPU0_SA_DQS_DN<3>")
	)
	(segment
		(start 395.859254 -240.6269)
		(end 402.399246 -240.6269)
		(width 0.16002)
		(layer "In6.Cu")
		(net "M_K_CPU0_SA_DQS_DN<3>")
	)
	(segment
		(start 436.098696 -229.552754)
		(end 436.75046 -229.552754)
		(width 0.16002)
		(layer "In6.Cu")
		(net "M_K_CPU0_SA_DQS_DN<3>")
	)
	(segment
		(start 392.332972 -241.729006)
		(end 392.343386 -241.735102)
		(width 0.09525)
		(layer "In6.Cu")
		(net "M_K_CPU0_SA_DQS_DN<3>")
	)
	(segment
		(start 411.443932 -229.552754)
		(end 414.118298 -229.552754)
		(width 0.16002)
		(layer "In6.Cu")
		(net "M_K_CPU0_SA_DQS_DN<3>")
	)
	(segment
		(start 414.969198 -228.701854)
		(end 415.357818 -228.701854)
		(width 0.16002)
		(layer "In6.Cu")
		(net "M_K_CPU0_SA_DQS_DN<3>")
	)
	(segment
		(start 424.954192 -228.362256)
		(end 425.804076 -229.21214)
		(width 0.16002)
		(layer "In6.Cu")
		(net "M_K_CPU0_SA_DQS_DN<3>")
	)
	(segment
		(start 418.260022 -229.21214)
		(end 420.669974 -229.21214)
		(width 0.16002)
		(layer "In6.Cu")
		(net "M_K_CPU0_SA_DQS_DN<3>")
	)
	(segment
		(start 423.24147 -228.362256)
		(end 424.954192 -228.362256)
		(width 0.16002)
		(layer "In6.Cu")
		(net "M_K_CPU0_SA_DQS_DN<3>")
	)
	(segment
		(start 390.418828 -241.788696)
		(end 390.519666 -241.762026)
		(width 0.09525)
		(layer "In6.Cu")
		(net "M_K_CPU0_SA_DQS_DN<3>")
	)
	(segment
		(start 393.961112 -241.677444)
		(end 394.525246 -241.11331)
		(width 0.09525)
		(layer "In6.Cu")
		(net "M_K_CPU0_SA_DQS_DN<3>")
	)
	(segment
		(start 415.697416 -228.362256)
		(end 417.410138 -228.362256)
		(width 0.16002)
		(layer "In6.Cu")
		(net "M_K_CPU0_SA_DQS_DN<3>")
	)
	(segment
		(start 432.498246 -228.362256)
		(end 433.34813 -229.21214)
		(width 0.16002)
		(layer "In6.Cu")
		(net "M_K_CPU0_SA_DQS_DN<3>")
	)
	(segment
		(start 428.214028 -229.21214)
		(end 428.554642 -229.552754)
		(width 0.16002)
		(layer "In6.Cu")
		(net "M_K_CPU0_SA_DQS_DN<3>")
	)
	(segment
		(start 444.475108 -229.361238)
		(end 446.370456 -229.361238)
		(width 0.16002)
		(layer "In6.Cu")
		(net "M_K_CPU0_SA_DQS_DN<3>")
	)
	(segment
		(start 420.669974 -229.21214)
		(end 421.010588 -229.552754)
		(width 0.16002)
		(layer "In6.Cu")
		(net "M_K_CPU0_SA_DQS_DN<3>")
	)
	(segment
		(start 395.581632 -240.567972)
		(end 395.776704 -240.567972)
		(width 0.09525)
		(layer "In6.Cu")
		(net "M_K_CPU0_SA_DQS_DN<3>")
	)
	(segment
		(start 407.450798 -233.545888)
		(end 411.443932 -229.552754)
		(width 0.16002)
		(layer "In6.Cu")
		(net "M_K_CPU0_SA_DQS_DN<3>")
	)
	(segment
		(start 428.554642 -229.552754)
		(end 429.206406 -229.552754)
		(width 0.16002)
		(layer "In6.Cu")
		(net "M_K_CPU0_SA_DQS_DN<3>")
	)
	(segment
		(start 395.835632 -240.6269)
		(end 395.859254 -240.6269)
		(width 0.09525)
		(layer "In6.Cu")
		(net "M_K_CPU0_SA_DQS_DN<3>")
	)
	(segment
		(start 440.811158 -228.936296)
		(end 443.021974 -228.936296)
		(width 0.16002)
		(layer "In6.Cu")
		(net "M_K_CPU0_SA_DQS_DN<3>")
	)
	(segment
		(start 438.329578 -228.362256)
		(end 440.237118 -228.362256)
		(width 0.16002)
		(layer "In6.Cu")
		(net "M_K_CPU0_SA_DQS_DN<3>")
	)
	(segment
		(start 421.010588 -229.552754)
		(end 421.662352 -229.552754)
		(width 0.16002)
		(layer "In6.Cu")
		(net "M_K_CPU0_SA_DQS_DN<3>")
	)
	(segment
		(start 430.445926 -228.701854)
		(end 430.785524 -228.362256)
		(width 0.16002)
		(layer "In6.Cu")
		(net "M_K_CPU0_SA_DQS_DN<3>")
	)
	(segment
		(start 430.057306 -228.701854)
		(end 430.445926 -228.701854)
		(width 0.16002)
		(layer "In6.Cu")
		(net "M_K_CPU0_SA_DQS_DN<3>")
	)
	(arc
		(start 390.519666 -241.762026)
		(mid 390.771807 -241.803596)
		(end 391.016236 -241.729006)
		(width 0.09525)
		(layer "In6.Cu")
		(net "M_K_CPU0_SA_DQS_DN<3>")
	)
	(arc
		(start 392.89609 -241.729006)
		(mid 392.987036 -241.690705)
		(end 393.084812 -241.677444)
		(width 0.09525)
		(layer "In6.Cu")
		(net "M_K_CPU0_SA_DQS_DN<3>")
	)
	(arc
		(start 391.956036 -241.729006)
		(mid 392.144504 -241.678329)
		(end 392.332972 -241.729006)
		(width 0.09525)
		(layer "In6.Cu")
		(net "M_K_CPU0_SA_DQS_DN<3>")
	)
	(arc
		(start 391.393426 -241.729006)
		(mid 391.668715 -241.804727)
		(end 391.945622 -241.735102)
		(width 0.09525)
		(layer "In6.Cu")
		(net "M_K_CPU0_SA_DQS_DN<3>")
	)
	(arc
		(start 391.024618 -241.72418)
		(mid 391.20965 -241.678266)
		(end 391.393426 -241.729006)
		(width 0.09525)
		(layer "In6.Cu")
		(net "M_K_CPU0_SA_DQS_DN<3>")
	)
	(arc
		(start 392.343386 -241.735102)
		(mid 392.620548 -241.804902)
		(end 392.89609 -241.729006)
		(width 0.09525)
		(layer "In6.Cu")
		(net "M_K_CPU0_SA_DQS_DN<3>")
	)
	(segment
		(start 389.798052 -237.460028)
		(end 390.264904 -237.19409)
		(width 0.12954)
		(layer "F.Cu")
		(net "M_K_CPU0_SA_DQS_DN<2>")
	)
	(segment
		(start 391.016236 -236.86897)
		(end 391.024618 -236.864144)
		(width 0.09525)
		(layer "In6.Cu")
		(net "M_K_CPU0_SA_DQS_DN<2>")
	)
	(segment
		(start 443.021974 -219.586302)
		(end 443.646052 -220.21038)
		(width 0.16002)
		(layer "In6.Cu")
		(net "M_K_CPU0_SA_DQS_DN<2>")
	)
	(segment
		(start 393.084812 -236.817408)
		(end 393.41044 -236.817408)
		(width 0.09525)
		(layer "In6.Cu")
		(net "M_K_CPU0_SA_DQS_DN<2>")
	)
	(segment
		(start 394.571728 -235.65612)
		(end 394.869416 -235.65612)
		(width 0.09525)
		(layer "In6.Cu")
		(net "M_K_CPU0_SA_DQS_DN<2>")
	)
	(segment
		(start 390.264904 -237.19409)
		(end 390.418828 -236.92866)
		(width 0.09525)
		(layer "In6.Cu")
		(net "M_K_CPU0_SA_DQS_DN<2>")
	)
	(segment
		(start 430.785524 -219.012262)
		(end 432.498246 -219.012262)
		(width 0.16002)
		(layer "In6.Cu")
		(net "M_K_CPU0_SA_DQS_DN<2>")
	)
	(segment
		(start 446.370456 -220.011244)
		(end 446.644268 -220.285056)
		(width 0.16002)
		(layer "In6.Cu")
		(net "M_K_CPU0_SA_DQS_DN<2>")
	)
	(segment
		(start 437.98998 -219.35186)
		(end 438.329578 -219.012262)
		(width 0.16002)
		(layer "In6.Cu")
		(net "M_K_CPU0_SA_DQS_DN<2>")
	)
	(segment
		(start 422.513252 -219.35186)
		(end 422.901872 -219.35186)
		(width 0.16002)
		(layer "In6.Cu")
		(net "M_K_CPU0_SA_DQS_DN<2>")
	)
	(segment
		(start 418.260022 -219.862146)
		(end 420.669974 -219.862146)
		(width 0.16002)
		(layer "In6.Cu")
		(net "M_K_CPU0_SA_DQS_DN<2>")
	)
	(segment
		(start 417.410138 -219.012262)
		(end 418.260022 -219.862146)
		(width 0.16002)
		(layer "In6.Cu")
		(net "M_K_CPU0_SA_DQS_DN<2>")
	)
	(segment
		(start 421.662352 -220.20276)
		(end 422.513252 -219.35186)
		(width 0.16002)
		(layer "In6.Cu")
		(net "M_K_CPU0_SA_DQS_DN<2>")
	)
	(segment
		(start 422.901872 -219.35186)
		(end 423.24147 -219.012262)
		(width 0.16002)
		(layer "In6.Cu")
		(net "M_K_CPU0_SA_DQS_DN<2>")
	)
	(segment
		(start 409.350718 -222.832422)
		(end 411.98038 -220.20276)
		(width 0.16002)
		(layer "In6.Cu")
		(net "M_K_CPU0_SA_DQS_DN<2>")
	)
	(segment
		(start 438.329578 -219.012262)
		(end 440.237118 -219.012262)
		(width 0.16002)
		(layer "In6.Cu")
		(net "M_K_CPU0_SA_DQS_DN<2>")
	)
	(segment
		(start 415.697416 -219.012262)
		(end 417.410138 -219.012262)
		(width 0.16002)
		(layer "In6.Cu")
		(net "M_K_CPU0_SA_DQS_DN<2>")
	)
	(segment
		(start 392.332972 -236.86897)
		(end 392.343386 -236.875066)
		(width 0.09525)
		(layer "In6.Cu")
		(net "M_K_CPU0_SA_DQS_DN<2>")
	)
	(segment
		(start 425.804076 -219.862146)
		(end 428.214028 -219.862146)
		(width 0.16002)
		(layer "In6.Cu")
		(net "M_K_CPU0_SA_DQS_DN<2>")
	)
	(segment
		(start 437.60136 -219.35186)
		(end 437.98998 -219.35186)
		(width 0.16002)
		(layer "In6.Cu")
		(net "M_K_CPU0_SA_DQS_DN<2>")
	)
	(segment
		(start 424.954192 -219.012262)
		(end 425.804076 -219.862146)
		(width 0.16002)
		(layer "In6.Cu")
		(net "M_K_CPU0_SA_DQS_DN<2>")
	)
	(segment
		(start 414.969198 -219.35186)
		(end 415.357818 -219.35186)
		(width 0.16002)
		(layer "In6.Cu")
		(net "M_K_CPU0_SA_DQS_DN<2>")
	)
	(segment
		(start 420.669974 -219.862146)
		(end 421.010588 -220.20276)
		(width 0.16002)
		(layer "In6.Cu")
		(net "M_K_CPU0_SA_DQS_DN<2>")
	)
	(segment
		(start 391.945622 -236.875066)
		(end 391.956036 -236.86897)
		(width 0.09525)
		(layer "In6.Cu")
		(net "M_K_CPU0_SA_DQS_DN<2>")
	)
	(segment
		(start 390.418828 -236.92866)
		(end 390.519666 -236.90199)
		(width 0.09525)
		(layer "In6.Cu")
		(net "M_K_CPU0_SA_DQS_DN<2>")
	)
	(segment
		(start 444.275972 -220.21038)
		(end 444.475108 -220.011244)
		(width 0.16002)
		(layer "In6.Cu")
		(net "M_K_CPU0_SA_DQS_DN<2>")
	)
	(segment
		(start 415.357818 -219.35186)
		(end 415.697416 -219.012262)
		(width 0.16002)
		(layer "In6.Cu")
		(net "M_K_CPU0_SA_DQS_DN<2>")
	)
	(segment
		(start 395.859254 -235.0008)
		(end 397.86306 -235.0008)
		(width 0.16002)
		(layer "In6.Cu")
		(net "M_K_CPU0_SA_DQS_DN<2>")
	)
	(segment
		(start 429.206406 -220.20276)
		(end 430.057306 -219.35186)
		(width 0.16002)
		(layer "In6.Cu")
		(net "M_K_CPU0_SA_DQS_DN<2>")
	)
	(segment
		(start 436.098696 -220.20276)
		(end 436.75046 -220.20276)
		(width 0.16002)
		(layer "In6.Cu")
		(net "M_K_CPU0_SA_DQS_DN<2>")
	)
	(segment
		(start 444.475108 -220.011244)
		(end 446.370456 -220.011244)
		(width 0.16002)
		(layer "In6.Cu")
		(net "M_K_CPU0_SA_DQS_DN<2>")
	)
	(segment
		(start 436.75046 -220.20276)
		(end 437.60136 -219.35186)
		(width 0.16002)
		(layer "In6.Cu")
		(net "M_K_CPU0_SA_DQS_DN<2>")
	)
	(segment
		(start 440.237118 -219.012262)
		(end 440.811158 -219.586302)
		(width 0.16002)
		(layer "In6.Cu")
		(net "M_K_CPU0_SA_DQS_DN<2>")
	)
	(segment
		(start 394.869416 -235.65612)
		(end 395.583664 -234.941872)
		(width 0.09525)
		(layer "In6.Cu")
		(net "M_K_CPU0_SA_DQS_DN<2>")
	)
	(segment
		(start 409.350718 -223.513142)
		(end 409.350718 -222.832422)
		(width 0.16002)
		(layer "In6.Cu")
		(net "M_K_CPU0_SA_DQS_DN<2>")
	)
	(segment
		(start 443.646052 -220.21038)
		(end 444.275972 -220.21038)
		(width 0.16002)
		(layer "In6.Cu")
		(net "M_K_CPU0_SA_DQS_DN<2>")
	)
	(segment
		(start 393.41044 -236.817408)
		(end 394.571728 -235.65612)
		(width 0.09525)
		(layer "In6.Cu")
		(net "M_K_CPU0_SA_DQS_DN<2>")
	)
	(segment
		(start 432.498246 -219.012262)
		(end 433.34813 -219.862146)
		(width 0.16002)
		(layer "In6.Cu")
		(net "M_K_CPU0_SA_DQS_DN<2>")
	)
	(segment
		(start 421.010588 -220.20276)
		(end 421.662352 -220.20276)
		(width 0.16002)
		(layer "In6.Cu")
		(net "M_K_CPU0_SA_DQS_DN<2>")
	)
	(segment
		(start 440.811158 -219.586302)
		(end 443.021974 -219.586302)
		(width 0.16002)
		(layer "In6.Cu")
		(net "M_K_CPU0_SA_DQS_DN<2>")
	)
	(segment
		(start 428.554642 -220.20276)
		(end 429.206406 -220.20276)
		(width 0.16002)
		(layer "In6.Cu")
		(net "M_K_CPU0_SA_DQS_DN<2>")
	)
	(segment
		(start 430.445926 -219.35186)
		(end 430.785524 -219.012262)
		(width 0.16002)
		(layer "In6.Cu")
		(net "M_K_CPU0_SA_DQS_DN<2>")
	)
	(segment
		(start 395.776704 -234.941872)
		(end 395.835632 -235.0008)
		(width 0.09525)
		(layer "In6.Cu")
		(net "M_K_CPU0_SA_DQS_DN<2>")
	)
	(segment
		(start 423.24147 -219.012262)
		(end 424.954192 -219.012262)
		(width 0.16002)
		(layer "In6.Cu")
		(net "M_K_CPU0_SA_DQS_DN<2>")
	)
	(segment
		(start 414.118298 -220.20276)
		(end 414.969198 -219.35186)
		(width 0.16002)
		(layer "In6.Cu")
		(net "M_K_CPU0_SA_DQS_DN<2>")
	)
	(segment
		(start 395.835632 -235.0008)
		(end 395.859254 -235.0008)
		(width 0.09525)
		(layer "In6.Cu")
		(net "M_K_CPU0_SA_DQS_DN<2>")
	)
	(segment
		(start 435.758082 -219.862146)
		(end 436.098696 -220.20276)
		(width 0.16002)
		(layer "In6.Cu")
		(net "M_K_CPU0_SA_DQS_DN<2>")
	)
	(segment
		(start 433.34813 -219.862146)
		(end 435.758082 -219.862146)
		(width 0.16002)
		(layer "In6.Cu")
		(net "M_K_CPU0_SA_DQS_DN<2>")
	)
	(segment
		(start 428.214028 -219.862146)
		(end 428.554642 -220.20276)
		(width 0.16002)
		(layer "In6.Cu")
		(net "M_K_CPU0_SA_DQS_DN<2>")
	)
	(segment
		(start 397.86306 -235.0008)
		(end 409.350718 -223.513142)
		(width 0.16002)
		(layer "In6.Cu")
		(net "M_K_CPU0_SA_DQS_DN<2>")
	)
	(segment
		(start 430.057306 -219.35186)
		(end 430.445926 -219.35186)
		(width 0.16002)
		(layer "In6.Cu")
		(net "M_K_CPU0_SA_DQS_DN<2>")
	)
	(segment
		(start 395.583664 -234.941872)
		(end 395.776704 -234.941872)
		(width 0.09525)
		(layer "In6.Cu")
		(net "M_K_CPU0_SA_DQS_DN<2>")
	)
	(segment
		(start 411.98038 -220.20276)
		(end 414.118298 -220.20276)
		(width 0.16002)
		(layer "In6.Cu")
		(net "M_K_CPU0_SA_DQS_DN<2>")
	)
	(arc
		(start 391.956036 -236.86897)
		(mid 392.144504 -236.818293)
		(end 392.332972 -236.86897)
		(width 0.09525)
		(layer "In6.Cu")
		(net "M_K_CPU0_SA_DQS_DN<2>")
	)
	(arc
		(start 390.519666 -236.90199)
		(mid 390.771807 -236.94356)
		(end 391.016236 -236.86897)
		(width 0.09525)
		(layer "In6.Cu")
		(net "M_K_CPU0_SA_DQS_DN<2>")
	)
	(arc
		(start 391.024618 -236.864144)
		(mid 391.20965 -236.81823)
		(end 391.393426 -236.86897)
		(width 0.09525)
		(layer "In6.Cu")
		(net "M_K_CPU0_SA_DQS_DN<2>")
	)
	(arc
		(start 391.393426 -236.86897)
		(mid 391.668715 -236.944691)
		(end 391.945622 -236.875066)
		(width 0.09525)
		(layer "In6.Cu")
		(net "M_K_CPU0_SA_DQS_DN<2>")
	)
	(arc
		(start 392.343386 -236.875066)
		(mid 392.620548 -236.944866)
		(end 392.89609 -236.86897)
		(width 0.09525)
		(layer "In6.Cu")
		(net "M_K_CPU0_SA_DQS_DN<2>")
	)
	(arc
		(start 392.89609 -236.86897)
		(mid 392.987036 -236.830669)
		(end 393.084812 -236.817408)
		(width 0.09525)
		(layer "In6.Cu")
		(net "M_K_CPU0_SA_DQS_DN<2>")
	)
	(segment
		(start 389.798052 -232.599992)
		(end 390.264904 -232.334054)
		(width 0.12954)
		(layer "F.Cu")
		(net "M_K_CPU0_SA_DQS_DN<1>")
	)
	(segment
		(start 393.010898 -231.920542)
		(end 393.121642 -231.809798)
		(width 0.09525)
		(layer "In6.Cu")
		(net "M_K_CPU0_SA_DQS_DN<1>")
	)
	(segment
		(start 432.498246 -209.662268)
		(end 433.34813 -210.512152)
		(width 0.16002)
		(layer "In6.Cu")
		(net "M_K_CPU0_SA_DQS_DN<1>")
	)
	(segment
		(start 414.969198 -210.001866)
		(end 417.749736 -210.001866)
		(width 0.16002)
		(layer "In6.Cu")
		(net "M_K_CPU0_SA_DQS_DN<1>")
	)
	(segment
		(start 421.010588 -210.852766)
		(end 421.662352 -210.852766)
		(width 0.16002)
		(layer "In6.Cu")
		(net "M_K_CPU0_SA_DQS_DN<1>")
	)
	(segment
		(start 395.859254 -229.011988)
		(end 399.46199 -225.409252)
		(width 0.16002)
		(layer "In6.Cu")
		(net "M_K_CPU0_SA_DQS_DN<1>")
	)
	(segment
		(start 436.75046 -210.852766)
		(end 437.60136 -210.001866)
		(width 0.16002)
		(layer "In6.Cu")
		(net "M_K_CPU0_SA_DQS_DN<1>")
	)
	(segment
		(start 399.46199 -225.409252)
		(end 399.46199 -225.408998)
		(width 0.16002)
		(layer "In6.Cu")
		(net "M_K_CPU0_SA_DQS_DN<1>")
	)
	(segment
		(start 394.201396 -230.85171)
		(end 394.201396 -230.14813)
		(width 0.09525)
		(layer "In6.Cu")
		(net "M_K_CPU0_SA_DQS_DN<1>")
	)
	(segment
		(start 403.153118 -219.557854)
		(end 411.858206 -210.852766)
		(width 0.16002)
		(layer "In6.Cu")
		(net "M_K_CPU0_SA_DQS_DN<1>")
	)
	(segment
		(start 391.945622 -232.01503)
		(end 391.956036 -232.008934)
		(width 0.09525)
		(layer "In6.Cu")
		(net "M_K_CPU0_SA_DQS_DN<1>")
	)
	(segment
		(start 435.758082 -210.512152)
		(end 436.098696 -210.852766)
		(width 0.16002)
		(layer "In6.Cu")
		(net "M_K_CPU0_SA_DQS_DN<1>")
	)
	(segment
		(start 430.785524 -209.662268)
		(end 432.498246 -209.662268)
		(width 0.16002)
		(layer "In6.Cu")
		(net "M_K_CPU0_SA_DQS_DN<1>")
	)
	(segment
		(start 444.475108 -210.66125)
		(end 446.370456 -210.66125)
		(width 0.16002)
		(layer "In6.Cu")
		(net "M_K_CPU0_SA_DQS_DN<1>")
	)
	(segment
		(start 395.75867 -229.028752)
		(end 395.84249 -229.028752)
		(width 0.09525)
		(layer "In6.Cu")
		(net "M_K_CPU0_SA_DQS_DN<1>")
	)
	(segment
		(start 394.539216 -229.81031)
		(end 394.977112 -229.81031)
		(width 0.09525)
		(layer "In6.Cu")
		(net "M_K_CPU0_SA_DQS_DN<1>")
	)
	(segment
		(start 411.858206 -210.852766)
		(end 414.118298 -210.852766)
		(width 0.16002)
		(layer "In6.Cu")
		(net "M_K_CPU0_SA_DQS_DN<1>")
	)
	(segment
		(start 414.118298 -210.852766)
		(end 414.969198 -210.001866)
		(width 0.16002)
		(layer "In6.Cu")
		(net "M_K_CPU0_SA_DQS_DN<1>")
	)
	(segment
		(start 424.954192 -209.662268)
		(end 425.804076 -210.512152)
		(width 0.16002)
		(layer "In6.Cu")
		(net "M_K_CPU0_SA_DQS_DN<1>")
	)
	(segment
		(start 443.646052 -210.860386)
		(end 444.275972 -210.860386)
		(width 0.16002)
		(layer "In6.Cu")
		(net "M_K_CPU0_SA_DQS_DN<1>")
	)
	(segment
		(start 425.804076 -210.512152)
		(end 428.214028 -210.512152)
		(width 0.16002)
		(layer "In6.Cu")
		(net "M_K_CPU0_SA_DQS_DN<1>")
	)
	(segment
		(start 428.554642 -210.852766)
		(end 429.206406 -210.852766)
		(width 0.16002)
		(layer "In6.Cu")
		(net "M_K_CPU0_SA_DQS_DN<1>")
	)
	(segment
		(start 430.057306 -210.001866)
		(end 430.445926 -210.001866)
		(width 0.16002)
		(layer "In6.Cu")
		(net "M_K_CPU0_SA_DQS_DN<1>")
	)
	(segment
		(start 392.332972 -232.008934)
		(end 392.343386 -232.01503)
		(width 0.09525)
		(layer "In6.Cu")
		(net "M_K_CPU0_SA_DQS_DN<1>")
	)
	(segment
		(start 390.264904 -232.334054)
		(end 390.418828 -232.068624)
		(width 0.09525)
		(layer "In6.Cu")
		(net "M_K_CPU0_SA_DQS_DN<1>")
	)
	(segment
		(start 428.214028 -210.512152)
		(end 428.554642 -210.852766)
		(width 0.16002)
		(layer "In6.Cu")
		(net "M_K_CPU0_SA_DQS_DN<1>")
	)
	(segment
		(start 394.977112 -229.81031)
		(end 395.75867 -229.028752)
		(width 0.09525)
		(layer "In6.Cu")
		(net "M_K_CPU0_SA_DQS_DN<1>")
	)
	(segment
		(start 436.098696 -210.852766)
		(end 436.75046 -210.852766)
		(width 0.16002)
		(layer "In6.Cu")
		(net "M_K_CPU0_SA_DQS_DN<1>")
	)
	(segment
		(start 422.513252 -210.001866)
		(end 422.901872 -210.001866)
		(width 0.16002)
		(layer "In6.Cu")
		(net "M_K_CPU0_SA_DQS_DN<1>")
	)
	(segment
		(start 437.98998 -210.001866)
		(end 438.329578 -209.662268)
		(width 0.16002)
		(layer "In6.Cu")
		(net "M_K_CPU0_SA_DQS_DN<1>")
	)
	(segment
		(start 393.243308 -231.809798)
		(end 394.201396 -230.85171)
		(width 0.09525)
		(layer "In6.Cu")
		(net "M_K_CPU0_SA_DQS_DN<1>")
	)
	(segment
		(start 395.84249 -229.028752)
		(end 395.859254 -229.011988)
		(width 0.09525)
		(layer "In6.Cu")
		(net "M_K_CPU0_SA_DQS_DN<1>")
	)
	(segment
		(start 393.121642 -231.809798)
		(end 393.243308 -231.809798)
		(width 0.09525)
		(layer "In6.Cu")
		(net "M_K_CPU0_SA_DQS_DN<1>")
	)
	(segment
		(start 422.901872 -210.001866)
		(end 423.24147 -209.662268)
		(width 0.16002)
		(layer "In6.Cu")
		(net "M_K_CPU0_SA_DQS_DN<1>")
	)
	(segment
		(start 438.329578 -209.662268)
		(end 440.237118 -209.662268)
		(width 0.16002)
		(layer "In6.Cu")
		(net "M_K_CPU0_SA_DQS_DN<1>")
	)
	(segment
		(start 429.206406 -210.852766)
		(end 430.057306 -210.001866)
		(width 0.16002)
		(layer "In6.Cu")
		(net "M_K_CPU0_SA_DQS_DN<1>")
	)
	(segment
		(start 394.201396 -230.14813)
		(end 394.539216 -229.81031)
		(width 0.09525)
		(layer "In6.Cu")
		(net "M_K_CPU0_SA_DQS_DN<1>")
	)
	(segment
		(start 440.237118 -209.662268)
		(end 440.811158 -210.236308)
		(width 0.16002)
		(layer "In6.Cu")
		(net "M_K_CPU0_SA_DQS_DN<1>")
	)
	(segment
		(start 420.669974 -210.512152)
		(end 421.010588 -210.852766)
		(width 0.16002)
		(layer "In6.Cu")
		(net "M_K_CPU0_SA_DQS_DN<1>")
	)
	(segment
		(start 423.24147 -209.662268)
		(end 424.954192 -209.662268)
		(width 0.16002)
		(layer "In6.Cu")
		(net "M_K_CPU0_SA_DQS_DN<1>")
	)
	(segment
		(start 399.46199 -225.408998)
		(end 403.153118 -221.71787)
		(width 0.16002)
		(layer "In6.Cu")
		(net "M_K_CPU0_SA_DQS_DN<1>")
	)
	(segment
		(start 440.811158 -210.236308)
		(end 443.021974 -210.236308)
		(width 0.16002)
		(layer "In6.Cu")
		(net "M_K_CPU0_SA_DQS_DN<1>")
	)
	(segment
		(start 446.370456 -210.66125)
		(end 446.644268 -210.935062)
		(width 0.16002)
		(layer "In6.Cu")
		(net "M_K_CPU0_SA_DQS_DN<1>")
	)
	(segment
		(start 418.260022 -210.512152)
		(end 420.669974 -210.512152)
		(width 0.16002)
		(layer "In6.Cu")
		(net "M_K_CPU0_SA_DQS_DN<1>")
	)
	(segment
		(start 390.418828 -232.068624)
		(end 390.519666 -232.041954)
		(width 0.09525)
		(layer "In6.Cu")
		(net "M_K_CPU0_SA_DQS_DN<1>")
	)
	(segment
		(start 421.662352 -210.852766)
		(end 422.513252 -210.001866)
		(width 0.16002)
		(layer "In6.Cu")
		(net "M_K_CPU0_SA_DQS_DN<1>")
	)
	(segment
		(start 430.445926 -210.001866)
		(end 430.785524 -209.662268)
		(width 0.16002)
		(layer "In6.Cu")
		(net "M_K_CPU0_SA_DQS_DN<1>")
	)
	(segment
		(start 417.749736 -210.001866)
		(end 418.260022 -210.512152)
		(width 0.16002)
		(layer "In6.Cu")
		(net "M_K_CPU0_SA_DQS_DN<1>")
	)
	(segment
		(start 403.153118 -221.71787)
		(end 403.153118 -219.557854)
		(width 0.16002)
		(layer "In6.Cu")
		(net "M_K_CPU0_SA_DQS_DN<1>")
	)
	(segment
		(start 433.34813 -210.512152)
		(end 435.758082 -210.512152)
		(width 0.16002)
		(layer "In6.Cu")
		(net "M_K_CPU0_SA_DQS_DN<1>")
	)
	(segment
		(start 443.021974 -210.236308)
		(end 443.646052 -210.860386)
		(width 0.16002)
		(layer "In6.Cu")
		(net "M_K_CPU0_SA_DQS_DN<1>")
	)
	(segment
		(start 437.60136 -210.001866)
		(end 437.98998 -210.001866)
		(width 0.16002)
		(layer "In6.Cu")
		(net "M_K_CPU0_SA_DQS_DN<1>")
	)
	(segment
		(start 444.275972 -210.860386)
		(end 444.475108 -210.66125)
		(width 0.16002)
		(layer "In6.Cu")
		(net "M_K_CPU0_SA_DQS_DN<1>")
	)
	(segment
		(start 391.016236 -232.008934)
		(end 391.024618 -232.004108)
		(width 0.09525)
		(layer "In6.Cu")
		(net "M_K_CPU0_SA_DQS_DN<1>")
	)
	(arc
		(start 391.024618 -232.004108)
		(mid 391.20965 -231.958194)
		(end 391.393426 -232.008934)
		(width 0.09525)
		(layer "In6.Cu")
		(net "M_K_CPU0_SA_DQS_DN<1>")
	)
	(arc
		(start 390.519666 -232.041954)
		(mid 390.771807 -232.083524)
		(end 391.016236 -232.008934)
		(width 0.09525)
		(layer "In6.Cu")
		(net "M_K_CPU0_SA_DQS_DN<1>")
	)
	(arc
		(start 392.343386 -232.01503)
		(mid 392.620548 -232.08483)
		(end 392.89609 -232.008934)
		(width 0.09525)
		(layer "In6.Cu")
		(net "M_K_CPU0_SA_DQS_DN<1>")
	)
	(arc
		(start 391.393426 -232.008934)
		(mid 391.668715 -232.084655)
		(end 391.945622 -232.01503)
		(width 0.09525)
		(layer "In6.Cu")
		(net "M_K_CPU0_SA_DQS_DN<1>")
	)
	(arc
		(start 391.956036 -232.008934)
		(mid 392.144504 -231.958257)
		(end 392.332972 -232.008934)
		(width 0.09525)
		(layer "In6.Cu")
		(net "M_K_CPU0_SA_DQS_DN<1>")
	)
	(arc
		(start 392.89609 -232.008934)
		(mid 392.956357 -231.968457)
		(end 393.010898 -231.920542)
		(width 0.09525)
		(layer "In6.Cu")
		(net "M_K_CPU0_SA_DQS_DN<1>")
	)
	(segment
		(start 389.798052 -227.74021)
		(end 390.264904 -227.474272)
		(width 0.12954)
		(layer "F.Cu")
		(net "M_K_CPU0_SA_DQS_DN<0>")
	)
	(segment
		(start 422.513252 -200.651872)
		(end 421.662352 -201.502772)
		(width 0.16002)
		(layer "In6.Cu")
		(net "M_K_CPU0_SA_DQS_DN<0>")
	)
	(segment
		(start 446.644268 -201.585068)
		(end 446.370456 -201.311256)
		(width 0.16002)
		(layer "In6.Cu")
		(net "M_K_CPU0_SA_DQS_DN<0>")
	)
	(segment
		(start 417.410138 -200.312274)
		(end 415.697416 -200.312274)
		(width 0.16002)
		(layer "In6.Cu")
		(net "M_K_CPU0_SA_DQS_DN<0>")
	)
	(segment
		(start 430.057306 -200.651872)
		(end 429.206406 -201.502772)
		(width 0.16002)
		(layer "In6.Cu")
		(net "M_K_CPU0_SA_DQS_DN<0>")
	)
	(segment
		(start 436.098696 -201.502772)
		(end 435.758082 -201.162158)
		(width 0.16002)
		(layer "In6.Cu")
		(net "M_K_CPU0_SA_DQS_DN<0>")
	)
	(segment
		(start 394.16609 -221.978474)
		(end 394.082778 -221.978474)
		(width 0.09525)
		(layer "In6.Cu")
		(net "M_K_CPU0_SA_DQS_DN<0>")
	)
	(segment
		(start 391.99439 -227.127054)
		(end 391.95629 -227.149152)
		(width 0.09525)
		(layer "In6.Cu")
		(net "M_K_CPU0_SA_DQS_DN<0>")
	)
	(segment
		(start 424.954192 -200.312274)
		(end 423.24147 -200.312274)
		(width 0.16002)
		(layer "In6.Cu")
		(net "M_K_CPU0_SA_DQS_DN<0>")
	)
	(segment
		(start 444.275972 -201.510392)
		(end 443.646052 -201.510392)
		(width 0.16002)
		(layer "In6.Cu")
		(net "M_K_CPU0_SA_DQS_DN<0>")
	)
	(segment
		(start 395.64564 -220.498924)
		(end 394.182854 -221.96171)
		(width 0.16002)
		(layer "In6.Cu")
		(net "M_K_CPU0_SA_DQS_DN<0>")
	)
	(segment
		(start 430.785524 -200.312274)
		(end 430.445926 -200.651872)
		(width 0.16002)
		(layer "In6.Cu")
		(net "M_K_CPU0_SA_DQS_DN<0>")
	)
	(segment
		(start 397.196818 -218.947492)
		(end 395.64564 -220.49867)
		(width 0.16002)
		(layer "In6.Cu")
		(net "M_K_CPU0_SA_DQS_DN<0>")
	)
	(segment
		(start 415.357818 -200.651872)
		(end 414.969198 -200.651872)
		(width 0.16002)
		(layer "In6.Cu")
		(net "M_K_CPU0_SA_DQS_DN<0>")
	)
	(segment
		(start 440.237118 -200.312274)
		(end 438.329578 -200.312274)
		(width 0.16002)
		(layer "In6.Cu")
		(net "M_K_CPU0_SA_DQS_DN<0>")
	)
	(segment
		(start 422.901872 -200.651872)
		(end 422.513252 -200.651872)
		(width 0.16002)
		(layer "In6.Cu")
		(net "M_K_CPU0_SA_DQS_DN<0>")
	)
	(segment
		(start 444.475108 -201.311256)
		(end 444.275972 -201.510392)
		(width 0.16002)
		(layer "In6.Cu")
		(net "M_K_CPU0_SA_DQS_DN<0>")
	)
	(segment
		(start 397.196818 -216.044272)
		(end 397.196818 -218.947492)
		(width 0.16002)
		(layer "In6.Cu")
		(net "M_K_CPU0_SA_DQS_DN<0>")
	)
	(segment
		(start 392.42619 -226.339146)
		(end 392.394694 -226.357434)
		(width 0.09525)
		(layer "In6.Cu")
		(net "M_K_CPU0_SA_DQS_DN<0>")
	)
	(segment
		(start 391.024618 -227.144326)
		(end 391.016236 -227.149152)
		(width 0.09525)
		(layer "In6.Cu")
		(net "M_K_CPU0_SA_DQS_DN<0>")
	)
	(segment
		(start 395.64564 -220.49867)
		(end 395.64564 -220.498924)
		(width 0.16002)
		(layer "In6.Cu")
		(net "M_K_CPU0_SA_DQS_DN<0>")
	)
	(segment
		(start 393.64666 -222.414592)
		(end 393.64666 -222.614236)
		(width 0.09525)
		(layer "In6.Cu")
		(net "M_K_CPU0_SA_DQS_DN<0>")
	)
	(segment
		(start 433.34813 -201.162158)
		(end 432.498246 -200.312274)
		(width 0.16002)
		(layer "In6.Cu")
		(net "M_K_CPU0_SA_DQS_DN<0>")
	)
	(segment
		(start 393.401296 -223.078548)
		(end 393.333732 -223.117918)
		(width 0.09525)
		(layer "In6.Cu")
		(net "M_K_CPU0_SA_DQS_DN<0>")
	)
	(segment
		(start 411.738318 -201.502772)
		(end 397.196818 -216.044272)
		(width 0.16002)
		(layer "In6.Cu")
		(net "M_K_CPU0_SA_DQS_DN<0>")
	)
	(segment
		(start 418.260022 -201.162158)
		(end 417.410138 -200.312274)
		(width 0.16002)
		(layer "In6.Cu")
		(net "M_K_CPU0_SA_DQS_DN<0>")
	)
	(segment
		(start 392.896344 -225.52914)
		(end 392.863832 -225.547936)
		(width 0.09525)
		(layer "In6.Cu")
		(net "M_K_CPU0_SA_DQS_DN<0>")
	)
	(segment
		(start 429.206406 -201.502772)
		(end 428.554642 -201.502772)
		(width 0.16002)
		(layer "In6.Cu")
		(net "M_K_CPU0_SA_DQS_DN<0>")
	)
	(segment
		(start 443.646052 -201.510392)
		(end 443.021974 -200.886314)
		(width 0.16002)
		(layer "In6.Cu")
		(net "M_K_CPU0_SA_DQS_DN<0>")
	)
	(segment
		(start 415.697416 -200.312274)
		(end 415.357818 -200.651872)
		(width 0.16002)
		(layer "In6.Cu")
		(net "M_K_CPU0_SA_DQS_DN<0>")
	)
	(segment
		(start 392.896344 -223.909128)
		(end 392.863832 -223.927924)
		(width 0.09525)
		(layer "In6.Cu")
		(net "M_K_CPU0_SA_DQS_DN<0>")
	)
	(segment
		(start 414.969198 -200.651872)
		(end 414.118298 -201.502772)
		(width 0.16002)
		(layer "In6.Cu")
		(net "M_K_CPU0_SA_DQS_DN<0>")
	)
	(segment
		(start 394.182854 -221.96171)
		(end 394.16609 -221.978474)
		(width 0.09525)
		(layer "In6.Cu")
		(net "M_K_CPU0_SA_DQS_DN<0>")
	)
	(segment
		(start 390.418828 -227.208842)
		(end 390.264904 -227.474272)
		(width 0.09525)
		(layer "In6.Cu")
		(net "M_K_CPU0_SA_DQS_DN<0>")
	)
	(segment
		(start 421.662352 -201.502772)
		(end 421.010588 -201.502772)
		(width 0.16002)
		(layer "In6.Cu")
		(net "M_K_CPU0_SA_DQS_DN<0>")
	)
	(segment
		(start 420.669974 -201.162158)
		(end 418.260022 -201.162158)
		(width 0.16002)
		(layer "In6.Cu")
		(net "M_K_CPU0_SA_DQS_DN<0>")
	)
	(segment
		(start 392.931396 -223.888554)
		(end 392.896344 -223.909128)
		(width 0.09525)
		(layer "In6.Cu")
		(net "M_K_CPU0_SA_DQS_DN<0>")
	)
	(segment
		(start 392.896344 -224.559368)
		(end 392.931396 -224.579942)
		(width 0.09525)
		(layer "In6.Cu")
		(net "M_K_CPU0_SA_DQS_DN<0>")
	)
	(segment
		(start 392.863832 -224.540572)
		(end 392.896344 -224.559368)
		(width 0.09525)
		(layer "In6.Cu")
		(net "M_K_CPU0_SA_DQS_DN<0>")
	)
	(segment
		(start 425.804076 -201.162158)
		(end 424.954192 -200.312274)
		(width 0.16002)
		(layer "In6.Cu")
		(net "M_K_CPU0_SA_DQS_DN<0>")
	)
	(segment
		(start 430.445926 -200.651872)
		(end 430.057306 -200.651872)
		(width 0.16002)
		(layer "In6.Cu")
		(net "M_K_CPU0_SA_DQS_DN<0>")
	)
	(segment
		(start 392.931396 -225.508566)
		(end 392.896344 -225.52914)
		(width 0.09525)
		(layer "In6.Cu")
		(net "M_K_CPU0_SA_DQS_DN<0>")
	)
	(segment
		(start 414.118298 -201.502772)
		(end 411.738318 -201.502772)
		(width 0.16002)
		(layer "In6.Cu")
		(net "M_K_CPU0_SA_DQS_DN<0>")
	)
	(segment
		(start 446.370456 -201.311256)
		(end 444.475108 -201.311256)
		(width 0.16002)
		(layer "In6.Cu")
		(net "M_K_CPU0_SA_DQS_DN<0>")
	)
	(segment
		(start 393.40536 -223.076008)
		(end 393.403328 -223.077278)
		(width 0.09525)
		(layer "In6.Cu")
		(net "M_K_CPU0_SA_DQS_DN<0>")
	)
	(segment
		(start 436.75046 -201.502772)
		(end 436.098696 -201.502772)
		(width 0.16002)
		(layer "In6.Cu")
		(net "M_K_CPU0_SA_DQS_DN<0>")
	)
	(segment
		(start 423.24147 -200.312274)
		(end 422.901872 -200.651872)
		(width 0.16002)
		(layer "In6.Cu")
		(net "M_K_CPU0_SA_DQS_DN<0>")
	)
	(segment
		(start 443.021974 -200.886314)
		(end 440.811158 -200.886314)
		(width 0.16002)
		(layer "In6.Cu")
		(net "M_K_CPU0_SA_DQS_DN<0>")
	)
	(segment
		(start 428.214028 -201.162158)
		(end 425.804076 -201.162158)
		(width 0.16002)
		(layer "In6.Cu")
		(net "M_K_CPU0_SA_DQS_DN<0>")
	)
	(segment
		(start 394.082778 -221.978474)
		(end 393.64666 -222.414592)
		(width 0.09525)
		(layer "In6.Cu")
		(net "M_K_CPU0_SA_DQS_DN<0>")
	)
	(segment
		(start 421.010588 -201.502772)
		(end 420.669974 -201.162158)
		(width 0.16002)
		(layer "In6.Cu")
		(net "M_K_CPU0_SA_DQS_DN<0>")
	)
	(segment
		(start 437.98998 -200.651872)
		(end 437.60136 -200.651872)
		(width 0.16002)
		(layer "In6.Cu")
		(net "M_K_CPU0_SA_DQS_DN<0>")
	)
	(segment
		(start 390.519666 -227.182172)
		(end 390.418828 -227.208842)
		(width 0.09525)
		(layer "In6.Cu")
		(net "M_K_CPU0_SA_DQS_DN<0>")
	)
	(segment
		(start 438.329578 -200.312274)
		(end 437.98998 -200.651872)
		(width 0.16002)
		(layer "In6.Cu")
		(net "M_K_CPU0_SA_DQS_DN<0>")
	)
	(segment
		(start 435.758082 -201.162158)
		(end 433.34813 -201.162158)
		(width 0.16002)
		(layer "In6.Cu")
		(net "M_K_CPU0_SA_DQS_DN<0>")
	)
	(segment
		(start 428.554642 -201.502772)
		(end 428.214028 -201.162158)
		(width 0.16002)
		(layer "In6.Cu")
		(net "M_K_CPU0_SA_DQS_DN<0>")
	)
	(segment
		(start 432.498246 -200.312274)
		(end 430.785524 -200.312274)
		(width 0.16002)
		(layer "In6.Cu")
		(net "M_K_CPU0_SA_DQS_DN<0>")
	)
	(segment
		(start 392.46429 -226.317048)
		(end 392.42619 -226.339146)
		(width 0.09525)
		(layer "In6.Cu")
		(net "M_K_CPU0_SA_DQS_DN<0>")
	)
	(segment
		(start 437.60136 -200.651872)
		(end 436.75046 -201.502772)
		(width 0.16002)
		(layer "In6.Cu")
		(net "M_K_CPU0_SA_DQS_DN<0>")
	)
	(segment
		(start 440.811158 -200.886314)
		(end 440.237118 -200.312274)
		(width 0.16002)
		(layer "In6.Cu")
		(net "M_K_CPU0_SA_DQS_DN<0>")
	)
	(arc
		(start 391.95629 -227.149152)
		(mid 391.674858 -227.224907)
		(end 391.393426 -227.149152)
		(width 0.09525)
		(layer "In6.Cu")
		(net "M_K_CPU0_SA_DQS_DN<0>")
	)
	(arc
		(start 392.931396 -224.579942)
		(mid 393.111787 -224.781641)
		(end 393.177014 -225.044254)
		(width 0.09525)
		(layer "In6.Cu")
		(net "M_K_CPU0_SA_DQS_DN<0>")
	)
	(arc
		(start 392.707114 -225.85426)
		(mid 392.642717 -226.115566)
		(end 392.46429 -226.317048)
		(width 0.09525)
		(layer "In6.Cu")
		(net "M_K_CPU0_SA_DQS_DN<0>")
	)
	(arc
		(start 393.403328 -223.077278)
		(mid 393.402313 -223.077914)
		(end 393.401296 -223.078548)
		(width 0.09525)
		(layer "In6.Cu")
		(net "M_K_CPU0_SA_DQS_DN<0>")
	)
	(arc
		(start 392.237214 -226.664266)
		(mid 392.172817 -226.925572)
		(end 391.99439 -227.127054)
		(width 0.09525)
		(layer "In6.Cu")
		(net "M_K_CPU0_SA_DQS_DN<0>")
	)
	(arc
		(start 393.177014 -225.044254)
		(mid 393.111767 -225.306857)
		(end 392.931396 -225.508566)
		(width 0.09525)
		(layer "In6.Cu")
		(net "M_K_CPU0_SA_DQS_DN<0>")
	)
	(arc
		(start 392.394694 -226.357434)
		(mid 392.278896 -226.491828)
		(end 392.237214 -226.664266)
		(width 0.09525)
		(layer "In6.Cu")
		(net "M_K_CPU0_SA_DQS_DN<0>")
	)
	(arc
		(start 393.177014 -223.424242)
		(mid 393.111767 -223.686845)
		(end 392.931396 -223.888554)
		(width 0.09525)
		(layer "In6.Cu")
		(net "M_K_CPU0_SA_DQS_DN<0>")
	)
	(arc
		(start 390.539478 -227.190046)
		(mid 390.529535 -227.186203)
		(end 390.519666 -227.182172)
		(width 0.09525)
		(layer "In6.Cu")
		(net "M_K_CPU0_SA_DQS_DN<0>")
	)
	(arc
		(start 393.333732 -223.117918)
		(mid 393.218458 -223.252196)
		(end 393.177014 -223.424242)
		(width 0.09525)
		(layer "In6.Cu")
		(net "M_K_CPU0_SA_DQS_DN<0>")
	)
	(arc
		(start 391.393426 -227.149152)
		(mid 391.209651 -227.09838)
		(end 391.024618 -227.144326)
		(width 0.09525)
		(layer "In6.Cu")
		(net "M_K_CPU0_SA_DQS_DN<0>")
	)
	(arc
		(start 391.016236 -227.149152)
		(mid 390.782441 -227.223019)
		(end 390.539478 -227.190046)
		(width 0.09525)
		(layer "In6.Cu")
		(net "M_K_CPU0_SA_DQS_DN<0>")
	)
	(arc
		(start 392.863832 -223.927924)
		(mid 392.7071 -224.234248)
		(end 392.863832 -224.540572)
		(width 0.09525)
		(layer "In6.Cu")
		(net "M_K_CPU0_SA_DQS_DN<0>")
	)
	(arc
		(start 392.863832 -225.547936)
		(mid 392.748558 -225.682214)
		(end 392.707114 -225.85426)
		(width 0.09525)
		(layer "In6.Cu")
		(net "M_K_CPU0_SA_DQS_DN<0>")
	)
	(arc
		(start 393.64666 -222.614236)
		(mid 393.582761 -222.874783)
		(end 393.40536 -223.076008)
		(width 0.09525)
		(layer "In6.Cu")
		(net "M_K_CPU0_SA_DQS_DN<0>")
	)
	(segment
		(start 388.857998 -230.97998)
		(end 389.32485 -230.714296)
		(width 0.10668)
		(layer "F.Cu")
		(net "M_K_CPU0_SA_DQ<9>")
	)
	(segment
		(start 394.234416 -229.17531)
		(end 394.587476 -229.17531)
		(width 0.0889)
		(layer "In6.Cu")
		(net "M_K_CPU0_SA_DQ<9>")
	)
	(segment
		(start 427.080934 -208.810098)
		(end 428.229268 -208.810098)
		(width 0.14478)
		(layer "In6.Cu")
		(net "M_K_CPU0_SA_DQ<9>")
	)
	(segment
		(start 415.203386 -207.95996)
		(end 417.489132 -207.95996)
		(width 0.14478)
		(layer "In6.Cu")
		(net "M_K_CPU0_SA_DQ<9>")
	)
	(segment
		(start 420.714424 -208.810098)
		(end 422.139872 -208.219548)
		(width 0.14478)
		(layer "In6.Cu")
		(net "M_K_CPU0_SA_DQ<9>")
	)
	(segment
		(start 437.392064 -208.15935)
		(end 437.872886 -207.960214)
		(width 0.14478)
		(layer "In6.Cu")
		(net "M_K_CPU0_SA_DQ<9>")
	)
	(segment
		(start 425.029122 -207.960214)
		(end 427.080934 -208.810098)
		(width 0.14478)
		(layer "In6.Cu")
		(net "M_K_CPU0_SA_DQ<9>")
	)
	(segment
		(start 430.28108 -207.960214)
		(end 432.590194 -207.960214)
		(width 0.14478)
		(layer "In6.Cu")
		(net "M_K_CPU0_SA_DQ<9>")
	)
	(segment
		(start 391.01776 -231.036622)
		(end 391.026142 -231.041448)
		(width 0.0889)
		(layer "In6.Cu")
		(net "M_K_CPU0_SA_DQ<9>")
	)
	(segment
		(start 432.590194 -207.960214)
		(end 434.641752 -208.810098)
		(width 0.14478)
		(layer "In6.Cu")
		(net "M_K_CPU0_SA_DQ<9>")
	)
	(segment
		(start 395.082014 -228.339396)
		(end 395.082014 -227.908104)
		(width 0.0889)
		(layer "In6.Cu")
		(net "M_K_CPU0_SA_DQ<9>")
	)
	(segment
		(start 390.443466 -231.041448)
		(end 390.451848 -231.036622)
		(width 0.0889)
		(layer "In6.Cu")
		(net "M_K_CPU0_SA_DQ<9>")
	)
	(segment
		(start 437.872886 -207.960214)
		(end 446.219326 -207.960214)
		(width 0.14478)
		(layer "In6.Cu")
		(net "M_K_CPU0_SA_DQ<9>")
	)
	(segment
		(start 401.681696 -219.080842)
		(end 411.95244 -208.810098)
		(width 0.14478)
		(layer "In6.Cu")
		(net "M_K_CPU0_SA_DQ<9>")
	)
	(segment
		(start 419.541706 -208.810098)
		(end 420.714424 -208.810098)
		(width 0.14478)
		(layer "In6.Cu")
		(net "M_K_CPU0_SA_DQ<9>")
	)
	(segment
		(start 422.765982 -207.960214)
		(end 425.029122 -207.960214)
		(width 0.14478)
		(layer "In6.Cu")
		(net "M_K_CPU0_SA_DQ<9>")
	)
	(segment
		(start 401.681696 -221.308422)
		(end 401.681696 -219.080842)
		(width 0.14478)
		(layer "In6.Cu")
		(net "M_K_CPU0_SA_DQ<9>")
	)
	(segment
		(start 428.229268 -208.810098)
		(end 429.683164 -208.207864)
		(width 0.14478)
		(layer "In6.Cu")
		(net "M_K_CPU0_SA_DQ<9>")
	)
	(segment
		(start 413.150812 -208.810098)
		(end 415.203386 -207.95996)
		(width 0.14478)
		(layer "In6.Cu")
		(net "M_K_CPU0_SA_DQ<9>")
	)
	(segment
		(start 446.219326 -207.960214)
		(end 446.644268 -208.385156)
		(width 0.14478)
		(layer "In6.Cu")
		(net "M_K_CPU0_SA_DQ<9>")
	)
	(segment
		(start 411.95244 -208.810098)
		(end 413.150812 -208.810098)
		(width 0.14478)
		(layer "In6.Cu")
		(net "M_K_CPU0_SA_DQ<9>")
	)
	(segment
		(start 394.840714 -228.922072)
		(end 395.082014 -228.339396)
		(width 0.0889)
		(layer "In6.Cu")
		(net "M_K_CPU0_SA_DQ<9>")
	)
	(segment
		(start 393.614148 -229.795578)
		(end 394.234416 -229.17531)
		(width 0.0889)
		(layer "In6.Cu")
		(net "M_K_CPU0_SA_DQ<9>")
	)
	(segment
		(start 394.587476 -229.17531)
		(end 394.840714 -228.922072)
		(width 0.0889)
		(layer "In6.Cu")
		(net "M_K_CPU0_SA_DQ<9>")
	)
	(segment
		(start 389.170926 -230.979726)
		(end 389.193024 -231.062784)
		(width 0.0889)
		(layer "In6.Cu")
		(net "M_K_CPU0_SA_DQ<9>")
	)
	(segment
		(start 435.82082 -208.810098)
		(end 437.392064 -208.15935)
		(width 0.14478)
		(layer "In6.Cu")
		(net "M_K_CPU0_SA_DQ<9>")
	)
	(segment
		(start 395.082014 -227.908104)
		(end 395.788388 -227.20173)
		(width 0.0889)
		(layer "In6.Cu")
		(net "M_K_CPU0_SA_DQ<9>")
	)
	(segment
		(start 417.489132 -207.95996)
		(end 419.541706 -208.810098)
		(width 0.14478)
		(layer "In6.Cu")
		(net "M_K_CPU0_SA_DQ<9>")
	)
	(segment
		(start 429.683164 -208.207864)
		(end 430.28108 -207.960214)
		(width 0.14478)
		(layer "In6.Cu")
		(net "M_K_CPU0_SA_DQ<9>")
	)
	(segment
		(start 434.641752 -208.810098)
		(end 435.82082 -208.810098)
		(width 0.14478)
		(layer "In6.Cu")
		(net "M_K_CPU0_SA_DQ<9>")
	)
	(segment
		(start 392.111992 -230.77932)
		(end 392.50874 -230.382572)
		(width 0.0889)
		(layer "In6.Cu")
		(net "M_K_CPU0_SA_DQ<9>")
	)
	(segment
		(start 395.788388 -227.20173)
		(end 401.681696 -221.308422)
		(width 0.14478)
		(layer "In6.Cu")
		(net "M_K_CPU0_SA_DQ<9>")
	)
	(segment
		(start 422.139872 -208.219548)
		(end 422.765982 -207.960214)
		(width 0.14478)
		(layer "In6.Cu")
		(net "M_K_CPU0_SA_DQ<9>")
	)
	(segment
		(start 389.32485 -230.714296)
		(end 389.170926 -230.979726)
		(width 0.0889)
		(layer "In6.Cu")
		(net "M_K_CPU0_SA_DQ<9>")
	)
	(arc
		(start 393.066778 -230.095044)
		(mid 393.365748 -229.991519)
		(end 393.614148 -229.795578)
		(width 0.0889)
		(layer "In6.Cu")
		(net "M_K_CPU0_SA_DQ<9>")
	)
	(arc
		(start 391.674858 -230.960422)
		(mid 391.911447 -230.913362)
		(end 392.111992 -230.77932)
		(width 0.0889)
		(layer "In6.Cu")
		(net "M_K_CPU0_SA_DQ<9>")
	)
	(arc
		(start 389.511794 -231.036622)
		(mid 389.79475 -230.960445)
		(end 390.077706 -231.036622)
		(width 0.0889)
		(layer "In6.Cu")
		(net "M_K_CPU0_SA_DQ<9>")
	)
	(arc
		(start 389.193024 -231.062784)
		(mid 389.355355 -231.085633)
		(end 389.511794 -231.036622)
		(width 0.0889)
		(layer "In6.Cu")
		(net "M_K_CPU0_SA_DQ<9>")
	)
	(arc
		(start 391.391902 -231.036622)
		(mid 391.528338 -230.979797)
		(end 391.674858 -230.960422)
		(width 0.0889)
		(layer "In6.Cu")
		(net "M_K_CPU0_SA_DQ<9>")
	)
	(arc
		(start 390.077706 -231.036622)
		(mid 390.259957 -231.087006)
		(end 390.443466 -231.041448)
		(width 0.0889)
		(layer "In6.Cu")
		(net "M_K_CPU0_SA_DQ<9>")
	)
	(arc
		(start 392.50874 -230.382572)
		(mid 392.765322 -230.195259)
		(end 393.066778 -230.095044)
		(width 0.0889)
		(layer "In6.Cu")
		(net "M_K_CPU0_SA_DQ<9>")
	)
	(arc
		(start 390.451848 -231.036622)
		(mid 390.734804 -230.960445)
		(end 391.01776 -231.036622)
		(width 0.0889)
		(layer "In6.Cu")
		(net "M_K_CPU0_SA_DQ<9>")
	)
	(arc
		(start 391.026142 -231.041448)
		(mid 391.20965 -231.086973)
		(end 391.391902 -231.036622)
		(width 0.0889)
		(layer "In6.Cu")
		(net "M_K_CPU0_SA_DQ<9>")
	)
	(segment
		(start 390.267952 -230.169974)
		(end 390.734804 -229.904036)
		(width 0.10668)
		(layer "F.Cu")
		(net "M_K_CPU0_SA_DQ<8>")
	)
	(segment
		(start 425.392342 -206.260192)
		(end 426.242226 -207.110076)
		(width 0.14478)
		(layer "In6.Cu")
		(net "M_K_CPU0_SA_DQ<8>")
	)
	(segment
		(start 390.734804 -229.904036)
		(end 390.58088 -230.169466)
		(width 0.0889)
		(layer "In6.Cu")
		(net "M_K_CPU0_SA_DQ<8>")
	)
	(segment
		(start 391.93851 -230.167688)
		(end 392.496548 -229.60965)
		(width 0.0889)
		(layer "In6.Cu")
		(net "M_K_CPU0_SA_DQ<8>")
	)
	(segment
		(start 394.099796 -228.163882)
		(end 395.117574 -227.146104)
		(width 0.0889)
		(layer "In6.Cu")
		(net "M_K_CPU0_SA_DQ<8>")
	)
	(segment
		(start 438.087008 -206.260192)
		(end 446.219326 -206.260192)
		(width 0.14478)
		(layer "In6.Cu")
		(net "M_K_CPU0_SA_DQ<8>")
	)
	(segment
		(start 395.117574 -226.586288)
		(end 395.813788 -225.890074)
		(width 0.0889)
		(layer "In6.Cu")
		(net "M_K_CPU0_SA_DQ<8>")
	)
	(segment
		(start 400.772376 -220.931486)
		(end 400.772376 -218.631262)
		(width 0.14478)
		(layer "In6.Cu")
		(net "M_K_CPU0_SA_DQ<8>")
	)
	(segment
		(start 428.521876 -207.110076)
		(end 429.476154 -206.714852)
		(width 0.14478)
		(layer "In6.Cu")
		(net "M_K_CPU0_SA_DQ<8>")
	)
	(segment
		(start 432.305968 -206.260192)
		(end 434.35778 -207.110076)
		(width 0.14478)
		(layer "In6.Cu")
		(net "M_K_CPU0_SA_DQ<8>")
	)
	(segment
		(start 395.813788 -225.890074)
		(end 400.772376 -220.931486)
		(width 0.14478)
		(layer "In6.Cu")
		(net "M_K_CPU0_SA_DQ<8>")
	)
	(segment
		(start 429.476154 -206.714852)
		(end 430.573942 -206.260192)
		(width 0.14478)
		(layer "In6.Cu")
		(net "M_K_CPU0_SA_DQ<8>")
	)
	(segment
		(start 436.035196 -207.110076)
		(end 437.24068 -206.610712)
		(width 0.14478)
		(layer "In6.Cu")
		(net "M_K_CPU0_SA_DQ<8>")
	)
	(segment
		(start 446.219326 -206.260192)
		(end 446.644268 -206.685134)
		(width 0.14478)
		(layer "In6.Cu")
		(net "M_K_CPU0_SA_DQ<8>")
	)
	(segment
		(start 414.896554 -206.259938)
		(end 417.848034 -206.259938)
		(width 0.14478)
		(layer "In6.Cu")
		(net "M_K_CPU0_SA_DQ<8>")
	)
	(segment
		(start 426.242226 -207.110076)
		(end 428.521876 -207.110076)
		(width 0.14478)
		(layer "In6.Cu")
		(net "M_K_CPU0_SA_DQ<8>")
	)
	(segment
		(start 414.046416 -207.110076)
		(end 414.896554 -206.259938)
		(width 0.14478)
		(layer "In6.Cu")
		(net "M_K_CPU0_SA_DQ<8>")
	)
	(segment
		(start 393.132056 -229.60965)
		(end 394.099796 -228.64191)
		(width 0.0889)
		(layer "In6.Cu")
		(net "M_K_CPU0_SA_DQ<8>")
	)
	(segment
		(start 437.24068 -206.610712)
		(end 438.087008 -206.260192)
		(width 0.14478)
		(layer "In6.Cu")
		(net "M_K_CPU0_SA_DQ<8>")
	)
	(segment
		(start 418.698172 -207.110076)
		(end 421.549322 -207.110076)
		(width 0.14478)
		(layer "In6.Cu")
		(net "M_K_CPU0_SA_DQ<8>")
	)
	(segment
		(start 392.496548 -229.60965)
		(end 393.132056 -229.60965)
		(width 0.0889)
		(layer "In6.Cu")
		(net "M_K_CPU0_SA_DQ<8>")
	)
	(segment
		(start 394.099796 -228.64191)
		(end 394.099796 -228.163882)
		(width 0.0889)
		(layer "In6.Cu")
		(net "M_K_CPU0_SA_DQ<8>")
	)
	(segment
		(start 400.772376 -218.631262)
		(end 412.293562 -207.110076)
		(width 0.14478)
		(layer "In6.Cu")
		(net "M_K_CPU0_SA_DQ<8>")
	)
	(segment
		(start 395.117574 -227.146104)
		(end 395.117574 -226.586288)
		(width 0.0889)
		(layer "In6.Cu")
		(net "M_K_CPU0_SA_DQ<8>")
	)
	(segment
		(start 390.58088 -230.169466)
		(end 390.603232 -230.252778)
		(width 0.0889)
		(layer "In6.Cu")
		(net "M_K_CPU0_SA_DQ<8>")
	)
	(segment
		(start 422.399206 -206.260192)
		(end 425.392342 -206.260192)
		(width 0.14478)
		(layer "In6.Cu")
		(net "M_K_CPU0_SA_DQ<8>")
	)
	(segment
		(start 412.293562 -207.110076)
		(end 414.046416 -207.110076)
		(width 0.14478)
		(layer "In6.Cu")
		(net "M_K_CPU0_SA_DQ<8>")
	)
	(segment
		(start 434.35778 -207.110076)
		(end 436.035196 -207.110076)
		(width 0.14478)
		(layer "In6.Cu")
		(net "M_K_CPU0_SA_DQ<8>")
	)
	(segment
		(start 421.549322 -207.110076)
		(end 422.399206 -206.260192)
		(width 0.14478)
		(layer "In6.Cu")
		(net "M_K_CPU0_SA_DQ<8>")
	)
	(segment
		(start 430.573942 -206.260192)
		(end 432.305968 -206.260192)
		(width 0.14478)
		(layer "In6.Cu")
		(net "M_K_CPU0_SA_DQ<8>")
	)
	(segment
		(start 417.848034 -206.259938)
		(end 418.698172 -207.110076)
		(width 0.14478)
		(layer "In6.Cu")
		(net "M_K_CPU0_SA_DQ<8>")
	)
	(arc
		(start 390.603232 -230.252778)
		(mid 390.765421 -230.275513)
		(end 390.921748 -230.226616)
		(width 0.0889)
		(layer "In6.Cu")
		(net "M_K_CPU0_SA_DQ<8>")
	)
	(arc
		(start 391.48766 -230.226616)
		(mid 391.723129 -230.273861)
		(end 391.93851 -230.167688)
		(width 0.0889)
		(layer "In6.Cu")
		(net "M_K_CPU0_SA_DQ<8>")
	)
	(arc
		(start 390.921748 -230.226616)
		(mid 391.204704 -230.150473)
		(end 391.48766 -230.226616)
		(width 0.0889)
		(layer "In6.Cu")
		(net "M_K_CPU0_SA_DQ<8>")
	)
	(segment
		(start 388.387844 -230.169974)
		(end 388.85495 -229.904036)
		(width 0.10668)
		(layer "F.Cu")
		(net "M_K_CPU0_SA_DQ<7>")
	)
	(segment
		(start 414.85693 -205.410054)
		(end 415.3281 -205.410054)
		(width 0.14478)
		(layer "In6.Cu")
		(net "M_K_CPU0_SA_DQ<7>")
	)
	(segment
		(start 441.82284 -205.265274)
		(end 441.96762 -205.410054)
		(width 0.14478)
		(layer "In6.Cu")
		(net "M_K_CPU0_SA_DQ<7>")
	)
	(segment
		(start 442.119258 -205.410054)
		(end 442.5442 -205.834996)
		(width 0.14478)
		(layer "In6.Cu")
		(net "M_K_CPU0_SA_DQ<7>")
	)
	(segment
		(start 395.77264 -225.14052)
		(end 400.210528 -220.702632)
		(width 0.14478)
		(layer "In6.Cu")
		(net "M_K_CPU0_SA_DQ<7>")
	)
	(segment
		(start 437.874664 -205.162912)
		(end 438.019444 -205.018132)
		(width 0.14478)
		(layer "In6.Cu")
		(net "M_K_CPU0_SA_DQ<7>")
	)
	(segment
		(start 430.53889 -205.177898)
		(end 430.701958 -205.01483)
		(width 0.14478)
		(layer "In6.Cu")
		(net "M_K_CPU0_SA_DQ<7>")
	)
	(segment
		(start 412.715202 -206.260192)
		(end 412.87827 -206.097124)
		(width 0.14478)
		(layer "In6.Cu")
		(net "M_K_CPU0_SA_DQ<7>")
	)
	(segment
		(start 389.607806 -229.58171)
		(end 389.616188 -229.576884)
		(width 0.0889)
		(layer "In6.Cu")
		(net "M_K_CPU0_SA_DQ<7>")
	)
	(segment
		(start 440.719972 -205.558136)
		(end 440.864752 -205.702916)
		(width 0.14478)
		(layer "In6.Cu")
		(net "M_K_CPU0_SA_DQ<7>")
	)
	(segment
		(start 423.403014 -205.02499)
		(end 423.566082 -205.188058)
		(width 0.14478)
		(layer "In6.Cu")
		(net "M_K_CPU0_SA_DQ<7>")
	)
	(segment
		(start 423.72915 -205.410054)
		(end 425.392088 -205.410054)
		(width 0.14478)
		(layer "In6.Cu")
		(net "M_K_CPU0_SA_DQ<7>")
	)
	(segment
		(start 394.881354 -226.031806)
		(end 395.77264 -225.14052)
		(width 0.0889)
		(layer "In6.Cu")
		(net "M_K_CPU0_SA_DQ<7>")
	)
	(segment
		(start 423.172636 -205.02499)
		(end 423.403014 -205.02499)
		(width 0.14478)
		(layer "In6.Cu")
		(net "M_K_CPU0_SA_DQ<7>")
	)
	(segment
		(start 441.82284 -205.261972)
		(end 441.82284 -205.265274)
		(width 0.14478)
		(layer "In6.Cu")
		(net "M_K_CPU0_SA_DQ<7>")
	)
	(segment
		(start 393.20978 -228.73081)
		(end 394.881354 -227.059236)
		(width 0.0889)
		(layer "In6.Cu")
		(net "M_K_CPU0_SA_DQ<7>")
	)
	(segment
		(start 429.931068 -205.410054)
		(end 430.375822 -205.410054)
		(width 0.14478)
		(layer "In6.Cu")
		(net "M_K_CPU0_SA_DQ<7>")
	)
	(segment
		(start 416.604196 -205.177898)
		(end 416.767264 -205.01483)
		(width 0.14478)
		(layer "In6.Cu")
		(net "M_K_CPU0_SA_DQ<7>")
	)
	(segment
		(start 423.009568 -205.246986)
		(end 423.009568 -205.188058)
		(width 0.14478)
		(layer "In6.Cu")
		(net "M_K_CPU0_SA_DQ<7>")
	)
	(segment
		(start 435.384194 -206.260192)
		(end 435.547262 -206.097124)
		(width 0.14478)
		(layer "In6.Cu")
		(net "M_K_CPU0_SA_DQ<7>")
	)
	(segment
		(start 440.168538 -205.558136)
		(end 440.168538 -205.261972)
		(width 0.14478)
		(layer "In6.Cu")
		(net "M_K_CPU0_SA_DQ<7>")
	)
	(segment
		(start 421.075358 -206.097124)
		(end 421.238426 -206.260192)
		(width 0.14478)
		(layer "In6.Cu")
		(net "M_K_CPU0_SA_DQ<7>")
	)
	(segment
		(start 421.549322 -206.260192)
		(end 422.39946 -205.410054)
		(width 0.14478)
		(layer "In6.Cu")
		(net "M_K_CPU0_SA_DQ<7>")
	)
	(segment
		(start 433.786026 -206.260192)
		(end 435.384194 -206.260192)
		(width 0.14478)
		(layer "In6.Cu")
		(net "M_K_CPU0_SA_DQ<7>")
	)
	(segment
		(start 411.592776 -206.855314)
		(end 411.592776 -206.65059)
		(width 0.14478)
		(layer "In6.Cu")
		(net "M_K_CPU0_SA_DQ<7>")
	)
	(segment
		(start 423.566082 -205.188058)
		(end 423.566082 -205.246986)
		(width 0.14478)
		(layer "In6.Cu")
		(net "M_K_CPU0_SA_DQ<7>")
	)
	(segment
		(start 388.85495 -229.904036)
		(end 389.008874 -229.638606)
		(width 0.0889)
		(layer "In6.Cu")
		(net "M_K_CPU0_SA_DQ<7>")
	)
	(segment
		(start 389.008874 -229.638606)
		(end 389.104632 -229.613206)
		(width 0.0889)
		(layer "In6.Cu")
		(net "M_K_CPU0_SA_DQ<7>")
	)
	(segment
		(start 414.006792 -206.260192)
		(end 414.85693 -205.410054)
		(width 0.14478)
		(layer "In6.Cu")
		(net "M_K_CPU0_SA_DQ<7>")
	)
	(segment
		(start 411.52699 -206.00924)
		(end 411.731714 -206.00924)
		(width 0.14478)
		(layer "In6.Cu")
		(net "M_K_CPU0_SA_DQ<7>")
	)
	(segment
		(start 417.16071 -205.246986)
		(end 417.323778 -205.410054)
		(width 0.14478)
		(layer "In6.Cu")
		(net "M_K_CPU0_SA_DQ<7>")
	)
	(segment
		(start 427.896782 -206.260192)
		(end 428.05985 -206.097124)
		(width 0.14478)
		(layer "In6.Cu")
		(net "M_K_CPU0_SA_DQ<7>")
	)
	(segment
		(start 412.87827 -206.031338)
		(end 413.041338 -205.86827)
		(width 0.14478)
		(layer "In6.Cu")
		(net "M_K_CPU0_SA_DQ<7>")
	)
	(segment
		(start 436.103776 -206.097124)
		(end 436.266844 -206.260192)
		(width 0.14478)
		(layer "In6.Cu")
		(net "M_K_CPU0_SA_DQ<7>")
	)
	(segment
		(start 435.940708 -205.86827)
		(end 436.103776 -206.031338)
		(width 0.14478)
		(layer "In6.Cu")
		(net "M_K_CPU0_SA_DQ<7>")
	)
	(segment
		(start 441.126626 -205.702916)
		(end 441.271406 -205.558136)
		(width 0.14478)
		(layer "In6.Cu")
		(net "M_K_CPU0_SA_DQ<7>")
	)
	(segment
		(start 430.53889 -205.246986)
		(end 430.53889 -205.177898)
		(width 0.14478)
		(layer "In6.Cu")
		(net "M_K_CPU0_SA_DQ<7>")
	)
	(segment
		(start 413.434784 -206.031338)
		(end 413.434784 -206.097124)
		(width 0.14478)
		(layer "In6.Cu")
		(net "M_K_CPU0_SA_DQ<7>")
	)
	(segment
		(start 420.355776 -206.260192)
		(end 420.518844 -206.097124)
		(width 0.14478)
		(layer "In6.Cu")
		(net "M_K_CPU0_SA_DQ<7>")
	)
	(segment
		(start 428.453296 -205.87335)
		(end 428.616364 -206.036418)
		(width 0.14478)
		(layer "In6.Cu")
		(net "M_K_CPU0_SA_DQ<7>")
	)
	(segment
		(start 441.416186 -205.117192)
		(end 441.67806 -205.117192)
		(width 0.14478)
		(layer "In6.Cu")
		(net "M_K_CPU0_SA_DQ<7>")
	)
	(segment
		(start 415.3281 -205.410054)
		(end 415.491168 -205.246986)
		(width 0.14478)
		(layer "In6.Cu")
		(net "M_K_CPU0_SA_DQ<7>")
	)
	(segment
		(start 417.323778 -205.410054)
		(end 417.848034 -205.410054)
		(width 0.14478)
		(layer "In6.Cu")
		(net "M_K_CPU0_SA_DQ<7>")
	)
	(segment
		(start 432.935888 -205.410054)
		(end 433.786026 -206.260192)
		(width 0.14478)
		(layer "In6.Cu")
		(net "M_K_CPU0_SA_DQ<7>")
	)
	(segment
		(start 416.767264 -205.01483)
		(end 416.997642 -205.01483)
		(width 0.14478)
		(layer "In6.Cu")
		(net "M_K_CPU0_SA_DQ<7>")
	)
	(segment
		(start 422.8465 -205.410054)
		(end 423.009568 -205.246986)
		(width 0.14478)
		(layer "In6.Cu")
		(net "M_K_CPU0_SA_DQ<7>")
	)
	(segment
		(start 438.281318 -205.018132)
		(end 438.426098 -205.162912)
		(width 0.14478)
		(layer "In6.Cu")
		(net "M_K_CPU0_SA_DQ<7>")
	)
	(segment
		(start 439.617104 -205.558136)
		(end 439.761884 -205.702916)
		(width 0.14478)
		(layer "In6.Cu")
		(net "M_K_CPU0_SA_DQ<7>")
	)
	(segment
		(start 416.997642 -205.01483)
		(end 417.16071 -205.177898)
		(width 0.14478)
		(layer "In6.Cu")
		(net "M_K_CPU0_SA_DQ<7>")
	)
	(segment
		(start 440.023758 -205.702916)
		(end 440.168538 -205.558136)
		(width 0.14478)
		(layer "In6.Cu")
		(net "M_K_CPU0_SA_DQ<7>")
	)
	(segment
		(start 428.616364 -206.097124)
		(end 428.779432 -206.260192)
		(width 0.14478)
		(layer "In6.Cu")
		(net "M_K_CPU0_SA_DQ<7>")
	)
	(segment
		(start 437.874664 -205.265274)
		(end 437.874664 -205.162912)
		(width 0.14478)
		(layer "In6.Cu")
		(net "M_K_CPU0_SA_DQ<7>")
	)
	(segment
		(start 420.518844 -206.097124)
		(end 420.518844 -206.031338)
		(width 0.14478)
		(layer "In6.Cu")
		(net "M_K_CPU0_SA_DQ<7>")
	)
	(segment
		(start 438.426098 -205.162912)
		(end 438.426098 -205.265274)
		(width 0.14478)
		(layer "In6.Cu")
		(net "M_K_CPU0_SA_DQ<7>")
	)
	(segment
		(start 421.238426 -206.260192)
		(end 421.549322 -206.260192)
		(width 0.14478)
		(layer "In6.Cu")
		(net "M_K_CPU0_SA_DQ<7>")
	)
	(segment
		(start 400.210528 -220.702632)
		(end 400.210528 -218.237562)
		(width 0.14478)
		(layer "In6.Cu")
		(net "M_K_CPU0_SA_DQ<7>")
	)
	(segment
		(start 436.103776 -206.031338)
		(end 436.103776 -206.097124)
		(width 0.14478)
		(layer "In6.Cu")
		(net "M_K_CPU0_SA_DQ<7>")
	)
	(segment
		(start 392.926316 -228.73081)
		(end 393.20978 -228.73081)
		(width 0.0889)
		(layer "In6.Cu")
		(net "M_K_CPU0_SA_DQ<7>")
	)
	(segment
		(start 416.604196 -205.246986)
		(end 416.604196 -205.177898)
		(width 0.14478)
		(layer "In6.Cu")
		(net "M_K_CPU0_SA_DQ<7>")
	)
	(segment
		(start 441.96762 -205.410054)
		(end 442.119258 -205.410054)
		(width 0.14478)
		(layer "In6.Cu")
		(net "M_K_CPU0_SA_DQ<7>")
	)
	(segment
		(start 413.271716 -205.86827)
		(end 413.434784 -206.031338)
		(width 0.14478)
		(layer "In6.Cu")
		(net "M_K_CPU0_SA_DQ<7>")
	)
	(segment
		(start 420.681912 -205.86827)
		(end 420.91229 -205.86827)
		(width 0.14478)
		(layer "In6.Cu")
		(net "M_K_CPU0_SA_DQ<7>")
	)
	(segment
		(start 435.547262 -206.097124)
		(end 435.547262 -206.031338)
		(width 0.14478)
		(layer "In6.Cu")
		(net "M_K_CPU0_SA_DQ<7>")
	)
	(segment
		(start 415.654236 -205.01483)
		(end 415.884614 -205.01483)
		(width 0.14478)
		(layer "In6.Cu")
		(net "M_K_CPU0_SA_DQ<7>")
	)
	(segment
		(start 428.05985 -206.036418)
		(end 428.222918 -205.87335)
		(width 0.14478)
		(layer "In6.Cu")
		(net "M_K_CPU0_SA_DQ<7>")
	)
	(segment
		(start 415.491168 -205.177898)
		(end 415.654236 -205.01483)
		(width 0.14478)
		(layer "In6.Cu")
		(net "M_K_CPU0_SA_DQ<7>")
	)
	(segment
		(start 440.719972 -205.261972)
		(end 440.719972 -205.558136)
		(width 0.14478)
		(layer "In6.Cu")
		(net "M_K_CPU0_SA_DQ<7>")
	)
	(segment
		(start 441.67806 -205.117192)
		(end 441.82284 -205.261972)
		(width 0.14478)
		(layer "In6.Cu")
		(net "M_K_CPU0_SA_DQ<7>")
	)
	(segment
		(start 440.864752 -205.702916)
		(end 441.126626 -205.702916)
		(width 0.14478)
		(layer "In6.Cu")
		(net "M_K_CPU0_SA_DQ<7>")
	)
	(segment
		(start 416.047682 -205.177898)
		(end 416.047682 -205.246986)
		(width 0.14478)
		(layer "In6.Cu")
		(net "M_K_CPU0_SA_DQ<7>")
	)
	(segment
		(start 418.698172 -206.260192)
		(end 420.355776 -206.260192)
		(width 0.14478)
		(layer "In6.Cu")
		(net "M_K_CPU0_SA_DQ<7>")
	)
	(segment
		(start 438.570878 -205.410054)
		(end 439.472324 -205.410054)
		(width 0.14478)
		(layer "In6.Cu")
		(net "M_K_CPU0_SA_DQ<7>")
	)
	(segment
		(start 437.729884 -205.410054)
		(end 437.874664 -205.265274)
		(width 0.14478)
		(layer "In6.Cu")
		(net "M_K_CPU0_SA_DQ<7>")
	)
	(segment
		(start 417.848034 -205.410054)
		(end 418.698172 -206.260192)
		(width 0.14478)
		(layer "In6.Cu")
		(net "M_K_CPU0_SA_DQ<7>")
	)
	(segment
		(start 411.34157 -206.399384)
		(end 411.34157 -206.19466)
		(width 0.14478)
		(layer "In6.Cu")
		(net "M_K_CPU0_SA_DQ<7>")
	)
	(segment
		(start 440.168538 -205.261972)
		(end 440.313318 -205.117192)
		(width 0.14478)
		(layer "In6.Cu")
		(net "M_K_CPU0_SA_DQ<7>")
	)
	(segment
		(start 411.34157 -206.19466)
		(end 411.52699 -206.00924)
		(width 0.14478)
		(layer "In6.Cu")
		(net "M_K_CPU0_SA_DQ<7>")
	)
	(segment
		(start 415.884614 -205.01483)
		(end 416.047682 -205.177898)
		(width 0.14478)
		(layer "In6.Cu")
		(net "M_K_CPU0_SA_DQ<7>")
	)
	(segment
		(start 436.6133 -206.260192)
		(end 437.463438 -205.410054)
		(width 0.14478)
		(layer "In6.Cu")
		(net "M_K_CPU0_SA_DQ<7>")
	)
	(segment
		(start 431.095404 -205.246986)
		(end 431.258472 -205.410054)
		(width 0.14478)
		(layer "In6.Cu")
		(net "M_K_CPU0_SA_DQ<7>")
	)
	(segment
		(start 425.392088 -205.410054)
		(end 426.242226 -206.260192)
		(width 0.14478)
		(layer "In6.Cu")
		(net "M_K_CPU0_SA_DQ<7>")
	)
	(segment
		(start 420.518844 -206.031338)
		(end 420.681912 -205.86827)
		(width 0.14478)
		(layer "In6.Cu")
		(net "M_K_CPU0_SA_DQ<7>")
	)
	(segment
		(start 413.041338 -205.86827)
		(end 413.271716 -205.86827)
		(width 0.14478)
		(layer "In6.Cu")
		(net "M_K_CPU0_SA_DQ<7>")
	)
	(segment
		(start 439.761884 -205.702916)
		(end 440.023758 -205.702916)
		(width 0.14478)
		(layer "In6.Cu")
		(net "M_K_CPU0_SA_DQ<7>")
	)
	(segment
		(start 429.08093 -206.260192)
		(end 429.931068 -205.410054)
		(width 0.14478)
		(layer "In6.Cu")
		(net "M_K_CPU0_SA_DQ<7>")
	)
	(segment
		(start 411.982666 -206.260192)
		(end 412.715202 -206.260192)
		(width 0.14478)
		(layer "In6.Cu")
		(net "M_K_CPU0_SA_DQ<7>")
	)
	(segment
		(start 440.313318 -205.117192)
		(end 440.575192 -205.117192)
		(width 0.14478)
		(layer "In6.Cu")
		(net "M_K_CPU0_SA_DQ<7>")
	)
	(segment
		(start 423.009568 -205.188058)
		(end 423.172636 -205.02499)
		(width 0.14478)
		(layer "In6.Cu")
		(net "M_K_CPU0_SA_DQ<7>")
	)
	(segment
		(start 400.210528 -218.237562)
		(end 411.592776 -206.855314)
		(width 0.14478)
		(layer "In6.Cu")
		(net "M_K_CPU0_SA_DQ<7>")
	)
	(segment
		(start 417.16071 -205.177898)
		(end 417.16071 -205.246986)
		(width 0.14478)
		(layer "In6.Cu")
		(net "M_K_CPU0_SA_DQ<7>")
	)
	(segment
		(start 439.472324 -205.410054)
		(end 439.617104 -205.554834)
		(width 0.14478)
		(layer "In6.Cu")
		(net "M_K_CPU0_SA_DQ<7>")
	)
	(segment
		(start 391.674858 -229.53091)
		(end 392.126216 -229.53091)
		(width 0.0889)
		(layer "In6.Cu")
		(net "M_K_CPU0_SA_DQ<7>")
	)
	(segment
		(start 428.222918 -205.87335)
		(end 428.453296 -205.87335)
		(width 0.14478)
		(layer "In6.Cu")
		(net "M_K_CPU0_SA_DQ<7>")
	)
	(segment
		(start 439.617104 -205.554834)
		(end 439.617104 -205.558136)
		(width 0.14478)
		(layer "In6.Cu")
		(net "M_K_CPU0_SA_DQ<7>")
	)
	(segment
		(start 428.05985 -206.097124)
		(end 428.05985 -206.036418)
		(width 0.14478)
		(layer "In6.Cu")
		(net "M_K_CPU0_SA_DQ<7>")
	)
	(segment
		(start 411.731714 -206.00924)
		(end 411.982666 -206.260192)
		(width 0.14478)
		(layer "In6.Cu")
		(net "M_K_CPU0_SA_DQ<7>")
	)
	(segment
		(start 435.547262 -206.031338)
		(end 435.71033 -205.86827)
		(width 0.14478)
		(layer "In6.Cu")
		(net "M_K_CPU0_SA_DQ<7>")
	)
	(segment
		(start 416.047682 -205.246986)
		(end 416.21075 -205.410054)
		(width 0.14478)
		(layer "In6.Cu")
		(net "M_K_CPU0_SA_DQ<7>")
	)
	(segment
		(start 420.91229 -205.86827)
		(end 421.075358 -206.031338)
		(width 0.14478)
		(layer "In6.Cu")
		(net "M_K_CPU0_SA_DQ<7>")
	)
	(segment
		(start 431.095404 -205.177898)
		(end 431.095404 -205.246986)
		(width 0.14478)
		(layer "In6.Cu")
		(net "M_K_CPU0_SA_DQ<7>")
	)
	(segment
		(start 430.375822 -205.410054)
		(end 430.53889 -205.246986)
		(width 0.14478)
		(layer "In6.Cu")
		(net "M_K_CPU0_SA_DQ<7>")
	)
	(segment
		(start 430.701958 -205.01483)
		(end 430.932336 -205.01483)
		(width 0.14478)
		(layer "In6.Cu")
		(net "M_K_CPU0_SA_DQ<7>")
	)
	(segment
		(start 421.075358 -206.031338)
		(end 421.075358 -206.097124)
		(width 0.14478)
		(layer "In6.Cu")
		(net "M_K_CPU0_SA_DQ<7>")
	)
	(segment
		(start 394.881354 -227.059236)
		(end 394.881354 -226.031806)
		(width 0.0889)
		(layer "In6.Cu")
		(net "M_K_CPU0_SA_DQ<7>")
	)
	(segment
		(start 428.779432 -206.260192)
		(end 429.08093 -206.260192)
		(width 0.14478)
		(layer "In6.Cu")
		(net "M_K_CPU0_SA_DQ<7>")
	)
	(segment
		(start 438.019444 -205.018132)
		(end 438.281318 -205.018132)
		(width 0.14478)
		(layer "In6.Cu")
		(net "M_K_CPU0_SA_DQ<7>")
	)
	(segment
		(start 430.932336 -205.01483)
		(end 431.095404 -205.177898)
		(width 0.14478)
		(layer "In6.Cu")
		(net "M_K_CPU0_SA_DQ<7>")
	)
	(segment
		(start 411.592776 -206.65059)
		(end 411.34157 -206.399384)
		(width 0.14478)
		(layer "In6.Cu")
		(net "M_K_CPU0_SA_DQ<7>")
	)
	(segment
		(start 441.271406 -205.558136)
		(end 441.271406 -205.261972)
		(width 0.14478)
		(layer "In6.Cu")
		(net "M_K_CPU0_SA_DQ<7>")
	)
	(segment
		(start 431.258472 -205.410054)
		(end 432.935888 -205.410054)
		(width 0.14478)
		(layer "In6.Cu")
		(net "M_K_CPU0_SA_DQ<7>")
	)
	(segment
		(start 441.271406 -205.261972)
		(end 441.416186 -205.117192)
		(width 0.14478)
		(layer "In6.Cu")
		(net "M_K_CPU0_SA_DQ<7>")
	)
	(segment
		(start 437.463438 -205.410054)
		(end 437.729884 -205.410054)
		(width 0.14478)
		(layer "In6.Cu")
		(net "M_K_CPU0_SA_DQ<7>")
	)
	(segment
		(start 416.21075 -205.410054)
		(end 416.441128 -205.410054)
		(width 0.14478)
		(layer "In6.Cu")
		(net "M_K_CPU0_SA_DQ<7>")
	)
	(segment
		(start 413.434784 -206.097124)
		(end 413.597852 -206.260192)
		(width 0.14478)
		(layer "In6.Cu")
		(net "M_K_CPU0_SA_DQ<7>")
	)
	(segment
		(start 416.441128 -205.410054)
		(end 416.604196 -205.246986)
		(width 0.14478)
		(layer "In6.Cu")
		(net "M_K_CPU0_SA_DQ<7>")
	)
	(segment
		(start 415.491168 -205.246986)
		(end 415.491168 -205.177898)
		(width 0.14478)
		(layer "In6.Cu")
		(net "M_K_CPU0_SA_DQ<7>")
	)
	(segment
		(start 392.126216 -229.53091)
		(end 392.926316 -228.73081)
		(width 0.0889)
		(layer "In6.Cu")
		(net "M_K_CPU0_SA_DQ<7>")
	)
	(segment
		(start 435.71033 -205.86827)
		(end 435.940708 -205.86827)
		(width 0.14478)
		(layer "In6.Cu")
		(net "M_K_CPU0_SA_DQ<7>")
	)
	(segment
		(start 423.566082 -205.246986)
		(end 423.72915 -205.410054)
		(width 0.14478)
		(layer "In6.Cu")
		(net "M_K_CPU0_SA_DQ<7>")
	)
	(segment
		(start 412.87827 -206.097124)
		(end 412.87827 -206.031338)
		(width 0.14478)
		(layer "In6.Cu")
		(net "M_K_CPU0_SA_DQ<7>")
	)
	(segment
		(start 413.597852 -206.260192)
		(end 414.006792 -206.260192)
		(width 0.14478)
		(layer "In6.Cu")
		(net "M_K_CPU0_SA_DQ<7>")
	)
	(segment
		(start 438.426098 -205.265274)
		(end 438.570878 -205.410054)
		(width 0.14478)
		(layer "In6.Cu")
		(net "M_K_CPU0_SA_DQ<7>")
	)
	(segment
		(start 440.575192 -205.117192)
		(end 440.719972 -205.261972)
		(width 0.14478)
		(layer "In6.Cu")
		(net "M_K_CPU0_SA_DQ<7>")
	)
	(segment
		(start 422.39946 -205.410054)
		(end 422.8465 -205.410054)
		(width 0.14478)
		(layer "In6.Cu")
		(net "M_K_CPU0_SA_DQ<7>")
	)
	(segment
		(start 436.266844 -206.260192)
		(end 436.6133 -206.260192)
		(width 0.14478)
		(layer "In6.Cu")
		(net "M_K_CPU0_SA_DQ<7>")
	)
	(segment
		(start 428.616364 -206.036418)
		(end 428.616364 -206.097124)
		(width 0.14478)
		(layer "In6.Cu")
		(net "M_K_CPU0_SA_DQ<7>")
	)
	(segment
		(start 426.242226 -206.260192)
		(end 427.896782 -206.260192)
		(width 0.14478)
		(layer "In6.Cu")
		(net "M_K_CPU0_SA_DQ<7>")
	)
	(arc
		(start 391.48766 -229.58171)
		(mid 391.577896 -229.543908)
		(end 391.674858 -229.53091)
		(width 0.0889)
		(layer "In6.Cu")
		(net "M_K_CPU0_SA_DQ<7>")
	)
	(arc
		(start 389.981948 -229.58171)
		(mid 390.264904 -229.657887)
		(end 390.54786 -229.58171)
		(width 0.0889)
		(layer "In6.Cu")
		(net "M_K_CPU0_SA_DQ<7>")
	)
	(arc
		(start 389.104632 -229.613206)
		(mid 389.359954 -229.656906)
		(end 389.607806 -229.58171)
		(width 0.0889)
		(layer "In6.Cu")
		(net "M_K_CPU0_SA_DQ<7>")
	)
	(arc
		(start 389.616188 -229.576884)
		(mid 389.799696 -229.531359)
		(end 389.981948 -229.58171)
		(width 0.0889)
		(layer "In6.Cu")
		(net "M_K_CPU0_SA_DQ<7>")
	)
	(arc
		(start 390.921748 -229.58171)
		(mid 391.204704 -229.657887)
		(end 391.48766 -229.58171)
		(width 0.0889)
		(layer "In6.Cu")
		(net "M_K_CPU0_SA_DQ<7>")
	)
	(arc
		(start 390.54786 -229.58171)
		(mid 390.734804 -229.531421)
		(end 390.921748 -229.58171)
		(width 0.0889)
		(layer "In6.Cu")
		(net "M_K_CPU0_SA_DQ<7>")
	)
	(segment
		(start 389.798052 -229.360222)
		(end 390.264904 -229.094284)
		(width 0.10668)
		(layer "F.Cu")
		(net "M_K_CPU0_SA_DQ<6>")
	)
	(segment
		(start 428.56277 -204.397102)
		(end 428.725838 -204.56017)
		(width 0.14478)
		(layer "In6.Cu")
		(net "M_K_CPU0_SA_DQ<6>")
	)
	(segment
		(start 418.698172 -204.56017)
		(end 420.355522 -204.56017)
		(width 0.14478)
		(layer "In6.Cu")
		(net "M_K_CPU0_SA_DQ<6>")
	)
	(segment
		(start 440.233562 -203.331572)
		(end 440.39663 -203.49464)
		(width 0.14478)
		(layer "In6.Cu")
		(net "M_K_CPU0_SA_DQ<6>")
	)
	(segment
		(start 394.0302 -226.17049)
		(end 394.924534 -225.276156)
		(width 0.0889)
		(layer "In6.Cu")
		(net "M_K_CPU0_SA_DQ<6>")
	)
	(segment
		(start 423.524172 -203.546964)
		(end 423.68724 -203.710032)
		(width 0.14478)
		(layer "In6.Cu")
		(net "M_K_CPU0_SA_DQ<6>")
	)
	(segment
		(start 417.443158 -203.710032)
		(end 417.848034 -203.710032)
		(width 0.14478)
		(layer "In6.Cu")
		(net "M_K_CPU0_SA_DQ<6>")
	)
	(segment
		(start 435.553358 -204.33538)
		(end 435.716426 -204.172312)
		(width 0.14478)
		(layer "In6.Cu")
		(net "M_K_CPU0_SA_DQ<6>")
	)
	(segment
		(start 430.322228 -203.710032)
		(end 430.485296 -203.546964)
		(width 0.14478)
		(layer "In6.Cu")
		(net "M_K_CPU0_SA_DQ<6>")
	)
	(segment
		(start 440.953144 -203.938886)
		(end 440.953144 -203.5048)
		(width 0.14478)
		(layer "In6.Cu")
		(net "M_K_CPU0_SA_DQ<6>")
	)
	(segment
		(start 407.258012 -209.633312)
		(end 407.462736 -209.633312)
		(width 0.14478)
		(layer "In6.Cu")
		(net "M_K_CPU0_SA_DQ<6>")
	)
	(segment
		(start 436.109872 -204.33538)
		(end 436.109872 -204.397102)
		(width 0.14478)
		(layer "In6.Cu")
		(net "M_K_CPU0_SA_DQ<6>")
	)
	(segment
		(start 407.648156 -209.447892)
		(end 407.648156 -209.243168)
		(width 0.14478)
		(layer "In6.Cu")
		(net "M_K_CPU0_SA_DQ<6>")
	)
	(segment
		(start 423.68724 -203.710032)
		(end 425.392088 -203.710032)
		(width 0.14478)
		(layer "In6.Cu")
		(net "M_K_CPU0_SA_DQ<6>")
	)
	(segment
		(start 393.701016 -227.650802)
		(end 393.701016 -226.965256)
		(width 0.0889)
		(layer "In6.Cu")
		(net "M_K_CPU0_SA_DQ<6>")
	)
	(segment
		(start 408.243024 -208.853024)
		(end 408.447494 -208.648554)
		(width 0.14478)
		(layer "In6.Cu")
		(net "M_K_CPU0_SA_DQ<6>")
	)
	(segment
		(start 425.392088 -203.710032)
		(end 426.242226 -204.56017)
		(width 0.14478)
		(layer "In6.Cu")
		(net "M_K_CPU0_SA_DQ<6>")
	)
	(segment
		(start 432.935888 -203.710032)
		(end 433.786026 -204.56017)
		(width 0.14478)
		(layer "In6.Cu")
		(net "M_K_CPU0_SA_DQ<6>")
	)
	(segment
		(start 406.867868 -210.023456)
		(end 406.578816 -209.734404)
		(width 0.14478)
		(layer "In6.Cu")
		(net "M_K_CPU0_SA_DQ<6>")
	)
	(segment
		(start 407.462736 -209.633312)
		(end 407.648156 -209.447892)
		(width 0.14478)
		(layer "In6.Cu")
		(net "M_K_CPU0_SA_DQ<6>")
	)
	(segment
		(start 428.56277 -204.334618)
		(end 428.56277 -204.397102)
		(width 0.14478)
		(layer "In6.Cu")
		(net "M_K_CPU0_SA_DQ<6>")
	)
	(segment
		(start 441.509658 -203.5048)
		(end 441.509658 -203.546964)
		(width 0.14478)
		(layer "In6.Cu")
		(net "M_K_CPU0_SA_DQ<6>")
	)
	(segment
		(start 430.878742 -203.32319)
		(end 431.04181 -203.486258)
		(width 0.14478)
		(layer "In6.Cu")
		(net "M_K_CPU0_SA_DQ<6>")
	)
	(segment
		(start 391.01776 -228.771704)
		(end 391.026142 -228.766878)
		(width 0.0889)
		(layer "In6.Cu")
		(net "M_K_CPU0_SA_DQ<6>")
	)
	(segment
		(start 439.677048 -203.710032)
		(end 439.840116 -203.546964)
		(width 0.14478)
		(layer "In6.Cu")
		(net "M_K_CPU0_SA_DQ<6>")
	)
	(segment
		(start 416.723576 -203.546964)
		(end 416.723576 -203.48448)
		(width 0.14478)
		(layer "In6.Cu")
		(net "M_K_CPU0_SA_DQ<6>")
	)
	(segment
		(start 393.184888 -228.16693)
		(end 393.701016 -227.650802)
		(width 0.0889)
		(layer "In6.Cu")
		(net "M_K_CPU0_SA_DQ<6>")
	)
	(segment
		(start 441.116212 -203.341732)
		(end 441.34659 -203.341732)
		(width 0.14478)
		(layer "In6.Cu")
		(net "M_K_CPU0_SA_DQ<6>")
	)
	(segment
		(start 438.66816 -203.710032)
		(end 439.677048 -203.710032)
		(width 0.14478)
		(layer "In6.Cu")
		(net "M_K_CPU0_SA_DQ<6>")
	)
	(segment
		(start 423.130726 -203.321412)
		(end 423.361104 -203.321412)
		(width 0.14478)
		(layer "In6.Cu")
		(net "M_K_CPU0_SA_DQ<6>")
	)
	(segment
		(start 430.485296 -203.546964)
		(end 430.485296 -203.486258)
		(width 0.14478)
		(layer "In6.Cu")
		(net "M_K_CPU0_SA_DQ<6>")
	)
	(segment
		(start 391.674858 -228.847904)
		(end 392.04265 -228.847904)
		(width 0.0889)
		(layer "In6.Cu")
		(net "M_K_CPU0_SA_DQ<6>")
	)
	(segment
		(start 438.505092 -203.937362)
		(end 438.505092 -203.8731)
		(width 0.14478)
		(layer "In6.Cu")
		(net "M_K_CPU0_SA_DQ<6>")
	)
	(segment
		(start 412.782766 -204.397102)
		(end 412.782766 -204.329538)
		(width 0.14478)
		(layer "In6.Cu")
		(net "M_K_CPU0_SA_DQ<6>")
	)
	(segment
		(start 415.610548 -203.48194)
		(end 415.773616 -203.318872)
		(width 0.14478)
		(layer "In6.Cu")
		(net "M_K_CPU0_SA_DQ<6>")
	)
	(segment
		(start 423.361104 -203.321412)
		(end 423.524172 -203.48448)
		(width 0.14478)
		(layer "In6.Cu")
		(net "M_K_CPU0_SA_DQ<6>")
	)
	(segment
		(start 407.648156 -209.243168)
		(end 407.359104 -208.954116)
		(width 0.14478)
		(layer "In6.Cu")
		(net "M_K_CPU0_SA_DQ<6>")
	)
	(segment
		(start 413.502348 -204.56017)
		(end 414.006792 -204.56017)
		(width 0.14478)
		(layer "In6.Cu")
		(net "M_K_CPU0_SA_DQ<6>")
	)
	(segment
		(start 440.39663 -203.938886)
		(end 440.559698 -204.101954)
		(width 0.14478)
		(layer "In6.Cu")
		(net "M_K_CPU0_SA_DQ<6>")
	)
	(segment
		(start 420.51859 -204.332078)
		(end 420.681658 -204.16901)
		(width 0.14478)
		(layer "In6.Cu")
		(net "M_K_CPU0_SA_DQ<6>")
	)
	(segment
		(start 440.953144 -203.5048)
		(end 441.116212 -203.341732)
		(width 0.14478)
		(layer "In6.Cu")
		(net "M_K_CPU0_SA_DQ<6>")
	)
	(segment
		(start 417.848034 -203.710032)
		(end 418.698172 -204.56017)
		(width 0.14478)
		(layer "In6.Cu")
		(net "M_K_CPU0_SA_DQ<6>")
	)
	(segment
		(start 412.619698 -204.56017)
		(end 412.782766 -204.397102)
		(width 0.14478)
		(layer "In6.Cu")
		(net "M_K_CPU0_SA_DQ<6>")
	)
	(segment
		(start 406.96896 -209.34426)
		(end 407.258012 -209.633312)
		(width 0.14478)
		(layer "In6.Cu")
		(net "M_K_CPU0_SA_DQ<6>")
	)
	(segment
		(start 437.948578 -203.8731)
		(end 437.948578 -203.937362)
		(width 0.14478)
		(layer "In6.Cu")
		(net "M_K_CPU0_SA_DQ<6>")
	)
	(segment
		(start 415.610548 -203.546964)
		(end 415.610548 -203.48194)
		(width 0.14478)
		(layer "In6.Cu")
		(net "M_K_CPU0_SA_DQ<6>")
	)
	(segment
		(start 422.967658 -203.48448)
		(end 423.130726 -203.321412)
		(width 0.14478)
		(layer "In6.Cu")
		(net "M_K_CPU0_SA_DQ<6>")
	)
	(segment
		(start 411.53334 -204.56017)
		(end 412.619698 -204.56017)
		(width 0.14478)
		(layer "In6.Cu")
		(net "M_K_CPU0_SA_DQ<6>")
	)
	(segment
		(start 394.924534 -225.276156)
		(end 394.924534 -224.571306)
		(width 0.0889)
		(layer "In6.Cu")
		(net "M_K_CPU0_SA_DQ<6>")
	)
	(segment
		(start 407.359104 -208.749392)
		(end 407.544524 -208.563972)
		(width 0.14478)
		(layer "In6.Cu")
		(net "M_K_CPU0_SA_DQ<6>")
	)
	(segment
		(start 428.006256 -204.397102)
		(end 428.006256 -204.334618)
		(width 0.14478)
		(layer "In6.Cu")
		(net "M_K_CPU0_SA_DQ<6>")
	)
	(segment
		(start 436.6133 -204.56017)
		(end 437.463438 -203.710032)
		(width 0.14478)
		(layer "In6.Cu")
		(net "M_K_CPU0_SA_DQ<6>")
	)
	(segment
		(start 390.264904 -229.094284)
		(end 390.418828 -228.828854)
		(width 0.0889)
		(layer "In6.Cu")
		(net "M_K_CPU0_SA_DQ<6>")
	)
	(segment
		(start 440.559698 -204.101954)
		(end 440.790076 -204.101954)
		(width 0.14478)
		(layer "In6.Cu")
		(net "M_K_CPU0_SA_DQ<6>")
	)
	(segment
		(start 417.28009 -203.546964)
		(end 417.443158 -203.710032)
		(width 0.14478)
		(layer "In6.Cu")
		(net "M_K_CPU0_SA_DQ<6>")
	)
	(segment
		(start 399.210276 -217.885772)
		(end 406.867868 -210.22818)
		(width 0.14478)
		(layer "In6.Cu")
		(net "M_K_CPU0_SA_DQ<6>")
	)
	(segment
		(start 422.80459 -203.710032)
		(end 422.967658 -203.546964)
		(width 0.14478)
		(layer "In6.Cu")
		(net "M_K_CPU0_SA_DQ<6>")
	)
	(segment
		(start 416.886644 -203.321412)
		(end 417.117022 -203.321412)
		(width 0.14478)
		(layer "In6.Cu")
		(net "M_K_CPU0_SA_DQ<6>")
	)
	(segment
		(start 430.648364 -203.32319)
		(end 430.878742 -203.32319)
		(width 0.14478)
		(layer "In6.Cu")
		(net "M_K_CPU0_SA_DQ<6>")
	)
	(segment
		(start 435.39029 -204.56017)
		(end 435.553358 -204.397102)
		(width 0.14478)
		(layer "In6.Cu")
		(net "M_K_CPU0_SA_DQ<6>")
	)
	(segment
		(start 429.08093 -204.56017)
		(end 429.931068 -203.710032)
		(width 0.14478)
		(layer "In6.Cu")
		(net "M_K_CPU0_SA_DQ<6>")
	)
	(segment
		(start 427.843188 -204.56017)
		(end 428.006256 -204.397102)
		(width 0.14478)
		(layer "In6.Cu")
		(net "M_K_CPU0_SA_DQ<6>")
	)
	(segment
		(start 407.749248 -208.563972)
		(end 408.0383 -208.853024)
		(width 0.14478)
		(layer "In6.Cu")
		(net "M_K_CPU0_SA_DQ<6>")
	)
	(segment
		(start 420.681658 -204.16901)
		(end 420.912036 -204.16901)
		(width 0.14478)
		(layer "In6.Cu")
		(net "M_K_CPU0_SA_DQ<6>")
	)
	(segment
		(start 408.0383 -208.853024)
		(end 408.243024 -208.853024)
		(width 0.14478)
		(layer "In6.Cu")
		(net "M_K_CPU0_SA_DQ<6>")
	)
	(segment
		(start 416.560508 -203.710032)
		(end 416.723576 -203.546964)
		(width 0.14478)
		(layer "In6.Cu")
		(net "M_K_CPU0_SA_DQ<6>")
	)
	(segment
		(start 436.109872 -204.397102)
		(end 436.27294 -204.56017)
		(width 0.14478)
		(layer "In6.Cu")
		(net "M_K_CPU0_SA_DQ<6>")
	)
	(segment
		(start 413.33928 -204.397102)
		(end 413.502348 -204.56017)
		(width 0.14478)
		(layer "In6.Cu")
		(net "M_K_CPU0_SA_DQ<6>")
	)
	(segment
		(start 416.167062 -203.48194)
		(end 416.167062 -203.546964)
		(width 0.14478)
		(layer "In6.Cu")
		(net "M_K_CPU0_SA_DQ<6>")
	)
	(segment
		(start 437.463438 -203.710032)
		(end 437.78551 -203.710032)
		(width 0.14478)
		(layer "In6.Cu")
		(net "M_K_CPU0_SA_DQ<6>")
	)
	(segment
		(start 406.578816 -209.52968)
		(end 406.764236 -209.34426)
		(width 0.14478)
		(layer "In6.Cu")
		(net "M_K_CPU0_SA_DQ<6>")
	)
	(segment
		(start 416.003994 -203.318872)
		(end 416.167062 -203.48194)
		(width 0.14478)
		(layer "In6.Cu")
		(net "M_K_CPU0_SA_DQ<6>")
	)
	(segment
		(start 390.418828 -228.828854)
		(end 390.51484 -228.803454)
		(width 0.0889)
		(layer "In6.Cu")
		(net "M_K_CPU0_SA_DQ<6>")
	)
	(segment
		(start 429.931068 -203.710032)
		(end 430.322228 -203.710032)
		(width 0.14478)
		(layer "In6.Cu")
		(net "M_K_CPU0_SA_DQ<6>")
	)
	(segment
		(start 422.967658 -203.546964)
		(end 422.967658 -203.48448)
		(width 0.14478)
		(layer "In6.Cu")
		(net "M_K_CPU0_SA_DQ<6>")
	)
	(segment
		(start 440.790076 -204.101954)
		(end 440.953144 -203.938886)
		(width 0.14478)
		(layer "In6.Cu")
		(net "M_K_CPU0_SA_DQ<6>")
	)
	(segment
		(start 442.119258 -203.710032)
		(end 442.5442 -204.134974)
		(width 0.14478)
		(layer "In6.Cu")
		(net "M_K_CPU0_SA_DQ<6>")
	)
	(segment
		(start 395.751304 -223.744536)
		(end 395.75359 -223.744536)
		(width 0.0889)
		(layer "In6.Cu")
		(net "M_K_CPU0_SA_DQ<6>")
	)
	(segment
		(start 431.204878 -203.710032)
		(end 432.935888 -203.710032)
		(width 0.14478)
		(layer "In6.Cu")
		(net "M_K_CPU0_SA_DQ<6>")
	)
	(segment
		(start 439.840116 -203.49464)
		(end 440.003184 -203.331572)
		(width 0.14478)
		(layer "In6.Cu")
		(net "M_K_CPU0_SA_DQ<6>")
	)
	(segment
		(start 394.924534 -224.571306)
		(end 395.751304 -223.744536)
		(width 0.0889)
		(layer "In6.Cu")
		(net "M_K_CPU0_SA_DQ<6>")
	)
	(segment
		(start 421.549322 -204.56017)
		(end 422.39946 -203.710032)
		(width 0.14478)
		(layer "In6.Cu")
		(net "M_K_CPU0_SA_DQ<6>")
	)
	(segment
		(start 438.111646 -204.10043)
		(end 438.342024 -204.10043)
		(width 0.14478)
		(layer "In6.Cu")
		(net "M_K_CPU0_SA_DQ<6>")
	)
	(segment
		(start 417.28009 -203.48448)
		(end 417.28009 -203.546964)
		(width 0.14478)
		(layer "In6.Cu")
		(net "M_K_CPU0_SA_DQ<6>")
	)
	(segment
		(start 395.75359 -223.744536)
		(end 399.210276 -220.28785)
		(width 0.14478)
		(layer "In6.Cu")
		(net "M_K_CPU0_SA_DQ<6>")
	)
	(segment
		(start 433.786026 -204.56017)
		(end 435.39029 -204.56017)
		(width 0.14478)
		(layer "In6.Cu")
		(net "M_K_CPU0_SA_DQ<6>")
	)
	(segment
		(start 437.948578 -203.937362)
		(end 438.111646 -204.10043)
		(width 0.14478)
		(layer "In6.Cu")
		(net "M_K_CPU0_SA_DQ<6>")
	)
	(segment
		(start 416.33013 -203.710032)
		(end 416.560508 -203.710032)
		(width 0.14478)
		(layer "In6.Cu")
		(net "M_K_CPU0_SA_DQ<6>")
	)
	(segment
		(start 392.04265 -228.847904)
		(end 392.723624 -228.16693)
		(width 0.0889)
		(layer "In6.Cu")
		(net "M_K_CPU0_SA_DQ<6>")
	)
	(segment
		(start 412.782766 -204.329538)
		(end 412.945834 -204.16647)
		(width 0.14478)
		(layer "In6.Cu")
		(net "M_K_CPU0_SA_DQ<6>")
	)
	(segment
		(start 406.867868 -210.22818)
		(end 406.867868 -210.023456)
		(width 0.14478)
		(layer "In6.Cu")
		(net "M_K_CPU0_SA_DQ<6>")
	)
	(segment
		(start 420.51859 -204.397102)
		(end 420.51859 -204.332078)
		(width 0.14478)
		(layer "In6.Cu")
		(net "M_K_CPU0_SA_DQ<6>")
	)
	(segment
		(start 428.725838 -204.56017)
		(end 429.08093 -204.56017)
		(width 0.14478)
		(layer "In6.Cu")
		(net "M_K_CPU0_SA_DQ<6>")
	)
	(segment
		(start 408.447494 -208.648554)
		(end 408.447494 -207.646016)
		(width 0.14478)
		(layer "In6.Cu")
		(net "M_K_CPU0_SA_DQ<6>")
	)
	(segment
		(start 392.723624 -228.16693)
		(end 393.184888 -228.16693)
		(width 0.0889)
		(layer "In6.Cu")
		(net "M_K_CPU0_SA_DQ<6>")
	)
	(segment
		(start 420.355522 -204.56017)
		(end 420.51859 -204.397102)
		(width 0.14478)
		(layer "In6.Cu")
		(net "M_K_CPU0_SA_DQ<6>")
	)
	(segment
		(start 415.773616 -203.318872)
		(end 416.003994 -203.318872)
		(width 0.14478)
		(layer "In6.Cu")
		(net "M_K_CPU0_SA_DQ<6>")
	)
	(segment
		(start 407.359104 -208.954116)
		(end 407.359104 -208.749392)
		(width 0.14478)
		(layer "In6.Cu")
		(net "M_K_CPU0_SA_DQ<6>")
	)
	(segment
		(start 413.176212 -204.16647)
		(end 413.33928 -204.329538)
		(width 0.14478)
		(layer "In6.Cu")
		(net "M_K_CPU0_SA_DQ<6>")
	)
	(segment
		(start 439.840116 -203.546964)
		(end 439.840116 -203.49464)
		(width 0.14478)
		(layer "In6.Cu")
		(net "M_K_CPU0_SA_DQ<6>")
	)
	(segment
		(start 408.447494 -207.646016)
		(end 411.53334 -204.56017)
		(width 0.14478)
		(layer "In6.Cu")
		(net "M_K_CPU0_SA_DQ<6>")
	)
	(segment
		(start 441.672726 -203.710032)
		(end 442.119258 -203.710032)
		(width 0.14478)
		(layer "In6.Cu")
		(net "M_K_CPU0_SA_DQ<6>")
	)
	(segment
		(start 438.342024 -204.10043)
		(end 438.505092 -203.937362)
		(width 0.14478)
		(layer "In6.Cu")
		(net "M_K_CPU0_SA_DQ<6>")
	)
	(segment
		(start 428.006256 -204.334618)
		(end 428.169324 -204.17155)
		(width 0.14478)
		(layer "In6.Cu")
		(net "M_K_CPU0_SA_DQ<6>")
	)
	(segment
		(start 421.075104 -204.332078)
		(end 421.075104 -204.397102)
		(width 0.14478)
		(layer "In6.Cu")
		(net "M_K_CPU0_SA_DQ<6>")
	)
	(segment
		(start 421.075104 -204.397102)
		(end 421.238172 -204.56017)
		(width 0.14478)
		(layer "In6.Cu")
		(net "M_K_CPU0_SA_DQ<6>")
	)
	(segment
		(start 416.723576 -203.48448)
		(end 416.886644 -203.321412)
		(width 0.14478)
		(layer "In6.Cu")
		(net "M_K_CPU0_SA_DQ<6>")
	)
	(segment
		(start 417.117022 -203.321412)
		(end 417.28009 -203.48448)
		(width 0.14478)
		(layer "In6.Cu")
		(net "M_K_CPU0_SA_DQ<6>")
	)
	(segment
		(start 431.04181 -203.486258)
		(end 431.04181 -203.546964)
		(width 0.14478)
		(layer "In6.Cu")
		(net "M_K_CPU0_SA_DQ<6>")
	)
	(segment
		(start 437.78551 -203.710032)
		(end 437.948578 -203.8731)
		(width 0.14478)
		(layer "In6.Cu")
		(net "M_K_CPU0_SA_DQ<6>")
	)
	(segment
		(start 414.85693 -203.710032)
		(end 415.44748 -203.710032)
		(width 0.14478)
		(layer "In6.Cu")
		(net "M_K_CPU0_SA_DQ<6>")
	)
	(segment
		(start 421.238172 -204.56017)
		(end 421.549322 -204.56017)
		(width 0.14478)
		(layer "In6.Cu")
		(net "M_K_CPU0_SA_DQ<6>")
	)
	(segment
		(start 415.44748 -203.710032)
		(end 415.610548 -203.546964)
		(width 0.14478)
		(layer "In6.Cu")
		(net "M_K_CPU0_SA_DQ<6>")
	)
	(segment
		(start 399.210276 -220.28785)
		(end 399.210276 -217.885772)
		(width 0.14478)
		(layer "In6.Cu")
		(net "M_K_CPU0_SA_DQ<6>")
	)
	(segment
		(start 420.912036 -204.16901)
		(end 421.075104 -204.332078)
		(width 0.14478)
		(layer "In6.Cu")
		(net "M_K_CPU0_SA_DQ<6>")
	)
	(segment
		(start 414.006792 -204.56017)
		(end 414.85693 -203.710032)
		(width 0.14478)
		(layer "In6.Cu")
		(net "M_K_CPU0_SA_DQ<6>")
	)
	(segment
		(start 428.169324 -204.17155)
		(end 428.399702 -204.17155)
		(width 0.14478)
		(layer "In6.Cu")
		(net "M_K_CPU0_SA_DQ<6>")
	)
	(segment
		(start 435.946804 -204.172312)
		(end 436.109872 -204.33538)
		(width 0.14478)
		(layer "In6.Cu")
		(net "M_K_CPU0_SA_DQ<6>")
	)
	(segment
		(start 440.39663 -203.49464)
		(end 440.39663 -203.938886)
		(width 0.14478)
		(layer "In6.Cu")
		(net "M_K_CPU0_SA_DQ<6>")
	)
	(segment
		(start 416.167062 -203.546964)
		(end 416.33013 -203.710032)
		(width 0.14478)
		(layer "In6.Cu")
		(net "M_K_CPU0_SA_DQ<6>")
	)
	(segment
		(start 422.39946 -203.710032)
		(end 422.80459 -203.710032)
		(width 0.14478)
		(layer "In6.Cu")
		(net "M_K_CPU0_SA_DQ<6>")
	)
	(segment
		(start 435.716426 -204.172312)
		(end 435.946804 -204.172312)
		(width 0.14478)
		(layer "In6.Cu")
		(net "M_K_CPU0_SA_DQ<6>")
	)
	(segment
		(start 441.34659 -203.341732)
		(end 441.509658 -203.5048)
		(width 0.14478)
		(layer "In6.Cu")
		(net "M_K_CPU0_SA_DQ<6>")
	)
	(segment
		(start 406.578816 -209.734404)
		(end 406.578816 -209.52968)
		(width 0.14478)
		(layer "In6.Cu")
		(net "M_K_CPU0_SA_DQ<6>")
	)
	(segment
		(start 413.33928 -204.329538)
		(end 413.33928 -204.397102)
		(width 0.14478)
		(layer "In6.Cu")
		(net "M_K_CPU0_SA_DQ<6>")
	)
	(segment
		(start 438.505092 -203.8731)
		(end 438.66816 -203.710032)
		(width 0.14478)
		(layer "In6.Cu")
		(net "M_K_CPU0_SA_DQ<6>")
	)
	(segment
		(start 407.544524 -208.563972)
		(end 407.749248 -208.563972)
		(width 0.14478)
		(layer "In6.Cu")
		(net "M_K_CPU0_SA_DQ<6>")
	)
	(segment
		(start 430.485296 -203.486258)
		(end 430.648364 -203.32319)
		(width 0.14478)
		(layer "In6.Cu")
		(net "M_K_CPU0_SA_DQ<6>")
	)
	(segment
		(start 406.764236 -209.34426)
		(end 406.96896 -209.34426)
		(width 0.14478)
		(layer "In6.Cu")
		(net "M_K_CPU0_SA_DQ<6>")
	)
	(segment
		(start 426.242226 -204.56017)
		(end 427.843188 -204.56017)
		(width 0.14478)
		(layer "In6.Cu")
		(net "M_K_CPU0_SA_DQ<6>")
	)
	(segment
		(start 436.27294 -204.56017)
		(end 436.6133 -204.56017)
		(width 0.14478)
		(layer "In6.Cu")
		(net "M_K_CPU0_SA_DQ<6>")
	)
	(segment
		(start 440.003184 -203.331572)
		(end 440.233562 -203.331572)
		(width 0.14478)
		(layer "In6.Cu")
		(net "M_K_CPU0_SA_DQ<6>")
	)
	(segment
		(start 435.553358 -204.397102)
		(end 435.553358 -204.33538)
		(width 0.14478)
		(layer "In6.Cu")
		(net "M_K_CPU0_SA_DQ<6>")
	)
	(segment
		(start 428.399702 -204.17155)
		(end 428.56277 -204.334618)
		(width 0.14478)
		(layer "In6.Cu")
		(net "M_K_CPU0_SA_DQ<6>")
	)
	(segment
		(start 423.524172 -203.48448)
		(end 423.524172 -203.546964)
		(width 0.14478)
		(layer "In6.Cu")
		(net "M_K_CPU0_SA_DQ<6>")
	)
	(segment
		(start 412.945834 -204.16647)
		(end 413.176212 -204.16647)
		(width 0.14478)
		(layer "In6.Cu")
		(net "M_K_CPU0_SA_DQ<6>")
	)
	(segment
		(start 393.701016 -226.965256)
		(end 394.0302 -226.17049)
		(width 0.0889)
		(layer "In6.Cu")
		(net "M_K_CPU0_SA_DQ<6>")
	)
	(segment
		(start 431.04181 -203.546964)
		(end 431.204878 -203.710032)
		(width 0.14478)
		(layer "In6.Cu")
		(net "M_K_CPU0_SA_DQ<6>")
	)
	(segment
		(start 441.509658 -203.546964)
		(end 441.672726 -203.710032)
		(width 0.14478)
		(layer "In6.Cu")
		(net "M_K_CPU0_SA_DQ<6>")
	)
	(arc
		(start 390.51484 -228.803454)
		(mid 390.770048 -228.846931)
		(end 391.01776 -228.771704)
		(width 0.0889)
		(layer "In6.Cu")
		(net "M_K_CPU0_SA_DQ<6>")
	)
	(arc
		(start 391.026142 -228.766878)
		(mid 391.20965 -228.721384)
		(end 391.391902 -228.771704)
		(width 0.0889)
		(layer "In6.Cu")
		(net "M_K_CPU0_SA_DQ<6>")
	)
	(arc
		(start 391.391902 -228.771704)
		(mid 391.528338 -228.828529)
		(end 391.674858 -228.847904)
		(width 0.0889)
		(layer "In6.Cu")
		(net "M_K_CPU0_SA_DQ<6>")
	)
	(segment
		(start 388.857998 -229.360222)
		(end 389.32485 -229.094284)
		(width 0.10668)
		(layer "F.Cu")
		(net "M_K_CPU0_SA_DQ<5>")
	)
	(segment
		(start 418.698172 -205.410054)
		(end 421.549322 -205.410054)
		(width 0.14478)
		(layer "In6.Cu")
		(net "M_K_CPU0_SA_DQ<5>")
	)
	(segment
		(start 444.791338 -204.723238)
		(end 444.954406 -204.56017)
		(width 0.14478)
		(layer "In6.Cu")
		(net "M_K_CPU0_SA_DQ<5>")
	)
	(segment
		(start 433.786026 -205.410054)
		(end 436.741316 -205.410054)
		(width 0.14478)
		(layer "In6.Cu")
		(net "M_K_CPU0_SA_DQ<5>")
	)
	(segment
		(start 444.954406 -204.56017)
		(end 446.219326 -204.56017)
		(width 0.14478)
		(layer "In6.Cu")
		(net "M_K_CPU0_SA_DQ<5>")
	)
	(segment
		(start 399.745454 -218.024456)
		(end 410.828998 -206.940912)
		(width 0.14478)
		(layer "In6.Cu")
		(net "M_K_CPU0_SA_DQ<5>")
	)
	(segment
		(start 414.046416 -205.410054)
		(end 414.896554 -204.559916)
		(width 0.14478)
		(layer "In6.Cu")
		(net "M_K_CPU0_SA_DQ<5>")
	)
	(segment
		(start 399.745454 -220.509592)
		(end 399.745454 -218.024456)
		(width 0.14478)
		(layer "In6.Cu")
		(net "M_K_CPU0_SA_DQ<5>")
	)
	(segment
		(start 429.930814 -204.56017)
		(end 432.936142 -204.56017)
		(width 0.14478)
		(layer "In6.Cu")
		(net "M_K_CPU0_SA_DQ<5>")
	)
	(segment
		(start 393.121388 -228.51999)
		(end 393.957556 -227.683822)
		(width 0.0889)
		(layer "In6.Cu")
		(net "M_K_CPU0_SA_DQ<5>")
	)
	(segment
		(start 394.172694 -226.442016)
		(end 395.303756 -225.310954)
		(width 0.0889)
		(layer "In6.Cu")
		(net "M_K_CPU0_SA_DQ<5>")
	)
	(segment
		(start 437.5912 -204.56017)
		(end 444.071756 -204.56017)
		(width 0.14478)
		(layer "In6.Cu")
		(net "M_K_CPU0_SA_DQ<5>")
	)
	(segment
		(start 444.234824 -205.169262)
		(end 444.397892 -205.33233)
		(width 0.14478)
		(layer "In6.Cu")
		(net "M_K_CPU0_SA_DQ<5>")
	)
	(segment
		(start 444.071756 -204.56017)
		(end 444.234824 -204.723238)
		(width 0.14478)
		(layer "In6.Cu")
		(net "M_K_CPU0_SA_DQ<5>")
	)
	(segment
		(start 444.791338 -205.169262)
		(end 444.791338 -204.723238)
		(width 0.14478)
		(layer "In6.Cu")
		(net "M_K_CPU0_SA_DQ<5>")
	)
	(segment
		(start 432.936142 -204.56017)
		(end 433.786026 -205.410054)
		(width 0.14478)
		(layer "In6.Cu")
		(net "M_K_CPU0_SA_DQ<5>")
	)
	(segment
		(start 426.242226 -205.410054)
		(end 429.08093 -205.410054)
		(width 0.14478)
		(layer "In6.Cu")
		(net "M_K_CPU0_SA_DQ<5>")
	)
	(segment
		(start 444.397892 -205.33233)
		(end 444.62827 -205.33233)
		(width 0.14478)
		(layer "In6.Cu")
		(net "M_K_CPU0_SA_DQ<5>")
	)
	(segment
		(start 389.32485 -229.094284)
		(end 389.170926 -229.359714)
		(width 0.0889)
		(layer "In6.Cu")
		(net "M_K_CPU0_SA_DQ<5>")
	)
	(segment
		(start 410.828998 -206.001112)
		(end 411.420056 -205.410054)
		(width 0.14478)
		(layer "In6.Cu")
		(net "M_K_CPU0_SA_DQ<5>")
	)
	(segment
		(start 422.399206 -204.56017)
		(end 425.392342 -204.56017)
		(width 0.14478)
		(layer "In6.Cu")
		(net "M_K_CPU0_SA_DQ<5>")
	)
	(segment
		(start 392.767566 -228.51999)
		(end 393.121388 -228.51999)
		(width 0.0889)
		(layer "In6.Cu")
		(net "M_K_CPU0_SA_DQ<5>")
	)
	(segment
		(start 391.01776 -229.41661)
		(end 391.026142 -229.421436)
		(width 0.0889)
		(layer "In6.Cu")
		(net "M_K_CPU0_SA_DQ<5>")
	)
	(segment
		(start 391.947146 -229.34041)
		(end 392.767566 -228.51999)
		(width 0.0889)
		(layer "In6.Cu")
		(net "M_K_CPU0_SA_DQ<5>")
	)
	(segment
		(start 446.219326 -204.56017)
		(end 446.644268 -204.985112)
		(width 0.14478)
		(layer "In6.Cu")
		(net "M_K_CPU0_SA_DQ<5>")
	)
	(segment
		(start 390.443466 -229.421436)
		(end 390.451848 -229.41661)
		(width 0.0889)
		(layer "In6.Cu")
		(net "M_K_CPU0_SA_DQ<5>")
	)
	(segment
		(start 389.170926 -229.359714)
		(end 389.193024 -229.442772)
		(width 0.0889)
		(layer "In6.Cu")
		(net "M_K_CPU0_SA_DQ<5>")
	)
	(segment
		(start 421.549322 -205.410054)
		(end 422.399206 -204.56017)
		(width 0.14478)
		(layer "In6.Cu")
		(net "M_K_CPU0_SA_DQ<5>")
	)
	(segment
		(start 395.303756 -225.310954)
		(end 395.303756 -224.95129)
		(width 0.0889)
		(layer "In6.Cu")
		(net "M_K_CPU0_SA_DQ<5>")
	)
	(segment
		(start 425.392342 -204.56017)
		(end 426.242226 -205.410054)
		(width 0.14478)
		(layer "In6.Cu")
		(net "M_K_CPU0_SA_DQ<5>")
	)
	(segment
		(start 410.828998 -206.940912)
		(end 410.828998 -206.001112)
		(width 0.14478)
		(layer "In6.Cu")
		(net "M_K_CPU0_SA_DQ<5>")
	)
	(segment
		(start 393.957556 -226.9617)
		(end 394.172694 -226.442016)
		(width 0.0889)
		(layer "In6.Cu")
		(net "M_K_CPU0_SA_DQ<5>")
	)
	(segment
		(start 444.234824 -204.723238)
		(end 444.234824 -205.169262)
		(width 0.14478)
		(layer "In6.Cu")
		(net "M_K_CPU0_SA_DQ<5>")
	)
	(segment
		(start 395.303756 -224.95129)
		(end 395.809216 -224.44583)
		(width 0.0889)
		(layer "In6.Cu")
		(net "M_K_CPU0_SA_DQ<5>")
	)
	(segment
		(start 436.741316 -205.410054)
		(end 437.5912 -204.56017)
		(width 0.14478)
		(layer "In6.Cu")
		(net "M_K_CPU0_SA_DQ<5>")
	)
	(segment
		(start 411.420056 -205.410054)
		(end 414.046416 -205.410054)
		(width 0.14478)
		(layer "In6.Cu")
		(net "M_K_CPU0_SA_DQ<5>")
	)
	(segment
		(start 391.674604 -229.34041)
		(end 391.947146 -229.34041)
		(width 0.0889)
		(layer "In6.Cu")
		(net "M_K_CPU0_SA_DQ<5>")
	)
	(segment
		(start 393.957556 -227.683822)
		(end 393.957556 -226.9617)
		(width 0.0889)
		(layer "In6.Cu")
		(net "M_K_CPU0_SA_DQ<5>")
	)
	(segment
		(start 417.848034 -204.559916)
		(end 418.698172 -205.410054)
		(width 0.14478)
		(layer "In6.Cu")
		(net "M_K_CPU0_SA_DQ<5>")
	)
	(segment
		(start 429.08093 -205.410054)
		(end 429.930814 -204.56017)
		(width 0.14478)
		(layer "In6.Cu")
		(net "M_K_CPU0_SA_DQ<5>")
	)
	(segment
		(start 444.62827 -205.33233)
		(end 444.791338 -205.169262)
		(width 0.14478)
		(layer "In6.Cu")
		(net "M_K_CPU0_SA_DQ<5>")
	)
	(segment
		(start 414.896554 -204.559916)
		(end 417.848034 -204.559916)
		(width 0.14478)
		(layer "In6.Cu")
		(net "M_K_CPU0_SA_DQ<5>")
	)
	(segment
		(start 395.809216 -224.44583)
		(end 399.745454 -220.509592)
		(width 0.14478)
		(layer "In6.Cu")
		(net "M_K_CPU0_SA_DQ<5>")
	)
	(arc
		(start 390.077706 -229.41661)
		(mid 390.259957 -229.466994)
		(end 390.443466 -229.421436)
		(width 0.0889)
		(layer "In6.Cu")
		(net "M_K_CPU0_SA_DQ<5>")
	)
	(arc
		(start 389.193024 -229.442772)
		(mid 389.355355 -229.465621)
		(end 389.511794 -229.41661)
		(width 0.0889)
		(layer "In6.Cu")
		(net "M_K_CPU0_SA_DQ<5>")
	)
	(arc
		(start 389.511794 -229.41661)
		(mid 389.79475 -229.340433)
		(end 390.077706 -229.41661)
		(width 0.0889)
		(layer "In6.Cu")
		(net "M_K_CPU0_SA_DQ<5>")
	)
	(arc
		(start 391.026142 -229.421436)
		(mid 391.20965 -229.466961)
		(end 391.391902 -229.41661)
		(width 0.0889)
		(layer "In6.Cu")
		(net "M_K_CPU0_SA_DQ<5>")
	)
	(arc
		(start 391.391902 -229.41661)
		(mid 391.52822 -229.359843)
		(end 391.674604 -229.34041)
		(width 0.0889)
		(layer "In6.Cu")
		(net "M_K_CPU0_SA_DQ<5>")
	)
	(arc
		(start 390.451848 -229.41661)
		(mid 390.734804 -229.340433)
		(end 391.01776 -229.41661)
		(width 0.0889)
		(layer "In6.Cu")
		(net "M_K_CPU0_SA_DQ<5>")
	)
	(segment
		(start 390.267952 -228.550216)
		(end 390.734804 -228.284278)
		(width 0.10668)
		(layer "F.Cu")
		(net "M_K_CPU0_SA_DQ<4>")
	)
	(segment
		(start 418.70757 -203.71943)
		(end 421.539924 -203.71943)
		(width 0.14478)
		(layer "In6.Cu")
		(net "M_K_CPU0_SA_DQ<4>")
	)
	(segment
		(start 393.871196 -226.016312)
		(end 393.871196 -224.981262)
		(width 0.0889)
		(layer "In6.Cu")
		(net "M_K_CPU0_SA_DQ<4>")
	)
	(segment
		(start 398.755616 -217.683588)
		(end 405.848058 -210.591146)
		(width 0.14478)
		(layer "In6.Cu")
		(net "M_K_CPU0_SA_DQ<4>")
	)
	(segment
		(start 393.098528 -227.96373)
		(end 393.462256 -227.600002)
		(width 0.0889)
		(layer "In6.Cu")
		(net "M_K_CPU0_SA_DQ<4>")
	)
	(segment
		(start 425.40174 -202.869546)
		(end 426.251624 -203.71943)
		(width 0.14478)
		(layer "In6.Cu")
		(net "M_K_CPU0_SA_DQ<4>")
	)
	(segment
		(start 444.369698 -202.869546)
		(end 444.379096 -202.860148)
		(width 0.14478)
		(layer "In6.Cu")
		(net "M_K_CPU0_SA_DQ<4>")
	)
	(segment
		(start 445.807338 -202.860148)
		(end 446.219326 -202.860148)
		(width 0.14478)
		(layer "In6.Cu")
		(net "M_K_CPU0_SA_DQ<4>")
	)
	(segment
		(start 395.820646 -223.034352)
		(end 398.755616 -220.099382)
		(width 0.14478)
		(layer "In6.Cu")
		(net "M_K_CPU0_SA_DQ<4>")
	)
	(segment
		(start 393.871196 -224.981262)
		(end 395.818106 -223.034352)
		(width 0.0889)
		(layer "In6.Cu")
		(net "M_K_CPU0_SA_DQ<4>")
	)
	(segment
		(start 414.887156 -202.869292)
		(end 417.857432 -202.869292)
		(width 0.14478)
		(layer "In6.Cu")
		(net "M_K_CPU0_SA_DQ<4>")
	)
	(segment
		(start 393.462256 -227.600002)
		(end 393.462256 -227.003356)
		(width 0.0889)
		(layer "In6.Cu")
		(net "M_K_CPU0_SA_DQ<4>")
	)
	(segment
		(start 445.255904 -203.923392)
		(end 445.517778 -203.923392)
		(width 0.14478)
		(layer "In6.Cu")
		(net "M_K_CPU0_SA_DQ<4>")
	)
	(segment
		(start 445.111124 -203.004928)
		(end 445.111124 -203.778612)
		(width 0.14478)
		(layer "In6.Cu")
		(net "M_K_CPU0_SA_DQ<4>")
	)
	(segment
		(start 405.848058 -209.587592)
		(end 411.725618 -203.710032)
		(width 0.14478)
		(layer "In6.Cu")
		(net "M_K_CPU0_SA_DQ<4>")
	)
	(segment
		(start 422.389808 -202.869546)
		(end 425.40174 -202.869546)
		(width 0.14478)
		(layer "In6.Cu")
		(net "M_K_CPU0_SA_DQ<4>")
	)
	(segment
		(start 390.58088 -228.549708)
		(end 390.603232 -228.63302)
		(width 0.0889)
		(layer "In6.Cu")
		(net "M_K_CPU0_SA_DQ<4>")
	)
	(segment
		(start 411.725618 -203.710032)
		(end 414.046416 -203.710032)
		(width 0.14478)
		(layer "In6.Cu")
		(net "M_K_CPU0_SA_DQ<4>")
	)
	(segment
		(start 392.639296 -227.96373)
		(end 393.098528 -227.96373)
		(width 0.0889)
		(layer "In6.Cu")
		(net "M_K_CPU0_SA_DQ<4>")
	)
	(segment
		(start 398.755616 -220.099382)
		(end 398.755616 -217.683588)
		(width 0.14478)
		(layer "In6.Cu")
		(net "M_K_CPU0_SA_DQ<4>")
	)
	(segment
		(start 445.111124 -203.778612)
		(end 445.255904 -203.923392)
		(width 0.14478)
		(layer "In6.Cu")
		(net "M_K_CPU0_SA_DQ<4>")
	)
	(segment
		(start 405.848058 -210.591146)
		(end 405.848058 -209.587592)
		(width 0.14478)
		(layer "In6.Cu")
		(net "M_K_CPU0_SA_DQ<4>")
	)
	(segment
		(start 429.921416 -202.869546)
		(end 432.94554 -202.869546)
		(width 0.14478)
		(layer "In6.Cu")
		(net "M_K_CPU0_SA_DQ<4>")
	)
	(segment
		(start 421.539924 -203.71943)
		(end 422.389808 -202.869546)
		(width 0.14478)
		(layer "In6.Cu")
		(net "M_K_CPU0_SA_DQ<4>")
	)
	(segment
		(start 446.219326 -202.860148)
		(end 446.644268 -203.28509)
		(width 0.14478)
		(layer "In6.Cu")
		(net "M_K_CPU0_SA_DQ<4>")
	)
	(segment
		(start 390.734804 -228.284278)
		(end 390.58088 -228.549708)
		(width 0.0889)
		(layer "In6.Cu")
		(net "M_K_CPU0_SA_DQ<4>")
	)
	(segment
		(start 429.071532 -203.71943)
		(end 429.921416 -202.869546)
		(width 0.14478)
		(layer "In6.Cu")
		(net "M_K_CPU0_SA_DQ<4>")
	)
	(segment
		(start 445.662558 -203.778612)
		(end 445.662558 -203.004928)
		(width 0.14478)
		(layer "In6.Cu")
		(net "M_K_CPU0_SA_DQ<4>")
	)
	(segment
		(start 445.662558 -203.004928)
		(end 445.807338 -202.860148)
		(width 0.14478)
		(layer "In6.Cu")
		(net "M_K_CPU0_SA_DQ<4>")
	)
	(segment
		(start 432.94554 -202.869546)
		(end 433.795424 -203.71943)
		(width 0.14478)
		(layer "In6.Cu")
		(net "M_K_CPU0_SA_DQ<4>")
	)
	(segment
		(start 395.818106 -223.034352)
		(end 395.820646 -223.034352)
		(width 0.0889)
		(layer "In6.Cu")
		(net "M_K_CPU0_SA_DQ<4>")
	)
	(segment
		(start 426.251624 -203.71943)
		(end 429.071532 -203.71943)
		(width 0.14478)
		(layer "In6.Cu")
		(net "M_K_CPU0_SA_DQ<4>")
	)
	(segment
		(start 445.517778 -203.923392)
		(end 445.662558 -203.778612)
		(width 0.14478)
		(layer "In6.Cu")
		(net "M_K_CPU0_SA_DQ<4>")
	)
	(segment
		(start 391.945622 -228.657404)
		(end 392.639296 -227.96373)
		(width 0.0889)
		(layer "In6.Cu")
		(net "M_K_CPU0_SA_DQ<4>")
	)
	(segment
		(start 437.581802 -202.869546)
		(end 444.369698 -202.869546)
		(width 0.14478)
		(layer "In6.Cu")
		(net "M_K_CPU0_SA_DQ<4>")
	)
	(segment
		(start 391.674858 -228.657404)
		(end 391.945622 -228.657404)
		(width 0.0889)
		(layer "In6.Cu")
		(net "M_K_CPU0_SA_DQ<4>")
	)
	(segment
		(start 433.795424 -203.71943)
		(end 436.731918 -203.71943)
		(width 0.14478)
		(layer "In6.Cu")
		(net "M_K_CPU0_SA_DQ<4>")
	)
	(segment
		(start 444.966344 -202.860148)
		(end 445.111124 -203.004928)
		(width 0.14478)
		(layer "In6.Cu")
		(net "M_K_CPU0_SA_DQ<4>")
	)
	(segment
		(start 444.379096 -202.860148)
		(end 444.966344 -202.860148)
		(width 0.14478)
		(layer "In6.Cu")
		(net "M_K_CPU0_SA_DQ<4>")
	)
	(segment
		(start 393.462256 -227.003356)
		(end 393.871196 -226.016312)
		(width 0.0889)
		(layer "In6.Cu")
		(net "M_K_CPU0_SA_DQ<4>")
	)
	(segment
		(start 414.046416 -203.710032)
		(end 414.887156 -202.869292)
		(width 0.14478)
		(layer "In6.Cu")
		(net "M_K_CPU0_SA_DQ<4>")
	)
	(segment
		(start 417.857432 -202.869292)
		(end 418.70757 -203.71943)
		(width 0.14478)
		(layer "In6.Cu")
		(net "M_K_CPU0_SA_DQ<4>")
	)
	(segment
		(start 436.731918 -203.71943)
		(end 437.581802 -202.869546)
		(width 0.14478)
		(layer "In6.Cu")
		(net "M_K_CPU0_SA_DQ<4>")
	)
	(arc
		(start 390.603232 -228.63302)
		(mid 390.765421 -228.655755)
		(end 390.921748 -228.606858)
		(width 0.0889)
		(layer "In6.Cu")
		(net "M_K_CPU0_SA_DQ<4>")
	)
	(arc
		(start 390.921748 -228.606858)
		(mid 391.204704 -228.530681)
		(end 391.48766 -228.606858)
		(width 0.0889)
		(layer "In6.Cu")
		(net "M_K_CPU0_SA_DQ<4>")
	)
	(arc
		(start 391.48766 -228.606858)
		(mid 391.577916 -228.644511)
		(end 391.674858 -228.657404)
		(width 0.0889)
		(layer "In6.Cu")
		(net "M_K_CPU0_SA_DQ<4>")
	)
	(segment
		(start 388.387844 -226.930204)
		(end 388.85495 -226.664266)
		(width 0.10668)
		(layer "F.Cu")
		(net "M_K_CPU0_SA_DQ<3>")
	)
	(segment
		(start 433.776628 -200.300844)
		(end 435.435502 -200.300844)
		(width 0.14478)
		(layer "In6.Cu")
		(net "M_K_CPU0_SA_DQ<3>")
	)
	(segment
		(start 412.056326 -200.165462)
		(end 412.056326 -200.143872)
		(width 0.14478)
		(layer "In6.Cu")
		(net "M_K_CPU0_SA_DQ<3>")
	)
	(segment
		(start 437.472836 -199.450706)
		(end 439.70575 -199.450706)
		(width 0.14478)
		(layer "In6.Cu")
		(net "M_K_CPU0_SA_DQ<3>")
	)
	(segment
		(start 420.43096 -200.300844)
		(end 420.57574 -200.156064)
		(width 0.14478)
		(layer "In6.Cu")
		(net "M_K_CPU0_SA_DQ<3>")
	)
	(segment
		(start 441.70854 -199.623172)
		(end 441.871608 -199.460104)
		(width 0.14478)
		(layer "In6.Cu")
		(net "M_K_CPU0_SA_DQ<3>")
	)
	(segment
		(start 411.651196 -200.310242)
		(end 411.911546 -200.310242)
		(width 0.14478)
		(layer "In6.Cu")
		(net "M_K_CPU0_SA_DQ<3>")
	)
	(segment
		(start 413.303974 -200.310242)
		(end 414.006792 -200.310242)
		(width 0.14478)
		(layer "In6.Cu")
		(net "M_K_CPU0_SA_DQ<3>")
	)
	(segment
		(start 435.589172 -200.087738)
		(end 435.75224 -199.92467)
		(width 0.14478)
		(layer "In6.Cu")
		(net "M_K_CPU0_SA_DQ<3>")
	)
	(segment
		(start 421.271954 -200.300844)
		(end 421.55872 -200.300844)
		(width 0.14478)
		(layer "In6.Cu")
		(net "M_K_CPU0_SA_DQ<3>")
	)
	(segment
		(start 391.99693 -224.579688)
		(end 391.957814 -224.556828)
		(width 0.0889)
		(layer "In6.Cu")
		(net "M_K_CPU0_SA_DQ<3>")
	)
	(segment
		(start 441.315094 -199.983852)
		(end 441.545472 -199.983852)
		(width 0.14478)
		(layer "In6.Cu")
		(net "M_K_CPU0_SA_DQ<3>")
	)
	(segment
		(start 389.607806 -226.341686)
		(end 389.616188 -226.33686)
		(width 0.0889)
		(layer "In6.Cu")
		(net "M_K_CPU0_SA_DQ<3>")
	)
	(segment
		(start 435.982618 -199.92467)
		(end 436.145686 -200.087738)
		(width 0.14478)
		(layer "In6.Cu")
		(net "M_K_CPU0_SA_DQ<3>")
	)
	(segment
		(start 412.201106 -199.999092)
		(end 412.46298 -199.999092)
		(width 0.14478)
		(layer "In6.Cu")
		(net "M_K_CPU0_SA_DQ<3>")
	)
	(segment
		(start 414.866328 -199.450706)
		(end 418.026596 -199.450706)
		(width 0.14478)
		(layer "In6.Cu")
		(net "M_K_CPU0_SA_DQ<3>")
	)
	(segment
		(start 420.57574 -200.062592)
		(end 420.72052 -199.917812)
		(width 0.14478)
		(layer "In6.Cu")
		(net "M_K_CPU0_SA_DQ<3>")
	)
	(segment
		(start 430.49698 -199.229218)
		(end 430.660048 -199.06615)
		(width 0.14478)
		(layer "In6.Cu")
		(net "M_K_CPU0_SA_DQ<3>")
	)
	(segment
		(start 439.70575 -199.450706)
		(end 439.85942 -199.297036)
		(width 0.14478)
		(layer "In6.Cu")
		(net "M_K_CPU0_SA_DQ<3>")
	)
	(segment
		(start 420.72052 -199.917812)
		(end 420.982394 -199.917812)
		(width 0.14478)
		(layer "In6.Cu")
		(net "M_K_CPU0_SA_DQ<3>")
	)
	(segment
		(start 423.283634 -199.07377)
		(end 423.446702 -199.236838)
		(width 0.14478)
		(layer "In6.Cu")
		(net "M_K_CPU0_SA_DQ<3>")
	)
	(segment
		(start 440.579002 -199.460104)
		(end 440.988958 -199.460104)
		(width 0.14478)
		(layer "In6.Cu")
		(net "M_K_CPU0_SA_DQ<3>")
	)
	(segment
		(start 441.545472 -199.983852)
		(end 441.70854 -199.820784)
		(width 0.14478)
		(layer "In6.Cu")
		(net "M_K_CPU0_SA_DQ<3>")
	)
	(segment
		(start 423.053256 -199.07377)
		(end 423.283634 -199.07377)
		(width 0.14478)
		(layer "In6.Cu")
		(net "M_K_CPU0_SA_DQ<3>")
	)
	(segment
		(start 413.159194 -200.476612)
		(end 413.159194 -200.455022)
		(width 0.14478)
		(layer "In6.Cu")
		(net "M_K_CPU0_SA_DQ<3>")
	)
	(segment
		(start 421.127174 -200.062592)
		(end 421.127174 -200.156064)
		(width 0.14478)
		(layer "In6.Cu")
		(net "M_K_CPU0_SA_DQ<3>")
	)
	(segment
		(start 440.252866 -199.06615)
		(end 440.415934 -199.229218)
		(width 0.14478)
		(layer "In6.Cu")
		(net "M_K_CPU0_SA_DQ<3>")
	)
	(segment
		(start 391.48766 -226.341686)
		(end 391.526776 -226.318826)
		(width 0.0889)
		(layer "In6.Cu")
		(net "M_K_CPU0_SA_DQ<3>")
	)
	(segment
		(start 428.610268 -200.090278)
		(end 428.610268 -200.147174)
		(width 0.14478)
		(layer "In6.Cu")
		(net "M_K_CPU0_SA_DQ<3>")
	)
	(segment
		(start 393.663424 -221.239842)
		(end 396.329916 -218.57335)
		(width 0.14478)
		(layer "In6.Cu")
		(net "M_K_CPU0_SA_DQ<3>")
	)
	(segment
		(start 428.053754 -200.147174)
		(end 428.053754 -200.090278)
		(width 0.14478)
		(layer "In6.Cu")
		(net "M_K_CPU0_SA_DQ<3>")
	)
	(segment
		(start 391.957814 -225.53168)
		(end 391.99693 -225.50882)
		(width 0.0889)
		(layer "In6.Cu")
		(net "M_K_CPU0_SA_DQ<3>")
	)
	(segment
		(start 391.926064 -225.549968)
		(end 391.957814 -225.53168)
		(width 0.0889)
		(layer "In6.Cu")
		(net "M_K_CPU0_SA_DQ<3>")
	)
	(segment
		(start 423.446702 -199.297036)
		(end 423.600372 -199.450706)
		(width 0.14478)
		(layer "In6.Cu")
		(net "M_K_CPU0_SA_DQ<3>")
	)
	(segment
		(start 412.46298 -199.999092)
		(end 412.60776 -200.143872)
		(width 0.14478)
		(layer "In6.Cu")
		(net "M_K_CPU0_SA_DQ<3>")
	)
	(segment
		(start 389.008874 -226.398836)
		(end 389.104886 -226.373436)
		(width 0.0889)
		(layer "In6.Cu")
		(net "M_K_CPU0_SA_DQ<3>")
	)
	(segment
		(start 431.207164 -199.450706)
		(end 432.92649 -199.450706)
		(width 0.14478)
		(layer "In6.Cu")
		(net "M_K_CPU0_SA_DQ<3>")
	)
	(segment
		(start 431.053494 -199.297036)
		(end 431.207164 -199.450706)
		(width 0.14478)
		(layer "In6.Cu")
		(net "M_K_CPU0_SA_DQ<3>")
	)
	(segment
		(start 435.75224 -199.92467)
		(end 435.982618 -199.92467)
		(width 0.14478)
		(layer "In6.Cu")
		(net "M_K_CPU0_SA_DQ<3>")
	)
	(segment
		(start 430.333912 -199.460104)
		(end 430.49698 -199.297036)
		(width 0.14478)
		(layer "In6.Cu")
		(net "M_K_CPU0_SA_DQ<3>")
	)
	(segment
		(start 440.415934 -199.297036)
		(end 440.579002 -199.460104)
		(width 0.14478)
		(layer "In6.Cu")
		(net "M_K_CPU0_SA_DQ<3>")
	)
	(segment
		(start 392.427714 -223.101662)
		(end 392.46683 -223.078802)
		(width 0.0889)
		(layer "In6.Cu")
		(net "M_K_CPU0_SA_DQ<3>")
	)
	(segment
		(start 396.329916 -218.57335)
		(end 396.329916 -215.631522)
		(width 0.14478)
		(layer "In6.Cu")
		(net "M_K_CPU0_SA_DQ<3>")
	)
	(segment
		(start 391.957814 -224.556828)
		(end 391.926064 -224.53854)
		(width 0.0889)
		(layer "In6.Cu")
		(net "M_K_CPU0_SA_DQ<3>")
	)
	(segment
		(start 418.876734 -200.300844)
		(end 420.43096 -200.300844)
		(width 0.14478)
		(layer "In6.Cu")
		(net "M_K_CPU0_SA_DQ<3>")
	)
	(segment
		(start 429.931068 -199.460104)
		(end 430.333912 -199.460104)
		(width 0.14478)
		(layer "In6.Cu")
		(net "M_K_CPU0_SA_DQ<3>")
	)
	(segment
		(start 422.890188 -199.297036)
		(end 422.890188 -199.236838)
		(width 0.14478)
		(layer "In6.Cu")
		(net "M_K_CPU0_SA_DQ<3>")
	)
	(segment
		(start 428.610268 -200.147174)
		(end 428.773336 -200.310242)
		(width 0.14478)
		(layer "In6.Cu")
		(net "M_K_CPU0_SA_DQ<3>")
	)
	(segment
		(start 428.053754 -200.090278)
		(end 428.216822 -199.92721)
		(width 0.14478)
		(layer "In6.Cu")
		(net "M_K_CPU0_SA_DQ<3>")
	)
	(segment
		(start 436.6133 -200.310242)
		(end 437.472836 -199.450706)
		(width 0.14478)
		(layer "In6.Cu")
		(net "M_K_CPU0_SA_DQ<3>")
	)
	(segment
		(start 422.72712 -199.460104)
		(end 422.890188 -199.297036)
		(width 0.14478)
		(layer "In6.Cu")
		(net "M_K_CPU0_SA_DQ<3>")
	)
	(segment
		(start 441.152026 -199.623172)
		(end 441.152026 -199.820784)
		(width 0.14478)
		(layer "In6.Cu")
		(net "M_K_CPU0_SA_DQ<3>")
	)
	(segment
		(start 427.900084 -200.300844)
		(end 428.053754 -200.147174)
		(width 0.14478)
		(layer "In6.Cu")
		(net "M_K_CPU0_SA_DQ<3>")
	)
	(segment
		(start 430.890426 -199.06615)
		(end 431.053494 -199.229218)
		(width 0.14478)
		(layer "In6.Cu")
		(net "M_K_CPU0_SA_DQ<3>")
	)
	(segment
		(start 440.415934 -199.229218)
		(end 440.415934 -199.297036)
		(width 0.14478)
		(layer "In6.Cu")
		(net "M_K_CPU0_SA_DQ<3>")
	)
	(segment
		(start 393.253976 -221.64929)
		(end 393.663424 -221.239842)
		(width 0.0889)
		(layer "In6.Cu")
		(net "M_K_CPU0_SA_DQ<3>")
	)
	(segment
		(start 425.38269 -199.450706)
		(end 426.232828 -200.300844)
		(width 0.14478)
		(layer "In6.Cu")
		(net "M_K_CPU0_SA_DQ<3>")
	)
	(segment
		(start 432.92649 -199.450706)
		(end 433.776628 -200.300844)
		(width 0.14478)
		(layer "In6.Cu")
		(net "M_K_CPU0_SA_DQ<3>")
	)
	(segment
		(start 413.159194 -200.455022)
		(end 413.303974 -200.310242)
		(width 0.14478)
		(layer "In6.Cu")
		(net "M_K_CPU0_SA_DQ<3>")
	)
	(segment
		(start 391.926064 -223.929956)
		(end 391.957814 -223.911668)
		(width 0.0889)
		(layer "In6.Cu")
		(net "M_K_CPU0_SA_DQ<3>")
	)
	(segment
		(start 431.053494 -199.229218)
		(end 431.053494 -199.297036)
		(width 0.14478)
		(layer "In6.Cu")
		(net "M_K_CPU0_SA_DQ<3>")
	)
	(segment
		(start 388.85495 -226.664266)
		(end 389.008874 -226.398836)
		(width 0.0889)
		(layer "In6.Cu")
		(net "M_K_CPU0_SA_DQ<3>")
	)
	(segment
		(start 435.435502 -200.300844)
		(end 435.589172 -200.147174)
		(width 0.14478)
		(layer "In6.Cu")
		(net "M_K_CPU0_SA_DQ<3>")
	)
	(segment
		(start 423.446702 -199.236838)
		(end 423.446702 -199.297036)
		(width 0.14478)
		(layer "In6.Cu")
		(net "M_K_CPU0_SA_DQ<3>")
	)
	(segment
		(start 430.660048 -199.06615)
		(end 430.890426 -199.06615)
		(width 0.14478)
		(layer "In6.Cu")
		(net "M_K_CPU0_SA_DQ<3>")
	)
	(segment
		(start 420.57574 -200.156064)
		(end 420.57574 -200.062592)
		(width 0.14478)
		(layer "In6.Cu")
		(net "M_K_CPU0_SA_DQ<3>")
	)
	(segment
		(start 441.70854 -199.820784)
		(end 441.70854 -199.623172)
		(width 0.14478)
		(layer "In6.Cu")
		(net "M_K_CPU0_SA_DQ<3>")
	)
	(segment
		(start 441.871608 -199.460104)
		(end 442.119258 -199.460104)
		(width 0.14478)
		(layer "In6.Cu")
		(net "M_K_CPU0_SA_DQ<3>")
	)
	(segment
		(start 429.08093 -200.310242)
		(end 429.931068 -199.460104)
		(width 0.14478)
		(layer "In6.Cu")
		(net "M_K_CPU0_SA_DQ<3>")
	)
	(segment
		(start 440.988958 -199.460104)
		(end 441.152026 -199.623172)
		(width 0.14478)
		(layer "In6.Cu")
		(net "M_K_CPU0_SA_DQ<3>")
	)
	(segment
		(start 430.49698 -199.297036)
		(end 430.49698 -199.229218)
		(width 0.14478)
		(layer "In6.Cu")
		(net "M_K_CPU0_SA_DQ<3>")
	)
	(segment
		(start 421.55872 -200.300844)
		(end 422.39946 -199.460104)
		(width 0.14478)
		(layer "In6.Cu")
		(net "M_K_CPU0_SA_DQ<3>")
	)
	(segment
		(start 411.911546 -200.310242)
		(end 412.056326 -200.165462)
		(width 0.14478)
		(layer "In6.Cu")
		(net "M_K_CPU0_SA_DQ<3>")
	)
	(segment
		(start 435.589172 -200.147174)
		(end 435.589172 -200.087738)
		(width 0.14478)
		(layer "In6.Cu")
		(net "M_K_CPU0_SA_DQ<3>")
	)
	(segment
		(start 439.85942 -199.297036)
		(end 439.85942 -199.229218)
		(width 0.14478)
		(layer "In6.Cu")
		(net "M_K_CPU0_SA_DQ<3>")
	)
	(segment
		(start 393.084812 -222.247714)
		(end 393.253976 -222.07855)
		(width 0.0889)
		(layer "In6.Cu")
		(net "M_K_CPU0_SA_DQ<3>")
	)
	(segment
		(start 412.60776 -200.476612)
		(end 412.75254 -200.621392)
		(width 0.14478)
		(layer "In6.Cu")
		(net "M_K_CPU0_SA_DQ<3>")
	)
	(segment
		(start 439.85942 -199.229218)
		(end 440.022488 -199.06615)
		(width 0.14478)
		(layer "In6.Cu")
		(net "M_K_CPU0_SA_DQ<3>")
	)
	(segment
		(start 442.119258 -199.460104)
		(end 442.5442 -199.885046)
		(width 0.14478)
		(layer "In6.Cu")
		(net "M_K_CPU0_SA_DQ<3>")
	)
	(segment
		(start 396.329916 -215.631522)
		(end 411.651196 -200.310242)
		(width 0.14478)
		(layer "In6.Cu")
		(net "M_K_CPU0_SA_DQ<3>")
	)
	(segment
		(start 413.014414 -200.621392)
		(end 413.159194 -200.476612)
		(width 0.14478)
		(layer "In6.Cu")
		(net "M_K_CPU0_SA_DQ<3>")
	)
	(segment
		(start 392.397234 -223.119442)
		(end 392.427714 -223.101662)
		(width 0.0889)
		(layer "In6.Cu")
		(net "M_K_CPU0_SA_DQ<3>")
	)
	(segment
		(start 422.39946 -199.460104)
		(end 422.72712 -199.460104)
		(width 0.14478)
		(layer "In6.Cu")
		(net "M_K_CPU0_SA_DQ<3>")
	)
	(segment
		(start 414.006792 -200.310242)
		(end 414.866328 -199.450706)
		(width 0.14478)
		(layer "In6.Cu")
		(net "M_K_CPU0_SA_DQ<3>")
	)
	(segment
		(start 428.4472 -199.92721)
		(end 428.610268 -200.090278)
		(width 0.14478)
		(layer "In6.Cu")
		(net "M_K_CPU0_SA_DQ<3>")
	)
	(segment
		(start 412.056326 -200.143872)
		(end 412.201106 -199.999092)
		(width 0.14478)
		(layer "In6.Cu")
		(net "M_K_CPU0_SA_DQ<3>")
	)
	(segment
		(start 441.152026 -199.820784)
		(end 441.315094 -199.983852)
		(width 0.14478)
		(layer "In6.Cu")
		(net "M_K_CPU0_SA_DQ<3>")
	)
	(segment
		(start 393.253976 -222.07855)
		(end 393.253976 -221.64929)
		(width 0.0889)
		(layer "In6.Cu")
		(net "M_K_CPU0_SA_DQ<3>")
	)
	(segment
		(start 436.145686 -200.087738)
		(end 436.145686 -200.147174)
		(width 0.14478)
		(layer "In6.Cu")
		(net "M_K_CPU0_SA_DQ<3>")
	)
	(segment
		(start 436.145686 -200.147174)
		(end 436.308754 -200.310242)
		(width 0.14478)
		(layer "In6.Cu")
		(net "M_K_CPU0_SA_DQ<3>")
	)
	(segment
		(start 391.957814 -223.911668)
		(end 391.99693 -223.888808)
		(width 0.0889)
		(layer "In6.Cu")
		(net "M_K_CPU0_SA_DQ<3>")
	)
	(segment
		(start 428.773336 -200.310242)
		(end 429.08093 -200.310242)
		(width 0.14478)
		(layer "In6.Cu")
		(net "M_K_CPU0_SA_DQ<3>")
	)
	(segment
		(start 412.60776 -200.143872)
		(end 412.60776 -200.476612)
		(width 0.14478)
		(layer "In6.Cu")
		(net "M_K_CPU0_SA_DQ<3>")
	)
	(segment
		(start 412.75254 -200.621392)
		(end 413.014414 -200.621392)
		(width 0.14478)
		(layer "In6.Cu")
		(net "M_K_CPU0_SA_DQ<3>")
	)
	(segment
		(start 392.865102 -222.310706)
		(end 392.897868 -222.291656)
		(width 0.0889)
		(layer "In6.Cu")
		(net "M_K_CPU0_SA_DQ<3>")
	)
	(segment
		(start 440.022488 -199.06615)
		(end 440.252866 -199.06615)
		(width 0.14478)
		(layer "In6.Cu")
		(net "M_K_CPU0_SA_DQ<3>")
	)
	(segment
		(start 418.026596 -199.450706)
		(end 418.876734 -200.300844)
		(width 0.14478)
		(layer "In6.Cu")
		(net "M_K_CPU0_SA_DQ<3>")
	)
	(segment
		(start 428.216822 -199.92721)
		(end 428.4472 -199.92721)
		(width 0.14478)
		(layer "In6.Cu")
		(net "M_K_CPU0_SA_DQ<3>")
	)
	(segment
		(start 422.890188 -199.236838)
		(end 423.053256 -199.07377)
		(width 0.14478)
		(layer "In6.Cu")
		(net "M_K_CPU0_SA_DQ<3>")
	)
	(segment
		(start 426.232828 -200.300844)
		(end 427.900084 -200.300844)
		(width 0.14478)
		(layer "In6.Cu")
		(net "M_K_CPU0_SA_DQ<3>")
	)
	(segment
		(start 436.308754 -200.310242)
		(end 436.6133 -200.310242)
		(width 0.14478)
		(layer "In6.Cu")
		(net "M_K_CPU0_SA_DQ<3>")
	)
	(segment
		(start 421.127174 -200.156064)
		(end 421.271954 -200.300844)
		(width 0.14478)
		(layer "In6.Cu")
		(net "M_K_CPU0_SA_DQ<3>")
	)
	(segment
		(start 420.982394 -199.917812)
		(end 421.127174 -200.062592)
		(width 0.14478)
		(layer "In6.Cu")
		(net "M_K_CPU0_SA_DQ<3>")
	)
	(segment
		(start 423.600372 -199.450706)
		(end 425.38269 -199.450706)
		(width 0.14478)
		(layer "In6.Cu")
		(net "M_K_CPU0_SA_DQ<3>")
	)
	(arc
		(start 392.46683 -223.078802)
		(mid 392.645643 -222.876452)
		(end 392.710162 -222.614236)
		(width 0.0889)
		(layer "In6.Cu")
		(net "M_K_CPU0_SA_DQ<3>")
	)
	(arc
		(start 389.616188 -226.33686)
		(mid 389.799696 -226.291366)
		(end 389.981948 -226.341686)
		(width 0.0889)
		(layer "In6.Cu")
		(net "M_K_CPU0_SA_DQ<3>")
	)
	(arc
		(start 392.897868 -222.291656)
		(mid 392.988065 -222.255746)
		(end 393.084812 -222.247714)
		(width 0.0889)
		(layer "In6.Cu")
		(net "M_K_CPU0_SA_DQ<3>")
	)
	(arc
		(start 389.981948 -226.341686)
		(mid 390.264904 -226.417863)
		(end 390.54786 -226.341686)
		(width 0.0889)
		(layer "In6.Cu")
		(net "M_K_CPU0_SA_DQ<3>")
	)
	(arc
		(start 391.526776 -226.318826)
		(mid 391.705589 -226.116476)
		(end 391.770108 -225.85426)
		(width 0.0889)
		(layer "In6.Cu")
		(net "M_K_CPU0_SA_DQ<3>")
	)
	(arc
		(start 389.104886 -226.373436)
		(mid 389.360094 -226.416913)
		(end 389.607806 -226.341686)
		(width 0.0889)
		(layer "In6.Cu")
		(net "M_K_CPU0_SA_DQ<3>")
	)
	(arc
		(start 391.99693 -225.50882)
		(mid 392.240257 -225.044254)
		(end 391.99693 -224.579688)
		(width 0.0889)
		(layer "In6.Cu")
		(net "M_K_CPU0_SA_DQ<3>")
	)
	(arc
		(start 392.240262 -223.424242)
		(mid 392.281811 -223.25282)
		(end 392.397234 -223.119442)
		(width 0.0889)
		(layer "In6.Cu")
		(net "M_K_CPU0_SA_DQ<3>")
	)
	(arc
		(start 390.921748 -226.341686)
		(mid 391.204704 -226.417863)
		(end 391.48766 -226.341686)
		(width 0.0889)
		(layer "In6.Cu")
		(net "M_K_CPU0_SA_DQ<3>")
	)
	(arc
		(start 390.54786 -226.341686)
		(mid 390.734804 -226.291431)
		(end 390.921748 -226.341686)
		(width 0.0889)
		(layer "In6.Cu")
		(net "M_K_CPU0_SA_DQ<3>")
	)
	(arc
		(start 392.710162 -222.614236)
		(mid 392.751128 -222.44383)
		(end 392.865102 -222.310706)
		(width 0.0889)
		(layer "In6.Cu")
		(net "M_K_CPU0_SA_DQ<3>")
	)
	(arc
		(start 391.770108 -225.85426)
		(mid 391.811363 -225.683289)
		(end 391.926064 -225.549968)
		(width 0.0889)
		(layer "In6.Cu")
		(net "M_K_CPU0_SA_DQ<3>")
	)
	(arc
		(start 391.99693 -223.888808)
		(mid 392.175743 -223.686458)
		(end 392.240262 -223.424242)
		(width 0.0889)
		(layer "In6.Cu")
		(net "M_K_CPU0_SA_DQ<3>")
	)
	(arc
		(start 391.926064 -224.53854)
		(mid 391.770136 -224.234248)
		(end 391.926064 -223.929956)
		(width 0.0889)
		(layer "In6.Cu")
		(net "M_K_CPU0_SA_DQ<3>")
	)
	(segment
		(start 388.387844 -244.750082)
		(end 388.85495 -244.484144)
		(width 0.10668)
		(layer "F.Cu")
		(net "M_K_CPU0_SA_DQ<31>")
	)
	(segment
		(start 423.211752 -233.07167)
		(end 423.37482 -233.234738)
		(width 0.14478)
		(layer "In6.Cu")
		(net "M_K_CPU0_SA_DQ<31>")
	)
	(segment
		(start 437.94807 -233.239818)
		(end 438.111138 -233.07675)
		(width 0.14478)
		(layer "In6.Cu")
		(net "M_K_CPU0_SA_DQ<31>")
	)
	(segment
		(start 391.861548 -244.161564)
		(end 391.871962 -244.16766)
		(width 0.0889)
		(layer "In6.Cu")
		(net "M_K_CPU0_SA_DQ<31>")
	)
	(segment
		(start 436.345838 -234.310174)
		(end 436.6133 -234.310174)
		(width 0.14478)
		(layer "In6.Cu")
		(net "M_K_CPU0_SA_DQ<31>")
	)
	(segment
		(start 423.37482 -233.234738)
		(end 423.37482 -233.296968)
		(width 0.14478)
		(layer "In6.Cu")
		(net "M_K_CPU0_SA_DQ<31>")
	)
	(segment
		(start 415.871406 -233.06659)
		(end 416.034474 -233.229658)
		(width 0.14478)
		(layer "In6.Cu")
		(net "M_K_CPU0_SA_DQ<31>")
	)
	(segment
		(start 430.95799 -233.296968)
		(end 431.121058 -233.460036)
		(width 0.14478)
		(layer "In6.Cu")
		(net "M_K_CPU0_SA_DQ<31>")
	)
	(segment
		(start 416.034474 -233.296968)
		(end 416.197542 -233.460036)
		(width 0.14478)
		(layer "In6.Cu")
		(net "M_K_CPU0_SA_DQ<31>")
	)
	(segment
		(start 440.648598 -233.594148)
		(end 440.78271 -233.72826)
		(width 0.14478)
		(layer "In6.Cu")
		(net "M_K_CPU0_SA_DQ<31>")
	)
	(segment
		(start 433.786026 -234.310174)
		(end 435.463188 -234.310174)
		(width 0.14478)
		(layer "In6.Cu")
		(net "M_K_CPU0_SA_DQ<31>")
	)
	(segment
		(start 435.626256 -234.105958)
		(end 435.789324 -233.94289)
		(width 0.14478)
		(layer "In6.Cu")
		(net "M_K_CPU0_SA_DQ<31>")
	)
	(segment
		(start 440.231276 -233.191812)
		(end 440.514486 -233.191812)
		(width 0.14478)
		(layer "In6.Cu")
		(net "M_K_CPU0_SA_DQ<31>")
	)
	(segment
		(start 412.76778 -234.310174)
		(end 412.930848 -234.147106)
		(width 0.14478)
		(layer "In6.Cu")
		(net "M_K_CPU0_SA_DQ<31>")
	)
	(segment
		(start 410.456634 -235.978954)
		(end 412.125414 -234.310174)
		(width 0.14478)
		(layer "In6.Cu")
		(net "M_K_CPU0_SA_DQ<31>")
	)
	(segment
		(start 441.334144 -233.191812)
		(end 441.617354 -233.191812)
		(width 0.14478)
		(layer "In6.Cu")
		(net "M_K_CPU0_SA_DQ<31>")
	)
	(segment
		(start 438.341516 -233.07675)
		(end 438.504584 -233.239818)
		(width 0.14478)
		(layer "In6.Cu")
		(net "M_K_CPU0_SA_DQ<31>")
	)
	(segment
		(start 423.537888 -233.460036)
		(end 425.392088 -233.460036)
		(width 0.14478)
		(layer "In6.Cu")
		(net "M_K_CPU0_SA_DQ<31>")
	)
	(segment
		(start 389.607806 -244.161564)
		(end 389.616188 -244.156738)
		(width 0.0889)
		(layer "In6.Cu")
		(net "M_K_CPU0_SA_DQ<31>")
	)
	(segment
		(start 437.94807 -233.296968)
		(end 437.94807 -233.239818)
		(width 0.14478)
		(layer "In6.Cu")
		(net "M_K_CPU0_SA_DQ<31>")
	)
	(segment
		(start 430.401476 -233.296968)
		(end 430.401476 -233.229658)
		(width 0.14478)
		(layer "In6.Cu")
		(net "M_K_CPU0_SA_DQ<31>")
	)
	(segment
		(start 422.39946 -233.460036)
		(end 422.655238 -233.460036)
		(width 0.14478)
		(layer "In6.Cu")
		(net "M_K_CPU0_SA_DQ<31>")
	)
	(segment
		(start 420.584122 -234.147106)
		(end 420.584122 -234.083098)
		(width 0.14478)
		(layer "In6.Cu")
		(net "M_K_CPU0_SA_DQ<31>")
	)
	(segment
		(start 418.698172 -234.310174)
		(end 420.421054 -234.310174)
		(width 0.14478)
		(layer "In6.Cu")
		(net "M_K_CPU0_SA_DQ<31>")
	)
	(segment
		(start 437.785002 -233.460036)
		(end 437.94807 -233.296968)
		(width 0.14478)
		(layer "In6.Cu")
		(net "M_K_CPU0_SA_DQ<31>")
	)
	(segment
		(start 432.935888 -233.460036)
		(end 433.786026 -234.310174)
		(width 0.14478)
		(layer "In6.Cu")
		(net "M_K_CPU0_SA_DQ<31>")
	)
	(segment
		(start 429.931068 -233.460036)
		(end 430.238408 -233.460036)
		(width 0.14478)
		(layer "In6.Cu")
		(net "M_K_CPU0_SA_DQ<31>")
	)
	(segment
		(start 421.549322 -234.310174)
		(end 422.39946 -233.460036)
		(width 0.14478)
		(layer "In6.Cu")
		(net "M_K_CPU0_SA_DQ<31>")
	)
	(segment
		(start 436.019702 -233.94289)
		(end 436.18277 -234.105958)
		(width 0.14478)
		(layer "In6.Cu")
		(net "M_K_CPU0_SA_DQ<31>")
	)
	(segment
		(start 442.119258 -233.460036)
		(end 442.5442 -233.884978)
		(width 0.14478)
		(layer "In6.Cu")
		(net "M_K_CPU0_SA_DQ<31>")
	)
	(segment
		(start 423.37482 -233.296968)
		(end 423.537888 -233.460036)
		(width 0.14478)
		(layer "In6.Cu")
		(net "M_K_CPU0_SA_DQ<31>")
	)
	(segment
		(start 431.121058 -233.460036)
		(end 432.935888 -233.460036)
		(width 0.14478)
		(layer "In6.Cu")
		(net "M_K_CPU0_SA_DQ<31>")
	)
	(segment
		(start 420.977568 -233.92003)
		(end 421.140636 -234.083098)
		(width 0.14478)
		(layer "In6.Cu")
		(net "M_K_CPU0_SA_DQ<31>")
	)
	(segment
		(start 437.463438 -233.460036)
		(end 437.785002 -233.460036)
		(width 0.14478)
		(layer "In6.Cu")
		(net "M_K_CPU0_SA_DQ<31>")
	)
	(segment
		(start 395.915134 -243.43995)
		(end 403.6568 -243.43995)
		(width 0.14478)
		(layer "In6.Cu")
		(net "M_K_CPU0_SA_DQ<31>")
	)
	(segment
		(start 430.564544 -233.06659)
		(end 430.794922 -233.06659)
		(width 0.14478)
		(layer "In6.Cu")
		(net "M_K_CPU0_SA_DQ<31>")
	)
	(segment
		(start 429.08093 -234.310174)
		(end 429.931068 -233.460036)
		(width 0.14478)
		(layer "In6.Cu")
		(net "M_K_CPU0_SA_DQ<31>")
	)
	(segment
		(start 426.242226 -234.310174)
		(end 427.873922 -234.310174)
		(width 0.14478)
		(layer "In6.Cu")
		(net "M_K_CPU0_SA_DQ<31>")
	)
	(segment
		(start 420.74719 -233.92003)
		(end 420.977568 -233.92003)
		(width 0.14478)
		(layer "In6.Cu")
		(net "M_K_CPU0_SA_DQ<31>")
	)
	(segment
		(start 414.006792 -234.310174)
		(end 414.85693 -233.460036)
		(width 0.14478)
		(layer "In6.Cu")
		(net "M_K_CPU0_SA_DQ<31>")
	)
	(segment
		(start 394.186664 -243.73205)
		(end 395.275816 -243.73205)
		(width 0.0889)
		(layer "In6.Cu")
		(net "M_K_CPU0_SA_DQ<31>")
	)
	(segment
		(start 428.593504 -234.147106)
		(end 428.756572 -234.310174)
		(width 0.14478)
		(layer "In6.Cu")
		(net "M_K_CPU0_SA_DQ<31>")
	)
	(segment
		(start 413.65043 -234.310174)
		(end 414.006792 -234.310174)
		(width 0.14478)
		(layer "In6.Cu")
		(net "M_K_CPU0_SA_DQ<31>")
	)
	(segment
		(start 395.567916 -243.43995)
		(end 395.915134 -243.43995)
		(width 0.0889)
		(layer "In6.Cu")
		(net "M_K_CPU0_SA_DQ<31>")
	)
	(segment
		(start 391.849864 -244.154706)
		(end 391.861548 -244.161564)
		(width 0.0889)
		(layer "In6.Cu")
		(net "M_K_CPU0_SA_DQ<31>")
	)
	(segment
		(start 420.584122 -234.083098)
		(end 420.74719 -233.92003)
		(width 0.14478)
		(layer "In6.Cu")
		(net "M_K_CPU0_SA_DQ<31>")
	)
	(segment
		(start 439.963052 -233.72826)
		(end 440.097164 -233.594148)
		(width 0.14478)
		(layer "In6.Cu")
		(net "M_K_CPU0_SA_DQ<31>")
	)
	(segment
		(start 416.984434 -233.06659)
		(end 417.147502 -233.229658)
		(width 0.14478)
		(layer "In6.Cu")
		(net "M_K_CPU0_SA_DQ<31>")
	)
	(segment
		(start 441.200032 -233.594148)
		(end 441.200032 -233.325924)
		(width 0.14478)
		(layer "In6.Cu")
		(net "M_K_CPU0_SA_DQ<31>")
	)
	(segment
		(start 438.667652 -233.460036)
		(end 439.411618 -233.460036)
		(width 0.14478)
		(layer "In6.Cu")
		(net "M_K_CPU0_SA_DQ<31>")
	)
	(segment
		(start 428.200058 -233.92003)
		(end 428.430436 -233.92003)
		(width 0.14478)
		(layer "In6.Cu")
		(net "M_K_CPU0_SA_DQ<31>")
	)
	(segment
		(start 417.147502 -233.296968)
		(end 417.31057 -233.460036)
		(width 0.14478)
		(layer "In6.Cu")
		(net "M_K_CPU0_SA_DQ<31>")
	)
	(segment
		(start 421.140636 -234.083098)
		(end 421.140636 -234.147106)
		(width 0.14478)
		(layer "In6.Cu")
		(net "M_K_CPU0_SA_DQ<31>")
	)
	(segment
		(start 416.42792 -233.460036)
		(end 416.590988 -233.296968)
		(width 0.14478)
		(layer "In6.Cu")
		(net "M_K_CPU0_SA_DQ<31>")
	)
	(segment
		(start 413.093916 -233.92003)
		(end 413.324294 -233.92003)
		(width 0.14478)
		(layer "In6.Cu")
		(net "M_K_CPU0_SA_DQ<31>")
	)
	(segment
		(start 430.238408 -233.460036)
		(end 430.401476 -233.296968)
		(width 0.14478)
		(layer "In6.Cu")
		(net "M_K_CPU0_SA_DQ<31>")
	)
	(segment
		(start 428.593504 -234.083098)
		(end 428.593504 -234.147106)
		(width 0.14478)
		(layer "In6.Cu")
		(net "M_K_CPU0_SA_DQ<31>")
	)
	(segment
		(start 430.401476 -233.229658)
		(end 430.564544 -233.06659)
		(width 0.14478)
		(layer "In6.Cu")
		(net "M_K_CPU0_SA_DQ<31>")
	)
	(segment
		(start 415.47796 -233.296968)
		(end 415.47796 -233.229658)
		(width 0.14478)
		(layer "In6.Cu")
		(net "M_K_CPU0_SA_DQ<31>")
	)
	(segment
		(start 413.487362 -234.083098)
		(end 413.487362 -234.147106)
		(width 0.14478)
		(layer "In6.Cu")
		(net "M_K_CPU0_SA_DQ<31>")
	)
	(segment
		(start 393.084812 -244.237764)
		(end 393.68095 -244.237764)
		(width 0.0889)
		(layer "In6.Cu")
		(net "M_K_CPU0_SA_DQ<31>")
	)
	(segment
		(start 421.140636 -234.147106)
		(end 421.303704 -234.310174)
		(width 0.14478)
		(layer "In6.Cu")
		(net "M_K_CPU0_SA_DQ<31>")
	)
	(segment
		(start 415.314892 -233.460036)
		(end 415.47796 -233.296968)
		(width 0.14478)
		(layer "In6.Cu")
		(net "M_K_CPU0_SA_DQ<31>")
	)
	(segment
		(start 422.655238 -233.460036)
		(end 422.818306 -233.296968)
		(width 0.14478)
		(layer "In6.Cu")
		(net "M_K_CPU0_SA_DQ<31>")
	)
	(segment
		(start 422.818306 -233.234738)
		(end 422.981374 -233.07167)
		(width 0.14478)
		(layer "In6.Cu")
		(net "M_K_CPU0_SA_DQ<31>")
	)
	(segment
		(start 395.275816 -243.73205)
		(end 395.567916 -243.43995)
		(width 0.0889)
		(layer "In6.Cu")
		(net "M_K_CPU0_SA_DQ<31>")
	)
	(segment
		(start 416.590988 -233.296968)
		(end 416.590988 -233.229658)
		(width 0.14478)
		(layer "In6.Cu")
		(net "M_K_CPU0_SA_DQ<31>")
	)
	(segment
		(start 417.31057 -233.460036)
		(end 417.848034 -233.460036)
		(width 0.14478)
		(layer "In6.Cu")
		(net "M_K_CPU0_SA_DQ<31>")
	)
	(segment
		(start 440.648598 -233.325924)
		(end 440.648598 -233.594148)
		(width 0.14478)
		(layer "In6.Cu")
		(net "M_K_CPU0_SA_DQ<31>")
	)
	(segment
		(start 430.794922 -233.06659)
		(end 430.95799 -233.229658)
		(width 0.14478)
		(layer "In6.Cu")
		(net "M_K_CPU0_SA_DQ<31>")
	)
	(segment
		(start 410.456634 -236.640116)
		(end 410.456634 -235.978954)
		(width 0.14478)
		(layer "In6.Cu")
		(net "M_K_CPU0_SA_DQ<31>")
	)
	(segment
		(start 440.097164 -233.594148)
		(end 440.097164 -233.325924)
		(width 0.14478)
		(layer "In6.Cu")
		(net "M_K_CPU0_SA_DQ<31>")
	)
	(segment
		(start 439.411618 -233.460036)
		(end 439.679842 -233.72826)
		(width 0.14478)
		(layer "In6.Cu")
		(net "M_K_CPU0_SA_DQ<31>")
	)
	(segment
		(start 422.818306 -233.296968)
		(end 422.818306 -233.234738)
		(width 0.14478)
		(layer "In6.Cu")
		(net "M_K_CPU0_SA_DQ<31>")
	)
	(segment
		(start 440.514486 -233.191812)
		(end 440.648598 -233.325924)
		(width 0.14478)
		(layer "In6.Cu")
		(net "M_K_CPU0_SA_DQ<31>")
	)
	(segment
		(start 430.95799 -233.229658)
		(end 430.95799 -233.296968)
		(width 0.14478)
		(layer "In6.Cu")
		(net "M_K_CPU0_SA_DQ<31>")
	)
	(segment
		(start 438.504584 -233.239818)
		(end 438.504584 -233.296968)
		(width 0.14478)
		(layer "In6.Cu")
		(net "M_K_CPU0_SA_DQ<31>")
	)
	(segment
		(start 428.756572 -234.310174)
		(end 429.08093 -234.310174)
		(width 0.14478)
		(layer "In6.Cu")
		(net "M_K_CPU0_SA_DQ<31>")
	)
	(segment
		(start 436.18277 -234.147106)
		(end 436.345838 -234.310174)
		(width 0.14478)
		(layer "In6.Cu")
		(net "M_K_CPU0_SA_DQ<31>")
	)
	(segment
		(start 428.430436 -233.92003)
		(end 428.593504 -234.083098)
		(width 0.14478)
		(layer "In6.Cu")
		(net "M_K_CPU0_SA_DQ<31>")
	)
	(segment
		(start 421.303704 -234.310174)
		(end 421.549322 -234.310174)
		(width 0.14478)
		(layer "In6.Cu")
		(net "M_K_CPU0_SA_DQ<31>")
	)
	(segment
		(start 413.487362 -234.147106)
		(end 413.65043 -234.310174)
		(width 0.14478)
		(layer "In6.Cu")
		(net "M_K_CPU0_SA_DQ<31>")
	)
	(segment
		(start 435.789324 -233.94289)
		(end 436.019702 -233.94289)
		(width 0.14478)
		(layer "In6.Cu")
		(net "M_K_CPU0_SA_DQ<31>")
	)
	(segment
		(start 416.034474 -233.229658)
		(end 416.034474 -233.296968)
		(width 0.14478)
		(layer "In6.Cu")
		(net "M_K_CPU0_SA_DQ<31>")
	)
	(segment
		(start 412.930848 -234.083098)
		(end 413.093916 -233.92003)
		(width 0.14478)
		(layer "In6.Cu")
		(net "M_K_CPU0_SA_DQ<31>")
	)
	(segment
		(start 438.111138 -233.07675)
		(end 438.341516 -233.07675)
		(width 0.14478)
		(layer "In6.Cu")
		(net "M_K_CPU0_SA_DQ<31>")
	)
	(segment
		(start 438.504584 -233.296968)
		(end 438.667652 -233.460036)
		(width 0.14478)
		(layer "In6.Cu")
		(net "M_K_CPU0_SA_DQ<31>")
	)
	(segment
		(start 416.590988 -233.229658)
		(end 416.754056 -233.06659)
		(width 0.14478)
		(layer "In6.Cu")
		(net "M_K_CPU0_SA_DQ<31>")
	)
	(segment
		(start 416.754056 -233.06659)
		(end 416.984434 -233.06659)
		(width 0.14478)
		(layer "In6.Cu")
		(net "M_K_CPU0_SA_DQ<31>")
	)
	(segment
		(start 422.981374 -233.07167)
		(end 423.211752 -233.07167)
		(width 0.14478)
		(layer "In6.Cu")
		(net "M_K_CPU0_SA_DQ<31>")
	)
	(segment
		(start 441.885578 -233.460036)
		(end 442.119258 -233.460036)
		(width 0.14478)
		(layer "In6.Cu")
		(net "M_K_CPU0_SA_DQ<31>")
	)
	(segment
		(start 441.200032 -233.325924)
		(end 441.334144 -233.191812)
		(width 0.14478)
		(layer "In6.Cu")
		(net "M_K_CPU0_SA_DQ<31>")
	)
	(segment
		(start 428.03699 -234.083098)
		(end 428.200058 -233.92003)
		(width 0.14478)
		(layer "In6.Cu")
		(net "M_K_CPU0_SA_DQ<31>")
	)
	(segment
		(start 415.641028 -233.06659)
		(end 415.871406 -233.06659)
		(width 0.14478)
		(layer "In6.Cu")
		(net "M_K_CPU0_SA_DQ<31>")
	)
	(segment
		(start 416.197542 -233.460036)
		(end 416.42792 -233.460036)
		(width 0.14478)
		(layer "In6.Cu")
		(net "M_K_CPU0_SA_DQ<31>")
	)
	(segment
		(start 412.125414 -234.310174)
		(end 412.76778 -234.310174)
		(width 0.14478)
		(layer "In6.Cu")
		(net "M_K_CPU0_SA_DQ<31>")
	)
	(segment
		(start 439.679842 -233.72826)
		(end 439.963052 -233.72826)
		(width 0.14478)
		(layer "In6.Cu")
		(net "M_K_CPU0_SA_DQ<31>")
	)
	(segment
		(start 392.427206 -244.161564)
		(end 392.43889 -244.154706)
		(width 0.0889)
		(layer "In6.Cu")
		(net "M_K_CPU0_SA_DQ<31>")
	)
	(segment
		(start 417.147502 -233.229658)
		(end 417.147502 -233.296968)
		(width 0.14478)
		(layer "In6.Cu")
		(net "M_K_CPU0_SA_DQ<31>")
	)
	(segment
		(start 435.463188 -234.310174)
		(end 435.626256 -234.147106)
		(width 0.14478)
		(layer "In6.Cu")
		(net "M_K_CPU0_SA_DQ<31>")
	)
	(segment
		(start 393.68095 -244.237764)
		(end 394.186664 -243.73205)
		(width 0.0889)
		(layer "In6.Cu")
		(net "M_K_CPU0_SA_DQ<31>")
	)
	(segment
		(start 440.097164 -233.325924)
		(end 440.231276 -233.191812)
		(width 0.14478)
		(layer "In6.Cu")
		(net "M_K_CPU0_SA_DQ<31>")
	)
	(segment
		(start 440.78271 -233.72826)
		(end 441.06592 -233.72826)
		(width 0.14478)
		(layer "In6.Cu")
		(net "M_K_CPU0_SA_DQ<31>")
	)
	(segment
		(start 389.008874 -244.218714)
		(end 389.104886 -244.193314)
		(width 0.0889)
		(layer "In6.Cu")
		(net "M_K_CPU0_SA_DQ<31>")
	)
	(segment
		(start 388.85495 -244.484144)
		(end 389.008874 -244.218714)
		(width 0.0889)
		(layer "In6.Cu")
		(net "M_K_CPU0_SA_DQ<31>")
	)
	(segment
		(start 436.18277 -234.105958)
		(end 436.18277 -234.147106)
		(width 0.14478)
		(layer "In6.Cu")
		(net "M_K_CPU0_SA_DQ<31>")
	)
	(segment
		(start 414.85693 -233.460036)
		(end 415.314892 -233.460036)
		(width 0.14478)
		(layer "In6.Cu")
		(net "M_K_CPU0_SA_DQ<31>")
	)
	(segment
		(start 420.421054 -234.310174)
		(end 420.584122 -234.147106)
		(width 0.14478)
		(layer "In6.Cu")
		(net "M_K_CPU0_SA_DQ<31>")
	)
	(segment
		(start 412.930848 -234.147106)
		(end 412.930848 -234.083098)
		(width 0.14478)
		(layer "In6.Cu")
		(net "M_K_CPU0_SA_DQ<31>")
	)
	(segment
		(start 436.6133 -234.310174)
		(end 437.463438 -233.460036)
		(width 0.14478)
		(layer "In6.Cu")
		(net "M_K_CPU0_SA_DQ<31>")
	)
	(segment
		(start 435.626256 -234.147106)
		(end 435.626256 -234.105958)
		(width 0.14478)
		(layer "In6.Cu")
		(net "M_K_CPU0_SA_DQ<31>")
	)
	(segment
		(start 441.06592 -233.72826)
		(end 441.200032 -233.594148)
		(width 0.14478)
		(layer "In6.Cu")
		(net "M_K_CPU0_SA_DQ<31>")
	)
	(segment
		(start 403.6568 -243.43995)
		(end 410.456634 -236.640116)
		(width 0.14478)
		(layer "In6.Cu")
		(net "M_K_CPU0_SA_DQ<31>")
	)
	(segment
		(start 427.873922 -234.310174)
		(end 428.03699 -234.147106)
		(width 0.14478)
		(layer "In6.Cu")
		(net "M_K_CPU0_SA_DQ<31>")
	)
	(segment
		(start 415.47796 -233.229658)
		(end 415.641028 -233.06659)
		(width 0.14478)
		(layer "In6.Cu")
		(net "M_K_CPU0_SA_DQ<31>")
	)
	(segment
		(start 428.03699 -234.147106)
		(end 428.03699 -234.083098)
		(width 0.14478)
		(layer "In6.Cu")
		(net "M_K_CPU0_SA_DQ<31>")
	)
	(segment
		(start 441.617354 -233.191812)
		(end 441.885578 -233.460036)
		(width 0.14478)
		(layer "In6.Cu")
		(net "M_K_CPU0_SA_DQ<31>")
	)
	(segment
		(start 417.848034 -233.460036)
		(end 418.698172 -234.310174)
		(width 0.14478)
		(layer "In6.Cu")
		(net "M_K_CPU0_SA_DQ<31>")
	)
	(segment
		(start 425.392088 -233.460036)
		(end 426.242226 -234.310174)
		(width 0.14478)
		(layer "In6.Cu")
		(net "M_K_CPU0_SA_DQ<31>")
	)
	(segment
		(start 413.324294 -233.92003)
		(end 413.487362 -234.083098)
		(width 0.14478)
		(layer "In6.Cu")
		(net "M_K_CPU0_SA_DQ<31>")
	)
	(arc
		(start 392.43889 -244.154706)
		(mid 392.621145 -244.111053)
		(end 392.801602 -244.161564)
		(width 0.0889)
		(layer "In6.Cu")
		(net "M_K_CPU0_SA_DQ<31>")
	)
	(arc
		(start 389.616188 -244.156738)
		(mid 389.799696 -244.111244)
		(end 389.981948 -244.161564)
		(width 0.0889)
		(layer "In6.Cu")
		(net "M_K_CPU0_SA_DQ<31>")
	)
	(arc
		(start 392.801602 -244.161564)
		(mid 392.938165 -244.218397)
		(end 393.084812 -244.237764)
		(width 0.0889)
		(layer "In6.Cu")
		(net "M_K_CPU0_SA_DQ<31>")
	)
	(arc
		(start 391.871962 -244.16766)
		(mid 392.150394 -244.237758)
		(end 392.427206 -244.161564)
		(width 0.0889)
		(layer "In6.Cu")
		(net "M_K_CPU0_SA_DQ<31>")
	)
	(arc
		(start 389.981948 -244.161564)
		(mid 390.264904 -244.237741)
		(end 390.54786 -244.161564)
		(width 0.0889)
		(layer "In6.Cu")
		(net "M_K_CPU0_SA_DQ<31>")
	)
	(arc
		(start 390.921748 -244.161564)
		(mid 391.204704 -244.237741)
		(end 391.48766 -244.161564)
		(width 0.0889)
		(layer "In6.Cu")
		(net "M_K_CPU0_SA_DQ<31>")
	)
	(arc
		(start 390.54786 -244.161564)
		(mid 390.734804 -244.111309)
		(end 390.921748 -244.161564)
		(width 0.0889)
		(layer "In6.Cu")
		(net "M_K_CPU0_SA_DQ<31>")
	)
	(arc
		(start 389.104886 -244.193314)
		(mid 389.360094 -244.236791)
		(end 389.607806 -244.161564)
		(width 0.0889)
		(layer "In6.Cu")
		(net "M_K_CPU0_SA_DQ<31>")
	)
	(arc
		(start 391.48766 -244.161564)
		(mid 391.667865 -244.111247)
		(end 391.849864 -244.154706)
		(width 0.0889)
		(layer "In6.Cu")
		(net "M_K_CPU0_SA_DQ<31>")
	)
	(segment
		(start 389.798052 -243.940076)
		(end 390.264904 -243.674138)
		(width 0.10668)
		(layer "F.Cu")
		(net "M_K_CPU0_SA_DQ<30>")
	)
	(segment
		(start 420.255192 -232.610152)
		(end 420.41826 -232.447084)
		(width 0.14478)
		(layer "In6.Cu")
		(net "M_K_CPU0_SA_DQ<30>")
	)
	(segment
		(start 438.199022 -231.36987)
		(end 438.36209 -231.532938)
		(width 0.14478)
		(layer "In6.Cu")
		(net "M_K_CPU0_SA_DQ<30>")
	)
	(segment
		(start 431.156872 -231.760014)
		(end 431.890932 -231.760014)
		(width 0.14478)
		(layer "In6.Cu")
		(net "M_K_CPU0_SA_DQ<30>")
	)
	(segment
		(start 432.731926 -231.760014)
		(end 432.935888 -231.760014)
		(width 0.14478)
		(layer "In6.Cu")
		(net "M_K_CPU0_SA_DQ<30>")
	)
	(segment
		(start 432.035712 -231.515412)
		(end 432.180492 -231.370632)
		(width 0.14478)
		(layer "In6.Cu")
		(net "M_K_CPU0_SA_DQ<30>")
	)
	(segment
		(start 441.346336 -232.14457)
		(end 441.509404 -231.981502)
		(width 0.14478)
		(layer "In6.Cu")
		(net "M_K_CPU0_SA_DQ<30>")
	)
	(segment
		(start 439.839862 -231.923082)
		(end 439.839862 -231.981502)
		(width 0.14478)
		(layer "In6.Cu")
		(net "M_K_CPU0_SA_DQ<30>")
	)
	(segment
		(start 430.274222 -231.760014)
		(end 430.43729 -231.596946)
		(width 0.14478)
		(layer "In6.Cu")
		(net "M_K_CPU0_SA_DQ<30>")
	)
	(segment
		(start 422.933622 -231.370632)
		(end 423.195496 -231.370632)
		(width 0.14478)
		(layer "In6.Cu")
		(net "M_K_CPU0_SA_DQ<30>")
	)
	(segment
		(start 390.418828 -243.408708)
		(end 390.51484 -243.383308)
		(width 0.0889)
		(layer "In6.Cu")
		(net "M_K_CPU0_SA_DQ<30>")
	)
	(segment
		(start 416.82162 -231.760014)
		(end 416.9664 -231.904794)
		(width 0.14478)
		(layer "In6.Cu")
		(net "M_K_CPU0_SA_DQ<30>")
	)
	(segment
		(start 417.373054 -232.140252)
		(end 417.517834 -231.995472)
		(width 0.14478)
		(layer "In6.Cu")
		(net "M_K_CPU0_SA_DQ<30>")
	)
	(segment
		(start 391.01776 -243.351558)
		(end 391.026142 -243.346732)
		(width 0.0889)
		(layer "In6.Cu")
		(net "M_K_CPU0_SA_DQ<30>")
	)
	(segment
		(start 435.445154 -232.610152)
		(end 435.608222 -232.447084)
		(width 0.14478)
		(layer "In6.Cu")
		(net "M_K_CPU0_SA_DQ<30>")
	)
	(segment
		(start 417.517834 -231.995472)
		(end 417.517834 -231.904794)
		(width 0.14478)
		(layer "In6.Cu")
		(net "M_K_CPU0_SA_DQ<30>")
	)
	(segment
		(start 425.392088 -231.760014)
		(end 426.242226 -232.610152)
		(width 0.14478)
		(layer "In6.Cu")
		(net "M_K_CPU0_SA_DQ<30>")
	)
	(segment
		(start 428.16018 -232.465372)
		(end 428.16018 -232.376472)
		(width 0.14478)
		(layer "In6.Cu")
		(net "M_K_CPU0_SA_DQ<30>")
	)
	(segment
		(start 413.39897 -232.447084)
		(end 413.562038 -232.610152)
		(width 0.14478)
		(layer "In6.Cu")
		(net "M_K_CPU0_SA_DQ<30>")
	)
	(segment
		(start 395.298676 -242.76939)
		(end 395.537436 -242.53063)
		(width 0.0889)
		(layer "In6.Cu")
		(net "M_K_CPU0_SA_DQ<30>")
	)
	(segment
		(start 432.935888 -231.760014)
		(end 433.786026 -232.610152)
		(width 0.14478)
		(layer "In6.Cu")
		(net "M_K_CPU0_SA_DQ<30>")
	)
	(segment
		(start 440.789822 -231.375458)
		(end 440.95289 -231.538526)
		(width 0.14478)
		(layer "In6.Cu")
		(net "M_K_CPU0_SA_DQ<30>")
	)
	(segment
		(start 442.119258 -231.760014)
		(end 442.5442 -232.184956)
		(width 0.14478)
		(layer "In6.Cu")
		(net "M_K_CPU0_SA_DQ<30>")
	)
	(segment
		(start 440.396376 -231.538526)
		(end 440.559444 -231.375458)
		(width 0.14478)
		(layer "In6.Cu")
		(net "M_K_CPU0_SA_DQ<30>")
	)
	(segment
		(start 436.327804 -232.610152)
		(end 436.6133 -232.610152)
		(width 0.14478)
		(layer "In6.Cu")
		(net "M_K_CPU0_SA_DQ<30>")
	)
	(segment
		(start 421.137842 -232.610152)
		(end 421.549322 -232.610152)
		(width 0.14478)
		(layer "In6.Cu")
		(net "M_K_CPU0_SA_DQ<30>")
	)
	(segment
		(start 428.711614 -232.465372)
		(end 428.856394 -232.610152)
		(width 0.14478)
		(layer "In6.Cu")
		(net "M_K_CPU0_SA_DQ<30>")
	)
	(segment
		(start 421.549322 -232.610152)
		(end 422.39946 -231.760014)
		(width 0.14478)
		(layer "In6.Cu")
		(net "M_K_CPU0_SA_DQ<30>")
	)
	(segment
		(start 441.509404 -231.923082)
		(end 441.672472 -231.760014)
		(width 0.14478)
		(layer "In6.Cu")
		(net "M_K_CPU0_SA_DQ<30>")
	)
	(segment
		(start 412.842456 -232.447084)
		(end 412.842456 -232.399078)
		(width 0.14478)
		(layer "In6.Cu")
		(net "M_K_CPU0_SA_DQ<30>")
	)
	(segment
		(start 440.95289 -231.538526)
		(end 440.95289 -231.981502)
		(width 0.14478)
		(layer "In6.Cu")
		(net "M_K_CPU0_SA_DQ<30>")
	)
	(segment
		(start 429.08093 -232.610152)
		(end 429.931068 -231.760014)
		(width 0.14478)
		(layer "In6.Cu")
		(net "M_K_CPU0_SA_DQ<30>")
	)
	(segment
		(start 423.340276 -231.515412)
		(end 423.340276 -231.615234)
		(width 0.14478)
		(layer "In6.Cu")
		(net "M_K_CPU0_SA_DQ<30>")
	)
	(segment
		(start 417.848034 -231.760014)
		(end 418.698172 -232.610152)
		(width 0.14478)
		(layer "In6.Cu")
		(net "M_K_CPU0_SA_DQ<30>")
	)
	(segment
		(start 441.115958 -232.14457)
		(end 441.346336 -232.14457)
		(width 0.14478)
		(layer "In6.Cu")
		(net "M_K_CPU0_SA_DQ<30>")
	)
	(segment
		(start 415.598356 -232.140252)
		(end 415.743136 -231.995472)
		(width 0.14478)
		(layer "In6.Cu")
		(net "M_K_CPU0_SA_DQ<30>")
	)
	(segment
		(start 391.947146 -243.357654)
		(end 391.95756 -243.351558)
		(width 0.0889)
		(layer "In6.Cu")
		(net "M_K_CPU0_SA_DQ<30>")
	)
	(segment
		(start 424.932348 -231.383332)
		(end 425.077128 -231.528112)
		(width 0.14478)
		(layer "In6.Cu")
		(net "M_K_CPU0_SA_DQ<30>")
	)
	(segment
		(start 424.525694 -231.528112)
		(end 424.670474 -231.383332)
		(width 0.14478)
		(layer "In6.Cu")
		(net "M_K_CPU0_SA_DQ<30>")
	)
	(segment
		(start 430.993804 -231.596946)
		(end 431.156872 -231.760014)
		(width 0.14478)
		(layer "In6.Cu")
		(net "M_K_CPU0_SA_DQ<30>")
	)
	(segment
		(start 433.786026 -232.610152)
		(end 435.445154 -232.610152)
		(width 0.14478)
		(layer "In6.Cu")
		(net "M_K_CPU0_SA_DQ<30>")
	)
	(segment
		(start 424.525694 -231.615234)
		(end 424.525694 -231.528112)
		(width 0.14478)
		(layer "In6.Cu")
		(net "M_K_CPU0_SA_DQ<30>")
	)
	(segment
		(start 428.0154 -232.610152)
		(end 428.16018 -232.465372)
		(width 0.14478)
		(layer "In6.Cu")
		(net "M_K_CPU0_SA_DQ<30>")
	)
	(segment
		(start 428.566834 -232.231692)
		(end 428.711614 -232.376472)
		(width 0.14478)
		(layer "In6.Cu")
		(net "M_K_CPU0_SA_DQ<30>")
	)
	(segment
		(start 414.006792 -232.610152)
		(end 414.85693 -231.760014)
		(width 0.14478)
		(layer "In6.Cu")
		(net "M_K_CPU0_SA_DQ<30>")
	)
	(segment
		(start 429.931068 -231.760014)
		(end 430.274222 -231.760014)
		(width 0.14478)
		(layer "In6.Cu")
		(net "M_K_CPU0_SA_DQ<30>")
	)
	(segment
		(start 436.164736 -232.399078)
		(end 436.164736 -232.447084)
		(width 0.14478)
		(layer "In6.Cu")
		(net "M_K_CPU0_SA_DQ<30>")
	)
	(segment
		(start 428.711614 -232.376472)
		(end 428.711614 -232.465372)
		(width 0.14478)
		(layer "In6.Cu")
		(net "M_K_CPU0_SA_DQ<30>")
	)
	(segment
		(start 417.662614 -231.760014)
		(end 417.848034 -231.760014)
		(width 0.14478)
		(layer "In6.Cu")
		(net "M_K_CPU0_SA_DQ<30>")
	)
	(segment
		(start 431.890932 -231.760014)
		(end 432.035712 -231.615234)
		(width 0.14478)
		(layer "In6.Cu")
		(net "M_K_CPU0_SA_DQ<30>")
	)
	(segment
		(start 435.608222 -232.447084)
		(end 435.608222 -232.399078)
		(width 0.14478)
		(layer "In6.Cu")
		(net "M_K_CPU0_SA_DQ<30>")
	)
	(segment
		(start 415.191702 -231.904794)
		(end 415.191702 -231.995472)
		(width 0.14478)
		(layer "In6.Cu")
		(net "M_K_CPU0_SA_DQ<30>")
	)
	(segment
		(start 437.642508 -231.760014)
		(end 437.805576 -231.596946)
		(width 0.14478)
		(layer "In6.Cu")
		(net "M_K_CPU0_SA_DQ<30>")
	)
	(segment
		(start 432.587146 -231.615234)
		(end 432.731926 -231.760014)
		(width 0.14478)
		(layer "In6.Cu")
		(net "M_K_CPU0_SA_DQ<30>")
	)
	(segment
		(start 395.537436 -242.53063)
		(end 395.886686 -242.53063)
		(width 0.0889)
		(layer "In6.Cu")
		(net "M_K_CPU0_SA_DQ<30>")
	)
	(segment
		(start 440.233308 -232.14457)
		(end 440.396376 -231.981502)
		(width 0.14478)
		(layer "In6.Cu")
		(net "M_K_CPU0_SA_DQ<30>")
	)
	(segment
		(start 409.511754 -236.29874)
		(end 409.511754 -235.24845)
		(width 0.14478)
		(layer "In6.Cu")
		(net "M_K_CPU0_SA_DQ<30>")
	)
	(segment
		(start 438.36209 -231.596946)
		(end 438.525158 -231.760014)
		(width 0.14478)
		(layer "In6.Cu")
		(net "M_K_CPU0_SA_DQ<30>")
	)
	(segment
		(start 426.242226 -232.610152)
		(end 428.0154 -232.610152)
		(width 0.14478)
		(layer "In6.Cu")
		(net "M_K_CPU0_SA_DQ<30>")
	)
	(segment
		(start 414.85693 -231.760014)
		(end 415.046922 -231.760014)
		(width 0.14478)
		(layer "In6.Cu")
		(net "M_K_CPU0_SA_DQ<30>")
	)
	(segment
		(start 432.587146 -231.515412)
		(end 432.587146 -231.615234)
		(width 0.14478)
		(layer "In6.Cu")
		(net "M_K_CPU0_SA_DQ<30>")
	)
	(segment
		(start 415.887916 -231.760014)
		(end 416.82162 -231.760014)
		(width 0.14478)
		(layer "In6.Cu")
		(net "M_K_CPU0_SA_DQ<30>")
	)
	(segment
		(start 415.191702 -231.995472)
		(end 415.336482 -232.140252)
		(width 0.14478)
		(layer "In6.Cu")
		(net "M_K_CPU0_SA_DQ<30>")
	)
	(segment
		(start 438.36209 -231.532938)
		(end 438.36209 -231.596946)
		(width 0.14478)
		(layer "In6.Cu")
		(net "M_K_CPU0_SA_DQ<30>")
	)
	(segment
		(start 428.30496 -232.231692)
		(end 428.566834 -232.231692)
		(width 0.14478)
		(layer "In6.Cu")
		(net "M_K_CPU0_SA_DQ<30>")
	)
	(segment
		(start 439.676794 -231.760014)
		(end 439.839862 -231.923082)
		(width 0.14478)
		(layer "In6.Cu")
		(net "M_K_CPU0_SA_DQ<30>")
	)
	(segment
		(start 403.279864 -242.53063)
		(end 409.511754 -236.29874)
		(width 0.14478)
		(layer "In6.Cu")
		(net "M_K_CPU0_SA_DQ<30>")
	)
	(segment
		(start 438.525158 -231.760014)
		(end 439.676794 -231.760014)
		(width 0.14478)
		(layer "In6.Cu")
		(net "M_K_CPU0_SA_DQ<30>")
	)
	(segment
		(start 436.001668 -232.23601)
		(end 436.164736 -232.399078)
		(width 0.14478)
		(layer "In6.Cu")
		(net "M_K_CPU0_SA_DQ<30>")
	)
	(segment
		(start 423.485056 -231.760014)
		(end 424.380914 -231.760014)
		(width 0.14478)
		(layer "In6.Cu")
		(net "M_K_CPU0_SA_DQ<30>")
	)
	(segment
		(start 437.805576 -231.596946)
		(end 437.805576 -231.532938)
		(width 0.14478)
		(layer "In6.Cu")
		(net "M_K_CPU0_SA_DQ<30>")
	)
	(segment
		(start 420.974774 -232.447084)
		(end 421.137842 -232.610152)
		(width 0.14478)
		(layer "In6.Cu")
		(net "M_K_CPU0_SA_DQ<30>")
	)
	(segment
		(start 416.9664 -231.904794)
		(end 416.9664 -231.995472)
		(width 0.14478)
		(layer "In6.Cu")
		(net "M_K_CPU0_SA_DQ<30>")
	)
	(segment
		(start 423.340276 -231.615234)
		(end 423.485056 -231.760014)
		(width 0.14478)
		(layer "In6.Cu")
		(net "M_K_CPU0_SA_DQ<30>")
	)
	(segment
		(start 432.180492 -231.370632)
		(end 432.442366 -231.370632)
		(width 0.14478)
		(layer "In6.Cu")
		(net "M_K_CPU0_SA_DQ<30>")
	)
	(segment
		(start 390.264904 -243.674138)
		(end 390.418828 -243.408708)
		(width 0.0889)
		(layer "In6.Cu")
		(net "M_K_CPU0_SA_DQ<30>")
	)
	(segment
		(start 440.95289 -231.981502)
		(end 441.115958 -232.14457)
		(width 0.14478)
		(layer "In6.Cu")
		(net "M_K_CPU0_SA_DQ<30>")
	)
	(segment
		(start 430.830736 -231.36987)
		(end 430.993804 -231.532938)
		(width 0.14478)
		(layer "In6.Cu")
		(net "M_K_CPU0_SA_DQ<30>")
	)
	(segment
		(start 418.698172 -232.610152)
		(end 420.255192 -232.610152)
		(width 0.14478)
		(layer "In6.Cu")
		(net "M_K_CPU0_SA_DQ<30>")
	)
	(segment
		(start 430.600358 -231.36987)
		(end 430.830736 -231.36987)
		(width 0.14478)
		(layer "In6.Cu")
		(net "M_K_CPU0_SA_DQ<30>")
	)
	(segment
		(start 436.164736 -232.447084)
		(end 436.327804 -232.610152)
		(width 0.14478)
		(layer "In6.Cu")
		(net "M_K_CPU0_SA_DQ<30>")
	)
	(segment
		(start 437.968644 -231.36987)
		(end 438.199022 -231.36987)
		(width 0.14478)
		(layer "In6.Cu")
		(net "M_K_CPU0_SA_DQ<30>")
	)
	(segment
		(start 436.6133 -232.610152)
		(end 437.463438 -231.760014)
		(width 0.14478)
		(layer "In6.Cu")
		(net "M_K_CPU0_SA_DQ<30>")
	)
	(segment
		(start 432.442366 -231.370632)
		(end 432.587146 -231.515412)
		(width 0.14478)
		(layer "In6.Cu")
		(net "M_K_CPU0_SA_DQ<30>")
	)
	(segment
		(start 422.644062 -231.760014)
		(end 422.788842 -231.615234)
		(width 0.14478)
		(layer "In6.Cu")
		(net "M_K_CPU0_SA_DQ<30>")
	)
	(segment
		(start 420.974774 -232.386378)
		(end 420.974774 -232.447084)
		(width 0.14478)
		(layer "In6.Cu")
		(net "M_K_CPU0_SA_DQ<30>")
	)
	(segment
		(start 413.39897 -232.399078)
		(end 413.39897 -232.447084)
		(width 0.14478)
		(layer "In6.Cu")
		(net "M_K_CPU0_SA_DQ<30>")
	)
	(segment
		(start 392.331448 -243.351558)
		(end 392.341862 -243.357654)
		(width 0.0889)
		(layer "In6.Cu")
		(net "M_K_CPU0_SA_DQ<30>")
	)
	(segment
		(start 423.195496 -231.370632)
		(end 423.340276 -231.515412)
		(width 0.14478)
		(layer "In6.Cu")
		(net "M_K_CPU0_SA_DQ<30>")
	)
	(segment
		(start 439.839862 -231.981502)
		(end 440.00293 -232.14457)
		(width 0.14478)
		(layer "In6.Cu")
		(net "M_K_CPU0_SA_DQ<30>")
	)
	(segment
		(start 430.993804 -231.532938)
		(end 430.993804 -231.596946)
		(width 0.14478)
		(layer "In6.Cu")
		(net "M_K_CPU0_SA_DQ<30>")
	)
	(segment
		(start 441.509404 -231.981502)
		(end 441.509404 -231.923082)
		(width 0.14478)
		(layer "In6.Cu")
		(net "M_K_CPU0_SA_DQ<30>")
	)
	(segment
		(start 435.608222 -232.399078)
		(end 435.77129 -232.23601)
		(width 0.14478)
		(layer "In6.Cu")
		(net "M_K_CPU0_SA_DQ<30>")
	)
	(segment
		(start 412.679388 -232.610152)
		(end 412.842456 -232.447084)
		(width 0.14478)
		(layer "In6.Cu")
		(net "M_K_CPU0_SA_DQ<30>")
	)
	(segment
		(start 415.743136 -231.995472)
		(end 415.743136 -231.904794)
		(width 0.14478)
		(layer "In6.Cu")
		(net "M_K_CPU0_SA_DQ<30>")
	)
	(segment
		(start 422.788842 -231.515412)
		(end 422.933622 -231.370632)
		(width 0.14478)
		(layer "In6.Cu")
		(net "M_K_CPU0_SA_DQ<30>")
	)
	(segment
		(start 415.743136 -231.904794)
		(end 415.887916 -231.760014)
		(width 0.14478)
		(layer "In6.Cu")
		(net "M_K_CPU0_SA_DQ<30>")
	)
	(segment
		(start 440.559444 -231.375458)
		(end 440.789822 -231.375458)
		(width 0.14478)
		(layer "In6.Cu")
		(net "M_K_CPU0_SA_DQ<30>")
	)
	(segment
		(start 395.886686 -242.53063)
		(end 403.279864 -242.53063)
		(width 0.14478)
		(layer "In6.Cu")
		(net "M_K_CPU0_SA_DQ<30>")
	)
	(segment
		(start 430.43729 -231.596946)
		(end 430.43729 -231.532938)
		(width 0.14478)
		(layer "In6.Cu")
		(net "M_K_CPU0_SA_DQ<30>")
	)
	(segment
		(start 424.670474 -231.383332)
		(end 424.932348 -231.383332)
		(width 0.14478)
		(layer "In6.Cu")
		(net "M_K_CPU0_SA_DQ<30>")
	)
	(segment
		(start 415.336482 -232.140252)
		(end 415.598356 -232.140252)
		(width 0.14478)
		(layer "In6.Cu")
		(net "M_K_CPU0_SA_DQ<30>")
	)
	(segment
		(start 394.396976 -242.76939)
		(end 395.298676 -242.76939)
		(width 0.0889)
		(layer "In6.Cu")
		(net "M_K_CPU0_SA_DQ<30>")
	)
	(segment
		(start 393.865354 -243.301012)
		(end 394.396976 -242.76939)
		(width 0.0889)
		(layer "In6.Cu")
		(net "M_K_CPU0_SA_DQ<30>")
	)
	(segment
		(start 417.11118 -232.140252)
		(end 417.373054 -232.140252)
		(width 0.14478)
		(layer "In6.Cu")
		(net "M_K_CPU0_SA_DQ<30>")
	)
	(segment
		(start 441.672472 -231.760014)
		(end 442.119258 -231.760014)
		(width 0.14478)
		(layer "In6.Cu")
		(net "M_K_CPU0_SA_DQ<30>")
	)
	(segment
		(start 413.562038 -232.610152)
		(end 414.006792 -232.610152)
		(width 0.14478)
		(layer "In6.Cu")
		(net "M_K_CPU0_SA_DQ<30>")
	)
	(segment
		(start 420.581328 -232.22331)
		(end 420.811706 -232.22331)
		(width 0.14478)
		(layer "In6.Cu")
		(net "M_K_CPU0_SA_DQ<30>")
	)
	(segment
		(start 424.380914 -231.760014)
		(end 424.525694 -231.615234)
		(width 0.14478)
		(layer "In6.Cu")
		(net "M_K_CPU0_SA_DQ<30>")
	)
	(segment
		(start 412.150052 -232.610152)
		(end 412.679388 -232.610152)
		(width 0.14478)
		(layer "In6.Cu")
		(net "M_K_CPU0_SA_DQ<30>")
	)
	(segment
		(start 420.41826 -232.386378)
		(end 420.581328 -232.22331)
		(width 0.14478)
		(layer "In6.Cu")
		(net "M_K_CPU0_SA_DQ<30>")
	)
	(segment
		(start 440.00293 -232.14457)
		(end 440.233308 -232.14457)
		(width 0.14478)
		(layer "In6.Cu")
		(net "M_K_CPU0_SA_DQ<30>")
	)
	(segment
		(start 432.035712 -231.615234)
		(end 432.035712 -231.515412)
		(width 0.14478)
		(layer "In6.Cu")
		(net "M_K_CPU0_SA_DQ<30>")
	)
	(segment
		(start 435.77129 -232.23601)
		(end 436.001668 -232.23601)
		(width 0.14478)
		(layer "In6.Cu")
		(net "M_K_CPU0_SA_DQ<30>")
	)
	(segment
		(start 393.084812 -243.301012)
		(end 393.865354 -243.301012)
		(width 0.0889)
		(layer "In6.Cu")
		(net "M_K_CPU0_SA_DQ<30>")
	)
	(segment
		(start 428.856394 -232.610152)
		(end 429.08093 -232.610152)
		(width 0.14478)
		(layer "In6.Cu")
		(net "M_K_CPU0_SA_DQ<30>")
	)
	(segment
		(start 430.43729 -231.532938)
		(end 430.600358 -231.36987)
		(width 0.14478)
		(layer "In6.Cu")
		(net "M_K_CPU0_SA_DQ<30>")
	)
	(segment
		(start 417.517834 -231.904794)
		(end 417.662614 -231.760014)
		(width 0.14478)
		(layer "In6.Cu")
		(net "M_K_CPU0_SA_DQ<30>")
	)
	(segment
		(start 413.005524 -232.23601)
		(end 413.235902 -232.23601)
		(width 0.14478)
		(layer "In6.Cu")
		(net "M_K_CPU0_SA_DQ<30>")
	)
	(segment
		(start 420.41826 -232.447084)
		(end 420.41826 -232.386378)
		(width 0.14478)
		(layer "In6.Cu")
		(net "M_K_CPU0_SA_DQ<30>")
	)
	(segment
		(start 413.235902 -232.23601)
		(end 413.39897 -232.399078)
		(width 0.14478)
		(layer "In6.Cu")
		(net "M_K_CPU0_SA_DQ<30>")
	)
	(segment
		(start 420.811706 -232.22331)
		(end 420.974774 -232.386378)
		(width 0.14478)
		(layer "In6.Cu")
		(net "M_K_CPU0_SA_DQ<30>")
	)
	(segment
		(start 425.221908 -231.760014)
		(end 425.392088 -231.760014)
		(width 0.14478)
		(layer "In6.Cu")
		(net "M_K_CPU0_SA_DQ<30>")
	)
	(segment
		(start 416.9664 -231.995472)
		(end 417.11118 -232.140252)
		(width 0.14478)
		(layer "In6.Cu")
		(net "M_K_CPU0_SA_DQ<30>")
	)
	(segment
		(start 412.842456 -232.399078)
		(end 413.005524 -232.23601)
		(width 0.14478)
		(layer "In6.Cu")
		(net "M_K_CPU0_SA_DQ<30>")
	)
	(segment
		(start 440.396376 -231.981502)
		(end 440.396376 -231.538526)
		(width 0.14478)
		(layer "In6.Cu")
		(net "M_K_CPU0_SA_DQ<30>")
	)
	(segment
		(start 428.16018 -232.376472)
		(end 428.30496 -232.231692)
		(width 0.14478)
		(layer "In6.Cu")
		(net "M_K_CPU0_SA_DQ<30>")
	)
	(segment
		(start 422.39946 -231.760014)
		(end 422.644062 -231.760014)
		(width 0.14478)
		(layer "In6.Cu")
		(net "M_K_CPU0_SA_DQ<30>")
	)
	(segment
		(start 437.463438 -231.760014)
		(end 437.642508 -231.760014)
		(width 0.14478)
		(layer "In6.Cu")
		(net "M_K_CPU0_SA_DQ<30>")
	)
	(segment
		(start 422.788842 -231.615234)
		(end 422.788842 -231.515412)
		(width 0.14478)
		(layer "In6.Cu")
		(net "M_K_CPU0_SA_DQ<30>")
	)
	(segment
		(start 425.077128 -231.528112)
		(end 425.077128 -231.615234)
		(width 0.14478)
		(layer "In6.Cu")
		(net "M_K_CPU0_SA_DQ<30>")
	)
	(segment
		(start 409.511754 -235.24845)
		(end 412.150052 -232.610152)
		(width 0.14478)
		(layer "In6.Cu")
		(net "M_K_CPU0_SA_DQ<30>")
	)
	(segment
		(start 415.046922 -231.760014)
		(end 415.191702 -231.904794)
		(width 0.14478)
		(layer "In6.Cu")
		(net "M_K_CPU0_SA_DQ<30>")
	)
	(segment
		(start 437.805576 -231.532938)
		(end 437.968644 -231.36987)
		(width 0.14478)
		(layer "In6.Cu")
		(net "M_K_CPU0_SA_DQ<30>")
	)
	(segment
		(start 425.077128 -231.615234)
		(end 425.221908 -231.760014)
		(width 0.14478)
		(layer "In6.Cu")
		(net "M_K_CPU0_SA_DQ<30>")
	)
	(arc
		(start 392.897614 -243.351558)
		(mid 392.987874 -243.31393)
		(end 393.084812 -243.301012)
		(width 0.0889)
		(layer "In6.Cu")
		(net "M_K_CPU0_SA_DQ<30>")
	)
	(arc
		(start 391.026142 -243.346732)
		(mid 391.20965 -243.301238)
		(end 391.391902 -243.351558)
		(width 0.0889)
		(layer "In6.Cu")
		(net "M_K_CPU0_SA_DQ<30>")
	)
	(arc
		(start 391.391902 -243.351558)
		(mid 391.668715 -243.427701)
		(end 391.947146 -243.357654)
		(width 0.0889)
		(layer "In6.Cu")
		(net "M_K_CPU0_SA_DQ<30>")
	)
	(arc
		(start 391.95756 -243.351558)
		(mid 392.144504 -243.301303)
		(end 392.331448 -243.351558)
		(width 0.0889)
		(layer "In6.Cu")
		(net "M_K_CPU0_SA_DQ<30>")
	)
	(arc
		(start 390.51484 -243.383308)
		(mid 390.770048 -243.426785)
		(end 391.01776 -243.351558)
		(width 0.0889)
		(layer "In6.Cu")
		(net "M_K_CPU0_SA_DQ<30>")
	)
	(arc
		(start 392.341862 -243.357654)
		(mid 392.620548 -243.427874)
		(end 392.897614 -243.351558)
		(width 0.0889)
		(layer "In6.Cu")
		(net "M_K_CPU0_SA_DQ<30>")
	)
	(segment
		(start 389.798052 -226.120198)
		(end 390.264904 -225.85426)
		(width 0.10668)
		(layer "F.Cu")
		(net "M_K_CPU0_SA_DQ<2>")
	)
	(segment
		(start 433.786026 -198.61022)
		(end 435.384194 -198.61022)
		(width 0.14478)
		(layer "In6.Cu")
		(net "M_K_CPU0_SA_DQ<2>")
	)
	(segment
		(start 391.45718 -223.119442)
		(end 391.48766 -223.101662)
		(width 0.0889)
		(layer "In6.Cu")
		(net "M_K_CPU0_SA_DQ<2>")
	)
	(segment
		(start 416.394646 -197.37705)
		(end 416.625024 -197.37705)
		(width 0.14478)
		(layer "In6.Cu")
		(net "M_K_CPU0_SA_DQ<2>")
	)
	(segment
		(start 421.303958 -198.61022)
		(end 421.549322 -198.61022)
		(width 0.14478)
		(layer "In6.Cu")
		(net "M_K_CPU0_SA_DQ<2>")
	)
	(segment
		(start 436.103776 -198.447152)
		(end 436.266844 -198.61022)
		(width 0.14478)
		(layer "In6.Cu")
		(net "M_K_CPU0_SA_DQ<2>")
	)
	(segment
		(start 390.264904 -225.85426)
		(end 390.418828 -225.58883)
		(width 0.0889)
		(layer "In6.Cu")
		(net "M_K_CPU0_SA_DQ<2>")
	)
	(segment
		(start 416.788092 -197.540118)
		(end 416.788092 -197.597014)
		(width 0.14478)
		(layer "In6.Cu")
		(net "M_K_CPU0_SA_DQ<2>")
	)
	(segment
		(start 420.584376 -198.383398)
		(end 420.747444 -198.22033)
		(width 0.14478)
		(layer "In6.Cu")
		(net "M_K_CPU0_SA_DQ<2>")
	)
	(segment
		(start 420.421308 -198.61022)
		(end 420.584376 -198.447152)
		(width 0.14478)
		(layer "In6.Cu")
		(net "M_K_CPU0_SA_DQ<2>")
	)
	(segment
		(start 431.059336 -197.535038)
		(end 431.059336 -197.597014)
		(width 0.14478)
		(layer "In6.Cu")
		(net "M_K_CPU0_SA_DQ<2>")
	)
	(segment
		(start 428.05985 -198.388478)
		(end 428.222918 -198.22541)
		(width 0.14478)
		(layer "In6.Cu")
		(net "M_K_CPU0_SA_DQ<2>")
	)
	(segment
		(start 441.569856 -197.991222)
		(end 441.569856 -197.92315)
		(width 0.14478)
		(layer "In6.Cu")
		(net "M_K_CPU0_SA_DQ<2>")
	)
	(segment
		(start 391.48766 -223.101662)
		(end 391.526776 -223.078802)
		(width 0.0889)
		(layer "In6.Cu")
		(net "M_K_CPU0_SA_DQ<2>")
	)
	(segment
		(start 440.29376 -198.15429)
		(end 440.456828 -197.991222)
		(width 0.14478)
		(layer "In6.Cu")
		(net "M_K_CPU0_SA_DQ<2>")
	)
	(segment
		(start 429.08093 -198.61022)
		(end 429.931068 -197.760082)
		(width 0.14478)
		(layer "In6.Cu")
		(net "M_K_CPU0_SA_DQ<2>")
	)
	(segment
		(start 435.547262 -198.383398)
		(end 435.71033 -198.22033)
		(width 0.14478)
		(layer "In6.Cu")
		(net "M_K_CPU0_SA_DQ<2>")
	)
	(segment
		(start 411.57271 -198.61022)
		(end 414.006792 -198.61022)
		(width 0.14478)
		(layer "In6.Cu")
		(net "M_K_CPU0_SA_DQ<2>")
	)
	(segment
		(start 441.013342 -197.528942)
		(end 441.013342 -197.991222)
		(width 0.14478)
		(layer "In6.Cu")
		(net "M_K_CPU0_SA_DQ<2>")
	)
	(segment
		(start 436.266844 -198.61022)
		(end 436.6133 -198.61022)
		(width 0.14478)
		(layer "In6.Cu")
		(net "M_K_CPU0_SA_DQ<2>")
	)
	(segment
		(start 440.850274 -197.365874)
		(end 441.013342 -197.528942)
		(width 0.14478)
		(layer "In6.Cu")
		(net "M_K_CPU0_SA_DQ<2>")
	)
	(segment
		(start 430.66589 -197.37197)
		(end 430.896268 -197.37197)
		(width 0.14478)
		(layer "In6.Cu")
		(net "M_K_CPU0_SA_DQ<2>")
	)
	(segment
		(start 392.240008 -221.80423)
		(end 392.240008 -221.64294)
		(width 0.0889)
		(layer "In6.Cu")
		(net "M_K_CPU0_SA_DQ<2>")
	)
	(segment
		(start 414.006792 -198.61022)
		(end 414.85693 -197.760082)
		(width 0.14478)
		(layer "In6.Cu")
		(net "M_K_CPU0_SA_DQ<2>")
	)
	(segment
		(start 438.60593 -197.983602)
		(end 438.60593 -197.92315)
		(width 0.14478)
		(layer "In6.Cu")
		(net "M_K_CPU0_SA_DQ<2>")
	)
	(segment
		(start 395.359636 -214.823294)
		(end 411.57271 -198.61022)
		(width 0.14478)
		(layer "In6.Cu")
		(net "M_K_CPU0_SA_DQ<2>")
	)
	(segment
		(start 441.013342 -197.991222)
		(end 441.17641 -198.15429)
		(width 0.14478)
		(layer "In6.Cu")
		(net "M_K_CPU0_SA_DQ<2>")
	)
	(segment
		(start 420.747444 -198.22033)
		(end 420.977822 -198.22033)
		(width 0.14478)
		(layer "In6.Cu")
		(net "M_K_CPU0_SA_DQ<2>")
	)
	(segment
		(start 436.103776 -198.383398)
		(end 436.103776 -198.447152)
		(width 0.14478)
		(layer "In6.Cu")
		(net "M_K_CPU0_SA_DQ<2>")
	)
	(segment
		(start 430.502822 -197.597014)
		(end 430.502822 -197.535038)
		(width 0.14478)
		(layer "In6.Cu")
		(net "M_K_CPU0_SA_DQ<2>")
	)
	(segment
		(start 416.788092 -197.597014)
		(end 416.95116 -197.760082)
		(width 0.14478)
		(layer "In6.Cu")
		(net "M_K_CPU0_SA_DQ<2>")
	)
	(segment
		(start 438.049416 -197.92315)
		(end 438.049416 -197.983602)
		(width 0.14478)
		(layer "In6.Cu")
		(net "M_K_CPU0_SA_DQ<2>")
	)
	(segment
		(start 425.392088 -197.760082)
		(end 426.242226 -198.61022)
		(width 0.14478)
		(layer "In6.Cu")
		(net "M_K_CPU0_SA_DQ<2>")
	)
	(segment
		(start 417.848034 -197.760082)
		(end 418.698172 -198.61022)
		(width 0.14478)
		(layer "In6.Cu")
		(net "M_K_CPU0_SA_DQ<2>")
	)
	(segment
		(start 440.456828 -197.528942)
		(end 440.619896 -197.365874)
		(width 0.14478)
		(layer "In6.Cu")
		(net "M_K_CPU0_SA_DQ<2>")
	)
	(segment
		(start 437.886348 -197.760082)
		(end 438.049416 -197.92315)
		(width 0.14478)
		(layer "In6.Cu")
		(net "M_K_CPU0_SA_DQ<2>")
	)
	(segment
		(start 439.900314 -197.92315)
		(end 439.900314 -197.991222)
		(width 0.14478)
		(layer "In6.Cu")
		(net "M_K_CPU0_SA_DQ<2>")
	)
	(segment
		(start 414.85693 -197.760082)
		(end 416.06851 -197.760082)
		(width 0.14478)
		(layer "In6.Cu")
		(net "M_K_CPU0_SA_DQ<2>")
	)
	(segment
		(start 422.884092 -197.540118)
		(end 423.04716 -197.37705)
		(width 0.14478)
		(layer "In6.Cu")
		(net "M_K_CPU0_SA_DQ<2>")
	)
	(segment
		(start 438.768998 -197.760082)
		(end 439.737246 -197.760082)
		(width 0.14478)
		(layer "In6.Cu")
		(net "M_K_CPU0_SA_DQ<2>")
	)
	(segment
		(start 428.779432 -198.61022)
		(end 429.08093 -198.61022)
		(width 0.14478)
		(layer "In6.Cu")
		(net "M_K_CPU0_SA_DQ<2>")
	)
	(segment
		(start 428.616364 -198.388478)
		(end 428.616364 -198.447152)
		(width 0.14478)
		(layer "In6.Cu")
		(net "M_K_CPU0_SA_DQ<2>")
	)
	(segment
		(start 441.732924 -197.760082)
		(end 442.119258 -197.760082)
		(width 0.14478)
		(layer "In6.Cu")
		(net "M_K_CPU0_SA_DQ<2>")
	)
	(segment
		(start 390.418828 -225.58883)
		(end 390.51484 -225.56343)
		(width 0.0889)
		(layer "In6.Cu")
		(net "M_K_CPU0_SA_DQ<2>")
	)
	(segment
		(start 420.977822 -198.22033)
		(end 421.14089 -198.383398)
		(width 0.14478)
		(layer "In6.Cu")
		(net "M_K_CPU0_SA_DQ<2>")
	)
	(segment
		(start 422.721024 -197.760082)
		(end 422.884092 -197.597014)
		(width 0.14478)
		(layer "In6.Cu")
		(net "M_K_CPU0_SA_DQ<2>")
	)
	(segment
		(start 416.231578 -197.540118)
		(end 416.394646 -197.37705)
		(width 0.14478)
		(layer "In6.Cu")
		(net "M_K_CPU0_SA_DQ<2>")
	)
	(segment
		(start 437.463438 -197.760082)
		(end 437.886348 -197.760082)
		(width 0.14478)
		(layer "In6.Cu")
		(net "M_K_CPU0_SA_DQ<2>")
	)
	(segment
		(start 423.440606 -197.540118)
		(end 423.440606 -197.597014)
		(width 0.14478)
		(layer "In6.Cu")
		(net "M_K_CPU0_SA_DQ<2>")
	)
	(segment
		(start 430.502822 -197.535038)
		(end 430.66589 -197.37197)
		(width 0.14478)
		(layer "In6.Cu")
		(net "M_K_CPU0_SA_DQ<2>")
	)
	(segment
		(start 435.940708 -198.22033)
		(end 436.103776 -198.383398)
		(width 0.14478)
		(layer "In6.Cu")
		(net "M_K_CPU0_SA_DQ<2>")
	)
	(segment
		(start 416.231578 -197.597014)
		(end 416.231578 -197.540118)
		(width 0.14478)
		(layer "In6.Cu")
		(net "M_K_CPU0_SA_DQ<2>")
	)
	(segment
		(start 423.603674 -197.760082)
		(end 425.392088 -197.760082)
		(width 0.14478)
		(layer "In6.Cu")
		(net "M_K_CPU0_SA_DQ<2>")
	)
	(segment
		(start 435.547262 -198.447152)
		(end 435.547262 -198.383398)
		(width 0.14478)
		(layer "In6.Cu")
		(net "M_K_CPU0_SA_DQ<2>")
	)
	(segment
		(start 391.01776 -223.911668)
		(end 391.056876 -223.888808)
		(width 0.0889)
		(layer "In6.Cu")
		(net "M_K_CPU0_SA_DQ<2>")
	)
	(segment
		(start 422.884092 -197.597014)
		(end 422.884092 -197.540118)
		(width 0.14478)
		(layer "In6.Cu")
		(net "M_K_CPU0_SA_DQ<2>")
	)
	(segment
		(start 395.359636 -218.16695)
		(end 395.359636 -214.823294)
		(width 0.14478)
		(layer "In6.Cu")
		(net "M_K_CPU0_SA_DQ<2>")
	)
	(segment
		(start 430.896268 -197.37197)
		(end 431.059336 -197.535038)
		(width 0.14478)
		(layer "In6.Cu")
		(net "M_K_CPU0_SA_DQ<2>")
	)
	(segment
		(start 428.05985 -198.447152)
		(end 428.05985 -198.388478)
		(width 0.14478)
		(layer "In6.Cu")
		(net "M_K_CPU0_SA_DQ<2>")
	)
	(segment
		(start 391.01776 -225.53168)
		(end 391.056876 -225.50882)
		(width 0.0889)
		(layer "In6.Cu")
		(net "M_K_CPU0_SA_DQ<2>")
	)
	(segment
		(start 392.446256 -221.25813)
		(end 392.446256 -221.08033)
		(width 0.14478)
		(layer "In6.Cu")
		(net "M_K_CPU0_SA_DQ<2>")
	)
	(segment
		(start 441.569856 -197.92315)
		(end 441.732924 -197.760082)
		(width 0.14478)
		(layer "In6.Cu")
		(net "M_K_CPU0_SA_DQ<2>")
	)
	(segment
		(start 430.339754 -197.760082)
		(end 430.502822 -197.597014)
		(width 0.14478)
		(layer "In6.Cu")
		(net "M_K_CPU0_SA_DQ<2>")
	)
	(segment
		(start 438.442862 -198.14667)
		(end 438.60593 -197.983602)
		(width 0.14478)
		(layer "In6.Cu")
		(net "M_K_CPU0_SA_DQ<2>")
	)
	(segment
		(start 428.222918 -198.22541)
		(end 428.453296 -198.22541)
		(width 0.14478)
		(layer "In6.Cu")
		(net "M_K_CPU0_SA_DQ<2>")
	)
	(segment
		(start 436.6133 -198.61022)
		(end 437.463438 -197.760082)
		(width 0.14478)
		(layer "In6.Cu")
		(net "M_K_CPU0_SA_DQ<2>")
	)
	(segment
		(start 439.737246 -197.760082)
		(end 439.900314 -197.92315)
		(width 0.14478)
		(layer "In6.Cu")
		(net "M_K_CPU0_SA_DQ<2>")
	)
	(segment
		(start 438.049416 -197.983602)
		(end 438.212484 -198.14667)
		(width 0.14478)
		(layer "In6.Cu")
		(net "M_K_CPU0_SA_DQ<2>")
	)
	(segment
		(start 420.584376 -198.447152)
		(end 420.584376 -198.383398)
		(width 0.14478)
		(layer "In6.Cu")
		(net "M_K_CPU0_SA_DQ<2>")
	)
	(segment
		(start 431.059336 -197.597014)
		(end 431.222404 -197.760082)
		(width 0.14478)
		(layer "In6.Cu")
		(net "M_K_CPU0_SA_DQ<2>")
	)
	(segment
		(start 428.616364 -198.447152)
		(end 428.779432 -198.61022)
		(width 0.14478)
		(layer "In6.Cu")
		(net "M_K_CPU0_SA_DQ<2>")
	)
	(segment
		(start 423.04716 -197.37705)
		(end 423.277538 -197.37705)
		(width 0.14478)
		(layer "In6.Cu")
		(net "M_K_CPU0_SA_DQ<2>")
	)
	(segment
		(start 391.01776 -224.556828)
		(end 390.98601 -224.53854)
		(width 0.0889)
		(layer "In6.Cu")
		(net "M_K_CPU0_SA_DQ<2>")
	)
	(segment
		(start 431.222404 -197.760082)
		(end 432.935888 -197.760082)
		(width 0.14478)
		(layer "In6.Cu")
		(net "M_K_CPU0_SA_DQ<2>")
	)
	(segment
		(start 432.935888 -197.760082)
		(end 433.786026 -198.61022)
		(width 0.14478)
		(layer "In6.Cu")
		(net "M_K_CPU0_SA_DQ<2>")
	)
	(segment
		(start 421.549322 -198.61022)
		(end 422.39946 -197.760082)
		(width 0.14478)
		(layer "In6.Cu")
		(net "M_K_CPU0_SA_DQ<2>")
	)
	(segment
		(start 438.212484 -198.14667)
		(end 438.442862 -198.14667)
		(width 0.14478)
		(layer "In6.Cu")
		(net "M_K_CPU0_SA_DQ<2>")
	)
	(segment
		(start 416.625024 -197.37705)
		(end 416.788092 -197.540118)
		(width 0.14478)
		(layer "In6.Cu")
		(net "M_K_CPU0_SA_DQ<2>")
	)
	(segment
		(start 440.063382 -198.15429)
		(end 440.29376 -198.15429)
		(width 0.14478)
		(layer "In6.Cu")
		(net "M_K_CPU0_SA_DQ<2>")
	)
	(segment
		(start 391.92708 -222.309436)
		(end 391.95756 -222.291656)
		(width 0.0889)
		(layer "In6.Cu")
		(net "M_K_CPU0_SA_DQ<2>")
	)
	(segment
		(start 438.60593 -197.92315)
		(end 438.768998 -197.760082)
		(width 0.14478)
		(layer "In6.Cu")
		(net "M_K_CPU0_SA_DQ<2>")
	)
	(segment
		(start 440.619896 -197.365874)
		(end 440.850274 -197.365874)
		(width 0.14478)
		(layer "In6.Cu")
		(net "M_K_CPU0_SA_DQ<2>")
	)
	(segment
		(start 442.119258 -197.760082)
		(end 442.5442 -198.185024)
		(width 0.14478)
		(layer "In6.Cu")
		(net "M_K_CPU0_SA_DQ<2>")
	)
	(segment
		(start 392.240008 -221.64294)
		(end 392.446256 -221.436692)
		(width 0.0889)
		(layer "In6.Cu")
		(net "M_K_CPU0_SA_DQ<2>")
	)
	(segment
		(start 423.277538 -197.37705)
		(end 423.440606 -197.540118)
		(width 0.14478)
		(layer "In6.Cu")
		(net "M_K_CPU0_SA_DQ<2>")
	)
	(segment
		(start 392.446256 -221.436692)
		(end 392.446256 -221.25813)
		(width 0.0889)
		(layer "In6.Cu")
		(net "M_K_CPU0_SA_DQ<2>")
	)
	(segment
		(start 421.14089 -198.447152)
		(end 421.303958 -198.61022)
		(width 0.14478)
		(layer "In6.Cu")
		(net "M_K_CPU0_SA_DQ<2>")
	)
	(segment
		(start 391.056876 -224.579688)
		(end 391.01776 -224.556828)
		(width 0.0889)
		(layer "In6.Cu")
		(net "M_K_CPU0_SA_DQ<2>")
	)
	(segment
		(start 422.39946 -197.760082)
		(end 422.721024 -197.760082)
		(width 0.14478)
		(layer "In6.Cu")
		(net "M_K_CPU0_SA_DQ<2>")
	)
	(segment
		(start 421.14089 -198.383398)
		(end 421.14089 -198.447152)
		(width 0.14478)
		(layer "In6.Cu")
		(net "M_K_CPU0_SA_DQ<2>")
	)
	(segment
		(start 416.06851 -197.760082)
		(end 416.231578 -197.597014)
		(width 0.14478)
		(layer "In6.Cu")
		(net "M_K_CPU0_SA_DQ<2>")
	)
	(segment
		(start 416.95116 -197.760082)
		(end 417.848034 -197.760082)
		(width 0.14478)
		(layer "In6.Cu")
		(net "M_K_CPU0_SA_DQ<2>")
	)
	(segment
		(start 429.931068 -197.760082)
		(end 430.339754 -197.760082)
		(width 0.14478)
		(layer "In6.Cu")
		(net "M_K_CPU0_SA_DQ<2>")
	)
	(segment
		(start 423.440606 -197.597014)
		(end 423.603674 -197.760082)
		(width 0.14478)
		(layer "In6.Cu")
		(net "M_K_CPU0_SA_DQ<2>")
	)
	(segment
		(start 440.456828 -197.991222)
		(end 440.456828 -197.528942)
		(width 0.14478)
		(layer "In6.Cu")
		(net "M_K_CPU0_SA_DQ<2>")
	)
	(segment
		(start 439.900314 -197.991222)
		(end 440.063382 -198.15429)
		(width 0.14478)
		(layer "In6.Cu")
		(net "M_K_CPU0_SA_DQ<2>")
	)
	(segment
		(start 426.242226 -198.61022)
		(end 427.896782 -198.61022)
		(width 0.14478)
		(layer "In6.Cu")
		(net "M_K_CPU0_SA_DQ<2>")
	)
	(segment
		(start 435.71033 -198.22033)
		(end 435.940708 -198.22033)
		(width 0.14478)
		(layer "In6.Cu")
		(net "M_K_CPU0_SA_DQ<2>")
	)
	(segment
		(start 390.98601 -223.929956)
		(end 391.01776 -223.911668)
		(width 0.0889)
		(layer "In6.Cu")
		(net "M_K_CPU0_SA_DQ<2>")
	)
	(segment
		(start 391.95756 -222.291656)
		(end 391.996676 -222.268796)
		(width 0.0889)
		(layer "In6.Cu")
		(net "M_K_CPU0_SA_DQ<2>")
	)
	(segment
		(start 418.698172 -198.61022)
		(end 420.421308 -198.61022)
		(width 0.14478)
		(layer "In6.Cu")
		(net "M_K_CPU0_SA_DQ<2>")
	)
	(segment
		(start 441.406788 -198.15429)
		(end 441.569856 -197.991222)
		(width 0.14478)
		(layer "In6.Cu")
		(net "M_K_CPU0_SA_DQ<2>")
	)
	(segment
		(start 441.17641 -198.15429)
		(end 441.406788 -198.15429)
		(width 0.14478)
		(layer "In6.Cu")
		(net "M_K_CPU0_SA_DQ<2>")
	)
	(segment
		(start 428.453296 -198.22541)
		(end 428.616364 -198.388478)
		(width 0.14478)
		(layer "In6.Cu")
		(net "M_K_CPU0_SA_DQ<2>")
	)
	(segment
		(start 392.446256 -221.08033)
		(end 395.359636 -218.16695)
		(width 0.14478)
		(layer "In6.Cu")
		(net "M_K_CPU0_SA_DQ<2>")
	)
	(segment
		(start 435.384194 -198.61022)
		(end 435.547262 -198.447152)
		(width 0.14478)
		(layer "In6.Cu")
		(net "M_K_CPU0_SA_DQ<2>")
	)
	(segment
		(start 427.896782 -198.61022)
		(end 428.05985 -198.447152)
		(width 0.14478)
		(layer "In6.Cu")
		(net "M_K_CPU0_SA_DQ<2>")
	)
	(arc
		(start 391.770108 -222.614236)
		(mid 391.811657 -222.442814)
		(end 391.92708 -222.309436)
		(width 0.0889)
		(layer "In6.Cu")
		(net "M_K_CPU0_SA_DQ<2>")
	)
	(arc
		(start 391.300208 -223.424242)
		(mid 391.341757 -223.25282)
		(end 391.45718 -223.119442)
		(width 0.0889)
		(layer "In6.Cu")
		(net "M_K_CPU0_SA_DQ<2>")
	)
	(arc
		(start 391.526776 -223.078802)
		(mid 391.705589 -222.876452)
		(end 391.770108 -222.614236)
		(width 0.0889)
		(layer "In6.Cu")
		(net "M_K_CPU0_SA_DQ<2>")
	)
	(arc
		(start 391.056876 -225.50882)
		(mid 391.300203 -225.044254)
		(end 391.056876 -224.579688)
		(width 0.0889)
		(layer "In6.Cu")
		(net "M_K_CPU0_SA_DQ<2>")
	)
	(arc
		(start 390.98601 -224.53854)
		(mid 390.830082 -224.234248)
		(end 390.98601 -223.929956)
		(width 0.0889)
		(layer "In6.Cu")
		(net "M_K_CPU0_SA_DQ<2>")
	)
	(arc
		(start 391.056876 -223.888808)
		(mid 391.235689 -223.686458)
		(end 391.300208 -223.424242)
		(width 0.0889)
		(layer "In6.Cu")
		(net "M_K_CPU0_SA_DQ<2>")
	)
	(arc
		(start 391.996676 -222.268796)
		(mid 392.175489 -222.066446)
		(end 392.240008 -221.80423)
		(width 0.0889)
		(layer "In6.Cu")
		(net "M_K_CPU0_SA_DQ<2>")
	)
	(arc
		(start 390.51484 -225.56343)
		(mid 390.770048 -225.606907)
		(end 391.01776 -225.53168)
		(width 0.0889)
		(layer "In6.Cu")
		(net "M_K_CPU0_SA_DQ<2>")
	)
	(segment
		(start 388.857998 -243.940076)
		(end 389.32485 -243.674138)
		(width 0.10668)
		(layer "F.Cu")
		(net "M_K_CPU0_SA_DQ<29>")
	)
	(segment
		(start 391.947146 -243.990622)
		(end 391.95756 -243.996718)
		(width 0.0889)
		(layer "In6.Cu")
		(net "M_K_CPU0_SA_DQ<29>")
	)
	(segment
		(start 422.399206 -232.610152)
		(end 425.392342 -232.610152)
		(width 0.14478)
		(layer "In6.Cu")
		(net "M_K_CPU0_SA_DQ<29>")
	)
	(segment
		(start 437.5912 -232.610152)
		(end 443.993778 -232.610152)
		(width 0.14478)
		(layer "In6.Cu")
		(net "M_K_CPU0_SA_DQ<29>")
	)
	(segment
		(start 426.242226 -233.460036)
		(end 429.08093 -233.460036)
		(width 0.14478)
		(layer "In6.Cu")
		(net "M_K_CPU0_SA_DQ<29>")
	)
	(segment
		(start 389.32485 -243.674138)
		(end 389.170926 -243.939568)
		(width 0.0889)
		(layer "In6.Cu")
		(net "M_K_CPU0_SA_DQ<29>")
	)
	(segment
		(start 391.95756 -243.996718)
		(end 391.965942 -244.001544)
		(width 0.0889)
		(layer "In6.Cu")
		(net "M_K_CPU0_SA_DQ<29>")
	)
	(segment
		(start 432.936142 -232.610152)
		(end 433.786026 -233.460036)
		(width 0.14478)
		(layer "In6.Cu")
		(net "M_K_CPU0_SA_DQ<29>")
	)
	(segment
		(start 429.08093 -233.460036)
		(end 429.930814 -232.610152)
		(width 0.14478)
		(layer "In6.Cu")
		(net "M_K_CPU0_SA_DQ<29>")
	)
	(segment
		(start 446.219326 -232.610152)
		(end 446.644268 -233.035094)
		(width 0.14478)
		(layer "In6.Cu")
		(net "M_K_CPU0_SA_DQ<29>")
	)
	(segment
		(start 444.550292 -233.07675)
		(end 444.71336 -232.913682)
		(width 0.14478)
		(layer "In6.Cu")
		(net "M_K_CPU0_SA_DQ<29>")
	)
	(segment
		(start 410.001974 -235.578396)
		(end 412.120334 -233.460036)
		(width 0.14478)
		(layer "In6.Cu")
		(net "M_K_CPU0_SA_DQ<29>")
	)
	(segment
		(start 425.392342 -232.610152)
		(end 426.242226 -233.460036)
		(width 0.14478)
		(layer "In6.Cu")
		(net "M_K_CPU0_SA_DQ<29>")
	)
	(segment
		(start 444.71336 -232.913682)
		(end 444.71336 -232.77322)
		(width 0.14478)
		(layer "In6.Cu")
		(net "M_K_CPU0_SA_DQ<29>")
	)
	(segment
		(start 394.152374 -243.48567)
		(end 395.044676 -243.48567)
		(width 0.0889)
		(layer "In6.Cu")
		(net "M_K_CPU0_SA_DQ<29>")
	)
	(segment
		(start 395.886686 -242.98529)
		(end 403.468332 -242.98529)
		(width 0.14478)
		(layer "In6.Cu")
		(net "M_K_CPU0_SA_DQ<29>")
	)
	(segment
		(start 418.698172 -233.460036)
		(end 421.549322 -233.460036)
		(width 0.14478)
		(layer "In6.Cu")
		(net "M_K_CPU0_SA_DQ<29>")
	)
	(segment
		(start 444.319914 -233.07675)
		(end 444.550292 -233.07675)
		(width 0.14478)
		(layer "In6.Cu")
		(net "M_K_CPU0_SA_DQ<29>")
	)
	(segment
		(start 429.930814 -232.610152)
		(end 432.936142 -232.610152)
		(width 0.14478)
		(layer "In6.Cu")
		(net "M_K_CPU0_SA_DQ<29>")
	)
	(segment
		(start 414.896554 -232.609898)
		(end 417.848034 -232.609898)
		(width 0.14478)
		(layer "In6.Cu")
		(net "M_K_CPU0_SA_DQ<29>")
	)
	(segment
		(start 393.59078 -244.047264)
		(end 394.152374 -243.48567)
		(width 0.0889)
		(layer "In6.Cu")
		(net "M_K_CPU0_SA_DQ<29>")
	)
	(segment
		(start 443.993778 -232.610152)
		(end 444.156846 -232.77322)
		(width 0.14478)
		(layer "In6.Cu")
		(net "M_K_CPU0_SA_DQ<29>")
	)
	(segment
		(start 433.786026 -233.460036)
		(end 436.741316 -233.460036)
		(width 0.14478)
		(layer "In6.Cu")
		(net "M_K_CPU0_SA_DQ<29>")
	)
	(segment
		(start 395.545056 -242.98529)
		(end 395.886686 -242.98529)
		(width 0.0889)
		(layer "In6.Cu")
		(net "M_K_CPU0_SA_DQ<29>")
	)
	(segment
		(start 412.120334 -233.460036)
		(end 414.046416 -233.460036)
		(width 0.14478)
		(layer "In6.Cu")
		(net "M_K_CPU0_SA_DQ<29>")
	)
	(segment
		(start 410.001974 -236.451648)
		(end 410.001974 -235.578396)
		(width 0.14478)
		(layer "In6.Cu")
		(net "M_K_CPU0_SA_DQ<29>")
	)
	(segment
		(start 390.443466 -244.001544)
		(end 390.451848 -243.996718)
		(width 0.0889)
		(layer "In6.Cu")
		(net "M_K_CPU0_SA_DQ<29>")
	)
	(segment
		(start 421.549322 -233.460036)
		(end 422.399206 -232.610152)
		(width 0.14478)
		(layer "In6.Cu")
		(net "M_K_CPU0_SA_DQ<29>")
	)
	(segment
		(start 444.156846 -232.77322)
		(end 444.156846 -232.913682)
		(width 0.14478)
		(layer "In6.Cu")
		(net "M_K_CPU0_SA_DQ<29>")
	)
	(segment
		(start 444.156846 -232.913682)
		(end 444.319914 -233.07675)
		(width 0.14478)
		(layer "In6.Cu")
		(net "M_K_CPU0_SA_DQ<29>")
	)
	(segment
		(start 392.331194 -243.996718)
		(end 392.341608 -243.990622)
		(width 0.0889)
		(layer "In6.Cu")
		(net "M_K_CPU0_SA_DQ<29>")
	)
	(segment
		(start 389.170926 -243.939568)
		(end 389.193278 -244.02288)
		(width 0.0889)
		(layer "In6.Cu")
		(net "M_K_CPU0_SA_DQ<29>")
	)
	(segment
		(start 436.741316 -233.460036)
		(end 437.5912 -232.610152)
		(width 0.14478)
		(layer "In6.Cu")
		(net "M_K_CPU0_SA_DQ<29>")
	)
	(segment
		(start 395.044676 -243.48567)
		(end 395.545056 -242.98529)
		(width 0.0889)
		(layer "In6.Cu")
		(net "M_K_CPU0_SA_DQ<29>")
	)
	(segment
		(start 403.468332 -242.98529)
		(end 410.001974 -236.451648)
		(width 0.14478)
		(layer "In6.Cu")
		(net "M_K_CPU0_SA_DQ<29>")
	)
	(segment
		(start 444.71336 -232.77322)
		(end 444.876428 -232.610152)
		(width 0.14478)
		(layer "In6.Cu")
		(net "M_K_CPU0_SA_DQ<29>")
	)
	(segment
		(start 391.01776 -243.996718)
		(end 391.026142 -244.001544)
		(width 0.0889)
		(layer "In6.Cu")
		(net "M_K_CPU0_SA_DQ<29>")
	)
	(segment
		(start 414.046416 -233.460036)
		(end 414.896554 -232.609898)
		(width 0.14478)
		(layer "In6.Cu")
		(net "M_K_CPU0_SA_DQ<29>")
	)
	(segment
		(start 444.876428 -232.610152)
		(end 446.219326 -232.610152)
		(width 0.14478)
		(layer "In6.Cu")
		(net "M_K_CPU0_SA_DQ<29>")
	)
	(segment
		(start 417.848034 -232.609898)
		(end 418.698172 -233.460036)
		(width 0.14478)
		(layer "In6.Cu")
		(net "M_K_CPU0_SA_DQ<29>")
	)
	(segment
		(start 393.084558 -244.047264)
		(end 393.59078 -244.047264)
		(width 0.0889)
		(layer "In6.Cu")
		(net "M_K_CPU0_SA_DQ<29>")
	)
	(arc
		(start 389.511794 -243.996718)
		(mid 389.79475 -243.920541)
		(end 390.077706 -243.996718)
		(width 0.0889)
		(layer "In6.Cu")
		(net "M_K_CPU0_SA_DQ<29>")
	)
	(arc
		(start 391.965942 -244.001544)
		(mid 392.149196 -244.046917)
		(end 392.331194 -243.996718)
		(width 0.0889)
		(layer "In6.Cu")
		(net "M_K_CPU0_SA_DQ<29>")
	)
	(arc
		(start 391.026142 -244.001544)
		(mid 391.20965 -244.047038)
		(end 391.391902 -243.996718)
		(width 0.0889)
		(layer "In6.Cu")
		(net "M_K_CPU0_SA_DQ<29>")
	)
	(arc
		(start 389.193278 -244.02288)
		(mid 389.355467 -244.045615)
		(end 389.511794 -243.996718)
		(width 0.0889)
		(layer "In6.Cu")
		(net "M_K_CPU0_SA_DQ<29>")
	)
	(arc
		(start 390.451848 -243.996718)
		(mid 390.734804 -243.920541)
		(end 391.01776 -243.996718)
		(width 0.0889)
		(layer "In6.Cu")
		(net "M_K_CPU0_SA_DQ<29>")
	)
	(arc
		(start 392.341608 -243.990622)
		(mid 392.620294 -243.920402)
		(end 392.89736 -243.996718)
		(width 0.0889)
		(layer "In6.Cu")
		(net "M_K_CPU0_SA_DQ<29>")
	)
	(arc
		(start 391.391902 -243.996718)
		(mid 391.668715 -243.920575)
		(end 391.947146 -243.990622)
		(width 0.0889)
		(layer "In6.Cu")
		(net "M_K_CPU0_SA_DQ<29>")
	)
	(arc
		(start 392.89736 -243.996718)
		(mid 392.98762 -244.034346)
		(end 393.084558 -244.047264)
		(width 0.0889)
		(layer "In6.Cu")
		(net "M_K_CPU0_SA_DQ<29>")
	)
	(arc
		(start 390.077706 -243.996718)
		(mid 390.259957 -244.047068)
		(end 390.443466 -244.001544)
		(width 0.0889)
		(layer "In6.Cu")
		(net "M_K_CPU0_SA_DQ<29>")
	)
	(segment
		(start 390.267952 -243.13007)
		(end 390.734804 -242.864132)
		(width 0.10668)
		(layer "F.Cu")
		(net "M_K_CPU0_SA_DQ<28>")
	)
	(segment
		(start 421.539924 -231.769412)
		(end 422.389808 -230.919528)
		(width 0.14478)
		(layer "In6.Cu")
		(net "M_K_CPU0_SA_DQ<28>")
	)
	(segment
		(start 403.091396 -242.07597)
		(end 409.041854 -236.125512)
		(width 0.14478)
		(layer "In6.Cu")
		(net "M_K_CPU0_SA_DQ<28>")
	)
	(segment
		(start 445.43218 -230.91013)
		(end 446.219326 -230.91013)
		(width 0.14478)
		(layer "In6.Cu")
		(net "M_K_CPU0_SA_DQ<28>")
	)
	(segment
		(start 393.774422 -243.110512)
		(end 394.379958 -242.504976)
		(width 0.0889)
		(layer "In6.Cu")
		(net "M_K_CPU0_SA_DQ<28>")
	)
	(segment
		(start 433.795424 -231.769412)
		(end 436.731918 -231.769412)
		(width 0.14478)
		(layer "In6.Cu")
		(net "M_K_CPU0_SA_DQ<28>")
	)
	(segment
		(start 392.42746 -243.186712)
		(end 392.435842 -243.191538)
		(width 0.0889)
		(layer "In6.Cu")
		(net "M_K_CPU0_SA_DQ<28>")
	)
	(segment
		(start 412.25851 -231.760014)
		(end 414.046416 -231.760014)
		(width 0.14478)
		(layer "In6.Cu")
		(net "M_K_CPU0_SA_DQ<28>")
	)
	(segment
		(start 445.106044 -231.97947)
		(end 445.269112 -231.816402)
		(width 0.14478)
		(layer "In6.Cu")
		(net "M_K_CPU0_SA_DQ<28>")
	)
	(segment
		(start 432.94554 -230.919528)
		(end 433.795424 -231.769412)
		(width 0.14478)
		(layer "In6.Cu")
		(net "M_K_CPU0_SA_DQ<28>")
	)
	(segment
		(start 414.522158 -231.284272)
		(end 418.22243 -231.284272)
		(width 0.14478)
		(layer "In6.Cu")
		(net "M_K_CPU0_SA_DQ<28>")
	)
	(segment
		(start 409.041854 -236.125512)
		(end 409.041854 -234.97667)
		(width 0.14478)
		(layer "In6.Cu")
		(net "M_K_CPU0_SA_DQ<28>")
	)
	(segment
		(start 395.13383 -242.504976)
		(end 395.562836 -242.07597)
		(width 0.0889)
		(layer "In6.Cu")
		(net "M_K_CPU0_SA_DQ<28>")
	)
	(segment
		(start 390.58088 -243.129562)
		(end 390.603232 -243.212874)
		(width 0.0889)
		(layer "In6.Cu")
		(net "M_K_CPU0_SA_DQ<28>")
	)
	(segment
		(start 429.921416 -230.919528)
		(end 432.94554 -230.919528)
		(width 0.14478)
		(layer "In6.Cu")
		(net "M_K_CPU0_SA_DQ<28>")
	)
	(segment
		(start 446.219326 -230.91013)
		(end 446.644268 -231.335072)
		(width 0.14478)
		(layer "In6.Cu")
		(net "M_K_CPU0_SA_DQ<28>")
	)
	(segment
		(start 444.875666 -231.97947)
		(end 445.106044 -231.97947)
		(width 0.14478)
		(layer "In6.Cu")
		(net "M_K_CPU0_SA_DQ<28>")
	)
	(segment
		(start 394.379958 -242.504976)
		(end 395.13383 -242.504976)
		(width 0.0889)
		(layer "In6.Cu")
		(net "M_K_CPU0_SA_DQ<28>")
	)
	(segment
		(start 409.041854 -234.97667)
		(end 412.25851 -231.760014)
		(width 0.14478)
		(layer "In6.Cu")
		(net "M_K_CPU0_SA_DQ<28>")
	)
	(segment
		(start 444.712598 -231.816402)
		(end 444.875666 -231.97947)
		(width 0.14478)
		(layer "In6.Cu")
		(net "M_K_CPU0_SA_DQ<28>")
	)
	(segment
		(start 390.734804 -242.864132)
		(end 390.58088 -243.129562)
		(width 0.0889)
		(layer "In6.Cu")
		(net "M_K_CPU0_SA_DQ<28>")
	)
	(segment
		(start 437.581802 -230.919528)
		(end 444.558928 -230.919528)
		(width 0.14478)
		(layer "In6.Cu")
		(net "M_K_CPU0_SA_DQ<28>")
	)
	(segment
		(start 425.40174 -230.919528)
		(end 426.251624 -231.769412)
		(width 0.14478)
		(layer "In6.Cu")
		(net "M_K_CPU0_SA_DQ<28>")
	)
	(segment
		(start 444.712598 -231.073198)
		(end 444.712598 -231.816402)
		(width 0.14478)
		(layer "In6.Cu")
		(net "M_K_CPU0_SA_DQ<28>")
	)
	(segment
		(start 414.046416 -231.760014)
		(end 414.522158 -231.284272)
		(width 0.14478)
		(layer "In6.Cu")
		(net "M_K_CPU0_SA_DQ<28>")
	)
	(segment
		(start 395.892274 -242.07597)
		(end 403.091396 -242.07597)
		(width 0.14478)
		(layer "In6.Cu")
		(net "M_K_CPU0_SA_DQ<28>")
	)
	(segment
		(start 445.269112 -231.073198)
		(end 445.43218 -230.91013)
		(width 0.14478)
		(layer "In6.Cu")
		(net "M_K_CPU0_SA_DQ<28>")
	)
	(segment
		(start 445.269112 -231.816402)
		(end 445.269112 -231.073198)
		(width 0.14478)
		(layer "In6.Cu")
		(net "M_K_CPU0_SA_DQ<28>")
	)
	(segment
		(start 436.731918 -231.769412)
		(end 437.581802 -230.919528)
		(width 0.14478)
		(layer "In6.Cu")
		(net "M_K_CPU0_SA_DQ<28>")
	)
	(segment
		(start 429.071532 -231.769412)
		(end 429.921416 -230.919528)
		(width 0.14478)
		(layer "In6.Cu")
		(net "M_K_CPU0_SA_DQ<28>")
	)
	(segment
		(start 418.22243 -231.284272)
		(end 418.70757 -231.769412)
		(width 0.14478)
		(layer "In6.Cu")
		(net "M_K_CPU0_SA_DQ<28>")
	)
	(segment
		(start 422.389808 -230.919528)
		(end 425.40174 -230.919528)
		(width 0.14478)
		(layer "In6.Cu")
		(net "M_K_CPU0_SA_DQ<28>")
	)
	(segment
		(start 391.85342 -243.191538)
		(end 391.861802 -243.186712)
		(width 0.0889)
		(layer "In6.Cu")
		(net "M_K_CPU0_SA_DQ<28>")
	)
	(segment
		(start 393.084812 -243.110512)
		(end 393.774422 -243.110512)
		(width 0.0889)
		(layer "In6.Cu")
		(net "M_K_CPU0_SA_DQ<28>")
	)
	(segment
		(start 426.251624 -231.769412)
		(end 429.071532 -231.769412)
		(width 0.14478)
		(layer "In6.Cu")
		(net "M_K_CPU0_SA_DQ<28>")
	)
	(segment
		(start 444.558928 -230.919528)
		(end 444.712598 -231.073198)
		(width 0.14478)
		(layer "In6.Cu")
		(net "M_K_CPU0_SA_DQ<28>")
	)
	(segment
		(start 418.70757 -231.769412)
		(end 421.539924 -231.769412)
		(width 0.14478)
		(layer "In6.Cu")
		(net "M_K_CPU0_SA_DQ<28>")
	)
	(segment
		(start 391.861802 -243.186712)
		(end 391.872216 -243.180616)
		(width 0.0889)
		(layer "In6.Cu")
		(net "M_K_CPU0_SA_DQ<28>")
	)
	(segment
		(start 395.562836 -242.07597)
		(end 395.892274 -242.07597)
		(width 0.0889)
		(layer "In6.Cu")
		(net "M_K_CPU0_SA_DQ<28>")
	)
	(arc
		(start 392.801602 -243.186712)
		(mid 392.938165 -243.129879)
		(end 393.084812 -243.110512)
		(width 0.0889)
		(layer "In6.Cu")
		(net "M_K_CPU0_SA_DQ<28>")
	)
	(arc
		(start 391.48766 -243.186712)
		(mid 391.669911 -243.237062)
		(end 391.85342 -243.191538)
		(width 0.0889)
		(layer "In6.Cu")
		(net "M_K_CPU0_SA_DQ<28>")
	)
	(arc
		(start 391.872216 -243.180616)
		(mid 392.150648 -243.110518)
		(end 392.42746 -243.186712)
		(width 0.0889)
		(layer "In6.Cu")
		(net "M_K_CPU0_SA_DQ<28>")
	)
	(arc
		(start 390.603232 -243.212874)
		(mid 390.765421 -243.235609)
		(end 390.921748 -243.186712)
		(width 0.0889)
		(layer "In6.Cu")
		(net "M_K_CPU0_SA_DQ<28>")
	)
	(arc
		(start 390.921748 -243.186712)
		(mid 391.204704 -243.110535)
		(end 391.48766 -243.186712)
		(width 0.0889)
		(layer "In6.Cu")
		(net "M_K_CPU0_SA_DQ<28>")
	)
	(arc
		(start 392.435842 -243.191538)
		(mid 392.61935 -243.237032)
		(end 392.801602 -243.186712)
		(width 0.0889)
		(layer "In6.Cu")
		(net "M_K_CPU0_SA_DQ<28>")
	)
	(segment
		(start 388.387844 -241.510058)
		(end 388.85495 -241.24412)
		(width 0.10668)
		(layer "F.Cu")
		(net "M_K_CPU0_SA_DQ<27>")
	)
	(segment
		(start 428.509938 -228.129338)
		(end 428.509938 -228.197156)
		(width 0.14478)
		(layer "In6.Cu")
		(net "M_K_CPU0_SA_DQ<27>")
	)
	(segment
		(start 430.329848 -227.347018)
		(end 430.329848 -227.286058)
		(width 0.14478)
		(layer "In6.Cu")
		(net "M_K_CPU0_SA_DQ<27>")
	)
	(segment
		(start 427.799754 -228.350826)
		(end 427.953424 -228.197156)
		(width 0.14478)
		(layer "In6.Cu")
		(net "M_K_CPU0_SA_DQ<27>")
	)
	(segment
		(start 423.456862 -227.500688)
		(end 425.38269 -227.500688)
		(width 0.14478)
		(layer "In6.Cu")
		(net "M_K_CPU0_SA_DQ<27>")
	)
	(segment
		(start 429.08093 -228.360224)
		(end 429.931068 -227.510086)
		(width 0.14478)
		(layer "In6.Cu")
		(net "M_K_CPU0_SA_DQ<27>")
	)
	(segment
		(start 435.900068 -227.97135)
		(end 436.063136 -228.134418)
		(width 0.14478)
		(layer "In6.Cu")
		(net "M_K_CPU0_SA_DQ<27>")
	)
	(segment
		(start 394.920724 -240.55451)
		(end 395.738604 -239.73663)
		(width 0.0889)
		(layer "In6.Cu")
		(net "M_K_CPU0_SA_DQ<27>")
	)
	(segment
		(start 433.776628 -228.350826)
		(end 435.352952 -228.350826)
		(width 0.14478)
		(layer "In6.Cu")
		(net "M_K_CPU0_SA_DQ<27>")
	)
	(segment
		(start 430.329848 -227.286058)
		(end 430.492916 -227.12299)
		(width 0.14478)
		(layer "In6.Cu")
		(net "M_K_CPU0_SA_DQ<27>")
	)
	(segment
		(start 435.352952 -228.350826)
		(end 435.506622 -228.197156)
		(width 0.14478)
		(layer "In6.Cu")
		(net "M_K_CPU0_SA_DQ<27>")
	)
	(segment
		(start 420.484046 -228.197156)
		(end 420.484046 -228.129338)
		(width 0.14478)
		(layer "In6.Cu")
		(net "M_K_CPU0_SA_DQ<27>")
	)
	(segment
		(start 441.188602 -228.043232)
		(end 441.41898 -228.043232)
		(width 0.14478)
		(layer "In6.Cu")
		(net "M_K_CPU0_SA_DQ<27>")
	)
	(segment
		(start 427.953424 -228.197156)
		(end 427.953424 -228.129338)
		(width 0.14478)
		(layer "In6.Cu")
		(net "M_K_CPU0_SA_DQ<27>")
	)
	(segment
		(start 429.931068 -227.510086)
		(end 430.16678 -227.510086)
		(width 0.14478)
		(layer "In6.Cu")
		(net "M_K_CPU0_SA_DQ<27>")
	)
	(segment
		(start 414.006792 -228.360224)
		(end 414.866328 -227.500688)
		(width 0.14478)
		(layer "In6.Cu")
		(net "M_K_CPU0_SA_DQ<27>")
	)
	(segment
		(start 423.303192 -227.347018)
		(end 423.456862 -227.500688)
		(width 0.14478)
		(layer "In6.Cu")
		(net "M_K_CPU0_SA_DQ<27>")
	)
	(segment
		(start 440.236864 -227.347018)
		(end 440.390534 -227.500688)
		(width 0.14478)
		(layer "In6.Cu")
		(net "M_K_CPU0_SA_DQ<27>")
	)
	(segment
		(start 441.025534 -227.880164)
		(end 441.188602 -228.043232)
		(width 0.14478)
		(layer "In6.Cu")
		(net "M_K_CPU0_SA_DQ<27>")
	)
	(segment
		(start 436.063136 -228.134418)
		(end 436.063136 -228.197156)
		(width 0.14478)
		(layer "In6.Cu")
		(net "M_K_CPU0_SA_DQ<27>")
	)
	(segment
		(start 388.85495 -241.24412)
		(end 389.008874 -240.97869)
		(width 0.0889)
		(layer "In6.Cu")
		(net "M_K_CPU0_SA_DQ<27>")
	)
	(segment
		(start 420.877492 -227.96627)
		(end 421.04056 -228.129338)
		(width 0.14478)
		(layer "In6.Cu")
		(net "M_K_CPU0_SA_DQ<27>")
	)
	(segment
		(start 428.34687 -227.96627)
		(end 428.509938 -228.129338)
		(width 0.14478)
		(layer "In6.Cu")
		(net "M_K_CPU0_SA_DQ<27>")
	)
	(segment
		(start 428.116492 -227.96627)
		(end 428.34687 -227.96627)
		(width 0.14478)
		(layer "In6.Cu")
		(net "M_K_CPU0_SA_DQ<27>")
	)
	(segment
		(start 440.073796 -227.11791)
		(end 440.236864 -227.280978)
		(width 0.14478)
		(layer "In6.Cu")
		(net "M_K_CPU0_SA_DQ<27>")
	)
	(segment
		(start 422.39946 -227.510086)
		(end 422.58361 -227.510086)
		(width 0.14478)
		(layer "In6.Cu")
		(net "M_K_CPU0_SA_DQ<27>")
	)
	(segment
		(start 420.484046 -228.129338)
		(end 420.647114 -227.96627)
		(width 0.14478)
		(layer "In6.Cu")
		(net "M_K_CPU0_SA_DQ<27>")
	)
	(segment
		(start 423.140124 -227.13061)
		(end 423.303192 -227.293678)
		(width 0.14478)
		(layer "In6.Cu")
		(net "M_K_CPU0_SA_DQ<27>")
	)
	(segment
		(start 421.203628 -228.360224)
		(end 421.549322 -228.360224)
		(width 0.14478)
		(layer "In6.Cu")
		(net "M_K_CPU0_SA_DQ<27>")
	)
	(segment
		(start 435.506622 -228.134418)
		(end 435.66969 -227.97135)
		(width 0.14478)
		(layer "In6.Cu")
		(net "M_K_CPU0_SA_DQ<27>")
	)
	(segment
		(start 432.92649 -227.500688)
		(end 433.776628 -228.350826)
		(width 0.14478)
		(layer "In6.Cu")
		(net "M_K_CPU0_SA_DQ<27>")
	)
	(segment
		(start 422.909746 -227.13061)
		(end 423.140124 -227.13061)
		(width 0.14478)
		(layer "In6.Cu")
		(net "M_K_CPU0_SA_DQ<27>")
	)
	(segment
		(start 430.723294 -227.12299)
		(end 430.886362 -227.286058)
		(width 0.14478)
		(layer "In6.Cu")
		(net "M_K_CPU0_SA_DQ<27>")
	)
	(segment
		(start 411.395418 -228.360224)
		(end 414.006792 -228.360224)
		(width 0.14478)
		(layer "In6.Cu")
		(net "M_K_CPU0_SA_DQ<27>")
	)
	(segment
		(start 439.843418 -227.11791)
		(end 440.073796 -227.11791)
		(width 0.14478)
		(layer "In6.Cu")
		(net "M_K_CPU0_SA_DQ<27>")
	)
	(segment
		(start 441.41898 -228.043232)
		(end 441.582048 -227.880164)
		(width 0.14478)
		(layer "In6.Cu")
		(net "M_K_CPU0_SA_DQ<27>")
	)
	(segment
		(start 417.838636 -227.500688)
		(end 418.688774 -228.350826)
		(width 0.14478)
		(layer "In6.Cu")
		(net "M_K_CPU0_SA_DQ<27>")
	)
	(segment
		(start 436.6133 -228.360224)
		(end 437.472836 -227.500688)
		(width 0.14478)
		(layer "In6.Cu")
		(net "M_K_CPU0_SA_DQ<27>")
	)
	(segment
		(start 422.58361 -227.510086)
		(end 422.746678 -227.347018)
		(width 0.14478)
		(layer "In6.Cu")
		(net "M_K_CPU0_SA_DQ<27>")
	)
	(segment
		(start 420.647114 -227.96627)
		(end 420.877492 -227.96627)
		(width 0.14478)
		(layer "In6.Cu")
		(net "M_K_CPU0_SA_DQ<27>")
	)
	(segment
		(start 441.025534 -227.673154)
		(end 441.025534 -227.880164)
		(width 0.14478)
		(layer "In6.Cu")
		(net "M_K_CPU0_SA_DQ<27>")
	)
	(segment
		(start 406.517856 -233.237786)
		(end 411.395418 -228.360224)
		(width 0.14478)
		(layer "In6.Cu")
		(net "M_K_CPU0_SA_DQ<27>")
	)
	(segment
		(start 441.582048 -227.673154)
		(end 441.745116 -227.510086)
		(width 0.14478)
		(layer "In6.Cu")
		(net "M_K_CPU0_SA_DQ<27>")
	)
	(segment
		(start 435.66969 -227.97135)
		(end 435.900068 -227.97135)
		(width 0.14478)
		(layer "In6.Cu")
		(net "M_K_CPU0_SA_DQ<27>")
	)
	(segment
		(start 421.04056 -228.197156)
		(end 421.203628 -228.360224)
		(width 0.14478)
		(layer "In6.Cu")
		(net "M_K_CPU0_SA_DQ<27>")
	)
	(segment
		(start 430.16678 -227.510086)
		(end 430.329848 -227.347018)
		(width 0.14478)
		(layer "In6.Cu")
		(net "M_K_CPU0_SA_DQ<27>")
	)
	(segment
		(start 427.953424 -228.129338)
		(end 428.116492 -227.96627)
		(width 0.14478)
		(layer "In6.Cu")
		(net "M_K_CPU0_SA_DQ<27>")
	)
	(segment
		(start 439.68035 -227.347018)
		(end 439.68035 -227.280978)
		(width 0.14478)
		(layer "In6.Cu")
		(net "M_K_CPU0_SA_DQ<27>")
	)
	(segment
		(start 442.119258 -227.510086)
		(end 442.5442 -227.935028)
		(width 0.14478)
		(layer "In6.Cu")
		(net "M_K_CPU0_SA_DQ<27>")
	)
	(segment
		(start 430.886362 -227.286058)
		(end 430.886362 -227.347018)
		(width 0.14478)
		(layer "In6.Cu")
		(net "M_K_CPU0_SA_DQ<27>")
	)
	(segment
		(start 402.053552 -239.73663)
		(end 406.517856 -235.272326)
		(width 0.14478)
		(layer "In6.Cu")
		(net "M_K_CPU0_SA_DQ<27>")
	)
	(segment
		(start 428.673006 -228.360224)
		(end 429.08093 -228.360224)
		(width 0.14478)
		(layer "In6.Cu")
		(net "M_K_CPU0_SA_DQ<27>")
	)
	(segment
		(start 418.688774 -228.350826)
		(end 420.330376 -228.350826)
		(width 0.14478)
		(layer "In6.Cu")
		(net "M_K_CPU0_SA_DQ<27>")
	)
	(segment
		(start 391.849864 -240.914682)
		(end 391.861548 -240.92154)
		(width 0.0889)
		(layer "In6.Cu")
		(net "M_K_CPU0_SA_DQ<27>")
	)
	(segment
		(start 441.582048 -227.880164)
		(end 441.582048 -227.673154)
		(width 0.14478)
		(layer "In6.Cu")
		(net "M_K_CPU0_SA_DQ<27>")
	)
	(segment
		(start 428.509938 -228.197156)
		(end 428.673006 -228.360224)
		(width 0.14478)
		(layer "In6.Cu")
		(net "M_K_CPU0_SA_DQ<27>")
	)
	(segment
		(start 440.236864 -227.280978)
		(end 440.236864 -227.347018)
		(width 0.14478)
		(layer "In6.Cu")
		(net "M_K_CPU0_SA_DQ<27>")
	)
	(segment
		(start 426.232828 -228.350826)
		(end 427.799754 -228.350826)
		(width 0.14478)
		(layer "In6.Cu")
		(net "M_K_CPU0_SA_DQ<27>")
	)
	(segment
		(start 440.853068 -227.500688)
		(end 441.025534 -227.673154)
		(width 0.14478)
		(layer "In6.Cu")
		(net "M_K_CPU0_SA_DQ<27>")
	)
	(segment
		(start 437.472836 -227.500688)
		(end 439.52668 -227.500688)
		(width 0.14478)
		(layer "In6.Cu")
		(net "M_K_CPU0_SA_DQ<27>")
	)
	(segment
		(start 425.38269 -227.500688)
		(end 426.232828 -228.350826)
		(width 0.14478)
		(layer "In6.Cu")
		(net "M_K_CPU0_SA_DQ<27>")
	)
	(segment
		(start 421.04056 -228.129338)
		(end 421.04056 -228.197156)
		(width 0.14478)
		(layer "In6.Cu")
		(net "M_K_CPU0_SA_DQ<27>")
	)
	(segment
		(start 414.866328 -227.500688)
		(end 417.838636 -227.500688)
		(width 0.14478)
		(layer "In6.Cu")
		(net "M_K_CPU0_SA_DQ<27>")
	)
	(segment
		(start 392.801602 -240.92154)
		(end 392.820906 -240.932716)
		(width 0.0889)
		(layer "In6.Cu")
		(net "M_K_CPU0_SA_DQ<27>")
	)
	(segment
		(start 420.330376 -228.350826)
		(end 420.484046 -228.197156)
		(width 0.14478)
		(layer "In6.Cu")
		(net "M_K_CPU0_SA_DQ<27>")
	)
	(segment
		(start 422.746678 -227.293678)
		(end 422.909746 -227.13061)
		(width 0.14478)
		(layer "In6.Cu")
		(net "M_K_CPU0_SA_DQ<27>")
	)
	(segment
		(start 440.390534 -227.500688)
		(end 440.853068 -227.500688)
		(width 0.14478)
		(layer "In6.Cu")
		(net "M_K_CPU0_SA_DQ<27>")
	)
	(segment
		(start 389.607806 -240.92154)
		(end 389.616188 -240.916714)
		(width 0.0889)
		(layer "In6.Cu")
		(net "M_K_CPU0_SA_DQ<27>")
	)
	(segment
		(start 441.745116 -227.510086)
		(end 442.119258 -227.510086)
		(width 0.14478)
		(layer "In6.Cu")
		(net "M_K_CPU0_SA_DQ<27>")
	)
	(segment
		(start 436.226204 -228.360224)
		(end 436.6133 -228.360224)
		(width 0.14478)
		(layer "In6.Cu")
		(net "M_K_CPU0_SA_DQ<27>")
	)
	(segment
		(start 395.738604 -239.73663)
		(end 395.892274 -239.73663)
		(width 0.0889)
		(layer "In6.Cu")
		(net "M_K_CPU0_SA_DQ<27>")
	)
	(segment
		(start 430.886362 -227.347018)
		(end 431.040032 -227.500688)
		(width 0.14478)
		(layer "In6.Cu")
		(net "M_K_CPU0_SA_DQ<27>")
	)
	(segment
		(start 421.549322 -228.360224)
		(end 422.39946 -227.510086)
		(width 0.14478)
		(layer "In6.Cu")
		(net "M_K_CPU0_SA_DQ<27>")
	)
	(segment
		(start 392.427206 -240.92154)
		(end 392.43889 -240.914682)
		(width 0.0889)
		(layer "In6.Cu")
		(net "M_K_CPU0_SA_DQ<27>")
	)
	(segment
		(start 435.506622 -228.197156)
		(end 435.506622 -228.134418)
		(width 0.14478)
		(layer "In6.Cu")
		(net "M_K_CPU0_SA_DQ<27>")
	)
	(segment
		(start 430.492916 -227.12299)
		(end 430.723294 -227.12299)
		(width 0.14478)
		(layer "In6.Cu")
		(net "M_K_CPU0_SA_DQ<27>")
	)
	(segment
		(start 394.214096 -240.55451)
		(end 394.920724 -240.55451)
		(width 0.0889)
		(layer "In6.Cu")
		(net "M_K_CPU0_SA_DQ<27>")
	)
	(segment
		(start 436.063136 -228.197156)
		(end 436.226204 -228.360224)
		(width 0.14478)
		(layer "In6.Cu")
		(net "M_K_CPU0_SA_DQ<27>")
	)
	(segment
		(start 423.303192 -227.293678)
		(end 423.303192 -227.347018)
		(width 0.14478)
		(layer "In6.Cu")
		(net "M_K_CPU0_SA_DQ<27>")
	)
	(segment
		(start 395.892274 -239.73663)
		(end 402.053552 -239.73663)
		(width 0.14478)
		(layer "In6.Cu")
		(net "M_K_CPU0_SA_DQ<27>")
	)
	(segment
		(start 439.52668 -227.500688)
		(end 439.68035 -227.347018)
		(width 0.14478)
		(layer "In6.Cu")
		(net "M_K_CPU0_SA_DQ<27>")
	)
	(segment
		(start 393.728956 -241.03965)
		(end 394.214096 -240.55451)
		(width 0.0889)
		(layer "In6.Cu")
		(net "M_K_CPU0_SA_DQ<27>")
	)
	(segment
		(start 389.008874 -240.97869)
		(end 389.104886 -240.95329)
		(width 0.0889)
		(layer "In6.Cu")
		(net "M_K_CPU0_SA_DQ<27>")
	)
	(segment
		(start 431.040032 -227.500688)
		(end 432.92649 -227.500688)
		(width 0.14478)
		(layer "In6.Cu")
		(net "M_K_CPU0_SA_DQ<27>")
	)
	(segment
		(start 393.2174 -241.03965)
		(end 393.728956 -241.03965)
		(width 0.0889)
		(layer "In6.Cu")
		(net "M_K_CPU0_SA_DQ<27>")
	)
	(segment
		(start 422.746678 -227.347018)
		(end 422.746678 -227.293678)
		(width 0.14478)
		(layer "In6.Cu")
		(net "M_K_CPU0_SA_DQ<27>")
	)
	(segment
		(start 391.861548 -240.92154)
		(end 391.871962 -240.927636)
		(width 0.0889)
		(layer "In6.Cu")
		(net "M_K_CPU0_SA_DQ<27>")
	)
	(segment
		(start 439.68035 -227.280978)
		(end 439.843418 -227.11791)
		(width 0.14478)
		(layer "In6.Cu")
		(net "M_K_CPU0_SA_DQ<27>")
	)
	(segment
		(start 406.517856 -235.272326)
		(end 406.517856 -233.237786)
		(width 0.14478)
		(layer "In6.Cu")
		(net "M_K_CPU0_SA_DQ<27>")
	)
	(arc
		(start 392.820906 -240.932716)
		(mid 393.012076 -241.012408)
		(end 393.2174 -241.03965)
		(width 0.0889)
		(layer "In6.Cu")
		(net "M_K_CPU0_SA_DQ<27>")
	)
	(arc
		(start 391.48766 -240.92154)
		(mid 391.667865 -240.871223)
		(end 391.849864 -240.914682)
		(width 0.0889)
		(layer "In6.Cu")
		(net "M_K_CPU0_SA_DQ<27>")
	)
	(arc
		(start 389.981948 -240.92154)
		(mid 390.264904 -240.997717)
		(end 390.54786 -240.92154)
		(width 0.0889)
		(layer "In6.Cu")
		(net "M_K_CPU0_SA_DQ<27>")
	)
	(arc
		(start 389.616188 -240.916714)
		(mid 389.799696 -240.87122)
		(end 389.981948 -240.92154)
		(width 0.0889)
		(layer "In6.Cu")
		(net "M_K_CPU0_SA_DQ<27>")
	)
	(arc
		(start 392.43889 -240.914682)
		(mid 392.621145 -240.871029)
		(end 392.801602 -240.92154)
		(width 0.0889)
		(layer "In6.Cu")
		(net "M_K_CPU0_SA_DQ<27>")
	)
	(arc
		(start 391.871962 -240.927636)
		(mid 392.150394 -240.997734)
		(end 392.427206 -240.92154)
		(width 0.0889)
		(layer "In6.Cu")
		(net "M_K_CPU0_SA_DQ<27>")
	)
	(arc
		(start 390.54786 -240.92154)
		(mid 390.734804 -240.871285)
		(end 390.921748 -240.92154)
		(width 0.0889)
		(layer "In6.Cu")
		(net "M_K_CPU0_SA_DQ<27>")
	)
	(arc
		(start 390.921748 -240.92154)
		(mid 391.204704 -240.997717)
		(end 391.48766 -240.92154)
		(width 0.0889)
		(layer "In6.Cu")
		(net "M_K_CPU0_SA_DQ<27>")
	)
	(arc
		(start 389.104886 -240.95329)
		(mid 389.360094 -240.996767)
		(end 389.607806 -240.92154)
		(width 0.0889)
		(layer "In6.Cu")
		(net "M_K_CPU0_SA_DQ<27>")
	)
	(segment
		(start 389.798052 -240.700052)
		(end 390.264904 -240.434114)
		(width 0.10668)
		(layer "F.Cu")
		(net "M_K_CPU0_SA_DQ<26>")
	)
	(segment
		(start 427.879256 -226.660202)
		(end 428.042324 -226.497134)
		(width 0.14478)
		(layer "In6.Cu")
		(net "M_K_CPU0_SA_DQ<26>")
	)
	(segment
		(start 433.786026 -226.660202)
		(end 435.36743 -226.660202)
		(width 0.14478)
		(layer "In6.Cu")
		(net "M_K_CPU0_SA_DQ<26>")
	)
	(segment
		(start 428.761906 -226.660202)
		(end 429.08093 -226.660202)
		(width 0.14478)
		(layer "In6.Cu")
		(net "M_K_CPU0_SA_DQ<26>")
	)
	(segment
		(start 442.119258 -225.810064)
		(end 442.5442 -226.235006)
		(width 0.14478)
		(layer "In6.Cu")
		(net "M_K_CPU0_SA_DQ<26>")
	)
	(segment
		(start 416.242754 -225.810064)
		(end 416.405822 -225.646996)
		(width 0.14478)
		(layer "In6.Cu")
		(net "M_K_CPU0_SA_DQ<26>")
	)
	(segment
		(start 430.931066 -225.646996)
		(end 431.094134 -225.810064)
		(width 0.14478)
		(layer "In6.Cu")
		(net "M_K_CPU0_SA_DQ<26>")
	)
	(segment
		(start 440.540394 -226.035362)
		(end 440.540394 -225.584766)
		(width 0.14478)
		(layer "In6.Cu")
		(net "M_K_CPU0_SA_DQ<26>")
	)
	(segment
		(start 416.012376 -225.810064)
		(end 416.242754 -225.810064)
		(width 0.14478)
		(layer "In6.Cu")
		(net "M_K_CPU0_SA_DQ<26>")
	)
	(segment
		(start 430.767998 -225.41611)
		(end 430.931066 -225.579178)
		(width 0.14478)
		(layer "In6.Cu")
		(net "M_K_CPU0_SA_DQ<26>")
	)
	(segment
		(start 440.146948 -226.19843)
		(end 440.377326 -226.19843)
		(width 0.14478)
		(layer "In6.Cu")
		(net "M_K_CPU0_SA_DQ<26>")
	)
	(segment
		(start 416.56889 -225.42373)
		(end 416.799268 -225.42373)
		(width 0.14478)
		(layer "In6.Cu")
		(net "M_K_CPU0_SA_DQ<26>")
	)
	(segment
		(start 423.104564 -225.42373)
		(end 423.267632 -225.586798)
		(width 0.14478)
		(layer "In6.Cu")
		(net "M_K_CPU0_SA_DQ<26>")
	)
	(segment
		(start 438.246774 -225.42373)
		(end 438.409842 -225.586798)
		(width 0.14478)
		(layer "In6.Cu")
		(net "M_K_CPU0_SA_DQ<26>")
	)
	(segment
		(start 411.788102 -226.660202)
		(end 414.006792 -226.660202)
		(width 0.14478)
		(layer "In6.Cu")
		(net "M_K_CPU0_SA_DQ<26>")
	)
	(segment
		(start 393.084812 -240.060988)
		(end 393.894818 -240.060988)
		(width 0.0889)
		(layer "In6.Cu")
		(net "M_K_CPU0_SA_DQ<26>")
	)
	(segment
		(start 440.703462 -225.421698)
		(end 440.93384 -225.421698)
		(width 0.14478)
		(layer "In6.Cu")
		(net "M_K_CPU0_SA_DQ<26>")
	)
	(segment
		(start 390.418828 -240.168684)
		(end 390.51484 -240.143284)
		(width 0.0889)
		(layer "In6.Cu")
		(net "M_K_CPU0_SA_DQ<26>")
	)
	(segment
		(start 436.25008 -226.660202)
		(end 436.6133 -226.660202)
		(width 0.14478)
		(layer "In6.Cu")
		(net "M_K_CPU0_SA_DQ<26>")
	)
	(segment
		(start 417.125404 -225.810064)
		(end 417.848034 -225.810064)
		(width 0.14478)
		(layer "In6.Cu")
		(net "M_K_CPU0_SA_DQ<26>")
	)
	(segment
		(start 423.267632 -225.586798)
		(end 423.267632 -225.646996)
		(width 0.14478)
		(layer "In6.Cu")
		(net "M_K_CPU0_SA_DQ<26>")
	)
	(segment
		(start 395.489176 -238.82223)
		(end 395.857984 -238.82223)
		(width 0.0889)
		(layer "In6.Cu")
		(net "M_K_CPU0_SA_DQ<26>")
	)
	(segment
		(start 437.463438 -225.810064)
		(end 437.69026 -225.810064)
		(width 0.14478)
		(layer "In6.Cu")
		(net "M_K_CPU0_SA_DQ<26>")
	)
	(segment
		(start 441.096908 -226.035362)
		(end 441.259976 -226.19843)
		(width 0.14478)
		(layer "In6.Cu")
		(net "M_K_CPU0_SA_DQ<26>")
	)
	(segment
		(start 426.242226 -226.660202)
		(end 427.879256 -226.660202)
		(width 0.14478)
		(layer "In6.Cu")
		(net "M_K_CPU0_SA_DQ<26>")
	)
	(segment
		(start 428.598838 -226.432618)
		(end 428.598838 -226.497134)
		(width 0.14478)
		(layer "In6.Cu")
		(net "M_K_CPU0_SA_DQ<26>")
	)
	(segment
		(start 415.849308 -225.646996)
		(end 416.012376 -225.810064)
		(width 0.14478)
		(layer "In6.Cu")
		(net "M_K_CPU0_SA_DQ<26>")
	)
	(segment
		(start 401.674584 -238.82223)
		(end 405.603456 -234.893358)
		(width 0.14478)
		(layer "In6.Cu")
		(net "M_K_CPU0_SA_DQ<26>")
	)
	(segment
		(start 436.6133 -226.660202)
		(end 437.463438 -225.810064)
		(width 0.14478)
		(layer "In6.Cu")
		(net "M_K_CPU0_SA_DQ<26>")
	)
	(segment
		(start 394.442696 -239.51311)
		(end 394.798296 -239.51311)
		(width 0.0889)
		(layer "In6.Cu")
		(net "M_K_CPU0_SA_DQ<26>")
	)
	(segment
		(start 435.530498 -226.497134)
		(end 435.530498 -226.445318)
		(width 0.14478)
		(layer "In6.Cu")
		(net "M_K_CPU0_SA_DQ<26>")
	)
	(segment
		(start 438.409842 -225.646996)
		(end 438.57291 -225.810064)
		(width 0.14478)
		(layer "In6.Cu")
		(net "M_K_CPU0_SA_DQ<26>")
	)
	(segment
		(start 428.205392 -226.26955)
		(end 428.43577 -226.26955)
		(width 0.14478)
		(layer "In6.Cu")
		(net "M_K_CPU0_SA_DQ<26>")
	)
	(segment
		(start 430.374552 -225.579178)
		(end 430.53762 -225.41611)
		(width 0.14478)
		(layer "In6.Cu")
		(net "M_K_CPU0_SA_DQ<26>")
	)
	(segment
		(start 415.68624 -225.42373)
		(end 415.849308 -225.586798)
		(width 0.14478)
		(layer "In6.Cu")
		(net "M_K_CPU0_SA_DQ<26>")
	)
	(segment
		(start 436.087012 -226.497134)
		(end 436.25008 -226.660202)
		(width 0.14478)
		(layer "In6.Cu")
		(net "M_K_CPU0_SA_DQ<26>")
	)
	(segment
		(start 428.042324 -226.497134)
		(end 428.042324 -226.432618)
		(width 0.14478)
		(layer "In6.Cu")
		(net "M_K_CPU0_SA_DQ<26>")
	)
	(segment
		(start 440.377326 -226.19843)
		(end 440.540394 -226.035362)
		(width 0.14478)
		(layer "In6.Cu")
		(net "M_K_CPU0_SA_DQ<26>")
	)
	(segment
		(start 440.93384 -225.421698)
		(end 441.096908 -225.584766)
		(width 0.14478)
		(layer "In6.Cu")
		(net "M_K_CPU0_SA_DQ<26>")
	)
	(segment
		(start 430.53762 -225.41611)
		(end 430.767998 -225.41611)
		(width 0.14478)
		(layer "In6.Cu")
		(net "M_K_CPU0_SA_DQ<26>")
	)
	(segment
		(start 422.711118 -225.586798)
		(end 422.874186 -225.42373)
		(width 0.14478)
		(layer "In6.Cu")
		(net "M_K_CPU0_SA_DQ<26>")
	)
	(segment
		(start 430.374552 -225.646996)
		(end 430.374552 -225.579178)
		(width 0.14478)
		(layer "In6.Cu")
		(net "M_K_CPU0_SA_DQ<26>")
	)
	(segment
		(start 439.820812 -225.810064)
		(end 439.98388 -225.973132)
		(width 0.14478)
		(layer "In6.Cu")
		(net "M_K_CPU0_SA_DQ<26>")
	)
	(segment
		(start 395.857984 -238.82223)
		(end 401.674584 -238.82223)
		(width 0.14478)
		(layer "In6.Cu")
		(net "M_K_CPU0_SA_DQ<26>")
	)
	(segment
		(start 435.530498 -226.445318)
		(end 435.693566 -226.28225)
		(width 0.14478)
		(layer "In6.Cu")
		(net "M_K_CPU0_SA_DQ<26>")
	)
	(segment
		(start 414.006792 -226.660202)
		(end 414.85693 -225.810064)
		(width 0.14478)
		(layer "In6.Cu")
		(net "M_K_CPU0_SA_DQ<26>")
	)
	(segment
		(start 394.798296 -239.51311)
		(end 395.489176 -238.82223)
		(width 0.0889)
		(layer "In6.Cu")
		(net "M_K_CPU0_SA_DQ<26>")
	)
	(segment
		(start 435.923944 -226.28225)
		(end 436.087012 -226.445318)
		(width 0.14478)
		(layer "In6.Cu")
		(net "M_K_CPU0_SA_DQ<26>")
	)
	(segment
		(start 392.331448 -240.111534)
		(end 392.341862 -240.11763)
		(width 0.0889)
		(layer "In6.Cu")
		(net "M_K_CPU0_SA_DQ<26>")
	)
	(segment
		(start 441.653422 -226.035362)
		(end 441.653422 -225.973132)
		(width 0.14478)
		(layer "In6.Cu")
		(net "M_K_CPU0_SA_DQ<26>")
	)
	(segment
		(start 435.36743 -226.660202)
		(end 435.530498 -226.497134)
		(width 0.14478)
		(layer "In6.Cu")
		(net "M_K_CPU0_SA_DQ<26>")
	)
	(segment
		(start 415.849308 -225.586798)
		(end 415.849308 -225.646996)
		(width 0.14478)
		(layer "In6.Cu")
		(net "M_K_CPU0_SA_DQ<26>")
	)
	(segment
		(start 391.947146 -240.11763)
		(end 391.95756 -240.111534)
		(width 0.0889)
		(layer "In6.Cu")
		(net "M_K_CPU0_SA_DQ<26>")
	)
	(segment
		(start 416.405822 -225.586798)
		(end 416.56889 -225.42373)
		(width 0.14478)
		(layer "In6.Cu")
		(net "M_K_CPU0_SA_DQ<26>")
	)
	(segment
		(start 422.54805 -225.810064)
		(end 422.711118 -225.646996)
		(width 0.14478)
		(layer "In6.Cu")
		(net "M_K_CPU0_SA_DQ<26>")
	)
	(segment
		(start 441.653422 -225.973132)
		(end 441.81649 -225.810064)
		(width 0.14478)
		(layer "In6.Cu")
		(net "M_K_CPU0_SA_DQ<26>")
	)
	(segment
		(start 439.98388 -226.035362)
		(end 440.146948 -226.19843)
		(width 0.14478)
		(layer "In6.Cu")
		(net "M_K_CPU0_SA_DQ<26>")
	)
	(segment
		(start 440.540394 -225.584766)
		(end 440.703462 -225.421698)
		(width 0.14478)
		(layer "In6.Cu")
		(net "M_K_CPU0_SA_DQ<26>")
	)
	(segment
		(start 429.08093 -226.660202)
		(end 429.931068 -225.810064)
		(width 0.14478)
		(layer "In6.Cu")
		(net "M_K_CPU0_SA_DQ<26>")
	)
	(segment
		(start 436.087012 -226.445318)
		(end 436.087012 -226.497134)
		(width 0.14478)
		(layer "In6.Cu")
		(net "M_K_CPU0_SA_DQ<26>")
	)
	(segment
		(start 437.853328 -225.586798)
		(end 438.016396 -225.42373)
		(width 0.14478)
		(layer "In6.Cu")
		(net "M_K_CPU0_SA_DQ<26>")
	)
	(segment
		(start 418.698172 -226.660202)
		(end 421.549322 -226.660202)
		(width 0.14478)
		(layer "In6.Cu")
		(net "M_K_CPU0_SA_DQ<26>")
	)
	(segment
		(start 428.042324 -226.432618)
		(end 428.205392 -226.26955)
		(width 0.14478)
		(layer "In6.Cu")
		(net "M_K_CPU0_SA_DQ<26>")
	)
	(segment
		(start 437.69026 -225.810064)
		(end 437.853328 -225.646996)
		(width 0.14478)
		(layer "In6.Cu")
		(net "M_K_CPU0_SA_DQ<26>")
	)
	(segment
		(start 430.931066 -225.579178)
		(end 430.931066 -225.646996)
		(width 0.14478)
		(layer "In6.Cu")
		(net "M_K_CPU0_SA_DQ<26>")
	)
	(segment
		(start 390.264904 -240.434114)
		(end 390.418828 -240.168684)
		(width 0.0889)
		(layer "In6.Cu")
		(net "M_K_CPU0_SA_DQ<26>")
	)
	(segment
		(start 415.455862 -225.42373)
		(end 415.68624 -225.42373)
		(width 0.14478)
		(layer "In6.Cu")
		(net "M_K_CPU0_SA_DQ<26>")
	)
	(segment
		(start 441.490354 -226.19843)
		(end 441.653422 -226.035362)
		(width 0.14478)
		(layer "In6.Cu")
		(net "M_K_CPU0_SA_DQ<26>")
	)
	(segment
		(start 393.894818 -240.060988)
		(end 394.442696 -239.51311)
		(width 0.0889)
		(layer "In6.Cu")
		(net "M_K_CPU0_SA_DQ<26>")
	)
	(segment
		(start 405.603456 -234.893358)
		(end 405.603456 -232.844848)
		(width 0.14478)
		(layer "In6.Cu")
		(net "M_K_CPU0_SA_DQ<26>")
	)
	(segment
		(start 422.874186 -225.42373)
		(end 423.104564 -225.42373)
		(width 0.14478)
		(layer "In6.Cu")
		(net "M_K_CPU0_SA_DQ<26>")
	)
	(segment
		(start 441.096908 -225.584766)
		(end 441.096908 -226.035362)
		(width 0.14478)
		(layer "In6.Cu")
		(net "M_K_CPU0_SA_DQ<26>")
	)
	(segment
		(start 431.094134 -225.810064)
		(end 432.935888 -225.810064)
		(width 0.14478)
		(layer "In6.Cu")
		(net "M_K_CPU0_SA_DQ<26>")
	)
	(segment
		(start 422.39946 -225.810064)
		(end 422.54805 -225.810064)
		(width 0.14478)
		(layer "In6.Cu")
		(net "M_K_CPU0_SA_DQ<26>")
	)
	(segment
		(start 423.4307 -225.810064)
		(end 425.392088 -225.810064)
		(width 0.14478)
		(layer "In6.Cu")
		(net "M_K_CPU0_SA_DQ<26>")
	)
	(segment
		(start 421.549322 -226.660202)
		(end 422.39946 -225.810064)
		(width 0.14478)
		(layer "In6.Cu")
		(net "M_K_CPU0_SA_DQ<26>")
	)
	(segment
		(start 423.267632 -225.646996)
		(end 423.4307 -225.810064)
		(width 0.14478)
		(layer "In6.Cu")
		(net "M_K_CPU0_SA_DQ<26>")
	)
	(segment
		(start 415.292794 -225.586798)
		(end 415.455862 -225.42373)
		(width 0.14478)
		(layer "In6.Cu")
		(net "M_K_CPU0_SA_DQ<26>")
	)
	(segment
		(start 438.409842 -225.586798)
		(end 438.409842 -225.646996)
		(width 0.14478)
		(layer "In6.Cu")
		(net "M_K_CPU0_SA_DQ<26>")
	)
	(segment
		(start 405.603456 -232.844848)
		(end 411.788102 -226.660202)
		(width 0.14478)
		(layer "In6.Cu")
		(net "M_K_CPU0_SA_DQ<26>")
	)
	(segment
		(start 428.598838 -226.497134)
		(end 428.761906 -226.660202)
		(width 0.14478)
		(layer "In6.Cu")
		(net "M_K_CPU0_SA_DQ<26>")
	)
	(segment
		(start 415.292794 -225.646996)
		(end 415.292794 -225.586798)
		(width 0.14478)
		(layer "In6.Cu")
		(net "M_K_CPU0_SA_DQ<26>")
	)
	(segment
		(start 416.962336 -225.646996)
		(end 417.125404 -225.810064)
		(width 0.14478)
		(layer "In6.Cu")
		(net "M_K_CPU0_SA_DQ<26>")
	)
	(segment
		(start 430.211484 -225.810064)
		(end 430.374552 -225.646996)
		(width 0.14478)
		(layer "In6.Cu")
		(net "M_K_CPU0_SA_DQ<26>")
	)
	(segment
		(start 429.931068 -225.810064)
		(end 430.211484 -225.810064)
		(width 0.14478)
		(layer "In6.Cu")
		(net "M_K_CPU0_SA_DQ<26>")
	)
	(segment
		(start 416.405822 -225.646996)
		(end 416.405822 -225.586798)
		(width 0.14478)
		(layer "In6.Cu")
		(net "M_K_CPU0_SA_DQ<26>")
	)
	(segment
		(start 439.98388 -225.973132)
		(end 439.98388 -226.035362)
		(width 0.14478)
		(layer "In6.Cu")
		(net "M_K_CPU0_SA_DQ<26>")
	)
	(segment
		(start 425.392088 -225.810064)
		(end 426.242226 -226.660202)
		(width 0.14478)
		(layer "In6.Cu")
		(net "M_K_CPU0_SA_DQ<26>")
	)
	(segment
		(start 435.693566 -226.28225)
		(end 435.923944 -226.28225)
		(width 0.14478)
		(layer "In6.Cu")
		(net "M_K_CPU0_SA_DQ<26>")
	)
	(segment
		(start 416.962336 -225.586798)
		(end 416.962336 -225.646996)
		(width 0.14478)
		(layer "In6.Cu")
		(net "M_K_CPU0_SA_DQ<26>")
	)
	(segment
		(start 391.01776 -240.111534)
		(end 391.026142 -240.106708)
		(width 0.0889)
		(layer "In6.Cu")
		(net "M_K_CPU0_SA_DQ<26>")
	)
	(segment
		(start 428.43577 -226.26955)
		(end 428.598838 -226.432618)
		(width 0.14478)
		(layer "In6.Cu")
		(net "M_K_CPU0_SA_DQ<26>")
	)
	(segment
		(start 441.259976 -226.19843)
		(end 441.490354 -226.19843)
		(width 0.14478)
		(layer "In6.Cu")
		(net "M_K_CPU0_SA_DQ<26>")
	)
	(segment
		(start 438.016396 -225.42373)
		(end 438.246774 -225.42373)
		(width 0.14478)
		(layer "In6.Cu")
		(net "M_K_CPU0_SA_DQ<26>")
	)
	(segment
		(start 432.935888 -225.810064)
		(end 433.786026 -226.660202)
		(width 0.14478)
		(layer "In6.Cu")
		(net "M_K_CPU0_SA_DQ<26>")
	)
	(segment
		(start 416.799268 -225.42373)
		(end 416.962336 -225.586798)
		(width 0.14478)
		(layer "In6.Cu")
		(net "M_K_CPU0_SA_DQ<26>")
	)
	(segment
		(start 414.85693 -225.810064)
		(end 415.129726 -225.810064)
		(width 0.14478)
		(layer "In6.Cu")
		(net "M_K_CPU0_SA_DQ<26>")
	)
	(segment
		(start 415.129726 -225.810064)
		(end 415.292794 -225.646996)
		(width 0.14478)
		(layer "In6.Cu")
		(net "M_K_CPU0_SA_DQ<26>")
	)
	(segment
		(start 441.81649 -225.810064)
		(end 442.119258 -225.810064)
		(width 0.14478)
		(layer "In6.Cu")
		(net "M_K_CPU0_SA_DQ<26>")
	)
	(segment
		(start 437.853328 -225.646996)
		(end 437.853328 -225.586798)
		(width 0.14478)
		(layer "In6.Cu")
		(net "M_K_CPU0_SA_DQ<26>")
	)
	(segment
		(start 417.848034 -225.810064)
		(end 418.698172 -226.660202)
		(width 0.14478)
		(layer "In6.Cu")
		(net "M_K_CPU0_SA_DQ<26>")
	)
	(segment
		(start 438.57291 -225.810064)
		(end 439.820812 -225.810064)
		(width 0.14478)
		(layer "In6.Cu")
		(net "M_K_CPU0_SA_DQ<26>")
	)
	(segment
		(start 422.711118 -225.646996)
		(end 422.711118 -225.586798)
		(width 0.14478)
		(layer "In6.Cu")
		(net "M_K_CPU0_SA_DQ<26>")
	)
	(arc
		(start 391.391902 -240.111534)
		(mid 391.668715 -240.187677)
		(end 391.947146 -240.11763)
		(width 0.0889)
		(layer "In6.Cu")
		(net "M_K_CPU0_SA_DQ<26>")
	)
	(arc
		(start 391.026142 -240.106708)
		(mid 391.20965 -240.061214)
		(end 391.391902 -240.111534)
		(width 0.0889)
		(layer "In6.Cu")
		(net "M_K_CPU0_SA_DQ<26>")
	)
	(arc
		(start 390.51484 -240.143284)
		(mid 390.770048 -240.186761)
		(end 391.01776 -240.111534)
		(width 0.0889)
		(layer "In6.Cu")
		(net "M_K_CPU0_SA_DQ<26>")
	)
	(arc
		(start 392.341862 -240.11763)
		(mid 392.620548 -240.18785)
		(end 392.897614 -240.111534)
		(width 0.0889)
		(layer "In6.Cu")
		(net "M_K_CPU0_SA_DQ<26>")
	)
	(arc
		(start 392.897614 -240.111534)
		(mid 392.987874 -240.073906)
		(end 393.084812 -240.060988)
		(width 0.0889)
		(layer "In6.Cu")
		(net "M_K_CPU0_SA_DQ<26>")
	)
	(arc
		(start 391.95756 -240.111534)
		(mid 392.144504 -240.061279)
		(end 392.331448 -240.111534)
		(width 0.0889)
		(layer "In6.Cu")
		(net "M_K_CPU0_SA_DQ<26>")
	)
	(segment
		(start 388.857998 -240.700052)
		(end 389.32485 -240.434114)
		(width 0.10668)
		(layer "F.Cu")
		(net "M_K_CPU0_SA_DQ<25>")
	)
	(segment
		(start 422.140126 -226.919282)
		(end 422.765728 -226.660202)
		(width 0.14478)
		(layer "In6.Cu")
		(net "M_K_CPU0_SA_DQ<25>")
	)
	(segment
		(start 393.375642 -240.69421)
		(end 393.761468 -240.308384)
		(width 0.0889)
		(layer "In6.Cu")
		(net "M_K_CPU0_SA_DQ<25>")
	)
	(segment
		(start 395.799056 -239.28197)
		(end 401.865084 -239.28197)
		(width 0.14478)
		(layer "In6.Cu")
		(net "M_K_CPU0_SA_DQ<25>")
	)
	(segment
		(start 411.602428 -227.510086)
		(end 413.152082 -227.510086)
		(width 0.14478)
		(layer "In6.Cu")
		(net "M_K_CPU0_SA_DQ<25>")
	)
	(segment
		(start 415.20491 -226.659948)
		(end 416.988498 -226.659948)
		(width 0.14478)
		(layer "In6.Cu")
		(net "M_K_CPU0_SA_DQ<25>")
	)
	(segment
		(start 392.331194 -240.756694)
		(end 392.341608 -240.750598)
		(width 0.0889)
		(layer "In6.Cu")
		(net "M_K_CPU0_SA_DQ<25>")
	)
	(segment
		(start 429.08093 -227.510086)
		(end 429.930814 -226.660202)
		(width 0.14478)
		(layer "In6.Cu")
		(net "M_K_CPU0_SA_DQ<25>")
	)
	(segment
		(start 418.455856 -227.26777)
		(end 419.041072 -227.510086)
		(width 0.14478)
		(layer "In6.Cu")
		(net "M_K_CPU0_SA_DQ<25>")
	)
	(segment
		(start 391.947146 -240.750598)
		(end 391.95756 -240.756694)
		(width 0.0889)
		(layer "In6.Cu")
		(net "M_K_CPU0_SA_DQ<25>")
	)
	(segment
		(start 420.713662 -227.510086)
		(end 422.140126 -226.919282)
		(width 0.14478)
		(layer "In6.Cu")
		(net "M_K_CPU0_SA_DQ<25>")
	)
	(segment
		(start 429.930814 -226.660202)
		(end 432.936142 -226.660202)
		(width 0.14478)
		(layer "In6.Cu")
		(net "M_K_CPU0_SA_DQ<25>")
	)
	(segment
		(start 413.152082 -227.510086)
		(end 415.20491 -226.659948)
		(width 0.14478)
		(layer "In6.Cu")
		(net "M_K_CPU0_SA_DQ<25>")
	)
	(segment
		(start 426.242226 -227.510086)
		(end 429.08093 -227.510086)
		(width 0.14478)
		(layer "In6.Cu")
		(net "M_K_CPU0_SA_DQ<25>")
	)
	(segment
		(start 406.063196 -235.083858)
		(end 406.063196 -233.049318)
		(width 0.14478)
		(layer "In6.Cu")
		(net "M_K_CPU0_SA_DQ<25>")
	)
	(segment
		(start 419.041072 -227.510086)
		(end 420.713662 -227.510086)
		(width 0.14478)
		(layer "In6.Cu")
		(net "M_K_CPU0_SA_DQ<25>")
	)
	(segment
		(start 446.219326 -226.660202)
		(end 446.644268 -227.085144)
		(width 0.14478)
		(layer "In6.Cu")
		(net "M_K_CPU0_SA_DQ<25>")
	)
	(segment
		(start 425.392342 -226.660202)
		(end 426.242226 -227.510086)
		(width 0.14478)
		(layer "In6.Cu")
		(net "M_K_CPU0_SA_DQ<25>")
	)
	(segment
		(start 401.865084 -239.28197)
		(end 406.063196 -235.083858)
		(width 0.14478)
		(layer "In6.Cu")
		(net "M_K_CPU0_SA_DQ<25>")
	)
	(segment
		(start 432.936142 -226.660202)
		(end 433.786026 -227.510086)
		(width 0.14478)
		(layer "In6.Cu")
		(net "M_K_CPU0_SA_DQ<25>")
	)
	(segment
		(start 390.443466 -240.76152)
		(end 390.451848 -240.756694)
		(width 0.0889)
		(layer "In6.Cu")
		(net "M_K_CPU0_SA_DQ<25>")
	)
	(segment
		(start 394.805916 -240.27511)
		(end 395.799056 -239.28197)
		(width 0.0889)
		(layer "In6.Cu")
		(net "M_K_CPU0_SA_DQ<25>")
	)
	(segment
		(start 436.741316 -227.510086)
		(end 437.5912 -226.660202)
		(width 0.14478)
		(layer "In6.Cu")
		(net "M_K_CPU0_SA_DQ<25>")
	)
	(segment
		(start 437.5912 -226.660202)
		(end 446.219326 -226.660202)
		(width 0.14478)
		(layer "In6.Cu")
		(net "M_K_CPU0_SA_DQ<25>")
	)
	(segment
		(start 433.786026 -227.510086)
		(end 436.741316 -227.510086)
		(width 0.14478)
		(layer "In6.Cu")
		(net "M_K_CPU0_SA_DQ<25>")
	)
	(segment
		(start 389.170926 -240.699544)
		(end 389.193278 -240.782856)
		(width 0.0889)
		(layer "In6.Cu")
		(net "M_K_CPU0_SA_DQ<25>")
	)
	(segment
		(start 406.063196 -233.049318)
		(end 411.602428 -227.510086)
		(width 0.14478)
		(layer "In6.Cu")
		(net "M_K_CPU0_SA_DQ<25>")
	)
	(segment
		(start 391.01776 -240.756694)
		(end 391.026142 -240.76152)
		(width 0.0889)
		(layer "In6.Cu")
		(net "M_K_CPU0_SA_DQ<25>")
	)
	(segment
		(start 393.841732 -240.27511)
		(end 394.805916 -240.27511)
		(width 0.0889)
		(layer "In6.Cu")
		(net "M_K_CPU0_SA_DQ<25>")
	)
	(segment
		(start 416.988498 -226.659948)
		(end 418.455856 -227.26777)
		(width 0.14478)
		(layer "In6.Cu")
		(net "M_K_CPU0_SA_DQ<25>")
	)
	(segment
		(start 422.765728 -226.660202)
		(end 425.392342 -226.660202)
		(width 0.14478)
		(layer "In6.Cu")
		(net "M_K_CPU0_SA_DQ<25>")
	)
	(segment
		(start 389.32485 -240.434114)
		(end 389.170926 -240.699544)
		(width 0.0889)
		(layer "In6.Cu")
		(net "M_K_CPU0_SA_DQ<25>")
	)
	(segment
		(start 391.95756 -240.756694)
		(end 391.965942 -240.76152)
		(width 0.0889)
		(layer "In6.Cu")
		(net "M_K_CPU0_SA_DQ<25>")
	)
	(arc
		(start 391.391902 -240.756694)
		(mid 391.668715 -240.680551)
		(end 391.947146 -240.750598)
		(width 0.0889)
		(layer "In6.Cu")
		(net "M_K_CPU0_SA_DQ<25>")
	)
	(arc
		(start 392.341608 -240.750598)
		(mid 392.620294 -240.680378)
		(end 392.89736 -240.756694)
		(width 0.0889)
		(layer "In6.Cu")
		(net "M_K_CPU0_SA_DQ<25>")
	)
	(arc
		(start 392.89736 -240.756694)
		(mid 393.147154 -240.806881)
		(end 393.375642 -240.69421)
		(width 0.0889)
		(layer "In6.Cu")
		(net "M_K_CPU0_SA_DQ<25>")
	)
	(arc
		(start 391.965942 -240.76152)
		(mid 392.149196 -240.806893)
		(end 392.331194 -240.756694)
		(width 0.0889)
		(layer "In6.Cu")
		(net "M_K_CPU0_SA_DQ<25>")
	)
	(arc
		(start 389.193278 -240.782856)
		(mid 389.355467 -240.805591)
		(end 389.511794 -240.756694)
		(width 0.0889)
		(layer "In6.Cu")
		(net "M_K_CPU0_SA_DQ<25>")
	)
	(arc
		(start 393.761468 -240.308384)
		(mid 393.798279 -240.283724)
		(end 393.841732 -240.27511)
		(width 0.0889)
		(layer "In6.Cu")
		(net "M_K_CPU0_SA_DQ<25>")
	)
	(arc
		(start 391.026142 -240.76152)
		(mid 391.20965 -240.807014)
		(end 391.391902 -240.756694)
		(width 0.0889)
		(layer "In6.Cu")
		(net "M_K_CPU0_SA_DQ<25>")
	)
	(arc
		(start 389.511794 -240.756694)
		(mid 389.79475 -240.680517)
		(end 390.077706 -240.756694)
		(width 0.0889)
		(layer "In6.Cu")
		(net "M_K_CPU0_SA_DQ<25>")
	)
	(arc
		(start 390.451848 -240.756694)
		(mid 390.734804 -240.680517)
		(end 391.01776 -240.756694)
		(width 0.0889)
		(layer "In6.Cu")
		(net "M_K_CPU0_SA_DQ<25>")
	)
	(arc
		(start 390.077706 -240.756694)
		(mid 390.259957 -240.807044)
		(end 390.443466 -240.76152)
		(width 0.0889)
		(layer "In6.Cu")
		(net "M_K_CPU0_SA_DQ<25>")
	)
	(segment
		(start 390.267952 -239.890046)
		(end 390.734804 -239.624108)
		(width 0.10668)
		(layer "F.Cu")
		(net "M_K_CPU0_SA_DQ<24>")
	)
	(segment
		(start 429.08093 -225.810064)
		(end 429.930814 -224.96018)
		(width 0.14478)
		(layer "In6.Cu")
		(net "M_K_CPU0_SA_DQ<24>")
	)
	(segment
		(start 417.848034 -224.959926)
		(end 418.698172 -225.810064)
		(width 0.14478)
		(layer "In6.Cu")
		(net "M_K_CPU0_SA_DQ<24>")
	)
	(segment
		(start 394.347446 -239.25911)
		(end 394.620496 -239.25911)
		(width 0.0889)
		(layer "In6.Cu")
		(net "M_K_CPU0_SA_DQ<24>")
	)
	(segment
		(start 436.741316 -225.810064)
		(end 437.5912 -224.96018)
		(width 0.14478)
		(layer "In6.Cu")
		(net "M_K_CPU0_SA_DQ<24>")
	)
	(segment
		(start 429.930814 -224.96018)
		(end 432.936142 -224.96018)
		(width 0.14478)
		(layer "In6.Cu")
		(net "M_K_CPU0_SA_DQ<24>")
	)
	(segment
		(start 391.85342 -239.951514)
		(end 391.861802 -239.946688)
		(width 0.0889)
		(layer "In6.Cu")
		(net "M_K_CPU0_SA_DQ<24>")
	)
	(segment
		(start 433.786026 -225.810064)
		(end 436.741316 -225.810064)
		(width 0.14478)
		(layer "In6.Cu")
		(net "M_K_CPU0_SA_DQ<24>")
	)
	(segment
		(start 390.734804 -239.624108)
		(end 390.58088 -239.889538)
		(width 0.0889)
		(layer "In6.Cu")
		(net "M_K_CPU0_SA_DQ<24>")
	)
	(segment
		(start 405.148796 -234.70489)
		(end 405.148796 -232.644188)
		(width 0.14478)
		(layer "In6.Cu")
		(net "M_K_CPU0_SA_DQ<24>")
	)
	(segment
		(start 425.392342 -224.96018)
		(end 426.242226 -225.810064)
		(width 0.14478)
		(layer "In6.Cu")
		(net "M_K_CPU0_SA_DQ<24>")
	)
	(segment
		(start 395.512036 -238.36757)
		(end 395.852396 -238.36757)
		(width 0.0889)
		(layer "In6.Cu")
		(net "M_K_CPU0_SA_DQ<24>")
	)
	(segment
		(start 446.219326 -224.96018)
		(end 446.644268 -225.385122)
		(width 0.14478)
		(layer "In6.Cu")
		(net "M_K_CPU0_SA_DQ<24>")
	)
	(segment
		(start 411.98292 -225.810064)
		(end 414.046416 -225.810064)
		(width 0.14478)
		(layer "In6.Cu")
		(net "M_K_CPU0_SA_DQ<24>")
	)
	(segment
		(start 414.896554 -224.959926)
		(end 417.848034 -224.959926)
		(width 0.14478)
		(layer "In6.Cu")
		(net "M_K_CPU0_SA_DQ<24>")
	)
	(segment
		(start 414.046416 -225.810064)
		(end 414.896554 -224.959926)
		(width 0.14478)
		(layer "In6.Cu")
		(net "M_K_CPU0_SA_DQ<24>")
	)
	(segment
		(start 393.736068 -239.870488)
		(end 394.347446 -239.25911)
		(width 0.0889)
		(layer "In6.Cu")
		(net "M_K_CPU0_SA_DQ<24>")
	)
	(segment
		(start 394.620496 -239.25911)
		(end 395.512036 -238.36757)
		(width 0.0889)
		(layer "In6.Cu")
		(net "M_K_CPU0_SA_DQ<24>")
	)
	(segment
		(start 401.486116 -238.36757)
		(end 405.148796 -234.70489)
		(width 0.14478)
		(layer "In6.Cu")
		(net "M_K_CPU0_SA_DQ<24>")
	)
	(segment
		(start 391.861802 -239.946688)
		(end 391.872216 -239.940592)
		(width 0.0889)
		(layer "In6.Cu")
		(net "M_K_CPU0_SA_DQ<24>")
	)
	(segment
		(start 426.242226 -225.810064)
		(end 429.08093 -225.810064)
		(width 0.14478)
		(layer "In6.Cu")
		(net "M_K_CPU0_SA_DQ<24>")
	)
	(segment
		(start 393.084812 -239.870488)
		(end 393.736068 -239.870488)
		(width 0.0889)
		(layer "In6.Cu")
		(net "M_K_CPU0_SA_DQ<24>")
	)
	(segment
		(start 395.852396 -238.36757)
		(end 401.486116 -238.36757)
		(width 0.14478)
		(layer "In6.Cu")
		(net "M_K_CPU0_SA_DQ<24>")
	)
	(segment
		(start 422.399206 -224.96018)
		(end 425.392342 -224.96018)
		(width 0.14478)
		(layer "In6.Cu")
		(net "M_K_CPU0_SA_DQ<24>")
	)
	(segment
		(start 421.549322 -225.810064)
		(end 422.399206 -224.96018)
		(width 0.14478)
		(layer "In6.Cu")
		(net "M_K_CPU0_SA_DQ<24>")
	)
	(segment
		(start 437.5912 -224.96018)
		(end 446.219326 -224.96018)
		(width 0.14478)
		(layer "In6.Cu")
		(net "M_K_CPU0_SA_DQ<24>")
	)
	(segment
		(start 432.936142 -224.96018)
		(end 433.786026 -225.810064)
		(width 0.14478)
		(layer "In6.Cu")
		(net "M_K_CPU0_SA_DQ<24>")
	)
	(segment
		(start 405.148796 -232.644188)
		(end 411.98292 -225.810064)
		(width 0.14478)
		(layer "In6.Cu")
		(net "M_K_CPU0_SA_DQ<24>")
	)
	(segment
		(start 392.42746 -239.946688)
		(end 392.435842 -239.951514)
		(width 0.0889)
		(layer "In6.Cu")
		(net "M_K_CPU0_SA_DQ<24>")
	)
	(segment
		(start 418.698172 -225.810064)
		(end 421.549322 -225.810064)
		(width 0.14478)
		(layer "In6.Cu")
		(net "M_K_CPU0_SA_DQ<24>")
	)
	(segment
		(start 390.58088 -239.889538)
		(end 390.603232 -239.97285)
		(width 0.0889)
		(layer "In6.Cu")
		(net "M_K_CPU0_SA_DQ<24>")
	)
	(arc
		(start 392.435842 -239.951514)
		(mid 392.61935 -239.997008)
		(end 392.801602 -239.946688)
		(width 0.0889)
		(layer "In6.Cu")
		(net "M_K_CPU0_SA_DQ<24>")
	)
	(arc
		(start 390.603232 -239.97285)
		(mid 390.765421 -239.995585)
		(end 390.921748 -239.946688)
		(width 0.0889)
		(layer "In6.Cu")
		(net "M_K_CPU0_SA_DQ<24>")
	)
	(arc
		(start 390.921748 -239.946688)
		(mid 391.204704 -239.870511)
		(end 391.48766 -239.946688)
		(width 0.0889)
		(layer "In6.Cu")
		(net "M_K_CPU0_SA_DQ<24>")
	)
	(arc
		(start 392.801602 -239.946688)
		(mid 392.938165 -239.889855)
		(end 393.084812 -239.870488)
		(width 0.0889)
		(layer "In6.Cu")
		(net "M_K_CPU0_SA_DQ<24>")
	)
	(arc
		(start 391.48766 -239.946688)
		(mid 391.669911 -239.997038)
		(end 391.85342 -239.951514)
		(width 0.0889)
		(layer "In6.Cu")
		(net "M_K_CPU0_SA_DQ<24>")
	)
	(arc
		(start 391.872216 -239.940592)
		(mid 392.150648 -239.870494)
		(end 392.42746 -239.946688)
		(width 0.0889)
		(layer "In6.Cu")
		(net "M_K_CPU0_SA_DQ<24>")
	)
	(segment
		(start 388.387844 -239.890046)
		(end 388.85495 -239.624108)
		(width 0.10668)
		(layer "F.Cu")
		(net "M_K_CPU0_SA_DQ<23>")
	)
	(segment
		(start 391.861548 -239.301528)
		(end 391.871962 -239.307624)
		(width 0.0889)
		(layer "In6.Cu")
		(net "M_K_CPU0_SA_DQ<23>")
	)
	(segment
		(start 438.668414 -224.110042)
		(end 439.575448 -224.110042)
		(width 0.14478)
		(layer "In6.Cu")
		(net "M_K_CPU0_SA_DQ<23>")
	)
	(segment
		(start 430.642268 -223.73209)
		(end 430.872646 -223.73209)
		(width 0.14478)
		(layer "In6.Cu")
		(net "M_K_CPU0_SA_DQ<23>")
	)
	(segment
		(start 441.408058 -223.946974)
		(end 441.571126 -224.110042)
		(width 0.14478)
		(layer "In6.Cu")
		(net "M_K_CPU0_SA_DQ<23>")
	)
	(segment
		(start 436.104792 -224.738438)
		(end 436.104792 -224.797112)
		(width 0.14478)
		(layer "In6.Cu")
		(net "M_K_CPU0_SA_DQ<23>")
	)
	(segment
		(start 442.119258 -224.110042)
		(end 442.5442 -224.534984)
		(width 0.14478)
		(layer "In6.Cu")
		(net "M_K_CPU0_SA_DQ<23>")
	)
	(segment
		(start 416.234626 -224.110042)
		(end 416.465004 -224.110042)
		(width 0.14478)
		(layer "In6.Cu")
		(net "M_K_CPU0_SA_DQ<23>")
	)
	(segment
		(start 417.184586 -223.946974)
		(end 417.347654 -224.110042)
		(width 0.14478)
		(layer "In6.Cu")
		(net "M_K_CPU0_SA_DQ<23>")
	)
	(segment
		(start 427.995334 -224.797112)
		(end 427.995334 -224.730818)
		(width 0.14478)
		(layer "In6.Cu")
		(net "M_K_CPU0_SA_DQ<23>")
	)
	(segment
		(start 418.698172 -224.96018)
		(end 420.30269 -224.96018)
		(width 0.14478)
		(layer "In6.Cu")
		(net "M_K_CPU0_SA_DQ<23>")
	)
	(segment
		(start 438.505346 -223.946974)
		(end 438.668414 -224.110042)
		(width 0.14478)
		(layer "In6.Cu")
		(net "M_K_CPU0_SA_DQ<23>")
	)
	(segment
		(start 423.410888 -223.946974)
		(end 423.573956 -224.110042)
		(width 0.14478)
		(layer "In6.Cu")
		(net "M_K_CPU0_SA_DQ<23>")
	)
	(segment
		(start 412.817056 -224.751138)
		(end 412.980124 -224.58807)
		(width 0.14478)
		(layer "In6.Cu")
		(net "M_K_CPU0_SA_DQ<23>")
	)
	(segment
		(start 429.08093 -224.96018)
		(end 429.931068 -224.110042)
		(width 0.14478)
		(layer "In6.Cu")
		(net "M_K_CPU0_SA_DQ<23>")
	)
	(segment
		(start 421.022272 -224.730818)
		(end 421.022272 -224.797112)
		(width 0.14478)
		(layer "In6.Cu")
		(net "M_K_CPU0_SA_DQ<23>")
	)
	(segment
		(start 392.427206 -239.301528)
		(end 392.43889 -239.29467)
		(width 0.0889)
		(layer "In6.Cu")
		(net "M_K_CPU0_SA_DQ<23>")
	)
	(segment
		(start 416.79114 -223.72701)
		(end 417.021518 -223.72701)
		(width 0.14478)
		(layer "In6.Cu")
		(net "M_K_CPU0_SA_DQ<23>")
	)
	(segment
		(start 438.342278 -223.72447)
		(end 438.505346 -223.887538)
		(width 0.14478)
		(layer "In6.Cu")
		(net "M_K_CPU0_SA_DQ<23>")
	)
	(segment
		(start 435.548278 -224.738438)
		(end 435.711346 -224.57537)
		(width 0.14478)
		(layer "In6.Cu")
		(net "M_K_CPU0_SA_DQ<23>")
	)
	(segment
		(start 389.607806 -239.301528)
		(end 389.616188 -239.296702)
		(width 0.0889)
		(layer "In6.Cu")
		(net "M_K_CPU0_SA_DQ<23>")
	)
	(segment
		(start 395.892274 -237.81131)
		(end 401.24888 -237.81131)
		(width 0.14478)
		(layer "In6.Cu")
		(net "M_K_CPU0_SA_DQ<23>")
	)
	(segment
		(start 440.131962 -223.71939)
		(end 440.29503 -223.882458)
		(width 0.14478)
		(layer "In6.Cu")
		(net "M_K_CPU0_SA_DQ<23>")
	)
	(segment
		(start 438.505346 -223.887538)
		(end 438.505346 -223.946974)
		(width 0.14478)
		(layer "In6.Cu")
		(net "M_K_CPU0_SA_DQ<23>")
	)
	(segment
		(start 413.37357 -224.797112)
		(end 413.536638 -224.96018)
		(width 0.14478)
		(layer "In6.Cu")
		(net "M_K_CPU0_SA_DQ<23>")
	)
	(segment
		(start 438.1119 -223.72447)
		(end 438.342278 -223.72447)
		(width 0.14478)
		(layer "In6.Cu")
		(net "M_K_CPU0_SA_DQ<23>")
	)
	(segment
		(start 440.29503 -224.046542)
		(end 440.458098 -224.20961)
		(width 0.14478)
		(layer "In6.Cu")
		(net "M_K_CPU0_SA_DQ<23>")
	)
	(segment
		(start 433.786026 -224.96018)
		(end 435.38521 -224.96018)
		(width 0.14478)
		(layer "In6.Cu")
		(net "M_K_CPU0_SA_DQ<23>")
	)
	(segment
		(start 413.210502 -224.58807)
		(end 413.37357 -224.751138)
		(width 0.14478)
		(layer "In6.Cu")
		(net "M_K_CPU0_SA_DQ<23>")
	)
	(segment
		(start 423.573956 -224.110042)
		(end 425.392088 -224.110042)
		(width 0.14478)
		(layer "In6.Cu")
		(net "M_K_CPU0_SA_DQ<23>")
	)
	(segment
		(start 436.6133 -224.96018)
		(end 437.463438 -224.110042)
		(width 0.14478)
		(layer "In6.Cu")
		(net "M_K_CPU0_SA_DQ<23>")
	)
	(segment
		(start 427.832266 -224.96018)
		(end 427.995334 -224.797112)
		(width 0.14478)
		(layer "In6.Cu")
		(net "M_K_CPU0_SA_DQ<23>")
	)
	(segment
		(start 439.901584 -223.71939)
		(end 440.131962 -223.71939)
		(width 0.14478)
		(layer "In6.Cu")
		(net "M_K_CPU0_SA_DQ<23>")
	)
	(segment
		(start 436.26786 -224.96018)
		(end 436.6133 -224.96018)
		(width 0.14478)
		(layer "In6.Cu")
		(net "M_K_CPU0_SA_DQ<23>")
	)
	(segment
		(start 440.29503 -223.882458)
		(end 440.29503 -224.046542)
		(width 0.14478)
		(layer "In6.Cu")
		(net "M_K_CPU0_SA_DQ<23>")
	)
	(segment
		(start 414.85693 -224.110042)
		(end 415.351976 -224.110042)
		(width 0.14478)
		(layer "In6.Cu")
		(net "M_K_CPU0_SA_DQ<23>")
	)
	(segment
		(start 394.168376 -239.00511)
		(end 394.493496 -239.00511)
		(width 0.0889)
		(layer "In6.Cu")
		(net "M_K_CPU0_SA_DQ<23>")
	)
	(segment
		(start 416.628072 -223.890078)
		(end 416.79114 -223.72701)
		(width 0.14478)
		(layer "In6.Cu")
		(net "M_K_CPU0_SA_DQ<23>")
	)
	(segment
		(start 437.463438 -224.110042)
		(end 437.785764 -224.110042)
		(width 0.14478)
		(layer "In6.Cu")
		(net "M_K_CPU0_SA_DQ<23>")
	)
	(segment
		(start 441.014612 -223.71939)
		(end 441.24499 -223.71939)
		(width 0.14478)
		(layer "In6.Cu")
		(net "M_K_CPU0_SA_DQ<23>")
	)
	(segment
		(start 430.4792 -223.946974)
		(end 430.4792 -223.895158)
		(width 0.14478)
		(layer "In6.Cu")
		(net "M_K_CPU0_SA_DQ<23>")
	)
	(segment
		(start 422.39946 -224.110042)
		(end 422.691306 -224.110042)
		(width 0.14478)
		(layer "In6.Cu")
		(net "M_K_CPU0_SA_DQ<23>")
	)
	(segment
		(start 422.691306 -224.110042)
		(end 422.854374 -223.946974)
		(width 0.14478)
		(layer "In6.Cu")
		(net "M_K_CPU0_SA_DQ<23>")
	)
	(segment
		(start 440.851544 -224.046542)
		(end 440.851544 -223.882458)
		(width 0.14478)
		(layer "In6.Cu")
		(net "M_K_CPU0_SA_DQ<23>")
	)
	(segment
		(start 441.408058 -223.882458)
		(end 441.408058 -223.946974)
		(width 0.14478)
		(layer "In6.Cu")
		(net "M_K_CPU0_SA_DQ<23>")
	)
	(segment
		(start 415.90849 -223.72701)
		(end 416.071558 -223.890078)
		(width 0.14478)
		(layer "In6.Cu")
		(net "M_K_CPU0_SA_DQ<23>")
	)
	(segment
		(start 439.738516 -223.946974)
		(end 439.738516 -223.882458)
		(width 0.14478)
		(layer "In6.Cu")
		(net "M_K_CPU0_SA_DQ<23>")
	)
	(segment
		(start 412.817056 -224.797112)
		(end 412.817056 -224.751138)
		(width 0.14478)
		(layer "In6.Cu")
		(net "M_K_CPU0_SA_DQ<23>")
	)
	(segment
		(start 404.564596 -232.311194)
		(end 411.91561 -224.96018)
		(width 0.14478)
		(layer "In6.Cu")
		(net "M_K_CPU0_SA_DQ<23>")
	)
	(segment
		(start 440.688476 -224.20961)
		(end 440.851544 -224.046542)
		(width 0.14478)
		(layer "In6.Cu")
		(net "M_K_CPU0_SA_DQ<23>")
	)
	(segment
		(start 422.854374 -223.890078)
		(end 423.017442 -223.72701)
		(width 0.14478)
		(layer "In6.Cu")
		(net "M_K_CPU0_SA_DQ<23>")
	)
	(segment
		(start 412.980124 -224.58807)
		(end 413.210502 -224.58807)
		(width 0.14478)
		(layer "In6.Cu")
		(net "M_K_CPU0_SA_DQ<23>")
	)
	(segment
		(start 413.37357 -224.751138)
		(end 413.37357 -224.797112)
		(width 0.14478)
		(layer "In6.Cu")
		(net "M_K_CPU0_SA_DQ<23>")
	)
	(segment
		(start 428.158402 -224.56775)
		(end 428.38878 -224.56775)
		(width 0.14478)
		(layer "In6.Cu")
		(net "M_K_CPU0_SA_DQ<23>")
	)
	(segment
		(start 401.24888 -237.81131)
		(end 404.564596 -234.495594)
		(width 0.14478)
		(layer "In6.Cu")
		(net "M_K_CPU0_SA_DQ<23>")
	)
	(segment
		(start 435.38521 -224.96018)
		(end 435.548278 -224.797112)
		(width 0.14478)
		(layer "In6.Cu")
		(net "M_K_CPU0_SA_DQ<23>")
	)
	(segment
		(start 437.948832 -223.887538)
		(end 438.1119 -223.72447)
		(width 0.14478)
		(layer "In6.Cu")
		(net "M_K_CPU0_SA_DQ<23>")
	)
	(segment
		(start 420.465758 -224.797112)
		(end 420.465758 -224.730818)
		(width 0.14478)
		(layer "In6.Cu")
		(net "M_K_CPU0_SA_DQ<23>")
	)
	(segment
		(start 420.465758 -224.730818)
		(end 420.628826 -224.56775)
		(width 0.14478)
		(layer "In6.Cu")
		(net "M_K_CPU0_SA_DQ<23>")
	)
	(segment
		(start 417.848034 -224.110042)
		(end 418.698172 -224.96018)
		(width 0.14478)
		(layer "In6.Cu")
		(net "M_K_CPU0_SA_DQ<23>")
	)
	(segment
		(start 428.551848 -224.797112)
		(end 428.714916 -224.96018)
		(width 0.14478)
		(layer "In6.Cu")
		(net "M_K_CPU0_SA_DQ<23>")
	)
	(segment
		(start 417.184586 -223.890078)
		(end 417.184586 -223.946974)
		(width 0.14478)
		(layer "In6.Cu")
		(net "M_K_CPU0_SA_DQ<23>")
	)
	(segment
		(start 430.4792 -223.895158)
		(end 430.642268 -223.73209)
		(width 0.14478)
		(layer "In6.Cu")
		(net "M_K_CPU0_SA_DQ<23>")
	)
	(segment
		(start 389.008874 -239.358678)
		(end 389.104886 -239.333278)
		(width 0.0889)
		(layer "In6.Cu")
		(net "M_K_CPU0_SA_DQ<23>")
	)
	(segment
		(start 412.653988 -224.96018)
		(end 412.817056 -224.797112)
		(width 0.14478)
		(layer "In6.Cu")
		(net "M_K_CPU0_SA_DQ<23>")
	)
	(segment
		(start 416.071558 -223.890078)
		(end 416.071558 -223.946974)
		(width 0.14478)
		(layer "In6.Cu")
		(net "M_K_CPU0_SA_DQ<23>")
	)
	(segment
		(start 413.536638 -224.96018)
		(end 414.006792 -224.96018)
		(width 0.14478)
		(layer "In6.Cu")
		(net "M_K_CPU0_SA_DQ<23>")
	)
	(segment
		(start 429.931068 -224.110042)
		(end 430.316132 -224.110042)
		(width 0.14478)
		(layer "In6.Cu")
		(net "M_K_CPU0_SA_DQ<23>")
	)
	(segment
		(start 393.911074 -239.262412)
		(end 394.168376 -239.00511)
		(width 0.0889)
		(layer "In6.Cu")
		(net "M_K_CPU0_SA_DQ<23>")
	)
	(segment
		(start 431.035714 -223.946974)
		(end 431.198782 -224.110042)
		(width 0.14478)
		(layer "In6.Cu")
		(net "M_K_CPU0_SA_DQ<23>")
	)
	(segment
		(start 428.551848 -224.730818)
		(end 428.551848 -224.797112)
		(width 0.14478)
		(layer "In6.Cu")
		(net "M_K_CPU0_SA_DQ<23>")
	)
	(segment
		(start 415.678112 -223.72701)
		(end 415.90849 -223.72701)
		(width 0.14478)
		(layer "In6.Cu")
		(net "M_K_CPU0_SA_DQ<23>")
	)
	(segment
		(start 421.549322 -224.96018)
		(end 422.39946 -224.110042)
		(width 0.14478)
		(layer "In6.Cu")
		(net "M_K_CPU0_SA_DQ<23>")
	)
	(segment
		(start 422.854374 -223.946974)
		(end 422.854374 -223.890078)
		(width 0.14478)
		(layer "In6.Cu")
		(net "M_K_CPU0_SA_DQ<23>")
	)
	(segment
		(start 426.242226 -224.96018)
		(end 427.832266 -224.96018)
		(width 0.14478)
		(layer "In6.Cu")
		(net "M_K_CPU0_SA_DQ<23>")
	)
	(segment
		(start 404.564596 -234.495594)
		(end 404.564596 -232.311194)
		(width 0.14478)
		(layer "In6.Cu")
		(net "M_K_CPU0_SA_DQ<23>")
	)
	(segment
		(start 439.575448 -224.110042)
		(end 439.738516 -223.946974)
		(width 0.14478)
		(layer "In6.Cu")
		(net "M_K_CPU0_SA_DQ<23>")
	)
	(segment
		(start 414.006792 -224.96018)
		(end 414.85693 -224.110042)
		(width 0.14478)
		(layer "In6.Cu")
		(net "M_K_CPU0_SA_DQ<23>")
	)
	(segment
		(start 393.534392 -239.262412)
		(end 393.911074 -239.262412)
		(width 0.0889)
		(layer "In6.Cu")
		(net "M_K_CPU0_SA_DQ<23>")
	)
	(segment
		(start 428.714916 -224.96018)
		(end 429.08093 -224.96018)
		(width 0.14478)
		(layer "In6.Cu")
		(net "M_K_CPU0_SA_DQ<23>")
	)
	(segment
		(start 415.351976 -224.110042)
		(end 415.515044 -223.946974)
		(width 0.14478)
		(layer "In6.Cu")
		(net "M_K_CPU0_SA_DQ<23>")
	)
	(segment
		(start 435.941724 -224.57537)
		(end 436.104792 -224.738438)
		(width 0.14478)
		(layer "In6.Cu")
		(net "M_K_CPU0_SA_DQ<23>")
	)
	(segment
		(start 423.24782 -223.72701)
		(end 423.410888 -223.890078)
		(width 0.14478)
		(layer "In6.Cu")
		(net "M_K_CPU0_SA_DQ<23>")
	)
	(segment
		(start 423.410888 -223.890078)
		(end 423.410888 -223.946974)
		(width 0.14478)
		(layer "In6.Cu")
		(net "M_K_CPU0_SA_DQ<23>")
	)
	(segment
		(start 416.465004 -224.110042)
		(end 416.628072 -223.946974)
		(width 0.14478)
		(layer "In6.Cu")
		(net "M_K_CPU0_SA_DQ<23>")
	)
	(segment
		(start 417.021518 -223.72701)
		(end 417.184586 -223.890078)
		(width 0.14478)
		(layer "In6.Cu")
		(net "M_K_CPU0_SA_DQ<23>")
	)
	(segment
		(start 417.347654 -224.110042)
		(end 417.848034 -224.110042)
		(width 0.14478)
		(layer "In6.Cu")
		(net "M_K_CPU0_SA_DQ<23>")
	)
	(segment
		(start 416.071558 -223.946974)
		(end 416.234626 -224.110042)
		(width 0.14478)
		(layer "In6.Cu")
		(net "M_K_CPU0_SA_DQ<23>")
	)
	(segment
		(start 415.515044 -223.946974)
		(end 415.515044 -223.890078)
		(width 0.14478)
		(layer "In6.Cu")
		(net "M_K_CPU0_SA_DQ<23>")
	)
	(segment
		(start 420.628826 -224.56775)
		(end 420.859204 -224.56775)
		(width 0.14478)
		(layer "In6.Cu")
		(net "M_K_CPU0_SA_DQ<23>")
	)
	(segment
		(start 430.872646 -223.73209)
		(end 431.035714 -223.895158)
		(width 0.14478)
		(layer "In6.Cu")
		(net "M_K_CPU0_SA_DQ<23>")
	)
	(segment
		(start 431.035714 -223.895158)
		(end 431.035714 -223.946974)
		(width 0.14478)
		(layer "In6.Cu")
		(net "M_K_CPU0_SA_DQ<23>")
	)
	(segment
		(start 388.85495 -239.624108)
		(end 389.008874 -239.358678)
		(width 0.0889)
		(layer "In6.Cu")
		(net "M_K_CPU0_SA_DQ<23>")
	)
	(segment
		(start 435.711346 -224.57537)
		(end 435.941724 -224.57537)
		(width 0.14478)
		(layer "In6.Cu")
		(net "M_K_CPU0_SA_DQ<23>")
	)
	(segment
		(start 415.515044 -223.890078)
		(end 415.678112 -223.72701)
		(width 0.14478)
		(layer "In6.Cu")
		(net "M_K_CPU0_SA_DQ<23>")
	)
	(segment
		(start 441.571126 -224.110042)
		(end 442.119258 -224.110042)
		(width 0.14478)
		(layer "In6.Cu")
		(net "M_K_CPU0_SA_DQ<23>")
	)
	(segment
		(start 416.628072 -223.946974)
		(end 416.628072 -223.890078)
		(width 0.14478)
		(layer "In6.Cu")
		(net "M_K_CPU0_SA_DQ<23>")
	)
	(segment
		(start 420.30269 -224.96018)
		(end 420.465758 -224.797112)
		(width 0.14478)
		(layer "In6.Cu")
		(net "M_K_CPU0_SA_DQ<23>")
	)
	(segment
		(start 395.687296 -237.81131)
		(end 395.892274 -237.81131)
		(width 0.0889)
		(layer "In6.Cu")
		(net "M_K_CPU0_SA_DQ<23>")
	)
	(segment
		(start 432.935888 -224.110042)
		(end 433.786026 -224.96018)
		(width 0.14478)
		(layer "In6.Cu")
		(net "M_K_CPU0_SA_DQ<23>")
	)
	(segment
		(start 428.38878 -224.56775)
		(end 428.551848 -224.730818)
		(width 0.14478)
		(layer "In6.Cu")
		(net "M_K_CPU0_SA_DQ<23>")
	)
	(segment
		(start 437.948832 -223.946974)
		(end 437.948832 -223.887538)
		(width 0.14478)
		(layer "In6.Cu")
		(net "M_K_CPU0_SA_DQ<23>")
	)
	(segment
		(start 440.458098 -224.20961)
		(end 440.688476 -224.20961)
		(width 0.14478)
		(layer "In6.Cu")
		(net "M_K_CPU0_SA_DQ<23>")
	)
	(segment
		(start 430.316132 -224.110042)
		(end 430.4792 -223.946974)
		(width 0.14478)
		(layer "In6.Cu")
		(net "M_K_CPU0_SA_DQ<23>")
	)
	(segment
		(start 440.851544 -223.882458)
		(end 441.014612 -223.71939)
		(width 0.14478)
		(layer "In6.Cu")
		(net "M_K_CPU0_SA_DQ<23>")
	)
	(segment
		(start 427.995334 -224.730818)
		(end 428.158402 -224.56775)
		(width 0.14478)
		(layer "In6.Cu")
		(net "M_K_CPU0_SA_DQ<23>")
	)
	(segment
		(start 435.548278 -224.797112)
		(end 435.548278 -224.738438)
		(width 0.14478)
		(layer "In6.Cu")
		(net "M_K_CPU0_SA_DQ<23>")
	)
	(segment
		(start 425.392088 -224.110042)
		(end 426.242226 -224.96018)
		(width 0.14478)
		(layer "In6.Cu")
		(net "M_K_CPU0_SA_DQ<23>")
	)
	(segment
		(start 436.104792 -224.797112)
		(end 436.26786 -224.96018)
		(width 0.14478)
		(layer "In6.Cu")
		(net "M_K_CPU0_SA_DQ<23>")
	)
	(segment
		(start 441.24499 -223.71939)
		(end 441.408058 -223.882458)
		(width 0.14478)
		(layer "In6.Cu")
		(net "M_K_CPU0_SA_DQ<23>")
	)
	(segment
		(start 439.738516 -223.882458)
		(end 439.901584 -223.71939)
		(width 0.14478)
		(layer "In6.Cu")
		(net "M_K_CPU0_SA_DQ<23>")
	)
	(segment
		(start 421.18534 -224.96018)
		(end 421.549322 -224.96018)
		(width 0.14478)
		(layer "In6.Cu")
		(net "M_K_CPU0_SA_DQ<23>")
	)
	(segment
		(start 437.785764 -224.110042)
		(end 437.948832 -223.946974)
		(width 0.14478)
		(layer "In6.Cu")
		(net "M_K_CPU0_SA_DQ<23>")
	)
	(segment
		(start 420.859204 -224.56775)
		(end 421.022272 -224.730818)
		(width 0.14478)
		(layer "In6.Cu")
		(net "M_K_CPU0_SA_DQ<23>")
	)
	(segment
		(start 394.493496 -239.00511)
		(end 395.687296 -237.81131)
		(width 0.0889)
		(layer "In6.Cu")
		(net "M_K_CPU0_SA_DQ<23>")
	)
	(segment
		(start 391.849864 -239.29467)
		(end 391.861548 -239.301528)
		(width 0.0889)
		(layer "In6.Cu")
		(net "M_K_CPU0_SA_DQ<23>")
	)
	(segment
		(start 431.198782 -224.110042)
		(end 432.935888 -224.110042)
		(width 0.14478)
		(layer "In6.Cu")
		(net "M_K_CPU0_SA_DQ<23>")
	)
	(segment
		(start 421.022272 -224.797112)
		(end 421.18534 -224.96018)
		(width 0.14478)
		(layer "In6.Cu")
		(net "M_K_CPU0_SA_DQ<23>")
	)
	(segment
		(start 423.017442 -223.72701)
		(end 423.24782 -223.72701)
		(width 0.14478)
		(layer "In6.Cu")
		(net "M_K_CPU0_SA_DQ<23>")
	)
	(segment
		(start 411.91561 -224.96018)
		(end 412.653988 -224.96018)
		(width 0.14478)
		(layer "In6.Cu")
		(net "M_K_CPU0_SA_DQ<23>")
	)
	(arc
		(start 389.616188 -239.296702)
		(mid 389.799696 -239.251208)
		(end 389.981948 -239.301528)
		(width 0.0889)
		(layer "In6.Cu")
		(net "M_K_CPU0_SA_DQ<23>")
	)
	(arc
		(start 391.871962 -239.307624)
		(mid 392.150394 -239.377722)
		(end 392.427206 -239.301528)
		(width 0.0889)
		(layer "In6.Cu")
		(net "M_K_CPU0_SA_DQ<23>")
	)
	(arc
		(start 391.48766 -239.301528)
		(mid 391.667865 -239.251211)
		(end 391.849864 -239.29467)
		(width 0.0889)
		(layer "In6.Cu")
		(net "M_K_CPU0_SA_DQ<23>")
	)
	(arc
		(start 389.981948 -239.301528)
		(mid 390.264904 -239.377705)
		(end 390.54786 -239.301528)
		(width 0.0889)
		(layer "In6.Cu")
		(net "M_K_CPU0_SA_DQ<23>")
	)
	(arc
		(start 389.104886 -239.333278)
		(mid 389.360094 -239.376755)
		(end 389.607806 -239.301528)
		(width 0.0889)
		(layer "In6.Cu")
		(net "M_K_CPU0_SA_DQ<23>")
	)
	(arc
		(start 390.54786 -239.301528)
		(mid 390.734804 -239.251273)
		(end 390.921748 -239.301528)
		(width 0.0889)
		(layer "In6.Cu")
		(net "M_K_CPU0_SA_DQ<23>")
	)
	(arc
		(start 392.801602 -239.301528)
		(mid 393.077534 -239.377785)
		(end 393.355322 -239.30864)
		(width 0.0889)
		(layer "In6.Cu")
		(net "M_K_CPU0_SA_DQ<23>")
	)
	(arc
		(start 392.43889 -239.29467)
		(mid 392.621145 -239.251017)
		(end 392.801602 -239.301528)
		(width 0.0889)
		(layer "In6.Cu")
		(net "M_K_CPU0_SA_DQ<23>")
	)
	(arc
		(start 390.921748 -239.301528)
		(mid 391.204704 -239.377705)
		(end 391.48766 -239.301528)
		(width 0.0889)
		(layer "In6.Cu")
		(net "M_K_CPU0_SA_DQ<23>")
	)
	(arc
		(start 393.355322 -239.30864)
		(mid 393.441946 -239.274234)
		(end 393.534392 -239.262412)
		(width 0.0889)
		(layer "In6.Cu")
		(net "M_K_CPU0_SA_DQ<23>")
	)
	(segment
		(start 389.798052 -239.08004)
		(end 390.264904 -238.814102)
		(width 0.10668)
		(layer "F.Cu")
		(net "M_K_CPU0_SA_DQ<22>")
	)
	(segment
		(start 430.324006 -222.246952)
		(end 430.324006 -222.188278)
		(width 0.14478)
		(layer "In6.Cu")
		(net "M_K_CPU0_SA_DQ<22>")
	)
	(segment
		(start 436.297832 -223.260158)
		(end 436.6133 -223.260158)
		(width 0.14478)
		(layer "In6.Cu")
		(net "M_K_CPU0_SA_DQ<22>")
	)
	(segment
		(start 417.848034 -222.41002)
		(end 418.698172 -223.260158)
		(width 0.14478)
		(layer "In6.Cu")
		(net "M_K_CPU0_SA_DQ<22>")
	)
	(segment
		(start 423.368978 -222.188278)
		(end 423.368978 -222.246952)
		(width 0.14478)
		(layer "In6.Cu")
		(net "M_K_CPU0_SA_DQ<22>")
	)
	(segment
		(start 420.664894 -222.87865)
		(end 420.895272 -222.87865)
		(width 0.14478)
		(layer "In6.Cu")
		(net "M_K_CPU0_SA_DQ<22>")
	)
	(segment
		(start 422.975532 -222.02521)
		(end 423.20591 -222.02521)
		(width 0.14478)
		(layer "In6.Cu")
		(net "M_K_CPU0_SA_DQ<22>")
	)
	(segment
		(start 400.871944 -236.90199)
		(end 401.119086 -236.654848)
		(width 0.14478)
		(layer "In6.Cu")
		(net "M_K_CPU0_SA_DQ<22>")
	)
	(segment
		(start 401.899374 -235.669836)
		(end 401.808696 -235.579158)
		(width 0.14478)
		(layer "In6.Cu")
		(net "M_K_CPU0_SA_DQ<22>")
	)
	(segment
		(start 401.713954 -236.05998)
		(end 401.899374 -235.87456)
		(width 0.14478)
		(layer "In6.Cu")
		(net "M_K_CPU0_SA_DQ<22>")
	)
	(segment
		(start 391.947146 -238.497618)
		(end 391.95756 -238.491522)
		(width 0.0889)
		(layer "In6.Cu")
		(net "M_K_CPU0_SA_DQ<22>")
	)
	(segment
		(start 440.218068 -222.79483)
		(end 440.448446 -222.79483)
		(width 0.14478)
		(layer "In6.Cu")
		(net "M_K_CPU0_SA_DQ<22>")
	)
	(segment
		(start 421.05834 -223.041718)
		(end 421.05834 -223.09709)
		(width 0.14478)
		(layer "In6.Cu")
		(net "M_K_CPU0_SA_DQ<22>")
	)
	(segment
		(start 440.611514 -222.188278)
		(end 440.774582 -222.02521)
		(width 0.14478)
		(layer "In6.Cu")
		(net "M_K_CPU0_SA_DQ<22>")
	)
	(segment
		(start 430.160938 -222.41002)
		(end 430.324006 -222.246952)
		(width 0.14478)
		(layer "In6.Cu")
		(net "M_K_CPU0_SA_DQ<22>")
	)
	(segment
		(start 402.289518 -235.279692)
		(end 402.494242 -235.279692)
		(width 0.14478)
		(layer "In6.Cu")
		(net "M_K_CPU0_SA_DQ<22>")
	)
	(segment
		(start 401.213828 -235.969302)
		(end 401.418552 -235.969302)
		(width 0.14478)
		(layer "In6.Cu")
		(net "M_K_CPU0_SA_DQ<22>")
	)
	(segment
		(start 430.88052 -222.188278)
		(end 430.88052 -222.246952)
		(width 0.14478)
		(layer "In6.Cu")
		(net "M_K_CPU0_SA_DQ<22>")
	)
	(segment
		(start 402.979128 -234.408726)
		(end 403.069806 -234.499404)
		(width 0.14478)
		(layer "In6.Cu")
		(net "M_K_CPU0_SA_DQ<22>")
	)
	(segment
		(start 422.649396 -222.41002)
		(end 422.812464 -222.246952)
		(width 0.14478)
		(layer "In6.Cu")
		(net "M_K_CPU0_SA_DQ<22>")
	)
	(segment
		(start 430.324006 -222.188278)
		(end 430.487074 -222.02521)
		(width 0.14478)
		(layer "In6.Cu")
		(net "M_K_CPU0_SA_DQ<22>")
	)
	(segment
		(start 394.620496 -237.45571)
		(end 395.052296 -237.45571)
		(width 0.0889)
		(layer "In6.Cu")
		(net "M_K_CPU0_SA_DQ<22>")
	)
	(segment
		(start 441.168028 -222.631762)
		(end 441.331096 -222.79483)
		(width 0.14478)
		(layer "In6.Cu")
		(net "M_K_CPU0_SA_DQ<22>")
	)
	(segment
		(start 435.57825 -223.036638)
		(end 435.741318 -222.87357)
		(width 0.14478)
		(layer "In6.Cu")
		(net "M_K_CPU0_SA_DQ<22>")
	)
	(segment
		(start 403.27453 -234.499404)
		(end 403.655276 -234.118658)
		(width 0.14478)
		(layer "In6.Cu")
		(net "M_K_CPU0_SA_DQ<22>")
	)
	(segment
		(start 441.331096 -222.79483)
		(end 441.561474 -222.79483)
		(width 0.14478)
		(layer "In6.Cu")
		(net "M_K_CPU0_SA_DQ<22>")
	)
	(segment
		(start 423.20591 -222.02521)
		(end 423.368978 -222.188278)
		(width 0.14478)
		(layer "In6.Cu")
		(net "M_K_CPU0_SA_DQ<22>")
	)
	(segment
		(start 435.741318 -222.87357)
		(end 435.971696 -222.87357)
		(width 0.14478)
		(layer "In6.Cu")
		(net "M_K_CPU0_SA_DQ<22>")
	)
	(segment
		(start 402.679662 -234.889548)
		(end 402.588984 -234.79887)
		(width 0.14478)
		(layer "In6.Cu")
		(net "M_K_CPU0_SA_DQ<22>")
	)
	(segment
		(start 415.650934 -222.183198)
		(end 415.814002 -222.02013)
		(width 0.14478)
		(layer "In6.Cu")
		(net "M_K_CPU0_SA_DQ<22>")
	)
	(segment
		(start 395.875256 -236.90199)
		(end 400.871944 -236.90199)
		(width 0.14478)
		(layer "In6.Cu")
		(net "M_K_CPU0_SA_DQ<22>")
	)
	(segment
		(start 429.08093 -223.260158)
		(end 429.931068 -222.41002)
		(width 0.14478)
		(layer "In6.Cu")
		(net "M_K_CPU0_SA_DQ<22>")
	)
	(segment
		(start 416.04438 -222.02013)
		(end 416.207448 -222.183198)
		(width 0.14478)
		(layer "In6.Cu")
		(net "M_K_CPU0_SA_DQ<22>")
	)
	(segment
		(start 401.50923 -236.05998)
		(end 401.713954 -236.05998)
		(width 0.14478)
		(layer "In6.Cu")
		(net "M_K_CPU0_SA_DQ<22>")
	)
	(segment
		(start 401.028408 -236.359446)
		(end 401.028408 -236.154722)
		(width 0.14478)
		(layer "In6.Cu")
		(net "M_K_CPU0_SA_DQ<22>")
	)
	(segment
		(start 412.084012 -223.260158)
		(end 412.773622 -223.260158)
		(width 0.14478)
		(layer "In6.Cu")
		(net "M_K_CPU0_SA_DQ<22>")
	)
	(segment
		(start 415.814002 -222.02013)
		(end 416.04438 -222.02013)
		(width 0.14478)
		(layer "In6.Cu")
		(net "M_K_CPU0_SA_DQ<22>")
	)
	(segment
		(start 401.418552 -235.969302)
		(end 401.50923 -236.05998)
		(width 0.14478)
		(layer "In6.Cu")
		(net "M_K_CPU0_SA_DQ<22>")
	)
	(segment
		(start 401.119086 -236.654848)
		(end 401.119086 -236.450124)
		(width 0.14478)
		(layer "In6.Cu")
		(net "M_K_CPU0_SA_DQ<22>")
	)
	(segment
		(start 421.05834 -223.09709)
		(end 421.221408 -223.260158)
		(width 0.14478)
		(layer "In6.Cu")
		(net "M_K_CPU0_SA_DQ<22>")
	)
	(segment
		(start 414.006792 -223.260158)
		(end 414.85693 -222.41002)
		(width 0.14478)
		(layer "In6.Cu")
		(net "M_K_CPU0_SA_DQ<22>")
	)
	(segment
		(start 433.786026 -223.260158)
		(end 435.415182 -223.260158)
		(width 0.14478)
		(layer "In6.Cu")
		(net "M_K_CPU0_SA_DQ<22>")
	)
	(segment
		(start 436.6133 -223.260158)
		(end 437.463438 -222.41002)
		(width 0.14478)
		(layer "In6.Cu")
		(net "M_K_CPU0_SA_DQ<22>")
	)
	(segment
		(start 416.370516 -222.41002)
		(end 416.600894 -222.41002)
		(width 0.14478)
		(layer "In6.Cu")
		(net "M_K_CPU0_SA_DQ<22>")
	)
	(segment
		(start 416.207448 -222.246952)
		(end 416.370516 -222.41002)
		(width 0.14478)
		(layer "In6.Cu")
		(net "M_K_CPU0_SA_DQ<22>")
	)
	(segment
		(start 422.39946 -222.41002)
		(end 422.649396 -222.41002)
		(width 0.14478)
		(layer "In6.Cu")
		(net "M_K_CPU0_SA_DQ<22>")
	)
	(segment
		(start 435.57825 -223.09709)
		(end 435.57825 -223.036638)
		(width 0.14478)
		(layer "In6.Cu")
		(net "M_K_CPU0_SA_DQ<22>")
	)
	(segment
		(start 440.448446 -222.79483)
		(end 440.611514 -222.631762)
		(width 0.14478)
		(layer "In6.Cu")
		(net "M_K_CPU0_SA_DQ<22>")
	)
	(segment
		(start 403.655276 -231.934258)
		(end 411.900878 -223.688656)
		(width 0.14478)
		(layer "In6.Cu")
		(net "M_K_CPU0_SA_DQ<22>")
	)
	(segment
		(start 440.774582 -222.02521)
		(end 441.00496 -222.02521)
		(width 0.14478)
		(layer "In6.Cu")
		(net "M_K_CPU0_SA_DQ<22>")
	)
	(segment
		(start 412.773622 -223.260158)
		(end 412.93669 -223.09709)
		(width 0.14478)
		(layer "In6.Cu")
		(net "M_K_CPU0_SA_DQ<22>")
	)
	(segment
		(start 403.069806 -234.499404)
		(end 403.27453 -234.499404)
		(width 0.14478)
		(layer "In6.Cu")
		(net "M_K_CPU0_SA_DQ<22>")
	)
	(segment
		(start 422.812464 -222.246952)
		(end 422.812464 -222.188278)
		(width 0.14478)
		(layer "In6.Cu")
		(net "M_K_CPU0_SA_DQ<22>")
	)
	(segment
		(start 402.588984 -234.594146)
		(end 402.774404 -234.408726)
		(width 0.14478)
		(layer "In6.Cu")
		(net "M_K_CPU0_SA_DQ<22>")
	)
	(segment
		(start 393.63523 -238.440976)
		(end 394.620496 -237.45571)
		(width 0.0889)
		(layer "In6.Cu")
		(net "M_K_CPU0_SA_DQ<22>")
	)
	(segment
		(start 415.650934 -222.246952)
		(end 415.650934 -222.183198)
		(width 0.14478)
		(layer "In6.Cu")
		(net "M_K_CPU0_SA_DQ<22>")
	)
	(segment
		(start 431.043588 -222.41002)
		(end 432.935888 -222.41002)
		(width 0.14478)
		(layer "In6.Cu")
		(net "M_K_CPU0_SA_DQ<22>")
	)
	(segment
		(start 390.418828 -238.548672)
		(end 390.51484 -238.523272)
		(width 0.0889)
		(layer "In6.Cu")
		(net "M_K_CPU0_SA_DQ<22>")
	)
	(segment
		(start 440.055 -222.573088)
		(end 440.055 -222.631762)
		(width 0.14478)
		(layer "In6.Cu")
		(net "M_K_CPU0_SA_DQ<22>")
	)
	(segment
		(start 430.88052 -222.246952)
		(end 431.043588 -222.41002)
		(width 0.14478)
		(layer "In6.Cu")
		(net "M_K_CPU0_SA_DQ<22>")
	)
	(segment
		(start 440.611514 -222.631762)
		(end 440.611514 -222.188278)
		(width 0.14478)
		(layer "In6.Cu")
		(net "M_K_CPU0_SA_DQ<22>")
	)
	(segment
		(start 421.549322 -223.260158)
		(end 422.39946 -222.41002)
		(width 0.14478)
		(layer "In6.Cu")
		(net "M_K_CPU0_SA_DQ<22>")
	)
	(segment
		(start 441.00496 -222.02521)
		(end 441.168028 -222.188278)
		(width 0.14478)
		(layer "In6.Cu")
		(net "M_K_CPU0_SA_DQ<22>")
	)
	(segment
		(start 426.242226 -223.260158)
		(end 429.08093 -223.260158)
		(width 0.14478)
		(layer "In6.Cu")
		(net "M_K_CPU0_SA_DQ<22>")
	)
	(segment
		(start 390.264904 -238.814102)
		(end 390.418828 -238.548672)
		(width 0.0889)
		(layer "In6.Cu")
		(net "M_K_CPU0_SA_DQ<22>")
	)
	(segment
		(start 441.561474 -222.79483)
		(end 441.724542 -222.631762)
		(width 0.14478)
		(layer "In6.Cu")
		(net "M_K_CPU0_SA_DQ<22>")
	)
	(segment
		(start 422.812464 -222.188278)
		(end 422.975532 -222.02521)
		(width 0.14478)
		(layer "In6.Cu")
		(net "M_K_CPU0_SA_DQ<22>")
	)
	(segment
		(start 421.221408 -223.260158)
		(end 421.549322 -223.260158)
		(width 0.14478)
		(layer "In6.Cu")
		(net "M_K_CPU0_SA_DQ<22>")
	)
	(segment
		(start 392.331448 -238.491522)
		(end 392.341862 -238.497618)
		(width 0.0889)
		(layer "In6.Cu")
		(net "M_K_CPU0_SA_DQ<22>")
	)
	(segment
		(start 417.320476 -222.183198)
		(end 417.320476 -222.246952)
		(width 0.14478)
		(layer "In6.Cu")
		(net "M_K_CPU0_SA_DQ<22>")
	)
	(segment
		(start 413.656272 -223.260158)
		(end 414.006792 -223.260158)
		(width 0.14478)
		(layer "In6.Cu")
		(net "M_K_CPU0_SA_DQ<22>")
	)
	(segment
		(start 435.971696 -222.87357)
		(end 436.134764 -223.036638)
		(width 0.14478)
		(layer "In6.Cu")
		(net "M_K_CPU0_SA_DQ<22>")
	)
	(segment
		(start 423.368978 -222.246952)
		(end 423.532046 -222.41002)
		(width 0.14478)
		(layer "In6.Cu")
		(net "M_K_CPU0_SA_DQ<22>")
	)
	(segment
		(start 417.320476 -222.246952)
		(end 417.483544 -222.41002)
		(width 0.14478)
		(layer "In6.Cu")
		(net "M_K_CPU0_SA_DQ<22>")
	)
	(segment
		(start 436.134764 -223.09709)
		(end 436.297832 -223.260158)
		(width 0.14478)
		(layer "In6.Cu")
		(net "M_K_CPU0_SA_DQ<22>")
	)
	(segment
		(start 401.994116 -235.189014)
		(end 402.19884 -235.189014)
		(width 0.14478)
		(layer "In6.Cu")
		(net "M_K_CPU0_SA_DQ<22>")
	)
	(segment
		(start 416.763962 -222.183198)
		(end 416.92703 -222.02013)
		(width 0.14478)
		(layer "In6.Cu")
		(net "M_K_CPU0_SA_DQ<22>")
	)
	(segment
		(start 416.600894 -222.41002)
		(end 416.763962 -222.246952)
		(width 0.14478)
		(layer "In6.Cu")
		(net "M_K_CPU0_SA_DQ<22>")
	)
	(segment
		(start 432.935888 -222.41002)
		(end 433.786026 -223.260158)
		(width 0.14478)
		(layer "In6.Cu")
		(net "M_K_CPU0_SA_DQ<22>")
	)
	(segment
		(start 416.207448 -222.183198)
		(end 416.207448 -222.246952)
		(width 0.14478)
		(layer "In6.Cu")
		(net "M_K_CPU0_SA_DQ<22>")
	)
	(segment
		(start 413.099758 -222.87357)
		(end 413.330136 -222.87357)
		(width 0.14478)
		(layer "In6.Cu")
		(net "M_K_CPU0_SA_DQ<22>")
	)
	(segment
		(start 417.157408 -222.02013)
		(end 417.320476 -222.183198)
		(width 0.14478)
		(layer "In6.Cu")
		(net "M_K_CPU0_SA_DQ<22>")
	)
	(segment
		(start 440.055 -222.631762)
		(end 440.218068 -222.79483)
		(width 0.14478)
		(layer "In6.Cu")
		(net "M_K_CPU0_SA_DQ<22>")
	)
	(segment
		(start 402.494242 -235.279692)
		(end 402.679662 -235.094272)
		(width 0.14478)
		(layer "In6.Cu")
		(net "M_K_CPU0_SA_DQ<22>")
	)
	(segment
		(start 420.501826 -223.09709)
		(end 420.501826 -223.041718)
		(width 0.14478)
		(layer "In6.Cu")
		(net "M_K_CPU0_SA_DQ<22>")
	)
	(segment
		(start 403.655276 -234.118658)
		(end 403.655276 -231.934258)
		(width 0.14478)
		(layer "In6.Cu")
		(net "M_K_CPU0_SA_DQ<22>")
	)
	(segment
		(start 417.483544 -222.41002)
		(end 417.848034 -222.41002)
		(width 0.14478)
		(layer "In6.Cu")
		(net "M_K_CPU0_SA_DQ<22>")
	)
	(segment
		(start 435.415182 -223.260158)
		(end 435.57825 -223.09709)
		(width 0.14478)
		(layer "In6.Cu")
		(net "M_K_CPU0_SA_DQ<22>")
	)
	(segment
		(start 429.931068 -222.41002)
		(end 430.160938 -222.41002)
		(width 0.14478)
		(layer "In6.Cu")
		(net "M_K_CPU0_SA_DQ<22>")
	)
	(segment
		(start 416.763962 -222.246952)
		(end 416.763962 -222.183198)
		(width 0.14478)
		(layer "In6.Cu")
		(net "M_K_CPU0_SA_DQ<22>")
	)
	(segment
		(start 402.774404 -234.408726)
		(end 402.979128 -234.408726)
		(width 0.14478)
		(layer "In6.Cu")
		(net "M_K_CPU0_SA_DQ<22>")
	)
	(segment
		(start 441.724542 -222.631762)
		(end 441.724542 -222.573088)
		(width 0.14478)
		(layer "In6.Cu")
		(net "M_K_CPU0_SA_DQ<22>")
	)
	(segment
		(start 412.93669 -223.036638)
		(end 413.099758 -222.87357)
		(width 0.14478)
		(layer "In6.Cu")
		(net "M_K_CPU0_SA_DQ<22>")
	)
	(segment
		(start 423.532046 -222.41002)
		(end 425.392088 -222.41002)
		(width 0.14478)
		(layer "In6.Cu")
		(net "M_K_CPU0_SA_DQ<22>")
	)
	(segment
		(start 393.084812 -238.440976)
		(end 393.63523 -238.440976)
		(width 0.0889)
		(layer "In6.Cu")
		(net "M_K_CPU0_SA_DQ<22>")
	)
	(segment
		(start 436.134764 -223.036638)
		(end 436.134764 -223.09709)
		(width 0.14478)
		(layer "In6.Cu")
		(net "M_K_CPU0_SA_DQ<22>")
	)
	(segment
		(start 416.92703 -222.02013)
		(end 417.157408 -222.02013)
		(width 0.14478)
		(layer "In6.Cu")
		(net "M_K_CPU0_SA_DQ<22>")
	)
	(segment
		(start 441.168028 -222.188278)
		(end 441.168028 -222.631762)
		(width 0.14478)
		(layer "In6.Cu")
		(net "M_K_CPU0_SA_DQ<22>")
	)
	(segment
		(start 420.338758 -223.260158)
		(end 420.501826 -223.09709)
		(width 0.14478)
		(layer "In6.Cu")
		(net "M_K_CPU0_SA_DQ<22>")
	)
	(segment
		(start 439.891932 -222.41002)
		(end 440.055 -222.573088)
		(width 0.14478)
		(layer "In6.Cu")
		(net "M_K_CPU0_SA_DQ<22>")
	)
	(segment
		(start 401.899374 -235.87456)
		(end 401.899374 -235.669836)
		(width 0.14478)
		(layer "In6.Cu")
		(net "M_K_CPU0_SA_DQ<22>")
	)
	(segment
		(start 437.463438 -222.41002)
		(end 439.891932 -222.41002)
		(width 0.14478)
		(layer "In6.Cu")
		(net "M_K_CPU0_SA_DQ<22>")
	)
	(segment
		(start 413.330136 -222.87357)
		(end 413.493204 -223.036638)
		(width 0.14478)
		(layer "In6.Cu")
		(net "M_K_CPU0_SA_DQ<22>")
	)
	(segment
		(start 412.93669 -223.09709)
		(end 412.93669 -223.036638)
		(width 0.14478)
		(layer "In6.Cu")
		(net "M_K_CPU0_SA_DQ<22>")
	)
	(segment
		(start 402.19884 -235.189014)
		(end 402.289518 -235.279692)
		(width 0.14478)
		(layer "In6.Cu")
		(net "M_K_CPU0_SA_DQ<22>")
	)
	(segment
		(start 413.493204 -223.036638)
		(end 413.493204 -223.09709)
		(width 0.14478)
		(layer "In6.Cu")
		(net "M_K_CPU0_SA_DQ<22>")
	)
	(segment
		(start 415.487866 -222.41002)
		(end 415.650934 -222.246952)
		(width 0.14478)
		(layer "In6.Cu")
		(net "M_K_CPU0_SA_DQ<22>")
	)
	(segment
		(start 418.698172 -223.260158)
		(end 420.338758 -223.260158)
		(width 0.14478)
		(layer "In6.Cu")
		(net "M_K_CPU0_SA_DQ<22>")
	)
	(segment
		(start 411.900878 -223.688656)
		(end 411.900878 -223.443292)
		(width 0.14478)
		(layer "In6.Cu")
		(net "M_K_CPU0_SA_DQ<22>")
	)
	(segment
		(start 414.85693 -222.41002)
		(end 415.487866 -222.41002)
		(width 0.14478)
		(layer "In6.Cu")
		(net "M_K_CPU0_SA_DQ<22>")
	)
	(segment
		(start 395.052296 -237.45571)
		(end 395.606016 -236.90199)
		(width 0.0889)
		(layer "In6.Cu")
		(net "M_K_CPU0_SA_DQ<22>")
	)
	(segment
		(start 391.01776 -238.491522)
		(end 391.026142 -238.486696)
		(width 0.0889)
		(layer "In6.Cu")
		(net "M_K_CPU0_SA_DQ<22>")
	)
	(segment
		(start 430.717452 -222.02521)
		(end 430.88052 -222.188278)
		(width 0.14478)
		(layer "In6.Cu")
		(net "M_K_CPU0_SA_DQ<22>")
	)
	(segment
		(start 441.88761 -222.41002)
		(end 442.119258 -222.41002)
		(width 0.14478)
		(layer "In6.Cu")
		(net "M_K_CPU0_SA_DQ<22>")
	)
	(segment
		(start 411.900878 -223.443292)
		(end 412.084012 -223.260158)
		(width 0.14478)
		(layer "In6.Cu")
		(net "M_K_CPU0_SA_DQ<22>")
	)
	(segment
		(start 441.724542 -222.573088)
		(end 441.88761 -222.41002)
		(width 0.14478)
		(layer "In6.Cu")
		(net "M_K_CPU0_SA_DQ<22>")
	)
	(segment
		(start 401.028408 -236.154722)
		(end 401.213828 -235.969302)
		(width 0.14478)
		(layer "In6.Cu")
		(net "M_K_CPU0_SA_DQ<22>")
	)
	(segment
		(start 395.606016 -236.90199)
		(end 395.875256 -236.90199)
		(width 0.0889)
		(layer "In6.Cu")
		(net "M_K_CPU0_SA_DQ<22>")
	)
	(segment
		(start 420.895272 -222.87865)
		(end 421.05834 -223.041718)
		(width 0.14478)
		(layer "In6.Cu")
		(net "M_K_CPU0_SA_DQ<22>")
	)
	(segment
		(start 425.392088 -222.41002)
		(end 426.242226 -223.260158)
		(width 0.14478)
		(layer "In6.Cu")
		(net "M_K_CPU0_SA_DQ<22>")
	)
	(segment
		(start 413.493204 -223.09709)
		(end 413.656272 -223.260158)
		(width 0.14478)
		(layer "In6.Cu")
		(net "M_K_CPU0_SA_DQ<22>")
	)
	(segment
		(start 442.119258 -222.41002)
		(end 442.5442 -222.834962)
		(width 0.14478)
		(layer "In6.Cu")
		(net "M_K_CPU0_SA_DQ<22>")
	)
	(segment
		(start 401.119086 -236.450124)
		(end 401.028408 -236.359446)
		(width 0.14478)
		(layer "In6.Cu")
		(net "M_K_CPU0_SA_DQ<22>")
	)
	(segment
		(start 401.808696 -235.579158)
		(end 401.808696 -235.374434)
		(width 0.14478)
		(layer "In6.Cu")
		(net "M_K_CPU0_SA_DQ<22>")
	)
	(segment
		(start 430.487074 -222.02521)
		(end 430.717452 -222.02521)
		(width 0.14478)
		(layer "In6.Cu")
		(net "M_K_CPU0_SA_DQ<22>")
	)
	(segment
		(start 402.679662 -235.094272)
		(end 402.679662 -234.889548)
		(width 0.14478)
		(layer "In6.Cu")
		(net "M_K_CPU0_SA_DQ<22>")
	)
	(segment
		(start 401.808696 -235.374434)
		(end 401.994116 -235.189014)
		(width 0.14478)
		(layer "In6.Cu")
		(net "M_K_CPU0_SA_DQ<22>")
	)
	(segment
		(start 420.501826 -223.041718)
		(end 420.664894 -222.87865)
		(width 0.14478)
		(layer "In6.Cu")
		(net "M_K_CPU0_SA_DQ<22>")
	)
	(segment
		(start 402.588984 -234.79887)
		(end 402.588984 -234.594146)
		(width 0.14478)
		(layer "In6.Cu")
		(net "M_K_CPU0_SA_DQ<22>")
	)
	(arc
		(start 391.026142 -238.486696)
		(mid 391.20965 -238.441202)
		(end 391.391902 -238.491522)
		(width 0.0889)
		(layer "In6.Cu")
		(net "M_K_CPU0_SA_DQ<22>")
	)
	(arc
		(start 392.341862 -238.497618)
		(mid 392.620548 -238.567838)
		(end 392.897614 -238.491522)
		(width 0.0889)
		(layer "In6.Cu")
		(net "M_K_CPU0_SA_DQ<22>")
	)
	(arc
		(start 390.51484 -238.523272)
		(mid 390.770048 -238.566749)
		(end 391.01776 -238.491522)
		(width 0.0889)
		(layer "In6.Cu")
		(net "M_K_CPU0_SA_DQ<22>")
	)
	(arc
		(start 391.95756 -238.491522)
		(mid 392.144504 -238.441267)
		(end 392.331448 -238.491522)
		(width 0.0889)
		(layer "In6.Cu")
		(net "M_K_CPU0_SA_DQ<22>")
	)
	(arc
		(start 391.391902 -238.491522)
		(mid 391.668715 -238.567665)
		(end 391.947146 -238.497618)
		(width 0.0889)
		(layer "In6.Cu")
		(net "M_K_CPU0_SA_DQ<22>")
	)
	(arc
		(start 392.897614 -238.491522)
		(mid 392.987874 -238.453894)
		(end 393.084812 -238.440976)
		(width 0.0889)
		(layer "In6.Cu")
		(net "M_K_CPU0_SA_DQ<22>")
	)
	(segment
		(start 388.857998 -239.08004)
		(end 389.32485 -238.814102)
		(width 0.10668)
		(layer "F.Cu")
		(net "M_K_CPU0_SA_DQ<21>")
	)
	(segment
		(start 444.367158 -223.546162)
		(end 444.367158 -223.423226)
		(width 0.14478)
		(layer "In6.Cu")
		(net "M_K_CPU0_SA_DQ<21>")
	)
	(segment
		(start 426.242226 -224.110042)
		(end 429.08093 -224.110042)
		(width 0.14478)
		(layer "In6.Cu")
		(net "M_K_CPU0_SA_DQ<21>")
	)
	(segment
		(start 432.936142 -223.260158)
		(end 433.786026 -224.110042)
		(width 0.14478)
		(layer "In6.Cu")
		(net "M_K_CPU0_SA_DQ<21>")
	)
	(segment
		(start 437.5912 -223.260158)
		(end 443.647576 -223.260158)
		(width 0.14478)
		(layer "In6.Cu")
		(net "M_K_CPU0_SA_DQ<21>")
	)
	(segment
		(start 414.896554 -223.259904)
		(end 417.848034 -223.259904)
		(width 0.14478)
		(layer "In6.Cu")
		(net "M_K_CPU0_SA_DQ<21>")
	)
	(segment
		(start 443.647576 -223.260158)
		(end 443.810644 -223.423226)
		(width 0.14478)
		(layer "In6.Cu")
		(net "M_K_CPU0_SA_DQ<21>")
	)
	(segment
		(start 391.01776 -239.136682)
		(end 391.026142 -239.141508)
		(width 0.0889)
		(layer "In6.Cu")
		(net "M_K_CPU0_SA_DQ<21>")
	)
	(segment
		(start 436.741316 -224.110042)
		(end 437.5912 -223.260158)
		(width 0.14478)
		(layer "In6.Cu")
		(net "M_K_CPU0_SA_DQ<21>")
	)
	(segment
		(start 421.549322 -224.110042)
		(end 422.399206 -223.260158)
		(width 0.14478)
		(layer "In6.Cu")
		(net "M_K_CPU0_SA_DQ<21>")
	)
	(segment
		(start 394.645896 -237.78591)
		(end 395.128496 -237.78591)
		(width 0.0889)
		(layer "In6.Cu")
		(net "M_K_CPU0_SA_DQ<21>")
	)
	(segment
		(start 443.810644 -223.423226)
		(end 443.810644 -223.546162)
		(width 0.14478)
		(layer "In6.Cu")
		(net "M_K_CPU0_SA_DQ<21>")
	)
	(segment
		(start 391.947146 -239.130586)
		(end 391.95756 -239.136682)
		(width 0.0889)
		(layer "In6.Cu")
		(net "M_K_CPU0_SA_DQ<21>")
	)
	(segment
		(start 443.810644 -223.546162)
		(end 443.973712 -223.70923)
		(width 0.14478)
		(layer "In6.Cu")
		(net "M_K_CPU0_SA_DQ<21>")
	)
	(segment
		(start 404.109936 -232.122726)
		(end 412.12262 -224.110042)
		(width 0.14478)
		(layer "In6.Cu")
		(net "M_K_CPU0_SA_DQ<21>")
	)
	(segment
		(start 389.170926 -239.079532)
		(end 389.193278 -239.162844)
		(width 0.0889)
		(layer "In6.Cu")
		(net "M_K_CPU0_SA_DQ<21>")
	)
	(segment
		(start 392.331194 -239.136682)
		(end 392.341608 -239.130586)
		(width 0.0889)
		(layer "In6.Cu")
		(net "M_K_CPU0_SA_DQ<21>")
	)
	(segment
		(start 444.367158 -223.423226)
		(end 444.530226 -223.260158)
		(width 0.14478)
		(layer "In6.Cu")
		(net "M_K_CPU0_SA_DQ<21>")
	)
	(segment
		(start 429.08093 -224.110042)
		(end 429.930814 -223.260158)
		(width 0.14478)
		(layer "In6.Cu")
		(net "M_K_CPU0_SA_DQ<21>")
	)
	(segment
		(start 401.060412 -237.35665)
		(end 404.109936 -234.307126)
		(width 0.14478)
		(layer "In6.Cu")
		(net "M_K_CPU0_SA_DQ<21>")
	)
	(segment
		(start 429.930814 -223.260158)
		(end 432.936142 -223.260158)
		(width 0.14478)
		(layer "In6.Cu")
		(net "M_K_CPU0_SA_DQ<21>")
	)
	(segment
		(start 395.875256 -237.35665)
		(end 401.060412 -237.35665)
		(width 0.14478)
		(layer "In6.Cu")
		(net "M_K_CPU0_SA_DQ<21>")
	)
	(segment
		(start 389.32485 -238.814102)
		(end 389.170926 -239.079532)
		(width 0.0889)
		(layer "In6.Cu")
		(net "M_K_CPU0_SA_DQ<21>")
	)
	(segment
		(start 444.20409 -223.70923)
		(end 444.367158 -223.546162)
		(width 0.14478)
		(layer "In6.Cu")
		(net "M_K_CPU0_SA_DQ<21>")
	)
	(segment
		(start 395.128496 -237.78591)
		(end 395.557756 -237.35665)
		(width 0.0889)
		(layer "In6.Cu")
		(net "M_K_CPU0_SA_DQ<21>")
	)
	(segment
		(start 393.534392 -239.071912)
		(end 393.784074 -239.071912)
		(width 0.0889)
		(layer "In6.Cu")
		(net "M_K_CPU0_SA_DQ<21>")
	)
	(segment
		(start 393.784074 -239.071912)
		(end 394.315696 -238.54029)
		(width 0.0889)
		(layer "In6.Cu")
		(net "M_K_CPU0_SA_DQ<21>")
	)
	(segment
		(start 414.046416 -224.110042)
		(end 414.896554 -223.259904)
		(width 0.14478)
		(layer "In6.Cu")
		(net "M_K_CPU0_SA_DQ<21>")
	)
	(segment
		(start 412.12262 -224.110042)
		(end 414.046416 -224.110042)
		(width 0.14478)
		(layer "In6.Cu")
		(net "M_K_CPU0_SA_DQ<21>")
	)
	(segment
		(start 394.315696 -238.11611)
		(end 394.645896 -237.78591)
		(width 0.0889)
		(layer "In6.Cu")
		(net "M_K_CPU0_SA_DQ<21>")
	)
	(segment
		(start 417.848034 -223.259904)
		(end 418.698172 -224.110042)
		(width 0.14478)
		(layer "In6.Cu")
		(net "M_K_CPU0_SA_DQ<21>")
	)
	(segment
		(start 390.443466 -239.141508)
		(end 390.451848 -239.136682)
		(width 0.0889)
		(layer "In6.Cu")
		(net "M_K_CPU0_SA_DQ<21>")
	)
	(segment
		(start 418.698172 -224.110042)
		(end 421.549322 -224.110042)
		(width 0.14478)
		(layer "In6.Cu")
		(net "M_K_CPU0_SA_DQ<21>")
	)
	(segment
		(start 425.392342 -223.260158)
		(end 426.242226 -224.110042)
		(width 0.14478)
		(layer "In6.Cu")
		(net "M_K_CPU0_SA_DQ<21>")
	)
	(segment
		(start 422.399206 -223.260158)
		(end 425.392342 -223.260158)
		(width 0.14478)
		(layer "In6.Cu")
		(net "M_K_CPU0_SA_DQ<21>")
	)
	(segment
		(start 391.95756 -239.136682)
		(end 391.965942 -239.141508)
		(width 0.0889)
		(layer "In6.Cu")
		(net "M_K_CPU0_SA_DQ<21>")
	)
	(segment
		(start 395.557756 -237.35665)
		(end 395.875256 -237.35665)
		(width 0.0889)
		(layer "In6.Cu")
		(net "M_K_CPU0_SA_DQ<21>")
	)
	(segment
		(start 444.530226 -223.260158)
		(end 446.219326 -223.260158)
		(width 0.14478)
		(layer "In6.Cu")
		(net "M_K_CPU0_SA_DQ<21>")
	)
	(segment
		(start 404.109936 -234.307126)
		(end 404.109936 -232.122726)
		(width 0.14478)
		(layer "In6.Cu")
		(net "M_K_CPU0_SA_DQ<21>")
	)
	(segment
		(start 394.315696 -238.54029)
		(end 394.315696 -238.11611)
		(width 0.0889)
		(layer "In6.Cu")
		(net "M_K_CPU0_SA_DQ<21>")
	)
	(segment
		(start 443.973712 -223.70923)
		(end 444.20409 -223.70923)
		(width 0.14478)
		(layer "In6.Cu")
		(net "M_K_CPU0_SA_DQ<21>")
	)
	(segment
		(start 446.219326 -223.260158)
		(end 446.644268 -223.6851)
		(width 0.14478)
		(layer "In6.Cu")
		(net "M_K_CPU0_SA_DQ<21>")
	)
	(segment
		(start 433.786026 -224.110042)
		(end 436.741316 -224.110042)
		(width 0.14478)
		(layer "In6.Cu")
		(net "M_K_CPU0_SA_DQ<21>")
	)
	(arc
		(start 390.451848 -239.136682)
		(mid 390.734804 -239.060505)
		(end 391.01776 -239.136682)
		(width 0.0889)
		(layer "In6.Cu")
		(net "M_K_CPU0_SA_DQ<21>")
	)
	(arc
		(start 389.193278 -239.162844)
		(mid 389.355467 -239.185579)
		(end 389.511794 -239.136682)
		(width 0.0889)
		(layer "In6.Cu")
		(net "M_K_CPU0_SA_DQ<21>")
	)
	(arc
		(start 392.341608 -239.130586)
		(mid 392.620294 -239.060366)
		(end 392.89736 -239.136682)
		(width 0.0889)
		(layer "In6.Cu")
		(net "M_K_CPU0_SA_DQ<21>")
	)
	(arc
		(start 393.253214 -239.146842)
		(mid 393.388889 -239.090939)
		(end 393.534392 -239.071912)
		(width 0.0889)
		(layer "In6.Cu")
		(net "M_K_CPU0_SA_DQ<21>")
	)
	(arc
		(start 392.89736 -239.136682)
		(mid 393.073988 -239.186915)
		(end 393.253214 -239.146842)
		(width 0.0889)
		(layer "In6.Cu")
		(net "M_K_CPU0_SA_DQ<21>")
	)
	(arc
		(start 391.026142 -239.141508)
		(mid 391.20965 -239.187002)
		(end 391.391902 -239.136682)
		(width 0.0889)
		(layer "In6.Cu")
		(net "M_K_CPU0_SA_DQ<21>")
	)
	(arc
		(start 391.965942 -239.141508)
		(mid 392.149196 -239.186881)
		(end 392.331194 -239.136682)
		(width 0.0889)
		(layer "In6.Cu")
		(net "M_K_CPU0_SA_DQ<21>")
	)
	(arc
		(start 390.077706 -239.136682)
		(mid 390.259957 -239.187032)
		(end 390.443466 -239.141508)
		(width 0.0889)
		(layer "In6.Cu")
		(net "M_K_CPU0_SA_DQ<21>")
	)
	(arc
		(start 391.391902 -239.136682)
		(mid 391.668715 -239.060539)
		(end 391.947146 -239.130586)
		(width 0.0889)
		(layer "In6.Cu")
		(net "M_K_CPU0_SA_DQ<21>")
	)
	(arc
		(start 389.511794 -239.136682)
		(mid 389.79475 -239.060505)
		(end 390.077706 -239.136682)
		(width 0.0889)
		(layer "In6.Cu")
		(net "M_K_CPU0_SA_DQ<21>")
	)
	(segment
		(start 390.267952 -238.270034)
		(end 390.734804 -238.004096)
		(width 0.10668)
		(layer "F.Cu")
		(net "M_K_CPU0_SA_DQ<20>")
	)
	(segment
		(start 425.40174 -221.569534)
		(end 426.251624 -222.419418)
		(width 0.14478)
		(layer "In6.Cu")
		(net "M_K_CPU0_SA_DQ<20>")
	)
	(segment
		(start 417.857432 -221.56928)
		(end 418.70757 -222.419418)
		(width 0.14478)
		(layer "In6.Cu")
		(net "M_K_CPU0_SA_DQ<20>")
	)
	(segment
		(start 391.85342 -238.331502)
		(end 391.861802 -238.326676)
		(width 0.0889)
		(layer "In6.Cu")
		(net "M_K_CPU0_SA_DQ<20>")
	)
	(segment
		(start 414.887156 -221.56928)
		(end 417.857432 -221.56928)
		(width 0.14478)
		(layer "In6.Cu")
		(net "M_K_CPU0_SA_DQ<20>")
	)
	(segment
		(start 446.219326 -221.560136)
		(end 446.644268 -221.985078)
		(width 0.14478)
		(layer "In6.Cu")
		(net "M_K_CPU0_SA_DQ<20>")
	)
	(segment
		(start 444.86703 -221.723204)
		(end 444.86703 -222.172022)
		(width 0.14478)
		(layer "In6.Cu")
		(net "M_K_CPU0_SA_DQ<20>")
	)
	(segment
		(start 392.42746 -238.326676)
		(end 392.435842 -238.331502)
		(width 0.0889)
		(layer "In6.Cu")
		(net "M_K_CPU0_SA_DQ<20>")
	)
	(segment
		(start 433.795424 -222.419418)
		(end 436.731918 -222.419418)
		(width 0.14478)
		(layer "In6.Cu")
		(net "M_K_CPU0_SA_DQ<20>")
	)
	(segment
		(start 432.94554 -221.569534)
		(end 433.795424 -222.419418)
		(width 0.14478)
		(layer "In6.Cu")
		(net "M_K_CPU0_SA_DQ<20>")
	)
	(segment
		(start 411.385258 -223.298512)
		(end 412.27375 -222.41002)
		(width 0.14478)
		(layer "In6.Cu")
		(net "M_K_CPU0_SA_DQ<20>")
	)
	(segment
		(start 422.389808 -221.569534)
		(end 425.40174 -221.569534)
		(width 0.14478)
		(layer "In6.Cu")
		(net "M_K_CPU0_SA_DQ<20>")
	)
	(segment
		(start 445.260476 -222.33509)
		(end 445.423544 -222.172022)
		(width 0.14478)
		(layer "In6.Cu")
		(net "M_K_CPU0_SA_DQ<20>")
	)
	(segment
		(start 437.581802 -221.569534)
		(end 444.71336 -221.569534)
		(width 0.14478)
		(layer "In6.Cu")
		(net "M_K_CPU0_SA_DQ<20>")
	)
	(segment
		(start 426.251624 -222.419418)
		(end 429.071532 -222.419418)
		(width 0.14478)
		(layer "In6.Cu")
		(net "M_K_CPU0_SA_DQ<20>")
	)
	(segment
		(start 414.046416 -222.41002)
		(end 414.887156 -221.56928)
		(width 0.14478)
		(layer "In6.Cu")
		(net "M_K_CPU0_SA_DQ<20>")
	)
	(segment
		(start 412.27375 -222.41002)
		(end 414.046416 -222.41002)
		(width 0.14478)
		(layer "In6.Cu")
		(net "M_K_CPU0_SA_DQ<20>")
	)
	(segment
		(start 429.921416 -221.569534)
		(end 432.94554 -221.569534)
		(width 0.14478)
		(layer "In6.Cu")
		(net "M_K_CPU0_SA_DQ<20>")
	)
	(segment
		(start 391.861802 -238.326676)
		(end 391.872216 -238.32058)
		(width 0.0889)
		(layer "In6.Cu")
		(net "M_K_CPU0_SA_DQ<20>")
	)
	(segment
		(start 390.58088 -238.269526)
		(end 390.603232 -238.352838)
		(width 0.0889)
		(layer "In6.Cu")
		(net "M_K_CPU0_SA_DQ<20>")
	)
	(segment
		(start 394.899896 -237.10011)
		(end 395.552676 -236.44733)
		(width 0.0889)
		(layer "In6.Cu")
		(net "M_K_CPU0_SA_DQ<20>")
	)
	(segment
		(start 395.886686 -236.44733)
		(end 400.04492 -236.44733)
		(width 0.14478)
		(layer "In6.Cu")
		(net "M_K_CPU0_SA_DQ<20>")
	)
	(segment
		(start 395.552676 -236.44733)
		(end 395.886686 -236.44733)
		(width 0.0889)
		(layer "In6.Cu")
		(net "M_K_CPU0_SA_DQ<20>")
	)
	(segment
		(start 400.04492 -236.44733)
		(end 403.200616 -233.291634)
		(width 0.14478)
		(layer "In6.Cu")
		(net "M_K_CPU0_SA_DQ<20>")
	)
	(segment
		(start 390.734804 -238.004096)
		(end 390.58088 -238.269526)
		(width 0.0889)
		(layer "In6.Cu")
		(net "M_K_CPU0_SA_DQ<20>")
	)
	(segment
		(start 403.200616 -233.291634)
		(end 403.200616 -231.74579)
		(width 0.14478)
		(layer "In6.Cu")
		(net "M_K_CPU0_SA_DQ<20>")
	)
	(segment
		(start 445.423544 -222.172022)
		(end 445.423544 -221.723204)
		(width 0.14478)
		(layer "In6.Cu")
		(net "M_K_CPU0_SA_DQ<20>")
	)
	(segment
		(start 445.586612 -221.560136)
		(end 446.219326 -221.560136)
		(width 0.14478)
		(layer "In6.Cu")
		(net "M_K_CPU0_SA_DQ<20>")
	)
	(segment
		(start 444.71336 -221.569534)
		(end 444.86703 -221.723204)
		(width 0.14478)
		(layer "In6.Cu")
		(net "M_K_CPU0_SA_DQ<20>")
	)
	(segment
		(start 394.651992 -237.10011)
		(end 394.899896 -237.10011)
		(width 0.0889)
		(layer "In6.Cu")
		(net "M_K_CPU0_SA_DQ<20>")
	)
	(segment
		(start 403.200616 -231.74579)
		(end 411.385258 -223.561148)
		(width 0.14478)
		(layer "In6.Cu")
		(net "M_K_CPU0_SA_DQ<20>")
	)
	(segment
		(start 445.030098 -222.33509)
		(end 445.260476 -222.33509)
		(width 0.14478)
		(layer "In6.Cu")
		(net "M_K_CPU0_SA_DQ<20>")
	)
	(segment
		(start 445.423544 -221.723204)
		(end 445.586612 -221.560136)
		(width 0.14478)
		(layer "In6.Cu")
		(net "M_K_CPU0_SA_DQ<20>")
	)
	(segment
		(start 444.86703 -222.172022)
		(end 445.030098 -222.33509)
		(width 0.14478)
		(layer "In6.Cu")
		(net "M_K_CPU0_SA_DQ<20>")
	)
	(segment
		(start 418.70757 -222.419418)
		(end 421.539924 -222.419418)
		(width 0.14478)
		(layer "In6.Cu")
		(net "M_K_CPU0_SA_DQ<20>")
	)
	(segment
		(start 436.731918 -222.419418)
		(end 437.581802 -221.569534)
		(width 0.14478)
		(layer "In6.Cu")
		(net "M_K_CPU0_SA_DQ<20>")
	)
	(segment
		(start 393.501626 -238.250476)
		(end 394.651992 -237.10011)
		(width 0.0889)
		(layer "In6.Cu")
		(net "M_K_CPU0_SA_DQ<20>")
	)
	(segment
		(start 393.084558 -238.250476)
		(end 393.501626 -238.250476)
		(width 0.0889)
		(layer "In6.Cu")
		(net "M_K_CPU0_SA_DQ<20>")
	)
	(segment
		(start 411.385258 -223.561148)
		(end 411.385258 -223.298512)
		(width 0.14478)
		(layer "In6.Cu")
		(net "M_K_CPU0_SA_DQ<20>")
	)
	(segment
		(start 429.071532 -222.419418)
		(end 429.921416 -221.569534)
		(width 0.14478)
		(layer "In6.Cu")
		(net "M_K_CPU0_SA_DQ<20>")
	)
	(segment
		(start 421.539924 -222.419418)
		(end 422.389808 -221.569534)
		(width 0.14478)
		(layer "In6.Cu")
		(net "M_K_CPU0_SA_DQ<20>")
	)
	(arc
		(start 392.435842 -238.331502)
		(mid 392.61935 -238.376996)
		(end 392.801602 -238.326676)
		(width 0.0889)
		(layer "In6.Cu")
		(net "M_K_CPU0_SA_DQ<20>")
	)
	(arc
		(start 392.801602 -238.326676)
		(mid 392.938043 -238.269876)
		(end 393.084558 -238.250476)
		(width 0.0889)
		(layer "In6.Cu")
		(net "M_K_CPU0_SA_DQ<20>")
	)
	(arc
		(start 391.48766 -238.326676)
		(mid 391.669911 -238.377026)
		(end 391.85342 -238.331502)
		(width 0.0889)
		(layer "In6.Cu")
		(net "M_K_CPU0_SA_DQ<20>")
	)
	(arc
		(start 390.603232 -238.352838)
		(mid 390.765421 -238.375573)
		(end 390.921748 -238.326676)
		(width 0.0889)
		(layer "In6.Cu")
		(net "M_K_CPU0_SA_DQ<20>")
	)
	(arc
		(start 390.921748 -238.326676)
		(mid 391.204704 -238.250499)
		(end 391.48766 -238.326676)
		(width 0.0889)
		(layer "In6.Cu")
		(net "M_K_CPU0_SA_DQ<20>")
	)
	(arc
		(start 391.872216 -238.32058)
		(mid 392.150648 -238.250482)
		(end 392.42746 -238.326676)
		(width 0.0889)
		(layer "In6.Cu")
		(net "M_K_CPU0_SA_DQ<20>")
	)
	(segment
		(start 388.857998 -226.120198)
		(end 389.32485 -225.85426)
		(width 0.10668)
		(layer "F.Cu")
		(net "M_K_CPU0_SA_DQ<1>")
	)
	(segment
		(start 392.29284 -222.959676)
		(end 392.331956 -222.936816)
		(width 0.0889)
		(layer "In6.Cu")
		(net "M_K_CPU0_SA_DQ<1>")
	)
	(segment
		(start 415.22904 -198.609966)
		(end 417.49345 -198.609966)
		(width 0.14478)
		(layer "In6.Cu")
		(net "M_K_CPU0_SA_DQ<1>")
	)
	(segment
		(start 392.972036 -222.006414)
		(end 392.972036 -221.26067)
		(width 0.0889)
		(layer "In6.Cu")
		(net "M_K_CPU0_SA_DQ<1>")
	)
	(segment
		(start 392.331956 -222.936816)
		(end 392.364722 -222.917766)
		(width 0.0889)
		(layer "In6.Cu")
		(net "M_K_CPU0_SA_DQ<1>")
	)
	(segment
		(start 391.822686 -223.769682)
		(end 391.861802 -223.746822)
		(width 0.0889)
		(layer "In6.Cu")
		(net "M_K_CPU0_SA_DQ<1>")
	)
	(segment
		(start 391.893552 -224.739962)
		(end 391.861802 -224.721674)
		(width 0.0889)
		(layer "In6.Cu")
		(net "M_K_CPU0_SA_DQ<1>")
	)
	(segment
		(start 422.157652 -198.851774)
		(end 422.740836 -198.61022)
		(width 0.14478)
		(layer "In6.Cu")
		(net "M_K_CPU0_SA_DQ<1>")
	)
	(segment
		(start 393.08532 -221.147386)
		(end 395.867636 -218.36507)
		(width 0.14478)
		(layer "In6.Cu")
		(net "M_K_CPU0_SA_DQ<1>")
	)
	(segment
		(start 434.58638 -199.460104)
		(end 435.777132 -199.460104)
		(width 0.14478)
		(layer "In6.Cu")
		(net "M_K_CPU0_SA_DQ<1>")
	)
	(segment
		(start 417.49345 -198.609966)
		(end 419.546024 -199.460104)
		(width 0.14478)
		(layer "In6.Cu")
		(net "M_K_CPU0_SA_DQ<1>")
	)
	(segment
		(start 413.176466 -199.460104)
		(end 415.22904 -198.609966)
		(width 0.14478)
		(layer "In6.Cu")
		(net "M_K_CPU0_SA_DQ<1>")
	)
	(segment
		(start 435.777132 -199.460104)
		(end 437.423306 -198.778114)
		(width 0.14478)
		(layer "In6.Cu")
		(net "M_K_CPU0_SA_DQ<1>")
	)
	(segment
		(start 429.667924 -198.87311)
		(end 430.30267 -198.61022)
		(width 0.14478)
		(layer "In6.Cu")
		(net "M_K_CPU0_SA_DQ<1>")
	)
	(segment
		(start 422.740836 -198.61022)
		(end 425.040552 -198.61022)
		(width 0.14478)
		(layer "In6.Cu")
		(net "M_K_CPU0_SA_DQ<1>")
	)
	(segment
		(start 425.040552 -198.61022)
		(end 427.092618 -199.460104)
		(width 0.14478)
		(layer "In6.Cu")
		(net "M_K_CPU0_SA_DQ<1>")
	)
	(segment
		(start 437.423306 -198.778114)
		(end 437.82869 -198.61022)
		(width 0.14478)
		(layer "In6.Cu")
		(net "M_K_CPU0_SA_DQ<1>")
	)
	(segment
		(start 391.01776 -226.17684)
		(end 391.026142 -226.181666)
		(width 0.0889)
		(layer "In6.Cu")
		(net "M_K_CPU0_SA_DQ<1>")
	)
	(segment
		(start 420.689024 -199.460104)
		(end 422.157652 -198.851774)
		(width 0.14478)
		(layer "In6.Cu")
		(net "M_K_CPU0_SA_DQ<1>")
	)
	(segment
		(start 390.443466 -226.181666)
		(end 390.451848 -226.17684)
		(width 0.0889)
		(layer "In6.Cu")
		(net "M_K_CPU0_SA_DQ<1>")
	)
	(segment
		(start 395.867636 -218.36507)
		(end 395.867636 -215.390222)
		(width 0.14478)
		(layer "In6.Cu")
		(net "M_K_CPU0_SA_DQ<1>")
	)
	(segment
		(start 428.250858 -199.460104)
		(end 429.667924 -198.87311)
		(width 0.14478)
		(layer "In6.Cu")
		(net "M_K_CPU0_SA_DQ<1>")
	)
	(segment
		(start 389.32485 -225.85426)
		(end 389.170926 -226.11969)
		(width 0.0889)
		(layer "In6.Cu")
		(net "M_K_CPU0_SA_DQ<1>")
	)
	(segment
		(start 392.972036 -221.26067)
		(end 393.08532 -221.147386)
		(width 0.0889)
		(layer "In6.Cu")
		(net "M_K_CPU0_SA_DQ<1>")
	)
	(segment
		(start 430.30267 -198.61022)
		(end 432.534314 -198.61022)
		(width 0.14478)
		(layer "In6.Cu")
		(net "M_K_CPU0_SA_DQ<1>")
	)
	(segment
		(start 395.867636 -215.390222)
		(end 411.797754 -199.460104)
		(width 0.14478)
		(layer "In6.Cu")
		(net "M_K_CPU0_SA_DQ<1>")
	)
	(segment
		(start 391.861802 -224.721674)
		(end 391.822686 -224.698814)
		(width 0.0889)
		(layer "In6.Cu")
		(net "M_K_CPU0_SA_DQ<1>")
	)
	(segment
		(start 391.861802 -225.366834)
		(end 391.893552 -225.348546)
		(width 0.0889)
		(layer "In6.Cu")
		(net "M_K_CPU0_SA_DQ<1>")
	)
	(segment
		(start 432.534314 -198.61022)
		(end 434.58638 -199.460104)
		(width 0.14478)
		(layer "In6.Cu")
		(net "M_K_CPU0_SA_DQ<1>")
	)
	(segment
		(start 427.092618 -199.460104)
		(end 428.250858 -199.460104)
		(width 0.14478)
		(layer "In6.Cu")
		(net "M_K_CPU0_SA_DQ<1>")
	)
	(segment
		(start 411.797754 -199.460104)
		(end 413.176466 -199.460104)
		(width 0.14478)
		(layer "In6.Cu")
		(net "M_K_CPU0_SA_DQ<1>")
	)
	(segment
		(start 392.762994 -222.14967)
		(end 392.80211 -222.12681)
		(width 0.0889)
		(layer "In6.Cu")
		(net "M_K_CPU0_SA_DQ<1>")
	)
	(segment
		(start 392.901678 -222.076772)
		(end 392.972036 -222.006414)
		(width 0.0889)
		(layer "In6.Cu")
		(net "M_K_CPU0_SA_DQ<1>")
	)
	(segment
		(start 391.861802 -223.746822)
		(end 391.893552 -223.728534)
		(width 0.0889)
		(layer "In6.Cu")
		(net "M_K_CPU0_SA_DQ<1>")
	)
	(segment
		(start 391.822686 -225.389694)
		(end 391.861802 -225.366834)
		(width 0.0889)
		(layer "In6.Cu")
		(net "M_K_CPU0_SA_DQ<1>")
	)
	(segment
		(start 419.546024 -199.460104)
		(end 420.689024 -199.460104)
		(width 0.14478)
		(layer "In6.Cu")
		(net "M_K_CPU0_SA_DQ<1>")
	)
	(segment
		(start 446.219326 -198.61022)
		(end 446.644268 -199.035162)
		(width 0.14478)
		(layer "In6.Cu")
		(net "M_K_CPU0_SA_DQ<1>")
	)
	(segment
		(start 389.170926 -226.11969)
		(end 389.193278 -226.203002)
		(width 0.0889)
		(layer "In6.Cu")
		(net "M_K_CPU0_SA_DQ<1>")
	)
	(segment
		(start 391.391902 -226.17684)
		(end 391.422382 -226.15906)
		(width 0.0889)
		(layer "In6.Cu")
		(net "M_K_CPU0_SA_DQ<1>")
	)
	(segment
		(start 437.82869 -198.61022)
		(end 446.219326 -198.61022)
		(width 0.14478)
		(layer "In6.Cu")
		(net "M_K_CPU0_SA_DQ<1>")
	)
	(arc
		(start 389.193278 -226.203002)
		(mid 389.355467 -226.225737)
		(end 389.511794 -226.17684)
		(width 0.0889)
		(layer "In6.Cu")
		(net "M_K_CPU0_SA_DQ<1>")
	)
	(arc
		(start 390.451848 -226.17684)
		(mid 390.734804 -226.100663)
		(end 391.01776 -226.17684)
		(width 0.0889)
		(layer "In6.Cu")
		(net "M_K_CPU0_SA_DQ<1>")
	)
	(arc
		(start 391.893552 -225.348546)
		(mid 392.04948 -225.044254)
		(end 391.893552 -224.739962)
		(width 0.0889)
		(layer "In6.Cu")
		(net "M_K_CPU0_SA_DQ<1>")
	)
	(arc
		(start 392.519662 -222.614236)
		(mid 392.584177 -222.352017)
		(end 392.762994 -222.14967)
		(width 0.0889)
		(layer "In6.Cu")
		(net "M_K_CPU0_SA_DQ<1>")
	)
	(arc
		(start 390.077706 -226.17684)
		(mid 390.259957 -226.22719)
		(end 390.443466 -226.181666)
		(width 0.0889)
		(layer "In6.Cu")
		(net "M_K_CPU0_SA_DQ<1>")
	)
	(arc
		(start 391.893552 -223.728534)
		(mid 392.008228 -223.5952)
		(end 392.049508 -223.424242)
		(width 0.0889)
		(layer "In6.Cu")
		(net "M_K_CPU0_SA_DQ<1>")
	)
	(arc
		(start 391.579354 -225.85426)
		(mid 391.643869 -225.592041)
		(end 391.822686 -225.389694)
		(width 0.0889)
		(layer "In6.Cu")
		(net "M_K_CPU0_SA_DQ<1>")
	)
	(arc
		(start 392.80211 -222.12681)
		(mid 392.851101 -222.100213)
		(end 392.901678 -222.076772)
		(width 0.0889)
		(layer "In6.Cu")
		(net "M_K_CPU0_SA_DQ<1>")
	)
	(arc
		(start 391.422382 -226.15906)
		(mid 391.537809 -226.025684)
		(end 391.579354 -225.85426)
		(width 0.0889)
		(layer "In6.Cu")
		(net "M_K_CPU0_SA_DQ<1>")
	)
	(arc
		(start 391.026142 -226.181666)
		(mid 391.20965 -226.22716)
		(end 391.391902 -226.17684)
		(width 0.0889)
		(layer "In6.Cu")
		(net "M_K_CPU0_SA_DQ<1>")
	)
	(arc
		(start 392.049508 -223.424242)
		(mid 392.114023 -223.162023)
		(end 392.29284 -222.959676)
		(width 0.0889)
		(layer "In6.Cu")
		(net "M_K_CPU0_SA_DQ<1>")
	)
	(arc
		(start 392.364722 -222.917766)
		(mid 392.478651 -222.784619)
		(end 392.519662 -222.614236)
		(width 0.0889)
		(layer "In6.Cu")
		(net "M_K_CPU0_SA_DQ<1>")
	)
	(arc
		(start 391.822686 -224.698814)
		(mid 391.579359 -224.234248)
		(end 391.822686 -223.769682)
		(width 0.0889)
		(layer "In6.Cu")
		(net "M_K_CPU0_SA_DQ<1>")
	)
	(arc
		(start 389.511794 -226.17684)
		(mid 389.79475 -226.100663)
		(end 390.077706 -226.17684)
		(width 0.0889)
		(layer "In6.Cu")
		(net "M_K_CPU0_SA_DQ<1>")
	)
	(segment
		(start 388.387844 -236.650022)
		(end 388.85495 -236.384084)
		(width 0.10668)
		(layer "F.Cu")
		(net "M_K_CPU0_SA_DQ<19>")
	)
	(segment
		(start 412.142432 -219.306648)
		(end 412.404306 -219.306648)
		(width 0.14478)
		(layer "In6.Cu")
		(net "M_K_CPU0_SA_DQ<19>")
	)
	(segment
		(start 417.838636 -218.150694)
		(end 418.688774 -219.000832)
		(width 0.14478)
		(layer "In6.Cu")
		(net "M_K_CPU0_SA_DQ<19>")
	)
	(segment
		(start 435.590188 -218.784678)
		(end 435.753256 -218.62161)
		(width 0.14478)
		(layer "In6.Cu")
		(net "M_K_CPU0_SA_DQ<19>")
	)
	(segment
		(start 388.85495 -236.384084)
		(end 389.008874 -236.118654)
		(width 0.0889)
		(layer "In6.Cu")
		(net "M_K_CPU0_SA_DQ<19>")
	)
	(segment
		(start 397.5227 -234.08513)
		(end 408.064716 -223.543114)
		(width 0.14478)
		(layer "In6.Cu")
		(net "M_K_CPU0_SA_DQ<19>")
	)
	(segment
		(start 441.50661 -218.652852)
		(end 441.669678 -218.489784)
		(width 0.14478)
		(layer "In6.Cu")
		(net "M_K_CPU0_SA_DQ<19>")
	)
	(segment
		(start 389.607806 -236.061504)
		(end 389.616188 -236.056678)
		(width 0.0889)
		(layer "In6.Cu")
		(net "M_K_CPU0_SA_DQ<19>")
	)
	(segment
		(start 429.931068 -218.160092)
		(end 430.250346 -218.160092)
		(width 0.14478)
		(layer "In6.Cu")
		(net "M_K_CPU0_SA_DQ<19>")
	)
	(segment
		(start 413.10052 -218.86545)
		(end 413.2453 -219.01023)
		(width 0.14478)
		(layer "In6.Cu")
		(net "M_K_CPU0_SA_DQ<19>")
	)
	(segment
		(start 428.773336 -219.01023)
		(end 429.08093 -219.01023)
		(width 0.14478)
		(layer "In6.Cu")
		(net "M_K_CPU0_SA_DQ<19>")
	)
	(segment
		(start 435.983634 -218.62161)
		(end 436.146702 -218.784678)
		(width 0.14478)
		(layer "In6.Cu")
		(net "M_K_CPU0_SA_DQ<19>")
	)
	(segment
		(start 439.858658 -217.941398)
		(end 440.021726 -217.77833)
		(width 0.14478)
		(layer "In6.Cu")
		(net "M_K_CPU0_SA_DQ<19>")
	)
	(segment
		(start 440.021726 -217.77833)
		(end 440.252104 -217.77833)
		(width 0.14478)
		(layer "In6.Cu")
		(net "M_K_CPU0_SA_DQ<19>")
	)
	(segment
		(start 412.549086 -218.858592)
		(end 412.693866 -218.713812)
		(width 0.14478)
		(layer "In6.Cu")
		(net "M_K_CPU0_SA_DQ<19>")
	)
	(segment
		(start 392.427206 -236.061504)
		(end 392.43889 -236.054646)
		(width 0.0889)
		(layer "In6.Cu")
		(net "M_K_CPU0_SA_DQ<19>")
	)
	(segment
		(start 428.610268 -218.784678)
		(end 428.610268 -218.847162)
		(width 0.14478)
		(layer "In6.Cu")
		(net "M_K_CPU0_SA_DQ<19>")
	)
	(segment
		(start 394.531596 -234.67441)
		(end 395.055852 -234.67441)
		(width 0.0889)
		(layer "In6.Cu")
		(net "M_K_CPU0_SA_DQ<19>")
	)
	(segment
		(start 441.113164 -218.32316)
		(end 441.113164 -218.489784)
		(width 0.14478)
		(layer "In6.Cu")
		(net "M_K_CPU0_SA_DQ<19>")
	)
	(segment
		(start 435.590188 -218.847162)
		(end 435.590188 -218.784678)
		(width 0.14478)
		(layer "In6.Cu")
		(net "M_K_CPU0_SA_DQ<19>")
	)
	(segment
		(start 417.208462 -217.931238)
		(end 417.208462 -217.997024)
		(width 0.14478)
		(layer "In6.Cu")
		(net "M_K_CPU0_SA_DQ<19>")
	)
	(segment
		(start 441.276232 -218.652852)
		(end 441.50661 -218.652852)
		(width 0.14478)
		(layer "In6.Cu")
		(net "M_K_CPU0_SA_DQ<19>")
	)
	(segment
		(start 415.53892 -217.997024)
		(end 415.53892 -217.931238)
		(width 0.14478)
		(layer "In6.Cu")
		(net "M_K_CPU0_SA_DQ<19>")
	)
	(segment
		(start 429.08093 -219.01023)
		(end 429.931068 -218.160092)
		(width 0.14478)
		(layer "In6.Cu")
		(net "M_K_CPU0_SA_DQ<19>")
	)
	(segment
		(start 428.216822 -218.62161)
		(end 428.4472 -218.62161)
		(width 0.14478)
		(layer "In6.Cu")
		(net "M_K_CPU0_SA_DQ<19>")
	)
	(segment
		(start 440.415172 -217.941398)
		(end 440.415172 -217.997024)
		(width 0.14478)
		(layer "In6.Cu")
		(net "M_K_CPU0_SA_DQ<19>")
	)
	(segment
		(start 395.920976 -234.08513)
		(end 397.5227 -234.08513)
		(width 0.14478)
		(layer "In6.Cu")
		(net "M_K_CPU0_SA_DQ<19>")
	)
	(segment
		(start 413.2453 -219.01023)
		(end 414.006792 -219.01023)
		(width 0.14478)
		(layer "In6.Cu")
		(net "M_K_CPU0_SA_DQ<19>")
	)
	(segment
		(start 427.900084 -219.000832)
		(end 428.053754 -218.847162)
		(width 0.14478)
		(layer "In6.Cu")
		(net "M_K_CPU0_SA_DQ<19>")
	)
	(segment
		(start 423.457624 -217.997024)
		(end 423.611294 -218.150694)
		(width 0.14478)
		(layer "In6.Cu")
		(net "M_K_CPU0_SA_DQ<19>")
	)
	(segment
		(start 417.208462 -217.997024)
		(end 417.362132 -218.150694)
		(width 0.14478)
		(layer "In6.Cu")
		(net "M_K_CPU0_SA_DQ<19>")
	)
	(segment
		(start 389.008874 -236.118654)
		(end 389.104886 -236.093254)
		(width 0.0889)
		(layer "In6.Cu")
		(net "M_K_CPU0_SA_DQ<19>")
	)
	(segment
		(start 436.146702 -218.847162)
		(end 436.30977 -219.01023)
		(width 0.14478)
		(layer "In6.Cu")
		(net "M_K_CPU0_SA_DQ<19>")
	)
	(segment
		(start 393.30376 -236.093508)
		(end 393.394438 -236.093508)
		(width 0.0889)
		(layer "In6.Cu")
		(net "M_K_CPU0_SA_DQ<19>")
	)
	(segment
		(start 408.064716 -223.543114)
		(end 408.064716 -222.63989)
		(width 0.14478)
		(layer "In6.Cu")
		(net "M_K_CPU0_SA_DQ<19>")
	)
	(segment
		(start 411.997652 -219.161868)
		(end 412.142432 -219.306648)
		(width 0.14478)
		(layer "In6.Cu")
		(net "M_K_CPU0_SA_DQ<19>")
	)
	(segment
		(start 428.053754 -218.784678)
		(end 428.216822 -218.62161)
		(width 0.14478)
		(layer "In6.Cu")
		(net "M_K_CPU0_SA_DQ<19>")
	)
	(segment
		(start 440.57824 -218.160092)
		(end 440.950096 -218.160092)
		(width 0.14478)
		(layer "In6.Cu")
		(net "M_K_CPU0_SA_DQ<19>")
	)
	(segment
		(start 435.436518 -219.000832)
		(end 435.590188 -218.847162)
		(width 0.14478)
		(layer "In6.Cu")
		(net "M_K_CPU0_SA_DQ<19>")
	)
	(segment
		(start 441.669678 -218.32316)
		(end 441.832746 -218.160092)
		(width 0.14478)
		(layer "In6.Cu")
		(net "M_K_CPU0_SA_DQ<19>")
	)
	(segment
		(start 430.80686 -217.77325)
		(end 430.969928 -217.936318)
		(width 0.14478)
		(layer "In6.Cu")
		(net "M_K_CPU0_SA_DQ<19>")
	)
	(segment
		(start 430.576482 -217.77325)
		(end 430.80686 -217.77325)
		(width 0.14478)
		(layer "In6.Cu")
		(net "M_K_CPU0_SA_DQ<19>")
	)
	(segment
		(start 442.119258 -218.160092)
		(end 442.5442 -218.585034)
		(width 0.14478)
		(layer "In6.Cu")
		(net "M_K_CPU0_SA_DQ<19>")
	)
	(segment
		(start 430.413414 -217.936318)
		(end 430.576482 -217.77325)
		(width 0.14478)
		(layer "In6.Cu")
		(net "M_K_CPU0_SA_DQ<19>")
	)
	(segment
		(start 412.95574 -218.713812)
		(end 413.10052 -218.858592)
		(width 0.14478)
		(layer "In6.Cu")
		(net "M_K_CPU0_SA_DQ<19>")
	)
	(segment
		(start 436.6133 -219.01023)
		(end 437.472836 -218.150694)
		(width 0.14478)
		(layer "In6.Cu")
		(net "M_K_CPU0_SA_DQ<19>")
	)
	(segment
		(start 412.404306 -219.306648)
		(end 412.549086 -219.161868)
		(width 0.14478)
		(layer "In6.Cu")
		(net "M_K_CPU0_SA_DQ<19>")
	)
	(segment
		(start 412.549086 -219.161868)
		(end 412.549086 -218.858592)
		(width 0.14478)
		(layer "In6.Cu")
		(net "M_K_CPU0_SA_DQ<19>")
	)
	(segment
		(start 435.753256 -218.62161)
		(end 435.983634 -218.62161)
		(width 0.14478)
		(layer "In6.Cu")
		(net "M_K_CPU0_SA_DQ<19>")
	)
	(segment
		(start 433.776628 -219.000832)
		(end 435.436518 -219.000832)
		(width 0.14478)
		(layer "In6.Cu")
		(net "M_K_CPU0_SA_DQ<19>")
	)
	(segment
		(start 414.85693 -218.160092)
		(end 415.375852 -218.160092)
		(width 0.14478)
		(layer "In6.Cu")
		(net "M_K_CPU0_SA_DQ<19>")
	)
	(segment
		(start 441.832746 -218.160092)
		(end 442.119258 -218.160092)
		(width 0.14478)
		(layer "In6.Cu")
		(net "M_K_CPU0_SA_DQ<19>")
	)
	(segment
		(start 430.969928 -217.936318)
		(end 430.969928 -217.997024)
		(width 0.14478)
		(layer "In6.Cu")
		(net "M_K_CPU0_SA_DQ<19>")
	)
	(segment
		(start 441.669678 -218.489784)
		(end 441.669678 -218.32316)
		(width 0.14478)
		(layer "In6.Cu")
		(net "M_K_CPU0_SA_DQ<19>")
	)
	(segment
		(start 430.969928 -217.997024)
		(end 431.123598 -218.150694)
		(width 0.14478)
		(layer "In6.Cu")
		(net "M_K_CPU0_SA_DQ<19>")
	)
	(segment
		(start 436.30977 -219.01023)
		(end 436.6133 -219.01023)
		(width 0.14478)
		(layer "In6.Cu")
		(net "M_K_CPU0_SA_DQ<19>")
	)
	(segment
		(start 423.457624 -217.931238)
		(end 423.457624 -217.997024)
		(width 0.14478)
		(layer "In6.Cu")
		(net "M_K_CPU0_SA_DQ<19>")
	)
	(segment
		(start 391.861548 -236.061504)
		(end 391.871962 -236.0676)
		(width 0.0889)
		(layer "In6.Cu")
		(net "M_K_CPU0_SA_DQ<19>")
	)
	(segment
		(start 417.045394 -217.76817)
		(end 417.208462 -217.931238)
		(width 0.14478)
		(layer "In6.Cu")
		(net "M_K_CPU0_SA_DQ<19>")
	)
	(segment
		(start 437.472836 -218.150694)
		(end 439.704988 -218.150694)
		(width 0.14478)
		(layer "In6.Cu")
		(net "M_K_CPU0_SA_DQ<19>")
	)
	(segment
		(start 422.39946 -218.160092)
		(end 422.738042 -218.160092)
		(width 0.14478)
		(layer "In6.Cu")
		(net "M_K_CPU0_SA_DQ<19>")
	)
	(segment
		(start 431.123598 -218.150694)
		(end 432.92649 -218.150694)
		(width 0.14478)
		(layer "In6.Cu")
		(net "M_K_CPU0_SA_DQ<19>")
	)
	(segment
		(start 418.688774 -219.000832)
		(end 421.55872 -219.000832)
		(width 0.14478)
		(layer "In6.Cu")
		(net "M_K_CPU0_SA_DQ<19>")
	)
	(segment
		(start 414.006792 -219.01023)
		(end 414.85693 -218.160092)
		(width 0.14478)
		(layer "In6.Cu")
		(net "M_K_CPU0_SA_DQ<19>")
	)
	(segment
		(start 441.113164 -218.489784)
		(end 441.276232 -218.652852)
		(width 0.14478)
		(layer "In6.Cu")
		(net "M_K_CPU0_SA_DQ<19>")
	)
	(segment
		(start 411.997652 -219.15501)
		(end 411.997652 -219.161868)
		(width 0.14478)
		(layer "In6.Cu")
		(net "M_K_CPU0_SA_DQ<19>")
	)
	(segment
		(start 395.055852 -234.67441)
		(end 395.645132 -234.08513)
		(width 0.0889)
		(layer "In6.Cu")
		(net "M_K_CPU0_SA_DQ<19>")
	)
	(segment
		(start 428.053754 -218.847162)
		(end 428.053754 -218.784678)
		(width 0.14478)
		(layer "In6.Cu")
		(net "M_K_CPU0_SA_DQ<19>")
	)
	(segment
		(start 440.950096 -218.160092)
		(end 441.113164 -218.32316)
		(width 0.14478)
		(layer "In6.Cu")
		(net "M_K_CPU0_SA_DQ<19>")
	)
	(segment
		(start 395.645132 -234.08513)
		(end 395.920976 -234.08513)
		(width 0.0889)
		(layer "In6.Cu")
		(net "M_K_CPU0_SA_DQ<19>")
	)
	(segment
		(start 440.252104 -217.77833)
		(end 440.415172 -217.941398)
		(width 0.14478)
		(layer "In6.Cu")
		(net "M_K_CPU0_SA_DQ<19>")
	)
	(segment
		(start 421.55872 -219.000832)
		(end 422.39946 -218.160092)
		(width 0.14478)
		(layer "In6.Cu")
		(net "M_K_CPU0_SA_DQ<19>")
	)
	(segment
		(start 439.704988 -218.150694)
		(end 439.858658 -217.997024)
		(width 0.14478)
		(layer "In6.Cu")
		(net "M_K_CPU0_SA_DQ<19>")
	)
	(segment
		(start 422.90111 -217.997024)
		(end 422.90111 -217.931238)
		(width 0.14478)
		(layer "In6.Cu")
		(net "M_K_CPU0_SA_DQ<19>")
	)
	(segment
		(start 408.064716 -222.63989)
		(end 411.694376 -219.01023)
		(width 0.14478)
		(layer "In6.Cu")
		(net "M_K_CPU0_SA_DQ<19>")
	)
	(segment
		(start 411.852872 -219.01023)
		(end 411.997652 -219.15501)
		(width 0.14478)
		(layer "In6.Cu")
		(net "M_K_CPU0_SA_DQ<19>")
	)
	(segment
		(start 423.611294 -218.150694)
		(end 425.38269 -218.150694)
		(width 0.14478)
		(layer "In6.Cu")
		(net "M_K_CPU0_SA_DQ<19>")
	)
	(segment
		(start 426.232828 -219.000832)
		(end 427.900084 -219.000832)
		(width 0.14478)
		(layer "In6.Cu")
		(net "M_K_CPU0_SA_DQ<19>")
	)
	(segment
		(start 439.858658 -217.997024)
		(end 439.858658 -217.941398)
		(width 0.14478)
		(layer "In6.Cu")
		(net "M_K_CPU0_SA_DQ<19>")
	)
	(segment
		(start 394.315696 -234.89031)
		(end 394.531596 -234.67441)
		(width 0.0889)
		(layer "In6.Cu")
		(net "M_K_CPU0_SA_DQ<19>")
	)
	(segment
		(start 391.849864 -236.054646)
		(end 391.861548 -236.061504)
		(width 0.0889)
		(layer "In6.Cu")
		(net "M_K_CPU0_SA_DQ<19>")
	)
	(segment
		(start 394.315696 -235.17225)
		(end 394.315696 -234.89031)
		(width 0.0889)
		(layer "In6.Cu")
		(net "M_K_CPU0_SA_DQ<19>")
	)
	(segment
		(start 423.294556 -217.76817)
		(end 423.457624 -217.931238)
		(width 0.14478)
		(layer "In6.Cu")
		(net "M_K_CPU0_SA_DQ<19>")
	)
	(segment
		(start 436.146702 -218.784678)
		(end 436.146702 -218.847162)
		(width 0.14478)
		(layer "In6.Cu")
		(net "M_K_CPU0_SA_DQ<19>")
	)
	(segment
		(start 423.064178 -217.76817)
		(end 423.294556 -217.76817)
		(width 0.14478)
		(layer "In6.Cu")
		(net "M_K_CPU0_SA_DQ<19>")
	)
	(segment
		(start 422.738042 -218.160092)
		(end 422.90111 -217.997024)
		(width 0.14478)
		(layer "In6.Cu")
		(net "M_K_CPU0_SA_DQ<19>")
	)
	(segment
		(start 413.10052 -218.858592)
		(end 413.10052 -218.86545)
		(width 0.14478)
		(layer "In6.Cu")
		(net "M_K_CPU0_SA_DQ<19>")
	)
	(segment
		(start 417.362132 -218.150694)
		(end 417.838636 -218.150694)
		(width 0.14478)
		(layer "In6.Cu")
		(net "M_K_CPU0_SA_DQ<19>")
	)
	(segment
		(start 422.90111 -217.931238)
		(end 423.064178 -217.76817)
		(width 0.14478)
		(layer "In6.Cu")
		(net "M_K_CPU0_SA_DQ<19>")
	)
	(segment
		(start 430.250346 -218.160092)
		(end 430.413414 -217.997024)
		(width 0.14478)
		(layer "In6.Cu")
		(net "M_K_CPU0_SA_DQ<19>")
	)
	(segment
		(start 393.394438 -236.093508)
		(end 394.315696 -235.17225)
		(width 0.0889)
		(layer "In6.Cu")
		(net "M_K_CPU0_SA_DQ<19>")
	)
	(segment
		(start 412.693866 -218.713812)
		(end 412.95574 -218.713812)
		(width 0.14478)
		(layer "In6.Cu")
		(net "M_K_CPU0_SA_DQ<19>")
	)
	(segment
		(start 428.610268 -218.847162)
		(end 428.773336 -219.01023)
		(width 0.14478)
		(layer "In6.Cu")
		(net "M_K_CPU0_SA_DQ<19>")
	)
	(segment
		(start 432.92649 -218.150694)
		(end 433.776628 -219.000832)
		(width 0.14478)
		(layer "In6.Cu")
		(net "M_K_CPU0_SA_DQ<19>")
	)
	(segment
		(start 430.413414 -217.997024)
		(end 430.413414 -217.936318)
		(width 0.14478)
		(layer "In6.Cu")
		(net "M_K_CPU0_SA_DQ<19>")
	)
	(segment
		(start 415.375852 -218.160092)
		(end 415.53892 -217.997024)
		(width 0.14478)
		(layer "In6.Cu")
		(net "M_K_CPU0_SA_DQ<19>")
	)
	(segment
		(start 411.694376 -219.01023)
		(end 411.852872 -219.01023)
		(width 0.14478)
		(layer "In6.Cu")
		(net "M_K_CPU0_SA_DQ<19>")
	)
	(segment
		(start 415.701988 -217.76817)
		(end 417.045394 -217.76817)
		(width 0.14478)
		(layer "In6.Cu")
		(net "M_K_CPU0_SA_DQ<19>")
	)
	(segment
		(start 425.38269 -218.150694)
		(end 426.232828 -219.000832)
		(width 0.14478)
		(layer "In6.Cu")
		(net "M_K_CPU0_SA_DQ<19>")
	)
	(segment
		(start 440.415172 -217.997024)
		(end 440.57824 -218.160092)
		(width 0.14478)
		(layer "In6.Cu")
		(net "M_K_CPU0_SA_DQ<19>")
	)
	(segment
		(start 428.4472 -218.62161)
		(end 428.610268 -218.784678)
		(width 0.14478)
		(layer "In6.Cu")
		(net "M_K_CPU0_SA_DQ<19>")
	)
	(segment
		(start 415.53892 -217.931238)
		(end 415.701988 -217.76817)
		(width 0.14478)
		(layer "In6.Cu")
		(net "M_K_CPU0_SA_DQ<19>")
	)
	(arc
		(start 391.48766 -236.061504)
		(mid 391.667865 -236.011187)
		(end 391.849864 -236.054646)
		(width 0.0889)
		(layer "In6.Cu")
		(net "M_K_CPU0_SA_DQ<19>")
	)
	(arc
		(start 392.801602 -236.061504)
		(mid 393.048916 -236.136664)
		(end 393.30376 -236.093508)
		(width 0.0889)
		(layer "In6.Cu")
		(net "M_K_CPU0_SA_DQ<19>")
	)
	(arc
		(start 390.54786 -236.061504)
		(mid 390.734804 -236.011249)
		(end 390.921748 -236.061504)
		(width 0.0889)
		(layer "In6.Cu")
		(net "M_K_CPU0_SA_DQ<19>")
	)
	(arc
		(start 389.616188 -236.056678)
		(mid 389.799696 -236.011184)
		(end 389.981948 -236.061504)
		(width 0.0889)
		(layer "In6.Cu")
		(net "M_K_CPU0_SA_DQ<19>")
	)
	(arc
		(start 389.104886 -236.093254)
		(mid 389.360094 -236.136731)
		(end 389.607806 -236.061504)
		(width 0.0889)
		(layer "In6.Cu")
		(net "M_K_CPU0_SA_DQ<19>")
	)
	(arc
		(start 391.871962 -236.0676)
		(mid 392.150394 -236.137698)
		(end 392.427206 -236.061504)
		(width 0.0889)
		(layer "In6.Cu")
		(net "M_K_CPU0_SA_DQ<19>")
	)
	(arc
		(start 389.981948 -236.061504)
		(mid 390.264904 -236.137681)
		(end 390.54786 -236.061504)
		(width 0.0889)
		(layer "In6.Cu")
		(net "M_K_CPU0_SA_DQ<19>")
	)
	(arc
		(start 392.43889 -236.054646)
		(mid 392.621145 -236.010993)
		(end 392.801602 -236.061504)
		(width 0.0889)
		(layer "In6.Cu")
		(net "M_K_CPU0_SA_DQ<19>")
	)
	(arc
		(start 390.921748 -236.061504)
		(mid 391.204704 -236.137681)
		(end 391.48766 -236.061504)
		(width 0.0889)
		(layer "In6.Cu")
		(net "M_K_CPU0_SA_DQ<19>")
	)
	(segment
		(start 389.798052 -235.840016)
		(end 390.264904 -235.574078)
		(width 0.10668)
		(layer "F.Cu")
		(net "M_K_CPU0_SA_DQ<18>")
	)
	(segment
		(start 413.037528 -216.91473)
		(end 413.200596 -217.077798)
		(width 0.14478)
		(layer "In6.Cu")
		(net "M_K_CPU0_SA_DQ<18>")
	)
	(segment
		(start 435.60111 -217.14714)
		(end 435.60111 -217.080338)
		(width 0.14478)
		(layer "In6.Cu")
		(net "M_K_CPU0_SA_DQ<18>")
	)
	(segment
		(start 437.463438 -216.46007)
		(end 439.659014 -216.46007)
		(width 0.14478)
		(layer "In6.Cu")
		(net "M_K_CPU0_SA_DQ<18>")
	)
	(segment
		(start 440.215528 -216.84107)
		(end 440.378596 -216.678002)
		(width 0.14478)
		(layer "In6.Cu")
		(net "M_K_CPU0_SA_DQ<18>")
	)
	(segment
		(start 393.352782 -235.200952)
		(end 394.450824 -234.10291)
		(width 0.0889)
		(layer "In6.Cu")
		(net "M_K_CPU0_SA_DQ<18>")
	)
	(segment
		(start 432.935888 -216.46007)
		(end 433.786026 -217.310208)
		(width 0.14478)
		(layer "In6.Cu")
		(net "M_K_CPU0_SA_DQ<18>")
	)
	(segment
		(start 416.206686 -216.079832)
		(end 416.351466 -216.224612)
		(width 0.14478)
		(layer "In6.Cu")
		(net "M_K_CPU0_SA_DQ<18>")
	)
	(segment
		(start 431.011838 -216.234518)
		(end 431.011838 -216.297002)
		(width 0.14478)
		(layer "In6.Cu")
		(net "M_K_CPU0_SA_DQ<18>")
	)
	(segment
		(start 391.947146 -235.257594)
		(end 391.95756 -235.251498)
		(width 0.0889)
		(layer "In6.Cu")
		(net "M_K_CPU0_SA_DQ<18>")
	)
	(segment
		(start 420.943024 -216.91981)
		(end 421.106092 -217.082878)
		(width 0.14478)
		(layer "In6.Cu")
		(net "M_K_CPU0_SA_DQ<18>")
	)
	(segment
		(start 423.271696 -216.07145)
		(end 423.434764 -216.234518)
		(width 0.14478)
		(layer "In6.Cu")
		(net "M_K_CPU0_SA_DQ<18>")
	)
	(segment
		(start 423.434764 -216.234518)
		(end 423.434764 -216.297002)
		(width 0.14478)
		(layer "In6.Cu")
		(net "M_K_CPU0_SA_DQ<18>")
	)
	(segment
		(start 412.035498 -217.310208)
		(end 412.481014 -217.310208)
		(width 0.14478)
		(layer "In6.Cu")
		(net "M_K_CPU0_SA_DQ<18>")
	)
	(segment
		(start 416.351466 -216.31529)
		(end 416.496246 -216.46007)
		(width 0.14478)
		(layer "In6.Cu")
		(net "M_K_CPU0_SA_DQ<18>")
	)
	(segment
		(start 412.481014 -217.310208)
		(end 412.644082 -217.14714)
		(width 0.14478)
		(layer "In6.Cu")
		(net "M_K_CPU0_SA_DQ<18>")
	)
	(segment
		(start 393.084812 -235.200952)
		(end 393.352782 -235.200952)
		(width 0.0889)
		(layer "In6.Cu")
		(net "M_K_CPU0_SA_DQ<18>")
	)
	(segment
		(start 428.07763 -217.077798)
		(end 428.240698 -216.91473)
		(width 0.14478)
		(layer "In6.Cu")
		(net "M_K_CPU0_SA_DQ<18>")
	)
	(segment
		(start 436.6133 -217.310208)
		(end 437.463438 -216.46007)
		(width 0.14478)
		(layer "In6.Cu")
		(net "M_K_CPU0_SA_DQ<18>")
	)
	(segment
		(start 442.119258 -216.46007)
		(end 442.5442 -216.885012)
		(width 0.14478)
		(layer "In6.Cu")
		(net "M_K_CPU0_SA_DQ<18>")
	)
	(segment
		(start 435.60111 -217.080338)
		(end 435.764178 -216.91727)
		(width 0.14478)
		(layer "In6.Cu")
		(net "M_K_CPU0_SA_DQ<18>")
	)
	(segment
		(start 407.155396 -223.166178)
		(end 407.155396 -222.19031)
		(width 0.14478)
		(layer "In6.Cu")
		(net "M_K_CPU0_SA_DQ<18>")
	)
	(segment
		(start 423.041318 -216.07145)
		(end 423.271696 -216.07145)
		(width 0.14478)
		(layer "In6.Cu")
		(net "M_K_CPU0_SA_DQ<18>")
	)
	(segment
		(start 430.84877 -216.07145)
		(end 431.011838 -216.234518)
		(width 0.14478)
		(layer "In6.Cu")
		(net "M_K_CPU0_SA_DQ<18>")
	)
	(segment
		(start 440.93511 -216.678002)
		(end 441.098178 -216.84107)
		(width 0.14478)
		(layer "In6.Cu")
		(net "M_K_CPU0_SA_DQ<18>")
	)
	(segment
		(start 416.9029 -216.31529)
		(end 416.9029 -216.224612)
		(width 0.14478)
		(layer "In6.Cu")
		(net "M_K_CPU0_SA_DQ<18>")
	)
	(segment
		(start 433.786026 -217.310208)
		(end 435.438042 -217.310208)
		(width 0.14478)
		(layer "In6.Cu")
		(net "M_K_CPU0_SA_DQ<18>")
	)
	(segment
		(start 435.764178 -216.91727)
		(end 435.994556 -216.91727)
		(width 0.14478)
		(layer "In6.Cu")
		(net "M_K_CPU0_SA_DQ<18>")
	)
	(segment
		(start 421.106092 -217.082878)
		(end 421.106092 -217.14714)
		(width 0.14478)
		(layer "In6.Cu")
		(net "M_K_CPU0_SA_DQ<18>")
	)
	(segment
		(start 440.378596 -216.242138)
		(end 440.541664 -216.07907)
		(width 0.14478)
		(layer "In6.Cu")
		(net "M_K_CPU0_SA_DQ<18>")
	)
	(segment
		(start 428.797212 -217.310208)
		(end 429.08093 -217.310208)
		(width 0.14478)
		(layer "In6.Cu")
		(net "M_K_CPU0_SA_DQ<18>")
	)
	(segment
		(start 431.011838 -216.297002)
		(end 431.174906 -216.46007)
		(width 0.14478)
		(layer "In6.Cu")
		(net "M_K_CPU0_SA_DQ<18>")
	)
	(segment
		(start 414.006792 -217.310208)
		(end 414.85693 -216.46007)
		(width 0.14478)
		(layer "In6.Cu")
		(net "M_K_CPU0_SA_DQ<18>")
	)
	(segment
		(start 428.240698 -216.91473)
		(end 428.471076 -216.91473)
		(width 0.14478)
		(layer "In6.Cu")
		(net "M_K_CPU0_SA_DQ<18>")
	)
	(segment
		(start 440.772042 -216.07907)
		(end 440.93511 -216.242138)
		(width 0.14478)
		(layer "In6.Cu")
		(net "M_K_CPU0_SA_DQ<18>")
	)
	(segment
		(start 428.07763 -217.14714)
		(end 428.07763 -217.077798)
		(width 0.14478)
		(layer "In6.Cu")
		(net "M_K_CPU0_SA_DQ<18>")
	)
	(segment
		(start 440.541664 -216.07907)
		(end 440.772042 -216.07907)
		(width 0.14478)
		(layer "In6.Cu")
		(net "M_K_CPU0_SA_DQ<18>")
	)
	(segment
		(start 417.309554 -216.079832)
		(end 417.454334 -216.224612)
		(width 0.14478)
		(layer "In6.Cu")
		(net "M_K_CPU0_SA_DQ<18>")
	)
	(segment
		(start 426.242226 -217.310208)
		(end 427.914562 -217.310208)
		(width 0.14478)
		(layer "In6.Cu")
		(net "M_K_CPU0_SA_DQ<18>")
	)
	(segment
		(start 412.644082 -217.077798)
		(end 412.80715 -216.91473)
		(width 0.14478)
		(layer "In6.Cu")
		(net "M_K_CPU0_SA_DQ<18>")
	)
	(segment
		(start 428.634144 -217.14714)
		(end 428.797212 -217.310208)
		(width 0.14478)
		(layer "In6.Cu")
		(net "M_K_CPU0_SA_DQ<18>")
	)
	(segment
		(start 423.597832 -216.46007)
		(end 425.392088 -216.46007)
		(width 0.14478)
		(layer "In6.Cu")
		(net "M_K_CPU0_SA_DQ<18>")
	)
	(segment
		(start 413.200596 -217.14714)
		(end 413.363664 -217.310208)
		(width 0.14478)
		(layer "In6.Cu")
		(net "M_K_CPU0_SA_DQ<18>")
	)
	(segment
		(start 417.454334 -216.224612)
		(end 417.454334 -216.31529)
		(width 0.14478)
		(layer "In6.Cu")
		(net "M_K_CPU0_SA_DQ<18>")
	)
	(segment
		(start 421.106092 -217.14714)
		(end 421.26916 -217.310208)
		(width 0.14478)
		(layer "In6.Cu")
		(net "M_K_CPU0_SA_DQ<18>")
	)
	(segment
		(start 429.08093 -217.310208)
		(end 429.931068 -216.46007)
		(width 0.14478)
		(layer "In6.Cu")
		(net "M_K_CPU0_SA_DQ<18>")
	)
	(segment
		(start 415.800032 -216.31529)
		(end 415.800032 -216.224612)
		(width 0.14478)
		(layer "In6.Cu")
		(net "M_K_CPU0_SA_DQ<18>")
	)
	(segment
		(start 417.454334 -216.31529)
		(end 417.599114 -216.46007)
		(width 0.14478)
		(layer "In6.Cu")
		(net "M_K_CPU0_SA_DQ<18>")
	)
	(segment
		(start 394.806424 -234.10291)
		(end 395.733524 -233.17581)
		(width 0.0889)
		(layer "In6.Cu")
		(net "M_K_CPU0_SA_DQ<18>")
	)
	(segment
		(start 439.822082 -216.678002)
		(end 439.98515 -216.84107)
		(width 0.14478)
		(layer "In6.Cu")
		(net "M_K_CPU0_SA_DQ<18>")
	)
	(segment
		(start 397.145764 -233.17581)
		(end 407.155396 -223.166178)
		(width 0.14478)
		(layer "In6.Cu")
		(net "M_K_CPU0_SA_DQ<18>")
	)
	(segment
		(start 390.264904 -235.574078)
		(end 390.418828 -235.308648)
		(width 0.0889)
		(layer "In6.Cu")
		(net "M_K_CPU0_SA_DQ<18>")
	)
	(segment
		(start 391.01776 -235.251498)
		(end 391.026142 -235.246672)
		(width 0.0889)
		(layer "In6.Cu")
		(net "M_K_CPU0_SA_DQ<18>")
	)
	(segment
		(start 412.80715 -216.91473)
		(end 413.037528 -216.91473)
		(width 0.14478)
		(layer "In6.Cu")
		(net "M_K_CPU0_SA_DQ<18>")
	)
	(segment
		(start 417.599114 -216.46007)
		(end 417.848034 -216.46007)
		(width 0.14478)
		(layer "In6.Cu")
		(net "M_K_CPU0_SA_DQ<18>")
	)
	(segment
		(start 407.155396 -222.19031)
		(end 412.035498 -217.310208)
		(width 0.14478)
		(layer "In6.Cu")
		(net "M_K_CPU0_SA_DQ<18>")
	)
	(segment
		(start 416.75812 -216.46007)
		(end 416.9029 -216.31529)
		(width 0.14478)
		(layer "In6.Cu")
		(net "M_K_CPU0_SA_DQ<18>")
	)
	(segment
		(start 392.331448 -235.251498)
		(end 392.341862 -235.257594)
		(width 0.0889)
		(layer "In6.Cu")
		(net "M_K_CPU0_SA_DQ<18>")
	)
	(segment
		(start 430.455324 -216.234518)
		(end 430.618392 -216.07145)
		(width 0.14478)
		(layer "In6.Cu")
		(net "M_K_CPU0_SA_DQ<18>")
	)
	(segment
		(start 412.644082 -217.14714)
		(end 412.644082 -217.077798)
		(width 0.14478)
		(layer "In6.Cu")
		(net "M_K_CPU0_SA_DQ<18>")
	)
	(segment
		(start 436.320692 -217.310208)
		(end 436.6133 -217.310208)
		(width 0.14478)
		(layer "In6.Cu")
		(net "M_K_CPU0_SA_DQ<18>")
	)
	(segment
		(start 441.491624 -216.623138)
		(end 441.654692 -216.46007)
		(width 0.14478)
		(layer "In6.Cu")
		(net "M_K_CPU0_SA_DQ<18>")
	)
	(segment
		(start 422.87825 -216.297002)
		(end 422.87825 -216.234518)
		(width 0.14478)
		(layer "In6.Cu")
		(net "M_K_CPU0_SA_DQ<18>")
	)
	(segment
		(start 439.659014 -216.46007)
		(end 439.822082 -216.623138)
		(width 0.14478)
		(layer "In6.Cu")
		(net "M_K_CPU0_SA_DQ<18>")
	)
	(segment
		(start 415.655252 -216.46007)
		(end 415.800032 -216.31529)
		(width 0.14478)
		(layer "In6.Cu")
		(net "M_K_CPU0_SA_DQ<18>")
	)
	(segment
		(start 436.157624 -217.14714)
		(end 436.320692 -217.310208)
		(width 0.14478)
		(layer "In6.Cu")
		(net "M_K_CPU0_SA_DQ<18>")
	)
	(segment
		(start 435.994556 -216.91727)
		(end 436.157624 -217.080338)
		(width 0.14478)
		(layer "In6.Cu")
		(net "M_K_CPU0_SA_DQ<18>")
	)
	(segment
		(start 422.715182 -216.46007)
		(end 422.87825 -216.297002)
		(width 0.14478)
		(layer "In6.Cu")
		(net "M_K_CPU0_SA_DQ<18>")
	)
	(segment
		(start 421.549322 -217.310208)
		(end 422.39946 -216.46007)
		(width 0.14478)
		(layer "In6.Cu")
		(net "M_K_CPU0_SA_DQ<18>")
	)
	(segment
		(start 415.944812 -216.079832)
		(end 416.206686 -216.079832)
		(width 0.14478)
		(layer "In6.Cu")
		(net "M_K_CPU0_SA_DQ<18>")
	)
	(segment
		(start 420.549578 -217.082878)
		(end 420.712646 -216.91981)
		(width 0.14478)
		(layer "In6.Cu")
		(net "M_K_CPU0_SA_DQ<18>")
	)
	(segment
		(start 395.892274 -233.17581)
		(end 397.145764 -233.17581)
		(width 0.14478)
		(layer "In6.Cu")
		(net "M_K_CPU0_SA_DQ<18>")
	)
	(segment
		(start 425.392088 -216.46007)
		(end 426.242226 -217.310208)
		(width 0.14478)
		(layer "In6.Cu")
		(net "M_K_CPU0_SA_DQ<18>")
	)
	(segment
		(start 439.98515 -216.84107)
		(end 440.215528 -216.84107)
		(width 0.14478)
		(layer "In6.Cu")
		(net "M_K_CPU0_SA_DQ<18>")
	)
	(segment
		(start 414.85693 -216.46007)
		(end 415.655252 -216.46007)
		(width 0.14478)
		(layer "In6.Cu")
		(net "M_K_CPU0_SA_DQ<18>")
	)
	(segment
		(start 440.93511 -216.242138)
		(end 440.93511 -216.678002)
		(width 0.14478)
		(layer "In6.Cu")
		(net "M_K_CPU0_SA_DQ<18>")
	)
	(segment
		(start 417.04768 -216.079832)
		(end 417.309554 -216.079832)
		(width 0.14478)
		(layer "In6.Cu")
		(net "M_K_CPU0_SA_DQ<18>")
	)
	(segment
		(start 415.800032 -216.224612)
		(end 415.944812 -216.079832)
		(width 0.14478)
		(layer "In6.Cu")
		(net "M_K_CPU0_SA_DQ<18>")
	)
	(segment
		(start 441.098178 -216.84107)
		(end 441.328556 -216.84107)
		(width 0.14478)
		(layer "In6.Cu")
		(net "M_K_CPU0_SA_DQ<18>")
	)
	(segment
		(start 423.434764 -216.297002)
		(end 423.597832 -216.46007)
		(width 0.14478)
		(layer "In6.Cu")
		(net "M_K_CPU0_SA_DQ<18>")
	)
	(segment
		(start 422.39946 -216.46007)
		(end 422.715182 -216.46007)
		(width 0.14478)
		(layer "In6.Cu")
		(net "M_K_CPU0_SA_DQ<18>")
	)
	(segment
		(start 420.549578 -217.14714)
		(end 420.549578 -217.082878)
		(width 0.14478)
		(layer "In6.Cu")
		(net "M_K_CPU0_SA_DQ<18>")
	)
	(segment
		(start 394.450824 -234.10291)
		(end 394.806424 -234.10291)
		(width 0.0889)
		(layer "In6.Cu")
		(net "M_K_CPU0_SA_DQ<18>")
	)
	(segment
		(start 418.698172 -217.310208)
		(end 420.38651 -217.310208)
		(width 0.14478)
		(layer "In6.Cu")
		(net "M_K_CPU0_SA_DQ<18>")
	)
	(segment
		(start 417.848034 -216.46007)
		(end 418.698172 -217.310208)
		(width 0.14478)
		(layer "In6.Cu")
		(net "M_K_CPU0_SA_DQ<18>")
	)
	(segment
		(start 413.200596 -217.077798)
		(end 413.200596 -217.14714)
		(width 0.14478)
		(layer "In6.Cu")
		(net "M_K_CPU0_SA_DQ<18>")
	)
	(segment
		(start 427.914562 -217.310208)
		(end 428.07763 -217.14714)
		(width 0.14478)
		(layer "In6.Cu")
		(net "M_K_CPU0_SA_DQ<18>")
	)
	(segment
		(start 440.378596 -216.678002)
		(end 440.378596 -216.242138)
		(width 0.14478)
		(layer "In6.Cu")
		(net "M_K_CPU0_SA_DQ<18>")
	)
	(segment
		(start 429.931068 -216.46007)
		(end 430.292256 -216.46007)
		(width 0.14478)
		(layer "In6.Cu")
		(net "M_K_CPU0_SA_DQ<18>")
	)
	(segment
		(start 395.733524 -233.17581)
		(end 395.892274 -233.17581)
		(width 0.0889)
		(layer "In6.Cu")
		(net "M_K_CPU0_SA_DQ<18>")
	)
	(segment
		(start 436.157624 -217.080338)
		(end 436.157624 -217.14714)
		(width 0.14478)
		(layer "In6.Cu")
		(net "M_K_CPU0_SA_DQ<18>")
	)
	(segment
		(start 390.418828 -235.308648)
		(end 390.51484 -235.283248)
		(width 0.0889)
		(layer "In6.Cu")
		(net "M_K_CPU0_SA_DQ<18>")
	)
	(segment
		(start 416.496246 -216.46007)
		(end 416.75812 -216.46007)
		(width 0.14478)
		(layer "In6.Cu")
		(net "M_K_CPU0_SA_DQ<18>")
	)
	(segment
		(start 430.292256 -216.46007)
		(end 430.455324 -216.297002)
		(width 0.14478)
		(layer "In6.Cu")
		(net "M_K_CPU0_SA_DQ<18>")
	)
	(segment
		(start 420.712646 -216.91981)
		(end 420.943024 -216.91981)
		(width 0.14478)
		(layer "In6.Cu")
		(net "M_K_CPU0_SA_DQ<18>")
	)
	(segment
		(start 431.174906 -216.46007)
		(end 432.935888 -216.46007)
		(width 0.14478)
		(layer "In6.Cu")
		(net "M_K_CPU0_SA_DQ<18>")
	)
	(segment
		(start 441.328556 -216.84107)
		(end 441.491624 -216.678002)
		(width 0.14478)
		(layer "In6.Cu")
		(net "M_K_CPU0_SA_DQ<18>")
	)
	(segment
		(start 416.9029 -216.224612)
		(end 417.04768 -216.079832)
		(width 0.14478)
		(layer "In6.Cu")
		(net "M_K_CPU0_SA_DQ<18>")
	)
	(segment
		(start 420.38651 -217.310208)
		(end 420.549578 -217.14714)
		(width 0.14478)
		(layer "In6.Cu")
		(net "M_K_CPU0_SA_DQ<18>")
	)
	(segment
		(start 428.634144 -217.077798)
		(end 428.634144 -217.14714)
		(width 0.14478)
		(layer "In6.Cu")
		(net "M_K_CPU0_SA_DQ<18>")
	)
	(segment
		(start 421.26916 -217.310208)
		(end 421.549322 -217.310208)
		(width 0.14478)
		(layer "In6.Cu")
		(net "M_K_CPU0_SA_DQ<18>")
	)
	(segment
		(start 428.471076 -216.91473)
		(end 428.634144 -217.077798)
		(width 0.14478)
		(layer "In6.Cu")
		(net "M_K_CPU0_SA_DQ<18>")
	)
	(segment
		(start 435.438042 -217.310208)
		(end 435.60111 -217.14714)
		(width 0.14478)
		(layer "In6.Cu")
		(net "M_K_CPU0_SA_DQ<18>")
	)
	(segment
		(start 422.87825 -216.234518)
		(end 423.041318 -216.07145)
		(width 0.14478)
		(layer "In6.Cu")
		(net "M_K_CPU0_SA_DQ<18>")
	)
	(segment
		(start 441.491624 -216.678002)
		(end 441.491624 -216.623138)
		(width 0.14478)
		(layer "In6.Cu")
		(net "M_K_CPU0_SA_DQ<18>")
	)
	(segment
		(start 416.351466 -216.224612)
		(end 416.351466 -216.31529)
		(width 0.14478)
		(layer "In6.Cu")
		(net "M_K_CPU0_SA_DQ<18>")
	)
	(segment
		(start 430.618392 -216.07145)
		(end 430.84877 -216.07145)
		(width 0.14478)
		(layer "In6.Cu")
		(net "M_K_CPU0_SA_DQ<18>")
	)
	(segment
		(start 441.654692 -216.46007)
		(end 442.119258 -216.46007)
		(width 0.14478)
		(layer "In6.Cu")
		(net "M_K_CPU0_SA_DQ<18>")
	)
	(segment
		(start 413.363664 -217.310208)
		(end 414.006792 -217.310208)
		(width 0.14478)
		(layer "In6.Cu")
		(net "M_K_CPU0_SA_DQ<18>")
	)
	(segment
		(start 430.455324 -216.297002)
		(end 430.455324 -216.234518)
		(width 0.14478)
		(layer "In6.Cu")
		(net "M_K_CPU0_SA_DQ<18>")
	)
	(segment
		(start 439.822082 -216.623138)
		(end 439.822082 -216.678002)
		(width 0.14478)
		(layer "In6.Cu")
		(net "M_K_CPU0_SA_DQ<18>")
	)
	(arc
		(start 391.026142 -235.246672)
		(mid 391.20965 -235.201178)
		(end 391.391902 -235.251498)
		(width 0.0889)
		(layer "In6.Cu")
		(net "M_K_CPU0_SA_DQ<18>")
	)
	(arc
		(start 391.391902 -235.251498)
		(mid 391.668715 -235.327641)
		(end 391.947146 -235.257594)
		(width 0.0889)
		(layer "In6.Cu")
		(net "M_K_CPU0_SA_DQ<18>")
	)
	(arc
		(start 391.95756 -235.251498)
		(mid 392.144504 -235.201243)
		(end 392.331448 -235.251498)
		(width 0.0889)
		(layer "In6.Cu")
		(net "M_K_CPU0_SA_DQ<18>")
	)
	(arc
		(start 392.897614 -235.251498)
		(mid 392.987874 -235.21387)
		(end 393.084812 -235.200952)
		(width 0.0889)
		(layer "In6.Cu")
		(net "M_K_CPU0_SA_DQ<18>")
	)
	(arc
		(start 392.341862 -235.257594)
		(mid 392.620548 -235.327814)
		(end 392.897614 -235.251498)
		(width 0.0889)
		(layer "In6.Cu")
		(net "M_K_CPU0_SA_DQ<18>")
	)
	(arc
		(start 390.51484 -235.283248)
		(mid 390.770048 -235.326725)
		(end 391.01776 -235.251498)
		(width 0.0889)
		(layer "In6.Cu")
		(net "M_K_CPU0_SA_DQ<18>")
	)
	(segment
		(start 388.857998 -235.840016)
		(end 389.32485 -235.574078)
		(width 0.10668)
		(layer "F.Cu")
		(net "M_K_CPU0_SA_DQ<17>")
	)
	(segment
		(start 430.288954 -217.310208)
		(end 432.550824 -217.310208)
		(width 0.14478)
		(layer "In6.Cu")
		(net "M_K_CPU0_SA_DQ<17>")
	)
	(segment
		(start 392.331194 -235.896658)
		(end 392.341608 -235.890562)
		(width 0.0889)
		(layer "In6.Cu")
		(net "M_K_CPU0_SA_DQ<17>")
	)
	(segment
		(start 397.334232 -233.63047)
		(end 407.610056 -223.354646)
		(width 0.14478)
		(layer "In6.Cu")
		(net "M_K_CPU0_SA_DQ<17>")
	)
	(segment
		(start 393.271502 -235.896404)
		(end 393.329922 -235.86186)
		(width 0.0889)
		(layer "In6.Cu")
		(net "M_K_CPU0_SA_DQ<17>")
	)
	(segment
		(start 429.677576 -217.563446)
		(end 430.288954 -217.310208)
		(width 0.14478)
		(layer "In6.Cu")
		(net "M_K_CPU0_SA_DQ<17>")
	)
	(segment
		(start 425.392342 -217.310208)
		(end 426.242226 -218.160092)
		(width 0.14478)
		(layer "In6.Cu")
		(net "M_K_CPU0_SA_DQ<17>")
	)
	(segment
		(start 394.112496 -235.079286)
		(end 394.112496 -234.76331)
		(width 0.0889)
		(layer "In6.Cu")
		(net "M_K_CPU0_SA_DQ<17>")
	)
	(segment
		(start 437.835294 -217.310208)
		(end 446.219326 -217.310208)
		(width 0.14478)
		(layer "In6.Cu")
		(net "M_K_CPU0_SA_DQ<17>")
	)
	(segment
		(start 437.418734 -217.482674)
		(end 437.835294 -217.310208)
		(width 0.14478)
		(layer "In6.Cu")
		(net "M_K_CPU0_SA_DQ<17>")
	)
	(segment
		(start 414.046416 -218.160092)
		(end 414.896554 -217.309954)
		(width 0.14478)
		(layer "In6.Cu")
		(net "M_K_CPU0_SA_DQ<17>")
	)
	(segment
		(start 407.610056 -223.354646)
		(end 407.610056 -222.40367)
		(width 0.14478)
		(layer "In6.Cu")
		(net "M_K_CPU0_SA_DQ<17>")
	)
	(segment
		(start 435.783228 -218.160092)
		(end 437.418734 -217.482674)
		(width 0.14478)
		(layer "In6.Cu")
		(net "M_K_CPU0_SA_DQ<17>")
	)
	(segment
		(start 394.925296 -234.45851)
		(end 395.753336 -233.63047)
		(width 0.0889)
		(layer "In6.Cu")
		(net "M_K_CPU0_SA_DQ<17>")
	)
	(segment
		(start 391.95756 -235.896658)
		(end 391.965942 -235.901484)
		(width 0.0889)
		(layer "In6.Cu")
		(net "M_K_CPU0_SA_DQ<17>")
	)
	(segment
		(start 428.237142 -218.160092)
		(end 429.677576 -217.563446)
		(width 0.14478)
		(layer "In6.Cu")
		(net "M_K_CPU0_SA_DQ<17>")
	)
	(segment
		(start 391.01776 -235.896658)
		(end 391.026142 -235.901484)
		(width 0.0889)
		(layer "In6.Cu")
		(net "M_K_CPU0_SA_DQ<17>")
	)
	(segment
		(start 394.112496 -234.76331)
		(end 394.417296 -234.45851)
		(width 0.0889)
		(layer "In6.Cu")
		(net "M_K_CPU0_SA_DQ<17>")
	)
	(segment
		(start 414.896554 -217.309954)
		(end 417.848034 -217.309954)
		(width 0.14478)
		(layer "In6.Cu")
		(net "M_K_CPU0_SA_DQ<17>")
	)
	(segment
		(start 393.253214 -235.906818)
		(end 393.271502 -235.896404)
		(width 0.0889)
		(layer "In6.Cu")
		(net "M_K_CPU0_SA_DQ<17>")
	)
	(segment
		(start 417.848034 -217.309954)
		(end 418.698172 -218.160092)
		(width 0.14478)
		(layer "In6.Cu")
		(net "M_K_CPU0_SA_DQ<17>")
	)
	(segment
		(start 391.947146 -235.890562)
		(end 391.95756 -235.896658)
		(width 0.0889)
		(layer "In6.Cu")
		(net "M_K_CPU0_SA_DQ<17>")
	)
	(segment
		(start 407.610056 -222.40367)
		(end 411.853634 -218.160092)
		(width 0.14478)
		(layer "In6.Cu")
		(net "M_K_CPU0_SA_DQ<17>")
	)
	(segment
		(start 395.753336 -233.63047)
		(end 395.920976 -233.63047)
		(width 0.0889)
		(layer "In6.Cu")
		(net "M_K_CPU0_SA_DQ<17>")
	)
	(segment
		(start 389.170926 -235.839508)
		(end 389.193278 -235.92282)
		(width 0.0889)
		(layer "In6.Cu")
		(net "M_K_CPU0_SA_DQ<17>")
	)
	(segment
		(start 418.698172 -218.160092)
		(end 421.549322 -218.160092)
		(width 0.14478)
		(layer "In6.Cu")
		(net "M_K_CPU0_SA_DQ<17>")
	)
	(segment
		(start 422.399206 -217.310208)
		(end 425.392342 -217.310208)
		(width 0.14478)
		(layer "In6.Cu")
		(net "M_K_CPU0_SA_DQ<17>")
	)
	(segment
		(start 421.549322 -218.160092)
		(end 422.399206 -217.310208)
		(width 0.14478)
		(layer "In6.Cu")
		(net "M_K_CPU0_SA_DQ<17>")
	)
	(segment
		(start 390.443466 -235.901484)
		(end 390.451848 -235.896658)
		(width 0.0889)
		(layer "In6.Cu")
		(net "M_K_CPU0_SA_DQ<17>")
	)
	(segment
		(start 432.550824 -217.310208)
		(end 434.603144 -218.160092)
		(width 0.14478)
		(layer "In6.Cu")
		(net "M_K_CPU0_SA_DQ<17>")
	)
	(segment
		(start 411.853634 -218.160092)
		(end 414.046416 -218.160092)
		(width 0.14478)
		(layer "In6.Cu")
		(net "M_K_CPU0_SA_DQ<17>")
	)
	(segment
		(start 393.329922 -235.86186)
		(end 394.112496 -235.079286)
		(width 0.0889)
		(layer "In6.Cu")
		(net "M_K_CPU0_SA_DQ<17>")
	)
	(segment
		(start 394.417296 -234.45851)
		(end 394.925296 -234.45851)
		(width 0.0889)
		(layer "In6.Cu")
		(net "M_K_CPU0_SA_DQ<17>")
	)
	(segment
		(start 389.32485 -235.574078)
		(end 389.170926 -235.839508)
		(width 0.0889)
		(layer "In6.Cu")
		(net "M_K_CPU0_SA_DQ<17>")
	)
	(segment
		(start 446.219326 -217.310208)
		(end 446.644268 -217.73515)
		(width 0.14478)
		(layer "In6.Cu")
		(net "M_K_CPU0_SA_DQ<17>")
	)
	(segment
		(start 395.920976 -233.63047)
		(end 397.334232 -233.63047)
		(width 0.14478)
		(layer "In6.Cu")
		(net "M_K_CPU0_SA_DQ<17>")
	)
	(segment
		(start 426.242226 -218.160092)
		(end 428.237142 -218.160092)
		(width 0.14478)
		(layer "In6.Cu")
		(net "M_K_CPU0_SA_DQ<17>")
	)
	(segment
		(start 434.603144 -218.160092)
		(end 435.783228 -218.160092)
		(width 0.14478)
		(layer "In6.Cu")
		(net "M_K_CPU0_SA_DQ<17>")
	)
	(arc
		(start 392.89736 -235.896658)
		(mid 393.073988 -235.946891)
		(end 393.253214 -235.906818)
		(width 0.0889)
		(layer "In6.Cu")
		(net "M_K_CPU0_SA_DQ<17>")
	)
	(arc
		(start 390.077706 -235.896658)
		(mid 390.259957 -235.947008)
		(end 390.443466 -235.901484)
		(width 0.0889)
		(layer "In6.Cu")
		(net "M_K_CPU0_SA_DQ<17>")
	)
	(arc
		(start 392.341608 -235.890562)
		(mid 392.620294 -235.820342)
		(end 392.89736 -235.896658)
		(width 0.0889)
		(layer "In6.Cu")
		(net "M_K_CPU0_SA_DQ<17>")
	)
	(arc
		(start 390.451848 -235.896658)
		(mid 390.734804 -235.820481)
		(end 391.01776 -235.896658)
		(width 0.0889)
		(layer "In6.Cu")
		(net "M_K_CPU0_SA_DQ<17>")
	)
	(arc
		(start 391.026142 -235.901484)
		(mid 391.20965 -235.946978)
		(end 391.391902 -235.896658)
		(width 0.0889)
		(layer "In6.Cu")
		(net "M_K_CPU0_SA_DQ<17>")
	)
	(arc
		(start 389.511794 -235.896658)
		(mid 389.79475 -235.820481)
		(end 390.077706 -235.896658)
		(width 0.0889)
		(layer "In6.Cu")
		(net "M_K_CPU0_SA_DQ<17>")
	)
	(arc
		(start 389.193278 -235.92282)
		(mid 389.355467 -235.945555)
		(end 389.511794 -235.896658)
		(width 0.0889)
		(layer "In6.Cu")
		(net "M_K_CPU0_SA_DQ<17>")
	)
	(arc
		(start 391.391902 -235.896658)
		(mid 391.668715 -235.820515)
		(end 391.947146 -235.890562)
		(width 0.0889)
		(layer "In6.Cu")
		(net "M_K_CPU0_SA_DQ<17>")
	)
	(arc
		(start 391.965942 -235.901484)
		(mid 392.149196 -235.946857)
		(end 392.331194 -235.896658)
		(width 0.0889)
		(layer "In6.Cu")
		(net "M_K_CPU0_SA_DQ<17>")
	)
	(segment
		(start 390.267952 -235.03001)
		(end 390.734804 -234.764072)
		(width 0.10668)
		(layer "F.Cu")
		(net "M_K_CPU0_SA_DQ<16>")
	)
	(segment
		(start 444.882524 -215.610186)
		(end 446.219326 -215.610186)
		(width 0.14478)
		(layer "In6.Cu")
		(net "M_K_CPU0_SA_DQ<16>")
	)
	(segment
		(start 446.219326 -215.610186)
		(end 446.644268 -216.035128)
		(width 0.14478)
		(layer "In6.Cu")
		(net "M_K_CPU0_SA_DQ<16>")
	)
	(segment
		(start 395.077696 -233.23931)
		(end 395.595856 -232.72115)
		(width 0.0889)
		(layer "In6.Cu")
		(net "M_K_CPU0_SA_DQ<16>")
	)
	(segment
		(start 426.242226 -216.46007)
		(end 429.08093 -216.46007)
		(width 0.14478)
		(layer "In6.Cu")
		(net "M_K_CPU0_SA_DQ<16>")
	)
	(segment
		(start 414.896554 -215.609932)
		(end 417.848034 -215.609932)
		(width 0.14478)
		(layer "In6.Cu")
		(net "M_K_CPU0_SA_DQ<16>")
	)
	(segment
		(start 392.42746 -235.086652)
		(end 392.435842 -235.091478)
		(width 0.0889)
		(layer "In6.Cu")
		(net "M_K_CPU0_SA_DQ<16>")
	)
	(segment
		(start 429.08093 -216.46007)
		(end 429.930814 -215.610186)
		(width 0.14478)
		(layer "In6.Cu")
		(net "M_K_CPU0_SA_DQ<16>")
	)
	(segment
		(start 444.719456 -215.890602)
		(end 444.719456 -215.773254)
		(width 0.14478)
		(layer "In6.Cu")
		(net "M_K_CPU0_SA_DQ<16>")
	)
	(segment
		(start 414.046416 -216.46007)
		(end 414.896554 -215.609932)
		(width 0.14478)
		(layer "In6.Cu")
		(net "M_K_CPU0_SA_DQ<16>")
	)
	(segment
		(start 412.179516 -216.46007)
		(end 414.046416 -216.46007)
		(width 0.14478)
		(layer "In6.Cu")
		(net "M_K_CPU0_SA_DQ<16>")
	)
	(segment
		(start 418.698172 -216.46007)
		(end 421.549322 -216.46007)
		(width 0.14478)
		(layer "In6.Cu")
		(net "M_K_CPU0_SA_DQ<16>")
	)
	(segment
		(start 417.848034 -215.609932)
		(end 418.698172 -216.46007)
		(width 0.14478)
		(layer "In6.Cu")
		(net "M_K_CPU0_SA_DQ<16>")
	)
	(segment
		(start 406.700736 -221.93885)
		(end 412.179516 -216.46007)
		(width 0.14478)
		(layer "In6.Cu")
		(net "M_K_CPU0_SA_DQ<16>")
	)
	(segment
		(start 444.556388 -216.05367)
		(end 444.719456 -215.890602)
		(width 0.14478)
		(layer "In6.Cu")
		(net "M_K_CPU0_SA_DQ<16>")
	)
	(segment
		(start 391.85342 -235.091478)
		(end 391.861802 -235.086652)
		(width 0.0889)
		(layer "In6.Cu")
		(net "M_K_CPU0_SA_DQ<16>")
	)
	(segment
		(start 395.077696 -233.534966)
		(end 395.077696 -233.23931)
		(width 0.0889)
		(layer "In6.Cu")
		(net "M_K_CPU0_SA_DQ<16>")
	)
	(segment
		(start 396.957296 -232.72115)
		(end 406.700736 -222.97771)
		(width 0.14478)
		(layer "In6.Cu")
		(net "M_K_CPU0_SA_DQ<16>")
	)
	(segment
		(start 391.861802 -235.086652)
		(end 391.872216 -235.080556)
		(width 0.0889)
		(layer "In6.Cu")
		(net "M_K_CPU0_SA_DQ<16>")
	)
	(segment
		(start 395.920976 -232.72115)
		(end 396.957296 -232.72115)
		(width 0.14478)
		(layer "In6.Cu")
		(net "M_K_CPU0_SA_DQ<16>")
	)
	(segment
		(start 393.262104 -235.010452)
		(end 394.372846 -233.89971)
		(width 0.0889)
		(layer "In6.Cu")
		(net "M_K_CPU0_SA_DQ<16>")
	)
	(segment
		(start 422.399206 -215.610186)
		(end 425.392342 -215.610186)
		(width 0.14478)
		(layer "In6.Cu")
		(net "M_K_CPU0_SA_DQ<16>")
	)
	(segment
		(start 432.936142 -215.610186)
		(end 433.786026 -216.46007)
		(width 0.14478)
		(layer "In6.Cu")
		(net "M_K_CPU0_SA_DQ<16>")
	)
	(segment
		(start 406.700736 -222.97771)
		(end 406.700736 -221.93885)
		(width 0.14478)
		(layer "In6.Cu")
		(net "M_K_CPU0_SA_DQ<16>")
	)
	(segment
		(start 429.930814 -215.610186)
		(end 432.936142 -215.610186)
		(width 0.14478)
		(layer "In6.Cu")
		(net "M_K_CPU0_SA_DQ<16>")
	)
	(segment
		(start 433.786026 -216.46007)
		(end 436.741316 -216.46007)
		(width 0.14478)
		(layer "In6.Cu")
		(net "M_K_CPU0_SA_DQ<16>")
	)
	(segment
		(start 393.084558 -235.010452)
		(end 393.262104 -235.010452)
		(width 0.0889)
		(layer "In6.Cu")
		(net "M_K_CPU0_SA_DQ<16>")
	)
	(segment
		(start 444.32601 -216.05367)
		(end 444.556388 -216.05367)
		(width 0.14478)
		(layer "In6.Cu")
		(net "M_K_CPU0_SA_DQ<16>")
	)
	(segment
		(start 444.162942 -215.890602)
		(end 444.32601 -216.05367)
		(width 0.14478)
		(layer "In6.Cu")
		(net "M_K_CPU0_SA_DQ<16>")
	)
	(segment
		(start 390.734804 -234.764072)
		(end 390.58088 -235.029502)
		(width 0.0889)
		(layer "In6.Cu")
		(net "M_K_CPU0_SA_DQ<16>")
	)
	(segment
		(start 437.5912 -215.610186)
		(end 443.999874 -215.610186)
		(width 0.14478)
		(layer "In6.Cu")
		(net "M_K_CPU0_SA_DQ<16>")
	)
	(segment
		(start 436.741316 -216.46007)
		(end 437.5912 -215.610186)
		(width 0.14478)
		(layer "In6.Cu")
		(net "M_K_CPU0_SA_DQ<16>")
	)
	(segment
		(start 395.595856 -232.72115)
		(end 395.920976 -232.72115)
		(width 0.0889)
		(layer "In6.Cu")
		(net "M_K_CPU0_SA_DQ<16>")
	)
	(segment
		(start 390.58088 -235.029502)
		(end 390.603232 -235.112814)
		(width 0.0889)
		(layer "In6.Cu")
		(net "M_K_CPU0_SA_DQ<16>")
	)
	(segment
		(start 421.549322 -216.46007)
		(end 422.399206 -215.610186)
		(width 0.14478)
		(layer "In6.Cu")
		(net "M_K_CPU0_SA_DQ<16>")
	)
	(segment
		(start 443.999874 -215.610186)
		(end 444.162942 -215.773254)
		(width 0.14478)
		(layer "In6.Cu")
		(net "M_K_CPU0_SA_DQ<16>")
	)
	(segment
		(start 425.392342 -215.610186)
		(end 426.242226 -216.46007)
		(width 0.14478)
		(layer "In6.Cu")
		(net "M_K_CPU0_SA_DQ<16>")
	)
	(segment
		(start 394.712952 -233.89971)
		(end 395.077696 -233.534966)
		(width 0.0889)
		(layer "In6.Cu")
		(net "M_K_CPU0_SA_DQ<16>")
	)
	(segment
		(start 444.162942 -215.773254)
		(end 444.162942 -215.890602)
		(width 0.14478)
		(layer "In6.Cu")
		(net "M_K_CPU0_SA_DQ<16>")
	)
	(segment
		(start 394.372846 -233.89971)
		(end 394.712952 -233.89971)
		(width 0.0889)
		(layer "In6.Cu")
		(net "M_K_CPU0_SA_DQ<16>")
	)
	(segment
		(start 444.719456 -215.773254)
		(end 444.882524 -215.610186)
		(width 0.14478)
		(layer "In6.Cu")
		(net "M_K_CPU0_SA_DQ<16>")
	)
	(arc
		(start 390.921748 -235.086652)
		(mid 391.204704 -235.010475)
		(end 391.48766 -235.086652)
		(width 0.0889)
		(layer "In6.Cu")
		(net "M_K_CPU0_SA_DQ<16>")
	)
	(arc
		(start 392.435842 -235.091478)
		(mid 392.61935 -235.136972)
		(end 392.801602 -235.086652)
		(width 0.0889)
		(layer "In6.Cu")
		(net "M_K_CPU0_SA_DQ<16>")
	)
	(arc
		(start 390.603232 -235.112814)
		(mid 390.765421 -235.135549)
		(end 390.921748 -235.086652)
		(width 0.0889)
		(layer "In6.Cu")
		(net "M_K_CPU0_SA_DQ<16>")
	)
	(arc
		(start 391.872216 -235.080556)
		(mid 392.150648 -235.010458)
		(end 392.42746 -235.086652)
		(width 0.0889)
		(layer "In6.Cu")
		(net "M_K_CPU0_SA_DQ<16>")
	)
	(arc
		(start 391.48766 -235.086652)
		(mid 391.669911 -235.137002)
		(end 391.85342 -235.091478)
		(width 0.0889)
		(layer "In6.Cu")
		(net "M_K_CPU0_SA_DQ<16>")
	)
	(arc
		(start 392.801602 -235.086652)
		(mid 392.938043 -235.029852)
		(end 393.084558 -235.010452)
		(width 0.0889)
		(layer "In6.Cu")
		(net "M_K_CPU0_SA_DQ<16>")
	)
	(segment
		(start 388.387844 -235.03001)
		(end 388.85495 -234.764072)
		(width 0.10668)
		(layer "F.Cu")
		(net "M_K_CPU0_SA_DQ<15>")
	)
	(segment
		(start 430.854104 -214.36965)
		(end 431.017172 -214.532718)
		(width 0.14478)
		(layer "In6.Cu")
		(net "M_K_CPU0_SA_DQ<15>")
	)
	(segment
		(start 394.319252 -233.558588)
		(end 394.319252 -233.223562)
		(width 0.0889)
		(layer "In6.Cu")
		(net "M_K_CPU0_SA_DQ<15>")
	)
	(segment
		(start 413.166814 -215.23071)
		(end 413.397192 -215.23071)
		(width 0.14478)
		(layer "In6.Cu")
		(net "M_K_CPU0_SA_DQ<15>")
	)
	(segment
		(start 413.56026 -215.393778)
		(end 413.56026 -215.447118)
		(width 0.14478)
		(layer "In6.Cu")
		(net "M_K_CPU0_SA_DQ<15>")
	)
	(segment
		(start 437.463438 -214.760048)
		(end 437.729122 -214.760048)
		(width 0.14478)
		(layer "In6.Cu")
		(net "M_K_CPU0_SA_DQ<15>")
	)
	(segment
		(start 417.848034 -214.760048)
		(end 418.698172 -215.610186)
		(width 0.14478)
		(layer "In6.Cu")
		(net "M_K_CPU0_SA_DQ<15>")
	)
	(segment
		(start 413.003746 -215.447118)
		(end 413.003746 -215.393778)
		(width 0.14478)
		(layer "In6.Cu")
		(net "M_K_CPU0_SA_DQ<15>")
	)
	(segment
		(start 440.492642 -214.760048)
		(end 440.72302 -214.760048)
		(width 0.14478)
		(layer "In6.Cu")
		(net "M_K_CPU0_SA_DQ<15>")
	)
	(segment
		(start 418.698172 -215.610186)
		(end 420.319708 -215.610186)
		(width 0.14478)
		(layer "In6.Cu")
		(net "M_K_CPU0_SA_DQ<15>")
	)
	(segment
		(start 435.614064 -215.447118)
		(end 435.614064 -215.381078)
		(width 0.14478)
		(layer "In6.Cu")
		(net "M_K_CPU0_SA_DQ<15>")
	)
	(segment
		(start 433.866798 -215.610186)
		(end 434.011578 -215.465406)
		(width 0.14478)
		(layer "In6.Cu")
		(net "M_K_CPU0_SA_DQ<15>")
	)
	(segment
		(start 430.460658 -214.59698)
		(end 430.460658 -214.532718)
		(width 0.14478)
		(layer "In6.Cu")
		(net "M_K_CPU0_SA_DQ<15>")
	)
	(segment
		(start 439.77306 -214.59698)
		(end 439.77306 -214.532718)
		(width 0.14478)
		(layer "In6.Cu")
		(net "M_K_CPU0_SA_DQ<15>")
	)
	(segment
		(start 416.693604 -214.59698)
		(end 416.693604 -214.532718)
		(width 0.14478)
		(layer "In6.Cu")
		(net "M_K_CPU0_SA_DQ<15>")
	)
	(segment
		(start 391.861548 -234.441492)
		(end 391.871962 -234.447588)
		(width 0.0889)
		(layer "In6.Cu")
		(net "M_K_CPU0_SA_DQ<15>")
	)
	(segment
		(start 412.18104 -215.610186)
		(end 412.840678 -215.610186)
		(width 0.14478)
		(layer "In6.Cu")
		(net "M_K_CPU0_SA_DQ<15>")
	)
	(segment
		(start 422.70299 -214.760048)
		(end 422.866058 -214.59698)
		(width 0.14478)
		(layer "In6.Cu")
		(net "M_K_CPU0_SA_DQ<15>")
	)
	(segment
		(start 413.723328 -215.610186)
		(end 414.006792 -215.610186)
		(width 0.14478)
		(layer "In6.Cu")
		(net "M_K_CPU0_SA_DQ<15>")
	)
	(segment
		(start 428.663608 -215.447118)
		(end 428.826676 -215.610186)
		(width 0.14478)
		(layer "In6.Cu")
		(net "M_K_CPU0_SA_DQ<15>")
	)
	(segment
		(start 434.156358 -215.244172)
		(end 434.418232 -215.244172)
		(width 0.14478)
		(layer "In6.Cu")
		(net "M_K_CPU0_SA_DQ<15>")
	)
	(segment
		(start 393.355322 -234.448604)
		(end 393.36726 -234.441746)
		(width 0.0889)
		(layer "In6.Cu")
		(net "M_K_CPU0_SA_DQ<15>")
	)
	(segment
		(start 417.413186 -214.760048)
		(end 417.848034 -214.760048)
		(width 0.14478)
		(layer "In6.Cu")
		(net "M_K_CPU0_SA_DQ<15>")
	)
	(segment
		(start 439.77306 -214.532718)
		(end 439.936128 -214.36965)
		(width 0.14478)
		(layer "In6.Cu")
		(net "M_K_CPU0_SA_DQ<15>")
	)
	(segment
		(start 391.849864 -234.434634)
		(end 391.861548 -234.441492)
		(width 0.0889)
		(layer "In6.Cu")
		(net "M_K_CPU0_SA_DQ<15>")
	)
	(segment
		(start 434.011578 -215.465406)
		(end 434.011578 -215.388952)
		(width 0.14478)
		(layer "In6.Cu")
		(net "M_K_CPU0_SA_DQ<15>")
	)
	(segment
		(start 420.482776 -215.447118)
		(end 420.482776 -215.378538)
		(width 0.14478)
		(layer "In6.Cu")
		(net "M_K_CPU0_SA_DQ<15>")
	)
	(segment
		(start 432.935888 -214.760048)
		(end 433.786026 -215.610186)
		(width 0.14478)
		(layer "In6.Cu")
		(net "M_K_CPU0_SA_DQ<15>")
	)
	(segment
		(start 423.259504 -214.36965)
		(end 423.422572 -214.532718)
		(width 0.14478)
		(layer "In6.Cu")
		(net "M_K_CPU0_SA_DQ<15>")
	)
	(segment
		(start 423.422572 -214.59698)
		(end 423.58564 -214.760048)
		(width 0.14478)
		(layer "In6.Cu")
		(net "M_K_CPU0_SA_DQ<15>")
	)
	(segment
		(start 436.00751 -215.21801)
		(end 436.170578 -215.381078)
		(width 0.14478)
		(layer "In6.Cu")
		(net "M_K_CPU0_SA_DQ<15>")
	)
	(segment
		(start 428.826676 -215.610186)
		(end 429.08093 -215.610186)
		(width 0.14478)
		(layer "In6.Cu")
		(net "M_K_CPU0_SA_DQ<15>")
	)
	(segment
		(start 430.29759 -214.760048)
		(end 430.460658 -214.59698)
		(width 0.14478)
		(layer "In6.Cu")
		(net "M_K_CPU0_SA_DQ<15>")
	)
	(segment
		(start 431.18024 -214.760048)
		(end 432.935888 -214.760048)
		(width 0.14478)
		(layer "In6.Cu")
		(net "M_K_CPU0_SA_DQ<15>")
	)
	(segment
		(start 436.170578 -215.447118)
		(end 436.333646 -215.610186)
		(width 0.14478)
		(layer "In6.Cu")
		(net "M_K_CPU0_SA_DQ<15>")
	)
	(segment
		(start 417.08705 -214.36965)
		(end 417.250118 -214.532718)
		(width 0.14478)
		(layer "In6.Cu")
		(net "M_K_CPU0_SA_DQ<15>")
	)
	(segment
		(start 421.202358 -215.610186)
		(end 421.549322 -215.610186)
		(width 0.14478)
		(layer "In6.Cu")
		(net "M_K_CPU0_SA_DQ<15>")
	)
	(segment
		(start 394.503148 -233.039666)
		(end 394.767308 -233.039666)
		(width 0.0889)
		(layer "In6.Cu")
		(net "M_K_CPU0_SA_DQ<15>")
	)
	(segment
		(start 437.873902 -214.615268)
		(end 437.873902 -214.517732)
		(width 0.14478)
		(layer "In6.Cu")
		(net "M_K_CPU0_SA_DQ<15>")
	)
	(segment
		(start 435.450996 -215.610186)
		(end 435.614064 -215.447118)
		(width 0.14478)
		(layer "In6.Cu")
		(net "M_K_CPU0_SA_DQ<15>")
	)
	(segment
		(start 431.017172 -214.59698)
		(end 431.18024 -214.760048)
		(width 0.14478)
		(layer "In6.Cu")
		(net "M_K_CPU0_SA_DQ<15>")
	)
	(segment
		(start 428.663608 -215.386158)
		(end 428.663608 -215.447118)
		(width 0.14478)
		(layer "In6.Cu")
		(net "M_K_CPU0_SA_DQ<15>")
	)
	(segment
		(start 435.777132 -215.21801)
		(end 436.00751 -215.21801)
		(width 0.14478)
		(layer "In6.Cu")
		(net "M_K_CPU0_SA_DQ<15>")
	)
	(segment
		(start 416.856672 -214.36965)
		(end 417.08705 -214.36965)
		(width 0.14478)
		(layer "In6.Cu")
		(net "M_K_CPU0_SA_DQ<15>")
	)
	(segment
		(start 394.767308 -233.039666)
		(end 395.649704 -232.15727)
		(width 0.0889)
		(layer "In6.Cu")
		(net "M_K_CPU0_SA_DQ<15>")
	)
	(segment
		(start 414.006792 -215.610186)
		(end 414.85693 -214.760048)
		(width 0.14478)
		(layer "In6.Cu")
		(net "M_K_CPU0_SA_DQ<15>")
	)
	(segment
		(start 421.03929 -215.378538)
		(end 421.03929 -215.447118)
		(width 0.14478)
		(layer "In6.Cu")
		(net "M_K_CPU0_SA_DQ<15>")
	)
	(segment
		(start 430.460658 -214.532718)
		(end 430.623726 -214.36965)
		(width 0.14478)
		(layer "In6.Cu")
		(net "M_K_CPU0_SA_DQ<15>")
	)
	(segment
		(start 416.693604 -214.532718)
		(end 416.856672 -214.36965)
		(width 0.14478)
		(layer "In6.Cu")
		(net "M_K_CPU0_SA_DQ<15>")
	)
	(segment
		(start 441.279534 -214.36965)
		(end 441.442602 -214.532718)
		(width 0.14478)
		(layer "In6.Cu")
		(net "M_K_CPU0_SA_DQ<15>")
	)
	(segment
		(start 439.609992 -214.760048)
		(end 439.77306 -214.59698)
		(width 0.14478)
		(layer "In6.Cu")
		(net "M_K_CPU0_SA_DQ<15>")
	)
	(segment
		(start 420.319708 -215.610186)
		(end 420.482776 -215.447118)
		(width 0.14478)
		(layer "In6.Cu")
		(net "M_K_CPU0_SA_DQ<15>")
	)
	(segment
		(start 421.03929 -215.447118)
		(end 421.202358 -215.610186)
		(width 0.14478)
		(layer "In6.Cu")
		(net "M_K_CPU0_SA_DQ<15>")
	)
	(segment
		(start 438.018682 -214.372952)
		(end 438.280556 -214.372952)
		(width 0.14478)
		(layer "In6.Cu")
		(net "M_K_CPU0_SA_DQ<15>")
	)
	(segment
		(start 437.873902 -214.517732)
		(end 438.018682 -214.372952)
		(width 0.14478)
		(layer "In6.Cu")
		(net "M_K_CPU0_SA_DQ<15>")
	)
	(segment
		(start 415.974022 -214.36965)
		(end 416.13709 -214.532718)
		(width 0.14478)
		(layer "In6.Cu")
		(net "M_K_CPU0_SA_DQ<15>")
	)
	(segment
		(start 414.85693 -214.760048)
		(end 415.417508 -214.760048)
		(width 0.14478)
		(layer "In6.Cu")
		(net "M_K_CPU0_SA_DQ<15>")
	)
	(segment
		(start 416.13709 -214.59698)
		(end 416.300158 -214.760048)
		(width 0.14478)
		(layer "In6.Cu")
		(net "M_K_CPU0_SA_DQ<15>")
	)
	(segment
		(start 427.944026 -215.610186)
		(end 428.107094 -215.447118)
		(width 0.14478)
		(layer "In6.Cu")
		(net "M_K_CPU0_SA_DQ<15>")
	)
	(segment
		(start 393.561062 -234.316778)
		(end 394.319252 -233.558588)
		(width 0.0889)
		(layer "In6.Cu")
		(net "M_K_CPU0_SA_DQ<15>")
	)
	(segment
		(start 438.425336 -214.615268)
		(end 438.570116 -214.760048)
		(width 0.14478)
		(layer "In6.Cu")
		(net "M_K_CPU0_SA_DQ<15>")
	)
	(segment
		(start 416.300158 -214.760048)
		(end 416.530536 -214.760048)
		(width 0.14478)
		(layer "In6.Cu")
		(net "M_K_CPU0_SA_DQ<15>")
	)
	(segment
		(start 421.549322 -215.610186)
		(end 422.39946 -214.760048)
		(width 0.14478)
		(layer "In6.Cu")
		(net "M_K_CPU0_SA_DQ<15>")
	)
	(segment
		(start 423.58564 -214.760048)
		(end 425.392088 -214.760048)
		(width 0.14478)
		(layer "In6.Cu")
		(net "M_K_CPU0_SA_DQ<15>")
	)
	(segment
		(start 426.242226 -215.610186)
		(end 427.944026 -215.610186)
		(width 0.14478)
		(layer "In6.Cu")
		(net "M_K_CPU0_SA_DQ<15>")
	)
	(segment
		(start 429.931068 -214.760048)
		(end 430.29759 -214.760048)
		(width 0.14478)
		(layer "In6.Cu")
		(net "M_K_CPU0_SA_DQ<15>")
	)
	(segment
		(start 439.936128 -214.36965)
		(end 440.166506 -214.36965)
		(width 0.14478)
		(layer "In6.Cu")
		(net "M_K_CPU0_SA_DQ<15>")
	)
	(segment
		(start 413.003746 -215.393778)
		(end 413.166814 -215.23071)
		(width 0.14478)
		(layer "In6.Cu")
		(net "M_K_CPU0_SA_DQ<15>")
	)
	(segment
		(start 416.13709 -214.532718)
		(end 416.13709 -214.59698)
		(width 0.14478)
		(layer "In6.Cu")
		(net "M_K_CPU0_SA_DQ<15>")
	)
	(segment
		(start 438.570116 -214.760048)
		(end 439.609992 -214.760048)
		(width 0.14478)
		(layer "In6.Cu")
		(net "M_K_CPU0_SA_DQ<15>")
	)
	(segment
		(start 429.08093 -215.610186)
		(end 429.931068 -214.760048)
		(width 0.14478)
		(layer "In6.Cu")
		(net "M_K_CPU0_SA_DQ<15>")
	)
	(segment
		(start 441.442602 -214.532718)
		(end 441.442602 -214.59698)
		(width 0.14478)
		(layer "In6.Cu")
		(net "M_K_CPU0_SA_DQ<15>")
	)
	(segment
		(start 413.397192 -215.23071)
		(end 413.56026 -215.393778)
		(width 0.14478)
		(layer "In6.Cu")
		(net "M_K_CPU0_SA_DQ<15>")
	)
	(segment
		(start 428.107094 -215.386158)
		(end 428.270162 -215.22309)
		(width 0.14478)
		(layer "In6.Cu")
		(net "M_K_CPU0_SA_DQ<15>")
	)
	(segment
		(start 396.956534 -231.928416)
		(end 406.113996 -222.770954)
		(width 0.14478)
		(layer "In6.Cu")
		(net "M_K_CPU0_SA_DQ<15>")
	)
	(segment
		(start 396.72768 -232.15727)
		(end 396.956534 -231.928416)
		(width 0.0889)
		(layer "In6.Cu")
		(net "M_K_CPU0_SA_DQ<15>")
	)
	(segment
		(start 389.607806 -234.441492)
		(end 389.616188 -234.436666)
		(width 0.0889)
		(layer "In6.Cu")
		(net "M_K_CPU0_SA_DQ<15>")
	)
	(segment
		(start 434.563012 -215.465406)
		(end 434.707792 -215.610186)
		(width 0.14478)
		(layer "In6.Cu")
		(net "M_K_CPU0_SA_DQ<15>")
	)
	(segment
		(start 413.56026 -215.447118)
		(end 413.723328 -215.610186)
		(width 0.14478)
		(layer "In6.Cu")
		(net "M_K_CPU0_SA_DQ<15>")
	)
	(segment
		(start 428.107094 -215.447118)
		(end 428.107094 -215.386158)
		(width 0.14478)
		(layer "In6.Cu")
		(net "M_K_CPU0_SA_DQ<15>")
	)
	(segment
		(start 393.380976 -234.433872)
		(end 393.561062 -234.316778)
		(width 0.0889)
		(layer "In6.Cu")
		(net "M_K_CPU0_SA_DQ<15>")
	)
	(segment
		(start 388.85495 -234.764072)
		(end 389.008874 -234.498642)
		(width 0.0889)
		(layer "In6.Cu")
		(net "M_K_CPU0_SA_DQ<15>")
	)
	(segment
		(start 436.170578 -215.381078)
		(end 436.170578 -215.447118)
		(width 0.14478)
		(layer "In6.Cu")
		(net "M_K_CPU0_SA_DQ<15>")
	)
	(segment
		(start 420.482776 -215.378538)
		(end 420.645844 -215.21547)
		(width 0.14478)
		(layer "In6.Cu")
		(net "M_K_CPU0_SA_DQ<15>")
	)
	(segment
		(start 431.017172 -214.532718)
		(end 431.017172 -214.59698)
		(width 0.14478)
		(layer "In6.Cu")
		(net "M_K_CPU0_SA_DQ<15>")
	)
	(segment
		(start 412.840678 -215.610186)
		(end 413.003746 -215.447118)
		(width 0.14478)
		(layer "In6.Cu")
		(net "M_K_CPU0_SA_DQ<15>")
	)
	(segment
		(start 415.743644 -214.36965)
		(end 415.974022 -214.36965)
		(width 0.14478)
		(layer "In6.Cu")
		(net "M_K_CPU0_SA_DQ<15>")
	)
	(segment
		(start 425.392088 -214.760048)
		(end 426.242226 -215.610186)
		(width 0.14478)
		(layer "In6.Cu")
		(net "M_K_CPU0_SA_DQ<15>")
	)
	(segment
		(start 417.250118 -214.59698)
		(end 417.413186 -214.760048)
		(width 0.14478)
		(layer "In6.Cu")
		(net "M_K_CPU0_SA_DQ<15>")
	)
	(segment
		(start 434.707792 -215.610186)
		(end 435.450996 -215.610186)
		(width 0.14478)
		(layer "In6.Cu")
		(net "M_K_CPU0_SA_DQ<15>")
	)
	(segment
		(start 440.886088 -214.59698)
		(end 440.886088 -214.532718)
		(width 0.14478)
		(layer "In6.Cu")
		(net "M_K_CPU0_SA_DQ<15>")
	)
	(segment
		(start 440.886088 -214.532718)
		(end 441.049156 -214.36965)
		(width 0.14478)
		(layer "In6.Cu")
		(net "M_K_CPU0_SA_DQ<15>")
	)
	(segment
		(start 423.029126 -214.36965)
		(end 423.259504 -214.36965)
		(width 0.14478)
		(layer "In6.Cu")
		(net "M_K_CPU0_SA_DQ<15>")
	)
	(segment
		(start 406.113996 -222.770954)
		(end 406.113996 -221.67723)
		(width 0.14478)
		(layer "In6.Cu")
		(net "M_K_CPU0_SA_DQ<15>")
	)
	(segment
		(start 420.645844 -215.21547)
		(end 420.876222 -215.21547)
		(width 0.14478)
		(layer "In6.Cu")
		(net "M_K_CPU0_SA_DQ<15>")
	)
	(segment
		(start 416.530536 -214.760048)
		(end 416.693604 -214.59698)
		(width 0.14478)
		(layer "In6.Cu")
		(net "M_K_CPU0_SA_DQ<15>")
	)
	(segment
		(start 430.623726 -214.36965)
		(end 430.854104 -214.36965)
		(width 0.14478)
		(layer "In6.Cu")
		(net "M_K_CPU0_SA_DQ<15>")
	)
	(segment
		(start 440.166506 -214.36965)
		(end 440.329574 -214.532718)
		(width 0.14478)
		(layer "In6.Cu")
		(net "M_K_CPU0_SA_DQ<15>")
	)
	(segment
		(start 422.866058 -214.532718)
		(end 423.029126 -214.36965)
		(width 0.14478)
		(layer "In6.Cu")
		(net "M_K_CPU0_SA_DQ<15>")
	)
	(segment
		(start 435.614064 -215.381078)
		(end 435.777132 -215.21801)
		(width 0.14478)
		(layer "In6.Cu")
		(net "M_K_CPU0_SA_DQ<15>")
	)
	(segment
		(start 441.442602 -214.59698)
		(end 441.60567 -214.760048)
		(width 0.14478)
		(layer "In6.Cu")
		(net "M_K_CPU0_SA_DQ<15>")
	)
	(segment
		(start 395.649704 -232.15727)
		(end 396.72768 -232.15727)
		(width 0.0889)
		(layer "In6.Cu")
		(net "M_K_CPU0_SA_DQ<15>")
	)
	(segment
		(start 433.786026 -215.610186)
		(end 433.866798 -215.610186)
		(width 0.14478)
		(layer "In6.Cu")
		(net "M_K_CPU0_SA_DQ<15>")
	)
	(segment
		(start 442.119258 -214.760048)
		(end 442.5442 -215.18499)
		(width 0.14478)
		(layer "In6.Cu")
		(net "M_K_CPU0_SA_DQ<15>")
	)
	(segment
		(start 392.427206 -234.441492)
		(end 392.43889 -234.434634)
		(width 0.0889)
		(layer "In6.Cu")
		(net "M_K_CPU0_SA_DQ<15>")
	)
	(segment
		(start 394.319252 -233.223562)
		(end 394.503148 -233.039666)
		(width 0.0889)
		(layer "In6.Cu")
		(net "M_K_CPU0_SA_DQ<15>")
	)
	(segment
		(start 440.329574 -214.59698)
		(end 440.492642 -214.760048)
		(width 0.14478)
		(layer "In6.Cu")
		(net "M_K_CPU0_SA_DQ<15>")
	)
	(segment
		(start 420.876222 -215.21547)
		(end 421.03929 -215.378538)
		(width 0.14478)
		(layer "In6.Cu")
		(net "M_K_CPU0_SA_DQ<15>")
	)
	(segment
		(start 422.39946 -214.760048)
		(end 422.70299 -214.760048)
		(width 0.14478)
		(layer "In6.Cu")
		(net "M_K_CPU0_SA_DQ<15>")
	)
	(segment
		(start 393.36726 -234.441746)
		(end 393.380976 -234.433872)
		(width 0.0889)
		(layer "In6.Cu")
		(net "M_K_CPU0_SA_DQ<15>")
	)
	(segment
		(start 434.418232 -215.244172)
		(end 434.563012 -215.388952)
		(width 0.14478)
		(layer "In6.Cu")
		(net "M_K_CPU0_SA_DQ<15>")
	)
	(segment
		(start 428.50054 -215.22309)
		(end 428.663608 -215.386158)
		(width 0.14478)
		(layer "In6.Cu")
		(net "M_K_CPU0_SA_DQ<15>")
	)
	(segment
		(start 434.563012 -215.388952)
		(end 434.563012 -215.465406)
		(width 0.14478)
		(layer "In6.Cu")
		(net "M_K_CPU0_SA_DQ<15>")
	)
	(segment
		(start 436.6133 -215.610186)
		(end 437.463438 -214.760048)
		(width 0.14478)
		(layer "In6.Cu")
		(net "M_K_CPU0_SA_DQ<15>")
	)
	(segment
		(start 438.280556 -214.372952)
		(end 438.425336 -214.517732)
		(width 0.14478)
		(layer "In6.Cu")
		(net "M_K_CPU0_SA_DQ<15>")
	)
	(segment
		(start 441.049156 -214.36965)
		(end 441.279534 -214.36965)
		(width 0.14478)
		(layer "In6.Cu")
		(net "M_K_CPU0_SA_DQ<15>")
	)
	(segment
		(start 415.580576 -214.59698)
		(end 415.580576 -214.532718)
		(width 0.14478)
		(layer "In6.Cu")
		(net "M_K_CPU0_SA_DQ<15>")
	)
	(segment
		(start 436.333646 -215.610186)
		(end 436.6133 -215.610186)
		(width 0.14478)
		(layer "In6.Cu")
		(net "M_K_CPU0_SA_DQ<15>")
	)
	(segment
		(start 437.729122 -214.760048)
		(end 437.873902 -214.615268)
		(width 0.14478)
		(layer "In6.Cu")
		(net "M_K_CPU0_SA_DQ<15>")
	)
	(segment
		(start 441.60567 -214.760048)
		(end 442.119258 -214.760048)
		(width 0.14478)
		(layer "In6.Cu")
		(net "M_K_CPU0_SA_DQ<15>")
	)
	(segment
		(start 440.329574 -214.532718)
		(end 440.329574 -214.59698)
		(width 0.14478)
		(layer "In6.Cu")
		(net "M_K_CPU0_SA_DQ<15>")
	)
	(segment
		(start 440.72302 -214.760048)
		(end 440.886088 -214.59698)
		(width 0.14478)
		(layer "In6.Cu")
		(net "M_K_CPU0_SA_DQ<15>")
	)
	(segment
		(start 417.250118 -214.532718)
		(end 417.250118 -214.59698)
		(width 0.14478)
		(layer "In6.Cu")
		(net "M_K_CPU0_SA_DQ<15>")
	)
	(segment
		(start 434.011578 -215.388952)
		(end 434.156358 -215.244172)
		(width 0.14478)
		(layer "In6.Cu")
		(net "M_K_CPU0_SA_DQ<15>")
	)
	(segment
		(start 422.866058 -214.59698)
		(end 422.866058 -214.532718)
		(width 0.14478)
		(layer "In6.Cu")
		(net "M_K_CPU0_SA_DQ<15>")
	)
	(segment
		(start 406.113996 -221.67723)
		(end 412.18104 -215.610186)
		(width 0.14478)
		(layer "In6.Cu")
		(net "M_K_CPU0_SA_DQ<15>")
	)
	(segment
		(start 389.008874 -234.498642)
		(end 389.104886 -234.473242)
		(width 0.0889)
		(layer "In6.Cu")
		(net "M_K_CPU0_SA_DQ<15>")
	)
	(segment
		(start 428.270162 -215.22309)
		(end 428.50054 -215.22309)
		(width 0.14478)
		(layer "In6.Cu")
		(net "M_K_CPU0_SA_DQ<15>")
	)
	(segment
		(start 415.417508 -214.760048)
		(end 415.580576 -214.59698)
		(width 0.14478)
		(layer "In6.Cu")
		(net "M_K_CPU0_SA_DQ<15>")
	)
	(segment
		(start 415.580576 -214.532718)
		(end 415.743644 -214.36965)
		(width 0.14478)
		(layer "In6.Cu")
		(net "M_K_CPU0_SA_DQ<15>")
	)
	(segment
		(start 423.422572 -214.532718)
		(end 423.422572 -214.59698)
		(width 0.14478)
		(layer "In6.Cu")
		(net "M_K_CPU0_SA_DQ<15>")
	)
	(segment
		(start 438.425336 -214.517732)
		(end 438.425336 -214.615268)
		(width 0.14478)
		(layer "In6.Cu")
		(net "M_K_CPU0_SA_DQ<15>")
	)
	(arc
		(start 391.48766 -234.441492)
		(mid 391.667865 -234.391175)
		(end 391.849864 -234.434634)
		(width 0.0889)
		(layer "In6.Cu")
		(net "M_K_CPU0_SA_DQ<15>")
	)
	(arc
		(start 392.801602 -234.441492)
		(mid 393.077534 -234.517749)
		(end 393.355322 -234.448604)
		(width 0.0889)
		(layer "In6.Cu")
		(net "M_K_CPU0_SA_DQ<15>")
	)
	(arc
		(start 390.921748 -234.441492)
		(mid 391.204704 -234.517669)
		(end 391.48766 -234.441492)
		(width 0.0889)
		(layer "In6.Cu")
		(net "M_K_CPU0_SA_DQ<15>")
	)
	(arc
		(start 389.616188 -234.436666)
		(mid 389.799696 -234.391172)
		(end 389.981948 -234.441492)
		(width 0.0889)
		(layer "In6.Cu")
		(net "M_K_CPU0_SA_DQ<15>")
	)
	(arc
		(start 390.54786 -234.441492)
		(mid 390.734804 -234.391237)
		(end 390.921748 -234.441492)
		(width 0.0889)
		(layer "In6.Cu")
		(net "M_K_CPU0_SA_DQ<15>")
	)
	(arc
		(start 391.871962 -234.447588)
		(mid 392.150394 -234.517686)
		(end 392.427206 -234.441492)
		(width 0.0889)
		(layer "In6.Cu")
		(net "M_K_CPU0_SA_DQ<15>")
	)
	(arc
		(start 389.104886 -234.473242)
		(mid 389.360094 -234.516719)
		(end 389.607806 -234.441492)
		(width 0.0889)
		(layer "In6.Cu")
		(net "M_K_CPU0_SA_DQ<15>")
	)
	(arc
		(start 389.981948 -234.441492)
		(mid 390.264904 -234.517669)
		(end 390.54786 -234.441492)
		(width 0.0889)
		(layer "In6.Cu")
		(net "M_K_CPU0_SA_DQ<15>")
	)
	(arc
		(start 392.43889 -234.434634)
		(mid 392.621145 -234.390981)
		(end 392.801602 -234.441492)
		(width 0.0889)
		(layer "In6.Cu")
		(net "M_K_CPU0_SA_DQ<15>")
	)
	(segment
		(start 389.798052 -234.220004)
		(end 390.264904 -233.954066)
		(width 0.10668)
		(layer "F.Cu")
		(net "M_K_CPU0_SA_DQ<14>")
	)
	(segment
		(start 423.071036 -212.676232)
		(end 423.301414 -212.676232)
		(width 0.14478)
		(layer "In6.Cu")
		(net "M_K_CPU0_SA_DQ<14>")
	)
	(segment
		(start 437.962548 -212.681312)
		(end 438.224422 -212.681312)
		(width 0.14478)
		(layer "In6.Cu")
		(net "M_K_CPU0_SA_DQ<14>")
	)
	(segment
		(start 440.426856 -212.83295)
		(end 440.589924 -212.669882)
		(width 0.14478)
		(layer "In6.Cu")
		(net "M_K_CPU0_SA_DQ<14>")
	)
	(segment
		(start 392.331448 -233.631486)
		(end 392.341862 -233.637582)
		(width 0.0889)
		(layer "In6.Cu")
		(net "M_K_CPU0_SA_DQ<14>")
	)
	(segment
		(start 423.301414 -212.676232)
		(end 423.464482 -212.8393)
		(width 0.14478)
		(layer "In6.Cu")
		(net "M_K_CPU0_SA_DQ<14>")
	)
	(segment
		(start 423.464482 -212.896958)
		(end 423.62755 -213.060026)
		(width 0.14478)
		(layer "In6.Cu")
		(net "M_K_CPU0_SA_DQ<14>")
	)
	(segment
		(start 428.393606 -213.527132)
		(end 428.556674 -213.6902)
		(width 0.14478)
		(layer "In6.Cu")
		(net "M_K_CPU0_SA_DQ<14>")
	)
	(segment
		(start 435.523386 -213.68512)
		(end 435.686454 -213.522052)
		(width 0.14478)
		(layer "In6.Cu")
		(net "M_K_CPU0_SA_DQ<14>")
	)
	(segment
		(start 420.48684 -213.666832)
		(end 420.63162 -213.522052)
		(width 0.14478)
		(layer "In6.Cu")
		(net "M_K_CPU0_SA_DQ<14>")
	)
	(segment
		(start 434.192426 -213.529672)
		(end 434.4543 -213.529672)
		(width 0.14478)
		(layer "In6.Cu")
		(net "M_K_CPU0_SA_DQ<14>")
	)
	(segment
		(start 421.038274 -213.765384)
		(end 421.183054 -213.910164)
		(width 0.14478)
		(layer "In6.Cu")
		(net "M_K_CPU0_SA_DQ<14>")
	)
	(segment
		(start 435.523386 -213.747096)
		(end 435.523386 -213.68512)
		(width 0.14478)
		(layer "In6.Cu")
		(net "M_K_CPU0_SA_DQ<14>")
	)
	(segment
		(start 441.539884 -213.287102)
		(end 441.539884 -213.223094)
		(width 0.14478)
		(layer "In6.Cu")
		(net "M_K_CPU0_SA_DQ<14>")
	)
	(segment
		(start 433.786026 -213.910164)
		(end 433.902866 -213.910164)
		(width 0.14478)
		(layer "In6.Cu")
		(net "M_K_CPU0_SA_DQ<14>")
	)
	(segment
		(start 391.01776 -233.631486)
		(end 391.026142 -233.62666)
		(width 0.0889)
		(layer "In6.Cu")
		(net "M_K_CPU0_SA_DQ<14>")
	)
	(segment
		(start 438.369202 -212.915246)
		(end 438.513982 -213.060026)
		(width 0.14478)
		(layer "In6.Cu")
		(net "M_K_CPU0_SA_DQ<14>")
	)
	(segment
		(start 429.931068 -213.060026)
		(end 430.196498 -213.060026)
		(width 0.14478)
		(layer "In6.Cu")
		(net "M_K_CPU0_SA_DQ<14>")
	)
	(segment
		(start 425.392088 -213.060026)
		(end 426.242226 -213.910164)
		(width 0.14478)
		(layer "In6.Cu")
		(net "M_K_CPU0_SA_DQ<14>")
	)
	(segment
		(start 427.837092 -213.910164)
		(end 428.00016 -213.747096)
		(width 0.14478)
		(layer "In6.Cu")
		(net "M_K_CPU0_SA_DQ<14>")
	)
	(segment
		(start 441.702952 -213.060026)
		(end 442.119258 -213.060026)
		(width 0.14478)
		(layer "In6.Cu")
		(net "M_K_CPU0_SA_DQ<14>")
	)
	(segment
		(start 428.556674 -213.747096)
		(end 428.719742 -213.910164)
		(width 0.14478)
		(layer "In6.Cu")
		(net "M_K_CPU0_SA_DQ<14>")
	)
	(segment
		(start 413.303466 -213.679278)
		(end 413.303466 -213.747096)
		(width 0.14478)
		(layer "In6.Cu")
		(net "M_K_CPU0_SA_DQ<14>")
	)
	(segment
		(start 432.500532 -212.681312)
		(end 432.645312 -212.826092)
		(width 0.14478)
		(layer "In6.Cu")
		(net "M_K_CPU0_SA_DQ<14>")
	)
	(segment
		(start 434.047646 -213.765384)
		(end 434.047646 -213.674452)
		(width 0.14478)
		(layer "In6.Cu")
		(net "M_K_CPU0_SA_DQ<14>")
	)
	(segment
		(start 396.604744 -230.99395)
		(end 405.189436 -222.409258)
		(width 0.14478)
		(layer "In6.Cu")
		(net "M_K_CPU0_SA_DQ<14>")
	)
	(segment
		(start 434.047646 -213.674452)
		(end 434.192426 -213.529672)
		(width 0.14478)
		(layer "In6.Cu")
		(net "M_K_CPU0_SA_DQ<14>")
	)
	(segment
		(start 429.08093 -213.910164)
		(end 429.931068 -213.060026)
		(width 0.14478)
		(layer "In6.Cu")
		(net "M_K_CPU0_SA_DQ<14>")
	)
	(segment
		(start 415.638996 -212.896958)
		(end 415.638996 -212.838538)
		(width 0.14478)
		(layer "In6.Cu")
		(net "M_K_CPU0_SA_DQ<14>")
	)
	(segment
		(start 417.14547 -212.67547)
		(end 417.308538 -212.838538)
		(width 0.14478)
		(layer "In6.Cu")
		(net "M_K_CPU0_SA_DQ<14>")
	)
	(segment
		(start 434.59908 -213.765384)
		(end 434.74386 -213.910164)
		(width 0.14478)
		(layer "In6.Cu")
		(net "M_K_CPU0_SA_DQ<14>")
	)
	(segment
		(start 420.34206 -213.910164)
		(end 420.48684 -213.765384)
		(width 0.14478)
		(layer "In6.Cu")
		(net "M_K_CPU0_SA_DQ<14>")
	)
	(segment
		(start 438.513982 -213.060026)
		(end 439.707274 -213.060026)
		(width 0.14478)
		(layer "In6.Cu")
		(net "M_K_CPU0_SA_DQ<14>")
	)
	(segment
		(start 416.588956 -213.060026)
		(end 416.752024 -212.896958)
		(width 0.14478)
		(layer "In6.Cu")
		(net "M_K_CPU0_SA_DQ<14>")
	)
	(segment
		(start 418.698172 -213.910164)
		(end 420.34206 -213.910164)
		(width 0.14478)
		(layer "In6.Cu")
		(net "M_K_CPU0_SA_DQ<14>")
	)
	(segment
		(start 414.85693 -213.060026)
		(end 415.475928 -213.060026)
		(width 0.14478)
		(layer "In6.Cu")
		(net "M_K_CPU0_SA_DQ<14>")
	)
	(segment
		(start 430.753012 -212.67547)
		(end 430.91608 -212.838538)
		(width 0.14478)
		(layer "In6.Cu")
		(net "M_K_CPU0_SA_DQ<14>")
	)
	(segment
		(start 430.359566 -212.896958)
		(end 430.359566 -212.838538)
		(width 0.14478)
		(layer "In6.Cu")
		(net "M_K_CPU0_SA_DQ<14>")
	)
	(segment
		(start 417.471606 -213.060026)
		(end 417.848034 -213.060026)
		(width 0.14478)
		(layer "In6.Cu")
		(net "M_K_CPU0_SA_DQ<14>")
	)
	(segment
		(start 435.360318 -213.910164)
		(end 435.523386 -213.747096)
		(width 0.14478)
		(layer "In6.Cu")
		(net "M_K_CPU0_SA_DQ<14>")
	)
	(segment
		(start 396.294864 -231.30383)
		(end 396.604744 -230.99395)
		(width 0.0889)
		(layer "In6.Cu")
		(net "M_K_CPU0_SA_DQ<14>")
	)
	(segment
		(start 440.820302 -212.669882)
		(end 440.98337 -212.83295)
		(width 0.14478)
		(layer "In6.Cu")
		(net "M_K_CPU0_SA_DQ<14>")
	)
	(segment
		(start 440.589924 -212.669882)
		(end 440.820302 -212.669882)
		(width 0.14478)
		(layer "In6.Cu")
		(net "M_K_CPU0_SA_DQ<14>")
	)
	(segment
		(start 391.947146 -233.637582)
		(end 391.95756 -233.631486)
		(width 0.0889)
		(layer "In6.Cu")
		(net "M_K_CPU0_SA_DQ<14>")
	)
	(segment
		(start 434.74386 -213.910164)
		(end 435.360318 -213.910164)
		(width 0.14478)
		(layer "In6.Cu")
		(net "M_K_CPU0_SA_DQ<14>")
	)
	(segment
		(start 421.549322 -213.910164)
		(end 422.39946 -213.060026)
		(width 0.14478)
		(layer "In6.Cu")
		(net "M_K_CPU0_SA_DQ<14>")
	)
	(segment
		(start 421.183054 -213.910164)
		(end 421.549322 -213.910164)
		(width 0.14478)
		(layer "In6.Cu")
		(net "M_K_CPU0_SA_DQ<14>")
	)
	(segment
		(start 394.324078 -232.578656)
		(end 394.426948 -232.578656)
		(width 0.0889)
		(layer "In6.Cu")
		(net "M_K_CPU0_SA_DQ<14>")
	)
	(segment
		(start 415.802064 -212.67547)
		(end 416.032442 -212.67547)
		(width 0.14478)
		(layer "In6.Cu")
		(net "M_K_CPU0_SA_DQ<14>")
	)
	(segment
		(start 413.466534 -213.910164)
		(end 414.006792 -213.910164)
		(width 0.14478)
		(layer "In6.Cu")
		(net "M_K_CPU0_SA_DQ<14>")
	)
	(segment
		(start 416.032442 -212.67547)
		(end 416.19551 -212.838538)
		(width 0.14478)
		(layer "In6.Cu")
		(net "M_K_CPU0_SA_DQ<14>")
	)
	(segment
		(start 417.308538 -212.896958)
		(end 417.471606 -213.060026)
		(width 0.14478)
		(layer "In6.Cu")
		(net "M_K_CPU0_SA_DQ<14>")
	)
	(segment
		(start 436.242968 -213.910164)
		(end 436.6133 -213.910164)
		(width 0.14478)
		(layer "In6.Cu")
		(net "M_K_CPU0_SA_DQ<14>")
	)
	(segment
		(start 394.426948 -232.578656)
		(end 395.701774 -231.30383)
		(width 0.0889)
		(layer "In6.Cu")
		(net "M_K_CPU0_SA_DQ<14>")
	)
	(segment
		(start 436.0799 -213.747096)
		(end 436.242968 -213.910164)
		(width 0.14478)
		(layer "In6.Cu")
		(net "M_K_CPU0_SA_DQ<14>")
	)
	(segment
		(start 405.189436 -222.409258)
		(end 405.189436 -220.902022)
		(width 0.14478)
		(layer "In6.Cu")
		(net "M_K_CPU0_SA_DQ<14>")
	)
	(segment
		(start 430.196498 -213.060026)
		(end 430.359566 -212.896958)
		(width 0.14478)
		(layer "In6.Cu")
		(net "M_K_CPU0_SA_DQ<14>")
	)
	(segment
		(start 439.707274 -213.060026)
		(end 439.870342 -213.223094)
		(width 0.14478)
		(layer "In6.Cu")
		(net "M_K_CPU0_SA_DQ<14>")
	)
	(segment
		(start 436.0799 -213.68512)
		(end 436.0799 -213.747096)
		(width 0.14478)
		(layer "In6.Cu")
		(net "M_K_CPU0_SA_DQ<14>")
	)
	(segment
		(start 412.746952 -213.747096)
		(end 412.746952 -213.679278)
		(width 0.14478)
		(layer "In6.Cu")
		(net "M_K_CPU0_SA_DQ<14>")
	)
	(segment
		(start 432.093878 -212.826092)
		(end 432.238658 -212.681312)
		(width 0.14478)
		(layer "In6.Cu")
		(net "M_K_CPU0_SA_DQ<14>")
	)
	(segment
		(start 414.006792 -213.910164)
		(end 414.85693 -213.060026)
		(width 0.14478)
		(layer "In6.Cu")
		(net "M_K_CPU0_SA_DQ<14>")
	)
	(segment
		(start 416.915092 -212.67547)
		(end 417.14547 -212.67547)
		(width 0.14478)
		(layer "In6.Cu")
		(net "M_K_CPU0_SA_DQ<14>")
	)
	(segment
		(start 405.189436 -220.902022)
		(end 412.181294 -213.910164)
		(width 0.14478)
		(layer "In6.Cu")
		(net "M_K_CPU0_SA_DQ<14>")
	)
	(segment
		(start 439.870342 -213.223094)
		(end 439.870342 -213.287102)
		(width 0.14478)
		(layer "In6.Cu")
		(net "M_K_CPU0_SA_DQ<14>")
	)
	(segment
		(start 439.870342 -213.287102)
		(end 440.03341 -213.45017)
		(width 0.14478)
		(layer "In6.Cu")
		(net "M_K_CPU0_SA_DQ<14>")
	)
	(segment
		(start 412.181294 -213.910164)
		(end 412.583884 -213.910164)
		(width 0.14478)
		(layer "In6.Cu")
		(net "M_K_CPU0_SA_DQ<14>")
	)
	(segment
		(start 440.98337 -213.287102)
		(end 441.146438 -213.45017)
		(width 0.14478)
		(layer "In6.Cu")
		(net "M_K_CPU0_SA_DQ<14>")
	)
	(segment
		(start 417.308538 -212.838538)
		(end 417.308538 -212.896958)
		(width 0.14478)
		(layer "In6.Cu")
		(net "M_K_CPU0_SA_DQ<14>")
	)
	(segment
		(start 430.91608 -212.838538)
		(end 430.91608 -212.896958)
		(width 0.14478)
		(layer "In6.Cu")
		(net "M_K_CPU0_SA_DQ<14>")
	)
	(segment
		(start 416.19551 -212.838538)
		(end 416.19551 -212.896958)
		(width 0.14478)
		(layer "In6.Cu")
		(net "M_K_CPU0_SA_DQ<14>")
	)
	(segment
		(start 435.686454 -213.522052)
		(end 435.916832 -213.522052)
		(width 0.14478)
		(layer "In6.Cu")
		(net "M_K_CPU0_SA_DQ<14>")
	)
	(segment
		(start 426.242226 -213.910164)
		(end 427.837092 -213.910164)
		(width 0.14478)
		(layer "In6.Cu")
		(net "M_K_CPU0_SA_DQ<14>")
	)
	(segment
		(start 415.638996 -212.838538)
		(end 415.802064 -212.67547)
		(width 0.14478)
		(layer "In6.Cu")
		(net "M_K_CPU0_SA_DQ<14>")
	)
	(segment
		(start 420.893494 -213.522052)
		(end 421.038274 -213.666832)
		(width 0.14478)
		(layer "In6.Cu")
		(net "M_K_CPU0_SA_DQ<14>")
	)
	(segment
		(start 428.00016 -213.747096)
		(end 428.00016 -213.6902)
		(width 0.14478)
		(layer "In6.Cu")
		(net "M_K_CPU0_SA_DQ<14>")
	)
	(segment
		(start 432.935888 -213.060026)
		(end 433.786026 -213.910164)
		(width 0.14478)
		(layer "In6.Cu")
		(net "M_K_CPU0_SA_DQ<14>")
	)
	(segment
		(start 440.03341 -213.45017)
		(end 440.263788 -213.45017)
		(width 0.14478)
		(layer "In6.Cu")
		(net "M_K_CPU0_SA_DQ<14>")
	)
	(segment
		(start 420.63162 -213.522052)
		(end 420.893494 -213.522052)
		(width 0.14478)
		(layer "In6.Cu")
		(net "M_K_CPU0_SA_DQ<14>")
	)
	(segment
		(start 432.093878 -212.915246)
		(end 432.093878 -212.826092)
		(width 0.14478)
		(layer "In6.Cu")
		(net "M_K_CPU0_SA_DQ<14>")
	)
	(segment
		(start 432.238658 -212.681312)
		(end 432.500532 -212.681312)
		(width 0.14478)
		(layer "In6.Cu")
		(net "M_K_CPU0_SA_DQ<14>")
	)
	(segment
		(start 416.358578 -213.060026)
		(end 416.588956 -213.060026)
		(width 0.14478)
		(layer "In6.Cu")
		(net "M_K_CPU0_SA_DQ<14>")
	)
	(segment
		(start 440.426856 -213.287102)
		(end 440.426856 -212.83295)
		(width 0.14478)
		(layer "In6.Cu")
		(net "M_K_CPU0_SA_DQ<14>")
	)
	(segment
		(start 432.645312 -212.826092)
		(end 432.645312 -212.915246)
		(width 0.14478)
		(layer "In6.Cu")
		(net "M_K_CPU0_SA_DQ<14>")
	)
	(segment
		(start 412.583884 -213.910164)
		(end 412.746952 -213.747096)
		(width 0.14478)
		(layer "In6.Cu")
		(net "M_K_CPU0_SA_DQ<14>")
	)
	(segment
		(start 417.848034 -213.060026)
		(end 418.698172 -213.910164)
		(width 0.14478)
		(layer "In6.Cu")
		(net "M_K_CPU0_SA_DQ<14>")
	)
	(segment
		(start 422.907968 -212.896958)
		(end 422.907968 -212.8393)
		(width 0.14478)
		(layer "In6.Cu")
		(net "M_K_CPU0_SA_DQ<14>")
	)
	(segment
		(start 423.464482 -212.8393)
		(end 423.464482 -212.896958)
		(width 0.14478)
		(layer "In6.Cu")
		(net "M_K_CPU0_SA_DQ<14>")
	)
	(segment
		(start 415.475928 -213.060026)
		(end 415.638996 -212.896958)
		(width 0.14478)
		(layer "In6.Cu")
		(net "M_K_CPU0_SA_DQ<14>")
	)
	(segment
		(start 435.916832 -213.522052)
		(end 436.0799 -213.68512)
		(width 0.14478)
		(layer "In6.Cu")
		(net "M_K_CPU0_SA_DQ<14>")
	)
	(segment
		(start 441.376816 -213.45017)
		(end 441.539884 -213.287102)
		(width 0.14478)
		(layer "In6.Cu")
		(net "M_K_CPU0_SA_DQ<14>")
	)
	(segment
		(start 438.224422 -212.681312)
		(end 438.369202 -212.826092)
		(width 0.14478)
		(layer "In6.Cu")
		(net "M_K_CPU0_SA_DQ<14>")
	)
	(segment
		(start 431.949098 -213.060026)
		(end 432.093878 -212.915246)
		(width 0.14478)
		(layer "In6.Cu")
		(net "M_K_CPU0_SA_DQ<14>")
	)
	(segment
		(start 437.463438 -213.060026)
		(end 437.672988 -213.060026)
		(width 0.14478)
		(layer "In6.Cu")
		(net "M_K_CPU0_SA_DQ<14>")
	)
	(segment
		(start 428.556674 -213.6902)
		(end 428.556674 -213.747096)
		(width 0.14478)
		(layer "In6.Cu")
		(net "M_K_CPU0_SA_DQ<14>")
	)
	(segment
		(start 437.817768 -212.826092)
		(end 437.962548 -212.681312)
		(width 0.14478)
		(layer "In6.Cu")
		(net "M_K_CPU0_SA_DQ<14>")
	)
	(segment
		(start 434.4543 -213.529672)
		(end 434.59908 -213.674452)
		(width 0.14478)
		(layer "In6.Cu")
		(net "M_K_CPU0_SA_DQ<14>")
	)
	(segment
		(start 413.303466 -213.747096)
		(end 413.466534 -213.910164)
		(width 0.14478)
		(layer "In6.Cu")
		(net "M_K_CPU0_SA_DQ<14>")
	)
	(segment
		(start 395.701774 -231.30383)
		(end 396.294864 -231.30383)
		(width 0.0889)
		(layer "In6.Cu")
		(net "M_K_CPU0_SA_DQ<14>")
	)
	(segment
		(start 432.645312 -212.915246)
		(end 432.790092 -213.060026)
		(width 0.14478)
		(layer "In6.Cu")
		(net "M_K_CPU0_SA_DQ<14>")
	)
	(segment
		(start 428.719742 -213.910164)
		(end 429.08093 -213.910164)
		(width 0.14478)
		(layer "In6.Cu")
		(net "M_K_CPU0_SA_DQ<14>")
	)
	(segment
		(start 423.62755 -213.060026)
		(end 425.392088 -213.060026)
		(width 0.14478)
		(layer "In6.Cu")
		(net "M_K_CPU0_SA_DQ<14>")
	)
	(segment
		(start 442.119258 -213.060026)
		(end 442.5442 -213.484968)
		(width 0.14478)
		(layer "In6.Cu")
		(net "M_K_CPU0_SA_DQ<14>")
	)
	(segment
		(start 393.084812 -233.58094)
		(end 393.321794 -233.58094)
		(width 0.0889)
		(layer "In6.Cu")
		(net "M_K_CPU0_SA_DQ<14>")
	)
	(segment
		(start 437.817768 -212.915246)
		(end 437.817768 -212.826092)
		(width 0.14478)
		(layer "In6.Cu")
		(net "M_K_CPU0_SA_DQ<14>")
	)
	(segment
		(start 416.19551 -212.896958)
		(end 416.358578 -213.060026)
		(width 0.14478)
		(layer "In6.Cu")
		(net "M_K_CPU0_SA_DQ<14>")
	)
	(segment
		(start 440.263788 -213.45017)
		(end 440.426856 -213.287102)
		(width 0.14478)
		(layer "In6.Cu")
		(net "M_K_CPU0_SA_DQ<14>")
	)
	(segment
		(start 437.672988 -213.060026)
		(end 437.817768 -212.915246)
		(width 0.14478)
		(layer "In6.Cu")
		(net "M_K_CPU0_SA_DQ<14>")
	)
	(segment
		(start 438.369202 -212.826092)
		(end 438.369202 -212.915246)
		(width 0.14478)
		(layer "In6.Cu")
		(net "M_K_CPU0_SA_DQ<14>")
	)
	(segment
		(start 421.038274 -213.666832)
		(end 421.038274 -213.765384)
		(width 0.14478)
		(layer "In6.Cu")
		(net "M_K_CPU0_SA_DQ<14>")
	)
	(segment
		(start 390.418828 -233.688636)
		(end 390.51484 -233.663236)
		(width 0.0889)
		(layer "In6.Cu")
		(net "M_K_CPU0_SA_DQ<14>")
	)
	(segment
		(start 422.7449 -213.060026)
		(end 422.907968 -212.896958)
		(width 0.14478)
		(layer "In6.Cu")
		(net "M_K_CPU0_SA_DQ<14>")
	)
	(segment
		(start 422.39946 -213.060026)
		(end 422.7449 -213.060026)
		(width 0.14478)
		(layer "In6.Cu")
		(net "M_K_CPU0_SA_DQ<14>")
	)
	(segment
		(start 413.140398 -213.51621)
		(end 413.303466 -213.679278)
		(width 0.14478)
		(layer "In6.Cu")
		(net "M_K_CPU0_SA_DQ<14>")
	)
	(segment
		(start 428.163228 -213.527132)
		(end 428.393606 -213.527132)
		(width 0.14478)
		(layer "In6.Cu")
		(net "M_K_CPU0_SA_DQ<14>")
	)
	(segment
		(start 436.6133 -213.910164)
		(end 437.463438 -213.060026)
		(width 0.14478)
		(layer "In6.Cu")
		(net "M_K_CPU0_SA_DQ<14>")
	)
	(segment
		(start 422.907968 -212.8393)
		(end 423.071036 -212.676232)
		(width 0.14478)
		(layer "In6.Cu")
		(net "M_K_CPU0_SA_DQ<14>")
	)
	(segment
		(start 416.752024 -212.838538)
		(end 416.915092 -212.67547)
		(width 0.14478)
		(layer "In6.Cu")
		(net "M_K_CPU0_SA_DQ<14>")
	)
	(segment
		(start 412.91002 -213.51621)
		(end 413.140398 -213.51621)
		(width 0.14478)
		(layer "In6.Cu")
		(net "M_K_CPU0_SA_DQ<14>")
	)
	(segment
		(start 441.539884 -213.223094)
		(end 441.702952 -213.060026)
		(width 0.14478)
		(layer "In6.Cu")
		(net "M_K_CPU0_SA_DQ<14>")
	)
	(segment
		(start 440.98337 -212.83295)
		(end 440.98337 -213.287102)
		(width 0.14478)
		(layer "In6.Cu")
		(net "M_K_CPU0_SA_DQ<14>")
	)
	(segment
		(start 390.264904 -233.954066)
		(end 390.418828 -233.688636)
		(width 0.0889)
		(layer "In6.Cu")
		(net "M_K_CPU0_SA_DQ<14>")
	)
	(segment
		(start 430.91608 -212.896958)
		(end 431.079148 -213.060026)
		(width 0.14478)
		(layer "In6.Cu")
		(net "M_K_CPU0_SA_DQ<14>")
	)
	(segment
		(start 416.752024 -212.896958)
		(end 416.752024 -212.838538)
		(width 0.14478)
		(layer "In6.Cu")
		(net "M_K_CPU0_SA_DQ<14>")
	)
	(segment
		(start 428.00016 -213.6902)
		(end 428.163228 -213.527132)
		(width 0.14478)
		(layer "In6.Cu")
		(net "M_K_CPU0_SA_DQ<14>")
	)
	(segment
		(start 393.321794 -233.58094)
		(end 394.324078 -232.578656)
		(width 0.0889)
		(layer "In6.Cu")
		(net "M_K_CPU0_SA_DQ<14>")
	)
	(segment
		(start 412.746952 -213.679278)
		(end 412.91002 -213.51621)
		(width 0.14478)
		(layer "In6.Cu")
		(net "M_K_CPU0_SA_DQ<14>")
	)
	(segment
		(start 441.146438 -213.45017)
		(end 441.376816 -213.45017)
		(width 0.14478)
		(layer "In6.Cu")
		(net "M_K_CPU0_SA_DQ<14>")
	)
	(segment
		(start 430.359566 -212.838538)
		(end 430.522634 -212.67547)
		(width 0.14478)
		(layer "In6.Cu")
		(net "M_K_CPU0_SA_DQ<14>")
	)
	(segment
		(start 432.790092 -213.060026)
		(end 432.935888 -213.060026)
		(width 0.14478)
		(layer "In6.Cu")
		(net "M_K_CPU0_SA_DQ<14>")
	)
	(segment
		(start 420.48684 -213.765384)
		(end 420.48684 -213.666832)
		(width 0.14478)
		(layer "In6.Cu")
		(net "M_K_CPU0_SA_DQ<14>")
	)
	(segment
		(start 431.079148 -213.060026)
		(end 431.949098 -213.060026)
		(width 0.14478)
		(layer "In6.Cu")
		(net "M_K_CPU0_SA_DQ<14>")
	)
	(segment
		(start 430.522634 -212.67547)
		(end 430.753012 -212.67547)
		(width 0.14478)
		(layer "In6.Cu")
		(net "M_K_CPU0_SA_DQ<14>")
	)
	(segment
		(start 433.902866 -213.910164)
		(end 434.047646 -213.765384)
		(width 0.14478)
		(layer "In6.Cu")
		(net "M_K_CPU0_SA_DQ<14>")
	)
	(segment
		(start 434.59908 -213.674452)
		(end 434.59908 -213.765384)
		(width 0.14478)
		(layer "In6.Cu")
		(net "M_K_CPU0_SA_DQ<14>")
	)
	(arc
		(start 392.897614 -233.631486)
		(mid 392.987874 -233.593858)
		(end 393.084812 -233.58094)
		(width 0.0889)
		(layer "In6.Cu")
		(net "M_K_CPU0_SA_DQ<14>")
	)
	(arc
		(start 391.391902 -233.631486)
		(mid 391.668715 -233.707629)
		(end 391.947146 -233.637582)
		(width 0.0889)
		(layer "In6.Cu")
		(net "M_K_CPU0_SA_DQ<14>")
	)
	(arc
		(start 390.51484 -233.663236)
		(mid 390.770048 -233.706713)
		(end 391.01776 -233.631486)
		(width 0.0889)
		(layer "In6.Cu")
		(net "M_K_CPU0_SA_DQ<14>")
	)
	(arc
		(start 392.341862 -233.637582)
		(mid 392.620548 -233.707802)
		(end 392.897614 -233.631486)
		(width 0.0889)
		(layer "In6.Cu")
		(net "M_K_CPU0_SA_DQ<14>")
	)
	(arc
		(start 391.95756 -233.631486)
		(mid 392.144504 -233.581231)
		(end 392.331448 -233.631486)
		(width 0.0889)
		(layer "In6.Cu")
		(net "M_K_CPU0_SA_DQ<14>")
	)
	(arc
		(start 391.026142 -233.62666)
		(mid 391.20965 -233.581166)
		(end 391.391902 -233.631486)
		(width 0.0889)
		(layer "In6.Cu")
		(net "M_K_CPU0_SA_DQ<14>")
	)
	(segment
		(start 388.857998 -234.220004)
		(end 389.32485 -233.954066)
		(width 0.10668)
		(layer "F.Cu")
		(net "M_K_CPU0_SA_DQ<13>")
	)
	(segment
		(start 390.443466 -234.281472)
		(end 390.451848 -234.276646)
		(width 0.0889)
		(layer "In6.Cu")
		(net "M_K_CPU0_SA_DQ<13>")
	)
	(segment
		(start 425.392342 -213.910164)
		(end 426.242226 -214.760048)
		(width 0.14478)
		(layer "In6.Cu")
		(net "M_K_CPU0_SA_DQ<13>")
	)
	(segment
		(start 394.112496 -233.13771)
		(end 394.417296 -232.83291)
		(width 0.0889)
		(layer "In6.Cu")
		(net "M_K_CPU0_SA_DQ<13>")
	)
	(segment
		(start 394.112496 -233.495596)
		(end 394.112496 -233.13771)
		(width 0.0889)
		(layer "In6.Cu")
		(net "M_K_CPU0_SA_DQ<13>")
	)
	(segment
		(start 396.920212 -231.32161)
		(end 405.644096 -222.597726)
		(width 0.14478)
		(layer "In6.Cu")
		(net "M_K_CPU0_SA_DQ<13>")
	)
	(segment
		(start 437.5912 -213.910164)
		(end 444.85052 -213.910164)
		(width 0.14478)
		(layer "In6.Cu")
		(net "M_K_CPU0_SA_DQ<13>")
	)
	(segment
		(start 393.27709 -234.27309)
		(end 393.44092 -234.167172)
		(width 0.0889)
		(layer "In6.Cu")
		(net "M_K_CPU0_SA_DQ<13>")
	)
	(segment
		(start 405.644096 -221.464886)
		(end 412.348934 -214.760048)
		(width 0.14478)
		(layer "In6.Cu")
		(net "M_K_CPU0_SA_DQ<13>")
	)
	(segment
		(start 392.331194 -234.276646)
		(end 392.341608 -234.27055)
		(width 0.0889)
		(layer "In6.Cu")
		(net "M_K_CPU0_SA_DQ<13>")
	)
	(segment
		(start 446.219326 -213.910164)
		(end 446.644268 -214.335106)
		(width 0.14478)
		(layer "In6.Cu")
		(net "M_K_CPU0_SA_DQ<13>")
	)
	(segment
		(start 429.08093 -214.760048)
		(end 429.930814 -213.910164)
		(width 0.14478)
		(layer "In6.Cu")
		(net "M_K_CPU0_SA_DQ<13>")
	)
	(segment
		(start 389.32485 -233.954066)
		(end 389.170926 -234.219496)
		(width 0.0889)
		(layer "In6.Cu")
		(net "M_K_CPU0_SA_DQ<13>")
	)
	(segment
		(start 391.947146 -234.27055)
		(end 391.95756 -234.276646)
		(width 0.0889)
		(layer "In6.Cu")
		(net "M_K_CPU0_SA_DQ<13>")
	)
	(segment
		(start 393.44092 -234.167172)
		(end 394.112496 -233.495596)
		(width 0.0889)
		(layer "In6.Cu")
		(net "M_K_CPU0_SA_DQ<13>")
	)
	(segment
		(start 396.531592 -231.71023)
		(end 396.920212 -231.32161)
		(width 0.0889)
		(layer "In6.Cu")
		(net "M_K_CPU0_SA_DQ<13>")
	)
	(segment
		(start 445.546734 -214.054944)
		(end 445.691514 -213.910164)
		(width 0.14478)
		(layer "In6.Cu")
		(net "M_K_CPU0_SA_DQ<13>")
	)
	(segment
		(start 394.417296 -232.83291)
		(end 394.592556 -232.83291)
		(width 0.0889)
		(layer "In6.Cu")
		(net "M_K_CPU0_SA_DQ<13>")
	)
	(segment
		(start 395.715236 -231.71023)
		(end 396.531592 -231.71023)
		(width 0.0889)
		(layer "In6.Cu")
		(net "M_K_CPU0_SA_DQ<13>")
	)
	(segment
		(start 389.170926 -234.219496)
		(end 389.193278 -234.302808)
		(width 0.0889)
		(layer "In6.Cu")
		(net "M_K_CPU0_SA_DQ<13>")
	)
	(segment
		(start 417.848034 -213.90991)
		(end 418.698172 -214.760048)
		(width 0.14478)
		(layer "In6.Cu")
		(net "M_K_CPU0_SA_DQ<13>")
	)
	(segment
		(start 436.741316 -214.760048)
		(end 437.5912 -213.910164)
		(width 0.14478)
		(layer "In6.Cu")
		(net "M_K_CPU0_SA_DQ<13>")
	)
	(segment
		(start 421.549322 -214.760048)
		(end 422.399206 -213.910164)
		(width 0.14478)
		(layer "In6.Cu")
		(net "M_K_CPU0_SA_DQ<13>")
	)
	(segment
		(start 391.01776 -234.276646)
		(end 391.026142 -234.281472)
		(width 0.0889)
		(layer "In6.Cu")
		(net "M_K_CPU0_SA_DQ<13>")
	)
	(segment
		(start 405.644096 -222.597726)
		(end 405.644096 -221.464886)
		(width 0.14478)
		(layer "In6.Cu")
		(net "M_K_CPU0_SA_DQ<13>")
	)
	(segment
		(start 426.242226 -214.760048)
		(end 429.08093 -214.760048)
		(width 0.14478)
		(layer "In6.Cu")
		(net "M_K_CPU0_SA_DQ<13>")
	)
	(segment
		(start 391.95756 -234.276646)
		(end 391.965942 -234.281472)
		(width 0.0889)
		(layer "In6.Cu")
		(net "M_K_CPU0_SA_DQ<13>")
	)
	(segment
		(start 445.14008 -214.451692)
		(end 445.401954 -214.451692)
		(width 0.14478)
		(layer "In6.Cu")
		(net "M_K_CPU0_SA_DQ<13>")
	)
	(segment
		(start 444.9953 -214.054944)
		(end 444.9953 -214.306912)
		(width 0.14478)
		(layer "In6.Cu")
		(net "M_K_CPU0_SA_DQ<13>")
	)
	(segment
		(start 444.85052 -213.910164)
		(end 444.9953 -214.054944)
		(width 0.14478)
		(layer "In6.Cu")
		(net "M_K_CPU0_SA_DQ<13>")
	)
	(segment
		(start 432.936142 -213.910164)
		(end 433.786026 -214.760048)
		(width 0.14478)
		(layer "In6.Cu")
		(net "M_K_CPU0_SA_DQ<13>")
	)
	(segment
		(start 429.930814 -213.910164)
		(end 432.936142 -213.910164)
		(width 0.14478)
		(layer "In6.Cu")
		(net "M_K_CPU0_SA_DQ<13>")
	)
	(segment
		(start 418.698172 -214.760048)
		(end 421.549322 -214.760048)
		(width 0.14478)
		(layer "In6.Cu")
		(net "M_K_CPU0_SA_DQ<13>")
	)
	(segment
		(start 422.399206 -213.910164)
		(end 425.392342 -213.910164)
		(width 0.14478)
		(layer "In6.Cu")
		(net "M_K_CPU0_SA_DQ<13>")
	)
	(segment
		(start 394.592556 -232.83291)
		(end 395.715236 -231.71023)
		(width 0.0889)
		(layer "In6.Cu")
		(net "M_K_CPU0_SA_DQ<13>")
	)
	(segment
		(start 445.546734 -214.306912)
		(end 445.546734 -214.054944)
		(width 0.14478)
		(layer "In6.Cu")
		(net "M_K_CPU0_SA_DQ<13>")
	)
	(segment
		(start 393.253214 -234.286806)
		(end 393.27709 -234.27309)
		(width 0.0889)
		(layer "In6.Cu")
		(net "M_K_CPU0_SA_DQ<13>")
	)
	(segment
		(start 433.786026 -214.760048)
		(end 436.741316 -214.760048)
		(width 0.14478)
		(layer "In6.Cu")
		(net "M_K_CPU0_SA_DQ<13>")
	)
	(segment
		(start 414.896554 -213.90991)
		(end 417.848034 -213.90991)
		(width 0.14478)
		(layer "In6.Cu")
		(net "M_K_CPU0_SA_DQ<13>")
	)
	(segment
		(start 412.348934 -214.760048)
		(end 414.046416 -214.760048)
		(width 0.14478)
		(layer "In6.Cu")
		(net "M_K_CPU0_SA_DQ<13>")
	)
	(segment
		(start 445.691514 -213.910164)
		(end 446.219326 -213.910164)
		(width 0.14478)
		(layer "In6.Cu")
		(net "M_K_CPU0_SA_DQ<13>")
	)
	(segment
		(start 445.401954 -214.451692)
		(end 445.546734 -214.306912)
		(width 0.14478)
		(layer "In6.Cu")
		(net "M_K_CPU0_SA_DQ<13>")
	)
	(segment
		(start 444.9953 -214.306912)
		(end 445.14008 -214.451692)
		(width 0.14478)
		(layer "In6.Cu")
		(net "M_K_CPU0_SA_DQ<13>")
	)
	(segment
		(start 414.046416 -214.760048)
		(end 414.896554 -213.90991)
		(width 0.14478)
		(layer "In6.Cu")
		(net "M_K_CPU0_SA_DQ<13>")
	)
	(arc
		(start 390.451848 -234.276646)
		(mid 390.734804 -234.200469)
		(end 391.01776 -234.276646)
		(width 0.0889)
		(layer "In6.Cu")
		(net "M_K_CPU0_SA_DQ<13>")
	)
	(arc
		(start 391.026142 -234.281472)
		(mid 391.20965 -234.326966)
		(end 391.391902 -234.276646)
		(width 0.0889)
		(layer "In6.Cu")
		(net "M_K_CPU0_SA_DQ<13>")
	)
	(arc
		(start 390.077706 -234.276646)
		(mid 390.259957 -234.326996)
		(end 390.443466 -234.281472)
		(width 0.0889)
		(layer "In6.Cu")
		(net "M_K_CPU0_SA_DQ<13>")
	)
	(arc
		(start 392.341608 -234.27055)
		(mid 392.620294 -234.20033)
		(end 392.89736 -234.276646)
		(width 0.0889)
		(layer "In6.Cu")
		(net "M_K_CPU0_SA_DQ<13>")
	)
	(arc
		(start 389.511794 -234.276646)
		(mid 389.79475 -234.200469)
		(end 390.077706 -234.276646)
		(width 0.0889)
		(layer "In6.Cu")
		(net "M_K_CPU0_SA_DQ<13>")
	)
	(arc
		(start 392.89736 -234.276646)
		(mid 393.073988 -234.326879)
		(end 393.253214 -234.286806)
		(width 0.0889)
		(layer "In6.Cu")
		(net "M_K_CPU0_SA_DQ<13>")
	)
	(arc
		(start 391.965942 -234.281472)
		(mid 392.149196 -234.326845)
		(end 392.331194 -234.276646)
		(width 0.0889)
		(layer "In6.Cu")
		(net "M_K_CPU0_SA_DQ<13>")
	)
	(arc
		(start 389.193278 -234.302808)
		(mid 389.355467 -234.325543)
		(end 389.511794 -234.276646)
		(width 0.0889)
		(layer "In6.Cu")
		(net "M_K_CPU0_SA_DQ<13>")
	)
	(arc
		(start 391.391902 -234.276646)
		(mid 391.668715 -234.200503)
		(end 391.947146 -234.27055)
		(width 0.0889)
		(layer "In6.Cu")
		(net "M_K_CPU0_SA_DQ<13>")
	)
	(segment
		(start 390.267952 -233.409998)
		(end 390.734804 -233.14406)
		(width 0.10668)
		(layer "F.Cu")
		(net "M_K_CPU0_SA_DQ<12>")
	)
	(segment
		(start 396.230856 -230.72471)
		(end 404.734776 -222.22079)
		(width 0.14478)
		(layer "In6.Cu")
		(net "M_K_CPU0_SA_DQ<12>")
	)
	(segment
		(start 444.789814 -212.779102)
		(end 444.952882 -212.94217)
		(width 0.14478)
		(layer "In6.Cu")
		(net "M_K_CPU0_SA_DQ<12>")
	)
	(segment
		(start 394.98778 -231.434386)
		(end 395.539976 -230.88219)
		(width 0.0889)
		(layer "In6.Cu")
		(net "M_K_CPU0_SA_DQ<12>")
	)
	(segment
		(start 391.85342 -233.471466)
		(end 391.861802 -233.46664)
		(width 0.0889)
		(layer "In6.Cu")
		(net "M_K_CPU0_SA_DQ<12>")
	)
	(segment
		(start 393.084812 -233.39044)
		(end 393.231116 -233.39044)
		(width 0.0889)
		(layer "In6.Cu")
		(net "M_K_CPU0_SA_DQ<12>")
	)
	(segment
		(start 426.251624 -213.069424)
		(end 429.071532 -213.069424)
		(width 0.14478)
		(layer "In6.Cu")
		(net "M_K_CPU0_SA_DQ<12>")
	)
	(segment
		(start 433.795424 -213.069424)
		(end 436.731918 -213.069424)
		(width 0.14478)
		(layer "In6.Cu")
		(net "M_K_CPU0_SA_DQ<12>")
	)
	(segment
		(start 414.046416 -213.060026)
		(end 414.887156 -212.219286)
		(width 0.14478)
		(layer "In6.Cu")
		(net "M_K_CPU0_SA_DQ<12>")
	)
	(segment
		(start 393.231116 -233.39044)
		(end 394.32738 -232.294176)
		(width 0.0889)
		(layer "In6.Cu")
		(net "M_K_CPU0_SA_DQ<12>")
	)
	(segment
		(start 421.539924 -213.069424)
		(end 422.389808 -212.21954)
		(width 0.14478)
		(layer "In6.Cu")
		(net "M_K_CPU0_SA_DQ<12>")
	)
	(segment
		(start 412.388304 -213.060026)
		(end 414.046416 -213.060026)
		(width 0.14478)
		(layer "In6.Cu")
		(net "M_K_CPU0_SA_DQ<12>")
	)
	(segment
		(start 425.40174 -212.21954)
		(end 426.251624 -213.069424)
		(width 0.14478)
		(layer "In6.Cu")
		(net "M_K_CPU0_SA_DQ<12>")
	)
	(segment
		(start 404.734776 -222.22079)
		(end 404.734776 -220.713554)
		(width 0.14478)
		(layer "In6.Cu")
		(net "M_K_CPU0_SA_DQ<12>")
	)
	(segment
		(start 417.857432 -212.219286)
		(end 418.70757 -213.069424)
		(width 0.14478)
		(layer "In6.Cu")
		(net "M_K_CPU0_SA_DQ<12>")
	)
	(segment
		(start 394.32738 -231.629966)
		(end 394.52296 -231.434386)
		(width 0.0889)
		(layer "In6.Cu")
		(net "M_K_CPU0_SA_DQ<12>")
	)
	(segment
		(start 445.509396 -212.210142)
		(end 446.219326 -212.210142)
		(width 0.14478)
		(layer "In6.Cu")
		(net "M_K_CPU0_SA_DQ<12>")
	)
	(segment
		(start 436.731918 -213.069424)
		(end 437.581802 -212.21954)
		(width 0.14478)
		(layer "In6.Cu")
		(net "M_K_CPU0_SA_DQ<12>")
	)
	(segment
		(start 390.734804 -233.14406)
		(end 390.58088 -233.40949)
		(width 0.0889)
		(layer "In6.Cu")
		(net "M_K_CPU0_SA_DQ<12>")
	)
	(segment
		(start 444.789814 -212.37321)
		(end 444.789814 -212.779102)
		(width 0.14478)
		(layer "In6.Cu")
		(net "M_K_CPU0_SA_DQ<12>")
	)
	(segment
		(start 390.58088 -233.40949)
		(end 390.603232 -233.492802)
		(width 0.0889)
		(layer "In6.Cu")
		(net "M_K_CPU0_SA_DQ<12>")
	)
	(segment
		(start 392.42746 -233.46664)
		(end 392.435842 -233.471466)
		(width 0.0889)
		(layer "In6.Cu")
		(net "M_K_CPU0_SA_DQ<12>")
	)
	(segment
		(start 422.389808 -212.21954)
		(end 425.40174 -212.21954)
		(width 0.14478)
		(layer "In6.Cu")
		(net "M_K_CPU0_SA_DQ<12>")
	)
	(segment
		(start 395.539976 -230.88219)
		(end 396.073376 -230.88219)
		(width 0.0889)
		(layer "In6.Cu")
		(net "M_K_CPU0_SA_DQ<12>")
	)
	(segment
		(start 429.071532 -213.069424)
		(end 429.921416 -212.21954)
		(width 0.14478)
		(layer "In6.Cu")
		(net "M_K_CPU0_SA_DQ<12>")
	)
	(segment
		(start 404.734776 -220.713554)
		(end 412.388304 -213.060026)
		(width 0.14478)
		(layer "In6.Cu")
		(net "M_K_CPU0_SA_DQ<12>")
	)
	(segment
		(start 437.581802 -212.21954)
		(end 444.636144 -212.21954)
		(width 0.14478)
		(layer "In6.Cu")
		(net "M_K_CPU0_SA_DQ<12>")
	)
	(segment
		(start 396.073376 -230.88219)
		(end 396.230856 -230.72471)
		(width 0.0889)
		(layer "In6.Cu")
		(net "M_K_CPU0_SA_DQ<12>")
	)
	(segment
		(start 445.346328 -212.37321)
		(end 445.509396 -212.210142)
		(width 0.14478)
		(layer "In6.Cu")
		(net "M_K_CPU0_SA_DQ<12>")
	)
	(segment
		(start 432.94554 -212.21954)
		(end 433.795424 -213.069424)
		(width 0.14478)
		(layer "In6.Cu")
		(net "M_K_CPU0_SA_DQ<12>")
	)
	(segment
		(start 414.887156 -212.219286)
		(end 417.857432 -212.219286)
		(width 0.14478)
		(layer "In6.Cu")
		(net "M_K_CPU0_SA_DQ<12>")
	)
	(segment
		(start 429.921416 -212.21954)
		(end 432.94554 -212.21954)
		(width 0.14478)
		(layer "In6.Cu")
		(net "M_K_CPU0_SA_DQ<12>")
	)
	(segment
		(start 445.18326 -212.94217)
		(end 445.346328 -212.779102)
		(width 0.14478)
		(layer "In6.Cu")
		(net "M_K_CPU0_SA_DQ<12>")
	)
	(segment
		(start 418.70757 -213.069424)
		(end 421.539924 -213.069424)
		(width 0.14478)
		(layer "In6.Cu")
		(net "M_K_CPU0_SA_DQ<12>")
	)
	(segment
		(start 394.32738 -232.294176)
		(end 394.32738 -231.629966)
		(width 0.0889)
		(layer "In6.Cu")
		(net "M_K_CPU0_SA_DQ<12>")
	)
	(segment
		(start 445.346328 -212.779102)
		(end 445.346328 -212.37321)
		(width 0.14478)
		(layer "In6.Cu")
		(net "M_K_CPU0_SA_DQ<12>")
	)
	(segment
		(start 394.52296 -231.434386)
		(end 394.98778 -231.434386)
		(width 0.0889)
		(layer "In6.Cu")
		(net "M_K_CPU0_SA_DQ<12>")
	)
	(segment
		(start 444.636144 -212.21954)
		(end 444.789814 -212.37321)
		(width 0.14478)
		(layer "In6.Cu")
		(net "M_K_CPU0_SA_DQ<12>")
	)
	(segment
		(start 444.952882 -212.94217)
		(end 445.18326 -212.94217)
		(width 0.14478)
		(layer "In6.Cu")
		(net "M_K_CPU0_SA_DQ<12>")
	)
	(segment
		(start 391.861802 -233.46664)
		(end 391.872216 -233.460544)
		(width 0.0889)
		(layer "In6.Cu")
		(net "M_K_CPU0_SA_DQ<12>")
	)
	(segment
		(start 446.219326 -212.210142)
		(end 446.644268 -212.635084)
		(width 0.14478)
		(layer "In6.Cu")
		(net "M_K_CPU0_SA_DQ<12>")
	)
	(arc
		(start 391.48766 -233.46664)
		(mid 391.669911 -233.51699)
		(end 391.85342 -233.471466)
		(width 0.0889)
		(layer "In6.Cu")
		(net "M_K_CPU0_SA_DQ<12>")
	)
	(arc
		(start 391.872216 -233.460544)
		(mid 392.150648 -233.390446)
		(end 392.42746 -233.46664)
		(width 0.0889)
		(layer "In6.Cu")
		(net "M_K_CPU0_SA_DQ<12>")
	)
	(arc
		(start 392.435842 -233.471466)
		(mid 392.61935 -233.51696)
		(end 392.801602 -233.46664)
		(width 0.0889)
		(layer "In6.Cu")
		(net "M_K_CPU0_SA_DQ<12>")
	)
	(arc
		(start 392.801602 -233.46664)
		(mid 392.938165 -233.409807)
		(end 393.084812 -233.39044)
		(width 0.0889)
		(layer "In6.Cu")
		(net "M_K_CPU0_SA_DQ<12>")
	)
	(arc
		(start 390.921748 -233.46664)
		(mid 391.204704 -233.390463)
		(end 391.48766 -233.46664)
		(width 0.0889)
		(layer "In6.Cu")
		(net "M_K_CPU0_SA_DQ<12>")
	)
	(arc
		(start 390.603232 -233.492802)
		(mid 390.765421 -233.515537)
		(end 390.921748 -233.46664)
		(width 0.0889)
		(layer "In6.Cu")
		(net "M_K_CPU0_SA_DQ<12>")
	)
	(segment
		(start 388.387844 -231.789986)
		(end 388.85495 -231.524048)
		(width 0.10668)
		(layer "F.Cu")
		(net "M_K_CPU0_SA_DQ<11>")
	)
	(segment
		(start 428.066962 -209.432398)
		(end 428.23003 -209.26933)
		(width 0.14478)
		(layer "In6.Cu")
		(net "M_K_CPU0_SA_DQ<11>")
	)
	(segment
		(start 430.641506 -208.41589)
		(end 430.871884 -208.41589)
		(width 0.14478)
		(layer "In6.Cu")
		(net "M_K_CPU0_SA_DQ<11>")
	)
	(segment
		(start 435.58841 -209.497168)
		(end 435.58841 -209.434938)
		(width 0.14478)
		(layer "In6.Cu")
		(net "M_K_CPU0_SA_DQ<11>")
	)
	(segment
		(start 436.144924 -209.497168)
		(end 436.307992 -209.660236)
		(width 0.14478)
		(layer "In6.Cu")
		(net "M_K_CPU0_SA_DQ<11>")
	)
	(segment
		(start 442.119258 -208.810098)
		(end 442.5442 -209.23504)
		(width 0.14478)
		(layer "In6.Cu")
		(net "M_K_CPU0_SA_DQ<11>")
	)
	(segment
		(start 436.307992 -209.660236)
		(end 436.6133 -209.660236)
		(width 0.14478)
		(layer "In6.Cu")
		(net "M_K_CPU0_SA_DQ<11>")
	)
	(segment
		(start 430.478438 -208.64703)
		(end 430.478438 -208.578958)
		(width 0.14478)
		(layer "In6.Cu")
		(net "M_K_CPU0_SA_DQ<11>")
	)
	(segment
		(start 411.769814 -209.660236)
		(end 414.006792 -209.660236)
		(width 0.14478)
		(layer "In6.Cu")
		(net "M_K_CPU0_SA_DQ<11>")
	)
	(segment
		(start 438.115202 -208.421732)
		(end 438.377076 -208.421732)
		(width 0.14478)
		(layer "In6.Cu")
		(net "M_K_CPU0_SA_DQ<11>")
	)
	(segment
		(start 438.521856 -208.566512)
		(end 438.521856 -208.65592)
		(width 0.14478)
		(layer "In6.Cu")
		(net "M_K_CPU0_SA_DQ<11>")
	)
	(segment
		(start 428.623476 -209.497168)
		(end 428.786544 -209.660236)
		(width 0.14478)
		(layer "In6.Cu")
		(net "M_K_CPU0_SA_DQ<11>")
	)
	(segment
		(start 389.008874 -231.258618)
		(end 389.104632 -231.233218)
		(width 0.0889)
		(layer "In6.Cu")
		(net "M_K_CPU0_SA_DQ<11>")
	)
	(segment
		(start 433.776628 -209.650838)
		(end 435.43474 -209.650838)
		(width 0.14478)
		(layer "In6.Cu")
		(net "M_K_CPU0_SA_DQ<11>")
	)
	(segment
		(start 429.08093 -209.660236)
		(end 429.931068 -208.810098)
		(width 0.14478)
		(layer "In6.Cu")
		(net "M_K_CPU0_SA_DQ<11>")
	)
	(segment
		(start 437.970422 -208.566512)
		(end 438.115202 -208.421732)
		(width 0.14478)
		(layer "In6.Cu")
		(net "M_K_CPU0_SA_DQ<11>")
	)
	(segment
		(start 441.282328 -209.300572)
		(end 441.512706 -209.300572)
		(width 0.14478)
		(layer "In6.Cu")
		(net "M_K_CPU0_SA_DQ<11>")
	)
	(segment
		(start 431.034952 -208.578958)
		(end 431.034952 -208.64703)
		(width 0.14478)
		(layer "In6.Cu")
		(net "M_K_CPU0_SA_DQ<11>")
	)
	(segment
		(start 437.472836 -208.8007)
		(end 437.825642 -208.8007)
		(width 0.14478)
		(layer "In6.Cu")
		(net "M_K_CPU0_SA_DQ<11>")
	)
	(segment
		(start 441.11926 -209.137504)
		(end 441.282328 -209.300572)
		(width 0.14478)
		(layer "In6.Cu")
		(net "M_K_CPU0_SA_DQ<11>")
	)
	(segment
		(start 418.688774 -209.650838)
		(end 421.55872 -209.650838)
		(width 0.14478)
		(layer "In6.Cu")
		(net "M_K_CPU0_SA_DQ<11>")
	)
	(segment
		(start 435.981856 -209.27187)
		(end 436.144924 -209.434938)
		(width 0.14478)
		(layer "In6.Cu")
		(net "M_K_CPU0_SA_DQ<11>")
	)
	(segment
		(start 389.607806 -231.201722)
		(end 389.616188 -231.196896)
		(width 0.0889)
		(layer "In6.Cu")
		(net "M_K_CPU0_SA_DQ<11>")
	)
	(segment
		(start 414.006792 -209.660236)
		(end 414.866328 -208.8007)
		(width 0.14478)
		(layer "In6.Cu")
		(net "M_K_CPU0_SA_DQ<11>")
	)
	(segment
		(start 402.136356 -219.293694)
		(end 411.769814 -209.660236)
		(width 0.14478)
		(layer "In6.Cu")
		(net "M_K_CPU0_SA_DQ<11>")
	)
	(segment
		(start 441.675774 -209.137504)
		(end 441.675774 -208.973166)
		(width 0.14478)
		(layer "In6.Cu")
		(net "M_K_CPU0_SA_DQ<11>")
	)
	(segment
		(start 430.478438 -208.578958)
		(end 430.641506 -208.41589)
		(width 0.14478)
		(layer "In6.Cu")
		(net "M_K_CPU0_SA_DQ<11>")
	)
	(segment
		(start 414.866328 -208.8007)
		(end 417.838636 -208.8007)
		(width 0.14478)
		(layer "In6.Cu")
		(net "M_K_CPU0_SA_DQ<11>")
	)
	(segment
		(start 421.55872 -209.650838)
		(end 422.408858 -208.8007)
		(width 0.14478)
		(layer "In6.Cu")
		(net "M_K_CPU0_SA_DQ<11>")
	)
	(segment
		(start 435.58841 -209.434938)
		(end 435.751478 -209.27187)
		(width 0.14478)
		(layer "In6.Cu")
		(net "M_K_CPU0_SA_DQ<11>")
	)
	(segment
		(start 422.408858 -208.8007)
		(end 425.38269 -208.8007)
		(width 0.14478)
		(layer "In6.Cu")
		(net "M_K_CPU0_SA_DQ<11>")
	)
	(segment
		(start 428.786544 -209.660236)
		(end 429.08093 -209.660236)
		(width 0.14478)
		(layer "In6.Cu")
		(net "M_K_CPU0_SA_DQ<11>")
	)
	(segment
		(start 426.232828 -209.650838)
		(end 427.913292 -209.650838)
		(width 0.14478)
		(layer "In6.Cu")
		(net "M_K_CPU0_SA_DQ<11>")
	)
	(segment
		(start 394.323316 -229.38867)
		(end 394.694156 -229.38867)
		(width 0.0889)
		(layer "In6.Cu")
		(net "M_K_CPU0_SA_DQ<11>")
	)
	(segment
		(start 431.034952 -208.64703)
		(end 431.188622 -208.8007)
		(width 0.14478)
		(layer "In6.Cu")
		(net "M_K_CPU0_SA_DQ<11>")
	)
	(segment
		(start 425.38269 -208.8007)
		(end 426.232828 -209.650838)
		(width 0.14478)
		(layer "In6.Cu")
		(net "M_K_CPU0_SA_DQ<11>")
	)
	(segment
		(start 439.713624 -208.8007)
		(end 439.867294 -208.64703)
		(width 0.14478)
		(layer "In6.Cu")
		(net "M_K_CPU0_SA_DQ<11>")
	)
	(segment
		(start 436.6133 -209.660236)
		(end 437.472836 -208.8007)
		(width 0.14478)
		(layer "In6.Cu")
		(net "M_K_CPU0_SA_DQ<11>")
	)
	(segment
		(start 395.320266 -228.31298)
		(end 395.812772 -227.820474)
		(width 0.0889)
		(layer "In6.Cu")
		(net "M_K_CPU0_SA_DQ<11>")
	)
	(segment
		(start 437.970422 -208.65592)
		(end 437.970422 -208.566512)
		(width 0.14478)
		(layer "In6.Cu")
		(net "M_K_CPU0_SA_DQ<11>")
	)
	(segment
		(start 393.617196 -230.09479)
		(end 394.323316 -229.38867)
		(width 0.0889)
		(layer "In6.Cu")
		(net "M_K_CPU0_SA_DQ<11>")
	)
	(segment
		(start 428.623476 -209.432398)
		(end 428.623476 -209.497168)
		(width 0.14478)
		(layer "In6.Cu")
		(net "M_K_CPU0_SA_DQ<11>")
	)
	(segment
		(start 441.512706 -209.300572)
		(end 441.675774 -209.137504)
		(width 0.14478)
		(layer "In6.Cu")
		(net "M_K_CPU0_SA_DQ<11>")
	)
	(segment
		(start 440.423808 -208.584038)
		(end 440.423808 -208.64703)
		(width 0.14478)
		(layer "In6.Cu")
		(net "M_K_CPU0_SA_DQ<11>")
	)
	(segment
		(start 393.617196 -230.75265)
		(end 393.617196 -230.09479)
		(width 0.0889)
		(layer "In6.Cu")
		(net "M_K_CPU0_SA_DQ<11>")
	)
	(segment
		(start 388.85495 -231.524048)
		(end 389.008874 -231.258618)
		(width 0.0889)
		(layer "In6.Cu")
		(net "M_K_CPU0_SA_DQ<11>")
	)
	(segment
		(start 430.871884 -208.41589)
		(end 431.034952 -208.578958)
		(width 0.14478)
		(layer "In6.Cu")
		(net "M_K_CPU0_SA_DQ<11>")
	)
	(segment
		(start 435.43474 -209.650838)
		(end 435.58841 -209.497168)
		(width 0.14478)
		(layer "In6.Cu")
		(net "M_K_CPU0_SA_DQ<11>")
	)
	(segment
		(start 440.586876 -208.810098)
		(end 440.956192 -208.810098)
		(width 0.14478)
		(layer "In6.Cu")
		(net "M_K_CPU0_SA_DQ<11>")
	)
	(segment
		(start 441.838842 -208.810098)
		(end 442.119258 -208.810098)
		(width 0.14478)
		(layer "In6.Cu")
		(net "M_K_CPU0_SA_DQ<11>")
	)
	(segment
		(start 417.838636 -208.8007)
		(end 418.688774 -209.650838)
		(width 0.14478)
		(layer "In6.Cu")
		(net "M_K_CPU0_SA_DQ<11>")
	)
	(segment
		(start 440.26074 -208.42097)
		(end 440.423808 -208.584038)
		(width 0.14478)
		(layer "In6.Cu")
		(net "M_K_CPU0_SA_DQ<11>")
	)
	(segment
		(start 441.11926 -208.973166)
		(end 441.11926 -209.137504)
		(width 0.14478)
		(layer "In6.Cu")
		(net "M_K_CPU0_SA_DQ<11>")
	)
	(segment
		(start 393.168124 -231.201722)
		(end 393.617196 -230.75265)
		(width 0.0889)
		(layer "In6.Cu")
		(net "M_K_CPU0_SA_DQ<11>")
	)
	(segment
		(start 395.812772 -227.820474)
		(end 402.136356 -221.49689)
		(width 0.14478)
		(layer "In6.Cu")
		(net "M_K_CPU0_SA_DQ<11>")
	)
	(segment
		(start 437.825642 -208.8007)
		(end 437.970422 -208.65592)
		(width 0.14478)
		(layer "In6.Cu")
		(net "M_K_CPU0_SA_DQ<11>")
	)
	(segment
		(start 391.861548 -231.201722)
		(end 391.871962 -231.207818)
		(width 0.0889)
		(layer "In6.Cu")
		(net "M_K_CPU0_SA_DQ<11>")
	)
	(segment
		(start 440.030362 -208.42097)
		(end 440.26074 -208.42097)
		(width 0.14478)
		(layer "In6.Cu")
		(net "M_K_CPU0_SA_DQ<11>")
	)
	(segment
		(start 428.066962 -209.497168)
		(end 428.066962 -209.432398)
		(width 0.14478)
		(layer "In6.Cu")
		(net "M_K_CPU0_SA_DQ<11>")
	)
	(segment
		(start 431.188622 -208.8007)
		(end 432.92649 -208.8007)
		(width 0.14478)
		(layer "In6.Cu")
		(net "M_K_CPU0_SA_DQ<11>")
	)
	(segment
		(start 402.136356 -221.49689)
		(end 402.136356 -219.293694)
		(width 0.14478)
		(layer "In6.Cu")
		(net "M_K_CPU0_SA_DQ<11>")
	)
	(segment
		(start 427.913292 -209.650838)
		(end 428.066962 -209.497168)
		(width 0.14478)
		(layer "In6.Cu")
		(net "M_K_CPU0_SA_DQ<11>")
	)
	(segment
		(start 438.521856 -208.65592)
		(end 438.666636 -208.8007)
		(width 0.14478)
		(layer "In6.Cu")
		(net "M_K_CPU0_SA_DQ<11>")
	)
	(segment
		(start 439.867294 -208.64703)
		(end 439.867294 -208.584038)
		(width 0.14478)
		(layer "In6.Cu")
		(net "M_K_CPU0_SA_DQ<11>")
	)
	(segment
		(start 430.31537 -208.810098)
		(end 430.478438 -208.64703)
		(width 0.14478)
		(layer "In6.Cu")
		(net "M_K_CPU0_SA_DQ<11>")
	)
	(segment
		(start 392.427206 -231.201722)
		(end 393.168124 -231.201722)
		(width 0.0889)
		(layer "In6.Cu")
		(net "M_K_CPU0_SA_DQ<11>")
	)
	(segment
		(start 395.002258 -229.080568)
		(end 395.320266 -228.31298)
		(width 0.0889)
		(layer "In6.Cu")
		(net "M_K_CPU0_SA_DQ<11>")
	)
	(segment
		(start 435.751478 -209.27187)
		(end 435.981856 -209.27187)
		(width 0.14478)
		(layer "In6.Cu")
		(net "M_K_CPU0_SA_DQ<11>")
	)
	(segment
		(start 436.144924 -209.434938)
		(end 436.144924 -209.497168)
		(width 0.14478)
		(layer "In6.Cu")
		(net "M_K_CPU0_SA_DQ<11>")
	)
	(segment
		(start 432.92649 -208.8007)
		(end 433.776628 -209.650838)
		(width 0.14478)
		(layer "In6.Cu")
		(net "M_K_CPU0_SA_DQ<11>")
	)
	(segment
		(start 439.867294 -208.584038)
		(end 440.030362 -208.42097)
		(width 0.14478)
		(layer "In6.Cu")
		(net "M_K_CPU0_SA_DQ<11>")
	)
	(segment
		(start 428.460408 -209.26933)
		(end 428.623476 -209.432398)
		(width 0.14478)
		(layer "In6.Cu")
		(net "M_K_CPU0_SA_DQ<11>")
	)
	(segment
		(start 440.423808 -208.64703)
		(end 440.586876 -208.810098)
		(width 0.14478)
		(layer "In6.Cu")
		(net "M_K_CPU0_SA_DQ<11>")
	)
	(segment
		(start 391.849864 -231.194864)
		(end 391.861548 -231.201722)
		(width 0.0889)
		(layer "In6.Cu")
		(net "M_K_CPU0_SA_DQ<11>")
	)
	(segment
		(start 394.694156 -229.38867)
		(end 395.002258 -229.080568)
		(width 0.0889)
		(layer "In6.Cu")
		(net "M_K_CPU0_SA_DQ<11>")
	)
	(segment
		(start 440.956192 -208.810098)
		(end 441.11926 -208.973166)
		(width 0.14478)
		(layer "In6.Cu")
		(net "M_K_CPU0_SA_DQ<11>")
	)
	(segment
		(start 428.23003 -209.26933)
		(end 428.460408 -209.26933)
		(width 0.14478)
		(layer "In6.Cu")
		(net "M_K_CPU0_SA_DQ<11>")
	)
	(segment
		(start 438.666636 -208.8007)
		(end 439.713624 -208.8007)
		(width 0.14478)
		(layer "In6.Cu")
		(net "M_K_CPU0_SA_DQ<11>")
	)
	(segment
		(start 429.931068 -208.810098)
		(end 430.31537 -208.810098)
		(width 0.14478)
		(layer "In6.Cu")
		(net "M_K_CPU0_SA_DQ<11>")
	)
	(segment
		(start 441.675774 -208.973166)
		(end 441.838842 -208.810098)
		(width 0.14478)
		(layer "In6.Cu")
		(net "M_K_CPU0_SA_DQ<11>")
	)
	(segment
		(start 438.377076 -208.421732)
		(end 438.521856 -208.566512)
		(width 0.14478)
		(layer "In6.Cu")
		(net "M_K_CPU0_SA_DQ<11>")
	)
	(arc
		(start 390.54786 -231.201722)
		(mid 390.734804 -231.151433)
		(end 390.921748 -231.201722)
		(width 0.0889)
		(layer "In6.Cu")
		(net "M_K_CPU0_SA_DQ<11>")
	)
	(arc
		(start 389.616188 -231.196896)
		(mid 389.799696 -231.151371)
		(end 389.981948 -231.201722)
		(width 0.0889)
		(layer "In6.Cu")
		(net "M_K_CPU0_SA_DQ<11>")
	)
	(arc
		(start 389.104632 -231.233218)
		(mid 389.359954 -231.276918)
		(end 389.607806 -231.201722)
		(width 0.0889)
		(layer "In6.Cu")
		(net "M_K_CPU0_SA_DQ<11>")
	)
	(arc
		(start 390.921748 -231.201722)
		(mid 391.204704 -231.277899)
		(end 391.48766 -231.201722)
		(width 0.0889)
		(layer "In6.Cu")
		(net "M_K_CPU0_SA_DQ<11>")
	)
	(arc
		(start 389.981948 -231.201722)
		(mid 390.264904 -231.277899)
		(end 390.54786 -231.201722)
		(width 0.0889)
		(layer "In6.Cu")
		(net "M_K_CPU0_SA_DQ<11>")
	)
	(arc
		(start 391.871962 -231.207818)
		(mid 392.150394 -231.277916)
		(end 392.427206 -231.201722)
		(width 0.0889)
		(layer "In6.Cu")
		(net "M_K_CPU0_SA_DQ<11>")
	)
	(arc
		(start 391.48766 -231.201722)
		(mid 391.667865 -231.151371)
		(end 391.849864 -231.194864)
		(width 0.0889)
		(layer "In6.Cu")
		(net "M_K_CPU0_SA_DQ<11>")
	)
	(segment
		(start 389.798052 -230.97998)
		(end 390.264904 -230.714296)
		(width 0.10668)
		(layer "F.Cu")
		(net "M_K_CPU0_SA_DQ<10>")
	)
	(segment
		(start 429.08093 -207.960214)
		(end 429.931068 -207.110076)
		(width 0.14478)
		(layer "In6.Cu")
		(net "M_K_CPU0_SA_DQ<10>")
	)
	(segment
		(start 421.05834 -207.728058)
		(end 421.05834 -207.797146)
		(width 0.14478)
		(layer "In6.Cu")
		(net "M_K_CPU0_SA_DQ<10>")
	)
	(segment
		(start 421.221408 -207.960214)
		(end 421.549322 -207.960214)
		(width 0.14478)
		(layer "In6.Cu")
		(net "M_K_CPU0_SA_DQ<10>")
	)
	(segment
		(start 421.549322 -207.960214)
		(end 422.39946 -207.110076)
		(width 0.14478)
		(layer "In6.Cu")
		(net "M_K_CPU0_SA_DQ<10>")
	)
	(segment
		(start 417.848034 -207.110076)
		(end 418.698172 -207.960214)
		(width 0.14478)
		(layer "In6.Cu")
		(net "M_K_CPU0_SA_DQ<10>")
	)
	(segment
		(start 401.227036 -221.119954)
		(end 401.227036 -218.844114)
		(width 0.14478)
		(layer "In6.Cu")
		(net "M_K_CPU0_SA_DQ<10>")
	)
	(segment
		(start 391.01776 -230.391716)
		(end 391.026142 -230.38689)
		(width 0.0889)
		(layer "In6.Cu")
		(net "M_K_CPU0_SA_DQ<10>")
	)
	(segment
		(start 437.463438 -207.110076)
		(end 439.803286 -207.110076)
		(width 0.14478)
		(layer "In6.Cu")
		(net "M_K_CPU0_SA_DQ<10>")
	)
	(segment
		(start 423.657522 -207.110076)
		(end 425.392088 -207.110076)
		(width 0.14478)
		(layer "In6.Cu")
		(net "M_K_CPU0_SA_DQ<10>")
	)
	(segment
		(start 428.550578 -207.797146)
		(end 428.713646 -207.960214)
		(width 0.14478)
		(layer "In6.Cu")
		(net "M_K_CPU0_SA_DQ<10>")
	)
	(segment
		(start 441.079382 -207.335882)
		(end 441.24245 -207.49895)
		(width 0.14478)
		(layer "In6.Cu")
		(net "M_K_CPU0_SA_DQ<10>")
	)
	(segment
		(start 430.914302 -206.72171)
		(end 431.07737 -206.884778)
		(width 0.14478)
		(layer "In6.Cu")
		(net "M_K_CPU0_SA_DQ<10>")
	)
	(segment
		(start 441.472828 -207.49895)
		(end 441.635896 -207.335882)
		(width 0.14478)
		(layer "In6.Cu")
		(net "M_K_CPU0_SA_DQ<10>")
	)
	(segment
		(start 393.22121 -229.808024)
		(end 394.146024 -228.88321)
		(width 0.0889)
		(layer "In6.Cu")
		(net "M_K_CPU0_SA_DQ<10>")
	)
	(segment
		(start 440.522868 -207.335882)
		(end 440.522868 -206.879698)
		(width 0.14478)
		(layer "In6.Cu")
		(net "M_K_CPU0_SA_DQ<10>")
	)
	(segment
		(start 401.227036 -218.844114)
		(end 412.110936 -207.960214)
		(width 0.14478)
		(layer "In6.Cu")
		(net "M_K_CPU0_SA_DQ<10>")
	)
	(segment
		(start 427.994064 -207.728058)
		(end 428.157132 -207.56499)
		(width 0.14478)
		(layer "In6.Cu")
		(net "M_K_CPU0_SA_DQ<10>")
	)
	(segment
		(start 435.565296 -207.733138)
		(end 435.728364 -207.57007)
		(width 0.14478)
		(layer "In6.Cu")
		(net "M_K_CPU0_SA_DQ<10>")
	)
	(segment
		(start 439.966354 -207.273144)
		(end 439.966354 -207.335882)
		(width 0.14478)
		(layer "In6.Cu")
		(net "M_K_CPU0_SA_DQ<10>")
	)
	(segment
		(start 440.129422 -207.49895)
		(end 440.3598 -207.49895)
		(width 0.14478)
		(layer "In6.Cu")
		(net "M_K_CPU0_SA_DQ<10>")
	)
	(segment
		(start 431.07737 -206.884778)
		(end 431.07737 -206.947008)
		(width 0.14478)
		(layer "In6.Cu")
		(net "M_K_CPU0_SA_DQ<10>")
	)
	(segment
		(start 423.331386 -206.72171)
		(end 423.494454 -206.884778)
		(width 0.14478)
		(layer "In6.Cu")
		(net "M_K_CPU0_SA_DQ<10>")
	)
	(segment
		(start 430.520856 -206.947008)
		(end 430.520856 -206.884778)
		(width 0.14478)
		(layer "In6.Cu")
		(net "M_K_CPU0_SA_DQ<10>")
	)
	(segment
		(start 436.12181 -207.797146)
		(end 436.284878 -207.960214)
		(width 0.14478)
		(layer "In6.Cu")
		(net "M_K_CPU0_SA_DQ<10>")
	)
	(segment
		(start 391.947146 -230.397812)
		(end 391.95756 -230.391716)
		(width 0.0889)
		(layer "In6.Cu")
		(net "M_K_CPU0_SA_DQ<10>")
	)
	(segment
		(start 436.6133 -207.960214)
		(end 437.463438 -207.110076)
		(width 0.14478)
		(layer "In6.Cu")
		(net "M_K_CPU0_SA_DQ<10>")
	)
	(segment
		(start 441.635896 -207.273144)
		(end 441.798964 -207.110076)
		(width 0.14478)
		(layer "In6.Cu")
		(net "M_K_CPU0_SA_DQ<10>")
	)
	(segment
		(start 435.958742 -207.57007)
		(end 436.12181 -207.733138)
		(width 0.14478)
		(layer "In6.Cu")
		(net "M_K_CPU0_SA_DQ<10>")
	)
	(segment
		(start 427.830996 -207.960214)
		(end 427.994064 -207.797146)
		(width 0.14478)
		(layer "In6.Cu")
		(net "M_K_CPU0_SA_DQ<10>")
	)
	(segment
		(start 425.392088 -207.110076)
		(end 426.242226 -207.960214)
		(width 0.14478)
		(layer "In6.Cu")
		(net "M_K_CPU0_SA_DQ<10>")
	)
	(segment
		(start 422.774872 -207.110076)
		(end 422.93794 -206.947008)
		(width 0.14478)
		(layer "In6.Cu")
		(net "M_K_CPU0_SA_DQ<10>")
	)
	(segment
		(start 440.3598 -207.49895)
		(end 440.522868 -207.335882)
		(width 0.14478)
		(layer "In6.Cu")
		(net "M_K_CPU0_SA_DQ<10>")
	)
	(segment
		(start 422.39946 -207.110076)
		(end 422.774872 -207.110076)
		(width 0.14478)
		(layer "In6.Cu")
		(net "M_K_CPU0_SA_DQ<10>")
	)
	(segment
		(start 394.853414 -227.84816)
		(end 395.379194 -227.32238)
		(width 0.0889)
		(layer "In6.Cu")
		(net "M_K_CPU0_SA_DQ<10>")
	)
	(segment
		(start 412.110936 -207.960214)
		(end 414.006792 -207.960214)
		(width 0.14478)
		(layer "In6.Cu")
		(net "M_K_CPU0_SA_DQ<10>")
	)
	(segment
		(start 431.07737 -206.947008)
		(end 431.240438 -207.110076)
		(width 0.14478)
		(layer "In6.Cu")
		(net "M_K_CPU0_SA_DQ<10>")
	)
	(segment
		(start 423.494454 -206.884778)
		(end 423.494454 -206.947008)
		(width 0.14478)
		(layer "In6.Cu")
		(net "M_K_CPU0_SA_DQ<10>")
	)
	(segment
		(start 427.994064 -207.797146)
		(end 427.994064 -207.728058)
		(width 0.14478)
		(layer "In6.Cu")
		(net "M_K_CPU0_SA_DQ<10>")
	)
	(segment
		(start 430.683924 -206.72171)
		(end 430.914302 -206.72171)
		(width 0.14478)
		(layer "In6.Cu")
		(net "M_K_CPU0_SA_DQ<10>")
	)
	(segment
		(start 430.520856 -206.884778)
		(end 430.683924 -206.72171)
		(width 0.14478)
		(layer "In6.Cu")
		(net "M_K_CPU0_SA_DQ<10>")
	)
	(segment
		(start 418.698172 -207.960214)
		(end 420.338758 -207.960214)
		(width 0.14478)
		(layer "In6.Cu")
		(net "M_K_CPU0_SA_DQ<10>")
	)
	(segment
		(start 395.379194 -226.967796)
		(end 395.914118 -226.432872)
		(width 0.0889)
		(layer "In6.Cu")
		(net "M_K_CPU0_SA_DQ<10>")
	)
	(segment
		(start 392.073384 -230.302562)
		(end 392.567922 -229.808024)
		(width 0.0889)
		(layer "In6.Cu")
		(net "M_K_CPU0_SA_DQ<10>")
	)
	(segment
		(start 426.242226 -207.960214)
		(end 427.830996 -207.960214)
		(width 0.14478)
		(layer "In6.Cu")
		(net "M_K_CPU0_SA_DQ<10>")
	)
	(segment
		(start 440.685936 -206.71663)
		(end 440.916314 -206.71663)
		(width 0.14478)
		(layer "In6.Cu")
		(net "M_K_CPU0_SA_DQ<10>")
	)
	(segment
		(start 439.966354 -207.335882)
		(end 440.129422 -207.49895)
		(width 0.14478)
		(layer "In6.Cu")
		(net "M_K_CPU0_SA_DQ<10>")
	)
	(segment
		(start 394.853414 -228.35997)
		(end 394.853414 -227.84816)
		(width 0.0889)
		(layer "In6.Cu")
		(net "M_K_CPU0_SA_DQ<10>")
	)
	(segment
		(start 422.93794 -206.947008)
		(end 422.93794 -206.884778)
		(width 0.14478)
		(layer "In6.Cu")
		(net "M_K_CPU0_SA_DQ<10>")
	)
	(segment
		(start 420.895272 -207.56499)
		(end 421.05834 -207.728058)
		(width 0.14478)
		(layer "In6.Cu")
		(net "M_K_CPU0_SA_DQ<10>")
	)
	(segment
		(start 421.05834 -207.797146)
		(end 421.221408 -207.960214)
		(width 0.14478)
		(layer "In6.Cu")
		(net "M_K_CPU0_SA_DQ<10>")
	)
	(segment
		(start 436.12181 -207.733138)
		(end 436.12181 -207.797146)
		(width 0.14478)
		(layer "In6.Cu")
		(net "M_K_CPU0_SA_DQ<10>")
	)
	(segment
		(start 395.914118 -226.432872)
		(end 401.227036 -221.119954)
		(width 0.14478)
		(layer "In6.Cu")
		(net "M_K_CPU0_SA_DQ<10>")
	)
	(segment
		(start 390.418828 -230.448866)
		(end 390.51484 -230.423466)
		(width 0.0889)
		(layer "In6.Cu")
		(net "M_K_CPU0_SA_DQ<10>")
	)
	(segment
		(start 439.803286 -207.110076)
		(end 439.966354 -207.273144)
		(width 0.14478)
		(layer "In6.Cu")
		(net "M_K_CPU0_SA_DQ<10>")
	)
	(segment
		(start 414.85693 -207.110076)
		(end 417.848034 -207.110076)
		(width 0.14478)
		(layer "In6.Cu")
		(net "M_K_CPU0_SA_DQ<10>")
	)
	(segment
		(start 431.240438 -207.110076)
		(end 432.935888 -207.110076)
		(width 0.14478)
		(layer "In6.Cu")
		(net "M_K_CPU0_SA_DQ<10>")
	)
	(segment
		(start 435.402228 -207.960214)
		(end 435.565296 -207.797146)
		(width 0.14478)
		(layer "In6.Cu")
		(net "M_K_CPU0_SA_DQ<10>")
	)
	(segment
		(start 394.73124 -228.654864)
		(end 394.853414 -228.35997)
		(width 0.0889)
		(layer "In6.Cu")
		(net "M_K_CPU0_SA_DQ<10>")
	)
	(segment
		(start 428.550578 -207.728058)
		(end 428.550578 -207.797146)
		(width 0.14478)
		(layer "In6.Cu")
		(net "M_K_CPU0_SA_DQ<10>")
	)
	(segment
		(start 435.728364 -207.57007)
		(end 435.958742 -207.57007)
		(width 0.14478)
		(layer "In6.Cu")
		(net "M_K_CPU0_SA_DQ<10>")
	)
	(segment
		(start 430.357788 -207.110076)
		(end 430.520856 -206.947008)
		(width 0.14478)
		(layer "In6.Cu")
		(net "M_K_CPU0_SA_DQ<10>")
	)
	(segment
		(start 392.567922 -229.808024)
		(end 393.22121 -229.808024)
		(width 0.0889)
		(layer "In6.Cu")
		(net "M_K_CPU0_SA_DQ<10>")
	)
	(segment
		(start 442.119258 -207.110076)
		(end 442.5442 -207.535018)
		(width 0.14478)
		(layer "In6.Cu")
		(net "M_K_CPU0_SA_DQ<10>")
	)
	(segment
		(start 423.494454 -206.947008)
		(end 423.657522 -207.110076)
		(width 0.14478)
		(layer "In6.Cu")
		(net "M_K_CPU0_SA_DQ<10>")
	)
	(segment
		(start 414.006792 -207.960214)
		(end 414.85693 -207.110076)
		(width 0.14478)
		(layer "In6.Cu")
		(net "M_K_CPU0_SA_DQ<10>")
	)
	(segment
		(start 441.24245 -207.49895)
		(end 441.472828 -207.49895)
		(width 0.14478)
		(layer "In6.Cu")
		(net "M_K_CPU0_SA_DQ<10>")
	)
	(segment
		(start 428.157132 -207.56499)
		(end 428.38751 -207.56499)
		(width 0.14478)
		(layer "In6.Cu")
		(net "M_K_CPU0_SA_DQ<10>")
	)
	(segment
		(start 441.079382 -206.879698)
		(end 441.079382 -207.335882)
		(width 0.14478)
		(layer "In6.Cu")
		(net "M_K_CPU0_SA_DQ<10>")
	)
	(segment
		(start 390.264904 -230.714296)
		(end 390.418828 -230.448866)
		(width 0.0889)
		(layer "In6.Cu")
		(net "M_K_CPU0_SA_DQ<10>")
	)
	(segment
		(start 420.501826 -207.728058)
		(end 420.664894 -207.56499)
		(width 0.14478)
		(layer "In6.Cu")
		(net "M_K_CPU0_SA_DQ<10>")
	)
	(segment
		(start 395.379194 -227.32238)
		(end 395.379194 -226.967796)
		(width 0.0889)
		(layer "In6.Cu")
		(net "M_K_CPU0_SA_DQ<10>")
	)
	(segment
		(start 432.935888 -207.110076)
		(end 433.786026 -207.960214)
		(width 0.14478)
		(layer "In6.Cu")
		(net "M_K_CPU0_SA_DQ<10>")
	)
	(segment
		(start 428.38751 -207.56499)
		(end 428.550578 -207.728058)
		(width 0.14478)
		(layer "In6.Cu")
		(net "M_K_CPU0_SA_DQ<10>")
	)
	(segment
		(start 420.338758 -207.960214)
		(end 420.501826 -207.797146)
		(width 0.14478)
		(layer "In6.Cu")
		(net "M_K_CPU0_SA_DQ<10>")
	)
	(segment
		(start 422.93794 -206.884778)
		(end 423.101008 -206.72171)
		(width 0.14478)
		(layer "In6.Cu")
		(net "M_K_CPU0_SA_DQ<10>")
	)
	(segment
		(start 394.502894 -228.88321)
		(end 394.73124 -228.654864)
		(width 0.0889)
		(layer "In6.Cu")
		(net "M_K_CPU0_SA_DQ<10>")
	)
	(segment
		(start 420.664894 -207.56499)
		(end 420.895272 -207.56499)
		(width 0.14478)
		(layer "In6.Cu")
		(net "M_K_CPU0_SA_DQ<10>")
	)
	(segment
		(start 441.798964 -207.110076)
		(end 442.119258 -207.110076)
		(width 0.14478)
		(layer "In6.Cu")
		(net "M_K_CPU0_SA_DQ<10>")
	)
	(segment
		(start 440.916314 -206.71663)
		(end 441.079382 -206.879698)
		(width 0.14478)
		(layer "In6.Cu")
		(net "M_K_CPU0_SA_DQ<10>")
	)
	(segment
		(start 428.713646 -207.960214)
		(end 429.08093 -207.960214)
		(width 0.14478)
		(layer "In6.Cu")
		(net "M_K_CPU0_SA_DQ<10>")
	)
	(segment
		(start 441.635896 -207.335882)
		(end 441.635896 -207.273144)
		(width 0.14478)
		(layer "In6.Cu")
		(net "M_K_CPU0_SA_DQ<10>")
	)
	(segment
		(start 423.101008 -206.72171)
		(end 423.331386 -206.72171)
		(width 0.14478)
		(layer "In6.Cu")
		(net "M_K_CPU0_SA_DQ<10>")
	)
	(segment
		(start 435.565296 -207.797146)
		(end 435.565296 -207.733138)
		(width 0.14478)
		(layer "In6.Cu")
		(net "M_K_CPU0_SA_DQ<10>")
	)
	(segment
		(start 433.786026 -207.960214)
		(end 435.402228 -207.960214)
		(width 0.14478)
		(layer "In6.Cu")
		(net "M_K_CPU0_SA_DQ<10>")
	)
	(segment
		(start 436.284878 -207.960214)
		(end 436.6133 -207.960214)
		(width 0.14478)
		(layer "In6.Cu")
		(net "M_K_CPU0_SA_DQ<10>")
	)
	(segment
		(start 440.522868 -206.879698)
		(end 440.685936 -206.71663)
		(width 0.14478)
		(layer "In6.Cu")
		(net "M_K_CPU0_SA_DQ<10>")
	)
	(segment
		(start 394.146024 -228.88321)
		(end 394.502894 -228.88321)
		(width 0.0889)
		(layer "In6.Cu")
		(net "M_K_CPU0_SA_DQ<10>")
	)
	(segment
		(start 420.501826 -207.797146)
		(end 420.501826 -207.728058)
		(width 0.14478)
		(layer "In6.Cu")
		(net "M_K_CPU0_SA_DQ<10>")
	)
	(segment
		(start 429.931068 -207.110076)
		(end 430.357788 -207.110076)
		(width 0.14478)
		(layer "In6.Cu")
		(net "M_K_CPU0_SA_DQ<10>")
	)
	(arc
		(start 391.95756 -230.391716)
		(mid 392.018375 -230.35091)
		(end 392.073384 -230.302562)
		(width 0.0889)
		(layer "In6.Cu")
		(net "M_K_CPU0_SA_DQ<10>")
	)
	(arc
		(start 391.391902 -230.391716)
		(mid 391.668715 -230.467825)
		(end 391.947146 -230.397812)
		(width 0.0889)
		(layer "In6.Cu")
		(net "M_K_CPU0_SA_DQ<10>")
	)
	(arc
		(start 391.026142 -230.38689)
		(mid 391.20965 -230.341396)
		(end 391.391902 -230.391716)
		(width 0.0889)
		(layer "In6.Cu")
		(net "M_K_CPU0_SA_DQ<10>")
	)
	(arc
		(start 390.51484 -230.423466)
		(mid 390.770048 -230.466923)
		(end 391.01776 -230.391716)
		(width 0.0889)
		(layer "In6.Cu")
		(net "M_K_CPU0_SA_DQ<10>")
	)
	(segment
		(start 390.267952 -225.310192)
		(end 390.734804 -225.044254)
		(width 0.10668)
		(layer "F.Cu")
		(net "M_K_CPU0_SA_DQ<0>")
	)
	(segment
		(start 425.392342 -196.910198)
		(end 426.242226 -197.760082)
		(width 0.14478)
		(layer "In6.Cu")
		(net "M_K_CPU0_SA_DQ<0>")
	)
	(segment
		(start 390.734804 -225.044254)
		(end 390.58088 -225.309684)
		(width 0.0889)
		(layer "In6.Cu")
		(net "M_K_CPU0_SA_DQ<0>")
	)
	(segment
		(start 392.049508 -221.80423)
		(end 392.049508 -221.553024)
		(width 0.0889)
		(layer "In6.Cu")
		(net "M_K_CPU0_SA_DQ<0>")
	)
	(segment
		(start 391.933176 -221.436692)
		(end 391.933176 -221.23273)
		(width 0.0889)
		(layer "In6.Cu")
		(net "M_K_CPU0_SA_DQ<0>")
	)
	(segment
		(start 394.899896 -217.97645)
		(end 394.899896 -214.599774)
		(width 0.14478)
		(layer "In6.Cu")
		(net "M_K_CPU0_SA_DQ<0>")
	)
	(segment
		(start 391.861802 -222.12681)
		(end 391.894568 -222.10776)
		(width 0.0889)
		(layer "In6.Cu")
		(net "M_K_CPU0_SA_DQ<0>")
	)
	(segment
		(start 390.58088 -225.309684)
		(end 390.603232 -225.392996)
		(width 0.0889)
		(layer "In6.Cu")
		(net "M_K_CPU0_SA_DQ<0>")
	)
	(segment
		(start 437.5912 -196.910198)
		(end 446.219326 -196.910198)
		(width 0.14478)
		(layer "In6.Cu")
		(net "M_K_CPU0_SA_DQ<0>")
	)
	(segment
		(start 418.698172 -197.760082)
		(end 421.549322 -197.760082)
		(width 0.14478)
		(layer "In6.Cu")
		(net "M_K_CPU0_SA_DQ<0>")
	)
	(segment
		(start 446.219326 -196.910198)
		(end 446.644268 -197.33514)
		(width 0.14478)
		(layer "In6.Cu")
		(net "M_K_CPU0_SA_DQ<0>")
	)
	(segment
		(start 414.046416 -197.760082)
		(end 414.896554 -196.909944)
		(width 0.14478)
		(layer "In6.Cu")
		(net "M_K_CPU0_SA_DQ<0>")
	)
	(segment
		(start 433.786026 -197.760082)
		(end 435.539388 -197.760082)
		(width 0.14478)
		(layer "In6.Cu")
		(net "M_K_CPU0_SA_DQ<0>")
	)
	(segment
		(start 390.885426 -223.767904)
		(end 390.921748 -223.746822)
		(width 0.0889)
		(layer "In6.Cu")
		(net "M_K_CPU0_SA_DQ<0>")
	)
	(segment
		(start 394.899896 -214.599774)
		(end 411.739588 -197.760082)
		(width 0.14478)
		(layer "In6.Cu")
		(net "M_K_CPU0_SA_DQ<0>")
	)
	(segment
		(start 432.936142 -196.910198)
		(end 433.786026 -197.760082)
		(width 0.14478)
		(layer "In6.Cu")
		(net "M_K_CPU0_SA_DQ<0>")
	)
	(segment
		(start 390.921748 -224.721674)
		(end 390.885426 -224.700592)
		(width 0.0889)
		(layer "In6.Cu")
		(net "M_K_CPU0_SA_DQ<0>")
	)
	(segment
		(start 391.933176 -221.23273)
		(end 391.933176 -220.94317)
		(width 0.14478)
		(layer "In6.Cu")
		(net "M_K_CPU0_SA_DQ<0>")
	)
	(segment
		(start 391.822686 -222.14967)
		(end 391.861802 -222.12681)
		(width 0.0889)
		(layer "In6.Cu")
		(net "M_K_CPU0_SA_DQ<0>")
	)
	(segment
		(start 390.921748 -225.366834)
		(end 390.953498 -225.348546)
		(width 0.0889)
		(layer "In6.Cu")
		(net "M_K_CPU0_SA_DQ<0>")
	)
	(segment
		(start 390.953498 -224.739962)
		(end 390.921748 -224.721674)
		(width 0.0889)
		(layer "In6.Cu")
		(net "M_K_CPU0_SA_DQ<0>")
	)
	(segment
		(start 411.739588 -197.760082)
		(end 414.046416 -197.760082)
		(width 0.14478)
		(layer "In6.Cu")
		(net "M_K_CPU0_SA_DQ<0>")
	)
	(segment
		(start 414.896554 -196.909944)
		(end 417.848034 -196.909944)
		(width 0.14478)
		(layer "In6.Cu")
		(net "M_K_CPU0_SA_DQ<0>")
	)
	(segment
		(start 426.242226 -197.760082)
		(end 429.08093 -197.760082)
		(width 0.14478)
		(layer "In6.Cu")
		(net "M_K_CPU0_SA_DQ<0>")
	)
	(segment
		(start 422.399206 -196.910198)
		(end 425.392342 -196.910198)
		(width 0.14478)
		(layer "In6.Cu")
		(net "M_K_CPU0_SA_DQ<0>")
	)
	(segment
		(start 421.549322 -197.760082)
		(end 422.399206 -196.910198)
		(width 0.14478)
		(layer "In6.Cu")
		(net "M_K_CPU0_SA_DQ<0>")
	)
	(segment
		(start 391.391902 -222.936816)
		(end 391.422382 -222.919036)
		(width 0.0889)
		(layer "In6.Cu")
		(net "M_K_CPU0_SA_DQ<0>")
	)
	(segment
		(start 391.352786 -222.959676)
		(end 391.391902 -222.936816)
		(width 0.0889)
		(layer "In6.Cu")
		(net "M_K_CPU0_SA_DQ<0>")
	)
	(segment
		(start 429.08093 -197.760082)
		(end 429.930814 -196.910198)
		(width 0.14478)
		(layer "In6.Cu")
		(net "M_K_CPU0_SA_DQ<0>")
	)
	(segment
		(start 392.049508 -221.553024)
		(end 391.933176 -221.436692)
		(width 0.0889)
		(layer "In6.Cu")
		(net "M_K_CPU0_SA_DQ<0>")
	)
	(segment
		(start 429.930814 -196.910198)
		(end 432.936142 -196.910198)
		(width 0.14478)
		(layer "In6.Cu")
		(net "M_K_CPU0_SA_DQ<0>")
	)
	(segment
		(start 391.933176 -220.94317)
		(end 394.899896 -217.97645)
		(width 0.14478)
		(layer "In6.Cu")
		(net "M_K_CPU0_SA_DQ<0>")
	)
	(segment
		(start 390.921748 -223.746822)
		(end 390.953498 -223.728534)
		(width 0.0889)
		(layer "In6.Cu")
		(net "M_K_CPU0_SA_DQ<0>")
	)
	(segment
		(start 435.539388 -197.760082)
		(end 437.5912 -196.910198)
		(width 0.14478)
		(layer "In6.Cu")
		(net "M_K_CPU0_SA_DQ<0>")
	)
	(segment
		(start 417.848034 -196.909944)
		(end 418.698172 -197.760082)
		(width 0.14478)
		(layer "In6.Cu")
		(net "M_K_CPU0_SA_DQ<0>")
	)
	(arc
		(start 390.953498 -223.728534)
		(mid 391.068174 -223.5952)
		(end 391.109454 -223.424242)
		(width 0.0889)
		(layer "In6.Cu")
		(net "M_K_CPU0_SA_DQ<0>")
	)
	(arc
		(start 391.894568 -222.10776)
		(mid 392.008497 -221.974613)
		(end 392.049508 -221.80423)
		(width 0.0889)
		(layer "In6.Cu")
		(net "M_K_CPU0_SA_DQ<0>")
	)
	(arc
		(start 391.422382 -222.919036)
		(mid 391.537809 -222.78566)
		(end 391.579354 -222.614236)
		(width 0.0889)
		(layer "In6.Cu")
		(net "M_K_CPU0_SA_DQ<0>")
	)
	(arc
		(start 390.885426 -224.700592)
		(mid 390.639536 -224.234248)
		(end 390.885426 -223.767904)
		(width 0.0889)
		(layer "In6.Cu")
		(net "M_K_CPU0_SA_DQ<0>")
	)
	(arc
		(start 390.603232 -225.392996)
		(mid 390.765421 -225.415731)
		(end 390.921748 -225.366834)
		(width 0.0889)
		(layer "In6.Cu")
		(net "M_K_CPU0_SA_DQ<0>")
	)
	(arc
		(start 391.109454 -223.424242)
		(mid 391.173969 -223.162023)
		(end 391.352786 -222.959676)
		(width 0.0889)
		(layer "In6.Cu")
		(net "M_K_CPU0_SA_DQ<0>")
	)
	(arc
		(start 391.579354 -222.614236)
		(mid 391.643869 -222.352017)
		(end 391.822686 -222.14967)
		(width 0.0889)
		(layer "In6.Cu")
		(net "M_K_CPU0_SA_DQ<0>")
	)
	(arc
		(start 390.953498 -225.348546)
		(mid 391.109426 -225.044254)
		(end 390.953498 -224.739962)
		(width 0.0889)
		(layer "In6.Cu")
		(net "M_K_CPU0_SA_DQ<0>")
	)
	(segment
		(start 388.857998 -252.040136)
		(end 389.32485 -251.774198)
		(width 0.10668)
		(layer "F.Cu")
		(net "M_K_CPU0_SA_CS_N<1>")
	)
	(segment
		(start 393.25296 -252.106938)
		(end 393.271248 -252.096524)
		(width 0.0889)
		(layer "In6.Cu")
		(net "M_K_CPU0_SA_CS_N<1>")
	)
	(segment
		(start 411.367732 -248.75998)
		(end 437.889396 -248.75998)
		(width 0.14478)
		(layer "In6.Cu")
		(net "M_K_CPU0_SA_CS_N<1>")
	)
	(segment
		(start 393.271248 -252.096524)
		(end 393.276836 -252.093222)
		(width 0.0889)
		(layer "In6.Cu")
		(net "M_K_CPU0_SA_CS_N<1>")
	)
	(segment
		(start 437.889396 -248.75998)
		(end 438.739534 -247.909842)
		(width 0.14478)
		(layer "In6.Cu")
		(net "M_K_CPU0_SA_CS_N<1>")
	)
	(segment
		(start 394.960856 -252.46203)
		(end 395.346936 -252.84811)
		(width 0.0889)
		(layer "In6.Cu")
		(net "M_K_CPU0_SA_CS_N<1>")
	)
	(segment
		(start 394.338556 -252.46203)
		(end 394.960856 -252.46203)
		(width 0.0889)
		(layer "In6.Cu")
		(net "M_K_CPU0_SA_CS_N<1>")
	)
	(segment
		(start 391.017506 -252.096778)
		(end 391.025888 -252.101604)
		(width 0.0889)
		(layer "In6.Cu")
		(net "M_K_CPU0_SA_CS_N<1>")
	)
	(segment
		(start 395.346936 -252.84811)
		(end 395.799564 -252.84811)
		(width 0.0889)
		(layer "In6.Cu")
		(net "M_K_CPU0_SA_CS_N<1>")
	)
	(segment
		(start 398.528286 -251.51588)
		(end 408.611832 -251.51588)
		(width 0.14478)
		(layer "In6.Cu")
		(net "M_K_CPU0_SA_CS_N<1>")
	)
	(segment
		(start 391.957306 -252.096778)
		(end 391.965688 -252.101604)
		(width 0.0889)
		(layer "In6.Cu")
		(net "M_K_CPU0_SA_CS_N<1>")
	)
	(segment
		(start 392.33094 -252.096778)
		(end 392.341354 -252.090682)
		(width 0.0889)
		(layer "In6.Cu")
		(net "M_K_CPU0_SA_CS_N<1>")
	)
	(segment
		(start 395.799564 -252.84811)
		(end 397.196056 -252.84811)
		(width 0.14478)
		(layer "In6.Cu")
		(net "M_K_CPU0_SA_CS_N<1>")
	)
	(segment
		(start 397.196056 -252.84811)
		(end 398.528286 -251.51588)
		(width 0.14478)
		(layer "In6.Cu")
		(net "M_K_CPU0_SA_CS_N<1>")
	)
	(segment
		(start 391.946892 -252.090682)
		(end 391.957306 -252.096778)
		(width 0.0889)
		(layer "In6.Cu")
		(net "M_K_CPU0_SA_CS_N<1>")
	)
	(segment
		(start 390.443212 -252.101604)
		(end 390.451594 -252.096778)
		(width 0.0889)
		(layer "In6.Cu")
		(net "M_K_CPU0_SA_CS_N<1>")
	)
	(segment
		(start 408.611832 -251.51588)
		(end 411.367732 -248.75998)
		(width 0.14478)
		(layer "In6.Cu")
		(net "M_K_CPU0_SA_CS_N<1>")
	)
	(segment
		(start 393.969748 -252.093222)
		(end 394.338556 -252.46203)
		(width 0.0889)
		(layer "In6.Cu")
		(net "M_K_CPU0_SA_CS_N<1>")
	)
	(segment
		(start 389.32485 -251.774198)
		(end 389.170672 -252.039628)
		(width 0.0889)
		(layer "In6.Cu")
		(net "M_K_CPU0_SA_CS_N<1>")
	)
	(segment
		(start 441.269374 -247.909842)
		(end 442.5442 -246.635016)
		(width 0.14478)
		(layer "In6.Cu")
		(net "M_K_CPU0_SA_CS_N<1>")
	)
	(segment
		(start 393.276836 -252.093222)
		(end 393.969748 -252.093222)
		(width 0.0889)
		(layer "In6.Cu")
		(net "M_K_CPU0_SA_CS_N<1>")
	)
	(segment
		(start 389.170672 -252.039628)
		(end 389.193024 -252.12294)
		(width 0.0889)
		(layer "In6.Cu")
		(net "M_K_CPU0_SA_CS_N<1>")
	)
	(segment
		(start 438.739534 -247.909842)
		(end 441.269374 -247.909842)
		(width 0.14478)
		(layer "In6.Cu")
		(net "M_K_CPU0_SA_CS_N<1>")
	)
	(arc
		(start 389.193024 -252.12294)
		(mid 389.355213 -252.145675)
		(end 389.51154 -252.096778)
		(width 0.0889)
		(layer "In6.Cu")
		(net "M_K_CPU0_SA_CS_N<1>")
	)
	(arc
		(start 391.391648 -252.096778)
		(mid 391.668461 -252.020635)
		(end 391.946892 -252.090682)
		(width 0.0889)
		(layer "In6.Cu")
		(net "M_K_CPU0_SA_CS_N<1>")
	)
	(arc
		(start 390.451594 -252.096778)
		(mid 390.73455 -252.020601)
		(end 391.017506 -252.096778)
		(width 0.0889)
		(layer "In6.Cu")
		(net "M_K_CPU0_SA_CS_N<1>")
	)
	(arc
		(start 392.341354 -252.090682)
		(mid 392.62004 -252.020462)
		(end 392.897106 -252.096778)
		(width 0.0889)
		(layer "In6.Cu")
		(net "M_K_CPU0_SA_CS_N<1>")
	)
	(arc
		(start 389.51154 -252.096778)
		(mid 389.794496 -252.020601)
		(end 390.077452 -252.096778)
		(width 0.0889)
		(layer "In6.Cu")
		(net "M_K_CPU0_SA_CS_N<1>")
	)
	(arc
		(start 392.897106 -252.096778)
		(mid 393.073734 -252.147011)
		(end 393.25296 -252.106938)
		(width 0.0889)
		(layer "In6.Cu")
		(net "M_K_CPU0_SA_CS_N<1>")
	)
	(arc
		(start 391.025888 -252.101604)
		(mid 391.209396 -252.147098)
		(end 391.391648 -252.096778)
		(width 0.0889)
		(layer "In6.Cu")
		(net "M_K_CPU0_SA_CS_N<1>")
	)
	(arc
		(start 391.965688 -252.101604)
		(mid 392.148942 -252.146977)
		(end 392.33094 -252.096778)
		(width 0.0889)
		(layer "In6.Cu")
		(net "M_K_CPU0_SA_CS_N<1>")
	)
	(arc
		(start 390.077452 -252.096778)
		(mid 390.259703 -252.147128)
		(end 390.443212 -252.101604)
		(width 0.0889)
		(layer "In6.Cu")
		(net "M_K_CPU0_SA_CS_N<1>")
	)
	(segment
		(start 390.267952 -251.23013)
		(end 390.734804 -250.964192)
		(width 0.10668)
		(layer "F.Cu")
		(net "M_K_CPU0_SA_CS_N<0>")
	)
	(segment
		(start 395.090396 -252.07849)
		(end 395.405356 -252.39345)
		(width 0.0889)
		(layer "In6.Cu")
		(net "M_K_CPU0_SA_CS_N<0>")
	)
	(segment
		(start 446.21958 -246.20982)
		(end 446.644268 -245.785132)
		(width 0.14478)
		(layer "In6.Cu")
		(net "M_K_CPU0_SA_CS_N<0>")
	)
	(segment
		(start 391.85342 -251.291598)
		(end 391.861802 -251.286772)
		(width 0.0889)
		(layer "In6.Cu")
		(net "M_K_CPU0_SA_CS_N<0>")
	)
	(segment
		(start 393.367514 -251.286772)
		(end 393.375896 -251.291598)
		(width 0.0889)
		(layer "In6.Cu")
		(net "M_K_CPU0_SA_CS_N<0>")
	)
	(segment
		(start 394.432536 -252.07849)
		(end 395.090396 -252.07849)
		(width 0.0889)
		(layer "In6.Cu")
		(net "M_K_CPU0_SA_CS_N<0>")
	)
	(segment
		(start 398.339818 -251.06122)
		(end 408.216608 -251.06122)
		(width 0.14478)
		(layer "In6.Cu")
		(net "M_K_CPU0_SA_CS_N<0>")
	)
	(segment
		(start 390.734804 -250.964192)
		(end 390.58088 -251.229622)
		(width 0.0889)
		(layer "In6.Cu")
		(net "M_K_CPU0_SA_CS_N<0>")
	)
	(segment
		(start 395.799564 -252.39345)
		(end 397.007588 -252.39345)
		(width 0.14478)
		(layer "In6.Cu")
		(net "M_K_CPU0_SA_CS_N<0>")
	)
	(segment
		(start 392.42746 -251.286772)
		(end 392.435842 -251.291598)
		(width 0.0889)
		(layer "In6.Cu")
		(net "M_K_CPU0_SA_CS_N<0>")
	)
	(segment
		(start 393.375896 -251.291598)
		(end 393.678664 -251.457206)
		(width 0.0889)
		(layer "In6.Cu")
		(net "M_K_CPU0_SA_CS_N<0>")
	)
	(segment
		(start 397.007588 -252.39345)
		(end 398.339818 -251.06122)
		(width 0.14478)
		(layer "In6.Cu")
		(net "M_K_CPU0_SA_CS_N<0>")
	)
	(segment
		(start 437.889396 -247.910096)
		(end 438.739534 -247.059958)
		(width 0.14478)
		(layer "In6.Cu")
		(net "M_K_CPU0_SA_CS_N<0>")
	)
	(segment
		(start 390.58088 -251.229622)
		(end 390.603232 -251.312934)
		(width 0.0889)
		(layer "In6.Cu")
		(net "M_K_CPU0_SA_CS_N<0>")
	)
	(segment
		(start 393.678664 -251.457206)
		(end 393.811252 -251.457206)
		(width 0.0889)
		(layer "In6.Cu")
		(net "M_K_CPU0_SA_CS_N<0>")
	)
	(segment
		(start 395.405356 -252.39345)
		(end 395.799564 -252.39345)
		(width 0.0889)
		(layer "In6.Cu")
		(net "M_K_CPU0_SA_CS_N<0>")
	)
	(segment
		(start 440.622944 -246.20982)
		(end 446.21958 -246.20982)
		(width 0.14478)
		(layer "In6.Cu")
		(net "M_K_CPU0_SA_CS_N<0>")
	)
	(segment
		(start 393.352782 -251.278136)
		(end 393.367514 -251.286772)
		(width 0.0889)
		(layer "In6.Cu")
		(net "M_K_CPU0_SA_CS_N<0>")
	)
	(segment
		(start 391.861802 -251.286772)
		(end 391.872216 -251.280676)
		(width 0.0889)
		(layer "In6.Cu")
		(net "M_K_CPU0_SA_CS_N<0>")
	)
	(segment
		(start 438.739534 -247.059958)
		(end 439.772806 -247.059958)
		(width 0.14478)
		(layer "In6.Cu")
		(net "M_K_CPU0_SA_CS_N<0>")
	)
	(segment
		(start 439.772806 -247.059958)
		(end 440.622944 -246.20982)
		(width 0.14478)
		(layer "In6.Cu")
		(net "M_K_CPU0_SA_CS_N<0>")
	)
	(segment
		(start 393.811252 -251.457206)
		(end 394.432536 -252.07849)
		(width 0.0889)
		(layer "In6.Cu")
		(net "M_K_CPU0_SA_CS_N<0>")
	)
	(segment
		(start 408.216608 -251.06122)
		(end 411.367732 -247.910096)
		(width 0.14478)
		(layer "In6.Cu")
		(net "M_K_CPU0_SA_CS_N<0>")
	)
	(segment
		(start 411.367732 -247.910096)
		(end 437.889396 -247.910096)
		(width 0.14478)
		(layer "In6.Cu")
		(net "M_K_CPU0_SA_CS_N<0>")
	)
	(arc
		(start 390.603232 -251.312934)
		(mid 390.765421 -251.335669)
		(end 390.921748 -251.286772)
		(width 0.0889)
		(layer "In6.Cu")
		(net "M_K_CPU0_SA_CS_N<0>")
	)
	(arc
		(start 390.921748 -251.286772)
		(mid 391.204704 -251.210595)
		(end 391.48766 -251.286772)
		(width 0.0889)
		(layer "In6.Cu")
		(net "M_K_CPU0_SA_CS_N<0>")
	)
	(arc
		(start 392.435842 -251.291598)
		(mid 392.61935 -251.337092)
		(end 392.801602 -251.286772)
		(width 0.0889)
		(layer "In6.Cu")
		(net "M_K_CPU0_SA_CS_N<0>")
	)
	(arc
		(start 392.801602 -251.286772)
		(mid 393.076054 -251.210536)
		(end 393.352782 -251.278136)
		(width 0.0889)
		(layer "In6.Cu")
		(net "M_K_CPU0_SA_CS_N<0>")
	)
	(arc
		(start 391.48766 -251.286772)
		(mid 391.669911 -251.337122)
		(end 391.85342 -251.291598)
		(width 0.0889)
		(layer "In6.Cu")
		(net "M_K_CPU0_SA_CS_N<0>")
	)
	(arc
		(start 391.872216 -251.280676)
		(mid 392.150648 -251.210578)
		(end 392.42746 -251.286772)
		(width 0.0889)
		(layer "In6.Cu")
		(net "M_K_CPU0_SA_CS_N<0>")
	)
	(segment
		(start 388.387844 -249.610118)
		(end 388.85495 -249.34418)
		(width 0.10668)
		(layer "F.Cu")
		(net "M_K_CPU0_SA_CB<7>")
	)
	(segment
		(start 428.476156 -243.902992)
		(end 428.476156 -244.365272)
		(width 0.14478)
		(layer "In6.Cu")
		(net "M_K_CPU0_SA_CB<7>")
	)
	(segment
		(start 396.647416 -249.96775)
		(end 397.535146 -249.08002)
		(width 0.14478)
		(layer "In6.Cu")
		(net "M_K_CPU0_SA_CB<7>")
	)
	(segment
		(start 429.579024 -244.365272)
		(end 429.723804 -244.510052)
		(width 0.14478)
		(layer "In6.Cu")
		(net "M_K_CPU0_SA_CB<7>")
	)
	(segment
		(start 427.924722 -244.365272)
		(end 427.924722 -243.902992)
		(width 0.14478)
		(layer "In6.Cu")
		(net "M_K_CPU0_SA_CB<7>")
	)
	(segment
		(start 397.535146 -249.08002)
		(end 406.84323 -249.08002)
		(width 0.14478)
		(layer "In6.Cu")
		(net "M_K_CPU0_SA_CB<7>")
	)
	(segment
		(start 389.607806 -249.0216)
		(end 389.616188 -249.016774)
		(width 0.0889)
		(layer "In6.Cu")
		(net "M_K_CPU0_SA_CB<7>")
	)
	(segment
		(start 429.02759 -244.365272)
		(end 429.02759 -243.902992)
		(width 0.14478)
		(layer "In6.Cu")
		(net "M_K_CPU0_SA_CB<7>")
	)
	(segment
		(start 434.048662 -244.365272)
		(end 434.193442 -244.510052)
		(width 0.14478)
		(layer "In6.Cu")
		(net "M_K_CPU0_SA_CB<7>")
	)
	(segment
		(start 411.413198 -244.510052)
		(end 427.779942 -244.510052)
		(width 0.14478)
		(layer "In6.Cu")
		(net "M_K_CPU0_SA_CB<7>")
	)
	(segment
		(start 389.008874 -249.07875)
		(end 389.104886 -249.05335)
		(width 0.0889)
		(layer "In6.Cu")
		(net "M_K_CPU0_SA_CB<7>")
	)
	(segment
		(start 406.84323 -249.08002)
		(end 411.413198 -244.510052)
		(width 0.14478)
		(layer "In6.Cu")
		(net "M_K_CPU0_SA_CB<7>")
	)
	(segment
		(start 432.801014 -243.331492)
		(end 432.945794 -243.476272)
		(width 0.14478)
		(layer "In6.Cu")
		(net "M_K_CPU0_SA_CB<7>")
	)
	(segment
		(start 433.642008 -243.331492)
		(end 433.903882 -243.331492)
		(width 0.14478)
		(layer "In6.Cu")
		(net "M_K_CPU0_SA_CB<7>")
	)
	(segment
		(start 432.39436 -243.476272)
		(end 432.53914 -243.331492)
		(width 0.14478)
		(layer "In6.Cu")
		(net "M_K_CPU0_SA_CB<7>")
	)
	(segment
		(start 395.247876 -249.96775)
		(end 396.647416 -249.96775)
		(width 0.14478)
		(layer "In6.Cu")
		(net "M_K_CPU0_SA_CB<7>")
	)
	(segment
		(start 433.497228 -243.476272)
		(end 433.642008 -243.331492)
		(width 0.14478)
		(layer "In6.Cu")
		(net "M_K_CPU0_SA_CB<7>")
	)
	(segment
		(start 434.193442 -244.510052)
		(end 436.145432 -244.510052)
		(width 0.14478)
		(layer "In6.Cu")
		(net "M_K_CPU0_SA_CB<7>")
	)
	(segment
		(start 429.723804 -244.510052)
		(end 432.24958 -244.510052)
		(width 0.14478)
		(layer "In6.Cu")
		(net "M_K_CPU0_SA_CB<7>")
	)
	(segment
		(start 433.352448 -244.510052)
		(end 433.497228 -244.365272)
		(width 0.14478)
		(layer "In6.Cu")
		(net "M_K_CPU0_SA_CB<7>")
	)
	(segment
		(start 428.88281 -244.510052)
		(end 429.02759 -244.365272)
		(width 0.14478)
		(layer "In6.Cu")
		(net "M_K_CPU0_SA_CB<7>")
	)
	(segment
		(start 427.924722 -243.902992)
		(end 428.069502 -243.758212)
		(width 0.14478)
		(layer "In6.Cu")
		(net "M_K_CPU0_SA_CB<7>")
	)
	(segment
		(start 432.53914 -243.331492)
		(end 432.801014 -243.331492)
		(width 0.14478)
		(layer "In6.Cu")
		(net "M_K_CPU0_SA_CB<7>")
	)
	(segment
		(start 392.801602 -249.0216)
		(end 393.738862 -249.96775)
		(width 0.0889)
		(layer "In6.Cu")
		(net "M_K_CPU0_SA_CB<7>")
	)
	(segment
		(start 392.427206 -249.0216)
		(end 392.43889 -249.014742)
		(width 0.0889)
		(layer "In6.Cu")
		(net "M_K_CPU0_SA_CB<7>")
	)
	(segment
		(start 429.02759 -243.902992)
		(end 429.17237 -243.758212)
		(width 0.14478)
		(layer "In6.Cu")
		(net "M_K_CPU0_SA_CB<7>")
	)
	(segment
		(start 391.861548 -249.0216)
		(end 391.871962 -249.027696)
		(width 0.0889)
		(layer "In6.Cu")
		(net "M_K_CPU0_SA_CB<7>")
	)
	(segment
		(start 428.476156 -244.365272)
		(end 428.620936 -244.510052)
		(width 0.14478)
		(layer "In6.Cu")
		(net "M_K_CPU0_SA_CB<7>")
	)
	(segment
		(start 432.39436 -244.365272)
		(end 432.39436 -243.476272)
		(width 0.14478)
		(layer "In6.Cu")
		(net "M_K_CPU0_SA_CB<7>")
	)
	(segment
		(start 428.620936 -244.510052)
		(end 428.88281 -244.510052)
		(width 0.14478)
		(layer "In6.Cu")
		(net "M_K_CPU0_SA_CB<7>")
	)
	(segment
		(start 388.85495 -249.34418)
		(end 389.008874 -249.07875)
		(width 0.0889)
		(layer "In6.Cu")
		(net "M_K_CPU0_SA_CB<7>")
	)
	(segment
		(start 428.331376 -243.758212)
		(end 428.476156 -243.902992)
		(width 0.14478)
		(layer "In6.Cu")
		(net "M_K_CPU0_SA_CB<7>")
	)
	(segment
		(start 432.24958 -244.510052)
		(end 432.39436 -244.365272)
		(width 0.14478)
		(layer "In6.Cu")
		(net "M_K_CPU0_SA_CB<7>")
	)
	(segment
		(start 429.434244 -243.758212)
		(end 429.579024 -243.902992)
		(width 0.14478)
		(layer "In6.Cu")
		(net "M_K_CPU0_SA_CB<7>")
	)
	(segment
		(start 393.738862 -249.96775)
		(end 395.247876 -249.96775)
		(width 0.0889)
		(layer "In6.Cu")
		(net "M_K_CPU0_SA_CB<7>")
	)
	(segment
		(start 434.048662 -243.476272)
		(end 434.048662 -244.365272)
		(width 0.14478)
		(layer "In6.Cu")
		(net "M_K_CPU0_SA_CB<7>")
	)
	(segment
		(start 437.845454 -242.81003)
		(end 442.119258 -242.81003)
		(width 0.14478)
		(layer "In6.Cu")
		(net "M_K_CPU0_SA_CB<7>")
	)
	(segment
		(start 433.090574 -244.510052)
		(end 433.352448 -244.510052)
		(width 0.14478)
		(layer "In6.Cu")
		(net "M_K_CPU0_SA_CB<7>")
	)
	(segment
		(start 436.145432 -244.510052)
		(end 437.845454 -242.81003)
		(width 0.14478)
		(layer "In6.Cu")
		(net "M_K_CPU0_SA_CB<7>")
	)
	(segment
		(start 433.903882 -243.331492)
		(end 434.048662 -243.476272)
		(width 0.14478)
		(layer "In6.Cu")
		(net "M_K_CPU0_SA_CB<7>")
	)
	(segment
		(start 428.069502 -243.758212)
		(end 428.331376 -243.758212)
		(width 0.14478)
		(layer "In6.Cu")
		(net "M_K_CPU0_SA_CB<7>")
	)
	(segment
		(start 429.17237 -243.758212)
		(end 429.434244 -243.758212)
		(width 0.14478)
		(layer "In6.Cu")
		(net "M_K_CPU0_SA_CB<7>")
	)
	(segment
		(start 391.849864 -249.014742)
		(end 391.861548 -249.0216)
		(width 0.0889)
		(layer "In6.Cu")
		(net "M_K_CPU0_SA_CB<7>")
	)
	(segment
		(start 432.945794 -244.365272)
		(end 433.090574 -244.510052)
		(width 0.14478)
		(layer "In6.Cu")
		(net "M_K_CPU0_SA_CB<7>")
	)
	(segment
		(start 433.497228 -244.365272)
		(end 433.497228 -243.476272)
		(width 0.14478)
		(layer "In6.Cu")
		(net "M_K_CPU0_SA_CB<7>")
	)
	(segment
		(start 429.579024 -243.902992)
		(end 429.579024 -244.365272)
		(width 0.14478)
		(layer "In6.Cu")
		(net "M_K_CPU0_SA_CB<7>")
	)
	(segment
		(start 432.945794 -243.476272)
		(end 432.945794 -244.365272)
		(width 0.14478)
		(layer "In6.Cu")
		(net "M_K_CPU0_SA_CB<7>")
	)
	(segment
		(start 427.779942 -244.510052)
		(end 427.924722 -244.365272)
		(width 0.14478)
		(layer "In6.Cu")
		(net "M_K_CPU0_SA_CB<7>")
	)
	(segment
		(start 442.119258 -242.81003)
		(end 442.5442 -243.234972)
		(width 0.14478)
		(layer "In6.Cu")
		(net "M_K_CPU0_SA_CB<7>")
	)
	(arc
		(start 389.104886 -249.05335)
		(mid 389.360094 -249.096827)
		(end 389.607806 -249.0216)
		(width 0.0889)
		(layer "In6.Cu")
		(net "M_K_CPU0_SA_CB<7>")
	)
	(arc
		(start 389.981948 -249.0216)
		(mid 390.264904 -249.097777)
		(end 390.54786 -249.0216)
		(width 0.0889)
		(layer "In6.Cu")
		(net "M_K_CPU0_SA_CB<7>")
	)
	(arc
		(start 392.43889 -249.014742)
		(mid 392.621145 -248.971089)
		(end 392.801602 -249.0216)
		(width 0.0889)
		(layer "In6.Cu")
		(net "M_K_CPU0_SA_CB<7>")
	)
	(arc
		(start 390.921748 -249.0216)
		(mid 391.204704 -249.097777)
		(end 391.48766 -249.0216)
		(width 0.0889)
		(layer "In6.Cu")
		(net "M_K_CPU0_SA_CB<7>")
	)
	(arc
		(start 389.616188 -249.016774)
		(mid 389.799696 -248.97128)
		(end 389.981948 -249.0216)
		(width 0.0889)
		(layer "In6.Cu")
		(net "M_K_CPU0_SA_CB<7>")
	)
	(arc
		(start 391.48766 -249.0216)
		(mid 391.667865 -248.971283)
		(end 391.849864 -249.014742)
		(width 0.0889)
		(layer "In6.Cu")
		(net "M_K_CPU0_SA_CB<7>")
	)
	(arc
		(start 391.871962 -249.027696)
		(mid 392.150394 -249.097794)
		(end 392.427206 -249.0216)
		(width 0.0889)
		(layer "In6.Cu")
		(net "M_K_CPU0_SA_CB<7>")
	)
	(arc
		(start 390.54786 -249.0216)
		(mid 390.734804 -248.971345)
		(end 390.921748 -249.0216)
		(width 0.0889)
		(layer "In6.Cu")
		(net "M_K_CPU0_SA_CB<7>")
	)
	(segment
		(start 389.798052 -248.800112)
		(end 390.264904 -248.534174)
		(width 0.10668)
		(layer "F.Cu")
		(net "M_K_CPU0_SA_CB<6>")
	)
	(segment
		(start 397.084804 -248.1707)
		(end 406.127204 -248.1707)
		(width 0.14478)
		(layer "In6.Cu")
		(net "M_K_CPU0_SA_CB<6>")
	)
	(segment
		(start 417.57092 -242.777772)
		(end 417.832794 -242.777772)
		(width 0.14478)
		(layer "In6.Cu")
		(net "M_K_CPU0_SA_CB<6>")
	)
	(segment
		(start 421.931592 -243.024152)
		(end 422.193466 -243.024152)
		(width 0.14478)
		(layer "In6.Cu")
		(net "M_K_CPU0_SA_CB<6>")
	)
	(segment
		(start 421.235378 -242.879372)
		(end 421.235378 -242.104926)
		(width 0.14478)
		(layer "In6.Cu")
		(net "M_K_CPU0_SA_CB<6>")
	)
	(segment
		(start 418.935662 -242.777772)
		(end 419.080442 -242.632992)
		(width 0.14478)
		(layer "In6.Cu")
		(net "M_K_CPU0_SA_CB<6>")
	)
	(segment
		(start 417.832794 -242.777772)
		(end 417.977574 -242.632992)
		(width 0.14478)
		(layer "In6.Cu")
		(net "M_K_CPU0_SA_CB<6>")
	)
	(segment
		(start 423.441114 -242.879372)
		(end 423.441114 -242.104926)
		(width 0.14478)
		(layer "In6.Cu")
		(net "M_K_CPU0_SA_CB<6>")
	)
	(segment
		(start 437.591454 -241.110008)
		(end 442.119258 -241.110008)
		(width 0.14478)
		(layer "In6.Cu")
		(net "M_K_CPU0_SA_CB<6>")
	)
	(segment
		(start 422.88968 -242.879372)
		(end 423.03446 -243.024152)
		(width 0.14478)
		(layer "In6.Cu")
		(net "M_K_CPU0_SA_CB<6>")
	)
	(segment
		(start 394.210286 -248.82221)
		(end 395.793214 -248.82221)
		(width 0.0889)
		(layer "In6.Cu")
		(net "M_K_CPU0_SA_CB<6>")
	)
	(segment
		(start 421.090598 -243.024152)
		(end 421.235378 -242.879372)
		(width 0.14478)
		(layer "In6.Cu")
		(net "M_K_CPU0_SA_CB<6>")
	)
	(segment
		(start 421.380158 -241.960146)
		(end 421.642032 -241.960146)
		(width 0.14478)
		(layer "In6.Cu")
		(net "M_K_CPU0_SA_CB<6>")
	)
	(segment
		(start 395.793214 -248.82221)
		(end 396.433294 -248.82221)
		(width 0.14478)
		(layer "In6.Cu")
		(net "M_K_CPU0_SA_CB<6>")
	)
	(segment
		(start 422.193466 -243.024152)
		(end 422.338246 -242.879372)
		(width 0.14478)
		(layer "In6.Cu")
		(net "M_K_CPU0_SA_CB<6>")
	)
	(segment
		(start 406.127204 -248.1707)
		(end 411.487874 -242.81003)
		(width 0.14478)
		(layer "In6.Cu")
		(net "M_K_CPU0_SA_CB<6>")
	)
	(segment
		(start 390.418828 -248.268744)
		(end 390.51484 -248.243344)
		(width 0.0889)
		(layer "In6.Cu")
		(net "M_K_CPU0_SA_CB<6>")
	)
	(segment
		(start 411.487874 -242.81003)
		(end 414.619694 -242.81003)
		(width 0.14478)
		(layer "In6.Cu")
		(net "M_K_CPU0_SA_CB<6>")
	)
	(segment
		(start 436.741316 -241.960146)
		(end 437.591454 -241.110008)
		(width 0.14478)
		(layer "In6.Cu")
		(net "M_K_CPU0_SA_CB<6>")
	)
	(segment
		(start 420.683944 -242.879372)
		(end 420.828724 -243.024152)
		(width 0.14478)
		(layer "In6.Cu")
		(net "M_K_CPU0_SA_CB<6>")
	)
	(segment
		(start 422.483026 -241.960146)
		(end 422.7449 -241.960146)
		(width 0.14478)
		(layer "In6.Cu")
		(net "M_K_CPU0_SA_CB<6>")
	)
	(segment
		(start 418.529008 -242.632992)
		(end 418.673788 -242.777772)
		(width 0.14478)
		(layer "In6.Cu")
		(net "M_K_CPU0_SA_CB<6>")
	)
	(segment
		(start 422.338246 -242.879372)
		(end 422.338246 -242.104926)
		(width 0.14478)
		(layer "In6.Cu")
		(net "M_K_CPU0_SA_CB<6>")
	)
	(segment
		(start 415.469578 -241.960146)
		(end 417.28136 -241.960146)
		(width 0.14478)
		(layer "In6.Cu")
		(net "M_K_CPU0_SA_CB<6>")
	)
	(segment
		(start 421.642032 -241.960146)
		(end 421.786812 -242.104926)
		(width 0.14478)
		(layer "In6.Cu")
		(net "M_K_CPU0_SA_CB<6>")
	)
	(segment
		(start 417.42614 -242.104926)
		(end 417.42614 -242.632992)
		(width 0.14478)
		(layer "In6.Cu")
		(net "M_K_CPU0_SA_CB<6>")
	)
	(segment
		(start 390.264904 -248.534174)
		(end 390.418828 -248.268744)
		(width 0.0889)
		(layer "In6.Cu")
		(net "M_K_CPU0_SA_CB<6>")
	)
	(segment
		(start 442.119258 -241.110008)
		(end 442.5442 -241.53495)
		(width 0.14478)
		(layer "In6.Cu")
		(net "M_K_CPU0_SA_CB<6>")
	)
	(segment
		(start 417.42614 -242.632992)
		(end 417.57092 -242.777772)
		(width 0.14478)
		(layer "In6.Cu")
		(net "M_K_CPU0_SA_CB<6>")
	)
	(segment
		(start 417.977574 -242.104926)
		(end 418.122354 -241.960146)
		(width 0.14478)
		(layer "In6.Cu")
		(net "M_K_CPU0_SA_CB<6>")
	)
	(segment
		(start 423.585894 -241.960146)
		(end 436.741316 -241.960146)
		(width 0.14478)
		(layer "In6.Cu")
		(net "M_K_CPU0_SA_CB<6>")
	)
	(segment
		(start 421.786812 -242.879372)
		(end 421.931592 -243.024152)
		(width 0.14478)
		(layer "In6.Cu")
		(net "M_K_CPU0_SA_CB<6>")
	)
	(segment
		(start 418.529008 -242.104926)
		(end 418.529008 -242.632992)
		(width 0.14478)
		(layer "In6.Cu")
		(net "M_K_CPU0_SA_CB<6>")
	)
	(segment
		(start 419.080442 -242.632992)
		(end 419.080442 -242.104926)
		(width 0.14478)
		(layer "In6.Cu")
		(net "M_K_CPU0_SA_CB<6>")
	)
	(segment
		(start 393.6619 -248.273824)
		(end 394.210286 -248.82221)
		(width 0.0889)
		(layer "In6.Cu")
		(net "M_K_CPU0_SA_CB<6>")
	)
	(segment
		(start 392.331448 -248.211594)
		(end 392.341862 -248.21769)
		(width 0.0889)
		(layer "In6.Cu")
		(net "M_K_CPU0_SA_CB<6>")
	)
	(segment
		(start 419.080442 -242.104926)
		(end 419.225222 -241.960146)
		(width 0.14478)
		(layer "In6.Cu")
		(net "M_K_CPU0_SA_CB<6>")
	)
	(segment
		(start 420.539164 -241.960146)
		(end 420.683944 -242.104926)
		(width 0.14478)
		(layer "In6.Cu")
		(net "M_K_CPU0_SA_CB<6>")
	)
	(segment
		(start 391.01776 -248.211594)
		(end 391.026142 -248.206768)
		(width 0.0889)
		(layer "In6.Cu")
		(net "M_K_CPU0_SA_CB<6>")
	)
	(segment
		(start 396.433294 -248.82221)
		(end 397.084804 -248.1707)
		(width 0.14478)
		(layer "In6.Cu")
		(net "M_K_CPU0_SA_CB<6>")
	)
	(segment
		(start 391.947146 -248.21769)
		(end 391.95756 -248.211594)
		(width 0.0889)
		(layer "In6.Cu")
		(net "M_K_CPU0_SA_CB<6>")
	)
	(segment
		(start 418.384228 -241.960146)
		(end 418.529008 -242.104926)
		(width 0.14478)
		(layer "In6.Cu")
		(net "M_K_CPU0_SA_CB<6>")
	)
	(segment
		(start 422.88968 -242.104926)
		(end 422.88968 -242.879372)
		(width 0.14478)
		(layer "In6.Cu")
		(net "M_K_CPU0_SA_CB<6>")
	)
	(segment
		(start 421.235378 -242.104926)
		(end 421.380158 -241.960146)
		(width 0.14478)
		(layer "In6.Cu")
		(net "M_K_CPU0_SA_CB<6>")
	)
	(segment
		(start 421.786812 -242.104926)
		(end 421.786812 -242.879372)
		(width 0.14478)
		(layer "In6.Cu")
		(net "M_K_CPU0_SA_CB<6>")
	)
	(segment
		(start 422.338246 -242.104926)
		(end 422.483026 -241.960146)
		(width 0.14478)
		(layer "In6.Cu")
		(net "M_K_CPU0_SA_CB<6>")
	)
	(segment
		(start 423.296334 -243.024152)
		(end 423.441114 -242.879372)
		(width 0.14478)
		(layer "In6.Cu")
		(net "M_K_CPU0_SA_CB<6>")
	)
	(segment
		(start 423.03446 -243.024152)
		(end 423.296334 -243.024152)
		(width 0.14478)
		(layer "In6.Cu")
		(net "M_K_CPU0_SA_CB<6>")
	)
	(segment
		(start 423.441114 -242.104926)
		(end 423.585894 -241.960146)
		(width 0.14478)
		(layer "In6.Cu")
		(net "M_K_CPU0_SA_CB<6>")
	)
	(segment
		(start 417.977574 -242.632992)
		(end 417.977574 -242.104926)
		(width 0.14478)
		(layer "In6.Cu")
		(net "M_K_CPU0_SA_CB<6>")
	)
	(segment
		(start 422.7449 -241.960146)
		(end 422.88968 -242.104926)
		(width 0.14478)
		(layer "In6.Cu")
		(net "M_K_CPU0_SA_CB<6>")
	)
	(segment
		(start 417.28136 -241.960146)
		(end 417.42614 -242.104926)
		(width 0.14478)
		(layer "In6.Cu")
		(net "M_K_CPU0_SA_CB<6>")
	)
	(segment
		(start 420.828724 -243.024152)
		(end 421.090598 -243.024152)
		(width 0.14478)
		(layer "In6.Cu")
		(net "M_K_CPU0_SA_CB<6>")
	)
	(segment
		(start 414.619694 -242.81003)
		(end 415.469578 -241.960146)
		(width 0.14478)
		(layer "In6.Cu")
		(net "M_K_CPU0_SA_CB<6>")
	)
	(segment
		(start 393.530074 -248.273824)
		(end 393.6619 -248.273824)
		(width 0.0889)
		(layer "In6.Cu")
		(net "M_K_CPU0_SA_CB<6>")
	)
	(segment
		(start 418.122354 -241.960146)
		(end 418.384228 -241.960146)
		(width 0.14478)
		(layer "In6.Cu")
		(net "M_K_CPU0_SA_CB<6>")
	)
	(segment
		(start 419.225222 -241.960146)
		(end 420.539164 -241.960146)
		(width 0.14478)
		(layer "In6.Cu")
		(net "M_K_CPU0_SA_CB<6>")
	)
	(segment
		(start 418.673788 -242.777772)
		(end 418.935662 -242.777772)
		(width 0.14478)
		(layer "In6.Cu")
		(net "M_K_CPU0_SA_CB<6>")
	)
	(segment
		(start 420.683944 -242.104926)
		(end 420.683944 -242.879372)
		(width 0.14478)
		(layer "In6.Cu")
		(net "M_K_CPU0_SA_CB<6>")
	)
	(arc
		(start 391.026142 -248.206768)
		(mid 391.20965 -248.161274)
		(end 391.391902 -248.211594)
		(width 0.0889)
		(layer "In6.Cu")
		(net "M_K_CPU0_SA_CB<6>")
	)
	(arc
		(start 392.897614 -248.211594)
		(mid 393.077819 -248.161277)
		(end 393.259818 -248.204736)
		(width 0.0889)
		(layer "In6.Cu")
		(net "M_K_CPU0_SA_CB<6>")
	)
	(arc
		(start 391.95756 -248.211594)
		(mid 392.144504 -248.161339)
		(end 392.331448 -248.211594)
		(width 0.0889)
		(layer "In6.Cu")
		(net "M_K_CPU0_SA_CB<6>")
	)
	(arc
		(start 390.51484 -248.243344)
		(mid 390.770048 -248.286821)
		(end 391.01776 -248.211594)
		(width 0.0889)
		(layer "In6.Cu")
		(net "M_K_CPU0_SA_CB<6>")
	)
	(arc
		(start 393.259818 -248.204736)
		(mid 393.390608 -248.256247)
		(end 393.530074 -248.273824)
		(width 0.0889)
		(layer "In6.Cu")
		(net "M_K_CPU0_SA_CB<6>")
	)
	(arc
		(start 392.341862 -248.21769)
		(mid 392.620548 -248.28791)
		(end 392.897614 -248.211594)
		(width 0.0889)
		(layer "In6.Cu")
		(net "M_K_CPU0_SA_CB<6>")
	)
	(arc
		(start 391.391902 -248.211594)
		(mid 391.668715 -248.287737)
		(end 391.947146 -248.21769)
		(width 0.0889)
		(layer "In6.Cu")
		(net "M_K_CPU0_SA_CB<6>")
	)
	(segment
		(start 388.857998 -248.800112)
		(end 389.32485 -248.534174)
		(width 0.10668)
		(layer "F.Cu")
		(net "M_K_CPU0_SA_CB<5>")
	)
	(segment
		(start 391.01776 -248.856754)
		(end 391.026142 -248.86158)
		(width 0.0889)
		(layer "In6.Cu")
		(net "M_K_CPU0_SA_CB<5>")
	)
	(segment
		(start 445.45885 -242.104926)
		(end 445.60363 -241.960146)
		(width 0.14478)
		(layer "In6.Cu")
		(net "M_K_CPU0_SA_CB<5>")
	)
	(segment
		(start 389.32485 -248.534174)
		(end 389.170926 -248.799604)
		(width 0.0889)
		(layer "In6.Cu")
		(net "M_K_CPU0_SA_CB<5>")
	)
	(segment
		(start 389.170926 -248.799604)
		(end 389.193278 -248.882916)
		(width 0.0889)
		(layer "In6.Cu")
		(net "M_K_CPU0_SA_CB<5>")
	)
	(segment
		(start 436.741316 -242.81003)
		(end 437.5912 -241.960146)
		(width 0.14478)
		(layer "In6.Cu")
		(net "M_K_CPU0_SA_CB<5>")
	)
	(segment
		(start 444.355982 -242.566952)
		(end 444.355982 -242.104926)
		(width 0.14478)
		(layer "In6.Cu")
		(net "M_K_CPU0_SA_CB<5>")
	)
	(segment
		(start 444.907416 -242.566952)
		(end 445.052196 -242.711732)
		(width 0.14478)
		(layer "In6.Cu")
		(net "M_K_CPU0_SA_CB<5>")
	)
	(segment
		(start 444.907416 -242.104926)
		(end 444.907416 -242.566952)
		(width 0.14478)
		(layer "In6.Cu")
		(net "M_K_CPU0_SA_CB<5>")
	)
	(segment
		(start 390.443466 -248.86158)
		(end 390.451848 -248.856754)
		(width 0.0889)
		(layer "In6.Cu")
		(net "M_K_CPU0_SA_CB<5>")
	)
	(segment
		(start 395.492224 -249.251978)
		(end 395.555216 -249.31497)
		(width 0.0889)
		(layer "In6.Cu")
		(net "M_K_CPU0_SA_CB<5>")
	)
	(segment
		(start 391.95756 -248.856754)
		(end 391.965942 -248.86158)
		(width 0.0889)
		(layer "In6.Cu")
		(net "M_K_CPU0_SA_CB<5>")
	)
	(segment
		(start 444.500762 -241.960146)
		(end 444.762636 -241.960146)
		(width 0.14478)
		(layer "In6.Cu")
		(net "M_K_CPU0_SA_CB<5>")
	)
	(segment
		(start 443.949328 -242.711732)
		(end 444.211202 -242.711732)
		(width 0.14478)
		(layer "In6.Cu")
		(net "M_K_CPU0_SA_CB<5>")
	)
	(segment
		(start 395.555216 -249.31497)
		(end 395.851126 -249.31497)
		(width 0.0889)
		(layer "In6.Cu")
		(net "M_K_CPU0_SA_CB<5>")
	)
	(segment
		(start 445.31407 -242.711732)
		(end 445.45885 -242.566952)
		(width 0.14478)
		(layer "In6.Cu")
		(net "M_K_CPU0_SA_CB<5>")
	)
	(segment
		(start 406.401778 -248.62536)
		(end 411.36697 -243.660168)
		(width 0.14478)
		(layer "In6.Cu")
		(net "M_K_CPU0_SA_CB<5>")
	)
	(segment
		(start 445.45885 -242.566952)
		(end 445.45885 -242.104926)
		(width 0.14478)
		(layer "In6.Cu")
		(net "M_K_CPU0_SA_CB<5>")
	)
	(segment
		(start 392.331194 -248.856754)
		(end 392.341608 -248.850658)
		(width 0.0889)
		(layer "In6.Cu")
		(net "M_K_CPU0_SA_CB<5>")
	)
	(segment
		(start 392.89736 -248.856754)
		(end 393.59586 -249.251978)
		(width 0.0889)
		(layer "In6.Cu")
		(net "M_K_CPU0_SA_CB<5>")
	)
	(segment
		(start 443.804548 -242.566952)
		(end 443.949328 -242.711732)
		(width 0.14478)
		(layer "In6.Cu")
		(net "M_K_CPU0_SA_CB<5>")
	)
	(segment
		(start 397.346678 -248.62536)
		(end 406.401778 -248.62536)
		(width 0.14478)
		(layer "In6.Cu")
		(net "M_K_CPU0_SA_CB<5>")
	)
	(segment
		(start 444.211202 -242.711732)
		(end 444.355982 -242.566952)
		(width 0.14478)
		(layer "In6.Cu")
		(net "M_K_CPU0_SA_CB<5>")
	)
	(segment
		(start 446.219326 -241.960146)
		(end 446.644268 -242.385088)
		(width 0.14478)
		(layer "In6.Cu")
		(net "M_K_CPU0_SA_CB<5>")
	)
	(segment
		(start 395.851126 -249.31497)
		(end 396.657068 -249.31497)
		(width 0.14478)
		(layer "In6.Cu")
		(net "M_K_CPU0_SA_CB<5>")
	)
	(segment
		(start 393.59586 -249.251978)
		(end 395.492224 -249.251978)
		(width 0.0889)
		(layer "In6.Cu")
		(net "M_K_CPU0_SA_CB<5>")
	)
	(segment
		(start 444.762636 -241.960146)
		(end 444.907416 -242.104926)
		(width 0.14478)
		(layer "In6.Cu")
		(net "M_K_CPU0_SA_CB<5>")
	)
	(segment
		(start 445.052196 -242.711732)
		(end 445.31407 -242.711732)
		(width 0.14478)
		(layer "In6.Cu")
		(net "M_K_CPU0_SA_CB<5>")
	)
	(segment
		(start 445.60363 -241.960146)
		(end 446.219326 -241.960146)
		(width 0.14478)
		(layer "In6.Cu")
		(net "M_K_CPU0_SA_CB<5>")
	)
	(segment
		(start 396.657068 -249.31497)
		(end 397.346678 -248.62536)
		(width 0.14478)
		(layer "In6.Cu")
		(net "M_K_CPU0_SA_CB<5>")
	)
	(segment
		(start 437.5912 -241.960146)
		(end 443.659768 -241.960146)
		(width 0.14478)
		(layer "In6.Cu")
		(net "M_K_CPU0_SA_CB<5>")
	)
	(segment
		(start 443.804548 -242.104926)
		(end 443.804548 -242.566952)
		(width 0.14478)
		(layer "In6.Cu")
		(net "M_K_CPU0_SA_CB<5>")
	)
	(segment
		(start 411.36697 -243.660168)
		(end 425.75607 -243.660168)
		(width 0.14478)
		(layer "In6.Cu")
		(net "M_K_CPU0_SA_CB<5>")
	)
	(segment
		(start 391.947146 -248.850658)
		(end 391.95756 -248.856754)
		(width 0.0889)
		(layer "In6.Cu")
		(net "M_K_CPU0_SA_CB<5>")
	)
	(segment
		(start 425.75607 -243.660168)
		(end 426.606208 -242.81003)
		(width 0.14478)
		(layer "In6.Cu")
		(net "M_K_CPU0_SA_CB<5>")
	)
	(segment
		(start 444.355982 -242.104926)
		(end 444.500762 -241.960146)
		(width 0.14478)
		(layer "In6.Cu")
		(net "M_K_CPU0_SA_CB<5>")
	)
	(segment
		(start 426.606208 -242.81003)
		(end 436.741316 -242.81003)
		(width 0.14478)
		(layer "In6.Cu")
		(net "M_K_CPU0_SA_CB<5>")
	)
	(segment
		(start 443.659768 -241.960146)
		(end 443.804548 -242.104926)
		(width 0.14478)
		(layer "In6.Cu")
		(net "M_K_CPU0_SA_CB<5>")
	)
	(arc
		(start 390.451848 -248.856754)
		(mid 390.734804 -248.780577)
		(end 391.01776 -248.856754)
		(width 0.0889)
		(layer "In6.Cu")
		(net "M_K_CPU0_SA_CB<5>")
	)
	(arc
		(start 391.965942 -248.86158)
		(mid 392.149196 -248.906953)
		(end 392.331194 -248.856754)
		(width 0.0889)
		(layer "In6.Cu")
		(net "M_K_CPU0_SA_CB<5>")
	)
	(arc
		(start 389.193278 -248.882916)
		(mid 389.355467 -248.905651)
		(end 389.511794 -248.856754)
		(width 0.0889)
		(layer "In6.Cu")
		(net "M_K_CPU0_SA_CB<5>")
	)
	(arc
		(start 392.341608 -248.850658)
		(mid 392.620294 -248.780438)
		(end 392.89736 -248.856754)
		(width 0.0889)
		(layer "In6.Cu")
		(net "M_K_CPU0_SA_CB<5>")
	)
	(arc
		(start 390.077706 -248.856754)
		(mid 390.259957 -248.907104)
		(end 390.443466 -248.86158)
		(width 0.0889)
		(layer "In6.Cu")
		(net "M_K_CPU0_SA_CB<5>")
	)
	(arc
		(start 391.391902 -248.856754)
		(mid 391.668715 -248.780611)
		(end 391.947146 -248.850658)
		(width 0.0889)
		(layer "In6.Cu")
		(net "M_K_CPU0_SA_CB<5>")
	)
	(arc
		(start 391.026142 -248.86158)
		(mid 391.20965 -248.907074)
		(end 391.391902 -248.856754)
		(width 0.0889)
		(layer "In6.Cu")
		(net "M_K_CPU0_SA_CB<5>")
	)
	(arc
		(start 389.511794 -248.856754)
		(mid 389.79475 -248.780577)
		(end 390.077706 -248.856754)
		(width 0.0889)
		(layer "In6.Cu")
		(net "M_K_CPU0_SA_CB<5>")
	)
	(segment
		(start 390.267952 -247.990106)
		(end 390.734804 -247.724168)
		(width 0.10668)
		(layer "F.Cu")
		(net "M_K_CPU0_SA_CB<4>")
	)
	(segment
		(start 436.731918 -241.119406)
		(end 437.581802 -240.269522)
		(width 0.14478)
		(layer "In6.Cu")
		(net "M_K_CPU0_SA_CB<4>")
	)
	(segment
		(start 396.235174 -248.35739)
		(end 396.876524 -247.71604)
		(width 0.14478)
		(layer "In6.Cu")
		(net "M_K_CPU0_SA_CB<4>")
	)
	(segment
		(start 412.010098 -241.355372)
		(end 412.271972 -241.355372)
		(width 0.14478)
		(layer "In6.Cu")
		(net "M_K_CPU0_SA_CB<4>")
	)
	(segment
		(start 412.561532 -241.960146)
		(end 412.823406 -241.960146)
		(width 0.14478)
		(layer "In6.Cu")
		(net "M_K_CPU0_SA_CB<4>")
	)
	(segment
		(start 445.26073 -241.180112)
		(end 445.522604 -241.180112)
		(width 0.14478)
		(layer "In6.Cu")
		(net "M_K_CPU0_SA_CB<4>")
	)
	(segment
		(start 437.581802 -240.269522)
		(end 444.97117 -240.269522)
		(width 0.14478)
		(layer "In6.Cu")
		(net "M_K_CPU0_SA_CB<4>")
	)
	(segment
		(start 394.032994 -248.35739)
		(end 395.787118 -248.35739)
		(width 0.0889)
		(layer "In6.Cu")
		(net "M_K_CPU0_SA_CB<4>")
	)
	(segment
		(start 393.530328 -248.083324)
		(end 393.758928 -248.083324)
		(width 0.0889)
		(layer "In6.Cu")
		(net "M_K_CPU0_SA_CB<4>")
	)
	(segment
		(start 412.416752 -241.815366)
		(end 412.561532 -241.960146)
		(width 0.14478)
		(layer "In6.Cu")
		(net "M_K_CPU0_SA_CB<4>")
	)
	(segment
		(start 391.861802 -248.046748)
		(end 391.872216 -248.040652)
		(width 0.0889)
		(layer "In6.Cu")
		(net "M_K_CPU0_SA_CB<4>")
	)
	(segment
		(start 411.865318 -241.815366)
		(end 411.865318 -241.500152)
		(width 0.14478)
		(layer "In6.Cu")
		(net "M_K_CPU0_SA_CB<4>")
	)
	(segment
		(start 413.6644 -241.960146)
		(end 413.943292 -241.960146)
		(width 0.14478)
		(layer "In6.Cu")
		(net "M_K_CPU0_SA_CB<4>")
	)
	(segment
		(start 413.51962 -241.815366)
		(end 413.6644 -241.960146)
		(width 0.14478)
		(layer "In6.Cu")
		(net "M_K_CPU0_SA_CB<4>")
	)
	(segment
		(start 411.865318 -241.500152)
		(end 412.010098 -241.355372)
		(width 0.14478)
		(layer "In6.Cu")
		(net "M_K_CPU0_SA_CB<4>")
	)
	(segment
		(start 412.968186 -241.500152)
		(end 413.112966 -241.355372)
		(width 0.14478)
		(layer "In6.Cu")
		(net "M_K_CPU0_SA_CB<4>")
	)
	(segment
		(start 390.734804 -247.724168)
		(end 390.58088 -247.989598)
		(width 0.0889)
		(layer "In6.Cu")
		(net "M_K_CPU0_SA_CB<4>")
	)
	(segment
		(start 393.758928 -248.083324)
		(end 394.032994 -248.35739)
		(width 0.0889)
		(layer "In6.Cu")
		(net "M_K_CPU0_SA_CB<4>")
	)
	(segment
		(start 413.943292 -241.960146)
		(end 414.784032 -241.119406)
		(width 0.14478)
		(layer "In6.Cu")
		(net "M_K_CPU0_SA_CB<4>")
	)
	(segment
		(start 390.58088 -247.989598)
		(end 390.603232 -248.07291)
		(width 0.0889)
		(layer "In6.Cu")
		(net "M_K_CPU0_SA_CB<4>")
	)
	(segment
		(start 411.502098 -241.960146)
		(end 411.720538 -241.960146)
		(width 0.14478)
		(layer "In6.Cu")
		(net "M_K_CPU0_SA_CB<4>")
	)
	(segment
		(start 444.97117 -240.269522)
		(end 445.11595 -240.414302)
		(width 0.14478)
		(layer "In6.Cu")
		(net "M_K_CPU0_SA_CB<4>")
	)
	(segment
		(start 445.667384 -241.035332)
		(end 445.667384 -240.414302)
		(width 0.14478)
		(layer "In6.Cu")
		(net "M_K_CPU0_SA_CB<4>")
	)
	(segment
		(start 405.746204 -247.71604)
		(end 411.502098 -241.960146)
		(width 0.14478)
		(layer "In6.Cu")
		(net "M_K_CPU0_SA_CB<4>")
	)
	(segment
		(start 413.112966 -241.355372)
		(end 413.37484 -241.355372)
		(width 0.14478)
		(layer "In6.Cu")
		(net "M_K_CPU0_SA_CB<4>")
	)
	(segment
		(start 395.787118 -248.35739)
		(end 396.235174 -248.35739)
		(width 0.14478)
		(layer "In6.Cu")
		(net "M_K_CPU0_SA_CB<4>")
	)
	(segment
		(start 413.37484 -241.355372)
		(end 413.51962 -241.500152)
		(width 0.14478)
		(layer "In6.Cu")
		(net "M_K_CPU0_SA_CB<4>")
	)
	(segment
		(start 396.876524 -247.71604)
		(end 405.746204 -247.71604)
		(width 0.14478)
		(layer "In6.Cu")
		(net "M_K_CPU0_SA_CB<4>")
	)
	(segment
		(start 414.784032 -241.119406)
		(end 436.731918 -241.119406)
		(width 0.14478)
		(layer "In6.Cu")
		(net "M_K_CPU0_SA_CB<4>")
	)
	(segment
		(start 445.522604 -241.180112)
		(end 445.667384 -241.035332)
		(width 0.14478)
		(layer "In6.Cu")
		(net "M_K_CPU0_SA_CB<4>")
	)
	(segment
		(start 445.812164 -240.269522)
		(end 446.228724 -240.269522)
		(width 0.14478)
		(layer "In6.Cu")
		(net "M_K_CPU0_SA_CB<4>")
	)
	(segment
		(start 445.667384 -240.414302)
		(end 445.812164 -240.269522)
		(width 0.14478)
		(layer "In6.Cu")
		(net "M_K_CPU0_SA_CB<4>")
	)
	(segment
		(start 412.271972 -241.355372)
		(end 412.416752 -241.500152)
		(width 0.14478)
		(layer "In6.Cu")
		(net "M_K_CPU0_SA_CB<4>")
	)
	(segment
		(start 411.720538 -241.960146)
		(end 411.865318 -241.815366)
		(width 0.14478)
		(layer "In6.Cu")
		(net "M_K_CPU0_SA_CB<4>")
	)
	(segment
		(start 445.11595 -240.414302)
		(end 445.11595 -241.035332)
		(width 0.14478)
		(layer "In6.Cu")
		(net "M_K_CPU0_SA_CB<4>")
	)
	(segment
		(start 391.85342 -248.051574)
		(end 391.861802 -248.046748)
		(width 0.0889)
		(layer "In6.Cu")
		(net "M_K_CPU0_SA_CB<4>")
	)
	(segment
		(start 412.823406 -241.960146)
		(end 412.968186 -241.815366)
		(width 0.14478)
		(layer "In6.Cu")
		(net "M_K_CPU0_SA_CB<4>")
	)
	(segment
		(start 413.51962 -241.500152)
		(end 413.51962 -241.815366)
		(width 0.14478)
		(layer "In6.Cu")
		(net "M_K_CPU0_SA_CB<4>")
	)
	(segment
		(start 412.968186 -241.815366)
		(end 412.968186 -241.500152)
		(width 0.14478)
		(layer "In6.Cu")
		(net "M_K_CPU0_SA_CB<4>")
	)
	(segment
		(start 392.42746 -248.046748)
		(end 392.435842 -248.051574)
		(width 0.0889)
		(layer "In6.Cu")
		(net "M_K_CPU0_SA_CB<4>")
	)
	(segment
		(start 412.416752 -241.500152)
		(end 412.416752 -241.815366)
		(width 0.14478)
		(layer "In6.Cu")
		(net "M_K_CPU0_SA_CB<4>")
	)
	(segment
		(start 446.228724 -240.269522)
		(end 446.644268 -240.685066)
		(width 0.14478)
		(layer "In6.Cu")
		(net "M_K_CPU0_SA_CB<4>")
	)
	(segment
		(start 445.11595 -241.035332)
		(end 445.26073 -241.180112)
		(width 0.14478)
		(layer "In6.Cu")
		(net "M_K_CPU0_SA_CB<4>")
	)
	(arc
		(start 392.435842 -248.051574)
		(mid 392.61935 -248.097068)
		(end 392.801602 -248.046748)
		(width 0.0889)
		(layer "In6.Cu")
		(net "M_K_CPU0_SA_CB<4>")
	)
	(arc
		(start 390.603232 -248.07291)
		(mid 390.765421 -248.095645)
		(end 390.921748 -248.046748)
		(width 0.0889)
		(layer "In6.Cu")
		(net "M_K_CPU0_SA_CB<4>")
	)
	(arc
		(start 392.801602 -248.046748)
		(mid 393.076054 -247.970512)
		(end 393.352782 -248.038112)
		(width 0.0889)
		(layer "In6.Cu")
		(net "M_K_CPU0_SA_CB<4>")
	)
	(arc
		(start 391.872216 -248.040652)
		(mid 392.150648 -247.970554)
		(end 392.42746 -248.046748)
		(width 0.0889)
		(layer "In6.Cu")
		(net "M_K_CPU0_SA_CB<4>")
	)
	(arc
		(start 391.48766 -248.046748)
		(mid 391.669911 -248.097098)
		(end 391.85342 -248.051574)
		(width 0.0889)
		(layer "In6.Cu")
		(net "M_K_CPU0_SA_CB<4>")
	)
	(arc
		(start 390.921748 -248.046748)
		(mid 391.204704 -247.970571)
		(end 391.48766 -248.046748)
		(width 0.0889)
		(layer "In6.Cu")
		(net "M_K_CPU0_SA_CB<4>")
	)
	(arc
		(start 393.352782 -248.038112)
		(mid 393.43874 -248.071767)
		(end 393.530328 -248.083324)
		(width 0.0889)
		(layer "In6.Cu")
		(net "M_K_CPU0_SA_CB<4>")
	)
	(segment
		(start 388.387844 -246.370094)
		(end 388.85495 -246.104156)
		(width 0.10668)
		(layer "F.Cu")
		(net "M_K_CPU0_SA_CB<3>")
	)
	(segment
		(start 392.801602 -245.781576)
		(end 392.81354 -245.793514)
		(width 0.0889)
		(layer "In6.Cu")
		(net "M_K_CPU0_SA_CB<3>")
	)
	(segment
		(start 438.40146 -236.623352)
		(end 438.40146 -236.705902)
		(width 0.14478)
		(layer "In6.Cu")
		(net "M_K_CPU0_SA_CB<3>")
	)
	(segment
		(start 436.339742 -237.710218)
		(end 436.6133 -237.710218)
		(width 0.14478)
		(layer "In6.Cu")
		(net "M_K_CPU0_SA_CB<3>")
	)
	(segment
		(start 423.041318 -236.46765)
		(end 423.271696 -236.46765)
		(width 0.14478)
		(layer "In6.Cu")
		(net "M_K_CPU0_SA_CB<3>")
	)
	(segment
		(start 430.886362 -236.630718)
		(end 430.886362 -236.697012)
		(width 0.14478)
		(layer "In6.Cu")
		(net "M_K_CPU0_SA_CB<3>")
	)
	(segment
		(start 428.394622 -237.32871)
		(end 428.55769 -237.491778)
		(width 0.14478)
		(layer "In6.Cu")
		(net "M_K_CPU0_SA_CB<3>")
	)
	(segment
		(start 388.85495 -246.104156)
		(end 389.008874 -245.838726)
		(width 0.0889)
		(layer "In6.Cu")
		(net "M_K_CPU0_SA_CB<3>")
	)
	(segment
		(start 420.913306 -237.32363)
		(end 421.076374 -237.486698)
		(width 0.14478)
		(layer "In6.Cu")
		(net "M_K_CPU0_SA_CB<3>")
	)
	(segment
		(start 422.87825 -236.630718)
		(end 423.041318 -236.46765)
		(width 0.14478)
		(layer "In6.Cu")
		(net "M_K_CPU0_SA_CB<3>")
	)
	(segment
		(start 414.006792 -237.710218)
		(end 414.866328 -236.850682)
		(width 0.14478)
		(layer "In6.Cu")
		(net "M_K_CPU0_SA_CB<3>")
	)
	(segment
		(start 391.85342 -245.77675)
		(end 391.861802 -245.781576)
		(width 0.0889)
		(layer "In6.Cu")
		(net "M_K_CPU0_SA_CB<3>")
	)
	(segment
		(start 440.943492 -236.86008)
		(end 441.10656 -237.023148)
		(width 0.14478)
		(layer "In6.Cu")
		(net "M_K_CPU0_SA_CB<3>")
	)
	(segment
		(start 441.663074 -237.245144)
		(end 441.663074 -237.023148)
		(width 0.14478)
		(layer "In6.Cu")
		(net "M_K_CPU0_SA_CB<3>")
	)
	(segment
		(start 421.549322 -237.710218)
		(end 422.39946 -236.86008)
		(width 0.14478)
		(layer "In6.Cu")
		(net "M_K_CPU0_SA_CB<3>")
	)
	(segment
		(start 389.008874 -245.838726)
		(end 389.104886 -245.813326)
		(width 0.0889)
		(layer "In6.Cu")
		(net "M_K_CPU0_SA_CB<3>")
	)
	(segment
		(start 395.840966 -245.36019)
		(end 404.495 -245.36019)
		(width 0.14478)
		(layer "In6.Cu")
		(net "M_K_CPU0_SA_CB<3>")
	)
	(segment
		(start 436.6133 -237.710218)
		(end 437.472836 -236.850682)
		(width 0.14478)
		(layer "In6.Cu")
		(net "M_K_CPU0_SA_CB<3>")
	)
	(segment
		(start 423.434764 -236.697012)
		(end 423.588434 -236.850682)
		(width 0.14478)
		(layer "In6.Cu")
		(net "M_K_CPU0_SA_CB<3>")
	)
	(segment
		(start 430.16678 -236.86008)
		(end 430.329848 -236.697012)
		(width 0.14478)
		(layer "In6.Cu")
		(net "M_K_CPU0_SA_CB<3>")
	)
	(segment
		(start 389.607806 -245.781576)
		(end 389.616188 -245.77675)
		(width 0.0889)
		(layer "In6.Cu")
		(net "M_K_CPU0_SA_CB<3>")
	)
	(segment
		(start 429.931068 -236.86008)
		(end 430.16678 -236.86008)
		(width 0.14478)
		(layer "In6.Cu")
		(net "M_K_CPU0_SA_CB<3>")
	)
	(segment
		(start 437.994806 -236.478572)
		(end 438.25668 -236.478572)
		(width 0.14478)
		(layer "In6.Cu")
		(net "M_K_CPU0_SA_CB<3>")
	)
	(segment
		(start 435.62016 -237.479078)
		(end 435.783228 -237.31601)
		(width 0.14478)
		(layer "In6.Cu")
		(net "M_K_CPU0_SA_CB<3>")
	)
	(segment
		(start 440.475624 -236.697012)
		(end 440.638692 -236.86008)
		(width 0.14478)
		(layer "In6.Cu")
		(net "M_K_CPU0_SA_CB<3>")
	)
	(segment
		(start 439.76544 -236.850682)
		(end 439.91911 -236.697012)
		(width 0.14478)
		(layer "In6.Cu")
		(net "M_K_CPU0_SA_CB<3>")
	)
	(segment
		(start 437.850026 -236.623352)
		(end 437.994806 -236.478572)
		(width 0.14478)
		(layer "In6.Cu")
		(net "M_K_CPU0_SA_CB<3>")
	)
	(segment
		(start 439.91911 -236.697012)
		(end 439.91911 -236.630718)
		(width 0.14478)
		(layer "In6.Cu")
		(net "M_K_CPU0_SA_CB<3>")
	)
	(segment
		(start 441.500006 -237.408212)
		(end 441.663074 -237.245144)
		(width 0.14478)
		(layer "In6.Cu")
		(net "M_K_CPU0_SA_CB<3>")
	)
	(segment
		(start 404.495 -245.36019)
		(end 412.144972 -237.710218)
		(width 0.14478)
		(layer "In6.Cu")
		(net "M_K_CPU0_SA_CB<3>")
	)
	(segment
		(start 421.076374 -237.54715)
		(end 421.239442 -237.710218)
		(width 0.14478)
		(layer "In6.Cu")
		(net "M_K_CPU0_SA_CB<3>")
	)
	(segment
		(start 428.164244 -237.32871)
		(end 428.394622 -237.32871)
		(width 0.14478)
		(layer "In6.Cu")
		(net "M_K_CPU0_SA_CB<3>")
	)
	(segment
		(start 421.076374 -237.486698)
		(end 421.076374 -237.54715)
		(width 0.14478)
		(layer "In6.Cu")
		(net "M_K_CPU0_SA_CB<3>")
	)
	(segment
		(start 430.886362 -236.697012)
		(end 431.040032 -236.850682)
		(width 0.14478)
		(layer "In6.Cu")
		(net "M_K_CPU0_SA_CB<3>")
	)
	(segment
		(start 432.92649 -236.850682)
		(end 433.776628 -237.70082)
		(width 0.14478)
		(layer "In6.Cu")
		(net "M_K_CPU0_SA_CB<3>")
	)
	(segment
		(start 441.663074 -237.023148)
		(end 441.826142 -236.86008)
		(width 0.14478)
		(layer "In6.Cu")
		(net "M_K_CPU0_SA_CB<3>")
	)
	(segment
		(start 436.176674 -237.54715)
		(end 436.339742 -237.710218)
		(width 0.14478)
		(layer "In6.Cu")
		(net "M_K_CPU0_SA_CB<3>")
	)
	(segment
		(start 438.54624 -236.850682)
		(end 439.76544 -236.850682)
		(width 0.14478)
		(layer "In6.Cu")
		(net "M_K_CPU0_SA_CB<3>")
	)
	(segment
		(start 430.492916 -236.46765)
		(end 430.723294 -236.46765)
		(width 0.14478)
		(layer "In6.Cu")
		(net "M_K_CPU0_SA_CB<3>")
	)
	(segment
		(start 412.144972 -237.710218)
		(end 414.006792 -237.710218)
		(width 0.14478)
		(layer "In6.Cu")
		(net "M_K_CPU0_SA_CB<3>")
	)
	(segment
		(start 395.669516 -245.36019)
		(end 395.840966 -245.36019)
		(width 0.0889)
		(layer "In6.Cu")
		(net "M_K_CPU0_SA_CB<3>")
	)
	(segment
		(start 414.866328 -236.850682)
		(end 417.838636 -236.850682)
		(width 0.14478)
		(layer "In6.Cu")
		(net "M_K_CPU0_SA_CB<3>")
	)
	(segment
		(start 425.38269 -236.850682)
		(end 426.232828 -237.70082)
		(width 0.14478)
		(layer "In6.Cu")
		(net "M_K_CPU0_SA_CB<3>")
	)
	(segment
		(start 392.81354 -245.793514)
		(end 392.928602 -245.841012)
		(width 0.0889)
		(layer "In6.Cu")
		(net "M_K_CPU0_SA_CB<3>")
	)
	(segment
		(start 440.475624 -236.630718)
		(end 440.475624 -236.697012)
		(width 0.14478)
		(layer "In6.Cu")
		(net "M_K_CPU0_SA_CB<3>")
	)
	(segment
		(start 429.08093 -237.710218)
		(end 429.931068 -236.86008)
		(width 0.14478)
		(layer "In6.Cu")
		(net "M_K_CPU0_SA_CB<3>")
	)
	(segment
		(start 418.688774 -237.70082)
		(end 420.36619 -237.70082)
		(width 0.14478)
		(layer "In6.Cu")
		(net "M_K_CPU0_SA_CB<3>")
	)
	(segment
		(start 438.40146 -236.705902)
		(end 438.54624 -236.850682)
		(width 0.14478)
		(layer "In6.Cu")
		(net "M_K_CPU0_SA_CB<3>")
	)
	(segment
		(start 440.312556 -236.46765)
		(end 440.475624 -236.630718)
		(width 0.14478)
		(layer "In6.Cu")
		(net "M_K_CPU0_SA_CB<3>")
	)
	(segment
		(start 433.776628 -237.70082)
		(end 435.46649 -237.70082)
		(width 0.14478)
		(layer "In6.Cu")
		(net "M_K_CPU0_SA_CB<3>")
	)
	(segment
		(start 437.472836 -236.850682)
		(end 437.705246 -236.850682)
		(width 0.14478)
		(layer "In6.Cu")
		(net "M_K_CPU0_SA_CB<3>")
	)
	(segment
		(start 392.42746 -245.781576)
		(end 392.435842 -245.77675)
		(width 0.0889)
		(layer "In6.Cu")
		(net "M_K_CPU0_SA_CB<3>")
	)
	(segment
		(start 428.001176 -237.54715)
		(end 428.001176 -237.491778)
		(width 0.14478)
		(layer "In6.Cu")
		(net "M_K_CPU0_SA_CB<3>")
	)
	(segment
		(start 423.588434 -236.850682)
		(end 425.38269 -236.850682)
		(width 0.14478)
		(layer "In6.Cu")
		(net "M_K_CPU0_SA_CB<3>")
	)
	(segment
		(start 435.62016 -237.54715)
		(end 435.62016 -237.479078)
		(width 0.14478)
		(layer "In6.Cu")
		(net "M_K_CPU0_SA_CB<3>")
	)
	(segment
		(start 395.165326 -245.86438)
		(end 395.669516 -245.36019)
		(width 0.0889)
		(layer "In6.Cu")
		(net "M_K_CPU0_SA_CB<3>")
	)
	(segment
		(start 420.682928 -237.32363)
		(end 420.913306 -237.32363)
		(width 0.14478)
		(layer "In6.Cu")
		(net "M_K_CPU0_SA_CB<3>")
	)
	(segment
		(start 423.434764 -236.630718)
		(end 423.434764 -236.697012)
		(width 0.14478)
		(layer "In6.Cu")
		(net "M_K_CPU0_SA_CB<3>")
	)
	(segment
		(start 438.25668 -236.478572)
		(end 438.40146 -236.623352)
		(width 0.14478)
		(layer "In6.Cu")
		(net "M_K_CPU0_SA_CB<3>")
	)
	(segment
		(start 422.87825 -236.697012)
		(end 422.87825 -236.630718)
		(width 0.14478)
		(layer "In6.Cu")
		(net "M_K_CPU0_SA_CB<3>")
	)
	(segment
		(start 442.119258 -236.86008)
		(end 442.5442 -237.285022)
		(width 0.14478)
		(layer "In6.Cu")
		(net "M_K_CPU0_SA_CB<3>")
	)
	(segment
		(start 393.046204 -245.86438)
		(end 395.165326 -245.86438)
		(width 0.0889)
		(layer "In6.Cu")
		(net "M_K_CPU0_SA_CB<3>")
	)
	(segment
		(start 437.705246 -236.850682)
		(end 437.850026 -236.705902)
		(width 0.14478)
		(layer "In6.Cu")
		(net "M_K_CPU0_SA_CB<3>")
	)
	(segment
		(start 426.232828 -237.70082)
		(end 427.847506 -237.70082)
		(width 0.14478)
		(layer "In6.Cu")
		(net "M_K_CPU0_SA_CB<3>")
	)
	(segment
		(start 428.720758 -237.710218)
		(end 429.08093 -237.710218)
		(width 0.14478)
		(layer "In6.Cu")
		(net "M_K_CPU0_SA_CB<3>")
	)
	(segment
		(start 435.783228 -237.31601)
		(end 436.013606 -237.31601)
		(width 0.14478)
		(layer "In6.Cu")
		(net "M_K_CPU0_SA_CB<3>")
	)
	(segment
		(start 422.715182 -236.86008)
		(end 422.87825 -236.697012)
		(width 0.14478)
		(layer "In6.Cu")
		(net "M_K_CPU0_SA_CB<3>")
	)
	(segment
		(start 428.55769 -237.54715)
		(end 428.720758 -237.710218)
		(width 0.14478)
		(layer "In6.Cu")
		(net "M_K_CPU0_SA_CB<3>")
	)
	(segment
		(start 421.239442 -237.710218)
		(end 421.549322 -237.710218)
		(width 0.14478)
		(layer "In6.Cu")
		(net "M_K_CPU0_SA_CB<3>")
	)
	(segment
		(start 422.39946 -236.86008)
		(end 422.715182 -236.86008)
		(width 0.14478)
		(layer "In6.Cu")
		(net "M_K_CPU0_SA_CB<3>")
	)
	(segment
		(start 430.329848 -236.697012)
		(end 430.329848 -236.630718)
		(width 0.14478)
		(layer "In6.Cu")
		(net "M_K_CPU0_SA_CB<3>")
	)
	(segment
		(start 430.723294 -236.46765)
		(end 430.886362 -236.630718)
		(width 0.14478)
		(layer "In6.Cu")
		(net "M_K_CPU0_SA_CB<3>")
	)
	(segment
		(start 436.176674 -237.479078)
		(end 436.176674 -237.54715)
		(width 0.14478)
		(layer "In6.Cu")
		(net "M_K_CPU0_SA_CB<3>")
	)
	(segment
		(start 427.847506 -237.70082)
		(end 428.001176 -237.54715)
		(width 0.14478)
		(layer "In6.Cu")
		(net "M_K_CPU0_SA_CB<3>")
	)
	(segment
		(start 441.826142 -236.86008)
		(end 442.119258 -236.86008)
		(width 0.14478)
		(layer "In6.Cu")
		(net "M_K_CPU0_SA_CB<3>")
	)
	(segment
		(start 441.10656 -237.245144)
		(end 441.269628 -237.408212)
		(width 0.14478)
		(layer "In6.Cu")
		(net "M_K_CPU0_SA_CB<3>")
	)
	(segment
		(start 420.36619 -237.70082)
		(end 420.51986 -237.54715)
		(width 0.14478)
		(layer "In6.Cu")
		(net "M_K_CPU0_SA_CB<3>")
	)
	(segment
		(start 423.271696 -236.46765)
		(end 423.434764 -236.630718)
		(width 0.14478)
		(layer "In6.Cu")
		(net "M_K_CPU0_SA_CB<3>")
	)
	(segment
		(start 430.329848 -236.630718)
		(end 430.492916 -236.46765)
		(width 0.14478)
		(layer "In6.Cu")
		(net "M_K_CPU0_SA_CB<3>")
	)
	(segment
		(start 440.082178 -236.46765)
		(end 440.312556 -236.46765)
		(width 0.14478)
		(layer "In6.Cu")
		(net "M_K_CPU0_SA_CB<3>")
	)
	(segment
		(start 428.001176 -237.491778)
		(end 428.164244 -237.32871)
		(width 0.14478)
		(layer "In6.Cu")
		(net "M_K_CPU0_SA_CB<3>")
	)
	(segment
		(start 441.269628 -237.408212)
		(end 441.500006 -237.408212)
		(width 0.14478)
		(layer "In6.Cu")
		(net "M_K_CPU0_SA_CB<3>")
	)
	(segment
		(start 392.928602 -245.841012)
		(end 393.046204 -245.86438)
		(width 0.0889)
		(layer "In6.Cu")
		(net "M_K_CPU0_SA_CB<3>")
	)
	(segment
		(start 420.51986 -237.54715)
		(end 420.51986 -237.486698)
		(width 0.14478)
		(layer "In6.Cu")
		(net "M_K_CPU0_SA_CB<3>")
	)
	(segment
		(start 391.861802 -245.781576)
		(end 391.872216 -245.787672)
		(width 0.0889)
		(layer "In6.Cu")
		(net "M_K_CPU0_SA_CB<3>")
	)
	(segment
		(start 435.46649 -237.70082)
		(end 435.62016 -237.54715)
		(width 0.14478)
		(layer "In6.Cu")
		(net "M_K_CPU0_SA_CB<3>")
	)
	(segment
		(start 436.013606 -237.31601)
		(end 436.176674 -237.479078)
		(width 0.14478)
		(layer "In6.Cu")
		(net "M_K_CPU0_SA_CB<3>")
	)
	(segment
		(start 440.638692 -236.86008)
		(end 440.943492 -236.86008)
		(width 0.14478)
		(layer "In6.Cu")
		(net "M_K_CPU0_SA_CB<3>")
	)
	(segment
		(start 441.10656 -237.023148)
		(end 441.10656 -237.245144)
		(width 0.14478)
		(layer "In6.Cu")
		(net "M_K_CPU0_SA_CB<3>")
	)
	(segment
		(start 437.850026 -236.705902)
		(end 437.850026 -236.623352)
		(width 0.14478)
		(layer "In6.Cu")
		(net "M_K_CPU0_SA_CB<3>")
	)
	(segment
		(start 428.55769 -237.491778)
		(end 428.55769 -237.54715)
		(width 0.14478)
		(layer "In6.Cu")
		(net "M_K_CPU0_SA_CB<3>")
	)
	(segment
		(start 439.91911 -236.630718)
		(end 440.082178 -236.46765)
		(width 0.14478)
		(layer "In6.Cu")
		(net "M_K_CPU0_SA_CB<3>")
	)
	(segment
		(start 431.040032 -236.850682)
		(end 432.92649 -236.850682)
		(width 0.14478)
		(layer "In6.Cu")
		(net "M_K_CPU0_SA_CB<3>")
	)
	(segment
		(start 417.838636 -236.850682)
		(end 418.688774 -237.70082)
		(width 0.14478)
		(layer "In6.Cu")
		(net "M_K_CPU0_SA_CB<3>")
	)
	(segment
		(start 420.51986 -237.486698)
		(end 420.682928 -237.32363)
		(width 0.14478)
		(layer "In6.Cu")
		(net "M_K_CPU0_SA_CB<3>")
	)
	(arc
		(start 389.104886 -245.813326)
		(mid 389.360094 -245.856803)
		(end 389.607806 -245.781576)
		(width 0.0889)
		(layer "In6.Cu")
		(net "M_K_CPU0_SA_CB<3>")
	)
	(arc
		(start 391.872216 -245.787672)
		(mid 392.150648 -245.85777)
		(end 392.42746 -245.781576)
		(width 0.0889)
		(layer "In6.Cu")
		(net "M_K_CPU0_SA_CB<3>")
	)
	(arc
		(start 392.435842 -245.77675)
		(mid 392.61935 -245.731256)
		(end 392.801602 -245.781576)
		(width 0.0889)
		(layer "In6.Cu")
		(net "M_K_CPU0_SA_CB<3>")
	)
	(arc
		(start 389.981948 -245.781576)
		(mid 390.264904 -245.857753)
		(end 390.54786 -245.781576)
		(width 0.0889)
		(layer "In6.Cu")
		(net "M_K_CPU0_SA_CB<3>")
	)
	(arc
		(start 390.54786 -245.781576)
		(mid 390.734804 -245.731321)
		(end 390.921748 -245.781576)
		(width 0.0889)
		(layer "In6.Cu")
		(net "M_K_CPU0_SA_CB<3>")
	)
	(arc
		(start 389.616188 -245.77675)
		(mid 389.799696 -245.731256)
		(end 389.981948 -245.781576)
		(width 0.0889)
		(layer "In6.Cu")
		(net "M_K_CPU0_SA_CB<3>")
	)
	(arc
		(start 390.921748 -245.781576)
		(mid 391.204704 -245.857753)
		(end 391.48766 -245.781576)
		(width 0.0889)
		(layer "In6.Cu")
		(net "M_K_CPU0_SA_CB<3>")
	)
	(arc
		(start 391.48766 -245.781576)
		(mid 391.669911 -245.731226)
		(end 391.85342 -245.77675)
		(width 0.0889)
		(layer "In6.Cu")
		(net "M_K_CPU0_SA_CB<3>")
	)
	(segment
		(start 389.798052 -245.560088)
		(end 390.264904 -245.29415)
		(width 0.10668)
		(layer "F.Cu")
		(net "M_K_CPU0_SA_CB<2>")
	)
	(segment
		(start 435.46903 -236.010196)
		(end 435.632098 -235.847128)
		(width 0.14478)
		(layer "In6.Cu")
		(net "M_K_CPU0_SA_CB<2>")
	)
	(segment
		(start 420.762684 -235.62183)
		(end 420.925752 -235.784898)
		(width 0.14478)
		(layer "In6.Cu")
		(net "M_K_CPU0_SA_CB<2>")
	)
	(segment
		(start 440.873896 -234.777026)
		(end 441.036964 -234.940094)
		(width 0.14478)
		(layer "In6.Cu")
		(net "M_K_CPU0_SA_CB<2>")
	)
	(segment
		(start 395.611096 -244.45087)
		(end 395.875256 -244.45087)
		(width 0.0889)
		(layer "In6.Cu")
		(net "M_K_CPU0_SA_CB<2>")
	)
	(segment
		(start 416.447478 -234.941618)
		(end 416.610546 -234.77855)
		(width 0.14478)
		(layer "In6.Cu")
		(net "M_K_CPU0_SA_CB<2>")
	)
	(segment
		(start 437.69026 -235.160058)
		(end 437.853328 -234.99699)
		(width 0.14478)
		(layer "In6.Cu")
		(net "M_K_CPU0_SA_CB<2>")
	)
	(segment
		(start 416.447478 -234.99699)
		(end 416.447478 -234.941618)
		(width 0.14478)
		(layer "In6.Cu")
		(net "M_K_CPU0_SA_CB<2>")
	)
	(segment
		(start 404.118064 -244.45087)
		(end 411.895798 -236.673136)
		(width 0.14478)
		(layer "In6.Cu")
		(net "M_K_CPU0_SA_CB<2>")
	)
	(segment
		(start 429.931068 -235.160058)
		(end 430.172622 -235.160058)
		(width 0.14478)
		(layer "In6.Cu")
		(net "M_K_CPU0_SA_CB<2>")
	)
	(segment
		(start 411.895798 -236.247432)
		(end 412.133034 -236.010196)
		(width 0.14478)
		(layer "In6.Cu")
		(net "M_K_CPU0_SA_CB<2>")
	)
	(segment
		(start 440.087004 -235.54309)
		(end 440.317382 -235.54309)
		(width 0.14478)
		(layer "In6.Cu")
		(net "M_K_CPU0_SA_CB<2>")
	)
	(segment
		(start 414.006792 -236.010196)
		(end 414.85693 -235.160058)
		(width 0.14478)
		(layer "In6.Cu")
		(net "M_K_CPU0_SA_CB<2>")
	)
	(segment
		(start 431.055272 -235.160058)
		(end 432.935888 -235.160058)
		(width 0.14478)
		(layer "In6.Cu")
		(net "M_K_CPU0_SA_CB<2>")
	)
	(segment
		(start 422.39946 -235.160058)
		(end 422.679368 -235.160058)
		(width 0.14478)
		(layer "In6.Cu")
		(net "M_K_CPU0_SA_CB<2>")
	)
	(segment
		(start 440.643518 -234.777026)
		(end 440.873896 -234.777026)
		(width 0.14478)
		(layer "In6.Cu")
		(net "M_K_CPU0_SA_CB<2>")
	)
	(segment
		(start 438.57291 -235.160058)
		(end 439.760868 -235.160058)
		(width 0.14478)
		(layer "In6.Cu")
		(net "M_K_CPU0_SA_CB<2>")
	)
	(segment
		(start 428.53864 -235.789978)
		(end 428.53864 -235.847128)
		(width 0.14478)
		(layer "In6.Cu")
		(net "M_K_CPU0_SA_CB<2>")
	)
	(segment
		(start 430.498758 -234.76585)
		(end 430.729136 -234.76585)
		(width 0.14478)
		(layer "In6.Cu")
		(net "M_K_CPU0_SA_CB<2>")
	)
	(segment
		(start 416.610546 -234.77855)
		(end 416.840924 -234.77855)
		(width 0.14478)
		(layer "In6.Cu")
		(net "M_K_CPU0_SA_CB<2>")
	)
	(segment
		(start 438.409842 -234.99699)
		(end 438.57291 -235.160058)
		(width 0.14478)
		(layer "In6.Cu")
		(net "M_K_CPU0_SA_CB<2>")
	)
	(segment
		(start 427.819058 -236.010196)
		(end 427.982126 -235.847128)
		(width 0.14478)
		(layer "In6.Cu")
		(net "M_K_CPU0_SA_CB<2>")
	)
	(segment
		(start 440.48045 -235.380022)
		(end 440.48045 -234.940094)
		(width 0.14478)
		(layer "In6.Cu")
		(net "M_K_CPU0_SA_CB<2>")
	)
	(segment
		(start 436.025544 -235.62183)
		(end 436.188612 -235.784898)
		(width 0.14478)
		(layer "In6.Cu")
		(net "M_K_CPU0_SA_CB<2>")
	)
	(segment
		(start 425.392088 -235.160058)
		(end 426.242226 -236.010196)
		(width 0.14478)
		(layer "In6.Cu")
		(net "M_K_CPU0_SA_CB<2>")
	)
	(segment
		(start 392.331448 -244.97157)
		(end 392.341862 -244.977666)
		(width 0.0889)
		(layer "In6.Cu")
		(net "M_K_CPU0_SA_CB<2>")
	)
	(segment
		(start 423.39895 -234.936538)
		(end 423.39895 -234.99699)
		(width 0.14478)
		(layer "In6.Cu")
		(net "M_K_CPU0_SA_CB<2>")
	)
	(segment
		(start 435.795166 -235.62183)
		(end 436.025544 -235.62183)
		(width 0.14478)
		(layer "In6.Cu")
		(net "M_K_CPU0_SA_CB<2>")
	)
	(segment
		(start 428.145194 -235.62691)
		(end 428.375572 -235.62691)
		(width 0.14478)
		(layer "In6.Cu")
		(net "M_K_CPU0_SA_CB<2>")
	)
	(segment
		(start 417.16706 -235.160058)
		(end 417.848034 -235.160058)
		(width 0.14478)
		(layer "In6.Cu")
		(net "M_K_CPU0_SA_CB<2>")
	)
	(segment
		(start 433.786026 -236.010196)
		(end 435.46903 -236.010196)
		(width 0.14478)
		(layer "In6.Cu")
		(net "M_K_CPU0_SA_CB<2>")
	)
	(segment
		(start 393.530074 -245.0338)
		(end 394.149834 -245.0338)
		(width 0.0889)
		(layer "In6.Cu")
		(net "M_K_CPU0_SA_CB<2>")
	)
	(segment
		(start 420.20617 -236.010196)
		(end 420.369238 -235.847128)
		(width 0.14478)
		(layer "In6.Cu")
		(net "M_K_CPU0_SA_CB<2>")
	)
	(segment
		(start 394.149834 -245.0338)
		(end 394.349224 -245.23319)
		(width 0.0889)
		(layer "In6.Cu")
		(net "M_K_CPU0_SA_CB<2>")
	)
	(segment
		(start 390.418828 -245.02872)
		(end 390.51484 -245.00332)
		(width 0.0889)
		(layer "In6.Cu")
		(net "M_K_CPU0_SA_CB<2>")
	)
	(segment
		(start 417.003992 -234.99699)
		(end 417.16706 -235.160058)
		(width 0.14478)
		(layer "In6.Cu")
		(net "M_K_CPU0_SA_CB<2>")
	)
	(segment
		(start 422.842436 -234.99699)
		(end 422.842436 -234.936538)
		(width 0.14478)
		(layer "In6.Cu")
		(net "M_K_CPU0_SA_CB<2>")
	)
	(segment
		(start 441.756546 -235.160058)
		(end 442.119258 -235.160058)
		(width 0.14478)
		(layer "In6.Cu")
		(net "M_K_CPU0_SA_CB<2>")
	)
	(segment
		(start 420.369238 -235.847128)
		(end 420.369238 -235.784898)
		(width 0.14478)
		(layer "In6.Cu")
		(net "M_K_CPU0_SA_CB<2>")
	)
	(segment
		(start 418.698172 -236.010196)
		(end 420.20617 -236.010196)
		(width 0.14478)
		(layer "In6.Cu")
		(net "M_K_CPU0_SA_CB<2>")
	)
	(segment
		(start 417.003992 -234.941618)
		(end 417.003992 -234.99699)
		(width 0.14478)
		(layer "In6.Cu")
		(net "M_K_CPU0_SA_CB<2>")
	)
	(segment
		(start 429.08093 -236.010196)
		(end 429.931068 -235.160058)
		(width 0.14478)
		(layer "In6.Cu")
		(net "M_K_CPU0_SA_CB<2>")
	)
	(segment
		(start 430.172622 -235.160058)
		(end 430.33569 -234.99699)
		(width 0.14478)
		(layer "In6.Cu")
		(net "M_K_CPU0_SA_CB<2>")
	)
	(segment
		(start 436.188612 -235.784898)
		(end 436.188612 -235.847128)
		(width 0.14478)
		(layer "In6.Cu")
		(net "M_K_CPU0_SA_CB<2>")
	)
	(segment
		(start 441.036964 -234.940094)
		(end 441.036964 -235.380022)
		(width 0.14478)
		(layer "In6.Cu")
		(net "M_K_CPU0_SA_CB<2>")
	)
	(segment
		(start 417.848034 -235.160058)
		(end 418.698172 -236.010196)
		(width 0.14478)
		(layer "In6.Cu")
		(net "M_K_CPU0_SA_CB<2>")
	)
	(segment
		(start 390.264904 -245.29415)
		(end 390.418828 -245.02872)
		(width 0.0889)
		(layer "In6.Cu")
		(net "M_K_CPU0_SA_CB<2>")
	)
	(segment
		(start 438.409842 -234.936538)
		(end 438.409842 -234.99699)
		(width 0.14478)
		(layer "In6.Cu")
		(net "M_K_CPU0_SA_CB<2>")
	)
	(segment
		(start 391.947146 -244.977666)
		(end 391.95756 -244.97157)
		(width 0.0889)
		(layer "In6.Cu")
		(net "M_K_CPU0_SA_CB<2>")
	)
	(segment
		(start 416.840924 -234.77855)
		(end 417.003992 -234.941618)
		(width 0.14478)
		(layer "In6.Cu")
		(net "M_K_CPU0_SA_CB<2>")
	)
	(segment
		(start 439.760868 -235.160058)
		(end 439.923936 -235.323126)
		(width 0.14478)
		(layer "In6.Cu")
		(net "M_K_CPU0_SA_CB<2>")
	)
	(segment
		(start 421.08882 -236.010196)
		(end 421.549322 -236.010196)
		(width 0.14478)
		(layer "In6.Cu")
		(net "M_K_CPU0_SA_CB<2>")
	)
	(segment
		(start 428.701708 -236.010196)
		(end 429.08093 -236.010196)
		(width 0.14478)
		(layer "In6.Cu")
		(net "M_K_CPU0_SA_CB<2>")
	)
	(segment
		(start 414.85693 -235.160058)
		(end 416.28441 -235.160058)
		(width 0.14478)
		(layer "In6.Cu")
		(net "M_K_CPU0_SA_CB<2>")
	)
	(segment
		(start 430.729136 -234.76585)
		(end 430.892204 -234.928918)
		(width 0.14478)
		(layer "In6.Cu")
		(net "M_K_CPU0_SA_CB<2>")
	)
	(segment
		(start 435.632098 -235.784898)
		(end 435.795166 -235.62183)
		(width 0.14478)
		(layer "In6.Cu")
		(net "M_K_CPU0_SA_CB<2>")
	)
	(segment
		(start 391.01776 -244.97157)
		(end 391.026142 -244.966744)
		(width 0.0889)
		(layer "In6.Cu")
		(net "M_K_CPU0_SA_CB<2>")
	)
	(segment
		(start 420.925752 -235.847128)
		(end 421.08882 -236.010196)
		(width 0.14478)
		(layer "In6.Cu")
		(net "M_K_CPU0_SA_CB<2>")
	)
	(segment
		(start 440.317382 -235.54309)
		(end 440.48045 -235.380022)
		(width 0.14478)
		(layer "In6.Cu")
		(net "M_K_CPU0_SA_CB<2>")
	)
	(segment
		(start 420.369238 -235.784898)
		(end 420.532306 -235.62183)
		(width 0.14478)
		(layer "In6.Cu")
		(net "M_K_CPU0_SA_CB<2>")
	)
	(segment
		(start 438.016396 -234.77347)
		(end 438.246774 -234.77347)
		(width 0.14478)
		(layer "In6.Cu")
		(net "M_K_CPU0_SA_CB<2>")
	)
	(segment
		(start 420.532306 -235.62183)
		(end 420.762684 -235.62183)
		(width 0.14478)
		(layer "In6.Cu")
		(net "M_K_CPU0_SA_CB<2>")
	)
	(segment
		(start 436.188612 -235.847128)
		(end 436.35168 -236.010196)
		(width 0.14478)
		(layer "In6.Cu")
		(net "M_K_CPU0_SA_CB<2>")
	)
	(segment
		(start 440.48045 -234.940094)
		(end 440.643518 -234.777026)
		(width 0.14478)
		(layer "In6.Cu")
		(net "M_K_CPU0_SA_CB<2>")
	)
	(segment
		(start 430.892204 -234.99699)
		(end 431.055272 -235.160058)
		(width 0.14478)
		(layer "In6.Cu")
		(net "M_K_CPU0_SA_CB<2>")
	)
	(segment
		(start 423.39895 -234.99699)
		(end 423.562018 -235.160058)
		(width 0.14478)
		(layer "In6.Cu")
		(net "M_K_CPU0_SA_CB<2>")
	)
	(segment
		(start 441.593478 -235.323126)
		(end 441.756546 -235.160058)
		(width 0.14478)
		(layer "In6.Cu")
		(net "M_K_CPU0_SA_CB<2>")
	)
	(segment
		(start 437.463438 -235.160058)
		(end 437.69026 -235.160058)
		(width 0.14478)
		(layer "In6.Cu")
		(net "M_K_CPU0_SA_CB<2>")
	)
	(segment
		(start 426.242226 -236.010196)
		(end 427.819058 -236.010196)
		(width 0.14478)
		(layer "In6.Cu")
		(net "M_K_CPU0_SA_CB<2>")
	)
	(segment
		(start 430.33569 -234.99699)
		(end 430.33569 -234.928918)
		(width 0.14478)
		(layer "In6.Cu")
		(net "M_K_CPU0_SA_CB<2>")
	)
	(segment
		(start 441.036964 -235.380022)
		(end 441.200032 -235.54309)
		(width 0.14478)
		(layer "In6.Cu")
		(net "M_K_CPU0_SA_CB<2>")
	)
	(segment
		(start 441.593478 -235.380022)
		(end 441.593478 -235.323126)
		(width 0.14478)
		(layer "In6.Cu")
		(net "M_K_CPU0_SA_CB<2>")
	)
	(segment
		(start 416.28441 -235.160058)
		(end 416.447478 -234.99699)
		(width 0.14478)
		(layer "In6.Cu")
		(net "M_K_CPU0_SA_CB<2>")
	)
	(segment
		(start 428.375572 -235.62691)
		(end 428.53864 -235.789978)
		(width 0.14478)
		(layer "In6.Cu")
		(net "M_K_CPU0_SA_CB<2>")
	)
	(segment
		(start 394.828776 -245.23319)
		(end 395.611096 -244.45087)
		(width 0.0889)
		(layer "In6.Cu")
		(net "M_K_CPU0_SA_CB<2>")
	)
	(segment
		(start 422.842436 -234.936538)
		(end 423.005504 -234.77347)
		(width 0.14478)
		(layer "In6.Cu")
		(net "M_K_CPU0_SA_CB<2>")
	)
	(segment
		(start 438.246774 -234.77347)
		(end 438.409842 -234.936538)
		(width 0.14478)
		(layer "In6.Cu")
		(net "M_K_CPU0_SA_CB<2>")
	)
	(segment
		(start 436.6133 -236.010196)
		(end 437.463438 -235.160058)
		(width 0.14478)
		(layer "In6.Cu")
		(net "M_K_CPU0_SA_CB<2>")
	)
	(segment
		(start 422.679368 -235.160058)
		(end 422.842436 -234.99699)
		(width 0.14478)
		(layer "In6.Cu")
		(net "M_K_CPU0_SA_CB<2>")
	)
	(segment
		(start 441.200032 -235.54309)
		(end 441.43041 -235.54309)
		(width 0.14478)
		(layer "In6.Cu")
		(net "M_K_CPU0_SA_CB<2>")
	)
	(segment
		(start 412.133034 -236.010196)
		(end 414.006792 -236.010196)
		(width 0.14478)
		(layer "In6.Cu")
		(net "M_K_CPU0_SA_CB<2>")
	)
	(segment
		(start 441.43041 -235.54309)
		(end 441.593478 -235.380022)
		(width 0.14478)
		(layer "In6.Cu")
		(net "M_K_CPU0_SA_CB<2>")
	)
	(segment
		(start 394.349224 -245.23319)
		(end 394.828776 -245.23319)
		(width 0.0889)
		(layer "In6.Cu")
		(net "M_K_CPU0_SA_CB<2>")
	)
	(segment
		(start 427.982126 -235.789978)
		(end 428.145194 -235.62691)
		(width 0.14478)
		(layer "In6.Cu")
		(net "M_K_CPU0_SA_CB<2>")
	)
	(segment
		(start 395.875256 -244.45087)
		(end 404.118064 -244.45087)
		(width 0.14478)
		(layer "In6.Cu")
		(net "M_K_CPU0_SA_CB<2>")
	)
	(segment
		(start 421.549322 -236.010196)
		(end 422.39946 -235.160058)
		(width 0.14478)
		(layer "In6.Cu")
		(net "M_K_CPU0_SA_CB<2>")
	)
	(segment
		(start 437.853328 -234.99699)
		(end 437.853328 -234.936538)
		(width 0.14478)
		(layer "In6.Cu")
		(net "M_K_CPU0_SA_CB<2>")
	)
	(segment
		(start 439.923936 -235.323126)
		(end 439.923936 -235.380022)
		(width 0.14478)
		(layer "In6.Cu")
		(net "M_K_CPU0_SA_CB<2>")
	)
	(segment
		(start 423.005504 -234.77347)
		(end 423.235882 -234.77347)
		(width 0.14478)
		(layer "In6.Cu")
		(net "M_K_CPU0_SA_CB<2>")
	)
	(segment
		(start 436.35168 -236.010196)
		(end 436.6133 -236.010196)
		(width 0.14478)
		(layer "In6.Cu")
		(net "M_K_CPU0_SA_CB<2>")
	)
	(segment
		(start 435.632098 -235.847128)
		(end 435.632098 -235.784898)
		(width 0.14478)
		(layer "In6.Cu")
		(net "M_K_CPU0_SA_CB<2>")
	)
	(segment
		(start 430.892204 -234.928918)
		(end 430.892204 -234.99699)
		(width 0.14478)
		(layer "In6.Cu")
		(net "M_K_CPU0_SA_CB<2>")
	)
	(segment
		(start 420.925752 -235.784898)
		(end 420.925752 -235.847128)
		(width 0.14478)
		(layer "In6.Cu")
		(net "M_K_CPU0_SA_CB<2>")
	)
	(segment
		(start 423.562018 -235.160058)
		(end 425.392088 -235.160058)
		(width 0.14478)
		(layer "In6.Cu")
		(net "M_K_CPU0_SA_CB<2>")
	)
	(segment
		(start 442.119258 -235.160058)
		(end 442.5442 -235.585)
		(width 0.14478)
		(layer "In6.Cu")
		(net "M_K_CPU0_SA_CB<2>")
	)
	(segment
		(start 437.853328 -234.936538)
		(end 438.016396 -234.77347)
		(width 0.14478)
		(layer "In6.Cu")
		(net "M_K_CPU0_SA_CB<2>")
	)
	(segment
		(start 423.235882 -234.77347)
		(end 423.39895 -234.936538)
		(width 0.14478)
		(layer "In6.Cu")
		(net "M_K_CPU0_SA_CB<2>")
	)
	(segment
		(start 428.53864 -235.847128)
		(end 428.701708 -236.010196)
		(width 0.14478)
		(layer "In6.Cu")
		(net "M_K_CPU0_SA_CB<2>")
	)
	(segment
		(start 432.935888 -235.160058)
		(end 433.786026 -236.010196)
		(width 0.14478)
		(layer "In6.Cu")
		(net "M_K_CPU0_SA_CB<2>")
	)
	(segment
		(start 430.33569 -234.928918)
		(end 430.498758 -234.76585)
		(width 0.14478)
		(layer "In6.Cu")
		(net "M_K_CPU0_SA_CB<2>")
	)
	(segment
		(start 439.923936 -235.380022)
		(end 440.087004 -235.54309)
		(width 0.14478)
		(layer "In6.Cu")
		(net "M_K_CPU0_SA_CB<2>")
	)
	(segment
		(start 427.982126 -235.847128)
		(end 427.982126 -235.789978)
		(width 0.14478)
		(layer "In6.Cu")
		(net "M_K_CPU0_SA_CB<2>")
	)
	(segment
		(start 411.895798 -236.673136)
		(end 411.895798 -236.247432)
		(width 0.14478)
		(layer "In6.Cu")
		(net "M_K_CPU0_SA_CB<2>")
	)
	(arc
		(start 391.026142 -244.966744)
		(mid 391.20965 -244.92125)
		(end 391.391902 -244.97157)
		(width 0.0889)
		(layer "In6.Cu")
		(net "M_K_CPU0_SA_CB<2>")
	)
	(arc
		(start 392.897614 -244.97157)
		(mid 393.077819 -244.921253)
		(end 393.259818 -244.964712)
		(width 0.0889)
		(layer "In6.Cu")
		(net "M_K_CPU0_SA_CB<2>")
	)
	(arc
		(start 392.341862 -244.977666)
		(mid 392.620548 -245.047886)
		(end 392.897614 -244.97157)
		(width 0.0889)
		(layer "In6.Cu")
		(net "M_K_CPU0_SA_CB<2>")
	)
	(arc
		(start 390.51484 -245.00332)
		(mid 390.770048 -245.046797)
		(end 391.01776 -244.97157)
		(width 0.0889)
		(layer "In6.Cu")
		(net "M_K_CPU0_SA_CB<2>")
	)
	(arc
		(start 393.259818 -244.964712)
		(mid 393.390608 -245.016223)
		(end 393.530074 -245.0338)
		(width 0.0889)
		(layer "In6.Cu")
		(net "M_K_CPU0_SA_CB<2>")
	)
	(arc
		(start 391.391902 -244.97157)
		(mid 391.668715 -245.047713)
		(end 391.947146 -244.977666)
		(width 0.0889)
		(layer "In6.Cu")
		(net "M_K_CPU0_SA_CB<2>")
	)
	(arc
		(start 391.95756 -244.97157)
		(mid 392.144504 -244.921315)
		(end 392.331448 -244.97157)
		(width 0.0889)
		(layer "In6.Cu")
		(net "M_K_CPU0_SA_CB<2>")
	)
	(segment
		(start 388.857998 -245.560088)
		(end 389.32485 -245.29415)
		(width 0.10668)
		(layer "F.Cu")
		(net "M_K_CPU0_SA_CB<1>")
	)
	(segment
		(start 393.271502 -245.61673)
		(end 394.953236 -245.61673)
		(width 0.0889)
		(layer "In6.Cu")
		(net "M_K_CPU0_SA_CB<1>")
	)
	(segment
		(start 390.443466 -245.621556)
		(end 390.451848 -245.61673)
		(width 0.0889)
		(layer "In6.Cu")
		(net "M_K_CPU0_SA_CB<1>")
	)
	(segment
		(start 415.232088 -236.009942)
		(end 417.046918 -236.009942)
		(width 0.14478)
		(layer "In6.Cu")
		(net "M_K_CPU0_SA_CB<1>")
	)
	(segment
		(start 394.953236 -245.61673)
		(end 395.664436 -244.90553)
		(width 0.0889)
		(layer "In6.Cu")
		(net "M_K_CPU0_SA_CB<1>")
	)
	(segment
		(start 418.414454 -236.576362)
		(end 419.099492 -236.86008)
		(width 0.14478)
		(layer "In6.Cu")
		(net "M_K_CPU0_SA_CB<1>")
	)
	(segment
		(start 425.392342 -236.010196)
		(end 426.242226 -236.86008)
		(width 0.14478)
		(layer "In6.Cu")
		(net "M_K_CPU0_SA_CB<1>")
	)
	(segment
		(start 433.786026 -236.86008)
		(end 436.741316 -236.86008)
		(width 0.14478)
		(layer "In6.Cu")
		(net "M_K_CPU0_SA_CB<1>")
	)
	(segment
		(start 420.702486 -236.86008)
		(end 422.148254 -236.261148)
		(width 0.14478)
		(layer "In6.Cu")
		(net "M_K_CPU0_SA_CB<1>")
	)
	(segment
		(start 446.219326 -236.010196)
		(end 446.644268 -236.435138)
		(width 0.14478)
		(layer "In6.Cu")
		(net "M_K_CPU0_SA_CB<1>")
	)
	(segment
		(start 395.857984 -244.90553)
		(end 404.306532 -244.90553)
		(width 0.14478)
		(layer "In6.Cu")
		(net "M_K_CPU0_SA_CB<1>")
	)
	(segment
		(start 412.351982 -236.86008)
		(end 413.179514 -236.86008)
		(width 0.14478)
		(layer "In6.Cu")
		(net "M_K_CPU0_SA_CB<1>")
	)
	(segment
		(start 426.242226 -236.86008)
		(end 429.08093 -236.86008)
		(width 0.14478)
		(layer "In6.Cu")
		(net "M_K_CPU0_SA_CB<1>")
	)
	(segment
		(start 436.741316 -236.86008)
		(end 437.5912 -236.010196)
		(width 0.14478)
		(layer "In6.Cu")
		(net "M_K_CPU0_SA_CB<1>")
	)
	(segment
		(start 392.331448 -245.61673)
		(end 392.341862 -245.610634)
		(width 0.0889)
		(layer "In6.Cu")
		(net "M_K_CPU0_SA_CB<1>")
	)
	(segment
		(start 419.099492 -236.86008)
		(end 420.702486 -236.86008)
		(width 0.14478)
		(layer "In6.Cu")
		(net "M_K_CPU0_SA_CB<1>")
	)
	(segment
		(start 413.179514 -236.86008)
		(end 415.232088 -236.009942)
		(width 0.14478)
		(layer "In6.Cu")
		(net "M_K_CPU0_SA_CB<1>")
	)
	(segment
		(start 389.170926 -245.55958)
		(end 389.193278 -245.642892)
		(width 0.0889)
		(layer "In6.Cu")
		(net "M_K_CPU0_SA_CB<1>")
	)
	(segment
		(start 422.148254 -236.261148)
		(end 422.754298 -236.010196)
		(width 0.14478)
		(layer "In6.Cu")
		(net "M_K_CPU0_SA_CB<1>")
	)
	(segment
		(start 391.947146 -245.610634)
		(end 391.95756 -245.61673)
		(width 0.0889)
		(layer "In6.Cu")
		(net "M_K_CPU0_SA_CB<1>")
	)
	(segment
		(start 429.930814 -236.010196)
		(end 432.936142 -236.010196)
		(width 0.14478)
		(layer "In6.Cu")
		(net "M_K_CPU0_SA_CB<1>")
	)
	(segment
		(start 404.306532 -244.90553)
		(end 412.351982 -236.86008)
		(width 0.14478)
		(layer "In6.Cu")
		(net "M_K_CPU0_SA_CB<1>")
	)
	(segment
		(start 422.754298 -236.010196)
		(end 425.392342 -236.010196)
		(width 0.14478)
		(layer "In6.Cu")
		(net "M_K_CPU0_SA_CB<1>")
	)
	(segment
		(start 429.08093 -236.86008)
		(end 429.930814 -236.010196)
		(width 0.14478)
		(layer "In6.Cu")
		(net "M_K_CPU0_SA_CB<1>")
	)
	(segment
		(start 437.5912 -236.010196)
		(end 446.219326 -236.010196)
		(width 0.14478)
		(layer "In6.Cu")
		(net "M_K_CPU0_SA_CB<1>")
	)
	(segment
		(start 393.259818 -245.623588)
		(end 393.271502 -245.61673)
		(width 0.0889)
		(layer "In6.Cu")
		(net "M_K_CPU0_SA_CB<1>")
	)
	(segment
		(start 389.32485 -245.29415)
		(end 389.170926 -245.55958)
		(width 0.0889)
		(layer "In6.Cu")
		(net "M_K_CPU0_SA_CB<1>")
	)
	(segment
		(start 391.01776 -245.61673)
		(end 391.026142 -245.621556)
		(width 0.0889)
		(layer "In6.Cu")
		(net "M_K_CPU0_SA_CB<1>")
	)
	(segment
		(start 432.936142 -236.010196)
		(end 433.786026 -236.86008)
		(width 0.14478)
		(layer "In6.Cu")
		(net "M_K_CPU0_SA_CB<1>")
	)
	(segment
		(start 395.664436 -244.90553)
		(end 395.857984 -244.90553)
		(width 0.0889)
		(layer "In6.Cu")
		(net "M_K_CPU0_SA_CB<1>")
	)
	(segment
		(start 417.046918 -236.009942)
		(end 418.414454 -236.576362)
		(width 0.14478)
		(layer "In6.Cu")
		(net "M_K_CPU0_SA_CB<1>")
	)
	(arc
		(start 391.95756 -245.61673)
		(mid 392.144504 -245.666985)
		(end 392.331448 -245.61673)
		(width 0.0889)
		(layer "In6.Cu")
		(net "M_K_CPU0_SA_CB<1>")
	)
	(arc
		(start 392.897614 -245.61673)
		(mid 393.077819 -245.667047)
		(end 393.259818 -245.623588)
		(width 0.0889)
		(layer "In6.Cu")
		(net "M_K_CPU0_SA_CB<1>")
	)
	(arc
		(start 392.341862 -245.610634)
		(mid 392.620548 -245.540414)
		(end 392.897614 -245.61673)
		(width 0.0889)
		(layer "In6.Cu")
		(net "M_K_CPU0_SA_CB<1>")
	)
	(arc
		(start 391.391902 -245.61673)
		(mid 391.668715 -245.540587)
		(end 391.947146 -245.610634)
		(width 0.0889)
		(layer "In6.Cu")
		(net "M_K_CPU0_SA_CB<1>")
	)
	(arc
		(start 389.193278 -245.642892)
		(mid 389.355467 -245.665627)
		(end 389.511794 -245.61673)
		(width 0.0889)
		(layer "In6.Cu")
		(net "M_K_CPU0_SA_CB<1>")
	)
	(arc
		(start 389.511794 -245.61673)
		(mid 389.79475 -245.540553)
		(end 390.077706 -245.61673)
		(width 0.0889)
		(layer "In6.Cu")
		(net "M_K_CPU0_SA_CB<1>")
	)
	(arc
		(start 390.451848 -245.61673)
		(mid 390.734804 -245.540553)
		(end 391.01776 -245.61673)
		(width 0.0889)
		(layer "In6.Cu")
		(net "M_K_CPU0_SA_CB<1>")
	)
	(arc
		(start 390.077706 -245.61673)
		(mid 390.259957 -245.66708)
		(end 390.443466 -245.621556)
		(width 0.0889)
		(layer "In6.Cu")
		(net "M_K_CPU0_SA_CB<1>")
	)
	(arc
		(start 391.026142 -245.621556)
		(mid 391.20965 -245.66705)
		(end 391.391902 -245.61673)
		(width 0.0889)
		(layer "In6.Cu")
		(net "M_K_CPU0_SA_CB<1>")
	)
	(segment
		(start 390.267952 -244.750082)
		(end 390.734804 -244.484144)
		(width 0.10668)
		(layer "F.Cu")
		(net "M_K_CPU0_SA_CB<0>")
	)
	(segment
		(start 432.936142 -234.310174)
		(end 433.786026 -235.160058)
		(width 0.14478)
		(layer "In6.Cu")
		(net "M_K_CPU0_SA_CB<0>")
	)
	(segment
		(start 403.929596 -243.99621)
		(end 411.410658 -236.515148)
		(width 0.14478)
		(layer "In6.Cu")
		(net "M_K_CPU0_SA_CB<0>")
	)
	(segment
		(start 411.410658 -236.515148)
		(end 411.410658 -236.039152)
		(width 0.14478)
		(layer "In6.Cu")
		(net "M_K_CPU0_SA_CB<0>")
	)
	(segment
		(start 394.765276 -243.99621)
		(end 395.857984 -243.99621)
		(width 0.0889)
		(layer "In6.Cu")
		(net "M_K_CPU0_SA_CB<0>")
	)
	(segment
		(start 414.046416 -235.160058)
		(end 414.896554 -234.30992)
		(width 0.14478)
		(layer "In6.Cu")
		(net "M_K_CPU0_SA_CB<0>")
	)
	(segment
		(start 412.289752 -235.160058)
		(end 414.046416 -235.160058)
		(width 0.14478)
		(layer "In6.Cu")
		(net "M_K_CPU0_SA_CB<0>")
	)
	(segment
		(start 417.848034 -234.30992)
		(end 418.698172 -235.160058)
		(width 0.14478)
		(layer "In6.Cu")
		(net "M_K_CPU0_SA_CB<0>")
	)
	(segment
		(start 421.549322 -235.160058)
		(end 422.399206 -234.310174)
		(width 0.14478)
		(layer "In6.Cu")
		(net "M_K_CPU0_SA_CB<0>")
	)
	(segment
		(start 392.42746 -244.806724)
		(end 392.435842 -244.81155)
		(width 0.0889)
		(layer "In6.Cu")
		(net "M_K_CPU0_SA_CB<0>")
	)
	(segment
		(start 390.734804 -244.484144)
		(end 390.58088 -244.749574)
		(width 0.0889)
		(layer "In6.Cu")
		(net "M_K_CPU0_SA_CB<0>")
	)
	(segment
		(start 391.85342 -244.81155)
		(end 391.861802 -244.806724)
		(width 0.0889)
		(layer "In6.Cu")
		(net "M_K_CPU0_SA_CB<0>")
	)
	(segment
		(start 426.242226 -235.160058)
		(end 429.08093 -235.160058)
		(width 0.14478)
		(layer "In6.Cu")
		(net "M_K_CPU0_SA_CB<0>")
	)
	(segment
		(start 425.392342 -234.310174)
		(end 426.242226 -235.160058)
		(width 0.14478)
		(layer "In6.Cu")
		(net "M_K_CPU0_SA_CB<0>")
	)
	(segment
		(start 393.918186 -244.8433)
		(end 394.765276 -243.99621)
		(width 0.0889)
		(layer "In6.Cu")
		(net "M_K_CPU0_SA_CB<0>")
	)
	(segment
		(start 429.08093 -235.160058)
		(end 429.930814 -234.310174)
		(width 0.14478)
		(layer "In6.Cu")
		(net "M_K_CPU0_SA_CB<0>")
	)
	(segment
		(start 390.58088 -244.749574)
		(end 390.603232 -244.832886)
		(width 0.0889)
		(layer "In6.Cu")
		(net "M_K_CPU0_SA_CB<0>")
	)
	(segment
		(start 411.410658 -236.039152)
		(end 412.289752 -235.160058)
		(width 0.14478)
		(layer "In6.Cu")
		(net "M_K_CPU0_SA_CB<0>")
	)
	(segment
		(start 422.399206 -234.310174)
		(end 425.392342 -234.310174)
		(width 0.14478)
		(layer "In6.Cu")
		(net "M_K_CPU0_SA_CB<0>")
	)
	(segment
		(start 393.530328 -244.8433)
		(end 393.918186 -244.8433)
		(width 0.0889)
		(layer "In6.Cu")
		(net "M_K_CPU0_SA_CB<0>")
	)
	(segment
		(start 395.857984 -243.99621)
		(end 403.929596 -243.99621)
		(width 0.14478)
		(layer "In6.Cu")
		(net "M_K_CPU0_SA_CB<0>")
	)
	(segment
		(start 436.741316 -235.160058)
		(end 437.5912 -234.310174)
		(width 0.14478)
		(layer "In6.Cu")
		(net "M_K_CPU0_SA_CB<0>")
	)
	(segment
		(start 446.219326 -234.310174)
		(end 446.644268 -234.735116)
		(width 0.14478)
		(layer "In6.Cu")
		(net "M_K_CPU0_SA_CB<0>")
	)
	(segment
		(start 391.861802 -244.806724)
		(end 391.872216 -244.800628)
		(width 0.0889)
		(layer "In6.Cu")
		(net "M_K_CPU0_SA_CB<0>")
	)
	(segment
		(start 418.698172 -235.160058)
		(end 421.549322 -235.160058)
		(width 0.14478)
		(layer "In6.Cu")
		(net "M_K_CPU0_SA_CB<0>")
	)
	(segment
		(start 433.786026 -235.160058)
		(end 436.741316 -235.160058)
		(width 0.14478)
		(layer "In6.Cu")
		(net "M_K_CPU0_SA_CB<0>")
	)
	(segment
		(start 429.930814 -234.310174)
		(end 432.936142 -234.310174)
		(width 0.14478)
		(layer "In6.Cu")
		(net "M_K_CPU0_SA_CB<0>")
	)
	(segment
		(start 414.896554 -234.30992)
		(end 417.848034 -234.30992)
		(width 0.14478)
		(layer "In6.Cu")
		(net "M_K_CPU0_SA_CB<0>")
	)
	(segment
		(start 437.5912 -234.310174)
		(end 446.219326 -234.310174)
		(width 0.14478)
		(layer "In6.Cu")
		(net "M_K_CPU0_SA_CB<0>")
	)
	(arc
		(start 392.435842 -244.81155)
		(mid 392.61935 -244.857044)
		(end 392.801602 -244.806724)
		(width 0.0889)
		(layer "In6.Cu")
		(net "M_K_CPU0_SA_CB<0>")
	)
	(arc
		(start 391.872216 -244.800628)
		(mid 392.150648 -244.73053)
		(end 392.42746 -244.806724)
		(width 0.0889)
		(layer "In6.Cu")
		(net "M_K_CPU0_SA_CB<0>")
	)
	(arc
		(start 393.352782 -244.798088)
		(mid 393.43874 -244.831743)
		(end 393.530328 -244.8433)
		(width 0.0889)
		(layer "In6.Cu")
		(net "M_K_CPU0_SA_CB<0>")
	)
	(arc
		(start 392.801602 -244.806724)
		(mid 393.076054 -244.730488)
		(end 393.352782 -244.798088)
		(width 0.0889)
		(layer "In6.Cu")
		(net "M_K_CPU0_SA_CB<0>")
	)
	(arc
		(start 390.921748 -244.806724)
		(mid 391.204704 -244.730547)
		(end 391.48766 -244.806724)
		(width 0.0889)
		(layer "In6.Cu")
		(net "M_K_CPU0_SA_CB<0>")
	)
	(arc
		(start 390.603232 -244.832886)
		(mid 390.765421 -244.855621)
		(end 390.921748 -244.806724)
		(width 0.0889)
		(layer "In6.Cu")
		(net "M_K_CPU0_SA_CB<0>")
	)
	(arc
		(start 391.48766 -244.806724)
		(mid 391.669911 -244.857074)
		(end 391.85342 -244.81155)
		(width 0.0889)
		(layer "In6.Cu")
		(net "M_K_CPU0_SA_CB<0>")
	)
	(segment
		(start 388.857998 -255.28016)
		(end 389.32485 -255.014222)
		(width 0.10668)
		(layer "F.Cu")
		(net "M_K_CPU0_SA_CA<6>")
	)
	(segment
		(start 442.370972 -252.160024)
		(end 442.72962 -252.160024)
		(width 0.0889)
		(layer "In6.Cu")
		(net "M_K_CPU0_SA_CA<6>")
	)
	(segment
		(start 393.271502 -255.336548)
		(end 393.27709 -255.333246)
		(width 0.0889)
		(layer "In6.Cu")
		(net "M_K_CPU0_SA_CA<6>")
	)
	(segment
		(start 391.01776 -255.336802)
		(end 391.026142 -255.341628)
		(width 0.0889)
		(layer "In6.Cu")
		(net "M_K_CPU0_SA_CA<6>")
	)
	(segment
		(start 395.822424 -256.06121)
		(end 398.484852 -256.06121)
		(width 0.14478)
		(layer "In6.Cu")
		(net "M_K_CPU0_SA_CA<6>")
	)
	(segment
		(start 398.484852 -256.06121)
		(end 399.847562 -254.6985)
		(width 0.14478)
		(layer "In6.Cu")
		(net "M_K_CPU0_SA_CA<6>")
	)
	(segment
		(start 399.847562 -254.6985)
		(end 410.764228 -254.6985)
		(width 0.14478)
		(layer "In6.Cu")
		(net "M_K_CPU0_SA_CA<6>")
	)
	(segment
		(start 442.163962 -252.36043)
		(end 442.307218 -252.217174)
		(width 0.14478)
		(layer "In6.Cu")
		(net "M_K_CPU0_SA_CA<6>")
	)
	(segment
		(start 442.313822 -252.217174)
		(end 442.370972 -252.160024)
		(width 0.0889)
		(layer "In6.Cu")
		(net "M_K_CPU0_SA_CA<6>")
	)
	(segment
		(start 442.72962 -252.160024)
		(end 442.729874 -252.15977)
		(width 0.14478)
		(layer "In6.Cu")
		(net "M_K_CPU0_SA_CA<6>")
	)
	(segment
		(start 393.253214 -255.346962)
		(end 393.271502 -255.336548)
		(width 0.0889)
		(layer "In6.Cu")
		(net "M_K_CPU0_SA_CA<6>")
	)
	(segment
		(start 394.333476 -255.58877)
		(end 394.813536 -255.58877)
		(width 0.0889)
		(layer "In6.Cu")
		(net "M_K_CPU0_SA_CA<6>")
	)
	(segment
		(start 442.729874 -252.15977)
		(end 446.219072 -252.15977)
		(width 0.14478)
		(layer "In6.Cu")
		(net "M_K_CPU0_SA_CA<6>")
	)
	(segment
		(start 389.32485 -255.014222)
		(end 389.170926 -255.279652)
		(width 0.0889)
		(layer "In6.Cu")
		(net "M_K_CPU0_SA_CA<6>")
	)
	(segment
		(start 391.95756 -255.336802)
		(end 391.965942 -255.341628)
		(width 0.0889)
		(layer "In6.Cu")
		(net "M_K_CPU0_SA_CA<6>")
	)
	(segment
		(start 410.764228 -254.6985)
		(end 410.783024 -254.717296)
		(width 0.14478)
		(layer "In6.Cu")
		(net "M_K_CPU0_SA_CA<6>")
	)
	(segment
		(start 393.27709 -255.333246)
		(end 393.32281 -255.287526)
		(width 0.0889)
		(layer "In6.Cu")
		(net "M_K_CPU0_SA_CA<6>")
	)
	(segment
		(start 439.425334 -253.859792)
		(end 440.924696 -252.36043)
		(width 0.14478)
		(layer "In6.Cu")
		(net "M_K_CPU0_SA_CA<6>")
	)
	(segment
		(start 395.285976 -256.06121)
		(end 395.822424 -256.06121)
		(width 0.0889)
		(layer "In6.Cu")
		(net "M_K_CPU0_SA_CA<6>")
	)
	(segment
		(start 438.739534 -253.859792)
		(end 439.425334 -253.859792)
		(width 0.14478)
		(layer "In6.Cu")
		(net "M_K_CPU0_SA_CA<6>")
	)
	(segment
		(start 446.219072 -252.15977)
		(end 446.644268 -252.584966)
		(width 0.14478)
		(layer "In6.Cu")
		(net "M_K_CPU0_SA_CA<6>")
	)
	(segment
		(start 442.307218 -252.217174)
		(end 442.313822 -252.217174)
		(width 0.0889)
		(layer "In6.Cu")
		(net "M_K_CPU0_SA_CA<6>")
	)
	(segment
		(start 410.783024 -254.717296)
		(end 437.88203 -254.717296)
		(width 0.14478)
		(layer "In6.Cu")
		(net "M_K_CPU0_SA_CA<6>")
	)
	(segment
		(start 391.947146 -255.330706)
		(end 391.95756 -255.336802)
		(width 0.0889)
		(layer "In6.Cu")
		(net "M_K_CPU0_SA_CA<6>")
	)
	(segment
		(start 437.88203 -254.717296)
		(end 438.739534 -253.859792)
		(width 0.14478)
		(layer "In6.Cu")
		(net "M_K_CPU0_SA_CA<6>")
	)
	(segment
		(start 394.032232 -255.287526)
		(end 394.333476 -255.58877)
		(width 0.0889)
		(layer "In6.Cu")
		(net "M_K_CPU0_SA_CA<6>")
	)
	(segment
		(start 394.813536 -255.58877)
		(end 395.285976 -256.06121)
		(width 0.0889)
		(layer "In6.Cu")
		(net "M_K_CPU0_SA_CA<6>")
	)
	(segment
		(start 392.331194 -255.336802)
		(end 392.341608 -255.330706)
		(width 0.0889)
		(layer "In6.Cu")
		(net "M_K_CPU0_SA_CA<6>")
	)
	(segment
		(start 440.924696 -252.36043)
		(end 442.163962 -252.36043)
		(width 0.14478)
		(layer "In6.Cu")
		(net "M_K_CPU0_SA_CA<6>")
	)
	(segment
		(start 390.443466 -255.341628)
		(end 390.451848 -255.336802)
		(width 0.0889)
		(layer "In6.Cu")
		(net "M_K_CPU0_SA_CA<6>")
	)
	(segment
		(start 389.170926 -255.279652)
		(end 389.193278 -255.362964)
		(width 0.0889)
		(layer "In6.Cu")
		(net "M_K_CPU0_SA_CA<6>")
	)
	(segment
		(start 393.32281 -255.287526)
		(end 394.032232 -255.287526)
		(width 0.0889)
		(layer "In6.Cu")
		(net "M_K_CPU0_SA_CA<6>")
	)
	(arc
		(start 390.451848 -255.336802)
		(mid 390.734804 -255.260625)
		(end 391.01776 -255.336802)
		(width 0.0889)
		(layer "In6.Cu")
		(net "M_K_CPU0_SA_CA<6>")
	)
	(arc
		(start 389.511794 -255.336802)
		(mid 389.79475 -255.260625)
		(end 390.077706 -255.336802)
		(width 0.0889)
		(layer "In6.Cu")
		(net "M_K_CPU0_SA_CA<6>")
	)
	(arc
		(start 391.965942 -255.341628)
		(mid 392.149196 -255.387001)
		(end 392.331194 -255.336802)
		(width 0.0889)
		(layer "In6.Cu")
		(net "M_K_CPU0_SA_CA<6>")
	)
	(arc
		(start 391.391902 -255.336802)
		(mid 391.668715 -255.260659)
		(end 391.947146 -255.330706)
		(width 0.0889)
		(layer "In6.Cu")
		(net "M_K_CPU0_SA_CA<6>")
	)
	(arc
		(start 392.89736 -255.336802)
		(mid 393.073988 -255.387035)
		(end 393.253214 -255.346962)
		(width 0.0889)
		(layer "In6.Cu")
		(net "M_K_CPU0_SA_CA<6>")
	)
	(arc
		(start 391.026142 -255.341628)
		(mid 391.20965 -255.387122)
		(end 391.391902 -255.336802)
		(width 0.0889)
		(layer "In6.Cu")
		(net "M_K_CPU0_SA_CA<6>")
	)
	(arc
		(start 392.341608 -255.330706)
		(mid 392.620294 -255.260486)
		(end 392.89736 -255.336802)
		(width 0.0889)
		(layer "In6.Cu")
		(net "M_K_CPU0_SA_CA<6>")
	)
	(arc
		(start 390.077706 -255.336802)
		(mid 390.259957 -255.387152)
		(end 390.443466 -255.341628)
		(width 0.0889)
		(layer "In6.Cu")
		(net "M_K_CPU0_SA_CA<6>")
	)
	(arc
		(start 389.193278 -255.362964)
		(mid 389.355467 -255.385699)
		(end 389.511794 -255.336802)
		(width 0.0889)
		(layer "In6.Cu")
		(net "M_K_CPU0_SA_CA<6>")
	)
	(segment
		(start 389.798052 -255.28016)
		(end 390.264904 -255.014222)
		(width 0.10668)
		(layer "F.Cu")
		(net "M_K_CPU0_SA_CA<5>")
	)
	(segment
		(start 418.388292 -253.636018)
		(end 418.388292 -253.696978)
		(width 0.14478)
		(layer "In6.Cu")
		(net "M_K_CPU0_SA_CA<5>")
	)
	(segment
		(start 415.057082 -254.25527)
		(end 415.22015 -254.092202)
		(width 0.14478)
		(layer "In6.Cu")
		(net "M_K_CPU0_SA_CA<5>")
	)
	(segment
		(start 414.663636 -254.092202)
		(end 414.826704 -254.25527)
		(width 0.14478)
		(layer "In6.Cu")
		(net "M_K_CPU0_SA_CA<5>")
	)
	(segment
		(start 392.331448 -254.691642)
		(end 392.341862 -254.697738)
		(width 0.0889)
		(layer "In6.Cu")
		(net "M_K_CPU0_SA_CA<5>")
	)
	(segment
		(start 439.425334 -253.009908)
		(end 440.70016 -251.735082)
		(width 0.14478)
		(layer "In6.Cu")
		(net "M_K_CPU0_SA_CA<5>")
	)
	(segment
		(start 391.01776 -254.691642)
		(end 391.026142 -254.686816)
		(width 0.0889)
		(layer "In6.Cu")
		(net "M_K_CPU0_SA_CA<5>")
	)
	(segment
		(start 417.831778 -253.636018)
		(end 417.994846 -253.47295)
		(width 0.14478)
		(layer "In6.Cu")
		(net "M_K_CPU0_SA_CA<5>")
	)
	(segment
		(start 390.264904 -255.014222)
		(end 390.418828 -254.748792)
		(width 0.0889)
		(layer "In6.Cu")
		(net "M_K_CPU0_SA_CA<5>")
	)
	(segment
		(start 413.38754 -253.860046)
		(end 413.550608 -254.023114)
		(width 0.14478)
		(layer "In6.Cu")
		(net "M_K_CPU0_SA_CA<5>")
	)
	(segment
		(start 418.388292 -253.696978)
		(end 418.55136 -253.860046)
		(width 0.14478)
		(layer "In6.Cu")
		(net "M_K_CPU0_SA_CA<5>")
	)
	(segment
		(start 414.27019 -253.464822)
		(end 414.500568 -253.464822)
		(width 0.14478)
		(layer "In6.Cu")
		(net "M_K_CPU0_SA_CA<5>")
	)
	(segment
		(start 391.947146 -254.697738)
		(end 391.95756 -254.691642)
		(width 0.0889)
		(layer "In6.Cu")
		(net "M_K_CPU0_SA_CA<5>")
	)
	(segment
		(start 414.826704 -254.25527)
		(end 415.057082 -254.25527)
		(width 0.14478)
		(layer "In6.Cu")
		(net "M_K_CPU0_SA_CA<5>")
	)
	(segment
		(start 413.944054 -254.25527)
		(end 414.107122 -254.092202)
		(width 0.14478)
		(layer "In6.Cu")
		(net "M_K_CPU0_SA_CA<5>")
	)
	(segment
		(start 418.225224 -253.47295)
		(end 418.388292 -253.636018)
		(width 0.14478)
		(layer "In6.Cu")
		(net "M_K_CPU0_SA_CA<5>")
	)
	(segment
		(start 395.799564 -255.57607)
		(end 398.326864 -255.57607)
		(width 0.14478)
		(layer "In6.Cu")
		(net "M_K_CPU0_SA_CA<5>")
	)
	(segment
		(start 417.994846 -253.47295)
		(end 418.225224 -253.47295)
		(width 0.14478)
		(layer "In6.Cu")
		(net "M_K_CPU0_SA_CA<5>")
	)
	(segment
		(start 390.418828 -254.748792)
		(end 390.51484 -254.723392)
		(width 0.0889)
		(layer "In6.Cu")
		(net "M_K_CPU0_SA_CA<5>")
	)
	(segment
		(start 438.739534 -253.009908)
		(end 439.425334 -253.009908)
		(width 0.14478)
		(layer "In6.Cu")
		(net "M_K_CPU0_SA_CA<5>")
	)
	(segment
		(start 417.66871 -253.860046)
		(end 417.831778 -253.696978)
		(width 0.14478)
		(layer "In6.Cu")
		(net "M_K_CPU0_SA_CA<5>")
	)
	(segment
		(start 413.550608 -254.092202)
		(end 413.713676 -254.25527)
		(width 0.14478)
		(layer "In6.Cu")
		(net "M_K_CPU0_SA_CA<5>")
	)
	(segment
		(start 414.107122 -254.092202)
		(end 414.107122 -253.62789)
		(width 0.14478)
		(layer "In6.Cu")
		(net "M_K_CPU0_SA_CA<5>")
	)
	(segment
		(start 415.22015 -254.023114)
		(end 415.383218 -253.860046)
		(width 0.14478)
		(layer "In6.Cu")
		(net "M_K_CPU0_SA_CA<5>")
	)
	(segment
		(start 410.85008 -254.24384)
		(end 411.233874 -253.860046)
		(width 0.14478)
		(layer "In6.Cu")
		(net "M_K_CPU0_SA_CA<5>")
	)
	(segment
		(start 393.60983 -254.774192)
		(end 393.997688 -254.774192)
		(width 0.0889)
		(layer "In6.Cu")
		(net "M_K_CPU0_SA_CA<5>")
	)
	(segment
		(start 418.55136 -253.860046)
		(end 437.889396 -253.860046)
		(width 0.14478)
		(layer "In6.Cu")
		(net "M_K_CPU0_SA_CA<5>")
	)
	(segment
		(start 414.663636 -253.62789)
		(end 414.663636 -254.092202)
		(width 0.14478)
		(layer "In6.Cu")
		(net "M_K_CPU0_SA_CA<5>")
	)
	(segment
		(start 394.849096 -255.09855)
		(end 395.326616 -255.57607)
		(width 0.0889)
		(layer "In6.Cu")
		(net "M_K_CPU0_SA_CA<5>")
	)
	(segment
		(start 394.077952 -254.807466)
		(end 394.369036 -255.09855)
		(width 0.0889)
		(layer "In6.Cu")
		(net "M_K_CPU0_SA_CA<5>")
	)
	(segment
		(start 414.107122 -253.62789)
		(end 414.27019 -253.464822)
		(width 0.14478)
		(layer "In6.Cu")
		(net "M_K_CPU0_SA_CA<5>")
	)
	(segment
		(start 413.550608 -254.023114)
		(end 413.550608 -254.092202)
		(width 0.14478)
		(layer "In6.Cu")
		(net "M_K_CPU0_SA_CA<5>")
	)
	(segment
		(start 415.22015 -254.092202)
		(end 415.22015 -254.023114)
		(width 0.14478)
		(layer "In6.Cu")
		(net "M_K_CPU0_SA_CA<5>")
	)
	(segment
		(start 440.70016 -251.735082)
		(end 442.5442 -251.735082)
		(width 0.14478)
		(layer "In6.Cu")
		(net "M_K_CPU0_SA_CA<5>")
	)
	(segment
		(start 394.369036 -255.09855)
		(end 394.849096 -255.09855)
		(width 0.0889)
		(layer "In6.Cu")
		(net "M_K_CPU0_SA_CA<5>")
	)
	(segment
		(start 395.326616 -255.57607)
		(end 395.799564 -255.57607)
		(width 0.0889)
		(layer "In6.Cu")
		(net "M_K_CPU0_SA_CA<5>")
	)
	(segment
		(start 415.383218 -253.860046)
		(end 417.66871 -253.860046)
		(width 0.14478)
		(layer "In6.Cu")
		(net "M_K_CPU0_SA_CA<5>")
	)
	(segment
		(start 413.713676 -254.25527)
		(end 413.944054 -254.25527)
		(width 0.14478)
		(layer "In6.Cu")
		(net "M_K_CPU0_SA_CA<5>")
	)
	(segment
		(start 437.889396 -253.860046)
		(end 438.739534 -253.009908)
		(width 0.14478)
		(layer "In6.Cu")
		(net "M_K_CPU0_SA_CA<5>")
	)
	(segment
		(start 398.326864 -255.57607)
		(end 399.659094 -254.24384)
		(width 0.14478)
		(layer "In6.Cu")
		(net "M_K_CPU0_SA_CA<5>")
	)
	(segment
		(start 399.659094 -254.24384)
		(end 410.85008 -254.24384)
		(width 0.14478)
		(layer "In6.Cu")
		(net "M_K_CPU0_SA_CA<5>")
	)
	(segment
		(start 417.831778 -253.696978)
		(end 417.831778 -253.636018)
		(width 0.14478)
		(layer "In6.Cu")
		(net "M_K_CPU0_SA_CA<5>")
	)
	(segment
		(start 411.233874 -253.860046)
		(end 413.38754 -253.860046)
		(width 0.14478)
		(layer "In6.Cu")
		(net "M_K_CPU0_SA_CA<5>")
	)
	(segment
		(start 414.500568 -253.464822)
		(end 414.663636 -253.62789)
		(width 0.14478)
		(layer "In6.Cu")
		(net "M_K_CPU0_SA_CA<5>")
	)
	(arc
		(start 390.51484 -254.723392)
		(mid 390.770048 -254.766869)
		(end 391.01776 -254.691642)
		(width 0.0889)
		(layer "In6.Cu")
		(net "M_K_CPU0_SA_CA<5>")
	)
	(arc
		(start 393.259818 -254.684784)
		(mid 393.429207 -254.75147)
		(end 393.60983 -254.774192)
		(width 0.0889)
		(layer "In6.Cu")
		(net "M_K_CPU0_SA_CA<5>")
	)
	(arc
		(start 391.95756 -254.691642)
		(mid 392.144504 -254.641387)
		(end 392.331448 -254.691642)
		(width 0.0889)
		(layer "In6.Cu")
		(net "M_K_CPU0_SA_CA<5>")
	)
	(arc
		(start 391.391902 -254.691642)
		(mid 391.668715 -254.767785)
		(end 391.947146 -254.697738)
		(width 0.0889)
		(layer "In6.Cu")
		(net "M_K_CPU0_SA_CA<5>")
	)
	(arc
		(start 393.997688 -254.774192)
		(mid 394.041123 -254.78285)
		(end 394.077952 -254.807466)
		(width 0.0889)
		(layer "In6.Cu")
		(net "M_K_CPU0_SA_CA<5>")
	)
	(arc
		(start 392.897614 -254.691642)
		(mid 393.077819 -254.641325)
		(end 393.259818 -254.684784)
		(width 0.0889)
		(layer "In6.Cu")
		(net "M_K_CPU0_SA_CA<5>")
	)
	(arc
		(start 392.341862 -254.697738)
		(mid 392.620548 -254.767958)
		(end 392.897614 -254.691642)
		(width 0.0889)
		(layer "In6.Cu")
		(net "M_K_CPU0_SA_CA<5>")
	)
	(arc
		(start 391.026142 -254.686816)
		(mid 391.20965 -254.641322)
		(end 391.391902 -254.691642)
		(width 0.0889)
		(layer "In6.Cu")
		(net "M_K_CPU0_SA_CA<5>")
	)
	(segment
		(start 390.267952 -254.470154)
		(end 390.734804 -254.204216)
		(width 0.10668)
		(layer "F.Cu")
		(net "M_K_CPU0_SA_CA<4>")
	)
	(segment
		(start 391.861802 -254.526796)
		(end 391.872216 -254.5207)
		(width 0.0889)
		(layer "In6.Cu")
		(net "M_K_CPU0_SA_CA<4>")
	)
	(segment
		(start 398.138396 -255.12141)
		(end 399.470626 -253.78918)
		(width 0.14478)
		(layer "In6.Cu")
		(net "M_K_CPU0_SA_CA<4>")
	)
	(segment
		(start 442.142118 -251.08789)
		(end 442.307218 -251.25299)
		(width 0.14478)
		(layer "In6.Cu")
		(net "M_K_CPU0_SA_CA<4>")
	)
	(segment
		(start 442.72962 -251.31014)
		(end 442.729874 -251.309886)
		(width 0.14478)
		(layer "In6.Cu")
		(net "M_K_CPU0_SA_CA<4>")
	)
	(segment
		(start 411.367732 -253.009908)
		(end 437.889396 -253.009908)
		(width 0.14478)
		(layer "In6.Cu")
		(net "M_K_CPU0_SA_CA<4>")
	)
	(segment
		(start 442.729874 -251.309886)
		(end 446.219326 -251.309886)
		(width 0.14478)
		(layer "In6.Cu")
		(net "M_K_CPU0_SA_CA<4>")
	)
	(segment
		(start 446.219326 -251.309886)
		(end 446.644268 -250.884944)
		(width 0.14478)
		(layer "In6.Cu")
		(net "M_K_CPU0_SA_CA<4>")
	)
	(segment
		(start 438.739534 -252.15977)
		(end 439.425334 -252.15977)
		(width 0.14478)
		(layer "In6.Cu")
		(net "M_K_CPU0_SA_CA<4>")
	)
	(segment
		(start 437.889396 -253.009908)
		(end 438.739534 -252.15977)
		(width 0.14478)
		(layer "In6.Cu")
		(net "M_K_CPU0_SA_CA<4>")
	)
	(segment
		(start 393.530328 -254.563372)
		(end 394.184378 -254.563372)
		(width 0.0889)
		(layer "In6.Cu")
		(net "M_K_CPU0_SA_CA<4>")
	)
	(segment
		(start 440.497214 -251.08789)
		(end 442.142118 -251.08789)
		(width 0.14478)
		(layer "In6.Cu")
		(net "M_K_CPU0_SA_CA<4>")
	)
	(segment
		(start 390.734804 -254.204216)
		(end 390.58088 -254.469646)
		(width 0.0889)
		(layer "In6.Cu")
		(net "M_K_CPU0_SA_CA<4>")
	)
	(segment
		(start 390.58088 -254.469646)
		(end 390.603232 -254.552958)
		(width 0.0889)
		(layer "In6.Cu")
		(net "M_K_CPU0_SA_CA<4>")
	)
	(segment
		(start 442.370972 -251.31014)
		(end 442.72962 -251.31014)
		(width 0.0889)
		(layer "In6.Cu")
		(net "M_K_CPU0_SA_CA<4>")
	)
	(segment
		(start 395.054836 -254.85471)
		(end 395.321536 -255.12141)
		(width 0.0889)
		(layer "In6.Cu")
		(net "M_K_CPU0_SA_CA<4>")
	)
	(segment
		(start 394.184378 -254.563372)
		(end 394.475716 -254.85471)
		(width 0.0889)
		(layer "In6.Cu")
		(net "M_K_CPU0_SA_CA<4>")
	)
	(segment
		(start 442.313822 -251.25299)
		(end 442.370972 -251.31014)
		(width 0.0889)
		(layer "In6.Cu")
		(net "M_K_CPU0_SA_CA<4>")
	)
	(segment
		(start 392.42746 -254.526796)
		(end 392.435842 -254.531622)
		(width 0.0889)
		(layer "In6.Cu")
		(net "M_K_CPU0_SA_CA<4>")
	)
	(segment
		(start 391.85342 -254.531622)
		(end 391.861802 -254.526796)
		(width 0.0889)
		(layer "In6.Cu")
		(net "M_K_CPU0_SA_CA<4>")
	)
	(segment
		(start 395.321536 -255.12141)
		(end 395.833854 -255.12141)
		(width 0.0889)
		(layer "In6.Cu")
		(net "M_K_CPU0_SA_CA<4>")
	)
	(segment
		(start 399.470626 -253.78918)
		(end 410.58846 -253.78918)
		(width 0.14478)
		(layer "In6.Cu")
		(net "M_K_CPU0_SA_CA<4>")
	)
	(segment
		(start 395.833854 -255.12141)
		(end 398.138396 -255.12141)
		(width 0.14478)
		(layer "In6.Cu")
		(net "M_K_CPU0_SA_CA<4>")
	)
	(segment
		(start 439.425334 -252.15977)
		(end 440.497214 -251.08789)
		(width 0.14478)
		(layer "In6.Cu")
		(net "M_K_CPU0_SA_CA<4>")
	)
	(segment
		(start 394.475716 -254.85471)
		(end 395.054836 -254.85471)
		(width 0.0889)
		(layer "In6.Cu")
		(net "M_K_CPU0_SA_CA<4>")
	)
	(segment
		(start 410.58846 -253.78918)
		(end 411.367732 -253.009908)
		(width 0.14478)
		(layer "In6.Cu")
		(net "M_K_CPU0_SA_CA<4>")
	)
	(segment
		(start 442.307218 -251.25299)
		(end 442.313822 -251.25299)
		(width 0.0889)
		(layer "In6.Cu")
		(net "M_K_CPU0_SA_CA<4>")
	)
	(arc
		(start 390.603232 -254.552958)
		(mid 390.765421 -254.575693)
		(end 390.921748 -254.526796)
		(width 0.0889)
		(layer "In6.Cu")
		(net "M_K_CPU0_SA_CA<4>")
	)
	(arc
		(start 391.872216 -254.5207)
		(mid 392.150648 -254.450602)
		(end 392.42746 -254.526796)
		(width 0.0889)
		(layer "In6.Cu")
		(net "M_K_CPU0_SA_CA<4>")
	)
	(arc
		(start 391.48766 -254.526796)
		(mid 391.669911 -254.577146)
		(end 391.85342 -254.531622)
		(width 0.0889)
		(layer "In6.Cu")
		(net "M_K_CPU0_SA_CA<4>")
	)
	(arc
		(start 392.435842 -254.531622)
		(mid 392.61935 -254.577116)
		(end 392.801602 -254.526796)
		(width 0.0889)
		(layer "In6.Cu")
		(net "M_K_CPU0_SA_CA<4>")
	)
	(arc
		(start 392.801602 -254.526796)
		(mid 393.076054 -254.45056)
		(end 393.352782 -254.51816)
		(width 0.0889)
		(layer "In6.Cu")
		(net "M_K_CPU0_SA_CA<4>")
	)
	(arc
		(start 393.352782 -254.51816)
		(mid 393.43874 -254.551815)
		(end 393.530328 -254.563372)
		(width 0.0889)
		(layer "In6.Cu")
		(net "M_K_CPU0_SA_CA<4>")
	)
	(arc
		(start 390.921748 -254.526796)
		(mid 391.204704 -254.450619)
		(end 391.48766 -254.526796)
		(width 0.0889)
		(layer "In6.Cu")
		(net "M_K_CPU0_SA_CA<4>")
	)
	(segment
		(start 388.387844 -254.470154)
		(end 388.85495 -254.204216)
		(width 0.10668)
		(layer "F.Cu")
		(net "M_K_CPU0_SA_CA<3>")
	)
	(segment
		(start 393.740894 -253.881636)
		(end 393.924028 -254.06477)
		(width 0.0889)
		(layer "In6.Cu")
		(net "M_K_CPU0_SA_CA<3>")
	)
	(segment
		(start 410.193236 -253.33452)
		(end 411.367732 -252.160024)
		(width 0.14478)
		(layer "In6.Cu")
		(net "M_K_CPU0_SA_CA<3>")
	)
	(segment
		(start 388.85495 -254.204216)
		(end 389.008874 -253.938786)
		(width 0.0889)
		(layer "In6.Cu")
		(net "M_K_CPU0_SA_CA<3>")
	)
	(segment
		(start 397.949928 -254.66675)
		(end 399.282158 -253.33452)
		(width 0.14478)
		(layer "In6.Cu")
		(net "M_K_CPU0_SA_CA<3>")
	)
	(segment
		(start 395.799564 -254.66675)
		(end 397.949928 -254.66675)
		(width 0.14478)
		(layer "In6.Cu")
		(net "M_K_CPU0_SA_CA<3>")
	)
	(segment
		(start 440.326526 -250.473718)
		(end 442.105542 -250.473718)
		(width 0.14478)
		(layer "In6.Cu")
		(net "M_K_CPU0_SA_CA<3>")
	)
	(segment
		(start 393.36726 -253.88189)
		(end 393.380976 -253.874016)
		(width 0.0889)
		(layer "In6.Cu")
		(net "M_K_CPU0_SA_CA<3>")
	)
	(segment
		(start 411.367732 -252.160024)
		(end 437.889396 -252.160024)
		(width 0.14478)
		(layer "In6.Cu")
		(net "M_K_CPU0_SA_CA<3>")
	)
	(segment
		(start 389.008874 -253.938786)
		(end 389.104886 -253.913386)
		(width 0.0889)
		(layer "In6.Cu")
		(net "M_K_CPU0_SA_CA<3>")
	)
	(segment
		(start 393.924028 -254.06477)
		(end 394.828776 -254.06477)
		(width 0.0889)
		(layer "In6.Cu")
		(net "M_K_CPU0_SA_CA<3>")
	)
	(segment
		(start 392.427206 -253.881636)
		(end 392.43889 -253.874778)
		(width 0.0889)
		(layer "In6.Cu")
		(net "M_K_CPU0_SA_CA<3>")
	)
	(segment
		(start 395.430756 -254.66675)
		(end 395.799564 -254.66675)
		(width 0.0889)
		(layer "In6.Cu")
		(net "M_K_CPU0_SA_CA<3>")
	)
	(segment
		(start 442.105542 -250.473718)
		(end 442.5442 -250.03506)
		(width 0.14478)
		(layer "In6.Cu")
		(net "M_K_CPU0_SA_CA<3>")
	)
	(segment
		(start 399.282158 -253.33452)
		(end 410.193236 -253.33452)
		(width 0.14478)
		(layer "In6.Cu")
		(net "M_K_CPU0_SA_CA<3>")
	)
	(segment
		(start 394.828776 -254.06477)
		(end 395.430756 -254.66675)
		(width 0.0889)
		(layer "In6.Cu")
		(net "M_K_CPU0_SA_CA<3>")
	)
	(segment
		(start 391.861548 -253.881636)
		(end 391.871962 -253.887732)
		(width 0.0889)
		(layer "In6.Cu")
		(net "M_K_CPU0_SA_CA<3>")
	)
	(segment
		(start 439.490358 -251.309886)
		(end 440.326526 -250.473718)
		(width 0.14478)
		(layer "In6.Cu")
		(net "M_K_CPU0_SA_CA<3>")
	)
	(segment
		(start 393.355322 -253.888748)
		(end 393.36726 -253.88189)
		(width 0.0889)
		(layer "In6.Cu")
		(net "M_K_CPU0_SA_CA<3>")
	)
	(segment
		(start 437.889396 -252.160024)
		(end 438.739534 -251.309886)
		(width 0.14478)
		(layer "In6.Cu")
		(net "M_K_CPU0_SA_CA<3>")
	)
	(segment
		(start 389.607806 -253.881636)
		(end 389.616188 -253.87681)
		(width 0.0889)
		(layer "In6.Cu")
		(net "M_K_CPU0_SA_CA<3>")
	)
	(segment
		(start 438.739534 -251.309886)
		(end 439.490358 -251.309886)
		(width 0.14478)
		(layer "In6.Cu")
		(net "M_K_CPU0_SA_CA<3>")
	)
	(segment
		(start 391.849864 -253.874778)
		(end 391.861548 -253.881636)
		(width 0.0889)
		(layer "In6.Cu")
		(net "M_K_CPU0_SA_CA<3>")
	)
	(arc
		(start 392.801602 -253.881636)
		(mid 393.077534 -253.957893)
		(end 393.355322 -253.888748)
		(width 0.0889)
		(layer "In6.Cu")
		(net "M_K_CPU0_SA_CA<3>")
	)
	(arc
		(start 391.48766 -253.881636)
		(mid 391.667865 -253.831319)
		(end 391.849864 -253.874778)
		(width 0.0889)
		(layer "In6.Cu")
		(net "M_K_CPU0_SA_CA<3>")
	)
	(arc
		(start 390.921748 -253.881636)
		(mid 391.204704 -253.957813)
		(end 391.48766 -253.881636)
		(width 0.0889)
		(layer "In6.Cu")
		(net "M_K_CPU0_SA_CA<3>")
	)
	(arc
		(start 392.43889 -253.874778)
		(mid 392.621145 -253.831125)
		(end 392.801602 -253.881636)
		(width 0.0889)
		(layer "In6.Cu")
		(net "M_K_CPU0_SA_CA<3>")
	)
	(arc
		(start 389.104886 -253.913386)
		(mid 389.360094 -253.956863)
		(end 389.607806 -253.881636)
		(width 0.0889)
		(layer "In6.Cu")
		(net "M_K_CPU0_SA_CA<3>")
	)
	(arc
		(start 393.380976 -253.874016)
		(mid 393.561906 -253.831538)
		(end 393.740894 -253.881636)
		(width 0.0889)
		(layer "In6.Cu")
		(net "M_K_CPU0_SA_CA<3>")
	)
	(arc
		(start 389.616188 -253.87681)
		(mid 389.799696 -253.831316)
		(end 389.981948 -253.881636)
		(width 0.0889)
		(layer "In6.Cu")
		(net "M_K_CPU0_SA_CA<3>")
	)
	(arc
		(start 390.54786 -253.881636)
		(mid 390.734804 -253.831381)
		(end 390.921748 -253.881636)
		(width 0.0889)
		(layer "In6.Cu")
		(net "M_K_CPU0_SA_CA<3>")
	)
	(arc
		(start 391.871962 -253.887732)
		(mid 392.150394 -253.95783)
		(end 392.427206 -253.881636)
		(width 0.0889)
		(layer "In6.Cu")
		(net "M_K_CPU0_SA_CA<3>")
	)
	(arc
		(start 389.981948 -253.881636)
		(mid 390.264904 -253.957813)
		(end 390.54786 -253.881636)
		(width 0.0889)
		(layer "In6.Cu")
		(net "M_K_CPU0_SA_CA<3>")
	)
	(segment
		(start 388.857998 -253.660148)
		(end 389.32485 -253.39421)
		(width 0.10668)
		(layer "F.Cu")
		(net "M_K_CPU0_SA_CA<2>")
	)
	(segment
		(start 393.836906 -253.71679)
		(end 394.264896 -253.71679)
		(width 0.0889)
		(layer "In6.Cu")
		(net "M_K_CPU0_SA_CA<2>")
	)
	(segment
		(start 389.170926 -253.65964)
		(end 389.193278 -253.742952)
		(width 0.0889)
		(layer "In6.Cu")
		(net "M_K_CPU0_SA_CA<2>")
	)
	(segment
		(start 397.76146 -254.21209)
		(end 399.09369 -252.87986)
		(width 0.14478)
		(layer "In6.Cu")
		(net "M_K_CPU0_SA_CA<2>")
	)
	(segment
		(start 440.028838 -249.87504)
		(end 441.918344 -249.87504)
		(width 0.14478)
		(layer "In6.Cu")
		(net "M_K_CPU0_SA_CA<2>")
	)
	(segment
		(start 394.369036 -253.82093)
		(end 394.935456 -253.82093)
		(width 0.0889)
		(layer "In6.Cu")
		(net "M_K_CPU0_SA_CA<2>")
	)
	(segment
		(start 399.09369 -252.87986)
		(end 409.797758 -252.87986)
		(width 0.14478)
		(layer "In6.Cu")
		(net "M_K_CPU0_SA_CA<2>")
	)
	(segment
		(start 395.326616 -254.21209)
		(end 395.799564 -254.21209)
		(width 0.0889)
		(layer "In6.Cu")
		(net "M_K_CPU0_SA_CA<2>")
	)
	(segment
		(start 394.935456 -253.82093)
		(end 395.326616 -254.21209)
		(width 0.0889)
		(layer "In6.Cu")
		(net "M_K_CPU0_SA_CA<2>")
	)
	(segment
		(start 439.44413 -250.459748)
		(end 440.028838 -249.87504)
		(width 0.14478)
		(layer "In6.Cu")
		(net "M_K_CPU0_SA_CA<2>")
	)
	(segment
		(start 391.01776 -253.71679)
		(end 391.026142 -253.721616)
		(width 0.0889)
		(layer "In6.Cu")
		(net "M_K_CPU0_SA_CA<2>")
	)
	(segment
		(start 446.21958 -249.609864)
		(end 446.644268 -249.185176)
		(width 0.14478)
		(layer "In6.Cu")
		(net "M_K_CPU0_SA_CA<2>")
	)
	(segment
		(start 395.799564 -254.21209)
		(end 397.76146 -254.21209)
		(width 0.14478)
		(layer "In6.Cu")
		(net "M_K_CPU0_SA_CA<2>")
	)
	(segment
		(start 442.18352 -249.609864)
		(end 446.21958 -249.609864)
		(width 0.14478)
		(layer "In6.Cu")
		(net "M_K_CPU0_SA_CA<2>")
	)
	(segment
		(start 391.947146 -253.710694)
		(end 391.95756 -253.71679)
		(width 0.0889)
		(layer "In6.Cu")
		(net "M_K_CPU0_SA_CA<2>")
	)
	(segment
		(start 392.331194 -253.71679)
		(end 392.341608 -253.710694)
		(width 0.0889)
		(layer "In6.Cu")
		(net "M_K_CPU0_SA_CA<2>")
	)
	(segment
		(start 393.253214 -253.72695)
		(end 393.271502 -253.716536)
		(width 0.0889)
		(layer "In6.Cu")
		(net "M_K_CPU0_SA_CA<2>")
	)
	(segment
		(start 441.918344 -249.87504)
		(end 442.18352 -249.609864)
		(width 0.14478)
		(layer "In6.Cu")
		(net "M_K_CPU0_SA_CA<2>")
	)
	(segment
		(start 438.739534 -250.459748)
		(end 439.44413 -250.459748)
		(width 0.14478)
		(layer "In6.Cu")
		(net "M_K_CPU0_SA_CA<2>")
	)
	(segment
		(start 409.797758 -252.87986)
		(end 411.367732 -251.309886)
		(width 0.14478)
		(layer "In6.Cu")
		(net "M_K_CPU0_SA_CA<2>")
	)
	(segment
		(start 393.271502 -253.716536)
		(end 393.27709 -253.713234)
		(width 0.0889)
		(layer "In6.Cu")
		(net "M_K_CPU0_SA_CA<2>")
	)
	(segment
		(start 394.264896 -253.71679)
		(end 394.369036 -253.82093)
		(width 0.0889)
		(layer "In6.Cu")
		(net "M_K_CPU0_SA_CA<2>")
	)
	(segment
		(start 437.889396 -251.309886)
		(end 438.739534 -250.459748)
		(width 0.14478)
		(layer "In6.Cu")
		(net "M_K_CPU0_SA_CA<2>")
	)
	(segment
		(start 391.95756 -253.71679)
		(end 391.965942 -253.721616)
		(width 0.0889)
		(layer "In6.Cu")
		(net "M_K_CPU0_SA_CA<2>")
	)
	(segment
		(start 390.443466 -253.721616)
		(end 390.451848 -253.71679)
		(width 0.0889)
		(layer "In6.Cu")
		(net "M_K_CPU0_SA_CA<2>")
	)
	(segment
		(start 411.367732 -251.309886)
		(end 437.889396 -251.309886)
		(width 0.14478)
		(layer "In6.Cu")
		(net "M_K_CPU0_SA_CA<2>")
	)
	(segment
		(start 389.32485 -253.39421)
		(end 389.170926 -253.65964)
		(width 0.0889)
		(layer "In6.Cu")
		(net "M_K_CPU0_SA_CA<2>")
	)
	(arc
		(start 390.077706 -253.71679)
		(mid 390.259957 -253.76714)
		(end 390.443466 -253.721616)
		(width 0.0889)
		(layer "In6.Cu")
		(net "M_K_CPU0_SA_CA<2>")
	)
	(arc
		(start 389.511794 -253.71679)
		(mid 389.79475 -253.640613)
		(end 390.077706 -253.71679)
		(width 0.0889)
		(layer "In6.Cu")
		(net "M_K_CPU0_SA_CA<2>")
	)
	(arc
		(start 389.193278 -253.742952)
		(mid 389.355467 -253.765687)
		(end 389.511794 -253.71679)
		(width 0.0889)
		(layer "In6.Cu")
		(net "M_K_CPU0_SA_CA<2>")
	)
	(arc
		(start 390.451848 -253.71679)
		(mid 390.734804 -253.640613)
		(end 391.01776 -253.71679)
		(width 0.0889)
		(layer "In6.Cu")
		(net "M_K_CPU0_SA_CA<2>")
	)
	(arc
		(start 393.27709 -253.713234)
		(mid 393.557479 -253.640565)
		(end 393.836906 -253.71679)
		(width 0.0889)
		(layer "In6.Cu")
		(net "M_K_CPU0_SA_CA<2>")
	)
	(arc
		(start 391.965942 -253.721616)
		(mid 392.149196 -253.766989)
		(end 392.331194 -253.71679)
		(width 0.0889)
		(layer "In6.Cu")
		(net "M_K_CPU0_SA_CA<2>")
	)
	(arc
		(start 391.391902 -253.71679)
		(mid 391.668715 -253.640647)
		(end 391.947146 -253.710694)
		(width 0.0889)
		(layer "In6.Cu")
		(net "M_K_CPU0_SA_CA<2>")
	)
	(arc
		(start 391.026142 -253.721616)
		(mid 391.20965 -253.76711)
		(end 391.391902 -253.71679)
		(width 0.0889)
		(layer "In6.Cu")
		(net "M_K_CPU0_SA_CA<2>")
	)
	(arc
		(start 392.341608 -253.710694)
		(mid 392.620294 -253.640474)
		(end 392.89736 -253.71679)
		(width 0.0889)
		(layer "In6.Cu")
		(net "M_K_CPU0_SA_CA<2>")
	)
	(arc
		(start 392.89736 -253.71679)
		(mid 393.073988 -253.767023)
		(end 393.253214 -253.72695)
		(width 0.0889)
		(layer "In6.Cu")
		(net "M_K_CPU0_SA_CA<2>")
	)
	(segment
		(start 389.798052 -253.660148)
		(end 390.264904 -253.39421)
		(width 0.10668)
		(layer "F.Cu")
		(net "M_K_CPU0_SA_CA<1>")
	)
	(segment
		(start 394.007086 -253.13386)
		(end 394.44549 -253.572264)
		(width 0.0889)
		(layer "In6.Cu")
		(net "M_K_CPU0_SA_CA<1>")
	)
	(segment
		(start 395.810994 -253.75743)
		(end 397.572992 -253.75743)
		(width 0.14478)
		(layer "In6.Cu")
		(net "M_K_CPU0_SA_CA<1>")
	)
	(segment
		(start 414.812988 -250.231402)
		(end 414.812988 -250.688602)
		(width 0.14478)
		(layer "In6.Cu")
		(net "M_K_CPU0_SA_CA<1>")
	)
	(segment
		(start 437.889396 -250.460002)
		(end 438.739534 -249.609864)
		(width 0.14478)
		(layer "In6.Cu")
		(net "M_K_CPU0_SA_CA<1>")
	)
	(segment
		(start 398.905222 -252.4252)
		(end 409.402534 -252.4252)
		(width 0.14478)
		(layer "In6.Cu")
		(net "M_K_CPU0_SA_CA<1>")
	)
	(segment
		(start 414.64992 -250.068334)
		(end 414.812988 -250.231402)
		(width 0.14478)
		(layer "In6.Cu")
		(net "M_K_CPU0_SA_CA<1>")
	)
	(segment
		(start 392.331448 -253.07163)
		(end 392.341862 -253.077726)
		(width 0.0889)
		(layer "In6.Cu")
		(net "M_K_CPU0_SA_CA<1>")
	)
	(segment
		(start 439.498486 -249.609864)
		(end 439.95086 -249.15749)
		(width 0.14478)
		(layer "In6.Cu")
		(net "M_K_CPU0_SA_CA<1>")
	)
	(segment
		(start 414.256474 -250.231402)
		(end 414.419542 -250.068334)
		(width 0.14478)
		(layer "In6.Cu")
		(net "M_K_CPU0_SA_CA<1>")
	)
	(segment
		(start 438.739534 -249.609864)
		(end 439.498486 -249.609864)
		(width 0.14478)
		(layer "In6.Cu")
		(net "M_K_CPU0_SA_CA<1>")
	)
	(segment
		(start 439.95086 -249.15749)
		(end 441.721748 -249.15749)
		(width 0.14478)
		(layer "In6.Cu")
		(net "M_K_CPU0_SA_CA<1>")
	)
	(segment
		(start 414.419542 -250.068334)
		(end 414.64992 -250.068334)
		(width 0.14478)
		(layer "In6.Cu")
		(net "M_K_CPU0_SA_CA<1>")
	)
	(segment
		(start 415.369502 -250.688602)
		(end 415.369502 -250.62307)
		(width 0.14478)
		(layer "In6.Cu")
		(net "M_K_CPU0_SA_CA<1>")
	)
	(segment
		(start 415.53257 -250.460002)
		(end 437.889396 -250.460002)
		(width 0.14478)
		(layer "In6.Cu")
		(net "M_K_CPU0_SA_CA<1>")
	)
	(segment
		(start 409.402534 -252.4252)
		(end 411.367732 -250.460002)
		(width 0.14478)
		(layer "In6.Cu")
		(net "M_K_CPU0_SA_CA<1>")
	)
	(segment
		(start 395.15415 -253.572264)
		(end 395.339316 -253.75743)
		(width 0.0889)
		(layer "In6.Cu")
		(net "M_K_CPU0_SA_CA<1>")
	)
	(segment
		(start 414.093406 -250.85167)
		(end 414.256474 -250.688602)
		(width 0.14478)
		(layer "In6.Cu")
		(net "M_K_CPU0_SA_CA<1>")
	)
	(segment
		(start 390.418828 -253.12878)
		(end 390.51484 -253.10338)
		(width 0.0889)
		(layer "In6.Cu")
		(net "M_K_CPU0_SA_CA<1>")
	)
	(segment
		(start 413.863028 -250.85167)
		(end 414.093406 -250.85167)
		(width 0.14478)
		(layer "In6.Cu")
		(net "M_K_CPU0_SA_CA<1>")
	)
	(segment
		(start 397.572992 -253.75743)
		(end 398.905222 -252.4252)
		(width 0.14478)
		(layer "In6.Cu")
		(net "M_K_CPU0_SA_CA<1>")
	)
	(segment
		(start 395.339316 -253.75743)
		(end 395.810994 -253.75743)
		(width 0.0889)
		(layer "In6.Cu")
		(net "M_K_CPU0_SA_CA<1>")
	)
	(segment
		(start 414.256474 -250.688602)
		(end 414.256474 -250.231402)
		(width 0.14478)
		(layer "In6.Cu")
		(net "M_K_CPU0_SA_CA<1>")
	)
	(segment
		(start 413.536892 -250.460002)
		(end 413.69996 -250.62307)
		(width 0.14478)
		(layer "In6.Cu")
		(net "M_K_CPU0_SA_CA<1>")
	)
	(segment
		(start 411.367732 -250.460002)
		(end 413.536892 -250.460002)
		(width 0.14478)
		(layer "In6.Cu")
		(net "M_K_CPU0_SA_CA<1>")
	)
	(segment
		(start 391.01776 -253.07163)
		(end 391.026142 -253.066804)
		(width 0.0889)
		(layer "In6.Cu")
		(net "M_K_CPU0_SA_CA<1>")
	)
	(segment
		(start 415.369502 -250.62307)
		(end 415.53257 -250.460002)
		(width 0.14478)
		(layer "In6.Cu")
		(net "M_K_CPU0_SA_CA<1>")
	)
	(segment
		(start 390.264904 -253.39421)
		(end 390.418828 -253.12878)
		(width 0.0889)
		(layer "In6.Cu")
		(net "M_K_CPU0_SA_CA<1>")
	)
	(segment
		(start 413.69996 -250.62307)
		(end 413.69996 -250.688602)
		(width 0.14478)
		(layer "In6.Cu")
		(net "M_K_CPU0_SA_CA<1>")
	)
	(segment
		(start 413.69996 -250.688602)
		(end 413.863028 -250.85167)
		(width 0.14478)
		(layer "In6.Cu")
		(net "M_K_CPU0_SA_CA<1>")
	)
	(segment
		(start 414.976056 -250.85167)
		(end 415.206434 -250.85167)
		(width 0.14478)
		(layer "In6.Cu")
		(net "M_K_CPU0_SA_CA<1>")
	)
	(segment
		(start 414.812988 -250.688602)
		(end 414.976056 -250.85167)
		(width 0.14478)
		(layer "In6.Cu")
		(net "M_K_CPU0_SA_CA<1>")
	)
	(segment
		(start 441.721748 -249.15749)
		(end 442.5442 -248.335038)
		(width 0.14478)
		(layer "In6.Cu")
		(net "M_K_CPU0_SA_CA<1>")
	)
	(segment
		(start 393.530074 -253.13386)
		(end 394.007086 -253.13386)
		(width 0.0889)
		(layer "In6.Cu")
		(net "M_K_CPU0_SA_CA<1>")
	)
	(segment
		(start 394.44549 -253.572264)
		(end 395.15415 -253.572264)
		(width 0.0889)
		(layer "In6.Cu")
		(net "M_K_CPU0_SA_CA<1>")
	)
	(segment
		(start 391.947146 -253.077726)
		(end 391.95756 -253.07163)
		(width 0.0889)
		(layer "In6.Cu")
		(net "M_K_CPU0_SA_CA<1>")
	)
	(segment
		(start 415.206434 -250.85167)
		(end 415.369502 -250.688602)
		(width 0.14478)
		(layer "In6.Cu")
		(net "M_K_CPU0_SA_CA<1>")
	)
	(arc
		(start 392.341862 -253.077726)
		(mid 392.620548 -253.147946)
		(end 392.897614 -253.07163)
		(width 0.0889)
		(layer "In6.Cu")
		(net "M_K_CPU0_SA_CA<1>")
	)
	(arc
		(start 392.897614 -253.07163)
		(mid 393.077819 -253.021313)
		(end 393.259818 -253.064772)
		(width 0.0889)
		(layer "In6.Cu")
		(net "M_K_CPU0_SA_CA<1>")
	)
	(arc
		(start 393.259818 -253.064772)
		(mid 393.390608 -253.116283)
		(end 393.530074 -253.13386)
		(width 0.0889)
		(layer "In6.Cu")
		(net "M_K_CPU0_SA_CA<1>")
	)
	(arc
		(start 391.95756 -253.07163)
		(mid 392.144504 -253.021375)
		(end 392.331448 -253.07163)
		(width 0.0889)
		(layer "In6.Cu")
		(net "M_K_CPU0_SA_CA<1>")
	)
	(arc
		(start 391.026142 -253.066804)
		(mid 391.20965 -253.02131)
		(end 391.391902 -253.07163)
		(width 0.0889)
		(layer "In6.Cu")
		(net "M_K_CPU0_SA_CA<1>")
	)
	(arc
		(start 390.51484 -253.10338)
		(mid 390.770048 -253.146857)
		(end 391.01776 -253.07163)
		(width 0.0889)
		(layer "In6.Cu")
		(net "M_K_CPU0_SA_CA<1>")
	)
	(arc
		(start 391.391902 -253.07163)
		(mid 391.668715 -253.147773)
		(end 391.947146 -253.077726)
		(width 0.0889)
		(layer "In6.Cu")
		(net "M_K_CPU0_SA_CA<1>")
	)
	(segment
		(start 390.267952 -252.850142)
		(end 390.734804 -252.584204)
		(width 0.10668)
		(layer "F.Cu")
		(net "M_K_CPU0_SA_CA<0>")
	)
	(segment
		(start 394.238226 -252.94336)
		(end 394.597636 -253.30277)
		(width 0.0889)
		(layer "In6.Cu")
		(net "M_K_CPU0_SA_CA<0>")
	)
	(segment
		(start 391.85342 -252.91161)
		(end 391.861802 -252.906784)
		(width 0.0889)
		(layer "In6.Cu")
		(net "M_K_CPU0_SA_CA<0>")
	)
	(segment
		(start 437.889396 -249.610118)
		(end 438.739534 -248.75998)
		(width 0.14478)
		(layer "In6.Cu")
		(net "M_K_CPU0_SA_CA<0>")
	)
	(segment
		(start 446.21958 -247.909842)
		(end 446.644268 -247.485154)
		(width 0.14478)
		(layer "In6.Cu")
		(net "M_K_CPU0_SA_CA<0>")
	)
	(segment
		(start 392.42746 -252.906784)
		(end 392.435842 -252.91161)
		(width 0.0889)
		(layer "In6.Cu")
		(net "M_K_CPU0_SA_CA<0>")
	)
	(segment
		(start 409.00731 -251.97054)
		(end 411.367732 -249.610118)
		(width 0.14478)
		(layer "In6.Cu")
		(net "M_K_CPU0_SA_CA<0>")
	)
	(segment
		(start 438.739534 -248.75998)
		(end 439.442098 -248.75998)
		(width 0.14478)
		(layer "In6.Cu")
		(net "M_K_CPU0_SA_CA<0>")
	)
	(segment
		(start 411.367732 -249.610118)
		(end 437.889396 -249.610118)
		(width 0.14478)
		(layer "In6.Cu")
		(net "M_K_CPU0_SA_CA<0>")
	)
	(segment
		(start 395.816836 -253.30277)
		(end 397.384524 -253.30277)
		(width 0.14478)
		(layer "In6.Cu")
		(net "M_K_CPU0_SA_CA<0>")
	)
	(segment
		(start 391.861802 -252.906784)
		(end 391.872216 -252.900688)
		(width 0.0889)
		(layer "In6.Cu")
		(net "M_K_CPU0_SA_CA<0>")
	)
	(segment
		(start 439.442098 -248.75998)
		(end 439.753502 -248.448576)
		(width 0.14478)
		(layer "In6.Cu")
		(net "M_K_CPU0_SA_CA<0>")
	)
	(segment
		(start 390.734804 -252.584204)
		(end 390.58088 -252.849634)
		(width 0.0889)
		(layer "In6.Cu")
		(net "M_K_CPU0_SA_CA<0>")
	)
	(segment
		(start 397.384524 -253.30277)
		(end 398.716754 -251.97054)
		(width 0.14478)
		(layer "In6.Cu")
		(net "M_K_CPU0_SA_CA<0>")
	)
	(segment
		(start 394.597636 -253.30277)
		(end 395.816836 -253.30277)
		(width 0.0889)
		(layer "In6.Cu")
		(net "M_K_CPU0_SA_CA<0>")
	)
	(segment
		(start 441.644786 -248.448576)
		(end 442.18352 -247.909842)
		(width 0.14478)
		(layer "In6.Cu")
		(net "M_K_CPU0_SA_CA<0>")
	)
	(segment
		(start 390.58088 -252.849634)
		(end 390.603232 -252.932946)
		(width 0.0889)
		(layer "In6.Cu")
		(net "M_K_CPU0_SA_CA<0>")
	)
	(segment
		(start 393.530328 -252.94336)
		(end 394.238226 -252.94336)
		(width 0.0889)
		(layer "In6.Cu")
		(net "M_K_CPU0_SA_CA<0>")
	)
	(segment
		(start 442.18352 -247.909842)
		(end 446.21958 -247.909842)
		(width 0.14478)
		(layer "In6.Cu")
		(net "M_K_CPU0_SA_CA<0>")
	)
	(segment
		(start 398.716754 -251.97054)
		(end 409.00731 -251.97054)
		(width 0.14478)
		(layer "In6.Cu")
		(net "M_K_CPU0_SA_CA<0>")
	)
	(segment
		(start 439.753502 -248.448576)
		(end 441.644786 -248.448576)
		(width 0.14478)
		(layer "In6.Cu")
		(net "M_K_CPU0_SA_CA<0>")
	)
	(arc
		(start 393.352782 -252.898148)
		(mid 393.43874 -252.931803)
		(end 393.530328 -252.94336)
		(width 0.0889)
		(layer "In6.Cu")
		(net "M_K_CPU0_SA_CA<0>")
	)
	(arc
		(start 391.872216 -252.900688)
		(mid 392.150648 -252.83059)
		(end 392.42746 -252.906784)
		(width 0.0889)
		(layer "In6.Cu")
		(net "M_K_CPU0_SA_CA<0>")
	)
	(arc
		(start 390.921748 -252.906784)
		(mid 391.204704 -252.830607)
		(end 391.48766 -252.906784)
		(width 0.0889)
		(layer "In6.Cu")
		(net "M_K_CPU0_SA_CA<0>")
	)
	(arc
		(start 392.801602 -252.906784)
		(mid 393.076054 -252.830548)
		(end 393.352782 -252.898148)
		(width 0.0889)
		(layer "In6.Cu")
		(net "M_K_CPU0_SA_CA<0>")
	)
	(arc
		(start 392.435842 -252.91161)
		(mid 392.61935 -252.957104)
		(end 392.801602 -252.906784)
		(width 0.0889)
		(layer "In6.Cu")
		(net "M_K_CPU0_SA_CA<0>")
	)
	(arc
		(start 391.48766 -252.906784)
		(mid 391.669911 -252.957134)
		(end 391.85342 -252.91161)
		(width 0.0889)
		(layer "In6.Cu")
		(net "M_K_CPU0_SA_CA<0>")
	)
	(arc
		(start 390.603232 -252.932946)
		(mid 390.765421 -252.955681)
		(end 390.921748 -252.906784)
		(width 0.0889)
		(layer "In6.Cu")
		(net "M_K_CPU0_SA_CA<0>")
	)
	(segment
		(start 388.387844 -251.23013)
		(end 388.85495 -250.964192)
		(width 0.10668)
		(layer "F.Cu")
		(net "M_K_CPU0_RESET_N")
	)
	(segment
		(start 389.607806 -250.641612)
		(end 389.616188 -250.636786)
		(width 0.0889)
		(layer "In6.Cu")
		(net "M_K_CPU0_RESET_N")
	)
	(segment
		(start 393.084812 -250.717812)
		(end 393.306808 -250.717812)
		(width 0.0889)
		(layer "In6.Cu")
		(net "M_K_CPU0_RESET_N")
	)
	(segment
		(start 393.636246 -251.04725)
		(end 393.962636 -251.04725)
		(width 0.0889)
		(layer "In6.Cu")
		(net "M_K_CPU0_RESET_N")
	)
	(segment
		(start 411.137608 -247.059958)
		(end 437.240426 -247.059958)
		(width 0.11684)
		(layer "In6.Cu")
		(net "M_K_CPU0_RESET_N")
	)
	(segment
		(start 389.008874 -250.698762)
		(end 389.104886 -250.673362)
		(width 0.0889)
		(layer "In6.Cu")
		(net "M_K_CPU0_RESET_N")
	)
	(segment
		(start 391.849864 -250.634754)
		(end 391.861548 -250.641612)
		(width 0.0889)
		(layer "In6.Cu")
		(net "M_K_CPU0_RESET_N")
	)
	(segment
		(start 391.861548 -250.641612)
		(end 391.871962 -250.647708)
		(width 0.0889)
		(layer "In6.Cu")
		(net "M_K_CPU0_RESET_N")
	)
	(segment
		(start 393.306808 -250.717812)
		(end 393.636246 -251.04725)
		(width 0.0889)
		(layer "In6.Cu")
		(net "M_K_CPU0_RESET_N")
	)
	(segment
		(start 396.692628 -251.63399)
		(end 398.024858 -250.30176)
		(width 0.11684)
		(layer "In6.Cu")
		(net "M_K_CPU0_RESET_N")
	)
	(segment
		(start 439.454544 -246.210074)
		(end 440.729624 -244.934994)
		(width 0.11684)
		(layer "In6.Cu")
		(net "M_K_CPU0_RESET_N")
	)
	(segment
		(start 392.427206 -250.641612)
		(end 392.43889 -250.634754)
		(width 0.0889)
		(layer "In6.Cu")
		(net "M_K_CPU0_RESET_N")
	)
	(segment
		(start 394.549376 -251.63399)
		(end 395.685264 -251.63399)
		(width 0.0889)
		(layer "In6.Cu")
		(net "M_K_CPU0_RESET_N")
	)
	(segment
		(start 398.024858 -250.30176)
		(end 407.895806 -250.30176)
		(width 0.11684)
		(layer "In6.Cu")
		(net "M_K_CPU0_RESET_N")
	)
	(segment
		(start 393.962636 -251.04725)
		(end 394.549376 -251.63399)
		(width 0.0889)
		(layer "In6.Cu")
		(net "M_K_CPU0_RESET_N")
	)
	(segment
		(start 388.85495 -250.964192)
		(end 389.008874 -250.698762)
		(width 0.0889)
		(layer "In6.Cu")
		(net "M_K_CPU0_RESET_N")
	)
	(segment
		(start 407.895806 -250.30176)
		(end 411.137608 -247.059958)
		(width 0.11684)
		(layer "In6.Cu")
		(net "M_K_CPU0_RESET_N")
	)
	(segment
		(start 437.240426 -247.059958)
		(end 438.09031 -246.210074)
		(width 0.11684)
		(layer "In6.Cu")
		(net "M_K_CPU0_RESET_N")
	)
	(segment
		(start 395.685264 -251.63399)
		(end 396.692628 -251.63399)
		(width 0.11684)
		(layer "In6.Cu")
		(net "M_K_CPU0_RESET_N")
	)
	(segment
		(start 438.09031 -246.210074)
		(end 439.454544 -246.210074)
		(width 0.11684)
		(layer "In6.Cu")
		(net "M_K_CPU0_RESET_N")
	)
	(segment
		(start 440.729624 -244.934994)
		(end 442.5442 -244.934994)
		(width 0.11684)
		(layer "In6.Cu")
		(net "M_K_CPU0_RESET_N")
	)
	(arc
		(start 389.981948 -250.641612)
		(mid 390.264904 -250.717789)
		(end 390.54786 -250.641612)
		(width 0.0889)
		(layer "In6.Cu")
		(net "M_K_CPU0_RESET_N")
	)
	(arc
		(start 390.54786 -250.641612)
		(mid 390.734804 -250.591357)
		(end 390.921748 -250.641612)
		(width 0.0889)
		(layer "In6.Cu")
		(net "M_K_CPU0_RESET_N")
	)
	(arc
		(start 392.43889 -250.634754)
		(mid 392.621145 -250.591101)
		(end 392.801602 -250.641612)
		(width 0.0889)
		(layer "In6.Cu")
		(net "M_K_CPU0_RESET_N")
	)
	(arc
		(start 391.871962 -250.647708)
		(mid 392.150394 -250.717806)
		(end 392.427206 -250.641612)
		(width 0.0889)
		(layer "In6.Cu")
		(net "M_K_CPU0_RESET_N")
	)
	(arc
		(start 389.104886 -250.673362)
		(mid 389.360094 -250.716839)
		(end 389.607806 -250.641612)
		(width 0.0889)
		(layer "In6.Cu")
		(net "M_K_CPU0_RESET_N")
	)
	(arc
		(start 391.48766 -250.641612)
		(mid 391.667865 -250.591295)
		(end 391.849864 -250.634754)
		(width 0.0889)
		(layer "In6.Cu")
		(net "M_K_CPU0_RESET_N")
	)
	(arc
		(start 389.616188 -250.636786)
		(mid 389.799696 -250.591292)
		(end 389.981948 -250.641612)
		(width 0.0889)
		(layer "In6.Cu")
		(net "M_K_CPU0_RESET_N")
	)
	(arc
		(start 390.921748 -250.641612)
		(mid 391.204704 -250.717789)
		(end 391.48766 -250.641612)
		(width 0.0889)
		(layer "In6.Cu")
		(net "M_K_CPU0_RESET_N")
	)
	(arc
		(start 392.801602 -250.641612)
		(mid 392.938165 -250.698445)
		(end 393.084812 -250.717812)
		(width 0.0889)
		(layer "In6.Cu")
		(net "M_K_CPU0_RESET_N")
	)
	(segment
		(start 390.267952 -256.090166)
		(end 390.734804 -255.824228)
		(width 0.14732)
		(layer "F.Cu")
		(net "M_K_CPU0_CLK_DP<0>")
	)
	(segment
		(start 407.849324 -257.04165)
		(end 407.849324 -257.738372)
		(width 0.16002)
		(layer "In6.Cu")
		(net "M_K_CPU0_CLK_DP<0>")
	)
	(segment
		(start 392.425936 -256.149348)
		(end 392.434318 -256.154174)
		(width 0.09525)
		(layer "In6.Cu")
		(net "M_K_CPU0_CLK_DP<0>")
	)
	(segment
		(start 408.619198 -257.738372)
		(end 408.619198 -257.04165)
		(width 0.16002)
		(layer "In6.Cu")
		(net "M_K_CPU0_CLK_DP<0>")
	)
	(segment
		(start 411.100524 -256.704592)
		(end 436.702708 -256.704592)
		(width 0.16002)
		(layer "In6.Cu")
		(net "M_K_CPU0_CLK_DP<0>")
	)
	(segment
		(start 410.763466 -257.738372)
		(end 410.763466 -257.04165)
		(width 0.16002)
		(layer "In6.Cu")
		(net "M_K_CPU0_CLK_DP<0>")
	)
	(segment
		(start 438.669938 -256.704592)
		(end 441.664598 -253.709932)
		(width 0.16002)
		(layer "In6.Cu")
		(net "M_K_CPU0_CLK_DP<0>")
	)
	(segment
		(start 408.619198 -257.04165)
		(end 408.956256 -256.704592)
		(width 0.16002)
		(layer "In6.Cu")
		(net "M_K_CPU0_CLK_DP<0>")
	)
	(segment
		(start 393.351258 -256.140712)
		(end 393.36599 -256.149348)
		(width 0.09525)
		(layer "In6.Cu")
		(net "M_K_CPU0_CLK_DP<0>")
	)
	(segment
		(start 390.734804 -255.824228)
		(end 390.58088 -256.089658)
		(width 0.09525)
		(layer "In6.Cu")
		(net "M_K_CPU0_CLK_DP<0>")
	)
	(segment
		(start 398.947132 -257.17627)
		(end 400.309842 -255.81356)
		(width 0.16002)
		(layer "In6.Cu")
		(net "M_K_CPU0_CLK_DP<0>")
	)
	(segment
		(start 409.656534 -256.704592)
		(end 409.993592 -257.04165)
		(width 0.16002)
		(layer "In6.Cu")
		(net "M_K_CPU0_CLK_DP<0>")
	)
	(segment
		(start 406.128474 -255.81356)
		(end 407.019506 -256.704592)
		(width 0.16002)
		(layer "In6.Cu")
		(net "M_K_CPU0_CLK_DP<0>")
	)
	(segment
		(start 407.849324 -257.738372)
		(end 408.009344 -257.898392)
		(width 0.16002)
		(layer "In6.Cu")
		(net "M_K_CPU0_CLK_DP<0>")
	)
	(segment
		(start 400.309842 -255.81356)
		(end 406.128474 -255.81356)
		(width 0.16002)
		(layer "In6.Cu")
		(net "M_K_CPU0_CLK_DP<0>")
	)
	(segment
		(start 408.009344 -257.898392)
		(end 408.459178 -257.898392)
		(width 0.16002)
		(layer "In6.Cu")
		(net "M_K_CPU0_CLK_DP<0>")
	)
	(segment
		(start 390.58088 -256.089658)
		(end 390.603994 -256.176272)
		(width 0.09525)
		(layer "In6.Cu")
		(net "M_K_CPU0_CLK_DP<0>")
	)
	(segment
		(start 436.702708 -256.704592)
		(end 436.829708 -256.577592)
		(width 0.16002)
		(layer "In6.Cu")
		(net "M_K_CPU0_CLK_DP<0>")
	)
	(segment
		(start 442.269372 -253.709932)
		(end 442.5442 -253.435104)
		(width 0.16002)
		(layer "In6.Cu")
		(net "M_K_CPU0_CLK_DP<0>")
	)
	(segment
		(start 410.603446 -257.898392)
		(end 410.763466 -257.738372)
		(width 0.16002)
		(layer "In6.Cu")
		(net "M_K_CPU0_CLK_DP<0>")
	)
	(segment
		(start 410.153612 -257.898392)
		(end 410.603446 -257.898392)
		(width 0.16002)
		(layer "In6.Cu")
		(net "M_K_CPU0_CLK_DP<0>")
	)
	(segment
		(start 407.019506 -256.704592)
		(end 407.512266 -256.704592)
		(width 0.16002)
		(layer "In6.Cu")
		(net "M_K_CPU0_CLK_DP<0>")
	)
	(segment
		(start 409.993592 -257.738372)
		(end 410.153612 -257.898392)
		(width 0.16002)
		(layer "In6.Cu")
		(net "M_K_CPU0_CLK_DP<0>")
	)
	(segment
		(start 437.436768 -256.704592)
		(end 438.669938 -256.704592)
		(width 0.16002)
		(layer "In6.Cu")
		(net "M_K_CPU0_CLK_DP<0>")
	)
	(segment
		(start 407.512266 -256.704592)
		(end 407.849324 -257.04165)
		(width 0.16002)
		(layer "In6.Cu")
		(net "M_K_CPU0_CLK_DP<0>")
	)
	(segment
		(start 408.956256 -256.704592)
		(end 409.656534 -256.704592)
		(width 0.16002)
		(layer "In6.Cu")
		(net "M_K_CPU0_CLK_DP<0>")
	)
	(segment
		(start 436.829708 -256.577592)
		(end 437.309768 -256.577592)
		(width 0.16002)
		(layer "In6.Cu")
		(net "M_K_CPU0_CLK_DP<0>")
	)
	(segment
		(start 437.309768 -256.577592)
		(end 437.436768 -256.704592)
		(width 0.16002)
		(layer "In6.Cu")
		(net "M_K_CPU0_CLK_DP<0>")
	)
	(segment
		(start 391.854944 -256.154174)
		(end 391.863326 -256.149348)
		(width 0.09525)
		(layer "In6.Cu")
		(net "M_K_CPU0_CLK_DP<0>")
	)
	(segment
		(start 410.763466 -257.04165)
		(end 411.100524 -256.704592)
		(width 0.16002)
		(layer "In6.Cu")
		(net "M_K_CPU0_CLK_DP<0>")
	)
	(segment
		(start 393.481052 -256.237994)
		(end 394.47851 -257.235452)
		(width 0.09525)
		(layer "In6.Cu")
		(net "M_K_CPU0_CLK_DP<0>")
	)
	(segment
		(start 408.459178 -257.898392)
		(end 408.619198 -257.738372)
		(width 0.16002)
		(layer "In6.Cu")
		(net "M_K_CPU0_CLK_DP<0>")
	)
	(segment
		(start 395.389354 -257.235452)
		(end 395.448536 -257.17627)
		(width 0.09525)
		(layer "In6.Cu")
		(net "M_K_CPU0_CLK_DP<0>")
	)
	(segment
		(start 395.472158 -257.17627)
		(end 398.947132 -257.17627)
		(width 0.16002)
		(layer "In6.Cu")
		(net "M_K_CPU0_CLK_DP<0>")
	)
	(segment
		(start 394.47851 -257.235452)
		(end 395.389354 -257.235452)
		(width 0.09525)
		(layer "In6.Cu")
		(net "M_K_CPU0_CLK_DP<0>")
	)
	(segment
		(start 395.448536 -257.17627)
		(end 395.472158 -257.17627)
		(width 0.09525)
		(layer "In6.Cu")
		(net "M_K_CPU0_CLK_DP<0>")
	)
	(segment
		(start 441.664598 -253.709932)
		(end 442.269372 -253.709932)
		(width 0.16002)
		(layer "In6.Cu")
		(net "M_K_CPU0_CLK_DP<0>")
	)
	(segment
		(start 409.993592 -257.04165)
		(end 409.993592 -257.738372)
		(width 0.16002)
		(layer "In6.Cu")
		(net "M_K_CPU0_CLK_DP<0>")
	)
	(segment
		(start 392.415522 -256.143252)
		(end 392.425936 -256.149348)
		(width 0.09525)
		(layer "In6.Cu")
		(net "M_K_CPU0_CLK_DP<0>")
	)
	(arc
		(start 392.803126 -256.149348)
		(mid 393.076054 -256.073534)
		(end 393.351258 -256.140712)
		(width 0.09525)
		(layer "In6.Cu")
		(net "M_K_CPU0_CLK_DP<0>")
	)
	(arc
		(start 392.434318 -256.154174)
		(mid 392.61935 -256.200088)
		(end 392.803126 -256.149348)
		(width 0.09525)
		(layer "In6.Cu")
		(net "M_K_CPU0_CLK_DP<0>")
	)
	(arc
		(start 391.486136 -256.149348)
		(mid 391.669911 -256.20012)
		(end 391.854944 -256.154174)
		(width 0.09525)
		(layer "In6.Cu")
		(net "M_K_CPU0_CLK_DP<0>")
	)
	(arc
		(start 390.923272 -256.149348)
		(mid 391.204704 -256.073593)
		(end 391.486136 -256.149348)
		(width 0.09525)
		(layer "In6.Cu")
		(net "M_K_CPU0_CLK_DP<0>")
	)
	(arc
		(start 393.36599 -256.149348)
		(mid 393.426405 -256.189928)
		(end 393.481052 -256.237994)
		(width 0.09525)
		(layer "In6.Cu")
		(net "M_K_CPU0_CLK_DP<0>")
	)
	(arc
		(start 391.863326 -256.149348)
		(mid 392.138615 -256.073627)
		(end 392.415522 -256.143252)
		(width 0.09525)
		(layer "In6.Cu")
		(net "M_K_CPU0_CLK_DP<0>")
	)
	(arc
		(start 390.603994 -256.176272)
		(mid 390.766645 -256.198532)
		(end 390.923272 -256.149348)
		(width 0.09525)
		(layer "In6.Cu")
		(net "M_K_CPU0_CLK_DP<0>")
	)
	(segment
		(start 389.798052 -256.900172)
		(end 390.264904 -256.634234)
		(width 0.14732)
		(layer "F.Cu")
		(net "M_K_CPU0_CLK_DN<0>")
	)
	(segment
		(start 399.072354 -257.47853)
		(end 400.435064 -256.11582)
		(width 0.16002)
		(layer "In6.Cu")
		(net "M_K_CPU0_CLK_DN<0>")
	)
	(segment
		(start 410.728668 -258.200652)
		(end 411.065726 -257.863594)
		(width 0.16002)
		(layer "In6.Cu")
		(net "M_K_CPU0_CLK_DN<0>")
	)
	(segment
		(start 406.894284 -257.006852)
		(end 407.387044 -257.006852)
		(width 0.16002)
		(layer "In6.Cu")
		(net "M_K_CPU0_CLK_DN<0>")
	)
	(segment
		(start 407.387044 -257.006852)
		(end 407.547064 -257.166872)
		(width 0.16002)
		(layer "In6.Cu")
		(net "M_K_CPU0_CLK_DN<0>")
	)
	(segment
		(start 411.065726 -257.863594)
		(end 411.065726 -257.166872)
		(width 0.16002)
		(layer "In6.Cu")
		(net "M_K_CPU0_CLK_DN<0>")
	)
	(segment
		(start 409.691332 -257.863594)
		(end 410.02839 -258.200652)
		(width 0.16002)
		(layer "In6.Cu")
		(net "M_K_CPU0_CLK_DN<0>")
	)
	(segment
		(start 400.435064 -256.11582)
		(end 406.003252 -256.11582)
		(width 0.16002)
		(layer "In6.Cu")
		(net "M_K_CPU0_CLK_DN<0>")
	)
	(segment
		(start 408.921458 -257.166872)
		(end 409.081478 -257.006852)
		(width 0.16002)
		(layer "In6.Cu")
		(net "M_K_CPU0_CLK_DN<0>")
	)
	(segment
		(start 408.921458 -257.863594)
		(end 408.921458 -257.166872)
		(width 0.16002)
		(layer "In6.Cu")
		(net "M_K_CPU0_CLK_DN<0>")
	)
	(segment
		(start 408.5844 -258.200652)
		(end 408.921458 -257.863594)
		(width 0.16002)
		(layer "In6.Cu")
		(net "M_K_CPU0_CLK_DN<0>")
	)
	(segment
		(start 390.264904 -256.634234)
		(end 390.418828 -256.368804)
		(width 0.09525)
		(layer "In6.Cu")
		(net "M_K_CPU0_CLK_DN<0>")
	)
	(segment
		(start 407.547064 -257.166872)
		(end 407.547064 -257.863594)
		(width 0.16002)
		(layer "In6.Cu")
		(net "M_K_CPU0_CLK_DN<0>")
	)
	(segment
		(start 393.35075 -256.368296)
		(end 394.402056 -257.419602)
		(width 0.09525)
		(layer "In6.Cu")
		(net "M_K_CPU0_CLK_DN<0>")
	)
	(segment
		(start 411.065726 -257.166872)
		(end 411.225746 -257.006852)
		(width 0.16002)
		(layer "In6.Cu")
		(net "M_K_CPU0_CLK_DN<0>")
	)
	(segment
		(start 395.472158 -257.47853)
		(end 399.072354 -257.47853)
		(width 0.16002)
		(layer "In6.Cu")
		(net "M_K_CPU0_CLK_DN<0>")
	)
	(segment
		(start 406.003252 -256.11582)
		(end 406.894284 -257.006852)
		(width 0.16002)
		(layer "In6.Cu")
		(net "M_K_CPU0_CLK_DN<0>")
	)
	(segment
		(start 407.884122 -258.200652)
		(end 408.5844 -258.200652)
		(width 0.16002)
		(layer "In6.Cu")
		(net "M_K_CPU0_CLK_DN<0>")
	)
	(segment
		(start 391.016236 -256.309114)
		(end 391.024618 -256.304288)
		(width 0.09525)
		(layer "In6.Cu")
		(net "M_K_CPU0_CLK_DN<0>")
	)
	(segment
		(start 395.389608 -257.419602)
		(end 395.448536 -257.47853)
		(width 0.09525)
		(layer "In6.Cu")
		(net "M_K_CPU0_CLK_DN<0>")
	)
	(segment
		(start 407.547064 -257.863594)
		(end 407.884122 -258.200652)
		(width 0.16002)
		(layer "In6.Cu")
		(net "M_K_CPU0_CLK_DN<0>")
	)
	(segment
		(start 395.448536 -257.47853)
		(end 395.472158 -257.47853)
		(width 0.09525)
		(layer "In6.Cu")
		(net "M_K_CPU0_CLK_DN<0>")
	)
	(segment
		(start 410.02839 -258.200652)
		(end 410.728668 -258.200652)
		(width 0.16002)
		(layer "In6.Cu")
		(net "M_K_CPU0_CLK_DN<0>")
	)
	(segment
		(start 409.691332 -257.166872)
		(end 409.691332 -257.863594)
		(width 0.16002)
		(layer "In6.Cu")
		(net "M_K_CPU0_CLK_DN<0>")
	)
	(segment
		(start 438.79516 -257.006852)
		(end 441.78982 -254.012192)
		(width 0.16002)
		(layer "In6.Cu")
		(net "M_K_CPU0_CLK_DN<0>")
	)
	(segment
		(start 409.531312 -257.006852)
		(end 409.691332 -257.166872)
		(width 0.16002)
		(layer "In6.Cu")
		(net "M_K_CPU0_CLK_DN<0>")
	)
	(segment
		(start 441.78982 -254.012192)
		(end 442.271404 -254.012192)
		(width 0.16002)
		(layer "In6.Cu")
		(net "M_K_CPU0_CLK_DN<0>")
	)
	(segment
		(start 392.333226 -256.309114)
		(end 392.347958 -256.31775)
		(width 0.09525)
		(layer "In6.Cu")
		(net "M_K_CPU0_CLK_DN<0>")
	)
	(segment
		(start 442.271404 -254.012192)
		(end 442.5442 -254.284988)
		(width 0.16002)
		(layer "In6.Cu")
		(net "M_K_CPU0_CLK_DN<0>")
	)
	(segment
		(start 390.418828 -256.368804)
		(end 390.519666 -256.342134)
		(width 0.09525)
		(layer "In6.Cu")
		(net "M_K_CPU0_CLK_DN<0>")
	)
	(segment
		(start 393.261088 -256.302256)
		(end 393.273026 -256.309114)
		(width 0.09525)
		(layer "In6.Cu")
		(net "M_K_CPU0_CLK_DN<0>")
	)
	(segment
		(start 409.081478 -257.006852)
		(end 409.531312 -257.006852)
		(width 0.16002)
		(layer "In6.Cu")
		(net "M_K_CPU0_CLK_DN<0>")
	)
	(segment
		(start 394.402056 -257.419602)
		(end 395.389608 -257.419602)
		(width 0.09525)
		(layer "In6.Cu")
		(net "M_K_CPU0_CLK_DN<0>")
	)
	(segment
		(start 411.225746 -257.006852)
		(end 438.79516 -257.006852)
		(width 0.16002)
		(layer "In6.Cu")
		(net "M_K_CPU0_CLK_DN<0>")
	)
	(arc
		(start 393.273026 -256.309114)
		(mid 393.313818 -256.33617)
		(end 393.35075 -256.368296)
		(width 0.09525)
		(layer "In6.Cu")
		(net "M_K_CPU0_CLK_DN<0>")
	)
	(arc
		(start 392.347958 -256.31775)
		(mid 392.623163 -256.385014)
		(end 392.89609 -256.309114)
		(width 0.09525)
		(layer "In6.Cu")
		(net "M_K_CPU0_CLK_DN<0>")
	)
	(arc
		(start 391.024618 -256.304288)
		(mid 391.20965 -256.258374)
		(end 391.393426 -256.309114)
		(width 0.09525)
		(layer "In6.Cu")
		(net "M_K_CPU0_CLK_DN<0>")
	)
	(arc
		(start 390.519666 -256.342134)
		(mid 390.771807 -256.383704)
		(end 391.016236 -256.309114)
		(width 0.09525)
		(layer "In6.Cu")
		(net "M_K_CPU0_CLK_DN<0>")
	)
	(arc
		(start 392.89609 -256.309114)
		(mid 393.077706 -256.258377)
		(end 393.261088 -256.302256)
		(width 0.09525)
		(layer "In6.Cu")
		(net "M_K_CPU0_CLK_DN<0>")
	)
	(arc
		(start 391.393426 -256.309114)
		(mid 391.674858 -256.384869)
		(end 391.95629 -256.309114)
		(width 0.09525)
		(layer "In6.Cu")
		(net "M_K_CPU0_CLK_DN<0>")
	)
	(arc
		(start 391.95629 -256.309114)
		(mid 392.144758 -256.258437)
		(end 392.333226 -256.309114)
		(width 0.09525)
		(layer "In6.Cu")
		(net "M_K_CPU0_CLK_DN<0>")
	)
	(segment
		(start 388.857998 -250.420124)
		(end 389.32485 -250.154186)
		(width 0.10668)
		(layer "F.Cu")
		(net "M_K_CPU0_ALERT_R_N")
	)
	(segment
		(start 407.68524 -249.86107)
		(end 411.336236 -246.210074)
		(width 0.11684)
		(layer "In6.Cu")
		(net "M_K_CPU0_ALERT_R_N")
	)
	(segment
		(start 411.336236 -246.210074)
		(end 436.82539 -246.210074)
		(width 0.11684)
		(layer "In6.Cu")
		(net "M_K_CPU0_ALERT_R_N")
	)
	(segment
		(start 439.275474 -245.36019)
		(end 440.975496 -243.660168)
		(width 0.11684)
		(layer "In6.Cu")
		(net "M_K_CPU0_ALERT_R_N")
	)
	(segment
		(start 393.084558 -250.527312)
		(end 393.490958 -250.527312)
		(width 0.0889)
		(layer "In6.Cu")
		(net "M_K_CPU0_ALERT_R_N")
	)
	(segment
		(start 391.947146 -250.47067)
		(end 391.95756 -250.476766)
		(width 0.0889)
		(layer "In6.Cu")
		(net "M_K_CPU0_ALERT_R_N")
	)
	(segment
		(start 444.822326 -243.660168)
		(end 445.247268 -244.08511)
		(width 0.11684)
		(layer "In6.Cu")
		(net "M_K_CPU0_ALERT_R_N")
	)
	(segment
		(start 389.170926 -250.419616)
		(end 389.193278 -250.502928)
		(width 0.0889)
		(layer "In6.Cu")
		(net "M_K_CPU0_ALERT_R_N")
	)
	(segment
		(start 395.719554 -250.71959)
		(end 396.969488 -250.71959)
		(width 0.11684)
		(layer "In6.Cu")
		(net "M_K_CPU0_ALERT_R_N")
	)
	(segment
		(start 392.331194 -250.476766)
		(end 392.341608 -250.47067)
		(width 0.0889)
		(layer "In6.Cu")
		(net "M_K_CPU0_ALERT_R_N")
	)
	(segment
		(start 390.443466 -250.481592)
		(end 390.451848 -250.476766)
		(width 0.0889)
		(layer "In6.Cu")
		(net "M_K_CPU0_ALERT_R_N")
	)
	(segment
		(start 389.32485 -250.154186)
		(end 389.170926 -250.419616)
		(width 0.0889)
		(layer "In6.Cu")
		(net "M_K_CPU0_ALERT_R_N")
	)
	(segment
		(start 393.490958 -250.527312)
		(end 393.683236 -250.71959)
		(width 0.0889)
		(layer "In6.Cu")
		(net "M_K_CPU0_ALERT_R_N")
	)
	(segment
		(start 440.975496 -243.660168)
		(end 444.822326 -243.660168)
		(width 0.11684)
		(layer "In6.Cu")
		(net "M_K_CPU0_ALERT_R_N")
	)
	(segment
		(start 391.95756 -250.476766)
		(end 391.965942 -250.481592)
		(width 0.0889)
		(layer "In6.Cu")
		(net "M_K_CPU0_ALERT_R_N")
	)
	(segment
		(start 396.969488 -250.71959)
		(end 397.828008 -249.86107)
		(width 0.11684)
		(layer "In6.Cu")
		(net "M_K_CPU0_ALERT_R_N")
	)
	(segment
		(start 437.675274 -245.36019)
		(end 439.275474 -245.36019)
		(width 0.11684)
		(layer "In6.Cu")
		(net "M_K_CPU0_ALERT_R_N")
	)
	(segment
		(start 391.01776 -250.476766)
		(end 391.026142 -250.481592)
		(width 0.0889)
		(layer "In6.Cu")
		(net "M_K_CPU0_ALERT_R_N")
	)
	(segment
		(start 393.683236 -250.71959)
		(end 395.719554 -250.71959)
		(width 0.0889)
		(layer "In6.Cu")
		(net "M_K_CPU0_ALERT_R_N")
	)
	(segment
		(start 397.828008 -249.86107)
		(end 407.68524 -249.86107)
		(width 0.11684)
		(layer "In6.Cu")
		(net "M_K_CPU0_ALERT_R_N")
	)
	(segment
		(start 436.82539 -246.210074)
		(end 437.675274 -245.36019)
		(width 0.11684)
		(layer "In6.Cu")
		(net "M_K_CPU0_ALERT_R_N")
	)
	(arc
		(start 392.341608 -250.47067)
		(mid 392.620294 -250.40045)
		(end 392.89736 -250.476766)
		(width 0.0889)
		(layer "In6.Cu")
		(net "M_K_CPU0_ALERT_R_N")
	)
	(arc
		(start 391.965942 -250.481592)
		(mid 392.149196 -250.526965)
		(end 392.331194 -250.476766)
		(width 0.0889)
		(layer "In6.Cu")
		(net "M_K_CPU0_ALERT_R_N")
	)
	(arc
		(start 389.511794 -250.476766)
		(mid 389.79475 -250.400589)
		(end 390.077706 -250.476766)
		(width 0.0889)
		(layer "In6.Cu")
		(net "M_K_CPU0_ALERT_R_N")
	)
	(arc
		(start 390.077706 -250.476766)
		(mid 390.259957 -250.527116)
		(end 390.443466 -250.481592)
		(width 0.0889)
		(layer "In6.Cu")
		(net "M_K_CPU0_ALERT_R_N")
	)
	(arc
		(start 390.451848 -250.476766)
		(mid 390.734804 -250.400589)
		(end 391.01776 -250.476766)
		(width 0.0889)
		(layer "In6.Cu")
		(net "M_K_CPU0_ALERT_R_N")
	)
	(arc
		(start 391.026142 -250.481592)
		(mid 391.20965 -250.527086)
		(end 391.391902 -250.476766)
		(width 0.0889)
		(layer "In6.Cu")
		(net "M_K_CPU0_ALERT_R_N")
	)
	(arc
		(start 391.391902 -250.476766)
		(mid 391.668715 -250.400623)
		(end 391.947146 -250.47067)
		(width 0.0889)
		(layer "In6.Cu")
		(net "M_K_CPU0_ALERT_R_N")
	)
	(arc
		(start 389.193278 -250.502928)
		(mid 389.355467 -250.525663)
		(end 389.511794 -250.476766)
		(width 0.0889)
		(layer "In6.Cu")
		(net "M_K_CPU0_ALERT_R_N")
	)
	(arc
		(start 392.89736 -250.476766)
		(mid 392.98762 -250.514394)
		(end 393.084558 -250.527312)
		(width 0.0889)
		(layer "In6.Cu")
		(net "M_K_CPU0_ALERT_R_N")
	)
	(via
		(at 446.644268 -244.08511)
		(size 0.4826)
		(drill 0.254)
		(layers "F.Cu" "B.Cu")
		(net "M_K_CPU0_ALERT_N")
	)
	(segment
		(start 446.047368 -244.08511)
		(end 446.644268 -244.08511)
		(width 0.10668)
		(layer "B.Cu")
		(net "M_K_CPU0_ALERT_N")
	)
	(segment
		(start 132.757926 -267.340334)
		(end 133.224778 -267.606272)
		(width 0.10668)
		(layer "F.Cu")
		(net "M_J_CPU1_SB_RSP<0>")
	)
	(segment
		(start 138.103356 -267.933678)
		(end 138.111738 -267.928852)
		(width 0.0889)
		(layer "In4.Cu")
		(net "M_J_CPU1_SB_RSP<0>")
	)
	(segment
		(start 134.917688 -267.928852)
		(end 134.92607 -267.933678)
		(width 0.0889)
		(layer "In4.Cu")
		(net "M_J_CPU1_SB_RSP<0>")
	)
	(segment
		(start 145.603214 -267.944346)
		(end 145.630646 -267.928598)
		(width 0.0889)
		(layer "In4.Cu")
		(net "M_J_CPU1_SB_RSP<0>")
	)
	(segment
		(start 189.023498 -270.010382)
		(end 191.160146 -270.435324)
		(width 0.11684)
		(layer "In4.Cu")
		(net "M_J_CPU1_SB_RSP<0>")
	)
	(segment
		(start 140.557758 -267.928852)
		(end 140.56614 -267.933678)
		(width 0.0889)
		(layer "In4.Cu")
		(net "M_J_CPU1_SB_RSP<0>")
	)
	(segment
		(start 144.316196 -267.928598)
		(end 144.334484 -267.939012)
		(width 0.0889)
		(layer "In4.Cu")
		(net "M_J_CPU1_SB_RSP<0>")
	)
	(segment
		(start 174.692056 -270.010382)
		(end 189.023498 -270.010382)
		(width 0.11684)
		(layer "In4.Cu")
		(net "M_J_CPU1_SB_RSP<0>")
	)
	(segment
		(start 133.224778 -267.606272)
		(end 133.070854 -267.871702)
		(width 0.0889)
		(layer "In4.Cu")
		(net "M_J_CPU1_SB_RSP<0>")
	)
	(segment
		(start 139.617704 -267.928852)
		(end 139.626086 -267.933678)
		(width 0.0889)
		(layer "In4.Cu")
		(net "M_J_CPU1_SB_RSP<0>")
	)
	(segment
		(start 164.538914 -270.86052)
		(end 165.217348 -270.86052)
		(width 0.11684)
		(layer "In4.Cu")
		(net "M_J_CPU1_SB_RSP<0>")
	)
	(segment
		(start 160.249108 -266.570714)
		(end 164.538914 -270.86052)
		(width 0.11684)
		(layer "In4.Cu")
		(net "M_J_CPU1_SB_RSP<0>")
	)
	(segment
		(start 171.697142 -270.86052)
		(end 172.639482 -270.86052)
		(width 0.11684)
		(layer "In4.Cu")
		(net "M_J_CPU1_SB_RSP<0>")
	)
	(segment
		(start 172.639482 -270.86052)
		(end 174.692056 -270.010382)
		(width 0.11684)
		(layer "In4.Cu")
		(net "M_J_CPU1_SB_RSP<0>")
	)
	(segment
		(start 147.77339 -266.570714)
		(end 160.249108 -266.570714)
		(width 0.11684)
		(layer "In4.Cu")
		(net "M_J_CPU1_SB_RSP<0>")
	)
	(segment
		(start 146.66468 -266.894564)
		(end 147.22983 -266.894564)
		(width 0.0889)
		(layer "In4.Cu")
		(net "M_J_CPU1_SB_RSP<0>")
	)
	(segment
		(start 133.070854 -267.871702)
		(end 133.093206 -267.955014)
		(width 0.0889)
		(layer "In4.Cu")
		(net "M_J_CPU1_SB_RSP<0>")
	)
	(segment
		(start 165.217348 -270.86052)
		(end 167.269922 -270.010382)
		(width 0.11684)
		(layer "In4.Cu")
		(net "M_J_CPU1_SB_RSP<0>")
	)
	(segment
		(start 145.630646 -267.928598)
		(end 146.66468 -266.894564)
		(width 0.0889)
		(layer "In4.Cu")
		(net "M_J_CPU1_SB_RSP<0>")
	)
	(segment
		(start 147.55368 -266.570714)
		(end 147.77339 -266.570714)
		(width 0.0889)
		(layer "In4.Cu")
		(net "M_J_CPU1_SB_RSP<0>")
	)
	(segment
		(start 142.803372 -267.933678)
		(end 142.811754 -267.928852)
		(width 0.0889)
		(layer "In4.Cu")
		(net "M_J_CPU1_SB_RSP<0>")
	)
	(segment
		(start 135.857742 -267.928852)
		(end 135.866124 -267.933678)
		(width 0.0889)
		(layer "In4.Cu")
		(net "M_J_CPU1_SB_RSP<0>")
	)
	(segment
		(start 134.343394 -267.933678)
		(end 134.351776 -267.928852)
		(width 0.0889)
		(layer "In4.Cu")
		(net "M_J_CPU1_SB_RSP<0>")
	)
	(segment
		(start 139.04341 -267.933678)
		(end 139.051792 -267.928852)
		(width 0.0889)
		(layer "In4.Cu")
		(net "M_J_CPU1_SB_RSP<0>")
	)
	(segment
		(start 144.294606 -267.916152)
		(end 144.316196 -267.928598)
		(width 0.0889)
		(layer "In4.Cu")
		(net "M_J_CPU1_SB_RSP<0>")
	)
	(segment
		(start 143.377666 -267.928852)
		(end 143.386048 -267.933678)
		(width 0.0889)
		(layer "In4.Cu")
		(net "M_J_CPU1_SB_RSP<0>")
	)
	(segment
		(start 169.644568 -270.010382)
		(end 171.697142 -270.86052)
		(width 0.11684)
		(layer "In4.Cu")
		(net "M_J_CPU1_SB_RSP<0>")
	)
	(segment
		(start 144.689322 -267.928852)
		(end 144.71269 -267.915136)
		(width 0.0889)
		(layer "In4.Cu")
		(net "M_J_CPU1_SB_RSP<0>")
	)
	(segment
		(start 167.269922 -270.010382)
		(end 169.644568 -270.010382)
		(width 0.11684)
		(layer "In4.Cu")
		(net "M_J_CPU1_SB_RSP<0>")
	)
	(segment
		(start 147.22983 -266.894564)
		(end 147.55368 -266.570714)
		(width 0.0889)
		(layer "In4.Cu")
		(net "M_J_CPU1_SB_RSP<0>")
	)
	(arc
		(start 140.56614 -267.933678)
		(mid 140.749648 -267.979172)
		(end 140.9319 -267.928852)
		(width 0.0889)
		(layer "In4.Cu")
		(net "M_J_CPU1_SB_RSP<0>")
	)
	(arc
		(start 139.626086 -267.933678)
		(mid 139.809594 -267.979172)
		(end 139.991846 -267.928852)
		(width 0.0889)
		(layer "In4.Cu")
		(net "M_J_CPU1_SB_RSP<0>")
	)
	(arc
		(start 136.797796 -267.928852)
		(mid 136.98474 -267.979107)
		(end 137.171684 -267.928852)
		(width 0.0889)
		(layer "In4.Cu")
		(net "M_J_CPU1_SB_RSP<0>")
	)
	(arc
		(start 134.92607 -267.933678)
		(mid 135.109578 -267.979172)
		(end 135.29183 -267.928852)
		(width 0.0889)
		(layer "In4.Cu")
		(net "M_J_CPU1_SB_RSP<0>")
	)
	(arc
		(start 136.231884 -267.928852)
		(mid 136.51484 -267.852675)
		(end 136.797796 -267.928852)
		(width 0.0889)
		(layer "In4.Cu")
		(net "M_J_CPU1_SB_RSP<0>")
	)
	(arc
		(start 142.437612 -267.928852)
		(mid 142.619863 -267.979202)
		(end 142.803372 -267.933678)
		(width 0.0889)
		(layer "In4.Cu")
		(net "M_J_CPU1_SB_RSP<0>")
	)
	(arc
		(start 139.991846 -267.928852)
		(mid 140.274802 -267.852675)
		(end 140.557758 -267.928852)
		(width 0.0889)
		(layer "In4.Cu")
		(net "M_J_CPU1_SB_RSP<0>")
	)
	(arc
		(start 138.111738 -267.928852)
		(mid 138.394694 -267.852675)
		(end 138.67765 -267.928852)
		(width 0.0889)
		(layer "In4.Cu")
		(net "M_J_CPU1_SB_RSP<0>")
	)
	(arc
		(start 145.256504 -267.928852)
		(mid 145.427959 -267.979369)
		(end 145.603214 -267.944346)
		(width 0.0889)
		(layer "In4.Cu")
		(net "M_J_CPU1_SB_RSP<0>")
	)
	(arc
		(start 138.67765 -267.928852)
		(mid 138.859901 -267.979202)
		(end 139.04341 -267.933678)
		(width 0.0889)
		(layer "In4.Cu")
		(net "M_J_CPU1_SB_RSP<0>")
	)
	(arc
		(start 137.737596 -267.928852)
		(mid 137.919847 -267.979202)
		(end 138.103356 -267.933678)
		(width 0.0889)
		(layer "In4.Cu")
		(net "M_J_CPU1_SB_RSP<0>")
	)
	(arc
		(start 133.977634 -267.928852)
		(mid 134.159885 -267.979202)
		(end 134.343394 -267.933678)
		(width 0.0889)
		(layer "In4.Cu")
		(net "M_J_CPU1_SB_RSP<0>")
	)
	(arc
		(start 139.051792 -267.928852)
		(mid 139.334748 -267.852675)
		(end 139.617704 -267.928852)
		(width 0.0889)
		(layer "In4.Cu")
		(net "M_J_CPU1_SB_RSP<0>")
	)
	(arc
		(start 144.334484 -267.939012)
		(mid 144.513205 -267.978935)
		(end 144.689322 -267.928852)
		(width 0.0889)
		(layer "In4.Cu")
		(net "M_J_CPU1_SB_RSP<0>")
	)
	(arc
		(start 140.9319 -267.928852)
		(mid 141.214856 -267.852675)
		(end 141.497812 -267.928852)
		(width 0.0889)
		(layer "In4.Cu")
		(net "M_J_CPU1_SB_RSP<0>")
	)
	(arc
		(start 135.866124 -267.933678)
		(mid 136.049632 -267.979172)
		(end 136.231884 -267.928852)
		(width 0.0889)
		(layer "In4.Cu")
		(net "M_J_CPU1_SB_RSP<0>")
	)
	(arc
		(start 134.351776 -267.928852)
		(mid 134.634732 -267.852675)
		(end 134.917688 -267.928852)
		(width 0.0889)
		(layer "In4.Cu")
		(net "M_J_CPU1_SB_RSP<0>")
	)
	(arc
		(start 143.386048 -267.933678)
		(mid 143.569556 -267.979172)
		(end 143.751808 -267.928852)
		(width 0.0889)
		(layer "In4.Cu")
		(net "M_J_CPU1_SB_RSP<0>")
	)
	(arc
		(start 133.093206 -267.955014)
		(mid 133.255395 -267.977749)
		(end 133.411722 -267.928852)
		(width 0.0889)
		(layer "In4.Cu")
		(net "M_J_CPU1_SB_RSP<0>")
	)
	(arc
		(start 141.8717 -267.928852)
		(mid 142.154656 -267.852675)
		(end 142.437612 -267.928852)
		(width 0.0889)
		(layer "In4.Cu")
		(net "M_J_CPU1_SB_RSP<0>")
	)
	(arc
		(start 141.497812 -267.928852)
		(mid 141.684756 -267.979107)
		(end 141.8717 -267.928852)
		(width 0.0889)
		(layer "In4.Cu")
		(net "M_J_CPU1_SB_RSP<0>")
	)
	(arc
		(start 133.411722 -267.928852)
		(mid 133.694678 -267.852675)
		(end 133.977634 -267.928852)
		(width 0.0889)
		(layer "In4.Cu")
		(net "M_J_CPU1_SB_RSP<0>")
	)
	(arc
		(start 142.811754 -267.928852)
		(mid 143.09471 -267.852675)
		(end 143.377666 -267.928852)
		(width 0.0889)
		(layer "In4.Cu")
		(net "M_J_CPU1_SB_RSP<0>")
	)
	(arc
		(start 135.29183 -267.928852)
		(mid 135.574786 -267.852675)
		(end 135.857742 -267.928852)
		(width 0.0889)
		(layer "In4.Cu")
		(net "M_J_CPU1_SB_RSP<0>")
	)
	(arc
		(start 144.71269 -267.915136)
		(mid 144.986344 -267.852193)
		(end 145.256504 -267.928852)
		(width 0.0889)
		(layer "In4.Cu")
		(net "M_J_CPU1_SB_RSP<0>")
	)
	(arc
		(start 143.751808 -267.928852)
		(mid 144.021577 -267.852829)
		(end 144.294606 -267.916152)
		(width 0.0889)
		(layer "In4.Cu")
		(net "M_J_CPU1_SB_RSP<0>")
	)
	(arc
		(start 137.171684 -267.928852)
		(mid 137.45464 -267.852675)
		(end 137.737596 -267.928852)
		(width 0.0889)
		(layer "In4.Cu")
		(net "M_J_CPU1_SB_RSP<0>")
	)
	(segment
		(start 131.347972 -264.910316)
		(end 131.814824 -265.176254)
		(width 0.10668)
		(layer "F.Cu")
		(net "M_J_CPU1_SB_PAR")
	)
	(segment
		(start 144.777968 -265.492738)
		(end 144.788382 -265.498834)
		(width 0.0889)
		(layer "In4.Cu")
		(net "M_J_CPU1_SB_PAR")
	)
	(segment
		(start 141.393418 -265.50366)
		(end 141.4018 -265.498834)
		(width 0.0889)
		(layer "In4.Cu")
		(net "M_J_CPU1_SB_PAR")
	)
	(segment
		(start 166.150036 -267.460476)
		(end 167.000174 -266.610338)
		(width 0.14478)
		(layer "In4.Cu")
		(net "M_J_CPU1_SB_PAR")
	)
	(segment
		(start 138.20775 -265.498834)
		(end 138.216132 -265.50366)
		(width 0.0889)
		(layer "In4.Cu")
		(net "M_J_CPU1_SB_PAR")
	)
	(segment
		(start 147.532852 -264.793984)
		(end 148.013674 -264.793984)
		(width 0.0889)
		(layer "In4.Cu")
		(net "M_J_CPU1_SB_PAR")
	)
	(segment
		(start 146.109436 -264.544556)
		(end 147.283424 -264.544556)
		(width 0.0889)
		(layer "In4.Cu")
		(net "M_J_CPU1_SB_PAR")
	)
	(segment
		(start 140.453364 -265.50366)
		(end 140.461746 -265.498834)
		(width 0.0889)
		(layer "In4.Cu")
		(net "M_J_CPU1_SB_PAR")
	)
	(segment
		(start 145.146014 -265.507978)
		(end 146.109436 -264.544556)
		(width 0.0889)
		(layer "In4.Cu")
		(net "M_J_CPU1_SB_PAR")
	)
	(segment
		(start 135.753348 -265.50366)
		(end 135.76173 -265.498834)
		(width 0.0889)
		(layer "In4.Cu")
		(net "M_J_CPU1_SB_PAR")
	)
	(segment
		(start 164.479224 -267.460476)
		(end 166.150036 -267.460476)
		(width 0.14478)
		(layer "In4.Cu")
		(net "M_J_CPU1_SB_PAR")
	)
	(segment
		(start 133.507734 -265.498834)
		(end 133.516116 -265.50366)
		(width 0.0889)
		(layer "In4.Cu")
		(net "M_J_CPU1_SB_PAR")
	)
	(segment
		(start 131.993386 -265.50366)
		(end 132.001768 -265.498834)
		(width 0.0889)
		(layer "In4.Cu")
		(net "M_J_CPU1_SB_PAR")
	)
	(segment
		(start 141.967712 -265.498834)
		(end 141.976094 -265.50366)
		(width 0.0889)
		(layer "In4.Cu")
		(net "M_J_CPU1_SB_PAR")
	)
	(segment
		(start 131.814824 -265.176254)
		(end 131.660646 -265.441684)
		(width 0.0889)
		(layer "In4.Cu")
		(net "M_J_CPU1_SB_PAR")
	)
	(segment
		(start 186.635136 -266.610338)
		(end 187.060078 -267.03528)
		(width 0.14478)
		(layer "In4.Cu")
		(net "M_J_CPU1_SB_PAR")
	)
	(segment
		(start 170.18254 -266.610338)
		(end 171.032678 -267.460476)
		(width 0.14478)
		(layer "In4.Cu")
		(net "M_J_CPU1_SB_PAR")
	)
	(segment
		(start 132.93344 -265.50366)
		(end 132.941822 -265.498834)
		(width 0.0889)
		(layer "In4.Cu")
		(net "M_J_CPU1_SB_PAR")
	)
	(segment
		(start 171.032678 -267.460476)
		(end 173.69409 -267.460476)
		(width 0.14478)
		(layer "In4.Cu")
		(net "M_J_CPU1_SB_PAR")
	)
	(segment
		(start 131.660646 -265.441684)
		(end 131.682998 -265.524996)
		(width 0.0889)
		(layer "In4.Cu")
		(net "M_J_CPU1_SB_PAR")
	)
	(segment
		(start 174.544228 -266.610338)
		(end 186.635136 -266.610338)
		(width 0.14478)
		(layer "In4.Cu")
		(net "M_J_CPU1_SB_PAR")
	)
	(segment
		(start 143.847566 -265.498834)
		(end 143.855948 -265.50366)
		(width 0.0889)
		(layer "In4.Cu")
		(net "M_J_CPU1_SB_PAR")
	)
	(segment
		(start 148.013674 -264.793984)
		(end 161.812732 -264.793984)
		(width 0.14478)
		(layer "In4.Cu")
		(net "M_J_CPU1_SB_PAR")
	)
	(segment
		(start 161.812732 -264.793984)
		(end 164.479224 -267.460476)
		(width 0.14478)
		(layer "In4.Cu")
		(net "M_J_CPU1_SB_PAR")
	)
	(segment
		(start 136.693402 -265.50366)
		(end 136.701784 -265.498834)
		(width 0.0889)
		(layer "In4.Cu")
		(net "M_J_CPU1_SB_PAR")
	)
	(segment
		(start 147.283424 -264.544556)
		(end 147.532852 -264.793984)
		(width 0.0889)
		(layer "In4.Cu")
		(net "M_J_CPU1_SB_PAR")
	)
	(segment
		(start 167.000174 -266.610338)
		(end 170.18254 -266.610338)
		(width 0.14478)
		(layer "In4.Cu")
		(net "M_J_CPU1_SB_PAR")
	)
	(segment
		(start 137.267696 -265.498834)
		(end 137.276078 -265.50366)
		(width 0.0889)
		(layer "In4.Cu")
		(net "M_J_CPU1_SB_PAR")
	)
	(segment
		(start 173.69409 -267.460476)
		(end 174.544228 -266.610338)
		(width 0.14478)
		(layer "In4.Cu")
		(net "M_J_CPU1_SB_PAR")
	)
	(arc
		(start 137.641838 -265.498834)
		(mid 137.924794 -265.422657)
		(end 138.20775 -265.498834)
		(width 0.0889)
		(layer "In4.Cu")
		(net "M_J_CPU1_SB_PAR")
	)
	(arc
		(start 144.788382 -265.498834)
		(mid 144.966032 -265.549094)
		(end 145.146014 -265.507978)
		(width 0.0889)
		(layer "In4.Cu")
		(net "M_J_CPU1_SB_PAR")
	)
	(arc
		(start 137.276078 -265.50366)
		(mid 137.459586 -265.549154)
		(end 137.641838 -265.498834)
		(width 0.0889)
		(layer "In4.Cu")
		(net "M_J_CPU1_SB_PAR")
	)
	(arc
		(start 132.56768 -265.498834)
		(mid 132.749931 -265.549184)
		(end 132.93344 -265.50366)
		(width 0.0889)
		(layer "In4.Cu")
		(net "M_J_CPU1_SB_PAR")
	)
	(arc
		(start 135.387588 -265.498834)
		(mid 135.569839 -265.549184)
		(end 135.753348 -265.50366)
		(width 0.0889)
		(layer "In4.Cu")
		(net "M_J_CPU1_SB_PAR")
	)
	(arc
		(start 136.701784 -265.498834)
		(mid 136.98474 -265.422657)
		(end 137.267696 -265.498834)
		(width 0.0889)
		(layer "In4.Cu")
		(net "M_J_CPU1_SB_PAR")
	)
	(arc
		(start 144.222216 -265.498834)
		(mid 144.499283 -265.422563)
		(end 144.777968 -265.492738)
		(width 0.0889)
		(layer "In4.Cu")
		(net "M_J_CPU1_SB_PAR")
	)
	(arc
		(start 132.941822 -265.498834)
		(mid 133.224778 -265.422657)
		(end 133.507734 -265.498834)
		(width 0.0889)
		(layer "In4.Cu")
		(net "M_J_CPU1_SB_PAR")
	)
	(arc
		(start 141.027658 -265.498834)
		(mid 141.209909 -265.549184)
		(end 141.393418 -265.50366)
		(width 0.0889)
		(layer "In4.Cu")
		(net "M_J_CPU1_SB_PAR")
	)
	(arc
		(start 131.682998 -265.524996)
		(mid 131.840508 -265.548194)
		(end 131.993386 -265.50366)
		(width 0.0889)
		(layer "In4.Cu")
		(net "M_J_CPU1_SB_PAR")
	)
	(arc
		(start 142.341854 -265.498834)
		(mid 142.62481 -265.422657)
		(end 142.907766 -265.498834)
		(width 0.0889)
		(layer "In4.Cu")
		(net "M_J_CPU1_SB_PAR")
	)
	(arc
		(start 139.147804 -265.498834)
		(mid 139.334748 -265.549089)
		(end 139.521692 -265.498834)
		(width 0.0889)
		(layer "In4.Cu")
		(net "M_J_CPU1_SB_PAR")
	)
	(arc
		(start 143.855948 -265.50366)
		(mid 144.03971 -265.549276)
		(end 144.222216 -265.498834)
		(width 0.0889)
		(layer "In4.Cu")
		(net "M_J_CPU1_SB_PAR")
	)
	(arc
		(start 143.281654 -265.498834)
		(mid 143.56461 -265.422657)
		(end 143.847566 -265.498834)
		(width 0.0889)
		(layer "In4.Cu")
		(net "M_J_CPU1_SB_PAR")
	)
	(arc
		(start 138.216132 -265.50366)
		(mid 138.39964 -265.549154)
		(end 138.581892 -265.498834)
		(width 0.0889)
		(layer "In4.Cu")
		(net "M_J_CPU1_SB_PAR")
	)
	(arc
		(start 132.001768 -265.498834)
		(mid 132.284724 -265.422657)
		(end 132.56768 -265.498834)
		(width 0.0889)
		(layer "In4.Cu")
		(net "M_J_CPU1_SB_PAR")
	)
	(arc
		(start 133.516116 -265.50366)
		(mid 133.699624 -265.549154)
		(end 133.881876 -265.498834)
		(width 0.0889)
		(layer "In4.Cu")
		(net "M_J_CPU1_SB_PAR")
	)
	(arc
		(start 140.461746 -265.498834)
		(mid 140.744702 -265.422657)
		(end 141.027658 -265.498834)
		(width 0.0889)
		(layer "In4.Cu")
		(net "M_J_CPU1_SB_PAR")
	)
	(arc
		(start 138.581892 -265.498834)
		(mid 138.864848 -265.422657)
		(end 139.147804 -265.498834)
		(width 0.0889)
		(layer "In4.Cu")
		(net "M_J_CPU1_SB_PAR")
	)
	(arc
		(start 136.327642 -265.498834)
		(mid 136.509893 -265.549184)
		(end 136.693402 -265.50366)
		(width 0.0889)
		(layer "In4.Cu")
		(net "M_J_CPU1_SB_PAR")
	)
	(arc
		(start 140.087604 -265.498834)
		(mid 140.269855 -265.549184)
		(end 140.453364 -265.50366)
		(width 0.0889)
		(layer "In4.Cu")
		(net "M_J_CPU1_SB_PAR")
	)
	(arc
		(start 134.821676 -265.498834)
		(mid 135.104632 -265.422657)
		(end 135.387588 -265.498834)
		(width 0.0889)
		(layer "In4.Cu")
		(net "M_J_CPU1_SB_PAR")
	)
	(arc
		(start 141.976094 -265.50366)
		(mid 142.159602 -265.549154)
		(end 142.341854 -265.498834)
		(width 0.0889)
		(layer "In4.Cu")
		(net "M_J_CPU1_SB_PAR")
	)
	(arc
		(start 135.76173 -265.498834)
		(mid 136.044686 -265.422657)
		(end 136.327642 -265.498834)
		(width 0.0889)
		(layer "In4.Cu")
		(net "M_J_CPU1_SB_PAR")
	)
	(arc
		(start 133.881876 -265.498834)
		(mid 134.164832 -265.422657)
		(end 134.447788 -265.498834)
		(width 0.0889)
		(layer "In4.Cu")
		(net "M_J_CPU1_SB_PAR")
	)
	(arc
		(start 139.521692 -265.498834)
		(mid 139.804648 -265.422657)
		(end 140.087604 -265.498834)
		(width 0.0889)
		(layer "In4.Cu")
		(net "M_J_CPU1_SB_PAR")
	)
	(arc
		(start 142.907766 -265.498834)
		(mid 143.09471 -265.549089)
		(end 143.281654 -265.498834)
		(width 0.0889)
		(layer "In4.Cu")
		(net "M_J_CPU1_SB_PAR")
	)
	(arc
		(start 134.447788 -265.498834)
		(mid 134.634732 -265.549089)
		(end 134.821676 -265.498834)
		(width 0.0889)
		(layer "In4.Cu")
		(net "M_J_CPU1_SB_PAR")
	)
	(arc
		(start 141.4018 -265.498834)
		(mid 141.684756 -265.422657)
		(end 141.967712 -265.498834)
		(width 0.0889)
		(layer "In4.Cu")
		(net "M_J_CPU1_SB_PAR")
	)
	(segment
		(start 132.757926 -270.580358)
		(end 133.224778 -270.846296)
		(width 0.12954)
		(layer "F.Cu")
		(net "M_J_CPU1_SB_DQS_DP<9>")
	)
	(segment
		(start 142.804896 -271.176242)
		(end 142.813278 -271.171416)
		(width 0.09525)
		(layer "In4.Cu")
		(net "M_J_CPU1_SB_DQS_DP<9>")
	)
	(segment
		(start 166.345108 -274.81022)
		(end 166.755318 -275.22043)
		(width 0.16002)
		(layer "In4.Cu")
		(net "M_J_CPU1_SB_DQS_DP<9>")
	)
	(segment
		(start 189.873128 -275.809202)
		(end 190.886334 -275.809202)
		(width 0.16002)
		(layer "In4.Cu")
		(net "M_J_CPU1_SB_DQS_DP<9>")
	)
	(segment
		(start 140.556234 -271.171416)
		(end 140.564616 -271.176242)
		(width 0.09525)
		(layer "In4.Cu")
		(net "M_J_CPU1_SB_DQS_DP<9>")
	)
	(segment
		(start 144.316196 -271.171416)
		(end 144.324578 -271.176242)
		(width 0.09525)
		(layer "In4.Cu")
		(net "M_J_CPU1_SB_DQS_DP<9>")
	)
	(segment
		(start 143.376142 -271.171416)
		(end 143.384524 -271.176242)
		(width 0.09525)
		(layer "In4.Cu")
		(net "M_J_CPU1_SB_DQS_DP<9>")
	)
	(segment
		(start 147.895564 -269.252954)
		(end 147.919186 -269.252954)
		(width 0.09525)
		(layer "In4.Cu")
		(net "M_J_CPU1_SB_DQS_DP<9>")
	)
	(segment
		(start 175.630332 -274.81022)
		(end 177.267108 -274.81022)
		(width 0.16002)
		(layer "In4.Cu")
		(net "M_J_CPU1_SB_DQS_DP<9>")
	)
	(segment
		(start 189.6872 -275.99513)
		(end 189.873128 -275.809202)
		(width 0.16002)
		(layer "In4.Cu")
		(net "M_J_CPU1_SB_DQS_DP<9>")
	)
	(segment
		(start 181.771036 -275.428964)
		(end 182.326788 -275.428964)
		(width 0.16002)
		(layer "In4.Cu")
		(net "M_J_CPU1_SB_DQS_DP<9>")
	)
	(segment
		(start 138.10488 -271.176242)
		(end 138.113262 -271.171416)
		(width 0.09525)
		(layer "In4.Cu")
		(net "M_J_CPU1_SB_DQS_DP<9>")
	)
	(segment
		(start 139.61618 -271.171416)
		(end 139.624562 -271.176242)
		(width 0.09525)
		(layer "In4.Cu")
		(net "M_J_CPU1_SB_DQS_DP<9>")
	)
	(segment
		(start 182.326788 -275.428964)
		(end 182.945532 -274.81022)
		(width 0.16002)
		(layer "In4.Cu")
		(net "M_J_CPU1_SB_DQS_DP<9>")
	)
	(segment
		(start 177.267108 -274.81022)
		(end 178.116992 -275.660104)
		(width 0.16002)
		(layer "In4.Cu")
		(net "M_J_CPU1_SB_DQS_DP<9>")
	)
	(segment
		(start 161.06394 -271.849342)
		(end 164.024818 -274.81022)
		(width 0.16002)
		(layer "In4.Cu")
		(net "M_J_CPU1_SB_DQS_DP<9>")
	)
	(segment
		(start 134.344918 -271.176242)
		(end 134.3533 -271.171416)
		(width 0.09525)
		(layer "In4.Cu")
		(net "M_J_CPU1_SB_DQS_DP<9>")
	)
	(segment
		(start 147.281138 -269.172944)
		(end 147.42033 -269.312136)
		(width 0.09525)
		(layer "In4.Cu")
		(net "M_J_CPU1_SB_DQS_DP<9>")
	)
	(segment
		(start 184.716928 -274.81022)
		(end 185.497978 -275.59127)
		(width 0.16002)
		(layer "In4.Cu")
		(net "M_J_CPU1_SB_DQS_DP<9>")
	)
	(segment
		(start 147.836382 -269.312136)
		(end 147.895564 -269.252954)
		(width 0.09525)
		(layer "In4.Cu")
		(net "M_J_CPU1_SB_DQS_DP<9>")
	)
	(segment
		(start 178.116992 -275.660104)
		(end 180.189124 -275.660104)
		(width 0.16002)
		(layer "In4.Cu")
		(net "M_J_CPU1_SB_DQS_DP<9>")
	)
	(segment
		(start 187.939426 -275.99513)
		(end 189.6872 -275.99513)
		(width 0.16002)
		(layer "In4.Cu")
		(net "M_J_CPU1_SB_DQS_DP<9>")
	)
	(segment
		(start 185.497978 -275.59127)
		(end 186.341766 -275.59127)
		(width 0.16002)
		(layer "In4.Cu")
		(net "M_J_CPU1_SB_DQS_DP<9>")
	)
	(segment
		(start 146.61515 -269.172944)
		(end 147.281138 -269.172944)
		(width 0.09525)
		(layer "In4.Cu")
		(net "M_J_CPU1_SB_DQS_DP<9>")
	)
	(segment
		(start 145.665952 -270.122142)
		(end 146.61515 -269.172944)
		(width 0.09525)
		(layer "In4.Cu")
		(net "M_J_CPU1_SB_DQS_DP<9>")
	)
	(segment
		(start 147.919186 -269.252954)
		(end 157.260036 -269.252954)
		(width 0.16002)
		(layer "In4.Cu")
		(net "M_J_CPU1_SB_DQS_DP<9>")
	)
	(segment
		(start 170.5102 -275.660104)
		(end 172.417232 -275.660104)
		(width 0.16002)
		(layer "In4.Cu")
		(net "M_J_CPU1_SB_DQS_DP<9>")
	)
	(segment
		(start 157.260036 -269.252954)
		(end 159.856424 -271.849342)
		(width 0.16002)
		(layer "In4.Cu")
		(net "M_J_CPU1_SB_DQS_DP<9>")
	)
	(segment
		(start 144.693386 -271.171416)
		(end 144.724882 -271.153128)
		(width 0.09525)
		(layer "In4.Cu")
		(net "M_J_CPU1_SB_DQS_DP<9>")
	)
	(segment
		(start 133.224778 -270.846296)
		(end 133.070854 -271.111726)
		(width 0.09525)
		(layer "In4.Cu")
		(net "M_J_CPU1_SB_DQS_DP<9>")
	)
	(segment
		(start 172.752258 -275.99513)
		(end 173.52137 -275.99513)
		(width 0.16002)
		(layer "In4.Cu")
		(net "M_J_CPU1_SB_DQS_DP<9>")
	)
	(segment
		(start 186.938666 -275.47443)
		(end 187.055506 -275.59127)
		(width 0.16002)
		(layer "In4.Cu")
		(net "M_J_CPU1_SB_DQS_DP<9>")
	)
	(segment
		(start 139.044934 -271.176242)
		(end 139.053316 -271.171416)
		(width 0.09525)
		(layer "In4.Cu")
		(net "M_J_CPU1_SB_DQS_DP<9>")
	)
	(segment
		(start 159.856424 -271.849342)
		(end 161.06394 -271.849342)
		(width 0.16002)
		(layer "In4.Cu")
		(net "M_J_CPU1_SB_DQS_DP<9>")
	)
	(segment
		(start 186.341766 -275.59127)
		(end 186.458606 -275.47443)
		(width 0.16002)
		(layer "In4.Cu")
		(net "M_J_CPU1_SB_DQS_DP<9>")
	)
	(segment
		(start 166.755318 -275.22043)
		(end 170.070526 -275.22043)
		(width 0.16002)
		(layer "In4.Cu")
		(net "M_J_CPU1_SB_DQS_DP<9>")
	)
	(segment
		(start 172.417232 -275.660104)
		(end 172.752258 -275.99513)
		(width 0.16002)
		(layer "In4.Cu")
		(net "M_J_CPU1_SB_DQS_DP<9>")
	)
	(segment
		(start 135.856218 -271.171416)
		(end 135.8646 -271.176242)
		(width 0.09525)
		(layer "In4.Cu")
		(net "M_J_CPU1_SB_DQS_DP<9>")
	)
	(segment
		(start 144.300956 -271.162526)
		(end 144.316196 -271.171416)
		(width 0.09525)
		(layer "In4.Cu")
		(net "M_J_CPU1_SB_DQS_DP<9>")
	)
	(segment
		(start 170.070526 -275.22043)
		(end 170.5102 -275.660104)
		(width 0.16002)
		(layer "In4.Cu")
		(net "M_J_CPU1_SB_DQS_DP<9>")
	)
	(segment
		(start 173.52137 -275.99513)
		(end 174.0281 -275.4884)
		(width 0.16002)
		(layer "In4.Cu")
		(net "M_J_CPU1_SB_DQS_DP<9>")
	)
	(segment
		(start 134.916164 -271.171416)
		(end 134.924546 -271.176242)
		(width 0.09525)
		(layer "In4.Cu")
		(net "M_J_CPU1_SB_DQS_DP<9>")
	)
	(segment
		(start 144.289272 -271.156684)
		(end 144.300956 -271.162526)
		(width 0.09525)
		(layer "In4.Cu")
		(net "M_J_CPU1_SB_DQS_DP<9>")
	)
	(segment
		(start 174.0281 -275.4884)
		(end 174.952152 -275.4884)
		(width 0.16002)
		(layer "In4.Cu")
		(net "M_J_CPU1_SB_DQS_DP<9>")
	)
	(segment
		(start 180.50129 -275.97227)
		(end 181.22773 -275.97227)
		(width 0.16002)
		(layer "In4.Cu")
		(net "M_J_CPU1_SB_DQS_DP<9>")
	)
	(segment
		(start 187.055506 -275.59127)
		(end 187.535566 -275.59127)
		(width 0.16002)
		(layer "In4.Cu")
		(net "M_J_CPU1_SB_DQS_DP<9>")
	)
	(segment
		(start 133.070854 -271.111726)
		(end 133.093968 -271.19834)
		(width 0.09525)
		(layer "In4.Cu")
		(net "M_J_CPU1_SB_DQS_DP<9>")
	)
	(segment
		(start 180.189124 -275.660104)
		(end 180.50129 -275.97227)
		(width 0.16002)
		(layer "In4.Cu")
		(net "M_J_CPU1_SB_DQS_DP<9>")
	)
	(segment
		(start 174.952152 -275.4884)
		(end 175.630332 -274.81022)
		(width 0.16002)
		(layer "In4.Cu")
		(net "M_J_CPU1_SB_DQS_DP<9>")
	)
	(segment
		(start 164.024818 -274.81022)
		(end 166.345108 -274.81022)
		(width 0.16002)
		(layer "In4.Cu")
		(net "M_J_CPU1_SB_DQS_DP<9>")
	)
	(segment
		(start 147.42033 -269.312136)
		(end 147.836382 -269.312136)
		(width 0.09525)
		(layer "In4.Cu")
		(net "M_J_CPU1_SB_DQS_DP<9>")
	)
	(segment
		(start 190.886334 -275.809202)
		(end 191.160146 -275.53539)
		(width 0.16002)
		(layer "In4.Cu")
		(net "M_J_CPU1_SB_DQS_DP<9>")
	)
	(segment
		(start 187.535566 -275.59127)
		(end 187.939426 -275.99513)
		(width 0.16002)
		(layer "In4.Cu")
		(net "M_J_CPU1_SB_DQS_DP<9>")
	)
	(segment
		(start 145.125186 -270.383508)
		(end 145.163286 -270.36141)
		(width 0.09525)
		(layer "In4.Cu")
		(net "M_J_CPU1_SB_DQS_DP<9>")
	)
	(segment
		(start 182.945532 -274.81022)
		(end 184.716928 -274.81022)
		(width 0.16002)
		(layer "In4.Cu")
		(net "M_J_CPU1_SB_DQS_DP<9>")
	)
	(segment
		(start 181.22773 -275.97227)
		(end 181.771036 -275.428964)
		(width 0.16002)
		(layer "In4.Cu")
		(net "M_J_CPU1_SB_DQS_DP<9>")
	)
	(segment
		(start 186.458606 -275.47443)
		(end 186.938666 -275.47443)
		(width 0.16002)
		(layer "In4.Cu")
		(net "M_J_CPU1_SB_DQS_DP<9>")
	)
	(arc
		(start 139.053316 -271.171416)
		(mid 139.334748 -271.095661)
		(end 139.61618 -271.171416)
		(width 0.09525)
		(layer "In4.Cu")
		(net "M_J_CPU1_SB_DQS_DP<9>")
	)
	(arc
		(start 133.413246 -271.171416)
		(mid 133.694678 -271.095661)
		(end 133.97611 -271.171416)
		(width 0.09525)
		(layer "In4.Cu")
		(net "M_J_CPU1_SB_DQS_DP<9>")
	)
	(arc
		(start 142.436088 -271.171416)
		(mid 142.619863 -271.222188)
		(end 142.804896 -271.176242)
		(width 0.09525)
		(layer "In4.Cu")
		(net "M_J_CPU1_SB_DQS_DP<9>")
	)
	(arc
		(start 135.8646 -271.176242)
		(mid 136.049632 -271.222156)
		(end 136.233408 -271.171416)
		(width 0.09525)
		(layer "In4.Cu")
		(net "M_J_CPU1_SB_DQS_DP<9>")
	)
	(arc
		(start 141.496288 -271.171416)
		(mid 141.684756 -271.222093)
		(end 141.873224 -271.171416)
		(width 0.09525)
		(layer "In4.Cu")
		(net "M_J_CPU1_SB_DQS_DP<9>")
	)
	(arc
		(start 145.163286 -270.36141)
		(mid 145.255908 -270.31836)
		(end 145.354802 -270.29283)
		(width 0.09525)
		(layer "In4.Cu")
		(net "M_J_CPU1_SB_DQS_DP<9>")
	)
	(arc
		(start 139.99337 -271.171416)
		(mid 140.274802 -271.095661)
		(end 140.556234 -271.171416)
		(width 0.09525)
		(layer "In4.Cu")
		(net "M_J_CPU1_SB_DQS_DP<9>")
	)
	(arc
		(start 143.384524 -271.176242)
		(mid 143.569556 -271.222156)
		(end 143.753332 -271.171416)
		(width 0.09525)
		(layer "In4.Cu")
		(net "M_J_CPU1_SB_DQS_DP<9>")
	)
	(arc
		(start 134.3533 -271.171416)
		(mid 134.634732 -271.095661)
		(end 134.916164 -271.171416)
		(width 0.09525)
		(layer "In4.Cu")
		(net "M_J_CPU1_SB_DQS_DP<9>")
	)
	(arc
		(start 137.173208 -271.171416)
		(mid 137.45464 -271.095661)
		(end 137.736072 -271.171416)
		(width 0.09525)
		(layer "In4.Cu")
		(net "M_J_CPU1_SB_DQS_DP<9>")
	)
	(arc
		(start 133.093968 -271.19834)
		(mid 133.256619 -271.2206)
		(end 133.413246 -271.171416)
		(width 0.09525)
		(layer "In4.Cu")
		(net "M_J_CPU1_SB_DQS_DP<9>")
	)
	(arc
		(start 138.676126 -271.171416)
		(mid 138.859901 -271.222188)
		(end 139.044934 -271.176242)
		(width 0.09525)
		(layer "In4.Cu")
		(net "M_J_CPU1_SB_DQS_DP<9>")
	)
	(arc
		(start 134.924546 -271.176242)
		(mid 135.109578 -271.222156)
		(end 135.293354 -271.171416)
		(width 0.09525)
		(layer "In4.Cu")
		(net "M_J_CPU1_SB_DQS_DP<9>")
	)
	(arc
		(start 144.324578 -271.176242)
		(mid 144.50961 -271.222156)
		(end 144.693386 -271.171416)
		(width 0.09525)
		(layer "In4.Cu")
		(net "M_J_CPU1_SB_DQS_DP<9>")
	)
	(arc
		(start 138.113262 -271.171416)
		(mid 138.394694 -271.095661)
		(end 138.676126 -271.171416)
		(width 0.09525)
		(layer "In4.Cu")
		(net "M_J_CPU1_SB_DQS_DP<9>")
	)
	(arc
		(start 141.873224 -271.171416)
		(mid 142.154656 -271.095661)
		(end 142.436088 -271.171416)
		(width 0.09525)
		(layer "In4.Cu")
		(net "M_J_CPU1_SB_DQS_DP<9>")
	)
	(arc
		(start 135.293354 -271.171416)
		(mid 135.574786 -271.095661)
		(end 135.856218 -271.171416)
		(width 0.09525)
		(layer "In4.Cu")
		(net "M_J_CPU1_SB_DQS_DP<9>")
	)
	(arc
		(start 144.724882 -271.153128)
		(mid 144.84068 -271.018734)
		(end 144.882362 -270.846296)
		(width 0.09525)
		(layer "In4.Cu")
		(net "M_J_CPU1_SB_DQS_DP<9>")
	)
	(arc
		(start 137.736072 -271.171416)
		(mid 137.919847 -271.222188)
		(end 138.10488 -271.176242)
		(width 0.09525)
		(layer "In4.Cu")
		(net "M_J_CPU1_SB_DQS_DP<9>")
	)
	(arc
		(start 142.813278 -271.171416)
		(mid 143.09471 -271.095661)
		(end 143.376142 -271.171416)
		(width 0.09525)
		(layer "In4.Cu")
		(net "M_J_CPU1_SB_DQS_DP<9>")
	)
	(arc
		(start 144.882362 -270.846296)
		(mid 144.946759 -270.58499)
		(end 145.125186 -270.383508)
		(width 0.09525)
		(layer "In4.Cu")
		(net "M_J_CPU1_SB_DQS_DP<9>")
	)
	(arc
		(start 136.796272 -271.171416)
		(mid 136.98474 -271.222093)
		(end 137.173208 -271.171416)
		(width 0.09525)
		(layer "In4.Cu")
		(net "M_J_CPU1_SB_DQS_DP<9>")
	)
	(arc
		(start 140.933424 -271.171416)
		(mid 141.214856 -271.095661)
		(end 141.496288 -271.171416)
		(width 0.09525)
		(layer "In4.Cu")
		(net "M_J_CPU1_SB_DQS_DP<9>")
	)
	(arc
		(start 139.624562 -271.176242)
		(mid 139.809594 -271.222156)
		(end 139.99337 -271.171416)
		(width 0.09525)
		(layer "In4.Cu")
		(net "M_J_CPU1_SB_DQS_DP<9>")
	)
	(arc
		(start 145.354802 -270.29283)
		(mid 145.525068 -270.234273)
		(end 145.665952 -270.122142)
		(width 0.09525)
		(layer "In4.Cu")
		(net "M_J_CPU1_SB_DQS_DP<9>")
	)
	(arc
		(start 133.97611 -271.171416)
		(mid 134.159885 -271.222188)
		(end 134.344918 -271.176242)
		(width 0.09525)
		(layer "In4.Cu")
		(net "M_J_CPU1_SB_DQS_DP<9>")
	)
	(arc
		(start 136.233408 -271.171416)
		(mid 136.51484 -271.095661)
		(end 136.796272 -271.171416)
		(width 0.09525)
		(layer "In4.Cu")
		(net "M_J_CPU1_SB_DQS_DP<9>")
	)
	(arc
		(start 143.753332 -271.171416)
		(mid 144.019419 -271.095871)
		(end 144.289272 -271.156684)
		(width 0.09525)
		(layer "In4.Cu")
		(net "M_J_CPU1_SB_DQS_DP<9>")
	)
	(arc
		(start 140.564616 -271.176242)
		(mid 140.749648 -271.222156)
		(end 140.933424 -271.171416)
		(width 0.09525)
		(layer "In4.Cu")
		(net "M_J_CPU1_SB_DQS_DP<9>")
	)
	(segment
		(start 130.877818 -291.64026)
		(end 131.34467 -291.906198)
		(width 0.12954)
		(layer "F.Cu")
		(net "M_J_CPU1_SB_DQS_DP<8>")
	)
	(segment
		(start 144.316196 -291.581078)
		(end 144.324578 -291.576252)
		(width 0.09525)
		(layer "In4.Cu")
		(net "M_J_CPU1_SB_DQS_DP<8>")
	)
	(segment
		(start 165.37559 -315.218826)
		(end 165.59657 -314.997846)
		(width 0.16002)
		(layer "In4.Cu")
		(net "M_J_CPU1_SB_DQS_DP<8>")
	)
	(segment
		(start 146.292316 -294.336216)
		(end 146.292316 -294.560498)
		(width 0.09525)
		(layer "In4.Cu")
		(net "M_J_CPU1_SB_DQS_DP<8>")
	)
	(segment
		(start 135.856218 -291.581078)
		(end 135.8646 -291.576252)
		(width 0.09525)
		(layer "In4.Cu")
		(net "M_J_CPU1_SB_DQS_DP<8>")
	)
	(segment
		(start 145.822924 -293.407084)
		(end 145.822924 -293.525702)
		(width 0.09525)
		(layer "In4.Cu")
		(net "M_J_CPU1_SB_DQS_DP<8>")
	)
	(segment
		(start 161.554414 -314.44438)
		(end 161.750248 -314.248546)
		(width 0.16002)
		(layer "In4.Cu")
		(net "M_J_CPU1_SB_DQS_DP<8>")
	)
	(segment
		(start 132.096256 -291.581078)
		(end 132.104638 -291.576252)
		(width 0.09525)
		(layer "In4.Cu")
		(net "M_J_CPU1_SB_DQS_DP<8>")
	)
	(segment
		(start 161.207958 -315.19241)
		(end 161.554414 -314.845954)
		(width 0.16002)
		(layer "In4.Cu")
		(net "M_J_CPU1_SB_DQS_DP<8>")
	)
	(segment
		(start 162.59556 -315.218826)
		(end 163.12261 -315.218826)
		(width 0.16002)
		(layer "In4.Cu")
		(net "M_J_CPU1_SB_DQS_DP<8>")
	)
	(segment
		(start 146.858228 -295.20896)
		(end 146.874992 -295.225724)
		(width 0.09525)
		(layer "In4.Cu")
		(net "M_J_CPU1_SB_DQS_DP<8>")
	)
	(segment
		(start 146.074638 -293.994586)
		(end 146.134836 -294.029384)
		(width 0.09525)
		(layer "In4.Cu")
		(net "M_J_CPU1_SB_DQS_DP<8>")
	)
	(segment
		(start 165.59657 -314.997846)
		(end 166.06139 -314.997846)
		(width 0.16002)
		(layer "In4.Cu")
		(net "M_J_CPU1_SB_DQS_DP<8>")
	)
	(segment
		(start 142.804896 -291.576252)
		(end 142.813278 -291.581078)
		(width 0.09525)
		(layer "In4.Cu")
		(net "M_J_CPU1_SB_DQS_DP<8>")
	)
	(segment
		(start 160.730946 -315.19241)
		(end 161.207958 -315.19241)
		(width 0.16002)
		(layer "In4.Cu")
		(net "M_J_CPU1_SB_DQS_DP<8>")
	)
	(segment
		(start 139.044934 -291.576252)
		(end 139.053316 -291.581078)
		(width 0.09525)
		(layer "In4.Cu")
		(net "M_J_CPU1_SB_DQS_DP<8>")
	)
	(segment
		(start 182.91683 -314.545726)
		(end 184.66943 -314.545726)
		(width 0.16002)
		(layer "In4.Cu")
		(net "M_J_CPU1_SB_DQS_DP<8>")
	)
	(segment
		(start 145.82267 -293.407338)
		(end 145.822924 -293.407084)
		(width 0.09525)
		(layer "In4.Cu")
		(net "M_J_CPU1_SB_DQS_DP<8>")
	)
	(segment
		(start 182.09641 -314.169806)
		(end 182.54091 -314.169806)
		(width 0.16002)
		(layer "In4.Cu")
		(net "M_J_CPU1_SB_DQS_DP<8>")
	)
	(segment
		(start 163.12261 -315.218826)
		(end 163.495482 -314.845954)
		(width 0.16002)
		(layer "In4.Cu")
		(net "M_J_CPU1_SB_DQS_DP<8>")
	)
	(segment
		(start 184.66943 -314.545726)
		(end 184.853834 -314.361322)
		(width 0.16002)
		(layer "In4.Cu")
		(net "M_J_CPU1_SB_DQS_DP<8>")
	)
	(segment
		(start 172.677074 -315.360558)
		(end 173.019466 -315.018166)
		(width 0.16002)
		(layer "In4.Cu")
		(net "M_J_CPU1_SB_DQS_DP<8>")
	)
	(segment
		(start 138.10488 -291.576252)
		(end 138.113262 -291.581078)
		(width 0.09525)
		(layer "In4.Cu")
		(net "M_J_CPU1_SB_DQS_DP<8>")
	)
	(segment
		(start 146.857974 -295.125648)
		(end 146.858228 -295.20896)
		(width 0.09525)
		(layer "In4.Cu")
		(net "M_J_CPU1_SB_DQS_DP<8>")
	)
	(segment
		(start 144.882616 -291.906198)
		(end 144.88287 -291.906452)
		(width 0.09525)
		(layer "In4.Cu")
		(net "M_J_CPU1_SB_DQS_DP<8>")
	)
	(segment
		(start 131.498594 -291.640768)
		(end 131.599432 -291.614098)
		(width 0.09525)
		(layer "In4.Cu")
		(net "M_J_CPU1_SB_DQS_DP<8>")
	)
	(segment
		(start 146.073876 -293.994078)
		(end 146.074638 -293.994586)
		(width 0.09525)
		(layer "In4.Cu")
		(net "M_J_CPU1_SB_DQS_DP<8>")
	)
	(segment
		(start 170.935142 -315.360558)
		(end 172.677074 -315.360558)
		(width 0.16002)
		(layer "In4.Cu")
		(net "M_J_CPU1_SB_DQS_DP<8>")
	)
	(segment
		(start 164.536628 -315.218826)
		(end 165.37559 -315.218826)
		(width 0.16002)
		(layer "In4.Cu")
		(net "M_J_CPU1_SB_DQS_DP<8>")
	)
	(segment
		(start 144.693386 -291.581078)
		(end 144.724882 -291.599366)
		(width 0.09525)
		(layer "In4.Cu")
		(net "M_J_CPU1_SB_DQS_DP<8>")
	)
	(segment
		(start 140.556234 -291.581078)
		(end 140.564616 -291.576252)
		(width 0.09525)
		(layer "In4.Cu")
		(net "M_J_CPU1_SB_DQS_DP<8>")
	)
	(segment
		(start 144.882362 -291.906198)
		(end 144.882616 -291.906198)
		(width 0.09525)
		(layer "In4.Cu")
		(net "M_J_CPU1_SB_DQS_DP<8>")
	)
	(segment
		(start 139.61618 -291.581078)
		(end 139.624562 -291.576252)
		(width 0.09525)
		(layer "In4.Cu")
		(net "M_J_CPU1_SB_DQS_DP<8>")
	)
	(segment
		(start 161.554414 -314.845954)
		(end 161.554414 -314.44438)
		(width 0.16002)
		(layer "In4.Cu")
		(net "M_J_CPU1_SB_DQS_DP<8>")
	)
	(segment
		(start 146.06524 -293.988998)
		(end 146.073876 -293.994078)
		(width 0.09525)
		(layer "In4.Cu")
		(net "M_J_CPU1_SB_DQS_DP<8>")
	)
	(segment
		(start 176.46777 -314.741306)
		(end 177.087022 -315.360558)
		(width 0.16002)
		(layer "In4.Cu")
		(net "M_J_CPU1_SB_DQS_DP<8>")
	)
	(segment
		(start 163.967922 -314.248546)
		(end 164.163756 -314.44438)
		(width 0.16002)
		(layer "In4.Cu")
		(net "M_J_CPU1_SB_DQS_DP<8>")
	)
	(segment
		(start 147.06219 -295.41216)
		(end 147.06219 -301.523654)
		(width 0.16002)
		(layer "In4.Cu")
		(net "M_J_CPU1_SB_DQS_DP<8>")
	)
	(segment
		(start 145.822924 -293.525702)
		(end 145.822416 -293.52621)
		(width 0.09525)
		(layer "In4.Cu")
		(net "M_J_CPU1_SB_DQS_DP<8>")
	)
	(segment
		(start 146.292316 -294.560498)
		(end 146.857974 -295.125648)
		(width 0.09525)
		(layer "In4.Cu")
		(net "M_J_CPU1_SB_DQS_DP<8>")
	)
	(segment
		(start 162.222688 -314.845954)
		(end 162.59556 -315.218826)
		(width 0.16002)
		(layer "In4.Cu")
		(net "M_J_CPU1_SB_DQS_DP<8>")
	)
	(segment
		(start 164.163756 -314.845954)
		(end 164.536628 -315.218826)
		(width 0.16002)
		(layer "In4.Cu")
		(net "M_J_CPU1_SB_DQS_DP<8>")
	)
	(segment
		(start 169.71899 -314.144406)
		(end 170.935142 -315.360558)
		(width 0.16002)
		(layer "In4.Cu")
		(net "M_J_CPU1_SB_DQS_DP<8>")
	)
	(segment
		(start 163.495482 -314.845954)
		(end 163.495482 -314.44438)
		(width 0.16002)
		(layer "In4.Cu")
		(net "M_J_CPU1_SB_DQS_DP<8>")
	)
	(segment
		(start 174.997364 -314.143136)
		(end 175.595534 -314.741306)
		(width 0.16002)
		(layer "In4.Cu")
		(net "M_J_CPU1_SB_DQS_DP<8>")
	)
	(segment
		(start 181.24805 -315.018166)
		(end 182.09641 -314.169806)
		(width 0.16002)
		(layer "In4.Cu")
		(net "M_J_CPU1_SB_DQS_DP<8>")
	)
	(segment
		(start 145.060162 -292.334442)
		(end 145.603468 -292.877748)
		(width 0.09525)
		(layer "In4.Cu")
		(net "M_J_CPU1_SB_DQS_DP<8>")
	)
	(segment
		(start 184.853834 -314.361322)
		(end 186.786012 -314.361322)
		(width 0.16002)
		(layer "In4.Cu")
		(net "M_J_CPU1_SB_DQS_DP<8>")
	)
	(segment
		(start 182.54091 -314.169806)
		(end 182.91683 -314.545726)
		(width 0.16002)
		(layer "In4.Cu")
		(net "M_J_CPU1_SB_DQS_DP<8>")
	)
	(segment
		(start 173.59249 -315.018166)
		(end 174.46752 -314.143136)
		(width 0.16002)
		(layer "In4.Cu")
		(net "M_J_CPU1_SB_DQS_DP<8>")
	)
	(segment
		(start 164.163756 -314.44438)
		(end 164.163756 -314.845954)
		(width 0.16002)
		(layer "In4.Cu")
		(net "M_J_CPU1_SB_DQS_DP<8>")
	)
	(segment
		(start 161.750248 -314.248546)
		(end 162.026854 -314.248546)
		(width 0.16002)
		(layer "In4.Cu")
		(net "M_J_CPU1_SB_DQS_DP<8>")
	)
	(segment
		(start 162.222688 -314.44438)
		(end 162.222688 -314.845954)
		(width 0.16002)
		(layer "In4.Cu")
		(net "M_J_CPU1_SB_DQS_DP<8>")
	)
	(segment
		(start 131.34467 -291.906198)
		(end 131.498594 -291.640768)
		(width 0.09525)
		(layer "In4.Cu")
		(net "M_J_CPU1_SB_DQS_DP<8>")
	)
	(segment
		(start 147.06219 -301.523654)
		(end 160.730946 -315.19241)
		(width 0.16002)
		(layer "In4.Cu")
		(net "M_J_CPU1_SB_DQS_DP<8>")
	)
	(segment
		(start 180.227478 -315.360558)
		(end 180.56987 -315.018166)
		(width 0.16002)
		(layer "In4.Cu")
		(net "M_J_CPU1_SB_DQS_DP<8>")
	)
	(segment
		(start 162.026854 -314.248546)
		(end 162.222688 -314.44438)
		(width 0.16002)
		(layer "In4.Cu")
		(net "M_J_CPU1_SB_DQS_DP<8>")
	)
	(segment
		(start 143.376142 -291.581078)
		(end 143.384524 -291.576252)
		(width 0.09525)
		(layer "In4.Cu")
		(net "M_J_CPU1_SB_DQS_DP<8>")
	)
	(segment
		(start 134.916164 -291.581078)
		(end 134.924546 -291.576252)
		(width 0.09525)
		(layer "In4.Cu")
		(net "M_J_CPU1_SB_DQS_DP<8>")
	)
	(segment
		(start 166.06139 -314.997846)
		(end 166.91483 -314.144406)
		(width 0.16002)
		(layer "In4.Cu")
		(net "M_J_CPU1_SB_DQS_DP<8>")
	)
	(segment
		(start 177.087022 -315.360558)
		(end 180.227478 -315.360558)
		(width 0.16002)
		(layer "In4.Cu")
		(net "M_J_CPU1_SB_DQS_DP<8>")
	)
	(segment
		(start 180.56987 -315.018166)
		(end 181.24805 -315.018166)
		(width 0.16002)
		(layer "In4.Cu")
		(net "M_J_CPU1_SB_DQS_DP<8>")
	)
	(segment
		(start 175.595534 -314.741306)
		(end 176.46777 -314.741306)
		(width 0.16002)
		(layer "In4.Cu")
		(net "M_J_CPU1_SB_DQS_DP<8>")
	)
	(segment
		(start 186.786012 -314.361322)
		(end 187.060078 -314.635388)
		(width 0.16002)
		(layer "In4.Cu")
		(net "M_J_CPU1_SB_DQS_DP<8>")
	)
	(segment
		(start 134.344918 -291.576252)
		(end 134.3533 -291.581078)
		(width 0.09525)
		(layer "In4.Cu")
		(net "M_J_CPU1_SB_DQS_DP<8>")
	)
	(segment
		(start 163.691316 -314.248546)
		(end 163.967922 -314.248546)
		(width 0.16002)
		(layer "In4.Cu")
		(net "M_J_CPU1_SB_DQS_DP<8>")
	)
	(segment
		(start 166.91483 -314.144406)
		(end 169.71899 -314.144406)
		(width 0.16002)
		(layer "In4.Cu")
		(net "M_J_CPU1_SB_DQS_DP<8>")
	)
	(segment
		(start 146.874992 -295.225724)
		(end 147.06219 -295.41216)
		(width 0.16002)
		(layer "In4.Cu")
		(net "M_J_CPU1_SB_DQS_DP<8>")
	)
	(segment
		(start 163.495482 -314.44438)
		(end 163.691316 -314.248546)
		(width 0.16002)
		(layer "In4.Cu")
		(net "M_J_CPU1_SB_DQS_DP<8>")
	)
	(segment
		(start 173.019466 -315.018166)
		(end 173.59249 -315.018166)
		(width 0.16002)
		(layer "In4.Cu")
		(net "M_J_CPU1_SB_DQS_DP<8>")
	)
	(segment
		(start 174.46752 -314.143136)
		(end 174.997364 -314.143136)
		(width 0.16002)
		(layer "In4.Cu")
		(net "M_J_CPU1_SB_DQS_DP<8>")
	)
	(arc
		(start 139.99337 -291.581078)
		(mid 140.274802 -291.656833)
		(end 140.556234 -291.581078)
		(width 0.09525)
		(layer "In4.Cu")
		(net "M_J_CPU1_SB_DQS_DP<8>")
	)
	(arc
		(start 144.724882 -291.599366)
		(mid 144.84068 -291.73376)
		(end 144.882362 -291.906198)
		(width 0.09525)
		(layer "In4.Cu")
		(net "M_J_CPU1_SB_DQS_DP<8>")
	)
	(arc
		(start 137.173208 -291.581078)
		(mid 137.45464 -291.656833)
		(end 137.736072 -291.581078)
		(width 0.09525)
		(layer "In4.Cu")
		(net "M_J_CPU1_SB_DQS_DP<8>")
	)
	(arc
		(start 131.599432 -291.614098)
		(mid 131.60968 -291.618261)
		(end 131.620006 -291.622226)
		(width 0.09525)
		(layer "In4.Cu")
		(net "M_J_CPU1_SB_DQS_DP<8>")
	)
	(arc
		(start 145.822416 -293.52621)
		(mid 145.886813 -293.787516)
		(end 146.06524 -293.988998)
		(width 0.09525)
		(layer "In4.Cu")
		(net "M_J_CPU1_SB_DQS_DP<8>")
	)
	(arc
		(start 132.473446 -291.581078)
		(mid 132.754878 -291.656833)
		(end 133.03631 -291.581078)
		(width 0.09525)
		(layer "In4.Cu")
		(net "M_J_CPU1_SB_DQS_DP<8>")
	)
	(arc
		(start 138.676126 -291.581078)
		(mid 138.859901 -291.530306)
		(end 139.044934 -291.576252)
		(width 0.09525)
		(layer "In4.Cu")
		(net "M_J_CPU1_SB_DQS_DP<8>")
	)
	(arc
		(start 137.736072 -291.581078)
		(mid 137.919847 -291.530306)
		(end 138.10488 -291.576252)
		(width 0.09525)
		(layer "In4.Cu")
		(net "M_J_CPU1_SB_DQS_DP<8>")
	)
	(arc
		(start 133.413246 -291.581078)
		(mid 133.694678 -291.656833)
		(end 133.97611 -291.581078)
		(width 0.09525)
		(layer "In4.Cu")
		(net "M_J_CPU1_SB_DQS_DP<8>")
	)
	(arc
		(start 132.104638 -291.576252)
		(mid 132.28967 -291.530338)
		(end 132.473446 -291.581078)
		(width 0.09525)
		(layer "In4.Cu")
		(net "M_J_CPU1_SB_DQS_DP<8>")
	)
	(arc
		(start 135.8646 -291.576252)
		(mid 136.049632 -291.530338)
		(end 136.233408 -291.581078)
		(width 0.09525)
		(layer "In4.Cu")
		(net "M_J_CPU1_SB_DQS_DP<8>")
	)
	(arc
		(start 143.384524 -291.576252)
		(mid 143.569556 -291.530338)
		(end 143.753332 -291.581078)
		(width 0.09525)
		(layer "In4.Cu")
		(net "M_J_CPU1_SB_DQS_DP<8>")
	)
	(arc
		(start 141.496288 -291.581078)
		(mid 141.684756 -291.530401)
		(end 141.873224 -291.581078)
		(width 0.09525)
		(layer "In4.Cu")
		(net "M_J_CPU1_SB_DQS_DP<8>")
	)
	(arc
		(start 141.873224 -291.581078)
		(mid 142.154656 -291.656833)
		(end 142.436088 -291.581078)
		(width 0.09525)
		(layer "In4.Cu")
		(net "M_J_CPU1_SB_DQS_DP<8>")
	)
	(arc
		(start 133.97611 -291.581078)
		(mid 134.159885 -291.530306)
		(end 134.344918 -291.576252)
		(width 0.09525)
		(layer "In4.Cu")
		(net "M_J_CPU1_SB_DQS_DP<8>")
	)
	(arc
		(start 138.113262 -291.581078)
		(mid 138.394694 -291.656833)
		(end 138.676126 -291.581078)
		(width 0.09525)
		(layer "In4.Cu")
		(net "M_J_CPU1_SB_DQS_DP<8>")
	)
	(arc
		(start 145.603468 -292.877748)
		(mid 145.765684 -293.120755)
		(end 145.82267 -293.407338)
		(width 0.09525)
		(layer "In4.Cu")
		(net "M_J_CPU1_SB_DQS_DP<8>")
	)
	(arc
		(start 142.436088 -291.581078)
		(mid 142.619863 -291.530306)
		(end 142.804896 -291.576252)
		(width 0.09525)
		(layer "In4.Cu")
		(net "M_J_CPU1_SB_DQS_DP<8>")
	)
	(arc
		(start 134.3533 -291.581078)
		(mid 134.634732 -291.656833)
		(end 134.916164 -291.581078)
		(width 0.09525)
		(layer "In4.Cu")
		(net "M_J_CPU1_SB_DQS_DP<8>")
	)
	(arc
		(start 142.813278 -291.581078)
		(mid 143.09471 -291.656833)
		(end 143.376142 -291.581078)
		(width 0.09525)
		(layer "In4.Cu")
		(net "M_J_CPU1_SB_DQS_DP<8>")
	)
	(arc
		(start 143.753332 -291.581078)
		(mid 144.034764 -291.656833)
		(end 144.316196 -291.581078)
		(width 0.09525)
		(layer "In4.Cu")
		(net "M_J_CPU1_SB_DQS_DP<8>")
	)
	(arc
		(start 131.620006 -291.622226)
		(mid 131.862748 -291.654996)
		(end 132.096256 -291.581078)
		(width 0.09525)
		(layer "In4.Cu")
		(net "M_J_CPU1_SB_DQS_DP<8>")
	)
	(arc
		(start 140.933424 -291.581078)
		(mid 141.214856 -291.656833)
		(end 141.496288 -291.581078)
		(width 0.09525)
		(layer "In4.Cu")
		(net "M_J_CPU1_SB_DQS_DP<8>")
	)
	(arc
		(start 135.293354 -291.581078)
		(mid 135.574786 -291.656833)
		(end 135.856218 -291.581078)
		(width 0.09525)
		(layer "In4.Cu")
		(net "M_J_CPU1_SB_DQS_DP<8>")
	)
	(arc
		(start 139.624562 -291.576252)
		(mid 139.809594 -291.530338)
		(end 139.99337 -291.581078)
		(width 0.09525)
		(layer "In4.Cu")
		(net "M_J_CPU1_SB_DQS_DP<8>")
	)
	(arc
		(start 144.324578 -291.576252)
		(mid 144.50961 -291.530338)
		(end 144.693386 -291.581078)
		(width 0.09525)
		(layer "In4.Cu")
		(net "M_J_CPU1_SB_DQS_DP<8>")
	)
	(arc
		(start 140.564616 -291.576252)
		(mid 140.749648 -291.530338)
		(end 140.933424 -291.581078)
		(width 0.09525)
		(layer "In4.Cu")
		(net "M_J_CPU1_SB_DQS_DP<8>")
	)
	(arc
		(start 139.053316 -291.581078)
		(mid 139.334748 -291.656833)
		(end 139.61618 -291.581078)
		(width 0.09525)
		(layer "In4.Cu")
		(net "M_J_CPU1_SB_DQS_DP<8>")
	)
	(arc
		(start 136.233408 -291.581078)
		(mid 136.51484 -291.656833)
		(end 136.796272 -291.581078)
		(width 0.09525)
		(layer "In4.Cu")
		(net "M_J_CPU1_SB_DQS_DP<8>")
	)
	(arc
		(start 134.924546 -291.576252)
		(mid 135.109578 -291.530338)
		(end 135.293354 -291.581078)
		(width 0.09525)
		(layer "In4.Cu")
		(net "M_J_CPU1_SB_DQS_DP<8>")
	)
	(arc
		(start 133.03631 -291.581078)
		(mid 133.224778 -291.530401)
		(end 133.413246 -291.581078)
		(width 0.09525)
		(layer "In4.Cu")
		(net "M_J_CPU1_SB_DQS_DP<8>")
	)
	(arc
		(start 144.88287 -291.906452)
		(mid 144.929012 -292.138044)
		(end 145.060162 -292.334442)
		(width 0.09525)
		(layer "In4.Cu")
		(net "M_J_CPU1_SB_DQS_DP<8>")
	)
	(arc
		(start 136.796272 -291.581078)
		(mid 136.98474 -291.530401)
		(end 137.173208 -291.581078)
		(width 0.09525)
		(layer "In4.Cu")
		(net "M_J_CPU1_SB_DQS_DP<8>")
	)
	(arc
		(start 146.134836 -294.029384)
		(mid 146.250634 -294.163778)
		(end 146.292316 -294.336216)
		(width 0.09525)
		(layer "In4.Cu")
		(net "M_J_CPU1_SB_DQS_DP<8>")
	)
	(segment
		(start 130.877818 -286.780478)
		(end 131.34467 -287.046162)
		(width 0.12954)
		(layer "F.Cu")
		(net "M_J_CPU1_SB_DQS_DP<7>")
	)
	(segment
		(start 182.09641 -304.819812)
		(end 182.54091 -304.819812)
		(width 0.16002)
		(layer "In4.Cu")
		(net "M_J_CPU1_SB_DQS_DP<7>")
	)
	(segment
		(start 166.06139 -305.647852)
		(end 166.91483 -304.794412)
		(width 0.16002)
		(layer "In4.Cu")
		(net "M_J_CPU1_SB_DQS_DP<7>")
	)
	(segment
		(start 131.34467 -287.046162)
		(end 131.498594 -286.780732)
		(width 0.09525)
		(layer "In4.Cu")
		(net "M_J_CPU1_SB_DQS_DP<7>")
	)
	(segment
		(start 142.804896 -286.716216)
		(end 142.813278 -286.721042)
		(width 0.09525)
		(layer "In4.Cu")
		(net "M_J_CPU1_SB_DQS_DP<7>")
	)
	(segment
		(start 143.376142 -286.721042)
		(end 143.384524 -286.716216)
		(width 0.09525)
		(layer "In4.Cu")
		(net "M_J_CPU1_SB_DQS_DP<7>")
	)
	(segment
		(start 165.347396 -306.001674)
		(end 165.701218 -305.647852)
		(width 0.16002)
		(layer "In4.Cu")
		(net "M_J_CPU1_SB_DQS_DP<7>")
	)
	(segment
		(start 179.009294 -306.010564)
		(end 180.227478 -306.010564)
		(width 0.16002)
		(layer "In4.Cu")
		(net "M_J_CPU1_SB_DQS_DP<7>")
	)
	(segment
		(start 161.933382 -304.941986)
		(end 162.129216 -305.13782)
		(width 0.16002)
		(layer "In4.Cu")
		(net "M_J_CPU1_SB_DQS_DP<7>")
	)
	(segment
		(start 152.63495 -292.749986)
		(end 152.63495 -298.168822)
		(width 0.16002)
		(layer "In4.Cu")
		(net "M_J_CPU1_SB_DQS_DP<7>")
	)
	(segment
		(start 174.46752 -304.793142)
		(end 174.997364 -304.793142)
		(width 0.16002)
		(layer "In4.Cu")
		(net "M_J_CPU1_SB_DQS_DP<7>")
	)
	(segment
		(start 186.786012 -305.011328)
		(end 187.060078 -305.285394)
		(width 0.16002)
		(layer "In4.Cu")
		(net "M_J_CPU1_SB_DQS_DP<7>")
	)
	(segment
		(start 164.443156 -306.001674)
		(end 165.347396 -306.001674)
		(width 0.16002)
		(layer "In4.Cu")
		(net "M_J_CPU1_SB_DQS_DP<7>")
	)
	(segment
		(start 184.704736 -305.160426)
		(end 184.853834 -305.011328)
		(width 0.16002)
		(layer "In4.Cu")
		(net "M_J_CPU1_SB_DQS_DP<7>")
	)
	(segment
		(start 184.853834 -305.011328)
		(end 186.786012 -305.011328)
		(width 0.16002)
		(layer "In4.Cu")
		(net "M_J_CPU1_SB_DQS_DP<7>")
	)
	(segment
		(start 163.40201 -305.13782)
		(end 163.597844 -304.941986)
		(width 0.16002)
		(layer "In4.Cu")
		(net "M_J_CPU1_SB_DQS_DP<7>")
	)
	(segment
		(start 147.688554 -287.720786)
		(end 147.688554 -287.80359)
		(width 0.09525)
		(layer "In4.Cu")
		(net "M_J_CPU1_SB_DQS_DP<7>")
	)
	(segment
		(start 147.2438 -287.165796)
		(end 147.474178 -287.396174)
		(width 0.09525)
		(layer "In4.Cu")
		(net "M_J_CPU1_SB_DQS_DP<7>")
	)
	(segment
		(start 164.070284 -305.628802)
		(end 164.443156 -306.001674)
		(width 0.16002)
		(layer "In4.Cu")
		(net "M_J_CPU1_SB_DQS_DP<7>")
	)
	(segment
		(start 161.656776 -304.941986)
		(end 161.933382 -304.941986)
		(width 0.16002)
		(layer "In4.Cu")
		(net "M_J_CPU1_SB_DQS_DP<7>")
	)
	(segment
		(start 132.096256 -286.721042)
		(end 132.104638 -286.716216)
		(width 0.09525)
		(layer "In4.Cu")
		(net "M_J_CPU1_SB_DQS_DP<7>")
	)
	(segment
		(start 174.997364 -304.793142)
		(end 175.364648 -305.160426)
		(width 0.16002)
		(layer "In4.Cu")
		(net "M_J_CPU1_SB_DQS_DP<7>")
	)
	(segment
		(start 147.705318 -287.820354)
		(end 152.63495 -292.749986)
		(width 0.16002)
		(layer "In4.Cu")
		(net "M_J_CPU1_SB_DQS_DP<7>")
	)
	(segment
		(start 147.474178 -287.506156)
		(end 147.688554 -287.720786)
		(width 0.09525)
		(layer "In4.Cu")
		(net "M_J_CPU1_SB_DQS_DP<7>")
	)
	(segment
		(start 160.45688 -305.990752)
		(end 161.098992 -305.990752)
		(width 0.16002)
		(layer "In4.Cu")
		(net "M_J_CPU1_SB_DQS_DP<7>")
	)
	(segment
		(start 163.87445 -304.941986)
		(end 164.070284 -305.13782)
		(width 0.16002)
		(layer "In4.Cu")
		(net "M_J_CPU1_SB_DQS_DP<7>")
	)
	(segment
		(start 131.498594 -286.780732)
		(end 131.599432 -286.754062)
		(width 0.09525)
		(layer "In4.Cu")
		(net "M_J_CPU1_SB_DQS_DP<7>")
	)
	(segment
		(start 135.856218 -286.721042)
		(end 135.8646 -286.716216)
		(width 0.09525)
		(layer "In4.Cu")
		(net "M_J_CPU1_SB_DQS_DP<7>")
	)
	(segment
		(start 164.070284 -305.13782)
		(end 164.070284 -305.628802)
		(width 0.16002)
		(layer "In4.Cu")
		(net "M_J_CPU1_SB_DQS_DP<7>")
	)
	(segment
		(start 161.460942 -305.13782)
		(end 161.656776 -304.941986)
		(width 0.16002)
		(layer "In4.Cu")
		(net "M_J_CPU1_SB_DQS_DP<7>")
	)
	(segment
		(start 180.56987 -305.668172)
		(end 181.24805 -305.668172)
		(width 0.16002)
		(layer "In4.Cu")
		(net "M_J_CPU1_SB_DQS_DP<7>")
	)
	(segment
		(start 147.474178 -287.396174)
		(end 147.474178 -287.506156)
		(width 0.09525)
		(layer "In4.Cu")
		(net "M_J_CPU1_SB_DQS_DP<7>")
	)
	(segment
		(start 143.753332 -286.721042)
		(end 143.763746 -286.727138)
		(width 0.09525)
		(layer "In4.Cu")
		(net "M_J_CPU1_SB_DQS_DP<7>")
	)
	(segment
		(start 144.505426 -286.669734)
		(end 146.077686 -286.669734)
		(width 0.09525)
		(layer "In4.Cu")
		(net "M_J_CPU1_SB_DQS_DP<7>")
	)
	(segment
		(start 161.098992 -305.990752)
		(end 161.460942 -305.628802)
		(width 0.16002)
		(layer "In4.Cu")
		(net "M_J_CPU1_SB_DQS_DP<7>")
	)
	(segment
		(start 162.129216 -305.628802)
		(end 162.502088 -306.001674)
		(width 0.16002)
		(layer "In4.Cu")
		(net "M_J_CPU1_SB_DQS_DP<7>")
	)
	(segment
		(start 152.63495 -298.168822)
		(end 160.45688 -305.990752)
		(width 0.16002)
		(layer "In4.Cu")
		(net "M_J_CPU1_SB_DQS_DP<7>")
	)
	(segment
		(start 146.077686 -286.669734)
		(end 146.573748 -287.165796)
		(width 0.09525)
		(layer "In4.Cu")
		(net "M_J_CPU1_SB_DQS_DP<7>")
	)
	(segment
		(start 169.71899 -304.794412)
		(end 170.935142 -306.010564)
		(width 0.16002)
		(layer "In4.Cu")
		(net "M_J_CPU1_SB_DQS_DP<7>")
	)
	(segment
		(start 139.61618 -286.721042)
		(end 139.624562 -286.716216)
		(width 0.09525)
		(layer "In4.Cu")
		(net "M_J_CPU1_SB_DQS_DP<7>")
	)
	(segment
		(start 180.227478 -306.010564)
		(end 180.56987 -305.668172)
		(width 0.16002)
		(layer "In4.Cu")
		(net "M_J_CPU1_SB_DQS_DP<7>")
	)
	(segment
		(start 140.556234 -286.721042)
		(end 140.564616 -286.716216)
		(width 0.09525)
		(layer "In4.Cu")
		(net "M_J_CPU1_SB_DQS_DP<7>")
	)
	(segment
		(start 172.677074 -306.010564)
		(end 173.019466 -305.668172)
		(width 0.16002)
		(layer "In4.Cu")
		(net "M_J_CPU1_SB_DQS_DP<7>")
	)
	(segment
		(start 134.344918 -286.716216)
		(end 134.3533 -286.721042)
		(width 0.09525)
		(layer "In4.Cu")
		(net "M_J_CPU1_SB_DQS_DP<7>")
	)
	(segment
		(start 162.129216 -305.13782)
		(end 162.129216 -305.628802)
		(width 0.16002)
		(layer "In4.Cu")
		(net "M_J_CPU1_SB_DQS_DP<7>")
	)
	(segment
		(start 173.019466 -305.668172)
		(end 173.59249 -305.668172)
		(width 0.16002)
		(layer "In4.Cu")
		(net "M_J_CPU1_SB_DQS_DP<7>")
	)
	(segment
		(start 170.935142 -306.010564)
		(end 172.677074 -306.010564)
		(width 0.16002)
		(layer "In4.Cu")
		(net "M_J_CPU1_SB_DQS_DP<7>")
	)
	(segment
		(start 182.881524 -305.160426)
		(end 184.704736 -305.160426)
		(width 0.16002)
		(layer "In4.Cu")
		(net "M_J_CPU1_SB_DQS_DP<7>")
	)
	(segment
		(start 163.597844 -304.941986)
		(end 163.87445 -304.941986)
		(width 0.16002)
		(layer "In4.Cu")
		(net "M_J_CPU1_SB_DQS_DP<7>")
	)
	(segment
		(start 146.573748 -287.165796)
		(end 147.2438 -287.165796)
		(width 0.09525)
		(layer "In4.Cu")
		(net "M_J_CPU1_SB_DQS_DP<7>")
	)
	(segment
		(start 147.688554 -287.80359)
		(end 147.705318 -287.820354)
		(width 0.09525)
		(layer "In4.Cu")
		(net "M_J_CPU1_SB_DQS_DP<7>")
	)
	(segment
		(start 182.54091 -304.819812)
		(end 182.881524 -305.160426)
		(width 0.16002)
		(layer "In4.Cu")
		(net "M_J_CPU1_SB_DQS_DP<7>")
	)
	(segment
		(start 173.59249 -305.668172)
		(end 174.46752 -304.793142)
		(width 0.16002)
		(layer "In4.Cu")
		(net "M_J_CPU1_SB_DQS_DP<7>")
	)
	(segment
		(start 134.916164 -286.721042)
		(end 134.924546 -286.716216)
		(width 0.09525)
		(layer "In4.Cu")
		(net "M_J_CPU1_SB_DQS_DP<7>")
	)
	(segment
		(start 166.91483 -304.794412)
		(end 169.71899 -304.794412)
		(width 0.16002)
		(layer "In4.Cu")
		(net "M_J_CPU1_SB_DQS_DP<7>")
	)
	(segment
		(start 165.701218 -305.647852)
		(end 166.06139 -305.647852)
		(width 0.16002)
		(layer "In4.Cu")
		(net "M_J_CPU1_SB_DQS_DP<7>")
	)
	(segment
		(start 139.044934 -286.716216)
		(end 139.053316 -286.721042)
		(width 0.09525)
		(layer "In4.Cu")
		(net "M_J_CPU1_SB_DQS_DP<7>")
	)
	(segment
		(start 162.502088 -306.001674)
		(end 163.029138 -306.001674)
		(width 0.16002)
		(layer "In4.Cu")
		(net "M_J_CPU1_SB_DQS_DP<7>")
	)
	(segment
		(start 161.460942 -305.628802)
		(end 161.460942 -305.13782)
		(width 0.16002)
		(layer "In4.Cu")
		(net "M_J_CPU1_SB_DQS_DP<7>")
	)
	(segment
		(start 138.10488 -286.716216)
		(end 138.113262 -286.721042)
		(width 0.09525)
		(layer "In4.Cu")
		(net "M_J_CPU1_SB_DQS_DP<7>")
	)
	(segment
		(start 144.31645 -286.721042)
		(end 144.31645 -286.720788)
		(width 0.09525)
		(layer "In4.Cu")
		(net "M_J_CPU1_SB_DQS_DP<7>")
	)
	(segment
		(start 181.24805 -305.668172)
		(end 182.09641 -304.819812)
		(width 0.16002)
		(layer "In4.Cu")
		(net "M_J_CPU1_SB_DQS_DP<7>")
	)
	(segment
		(start 163.40201 -305.628802)
		(end 163.40201 -305.13782)
		(width 0.16002)
		(layer "In4.Cu")
		(net "M_J_CPU1_SB_DQS_DP<7>")
	)
	(segment
		(start 175.364648 -305.160426)
		(end 178.159156 -305.160426)
		(width 0.16002)
		(layer "In4.Cu")
		(net "M_J_CPU1_SB_DQS_DP<7>")
	)
	(segment
		(start 163.029138 -306.001674)
		(end 163.40201 -305.628802)
		(width 0.16002)
		(layer "In4.Cu")
		(net "M_J_CPU1_SB_DQS_DP<7>")
	)
	(segment
		(start 178.159156 -305.160426)
		(end 179.009294 -306.010564)
		(width 0.16002)
		(layer "In4.Cu")
		(net "M_J_CPU1_SB_DQS_DP<7>")
	)
	(arc
		(start 139.624562 -286.716216)
		(mid 139.809594 -286.670302)
		(end 139.99337 -286.721042)
		(width 0.09525)
		(layer "In4.Cu")
		(net "M_J_CPU1_SB_DQS_DP<7>")
	)
	(arc
		(start 138.676126 -286.721042)
		(mid 138.859901 -286.67027)
		(end 139.044934 -286.716216)
		(width 0.09525)
		(layer "In4.Cu")
		(net "M_J_CPU1_SB_DQS_DP<7>")
	)
	(arc
		(start 134.924546 -286.716216)
		(mid 135.109578 -286.670302)
		(end 135.293354 -286.721042)
		(width 0.09525)
		(layer "In4.Cu")
		(net "M_J_CPU1_SB_DQS_DP<7>")
	)
	(arc
		(start 144.31645 -286.720788)
		(mid 144.407568 -286.682801)
		(end 144.505426 -286.669734)
		(width 0.09525)
		(layer "In4.Cu")
		(net "M_J_CPU1_SB_DQS_DP<7>")
	)
	(arc
		(start 136.233408 -286.721042)
		(mid 136.51484 -286.796831)
		(end 136.796272 -286.721042)
		(width 0.09525)
		(layer "In4.Cu")
		(net "M_J_CPU1_SB_DQS_DP<7>")
	)
	(arc
		(start 143.384524 -286.716216)
		(mid 143.569556 -286.670302)
		(end 143.753332 -286.721042)
		(width 0.09525)
		(layer "In4.Cu")
		(net "M_J_CPU1_SB_DQS_DP<7>")
	)
	(arc
		(start 140.933424 -286.721042)
		(mid 141.214856 -286.796831)
		(end 141.496288 -286.721042)
		(width 0.09525)
		(layer "In4.Cu")
		(net "M_J_CPU1_SB_DQS_DP<7>")
	)
	(arc
		(start 132.473446 -286.721042)
		(mid 132.754878 -286.796831)
		(end 133.03631 -286.721042)
		(width 0.09525)
		(layer "In4.Cu")
		(net "M_J_CPU1_SB_DQS_DP<7>")
	)
	(arc
		(start 133.97611 -286.721042)
		(mid 134.159885 -286.67027)
		(end 134.344918 -286.716216)
		(width 0.09525)
		(layer "In4.Cu")
		(net "M_J_CPU1_SB_DQS_DP<7>")
	)
	(arc
		(start 139.053316 -286.721042)
		(mid 139.334748 -286.796831)
		(end 139.61618 -286.721042)
		(width 0.09525)
		(layer "In4.Cu")
		(net "M_J_CPU1_SB_DQS_DP<7>")
	)
	(arc
		(start 143.763746 -286.727138)
		(mid 144.040908 -286.79697)
		(end 144.31645 -286.721042)
		(width 0.09525)
		(layer "In4.Cu")
		(net "M_J_CPU1_SB_DQS_DP<7>")
	)
	(arc
		(start 135.293354 -286.721042)
		(mid 135.574786 -286.796831)
		(end 135.856218 -286.721042)
		(width 0.09525)
		(layer "In4.Cu")
		(net "M_J_CPU1_SB_DQS_DP<7>")
	)
	(arc
		(start 136.796272 -286.721042)
		(mid 136.98474 -286.670365)
		(end 137.173208 -286.721042)
		(width 0.09525)
		(layer "In4.Cu")
		(net "M_J_CPU1_SB_DQS_DP<7>")
	)
	(arc
		(start 139.99337 -286.721042)
		(mid 140.274802 -286.796831)
		(end 140.556234 -286.721042)
		(width 0.09525)
		(layer "In4.Cu")
		(net "M_J_CPU1_SB_DQS_DP<7>")
	)
	(arc
		(start 141.873224 -286.721042)
		(mid 142.154656 -286.796831)
		(end 142.436088 -286.721042)
		(width 0.09525)
		(layer "In4.Cu")
		(net "M_J_CPU1_SB_DQS_DP<7>")
	)
	(arc
		(start 142.813278 -286.721042)
		(mid 143.09471 -286.796831)
		(end 143.376142 -286.721042)
		(width 0.09525)
		(layer "In4.Cu")
		(net "M_J_CPU1_SB_DQS_DP<7>")
	)
	(arc
		(start 140.564616 -286.716216)
		(mid 140.749648 -286.670302)
		(end 140.933424 -286.721042)
		(width 0.09525)
		(layer "In4.Cu")
		(net "M_J_CPU1_SB_DQS_DP<7>")
	)
	(arc
		(start 141.496288 -286.721042)
		(mid 141.684756 -286.670365)
		(end 141.873224 -286.721042)
		(width 0.09525)
		(layer "In4.Cu")
		(net "M_J_CPU1_SB_DQS_DP<7>")
	)
	(arc
		(start 131.599432 -286.754062)
		(mid 131.851715 -286.795775)
		(end 132.096256 -286.721042)
		(width 0.09525)
		(layer "In4.Cu")
		(net "M_J_CPU1_SB_DQS_DP<7>")
	)
	(arc
		(start 134.3533 -286.721042)
		(mid 134.634732 -286.796831)
		(end 134.916164 -286.721042)
		(width 0.09525)
		(layer "In4.Cu")
		(net "M_J_CPU1_SB_DQS_DP<7>")
	)
	(arc
		(start 133.03631 -286.721042)
		(mid 133.224778 -286.670365)
		(end 133.413246 -286.721042)
		(width 0.09525)
		(layer "In4.Cu")
		(net "M_J_CPU1_SB_DQS_DP<7>")
	)
	(arc
		(start 133.413246 -286.721042)
		(mid 133.694678 -286.796831)
		(end 133.97611 -286.721042)
		(width 0.09525)
		(layer "In4.Cu")
		(net "M_J_CPU1_SB_DQS_DP<7>")
	)
	(arc
		(start 132.104638 -286.716216)
		(mid 132.28967 -286.670302)
		(end 132.473446 -286.721042)
		(width 0.09525)
		(layer "In4.Cu")
		(net "M_J_CPU1_SB_DQS_DP<7>")
	)
	(arc
		(start 138.113262 -286.721042)
		(mid 138.394694 -286.796831)
		(end 138.676126 -286.721042)
		(width 0.09525)
		(layer "In4.Cu")
		(net "M_J_CPU1_SB_DQS_DP<7>")
	)
	(arc
		(start 135.8646 -286.716216)
		(mid 136.049632 -286.670302)
		(end 136.233408 -286.721042)
		(width 0.09525)
		(layer "In4.Cu")
		(net "M_J_CPU1_SB_DQS_DP<7>")
	)
	(arc
		(start 142.436088 -286.721042)
		(mid 142.619863 -286.67027)
		(end 142.804896 -286.716216)
		(width 0.09525)
		(layer "In4.Cu")
		(net "M_J_CPU1_SB_DQS_DP<7>")
	)
	(arc
		(start 137.173208 -286.721042)
		(mid 137.45464 -286.796831)
		(end 137.736072 -286.721042)
		(width 0.09525)
		(layer "In4.Cu")
		(net "M_J_CPU1_SB_DQS_DP<7>")
	)
	(arc
		(start 137.736072 -286.721042)
		(mid 137.919847 -286.67027)
		(end 138.10488 -286.716216)
		(width 0.09525)
		(layer "In4.Cu")
		(net "M_J_CPU1_SB_DQS_DP<7>")
	)
	(segment
		(start 130.877818 -281.920442)
		(end 131.34467 -282.18638)
		(width 0.12954)
		(layer "F.Cu")
		(net "M_J_CPU1_SB_DQS_DP<6>")
	)
	(segment
		(start 166.06139 -296.297858)
		(end 166.91483 -295.444418)
		(width 0.16002)
		(layer "In4.Cu")
		(net "M_J_CPU1_SB_DQS_DP<6>")
	)
	(segment
		(start 173.019466 -296.318178)
		(end 173.59249 -296.318178)
		(width 0.16002)
		(layer "In4.Cu")
		(net "M_J_CPU1_SB_DQS_DP<6>")
	)
	(segment
		(start 174.46752 -295.443148)
		(end 174.997364 -295.443148)
		(width 0.16002)
		(layer "In4.Cu")
		(net "M_J_CPU1_SB_DQS_DP<6>")
	)
	(segment
		(start 134.916164 -281.86126)
		(end 134.924546 -281.856434)
		(width 0.09525)
		(layer "In4.Cu")
		(net "M_J_CPU1_SB_DQS_DP<6>")
	)
	(segment
		(start 158.385764 -292.499796)
		(end 158.17215 -292.71341)
		(width 0.16002)
		(layer "In4.Cu")
		(net "M_J_CPU1_SB_DQS_DP<6>")
	)
	(segment
		(start 181.24805 -296.318178)
		(end 182.09641 -295.469818)
		(width 0.16002)
		(layer "In4.Cu")
		(net "M_J_CPU1_SB_DQS_DP<6>")
	)
	(segment
		(start 135.856218 -281.86126)
		(end 135.8646 -281.856434)
		(width 0.09525)
		(layer "In4.Cu")
		(net "M_J_CPU1_SB_DQS_DP<6>")
	)
	(segment
		(start 184.704736 -295.810432)
		(end 184.853834 -295.661334)
		(width 0.16002)
		(layer "In4.Cu")
		(net "M_J_CPU1_SB_DQS_DP<6>")
	)
	(segment
		(start 184.853834 -295.661334)
		(end 186.786012 -295.661334)
		(width 0.16002)
		(layer "In4.Cu")
		(net "M_J_CPU1_SB_DQS_DP<6>")
	)
	(segment
		(start 174.997364 -295.443148)
		(end 175.364648 -295.810432)
		(width 0.16002)
		(layer "In4.Cu")
		(net "M_J_CPU1_SB_DQS_DP<6>")
	)
	(segment
		(start 160.818322 -295.561766)
		(end 160.818322 -296.08907)
		(width 0.16002)
		(layer "In4.Cu")
		(net "M_J_CPU1_SB_DQS_DP<6>")
	)
	(segment
		(start 172.677074 -296.66057)
		(end 173.019466 -296.318178)
		(width 0.16002)
		(layer "In4.Cu")
		(net "M_J_CPU1_SB_DQS_DP<6>")
	)
	(segment
		(start 140.556234 -281.86126)
		(end 140.564616 -281.856434)
		(width 0.09525)
		(layer "In4.Cu")
		(net "M_J_CPU1_SB_DQS_DP<6>")
	)
	(segment
		(start 138.10488 -281.856434)
		(end 138.113262 -281.86126)
		(width 0.09525)
		(layer "In4.Cu")
		(net "M_J_CPU1_SB_DQS_DP<6>")
	)
	(segment
		(start 158.17215 -290.42487)
		(end 158.17215 -292.009322)
		(width 0.16002)
		(layer "In4.Cu")
		(net "M_J_CPU1_SB_DQS_DP<6>")
	)
	(segment
		(start 159.759396 -293.873428)
		(end 159.44469 -294.188134)
		(width 0.16002)
		(layer "In4.Cu")
		(net "M_J_CPU1_SB_DQS_DP<6>")
	)
	(segment
		(start 158.545784 -293.614348)
		(end 159.073088 -293.614348)
		(width 0.16002)
		(layer "In4.Cu")
		(net "M_J_CPU1_SB_DQS_DP<6>")
	)
	(segment
		(start 166.91483 -295.444418)
		(end 169.71899 -295.444418)
		(width 0.16002)
		(layer "In4.Cu")
		(net "M_J_CPU1_SB_DQS_DP<6>")
	)
	(segment
		(start 161.191956 -296.462704)
		(end 161.71926 -296.462704)
		(width 0.16002)
		(layer "In4.Cu")
		(net "M_J_CPU1_SB_DQS_DP<6>")
	)
	(segment
		(start 180.56987 -296.318178)
		(end 181.24805 -296.318178)
		(width 0.16002)
		(layer "In4.Cu")
		(net "M_J_CPU1_SB_DQS_DP<6>")
	)
	(segment
		(start 159.073088 -293.614348)
		(end 159.286702 -293.400734)
		(width 0.16002)
		(layer "In4.Cu")
		(net "M_J_CPU1_SB_DQS_DP<6>")
	)
	(segment
		(start 182.881524 -295.810432)
		(end 184.704736 -295.810432)
		(width 0.16002)
		(layer "In4.Cu")
		(net "M_J_CPU1_SB_DQS_DP<6>")
	)
	(segment
		(start 159.44469 -294.188134)
		(end 159.44469 -294.715438)
		(width 0.16002)
		(layer "In4.Cu")
		(net "M_J_CPU1_SB_DQS_DP<6>")
	)
	(segment
		(start 159.818324 -295.089072)
		(end 160.345628 -295.089072)
		(width 0.16002)
		(layer "In4.Cu")
		(net "M_J_CPU1_SB_DQS_DP<6>")
	)
	(segment
		(start 146.816572 -282.061666)
		(end 147.590764 -282.061666)
		(width 0.09525)
		(layer "In4.Cu")
		(net "M_J_CPU1_SB_DQS_DP<6>")
	)
	(segment
		(start 158.17215 -292.009322)
		(end 158.385764 -292.222936)
		(width 0.16002)
		(layer "In4.Cu")
		(net "M_J_CPU1_SB_DQS_DP<6>")
	)
	(segment
		(start 162.460686 -296.297858)
		(end 166.06139 -296.297858)
		(width 0.16002)
		(layer "In4.Cu")
		(net "M_J_CPU1_SB_DQS_DP<6>")
	)
	(segment
		(start 143.376142 -281.86126)
		(end 143.384524 -281.856434)
		(width 0.09525)
		(layer "In4.Cu")
		(net "M_J_CPU1_SB_DQS_DP<6>")
	)
	(segment
		(start 173.59249 -296.318178)
		(end 174.46752 -295.443148)
		(width 0.16002)
		(layer "In4.Cu")
		(net "M_J_CPU1_SB_DQS_DP<6>")
	)
	(segment
		(start 161.133028 -295.24706)
		(end 160.818322 -295.561766)
		(width 0.16002)
		(layer "In4.Cu")
		(net "M_J_CPU1_SB_DQS_DP<6>")
	)
	(segment
		(start 159.286702 -293.400734)
		(end 159.563562 -293.400734)
		(width 0.16002)
		(layer "In4.Cu")
		(net "M_J_CPU1_SB_DQS_DP<6>")
	)
	(segment
		(start 162.033966 -296.147998)
		(end 162.310826 -296.147998)
		(width 0.16002)
		(layer "In4.Cu")
		(net "M_J_CPU1_SB_DQS_DP<6>")
	)
	(segment
		(start 182.09641 -295.469818)
		(end 182.54091 -295.469818)
		(width 0.16002)
		(layer "In4.Cu")
		(net "M_J_CPU1_SB_DQS_DP<6>")
	)
	(segment
		(start 142.804896 -281.856434)
		(end 142.813278 -281.86126)
		(width 0.09525)
		(layer "In4.Cu")
		(net "M_J_CPU1_SB_DQS_DP<6>")
	)
	(segment
		(start 186.786012 -295.661334)
		(end 187.060078 -295.9354)
		(width 0.16002)
		(layer "In4.Cu")
		(net "M_J_CPU1_SB_DQS_DP<6>")
	)
	(segment
		(start 134.344918 -281.856434)
		(end 134.3533 -281.86126)
		(width 0.09525)
		(layer "In4.Cu")
		(net "M_J_CPU1_SB_DQS_DP<6>")
	)
	(segment
		(start 180.227478 -296.66057)
		(end 180.56987 -296.318178)
		(width 0.16002)
		(layer "In4.Cu")
		(net "M_J_CPU1_SB_DQS_DP<6>")
	)
	(segment
		(start 147.673314 -282.120594)
		(end 149.867874 -282.120594)
		(width 0.16002)
		(layer "In4.Cu")
		(net "M_J_CPU1_SB_DQS_DP<6>")
	)
	(segment
		(start 161.133028 -294.9702)
		(end 161.133028 -295.24706)
		(width 0.16002)
		(layer "In4.Cu")
		(net "M_J_CPU1_SB_DQS_DP<6>")
	)
	(segment
		(start 149.867874 -282.120594)
		(end 158.17215 -290.42487)
		(width 0.16002)
		(layer "In4.Cu")
		(net "M_J_CPU1_SB_DQS_DP<6>")
	)
	(segment
		(start 162.310826 -296.147998)
		(end 162.460686 -296.297858)
		(width 0.16002)
		(layer "In4.Cu")
		(net "M_J_CPU1_SB_DQS_DP<6>")
	)
	(segment
		(start 139.61618 -281.86126)
		(end 139.624562 -281.856434)
		(width 0.09525)
		(layer "In4.Cu")
		(net "M_J_CPU1_SB_DQS_DP<6>")
	)
	(segment
		(start 143.753332 -281.86126)
		(end 143.763746 -281.867356)
		(width 0.09525)
		(layer "In4.Cu")
		(net "M_J_CPU1_SB_DQS_DP<6>")
	)
	(segment
		(start 147.649692 -282.120594)
		(end 147.673314 -282.120594)
		(width 0.09525)
		(layer "In4.Cu")
		(net "M_J_CPU1_SB_DQS_DP<6>")
	)
	(segment
		(start 178.159156 -295.810432)
		(end 179.009294 -296.66057)
		(width 0.16002)
		(layer "In4.Cu")
		(net "M_J_CPU1_SB_DQS_DP<6>")
	)
	(segment
		(start 158.17215 -293.240714)
		(end 158.545784 -293.614348)
		(width 0.16002)
		(layer "In4.Cu")
		(net "M_J_CPU1_SB_DQS_DP<6>")
	)
	(segment
		(start 160.937194 -294.774366)
		(end 161.133028 -294.9702)
		(width 0.16002)
		(layer "In4.Cu")
		(net "M_J_CPU1_SB_DQS_DP<6>")
	)
	(segment
		(start 161.71926 -296.462704)
		(end 162.033966 -296.147998)
		(width 0.16002)
		(layer "In4.Cu")
		(net "M_J_CPU1_SB_DQS_DP<6>")
	)
	(segment
		(start 131.498594 -281.92095)
		(end 131.599432 -281.89428)
		(width 0.09525)
		(layer "In4.Cu")
		(net "M_J_CPU1_SB_DQS_DP<6>")
	)
	(segment
		(start 159.759396 -293.596568)
		(end 159.759396 -293.873428)
		(width 0.16002)
		(layer "In4.Cu")
		(net "M_J_CPU1_SB_DQS_DP<6>")
	)
	(segment
		(start 175.364648 -295.810432)
		(end 178.159156 -295.810432)
		(width 0.16002)
		(layer "In4.Cu")
		(net "M_J_CPU1_SB_DQS_DP<6>")
	)
	(segment
		(start 182.54091 -295.469818)
		(end 182.881524 -295.810432)
		(width 0.16002)
		(layer "In4.Cu")
		(net "M_J_CPU1_SB_DQS_DP<6>")
	)
	(segment
		(start 158.385764 -292.222936)
		(end 158.385764 -292.499796)
		(width 0.16002)
		(layer "In4.Cu")
		(net "M_J_CPU1_SB_DQS_DP<6>")
	)
	(segment
		(start 169.71899 -295.444418)
		(end 170.935142 -296.66057)
		(width 0.16002)
		(layer "In4.Cu")
		(net "M_J_CPU1_SB_DQS_DP<6>")
	)
	(segment
		(start 170.935142 -296.66057)
		(end 172.677074 -296.66057)
		(width 0.16002)
		(layer "In4.Cu")
		(net "M_J_CPU1_SB_DQS_DP<6>")
	)
	(segment
		(start 159.563562 -293.400734)
		(end 159.759396 -293.596568)
		(width 0.16002)
		(layer "In4.Cu")
		(net "M_J_CPU1_SB_DQS_DP<6>")
	)
	(segment
		(start 132.096256 -281.86126)
		(end 132.104638 -281.856434)
		(width 0.09525)
		(layer "In4.Cu")
		(net "M_J_CPU1_SB_DQS_DP<6>")
	)
	(segment
		(start 160.660334 -294.774366)
		(end 160.937194 -294.774366)
		(width 0.16002)
		(layer "In4.Cu")
		(net "M_J_CPU1_SB_DQS_DP<6>")
	)
	(segment
		(start 146.600926 -281.84602)
		(end 146.816572 -282.061666)
		(width 0.09525)
		(layer "In4.Cu")
		(net "M_J_CPU1_SB_DQS_DP<6>")
	)
	(segment
		(start 131.34467 -282.18638)
		(end 131.498594 -281.92095)
		(width 0.09525)
		(layer "In4.Cu")
		(net "M_J_CPU1_SB_DQS_DP<6>")
	)
	(segment
		(start 145.444718 -281.809952)
		(end 146.486372 -281.809952)
		(width 0.09525)
		(layer "In4.Cu")
		(net "M_J_CPU1_SB_DQS_DP<6>")
	)
	(segment
		(start 159.44469 -294.715438)
		(end 159.818324 -295.089072)
		(width 0.16002)
		(layer "In4.Cu")
		(net "M_J_CPU1_SB_DQS_DP<6>")
	)
	(segment
		(start 147.590764 -282.061666)
		(end 147.649692 -282.120594)
		(width 0.09525)
		(layer "In4.Cu")
		(net "M_J_CPU1_SB_DQS_DP<6>")
	)
	(segment
		(start 158.17215 -292.71341)
		(end 158.17215 -293.240714)
		(width 0.16002)
		(layer "In4.Cu")
		(net "M_J_CPU1_SB_DQS_DP<6>")
	)
	(segment
		(start 144.685766 -281.856434)
		(end 144.694148 -281.86126)
		(width 0.09525)
		(layer "In4.Cu")
		(net "M_J_CPU1_SB_DQS_DP<6>")
	)
	(segment
		(start 160.345628 -295.089072)
		(end 160.660334 -294.774366)
		(width 0.16002)
		(layer "In4.Cu")
		(net "M_J_CPU1_SB_DQS_DP<6>")
	)
	(segment
		(start 160.818322 -296.08907)
		(end 161.191956 -296.462704)
		(width 0.16002)
		(layer "In4.Cu")
		(net "M_J_CPU1_SB_DQS_DP<6>")
	)
	(segment
		(start 179.009294 -296.66057)
		(end 180.227478 -296.66057)
		(width 0.16002)
		(layer "In4.Cu")
		(net "M_J_CPU1_SB_DQS_DP<6>")
	)
	(segment
		(start 139.044934 -281.856434)
		(end 139.053316 -281.86126)
		(width 0.09525)
		(layer "In4.Cu")
		(net "M_J_CPU1_SB_DQS_DP<6>")
	)
	(arc
		(start 143.384524 -281.856434)
		(mid 143.569556 -281.81052)
		(end 143.753332 -281.86126)
		(width 0.09525)
		(layer "In4.Cu")
		(net "M_J_CPU1_SB_DQS_DP<6>")
	)
	(arc
		(start 137.736072 -281.86126)
		(mid 137.919847 -281.810488)
		(end 138.10488 -281.856434)
		(width 0.09525)
		(layer "In4.Cu")
		(net "M_J_CPU1_SB_DQS_DP<6>")
	)
	(arc
		(start 139.053316 -281.86126)
		(mid 139.334748 -281.937015)
		(end 139.61618 -281.86126)
		(width 0.09525)
		(layer "In4.Cu")
		(net "M_J_CPU1_SB_DQS_DP<6>")
	)
	(arc
		(start 146.486372 -281.809952)
		(mid 146.546407 -281.819223)
		(end 146.600926 -281.84602)
		(width 0.09525)
		(layer "In4.Cu")
		(net "M_J_CPU1_SB_DQS_DP<6>")
	)
	(arc
		(start 137.173208 -281.86126)
		(mid 137.45464 -281.937015)
		(end 137.736072 -281.86126)
		(width 0.09525)
		(layer "In4.Cu")
		(net "M_J_CPU1_SB_DQS_DP<6>")
	)
	(arc
		(start 145.241772 -281.869896)
		(mid 145.338944 -281.825365)
		(end 145.444718 -281.809952)
		(width 0.09525)
		(layer "In4.Cu")
		(net "M_J_CPU1_SB_DQS_DP<6>")
	)
	(arc
		(start 135.8646 -281.856434)
		(mid 136.049632 -281.81052)
		(end 136.233408 -281.86126)
		(width 0.09525)
		(layer "In4.Cu")
		(net "M_J_CPU1_SB_DQS_DP<6>")
	)
	(arc
		(start 139.99337 -281.86126)
		(mid 140.274802 -281.937015)
		(end 140.556234 -281.86126)
		(width 0.09525)
		(layer "In4.Cu")
		(net "M_J_CPU1_SB_DQS_DP<6>")
	)
	(arc
		(start 138.113262 -281.86126)
		(mid 138.394694 -281.937015)
		(end 138.676126 -281.86126)
		(width 0.09525)
		(layer "In4.Cu")
		(net "M_J_CPU1_SB_DQS_DP<6>")
	)
	(arc
		(start 132.104638 -281.856434)
		(mid 132.28967 -281.81052)
		(end 132.473446 -281.86126)
		(width 0.09525)
		(layer "In4.Cu")
		(net "M_J_CPU1_SB_DQS_DP<6>")
	)
	(arc
		(start 132.473446 -281.86126)
		(mid 132.754878 -281.937015)
		(end 133.03631 -281.86126)
		(width 0.09525)
		(layer "In4.Cu")
		(net "M_J_CPU1_SB_DQS_DP<6>")
	)
	(arc
		(start 143.763746 -281.867356)
		(mid 144.040908 -281.937156)
		(end 144.31645 -281.86126)
		(width 0.09525)
		(layer "In4.Cu")
		(net "M_J_CPU1_SB_DQS_DP<6>")
	)
	(arc
		(start 138.676126 -281.86126)
		(mid 138.859901 -281.810488)
		(end 139.044934 -281.856434)
		(width 0.09525)
		(layer "In4.Cu")
		(net "M_J_CPU1_SB_DQS_DP<6>")
	)
	(arc
		(start 131.620006 -281.902408)
		(mid 131.862748 -281.935178)
		(end 132.096256 -281.86126)
		(width 0.09525)
		(layer "In4.Cu")
		(net "M_J_CPU1_SB_DQS_DP<6>")
	)
	(arc
		(start 134.3533 -281.86126)
		(mid 134.634732 -281.937015)
		(end 134.916164 -281.86126)
		(width 0.09525)
		(layer "In4.Cu")
		(net "M_J_CPU1_SB_DQS_DP<6>")
	)
	(arc
		(start 133.03631 -281.86126)
		(mid 133.224778 -281.810583)
		(end 133.413246 -281.86126)
		(width 0.09525)
		(layer "In4.Cu")
		(net "M_J_CPU1_SB_DQS_DP<6>")
	)
	(arc
		(start 144.694148 -281.86126)
		(mid 144.966822 -281.936947)
		(end 145.241772 -281.869896)
		(width 0.09525)
		(layer "In4.Cu")
		(net "M_J_CPU1_SB_DQS_DP<6>")
	)
	(arc
		(start 139.624562 -281.856434)
		(mid 139.809594 -281.81052)
		(end 139.99337 -281.86126)
		(width 0.09525)
		(layer "In4.Cu")
		(net "M_J_CPU1_SB_DQS_DP<6>")
	)
	(arc
		(start 134.924546 -281.856434)
		(mid 135.109578 -281.81052)
		(end 135.293354 -281.86126)
		(width 0.09525)
		(layer "In4.Cu")
		(net "M_J_CPU1_SB_DQS_DP<6>")
	)
	(arc
		(start 136.796272 -281.86126)
		(mid 136.98474 -281.810583)
		(end 137.173208 -281.86126)
		(width 0.09525)
		(layer "In4.Cu")
		(net "M_J_CPU1_SB_DQS_DP<6>")
	)
	(arc
		(start 133.413246 -281.86126)
		(mid 133.694678 -281.937015)
		(end 133.97611 -281.86126)
		(width 0.09525)
		(layer "In4.Cu")
		(net "M_J_CPU1_SB_DQS_DP<6>")
	)
	(arc
		(start 133.97611 -281.86126)
		(mid 134.159885 -281.810488)
		(end 134.344918 -281.856434)
		(width 0.09525)
		(layer "In4.Cu")
		(net "M_J_CPU1_SB_DQS_DP<6>")
	)
	(arc
		(start 142.813278 -281.86126)
		(mid 143.09471 -281.937015)
		(end 143.376142 -281.86126)
		(width 0.09525)
		(layer "In4.Cu")
		(net "M_J_CPU1_SB_DQS_DP<6>")
	)
	(arc
		(start 140.933424 -281.86126)
		(mid 141.214856 -281.937015)
		(end 141.496288 -281.86126)
		(width 0.09525)
		(layer "In4.Cu")
		(net "M_J_CPU1_SB_DQS_DP<6>")
	)
	(arc
		(start 142.436088 -281.86126)
		(mid 142.619863 -281.810488)
		(end 142.804896 -281.856434)
		(width 0.09525)
		(layer "In4.Cu")
		(net "M_J_CPU1_SB_DQS_DP<6>")
	)
	(arc
		(start 141.496288 -281.86126)
		(mid 141.684756 -281.810583)
		(end 141.873224 -281.86126)
		(width 0.09525)
		(layer "In4.Cu")
		(net "M_J_CPU1_SB_DQS_DP<6>")
	)
	(arc
		(start 141.873224 -281.86126)
		(mid 142.154656 -281.937015)
		(end 142.436088 -281.86126)
		(width 0.09525)
		(layer "In4.Cu")
		(net "M_J_CPU1_SB_DQS_DP<6>")
	)
	(arc
		(start 135.293354 -281.86126)
		(mid 135.574786 -281.937015)
		(end 135.856218 -281.86126)
		(width 0.09525)
		(layer "In4.Cu")
		(net "M_J_CPU1_SB_DQS_DP<6>")
	)
	(arc
		(start 136.233408 -281.86126)
		(mid 136.51484 -281.937015)
		(end 136.796272 -281.86126)
		(width 0.09525)
		(layer "In4.Cu")
		(net "M_J_CPU1_SB_DQS_DP<6>")
	)
	(arc
		(start 144.31645 -281.86126)
		(mid 144.500479 -281.810361)
		(end 144.685766 -281.856434)
		(width 0.09525)
		(layer "In4.Cu")
		(net "M_J_CPU1_SB_DQS_DP<6>")
	)
	(arc
		(start 131.599432 -281.89428)
		(mid 131.60968 -281.898443)
		(end 131.620006 -281.902408)
		(width 0.09525)
		(layer "In4.Cu")
		(net "M_J_CPU1_SB_DQS_DP<6>")
	)
	(arc
		(start 140.564616 -281.856434)
		(mid 140.749648 -281.81052)
		(end 140.933424 -281.86126)
		(width 0.09525)
		(layer "In4.Cu")
		(net "M_J_CPU1_SB_DQS_DP<6>")
	)
	(segment
		(start 130.877818 -277.060406)
		(end 131.34467 -277.326344)
		(width 0.12954)
		(layer "F.Cu")
		(net "M_J_CPU1_SB_DQS_DP<5>")
	)
	(segment
		(start 146.249898 -276.393148)
		(end 146.781012 -275.862034)
		(width 0.09525)
		(layer "In4.Cu")
		(net "M_J_CPU1_SB_DQS_DP<5>")
	)
	(segment
		(start 134.344918 -276.996398)
		(end 134.3533 -277.001224)
		(width 0.09525)
		(layer "In4.Cu")
		(net "M_J_CPU1_SB_DQS_DP<5>")
	)
	(segment
		(start 156.639006 -280.385774)
		(end 157.447742 -280.385774)
		(width 0.16002)
		(layer "In4.Cu")
		(net "M_J_CPU1_SB_DQS_DP<5>")
	)
	(segment
		(start 147.468336 -276.036532)
		(end 147.771612 -276.036532)
		(width 0.09525)
		(layer "In4.Cu")
		(net "M_J_CPU1_SB_DQS_DP<5>")
	)
	(segment
		(start 147.854162 -276.09546)
		(end 152.171908 -276.09546)
		(width 0.16002)
		(layer "In4.Cu")
		(net "M_J_CPU1_SB_DQS_DP<5>")
	)
	(segment
		(start 131.34467 -277.326344)
		(end 131.498594 -277.060914)
		(width 0.09525)
		(layer "In4.Cu")
		(net "M_J_CPU1_SB_DQS_DP<5>")
	)
	(segment
		(start 147.83054 -276.09546)
		(end 147.854162 -276.09546)
		(width 0.09525)
		(layer "In4.Cu")
		(net "M_J_CPU1_SB_DQS_DP<5>")
	)
	(segment
		(start 144.686274 -276.996144)
		(end 144.687036 -276.996652)
		(width 0.09525)
		(layer "In4.Cu")
		(net "M_J_CPU1_SB_DQS_DP<5>")
	)
	(segment
		(start 171.140374 -287.310576)
		(end 172.677074 -287.310576)
		(width 0.16002)
		(layer "In4.Cu")
		(net "M_J_CPU1_SB_DQS_DP<5>")
	)
	(segment
		(start 182.09641 -286.119824)
		(end 182.54091 -286.119824)
		(width 0.16002)
		(layer "In4.Cu")
		(net "M_J_CPU1_SB_DQS_DP<5>")
	)
	(segment
		(start 142.804896 -276.996398)
		(end 142.813278 -277.001224)
		(width 0.09525)
		(layer "In4.Cu")
		(net "M_J_CPU1_SB_DQS_DP<5>")
	)
	(segment
		(start 158.927292 -282.109164)
		(end 158.927292 -282.850844)
		(width 0.16002)
		(layer "In4.Cu")
		(net "M_J_CPU1_SB_DQS_DP<5>")
	)
	(segment
		(start 186.786012 -286.31134)
		(end 187.060078 -286.585406)
		(width 0.16002)
		(layer "In4.Cu")
		(net "M_J_CPU1_SB_DQS_DP<5>")
	)
	(segment
		(start 144.688052 -276.99716)
		(end 144.694148 -277.000716)
		(width 0.09525)
		(layer "In4.Cu")
		(net "M_J_CPU1_SB_DQS_DP<5>")
	)
	(segment
		(start 180.227478 -287.310576)
		(end 180.56987 -286.968184)
		(width 0.16002)
		(layer "In4.Cu")
		(net "M_J_CPU1_SB_DQS_DP<5>")
	)
	(segment
		(start 169.924222 -286.094424)
		(end 171.140374 -287.310576)
		(width 0.16002)
		(layer "In4.Cu")
		(net "M_J_CPU1_SB_DQS_DP<5>")
	)
	(segment
		(start 182.881524 -286.460438)
		(end 184.704736 -286.460438)
		(width 0.16002)
		(layer "In4.Cu")
		(net "M_J_CPU1_SB_DQS_DP<5>")
	)
	(segment
		(start 174.997364 -286.093154)
		(end 175.364648 -286.460438)
		(width 0.16002)
		(layer "In4.Cu")
		(net "M_J_CPU1_SB_DQS_DP<5>")
	)
	(segment
		(start 174.46752 -286.093154)
		(end 174.997364 -286.093154)
		(width 0.16002)
		(layer "In4.Cu")
		(net "M_J_CPU1_SB_DQS_DP<5>")
	)
	(segment
		(start 182.54091 -286.119824)
		(end 182.881524 -286.460438)
		(width 0.16002)
		(layer "In4.Cu")
		(net "M_J_CPU1_SB_DQS_DP<5>")
	)
	(segment
		(start 144.685766 -276.996398)
		(end 144.686274 -276.996144)
		(width 0.09525)
		(layer "In4.Cu")
		(net "M_J_CPU1_SB_DQS_DP<5>")
	)
	(segment
		(start 156.07411 -279.012142)
		(end 156.301948 -279.23998)
		(width 0.16002)
		(layer "In4.Cu")
		(net "M_J_CPU1_SB_DQS_DP<5>")
	)
	(segment
		(start 172.677074 -287.310576)
		(end 173.019466 -286.968184)
		(width 0.16002)
		(layer "In4.Cu")
		(net "M_J_CPU1_SB_DQS_DP<5>")
	)
	(segment
		(start 163.757102 -285.836106)
		(end 164.86886 -286.947864)
		(width 0.16002)
		(layer "In4.Cu")
		(net "M_J_CPU1_SB_DQS_DP<5>")
	)
	(segment
		(start 184.704736 -286.460438)
		(end 184.853834 -286.31134)
		(width 0.16002)
		(layer "In4.Cu")
		(net "M_J_CPU1_SB_DQS_DP<5>")
	)
	(segment
		(start 180.56987 -286.968184)
		(end 181.24805 -286.968184)
		(width 0.16002)
		(layer "In4.Cu")
		(net "M_J_CPU1_SB_DQS_DP<5>")
	)
	(segment
		(start 157.648148 -281.5717)
		(end 157.985206 -281.908758)
		(width 0.16002)
		(layer "In4.Cu")
		(net "M_J_CPU1_SB_DQS_DP<5>")
	)
	(segment
		(start 164.86886 -286.947864)
		(end 166.06139 -286.947864)
		(width 0.16002)
		(layer "In4.Cu")
		(net "M_J_CPU1_SB_DQS_DP<5>")
	)
	(segment
		(start 155.08859 -279.012142)
		(end 156.07411 -279.012142)
		(width 0.16002)
		(layer "In4.Cu")
		(net "M_J_CPU1_SB_DQS_DP<5>")
	)
	(segment
		(start 156.301948 -280.048716)
		(end 156.639006 -280.385774)
		(width 0.16002)
		(layer "In4.Cu")
		(net "M_J_CPU1_SB_DQS_DP<5>")
	)
	(segment
		(start 156.301948 -279.23998)
		(end 156.301948 -280.048716)
		(width 0.16002)
		(layer "In4.Cu")
		(net "M_J_CPU1_SB_DQS_DP<5>")
	)
	(segment
		(start 173.59249 -286.968184)
		(end 174.46752 -286.093154)
		(width 0.16002)
		(layer "In4.Cu")
		(net "M_J_CPU1_SB_DQS_DP<5>")
	)
	(segment
		(start 152.171908 -276.09546)
		(end 155.08859 -279.012142)
		(width 0.16002)
		(layer "In4.Cu")
		(net "M_J_CPU1_SB_DQS_DP<5>")
	)
	(segment
		(start 143.753332 -277.001224)
		(end 143.763746 -277.00732)
		(width 0.09525)
		(layer "In4.Cu")
		(net "M_J_CPU1_SB_DQS_DP<5>")
	)
	(segment
		(start 157.648148 -280.58618)
		(end 157.648148 -281.5717)
		(width 0.16002)
		(layer "In4.Cu")
		(net "M_J_CPU1_SB_DQS_DP<5>")
	)
	(segment
		(start 147.293838 -275.862034)
		(end 147.468336 -276.036532)
		(width 0.09525)
		(layer "In4.Cu")
		(net "M_J_CPU1_SB_DQS_DP<5>")
	)
	(segment
		(start 173.019466 -286.968184)
		(end 173.59249 -286.968184)
		(width 0.16002)
		(layer "In4.Cu")
		(net "M_J_CPU1_SB_DQS_DP<5>")
	)
	(segment
		(start 147.771612 -276.036532)
		(end 147.83054 -276.09546)
		(width 0.09525)
		(layer "In4.Cu")
		(net "M_J_CPU1_SB_DQS_DP<5>")
	)
	(segment
		(start 144.687036 -276.996652)
		(end 144.688052 -276.99716)
		(width 0.09525)
		(layer "In4.Cu")
		(net "M_J_CPU1_SB_DQS_DP<5>")
	)
	(segment
		(start 184.853834 -286.31134)
		(end 186.786012 -286.31134)
		(width 0.16002)
		(layer "In4.Cu")
		(net "M_J_CPU1_SB_DQS_DP<5>")
	)
	(segment
		(start 160.316926 -283.254958)
		(end 162.898074 -285.836106)
		(width 0.16002)
		(layer "In4.Cu")
		(net "M_J_CPU1_SB_DQS_DP<5>")
	)
	(segment
		(start 145.786094 -276.712426)
		(end 145.853912 -276.678644)
		(width 0.09525)
		(layer "In4.Cu")
		(net "M_J_CPU1_SB_DQS_DP<5>")
	)
	(segment
		(start 145.22069 -277.01113)
		(end 145.786094 -276.712426)
		(width 0.09525)
		(layer "In4.Cu")
		(net "M_J_CPU1_SB_DQS_DP<5>")
	)
	(segment
		(start 175.364648 -286.460438)
		(end 178.159156 -286.460438)
		(width 0.16002)
		(layer "In4.Cu")
		(net "M_J_CPU1_SB_DQS_DP<5>")
	)
	(segment
		(start 138.10488 -276.996398)
		(end 138.113262 -277.001224)
		(width 0.09525)
		(layer "In4.Cu")
		(net "M_J_CPU1_SB_DQS_DP<5>")
	)
	(segment
		(start 134.916164 -277.001224)
		(end 134.924546 -276.996398)
		(width 0.09525)
		(layer "In4.Cu")
		(net "M_J_CPU1_SB_DQS_DP<5>")
	)
	(segment
		(start 158.927292 -282.850844)
		(end 159.331406 -283.254958)
		(width 0.16002)
		(layer "In4.Cu")
		(net "M_J_CPU1_SB_DQS_DP<5>")
	)
	(segment
		(start 158.726886 -281.908758)
		(end 158.927292 -282.109164)
		(width 0.16002)
		(layer "In4.Cu")
		(net "M_J_CPU1_SB_DQS_DP<5>")
	)
	(segment
		(start 132.096256 -277.001224)
		(end 132.104638 -276.996398)
		(width 0.09525)
		(layer "In4.Cu")
		(net "M_J_CPU1_SB_DQS_DP<5>")
	)
	(segment
		(start 140.556234 -277.001224)
		(end 140.564616 -276.996398)
		(width 0.09525)
		(layer "In4.Cu")
		(net "M_J_CPU1_SB_DQS_DP<5>")
	)
	(segment
		(start 139.044934 -276.996398)
		(end 139.053316 -277.001224)
		(width 0.09525)
		(layer "In4.Cu")
		(net "M_J_CPU1_SB_DQS_DP<5>")
	)
	(segment
		(start 157.985206 -281.908758)
		(end 158.726886 -281.908758)
		(width 0.16002)
		(layer "In4.Cu")
		(net "M_J_CPU1_SB_DQS_DP<5>")
	)
	(segment
		(start 131.498594 -277.060914)
		(end 131.599432 -277.034244)
		(width 0.09525)
		(layer "In4.Cu")
		(net "M_J_CPU1_SB_DQS_DP<5>")
	)
	(segment
		(start 143.376142 -277.001224)
		(end 143.384524 -276.996398)
		(width 0.09525)
		(layer "In4.Cu")
		(net "M_J_CPU1_SB_DQS_DP<5>")
	)
	(segment
		(start 181.24805 -286.968184)
		(end 182.09641 -286.119824)
		(width 0.16002)
		(layer "In4.Cu")
		(net "M_J_CPU1_SB_DQS_DP<5>")
	)
	(segment
		(start 139.61618 -277.001224)
		(end 139.624562 -276.996398)
		(width 0.09525)
		(layer "In4.Cu")
		(net "M_J_CPU1_SB_DQS_DP<5>")
	)
	(segment
		(start 166.91483 -286.094424)
		(end 169.924222 -286.094424)
		(width 0.16002)
		(layer "In4.Cu")
		(net "M_J_CPU1_SB_DQS_DP<5>")
	)
	(segment
		(start 146.781012 -275.862034)
		(end 147.293838 -275.862034)
		(width 0.09525)
		(layer "In4.Cu")
		(net "M_J_CPU1_SB_DQS_DP<5>")
	)
	(segment
		(start 162.898074 -285.836106)
		(end 163.757102 -285.836106)
		(width 0.16002)
		(layer "In4.Cu")
		(net "M_J_CPU1_SB_DQS_DP<5>")
	)
	(segment
		(start 159.331406 -283.254958)
		(end 160.316926 -283.254958)
		(width 0.16002)
		(layer "In4.Cu")
		(net "M_J_CPU1_SB_DQS_DP<5>")
	)
	(segment
		(start 166.06139 -286.947864)
		(end 166.91483 -286.094424)
		(width 0.16002)
		(layer "In4.Cu")
		(net "M_J_CPU1_SB_DQS_DP<5>")
	)
	(segment
		(start 178.159156 -286.460438)
		(end 179.009294 -287.310576)
		(width 0.16002)
		(layer "In4.Cu")
		(net "M_J_CPU1_SB_DQS_DP<5>")
	)
	(segment
		(start 135.856218 -277.001224)
		(end 135.8646 -276.996398)
		(width 0.09525)
		(layer "In4.Cu")
		(net "M_J_CPU1_SB_DQS_DP<5>")
	)
	(segment
		(start 157.447742 -280.385774)
		(end 157.648148 -280.58618)
		(width 0.16002)
		(layer "In4.Cu")
		(net "M_J_CPU1_SB_DQS_DP<5>")
	)
	(segment
		(start 179.009294 -287.310576)
		(end 180.227478 -287.310576)
		(width 0.16002)
		(layer "In4.Cu")
		(net "M_J_CPU1_SB_DQS_DP<5>")
	)
	(arc
		(start 131.599432 -277.034244)
		(mid 131.60968 -277.038407)
		(end 131.620006 -277.042372)
		(width 0.09525)
		(layer "In4.Cu")
		(net "M_J_CPU1_SB_DQS_DP<5>")
	)
	(arc
		(start 138.113262 -277.001224)
		(mid 138.394694 -277.076979)
		(end 138.676126 -277.001224)
		(width 0.09525)
		(layer "In4.Cu")
		(net "M_J_CPU1_SB_DQS_DP<5>")
	)
	(arc
		(start 142.436088 -277.001224)
		(mid 142.619863 -276.950452)
		(end 142.804896 -276.996398)
		(width 0.09525)
		(layer "In4.Cu")
		(net "M_J_CPU1_SB_DQS_DP<5>")
	)
	(arc
		(start 144.31645 -277.001224)
		(mid 144.500479 -276.950325)
		(end 144.685766 -276.996398)
		(width 0.09525)
		(layer "In4.Cu")
		(net "M_J_CPU1_SB_DQS_DP<5>")
	)
	(arc
		(start 133.413246 -277.001224)
		(mid 133.694678 -277.076979)
		(end 133.97611 -277.001224)
		(width 0.09525)
		(layer "In4.Cu")
		(net "M_J_CPU1_SB_DQS_DP<5>")
	)
	(arc
		(start 137.173208 -277.001224)
		(mid 137.45464 -277.076979)
		(end 137.736072 -277.001224)
		(width 0.09525)
		(layer "In4.Cu")
		(net "M_J_CPU1_SB_DQS_DP<5>")
	)
	(arc
		(start 137.736072 -277.001224)
		(mid 137.919847 -276.950452)
		(end 138.10488 -276.996398)
		(width 0.09525)
		(layer "In4.Cu")
		(net "M_J_CPU1_SB_DQS_DP<5>")
	)
	(arc
		(start 136.233408 -277.001224)
		(mid 136.51484 -277.076979)
		(end 136.796272 -277.001224)
		(width 0.09525)
		(layer "In4.Cu")
		(net "M_J_CPU1_SB_DQS_DP<5>")
	)
	(arc
		(start 140.564616 -276.996398)
		(mid 140.749648 -276.950484)
		(end 140.933424 -277.001224)
		(width 0.09525)
		(layer "In4.Cu")
		(net "M_J_CPU1_SB_DQS_DP<5>")
	)
	(arc
		(start 143.384524 -276.996398)
		(mid 143.569556 -276.950484)
		(end 143.753332 -277.001224)
		(width 0.09525)
		(layer "In4.Cu")
		(net "M_J_CPU1_SB_DQS_DP<5>")
	)
	(arc
		(start 139.624562 -276.996398)
		(mid 139.809594 -276.950484)
		(end 139.99337 -277.001224)
		(width 0.09525)
		(layer "In4.Cu")
		(net "M_J_CPU1_SB_DQS_DP<5>")
	)
	(arc
		(start 136.796272 -277.001224)
		(mid 136.98474 -276.950547)
		(end 137.173208 -277.001224)
		(width 0.09525)
		(layer "In4.Cu")
		(net "M_J_CPU1_SB_DQS_DP<5>")
	)
	(arc
		(start 141.873224 -277.001224)
		(mid 142.154656 -277.076979)
		(end 142.436088 -277.001224)
		(width 0.09525)
		(layer "In4.Cu")
		(net "M_J_CPU1_SB_DQS_DP<5>")
	)
	(arc
		(start 138.676126 -277.001224)
		(mid 138.859901 -276.950452)
		(end 139.044934 -276.996398)
		(width 0.09525)
		(layer "In4.Cu")
		(net "M_J_CPU1_SB_DQS_DP<5>")
	)
	(arc
		(start 145.853912 -276.678644)
		(mid 146.063414 -276.551856)
		(end 146.249898 -276.393148)
		(width 0.09525)
		(layer "In4.Cu")
		(net "M_J_CPU1_SB_DQS_DP<5>")
	)
	(arc
		(start 135.293354 -277.001224)
		(mid 135.574786 -277.076979)
		(end 135.856218 -277.001224)
		(width 0.09525)
		(layer "In4.Cu")
		(net "M_J_CPU1_SB_DQS_DP<5>")
	)
	(arc
		(start 141.496288 -277.001224)
		(mid 141.684756 -276.950547)
		(end 141.873224 -277.001224)
		(width 0.09525)
		(layer "In4.Cu")
		(net "M_J_CPU1_SB_DQS_DP<5>")
	)
	(arc
		(start 142.813278 -277.001224)
		(mid 143.09471 -277.076979)
		(end 143.376142 -277.001224)
		(width 0.09525)
		(layer "In4.Cu")
		(net "M_J_CPU1_SB_DQS_DP<5>")
	)
	(arc
		(start 140.933424 -277.001224)
		(mid 141.214856 -277.076979)
		(end 141.496288 -277.001224)
		(width 0.09525)
		(layer "In4.Cu")
		(net "M_J_CPU1_SB_DQS_DP<5>")
	)
	(arc
		(start 134.3533 -277.001224)
		(mid 134.634732 -277.076979)
		(end 134.916164 -277.001224)
		(width 0.09525)
		(layer "In4.Cu")
		(net "M_J_CPU1_SB_DQS_DP<5>")
	)
	(arc
		(start 139.99337 -277.001224)
		(mid 140.274802 -277.076979)
		(end 140.556234 -277.001224)
		(width 0.09525)
		(layer "In4.Cu")
		(net "M_J_CPU1_SB_DQS_DP<5>")
	)
	(arc
		(start 132.104638 -276.996398)
		(mid 132.28967 -276.950484)
		(end 132.473446 -277.001224)
		(width 0.09525)
		(layer "In4.Cu")
		(net "M_J_CPU1_SB_DQS_DP<5>")
	)
	(arc
		(start 139.053316 -277.001224)
		(mid 139.334748 -277.076979)
		(end 139.61618 -277.001224)
		(width 0.09525)
		(layer "In4.Cu")
		(net "M_J_CPU1_SB_DQS_DP<5>")
	)
	(arc
		(start 131.620006 -277.042372)
		(mid 131.862748 -277.075142)
		(end 132.096256 -277.001224)
		(width 0.09525)
		(layer "In4.Cu")
		(net "M_J_CPU1_SB_DQS_DP<5>")
	)
	(arc
		(start 134.924546 -276.996398)
		(mid 135.109578 -276.950484)
		(end 135.293354 -277.001224)
		(width 0.09525)
		(layer "In4.Cu")
		(net "M_J_CPU1_SB_DQS_DP<5>")
	)
	(arc
		(start 135.8646 -276.996398)
		(mid 136.049632 -276.950484)
		(end 136.233408 -277.001224)
		(width 0.09525)
		(layer "In4.Cu")
		(net "M_J_CPU1_SB_DQS_DP<5>")
	)
	(arc
		(start 144.694148 -277.000716)
		(mid 144.956058 -277.073998)
		(end 145.22069 -277.01113)
		(width 0.09525)
		(layer "In4.Cu")
		(net "M_J_CPU1_SB_DQS_DP<5>")
	)
	(arc
		(start 143.763746 -277.00732)
		(mid 144.040908 -277.07712)
		(end 144.31645 -277.001224)
		(width 0.09525)
		(layer "In4.Cu")
		(net "M_J_CPU1_SB_DQS_DP<5>")
	)
	(arc
		(start 133.03631 -277.001224)
		(mid 133.224778 -276.950547)
		(end 133.413246 -277.001224)
		(width 0.09525)
		(layer "In4.Cu")
		(net "M_J_CPU1_SB_DQS_DP<5>")
	)
	(arc
		(start 133.97611 -277.001224)
		(mid 134.159885 -276.950452)
		(end 134.344918 -276.996398)
		(width 0.09525)
		(layer "In4.Cu")
		(net "M_J_CPU1_SB_DQS_DP<5>")
	)
	(arc
		(start 132.473446 -277.001224)
		(mid 132.754878 -277.076979)
		(end 133.03631 -277.001224)
		(width 0.09525)
		(layer "In4.Cu")
		(net "M_J_CPU1_SB_DQS_DP<5>")
	)
	(segment
		(start 130.877818 -272.20037)
		(end 131.34467 -272.466308)
		(width 0.12954)
		(layer "F.Cu")
		(net "M_J_CPU1_SB_DQS_DP<4>")
	)
	(segment
		(start 163.071048 -276.192996)
		(end 163.270946 -275.993098)
		(width 0.16002)
		(layer "In4.Cu")
		(net "M_J_CPU1_SB_DQS_DP<4>")
	)
	(segment
		(start 170.935142 -277.960582)
		(end 172.677074 -277.960582)
		(width 0.16002)
		(layer "In4.Cu")
		(net "M_J_CPU1_SB_DQS_DP<4>")
	)
	(segment
		(start 162.37077 -275.092922)
		(end 162.170872 -275.29282)
		(width 0.16002)
		(layer "In4.Cu")
		(net "M_J_CPU1_SB_DQS_DP<4>")
	)
	(segment
		(start 160.79724 -273.919188)
		(end 160.79724 -274.446492)
		(width 0.16002)
		(layer "In4.Cu")
		(net "M_J_CPU1_SB_DQS_DP<4>")
	)
	(segment
		(start 162.170872 -275.820124)
		(end 162.543744 -276.192996)
		(width 0.16002)
		(layer "In4.Cu")
		(net "M_J_CPU1_SB_DQS_DP<4>")
	)
	(segment
		(start 173.019466 -277.61819)
		(end 173.59249 -277.61819)
		(width 0.16002)
		(layer "In4.Cu")
		(net "M_J_CPU1_SB_DQS_DP<4>")
	)
	(segment
		(start 181.24805 -277.61819)
		(end 182.09641 -276.76983)
		(width 0.16002)
		(layer "In4.Cu")
		(net "M_J_CPU1_SB_DQS_DP<4>")
	)
	(segment
		(start 184.704736 -277.110444)
		(end 184.853834 -276.961346)
		(width 0.16002)
		(layer "In4.Cu")
		(net "M_J_CPU1_SB_DQS_DP<4>")
	)
	(segment
		(start 131.34467 -272.466308)
		(end 131.498594 -272.200878)
		(width 0.09525)
		(layer "In4.Cu")
		(net "M_J_CPU1_SB_DQS_DP<4>")
	)
	(segment
		(start 174.46752 -276.74316)
		(end 174.997364 -276.74316)
		(width 0.16002)
		(layer "In4.Cu")
		(net "M_J_CPU1_SB_DQS_DP<4>")
	)
	(segment
		(start 162.543744 -276.192996)
		(end 163.071048 -276.192996)
		(width 0.16002)
		(layer "In4.Cu")
		(net "M_J_CPU1_SB_DQS_DP<4>")
	)
	(segment
		(start 169.71899 -276.74443)
		(end 170.935142 -277.960582)
		(width 0.16002)
		(layer "In4.Cu")
		(net "M_J_CPU1_SB_DQS_DP<4>")
	)
	(segment
		(start 180.227478 -277.960582)
		(end 180.56987 -277.61819)
		(width 0.16002)
		(layer "In4.Cu")
		(net "M_J_CPU1_SB_DQS_DP<4>")
	)
	(segment
		(start 165.152578 -277.59787)
		(end 166.06139 -277.59787)
		(width 0.16002)
		(layer "In4.Cu")
		(net "M_J_CPU1_SB_DQS_DP<4>")
	)
	(segment
		(start 162.170872 -275.29282)
		(end 162.170872 -275.820124)
		(width 0.16002)
		(layer "In4.Cu")
		(net "M_J_CPU1_SB_DQS_DP<4>")
	)
	(segment
		(start 162.174174 -274.619466)
		(end 162.37077 -274.816062)
		(width 0.16002)
		(layer "In4.Cu")
		(net "M_J_CPU1_SB_DQS_DP<4>")
	)
	(segment
		(start 162.37077 -274.816062)
		(end 162.37077 -275.092922)
		(width 0.16002)
		(layer "In4.Cu")
		(net "M_J_CPU1_SB_DQS_DP<4>")
	)
	(segment
		(start 160.800542 -273.245834)
		(end 160.997138 -273.44243)
		(width 0.16002)
		(layer "In4.Cu")
		(net "M_J_CPU1_SB_DQS_DP<4>")
	)
	(segment
		(start 166.91483 -276.74443)
		(end 169.71899 -276.74443)
		(width 0.16002)
		(layer "In4.Cu")
		(net "M_J_CPU1_SB_DQS_DP<4>")
	)
	(segment
		(start 175.364648 -277.110444)
		(end 178.159156 -277.110444)
		(width 0.16002)
		(layer "In4.Cu")
		(net "M_J_CPU1_SB_DQS_DP<4>")
	)
	(segment
		(start 161.897314 -274.619466)
		(end 162.174174 -274.619466)
		(width 0.16002)
		(layer "In4.Cu")
		(net "M_J_CPU1_SB_DQS_DP<4>")
	)
	(segment
		(start 135.856218 -272.141188)
		(end 135.8646 -272.136362)
		(width 0.09525)
		(layer "In4.Cu")
		(net "M_J_CPU1_SB_DQS_DP<4>")
	)
	(segment
		(start 139.61618 -272.141188)
		(end 139.624562 -272.136362)
		(width 0.09525)
		(layer "In4.Cu")
		(net "M_J_CPU1_SB_DQS_DP<4>")
	)
	(segment
		(start 186.786012 -276.961346)
		(end 187.060078 -277.235412)
		(width 0.16002)
		(layer "In4.Cu")
		(net "M_J_CPU1_SB_DQS_DP<4>")
	)
	(segment
		(start 131.498594 -272.200878)
		(end 131.599432 -272.174208)
		(width 0.09525)
		(layer "In4.Cu")
		(net "M_J_CPU1_SB_DQS_DP<4>")
	)
	(segment
		(start 161.697416 -274.819364)
		(end 161.897314 -274.619466)
		(width 0.16002)
		(layer "In4.Cu")
		(net "M_J_CPU1_SB_DQS_DP<4>")
	)
	(segment
		(start 156.797502 -270.446754)
		(end 159.79648 -273.445732)
		(width 0.16002)
		(layer "In4.Cu")
		(net "M_J_CPU1_SB_DQS_DP<4>")
	)
	(segment
		(start 180.56987 -277.61819)
		(end 181.24805 -277.61819)
		(width 0.16002)
		(layer "In4.Cu")
		(net "M_J_CPU1_SB_DQS_DP<4>")
	)
	(segment
		(start 140.556234 -272.141188)
		(end 140.564616 -272.136362)
		(width 0.09525)
		(layer "In4.Cu")
		(net "M_J_CPU1_SB_DQS_DP<4>")
	)
	(segment
		(start 163.270946 -275.993098)
		(end 163.547806 -275.993098)
		(width 0.16002)
		(layer "In4.Cu")
		(net "M_J_CPU1_SB_DQS_DP<4>")
	)
	(segment
		(start 172.677074 -277.960582)
		(end 173.019466 -277.61819)
		(width 0.16002)
		(layer "In4.Cu")
		(net "M_J_CPU1_SB_DQS_DP<4>")
	)
	(segment
		(start 160.997138 -273.44243)
		(end 160.997138 -273.71929)
		(width 0.16002)
		(layer "In4.Cu")
		(net "M_J_CPU1_SB_DQS_DP<4>")
	)
	(segment
		(start 134.916164 -272.141188)
		(end 134.924546 -272.136362)
		(width 0.09525)
		(layer "In4.Cu")
		(net "M_J_CPU1_SB_DQS_DP<4>")
	)
	(segment
		(start 166.06139 -277.59787)
		(end 166.91483 -276.74443)
		(width 0.16002)
		(layer "In4.Cu")
		(net "M_J_CPU1_SB_DQS_DP<4>")
	)
	(segment
		(start 159.79648 -273.445732)
		(end 160.323784 -273.445732)
		(width 0.16002)
		(layer "In4.Cu")
		(net "M_J_CPU1_SB_DQS_DP<4>")
	)
	(segment
		(start 146.485102 -270.59763)
		(end 147.01901 -270.59763)
		(width 0.09525)
		(layer "In4.Cu")
		(net "M_J_CPU1_SB_DQS_DP<4>")
	)
	(segment
		(start 143.753332 -272.141188)
		(end 143.763746 -272.147284)
		(width 0.09525)
		(layer "In4.Cu")
		(net "M_J_CPU1_SB_DQS_DP<4>")
	)
	(segment
		(start 173.59249 -277.61819)
		(end 174.46752 -276.74316)
		(width 0.16002)
		(layer "In4.Cu")
		(net "M_J_CPU1_SB_DQS_DP<4>")
	)
	(segment
		(start 182.09641 -276.76983)
		(end 182.54091 -276.76983)
		(width 0.16002)
		(layer "In4.Cu")
		(net "M_J_CPU1_SB_DQS_DP<4>")
	)
	(segment
		(start 179.009294 -277.960582)
		(end 180.227478 -277.960582)
		(width 0.16002)
		(layer "In4.Cu")
		(net "M_J_CPU1_SB_DQS_DP<4>")
	)
	(segment
		(start 147.01901 -270.59763)
		(end 147.228814 -270.387826)
		(width 0.09525)
		(layer "In4.Cu")
		(net "M_J_CPU1_SB_DQS_DP<4>")
	)
	(segment
		(start 178.159156 -277.110444)
		(end 179.009294 -277.960582)
		(width 0.16002)
		(layer "In4.Cu")
		(net "M_J_CPU1_SB_DQS_DP<4>")
	)
	(segment
		(start 134.344918 -272.136362)
		(end 134.3533 -272.141188)
		(width 0.09525)
		(layer "In4.Cu")
		(net "M_J_CPU1_SB_DQS_DP<4>")
	)
	(segment
		(start 160.323784 -273.445732)
		(end 160.523682 -273.245834)
		(width 0.16002)
		(layer "In4.Cu")
		(net "M_J_CPU1_SB_DQS_DP<4>")
	)
	(segment
		(start 143.376142 -272.141188)
		(end 143.384524 -272.136362)
		(width 0.09525)
		(layer "In4.Cu")
		(net "M_J_CPU1_SB_DQS_DP<4>")
	)
	(segment
		(start 147.786852 -270.446754)
		(end 147.810474 -270.446754)
		(width 0.09525)
		(layer "In4.Cu")
		(net "M_J_CPU1_SB_DQS_DP<4>")
	)
	(segment
		(start 161.170112 -274.819364)
		(end 161.697416 -274.819364)
		(width 0.16002)
		(layer "In4.Cu")
		(net "M_J_CPU1_SB_DQS_DP<4>")
	)
	(segment
		(start 160.79724 -274.446492)
		(end 161.170112 -274.819364)
		(width 0.16002)
		(layer "In4.Cu")
		(net "M_J_CPU1_SB_DQS_DP<4>")
	)
	(segment
		(start 184.853834 -276.961346)
		(end 186.786012 -276.961346)
		(width 0.16002)
		(layer "In4.Cu")
		(net "M_J_CPU1_SB_DQS_DP<4>")
	)
	(segment
		(start 182.881524 -277.110444)
		(end 184.704736 -277.110444)
		(width 0.16002)
		(layer "In4.Cu")
		(net "M_J_CPU1_SB_DQS_DP<4>")
	)
	(segment
		(start 144.505426 -272.089626)
		(end 144.993106 -272.089626)
		(width 0.09525)
		(layer "In4.Cu")
		(net "M_J_CPU1_SB_DQS_DP<4>")
	)
	(segment
		(start 160.997138 -273.71929)
		(end 160.79724 -273.919188)
		(width 0.16002)
		(layer "In4.Cu")
		(net "M_J_CPU1_SB_DQS_DP<4>")
	)
	(segment
		(start 147.810474 -270.446754)
		(end 156.797502 -270.446754)
		(width 0.16002)
		(layer "In4.Cu")
		(net "M_J_CPU1_SB_DQS_DP<4>")
	)
	(segment
		(start 174.997364 -276.74316)
		(end 175.364648 -277.110444)
		(width 0.16002)
		(layer "In4.Cu")
		(net "M_J_CPU1_SB_DQS_DP<4>")
	)
	(segment
		(start 147.727924 -270.387826)
		(end 147.786852 -270.446754)
		(width 0.09525)
		(layer "In4.Cu")
		(net "M_J_CPU1_SB_DQS_DP<4>")
	)
	(segment
		(start 160.523682 -273.245834)
		(end 160.800542 -273.245834)
		(width 0.16002)
		(layer "In4.Cu")
		(net "M_J_CPU1_SB_DQS_DP<4>")
	)
	(segment
		(start 139.044934 -272.136362)
		(end 139.053316 -272.141188)
		(width 0.09525)
		(layer "In4.Cu")
		(net "M_J_CPU1_SB_DQS_DP<4>")
	)
	(segment
		(start 163.547806 -275.993098)
		(end 165.152578 -277.59787)
		(width 0.16002)
		(layer "In4.Cu")
		(net "M_J_CPU1_SB_DQS_DP<4>")
	)
	(segment
		(start 144.993106 -272.089626)
		(end 146.485102 -270.59763)
		(width 0.09525)
		(layer "In4.Cu")
		(net "M_J_CPU1_SB_DQS_DP<4>")
	)
	(segment
		(start 147.228814 -270.387826)
		(end 147.727924 -270.387826)
		(width 0.09525)
		(layer "In4.Cu")
		(net "M_J_CPU1_SB_DQS_DP<4>")
	)
	(segment
		(start 138.10488 -272.136362)
		(end 138.113262 -272.141188)
		(width 0.09525)
		(layer "In4.Cu")
		(net "M_J_CPU1_SB_DQS_DP<4>")
	)
	(segment
		(start 182.54091 -276.76983)
		(end 182.881524 -277.110444)
		(width 0.16002)
		(layer "In4.Cu")
		(net "M_J_CPU1_SB_DQS_DP<4>")
	)
	(segment
		(start 142.804896 -272.136362)
		(end 142.813278 -272.141188)
		(width 0.09525)
		(layer "In4.Cu")
		(net "M_J_CPU1_SB_DQS_DP<4>")
	)
	(segment
		(start 132.096256 -272.141188)
		(end 132.104638 -272.136362)
		(width 0.09525)
		(layer "In4.Cu")
		(net "M_J_CPU1_SB_DQS_DP<4>")
	)
	(arc
		(start 140.933424 -272.141188)
		(mid 141.214856 -272.216943)
		(end 141.496288 -272.141188)
		(width 0.09525)
		(layer "In4.Cu")
		(net "M_J_CPU1_SB_DQS_DP<4>")
	)
	(arc
		(start 140.564616 -272.136362)
		(mid 140.749648 -272.090448)
		(end 140.933424 -272.141188)
		(width 0.09525)
		(layer "In4.Cu")
		(net "M_J_CPU1_SB_DQS_DP<4>")
	)
	(arc
		(start 132.473446 -272.141188)
		(mid 132.754878 -272.216943)
		(end 133.03631 -272.141188)
		(width 0.09525)
		(layer "In4.Cu")
		(net "M_J_CPU1_SB_DQS_DP<4>")
	)
	(arc
		(start 137.173208 -272.141188)
		(mid 137.45464 -272.216943)
		(end 137.736072 -272.141188)
		(width 0.09525)
		(layer "In4.Cu")
		(net "M_J_CPU1_SB_DQS_DP<4>")
	)
	(arc
		(start 139.624562 -272.136362)
		(mid 139.809594 -272.090448)
		(end 139.99337 -272.141188)
		(width 0.09525)
		(layer "In4.Cu")
		(net "M_J_CPU1_SB_DQS_DP<4>")
	)
	(arc
		(start 141.496288 -272.141188)
		(mid 141.684756 -272.090511)
		(end 141.873224 -272.141188)
		(width 0.09525)
		(layer "In4.Cu")
		(net "M_J_CPU1_SB_DQS_DP<4>")
	)
	(arc
		(start 133.03631 -272.141188)
		(mid 133.224778 -272.090511)
		(end 133.413246 -272.141188)
		(width 0.09525)
		(layer "In4.Cu")
		(net "M_J_CPU1_SB_DQS_DP<4>")
	)
	(arc
		(start 133.97611 -272.141188)
		(mid 134.159885 -272.090416)
		(end 134.344918 -272.136362)
		(width 0.09525)
		(layer "In4.Cu")
		(net "M_J_CPU1_SB_DQS_DP<4>")
	)
	(arc
		(start 138.113262 -272.141188)
		(mid 138.394694 -272.216943)
		(end 138.676126 -272.141188)
		(width 0.09525)
		(layer "In4.Cu")
		(net "M_J_CPU1_SB_DQS_DP<4>")
	)
	(arc
		(start 134.3533 -272.141188)
		(mid 134.634732 -272.216943)
		(end 134.916164 -272.141188)
		(width 0.09525)
		(layer "In4.Cu")
		(net "M_J_CPU1_SB_DQS_DP<4>")
	)
	(arc
		(start 135.8646 -272.136362)
		(mid 136.049632 -272.090448)
		(end 136.233408 -272.141188)
		(width 0.09525)
		(layer "In4.Cu")
		(net "M_J_CPU1_SB_DQS_DP<4>")
	)
	(arc
		(start 144.31645 -272.141188)
		(mid 144.407527 -272.102904)
		(end 144.505426 -272.089626)
		(width 0.09525)
		(layer "In4.Cu")
		(net "M_J_CPU1_SB_DQS_DP<4>")
	)
	(arc
		(start 134.924546 -272.136362)
		(mid 135.109578 -272.090448)
		(end 135.293354 -272.141188)
		(width 0.09525)
		(layer "In4.Cu")
		(net "M_J_CPU1_SB_DQS_DP<4>")
	)
	(arc
		(start 141.873224 -272.141188)
		(mid 142.154656 -272.216943)
		(end 142.436088 -272.141188)
		(width 0.09525)
		(layer "In4.Cu")
		(net "M_J_CPU1_SB_DQS_DP<4>")
	)
	(arc
		(start 142.436088 -272.141188)
		(mid 142.619863 -272.090416)
		(end 142.804896 -272.136362)
		(width 0.09525)
		(layer "In4.Cu")
		(net "M_J_CPU1_SB_DQS_DP<4>")
	)
	(arc
		(start 138.676126 -272.141188)
		(mid 138.859901 -272.090416)
		(end 139.044934 -272.136362)
		(width 0.09525)
		(layer "In4.Cu")
		(net "M_J_CPU1_SB_DQS_DP<4>")
	)
	(arc
		(start 139.053316 -272.141188)
		(mid 139.334748 -272.216943)
		(end 139.61618 -272.141188)
		(width 0.09525)
		(layer "In4.Cu")
		(net "M_J_CPU1_SB_DQS_DP<4>")
	)
	(arc
		(start 142.813278 -272.141188)
		(mid 143.09471 -272.216943)
		(end 143.376142 -272.141188)
		(width 0.09525)
		(layer "In4.Cu")
		(net "M_J_CPU1_SB_DQS_DP<4>")
	)
	(arc
		(start 135.293354 -272.141188)
		(mid 135.574786 -272.216943)
		(end 135.856218 -272.141188)
		(width 0.09525)
		(layer "In4.Cu")
		(net "M_J_CPU1_SB_DQS_DP<4>")
	)
	(arc
		(start 139.99337 -272.141188)
		(mid 140.274802 -272.216943)
		(end 140.556234 -272.141188)
		(width 0.09525)
		(layer "In4.Cu")
		(net "M_J_CPU1_SB_DQS_DP<4>")
	)
	(arc
		(start 143.384524 -272.136362)
		(mid 143.569556 -272.090448)
		(end 143.753332 -272.141188)
		(width 0.09525)
		(layer "In4.Cu")
		(net "M_J_CPU1_SB_DQS_DP<4>")
	)
	(arc
		(start 133.413246 -272.141188)
		(mid 133.694678 -272.216943)
		(end 133.97611 -272.141188)
		(width 0.09525)
		(layer "In4.Cu")
		(net "M_J_CPU1_SB_DQS_DP<4>")
	)
	(arc
		(start 132.104638 -272.136362)
		(mid 132.28967 -272.090448)
		(end 132.473446 -272.141188)
		(width 0.09525)
		(layer "In4.Cu")
		(net "M_J_CPU1_SB_DQS_DP<4>")
	)
	(arc
		(start 136.233408 -272.141188)
		(mid 136.51484 -272.216943)
		(end 136.796272 -272.141188)
		(width 0.09525)
		(layer "In4.Cu")
		(net "M_J_CPU1_SB_DQS_DP<4>")
	)
	(arc
		(start 136.796272 -272.141188)
		(mid 136.98474 -272.090511)
		(end 137.173208 -272.141188)
		(width 0.09525)
		(layer "In4.Cu")
		(net "M_J_CPU1_SB_DQS_DP<4>")
	)
	(arc
		(start 143.763746 -272.147284)
		(mid 144.040908 -272.217084)
		(end 144.31645 -272.141188)
		(width 0.09525)
		(layer "In4.Cu")
		(net "M_J_CPU1_SB_DQS_DP<4>")
	)
	(arc
		(start 137.736072 -272.141188)
		(mid 137.919847 -272.090416)
		(end 138.10488 -272.136362)
		(width 0.09525)
		(layer "In4.Cu")
		(net "M_J_CPU1_SB_DQS_DP<4>")
	)
	(arc
		(start 131.599432 -272.174208)
		(mid 131.851716 -272.215902)
		(end 132.096256 -272.141188)
		(width 0.09525)
		(layer "In4.Cu")
		(net "M_J_CPU1_SB_DQS_DP<4>")
	)
	(segment
		(start 132.757926 -290.020248)
		(end 133.224778 -290.286186)
		(width 0.12954)
		(layer "F.Cu")
		(net "M_J_CPU1_SB_DQS_DP<3>")
	)
	(segment
		(start 175.630332 -312.210196)
		(end 177.267108 -312.210196)
		(width 0.16002)
		(layer "In4.Cu")
		(net "M_J_CPU1_SB_DQS_DP<3>")
	)
	(segment
		(start 160.263586 -313.06897)
		(end 165.16985 -313.06897)
		(width 0.16002)
		(layer "In4.Cu")
		(net "M_J_CPU1_SB_DQS_DP<3>")
	)
	(segment
		(start 178.116738 -313.059826)
		(end 180.18887 -313.059826)
		(width 0.16002)
		(layer "In4.Cu")
		(net "M_J_CPU1_SB_DQS_DP<3>")
	)
	(segment
		(start 139.61618 -290.611306)
		(end 139.624562 -290.616132)
		(width 0.09525)
		(layer "In4.Cu")
		(net "M_J_CPU1_SB_DQS_DP<3>")
	)
	(segment
		(start 140.556234 -290.611306)
		(end 140.564616 -290.616132)
		(width 0.09525)
		(layer "In4.Cu")
		(net "M_J_CPU1_SB_DQS_DP<3>")
	)
	(segment
		(start 187.535566 -312.991246)
		(end 187.939426 -313.395106)
		(width 0.16002)
		(layer "In4.Cu")
		(net "M_J_CPU1_SB_DQS_DP<3>")
	)
	(segment
		(start 142.804896 -290.616132)
		(end 142.813278 -290.611306)
		(width 0.09525)
		(layer "In4.Cu")
		(net "M_J_CPU1_SB_DQS_DP<3>")
	)
	(segment
		(start 180.50129 -313.372246)
		(end 181.22773 -313.372246)
		(width 0.16002)
		(layer "In4.Cu")
		(net "M_J_CPU1_SB_DQS_DP<3>")
	)
	(segment
		(start 186.03722 -312.991246)
		(end 186.15406 -312.874406)
		(width 0.16002)
		(layer "In4.Cu")
		(net "M_J_CPU1_SB_DQS_DP<3>")
	)
	(segment
		(start 135.856218 -290.611306)
		(end 135.8646 -290.616132)
		(width 0.09525)
		(layer "In4.Cu")
		(net "M_J_CPU1_SB_DQS_DP<3>")
	)
	(segment
		(start 134.916164 -290.611306)
		(end 134.924546 -290.616132)
		(width 0.09525)
		(layer "In4.Cu")
		(net "M_J_CPU1_SB_DQS_DP<3>")
	)
	(segment
		(start 174.0281 -312.888376)
		(end 174.952152 -312.888376)
		(width 0.16002)
		(layer "In4.Cu")
		(net "M_J_CPU1_SB_DQS_DP<3>")
	)
	(segment
		(start 189.692534 -313.209178)
		(end 189.809374 -313.092338)
		(width 0.16002)
		(layer "In4.Cu")
		(net "M_J_CPU1_SB_DQS_DP<3>")
	)
	(segment
		(start 144.690846 -290.611306)
		(end 144.714214 -290.597844)
		(width 0.09525)
		(layer "In4.Cu")
		(net "M_J_CPU1_SB_DQS_DP<3>")
	)
	(segment
		(start 186.63412 -312.874406)
		(end 186.75096 -312.991246)
		(width 0.16002)
		(layer "In4.Cu")
		(net "M_J_CPU1_SB_DQS_DP<3>")
	)
	(segment
		(start 188.582808 -313.395106)
		(end 188.768736 -313.209178)
		(width 0.16002)
		(layer "In4.Cu")
		(net "M_J_CPU1_SB_DQS_DP<3>")
	)
	(segment
		(start 144.314672 -290.611306)
		(end 144.32915 -290.619688)
		(width 0.09525)
		(layer "In4.Cu")
		(net "M_J_CPU1_SB_DQS_DP<3>")
	)
	(segment
		(start 190.886334 -313.209178)
		(end 191.160146 -312.935366)
		(width 0.16002)
		(layer "In4.Cu")
		(net "M_J_CPU1_SB_DQS_DP<3>")
	)
	(segment
		(start 145.654268 -290.98367)
		(end 146.501866 -293.006526)
		(width 0.09525)
		(layer "In4.Cu")
		(net "M_J_CPU1_SB_DQS_DP<3>")
	)
	(segment
		(start 138.10488 -290.616132)
		(end 138.113262 -290.611306)
		(width 0.09525)
		(layer "In4.Cu")
		(net "M_J_CPU1_SB_DQS_DP<3>")
	)
	(segment
		(start 165.987222 -313.405266)
		(end 166.772082 -312.620406)
		(width 0.16002)
		(layer "In4.Cu")
		(net "M_J_CPU1_SB_DQS_DP<3>")
	)
	(segment
		(start 174.952152 -312.888376)
		(end 175.630332 -312.210196)
		(width 0.16002)
		(layer "In4.Cu")
		(net "M_J_CPU1_SB_DQS_DP<3>")
	)
	(segment
		(start 173.52137 -313.395106)
		(end 174.0281 -312.888376)
		(width 0.16002)
		(layer "In4.Cu")
		(net "M_J_CPU1_SB_DQS_DP<3>")
	)
	(segment
		(start 190.289434 -313.092338)
		(end 190.406274 -313.209178)
		(width 0.16002)
		(layer "In4.Cu")
		(net "M_J_CPU1_SB_DQS_DP<3>")
	)
	(segment
		(start 133.224778 -290.286186)
		(end 133.070854 -290.551616)
		(width 0.09525)
		(layer "In4.Cu")
		(net "M_J_CPU1_SB_DQS_DP<3>")
	)
	(segment
		(start 186.15406 -312.874406)
		(end 186.63412 -312.874406)
		(width 0.16002)
		(layer "In4.Cu")
		(net "M_J_CPU1_SB_DQS_DP<3>")
	)
	(segment
		(start 182.326788 -312.82894)
		(end 182.945532 -312.210196)
		(width 0.16002)
		(layer "In4.Cu")
		(net "M_J_CPU1_SB_DQS_DP<3>")
	)
	(segment
		(start 134.344918 -290.616132)
		(end 134.3533 -290.611306)
		(width 0.09525)
		(layer "In4.Cu")
		(net "M_J_CPU1_SB_DQS_DP<3>")
	)
	(segment
		(start 181.771036 -312.82894)
		(end 182.326788 -312.82894)
		(width 0.16002)
		(layer "In4.Cu")
		(net "M_J_CPU1_SB_DQS_DP<3>")
	)
	(segment
		(start 177.267108 -312.210196)
		(end 178.116738 -313.059826)
		(width 0.16002)
		(layer "In4.Cu")
		(net "M_J_CPU1_SB_DQS_DP<3>")
	)
	(segment
		(start 147.263612 -293.684452)
		(end 148.26869 -294.68953)
		(width 0.16002)
		(layer "In4.Cu")
		(net "M_J_CPU1_SB_DQS_DP<3>")
	)
	(segment
		(start 181.22773 -313.372246)
		(end 181.771036 -312.82894)
		(width 0.16002)
		(layer "In4.Cu")
		(net "M_J_CPU1_SB_DQS_DP<3>")
	)
	(segment
		(start 187.939426 -313.395106)
		(end 188.582808 -313.395106)
		(width 0.16002)
		(layer "In4.Cu")
		(net "M_J_CPU1_SB_DQS_DP<3>")
	)
	(segment
		(start 184.716928 -312.210196)
		(end 185.497978 -312.991246)
		(width 0.16002)
		(layer "In4.Cu")
		(net "M_J_CPU1_SB_DQS_DP<3>")
	)
	(segment
		(start 180.18887 -313.059826)
		(end 180.50129 -313.372246)
		(width 0.16002)
		(layer "In4.Cu")
		(net "M_J_CPU1_SB_DQS_DP<3>")
	)
	(segment
		(start 190.406274 -313.209178)
		(end 190.886334 -313.209178)
		(width 0.16002)
		(layer "In4.Cu")
		(net "M_J_CPU1_SB_DQS_DP<3>")
	)
	(segment
		(start 185.497978 -312.991246)
		(end 186.03722 -312.991246)
		(width 0.16002)
		(layer "In4.Cu")
		(net "M_J_CPU1_SB_DQS_DP<3>")
	)
	(segment
		(start 143.376142 -290.611306)
		(end 143.384524 -290.616132)
		(width 0.09525)
		(layer "In4.Cu")
		(net "M_J_CPU1_SB_DQS_DP<3>")
	)
	(segment
		(start 166.772082 -312.620406)
		(end 170.070526 -312.620406)
		(width 0.16002)
		(layer "In4.Cu")
		(net "M_J_CPU1_SB_DQS_DP<3>")
	)
	(segment
		(start 139.044934 -290.616132)
		(end 139.053316 -290.611306)
		(width 0.09525)
		(layer "In4.Cu")
		(net "M_J_CPU1_SB_DQS_DP<3>")
	)
	(segment
		(start 145.370804 -290.700206)
		(end 145.654268 -290.98367)
		(width 0.09525)
		(layer "In4.Cu")
		(net "M_J_CPU1_SB_DQS_DP<3>")
	)
	(segment
		(start 189.809374 -313.092338)
		(end 190.289434 -313.092338)
		(width 0.16002)
		(layer "In4.Cu")
		(net "M_J_CPU1_SB_DQS_DP<3>")
	)
	(segment
		(start 172.417232 -313.06008)
		(end 172.752258 -313.395106)
		(width 0.16002)
		(layer "In4.Cu")
		(net "M_J_CPU1_SB_DQS_DP<3>")
	)
	(segment
		(start 148.26869 -294.68953)
		(end 148.26869 -301.074074)
		(width 0.16002)
		(layer "In4.Cu")
		(net "M_J_CPU1_SB_DQS_DP<3>")
	)
	(segment
		(start 165.506146 -313.405266)
		(end 165.987222 -313.405266)
		(width 0.16002)
		(layer "In4.Cu")
		(net "M_J_CPU1_SB_DQS_DP<3>")
	)
	(segment
		(start 172.752258 -313.395106)
		(end 173.52137 -313.395106)
		(width 0.16002)
		(layer "In4.Cu")
		(net "M_J_CPU1_SB_DQS_DP<3>")
	)
	(segment
		(start 188.768736 -313.209178)
		(end 189.692534 -313.209178)
		(width 0.16002)
		(layer "In4.Cu")
		(net "M_J_CPU1_SB_DQS_DP<3>")
	)
	(segment
		(start 182.945532 -312.210196)
		(end 184.716928 -312.210196)
		(width 0.16002)
		(layer "In4.Cu")
		(net "M_J_CPU1_SB_DQS_DP<3>")
	)
	(segment
		(start 170.5102 -313.06008)
		(end 172.417232 -313.06008)
		(width 0.16002)
		(layer "In4.Cu")
		(net "M_J_CPU1_SB_DQS_DP<3>")
	)
	(segment
		(start 147.163028 -293.667688)
		(end 147.246848 -293.667688)
		(width 0.09525)
		(layer "In4.Cu")
		(net "M_J_CPU1_SB_DQS_DP<3>")
	)
	(segment
		(start 146.501866 -293.006526)
		(end 147.163028 -293.667688)
		(width 0.09525)
		(layer "In4.Cu")
		(net "M_J_CPU1_SB_DQS_DP<3>")
	)
	(segment
		(start 165.16985 -313.06897)
		(end 165.506146 -313.405266)
		(width 0.16002)
		(layer "In4.Cu")
		(net "M_J_CPU1_SB_DQS_DP<3>")
	)
	(segment
		(start 186.75096 -312.991246)
		(end 187.535566 -312.991246)
		(width 0.16002)
		(layer "In4.Cu")
		(net "M_J_CPU1_SB_DQS_DP<3>")
	)
	(segment
		(start 170.070526 -312.620406)
		(end 170.5102 -313.06008)
		(width 0.16002)
		(layer "In4.Cu")
		(net "M_J_CPU1_SB_DQS_DP<3>")
	)
	(segment
		(start 148.26869 -301.074074)
		(end 160.263586 -313.06897)
		(width 0.16002)
		(layer "In4.Cu")
		(net "M_J_CPU1_SB_DQS_DP<3>")
	)
	(segment
		(start 133.070854 -290.551616)
		(end 133.093968 -290.63823)
		(width 0.09525)
		(layer "In4.Cu")
		(net "M_J_CPU1_SB_DQS_DP<3>")
	)
	(segment
		(start 144.289272 -290.596574)
		(end 144.314672 -290.611306)
		(width 0.09525)
		(layer "In4.Cu")
		(net "M_J_CPU1_SB_DQS_DP<3>")
	)
	(segment
		(start 147.246848 -293.667688)
		(end 147.263612 -293.684452)
		(width 0.09525)
		(layer "In4.Cu")
		(net "M_J_CPU1_SB_DQS_DP<3>")
	)
	(arc
		(start 145.25498 -290.611306)
		(mid 145.3158 -290.651967)
		(end 145.370804 -290.700206)
		(width 0.09525)
		(layer "In4.Cu")
		(net "M_J_CPU1_SB_DQS_DP<3>")
	)
	(arc
		(start 144.714214 -290.597844)
		(mid 144.986315 -290.535166)
		(end 145.25498 -290.611306)
		(width 0.09525)
		(layer "In4.Cu")
		(net "M_J_CPU1_SB_DQS_DP<3>")
	)
	(arc
		(start 135.293354 -290.611306)
		(mid 135.574786 -290.535551)
		(end 135.856218 -290.611306)
		(width 0.09525)
		(layer "In4.Cu")
		(net "M_J_CPU1_SB_DQS_DP<3>")
	)
	(arc
		(start 142.813278 -290.611306)
		(mid 143.09471 -290.535551)
		(end 143.376142 -290.611306)
		(width 0.09525)
		(layer "In4.Cu")
		(net "M_J_CPU1_SB_DQS_DP<3>")
	)
	(arc
		(start 144.32915 -290.619688)
		(mid 144.511075 -290.661893)
		(end 144.690846 -290.611306)
		(width 0.09525)
		(layer "In4.Cu")
		(net "M_J_CPU1_SB_DQS_DP<3>")
	)
	(arc
		(start 142.436088 -290.611306)
		(mid 142.619863 -290.662078)
		(end 142.804896 -290.616132)
		(width 0.09525)
		(layer "In4.Cu")
		(net "M_J_CPU1_SB_DQS_DP<3>")
	)
	(arc
		(start 141.496288 -290.611306)
		(mid 141.684756 -290.661983)
		(end 141.873224 -290.611306)
		(width 0.09525)
		(layer "In4.Cu")
		(net "M_J_CPU1_SB_DQS_DP<3>")
	)
	(arc
		(start 139.053316 -290.611306)
		(mid 139.334748 -290.535551)
		(end 139.61618 -290.611306)
		(width 0.09525)
		(layer "In4.Cu")
		(net "M_J_CPU1_SB_DQS_DP<3>")
	)
	(arc
		(start 136.796272 -290.611306)
		(mid 136.98474 -290.661983)
		(end 137.173208 -290.611306)
		(width 0.09525)
		(layer "In4.Cu")
		(net "M_J_CPU1_SB_DQS_DP<3>")
	)
	(arc
		(start 139.624562 -290.616132)
		(mid 139.809594 -290.662046)
		(end 139.99337 -290.611306)
		(width 0.09525)
		(layer "In4.Cu")
		(net "M_J_CPU1_SB_DQS_DP<3>")
	)
	(arc
		(start 135.8646 -290.616132)
		(mid 136.049632 -290.662046)
		(end 136.233408 -290.611306)
		(width 0.09525)
		(layer "In4.Cu")
		(net "M_J_CPU1_SB_DQS_DP<3>")
	)
	(arc
		(start 143.384524 -290.616132)
		(mid 143.569556 -290.662046)
		(end 143.753332 -290.611306)
		(width 0.09525)
		(layer "In4.Cu")
		(net "M_J_CPU1_SB_DQS_DP<3>")
	)
	(arc
		(start 138.676126 -290.611306)
		(mid 138.859901 -290.662078)
		(end 139.044934 -290.616132)
		(width 0.09525)
		(layer "In4.Cu")
		(net "M_J_CPU1_SB_DQS_DP<3>")
	)
	(arc
		(start 133.093968 -290.63823)
		(mid 133.256619 -290.66049)
		(end 133.413246 -290.611306)
		(width 0.09525)
		(layer "In4.Cu")
		(net "M_J_CPU1_SB_DQS_DP<3>")
	)
	(arc
		(start 134.3533 -290.611306)
		(mid 134.634732 -290.535551)
		(end 134.916164 -290.611306)
		(width 0.09525)
		(layer "In4.Cu")
		(net "M_J_CPU1_SB_DQS_DP<3>")
	)
	(arc
		(start 137.736072 -290.611306)
		(mid 137.919847 -290.662078)
		(end 138.10488 -290.616132)
		(width 0.09525)
		(layer "In4.Cu")
		(net "M_J_CPU1_SB_DQS_DP<3>")
	)
	(arc
		(start 137.173208 -290.611306)
		(mid 137.45464 -290.535551)
		(end 137.736072 -290.611306)
		(width 0.09525)
		(layer "In4.Cu")
		(net "M_J_CPU1_SB_DQS_DP<3>")
	)
	(arc
		(start 143.753332 -290.611306)
		(mid 144.019419 -290.535761)
		(end 144.289272 -290.596574)
		(width 0.09525)
		(layer "In4.Cu")
		(net "M_J_CPU1_SB_DQS_DP<3>")
	)
	(arc
		(start 141.873224 -290.611306)
		(mid 142.154656 -290.535551)
		(end 142.436088 -290.611306)
		(width 0.09525)
		(layer "In4.Cu")
		(net "M_J_CPU1_SB_DQS_DP<3>")
	)
	(arc
		(start 139.99337 -290.611306)
		(mid 140.274802 -290.535551)
		(end 140.556234 -290.611306)
		(width 0.09525)
		(layer "In4.Cu")
		(net "M_J_CPU1_SB_DQS_DP<3>")
	)
	(arc
		(start 133.413246 -290.611306)
		(mid 133.694678 -290.535551)
		(end 133.97611 -290.611306)
		(width 0.09525)
		(layer "In4.Cu")
		(net "M_J_CPU1_SB_DQS_DP<3>")
	)
	(arc
		(start 134.924546 -290.616132)
		(mid 135.109578 -290.662046)
		(end 135.293354 -290.611306)
		(width 0.09525)
		(layer "In4.Cu")
		(net "M_J_CPU1_SB_DQS_DP<3>")
	)
	(arc
		(start 136.233408 -290.611306)
		(mid 136.51484 -290.535551)
		(end 136.796272 -290.611306)
		(width 0.09525)
		(layer "In4.Cu")
		(net "M_J_CPU1_SB_DQS_DP<3>")
	)
	(arc
		(start 140.564616 -290.616132)
		(mid 140.749648 -290.662046)
		(end 140.933424 -290.611306)
		(width 0.09525)
		(layer "In4.Cu")
		(net "M_J_CPU1_SB_DQS_DP<3>")
	)
	(arc
		(start 140.933424 -290.611306)
		(mid 141.214856 -290.535551)
		(end 141.496288 -290.611306)
		(width 0.09525)
		(layer "In4.Cu")
		(net "M_J_CPU1_SB_DQS_DP<3>")
	)
	(arc
		(start 138.113262 -290.611306)
		(mid 138.394694 -290.535551)
		(end 138.676126 -290.611306)
		(width 0.09525)
		(layer "In4.Cu")
		(net "M_J_CPU1_SB_DQS_DP<3>")
	)
	(arc
		(start 133.97611 -290.611306)
		(mid 134.159885 -290.662078)
		(end 134.344918 -290.616132)
		(width 0.09525)
		(layer "In4.Cu")
		(net "M_J_CPU1_SB_DQS_DP<3>")
	)
	(segment
		(start 132.757926 -285.160466)
		(end 133.224778 -285.426404)
		(width 0.12954)
		(layer "F.Cu")
		(net "M_J_CPU1_SB_DQS_DP<2>")
	)
	(segment
		(start 190.38062 -303.859184)
		(end 190.886334 -303.859184)
		(width 0.16002)
		(layer "In4.Cu")
		(net "M_J_CPU1_SB_DQS_DP<2>")
	)
	(segment
		(start 185.497978 -303.641252)
		(end 187.535566 -303.641252)
		(width 0.16002)
		(layer "In4.Cu")
		(net "M_J_CPU1_SB_DQS_DP<2>")
	)
	(segment
		(start 165.401498 -304.055272)
		(end 165.987222 -304.055272)
		(width 0.16002)
		(layer "In4.Cu")
		(net "M_J_CPU1_SB_DQS_DP<2>")
	)
	(segment
		(start 188.855604 -304.045112)
		(end 189.041532 -303.859184)
		(width 0.16002)
		(layer "In4.Cu")
		(net "M_J_CPU1_SB_DQS_DP<2>")
	)
	(segment
		(start 181.771036 -303.478946)
		(end 182.326788 -303.478946)
		(width 0.16002)
		(layer "In4.Cu")
		(net "M_J_CPU1_SB_DQS_DP<2>")
	)
	(segment
		(start 144.314672 -285.751524)
		(end 144.32915 -285.759906)
		(width 0.09525)
		(layer "In4.Cu")
		(net "M_J_CPU1_SB_DQS_DP<2>")
	)
	(segment
		(start 165.065456 -303.71923)
		(end 165.401498 -304.055272)
		(width 0.16002)
		(layer "In4.Cu")
		(net "M_J_CPU1_SB_DQS_DP<2>")
	)
	(segment
		(start 189.78372 -303.742344)
		(end 190.26378 -303.742344)
		(width 0.16002)
		(layer "In4.Cu")
		(net "M_J_CPU1_SB_DQS_DP<2>")
	)
	(segment
		(start 190.26378 -303.742344)
		(end 190.38062 -303.859184)
		(width 0.16002)
		(layer "In4.Cu")
		(net "M_J_CPU1_SB_DQS_DP<2>")
	)
	(segment
		(start 182.326788 -303.478946)
		(end 182.945532 -302.860202)
		(width 0.16002)
		(layer "In4.Cu")
		(net "M_J_CPU1_SB_DQS_DP<2>")
	)
	(segment
		(start 189.041532 -303.859184)
		(end 189.66688 -303.859184)
		(width 0.16002)
		(layer "In4.Cu")
		(net "M_J_CPU1_SB_DQS_DP<2>")
	)
	(segment
		(start 147.396962 -286.378904)
		(end 147.69973 -286.681672)
		(width 0.09525)
		(layer "In4.Cu")
		(net "M_J_CPU1_SB_DQS_DP<2>")
	)
	(segment
		(start 174.0281 -303.538382)
		(end 174.952152 -303.538382)
		(width 0.16002)
		(layer "In4.Cu")
		(net "M_J_CPU1_SB_DQS_DP<2>")
	)
	(segment
		(start 134.916164 -285.751524)
		(end 134.924546 -285.75635)
		(width 0.09525)
		(layer "In4.Cu")
		(net "M_J_CPU1_SB_DQS_DP<2>")
	)
	(segment
		(start 153.80589 -292.23589)
		(end 153.80589 -297.683428)
		(width 0.16002)
		(layer "In4.Cu")
		(net "M_J_CPU1_SB_DQS_DP<2>")
	)
	(segment
		(start 143.376142 -285.751524)
		(end 143.384524 -285.75635)
		(width 0.09525)
		(layer "In4.Cu")
		(net "M_J_CPU1_SB_DQS_DP<2>")
	)
	(segment
		(start 133.070854 -285.691834)
		(end 133.093968 -285.778448)
		(width 0.09525)
		(layer "In4.Cu")
		(net "M_J_CPU1_SB_DQS_DP<2>")
	)
	(segment
		(start 180.189124 -303.710086)
		(end 180.50129 -304.022252)
		(width 0.16002)
		(layer "In4.Cu")
		(net "M_J_CPU1_SB_DQS_DP<2>")
	)
	(segment
		(start 187.535566 -303.641252)
		(end 187.939426 -304.045112)
		(width 0.16002)
		(layer "In4.Cu")
		(net "M_J_CPU1_SB_DQS_DP<2>")
	)
	(segment
		(start 139.61618 -285.751524)
		(end 139.624562 -285.75635)
		(width 0.09525)
		(layer "In4.Cu")
		(net "M_J_CPU1_SB_DQS_DP<2>")
	)
	(segment
		(start 172.752258 -304.045112)
		(end 173.52137 -304.045112)
		(width 0.16002)
		(layer "In4.Cu")
		(net "M_J_CPU1_SB_DQS_DP<2>")
	)
	(segment
		(start 138.10488 -285.75635)
		(end 138.113262 -285.751524)
		(width 0.09525)
		(layer "In4.Cu")
		(net "M_J_CPU1_SB_DQS_DP<2>")
	)
	(segment
		(start 170.070526 -303.270412)
		(end 170.5102 -303.710086)
		(width 0.16002)
		(layer "In4.Cu")
		(net "M_J_CPU1_SB_DQS_DP<2>")
	)
	(segment
		(start 177.267108 -302.860202)
		(end 178.116992 -303.710086)
		(width 0.16002)
		(layer "In4.Cu")
		(net "M_J_CPU1_SB_DQS_DP<2>")
	)
	(segment
		(start 189.66688 -303.859184)
		(end 189.78372 -303.742344)
		(width 0.16002)
		(layer "In4.Cu")
		(net "M_J_CPU1_SB_DQS_DP<2>")
	)
	(segment
		(start 133.224778 -285.426404)
		(end 133.070854 -285.691834)
		(width 0.09525)
		(layer "In4.Cu")
		(net "M_J_CPU1_SB_DQS_DP<2>")
	)
	(segment
		(start 153.80589 -297.683428)
		(end 159.841692 -303.71923)
		(width 0.16002)
		(layer "In4.Cu")
		(net "M_J_CPU1_SB_DQS_DP<2>")
	)
	(segment
		(start 172.417232 -303.710086)
		(end 172.752258 -304.045112)
		(width 0.16002)
		(layer "In4.Cu")
		(net "M_J_CPU1_SB_DQS_DP<2>")
	)
	(segment
		(start 166.772082 -303.270412)
		(end 170.070526 -303.270412)
		(width 0.16002)
		(layer "In4.Cu")
		(net "M_J_CPU1_SB_DQS_DP<2>")
	)
	(segment
		(start 135.856218 -285.751524)
		(end 135.8646 -285.75635)
		(width 0.09525)
		(layer "In4.Cu")
		(net "M_J_CPU1_SB_DQS_DP<2>")
	)
	(segment
		(start 178.116992 -303.710086)
		(end 180.189124 -303.710086)
		(width 0.16002)
		(layer "In4.Cu")
		(net "M_J_CPU1_SB_DQS_DP<2>")
	)
	(segment
		(start 170.5102 -303.710086)
		(end 172.417232 -303.710086)
		(width 0.16002)
		(layer "In4.Cu")
		(net "M_J_CPU1_SB_DQS_DP<2>")
	)
	(segment
		(start 142.804896 -285.75635)
		(end 142.813278 -285.751524)
		(width 0.09525)
		(layer "In4.Cu")
		(net "M_J_CPU1_SB_DQS_DP<2>")
	)
	(segment
		(start 159.841692 -303.71923)
		(end 165.065456 -303.71923)
		(width 0.16002)
		(layer "In4.Cu")
		(net "M_J_CPU1_SB_DQS_DP<2>")
	)
	(segment
		(start 134.344918 -285.75635)
		(end 134.3533 -285.751524)
		(width 0.09525)
		(layer "In4.Cu")
		(net "M_J_CPU1_SB_DQS_DP<2>")
	)
	(segment
		(start 147.80133 -286.681672)
		(end 147.860512 -286.62249)
		(width 0.09525)
		(layer "In4.Cu")
		(net "M_J_CPU1_SB_DQS_DP<2>")
	)
	(segment
		(start 175.630332 -302.860202)
		(end 177.267108 -302.860202)
		(width 0.16002)
		(layer "In4.Cu")
		(net "M_J_CPU1_SB_DQS_DP<2>")
	)
	(segment
		(start 147.884134 -286.62249)
		(end 148.19249 -286.62249)
		(width 0.16002)
		(layer "In4.Cu")
		(net "M_J_CPU1_SB_DQS_DP<2>")
	)
	(segment
		(start 146.854926 -286.378904)
		(end 147.396962 -286.378904)
		(width 0.09525)
		(layer "In4.Cu")
		(net "M_J_CPU1_SB_DQS_DP<2>")
	)
	(segment
		(start 173.52137 -304.045112)
		(end 174.0281 -303.538382)
		(width 0.16002)
		(layer "In4.Cu")
		(net "M_J_CPU1_SB_DQS_DP<2>")
	)
	(segment
		(start 165.987222 -304.055272)
		(end 166.772082 -303.270412)
		(width 0.16002)
		(layer "In4.Cu")
		(net "M_J_CPU1_SB_DQS_DP<2>")
	)
	(segment
		(start 144.289272 -285.736792)
		(end 144.314672 -285.751524)
		(width 0.09525)
		(layer "In4.Cu")
		(net "M_J_CPU1_SB_DQS_DP<2>")
	)
	(segment
		(start 140.556234 -285.751524)
		(end 140.564616 -285.75635)
		(width 0.09525)
		(layer "In4.Cu")
		(net "M_J_CPU1_SB_DQS_DP<2>")
	)
	(segment
		(start 147.860512 -286.62249)
		(end 147.884134 -286.62249)
		(width 0.09525)
		(layer "In4.Cu")
		(net "M_J_CPU1_SB_DQS_DP<2>")
	)
	(segment
		(start 187.939426 -304.045112)
		(end 188.855604 -304.045112)
		(width 0.16002)
		(layer "In4.Cu")
		(net "M_J_CPU1_SB_DQS_DP<2>")
	)
	(segment
		(start 147.69973 -286.681672)
		(end 147.80133 -286.681672)
		(width 0.09525)
		(layer "In4.Cu")
		(net "M_J_CPU1_SB_DQS_DP<2>")
	)
	(segment
		(start 180.50129 -304.022252)
		(end 181.22773 -304.022252)
		(width 0.16002)
		(layer "In4.Cu")
		(net "M_J_CPU1_SB_DQS_DP<2>")
	)
	(segment
		(start 146.279616 -285.803594)
		(end 146.854926 -286.378904)
		(width 0.09525)
		(layer "In4.Cu")
		(net "M_J_CPU1_SB_DQS_DP<2>")
	)
	(segment
		(start 190.886334 -303.859184)
		(end 191.160146 -303.585372)
		(width 0.16002)
		(layer "In4.Cu")
		(net "M_J_CPU1_SB_DQS_DP<2>")
	)
	(segment
		(start 144.690846 -285.751524)
		(end 144.714214 -285.738062)
		(width 0.09525)
		(layer "In4.Cu")
		(net "M_J_CPU1_SB_DQS_DP<2>")
	)
	(segment
		(start 145.444718 -285.803594)
		(end 146.279616 -285.803594)
		(width 0.09525)
		(layer "In4.Cu")
		(net "M_J_CPU1_SB_DQS_DP<2>")
	)
	(segment
		(start 139.044934 -285.75635)
		(end 139.053316 -285.751524)
		(width 0.09525)
		(layer "In4.Cu")
		(net "M_J_CPU1_SB_DQS_DP<2>")
	)
	(segment
		(start 182.945532 -302.860202)
		(end 184.716928 -302.860202)
		(width 0.16002)
		(layer "In4.Cu")
		(net "M_J_CPU1_SB_DQS_DP<2>")
	)
	(segment
		(start 184.716928 -302.860202)
		(end 185.497978 -303.641252)
		(width 0.16002)
		(layer "In4.Cu")
		(net "M_J_CPU1_SB_DQS_DP<2>")
	)
	(segment
		(start 181.22773 -304.022252)
		(end 181.771036 -303.478946)
		(width 0.16002)
		(layer "In4.Cu")
		(net "M_J_CPU1_SB_DQS_DP<2>")
	)
	(segment
		(start 148.19249 -286.62249)
		(end 153.80589 -292.23589)
		(width 0.16002)
		(layer "In4.Cu")
		(net "M_J_CPU1_SB_DQS_DP<2>")
	)
	(segment
		(start 174.952152 -303.538382)
		(end 175.630332 -302.860202)
		(width 0.16002)
		(layer "In4.Cu")
		(net "M_J_CPU1_SB_DQS_DP<2>")
	)
	(arc
		(start 133.413246 -285.751524)
		(mid 133.694678 -285.675769)
		(end 133.97611 -285.751524)
		(width 0.09525)
		(layer "In4.Cu")
		(net "M_J_CPU1_SB_DQS_DP<2>")
	)
	(arc
		(start 134.924546 -285.75635)
		(mid 135.109578 -285.802264)
		(end 135.293354 -285.751524)
		(width 0.09525)
		(layer "In4.Cu")
		(net "M_J_CPU1_SB_DQS_DP<2>")
	)
	(arc
		(start 137.173208 -285.751524)
		(mid 137.45464 -285.675769)
		(end 137.736072 -285.751524)
		(width 0.09525)
		(layer "In4.Cu")
		(net "M_J_CPU1_SB_DQS_DP<2>")
	)
	(arc
		(start 139.053316 -285.751524)
		(mid 139.334748 -285.675769)
		(end 139.61618 -285.751524)
		(width 0.09525)
		(layer "In4.Cu")
		(net "M_J_CPU1_SB_DQS_DP<2>")
	)
	(arc
		(start 140.933424 -285.751524)
		(mid 141.214856 -285.675769)
		(end 141.496288 -285.751524)
		(width 0.09525)
		(layer "In4.Cu")
		(net "M_J_CPU1_SB_DQS_DP<2>")
	)
	(arc
		(start 139.624562 -285.75635)
		(mid 139.809594 -285.802264)
		(end 139.99337 -285.751524)
		(width 0.09525)
		(layer "In4.Cu")
		(net "M_J_CPU1_SB_DQS_DP<2>")
	)
	(arc
		(start 144.32915 -285.759906)
		(mid 144.511075 -285.802111)
		(end 144.690846 -285.751524)
		(width 0.09525)
		(layer "In4.Cu")
		(net "M_J_CPU1_SB_DQS_DP<2>")
	)
	(arc
		(start 138.676126 -285.751524)
		(mid 138.859901 -285.802296)
		(end 139.044934 -285.75635)
		(width 0.09525)
		(layer "In4.Cu")
		(net "M_J_CPU1_SB_DQS_DP<2>")
	)
	(arc
		(start 142.813278 -285.751524)
		(mid 143.09471 -285.675769)
		(end 143.376142 -285.751524)
		(width 0.09525)
		(layer "In4.Cu")
		(net "M_J_CPU1_SB_DQS_DP<2>")
	)
	(arc
		(start 138.113262 -285.751524)
		(mid 138.394694 -285.675769)
		(end 138.676126 -285.751524)
		(width 0.09525)
		(layer "In4.Cu")
		(net "M_J_CPU1_SB_DQS_DP<2>")
	)
	(arc
		(start 143.384524 -285.75635)
		(mid 143.569556 -285.802264)
		(end 143.753332 -285.751524)
		(width 0.09525)
		(layer "In4.Cu")
		(net "M_J_CPU1_SB_DQS_DP<2>")
	)
	(arc
		(start 135.8646 -285.75635)
		(mid 136.049632 -285.802264)
		(end 136.233408 -285.751524)
		(width 0.09525)
		(layer "In4.Cu")
		(net "M_J_CPU1_SB_DQS_DP<2>")
	)
	(arc
		(start 133.093968 -285.778448)
		(mid 133.256619 -285.800708)
		(end 133.413246 -285.751524)
		(width 0.09525)
		(layer "In4.Cu")
		(net "M_J_CPU1_SB_DQS_DP<2>")
	)
	(arc
		(start 137.736072 -285.751524)
		(mid 137.919847 -285.802296)
		(end 138.10488 -285.75635)
		(width 0.09525)
		(layer "In4.Cu")
		(net "M_J_CPU1_SB_DQS_DP<2>")
	)
	(arc
		(start 134.3533 -285.751524)
		(mid 134.634732 -285.675769)
		(end 134.916164 -285.751524)
		(width 0.09525)
		(layer "In4.Cu")
		(net "M_J_CPU1_SB_DQS_DP<2>")
	)
	(arc
		(start 141.496288 -285.751524)
		(mid 141.684756 -285.802201)
		(end 141.873224 -285.751524)
		(width 0.09525)
		(layer "In4.Cu")
		(net "M_J_CPU1_SB_DQS_DP<2>")
	)
	(arc
		(start 133.97611 -285.751524)
		(mid 134.159885 -285.802296)
		(end 134.344918 -285.75635)
		(width 0.09525)
		(layer "In4.Cu")
		(net "M_J_CPU1_SB_DQS_DP<2>")
	)
	(arc
		(start 143.753332 -285.751524)
		(mid 144.019419 -285.675979)
		(end 144.289272 -285.736792)
		(width 0.09525)
		(layer "In4.Cu")
		(net "M_J_CPU1_SB_DQS_DP<2>")
	)
	(arc
		(start 139.99337 -285.751524)
		(mid 140.274802 -285.675769)
		(end 140.556234 -285.751524)
		(width 0.09525)
		(layer "In4.Cu")
		(net "M_J_CPU1_SB_DQS_DP<2>")
	)
	(arc
		(start 135.293354 -285.751524)
		(mid 135.574786 -285.675769)
		(end 135.856218 -285.751524)
		(width 0.09525)
		(layer "In4.Cu")
		(net "M_J_CPU1_SB_DQS_DP<2>")
	)
	(arc
		(start 142.436088 -285.751524)
		(mid 142.619863 -285.802296)
		(end 142.804896 -285.75635)
		(width 0.09525)
		(layer "In4.Cu")
		(net "M_J_CPU1_SB_DQS_DP<2>")
	)
	(arc
		(start 140.564616 -285.75635)
		(mid 140.749648 -285.802264)
		(end 140.933424 -285.751524)
		(width 0.09525)
		(layer "In4.Cu")
		(net "M_J_CPU1_SB_DQS_DP<2>")
	)
	(arc
		(start 141.873224 -285.751524)
		(mid 142.154656 -285.675769)
		(end 142.436088 -285.751524)
		(width 0.09525)
		(layer "In4.Cu")
		(net "M_J_CPU1_SB_DQS_DP<2>")
	)
	(arc
		(start 136.233408 -285.751524)
		(mid 136.51484 -285.675769)
		(end 136.796272 -285.751524)
		(width 0.09525)
		(layer "In4.Cu")
		(net "M_J_CPU1_SB_DQS_DP<2>")
	)
	(arc
		(start 145.25498 -285.751524)
		(mid 145.346392 -285.790144)
		(end 145.444718 -285.803594)
		(width 0.09525)
		(layer "In4.Cu")
		(net "M_J_CPU1_SB_DQS_DP<2>")
	)
	(arc
		(start 136.796272 -285.751524)
		(mid 136.98474 -285.802201)
		(end 137.173208 -285.751524)
		(width 0.09525)
		(layer "In4.Cu")
		(net "M_J_CPU1_SB_DQS_DP<2>")
	)
	(arc
		(start 144.714214 -285.738062)
		(mid 144.986315 -285.675384)
		(end 145.25498 -285.751524)
		(width 0.09525)
		(layer "In4.Cu")
		(net "M_J_CPU1_SB_DQS_DP<2>")
	)
	(segment
		(start 132.757926 -280.30043)
		(end 133.224778 -280.566368)
		(width 0.12954)
		(layer "F.Cu")
		(net "M_J_CPU1_SB_DQS_DP<1>")
	)
	(segment
		(start 182.326788 -294.128952)
		(end 182.945532 -293.510208)
		(width 0.16002)
		(layer "In4.Cu")
		(net "M_J_CPU1_SB_DQS_DP<1>")
	)
	(segment
		(start 159.34309 -291.524182)
		(end 162.89528 -295.076372)
		(width 0.16002)
		(layer "In4.Cu")
		(net "M_J_CPU1_SB_DQS_DP<1>")
	)
	(segment
		(start 162.89528 -295.076372)
		(end 164.506656 -295.076372)
		(width 0.16002)
		(layer "In4.Cu")
		(net "M_J_CPU1_SB_DQS_DP<1>")
	)
	(segment
		(start 180.189124 -294.360092)
		(end 180.50129 -294.672258)
		(width 0.16002)
		(layer "In4.Cu")
		(net "M_J_CPU1_SB_DQS_DP<1>")
	)
	(segment
		(start 181.771036 -294.128952)
		(end 182.326788 -294.128952)
		(width 0.16002)
		(layer "In4.Cu")
		(net "M_J_CPU1_SB_DQS_DP<1>")
	)
	(segment
		(start 165.987222 -294.705278)
		(end 166.772082 -293.920418)
		(width 0.16002)
		(layer "In4.Cu")
		(net "M_J_CPU1_SB_DQS_DP<1>")
	)
	(segment
		(start 147.919186 -280.857452)
		(end 150.261066 -280.857452)
		(width 0.16002)
		(layer "In4.Cu")
		(net "M_J_CPU1_SB_DQS_DP<1>")
	)
	(segment
		(start 135.856218 -280.891488)
		(end 135.8646 -280.896314)
		(width 0.09525)
		(layer "In4.Cu")
		(net "M_J_CPU1_SB_DQS_DP<1>")
	)
	(segment
		(start 166.772082 -293.920418)
		(end 170.070526 -293.920418)
		(width 0.16002)
		(layer "In4.Cu")
		(net "M_J_CPU1_SB_DQS_DP<1>")
	)
	(segment
		(start 180.50129 -294.672258)
		(end 181.22773 -294.672258)
		(width 0.16002)
		(layer "In4.Cu")
		(net "M_J_CPU1_SB_DQS_DP<1>")
	)
	(segment
		(start 189.625732 -294.39235)
		(end 190.105792 -294.39235)
		(width 0.16002)
		(layer "In4.Cu")
		(net "M_J_CPU1_SB_DQS_DP<1>")
	)
	(segment
		(start 170.5102 -294.360092)
		(end 172.417232 -294.360092)
		(width 0.16002)
		(layer "In4.Cu")
		(net "M_J_CPU1_SB_DQS_DP<1>")
	)
	(segment
		(start 189.028832 -294.50919)
		(end 189.508892 -294.50919)
		(width 0.16002)
		(layer "In4.Cu")
		(net "M_J_CPU1_SB_DQS_DP<1>")
	)
	(segment
		(start 181.22773 -294.672258)
		(end 181.771036 -294.128952)
		(width 0.16002)
		(layer "In4.Cu")
		(net "M_J_CPU1_SB_DQS_DP<1>")
	)
	(segment
		(start 190.105792 -294.39235)
		(end 190.222632 -294.50919)
		(width 0.16002)
		(layer "In4.Cu")
		(net "M_J_CPU1_SB_DQS_DP<1>")
	)
	(segment
		(start 134.916164 -280.891488)
		(end 134.924546 -280.896314)
		(width 0.09525)
		(layer "In4.Cu")
		(net "M_J_CPU1_SB_DQS_DP<1>")
	)
	(segment
		(start 187.535566 -294.291258)
		(end 187.939426 -294.695118)
		(width 0.16002)
		(layer "In4.Cu")
		(net "M_J_CPU1_SB_DQS_DP<1>")
	)
	(segment
		(start 172.752258 -294.695118)
		(end 173.52137 -294.695118)
		(width 0.16002)
		(layer "In4.Cu")
		(net "M_J_CPU1_SB_DQS_DP<1>")
	)
	(segment
		(start 164.87775 -294.705278)
		(end 165.987222 -294.705278)
		(width 0.16002)
		(layer "In4.Cu")
		(net "M_J_CPU1_SB_DQS_DP<1>")
	)
	(segment
		(start 150.261066 -280.857452)
		(end 159.34309 -289.939476)
		(width 0.16002)
		(layer "In4.Cu")
		(net "M_J_CPU1_SB_DQS_DP<1>")
	)
	(segment
		(start 143.376142 -280.891488)
		(end 143.384524 -280.896314)
		(width 0.09525)
		(layer "In4.Cu")
		(net "M_J_CPU1_SB_DQS_DP<1>")
	)
	(segment
		(start 133.224778 -280.566368)
		(end 133.070854 -280.831798)
		(width 0.09525)
		(layer "In4.Cu")
		(net "M_J_CPU1_SB_DQS_DP<1>")
	)
	(segment
		(start 140.556234 -280.891488)
		(end 140.564616 -280.896314)
		(width 0.09525)
		(layer "In4.Cu")
		(net "M_J_CPU1_SB_DQS_DP<1>")
	)
	(segment
		(start 190.886334 -294.50919)
		(end 191.160146 -294.235378)
		(width 0.16002)
		(layer "In4.Cu")
		(net "M_J_CPU1_SB_DQS_DP<1>")
	)
	(segment
		(start 174.0281 -294.188388)
		(end 174.952152 -294.188388)
		(width 0.16002)
		(layer "In4.Cu")
		(net "M_J_CPU1_SB_DQS_DP<1>")
	)
	(segment
		(start 139.044934 -280.896314)
		(end 139.053316 -280.891488)
		(width 0.09525)
		(layer "In4.Cu")
		(net "M_J_CPU1_SB_DQS_DP<1>")
	)
	(segment
		(start 178.116992 -294.360092)
		(end 180.189124 -294.360092)
		(width 0.16002)
		(layer "In4.Cu")
		(net "M_J_CPU1_SB_DQS_DP<1>")
	)
	(segment
		(start 182.945532 -293.510208)
		(end 184.716928 -293.510208)
		(width 0.16002)
		(layer "In4.Cu")
		(net "M_J_CPU1_SB_DQS_DP<1>")
	)
	(segment
		(start 190.222632 -294.50919)
		(end 190.886334 -294.50919)
		(width 0.16002)
		(layer "In4.Cu")
		(net "M_J_CPU1_SB_DQS_DP<1>")
	)
	(segment
		(start 173.52137 -294.695118)
		(end 174.0281 -294.188388)
		(width 0.16002)
		(layer "In4.Cu")
		(net "M_J_CPU1_SB_DQS_DP<1>")
	)
	(segment
		(start 147.337272 -280.53792)
		(end 147.609814 -280.916634)
		(width 0.09525)
		(layer "In4.Cu")
		(net "M_J_CPU1_SB_DQS_DP<1>")
	)
	(segment
		(start 175.630332 -293.510208)
		(end 177.267108 -293.510208)
		(width 0.16002)
		(layer "In4.Cu")
		(net "M_J_CPU1_SB_DQS_DP<1>")
	)
	(segment
		(start 189.508892 -294.50919)
		(end 189.625732 -294.39235)
		(width 0.16002)
		(layer "In4.Cu")
		(net "M_J_CPU1_SB_DQS_DP<1>")
	)
	(segment
		(start 177.267108 -293.510208)
		(end 178.116992 -294.360092)
		(width 0.16002)
		(layer "In4.Cu")
		(net "M_J_CPU1_SB_DQS_DP<1>")
	)
	(segment
		(start 187.939426 -294.695118)
		(end 188.842904 -294.695118)
		(width 0.16002)
		(layer "In4.Cu")
		(net "M_J_CPU1_SB_DQS_DP<1>")
	)
	(segment
		(start 138.10488 -280.896314)
		(end 138.113262 -280.891488)
		(width 0.09525)
		(layer "In4.Cu")
		(net "M_J_CPU1_SB_DQS_DP<1>")
	)
	(segment
		(start 188.842904 -294.695118)
		(end 189.028832 -294.50919)
		(width 0.16002)
		(layer "In4.Cu")
		(net "M_J_CPU1_SB_DQS_DP<1>")
	)
	(segment
		(start 172.417232 -294.360092)
		(end 172.752258 -294.695118)
		(width 0.16002)
		(layer "In4.Cu")
		(net "M_J_CPU1_SB_DQS_DP<1>")
	)
	(segment
		(start 147.836382 -280.916634)
		(end 147.895564 -280.857452)
		(width 0.09525)
		(layer "In4.Cu")
		(net "M_J_CPU1_SB_DQS_DP<1>")
	)
	(segment
		(start 144.289272 -280.876756)
		(end 144.314672 -280.891488)
		(width 0.09525)
		(layer "In4.Cu")
		(net "M_J_CPU1_SB_DQS_DP<1>")
	)
	(segment
		(start 139.61618 -280.891488)
		(end 139.624562 -280.896314)
		(width 0.09525)
		(layer "In4.Cu")
		(net "M_J_CPU1_SB_DQS_DP<1>")
	)
	(segment
		(start 144.690846 -280.891488)
		(end 144.714214 -280.878026)
		(width 0.09525)
		(layer "In4.Cu")
		(net "M_J_CPU1_SB_DQS_DP<1>")
	)
	(segment
		(start 142.804896 -280.896314)
		(end 142.813278 -280.891488)
		(width 0.09525)
		(layer "In4.Cu")
		(net "M_J_CPU1_SB_DQS_DP<1>")
	)
	(segment
		(start 133.070854 -280.831798)
		(end 133.093968 -280.918412)
		(width 0.09525)
		(layer "In4.Cu")
		(net "M_J_CPU1_SB_DQS_DP<1>")
	)
	(segment
		(start 144.314672 -280.891488)
		(end 144.32915 -280.89987)
		(width 0.09525)
		(layer "In4.Cu")
		(net "M_J_CPU1_SB_DQS_DP<1>")
	)
	(segment
		(start 134.344918 -280.896314)
		(end 134.3533 -280.891488)
		(width 0.09525)
		(layer "In4.Cu")
		(net "M_J_CPU1_SB_DQS_DP<1>")
	)
	(segment
		(start 147.895564 -280.857452)
		(end 147.919186 -280.857452)
		(width 0.09525)
		(layer "In4.Cu")
		(net "M_J_CPU1_SB_DQS_DP<1>")
	)
	(segment
		(start 174.952152 -294.188388)
		(end 175.630332 -293.510208)
		(width 0.16002)
		(layer "In4.Cu")
		(net "M_J_CPU1_SB_DQS_DP<1>")
	)
	(segment
		(start 159.34309 -289.939476)
		(end 159.34309 -291.524182)
		(width 0.16002)
		(layer "In4.Cu")
		(net "M_J_CPU1_SB_DQS_DP<1>")
	)
	(segment
		(start 164.506656 -295.076372)
		(end 164.87775 -294.705278)
		(width 0.16002)
		(layer "In4.Cu")
		(net "M_J_CPU1_SB_DQS_DP<1>")
	)
	(segment
		(start 147.609814 -280.916634)
		(end 147.836382 -280.916634)
		(width 0.09525)
		(layer "In4.Cu")
		(net "M_J_CPU1_SB_DQS_DP<1>")
	)
	(segment
		(start 146.213576 -280.53792)
		(end 147.337272 -280.53792)
		(width 0.09525)
		(layer "In4.Cu")
		(net "M_J_CPU1_SB_DQS_DP<1>")
	)
	(segment
		(start 185.497978 -294.291258)
		(end 187.535566 -294.291258)
		(width 0.16002)
		(layer "In4.Cu")
		(net "M_J_CPU1_SB_DQS_DP<1>")
	)
	(segment
		(start 184.716928 -293.510208)
		(end 185.497978 -294.291258)
		(width 0.16002)
		(layer "In4.Cu")
		(net "M_J_CPU1_SB_DQS_DP<1>")
	)
	(segment
		(start 170.070526 -293.920418)
		(end 170.5102 -294.360092)
		(width 0.16002)
		(layer "In4.Cu")
		(net "M_J_CPU1_SB_DQS_DP<1>")
	)
	(segment
		(start 145.761964 -280.834846)
		(end 145.949416 -280.647394)
		(width 0.09525)
		(layer "In4.Cu")
		(net "M_J_CPU1_SB_DQS_DP<1>")
	)
	(arc
		(start 136.796272 -280.891488)
		(mid 136.98474 -280.942165)
		(end 137.173208 -280.891488)
		(width 0.09525)
		(layer "In4.Cu")
		(net "M_J_CPU1_SB_DQS_DP<1>")
	)
	(arc
		(start 136.233408 -280.891488)
		(mid 136.51484 -280.815733)
		(end 136.796272 -280.891488)
		(width 0.09525)
		(layer "In4.Cu")
		(net "M_J_CPU1_SB_DQS_DP<1>")
	)
	(arc
		(start 133.413246 -280.891488)
		(mid 133.694678 -280.815733)
		(end 133.97611 -280.891488)
		(width 0.09525)
		(layer "In4.Cu")
		(net "M_J_CPU1_SB_DQS_DP<1>")
	)
	(arc
		(start 135.293354 -280.891488)
		(mid 135.574786 -280.815733)
		(end 135.856218 -280.891488)
		(width 0.09525)
		(layer "In4.Cu")
		(net "M_J_CPU1_SB_DQS_DP<1>")
	)
	(arc
		(start 141.873224 -280.891488)
		(mid 142.154656 -280.815733)
		(end 142.436088 -280.891488)
		(width 0.09525)
		(layer "In4.Cu")
		(net "M_J_CPU1_SB_DQS_DP<1>")
	)
	(arc
		(start 145.444718 -280.943558)
		(mid 145.612392 -280.915621)
		(end 145.761964 -280.834846)
		(width 0.09525)
		(layer "In4.Cu")
		(net "M_J_CPU1_SB_DQS_DP<1>")
	)
	(arc
		(start 144.714214 -280.878026)
		(mid 144.986315 -280.815348)
		(end 145.25498 -280.891488)
		(width 0.09525)
		(layer "In4.Cu")
		(net "M_J_CPU1_SB_DQS_DP<1>")
	)
	(arc
		(start 138.676126 -280.891488)
		(mid 138.859901 -280.94226)
		(end 139.044934 -280.896314)
		(width 0.09525)
		(layer "In4.Cu")
		(net "M_J_CPU1_SB_DQS_DP<1>")
	)
	(arc
		(start 140.933424 -280.891488)
		(mid 141.214856 -280.815733)
		(end 141.496288 -280.891488)
		(width 0.09525)
		(layer "In4.Cu")
		(net "M_J_CPU1_SB_DQS_DP<1>")
	)
	(arc
		(start 137.173208 -280.891488)
		(mid 137.45464 -280.815733)
		(end 137.736072 -280.891488)
		(width 0.09525)
		(layer "In4.Cu")
		(net "M_J_CPU1_SB_DQS_DP<1>")
	)
	(arc
		(start 145.25498 -280.891488)
		(mid 145.346392 -280.930108)
		(end 145.444718 -280.943558)
		(width 0.09525)
		(layer "In4.Cu")
		(net "M_J_CPU1_SB_DQS_DP<1>")
	)
	(arc
		(start 137.736072 -280.891488)
		(mid 137.919847 -280.94226)
		(end 138.10488 -280.896314)
		(width 0.09525)
		(layer "In4.Cu")
		(net "M_J_CPU1_SB_DQS_DP<1>")
	)
	(arc
		(start 142.813278 -280.891488)
		(mid 143.09471 -280.815733)
		(end 143.376142 -280.891488)
		(width 0.09525)
		(layer "In4.Cu")
		(net "M_J_CPU1_SB_DQS_DP<1>")
	)
	(arc
		(start 139.99337 -280.891488)
		(mid 140.274802 -280.815733)
		(end 140.556234 -280.891488)
		(width 0.09525)
		(layer "In4.Cu")
		(net "M_J_CPU1_SB_DQS_DP<1>")
	)
	(arc
		(start 133.093968 -280.918412)
		(mid 133.256619 -280.940672)
		(end 133.413246 -280.891488)
		(width 0.09525)
		(layer "In4.Cu")
		(net "M_J_CPU1_SB_DQS_DP<1>")
	)
	(arc
		(start 139.053316 -280.891488)
		(mid 139.334748 -280.815733)
		(end 139.61618 -280.891488)
		(width 0.09525)
		(layer "In4.Cu")
		(net "M_J_CPU1_SB_DQS_DP<1>")
	)
	(arc
		(start 142.436088 -280.891488)
		(mid 142.619863 -280.94226)
		(end 142.804896 -280.896314)
		(width 0.09525)
		(layer "In4.Cu")
		(net "M_J_CPU1_SB_DQS_DP<1>")
	)
	(arc
		(start 134.3533 -280.891488)
		(mid 134.634732 -280.815733)
		(end 134.916164 -280.891488)
		(width 0.09525)
		(layer "In4.Cu")
		(net "M_J_CPU1_SB_DQS_DP<1>")
	)
	(arc
		(start 144.32915 -280.89987)
		(mid 144.511075 -280.942075)
		(end 144.690846 -280.891488)
		(width 0.09525)
		(layer "In4.Cu")
		(net "M_J_CPU1_SB_DQS_DP<1>")
	)
	(arc
		(start 141.496288 -280.891488)
		(mid 141.684756 -280.942165)
		(end 141.873224 -280.891488)
		(width 0.09525)
		(layer "In4.Cu")
		(net "M_J_CPU1_SB_DQS_DP<1>")
	)
	(arc
		(start 140.564616 -280.896314)
		(mid 140.749648 -280.942228)
		(end 140.933424 -280.891488)
		(width 0.09525)
		(layer "In4.Cu")
		(net "M_J_CPU1_SB_DQS_DP<1>")
	)
	(arc
		(start 138.113262 -280.891488)
		(mid 138.394694 -280.815733)
		(end 138.676126 -280.891488)
		(width 0.09525)
		(layer "In4.Cu")
		(net "M_J_CPU1_SB_DQS_DP<1>")
	)
	(arc
		(start 143.384524 -280.896314)
		(mid 143.569556 -280.942228)
		(end 143.753332 -280.891488)
		(width 0.09525)
		(layer "In4.Cu")
		(net "M_J_CPU1_SB_DQS_DP<1>")
	)
	(arc
		(start 145.949416 -280.647394)
		(mid 146.070599 -280.566359)
		(end 146.213576 -280.53792)
		(width 0.09525)
		(layer "In4.Cu")
		(net "M_J_CPU1_SB_DQS_DP<1>")
	)
	(arc
		(start 134.924546 -280.896314)
		(mid 135.109578 -280.942228)
		(end 135.293354 -280.891488)
		(width 0.09525)
		(layer "In4.Cu")
		(net "M_J_CPU1_SB_DQS_DP<1>")
	)
	(arc
		(start 133.97611 -280.891488)
		(mid 134.159885 -280.94226)
		(end 134.344918 -280.896314)
		(width 0.09525)
		(layer "In4.Cu")
		(net "M_J_CPU1_SB_DQS_DP<1>")
	)
	(arc
		(start 143.753332 -280.891488)
		(mid 144.019419 -280.815943)
		(end 144.289272 -280.876756)
		(width 0.09525)
		(layer "In4.Cu")
		(net "M_J_CPU1_SB_DQS_DP<1>")
	)
	(arc
		(start 139.624562 -280.896314)
		(mid 139.809594 -280.942228)
		(end 139.99337 -280.891488)
		(width 0.09525)
		(layer "In4.Cu")
		(net "M_J_CPU1_SB_DQS_DP<1>")
	)
	(arc
		(start 135.8646 -280.896314)
		(mid 136.049632 -280.942228)
		(end 136.233408 -280.891488)
		(width 0.09525)
		(layer "In4.Cu")
		(net "M_J_CPU1_SB_DQS_DP<1>")
	)
	(segment
		(start 132.757926 -275.440394)
		(end 133.224778 -275.706332)
		(width 0.12954)
		(layer "F.Cu")
		(net "M_J_CPU1_SB_DQS_DP<0>")
	)
	(segment
		(start 187.535566 -284.941264)
		(end 187.939426 -285.345124)
		(width 0.16002)
		(layer "In4.Cu")
		(net "M_J_CPU1_SB_DQS_DP<0>")
	)
	(segment
		(start 145.710402 -275.972016)
		(end 146.685 -274.997418)
		(width 0.09525)
		(layer "In4.Cu")
		(net "M_J_CPU1_SB_DQS_DP<0>")
	)
	(segment
		(start 134.344918 -276.036278)
		(end 134.3533 -276.031452)
		(width 0.09525)
		(layer "In4.Cu")
		(net "M_J_CPU1_SB_DQS_DP<0>")
	)
	(segment
		(start 164.947346 -284.618684)
		(end 165.683946 -285.355284)
		(width 0.16002)
		(layer "In4.Cu")
		(net "M_J_CPU1_SB_DQS_DP<0>")
	)
	(segment
		(start 187.055506 -284.941264)
		(end 187.535566 -284.941264)
		(width 0.16002)
		(layer "In4.Cu")
		(net "M_J_CPU1_SB_DQS_DP<0>")
	)
	(segment
		(start 152.630632 -274.89785)
		(end 155.32227 -277.589488)
		(width 0.16002)
		(layer "In4.Cu")
		(net "M_J_CPU1_SB_DQS_DP<0>")
	)
	(segment
		(start 144.314672 -276.031452)
		(end 144.32915 -276.039834)
		(width 0.09525)
		(layer "In4.Cu")
		(net "M_J_CPU1_SB_DQS_DP<0>")
	)
	(segment
		(start 155.32227 -277.589488)
		(end 156.30779 -277.589488)
		(width 0.16002)
		(layer "In4.Cu")
		(net "M_J_CPU1_SB_DQS_DP<0>")
	)
	(segment
		(start 165.683946 -285.355284)
		(end 165.987222 -285.355284)
		(width 0.16002)
		(layer "In4.Cu")
		(net "M_J_CPU1_SB_DQS_DP<0>")
	)
	(segment
		(start 144.690846 -276.031452)
		(end 144.714214 -276.01799)
		(width 0.09525)
		(layer "In4.Cu")
		(net "M_J_CPU1_SB_DQS_DP<0>")
	)
	(segment
		(start 186.341766 -284.941264)
		(end 186.458606 -284.824424)
		(width 0.16002)
		(layer "In4.Cu")
		(net "M_J_CPU1_SB_DQS_DP<0>")
	)
	(segment
		(start 173.52137 -285.345124)
		(end 174.0281 -284.838394)
		(width 0.16002)
		(layer "In4.Cu")
		(net "M_J_CPU1_SB_DQS_DP<0>")
	)
	(segment
		(start 135.856218 -276.031452)
		(end 135.8646 -276.036278)
		(width 0.09525)
		(layer "In4.Cu")
		(net "M_J_CPU1_SB_DQS_DP<0>")
	)
	(segment
		(start 174.952152 -284.838394)
		(end 175.630332 -284.160214)
		(width 0.16002)
		(layer "In4.Cu")
		(net "M_J_CPU1_SB_DQS_DP<0>")
	)
	(segment
		(start 186.458606 -284.824424)
		(end 186.938666 -284.824424)
		(width 0.16002)
		(layer "In4.Cu")
		(net "M_J_CPU1_SB_DQS_DP<0>")
	)
	(segment
		(start 147.836382 -274.957032)
		(end 147.895564 -274.89785)
		(width 0.09525)
		(layer "In4.Cu")
		(net "M_J_CPU1_SB_DQS_DP<0>")
	)
	(segment
		(start 185.497978 -284.941264)
		(end 186.341766 -284.941264)
		(width 0.16002)
		(layer "In4.Cu")
		(net "M_J_CPU1_SB_DQS_DP<0>")
	)
	(segment
		(start 140.556234 -276.031452)
		(end 140.564616 -276.036278)
		(width 0.09525)
		(layer "In4.Cu")
		(net "M_J_CPU1_SB_DQS_DP<0>")
	)
	(segment
		(start 172.417232 -285.010098)
		(end 172.752258 -285.345124)
		(width 0.16002)
		(layer "In4.Cu")
		(net "M_J_CPU1_SB_DQS_DP<0>")
	)
	(segment
		(start 189.873128 -285.159196)
		(end 190.886334 -285.159196)
		(width 0.16002)
		(layer "In4.Cu")
		(net "M_J_CPU1_SB_DQS_DP<0>")
	)
	(segment
		(start 138.10488 -276.036278)
		(end 138.113262 -276.031452)
		(width 0.09525)
		(layer "In4.Cu")
		(net "M_J_CPU1_SB_DQS_DP<0>")
	)
	(segment
		(start 174.0281 -284.838394)
		(end 174.952152 -284.838394)
		(width 0.16002)
		(layer "In4.Cu")
		(net "M_J_CPU1_SB_DQS_DP<0>")
	)
	(segment
		(start 163.336986 -284.618684)
		(end 164.947346 -284.618684)
		(width 0.16002)
		(layer "In4.Cu")
		(net "M_J_CPU1_SB_DQS_DP<0>")
	)
	(segment
		(start 181.771036 -284.778958)
		(end 182.326788 -284.778958)
		(width 0.16002)
		(layer "In4.Cu")
		(net "M_J_CPU1_SB_DQS_DP<0>")
	)
	(segment
		(start 182.326788 -284.778958)
		(end 182.945532 -284.160214)
		(width 0.16002)
		(layer "In4.Cu")
		(net "M_J_CPU1_SB_DQS_DP<0>")
	)
	(segment
		(start 144.289272 -276.01672)
		(end 144.314672 -276.031452)
		(width 0.09525)
		(layer "In4.Cu")
		(net "M_J_CPU1_SB_DQS_DP<0>")
	)
	(segment
		(start 165.987222 -285.355284)
		(end 166.772082 -284.570424)
		(width 0.16002)
		(layer "In4.Cu")
		(net "M_J_CPU1_SB_DQS_DP<0>")
	)
	(segment
		(start 181.22773 -285.322264)
		(end 181.771036 -284.778958)
		(width 0.16002)
		(layer "In4.Cu")
		(net "M_J_CPU1_SB_DQS_DP<0>")
	)
	(segment
		(start 156.30779 -277.589488)
		(end 163.336986 -284.618684)
		(width 0.16002)
		(layer "In4.Cu")
		(net "M_J_CPU1_SB_DQS_DP<0>")
	)
	(segment
		(start 177.267108 -284.160214)
		(end 178.116992 -285.010098)
		(width 0.16002)
		(layer "In4.Cu")
		(net "M_J_CPU1_SB_DQS_DP<0>")
	)
	(segment
		(start 139.044934 -276.036278)
		(end 139.053316 -276.031452)
		(width 0.09525)
		(layer "In4.Cu")
		(net "M_J_CPU1_SB_DQS_DP<0>")
	)
	(segment
		(start 134.916164 -276.031452)
		(end 134.924546 -276.036278)
		(width 0.09525)
		(layer "In4.Cu")
		(net "M_J_CPU1_SB_DQS_DP<0>")
	)
	(segment
		(start 145.60677 -276.04593)
		(end 145.63217 -276.031452)
		(width 0.09525)
		(layer "In4.Cu")
		(net "M_J_CPU1_SB_DQS_DP<0>")
	)
	(segment
		(start 180.189124 -285.010098)
		(end 180.50129 -285.322264)
		(width 0.16002)
		(layer "In4.Cu")
		(net "M_J_CPU1_SB_DQS_DP<0>")
	)
	(segment
		(start 139.61618 -276.031452)
		(end 139.624562 -276.036278)
		(width 0.09525)
		(layer "In4.Cu")
		(net "M_J_CPU1_SB_DQS_DP<0>")
	)
	(segment
		(start 169.81297 -284.570424)
		(end 170.87469 -285.010098)
		(width 0.16002)
		(layer "In4.Cu")
		(net "M_J_CPU1_SB_DQS_DP<0>")
	)
	(segment
		(start 142.804896 -276.036278)
		(end 142.813278 -276.031452)
		(width 0.09525)
		(layer "In4.Cu")
		(net "M_J_CPU1_SB_DQS_DP<0>")
	)
	(segment
		(start 189.6872 -285.345124)
		(end 189.873128 -285.159196)
		(width 0.16002)
		(layer "In4.Cu")
		(net "M_J_CPU1_SB_DQS_DP<0>")
	)
	(segment
		(start 147.919186 -274.89785)
		(end 152.630632 -274.89785)
		(width 0.16002)
		(layer "In4.Cu")
		(net "M_J_CPU1_SB_DQS_DP<0>")
	)
	(segment
		(start 187.939426 -285.345124)
		(end 189.6872 -285.345124)
		(width 0.16002)
		(layer "In4.Cu")
		(net "M_J_CPU1_SB_DQS_DP<0>")
	)
	(segment
		(start 170.87469 -285.010098)
		(end 172.417232 -285.010098)
		(width 0.16002)
		(layer "In4.Cu")
		(net "M_J_CPU1_SB_DQS_DP<0>")
	)
	(segment
		(start 147.283678 -274.997418)
		(end 147.324064 -274.957032)
		(width 0.09525)
		(layer "In4.Cu")
		(net "M_J_CPU1_SB_DQS_DP<0>")
	)
	(segment
		(start 147.895564 -274.89785)
		(end 147.919186 -274.89785)
		(width 0.09525)
		(layer "In4.Cu")
		(net "M_J_CPU1_SB_DQS_DP<0>")
	)
	(segment
		(start 133.224778 -275.706332)
		(end 133.070854 -275.971762)
		(width 0.09525)
		(layer "In4.Cu")
		(net "M_J_CPU1_SB_DQS_DP<0>")
	)
	(segment
		(start 182.945532 -284.160214)
		(end 184.716928 -284.160214)
		(width 0.16002)
		(layer "In4.Cu")
		(net "M_J_CPU1_SB_DQS_DP<0>")
	)
	(segment
		(start 146.685 -274.997418)
		(end 147.283678 -274.997418)
		(width 0.09525)
		(layer "In4.Cu")
		(net "M_J_CPU1_SB_DQS_DP<0>")
	)
	(segment
		(start 186.938666 -284.824424)
		(end 187.055506 -284.941264)
		(width 0.16002)
		(layer "In4.Cu")
		(net "M_J_CPU1_SB_DQS_DP<0>")
	)
	(segment
		(start 180.50129 -285.322264)
		(end 181.22773 -285.322264)
		(width 0.16002)
		(layer "In4.Cu")
		(net "M_J_CPU1_SB_DQS_DP<0>")
	)
	(segment
		(start 175.630332 -284.160214)
		(end 177.267108 -284.160214)
		(width 0.16002)
		(layer "In4.Cu")
		(net "M_J_CPU1_SB_DQS_DP<0>")
	)
	(segment
		(start 190.886334 -285.159196)
		(end 191.160146 -284.885384)
		(width 0.16002)
		(layer "In4.Cu")
		(net "M_J_CPU1_SB_DQS_DP<0>")
	)
	(segment
		(start 143.376142 -276.031452)
		(end 143.384524 -276.036278)
		(width 0.09525)
		(layer "In4.Cu")
		(net "M_J_CPU1_SB_DQS_DP<0>")
	)
	(segment
		(start 133.070854 -275.971762)
		(end 133.093968 -276.058376)
		(width 0.09525)
		(layer "In4.Cu")
		(net "M_J_CPU1_SB_DQS_DP<0>")
	)
	(segment
		(start 147.324064 -274.957032)
		(end 147.836382 -274.957032)
		(width 0.09525)
		(layer "In4.Cu")
		(net "M_J_CPU1_SB_DQS_DP<0>")
	)
	(segment
		(start 166.772082 -284.570424)
		(end 169.81297 -284.570424)
		(width 0.16002)
		(layer "In4.Cu")
		(net "M_J_CPU1_SB_DQS_DP<0>")
	)
	(segment
		(start 172.752258 -285.345124)
		(end 173.52137 -285.345124)
		(width 0.16002)
		(layer "In4.Cu")
		(net "M_J_CPU1_SB_DQS_DP<0>")
	)
	(segment
		(start 178.116992 -285.010098)
		(end 180.189124 -285.010098)
		(width 0.16002)
		(layer "In4.Cu")
		(net "M_J_CPU1_SB_DQS_DP<0>")
	)
	(segment
		(start 184.716928 -284.160214)
		(end 185.497978 -284.941264)
		(width 0.16002)
		(layer "In4.Cu")
		(net "M_J_CPU1_SB_DQS_DP<0>")
	)
	(arc
		(start 138.676126 -276.031452)
		(mid 138.859901 -276.082224)
		(end 139.044934 -276.036278)
		(width 0.09525)
		(layer "In4.Cu")
		(net "M_J_CPU1_SB_DQS_DP<0>")
	)
	(arc
		(start 143.384524 -276.036278)
		(mid 143.569556 -276.082192)
		(end 143.753332 -276.031452)
		(width 0.09525)
		(layer "In4.Cu")
		(net "M_J_CPU1_SB_DQS_DP<0>")
	)
	(arc
		(start 144.32915 -276.039834)
		(mid 144.511075 -276.082039)
		(end 144.690846 -276.031452)
		(width 0.09525)
		(layer "In4.Cu")
		(net "M_J_CPU1_SB_DQS_DP<0>")
	)
	(arc
		(start 133.413246 -276.031452)
		(mid 133.694678 -275.955697)
		(end 133.97611 -276.031452)
		(width 0.09525)
		(layer "In4.Cu")
		(net "M_J_CPU1_SB_DQS_DP<0>")
	)
	(arc
		(start 136.796272 -276.031452)
		(mid 136.98474 -276.082129)
		(end 137.173208 -276.031452)
		(width 0.09525)
		(layer "In4.Cu")
		(net "M_J_CPU1_SB_DQS_DP<0>")
	)
	(arc
		(start 141.496288 -276.031452)
		(mid 141.684756 -276.082129)
		(end 141.873224 -276.031452)
		(width 0.09525)
		(layer "In4.Cu")
		(net "M_J_CPU1_SB_DQS_DP<0>")
	)
	(arc
		(start 145.25498 -276.031452)
		(mid 145.429069 -276.082324)
		(end 145.60677 -276.04593)
		(width 0.09525)
		(layer "In4.Cu")
		(net "M_J_CPU1_SB_DQS_DP<0>")
	)
	(arc
		(start 140.564616 -276.036278)
		(mid 140.749648 -276.082192)
		(end 140.933424 -276.031452)
		(width 0.09525)
		(layer "In4.Cu")
		(net "M_J_CPU1_SB_DQS_DP<0>")
	)
	(arc
		(start 133.97611 -276.031452)
		(mid 134.159885 -276.082224)
		(end 134.344918 -276.036278)
		(width 0.09525)
		(layer "In4.Cu")
		(net "M_J_CPU1_SB_DQS_DP<0>")
	)
	(arc
		(start 133.093968 -276.058376)
		(mid 133.256619 -276.080636)
		(end 133.413246 -276.031452)
		(width 0.09525)
		(layer "In4.Cu")
		(net "M_J_CPU1_SB_DQS_DP<0>")
	)
	(arc
		(start 140.933424 -276.031452)
		(mid 141.214856 -275.955697)
		(end 141.496288 -276.031452)
		(width 0.09525)
		(layer "In4.Cu")
		(net "M_J_CPU1_SB_DQS_DP<0>")
	)
	(arc
		(start 138.113262 -276.031452)
		(mid 138.394694 -275.955697)
		(end 138.676126 -276.031452)
		(width 0.09525)
		(layer "In4.Cu")
		(net "M_J_CPU1_SB_DQS_DP<0>")
	)
	(arc
		(start 134.924546 -276.036278)
		(mid 135.109578 -276.082192)
		(end 135.293354 -276.031452)
		(width 0.09525)
		(layer "In4.Cu")
		(net "M_J_CPU1_SB_DQS_DP<0>")
	)
	(arc
		(start 136.233408 -276.031452)
		(mid 136.51484 -275.955697)
		(end 136.796272 -276.031452)
		(width 0.09525)
		(layer "In4.Cu")
		(net "M_J_CPU1_SB_DQS_DP<0>")
	)
	(arc
		(start 145.63217 -276.031452)
		(mid 145.663725 -276.011245)
		(end 145.69313 -275.988018)
		(width 0.09525)
		(layer "In4.Cu")
		(net "M_J_CPU1_SB_DQS_DP<0>")
	)
	(arc
		(start 139.053316 -276.031452)
		(mid 139.334748 -275.955697)
		(end 139.61618 -276.031452)
		(width 0.09525)
		(layer "In4.Cu")
		(net "M_J_CPU1_SB_DQS_DP<0>")
	)
	(arc
		(start 144.714214 -276.01799)
		(mid 144.986315 -275.955312)
		(end 145.25498 -276.031452)
		(width 0.09525)
		(layer "In4.Cu")
		(net "M_J_CPU1_SB_DQS_DP<0>")
	)
	(arc
		(start 137.736072 -276.031452)
		(mid 137.919847 -276.082224)
		(end 138.10488 -276.036278)
		(width 0.09525)
		(layer "In4.Cu")
		(net "M_J_CPU1_SB_DQS_DP<0>")
	)
	(arc
		(start 139.99337 -276.031452)
		(mid 140.274802 -275.955697)
		(end 140.556234 -276.031452)
		(width 0.09525)
		(layer "In4.Cu")
		(net "M_J_CPU1_SB_DQS_DP<0>")
	)
	(arc
		(start 145.69313 -275.988018)
		(mid 145.701891 -275.980152)
		(end 145.710402 -275.972016)
		(width 0.09525)
		(layer "In4.Cu")
		(net "M_J_CPU1_SB_DQS_DP<0>")
	)
	(arc
		(start 134.3533 -276.031452)
		(mid 134.634732 -275.955697)
		(end 134.916164 -276.031452)
		(width 0.09525)
		(layer "In4.Cu")
		(net "M_J_CPU1_SB_DQS_DP<0>")
	)
	(arc
		(start 135.293354 -276.031452)
		(mid 135.574786 -275.955697)
		(end 135.856218 -276.031452)
		(width 0.09525)
		(layer "In4.Cu")
		(net "M_J_CPU1_SB_DQS_DP<0>")
	)
	(arc
		(start 142.436088 -276.031452)
		(mid 142.619863 -276.082224)
		(end 142.804896 -276.036278)
		(width 0.09525)
		(layer "In4.Cu")
		(net "M_J_CPU1_SB_DQS_DP<0>")
	)
	(arc
		(start 143.753332 -276.031452)
		(mid 144.019419 -275.955907)
		(end 144.289272 -276.01672)
		(width 0.09525)
		(layer "In4.Cu")
		(net "M_J_CPU1_SB_DQS_DP<0>")
	)
	(arc
		(start 142.813278 -276.031452)
		(mid 143.09471 -275.955697)
		(end 143.376142 -276.031452)
		(width 0.09525)
		(layer "In4.Cu")
		(net "M_J_CPU1_SB_DQS_DP<0>")
	)
	(arc
		(start 141.873224 -276.031452)
		(mid 142.154656 -275.955697)
		(end 142.436088 -276.031452)
		(width 0.09525)
		(layer "In4.Cu")
		(net "M_J_CPU1_SB_DQS_DP<0>")
	)
	(arc
		(start 135.8646 -276.036278)
		(mid 136.049632 -276.082192)
		(end 136.233408 -276.031452)
		(width 0.09525)
		(layer "In4.Cu")
		(net "M_J_CPU1_SB_DQS_DP<0>")
	)
	(arc
		(start 139.624562 -276.036278)
		(mid 139.809594 -276.082192)
		(end 139.99337 -276.031452)
		(width 0.09525)
		(layer "In4.Cu")
		(net "M_J_CPU1_SB_DQS_DP<0>")
	)
	(arc
		(start 137.173208 -276.031452)
		(mid 137.45464 -275.955697)
		(end 137.736072 -276.031452)
		(width 0.09525)
		(layer "In4.Cu")
		(net "M_J_CPU1_SB_DQS_DP<0>")
	)
	(segment
		(start 132.287772 -271.390364)
		(end 132.754878 -271.656302)
		(width 0.12954)
		(layer "F.Cu")
		(net "M_J_CPU1_SB_DQS_DN<9>")
	)
	(segment
		(start 138.206226 -271.331182)
		(end 138.214608 -271.326356)
		(width 0.09525)
		(layer "In4.Cu")
		(net "M_J_CPU1_SB_DQS_DN<9>")
	)
	(segment
		(start 180.376068 -276.27453)
		(end 181.352952 -276.27453)
		(width 0.16002)
		(layer "In4.Cu")
		(net "M_J_CPU1_SB_DQS_DN<9>")
	)
	(segment
		(start 183.070754 -275.11248)
		(end 184.591706 -275.11248)
		(width 0.16002)
		(layer "In4.Cu")
		(net "M_J_CPU1_SB_DQS_DN<9>")
	)
	(segment
		(start 144.205706 -271.32153)
		(end 144.213072 -271.32534)
		(width 0.09525)
		(layer "In4.Cu")
		(net "M_J_CPU1_SB_DQS_DN<9>")
	)
	(segment
		(start 140.454888 -271.326356)
		(end 140.46327 -271.331182)
		(width 0.09525)
		(layer "In4.Cu")
		(net "M_J_CPU1_SB_DQS_DN<9>")
	)
	(segment
		(start 181.352952 -276.27453)
		(end 181.896258 -275.731224)
		(width 0.16002)
		(layer "In4.Cu")
		(net "M_J_CPU1_SB_DQS_DN<9>")
	)
	(segment
		(start 169.945304 -275.52269)
		(end 170.384978 -275.962364)
		(width 0.16002)
		(layer "In4.Cu")
		(net "M_J_CPU1_SB_DQS_DN<9>")
	)
	(segment
		(start 133.50621 -271.331182)
		(end 133.514592 -271.326356)
		(width 0.09525)
		(layer "In4.Cu")
		(net "M_J_CPU1_SB_DQS_DN<9>")
	)
	(segment
		(start 145.25625 -270.521176)
		(end 145.25625 -270.520668)
		(width 0.09525)
		(layer "In4.Cu")
		(net "M_J_CPU1_SB_DQS_DN<9>")
	)
	(segment
		(start 187.410344 -275.89353)
		(end 187.814204 -276.29739)
		(width 0.16002)
		(layer "In4.Cu")
		(net "M_J_CPU1_SB_DQS_DN<9>")
	)
	(segment
		(start 166.630096 -275.52269)
		(end 169.945304 -275.52269)
		(width 0.16002)
		(layer "In4.Cu")
		(net "M_J_CPU1_SB_DQS_DN<9>")
	)
	(segment
		(start 177.99177 -275.962364)
		(end 180.063902 -275.962364)
		(width 0.16002)
		(layer "In4.Cu")
		(net "M_J_CPU1_SB_DQS_DN<9>")
	)
	(segment
		(start 175.077374 -275.79066)
		(end 175.755554 -275.11248)
		(width 0.16002)
		(layer "In4.Cu")
		(net "M_J_CPU1_SB_DQS_DN<9>")
	)
	(segment
		(start 170.384978 -275.962364)
		(end 172.29201 -275.962364)
		(width 0.16002)
		(layer "In4.Cu")
		(net "M_J_CPU1_SB_DQS_DN<9>")
	)
	(segment
		(start 177.141886 -275.11248)
		(end 177.99177 -275.962364)
		(width 0.16002)
		(layer "In4.Cu")
		(net "M_J_CPU1_SB_DQS_DN<9>")
	)
	(segment
		(start 147.919186 -269.555214)
		(end 157.134814 -269.555214)
		(width 0.16002)
		(layer "In4.Cu")
		(net "M_J_CPU1_SB_DQS_DN<9>")
	)
	(segment
		(start 132.908802 -271.390872)
		(end 133.00964 -271.364202)
		(width 0.09525)
		(layer "In4.Cu")
		(net "M_J_CPU1_SB_DQS_DN<9>")
	)
	(segment
		(start 172.627036 -276.29739)
		(end 173.646592 -276.29739)
		(width 0.16002)
		(layer "In4.Cu")
		(net "M_J_CPU1_SB_DQS_DN<9>")
	)
	(segment
		(start 184.591706 -275.11248)
		(end 185.372756 -275.89353)
		(width 0.16002)
		(layer "In4.Cu")
		(net "M_J_CPU1_SB_DQS_DN<9>")
	)
	(segment
		(start 157.134814 -269.555214)
		(end 159.731202 -272.151602)
		(width 0.16002)
		(layer "In4.Cu")
		(net "M_J_CPU1_SB_DQS_DN<9>")
	)
	(segment
		(start 163.899596 -275.11248)
		(end 166.219886 -275.11248)
		(width 0.16002)
		(layer "In4.Cu")
		(net "M_J_CPU1_SB_DQS_DN<9>")
	)
	(segment
		(start 175.755554 -275.11248)
		(end 177.141886 -275.11248)
		(width 0.16002)
		(layer "In4.Cu")
		(net "M_J_CPU1_SB_DQS_DN<9>")
	)
	(segment
		(start 174.153322 -275.79066)
		(end 175.077374 -275.79066)
		(width 0.16002)
		(layer "In4.Cu")
		(net "M_J_CPU1_SB_DQS_DN<9>")
	)
	(segment
		(start 145.223738 -270.539972)
		(end 145.25625 -270.521176)
		(width 0.09525)
		(layer "In4.Cu")
		(net "M_J_CPU1_SB_DQS_DN<9>")
	)
	(segment
		(start 132.754878 -271.656302)
		(end 132.908802 -271.390872)
		(width 0.09525)
		(layer "In4.Cu")
		(net "M_J_CPU1_SB_DQS_DN<9>")
	)
	(segment
		(start 159.731202 -272.151602)
		(end 160.938718 -272.151602)
		(width 0.16002)
		(layer "In4.Cu")
		(net "M_J_CPU1_SB_DQS_DN<9>")
	)
	(segment
		(start 141.394942 -271.326356)
		(end 141.403324 -271.331182)
		(width 0.09525)
		(layer "In4.Cu")
		(net "M_J_CPU1_SB_DQS_DN<9>")
	)
	(segment
		(start 135.754872 -271.326356)
		(end 135.763254 -271.331182)
		(width 0.09525)
		(layer "In4.Cu")
		(net "M_J_CPU1_SB_DQS_DN<9>")
	)
	(segment
		(start 189.99835 -276.111462)
		(end 190.886334 -276.111462)
		(width 0.16002)
		(layer "In4.Cu")
		(net "M_J_CPU1_SB_DQS_DN<9>")
	)
	(segment
		(start 146.691604 -269.357094)
		(end 147.204684 -269.357094)
		(width 0.09525)
		(layer "In4.Cu")
		(net "M_J_CPU1_SB_DQS_DN<9>")
	)
	(segment
		(start 147.895564 -269.555214)
		(end 147.919186 -269.555214)
		(width 0.09525)
		(layer "In4.Cu")
		(net "M_J_CPU1_SB_DQS_DN<9>")
	)
	(segment
		(start 180.063902 -275.962364)
		(end 180.376068 -276.27453)
		(width 0.16002)
		(layer "In4.Cu")
		(net "M_J_CPU1_SB_DQS_DN<9>")
	)
	(segment
		(start 147.343876 -269.496286)
		(end 147.836636 -269.496286)
		(width 0.09525)
		(layer "In4.Cu")
		(net "M_J_CPU1_SB_DQS_DN<9>")
	)
	(segment
		(start 187.814204 -276.29739)
		(end 189.812422 -276.29739)
		(width 0.16002)
		(layer "In4.Cu")
		(net "M_J_CPU1_SB_DQS_DN<9>")
	)
	(segment
		(start 189.812422 -276.29739)
		(end 189.99835 -276.111462)
		(width 0.16002)
		(layer "In4.Cu")
		(net "M_J_CPU1_SB_DQS_DN<9>")
	)
	(segment
		(start 145.79981 -270.249142)
		(end 146.691604 -269.357094)
		(width 0.09525)
		(layer "In4.Cu")
		(net "M_J_CPU1_SB_DQS_DN<9>")
	)
	(segment
		(start 172.29201 -275.962364)
		(end 172.627036 -276.29739)
		(width 0.16002)
		(layer "In4.Cu")
		(net "M_J_CPU1_SB_DQS_DN<9>")
	)
	(segment
		(start 144.213072 -271.32534)
		(end 144.223232 -271.331182)
		(width 0.09525)
		(layer "In4.Cu")
		(net "M_J_CPU1_SB_DQS_DN<9>")
	)
	(segment
		(start 136.694926 -271.326356)
		(end 136.703308 -271.331182)
		(width 0.09525)
		(layer "In4.Cu")
		(net "M_J_CPU1_SB_DQS_DN<9>")
	)
	(segment
		(start 160.938718 -272.151602)
		(end 163.899596 -275.11248)
		(width 0.16002)
		(layer "In4.Cu")
		(net "M_J_CPU1_SB_DQS_DN<9>")
	)
	(segment
		(start 147.204684 -269.357094)
		(end 147.343876 -269.496286)
		(width 0.09525)
		(layer "In4.Cu")
		(net "M_J_CPU1_SB_DQS_DN<9>")
	)
	(segment
		(start 147.836636 -269.496286)
		(end 147.895564 -269.555214)
		(width 0.09525)
		(layer "In4.Cu")
		(net "M_J_CPU1_SB_DQS_DN<9>")
	)
	(segment
		(start 190.886334 -276.111462)
		(end 191.160146 -276.385274)
		(width 0.16002)
		(layer "In4.Cu")
		(net "M_J_CPU1_SB_DQS_DN<9>")
	)
	(segment
		(start 181.896258 -275.731224)
		(end 182.45201 -275.731224)
		(width 0.16002)
		(layer "In4.Cu")
		(net "M_J_CPU1_SB_DQS_DN<9>")
	)
	(segment
		(start 144.786096 -271.331182)
		(end 144.824196 -271.309084)
		(width 0.09525)
		(layer "In4.Cu")
		(net "M_J_CPU1_SB_DQS_DN<9>")
	)
	(segment
		(start 166.219886 -275.11248)
		(end 166.630096 -275.52269)
		(width 0.16002)
		(layer "In4.Cu")
		(net "M_J_CPU1_SB_DQS_DN<9>")
	)
	(segment
		(start 173.646592 -276.29739)
		(end 174.153322 -275.79066)
		(width 0.16002)
		(layer "In4.Cu")
		(net "M_J_CPU1_SB_DQS_DN<9>")
	)
	(segment
		(start 137.266172 -271.331182)
		(end 137.274554 -271.326356)
		(width 0.09525)
		(layer "In4.Cu")
		(net "M_J_CPU1_SB_DQS_DN<9>")
	)
	(segment
		(start 182.45201 -275.731224)
		(end 183.070754 -275.11248)
		(width 0.16002)
		(layer "In4.Cu")
		(net "M_J_CPU1_SB_DQS_DN<9>")
	)
	(segment
		(start 185.372756 -275.89353)
		(end 187.410344 -275.89353)
		(width 0.16002)
		(layer "In4.Cu")
		(net "M_J_CPU1_SB_DQS_DN<9>")
	)
	(segment
		(start 141.966188 -271.331182)
		(end 141.97457 -271.326356)
		(width 0.09525)
		(layer "In4.Cu")
		(net "M_J_CPU1_SB_DQS_DN<9>")
	)
	(arc
		(start 145.384266 -270.474694)
		(mid 145.611221 -270.397264)
		(end 145.79981 -270.249142)
		(width 0.09525)
		(layer "In4.Cu")
		(net "M_J_CPU1_SB_DQS_DN<9>")
	)
	(arc
		(start 144.223232 -271.331182)
		(mid 144.504664 -271.406937)
		(end 144.786096 -271.331182)
		(width 0.09525)
		(layer "In4.Cu")
		(net "M_J_CPU1_SB_DQS_DN<9>")
	)
	(arc
		(start 133.514592 -271.326356)
		(mid 133.699624 -271.280442)
		(end 133.8834 -271.331182)
		(width 0.09525)
		(layer "In4.Cu")
		(net "M_J_CPU1_SB_DQS_DN<9>")
	)
	(arc
		(start 136.703308 -271.331182)
		(mid 136.98474 -271.406937)
		(end 137.266172 -271.331182)
		(width 0.09525)
		(layer "In4.Cu")
		(net "M_J_CPU1_SB_DQS_DN<9>")
	)
	(arc
		(start 133.00964 -271.364202)
		(mid 133.019508 -271.368233)
		(end 133.029452 -271.372076)
		(width 0.09525)
		(layer "In4.Cu")
		(net "M_J_CPU1_SB_DQS_DN<9>")
	)
	(arc
		(start 144.824196 -271.309084)
		(mid 145.002646 -271.107614)
		(end 145.06702 -270.846296)
		(width 0.09525)
		(layer "In4.Cu")
		(net "M_J_CPU1_SB_DQS_DN<9>")
	)
	(arc
		(start 143.846042 -271.331182)
		(mid 144.024648 -271.280514)
		(end 144.205706 -271.32153)
		(width 0.09525)
		(layer "In4.Cu")
		(net "M_J_CPU1_SB_DQS_DN<9>")
	)
	(arc
		(start 139.14628 -271.331182)
		(mid 139.334748 -271.280505)
		(end 139.523216 -271.331182)
		(width 0.09525)
		(layer "In4.Cu")
		(net "M_J_CPU1_SB_DQS_DN<9>")
	)
	(arc
		(start 138.583416 -271.331182)
		(mid 138.864848 -271.406937)
		(end 139.14628 -271.331182)
		(width 0.09525)
		(layer "In4.Cu")
		(net "M_J_CPU1_SB_DQS_DN<9>")
	)
	(arc
		(start 140.46327 -271.331182)
		(mid 140.744702 -271.406937)
		(end 141.026134 -271.331182)
		(width 0.09525)
		(layer "In4.Cu")
		(net "M_J_CPU1_SB_DQS_DN<9>")
	)
	(arc
		(start 135.763254 -271.331182)
		(mid 136.044686 -271.406937)
		(end 136.326118 -271.331182)
		(width 0.09525)
		(layer "In4.Cu")
		(net "M_J_CPU1_SB_DQS_DN<9>")
	)
	(arc
		(start 142.906242 -271.331182)
		(mid 143.09471 -271.280505)
		(end 143.283178 -271.331182)
		(width 0.09525)
		(layer "In4.Cu")
		(net "M_J_CPU1_SB_DQS_DN<9>")
	)
	(arc
		(start 141.403324 -271.331182)
		(mid 141.684756 -271.406937)
		(end 141.966188 -271.331182)
		(width 0.09525)
		(layer "In4.Cu")
		(net "M_J_CPU1_SB_DQS_DN<9>")
	)
	(arc
		(start 134.8232 -271.331182)
		(mid 135.104632 -271.406937)
		(end 135.386064 -271.331182)
		(width 0.09525)
		(layer "In4.Cu")
		(net "M_J_CPU1_SB_DQS_DN<9>")
	)
	(arc
		(start 137.643362 -271.331182)
		(mid 137.924794 -271.406937)
		(end 138.206226 -271.331182)
		(width 0.09525)
		(layer "In4.Cu")
		(net "M_J_CPU1_SB_DQS_DN<9>")
	)
	(arc
		(start 138.214608 -271.326356)
		(mid 138.39964 -271.280442)
		(end 138.583416 -271.331182)
		(width 0.09525)
		(layer "In4.Cu")
		(net "M_J_CPU1_SB_DQS_DN<9>")
	)
	(arc
		(start 142.343378 -271.331182)
		(mid 142.62481 -271.406937)
		(end 142.906242 -271.331182)
		(width 0.09525)
		(layer "In4.Cu")
		(net "M_J_CPU1_SB_DQS_DN<9>")
	)
	(arc
		(start 137.274554 -271.326356)
		(mid 137.459586 -271.280442)
		(end 137.643362 -271.331182)
		(width 0.09525)
		(layer "In4.Cu")
		(net "M_J_CPU1_SB_DQS_DN<9>")
	)
	(arc
		(start 140.08608 -271.331182)
		(mid 140.269855 -271.28041)
		(end 140.454888 -271.326356)
		(width 0.09525)
		(layer "In4.Cu")
		(net "M_J_CPU1_SB_DQS_DN<9>")
	)
	(arc
		(start 133.029452 -271.372076)
		(mid 133.272416 -271.405063)
		(end 133.50621 -271.331182)
		(width 0.09525)
		(layer "In4.Cu")
		(net "M_J_CPU1_SB_DQS_DN<9>")
	)
	(arc
		(start 136.326118 -271.331182)
		(mid 136.509893 -271.28041)
		(end 136.694926 -271.326356)
		(width 0.09525)
		(layer "In4.Cu")
		(net "M_J_CPU1_SB_DQS_DN<9>")
	)
	(arc
		(start 134.446264 -271.331182)
		(mid 134.634732 -271.280505)
		(end 134.8232 -271.331182)
		(width 0.09525)
		(layer "In4.Cu")
		(net "M_J_CPU1_SB_DQS_DN<9>")
	)
	(arc
		(start 141.026134 -271.331182)
		(mid 141.209909 -271.28041)
		(end 141.394942 -271.326356)
		(width 0.09525)
		(layer "In4.Cu")
		(net "M_J_CPU1_SB_DQS_DN<9>")
	)
	(arc
		(start 141.97457 -271.326356)
		(mid 142.159602 -271.280442)
		(end 142.343378 -271.331182)
		(width 0.09525)
		(layer "In4.Cu")
		(net "M_J_CPU1_SB_DQS_DN<9>")
	)
	(arc
		(start 145.06702 -270.846296)
		(mid 145.108477 -270.674256)
		(end 145.223738 -270.539972)
		(width 0.09525)
		(layer "In4.Cu")
		(net "M_J_CPU1_SB_DQS_DN<9>")
	)
	(arc
		(start 133.8834 -271.331182)
		(mid 134.164832 -271.406937)
		(end 134.446264 -271.331182)
		(width 0.09525)
		(layer "In4.Cu")
		(net "M_J_CPU1_SB_DQS_DN<9>")
	)
	(arc
		(start 145.25625 -270.520668)
		(mid 145.318159 -270.491831)
		(end 145.384266 -270.474694)
		(width 0.09525)
		(layer "In4.Cu")
		(net "M_J_CPU1_SB_DQS_DN<9>")
	)
	(arc
		(start 135.386064 -271.331182)
		(mid 135.569839 -271.28041)
		(end 135.754872 -271.326356)
		(width 0.09525)
		(layer "In4.Cu")
		(net "M_J_CPU1_SB_DQS_DN<9>")
	)
	(arc
		(start 139.523216 -271.331182)
		(mid 139.804648 -271.406937)
		(end 140.08608 -271.331182)
		(width 0.09525)
		(layer "In4.Cu")
		(net "M_J_CPU1_SB_DQS_DN<9>")
	)
	(arc
		(start 143.283178 -271.331182)
		(mid 143.56461 -271.406937)
		(end 143.846042 -271.331182)
		(width 0.09525)
		(layer "In4.Cu")
		(net "M_J_CPU1_SB_DQS_DN<9>")
	)
	(segment
		(start 131.347972 -290.830254)
		(end 131.814824 -291.096192)
		(width 0.12954)
		(layer "F.Cu")
		(net "M_J_CPU1_SB_DQS_DN<8>")
	)
	(segment
		(start 146.476466 -294.336216)
		(end 146.476466 -294.484044)
		(width 0.09525)
		(layer "In4.Cu")
		(net "M_J_CPU1_SB_DQS_DN<8>")
	)
	(segment
		(start 160.856168 -314.89015)
		(end 161.082736 -314.89015)
		(width 0.16002)
		(layer "In4.Cu")
		(net "M_J_CPU1_SB_DQS_DN<8>")
	)
	(segment
		(start 131.814824 -291.096192)
		(end 131.6609 -291.361622)
		(width 0.09525)
		(layer "In4.Cu")
		(net "M_J_CPU1_SB_DQS_DN<8>")
	)
	(segment
		(start 161.252154 -314.319158)
		(end 161.625026 -313.946286)
		(width 0.16002)
		(layer "In4.Cu")
		(net "M_J_CPU1_SB_DQS_DN<8>")
	)
	(segment
		(start 146.476466 -294.484044)
		(end 146.988022 -294.994838)
		(width 0.09525)
		(layer "In4.Cu")
		(net "M_J_CPU1_SB_DQS_DN<8>")
	)
	(segment
		(start 169.844212 -313.842146)
		(end 171.060364 -315.058298)
		(width 0.16002)
		(layer "In4.Cu")
		(net "M_J_CPU1_SB_DQS_DN<8>")
	)
	(segment
		(start 185.709306 -313.942222)
		(end 186.189366 -313.942222)
		(width 0.16002)
		(layer "In4.Cu")
		(net "M_J_CPU1_SB_DQS_DN<8>")
	)
	(segment
		(start 162.524948 -314.319158)
		(end 162.524948 -314.720732)
		(width 0.16002)
		(layer "In4.Cu")
		(net "M_J_CPU1_SB_DQS_DN<8>")
	)
	(segment
		(start 162.524948 -314.720732)
		(end 162.720782 -314.916566)
		(width 0.16002)
		(layer "In4.Cu")
		(net "M_J_CPU1_SB_DQS_DN<8>")
	)
	(segment
		(start 178.8033 -315.058298)
		(end 180.102256 -315.058298)
		(width 0.16002)
		(layer "In4.Cu")
		(net "M_J_CPU1_SB_DQS_DN<8>")
	)
	(segment
		(start 174.342298 -313.840876)
		(end 175.122586 -313.840876)
		(width 0.16002)
		(layer "In4.Cu")
		(net "M_J_CPU1_SB_DQS_DN<8>")
	)
	(segment
		(start 146.166332 -293.834058)
		(end 146.167348 -293.834566)
		(width 0.09525)
		(layer "In4.Cu")
		(net "M_J_CPU1_SB_DQS_DN<8>")
	)
	(segment
		(start 137.266172 -291.421312)
		(end 137.274554 -291.426138)
		(width 0.09525)
		(layer "In4.Cu")
		(net "M_J_CPU1_SB_DQS_DN<8>")
	)
	(segment
		(start 176.592992 -314.439046)
		(end 177.212244 -315.058298)
		(width 0.16002)
		(layer "In4.Cu")
		(net "M_J_CPU1_SB_DQS_DN<8>")
	)
	(segment
		(start 172.551852 -315.058298)
		(end 172.894244 -314.715906)
		(width 0.16002)
		(layer "In4.Cu")
		(net "M_J_CPU1_SB_DQS_DN<8>")
	)
	(segment
		(start 144.21485 -291.426138)
		(end 144.223232 -291.421312)
		(width 0.09525)
		(layer "In4.Cu")
		(net "M_J_CPU1_SB_DQS_DN<8>")
	)
	(segment
		(start 133.50621 -291.421312)
		(end 133.514592 -291.426138)
		(width 0.09525)
		(layer "In4.Cu")
		(net "M_J_CPU1_SB_DQS_DN<8>")
	)
	(segment
		(start 163.193222 -314.319158)
		(end 163.566094 -313.946286)
		(width 0.16002)
		(layer "In4.Cu")
		(net "M_J_CPU1_SB_DQS_DN<8>")
	)
	(segment
		(start 146.18081 -293.84244)
		(end 146.234658 -293.874444)
		(width 0.09525)
		(layer "In4.Cu")
		(net "M_J_CPU1_SB_DQS_DN<8>")
	)
	(segment
		(start 186.786266 -314.059062)
		(end 187.060078 -313.78525)
		(width 0.16002)
		(layer "In4.Cu")
		(net "M_J_CPU1_SB_DQS_DN<8>")
	)
	(segment
		(start 131.6609 -291.361622)
		(end 131.684268 -291.44849)
		(width 0.09525)
		(layer "In4.Cu")
		(net "M_J_CPU1_SB_DQS_DN<8>")
	)
	(segment
		(start 184.728612 -314.059062)
		(end 185.592466 -314.059062)
		(width 0.16002)
		(layer "In4.Cu")
		(net "M_J_CPU1_SB_DQS_DN<8>")
	)
	(segment
		(start 164.466016 -314.720732)
		(end 164.66185 -314.916566)
		(width 0.16002)
		(layer "In4.Cu")
		(net "M_J_CPU1_SB_DQS_DN<8>")
	)
	(segment
		(start 186.306206 -314.059062)
		(end 186.786266 -314.059062)
		(width 0.16002)
		(layer "In4.Cu")
		(net "M_J_CPU1_SB_DQS_DN<8>")
	)
	(segment
		(start 172.894244 -314.715906)
		(end 173.467268 -314.715906)
		(width 0.16002)
		(layer "In4.Cu")
		(net "M_J_CPU1_SB_DQS_DN<8>")
	)
	(segment
		(start 163.566094 -313.946286)
		(end 164.093144 -313.946286)
		(width 0.16002)
		(layer "In4.Cu")
		(net "M_J_CPU1_SB_DQS_DN<8>")
	)
	(segment
		(start 178.2064 -314.941458)
		(end 178.68646 -314.941458)
		(width 0.16002)
		(layer "In4.Cu")
		(net "M_J_CPU1_SB_DQS_DN<8>")
	)
	(segment
		(start 175.720756 -314.439046)
		(end 176.592992 -314.439046)
		(width 0.16002)
		(layer "In4.Cu")
		(net "M_J_CPU1_SB_DQS_DN<8>")
	)
	(segment
		(start 178.08956 -315.058298)
		(end 178.2064 -314.941458)
		(width 0.16002)
		(layer "In4.Cu")
		(net "M_J_CPU1_SB_DQS_DN<8>")
	)
	(segment
		(start 146.164554 -293.833042)
		(end 146.164808 -293.833042)
		(width 0.09525)
		(layer "In4.Cu")
		(net "M_J_CPU1_SB_DQS_DN<8>")
	)
	(segment
		(start 147.36445 -295.28643)
		(end 147.36445 -301.398432)
		(width 0.16002)
		(layer "In4.Cu")
		(net "M_J_CPU1_SB_DQS_DN<8>")
	)
	(segment
		(start 163.193222 -314.720732)
		(end 163.193222 -314.319158)
		(width 0.16002)
		(layer "In4.Cu")
		(net "M_J_CPU1_SB_DQS_DN<8>")
	)
	(segment
		(start 161.082736 -314.89015)
		(end 161.252154 -314.720732)
		(width 0.16002)
		(layer "In4.Cu")
		(net "M_J_CPU1_SB_DQS_DN<8>")
	)
	(segment
		(start 146.167348 -293.834566)
		(end 146.168872 -293.835582)
		(width 0.09525)
		(layer "In4.Cu")
		(net "M_J_CPU1_SB_DQS_DN<8>")
	)
	(segment
		(start 180.102256 -315.058298)
		(end 180.444648 -314.715906)
		(width 0.16002)
		(layer "In4.Cu")
		(net "M_J_CPU1_SB_DQS_DN<8>")
	)
	(segment
		(start 136.694926 -291.426138)
		(end 136.703308 -291.421312)
		(width 0.09525)
		(layer "In4.Cu")
		(net "M_J_CPU1_SB_DQS_DN<8>")
	)
	(segment
		(start 144.786096 -291.421312)
		(end 144.824196 -291.44341)
		(width 0.09525)
		(layer "In4.Cu")
		(net "M_J_CPU1_SB_DQS_DN<8>")
	)
	(segment
		(start 132.934964 -291.426138)
		(end 132.943346 -291.421312)
		(width 0.09525)
		(layer "In4.Cu")
		(net "M_J_CPU1_SB_DQS_DN<8>")
	)
	(segment
		(start 164.66185 -314.916566)
		(end 165.250368 -314.916566)
		(width 0.16002)
		(layer "In4.Cu")
		(net "M_J_CPU1_SB_DQS_DN<8>")
	)
	(segment
		(start 164.466016 -314.319158)
		(end 164.466016 -314.720732)
		(width 0.16002)
		(layer "In4.Cu")
		(net "M_J_CPU1_SB_DQS_DN<8>")
	)
	(segment
		(start 182.666132 -313.867546)
		(end 183.042052 -314.243466)
		(width 0.16002)
		(layer "In4.Cu")
		(net "M_J_CPU1_SB_DQS_DN<8>")
	)
	(segment
		(start 177.212244 -315.058298)
		(end 178.08956 -315.058298)
		(width 0.16002)
		(layer "In4.Cu")
		(net "M_J_CPU1_SB_DQS_DN<8>")
	)
	(segment
		(start 180.444648 -314.715906)
		(end 181.122828 -314.715906)
		(width 0.16002)
		(layer "In4.Cu")
		(net "M_J_CPU1_SB_DQS_DN<8>")
	)
	(segment
		(start 141.966188 -291.421312)
		(end 141.97457 -291.426138)
		(width 0.09525)
		(layer "In4.Cu")
		(net "M_J_CPU1_SB_DQS_DN<8>")
	)
	(segment
		(start 165.250368 -314.916566)
		(end 165.471348 -314.695586)
		(width 0.16002)
		(layer "In4.Cu")
		(net "M_J_CPU1_SB_DQS_DN<8>")
	)
	(segment
		(start 146.164808 -293.833042)
		(end 146.166332 -293.834058)
		(width 0.09525)
		(layer "In4.Cu")
		(net "M_J_CPU1_SB_DQS_DN<8>")
	)
	(segment
		(start 183.042052 -314.243466)
		(end 184.544208 -314.243466)
		(width 0.16002)
		(layer "In4.Cu")
		(net "M_J_CPU1_SB_DQS_DN<8>")
	)
	(segment
		(start 178.68646 -314.941458)
		(end 178.8033 -315.058298)
		(width 0.16002)
		(layer "In4.Cu")
		(net "M_J_CPU1_SB_DQS_DN<8>")
	)
	(segment
		(start 161.252154 -314.720732)
		(end 161.252154 -314.319158)
		(width 0.16002)
		(layer "In4.Cu")
		(net "M_J_CPU1_SB_DQS_DN<8>")
	)
	(segment
		(start 181.971188 -313.867546)
		(end 182.666132 -313.867546)
		(width 0.16002)
		(layer "In4.Cu")
		(net "M_J_CPU1_SB_DQS_DN<8>")
	)
	(segment
		(start 166.789608 -313.842146)
		(end 169.844212 -313.842146)
		(width 0.16002)
		(layer "In4.Cu")
		(net "M_J_CPU1_SB_DQS_DN<8>")
	)
	(segment
		(start 165.471348 -314.695586)
		(end 165.936168 -314.695586)
		(width 0.16002)
		(layer "In4.Cu")
		(net "M_J_CPU1_SB_DQS_DN<8>")
	)
	(segment
		(start 186.189366 -313.942222)
		(end 186.306206 -314.059062)
		(width 0.16002)
		(layer "In4.Cu")
		(net "M_J_CPU1_SB_DQS_DN<8>")
	)
	(segment
		(start 185.592466 -314.059062)
		(end 185.709306 -313.942222)
		(width 0.16002)
		(layer "In4.Cu")
		(net "M_J_CPU1_SB_DQS_DN<8>")
	)
	(segment
		(start 162.152076 -313.946286)
		(end 162.524948 -314.319158)
		(width 0.16002)
		(layer "In4.Cu")
		(net "M_J_CPU1_SB_DQS_DN<8>")
	)
	(segment
		(start 146.168872 -293.835582)
		(end 146.18081 -293.84244)
		(width 0.09525)
		(layer "In4.Cu")
		(net "M_J_CPU1_SB_DQS_DN<8>")
	)
	(segment
		(start 162.720782 -314.916566)
		(end 162.997388 -314.916566)
		(width 0.16002)
		(layer "In4.Cu")
		(net "M_J_CPU1_SB_DQS_DN<8>")
	)
	(segment
		(start 181.122828 -314.715906)
		(end 181.971188 -313.867546)
		(width 0.16002)
		(layer "In4.Cu")
		(net "M_J_CPU1_SB_DQS_DN<8>")
	)
	(segment
		(start 138.206226 -291.421312)
		(end 138.214608 -291.426138)
		(width 0.09525)
		(layer "In4.Cu")
		(net "M_J_CPU1_SB_DQS_DN<8>")
	)
	(segment
		(start 184.544208 -314.243466)
		(end 184.728612 -314.059062)
		(width 0.16002)
		(layer "In4.Cu")
		(net "M_J_CPU1_SB_DQS_DN<8>")
	)
	(segment
		(start 146.988022 -294.994838)
		(end 147.071334 -294.99433)
		(width 0.09525)
		(layer "In4.Cu")
		(net "M_J_CPU1_SB_DQS_DN<8>")
	)
	(segment
		(start 141.394942 -291.426138)
		(end 141.403324 -291.421312)
		(width 0.09525)
		(layer "In4.Cu")
		(net "M_J_CPU1_SB_DQS_DN<8>")
	)
	(segment
		(start 162.997388 -314.916566)
		(end 163.193222 -314.720732)
		(width 0.16002)
		(layer "In4.Cu")
		(net "M_J_CPU1_SB_DQS_DN<8>")
	)
	(segment
		(start 175.122586 -313.840876)
		(end 175.720756 -314.439046)
		(width 0.16002)
		(layer "In4.Cu")
		(net "M_J_CPU1_SB_DQS_DN<8>")
	)
	(segment
		(start 165.936168 -314.695586)
		(end 166.789608 -313.842146)
		(width 0.16002)
		(layer "In4.Cu")
		(net "M_J_CPU1_SB_DQS_DN<8>")
	)
	(segment
		(start 147.088098 -295.011094)
		(end 147.36445 -295.28643)
		(width 0.16002)
		(layer "In4.Cu")
		(net "M_J_CPU1_SB_DQS_DN<8>")
	)
	(segment
		(start 161.625026 -313.946286)
		(end 162.152076 -313.946286)
		(width 0.16002)
		(layer "In4.Cu")
		(net "M_J_CPU1_SB_DQS_DN<8>")
	)
	(segment
		(start 147.071334 -294.99433)
		(end 147.088098 -295.011094)
		(width 0.09525)
		(layer "In4.Cu")
		(net "M_J_CPU1_SB_DQS_DN<8>")
	)
	(segment
		(start 164.093144 -313.946286)
		(end 164.466016 -314.319158)
		(width 0.16002)
		(layer "In4.Cu")
		(net "M_J_CPU1_SB_DQS_DN<8>")
	)
	(segment
		(start 135.754872 -291.426138)
		(end 135.763254 -291.421312)
		(width 0.09525)
		(layer "In4.Cu")
		(net "M_J_CPU1_SB_DQS_DN<8>")
	)
	(segment
		(start 145.190464 -292.20414)
		(end 145.73377 -292.747446)
		(width 0.09525)
		(layer "In4.Cu")
		(net "M_J_CPU1_SB_DQS_DN<8>")
	)
	(segment
		(start 173.467268 -314.715906)
		(end 174.342298 -313.840876)
		(width 0.16002)
		(layer "In4.Cu")
		(net "M_J_CPU1_SB_DQS_DN<8>")
	)
	(segment
		(start 131.99491 -291.426138)
		(end 132.003292 -291.421312)
		(width 0.09525)
		(layer "In4.Cu")
		(net "M_J_CPU1_SB_DQS_DN<8>")
	)
	(segment
		(start 147.36445 -301.398432)
		(end 160.856168 -314.89015)
		(width 0.16002)
		(layer "In4.Cu")
		(net "M_J_CPU1_SB_DQS_DN<8>")
	)
	(segment
		(start 171.060364 -315.058298)
		(end 172.551852 -315.058298)
		(width 0.16002)
		(layer "In4.Cu")
		(net "M_J_CPU1_SB_DQS_DN<8>")
	)
	(segment
		(start 146.007074 -293.407338)
		(end 146.007074 -293.52621)
		(width 0.09525)
		(layer "In4.Cu")
		(net "M_J_CPU1_SB_DQS_DN<8>")
	)
	(segment
		(start 140.454888 -291.426138)
		(end 140.46327 -291.421312)
		(width 0.09525)
		(layer "In4.Cu")
		(net "M_J_CPU1_SB_DQS_DN<8>")
	)
	(arc
		(start 145.06702 -291.906198)
		(mid 145.099096 -292.067455)
		(end 145.190464 -292.20414)
		(width 0.09525)
		(layer "In4.Cu")
		(net "M_J_CPU1_SB_DQS_DN<8>")
	)
	(arc
		(start 142.906242 -291.421312)
		(mid 143.09471 -291.471989)
		(end 143.283178 -291.421312)
		(width 0.09525)
		(layer "In4.Cu")
		(net "M_J_CPU1_SB_DQS_DN<8>")
	)
	(arc
		(start 137.643362 -291.421312)
		(mid 137.924794 -291.345557)
		(end 138.206226 -291.421312)
		(width 0.09525)
		(layer "In4.Cu")
		(net "M_J_CPU1_SB_DQS_DN<8>")
	)
	(arc
		(start 136.703308 -291.421312)
		(mid 136.98474 -291.345557)
		(end 137.266172 -291.421312)
		(width 0.09525)
		(layer "In4.Cu")
		(net "M_J_CPU1_SB_DQS_DN<8>")
	)
	(arc
		(start 140.46327 -291.421312)
		(mid 140.744702 -291.345557)
		(end 141.026134 -291.421312)
		(width 0.09525)
		(layer "In4.Cu")
		(net "M_J_CPU1_SB_DQS_DN<8>")
	)
	(arc
		(start 146.007074 -293.52621)
		(mid 146.048739 -293.698657)
		(end 146.164554 -293.833042)
		(width 0.09525)
		(layer "In4.Cu")
		(net "M_J_CPU1_SB_DQS_DN<8>")
	)
	(arc
		(start 134.8232 -291.421312)
		(mid 135.104632 -291.345557)
		(end 135.386064 -291.421312)
		(width 0.09525)
		(layer "In4.Cu")
		(net "M_J_CPU1_SB_DQS_DN<8>")
	)
	(arc
		(start 144.223232 -291.421312)
		(mid 144.504664 -291.345557)
		(end 144.786096 -291.421312)
		(width 0.09525)
		(layer "In4.Cu")
		(net "M_J_CPU1_SB_DQS_DN<8>")
	)
	(arc
		(start 141.026134 -291.421312)
		(mid 141.209909 -291.472084)
		(end 141.394942 -291.426138)
		(width 0.09525)
		(layer "In4.Cu")
		(net "M_J_CPU1_SB_DQS_DN<8>")
	)
	(arc
		(start 137.274554 -291.426138)
		(mid 137.459586 -291.472052)
		(end 137.643362 -291.421312)
		(width 0.09525)
		(layer "In4.Cu")
		(net "M_J_CPU1_SB_DQS_DN<8>")
	)
	(arc
		(start 136.326118 -291.421312)
		(mid 136.509893 -291.472084)
		(end 136.694926 -291.426138)
		(width 0.09525)
		(layer "In4.Cu")
		(net "M_J_CPU1_SB_DQS_DN<8>")
	)
	(arc
		(start 141.403324 -291.421312)
		(mid 141.684756 -291.345557)
		(end 141.966188 -291.421312)
		(width 0.09525)
		(layer "In4.Cu")
		(net "M_J_CPU1_SB_DQS_DN<8>")
	)
	(arc
		(start 142.343378 -291.421312)
		(mid 142.62481 -291.345557)
		(end 142.906242 -291.421312)
		(width 0.09525)
		(layer "In4.Cu")
		(net "M_J_CPU1_SB_DQS_DN<8>")
	)
	(arc
		(start 138.583416 -291.421312)
		(mid 138.864848 -291.345557)
		(end 139.14628 -291.421312)
		(width 0.09525)
		(layer "In4.Cu")
		(net "M_J_CPU1_SB_DQS_DN<8>")
	)
	(arc
		(start 132.003292 -291.421312)
		(mid 132.284724 -291.345557)
		(end 132.566156 -291.421312)
		(width 0.09525)
		(layer "In4.Cu")
		(net "M_J_CPU1_SB_DQS_DN<8>")
	)
	(arc
		(start 145.73377 -292.747446)
		(mid 145.936068 -293.050207)
		(end 146.007074 -293.407338)
		(width 0.09525)
		(layer "In4.Cu")
		(net "M_J_CPU1_SB_DQS_DN<8>")
	)
	(arc
		(start 139.523216 -291.421312)
		(mid 139.804648 -291.345557)
		(end 140.08608 -291.421312)
		(width 0.09525)
		(layer "In4.Cu")
		(net "M_J_CPU1_SB_DQS_DN<8>")
	)
	(arc
		(start 139.14628 -291.421312)
		(mid 139.334748 -291.471989)
		(end 139.523216 -291.421312)
		(width 0.09525)
		(layer "In4.Cu")
		(net "M_J_CPU1_SB_DQS_DN<8>")
	)
	(arc
		(start 144.824196 -291.44341)
		(mid 145.002646 -291.64488)
		(end 145.06702 -291.906198)
		(width 0.09525)
		(layer "In4.Cu")
		(net "M_J_CPU1_SB_DQS_DN<8>")
	)
	(arc
		(start 143.846042 -291.421312)
		(mid 144.029817 -291.472084)
		(end 144.21485 -291.426138)
		(width 0.09525)
		(layer "In4.Cu")
		(net "M_J_CPU1_SB_DQS_DN<8>")
	)
	(arc
		(start 135.763254 -291.421312)
		(mid 136.044686 -291.345557)
		(end 136.326118 -291.421312)
		(width 0.09525)
		(layer "In4.Cu")
		(net "M_J_CPU1_SB_DQS_DN<8>")
	)
	(arc
		(start 140.08608 -291.421312)
		(mid 140.269855 -291.472084)
		(end 140.454888 -291.426138)
		(width 0.09525)
		(layer "In4.Cu")
		(net "M_J_CPU1_SB_DQS_DN<8>")
	)
	(arc
		(start 131.684268 -291.44849)
		(mid 131.842018 -291.471009)
		(end 131.99491 -291.426138)
		(width 0.09525)
		(layer "In4.Cu")
		(net "M_J_CPU1_SB_DQS_DN<8>")
	)
	(arc
		(start 143.283178 -291.421312)
		(mid 143.56461 -291.345557)
		(end 143.846042 -291.421312)
		(width 0.09525)
		(layer "In4.Cu")
		(net "M_J_CPU1_SB_DQS_DN<8>")
	)
	(arc
		(start 133.8834 -291.421312)
		(mid 134.164832 -291.345557)
		(end 134.446264 -291.421312)
		(width 0.09525)
		(layer "In4.Cu")
		(net "M_J_CPU1_SB_DQS_DN<8>")
	)
	(arc
		(start 134.446264 -291.421312)
		(mid 134.634732 -291.471989)
		(end 134.8232 -291.421312)
		(width 0.09525)
		(layer "In4.Cu")
		(net "M_J_CPU1_SB_DQS_DN<8>")
	)
	(arc
		(start 141.97457 -291.426138)
		(mid 142.159602 -291.472052)
		(end 142.343378 -291.421312)
		(width 0.09525)
		(layer "In4.Cu")
		(net "M_J_CPU1_SB_DQS_DN<8>")
	)
	(arc
		(start 138.214608 -291.426138)
		(mid 138.39964 -291.472052)
		(end 138.583416 -291.421312)
		(width 0.09525)
		(layer "In4.Cu")
		(net "M_J_CPU1_SB_DQS_DN<8>")
	)
	(arc
		(start 132.943346 -291.421312)
		(mid 133.224778 -291.345557)
		(end 133.50621 -291.421312)
		(width 0.09525)
		(layer "In4.Cu")
		(net "M_J_CPU1_SB_DQS_DN<8>")
	)
	(arc
		(start 135.386064 -291.421312)
		(mid 135.569839 -291.472084)
		(end 135.754872 -291.426138)
		(width 0.09525)
		(layer "In4.Cu")
		(net "M_J_CPU1_SB_DQS_DN<8>")
	)
	(arc
		(start 133.514592 -291.426138)
		(mid 133.699624 -291.472052)
		(end 133.8834 -291.421312)
		(width 0.09525)
		(layer "In4.Cu")
		(net "M_J_CPU1_SB_DQS_DN<8>")
	)
	(arc
		(start 146.234658 -293.874444)
		(mid 146.412347 -294.075593)
		(end 146.476466 -294.336216)
		(width 0.09525)
		(layer "In4.Cu")
		(net "M_J_CPU1_SB_DQS_DN<8>")
	)
	(arc
		(start 132.566156 -291.421312)
		(mid 132.749931 -291.472084)
		(end 132.934964 -291.426138)
		(width 0.09525)
		(layer "In4.Cu")
		(net "M_J_CPU1_SB_DQS_DN<8>")
	)
	(segment
		(start 131.347972 -285.970472)
		(end 131.814824 -286.23641)
		(width 0.12954)
		(layer "F.Cu")
		(net "M_J_CPU1_SB_DQS_DN<7>")
	)
	(segment
		(start 177.0634 -304.858166)
		(end 177.18024 -304.741326)
		(width 0.16002)
		(layer "In4.Cu")
		(net "M_J_CPU1_SB_DQS_DN<7>")
	)
	(segment
		(start 162.62731 -305.699414)
		(end 162.903916 -305.699414)
		(width 0.16002)
		(layer "In4.Cu")
		(net "M_J_CPU1_SB_DQS_DN<7>")
	)
	(segment
		(start 184.579514 -304.858166)
		(end 184.728612 -304.709068)
		(width 0.16002)
		(layer "In4.Cu")
		(net "M_J_CPU1_SB_DQS_DN<7>")
	)
	(segment
		(start 147.658328 -287.429702)
		(end 147.818602 -287.589976)
		(width 0.09525)
		(layer "In4.Cu")
		(net "M_J_CPU1_SB_DQS_DN<7>")
	)
	(segment
		(start 177.18024 -304.741326)
		(end 177.6603 -304.741326)
		(width 0.16002)
		(layer "In4.Cu")
		(net "M_J_CPU1_SB_DQS_DN<7>")
	)
	(segment
		(start 133.50621 -286.56153)
		(end 133.514592 -286.566356)
		(width 0.09525)
		(layer "In4.Cu")
		(net "M_J_CPU1_SB_DQS_DN<7>")
	)
	(segment
		(start 175.48987 -304.858166)
		(end 177.0634 -304.858166)
		(width 0.16002)
		(layer "In4.Cu")
		(net "M_J_CPU1_SB_DQS_DN<7>")
	)
	(segment
		(start 179.134516 -305.708304)
		(end 180.102256 -305.708304)
		(width 0.16002)
		(layer "In4.Cu")
		(net "M_J_CPU1_SB_DQS_DN<7>")
	)
	(segment
		(start 163.999672 -304.639726)
		(end 164.372544 -305.012598)
		(width 0.16002)
		(layer "In4.Cu")
		(net "M_J_CPU1_SB_DQS_DN<7>")
	)
	(segment
		(start 146.650202 -286.981646)
		(end 147.320254 -286.981646)
		(width 0.09525)
		(layer "In4.Cu")
		(net "M_J_CPU1_SB_DQS_DN<7>")
	)
	(segment
		(start 147.902422 -287.589976)
		(end 147.919186 -287.60674)
		(width 0.09525)
		(layer "In4.Cu")
		(net "M_J_CPU1_SB_DQS_DN<7>")
	)
	(segment
		(start 163.472622 -304.639726)
		(end 163.999672 -304.639726)
		(width 0.16002)
		(layer "In4.Cu")
		(net "M_J_CPU1_SB_DQS_DN<7>")
	)
	(segment
		(start 146.15414 -286.485584)
		(end 146.650202 -286.981646)
		(width 0.09525)
		(layer "In4.Cu")
		(net "M_J_CPU1_SB_DQS_DN<7>")
	)
	(segment
		(start 181.122828 -305.365912)
		(end 181.971188 -304.517552)
		(width 0.16002)
		(layer "In4.Cu")
		(net "M_J_CPU1_SB_DQS_DN<7>")
	)
	(segment
		(start 147.818602 -287.589976)
		(end 147.902422 -287.589976)
		(width 0.09525)
		(layer "In4.Cu")
		(net "M_J_CPU1_SB_DQS_DN<7>")
	)
	(segment
		(start 172.551852 -305.708304)
		(end 172.894244 -305.365912)
		(width 0.16002)
		(layer "In4.Cu")
		(net "M_J_CPU1_SB_DQS_DN<7>")
	)
	(segment
		(start 173.467268 -305.365912)
		(end 174.342298 -304.490882)
		(width 0.16002)
		(layer "In4.Cu")
		(net "M_J_CPU1_SB_DQS_DN<7>")
	)
	(segment
		(start 186.786266 -304.709068)
		(end 187.060078 -304.435256)
		(width 0.16002)
		(layer "In4.Cu")
		(net "M_J_CPU1_SB_DQS_DN<7>")
	)
	(segment
		(start 141.394942 -286.566356)
		(end 141.403324 -286.56153)
		(width 0.09525)
		(layer "In4.Cu")
		(net "M_J_CPU1_SB_DQS_DN<7>")
	)
	(segment
		(start 165.936168 -305.345592)
		(end 166.789608 -304.492152)
		(width 0.16002)
		(layer "In4.Cu")
		(net "M_J_CPU1_SB_DQS_DN<7>")
	)
	(segment
		(start 177.77714 -304.858166)
		(end 178.284378 -304.858166)
		(width 0.16002)
		(layer "In4.Cu")
		(net "M_J_CPU1_SB_DQS_DN<7>")
	)
	(segment
		(start 147.658328 -287.31972)
		(end 147.658328 -287.429702)
		(width 0.09525)
		(layer "In4.Cu")
		(net "M_J_CPU1_SB_DQS_DN<7>")
	)
	(segment
		(start 165.222174 -305.699414)
		(end 165.575996 -305.345592)
		(width 0.16002)
		(layer "In4.Cu")
		(net "M_J_CPU1_SB_DQS_DN<7>")
	)
	(segment
		(start 182.666132 -304.517552)
		(end 183.006746 -304.858166)
		(width 0.16002)
		(layer "In4.Cu")
		(net "M_J_CPU1_SB_DQS_DN<7>")
	)
	(segment
		(start 184.728612 -304.709068)
		(end 185.4708 -304.709068)
		(width 0.16002)
		(layer "In4.Cu")
		(net "M_J_CPU1_SB_DQS_DN<7>")
	)
	(segment
		(start 160.97377 -305.688492)
		(end 161.158682 -305.50358)
		(width 0.16002)
		(layer "In4.Cu")
		(net "M_J_CPU1_SB_DQS_DN<7>")
	)
	(segment
		(start 186.18454 -304.709068)
		(end 186.786266 -304.709068)
		(width 0.16002)
		(layer "In4.Cu")
		(net "M_J_CPU1_SB_DQS_DN<7>")
	)
	(segment
		(start 135.754872 -286.566356)
		(end 135.763254 -286.56153)
		(width 0.09525)
		(layer "In4.Cu")
		(net "M_J_CPU1_SB_DQS_DN<7>")
	)
	(segment
		(start 180.444648 -305.365912)
		(end 181.122828 -305.365912)
		(width 0.16002)
		(layer "In4.Cu")
		(net "M_J_CPU1_SB_DQS_DN<7>")
	)
	(segment
		(start 152.93721 -292.624764)
		(end 152.93721 -298.0436)
		(width 0.16002)
		(layer "In4.Cu")
		(net "M_J_CPU1_SB_DQS_DN<7>")
	)
	(segment
		(start 131.6609 -286.50184)
		(end 131.684268 -286.588708)
		(width 0.09525)
		(layer "In4.Cu")
		(net "M_J_CPU1_SB_DQS_DN<7>")
	)
	(segment
		(start 163.09975 -305.50358)
		(end 163.09975 -305.012598)
		(width 0.16002)
		(layer "In4.Cu")
		(net "M_J_CPU1_SB_DQS_DN<7>")
	)
	(segment
		(start 162.903916 -305.699414)
		(end 163.09975 -305.50358)
		(width 0.16002)
		(layer "In4.Cu")
		(net "M_J_CPU1_SB_DQS_DN<7>")
	)
	(segment
		(start 174.342298 -304.490882)
		(end 175.122586 -304.490882)
		(width 0.16002)
		(layer "In4.Cu")
		(net "M_J_CPU1_SB_DQS_DN<7>")
	)
	(segment
		(start 161.158682 -305.50358)
		(end 161.158682 -305.012598)
		(width 0.16002)
		(layer "In4.Cu")
		(net "M_J_CPU1_SB_DQS_DN<7>")
	)
	(segment
		(start 141.966188 -286.56153)
		(end 141.97457 -286.566356)
		(width 0.09525)
		(layer "In4.Cu")
		(net "M_J_CPU1_SB_DQS_DN<7>")
	)
	(segment
		(start 178.284378 -304.858166)
		(end 179.134516 -305.708304)
		(width 0.16002)
		(layer "In4.Cu")
		(net "M_J_CPU1_SB_DQS_DN<7>")
	)
	(segment
		(start 152.93721 -298.0436)
		(end 160.582102 -305.688492)
		(width 0.16002)
		(layer "In4.Cu")
		(net "M_J_CPU1_SB_DQS_DN<7>")
	)
	(segment
		(start 185.58764 -304.592228)
		(end 186.0677 -304.592228)
		(width 0.16002)
		(layer "In4.Cu")
		(net "M_J_CPU1_SB_DQS_DN<7>")
	)
	(segment
		(start 180.102256 -305.708304)
		(end 180.444648 -305.365912)
		(width 0.16002)
		(layer "In4.Cu")
		(net "M_J_CPU1_SB_DQS_DN<7>")
	)
	(segment
		(start 147.320254 -286.981646)
		(end 147.658328 -287.31972)
		(width 0.09525)
		(layer "In4.Cu")
		(net "M_J_CPU1_SB_DQS_DN<7>")
	)
	(segment
		(start 186.0677 -304.592228)
		(end 186.18454 -304.709068)
		(width 0.16002)
		(layer "In4.Cu")
		(net "M_J_CPU1_SB_DQS_DN<7>")
	)
	(segment
		(start 162.431476 -305.50358)
		(end 162.62731 -305.699414)
		(width 0.16002)
		(layer "In4.Cu")
		(net "M_J_CPU1_SB_DQS_DN<7>")
	)
	(segment
		(start 131.99491 -286.566356)
		(end 132.003292 -286.56153)
		(width 0.09525)
		(layer "In4.Cu")
		(net "M_J_CPU1_SB_DQS_DN<7>")
	)
	(segment
		(start 140.454888 -286.566356)
		(end 140.46327 -286.56153)
		(width 0.09525)
		(layer "In4.Cu")
		(net "M_J_CPU1_SB_DQS_DN<7>")
	)
	(segment
		(start 171.060364 -305.708304)
		(end 172.551852 -305.708304)
		(width 0.16002)
		(layer "In4.Cu")
		(net "M_J_CPU1_SB_DQS_DN<7>")
	)
	(segment
		(start 160.582102 -305.688492)
		(end 160.97377 -305.688492)
		(width 0.16002)
		(layer "In4.Cu")
		(net "M_J_CPU1_SB_DQS_DN<7>")
	)
	(segment
		(start 132.934964 -286.566356)
		(end 132.943346 -286.56153)
		(width 0.09525)
		(layer "In4.Cu")
		(net "M_J_CPU1_SB_DQS_DN<7>")
	)
	(segment
		(start 172.894244 -305.365912)
		(end 173.467268 -305.365912)
		(width 0.16002)
		(layer "In4.Cu")
		(net "M_J_CPU1_SB_DQS_DN<7>")
	)
	(segment
		(start 166.789608 -304.492152)
		(end 169.844212 -304.492152)
		(width 0.16002)
		(layer "In4.Cu")
		(net "M_J_CPU1_SB_DQS_DN<7>")
	)
	(segment
		(start 147.919186 -287.60674)
		(end 152.93721 -292.624764)
		(width 0.16002)
		(layer "In4.Cu")
		(net "M_J_CPU1_SB_DQS_DN<7>")
	)
	(segment
		(start 161.158682 -305.012598)
		(end 161.531554 -304.639726)
		(width 0.16002)
		(layer "In4.Cu")
		(net "M_J_CPU1_SB_DQS_DN<7>")
	)
	(segment
		(start 131.814824 -286.23641)
		(end 131.6609 -286.50184)
		(width 0.09525)
		(layer "In4.Cu")
		(net "M_J_CPU1_SB_DQS_DN<7>")
	)
	(segment
		(start 136.694926 -286.566356)
		(end 136.703308 -286.56153)
		(width 0.09525)
		(layer "In4.Cu")
		(net "M_J_CPU1_SB_DQS_DN<7>")
	)
	(segment
		(start 183.006746 -304.858166)
		(end 184.579514 -304.858166)
		(width 0.16002)
		(layer "In4.Cu")
		(net "M_J_CPU1_SB_DQS_DN<7>")
	)
	(segment
		(start 164.568378 -305.699414)
		(end 165.222174 -305.699414)
		(width 0.16002)
		(layer "In4.Cu")
		(net "M_J_CPU1_SB_DQS_DN<7>")
	)
	(segment
		(start 169.844212 -304.492152)
		(end 171.060364 -305.708304)
		(width 0.16002)
		(layer "In4.Cu")
		(net "M_J_CPU1_SB_DQS_DN<7>")
	)
	(segment
		(start 144.50568 -286.485584)
		(end 146.15414 -286.485584)
		(width 0.09525)
		(layer "In4.Cu")
		(net "M_J_CPU1_SB_DQS_DN<7>")
	)
	(segment
		(start 161.531554 -304.639726)
		(end 162.058604 -304.639726)
		(width 0.16002)
		(layer "In4.Cu")
		(net "M_J_CPU1_SB_DQS_DN<7>")
	)
	(segment
		(start 138.206226 -286.56153)
		(end 138.214608 -286.566356)
		(width 0.09525)
		(layer "In4.Cu")
		(net "M_J_CPU1_SB_DQS_DN<7>")
	)
	(segment
		(start 175.122586 -304.490882)
		(end 175.48987 -304.858166)
		(width 0.16002)
		(layer "In4.Cu")
		(net "M_J_CPU1_SB_DQS_DN<7>")
	)
	(segment
		(start 163.09975 -305.012598)
		(end 163.472622 -304.639726)
		(width 0.16002)
		(layer "In4.Cu")
		(net "M_J_CPU1_SB_DQS_DN<7>")
	)
	(segment
		(start 177.6603 -304.741326)
		(end 177.77714 -304.858166)
		(width 0.16002)
		(layer "In4.Cu")
		(net "M_J_CPU1_SB_DQS_DN<7>")
	)
	(segment
		(start 181.971188 -304.517552)
		(end 182.666132 -304.517552)
		(width 0.16002)
		(layer "In4.Cu")
		(net "M_J_CPU1_SB_DQS_DN<7>")
	)
	(segment
		(start 164.372544 -305.012598)
		(end 164.372544 -305.50358)
		(width 0.16002)
		(layer "In4.Cu")
		(net "M_J_CPU1_SB_DQS_DN<7>")
	)
	(segment
		(start 143.846042 -286.56153)
		(end 143.854424 -286.566356)
		(width 0.09525)
		(layer "In4.Cu")
		(net "M_J_CPU1_SB_DQS_DN<7>")
	)
	(segment
		(start 164.372544 -305.50358)
		(end 164.568378 -305.699414)
		(width 0.16002)
		(layer "In4.Cu")
		(net "M_J_CPU1_SB_DQS_DN<7>")
	)
	(segment
		(start 185.4708 -304.709068)
		(end 185.58764 -304.592228)
		(width 0.16002)
		(layer "In4.Cu")
		(net "M_J_CPU1_SB_DQS_DN<7>")
	)
	(segment
		(start 137.266172 -286.56153)
		(end 137.274554 -286.566356)
		(width 0.09525)
		(layer "In4.Cu")
		(net "M_J_CPU1_SB_DQS_DN<7>")
	)
	(segment
		(start 162.058604 -304.639726)
		(end 162.431476 -305.012598)
		(width 0.16002)
		(layer "In4.Cu")
		(net "M_J_CPU1_SB_DQS_DN<7>")
	)
	(segment
		(start 165.575996 -305.345592)
		(end 165.936168 -305.345592)
		(width 0.16002)
		(layer "In4.Cu")
		(net "M_J_CPU1_SB_DQS_DN<7>")
	)
	(segment
		(start 162.431476 -305.012598)
		(end 162.431476 -305.50358)
		(width 0.16002)
		(layer "In4.Cu")
		(net "M_J_CPU1_SB_DQS_DN<7>")
	)
	(arc
		(start 141.026134 -286.56153)
		(mid 141.209909 -286.612302)
		(end 141.394942 -286.566356)
		(width 0.09525)
		(layer "In4.Cu")
		(net "M_J_CPU1_SB_DQS_DN<7>")
	)
	(arc
		(start 132.943346 -286.56153)
		(mid 133.224778 -286.485741)
		(end 133.50621 -286.56153)
		(width 0.09525)
		(layer "In4.Cu")
		(net "M_J_CPU1_SB_DQS_DN<7>")
	)
	(arc
		(start 134.8232 -286.56153)
		(mid 135.104632 -286.485741)
		(end 135.386064 -286.56153)
		(width 0.09525)
		(layer "In4.Cu")
		(net "M_J_CPU1_SB_DQS_DN<7>")
	)
	(arc
		(start 140.08608 -286.56153)
		(mid 140.269855 -286.612302)
		(end 140.454888 -286.566356)
		(width 0.09525)
		(layer "In4.Cu")
		(net "M_J_CPU1_SB_DQS_DN<7>")
	)
	(arc
		(start 139.14628 -286.56153)
		(mid 139.334748 -286.612207)
		(end 139.523216 -286.56153)
		(width 0.09525)
		(layer "In4.Cu")
		(net "M_J_CPU1_SB_DQS_DN<7>")
	)
	(arc
		(start 134.446264 -286.56153)
		(mid 134.634732 -286.612207)
		(end 134.8232 -286.56153)
		(width 0.09525)
		(layer "In4.Cu")
		(net "M_J_CPU1_SB_DQS_DN<7>")
	)
	(arc
		(start 143.283178 -286.56153)
		(mid 143.56461 -286.485741)
		(end 143.846042 -286.56153)
		(width 0.09525)
		(layer "In4.Cu")
		(net "M_J_CPU1_SB_DQS_DN<7>")
	)
	(arc
		(start 131.684268 -286.588708)
		(mid 131.842018 -286.611227)
		(end 131.99491 -286.566356)
		(width 0.09525)
		(layer "In4.Cu")
		(net "M_J_CPU1_SB_DQS_DN<7>")
	)
	(arc
		(start 138.583416 -286.56153)
		(mid 138.864848 -286.485741)
		(end 139.14628 -286.56153)
		(width 0.09525)
		(layer "In4.Cu")
		(net "M_J_CPU1_SB_DQS_DN<7>")
	)
	(arc
		(start 142.906242 -286.56153)
		(mid 143.09471 -286.612207)
		(end 143.283178 -286.56153)
		(width 0.09525)
		(layer "In4.Cu")
		(net "M_J_CPU1_SB_DQS_DN<7>")
	)
	(arc
		(start 142.343378 -286.56153)
		(mid 142.62481 -286.485741)
		(end 142.906242 -286.56153)
		(width 0.09525)
		(layer "In4.Cu")
		(net "M_J_CPU1_SB_DQS_DN<7>")
	)
	(arc
		(start 135.386064 -286.56153)
		(mid 135.569839 -286.612302)
		(end 135.754872 -286.566356)
		(width 0.09525)
		(layer "In4.Cu")
		(net "M_J_CPU1_SB_DQS_DN<7>")
	)
	(arc
		(start 144.22374 -286.56153)
		(mid 144.359677 -286.504856)
		(end 144.50568 -286.485584)
		(width 0.09525)
		(layer "In4.Cu")
		(net "M_J_CPU1_SB_DQS_DN<7>")
	)
	(arc
		(start 140.46327 -286.56153)
		(mid 140.744702 -286.485741)
		(end 141.026134 -286.56153)
		(width 0.09525)
		(layer "In4.Cu")
		(net "M_J_CPU1_SB_DQS_DN<7>")
	)
	(arc
		(start 137.274554 -286.566356)
		(mid 137.459586 -286.61227)
		(end 137.643362 -286.56153)
		(width 0.09525)
		(layer "In4.Cu")
		(net "M_J_CPU1_SB_DQS_DN<7>")
	)
	(arc
		(start 141.97457 -286.566356)
		(mid 142.159602 -286.61227)
		(end 142.343378 -286.56153)
		(width 0.09525)
		(layer "In4.Cu")
		(net "M_J_CPU1_SB_DQS_DN<7>")
	)
	(arc
		(start 136.703308 -286.56153)
		(mid 136.98474 -286.485741)
		(end 137.266172 -286.56153)
		(width 0.09525)
		(layer "In4.Cu")
		(net "M_J_CPU1_SB_DQS_DN<7>")
	)
	(arc
		(start 135.763254 -286.56153)
		(mid 136.044686 -286.485741)
		(end 136.326118 -286.56153)
		(width 0.09525)
		(layer "In4.Cu")
		(net "M_J_CPU1_SB_DQS_DN<7>")
	)
	(arc
		(start 139.523216 -286.56153)
		(mid 139.804648 -286.485741)
		(end 140.08608 -286.56153)
		(width 0.09525)
		(layer "In4.Cu")
		(net "M_J_CPU1_SB_DQS_DN<7>")
	)
	(arc
		(start 137.643362 -286.56153)
		(mid 137.924794 -286.485741)
		(end 138.206226 -286.56153)
		(width 0.09525)
		(layer "In4.Cu")
		(net "M_J_CPU1_SB_DQS_DN<7>")
	)
	(arc
		(start 141.403324 -286.56153)
		(mid 141.684756 -286.485741)
		(end 141.966188 -286.56153)
		(width 0.09525)
		(layer "In4.Cu")
		(net "M_J_CPU1_SB_DQS_DN<7>")
	)
	(arc
		(start 138.214608 -286.566356)
		(mid 138.39964 -286.61227)
		(end 138.583416 -286.56153)
		(width 0.09525)
		(layer "In4.Cu")
		(net "M_J_CPU1_SB_DQS_DN<7>")
	)
	(arc
		(start 136.326118 -286.56153)
		(mid 136.509893 -286.612302)
		(end 136.694926 -286.566356)
		(width 0.09525)
		(layer "In4.Cu")
		(net "M_J_CPU1_SB_DQS_DN<7>")
	)
	(arc
		(start 143.854424 -286.566356)
		(mid 144.03971 -286.612392)
		(end 144.22374 -286.56153)
		(width 0.09525)
		(layer "In4.Cu")
		(net "M_J_CPU1_SB_DQS_DN<7>")
	)
	(arc
		(start 132.003292 -286.56153)
		(mid 132.284724 -286.485741)
		(end 132.566156 -286.56153)
		(width 0.09525)
		(layer "In4.Cu")
		(net "M_J_CPU1_SB_DQS_DN<7>")
	)
	(arc
		(start 133.8834 -286.56153)
		(mid 134.164832 -286.485741)
		(end 134.446264 -286.56153)
		(width 0.09525)
		(layer "In4.Cu")
		(net "M_J_CPU1_SB_DQS_DN<7>")
	)
	(arc
		(start 132.566156 -286.56153)
		(mid 132.749931 -286.612302)
		(end 132.934964 -286.566356)
		(width 0.09525)
		(layer "In4.Cu")
		(net "M_J_CPU1_SB_DQS_DN<7>")
	)
	(arc
		(start 133.514592 -286.566356)
		(mid 133.699624 -286.61227)
		(end 133.8834 -286.56153)
		(width 0.09525)
		(layer "In4.Cu")
		(net "M_J_CPU1_SB_DQS_DN<7>")
	)
	(segment
		(start 131.347972 -281.110436)
		(end 131.814824 -281.376374)
		(width 0.12954)
		(layer "F.Cu")
		(net "M_J_CPU1_SB_DQS_DN<6>")
	)
	(segment
		(start 161.435288 -295.372282)
		(end 161.120582 -295.686988)
		(width 0.16002)
		(layer "In4.Cu")
		(net "M_J_CPU1_SB_DQS_DN<6>")
	)
	(segment
		(start 132.934964 -281.70632)
		(end 132.943346 -281.701494)
		(width 0.09525)
		(layer "In4.Cu")
		(net "M_J_CPU1_SB_DQS_DN<6>")
	)
	(segment
		(start 185.6867 -295.242234)
		(end 186.16676 -295.242234)
		(width 0.16002)
		(layer "In4.Cu")
		(net "M_J_CPU1_SB_DQS_DN<6>")
	)
	(segment
		(start 131.814824 -281.376374)
		(end 131.6609 -281.641804)
		(width 0.09525)
		(layer "In4.Cu")
		(net "M_J_CPU1_SB_DQS_DN<6>")
	)
	(segment
		(start 146.721576 -281.706066)
		(end 146.893026 -281.877516)
		(width 0.09525)
		(layer "In4.Cu")
		(net "M_J_CPU1_SB_DQS_DN<6>")
	)
	(segment
		(start 166.789608 -295.142158)
		(end 169.844212 -295.142158)
		(width 0.16002)
		(layer "In4.Cu")
		(net "M_J_CPU1_SB_DQS_DN<6>")
	)
	(segment
		(start 131.6609 -281.641804)
		(end 131.684268 -281.728672)
		(width 0.09525)
		(layer "In4.Cu")
		(net "M_J_CPU1_SB_DQS_DN<6>")
	)
	(segment
		(start 147.649692 -281.818334)
		(end 147.673314 -281.818334)
		(width 0.09525)
		(layer "In4.Cu")
		(net "M_J_CPU1_SB_DQS_DN<6>")
	)
	(segment
		(start 172.894244 -296.015918)
		(end 173.467268 -296.015918)
		(width 0.16002)
		(layer "In4.Cu")
		(net "M_J_CPU1_SB_DQS_DN<6>")
	)
	(segment
		(start 161.908744 -295.845738)
		(end 162.436048 -295.845738)
		(width 0.16002)
		(layer "In4.Cu")
		(net "M_J_CPU1_SB_DQS_DN<6>")
	)
	(segment
		(start 186.16676 -295.242234)
		(end 186.2836 -295.359074)
		(width 0.16002)
		(layer "In4.Cu")
		(net "M_J_CPU1_SB_DQS_DN<6>")
	)
	(segment
		(start 184.579514 -295.508172)
		(end 184.728612 -295.359074)
		(width 0.16002)
		(layer "In4.Cu")
		(net "M_J_CPU1_SB_DQS_DN<6>")
	)
	(segment
		(start 160.061656 -293.99865)
		(end 159.74695 -294.313356)
		(width 0.16002)
		(layer "In4.Cu")
		(net "M_J_CPU1_SB_DQS_DN<6>")
	)
	(segment
		(start 172.551852 -296.35831)
		(end 172.894244 -296.015918)
		(width 0.16002)
		(layer "In4.Cu")
		(net "M_J_CPU1_SB_DQS_DN<6>")
	)
	(segment
		(start 165.936168 -295.995598)
		(end 166.789608 -295.142158)
		(width 0.16002)
		(layer "In4.Cu")
		(net "M_J_CPU1_SB_DQS_DN<6>")
	)
	(segment
		(start 178.284378 -295.508172)
		(end 179.134516 -296.35831)
		(width 0.16002)
		(layer "In4.Cu")
		(net "M_J_CPU1_SB_DQS_DN<6>")
	)
	(segment
		(start 136.694926 -281.70632)
		(end 136.703308 -281.701494)
		(width 0.09525)
		(layer "In4.Cu")
		(net "M_J_CPU1_SB_DQS_DN<6>")
	)
	(segment
		(start 161.120582 -295.963848)
		(end 161.317178 -296.160444)
		(width 0.16002)
		(layer "In4.Cu")
		(net "M_J_CPU1_SB_DQS_DN<6>")
	)
	(segment
		(start 141.966188 -281.701494)
		(end 141.97457 -281.70632)
		(width 0.09525)
		(layer "In4.Cu")
		(net "M_J_CPU1_SB_DQS_DN<6>")
	)
	(segment
		(start 160.220406 -294.786812)
		(end 160.535112 -294.472106)
		(width 0.16002)
		(layer "In4.Cu")
		(net "M_J_CPU1_SB_DQS_DN<6>")
	)
	(segment
		(start 147.59051 -281.877516)
		(end 147.649692 -281.818334)
		(width 0.09525)
		(layer "In4.Cu")
		(net "M_J_CPU1_SB_DQS_DN<6>")
	)
	(segment
		(start 159.688784 -293.098474)
		(end 160.061656 -293.471346)
		(width 0.16002)
		(layer "In4.Cu")
		(net "M_J_CPU1_SB_DQS_DN<6>")
	)
	(segment
		(start 159.74695 -294.590216)
		(end 159.943546 -294.786812)
		(width 0.16002)
		(layer "In4.Cu")
		(net "M_J_CPU1_SB_DQS_DN<6>")
	)
	(segment
		(start 161.062416 -294.472106)
		(end 161.435288 -294.844978)
		(width 0.16002)
		(layer "In4.Cu")
		(net "M_J_CPU1_SB_DQS_DN<6>")
	)
	(segment
		(start 161.317178 -296.160444)
		(end 161.594038 -296.160444)
		(width 0.16002)
		(layer "In4.Cu")
		(net "M_J_CPU1_SB_DQS_DN<6>")
	)
	(segment
		(start 133.50621 -281.701494)
		(end 133.514592 -281.70632)
		(width 0.09525)
		(layer "In4.Cu")
		(net "M_J_CPU1_SB_DQS_DN<6>")
	)
	(segment
		(start 160.061656 -293.471346)
		(end 160.061656 -293.99865)
		(width 0.16002)
		(layer "In4.Cu")
		(net "M_J_CPU1_SB_DQS_DN<6>")
	)
	(segment
		(start 143.846042 -281.701494)
		(end 143.854424 -281.70632)
		(width 0.09525)
		(layer "In4.Cu")
		(net "M_J_CPU1_SB_DQS_DN<6>")
	)
	(segment
		(start 146.893026 -281.877516)
		(end 147.59051 -281.877516)
		(width 0.09525)
		(layer "In4.Cu")
		(net "M_J_CPU1_SB_DQS_DN<6>")
	)
	(segment
		(start 160.535112 -294.472106)
		(end 161.062416 -294.472106)
		(width 0.16002)
		(layer "In4.Cu")
		(net "M_J_CPU1_SB_DQS_DN<6>")
	)
	(segment
		(start 162.436048 -295.845738)
		(end 162.585908 -295.995598)
		(width 0.16002)
		(layer "In4.Cu")
		(net "M_J_CPU1_SB_DQS_DN<6>")
	)
	(segment
		(start 185.56986 -295.359074)
		(end 185.6867 -295.242234)
		(width 0.16002)
		(layer "In4.Cu")
		(net "M_J_CPU1_SB_DQS_DN<6>")
	)
	(segment
		(start 138.206226 -281.701494)
		(end 138.214608 -281.70632)
		(width 0.09525)
		(layer "In4.Cu")
		(net "M_J_CPU1_SB_DQS_DN<6>")
	)
	(segment
		(start 175.122586 -295.140888)
		(end 175.48987 -295.508172)
		(width 0.16002)
		(layer "In4.Cu")
		(net "M_J_CPU1_SB_DQS_DN<6>")
	)
	(segment
		(start 158.947866 -293.312088)
		(end 159.16148 -293.098474)
		(width 0.16002)
		(layer "In4.Cu")
		(net "M_J_CPU1_SB_DQS_DN<6>")
	)
	(segment
		(start 147.673314 -281.818334)
		(end 149.993096 -281.818334)
		(width 0.16002)
		(layer "In4.Cu")
		(net "M_J_CPU1_SB_DQS_DN<6>")
	)
	(segment
		(start 159.74695 -294.313356)
		(end 159.74695 -294.590216)
		(width 0.16002)
		(layer "In4.Cu")
		(net "M_J_CPU1_SB_DQS_DN<6>")
	)
	(segment
		(start 141.394942 -281.70632)
		(end 141.403324 -281.701494)
		(width 0.09525)
		(layer "In4.Cu")
		(net "M_J_CPU1_SB_DQS_DN<6>")
	)
	(segment
		(start 158.671006 -293.312088)
		(end 158.947866 -293.312088)
		(width 0.16002)
		(layer "In4.Cu")
		(net "M_J_CPU1_SB_DQS_DN<6>")
	)
	(segment
		(start 181.971188 -295.167558)
		(end 182.666132 -295.167558)
		(width 0.16002)
		(layer "In4.Cu")
		(net "M_J_CPU1_SB_DQS_DN<6>")
	)
	(segment
		(start 162.585908 -295.995598)
		(end 165.936168 -295.995598)
		(width 0.16002)
		(layer "In4.Cu")
		(net "M_J_CPU1_SB_DQS_DN<6>")
	)
	(segment
		(start 169.844212 -295.142158)
		(end 171.060364 -296.35831)
		(width 0.16002)
		(layer "In4.Cu")
		(net "M_J_CPU1_SB_DQS_DN<6>")
	)
	(segment
		(start 179.134516 -296.35831)
		(end 180.102256 -296.35831)
		(width 0.16002)
		(layer "In4.Cu")
		(net "M_J_CPU1_SB_DQS_DN<6>")
	)
	(segment
		(start 149.993096 -281.818334)
		(end 158.47441 -290.299648)
		(width 0.16002)
		(layer "In4.Cu")
		(net "M_J_CPU1_SB_DQS_DN<6>")
	)
	(segment
		(start 184.728612 -295.359074)
		(end 185.56986 -295.359074)
		(width 0.16002)
		(layer "In4.Cu")
		(net "M_J_CPU1_SB_DQS_DN<6>")
	)
	(segment
		(start 159.16148 -293.098474)
		(end 159.688784 -293.098474)
		(width 0.16002)
		(layer "In4.Cu")
		(net "M_J_CPU1_SB_DQS_DN<6>")
	)
	(segment
		(start 158.47441 -291.8841)
		(end 158.688024 -292.097714)
		(width 0.16002)
		(layer "In4.Cu")
		(net "M_J_CPU1_SB_DQS_DN<6>")
	)
	(segment
		(start 186.786266 -295.359074)
		(end 187.060078 -295.085262)
		(width 0.16002)
		(layer "In4.Cu")
		(net "M_J_CPU1_SB_DQS_DN<6>")
	)
	(segment
		(start 182.666132 -295.167558)
		(end 183.006746 -295.508172)
		(width 0.16002)
		(layer "In4.Cu")
		(net "M_J_CPU1_SB_DQS_DN<6>")
	)
	(segment
		(start 161.435288 -294.844978)
		(end 161.435288 -295.372282)
		(width 0.16002)
		(layer "In4.Cu")
		(net "M_J_CPU1_SB_DQS_DN<6>")
	)
	(segment
		(start 140.454888 -281.70632)
		(end 140.46327 -281.701494)
		(width 0.09525)
		(layer "In4.Cu")
		(net "M_J_CPU1_SB_DQS_DN<6>")
	)
	(segment
		(start 145.444718 -281.625802)
		(end 146.486372 -281.625802)
		(width 0.09525)
		(layer "In4.Cu")
		(net "M_J_CPU1_SB_DQS_DN<6>")
	)
	(segment
		(start 174.342298 -295.140888)
		(end 175.122586 -295.140888)
		(width 0.16002)
		(layer "In4.Cu")
		(net "M_J_CPU1_SB_DQS_DN<6>")
	)
	(segment
		(start 175.48987 -295.508172)
		(end 178.284378 -295.508172)
		(width 0.16002)
		(layer "In4.Cu")
		(net "M_J_CPU1_SB_DQS_DN<6>")
	)
	(segment
		(start 186.2836 -295.359074)
		(end 186.786266 -295.359074)
		(width 0.16002)
		(layer "In4.Cu")
		(net "M_J_CPU1_SB_DQS_DN<6>")
	)
	(segment
		(start 158.688024 -292.625018)
		(end 158.47441 -292.838632)
		(width 0.16002)
		(layer "In4.Cu")
		(net "M_J_CPU1_SB_DQS_DN<6>")
	)
	(segment
		(start 158.47441 -290.299648)
		(end 158.47441 -291.8841)
		(width 0.16002)
		(layer "In4.Cu")
		(net "M_J_CPU1_SB_DQS_DN<6>")
	)
	(segment
		(start 180.102256 -296.35831)
		(end 180.444648 -296.015918)
		(width 0.16002)
		(layer "In4.Cu")
		(net "M_J_CPU1_SB_DQS_DN<6>")
	)
	(segment
		(start 131.99491 -281.70632)
		(end 132.003292 -281.701494)
		(width 0.09525)
		(layer "In4.Cu")
		(net "M_J_CPU1_SB_DQS_DN<6>")
	)
	(segment
		(start 161.594038 -296.160444)
		(end 161.908744 -295.845738)
		(width 0.16002)
		(layer "In4.Cu")
		(net "M_J_CPU1_SB_DQS_DN<6>")
	)
	(segment
		(start 181.122828 -296.015918)
		(end 181.971188 -295.167558)
		(width 0.16002)
		(layer "In4.Cu")
		(net "M_J_CPU1_SB_DQS_DN<6>")
	)
	(segment
		(start 171.060364 -296.35831)
		(end 172.551852 -296.35831)
		(width 0.16002)
		(layer "In4.Cu")
		(net "M_J_CPU1_SB_DQS_DN<6>")
	)
	(segment
		(start 158.47441 -293.115492)
		(end 158.671006 -293.312088)
		(width 0.16002)
		(layer "In4.Cu")
		(net "M_J_CPU1_SB_DQS_DN<6>")
	)
	(segment
		(start 180.444648 -296.015918)
		(end 181.122828 -296.015918)
		(width 0.16002)
		(layer "In4.Cu")
		(net "M_J_CPU1_SB_DQS_DN<6>")
	)
	(segment
		(start 183.006746 -295.508172)
		(end 184.579514 -295.508172)
		(width 0.16002)
		(layer "In4.Cu")
		(net "M_J_CPU1_SB_DQS_DN<6>")
	)
	(segment
		(start 135.754872 -281.70632)
		(end 135.763254 -281.701494)
		(width 0.09525)
		(layer "In4.Cu")
		(net "M_J_CPU1_SB_DQS_DN<6>")
	)
	(segment
		(start 144.776444 -281.695398)
		(end 144.786858 -281.701494)
		(width 0.09525)
		(layer "In4.Cu")
		(net "M_J_CPU1_SB_DQS_DN<6>")
	)
	(segment
		(start 137.266172 -281.701494)
		(end 137.274554 -281.70632)
		(width 0.09525)
		(layer "In4.Cu")
		(net "M_J_CPU1_SB_DQS_DN<6>")
	)
	(segment
		(start 158.688024 -292.097714)
		(end 158.688024 -292.625018)
		(width 0.16002)
		(layer "In4.Cu")
		(net "M_J_CPU1_SB_DQS_DN<6>")
	)
	(segment
		(start 159.943546 -294.786812)
		(end 160.220406 -294.786812)
		(width 0.16002)
		(layer "In4.Cu")
		(net "M_J_CPU1_SB_DQS_DN<6>")
	)
	(segment
		(start 173.467268 -296.015918)
		(end 174.342298 -295.140888)
		(width 0.16002)
		(layer "In4.Cu")
		(net "M_J_CPU1_SB_DQS_DN<6>")
	)
	(segment
		(start 158.47441 -292.838632)
		(end 158.47441 -293.115492)
		(width 0.16002)
		(layer "In4.Cu")
		(net "M_J_CPU1_SB_DQS_DN<6>")
	)
	(segment
		(start 161.120582 -295.686988)
		(end 161.120582 -295.963848)
		(width 0.16002)
		(layer "In4.Cu")
		(net "M_J_CPU1_SB_DQS_DN<6>")
	)
	(arc
		(start 141.97457 -281.70632)
		(mid 142.159602 -281.752234)
		(end 142.343378 -281.701494)
		(width 0.09525)
		(layer "In4.Cu")
		(net "M_J_CPU1_SB_DQS_DN<6>")
	)
	(arc
		(start 133.8834 -281.701494)
		(mid 134.164832 -281.625739)
		(end 134.446264 -281.701494)
		(width 0.09525)
		(layer "In4.Cu")
		(net "M_J_CPU1_SB_DQS_DN<6>")
	)
	(arc
		(start 134.8232 -281.701494)
		(mid 135.104632 -281.625739)
		(end 135.386064 -281.701494)
		(width 0.09525)
		(layer "In4.Cu")
		(net "M_J_CPU1_SB_DQS_DN<6>")
	)
	(arc
		(start 139.14628 -281.701494)
		(mid 139.334748 -281.752171)
		(end 139.523216 -281.701494)
		(width 0.09525)
		(layer "In4.Cu")
		(net "M_J_CPU1_SB_DQS_DN<6>")
	)
	(arc
		(start 132.003292 -281.701494)
		(mid 132.284724 -281.625739)
		(end 132.566156 -281.701494)
		(width 0.09525)
		(layer "In4.Cu")
		(net "M_J_CPU1_SB_DQS_DN<6>")
	)
	(arc
		(start 143.854424 -281.70632)
		(mid 144.03971 -281.752356)
		(end 144.22374 -281.701494)
		(width 0.09525)
		(layer "In4.Cu")
		(net "M_J_CPU1_SB_DQS_DN<6>")
	)
	(arc
		(start 139.523216 -281.701494)
		(mid 139.804648 -281.625739)
		(end 140.08608 -281.701494)
		(width 0.09525)
		(layer "In4.Cu")
		(net "M_J_CPU1_SB_DQS_DN<6>")
	)
	(arc
		(start 144.22374 -281.701494)
		(mid 144.499283 -281.625645)
		(end 144.776444 -281.695398)
		(width 0.09525)
		(layer "In4.Cu")
		(net "M_J_CPU1_SB_DQS_DN<6>")
	)
	(arc
		(start 133.514592 -281.70632)
		(mid 133.699624 -281.752234)
		(end 133.8834 -281.701494)
		(width 0.09525)
		(layer "In4.Cu")
		(net "M_J_CPU1_SB_DQS_DN<6>")
	)
	(arc
		(start 134.446264 -281.701494)
		(mid 134.634732 -281.752171)
		(end 134.8232 -281.701494)
		(width 0.09525)
		(layer "In4.Cu")
		(net "M_J_CPU1_SB_DQS_DN<6>")
	)
	(arc
		(start 132.566156 -281.701494)
		(mid 132.749931 -281.752266)
		(end 132.934964 -281.70632)
		(width 0.09525)
		(layer "In4.Cu")
		(net "M_J_CPU1_SB_DQS_DN<6>")
	)
	(arc
		(start 137.643362 -281.701494)
		(mid 137.924794 -281.625739)
		(end 138.206226 -281.701494)
		(width 0.09525)
		(layer "In4.Cu")
		(net "M_J_CPU1_SB_DQS_DN<6>")
	)
	(arc
		(start 135.386064 -281.701494)
		(mid 135.569839 -281.752266)
		(end 135.754872 -281.70632)
		(width 0.09525)
		(layer "In4.Cu")
		(net "M_J_CPU1_SB_DQS_DN<6>")
	)
	(arc
		(start 144.786858 -281.701494)
		(mid 144.968474 -281.752231)
		(end 145.151856 -281.708352)
		(width 0.09525)
		(layer "In4.Cu")
		(net "M_J_CPU1_SB_DQS_DN<6>")
	)
	(arc
		(start 145.151856 -281.708352)
		(mid 145.292582 -281.646841)
		(end 145.444718 -281.625802)
		(width 0.09525)
		(layer "In4.Cu")
		(net "M_J_CPU1_SB_DQS_DN<6>")
	)
	(arc
		(start 135.763254 -281.701494)
		(mid 136.044686 -281.625739)
		(end 136.326118 -281.701494)
		(width 0.09525)
		(layer "In4.Cu")
		(net "M_J_CPU1_SB_DQS_DN<6>")
	)
	(arc
		(start 142.343378 -281.701494)
		(mid 142.62481 -281.625739)
		(end 142.906242 -281.701494)
		(width 0.09525)
		(layer "In4.Cu")
		(net "M_J_CPU1_SB_DQS_DN<6>")
	)
	(arc
		(start 131.684268 -281.728672)
		(mid 131.842018 -281.751191)
		(end 131.99491 -281.70632)
		(width 0.09525)
		(layer "In4.Cu")
		(net "M_J_CPU1_SB_DQS_DN<6>")
	)
	(arc
		(start 136.326118 -281.701494)
		(mid 136.509893 -281.752266)
		(end 136.694926 -281.70632)
		(width 0.09525)
		(layer "In4.Cu")
		(net "M_J_CPU1_SB_DQS_DN<6>")
	)
	(arc
		(start 140.46327 -281.701494)
		(mid 140.744702 -281.625739)
		(end 141.026134 -281.701494)
		(width 0.09525)
		(layer "In4.Cu")
		(net "M_J_CPU1_SB_DQS_DN<6>")
	)
	(arc
		(start 136.703308 -281.701494)
		(mid 136.98474 -281.625739)
		(end 137.266172 -281.701494)
		(width 0.09525)
		(layer "In4.Cu")
		(net "M_J_CPU1_SB_DQS_DN<6>")
	)
	(arc
		(start 142.906242 -281.701494)
		(mid 143.09471 -281.752171)
		(end 143.283178 -281.701494)
		(width 0.09525)
		(layer "In4.Cu")
		(net "M_J_CPU1_SB_DQS_DN<6>")
	)
	(arc
		(start 146.486372 -281.625802)
		(mid 146.610635 -281.646418)
		(end 146.721576 -281.706066)
		(width 0.09525)
		(layer "In4.Cu")
		(net "M_J_CPU1_SB_DQS_DN<6>")
	)
	(arc
		(start 137.274554 -281.70632)
		(mid 137.459586 -281.752234)
		(end 137.643362 -281.701494)
		(width 0.09525)
		(layer "In4.Cu")
		(net "M_J_CPU1_SB_DQS_DN<6>")
	)
	(arc
		(start 141.403324 -281.701494)
		(mid 141.684756 -281.625739)
		(end 141.966188 -281.701494)
		(width 0.09525)
		(layer "In4.Cu")
		(net "M_J_CPU1_SB_DQS_DN<6>")
	)
	(arc
		(start 132.943346 -281.701494)
		(mid 133.224778 -281.625739)
		(end 133.50621 -281.701494)
		(width 0.09525)
		(layer "In4.Cu")
		(net "M_J_CPU1_SB_DQS_DN<6>")
	)
	(arc
		(start 143.283178 -281.701494)
		(mid 143.56461 -281.625739)
		(end 143.846042 -281.701494)
		(width 0.09525)
		(layer "In4.Cu")
		(net "M_J_CPU1_SB_DQS_DN<6>")
	)
	(arc
		(start 138.583416 -281.701494)
		(mid 138.864848 -281.625739)
		(end 139.14628 -281.701494)
		(width 0.09525)
		(layer "In4.Cu")
		(net "M_J_CPU1_SB_DQS_DN<6>")
	)
	(arc
		(start 140.08608 -281.701494)
		(mid 140.269855 -281.752266)
		(end 140.454888 -281.70632)
		(width 0.09525)
		(layer "In4.Cu")
		(net "M_J_CPU1_SB_DQS_DN<6>")
	)
	(arc
		(start 141.026134 -281.701494)
		(mid 141.209909 -281.752266)
		(end 141.394942 -281.70632)
		(width 0.09525)
		(layer "In4.Cu")
		(net "M_J_CPU1_SB_DQS_DN<6>")
	)
	(arc
		(start 138.214608 -281.70632)
		(mid 138.39964 -281.752234)
		(end 138.583416 -281.701494)
		(width 0.09525)
		(layer "In4.Cu")
		(net "M_J_CPU1_SB_DQS_DN<6>")
	)
	(segment
		(start 131.347972 -276.2504)
		(end 131.814824 -276.516338)
		(width 0.12954)
		(layer "F.Cu")
		(net "M_J_CPU1_SB_DQS_DN<5>")
	)
	(segment
		(start 147.854162 -275.7932)
		(end 152.29713 -275.7932)
		(width 0.16002)
		(layer "In4.Cu")
		(net "M_J_CPU1_SB_DQS_DN<5>")
	)
	(segment
		(start 183.006746 -286.158178)
		(end 184.579514 -286.158178)
		(width 0.16002)
		(layer "In4.Cu")
		(net "M_J_CPU1_SB_DQS_DN<5>")
	)
	(segment
		(start 131.814824 -276.516338)
		(end 131.6609 -276.781768)
		(width 0.09525)
		(layer "In4.Cu")
		(net "M_J_CPU1_SB_DQS_DN<5>")
	)
	(segment
		(start 136.694926 -276.846284)
		(end 136.703308 -276.841458)
		(width 0.09525)
		(layer "In4.Cu")
		(net "M_J_CPU1_SB_DQS_DN<5>")
	)
	(segment
		(start 174.342298 -285.790894)
		(end 175.122586 -285.790894)
		(width 0.16002)
		(layer "In4.Cu")
		(net "M_J_CPU1_SB_DQS_DN<5>")
	)
	(segment
		(start 172.551852 -287.008316)
		(end 172.894244 -286.665924)
		(width 0.16002)
		(layer "In4.Cu")
		(net "M_J_CPU1_SB_DQS_DN<5>")
	)
	(segment
		(start 141.394942 -276.846284)
		(end 141.403324 -276.841458)
		(width 0.09525)
		(layer "In4.Cu")
		(net "M_J_CPU1_SB_DQS_DN<5>")
	)
	(segment
		(start 157.572964 -280.083514)
		(end 157.950408 -280.460958)
		(width 0.16002)
		(layer "In4.Cu")
		(net "M_J_CPU1_SB_DQS_DN<5>")
	)
	(segment
		(start 140.454888 -276.846284)
		(end 140.46327 -276.841458)
		(width 0.09525)
		(layer "In4.Cu")
		(net "M_J_CPU1_SB_DQS_DN<5>")
	)
	(segment
		(start 155.213812 -278.709882)
		(end 156.199332 -278.709882)
		(width 0.16002)
		(layer "In4.Cu")
		(net "M_J_CPU1_SB_DQS_DN<5>")
	)
	(segment
		(start 179.134516 -287.008316)
		(end 180.102256 -287.008316)
		(width 0.16002)
		(layer "In4.Cu")
		(net "M_J_CPU1_SB_DQS_DN<5>")
	)
	(segment
		(start 145.134584 -276.848316)
		(end 145.701766 -276.548596)
		(width 0.09525)
		(layer "In4.Cu")
		(net "M_J_CPU1_SB_DQS_DN<5>")
	)
	(segment
		(start 159.229552 -282.725622)
		(end 159.456628 -282.952698)
		(width 0.16002)
		(layer "In4.Cu")
		(net "M_J_CPU1_SB_DQS_DN<5>")
	)
	(segment
		(start 146.119596 -276.262846)
		(end 146.704558 -275.677884)
		(width 0.09525)
		(layer "In4.Cu")
		(net "M_J_CPU1_SB_DQS_DN<5>")
	)
	(segment
		(start 147.370292 -275.677884)
		(end 147.54479 -275.852382)
		(width 0.09525)
		(layer "In4.Cu")
		(net "M_J_CPU1_SB_DQS_DN<5>")
	)
	(segment
		(start 182.666132 -285.817564)
		(end 183.006746 -286.158178)
		(width 0.16002)
		(layer "In4.Cu")
		(net "M_J_CPU1_SB_DQS_DN<5>")
	)
	(segment
		(start 186.786266 -286.00908)
		(end 187.060078 -285.735268)
		(width 0.16002)
		(layer "In4.Cu")
		(net "M_J_CPU1_SB_DQS_DN<5>")
	)
	(segment
		(start 166.789608 -285.792164)
		(end 170.049444 -285.792164)
		(width 0.16002)
		(layer "In4.Cu")
		(net "M_J_CPU1_SB_DQS_DN<5>")
	)
	(segment
		(start 170.049444 -285.792164)
		(end 171.265596 -287.008316)
		(width 0.16002)
		(layer "In4.Cu")
		(net "M_J_CPU1_SB_DQS_DN<5>")
	)
	(segment
		(start 147.54479 -275.852382)
		(end 147.771358 -275.852382)
		(width 0.09525)
		(layer "In4.Cu")
		(net "M_J_CPU1_SB_DQS_DN<5>")
	)
	(segment
		(start 131.99491 -276.846284)
		(end 132.003292 -276.841458)
		(width 0.09525)
		(layer "In4.Cu")
		(net "M_J_CPU1_SB_DQS_DN<5>")
	)
	(segment
		(start 164.994082 -286.645604)
		(end 165.936168 -286.645604)
		(width 0.16002)
		(layer "In4.Cu")
		(net "M_J_CPU1_SB_DQS_DN<5>")
	)
	(segment
		(start 143.846042 -276.841458)
		(end 143.854424 -276.846284)
		(width 0.09525)
		(layer "In4.Cu")
		(net "M_J_CPU1_SB_DQS_DN<5>")
	)
	(segment
		(start 160.442148 -282.952698)
		(end 163.023296 -285.533846)
		(width 0.16002)
		(layer "In4.Cu")
		(net "M_J_CPU1_SB_DQS_DN<5>")
	)
	(segment
		(start 178.284378 -286.158178)
		(end 179.134516 -287.008316)
		(width 0.16002)
		(layer "In4.Cu")
		(net "M_J_CPU1_SB_DQS_DN<5>")
	)
	(segment
		(start 181.971188 -285.817564)
		(end 182.666132 -285.817564)
		(width 0.16002)
		(layer "In4.Cu")
		(net "M_J_CPU1_SB_DQS_DN<5>")
	)
	(segment
		(start 147.83054 -275.7932)
		(end 147.854162 -275.7932)
		(width 0.09525)
		(layer "In4.Cu")
		(net "M_J_CPU1_SB_DQS_DN<5>")
	)
	(segment
		(start 180.102256 -287.008316)
		(end 180.444648 -286.665924)
		(width 0.16002)
		(layer "In4.Cu")
		(net "M_J_CPU1_SB_DQS_DN<5>")
	)
	(segment
		(start 156.199332 -278.709882)
		(end 156.604208 -279.114758)
		(width 0.16002)
		(layer "In4.Cu")
		(net "M_J_CPU1_SB_DQS_DN<5>")
	)
	(segment
		(start 165.936168 -286.645604)
		(end 166.789608 -285.792164)
		(width 0.16002)
		(layer "In4.Cu")
		(net "M_J_CPU1_SB_DQS_DN<5>")
	)
	(segment
		(start 186.306206 -286.00908)
		(end 186.786266 -286.00908)
		(width 0.16002)
		(layer "In4.Cu")
		(net "M_J_CPU1_SB_DQS_DN<5>")
	)
	(segment
		(start 185.592466 -286.00908)
		(end 185.709306 -285.89224)
		(width 0.16002)
		(layer "In4.Cu")
		(net "M_J_CPU1_SB_DQS_DN<5>")
	)
	(segment
		(start 185.709306 -285.89224)
		(end 186.189366 -285.89224)
		(width 0.16002)
		(layer "In4.Cu")
		(net "M_J_CPU1_SB_DQS_DN<5>")
	)
	(segment
		(start 163.023296 -285.533846)
		(end 163.882324 -285.533846)
		(width 0.16002)
		(layer "In4.Cu")
		(net "M_J_CPU1_SB_DQS_DN<5>")
	)
	(segment
		(start 159.456628 -282.952698)
		(end 160.442148 -282.952698)
		(width 0.16002)
		(layer "In4.Cu")
		(net "M_J_CPU1_SB_DQS_DN<5>")
	)
	(segment
		(start 156.764228 -280.083514)
		(end 157.572964 -280.083514)
		(width 0.16002)
		(layer "In4.Cu")
		(net "M_J_CPU1_SB_DQS_DN<5>")
	)
	(segment
		(start 132.934964 -276.846284)
		(end 132.943346 -276.841458)
		(width 0.09525)
		(layer "In4.Cu")
		(net "M_J_CPU1_SB_DQS_DN<5>")
	)
	(segment
		(start 181.122828 -286.665924)
		(end 181.971188 -285.817564)
		(width 0.16002)
		(layer "In4.Cu")
		(net "M_J_CPU1_SB_DQS_DN<5>")
	)
	(segment
		(start 184.728612 -286.00908)
		(end 185.592466 -286.00908)
		(width 0.16002)
		(layer "In4.Cu")
		(net "M_J_CPU1_SB_DQS_DN<5>")
	)
	(segment
		(start 147.771358 -275.852382)
		(end 147.83054 -275.7932)
		(width 0.09525)
		(layer "In4.Cu")
		(net "M_J_CPU1_SB_DQS_DN<5>")
	)
	(segment
		(start 158.852108 -281.606498)
		(end 159.229552 -281.983942)
		(width 0.16002)
		(layer "In4.Cu")
		(net "M_J_CPU1_SB_DQS_DN<5>")
	)
	(segment
		(start 152.29713 -275.7932)
		(end 155.213812 -278.709882)
		(width 0.16002)
		(layer "In4.Cu")
		(net "M_J_CPU1_SB_DQS_DN<5>")
	)
	(segment
		(start 141.966188 -276.841458)
		(end 141.97457 -276.846284)
		(width 0.09525)
		(layer "In4.Cu")
		(net "M_J_CPU1_SB_DQS_DN<5>")
	)
	(segment
		(start 175.48987 -286.158178)
		(end 178.284378 -286.158178)
		(width 0.16002)
		(layer "In4.Cu")
		(net "M_J_CPU1_SB_DQS_DN<5>")
	)
	(segment
		(start 159.229552 -281.983942)
		(end 159.229552 -282.725622)
		(width 0.16002)
		(layer "In4.Cu")
		(net "M_J_CPU1_SB_DQS_DN<5>")
	)
	(segment
		(start 137.266172 -276.841458)
		(end 137.274554 -276.846284)
		(width 0.09525)
		(layer "In4.Cu")
		(net "M_J_CPU1_SB_DQS_DN<5>")
	)
	(segment
		(start 145.701766 -276.548596)
		(end 145.771362 -276.513798)
		(width 0.09525)
		(layer "In4.Cu")
		(net "M_J_CPU1_SB_DQS_DN<5>")
	)
	(segment
		(start 156.604208 -279.114758)
		(end 156.604208 -279.923494)
		(width 0.16002)
		(layer "In4.Cu")
		(net "M_J_CPU1_SB_DQS_DN<5>")
	)
	(segment
		(start 186.189366 -285.89224)
		(end 186.306206 -286.00908)
		(width 0.16002)
		(layer "In4.Cu")
		(net "M_J_CPU1_SB_DQS_DN<5>")
	)
	(segment
		(start 157.950408 -281.446478)
		(end 158.110428 -281.606498)
		(width 0.16002)
		(layer "In4.Cu")
		(net "M_J_CPU1_SB_DQS_DN<5>")
	)
	(segment
		(start 171.265596 -287.008316)
		(end 172.551852 -287.008316)
		(width 0.16002)
		(layer "In4.Cu")
		(net "M_J_CPU1_SB_DQS_DN<5>")
	)
	(segment
		(start 175.122586 -285.790894)
		(end 175.48987 -286.158178)
		(width 0.16002)
		(layer "In4.Cu")
		(net "M_J_CPU1_SB_DQS_DN<5>")
	)
	(segment
		(start 138.206226 -276.841458)
		(end 138.214608 -276.846284)
		(width 0.09525)
		(layer "In4.Cu")
		(net "M_J_CPU1_SB_DQS_DN<5>")
	)
	(segment
		(start 133.50621 -276.841458)
		(end 133.514592 -276.846284)
		(width 0.09525)
		(layer "In4.Cu")
		(net "M_J_CPU1_SB_DQS_DN<5>")
	)
	(segment
		(start 180.444648 -286.665924)
		(end 181.122828 -286.665924)
		(width 0.16002)
		(layer "In4.Cu")
		(net "M_J_CPU1_SB_DQS_DN<5>")
	)
	(segment
		(start 163.882324 -285.533846)
		(end 164.994082 -286.645604)
		(width 0.16002)
		(layer "In4.Cu")
		(net "M_J_CPU1_SB_DQS_DN<5>")
	)
	(segment
		(start 173.467268 -286.665924)
		(end 174.342298 -285.790894)
		(width 0.16002)
		(layer "In4.Cu")
		(net "M_J_CPU1_SB_DQS_DN<5>")
	)
	(segment
		(start 157.950408 -280.460958)
		(end 157.950408 -281.446478)
		(width 0.16002)
		(layer "In4.Cu")
		(net "M_J_CPU1_SB_DQS_DN<5>")
	)
	(segment
		(start 172.894244 -286.665924)
		(end 173.467268 -286.665924)
		(width 0.16002)
		(layer "In4.Cu")
		(net "M_J_CPU1_SB_DQS_DN<5>")
	)
	(segment
		(start 156.604208 -279.923494)
		(end 156.764228 -280.083514)
		(width 0.16002)
		(layer "In4.Cu")
		(net "M_J_CPU1_SB_DQS_DN<5>")
	)
	(segment
		(start 135.754872 -276.846284)
		(end 135.763254 -276.841458)
		(width 0.09525)
		(layer "In4.Cu")
		(net "M_J_CPU1_SB_DQS_DN<5>")
	)
	(segment
		(start 131.6609 -276.781768)
		(end 131.684268 -276.868636)
		(width 0.09525)
		(layer "In4.Cu")
		(net "M_J_CPU1_SB_DQS_DN<5>")
	)
	(segment
		(start 144.776444 -276.835362)
		(end 144.786858 -276.841458)
		(width 0.09525)
		(layer "In4.Cu")
		(net "M_J_CPU1_SB_DQS_DN<5>")
	)
	(segment
		(start 158.110428 -281.606498)
		(end 158.852108 -281.606498)
		(width 0.16002)
		(layer "In4.Cu")
		(net "M_J_CPU1_SB_DQS_DN<5>")
	)
	(segment
		(start 146.704558 -275.677884)
		(end 147.370292 -275.677884)
		(width 0.09525)
		(layer "In4.Cu")
		(net "M_J_CPU1_SB_DQS_DN<5>")
	)
	(segment
		(start 184.579514 -286.158178)
		(end 184.728612 -286.00908)
		(width 0.16002)
		(layer "In4.Cu")
		(net "M_J_CPU1_SB_DQS_DN<5>")
	)
	(arc
		(start 134.446264 -276.841458)
		(mid 134.634732 -276.892135)
		(end 134.8232 -276.841458)
		(width 0.09525)
		(layer "In4.Cu")
		(net "M_J_CPU1_SB_DQS_DN<5>")
	)
	(arc
		(start 145.771362 -276.513798)
		(mid 145.955571 -276.402329)
		(end 146.119596 -276.262846)
		(width 0.09525)
		(layer "In4.Cu")
		(net "M_J_CPU1_SB_DQS_DN<5>")
	)
	(arc
		(start 142.343378 -276.841458)
		(mid 142.62481 -276.765703)
		(end 142.906242 -276.841458)
		(width 0.09525)
		(layer "In4.Cu")
		(net "M_J_CPU1_SB_DQS_DN<5>")
	)
	(arc
		(start 139.14628 -276.841458)
		(mid 139.334748 -276.892135)
		(end 139.523216 -276.841458)
		(width 0.09525)
		(layer "In4.Cu")
		(net "M_J_CPU1_SB_DQS_DN<5>")
	)
	(arc
		(start 141.97457 -276.846284)
		(mid 142.159602 -276.892198)
		(end 142.343378 -276.841458)
		(width 0.09525)
		(layer "In4.Cu")
		(net "M_J_CPU1_SB_DQS_DN<5>")
	)
	(arc
		(start 139.523216 -276.841458)
		(mid 139.804648 -276.765703)
		(end 140.08608 -276.841458)
		(width 0.09525)
		(layer "In4.Cu")
		(net "M_J_CPU1_SB_DQS_DN<5>")
	)
	(arc
		(start 138.583416 -276.841458)
		(mid 138.864848 -276.765703)
		(end 139.14628 -276.841458)
		(width 0.09525)
		(layer "In4.Cu")
		(net "M_J_CPU1_SB_DQS_DN<5>")
	)
	(arc
		(start 143.283178 -276.841458)
		(mid 143.56461 -276.765703)
		(end 143.846042 -276.841458)
		(width 0.09525)
		(layer "In4.Cu")
		(net "M_J_CPU1_SB_DQS_DN<5>")
	)
	(arc
		(start 141.026134 -276.841458)
		(mid 141.209909 -276.89223)
		(end 141.394942 -276.846284)
		(width 0.09525)
		(layer "In4.Cu")
		(net "M_J_CPU1_SB_DQS_DN<5>")
	)
	(arc
		(start 144.786858 -276.841458)
		(mid 144.959839 -276.889847)
		(end 145.134584 -276.848316)
		(width 0.09525)
		(layer "In4.Cu")
		(net "M_J_CPU1_SB_DQS_DN<5>")
	)
	(arc
		(start 143.854424 -276.846284)
		(mid 144.03971 -276.89232)
		(end 144.22374 -276.841458)
		(width 0.09525)
		(layer "In4.Cu")
		(net "M_J_CPU1_SB_DQS_DN<5>")
	)
	(arc
		(start 136.703308 -276.841458)
		(mid 136.98474 -276.765703)
		(end 137.266172 -276.841458)
		(width 0.09525)
		(layer "In4.Cu")
		(net "M_J_CPU1_SB_DQS_DN<5>")
	)
	(arc
		(start 141.403324 -276.841458)
		(mid 141.684756 -276.765703)
		(end 141.966188 -276.841458)
		(width 0.09525)
		(layer "In4.Cu")
		(net "M_J_CPU1_SB_DQS_DN<5>")
	)
	(arc
		(start 133.8834 -276.841458)
		(mid 134.164832 -276.765703)
		(end 134.446264 -276.841458)
		(width 0.09525)
		(layer "In4.Cu")
		(net "M_J_CPU1_SB_DQS_DN<5>")
	)
	(arc
		(start 133.514592 -276.846284)
		(mid 133.699624 -276.892198)
		(end 133.8834 -276.841458)
		(width 0.09525)
		(layer "In4.Cu")
		(net "M_J_CPU1_SB_DQS_DN<5>")
	)
	(arc
		(start 135.386064 -276.841458)
		(mid 135.569839 -276.89223)
		(end 135.754872 -276.846284)
		(width 0.09525)
		(layer "In4.Cu")
		(net "M_J_CPU1_SB_DQS_DN<5>")
	)
	(arc
		(start 132.003292 -276.841458)
		(mid 132.284724 -276.765703)
		(end 132.566156 -276.841458)
		(width 0.09525)
		(layer "In4.Cu")
		(net "M_J_CPU1_SB_DQS_DN<5>")
	)
	(arc
		(start 132.943346 -276.841458)
		(mid 133.224778 -276.765703)
		(end 133.50621 -276.841458)
		(width 0.09525)
		(layer "In4.Cu")
		(net "M_J_CPU1_SB_DQS_DN<5>")
	)
	(arc
		(start 132.566156 -276.841458)
		(mid 132.749931 -276.89223)
		(end 132.934964 -276.846284)
		(width 0.09525)
		(layer "In4.Cu")
		(net "M_J_CPU1_SB_DQS_DN<5>")
	)
	(arc
		(start 140.46327 -276.841458)
		(mid 140.744702 -276.765703)
		(end 141.026134 -276.841458)
		(width 0.09525)
		(layer "In4.Cu")
		(net "M_J_CPU1_SB_DQS_DN<5>")
	)
	(arc
		(start 140.08608 -276.841458)
		(mid 140.269855 -276.89223)
		(end 140.454888 -276.846284)
		(width 0.09525)
		(layer "In4.Cu")
		(net "M_J_CPU1_SB_DQS_DN<5>")
	)
	(arc
		(start 137.643362 -276.841458)
		(mid 137.924794 -276.765703)
		(end 138.206226 -276.841458)
		(width 0.09525)
		(layer "In4.Cu")
		(net "M_J_CPU1_SB_DQS_DN<5>")
	)
	(arc
		(start 137.274554 -276.846284)
		(mid 137.459586 -276.892198)
		(end 137.643362 -276.841458)
		(width 0.09525)
		(layer "In4.Cu")
		(net "M_J_CPU1_SB_DQS_DN<5>")
	)
	(arc
		(start 144.22374 -276.841458)
		(mid 144.499283 -276.765609)
		(end 144.776444 -276.835362)
		(width 0.09525)
		(layer "In4.Cu")
		(net "M_J_CPU1_SB_DQS_DN<5>")
	)
	(arc
		(start 138.214608 -276.846284)
		(mid 138.39964 -276.892198)
		(end 138.583416 -276.841458)
		(width 0.09525)
		(layer "In4.Cu")
		(net "M_J_CPU1_SB_DQS_DN<5>")
	)
	(arc
		(start 136.326118 -276.841458)
		(mid 136.509893 -276.89223)
		(end 136.694926 -276.846284)
		(width 0.09525)
		(layer "In4.Cu")
		(net "M_J_CPU1_SB_DQS_DN<5>")
	)
	(arc
		(start 131.684268 -276.868636)
		(mid 131.842018 -276.891155)
		(end 131.99491 -276.846284)
		(width 0.09525)
		(layer "In4.Cu")
		(net "M_J_CPU1_SB_DQS_DN<5>")
	)
	(arc
		(start 135.763254 -276.841458)
		(mid 136.044686 -276.765703)
		(end 136.326118 -276.841458)
		(width 0.09525)
		(layer "In4.Cu")
		(net "M_J_CPU1_SB_DQS_DN<5>")
	)
	(arc
		(start 142.906242 -276.841458)
		(mid 143.09471 -276.892135)
		(end 143.283178 -276.841458)
		(width 0.09525)
		(layer "In4.Cu")
		(net "M_J_CPU1_SB_DQS_DN<5>")
	)
	(arc
		(start 134.8232 -276.841458)
		(mid 135.104632 -276.765703)
		(end 135.386064 -276.841458)
		(width 0.09525)
		(layer "In4.Cu")
		(net "M_J_CPU1_SB_DQS_DN<5>")
	)
	(segment
		(start 131.347972 -271.390364)
		(end 131.814824 -271.656302)
		(width 0.12954)
		(layer "F.Cu")
		(net "M_J_CPU1_SB_DQS_DN<4>")
	)
	(segment
		(start 161.772092 -274.317206)
		(end 162.299396 -274.317206)
		(width 0.16002)
		(layer "In4.Cu")
		(net "M_J_CPU1_SB_DQS_DN<4>")
	)
	(segment
		(start 137.266172 -271.981422)
		(end 137.274554 -271.986248)
		(width 0.09525)
		(layer "In4.Cu")
		(net "M_J_CPU1_SB_DQS_DN<4>")
	)
	(segment
		(start 143.846042 -271.981422)
		(end 143.854424 -271.986248)
		(width 0.09525)
		(layer "In4.Cu")
		(net "M_J_CPU1_SB_DQS_DN<4>")
	)
	(segment
		(start 171.060364 -277.658322)
		(end 172.551852 -277.658322)
		(width 0.16002)
		(layer "In4.Cu")
		(net "M_J_CPU1_SB_DQS_DN<4>")
	)
	(segment
		(start 174.342298 -276.4409)
		(end 175.122586 -276.4409)
		(width 0.16002)
		(layer "In4.Cu")
		(net "M_J_CPU1_SB_DQS_DN<4>")
	)
	(segment
		(start 180.102256 -277.658322)
		(end 180.444648 -277.31593)
		(width 0.16002)
		(layer "In4.Cu")
		(net "M_J_CPU1_SB_DQS_DN<4>")
	)
	(segment
		(start 185.50636 -276.659086)
		(end 185.6232 -276.542246)
		(width 0.16002)
		(layer "In4.Cu")
		(net "M_J_CPU1_SB_DQS_DN<4>")
	)
	(segment
		(start 161.572194 -274.517104)
		(end 161.772092 -274.317206)
		(width 0.16002)
		(layer "In4.Cu")
		(net "M_J_CPU1_SB_DQS_DN<4>")
	)
	(segment
		(start 183.006746 -276.808184)
		(end 184.579514 -276.808184)
		(width 0.16002)
		(layer "In4.Cu")
		(net "M_J_CPU1_SB_DQS_DN<4>")
	)
	(segment
		(start 132.934964 -271.986248)
		(end 132.943346 -271.981422)
		(width 0.09525)
		(layer "In4.Cu")
		(net "M_J_CPU1_SB_DQS_DN<4>")
	)
	(segment
		(start 131.814824 -271.656302)
		(end 131.6609 -271.921732)
		(width 0.09525)
		(layer "In4.Cu")
		(net "M_J_CPU1_SB_DQS_DN<4>")
	)
	(segment
		(start 184.728612 -276.659086)
		(end 185.50636 -276.659086)
		(width 0.16002)
		(layer "In4.Cu")
		(net "M_J_CPU1_SB_DQS_DN<4>")
	)
	(segment
		(start 161.0995 -274.04441)
		(end 161.0995 -274.32127)
		(width 0.16002)
		(layer "In4.Cu")
		(net "M_J_CPU1_SB_DQS_DN<4>")
	)
	(segment
		(start 146.942556 -270.41348)
		(end 147.15236 -270.203676)
		(width 0.09525)
		(layer "In4.Cu")
		(net "M_J_CPU1_SB_DQS_DN<4>")
	)
	(segment
		(start 162.67303 -274.69084)
		(end 162.67303 -275.218144)
		(width 0.16002)
		(layer "In4.Cu")
		(net "M_J_CPU1_SB_DQS_DN<4>")
	)
	(segment
		(start 162.945826 -275.890736)
		(end 163.145724 -275.690838)
		(width 0.16002)
		(layer "In4.Cu")
		(net "M_J_CPU1_SB_DQS_DN<4>")
	)
	(segment
		(start 161.295334 -274.517104)
		(end 161.572194 -274.517104)
		(width 0.16002)
		(layer "In4.Cu")
		(net "M_J_CPU1_SB_DQS_DN<4>")
	)
	(segment
		(start 147.15236 -270.203676)
		(end 147.72767 -270.203676)
		(width 0.09525)
		(layer "In4.Cu")
		(net "M_J_CPU1_SB_DQS_DN<4>")
	)
	(segment
		(start 162.668966 -275.890736)
		(end 162.945826 -275.890736)
		(width 0.16002)
		(layer "In4.Cu")
		(net "M_J_CPU1_SB_DQS_DN<4>")
	)
	(segment
		(start 140.454888 -271.986248)
		(end 140.46327 -271.981422)
		(width 0.09525)
		(layer "In4.Cu")
		(net "M_J_CPU1_SB_DQS_DN<4>")
	)
	(segment
		(start 179.134516 -277.658322)
		(end 180.102256 -277.658322)
		(width 0.16002)
		(layer "In4.Cu")
		(net "M_J_CPU1_SB_DQS_DN<4>")
	)
	(segment
		(start 181.971188 -276.46757)
		(end 182.666132 -276.46757)
		(width 0.16002)
		(layer "In4.Cu")
		(net "M_J_CPU1_SB_DQS_DN<4>")
	)
	(segment
		(start 175.48987 -276.808184)
		(end 178.284378 -276.808184)
		(width 0.16002)
		(layer "In4.Cu")
		(net "M_J_CPU1_SB_DQS_DN<4>")
	)
	(segment
		(start 181.122828 -277.31593)
		(end 181.971188 -276.46757)
		(width 0.16002)
		(layer "In4.Cu")
		(net "M_J_CPU1_SB_DQS_DN<4>")
	)
	(segment
		(start 147.72767 -270.203676)
		(end 147.786852 -270.144494)
		(width 0.09525)
		(layer "In4.Cu")
		(net "M_J_CPU1_SB_DQS_DN<4>")
	)
	(segment
		(start 169.844212 -276.44217)
		(end 171.060364 -277.658322)
		(width 0.16002)
		(layer "In4.Cu")
		(net "M_J_CPU1_SB_DQS_DN<4>")
	)
	(segment
		(start 178.284378 -276.808184)
		(end 179.134516 -277.658322)
		(width 0.16002)
		(layer "In4.Cu")
		(net "M_J_CPU1_SB_DQS_DN<4>")
	)
	(segment
		(start 160.39846 -272.943574)
		(end 160.925764 -272.943574)
		(width 0.16002)
		(layer "In4.Cu")
		(net "M_J_CPU1_SB_DQS_DN<4>")
	)
	(segment
		(start 147.786852 -270.144494)
		(end 147.810474 -270.144494)
		(width 0.09525)
		(layer "In4.Cu")
		(net "M_J_CPU1_SB_DQS_DN<4>")
	)
	(segment
		(start 162.473132 -275.418042)
		(end 162.473132 -275.694902)
		(width 0.16002)
		(layer "In4.Cu")
		(net "M_J_CPU1_SB_DQS_DN<4>")
	)
	(segment
		(start 159.921702 -273.143472)
		(end 160.198562 -273.143472)
		(width 0.16002)
		(layer "In4.Cu")
		(net "M_J_CPU1_SB_DQS_DN<4>")
	)
	(segment
		(start 136.694926 -271.986248)
		(end 136.703308 -271.981422)
		(width 0.09525)
		(layer "In4.Cu")
		(net "M_J_CPU1_SB_DQS_DN<4>")
	)
	(segment
		(start 131.99491 -271.986248)
		(end 132.003292 -271.981422)
		(width 0.09525)
		(layer "In4.Cu")
		(net "M_J_CPU1_SB_DQS_DN<4>")
	)
	(segment
		(start 165.936168 -277.29561)
		(end 166.789608 -276.44217)
		(width 0.16002)
		(layer "In4.Cu")
		(net "M_J_CPU1_SB_DQS_DN<4>")
	)
	(segment
		(start 165.2778 -277.29561)
		(end 165.936168 -277.29561)
		(width 0.16002)
		(layer "In4.Cu")
		(net "M_J_CPU1_SB_DQS_DN<4>")
	)
	(segment
		(start 182.666132 -276.46757)
		(end 183.006746 -276.808184)
		(width 0.16002)
		(layer "In4.Cu")
		(net "M_J_CPU1_SB_DQS_DN<4>")
	)
	(segment
		(start 141.394942 -271.986248)
		(end 141.403324 -271.981422)
		(width 0.09525)
		(layer "In4.Cu")
		(net "M_J_CPU1_SB_DQS_DN<4>")
	)
	(segment
		(start 161.299398 -273.317208)
		(end 161.299398 -273.844512)
		(width 0.16002)
		(layer "In4.Cu")
		(net "M_J_CPU1_SB_DQS_DN<4>")
	)
	(segment
		(start 161.299398 -273.844512)
		(end 161.0995 -274.04441)
		(width 0.16002)
		(layer "In4.Cu")
		(net "M_J_CPU1_SB_DQS_DN<4>")
	)
	(segment
		(start 162.299396 -274.317206)
		(end 162.67303 -274.69084)
		(width 0.16002)
		(layer "In4.Cu")
		(net "M_J_CPU1_SB_DQS_DN<4>")
	)
	(segment
		(start 162.67303 -275.218144)
		(end 162.473132 -275.418042)
		(width 0.16002)
		(layer "In4.Cu")
		(net "M_J_CPU1_SB_DQS_DN<4>")
	)
	(segment
		(start 175.122586 -276.4409)
		(end 175.48987 -276.808184)
		(width 0.16002)
		(layer "In4.Cu")
		(net "M_J_CPU1_SB_DQS_DN<4>")
	)
	(segment
		(start 173.467268 -277.31593)
		(end 174.342298 -276.4409)
		(width 0.16002)
		(layer "In4.Cu")
		(net "M_J_CPU1_SB_DQS_DN<4>")
	)
	(segment
		(start 172.551852 -277.658322)
		(end 172.894244 -277.31593)
		(width 0.16002)
		(layer "In4.Cu")
		(net "M_J_CPU1_SB_DQS_DN<4>")
	)
	(segment
		(start 144.505426 -271.905476)
		(end 144.916652 -271.905476)
		(width 0.09525)
		(layer "In4.Cu")
		(net "M_J_CPU1_SB_DQS_DN<4>")
	)
	(segment
		(start 172.894244 -277.31593)
		(end 173.467268 -277.31593)
		(width 0.16002)
		(layer "In4.Cu")
		(net "M_J_CPU1_SB_DQS_DN<4>")
	)
	(segment
		(start 147.810474 -270.144494)
		(end 156.922724 -270.144494)
		(width 0.16002)
		(layer "In4.Cu")
		(net "M_J_CPU1_SB_DQS_DN<4>")
	)
	(segment
		(start 186.2201 -276.659086)
		(end 186.786266 -276.659086)
		(width 0.16002)
		(layer "In4.Cu")
		(net "M_J_CPU1_SB_DQS_DN<4>")
	)
	(segment
		(start 163.673028 -275.690838)
		(end 165.2778 -277.29561)
		(width 0.16002)
		(layer "In4.Cu")
		(net "M_J_CPU1_SB_DQS_DN<4>")
	)
	(segment
		(start 186.786266 -276.659086)
		(end 187.060078 -276.385274)
		(width 0.16002)
		(layer "In4.Cu")
		(net "M_J_CPU1_SB_DQS_DN<4>")
	)
	(segment
		(start 131.6609 -271.921732)
		(end 131.684268 -272.0086)
		(width 0.09525)
		(layer "In4.Cu")
		(net "M_J_CPU1_SB_DQS_DN<4>")
	)
	(segment
		(start 138.206226 -271.981422)
		(end 138.214608 -271.986248)
		(width 0.09525)
		(layer "In4.Cu")
		(net "M_J_CPU1_SB_DQS_DN<4>")
	)
	(segment
		(start 146.408648 -270.41348)
		(end 146.942556 -270.41348)
		(width 0.09525)
		(layer "In4.Cu")
		(net "M_J_CPU1_SB_DQS_DN<4>")
	)
	(segment
		(start 166.789608 -276.44217)
		(end 169.844212 -276.44217)
		(width 0.16002)
		(layer "In4.Cu")
		(net "M_J_CPU1_SB_DQS_DN<4>")
	)
	(segment
		(start 186.10326 -276.542246)
		(end 186.2201 -276.659086)
		(width 0.16002)
		(layer "In4.Cu")
		(net "M_J_CPU1_SB_DQS_DN<4>")
	)
	(segment
		(start 160.198562 -273.143472)
		(end 160.39846 -272.943574)
		(width 0.16002)
		(layer "In4.Cu")
		(net "M_J_CPU1_SB_DQS_DN<4>")
	)
	(segment
		(start 185.6232 -276.542246)
		(end 186.10326 -276.542246)
		(width 0.16002)
		(layer "In4.Cu")
		(net "M_J_CPU1_SB_DQS_DN<4>")
	)
	(segment
		(start 184.579514 -276.808184)
		(end 184.728612 -276.659086)
		(width 0.16002)
		(layer "In4.Cu")
		(net "M_J_CPU1_SB_DQS_DN<4>")
	)
	(segment
		(start 141.966188 -271.981422)
		(end 141.97457 -271.986248)
		(width 0.09525)
		(layer "In4.Cu")
		(net "M_J_CPU1_SB_DQS_DN<4>")
	)
	(segment
		(start 135.754872 -271.986248)
		(end 135.763254 -271.981422)
		(width 0.09525)
		(layer "In4.Cu")
		(net "M_J_CPU1_SB_DQS_DN<4>")
	)
	(segment
		(start 163.145724 -275.690838)
		(end 163.673028 -275.690838)
		(width 0.16002)
		(layer "In4.Cu")
		(net "M_J_CPU1_SB_DQS_DN<4>")
	)
	(segment
		(start 161.0995 -274.32127)
		(end 161.295334 -274.517104)
		(width 0.16002)
		(layer "In4.Cu")
		(net "M_J_CPU1_SB_DQS_DN<4>")
	)
	(segment
		(start 156.922724 -270.144494)
		(end 159.921702 -273.143472)
		(width 0.16002)
		(layer "In4.Cu")
		(net "M_J_CPU1_SB_DQS_DN<4>")
	)
	(segment
		(start 180.444648 -277.31593)
		(end 181.122828 -277.31593)
		(width 0.16002)
		(layer "In4.Cu")
		(net "M_J_CPU1_SB_DQS_DN<4>")
	)
	(segment
		(start 160.925764 -272.943574)
		(end 161.299398 -273.317208)
		(width 0.16002)
		(layer "In4.Cu")
		(net "M_J_CPU1_SB_DQS_DN<4>")
	)
	(segment
		(start 162.473132 -275.694902)
		(end 162.668966 -275.890736)
		(width 0.16002)
		(layer "In4.Cu")
		(net "M_J_CPU1_SB_DQS_DN<4>")
	)
	(segment
		(start 144.916652 -271.905476)
		(end 146.408648 -270.41348)
		(width 0.09525)
		(layer "In4.Cu")
		(net "M_J_CPU1_SB_DQS_DN<4>")
	)
	(segment
		(start 133.50621 -271.981422)
		(end 133.514592 -271.986248)
		(width 0.09525)
		(layer "In4.Cu")
		(net "M_J_CPU1_SB_DQS_DN<4>")
	)
	(arc
		(start 141.026134 -271.981422)
		(mid 141.209909 -272.032194)
		(end 141.394942 -271.986248)
		(width 0.09525)
		(layer "In4.Cu")
		(net "M_J_CPU1_SB_DQS_DN<4>")
	)
	(arc
		(start 141.403324 -271.981422)
		(mid 141.684756 -271.905667)
		(end 141.966188 -271.981422)
		(width 0.09525)
		(layer "In4.Cu")
		(net "M_J_CPU1_SB_DQS_DN<4>")
	)
	(arc
		(start 137.643362 -271.981422)
		(mid 137.924794 -271.905667)
		(end 138.206226 -271.981422)
		(width 0.09525)
		(layer "In4.Cu")
		(net "M_J_CPU1_SB_DQS_DN<4>")
	)
	(arc
		(start 135.763254 -271.981422)
		(mid 136.044686 -271.905667)
		(end 136.326118 -271.981422)
		(width 0.09525)
		(layer "In4.Cu")
		(net "M_J_CPU1_SB_DQS_DN<4>")
	)
	(arc
		(start 141.97457 -271.986248)
		(mid 142.159602 -272.032162)
		(end 142.343378 -271.981422)
		(width 0.09525)
		(layer "In4.Cu")
		(net "M_J_CPU1_SB_DQS_DN<4>")
	)
	(arc
		(start 143.854424 -271.986248)
		(mid 144.03971 -272.032284)
		(end 144.22374 -271.981422)
		(width 0.09525)
		(layer "In4.Cu")
		(net "M_J_CPU1_SB_DQS_DN<4>")
	)
	(arc
		(start 140.46327 -271.981422)
		(mid 140.744702 -271.905667)
		(end 141.026134 -271.981422)
		(width 0.09525)
		(layer "In4.Cu")
		(net "M_J_CPU1_SB_DQS_DN<4>")
	)
	(arc
		(start 140.08608 -271.981422)
		(mid 140.269855 -272.032194)
		(end 140.454888 -271.986248)
		(width 0.09525)
		(layer "In4.Cu")
		(net "M_J_CPU1_SB_DQS_DN<4>")
	)
	(arc
		(start 132.566156 -271.981422)
		(mid 132.749931 -272.032194)
		(end 132.934964 -271.986248)
		(width 0.09525)
		(layer "In4.Cu")
		(net "M_J_CPU1_SB_DQS_DN<4>")
	)
	(arc
		(start 136.326118 -271.981422)
		(mid 136.509893 -272.032194)
		(end 136.694926 -271.986248)
		(width 0.09525)
		(layer "In4.Cu")
		(net "M_J_CPU1_SB_DQS_DN<4>")
	)
	(arc
		(start 138.214608 -271.986248)
		(mid 138.39964 -272.032162)
		(end 138.583416 -271.981422)
		(width 0.09525)
		(layer "In4.Cu")
		(net "M_J_CPU1_SB_DQS_DN<4>")
	)
	(arc
		(start 139.523216 -271.981422)
		(mid 139.804648 -271.905667)
		(end 140.08608 -271.981422)
		(width 0.09525)
		(layer "In4.Cu")
		(net "M_J_CPU1_SB_DQS_DN<4>")
	)
	(arc
		(start 132.943346 -271.981422)
		(mid 133.224778 -271.905667)
		(end 133.50621 -271.981422)
		(width 0.09525)
		(layer "In4.Cu")
		(net "M_J_CPU1_SB_DQS_DN<4>")
	)
	(arc
		(start 138.583416 -271.981422)
		(mid 138.864848 -271.905667)
		(end 139.14628 -271.981422)
		(width 0.09525)
		(layer "In4.Cu")
		(net "M_J_CPU1_SB_DQS_DN<4>")
	)
	(arc
		(start 144.22374 -271.981422)
		(mid 144.359559 -271.924806)
		(end 144.505426 -271.905476)
		(width 0.09525)
		(layer "In4.Cu")
		(net "M_J_CPU1_SB_DQS_DN<4>")
	)
	(arc
		(start 134.8232 -271.981422)
		(mid 135.104632 -271.905667)
		(end 135.386064 -271.981422)
		(width 0.09525)
		(layer "In4.Cu")
		(net "M_J_CPU1_SB_DQS_DN<4>")
	)
	(arc
		(start 137.274554 -271.986248)
		(mid 137.459586 -272.032162)
		(end 137.643362 -271.981422)
		(width 0.09525)
		(layer "In4.Cu")
		(net "M_J_CPU1_SB_DQS_DN<4>")
	)
	(arc
		(start 132.003292 -271.981422)
		(mid 132.284724 -271.905667)
		(end 132.566156 -271.981422)
		(width 0.09525)
		(layer "In4.Cu")
		(net "M_J_CPU1_SB_DQS_DN<4>")
	)
	(arc
		(start 142.343378 -271.981422)
		(mid 142.62481 -271.905667)
		(end 142.906242 -271.981422)
		(width 0.09525)
		(layer "In4.Cu")
		(net "M_J_CPU1_SB_DQS_DN<4>")
	)
	(arc
		(start 133.514592 -271.986248)
		(mid 133.699624 -272.032162)
		(end 133.8834 -271.981422)
		(width 0.09525)
		(layer "In4.Cu")
		(net "M_J_CPU1_SB_DQS_DN<4>")
	)
	(arc
		(start 136.703308 -271.981422)
		(mid 136.98474 -271.905667)
		(end 137.266172 -271.981422)
		(width 0.09525)
		(layer "In4.Cu")
		(net "M_J_CPU1_SB_DQS_DN<4>")
	)
	(arc
		(start 135.386064 -271.981422)
		(mid 135.569839 -272.032194)
		(end 135.754872 -271.986248)
		(width 0.09525)
		(layer "In4.Cu")
		(net "M_J_CPU1_SB_DQS_DN<4>")
	)
	(arc
		(start 139.14628 -271.981422)
		(mid 139.334748 -272.032099)
		(end 139.523216 -271.981422)
		(width 0.09525)
		(layer "In4.Cu")
		(net "M_J_CPU1_SB_DQS_DN<4>")
	)
	(arc
		(start 133.8834 -271.981422)
		(mid 134.164832 -271.905667)
		(end 134.446264 -271.981422)
		(width 0.09525)
		(layer "In4.Cu")
		(net "M_J_CPU1_SB_DQS_DN<4>")
	)
	(arc
		(start 134.446264 -271.981422)
		(mid 134.634732 -272.032099)
		(end 134.8232 -271.981422)
		(width 0.09525)
		(layer "In4.Cu")
		(net "M_J_CPU1_SB_DQS_DN<4>")
	)
	(arc
		(start 131.684268 -272.0086)
		(mid 131.842018 -272.031119)
		(end 131.99491 -271.986248)
		(width 0.09525)
		(layer "In4.Cu")
		(net "M_J_CPU1_SB_DQS_DN<4>")
	)
	(arc
		(start 142.906242 -271.981422)
		(mid 143.09471 -272.032099)
		(end 143.283178 -271.981422)
		(width 0.09525)
		(layer "In4.Cu")
		(net "M_J_CPU1_SB_DQS_DN<4>")
	)
	(arc
		(start 143.283178 -271.981422)
		(mid 143.56461 -271.905667)
		(end 143.846042 -271.981422)
		(width 0.09525)
		(layer "In4.Cu")
		(net "M_J_CPU1_SB_DQS_DN<4>")
	)
	(segment
		(start 132.287772 -290.830254)
		(end 132.754878 -291.096192)
		(width 0.12954)
		(layer "F.Cu")
		(net "M_J_CPU1_SB_DQS_DN<3>")
	)
	(segment
		(start 147.033234 -293.881556)
		(end 147.049998 -293.89832)
		(width 0.09525)
		(layer "In4.Cu")
		(net "M_J_CPU1_SB_DQS_DN<3>")
	)
	(segment
		(start 136.694926 -290.766246)
		(end 136.703308 -290.771072)
		(width 0.09525)
		(layer "In4.Cu")
		(net "M_J_CPU1_SB_DQS_DN<3>")
	)
	(segment
		(start 146.34591 -293.111174)
		(end 147.033488 -293.798752)
		(width 0.09525)
		(layer "In4.Cu")
		(net "M_J_CPU1_SB_DQS_DN<3>")
	)
	(segment
		(start 138.206226 -290.771072)
		(end 138.214608 -290.766246)
		(width 0.09525)
		(layer "In4.Cu")
		(net "M_J_CPU1_SB_DQS_DN<3>")
	)
	(segment
		(start 177.141886 -312.512456)
		(end 177.991516 -313.362086)
		(width 0.16002)
		(layer "In4.Cu")
		(net "M_J_CPU1_SB_DQS_DN<3>")
	)
	(segment
		(start 188.70803 -313.697366)
		(end 188.893958 -313.511438)
		(width 0.16002)
		(layer "In4.Cu")
		(net "M_J_CPU1_SB_DQS_DN<3>")
	)
	(segment
		(start 181.352952 -313.674506)
		(end 181.896258 -313.1312)
		(width 0.16002)
		(layer "In4.Cu")
		(net "M_J_CPU1_SB_DQS_DN<3>")
	)
	(segment
		(start 172.627036 -313.697366)
		(end 173.646592 -313.697366)
		(width 0.16002)
		(layer "In4.Cu")
		(net "M_J_CPU1_SB_DQS_DN<3>")
	)
	(segment
		(start 185.372756 -313.293506)
		(end 187.410344 -313.293506)
		(width 0.16002)
		(layer "In4.Cu")
		(net "M_J_CPU1_SB_DQS_DN<3>")
	)
	(segment
		(start 135.754872 -290.766246)
		(end 135.763254 -290.771072)
		(width 0.09525)
		(layer "In4.Cu")
		(net "M_J_CPU1_SB_DQS_DN<3>")
	)
	(segment
		(start 174.153322 -313.190636)
		(end 175.077374 -313.190636)
		(width 0.16002)
		(layer "In4.Cu")
		(net "M_J_CPU1_SB_DQS_DN<3>")
	)
	(segment
		(start 141.966188 -290.771072)
		(end 141.97457 -290.766246)
		(width 0.09525)
		(layer "In4.Cu")
		(net "M_J_CPU1_SB_DQS_DN<3>")
	)
	(segment
		(start 166.112444 -313.707526)
		(end 166.897304 -312.922666)
		(width 0.16002)
		(layer "In4.Cu")
		(net "M_J_CPU1_SB_DQS_DN<3>")
	)
	(segment
		(start 187.410344 -313.293506)
		(end 187.814204 -313.697366)
		(width 0.16002)
		(layer "In4.Cu")
		(net "M_J_CPU1_SB_DQS_DN<3>")
	)
	(segment
		(start 165.380924 -313.707526)
		(end 166.112444 -313.707526)
		(width 0.16002)
		(layer "In4.Cu")
		(net "M_J_CPU1_SB_DQS_DN<3>")
	)
	(segment
		(start 190.886334 -313.511438)
		(end 191.160146 -313.78525)
		(width 0.16002)
		(layer "In4.Cu")
		(net "M_J_CPU1_SB_DQS_DN<3>")
	)
	(segment
		(start 175.755554 -312.512456)
		(end 177.141886 -312.512456)
		(width 0.16002)
		(layer "In4.Cu")
		(net "M_J_CPU1_SB_DQS_DN<3>")
	)
	(segment
		(start 188.893958 -313.511438)
		(end 190.886334 -313.511438)
		(width 0.16002)
		(layer "In4.Cu")
		(net "M_J_CPU1_SB_DQS_DN<3>")
	)
	(segment
		(start 181.896258 -313.1312)
		(end 182.45201 -313.1312)
		(width 0.16002)
		(layer "In4.Cu")
		(net "M_J_CPU1_SB_DQS_DN<3>")
	)
	(segment
		(start 145.498312 -291.088318)
		(end 146.34591 -293.111174)
		(width 0.09525)
		(layer "In4.Cu")
		(net "M_J_CPU1_SB_DQS_DN<3>")
	)
	(segment
		(start 184.591706 -312.512456)
		(end 185.372756 -313.293506)
		(width 0.16002)
		(layer "In4.Cu")
		(net "M_J_CPU1_SB_DQS_DN<3>")
	)
	(segment
		(start 147.049998 -293.89832)
		(end 147.96643 -294.814752)
		(width 0.16002)
		(layer "In4.Cu")
		(net "M_J_CPU1_SB_DQS_DN<3>")
	)
	(segment
		(start 132.754878 -291.096192)
		(end 132.908802 -290.830762)
		(width 0.09525)
		(layer "In4.Cu")
		(net "M_J_CPU1_SB_DQS_DN<3>")
	)
	(segment
		(start 177.991516 -313.362086)
		(end 180.063648 -313.362086)
		(width 0.16002)
		(layer "In4.Cu")
		(net "M_J_CPU1_SB_DQS_DN<3>")
	)
	(segment
		(start 141.394942 -290.766246)
		(end 141.403324 -290.771072)
		(width 0.09525)
		(layer "In4.Cu")
		(net "M_J_CPU1_SB_DQS_DN<3>")
	)
	(segment
		(start 144.205706 -290.76142)
		(end 144.22247 -290.771072)
		(width 0.09525)
		(layer "In4.Cu")
		(net "M_J_CPU1_SB_DQS_DN<3>")
	)
	(segment
		(start 169.945304 -312.922666)
		(end 170.384978 -313.36234)
		(width 0.16002)
		(layer "In4.Cu")
		(net "M_J_CPU1_SB_DQS_DN<3>")
	)
	(segment
		(start 182.45201 -313.1312)
		(end 183.070754 -312.512456)
		(width 0.16002)
		(layer "In4.Cu")
		(net "M_J_CPU1_SB_DQS_DN<3>")
	)
	(segment
		(start 137.266172 -290.771072)
		(end 137.274554 -290.766246)
		(width 0.09525)
		(layer "In4.Cu")
		(net "M_J_CPU1_SB_DQS_DN<3>")
	)
	(segment
		(start 144.22247 -290.771072)
		(end 144.24787 -290.785804)
		(width 0.09525)
		(layer "In4.Cu")
		(net "M_J_CPU1_SB_DQS_DN<3>")
	)
	(segment
		(start 160.138364 -313.37123)
		(end 165.044628 -313.37123)
		(width 0.16002)
		(layer "In4.Cu")
		(net "M_J_CPU1_SB_DQS_DN<3>")
	)
	(segment
		(start 183.070754 -312.512456)
		(end 184.591706 -312.512456)
		(width 0.16002)
		(layer "In4.Cu")
		(net "M_J_CPU1_SB_DQS_DN<3>")
	)
	(segment
		(start 145.240502 -290.830508)
		(end 145.498312 -291.088318)
		(width 0.09525)
		(layer "In4.Cu")
		(net "M_J_CPU1_SB_DQS_DN<3>")
	)
	(segment
		(start 166.897304 -312.922666)
		(end 169.945304 -312.922666)
		(width 0.16002)
		(layer "In4.Cu")
		(net "M_J_CPU1_SB_DQS_DN<3>")
	)
	(segment
		(start 165.044628 -313.37123)
		(end 165.380924 -313.707526)
		(width 0.16002)
		(layer "In4.Cu")
		(net "M_J_CPU1_SB_DQS_DN<3>")
	)
	(segment
		(start 140.454888 -290.766246)
		(end 140.46327 -290.771072)
		(width 0.09525)
		(layer "In4.Cu")
		(net "M_J_CPU1_SB_DQS_DN<3>")
	)
	(segment
		(start 144.78381 -290.771072)
		(end 144.802606 -290.76015)
		(width 0.09525)
		(layer "In4.Cu")
		(net "M_J_CPU1_SB_DQS_DN<3>")
	)
	(segment
		(start 187.814204 -313.697366)
		(end 188.70803 -313.697366)
		(width 0.16002)
		(layer "In4.Cu")
		(net "M_J_CPU1_SB_DQS_DN<3>")
	)
	(segment
		(start 147.96643 -301.199296)
		(end 160.138364 -313.37123)
		(width 0.16002)
		(layer "In4.Cu")
		(net "M_J_CPU1_SB_DQS_DN<3>")
	)
	(segment
		(start 172.29201 -313.36234)
		(end 172.627036 -313.697366)
		(width 0.16002)
		(layer "In4.Cu")
		(net "M_J_CPU1_SB_DQS_DN<3>")
	)
	(segment
		(start 180.063648 -313.362086)
		(end 180.376068 -313.674506)
		(width 0.16002)
		(layer "In4.Cu")
		(net "M_J_CPU1_SB_DQS_DN<3>")
	)
	(segment
		(start 170.384978 -313.36234)
		(end 172.29201 -313.36234)
		(width 0.16002)
		(layer "In4.Cu")
		(net "M_J_CPU1_SB_DQS_DN<3>")
	)
	(segment
		(start 132.908802 -290.830762)
		(end 133.00964 -290.804092)
		(width 0.09525)
		(layer "In4.Cu")
		(net "M_J_CPU1_SB_DQS_DN<3>")
	)
	(segment
		(start 133.50621 -290.771072)
		(end 133.514592 -290.766246)
		(width 0.09525)
		(layer "In4.Cu")
		(net "M_J_CPU1_SB_DQS_DN<3>")
	)
	(segment
		(start 180.376068 -313.674506)
		(end 181.352952 -313.674506)
		(width 0.16002)
		(layer "In4.Cu")
		(net "M_J_CPU1_SB_DQS_DN<3>")
	)
	(segment
		(start 147.033488 -293.798752)
		(end 147.033234 -293.881556)
		(width 0.09525)
		(layer "In4.Cu")
		(net "M_J_CPU1_SB_DQS_DN<3>")
	)
	(segment
		(start 175.077374 -313.190636)
		(end 175.755554 -312.512456)
		(width 0.16002)
		(layer "In4.Cu")
		(net "M_J_CPU1_SB_DQS_DN<3>")
	)
	(segment
		(start 173.646592 -313.697366)
		(end 174.153322 -313.190636)
		(width 0.16002)
		(layer "In4.Cu")
		(net "M_J_CPU1_SB_DQS_DN<3>")
	)
	(segment
		(start 147.96643 -294.814752)
		(end 147.96643 -301.199296)
		(width 0.16002)
		(layer "In4.Cu")
		(net "M_J_CPU1_SB_DQS_DN<3>")
	)
	(arc
		(start 142.343378 -290.771072)
		(mid 142.62481 -290.846827)
		(end 142.906242 -290.771072)
		(width 0.09525)
		(layer "In4.Cu")
		(net "M_J_CPU1_SB_DQS_DN<3>")
	)
	(arc
		(start 144.24787 -290.785804)
		(mid 144.517724 -290.846683)
		(end 144.78381 -290.771072)
		(width 0.09525)
		(layer "In4.Cu")
		(net "M_J_CPU1_SB_DQS_DN<3>")
	)
	(arc
		(start 134.8232 -290.771072)
		(mid 135.104632 -290.846827)
		(end 135.386064 -290.771072)
		(width 0.09525)
		(layer "In4.Cu")
		(net "M_J_CPU1_SB_DQS_DN<3>")
	)
	(arc
		(start 143.283178 -290.771072)
		(mid 143.56461 -290.846827)
		(end 143.846042 -290.771072)
		(width 0.09525)
		(layer "In4.Cu")
		(net "M_J_CPU1_SB_DQS_DN<3>")
	)
	(arc
		(start 141.403324 -290.771072)
		(mid 141.684756 -290.846827)
		(end 141.966188 -290.771072)
		(width 0.09525)
		(layer "In4.Cu")
		(net "M_J_CPU1_SB_DQS_DN<3>")
	)
	(arc
		(start 143.846042 -290.771072)
		(mid 144.024648 -290.720404)
		(end 144.205706 -290.76142)
		(width 0.09525)
		(layer "In4.Cu")
		(net "M_J_CPU1_SB_DQS_DN<3>")
	)
	(arc
		(start 133.00964 -290.804092)
		(mid 133.019508 -290.808123)
		(end 133.029452 -290.811966)
		(width 0.09525)
		(layer "In4.Cu")
		(net "M_J_CPU1_SB_DQS_DN<3>")
	)
	(arc
		(start 134.446264 -290.771072)
		(mid 134.634732 -290.720395)
		(end 134.8232 -290.771072)
		(width 0.09525)
		(layer "In4.Cu")
		(net "M_J_CPU1_SB_DQS_DN<3>")
	)
	(arc
		(start 136.703308 -290.771072)
		(mid 136.98474 -290.846827)
		(end 137.266172 -290.771072)
		(width 0.09525)
		(layer "In4.Cu")
		(net "M_J_CPU1_SB_DQS_DN<3>")
	)
	(arc
		(start 144.802606 -290.76015)
		(mid 144.983701 -290.719918)
		(end 145.162016 -290.771072)
		(width 0.09525)
		(layer "In4.Cu")
		(net "M_J_CPU1_SB_DQS_DN<3>")
	)
	(arc
		(start 133.8834 -290.771072)
		(mid 134.164832 -290.846827)
		(end 134.446264 -290.771072)
		(width 0.09525)
		(layer "In4.Cu")
		(net "M_J_CPU1_SB_DQS_DN<3>")
	)
	(arc
		(start 138.214608 -290.766246)
		(mid 138.39964 -290.720332)
		(end 138.583416 -290.771072)
		(width 0.09525)
		(layer "In4.Cu")
		(net "M_J_CPU1_SB_DQS_DN<3>")
	)
	(arc
		(start 141.026134 -290.771072)
		(mid 141.209909 -290.7203)
		(end 141.394942 -290.766246)
		(width 0.09525)
		(layer "In4.Cu")
		(net "M_J_CPU1_SB_DQS_DN<3>")
	)
	(arc
		(start 139.14628 -290.771072)
		(mid 139.334748 -290.720395)
		(end 139.523216 -290.771072)
		(width 0.09525)
		(layer "In4.Cu")
		(net "M_J_CPU1_SB_DQS_DN<3>")
	)
	(arc
		(start 139.523216 -290.771072)
		(mid 139.804648 -290.846827)
		(end 140.08608 -290.771072)
		(width 0.09525)
		(layer "In4.Cu")
		(net "M_J_CPU1_SB_DQS_DN<3>")
	)
	(arc
		(start 137.643362 -290.771072)
		(mid 137.924794 -290.846827)
		(end 138.206226 -290.771072)
		(width 0.09525)
		(layer "In4.Cu")
		(net "M_J_CPU1_SB_DQS_DN<3>")
	)
	(arc
		(start 141.97457 -290.766246)
		(mid 142.159602 -290.720332)
		(end 142.343378 -290.771072)
		(width 0.09525)
		(layer "In4.Cu")
		(net "M_J_CPU1_SB_DQS_DN<3>")
	)
	(arc
		(start 135.386064 -290.771072)
		(mid 135.569839 -290.7203)
		(end 135.754872 -290.766246)
		(width 0.09525)
		(layer "In4.Cu")
		(net "M_J_CPU1_SB_DQS_DN<3>")
	)
	(arc
		(start 138.583416 -290.771072)
		(mid 138.864848 -290.846827)
		(end 139.14628 -290.771072)
		(width 0.09525)
		(layer "In4.Cu")
		(net "M_J_CPU1_SB_DQS_DN<3>")
	)
	(arc
		(start 133.514592 -290.766246)
		(mid 133.699624 -290.720332)
		(end 133.8834 -290.771072)
		(width 0.09525)
		(layer "In4.Cu")
		(net "M_J_CPU1_SB_DQS_DN<3>")
	)
	(arc
		(start 136.326118 -290.771072)
		(mid 136.509893 -290.7203)
		(end 136.694926 -290.766246)
		(width 0.09525)
		(layer "In4.Cu")
		(net "M_J_CPU1_SB_DQS_DN<3>")
	)
	(arc
		(start 140.08608 -290.771072)
		(mid 140.269855 -290.7203)
		(end 140.454888 -290.766246)
		(width 0.09525)
		(layer "In4.Cu")
		(net "M_J_CPU1_SB_DQS_DN<3>")
	)
	(arc
		(start 137.274554 -290.766246)
		(mid 137.459586 -290.720332)
		(end 137.643362 -290.771072)
		(width 0.09525)
		(layer "In4.Cu")
		(net "M_J_CPU1_SB_DQS_DN<3>")
	)
	(arc
		(start 140.46327 -290.771072)
		(mid 140.744702 -290.846827)
		(end 141.026134 -290.771072)
		(width 0.09525)
		(layer "In4.Cu")
		(net "M_J_CPU1_SB_DQS_DN<3>")
	)
	(arc
		(start 145.162016 -290.771072)
		(mid 145.203216 -290.798206)
		(end 145.240502 -290.830508)
		(width 0.09525)
		(layer "In4.Cu")
		(net "M_J_CPU1_SB_DQS_DN<3>")
	)
	(arc
		(start 142.906242 -290.771072)
		(mid 143.09471 -290.720395)
		(end 143.283178 -290.771072)
		(width 0.09525)
		(layer "In4.Cu")
		(net "M_J_CPU1_SB_DQS_DN<3>")
	)
	(arc
		(start 133.029452 -290.811966)
		(mid 133.272416 -290.844953)
		(end 133.50621 -290.771072)
		(width 0.09525)
		(layer "In4.Cu")
		(net "M_J_CPU1_SB_DQS_DN<3>")
	)
	(arc
		(start 135.763254 -290.771072)
		(mid 136.044686 -290.846827)
		(end 136.326118 -290.771072)
		(width 0.09525)
		(layer "In4.Cu")
		(net "M_J_CPU1_SB_DQS_DN<3>")
	)
	(segment
		(start 132.287772 -285.970472)
		(end 132.754878 -286.23641)
		(width 0.12954)
		(layer "F.Cu")
		(net "M_J_CPU1_SB_DQS_DN<2>")
	)
	(segment
		(start 177.141886 -303.162462)
		(end 177.99177 -304.012346)
		(width 0.16002)
		(layer "In4.Cu")
		(net "M_J_CPU1_SB_DQS_DN<2>")
	)
	(segment
		(start 141.394942 -285.906464)
		(end 141.403324 -285.91129)
		(width 0.09525)
		(layer "In4.Cu")
		(net "M_J_CPU1_SB_DQS_DN<2>")
	)
	(segment
		(start 137.266172 -285.91129)
		(end 137.274554 -285.906464)
		(width 0.09525)
		(layer "In4.Cu")
		(net "M_J_CPU1_SB_DQS_DN<2>")
	)
	(segment
		(start 180.376068 -304.324512)
		(end 181.352952 -304.324512)
		(width 0.16002)
		(layer "In4.Cu")
		(net "M_J_CPU1_SB_DQS_DN<2>")
	)
	(segment
		(start 147.320508 -286.563054)
		(end 147.623276 -286.865822)
		(width 0.09525)
		(layer "In4.Cu")
		(net "M_J_CPU1_SB_DQS_DN<2>")
	)
	(segment
		(start 141.966188 -285.91129)
		(end 141.97457 -285.906464)
		(width 0.09525)
		(layer "In4.Cu")
		(net "M_J_CPU1_SB_DQS_DN<2>")
	)
	(segment
		(start 135.754872 -285.906464)
		(end 135.763254 -285.91129)
		(width 0.09525)
		(layer "In4.Cu")
		(net "M_J_CPU1_SB_DQS_DN<2>")
	)
	(segment
		(start 181.352952 -304.324512)
		(end 181.896258 -303.781206)
		(width 0.16002)
		(layer "In4.Cu")
		(net "M_J_CPU1_SB_DQS_DN<2>")
	)
	(segment
		(start 174.153322 -303.840642)
		(end 175.077374 -303.840642)
		(width 0.16002)
		(layer "In4.Cu")
		(net "M_J_CPU1_SB_DQS_DN<2>")
	)
	(segment
		(start 183.070754 -303.162462)
		(end 184.591706 -303.162462)
		(width 0.16002)
		(layer "In4.Cu")
		(net "M_J_CPU1_SB_DQS_DN<2>")
	)
	(segment
		(start 147.623276 -286.865822)
		(end 147.801584 -286.865822)
		(width 0.09525)
		(layer "In4.Cu")
		(net "M_J_CPU1_SB_DQS_DN<2>")
	)
	(segment
		(start 132.908802 -285.97098)
		(end 133.00964 -285.94431)
		(width 0.09525)
		(layer "In4.Cu")
		(net "M_J_CPU1_SB_DQS_DN<2>")
	)
	(segment
		(start 187.814204 -304.347372)
		(end 188.980826 -304.347372)
		(width 0.16002)
		(layer "In4.Cu")
		(net "M_J_CPU1_SB_DQS_DN<2>")
	)
	(segment
		(start 153.50363 -297.80865)
		(end 159.71647 -304.02149)
		(width 0.16002)
		(layer "In4.Cu")
		(net "M_J_CPU1_SB_DQS_DN<2>")
	)
	(segment
		(start 172.29201 -304.012346)
		(end 172.627036 -304.347372)
		(width 0.16002)
		(layer "In4.Cu")
		(net "M_J_CPU1_SB_DQS_DN<2>")
	)
	(segment
		(start 169.945304 -303.572672)
		(end 170.384978 -304.012346)
		(width 0.16002)
		(layer "In4.Cu")
		(net "M_J_CPU1_SB_DQS_DN<2>")
	)
	(segment
		(start 159.71647 -304.02149)
		(end 164.940234 -304.02149)
		(width 0.16002)
		(layer "In4.Cu")
		(net "M_J_CPU1_SB_DQS_DN<2>")
	)
	(segment
		(start 180.063902 -304.012346)
		(end 180.376068 -304.324512)
		(width 0.16002)
		(layer "In4.Cu")
		(net "M_J_CPU1_SB_DQS_DN<2>")
	)
	(segment
		(start 188.980826 -304.347372)
		(end 189.166754 -304.161444)
		(width 0.16002)
		(layer "In4.Cu")
		(net "M_J_CPU1_SB_DQS_DN<2>")
	)
	(segment
		(start 165.276276 -304.357532)
		(end 166.112444 -304.357532)
		(width 0.16002)
		(layer "In4.Cu")
		(net "M_J_CPU1_SB_DQS_DN<2>")
	)
	(segment
		(start 147.860512 -286.92475)
		(end 147.884134 -286.92475)
		(width 0.09525)
		(layer "In4.Cu")
		(net "M_J_CPU1_SB_DQS_DN<2>")
	)
	(segment
		(start 132.754878 -286.23641)
		(end 132.908802 -285.97098)
		(width 0.09525)
		(layer "In4.Cu")
		(net "M_J_CPU1_SB_DQS_DN<2>")
	)
	(segment
		(start 173.646592 -304.347372)
		(end 174.153322 -303.840642)
		(width 0.16002)
		(layer "In4.Cu")
		(net "M_J_CPU1_SB_DQS_DN<2>")
	)
	(segment
		(start 175.077374 -303.840642)
		(end 175.755554 -303.162462)
		(width 0.16002)
		(layer "In4.Cu")
		(net "M_J_CPU1_SB_DQS_DN<2>")
	)
	(segment
		(start 136.694926 -285.906464)
		(end 136.703308 -285.91129)
		(width 0.09525)
		(layer "In4.Cu")
		(net "M_J_CPU1_SB_DQS_DN<2>")
	)
	(segment
		(start 166.112444 -304.357532)
		(end 166.897304 -303.572672)
		(width 0.16002)
		(layer "In4.Cu")
		(net "M_J_CPU1_SB_DQS_DN<2>")
	)
	(segment
		(start 190.886334 -304.161444)
		(end 191.160146 -304.435256)
		(width 0.16002)
		(layer "In4.Cu")
		(net "M_J_CPU1_SB_DQS_DN<2>")
	)
	(segment
		(start 146.203162 -285.987744)
		(end 146.778472 -286.563054)
		(width 0.09525)
		(layer "In4.Cu")
		(net "M_J_CPU1_SB_DQS_DN<2>")
	)
	(segment
		(start 172.627036 -304.347372)
		(end 173.646592 -304.347372)
		(width 0.16002)
		(layer "In4.Cu")
		(net "M_J_CPU1_SB_DQS_DN<2>")
	)
	(segment
		(start 177.99177 -304.012346)
		(end 180.063902 -304.012346)
		(width 0.16002)
		(layer "In4.Cu")
		(net "M_J_CPU1_SB_DQS_DN<2>")
	)
	(segment
		(start 182.45201 -303.781206)
		(end 183.070754 -303.162462)
		(width 0.16002)
		(layer "In4.Cu")
		(net "M_J_CPU1_SB_DQS_DN<2>")
	)
	(segment
		(start 138.206226 -285.91129)
		(end 138.214608 -285.906464)
		(width 0.09525)
		(layer "In4.Cu")
		(net "M_J_CPU1_SB_DQS_DN<2>")
	)
	(segment
		(start 148.067268 -286.92475)
		(end 153.50363 -292.361112)
		(width 0.16002)
		(layer "In4.Cu")
		(net "M_J_CPU1_SB_DQS_DN<2>")
	)
	(segment
		(start 184.591706 -303.162462)
		(end 185.372756 -303.943512)
		(width 0.16002)
		(layer "In4.Cu")
		(net "M_J_CPU1_SB_DQS_DN<2>")
	)
	(segment
		(start 166.897304 -303.572672)
		(end 169.945304 -303.572672)
		(width 0.16002)
		(layer "In4.Cu")
		(net "M_J_CPU1_SB_DQS_DN<2>")
	)
	(segment
		(start 153.50363 -292.361112)
		(end 153.50363 -297.80865)
		(width 0.16002)
		(layer "In4.Cu")
		(net "M_J_CPU1_SB_DQS_DN<2>")
	)
	(segment
		(start 144.22247 -285.91129)
		(end 144.24787 -285.926022)
		(width 0.09525)
		(layer "In4.Cu")
		(net "M_J_CPU1_SB_DQS_DN<2>")
	)
	(segment
		(start 147.801584 -286.865822)
		(end 147.860512 -286.92475)
		(width 0.09525)
		(layer "In4.Cu")
		(net "M_J_CPU1_SB_DQS_DN<2>")
	)
	(segment
		(start 146.778472 -286.563054)
		(end 147.320508 -286.563054)
		(width 0.09525)
		(layer "In4.Cu")
		(net "M_J_CPU1_SB_DQS_DN<2>")
	)
	(segment
		(start 170.384978 -304.012346)
		(end 172.29201 -304.012346)
		(width 0.16002)
		(layer "In4.Cu")
		(net "M_J_CPU1_SB_DQS_DN<2>")
	)
	(segment
		(start 147.884134 -286.92475)
		(end 148.067268 -286.92475)
		(width 0.16002)
		(layer "In4.Cu")
		(net "M_J_CPU1_SB_DQS_DN<2>")
	)
	(segment
		(start 145.444718 -285.987744)
		(end 146.203162 -285.987744)
		(width 0.09525)
		(layer "In4.Cu")
		(net "M_J_CPU1_SB_DQS_DN<2>")
	)
	(segment
		(start 140.454888 -285.906464)
		(end 140.46327 -285.91129)
		(width 0.09525)
		(layer "In4.Cu")
		(net "M_J_CPU1_SB_DQS_DN<2>")
	)
	(segment
		(start 164.940234 -304.02149)
		(end 165.276276 -304.357532)
		(width 0.16002)
		(layer "In4.Cu")
		(net "M_J_CPU1_SB_DQS_DN<2>")
	)
	(segment
		(start 185.372756 -303.943512)
		(end 187.410344 -303.943512)
		(width 0.16002)
		(layer "In4.Cu")
		(net "M_J_CPU1_SB_DQS_DN<2>")
	)
	(segment
		(start 187.410344 -303.943512)
		(end 187.814204 -304.347372)
		(width 0.16002)
		(layer "In4.Cu")
		(net "M_J_CPU1_SB_DQS_DN<2>")
	)
	(segment
		(start 181.896258 -303.781206)
		(end 182.45201 -303.781206)
		(width 0.16002)
		(layer "In4.Cu")
		(net "M_J_CPU1_SB_DQS_DN<2>")
	)
	(segment
		(start 144.205706 -285.901638)
		(end 144.22247 -285.91129)
		(width 0.09525)
		(layer "In4.Cu")
		(net "M_J_CPU1_SB_DQS_DN<2>")
	)
	(segment
		(start 189.166754 -304.161444)
		(end 190.886334 -304.161444)
		(width 0.16002)
		(layer "In4.Cu")
		(net "M_J_CPU1_SB_DQS_DN<2>")
	)
	(segment
		(start 133.50621 -285.91129)
		(end 133.514592 -285.906464)
		(width 0.09525)
		(layer "In4.Cu")
		(net "M_J_CPU1_SB_DQS_DN<2>")
	)
	(segment
		(start 144.78381 -285.91129)
		(end 144.802606 -285.900368)
		(width 0.09525)
		(layer "In4.Cu")
		(net "M_J_CPU1_SB_DQS_DN<2>")
	)
	(segment
		(start 175.755554 -303.162462)
		(end 177.141886 -303.162462)
		(width 0.16002)
		(layer "In4.Cu")
		(net "M_J_CPU1_SB_DQS_DN<2>")
	)
	(arc
		(start 143.846042 -285.91129)
		(mid 144.024648 -285.860622)
		(end 144.205706 -285.901638)
		(width 0.09525)
		(layer "In4.Cu")
		(net "M_J_CPU1_SB_DQS_DN<2>")
	)
	(arc
		(start 134.446264 -285.91129)
		(mid 134.634732 -285.860613)
		(end 134.8232 -285.91129)
		(width 0.09525)
		(layer "In4.Cu")
		(net "M_J_CPU1_SB_DQS_DN<2>")
	)
	(arc
		(start 133.029452 -285.952184)
		(mid 133.272416 -285.985171)
		(end 133.50621 -285.91129)
		(width 0.09525)
		(layer "In4.Cu")
		(net "M_J_CPU1_SB_DQS_DN<2>")
	)
	(arc
		(start 133.514592 -285.906464)
		(mid 133.699624 -285.86055)
		(end 133.8834 -285.91129)
		(width 0.09525)
		(layer "In4.Cu")
		(net "M_J_CPU1_SB_DQS_DN<2>")
	)
	(arc
		(start 144.802606 -285.900368)
		(mid 144.983701 -285.860136)
		(end 145.162016 -285.91129)
		(width 0.09525)
		(layer "In4.Cu")
		(net "M_J_CPU1_SB_DQS_DN<2>")
	)
	(arc
		(start 136.326118 -285.91129)
		(mid 136.509893 -285.860518)
		(end 136.694926 -285.906464)
		(width 0.09525)
		(layer "In4.Cu")
		(net "M_J_CPU1_SB_DQS_DN<2>")
	)
	(arc
		(start 140.08608 -285.91129)
		(mid 140.269855 -285.860518)
		(end 140.454888 -285.906464)
		(width 0.09525)
		(layer "In4.Cu")
		(net "M_J_CPU1_SB_DQS_DN<2>")
	)
	(arc
		(start 138.214608 -285.906464)
		(mid 138.39964 -285.86055)
		(end 138.583416 -285.91129)
		(width 0.09525)
		(layer "In4.Cu")
		(net "M_J_CPU1_SB_DQS_DN<2>")
	)
	(arc
		(start 141.97457 -285.906464)
		(mid 142.159602 -285.86055)
		(end 142.343378 -285.91129)
		(width 0.09525)
		(layer "In4.Cu")
		(net "M_J_CPU1_SB_DQS_DN<2>")
	)
	(arc
		(start 141.403324 -285.91129)
		(mid 141.684756 -285.987045)
		(end 141.966188 -285.91129)
		(width 0.09525)
		(layer "In4.Cu")
		(net "M_J_CPU1_SB_DQS_DN<2>")
	)
	(arc
		(start 133.8834 -285.91129)
		(mid 134.164832 -285.987045)
		(end 134.446264 -285.91129)
		(width 0.09525)
		(layer "In4.Cu")
		(net "M_J_CPU1_SB_DQS_DN<2>")
	)
	(arc
		(start 139.523216 -285.91129)
		(mid 139.804648 -285.987045)
		(end 140.08608 -285.91129)
		(width 0.09525)
		(layer "In4.Cu")
		(net "M_J_CPU1_SB_DQS_DN<2>")
	)
	(arc
		(start 133.00964 -285.94431)
		(mid 133.019508 -285.948341)
		(end 133.029452 -285.952184)
		(width 0.09525)
		(layer "In4.Cu")
		(net "M_J_CPU1_SB_DQS_DN<2>")
	)
	(arc
		(start 143.283178 -285.91129)
		(mid 143.56461 -285.987045)
		(end 143.846042 -285.91129)
		(width 0.09525)
		(layer "In4.Cu")
		(net "M_J_CPU1_SB_DQS_DN<2>")
	)
	(arc
		(start 142.343378 -285.91129)
		(mid 142.62481 -285.987045)
		(end 142.906242 -285.91129)
		(width 0.09525)
		(layer "In4.Cu")
		(net "M_J_CPU1_SB_DQS_DN<2>")
	)
	(arc
		(start 135.763254 -285.91129)
		(mid 136.044686 -285.987045)
		(end 136.326118 -285.91129)
		(width 0.09525)
		(layer "In4.Cu")
		(net "M_J_CPU1_SB_DQS_DN<2>")
	)
	(arc
		(start 144.24787 -285.926022)
		(mid 144.517724 -285.986901)
		(end 144.78381 -285.91129)
		(width 0.09525)
		(layer "In4.Cu")
		(net "M_J_CPU1_SB_DQS_DN<2>")
	)
	(arc
		(start 141.026134 -285.91129)
		(mid 141.209909 -285.860518)
		(end 141.394942 -285.906464)
		(width 0.09525)
		(layer "In4.Cu")
		(net "M_J_CPU1_SB_DQS_DN<2>")
	)
	(arc
		(start 140.46327 -285.91129)
		(mid 140.744702 -285.987045)
		(end 141.026134 -285.91129)
		(width 0.09525)
		(layer "In4.Cu")
		(net "M_J_CPU1_SB_DQS_DN<2>")
	)
	(arc
		(start 137.274554 -285.906464)
		(mid 137.459586 -285.86055)
		(end 137.643362 -285.91129)
		(width 0.09525)
		(layer "In4.Cu")
		(net "M_J_CPU1_SB_DQS_DN<2>")
	)
	(arc
		(start 135.386064 -285.91129)
		(mid 135.569839 -285.860518)
		(end 135.754872 -285.906464)
		(width 0.09525)
		(layer "In4.Cu")
		(net "M_J_CPU1_SB_DQS_DN<2>")
	)
	(arc
		(start 137.643362 -285.91129)
		(mid 137.924794 -285.987045)
		(end 138.206226 -285.91129)
		(width 0.09525)
		(layer "In4.Cu")
		(net "M_J_CPU1_SB_DQS_DN<2>")
	)
	(arc
		(start 134.8232 -285.91129)
		(mid 135.104632 -285.987045)
		(end 135.386064 -285.91129)
		(width 0.09525)
		(layer "In4.Cu")
		(net "M_J_CPU1_SB_DQS_DN<2>")
	)
	(arc
		(start 145.162016 -285.91129)
		(mid 145.298297 -285.968249)
		(end 145.444718 -285.987744)
		(width 0.09525)
		(layer "In4.Cu")
		(net "M_J_CPU1_SB_DQS_DN<2>")
	)
	(arc
		(start 142.906242 -285.91129)
		(mid 143.09471 -285.860613)
		(end 143.283178 -285.91129)
		(width 0.09525)
		(layer "In4.Cu")
		(net "M_J_CPU1_SB_DQS_DN<2>")
	)
	(arc
		(start 138.583416 -285.91129)
		(mid 138.864848 -285.987045)
		(end 139.14628 -285.91129)
		(width 0.09525)
		(layer "In4.Cu")
		(net "M_J_CPU1_SB_DQS_DN<2>")
	)
	(arc
		(start 139.14628 -285.91129)
		(mid 139.334748 -285.860613)
		(end 139.523216 -285.91129)
		(width 0.09525)
		(layer "In4.Cu")
		(net "M_J_CPU1_SB_DQS_DN<2>")
	)
	(arc
		(start 136.703308 -285.91129)
		(mid 136.98474 -285.987045)
		(end 137.266172 -285.91129)
		(width 0.09525)
		(layer "In4.Cu")
		(net "M_J_CPU1_SB_DQS_DN<2>")
	)
	(segment
		(start 132.287772 -281.110436)
		(end 132.754878 -281.376374)
		(width 0.12954)
		(layer "F.Cu")
		(net "M_J_CPU1_SB_DQS_DN<1>")
	)
	(segment
		(start 144.205706 -281.041602)
		(end 144.22247 -281.051254)
		(width 0.09525)
		(layer "In4.Cu")
		(net "M_J_CPU1_SB_DQS_DN<1>")
	)
	(segment
		(start 132.908802 -281.110944)
		(end 133.00964 -281.084274)
		(width 0.09525)
		(layer "In4.Cu")
		(net "M_J_CPU1_SB_DQS_DN<1>")
	)
	(segment
		(start 175.755554 -293.812468)
		(end 177.141886 -293.812468)
		(width 0.16002)
		(layer "In4.Cu")
		(net "M_J_CPU1_SB_DQS_DN<1>")
	)
	(segment
		(start 173.646592 -294.997378)
		(end 174.153322 -294.490648)
		(width 0.16002)
		(layer "In4.Cu")
		(net "M_J_CPU1_SB_DQS_DN<1>")
	)
	(segment
		(start 144.78381 -281.051254)
		(end 144.802606 -281.040332)
		(width 0.09525)
		(layer "In4.Cu")
		(net "M_J_CPU1_SB_DQS_DN<1>")
	)
	(segment
		(start 138.206226 -281.051254)
		(end 138.214608 -281.046428)
		(width 0.09525)
		(layer "In4.Cu")
		(net "M_J_CPU1_SB_DQS_DN<1>")
	)
	(segment
		(start 133.50621 -281.051254)
		(end 133.514592 -281.046428)
		(width 0.09525)
		(layer "In4.Cu")
		(net "M_J_CPU1_SB_DQS_DN<1>")
	)
	(segment
		(start 189.154054 -294.81145)
		(end 190.886334 -294.81145)
		(width 0.16002)
		(layer "In4.Cu")
		(net "M_J_CPU1_SB_DQS_DN<1>")
	)
	(segment
		(start 159.04083 -290.064698)
		(end 159.04083 -291.649404)
		(width 0.16002)
		(layer "In4.Cu")
		(net "M_J_CPU1_SB_DQS_DN<1>")
	)
	(segment
		(start 140.454888 -281.046428)
		(end 140.46327 -281.051254)
		(width 0.09525)
		(layer "In4.Cu")
		(net "M_J_CPU1_SB_DQS_DN<1>")
	)
	(segment
		(start 162.770058 -295.378632)
		(end 164.631878 -295.378632)
		(width 0.16002)
		(layer "In4.Cu")
		(net "M_J_CPU1_SB_DQS_DN<1>")
	)
	(segment
		(start 180.376068 -294.974518)
		(end 181.352952 -294.974518)
		(width 0.16002)
		(layer "In4.Cu")
		(net "M_J_CPU1_SB_DQS_DN<1>")
	)
	(segment
		(start 166.897304 -294.222678)
		(end 169.945304 -294.222678)
		(width 0.16002)
		(layer "In4.Cu")
		(net "M_J_CPU1_SB_DQS_DN<1>")
	)
	(segment
		(start 184.591706 -293.812468)
		(end 185.372756 -294.593518)
		(width 0.16002)
		(layer "In4.Cu")
		(net "M_J_CPU1_SB_DQS_DN<1>")
	)
	(segment
		(start 181.352952 -294.974518)
		(end 181.896258 -294.431212)
		(width 0.16002)
		(layer "In4.Cu")
		(net "M_J_CPU1_SB_DQS_DN<1>")
	)
	(segment
		(start 147.242784 -280.72207)
		(end 147.515326 -281.100784)
		(width 0.09525)
		(layer "In4.Cu")
		(net "M_J_CPU1_SB_DQS_DN<1>")
	)
	(segment
		(start 165.002972 -295.007538)
		(end 166.112444 -295.007538)
		(width 0.16002)
		(layer "In4.Cu")
		(net "M_J_CPU1_SB_DQS_DN<1>")
	)
	(segment
		(start 144.22247 -281.051254)
		(end 144.24787 -281.065986)
		(width 0.09525)
		(layer "In4.Cu")
		(net "M_J_CPU1_SB_DQS_DN<1>")
	)
	(segment
		(start 181.896258 -294.431212)
		(end 182.45201 -294.431212)
		(width 0.16002)
		(layer "In4.Cu")
		(net "M_J_CPU1_SB_DQS_DN<1>")
	)
	(segment
		(start 169.945304 -294.222678)
		(end 170.384978 -294.662352)
		(width 0.16002)
		(layer "In4.Cu")
		(net "M_J_CPU1_SB_DQS_DN<1>")
	)
	(segment
		(start 177.99177 -294.662352)
		(end 180.063902 -294.662352)
		(width 0.16002)
		(layer "In4.Cu")
		(net "M_J_CPU1_SB_DQS_DN<1>")
	)
	(segment
		(start 147.836636 -281.100784)
		(end 147.895564 -281.159712)
		(width 0.09525)
		(layer "In4.Cu")
		(net "M_J_CPU1_SB_DQS_DN<1>")
	)
	(segment
		(start 174.153322 -294.490648)
		(end 175.077374 -294.490648)
		(width 0.16002)
		(layer "In4.Cu")
		(net "M_J_CPU1_SB_DQS_DN<1>")
	)
	(segment
		(start 147.515326 -281.100784)
		(end 147.836636 -281.100784)
		(width 0.09525)
		(layer "In4.Cu")
		(net "M_J_CPU1_SB_DQS_DN<1>")
	)
	(segment
		(start 187.410344 -294.593518)
		(end 187.814204 -294.997378)
		(width 0.16002)
		(layer "In4.Cu")
		(net "M_J_CPU1_SB_DQS_DN<1>")
	)
	(segment
		(start 166.112444 -295.007538)
		(end 166.897304 -294.222678)
		(width 0.16002)
		(layer "In4.Cu")
		(net "M_J_CPU1_SB_DQS_DN<1>")
	)
	(segment
		(start 145.874994 -280.980388)
		(end 145.877026 -280.980388)
		(width 0.09525)
		(layer "In4.Cu")
		(net "M_J_CPU1_SB_DQS_DN<1>")
	)
	(segment
		(start 177.141886 -293.812468)
		(end 177.99177 -294.662352)
		(width 0.16002)
		(layer "In4.Cu")
		(net "M_J_CPU1_SB_DQS_DN<1>")
	)
	(segment
		(start 147.919186 -281.159712)
		(end 150.135844 -281.159712)
		(width 0.16002)
		(layer "In4.Cu")
		(net "M_J_CPU1_SB_DQS_DN<1>")
	)
	(segment
		(start 190.886334 -294.81145)
		(end 191.160146 -295.085262)
		(width 0.16002)
		(layer "In4.Cu")
		(net "M_J_CPU1_SB_DQS_DN<1>")
	)
	(segment
		(start 172.29201 -294.662352)
		(end 172.627036 -294.997378)
		(width 0.16002)
		(layer "In4.Cu")
		(net "M_J_CPU1_SB_DQS_DN<1>")
	)
	(segment
		(start 170.384978 -294.662352)
		(end 172.29201 -294.662352)
		(width 0.16002)
		(layer "In4.Cu")
		(net "M_J_CPU1_SB_DQS_DN<1>")
	)
	(segment
		(start 145.877026 -280.980388)
		(end 146.079718 -280.777696)
		(width 0.09525)
		(layer "In4.Cu")
		(net "M_J_CPU1_SB_DQS_DN<1>")
	)
	(segment
		(start 159.04083 -291.649404)
		(end 162.770058 -295.378632)
		(width 0.16002)
		(layer "In4.Cu")
		(net "M_J_CPU1_SB_DQS_DN<1>")
	)
	(segment
		(start 141.394942 -281.046428)
		(end 141.403324 -281.051254)
		(width 0.09525)
		(layer "In4.Cu")
		(net "M_J_CPU1_SB_DQS_DN<1>")
	)
	(segment
		(start 182.45201 -294.431212)
		(end 183.070754 -293.812468)
		(width 0.16002)
		(layer "In4.Cu")
		(net "M_J_CPU1_SB_DQS_DN<1>")
	)
	(segment
		(start 183.070754 -293.812468)
		(end 184.591706 -293.812468)
		(width 0.16002)
		(layer "In4.Cu")
		(net "M_J_CPU1_SB_DQS_DN<1>")
	)
	(segment
		(start 175.077374 -294.490648)
		(end 175.755554 -293.812468)
		(width 0.16002)
		(layer "In4.Cu")
		(net "M_J_CPU1_SB_DQS_DN<1>")
	)
	(segment
		(start 135.754872 -281.046428)
		(end 135.763254 -281.051254)
		(width 0.09525)
		(layer "In4.Cu")
		(net "M_J_CPU1_SB_DQS_DN<1>")
	)
	(segment
		(start 188.968126 -294.997378)
		(end 189.154054 -294.81145)
		(width 0.16002)
		(layer "In4.Cu")
		(net "M_J_CPU1_SB_DQS_DN<1>")
	)
	(segment
		(start 187.814204 -294.997378)
		(end 188.968126 -294.997378)
		(width 0.16002)
		(layer "In4.Cu")
		(net "M_J_CPU1_SB_DQS_DN<1>")
	)
	(segment
		(start 141.966188 -281.051254)
		(end 141.97457 -281.046428)
		(width 0.09525)
		(layer "In4.Cu")
		(net "M_J_CPU1_SB_DQS_DN<1>")
	)
	(segment
		(start 146.213576 -280.72207)
		(end 147.242784 -280.72207)
		(width 0.09525)
		(layer "In4.Cu")
		(net "M_J_CPU1_SB_DQS_DN<1>")
	)
	(segment
		(start 132.754878 -281.376374)
		(end 132.908802 -281.110944)
		(width 0.09525)
		(layer "In4.Cu")
		(net "M_J_CPU1_SB_DQS_DN<1>")
	)
	(segment
		(start 185.372756 -294.593518)
		(end 187.410344 -294.593518)
		(width 0.16002)
		(layer "In4.Cu")
		(net "M_J_CPU1_SB_DQS_DN<1>")
	)
	(segment
		(start 136.694926 -281.046428)
		(end 136.703308 -281.051254)
		(width 0.09525)
		(layer "In4.Cu")
		(net "M_J_CPU1_SB_DQS_DN<1>")
	)
	(segment
		(start 137.266172 -281.051254)
		(end 137.274554 -281.046428)
		(width 0.09525)
		(layer "In4.Cu")
		(net "M_J_CPU1_SB_DQS_DN<1>")
	)
	(segment
		(start 150.135844 -281.159712)
		(end 159.04083 -290.064698)
		(width 0.16002)
		(layer "In4.Cu")
		(net "M_J_CPU1_SB_DQS_DN<1>")
	)
	(segment
		(start 147.895564 -281.159712)
		(end 147.919186 -281.159712)
		(width 0.09525)
		(layer "In4.Cu")
		(net "M_J_CPU1_SB_DQS_DN<1>")
	)
	(segment
		(start 172.627036 -294.997378)
		(end 173.646592 -294.997378)
		(width 0.16002)
		(layer "In4.Cu")
		(net "M_J_CPU1_SB_DQS_DN<1>")
	)
	(segment
		(start 164.631878 -295.378632)
		(end 165.002972 -295.007538)
		(width 0.16002)
		(layer "In4.Cu")
		(net "M_J_CPU1_SB_DQS_DN<1>")
	)
	(segment
		(start 180.063902 -294.662352)
		(end 180.376068 -294.974518)
		(width 0.16002)
		(layer "In4.Cu")
		(net "M_J_CPU1_SB_DQS_DN<1>")
	)
	(arc
		(start 134.446264 -281.051254)
		(mid 134.634732 -281.000577)
		(end 134.8232 -281.051254)
		(width 0.09525)
		(layer "In4.Cu")
		(net "M_J_CPU1_SB_DQS_DN<1>")
	)
	(arc
		(start 141.026134 -281.051254)
		(mid 141.209909 -281.000482)
		(end 141.394942 -281.046428)
		(width 0.09525)
		(layer "In4.Cu")
		(net "M_J_CPU1_SB_DQS_DN<1>")
	)
	(arc
		(start 137.274554 -281.046428)
		(mid 137.459586 -281.000514)
		(end 137.643362 -281.051254)
		(width 0.09525)
		(layer "In4.Cu")
		(net "M_J_CPU1_SB_DQS_DN<1>")
	)
	(arc
		(start 135.386064 -281.051254)
		(mid 135.569839 -281.000482)
		(end 135.754872 -281.046428)
		(width 0.09525)
		(layer "In4.Cu")
		(net "M_J_CPU1_SB_DQS_DN<1>")
	)
	(arc
		(start 138.583416 -281.051254)
		(mid 138.864848 -281.127009)
		(end 139.14628 -281.051254)
		(width 0.09525)
		(layer "In4.Cu")
		(net "M_J_CPU1_SB_DQS_DN<1>")
	)
	(arc
		(start 142.906242 -281.051254)
		(mid 143.09471 -281.000577)
		(end 143.283178 -281.051254)
		(width 0.09525)
		(layer "In4.Cu")
		(net "M_J_CPU1_SB_DQS_DN<1>")
	)
	(arc
		(start 139.14628 -281.051254)
		(mid 139.334748 -281.000577)
		(end 139.523216 -281.051254)
		(width 0.09525)
		(layer "In4.Cu")
		(net "M_J_CPU1_SB_DQS_DN<1>")
	)
	(arc
		(start 141.403324 -281.051254)
		(mid 141.684756 -281.127009)
		(end 141.966188 -281.051254)
		(width 0.09525)
		(layer "In4.Cu")
		(net "M_J_CPU1_SB_DQS_DN<1>")
	)
	(arc
		(start 133.8834 -281.051254)
		(mid 134.164832 -281.127009)
		(end 134.446264 -281.051254)
		(width 0.09525)
		(layer "In4.Cu")
		(net "M_J_CPU1_SB_DQS_DN<1>")
	)
	(arc
		(start 136.703308 -281.051254)
		(mid 136.98474 -281.127009)
		(end 137.266172 -281.051254)
		(width 0.09525)
		(layer "In4.Cu")
		(net "M_J_CPU1_SB_DQS_DN<1>")
	)
	(arc
		(start 146.079718 -280.777696)
		(mid 146.141103 -280.736523)
		(end 146.213576 -280.72207)
		(width 0.09525)
		(layer "In4.Cu")
		(net "M_J_CPU1_SB_DQS_DN<1>")
	)
	(arc
		(start 141.97457 -281.046428)
		(mid 142.159602 -281.000514)
		(end 142.343378 -281.051254)
		(width 0.09525)
		(layer "In4.Cu")
		(net "M_J_CPU1_SB_DQS_DN<1>")
	)
	(arc
		(start 144.24787 -281.065986)
		(mid 144.517724 -281.126865)
		(end 144.78381 -281.051254)
		(width 0.09525)
		(layer "In4.Cu")
		(net "M_J_CPU1_SB_DQS_DN<1>")
	)
	(arc
		(start 140.46327 -281.051254)
		(mid 140.744702 -281.127009)
		(end 141.026134 -281.051254)
		(width 0.09525)
		(layer "In4.Cu")
		(net "M_J_CPU1_SB_DQS_DN<1>")
	)
	(arc
		(start 143.283178 -281.051254)
		(mid 143.56461 -281.127009)
		(end 143.846042 -281.051254)
		(width 0.09525)
		(layer "In4.Cu")
		(net "M_J_CPU1_SB_DQS_DN<1>")
	)
	(arc
		(start 143.846042 -281.051254)
		(mid 144.024648 -281.000586)
		(end 144.205706 -281.041602)
		(width 0.09525)
		(layer "In4.Cu")
		(net "M_J_CPU1_SB_DQS_DN<1>")
	)
	(arc
		(start 133.029452 -281.092148)
		(mid 133.272416 -281.125135)
		(end 133.50621 -281.051254)
		(width 0.09525)
		(layer "In4.Cu")
		(net "M_J_CPU1_SB_DQS_DN<1>")
	)
	(arc
		(start 145.162016 -281.051254)
		(mid 145.298297 -281.108213)
		(end 145.444718 -281.127708)
		(width 0.09525)
		(layer "In4.Cu")
		(net "M_J_CPU1_SB_DQS_DN<1>")
	)
	(arc
		(start 144.802606 -281.040332)
		(mid 144.983701 -281.0001)
		(end 145.162016 -281.051254)
		(width 0.09525)
		(layer "In4.Cu")
		(net "M_J_CPU1_SB_DQS_DN<1>")
	)
	(arc
		(start 142.343378 -281.051254)
		(mid 142.62481 -281.127009)
		(end 142.906242 -281.051254)
		(width 0.09525)
		(layer "In4.Cu")
		(net "M_J_CPU1_SB_DQS_DN<1>")
	)
	(arc
		(start 135.763254 -281.051254)
		(mid 136.044686 -281.127009)
		(end 136.326118 -281.051254)
		(width 0.09525)
		(layer "In4.Cu")
		(net "M_J_CPU1_SB_DQS_DN<1>")
	)
	(arc
		(start 133.514592 -281.046428)
		(mid 133.699624 -281.000514)
		(end 133.8834 -281.051254)
		(width 0.09525)
		(layer "In4.Cu")
		(net "M_J_CPU1_SB_DQS_DN<1>")
	)
	(arc
		(start 145.444718 -281.127708)
		(mid 145.67214 -281.08991)
		(end 145.874994 -280.980388)
		(width 0.09525)
		(layer "In4.Cu")
		(net "M_J_CPU1_SB_DQS_DN<1>")
	)
	(arc
		(start 136.326118 -281.051254)
		(mid 136.509893 -281.000482)
		(end 136.694926 -281.046428)
		(width 0.09525)
		(layer "In4.Cu")
		(net "M_J_CPU1_SB_DQS_DN<1>")
	)
	(arc
		(start 134.8232 -281.051254)
		(mid 135.104632 -281.127009)
		(end 135.386064 -281.051254)
		(width 0.09525)
		(layer "In4.Cu")
		(net "M_J_CPU1_SB_DQS_DN<1>")
	)
	(arc
		(start 139.523216 -281.051254)
		(mid 139.804648 -281.127009)
		(end 140.08608 -281.051254)
		(width 0.09525)
		(layer "In4.Cu")
		(net "M_J_CPU1_SB_DQS_DN<1>")
	)
	(arc
		(start 137.643362 -281.051254)
		(mid 137.924794 -281.127009)
		(end 138.206226 -281.051254)
		(width 0.09525)
		(layer "In4.Cu")
		(net "M_J_CPU1_SB_DQS_DN<1>")
	)
	(arc
		(start 138.214608 -281.046428)
		(mid 138.39964 -281.000514)
		(end 138.583416 -281.051254)
		(width 0.09525)
		(layer "In4.Cu")
		(net "M_J_CPU1_SB_DQS_DN<1>")
	)
	(arc
		(start 140.08608 -281.051254)
		(mid 140.269855 -281.000482)
		(end 140.454888 -281.046428)
		(width 0.09525)
		(layer "In4.Cu")
		(net "M_J_CPU1_SB_DQS_DN<1>")
	)
	(arc
		(start 133.00964 -281.084274)
		(mid 133.019508 -281.088305)
		(end 133.029452 -281.092148)
		(width 0.09525)
		(layer "In4.Cu")
		(net "M_J_CPU1_SB_DQS_DN<1>")
	)
	(segment
		(start 132.287772 -276.2504)
		(end 132.754878 -276.516338)
		(width 0.12954)
		(layer "F.Cu")
		(net "M_J_CPU1_SB_DQS_DN<0>")
	)
	(segment
		(start 181.896258 -285.081218)
		(end 182.45201 -285.081218)
		(width 0.16002)
		(layer "In4.Cu")
		(net "M_J_CPU1_SB_DQS_DN<0>")
	)
	(segment
		(start 172.627036 -285.647384)
		(end 173.646592 -285.647384)
		(width 0.16002)
		(layer "In4.Cu")
		(net "M_J_CPU1_SB_DQS_DN<0>")
	)
	(segment
		(start 133.50621 -276.191218)
		(end 133.514592 -276.186392)
		(width 0.09525)
		(layer "In4.Cu")
		(net "M_J_CPU1_SB_DQS_DN<0>")
	)
	(segment
		(start 169.752772 -284.872684)
		(end 170.814492 -285.312358)
		(width 0.16002)
		(layer "In4.Cu")
		(net "M_J_CPU1_SB_DQS_DN<0>")
	)
	(segment
		(start 137.266172 -276.191218)
		(end 137.274554 -276.186392)
		(width 0.09525)
		(layer "In4.Cu")
		(net "M_J_CPU1_SB_DQS_DN<0>")
	)
	(segment
		(start 136.694926 -276.186392)
		(end 136.703308 -276.191218)
		(width 0.09525)
		(layer "In4.Cu")
		(net "M_J_CPU1_SB_DQS_DN<0>")
	)
	(segment
		(start 189.99835 -285.461456)
		(end 190.886334 -285.461456)
		(width 0.16002)
		(layer "In4.Cu")
		(net "M_J_CPU1_SB_DQS_DN<0>")
	)
	(segment
		(start 177.141886 -284.462474)
		(end 177.99177 -285.312358)
		(width 0.16002)
		(layer "In4.Cu")
		(net "M_J_CPU1_SB_DQS_DN<0>")
	)
	(segment
		(start 166.112444 -285.657544)
		(end 166.897304 -284.872684)
		(width 0.16002)
		(layer "In4.Cu")
		(net "M_J_CPU1_SB_DQS_DN<0>")
	)
	(segment
		(start 147.360132 -275.181568)
		(end 147.400518 -275.141182)
		(width 0.09525)
		(layer "In4.Cu")
		(net "M_J_CPU1_SB_DQS_DN<0>")
	)
	(segment
		(start 170.814492 -285.312358)
		(end 172.29201 -285.312358)
		(width 0.16002)
		(layer "In4.Cu")
		(net "M_J_CPU1_SB_DQS_DN<0>")
	)
	(segment
		(start 175.755554 -284.462474)
		(end 177.141886 -284.462474)
		(width 0.16002)
		(layer "In4.Cu")
		(net "M_J_CPU1_SB_DQS_DN<0>")
	)
	(segment
		(start 173.646592 -285.647384)
		(end 174.153322 -285.140654)
		(width 0.16002)
		(layer "In4.Cu")
		(net "M_J_CPU1_SB_DQS_DN<0>")
	)
	(segment
		(start 147.836636 -275.141182)
		(end 147.895564 -275.20011)
		(width 0.09525)
		(layer "In4.Cu")
		(net "M_J_CPU1_SB_DQS_DN<0>")
	)
	(segment
		(start 165.558724 -285.657544)
		(end 166.112444 -285.657544)
		(width 0.16002)
		(layer "In4.Cu")
		(net "M_J_CPU1_SB_DQS_DN<0>")
	)
	(segment
		(start 144.205706 -276.181566)
		(end 144.22247 -276.191218)
		(width 0.09525)
		(layer "In4.Cu")
		(net "M_J_CPU1_SB_DQS_DN<0>")
	)
	(segment
		(start 163.211764 -284.920944)
		(end 164.822124 -284.920944)
		(width 0.16002)
		(layer "In4.Cu")
		(net "M_J_CPU1_SB_DQS_DN<0>")
	)
	(segment
		(start 147.400518 -275.141182)
		(end 147.836636 -275.141182)
		(width 0.09525)
		(layer "In4.Cu")
		(net "M_J_CPU1_SB_DQS_DN<0>")
	)
	(segment
		(start 187.410344 -285.243524)
		(end 187.814204 -285.647384)
		(width 0.16002)
		(layer "In4.Cu")
		(net "M_J_CPU1_SB_DQS_DN<0>")
	)
	(segment
		(start 177.99177 -285.312358)
		(end 180.063902 -285.312358)
		(width 0.16002)
		(layer "In4.Cu")
		(net "M_J_CPU1_SB_DQS_DN<0>")
	)
	(segment
		(start 135.754872 -276.186392)
		(end 135.763254 -276.191218)
		(width 0.09525)
		(layer "In4.Cu")
		(net "M_J_CPU1_SB_DQS_DN<0>")
	)
	(segment
		(start 166.897304 -284.872684)
		(end 169.752772 -284.872684)
		(width 0.16002)
		(layer "In4.Cu")
		(net "M_J_CPU1_SB_DQS_DN<0>")
	)
	(segment
		(start 174.153322 -285.140654)
		(end 175.077374 -285.140654)
		(width 0.16002)
		(layer "In4.Cu")
		(net "M_J_CPU1_SB_DQS_DN<0>")
	)
	(segment
		(start 180.063902 -285.312358)
		(end 180.376068 -285.624524)
		(width 0.16002)
		(layer "In4.Cu")
		(net "M_J_CPU1_SB_DQS_DN<0>")
	)
	(segment
		(start 180.376068 -285.624524)
		(end 181.352952 -285.624524)
		(width 0.16002)
		(layer "In4.Cu")
		(net "M_J_CPU1_SB_DQS_DN<0>")
	)
	(segment
		(start 175.077374 -285.140654)
		(end 175.755554 -284.462474)
		(width 0.16002)
		(layer "In4.Cu")
		(net "M_J_CPU1_SB_DQS_DN<0>")
	)
	(segment
		(start 184.591706 -284.462474)
		(end 185.372756 -285.243524)
		(width 0.16002)
		(layer "In4.Cu")
		(net "M_J_CPU1_SB_DQS_DN<0>")
	)
	(segment
		(start 147.895564 -275.20011)
		(end 147.919186 -275.20011)
		(width 0.09525)
		(layer "In4.Cu")
		(net "M_J_CPU1_SB_DQS_DN<0>")
	)
	(segment
		(start 181.352952 -285.624524)
		(end 181.896258 -285.081218)
		(width 0.16002)
		(layer "In4.Cu")
		(net "M_J_CPU1_SB_DQS_DN<0>")
	)
	(segment
		(start 132.908802 -276.250908)
		(end 133.00964 -276.224238)
		(width 0.09525)
		(layer "In4.Cu")
		(net "M_J_CPU1_SB_DQS_DN<0>")
	)
	(segment
		(start 155.197048 -277.891748)
		(end 156.182568 -277.891748)
		(width 0.16002)
		(layer "In4.Cu")
		(net "M_J_CPU1_SB_DQS_DN<0>")
	)
	(segment
		(start 185.372756 -285.243524)
		(end 187.410344 -285.243524)
		(width 0.16002)
		(layer "In4.Cu")
		(net "M_J_CPU1_SB_DQS_DN<0>")
	)
	(segment
		(start 183.070754 -284.462474)
		(end 184.591706 -284.462474)
		(width 0.16002)
		(layer "In4.Cu")
		(net "M_J_CPU1_SB_DQS_DN<0>")
	)
	(segment
		(start 164.822124 -284.920944)
		(end 165.558724 -285.657544)
		(width 0.16002)
		(layer "In4.Cu")
		(net "M_J_CPU1_SB_DQS_DN<0>")
	)
	(segment
		(start 152.50541 -275.20011)
		(end 155.197048 -277.891748)
		(width 0.16002)
		(layer "In4.Cu")
		(net "M_J_CPU1_SB_DQS_DN<0>")
	)
	(segment
		(start 190.886334 -285.461456)
		(end 191.160146 -285.735268)
		(width 0.16002)
		(layer "In4.Cu")
		(net "M_J_CPU1_SB_DQS_DN<0>")
	)
	(segment
		(start 156.182568 -277.891748)
		(end 163.211764 -284.920944)
		(width 0.16002)
		(layer "In4.Cu")
		(net "M_J_CPU1_SB_DQS_DN<0>")
	)
	(segment
		(start 144.22247 -276.191218)
		(end 144.24787 -276.20595)
		(width 0.09525)
		(layer "In4.Cu")
		(net "M_J_CPU1_SB_DQS_DN<0>")
	)
	(segment
		(start 140.454888 -276.186392)
		(end 140.46327 -276.191218)
		(width 0.09525)
		(layer "In4.Cu")
		(net "M_J_CPU1_SB_DQS_DN<0>")
	)
	(segment
		(start 145.690082 -276.211284)
		(end 145.724626 -276.191218)
		(width 0.09525)
		(layer "In4.Cu")
		(net "M_J_CPU1_SB_DQS_DN<0>")
	)
	(segment
		(start 189.812422 -285.647384)
		(end 189.99835 -285.461456)
		(width 0.16002)
		(layer "In4.Cu")
		(net "M_J_CPU1_SB_DQS_DN<0>")
	)
	(segment
		(start 132.754878 -276.516338)
		(end 132.908802 -276.250908)
		(width 0.09525)
		(layer "In4.Cu")
		(net "M_J_CPU1_SB_DQS_DN<0>")
	)
	(segment
		(start 141.394942 -276.186392)
		(end 141.403324 -276.191218)
		(width 0.09525)
		(layer "In4.Cu")
		(net "M_J_CPU1_SB_DQS_DN<0>")
	)
	(segment
		(start 144.78381 -276.191218)
		(end 144.802606 -276.180296)
		(width 0.09525)
		(layer "In4.Cu")
		(net "M_J_CPU1_SB_DQS_DN<0>")
	)
	(segment
		(start 182.45201 -285.081218)
		(end 183.070754 -284.462474)
		(width 0.16002)
		(layer "In4.Cu")
		(net "M_J_CPU1_SB_DQS_DN<0>")
	)
	(segment
		(start 138.206226 -276.191218)
		(end 138.214608 -276.186392)
		(width 0.09525)
		(layer "In4.Cu")
		(net "M_J_CPU1_SB_DQS_DN<0>")
	)
	(segment
		(start 172.29201 -285.312358)
		(end 172.627036 -285.647384)
		(width 0.16002)
		(layer "In4.Cu")
		(net "M_J_CPU1_SB_DQS_DN<0>")
	)
	(segment
		(start 187.814204 -285.647384)
		(end 189.812422 -285.647384)
		(width 0.16002)
		(layer "In4.Cu")
		(net "M_J_CPU1_SB_DQS_DN<0>")
	)
	(segment
		(start 145.84045 -276.102572)
		(end 146.761454 -275.181568)
		(width 0.09525)
		(layer "In4.Cu")
		(net "M_J_CPU1_SB_DQS_DN<0>")
	)
	(segment
		(start 147.919186 -275.20011)
		(end 152.50541 -275.20011)
		(width 0.16002)
		(layer "In4.Cu")
		(net "M_J_CPU1_SB_DQS_DN<0>")
	)
	(segment
		(start 141.966188 -276.191218)
		(end 141.97457 -276.186392)
		(width 0.09525)
		(layer "In4.Cu")
		(net "M_J_CPU1_SB_DQS_DN<0>")
	)
	(segment
		(start 146.761454 -275.181568)
		(end 147.360132 -275.181568)
		(width 0.09525)
		(layer "In4.Cu")
		(net "M_J_CPU1_SB_DQS_DN<0>")
	)
	(arc
		(start 133.514592 -276.186392)
		(mid 133.699624 -276.140478)
		(end 133.8834 -276.191218)
		(width 0.09525)
		(layer "In4.Cu")
		(net "M_J_CPU1_SB_DQS_DN<0>")
	)
	(arc
		(start 143.283178 -276.191218)
		(mid 143.56461 -276.266973)
		(end 143.846042 -276.191218)
		(width 0.09525)
		(layer "In4.Cu")
		(net "M_J_CPU1_SB_DQS_DN<0>")
	)
	(arc
		(start 145.162016 -276.191218)
		(mid 145.423552 -276.267331)
		(end 145.690082 -276.211284)
		(width 0.09525)
		(layer "In4.Cu")
		(net "M_J_CPU1_SB_DQS_DN<0>")
	)
	(arc
		(start 135.386064 -276.191218)
		(mid 135.569839 -276.140446)
		(end 135.754872 -276.186392)
		(width 0.09525)
		(layer "In4.Cu")
		(net "M_J_CPU1_SB_DQS_DN<0>")
	)
	(arc
		(start 144.24787 -276.20595)
		(mid 144.517724 -276.266829)
		(end 144.78381 -276.191218)
		(width 0.09525)
		(layer "In4.Cu")
		(net "M_J_CPU1_SB_DQS_DN<0>")
	)
	(arc
		(start 137.274554 -276.186392)
		(mid 137.459586 -276.140478)
		(end 137.643362 -276.191218)
		(width 0.09525)
		(layer "In4.Cu")
		(net "M_J_CPU1_SB_DQS_DN<0>")
	)
	(arc
		(start 140.46327 -276.191218)
		(mid 140.744702 -276.266973)
		(end 141.026134 -276.191218)
		(width 0.09525)
		(layer "In4.Cu")
		(net "M_J_CPU1_SB_DQS_DN<0>")
	)
	(arc
		(start 141.97457 -276.186392)
		(mid 142.159602 -276.140478)
		(end 142.343378 -276.191218)
		(width 0.09525)
		(layer "In4.Cu")
		(net "M_J_CPU1_SB_DQS_DN<0>")
	)
	(arc
		(start 136.326118 -276.191218)
		(mid 136.509893 -276.140446)
		(end 136.694926 -276.186392)
		(width 0.09525)
		(layer "In4.Cu")
		(net "M_J_CPU1_SB_DQS_DN<0>")
	)
	(arc
		(start 140.08608 -276.191218)
		(mid 140.269855 -276.140446)
		(end 140.454888 -276.186392)
		(width 0.09525)
		(layer "In4.Cu")
		(net "M_J_CPU1_SB_DQS_DN<0>")
	)
	(arc
		(start 145.814288 -276.126956)
		(mid 145.827564 -276.114973)
		(end 145.84045 -276.102572)
		(width 0.09525)
		(layer "In4.Cu")
		(net "M_J_CPU1_SB_DQS_DN<0>")
	)
	(arc
		(start 133.8834 -276.191218)
		(mid 134.164832 -276.266973)
		(end 134.446264 -276.191218)
		(width 0.09525)
		(layer "In4.Cu")
		(net "M_J_CPU1_SB_DQS_DN<0>")
	)
	(arc
		(start 136.703308 -276.191218)
		(mid 136.98474 -276.266973)
		(end 137.266172 -276.191218)
		(width 0.09525)
		(layer "In4.Cu")
		(net "M_J_CPU1_SB_DQS_DN<0>")
	)
	(arc
		(start 139.523216 -276.191218)
		(mid 139.804648 -276.266973)
		(end 140.08608 -276.191218)
		(width 0.09525)
		(layer "In4.Cu")
		(net "M_J_CPU1_SB_DQS_DN<0>")
	)
	(arc
		(start 143.846042 -276.191218)
		(mid 144.024648 -276.14055)
		(end 144.205706 -276.181566)
		(width 0.09525)
		(layer "In4.Cu")
		(net "M_J_CPU1_SB_DQS_DN<0>")
	)
	(arc
		(start 144.802606 -276.180296)
		(mid 144.983701 -276.140064)
		(end 145.162016 -276.191218)
		(width 0.09525)
		(layer "In4.Cu")
		(net "M_J_CPU1_SB_DQS_DN<0>")
	)
	(arc
		(start 133.00964 -276.224238)
		(mid 133.019508 -276.228269)
		(end 133.029452 -276.232112)
		(width 0.09525)
		(layer "In4.Cu")
		(net "M_J_CPU1_SB_DQS_DN<0>")
	)
	(arc
		(start 142.343378 -276.191218)
		(mid 142.62481 -276.266973)
		(end 142.906242 -276.191218)
		(width 0.09525)
		(layer "In4.Cu")
		(net "M_J_CPU1_SB_DQS_DN<0>")
	)
	(arc
		(start 138.214608 -276.186392)
		(mid 138.39964 -276.140478)
		(end 138.583416 -276.191218)
		(width 0.09525)
		(layer "In4.Cu")
		(net "M_J_CPU1_SB_DQS_DN<0>")
	)
	(arc
		(start 133.029452 -276.232112)
		(mid 133.272416 -276.265099)
		(end 133.50621 -276.191218)
		(width 0.09525)
		(layer "In4.Cu")
		(net "M_J_CPU1_SB_DQS_DN<0>")
	)
	(arc
		(start 139.14628 -276.191218)
		(mid 139.334748 -276.140541)
		(end 139.523216 -276.191218)
		(width 0.09525)
		(layer "In4.Cu")
		(net "M_J_CPU1_SB_DQS_DN<0>")
	)
	(arc
		(start 134.8232 -276.191218)
		(mid 135.104632 -276.266973)
		(end 135.386064 -276.191218)
		(width 0.09525)
		(layer "In4.Cu")
		(net "M_J_CPU1_SB_DQS_DN<0>")
	)
	(arc
		(start 138.583416 -276.191218)
		(mid 138.864848 -276.266973)
		(end 139.14628 -276.191218)
		(width 0.09525)
		(layer "In4.Cu")
		(net "M_J_CPU1_SB_DQS_DN<0>")
	)
	(arc
		(start 141.403324 -276.191218)
		(mid 141.684756 -276.266973)
		(end 141.966188 -276.191218)
		(width 0.09525)
		(layer "In4.Cu")
		(net "M_J_CPU1_SB_DQS_DN<0>")
	)
	(arc
		(start 134.446264 -276.191218)
		(mid 134.634732 -276.140541)
		(end 134.8232 -276.191218)
		(width 0.09525)
		(layer "In4.Cu")
		(net "M_J_CPU1_SB_DQS_DN<0>")
	)
	(arc
		(start 141.026134 -276.191218)
		(mid 141.209909 -276.140446)
		(end 141.394942 -276.186392)
		(width 0.09525)
		(layer "In4.Cu")
		(net "M_J_CPU1_SB_DQS_DN<0>")
	)
	(arc
		(start 137.643362 -276.191218)
		(mid 137.924794 -276.266973)
		(end 138.206226 -276.191218)
		(width 0.09525)
		(layer "In4.Cu")
		(net "M_J_CPU1_SB_DQS_DN<0>")
	)
	(arc
		(start 135.763254 -276.191218)
		(mid 136.044686 -276.266973)
		(end 136.326118 -276.191218)
		(width 0.09525)
		(layer "In4.Cu")
		(net "M_J_CPU1_SB_DQS_DN<0>")
	)
	(arc
		(start 145.724626 -276.191218)
		(mid 145.771044 -276.161302)
		(end 145.814288 -276.126956)
		(width 0.09525)
		(layer "In4.Cu")
		(net "M_J_CPU1_SB_DQS_DN<0>")
	)
	(arc
		(start 142.906242 -276.191218)
		(mid 143.09471 -276.140541)
		(end 143.283178 -276.191218)
		(width 0.09525)
		(layer "In4.Cu")
		(net "M_J_CPU1_SB_DQS_DN<0>")
	)
	(segment
		(start 131.347972 -279.490424)
		(end 131.814824 -279.756362)
		(width 0.10668)
		(layer "F.Cu")
		(net "M_J_CPU1_SB_DQ<9>")
	)
	(segment
		(start 131.814824 -279.756362)
		(end 131.660646 -280.021792)
		(width 0.0889)
		(layer "In4.Cu")
		(net "M_J_CPU1_SB_DQ<9>")
	)
	(segment
		(start 150.575772 -279.745694)
		(end 160.35147 -289.521392)
		(width 0.14478)
		(layer "In4.Cu")
		(net "M_J_CPU1_SB_DQ<9>")
	)
	(segment
		(start 131.660646 -280.021792)
		(end 131.682998 -280.105104)
		(width 0.0889)
		(layer "In4.Cu")
		(net "M_J_CPU1_SB_DQ<9>")
	)
	(segment
		(start 188.560964 -292.11016)
		(end 188.722508 -292.271704)
		(width 0.14478)
		(layer "In4.Cu")
		(net "M_J_CPU1_SB_DQ<9>")
	)
	(segment
		(start 189.112398 -292.780466)
		(end 189.273942 -292.618922)
		(width 0.14478)
		(layer "In4.Cu")
		(net "M_J_CPU1_SB_DQ<9>")
	)
	(segment
		(start 167.044624 -292.110414)
		(end 169.768012 -292.110414)
		(width 0.14478)
		(layer "In4.Cu")
		(net "M_J_CPU1_SB_DQ<9>")
	)
	(segment
		(start 163.33724 -292.960298)
		(end 166.19474 -292.960298)
		(width 0.14478)
		(layer "In4.Cu")
		(net "M_J_CPU1_SB_DQ<9>")
	)
	(segment
		(start 182.042816 -292.11016)
		(end 188.560964 -292.11016)
		(width 0.14478)
		(layer "In4.Cu")
		(net "M_J_CPU1_SB_DQ<9>")
	)
	(segment
		(start 173.534578 -292.960298)
		(end 174.384462 -292.110414)
		(width 0.14478)
		(layer "In4.Cu")
		(net "M_J_CPU1_SB_DQ<9>")
	)
	(segment
		(start 132.93344 -280.083768)
		(end 132.941822 -280.078942)
		(width 0.0889)
		(layer "In4.Cu")
		(net "M_J_CPU1_SB_DQ<9>")
	)
	(segment
		(start 160.35147 -289.974528)
		(end 163.33724 -292.960298)
		(width 0.14478)
		(layer "In4.Cu")
		(net "M_J_CPU1_SB_DQ<9>")
	)
	(segment
		(start 140.453364 -280.083768)
		(end 140.461746 -280.078942)
		(width 0.0889)
		(layer "In4.Cu")
		(net "M_J_CPU1_SB_DQ<9>")
	)
	(segment
		(start 145.704306 -279.928066)
		(end 147.18919 -279.928066)
		(width 0.0889)
		(layer "In4.Cu")
		(net "M_J_CPU1_SB_DQ<9>")
	)
	(segment
		(start 170.617896 -292.960298)
		(end 173.534578 -292.960298)
		(width 0.14478)
		(layer "In4.Cu")
		(net "M_J_CPU1_SB_DQ<9>")
	)
	(segment
		(start 189.273942 -292.271704)
		(end 189.435486 -292.11016)
		(width 0.14478)
		(layer "In4.Cu")
		(net "M_J_CPU1_SB_DQ<9>")
	)
	(segment
		(start 191.160146 -292.535102)
		(end 191.160146 -292.535356)
		(width 0.14478)
		(layer "In4.Cu")
		(net "M_J_CPU1_SB_DQ<9>")
	)
	(segment
		(start 178.357022 -292.960298)
		(end 181.192678 -292.960298)
		(width 0.14478)
		(layer "In4.Cu")
		(net "M_J_CPU1_SB_DQ<9>")
	)
	(segment
		(start 144.777968 -280.072846)
		(end 144.788382 -280.078942)
		(width 0.0889)
		(layer "In4.Cu")
		(net "M_J_CPU1_SB_DQ<9>")
	)
	(segment
		(start 133.507734 -280.078942)
		(end 133.516116 -280.083768)
		(width 0.0889)
		(layer "In4.Cu")
		(net "M_J_CPU1_SB_DQ<9>")
	)
	(segment
		(start 181.192678 -292.960298)
		(end 182.042816 -292.11016)
		(width 0.14478)
		(layer "In4.Cu")
		(net "M_J_CPU1_SB_DQ<9>")
	)
	(segment
		(start 131.993386 -280.083768)
		(end 132.001768 -280.078942)
		(width 0.0889)
		(layer "In4.Cu")
		(net "M_J_CPU1_SB_DQ<9>")
	)
	(segment
		(start 135.753348 -280.083768)
		(end 135.76173 -280.078942)
		(width 0.0889)
		(layer "In4.Cu")
		(net "M_J_CPU1_SB_DQ<9>")
	)
	(segment
		(start 189.435486 -292.11016)
		(end 190.735204 -292.11016)
		(width 0.14478)
		(layer "In4.Cu")
		(net "M_J_CPU1_SB_DQ<9>")
	)
	(segment
		(start 141.393418 -280.083768)
		(end 141.4018 -280.078942)
		(width 0.0889)
		(layer "In4.Cu")
		(net "M_J_CPU1_SB_DQ<9>")
	)
	(segment
		(start 188.722508 -292.271704)
		(end 188.722508 -292.618922)
		(width 0.14478)
		(layer "In4.Cu")
		(net "M_J_CPU1_SB_DQ<9>")
	)
	(segment
		(start 190.735204 -292.11016)
		(end 191.160146 -292.535102)
		(width 0.14478)
		(layer "In4.Cu")
		(net "M_J_CPU1_SB_DQ<9>")
	)
	(segment
		(start 169.768012 -292.110414)
		(end 170.617896 -292.960298)
		(width 0.14478)
		(layer "In4.Cu")
		(net "M_J_CPU1_SB_DQ<9>")
	)
	(segment
		(start 137.267696 -280.078942)
		(end 137.276078 -280.083768)
		(width 0.0889)
		(layer "In4.Cu")
		(net "M_J_CPU1_SB_DQ<9>")
	)
	(segment
		(start 188.884052 -292.780466)
		(end 189.112398 -292.780466)
		(width 0.14478)
		(layer "In4.Cu")
		(net "M_J_CPU1_SB_DQ<9>")
	)
	(segment
		(start 147.827238 -279.745694)
		(end 150.575772 -279.745694)
		(width 0.14478)
		(layer "In4.Cu")
		(net "M_J_CPU1_SB_DQ<9>")
	)
	(segment
		(start 147.371562 -279.745694)
		(end 147.827238 -279.745694)
		(width 0.0889)
		(layer "In4.Cu")
		(net "M_J_CPU1_SB_DQ<9>")
	)
	(segment
		(start 189.273942 -292.618922)
		(end 189.273942 -292.271704)
		(width 0.14478)
		(layer "In4.Cu")
		(net "M_J_CPU1_SB_DQ<9>")
	)
	(segment
		(start 174.384462 -292.110414)
		(end 177.507138 -292.110414)
		(width 0.14478)
		(layer "In4.Cu")
		(net "M_J_CPU1_SB_DQ<9>")
	)
	(segment
		(start 188.722508 -292.618922)
		(end 188.884052 -292.780466)
		(width 0.14478)
		(layer "In4.Cu")
		(net "M_J_CPU1_SB_DQ<9>")
	)
	(segment
		(start 136.693402 -280.083768)
		(end 136.701784 -280.078942)
		(width 0.0889)
		(layer "In4.Cu")
		(net "M_J_CPU1_SB_DQ<9>")
	)
	(segment
		(start 147.18919 -279.928066)
		(end 147.371562 -279.745694)
		(width 0.0889)
		(layer "In4.Cu")
		(net "M_J_CPU1_SB_DQ<9>")
	)
	(segment
		(start 138.20775 -280.078942)
		(end 138.216132 -280.083768)
		(width 0.0889)
		(layer "In4.Cu")
		(net "M_J_CPU1_SB_DQ<9>")
	)
	(segment
		(start 141.967712 -280.078942)
		(end 141.976094 -280.083768)
		(width 0.0889)
		(layer "In4.Cu")
		(net "M_J_CPU1_SB_DQ<9>")
	)
	(segment
		(start 166.19474 -292.960298)
		(end 167.044624 -292.110414)
		(width 0.14478)
		(layer "In4.Cu")
		(net "M_J_CPU1_SB_DQ<9>")
	)
	(segment
		(start 177.507138 -292.110414)
		(end 178.357022 -292.960298)
		(width 0.14478)
		(layer "In4.Cu")
		(net "M_J_CPU1_SB_DQ<9>")
	)
	(segment
		(start 160.35147 -289.521392)
		(end 160.35147 -289.974528)
		(width 0.14478)
		(layer "In4.Cu")
		(net "M_J_CPU1_SB_DQ<9>")
	)
	(segment
		(start 143.847566 -280.078942)
		(end 143.855948 -280.083768)
		(width 0.0889)
		(layer "In4.Cu")
		(net "M_J_CPU1_SB_DQ<9>")
	)
	(arc
		(start 141.976094 -280.083768)
		(mid 142.159602 -280.129262)
		(end 142.341854 -280.078942)
		(width 0.0889)
		(layer "In4.Cu")
		(net "M_J_CPU1_SB_DQ<9>")
	)
	(arc
		(start 144.222216 -280.078942)
		(mid 144.499283 -280.002671)
		(end 144.777968 -280.072846)
		(width 0.0889)
		(layer "In4.Cu")
		(net "M_J_CPU1_SB_DQ<9>")
	)
	(arc
		(start 143.855948 -280.083768)
		(mid 144.03971 -280.129384)
		(end 144.222216 -280.078942)
		(width 0.0889)
		(layer "In4.Cu")
		(net "M_J_CPU1_SB_DQ<9>")
	)
	(arc
		(start 138.581892 -280.078942)
		(mid 138.864848 -280.002765)
		(end 139.147804 -280.078942)
		(width 0.0889)
		(layer "In4.Cu")
		(net "M_J_CPU1_SB_DQ<9>")
	)
	(arc
		(start 136.327642 -280.078942)
		(mid 136.509893 -280.129292)
		(end 136.693402 -280.083768)
		(width 0.0889)
		(layer "In4.Cu")
		(net "M_J_CPU1_SB_DQ<9>")
	)
	(arc
		(start 144.788382 -280.078942)
		(mid 144.966032 -280.129202)
		(end 145.146014 -280.088086)
		(width 0.0889)
		(layer "In4.Cu")
		(net "M_J_CPU1_SB_DQ<9>")
	)
	(arc
		(start 133.881876 -280.078942)
		(mid 134.164832 -280.002765)
		(end 134.447788 -280.078942)
		(width 0.0889)
		(layer "In4.Cu")
		(net "M_J_CPU1_SB_DQ<9>")
	)
	(arc
		(start 134.821676 -280.078942)
		(mid 135.104632 -280.002765)
		(end 135.387588 -280.078942)
		(width 0.0889)
		(layer "In4.Cu")
		(net "M_J_CPU1_SB_DQ<9>")
	)
	(arc
		(start 135.76173 -280.078942)
		(mid 136.044686 -280.002765)
		(end 136.327642 -280.078942)
		(width 0.0889)
		(layer "In4.Cu")
		(net "M_J_CPU1_SB_DQ<9>")
	)
	(arc
		(start 133.516116 -280.083768)
		(mid 133.699624 -280.129262)
		(end 133.881876 -280.078942)
		(width 0.0889)
		(layer "In4.Cu")
		(net "M_J_CPU1_SB_DQ<9>")
	)
	(arc
		(start 140.087604 -280.078942)
		(mid 140.269855 -280.129292)
		(end 140.453364 -280.083768)
		(width 0.0889)
		(layer "In4.Cu")
		(net "M_J_CPU1_SB_DQ<9>")
	)
	(arc
		(start 143.281654 -280.078942)
		(mid 143.56461 -280.002765)
		(end 143.847566 -280.078942)
		(width 0.0889)
		(layer "In4.Cu")
		(net "M_J_CPU1_SB_DQ<9>")
	)
	(arc
		(start 135.387588 -280.078942)
		(mid 135.569839 -280.129292)
		(end 135.753348 -280.083768)
		(width 0.0889)
		(layer "In4.Cu")
		(net "M_J_CPU1_SB_DQ<9>")
	)
	(arc
		(start 131.682998 -280.105104)
		(mid 131.840508 -280.128302)
		(end 131.993386 -280.083768)
		(width 0.0889)
		(layer "In4.Cu")
		(net "M_J_CPU1_SB_DQ<9>")
	)
	(arc
		(start 141.4018 -280.078942)
		(mid 141.684756 -280.002765)
		(end 141.967712 -280.078942)
		(width 0.0889)
		(layer "In4.Cu")
		(net "M_J_CPU1_SB_DQ<9>")
	)
	(arc
		(start 137.276078 -280.083768)
		(mid 137.459586 -280.129262)
		(end 137.641838 -280.078942)
		(width 0.0889)
		(layer "In4.Cu")
		(net "M_J_CPU1_SB_DQ<9>")
	)
	(arc
		(start 132.56768 -280.078942)
		(mid 132.749931 -280.129292)
		(end 132.93344 -280.083768)
		(width 0.0889)
		(layer "In4.Cu")
		(net "M_J_CPU1_SB_DQ<9>")
	)
	(arc
		(start 132.941822 -280.078942)
		(mid 133.224778 -280.002765)
		(end 133.507734 -280.078942)
		(width 0.0889)
		(layer "In4.Cu")
		(net "M_J_CPU1_SB_DQ<9>")
	)
	(arc
		(start 142.341854 -280.078942)
		(mid 142.62481 -280.002765)
		(end 142.907766 -280.078942)
		(width 0.0889)
		(layer "In4.Cu")
		(net "M_J_CPU1_SB_DQ<9>")
	)
	(arc
		(start 142.907766 -280.078942)
		(mid 143.09471 -280.129197)
		(end 143.281654 -280.078942)
		(width 0.0889)
		(layer "In4.Cu")
		(net "M_J_CPU1_SB_DQ<9>")
	)
	(arc
		(start 139.521692 -280.078942)
		(mid 139.804648 -280.002765)
		(end 140.087604 -280.078942)
		(width 0.0889)
		(layer "In4.Cu")
		(net "M_J_CPU1_SB_DQ<9>")
	)
	(arc
		(start 136.701784 -280.078942)
		(mid 136.98474 -280.002765)
		(end 137.267696 -280.078942)
		(width 0.0889)
		(layer "In4.Cu")
		(net "M_J_CPU1_SB_DQ<9>")
	)
	(arc
		(start 138.216132 -280.083768)
		(mid 138.39964 -280.129262)
		(end 138.581892 -280.078942)
		(width 0.0889)
		(layer "In4.Cu")
		(net "M_J_CPU1_SB_DQ<9>")
	)
	(arc
		(start 139.147804 -280.078942)
		(mid 139.334748 -280.129197)
		(end 139.521692 -280.078942)
		(width 0.0889)
		(layer "In4.Cu")
		(net "M_J_CPU1_SB_DQ<9>")
	)
	(arc
		(start 137.641838 -280.078942)
		(mid 137.924794 -280.002765)
		(end 138.20775 -280.078942)
		(width 0.0889)
		(layer "In4.Cu")
		(net "M_J_CPU1_SB_DQ<9>")
	)
	(arc
		(start 134.447788 -280.078942)
		(mid 134.634732 -280.129197)
		(end 134.821676 -280.078942)
		(width 0.0889)
		(layer "In4.Cu")
		(net "M_J_CPU1_SB_DQ<9>")
	)
	(arc
		(start 145.146014 -280.088086)
		(mid 145.413929 -279.968909)
		(end 145.704306 -279.928066)
		(width 0.0889)
		(layer "In4.Cu")
		(net "M_J_CPU1_SB_DQ<9>")
	)
	(arc
		(start 141.027658 -280.078942)
		(mid 141.209909 -280.129292)
		(end 141.393418 -280.083768)
		(width 0.0889)
		(layer "In4.Cu")
		(net "M_J_CPU1_SB_DQ<9>")
	)
	(arc
		(start 132.001768 -280.078942)
		(mid 132.284724 -280.002765)
		(end 132.56768 -280.078942)
		(width 0.0889)
		(layer "In4.Cu")
		(net "M_J_CPU1_SB_DQ<9>")
	)
	(arc
		(start 140.461746 -280.078942)
		(mid 140.744702 -280.002765)
		(end 141.027658 -280.078942)
		(width 0.0889)
		(layer "In4.Cu")
		(net "M_J_CPU1_SB_DQ<9>")
	)
	(segment
		(start 132.757926 -278.680418)
		(end 133.224778 -278.946356)
		(width 0.10668)
		(layer "F.Cu")
		(net "M_J_CPU1_SB_DQ<8>")
	)
	(segment
		(start 139.617704 -279.268936)
		(end 139.626086 -279.273762)
		(width 0.0889)
		(layer "In4.Cu")
		(net "M_J_CPU1_SB_DQ<8>")
	)
	(segment
		(start 134.343394 -279.273762)
		(end 134.351776 -279.268936)
		(width 0.0889)
		(layer "In4.Cu")
		(net "M_J_CPU1_SB_DQ<8>")
	)
	(segment
		(start 188.351922 -291.145722)
		(end 188.513466 -291.307266)
		(width 0.14478)
		(layer "In4.Cu")
		(net "M_J_CPU1_SB_DQ<8>")
	)
	(segment
		(start 142.803372 -279.273762)
		(end 142.811754 -279.268936)
		(width 0.0889)
		(layer "In4.Cu")
		(net "M_J_CPU1_SB_DQ<8>")
	)
	(segment
		(start 145.81378 -279.190196)
		(end 145.871184 -279.143206)
		(width 0.0889)
		(layer "In4.Cu")
		(net "M_J_CPU1_SB_DQ<8>")
	)
	(segment
		(start 188.190378 -290.410392)
		(end 188.351922 -290.571936)
		(width 0.14478)
		(layer "In4.Cu")
		(net "M_J_CPU1_SB_DQ<8>")
	)
	(segment
		(start 174.636938 -290.410392)
		(end 177.22469 -290.410392)
		(width 0.14478)
		(layer "In4.Cu")
		(net "M_J_CPU1_SB_DQ<8>")
	)
	(segment
		(start 166.243 -291.260276)
		(end 167.092884 -290.410392)
		(width 0.14478)
		(layer "In4.Cu")
		(net "M_J_CPU1_SB_DQ<8>")
	)
	(segment
		(start 190.006224 -290.571936)
		(end 190.167768 -290.410392)
		(width 0.14478)
		(layer "In4.Cu")
		(net "M_J_CPU1_SB_DQ<8>")
	)
	(segment
		(start 144.316196 -279.268682)
		(end 144.334484 -279.279096)
		(width 0.0889)
		(layer "In4.Cu")
		(net "M_J_CPU1_SB_DQ<8>")
	)
	(segment
		(start 188.903356 -291.145722)
		(end 188.903356 -290.571936)
		(width 0.14478)
		(layer "In4.Cu")
		(net "M_J_CPU1_SB_DQ<8>")
	)
	(segment
		(start 189.45479 -290.571936)
		(end 189.45479 -291.145722)
		(width 0.14478)
		(layer "In4.Cu")
		(net "M_J_CPU1_SB_DQ<8>")
	)
	(segment
		(start 189.293246 -290.410392)
		(end 189.45479 -290.571936)
		(width 0.14478)
		(layer "In4.Cu")
		(net "M_J_CPU1_SB_DQ<8>")
	)
	(segment
		(start 189.0649 -290.410392)
		(end 189.293246 -290.410392)
		(width 0.14478)
		(layer "In4.Cu")
		(net "M_J_CPU1_SB_DQ<8>")
	)
	(segment
		(start 189.45479 -291.145722)
		(end 189.616334 -291.307266)
		(width 0.14478)
		(layer "In4.Cu")
		(net "M_J_CPU1_SB_DQ<8>")
	)
	(segment
		(start 188.903356 -290.571936)
		(end 189.0649 -290.410392)
		(width 0.14478)
		(layer "In4.Cu")
		(net "M_J_CPU1_SB_DQ<8>")
	)
	(segment
		(start 190.006224 -291.145722)
		(end 190.006224 -290.571936)
		(width 0.14478)
		(layer "In4.Cu")
		(net "M_J_CPU1_SB_DQ<8>")
	)
	(segment
		(start 188.351922 -290.571936)
		(end 188.351922 -291.145722)
		(width 0.14478)
		(layer "In4.Cu")
		(net "M_J_CPU1_SB_DQ<8>")
	)
	(segment
		(start 143.377666 -279.268936)
		(end 143.386048 -279.273762)
		(width 0.0889)
		(layer "In4.Cu")
		(net "M_J_CPU1_SB_DQ<8>")
	)
	(segment
		(start 178.074574 -291.260276)
		(end 181.414166 -291.260276)
		(width 0.14478)
		(layer "In4.Cu")
		(net "M_J_CPU1_SB_DQ<8>")
	)
	(segment
		(start 145.871184 -279.143206)
		(end 146.362166 -278.652224)
		(width 0.0889)
		(layer "In4.Cu")
		(net "M_J_CPU1_SB_DQ<8>")
	)
	(segment
		(start 133.070854 -279.211786)
		(end 133.093206 -279.295098)
		(width 0.0889)
		(layer "In4.Cu")
		(net "M_J_CPU1_SB_DQ<8>")
	)
	(segment
		(start 151.209248 -278.61133)
		(end 163.858194 -291.260276)
		(width 0.14478)
		(layer "In4.Cu")
		(net "M_J_CPU1_SB_DQ<8>")
	)
	(segment
		(start 139.04341 -279.273762)
		(end 139.051792 -279.268936)
		(width 0.0889)
		(layer "In4.Cu")
		(net "M_J_CPU1_SB_DQ<8>")
	)
	(segment
		(start 144.294606 -279.256236)
		(end 144.316196 -279.268682)
		(width 0.0889)
		(layer "In4.Cu")
		(net "M_J_CPU1_SB_DQ<8>")
	)
	(segment
		(start 147.985226 -278.61133)
		(end 151.209248 -278.61133)
		(width 0.14478)
		(layer "In4.Cu")
		(net "M_J_CPU1_SB_DQ<8>")
	)
	(segment
		(start 144.689322 -279.268936)
		(end 144.71269 -279.25522)
		(width 0.0889)
		(layer "In4.Cu")
		(net "M_J_CPU1_SB_DQ<8>")
	)
	(segment
		(start 170.52036 -291.260276)
		(end 173.787054 -291.260276)
		(width 0.14478)
		(layer "In4.Cu")
		(net "M_J_CPU1_SB_DQ<8>")
	)
	(segment
		(start 167.092884 -290.410392)
		(end 169.670476 -290.410392)
		(width 0.14478)
		(layer "In4.Cu")
		(net "M_J_CPU1_SB_DQ<8>")
	)
	(segment
		(start 190.167768 -290.410392)
		(end 190.735458 -290.410392)
		(width 0.14478)
		(layer "In4.Cu")
		(net "M_J_CPU1_SB_DQ<8>")
	)
	(segment
		(start 173.787054 -291.260276)
		(end 174.636938 -290.410392)
		(width 0.14478)
		(layer "In4.Cu")
		(net "M_J_CPU1_SB_DQ<8>")
	)
	(segment
		(start 182.26405 -290.410392)
		(end 188.190378 -290.410392)
		(width 0.14478)
		(layer "In4.Cu")
		(net "M_J_CPU1_SB_DQ<8>")
	)
	(segment
		(start 138.103356 -279.273762)
		(end 138.111738 -279.268936)
		(width 0.0889)
		(layer "In4.Cu")
		(net "M_J_CPU1_SB_DQ<8>")
	)
	(segment
		(start 189.84468 -291.307266)
		(end 190.006224 -291.145722)
		(width 0.14478)
		(layer "In4.Cu")
		(net "M_J_CPU1_SB_DQ<8>")
	)
	(segment
		(start 163.858194 -291.260276)
		(end 166.243 -291.260276)
		(width 0.14478)
		(layer "In4.Cu")
		(net "M_J_CPU1_SB_DQ<8>")
	)
	(segment
		(start 191.160146 -290.83508)
		(end 191.160146 -290.835334)
		(width 0.14478)
		(layer "In4.Cu")
		(net "M_J_CPU1_SB_DQ<8>")
	)
	(segment
		(start 147.252944 -278.61133)
		(end 147.985226 -278.61133)
		(width 0.0889)
		(layer "In4.Cu")
		(net "M_J_CPU1_SB_DQ<8>")
	)
	(segment
		(start 145.460466 -279.313386)
		(end 145.534126 -279.30602)
		(width 0.0889)
		(layer "In4.Cu")
		(net "M_J_CPU1_SB_DQ<8>")
	)
	(segment
		(start 140.557758 -279.268936)
		(end 140.56614 -279.273762)
		(width 0.0889)
		(layer "In4.Cu")
		(net "M_J_CPU1_SB_DQ<8>")
	)
	(segment
		(start 146.362166 -278.652224)
		(end 147.21205 -278.652224)
		(width 0.0889)
		(layer "In4.Cu")
		(net "M_J_CPU1_SB_DQ<8>")
	)
	(segment
		(start 181.414166 -291.260276)
		(end 182.26405 -290.410392)
		(width 0.14478)
		(layer "In4.Cu")
		(net "M_J_CPU1_SB_DQ<8>")
	)
	(segment
		(start 177.22469 -290.410392)
		(end 178.074574 -291.260276)
		(width 0.14478)
		(layer "In4.Cu")
		(net "M_J_CPU1_SB_DQ<8>")
	)
	(segment
		(start 189.616334 -291.307266)
		(end 189.84468 -291.307266)
		(width 0.14478)
		(layer "In4.Cu")
		(net "M_J_CPU1_SB_DQ<8>")
	)
	(segment
		(start 147.21205 -278.652224)
		(end 147.252944 -278.61133)
		(width 0.0889)
		(layer "In4.Cu")
		(net "M_J_CPU1_SB_DQ<8>")
	)
	(segment
		(start 169.670476 -290.410392)
		(end 170.52036 -291.260276)
		(width 0.14478)
		(layer "In4.Cu")
		(net "M_J_CPU1_SB_DQ<8>")
	)
	(segment
		(start 188.741812 -291.307266)
		(end 188.903356 -291.145722)
		(width 0.14478)
		(layer "In4.Cu")
		(net "M_J_CPU1_SB_DQ<8>")
	)
	(segment
		(start 135.857742 -279.268936)
		(end 135.866124 -279.273762)
		(width 0.0889)
		(layer "In4.Cu")
		(net "M_J_CPU1_SB_DQ<8>")
	)
	(segment
		(start 188.513466 -291.307266)
		(end 188.741812 -291.307266)
		(width 0.14478)
		(layer "In4.Cu")
		(net "M_J_CPU1_SB_DQ<8>")
	)
	(segment
		(start 134.917688 -279.268936)
		(end 134.92607 -279.273762)
		(width 0.0889)
		(layer "In4.Cu")
		(net "M_J_CPU1_SB_DQ<8>")
	)
	(segment
		(start 190.735458 -290.410392)
		(end 191.160146 -290.83508)
		(width 0.14478)
		(layer "In4.Cu")
		(net "M_J_CPU1_SB_DQ<8>")
	)
	(segment
		(start 133.224778 -278.946356)
		(end 133.070854 -279.211786)
		(width 0.0889)
		(layer "In4.Cu")
		(net "M_J_CPU1_SB_DQ<8>")
	)
	(arc
		(start 134.351776 -279.268936)
		(mid 134.634732 -279.192759)
		(end 134.917688 -279.268936)
		(width 0.0889)
		(layer "In4.Cu")
		(net "M_J_CPU1_SB_DQ<8>")
	)
	(arc
		(start 140.56614 -279.273762)
		(mid 140.749648 -279.319256)
		(end 140.9319 -279.268936)
		(width 0.0889)
		(layer "In4.Cu")
		(net "M_J_CPU1_SB_DQ<8>")
	)
	(arc
		(start 143.751808 -279.268936)
		(mid 144.021577 -279.192913)
		(end 144.294606 -279.256236)
		(width 0.0889)
		(layer "In4.Cu")
		(net "M_J_CPU1_SB_DQ<8>")
	)
	(arc
		(start 134.92607 -279.273762)
		(mid 135.109578 -279.319256)
		(end 135.29183 -279.268936)
		(width 0.0889)
		(layer "In4.Cu")
		(net "M_J_CPU1_SB_DQ<8>")
	)
	(arc
		(start 138.67765 -279.268936)
		(mid 138.859901 -279.319286)
		(end 139.04341 -279.273762)
		(width 0.0889)
		(layer "In4.Cu")
		(net "M_J_CPU1_SB_DQ<8>")
	)
	(arc
		(start 141.497812 -279.268936)
		(mid 141.684756 -279.319191)
		(end 141.8717 -279.268936)
		(width 0.0889)
		(layer "In4.Cu")
		(net "M_J_CPU1_SB_DQ<8>")
	)
	(arc
		(start 142.437612 -279.268936)
		(mid 142.619863 -279.319286)
		(end 142.803372 -279.273762)
		(width 0.0889)
		(layer "In4.Cu")
		(net "M_J_CPU1_SB_DQ<8>")
	)
	(arc
		(start 140.9319 -279.268936)
		(mid 141.214856 -279.192759)
		(end 141.497812 -279.268936)
		(width 0.0889)
		(layer "In4.Cu")
		(net "M_J_CPU1_SB_DQ<8>")
	)
	(arc
		(start 133.093206 -279.295098)
		(mid 133.255395 -279.317833)
		(end 133.411722 -279.268936)
		(width 0.0889)
		(layer "In4.Cu")
		(net "M_J_CPU1_SB_DQ<8>")
	)
	(arc
		(start 133.977634 -279.268936)
		(mid 134.159885 -279.319286)
		(end 134.343394 -279.273762)
		(width 0.0889)
		(layer "In4.Cu")
		(net "M_J_CPU1_SB_DQ<8>")
	)
	(arc
		(start 144.334484 -279.279096)
		(mid 144.513205 -279.319019)
		(end 144.689322 -279.268936)
		(width 0.0889)
		(layer "In4.Cu")
		(net "M_J_CPU1_SB_DQ<8>")
	)
	(arc
		(start 136.797796 -279.268936)
		(mid 136.98474 -279.319191)
		(end 137.171684 -279.268936)
		(width 0.0889)
		(layer "In4.Cu")
		(net "M_J_CPU1_SB_DQ<8>")
	)
	(arc
		(start 133.411722 -279.268936)
		(mid 133.694678 -279.192759)
		(end 133.977634 -279.268936)
		(width 0.0889)
		(layer "In4.Cu")
		(net "M_J_CPU1_SB_DQ<8>")
	)
	(arc
		(start 141.8717 -279.268936)
		(mid 142.154656 -279.192759)
		(end 142.437612 -279.268936)
		(width 0.0889)
		(layer "In4.Cu")
		(net "M_J_CPU1_SB_DQ<8>")
	)
	(arc
		(start 135.29183 -279.268936)
		(mid 135.574786 -279.192759)
		(end 135.857742 -279.268936)
		(width 0.0889)
		(layer "In4.Cu")
		(net "M_J_CPU1_SB_DQ<8>")
	)
	(arc
		(start 142.811754 -279.268936)
		(mid 143.09471 -279.192759)
		(end 143.377666 -279.268936)
		(width 0.0889)
		(layer "In4.Cu")
		(net "M_J_CPU1_SB_DQ<8>")
	)
	(arc
		(start 137.171684 -279.268936)
		(mid 137.45464 -279.192759)
		(end 137.737596 -279.268936)
		(width 0.0889)
		(layer "In4.Cu")
		(net "M_J_CPU1_SB_DQ<8>")
	)
	(arc
		(start 139.626086 -279.273762)
		(mid 139.809594 -279.319256)
		(end 139.991846 -279.268936)
		(width 0.0889)
		(layer "In4.Cu")
		(net "M_J_CPU1_SB_DQ<8>")
	)
	(arc
		(start 144.71269 -279.25522)
		(mid 144.986344 -279.192277)
		(end 145.256504 -279.268936)
		(width 0.0889)
		(layer "In4.Cu")
		(net "M_J_CPU1_SB_DQ<8>")
	)
	(arc
		(start 145.534126 -279.30602)
		(mid 145.682504 -279.268763)
		(end 145.81378 -279.190196)
		(width 0.0889)
		(layer "In4.Cu")
		(net "M_J_CPU1_SB_DQ<8>")
	)
	(arc
		(start 137.737596 -279.268936)
		(mid 137.919847 -279.319286)
		(end 138.103356 -279.273762)
		(width 0.0889)
		(layer "In4.Cu")
		(net "M_J_CPU1_SB_DQ<8>")
	)
	(arc
		(start 145.256504 -279.268936)
		(mid 145.354971 -279.307276)
		(end 145.460466 -279.313386)
		(width 0.0889)
		(layer "In4.Cu")
		(net "M_J_CPU1_SB_DQ<8>")
	)
	(arc
		(start 139.051792 -279.268936)
		(mid 139.334748 -279.192759)
		(end 139.617704 -279.268936)
		(width 0.0889)
		(layer "In4.Cu")
		(net "M_J_CPU1_SB_DQ<8>")
	)
	(arc
		(start 135.866124 -279.273762)
		(mid 136.049632 -279.319256)
		(end 136.231884 -279.268936)
		(width 0.0889)
		(layer "In4.Cu")
		(net "M_J_CPU1_SB_DQ<8>")
	)
	(arc
		(start 143.386048 -279.273762)
		(mid 143.569556 -279.319256)
		(end 143.751808 -279.268936)
		(width 0.0889)
		(layer "In4.Cu")
		(net "M_J_CPU1_SB_DQ<8>")
	)
	(arc
		(start 136.231884 -279.268936)
		(mid 136.51484 -279.192759)
		(end 136.797796 -279.268936)
		(width 0.0889)
		(layer "In4.Cu")
		(net "M_J_CPU1_SB_DQ<8>")
	)
	(arc
		(start 138.111738 -279.268936)
		(mid 138.394694 -279.192759)
		(end 138.67765 -279.268936)
		(width 0.0889)
		(layer "In4.Cu")
		(net "M_J_CPU1_SB_DQ<8>")
	)
	(arc
		(start 139.991846 -279.268936)
		(mid 140.274802 -279.192759)
		(end 140.557758 -279.268936)
		(width 0.0889)
		(layer "In4.Cu")
		(net "M_J_CPU1_SB_DQ<8>")
	)
	(segment
		(start 130.877818 -278.680418)
		(end 131.34467 -278.946356)
		(width 0.10668)
		(layer "F.Cu")
		(net "M_J_CPU1_SB_DQ<7>")
	)
	(segment
		(start 185.376058 -289.326828)
		(end 185.376058 -289.707066)
		(width 0.14478)
		(layer "In4.Cu")
		(net "M_J_CPU1_SB_DQ<7>")
	)
	(segment
		(start 145.25244 -278.627332)
		(end 145.956782 -278.236172)
		(width 0.0889)
		(layer "In4.Cu")
		(net "M_J_CPU1_SB_DQ<7>")
	)
	(segment
		(start 147.409662 -278.05507)
		(end 148.019516 -278.05507)
		(width 0.0889)
		(layer "In4.Cu")
		(net "M_J_CPU1_SB_DQ<7>")
	)
	(segment
		(start 139.617704 -278.623776)
		(end 139.626086 -278.61895)
		(width 0.0889)
		(layer "In4.Cu")
		(net "M_J_CPU1_SB_DQ<7>")
	)
	(segment
		(start 185.522362 -289.85337)
		(end 185.786268 -289.85337)
		(width 0.14478)
		(layer "In4.Cu")
		(net "M_J_CPU1_SB_DQ<7>")
	)
	(segment
		(start 185.932572 -289.414458)
		(end 186.078876 -289.268154)
		(width 0.14478)
		(layer "In4.Cu")
		(net "M_J_CPU1_SB_DQ<7>")
	)
	(segment
		(start 140.557758 -278.623776)
		(end 140.56614 -278.61895)
		(width 0.0889)
		(layer "In4.Cu")
		(net "M_J_CPU1_SB_DQ<7>")
	)
	(segment
		(start 182.281068 -289.560762)
		(end 184.116726 -289.560762)
		(width 0.14478)
		(layer "In4.Cu")
		(net "M_J_CPU1_SB_DQ<7>")
	)
	(segment
		(start 174.544228 -289.560508)
		(end 177.230786 -289.560508)
		(width 0.14478)
		(layer "In4.Cu")
		(net "M_J_CPU1_SB_DQ<7>")
	)
	(segment
		(start 134.917688 -278.623776)
		(end 134.92607 -278.61895)
		(width 0.0889)
		(layer "In4.Cu")
		(net "M_J_CPU1_SB_DQ<7>")
	)
	(segment
		(start 185.786268 -289.85337)
		(end 185.932572 -289.707066)
		(width 0.14478)
		(layer "In4.Cu")
		(net "M_J_CPU1_SB_DQ<7>")
	)
	(segment
		(start 184.67324 -289.85337)
		(end 184.819544 -289.707066)
		(width 0.14478)
		(layer "In4.Cu")
		(net "M_J_CPU1_SB_DQ<7>")
	)
	(segment
		(start 186.078876 -289.268154)
		(end 186.342782 -289.268154)
		(width 0.14478)
		(layer "In4.Cu")
		(net "M_J_CPU1_SB_DQ<7>")
	)
	(segment
		(start 181.431438 -290.410392)
		(end 182.281068 -289.560762)
		(width 0.14478)
		(layer "In4.Cu")
		(net "M_J_CPU1_SB_DQ<7>")
	)
	(segment
		(start 135.857742 -278.623776)
		(end 135.866124 -278.61895)
		(width 0.0889)
		(layer "In4.Cu")
		(net "M_J_CPU1_SB_DQ<7>")
	)
	(segment
		(start 139.04341 -278.61895)
		(end 139.051792 -278.623776)
		(width 0.0889)
		(layer "In4.Cu")
		(net "M_J_CPU1_SB_DQ<7>")
	)
	(segment
		(start 163.78809 -290.410646)
		(end 165.736524 -290.410646)
		(width 0.14478)
		(layer "In4.Cu")
		(net "M_J_CPU1_SB_DQ<7>")
	)
	(segment
		(start 185.229754 -289.180524)
		(end 185.376058 -289.326828)
		(width 0.14478)
		(layer "In4.Cu")
		(net "M_J_CPU1_SB_DQ<7>")
	)
	(segment
		(start 168.947592 -289.244786)
		(end 169.263314 -289.560508)
		(width 0.14478)
		(layer "In4.Cu")
		(net "M_J_CPU1_SB_DQ<7>")
	)
	(segment
		(start 169.752772 -289.560508)
		(end 170.60291 -290.410646)
		(width 0.14478)
		(layer "In4.Cu")
		(net "M_J_CPU1_SB_DQ<7>")
	)
	(segment
		(start 168.396158 -289.560508)
		(end 168.71188 -289.244786)
		(width 0.14478)
		(layer "In4.Cu")
		(net "M_J_CPU1_SB_DQ<7>")
	)
	(segment
		(start 134.343394 -278.61895)
		(end 134.351776 -278.623776)
		(width 0.0889)
		(layer "In4.Cu")
		(net "M_J_CPU1_SB_DQ<7>")
	)
	(segment
		(start 167.29329 -289.560508)
		(end 167.609012 -289.244786)
		(width 0.14478)
		(layer "In4.Cu")
		(net "M_J_CPU1_SB_DQ<7>")
	)
	(segment
		(start 185.932572 -289.707066)
		(end 185.932572 -289.414458)
		(width 0.14478)
		(layer "In4.Cu")
		(net "M_J_CPU1_SB_DQ<7>")
	)
	(segment
		(start 178.08067 -290.410392)
		(end 181.431438 -290.410392)
		(width 0.14478)
		(layer "In4.Cu")
		(net "M_J_CPU1_SB_DQ<7>")
	)
	(segment
		(start 170.60291 -290.410646)
		(end 173.69409 -290.410646)
		(width 0.14478)
		(layer "In4.Cu")
		(net "M_J_CPU1_SB_DQ<7>")
	)
	(segment
		(start 145.956782 -278.236172)
		(end 147.22856 -278.236172)
		(width 0.0889)
		(layer "In4.Cu")
		(net "M_J_CPU1_SB_DQ<7>")
	)
	(segment
		(start 151.432514 -278.05507)
		(end 163.78809 -290.410646)
		(width 0.14478)
		(layer "In4.Cu")
		(net "M_J_CPU1_SB_DQ<7>")
	)
	(segment
		(start 132.09778 -278.623776)
		(end 132.106162 -278.61895)
		(width 0.0889)
		(layer "In4.Cu")
		(net "M_J_CPU1_SB_DQ<7>")
	)
	(segment
		(start 168.160446 -289.560508)
		(end 168.396158 -289.560508)
		(width 0.14478)
		(layer "In4.Cu")
		(net "M_J_CPU1_SB_DQ<7>")
	)
	(segment
		(start 184.819544 -289.326828)
		(end 184.965848 -289.180524)
		(width 0.14478)
		(layer "In4.Cu")
		(net "M_J_CPU1_SB_DQ<7>")
	)
	(segment
		(start 143.751808 -278.623776)
		(end 143.762222 -278.629872)
		(width 0.0889)
		(layer "In4.Cu")
		(net "M_J_CPU1_SB_DQ<7>")
	)
	(segment
		(start 148.019516 -278.05507)
		(end 151.432514 -278.05507)
		(width 0.14478)
		(layer "In4.Cu")
		(net "M_J_CPU1_SB_DQ<7>")
	)
	(segment
		(start 177.230786 -289.560508)
		(end 178.08067 -290.410392)
		(width 0.14478)
		(layer "In4.Cu")
		(net "M_J_CPU1_SB_DQ<7>")
	)
	(segment
		(start 184.819544 -289.707066)
		(end 184.819544 -289.326828)
		(width 0.14478)
		(layer "In4.Cu")
		(net "M_J_CPU1_SB_DQ<7>")
	)
	(segment
		(start 147.22856 -278.236172)
		(end 147.409662 -278.05507)
		(width 0.0889)
		(layer "In4.Cu")
		(net "M_J_CPU1_SB_DQ<7>")
	)
	(segment
		(start 184.116726 -289.560762)
		(end 184.409334 -289.85337)
		(width 0.14478)
		(layer "In4.Cu")
		(net "M_J_CPU1_SB_DQ<7>")
	)
	(segment
		(start 168.71188 -289.244786)
		(end 168.947592 -289.244786)
		(width 0.14478)
		(layer "In4.Cu")
		(net "M_J_CPU1_SB_DQ<7>")
	)
	(segment
		(start 138.103356 -278.61895)
		(end 138.111738 -278.623776)
		(width 0.0889)
		(layer "In4.Cu")
		(net "M_J_CPU1_SB_DQ<7>")
	)
	(segment
		(start 143.377666 -278.623776)
		(end 143.386048 -278.61895)
		(width 0.0889)
		(layer "In4.Cu")
		(net "M_J_CPU1_SB_DQ<7>")
	)
	(segment
		(start 131.34467 -278.946356)
		(end 131.498848 -278.680926)
		(width 0.0889)
		(layer "In4.Cu")
		(net "M_J_CPU1_SB_DQ<7>")
	)
	(segment
		(start 166.586662 -289.560508)
		(end 167.29329 -289.560508)
		(width 0.14478)
		(layer "In4.Cu")
		(net "M_J_CPU1_SB_DQ<7>")
	)
	(segment
		(start 131.498848 -278.680926)
		(end 131.595114 -278.655526)
		(width 0.0889)
		(layer "In4.Cu")
		(net "M_J_CPU1_SB_DQ<7>")
	)
	(segment
		(start 184.409334 -289.85337)
		(end 184.67324 -289.85337)
		(width 0.14478)
		(layer "In4.Cu")
		(net "M_J_CPU1_SB_DQ<7>")
	)
	(segment
		(start 142.803372 -278.61895)
		(end 142.811754 -278.623776)
		(width 0.0889)
		(layer "In4.Cu")
		(net "M_J_CPU1_SB_DQ<7>")
	)
	(segment
		(start 169.263314 -289.560508)
		(end 169.752772 -289.560508)
		(width 0.14478)
		(layer "In4.Cu")
		(net "M_J_CPU1_SB_DQ<7>")
	)
	(segment
		(start 144.684242 -278.61895)
		(end 144.692624 -278.623776)
		(width 0.0889)
		(layer "In4.Cu")
		(net "M_J_CPU1_SB_DQ<7>")
	)
	(segment
		(start 173.69409 -290.410646)
		(end 174.544228 -289.560508)
		(width 0.14478)
		(layer "In4.Cu")
		(net "M_J_CPU1_SB_DQ<7>")
	)
	(segment
		(start 165.736524 -290.410646)
		(end 166.586662 -289.560508)
		(width 0.14478)
		(layer "In4.Cu")
		(net "M_J_CPU1_SB_DQ<7>")
	)
	(segment
		(start 184.965848 -289.180524)
		(end 185.229754 -289.180524)
		(width 0.14478)
		(layer "In4.Cu")
		(net "M_J_CPU1_SB_DQ<7>")
	)
	(segment
		(start 186.342782 -289.268154)
		(end 187.060078 -289.98545)
		(width 0.14478)
		(layer "In4.Cu")
		(net "M_J_CPU1_SB_DQ<7>")
	)
	(segment
		(start 167.844724 -289.244786)
		(end 168.160446 -289.560508)
		(width 0.14478)
		(layer "In4.Cu")
		(net "M_J_CPU1_SB_DQ<7>")
	)
	(segment
		(start 185.376058 -289.707066)
		(end 185.522362 -289.85337)
		(width 0.14478)
		(layer "In4.Cu")
		(net "M_J_CPU1_SB_DQ<7>")
	)
	(segment
		(start 167.609012 -289.244786)
		(end 167.844724 -289.244786)
		(width 0.14478)
		(layer "In4.Cu")
		(net "M_J_CPU1_SB_DQ<7>")
	)
	(arc
		(start 144.692624 -278.623776)
		(mid 144.972052 -278.699942)
		(end 145.25244 -278.627332)
		(width 0.0889)
		(layer "In4.Cu")
		(net "M_J_CPU1_SB_DQ<7>")
	)
	(arc
		(start 142.811754 -278.623776)
		(mid 143.09471 -278.699953)
		(end 143.377666 -278.623776)
		(width 0.0889)
		(layer "In4.Cu")
		(net "M_J_CPU1_SB_DQ<7>")
	)
	(arc
		(start 140.56614 -278.61895)
		(mid 140.749648 -278.573456)
		(end 140.9319 -278.623776)
		(width 0.0889)
		(layer "In4.Cu")
		(net "M_J_CPU1_SB_DQ<7>")
	)
	(arc
		(start 135.866124 -278.61895)
		(mid 136.049632 -278.573456)
		(end 136.231884 -278.623776)
		(width 0.0889)
		(layer "In4.Cu")
		(net "M_J_CPU1_SB_DQ<7>")
	)
	(arc
		(start 136.797796 -278.623776)
		(mid 136.98474 -278.573521)
		(end 137.171684 -278.623776)
		(width 0.0889)
		(layer "In4.Cu")
		(net "M_J_CPU1_SB_DQ<7>")
	)
	(arc
		(start 139.991846 -278.623776)
		(mid 140.274802 -278.699953)
		(end 140.557758 -278.623776)
		(width 0.0889)
		(layer "In4.Cu")
		(net "M_J_CPU1_SB_DQ<7>")
	)
	(arc
		(start 143.762222 -278.629872)
		(mid 144.040908 -278.700092)
		(end 144.317974 -278.623776)
		(width 0.0889)
		(layer "In4.Cu")
		(net "M_J_CPU1_SB_DQ<7>")
	)
	(arc
		(start 139.051792 -278.623776)
		(mid 139.334748 -278.699953)
		(end 139.617704 -278.623776)
		(width 0.0889)
		(layer "In4.Cu")
		(net "M_J_CPU1_SB_DQ<7>")
	)
	(arc
		(start 138.111738 -278.623776)
		(mid 138.394694 -278.699953)
		(end 138.67765 -278.623776)
		(width 0.0889)
		(layer "In4.Cu")
		(net "M_J_CPU1_SB_DQ<7>")
	)
	(arc
		(start 141.497812 -278.623776)
		(mid 141.684756 -278.573521)
		(end 141.8717 -278.623776)
		(width 0.0889)
		(layer "In4.Cu")
		(net "M_J_CPU1_SB_DQ<7>")
	)
	(arc
		(start 137.171684 -278.623776)
		(mid 137.45464 -278.699953)
		(end 137.737596 -278.623776)
		(width 0.0889)
		(layer "In4.Cu")
		(net "M_J_CPU1_SB_DQ<7>")
	)
	(arc
		(start 137.737596 -278.623776)
		(mid 137.919847 -278.573426)
		(end 138.103356 -278.61895)
		(width 0.0889)
		(layer "In4.Cu")
		(net "M_J_CPU1_SB_DQ<7>")
	)
	(arc
		(start 136.231884 -278.623776)
		(mid 136.51484 -278.699953)
		(end 136.797796 -278.623776)
		(width 0.0889)
		(layer "In4.Cu")
		(net "M_J_CPU1_SB_DQ<7>")
	)
	(arc
		(start 133.411722 -278.623776)
		(mid 133.694678 -278.699953)
		(end 133.977634 -278.623776)
		(width 0.0889)
		(layer "In4.Cu")
		(net "M_J_CPU1_SB_DQ<7>")
	)
	(arc
		(start 142.437612 -278.623776)
		(mid 142.619863 -278.573426)
		(end 142.803372 -278.61895)
		(width 0.0889)
		(layer "In4.Cu")
		(net "M_J_CPU1_SB_DQ<7>")
	)
	(arc
		(start 141.8717 -278.623776)
		(mid 142.154656 -278.699953)
		(end 142.437612 -278.623776)
		(width 0.0889)
		(layer "In4.Cu")
		(net "M_J_CPU1_SB_DQ<7>")
	)
	(arc
		(start 135.29183 -278.623776)
		(mid 135.574786 -278.699953)
		(end 135.857742 -278.623776)
		(width 0.0889)
		(layer "In4.Cu")
		(net "M_J_CPU1_SB_DQ<7>")
	)
	(arc
		(start 134.351776 -278.623776)
		(mid 134.634732 -278.699953)
		(end 134.917688 -278.623776)
		(width 0.0889)
		(layer "In4.Cu")
		(net "M_J_CPU1_SB_DQ<7>")
	)
	(arc
		(start 133.037834 -278.623776)
		(mid 133.224778 -278.573521)
		(end 133.411722 -278.623776)
		(width 0.0889)
		(layer "In4.Cu")
		(net "M_J_CPU1_SB_DQ<7>")
	)
	(arc
		(start 138.67765 -278.623776)
		(mid 138.859901 -278.573426)
		(end 139.04341 -278.61895)
		(width 0.0889)
		(layer "In4.Cu")
		(net "M_J_CPU1_SB_DQ<7>")
	)
	(arc
		(start 132.471922 -278.623776)
		(mid 132.754878 -278.699953)
		(end 133.037834 -278.623776)
		(width 0.0889)
		(layer "In4.Cu")
		(net "M_J_CPU1_SB_DQ<7>")
	)
	(arc
		(start 131.595114 -278.655526)
		(mid 131.850179 -278.698877)
		(end 132.09778 -278.623776)
		(width 0.0889)
		(layer "In4.Cu")
		(net "M_J_CPU1_SB_DQ<7>")
	)
	(arc
		(start 144.317974 -278.623776)
		(mid 144.500479 -278.573299)
		(end 144.684242 -278.61895)
		(width 0.0889)
		(layer "In4.Cu")
		(net "M_J_CPU1_SB_DQ<7>")
	)
	(arc
		(start 140.9319 -278.623776)
		(mid 141.214856 -278.699953)
		(end 141.497812 -278.623776)
		(width 0.0889)
		(layer "In4.Cu")
		(net "M_J_CPU1_SB_DQ<7>")
	)
	(arc
		(start 133.977634 -278.623776)
		(mid 134.159885 -278.573426)
		(end 134.343394 -278.61895)
		(width 0.0889)
		(layer "In4.Cu")
		(net "M_J_CPU1_SB_DQ<7>")
	)
	(arc
		(start 139.626086 -278.61895)
		(mid 139.809594 -278.573456)
		(end 139.991846 -278.623776)
		(width 0.0889)
		(layer "In4.Cu")
		(net "M_J_CPU1_SB_DQ<7>")
	)
	(arc
		(start 143.386048 -278.61895)
		(mid 143.569556 -278.573456)
		(end 143.751808 -278.623776)
		(width 0.0889)
		(layer "In4.Cu")
		(net "M_J_CPU1_SB_DQ<7>")
	)
	(arc
		(start 132.106162 -278.61895)
		(mid 132.28967 -278.573456)
		(end 132.471922 -278.623776)
		(width 0.0889)
		(layer "In4.Cu")
		(net "M_J_CPU1_SB_DQ<7>")
	)
	(arc
		(start 134.92607 -278.61895)
		(mid 135.109578 -278.573456)
		(end 135.29183 -278.623776)
		(width 0.0889)
		(layer "In4.Cu")
		(net "M_J_CPU1_SB_DQ<7>")
	)
	(segment
		(start 132.287772 -277.870412)
		(end 132.754878 -278.13635)
		(width 0.10668)
		(layer "F.Cu")
		(net "M_J_CPU1_SB_DQ<6>")
	)
	(segment
		(start 151.79548 -277.14575)
		(end 159.360616 -284.710886)
		(width 0.14478)
		(layer "In4.Cu")
		(net "M_J_CPU1_SB_DQ<6>")
	)
	(segment
		(start 160.111186 -284.500828)
		(end 160.302702 -284.692344)
		(width 0.14478)
		(layer "In4.Cu")
		(net "M_J_CPU1_SB_DQ<6>")
	)
	(segment
		(start 144.220946 -277.814024)
		(end 144.242536 -277.82647)
		(width 0.0889)
		(layer "In4.Cu")
		(net "M_J_CPU1_SB_DQ<6>")
	)
	(segment
		(start 181.97195 -287.860486)
		(end 186.635136 -287.860486)
		(width 0.14478)
		(layer "In4.Cu")
		(net "M_J_CPU1_SB_DQ<6>")
	)
	(segment
		(start 138.20775 -277.81377)
		(end 138.216132 -277.808944)
		(width 0.0889)
		(layer "In4.Cu")
		(net "M_J_CPU1_SB_DQ<6>")
	)
	(segment
		(start 135.753348 -277.808944)
		(end 135.76173 -277.81377)
		(width 0.0889)
		(layer "In4.Cu")
		(net "M_J_CPU1_SB_DQ<6>")
	)
	(segment
		(start 159.630872 -284.710886)
		(end 159.84093 -284.500828)
		(width 0.14478)
		(layer "In4.Cu")
		(net "M_J_CPU1_SB_DQ<6>")
	)
	(segment
		(start 159.360616 -284.710886)
		(end 159.630872 -284.710886)
		(width 0.14478)
		(layer "In4.Cu")
		(net "M_J_CPU1_SB_DQ<6>")
	)
	(segment
		(start 162.14979 -286.809688)
		(end 161.939732 -287.019746)
		(width 0.14478)
		(layer "In4.Cu")
		(net "M_J_CPU1_SB_DQ<6>")
	)
	(segment
		(start 160.28416 -285.63443)
		(end 160.554416 -285.63443)
		(width 0.14478)
		(layer "In4.Cu")
		(net "M_J_CPU1_SB_DQ<6>")
	)
	(segment
		(start 141.393418 -277.808944)
		(end 141.4018 -277.81377)
		(width 0.0889)
		(layer "In4.Cu")
		(net "M_J_CPU1_SB_DQ<6>")
	)
	(segment
		(start 178.330606 -288.71037)
		(end 181.122066 -288.71037)
		(width 0.14478)
		(layer "In4.Cu")
		(net "M_J_CPU1_SB_DQ<6>")
	)
	(segment
		(start 162.611562 -287.27146)
		(end 162.881818 -287.27146)
		(width 0.14478)
		(layer "In4.Cu")
		(net "M_J_CPU1_SB_DQ<6>")
	)
	(segment
		(start 160.302702 -284.9626)
		(end 160.092644 -285.172658)
		(width 0.14478)
		(layer "In4.Cu")
		(net "M_J_CPU1_SB_DQ<6>")
	)
	(segment
		(start 161.688018 -286.347916)
		(end 161.958274 -286.347916)
		(width 0.14478)
		(layer "In4.Cu")
		(net "M_J_CPU1_SB_DQ<6>")
	)
	(segment
		(start 170.988482 -288.710624)
		(end 173.69409 -288.710624)
		(width 0.14478)
		(layer "In4.Cu")
		(net "M_J_CPU1_SB_DQ<6>")
	)
	(segment
		(start 162.131248 -287.481518)
		(end 162.401504 -287.481518)
		(width 0.14478)
		(layer "In4.Cu")
		(net "M_J_CPU1_SB_DQ<6>")
	)
	(segment
		(start 161.939732 -287.290002)
		(end 162.131248 -287.481518)
		(width 0.14478)
		(layer "In4.Cu")
		(net "M_J_CPU1_SB_DQ<6>")
	)
	(segment
		(start 144.20088 -277.802594)
		(end 144.220946 -277.814024)
		(width 0.0889)
		(layer "In4.Cu")
		(net "M_J_CPU1_SB_DQ<6>")
	)
	(segment
		(start 159.84093 -284.500828)
		(end 160.111186 -284.500828)
		(width 0.14478)
		(layer "In4.Cu")
		(net "M_J_CPU1_SB_DQ<6>")
	)
	(segment
		(start 133.507734 -277.81377)
		(end 133.516116 -277.808944)
		(width 0.0889)
		(layer "In4.Cu")
		(net "M_J_CPU1_SB_DQ<6>")
	)
	(segment
		(start 162.14979 -286.539432)
		(end 162.14979 -286.809688)
		(width 0.14478)
		(layer "In4.Cu")
		(net "M_J_CPU1_SB_DQ<6>")
	)
	(segment
		(start 161.207704 -286.557974)
		(end 161.47796 -286.557974)
		(width 0.14478)
		(layer "In4.Cu")
		(net "M_J_CPU1_SB_DQ<6>")
	)
	(segment
		(start 160.302702 -284.692344)
		(end 160.302702 -284.9626)
		(width 0.14478)
		(layer "In4.Cu")
		(net "M_J_CPU1_SB_DQ<6>")
	)
	(segment
		(start 160.092644 -285.442914)
		(end 160.28416 -285.63443)
		(width 0.14478)
		(layer "In4.Cu")
		(net "M_J_CPU1_SB_DQ<6>")
	)
	(segment
		(start 147.998434 -277.14575)
		(end 151.79548 -277.14575)
		(width 0.14478)
		(layer "In4.Cu")
		(net "M_J_CPU1_SB_DQ<6>")
	)
	(segment
		(start 146.037046 -277.318724)
		(end 146.21002 -277.14575)
		(width 0.0889)
		(layer "In4.Cu")
		(net "M_J_CPU1_SB_DQ<6>")
	)
	(segment
		(start 140.453364 -277.808944)
		(end 140.461746 -277.81377)
		(width 0.0889)
		(layer "In4.Cu")
		(net "M_J_CPU1_SB_DQ<6>")
	)
	(segment
		(start 144.785334 -277.81377)
		(end 144.80413 -277.802848)
		(width 0.0889)
		(layer "In4.Cu")
		(net "M_J_CPU1_SB_DQ<6>")
	)
	(segment
		(start 161.939732 -287.019746)
		(end 161.939732 -287.290002)
		(width 0.14478)
		(layer "In4.Cu")
		(net "M_J_CPU1_SB_DQ<6>")
	)
	(segment
		(start 163.073334 -287.462976)
		(end 163.073334 -287.733232)
		(width 0.14478)
		(layer "In4.Cu")
		(net "M_J_CPU1_SB_DQ<6>")
	)
	(segment
		(start 162.863276 -287.94329)
		(end 162.863276 -288.213546)
		(width 0.14478)
		(layer "In4.Cu")
		(net "M_J_CPU1_SB_DQ<6>")
	)
	(segment
		(start 160.554416 -285.63443)
		(end 160.764474 -285.424372)
		(width 0.14478)
		(layer "In4.Cu")
		(net "M_J_CPU1_SB_DQ<6>")
	)
	(segment
		(start 132.754878 -278.13635)
		(end 132.908802 -277.87092)
		(width 0.0889)
		(layer "In4.Cu")
		(net "M_J_CPU1_SB_DQ<6>")
	)
	(segment
		(start 167.000174 -287.860486)
		(end 170.138344 -287.860486)
		(width 0.14478)
		(layer "In4.Cu")
		(net "M_J_CPU1_SB_DQ<6>")
	)
	(segment
		(start 173.69409 -288.710624)
		(end 174.544228 -287.860486)
		(width 0.14478)
		(layer "In4.Cu")
		(net "M_J_CPU1_SB_DQ<6>")
	)
	(segment
		(start 162.401504 -287.481518)
		(end 162.611562 -287.27146)
		(width 0.14478)
		(layer "In4.Cu")
		(net "M_J_CPU1_SB_DQ<6>")
	)
	(segment
		(start 132.908802 -277.87092)
		(end 133.004814 -277.84552)
		(width 0.0889)
		(layer "In4.Cu")
		(net "M_J_CPU1_SB_DQ<6>")
	)
	(segment
		(start 137.267696 -277.81377)
		(end 137.276078 -277.808944)
		(width 0.0889)
		(layer "In4.Cu")
		(net "M_J_CPU1_SB_DQ<6>")
	)
	(segment
		(start 170.138344 -287.860486)
		(end 170.988482 -288.710624)
		(width 0.14478)
		(layer "In4.Cu")
		(net "M_J_CPU1_SB_DQ<6>")
	)
	(segment
		(start 161.226246 -285.886144)
		(end 161.016188 -286.096202)
		(width 0.14478)
		(layer "In4.Cu")
		(net "M_J_CPU1_SB_DQ<6>")
	)
	(segment
		(start 160.092644 -285.172658)
		(end 160.092644 -285.442914)
		(width 0.14478)
		(layer "In4.Cu")
		(net "M_J_CPU1_SB_DQ<6>")
	)
	(segment
		(start 177.480722 -287.860486)
		(end 178.330606 -288.71037)
		(width 0.14478)
		(layer "In4.Cu")
		(net "M_J_CPU1_SB_DQ<6>")
	)
	(segment
		(start 161.03473 -285.424372)
		(end 161.226246 -285.615888)
		(width 0.14478)
		(layer "In4.Cu")
		(net "M_J_CPU1_SB_DQ<6>")
	)
	(segment
		(start 161.016188 -286.096202)
		(end 161.016188 -286.366458)
		(width 0.14478)
		(layer "In4.Cu")
		(net "M_J_CPU1_SB_DQ<6>")
	)
	(segment
		(start 161.226246 -285.615888)
		(end 161.226246 -285.886144)
		(width 0.14478)
		(layer "In4.Cu")
		(net "M_J_CPU1_SB_DQ<6>")
	)
	(segment
		(start 146.21002 -277.14575)
		(end 147.998434 -277.14575)
		(width 0.0889)
		(layer "In4.Cu")
		(net "M_J_CPU1_SB_DQ<6>")
	)
	(segment
		(start 136.693402 -277.808944)
		(end 136.701784 -277.81377)
		(width 0.0889)
		(layer "In4.Cu")
		(net "M_J_CPU1_SB_DQ<6>")
	)
	(segment
		(start 162.863276 -288.213546)
		(end 163.360354 -288.710624)
		(width 0.14478)
		(layer "In4.Cu")
		(net "M_J_CPU1_SB_DQ<6>")
	)
	(segment
		(start 174.544228 -287.860486)
		(end 177.480722 -287.860486)
		(width 0.14478)
		(layer "In4.Cu")
		(net "M_J_CPU1_SB_DQ<6>")
	)
	(segment
		(start 160.764474 -285.424372)
		(end 161.03473 -285.424372)
		(width 0.14478)
		(layer "In4.Cu")
		(net "M_J_CPU1_SB_DQ<6>")
	)
	(segment
		(start 161.016188 -286.366458)
		(end 161.207704 -286.557974)
		(width 0.14478)
		(layer "In4.Cu")
		(net "M_J_CPU1_SB_DQ<6>")
	)
	(segment
		(start 161.958274 -286.347916)
		(end 162.14979 -286.539432)
		(width 0.14478)
		(layer "In4.Cu")
		(net "M_J_CPU1_SB_DQ<6>")
	)
	(segment
		(start 146.037046 -277.395686)
		(end 146.037046 -277.318724)
		(width 0.0889)
		(layer "In4.Cu")
		(net "M_J_CPU1_SB_DQ<6>")
	)
	(segment
		(start 162.881818 -287.27146)
		(end 163.073334 -287.462976)
		(width 0.14478)
		(layer "In4.Cu")
		(net "M_J_CPU1_SB_DQ<6>")
	)
	(segment
		(start 141.967712 -277.81377)
		(end 141.976094 -277.808944)
		(width 0.0889)
		(layer "In4.Cu")
		(net "M_J_CPU1_SB_DQ<6>")
	)
	(segment
		(start 163.073334 -287.733232)
		(end 162.863276 -287.94329)
		(width 0.14478)
		(layer "In4.Cu")
		(net "M_J_CPU1_SB_DQ<6>")
	)
	(segment
		(start 161.47796 -286.557974)
		(end 161.688018 -286.347916)
		(width 0.14478)
		(layer "In4.Cu")
		(net "M_J_CPU1_SB_DQ<6>")
	)
	(segment
		(start 163.360354 -288.710624)
		(end 166.150036 -288.710624)
		(width 0.14478)
		(layer "In4.Cu")
		(net "M_J_CPU1_SB_DQ<6>")
	)
	(segment
		(start 186.635136 -287.860486)
		(end 187.060078 -288.285428)
		(width 0.14478)
		(layer "In4.Cu")
		(net "M_J_CPU1_SB_DQ<6>")
	)
	(segment
		(start 181.122066 -288.71037)
		(end 181.97195 -287.860486)
		(width 0.14478)
		(layer "In4.Cu")
		(net "M_J_CPU1_SB_DQ<6>")
	)
	(segment
		(start 166.150036 -288.710624)
		(end 167.000174 -287.860486)
		(width 0.14478)
		(layer "In4.Cu")
		(net "M_J_CPU1_SB_DQ<6>")
	)
	(arc
		(start 139.147804 -277.81377)
		(mid 139.334748 -277.763515)
		(end 139.521692 -277.81377)
		(width 0.0889)
		(layer "In4.Cu")
		(net "M_J_CPU1_SB_DQ<6>")
	)
	(arc
		(start 138.216132 -277.808944)
		(mid 138.39964 -277.76345)
		(end 138.581892 -277.81377)
		(width 0.0889)
		(layer "In4.Cu")
		(net "M_J_CPU1_SB_DQ<6>")
	)
	(arc
		(start 134.447788 -277.81377)
		(mid 134.634732 -277.763515)
		(end 134.821676 -277.81377)
		(width 0.0889)
		(layer "In4.Cu")
		(net "M_J_CPU1_SB_DQ<6>")
	)
	(arc
		(start 136.701784 -277.81377)
		(mid 136.98474 -277.889947)
		(end 137.267696 -277.81377)
		(width 0.0889)
		(layer "In4.Cu")
		(net "M_J_CPU1_SB_DQ<6>")
	)
	(arc
		(start 133.004814 -277.84552)
		(mid 133.260022 -277.888997)
		(end 133.507734 -277.81377)
		(width 0.0889)
		(layer "In4.Cu")
		(net "M_J_CPU1_SB_DQ<6>")
	)
	(arc
		(start 143.281654 -277.81377)
		(mid 143.56461 -277.889947)
		(end 143.847566 -277.81377)
		(width 0.0889)
		(layer "In4.Cu")
		(net "M_J_CPU1_SB_DQ<6>")
	)
	(arc
		(start 140.087604 -277.81377)
		(mid 140.269855 -277.76342)
		(end 140.453364 -277.808944)
		(width 0.0889)
		(layer "In4.Cu")
		(net "M_J_CPU1_SB_DQ<6>")
	)
	(arc
		(start 141.4018 -277.81377)
		(mid 141.684756 -277.889947)
		(end 141.967712 -277.81377)
		(width 0.0889)
		(layer "In4.Cu")
		(net "M_J_CPU1_SB_DQ<6>")
	)
	(arc
		(start 143.847566 -277.81377)
		(mid 144.022805 -277.763699)
		(end 144.20088 -277.802594)
		(width 0.0889)
		(layer "In4.Cu")
		(net "M_J_CPU1_SB_DQ<6>")
	)
	(arc
		(start 142.341854 -277.81377)
		(mid 142.62481 -277.889947)
		(end 142.907766 -277.81377)
		(width 0.0889)
		(layer "In4.Cu")
		(net "M_J_CPU1_SB_DQ<6>")
	)
	(arc
		(start 144.80413 -277.802848)
		(mid 144.983701 -277.763031)
		(end 145.160492 -277.81377)
		(width 0.0889)
		(layer "In4.Cu")
		(net "M_J_CPU1_SB_DQ<6>")
	)
	(arc
		(start 137.276078 -277.808944)
		(mid 137.459586 -277.76345)
		(end 137.641838 -277.81377)
		(width 0.0889)
		(layer "In4.Cu")
		(net "M_J_CPU1_SB_DQ<6>")
	)
	(arc
		(start 145.160492 -277.81377)
		(mid 145.297519 -277.872774)
		(end 145.444718 -277.897082)
		(width 0.0889)
		(layer "In4.Cu")
		(net "M_J_CPU1_SB_DQ<6>")
	)
	(arc
		(start 141.027658 -277.81377)
		(mid 141.209909 -277.76342)
		(end 141.393418 -277.808944)
		(width 0.0889)
		(layer "In4.Cu")
		(net "M_J_CPU1_SB_DQ<6>")
	)
	(arc
		(start 145.878804 -277.730966)
		(mid 145.987076 -277.577087)
		(end 146.037046 -277.395686)
		(width 0.0889)
		(layer "In4.Cu")
		(net "M_J_CPU1_SB_DQ<6>")
	)
	(arc
		(start 145.444718 -277.897082)
		(mid 145.678917 -277.858865)
		(end 145.878804 -277.730966)
		(width 0.0889)
		(layer "In4.Cu")
		(net "M_J_CPU1_SB_DQ<6>")
	)
	(arc
		(start 144.242536 -277.82647)
		(mid 144.515565 -277.889789)
		(end 144.785334 -277.81377)
		(width 0.0889)
		(layer "In4.Cu")
		(net "M_J_CPU1_SB_DQ<6>")
	)
	(arc
		(start 140.461746 -277.81377)
		(mid 140.744702 -277.889947)
		(end 141.027658 -277.81377)
		(width 0.0889)
		(layer "In4.Cu")
		(net "M_J_CPU1_SB_DQ<6>")
	)
	(arc
		(start 141.976094 -277.808944)
		(mid 142.159602 -277.76345)
		(end 142.341854 -277.81377)
		(width 0.0889)
		(layer "In4.Cu")
		(net "M_J_CPU1_SB_DQ<6>")
	)
	(arc
		(start 133.516116 -277.808944)
		(mid 133.699624 -277.76345)
		(end 133.881876 -277.81377)
		(width 0.0889)
		(layer "In4.Cu")
		(net "M_J_CPU1_SB_DQ<6>")
	)
	(arc
		(start 134.821676 -277.81377)
		(mid 135.104632 -277.889947)
		(end 135.387588 -277.81377)
		(width 0.0889)
		(layer "In4.Cu")
		(net "M_J_CPU1_SB_DQ<6>")
	)
	(arc
		(start 135.387588 -277.81377)
		(mid 135.569839 -277.76342)
		(end 135.753348 -277.808944)
		(width 0.0889)
		(layer "In4.Cu")
		(net "M_J_CPU1_SB_DQ<6>")
	)
	(arc
		(start 135.76173 -277.81377)
		(mid 136.044686 -277.889947)
		(end 136.327642 -277.81377)
		(width 0.0889)
		(layer "In4.Cu")
		(net "M_J_CPU1_SB_DQ<6>")
	)
	(arc
		(start 136.327642 -277.81377)
		(mid 136.509893 -277.76342)
		(end 136.693402 -277.808944)
		(width 0.0889)
		(layer "In4.Cu")
		(net "M_J_CPU1_SB_DQ<6>")
	)
	(arc
		(start 142.907766 -277.81377)
		(mid 143.09471 -277.763515)
		(end 143.281654 -277.81377)
		(width 0.0889)
		(layer "In4.Cu")
		(net "M_J_CPU1_SB_DQ<6>")
	)
	(arc
		(start 137.641838 -277.81377)
		(mid 137.924794 -277.889947)
		(end 138.20775 -277.81377)
		(width 0.0889)
		(layer "In4.Cu")
		(net "M_J_CPU1_SB_DQ<6>")
	)
	(arc
		(start 138.581892 -277.81377)
		(mid 138.864848 -277.889947)
		(end 139.147804 -277.81377)
		(width 0.0889)
		(layer "In4.Cu")
		(net "M_J_CPU1_SB_DQ<6>")
	)
	(arc
		(start 133.881876 -277.81377)
		(mid 134.164832 -277.889947)
		(end 134.447788 -277.81377)
		(width 0.0889)
		(layer "In4.Cu")
		(net "M_J_CPU1_SB_DQ<6>")
	)
	(arc
		(start 139.521692 -277.81377)
		(mid 139.804648 -277.889947)
		(end 140.087604 -277.81377)
		(width 0.0889)
		(layer "In4.Cu")
		(net "M_J_CPU1_SB_DQ<6>")
	)
	(segment
		(start 131.347972 -277.870412)
		(end 131.814824 -278.13635)
		(width 0.10668)
		(layer "F.Cu")
		(net "M_J_CPU1_SB_DQ<5>")
	)
	(segment
		(start 183.020716 -288.71037)
		(end 185.62447 -288.71037)
		(width 0.14478)
		(layer "In4.Cu")
		(net "M_J_CPU1_SB_DQ<5>")
	)
	(segment
		(start 185.62447 -288.71037)
		(end 185.624724 -288.710624)
		(width 0.14478)
		(layer "In4.Cu")
		(net "M_J_CPU1_SB_DQ<5>")
	)
	(segment
		(start 169.0751 -288.710624)
		(end 171.126912 -289.560508)
		(width 0.14478)
		(layer "In4.Cu")
		(net "M_J_CPU1_SB_DQ<5>")
	)
	(segment
		(start 140.453364 -278.463756)
		(end 140.461746 -278.45893)
		(width 0.0889)
		(layer "In4.Cu")
		(net "M_J_CPU1_SB_DQ<5>")
	)
	(segment
		(start 131.993386 -278.463756)
		(end 132.001768 -278.45893)
		(width 0.0889)
		(layer "In4.Cu")
		(net "M_J_CPU1_SB_DQ<5>")
	)
	(segment
		(start 147.92833 -277.60041)
		(end 151.614124 -277.60041)
		(width 0.14478)
		(layer "In4.Cu")
		(net "M_J_CPU1_SB_DQ<5>")
	)
	(segment
		(start 147.274026 -277.511764)
		(end 147.362672 -277.60041)
		(width 0.0889)
		(layer "In4.Cu")
		(net "M_J_CPU1_SB_DQ<5>")
	)
	(segment
		(start 151.614124 -277.60041)
		(end 163.574222 -289.560508)
		(width 0.14478)
		(layer "In4.Cu")
		(net "M_J_CPU1_SB_DQ<5>")
	)
	(segment
		(start 146.763486 -277.511764)
		(end 147.274026 -277.511764)
		(width 0.0889)
		(layer "In4.Cu")
		(net "M_J_CPU1_SB_DQ<5>")
	)
	(segment
		(start 165.386512 -289.560508)
		(end 167.438324 -288.710624)
		(width 0.14478)
		(layer "In4.Cu")
		(net "M_J_CPU1_SB_DQ<5>")
	)
	(segment
		(start 131.660646 -278.40178)
		(end 131.682998 -278.485092)
		(width 0.0889)
		(layer "In4.Cu")
		(net "M_J_CPU1_SB_DQ<5>")
	)
	(segment
		(start 171.126912 -289.560508)
		(end 172.945298 -289.560508)
		(width 0.14478)
		(layer "In4.Cu")
		(net "M_J_CPU1_SB_DQ<5>")
	)
	(segment
		(start 147.362672 -277.60041)
		(end 147.92833 -277.60041)
		(width 0.0889)
		(layer "In4.Cu")
		(net "M_J_CPU1_SB_DQ<5>")
	)
	(segment
		(start 145.146014 -278.468074)
		(end 146.763486 -277.511764)
		(width 0.0889)
		(layer "In4.Cu")
		(net "M_J_CPU1_SB_DQ<5>")
	)
	(segment
		(start 132.93344 -278.463756)
		(end 132.941822 -278.45893)
		(width 0.0889)
		(layer "In4.Cu")
		(net "M_J_CPU1_SB_DQ<5>")
	)
	(segment
		(start 143.847566 -278.45893)
		(end 143.855948 -278.463756)
		(width 0.0889)
		(layer "In4.Cu")
		(net "M_J_CPU1_SB_DQ<5>")
	)
	(segment
		(start 141.967712 -278.45893)
		(end 141.976094 -278.463756)
		(width 0.0889)
		(layer "In4.Cu")
		(net "M_J_CPU1_SB_DQ<5>")
	)
	(segment
		(start 131.814824 -278.13635)
		(end 131.660646 -278.40178)
		(width 0.0889)
		(layer "In4.Cu")
		(net "M_J_CPU1_SB_DQ<5>")
	)
	(segment
		(start 172.945298 -289.560508)
		(end 174.99711 -288.710624)
		(width 0.14478)
		(layer "In4.Cu")
		(net "M_J_CPU1_SB_DQ<5>")
	)
	(segment
		(start 174.99711 -288.710624)
		(end 176.694338 -288.710624)
		(width 0.14478)
		(layer "In4.Cu")
		(net "M_J_CPU1_SB_DQ<5>")
	)
	(segment
		(start 144.777968 -278.452834)
		(end 144.788382 -278.45893)
		(width 0.0889)
		(layer "In4.Cu")
		(net "M_J_CPU1_SB_DQ<5>")
	)
	(segment
		(start 133.507734 -278.45893)
		(end 133.516116 -278.463756)
		(width 0.0889)
		(layer "In4.Cu")
		(net "M_J_CPU1_SB_DQ<5>")
	)
	(segment
		(start 137.267696 -278.45893)
		(end 137.276078 -278.463756)
		(width 0.0889)
		(layer "In4.Cu")
		(net "M_J_CPU1_SB_DQ<5>")
	)
	(segment
		(start 176.694338 -288.710624)
		(end 178.74615 -289.560508)
		(width 0.14478)
		(layer "In4.Cu")
		(net "M_J_CPU1_SB_DQ<5>")
	)
	(segment
		(start 138.20775 -278.45893)
		(end 138.216132 -278.463756)
		(width 0.0889)
		(layer "In4.Cu")
		(net "M_J_CPU1_SB_DQ<5>")
	)
	(segment
		(start 141.393418 -278.463756)
		(end 141.4018 -278.45893)
		(width 0.0889)
		(layer "In4.Cu")
		(net "M_J_CPU1_SB_DQ<5>")
	)
	(segment
		(start 135.753348 -278.463756)
		(end 135.76173 -278.45893)
		(width 0.0889)
		(layer "In4.Cu")
		(net "M_J_CPU1_SB_DQ<5>")
	)
	(segment
		(start 136.693402 -278.463756)
		(end 136.701784 -278.45893)
		(width 0.0889)
		(layer "In4.Cu")
		(net "M_J_CPU1_SB_DQ<5>")
	)
	(segment
		(start 163.574222 -289.560508)
		(end 165.386512 -289.560508)
		(width 0.14478)
		(layer "In4.Cu")
		(net "M_J_CPU1_SB_DQ<5>")
	)
	(segment
		(start 189.024768 -288.710624)
		(end 191.160146 -289.135312)
		(width 0.14478)
		(layer "In4.Cu")
		(net "M_J_CPU1_SB_DQ<5>")
	)
	(segment
		(start 178.74615 -289.560508)
		(end 180.968142 -289.560508)
		(width 0.14478)
		(layer "In4.Cu")
		(net "M_J_CPU1_SB_DQ<5>")
	)
	(segment
		(start 167.438324 -288.710624)
		(end 169.0751 -288.710624)
		(width 0.14478)
		(layer "In4.Cu")
		(net "M_J_CPU1_SB_DQ<5>")
	)
	(segment
		(start 185.624724 -288.710624)
		(end 189.024768 -288.710624)
		(width 0.14478)
		(layer "In4.Cu")
		(net "M_J_CPU1_SB_DQ<5>")
	)
	(segment
		(start 180.968142 -289.560508)
		(end 183.020716 -288.71037)
		(width 0.14478)
		(layer "In4.Cu")
		(net "M_J_CPU1_SB_DQ<5>")
	)
	(arc
		(start 138.216132 -278.463756)
		(mid 138.39964 -278.50925)
		(end 138.581892 -278.45893)
		(width 0.0889)
		(layer "In4.Cu")
		(net "M_J_CPU1_SB_DQ<5>")
	)
	(arc
		(start 142.907766 -278.45893)
		(mid 143.09471 -278.509185)
		(end 143.281654 -278.45893)
		(width 0.0889)
		(layer "In4.Cu")
		(net "M_J_CPU1_SB_DQ<5>")
	)
	(arc
		(start 136.701784 -278.45893)
		(mid 136.98474 -278.382753)
		(end 137.267696 -278.45893)
		(width 0.0889)
		(layer "In4.Cu")
		(net "M_J_CPU1_SB_DQ<5>")
	)
	(arc
		(start 139.521692 -278.45893)
		(mid 139.804648 -278.382753)
		(end 140.087604 -278.45893)
		(width 0.0889)
		(layer "In4.Cu")
		(net "M_J_CPU1_SB_DQ<5>")
	)
	(arc
		(start 143.855948 -278.463756)
		(mid 144.03971 -278.509372)
		(end 144.222216 -278.45893)
		(width 0.0889)
		(layer "In4.Cu")
		(net "M_J_CPU1_SB_DQ<5>")
	)
	(arc
		(start 137.276078 -278.463756)
		(mid 137.459586 -278.50925)
		(end 137.641838 -278.45893)
		(width 0.0889)
		(layer "In4.Cu")
		(net "M_J_CPU1_SB_DQ<5>")
	)
	(arc
		(start 133.516116 -278.463756)
		(mid 133.699624 -278.50925)
		(end 133.881876 -278.45893)
		(width 0.0889)
		(layer "In4.Cu")
		(net "M_J_CPU1_SB_DQ<5>")
	)
	(arc
		(start 136.327642 -278.45893)
		(mid 136.509893 -278.50928)
		(end 136.693402 -278.463756)
		(width 0.0889)
		(layer "In4.Cu")
		(net "M_J_CPU1_SB_DQ<5>")
	)
	(arc
		(start 140.087604 -278.45893)
		(mid 140.269855 -278.50928)
		(end 140.453364 -278.463756)
		(width 0.0889)
		(layer "In4.Cu")
		(net "M_J_CPU1_SB_DQ<5>")
	)
	(arc
		(start 143.281654 -278.45893)
		(mid 143.56461 -278.382753)
		(end 143.847566 -278.45893)
		(width 0.0889)
		(layer "In4.Cu")
		(net "M_J_CPU1_SB_DQ<5>")
	)
	(arc
		(start 140.461746 -278.45893)
		(mid 140.744702 -278.382753)
		(end 141.027658 -278.45893)
		(width 0.0889)
		(layer "In4.Cu")
		(net "M_J_CPU1_SB_DQ<5>")
	)
	(arc
		(start 138.581892 -278.45893)
		(mid 138.864848 -278.382753)
		(end 139.147804 -278.45893)
		(width 0.0889)
		(layer "In4.Cu")
		(net "M_J_CPU1_SB_DQ<5>")
	)
	(arc
		(start 144.788382 -278.45893)
		(mid 144.966032 -278.50919)
		(end 145.146014 -278.468074)
		(width 0.0889)
		(layer "In4.Cu")
		(net "M_J_CPU1_SB_DQ<5>")
	)
	(arc
		(start 133.881876 -278.45893)
		(mid 134.164832 -278.382753)
		(end 134.447788 -278.45893)
		(width 0.0889)
		(layer "In4.Cu")
		(net "M_J_CPU1_SB_DQ<5>")
	)
	(arc
		(start 135.387588 -278.45893)
		(mid 135.569839 -278.50928)
		(end 135.753348 -278.463756)
		(width 0.0889)
		(layer "In4.Cu")
		(net "M_J_CPU1_SB_DQ<5>")
	)
	(arc
		(start 141.027658 -278.45893)
		(mid 141.209909 -278.50928)
		(end 141.393418 -278.463756)
		(width 0.0889)
		(layer "In4.Cu")
		(net "M_J_CPU1_SB_DQ<5>")
	)
	(arc
		(start 132.941822 -278.45893)
		(mid 133.224778 -278.382753)
		(end 133.507734 -278.45893)
		(width 0.0889)
		(layer "In4.Cu")
		(net "M_J_CPU1_SB_DQ<5>")
	)
	(arc
		(start 142.341854 -278.45893)
		(mid 142.62481 -278.382753)
		(end 142.907766 -278.45893)
		(width 0.0889)
		(layer "In4.Cu")
		(net "M_J_CPU1_SB_DQ<5>")
	)
	(arc
		(start 137.641838 -278.45893)
		(mid 137.924794 -278.382753)
		(end 138.20775 -278.45893)
		(width 0.0889)
		(layer "In4.Cu")
		(net "M_J_CPU1_SB_DQ<5>")
	)
	(arc
		(start 132.001768 -278.45893)
		(mid 132.284724 -278.382753)
		(end 132.56768 -278.45893)
		(width 0.0889)
		(layer "In4.Cu")
		(net "M_J_CPU1_SB_DQ<5>")
	)
	(arc
		(start 135.76173 -278.45893)
		(mid 136.044686 -278.382753)
		(end 136.327642 -278.45893)
		(width 0.0889)
		(layer "In4.Cu")
		(net "M_J_CPU1_SB_DQ<5>")
	)
	(arc
		(start 144.222216 -278.45893)
		(mid 144.499283 -278.382659)
		(end 144.777968 -278.452834)
		(width 0.0889)
		(layer "In4.Cu")
		(net "M_J_CPU1_SB_DQ<5>")
	)
	(arc
		(start 139.147804 -278.45893)
		(mid 139.334748 -278.509185)
		(end 139.521692 -278.45893)
		(width 0.0889)
		(layer "In4.Cu")
		(net "M_J_CPU1_SB_DQ<5>")
	)
	(arc
		(start 134.821676 -278.45893)
		(mid 135.104632 -278.382753)
		(end 135.387588 -278.45893)
		(width 0.0889)
		(layer "In4.Cu")
		(net "M_J_CPU1_SB_DQ<5>")
	)
	(arc
		(start 131.682998 -278.485092)
		(mid 131.840508 -278.50829)
		(end 131.993386 -278.463756)
		(width 0.0889)
		(layer "In4.Cu")
		(net "M_J_CPU1_SB_DQ<5>")
	)
	(arc
		(start 141.976094 -278.463756)
		(mid 142.159602 -278.50925)
		(end 142.341854 -278.45893)
		(width 0.0889)
		(layer "In4.Cu")
		(net "M_J_CPU1_SB_DQ<5>")
	)
	(arc
		(start 141.4018 -278.45893)
		(mid 141.684756 -278.382753)
		(end 141.967712 -278.45893)
		(width 0.0889)
		(layer "In4.Cu")
		(net "M_J_CPU1_SB_DQ<5>")
	)
	(arc
		(start 134.447788 -278.45893)
		(mid 134.634732 -278.509185)
		(end 134.821676 -278.45893)
		(width 0.0889)
		(layer "In4.Cu")
		(net "M_J_CPU1_SB_DQ<5>")
	)
	(arc
		(start 132.56768 -278.45893)
		(mid 132.749931 -278.50928)
		(end 132.93344 -278.463756)
		(width 0.0889)
		(layer "In4.Cu")
		(net "M_J_CPU1_SB_DQ<5>")
	)
	(segment
		(start 132.757926 -277.060406)
		(end 133.224778 -277.326344)
		(width 0.10668)
		(layer "F.Cu")
		(net "M_J_CPU1_SB_DQ<4>")
	)
	(segment
		(start 145.76298 -277.52929)
		(end 145.805906 -277.425658)
		(width 0.0889)
		(layer "In4.Cu")
		(net "M_J_CPU1_SB_DQ<4>")
	)
	(segment
		(start 151.976836 -276.69109)
		(end 159.099504 -283.813758)
		(width 0.14478)
		(layer "In4.Cu")
		(net "M_J_CPU1_SB_DQ<4>")
	)
	(segment
		(start 147.370546 -276.711664)
		(end 147.39112 -276.69109)
		(width 0.0889)
		(layer "In4.Cu")
		(net "M_J_CPU1_SB_DQ<4>")
	)
	(segment
		(start 133.224778 -277.326344)
		(end 133.070854 -277.591774)
		(width 0.0889)
		(layer "In4.Cu")
		(net "M_J_CPU1_SB_DQ<4>")
	)
	(segment
		(start 145.630646 -277.64867)
		(end 145.680938 -277.611332)
		(width 0.0889)
		(layer "In4.Cu")
		(net "M_J_CPU1_SB_DQ<4>")
	)
	(segment
		(start 144.294606 -277.636224)
		(end 144.316196 -277.64867)
		(width 0.0889)
		(layer "In4.Cu")
		(net "M_J_CPU1_SB_DQ<4>")
	)
	(segment
		(start 134.343394 -277.65375)
		(end 134.351776 -277.648924)
		(width 0.0889)
		(layer "In4.Cu")
		(net "M_J_CPU1_SB_DQ<4>")
	)
	(segment
		(start 178.30038 -287.869884)
		(end 181.258464 -287.869884)
		(width 0.14478)
		(layer "In4.Cu")
		(net "M_J_CPU1_SB_DQ<4>")
	)
	(segment
		(start 159.099504 -283.813758)
		(end 160.085024 -283.813758)
		(width 0.14478)
		(layer "In4.Cu")
		(net "M_J_CPU1_SB_DQ<4>")
	)
	(segment
		(start 133.070854 -277.591774)
		(end 133.093206 -277.675086)
		(width 0.0889)
		(layer "In4.Cu")
		(net "M_J_CPU1_SB_DQ<4>")
	)
	(segment
		(start 177.450496 -287.02)
		(end 178.30038 -287.869884)
		(width 0.14478)
		(layer "In4.Cu")
		(net "M_J_CPU1_SB_DQ<4>")
	)
	(segment
		(start 140.557758 -277.648924)
		(end 140.56614 -277.65375)
		(width 0.0889)
		(layer "In4.Cu")
		(net "M_J_CPU1_SB_DQ<4>")
	)
	(segment
		(start 173.777402 -287.870138)
		(end 174.62754 -287.02)
		(width 0.14478)
		(layer "In4.Cu")
		(net "M_J_CPU1_SB_DQ<4>")
	)
	(segment
		(start 145.805906 -277.153624)
		(end 146.247866 -276.711664)
		(width 0.0889)
		(layer "In4.Cu")
		(net "M_J_CPU1_SB_DQ<4>")
	)
	(segment
		(start 142.803372 -277.65375)
		(end 142.811754 -277.648924)
		(width 0.0889)
		(layer "In4.Cu")
		(net "M_J_CPU1_SB_DQ<4>")
	)
	(segment
		(start 147.39112 -276.69109)
		(end 148.053552 -276.69109)
		(width 0.0889)
		(layer "In4.Cu")
		(net "M_J_CPU1_SB_DQ<4>")
	)
	(segment
		(start 139.617704 -277.648924)
		(end 139.626086 -277.65375)
		(width 0.0889)
		(layer "In4.Cu")
		(net "M_J_CPU1_SB_DQ<4>")
	)
	(segment
		(start 139.04341 -277.65375)
		(end 139.051792 -277.648924)
		(width 0.0889)
		(layer "In4.Cu")
		(net "M_J_CPU1_SB_DQ<4>")
	)
	(segment
		(start 169.961052 -287.010602)
		(end 170.820588 -287.870138)
		(width 0.14478)
		(layer "In4.Cu")
		(net "M_J_CPU1_SB_DQ<4>")
	)
	(segment
		(start 135.857742 -277.648924)
		(end 135.866124 -277.65375)
		(width 0.0889)
		(layer "In4.Cu")
		(net "M_J_CPU1_SB_DQ<4>")
	)
	(segment
		(start 182.108348 -287.02)
		(end 190.744856 -287.02)
		(width 0.14478)
		(layer "In4.Cu")
		(net "M_J_CPU1_SB_DQ<4>")
	)
	(segment
		(start 145.603214 -277.664418)
		(end 145.630646 -277.64867)
		(width 0.0889)
		(layer "In4.Cu")
		(net "M_J_CPU1_SB_DQ<4>")
	)
	(segment
		(start 145.680938 -277.611332)
		(end 145.76298 -277.52929)
		(width 0.0889)
		(layer "In4.Cu")
		(net "M_J_CPU1_SB_DQ<4>")
	)
	(segment
		(start 167.092884 -287.010602)
		(end 169.961052 -287.010602)
		(width 0.14478)
		(layer "In4.Cu")
		(net "M_J_CPU1_SB_DQ<4>")
	)
	(segment
		(start 181.258464 -287.869884)
		(end 182.108348 -287.02)
		(width 0.14478)
		(layer "In4.Cu")
		(net "M_J_CPU1_SB_DQ<4>")
	)
	(segment
		(start 144.689322 -277.648924)
		(end 144.71269 -277.635208)
		(width 0.0889)
		(layer "In4.Cu")
		(net "M_J_CPU1_SB_DQ<4>")
	)
	(segment
		(start 134.917688 -277.648924)
		(end 134.92607 -277.65375)
		(width 0.0889)
		(layer "In4.Cu")
		(net "M_J_CPU1_SB_DQ<4>")
	)
	(segment
		(start 146.247866 -276.711664)
		(end 147.370546 -276.711664)
		(width 0.0889)
		(layer "In4.Cu")
		(net "M_J_CPU1_SB_DQ<4>")
	)
	(segment
		(start 190.744856 -287.02)
		(end 191.160146 -287.43529)
		(width 0.14478)
		(layer "In4.Cu")
		(net "M_J_CPU1_SB_DQ<4>")
	)
	(segment
		(start 138.103356 -277.65375)
		(end 138.111738 -277.648924)
		(width 0.0889)
		(layer "In4.Cu")
		(net "M_J_CPU1_SB_DQ<4>")
	)
	(segment
		(start 160.085024 -283.813758)
		(end 164.131752 -287.860486)
		(width 0.14478)
		(layer "In4.Cu")
		(net "M_J_CPU1_SB_DQ<4>")
	)
	(segment
		(start 148.053552 -276.69109)
		(end 151.976836 -276.69109)
		(width 0.14478)
		(layer "In4.Cu")
		(net "M_J_CPU1_SB_DQ<4>")
	)
	(segment
		(start 166.243 -287.860486)
		(end 167.092884 -287.010602)
		(width 0.14478)
		(layer "In4.Cu")
		(net "M_J_CPU1_SB_DQ<4>")
	)
	(segment
		(start 170.820588 -287.870138)
		(end 173.777402 -287.870138)
		(width 0.14478)
		(layer "In4.Cu")
		(net "M_J_CPU1_SB_DQ<4>")
	)
	(segment
		(start 144.316196 -277.64867)
		(end 144.334484 -277.659084)
		(width 0.0889)
		(layer "In4.Cu")
		(net "M_J_CPU1_SB_DQ<4>")
	)
	(segment
		(start 164.131752 -287.860486)
		(end 166.243 -287.860486)
		(width 0.14478)
		(layer "In4.Cu")
		(net "M_J_CPU1_SB_DQ<4>")
	)
	(segment
		(start 145.805906 -277.425658)
		(end 145.805906 -277.153624)
		(width 0.0889)
		(layer "In4.Cu")
		(net "M_J_CPU1_SB_DQ<4>")
	)
	(segment
		(start 174.62754 -287.02)
		(end 177.450496 -287.02)
		(width 0.14478)
		(layer "In4.Cu")
		(net "M_J_CPU1_SB_DQ<4>")
	)
	(segment
		(start 143.377666 -277.648924)
		(end 143.386048 -277.65375)
		(width 0.0889)
		(layer "In4.Cu")
		(net "M_J_CPU1_SB_DQ<4>")
	)
	(arc
		(start 140.56614 -277.65375)
		(mid 140.749648 -277.699244)
		(end 140.9319 -277.648924)
		(width 0.0889)
		(layer "In4.Cu")
		(net "M_J_CPU1_SB_DQ<4>")
	)
	(arc
		(start 139.051792 -277.648924)
		(mid 139.334748 -277.572747)
		(end 139.617704 -277.648924)
		(width 0.0889)
		(layer "In4.Cu")
		(net "M_J_CPU1_SB_DQ<4>")
	)
	(arc
		(start 136.231884 -277.648924)
		(mid 136.51484 -277.572747)
		(end 136.797796 -277.648924)
		(width 0.0889)
		(layer "In4.Cu")
		(net "M_J_CPU1_SB_DQ<4>")
	)
	(arc
		(start 136.797796 -277.648924)
		(mid 136.98474 -277.699179)
		(end 137.171684 -277.648924)
		(width 0.0889)
		(layer "In4.Cu")
		(net "M_J_CPU1_SB_DQ<4>")
	)
	(arc
		(start 141.8717 -277.648924)
		(mid 142.154656 -277.572747)
		(end 142.437612 -277.648924)
		(width 0.0889)
		(layer "In4.Cu")
		(net "M_J_CPU1_SB_DQ<4>")
	)
	(arc
		(start 142.437612 -277.648924)
		(mid 142.619863 -277.699274)
		(end 142.803372 -277.65375)
		(width 0.0889)
		(layer "In4.Cu")
		(net "M_J_CPU1_SB_DQ<4>")
	)
	(arc
		(start 143.386048 -277.65375)
		(mid 143.569556 -277.699244)
		(end 143.751808 -277.648924)
		(width 0.0889)
		(layer "In4.Cu")
		(net "M_J_CPU1_SB_DQ<4>")
	)
	(arc
		(start 137.171684 -277.648924)
		(mid 137.45464 -277.572747)
		(end 137.737596 -277.648924)
		(width 0.0889)
		(layer "In4.Cu")
		(net "M_J_CPU1_SB_DQ<4>")
	)
	(arc
		(start 133.093206 -277.675086)
		(mid 133.255395 -277.697821)
		(end 133.411722 -277.648924)
		(width 0.0889)
		(layer "In4.Cu")
		(net "M_J_CPU1_SB_DQ<4>")
	)
	(arc
		(start 134.351776 -277.648924)
		(mid 134.634732 -277.572747)
		(end 134.917688 -277.648924)
		(width 0.0889)
		(layer "In4.Cu")
		(net "M_J_CPU1_SB_DQ<4>")
	)
	(arc
		(start 138.67765 -277.648924)
		(mid 138.859901 -277.699274)
		(end 139.04341 -277.65375)
		(width 0.0889)
		(layer "In4.Cu")
		(net "M_J_CPU1_SB_DQ<4>")
	)
	(arc
		(start 137.737596 -277.648924)
		(mid 137.919847 -277.699274)
		(end 138.103356 -277.65375)
		(width 0.0889)
		(layer "In4.Cu")
		(net "M_J_CPU1_SB_DQ<4>")
	)
	(arc
		(start 139.991846 -277.648924)
		(mid 140.274802 -277.572747)
		(end 140.557758 -277.648924)
		(width 0.0889)
		(layer "In4.Cu")
		(net "M_J_CPU1_SB_DQ<4>")
	)
	(arc
		(start 133.977634 -277.648924)
		(mid 134.159885 -277.699274)
		(end 134.343394 -277.65375)
		(width 0.0889)
		(layer "In4.Cu")
		(net "M_J_CPU1_SB_DQ<4>")
	)
	(arc
		(start 144.71269 -277.635208)
		(mid 144.986344 -277.572265)
		(end 145.256504 -277.648924)
		(width 0.0889)
		(layer "In4.Cu")
		(net "M_J_CPU1_SB_DQ<4>")
	)
	(arc
		(start 138.111738 -277.648924)
		(mid 138.394694 -277.572747)
		(end 138.67765 -277.648924)
		(width 0.0889)
		(layer "In4.Cu")
		(net "M_J_CPU1_SB_DQ<4>")
	)
	(arc
		(start 144.334484 -277.659084)
		(mid 144.513205 -277.699007)
		(end 144.689322 -277.648924)
		(width 0.0889)
		(layer "In4.Cu")
		(net "M_J_CPU1_SB_DQ<4>")
	)
	(arc
		(start 143.751808 -277.648924)
		(mid 144.021577 -277.572901)
		(end 144.294606 -277.636224)
		(width 0.0889)
		(layer "In4.Cu")
		(net "M_J_CPU1_SB_DQ<4>")
	)
	(arc
		(start 142.811754 -277.648924)
		(mid 143.09471 -277.572747)
		(end 143.377666 -277.648924)
		(width 0.0889)
		(layer "In4.Cu")
		(net "M_J_CPU1_SB_DQ<4>")
	)
	(arc
		(start 141.497812 -277.648924)
		(mid 141.684756 -277.699179)
		(end 141.8717 -277.648924)
		(width 0.0889)
		(layer "In4.Cu")
		(net "M_J_CPU1_SB_DQ<4>")
	)
	(arc
		(start 134.92607 -277.65375)
		(mid 135.109578 -277.699244)
		(end 135.29183 -277.648924)
		(width 0.0889)
		(layer "In4.Cu")
		(net "M_J_CPU1_SB_DQ<4>")
	)
	(arc
		(start 133.411722 -277.648924)
		(mid 133.694678 -277.572747)
		(end 133.977634 -277.648924)
		(width 0.0889)
		(layer "In4.Cu")
		(net "M_J_CPU1_SB_DQ<4>")
	)
	(arc
		(start 145.256504 -277.648924)
		(mid 145.427959 -277.699441)
		(end 145.603214 -277.664418)
		(width 0.0889)
		(layer "In4.Cu")
		(net "M_J_CPU1_SB_DQ<4>")
	)
	(arc
		(start 140.9319 -277.648924)
		(mid 141.214856 -277.572747)
		(end 141.497812 -277.648924)
		(width 0.0889)
		(layer "In4.Cu")
		(net "M_J_CPU1_SB_DQ<4>")
	)
	(arc
		(start 139.626086 -277.65375)
		(mid 139.809594 -277.699244)
		(end 139.991846 -277.648924)
		(width 0.0889)
		(layer "In4.Cu")
		(net "M_J_CPU1_SB_DQ<4>")
	)
	(arc
		(start 135.29183 -277.648924)
		(mid 135.574786 -277.572747)
		(end 135.857742 -277.648924)
		(width 0.0889)
		(layer "In4.Cu")
		(net "M_J_CPU1_SB_DQ<4>")
	)
	(arc
		(start 135.866124 -277.65375)
		(mid 136.049632 -277.699244)
		(end 136.231884 -277.648924)
		(width 0.0889)
		(layer "In4.Cu")
		(net "M_J_CPU1_SB_DQ<4>")
	)
	(segment
		(start 130.877818 -275.440394)
		(end 131.34467 -275.706332)
		(width 0.10668)
		(layer "F.Cu")
		(net "M_J_CPU1_SB_DQ<3>")
	)
	(segment
		(start 154.488896 -275.208492)
		(end 154.717496 -275.208492)
		(width 0.14478)
		(layer "In4.Cu")
		(net "M_J_CPU1_SB_DQ<3>")
	)
	(segment
		(start 139.617704 -275.383752)
		(end 139.626086 -275.378926)
		(width 0.0889)
		(layer "In4.Cu")
		(net "M_J_CPU1_SB_DQ<3>")
	)
	(segment
		(start 145.490946 -275.316442)
		(end 145.931382 -275.133562)
		(width 0.0889)
		(layer "In4.Cu")
		(net "M_J_CPU1_SB_DQ<3>")
	)
	(segment
		(start 181.147212 -284.450536)
		(end 181.997096 -283.600652)
		(width 0.14478)
		(layer "In4.Cu")
		(net "M_J_CPU1_SB_DQ<3>")
	)
	(segment
		(start 154.61742 -275.860256)
		(end 154.61742 -276.088856)
		(width 0.14478)
		(layer "In4.Cu")
		(net "M_J_CPU1_SB_DQ<3>")
	)
	(segment
		(start 154.717496 -275.208492)
		(end 154.87904 -275.370036)
		(width 0.14478)
		(layer "In4.Cu")
		(net "M_J_CPU1_SB_DQ<3>")
	)
	(segment
		(start 145.25244 -275.387308)
		(end 145.392648 -275.343366)
		(width 0.0889)
		(layer "In4.Cu")
		(net "M_J_CPU1_SB_DQ<3>")
	)
	(segment
		(start 171.022772 -284.450536)
		(end 173.54042 -284.450536)
		(width 0.14478)
		(layer "In4.Cu")
		(net "M_J_CPU1_SB_DQ<3>")
	)
	(segment
		(start 154.098752 -274.818348)
		(end 153.837132 -275.079968)
		(width 0.14478)
		(layer "In4.Cu")
		(net "M_J_CPU1_SB_DQ<3>")
	)
	(segment
		(start 146.015202 -275.077428)
		(end 146.834606 -274.258024)
		(width 0.0889)
		(layer "In4.Cu")
		(net "M_J_CPU1_SB_DQ<3>")
	)
	(segment
		(start 155.497784 -275.98878)
		(end 155.659328 -276.150324)
		(width 0.14478)
		(layer "In4.Cu")
		(net "M_J_CPU1_SB_DQ<3>")
	)
	(segment
		(start 144.684242 -275.378926)
		(end 144.692624 -275.383752)
		(width 0.0889)
		(layer "In4.Cu")
		(net "M_J_CPU1_SB_DQ<3>")
	)
	(segment
		(start 156.278072 -276.769068)
		(end 163.568888 -284.059884)
		(width 0.14478)
		(layer "In4.Cu")
		(net "M_J_CPU1_SB_DQ<3>")
	)
	(segment
		(start 155.659328 -276.378924)
		(end 155.397708 -276.640544)
		(width 0.14478)
		(layer "In4.Cu")
		(net "M_J_CPU1_SB_DQ<3>")
	)
	(segment
		(start 174.390304 -283.600652)
		(end 177.694082 -283.600652)
		(width 0.14478)
		(layer "In4.Cu")
		(net "M_J_CPU1_SB_DQ<3>")
	)
	(segment
		(start 186.625484 -283.600652)
		(end 187.060078 -284.035246)
		(width 0.14478)
		(layer "In4.Cu")
		(net "M_J_CPU1_SB_DQ<3>")
	)
	(segment
		(start 135.857742 -275.383752)
		(end 135.866124 -275.378926)
		(width 0.0889)
		(layer "In4.Cu")
		(net "M_J_CPU1_SB_DQ<3>")
	)
	(segment
		(start 181.997096 -283.600652)
		(end 186.625484 -283.600652)
		(width 0.14478)
		(layer "In4.Cu")
		(net "M_J_CPU1_SB_DQ<3>")
	)
	(segment
		(start 166.480998 -284.059884)
		(end 166.930578 -283.610304)
		(width 0.14478)
		(layer "In4.Cu")
		(net "M_J_CPU1_SB_DQ<3>")
	)
	(segment
		(start 155.659328 -276.150324)
		(end 155.659328 -276.378924)
		(width 0.14478)
		(layer "In4.Cu")
		(net "M_J_CPU1_SB_DQ<3>")
	)
	(segment
		(start 177.694082 -283.600652)
		(end 178.543966 -284.450536)
		(width 0.14478)
		(layer "In4.Cu")
		(net "M_J_CPU1_SB_DQ<3>")
	)
	(segment
		(start 155.787852 -277.030688)
		(end 156.049472 -276.769068)
		(width 0.14478)
		(layer "In4.Cu")
		(net "M_J_CPU1_SB_DQ<3>")
	)
	(segment
		(start 155.397708 -276.640544)
		(end 155.397708 -276.869144)
		(width 0.14478)
		(layer "In4.Cu")
		(net "M_J_CPU1_SB_DQ<3>")
	)
	(segment
		(start 138.103356 -275.378926)
		(end 138.111738 -275.383752)
		(width 0.0889)
		(layer "In4.Cu")
		(net "M_J_CPU1_SB_DQ<3>")
	)
	(segment
		(start 173.54042 -284.450536)
		(end 174.390304 -283.600652)
		(width 0.14478)
		(layer "In4.Cu")
		(net "M_J_CPU1_SB_DQ<3>")
	)
	(segment
		(start 163.568888 -284.059884)
		(end 166.480998 -284.059884)
		(width 0.14478)
		(layer "In4.Cu")
		(net "M_J_CPU1_SB_DQ<3>")
	)
	(segment
		(start 155.269184 -275.98878)
		(end 155.497784 -275.98878)
		(width 0.14478)
		(layer "In4.Cu")
		(net "M_J_CPU1_SB_DQ<3>")
	)
	(segment
		(start 145.931382 -275.133562)
		(end 146.015202 -275.077428)
		(width 0.0889)
		(layer "In4.Cu")
		(net "M_J_CPU1_SB_DQ<3>")
	)
	(segment
		(start 155.397708 -276.869144)
		(end 155.559252 -277.030688)
		(width 0.14478)
		(layer "In4.Cu")
		(net "M_J_CPU1_SB_DQ<3>")
	)
	(segment
		(start 142.803372 -275.378926)
		(end 142.811754 -275.383752)
		(width 0.0889)
		(layer "In4.Cu")
		(net "M_J_CPU1_SB_DQ<3>")
	)
	(segment
		(start 145.392648 -275.343366)
		(end 145.490946 -275.316442)
		(width 0.0889)
		(layer "In4.Cu")
		(net "M_J_CPU1_SB_DQ<3>")
	)
	(segment
		(start 139.04341 -275.378926)
		(end 139.051792 -275.383752)
		(width 0.0889)
		(layer "In4.Cu")
		(net "M_J_CPU1_SB_DQ<3>")
	)
	(segment
		(start 153.812748 -274.303744)
		(end 154.098752 -274.589748)
		(width 0.14478)
		(layer "In4.Cu")
		(net "M_J_CPU1_SB_DQ<3>")
	)
	(segment
		(start 153.998676 -275.470112)
		(end 154.227276 -275.470112)
		(width 0.14478)
		(layer "In4.Cu")
		(net "M_J_CPU1_SB_DQ<3>")
	)
	(segment
		(start 147.96262 -274.303744)
		(end 153.812748 -274.303744)
		(width 0.14478)
		(layer "In4.Cu")
		(net "M_J_CPU1_SB_DQ<3>")
	)
	(segment
		(start 140.557758 -275.383752)
		(end 140.56614 -275.378926)
		(width 0.0889)
		(layer "In4.Cu")
		(net "M_J_CPU1_SB_DQ<3>")
	)
	(segment
		(start 131.34467 -275.706332)
		(end 131.498848 -275.440902)
		(width 0.0889)
		(layer "In4.Cu")
		(net "M_J_CPU1_SB_DQ<3>")
	)
	(segment
		(start 134.917688 -275.383752)
		(end 134.92607 -275.378926)
		(width 0.0889)
		(layer "In4.Cu")
		(net "M_J_CPU1_SB_DQ<3>")
	)
	(segment
		(start 153.837132 -275.308568)
		(end 153.998676 -275.470112)
		(width 0.14478)
		(layer "In4.Cu")
		(net "M_J_CPU1_SB_DQ<3>")
	)
	(segment
		(start 155.559252 -277.030688)
		(end 155.787852 -277.030688)
		(width 0.14478)
		(layer "In4.Cu")
		(net "M_J_CPU1_SB_DQ<3>")
	)
	(segment
		(start 156.049472 -276.769068)
		(end 156.278072 -276.769068)
		(width 0.14478)
		(layer "In4.Cu")
		(net "M_J_CPU1_SB_DQ<3>")
	)
	(segment
		(start 154.778964 -276.2504)
		(end 155.007564 -276.2504)
		(width 0.14478)
		(layer "In4.Cu")
		(net "M_J_CPU1_SB_DQ<3>")
	)
	(segment
		(start 154.227276 -275.470112)
		(end 154.488896 -275.208492)
		(width 0.14478)
		(layer "In4.Cu")
		(net "M_J_CPU1_SB_DQ<3>")
	)
	(segment
		(start 134.343394 -275.378926)
		(end 134.351776 -275.383752)
		(width 0.0889)
		(layer "In4.Cu")
		(net "M_J_CPU1_SB_DQ<3>")
	)
	(segment
		(start 143.377666 -275.383752)
		(end 143.386048 -275.378926)
		(width 0.0889)
		(layer "In4.Cu")
		(net "M_J_CPU1_SB_DQ<3>")
	)
	(segment
		(start 178.543966 -284.450536)
		(end 181.147212 -284.450536)
		(width 0.14478)
		(layer "In4.Cu")
		(net "M_J_CPU1_SB_DQ<3>")
	)
	(segment
		(start 147.394422 -274.258024)
		(end 147.440142 -274.303744)
		(width 0.0889)
		(layer "In4.Cu")
		(net "M_J_CPU1_SB_DQ<3>")
	)
	(segment
		(start 146.834606 -274.258024)
		(end 147.394422 -274.258024)
		(width 0.0889)
		(layer "In4.Cu")
		(net "M_J_CPU1_SB_DQ<3>")
	)
	(segment
		(start 155.007564 -276.2504)
		(end 155.269184 -275.98878)
		(width 0.14478)
		(layer "In4.Cu")
		(net "M_J_CPU1_SB_DQ<3>")
	)
	(segment
		(start 153.837132 -275.079968)
		(end 153.837132 -275.308568)
		(width 0.14478)
		(layer "In4.Cu")
		(net "M_J_CPU1_SB_DQ<3>")
	)
	(segment
		(start 154.61742 -276.088856)
		(end 154.778964 -276.2504)
		(width 0.14478)
		(layer "In4.Cu")
		(net "M_J_CPU1_SB_DQ<3>")
	)
	(segment
		(start 147.440142 -274.303744)
		(end 147.96262 -274.303744)
		(width 0.0889)
		(layer "In4.Cu")
		(net "M_J_CPU1_SB_DQ<3>")
	)
	(segment
		(start 132.09778 -275.383752)
		(end 132.106162 -275.378926)
		(width 0.0889)
		(layer "In4.Cu")
		(net "M_J_CPU1_SB_DQ<3>")
	)
	(segment
		(start 154.87904 -275.370036)
		(end 154.87904 -275.598636)
		(width 0.14478)
		(layer "In4.Cu")
		(net "M_J_CPU1_SB_DQ<3>")
	)
	(segment
		(start 166.930578 -283.610304)
		(end 170.18254 -283.610304)
		(width 0.14478)
		(layer "In4.Cu")
		(net "M_J_CPU1_SB_DQ<3>")
	)
	(segment
		(start 154.87904 -275.598636)
		(end 154.61742 -275.860256)
		(width 0.14478)
		(layer "In4.Cu")
		(net "M_J_CPU1_SB_DQ<3>")
	)
	(segment
		(start 170.18254 -283.610304)
		(end 171.022772 -284.450536)
		(width 0.14478)
		(layer "In4.Cu")
		(net "M_J_CPU1_SB_DQ<3>")
	)
	(segment
		(start 143.751808 -275.383752)
		(end 143.762222 -275.389848)
		(width 0.0889)
		(layer "In4.Cu")
		(net "M_J_CPU1_SB_DQ<3>")
	)
	(segment
		(start 154.098752 -274.589748)
		(end 154.098752 -274.818348)
		(width 0.14478)
		(layer "In4.Cu")
		(net "M_J_CPU1_SB_DQ<3>")
	)
	(segment
		(start 131.498848 -275.440902)
		(end 131.595114 -275.415502)
		(width 0.0889)
		(layer "In4.Cu")
		(net "M_J_CPU1_SB_DQ<3>")
	)
	(arc
		(start 144.317974 -275.383752)
		(mid 144.500479 -275.333275)
		(end 144.684242 -275.378926)
		(width 0.0889)
		(layer "In4.Cu")
		(net "M_J_CPU1_SB_DQ<3>")
	)
	(arc
		(start 136.231884 -275.383752)
		(mid 136.51484 -275.459929)
		(end 136.797796 -275.383752)
		(width 0.0889)
		(layer "In4.Cu")
		(net "M_J_CPU1_SB_DQ<3>")
	)
	(arc
		(start 140.56614 -275.378926)
		(mid 140.749648 -275.333432)
		(end 140.9319 -275.383752)
		(width 0.0889)
		(layer "In4.Cu")
		(net "M_J_CPU1_SB_DQ<3>")
	)
	(arc
		(start 139.051792 -275.383752)
		(mid 139.334748 -275.459929)
		(end 139.617704 -275.383752)
		(width 0.0889)
		(layer "In4.Cu")
		(net "M_J_CPU1_SB_DQ<3>")
	)
	(arc
		(start 131.595114 -275.415502)
		(mid 131.850179 -275.458853)
		(end 132.09778 -275.383752)
		(width 0.0889)
		(layer "In4.Cu")
		(net "M_J_CPU1_SB_DQ<3>")
	)
	(arc
		(start 135.29183 -275.383752)
		(mid 135.574786 -275.459929)
		(end 135.857742 -275.383752)
		(width 0.0889)
		(layer "In4.Cu")
		(net "M_J_CPU1_SB_DQ<3>")
	)
	(arc
		(start 134.92607 -275.378926)
		(mid 135.109578 -275.333432)
		(end 135.29183 -275.383752)
		(width 0.0889)
		(layer "In4.Cu")
		(net "M_J_CPU1_SB_DQ<3>")
	)
	(arc
		(start 137.171684 -275.383752)
		(mid 137.45464 -275.459929)
		(end 137.737596 -275.383752)
		(width 0.0889)
		(layer "In4.Cu")
		(net "M_J_CPU1_SB_DQ<3>")
	)
	(arc
		(start 141.8717 -275.383752)
		(mid 142.154656 -275.459929)
		(end 142.437612 -275.383752)
		(width 0.0889)
		(layer "In4.Cu")
		(net "M_J_CPU1_SB_DQ<3>")
	)
	(arc
		(start 136.797796 -275.383752)
		(mid 136.98474 -275.333497)
		(end 137.171684 -275.383752)
		(width 0.0889)
		(layer "In4.Cu")
		(net "M_J_CPU1_SB_DQ<3>")
	)
	(arc
		(start 140.9319 -275.383752)
		(mid 141.214856 -275.459929)
		(end 141.497812 -275.383752)
		(width 0.0889)
		(layer "In4.Cu")
		(net "M_J_CPU1_SB_DQ<3>")
	)
	(arc
		(start 133.411722 -275.383752)
		(mid 133.694678 -275.459929)
		(end 133.977634 -275.383752)
		(width 0.0889)
		(layer "In4.Cu")
		(net "M_J_CPU1_SB_DQ<3>")
	)
	(arc
		(start 137.737596 -275.383752)
		(mid 137.919847 -275.333402)
		(end 138.103356 -275.378926)
		(width 0.0889)
		(layer "In4.Cu")
		(net "M_J_CPU1_SB_DQ<3>")
	)
	(arc
		(start 138.111738 -275.383752)
		(mid 138.394694 -275.459929)
		(end 138.67765 -275.383752)
		(width 0.0889)
		(layer "In4.Cu")
		(net "M_J_CPU1_SB_DQ<3>")
	)
	(arc
		(start 133.977634 -275.383752)
		(mid 134.159885 -275.333402)
		(end 134.343394 -275.378926)
		(width 0.0889)
		(layer "In4.Cu")
		(net "M_J_CPU1_SB_DQ<3>")
	)
	(arc
		(start 142.437612 -275.383752)
		(mid 142.619863 -275.333402)
		(end 142.803372 -275.378926)
		(width 0.0889)
		(layer "In4.Cu")
		(net "M_J_CPU1_SB_DQ<3>")
	)
	(arc
		(start 138.67765 -275.383752)
		(mid 138.859901 -275.333402)
		(end 139.04341 -275.378926)
		(width 0.0889)
		(layer "In4.Cu")
		(net "M_J_CPU1_SB_DQ<3>")
	)
	(arc
		(start 132.106162 -275.378926)
		(mid 132.28967 -275.333432)
		(end 132.471922 -275.383752)
		(width 0.0889)
		(layer "In4.Cu")
		(net "M_J_CPU1_SB_DQ<3>")
	)
	(arc
		(start 139.991846 -275.383752)
		(mid 140.274802 -275.459929)
		(end 140.557758 -275.383752)
		(width 0.0889)
		(layer "In4.Cu")
		(net "M_J_CPU1_SB_DQ<3>")
	)
	(arc
		(start 144.692624 -275.383752)
		(mid 144.972052 -275.459918)
		(end 145.25244 -275.387308)
		(width 0.0889)
		(layer "In4.Cu")
		(net "M_J_CPU1_SB_DQ<3>")
	)
	(arc
		(start 139.626086 -275.378926)
		(mid 139.809594 -275.333432)
		(end 139.991846 -275.383752)
		(width 0.0889)
		(layer "In4.Cu")
		(net "M_J_CPU1_SB_DQ<3>")
	)
	(arc
		(start 133.037834 -275.383752)
		(mid 133.224778 -275.333497)
		(end 133.411722 -275.383752)
		(width 0.0889)
		(layer "In4.Cu")
		(net "M_J_CPU1_SB_DQ<3>")
	)
	(arc
		(start 134.351776 -275.383752)
		(mid 134.634732 -275.459929)
		(end 134.917688 -275.383752)
		(width 0.0889)
		(layer "In4.Cu")
		(net "M_J_CPU1_SB_DQ<3>")
	)
	(arc
		(start 141.497812 -275.383752)
		(mid 141.684756 -275.333497)
		(end 141.8717 -275.383752)
		(width 0.0889)
		(layer "In4.Cu")
		(net "M_J_CPU1_SB_DQ<3>")
	)
	(arc
		(start 142.811754 -275.383752)
		(mid 143.09471 -275.459929)
		(end 143.377666 -275.383752)
		(width 0.0889)
		(layer "In4.Cu")
		(net "M_J_CPU1_SB_DQ<3>")
	)
	(arc
		(start 143.762222 -275.389848)
		(mid 144.040908 -275.460068)
		(end 144.317974 -275.383752)
		(width 0.0889)
		(layer "In4.Cu")
		(net "M_J_CPU1_SB_DQ<3>")
	)
	(arc
		(start 132.471922 -275.383752)
		(mid 132.754878 -275.459929)
		(end 133.037834 -275.383752)
		(width 0.0889)
		(layer "In4.Cu")
		(net "M_J_CPU1_SB_DQ<3>")
	)
	(arc
		(start 143.386048 -275.378926)
		(mid 143.569556 -275.333432)
		(end 143.751808 -275.383752)
		(width 0.0889)
		(layer "In4.Cu")
		(net "M_J_CPU1_SB_DQ<3>")
	)
	(arc
		(start 135.866124 -275.378926)
		(mid 136.049632 -275.333432)
		(end 136.231884 -275.383752)
		(width 0.0889)
		(layer "In4.Cu")
		(net "M_J_CPU1_SB_DQ<3>")
	)
	(segment
		(start 132.757926 -293.260272)
		(end 133.224778 -293.52621)
		(width 0.10668)
		(layer "F.Cu")
		(net "M_J_CPU1_SB_DQ<31>")
	)
	(segment
		(start 151.840438 -309.306214)
		(end 151.696674 -309.449724)
		(width 0.14478)
		(layer "In4.Cu")
		(net "M_J_CPU1_SB_DQ<31>")
	)
	(segment
		(start 156.912056 -314.378086)
		(end 157.140402 -314.378086)
		(width 0.14478)
		(layer "In4.Cu")
		(net "M_J_CPU1_SB_DQ<31>")
	)
	(segment
		(start 156.360114 -313.597798)
		(end 156.522166 -313.75985)
		(width 0.14478)
		(layer "In4.Cu")
		(net "M_J_CPU1_SB_DQ<31>")
	)
	(segment
		(start 155.579826 -312.81751)
		(end 155.741878 -312.979562)
		(width 0.14478)
		(layer "In4.Cu")
		(net "M_J_CPU1_SB_DQ<31>")
	)
	(segment
		(start 153.25725 -311.238392)
		(end 153.419302 -311.400444)
		(width 0.14478)
		(layer "In4.Cu")
		(net "M_J_CPU1_SB_DQ<31>")
	)
	(segment
		(start 153.401014 -310.86679)
		(end 153.25725 -311.0103)
		(width 0.14478)
		(layer "In4.Cu")
		(net "M_J_CPU1_SB_DQ<31>")
	)
	(segment
		(start 145.11528 -303.096422)
		(end 151.078438 -309.05958)
		(width 0.14478)
		(layer "In4.Cu")
		(net "M_J_CPU1_SB_DQ<31>")
	)
	(segment
		(start 139.617704 -293.20363)
		(end 139.626086 -293.198804)
		(width 0.0889)
		(layer "In4.Cu")
		(net "M_J_CPU1_SB_DQ<31>")
	)
	(segment
		(start 143.751808 -293.20363)
		(end 143.782288 -293.22141)
		(width 0.0889)
		(layer "In4.Cu")
		(net "M_J_CPU1_SB_DQ<31>")
	)
	(segment
		(start 144.221708 -294.013636)
		(end 144.252188 -294.031416)
		(width 0.0889)
		(layer "In4.Cu")
		(net "M_J_CPU1_SB_DQ<31>")
	)
	(segment
		(start 144.182592 -293.990776)
		(end 144.221708 -294.013636)
		(width 0.0889)
		(layer "In4.Cu")
		(net "M_J_CPU1_SB_DQ<31>")
	)
	(segment
		(start 163.462462 -318.460374)
		(end 186.635136 -318.460374)
		(width 0.14478)
		(layer "In4.Cu")
		(net "M_J_CPU1_SB_DQ<31>")
	)
	(segment
		(start 151.078438 -309.05958)
		(end 151.30653 -309.05958)
		(width 0.14478)
		(layer "In4.Cu")
		(net "M_J_CPU1_SB_DQ<31>")
	)
	(segment
		(start 154.181302 -311.647078)
		(end 154.037538 -311.790588)
		(width 0.14478)
		(layer "In4.Cu")
		(net "M_J_CPU1_SB_DQ<31>")
	)
	(segment
		(start 156.540454 -314.521596)
		(end 156.768546 -314.521596)
		(width 0.14478)
		(layer "In4.Cu")
		(net "M_J_CPU1_SB_DQ<31>")
	)
	(segment
		(start 153.790904 -311.256934)
		(end 154.01925 -311.256934)
		(width 0.14478)
		(layer "In4.Cu")
		(net "M_J_CPU1_SB_DQ<31>")
	)
	(segment
		(start 153.25725 -311.0103)
		(end 153.25725 -311.238392)
		(width 0.14478)
		(layer "In4.Cu")
		(net "M_J_CPU1_SB_DQ<31>")
	)
	(segment
		(start 153.010616 -310.476646)
		(end 153.238962 -310.476646)
		(width 0.14478)
		(layer "In4.Cu")
		(net "M_J_CPU1_SB_DQ<31>")
	)
	(segment
		(start 152.230328 -309.696358)
		(end 152.458674 -309.696358)
		(width 0.14478)
		(layer "In4.Cu")
		(net "M_J_CPU1_SB_DQ<31>")
	)
	(segment
		(start 155.598114 -313.579256)
		(end 155.760166 -313.741308)
		(width 0.14478)
		(layer "In4.Cu")
		(net "M_J_CPU1_SB_DQ<31>")
	)
	(segment
		(start 134.917688 -293.20363)
		(end 134.92607 -293.198804)
		(width 0.0889)
		(layer "In4.Cu")
		(net "M_J_CPU1_SB_DQ<31>")
	)
	(segment
		(start 156.131768 -313.597798)
		(end 156.360114 -313.597798)
		(width 0.14478)
		(layer "In4.Cu")
		(net "M_J_CPU1_SB_DQ<31>")
	)
	(segment
		(start 154.19959 -312.180732)
		(end 154.427682 -312.180732)
		(width 0.14478)
		(layer "In4.Cu")
		(net "M_J_CPU1_SB_DQ<31>")
	)
	(segment
		(start 143.377666 -293.20363)
		(end 143.386048 -293.198804)
		(width 0.0889)
		(layer "In4.Cu")
		(net "M_J_CPU1_SB_DQ<31>")
	)
	(segment
		(start 142.803372 -293.198804)
		(end 142.811754 -293.20363)
		(width 0.0889)
		(layer "In4.Cu")
		(net "M_J_CPU1_SB_DQ<31>")
	)
	(segment
		(start 156.522166 -313.987942)
		(end 156.378402 -314.131452)
		(width 0.14478)
		(layer "In4.Cu")
		(net "M_J_CPU1_SB_DQ<31>")
	)
	(segment
		(start 151.45004 -308.91607)
		(end 151.678386 -308.91607)
		(width 0.14478)
		(layer "In4.Cu")
		(net "M_J_CPU1_SB_DQ<31>")
	)
	(segment
		(start 144.652492 -294.800782)
		(end 144.691608 -294.823642)
		(width 0.0889)
		(layer "In4.Cu")
		(net "M_J_CPU1_SB_DQ<31>")
	)
	(segment
		(start 153.419302 -311.400444)
		(end 153.647394 -311.400444)
		(width 0.14478)
		(layer "In4.Cu")
		(net "M_J_CPU1_SB_DQ<31>")
	)
	(segment
		(start 156.378402 -314.359544)
		(end 156.540454 -314.521596)
		(width 0.14478)
		(layer "In4.Cu")
		(net "M_J_CPU1_SB_DQ<31>")
	)
	(segment
		(start 152.639014 -310.620156)
		(end 152.867106 -310.620156)
		(width 0.14478)
		(layer "In4.Cu")
		(net "M_J_CPU1_SB_DQ<31>")
	)
	(segment
		(start 155.760166 -313.741308)
		(end 155.988258 -313.741308)
		(width 0.14478)
		(layer "In4.Cu")
		(net "M_J_CPU1_SB_DQ<31>")
	)
	(segment
		(start 145.349214 -295.956228)
		(end 145.349214 -296.154602)
		(width 0.0889)
		(layer "In4.Cu")
		(net "M_J_CPU1_SB_DQ<31>")
	)
	(segment
		(start 157.140402 -314.378086)
		(end 157.302454 -314.540138)
		(width 0.14478)
		(layer "In4.Cu")
		(net "M_J_CPU1_SB_DQ<31>")
	)
	(segment
		(start 154.037538 -312.01868)
		(end 154.19959 -312.180732)
		(width 0.14478)
		(layer "In4.Cu")
		(net "M_J_CPU1_SB_DQ<31>")
	)
	(segment
		(start 154.96159 -312.427366)
		(end 154.817826 -312.570876)
		(width 0.14478)
		(layer "In4.Cu")
		(net "M_J_CPU1_SB_DQ<31>")
	)
	(segment
		(start 154.181302 -311.418986)
		(end 154.181302 -311.647078)
		(width 0.14478)
		(layer "In4.Cu")
		(net "M_J_CPU1_SB_DQ<31>")
	)
	(segment
		(start 153.401014 -310.638698)
		(end 153.401014 -310.86679)
		(width 0.14478)
		(layer "In4.Cu")
		(net "M_J_CPU1_SB_DQ<31>")
	)
	(segment
		(start 154.817826 -312.798968)
		(end 154.979878 -312.96102)
		(width 0.14478)
		(layer "In4.Cu")
		(net "M_J_CPU1_SB_DQ<31>")
	)
	(segment
		(start 154.979878 -312.96102)
		(end 155.20797 -312.96102)
		(width 0.14478)
		(layer "In4.Cu")
		(net "M_J_CPU1_SB_DQ<31>")
	)
	(segment
		(start 153.647394 -311.400444)
		(end 153.790904 -311.256934)
		(width 0.14478)
		(layer "In4.Cu")
		(net "M_J_CPU1_SB_DQ<31>")
	)
	(segment
		(start 151.678386 -308.91607)
		(end 151.840438 -309.078122)
		(width 0.14478)
		(layer "In4.Cu")
		(net "M_J_CPU1_SB_DQ<31>")
	)
	(segment
		(start 152.458674 -309.696358)
		(end 152.620726 -309.85841)
		(width 0.14478)
		(layer "In4.Cu")
		(net "M_J_CPU1_SB_DQ<31>")
	)
	(segment
		(start 154.01925 -311.256934)
		(end 154.181302 -311.418986)
		(width 0.14478)
		(layer "In4.Cu")
		(net "M_J_CPU1_SB_DQ<31>")
	)
	(segment
		(start 138.103356 -293.198804)
		(end 138.111738 -293.20363)
		(width 0.0889)
		(layer "In4.Cu")
		(net "M_J_CPU1_SB_DQ<31>")
	)
	(segment
		(start 144.691608 -294.823642)
		(end 144.724374 -294.842692)
		(width 0.0889)
		(layer "In4.Cu")
		(net "M_J_CPU1_SB_DQ<31>")
	)
	(segment
		(start 155.741878 -313.207654)
		(end 155.598114 -313.351164)
		(width 0.14478)
		(layer "In4.Cu")
		(net "M_J_CPU1_SB_DQ<31>")
	)
	(segment
		(start 159.036766 -317.017908)
		(end 161.64814 -318.09944)
		(width 0.14478)
		(layer "In4.Cu")
		(net "M_J_CPU1_SB_DQ<31>")
	)
	(segment
		(start 157.15869 -315.139832)
		(end 159.036766 -317.017908)
		(width 0.14478)
		(layer "In4.Cu")
		(net "M_J_CPU1_SB_DQ<31>")
	)
	(segment
		(start 155.598114 -313.351164)
		(end 155.598114 -313.579256)
		(width 0.14478)
		(layer "In4.Cu")
		(net "M_J_CPU1_SB_DQ<31>")
	)
	(segment
		(start 155.741878 -312.979562)
		(end 155.741878 -313.207654)
		(width 0.14478)
		(layer "In4.Cu")
		(net "M_J_CPU1_SB_DQ<31>")
	)
	(segment
		(start 154.427682 -312.180732)
		(end 154.571192 -312.037222)
		(width 0.14478)
		(layer "In4.Cu")
		(net "M_J_CPU1_SB_DQ<31>")
	)
	(segment
		(start 154.96159 -312.199274)
		(end 154.96159 -312.427366)
		(width 0.14478)
		(layer "In4.Cu")
		(net "M_J_CPU1_SB_DQ<31>")
	)
	(segment
		(start 151.840438 -309.078122)
		(end 151.840438 -309.306214)
		(width 0.14478)
		(layer "In4.Cu")
		(net "M_J_CPU1_SB_DQ<31>")
	)
	(segment
		(start 155.20797 -312.96102)
		(end 155.35148 -312.81751)
		(width 0.14478)
		(layer "In4.Cu")
		(net "M_J_CPU1_SB_DQ<31>")
	)
	(segment
		(start 186.635136 -318.460374)
		(end 187.060078 -318.035432)
		(width 0.14478)
		(layer "In4.Cu")
		(net "M_J_CPU1_SB_DQ<31>")
	)
	(segment
		(start 161.64814 -318.09944)
		(end 163.462462 -318.460374)
		(width 0.14478)
		(layer "In4.Cu")
		(net "M_J_CPU1_SB_DQ<31>")
	)
	(segment
		(start 145.349214 -296.154602)
		(end 145.11528 -296.388536)
		(width 0.0889)
		(layer "In4.Cu")
		(net "M_J_CPU1_SB_DQ<31>")
	)
	(segment
		(start 152.867106 -310.620156)
		(end 153.010616 -310.476646)
		(width 0.14478)
		(layer "In4.Cu")
		(net "M_J_CPU1_SB_DQ<31>")
	)
	(segment
		(start 155.988258 -313.741308)
		(end 156.131768 -313.597798)
		(width 0.14478)
		(layer "In4.Cu")
		(net "M_J_CPU1_SB_DQ<31>")
	)
	(segment
		(start 145.11528 -296.388536)
		(end 145.11528 -303.096422)
		(width 0.14478)
		(layer "In4.Cu")
		(net "M_J_CPU1_SB_DQ<31>")
	)
	(segment
		(start 151.696674 -309.677816)
		(end 151.858726 -309.839868)
		(width 0.14478)
		(layer "In4.Cu")
		(net "M_J_CPU1_SB_DQ<31>")
	)
	(segment
		(start 152.620726 -309.85841)
		(end 152.620726 -310.086502)
		(width 0.14478)
		(layer "In4.Cu")
		(net "M_J_CPU1_SB_DQ<31>")
	)
	(segment
		(start 151.30653 -309.05958)
		(end 151.45004 -308.91607)
		(width 0.14478)
		(layer "In4.Cu")
		(net "M_J_CPU1_SB_DQ<31>")
	)
	(segment
		(start 157.302454 -314.540138)
		(end 157.302454 -314.76823)
		(width 0.14478)
		(layer "In4.Cu")
		(net "M_J_CPU1_SB_DQ<31>")
	)
	(segment
		(start 134.343394 -293.198804)
		(end 134.351776 -293.20363)
		(width 0.0889)
		(layer "In4.Cu")
		(net "M_J_CPU1_SB_DQ<31>")
	)
	(segment
		(start 156.522166 -313.75985)
		(end 156.522166 -313.987942)
		(width 0.14478)
		(layer "In4.Cu")
		(net "M_J_CPU1_SB_DQ<31>")
	)
	(segment
		(start 156.768546 -314.521596)
		(end 156.912056 -314.378086)
		(width 0.14478)
		(layer "In4.Cu")
		(net "M_J_CPU1_SB_DQ<31>")
	)
	(segment
		(start 133.947408 -293.22141)
		(end 133.977634 -293.20363)
		(width 0.0889)
		(layer "In4.Cu")
		(net "M_J_CPU1_SB_DQ<31>")
	)
	(segment
		(start 151.696674 -309.449724)
		(end 151.696674 -309.677816)
		(width 0.14478)
		(layer "In4.Cu")
		(net "M_J_CPU1_SB_DQ<31>")
	)
	(segment
		(start 153.238962 -310.476646)
		(end 153.401014 -310.638698)
		(width 0.14478)
		(layer "In4.Cu")
		(net "M_J_CPU1_SB_DQ<31>")
	)
	(segment
		(start 152.476962 -310.230012)
		(end 152.476962 -310.458104)
		(width 0.14478)
		(layer "In4.Cu")
		(net "M_J_CPU1_SB_DQ<31>")
	)
	(segment
		(start 135.857742 -293.20363)
		(end 135.866124 -293.198804)
		(width 0.0889)
		(layer "In4.Cu")
		(net "M_J_CPU1_SB_DQ<31>")
	)
	(segment
		(start 152.086818 -309.839868)
		(end 152.230328 -309.696358)
		(width 0.14478)
		(layer "In4.Cu")
		(net "M_J_CPU1_SB_DQ<31>")
	)
	(segment
		(start 152.620726 -310.086502)
		(end 152.476962 -310.230012)
		(width 0.14478)
		(layer "In4.Cu")
		(net "M_J_CPU1_SB_DQ<31>")
	)
	(segment
		(start 156.378402 -314.131452)
		(end 156.378402 -314.359544)
		(width 0.14478)
		(layer "In4.Cu")
		(net "M_J_CPU1_SB_DQ<31>")
	)
	(segment
		(start 151.858726 -309.839868)
		(end 152.086818 -309.839868)
		(width 0.14478)
		(layer "In4.Cu")
		(net "M_J_CPU1_SB_DQ<31>")
	)
	(segment
		(start 154.571192 -312.037222)
		(end 154.799538 -312.037222)
		(width 0.14478)
		(layer "In4.Cu")
		(net "M_J_CPU1_SB_DQ<31>")
	)
	(segment
		(start 139.04341 -293.198804)
		(end 139.051792 -293.20363)
		(width 0.0889)
		(layer "In4.Cu")
		(net "M_J_CPU1_SB_DQ<31>")
	)
	(segment
		(start 154.817826 -312.570876)
		(end 154.817826 -312.798968)
		(width 0.14478)
		(layer "In4.Cu")
		(net "M_J_CPU1_SB_DQ<31>")
	)
	(segment
		(start 152.476962 -310.458104)
		(end 152.639014 -310.620156)
		(width 0.14478)
		(layer "In4.Cu")
		(net "M_J_CPU1_SB_DQ<31>")
	)
	(segment
		(start 155.35148 -312.81751)
		(end 155.579826 -312.81751)
		(width 0.14478)
		(layer "In4.Cu")
		(net "M_J_CPU1_SB_DQ<31>")
	)
	(segment
		(start 157.15869 -314.91174)
		(end 157.15869 -315.139832)
		(width 0.14478)
		(layer "In4.Cu")
		(net "M_J_CPU1_SB_DQ<31>")
	)
	(segment
		(start 154.799538 -312.037222)
		(end 154.96159 -312.199274)
		(width 0.14478)
		(layer "In4.Cu")
		(net "M_J_CPU1_SB_DQ<31>")
	)
	(segment
		(start 145.122646 -295.610788)
		(end 145.161762 -295.633648)
		(width 0.0889)
		(layer "In4.Cu")
		(net "M_J_CPU1_SB_DQ<31>")
	)
	(segment
		(start 154.037538 -311.790588)
		(end 154.037538 -312.01868)
		(width 0.14478)
		(layer "In4.Cu")
		(net "M_J_CPU1_SB_DQ<31>")
	)
	(segment
		(start 157.302454 -314.76823)
		(end 157.15869 -314.91174)
		(width 0.14478)
		(layer "In4.Cu")
		(net "M_J_CPU1_SB_DQ<31>")
	)
	(segment
		(start 133.224778 -293.52621)
		(end 133.947408 -293.22141)
		(width 0.0889)
		(layer "In4.Cu")
		(net "M_J_CPU1_SB_DQ<31>")
	)
	(segment
		(start 145.161762 -295.633648)
		(end 145.191226 -295.650666)
		(width 0.0889)
		(layer "In4.Cu")
		(net "M_J_CPU1_SB_DQ<31>")
	)
	(segment
		(start 140.557758 -293.20363)
		(end 140.56614 -293.198804)
		(width 0.0889)
		(layer "In4.Cu")
		(net "M_J_CPU1_SB_DQ<31>")
	)
	(arc
		(start 139.991846 -293.20363)
		(mid 140.274802 -293.279807)
		(end 140.557758 -293.20363)
		(width 0.0889)
		(layer "In4.Cu")
		(net "M_J_CPU1_SB_DQ<31>")
	)
	(arc
		(start 144.252188 -294.031416)
		(mid 144.367615 -294.164792)
		(end 144.40916 -294.336216)
		(width 0.0889)
		(layer "In4.Cu")
		(net "M_J_CPU1_SB_DQ<31>")
	)
	(arc
		(start 135.29183 -293.20363)
		(mid 135.574786 -293.279807)
		(end 135.857742 -293.20363)
		(width 0.0889)
		(layer "In4.Cu")
		(net "M_J_CPU1_SB_DQ<31>")
	)
	(arc
		(start 139.626086 -293.198804)
		(mid 139.809594 -293.15331)
		(end 139.991846 -293.20363)
		(width 0.0889)
		(layer "In4.Cu")
		(net "M_J_CPU1_SB_DQ<31>")
	)
	(arc
		(start 135.866124 -293.198804)
		(mid 136.049632 -293.15331)
		(end 136.231884 -293.20363)
		(width 0.0889)
		(layer "In4.Cu")
		(net "M_J_CPU1_SB_DQ<31>")
	)
	(arc
		(start 144.40916 -294.336216)
		(mid 144.473675 -294.598435)
		(end 144.652492 -294.800782)
		(width 0.0889)
		(layer "In4.Cu")
		(net "M_J_CPU1_SB_DQ<31>")
	)
	(arc
		(start 133.977634 -293.20363)
		(mid 134.159885 -293.15328)
		(end 134.343394 -293.198804)
		(width 0.0889)
		(layer "In4.Cu")
		(net "M_J_CPU1_SB_DQ<31>")
	)
	(arc
		(start 136.231884 -293.20363)
		(mid 136.51484 -293.279807)
		(end 136.797796 -293.20363)
		(width 0.0889)
		(layer "In4.Cu")
		(net "M_J_CPU1_SB_DQ<31>")
	)
	(arc
		(start 140.56614 -293.198804)
		(mid 140.749648 -293.15331)
		(end 140.9319 -293.20363)
		(width 0.0889)
		(layer "In4.Cu")
		(net "M_J_CPU1_SB_DQ<31>")
	)
	(arc
		(start 137.171684 -293.20363)
		(mid 137.45464 -293.279807)
		(end 137.737596 -293.20363)
		(width 0.0889)
		(layer "In4.Cu")
		(net "M_J_CPU1_SB_DQ<31>")
	)
	(arc
		(start 143.782288 -293.22141)
		(mid 143.897715 -293.354786)
		(end 143.93926 -293.52621)
		(width 0.0889)
		(layer "In4.Cu")
		(net "M_J_CPU1_SB_DQ<31>")
	)
	(arc
		(start 136.797796 -293.20363)
		(mid 136.98474 -293.153375)
		(end 137.171684 -293.20363)
		(width 0.0889)
		(layer "In4.Cu")
		(net "M_J_CPU1_SB_DQ<31>")
	)
	(arc
		(start 141.8717 -293.20363)
		(mid 142.154656 -293.279807)
		(end 142.437612 -293.20363)
		(width 0.0889)
		(layer "In4.Cu")
		(net "M_J_CPU1_SB_DQ<31>")
	)
	(arc
		(start 144.879314 -295.146222)
		(mid 144.943829 -295.408441)
		(end 145.122646 -295.610788)
		(width 0.0889)
		(layer "In4.Cu")
		(net "M_J_CPU1_SB_DQ<31>")
	)
	(arc
		(start 142.437612 -293.20363)
		(mid 142.619863 -293.15328)
		(end 142.803372 -293.198804)
		(width 0.0889)
		(layer "In4.Cu")
		(net "M_J_CPU1_SB_DQ<31>")
	)
	(arc
		(start 138.111738 -293.20363)
		(mid 138.394694 -293.279807)
		(end 138.67765 -293.20363)
		(width 0.0889)
		(layer "In4.Cu")
		(net "M_J_CPU1_SB_DQ<31>")
	)
	(arc
		(start 145.191226 -295.650666)
		(mid 145.307407 -295.784225)
		(end 145.349214 -295.956228)
		(width 0.0889)
		(layer "In4.Cu")
		(net "M_J_CPU1_SB_DQ<31>")
	)
	(arc
		(start 144.724374 -294.842692)
		(mid 144.838303 -294.975839)
		(end 144.879314 -295.146222)
		(width 0.0889)
		(layer "In4.Cu")
		(net "M_J_CPU1_SB_DQ<31>")
	)
	(arc
		(start 134.351776 -293.20363)
		(mid 134.634732 -293.279807)
		(end 134.917688 -293.20363)
		(width 0.0889)
		(layer "In4.Cu")
		(net "M_J_CPU1_SB_DQ<31>")
	)
	(arc
		(start 141.497812 -293.20363)
		(mid 141.684756 -293.153375)
		(end 141.8717 -293.20363)
		(width 0.0889)
		(layer "In4.Cu")
		(net "M_J_CPU1_SB_DQ<31>")
	)
	(arc
		(start 142.811754 -293.20363)
		(mid 143.09471 -293.279807)
		(end 143.377666 -293.20363)
		(width 0.0889)
		(layer "In4.Cu")
		(net "M_J_CPU1_SB_DQ<31>")
	)
	(arc
		(start 137.737596 -293.20363)
		(mid 137.919847 -293.15328)
		(end 138.103356 -293.198804)
		(width 0.0889)
		(layer "In4.Cu")
		(net "M_J_CPU1_SB_DQ<31>")
	)
	(arc
		(start 134.92607 -293.198804)
		(mid 135.109578 -293.15331)
		(end 135.29183 -293.20363)
		(width 0.0889)
		(layer "In4.Cu")
		(net "M_J_CPU1_SB_DQ<31>")
	)
	(arc
		(start 143.93926 -293.52621)
		(mid 144.003775 -293.788429)
		(end 144.182592 -293.990776)
		(width 0.0889)
		(layer "In4.Cu")
		(net "M_J_CPU1_SB_DQ<31>")
	)
	(arc
		(start 139.051792 -293.20363)
		(mid 139.334748 -293.279807)
		(end 139.617704 -293.20363)
		(width 0.0889)
		(layer "In4.Cu")
		(net "M_J_CPU1_SB_DQ<31>")
	)
	(arc
		(start 143.386048 -293.198804)
		(mid 143.569556 -293.15331)
		(end 143.751808 -293.20363)
		(width 0.0889)
		(layer "In4.Cu")
		(net "M_J_CPU1_SB_DQ<31>")
	)
	(arc
		(start 138.67765 -293.20363)
		(mid 138.859901 -293.15328)
		(end 139.04341 -293.198804)
		(width 0.0889)
		(layer "In4.Cu")
		(net "M_J_CPU1_SB_DQ<31>")
	)
	(arc
		(start 140.9319 -293.20363)
		(mid 141.214856 -293.279807)
		(end 141.497812 -293.20363)
		(width 0.0889)
		(layer "In4.Cu")
		(net "M_J_CPU1_SB_DQ<31>")
	)
	(segment
		(start 132.287772 -292.450266)
		(end 132.754878 -292.716204)
		(width 0.10668)
		(layer "F.Cu")
		(net "M_J_CPU1_SB_DQ<30>")
	)
	(segment
		(start 150.907496 -307.387752)
		(end 150.907496 -307.616352)
		(width 0.14478)
		(layer "In4.Cu")
		(net "M_J_CPU1_SB_DQ<30>")
	)
	(segment
		(start 160.871916 -316.760352)
		(end 186.635136 -316.760352)
		(width 0.14478)
		(layer "In4.Cu")
		(net "M_J_CPU1_SB_DQ<30>")
	)
	(segment
		(start 149.138386 -305.255422)
		(end 149.366986 -305.255422)
		(width 0.14478)
		(layer "In4.Cu")
		(net "M_J_CPU1_SB_DQ<30>")
	)
	(segment
		(start 150.127208 -306.607464)
		(end 150.127208 -306.836064)
		(width 0.14478)
		(layer "In4.Cu")
		(net "M_J_CPU1_SB_DQ<30>")
	)
	(segment
		(start 133.507734 -292.393624)
		(end 133.516116 -292.388798)
		(width 0.0889)
		(layer "In4.Cu")
		(net "M_J_CPU1_SB_DQ<30>")
	)
	(segment
		(start 147.1676 -303.876456)
		(end 147.3962 -303.876456)
		(width 0.14478)
		(layer "In4.Cu")
		(net "M_J_CPU1_SB_DQ<30>")
	)
	(segment
		(start 151.47925 -307.596286)
		(end 151.70785 -307.596286)
		(width 0.14478)
		(layer "In4.Cu")
		(net "M_J_CPU1_SB_DQ<30>")
	)
	(segment
		(start 151.089106 -307.206142)
		(end 150.907496 -307.387752)
		(width 0.14478)
		(layer "In4.Cu")
		(net "M_J_CPU1_SB_DQ<30>")
	)
	(segment
		(start 137.267696 -292.393624)
		(end 137.276078 -292.388798)
		(width 0.0889)
		(layer "In4.Cu")
		(net "M_J_CPU1_SB_DQ<30>")
	)
	(segment
		(start 150.147274 -306.03571)
		(end 150.308818 -306.197254)
		(width 0.14478)
		(layer "In4.Cu")
		(net "M_J_CPU1_SB_DQ<30>")
	)
	(segment
		(start 145.819368 -295.443656)
		(end 146.0246 -295.648888)
		(width 0.0889)
		(layer "In4.Cu")
		(net "M_J_CPU1_SB_DQ<30>")
	)
	(segment
		(start 146.0246 -296.358818)
		(end 146.0246 -301.913036)
		(width 0.14478)
		(layer "In4.Cu")
		(net "M_J_CPU1_SB_DQ<30>")
	)
	(segment
		(start 145.161762 -294.013636)
		(end 145.192242 -294.031416)
		(width 0.0889)
		(layer "In4.Cu")
		(net "M_J_CPU1_SB_DQ<30>")
	)
	(segment
		(start 146.225768 -302.934624)
		(end 146.387312 -303.096168)
		(width 0.14478)
		(layer "In4.Cu")
		(net "M_J_CPU1_SB_DQ<30>")
	)
	(segment
		(start 146.615912 -303.096168)
		(end 146.797522 -302.914558)
		(width 0.14478)
		(layer "In4.Cu")
		(net "M_J_CPU1_SB_DQ<30>")
	)
	(segment
		(start 147.006056 -303.714912)
		(end 147.1676 -303.876456)
		(width 0.14478)
		(layer "In4.Cu")
		(net "M_J_CPU1_SB_DQ<30>")
	)
	(segment
		(start 145.631662 -294.823642)
		(end 145.663412 -294.84193)
		(width 0.0889)
		(layer "In4.Cu")
		(net "M_J_CPU1_SB_DQ<30>")
	)
	(segment
		(start 144.652746 -293.18077)
		(end 144.691862 -293.20363)
		(width 0.0889)
		(layer "In4.Cu")
		(net "M_J_CPU1_SB_DQ<30>")
	)
	(segment
		(start 150.907496 -307.616352)
		(end 151.06904 -307.777896)
		(width 0.14478)
		(layer "In4.Cu")
		(net "M_J_CPU1_SB_DQ<30>")
	)
	(segment
		(start 186.635136 -316.760352)
		(end 187.060078 -316.33541)
		(width 0.14478)
		(layer "In4.Cu")
		(net "M_J_CPU1_SB_DQ<30>")
	)
	(segment
		(start 148.566632 -305.046888)
		(end 148.566632 -305.275488)
		(width 0.14478)
		(layer "In4.Cu")
		(net "M_J_CPU1_SB_DQ<30>")
	)
	(segment
		(start 132.754878 -292.716204)
		(end 132.908802 -292.450774)
		(width 0.0889)
		(layer "In4.Cu")
		(net "M_J_CPU1_SB_DQ<30>")
	)
	(segment
		(start 146.0246 -301.913036)
		(end 146.407378 -302.295814)
		(width 0.14478)
		(layer "In4.Cu")
		(net "M_J_CPU1_SB_DQ<30>")
	)
	(segment
		(start 147.967954 -303.85639)
		(end 147.967954 -304.08499)
		(width 0.14478)
		(layer "In4.Cu")
		(net "M_J_CPU1_SB_DQ<30>")
	)
	(segment
		(start 151.29764 -307.777896)
		(end 151.47925 -307.596286)
		(width 0.14478)
		(layer "In4.Cu")
		(net "M_J_CPU1_SB_DQ<30>")
	)
	(segment
		(start 151.70785 -307.596286)
		(end 160.871916 -316.760352)
		(width 0.14478)
		(layer "In4.Cu")
		(net "M_J_CPU1_SB_DQ<30>")
	)
	(segment
		(start 147.57781 -303.694846)
		(end 147.80641 -303.694846)
		(width 0.14478)
		(layer "In4.Cu")
		(net "M_J_CPU1_SB_DQ<30>")
	)
	(segment
		(start 148.586698 -304.475134)
		(end 148.748242 -304.636678)
		(width 0.14478)
		(layer "In4.Cu")
		(net "M_J_CPU1_SB_DQ<30>")
	)
	(segment
		(start 149.508464 -306.21732)
		(end 149.737064 -306.21732)
		(width 0.14478)
		(layer "In4.Cu")
		(net "M_J_CPU1_SB_DQ<30>")
	)
	(segment
		(start 144.691862 -293.20363)
		(end 144.722342 -293.22141)
		(width 0.0889)
		(layer "In4.Cu")
		(net "M_J_CPU1_SB_DQ<30>")
	)
	(segment
		(start 146.0246 -295.648888)
		(end 146.0246 -296.358818)
		(width 0.0889)
		(layer "In4.Cu")
		(net "M_J_CPU1_SB_DQ<30>")
	)
	(segment
		(start 147.026122 -302.914558)
		(end 147.187666 -303.076102)
		(width 0.14478)
		(layer "In4.Cu")
		(net "M_J_CPU1_SB_DQ<30>")
	)
	(segment
		(start 151.089106 -306.977542)
		(end 151.089106 -307.206142)
		(width 0.14478)
		(layer "In4.Cu")
		(net "M_J_CPU1_SB_DQ<30>")
	)
	(segment
		(start 150.288752 -306.997608)
		(end 150.517352 -306.997608)
		(width 0.14478)
		(layer "In4.Cu")
		(net "M_J_CPU1_SB_DQ<30>")
	)
	(segment
		(start 147.006056 -303.486312)
		(end 147.006056 -303.714912)
		(width 0.14478)
		(layer "In4.Cu")
		(net "M_J_CPU1_SB_DQ<30>")
	)
	(segment
		(start 148.748242 -304.636678)
		(end 148.748242 -304.865278)
		(width 0.14478)
		(layer "In4.Cu")
		(net "M_J_CPU1_SB_DQ<30>")
	)
	(segment
		(start 150.517352 -306.997608)
		(end 150.698962 -306.815998)
		(width 0.14478)
		(layer "In4.Cu")
		(net "M_J_CPU1_SB_DQ<30>")
	)
	(segment
		(start 146.407378 -302.295814)
		(end 146.407378 -302.524414)
		(width 0.14478)
		(layer "In4.Cu")
		(net "M_J_CPU1_SB_DQ<30>")
	)
	(segment
		(start 146.407378 -302.524414)
		(end 146.225768 -302.706024)
		(width 0.14478)
		(layer "In4.Cu")
		(net "M_J_CPU1_SB_DQ<30>")
	)
	(segment
		(start 147.786344 -304.4952)
		(end 147.947888 -304.656744)
		(width 0.14478)
		(layer "In4.Cu")
		(net "M_J_CPU1_SB_DQ<30>")
	)
	(segment
		(start 148.728176 -305.437032)
		(end 148.956776 -305.437032)
		(width 0.14478)
		(layer "In4.Cu")
		(net "M_J_CPU1_SB_DQ<30>")
	)
	(segment
		(start 148.748242 -304.865278)
		(end 148.566632 -305.046888)
		(width 0.14478)
		(layer "In4.Cu")
		(net "M_J_CPU1_SB_DQ<30>")
	)
	(segment
		(start 146.387312 -303.096168)
		(end 146.615912 -303.096168)
		(width 0.14478)
		(layer "In4.Cu")
		(net "M_J_CPU1_SB_DQ<30>")
	)
	(segment
		(start 146.225768 -302.706024)
		(end 146.225768 -302.934624)
		(width 0.14478)
		(layer "In4.Cu")
		(net "M_J_CPU1_SB_DQ<30>")
	)
	(segment
		(start 148.176488 -304.656744)
		(end 148.358098 -304.475134)
		(width 0.14478)
		(layer "In4.Cu")
		(net "M_J_CPU1_SB_DQ<30>")
	)
	(segment
		(start 150.308818 -306.425854)
		(end 150.127208 -306.607464)
		(width 0.14478)
		(layer "In4.Cu")
		(net "M_J_CPU1_SB_DQ<30>")
	)
	(segment
		(start 147.786344 -304.2666)
		(end 147.786344 -304.4952)
		(width 0.14478)
		(layer "In4.Cu")
		(net "M_J_CPU1_SB_DQ<30>")
	)
	(segment
		(start 147.187666 -303.076102)
		(end 147.187666 -303.304702)
		(width 0.14478)
		(layer "In4.Cu")
		(net "M_J_CPU1_SB_DQ<30>")
	)
	(segment
		(start 149.52853 -305.416966)
		(end 149.52853 -305.645566)
		(width 0.14478)
		(layer "In4.Cu")
		(net "M_J_CPU1_SB_DQ<30>")
	)
	(segment
		(start 145.592546 -294.800782)
		(end 145.631662 -294.823642)
		(width 0.0889)
		(layer "In4.Cu")
		(net "M_J_CPU1_SB_DQ<30>")
	)
	(segment
		(start 147.967954 -304.08499)
		(end 147.786344 -304.2666)
		(width 0.14478)
		(layer "In4.Cu")
		(net "M_J_CPU1_SB_DQ<30>")
	)
	(segment
		(start 148.358098 -304.475134)
		(end 148.586698 -304.475134)
		(width 0.14478)
		(layer "In4.Cu")
		(net "M_J_CPU1_SB_DQ<30>")
	)
	(segment
		(start 136.693402 -292.388798)
		(end 136.701784 -292.393624)
		(width 0.0889)
		(layer "In4.Cu")
		(net "M_J_CPU1_SB_DQ<30>")
	)
	(segment
		(start 151.06904 -307.777896)
		(end 151.29764 -307.777896)
		(width 0.14478)
		(layer "In4.Cu")
		(net "M_J_CPU1_SB_DQ<30>")
	)
	(segment
		(start 150.308818 -306.197254)
		(end 150.308818 -306.425854)
		(width 0.14478)
		(layer "In4.Cu")
		(net "M_J_CPU1_SB_DQ<30>")
	)
	(segment
		(start 147.187666 -303.304702)
		(end 147.006056 -303.486312)
		(width 0.14478)
		(layer "In4.Cu")
		(net "M_J_CPU1_SB_DQ<30>")
	)
	(segment
		(start 146.797522 -302.914558)
		(end 147.026122 -302.914558)
		(width 0.14478)
		(layer "In4.Cu")
		(net "M_J_CPU1_SB_DQ<30>")
	)
	(segment
		(start 149.366986 -305.255422)
		(end 149.52853 -305.416966)
		(width 0.14478)
		(layer "In4.Cu")
		(net "M_J_CPU1_SB_DQ<30>")
	)
	(segment
		(start 147.80641 -303.694846)
		(end 147.967954 -303.85639)
		(width 0.14478)
		(layer "In4.Cu")
		(net "M_J_CPU1_SB_DQ<30>")
	)
	(segment
		(start 149.52853 -305.645566)
		(end 149.34692 -305.827176)
		(width 0.14478)
		(layer "In4.Cu")
		(net "M_J_CPU1_SB_DQ<30>")
	)
	(segment
		(start 140.453364 -292.388798)
		(end 140.461746 -292.393624)
		(width 0.0889)
		(layer "In4.Cu")
		(net "M_J_CPU1_SB_DQ<30>")
	)
	(segment
		(start 135.753348 -292.388798)
		(end 135.76173 -292.393624)
		(width 0.0889)
		(layer "In4.Cu")
		(net "M_J_CPU1_SB_DQ<30>")
	)
	(segment
		(start 138.20775 -292.393624)
		(end 138.216132 -292.388798)
		(width 0.0889)
		(layer "In4.Cu")
		(net "M_J_CPU1_SB_DQ<30>")
	)
	(segment
		(start 145.122646 -293.990776)
		(end 145.161762 -294.013636)
		(width 0.0889)
		(layer "In4.Cu")
		(net "M_J_CPU1_SB_DQ<30>")
	)
	(segment
		(start 141.393418 -292.388798)
		(end 141.4018 -292.393624)
		(width 0.0889)
		(layer "In4.Cu")
		(net "M_J_CPU1_SB_DQ<30>")
	)
	(segment
		(start 132.908802 -292.450774)
		(end 133.004814 -292.425374)
		(width 0.0889)
		(layer "In4.Cu")
		(net "M_J_CPU1_SB_DQ<30>")
	)
	(segment
		(start 150.927562 -306.815998)
		(end 151.089106 -306.977542)
		(width 0.14478)
		(layer "In4.Cu")
		(net "M_J_CPU1_SB_DQ<30>")
	)
	(segment
		(start 145.819368 -295.146222)
		(end 145.819368 -295.443656)
		(width 0.0889)
		(layer "In4.Cu")
		(net "M_J_CPU1_SB_DQ<30>")
	)
	(segment
		(start 148.566632 -305.275488)
		(end 148.728176 -305.437032)
		(width 0.14478)
		(layer "In4.Cu")
		(net "M_J_CPU1_SB_DQ<30>")
	)
	(segment
		(start 150.698962 -306.815998)
		(end 150.927562 -306.815998)
		(width 0.14478)
		(layer "In4.Cu")
		(net "M_J_CPU1_SB_DQ<30>")
	)
	(segment
		(start 149.918674 -306.03571)
		(end 150.147274 -306.03571)
		(width 0.14478)
		(layer "In4.Cu")
		(net "M_J_CPU1_SB_DQ<30>")
	)
	(segment
		(start 141.967712 -292.393624)
		(end 141.976094 -292.388798)
		(width 0.0889)
		(layer "In4.Cu")
		(net "M_J_CPU1_SB_DQ<30>")
	)
	(segment
		(start 148.956776 -305.437032)
		(end 149.138386 -305.255422)
		(width 0.14478)
		(layer "In4.Cu")
		(net "M_J_CPU1_SB_DQ<30>")
	)
	(segment
		(start 149.34692 -306.055776)
		(end 149.508464 -306.21732)
		(width 0.14478)
		(layer "In4.Cu")
		(net "M_J_CPU1_SB_DQ<30>")
	)
	(segment
		(start 144.221962 -292.393624)
		(end 144.252442 -292.411404)
		(width 0.0889)
		(layer "In4.Cu")
		(net "M_J_CPU1_SB_DQ<30>")
	)
	(segment
		(start 147.947888 -304.656744)
		(end 148.176488 -304.656744)
		(width 0.14478)
		(layer "In4.Cu")
		(net "M_J_CPU1_SB_DQ<30>")
	)
	(segment
		(start 149.737064 -306.21732)
		(end 149.918674 -306.03571)
		(width 0.14478)
		(layer "In4.Cu")
		(net "M_J_CPU1_SB_DQ<30>")
	)
	(segment
		(start 149.34692 -305.827176)
		(end 149.34692 -306.055776)
		(width 0.14478)
		(layer "In4.Cu")
		(net "M_J_CPU1_SB_DQ<30>")
	)
	(segment
		(start 147.3962 -303.876456)
		(end 147.57781 -303.694846)
		(width 0.14478)
		(layer "In4.Cu")
		(net "M_J_CPU1_SB_DQ<30>")
	)
	(segment
		(start 150.127208 -306.836064)
		(end 150.288752 -306.997608)
		(width 0.14478)
		(layer "In4.Cu")
		(net "M_J_CPU1_SB_DQ<30>")
	)
	(arc
		(start 134.821676 -292.393624)
		(mid 135.104632 -292.469801)
		(end 135.387588 -292.393624)
		(width 0.0889)
		(layer "In4.Cu")
		(net "M_J_CPU1_SB_DQ<30>")
	)
	(arc
		(start 144.722342 -293.22141)
		(mid 144.837769 -293.354786)
		(end 144.879314 -293.52621)
		(width 0.0889)
		(layer "In4.Cu")
		(net "M_J_CPU1_SB_DQ<30>")
	)
	(arc
		(start 140.087604 -292.393624)
		(mid 140.269855 -292.343274)
		(end 140.453364 -292.388798)
		(width 0.0889)
		(layer "In4.Cu")
		(net "M_J_CPU1_SB_DQ<30>")
	)
	(arc
		(start 134.447788 -292.393624)
		(mid 134.634732 -292.343369)
		(end 134.821676 -292.393624)
		(width 0.0889)
		(layer "In4.Cu")
		(net "M_J_CPU1_SB_DQ<30>")
	)
	(arc
		(start 135.76173 -292.393624)
		(mid 136.044686 -292.469801)
		(end 136.327642 -292.393624)
		(width 0.0889)
		(layer "In4.Cu")
		(net "M_J_CPU1_SB_DQ<30>")
	)
	(arc
		(start 135.387588 -292.393624)
		(mid 135.569839 -292.343274)
		(end 135.753348 -292.388798)
		(width 0.0889)
		(layer "In4.Cu")
		(net "M_J_CPU1_SB_DQ<30>")
	)
	(arc
		(start 137.276078 -292.388798)
		(mid 137.459586 -292.343304)
		(end 137.641838 -292.393624)
		(width 0.0889)
		(layer "In4.Cu")
		(net "M_J_CPU1_SB_DQ<30>")
	)
	(arc
		(start 139.147804 -292.393624)
		(mid 139.334748 -292.343369)
		(end 139.521692 -292.393624)
		(width 0.0889)
		(layer "In4.Cu")
		(net "M_J_CPU1_SB_DQ<30>")
	)
	(arc
		(start 138.216132 -292.388798)
		(mid 138.39964 -292.343304)
		(end 138.581892 -292.393624)
		(width 0.0889)
		(layer "In4.Cu")
		(net "M_J_CPU1_SB_DQ<30>")
	)
	(arc
		(start 139.521692 -292.393624)
		(mid 139.804648 -292.469801)
		(end 140.087604 -292.393624)
		(width 0.0889)
		(layer "In4.Cu")
		(net "M_J_CPU1_SB_DQ<30>")
	)
	(arc
		(start 136.701784 -292.393624)
		(mid 136.98474 -292.469801)
		(end 137.267696 -292.393624)
		(width 0.0889)
		(layer "In4.Cu")
		(net "M_J_CPU1_SB_DQ<30>")
	)
	(arc
		(start 136.327642 -292.393624)
		(mid 136.509893 -292.343274)
		(end 136.693402 -292.388798)
		(width 0.0889)
		(layer "In4.Cu")
		(net "M_J_CPU1_SB_DQ<30>")
	)
	(arc
		(start 144.409414 -292.716204)
		(mid 144.473929 -292.978423)
		(end 144.652746 -293.18077)
		(width 0.0889)
		(layer "In4.Cu")
		(net "M_J_CPU1_SB_DQ<30>")
	)
	(arc
		(start 133.881876 -292.393624)
		(mid 134.164832 -292.469801)
		(end 134.447788 -292.393624)
		(width 0.0889)
		(layer "In4.Cu")
		(net "M_J_CPU1_SB_DQ<30>")
	)
	(arc
		(start 145.663412 -294.84193)
		(mid 145.778088 -294.975264)
		(end 145.819368 -295.146222)
		(width 0.0889)
		(layer "In4.Cu")
		(net "M_J_CPU1_SB_DQ<30>")
	)
	(arc
		(start 143.847566 -292.393624)
		(mid 144.034764 -292.343242)
		(end 144.221962 -292.393624)
		(width 0.0889)
		(layer "In4.Cu")
		(net "M_J_CPU1_SB_DQ<30>")
	)
	(arc
		(start 141.027658 -292.393624)
		(mid 141.209909 -292.343274)
		(end 141.393418 -292.388798)
		(width 0.0889)
		(layer "In4.Cu")
		(net "M_J_CPU1_SB_DQ<30>")
	)
	(arc
		(start 142.341854 -292.393624)
		(mid 142.62481 -292.469801)
		(end 142.907766 -292.393624)
		(width 0.0889)
		(layer "In4.Cu")
		(net "M_J_CPU1_SB_DQ<30>")
	)
	(arc
		(start 144.252442 -292.411404)
		(mid 144.367869 -292.54478)
		(end 144.409414 -292.716204)
		(width 0.0889)
		(layer "In4.Cu")
		(net "M_J_CPU1_SB_DQ<30>")
	)
	(arc
		(start 133.516116 -292.388798)
		(mid 133.699624 -292.343304)
		(end 133.881876 -292.393624)
		(width 0.0889)
		(layer "In4.Cu")
		(net "M_J_CPU1_SB_DQ<30>")
	)
	(arc
		(start 143.281654 -292.393624)
		(mid 143.56461 -292.469801)
		(end 143.847566 -292.393624)
		(width 0.0889)
		(layer "In4.Cu")
		(net "M_J_CPU1_SB_DQ<30>")
	)
	(arc
		(start 141.4018 -292.393624)
		(mid 141.684756 -292.469801)
		(end 141.967712 -292.393624)
		(width 0.0889)
		(layer "In4.Cu")
		(net "M_J_CPU1_SB_DQ<30>")
	)
	(arc
		(start 141.976094 -292.388798)
		(mid 142.159602 -292.343304)
		(end 142.341854 -292.393624)
		(width 0.0889)
		(layer "In4.Cu")
		(net "M_J_CPU1_SB_DQ<30>")
	)
	(arc
		(start 133.004814 -292.425374)
		(mid 133.260022 -292.468851)
		(end 133.507734 -292.393624)
		(width 0.0889)
		(layer "In4.Cu")
		(net "M_J_CPU1_SB_DQ<30>")
	)
	(arc
		(start 137.641838 -292.393624)
		(mid 137.924794 -292.469801)
		(end 138.20775 -292.393624)
		(width 0.0889)
		(layer "In4.Cu")
		(net "M_J_CPU1_SB_DQ<30>")
	)
	(arc
		(start 145.349214 -294.336216)
		(mid 145.413729 -294.598435)
		(end 145.592546 -294.800782)
		(width 0.0889)
		(layer "In4.Cu")
		(net "M_J_CPU1_SB_DQ<30>")
	)
	(arc
		(start 142.907766 -292.393624)
		(mid 143.09471 -292.343369)
		(end 143.281654 -292.393624)
		(width 0.0889)
		(layer "In4.Cu")
		(net "M_J_CPU1_SB_DQ<30>")
	)
	(arc
		(start 145.192242 -294.031416)
		(mid 145.307669 -294.164792)
		(end 145.349214 -294.336216)
		(width 0.0889)
		(layer "In4.Cu")
		(net "M_J_CPU1_SB_DQ<30>")
	)
	(arc
		(start 144.879314 -293.52621)
		(mid 144.943829 -293.788429)
		(end 145.122646 -293.990776)
		(width 0.0889)
		(layer "In4.Cu")
		(net "M_J_CPU1_SB_DQ<30>")
	)
	(arc
		(start 140.461746 -292.393624)
		(mid 140.744702 -292.469801)
		(end 141.027658 -292.393624)
		(width 0.0889)
		(layer "In4.Cu")
		(net "M_J_CPU1_SB_DQ<30>")
	)
	(arc
		(start 138.581892 -292.393624)
		(mid 138.864848 -292.469801)
		(end 139.147804 -292.393624)
		(width 0.0889)
		(layer "In4.Cu")
		(net "M_J_CPU1_SB_DQ<30>")
	)
	(segment
		(start 132.287772 -274.630388)
		(end 132.754878 -274.896326)
		(width 0.10668)
		(layer "F.Cu")
		(net "M_J_CPU1_SB_DQ<2>")
	)
	(segment
		(start 160.173924 -278.99233)
		(end 160.494726 -278.671782)
		(width 0.14478)
		(layer "In4.Cu")
		(net "M_J_CPU1_SB_DQ<2>")
	)
	(segment
		(start 160.494726 -278.671782)
		(end 160.722818 -278.671782)
		(width 0.14478)
		(layer "In4.Cu")
		(net "M_J_CPU1_SB_DQ<2>")
	)
	(segment
		(start 166.150036 -282.76042)
		(end 167.000174 -281.910282)
		(width 0.14478)
		(layer "In4.Cu")
		(net "M_J_CPU1_SB_DQ<2>")
	)
	(segment
		(start 144.220946 -274.574)
		(end 144.242536 -274.586446)
		(width 0.0889)
		(layer "In4.Cu")
		(net "M_J_CPU1_SB_DQ<2>")
	)
	(segment
		(start 137.267696 -274.573746)
		(end 137.276078 -274.56892)
		(width 0.0889)
		(layer "In4.Cu")
		(net "M_J_CPU1_SB_DQ<2>")
	)
	(segment
		(start 161.344356 -280.162762)
		(end 161.344356 -280.390854)
		(width 0.14478)
		(layer "In4.Cu")
		(net "M_J_CPU1_SB_DQ<2>")
	)
	(segment
		(start 163.713922 -282.76042)
		(end 166.150036 -282.76042)
		(width 0.14478)
		(layer "In4.Cu")
		(net "M_J_CPU1_SB_DQ<2>")
	)
	(segment
		(start 132.908802 -274.630896)
		(end 133.004814 -274.605496)
		(width 0.0889)
		(layer "In4.Cu")
		(net "M_J_CPU1_SB_DQ<2>")
	)
	(segment
		(start 145.444718 -274.650454)
		(end 145.640044 -274.650454)
		(width 0.0889)
		(layer "In4.Cu")
		(net "M_J_CPU1_SB_DQ<2>")
	)
	(segment
		(start 174.544228 -281.910282)
		(end 177.726594 -281.910282)
		(width 0.14478)
		(layer "In4.Cu")
		(net "M_J_CPU1_SB_DQ<2>")
	)
	(segment
		(start 162.283394 -280.232358)
		(end 162.445446 -280.39441)
		(width 0.14478)
		(layer "In4.Cu")
		(net "M_J_CPU1_SB_DQ<2>")
	)
	(segment
		(start 145.81886 -274.583144)
		(end 146.75612 -273.645884)
		(width 0.0889)
		(layer "In4.Cu")
		(net "M_J_CPU1_SB_DQ<2>")
	)
	(segment
		(start 162.445446 -280.39441)
		(end 162.445446 -280.622502)
		(width 0.14478)
		(layer "In4.Cu")
		(net "M_J_CPU1_SB_DQ<2>")
	)
	(segment
		(start 160.88487 -279.061926)
		(end 160.564068 -279.382474)
		(width 0.14478)
		(layer "In4.Cu")
		(net "M_J_CPU1_SB_DQ<2>")
	)
	(segment
		(start 154.347926 -273.394424)
		(end 159.945832 -278.99233)
		(width 0.14478)
		(layer "In4.Cu")
		(net "M_J_CPU1_SB_DQ<2>")
	)
	(segment
		(start 186.635136 -281.910282)
		(end 187.060078 -282.335224)
		(width 0.14478)
		(layer "In4.Cu")
		(net "M_J_CPU1_SB_DQ<2>")
	)
	(segment
		(start 171.032678 -282.76042)
		(end 173.69409 -282.76042)
		(width 0.14478)
		(layer "In4.Cu")
		(net "M_J_CPU1_SB_DQ<2>")
	)
	(segment
		(start 161.665158 -279.614122)
		(end 161.665158 -279.842214)
		(width 0.14478)
		(layer "In4.Cu")
		(net "M_J_CPU1_SB_DQ<2>")
	)
	(segment
		(start 144.785334 -274.573746)
		(end 144.80413 -274.562824)
		(width 0.0889)
		(layer "In4.Cu")
		(net "M_J_CPU1_SB_DQ<2>")
	)
	(segment
		(start 141.967712 -274.573746)
		(end 141.976094 -274.56892)
		(width 0.0889)
		(layer "In4.Cu")
		(net "M_J_CPU1_SB_DQ<2>")
	)
	(segment
		(start 161.665158 -279.842214)
		(end 161.344356 -280.162762)
		(width 0.14478)
		(layer "In4.Cu")
		(net "M_J_CPU1_SB_DQ<2>")
	)
	(segment
		(start 162.904932 -281.723338)
		(end 162.904932 -281.95143)
		(width 0.14478)
		(layer "In4.Cu")
		(net "M_J_CPU1_SB_DQ<2>")
	)
	(segment
		(start 162.124644 -280.94305)
		(end 162.124644 -281.171142)
		(width 0.14478)
		(layer "In4.Cu")
		(net "M_J_CPU1_SB_DQ<2>")
	)
	(segment
		(start 162.286696 -281.333194)
		(end 162.514788 -281.333194)
		(width 0.14478)
		(layer "In4.Cu")
		(net "M_J_CPU1_SB_DQ<2>")
	)
	(segment
		(start 160.72612 -279.772618)
		(end 160.954212 -279.772618)
		(width 0.14478)
		(layer "In4.Cu")
		(net "M_J_CPU1_SB_DQ<2>")
	)
	(segment
		(start 160.722818 -278.671782)
		(end 160.88487 -278.833834)
		(width 0.14478)
		(layer "In4.Cu")
		(net "M_J_CPU1_SB_DQ<2>")
	)
	(segment
		(start 140.453364 -274.56892)
		(end 140.461746 -274.573746)
		(width 0.0889)
		(layer "In4.Cu")
		(net "M_J_CPU1_SB_DQ<2>")
	)
	(segment
		(start 161.506408 -280.552906)
		(end 161.7345 -280.552906)
		(width 0.14478)
		(layer "In4.Cu")
		(net "M_J_CPU1_SB_DQ<2>")
	)
	(segment
		(start 144.20088 -274.56257)
		(end 144.220946 -274.574)
		(width 0.0889)
		(layer "In4.Cu")
		(net "M_J_CPU1_SB_DQ<2>")
	)
	(segment
		(start 162.904932 -281.95143)
		(end 163.713922 -282.76042)
		(width 0.14478)
		(layer "In4.Cu")
		(net "M_J_CPU1_SB_DQ<2>")
	)
	(segment
		(start 146.75612 -273.645884)
		(end 147.297648 -273.645884)
		(width 0.0889)
		(layer "In4.Cu")
		(net "M_J_CPU1_SB_DQ<2>")
	)
	(segment
		(start 170.18254 -281.910282)
		(end 171.032678 -282.76042)
		(width 0.14478)
		(layer "In4.Cu")
		(net "M_J_CPU1_SB_DQ<2>")
	)
	(segment
		(start 160.954212 -279.772618)
		(end 161.275014 -279.45207)
		(width 0.14478)
		(layer "In4.Cu")
		(net "M_J_CPU1_SB_DQ<2>")
	)
	(segment
		(start 167.000174 -281.910282)
		(end 170.18254 -281.910282)
		(width 0.14478)
		(layer "In4.Cu")
		(net "M_J_CPU1_SB_DQ<2>")
	)
	(segment
		(start 148.048218 -273.394424)
		(end 154.347926 -273.394424)
		(width 0.14478)
		(layer "In4.Cu")
		(net "M_J_CPU1_SB_DQ<2>")
	)
	(segment
		(start 177.726594 -281.910282)
		(end 178.576732 -282.76042)
		(width 0.14478)
		(layer "In4.Cu")
		(net "M_J_CPU1_SB_DQ<2>")
	)
	(segment
		(start 163.225734 -281.174698)
		(end 163.225734 -281.40279)
		(width 0.14478)
		(layer "In4.Cu")
		(net "M_J_CPU1_SB_DQ<2>")
	)
	(segment
		(start 181.5592 -281.910282)
		(end 186.635136 -281.910282)
		(width 0.14478)
		(layer "In4.Cu")
		(net "M_J_CPU1_SB_DQ<2>")
	)
	(segment
		(start 160.564068 -279.610566)
		(end 160.72612 -279.772618)
		(width 0.14478)
		(layer "In4.Cu")
		(net "M_J_CPU1_SB_DQ<2>")
	)
	(segment
		(start 161.344356 -280.390854)
		(end 161.506408 -280.552906)
		(width 0.14478)
		(layer "In4.Cu")
		(net "M_J_CPU1_SB_DQ<2>")
	)
	(segment
		(start 161.275014 -279.45207)
		(end 161.503106 -279.45207)
		(width 0.14478)
		(layer "In4.Cu")
		(net "M_J_CPU1_SB_DQ<2>")
	)
	(segment
		(start 147.297648 -273.645884)
		(end 147.549108 -273.394424)
		(width 0.0889)
		(layer "In4.Cu")
		(net "M_J_CPU1_SB_DQ<2>")
	)
	(segment
		(start 162.445446 -280.622502)
		(end 162.124644 -280.94305)
		(width 0.14478)
		(layer "In4.Cu")
		(net "M_J_CPU1_SB_DQ<2>")
	)
	(segment
		(start 161.503106 -279.45207)
		(end 161.665158 -279.614122)
		(width 0.14478)
		(layer "In4.Cu")
		(net "M_J_CPU1_SB_DQ<2>")
	)
	(segment
		(start 136.693402 -274.56892)
		(end 136.701784 -274.573746)
		(width 0.0889)
		(layer "In4.Cu")
		(net "M_J_CPU1_SB_DQ<2>")
	)
	(segment
		(start 162.124644 -281.171142)
		(end 162.286696 -281.333194)
		(width 0.14478)
		(layer "In4.Cu")
		(net "M_J_CPU1_SB_DQ<2>")
	)
	(segment
		(start 178.576732 -282.76042)
		(end 180.709062 -282.76042)
		(width 0.14478)
		(layer "In4.Cu")
		(net "M_J_CPU1_SB_DQ<2>")
	)
	(segment
		(start 132.754878 -274.896326)
		(end 132.908802 -274.630896)
		(width 0.0889)
		(layer "In4.Cu")
		(net "M_J_CPU1_SB_DQ<2>")
	)
	(segment
		(start 180.709062 -282.76042)
		(end 181.5592 -281.910282)
		(width 0.14478)
		(layer "In4.Cu")
		(net "M_J_CPU1_SB_DQ<2>")
	)
	(segment
		(start 163.063682 -281.012646)
		(end 163.225734 -281.174698)
		(width 0.14478)
		(layer "In4.Cu")
		(net "M_J_CPU1_SB_DQ<2>")
	)
	(segment
		(start 160.88487 -278.833834)
		(end 160.88487 -279.061926)
		(width 0.14478)
		(layer "In4.Cu")
		(net "M_J_CPU1_SB_DQ<2>")
	)
	(segment
		(start 173.69409 -282.76042)
		(end 174.544228 -281.910282)
		(width 0.14478)
		(layer "In4.Cu")
		(net "M_J_CPU1_SB_DQ<2>")
	)
	(segment
		(start 159.945832 -278.99233)
		(end 160.173924 -278.99233)
		(width 0.14478)
		(layer "In4.Cu")
		(net "M_J_CPU1_SB_DQ<2>")
	)
	(segment
		(start 163.225734 -281.40279)
		(end 162.904932 -281.723338)
		(width 0.14478)
		(layer "In4.Cu")
		(net "M_J_CPU1_SB_DQ<2>")
	)
	(segment
		(start 161.7345 -280.552906)
		(end 162.055302 -280.232358)
		(width 0.14478)
		(layer "In4.Cu")
		(net "M_J_CPU1_SB_DQ<2>")
	)
	(segment
		(start 162.055302 -280.232358)
		(end 162.283394 -280.232358)
		(width 0.14478)
		(layer "In4.Cu")
		(net "M_J_CPU1_SB_DQ<2>")
	)
	(segment
		(start 147.549108 -273.394424)
		(end 148.048218 -273.394424)
		(width 0.0889)
		(layer "In4.Cu")
		(net "M_J_CPU1_SB_DQ<2>")
	)
	(segment
		(start 133.507734 -274.573746)
		(end 133.516116 -274.56892)
		(width 0.0889)
		(layer "In4.Cu")
		(net "M_J_CPU1_SB_DQ<2>")
	)
	(segment
		(start 145.640044 -274.650454)
		(end 145.81886 -274.583144)
		(width 0.0889)
		(layer "In4.Cu")
		(net "M_J_CPU1_SB_DQ<2>")
	)
	(segment
		(start 162.514788 -281.333194)
		(end 162.83559 -281.012646)
		(width 0.14478)
		(layer "In4.Cu")
		(net "M_J_CPU1_SB_DQ<2>")
	)
	(segment
		(start 135.753348 -274.56892)
		(end 135.76173 -274.573746)
		(width 0.0889)
		(layer "In4.Cu")
		(net "M_J_CPU1_SB_DQ<2>")
	)
	(segment
		(start 141.393418 -274.56892)
		(end 141.4018 -274.573746)
		(width 0.0889)
		(layer "In4.Cu")
		(net "M_J_CPU1_SB_DQ<2>")
	)
	(segment
		(start 162.83559 -281.012646)
		(end 163.063682 -281.012646)
		(width 0.14478)
		(layer "In4.Cu")
		(net "M_J_CPU1_SB_DQ<2>")
	)
	(segment
		(start 138.20775 -274.573746)
		(end 138.216132 -274.56892)
		(width 0.0889)
		(layer "In4.Cu")
		(net "M_J_CPU1_SB_DQ<2>")
	)
	(segment
		(start 160.564068 -279.382474)
		(end 160.564068 -279.610566)
		(width 0.14478)
		(layer "In4.Cu")
		(net "M_J_CPU1_SB_DQ<2>")
	)
	(arc
		(start 138.216132 -274.56892)
		(mid 138.39964 -274.523426)
		(end 138.581892 -274.573746)
		(width 0.0889)
		(layer "In4.Cu")
		(net "M_J_CPU1_SB_DQ<2>")
	)
	(arc
		(start 137.641838 -274.573746)
		(mid 137.924794 -274.649923)
		(end 138.20775 -274.573746)
		(width 0.0889)
		(layer "In4.Cu")
		(net "M_J_CPU1_SB_DQ<2>")
	)
	(arc
		(start 133.004814 -274.605496)
		(mid 133.260022 -274.648973)
		(end 133.507734 -274.573746)
		(width 0.0889)
		(layer "In4.Cu")
		(net "M_J_CPU1_SB_DQ<2>")
	)
	(arc
		(start 138.581892 -274.573746)
		(mid 138.864848 -274.649923)
		(end 139.147804 -274.573746)
		(width 0.0889)
		(layer "In4.Cu")
		(net "M_J_CPU1_SB_DQ<2>")
	)
	(arc
		(start 141.976094 -274.56892)
		(mid 142.159602 -274.523426)
		(end 142.341854 -274.573746)
		(width 0.0889)
		(layer "In4.Cu")
		(net "M_J_CPU1_SB_DQ<2>")
	)
	(arc
		(start 133.516116 -274.56892)
		(mid 133.699624 -274.523426)
		(end 133.881876 -274.573746)
		(width 0.0889)
		(layer "In4.Cu")
		(net "M_J_CPU1_SB_DQ<2>")
	)
	(arc
		(start 143.281654 -274.573746)
		(mid 143.56461 -274.649923)
		(end 143.847566 -274.573746)
		(width 0.0889)
		(layer "In4.Cu")
		(net "M_J_CPU1_SB_DQ<2>")
	)
	(arc
		(start 142.907766 -274.573746)
		(mid 143.09471 -274.523491)
		(end 143.281654 -274.573746)
		(width 0.0889)
		(layer "In4.Cu")
		(net "M_J_CPU1_SB_DQ<2>")
	)
	(arc
		(start 142.341854 -274.573746)
		(mid 142.62481 -274.649923)
		(end 142.907766 -274.573746)
		(width 0.0889)
		(layer "In4.Cu")
		(net "M_J_CPU1_SB_DQ<2>")
	)
	(arc
		(start 135.387588 -274.573746)
		(mid 135.569839 -274.523396)
		(end 135.753348 -274.56892)
		(width 0.0889)
		(layer "In4.Cu")
		(net "M_J_CPU1_SB_DQ<2>")
	)
	(arc
		(start 137.276078 -274.56892)
		(mid 137.459586 -274.523426)
		(end 137.641838 -274.573746)
		(width 0.0889)
		(layer "In4.Cu")
		(net "M_J_CPU1_SB_DQ<2>")
	)
	(arc
		(start 144.242536 -274.586446)
		(mid 144.515565 -274.649765)
		(end 144.785334 -274.573746)
		(width 0.0889)
		(layer "In4.Cu")
		(net "M_J_CPU1_SB_DQ<2>")
	)
	(arc
		(start 141.027658 -274.573746)
		(mid 141.209909 -274.523396)
		(end 141.393418 -274.56892)
		(width 0.0889)
		(layer "In4.Cu")
		(net "M_J_CPU1_SB_DQ<2>")
	)
	(arc
		(start 140.087604 -274.573746)
		(mid 140.269855 -274.523396)
		(end 140.453364 -274.56892)
		(width 0.0889)
		(layer "In4.Cu")
		(net "M_J_CPU1_SB_DQ<2>")
	)
	(arc
		(start 143.847566 -274.573746)
		(mid 144.022805 -274.523675)
		(end 144.20088 -274.56257)
		(width 0.0889)
		(layer "In4.Cu")
		(net "M_J_CPU1_SB_DQ<2>")
	)
	(arc
		(start 136.327642 -274.573746)
		(mid 136.509893 -274.523396)
		(end 136.693402 -274.56892)
		(width 0.0889)
		(layer "In4.Cu")
		(net "M_J_CPU1_SB_DQ<2>")
	)
	(arc
		(start 133.881876 -274.573746)
		(mid 134.164832 -274.649923)
		(end 134.447788 -274.573746)
		(width 0.0889)
		(layer "In4.Cu")
		(net "M_J_CPU1_SB_DQ<2>")
	)
	(arc
		(start 134.821676 -274.573746)
		(mid 135.104632 -274.649923)
		(end 135.387588 -274.573746)
		(width 0.0889)
		(layer "In4.Cu")
		(net "M_J_CPU1_SB_DQ<2>")
	)
	(arc
		(start 144.80413 -274.562824)
		(mid 144.983701 -274.523007)
		(end 145.160492 -274.573746)
		(width 0.0889)
		(layer "In4.Cu")
		(net "M_J_CPU1_SB_DQ<2>")
	)
	(arc
		(start 145.160492 -274.573746)
		(mid 145.297514 -274.630957)
		(end 145.444718 -274.650454)
		(width 0.0889)
		(layer "In4.Cu")
		(net "M_J_CPU1_SB_DQ<2>")
	)
	(arc
		(start 140.461746 -274.573746)
		(mid 140.744702 -274.649923)
		(end 141.027658 -274.573746)
		(width 0.0889)
		(layer "In4.Cu")
		(net "M_J_CPU1_SB_DQ<2>")
	)
	(arc
		(start 141.4018 -274.573746)
		(mid 141.684756 -274.649923)
		(end 141.967712 -274.573746)
		(width 0.0889)
		(layer "In4.Cu")
		(net "M_J_CPU1_SB_DQ<2>")
	)
	(arc
		(start 135.76173 -274.573746)
		(mid 136.044686 -274.649923)
		(end 136.327642 -274.573746)
		(width 0.0889)
		(layer "In4.Cu")
		(net "M_J_CPU1_SB_DQ<2>")
	)
	(arc
		(start 136.701784 -274.573746)
		(mid 136.98474 -274.649923)
		(end 137.267696 -274.573746)
		(width 0.0889)
		(layer "In4.Cu")
		(net "M_J_CPU1_SB_DQ<2>")
	)
	(arc
		(start 134.447788 -274.573746)
		(mid 134.634732 -274.523491)
		(end 134.821676 -274.573746)
		(width 0.0889)
		(layer "In4.Cu")
		(net "M_J_CPU1_SB_DQ<2>")
	)
	(arc
		(start 139.521692 -274.573746)
		(mid 139.804648 -274.649923)
		(end 140.087604 -274.573746)
		(width 0.0889)
		(layer "In4.Cu")
		(net "M_J_CPU1_SB_DQ<2>")
	)
	(arc
		(start 139.147804 -274.573746)
		(mid 139.334748 -274.523491)
		(end 139.521692 -274.573746)
		(width 0.0889)
		(layer "In4.Cu")
		(net "M_J_CPU1_SB_DQ<2>")
	)
	(segment
		(start 131.347972 -292.450266)
		(end 131.814824 -292.716204)
		(width 0.10668)
		(layer "F.Cu")
		(net "M_J_CPU1_SB_DQ<29>")
	)
	(segment
		(start 143.847566 -293.038784)
		(end 143.886682 -293.061644)
		(width 0.0889)
		(layer "In4.Cu")
		(net "M_J_CPU1_SB_DQ<29>")
	)
	(segment
		(start 131.814824 -292.716204)
		(end 132.537454 -293.021004)
		(width 0.0889)
		(layer "In4.Cu")
		(net "M_J_CPU1_SB_DQ<29>")
	)
	(segment
		(start 145.56994 -296.18559)
		(end 145.56994 -302.915066)
		(width 0.14478)
		(layer "In4.Cu")
		(net "M_J_CPU1_SB_DQ<29>")
	)
	(segment
		(start 145.492978 -295.682162)
		(end 145.56994 -295.853104)
		(width 0.0889)
		(layer "In4.Cu")
		(net "M_J_CPU1_SB_DQ<29>")
	)
	(segment
		(start 145.179542 -295.399968)
		(end 145.386044 -295.55059)
		(width 0.0889)
		(layer "In4.Cu")
		(net "M_J_CPU1_SB_DQ<29>")
	)
	(segment
		(start 160.68675 -317.211456)
		(end 161.650172 -317.61049)
		(width 0.14478)
		(layer "In4.Cu")
		(net "M_J_CPU1_SB_DQ<29>")
	)
	(segment
		(start 190.73495 -317.61049)
		(end 191.160146 -317.185294)
		(width 0.14478)
		(layer "In4.Cu")
		(net "M_J_CPU1_SB_DQ<29>")
	)
	(segment
		(start 145.56994 -295.853104)
		(end 145.56994 -296.18559)
		(width 0.0889)
		(layer "In4.Cu")
		(net "M_J_CPU1_SB_DQ<29>")
	)
	(segment
		(start 138.20775 -293.038784)
		(end 138.216132 -293.04361)
		(width 0.0889)
		(layer "In4.Cu")
		(net "M_J_CPU1_SB_DQ<29>")
	)
	(segment
		(start 151.70277 -308.227476)
		(end 160.68675 -317.211456)
		(width 0.14478)
		(layer "In4.Cu")
		(net "M_J_CPU1_SB_DQ<29>")
	)
	(segment
		(start 133.507734 -293.038784)
		(end 133.516116 -293.04361)
		(width 0.0889)
		(layer "In4.Cu")
		(net "M_J_CPU1_SB_DQ<29>")
	)
	(segment
		(start 141.967712 -293.038784)
		(end 141.976094 -293.04361)
		(width 0.0889)
		(layer "In4.Cu")
		(net "M_J_CPU1_SB_DQ<29>")
	)
	(segment
		(start 144.756886 -294.641016)
		(end 144.787366 -294.658796)
		(width 0.0889)
		(layer "In4.Cu")
		(net "M_J_CPU1_SB_DQ<29>")
	)
	(segment
		(start 161.650172 -317.61049)
		(end 190.73495 -317.61049)
		(width 0.14478)
		(layer "In4.Cu")
		(net "M_J_CPU1_SB_DQ<29>")
	)
	(segment
		(start 144.286986 -293.83101)
		(end 144.317466 -293.84879)
		(width 0.0889)
		(layer "In4.Cu")
		(net "M_J_CPU1_SB_DQ<29>")
	)
	(segment
		(start 132.537454 -293.021004)
		(end 132.56768 -293.038784)
		(width 0.0889)
		(layer "In4.Cu")
		(net "M_J_CPU1_SB_DQ<29>")
	)
	(segment
		(start 136.693402 -293.04361)
		(end 136.701784 -293.038784)
		(width 0.0889)
		(layer "In4.Cu")
		(net "M_J_CPU1_SB_DQ<29>")
	)
	(segment
		(start 150.88235 -308.227476)
		(end 151.70277 -308.227476)
		(width 0.14478)
		(layer "In4.Cu")
		(net "M_J_CPU1_SB_DQ<29>")
	)
	(segment
		(start 141.393418 -293.04361)
		(end 141.4018 -293.038784)
		(width 0.0889)
		(layer "In4.Cu")
		(net "M_J_CPU1_SB_DQ<29>")
	)
	(segment
		(start 144.787366 -294.658796)
		(end 144.826482 -294.681656)
		(width 0.0889)
		(layer "In4.Cu")
		(net "M_J_CPU1_SB_DQ<29>")
	)
	(segment
		(start 144.317466 -293.84879)
		(end 144.356582 -293.87165)
		(width 0.0889)
		(layer "In4.Cu")
		(net "M_J_CPU1_SB_DQ<29>")
	)
	(segment
		(start 135.753348 -293.04361)
		(end 135.76173 -293.038784)
		(width 0.0889)
		(layer "In4.Cu")
		(net "M_J_CPU1_SB_DQ<29>")
	)
	(segment
		(start 140.453364 -293.04361)
		(end 140.461746 -293.038784)
		(width 0.0889)
		(layer "In4.Cu")
		(net "M_J_CPU1_SB_DQ<29>")
	)
	(segment
		(start 145.56994 -302.915066)
		(end 150.88235 -308.227476)
		(width 0.14478)
		(layer "In4.Cu")
		(net "M_J_CPU1_SB_DQ<29>")
	)
	(segment
		(start 137.267696 -293.038784)
		(end 137.276078 -293.04361)
		(width 0.0889)
		(layer "In4.Cu")
		(net "M_J_CPU1_SB_DQ<29>")
	)
	(segment
		(start 132.93344 -293.04361)
		(end 132.941822 -293.038784)
		(width 0.0889)
		(layer "In4.Cu")
		(net "M_J_CPU1_SB_DQ<29>")
	)
	(arc
		(start 142.341854 -293.038784)
		(mid 142.62481 -292.962607)
		(end 142.907766 -293.038784)
		(width 0.0889)
		(layer "In4.Cu")
		(net "M_J_CPU1_SB_DQ<29>")
	)
	(arc
		(start 139.521692 -293.038784)
		(mid 139.804648 -292.962607)
		(end 140.087604 -293.038784)
		(width 0.0889)
		(layer "In4.Cu")
		(net "M_J_CPU1_SB_DQ<29>")
	)
	(arc
		(start 141.976094 -293.04361)
		(mid 142.159602 -293.089104)
		(end 142.341854 -293.038784)
		(width 0.0889)
		(layer "In4.Cu")
		(net "M_J_CPU1_SB_DQ<29>")
	)
	(arc
		(start 135.387588 -293.038784)
		(mid 135.569839 -293.089134)
		(end 135.753348 -293.04361)
		(width 0.0889)
		(layer "In4.Cu")
		(net "M_J_CPU1_SB_DQ<29>")
	)
	(arc
		(start 133.881876 -293.038784)
		(mid 134.164832 -292.962607)
		(end 134.447788 -293.038784)
		(width 0.0889)
		(layer "In4.Cu")
		(net "M_J_CPU1_SB_DQ<29>")
	)
	(arc
		(start 139.147804 -293.038784)
		(mid 139.334748 -293.089039)
		(end 139.521692 -293.038784)
		(width 0.0889)
		(layer "In4.Cu")
		(net "M_J_CPU1_SB_DQ<29>")
	)
	(arc
		(start 132.56768 -293.038784)
		(mid 132.749931 -293.089134)
		(end 132.93344 -293.04361)
		(width 0.0889)
		(layer "In4.Cu")
		(net "M_J_CPU1_SB_DQ<29>")
	)
	(arc
		(start 144.130014 -293.52621)
		(mid 144.171563 -293.697632)
		(end 144.286986 -293.83101)
		(width 0.0889)
		(layer "In4.Cu")
		(net "M_J_CPU1_SB_DQ<29>")
	)
	(arc
		(start 143.281654 -293.038784)
		(mid 143.56461 -292.962607)
		(end 143.847566 -293.038784)
		(width 0.0889)
		(layer "In4.Cu")
		(net "M_J_CPU1_SB_DQ<29>")
	)
	(arc
		(start 143.886682 -293.061644)
		(mid 144.065495 -293.263994)
		(end 144.130014 -293.52621)
		(width 0.0889)
		(layer "In4.Cu")
		(net "M_J_CPU1_SB_DQ<29>")
	)
	(arc
		(start 145.12036 -295.333674)
		(mid 145.146494 -295.369906)
		(end 145.179542 -295.399968)
		(width 0.0889)
		(layer "In4.Cu")
		(net "M_J_CPU1_SB_DQ<29>")
	)
	(arc
		(start 132.941822 -293.038784)
		(mid 133.224778 -292.962607)
		(end 133.507734 -293.038784)
		(width 0.0889)
		(layer "In4.Cu")
		(net "M_J_CPU1_SB_DQ<29>")
	)
	(arc
		(start 136.327642 -293.038784)
		(mid 136.509893 -293.089134)
		(end 136.693402 -293.04361)
		(width 0.0889)
		(layer "In4.Cu")
		(net "M_J_CPU1_SB_DQ<29>")
	)
	(arc
		(start 137.276078 -293.04361)
		(mid 137.459586 -293.089104)
		(end 137.641838 -293.038784)
		(width 0.0889)
		(layer "In4.Cu")
		(net "M_J_CPU1_SB_DQ<29>")
	)
	(arc
		(start 141.027658 -293.038784)
		(mid 141.209909 -293.089134)
		(end 141.393418 -293.04361)
		(width 0.0889)
		(layer "In4.Cu")
		(net "M_J_CPU1_SB_DQ<29>")
	)
	(arc
		(start 136.701784 -293.038784)
		(mid 136.98474 -292.962607)
		(end 137.267696 -293.038784)
		(width 0.0889)
		(layer "In4.Cu")
		(net "M_J_CPU1_SB_DQ<29>")
	)
	(arc
		(start 137.641838 -293.038784)
		(mid 137.924794 -292.962607)
		(end 138.20775 -293.038784)
		(width 0.0889)
		(layer "In4.Cu")
		(net "M_J_CPU1_SB_DQ<29>")
	)
	(arc
		(start 140.461746 -293.038784)
		(mid 140.744702 -292.962607)
		(end 141.027658 -293.038784)
		(width 0.0889)
		(layer "In4.Cu")
		(net "M_J_CPU1_SB_DQ<29>")
	)
	(arc
		(start 133.516116 -293.04361)
		(mid 133.699624 -293.089104)
		(end 133.881876 -293.038784)
		(width 0.0889)
		(layer "In4.Cu")
		(net "M_J_CPU1_SB_DQ<29>")
	)
	(arc
		(start 145.069814 -295.146222)
		(mid 145.082732 -295.243281)
		(end 145.12036 -295.333674)
		(width 0.0889)
		(layer "In4.Cu")
		(net "M_J_CPU1_SB_DQ<29>")
	)
	(arc
		(start 134.821676 -293.038784)
		(mid 135.104632 -292.962607)
		(end 135.387588 -293.038784)
		(width 0.0889)
		(layer "In4.Cu")
		(net "M_J_CPU1_SB_DQ<29>")
	)
	(arc
		(start 138.581892 -293.038784)
		(mid 138.864848 -292.962607)
		(end 139.147804 -293.038784)
		(width 0.0889)
		(layer "In4.Cu")
		(net "M_J_CPU1_SB_DQ<29>")
	)
	(arc
		(start 134.447788 -293.038784)
		(mid 134.634732 -293.089039)
		(end 134.821676 -293.038784)
		(width 0.0889)
		(layer "In4.Cu")
		(net "M_J_CPU1_SB_DQ<29>")
	)
	(arc
		(start 144.599914 -294.336216)
		(mid 144.641463 -294.507638)
		(end 144.756886 -294.641016)
		(width 0.0889)
		(layer "In4.Cu")
		(net "M_J_CPU1_SB_DQ<29>")
	)
	(arc
		(start 138.216132 -293.04361)
		(mid 138.39964 -293.089104)
		(end 138.581892 -293.038784)
		(width 0.0889)
		(layer "In4.Cu")
		(net "M_J_CPU1_SB_DQ<29>")
	)
	(arc
		(start 145.386044 -295.55059)
		(mid 145.448062 -295.609421)
		(end 145.492978 -295.682162)
		(width 0.0889)
		(layer "In4.Cu")
		(net "M_J_CPU1_SB_DQ<29>")
	)
	(arc
		(start 142.907766 -293.038784)
		(mid 143.09471 -293.089039)
		(end 143.281654 -293.038784)
		(width 0.0889)
		(layer "In4.Cu")
		(net "M_J_CPU1_SB_DQ<29>")
	)
	(arc
		(start 135.76173 -293.038784)
		(mid 136.044686 -292.962607)
		(end 136.327642 -293.038784)
		(width 0.0889)
		(layer "In4.Cu")
		(net "M_J_CPU1_SB_DQ<29>")
	)
	(arc
		(start 140.087604 -293.038784)
		(mid 140.269855 -293.089134)
		(end 140.453364 -293.04361)
		(width 0.0889)
		(layer "In4.Cu")
		(net "M_J_CPU1_SB_DQ<29>")
	)
	(arc
		(start 141.4018 -293.038784)
		(mid 141.684756 -292.962607)
		(end 141.967712 -293.038784)
		(width 0.0889)
		(layer "In4.Cu")
		(net "M_J_CPU1_SB_DQ<29>")
	)
	(arc
		(start 144.356582 -293.87165)
		(mid 144.535395 -294.074)
		(end 144.599914 -294.336216)
		(width 0.0889)
		(layer "In4.Cu")
		(net "M_J_CPU1_SB_DQ<29>")
	)
	(arc
		(start 144.826482 -294.681656)
		(mid 145.005295 -294.884006)
		(end 145.069814 -295.146222)
		(width 0.0889)
		(layer "In4.Cu")
		(net "M_J_CPU1_SB_DQ<29>")
	)
	(segment
		(start 132.757926 -291.64026)
		(end 133.224778 -291.906198)
		(width 0.10668)
		(layer "F.Cu")
		(net "M_J_CPU1_SB_DQ<28>")
	)
	(segment
		(start 143.377666 -292.228778)
		(end 143.386048 -292.233604)
		(width 0.0889)
		(layer "In4.Cu")
		(net "M_J_CPU1_SB_DQ<28>")
	)
	(segment
		(start 188.327284 -316.588902)
		(end 188.488828 -316.750446)
		(width 0.14478)
		(layer "In4.Cu")
		(net "M_J_CPU1_SB_DQ<28>")
	)
	(segment
		(start 189.981586 -316.081664)
		(end 190.14313 -315.92012)
		(width 0.14478)
		(layer "In4.Cu")
		(net "M_J_CPU1_SB_DQ<28>")
	)
	(segment
		(start 189.268608 -315.92012)
		(end 189.430152 -316.081664)
		(width 0.14478)
		(layer "In4.Cu")
		(net "M_J_CPU1_SB_DQ<28>")
	)
	(segment
		(start 144.78762 -293.038784)
		(end 144.826736 -293.061644)
		(width 0.0889)
		(layer "In4.Cu")
		(net "M_J_CPU1_SB_DQ<28>")
	)
	(segment
		(start 146.47926 -295.615614)
		(end 146.47926 -295.995598)
		(width 0.0889)
		(layer "In4.Cu")
		(net "M_J_CPU1_SB_DQ<28>")
	)
	(segment
		(start 135.857742 -292.228778)
		(end 135.866124 -292.233604)
		(width 0.0889)
		(layer "In4.Cu")
		(net "M_J_CPU1_SB_DQ<28>")
	)
	(segment
		(start 138.103356 -292.233604)
		(end 138.111738 -292.228778)
		(width 0.0889)
		(layer "In4.Cu")
		(net "M_J_CPU1_SB_DQ<28>")
	)
	(segment
		(start 190.14313 -315.92012)
		(end 190.725298 -315.92012)
		(width 0.14478)
		(layer "In4.Cu")
		(net "M_J_CPU1_SB_DQ<28>")
	)
	(segment
		(start 140.557758 -292.228778)
		(end 140.56614 -292.233604)
		(width 0.0889)
		(layer "In4.Cu")
		(net "M_J_CPU1_SB_DQ<28>")
	)
	(segment
		(start 146.009868 -295.146222)
		(end 146.47926 -295.615614)
		(width 0.0889)
		(layer "In4.Cu")
		(net "M_J_CPU1_SB_DQ<28>")
	)
	(segment
		(start 189.430152 -316.588902)
		(end 189.591696 -316.750446)
		(width 0.14478)
		(layer "In4.Cu")
		(net "M_J_CPU1_SB_DQ<28>")
	)
	(segment
		(start 160.667954 -315.92012)
		(end 188.16574 -315.92012)
		(width 0.14478)
		(layer "In4.Cu")
		(net "M_J_CPU1_SB_DQ<28>")
	)
	(segment
		(start 189.981586 -316.588902)
		(end 189.981586 -316.081664)
		(width 0.14478)
		(layer "In4.Cu")
		(net "M_J_CPU1_SB_DQ<28>")
	)
	(segment
		(start 139.617704 -292.228778)
		(end 139.626086 -292.233604)
		(width 0.0889)
		(layer "In4.Cu")
		(net "M_J_CPU1_SB_DQ<28>")
	)
	(segment
		(start 190.725298 -315.92012)
		(end 191.160146 -315.485272)
		(width 0.14478)
		(layer "In4.Cu")
		(net "M_J_CPU1_SB_DQ<28>")
	)
	(segment
		(start 133.070854 -292.171628)
		(end 133.093206 -292.25494)
		(width 0.0889)
		(layer "In4.Cu")
		(net "M_J_CPU1_SB_DQ<28>")
	)
	(segment
		(start 133.224778 -291.906198)
		(end 133.070854 -292.171628)
		(width 0.0889)
		(layer "In4.Cu")
		(net "M_J_CPU1_SB_DQ<28>")
	)
	(segment
		(start 145.727674 -294.658796)
		(end 145.763996 -294.679878)
		(width 0.0889)
		(layer "In4.Cu")
		(net "M_J_CPU1_SB_DQ<28>")
	)
	(segment
		(start 145.25752 -293.84879)
		(end 145.296636 -293.87165)
		(width 0.0889)
		(layer "In4.Cu")
		(net "M_J_CPU1_SB_DQ<28>")
	)
	(segment
		(start 188.878718 -316.588902)
		(end 188.878718 -316.081664)
		(width 0.14478)
		(layer "In4.Cu")
		(net "M_J_CPU1_SB_DQ<28>")
	)
	(segment
		(start 188.16574 -315.92012)
		(end 188.327284 -316.081664)
		(width 0.14478)
		(layer "In4.Cu")
		(net "M_J_CPU1_SB_DQ<28>")
	)
	(segment
		(start 134.917688 -292.228778)
		(end 134.92607 -292.233604)
		(width 0.0889)
		(layer "In4.Cu")
		(net "M_J_CPU1_SB_DQ<28>")
	)
	(segment
		(start 189.040262 -315.92012)
		(end 189.268608 -315.92012)
		(width 0.14478)
		(layer "In4.Cu")
		(net "M_J_CPU1_SB_DQ<28>")
	)
	(segment
		(start 188.327284 -316.081664)
		(end 188.327284 -316.588902)
		(width 0.14478)
		(layer "In4.Cu")
		(net "M_J_CPU1_SB_DQ<28>")
	)
	(segment
		(start 146.47926 -301.731426)
		(end 160.667954 -315.92012)
		(width 0.14478)
		(layer "In4.Cu")
		(net "M_J_CPU1_SB_DQ<28>")
	)
	(segment
		(start 144.75714 -293.021004)
		(end 144.78762 -293.038784)
		(width 0.0889)
		(layer "In4.Cu")
		(net "M_J_CPU1_SB_DQ<28>")
	)
	(segment
		(start 188.488828 -316.750446)
		(end 188.717174 -316.750446)
		(width 0.14478)
		(layer "In4.Cu")
		(net "M_J_CPU1_SB_DQ<28>")
	)
	(segment
		(start 134.343394 -292.233604)
		(end 134.351776 -292.228778)
		(width 0.0889)
		(layer "In4.Cu")
		(net "M_J_CPU1_SB_DQ<28>")
	)
	(segment
		(start 139.04341 -292.233604)
		(end 139.051792 -292.228778)
		(width 0.0889)
		(layer "In4.Cu")
		(net "M_J_CPU1_SB_DQ<28>")
	)
	(segment
		(start 188.717174 -316.750446)
		(end 188.878718 -316.588902)
		(width 0.14478)
		(layer "In4.Cu")
		(net "M_J_CPU1_SB_DQ<28>")
	)
	(segment
		(start 145.695924 -294.640508)
		(end 145.727674 -294.658796)
		(width 0.0889)
		(layer "In4.Cu")
		(net "M_J_CPU1_SB_DQ<28>")
	)
	(segment
		(start 146.47926 -295.995598)
		(end 146.47926 -301.731426)
		(width 0.14478)
		(layer "In4.Cu")
		(net "M_J_CPU1_SB_DQ<28>")
	)
	(segment
		(start 145.22704 -293.83101)
		(end 145.25752 -293.84879)
		(width 0.0889)
		(layer "In4.Cu")
		(net "M_J_CPU1_SB_DQ<28>")
	)
	(segment
		(start 142.803372 -292.233604)
		(end 142.811754 -292.228778)
		(width 0.0889)
		(layer "In4.Cu")
		(net "M_J_CPU1_SB_DQ<28>")
	)
	(segment
		(start 188.878718 -316.081664)
		(end 189.040262 -315.92012)
		(width 0.14478)
		(layer "In4.Cu")
		(net "M_J_CPU1_SB_DQ<28>")
	)
	(segment
		(start 144.31772 -292.228778)
		(end 144.356836 -292.251638)
		(width 0.0889)
		(layer "In4.Cu")
		(net "M_J_CPU1_SB_DQ<28>")
	)
	(segment
		(start 189.820042 -316.750446)
		(end 189.981586 -316.588902)
		(width 0.14478)
		(layer "In4.Cu")
		(net "M_J_CPU1_SB_DQ<28>")
	)
	(segment
		(start 189.591696 -316.750446)
		(end 189.820042 -316.750446)
		(width 0.14478)
		(layer "In4.Cu")
		(net "M_J_CPU1_SB_DQ<28>")
	)
	(segment
		(start 189.430152 -316.081664)
		(end 189.430152 -316.588902)
		(width 0.14478)
		(layer "In4.Cu")
		(net "M_J_CPU1_SB_DQ<28>")
	)
	(arc
		(start 141.8717 -292.228778)
		(mid 142.154656 -292.152601)
		(end 142.437612 -292.228778)
		(width 0.0889)
		(layer "In4.Cu")
		(net "M_J_CPU1_SB_DQ<28>")
	)
	(arc
		(start 143.751808 -292.228778)
		(mid 144.034764 -292.152601)
		(end 144.31772 -292.228778)
		(width 0.0889)
		(layer "In4.Cu")
		(net "M_J_CPU1_SB_DQ<28>")
	)
	(arc
		(start 139.626086 -292.233604)
		(mid 139.809594 -292.279098)
		(end 139.991846 -292.228778)
		(width 0.0889)
		(layer "In4.Cu")
		(net "M_J_CPU1_SB_DQ<28>")
	)
	(arc
		(start 137.171684 -292.228778)
		(mid 137.45464 -292.152601)
		(end 137.737596 -292.228778)
		(width 0.0889)
		(layer "In4.Cu")
		(net "M_J_CPU1_SB_DQ<28>")
	)
	(arc
		(start 135.29183 -292.228778)
		(mid 135.574786 -292.152601)
		(end 135.857742 -292.228778)
		(width 0.0889)
		(layer "In4.Cu")
		(net "M_J_CPU1_SB_DQ<28>")
	)
	(arc
		(start 138.67765 -292.228778)
		(mid 138.859901 -292.279128)
		(end 139.04341 -292.233604)
		(width 0.0889)
		(layer "In4.Cu")
		(net "M_J_CPU1_SB_DQ<28>")
	)
	(arc
		(start 140.56614 -292.233604)
		(mid 140.749648 -292.279098)
		(end 140.9319 -292.228778)
		(width 0.0889)
		(layer "In4.Cu")
		(net "M_J_CPU1_SB_DQ<28>")
	)
	(arc
		(start 135.866124 -292.233604)
		(mid 136.049632 -292.279098)
		(end 136.231884 -292.228778)
		(width 0.0889)
		(layer "In4.Cu")
		(net "M_J_CPU1_SB_DQ<28>")
	)
	(arc
		(start 140.9319 -292.228778)
		(mid 141.214856 -292.152601)
		(end 141.497812 -292.228778)
		(width 0.0889)
		(layer "In4.Cu")
		(net "M_J_CPU1_SB_DQ<28>")
	)
	(arc
		(start 143.386048 -292.233604)
		(mid 143.569556 -292.279098)
		(end 143.751808 -292.228778)
		(width 0.0889)
		(layer "In4.Cu")
		(net "M_J_CPU1_SB_DQ<28>")
	)
	(arc
		(start 139.051792 -292.228778)
		(mid 139.334748 -292.152601)
		(end 139.617704 -292.228778)
		(width 0.0889)
		(layer "In4.Cu")
		(net "M_J_CPU1_SB_DQ<28>")
	)
	(arc
		(start 145.763996 -294.679878)
		(mid 145.944648 -294.882623)
		(end 146.009868 -295.146222)
		(width 0.0889)
		(layer "In4.Cu")
		(net "M_J_CPU1_SB_DQ<28>")
	)
	(arc
		(start 136.797796 -292.228778)
		(mid 136.98474 -292.279033)
		(end 137.171684 -292.228778)
		(width 0.0889)
		(layer "In4.Cu")
		(net "M_J_CPU1_SB_DQ<28>")
	)
	(arc
		(start 144.600168 -292.716204)
		(mid 144.641717 -292.887626)
		(end 144.75714 -293.021004)
		(width 0.0889)
		(layer "In4.Cu")
		(net "M_J_CPU1_SB_DQ<28>")
	)
	(arc
		(start 133.411722 -292.228778)
		(mid 133.694678 -292.152601)
		(end 133.977634 -292.228778)
		(width 0.0889)
		(layer "In4.Cu")
		(net "M_J_CPU1_SB_DQ<28>")
	)
	(arc
		(start 145.539968 -294.336216)
		(mid 145.581223 -294.507187)
		(end 145.695924 -294.640508)
		(width 0.0889)
		(layer "In4.Cu")
		(net "M_J_CPU1_SB_DQ<28>")
	)
	(arc
		(start 138.111738 -292.228778)
		(mid 138.394694 -292.152601)
		(end 138.67765 -292.228778)
		(width 0.0889)
		(layer "In4.Cu")
		(net "M_J_CPU1_SB_DQ<28>")
	)
	(arc
		(start 145.296636 -293.87165)
		(mid 145.475449 -294.074)
		(end 145.539968 -294.336216)
		(width 0.0889)
		(layer "In4.Cu")
		(net "M_J_CPU1_SB_DQ<28>")
	)
	(arc
		(start 142.811754 -292.228778)
		(mid 143.09471 -292.152601)
		(end 143.377666 -292.228778)
		(width 0.0889)
		(layer "In4.Cu")
		(net "M_J_CPU1_SB_DQ<28>")
	)
	(arc
		(start 141.497812 -292.228778)
		(mid 141.684756 -292.279033)
		(end 141.8717 -292.228778)
		(width 0.0889)
		(layer "In4.Cu")
		(net "M_J_CPU1_SB_DQ<28>")
	)
	(arc
		(start 133.977634 -292.228778)
		(mid 134.159885 -292.279128)
		(end 134.343394 -292.233604)
		(width 0.0889)
		(layer "In4.Cu")
		(net "M_J_CPU1_SB_DQ<28>")
	)
	(arc
		(start 144.826736 -293.061644)
		(mid 145.005549 -293.263994)
		(end 145.070068 -293.52621)
		(width 0.0889)
		(layer "In4.Cu")
		(net "M_J_CPU1_SB_DQ<28>")
	)
	(arc
		(start 133.093206 -292.25494)
		(mid 133.255395 -292.277675)
		(end 133.411722 -292.228778)
		(width 0.0889)
		(layer "In4.Cu")
		(net "M_J_CPU1_SB_DQ<28>")
	)
	(arc
		(start 142.437612 -292.228778)
		(mid 142.619863 -292.279128)
		(end 142.803372 -292.233604)
		(width 0.0889)
		(layer "In4.Cu")
		(net "M_J_CPU1_SB_DQ<28>")
	)
	(arc
		(start 145.070068 -293.52621)
		(mid 145.111617 -293.697632)
		(end 145.22704 -293.83101)
		(width 0.0889)
		(layer "In4.Cu")
		(net "M_J_CPU1_SB_DQ<28>")
	)
	(arc
		(start 137.737596 -292.228778)
		(mid 137.919847 -292.279128)
		(end 138.103356 -292.233604)
		(width 0.0889)
		(layer "In4.Cu")
		(net "M_J_CPU1_SB_DQ<28>")
	)
	(arc
		(start 134.351776 -292.228778)
		(mid 134.634732 -292.152601)
		(end 134.917688 -292.228778)
		(width 0.0889)
		(layer "In4.Cu")
		(net "M_J_CPU1_SB_DQ<28>")
	)
	(arc
		(start 144.356836 -292.251638)
		(mid 144.535649 -292.453988)
		(end 144.600168 -292.716204)
		(width 0.0889)
		(layer "In4.Cu")
		(net "M_J_CPU1_SB_DQ<28>")
	)
	(arc
		(start 134.92607 -292.233604)
		(mid 135.109578 -292.279098)
		(end 135.29183 -292.228778)
		(width 0.0889)
		(layer "In4.Cu")
		(net "M_J_CPU1_SB_DQ<28>")
	)
	(arc
		(start 136.231884 -292.228778)
		(mid 136.51484 -292.152601)
		(end 136.797796 -292.228778)
		(width 0.0889)
		(layer "In4.Cu")
		(net "M_J_CPU1_SB_DQ<28>")
	)
	(arc
		(start 139.991846 -292.228778)
		(mid 140.274802 -292.152601)
		(end 140.557758 -292.228778)
		(width 0.0889)
		(layer "In4.Cu")
		(net "M_J_CPU1_SB_DQ<28>")
	)
	(segment
		(start 130.877818 -290.020248)
		(end 131.34467 -290.286186)
		(width 0.10668)
		(layer "F.Cu")
		(net "M_J_CPU1_SB_DQ<27>")
	)
	(segment
		(start 161.707576 -312.206386)
		(end 162.01136 -312.51017)
		(width 0.14478)
		(layer "In4.Cu")
		(net "M_J_CPU1_SB_DQ<27>")
	)
	(segment
		(start 161.459926 -312.206386)
		(end 161.707576 -312.206386)
		(width 0.14478)
		(layer "In4.Cu")
		(net "M_J_CPU1_SB_DQ<27>")
	)
	(segment
		(start 163.361878 -312.51017)
		(end 163.665662 -312.206386)
		(width 0.14478)
		(layer "In4.Cu")
		(net "M_J_CPU1_SB_DQ<27>")
	)
	(segment
		(start 131.34467 -290.286186)
		(end 131.498848 -290.020756)
		(width 0.0889)
		(layer "In4.Cu")
		(net "M_J_CPU1_SB_DQ<27>")
	)
	(segment
		(start 177.91557 -311.650634)
		(end 178.765454 -312.500518)
		(width 0.14478)
		(layer "In4.Cu")
		(net "M_J_CPU1_SB_DQ<27>")
	)
	(segment
		(start 185.253122 -311.259728)
		(end 185.414666 -311.421272)
		(width 0.14478)
		(layer "In4.Cu")
		(net "M_J_CPU1_SB_DQ<27>")
	)
	(segment
		(start 160.495234 -312.51017)
		(end 161.156142 -312.51017)
		(width 0.14478)
		(layer "In4.Cu")
		(net "M_J_CPU1_SB_DQ<27>")
	)
	(segment
		(start 167.819832 -311.368186)
		(end 168.079166 -311.368186)
		(width 0.14478)
		(layer "In4.Cu")
		(net "M_J_CPU1_SB_DQ<27>")
	)
	(segment
		(start 185.804556 -312.092086)
		(end 185.9661 -311.930542)
		(width 0.14478)
		(layer "In4.Cu")
		(net "M_J_CPU1_SB_DQ<27>")
	)
	(segment
		(start 132.09778 -289.963606)
		(end 132.106162 -289.95878)
		(width 0.0889)
		(layer "In4.Cu")
		(net "M_J_CPU1_SB_DQ<27>")
	)
	(segment
		(start 138.103356 -289.95878)
		(end 138.111738 -289.963606)
		(width 0.0889)
		(layer "In4.Cu")
		(net "M_J_CPU1_SB_DQ<27>")
	)
	(segment
		(start 168.371266 -311.660286)
		(end 168.6306 -311.660286)
		(width 0.14478)
		(layer "In4.Cu")
		(net "M_J_CPU1_SB_DQ<27>")
	)
	(segment
		(start 135.857742 -289.963606)
		(end 135.866124 -289.95878)
		(width 0.0889)
		(layer "In4.Cu")
		(net "M_J_CPU1_SB_DQ<27>")
	)
	(segment
		(start 164.217096 -312.51017)
		(end 164.464746 -312.51017)
		(width 0.14478)
		(layer "In4.Cu")
		(net "M_J_CPU1_SB_DQ<27>")
	)
	(segment
		(start 181.096412 -312.500518)
		(end 181.946296 -311.650634)
		(width 0.14478)
		(layer "In4.Cu")
		(net "M_J_CPU1_SB_DQ<27>")
	)
	(segment
		(start 165.938454 -312.51017)
		(end 166.788338 -311.660286)
		(width 0.14478)
		(layer "In4.Cu")
		(net "M_J_CPU1_SB_DQ<27>")
	)
	(segment
		(start 145.932906 -291.042852)
		(end 146.503898 -292.421056)
		(width 0.0889)
		(layer "In4.Cu")
		(net "M_J_CPU1_SB_DQ<27>")
	)
	(segment
		(start 162.810444 -312.206386)
		(end 163.114228 -312.51017)
		(width 0.14478)
		(layer "In4.Cu")
		(net "M_J_CPU1_SB_DQ<27>")
	)
	(segment
		(start 134.917688 -289.963606)
		(end 134.92607 -289.95878)
		(width 0.0889)
		(layer "In4.Cu")
		(net "M_J_CPU1_SB_DQ<27>")
	)
	(segment
		(start 163.665662 -312.206386)
		(end 163.913312 -312.206386)
		(width 0.14478)
		(layer "In4.Cu")
		(net "M_J_CPU1_SB_DQ<27>")
	)
	(segment
		(start 185.57621 -312.092086)
		(end 185.804556 -312.092086)
		(width 0.14478)
		(layer "In4.Cu")
		(net "M_J_CPU1_SB_DQ<27>")
	)
	(segment
		(start 164.464746 -312.51017)
		(end 164.76853 -312.206386)
		(width 0.14478)
		(layer "In4.Cu")
		(net "M_J_CPU1_SB_DQ<27>")
	)
	(segment
		(start 165.01618 -312.206386)
		(end 165.319964 -312.51017)
		(width 0.14478)
		(layer "In4.Cu")
		(net "M_J_CPU1_SB_DQ<27>")
	)
	(segment
		(start 144.88668 -289.884358)
		(end 145.6055 -289.884358)
		(width 0.0889)
		(layer "In4.Cu")
		(net "M_J_CPU1_SB_DQ<27>")
	)
	(segment
		(start 140.557758 -289.963606)
		(end 140.56614 -289.95878)
		(width 0.0889)
		(layer "In4.Cu")
		(net "M_J_CPU1_SB_DQ<27>")
	)
	(segment
		(start 162.562794 -312.206386)
		(end 162.810444 -312.206386)
		(width 0.14478)
		(layer "In4.Cu")
		(net "M_J_CPU1_SB_DQ<27>")
	)
	(segment
		(start 139.04341 -289.95878)
		(end 139.051792 -289.963606)
		(width 0.0889)
		(layer "In4.Cu")
		(net "M_J_CPU1_SB_DQ<27>")
	)
	(segment
		(start 162.25901 -312.51017)
		(end 162.562794 -312.206386)
		(width 0.14478)
		(layer "In4.Cu")
		(net "M_J_CPU1_SB_DQ<27>")
	)
	(segment
		(start 145.6055 -289.884358)
		(end 145.932906 -290.211764)
		(width 0.0889)
		(layer "In4.Cu")
		(net "M_J_CPU1_SB_DQ<27>")
	)
	(segment
		(start 148.82749 -294.438832)
		(end 148.82749 -300.842426)
		(width 0.14478)
		(layer "In4.Cu")
		(net "M_J_CPU1_SB_DQ<27>")
	)
	(segment
		(start 167.527732 -311.660286)
		(end 167.819832 -311.368186)
		(width 0.14478)
		(layer "In4.Cu")
		(net "M_J_CPU1_SB_DQ<27>")
	)
	(segment
		(start 186.127644 -311.259728)
		(end 186.490356 -311.259728)
		(width 0.14478)
		(layer "In4.Cu")
		(net "M_J_CPU1_SB_DQ<27>")
	)
	(segment
		(start 162.01136 -312.51017)
		(end 162.25901 -312.51017)
		(width 0.14478)
		(layer "In4.Cu")
		(net "M_J_CPU1_SB_DQ<27>")
	)
	(segment
		(start 186.75223 -311.521602)
		(end 186.75223 -311.940448)
		(width 0.14478)
		(layer "In4.Cu")
		(net "M_J_CPU1_SB_DQ<27>")
	)
	(segment
		(start 169.182034 -311.368186)
		(end 169.474134 -311.660286)
		(width 0.14478)
		(layer "In4.Cu")
		(net "M_J_CPU1_SB_DQ<27>")
	)
	(segment
		(start 186.490356 -311.259728)
		(end 186.75223 -311.521602)
		(width 0.14478)
		(layer "In4.Cu")
		(net "M_J_CPU1_SB_DQ<27>")
	)
	(segment
		(start 169.474134 -311.660286)
		(end 169.954448 -311.660286)
		(width 0.14478)
		(layer "In4.Cu")
		(net "M_J_CPU1_SB_DQ<27>")
	)
	(segment
		(start 164.76853 -312.206386)
		(end 165.01618 -312.206386)
		(width 0.14478)
		(layer "In4.Cu")
		(net "M_J_CPU1_SB_DQ<27>")
	)
	(segment
		(start 146.931126 -292.848284)
		(end 147.236942 -292.848284)
		(width 0.0889)
		(layer "In4.Cu")
		(net "M_J_CPU1_SB_DQ<27>")
	)
	(segment
		(start 163.114228 -312.51017)
		(end 163.361878 -312.51017)
		(width 0.14478)
		(layer "In4.Cu")
		(net "M_J_CPU1_SB_DQ<27>")
	)
	(segment
		(start 173.49216 -312.500518)
		(end 174.342044 -311.650634)
		(width 0.14478)
		(layer "In4.Cu")
		(net "M_J_CPU1_SB_DQ<27>")
	)
	(segment
		(start 163.913312 -312.206386)
		(end 164.217096 -312.51017)
		(width 0.14478)
		(layer "In4.Cu")
		(net "M_J_CPU1_SB_DQ<27>")
	)
	(segment
		(start 146.503898 -292.421056)
		(end 146.931126 -292.848284)
		(width 0.0889)
		(layer "In4.Cu")
		(net "M_J_CPU1_SB_DQ<27>")
	)
	(segment
		(start 145.932906 -290.211764)
		(end 145.932906 -291.042852)
		(width 0.0889)
		(layer "In4.Cu")
		(net "M_J_CPU1_SB_DQ<27>")
	)
	(segment
		(start 181.946296 -311.650634)
		(end 184.26049 -311.650634)
		(width 0.14478)
		(layer "In4.Cu")
		(net "M_J_CPU1_SB_DQ<27>")
	)
	(segment
		(start 186.89701 -312.085228)
		(end 187.060078 -312.085228)
		(width 0.14478)
		(layer "In4.Cu")
		(net "M_J_CPU1_SB_DQ<27>")
	)
	(segment
		(start 168.079166 -311.368186)
		(end 168.371266 -311.660286)
		(width 0.14478)
		(layer "In4.Cu")
		(net "M_J_CPU1_SB_DQ<27>")
	)
	(segment
		(start 170.79468 -312.500518)
		(end 173.49216 -312.500518)
		(width 0.14478)
		(layer "In4.Cu")
		(net "M_J_CPU1_SB_DQ<27>")
	)
	(segment
		(start 144.034764 -290.039806)
		(end 144.731232 -290.039806)
		(width 0.0889)
		(layer "In4.Cu")
		(net "M_J_CPU1_SB_DQ<27>")
	)
	(segment
		(start 168.9227 -311.368186)
		(end 169.182034 -311.368186)
		(width 0.14478)
		(layer "In4.Cu")
		(net "M_J_CPU1_SB_DQ<27>")
	)
	(segment
		(start 134.343394 -289.95878)
		(end 134.351776 -289.963606)
		(width 0.0889)
		(layer "In4.Cu")
		(net "M_J_CPU1_SB_DQ<27>")
	)
	(segment
		(start 184.26049 -311.650634)
		(end 184.651396 -311.259728)
		(width 0.14478)
		(layer "In4.Cu")
		(net "M_J_CPU1_SB_DQ<27>")
	)
	(segment
		(start 168.6306 -311.660286)
		(end 168.9227 -311.368186)
		(width 0.14478)
		(layer "In4.Cu")
		(net "M_J_CPU1_SB_DQ<27>")
	)
	(segment
		(start 185.414666 -311.930542)
		(end 185.57621 -312.092086)
		(width 0.14478)
		(layer "In4.Cu")
		(net "M_J_CPU1_SB_DQ<27>")
	)
	(segment
		(start 143.377666 -289.963606)
		(end 143.386048 -289.95878)
		(width 0.0889)
		(layer "In4.Cu")
		(net "M_J_CPU1_SB_DQ<27>")
	)
	(segment
		(start 161.156142 -312.51017)
		(end 161.459926 -312.206386)
		(width 0.14478)
		(layer "In4.Cu")
		(net "M_J_CPU1_SB_DQ<27>")
	)
	(segment
		(start 174.342044 -311.650634)
		(end 177.91557 -311.650634)
		(width 0.14478)
		(layer "In4.Cu")
		(net "M_J_CPU1_SB_DQ<27>")
	)
	(segment
		(start 131.498848 -290.020756)
		(end 131.595114 -289.995356)
		(width 0.0889)
		(layer "In4.Cu")
		(net "M_J_CPU1_SB_DQ<27>")
	)
	(segment
		(start 184.651396 -311.259728)
		(end 185.253122 -311.259728)
		(width 0.14478)
		(layer "In4.Cu")
		(net "M_J_CPU1_SB_DQ<27>")
	)
	(segment
		(start 142.803372 -289.95878)
		(end 142.811754 -289.963606)
		(width 0.0889)
		(layer "In4.Cu")
		(net "M_J_CPU1_SB_DQ<27>")
	)
	(segment
		(start 166.788338 -311.660286)
		(end 167.527732 -311.660286)
		(width 0.14478)
		(layer "In4.Cu")
		(net "M_J_CPU1_SB_DQ<27>")
	)
	(segment
		(start 144.731232 -290.039806)
		(end 144.88668 -289.884358)
		(width 0.0889)
		(layer "In4.Cu")
		(net "M_J_CPU1_SB_DQ<27>")
	)
	(segment
		(start 185.9661 -311.421272)
		(end 186.127644 -311.259728)
		(width 0.14478)
		(layer "In4.Cu")
		(net "M_J_CPU1_SB_DQ<27>")
	)
	(segment
		(start 148.82749 -300.842426)
		(end 160.495234 -312.51017)
		(width 0.14478)
		(layer "In4.Cu")
		(net "M_J_CPU1_SB_DQ<27>")
	)
	(segment
		(start 178.765454 -312.500518)
		(end 181.096412 -312.500518)
		(width 0.14478)
		(layer "In4.Cu")
		(net "M_J_CPU1_SB_DQ<27>")
	)
	(segment
		(start 169.954448 -311.660286)
		(end 170.79468 -312.500518)
		(width 0.14478)
		(layer "In4.Cu")
		(net "M_J_CPU1_SB_DQ<27>")
	)
	(segment
		(start 139.617704 -289.963606)
		(end 139.626086 -289.95878)
		(width 0.0889)
		(layer "In4.Cu")
		(net "M_J_CPU1_SB_DQ<27>")
	)
	(segment
		(start 185.414666 -311.421272)
		(end 185.414666 -311.930542)
		(width 0.14478)
		(layer "In4.Cu")
		(net "M_J_CPU1_SB_DQ<27>")
	)
	(segment
		(start 185.9661 -311.930542)
		(end 185.9661 -311.421272)
		(width 0.14478)
		(layer "In4.Cu")
		(net "M_J_CPU1_SB_DQ<27>")
	)
	(segment
		(start 165.319964 -312.51017)
		(end 165.938454 -312.51017)
		(width 0.14478)
		(layer "In4.Cu")
		(net "M_J_CPU1_SB_DQ<27>")
	)
	(segment
		(start 147.236942 -292.848284)
		(end 148.82749 -294.438832)
		(width 0.14478)
		(layer "In4.Cu")
		(net "M_J_CPU1_SB_DQ<27>")
	)
	(segment
		(start 186.75223 -311.940448)
		(end 186.89701 -312.085228)
		(width 0.14478)
		(layer "In4.Cu")
		(net "M_J_CPU1_SB_DQ<27>")
	)
	(arc
		(start 139.626086 -289.95878)
		(mid 139.809594 -289.913286)
		(end 139.991846 -289.963606)
		(width 0.0889)
		(layer "In4.Cu")
		(net "M_J_CPU1_SB_DQ<27>")
	)
	(arc
		(start 136.797796 -289.963606)
		(mid 136.98474 -289.913351)
		(end 137.171684 -289.963606)
		(width 0.0889)
		(layer "In4.Cu")
		(net "M_J_CPU1_SB_DQ<27>")
	)
	(arc
		(start 140.9319 -289.963606)
		(mid 141.214856 -290.039783)
		(end 141.497812 -289.963606)
		(width 0.0889)
		(layer "In4.Cu")
		(net "M_J_CPU1_SB_DQ<27>")
	)
	(arc
		(start 132.471922 -289.963606)
		(mid 132.754878 -290.039783)
		(end 133.037834 -289.963606)
		(width 0.0889)
		(layer "In4.Cu")
		(net "M_J_CPU1_SB_DQ<27>")
	)
	(arc
		(start 140.56614 -289.95878)
		(mid 140.749648 -289.913286)
		(end 140.9319 -289.963606)
		(width 0.0889)
		(layer "In4.Cu")
		(net "M_J_CPU1_SB_DQ<27>")
	)
	(arc
		(start 135.866124 -289.95878)
		(mid 136.049632 -289.913286)
		(end 136.231884 -289.963606)
		(width 0.0889)
		(layer "In4.Cu")
		(net "M_J_CPU1_SB_DQ<27>")
	)
	(arc
		(start 138.111738 -289.963606)
		(mid 138.394694 -290.039783)
		(end 138.67765 -289.963606)
		(width 0.0889)
		(layer "In4.Cu")
		(net "M_J_CPU1_SB_DQ<27>")
	)
	(arc
		(start 141.497812 -289.963606)
		(mid 141.684756 -289.913351)
		(end 141.8717 -289.963606)
		(width 0.0889)
		(layer "In4.Cu")
		(net "M_J_CPU1_SB_DQ<27>")
	)
	(arc
		(start 142.811754 -289.963606)
		(mid 143.09471 -290.039783)
		(end 143.377666 -289.963606)
		(width 0.0889)
		(layer "In4.Cu")
		(net "M_J_CPU1_SB_DQ<27>")
	)
	(arc
		(start 142.437612 -289.963606)
		(mid 142.619863 -289.913256)
		(end 142.803372 -289.95878)
		(width 0.0889)
		(layer "In4.Cu")
		(net "M_J_CPU1_SB_DQ<27>")
	)
	(arc
		(start 136.231884 -289.963606)
		(mid 136.51484 -290.039783)
		(end 136.797796 -289.963606)
		(width 0.0889)
		(layer "In4.Cu")
		(net "M_J_CPU1_SB_DQ<27>")
	)
	(arc
		(start 141.8717 -289.963606)
		(mid 142.154656 -290.039783)
		(end 142.437612 -289.963606)
		(width 0.0889)
		(layer "In4.Cu")
		(net "M_J_CPU1_SB_DQ<27>")
	)
	(arc
		(start 134.351776 -289.963606)
		(mid 134.634732 -290.039783)
		(end 134.917688 -289.963606)
		(width 0.0889)
		(layer "In4.Cu")
		(net "M_J_CPU1_SB_DQ<27>")
	)
	(arc
		(start 138.67765 -289.963606)
		(mid 138.859901 -289.913256)
		(end 139.04341 -289.95878)
		(width 0.0889)
		(layer "In4.Cu")
		(net "M_J_CPU1_SB_DQ<27>")
	)
	(arc
		(start 139.051792 -289.963606)
		(mid 139.334748 -290.039783)
		(end 139.617704 -289.963606)
		(width 0.0889)
		(layer "In4.Cu")
		(net "M_J_CPU1_SB_DQ<27>")
	)
	(arc
		(start 143.751808 -289.963606)
		(mid 143.888244 -290.020431)
		(end 144.034764 -290.039806)
		(width 0.0889)
		(layer "In4.Cu")
		(net "M_J_CPU1_SB_DQ<27>")
	)
	(arc
		(start 143.386048 -289.95878)
		(mid 143.569556 -289.913286)
		(end 143.751808 -289.963606)
		(width 0.0889)
		(layer "In4.Cu")
		(net "M_J_CPU1_SB_DQ<27>")
	)
	(arc
		(start 137.171684 -289.963606)
		(mid 137.45464 -290.039783)
		(end 137.737596 -289.963606)
		(width 0.0889)
		(layer "In4.Cu")
		(net "M_J_CPU1_SB_DQ<27>")
	)
	(arc
		(start 132.106162 -289.95878)
		(mid 132.28967 -289.913286)
		(end 132.471922 -289.963606)
		(width 0.0889)
		(layer "In4.Cu")
		(net "M_J_CPU1_SB_DQ<27>")
	)
	(arc
		(start 139.991846 -289.963606)
		(mid 140.274802 -290.039783)
		(end 140.557758 -289.963606)
		(width 0.0889)
		(layer "In4.Cu")
		(net "M_J_CPU1_SB_DQ<27>")
	)
	(arc
		(start 137.737596 -289.963606)
		(mid 137.919847 -289.913256)
		(end 138.103356 -289.95878)
		(width 0.0889)
		(layer "In4.Cu")
		(net "M_J_CPU1_SB_DQ<27>")
	)
	(arc
		(start 133.977634 -289.963606)
		(mid 134.159885 -289.913256)
		(end 134.343394 -289.95878)
		(width 0.0889)
		(layer "In4.Cu")
		(net "M_J_CPU1_SB_DQ<27>")
	)
	(arc
		(start 135.29183 -289.963606)
		(mid 135.574786 -290.039783)
		(end 135.857742 -289.963606)
		(width 0.0889)
		(layer "In4.Cu")
		(net "M_J_CPU1_SB_DQ<27>")
	)
	(arc
		(start 133.037834 -289.963606)
		(mid 133.224778 -289.913351)
		(end 133.411722 -289.963606)
		(width 0.0889)
		(layer "In4.Cu")
		(net "M_J_CPU1_SB_DQ<27>")
	)
	(arc
		(start 134.92607 -289.95878)
		(mid 135.109578 -289.913286)
		(end 135.29183 -289.963606)
		(width 0.0889)
		(layer "In4.Cu")
		(net "M_J_CPU1_SB_DQ<27>")
	)
	(arc
		(start 131.595114 -289.995356)
		(mid 131.850179 -290.038707)
		(end 132.09778 -289.963606)
		(width 0.0889)
		(layer "In4.Cu")
		(net "M_J_CPU1_SB_DQ<27>")
	)
	(arc
		(start 133.411722 -289.963606)
		(mid 133.694678 -290.039783)
		(end 133.977634 -289.963606)
		(width 0.0889)
		(layer "In4.Cu")
		(net "M_J_CPU1_SB_DQ<27>")
	)
	(segment
		(start 132.287772 -289.210242)
		(end 132.754878 -289.47618)
		(width 0.10668)
		(layer "F.Cu")
		(net "M_J_CPU1_SB_DQ<26>")
	)
	(segment
		(start 145.594578 -289.28695)
		(end 146.357086 -290.049458)
		(width 0.0889)
		(layer "In4.Cu")
		(net "M_J_CPU1_SB_DQ<26>")
	)
	(segment
		(start 163.53917 -310.810402)
		(end 163.787328 -310.810402)
		(width 0.14478)
		(layer "In4.Cu")
		(net "M_J_CPU1_SB_DQ<26>")
	)
	(segment
		(start 186.635136 -309.960264)
		(end 187.060078 -310.385206)
		(width 0.14478)
		(layer "In4.Cu")
		(net "M_J_CPU1_SB_DQ<26>")
	)
	(segment
		(start 159.667448 -309.647844)
		(end 159.667448 -309.876444)
		(width 0.14478)
		(layer "In4.Cu")
		(net "M_J_CPU1_SB_DQ<26>")
	)
	(segment
		(start 157.945328 -307.925724)
		(end 158.106872 -308.087268)
		(width 0.14478)
		(layer "In4.Cu")
		(net "M_J_CPU1_SB_DQ<26>")
	)
	(segment
		(start 156.156152 -306.365148)
		(end 156.384752 -306.365148)
		(width 0.14478)
		(layer "In4.Cu")
		(net "M_J_CPU1_SB_DQ<26>")
	)
	(segment
		(start 147.89785 -292.222682)
		(end 149.72665 -294.051482)
		(width 0.14478)
		(layer "In4.Cu")
		(net "M_J_CPU1_SB_DQ<26>")
	)
	(segment
		(start 156.93644 -307.145436)
		(end 157.16504 -307.145436)
		(width 0.14478)
		(layer "In4.Cu")
		(net "M_J_CPU1_SB_DQ<26>")
	)
	(segment
		(start 164.890196 -310.810402)
		(end 165.193472 -310.507126)
		(width 0.14478)
		(layer "In4.Cu")
		(net "M_J_CPU1_SB_DQ<26>")
	)
	(segment
		(start 161.581592 -310.810402)
		(end 161.884868 -310.507126)
		(width 0.14478)
		(layer "In4.Cu")
		(net "M_J_CPU1_SB_DQ<26>")
	)
	(segment
		(start 158.88716 -309.096156)
		(end 158.734506 -309.24881)
		(width 0.14478)
		(layer "In4.Cu")
		(net "M_J_CPU1_SB_DQ<26>")
	)
	(segment
		(start 157.17393 -307.688234)
		(end 157.17393 -307.916834)
		(width 0.14478)
		(layer "In4.Cu")
		(net "M_J_CPU1_SB_DQ<26>")
	)
	(segment
		(start 162.436302 -310.810402)
		(end 162.68446 -310.810402)
		(width 0.14478)
		(layer "In4.Cu")
		(net "M_J_CPU1_SB_DQ<26>")
	)
	(segment
		(start 157.17393 -307.916834)
		(end 157.335474 -308.078378)
		(width 0.14478)
		(layer "In4.Cu")
		(net "M_J_CPU1_SB_DQ<26>")
	)
	(segment
		(start 159.514794 -310.257698)
		(end 160.067498 -310.810402)
		(width 0.14478)
		(layer "In4.Cu")
		(net "M_J_CPU1_SB_DQ<26>")
	)
	(segment
		(start 135.753348 -289.148774)
		(end 135.76173 -289.1536)
		(width 0.0889)
		(layer "In4.Cu")
		(net "M_J_CPU1_SB_DQ<26>")
	)
	(segment
		(start 158.344362 -308.858666)
		(end 158.497016 -308.706012)
		(width 0.14478)
		(layer "In4.Cu")
		(net "M_J_CPU1_SB_DQ<26>")
	)
	(segment
		(start 146.514566 -291.321236)
		(end 147.183856 -291.768784)
		(width 0.0889)
		(layer "In4.Cu")
		(net "M_J_CPU1_SB_DQ<26>")
	)
	(segment
		(start 157.16504 -307.145436)
		(end 157.326584 -307.30698)
		(width 0.14478)
		(layer "In4.Cu")
		(net "M_J_CPU1_SB_DQ<26>")
	)
	(segment
		(start 161.884868 -310.507126)
		(end 162.133026 -310.507126)
		(width 0.14478)
		(layer "In4.Cu")
		(net "M_J_CPU1_SB_DQ<26>")
	)
	(segment
		(start 157.326584 -307.53558)
		(end 157.17393 -307.688234)
		(width 0.14478)
		(layer "In4.Cu")
		(net "M_J_CPU1_SB_DQ<26>")
	)
	(segment
		(start 164.642038 -310.810402)
		(end 164.890196 -310.810402)
		(width 0.14478)
		(layer "In4.Cu")
		(net "M_J_CPU1_SB_DQ<26>")
	)
	(segment
		(start 137.267696 -289.1536)
		(end 137.276078 -289.148774)
		(width 0.0889)
		(layer "In4.Cu")
		(net "M_J_CPU1_SB_DQ<26>")
	)
	(segment
		(start 146.357086 -290.941252)
		(end 146.514566 -291.321236)
		(width 0.0889)
		(layer "In4.Cu")
		(net "M_J_CPU1_SB_DQ<26>")
	)
	(segment
		(start 162.68446 -310.810402)
		(end 162.987736 -310.507126)
		(width 0.14478)
		(layer "In4.Cu")
		(net "M_J_CPU1_SB_DQ<26>")
	)
	(segment
		(start 170.18254 -309.960264)
		(end 171.032678 -310.810402)
		(width 0.14478)
		(layer "In4.Cu")
		(net "M_J_CPU1_SB_DQ<26>")
	)
	(segment
		(start 165.744906 -310.810402)
		(end 166.150036 -310.810402)
		(width 0.14478)
		(layer "In4.Cu")
		(net "M_J_CPU1_SB_DQ<26>")
	)
	(segment
		(start 161.030158 -310.507126)
		(end 161.333434 -310.810402)
		(width 0.14478)
		(layer "In4.Cu")
		(net "M_J_CPU1_SB_DQ<26>")
	)
	(segment
		(start 160.478724 -310.810402)
		(end 160.782 -310.507126)
		(width 0.14478)
		(layer "In4.Cu")
		(net "M_J_CPU1_SB_DQ<26>")
	)
	(segment
		(start 156.003498 -306.517802)
		(end 156.156152 -306.365148)
		(width 0.14478)
		(layer "In4.Cu")
		(net "M_J_CPU1_SB_DQ<26>")
	)
	(segment
		(start 163.787328 -310.810402)
		(end 164.090604 -310.507126)
		(width 0.14478)
		(layer "In4.Cu")
		(net "M_J_CPU1_SB_DQ<26>")
	)
	(segment
		(start 166.150036 -310.810402)
		(end 167.000174 -309.960264)
		(width 0.14478)
		(layer "In4.Cu")
		(net "M_J_CPU1_SB_DQ<26>")
	)
	(segment
		(start 177.726594 -309.960264)
		(end 178.576478 -310.810148)
		(width 0.14478)
		(layer "In4.Cu")
		(net "M_J_CPU1_SB_DQ<26>")
	)
	(segment
		(start 158.725616 -308.706012)
		(end 158.88716 -308.867556)
		(width 0.14478)
		(layer "In4.Cu")
		(net "M_J_CPU1_SB_DQ<26>")
	)
	(segment
		(start 157.954218 -308.468522)
		(end 157.954218 -308.697122)
		(width 0.14478)
		(layer "In4.Cu")
		(net "M_J_CPU1_SB_DQ<26>")
	)
	(segment
		(start 161.333434 -310.810402)
		(end 161.581592 -310.810402)
		(width 0.14478)
		(layer "In4.Cu")
		(net "M_J_CPU1_SB_DQ<26>")
	)
	(segment
		(start 149.72665 -294.051482)
		(end 149.72665 -300.469554)
		(width 0.14478)
		(layer "In4.Cu")
		(net "M_J_CPU1_SB_DQ<26>")
	)
	(segment
		(start 155.774898 -306.517802)
		(end 156.003498 -306.517802)
		(width 0.14478)
		(layer "In4.Cu")
		(net "M_J_CPU1_SB_DQ<26>")
	)
	(segment
		(start 159.12465 -309.638954)
		(end 159.277304 -309.4863)
		(width 0.14478)
		(layer "In4.Cu")
		(net "M_J_CPU1_SB_DQ<26>")
	)
	(segment
		(start 144.701514 -289.28695)
		(end 145.594578 -289.28695)
		(width 0.0889)
		(layer "In4.Cu")
		(net "M_J_CPU1_SB_DQ<26>")
	)
	(segment
		(start 158.734506 -309.24881)
		(end 158.734506 -309.47741)
		(width 0.14478)
		(layer "In4.Cu")
		(net "M_J_CPU1_SB_DQ<26>")
	)
	(segment
		(start 147.183856 -291.768784)
		(end 147.443952 -291.768784)
		(width 0.0889)
		(layer "In4.Cu")
		(net "M_J_CPU1_SB_DQ<26>")
	)
	(segment
		(start 158.88716 -308.867556)
		(end 158.88716 -309.096156)
		(width 0.14478)
		(layer "In4.Cu")
		(net "M_J_CPU1_SB_DQ<26>")
	)
	(segment
		(start 158.115762 -308.858666)
		(end 158.344362 -308.858666)
		(width 0.14478)
		(layer "In4.Cu")
		(net "M_J_CPU1_SB_DQ<26>")
	)
	(segment
		(start 159.505904 -309.4863)
		(end 159.667448 -309.647844)
		(width 0.14478)
		(layer "In4.Cu")
		(net "M_J_CPU1_SB_DQ<26>")
	)
	(segment
		(start 146.357086 -290.049458)
		(end 146.357086 -290.941252)
		(width 0.0889)
		(layer "In4.Cu")
		(net "M_J_CPU1_SB_DQ<26>")
	)
	(segment
		(start 165.44163 -310.507126)
		(end 165.744906 -310.810402)
		(width 0.14478)
		(layer "In4.Cu")
		(net "M_J_CPU1_SB_DQ<26>")
	)
	(segment
		(start 158.734506 -309.47741)
		(end 158.89605 -309.638954)
		(width 0.14478)
		(layer "In4.Cu")
		(net "M_J_CPU1_SB_DQ<26>")
	)
	(segment
		(start 174.544228 -309.960264)
		(end 177.726594 -309.960264)
		(width 0.14478)
		(layer "In4.Cu")
		(net "M_J_CPU1_SB_DQ<26>")
	)
	(segment
		(start 159.277304 -309.4863)
		(end 159.505904 -309.4863)
		(width 0.14478)
		(layer "In4.Cu")
		(net "M_J_CPU1_SB_DQ<26>")
	)
	(segment
		(start 157.716728 -307.925724)
		(end 157.945328 -307.925724)
		(width 0.14478)
		(layer "In4.Cu")
		(net "M_J_CPU1_SB_DQ<26>")
	)
	(segment
		(start 158.106872 -308.315868)
		(end 157.954218 -308.468522)
		(width 0.14478)
		(layer "In4.Cu")
		(net "M_J_CPU1_SB_DQ<26>")
	)
	(segment
		(start 162.133026 -310.507126)
		(end 162.436302 -310.810402)
		(width 0.14478)
		(layer "In4.Cu")
		(net "M_J_CPU1_SB_DQ<26>")
	)
	(segment
		(start 149.72665 -300.469554)
		(end 155.774898 -306.517802)
		(width 0.14478)
		(layer "In4.Cu")
		(net "M_J_CPU1_SB_DQ<26>")
	)
	(segment
		(start 140.453364 -289.148774)
		(end 140.461746 -289.1536)
		(width 0.0889)
		(layer "In4.Cu")
		(net "M_J_CPU1_SB_DQ<26>")
	)
	(segment
		(start 178.576478 -310.810148)
		(end 181.140862 -310.810148)
		(width 0.14478)
		(layer "In4.Cu")
		(net "M_J_CPU1_SB_DQ<26>")
	)
	(segment
		(start 160.067498 -310.810402)
		(end 160.478724 -310.810402)
		(width 0.14478)
		(layer "In4.Cu")
		(net "M_J_CPU1_SB_DQ<26>")
	)
	(segment
		(start 156.546296 -306.526692)
		(end 156.546296 -306.755292)
		(width 0.14478)
		(layer "In4.Cu")
		(net "M_J_CPU1_SB_DQ<26>")
	)
	(segment
		(start 136.693402 -289.148774)
		(end 136.701784 -289.1536)
		(width 0.0889)
		(layer "In4.Cu")
		(net "M_J_CPU1_SB_DQ<26>")
	)
	(segment
		(start 132.754878 -289.47618)
		(end 132.908802 -289.21075)
		(width 0.0889)
		(layer "In4.Cu")
		(net "M_J_CPU1_SB_DQ<26>")
	)
	(segment
		(start 156.555186 -307.29809)
		(end 156.783786 -307.29809)
		(width 0.14478)
		(layer "In4.Cu")
		(net "M_J_CPU1_SB_DQ<26>")
	)
	(segment
		(start 156.546296 -306.755292)
		(end 156.393642 -306.907946)
		(width 0.14478)
		(layer "In4.Cu")
		(net "M_J_CPU1_SB_DQ<26>")
	)
	(segment
		(start 158.106872 -308.087268)
		(end 158.106872 -308.315868)
		(width 0.14478)
		(layer "In4.Cu")
		(net "M_J_CPU1_SB_DQ<26>")
	)
	(segment
		(start 163.235894 -310.507126)
		(end 163.53917 -310.810402)
		(width 0.14478)
		(layer "In4.Cu")
		(net "M_J_CPU1_SB_DQ<26>")
	)
	(segment
		(start 132.908802 -289.21075)
		(end 133.004814 -289.18535)
		(width 0.0889)
		(layer "In4.Cu")
		(net "M_J_CPU1_SB_DQ<26>")
	)
	(segment
		(start 147.443952 -291.768784)
		(end 147.89785 -292.222682)
		(width 0.0889)
		(layer "In4.Cu")
		(net "M_J_CPU1_SB_DQ<26>")
	)
	(segment
		(start 162.987736 -310.507126)
		(end 163.235894 -310.507126)
		(width 0.14478)
		(layer "In4.Cu")
		(net "M_J_CPU1_SB_DQ<26>")
	)
	(segment
		(start 159.514794 -310.029098)
		(end 159.514794 -310.257698)
		(width 0.14478)
		(layer "In4.Cu")
		(net "M_J_CPU1_SB_DQ<26>")
	)
	(segment
		(start 156.783786 -307.29809)
		(end 156.93644 -307.145436)
		(width 0.14478)
		(layer "In4.Cu")
		(net "M_J_CPU1_SB_DQ<26>")
	)
	(segment
		(start 158.89605 -309.638954)
		(end 159.12465 -309.638954)
		(width 0.14478)
		(layer "In4.Cu")
		(net "M_J_CPU1_SB_DQ<26>")
	)
	(segment
		(start 156.393642 -306.907946)
		(end 156.393642 -307.136546)
		(width 0.14478)
		(layer "In4.Cu")
		(net "M_J_CPU1_SB_DQ<26>")
	)
	(segment
		(start 159.667448 -309.876444)
		(end 159.514794 -310.029098)
		(width 0.14478)
		(layer "In4.Cu")
		(net "M_J_CPU1_SB_DQ<26>")
	)
	(segment
		(start 133.507734 -289.1536)
		(end 133.516116 -289.148774)
		(width 0.0889)
		(layer "In4.Cu")
		(net "M_J_CPU1_SB_DQ<26>")
	)
	(segment
		(start 156.393642 -307.136546)
		(end 156.555186 -307.29809)
		(width 0.14478)
		(layer "In4.Cu")
		(net "M_J_CPU1_SB_DQ<26>")
	)
	(segment
		(start 157.335474 -308.078378)
		(end 157.564074 -308.078378)
		(width 0.14478)
		(layer "In4.Cu")
		(net "M_J_CPU1_SB_DQ<26>")
	)
	(segment
		(start 164.338762 -310.507126)
		(end 164.642038 -310.810402)
		(width 0.14478)
		(layer "In4.Cu")
		(net "M_J_CPU1_SB_DQ<26>")
	)
	(segment
		(start 181.140862 -310.810148)
		(end 181.990746 -309.960264)
		(width 0.14478)
		(layer "In4.Cu")
		(net "M_J_CPU1_SB_DQ<26>")
	)
	(segment
		(start 160.782 -310.507126)
		(end 161.030158 -310.507126)
		(width 0.14478)
		(layer "In4.Cu")
		(net "M_J_CPU1_SB_DQ<26>")
	)
	(segment
		(start 171.032678 -310.810402)
		(end 173.69409 -310.810402)
		(width 0.14478)
		(layer "In4.Cu")
		(net "M_J_CPU1_SB_DQ<26>")
	)
	(segment
		(start 173.69409 -310.810402)
		(end 174.544228 -309.960264)
		(width 0.14478)
		(layer "In4.Cu")
		(net "M_J_CPU1_SB_DQ<26>")
	)
	(segment
		(start 156.384752 -306.365148)
		(end 156.546296 -306.526692)
		(width 0.14478)
		(layer "In4.Cu")
		(net "M_J_CPU1_SB_DQ<26>")
	)
	(segment
		(start 164.090604 -310.507126)
		(end 164.338762 -310.507126)
		(width 0.14478)
		(layer "In4.Cu")
		(net "M_J_CPU1_SB_DQ<26>")
	)
	(segment
		(start 167.000174 -309.960264)
		(end 170.18254 -309.960264)
		(width 0.14478)
		(layer "In4.Cu")
		(net "M_J_CPU1_SB_DQ<26>")
	)
	(segment
		(start 141.967712 -289.1536)
		(end 141.976094 -289.148774)
		(width 0.0889)
		(layer "In4.Cu")
		(net "M_J_CPU1_SB_DQ<26>")
	)
	(segment
		(start 157.954218 -308.697122)
		(end 158.115762 -308.858666)
		(width 0.14478)
		(layer "In4.Cu")
		(net "M_J_CPU1_SB_DQ<26>")
	)
	(segment
		(start 141.393418 -289.148774)
		(end 141.4018 -289.1536)
		(width 0.0889)
		(layer "In4.Cu")
		(net "M_J_CPU1_SB_DQ<26>")
	)
	(segment
		(start 158.497016 -308.706012)
		(end 158.725616 -308.706012)
		(width 0.14478)
		(layer "In4.Cu")
		(net "M_J_CPU1_SB_DQ<26>")
	)
	(segment
		(start 165.193472 -310.507126)
		(end 165.44163 -310.507126)
		(width 0.14478)
		(layer "In4.Cu")
		(net "M_J_CPU1_SB_DQ<26>")
	)
	(segment
		(start 157.326584 -307.30698)
		(end 157.326584 -307.53558)
		(width 0.14478)
		(layer "In4.Cu")
		(net "M_J_CPU1_SB_DQ<26>")
	)
	(segment
		(start 157.564074 -308.078378)
		(end 157.716728 -307.925724)
		(width 0.14478)
		(layer "In4.Cu")
		(net "M_J_CPU1_SB_DQ<26>")
	)
	(segment
		(start 138.20775 -289.1536)
		(end 138.216132 -289.148774)
		(width 0.0889)
		(layer "In4.Cu")
		(net "M_J_CPU1_SB_DQ<26>")
	)
	(segment
		(start 181.990746 -309.960264)
		(end 186.635136 -309.960264)
		(width 0.14478)
		(layer "In4.Cu")
		(net "M_J_CPU1_SB_DQ<26>")
	)
	(arc
		(start 137.641838 -289.1536)
		(mid 137.924794 -289.229777)
		(end 138.20775 -289.1536)
		(width 0.0889)
		(layer "In4.Cu")
		(net "M_J_CPU1_SB_DQ<26>")
	)
	(arc
		(start 134.821676 -289.1536)
		(mid 135.104632 -289.229777)
		(end 135.387588 -289.1536)
		(width 0.0889)
		(layer "In4.Cu")
		(net "M_J_CPU1_SB_DQ<26>")
	)
	(arc
		(start 137.276078 -289.148774)
		(mid 137.459586 -289.10328)
		(end 137.641838 -289.1536)
		(width 0.0889)
		(layer "In4.Cu")
		(net "M_J_CPU1_SB_DQ<26>")
	)
	(arc
		(start 141.027658 -289.1536)
		(mid 141.209909 -289.10325)
		(end 141.393418 -289.148774)
		(width 0.0889)
		(layer "In4.Cu")
		(net "M_J_CPU1_SB_DQ<26>")
	)
	(arc
		(start 138.581892 -289.1536)
		(mid 138.864848 -289.229777)
		(end 139.147804 -289.1536)
		(width 0.0889)
		(layer "In4.Cu")
		(net "M_J_CPU1_SB_DQ<26>")
	)
	(arc
		(start 143.281654 -289.1536)
		(mid 143.56461 -289.229777)
		(end 143.847566 -289.1536)
		(width 0.0889)
		(layer "In4.Cu")
		(net "M_J_CPU1_SB_DQ<26>")
	)
	(arc
		(start 141.976094 -289.148774)
		(mid 142.159602 -289.10328)
		(end 142.341854 -289.1536)
		(width 0.0889)
		(layer "In4.Cu")
		(net "M_J_CPU1_SB_DQ<26>")
	)
	(arc
		(start 139.147804 -289.1536)
		(mid 139.334748 -289.103345)
		(end 139.521692 -289.1536)
		(width 0.0889)
		(layer "In4.Cu")
		(net "M_J_CPU1_SB_DQ<26>")
	)
	(arc
		(start 133.516116 -289.148774)
		(mid 133.699624 -289.10328)
		(end 133.881876 -289.1536)
		(width 0.0889)
		(layer "In4.Cu")
		(net "M_J_CPU1_SB_DQ<26>")
	)
	(arc
		(start 135.387588 -289.1536)
		(mid 135.569839 -289.10325)
		(end 135.753348 -289.148774)
		(width 0.0889)
		(layer "In4.Cu")
		(net "M_J_CPU1_SB_DQ<26>")
	)
	(arc
		(start 133.004814 -289.18535)
		(mid 133.260022 -289.228827)
		(end 133.507734 -289.1536)
		(width 0.0889)
		(layer "In4.Cu")
		(net "M_J_CPU1_SB_DQ<26>")
	)
	(arc
		(start 140.087604 -289.1536)
		(mid 140.269855 -289.10325)
		(end 140.453364 -289.148774)
		(width 0.0889)
		(layer "In4.Cu")
		(net "M_J_CPU1_SB_DQ<26>")
	)
	(arc
		(start 135.76173 -289.1536)
		(mid 136.044686 -289.229777)
		(end 136.327642 -289.1536)
		(width 0.0889)
		(layer "In4.Cu")
		(net "M_J_CPU1_SB_DQ<26>")
	)
	(arc
		(start 136.701784 -289.1536)
		(mid 136.98474 -289.229777)
		(end 137.267696 -289.1536)
		(width 0.0889)
		(layer "In4.Cu")
		(net "M_J_CPU1_SB_DQ<26>")
	)
	(arc
		(start 141.4018 -289.1536)
		(mid 141.684756 -289.229777)
		(end 141.967712 -289.1536)
		(width 0.0889)
		(layer "In4.Cu")
		(net "M_J_CPU1_SB_DQ<26>")
	)
	(arc
		(start 142.341854 -289.1536)
		(mid 142.62481 -289.229777)
		(end 142.907766 -289.1536)
		(width 0.0889)
		(layer "In4.Cu")
		(net "M_J_CPU1_SB_DQ<26>")
	)
	(arc
		(start 134.447788 -289.1536)
		(mid 134.634732 -289.103345)
		(end 134.821676 -289.1536)
		(width 0.0889)
		(layer "In4.Cu")
		(net "M_J_CPU1_SB_DQ<26>")
	)
	(arc
		(start 143.847566 -289.1536)
		(mid 144.022805 -289.103529)
		(end 144.20088 -289.142424)
		(width 0.0889)
		(layer "In4.Cu")
		(net "M_J_CPU1_SB_DQ<26>")
	)
	(arc
		(start 140.461746 -289.1536)
		(mid 140.744702 -289.229777)
		(end 141.027658 -289.1536)
		(width 0.0889)
		(layer "In4.Cu")
		(net "M_J_CPU1_SB_DQ<26>")
	)
	(arc
		(start 133.881876 -289.1536)
		(mid 134.164832 -289.229777)
		(end 134.447788 -289.1536)
		(width 0.0889)
		(layer "In4.Cu")
		(net "M_J_CPU1_SB_DQ<26>")
	)
	(arc
		(start 138.216132 -289.148774)
		(mid 138.39964 -289.10328)
		(end 138.581892 -289.1536)
		(width 0.0889)
		(layer "In4.Cu")
		(net "M_J_CPU1_SB_DQ<26>")
	)
	(arc
		(start 142.907766 -289.1536)
		(mid 143.09471 -289.103345)
		(end 143.281654 -289.1536)
		(width 0.0889)
		(layer "In4.Cu")
		(net "M_J_CPU1_SB_DQ<26>")
	)
	(arc
		(start 136.327642 -289.1536)
		(mid 136.509893 -289.10325)
		(end 136.693402 -289.148774)
		(width 0.0889)
		(layer "In4.Cu")
		(net "M_J_CPU1_SB_DQ<26>")
	)
	(arc
		(start 144.20088 -289.142424)
		(mid 144.444623 -289.237462)
		(end 144.701514 -289.28695)
		(width 0.0889)
		(layer "In4.Cu")
		(net "M_J_CPU1_SB_DQ<26>")
	)
	(arc
		(start 139.521692 -289.1536)
		(mid 139.804648 -289.229777)
		(end 140.087604 -289.1536)
		(width 0.0889)
		(layer "In4.Cu")
		(net "M_J_CPU1_SB_DQ<26>")
	)
	(segment
		(start 131.347972 -289.210242)
		(end 131.814824 -289.47618)
		(width 0.10668)
		(layer "F.Cu")
		(net "M_J_CPU1_SB_DQ<25>")
	)
	(segment
		(start 131.814824 -289.47618)
		(end 131.660646 -289.74161)
		(width 0.0889)
		(layer "In4.Cu")
		(net "M_J_CPU1_SB_DQ<25>")
	)
	(segment
		(start 138.20775 -289.79876)
		(end 138.216132 -289.803586)
		(width 0.0889)
		(layer "In4.Cu")
		(net "M_J_CPU1_SB_DQ<25>")
	)
	(segment
		(start 145.62328 -289.61461)
		(end 146.136106 -290.127436)
		(width 0.0889)
		(layer "In4.Cu")
		(net "M_J_CPU1_SB_DQ<25>")
	)
	(segment
		(start 191.160146 -311.23509)
		(end 191.160146 -311.235344)
		(width 0.14478)
		(layer "In4.Cu")
		(net "M_J_CPU1_SB_DQ<25>")
	)
	(segment
		(start 141.967712 -289.79876)
		(end 141.976094 -289.803586)
		(width 0.0889)
		(layer "In4.Cu")
		(net "M_J_CPU1_SB_DQ<25>")
	)
	(segment
		(start 190.735204 -310.810148)
		(end 191.160146 -311.23509)
		(width 0.14478)
		(layer "In4.Cu")
		(net "M_J_CPU1_SB_DQ<25>")
	)
	(segment
		(start 146.136106 -290.952428)
		(end 146.35734 -291.486336)
		(width 0.0889)
		(layer "In4.Cu")
		(net "M_J_CPU1_SB_DQ<25>")
	)
	(segment
		(start 146.136106 -290.127436)
		(end 146.136106 -290.952428)
		(width 0.0889)
		(layer "In4.Cu")
		(net "M_J_CPU1_SB_DQ<25>")
	)
	(segment
		(start 135.753348 -289.803586)
		(end 135.76173 -289.79876)
		(width 0.0889)
		(layer "In4.Cu")
		(net "M_J_CPU1_SB_DQ<25>")
	)
	(segment
		(start 181.963568 -310.810148)
		(end 190.735204 -310.810148)
		(width 0.14478)
		(layer "In4.Cu")
		(net "M_J_CPU1_SB_DQ<25>")
	)
	(segment
		(start 137.267696 -289.79876)
		(end 137.276078 -289.803586)
		(width 0.0889)
		(layer "In4.Cu")
		(net "M_J_CPU1_SB_DQ<25>")
	)
	(segment
		(start 170.216576 -310.810402)
		(end 171.06646 -311.660286)
		(width 0.14478)
		(layer "In4.Cu")
		(net "M_J_CPU1_SB_DQ<25>")
	)
	(segment
		(start 144.79778 -289.61461)
		(end 145.62328 -289.61461)
		(width 0.0889)
		(layer "In4.Cu")
		(net "M_J_CPU1_SB_DQ<25>")
	)
	(segment
		(start 149.27707 -300.65599)
		(end 160.281366 -311.660286)
		(width 0.14478)
		(layer "In4.Cu")
		(net "M_J_CPU1_SB_DQ<25>")
	)
	(segment
		(start 166.036244 -311.660286)
		(end 166.886128 -310.810402)
		(width 0.14478)
		(layer "In4.Cu")
		(net "M_J_CPU1_SB_DQ<25>")
	)
	(segment
		(start 131.993386 -289.803586)
		(end 132.001768 -289.79876)
		(width 0.0889)
		(layer "In4.Cu")
		(net "M_J_CPU1_SB_DQ<25>")
	)
	(segment
		(start 146.35734 -291.486336)
		(end 147.305776 -292.119812)
		(width 0.0889)
		(layer "In4.Cu")
		(net "M_J_CPU1_SB_DQ<25>")
	)
	(segment
		(start 166.886128 -310.810402)
		(end 170.216576 -310.810402)
		(width 0.14478)
		(layer "In4.Cu")
		(net "M_J_CPU1_SB_DQ<25>")
	)
	(segment
		(start 144.034764 -289.849306)
		(end 144.563084 -289.849306)
		(width 0.0889)
		(layer "In4.Cu")
		(net "M_J_CPU1_SB_DQ<25>")
	)
	(segment
		(start 136.693402 -289.803586)
		(end 136.701784 -289.79876)
		(width 0.0889)
		(layer "In4.Cu")
		(net "M_J_CPU1_SB_DQ<25>")
	)
	(segment
		(start 147.883626 -292.85184)
		(end 149.27707 -294.245284)
		(width 0.14478)
		(layer "In4.Cu")
		(net "M_J_CPU1_SB_DQ<25>")
	)
	(segment
		(start 131.660646 -289.74161)
		(end 131.682998 -289.824922)
		(width 0.0889)
		(layer "In4.Cu")
		(net "M_J_CPU1_SB_DQ<25>")
	)
	(segment
		(start 149.27707 -294.245284)
		(end 149.27707 -300.65599)
		(width 0.14478)
		(layer "In4.Cu")
		(net "M_J_CPU1_SB_DQ<25>")
	)
	(segment
		(start 140.453364 -289.803586)
		(end 140.461746 -289.79876)
		(width 0.0889)
		(layer "In4.Cu")
		(net "M_J_CPU1_SB_DQ<25>")
	)
	(segment
		(start 133.507734 -289.79876)
		(end 133.516116 -289.803586)
		(width 0.0889)
		(layer "In4.Cu")
		(net "M_J_CPU1_SB_DQ<25>")
	)
	(segment
		(start 141.393418 -289.803586)
		(end 141.4018 -289.79876)
		(width 0.0889)
		(layer "In4.Cu")
		(net "M_J_CPU1_SB_DQ<25>")
	)
	(segment
		(start 171.06646 -311.660286)
		(end 173.580298 -311.660286)
		(width 0.14478)
		(layer "In4.Cu")
		(net "M_J_CPU1_SB_DQ<25>")
	)
	(segment
		(start 177.76063 -310.810402)
		(end 178.61026 -311.660032)
		(width 0.14478)
		(layer "In4.Cu")
		(net "M_J_CPU1_SB_DQ<25>")
	)
	(segment
		(start 147.305776 -292.119812)
		(end 147.482814 -292.451028)
		(width 0.0889)
		(layer "In4.Cu")
		(net "M_J_CPU1_SB_DQ<25>")
	)
	(segment
		(start 147.482814 -292.451028)
		(end 147.883626 -292.85184)
		(width 0.0889)
		(layer "In4.Cu")
		(net "M_J_CPU1_SB_DQ<25>")
	)
	(segment
		(start 174.430182 -310.810402)
		(end 177.76063 -310.810402)
		(width 0.14478)
		(layer "In4.Cu")
		(net "M_J_CPU1_SB_DQ<25>")
	)
	(segment
		(start 181.113684 -311.660032)
		(end 181.963568 -310.810148)
		(width 0.14478)
		(layer "In4.Cu")
		(net "M_J_CPU1_SB_DQ<25>")
	)
	(segment
		(start 160.281366 -311.660286)
		(end 166.036244 -311.660286)
		(width 0.14478)
		(layer "In4.Cu")
		(net "M_J_CPU1_SB_DQ<25>")
	)
	(segment
		(start 144.563084 -289.849306)
		(end 144.79778 -289.61461)
		(width 0.0889)
		(layer "In4.Cu")
		(net "M_J_CPU1_SB_DQ<25>")
	)
	(segment
		(start 173.580298 -311.660286)
		(end 174.430182 -310.810402)
		(width 0.14478)
		(layer "In4.Cu")
		(net "M_J_CPU1_SB_DQ<25>")
	)
	(segment
		(start 178.61026 -311.660032)
		(end 181.113684 -311.660032)
		(width 0.14478)
		(layer "In4.Cu")
		(net "M_J_CPU1_SB_DQ<25>")
	)
	(segment
		(start 132.93344 -289.803586)
		(end 132.941822 -289.79876)
		(width 0.0889)
		(layer "In4.Cu")
		(net "M_J_CPU1_SB_DQ<25>")
	)
	(arc
		(start 140.461746 -289.79876)
		(mid 140.744702 -289.722583)
		(end 141.027658 -289.79876)
		(width 0.0889)
		(layer "In4.Cu")
		(net "M_J_CPU1_SB_DQ<25>")
	)
	(arc
		(start 134.447788 -289.79876)
		(mid 134.634732 -289.849015)
		(end 134.821676 -289.79876)
		(width 0.0889)
		(layer "In4.Cu")
		(net "M_J_CPU1_SB_DQ<25>")
	)
	(arc
		(start 141.976094 -289.803586)
		(mid 142.159602 -289.84908)
		(end 142.341854 -289.79876)
		(width 0.0889)
		(layer "In4.Cu")
		(net "M_J_CPU1_SB_DQ<25>")
	)
	(arc
		(start 142.341854 -289.79876)
		(mid 142.62481 -289.722583)
		(end 142.907766 -289.79876)
		(width 0.0889)
		(layer "In4.Cu")
		(net "M_J_CPU1_SB_DQ<25>")
	)
	(arc
		(start 137.641838 -289.79876)
		(mid 137.924794 -289.722583)
		(end 138.20775 -289.79876)
		(width 0.0889)
		(layer "In4.Cu")
		(net "M_J_CPU1_SB_DQ<25>")
	)
	(arc
		(start 138.581892 -289.79876)
		(mid 138.864848 -289.722583)
		(end 139.147804 -289.79876)
		(width 0.0889)
		(layer "In4.Cu")
		(net "M_J_CPU1_SB_DQ<25>")
	)
	(arc
		(start 133.881876 -289.79876)
		(mid 134.164832 -289.722583)
		(end 134.447788 -289.79876)
		(width 0.0889)
		(layer "In4.Cu")
		(net "M_J_CPU1_SB_DQ<25>")
	)
	(arc
		(start 131.682998 -289.824922)
		(mid 131.840508 -289.84812)
		(end 131.993386 -289.803586)
		(width 0.0889)
		(layer "In4.Cu")
		(net "M_J_CPU1_SB_DQ<25>")
	)
	(arc
		(start 139.521692 -289.79876)
		(mid 139.804648 -289.722583)
		(end 140.087604 -289.79876)
		(width 0.0889)
		(layer "In4.Cu")
		(net "M_J_CPU1_SB_DQ<25>")
	)
	(arc
		(start 135.76173 -289.79876)
		(mid 136.044686 -289.722583)
		(end 136.327642 -289.79876)
		(width 0.0889)
		(layer "In4.Cu")
		(net "M_J_CPU1_SB_DQ<25>")
	)
	(arc
		(start 137.276078 -289.803586)
		(mid 137.459586 -289.84908)
		(end 137.641838 -289.79876)
		(width 0.0889)
		(layer "In4.Cu")
		(net "M_J_CPU1_SB_DQ<25>")
	)
	(arc
		(start 136.327642 -289.79876)
		(mid 136.509893 -289.84911)
		(end 136.693402 -289.803586)
		(width 0.0889)
		(layer "In4.Cu")
		(net "M_J_CPU1_SB_DQ<25>")
	)
	(arc
		(start 132.56768 -289.79876)
		(mid 132.749931 -289.84911)
		(end 132.93344 -289.803586)
		(width 0.0889)
		(layer "In4.Cu")
		(net "M_J_CPU1_SB_DQ<25>")
	)
	(arc
		(start 136.701784 -289.79876)
		(mid 136.98474 -289.722583)
		(end 137.267696 -289.79876)
		(width 0.0889)
		(layer "In4.Cu")
		(net "M_J_CPU1_SB_DQ<25>")
	)
	(arc
		(start 138.216132 -289.803586)
		(mid 138.39964 -289.84908)
		(end 138.581892 -289.79876)
		(width 0.0889)
		(layer "In4.Cu")
		(net "M_J_CPU1_SB_DQ<25>")
	)
	(arc
		(start 143.847566 -289.79876)
		(mid 143.937822 -289.836413)
		(end 144.034764 -289.849306)
		(width 0.0889)
		(layer "In4.Cu")
		(net "M_J_CPU1_SB_DQ<25>")
	)
	(arc
		(start 142.907766 -289.79876)
		(mid 143.09471 -289.849015)
		(end 143.281654 -289.79876)
		(width 0.0889)
		(layer "In4.Cu")
		(net "M_J_CPU1_SB_DQ<25>")
	)
	(arc
		(start 143.281654 -289.79876)
		(mid 143.56461 -289.722583)
		(end 143.847566 -289.79876)
		(width 0.0889)
		(layer "In4.Cu")
		(net "M_J_CPU1_SB_DQ<25>")
	)
	(arc
		(start 132.941822 -289.79876)
		(mid 133.224778 -289.722583)
		(end 133.507734 -289.79876)
		(width 0.0889)
		(layer "In4.Cu")
		(net "M_J_CPU1_SB_DQ<25>")
	)
	(arc
		(start 141.4018 -289.79876)
		(mid 141.684756 -289.722583)
		(end 141.967712 -289.79876)
		(width 0.0889)
		(layer "In4.Cu")
		(net "M_J_CPU1_SB_DQ<25>")
	)
	(arc
		(start 133.516116 -289.803586)
		(mid 133.699624 -289.84908)
		(end 133.881876 -289.79876)
		(width 0.0889)
		(layer "In4.Cu")
		(net "M_J_CPU1_SB_DQ<25>")
	)
	(arc
		(start 139.147804 -289.79876)
		(mid 139.334748 -289.849015)
		(end 139.521692 -289.79876)
		(width 0.0889)
		(layer "In4.Cu")
		(net "M_J_CPU1_SB_DQ<25>")
	)
	(arc
		(start 141.027658 -289.79876)
		(mid 141.209909 -289.84911)
		(end 141.393418 -289.803586)
		(width 0.0889)
		(layer "In4.Cu")
		(net "M_J_CPU1_SB_DQ<25>")
	)
	(arc
		(start 132.001768 -289.79876)
		(mid 132.284724 -289.722583)
		(end 132.56768 -289.79876)
		(width 0.0889)
		(layer "In4.Cu")
		(net "M_J_CPU1_SB_DQ<25>")
	)
	(arc
		(start 134.821676 -289.79876)
		(mid 135.104632 -289.722583)
		(end 135.387588 -289.79876)
		(width 0.0889)
		(layer "In4.Cu")
		(net "M_J_CPU1_SB_DQ<25>")
	)
	(arc
		(start 140.087604 -289.79876)
		(mid 140.269855 -289.84911)
		(end 140.453364 -289.803586)
		(width 0.0889)
		(layer "In4.Cu")
		(net "M_J_CPU1_SB_DQ<25>")
	)
	(arc
		(start 135.387588 -289.79876)
		(mid 135.569839 -289.84911)
		(end 135.753348 -289.803586)
		(width 0.0889)
		(layer "In4.Cu")
		(net "M_J_CPU1_SB_DQ<25>")
	)
	(segment
		(start 132.757926 -288.400236)
		(end 133.224778 -288.666174)
		(width 0.10668)
		(layer "F.Cu")
		(net "M_J_CPU1_SB_DQ<24>")
	)
	(segment
		(start 166.243 -309.960264)
		(end 167.092884 -309.11038)
		(width 0.14478)
		(layer "In4.Cu")
		(net "M_J_CPU1_SB_DQ<24>")
	)
	(segment
		(start 189.20587 -309.110126)
		(end 189.367414 -309.27167)
		(width 0.14478)
		(layer "In4.Cu")
		(net "M_J_CPU1_SB_DQ<24>")
	)
	(segment
		(start 181.13248 -309.96001)
		(end 181.982364 -309.110126)
		(width 0.14478)
		(layer "In4.Cu")
		(net "M_J_CPU1_SB_DQ<24>")
	)
	(segment
		(start 146.603466 -290.003738)
		(end 146.603466 -291.004244)
		(width 0.0889)
		(layer "In4.Cu")
		(net "M_J_CPU1_SB_DQ<24>")
	)
	(segment
		(start 150.17623 -300.282864)
		(end 155.478734 -305.585368)
		(width 0.14478)
		(layer "In4.Cu")
		(net "M_J_CPU1_SB_DQ<24>")
	)
	(segment
		(start 143.377666 -288.988754)
		(end 143.386048 -288.99358)
		(width 0.0889)
		(layer "In4.Cu")
		(net "M_J_CPU1_SB_DQ<24>")
	)
	(segment
		(start 144.513808 -289.033458)
		(end 144.615154 -289.043364)
		(width 0.0889)
		(layer "In4.Cu")
		(net "M_J_CPU1_SB_DQ<24>")
	)
	(segment
		(start 140.557758 -288.988754)
		(end 140.56614 -288.99358)
		(width 0.0889)
		(layer "In4.Cu")
		(net "M_J_CPU1_SB_DQ<24>")
	)
	(segment
		(start 133.070854 -288.931604)
		(end 133.093206 -289.014916)
		(width 0.0889)
		(layer "In4.Cu")
		(net "M_J_CPU1_SB_DQ<24>")
	)
	(segment
		(start 170.9674 -309.960264)
		(end 173.787054 -309.960264)
		(width 0.14478)
		(layer "In4.Cu")
		(net "M_J_CPU1_SB_DQ<24>")
	)
	(segment
		(start 173.787054 -309.960264)
		(end 174.636938 -309.11038)
		(width 0.14478)
		(layer "In4.Cu")
		(net "M_J_CPU1_SB_DQ<24>")
	)
	(segment
		(start 178.511454 -309.960264)
		(end 178.511708 -309.96001)
		(width 0.14478)
		(layer "In4.Cu")
		(net "M_J_CPU1_SB_DQ<24>")
	)
	(segment
		(start 178.511708 -309.96001)
		(end 181.13248 -309.96001)
		(width 0.14478)
		(layer "In4.Cu")
		(net "M_J_CPU1_SB_DQ<24>")
	)
	(segment
		(start 190.080392 -309.110126)
		(end 190.735204 -309.110126)
		(width 0.14478)
		(layer "In4.Cu")
		(net "M_J_CPU1_SB_DQ<24>")
	)
	(segment
		(start 167.092884 -309.11038)
		(end 170.117516 -309.11038)
		(width 0.14478)
		(layer "In4.Cu")
		(net "M_J_CPU1_SB_DQ<24>")
	)
	(segment
		(start 189.528958 -310.052466)
		(end 189.757304 -310.052466)
		(width 0.14478)
		(layer "In4.Cu")
		(net "M_J_CPU1_SB_DQ<24>")
	)
	(segment
		(start 134.343394 -288.99358)
		(end 134.351776 -288.988754)
		(width 0.0889)
		(layer "In4.Cu")
		(net "M_J_CPU1_SB_DQ<24>")
	)
	(segment
		(start 133.224778 -288.666174)
		(end 133.070854 -288.931604)
		(width 0.0889)
		(layer "In4.Cu")
		(net "M_J_CPU1_SB_DQ<24>")
	)
	(segment
		(start 191.160146 -309.535068)
		(end 191.160146 -309.535322)
		(width 0.14478)
		(layer "In4.Cu")
		(net "M_J_CPU1_SB_DQ<24>")
	)
	(segment
		(start 190.735204 -309.110126)
		(end 191.160146 -309.535068)
		(width 0.14478)
		(layer "In4.Cu")
		(net "M_J_CPU1_SB_DQ<24>")
	)
	(segment
		(start 146.953986 -291.354764)
		(end 147.67306 -291.354764)
		(width 0.0889)
		(layer "In4.Cu")
		(net "M_J_CPU1_SB_DQ<24>")
	)
	(segment
		(start 144.615154 -289.043364)
		(end 145.643092 -289.043364)
		(width 0.0889)
		(layer "In4.Cu")
		(net "M_J_CPU1_SB_DQ<24>")
	)
	(segment
		(start 170.117516 -309.11038)
		(end 170.9674 -309.960264)
		(width 0.14478)
		(layer "In4.Cu")
		(net "M_J_CPU1_SB_DQ<24>")
	)
	(segment
		(start 147.67306 -291.354764)
		(end 147.894548 -291.576252)
		(width 0.0889)
		(layer "In4.Cu")
		(net "M_J_CPU1_SB_DQ<24>")
	)
	(segment
		(start 147.894548 -291.576252)
		(end 150.17623 -293.857934)
		(width 0.14478)
		(layer "In4.Cu")
		(net "M_J_CPU1_SB_DQ<24>")
	)
	(segment
		(start 135.857742 -288.988754)
		(end 135.866124 -288.99358)
		(width 0.0889)
		(layer "In4.Cu")
		(net "M_J_CPU1_SB_DQ<24>")
	)
	(segment
		(start 189.367414 -309.890922)
		(end 189.528958 -310.052466)
		(width 0.14478)
		(layer "In4.Cu")
		(net "M_J_CPU1_SB_DQ<24>")
	)
	(segment
		(start 189.918848 -309.890922)
		(end 189.918848 -309.27167)
		(width 0.14478)
		(layer "In4.Cu")
		(net "M_J_CPU1_SB_DQ<24>")
	)
	(segment
		(start 138.103356 -288.99358)
		(end 138.111738 -288.988754)
		(width 0.0889)
		(layer "In4.Cu")
		(net "M_J_CPU1_SB_DQ<24>")
	)
	(segment
		(start 146.603466 -291.004244)
		(end 146.953986 -291.354764)
		(width 0.0889)
		(layer "In4.Cu")
		(net "M_J_CPU1_SB_DQ<24>")
	)
	(segment
		(start 174.636938 -309.11038)
		(end 177.66157 -309.11038)
		(width 0.14478)
		(layer "In4.Cu")
		(net "M_J_CPU1_SB_DQ<24>")
	)
	(segment
		(start 160.681162 -309.960264)
		(end 166.243 -309.960264)
		(width 0.14478)
		(layer "In4.Cu")
		(net "M_J_CPU1_SB_DQ<24>")
	)
	(segment
		(start 139.617704 -288.988754)
		(end 139.626086 -288.99358)
		(width 0.0889)
		(layer "In4.Cu")
		(net "M_J_CPU1_SB_DQ<24>")
	)
	(segment
		(start 177.66157 -309.11038)
		(end 178.511454 -309.960264)
		(width 0.14478)
		(layer "In4.Cu")
		(net "M_J_CPU1_SB_DQ<24>")
	)
	(segment
		(start 134.917688 -288.988754)
		(end 134.92607 -288.99358)
		(width 0.0889)
		(layer "In4.Cu")
		(net "M_J_CPU1_SB_DQ<24>")
	)
	(segment
		(start 139.04341 -288.99358)
		(end 139.051792 -288.988754)
		(width 0.0889)
		(layer "In4.Cu")
		(net "M_J_CPU1_SB_DQ<24>")
	)
	(segment
		(start 156.306266 -305.585368)
		(end 160.681162 -309.960264)
		(width 0.14478)
		(layer "In4.Cu")
		(net "M_J_CPU1_SB_DQ<24>")
	)
	(segment
		(start 142.803372 -288.99358)
		(end 142.811754 -288.988754)
		(width 0.0889)
		(layer "In4.Cu")
		(net "M_J_CPU1_SB_DQ<24>")
	)
	(segment
		(start 189.757304 -310.052466)
		(end 189.918848 -309.890922)
		(width 0.14478)
		(layer "In4.Cu")
		(net "M_J_CPU1_SB_DQ<24>")
	)
	(segment
		(start 150.17623 -293.857934)
		(end 150.17623 -300.282864)
		(width 0.14478)
		(layer "In4.Cu")
		(net "M_J_CPU1_SB_DQ<24>")
	)
	(segment
		(start 145.643092 -289.043364)
		(end 146.603466 -290.003738)
		(width 0.0889)
		(layer "In4.Cu")
		(net "M_J_CPU1_SB_DQ<24>")
	)
	(segment
		(start 189.367414 -309.27167)
		(end 189.367414 -309.890922)
		(width 0.14478)
		(layer "In4.Cu")
		(net "M_J_CPU1_SB_DQ<24>")
	)
	(segment
		(start 189.918848 -309.27167)
		(end 190.080392 -309.110126)
		(width 0.14478)
		(layer "In4.Cu")
		(net "M_J_CPU1_SB_DQ<24>")
	)
	(segment
		(start 181.982364 -309.110126)
		(end 189.20587 -309.110126)
		(width 0.14478)
		(layer "In4.Cu")
		(net "M_J_CPU1_SB_DQ<24>")
	)
	(segment
		(start 144.294606 -288.976054)
		(end 144.513808 -289.033458)
		(width 0.0889)
		(layer "In4.Cu")
		(net "M_J_CPU1_SB_DQ<24>")
	)
	(segment
		(start 155.478734 -305.585368)
		(end 156.306266 -305.585368)
		(width 0.14478)
		(layer "In4.Cu")
		(net "M_J_CPU1_SB_DQ<24>")
	)
	(arc
		(start 142.437612 -288.988754)
		(mid 142.619863 -289.039104)
		(end 142.803372 -288.99358)
		(width 0.0889)
		(layer "In4.Cu")
		(net "M_J_CPU1_SB_DQ<24>")
	)
	(arc
		(start 143.751808 -288.988754)
		(mid 144.021577 -288.912731)
		(end 144.294606 -288.976054)
		(width 0.0889)
		(layer "In4.Cu")
		(net "M_J_CPU1_SB_DQ<24>")
	)
	(arc
		(start 139.991846 -288.988754)
		(mid 140.274802 -288.912577)
		(end 140.557758 -288.988754)
		(width 0.0889)
		(layer "In4.Cu")
		(net "M_J_CPU1_SB_DQ<24>")
	)
	(arc
		(start 141.497812 -288.988754)
		(mid 141.684756 -289.039009)
		(end 141.8717 -288.988754)
		(width 0.0889)
		(layer "In4.Cu")
		(net "M_J_CPU1_SB_DQ<24>")
	)
	(arc
		(start 141.8717 -288.988754)
		(mid 142.154656 -288.912577)
		(end 142.437612 -288.988754)
		(width 0.0889)
		(layer "In4.Cu")
		(net "M_J_CPU1_SB_DQ<24>")
	)
	(arc
		(start 137.171684 -288.988754)
		(mid 137.45464 -288.912577)
		(end 137.737596 -288.988754)
		(width 0.0889)
		(layer "In4.Cu")
		(net "M_J_CPU1_SB_DQ<24>")
	)
	(arc
		(start 136.797796 -288.988754)
		(mid 136.98474 -289.039009)
		(end 137.171684 -288.988754)
		(width 0.0889)
		(layer "In4.Cu")
		(net "M_J_CPU1_SB_DQ<24>")
	)
	(arc
		(start 135.866124 -288.99358)
		(mid 136.049632 -289.039074)
		(end 136.231884 -288.988754)
		(width 0.0889)
		(layer "In4.Cu")
		(net "M_J_CPU1_SB_DQ<24>")
	)
	(arc
		(start 138.67765 -288.988754)
		(mid 138.859901 -289.039104)
		(end 139.04341 -288.99358)
		(width 0.0889)
		(layer "In4.Cu")
		(net "M_J_CPU1_SB_DQ<24>")
	)
	(arc
		(start 139.051792 -288.988754)
		(mid 139.334748 -288.912577)
		(end 139.617704 -288.988754)
		(width 0.0889)
		(layer "In4.Cu")
		(net "M_J_CPU1_SB_DQ<24>")
	)
	(arc
		(start 143.386048 -288.99358)
		(mid 143.569556 -289.039074)
		(end 143.751808 -288.988754)
		(width 0.0889)
		(layer "In4.Cu")
		(net "M_J_CPU1_SB_DQ<24>")
	)
	(arc
		(start 140.56614 -288.99358)
		(mid 140.749648 -289.039074)
		(end 140.9319 -288.988754)
		(width 0.0889)
		(layer "In4.Cu")
		(net "M_J_CPU1_SB_DQ<24>")
	)
	(arc
		(start 140.9319 -288.988754)
		(mid 141.214856 -288.912577)
		(end 141.497812 -288.988754)
		(width 0.0889)
		(layer "In4.Cu")
		(net "M_J_CPU1_SB_DQ<24>")
	)
	(arc
		(start 133.093206 -289.014916)
		(mid 133.255395 -289.037651)
		(end 133.411722 -288.988754)
		(width 0.0889)
		(layer "In4.Cu")
		(net "M_J_CPU1_SB_DQ<24>")
	)
	(arc
		(start 133.411722 -288.988754)
		(mid 133.694678 -288.912577)
		(end 133.977634 -288.988754)
		(width 0.0889)
		(layer "In4.Cu")
		(net "M_J_CPU1_SB_DQ<24>")
	)
	(arc
		(start 133.977634 -288.988754)
		(mid 134.159885 -289.039104)
		(end 134.343394 -288.99358)
		(width 0.0889)
		(layer "In4.Cu")
		(net "M_J_CPU1_SB_DQ<24>")
	)
	(arc
		(start 138.111738 -288.988754)
		(mid 138.394694 -288.912577)
		(end 138.67765 -288.988754)
		(width 0.0889)
		(layer "In4.Cu")
		(net "M_J_CPU1_SB_DQ<24>")
	)
	(arc
		(start 142.811754 -288.988754)
		(mid 143.09471 -288.912577)
		(end 143.377666 -288.988754)
		(width 0.0889)
		(layer "In4.Cu")
		(net "M_J_CPU1_SB_DQ<24>")
	)
	(arc
		(start 135.29183 -288.988754)
		(mid 135.574786 -288.912577)
		(end 135.857742 -288.988754)
		(width 0.0889)
		(layer "In4.Cu")
		(net "M_J_CPU1_SB_DQ<24>")
	)
	(arc
		(start 136.231884 -288.988754)
		(mid 136.51484 -288.912577)
		(end 136.797796 -288.988754)
		(width 0.0889)
		(layer "In4.Cu")
		(net "M_J_CPU1_SB_DQ<24>")
	)
	(arc
		(start 137.737596 -288.988754)
		(mid 137.919847 -289.039104)
		(end 138.103356 -288.99358)
		(width 0.0889)
		(layer "In4.Cu")
		(net "M_J_CPU1_SB_DQ<24>")
	)
	(arc
		(start 134.351776 -288.988754)
		(mid 134.634732 -288.912577)
		(end 134.917688 -288.988754)
		(width 0.0889)
		(layer "In4.Cu")
		(net "M_J_CPU1_SB_DQ<24>")
	)
	(arc
		(start 134.92607 -288.99358)
		(mid 135.109578 -289.039074)
		(end 135.29183 -288.988754)
		(width 0.0889)
		(layer "In4.Cu")
		(net "M_J_CPU1_SB_DQ<24>")
	)
	(arc
		(start 139.626086 -288.99358)
		(mid 139.809594 -289.039074)
		(end 139.991846 -288.988754)
		(width 0.0889)
		(layer "In4.Cu")
		(net "M_J_CPU1_SB_DQ<24>")
	)
	(segment
		(start 130.877818 -288.400236)
		(end 131.34467 -288.666174)
		(width 0.10668)
		(layer "F.Cu")
		(net "M_J_CPU1_SB_DQ<23>")
	)
	(segment
		(start 154.146504 -303.473612)
		(end 154.375104 -303.473612)
		(width 0.14478)
		(layer "In4.Cu")
		(net "M_J_CPU1_SB_DQ<23>")
	)
	(segment
		(start 138.103356 -288.339022)
		(end 138.111738 -288.343848)
		(width 0.0889)
		(layer "In4.Cu")
		(net "M_J_CPU1_SB_DQ<23>")
	)
	(segment
		(start 154.56027 -303.288446)
		(end 154.78887 -303.288446)
		(width 0.14478)
		(layer "In4.Cu")
		(net "M_J_CPU1_SB_DQ<23>")
	)
	(segment
		(start 147.078446 -290.173918)
		(end 147.27936 -290.173918)
		(width 0.0889)
		(layer "In4.Cu")
		(net "M_J_CPU1_SB_DQ<23>")
	)
	(segment
		(start 139.04341 -288.339022)
		(end 139.051792 -288.343848)
		(width 0.0889)
		(layer "In4.Cu")
		(net "M_J_CPU1_SB_DQ<23>")
	)
	(segment
		(start 150.72741 -293.621968)
		(end 150.72741 -300.054518)
		(width 0.14478)
		(layer "In4.Cu")
		(net "M_J_CPU1_SB_DQ<23>")
	)
	(segment
		(start 154.765248 -303.863756)
		(end 154.765248 -304.092356)
		(width 0.14478)
		(layer "In4.Cu")
		(net "M_J_CPU1_SB_DQ<23>")
	)
	(segment
		(start 155.730702 -304.458878)
		(end 155.545536 -304.644044)
		(width 0.14478)
		(layer "In4.Cu")
		(net "M_J_CPU1_SB_DQ<23>")
	)
	(segment
		(start 155.545536 -304.872644)
		(end 155.70708 -305.034188)
		(width 0.14478)
		(layer "In4.Cu")
		(net "M_J_CPU1_SB_DQ<23>")
	)
	(segment
		(start 155.93568 -305.034188)
		(end 156.120846 -304.849022)
		(width 0.14478)
		(layer "In4.Cu")
		(net "M_J_CPU1_SB_DQ<23>")
	)
	(segment
		(start 134.343394 -288.339022)
		(end 134.351776 -288.343848)
		(width 0.0889)
		(layer "In4.Cu")
		(net "M_J_CPU1_SB_DQ<23>")
	)
	(segment
		(start 181.073298 -309.110126)
		(end 181.922928 -308.260496)
		(width 0.14478)
		(layer "In4.Cu")
		(net "M_J_CPU1_SB_DQ<23>")
	)
	(segment
		(start 155.545536 -304.644044)
		(end 155.545536 -304.872644)
		(width 0.14478)
		(layer "In4.Cu")
		(net "M_J_CPU1_SB_DQ<23>")
	)
	(segment
		(start 178.576224 -309.110126)
		(end 181.073298 -309.110126)
		(width 0.14478)
		(layer "In4.Cu")
		(net "M_J_CPU1_SB_DQ<23>")
	)
	(segment
		(start 154.765248 -304.092356)
		(end 154.926792 -304.2539)
		(width 0.14478)
		(layer "In4.Cu")
		(net "M_J_CPU1_SB_DQ<23>")
	)
	(segment
		(start 186.635136 -308.260496)
		(end 187.060078 -308.685438)
		(width 0.14478)
		(layer "In4.Cu")
		(net "M_J_CPU1_SB_DQ<23>")
	)
	(segment
		(start 174.544228 -308.260496)
		(end 177.726594 -308.260496)
		(width 0.14478)
		(layer "In4.Cu")
		(net "M_J_CPU1_SB_DQ<23>")
	)
	(segment
		(start 134.917688 -288.343848)
		(end 134.92607 -288.339022)
		(width 0.0889)
		(layer "In4.Cu")
		(net "M_J_CPU1_SB_DQ<23>")
	)
	(segment
		(start 166.150036 -309.110634)
		(end 167.000174 -308.260496)
		(width 0.14478)
		(layer "In4.Cu")
		(net "M_J_CPU1_SB_DQ<23>")
	)
	(segment
		(start 155.569158 -304.068734)
		(end 155.730702 -304.230278)
		(width 0.14478)
		(layer "In4.Cu")
		(net "M_J_CPU1_SB_DQ<23>")
	)
	(segment
		(start 146.016726 -289.112198)
		(end 147.078446 -290.173918)
		(width 0.0889)
		(layer "In4.Cu")
		(net "M_J_CPU1_SB_DQ<23>")
	)
	(segment
		(start 145.534634 -288.23793)
		(end 146.016726 -288.720022)
		(width 0.0889)
		(layer "In4.Cu")
		(net "M_J_CPU1_SB_DQ<23>")
	)
	(segment
		(start 173.69409 -309.110634)
		(end 174.544228 -308.260496)
		(width 0.14478)
		(layer "In4.Cu")
		(net "M_J_CPU1_SB_DQ<23>")
	)
	(segment
		(start 147.889468 -290.784026)
		(end 150.72741 -293.621968)
		(width 0.14478)
		(layer "In4.Cu")
		(net "M_J_CPU1_SB_DQ<23>")
	)
	(segment
		(start 154.375104 -303.473612)
		(end 154.56027 -303.288446)
		(width 0.14478)
		(layer "In4.Cu")
		(net "M_J_CPU1_SB_DQ<23>")
	)
	(segment
		(start 142.803372 -288.339022)
		(end 142.811754 -288.343848)
		(width 0.0889)
		(layer "In4.Cu")
		(net "M_J_CPU1_SB_DQ<23>")
	)
	(segment
		(start 155.155392 -304.2539)
		(end 155.340558 -304.068734)
		(width 0.14478)
		(layer "In4.Cu")
		(net "M_J_CPU1_SB_DQ<23>")
	)
	(segment
		(start 147.27936 -290.173918)
		(end 147.889468 -290.784026)
		(width 0.0889)
		(layer "In4.Cu")
		(net "M_J_CPU1_SB_DQ<23>")
	)
	(segment
		(start 160.611058 -309.110634)
		(end 166.150036 -309.110634)
		(width 0.14478)
		(layer "In4.Cu")
		(net "M_J_CPU1_SB_DQ<23>")
	)
	(segment
		(start 155.70708 -305.034188)
		(end 155.93568 -305.034188)
		(width 0.14478)
		(layer "In4.Cu")
		(net "M_J_CPU1_SB_DQ<23>")
	)
	(segment
		(start 154.926792 -304.2539)
		(end 155.155392 -304.2539)
		(width 0.14478)
		(layer "In4.Cu")
		(net "M_J_CPU1_SB_DQ<23>")
	)
	(segment
		(start 170.18254 -308.260496)
		(end 171.032678 -309.110634)
		(width 0.14478)
		(layer "In4.Cu")
		(net "M_J_CPU1_SB_DQ<23>")
	)
	(segment
		(start 154.78887 -303.288446)
		(end 154.950414 -303.44999)
		(width 0.14478)
		(layer "In4.Cu")
		(net "M_J_CPU1_SB_DQ<23>")
	)
	(segment
		(start 154.950414 -303.44999)
		(end 154.950414 -303.67859)
		(width 0.14478)
		(layer "In4.Cu")
		(net "M_J_CPU1_SB_DQ<23>")
	)
	(segment
		(start 131.498848 -288.400744)
		(end 131.594606 -288.375344)
		(width 0.0889)
		(layer "In4.Cu")
		(net "M_J_CPU1_SB_DQ<23>")
	)
	(segment
		(start 156.349446 -304.849022)
		(end 160.611058 -309.110634)
		(width 0.14478)
		(layer "In4.Cu")
		(net "M_J_CPU1_SB_DQ<23>")
	)
	(segment
		(start 171.032678 -309.110634)
		(end 173.69409 -309.110634)
		(width 0.14478)
		(layer "In4.Cu")
		(net "M_J_CPU1_SB_DQ<23>")
	)
	(segment
		(start 155.730702 -304.230278)
		(end 155.730702 -304.458878)
		(width 0.14478)
		(layer "In4.Cu")
		(net "M_J_CPU1_SB_DQ<23>")
	)
	(segment
		(start 144.6149 -288.23793)
		(end 145.534634 -288.23793)
		(width 0.0889)
		(layer "In4.Cu")
		(net "M_J_CPU1_SB_DQ<23>")
	)
	(segment
		(start 155.340558 -304.068734)
		(end 155.569158 -304.068734)
		(width 0.14478)
		(layer "In4.Cu")
		(net "M_J_CPU1_SB_DQ<23>")
	)
	(segment
		(start 146.016726 -288.720022)
		(end 146.016726 -289.112198)
		(width 0.0889)
		(layer "In4.Cu")
		(net "M_J_CPU1_SB_DQ<23>")
	)
	(segment
		(start 143.377666 -288.343848)
		(end 143.386048 -288.339022)
		(width 0.0889)
		(layer "In4.Cu")
		(net "M_J_CPU1_SB_DQ<23>")
	)
	(segment
		(start 181.922928 -308.260496)
		(end 186.635136 -308.260496)
		(width 0.14478)
		(layer "In4.Cu")
		(net "M_J_CPU1_SB_DQ<23>")
	)
	(segment
		(start 131.34467 -288.666174)
		(end 131.498848 -288.400744)
		(width 0.0889)
		(layer "In4.Cu")
		(net "M_J_CPU1_SB_DQ<23>")
	)
	(segment
		(start 135.857742 -288.343848)
		(end 135.866124 -288.339022)
		(width 0.0889)
		(layer "In4.Cu")
		(net "M_J_CPU1_SB_DQ<23>")
	)
	(segment
		(start 154.950414 -303.67859)
		(end 154.765248 -303.863756)
		(width 0.14478)
		(layer "In4.Cu")
		(net "M_J_CPU1_SB_DQ<23>")
	)
	(segment
		(start 139.617704 -288.343848)
		(end 139.626086 -288.339022)
		(width 0.0889)
		(layer "In4.Cu")
		(net "M_J_CPU1_SB_DQ<23>")
	)
	(segment
		(start 167.000174 -308.260496)
		(end 170.18254 -308.260496)
		(width 0.14478)
		(layer "In4.Cu")
		(net "M_J_CPU1_SB_DQ<23>")
	)
	(segment
		(start 132.09778 -288.343848)
		(end 132.106162 -288.339022)
		(width 0.0889)
		(layer "In4.Cu")
		(net "M_J_CPU1_SB_DQ<23>")
	)
	(segment
		(start 150.72741 -300.054518)
		(end 154.146504 -303.473612)
		(width 0.14478)
		(layer "In4.Cu")
		(net "M_J_CPU1_SB_DQ<23>")
	)
	(segment
		(start 177.726594 -308.260496)
		(end 178.576224 -309.110126)
		(width 0.14478)
		(layer "In4.Cu")
		(net "M_J_CPU1_SB_DQ<23>")
	)
	(segment
		(start 140.557758 -288.343848)
		(end 140.56614 -288.339022)
		(width 0.0889)
		(layer "In4.Cu")
		(net "M_J_CPU1_SB_DQ<23>")
	)
	(segment
		(start 156.120846 -304.849022)
		(end 156.349446 -304.849022)
		(width 0.14478)
		(layer "In4.Cu")
		(net "M_J_CPU1_SB_DQ<23>")
	)
	(arc
		(start 139.626086 -288.339022)
		(mid 139.809594 -288.293497)
		(end 139.991846 -288.343848)
		(width 0.0889)
		(layer "In4.Cu")
		(net "M_J_CPU1_SB_DQ<23>")
	)
	(arc
		(start 138.67765 -288.343848)
		(mid 138.859901 -288.293464)
		(end 139.04341 -288.339022)
		(width 0.0889)
		(layer "In4.Cu")
		(net "M_J_CPU1_SB_DQ<23>")
	)
	(arc
		(start 139.991846 -288.343848)
		(mid 140.274802 -288.420025)
		(end 140.557758 -288.343848)
		(width 0.0889)
		(layer "In4.Cu")
		(net "M_J_CPU1_SB_DQ<23>")
	)
	(arc
		(start 131.594606 -288.375344)
		(mid 131.849928 -288.419044)
		(end 132.09778 -288.343848)
		(width 0.0889)
		(layer "In4.Cu")
		(net "M_J_CPU1_SB_DQ<23>")
	)
	(arc
		(start 133.037834 -288.343848)
		(mid 133.224778 -288.293559)
		(end 133.411722 -288.343848)
		(width 0.0889)
		(layer "In4.Cu")
		(net "M_J_CPU1_SB_DQ<23>")
	)
	(arc
		(start 134.92607 -288.339022)
		(mid 135.109578 -288.293497)
		(end 135.29183 -288.343848)
		(width 0.0889)
		(layer "In4.Cu")
		(net "M_J_CPU1_SB_DQ<23>")
	)
	(arc
		(start 142.811754 -288.343848)
		(mid 143.09471 -288.420025)
		(end 143.377666 -288.343848)
		(width 0.0889)
		(layer "In4.Cu")
		(net "M_J_CPU1_SB_DQ<23>")
	)
	(arc
		(start 136.231884 -288.343848)
		(mid 136.51484 -288.420025)
		(end 136.797796 -288.343848)
		(width 0.0889)
		(layer "In4.Cu")
		(net "M_J_CPU1_SB_DQ<23>")
	)
	(arc
		(start 139.051792 -288.343848)
		(mid 139.334748 -288.420025)
		(end 139.617704 -288.343848)
		(width 0.0889)
		(layer "In4.Cu")
		(net "M_J_CPU1_SB_DQ<23>")
	)
	(arc
		(start 133.411722 -288.343848)
		(mid 133.694678 -288.420025)
		(end 133.977634 -288.343848)
		(width 0.0889)
		(layer "In4.Cu")
		(net "M_J_CPU1_SB_DQ<23>")
	)
	(arc
		(start 135.29183 -288.343848)
		(mid 135.574786 -288.420025)
		(end 135.857742 -288.343848)
		(width 0.0889)
		(layer "In4.Cu")
		(net "M_J_CPU1_SB_DQ<23>")
	)
	(arc
		(start 140.56614 -288.339022)
		(mid 140.749648 -288.293497)
		(end 140.9319 -288.343848)
		(width 0.0889)
		(layer "In4.Cu")
		(net "M_J_CPU1_SB_DQ<23>")
	)
	(arc
		(start 140.9319 -288.343848)
		(mid 141.214856 -288.420025)
		(end 141.497812 -288.343848)
		(width 0.0889)
		(layer "In4.Cu")
		(net "M_J_CPU1_SB_DQ<23>")
	)
	(arc
		(start 141.497812 -288.343848)
		(mid 141.684756 -288.293559)
		(end 141.8717 -288.343848)
		(width 0.0889)
		(layer "In4.Cu")
		(net "M_J_CPU1_SB_DQ<23>")
	)
	(arc
		(start 143.386048 -288.339022)
		(mid 143.569556 -288.293497)
		(end 143.751808 -288.343848)
		(width 0.0889)
		(layer "In4.Cu")
		(net "M_J_CPU1_SB_DQ<23>")
	)
	(arc
		(start 141.8717 -288.343848)
		(mid 142.154656 -288.420025)
		(end 142.437612 -288.343848)
		(width 0.0889)
		(layer "In4.Cu")
		(net "M_J_CPU1_SB_DQ<23>")
	)
	(arc
		(start 132.471922 -288.343848)
		(mid 132.754878 -288.420025)
		(end 133.037834 -288.343848)
		(width 0.0889)
		(layer "In4.Cu")
		(net "M_J_CPU1_SB_DQ<23>")
	)
	(arc
		(start 136.797796 -288.343848)
		(mid 136.98474 -288.293559)
		(end 137.171684 -288.343848)
		(width 0.0889)
		(layer "In4.Cu")
		(net "M_J_CPU1_SB_DQ<23>")
	)
	(arc
		(start 143.751808 -288.343848)
		(mid 143.888244 -288.400673)
		(end 144.034764 -288.420048)
		(width 0.0889)
		(layer "In4.Cu")
		(net "M_J_CPU1_SB_DQ<23>")
	)
	(arc
		(start 142.437612 -288.343848)
		(mid 142.619863 -288.293464)
		(end 142.803372 -288.339022)
		(width 0.0889)
		(layer "In4.Cu")
		(net "M_J_CPU1_SB_DQ<23>")
	)
	(arc
		(start 135.866124 -288.339022)
		(mid 136.049632 -288.293497)
		(end 136.231884 -288.343848)
		(width 0.0889)
		(layer "In4.Cu")
		(net "M_J_CPU1_SB_DQ<23>")
	)
	(arc
		(start 133.977634 -288.343848)
		(mid 134.159885 -288.293464)
		(end 134.343394 -288.339022)
		(width 0.0889)
		(layer "In4.Cu")
		(net "M_J_CPU1_SB_DQ<23>")
	)
	(arc
		(start 137.737596 -288.343848)
		(mid 137.919847 -288.293464)
		(end 138.103356 -288.339022)
		(width 0.0889)
		(layer "In4.Cu")
		(net "M_J_CPU1_SB_DQ<23>")
	)
	(arc
		(start 134.351776 -288.343848)
		(mid 134.634732 -288.420025)
		(end 134.917688 -288.343848)
		(width 0.0889)
		(layer "In4.Cu")
		(net "M_J_CPU1_SB_DQ<23>")
	)
	(arc
		(start 137.171684 -288.343848)
		(mid 137.45464 -288.420025)
		(end 137.737596 -288.343848)
		(width 0.0889)
		(layer "In4.Cu")
		(net "M_J_CPU1_SB_DQ<23>")
	)
	(arc
		(start 144.034764 -288.420048)
		(mid 144.338787 -288.373445)
		(end 144.6149 -288.23793)
		(width 0.0889)
		(layer "In4.Cu")
		(net "M_J_CPU1_SB_DQ<23>")
	)
	(arc
		(start 138.111738 -288.343848)
		(mid 138.394694 -288.420025)
		(end 138.67765 -288.343848)
		(width 0.0889)
		(layer "In4.Cu")
		(net "M_J_CPU1_SB_DQ<23>")
	)
	(arc
		(start 132.106162 -288.339022)
		(mid 132.28967 -288.293497)
		(end 132.471922 -288.343848)
		(width 0.0889)
		(layer "In4.Cu")
		(net "M_J_CPU1_SB_DQ<23>")
	)
	(segment
		(start 132.287772 -287.590484)
		(end 132.754878 -287.856422)
		(width 0.10668)
		(layer "F.Cu")
		(net "M_J_CPU1_SB_DQ<22>")
	)
	(segment
		(start 181.246526 -307.410104)
		(end 182.096156 -306.560474)
		(width 0.14478)
		(layer "In4.Cu")
		(net "M_J_CPU1_SB_DQ<22>")
	)
	(segment
		(start 182.096156 -306.560474)
		(end 186.635136 -306.560474)
		(width 0.14478)
		(layer "In4.Cu")
		(net "M_J_CPU1_SB_DQ<22>")
	)
	(segment
		(start 154.127962 -301.088552)
		(end 154.290014 -301.250604)
		(width 0.14478)
		(layer "In4.Cu")
		(net "M_J_CPU1_SB_DQ<22>")
	)
	(segment
		(start 152.800558 -300.627034)
		(end 153.119582 -300.308264)
		(width 0.14478)
		(layer "In4.Cu")
		(net "M_J_CPU1_SB_DQ<22>")
	)
	(segment
		(start 145.09369 -287.641284)
		(end 145.643346 -287.641284)
		(width 0.0889)
		(layer "In4.Cu")
		(net "M_J_CPU1_SB_DQ<22>")
	)
	(segment
		(start 132.754878 -287.856422)
		(end 132.908802 -287.590992)
		(width 0.0889)
		(layer "In4.Cu")
		(net "M_J_CPU1_SB_DQ<22>")
	)
	(segment
		(start 152.572466 -300.627034)
		(end 152.800558 -300.627034)
		(width 0.14478)
		(layer "In4.Cu")
		(net "M_J_CPU1_SB_DQ<22>")
	)
	(segment
		(start 151.630126 -299.684694)
		(end 151.792178 -299.846746)
		(width 0.14478)
		(layer "In4.Cu")
		(net "M_J_CPU1_SB_DQ<22>")
	)
	(segment
		(start 153.97099 -302.025558)
		(end 154.133042 -302.18761)
		(width 0.14478)
		(layer "In4.Cu")
		(net "M_J_CPU1_SB_DQ<22>")
	)
	(segment
		(start 144.727422 -287.483042)
		(end 145.09369 -287.641284)
		(width 0.0889)
		(layer "In4.Cu")
		(net "M_J_CPU1_SB_DQ<22>")
	)
	(segment
		(start 186.635136 -306.560474)
		(end 187.060078 -306.985416)
		(width 0.14478)
		(layer "In4.Cu")
		(net "M_J_CPU1_SB_DQ<22>")
	)
	(segment
		(start 146.767042 -288.375344)
		(end 147.589748 -289.19805)
		(width 0.0889)
		(layer "In4.Cu")
		(net "M_J_CPU1_SB_DQ<22>")
	)
	(segment
		(start 177.51679 -306.560474)
		(end 178.36642 -307.410104)
		(width 0.14478)
		(layer "In4.Cu")
		(net "M_J_CPU1_SB_DQ<22>")
	)
	(segment
		(start 152.410414 -300.464982)
		(end 152.572466 -300.627034)
		(width 0.14478)
		(layer "In4.Cu")
		(net "M_J_CPU1_SB_DQ<22>")
	)
	(segment
		(start 153.97099 -301.797466)
		(end 153.97099 -302.025558)
		(width 0.14478)
		(layer "In4.Cu")
		(net "M_J_CPU1_SB_DQ<22>")
	)
	(segment
		(start 151.62657 -293.234872)
		(end 151.62657 -298.58716)
		(width 0.14478)
		(layer "In4.Cu")
		(net "M_J_CPU1_SB_DQ<22>")
	)
	(segment
		(start 154.361134 -302.18761)
		(end 154.680158 -301.86884)
		(width 0.14478)
		(layer "In4.Cu")
		(net "M_J_CPU1_SB_DQ<22>")
	)
	(segment
		(start 144.034764 -287.483042)
		(end 144.727422 -287.483042)
		(width 0.0889)
		(layer "In4.Cu")
		(net "M_J_CPU1_SB_DQ<22>")
	)
	(segment
		(start 152.729438 -299.690028)
		(end 152.729438 -299.91812)
		(width 0.14478)
		(layer "In4.Cu")
		(net "M_J_CPU1_SB_DQ<22>")
	)
	(segment
		(start 170.701462 -307.410612)
		(end 173.69409 -307.410612)
		(width 0.14478)
		(layer "In4.Cu")
		(net "M_J_CPU1_SB_DQ<22>")
	)
	(segment
		(start 152.567386 -299.527976)
		(end 152.729438 -299.690028)
		(width 0.14478)
		(layer "In4.Cu")
		(net "M_J_CPU1_SB_DQ<22>")
	)
	(segment
		(start 145.643346 -287.641284)
		(end 146.377406 -288.375344)
		(width 0.0889)
		(layer "In4.Cu")
		(net "M_J_CPU1_SB_DQ<22>")
	)
	(segment
		(start 153.190702 -301.24527)
		(end 153.352754 -301.407322)
		(width 0.14478)
		(layer "In4.Cu")
		(net "M_J_CPU1_SB_DQ<22>")
	)
	(segment
		(start 174.544228 -306.560474)
		(end 177.51679 -306.560474)
		(width 0.14478)
		(layer "In4.Cu")
		(net "M_J_CPU1_SB_DQ<22>")
	)
	(segment
		(start 154.290014 -301.250604)
		(end 154.290014 -301.478696)
		(width 0.14478)
		(layer "In4.Cu")
		(net "M_J_CPU1_SB_DQ<22>")
	)
	(segment
		(start 166.150036 -307.410612)
		(end 167.000174 -306.560474)
		(width 0.14478)
		(layer "In4.Cu")
		(net "M_J_CPU1_SB_DQ<22>")
	)
	(segment
		(start 151.792178 -299.846746)
		(end 152.02027 -299.846746)
		(width 0.14478)
		(layer "In4.Cu")
		(net "M_J_CPU1_SB_DQ<22>")
	)
	(segment
		(start 146.377406 -288.375344)
		(end 146.767042 -288.375344)
		(width 0.0889)
		(layer "In4.Cu")
		(net "M_J_CPU1_SB_DQ<22>")
	)
	(segment
		(start 147.589748 -289.19805)
		(end 151.62657 -293.234872)
		(width 0.14478)
		(layer "In4.Cu")
		(net "M_J_CPU1_SB_DQ<22>")
	)
	(segment
		(start 136.693402 -287.529016)
		(end 136.701784 -287.533842)
		(width 0.0889)
		(layer "In4.Cu")
		(net "M_J_CPU1_SB_DQ<22>")
	)
	(segment
		(start 173.69409 -307.410612)
		(end 174.544228 -306.560474)
		(width 0.14478)
		(layer "In4.Cu")
		(net "M_J_CPU1_SB_DQ<22>")
	)
	(segment
		(start 154.680158 -301.86884)
		(end 154.90825 -301.86884)
		(width 0.14478)
		(layer "In4.Cu")
		(net "M_J_CPU1_SB_DQ<22>")
	)
	(segment
		(start 152.729438 -299.91812)
		(end 152.410414 -300.23689)
		(width 0.14478)
		(layer "In4.Cu")
		(net "M_J_CPU1_SB_DQ<22>")
	)
	(segment
		(start 178.36642 -307.410104)
		(end 181.246526 -307.410104)
		(width 0.14478)
		(layer "In4.Cu")
		(net "M_J_CPU1_SB_DQ<22>")
	)
	(segment
		(start 153.119582 -300.308264)
		(end 153.347674 -300.308264)
		(width 0.14478)
		(layer "In4.Cu")
		(net "M_J_CPU1_SB_DQ<22>")
	)
	(segment
		(start 135.753348 -287.529016)
		(end 135.76173 -287.533842)
		(width 0.0889)
		(layer "In4.Cu")
		(net "M_J_CPU1_SB_DQ<22>")
	)
	(segment
		(start 169.851324 -306.560474)
		(end 170.701462 -307.410612)
		(width 0.14478)
		(layer "In4.Cu")
		(net "M_J_CPU1_SB_DQ<22>")
	)
	(segment
		(start 154.90825 -301.86884)
		(end 160.450022 -307.410612)
		(width 0.14478)
		(layer "In4.Cu")
		(net "M_J_CPU1_SB_DQ<22>")
	)
	(segment
		(start 153.89987 -301.088552)
		(end 154.127962 -301.088552)
		(width 0.14478)
		(layer "In4.Cu")
		(net "M_J_CPU1_SB_DQ<22>")
	)
	(segment
		(start 151.62657 -298.58716)
		(end 151.94915 -298.90974)
		(width 0.14478)
		(layer "In4.Cu")
		(net "M_J_CPU1_SB_DQ<22>")
	)
	(segment
		(start 152.339294 -299.527976)
		(end 152.567386 -299.527976)
		(width 0.14478)
		(layer "In4.Cu")
		(net "M_J_CPU1_SB_DQ<22>")
	)
	(segment
		(start 153.509726 -300.470316)
		(end 153.509726 -300.698408)
		(width 0.14478)
		(layer "In4.Cu")
		(net "M_J_CPU1_SB_DQ<22>")
	)
	(segment
		(start 141.393418 -287.529016)
		(end 141.4018 -287.533842)
		(width 0.0889)
		(layer "In4.Cu")
		(net "M_J_CPU1_SB_DQ<22>")
	)
	(segment
		(start 154.290014 -301.478696)
		(end 153.97099 -301.797466)
		(width 0.14478)
		(layer "In4.Cu")
		(net "M_J_CPU1_SB_DQ<22>")
	)
	(segment
		(start 132.908802 -287.590992)
		(end 133.004814 -287.565592)
		(width 0.0889)
		(layer "In4.Cu")
		(net "M_J_CPU1_SB_DQ<22>")
	)
	(segment
		(start 151.94915 -299.137832)
		(end 151.630126 -299.456602)
		(width 0.14478)
		(layer "In4.Cu")
		(net "M_J_CPU1_SB_DQ<22>")
	)
	(segment
		(start 160.450022 -307.410612)
		(end 166.150036 -307.410612)
		(width 0.14478)
		(layer "In4.Cu")
		(net "M_J_CPU1_SB_DQ<22>")
	)
	(segment
		(start 153.352754 -301.407322)
		(end 153.580846 -301.407322)
		(width 0.14478)
		(layer "In4.Cu")
		(net "M_J_CPU1_SB_DQ<22>")
	)
	(segment
		(start 152.410414 -300.23689)
		(end 152.410414 -300.464982)
		(width 0.14478)
		(layer "In4.Cu")
		(net "M_J_CPU1_SB_DQ<22>")
	)
	(segment
		(start 151.94915 -298.90974)
		(end 151.94915 -299.137832)
		(width 0.14478)
		(layer "In4.Cu")
		(net "M_J_CPU1_SB_DQ<22>")
	)
	(segment
		(start 153.190702 -301.017178)
		(end 153.190702 -301.24527)
		(width 0.14478)
		(layer "In4.Cu")
		(net "M_J_CPU1_SB_DQ<22>")
	)
	(segment
		(start 154.133042 -302.18761)
		(end 154.361134 -302.18761)
		(width 0.14478)
		(layer "In4.Cu")
		(net "M_J_CPU1_SB_DQ<22>")
	)
	(segment
		(start 153.509726 -300.698408)
		(end 153.190702 -301.017178)
		(width 0.14478)
		(layer "In4.Cu")
		(net "M_J_CPU1_SB_DQ<22>")
	)
	(segment
		(start 133.507734 -287.533842)
		(end 133.516116 -287.529016)
		(width 0.0889)
		(layer "In4.Cu")
		(net "M_J_CPU1_SB_DQ<22>")
	)
	(segment
		(start 138.20775 -287.533842)
		(end 138.216132 -287.529016)
		(width 0.0889)
		(layer "In4.Cu")
		(net "M_J_CPU1_SB_DQ<22>")
	)
	(segment
		(start 153.580846 -301.407322)
		(end 153.89987 -301.088552)
		(width 0.14478)
		(layer "In4.Cu")
		(net "M_J_CPU1_SB_DQ<22>")
	)
	(segment
		(start 141.967712 -287.533842)
		(end 141.976094 -287.529016)
		(width 0.0889)
		(layer "In4.Cu")
		(net "M_J_CPU1_SB_DQ<22>")
	)
	(segment
		(start 140.453364 -287.529016)
		(end 140.461746 -287.533842)
		(width 0.0889)
		(layer "In4.Cu")
		(net "M_J_CPU1_SB_DQ<22>")
	)
	(segment
		(start 152.02027 -299.846746)
		(end 152.339294 -299.527976)
		(width 0.14478)
		(layer "In4.Cu")
		(net "M_J_CPU1_SB_DQ<22>")
	)
	(segment
		(start 137.267696 -287.533842)
		(end 137.276078 -287.529016)
		(width 0.0889)
		(layer "In4.Cu")
		(net "M_J_CPU1_SB_DQ<22>")
	)
	(segment
		(start 153.347674 -300.308264)
		(end 153.509726 -300.470316)
		(width 0.14478)
		(layer "In4.Cu")
		(net "M_J_CPU1_SB_DQ<22>")
	)
	(segment
		(start 151.630126 -299.456602)
		(end 151.630126 -299.684694)
		(width 0.14478)
		(layer "In4.Cu")
		(net "M_J_CPU1_SB_DQ<22>")
	)
	(segment
		(start 167.000174 -306.560474)
		(end 169.851324 -306.560474)
		(width 0.14478)
		(layer "In4.Cu")
		(net "M_J_CPU1_SB_DQ<22>")
	)
	(arc
		(start 142.341854 -287.533842)
		(mid 142.62481 -287.609985)
		(end 142.907766 -287.533842)
		(width 0.0889)
		(layer "In4.Cu")
		(net "M_J_CPU1_SB_DQ<22>")
	)
	(arc
		(start 134.821676 -287.533842)
		(mid 135.104632 -287.609985)
		(end 135.387588 -287.533842)
		(width 0.0889)
		(layer "In4.Cu")
		(net "M_J_CPU1_SB_DQ<22>")
	)
	(arc
		(start 133.004814 -287.565592)
		(mid 133.260022 -287.609049)
		(end 133.507734 -287.533842)
		(width 0.0889)
		(layer "In4.Cu")
		(net "M_J_CPU1_SB_DQ<22>")
	)
	(arc
		(start 143.281654 -287.533842)
		(mid 143.56461 -287.609985)
		(end 143.847566 -287.533842)
		(width 0.0889)
		(layer "In4.Cu")
		(net "M_J_CPU1_SB_DQ<22>")
	)
	(arc
		(start 136.701784 -287.533842)
		(mid 136.98474 -287.609985)
		(end 137.267696 -287.533842)
		(width 0.0889)
		(layer "In4.Cu")
		(net "M_J_CPU1_SB_DQ<22>")
	)
	(arc
		(start 141.976094 -287.529016)
		(mid 142.159602 -287.483522)
		(end 142.341854 -287.533842)
		(width 0.0889)
		(layer "In4.Cu")
		(net "M_J_CPU1_SB_DQ<22>")
	)
	(arc
		(start 139.521692 -287.533842)
		(mid 139.804648 -287.609985)
		(end 140.087604 -287.533842)
		(width 0.0889)
		(layer "In4.Cu")
		(net "M_J_CPU1_SB_DQ<22>")
	)
	(arc
		(start 137.276078 -287.529016)
		(mid 137.459586 -287.483522)
		(end 137.641838 -287.533842)
		(width 0.0889)
		(layer "In4.Cu")
		(net "M_J_CPU1_SB_DQ<22>")
	)
	(arc
		(start 133.516116 -287.529016)
		(mid 133.699624 -287.483522)
		(end 133.881876 -287.533842)
		(width 0.0889)
		(layer "In4.Cu")
		(net "M_J_CPU1_SB_DQ<22>")
	)
	(arc
		(start 134.447788 -287.533842)
		(mid 134.634732 -287.483587)
		(end 134.821676 -287.533842)
		(width 0.0889)
		(layer "In4.Cu")
		(net "M_J_CPU1_SB_DQ<22>")
	)
	(arc
		(start 141.027658 -287.533842)
		(mid 141.209909 -287.483492)
		(end 141.393418 -287.529016)
		(width 0.0889)
		(layer "In4.Cu")
		(net "M_J_CPU1_SB_DQ<22>")
	)
	(arc
		(start 137.641838 -287.533842)
		(mid 137.924794 -287.609985)
		(end 138.20775 -287.533842)
		(width 0.0889)
		(layer "In4.Cu")
		(net "M_J_CPU1_SB_DQ<22>")
	)
	(arc
		(start 143.847566 -287.533842)
		(mid 143.937806 -287.496065)
		(end 144.034764 -287.483042)
		(width 0.0889)
		(layer "In4.Cu")
		(net "M_J_CPU1_SB_DQ<22>")
	)
	(arc
		(start 136.327642 -287.533842)
		(mid 136.509893 -287.483492)
		(end 136.693402 -287.529016)
		(width 0.0889)
		(layer "In4.Cu")
		(net "M_J_CPU1_SB_DQ<22>")
	)
	(arc
		(start 140.087604 -287.533842)
		(mid 140.269855 -287.483492)
		(end 140.453364 -287.529016)
		(width 0.0889)
		(layer "In4.Cu")
		(net "M_J_CPU1_SB_DQ<22>")
	)
	(arc
		(start 138.581892 -287.533842)
		(mid 138.864848 -287.609985)
		(end 139.147804 -287.533842)
		(width 0.0889)
		(layer "In4.Cu")
		(net "M_J_CPU1_SB_DQ<22>")
	)
	(arc
		(start 141.4018 -287.533842)
		(mid 141.684756 -287.609985)
		(end 141.967712 -287.533842)
		(width 0.0889)
		(layer "In4.Cu")
		(net "M_J_CPU1_SB_DQ<22>")
	)
	(arc
		(start 133.881876 -287.533842)
		(mid 134.164832 -287.609985)
		(end 134.447788 -287.533842)
		(width 0.0889)
		(layer "In4.Cu")
		(net "M_J_CPU1_SB_DQ<22>")
	)
	(arc
		(start 138.216132 -287.529016)
		(mid 138.39964 -287.483522)
		(end 138.581892 -287.533842)
		(width 0.0889)
		(layer "In4.Cu")
		(net "M_J_CPU1_SB_DQ<22>")
	)
	(arc
		(start 139.147804 -287.533842)
		(mid 139.334748 -287.483587)
		(end 139.521692 -287.533842)
		(width 0.0889)
		(layer "In4.Cu")
		(net "M_J_CPU1_SB_DQ<22>")
	)
	(arc
		(start 135.76173 -287.533842)
		(mid 136.044686 -287.609985)
		(end 136.327642 -287.533842)
		(width 0.0889)
		(layer "In4.Cu")
		(net "M_J_CPU1_SB_DQ<22>")
	)
	(arc
		(start 140.461746 -287.533842)
		(mid 140.744702 -287.609985)
		(end 141.027658 -287.533842)
		(width 0.0889)
		(layer "In4.Cu")
		(net "M_J_CPU1_SB_DQ<22>")
	)
	(arc
		(start 135.387588 -287.533842)
		(mid 135.569839 -287.483492)
		(end 135.753348 -287.529016)
		(width 0.0889)
		(layer "In4.Cu")
		(net "M_J_CPU1_SB_DQ<22>")
	)
	(arc
		(start 142.907766 -287.533842)
		(mid 143.09471 -287.483587)
		(end 143.281654 -287.533842)
		(width 0.0889)
		(layer "In4.Cu")
		(net "M_J_CPU1_SB_DQ<22>")
	)
	(segment
		(start 131.347972 -287.590484)
		(end 131.814824 -287.856422)
		(width 0.10668)
		(layer "F.Cu")
		(net "M_J_CPU1_SB_DQ<21>")
	)
	(segment
		(start 132.93344 -288.183574)
		(end 132.941822 -288.178748)
		(width 0.0889)
		(layer "In4.Cu")
		(net "M_J_CPU1_SB_DQ<21>")
	)
	(segment
		(start 147.589494 -289.840924)
		(end 147.866354 -290.117784)
		(width 0.0889)
		(layer "In4.Cu")
		(net "M_J_CPU1_SB_DQ<21>")
	)
	(segment
		(start 171.538392 -308.260496)
		(end 173.152054 -308.260496)
		(width 0.14478)
		(layer "In4.Cu")
		(net "M_J_CPU1_SB_DQ<21>")
	)
	(segment
		(start 137.267696 -288.178748)
		(end 137.276078 -288.183574)
		(width 0.0889)
		(layer "In4.Cu")
		(net "M_J_CPU1_SB_DQ<21>")
	)
	(segment
		(start 145.587212 -287.96361)
		(end 146.280886 -288.657284)
		(width 0.0889)
		(layer "In4.Cu")
		(net "M_J_CPU1_SB_DQ<21>")
	)
	(segment
		(start 160.28035 -307.876956)
		(end 161.206434 -308.260496)
		(width 0.14478)
		(layer "In4.Cu")
		(net "M_J_CPU1_SB_DQ<21>")
	)
	(segment
		(start 180.553868 -308.260242)
		(end 182.60568 -307.410358)
		(width 0.14478)
		(layer "In4.Cu")
		(net "M_J_CPU1_SB_DQ<21>")
	)
	(segment
		(start 155.040584 -302.63719)
		(end 160.28035 -307.876956)
		(width 0.14478)
		(layer "In4.Cu")
		(net "M_J_CPU1_SB_DQ<21>")
	)
	(segment
		(start 182.60568 -307.410358)
		(end 189.023752 -307.410358)
		(width 0.14478)
		(layer "In4.Cu")
		(net "M_J_CPU1_SB_DQ<21>")
	)
	(segment
		(start 131.660646 -288.121852)
		(end 131.682744 -288.20491)
		(width 0.0889)
		(layer "In4.Cu")
		(net "M_J_CPU1_SB_DQ<21>")
	)
	(segment
		(start 165.443916 -308.260496)
		(end 167.495728 -307.410612)
		(width 0.14478)
		(layer "In4.Cu")
		(net "M_J_CPU1_SB_DQ<21>")
	)
	(segment
		(start 175.203866 -307.410612)
		(end 176.947322 -307.410612)
		(width 0.14478)
		(layer "In4.Cu")
		(net "M_J_CPU1_SB_DQ<21>")
	)
	(segment
		(start 146.280886 -289.002724)
		(end 147.119086 -289.840924)
		(width 0.0889)
		(layer "In4.Cu")
		(net "M_J_CPU1_SB_DQ<21>")
	)
	(segment
		(start 161.206434 -308.260496)
		(end 165.443916 -308.260496)
		(width 0.14478)
		(layer "In4.Cu")
		(net "M_J_CPU1_SB_DQ<21>")
	)
	(segment
		(start 141.967712 -288.178748)
		(end 141.976094 -288.183574)
		(width 0.0889)
		(layer "In4.Cu")
		(net "M_J_CPU1_SB_DQ<21>")
	)
	(segment
		(start 141.393418 -288.183574)
		(end 141.4018 -288.178748)
		(width 0.0889)
		(layer "In4.Cu")
		(net "M_J_CPU1_SB_DQ<21>")
	)
	(segment
		(start 169.48658 -307.410612)
		(end 171.538392 -308.260496)
		(width 0.14478)
		(layer "In4.Cu")
		(net "M_J_CPU1_SB_DQ<21>")
	)
	(segment
		(start 133.507734 -288.178748)
		(end 133.516116 -288.183574)
		(width 0.0889)
		(layer "In4.Cu")
		(net "M_J_CPU1_SB_DQ<21>")
	)
	(segment
		(start 131.993386 -288.183574)
		(end 132.001768 -288.178748)
		(width 0.0889)
		(layer "In4.Cu")
		(net "M_J_CPU1_SB_DQ<21>")
	)
	(segment
		(start 151.17699 -293.42842)
		(end 151.17699 -299.867828)
		(width 0.14478)
		(layer "In4.Cu")
		(net "M_J_CPU1_SB_DQ<21>")
	)
	(segment
		(start 176.947322 -307.410612)
		(end 178.998626 -308.260242)
		(width 0.14478)
		(layer "In4.Cu")
		(net "M_J_CPU1_SB_DQ<21>")
	)
	(segment
		(start 131.814824 -287.856422)
		(end 131.660646 -288.121852)
		(width 0.0889)
		(layer "In4.Cu")
		(net "M_J_CPU1_SB_DQ<21>")
	)
	(segment
		(start 189.023752 -307.410358)
		(end 191.160146 -307.8353)
		(width 0.14478)
		(layer "In4.Cu")
		(net "M_J_CPU1_SB_DQ<21>")
	)
	(segment
		(start 147.119086 -289.840924)
		(end 147.589494 -289.840924)
		(width 0.0889)
		(layer "In4.Cu")
		(net "M_J_CPU1_SB_DQ<21>")
	)
	(segment
		(start 144.460976 -288.087054)
		(end 144.58442 -287.96361)
		(width 0.0889)
		(layer "In4.Cu")
		(net "M_J_CPU1_SB_DQ<21>")
	)
	(segment
		(start 151.17699 -299.867828)
		(end 153.946352 -302.63719)
		(width 0.14478)
		(layer "In4.Cu")
		(net "M_J_CPU1_SB_DQ<21>")
	)
	(segment
		(start 147.866354 -290.117784)
		(end 151.17699 -293.42842)
		(width 0.14478)
		(layer "In4.Cu")
		(net "M_J_CPU1_SB_DQ<21>")
	)
	(segment
		(start 153.946352 -302.63719)
		(end 155.040584 -302.63719)
		(width 0.14478)
		(layer "In4.Cu")
		(net "M_J_CPU1_SB_DQ<21>")
	)
	(segment
		(start 173.152054 -308.260496)
		(end 175.203866 -307.410612)
		(width 0.14478)
		(layer "In4.Cu")
		(net "M_J_CPU1_SB_DQ<21>")
	)
	(segment
		(start 167.495728 -307.410612)
		(end 169.48658 -307.410612)
		(width 0.14478)
		(layer "In4.Cu")
		(net "M_J_CPU1_SB_DQ<21>")
	)
	(segment
		(start 146.280886 -288.657284)
		(end 146.280886 -289.002724)
		(width 0.0889)
		(layer "In4.Cu")
		(net "M_J_CPU1_SB_DQ<21>")
	)
	(segment
		(start 138.20775 -288.178748)
		(end 138.216132 -288.183574)
		(width 0.0889)
		(layer "In4.Cu")
		(net "M_J_CPU1_SB_DQ<21>")
	)
	(segment
		(start 144.58442 -287.96361)
		(end 145.587212 -287.96361)
		(width 0.0889)
		(layer "In4.Cu")
		(net "M_J_CPU1_SB_DQ<21>")
	)
	(segment
		(start 140.453364 -288.183574)
		(end 140.461746 -288.178748)
		(width 0.0889)
		(layer "In4.Cu")
		(net "M_J_CPU1_SB_DQ<21>")
	)
	(segment
		(start 178.998626 -308.260242)
		(end 180.553868 -308.260242)
		(width 0.14478)
		(layer "In4.Cu")
		(net "M_J_CPU1_SB_DQ<21>")
	)
	(segment
		(start 136.693402 -288.183574)
		(end 136.701784 -288.178748)
		(width 0.0889)
		(layer "In4.Cu")
		(net "M_J_CPU1_SB_DQ<21>")
	)
	(segment
		(start 135.753348 -288.183574)
		(end 135.76173 -288.178748)
		(width 0.0889)
		(layer "In4.Cu")
		(net "M_J_CPU1_SB_DQ<21>")
	)
	(arc
		(start 132.56768 -288.178748)
		(mid 132.749931 -288.229132)
		(end 132.93344 -288.183574)
		(width 0.0889)
		(layer "In4.Cu")
		(net "M_J_CPU1_SB_DQ<21>")
	)
	(arc
		(start 141.976094 -288.183574)
		(mid 142.159602 -288.229099)
		(end 142.341854 -288.178748)
		(width 0.0889)
		(layer "In4.Cu")
		(net "M_J_CPU1_SB_DQ<21>")
	)
	(arc
		(start 138.581892 -288.178748)
		(mid 138.864848 -288.102571)
		(end 139.147804 -288.178748)
		(width 0.0889)
		(layer "In4.Cu")
		(net "M_J_CPU1_SB_DQ<21>")
	)
	(arc
		(start 140.461746 -288.178748)
		(mid 140.744702 -288.102571)
		(end 141.027658 -288.178748)
		(width 0.0889)
		(layer "In4.Cu")
		(net "M_J_CPU1_SB_DQ<21>")
	)
	(arc
		(start 137.641838 -288.178748)
		(mid 137.924794 -288.102571)
		(end 138.20775 -288.178748)
		(width 0.0889)
		(layer "In4.Cu")
		(net "M_J_CPU1_SB_DQ<21>")
	)
	(arc
		(start 137.276078 -288.183574)
		(mid 137.459586 -288.229099)
		(end 137.641838 -288.178748)
		(width 0.0889)
		(layer "In4.Cu")
		(net "M_J_CPU1_SB_DQ<21>")
	)
	(arc
		(start 136.701784 -288.178748)
		(mid 136.98474 -288.102571)
		(end 137.267696 -288.178748)
		(width 0.0889)
		(layer "In4.Cu")
		(net "M_J_CPU1_SB_DQ<21>")
	)
	(arc
		(start 142.341854 -288.178748)
		(mid 142.62481 -288.102571)
		(end 142.907766 -288.178748)
		(width 0.0889)
		(layer "In4.Cu")
		(net "M_J_CPU1_SB_DQ<21>")
	)
	(arc
		(start 139.521692 -288.178748)
		(mid 139.804648 -288.102571)
		(end 140.087604 -288.178748)
		(width 0.0889)
		(layer "In4.Cu")
		(net "M_J_CPU1_SB_DQ<21>")
	)
	(arc
		(start 131.682744 -288.20491)
		(mid 131.840395 -288.228222)
		(end 131.993386 -288.183574)
		(width 0.0889)
		(layer "In4.Cu")
		(net "M_J_CPU1_SB_DQ<21>")
	)
	(arc
		(start 133.881876 -288.178748)
		(mid 134.164832 -288.102571)
		(end 134.447788 -288.178748)
		(width 0.0889)
		(layer "In4.Cu")
		(net "M_J_CPU1_SB_DQ<21>")
	)
	(arc
		(start 139.147804 -288.178748)
		(mid 139.334748 -288.229037)
		(end 139.521692 -288.178748)
		(width 0.0889)
		(layer "In4.Cu")
		(net "M_J_CPU1_SB_DQ<21>")
	)
	(arc
		(start 135.76173 -288.178748)
		(mid 136.044686 -288.102571)
		(end 136.327642 -288.178748)
		(width 0.0889)
		(layer "In4.Cu")
		(net "M_J_CPU1_SB_DQ<21>")
	)
	(arc
		(start 135.387588 -288.178748)
		(mid 135.569839 -288.229132)
		(end 135.753348 -288.183574)
		(width 0.0889)
		(layer "In4.Cu")
		(net "M_J_CPU1_SB_DQ<21>")
	)
	(arc
		(start 141.4018 -288.178748)
		(mid 141.684756 -288.102571)
		(end 141.967712 -288.178748)
		(width 0.0889)
		(layer "In4.Cu")
		(net "M_J_CPU1_SB_DQ<21>")
	)
	(arc
		(start 144.034764 -288.229548)
		(mid 144.259464 -288.192981)
		(end 144.460976 -288.087054)
		(width 0.0889)
		(layer "In4.Cu")
		(net "M_J_CPU1_SB_DQ<21>")
	)
	(arc
		(start 136.327642 -288.178748)
		(mid 136.509893 -288.229132)
		(end 136.693402 -288.183574)
		(width 0.0889)
		(layer "In4.Cu")
		(net "M_J_CPU1_SB_DQ<21>")
	)
	(arc
		(start 134.447788 -288.178748)
		(mid 134.634732 -288.229037)
		(end 134.821676 -288.178748)
		(width 0.0889)
		(layer "In4.Cu")
		(net "M_J_CPU1_SB_DQ<21>")
	)
	(arc
		(start 138.216132 -288.183574)
		(mid 138.39964 -288.229099)
		(end 138.581892 -288.178748)
		(width 0.0889)
		(layer "In4.Cu")
		(net "M_J_CPU1_SB_DQ<21>")
	)
	(arc
		(start 141.027658 -288.178748)
		(mid 141.209909 -288.229132)
		(end 141.393418 -288.183574)
		(width 0.0889)
		(layer "In4.Cu")
		(net "M_J_CPU1_SB_DQ<21>")
	)
	(arc
		(start 132.941822 -288.178748)
		(mid 133.224778 -288.102571)
		(end 133.507734 -288.178748)
		(width 0.0889)
		(layer "In4.Cu")
		(net "M_J_CPU1_SB_DQ<21>")
	)
	(arc
		(start 140.087604 -288.178748)
		(mid 140.269855 -288.229132)
		(end 140.453364 -288.183574)
		(width 0.0889)
		(layer "In4.Cu")
		(net "M_J_CPU1_SB_DQ<21>")
	)
	(arc
		(start 132.001768 -288.178748)
		(mid 132.284724 -288.102571)
		(end 132.56768 -288.178748)
		(width 0.0889)
		(layer "In4.Cu")
		(net "M_J_CPU1_SB_DQ<21>")
	)
	(arc
		(start 143.281654 -288.178748)
		(mid 143.56461 -288.102571)
		(end 143.847566 -288.178748)
		(width 0.0889)
		(layer "In4.Cu")
		(net "M_J_CPU1_SB_DQ<21>")
	)
	(arc
		(start 143.847566 -288.178748)
		(mid 143.937802 -288.21655)
		(end 144.034764 -288.229548)
		(width 0.0889)
		(layer "In4.Cu")
		(net "M_J_CPU1_SB_DQ<21>")
	)
	(arc
		(start 142.907766 -288.178748)
		(mid 143.09471 -288.229037)
		(end 143.281654 -288.178748)
		(width 0.0889)
		(layer "In4.Cu")
		(net "M_J_CPU1_SB_DQ<21>")
	)
	(arc
		(start 134.821676 -288.178748)
		(mid 135.104632 -288.102571)
		(end 135.387588 -288.178748)
		(width 0.0889)
		(layer "In4.Cu")
		(net "M_J_CPU1_SB_DQ<21>")
	)
	(arc
		(start 133.516116 -288.183574)
		(mid 133.699624 -288.229099)
		(end 133.881876 -288.178748)
		(width 0.0889)
		(layer "In4.Cu")
		(net "M_J_CPU1_SB_DQ<21>")
	)
	(segment
		(start 132.757926 -286.780478)
		(end 133.224778 -287.046162)
		(width 0.10668)
		(layer "F.Cu")
		(net "M_J_CPU1_SB_DQ<20>")
	)
	(segment
		(start 139.617704 -287.368742)
		(end 139.626086 -287.373568)
		(width 0.0889)
		(layer "In4.Cu")
		(net "M_J_CPU1_SB_DQ<20>")
	)
	(segment
		(start 134.917688 -287.368742)
		(end 134.92607 -287.373568)
		(width 0.0889)
		(layer "In4.Cu")
		(net "M_J_CPU1_SB_DQ<20>")
	)
	(segment
		(start 166.243 -306.560474)
		(end 167.092884 -305.71059)
		(width 0.14478)
		(layer "In4.Cu")
		(net "M_J_CPU1_SB_DQ<20>")
	)
	(segment
		(start 173.777402 -306.570126)
		(end 174.62754 -305.719988)
		(width 0.14478)
		(layer "In4.Cu")
		(net "M_J_CPU1_SB_DQ<20>")
	)
	(segment
		(start 190.08344 -306.352702)
		(end 190.08344 -305.881532)
		(width 0.14478)
		(layer "In4.Cu")
		(net "M_J_CPU1_SB_DQ<20>")
	)
	(segment
		(start 169.75074 -305.71059)
		(end 170.610276 -306.570126)
		(width 0.14478)
		(layer "In4.Cu")
		(net "M_J_CPU1_SB_DQ<20>")
	)
	(segment
		(start 160.236154 -306.560474)
		(end 166.243 -306.560474)
		(width 0.14478)
		(layer "In4.Cu")
		(net "M_J_CPU1_SB_DQ<20>")
	)
	(segment
		(start 147.117816 -288.075624)
		(end 147.761198 -288.719006)
		(width 0.0889)
		(layer "In4.Cu")
		(net "M_J_CPU1_SB_DQ<20>")
	)
	(segment
		(start 145.823686 -287.417764)
		(end 146.481546 -288.075624)
		(width 0.0889)
		(layer "In4.Cu")
		(net "M_J_CPU1_SB_DQ<20>")
	)
	(segment
		(start 182.108348 -305.719988)
		(end 189.370462 -305.719988)
		(width 0.14478)
		(layer "In4.Cu")
		(net "M_J_CPU1_SB_DQ<20>")
	)
	(segment
		(start 147.761198 -288.719006)
		(end 152.07615 -293.033958)
		(width 0.14478)
		(layer "In4.Cu")
		(net "M_J_CPU1_SB_DQ<20>")
	)
	(segment
		(start 134.343394 -287.373568)
		(end 134.351776 -287.368742)
		(width 0.0889)
		(layer "In4.Cu")
		(net "M_J_CPU1_SB_DQ<20>")
	)
	(segment
		(start 145.15084 -287.417764)
		(end 145.823686 -287.417764)
		(width 0.0889)
		(layer "In4.Cu")
		(net "M_J_CPU1_SB_DQ<20>")
	)
	(segment
		(start 189.370462 -305.719988)
		(end 189.532006 -305.881532)
		(width 0.14478)
		(layer "In4.Cu")
		(net "M_J_CPU1_SB_DQ<20>")
	)
	(segment
		(start 174.62754 -305.719988)
		(end 177.450496 -305.719988)
		(width 0.14478)
		(layer "In4.Cu")
		(net "M_J_CPU1_SB_DQ<20>")
	)
	(segment
		(start 135.857742 -287.368742)
		(end 135.866124 -287.373568)
		(width 0.0889)
		(layer "In4.Cu")
		(net "M_J_CPU1_SB_DQ<20>")
	)
	(segment
		(start 152.07615 -298.40047)
		(end 160.236154 -306.560474)
		(width 0.14478)
		(layer "In4.Cu")
		(net "M_J_CPU1_SB_DQ<20>")
	)
	(segment
		(start 177.450496 -305.719988)
		(end 178.30038 -306.569872)
		(width 0.14478)
		(layer "In4.Cu")
		(net "M_J_CPU1_SB_DQ<20>")
	)
	(segment
		(start 190.08344 -305.881532)
		(end 190.244984 -305.719988)
		(width 0.14478)
		(layer "In4.Cu")
		(net "M_J_CPU1_SB_DQ<20>")
	)
	(segment
		(start 190.744856 -305.719988)
		(end 191.160146 -306.135278)
		(width 0.14478)
		(layer "In4.Cu")
		(net "M_J_CPU1_SB_DQ<20>")
	)
	(segment
		(start 133.224778 -287.046162)
		(end 133.070854 -287.311592)
		(width 0.0889)
		(layer "In4.Cu")
		(net "M_J_CPU1_SB_DQ<20>")
	)
	(segment
		(start 133.070854 -287.311592)
		(end 133.093206 -287.394904)
		(width 0.0889)
		(layer "In4.Cu")
		(net "M_J_CPU1_SB_DQ<20>")
	)
	(segment
		(start 189.921896 -306.514246)
		(end 190.08344 -306.352702)
		(width 0.14478)
		(layer "In4.Cu")
		(net "M_J_CPU1_SB_DQ<20>")
	)
	(segment
		(start 142.803372 -287.373568)
		(end 142.811754 -287.368742)
		(width 0.0889)
		(layer "In4.Cu")
		(net "M_J_CPU1_SB_DQ<20>")
	)
	(segment
		(start 189.532006 -306.352702)
		(end 189.69355 -306.514246)
		(width 0.14478)
		(layer "In4.Cu")
		(net "M_J_CPU1_SB_DQ<20>")
	)
	(segment
		(start 146.481546 -288.075624)
		(end 147.117816 -288.075624)
		(width 0.0889)
		(layer "In4.Cu")
		(net "M_J_CPU1_SB_DQ<20>")
	)
	(segment
		(start 189.532006 -305.881532)
		(end 189.532006 -306.352702)
		(width 0.14478)
		(layer "In4.Cu")
		(net "M_J_CPU1_SB_DQ<20>")
	)
	(segment
		(start 167.092884 -305.71059)
		(end 169.75074 -305.71059)
		(width 0.14478)
		(layer "In4.Cu")
		(net "M_J_CPU1_SB_DQ<20>")
	)
	(segment
		(start 178.30038 -306.569872)
		(end 181.258464 -306.569872)
		(width 0.14478)
		(layer "In4.Cu")
		(net "M_J_CPU1_SB_DQ<20>")
	)
	(segment
		(start 144.833594 -287.292542)
		(end 145.15084 -287.417764)
		(width 0.0889)
		(layer "In4.Cu")
		(net "M_J_CPU1_SB_DQ<20>")
	)
	(segment
		(start 144.03451 -287.292542)
		(end 144.833594 -287.292542)
		(width 0.0889)
		(layer "In4.Cu")
		(net "M_J_CPU1_SB_DQ<20>")
	)
	(segment
		(start 143.377666 -287.368742)
		(end 143.386048 -287.373568)
		(width 0.0889)
		(layer "In4.Cu")
		(net "M_J_CPU1_SB_DQ<20>")
	)
	(segment
		(start 181.258464 -306.569872)
		(end 182.108348 -305.719988)
		(width 0.14478)
		(layer "In4.Cu")
		(net "M_J_CPU1_SB_DQ<20>")
	)
	(segment
		(start 190.244984 -305.719988)
		(end 190.744856 -305.719988)
		(width 0.14478)
		(layer "In4.Cu")
		(net "M_J_CPU1_SB_DQ<20>")
	)
	(segment
		(start 189.69355 -306.514246)
		(end 189.921896 -306.514246)
		(width 0.14478)
		(layer "In4.Cu")
		(net "M_J_CPU1_SB_DQ<20>")
	)
	(segment
		(start 139.04341 -287.373568)
		(end 139.051792 -287.368742)
		(width 0.0889)
		(layer "In4.Cu")
		(net "M_J_CPU1_SB_DQ<20>")
	)
	(segment
		(start 152.07615 -293.033958)
		(end 152.07615 -298.40047)
		(width 0.14478)
		(layer "In4.Cu")
		(net "M_J_CPU1_SB_DQ<20>")
	)
	(segment
		(start 170.610276 -306.570126)
		(end 173.777402 -306.570126)
		(width 0.14478)
		(layer "In4.Cu")
		(net "M_J_CPU1_SB_DQ<20>")
	)
	(segment
		(start 138.103356 -287.373568)
		(end 138.111738 -287.368742)
		(width 0.0889)
		(layer "In4.Cu")
		(net "M_J_CPU1_SB_DQ<20>")
	)
	(segment
		(start 140.557758 -287.368742)
		(end 140.56614 -287.373568)
		(width 0.0889)
		(layer "In4.Cu")
		(net "M_J_CPU1_SB_DQ<20>")
	)
	(arc
		(start 139.051792 -287.368742)
		(mid 139.334748 -287.292599)
		(end 139.617704 -287.368742)
		(width 0.0889)
		(layer "In4.Cu")
		(net "M_J_CPU1_SB_DQ<20>")
	)
	(arc
		(start 137.737596 -287.368742)
		(mid 137.919847 -287.419092)
		(end 138.103356 -287.373568)
		(width 0.0889)
		(layer "In4.Cu")
		(net "M_J_CPU1_SB_DQ<20>")
	)
	(arc
		(start 140.9319 -287.368742)
		(mid 141.214856 -287.292599)
		(end 141.497812 -287.368742)
		(width 0.0889)
		(layer "In4.Cu")
		(net "M_J_CPU1_SB_DQ<20>")
	)
	(arc
		(start 134.92607 -287.373568)
		(mid 135.109578 -287.419062)
		(end 135.29183 -287.368742)
		(width 0.0889)
		(layer "In4.Cu")
		(net "M_J_CPU1_SB_DQ<20>")
	)
	(arc
		(start 135.866124 -287.373568)
		(mid 136.049632 -287.419062)
		(end 136.231884 -287.368742)
		(width 0.0889)
		(layer "In4.Cu")
		(net "M_J_CPU1_SB_DQ<20>")
	)
	(arc
		(start 142.811754 -287.368742)
		(mid 143.09471 -287.292599)
		(end 143.377666 -287.368742)
		(width 0.0889)
		(layer "In4.Cu")
		(net "M_J_CPU1_SB_DQ<20>")
	)
	(arc
		(start 138.67765 -287.368742)
		(mid 138.859901 -287.419092)
		(end 139.04341 -287.373568)
		(width 0.0889)
		(layer "In4.Cu")
		(net "M_J_CPU1_SB_DQ<20>")
	)
	(arc
		(start 142.437612 -287.368742)
		(mid 142.619863 -287.419092)
		(end 142.803372 -287.373568)
		(width 0.0889)
		(layer "In4.Cu")
		(net "M_J_CPU1_SB_DQ<20>")
	)
	(arc
		(start 133.411722 -287.368742)
		(mid 133.694678 -287.292599)
		(end 133.977634 -287.368742)
		(width 0.0889)
		(layer "In4.Cu")
		(net "M_J_CPU1_SB_DQ<20>")
	)
	(arc
		(start 141.497812 -287.368742)
		(mid 141.684756 -287.418997)
		(end 141.8717 -287.368742)
		(width 0.0889)
		(layer "In4.Cu")
		(net "M_J_CPU1_SB_DQ<20>")
	)
	(arc
		(start 143.386048 -287.373568)
		(mid 143.569556 -287.419062)
		(end 143.751808 -287.368742)
		(width 0.0889)
		(layer "In4.Cu")
		(net "M_J_CPU1_SB_DQ<20>")
	)
	(arc
		(start 140.56614 -287.373568)
		(mid 140.749648 -287.419062)
		(end 140.9319 -287.368742)
		(width 0.0889)
		(layer "In4.Cu")
		(net "M_J_CPU1_SB_DQ<20>")
	)
	(arc
		(start 143.751808 -287.368742)
		(mid 143.858142 -287.320978)
		(end 143.972026 -287.296098)
		(width 0.0889)
		(layer "In4.Cu")
		(net "M_J_CPU1_SB_DQ<20>")
	)
	(arc
		(start 141.8717 -287.368742)
		(mid 142.154656 -287.292599)
		(end 142.437612 -287.368742)
		(width 0.0889)
		(layer "In4.Cu")
		(net "M_J_CPU1_SB_DQ<20>")
	)
	(arc
		(start 137.171684 -287.368742)
		(mid 137.45464 -287.292599)
		(end 137.737596 -287.368742)
		(width 0.0889)
		(layer "In4.Cu")
		(net "M_J_CPU1_SB_DQ<20>")
	)
	(arc
		(start 136.797796 -287.368742)
		(mid 136.98474 -287.418997)
		(end 137.171684 -287.368742)
		(width 0.0889)
		(layer "In4.Cu")
		(net "M_J_CPU1_SB_DQ<20>")
	)
	(arc
		(start 133.093206 -287.394904)
		(mid 133.255395 -287.417639)
		(end 133.411722 -287.368742)
		(width 0.0889)
		(layer "In4.Cu")
		(net "M_J_CPU1_SB_DQ<20>")
	)
	(arc
		(start 135.29183 -287.368742)
		(mid 135.574786 -287.292599)
		(end 135.857742 -287.368742)
		(width 0.0889)
		(layer "In4.Cu")
		(net "M_J_CPU1_SB_DQ<20>")
	)
	(arc
		(start 143.972026 -287.296098)
		(mid 144.003219 -287.29345)
		(end 144.03451 -287.292542)
		(width 0.0889)
		(layer "In4.Cu")
		(net "M_J_CPU1_SB_DQ<20>")
	)
	(arc
		(start 134.351776 -287.368742)
		(mid 134.634732 -287.292599)
		(end 134.917688 -287.368742)
		(width 0.0889)
		(layer "In4.Cu")
		(net "M_J_CPU1_SB_DQ<20>")
	)
	(arc
		(start 139.991846 -287.368742)
		(mid 140.274802 -287.292599)
		(end 140.557758 -287.368742)
		(width 0.0889)
		(layer "In4.Cu")
		(net "M_J_CPU1_SB_DQ<20>")
	)
	(arc
		(start 138.111738 -287.368742)
		(mid 138.394694 -287.292599)
		(end 138.67765 -287.368742)
		(width 0.0889)
		(layer "In4.Cu")
		(net "M_J_CPU1_SB_DQ<20>")
	)
	(arc
		(start 139.626086 -287.373568)
		(mid 139.809594 -287.419062)
		(end 139.991846 -287.368742)
		(width 0.0889)
		(layer "In4.Cu")
		(net "M_J_CPU1_SB_DQ<20>")
	)
	(arc
		(start 136.231884 -287.368742)
		(mid 136.51484 -287.292599)
		(end 136.797796 -287.368742)
		(width 0.0889)
		(layer "In4.Cu")
		(net "M_J_CPU1_SB_DQ<20>")
	)
	(arc
		(start 133.977634 -287.368742)
		(mid 134.159885 -287.419092)
		(end 134.343394 -287.373568)
		(width 0.0889)
		(layer "In4.Cu")
		(net "M_J_CPU1_SB_DQ<20>")
	)
	(segment
		(start 131.347972 -274.630388)
		(end 131.814824 -274.896326)
		(width 0.10668)
		(layer "F.Cu")
		(net "M_J_CPU1_SB_DQ<1>")
	)
	(segment
		(start 137.267696 -275.218906)
		(end 137.276078 -275.223732)
		(width 0.0889)
		(layer "In4.Cu")
		(net "M_J_CPU1_SB_DQ<1>")
	)
	(segment
		(start 147.497546 -273.849084)
		(end 148.060918 -273.849084)
		(width 0.0889)
		(layer "In4.Cu")
		(net "M_J_CPU1_SB_DQ<1>")
	)
	(segment
		(start 144.777968 -275.21281)
		(end 144.788382 -275.218906)
		(width 0.0889)
		(layer "In4.Cu")
		(net "M_J_CPU1_SB_DQ<1>")
	)
	(segment
		(start 189.023752 -282.76042)
		(end 191.160146 -283.185362)
		(width 0.14478)
		(layer "In4.Cu")
		(net "M_J_CPU1_SB_DQ<1>")
	)
	(segment
		(start 172.983906 -283.610304)
		(end 175.035718 -282.76042)
		(width 0.14478)
		(layer "In4.Cu")
		(net "M_J_CPU1_SB_DQ<1>")
	)
	(segment
		(start 131.660646 -275.161756)
		(end 131.682998 -275.245068)
		(width 0.0889)
		(layer "In4.Cu")
		(net "M_J_CPU1_SB_DQ<1>")
	)
	(segment
		(start 180.38318 -283.610304)
		(end 182.434992 -282.76042)
		(width 0.14478)
		(layer "In4.Cu")
		(net "M_J_CPU1_SB_DQ<1>")
	)
	(segment
		(start 176.99482 -282.76042)
		(end 179.046632 -283.610304)
		(width 0.14478)
		(layer "In4.Cu")
		(net "M_J_CPU1_SB_DQ<1>")
	)
	(segment
		(start 169.530522 -282.76042)
		(end 171.582334 -283.610304)
		(width 0.14478)
		(layer "In4.Cu")
		(net "M_J_CPU1_SB_DQ<1>")
	)
	(segment
		(start 166.825676 -282.76042)
		(end 169.530522 -282.76042)
		(width 0.14478)
		(layer "In4.Cu")
		(net "M_J_CPU1_SB_DQ<1>")
	)
	(segment
		(start 133.507734 -275.218906)
		(end 133.516116 -275.223732)
		(width 0.0889)
		(layer "In4.Cu")
		(net "M_J_CPU1_SB_DQ<1>")
	)
	(segment
		(start 145.734532 -274.98802)
		(end 145.824448 -274.927822)
		(width 0.0889)
		(layer "In4.Cu")
		(net "M_J_CPU1_SB_DQ<1>")
	)
	(segment
		(start 131.993386 -275.223732)
		(end 132.001768 -275.218906)
		(width 0.0889)
		(layer "In4.Cu")
		(net "M_J_CPU1_SB_DQ<1>")
	)
	(segment
		(start 138.20775 -275.218906)
		(end 138.216132 -275.223732)
		(width 0.0889)
		(layer "In4.Cu")
		(net "M_J_CPU1_SB_DQ<1>")
	)
	(segment
		(start 182.434992 -282.76042)
		(end 189.023752 -282.76042)
		(width 0.14478)
		(layer "In4.Cu")
		(net "M_J_CPU1_SB_DQ<1>")
	)
	(segment
		(start 145.42897 -275.114766)
		(end 145.734532 -274.98802)
		(width 0.0889)
		(layer "In4.Cu")
		(net "M_J_CPU1_SB_DQ<1>")
	)
	(segment
		(start 140.453364 -275.223732)
		(end 140.461746 -275.218906)
		(width 0.0889)
		(layer "In4.Cu")
		(net "M_J_CPU1_SB_DQ<1>")
	)
	(segment
		(start 179.046632 -283.610304)
		(end 180.38318 -283.610304)
		(width 0.14478)
		(layer "In4.Cu")
		(net "M_J_CPU1_SB_DQ<1>")
	)
	(segment
		(start 135.753348 -275.223732)
		(end 135.76173 -275.218906)
		(width 0.0889)
		(layer "In4.Cu")
		(net "M_J_CPU1_SB_DQ<1>")
	)
	(segment
		(start 143.847566 -275.218906)
		(end 143.855948 -275.223732)
		(width 0.0889)
		(layer "In4.Cu")
		(net "M_J_CPU1_SB_DQ<1>")
	)
	(segment
		(start 146.743166 -274.009104)
		(end 147.337526 -274.009104)
		(width 0.0889)
		(layer "In4.Cu")
		(net "M_J_CPU1_SB_DQ<1>")
	)
	(segment
		(start 141.967712 -275.218906)
		(end 141.976094 -275.223732)
		(width 0.0889)
		(layer "In4.Cu")
		(net "M_J_CPU1_SB_DQ<1>")
	)
	(segment
		(start 132.93344 -275.223732)
		(end 132.941822 -275.218906)
		(width 0.0889)
		(layer "In4.Cu")
		(net "M_J_CPU1_SB_DQ<1>")
	)
	(segment
		(start 154.166316 -273.849084)
		(end 163.927536 -283.610304)
		(width 0.14478)
		(layer "In4.Cu")
		(net "M_J_CPU1_SB_DQ<1>")
	)
	(segment
		(start 175.035718 -282.76042)
		(end 176.99482 -282.76042)
		(width 0.14478)
		(layer "In4.Cu")
		(net "M_J_CPU1_SB_DQ<1>")
	)
	(segment
		(start 131.814824 -274.896326)
		(end 131.660646 -275.161756)
		(width 0.0889)
		(layer "In4.Cu")
		(net "M_J_CPU1_SB_DQ<1>")
	)
	(segment
		(start 136.693402 -275.223732)
		(end 136.701784 -275.218906)
		(width 0.0889)
		(layer "In4.Cu")
		(net "M_J_CPU1_SB_DQ<1>")
	)
	(segment
		(start 148.060918 -273.849084)
		(end 154.166316 -273.849084)
		(width 0.14478)
		(layer "In4.Cu")
		(net "M_J_CPU1_SB_DQ<1>")
	)
	(segment
		(start 165.975792 -283.610304)
		(end 166.825676 -282.76042)
		(width 0.14478)
		(layer "In4.Cu")
		(net "M_J_CPU1_SB_DQ<1>")
	)
	(segment
		(start 145.824448 -274.927822)
		(end 146.743166 -274.009104)
		(width 0.0889)
		(layer "In4.Cu")
		(net "M_J_CPU1_SB_DQ<1>")
	)
	(segment
		(start 163.927536 -283.610304)
		(end 165.975792 -283.610304)
		(width 0.14478)
		(layer "In4.Cu")
		(net "M_J_CPU1_SB_DQ<1>")
	)
	(segment
		(start 171.582334 -283.610304)
		(end 172.983906 -283.610304)
		(width 0.14478)
		(layer "In4.Cu")
		(net "M_J_CPU1_SB_DQ<1>")
	)
	(segment
		(start 147.337526 -274.009104)
		(end 147.497546 -273.849084)
		(width 0.0889)
		(layer "In4.Cu")
		(net "M_J_CPU1_SB_DQ<1>")
	)
	(segment
		(start 141.393418 -275.223732)
		(end 141.4018 -275.218906)
		(width 0.0889)
		(layer "In4.Cu")
		(net "M_J_CPU1_SB_DQ<1>")
	)
	(arc
		(start 135.387588 -275.218906)
		(mid 135.569839 -275.269256)
		(end 135.753348 -275.223732)
		(width 0.0889)
		(layer "In4.Cu")
		(net "M_J_CPU1_SB_DQ<1>")
	)
	(arc
		(start 137.276078 -275.223732)
		(mid 137.459586 -275.269226)
		(end 137.641838 -275.218906)
		(width 0.0889)
		(layer "In4.Cu")
		(net "M_J_CPU1_SB_DQ<1>")
	)
	(arc
		(start 137.641838 -275.218906)
		(mid 137.924794 -275.142729)
		(end 138.20775 -275.218906)
		(width 0.0889)
		(layer "In4.Cu")
		(net "M_J_CPU1_SB_DQ<1>")
	)
	(arc
		(start 132.56768 -275.218906)
		(mid 132.749931 -275.269256)
		(end 132.93344 -275.223732)
		(width 0.0889)
		(layer "In4.Cu")
		(net "M_J_CPU1_SB_DQ<1>")
	)
	(arc
		(start 135.76173 -275.218906)
		(mid 136.044686 -275.142729)
		(end 136.327642 -275.218906)
		(width 0.0889)
		(layer "In4.Cu")
		(net "M_J_CPU1_SB_DQ<1>")
	)
	(arc
		(start 140.461746 -275.218906)
		(mid 140.744702 -275.142729)
		(end 141.027658 -275.218906)
		(width 0.0889)
		(layer "In4.Cu")
		(net "M_J_CPU1_SB_DQ<1>")
	)
	(arc
		(start 133.881876 -275.218906)
		(mid 134.164832 -275.142729)
		(end 134.447788 -275.218906)
		(width 0.0889)
		(layer "In4.Cu")
		(net "M_J_CPU1_SB_DQ<1>")
	)
	(arc
		(start 136.701784 -275.218906)
		(mid 136.98474 -275.142729)
		(end 137.267696 -275.218906)
		(width 0.0889)
		(layer "In4.Cu")
		(net "M_J_CPU1_SB_DQ<1>")
	)
	(arc
		(start 139.521692 -275.218906)
		(mid 139.804648 -275.142729)
		(end 140.087604 -275.218906)
		(width 0.0889)
		(layer "In4.Cu")
		(net "M_J_CPU1_SB_DQ<1>")
	)
	(arc
		(start 141.027658 -275.218906)
		(mid 141.209909 -275.269256)
		(end 141.393418 -275.223732)
		(width 0.0889)
		(layer "In4.Cu")
		(net "M_J_CPU1_SB_DQ<1>")
	)
	(arc
		(start 131.682998 -275.245068)
		(mid 131.840508 -275.268266)
		(end 131.993386 -275.223732)
		(width 0.0889)
		(layer "In4.Cu")
		(net "M_J_CPU1_SB_DQ<1>")
	)
	(arc
		(start 145.158714 -275.213318)
		(mid 145.234478 -275.174902)
		(end 145.31594 -275.150834)
		(width 0.0889)
		(layer "In4.Cu")
		(net "M_J_CPU1_SB_DQ<1>")
	)
	(arc
		(start 143.855948 -275.223732)
		(mid 144.03971 -275.269348)
		(end 144.222216 -275.218906)
		(width 0.0889)
		(layer "In4.Cu")
		(net "M_J_CPU1_SB_DQ<1>")
	)
	(arc
		(start 145.31594 -275.150834)
		(mid 145.373468 -275.135974)
		(end 145.42897 -275.114766)
		(width 0.0889)
		(layer "In4.Cu")
		(net "M_J_CPU1_SB_DQ<1>")
	)
	(arc
		(start 134.821676 -275.218906)
		(mid 135.104632 -275.142729)
		(end 135.387588 -275.218906)
		(width 0.0889)
		(layer "In4.Cu")
		(net "M_J_CPU1_SB_DQ<1>")
	)
	(arc
		(start 132.941822 -275.218906)
		(mid 133.224778 -275.142729)
		(end 133.507734 -275.218906)
		(width 0.0889)
		(layer "In4.Cu")
		(net "M_J_CPU1_SB_DQ<1>")
	)
	(arc
		(start 138.581892 -275.218906)
		(mid 138.864848 -275.142729)
		(end 139.147804 -275.218906)
		(width 0.0889)
		(layer "In4.Cu")
		(net "M_J_CPU1_SB_DQ<1>")
	)
	(arc
		(start 134.447788 -275.218906)
		(mid 134.634732 -275.269161)
		(end 134.821676 -275.218906)
		(width 0.0889)
		(layer "In4.Cu")
		(net "M_J_CPU1_SB_DQ<1>")
	)
	(arc
		(start 144.222216 -275.218906)
		(mid 144.499283 -275.142635)
		(end 144.777968 -275.21281)
		(width 0.0889)
		(layer "In4.Cu")
		(net "M_J_CPU1_SB_DQ<1>")
	)
	(arc
		(start 143.281654 -275.218906)
		(mid 143.56461 -275.142729)
		(end 143.847566 -275.218906)
		(width 0.0889)
		(layer "In4.Cu")
		(net "M_J_CPU1_SB_DQ<1>")
	)
	(arc
		(start 142.907766 -275.218906)
		(mid 143.09471 -275.269161)
		(end 143.281654 -275.218906)
		(width 0.0889)
		(layer "In4.Cu")
		(net "M_J_CPU1_SB_DQ<1>")
	)
	(arc
		(start 136.327642 -275.218906)
		(mid 136.509893 -275.269256)
		(end 136.693402 -275.223732)
		(width 0.0889)
		(layer "In4.Cu")
		(net "M_J_CPU1_SB_DQ<1>")
	)
	(arc
		(start 140.087604 -275.218906)
		(mid 140.269855 -275.269256)
		(end 140.453364 -275.223732)
		(width 0.0889)
		(layer "In4.Cu")
		(net "M_J_CPU1_SB_DQ<1>")
	)
	(arc
		(start 138.216132 -275.223732)
		(mid 138.39964 -275.269226)
		(end 138.581892 -275.218906)
		(width 0.0889)
		(layer "In4.Cu")
		(net "M_J_CPU1_SB_DQ<1>")
	)
	(arc
		(start 144.788382 -275.218906)
		(mid 144.974334 -275.267858)
		(end 145.158714 -275.213318)
		(width 0.0889)
		(layer "In4.Cu")
		(net "M_J_CPU1_SB_DQ<1>")
	)
	(arc
		(start 142.341854 -275.218906)
		(mid 142.62481 -275.142729)
		(end 142.907766 -275.218906)
		(width 0.0889)
		(layer "In4.Cu")
		(net "M_J_CPU1_SB_DQ<1>")
	)
	(arc
		(start 139.147804 -275.218906)
		(mid 139.334748 -275.269161)
		(end 139.521692 -275.218906)
		(width 0.0889)
		(layer "In4.Cu")
		(net "M_J_CPU1_SB_DQ<1>")
	)
	(arc
		(start 141.976094 -275.223732)
		(mid 142.159602 -275.269226)
		(end 142.341854 -275.218906)
		(width 0.0889)
		(layer "In4.Cu")
		(net "M_J_CPU1_SB_DQ<1>")
	)
	(arc
		(start 133.516116 -275.223732)
		(mid 133.699624 -275.269226)
		(end 133.881876 -275.218906)
		(width 0.0889)
		(layer "In4.Cu")
		(net "M_J_CPU1_SB_DQ<1>")
	)
	(arc
		(start 141.4018 -275.218906)
		(mid 141.684756 -275.142729)
		(end 141.967712 -275.218906)
		(width 0.0889)
		(layer "In4.Cu")
		(net "M_J_CPU1_SB_DQ<1>")
	)
	(arc
		(start 132.001768 -275.218906)
		(mid 132.284724 -275.142729)
		(end 132.56768 -275.218906)
		(width 0.0889)
		(layer "In4.Cu")
		(net "M_J_CPU1_SB_DQ<1>")
	)
	(segment
		(start 130.877818 -285.160466)
		(end 131.34467 -285.426404)
		(width 0.10668)
		(layer "F.Cu")
		(net "M_J_CPU1_SB_DQ<19>")
	)
	(segment
		(start 146.668998 -285.540704)
		(end 147.220686 -285.540704)
		(width 0.0889)
		(layer "In4.Cu")
		(net "M_J_CPU1_SB_DQ<19>")
	)
	(segment
		(start 158.77286 -301.155608)
		(end 158.934404 -301.317152)
		(width 0.14478)
		(layer "In4.Cu")
		(net "M_J_CPU1_SB_DQ<19>")
	)
	(segment
		(start 159.324548 -301.935896)
		(end 159.553148 -301.935896)
		(width 0.14478)
		(layer "In4.Cu")
		(net "M_J_CPU1_SB_DQ<19>")
	)
	(segment
		(start 158.154116 -300.536864)
		(end 158.154116 -300.765464)
		(width 0.14478)
		(layer "In4.Cu")
		(net "M_J_CPU1_SB_DQ<19>")
	)
	(segment
		(start 147.850098 -285.977584)
		(end 148.338286 -285.977584)
		(width 0.14478)
		(layer "In4.Cu")
		(net "M_J_CPU1_SB_DQ<19>")
	)
	(segment
		(start 131.498848 -285.160974)
		(end 131.595114 -285.135574)
		(width 0.0889)
		(layer "In4.Cu")
		(net "M_J_CPU1_SB_DQ<19>")
	)
	(segment
		(start 186.625484 -302.30064)
		(end 187.060078 -302.735234)
		(width 0.14478)
		(layer "In4.Cu")
		(net "M_J_CPU1_SB_DQ<19>")
	)
	(segment
		(start 146.178778 -285.050484)
		(end 146.668998 -285.540704)
		(width 0.0889)
		(layer "In4.Cu")
		(net "M_J_CPU1_SB_DQ<19>")
	)
	(segment
		(start 157.212284 -299.595032)
		(end 157.373828 -299.756576)
		(width 0.14478)
		(layer "In4.Cu")
		(net "M_J_CPU1_SB_DQ<19>")
	)
	(segment
		(start 157.250384 -300.33722)
		(end 157.411928 -300.498764)
		(width 0.14478)
		(layer "In4.Cu")
		(net "M_J_CPU1_SB_DQ<19>")
	)
	(segment
		(start 155.689808 -298.548044)
		(end 155.689808 -298.776644)
		(width 0.14478)
		(layer "In4.Cu")
		(net "M_J_CPU1_SB_DQ<19>")
	)
	(segment
		(start 174.390304 -302.30064)
		(end 177.694082 -302.30064)
		(width 0.14478)
		(layer "In4.Cu")
		(net "M_J_CPU1_SB_DQ<19>")
	)
	(segment
		(start 156.86024 -299.718476)
		(end 156.983684 -299.595032)
		(width 0.14478)
		(layer "In4.Cu")
		(net "M_J_CPU1_SB_DQ<19>")
	)
	(segment
		(start 134.917688 -285.103824)
		(end 134.92607 -285.098998)
		(width 0.0889)
		(layer "In4.Cu")
		(net "M_J_CPU1_SB_DQ<19>")
	)
	(segment
		(start 158.54426 -301.155608)
		(end 158.77286 -301.155608)
		(width 0.14478)
		(layer "In4.Cu")
		(net "M_J_CPU1_SB_DQ<19>")
	)
	(segment
		(start 158.81096 -301.897796)
		(end 158.972504 -302.05934)
		(width 0.14478)
		(layer "In4.Cu")
		(net "M_J_CPU1_SB_DQ<19>")
	)
	(segment
		(start 156.59354 -299.204888)
		(end 156.470096 -299.328332)
		(width 0.14478)
		(layer "In4.Cu")
		(net "M_J_CPU1_SB_DQ<19>")
	)
	(segment
		(start 154.36469 -296.747438)
		(end 155.032964 -297.415712)
		(width 0.14478)
		(layer "In4.Cu")
		(net "M_J_CPU1_SB_DQ<19>")
	)
	(segment
		(start 158.972504 -302.05934)
		(end 159.201104 -302.05934)
		(width 0.14478)
		(layer "In4.Cu")
		(net "M_J_CPU1_SB_DQ<19>")
	)
	(segment
		(start 145.276316 -285.093664)
		(end 145.347944 -285.050484)
		(width 0.0889)
		(layer "In4.Cu")
		(net "M_J_CPU1_SB_DQ<19>")
	)
	(segment
		(start 139.04341 -285.098998)
		(end 139.051792 -285.103824)
		(width 0.0889)
		(layer "In4.Cu")
		(net "M_J_CPU1_SB_DQ<19>")
	)
	(segment
		(start 157.992572 -300.37532)
		(end 158.154116 -300.536864)
		(width 0.14478)
		(layer "In4.Cu")
		(net "M_J_CPU1_SB_DQ<19>")
	)
	(segment
		(start 143.377666 -285.103824)
		(end 143.386048 -285.098998)
		(width 0.0889)
		(layer "In4.Cu")
		(net "M_J_CPU1_SB_DQ<19>")
	)
	(segment
		(start 158.81096 -301.669196)
		(end 158.81096 -301.897796)
		(width 0.14478)
		(layer "In4.Cu")
		(net "M_J_CPU1_SB_DQ<19>")
	)
	(segment
		(start 157.640528 -300.498764)
		(end 157.763972 -300.37532)
		(width 0.14478)
		(layer "In4.Cu")
		(net "M_J_CPU1_SB_DQ<19>")
	)
	(segment
		(start 131.34467 -285.426404)
		(end 131.498848 -285.160974)
		(width 0.0889)
		(layer "In4.Cu")
		(net "M_J_CPU1_SB_DQ<19>")
	)
	(segment
		(start 143.751808 -285.103824)
		(end 143.762222 -285.10992)
		(width 0.0889)
		(layer "In4.Cu")
		(net "M_J_CPU1_SB_DQ<19>")
	)
	(segment
		(start 181.147212 -303.150524)
		(end 181.997096 -302.30064)
		(width 0.14478)
		(layer "In4.Cu")
		(net "M_J_CPU1_SB_DQ<19>")
	)
	(segment
		(start 156.079952 -298.938188)
		(end 156.203396 -298.814744)
		(width 0.14478)
		(layer "In4.Cu")
		(net "M_J_CPU1_SB_DQ<19>")
	)
	(segment
		(start 160.777682 -303.16043)
		(end 166.08044 -303.16043)
		(width 0.14478)
		(layer "In4.Cu")
		(net "M_J_CPU1_SB_DQ<19>")
	)
	(segment
		(start 158.030672 -300.888908)
		(end 158.030672 -301.117508)
		(width 0.14478)
		(layer "In4.Cu")
		(net "M_J_CPU1_SB_DQ<19>")
	)
	(segment
		(start 158.934404 -301.317152)
		(end 158.934404 -301.545752)
		(width 0.14478)
		(layer "In4.Cu")
		(net "M_J_CPU1_SB_DQ<19>")
	)
	(segment
		(start 160.104836 -302.716184)
		(end 160.333436 -302.716184)
		(width 0.14478)
		(layer "In4.Cu")
		(net "M_J_CPU1_SB_DQ<19>")
	)
	(segment
		(start 155.689808 -298.776644)
		(end 155.851352 -298.938188)
		(width 0.14478)
		(layer "In4.Cu")
		(net "M_J_CPU1_SB_DQ<19>")
	)
	(segment
		(start 159.591248 -302.449484)
		(end 159.591248 -302.678084)
		(width 0.14478)
		(layer "In4.Cu")
		(net "M_J_CPU1_SB_DQ<19>")
	)
	(segment
		(start 157.411928 -300.498764)
		(end 157.640528 -300.498764)
		(width 0.14478)
		(layer "In4.Cu")
		(net "M_J_CPU1_SB_DQ<19>")
	)
	(segment
		(start 158.420816 -301.279052)
		(end 158.54426 -301.155608)
		(width 0.14478)
		(layer "In4.Cu")
		(net "M_J_CPU1_SB_DQ<19>")
	)
	(segment
		(start 155.032964 -297.644312)
		(end 154.90952 -297.767756)
		(width 0.14478)
		(layer "In4.Cu")
		(net "M_J_CPU1_SB_DQ<19>")
	)
	(segment
		(start 156.470096 -299.328332)
		(end 156.470096 -299.556932)
		(width 0.14478)
		(layer "In4.Cu")
		(net "M_J_CPU1_SB_DQ<19>")
	)
	(segment
		(start 135.857742 -285.103824)
		(end 135.866124 -285.098998)
		(width 0.0889)
		(layer "In4.Cu")
		(net "M_J_CPU1_SB_DQ<19>")
	)
	(segment
		(start 158.154116 -300.765464)
		(end 158.030672 -300.888908)
		(width 0.14478)
		(layer "In4.Cu")
		(net "M_J_CPU1_SB_DQ<19>")
	)
	(segment
		(start 157.373828 -299.756576)
		(end 157.373828 -299.985176)
		(width 0.14478)
		(layer "In4.Cu")
		(net "M_J_CPU1_SB_DQ<19>")
	)
	(segment
		(start 158.030672 -301.117508)
		(end 158.192216 -301.279052)
		(width 0.14478)
		(layer "In4.Cu")
		(net "M_J_CPU1_SB_DQ<19>")
	)
	(segment
		(start 156.431996 -298.814744)
		(end 156.59354 -298.976288)
		(width 0.14478)
		(layer "In4.Cu")
		(net "M_J_CPU1_SB_DQ<19>")
	)
	(segment
		(start 166.930578 -302.310292)
		(end 170.18254 -302.310292)
		(width 0.14478)
		(layer "In4.Cu")
		(net "M_J_CPU1_SB_DQ<19>")
	)
	(segment
		(start 155.813252 -298.196)
		(end 155.813252 -298.4246)
		(width 0.14478)
		(layer "In4.Cu")
		(net "M_J_CPU1_SB_DQ<19>")
	)
	(segment
		(start 159.752792 -302.839628)
		(end 159.981392 -302.839628)
		(width 0.14478)
		(layer "In4.Cu")
		(net "M_J_CPU1_SB_DQ<19>")
	)
	(segment
		(start 159.591248 -302.678084)
		(end 159.752792 -302.839628)
		(width 0.14478)
		(layer "In4.Cu")
		(net "M_J_CPU1_SB_DQ<19>")
	)
	(segment
		(start 178.543966 -303.150524)
		(end 181.147212 -303.150524)
		(width 0.14478)
		(layer "In4.Cu")
		(net "M_J_CPU1_SB_DQ<19>")
	)
	(segment
		(start 158.934404 -301.545752)
		(end 158.81096 -301.669196)
		(width 0.14478)
		(layer "In4.Cu")
		(net "M_J_CPU1_SB_DQ<19>")
	)
	(segment
		(start 157.373828 -299.985176)
		(end 157.250384 -300.10862)
		(width 0.14478)
		(layer "In4.Cu")
		(net "M_J_CPU1_SB_DQ<19>")
	)
	(segment
		(start 154.36469 -292.003988)
		(end 154.36469 -296.747438)
		(width 0.14478)
		(layer "In4.Cu")
		(net "M_J_CPU1_SB_DQ<19>")
	)
	(segment
		(start 166.08044 -303.16043)
		(end 166.930578 -302.310292)
		(width 0.14478)
		(layer "In4.Cu")
		(net "M_J_CPU1_SB_DQ<19>")
	)
	(segment
		(start 159.714692 -302.09744)
		(end 159.714692 -302.32604)
		(width 0.14478)
		(layer "In4.Cu")
		(net "M_J_CPU1_SB_DQ<19>")
	)
	(segment
		(start 156.203396 -298.814744)
		(end 156.431996 -298.814744)
		(width 0.14478)
		(layer "In4.Cu")
		(net "M_J_CPU1_SB_DQ<19>")
	)
	(segment
		(start 155.423108 -298.034456)
		(end 155.651708 -298.034456)
		(width 0.14478)
		(layer "In4.Cu")
		(net "M_J_CPU1_SB_DQ<19>")
	)
	(segment
		(start 148.338286 -285.977584)
		(end 154.36469 -292.003988)
		(width 0.14478)
		(layer "In4.Cu")
		(net "M_J_CPU1_SB_DQ<19>")
	)
	(segment
		(start 154.90952 -297.767756)
		(end 154.90952 -297.996356)
		(width 0.14478)
		(layer "In4.Cu")
		(net "M_J_CPU1_SB_DQ<19>")
	)
	(segment
		(start 132.09778 -285.103824)
		(end 132.106162 -285.098998)
		(width 0.0889)
		(layer "In4.Cu")
		(net "M_J_CPU1_SB_DQ<19>")
	)
	(segment
		(start 155.071064 -298.1579)
		(end 155.299664 -298.1579)
		(width 0.14478)
		(layer "In4.Cu")
		(net "M_J_CPU1_SB_DQ<19>")
	)
	(segment
		(start 157.250384 -300.10862)
		(end 157.250384 -300.33722)
		(width 0.14478)
		(layer "In4.Cu")
		(net "M_J_CPU1_SB_DQ<19>")
	)
	(segment
		(start 155.032964 -297.415712)
		(end 155.032964 -297.644312)
		(width 0.14478)
		(layer "In4.Cu")
		(net "M_J_CPU1_SB_DQ<19>")
	)
	(segment
		(start 147.220686 -285.540704)
		(end 147.657566 -285.977584)
		(width 0.0889)
		(layer "In4.Cu")
		(net "M_J_CPU1_SB_DQ<19>")
	)
	(segment
		(start 138.103356 -285.098998)
		(end 138.111738 -285.103824)
		(width 0.0889)
		(layer "In4.Cu")
		(net "M_J_CPU1_SB_DQ<19>")
	)
	(segment
		(start 155.299664 -298.1579)
		(end 155.423108 -298.034456)
		(width 0.14478)
		(layer "In4.Cu")
		(net "M_J_CPU1_SB_DQ<19>")
	)
	(segment
		(start 159.981392 -302.839628)
		(end 160.104836 -302.716184)
		(width 0.14478)
		(layer "In4.Cu")
		(net "M_J_CPU1_SB_DQ<19>")
	)
	(segment
		(start 157.763972 -300.37532)
		(end 157.992572 -300.37532)
		(width 0.14478)
		(layer "In4.Cu")
		(net "M_J_CPU1_SB_DQ<19>")
	)
	(segment
		(start 156.470096 -299.556932)
		(end 156.63164 -299.718476)
		(width 0.14478)
		(layer "In4.Cu")
		(net "M_J_CPU1_SB_DQ<19>")
	)
	(segment
		(start 155.813252 -298.4246)
		(end 155.689808 -298.548044)
		(width 0.14478)
		(layer "In4.Cu")
		(net "M_J_CPU1_SB_DQ<19>")
	)
	(segment
		(start 156.63164 -299.718476)
		(end 156.86024 -299.718476)
		(width 0.14478)
		(layer "In4.Cu")
		(net "M_J_CPU1_SB_DQ<19>")
	)
	(segment
		(start 173.54042 -303.150524)
		(end 174.390304 -302.30064)
		(width 0.14478)
		(layer "In4.Cu")
		(net "M_J_CPU1_SB_DQ<19>")
	)
	(segment
		(start 154.90952 -297.996356)
		(end 155.071064 -298.1579)
		(width 0.14478)
		(layer "In4.Cu")
		(net "M_J_CPU1_SB_DQ<19>")
	)
	(segment
		(start 158.192216 -301.279052)
		(end 158.420816 -301.279052)
		(width 0.14478)
		(layer "In4.Cu")
		(net "M_J_CPU1_SB_DQ<19>")
	)
	(segment
		(start 144.684242 -285.098998)
		(end 144.692624 -285.103824)
		(width 0.0889)
		(layer "In4.Cu")
		(net "M_J_CPU1_SB_DQ<19>")
	)
	(segment
		(start 147.657566 -285.977584)
		(end 147.850098 -285.977584)
		(width 0.0889)
		(layer "In4.Cu")
		(net "M_J_CPU1_SB_DQ<19>")
	)
	(segment
		(start 171.022772 -303.150524)
		(end 173.54042 -303.150524)
		(width 0.14478)
		(layer "In4.Cu")
		(net "M_J_CPU1_SB_DQ<19>")
	)
	(segment
		(start 159.201104 -302.05934)
		(end 159.324548 -301.935896)
		(width 0.14478)
		(layer "In4.Cu")
		(net "M_J_CPU1_SB_DQ<19>")
	)
	(segment
		(start 155.851352 -298.938188)
		(end 156.079952 -298.938188)
		(width 0.14478)
		(layer "In4.Cu")
		(net "M_J_CPU1_SB_DQ<19>")
	)
	(segment
		(start 140.557758 -285.103824)
		(end 140.56614 -285.098998)
		(width 0.0889)
		(layer "In4.Cu")
		(net "M_J_CPU1_SB_DQ<19>")
	)
	(segment
		(start 156.59354 -298.976288)
		(end 156.59354 -299.204888)
		(width 0.14478)
		(layer "In4.Cu")
		(net "M_J_CPU1_SB_DQ<19>")
	)
	(segment
		(start 155.651708 -298.034456)
		(end 155.813252 -298.196)
		(width 0.14478)
		(layer "In4.Cu")
		(net "M_J_CPU1_SB_DQ<19>")
	)
	(segment
		(start 139.617704 -285.103824)
		(end 139.626086 -285.098998)
		(width 0.0889)
		(layer "In4.Cu")
		(net "M_J_CPU1_SB_DQ<19>")
	)
	(segment
		(start 177.694082 -302.30064)
		(end 178.543966 -303.150524)
		(width 0.14478)
		(layer "In4.Cu")
		(net "M_J_CPU1_SB_DQ<19>")
	)
	(segment
		(start 142.803372 -285.098998)
		(end 142.811754 -285.103824)
		(width 0.0889)
		(layer "In4.Cu")
		(net "M_J_CPU1_SB_DQ<19>")
	)
	(segment
		(start 145.25244 -285.10738)
		(end 145.258028 -285.104078)
		(width 0.0889)
		(layer "In4.Cu")
		(net "M_J_CPU1_SB_DQ<19>")
	)
	(segment
		(start 170.18254 -302.310292)
		(end 171.022772 -303.150524)
		(width 0.14478)
		(layer "In4.Cu")
		(net "M_J_CPU1_SB_DQ<19>")
	)
	(segment
		(start 159.553148 -301.935896)
		(end 159.714692 -302.09744)
		(width 0.14478)
		(layer "In4.Cu")
		(net "M_J_CPU1_SB_DQ<19>")
	)
	(segment
		(start 156.983684 -299.595032)
		(end 157.212284 -299.595032)
		(width 0.14478)
		(layer "In4.Cu")
		(net "M_J_CPU1_SB_DQ<19>")
	)
	(segment
		(start 145.258028 -285.104078)
		(end 145.276316 -285.093664)
		(width 0.0889)
		(layer "In4.Cu")
		(net "M_J_CPU1_SB_DQ<19>")
	)
	(segment
		(start 160.333436 -302.716184)
		(end 160.777682 -303.16043)
		(width 0.14478)
		(layer "In4.Cu")
		(net "M_J_CPU1_SB_DQ<19>")
	)
	(segment
		(start 134.343394 -285.098998)
		(end 134.351776 -285.103824)
		(width 0.0889)
		(layer "In4.Cu")
		(net "M_J_CPU1_SB_DQ<19>")
	)
	(segment
		(start 181.997096 -302.30064)
		(end 186.625484 -302.30064)
		(width 0.14478)
		(layer "In4.Cu")
		(net "M_J_CPU1_SB_DQ<19>")
	)
	(segment
		(start 145.347944 -285.050484)
		(end 146.178778 -285.050484)
		(width 0.0889)
		(layer "In4.Cu")
		(net "M_J_CPU1_SB_DQ<19>")
	)
	(segment
		(start 159.714692 -302.32604)
		(end 159.591248 -302.449484)
		(width 0.14478)
		(layer "In4.Cu")
		(net "M_J_CPU1_SB_DQ<19>")
	)
	(arc
		(start 136.797796 -285.103824)
		(mid 136.98474 -285.053569)
		(end 137.171684 -285.103824)
		(width 0.0889)
		(layer "In4.Cu")
		(net "M_J_CPU1_SB_DQ<19>")
	)
	(arc
		(start 142.811754 -285.103824)
		(mid 143.09471 -285.180001)
		(end 143.377666 -285.103824)
		(width 0.0889)
		(layer "In4.Cu")
		(net "M_J_CPU1_SB_DQ<19>")
	)
	(arc
		(start 142.437612 -285.103824)
		(mid 142.619863 -285.053474)
		(end 142.803372 -285.098998)
		(width 0.0889)
		(layer "In4.Cu")
		(net "M_J_CPU1_SB_DQ<19>")
	)
	(arc
		(start 132.471922 -285.103824)
		(mid 132.754878 -285.180001)
		(end 133.037834 -285.103824)
		(width 0.0889)
		(layer "In4.Cu")
		(net "M_J_CPU1_SB_DQ<19>")
	)
	(arc
		(start 144.317974 -285.103824)
		(mid 144.500479 -285.053347)
		(end 144.684242 -285.098998)
		(width 0.0889)
		(layer "In4.Cu")
		(net "M_J_CPU1_SB_DQ<19>")
	)
	(arc
		(start 144.692624 -285.103824)
		(mid 144.972052 -285.17999)
		(end 145.25244 -285.10738)
		(width 0.0889)
		(layer "In4.Cu")
		(net "M_J_CPU1_SB_DQ<19>")
	)
	(arc
		(start 135.866124 -285.098998)
		(mid 136.049632 -285.053504)
		(end 136.231884 -285.103824)
		(width 0.0889)
		(layer "In4.Cu")
		(net "M_J_CPU1_SB_DQ<19>")
	)
	(arc
		(start 141.497812 -285.103824)
		(mid 141.684756 -285.053569)
		(end 141.8717 -285.103824)
		(width 0.0889)
		(layer "In4.Cu")
		(net "M_J_CPU1_SB_DQ<19>")
	)
	(arc
		(start 139.626086 -285.098998)
		(mid 139.809594 -285.053504)
		(end 139.991846 -285.103824)
		(width 0.0889)
		(layer "In4.Cu")
		(net "M_J_CPU1_SB_DQ<19>")
	)
	(arc
		(start 133.037834 -285.103824)
		(mid 133.224778 -285.053569)
		(end 133.411722 -285.103824)
		(width 0.0889)
		(layer "In4.Cu")
		(net "M_J_CPU1_SB_DQ<19>")
	)
	(arc
		(start 131.595114 -285.135574)
		(mid 131.850179 -285.178925)
		(end 132.09778 -285.103824)
		(width 0.0889)
		(layer "In4.Cu")
		(net "M_J_CPU1_SB_DQ<19>")
	)
	(arc
		(start 137.171684 -285.103824)
		(mid 137.45464 -285.180001)
		(end 137.737596 -285.103824)
		(width 0.0889)
		(layer "In4.Cu")
		(net "M_J_CPU1_SB_DQ<19>")
	)
	(arc
		(start 135.29183 -285.103824)
		(mid 135.574786 -285.180001)
		(end 135.857742 -285.103824)
		(width 0.0889)
		(layer "In4.Cu")
		(net "M_J_CPU1_SB_DQ<19>")
	)
	(arc
		(start 139.051792 -285.103824)
		(mid 139.334748 -285.180001)
		(end 139.617704 -285.103824)
		(width 0.0889)
		(layer "In4.Cu")
		(net "M_J_CPU1_SB_DQ<19>")
	)
	(arc
		(start 132.106162 -285.098998)
		(mid 132.28967 -285.053504)
		(end 132.471922 -285.103824)
		(width 0.0889)
		(layer "In4.Cu")
		(net "M_J_CPU1_SB_DQ<19>")
	)
	(arc
		(start 138.111738 -285.103824)
		(mid 138.394694 -285.180001)
		(end 138.67765 -285.103824)
		(width 0.0889)
		(layer "In4.Cu")
		(net "M_J_CPU1_SB_DQ<19>")
	)
	(arc
		(start 138.67765 -285.103824)
		(mid 138.859901 -285.053474)
		(end 139.04341 -285.098998)
		(width 0.0889)
		(layer "In4.Cu")
		(net "M_J_CPU1_SB_DQ<19>")
	)
	(arc
		(start 140.9319 -285.103824)
		(mid 141.214856 -285.180001)
		(end 141.497812 -285.103824)
		(width 0.0889)
		(layer "In4.Cu")
		(net "M_J_CPU1_SB_DQ<19>")
	)
	(arc
		(start 134.351776 -285.103824)
		(mid 134.634732 -285.180001)
		(end 134.917688 -285.103824)
		(width 0.0889)
		(layer "In4.Cu")
		(net "M_J_CPU1_SB_DQ<19>")
	)
	(arc
		(start 133.977634 -285.103824)
		(mid 134.159885 -285.053474)
		(end 134.343394 -285.098998)
		(width 0.0889)
		(layer "In4.Cu")
		(net "M_J_CPU1_SB_DQ<19>")
	)
	(arc
		(start 137.737596 -285.103824)
		(mid 137.919847 -285.053474)
		(end 138.103356 -285.098998)
		(width 0.0889)
		(layer "In4.Cu")
		(net "M_J_CPU1_SB_DQ<19>")
	)
	(arc
		(start 141.8717 -285.103824)
		(mid 142.154656 -285.180001)
		(end 142.437612 -285.103824)
		(width 0.0889)
		(layer "In4.Cu")
		(net "M_J_CPU1_SB_DQ<19>")
	)
	(arc
		(start 140.56614 -285.098998)
		(mid 140.749648 -285.053504)
		(end 140.9319 -285.103824)
		(width 0.0889)
		(layer "In4.Cu")
		(net "M_J_CPU1_SB_DQ<19>")
	)
	(arc
		(start 133.411722 -285.103824)
		(mid 133.694678 -285.180001)
		(end 133.977634 -285.103824)
		(width 0.0889)
		(layer "In4.Cu")
		(net "M_J_CPU1_SB_DQ<19>")
	)
	(arc
		(start 134.92607 -285.098998)
		(mid 135.109578 -285.053504)
		(end 135.29183 -285.103824)
		(width 0.0889)
		(layer "In4.Cu")
		(net "M_J_CPU1_SB_DQ<19>")
	)
	(arc
		(start 136.231884 -285.103824)
		(mid 136.51484 -285.180001)
		(end 136.797796 -285.103824)
		(width 0.0889)
		(layer "In4.Cu")
		(net "M_J_CPU1_SB_DQ<19>")
	)
	(arc
		(start 139.991846 -285.103824)
		(mid 140.274802 -285.180001)
		(end 140.557758 -285.103824)
		(width 0.0889)
		(layer "In4.Cu")
		(net "M_J_CPU1_SB_DQ<19>")
	)
	(arc
		(start 143.386048 -285.098998)
		(mid 143.569556 -285.053504)
		(end 143.751808 -285.103824)
		(width 0.0889)
		(layer "In4.Cu")
		(net "M_J_CPU1_SB_DQ<19>")
	)
	(arc
		(start 143.762222 -285.10992)
		(mid 144.040908 -285.18014)
		(end 144.317974 -285.103824)
		(width 0.0889)
		(layer "In4.Cu")
		(net "M_J_CPU1_SB_DQ<19>")
	)
	(segment
		(start 132.287772 -284.35046)
		(end 132.754878 -284.616398)
		(width 0.10668)
		(layer "F.Cu")
		(net "M_J_CPU1_SB_DQ<18>")
	)
	(segment
		(start 159.45866 -300.569376)
		(end 159.68726 -300.569376)
		(width 0.14478)
		(layer "In4.Cu")
		(net "M_J_CPU1_SB_DQ<18>")
	)
	(segment
		(start 144.785334 -284.293818)
		(end 144.80413 -284.282896)
		(width 0.0889)
		(layer "In4.Cu")
		(net "M_J_CPU1_SB_DQ<18>")
	)
	(segment
		(start 157.135068 -297.430952)
		(end 157.135068 -297.659552)
		(width 0.14478)
		(layer "In4.Cu")
		(net "M_J_CPU1_SB_DQ<18>")
	)
	(segment
		(start 145.444718 -284.370526)
		(end 146.201892 -284.370526)
		(width 0.0889)
		(layer "In4.Cu")
		(net "M_J_CPU1_SB_DQ<18>")
	)
	(segment
		(start 157.135068 -297.659552)
		(end 156.956252 -297.838368)
		(width 0.14478)
		(layer "In4.Cu")
		(net "M_J_CPU1_SB_DQ<18>")
	)
	(segment
		(start 167.000174 -300.61027)
		(end 170.18254 -300.61027)
		(width 0.14478)
		(layer "In4.Cu")
		(net "M_J_CPU1_SB_DQ<18>")
	)
	(segment
		(start 155.574492 -295.870376)
		(end 155.574492 -296.098976)
		(width 0.14478)
		(layer "In4.Cu")
		(net "M_J_CPU1_SB_DQ<18>")
	)
	(segment
		(start 161.164524 -301.460408)
		(end 161.68497 -301.460408)
		(width 0.14478)
		(layer "In4.Cu")
		(net "M_J_CPU1_SB_DQ<18>")
	)
	(segment
		(start 184.523888 -300.911006)
		(end 184.774586 -300.911006)
		(width 0.14478)
		(layer "In4.Cu")
		(net "M_J_CPU1_SB_DQ<18>")
	)
	(segment
		(start 165.83533 -301.460408)
		(end 166.150036 -301.460408)
		(width 0.14478)
		(layer "In4.Cu")
		(net "M_J_CPU1_SB_DQ<18>")
	)
	(segment
		(start 132.754878 -284.616398)
		(end 132.908802 -284.350968)
		(width 0.0889)
		(layer "In4.Cu")
		(net "M_J_CPU1_SB_DQ<18>")
	)
	(segment
		(start 136.693402 -284.288992)
		(end 136.701784 -284.293818)
		(width 0.0889)
		(layer "In4.Cu")
		(net "M_J_CPU1_SB_DQ<18>")
	)
	(segment
		(start 156.35478 -296.650664)
		(end 156.35478 -296.879264)
		(width 0.14478)
		(layer "In4.Cu")
		(net "M_J_CPU1_SB_DQ<18>")
	)
	(segment
		(start 147.528026 -284.959044)
		(end 147.637246 -285.068264)
		(width 0.0889)
		(layer "In4.Cu")
		(net "M_J_CPU1_SB_DQ<18>")
	)
	(segment
		(start 164.44214 -301.170086)
		(end 164.732462 -301.460408)
		(width 0.14478)
		(layer "In4.Cu")
		(net "M_J_CPU1_SB_DQ<18>")
	)
	(segment
		(start 166.150036 -301.460408)
		(end 167.000174 -300.61027)
		(width 0.14478)
		(layer "In4.Cu")
		(net "M_J_CPU1_SB_DQ<18>")
	)
	(segment
		(start 160.25622 -300.552104)
		(end 160.25622 -300.780704)
		(width 0.14478)
		(layer "In4.Cu")
		(net "M_J_CPU1_SB_DQ<18>")
	)
	(segment
		(start 158.695644 -299.220128)
		(end 158.516828 -299.398944)
		(width 0.14478)
		(layer "In4.Cu")
		(net "M_J_CPU1_SB_DQ<18>")
	)
	(segment
		(start 160.25622 -300.780704)
		(end 160.077404 -300.95952)
		(width 0.14478)
		(layer "In4.Cu")
		(net "M_J_CPU1_SB_DQ<18>")
	)
	(segment
		(start 158.126684 -299.0088)
		(end 158.3055 -298.829984)
		(width 0.14478)
		(layer "In4.Cu")
		(net "M_J_CPU1_SB_DQ<18>")
	)
	(segment
		(start 156.566108 -297.448224)
		(end 156.744924 -297.269408)
		(width 0.14478)
		(layer "In4.Cu")
		(net "M_J_CPU1_SB_DQ<18>")
	)
	(segment
		(start 160.874964 -301.170848)
		(end 161.164524 -301.460408)
		(width 0.14478)
		(layer "In4.Cu")
		(net "M_J_CPU1_SB_DQ<18>")
	)
	(segment
		(start 157.73654 -298.618656)
		(end 157.73654 -298.847256)
		(width 0.14478)
		(layer "In4.Cu")
		(net "M_J_CPU1_SB_DQ<18>")
	)
	(segment
		(start 140.453364 -284.288992)
		(end 140.461746 -284.293818)
		(width 0.0889)
		(layer "In4.Cu")
		(net "M_J_CPU1_SB_DQ<18>")
	)
	(segment
		(start 186.635136 -300.61027)
		(end 187.060078 -301.035212)
		(width 0.14478)
		(layer "In4.Cu")
		(net "M_J_CPU1_SB_DQ<18>")
	)
	(segment
		(start 160.467548 -301.349664)
		(end 160.646364 -301.170848)
		(width 0.14478)
		(layer "In4.Cu")
		(net "M_J_CPU1_SB_DQ<18>")
	)
	(segment
		(start 156.744924 -297.269408)
		(end 156.973524 -297.269408)
		(width 0.14478)
		(layer "In4.Cu")
		(net "M_J_CPU1_SB_DQ<18>")
	)
	(segment
		(start 156.956252 -298.066968)
		(end 157.117796 -298.228512)
		(width 0.14478)
		(layer "In4.Cu")
		(net "M_J_CPU1_SB_DQ<18>")
	)
	(segment
		(start 156.175964 -297.05808)
		(end 156.175964 -297.28668)
		(width 0.14478)
		(layer "In4.Cu")
		(net "M_J_CPU1_SB_DQ<18>")
	)
	(segment
		(start 185.877454 -300.911006)
		(end 186.17819 -300.61027)
		(width 0.14478)
		(layer "In4.Cu")
		(net "M_J_CPU1_SB_DQ<18>")
	)
	(segment
		(start 137.267696 -284.293818)
		(end 137.276078 -284.288992)
		(width 0.0889)
		(layer "In4.Cu")
		(net "M_J_CPU1_SB_DQ<18>")
	)
	(segment
		(start 173.59757 -301.460408)
		(end 174.447708 -300.61027)
		(width 0.14478)
		(layer "In4.Cu")
		(net "M_J_CPU1_SB_DQ<18>")
	)
	(segment
		(start 146.201892 -284.370526)
		(end 146.79041 -284.959044)
		(width 0.0889)
		(layer "In4.Cu")
		(net "M_J_CPU1_SB_DQ<18>")
	)
	(segment
		(start 163.339272 -301.170086)
		(end 163.629594 -301.460408)
		(width 0.14478)
		(layer "In4.Cu")
		(net "M_J_CPU1_SB_DQ<18>")
	)
	(segment
		(start 162.526726 -301.460408)
		(end 162.787838 -301.460408)
		(width 0.14478)
		(layer "In4.Cu")
		(net "M_J_CPU1_SB_DQ<18>")
	)
	(segment
		(start 171.032678 -301.460408)
		(end 173.59757 -301.460408)
		(width 0.14478)
		(layer "In4.Cu")
		(net "M_J_CPU1_SB_DQ<18>")
	)
	(segment
		(start 160.094676 -300.39056)
		(end 160.25622 -300.552104)
		(width 0.14478)
		(layer "In4.Cu")
		(net "M_J_CPU1_SB_DQ<18>")
	)
	(segment
		(start 159.866076 -300.39056)
		(end 160.094676 -300.39056)
		(width 0.14478)
		(layer "In4.Cu")
		(net "M_J_CPU1_SB_DQ<18>")
	)
	(segment
		(start 164.181028 -301.170086)
		(end 164.44214 -301.170086)
		(width 0.14478)
		(layer "In4.Cu")
		(net "M_J_CPU1_SB_DQ<18>")
	)
	(segment
		(start 132.908802 -284.350968)
		(end 133.004814 -284.325568)
		(width 0.0889)
		(layer "In4.Cu")
		(net "M_J_CPU1_SB_DQ<18>")
	)
	(segment
		(start 160.077404 -300.95952)
		(end 160.077404 -301.18812)
		(width 0.14478)
		(layer "In4.Cu")
		(net "M_J_CPU1_SB_DQ<18>")
	)
	(segment
		(start 157.915356 -298.43984)
		(end 157.73654 -298.618656)
		(width 0.14478)
		(layer "In4.Cu")
		(net "M_J_CPU1_SB_DQ<18>")
	)
	(segment
		(start 157.117796 -298.228512)
		(end 157.346396 -298.228512)
		(width 0.14478)
		(layer "In4.Cu")
		(net "M_J_CPU1_SB_DQ<18>")
	)
	(segment
		(start 164.732462 -301.460408)
		(end 164.993574 -301.460408)
		(width 0.14478)
		(layer "In4.Cu")
		(net "M_J_CPU1_SB_DQ<18>")
	)
	(segment
		(start 155.395676 -296.506392)
		(end 155.55722 -296.667936)
		(width 0.14478)
		(layer "In4.Cu")
		(net "M_J_CPU1_SB_DQ<18>")
	)
	(segment
		(start 148.700998 -285.068264)
		(end 155.26385 -291.631116)
		(width 0.14478)
		(layer "In4.Cu")
		(net "M_J_CPU1_SB_DQ<18>")
	)
	(segment
		(start 157.525212 -298.049696)
		(end 157.753812 -298.049696)
		(width 0.14478)
		(layer "In4.Cu")
		(net "M_J_CPU1_SB_DQ<18>")
	)
	(segment
		(start 160.077404 -301.18812)
		(end 160.238948 -301.349664)
		(width 0.14478)
		(layer "In4.Cu")
		(net "M_J_CPU1_SB_DQ<18>")
	)
	(segment
		(start 133.507734 -284.293818)
		(end 133.516116 -284.288992)
		(width 0.0889)
		(layer "In4.Cu")
		(net "M_J_CPU1_SB_DQ<18>")
	)
	(segment
		(start 156.973524 -297.269408)
		(end 157.135068 -297.430952)
		(width 0.14478)
		(layer "In4.Cu")
		(net "M_J_CPU1_SB_DQ<18>")
	)
	(segment
		(start 158.5341 -298.829984)
		(end 158.695644 -298.991528)
		(width 0.14478)
		(layer "In4.Cu")
		(net "M_J_CPU1_SB_DQ<18>")
	)
	(segment
		(start 163.07816 -301.170086)
		(end 163.339272 -301.170086)
		(width 0.14478)
		(layer "In4.Cu")
		(net "M_J_CPU1_SB_DQ<18>")
	)
	(segment
		(start 155.55722 -296.667936)
		(end 155.78582 -296.667936)
		(width 0.14478)
		(layer "In4.Cu")
		(net "M_J_CPU1_SB_DQ<18>")
	)
	(segment
		(start 160.646364 -301.170848)
		(end 160.874964 -301.170848)
		(width 0.14478)
		(layer "In4.Cu")
		(net "M_J_CPU1_SB_DQ<18>")
	)
	(segment
		(start 144.20088 -284.282642)
		(end 144.220946 -284.294072)
		(width 0.0889)
		(layer "In4.Cu")
		(net "M_J_CPU1_SB_DQ<18>")
	)
	(segment
		(start 181.285642 -301.460154)
		(end 182.135526 -300.61027)
		(width 0.14478)
		(layer "In4.Cu")
		(net "M_J_CPU1_SB_DQ<18>")
	)
	(segment
		(start 155.574492 -296.098976)
		(end 155.395676 -296.277792)
		(width 0.14478)
		(layer "In4.Cu")
		(net "M_J_CPU1_SB_DQ<18>")
	)
	(segment
		(start 141.393418 -284.288992)
		(end 141.4018 -284.293818)
		(width 0.0889)
		(layer "In4.Cu")
		(net "M_J_CPU1_SB_DQ<18>")
	)
	(segment
		(start 156.193236 -296.48912)
		(end 156.35478 -296.650664)
		(width 0.14478)
		(layer "In4.Cu")
		(net "M_J_CPU1_SB_DQ<18>")
	)
	(segment
		(start 159.314388 -299.610272)
		(end 159.475932 -299.771816)
		(width 0.14478)
		(layer "In4.Cu")
		(net "M_J_CPU1_SB_DQ<18>")
	)
	(segment
		(start 163.890706 -301.460408)
		(end 164.181028 -301.170086)
		(width 0.14478)
		(layer "In4.Cu")
		(net "M_J_CPU1_SB_DQ<18>")
	)
	(segment
		(start 155.395676 -296.277792)
		(end 155.395676 -296.506392)
		(width 0.14478)
		(layer "In4.Cu")
		(net "M_J_CPU1_SB_DQ<18>")
	)
	(segment
		(start 157.915356 -298.21124)
		(end 157.915356 -298.43984)
		(width 0.14478)
		(layer "In4.Cu")
		(net "M_J_CPU1_SB_DQ<18>")
	)
	(segment
		(start 185.075322 -300.61027)
		(end 185.32602 -300.61027)
		(width 0.14478)
		(layer "In4.Cu")
		(net "M_J_CPU1_SB_DQ<18>")
	)
	(segment
		(start 158.906972 -299.789088)
		(end 159.085788 -299.610272)
		(width 0.14478)
		(layer "In4.Cu")
		(net "M_J_CPU1_SB_DQ<18>")
	)
	(segment
		(start 159.085788 -299.610272)
		(end 159.314388 -299.610272)
		(width 0.14478)
		(layer "In4.Cu")
		(net "M_J_CPU1_SB_DQ<18>")
	)
	(segment
		(start 158.678372 -299.789088)
		(end 158.906972 -299.789088)
		(width 0.14478)
		(layer "In4.Cu")
		(net "M_J_CPU1_SB_DQ<18>")
	)
	(segment
		(start 161.68497 -301.460408)
		(end 161.975292 -301.170086)
		(width 0.14478)
		(layer "In4.Cu")
		(net "M_J_CPU1_SB_DQ<18>")
	)
	(segment
		(start 178.576478 -301.460154)
		(end 181.285642 -301.460154)
		(width 0.14478)
		(layer "In4.Cu")
		(net "M_J_CPU1_SB_DQ<18>")
	)
	(segment
		(start 158.516828 -299.398944)
		(end 158.516828 -299.627544)
		(width 0.14478)
		(layer "In4.Cu")
		(net "M_J_CPU1_SB_DQ<18>")
	)
	(segment
		(start 157.753812 -298.049696)
		(end 157.915356 -298.21124)
		(width 0.14478)
		(layer "In4.Cu")
		(net "M_J_CPU1_SB_DQ<18>")
	)
	(segment
		(start 161.975292 -301.170086)
		(end 162.236404 -301.170086)
		(width 0.14478)
		(layer "In4.Cu")
		(net "M_J_CPU1_SB_DQ<18>")
	)
	(segment
		(start 162.787838 -301.460408)
		(end 163.07816 -301.170086)
		(width 0.14478)
		(layer "In4.Cu")
		(net "M_J_CPU1_SB_DQ<18>")
	)
	(segment
		(start 165.283896 -301.170086)
		(end 165.545008 -301.170086)
		(width 0.14478)
		(layer "In4.Cu")
		(net "M_J_CPU1_SB_DQ<18>")
	)
	(segment
		(start 155.26385 -291.631116)
		(end 155.26385 -295.559734)
		(width 0.14478)
		(layer "In4.Cu")
		(net "M_J_CPU1_SB_DQ<18>")
	)
	(segment
		(start 156.956252 -297.838368)
		(end 156.956252 -298.066968)
		(width 0.14478)
		(layer "In4.Cu")
		(net "M_J_CPU1_SB_DQ<18>")
	)
	(segment
		(start 184.774586 -300.911006)
		(end 185.075322 -300.61027)
		(width 0.14478)
		(layer "In4.Cu")
		(net "M_J_CPU1_SB_DQ<18>")
	)
	(segment
		(start 174.447708 -300.61027)
		(end 177.726594 -300.61027)
		(width 0.14478)
		(layer "In4.Cu")
		(net "M_J_CPU1_SB_DQ<18>")
	)
	(segment
		(start 135.753348 -284.288992)
		(end 135.76173 -284.293818)
		(width 0.0889)
		(layer "In4.Cu")
		(net "M_J_CPU1_SB_DQ<18>")
	)
	(segment
		(start 185.626756 -300.911006)
		(end 185.877454 -300.911006)
		(width 0.14478)
		(layer "In4.Cu")
		(net "M_J_CPU1_SB_DQ<18>")
	)
	(segment
		(start 159.475932 -299.771816)
		(end 159.475932 -300.000416)
		(width 0.14478)
		(layer "In4.Cu")
		(net "M_J_CPU1_SB_DQ<18>")
	)
	(segment
		(start 147.637246 -285.068264)
		(end 147.912836 -285.068264)
		(width 0.0889)
		(layer "In4.Cu")
		(net "M_J_CPU1_SB_DQ<18>")
	)
	(segment
		(start 185.32602 -300.61027)
		(end 185.626756 -300.911006)
		(width 0.14478)
		(layer "In4.Cu")
		(net "M_J_CPU1_SB_DQ<18>")
	)
	(segment
		(start 157.73654 -298.847256)
		(end 157.898084 -299.0088)
		(width 0.14478)
		(layer "In4.Cu")
		(net "M_J_CPU1_SB_DQ<18>")
	)
	(segment
		(start 160.238948 -301.349664)
		(end 160.467548 -301.349664)
		(width 0.14478)
		(layer "In4.Cu")
		(net "M_J_CPU1_SB_DQ<18>")
	)
	(segment
		(start 159.68726 -300.569376)
		(end 159.866076 -300.39056)
		(width 0.14478)
		(layer "In4.Cu")
		(net "M_J_CPU1_SB_DQ<18>")
	)
	(segment
		(start 157.346396 -298.228512)
		(end 157.525212 -298.049696)
		(width 0.14478)
		(layer "In4.Cu")
		(net "M_J_CPU1_SB_DQ<18>")
	)
	(segment
		(start 156.337508 -297.448224)
		(end 156.566108 -297.448224)
		(width 0.14478)
		(layer "In4.Cu")
		(net "M_J_CPU1_SB_DQ<18>")
	)
	(segment
		(start 156.175964 -297.28668)
		(end 156.337508 -297.448224)
		(width 0.14478)
		(layer "In4.Cu")
		(net "M_J_CPU1_SB_DQ<18>")
	)
	(segment
		(start 182.135526 -300.61027)
		(end 184.223152 -300.61027)
		(width 0.14478)
		(layer "In4.Cu")
		(net "M_J_CPU1_SB_DQ<18>")
	)
	(segment
		(start 138.20775 -284.293818)
		(end 138.216132 -284.288992)
		(width 0.0889)
		(layer "In4.Cu")
		(net "M_J_CPU1_SB_DQ<18>")
	)
	(segment
		(start 156.35478 -296.879264)
		(end 156.175964 -297.05808)
		(width 0.14478)
		(layer "In4.Cu")
		(net "M_J_CPU1_SB_DQ<18>")
	)
	(segment
		(start 177.726594 -300.61027)
		(end 178.576478 -301.460154)
		(width 0.14478)
		(layer "In4.Cu")
		(net "M_J_CPU1_SB_DQ<18>")
	)
	(segment
		(start 158.516828 -299.627544)
		(end 158.678372 -299.789088)
		(width 0.14478)
		(layer "In4.Cu")
		(net "M_J_CPU1_SB_DQ<18>")
	)
	(segment
		(start 159.297116 -300.407832)
		(end 159.45866 -300.569376)
		(width 0.14478)
		(layer "In4.Cu")
		(net "M_J_CPU1_SB_DQ<18>")
	)
	(segment
		(start 155.26385 -295.559734)
		(end 155.574492 -295.870376)
		(width 0.14478)
		(layer "In4.Cu")
		(net "M_J_CPU1_SB_DQ<18>")
	)
	(segment
		(start 157.898084 -299.0088)
		(end 158.126684 -299.0088)
		(width 0.14478)
		(layer "In4.Cu")
		(net "M_J_CPU1_SB_DQ<18>")
	)
	(segment
		(start 144.220946 -284.294072)
		(end 144.242536 -284.306518)
		(width 0.0889)
		(layer "In4.Cu")
		(net "M_J_CPU1_SB_DQ<18>")
	)
	(segment
		(start 159.475932 -300.000416)
		(end 159.297116 -300.179232)
		(width 0.14478)
		(layer "In4.Cu")
		(net "M_J_CPU1_SB_DQ<18>")
	)
	(segment
		(start 165.545008 -301.170086)
		(end 165.83533 -301.460408)
		(width 0.14478)
		(layer "In4.Cu")
		(net "M_J_CPU1_SB_DQ<18>")
	)
	(segment
		(start 141.967712 -284.293818)
		(end 141.976094 -284.288992)
		(width 0.0889)
		(layer "In4.Cu")
		(net "M_J_CPU1_SB_DQ<18>")
	)
	(segment
		(start 170.18254 -300.61027)
		(end 171.032678 -301.460408)
		(width 0.14478)
		(layer "In4.Cu")
		(net "M_J_CPU1_SB_DQ<18>")
	)
	(segment
		(start 147.912836 -285.068264)
		(end 148.700998 -285.068264)
		(width 0.14478)
		(layer "In4.Cu")
		(net "M_J_CPU1_SB_DQ<18>")
	)
	(segment
		(start 155.964636 -296.48912)
		(end 156.193236 -296.48912)
		(width 0.14478)
		(layer "In4.Cu")
		(net "M_J_CPU1_SB_DQ<18>")
	)
	(segment
		(start 159.297116 -300.179232)
		(end 159.297116 -300.407832)
		(width 0.14478)
		(layer "In4.Cu")
		(net "M_J_CPU1_SB_DQ<18>")
	)
	(segment
		(start 162.236404 -301.170086)
		(end 162.526726 -301.460408)
		(width 0.14478)
		(layer "In4.Cu")
		(net "M_J_CPU1_SB_DQ<18>")
	)
	(segment
		(start 184.223152 -300.61027)
		(end 184.523888 -300.911006)
		(width 0.14478)
		(layer "In4.Cu")
		(net "M_J_CPU1_SB_DQ<18>")
	)
	(segment
		(start 146.79041 -284.959044)
		(end 147.528026 -284.959044)
		(width 0.0889)
		(layer "In4.Cu")
		(net "M_J_CPU1_SB_DQ<18>")
	)
	(segment
		(start 164.993574 -301.460408)
		(end 165.283896 -301.170086)
		(width 0.14478)
		(layer "In4.Cu")
		(net "M_J_CPU1_SB_DQ<18>")
	)
	(segment
		(start 163.629594 -301.460408)
		(end 163.890706 -301.460408)
		(width 0.14478)
		(layer "In4.Cu")
		(net "M_J_CPU1_SB_DQ<18>")
	)
	(segment
		(start 155.78582 -296.667936)
		(end 155.964636 -296.48912)
		(width 0.14478)
		(layer "In4.Cu")
		(net "M_J_CPU1_SB_DQ<18>")
	)
	(segment
		(start 186.17819 -300.61027)
		(end 186.635136 -300.61027)
		(width 0.14478)
		(layer "In4.Cu")
		(net "M_J_CPU1_SB_DQ<18>")
	)
	(segment
		(start 158.695644 -298.991528)
		(end 158.695644 -299.220128)
		(width 0.14478)
		(layer "In4.Cu")
		(net "M_J_CPU1_SB_DQ<18>")
	)
	(segment
		(start 158.3055 -298.829984)
		(end 158.5341 -298.829984)
		(width 0.14478)
		(layer "In4.Cu")
		(net "M_J_CPU1_SB_DQ<18>")
	)
	(arc
		(start 141.027658 -284.293818)
		(mid 141.209909 -284.243468)
		(end 141.393418 -284.288992)
		(width 0.0889)
		(layer "In4.Cu")
		(net "M_J_CPU1_SB_DQ<18>")
	)
	(arc
		(start 136.701784 -284.293818)
		(mid 136.98474 -284.369995)
		(end 137.267696 -284.293818)
		(width 0.0889)
		(layer "In4.Cu")
		(net "M_J_CPU1_SB_DQ<18>")
	)
	(arc
		(start 141.976094 -284.288992)
		(mid 142.159602 -284.243498)
		(end 142.341854 -284.293818)
		(width 0.0889)
		(layer "In4.Cu")
		(net "M_J_CPU1_SB_DQ<18>")
	)
	(arc
		(start 135.76173 -284.293818)
		(mid 136.044686 -284.369995)
		(end 136.327642 -284.293818)
		(width 0.0889)
		(layer "In4.Cu")
		(net "M_J_CPU1_SB_DQ<18>")
	)
	(arc
		(start 133.881876 -284.293818)
		(mid 134.164832 -284.369995)
		(end 134.447788 -284.293818)
		(width 0.0889)
		(layer "In4.Cu")
		(net "M_J_CPU1_SB_DQ<18>")
	)
	(arc
		(start 134.447788 -284.293818)
		(mid 134.634732 -284.243563)
		(end 134.821676 -284.293818)
		(width 0.0889)
		(layer "In4.Cu")
		(net "M_J_CPU1_SB_DQ<18>")
	)
	(arc
		(start 140.087604 -284.293818)
		(mid 140.269855 -284.243468)
		(end 140.453364 -284.288992)
		(width 0.0889)
		(layer "In4.Cu")
		(net "M_J_CPU1_SB_DQ<18>")
	)
	(arc
		(start 135.387588 -284.293818)
		(mid 135.569839 -284.243468)
		(end 135.753348 -284.288992)
		(width 0.0889)
		(layer "In4.Cu")
		(net "M_J_CPU1_SB_DQ<18>")
	)
	(arc
		(start 138.216132 -284.288992)
		(mid 138.39964 -284.243498)
		(end 138.581892 -284.293818)
		(width 0.0889)
		(layer "In4.Cu")
		(net "M_J_CPU1_SB_DQ<18>")
	)
	(arc
		(start 139.521692 -284.293818)
		(mid 139.804648 -284.369995)
		(end 140.087604 -284.293818)
		(width 0.0889)
		(layer "In4.Cu")
		(net "M_J_CPU1_SB_DQ<18>")
	)
	(arc
		(start 138.581892 -284.293818)
		(mid 138.864848 -284.369995)
		(end 139.147804 -284.293818)
		(width 0.0889)
		(layer "In4.Cu")
		(net "M_J_CPU1_SB_DQ<18>")
	)
	(arc
		(start 134.821676 -284.293818)
		(mid 135.104632 -284.369995)
		(end 135.387588 -284.293818)
		(width 0.0889)
		(layer "In4.Cu")
		(net "M_J_CPU1_SB_DQ<18>")
	)
	(arc
		(start 143.847566 -284.293818)
		(mid 144.022805 -284.243747)
		(end 144.20088 -284.282642)
		(width 0.0889)
		(layer "In4.Cu")
		(net "M_J_CPU1_SB_DQ<18>")
	)
	(arc
		(start 142.341854 -284.293818)
		(mid 142.62481 -284.369995)
		(end 142.907766 -284.293818)
		(width 0.0889)
		(layer "In4.Cu")
		(net "M_J_CPU1_SB_DQ<18>")
	)
	(arc
		(start 139.147804 -284.293818)
		(mid 139.334748 -284.243563)
		(end 139.521692 -284.293818)
		(width 0.0889)
		(layer "In4.Cu")
		(net "M_J_CPU1_SB_DQ<18>")
	)
	(arc
		(start 137.641838 -284.293818)
		(mid 137.924794 -284.369995)
		(end 138.20775 -284.293818)
		(width 0.0889)
		(layer "In4.Cu")
		(net "M_J_CPU1_SB_DQ<18>")
	)
	(arc
		(start 136.327642 -284.293818)
		(mid 136.509893 -284.243468)
		(end 136.693402 -284.288992)
		(width 0.0889)
		(layer "In4.Cu")
		(net "M_J_CPU1_SB_DQ<18>")
	)
	(arc
		(start 141.4018 -284.293818)
		(mid 141.684756 -284.369995)
		(end 141.967712 -284.293818)
		(width 0.0889)
		(layer "In4.Cu")
		(net "M_J_CPU1_SB_DQ<18>")
	)
	(arc
		(start 133.516116 -284.288992)
		(mid 133.699624 -284.243498)
		(end 133.881876 -284.293818)
		(width 0.0889)
		(layer "In4.Cu")
		(net "M_J_CPU1_SB_DQ<18>")
	)
	(arc
		(start 145.160492 -284.293818)
		(mid 145.297514 -284.351029)
		(end 145.444718 -284.370526)
		(width 0.0889)
		(layer "In4.Cu")
		(net "M_J_CPU1_SB_DQ<18>")
	)
	(arc
		(start 133.004814 -284.325568)
		(mid 133.260022 -284.369045)
		(end 133.507734 -284.293818)
		(width 0.0889)
		(layer "In4.Cu")
		(net "M_J_CPU1_SB_DQ<18>")
	)
	(arc
		(start 140.461746 -284.293818)
		(mid 140.744702 -284.369995)
		(end 141.027658 -284.293818)
		(width 0.0889)
		(layer "In4.Cu")
		(net "M_J_CPU1_SB_DQ<18>")
	)
	(arc
		(start 142.907766 -284.293818)
		(mid 143.09471 -284.243563)
		(end 143.281654 -284.293818)
		(width 0.0889)
		(layer "In4.Cu")
		(net "M_J_CPU1_SB_DQ<18>")
	)
	(arc
		(start 144.242536 -284.306518)
		(mid 144.515565 -284.369837)
		(end 144.785334 -284.293818)
		(width 0.0889)
		(layer "In4.Cu")
		(net "M_J_CPU1_SB_DQ<18>")
	)
	(arc
		(start 144.80413 -284.282896)
		(mid 144.983701 -284.243079)
		(end 145.160492 -284.293818)
		(width 0.0889)
		(layer "In4.Cu")
		(net "M_J_CPU1_SB_DQ<18>")
	)
	(arc
		(start 143.281654 -284.293818)
		(mid 143.56461 -284.369995)
		(end 143.847566 -284.293818)
		(width 0.0889)
		(layer "In4.Cu")
		(net "M_J_CPU1_SB_DQ<18>")
	)
	(arc
		(start 137.276078 -284.288992)
		(mid 137.459586 -284.243498)
		(end 137.641838 -284.293818)
		(width 0.0889)
		(layer "In4.Cu")
		(net "M_J_CPU1_SB_DQ<18>")
	)
	(segment
		(start 131.347972 -284.35046)
		(end 131.814824 -284.616398)
		(width 0.10668)
		(layer "F.Cu")
		(net "M_J_CPU1_SB_DQ<17>")
	)
	(segment
		(start 145.318988 -284.844744)
		(end 146.303492 -284.844744)
		(width 0.0889)
		(layer "In4.Cu")
		(net "M_J_CPU1_SB_DQ<17>")
	)
	(segment
		(start 178.511708 -302.310038)
		(end 181.279292 -302.310038)
		(width 0.14478)
		(layer "In4.Cu")
		(net "M_J_CPU1_SB_DQ<17>")
	)
	(segment
		(start 189.134496 -301.460154)
		(end 190.735204 -301.460154)
		(width 0.14478)
		(layer "In4.Cu")
		(net "M_J_CPU1_SB_DQ<17>")
	)
	(segment
		(start 190.735204 -301.460154)
		(end 191.160146 -301.885096)
		(width 0.14478)
		(layer "In4.Cu")
		(net "M_J_CPU1_SB_DQ<17>")
	)
	(segment
		(start 135.753348 -284.943804)
		(end 135.76173 -284.938978)
		(width 0.0889)
		(layer "In4.Cu")
		(net "M_J_CPU1_SB_DQ<17>")
	)
	(segment
		(start 131.660646 -284.881828)
		(end 131.682998 -284.96514)
		(width 0.0889)
		(layer "In4.Cu")
		(net "M_J_CPU1_SB_DQ<17>")
	)
	(segment
		(start 133.507734 -284.938978)
		(end 133.516116 -284.943804)
		(width 0.0889)
		(layer "In4.Cu")
		(net "M_J_CPU1_SB_DQ<17>")
	)
	(segment
		(start 170.117516 -301.460408)
		(end 170.9674 -302.310292)
		(width 0.14478)
		(layer "In4.Cu")
		(net "M_J_CPU1_SB_DQ<17>")
	)
	(segment
		(start 146.687032 -285.228284)
		(end 147.33016 -285.228284)
		(width 0.0889)
		(layer "In4.Cu")
		(net "M_J_CPU1_SB_DQ<17>")
	)
	(segment
		(start 154.81427 -291.817552)
		(end 154.81427 -296.561002)
		(width 0.14478)
		(layer "In4.Cu")
		(net "M_J_CPU1_SB_DQ<17>")
	)
	(segment
		(start 160.56356 -302.310292)
		(end 166.243 -302.310292)
		(width 0.14478)
		(layer "In4.Cu")
		(net "M_J_CPU1_SB_DQ<17>")
	)
	(segment
		(start 188.583062 -302.117506)
		(end 188.811408 -302.117506)
		(width 0.14478)
		(layer "In4.Cu")
		(net "M_J_CPU1_SB_DQ<17>")
	)
	(segment
		(start 167.092884 -301.460408)
		(end 170.117516 -301.460408)
		(width 0.14478)
		(layer "In4.Cu")
		(net "M_J_CPU1_SB_DQ<17>")
	)
	(segment
		(start 188.421518 -301.955962)
		(end 188.583062 -302.117506)
		(width 0.14478)
		(layer "In4.Cu")
		(net "M_J_CPU1_SB_DQ<17>")
	)
	(segment
		(start 173.690534 -302.310292)
		(end 174.540418 -301.460408)
		(width 0.14478)
		(layer "In4.Cu")
		(net "M_J_CPU1_SB_DQ<17>")
	)
	(segment
		(start 188.259974 -301.460154)
		(end 188.421518 -301.621698)
		(width 0.14478)
		(layer "In4.Cu")
		(net "M_J_CPU1_SB_DQ<17>")
	)
	(segment
		(start 148.519642 -285.522924)
		(end 154.81427 -291.817552)
		(width 0.14478)
		(layer "In4.Cu")
		(net "M_J_CPU1_SB_DQ<17>")
	)
	(segment
		(start 143.847566 -284.938978)
		(end 143.855948 -284.943804)
		(width 0.0889)
		(layer "In4.Cu")
		(net "M_J_CPU1_SB_DQ<17>")
	)
	(segment
		(start 188.972952 -301.621698)
		(end 189.134496 -301.460154)
		(width 0.14478)
		(layer "In4.Cu")
		(net "M_J_CPU1_SB_DQ<17>")
	)
	(segment
		(start 140.453364 -284.943804)
		(end 140.461746 -284.938978)
		(width 0.0889)
		(layer "In4.Cu")
		(net "M_J_CPU1_SB_DQ<17>")
	)
	(segment
		(start 131.814824 -284.616398)
		(end 131.660646 -284.881828)
		(width 0.0889)
		(layer "In4.Cu")
		(net "M_J_CPU1_SB_DQ<17>")
	)
	(segment
		(start 154.81427 -296.561002)
		(end 160.56356 -302.310292)
		(width 0.14478)
		(layer "In4.Cu")
		(net "M_J_CPU1_SB_DQ<17>")
	)
	(segment
		(start 147.85594 -285.522924)
		(end 148.519642 -285.522924)
		(width 0.14478)
		(layer "In4.Cu")
		(net "M_J_CPU1_SB_DQ<17>")
	)
	(segment
		(start 177.66157 -301.460408)
		(end 178.511454 -302.310292)
		(width 0.14478)
		(layer "In4.Cu")
		(net "M_J_CPU1_SB_DQ<17>")
	)
	(segment
		(start 166.243 -302.310292)
		(end 167.092884 -301.460408)
		(width 0.14478)
		(layer "In4.Cu")
		(net "M_J_CPU1_SB_DQ<17>")
	)
	(segment
		(start 170.9674 -302.310292)
		(end 173.690534 -302.310292)
		(width 0.14478)
		(layer "In4.Cu")
		(net "M_J_CPU1_SB_DQ<17>")
	)
	(segment
		(start 181.279292 -302.310038)
		(end 182.129176 -301.460154)
		(width 0.14478)
		(layer "In4.Cu")
		(net "M_J_CPU1_SB_DQ<17>")
	)
	(segment
		(start 145.146014 -284.948122)
		(end 145.318988 -284.844744)
		(width 0.0889)
		(layer "In4.Cu")
		(net "M_J_CPU1_SB_DQ<17>")
	)
	(segment
		(start 137.267696 -284.938978)
		(end 137.276078 -284.943804)
		(width 0.0889)
		(layer "In4.Cu")
		(net "M_J_CPU1_SB_DQ<17>")
	)
	(segment
		(start 188.972952 -301.955962)
		(end 188.972952 -301.621698)
		(width 0.14478)
		(layer "In4.Cu")
		(net "M_J_CPU1_SB_DQ<17>")
	)
	(segment
		(start 178.511454 -302.310292)
		(end 178.511708 -302.310038)
		(width 0.14478)
		(layer "In4.Cu")
		(net "M_J_CPU1_SB_DQ<17>")
	)
	(segment
		(start 146.303492 -284.844744)
		(end 146.687032 -285.228284)
		(width 0.0889)
		(layer "In4.Cu")
		(net "M_J_CPU1_SB_DQ<17>")
	)
	(segment
		(start 136.693402 -284.943804)
		(end 136.701784 -284.938978)
		(width 0.0889)
		(layer "In4.Cu")
		(net "M_J_CPU1_SB_DQ<17>")
	)
	(segment
		(start 131.993386 -284.943804)
		(end 132.001768 -284.938978)
		(width 0.0889)
		(layer "In4.Cu")
		(net "M_J_CPU1_SB_DQ<17>")
	)
	(segment
		(start 132.93344 -284.943804)
		(end 132.941822 -284.938978)
		(width 0.0889)
		(layer "In4.Cu")
		(net "M_J_CPU1_SB_DQ<17>")
	)
	(segment
		(start 191.160146 -301.885096)
		(end 191.160146 -301.88535)
		(width 0.14478)
		(layer "In4.Cu")
		(net "M_J_CPU1_SB_DQ<17>")
	)
	(segment
		(start 144.777968 -284.932882)
		(end 144.788382 -284.938978)
		(width 0.0889)
		(layer "In4.Cu")
		(net "M_J_CPU1_SB_DQ<17>")
	)
	(segment
		(start 141.393418 -284.943804)
		(end 141.4018 -284.938978)
		(width 0.0889)
		(layer "In4.Cu")
		(net "M_J_CPU1_SB_DQ<17>")
	)
	(segment
		(start 141.967712 -284.938978)
		(end 141.976094 -284.943804)
		(width 0.0889)
		(layer "In4.Cu")
		(net "M_J_CPU1_SB_DQ<17>")
	)
	(segment
		(start 188.811408 -302.117506)
		(end 188.972952 -301.955962)
		(width 0.14478)
		(layer "In4.Cu")
		(net "M_J_CPU1_SB_DQ<17>")
	)
	(segment
		(start 138.20775 -284.938978)
		(end 138.216132 -284.943804)
		(width 0.0889)
		(layer "In4.Cu")
		(net "M_J_CPU1_SB_DQ<17>")
	)
	(segment
		(start 147.33016 -285.228284)
		(end 147.6248 -285.522924)
		(width 0.0889)
		(layer "In4.Cu")
		(net "M_J_CPU1_SB_DQ<17>")
	)
	(segment
		(start 174.540418 -301.460408)
		(end 177.66157 -301.460408)
		(width 0.14478)
		(layer "In4.Cu")
		(net "M_J_CPU1_SB_DQ<17>")
	)
	(segment
		(start 182.129176 -301.460154)
		(end 188.259974 -301.460154)
		(width 0.14478)
		(layer "In4.Cu")
		(net "M_J_CPU1_SB_DQ<17>")
	)
	(segment
		(start 147.6248 -285.522924)
		(end 147.85594 -285.522924)
		(width 0.0889)
		(layer "In4.Cu")
		(net "M_J_CPU1_SB_DQ<17>")
	)
	(segment
		(start 188.421518 -301.621698)
		(end 188.421518 -301.955962)
		(width 0.14478)
		(layer "In4.Cu")
		(net "M_J_CPU1_SB_DQ<17>")
	)
	(arc
		(start 133.881876 -284.938978)
		(mid 134.164832 -284.862801)
		(end 134.447788 -284.938978)
		(width 0.0889)
		(layer "In4.Cu")
		(net "M_J_CPU1_SB_DQ<17>")
	)
	(arc
		(start 142.341854 -284.938978)
		(mid 142.62481 -284.862801)
		(end 142.907766 -284.938978)
		(width 0.0889)
		(layer "In4.Cu")
		(net "M_J_CPU1_SB_DQ<17>")
	)
	(arc
		(start 139.521692 -284.938978)
		(mid 139.804648 -284.862801)
		(end 140.087604 -284.938978)
		(width 0.0889)
		(layer "In4.Cu")
		(net "M_J_CPU1_SB_DQ<17>")
	)
	(arc
		(start 135.76173 -284.938978)
		(mid 136.044686 -284.862801)
		(end 136.327642 -284.938978)
		(width 0.0889)
		(layer "In4.Cu")
		(net "M_J_CPU1_SB_DQ<17>")
	)
	(arc
		(start 137.276078 -284.943804)
		(mid 137.459586 -284.989298)
		(end 137.641838 -284.938978)
		(width 0.0889)
		(layer "In4.Cu")
		(net "M_J_CPU1_SB_DQ<17>")
	)
	(arc
		(start 141.4018 -284.938978)
		(mid 141.684756 -284.862801)
		(end 141.967712 -284.938978)
		(width 0.0889)
		(layer "In4.Cu")
		(net "M_J_CPU1_SB_DQ<17>")
	)
	(arc
		(start 133.516116 -284.943804)
		(mid 133.699624 -284.989298)
		(end 133.881876 -284.938978)
		(width 0.0889)
		(layer "In4.Cu")
		(net "M_J_CPU1_SB_DQ<17>")
	)
	(arc
		(start 140.087604 -284.938978)
		(mid 140.269855 -284.989328)
		(end 140.453364 -284.943804)
		(width 0.0889)
		(layer "In4.Cu")
		(net "M_J_CPU1_SB_DQ<17>")
	)
	(arc
		(start 144.788382 -284.938978)
		(mid 144.966032 -284.989238)
		(end 145.146014 -284.948122)
		(width 0.0889)
		(layer "In4.Cu")
		(net "M_J_CPU1_SB_DQ<17>")
	)
	(arc
		(start 136.701784 -284.938978)
		(mid 136.98474 -284.862801)
		(end 137.267696 -284.938978)
		(width 0.0889)
		(layer "In4.Cu")
		(net "M_J_CPU1_SB_DQ<17>")
	)
	(arc
		(start 132.941822 -284.938978)
		(mid 133.224778 -284.862801)
		(end 133.507734 -284.938978)
		(width 0.0889)
		(layer "In4.Cu")
		(net "M_J_CPU1_SB_DQ<17>")
	)
	(arc
		(start 141.976094 -284.943804)
		(mid 142.159602 -284.989298)
		(end 142.341854 -284.938978)
		(width 0.0889)
		(layer "In4.Cu")
		(net "M_J_CPU1_SB_DQ<17>")
	)
	(arc
		(start 143.855948 -284.943804)
		(mid 144.03971 -284.98942)
		(end 144.222216 -284.938978)
		(width 0.0889)
		(layer "In4.Cu")
		(net "M_J_CPU1_SB_DQ<17>")
	)
	(arc
		(start 134.821676 -284.938978)
		(mid 135.104632 -284.862801)
		(end 135.387588 -284.938978)
		(width 0.0889)
		(layer "In4.Cu")
		(net "M_J_CPU1_SB_DQ<17>")
	)
	(arc
		(start 132.56768 -284.938978)
		(mid 132.749931 -284.989328)
		(end 132.93344 -284.943804)
		(width 0.0889)
		(layer "In4.Cu")
		(net "M_J_CPU1_SB_DQ<17>")
	)
	(arc
		(start 139.147804 -284.938978)
		(mid 139.334748 -284.989233)
		(end 139.521692 -284.938978)
		(width 0.0889)
		(layer "In4.Cu")
		(net "M_J_CPU1_SB_DQ<17>")
	)
	(arc
		(start 141.027658 -284.938978)
		(mid 141.209909 -284.989328)
		(end 141.393418 -284.943804)
		(width 0.0889)
		(layer "In4.Cu")
		(net "M_J_CPU1_SB_DQ<17>")
	)
	(arc
		(start 143.281654 -284.938978)
		(mid 143.56461 -284.862801)
		(end 143.847566 -284.938978)
		(width 0.0889)
		(layer "In4.Cu")
		(net "M_J_CPU1_SB_DQ<17>")
	)
	(arc
		(start 137.641838 -284.938978)
		(mid 137.924794 -284.862801)
		(end 138.20775 -284.938978)
		(width 0.0889)
		(layer "In4.Cu")
		(net "M_J_CPU1_SB_DQ<17>")
	)
	(arc
		(start 136.327642 -284.938978)
		(mid 136.509893 -284.989328)
		(end 136.693402 -284.943804)
		(width 0.0889)
		(layer "In4.Cu")
		(net "M_J_CPU1_SB_DQ<17>")
	)
	(arc
		(start 134.447788 -284.938978)
		(mid 134.634732 -284.989233)
		(end 134.821676 -284.938978)
		(width 0.0889)
		(layer "In4.Cu")
		(net "M_J_CPU1_SB_DQ<17>")
	)
	(arc
		(start 144.222216 -284.938978)
		(mid 144.499283 -284.862707)
		(end 144.777968 -284.932882)
		(width 0.0889)
		(layer "In4.Cu")
		(net "M_J_CPU1_SB_DQ<17>")
	)
	(arc
		(start 132.001768 -284.938978)
		(mid 132.284724 -284.862801)
		(end 132.56768 -284.938978)
		(width 0.0889)
		(layer "In4.Cu")
		(net "M_J_CPU1_SB_DQ<17>")
	)
	(arc
		(start 140.461746 -284.938978)
		(mid 140.744702 -284.862801)
		(end 141.027658 -284.938978)
		(width 0.0889)
		(layer "In4.Cu")
		(net "M_J_CPU1_SB_DQ<17>")
	)
	(arc
		(start 131.682998 -284.96514)
		(mid 131.840508 -284.988338)
		(end 131.993386 -284.943804)
		(width 0.0889)
		(layer "In4.Cu")
		(net "M_J_CPU1_SB_DQ<17>")
	)
	(arc
		(start 142.907766 -284.938978)
		(mid 143.09471 -284.989233)
		(end 143.281654 -284.938978)
		(width 0.0889)
		(layer "In4.Cu")
		(net "M_J_CPU1_SB_DQ<17>")
	)
	(arc
		(start 135.387588 -284.938978)
		(mid 135.569839 -284.989328)
		(end 135.753348 -284.943804)
		(width 0.0889)
		(layer "In4.Cu")
		(net "M_J_CPU1_SB_DQ<17>")
	)
	(arc
		(start 138.216132 -284.943804)
		(mid 138.39964 -284.989298)
		(end 138.581892 -284.938978)
		(width 0.0889)
		(layer "In4.Cu")
		(net "M_J_CPU1_SB_DQ<17>")
	)
	(arc
		(start 138.581892 -284.938978)
		(mid 138.864848 -284.862801)
		(end 139.147804 -284.938978)
		(width 0.0889)
		(layer "In4.Cu")
		(net "M_J_CPU1_SB_DQ<17>")
	)
	(segment
		(start 132.757926 -283.540454)
		(end 133.224778 -283.806392)
		(width 0.10668)
		(layer "F.Cu")
		(net "M_J_CPU1_SB_DQ<16>")
	)
	(segment
		(start 147.373086 -284.613604)
		(end 147.86737 -284.613604)
		(width 0.0889)
		(layer "In4.Cu")
		(net "M_J_CPU1_SB_DQ<16>")
	)
	(segment
		(start 177.683922 -299.760386)
		(end 178.533552 -300.610016)
		(width 0.14478)
		(layer "In4.Cu")
		(net "M_J_CPU1_SB_DQ<16>")
	)
	(segment
		(start 147.258786 -284.727904)
		(end 147.373086 -284.613604)
		(width 0.0889)
		(layer "In4.Cu")
		(net "M_J_CPU1_SB_DQ<16>")
	)
	(segment
		(start 145.444972 -284.180026)
		(end 146.347688 -284.180026)
		(width 0.0889)
		(layer "In4.Cu")
		(net "M_J_CPU1_SB_DQ<16>")
	)
	(segment
		(start 188.895228 -299.760132)
		(end 189.123574 -299.760132)
		(width 0.14478)
		(layer "In4.Cu")
		(net "M_J_CPU1_SB_DQ<16>")
	)
	(segment
		(start 135.857742 -284.128972)
		(end 135.866124 -284.133798)
		(width 0.0889)
		(layer "In4.Cu")
		(net "M_J_CPU1_SB_DQ<16>")
	)
	(segment
		(start 190.735204 -299.760132)
		(end 191.160146 -300.185074)
		(width 0.14478)
		(layer "In4.Cu")
		(net "M_J_CPU1_SB_DQ<16>")
	)
	(segment
		(start 145.444718 -284.179772)
		(end 145.444972 -284.180026)
		(width 0.0889)
		(layer "In4.Cu")
		(net "M_J_CPU1_SB_DQ<16>")
	)
	(segment
		(start 188.733684 -299.921676)
		(end 188.895228 -299.760132)
		(width 0.14478)
		(layer "In4.Cu")
		(net "M_J_CPU1_SB_DQ<16>")
	)
	(segment
		(start 167.092884 -299.760386)
		(end 170.117516 -299.760386)
		(width 0.14478)
		(layer "In4.Cu")
		(net "M_J_CPU1_SB_DQ<16>")
	)
	(segment
		(start 133.224778 -283.806392)
		(end 133.070854 -284.071822)
		(width 0.0889)
		(layer "In4.Cu")
		(net "M_J_CPU1_SB_DQ<16>")
	)
	(segment
		(start 188.18225 -300.480222)
		(end 188.343794 -300.641766)
		(width 0.14478)
		(layer "In4.Cu")
		(net "M_J_CPU1_SB_DQ<16>")
	)
	(segment
		(start 170.9674 -300.61027)
		(end 173.787054 -300.61027)
		(width 0.14478)
		(layer "In4.Cu")
		(net "M_J_CPU1_SB_DQ<16>")
	)
	(segment
		(start 138.103356 -284.133798)
		(end 138.111738 -284.128972)
		(width 0.0889)
		(layer "In4.Cu")
		(net "M_J_CPU1_SB_DQ<16>")
	)
	(segment
		(start 144.316196 -284.128718)
		(end 144.334484 -284.139132)
		(width 0.0889)
		(layer "In4.Cu")
		(net "M_J_CPU1_SB_DQ<16>")
	)
	(segment
		(start 142.803372 -284.133798)
		(end 142.811754 -284.128972)
		(width 0.0889)
		(layer "In4.Cu")
		(net "M_J_CPU1_SB_DQ<16>")
	)
	(segment
		(start 166.243 -300.61027)
		(end 167.092884 -299.760386)
		(width 0.14478)
		(layer "In4.Cu")
		(net "M_J_CPU1_SB_DQ<16>")
	)
	(segment
		(start 189.446662 -300.641766)
		(end 189.675008 -300.641766)
		(width 0.14478)
		(layer "In4.Cu")
		(net "M_J_CPU1_SB_DQ<16>")
	)
	(segment
		(start 189.123574 -299.760132)
		(end 189.285118 -299.921676)
		(width 0.14478)
		(layer "In4.Cu")
		(net "M_J_CPU1_SB_DQ<16>")
	)
	(segment
		(start 189.998096 -299.760132)
		(end 190.735204 -299.760132)
		(width 0.14478)
		(layer "In4.Cu")
		(net "M_J_CPU1_SB_DQ<16>")
	)
	(segment
		(start 133.070854 -284.071822)
		(end 133.093206 -284.155134)
		(width 0.0889)
		(layer "In4.Cu")
		(net "M_J_CPU1_SB_DQ<16>")
	)
	(segment
		(start 170.117516 -299.760386)
		(end 170.9674 -300.61027)
		(width 0.14478)
		(layer "In4.Cu")
		(net "M_J_CPU1_SB_DQ<16>")
	)
	(segment
		(start 146.347688 -284.180026)
		(end 146.895566 -284.727904)
		(width 0.0889)
		(layer "In4.Cu")
		(net "M_J_CPU1_SB_DQ<16>")
	)
	(segment
		(start 144.294606 -284.116272)
		(end 144.316196 -284.128718)
		(width 0.0889)
		(layer "In4.Cu")
		(net "M_J_CPU1_SB_DQ<16>")
	)
	(segment
		(start 147.86737 -284.613604)
		(end 148.882354 -284.613604)
		(width 0.14478)
		(layer "In4.Cu")
		(net "M_J_CPU1_SB_DQ<16>")
	)
	(segment
		(start 146.895566 -284.727904)
		(end 147.258786 -284.727904)
		(width 0.0889)
		(layer "In4.Cu")
		(net "M_J_CPU1_SB_DQ<16>")
	)
	(segment
		(start 189.675008 -300.641766)
		(end 189.836552 -300.480222)
		(width 0.14478)
		(layer "In4.Cu")
		(net "M_J_CPU1_SB_DQ<16>")
	)
	(segment
		(start 189.285118 -299.921676)
		(end 189.285118 -300.480222)
		(width 0.14478)
		(layer "In4.Cu")
		(net "M_J_CPU1_SB_DQ<16>")
	)
	(segment
		(start 155.71343 -291.44468)
		(end 155.71343 -295.373298)
		(width 0.14478)
		(layer "In4.Cu")
		(net "M_J_CPU1_SB_DQ<16>")
	)
	(segment
		(start 139.04341 -284.133798)
		(end 139.051792 -284.128972)
		(width 0.0889)
		(layer "In4.Cu")
		(net "M_J_CPU1_SB_DQ<16>")
	)
	(segment
		(start 181.361588 -300.610016)
		(end 182.211472 -299.760132)
		(width 0.14478)
		(layer "In4.Cu")
		(net "M_J_CPU1_SB_DQ<16>")
	)
	(segment
		(start 174.636938 -299.760386)
		(end 177.683922 -299.760386)
		(width 0.14478)
		(layer "In4.Cu")
		(net "M_J_CPU1_SB_DQ<16>")
	)
	(segment
		(start 188.733684 -300.480222)
		(end 188.733684 -299.921676)
		(width 0.14478)
		(layer "In4.Cu")
		(net "M_J_CPU1_SB_DQ<16>")
	)
	(segment
		(start 160.950402 -300.61027)
		(end 166.243 -300.61027)
		(width 0.14478)
		(layer "In4.Cu")
		(net "M_J_CPU1_SB_DQ<16>")
	)
	(segment
		(start 189.836552 -299.921676)
		(end 189.998096 -299.760132)
		(width 0.14478)
		(layer "In4.Cu")
		(net "M_J_CPU1_SB_DQ<16>")
	)
	(segment
		(start 189.836552 -300.480222)
		(end 189.836552 -299.921676)
		(width 0.14478)
		(layer "In4.Cu")
		(net "M_J_CPU1_SB_DQ<16>")
	)
	(segment
		(start 144.689322 -284.128972)
		(end 144.71269 -284.115256)
		(width 0.0889)
		(layer "In4.Cu")
		(net "M_J_CPU1_SB_DQ<16>")
	)
	(segment
		(start 188.18225 -299.921676)
		(end 188.18225 -300.480222)
		(width 0.14478)
		(layer "In4.Cu")
		(net "M_J_CPU1_SB_DQ<16>")
	)
	(segment
		(start 182.211472 -299.760132)
		(end 188.020706 -299.760132)
		(width 0.14478)
		(layer "In4.Cu")
		(net "M_J_CPU1_SB_DQ<16>")
	)
	(segment
		(start 188.020706 -299.760132)
		(end 188.18225 -299.921676)
		(width 0.14478)
		(layer "In4.Cu")
		(net "M_J_CPU1_SB_DQ<16>")
	)
	(segment
		(start 139.617704 -284.128972)
		(end 139.626086 -284.133798)
		(width 0.0889)
		(layer "In4.Cu")
		(net "M_J_CPU1_SB_DQ<16>")
	)
	(segment
		(start 189.285118 -300.480222)
		(end 189.446662 -300.641766)
		(width 0.14478)
		(layer "In4.Cu")
		(net "M_J_CPU1_SB_DQ<16>")
	)
	(segment
		(start 191.160146 -300.185074)
		(end 191.160146 -300.185328)
		(width 0.14478)
		(layer "In4.Cu")
		(net "M_J_CPU1_SB_DQ<16>")
	)
	(segment
		(start 178.533552 -300.610016)
		(end 181.361588 -300.610016)
		(width 0.14478)
		(layer "In4.Cu")
		(net "M_J_CPU1_SB_DQ<16>")
	)
	(segment
		(start 155.71343 -295.373298)
		(end 160.950402 -300.61027)
		(width 0.14478)
		(layer "In4.Cu")
		(net "M_J_CPU1_SB_DQ<16>")
	)
	(segment
		(start 173.787054 -300.61027)
		(end 174.636938 -299.760386)
		(width 0.14478)
		(layer "In4.Cu")
		(net "M_J_CPU1_SB_DQ<16>")
	)
	(segment
		(start 134.343394 -284.133798)
		(end 134.351776 -284.128972)
		(width 0.0889)
		(layer "In4.Cu")
		(net "M_J_CPU1_SB_DQ<16>")
	)
	(segment
		(start 140.557758 -284.128972)
		(end 140.56614 -284.133798)
		(width 0.0889)
		(layer "In4.Cu")
		(net "M_J_CPU1_SB_DQ<16>")
	)
	(segment
		(start 148.882354 -284.613604)
		(end 155.71343 -291.44468)
		(width 0.14478)
		(layer "In4.Cu")
		(net "M_J_CPU1_SB_DQ<16>")
	)
	(segment
		(start 188.57214 -300.641766)
		(end 188.733684 -300.480222)
		(width 0.14478)
		(layer "In4.Cu")
		(net "M_J_CPU1_SB_DQ<16>")
	)
	(segment
		(start 143.377666 -284.128972)
		(end 143.386048 -284.133798)
		(width 0.0889)
		(layer "In4.Cu")
		(net "M_J_CPU1_SB_DQ<16>")
	)
	(segment
		(start 188.343794 -300.641766)
		(end 188.57214 -300.641766)
		(width 0.14478)
		(layer "In4.Cu")
		(net "M_J_CPU1_SB_DQ<16>")
	)
	(segment
		(start 134.917688 -284.128972)
		(end 134.92607 -284.133798)
		(width 0.0889)
		(layer "In4.Cu")
		(net "M_J_CPU1_SB_DQ<16>")
	)
	(arc
		(start 143.386048 -284.133798)
		(mid 143.569556 -284.179292)
		(end 143.751808 -284.128972)
		(width 0.0889)
		(layer "In4.Cu")
		(net "M_J_CPU1_SB_DQ<16>")
	)
	(arc
		(start 137.171684 -284.128972)
		(mid 137.45464 -284.052795)
		(end 137.737596 -284.128972)
		(width 0.0889)
		(layer "In4.Cu")
		(net "M_J_CPU1_SB_DQ<16>")
	)
	(arc
		(start 133.093206 -284.155134)
		(mid 133.255395 -284.177869)
		(end 133.411722 -284.128972)
		(width 0.0889)
		(layer "In4.Cu")
		(net "M_J_CPU1_SB_DQ<16>")
	)
	(arc
		(start 145.256504 -284.128972)
		(mid 145.347239 -284.166856)
		(end 145.444718 -284.179772)
		(width 0.0889)
		(layer "In4.Cu")
		(net "M_J_CPU1_SB_DQ<16>")
	)
	(arc
		(start 141.497812 -284.128972)
		(mid 141.684756 -284.179227)
		(end 141.8717 -284.128972)
		(width 0.0889)
		(layer "In4.Cu")
		(net "M_J_CPU1_SB_DQ<16>")
	)
	(arc
		(start 138.67765 -284.128972)
		(mid 138.859901 -284.179322)
		(end 139.04341 -284.133798)
		(width 0.0889)
		(layer "In4.Cu")
		(net "M_J_CPU1_SB_DQ<16>")
	)
	(arc
		(start 133.977634 -284.128972)
		(mid 134.159885 -284.179322)
		(end 134.343394 -284.133798)
		(width 0.0889)
		(layer "In4.Cu")
		(net "M_J_CPU1_SB_DQ<16>")
	)
	(arc
		(start 135.29183 -284.128972)
		(mid 135.574786 -284.052795)
		(end 135.857742 -284.128972)
		(width 0.0889)
		(layer "In4.Cu")
		(net "M_J_CPU1_SB_DQ<16>")
	)
	(arc
		(start 138.111738 -284.128972)
		(mid 138.394694 -284.052795)
		(end 138.67765 -284.128972)
		(width 0.0889)
		(layer "In4.Cu")
		(net "M_J_CPU1_SB_DQ<16>")
	)
	(arc
		(start 136.797796 -284.128972)
		(mid 136.98474 -284.179227)
		(end 137.171684 -284.128972)
		(width 0.0889)
		(layer "In4.Cu")
		(net "M_J_CPU1_SB_DQ<16>")
	)
	(arc
		(start 143.751808 -284.128972)
		(mid 144.021577 -284.052949)
		(end 144.294606 -284.116272)
		(width 0.0889)
		(layer "In4.Cu")
		(net "M_J_CPU1_SB_DQ<16>")
	)
	(arc
		(start 134.92607 -284.133798)
		(mid 135.109578 -284.179292)
		(end 135.29183 -284.128972)
		(width 0.0889)
		(layer "In4.Cu")
		(net "M_J_CPU1_SB_DQ<16>")
	)
	(arc
		(start 134.351776 -284.128972)
		(mid 134.634732 -284.052795)
		(end 134.917688 -284.128972)
		(width 0.0889)
		(layer "In4.Cu")
		(net "M_J_CPU1_SB_DQ<16>")
	)
	(arc
		(start 139.051792 -284.128972)
		(mid 139.334748 -284.052795)
		(end 139.617704 -284.128972)
		(width 0.0889)
		(layer "In4.Cu")
		(net "M_J_CPU1_SB_DQ<16>")
	)
	(arc
		(start 140.9319 -284.128972)
		(mid 141.214856 -284.052795)
		(end 141.497812 -284.128972)
		(width 0.0889)
		(layer "In4.Cu")
		(net "M_J_CPU1_SB_DQ<16>")
	)
	(arc
		(start 133.411722 -284.128972)
		(mid 133.694678 -284.052795)
		(end 133.977634 -284.128972)
		(width 0.0889)
		(layer "In4.Cu")
		(net "M_J_CPU1_SB_DQ<16>")
	)
	(arc
		(start 136.231884 -284.128972)
		(mid 136.51484 -284.052795)
		(end 136.797796 -284.128972)
		(width 0.0889)
		(layer "In4.Cu")
		(net "M_J_CPU1_SB_DQ<16>")
	)
	(arc
		(start 144.71269 -284.115256)
		(mid 144.986344 -284.052313)
		(end 145.256504 -284.128972)
		(width 0.0889)
		(layer "In4.Cu")
		(net "M_J_CPU1_SB_DQ<16>")
	)
	(arc
		(start 142.811754 -284.128972)
		(mid 143.09471 -284.052795)
		(end 143.377666 -284.128972)
		(width 0.0889)
		(layer "In4.Cu")
		(net "M_J_CPU1_SB_DQ<16>")
	)
	(arc
		(start 139.991846 -284.128972)
		(mid 140.274802 -284.052795)
		(end 140.557758 -284.128972)
		(width 0.0889)
		(layer "In4.Cu")
		(net "M_J_CPU1_SB_DQ<16>")
	)
	(arc
		(start 135.866124 -284.133798)
		(mid 136.049632 -284.179292)
		(end 136.231884 -284.128972)
		(width 0.0889)
		(layer "In4.Cu")
		(net "M_J_CPU1_SB_DQ<16>")
	)
	(arc
		(start 139.626086 -284.133798)
		(mid 139.809594 -284.179292)
		(end 139.991846 -284.128972)
		(width 0.0889)
		(layer "In4.Cu")
		(net "M_J_CPU1_SB_DQ<16>")
	)
	(arc
		(start 144.334484 -284.139132)
		(mid 144.513205 -284.179055)
		(end 144.689322 -284.128972)
		(width 0.0889)
		(layer "In4.Cu")
		(net "M_J_CPU1_SB_DQ<16>")
	)
	(arc
		(start 137.737596 -284.128972)
		(mid 137.919847 -284.179322)
		(end 138.103356 -284.133798)
		(width 0.0889)
		(layer "In4.Cu")
		(net "M_J_CPU1_SB_DQ<16>")
	)
	(arc
		(start 140.56614 -284.133798)
		(mid 140.749648 -284.179292)
		(end 140.9319 -284.128972)
		(width 0.0889)
		(layer "In4.Cu")
		(net "M_J_CPU1_SB_DQ<16>")
	)
	(arc
		(start 141.8717 -284.128972)
		(mid 142.154656 -284.052795)
		(end 142.437612 -284.128972)
		(width 0.0889)
		(layer "In4.Cu")
		(net "M_J_CPU1_SB_DQ<16>")
	)
	(arc
		(start 142.437612 -284.128972)
		(mid 142.619863 -284.179322)
		(end 142.803372 -284.133798)
		(width 0.0889)
		(layer "In4.Cu")
		(net "M_J_CPU1_SB_DQ<16>")
	)
	(segment
		(start 130.877818 -283.540454)
		(end 131.34467 -283.806392)
		(width 0.10668)
		(layer "F.Cu")
		(net "M_J_CPU1_SB_DQ<15>")
	)
	(segment
		(start 169.502074 -298.612306)
		(end 169.80027 -298.910502)
		(width 0.14478)
		(layer "In4.Cu")
		(net "M_J_CPU1_SB_DQ<15>")
	)
	(segment
		(start 146.179286 -283.412946)
		(end 146.45386 -283.68752)
		(width 0.0889)
		(layer "In4.Cu")
		(net "M_J_CPU1_SB_DQ<15>")
	)
	(segment
		(start 185.14441 -298.910502)
		(end 185.402728 -298.910502)
		(width 0.14478)
		(layer "In4.Cu")
		(net "M_J_CPU1_SB_DQ<15>")
	)
	(segment
		(start 165.13048 -299.455586)
		(end 165.37686 -299.455586)
		(width 0.14478)
		(layer "In4.Cu")
		(net "M_J_CPU1_SB_DQ<15>")
	)
	(segment
		(start 143.377666 -283.483812)
		(end 143.386048 -283.478986)
		(width 0.0889)
		(layer "In4.Cu")
		(net "M_J_CPU1_SB_DQ<15>")
	)
	(segment
		(start 145.51787 -283.412946)
		(end 146.179286 -283.412946)
		(width 0.0889)
		(layer "In4.Cu")
		(net "M_J_CPU1_SB_DQ<15>")
	)
	(segment
		(start 168.95064 -298.910502)
		(end 169.248836 -298.612306)
		(width 0.14478)
		(layer "In4.Cu")
		(net "M_J_CPU1_SB_DQ<15>")
	)
	(segment
		(start 169.248836 -298.612306)
		(end 169.502074 -298.612306)
		(width 0.14478)
		(layer "In4.Cu")
		(net "M_J_CPU1_SB_DQ<15>")
	)
	(segment
		(start 139.617704 -283.483812)
		(end 139.626086 -283.478986)
		(width 0.0889)
		(layer "In4.Cu")
		(net "M_J_CPU1_SB_DQ<15>")
	)
	(segment
		(start 184.29986 -298.910502)
		(end 184.592976 -298.617386)
		(width 0.14478)
		(layer "In4.Cu")
		(net "M_J_CPU1_SB_DQ<15>")
	)
	(segment
		(start 140.557758 -283.483812)
		(end 140.56614 -283.478986)
		(width 0.0889)
		(layer "In4.Cu")
		(net "M_J_CPU1_SB_DQ<15>")
	)
	(segment
		(start 184.851294 -298.617386)
		(end 185.14441 -298.910502)
		(width 0.14478)
		(layer "In4.Cu")
		(net "M_J_CPU1_SB_DQ<15>")
	)
	(segment
		(start 156.26461 -291.21608)
		(end 156.26461 -295.144698)
		(width 0.14478)
		(layer "In4.Cu")
		(net "M_J_CPU1_SB_DQ<15>")
	)
	(segment
		(start 169.80027 -298.910502)
		(end 170.18254 -298.910502)
		(width 0.14478)
		(layer "In4.Cu")
		(net "M_J_CPU1_SB_DQ<15>")
	)
	(segment
		(start 162.924744 -299.455586)
		(end 163.171124 -299.455586)
		(width 0.14478)
		(layer "In4.Cu")
		(net "M_J_CPU1_SB_DQ<15>")
	)
	(segment
		(start 186.635136 -298.910502)
		(end 187.060078 -299.335444)
		(width 0.14478)
		(layer "In4.Cu")
		(net "M_J_CPU1_SB_DQ<15>")
	)
	(segment
		(start 166.150036 -299.76064)
		(end 167.000174 -298.910502)
		(width 0.14478)
		(layer "In4.Cu")
		(net "M_J_CPU1_SB_DQ<15>")
	)
	(segment
		(start 181.400958 -299.760132)
		(end 182.250588 -298.910502)
		(width 0.14478)
		(layer "In4.Cu")
		(net "M_J_CPU1_SB_DQ<15>")
	)
	(segment
		(start 185.695844 -298.617386)
		(end 185.954162 -298.617386)
		(width 0.14478)
		(layer "In4.Cu")
		(net "M_J_CPU1_SB_DQ<15>")
	)
	(segment
		(start 168.697402 -298.910502)
		(end 168.95064 -298.910502)
		(width 0.14478)
		(layer "In4.Cu")
		(net "M_J_CPU1_SB_DQ<15>")
	)
	(segment
		(start 185.402728 -298.910502)
		(end 185.695844 -298.617386)
		(width 0.14478)
		(layer "In4.Cu")
		(net "M_J_CPU1_SB_DQ<15>")
	)
	(segment
		(start 165.37686 -299.455586)
		(end 165.681914 -299.76064)
		(width 0.14478)
		(layer "In4.Cu")
		(net "M_J_CPU1_SB_DQ<15>")
	)
	(segment
		(start 162.068256 -299.455586)
		(end 162.37331 -299.76064)
		(width 0.14478)
		(layer "In4.Cu")
		(net "M_J_CPU1_SB_DQ<15>")
	)
	(segment
		(start 156.26461 -295.144698)
		(end 160.880552 -299.76064)
		(width 0.14478)
		(layer "In4.Cu")
		(net "M_J_CPU1_SB_DQ<15>")
	)
	(segment
		(start 147.275042 -283.68752)
		(end 147.644866 -284.057344)
		(width 0.0889)
		(layer "In4.Cu")
		(net "M_J_CPU1_SB_DQ<15>")
	)
	(segment
		(start 163.476178 -299.76064)
		(end 163.722558 -299.76064)
		(width 0.14478)
		(layer "In4.Cu")
		(net "M_J_CPU1_SB_DQ<15>")
	)
	(segment
		(start 142.803372 -283.478986)
		(end 142.811754 -283.483812)
		(width 0.0889)
		(layer "In4.Cu")
		(net "M_J_CPU1_SB_DQ<15>")
	)
	(segment
		(start 135.857742 -283.483812)
		(end 135.866124 -283.478986)
		(width 0.0889)
		(layer "In4.Cu")
		(net "M_J_CPU1_SB_DQ<15>")
	)
	(segment
		(start 164.579046 -299.76064)
		(end 164.825426 -299.76064)
		(width 0.14478)
		(layer "In4.Cu")
		(net "M_J_CPU1_SB_DQ<15>")
	)
	(segment
		(start 134.343394 -283.478986)
		(end 134.351776 -283.483812)
		(width 0.0889)
		(layer "In4.Cu")
		(net "M_J_CPU1_SB_DQ<15>")
	)
	(segment
		(start 132.09778 -283.483812)
		(end 132.106162 -283.478986)
		(width 0.0889)
		(layer "In4.Cu")
		(net "M_J_CPU1_SB_DQ<15>")
	)
	(segment
		(start 178.503834 -299.760132)
		(end 181.400958 -299.760132)
		(width 0.14478)
		(layer "In4.Cu")
		(net "M_J_CPU1_SB_DQ<15>")
	)
	(segment
		(start 170.18254 -298.910502)
		(end 171.032678 -299.76064)
		(width 0.14478)
		(layer "In4.Cu")
		(net "M_J_CPU1_SB_DQ<15>")
	)
	(segment
		(start 164.027612 -299.455586)
		(end 164.273992 -299.455586)
		(width 0.14478)
		(layer "In4.Cu")
		(net "M_J_CPU1_SB_DQ<15>")
	)
	(segment
		(start 168.145968 -298.612306)
		(end 168.399206 -298.612306)
		(width 0.14478)
		(layer "In4.Cu")
		(net "M_J_CPU1_SB_DQ<15>")
	)
	(segment
		(start 144.684242 -283.478986)
		(end 144.692624 -283.483812)
		(width 0.0889)
		(layer "In4.Cu")
		(net "M_J_CPU1_SB_DQ<15>")
	)
	(segment
		(start 147.644866 -284.057344)
		(end 147.84451 -284.057344)
		(width 0.0889)
		(layer "In4.Cu")
		(net "M_J_CPU1_SB_DQ<15>")
	)
	(segment
		(start 147.84451 -284.057344)
		(end 149.105874 -284.057344)
		(width 0.14478)
		(layer "In4.Cu")
		(net "M_J_CPU1_SB_DQ<15>")
	)
	(segment
		(start 182.250588 -298.910502)
		(end 184.29986 -298.910502)
		(width 0.14478)
		(layer "In4.Cu")
		(net "M_J_CPU1_SB_DQ<15>")
	)
	(segment
		(start 160.880552 -299.76064)
		(end 161.516822 -299.76064)
		(width 0.14478)
		(layer "In4.Cu")
		(net "M_J_CPU1_SB_DQ<15>")
	)
	(segment
		(start 173.69409 -299.76064)
		(end 174.544228 -298.910502)
		(width 0.14478)
		(layer "In4.Cu")
		(net "M_J_CPU1_SB_DQ<15>")
	)
	(segment
		(start 164.273992 -299.455586)
		(end 164.579046 -299.76064)
		(width 0.14478)
		(layer "In4.Cu")
		(net "M_J_CPU1_SB_DQ<15>")
	)
	(segment
		(start 138.103356 -283.478986)
		(end 138.111738 -283.483812)
		(width 0.0889)
		(layer "In4.Cu")
		(net "M_J_CPU1_SB_DQ<15>")
	)
	(segment
		(start 162.61969 -299.76064)
		(end 162.924744 -299.455586)
		(width 0.14478)
		(layer "In4.Cu")
		(net "M_J_CPU1_SB_DQ<15>")
	)
	(segment
		(start 139.04341 -283.478986)
		(end 139.051792 -283.483812)
		(width 0.0889)
		(layer "In4.Cu")
		(net "M_J_CPU1_SB_DQ<15>")
	)
	(segment
		(start 163.722558 -299.76064)
		(end 164.027612 -299.455586)
		(width 0.14478)
		(layer "In4.Cu")
		(net "M_J_CPU1_SB_DQ<15>")
	)
	(segment
		(start 185.954162 -298.617386)
		(end 186.247278 -298.910502)
		(width 0.14478)
		(layer "In4.Cu")
		(net "M_J_CPU1_SB_DQ<15>")
	)
	(segment
		(start 164.825426 -299.76064)
		(end 165.13048 -299.455586)
		(width 0.14478)
		(layer "In4.Cu")
		(net "M_J_CPU1_SB_DQ<15>")
	)
	(segment
		(start 161.516822 -299.76064)
		(end 161.821876 -299.455586)
		(width 0.14478)
		(layer "In4.Cu")
		(net "M_J_CPU1_SB_DQ<15>")
	)
	(segment
		(start 167.000174 -298.910502)
		(end 167.847772 -298.910502)
		(width 0.14478)
		(layer "In4.Cu")
		(net "M_J_CPU1_SB_DQ<15>")
	)
	(segment
		(start 161.821876 -299.455586)
		(end 162.068256 -299.455586)
		(width 0.14478)
		(layer "In4.Cu")
		(net "M_J_CPU1_SB_DQ<15>")
	)
	(segment
		(start 149.105874 -284.057344)
		(end 156.26461 -291.21608)
		(width 0.14478)
		(layer "In4.Cu")
		(net "M_J_CPU1_SB_DQ<15>")
	)
	(segment
		(start 174.544228 -298.910502)
		(end 177.654204 -298.910502)
		(width 0.14478)
		(layer "In4.Cu")
		(net "M_J_CPU1_SB_DQ<15>")
	)
	(segment
		(start 177.654204 -298.910502)
		(end 178.503834 -299.760132)
		(width 0.14478)
		(layer "In4.Cu")
		(net "M_J_CPU1_SB_DQ<15>")
	)
	(segment
		(start 134.917688 -283.483812)
		(end 134.92607 -283.478986)
		(width 0.0889)
		(layer "In4.Cu")
		(net "M_J_CPU1_SB_DQ<15>")
	)
	(segment
		(start 162.37331 -299.76064)
		(end 162.61969 -299.76064)
		(width 0.14478)
		(layer "In4.Cu")
		(net "M_J_CPU1_SB_DQ<15>")
	)
	(segment
		(start 143.751808 -283.483812)
		(end 143.762222 -283.489908)
		(width 0.0889)
		(layer "In4.Cu")
		(net "M_J_CPU1_SB_DQ<15>")
	)
	(segment
		(start 131.34467 -283.806392)
		(end 131.498848 -283.540962)
		(width 0.0889)
		(layer "In4.Cu")
		(net "M_J_CPU1_SB_DQ<15>")
	)
	(segment
		(start 146.45386 -283.68752)
		(end 147.275042 -283.68752)
		(width 0.0889)
		(layer "In4.Cu")
		(net "M_J_CPU1_SB_DQ<15>")
	)
	(segment
		(start 131.498848 -283.540962)
		(end 131.595114 -283.515562)
		(width 0.0889)
		(layer "In4.Cu")
		(net "M_J_CPU1_SB_DQ<15>")
	)
	(segment
		(start 171.032678 -299.76064)
		(end 173.69409 -299.76064)
		(width 0.14478)
		(layer "In4.Cu")
		(net "M_J_CPU1_SB_DQ<15>")
	)
	(segment
		(start 163.171124 -299.455586)
		(end 163.476178 -299.76064)
		(width 0.14478)
		(layer "In4.Cu")
		(net "M_J_CPU1_SB_DQ<15>")
	)
	(segment
		(start 168.399206 -298.612306)
		(end 168.697402 -298.910502)
		(width 0.14478)
		(layer "In4.Cu")
		(net "M_J_CPU1_SB_DQ<15>")
	)
	(segment
		(start 165.681914 -299.76064)
		(end 166.150036 -299.76064)
		(width 0.14478)
		(layer "In4.Cu")
		(net "M_J_CPU1_SB_DQ<15>")
	)
	(segment
		(start 186.247278 -298.910502)
		(end 186.635136 -298.910502)
		(width 0.14478)
		(layer "In4.Cu")
		(net "M_J_CPU1_SB_DQ<15>")
	)
	(segment
		(start 184.592976 -298.617386)
		(end 184.851294 -298.617386)
		(width 0.14478)
		(layer "In4.Cu")
		(net "M_J_CPU1_SB_DQ<15>")
	)
	(segment
		(start 167.847772 -298.910502)
		(end 168.145968 -298.612306)
		(width 0.14478)
		(layer "In4.Cu")
		(net "M_J_CPU1_SB_DQ<15>")
	)
	(arc
		(start 144.317974 -283.483812)
		(mid 144.500479 -283.433335)
		(end 144.684242 -283.478986)
		(width 0.0889)
		(layer "In4.Cu")
		(net "M_J_CPU1_SB_DQ<15>")
	)
	(arc
		(start 131.595114 -283.515562)
		(mid 131.850179 -283.558913)
		(end 132.09778 -283.483812)
		(width 0.0889)
		(layer "In4.Cu")
		(net "M_J_CPU1_SB_DQ<15>")
	)
	(arc
		(start 132.471922 -283.483812)
		(mid 132.754878 -283.559989)
		(end 133.037834 -283.483812)
		(width 0.0889)
		(layer "In4.Cu")
		(net "M_J_CPU1_SB_DQ<15>")
	)
	(arc
		(start 136.797796 -283.483812)
		(mid 136.98474 -283.433557)
		(end 137.171684 -283.483812)
		(width 0.0889)
		(layer "In4.Cu")
		(net "M_J_CPU1_SB_DQ<15>")
	)
	(arc
		(start 134.92607 -283.478986)
		(mid 135.109578 -283.433492)
		(end 135.29183 -283.483812)
		(width 0.0889)
		(layer "In4.Cu")
		(net "M_J_CPU1_SB_DQ<15>")
	)
	(arc
		(start 139.626086 -283.478986)
		(mid 139.809594 -283.433492)
		(end 139.991846 -283.483812)
		(width 0.0889)
		(layer "In4.Cu")
		(net "M_J_CPU1_SB_DQ<15>")
	)
	(arc
		(start 138.67765 -283.483812)
		(mid 138.859901 -283.433462)
		(end 139.04341 -283.478986)
		(width 0.0889)
		(layer "In4.Cu")
		(net "M_J_CPU1_SB_DQ<15>")
	)
	(arc
		(start 143.762222 -283.489908)
		(mid 144.040908 -283.560128)
		(end 144.317974 -283.483812)
		(width 0.0889)
		(layer "In4.Cu")
		(net "M_J_CPU1_SB_DQ<15>")
	)
	(arc
		(start 133.037834 -283.483812)
		(mid 133.224778 -283.433557)
		(end 133.411722 -283.483812)
		(width 0.0889)
		(layer "In4.Cu")
		(net "M_J_CPU1_SB_DQ<15>")
	)
	(arc
		(start 136.231884 -283.483812)
		(mid 136.51484 -283.559989)
		(end 136.797796 -283.483812)
		(width 0.0889)
		(layer "In4.Cu")
		(net "M_J_CPU1_SB_DQ<15>")
	)
	(arc
		(start 137.737596 -283.483812)
		(mid 137.919847 -283.433462)
		(end 138.103356 -283.478986)
		(width 0.0889)
		(layer "In4.Cu")
		(net "M_J_CPU1_SB_DQ<15>")
	)
	(arc
		(start 133.977634 -283.483812)
		(mid 134.159885 -283.433462)
		(end 134.343394 -283.478986)
		(width 0.0889)
		(layer "In4.Cu")
		(net "M_J_CPU1_SB_DQ<15>")
	)
	(arc
		(start 132.106162 -283.478986)
		(mid 132.28967 -283.433492)
		(end 132.471922 -283.483812)
		(width 0.0889)
		(layer "In4.Cu")
		(net "M_J_CPU1_SB_DQ<15>")
	)
	(arc
		(start 139.991846 -283.483812)
		(mid 140.274802 -283.559989)
		(end 140.557758 -283.483812)
		(width 0.0889)
		(layer "In4.Cu")
		(net "M_J_CPU1_SB_DQ<15>")
	)
	(arc
		(start 141.497812 -283.483812)
		(mid 141.684756 -283.433557)
		(end 141.8717 -283.483812)
		(width 0.0889)
		(layer "In4.Cu")
		(net "M_J_CPU1_SB_DQ<15>")
	)
	(arc
		(start 134.351776 -283.483812)
		(mid 134.634732 -283.559989)
		(end 134.917688 -283.483812)
		(width 0.0889)
		(layer "In4.Cu")
		(net "M_J_CPU1_SB_DQ<15>")
	)
	(arc
		(start 133.411722 -283.483812)
		(mid 133.694678 -283.559989)
		(end 133.977634 -283.483812)
		(width 0.0889)
		(layer "In4.Cu")
		(net "M_J_CPU1_SB_DQ<15>")
	)
	(arc
		(start 142.811754 -283.483812)
		(mid 143.09471 -283.559989)
		(end 143.377666 -283.483812)
		(width 0.0889)
		(layer "In4.Cu")
		(net "M_J_CPU1_SB_DQ<15>")
	)
	(arc
		(start 143.386048 -283.478986)
		(mid 143.569556 -283.433492)
		(end 143.751808 -283.483812)
		(width 0.0889)
		(layer "In4.Cu")
		(net "M_J_CPU1_SB_DQ<15>")
	)
	(arc
		(start 135.29183 -283.483812)
		(mid 135.574786 -283.559989)
		(end 135.857742 -283.483812)
		(width 0.0889)
		(layer "In4.Cu")
		(net "M_J_CPU1_SB_DQ<15>")
	)
	(arc
		(start 137.171684 -283.483812)
		(mid 137.45464 -283.559989)
		(end 137.737596 -283.483812)
		(width 0.0889)
		(layer "In4.Cu")
		(net "M_J_CPU1_SB_DQ<15>")
	)
	(arc
		(start 140.9319 -283.483812)
		(mid 141.214856 -283.559989)
		(end 141.497812 -283.483812)
		(width 0.0889)
		(layer "In4.Cu")
		(net "M_J_CPU1_SB_DQ<15>")
	)
	(arc
		(start 140.56614 -283.478986)
		(mid 140.749648 -283.433492)
		(end 140.9319 -283.483812)
		(width 0.0889)
		(layer "In4.Cu")
		(net "M_J_CPU1_SB_DQ<15>")
	)
	(arc
		(start 142.437612 -283.483812)
		(mid 142.619863 -283.433462)
		(end 142.803372 -283.478986)
		(width 0.0889)
		(layer "In4.Cu")
		(net "M_J_CPU1_SB_DQ<15>")
	)
	(arc
		(start 144.692624 -283.483812)
		(mid 144.972052 -283.559978)
		(end 145.25244 -283.487368)
		(width 0.0889)
		(layer "In4.Cu")
		(net "M_J_CPU1_SB_DQ<15>")
	)
	(arc
		(start 139.051792 -283.483812)
		(mid 139.334748 -283.559989)
		(end 139.617704 -283.483812)
		(width 0.0889)
		(layer "In4.Cu")
		(net "M_J_CPU1_SB_DQ<15>")
	)
	(arc
		(start 141.8717 -283.483812)
		(mid 142.154656 -283.559989)
		(end 142.437612 -283.483812)
		(width 0.0889)
		(layer "In4.Cu")
		(net "M_J_CPU1_SB_DQ<15>")
	)
	(arc
		(start 135.866124 -283.478986)
		(mid 136.049632 -283.433492)
		(end 136.231884 -283.483812)
		(width 0.0889)
		(layer "In4.Cu")
		(net "M_J_CPU1_SB_DQ<15>")
	)
	(arc
		(start 145.25244 -283.487368)
		(mid 145.380037 -283.431903)
		(end 145.51787 -283.412946)
		(width 0.0889)
		(layer "In4.Cu")
		(net "M_J_CPU1_SB_DQ<15>")
	)
	(arc
		(start 138.111738 -283.483812)
		(mid 138.394694 -283.559989)
		(end 138.67765 -283.483812)
		(width 0.0889)
		(layer "In4.Cu")
		(net "M_J_CPU1_SB_DQ<15>")
	)
	(segment
		(start 132.287772 -282.730448)
		(end 132.754878 -282.996386)
		(width 0.10668)
		(layer "F.Cu")
		(net "M_J_CPU1_SB_DQ<14>")
	)
	(segment
		(start 157.16377 -293.86149)
		(end 157.450536 -294.148256)
		(width 0.14478)
		(layer "In4.Cu")
		(net "M_J_CPU1_SB_DQ<14>")
	)
	(segment
		(start 158.1658 -295.773856)
		(end 158.3944 -295.773856)
		(width 0.14478)
		(layer "In4.Cu")
		(net "M_J_CPU1_SB_DQ<14>")
	)
	(segment
		(start 158.784544 -296.3926)
		(end 158.946088 -296.554144)
		(width 0.14478)
		(layer "In4.Cu")
		(net "M_J_CPU1_SB_DQ<14>")
	)
	(segment
		(start 159.7914 -296.71772)
		(end 159.564832 -296.944288)
		(width 0.14478)
		(layer "In4.Cu")
		(net "M_J_CPU1_SB_DQ<14>")
	)
	(segment
		(start 157.385512 -294.993568)
		(end 157.614112 -294.993568)
		(width 0.14478)
		(layer "In4.Cu")
		(net "M_J_CPU1_SB_DQ<14>")
	)
	(segment
		(start 159.7914 -296.48912)
		(end 159.7914 -296.71772)
		(width 0.14478)
		(layer "In4.Cu")
		(net "M_J_CPU1_SB_DQ<14>")
	)
	(segment
		(start 167.000174 -297.21048)
		(end 169.950384 -297.21048)
		(width 0.14478)
		(layer "In4.Cu")
		(net "M_J_CPU1_SB_DQ<14>")
	)
	(segment
		(start 144.220946 -282.67406)
		(end 144.242536 -282.686506)
		(width 0.0889)
		(layer "In4.Cu")
		(net "M_J_CPU1_SB_DQ<14>")
	)
	(segment
		(start 160.181544 -297.107864)
		(end 160.410144 -297.107864)
		(width 0.14478)
		(layer "In4.Cu")
		(net "M_J_CPU1_SB_DQ<14>")
	)
	(segment
		(start 158.004256 -295.612312)
		(end 158.1658 -295.773856)
		(width 0.14478)
		(layer "In4.Cu")
		(net "M_J_CPU1_SB_DQ<14>")
	)
	(segment
		(start 138.20775 -282.673806)
		(end 138.216132 -282.66898)
		(width 0.0889)
		(layer "In4.Cu")
		(net "M_J_CPU1_SB_DQ<14>")
	)
	(segment
		(start 158.849568 -295.547288)
		(end 159.011112 -295.708832)
		(width 0.14478)
		(layer "In4.Cu")
		(net "M_J_CPU1_SB_DQ<14>")
	)
	(segment
		(start 158.230824 -295.157144)
		(end 158.004256 -295.383712)
		(width 0.14478)
		(layer "In4.Cu")
		(net "M_J_CPU1_SB_DQ<14>")
	)
	(segment
		(start 181.325266 -298.060364)
		(end 182.17515 -297.21048)
		(width 0.14478)
		(layer "In4.Cu")
		(net "M_J_CPU1_SB_DQ<14>")
	)
	(segment
		(start 160.34512 -297.953176)
		(end 160.506664 -298.11472)
		(width 0.14478)
		(layer "In4.Cu")
		(net "M_J_CPU1_SB_DQ<14>")
	)
	(segment
		(start 160.961832 -297.888152)
		(end 161.190432 -297.888152)
		(width 0.14478)
		(layer "In4.Cu")
		(net "M_J_CPU1_SB_DQ<14>")
	)
	(segment
		(start 145.444718 -282.750514)
		(end 146.195796 -282.750514)
		(width 0.0889)
		(layer "In4.Cu")
		(net "M_J_CPU1_SB_DQ<14>")
	)
	(segment
		(start 161.190432 -297.888152)
		(end 161.362898 -298.060618)
		(width 0.14478)
		(layer "In4.Cu")
		(net "M_J_CPU1_SB_DQ<14>")
	)
	(segment
		(start 159.564832 -296.944288)
		(end 159.564832 -297.172888)
		(width 0.14478)
		(layer "In4.Cu")
		(net "M_J_CPU1_SB_DQ<14>")
	)
	(segment
		(start 159.401256 -296.327576)
		(end 159.629856 -296.327576)
		(width 0.14478)
		(layer "In4.Cu")
		(net "M_J_CPU1_SB_DQ<14>")
	)
	(segment
		(start 158.3944 -295.773856)
		(end 158.620968 -295.547288)
		(width 0.14478)
		(layer "In4.Cu")
		(net "M_J_CPU1_SB_DQ<14>")
	)
	(segment
		(start 147.816062 -283.148024)
		(end 149.468586 -283.148024)
		(width 0.14478)
		(layer "In4.Cu")
		(net "M_J_CPU1_SB_DQ<14>")
	)
	(segment
		(start 132.908802 -282.730956)
		(end 133.004814 -282.705556)
		(width 0.0889)
		(layer "In4.Cu")
		(net "M_J_CPU1_SB_DQ<14>")
	)
	(segment
		(start 160.735264 -298.11472)
		(end 160.961832 -297.888152)
		(width 0.14478)
		(layer "In4.Cu")
		(net "M_J_CPU1_SB_DQ<14>")
	)
	(segment
		(start 157.223968 -294.832024)
		(end 157.385512 -294.993568)
		(width 0.14478)
		(layer "In4.Cu")
		(net "M_J_CPU1_SB_DQ<14>")
	)
	(segment
		(start 136.693402 -282.66898)
		(end 136.701784 -282.673806)
		(width 0.0889)
		(layer "In4.Cu")
		(net "M_J_CPU1_SB_DQ<14>")
	)
	(segment
		(start 157.450536 -294.376856)
		(end 157.223968 -294.603424)
		(width 0.14478)
		(layer "In4.Cu")
		(net "M_J_CPU1_SB_DQ<14>")
	)
	(segment
		(start 144.20088 -282.66263)
		(end 144.220946 -282.67406)
		(width 0.0889)
		(layer "In4.Cu")
		(net "M_J_CPU1_SB_DQ<14>")
	)
	(segment
		(start 158.784544 -296.164)
		(end 158.784544 -296.3926)
		(width 0.14478)
		(layer "In4.Cu")
		(net "M_J_CPU1_SB_DQ<14>")
	)
	(segment
		(start 186.635136 -297.21048)
		(end 187.060078 -297.635422)
		(width 0.14478)
		(layer "In4.Cu")
		(net "M_J_CPU1_SB_DQ<14>")
	)
	(segment
		(start 170.800522 -298.060618)
		(end 173.69409 -298.060618)
		(width 0.14478)
		(layer "In4.Cu")
		(net "M_J_CPU1_SB_DQ<14>")
	)
	(segment
		(start 141.393418 -282.66898)
		(end 141.4018 -282.673806)
		(width 0.0889)
		(layer "In4.Cu")
		(net "M_J_CPU1_SB_DQ<14>")
	)
	(segment
		(start 146.195796 -282.750514)
		(end 146.593306 -283.148024)
		(width 0.0889)
		(layer "In4.Cu")
		(net "M_J_CPU1_SB_DQ<14>")
	)
	(segment
		(start 137.267696 -282.673806)
		(end 137.276078 -282.66898)
		(width 0.0889)
		(layer "In4.Cu")
		(net "M_J_CPU1_SB_DQ<14>")
	)
	(segment
		(start 159.954976 -297.334432)
		(end 160.181544 -297.107864)
		(width 0.14478)
		(layer "In4.Cu")
		(net "M_J_CPU1_SB_DQ<14>")
	)
	(segment
		(start 177.361342 -297.21048)
		(end 178.211226 -298.060364)
		(width 0.14478)
		(layer "In4.Cu")
		(net "M_J_CPU1_SB_DQ<14>")
	)
	(segment
		(start 158.06928 -294.767)
		(end 158.230824 -294.928544)
		(width 0.14478)
		(layer "In4.Cu")
		(net "M_J_CPU1_SB_DQ<14>")
	)
	(segment
		(start 160.34512 -297.724576)
		(end 160.34512 -297.953176)
		(width 0.14478)
		(layer "In4.Cu")
		(net "M_J_CPU1_SB_DQ<14>")
	)
	(segment
		(start 159.174688 -296.554144)
		(end 159.401256 -296.327576)
		(width 0.14478)
		(layer "In4.Cu")
		(net "M_J_CPU1_SB_DQ<14>")
	)
	(segment
		(start 157.16377 -290.843208)
		(end 157.16377 -293.86149)
		(width 0.14478)
		(layer "In4.Cu")
		(net "M_J_CPU1_SB_DQ<14>")
	)
	(segment
		(start 158.004256 -295.383712)
		(end 158.004256 -295.612312)
		(width 0.14478)
		(layer "In4.Cu")
		(net "M_J_CPU1_SB_DQ<14>")
	)
	(segment
		(start 160.506664 -298.11472)
		(end 160.735264 -298.11472)
		(width 0.14478)
		(layer "In4.Cu")
		(net "M_J_CPU1_SB_DQ<14>")
	)
	(segment
		(start 159.629856 -296.327576)
		(end 159.7914 -296.48912)
		(width 0.14478)
		(layer "In4.Cu")
		(net "M_J_CPU1_SB_DQ<14>")
	)
	(segment
		(start 159.011112 -295.708832)
		(end 159.011112 -295.937432)
		(width 0.14478)
		(layer "In4.Cu")
		(net "M_J_CPU1_SB_DQ<14>")
	)
	(segment
		(start 132.754878 -282.996386)
		(end 132.908802 -282.730956)
		(width 0.0889)
		(layer "In4.Cu")
		(net "M_J_CPU1_SB_DQ<14>")
	)
	(segment
		(start 159.564832 -297.172888)
		(end 159.726376 -297.334432)
		(width 0.14478)
		(layer "In4.Cu")
		(net "M_J_CPU1_SB_DQ<14>")
	)
	(segment
		(start 169.950384 -297.21048)
		(end 170.800522 -298.060618)
		(width 0.14478)
		(layer "In4.Cu")
		(net "M_J_CPU1_SB_DQ<14>")
	)
	(segment
		(start 149.468586 -283.148024)
		(end 157.16377 -290.843208)
		(width 0.14478)
		(layer "In4.Cu")
		(net "M_J_CPU1_SB_DQ<14>")
	)
	(segment
		(start 157.614112 -294.993568)
		(end 157.84068 -294.767)
		(width 0.14478)
		(layer "In4.Cu")
		(net "M_J_CPU1_SB_DQ<14>")
	)
	(segment
		(start 158.620968 -295.547288)
		(end 158.849568 -295.547288)
		(width 0.14478)
		(layer "In4.Cu")
		(net "M_J_CPU1_SB_DQ<14>")
	)
	(segment
		(start 157.223968 -294.603424)
		(end 157.223968 -294.832024)
		(width 0.14478)
		(layer "In4.Cu")
		(net "M_J_CPU1_SB_DQ<14>")
	)
	(segment
		(start 166.150036 -298.060618)
		(end 167.000174 -297.21048)
		(width 0.14478)
		(layer "In4.Cu")
		(net "M_J_CPU1_SB_DQ<14>")
	)
	(segment
		(start 159.726376 -297.334432)
		(end 159.954976 -297.334432)
		(width 0.14478)
		(layer "In4.Cu")
		(net "M_J_CPU1_SB_DQ<14>")
	)
	(segment
		(start 182.17515 -297.21048)
		(end 186.635136 -297.21048)
		(width 0.14478)
		(layer "In4.Cu")
		(net "M_J_CPU1_SB_DQ<14>")
	)
	(segment
		(start 174.544228 -297.21048)
		(end 177.361342 -297.21048)
		(width 0.14478)
		(layer "In4.Cu")
		(net "M_J_CPU1_SB_DQ<14>")
	)
	(segment
		(start 159.011112 -295.937432)
		(end 158.784544 -296.164)
		(width 0.14478)
		(layer "In4.Cu")
		(net "M_J_CPU1_SB_DQ<14>")
	)
	(segment
		(start 158.230824 -294.928544)
		(end 158.230824 -295.157144)
		(width 0.14478)
		(layer "In4.Cu")
		(net "M_J_CPU1_SB_DQ<14>")
	)
	(segment
		(start 160.571688 -297.498008)
		(end 160.34512 -297.724576)
		(width 0.14478)
		(layer "In4.Cu")
		(net "M_J_CPU1_SB_DQ<14>")
	)
	(segment
		(start 160.410144 -297.107864)
		(end 160.571688 -297.269408)
		(width 0.14478)
		(layer "In4.Cu")
		(net "M_J_CPU1_SB_DQ<14>")
	)
	(segment
		(start 161.362898 -298.060618)
		(end 166.150036 -298.060618)
		(width 0.14478)
		(layer "In4.Cu")
		(net "M_J_CPU1_SB_DQ<14>")
	)
	(segment
		(start 144.785334 -282.673806)
		(end 144.80413 -282.662884)
		(width 0.0889)
		(layer "In4.Cu")
		(net "M_J_CPU1_SB_DQ<14>")
	)
	(segment
		(start 157.450536 -294.148256)
		(end 157.450536 -294.376856)
		(width 0.14478)
		(layer "In4.Cu")
		(net "M_J_CPU1_SB_DQ<14>")
	)
	(segment
		(start 135.753348 -282.66898)
		(end 135.76173 -282.673806)
		(width 0.0889)
		(layer "In4.Cu")
		(net "M_J_CPU1_SB_DQ<14>")
	)
	(segment
		(start 140.453364 -282.66898)
		(end 140.461746 -282.673806)
		(width 0.0889)
		(layer "In4.Cu")
		(net "M_J_CPU1_SB_DQ<14>")
	)
	(segment
		(start 157.84068 -294.767)
		(end 158.06928 -294.767)
		(width 0.14478)
		(layer "In4.Cu")
		(net "M_J_CPU1_SB_DQ<14>")
	)
	(segment
		(start 160.571688 -297.269408)
		(end 160.571688 -297.498008)
		(width 0.14478)
		(layer "In4.Cu")
		(net "M_J_CPU1_SB_DQ<14>")
	)
	(segment
		(start 173.69409 -298.060618)
		(end 174.544228 -297.21048)
		(width 0.14478)
		(layer "In4.Cu")
		(net "M_J_CPU1_SB_DQ<14>")
	)
	(segment
		(start 133.507734 -282.673806)
		(end 133.516116 -282.66898)
		(width 0.0889)
		(layer "In4.Cu")
		(net "M_J_CPU1_SB_DQ<14>")
	)
	(segment
		(start 146.593306 -283.148024)
		(end 147.816062 -283.148024)
		(width 0.0889)
		(layer "In4.Cu")
		(net "M_J_CPU1_SB_DQ<14>")
	)
	(segment
		(start 178.211226 -298.060364)
		(end 181.325266 -298.060364)
		(width 0.14478)
		(layer "In4.Cu")
		(net "M_J_CPU1_SB_DQ<14>")
	)
	(segment
		(start 141.967712 -282.673806)
		(end 141.976094 -282.66898)
		(width 0.0889)
		(layer "In4.Cu")
		(net "M_J_CPU1_SB_DQ<14>")
	)
	(segment
		(start 158.946088 -296.554144)
		(end 159.174688 -296.554144)
		(width 0.14478)
		(layer "In4.Cu")
		(net "M_J_CPU1_SB_DQ<14>")
	)
	(arc
		(start 133.516116 -282.66898)
		(mid 133.699624 -282.623486)
		(end 133.881876 -282.673806)
		(width 0.0889)
		(layer "In4.Cu")
		(net "M_J_CPU1_SB_DQ<14>")
	)
	(arc
		(start 134.821676 -282.673806)
		(mid 135.104632 -282.749983)
		(end 135.387588 -282.673806)
		(width 0.0889)
		(layer "In4.Cu")
		(net "M_J_CPU1_SB_DQ<14>")
	)
	(arc
		(start 135.387588 -282.673806)
		(mid 135.569839 -282.623456)
		(end 135.753348 -282.66898)
		(width 0.0889)
		(layer "In4.Cu")
		(net "M_J_CPU1_SB_DQ<14>")
	)
	(arc
		(start 144.80413 -282.662884)
		(mid 144.983701 -282.623067)
		(end 145.160492 -282.673806)
		(width 0.0889)
		(layer "In4.Cu")
		(net "M_J_CPU1_SB_DQ<14>")
	)
	(arc
		(start 142.341854 -282.673806)
		(mid 142.62481 -282.749983)
		(end 142.907766 -282.673806)
		(width 0.0889)
		(layer "In4.Cu")
		(net "M_J_CPU1_SB_DQ<14>")
	)
	(arc
		(start 141.976094 -282.66898)
		(mid 142.159602 -282.623486)
		(end 142.341854 -282.673806)
		(width 0.0889)
		(layer "In4.Cu")
		(net "M_J_CPU1_SB_DQ<14>")
	)
	(arc
		(start 143.281654 -282.673806)
		(mid 143.56461 -282.749983)
		(end 143.847566 -282.673806)
		(width 0.0889)
		(layer "In4.Cu")
		(net "M_J_CPU1_SB_DQ<14>")
	)
	(arc
		(start 139.147804 -282.673806)
		(mid 139.334748 -282.623551)
		(end 139.521692 -282.673806)
		(width 0.0889)
		(layer "In4.Cu")
		(net "M_J_CPU1_SB_DQ<14>")
	)
	(arc
		(start 137.276078 -282.66898)
		(mid 137.459586 -282.623486)
		(end 137.641838 -282.673806)
		(width 0.0889)
		(layer "In4.Cu")
		(net "M_J_CPU1_SB_DQ<14>")
	)
	(arc
		(start 143.847566 -282.673806)
		(mid 144.022805 -282.623735)
		(end 144.20088 -282.66263)
		(width 0.0889)
		(layer "In4.Cu")
		(net "M_J_CPU1_SB_DQ<14>")
	)
	(arc
		(start 135.76173 -282.673806)
		(mid 136.044686 -282.749983)
		(end 136.327642 -282.673806)
		(width 0.0889)
		(layer "In4.Cu")
		(net "M_J_CPU1_SB_DQ<14>")
	)
	(arc
		(start 138.216132 -282.66898)
		(mid 138.39964 -282.623486)
		(end 138.581892 -282.673806)
		(width 0.0889)
		(layer "In4.Cu")
		(net "M_J_CPU1_SB_DQ<14>")
	)
	(arc
		(start 133.004814 -282.705556)
		(mid 133.260022 -282.749033)
		(end 133.507734 -282.673806)
		(width 0.0889)
		(layer "In4.Cu")
		(net "M_J_CPU1_SB_DQ<14>")
	)
	(arc
		(start 144.242536 -282.686506)
		(mid 144.515565 -282.749825)
		(end 144.785334 -282.673806)
		(width 0.0889)
		(layer "In4.Cu")
		(net "M_J_CPU1_SB_DQ<14>")
	)
	(arc
		(start 134.447788 -282.673806)
		(mid 134.634732 -282.623551)
		(end 134.821676 -282.673806)
		(width 0.0889)
		(layer "In4.Cu")
		(net "M_J_CPU1_SB_DQ<14>")
	)
	(arc
		(start 136.701784 -282.673806)
		(mid 136.98474 -282.749983)
		(end 137.267696 -282.673806)
		(width 0.0889)
		(layer "In4.Cu")
		(net "M_J_CPU1_SB_DQ<14>")
	)
	(arc
		(start 145.160492 -282.673806)
		(mid 145.297514 -282.731017)
		(end 145.444718 -282.750514)
		(width 0.0889)
		(layer "In4.Cu")
		(net "M_J_CPU1_SB_DQ<14>")
	)
	(arc
		(start 140.461746 -282.673806)
		(mid 140.744702 -282.749983)
		(end 141.027658 -282.673806)
		(width 0.0889)
		(layer "In4.Cu")
		(net "M_J_CPU1_SB_DQ<14>")
	)
	(arc
		(start 137.641838 -282.673806)
		(mid 137.924794 -282.749983)
		(end 138.20775 -282.673806)
		(width 0.0889)
		(layer "In4.Cu")
		(net "M_J_CPU1_SB_DQ<14>")
	)
	(arc
		(start 136.327642 -282.673806)
		(mid 136.509893 -282.623456)
		(end 136.693402 -282.66898)
		(width 0.0889)
		(layer "In4.Cu")
		(net "M_J_CPU1_SB_DQ<14>")
	)
	(arc
		(start 141.027658 -282.673806)
		(mid 141.209909 -282.623456)
		(end 141.393418 -282.66898)
		(width 0.0889)
		(layer "In4.Cu")
		(net "M_J_CPU1_SB_DQ<14>")
	)
	(arc
		(start 133.881876 -282.673806)
		(mid 134.164832 -282.749983)
		(end 134.447788 -282.673806)
		(width 0.0889)
		(layer "In4.Cu")
		(net "M_J_CPU1_SB_DQ<14>")
	)
	(arc
		(start 141.4018 -282.673806)
		(mid 141.684756 -282.749983)
		(end 141.967712 -282.673806)
		(width 0.0889)
		(layer "In4.Cu")
		(net "M_J_CPU1_SB_DQ<14>")
	)
	(arc
		(start 142.907766 -282.673806)
		(mid 143.09471 -282.623551)
		(end 143.281654 -282.673806)
		(width 0.0889)
		(layer "In4.Cu")
		(net "M_J_CPU1_SB_DQ<14>")
	)
	(arc
		(start 139.521692 -282.673806)
		(mid 139.804648 -282.749983)
		(end 140.087604 -282.673806)
		(width 0.0889)
		(layer "In4.Cu")
		(net "M_J_CPU1_SB_DQ<14>")
	)
	(arc
		(start 138.581892 -282.673806)
		(mid 138.864848 -282.749983)
		(end 139.147804 -282.673806)
		(width 0.0889)
		(layer "In4.Cu")
		(net "M_J_CPU1_SB_DQ<14>")
	)
	(arc
		(start 140.087604 -282.673806)
		(mid 140.269855 -282.623456)
		(end 140.453364 -282.66898)
		(width 0.0889)
		(layer "In4.Cu")
		(net "M_J_CPU1_SB_DQ<14>")
	)
	(segment
		(start 131.347972 -282.730448)
		(end 131.814824 -282.996386)
		(width 0.10668)
		(layer "F.Cu")
		(net "M_J_CPU1_SB_DQ<13>")
	)
	(segment
		(start 137.267696 -283.318966)
		(end 137.276078 -283.323792)
		(width 0.0889)
		(layer "In4.Cu")
		(net "M_J_CPU1_SB_DQ<13>")
	)
	(segment
		(start 149.28723 -283.602684)
		(end 156.71419 -291.029644)
		(width 0.14478)
		(layer "In4.Cu")
		(net "M_J_CPU1_SB_DQ<13>")
	)
	(segment
		(start 189.023752 -298.060364)
		(end 191.160146 -298.485306)
		(width 0.14478)
		(layer "In4.Cu")
		(net "M_J_CPU1_SB_DQ<13>")
	)
	(segment
		(start 178.971448 -298.910248)
		(end 180.889656 -298.910248)
		(width 0.14478)
		(layer "In4.Cu")
		(net "M_J_CPU1_SB_DQ<13>")
	)
	(segment
		(start 131.814824 -282.996386)
		(end 131.660646 -283.261816)
		(width 0.0889)
		(layer "In4.Cu")
		(net "M_J_CPU1_SB_DQ<13>")
	)
	(segment
		(start 135.753348 -283.323792)
		(end 135.76173 -283.318966)
		(width 0.0889)
		(layer "In4.Cu")
		(net "M_J_CPU1_SB_DQ<13>")
	)
	(segment
		(start 141.393418 -283.323792)
		(end 141.4018 -283.318966)
		(width 0.0889)
		(layer "In4.Cu")
		(net "M_J_CPU1_SB_DQ<13>")
	)
	(segment
		(start 138.20775 -283.318966)
		(end 138.216132 -283.323792)
		(width 0.0889)
		(layer "In4.Cu")
		(net "M_J_CPU1_SB_DQ<13>")
	)
	(segment
		(start 156.71419 -294.958262)
		(end 160.66643 -298.910502)
		(width 0.14478)
		(layer "In4.Cu")
		(net "M_J_CPU1_SB_DQ<13>")
	)
	(segment
		(start 147.895818 -283.602684)
		(end 149.28723 -283.602684)
		(width 0.14478)
		(layer "In4.Cu")
		(net "M_J_CPU1_SB_DQ<13>")
	)
	(segment
		(start 182.941468 -298.060364)
		(end 189.023752 -298.060364)
		(width 0.14478)
		(layer "In4.Cu")
		(net "M_J_CPU1_SB_DQ<13>")
	)
	(segment
		(start 160.66643 -298.910502)
		(end 165.66896 -298.910502)
		(width 0.14478)
		(layer "In4.Cu")
		(net "M_J_CPU1_SB_DQ<13>")
	)
	(segment
		(start 147.378166 -283.407104)
		(end 147.573746 -283.602684)
		(width 0.0889)
		(layer "In4.Cu")
		(net "M_J_CPU1_SB_DQ<13>")
	)
	(segment
		(start 143.847566 -283.318966)
		(end 143.855948 -283.323792)
		(width 0.0889)
		(layer "In4.Cu")
		(net "M_J_CPU1_SB_DQ<13>")
	)
	(segment
		(start 131.993386 -283.323792)
		(end 132.001768 -283.318966)
		(width 0.0889)
		(layer "In4.Cu")
		(net "M_J_CPU1_SB_DQ<13>")
	)
	(segment
		(start 146.274028 -283.191966)
		(end 146.489166 -283.407104)
		(width 0.0889)
		(layer "In4.Cu")
		(net "M_J_CPU1_SB_DQ<13>")
	)
	(segment
		(start 176.920144 -298.060618)
		(end 178.971448 -298.910248)
		(width 0.14478)
		(layer "In4.Cu")
		(net "M_J_CPU1_SB_DQ<13>")
	)
	(segment
		(start 175.254666 -298.060618)
		(end 176.920144 -298.060618)
		(width 0.14478)
		(layer "In4.Cu")
		(net "M_J_CPU1_SB_DQ<13>")
	)
	(segment
		(start 165.66896 -298.910502)
		(end 167.720772 -298.060618)
		(width 0.14478)
		(layer "In4.Cu")
		(net "M_J_CPU1_SB_DQ<13>")
	)
	(segment
		(start 180.889656 -298.910248)
		(end 182.941468 -298.060364)
		(width 0.14478)
		(layer "In4.Cu")
		(net "M_J_CPU1_SB_DQ<13>")
	)
	(segment
		(start 145.620994 -283.191966)
		(end 146.274028 -283.191966)
		(width 0.0889)
		(layer "In4.Cu")
		(net "M_J_CPU1_SB_DQ<13>")
	)
	(segment
		(start 147.573746 -283.602684)
		(end 147.895818 -283.602684)
		(width 0.0889)
		(layer "In4.Cu")
		(net "M_J_CPU1_SB_DQ<13>")
	)
	(segment
		(start 173.202854 -298.910502)
		(end 175.254666 -298.060618)
		(width 0.14478)
		(layer "In4.Cu")
		(net "M_J_CPU1_SB_DQ<13>")
	)
	(segment
		(start 169.613834 -298.060618)
		(end 171.665646 -298.910502)
		(width 0.14478)
		(layer "In4.Cu")
		(net "M_J_CPU1_SB_DQ<13>")
	)
	(segment
		(start 171.665646 -298.910502)
		(end 173.202854 -298.910502)
		(width 0.14478)
		(layer "In4.Cu")
		(net "M_J_CPU1_SB_DQ<13>")
	)
	(segment
		(start 156.71419 -291.029644)
		(end 156.71419 -294.958262)
		(width 0.14478)
		(layer "In4.Cu")
		(net "M_J_CPU1_SB_DQ<13>")
	)
	(segment
		(start 140.453364 -283.323792)
		(end 140.461746 -283.318966)
		(width 0.0889)
		(layer "In4.Cu")
		(net "M_J_CPU1_SB_DQ<13>")
	)
	(segment
		(start 146.489166 -283.407104)
		(end 147.378166 -283.407104)
		(width 0.0889)
		(layer "In4.Cu")
		(net "M_J_CPU1_SB_DQ<13>")
	)
	(segment
		(start 167.720772 -298.060618)
		(end 169.613834 -298.060618)
		(width 0.14478)
		(layer "In4.Cu")
		(net "M_J_CPU1_SB_DQ<13>")
	)
	(segment
		(start 131.660646 -283.261816)
		(end 131.682998 -283.345128)
		(width 0.0889)
		(layer "In4.Cu")
		(net "M_J_CPU1_SB_DQ<13>")
	)
	(segment
		(start 136.693402 -283.323792)
		(end 136.701784 -283.318966)
		(width 0.0889)
		(layer "In4.Cu")
		(net "M_J_CPU1_SB_DQ<13>")
	)
	(segment
		(start 141.967712 -283.318966)
		(end 141.976094 -283.323792)
		(width 0.0889)
		(layer "In4.Cu")
		(net "M_J_CPU1_SB_DQ<13>")
	)
	(segment
		(start 133.507734 -283.318966)
		(end 133.516116 -283.323792)
		(width 0.0889)
		(layer "In4.Cu")
		(net "M_J_CPU1_SB_DQ<13>")
	)
	(segment
		(start 144.777968 -283.31287)
		(end 144.788382 -283.318966)
		(width 0.0889)
		(layer "In4.Cu")
		(net "M_J_CPU1_SB_DQ<13>")
	)
	(segment
		(start 132.93344 -283.323792)
		(end 132.941822 -283.318966)
		(width 0.0889)
		(layer "In4.Cu")
		(net "M_J_CPU1_SB_DQ<13>")
	)
	(arc
		(start 137.641838 -283.318966)
		(mid 137.924794 -283.242789)
		(end 138.20775 -283.318966)
		(width 0.0889)
		(layer "In4.Cu")
		(net "M_J_CPU1_SB_DQ<13>")
	)
	(arc
		(start 142.907766 -283.318966)
		(mid 143.09471 -283.369221)
		(end 143.281654 -283.318966)
		(width 0.0889)
		(layer "In4.Cu")
		(net "M_J_CPU1_SB_DQ<13>")
	)
	(arc
		(start 144.788382 -283.318966)
		(mid 144.966032 -283.369226)
		(end 145.146014 -283.32811)
		(width 0.0889)
		(layer "In4.Cu")
		(net "M_J_CPU1_SB_DQ<13>")
	)
	(arc
		(start 140.087604 -283.318966)
		(mid 140.269855 -283.369316)
		(end 140.453364 -283.323792)
		(width 0.0889)
		(layer "In4.Cu")
		(net "M_J_CPU1_SB_DQ<13>")
	)
	(arc
		(start 141.976094 -283.323792)
		(mid 142.159602 -283.369286)
		(end 142.341854 -283.318966)
		(width 0.0889)
		(layer "In4.Cu")
		(net "M_J_CPU1_SB_DQ<13>")
	)
	(arc
		(start 135.387588 -283.318966)
		(mid 135.569839 -283.369316)
		(end 135.753348 -283.323792)
		(width 0.0889)
		(layer "In4.Cu")
		(net "M_J_CPU1_SB_DQ<13>")
	)
	(arc
		(start 138.216132 -283.323792)
		(mid 138.39964 -283.369286)
		(end 138.581892 -283.318966)
		(width 0.0889)
		(layer "In4.Cu")
		(net "M_J_CPU1_SB_DQ<13>")
	)
	(arc
		(start 141.027658 -283.318966)
		(mid 141.209909 -283.369316)
		(end 141.393418 -283.323792)
		(width 0.0889)
		(layer "In4.Cu")
		(net "M_J_CPU1_SB_DQ<13>")
	)
	(arc
		(start 136.701784 -283.318966)
		(mid 136.98474 -283.242789)
		(end 137.267696 -283.318966)
		(width 0.0889)
		(layer "In4.Cu")
		(net "M_J_CPU1_SB_DQ<13>")
	)
	(arc
		(start 132.56768 -283.318966)
		(mid 132.749931 -283.369316)
		(end 132.93344 -283.323792)
		(width 0.0889)
		(layer "In4.Cu")
		(net "M_J_CPU1_SB_DQ<13>")
	)
	(arc
		(start 145.146014 -283.32811)
		(mid 145.373951 -283.22673)
		(end 145.620994 -283.191966)
		(width 0.0889)
		(layer "In4.Cu")
		(net "M_J_CPU1_SB_DQ<13>")
	)
	(arc
		(start 132.941822 -283.318966)
		(mid 133.224778 -283.242789)
		(end 133.507734 -283.318966)
		(width 0.0889)
		(layer "In4.Cu")
		(net "M_J_CPU1_SB_DQ<13>")
	)
	(arc
		(start 138.581892 -283.318966)
		(mid 138.864848 -283.242789)
		(end 139.147804 -283.318966)
		(width 0.0889)
		(layer "In4.Cu")
		(net "M_J_CPU1_SB_DQ<13>")
	)
	(arc
		(start 135.76173 -283.318966)
		(mid 136.044686 -283.242789)
		(end 136.327642 -283.318966)
		(width 0.0889)
		(layer "In4.Cu")
		(net "M_J_CPU1_SB_DQ<13>")
	)
	(arc
		(start 134.821676 -283.318966)
		(mid 135.104632 -283.242789)
		(end 135.387588 -283.318966)
		(width 0.0889)
		(layer "In4.Cu")
		(net "M_J_CPU1_SB_DQ<13>")
	)
	(arc
		(start 134.447788 -283.318966)
		(mid 134.634732 -283.369221)
		(end 134.821676 -283.318966)
		(width 0.0889)
		(layer "In4.Cu")
		(net "M_J_CPU1_SB_DQ<13>")
	)
	(arc
		(start 139.521692 -283.318966)
		(mid 139.804648 -283.242789)
		(end 140.087604 -283.318966)
		(width 0.0889)
		(layer "In4.Cu")
		(net "M_J_CPU1_SB_DQ<13>")
	)
	(arc
		(start 140.461746 -283.318966)
		(mid 140.744702 -283.242789)
		(end 141.027658 -283.318966)
		(width 0.0889)
		(layer "In4.Cu")
		(net "M_J_CPU1_SB_DQ<13>")
	)
	(arc
		(start 141.4018 -283.318966)
		(mid 141.684756 -283.242789)
		(end 141.967712 -283.318966)
		(width 0.0889)
		(layer "In4.Cu")
		(net "M_J_CPU1_SB_DQ<13>")
	)
	(arc
		(start 137.276078 -283.323792)
		(mid 137.459586 -283.369286)
		(end 137.641838 -283.318966)
		(width 0.0889)
		(layer "In4.Cu")
		(net "M_J_CPU1_SB_DQ<13>")
	)
	(arc
		(start 142.341854 -283.318966)
		(mid 142.62481 -283.242789)
		(end 142.907766 -283.318966)
		(width 0.0889)
		(layer "In4.Cu")
		(net "M_J_CPU1_SB_DQ<13>")
	)
	(arc
		(start 139.147804 -283.318966)
		(mid 139.334748 -283.369221)
		(end 139.521692 -283.318966)
		(width 0.0889)
		(layer "In4.Cu")
		(net "M_J_CPU1_SB_DQ<13>")
	)
	(arc
		(start 132.001768 -283.318966)
		(mid 132.284724 -283.242789)
		(end 132.56768 -283.318966)
		(width 0.0889)
		(layer "In4.Cu")
		(net "M_J_CPU1_SB_DQ<13>")
	)
	(arc
		(start 143.281654 -283.318966)
		(mid 143.56461 -283.242789)
		(end 143.847566 -283.318966)
		(width 0.0889)
		(layer "In4.Cu")
		(net "M_J_CPU1_SB_DQ<13>")
	)
	(arc
		(start 144.222216 -283.318966)
		(mid 144.499283 -283.242695)
		(end 144.777968 -283.31287)
		(width 0.0889)
		(layer "In4.Cu")
		(net "M_J_CPU1_SB_DQ<13>")
	)
	(arc
		(start 133.516116 -283.323792)
		(mid 133.699624 -283.369286)
		(end 133.881876 -283.318966)
		(width 0.0889)
		(layer "In4.Cu")
		(net "M_J_CPU1_SB_DQ<13>")
	)
	(arc
		(start 131.682998 -283.345128)
		(mid 131.840508 -283.368326)
		(end 131.993386 -283.323792)
		(width 0.0889)
		(layer "In4.Cu")
		(net "M_J_CPU1_SB_DQ<13>")
	)
	(arc
		(start 143.855948 -283.323792)
		(mid 144.03971 -283.369408)
		(end 144.222216 -283.318966)
		(width 0.0889)
		(layer "In4.Cu")
		(net "M_J_CPU1_SB_DQ<13>")
	)
	(arc
		(start 133.881876 -283.318966)
		(mid 134.164832 -283.242789)
		(end 134.447788 -283.318966)
		(width 0.0889)
		(layer "In4.Cu")
		(net "M_J_CPU1_SB_DQ<13>")
	)
	(arc
		(start 136.327642 -283.318966)
		(mid 136.509893 -283.369316)
		(end 136.693402 -283.323792)
		(width 0.0889)
		(layer "In4.Cu")
		(net "M_J_CPU1_SB_DQ<13>")
	)
	(segment
		(start 132.757926 -281.920442)
		(end 133.224778 -282.18638)
		(width 0.10668)
		(layer "F.Cu")
		(net "M_J_CPU1_SB_DQ<12>")
	)
	(segment
		(start 178.30038 -297.219878)
		(end 181.258464 -297.219878)
		(width 0.14478)
		(layer "In4.Cu")
		(net "M_J_CPU1_SB_DQ<12>")
	)
	(segment
		(start 144.316196 -282.508706)
		(end 144.334484 -282.51912)
		(width 0.0889)
		(layer "In4.Cu")
		(net "M_J_CPU1_SB_DQ<12>")
	)
	(segment
		(start 134.343394 -282.513786)
		(end 134.351776 -282.50896)
		(width 0.0889)
		(layer "In4.Cu")
		(net "M_J_CPU1_SB_DQ<12>")
	)
	(segment
		(start 167.092884 -296.360596)
		(end 169.75074 -296.360596)
		(width 0.14478)
		(layer "In4.Cu")
		(net "M_J_CPU1_SB_DQ<12>")
	)
	(segment
		(start 144.294606 -282.49626)
		(end 144.316196 -282.508706)
		(width 0.0889)
		(layer "In4.Cu")
		(net "M_J_CPU1_SB_DQ<12>")
	)
	(segment
		(start 189.663832 -297.057826)
		(end 189.825376 -296.896282)
		(width 0.14478)
		(layer "In4.Cu")
		(net "M_J_CPU1_SB_DQ<12>")
	)
	(segment
		(start 174.62754 -296.369994)
		(end 177.450496 -296.369994)
		(width 0.14478)
		(layer "In4.Cu")
		(net "M_J_CPU1_SB_DQ<12>")
	)
	(segment
		(start 143.377666 -282.50896)
		(end 143.386048 -282.513786)
		(width 0.0889)
		(layer "In4.Cu")
		(net "M_J_CPU1_SB_DQ<12>")
	)
	(segment
		(start 173.777402 -297.220132)
		(end 174.62754 -296.369994)
		(width 0.14478)
		(layer "In4.Cu")
		(net "M_J_CPU1_SB_DQ<12>")
	)
	(segment
		(start 140.557758 -282.50896)
		(end 140.56614 -282.513786)
		(width 0.0889)
		(layer "In4.Cu")
		(net "M_J_CPU1_SB_DQ<12>")
	)
	(segment
		(start 146.296888 -282.560014)
		(end 146.506438 -282.350464)
		(width 0.0889)
		(layer "In4.Cu")
		(net "M_J_CPU1_SB_DQ<12>")
	)
	(segment
		(start 133.070854 -282.45181)
		(end 133.093206 -282.535122)
		(width 0.0889)
		(layer "In4.Cu")
		(net "M_J_CPU1_SB_DQ<12>")
	)
	(segment
		(start 170.610276 -297.220132)
		(end 173.777402 -297.220132)
		(width 0.14478)
		(layer "In4.Cu")
		(net "M_J_CPU1_SB_DQ<12>")
	)
	(segment
		(start 190.744856 -296.369994)
		(end 191.160146 -296.785284)
		(width 0.14478)
		(layer "In4.Cu")
		(net "M_J_CPU1_SB_DQ<12>")
	)
	(segment
		(start 189.825376 -296.896282)
		(end 189.825376 -296.531538)
		(width 0.14478)
		(layer "In4.Cu")
		(net "M_J_CPU1_SB_DQ<12>")
	)
	(segment
		(start 169.75074 -296.360596)
		(end 170.610276 -297.220132)
		(width 0.14478)
		(layer "In4.Cu")
		(net "M_J_CPU1_SB_DQ<12>")
	)
	(segment
		(start 144.689322 -282.50896)
		(end 144.71269 -282.495244)
		(width 0.0889)
		(layer "In4.Cu")
		(net "M_J_CPU1_SB_DQ<12>")
	)
	(segment
		(start 133.224778 -282.18638)
		(end 133.070854 -282.45181)
		(width 0.0889)
		(layer "In4.Cu")
		(net "M_J_CPU1_SB_DQ<12>")
	)
	(segment
		(start 147.895818 -282.693364)
		(end 149.649942 -282.693364)
		(width 0.14478)
		(layer "In4.Cu")
		(net "M_J_CPU1_SB_DQ<12>")
	)
	(segment
		(start 181.258464 -297.219878)
		(end 182.108348 -296.369994)
		(width 0.14478)
		(layer "In4.Cu")
		(net "M_J_CPU1_SB_DQ<12>")
	)
	(segment
		(start 189.273942 -296.896282)
		(end 189.435486 -297.057826)
		(width 0.14478)
		(layer "In4.Cu")
		(net "M_J_CPU1_SB_DQ<12>")
	)
	(segment
		(start 139.617704 -282.50896)
		(end 139.626086 -282.513786)
		(width 0.0889)
		(layer "In4.Cu")
		(net "M_J_CPU1_SB_DQ<12>")
	)
	(segment
		(start 145.444972 -282.560014)
		(end 146.296888 -282.560014)
		(width 0.0889)
		(layer "In4.Cu")
		(net "M_J_CPU1_SB_DQ<12>")
	)
	(segment
		(start 138.103356 -282.513786)
		(end 138.111738 -282.50896)
		(width 0.0889)
		(layer "In4.Cu")
		(net "M_J_CPU1_SB_DQ<12>")
	)
	(segment
		(start 145.444718 -282.55976)
		(end 145.444972 -282.560014)
		(width 0.0889)
		(layer "In4.Cu")
		(net "M_J_CPU1_SB_DQ<12>")
	)
	(segment
		(start 146.506438 -282.350464)
		(end 147.274534 -282.350464)
		(width 0.0889)
		(layer "In4.Cu")
		(net "M_J_CPU1_SB_DQ<12>")
	)
	(segment
		(start 135.857742 -282.50896)
		(end 135.866124 -282.513786)
		(width 0.0889)
		(layer "In4.Cu")
		(net "M_J_CPU1_SB_DQ<12>")
	)
	(segment
		(start 147.274534 -282.350464)
		(end 147.617434 -282.693364)
		(width 0.0889)
		(layer "In4.Cu")
		(net "M_J_CPU1_SB_DQ<12>")
	)
	(segment
		(start 166.243 -297.21048)
		(end 167.092884 -296.360596)
		(width 0.14478)
		(layer "In4.Cu")
		(net "M_J_CPU1_SB_DQ<12>")
	)
	(segment
		(start 177.450496 -296.369994)
		(end 178.30038 -297.219878)
		(width 0.14478)
		(layer "In4.Cu")
		(net "M_J_CPU1_SB_DQ<12>")
	)
	(segment
		(start 139.04341 -282.513786)
		(end 139.051792 -282.50896)
		(width 0.0889)
		(layer "In4.Cu")
		(net "M_J_CPU1_SB_DQ<12>")
	)
	(segment
		(start 189.112398 -296.369994)
		(end 189.273942 -296.531538)
		(width 0.14478)
		(layer "In4.Cu")
		(net "M_J_CPU1_SB_DQ<12>")
	)
	(segment
		(start 182.108348 -296.369994)
		(end 189.112398 -296.369994)
		(width 0.14478)
		(layer "In4.Cu")
		(net "M_J_CPU1_SB_DQ<12>")
	)
	(segment
		(start 147.617434 -282.693364)
		(end 147.895818 -282.693364)
		(width 0.0889)
		(layer "In4.Cu")
		(net "M_J_CPU1_SB_DQ<12>")
	)
	(segment
		(start 157.61335 -290.656772)
		(end 157.61335 -293.6748)
		(width 0.14478)
		(layer "In4.Cu")
		(net "M_J_CPU1_SB_DQ<12>")
	)
	(segment
		(start 189.435486 -297.057826)
		(end 189.663832 -297.057826)
		(width 0.14478)
		(layer "In4.Cu")
		(net "M_J_CPU1_SB_DQ<12>")
	)
	(segment
		(start 149.649942 -282.693364)
		(end 157.61335 -290.656772)
		(width 0.14478)
		(layer "In4.Cu")
		(net "M_J_CPU1_SB_DQ<12>")
	)
	(segment
		(start 189.273942 -296.531538)
		(end 189.273942 -296.896282)
		(width 0.14478)
		(layer "In4.Cu")
		(net "M_J_CPU1_SB_DQ<12>")
	)
	(segment
		(start 189.825376 -296.531538)
		(end 189.98692 -296.369994)
		(width 0.14478)
		(layer "In4.Cu")
		(net "M_J_CPU1_SB_DQ<12>")
	)
	(segment
		(start 142.803372 -282.513786)
		(end 142.811754 -282.50896)
		(width 0.0889)
		(layer "In4.Cu")
		(net "M_J_CPU1_SB_DQ<12>")
	)
	(segment
		(start 134.917688 -282.50896)
		(end 134.92607 -282.513786)
		(width 0.0889)
		(layer "In4.Cu")
		(net "M_J_CPU1_SB_DQ<12>")
	)
	(segment
		(start 161.14903 -297.21048)
		(end 166.243 -297.21048)
		(width 0.14478)
		(layer "In4.Cu")
		(net "M_J_CPU1_SB_DQ<12>")
	)
	(segment
		(start 189.98692 -296.369994)
		(end 190.744856 -296.369994)
		(width 0.14478)
		(layer "In4.Cu")
		(net "M_J_CPU1_SB_DQ<12>")
	)
	(segment
		(start 157.61335 -293.6748)
		(end 161.14903 -297.21048)
		(width 0.14478)
		(layer "In4.Cu")
		(net "M_J_CPU1_SB_DQ<12>")
	)
	(arc
		(start 140.56614 -282.513786)
		(mid 140.749648 -282.55928)
		(end 140.9319 -282.50896)
		(width 0.0889)
		(layer "In4.Cu")
		(net "M_J_CPU1_SB_DQ<12>")
	)
	(arc
		(start 133.093206 -282.535122)
		(mid 133.255395 -282.557857)
		(end 133.411722 -282.50896)
		(width 0.0889)
		(layer "In4.Cu")
		(net "M_J_CPU1_SB_DQ<12>")
	)
	(arc
		(start 136.231884 -282.50896)
		(mid 136.51484 -282.432783)
		(end 136.797796 -282.50896)
		(width 0.0889)
		(layer "In4.Cu")
		(net "M_J_CPU1_SB_DQ<12>")
	)
	(arc
		(start 134.351776 -282.50896)
		(mid 134.634732 -282.432783)
		(end 134.917688 -282.50896)
		(width 0.0889)
		(layer "In4.Cu")
		(net "M_J_CPU1_SB_DQ<12>")
	)
	(arc
		(start 143.751808 -282.50896)
		(mid 144.021577 -282.432937)
		(end 144.294606 -282.49626)
		(width 0.0889)
		(layer "In4.Cu")
		(net "M_J_CPU1_SB_DQ<12>")
	)
	(arc
		(start 137.171684 -282.50896)
		(mid 137.45464 -282.432783)
		(end 137.737596 -282.50896)
		(width 0.0889)
		(layer "In4.Cu")
		(net "M_J_CPU1_SB_DQ<12>")
	)
	(arc
		(start 133.977634 -282.50896)
		(mid 134.159885 -282.55931)
		(end 134.343394 -282.513786)
		(width 0.0889)
		(layer "In4.Cu")
		(net "M_J_CPU1_SB_DQ<12>")
	)
	(arc
		(start 135.866124 -282.513786)
		(mid 136.049632 -282.55928)
		(end 136.231884 -282.50896)
		(width 0.0889)
		(layer "In4.Cu")
		(net "M_J_CPU1_SB_DQ<12>")
	)
	(arc
		(start 140.9319 -282.50896)
		(mid 141.214856 -282.432783)
		(end 141.497812 -282.50896)
		(width 0.0889)
		(layer "In4.Cu")
		(net "M_J_CPU1_SB_DQ<12>")
	)
	(arc
		(start 136.797796 -282.50896)
		(mid 136.98474 -282.559215)
		(end 137.171684 -282.50896)
		(width 0.0889)
		(layer "In4.Cu")
		(net "M_J_CPU1_SB_DQ<12>")
	)
	(arc
		(start 139.051792 -282.50896)
		(mid 139.334748 -282.432783)
		(end 139.617704 -282.50896)
		(width 0.0889)
		(layer "In4.Cu")
		(net "M_J_CPU1_SB_DQ<12>")
	)
	(arc
		(start 142.437612 -282.50896)
		(mid 142.619863 -282.55931)
		(end 142.803372 -282.513786)
		(width 0.0889)
		(layer "In4.Cu")
		(net "M_J_CPU1_SB_DQ<12>")
	)
	(arc
		(start 138.111738 -282.50896)
		(mid 138.394694 -282.432783)
		(end 138.67765 -282.50896)
		(width 0.0889)
		(layer "In4.Cu")
		(net "M_J_CPU1_SB_DQ<12>")
	)
	(arc
		(start 137.737596 -282.50896)
		(mid 137.919847 -282.55931)
		(end 138.103356 -282.513786)
		(width 0.0889)
		(layer "In4.Cu")
		(net "M_J_CPU1_SB_DQ<12>")
	)
	(arc
		(start 142.811754 -282.50896)
		(mid 143.09471 -282.432783)
		(end 143.377666 -282.50896)
		(width 0.0889)
		(layer "In4.Cu")
		(net "M_J_CPU1_SB_DQ<12>")
	)
	(arc
		(start 139.991846 -282.50896)
		(mid 140.274802 -282.432783)
		(end 140.557758 -282.50896)
		(width 0.0889)
		(layer "In4.Cu")
		(net "M_J_CPU1_SB_DQ<12>")
	)
	(arc
		(start 141.497812 -282.50896)
		(mid 141.684756 -282.559215)
		(end 141.8717 -282.50896)
		(width 0.0889)
		(layer "In4.Cu")
		(net "M_J_CPU1_SB_DQ<12>")
	)
	(arc
		(start 141.8717 -282.50896)
		(mid 142.154656 -282.432783)
		(end 142.437612 -282.50896)
		(width 0.0889)
		(layer "In4.Cu")
		(net "M_J_CPU1_SB_DQ<12>")
	)
	(arc
		(start 139.626086 -282.513786)
		(mid 139.809594 -282.55928)
		(end 139.991846 -282.50896)
		(width 0.0889)
		(layer "In4.Cu")
		(net "M_J_CPU1_SB_DQ<12>")
	)
	(arc
		(start 135.29183 -282.50896)
		(mid 135.574786 -282.432783)
		(end 135.857742 -282.50896)
		(width 0.0889)
		(layer "In4.Cu")
		(net "M_J_CPU1_SB_DQ<12>")
	)
	(arc
		(start 144.334484 -282.51912)
		(mid 144.513205 -282.559043)
		(end 144.689322 -282.50896)
		(width 0.0889)
		(layer "In4.Cu")
		(net "M_J_CPU1_SB_DQ<12>")
	)
	(arc
		(start 138.67765 -282.50896)
		(mid 138.859901 -282.55931)
		(end 139.04341 -282.513786)
		(width 0.0889)
		(layer "In4.Cu")
		(net "M_J_CPU1_SB_DQ<12>")
	)
	(arc
		(start 143.386048 -282.513786)
		(mid 143.569556 -282.55928)
		(end 143.751808 -282.50896)
		(width 0.0889)
		(layer "In4.Cu")
		(net "M_J_CPU1_SB_DQ<12>")
	)
	(arc
		(start 145.256504 -282.50896)
		(mid 145.347239 -282.546844)
		(end 145.444718 -282.55976)
		(width 0.0889)
		(layer "In4.Cu")
		(net "M_J_CPU1_SB_DQ<12>")
	)
	(arc
		(start 133.411722 -282.50896)
		(mid 133.694678 -282.432783)
		(end 133.977634 -282.50896)
		(width 0.0889)
		(layer "In4.Cu")
		(net "M_J_CPU1_SB_DQ<12>")
	)
	(arc
		(start 134.92607 -282.513786)
		(mid 135.109578 -282.55928)
		(end 135.29183 -282.50896)
		(width 0.0889)
		(layer "In4.Cu")
		(net "M_J_CPU1_SB_DQ<12>")
	)
	(arc
		(start 144.71269 -282.495244)
		(mid 144.986344 -282.432301)
		(end 145.256504 -282.50896)
		(width 0.0889)
		(layer "In4.Cu")
		(net "M_J_CPU1_SB_DQ<12>")
	)
	(segment
		(start 130.877818 -280.30043)
		(end 131.34467 -280.566368)
		(width 0.10668)
		(layer "F.Cu")
		(net "M_J_CPU1_SB_DQ<11>")
	)
	(segment
		(start 160.254188 -290.513262)
		(end 160.254188 -290.741862)
		(width 0.14478)
		(layer "In4.Cu")
		(net "M_J_CPU1_SB_DQ<11>")
	)
	(segment
		(start 161.86785 -293.02964)
		(end 162.204908 -292.692582)
		(width 0.14478)
		(layer "In4.Cu")
		(net "M_J_CPU1_SB_DQ<11>")
	)
	(segment
		(start 181.147212 -293.80053)
		(end 181.997096 -292.950646)
		(width 0.14478)
		(layer "In4.Cu")
		(net "M_J_CPU1_SB_DQ<11>")
	)
	(segment
		(start 138.103356 -280.238962)
		(end 138.111738 -280.243788)
		(width 0.0889)
		(layer "In4.Cu")
		(net "M_J_CPU1_SB_DQ<11>")
	)
	(segment
		(start 159.91713 -291.07892)
		(end 159.91713 -291.30752)
		(width 0.14478)
		(layer "In4.Cu")
		(net "M_J_CPU1_SB_DQ<11>")
	)
	(segment
		(start 160.697418 -291.859208)
		(end 160.697418 -292.087808)
		(width 0.14478)
		(layer "In4.Cu")
		(net "M_J_CPU1_SB_DQ<11>")
	)
	(segment
		(start 147.808696 -280.192988)
		(end 147.816062 -280.200354)
		(width 0.0889)
		(layer "In4.Cu")
		(net "M_J_CPU1_SB_DQ<11>")
	)
	(segment
		(start 142.803372 -280.238962)
		(end 142.811754 -280.243788)
		(width 0.0889)
		(layer "In4.Cu")
		(net "M_J_CPU1_SB_DQ<11>")
	)
	(segment
		(start 131.498848 -280.300938)
		(end 131.595114 -280.275538)
		(width 0.0889)
		(layer "In4.Cu")
		(net "M_J_CPU1_SB_DQ<11>")
	)
	(segment
		(start 134.343394 -280.238962)
		(end 134.351776 -280.243788)
		(width 0.0889)
		(layer "In4.Cu")
		(net "M_J_CPU1_SB_DQ<11>")
	)
	(segment
		(start 181.997096 -292.950646)
		(end 184.402222 -292.950646)
		(width 0.14478)
		(layer "In4.Cu")
		(net "M_J_CPU1_SB_DQ<11>")
	)
	(segment
		(start 143.751808 -280.243788)
		(end 143.762222 -280.249884)
		(width 0.0889)
		(layer "In4.Cu")
		(net "M_J_CPU1_SB_DQ<11>")
	)
	(segment
		(start 161.034476 -291.52215)
		(end 160.697418 -291.859208)
		(width 0.14478)
		(layer "In4.Cu")
		(net "M_J_CPU1_SB_DQ<11>")
	)
	(segment
		(start 185.79465 -292.661086)
		(end 186.056524 -292.661086)
		(width 0.14478)
		(layer "In4.Cu")
		(net "M_J_CPU1_SB_DQ<11>")
	)
	(segment
		(start 162.595052 -293.082726)
		(end 162.257994 -293.419784)
		(width 0.14478)
		(layer "In4.Cu")
		(net "M_J_CPU1_SB_DQ<11>")
	)
	(segment
		(start 174.390304 -292.950646)
		(end 177.694082 -292.950646)
		(width 0.14478)
		(layer "In4.Cu")
		(net "M_J_CPU1_SB_DQ<11>")
	)
	(segment
		(start 160.872932 -291.132006)
		(end 161.034476 -291.29355)
		(width 0.14478)
		(layer "In4.Cu")
		(net "M_J_CPU1_SB_DQ<11>")
	)
	(segment
		(start 161.477706 -292.868096)
		(end 161.63925 -293.02964)
		(width 0.14478)
		(layer "In4.Cu")
		(net "M_J_CPU1_SB_DQ<11>")
	)
	(segment
		(start 145.444718 -280.192988)
		(end 147.808696 -280.192988)
		(width 0.0889)
		(layer "In4.Cu")
		(net "M_J_CPU1_SB_DQ<11>")
	)
	(segment
		(start 162.257994 -293.419784)
		(end 162.257994 -293.648384)
		(width 0.14478)
		(layer "In4.Cu")
		(net "M_J_CPU1_SB_DQ<11>")
	)
	(segment
		(start 144.684242 -280.238962)
		(end 144.692624 -280.243788)
		(width 0.0889)
		(layer "In4.Cu")
		(net "M_J_CPU1_SB_DQ<11>")
	)
	(segment
		(start 140.557758 -280.243788)
		(end 140.56614 -280.238962)
		(width 0.0889)
		(layer "In4.Cu")
		(net "M_J_CPU1_SB_DQ<11>")
	)
	(segment
		(start 159.91713 -291.30752)
		(end 160.078674 -291.469064)
		(width 0.14478)
		(layer "In4.Cu")
		(net "M_J_CPU1_SB_DQ<11>")
	)
	(segment
		(start 160.858962 -292.249352)
		(end 161.087562 -292.249352)
		(width 0.14478)
		(layer "In4.Cu")
		(net "M_J_CPU1_SB_DQ<11>")
	)
	(segment
		(start 185.50509 -292.950646)
		(end 185.79465 -292.661086)
		(width 0.14478)
		(layer "In4.Cu")
		(net "M_J_CPU1_SB_DQ<11>")
	)
	(segment
		(start 162.257994 -293.648384)
		(end 162.419538 -293.809928)
		(width 0.14478)
		(layer "In4.Cu")
		(net "M_J_CPU1_SB_DQ<11>")
	)
	(segment
		(start 143.377666 -280.243788)
		(end 143.386048 -280.238962)
		(width 0.0889)
		(layer "In4.Cu")
		(net "M_J_CPU1_SB_DQ<11>")
	)
	(segment
		(start 162.204908 -292.692582)
		(end 162.433508 -292.692582)
		(width 0.14478)
		(layer "In4.Cu")
		(net "M_J_CPU1_SB_DQ<11>")
	)
	(segment
		(start 161.477706 -292.639496)
		(end 161.477706 -292.868096)
		(width 0.14478)
		(layer "In4.Cu")
		(net "M_J_CPU1_SB_DQ<11>")
	)
	(segment
		(start 177.694082 -292.950646)
		(end 178.543966 -293.80053)
		(width 0.14478)
		(layer "In4.Cu")
		(net "M_J_CPU1_SB_DQ<11>")
	)
	(segment
		(start 139.617704 -280.243788)
		(end 139.626086 -280.238962)
		(width 0.0889)
		(layer "In4.Cu")
		(net "M_J_CPU1_SB_DQ<11>")
	)
	(segment
		(start 160.078674 -291.469064)
		(end 160.307274 -291.469064)
		(width 0.14478)
		(layer "In4.Cu")
		(net "M_J_CPU1_SB_DQ<11>")
	)
	(segment
		(start 160.644332 -291.132006)
		(end 160.872932 -291.132006)
		(width 0.14478)
		(layer "In4.Cu")
		(net "M_J_CPU1_SB_DQ<11>")
	)
	(segment
		(start 161.814764 -292.302438)
		(end 161.477706 -292.639496)
		(width 0.14478)
		(layer "In4.Cu")
		(net "M_J_CPU1_SB_DQ<11>")
	)
	(segment
		(start 139.04341 -280.238962)
		(end 139.051792 -280.243788)
		(width 0.0889)
		(layer "In4.Cu")
		(net "M_J_CPU1_SB_DQ<11>")
	)
	(segment
		(start 162.419538 -293.809928)
		(end 162.74034 -293.809928)
		(width 0.14478)
		(layer "In4.Cu")
		(net "M_J_CPU1_SB_DQ<11>")
	)
	(segment
		(start 184.402222 -292.950646)
		(end 184.691782 -292.661086)
		(width 0.14478)
		(layer "In4.Cu")
		(net "M_J_CPU1_SB_DQ<11>")
	)
	(segment
		(start 159.90189 -290.160964)
		(end 160.254188 -290.513262)
		(width 0.14478)
		(layer "In4.Cu")
		(net "M_J_CPU1_SB_DQ<11>")
	)
	(segment
		(start 150.394416 -280.200354)
		(end 159.90189 -289.707828)
		(width 0.14478)
		(layer "In4.Cu")
		(net "M_J_CPU1_SB_DQ<11>")
	)
	(segment
		(start 186.056524 -292.661086)
		(end 186.346084 -292.950646)
		(width 0.14478)
		(layer "In4.Cu")
		(net "M_J_CPU1_SB_DQ<11>")
	)
	(segment
		(start 166.325804 -293.565072)
		(end 166.930578 -292.960298)
		(width 0.14478)
		(layer "In4.Cu")
		(net "M_J_CPU1_SB_DQ<11>")
	)
	(segment
		(start 161.63925 -293.02964)
		(end 161.86785 -293.02964)
		(width 0.14478)
		(layer "In4.Cu")
		(net "M_J_CPU1_SB_DQ<11>")
	)
	(segment
		(start 161.42462 -291.912294)
		(end 161.65322 -291.912294)
		(width 0.14478)
		(layer "In4.Cu")
		(net "M_J_CPU1_SB_DQ<11>")
	)
	(segment
		(start 186.625484 -292.950646)
		(end 187.060078 -293.38524)
		(width 0.14478)
		(layer "In4.Cu")
		(net "M_J_CPU1_SB_DQ<11>")
	)
	(segment
		(start 162.985196 -293.565072)
		(end 166.325804 -293.565072)
		(width 0.14478)
		(layer "In4.Cu")
		(net "M_J_CPU1_SB_DQ<11>")
	)
	(segment
		(start 166.930578 -292.960298)
		(end 169.934636 -292.960298)
		(width 0.14478)
		(layer "In4.Cu")
		(net "M_J_CPU1_SB_DQ<11>")
	)
	(segment
		(start 184.953656 -292.661086)
		(end 185.243216 -292.950646)
		(width 0.14478)
		(layer "In4.Cu")
		(net "M_J_CPU1_SB_DQ<11>")
	)
	(segment
		(start 161.814764 -292.073838)
		(end 161.814764 -292.302438)
		(width 0.14478)
		(layer "In4.Cu")
		(net "M_J_CPU1_SB_DQ<11>")
	)
	(segment
		(start 178.543966 -293.80053)
		(end 181.147212 -293.80053)
		(width 0.14478)
		(layer "In4.Cu")
		(net "M_J_CPU1_SB_DQ<11>")
	)
	(segment
		(start 169.934636 -292.960298)
		(end 170.774868 -293.80053)
		(width 0.14478)
		(layer "In4.Cu")
		(net "M_J_CPU1_SB_DQ<11>")
	)
	(segment
		(start 134.917688 -280.243788)
		(end 134.92607 -280.238962)
		(width 0.0889)
		(layer "In4.Cu")
		(net "M_J_CPU1_SB_DQ<11>")
	)
	(segment
		(start 135.857742 -280.243788)
		(end 135.866124 -280.238962)
		(width 0.0889)
		(layer "In4.Cu")
		(net "M_J_CPU1_SB_DQ<11>")
	)
	(segment
		(start 162.74034 -293.809928)
		(end 162.985196 -293.565072)
		(width 0.14478)
		(layer "In4.Cu")
		(net "M_J_CPU1_SB_DQ<11>")
	)
	(segment
		(start 185.243216 -292.950646)
		(end 185.50509 -292.950646)
		(width 0.14478)
		(layer "In4.Cu")
		(net "M_J_CPU1_SB_DQ<11>")
	)
	(segment
		(start 131.34467 -280.566368)
		(end 131.498848 -280.300938)
		(width 0.0889)
		(layer "In4.Cu")
		(net "M_J_CPU1_SB_DQ<11>")
	)
	(segment
		(start 161.087562 -292.249352)
		(end 161.42462 -291.912294)
		(width 0.14478)
		(layer "In4.Cu")
		(net "M_J_CPU1_SB_DQ<11>")
	)
	(segment
		(start 159.90189 -289.707828)
		(end 159.90189 -290.160964)
		(width 0.14478)
		(layer "In4.Cu")
		(net "M_J_CPU1_SB_DQ<11>")
	)
	(segment
		(start 161.034476 -291.29355)
		(end 161.034476 -291.52215)
		(width 0.14478)
		(layer "In4.Cu")
		(net "M_J_CPU1_SB_DQ<11>")
	)
	(segment
		(start 160.307274 -291.469064)
		(end 160.644332 -291.132006)
		(width 0.14478)
		(layer "In4.Cu")
		(net "M_J_CPU1_SB_DQ<11>")
	)
	(segment
		(start 162.433508 -292.692582)
		(end 162.595052 -292.854126)
		(width 0.14478)
		(layer "In4.Cu")
		(net "M_J_CPU1_SB_DQ<11>")
	)
	(segment
		(start 160.254188 -290.741862)
		(end 159.91713 -291.07892)
		(width 0.14478)
		(layer "In4.Cu")
		(net "M_J_CPU1_SB_DQ<11>")
	)
	(segment
		(start 160.697418 -292.087808)
		(end 160.858962 -292.249352)
		(width 0.14478)
		(layer "In4.Cu")
		(net "M_J_CPU1_SB_DQ<11>")
	)
	(segment
		(start 186.346084 -292.950646)
		(end 186.625484 -292.950646)
		(width 0.14478)
		(layer "In4.Cu")
		(net "M_J_CPU1_SB_DQ<11>")
	)
	(segment
		(start 170.774868 -293.80053)
		(end 173.54042 -293.80053)
		(width 0.14478)
		(layer "In4.Cu")
		(net "M_J_CPU1_SB_DQ<11>")
	)
	(segment
		(start 173.54042 -293.80053)
		(end 174.390304 -292.950646)
		(width 0.14478)
		(layer "In4.Cu")
		(net "M_J_CPU1_SB_DQ<11>")
	)
	(segment
		(start 147.816062 -280.200354)
		(end 150.394416 -280.200354)
		(width 0.14478)
		(layer "In4.Cu")
		(net "M_J_CPU1_SB_DQ<11>")
	)
	(segment
		(start 184.691782 -292.661086)
		(end 184.953656 -292.661086)
		(width 0.14478)
		(layer "In4.Cu")
		(net "M_J_CPU1_SB_DQ<11>")
	)
	(segment
		(start 132.09778 -280.243788)
		(end 132.106162 -280.238962)
		(width 0.0889)
		(layer "In4.Cu")
		(net "M_J_CPU1_SB_DQ<11>")
	)
	(segment
		(start 161.65322 -291.912294)
		(end 161.814764 -292.073838)
		(width 0.14478)
		(layer "In4.Cu")
		(net "M_J_CPU1_SB_DQ<11>")
	)
	(segment
		(start 162.595052 -292.854126)
		(end 162.595052 -293.082726)
		(width 0.14478)
		(layer "In4.Cu")
		(net "M_J_CPU1_SB_DQ<11>")
	)
	(arc
		(start 141.8717 -280.243788)
		(mid 142.154656 -280.319965)
		(end 142.437612 -280.243788)
		(width 0.0889)
		(layer "In4.Cu")
		(net "M_J_CPU1_SB_DQ<11>")
	)
	(arc
		(start 133.977634 -280.243788)
		(mid 134.159885 -280.193438)
		(end 134.343394 -280.238962)
		(width 0.0889)
		(layer "In4.Cu")
		(net "M_J_CPU1_SB_DQ<11>")
	)
	(arc
		(start 140.9319 -280.243788)
		(mid 141.214856 -280.319965)
		(end 141.497812 -280.243788)
		(width 0.0889)
		(layer "In4.Cu")
		(net "M_J_CPU1_SB_DQ<11>")
	)
	(arc
		(start 134.351776 -280.243788)
		(mid 134.634732 -280.319965)
		(end 134.917688 -280.243788)
		(width 0.0889)
		(layer "In4.Cu")
		(net "M_J_CPU1_SB_DQ<11>")
	)
	(arc
		(start 142.811754 -280.243788)
		(mid 143.09471 -280.319965)
		(end 143.377666 -280.243788)
		(width 0.0889)
		(layer "In4.Cu")
		(net "M_J_CPU1_SB_DQ<11>")
	)
	(arc
		(start 143.762222 -280.249884)
		(mid 144.040908 -280.320104)
		(end 144.317974 -280.243788)
		(width 0.0889)
		(layer "In4.Cu")
		(net "M_J_CPU1_SB_DQ<11>")
	)
	(arc
		(start 144.317974 -280.243788)
		(mid 144.500479 -280.193311)
		(end 144.684242 -280.238962)
		(width 0.0889)
		(layer "In4.Cu")
		(net "M_J_CPU1_SB_DQ<11>")
	)
	(arc
		(start 135.866124 -280.238962)
		(mid 136.049632 -280.193468)
		(end 136.231884 -280.243788)
		(width 0.0889)
		(layer "In4.Cu")
		(net "M_J_CPU1_SB_DQ<11>")
	)
	(arc
		(start 135.29183 -280.243788)
		(mid 135.574786 -280.319965)
		(end 135.857742 -280.243788)
		(width 0.0889)
		(layer "In4.Cu")
		(net "M_J_CPU1_SB_DQ<11>")
	)
	(arc
		(start 139.626086 -280.238962)
		(mid 139.809594 -280.193468)
		(end 139.991846 -280.243788)
		(width 0.0889)
		(layer "In4.Cu")
		(net "M_J_CPU1_SB_DQ<11>")
	)
	(arc
		(start 136.231884 -280.243788)
		(mid 136.51484 -280.319965)
		(end 136.797796 -280.243788)
		(width 0.0889)
		(layer "In4.Cu")
		(net "M_J_CPU1_SB_DQ<11>")
	)
	(arc
		(start 142.437612 -280.243788)
		(mid 142.619863 -280.193438)
		(end 142.803372 -280.238962)
		(width 0.0889)
		(layer "In4.Cu")
		(net "M_J_CPU1_SB_DQ<11>")
	)
	(arc
		(start 141.497812 -280.243788)
		(mid 141.684756 -280.193533)
		(end 141.8717 -280.243788)
		(width 0.0889)
		(layer "In4.Cu")
		(net "M_J_CPU1_SB_DQ<11>")
	)
	(arc
		(start 134.92607 -280.238962)
		(mid 135.109578 -280.193468)
		(end 135.29183 -280.243788)
		(width 0.0889)
		(layer "In4.Cu")
		(net "M_J_CPU1_SB_DQ<11>")
	)
	(arc
		(start 136.797796 -280.243788)
		(mid 136.98474 -280.193533)
		(end 137.171684 -280.243788)
		(width 0.0889)
		(layer "In4.Cu")
		(net "M_J_CPU1_SB_DQ<11>")
	)
	(arc
		(start 137.737596 -280.243788)
		(mid 137.919847 -280.193438)
		(end 138.103356 -280.238962)
		(width 0.0889)
		(layer "In4.Cu")
		(net "M_J_CPU1_SB_DQ<11>")
	)
	(arc
		(start 133.037834 -280.243788)
		(mid 133.224778 -280.193533)
		(end 133.411722 -280.243788)
		(width 0.0889)
		(layer "In4.Cu")
		(net "M_J_CPU1_SB_DQ<11>")
	)
	(arc
		(start 138.111738 -280.243788)
		(mid 138.394694 -280.319965)
		(end 138.67765 -280.243788)
		(width 0.0889)
		(layer "In4.Cu")
		(net "M_J_CPU1_SB_DQ<11>")
	)
	(arc
		(start 131.595114 -280.275538)
		(mid 131.850179 -280.318889)
		(end 132.09778 -280.243788)
		(width 0.0889)
		(layer "In4.Cu")
		(net "M_J_CPU1_SB_DQ<11>")
	)
	(arc
		(start 132.106162 -280.238962)
		(mid 132.28967 -280.193468)
		(end 132.471922 -280.243788)
		(width 0.0889)
		(layer "In4.Cu")
		(net "M_J_CPU1_SB_DQ<11>")
	)
	(arc
		(start 140.56614 -280.238962)
		(mid 140.749648 -280.193468)
		(end 140.9319 -280.243788)
		(width 0.0889)
		(layer "In4.Cu")
		(net "M_J_CPU1_SB_DQ<11>")
	)
	(arc
		(start 133.411722 -280.243788)
		(mid 133.694678 -280.319965)
		(end 133.977634 -280.243788)
		(width 0.0889)
		(layer "In4.Cu")
		(net "M_J_CPU1_SB_DQ<11>")
	)
	(arc
		(start 144.692624 -280.243788)
		(mid 144.972052 -280.319954)
		(end 145.25244 -280.247344)
		(width 0.0889)
		(layer "In4.Cu")
		(net "M_J_CPU1_SB_DQ<11>")
	)
	(arc
		(start 132.471922 -280.243788)
		(mid 132.754878 -280.319965)
		(end 133.037834 -280.243788)
		(width 0.0889)
		(layer "In4.Cu")
		(net "M_J_CPU1_SB_DQ<11>")
	)
	(arc
		(start 143.386048 -280.238962)
		(mid 143.569556 -280.193468)
		(end 143.751808 -280.243788)
		(width 0.0889)
		(layer "In4.Cu")
		(net "M_J_CPU1_SB_DQ<11>")
	)
	(arc
		(start 139.991846 -280.243788)
		(mid 140.274802 -280.319965)
		(end 140.557758 -280.243788)
		(width 0.0889)
		(layer "In4.Cu")
		(net "M_J_CPU1_SB_DQ<11>")
	)
	(arc
		(start 139.051792 -280.243788)
		(mid 139.334748 -280.319965)
		(end 139.617704 -280.243788)
		(width 0.0889)
		(layer "In4.Cu")
		(net "M_J_CPU1_SB_DQ<11>")
	)
	(arc
		(start 138.67765 -280.243788)
		(mid 138.859901 -280.193438)
		(end 139.04341 -280.238962)
		(width 0.0889)
		(layer "In4.Cu")
		(net "M_J_CPU1_SB_DQ<11>")
	)
	(arc
		(start 145.25244 -280.247344)
		(mid 145.344872 -280.207062)
		(end 145.444718 -280.192988)
		(width 0.0889)
		(layer "In4.Cu")
		(net "M_J_CPU1_SB_DQ<11>")
	)
	(arc
		(start 137.171684 -280.243788)
		(mid 137.45464 -280.319965)
		(end 137.737596 -280.243788)
		(width 0.0889)
		(layer "In4.Cu")
		(net "M_J_CPU1_SB_DQ<11>")
	)
	(segment
		(start 132.287772 -279.490424)
		(end 132.754878 -279.756362)
		(width 0.10668)
		(layer "F.Cu")
		(net "M_J_CPU1_SB_DQ<10>")
	)
	(segment
		(start 146.45132 -278.913844)
		(end 147.29587 -278.913844)
		(width 0.0889)
		(layer "In4.Cu")
		(net "M_J_CPU1_SB_DQ<10>")
	)
	(segment
		(start 144.20088 -279.422606)
		(end 144.220946 -279.434036)
		(width 0.0889)
		(layer "In4.Cu")
		(net "M_J_CPU1_SB_DQ<10>")
	)
	(segment
		(start 161.972244 -290.010342)
		(end 161.972244 -290.238942)
		(width 0.14478)
		(layer "In4.Cu")
		(net "M_J_CPU1_SB_DQ<10>")
	)
	(segment
		(start 158.83255 -287.065466)
		(end 159.027114 -287.065212)
		(width 0.14478)
		(layer "In4.Cu")
		(net "M_J_CPU1_SB_DQ<10>")
	)
	(segment
		(start 144.785334 -279.433782)
		(end 144.80413 -279.42286)
		(width 0.0889)
		(layer "In4.Cu")
		(net "M_J_CPU1_SB_DQ<10>")
	)
	(segment
		(start 152.963626 -281.424634)
		(end 153.142442 -281.60345)
		(width 0.14478)
		(layer "In4.Cu")
		(net "M_J_CPU1_SB_DQ<10>")
	)
	(segment
		(start 160.393126 -288.626042)
		(end 160.58769 -288.625788)
		(width 0.14478)
		(layer "In4.Cu")
		(net "M_J_CPU1_SB_DQ<10>")
	)
	(segment
		(start 155.905962 -283.94406)
		(end 156.084778 -284.122876)
		(width 0.14478)
		(layer "In4.Cu")
		(net "M_J_CPU1_SB_DQ<10>")
	)
	(segment
		(start 158.425642 -286.46374)
		(end 158.425642 -286.88665)
		(width 0.14478)
		(layer "In4.Cu")
		(net "M_J_CPU1_SB_DQ<10>")
	)
	(segment
		(start 153.743914 -281.782012)
		(end 153.743914 -282.204922)
		(width 0.14478)
		(layer "In4.Cu")
		(net "M_J_CPU1_SB_DQ<10>")
	)
	(segment
		(start 155.30449 -283.765498)
		(end 155.483306 -283.944314)
		(width 0.14478)
		(layer "In4.Cu")
		(net "M_J_CPU1_SB_DQ<10>")
	)
	(segment
		(start 184.222136 -291.260276)
		(end 184.515506 -291.553646)
		(width 0.14478)
		(layer "In4.Cu")
		(net "M_J_CPU1_SB_DQ<10>")
	)
	(segment
		(start 161.191956 -289.230054)
		(end 161.191956 -289.458654)
		(width 0.14478)
		(layer "In4.Cu")
		(net "M_J_CPU1_SB_DQ<10>")
	)
	(segment
		(start 151.40305 -279.864058)
		(end 151.581866 -280.042874)
		(width 0.14478)
		(layer "In4.Cu")
		(net "M_J_CPU1_SB_DQ<10>")
	)
	(segment
		(start 153.370534 -281.60345)
		(end 153.565098 -281.603196)
		(width 0.14478)
		(layer "In4.Cu")
		(net "M_J_CPU1_SB_DQ<10>")
	)
	(segment
		(start 161.726372 -290.713414)
		(end 161.887916 -290.874958)
		(width 0.14478)
		(layer "In4.Cu")
		(net "M_J_CPU1_SB_DQ<10>")
	)
	(segment
		(start 162.590988 -290.629086)
		(end 162.752532 -290.79063)
		(width 0.14478)
		(layer "In4.Cu")
		(net "M_J_CPU1_SB_DQ<10>")
	)
	(segment
		(start 157.645354 -286.106362)
		(end 157.82417 -286.285178)
		(width 0.14478)
		(layer "In4.Cu")
		(net "M_J_CPU1_SB_DQ<10>")
	)
	(segment
		(start 155.711398 -283.944314)
		(end 155.905962 -283.94406)
		(width 0.14478)
		(layer "In4.Cu")
		(net "M_J_CPU1_SB_DQ<10>")
	)
	(segment
		(start 154.93111 -283.164026)
		(end 155.125674 -283.163772)
		(width 0.14478)
		(layer "In4.Cu")
		(net "M_J_CPU1_SB_DQ<10>")
	)
	(segment
		(start 153.92273 -282.383738)
		(end 154.150822 -282.383738)
		(width 0.14478)
		(layer "In4.Cu")
		(net "M_J_CPU1_SB_DQ<10>")
	)
	(segment
		(start 163.142676 -291.409374)
		(end 163.371276 -291.409374)
		(width 0.14478)
		(layer "In4.Cu")
		(net "M_J_CPU1_SB_DQ<10>")
	)
	(segment
		(start 186.169808 -291.260276)
		(end 186.635136 -291.260276)
		(width 0.14478)
		(layer "In4.Cu")
		(net "M_J_CPU1_SB_DQ<10>")
	)
	(segment
		(start 164.863018 -291.810186)
		(end 165.114224 -291.810186)
		(width 0.14478)
		(layer "In4.Cu")
		(net "M_J_CPU1_SB_DQ<10>")
	)
	(segment
		(start 161.887916 -290.874958)
		(end 162.116516 -290.874958)
		(width 0.14478)
		(layer "In4.Cu")
		(net "M_J_CPU1_SB_DQ<10>")
	)
	(segment
		(start 135.753348 -279.428956)
		(end 135.76173 -279.433782)
		(width 0.0889)
		(layer "In4.Cu")
		(net "M_J_CPU1_SB_DQ<10>")
	)
	(segment
		(start 140.453364 -279.428956)
		(end 140.461746 -279.433782)
		(width 0.0889)
		(layer "In4.Cu")
		(net "M_J_CPU1_SB_DQ<10>")
	)
	(segment
		(start 182.097934 -291.260276)
		(end 184.222136 -291.260276)
		(width 0.14478)
		(layer "In4.Cu")
		(net "M_J_CPU1_SB_DQ<10>")
	)
	(segment
		(start 132.908802 -279.490932)
		(end 133.004814 -279.465532)
		(width 0.0889)
		(layer "In4.Cu")
		(net "M_J_CPU1_SB_DQ<10>")
	)
	(segment
		(start 156.865066 -285.326074)
		(end 157.043882 -285.50489)
		(width 0.14478)
		(layer "In4.Cu")
		(net "M_J_CPU1_SB_DQ<10>")
	)
	(segment
		(start 159.986218 -288.447226)
		(end 160.165034 -288.626042)
		(width 0.14478)
		(layer "In4.Cu")
		(net "M_J_CPU1_SB_DQ<10>")
	)
	(segment
		(start 186.635136 -291.260276)
		(end 187.060078 -291.685218)
		(width 0.14478)
		(layer "In4.Cu")
		(net "M_J_CPU1_SB_DQ<10>")
	)
	(segment
		(start 132.754878 -279.756362)
		(end 132.908802 -279.490932)
		(width 0.0889)
		(layer "In4.Cu")
		(net "M_J_CPU1_SB_DQ<10>")
	)
	(segment
		(start 160.946084 -289.933126)
		(end 161.107628 -290.09467)
		(width 0.14478)
		(layer "In4.Cu")
		(net "M_J_CPU1_SB_DQ<10>")
	)
	(segment
		(start 178.200558 -292.11016)
		(end 181.24805 -292.11016)
		(width 0.14478)
		(layer "In4.Cu")
		(net "M_J_CPU1_SB_DQ<10>")
	)
	(segment
		(start 159.20593 -287.666938)
		(end 159.384746 -287.845754)
		(width 0.14478)
		(layer "In4.Cu")
		(net "M_J_CPU1_SB_DQ<10>")
	)
	(segment
		(start 155.125674 -283.163772)
		(end 155.30449 -283.342588)
		(width 0.14478)
		(layer "In4.Cu")
		(net "M_J_CPU1_SB_DQ<10>")
	)
	(segment
		(start 162.752532 -290.79063)
		(end 162.752532 -291.01923)
		(width 0.14478)
		(layer "In4.Cu")
		(net "M_J_CPU1_SB_DQ<10>")
	)
	(segment
		(start 152.362154 -280.823162)
		(end 152.590246 -280.823162)
		(width 0.14478)
		(layer "In4.Cu")
		(net "M_J_CPU1_SB_DQ<10>")
	)
	(segment
		(start 165.114224 -291.810186)
		(end 165.414452 -292.110414)
		(width 0.14478)
		(layer "In4.Cu")
		(net "M_J_CPU1_SB_DQ<10>")
	)
	(segment
		(start 137.267696 -279.433782)
		(end 137.276078 -279.428956)
		(width 0.0889)
		(layer "In4.Cu")
		(net "M_J_CPU1_SB_DQ<10>")
	)
	(segment
		(start 155.483306 -283.944314)
		(end 155.711398 -283.944314)
		(width 0.14478)
		(layer "In4.Cu")
		(net "M_J_CPU1_SB_DQ<10>")
	)
	(segment
		(start 138.20775 -279.433782)
		(end 138.216132 -279.428956)
		(width 0.0889)
		(layer "In4.Cu")
		(net "M_J_CPU1_SB_DQ<10>")
	)
	(segment
		(start 184.515506 -291.553646)
		(end 184.77357 -291.553646)
		(width 0.14478)
		(layer "In4.Cu")
		(net "M_J_CPU1_SB_DQ<10>")
	)
	(segment
		(start 161.8107 -289.848798)
		(end 161.972244 -290.010342)
		(width 0.14478)
		(layer "In4.Cu")
		(net "M_J_CPU1_SB_DQ<10>")
	)
	(segment
		(start 157.043882 -285.50489)
		(end 157.271974 -285.50489)
		(width 0.14478)
		(layer "In4.Cu")
		(net "M_J_CPU1_SB_DQ<10>")
	)
	(segment
		(start 170.539918 -292.110414)
		(end 173.69409 -292.110414)
		(width 0.14478)
		(layer "In4.Cu")
		(net "M_J_CPU1_SB_DQ<10>")
	)
	(segment
		(start 154.703018 -283.164026)
		(end 154.93111 -283.164026)
		(width 0.14478)
		(layer "In4.Cu")
		(net "M_J_CPU1_SB_DQ<10>")
	)
	(segment
		(start 185.325004 -291.260276)
		(end 185.618374 -291.553646)
		(width 0.14478)
		(layer "In4.Cu")
		(net "M_J_CPU1_SB_DQ<10>")
	)
	(segment
		(start 161.726372 -290.484814)
		(end 161.726372 -290.713414)
		(width 0.14478)
		(layer "In4.Cu")
		(net "M_J_CPU1_SB_DQ<10>")
	)
	(segment
		(start 152.183338 -280.221436)
		(end 152.183338 -280.644346)
		(width 0.14478)
		(layer "In4.Cu")
		(net "M_J_CPU1_SB_DQ<10>")
	)
	(segment
		(start 152.78481 -280.822908)
		(end 152.963626 -281.001724)
		(width 0.14478)
		(layer "In4.Cu")
		(net "M_J_CPU1_SB_DQ<10>")
	)
	(segment
		(start 165.414452 -292.110414)
		(end 166.150036 -292.110414)
		(width 0.14478)
		(layer "In4.Cu")
		(net "M_J_CPU1_SB_DQ<10>")
	)
	(segment
		(start 184.77357 -291.553646)
		(end 185.06694 -291.260276)
		(width 0.14478)
		(layer "In4.Cu")
		(net "M_J_CPU1_SB_DQ<10>")
	)
	(segment
		(start 162.752532 -291.01923)
		(end 162.50666 -291.265102)
		(width 0.14478)
		(layer "In4.Cu")
		(net "M_J_CPU1_SB_DQ<10>")
	)
	(segment
		(start 169.68978 -291.260276)
		(end 170.539918 -292.110414)
		(width 0.14478)
		(layer "In4.Cu")
		(net "M_J_CPU1_SB_DQ<10>")
	)
	(segment
		(start 158.425642 -286.88665)
		(end 158.604458 -287.065466)
		(width 0.14478)
		(layer "In4.Cu")
		(net "M_J_CPU1_SB_DQ<10>")
	)
	(segment
		(start 144.220946 -279.434036)
		(end 144.242536 -279.446482)
		(width 0.0889)
		(layer "In4.Cu")
		(net "M_J_CPU1_SB_DQ<10>")
	)
	(segment
		(start 153.743914 -282.204922)
		(end 153.92273 -282.383738)
		(width 0.14478)
		(layer "In4.Cu")
		(net "M_J_CPU1_SB_DQ<10>")
	)
	(segment
		(start 160.58769 -288.625788)
		(end 161.191956 -289.230054)
		(width 0.14478)
		(layer "In4.Cu")
		(net "M_J_CPU1_SB_DQ<10>")
	)
	(segment
		(start 151.581866 -280.042874)
		(end 151.809958 -280.042874)
		(width 0.14478)
		(layer "In4.Cu")
		(net "M_J_CPU1_SB_DQ<10>")
	)
	(segment
		(start 154.524202 -282.5623)
		(end 154.524202 -282.98521)
		(width 0.14478)
		(layer "In4.Cu")
		(net "M_J_CPU1_SB_DQ<10>")
	)
	(segment
		(start 152.590246 -280.823162)
		(end 152.78481 -280.822908)
		(width 0.14478)
		(layer "In4.Cu")
		(net "M_J_CPU1_SB_DQ<10>")
	)
	(segment
		(start 151.809958 -280.042874)
		(end 152.004522 -280.04262)
		(width 0.14478)
		(layer "In4.Cu")
		(net "M_J_CPU1_SB_DQ<10>")
	)
	(segment
		(start 185.876438 -291.553646)
		(end 186.169808 -291.260276)
		(width 0.14478)
		(layer "In4.Cu")
		(net "M_J_CPU1_SB_DQ<10>")
	)
	(segment
		(start 156.491686 -284.724602)
		(end 156.68625 -284.724348)
		(width 0.14478)
		(layer "In4.Cu")
		(net "M_J_CPU1_SB_DQ<10>")
	)
	(segment
		(start 145.92935 -279.379426)
		(end 146.35988 -278.95169)
		(width 0.0889)
		(layer "In4.Cu")
		(net "M_J_CPU1_SB_DQ<10>")
	)
	(segment
		(start 147.448016 -279.06599)
		(end 147.922488 -279.06599)
		(width 0.0889)
		(layer "In4.Cu")
		(net "M_J_CPU1_SB_DQ<10>")
	)
	(segment
		(start 154.524202 -282.98521)
		(end 154.703018 -283.164026)
		(width 0.14478)
		(layer "In4.Cu")
		(net "M_J_CPU1_SB_DQ<10>")
	)
	(segment
		(start 162.116516 -290.874958)
		(end 162.362388 -290.629086)
		(width 0.14478)
		(layer "In4.Cu")
		(net "M_J_CPU1_SB_DQ<10>")
	)
	(segment
		(start 133.507734 -279.433782)
		(end 133.516116 -279.428956)
		(width 0.0889)
		(layer "In4.Cu")
		(net "M_J_CPU1_SB_DQ<10>")
	)
	(segment
		(start 161.972244 -290.238942)
		(end 161.726372 -290.484814)
		(width 0.14478)
		(layer "In4.Cu")
		(net "M_J_CPU1_SB_DQ<10>")
	)
	(segment
		(start 164.072316 -292.110414)
		(end 164.56279 -292.110414)
		(width 0.14478)
		(layer "In4.Cu")
		(net "M_J_CPU1_SB_DQ<10>")
	)
	(segment
		(start 156.68625 -284.724348)
		(end 156.865066 -284.903164)
		(width 0.14478)
		(layer "In4.Cu")
		(net "M_J_CPU1_SB_DQ<10>")
	)
	(segment
		(start 161.336228 -290.09467)
		(end 161.5821 -289.848798)
		(width 0.14478)
		(layer "In4.Cu")
		(net "M_J_CPU1_SB_DQ<10>")
	)
	(segment
		(start 156.865066 -284.903164)
		(end 156.865066 -285.326074)
		(width 0.14478)
		(layer "In4.Cu")
		(net "M_J_CPU1_SB_DQ<10>")
	)
	(segment
		(start 159.986218 -288.024316)
		(end 159.986218 -288.447226)
		(width 0.14478)
		(layer "In4.Cu")
		(net "M_J_CPU1_SB_DQ<10>")
	)
	(segment
		(start 166.150036 -292.110414)
		(end 167.000174 -291.260276)
		(width 0.14478)
		(layer "In4.Cu")
		(net "M_J_CPU1_SB_DQ<10>")
	)
	(segment
		(start 153.565098 -281.603196)
		(end 153.743914 -281.782012)
		(width 0.14478)
		(layer "In4.Cu")
		(net "M_J_CPU1_SB_DQ<10>")
	)
	(segment
		(start 158.052262 -286.285178)
		(end 158.246826 -286.284924)
		(width 0.14478)
		(layer "In4.Cu")
		(net "M_J_CPU1_SB_DQ<10>")
	)
	(segment
		(start 161.107628 -290.09467)
		(end 161.336228 -290.09467)
		(width 0.14478)
		(layer "In4.Cu")
		(net "M_J_CPU1_SB_DQ<10>")
	)
	(segment
		(start 155.30449 -283.342588)
		(end 155.30449 -283.765498)
		(width 0.14478)
		(layer "In4.Cu")
		(net "M_J_CPU1_SB_DQ<10>")
	)
	(segment
		(start 181.24805 -292.11016)
		(end 182.097934 -291.260276)
		(width 0.14478)
		(layer "In4.Cu")
		(net "M_J_CPU1_SB_DQ<10>")
	)
	(segment
		(start 159.20593 -287.244028)
		(end 159.20593 -287.666938)
		(width 0.14478)
		(layer "In4.Cu")
		(net "M_J_CPU1_SB_DQ<10>")
	)
	(segment
		(start 164.56279 -292.110414)
		(end 164.863018 -291.810186)
		(width 0.14478)
		(layer "In4.Cu")
		(net "M_J_CPU1_SB_DQ<10>")
	)
	(segment
		(start 163.371276 -291.409374)
		(end 164.072316 -292.110414)
		(width 0.14478)
		(layer "In4.Cu")
		(net "M_J_CPU1_SB_DQ<10>")
	)
	(segment
		(start 159.384746 -287.845754)
		(end 159.612838 -287.845754)
		(width 0.14478)
		(layer "In4.Cu")
		(net "M_J_CPU1_SB_DQ<10>")
	)
	(segment
		(start 162.896804 -291.655246)
		(end 163.142676 -291.409374)
		(width 0.14478)
		(layer "In4.Cu")
		(net "M_J_CPU1_SB_DQ<10>")
	)
	(segment
		(start 159.807402 -287.8455)
		(end 159.986218 -288.024316)
		(width 0.14478)
		(layer "In4.Cu")
		(net "M_J_CPU1_SB_DQ<10>")
	)
	(segment
		(start 177.350674 -291.260276)
		(end 178.200558 -292.11016)
		(width 0.14478)
		(layer "In4.Cu")
		(net "M_J_CPU1_SB_DQ<10>")
	)
	(segment
		(start 154.345386 -282.383484)
		(end 154.524202 -282.5623)
		(width 0.14478)
		(layer "In4.Cu")
		(net "M_J_CPU1_SB_DQ<10>")
	)
	(segment
		(start 167.000174 -291.260276)
		(end 169.68978 -291.260276)
		(width 0.14478)
		(layer "In4.Cu")
		(net "M_J_CPU1_SB_DQ<10>")
	)
	(segment
		(start 185.06694 -291.260276)
		(end 185.325004 -291.260276)
		(width 0.14478)
		(layer "In4.Cu")
		(net "M_J_CPU1_SB_DQ<10>")
	)
	(segment
		(start 152.183338 -280.644346)
		(end 152.362154 -280.823162)
		(width 0.14478)
		(layer "In4.Cu")
		(net "M_J_CPU1_SB_DQ<10>")
	)
	(segment
		(start 156.084778 -284.545786)
		(end 156.263594 -284.724602)
		(width 0.14478)
		(layer "In4.Cu")
		(net "M_J_CPU1_SB_DQ<10>")
	)
	(segment
		(start 156.263594 -284.724602)
		(end 156.491686 -284.724602)
		(width 0.14478)
		(layer "In4.Cu")
		(net "M_J_CPU1_SB_DQ<10>")
	)
	(segment
		(start 173.69409 -292.110414)
		(end 174.544228 -291.260276)
		(width 0.14478)
		(layer "In4.Cu")
		(net "M_J_CPU1_SB_DQ<10>")
	)
	(segment
		(start 147.29587 -278.913844)
		(end 147.448016 -279.06599)
		(width 0.0889)
		(layer "In4.Cu")
		(net "M_J_CPU1_SB_DQ<10>")
	)
	(segment
		(start 151.40305 -279.441148)
		(end 151.40305 -279.864058)
		(width 0.14478)
		(layer "In4.Cu")
		(net "M_J_CPU1_SB_DQ<10>")
	)
	(segment
		(start 141.967712 -279.433782)
		(end 141.976094 -279.428956)
		(width 0.0889)
		(layer "In4.Cu")
		(net "M_J_CPU1_SB_DQ<10>")
	)
	(segment
		(start 162.362388 -290.629086)
		(end 162.590988 -290.629086)
		(width 0.14478)
		(layer "In4.Cu")
		(net "M_J_CPU1_SB_DQ<10>")
	)
	(segment
		(start 159.027114 -287.065212)
		(end 159.20593 -287.244028)
		(width 0.14478)
		(layer "In4.Cu")
		(net "M_J_CPU1_SB_DQ<10>")
	)
	(segment
		(start 159.612838 -287.845754)
		(end 159.807402 -287.8455)
		(width 0.14478)
		(layer "In4.Cu")
		(net "M_J_CPU1_SB_DQ<10>")
	)
	(segment
		(start 156.084778 -284.122876)
		(end 156.084778 -284.545786)
		(width 0.14478)
		(layer "In4.Cu")
		(net "M_J_CPU1_SB_DQ<10>")
	)
	(segment
		(start 154.150822 -282.383738)
		(end 154.345386 -282.383484)
		(width 0.14478)
		(layer "In4.Cu")
		(net "M_J_CPU1_SB_DQ<10>")
	)
	(segment
		(start 157.466538 -285.504636)
		(end 157.645354 -285.683452)
		(width 0.14478)
		(layer "In4.Cu")
		(net "M_J_CPU1_SB_DQ<10>")
	)
	(segment
		(start 160.946084 -289.704526)
		(end 160.946084 -289.933126)
		(width 0.14478)
		(layer "In4.Cu")
		(net "M_J_CPU1_SB_DQ<10>")
	)
	(segment
		(start 160.165034 -288.626042)
		(end 160.393126 -288.626042)
		(width 0.14478)
		(layer "In4.Cu")
		(net "M_J_CPU1_SB_DQ<10>")
	)
	(segment
		(start 162.50666 -291.493702)
		(end 162.668204 -291.655246)
		(width 0.14478)
		(layer "In4.Cu")
		(net "M_J_CPU1_SB_DQ<10>")
	)
	(segment
		(start 151.027892 -279.06599)
		(end 151.40305 -279.441148)
		(width 0.14478)
		(layer "In4.Cu")
		(net "M_J_CPU1_SB_DQ<10>")
	)
	(segment
		(start 157.271974 -285.50489)
		(end 157.466538 -285.504636)
		(width 0.14478)
		(layer "In4.Cu")
		(net "M_J_CPU1_SB_DQ<10>")
	)
	(segment
		(start 136.693402 -279.428956)
		(end 136.701784 -279.433782)
		(width 0.0889)
		(layer "In4.Cu")
		(net "M_J_CPU1_SB_DQ<10>")
	)
	(segment
		(start 147.922488 -279.06599)
		(end 151.027892 -279.06599)
		(width 0.14478)
		(layer "In4.Cu")
		(net "M_J_CPU1_SB_DQ<10>")
	)
	(segment
		(start 158.246826 -286.284924)
		(end 158.425642 -286.46374)
		(width 0.14478)
		(layer "In4.Cu")
		(net "M_J_CPU1_SB_DQ<10>")
	)
	(segment
		(start 162.668204 -291.655246)
		(end 162.896804 -291.655246)
		(width 0.14478)
		(layer "In4.Cu")
		(net "M_J_CPU1_SB_DQ<10>")
	)
	(segment
		(start 185.618374 -291.553646)
		(end 185.876438 -291.553646)
		(width 0.14478)
		(layer "In4.Cu")
		(net "M_J_CPU1_SB_DQ<10>")
	)
	(segment
		(start 174.544228 -291.260276)
		(end 177.350674 -291.260276)
		(width 0.14478)
		(layer "In4.Cu")
		(net "M_J_CPU1_SB_DQ<10>")
	)
	(segment
		(start 152.004522 -280.04262)
		(end 152.183338 -280.221436)
		(width 0.14478)
		(layer "In4.Cu")
		(net "M_J_CPU1_SB_DQ<10>")
	)
	(segment
		(start 162.50666 -291.265102)
		(end 162.50666 -291.493702)
		(width 0.14478)
		(layer "In4.Cu")
		(net "M_J_CPU1_SB_DQ<10>")
	)
	(segment
		(start 158.604458 -287.065466)
		(end 158.83255 -287.065466)
		(width 0.14478)
		(layer "In4.Cu")
		(net "M_J_CPU1_SB_DQ<10>")
	)
	(segment
		(start 157.645354 -285.683452)
		(end 157.645354 -286.106362)
		(width 0.14478)
		(layer "In4.Cu")
		(net "M_J_CPU1_SB_DQ<10>")
	)
	(segment
		(start 153.142442 -281.60345)
		(end 153.370534 -281.60345)
		(width 0.14478)
		(layer "In4.Cu")
		(net "M_J_CPU1_SB_DQ<10>")
	)
	(segment
		(start 157.82417 -286.285178)
		(end 158.052262 -286.285178)
		(width 0.14478)
		(layer "In4.Cu")
		(net "M_J_CPU1_SB_DQ<10>")
	)
	(segment
		(start 152.963626 -281.001724)
		(end 152.963626 -281.424634)
		(width 0.14478)
		(layer "In4.Cu")
		(net "M_J_CPU1_SB_DQ<10>")
	)
	(segment
		(start 161.191956 -289.458654)
		(end 160.946084 -289.704526)
		(width 0.14478)
		(layer "In4.Cu")
		(net "M_J_CPU1_SB_DQ<10>")
	)
	(segment
		(start 161.5821 -289.848798)
		(end 161.8107 -289.848798)
		(width 0.14478)
		(layer "In4.Cu")
		(net "M_J_CPU1_SB_DQ<10>")
	)
	(segment
		(start 141.393418 -279.428956)
		(end 141.4018 -279.433782)
		(width 0.0889)
		(layer "In4.Cu")
		(net "M_J_CPU1_SB_DQ<10>")
	)
	(arc
		(start 141.027658 -279.433782)
		(mid 141.209909 -279.383432)
		(end 141.393418 -279.428956)
		(width 0.0889)
		(layer "In4.Cu")
		(net "M_J_CPU1_SB_DQ<10>")
	)
	(arc
		(start 137.276078 -279.428956)
		(mid 137.459586 -279.383462)
		(end 137.641838 -279.433782)
		(width 0.0889)
		(layer "In4.Cu")
		(net "M_J_CPU1_SB_DQ<10>")
	)
	(arc
		(start 145.44167 -279.514046)
		(mid 145.643464 -279.498944)
		(end 145.83791 -279.442926)
		(width 0.0889)
		(layer "In4.Cu")
		(net "M_J_CPU1_SB_DQ<10>")
	)
	(arc
		(start 137.641838 -279.433782)
		(mid 137.924794 -279.509959)
		(end 138.20775 -279.433782)
		(width 0.0889)
		(layer "In4.Cu")
		(net "M_J_CPU1_SB_DQ<10>")
	)
	(arc
		(start 133.004814 -279.465532)
		(mid 133.260022 -279.509009)
		(end 133.507734 -279.433782)
		(width 0.0889)
		(layer "In4.Cu")
		(net "M_J_CPU1_SB_DQ<10>")
	)
	(arc
		(start 142.341854 -279.433782)
		(mid 142.62481 -279.509959)
		(end 142.907766 -279.433782)
		(width 0.0889)
		(layer "In4.Cu")
		(net "M_J_CPU1_SB_DQ<10>")
	)
	(arc
		(start 138.216132 -279.428956)
		(mid 138.39964 -279.383462)
		(end 138.581892 -279.433782)
		(width 0.0889)
		(layer "In4.Cu")
		(net "M_J_CPU1_SB_DQ<10>")
	)
	(arc
		(start 144.242536 -279.446482)
		(mid 144.515565 -279.509801)
		(end 144.785334 -279.433782)
		(width 0.0889)
		(layer "In4.Cu")
		(net "M_J_CPU1_SB_DQ<10>")
	)
	(arc
		(start 138.581892 -279.433782)
		(mid 138.864848 -279.509959)
		(end 139.147804 -279.433782)
		(width 0.0889)
		(layer "In4.Cu")
		(net "M_J_CPU1_SB_DQ<10>")
	)
	(arc
		(start 133.516116 -279.428956)
		(mid 133.699624 -279.383462)
		(end 133.881876 -279.433782)
		(width 0.0889)
		(layer "In4.Cu")
		(net "M_J_CPU1_SB_DQ<10>")
	)
	(arc
		(start 140.087604 -279.433782)
		(mid 140.269855 -279.383432)
		(end 140.453364 -279.428956)
		(width 0.0889)
		(layer "In4.Cu")
		(net "M_J_CPU1_SB_DQ<10>")
	)
	(arc
		(start 139.521692 -279.433782)
		(mid 139.804648 -279.509959)
		(end 140.087604 -279.433782)
		(width 0.0889)
		(layer "In4.Cu")
		(net "M_J_CPU1_SB_DQ<10>")
	)
	(arc
		(start 139.147804 -279.433782)
		(mid 139.334748 -279.383527)
		(end 139.521692 -279.433782)
		(width 0.0889)
		(layer "In4.Cu")
		(net "M_J_CPU1_SB_DQ<10>")
	)
	(arc
		(start 146.35988 -278.95169)
		(mid 146.401833 -278.923658)
		(end 146.45132 -278.913844)
		(width 0.0889)
		(layer "In4.Cu")
		(net "M_J_CPU1_SB_DQ<10>")
	)
	(arc
		(start 134.447788 -279.433782)
		(mid 134.634732 -279.383527)
		(end 134.821676 -279.433782)
		(width 0.0889)
		(layer "In4.Cu")
		(net "M_J_CPU1_SB_DQ<10>")
	)
	(arc
		(start 134.821676 -279.433782)
		(mid 135.104632 -279.509959)
		(end 135.387588 -279.433782)
		(width 0.0889)
		(layer "In4.Cu")
		(net "M_J_CPU1_SB_DQ<10>")
	)
	(arc
		(start 140.461746 -279.433782)
		(mid 140.744702 -279.509959)
		(end 141.027658 -279.433782)
		(width 0.0889)
		(layer "In4.Cu")
		(net "M_J_CPU1_SB_DQ<10>")
	)
	(arc
		(start 135.387588 -279.433782)
		(mid 135.569839 -279.383432)
		(end 135.753348 -279.428956)
		(width 0.0889)
		(layer "In4.Cu")
		(net "M_J_CPU1_SB_DQ<10>")
	)
	(arc
		(start 143.281654 -279.433782)
		(mid 143.56461 -279.509959)
		(end 143.847566 -279.433782)
		(width 0.0889)
		(layer "In4.Cu")
		(net "M_J_CPU1_SB_DQ<10>")
	)
	(arc
		(start 143.847566 -279.433782)
		(mid 144.022805 -279.383711)
		(end 144.20088 -279.422606)
		(width 0.0889)
		(layer "In4.Cu")
		(net "M_J_CPU1_SB_DQ<10>")
	)
	(arc
		(start 144.80413 -279.42286)
		(mid 144.983701 -279.383043)
		(end 145.160492 -279.433782)
		(width 0.0889)
		(layer "In4.Cu")
		(net "M_J_CPU1_SB_DQ<10>")
	)
	(arc
		(start 141.976094 -279.428956)
		(mid 142.159602 -279.383462)
		(end 142.341854 -279.433782)
		(width 0.0889)
		(layer "In4.Cu")
		(net "M_J_CPU1_SB_DQ<10>")
	)
	(arc
		(start 141.4018 -279.433782)
		(mid 141.684756 -279.509959)
		(end 141.967712 -279.433782)
		(width 0.0889)
		(layer "In4.Cu")
		(net "M_J_CPU1_SB_DQ<10>")
	)
	(arc
		(start 133.881876 -279.433782)
		(mid 134.164832 -279.509959)
		(end 134.447788 -279.433782)
		(width 0.0889)
		(layer "In4.Cu")
		(net "M_J_CPU1_SB_DQ<10>")
	)
	(arc
		(start 136.701784 -279.433782)
		(mid 136.98474 -279.509959)
		(end 137.267696 -279.433782)
		(width 0.0889)
		(layer "In4.Cu")
		(net "M_J_CPU1_SB_DQ<10>")
	)
	(arc
		(start 142.907766 -279.433782)
		(mid 143.09471 -279.383527)
		(end 143.281654 -279.433782)
		(width 0.0889)
		(layer "In4.Cu")
		(net "M_J_CPU1_SB_DQ<10>")
	)
	(arc
		(start 135.76173 -279.433782)
		(mid 136.044686 -279.509959)
		(end 136.327642 -279.433782)
		(width 0.0889)
		(layer "In4.Cu")
		(net "M_J_CPU1_SB_DQ<10>")
	)
	(arc
		(start 145.83791 -279.442926)
		(mid 145.887189 -279.416304)
		(end 145.92935 -279.379426)
		(width 0.0889)
		(layer "In4.Cu")
		(net "M_J_CPU1_SB_DQ<10>")
	)
	(arc
		(start 145.160492 -279.433782)
		(mid 145.296037 -279.49158)
		(end 145.44167 -279.514046)
		(width 0.0889)
		(layer "In4.Cu")
		(net "M_J_CPU1_SB_DQ<10>")
	)
	(arc
		(start 136.327642 -279.433782)
		(mid 136.509893 -279.383432)
		(end 136.693402 -279.428956)
		(width 0.0889)
		(layer "In4.Cu")
		(net "M_J_CPU1_SB_DQ<10>")
	)
	(segment
		(start 132.757926 -273.820382)
		(end 133.224778 -274.08632)
		(width 0.10668)
		(layer "F.Cu")
		(net "M_J_CPU1_SB_DQ<0>")
	)
	(segment
		(start 133.070854 -274.35175)
		(end 133.093206 -274.435062)
		(width 0.0889)
		(layer "In4.Cu")
		(net "M_J_CPU1_SB_DQ<0>")
	)
	(segment
		(start 133.224778 -274.08632)
		(end 133.070854 -274.35175)
		(width 0.0889)
		(layer "In4.Cu")
		(net "M_J_CPU1_SB_DQ<0>")
	)
	(segment
		(start 135.857742 -274.4089)
		(end 135.866124 -274.413726)
		(width 0.0889)
		(layer "In4.Cu")
		(net "M_J_CPU1_SB_DQ<0>")
	)
	(segment
		(start 188.931804 -281.848306)
		(end 189.16015 -281.848306)
		(width 0.14478)
		(layer "In4.Cu")
		(net "M_J_CPU1_SB_DQ<0>")
	)
	(segment
		(start 177.66157 -281.060398)
		(end 178.511454 -281.910282)
		(width 0.14478)
		(layer "In4.Cu")
		(net "M_J_CPU1_SB_DQ<0>")
	)
	(segment
		(start 145.444718 -274.4597)
		(end 145.444972 -274.459954)
		(width 0.0889)
		(layer "In4.Cu")
		(net "M_J_CPU1_SB_DQ<0>")
	)
	(segment
		(start 188.77026 -281.221942)
		(end 188.77026 -281.686762)
		(width 0.14478)
		(layer "In4.Cu")
		(net "M_J_CPU1_SB_DQ<0>")
	)
	(segment
		(start 163.78555 -281.495246)
		(end 164.200586 -281.910282)
		(width 0.14478)
		(layer "In4.Cu")
		(net "M_J_CPU1_SB_DQ<0>")
	)
	(segment
		(start 178.511454 -281.910282)
		(end 180.860954 -281.910282)
		(width 0.14478)
		(layer "In4.Cu")
		(net "M_J_CPU1_SB_DQ<0>")
	)
	(segment
		(start 138.103356 -274.413726)
		(end 138.111738 -274.4089)
		(width 0.0889)
		(layer "In4.Cu")
		(net "M_J_CPU1_SB_DQ<0>")
	)
	(segment
		(start 180.860954 -281.910282)
		(end 181.710838 -281.060398)
		(width 0.14478)
		(layer "In4.Cu")
		(net "M_J_CPU1_SB_DQ<0>")
	)
	(segment
		(start 164.200586 -281.910282)
		(end 165.629844 -281.910282)
		(width 0.14478)
		(layer "In4.Cu")
		(net "M_J_CPU1_SB_DQ<0>")
	)
	(segment
		(start 144.316196 -274.408646)
		(end 144.334484 -274.41906)
		(width 0.0889)
		(layer "In4.Cu")
		(net "M_J_CPU1_SB_DQ<0>")
	)
	(segment
		(start 145.706084 -274.405598)
		(end 146.717258 -273.394424)
		(width 0.0889)
		(layer "In4.Cu")
		(net "M_J_CPU1_SB_DQ<0>")
	)
	(segment
		(start 145.444972 -274.459954)
		(end 145.589498 -274.459954)
		(width 0.0889)
		(layer "In4.Cu")
		(net "M_J_CPU1_SB_DQ<0>")
	)
	(segment
		(start 143.377666 -274.4089)
		(end 143.386048 -274.413726)
		(width 0.0889)
		(layer "In4.Cu")
		(net "M_J_CPU1_SB_DQ<0>")
	)
	(segment
		(start 188.608716 -281.060398)
		(end 188.77026 -281.221942)
		(width 0.14478)
		(layer "In4.Cu")
		(net "M_J_CPU1_SB_DQ<0>")
	)
	(segment
		(start 145.589498 -274.459954)
		(end 145.706084 -274.405598)
		(width 0.0889)
		(layer "In4.Cu")
		(net "M_J_CPU1_SB_DQ<0>")
	)
	(segment
		(start 163.78555 -280.936954)
		(end 163.78555 -281.495246)
		(width 0.14478)
		(layer "In4.Cu")
		(net "M_J_CPU1_SB_DQ<0>")
	)
	(segment
		(start 174.636938 -281.060398)
		(end 177.66157 -281.060398)
		(width 0.14478)
		(layer "In4.Cu")
		(net "M_J_CPU1_SB_DQ<0>")
	)
	(segment
		(start 181.710838 -281.060398)
		(end 188.608716 -281.060398)
		(width 0.14478)
		(layer "In4.Cu")
		(net "M_J_CPU1_SB_DQ<0>")
	)
	(segment
		(start 189.483238 -281.060398)
		(end 190.735204 -281.060398)
		(width 0.14478)
		(layer "In4.Cu")
		(net "M_J_CPU1_SB_DQ<0>")
	)
	(segment
		(start 147.623276 -272.939764)
		(end 148.047964 -272.939764)
		(width 0.0889)
		(layer "In4.Cu")
		(net "M_J_CPU1_SB_DQ<0>")
	)
	(segment
		(start 189.321694 -281.221942)
		(end 189.483238 -281.060398)
		(width 0.14478)
		(layer "In4.Cu")
		(net "M_J_CPU1_SB_DQ<0>")
	)
	(segment
		(start 161.026094 -278.177498)
		(end 163.78555 -280.936954)
		(width 0.14478)
		(layer "In4.Cu")
		(net "M_J_CPU1_SB_DQ<0>")
	)
	(segment
		(start 189.16015 -281.848306)
		(end 189.321694 -281.686762)
		(width 0.14478)
		(layer "In4.Cu")
		(net "M_J_CPU1_SB_DQ<0>")
	)
	(segment
		(start 144.294606 -274.3962)
		(end 144.316196 -274.408646)
		(width 0.0889)
		(layer "In4.Cu")
		(net "M_J_CPU1_SB_DQ<0>")
	)
	(segment
		(start 147.168616 -273.394424)
		(end 147.623276 -272.939764)
		(width 0.0889)
		(layer "In4.Cu")
		(net "M_J_CPU1_SB_DQ<0>")
	)
	(segment
		(start 167.681656 -281.060398)
		(end 170.117516 -281.060398)
		(width 0.14478)
		(layer "In4.Cu")
		(net "M_J_CPU1_SB_DQ<0>")
	)
	(segment
		(start 139.04341 -274.413726)
		(end 139.051792 -274.4089)
		(width 0.0889)
		(layer "In4.Cu")
		(net "M_J_CPU1_SB_DQ<0>")
	)
	(segment
		(start 165.629844 -281.910282)
		(end 167.681656 -281.060398)
		(width 0.14478)
		(layer "In4.Cu")
		(net "M_J_CPU1_SB_DQ<0>")
	)
	(segment
		(start 188.77026 -281.686762)
		(end 188.931804 -281.848306)
		(width 0.14478)
		(layer "In4.Cu")
		(net "M_J_CPU1_SB_DQ<0>")
	)
	(segment
		(start 173.787054 -281.910282)
		(end 174.636938 -281.060398)
		(width 0.14478)
		(layer "In4.Cu")
		(net "M_J_CPU1_SB_DQ<0>")
	)
	(segment
		(start 134.917688 -274.4089)
		(end 134.92607 -274.413726)
		(width 0.0889)
		(layer "In4.Cu")
		(net "M_J_CPU1_SB_DQ<0>")
	)
	(segment
		(start 142.803372 -274.413726)
		(end 142.811754 -274.4089)
		(width 0.0889)
		(layer "In4.Cu")
		(net "M_J_CPU1_SB_DQ<0>")
	)
	(segment
		(start 144.689322 -274.4089)
		(end 144.71269 -274.395184)
		(width 0.0889)
		(layer "In4.Cu")
		(net "M_J_CPU1_SB_DQ<0>")
	)
	(segment
		(start 134.343394 -274.413726)
		(end 134.351776 -274.4089)
		(width 0.0889)
		(layer "In4.Cu")
		(net "M_J_CPU1_SB_DQ<0>")
	)
	(segment
		(start 148.047964 -272.939764)
		(end 154.829256 -272.939764)
		(width 0.14478)
		(layer "In4.Cu")
		(net "M_J_CPU1_SB_DQ<0>")
	)
	(segment
		(start 160.06699 -278.177498)
		(end 161.026094 -278.177498)
		(width 0.14478)
		(layer "In4.Cu")
		(net "M_J_CPU1_SB_DQ<0>")
	)
	(segment
		(start 139.617704 -274.4089)
		(end 139.626086 -274.413726)
		(width 0.0889)
		(layer "In4.Cu")
		(net "M_J_CPU1_SB_DQ<0>")
	)
	(segment
		(start 189.321694 -281.686762)
		(end 189.321694 -281.221942)
		(width 0.14478)
		(layer "In4.Cu")
		(net "M_J_CPU1_SB_DQ<0>")
	)
	(segment
		(start 146.717258 -273.394424)
		(end 147.168616 -273.394424)
		(width 0.0889)
		(layer "In4.Cu")
		(net "M_J_CPU1_SB_DQ<0>")
	)
	(segment
		(start 140.557758 -274.4089)
		(end 140.56614 -274.413726)
		(width 0.0889)
		(layer "In4.Cu")
		(net "M_J_CPU1_SB_DQ<0>")
	)
	(segment
		(start 190.735204 -281.060398)
		(end 191.160146 -281.48534)
		(width 0.14478)
		(layer "In4.Cu")
		(net "M_J_CPU1_SB_DQ<0>")
	)
	(segment
		(start 154.829256 -272.939764)
		(end 160.06699 -278.177498)
		(width 0.14478)
		(layer "In4.Cu")
		(net "M_J_CPU1_SB_DQ<0>")
	)
	(segment
		(start 170.117516 -281.060398)
		(end 170.9674 -281.910282)
		(width 0.14478)
		(layer "In4.Cu")
		(net "M_J_CPU1_SB_DQ<0>")
	)
	(segment
		(start 170.9674 -281.910282)
		(end 173.787054 -281.910282)
		(width 0.14478)
		(layer "In4.Cu")
		(net "M_J_CPU1_SB_DQ<0>")
	)
	(arc
		(start 133.977634 -274.4089)
		(mid 134.159885 -274.45925)
		(end 134.343394 -274.413726)
		(width 0.0889)
		(layer "In4.Cu")
		(net "M_J_CPU1_SB_DQ<0>")
	)
	(arc
		(start 134.351776 -274.4089)
		(mid 134.634732 -274.332723)
		(end 134.917688 -274.4089)
		(width 0.0889)
		(layer "In4.Cu")
		(net "M_J_CPU1_SB_DQ<0>")
	)
	(arc
		(start 136.231884 -274.4089)
		(mid 136.51484 -274.332723)
		(end 136.797796 -274.4089)
		(width 0.0889)
		(layer "In4.Cu")
		(net "M_J_CPU1_SB_DQ<0>")
	)
	(arc
		(start 139.991846 -274.4089)
		(mid 140.274802 -274.332723)
		(end 140.557758 -274.4089)
		(width 0.0889)
		(layer "In4.Cu")
		(net "M_J_CPU1_SB_DQ<0>")
	)
	(arc
		(start 138.67765 -274.4089)
		(mid 138.859901 -274.45925)
		(end 139.04341 -274.413726)
		(width 0.0889)
		(layer "In4.Cu")
		(net "M_J_CPU1_SB_DQ<0>")
	)
	(arc
		(start 145.256504 -274.4089)
		(mid 145.347239 -274.446784)
		(end 145.444718 -274.4597)
		(width 0.0889)
		(layer "In4.Cu")
		(net "M_J_CPU1_SB_DQ<0>")
	)
	(arc
		(start 140.56614 -274.413726)
		(mid 140.749648 -274.45922)
		(end 140.9319 -274.4089)
		(width 0.0889)
		(layer "In4.Cu")
		(net "M_J_CPU1_SB_DQ<0>")
	)
	(arc
		(start 138.111738 -274.4089)
		(mid 138.394694 -274.332723)
		(end 138.67765 -274.4089)
		(width 0.0889)
		(layer "In4.Cu")
		(net "M_J_CPU1_SB_DQ<0>")
	)
	(arc
		(start 142.437612 -274.4089)
		(mid 142.619863 -274.45925)
		(end 142.803372 -274.413726)
		(width 0.0889)
		(layer "In4.Cu")
		(net "M_J_CPU1_SB_DQ<0>")
	)
	(arc
		(start 135.29183 -274.4089)
		(mid 135.574786 -274.332723)
		(end 135.857742 -274.4089)
		(width 0.0889)
		(layer "In4.Cu")
		(net "M_J_CPU1_SB_DQ<0>")
	)
	(arc
		(start 133.411722 -274.4089)
		(mid 133.694678 -274.332723)
		(end 133.977634 -274.4089)
		(width 0.0889)
		(layer "In4.Cu")
		(net "M_J_CPU1_SB_DQ<0>")
	)
	(arc
		(start 141.8717 -274.4089)
		(mid 142.154656 -274.332723)
		(end 142.437612 -274.4089)
		(width 0.0889)
		(layer "In4.Cu")
		(net "M_J_CPU1_SB_DQ<0>")
	)
	(arc
		(start 136.797796 -274.4089)
		(mid 136.98474 -274.459155)
		(end 137.171684 -274.4089)
		(width 0.0889)
		(layer "In4.Cu")
		(net "M_J_CPU1_SB_DQ<0>")
	)
	(arc
		(start 133.093206 -274.435062)
		(mid 133.255395 -274.457797)
		(end 133.411722 -274.4089)
		(width 0.0889)
		(layer "In4.Cu")
		(net "M_J_CPU1_SB_DQ<0>")
	)
	(arc
		(start 144.334484 -274.41906)
		(mid 144.513205 -274.458983)
		(end 144.689322 -274.4089)
		(width 0.0889)
		(layer "In4.Cu")
		(net "M_J_CPU1_SB_DQ<0>")
	)
	(arc
		(start 139.626086 -274.413726)
		(mid 139.809594 -274.45922)
		(end 139.991846 -274.4089)
		(width 0.0889)
		(layer "In4.Cu")
		(net "M_J_CPU1_SB_DQ<0>")
	)
	(arc
		(start 135.866124 -274.413726)
		(mid 136.049632 -274.45922)
		(end 136.231884 -274.4089)
		(width 0.0889)
		(layer "In4.Cu")
		(net "M_J_CPU1_SB_DQ<0>")
	)
	(arc
		(start 144.71269 -274.395184)
		(mid 144.986344 -274.332241)
		(end 145.256504 -274.4089)
		(width 0.0889)
		(layer "In4.Cu")
		(net "M_J_CPU1_SB_DQ<0>")
	)
	(arc
		(start 139.051792 -274.4089)
		(mid 139.334748 -274.332723)
		(end 139.617704 -274.4089)
		(width 0.0889)
		(layer "In4.Cu")
		(net "M_J_CPU1_SB_DQ<0>")
	)
	(arc
		(start 137.171684 -274.4089)
		(mid 137.45464 -274.332723)
		(end 137.737596 -274.4089)
		(width 0.0889)
		(layer "In4.Cu")
		(net "M_J_CPU1_SB_DQ<0>")
	)
	(arc
		(start 134.92607 -274.413726)
		(mid 135.109578 -274.45922)
		(end 135.29183 -274.4089)
		(width 0.0889)
		(layer "In4.Cu")
		(net "M_J_CPU1_SB_DQ<0>")
	)
	(arc
		(start 143.386048 -274.413726)
		(mid 143.569556 -274.45922)
		(end 143.751808 -274.4089)
		(width 0.0889)
		(layer "In4.Cu")
		(net "M_J_CPU1_SB_DQ<0>")
	)
	(arc
		(start 143.751808 -274.4089)
		(mid 144.021577 -274.332877)
		(end 144.294606 -274.3962)
		(width 0.0889)
		(layer "In4.Cu")
		(net "M_J_CPU1_SB_DQ<0>")
	)
	(arc
		(start 137.737596 -274.4089)
		(mid 137.919847 -274.45925)
		(end 138.103356 -274.413726)
		(width 0.0889)
		(layer "In4.Cu")
		(net "M_J_CPU1_SB_DQ<0>")
	)
	(arc
		(start 142.811754 -274.4089)
		(mid 143.09471 -274.332723)
		(end 143.377666 -274.4089)
		(width 0.0889)
		(layer "In4.Cu")
		(net "M_J_CPU1_SB_DQ<0>")
	)
	(arc
		(start 140.9319 -274.4089)
		(mid 141.214856 -274.332723)
		(end 141.497812 -274.4089)
		(width 0.0889)
		(layer "In4.Cu")
		(net "M_J_CPU1_SB_DQ<0>")
	)
	(arc
		(start 141.497812 -274.4089)
		(mid 141.684756 -274.459155)
		(end 141.8717 -274.4089)
		(width 0.0889)
		(layer "In4.Cu")
		(net "M_J_CPU1_SB_DQ<0>")
	)
	(segment
		(start 132.287772 -266.530328)
		(end 132.754878 -266.796266)
		(width 0.10668)
		(layer "F.Cu")
		(net "M_J_CPU1_SB_CS_N<1>")
	)
	(segment
		(start 173.69409 -269.160498)
		(end 174.544228 -268.31036)
		(width 0.14478)
		(layer "In4.Cu")
		(net "M_J_CPU1_SB_CS_N<1>")
	)
	(segment
		(start 181.297072 -268.31036)
		(end 181.54777 -268.31036)
		(width 0.14478)
		(layer "In4.Cu")
		(net "M_J_CPU1_SB_CS_N<1>")
	)
	(segment
		(start 181.54777 -268.31036)
		(end 181.853586 -268.004544)
		(width 0.14478)
		(layer "In4.Cu")
		(net "M_J_CPU1_SB_CS_N<1>")
	)
	(segment
		(start 140.453364 -266.46886)
		(end 140.461746 -266.473686)
		(width 0.0889)
		(layer "In4.Cu")
		(net "M_J_CPU1_SB_CS_N<1>")
	)
	(segment
		(start 181.853586 -268.004544)
		(end 182.104284 -268.004544)
		(width 0.14478)
		(layer "In4.Cu")
		(net "M_J_CPU1_SB_CS_N<1>")
	)
	(segment
		(start 166.97579 -268.31036)
		(end 170.18254 -268.31036)
		(width 0.14478)
		(layer "In4.Cu")
		(net "M_J_CPU1_SB_CS_N<1>")
	)
	(segment
		(start 133.507734 -266.473686)
		(end 133.516116 -266.46886)
		(width 0.0889)
		(layer "In4.Cu")
		(net "M_J_CPU1_SB_CS_N<1>")
	)
	(segment
		(start 146.237706 -265.703304)
		(end 148.025104 -265.703304)
		(width 0.0889)
		(layer "In4.Cu")
		(net "M_J_CPU1_SB_CS_N<1>")
	)
	(segment
		(start 148.025104 -265.703304)
		(end 161.02203 -265.703304)
		(width 0.14478)
		(layer "In4.Cu")
		(net "M_J_CPU1_SB_CS_N<1>")
	)
	(segment
		(start 144.220946 -266.47394)
		(end 144.242536 -266.486386)
		(width 0.0889)
		(layer "In4.Cu")
		(net "M_J_CPU1_SB_CS_N<1>")
	)
	(segment
		(start 161.02203 -265.703304)
		(end 164.479224 -269.160498)
		(width 0.14478)
		(layer "In4.Cu")
		(net "M_J_CPU1_SB_CS_N<1>")
	)
	(segment
		(start 180.740558 -268.004544)
		(end 180.991256 -268.004544)
		(width 0.14478)
		(layer "In4.Cu")
		(net "M_J_CPU1_SB_CS_N<1>")
	)
	(segment
		(start 178.232816 -268.007846)
		(end 178.53533 -268.31036)
		(width 0.14478)
		(layer "In4.Cu")
		(net "M_J_CPU1_SB_CS_N<1>")
	)
	(segment
		(start 138.20775 -266.473686)
		(end 138.216132 -266.46886)
		(width 0.0889)
		(layer "In4.Cu")
		(net "M_J_CPU1_SB_CS_N<1>")
	)
	(segment
		(start 186.635136 -268.31036)
		(end 187.060078 -268.735302)
		(width 0.14478)
		(layer "In4.Cu")
		(net "M_J_CPU1_SB_CS_N<1>")
	)
	(segment
		(start 135.753348 -266.46886)
		(end 135.76173 -266.473686)
		(width 0.0889)
		(layer "In4.Cu")
		(net "M_J_CPU1_SB_CS_N<1>")
	)
	(segment
		(start 132.754878 -266.796266)
		(end 132.908802 -266.530836)
		(width 0.0889)
		(layer "In4.Cu")
		(net "M_J_CPU1_SB_CS_N<1>")
	)
	(segment
		(start 180.434742 -268.31036)
		(end 180.740558 -268.004544)
		(width 0.14478)
		(layer "In4.Cu")
		(net "M_J_CPU1_SB_CS_N<1>")
	)
	(segment
		(start 170.18254 -268.31036)
		(end 171.032678 -269.160498)
		(width 0.14478)
		(layer "In4.Cu")
		(net "M_J_CPU1_SB_CS_N<1>")
	)
	(segment
		(start 137.267696 -266.473686)
		(end 137.276078 -266.46886)
		(width 0.0889)
		(layer "In4.Cu")
		(net "M_J_CPU1_SB_CS_N<1>")
	)
	(segment
		(start 164.479224 -269.160498)
		(end 166.125652 -269.160498)
		(width 0.14478)
		(layer "In4.Cu")
		(net "M_J_CPU1_SB_CS_N<1>")
	)
	(segment
		(start 177.98415 -268.007846)
		(end 178.232816 -268.007846)
		(width 0.14478)
		(layer "In4.Cu")
		(net "M_J_CPU1_SB_CS_N<1>")
	)
	(segment
		(start 171.032678 -269.160498)
		(end 173.69409 -269.160498)
		(width 0.14478)
		(layer "In4.Cu")
		(net "M_J_CPU1_SB_CS_N<1>")
	)
	(segment
		(start 141.967712 -266.473686)
		(end 141.976094 -266.46886)
		(width 0.0889)
		(layer "In4.Cu")
		(net "M_J_CPU1_SB_CS_N<1>")
	)
	(segment
		(start 178.53533 -268.31036)
		(end 180.434742 -268.31036)
		(width 0.14478)
		(layer "In4.Cu")
		(net "M_J_CPU1_SB_CS_N<1>")
	)
	(segment
		(start 141.393418 -266.46886)
		(end 141.4018 -266.473686)
		(width 0.0889)
		(layer "In4.Cu")
		(net "M_J_CPU1_SB_CS_N<1>")
	)
	(segment
		(start 182.4101 -268.31036)
		(end 186.635136 -268.31036)
		(width 0.14478)
		(layer "In4.Cu")
		(net "M_J_CPU1_SB_CS_N<1>")
	)
	(segment
		(start 144.20088 -266.46251)
		(end 144.220946 -266.47394)
		(width 0.0889)
		(layer "In4.Cu")
		(net "M_J_CPU1_SB_CS_N<1>")
	)
	(segment
		(start 166.125652 -269.160498)
		(end 166.97579 -268.31036)
		(width 0.14478)
		(layer "In4.Cu")
		(net "M_J_CPU1_SB_CS_N<1>")
	)
	(segment
		(start 145.516346 -266.424664)
		(end 146.237706 -265.703304)
		(width 0.0889)
		(layer "In4.Cu")
		(net "M_J_CPU1_SB_CS_N<1>")
	)
	(segment
		(start 174.544228 -268.31036)
		(end 177.681636 -268.31036)
		(width 0.14478)
		(layer "In4.Cu")
		(net "M_J_CPU1_SB_CS_N<1>")
	)
	(segment
		(start 180.991256 -268.004544)
		(end 181.297072 -268.31036)
		(width 0.14478)
		(layer "In4.Cu")
		(net "M_J_CPU1_SB_CS_N<1>")
	)
	(segment
		(start 132.908802 -266.530836)
		(end 133.004814 -266.505436)
		(width 0.0889)
		(layer "In4.Cu")
		(net "M_J_CPU1_SB_CS_N<1>")
	)
	(segment
		(start 182.104284 -268.004544)
		(end 182.4101 -268.31036)
		(width 0.14478)
		(layer "In4.Cu")
		(net "M_J_CPU1_SB_CS_N<1>")
	)
	(segment
		(start 177.681636 -268.31036)
		(end 177.98415 -268.007846)
		(width 0.14478)
		(layer "In4.Cu")
		(net "M_J_CPU1_SB_CS_N<1>")
	)
	(segment
		(start 145.034254 -266.424664)
		(end 145.516346 -266.424664)
		(width 0.0889)
		(layer "In4.Cu")
		(net "M_J_CPU1_SB_CS_N<1>")
	)
	(segment
		(start 136.693402 -266.46886)
		(end 136.701784 -266.473686)
		(width 0.0889)
		(layer "In4.Cu")
		(net "M_J_CPU1_SB_CS_N<1>")
	)
	(arc
		(start 144.242536 -266.486386)
		(mid 144.515565 -266.549705)
		(end 144.785334 -266.473686)
		(width 0.0889)
		(layer "In4.Cu")
		(net "M_J_CPU1_SB_CS_N<1>")
	)
	(arc
		(start 133.881876 -266.473686)
		(mid 134.164832 -266.549863)
		(end 134.447788 -266.473686)
		(width 0.0889)
		(layer "In4.Cu")
		(net "M_J_CPU1_SB_CS_N<1>")
	)
	(arc
		(start 137.276078 -266.46886)
		(mid 137.459586 -266.423366)
		(end 137.641838 -266.473686)
		(width 0.0889)
		(layer "In4.Cu")
		(net "M_J_CPU1_SB_CS_N<1>")
	)
	(arc
		(start 133.004814 -266.505436)
		(mid 133.260022 -266.548913)
		(end 133.507734 -266.473686)
		(width 0.0889)
		(layer "In4.Cu")
		(net "M_J_CPU1_SB_CS_N<1>")
	)
	(arc
		(start 141.976094 -266.46886)
		(mid 142.159602 -266.423366)
		(end 142.341854 -266.473686)
		(width 0.0889)
		(layer "In4.Cu")
		(net "M_J_CPU1_SB_CS_N<1>")
	)
	(arc
		(start 135.76173 -266.473686)
		(mid 136.044686 -266.549863)
		(end 136.327642 -266.473686)
		(width 0.0889)
		(layer "In4.Cu")
		(net "M_J_CPU1_SB_CS_N<1>")
	)
	(arc
		(start 141.4018 -266.473686)
		(mid 141.684756 -266.549863)
		(end 141.967712 -266.473686)
		(width 0.0889)
		(layer "In4.Cu")
		(net "M_J_CPU1_SB_CS_N<1>")
	)
	(arc
		(start 135.387588 -266.473686)
		(mid 135.569839 -266.423336)
		(end 135.753348 -266.46886)
		(width 0.0889)
		(layer "In4.Cu")
		(net "M_J_CPU1_SB_CS_N<1>")
	)
	(arc
		(start 142.907766 -266.473686)
		(mid 143.09471 -266.423431)
		(end 143.281654 -266.473686)
		(width 0.0889)
		(layer "In4.Cu")
		(net "M_J_CPU1_SB_CS_N<1>")
	)
	(arc
		(start 137.641838 -266.473686)
		(mid 137.924794 -266.549863)
		(end 138.20775 -266.473686)
		(width 0.0889)
		(layer "In4.Cu")
		(net "M_J_CPU1_SB_CS_N<1>")
	)
	(arc
		(start 141.027658 -266.473686)
		(mid 141.209909 -266.423336)
		(end 141.393418 -266.46886)
		(width 0.0889)
		(layer "In4.Cu")
		(net "M_J_CPU1_SB_CS_N<1>")
	)
	(arc
		(start 136.701784 -266.473686)
		(mid 136.98474 -266.549863)
		(end 137.267696 -266.473686)
		(width 0.0889)
		(layer "In4.Cu")
		(net "M_J_CPU1_SB_CS_N<1>")
	)
	(arc
		(start 138.581892 -266.473686)
		(mid 138.864848 -266.549863)
		(end 139.147804 -266.473686)
		(width 0.0889)
		(layer "In4.Cu")
		(net "M_J_CPU1_SB_CS_N<1>")
	)
	(arc
		(start 140.087604 -266.473686)
		(mid 140.269855 -266.423336)
		(end 140.453364 -266.46886)
		(width 0.0889)
		(layer "In4.Cu")
		(net "M_J_CPU1_SB_CS_N<1>")
	)
	(arc
		(start 139.147804 -266.473686)
		(mid 139.334748 -266.423431)
		(end 139.521692 -266.473686)
		(width 0.0889)
		(layer "In4.Cu")
		(net "M_J_CPU1_SB_CS_N<1>")
	)
	(arc
		(start 139.521692 -266.473686)
		(mid 139.804648 -266.549863)
		(end 140.087604 -266.473686)
		(width 0.0889)
		(layer "In4.Cu")
		(net "M_J_CPU1_SB_CS_N<1>")
	)
	(arc
		(start 138.216132 -266.46886)
		(mid 138.39964 -266.423366)
		(end 138.581892 -266.473686)
		(width 0.0889)
		(layer "In4.Cu")
		(net "M_J_CPU1_SB_CS_N<1>")
	)
	(arc
		(start 144.785334 -266.473686)
		(mid 144.905694 -266.428381)
		(end 145.034254 -266.424664)
		(width 0.0889)
		(layer "In4.Cu")
		(net "M_J_CPU1_SB_CS_N<1>")
	)
	(arc
		(start 136.327642 -266.473686)
		(mid 136.509893 -266.423336)
		(end 136.693402 -266.46886)
		(width 0.0889)
		(layer "In4.Cu")
		(net "M_J_CPU1_SB_CS_N<1>")
	)
	(arc
		(start 133.516116 -266.46886)
		(mid 133.699624 -266.423366)
		(end 133.881876 -266.473686)
		(width 0.0889)
		(layer "In4.Cu")
		(net "M_J_CPU1_SB_CS_N<1>")
	)
	(arc
		(start 142.341854 -266.473686)
		(mid 142.62481 -266.549863)
		(end 142.907766 -266.473686)
		(width 0.0889)
		(layer "In4.Cu")
		(net "M_J_CPU1_SB_CS_N<1>")
	)
	(arc
		(start 143.847566 -266.473686)
		(mid 144.022805 -266.423615)
		(end 144.20088 -266.46251)
		(width 0.0889)
		(layer "In4.Cu")
		(net "M_J_CPU1_SB_CS_N<1>")
	)
	(arc
		(start 134.447788 -266.473686)
		(mid 134.634732 -266.423431)
		(end 134.821676 -266.473686)
		(width 0.0889)
		(layer "In4.Cu")
		(net "M_J_CPU1_SB_CS_N<1>")
	)
	(arc
		(start 140.461746 -266.473686)
		(mid 140.744702 -266.549863)
		(end 141.027658 -266.473686)
		(width 0.0889)
		(layer "In4.Cu")
		(net "M_J_CPU1_SB_CS_N<1>")
	)
	(arc
		(start 134.821676 -266.473686)
		(mid 135.104632 -266.549863)
		(end 135.387588 -266.473686)
		(width 0.0889)
		(layer "In4.Cu")
		(net "M_J_CPU1_SB_CS_N<1>")
	)
	(arc
		(start 143.281654 -266.473686)
		(mid 143.56461 -266.549863)
		(end 143.847566 -266.473686)
		(width 0.0889)
		(layer "In4.Cu")
		(net "M_J_CPU1_SB_CS_N<1>")
	)
	(segment
		(start 130.877818 -265.720322)
		(end 131.34467 -265.98626)
		(width 0.10668)
		(layer "F.Cu")
		(net "M_J_CPU1_SB_CS_N<0>")
	)
	(segment
		(start 173.787054 -268.31036)
		(end 174.636938 -267.460476)
		(width 0.14478)
		(layer "In4.Cu")
		(net "M_J_CPU1_SB_CS_N<0>")
	)
	(segment
		(start 166.243 -268.31036)
		(end 167.092884 -267.460476)
		(width 0.14478)
		(layer "In4.Cu")
		(net "M_J_CPU1_SB_CS_N<0>")
	)
	(segment
		(start 145.960084 -265.274044)
		(end 147.236688 -265.274044)
		(width 0.0889)
		(layer "In4.Cu")
		(net "M_J_CPU1_SB_CS_N<0>")
	)
	(segment
		(start 147.236688 -265.274044)
		(end 147.262088 -265.248644)
		(width 0.0889)
		(layer "In4.Cu")
		(net "M_J_CPU1_SB_CS_N<0>")
	)
	(segment
		(start 143.377666 -265.66368)
		(end 143.386048 -265.658854)
		(width 0.0889)
		(layer "In4.Cu")
		(net "M_J_CPU1_SB_CS_N<0>")
	)
	(segment
		(start 167.092884 -267.460476)
		(end 170.117516 -267.460476)
		(width 0.14478)
		(layer "In4.Cu")
		(net "M_J_CPU1_SB_CS_N<0>")
	)
	(segment
		(start 132.09778 -265.66368)
		(end 132.106162 -265.658854)
		(width 0.0889)
		(layer "In4.Cu")
		(net "M_J_CPU1_SB_CS_N<0>")
	)
	(segment
		(start 161.203386 -265.248644)
		(end 164.265102 -268.31036)
		(width 0.14478)
		(layer "In4.Cu")
		(net "M_J_CPU1_SB_CS_N<0>")
	)
	(segment
		(start 190.735204 -267.460476)
		(end 191.160146 -267.885418)
		(width 0.14478)
		(layer "In4.Cu")
		(net "M_J_CPU1_SB_CS_N<0>")
	)
	(segment
		(start 148.036788 -265.248644)
		(end 161.203386 -265.248644)
		(width 0.14478)
		(layer "In4.Cu")
		(net "M_J_CPU1_SB_CS_N<0>")
	)
	(segment
		(start 139.617704 -265.66368)
		(end 139.626086 -265.658854)
		(width 0.0889)
		(layer "In4.Cu")
		(net "M_J_CPU1_SB_CS_N<0>")
	)
	(segment
		(start 142.803372 -265.658854)
		(end 142.811754 -265.66368)
		(width 0.0889)
		(layer "In4.Cu")
		(net "M_J_CPU1_SB_CS_N<0>")
	)
	(segment
		(start 131.498848 -265.72083)
		(end 131.595114 -265.69543)
		(width 0.0889)
		(layer "In4.Cu")
		(net "M_J_CPU1_SB_CS_N<0>")
	)
	(segment
		(start 144.684242 -265.658854)
		(end 144.692624 -265.66368)
		(width 0.0889)
		(layer "In4.Cu")
		(net "M_J_CPU1_SB_CS_N<0>")
	)
	(segment
		(start 138.103356 -265.658854)
		(end 138.111738 -265.66368)
		(width 0.0889)
		(layer "In4.Cu")
		(net "M_J_CPU1_SB_CS_N<0>")
	)
	(segment
		(start 134.343394 -265.658854)
		(end 134.351776 -265.66368)
		(width 0.0889)
		(layer "In4.Cu")
		(net "M_J_CPU1_SB_CS_N<0>")
	)
	(segment
		(start 139.04341 -265.658854)
		(end 139.051792 -265.66368)
		(width 0.0889)
		(layer "In4.Cu")
		(net "M_J_CPU1_SB_CS_N<0>")
	)
	(segment
		(start 170.9674 -268.31036)
		(end 173.787054 -268.31036)
		(width 0.14478)
		(layer "In4.Cu")
		(net "M_J_CPU1_SB_CS_N<0>")
	)
	(segment
		(start 131.34467 -265.98626)
		(end 131.498848 -265.72083)
		(width 0.0889)
		(layer "In4.Cu")
		(net "M_J_CPU1_SB_CS_N<0>")
	)
	(segment
		(start 164.265102 -268.31036)
		(end 166.243 -268.31036)
		(width 0.14478)
		(layer "In4.Cu")
		(net "M_J_CPU1_SB_CS_N<0>")
	)
	(segment
		(start 135.857742 -265.66368)
		(end 135.866124 -265.658854)
		(width 0.0889)
		(layer "In4.Cu")
		(net "M_J_CPU1_SB_CS_N<0>")
	)
	(segment
		(start 134.917688 -265.66368)
		(end 134.92607 -265.658854)
		(width 0.0889)
		(layer "In4.Cu")
		(net "M_J_CPU1_SB_CS_N<0>")
	)
	(segment
		(start 170.117516 -267.460476)
		(end 170.9674 -268.31036)
		(width 0.14478)
		(layer "In4.Cu")
		(net "M_J_CPU1_SB_CS_N<0>")
	)
	(segment
		(start 145.25244 -265.667236)
		(end 145.960084 -265.274044)
		(width 0.0889)
		(layer "In4.Cu")
		(net "M_J_CPU1_SB_CS_N<0>")
	)
	(segment
		(start 147.262088 -265.248644)
		(end 148.036788 -265.248644)
		(width 0.0889)
		(layer "In4.Cu")
		(net "M_J_CPU1_SB_CS_N<0>")
	)
	(segment
		(start 174.636938 -267.460476)
		(end 190.735204 -267.460476)
		(width 0.14478)
		(layer "In4.Cu")
		(net "M_J_CPU1_SB_CS_N<0>")
	)
	(segment
		(start 143.751808 -265.66368)
		(end 143.762222 -265.669776)
		(width 0.0889)
		(layer "In4.Cu")
		(net "M_J_CPU1_SB_CS_N<0>")
	)
	(segment
		(start 140.557758 -265.66368)
		(end 140.56614 -265.658854)
		(width 0.0889)
		(layer "In4.Cu")
		(net "M_J_CPU1_SB_CS_N<0>")
	)
	(arc
		(start 133.411722 -265.66368)
		(mid 133.694678 -265.739857)
		(end 133.977634 -265.66368)
		(width 0.0889)
		(layer "In4.Cu")
		(net "M_J_CPU1_SB_CS_N<0>")
	)
	(arc
		(start 142.437612 -265.66368)
		(mid 142.619863 -265.61333)
		(end 142.803372 -265.658854)
		(width 0.0889)
		(layer "In4.Cu")
		(net "M_J_CPU1_SB_CS_N<0>")
	)
	(arc
		(start 134.92607 -265.658854)
		(mid 135.109578 -265.61336)
		(end 135.29183 -265.66368)
		(width 0.0889)
		(layer "In4.Cu")
		(net "M_J_CPU1_SB_CS_N<0>")
	)
	(arc
		(start 138.111738 -265.66368)
		(mid 138.394694 -265.739857)
		(end 138.67765 -265.66368)
		(width 0.0889)
		(layer "In4.Cu")
		(net "M_J_CPU1_SB_CS_N<0>")
	)
	(arc
		(start 138.67765 -265.66368)
		(mid 138.859901 -265.61333)
		(end 139.04341 -265.658854)
		(width 0.0889)
		(layer "In4.Cu")
		(net "M_J_CPU1_SB_CS_N<0>")
	)
	(arc
		(start 134.351776 -265.66368)
		(mid 134.634732 -265.739857)
		(end 134.917688 -265.66368)
		(width 0.0889)
		(layer "In4.Cu")
		(net "M_J_CPU1_SB_CS_N<0>")
	)
	(arc
		(start 136.797796 -265.66368)
		(mid 136.98474 -265.613425)
		(end 137.171684 -265.66368)
		(width 0.0889)
		(layer "In4.Cu")
		(net "M_J_CPU1_SB_CS_N<0>")
	)
	(arc
		(start 141.8717 -265.66368)
		(mid 142.154656 -265.739857)
		(end 142.437612 -265.66368)
		(width 0.0889)
		(layer "In4.Cu")
		(net "M_J_CPU1_SB_CS_N<0>")
	)
	(arc
		(start 136.231884 -265.66368)
		(mid 136.51484 -265.739857)
		(end 136.797796 -265.66368)
		(width 0.0889)
		(layer "In4.Cu")
		(net "M_J_CPU1_SB_CS_N<0>")
	)
	(arc
		(start 140.9319 -265.66368)
		(mid 141.214856 -265.739857)
		(end 141.497812 -265.66368)
		(width 0.0889)
		(layer "In4.Cu")
		(net "M_J_CPU1_SB_CS_N<0>")
	)
	(arc
		(start 132.471922 -265.66368)
		(mid 132.754878 -265.739857)
		(end 133.037834 -265.66368)
		(width 0.0889)
		(layer "In4.Cu")
		(net "M_J_CPU1_SB_CS_N<0>")
	)
	(arc
		(start 135.29183 -265.66368)
		(mid 135.574786 -265.739857)
		(end 135.857742 -265.66368)
		(width 0.0889)
		(layer "In4.Cu")
		(net "M_J_CPU1_SB_CS_N<0>")
	)
	(arc
		(start 137.171684 -265.66368)
		(mid 137.45464 -265.739857)
		(end 137.737596 -265.66368)
		(width 0.0889)
		(layer "In4.Cu")
		(net "M_J_CPU1_SB_CS_N<0>")
	)
	(arc
		(start 132.106162 -265.658854)
		(mid 132.28967 -265.61336)
		(end 132.471922 -265.66368)
		(width 0.0889)
		(layer "In4.Cu")
		(net "M_J_CPU1_SB_CS_N<0>")
	)
	(arc
		(start 143.762222 -265.669776)
		(mid 144.040908 -265.739996)
		(end 144.317974 -265.66368)
		(width 0.0889)
		(layer "In4.Cu")
		(net "M_J_CPU1_SB_CS_N<0>")
	)
	(arc
		(start 139.991846 -265.66368)
		(mid 140.274802 -265.739857)
		(end 140.557758 -265.66368)
		(width 0.0889)
		(layer "In4.Cu")
		(net "M_J_CPU1_SB_CS_N<0>")
	)
	(arc
		(start 135.866124 -265.658854)
		(mid 136.049632 -265.61336)
		(end 136.231884 -265.66368)
		(width 0.0889)
		(layer "In4.Cu")
		(net "M_J_CPU1_SB_CS_N<0>")
	)
	(arc
		(start 142.811754 -265.66368)
		(mid 143.09471 -265.739857)
		(end 143.377666 -265.66368)
		(width 0.0889)
		(layer "In4.Cu")
		(net "M_J_CPU1_SB_CS_N<0>")
	)
	(arc
		(start 144.317974 -265.66368)
		(mid 144.500479 -265.613203)
		(end 144.684242 -265.658854)
		(width 0.0889)
		(layer "In4.Cu")
		(net "M_J_CPU1_SB_CS_N<0>")
	)
	(arc
		(start 131.595114 -265.69543)
		(mid 131.850179 -265.738781)
		(end 132.09778 -265.66368)
		(width 0.0889)
		(layer "In4.Cu")
		(net "M_J_CPU1_SB_CS_N<0>")
	)
	(arc
		(start 139.051792 -265.66368)
		(mid 139.334748 -265.739857)
		(end 139.617704 -265.66368)
		(width 0.0889)
		(layer "In4.Cu")
		(net "M_J_CPU1_SB_CS_N<0>")
	)
	(arc
		(start 144.692624 -265.66368)
		(mid 144.972052 -265.739846)
		(end 145.25244 -265.667236)
		(width 0.0889)
		(layer "In4.Cu")
		(net "M_J_CPU1_SB_CS_N<0>")
	)
	(arc
		(start 143.386048 -265.658854)
		(mid 143.569556 -265.61336)
		(end 143.751808 -265.66368)
		(width 0.0889)
		(layer "In4.Cu")
		(net "M_J_CPU1_SB_CS_N<0>")
	)
	(arc
		(start 137.737596 -265.66368)
		(mid 137.919847 -265.61333)
		(end 138.103356 -265.658854)
		(width 0.0889)
		(layer "In4.Cu")
		(net "M_J_CPU1_SB_CS_N<0>")
	)
	(arc
		(start 133.977634 -265.66368)
		(mid 134.159885 -265.61333)
		(end 134.343394 -265.658854)
		(width 0.0889)
		(layer "In4.Cu")
		(net "M_J_CPU1_SB_CS_N<0>")
	)
	(arc
		(start 140.56614 -265.658854)
		(mid 140.749648 -265.61336)
		(end 140.9319 -265.66368)
		(width 0.0889)
		(layer "In4.Cu")
		(net "M_J_CPU1_SB_CS_N<0>")
	)
	(arc
		(start 139.626086 -265.658854)
		(mid 139.809594 -265.61336)
		(end 139.991846 -265.66368)
		(width 0.0889)
		(layer "In4.Cu")
		(net "M_J_CPU1_SB_CS_N<0>")
	)
	(arc
		(start 141.497812 -265.66368)
		(mid 141.684756 -265.613425)
		(end 141.8717 -265.66368)
		(width 0.0889)
		(layer "In4.Cu")
		(net "M_J_CPU1_SB_CS_N<0>")
	)
	(arc
		(start 133.037834 -265.66368)
		(mid 133.224778 -265.613425)
		(end 133.411722 -265.66368)
		(width 0.0889)
		(layer "In4.Cu")
		(net "M_J_CPU1_SB_CS_N<0>")
	)
	(segment
		(start 130.877818 -270.580358)
		(end 131.34467 -270.846296)
		(width 0.10668)
		(layer "F.Cu")
		(net "M_J_CPU1_SB_CB<7>")
	)
	(segment
		(start 181.597046 -273.57197)
		(end 181.597046 -274.135342)
		(width 0.14478)
		(layer "In4.Cu")
		(net "M_J_CPU1_SB_CB<7>")
	)
	(segment
		(start 180.494178 -274.447762)
		(end 180.655722 -274.609306)
		(width 0.14478)
		(layer "In4.Cu")
		(net "M_J_CPU1_SB_CB<7>")
	)
	(segment
		(start 181.435502 -273.410426)
		(end 181.597046 -273.57197)
		(width 0.14478)
		(layer "In4.Cu")
		(net "M_J_CPU1_SB_CB<7>")
	)
	(segment
		(start 174.636938 -273.410426)
		(end 180.332634 -273.410426)
		(width 0.14478)
		(layer "In4.Cu")
		(net "M_J_CPU1_SB_CB<7>")
	)
	(segment
		(start 134.917688 -270.523716)
		(end 134.92607 -270.51889)
		(width 0.0889)
		(layer "In4.Cu")
		(net "M_J_CPU1_SB_CB<7>")
	)
	(segment
		(start 145.15338 -269.708884)
		(end 145.161762 -269.71371)
		(width 0.0889)
		(layer "In4.Cu")
		(net "M_J_CPU1_SB_CB<7>")
	)
	(segment
		(start 170.778932 -274.26031)
		(end 173.787054 -274.26031)
		(width 0.14478)
		(layer "In4.Cu")
		(net "M_J_CPU1_SB_CB<7>")
	)
	(segment
		(start 181.597046 -274.135342)
		(end 181.75859 -274.296886)
		(width 0.14478)
		(layer "In4.Cu")
		(net "M_J_CPU1_SB_CB<7>")
	)
	(segment
		(start 142.803372 -270.51889)
		(end 142.811754 -270.523716)
		(width 0.0889)
		(layer "In4.Cu")
		(net "M_J_CPU1_SB_CB<7>")
	)
	(segment
		(start 131.34467 -270.846296)
		(end 131.498848 -270.580866)
		(width 0.0889)
		(layer "In4.Cu")
		(net "M_J_CPU1_SB_CB<7>")
	)
	(segment
		(start 166.252652 -274.250658)
		(end 167.092884 -273.410426)
		(width 0.14478)
		(layer "In4.Cu")
		(net "M_J_CPU1_SB_CB<7>")
	)
	(segment
		(start 135.857742 -270.523716)
		(end 135.866124 -270.51889)
		(width 0.0889)
		(layer "In4.Cu")
		(net "M_J_CPU1_SB_CB<7>")
	)
	(segment
		(start 160.110932 -271.290542)
		(end 161.295588 -271.290542)
		(width 0.14478)
		(layer "In4.Cu")
		(net "M_J_CPU1_SB_CB<7>")
	)
	(segment
		(start 161.295588 -271.290542)
		(end 164.255704 -274.250658)
		(width 0.14478)
		(layer "In4.Cu")
		(net "M_J_CPU1_SB_CB<7>")
	)
	(segment
		(start 131.498848 -270.580866)
		(end 131.595114 -270.555466)
		(width 0.0889)
		(layer "In4.Cu")
		(net "M_J_CPU1_SB_CB<7>")
	)
	(segment
		(start 144.75714 -269.73149)
		(end 144.757902 -269.730982)
		(width 0.0889)
		(layer "In4.Cu")
		(net "M_J_CPU1_SB_CB<7>")
	)
	(segment
		(start 180.884068 -274.609306)
		(end 181.045612 -274.447762)
		(width 0.14478)
		(layer "In4.Cu")
		(net "M_J_CPU1_SB_CB<7>")
	)
	(segment
		(start 146.639534 -268.837664)
		(end 147.293584 -268.837664)
		(width 0.0889)
		(layer "In4.Cu")
		(net "M_J_CPU1_SB_CB<7>")
	)
	(segment
		(start 143.377666 -270.523716)
		(end 143.386048 -270.51889)
		(width 0.0889)
		(layer "In4.Cu")
		(net "M_J_CPU1_SB_CB<7>")
	)
	(segment
		(start 148.026882 -268.680184)
		(end 157.500574 -268.680184)
		(width 0.14478)
		(layer "In4.Cu")
		(net "M_J_CPU1_SB_CB<7>")
	)
	(segment
		(start 144.31772 -270.523716)
		(end 144.356836 -270.500856)
		(width 0.0889)
		(layer "In4.Cu")
		(net "M_J_CPU1_SB_CB<7>")
	)
	(segment
		(start 182.14848 -274.135342)
		(end 182.14848 -273.57197)
		(width 0.14478)
		(layer "In4.Cu")
		(net "M_J_CPU1_SB_CB<7>")
	)
	(segment
		(start 181.045612 -274.447762)
		(end 181.045612 -273.57197)
		(width 0.14478)
		(layer "In4.Cu")
		(net "M_J_CPU1_SB_CB<7>")
	)
	(segment
		(start 181.207156 -273.410426)
		(end 181.435502 -273.410426)
		(width 0.14478)
		(layer "In4.Cu")
		(net "M_J_CPU1_SB_CB<7>")
	)
	(segment
		(start 181.045612 -273.57197)
		(end 181.207156 -273.410426)
		(width 0.14478)
		(layer "In4.Cu")
		(net "M_J_CPU1_SB_CB<7>")
	)
	(segment
		(start 164.255704 -274.250658)
		(end 166.252652 -274.250658)
		(width 0.14478)
		(layer "In4.Cu")
		(net "M_J_CPU1_SB_CB<7>")
	)
	(segment
		(start 181.75859 -274.296886)
		(end 181.986936 -274.296886)
		(width 0.14478)
		(layer "In4.Cu")
		(net "M_J_CPU1_SB_CB<7>")
	)
	(segment
		(start 138.103356 -270.51889)
		(end 138.111738 -270.523716)
		(width 0.0889)
		(layer "In4.Cu")
		(net "M_J_CPU1_SB_CB<7>")
	)
	(segment
		(start 134.343394 -270.51889)
		(end 134.351776 -270.523716)
		(width 0.0889)
		(layer "In4.Cu")
		(net "M_J_CPU1_SB_CB<7>")
	)
	(segment
		(start 184.524396 -273.410426)
		(end 185.799222 -274.685252)
		(width 0.14478)
		(layer "In4.Cu")
		(net "M_J_CPU1_SB_CB<7>")
	)
	(segment
		(start 157.500574 -268.680184)
		(end 160.110932 -271.290542)
		(width 0.14478)
		(layer "In4.Cu")
		(net "M_J_CPU1_SB_CB<7>")
	)
	(segment
		(start 169.929048 -273.410426)
		(end 170.778932 -274.26031)
		(width 0.14478)
		(layer "In4.Cu")
		(net "M_J_CPU1_SB_CB<7>")
	)
	(segment
		(start 182.14848 -273.57197)
		(end 182.310024 -273.410426)
		(width 0.14478)
		(layer "In4.Cu")
		(net "M_J_CPU1_SB_CB<7>")
	)
	(segment
		(start 185.799222 -274.685252)
		(end 187.060078 -274.685252)
		(width 0.14478)
		(layer "In4.Cu")
		(net "M_J_CPU1_SB_CB<7>")
	)
	(segment
		(start 140.557758 -270.523716)
		(end 140.56614 -270.51889)
		(width 0.0889)
		(layer "In4.Cu")
		(net "M_J_CPU1_SB_CB<7>")
	)
	(segment
		(start 147.451064 -268.680184)
		(end 148.026882 -268.680184)
		(width 0.0889)
		(layer "In4.Cu")
		(net "M_J_CPU1_SB_CB<7>")
	)
	(segment
		(start 132.09778 -270.523716)
		(end 132.106162 -270.51889)
		(width 0.0889)
		(layer "In4.Cu")
		(net "M_J_CPU1_SB_CB<7>")
	)
	(segment
		(start 180.494178 -273.57197)
		(end 180.494178 -274.447762)
		(width 0.14478)
		(layer "In4.Cu")
		(net "M_J_CPU1_SB_CB<7>")
	)
	(segment
		(start 173.787054 -274.26031)
		(end 174.636938 -273.410426)
		(width 0.14478)
		(layer "In4.Cu")
		(net "M_J_CPU1_SB_CB<7>")
	)
	(segment
		(start 144.757902 -269.730982)
		(end 144.78762 -269.71371)
		(width 0.0889)
		(layer "In4.Cu")
		(net "M_J_CPU1_SB_CB<7>")
	)
	(segment
		(start 180.655722 -274.609306)
		(end 180.884068 -274.609306)
		(width 0.14478)
		(layer "In4.Cu")
		(net "M_J_CPU1_SB_CB<7>")
	)
	(segment
		(start 139.617704 -270.523716)
		(end 139.626086 -270.51889)
		(width 0.0889)
		(layer "In4.Cu")
		(net "M_J_CPU1_SB_CB<7>")
	)
	(segment
		(start 145.850356 -269.626842)
		(end 146.639534 -268.837664)
		(width 0.0889)
		(layer "In4.Cu")
		(net "M_J_CPU1_SB_CB<7>")
	)
	(segment
		(start 139.04341 -270.51889)
		(end 139.051792 -270.523716)
		(width 0.0889)
		(layer "In4.Cu")
		(net "M_J_CPU1_SB_CB<7>")
	)
	(segment
		(start 147.293584 -268.837664)
		(end 147.451064 -268.680184)
		(width 0.0889)
		(layer "In4.Cu")
		(net "M_J_CPU1_SB_CB<7>")
	)
	(segment
		(start 180.332634 -273.410426)
		(end 180.494178 -273.57197)
		(width 0.14478)
		(layer "In4.Cu")
		(net "M_J_CPU1_SB_CB<7>")
	)
	(segment
		(start 182.310024 -273.410426)
		(end 184.524396 -273.410426)
		(width 0.14478)
		(layer "In4.Cu")
		(net "M_J_CPU1_SB_CB<7>")
	)
	(segment
		(start 181.986936 -274.296886)
		(end 182.14848 -274.135342)
		(width 0.14478)
		(layer "In4.Cu")
		(net "M_J_CPU1_SB_CB<7>")
	)
	(segment
		(start 167.092884 -273.410426)
		(end 169.929048 -273.410426)
		(width 0.14478)
		(layer "In4.Cu")
		(net "M_J_CPU1_SB_CB<7>")
	)
	(arc
		(start 140.9319 -270.523716)
		(mid 141.214856 -270.599893)
		(end 141.497812 -270.523716)
		(width 0.0889)
		(layer "In4.Cu")
		(net "M_J_CPU1_SB_CB<7>")
	)
	(arc
		(start 132.471922 -270.523716)
		(mid 132.754878 -270.599893)
		(end 133.037834 -270.523716)
		(width 0.0889)
		(layer "In4.Cu")
		(net "M_J_CPU1_SB_CB<7>")
	)
	(arc
		(start 132.106162 -270.51889)
		(mid 132.28967 -270.473396)
		(end 132.471922 -270.523716)
		(width 0.0889)
		(layer "In4.Cu")
		(net "M_J_CPU1_SB_CB<7>")
	)
	(arc
		(start 134.351776 -270.523716)
		(mid 134.634732 -270.599893)
		(end 134.917688 -270.523716)
		(width 0.0889)
		(layer "In4.Cu")
		(net "M_J_CPU1_SB_CB<7>")
	)
	(arc
		(start 138.67765 -270.523716)
		(mid 138.859901 -270.473366)
		(end 139.04341 -270.51889)
		(width 0.0889)
		(layer "In4.Cu")
		(net "M_J_CPU1_SB_CB<7>")
	)
	(arc
		(start 136.797796 -270.523716)
		(mid 136.98474 -270.473461)
		(end 137.171684 -270.523716)
		(width 0.0889)
		(layer "In4.Cu")
		(net "M_J_CPU1_SB_CB<7>")
	)
	(arc
		(start 131.595114 -270.555466)
		(mid 131.850179 -270.598817)
		(end 132.09778 -270.523716)
		(width 0.0889)
		(layer "In4.Cu")
		(net "M_J_CPU1_SB_CB<7>")
	)
	(arc
		(start 143.386048 -270.51889)
		(mid 143.569556 -270.473396)
		(end 143.751808 -270.523716)
		(width 0.0889)
		(layer "In4.Cu")
		(net "M_J_CPU1_SB_CB<7>")
	)
	(arc
		(start 145.161762 -269.71371)
		(mid 145.444718 -269.789887)
		(end 145.727674 -269.71371)
		(width 0.0889)
		(layer "In4.Cu")
		(net "M_J_CPU1_SB_CB<7>")
	)
	(arc
		(start 143.751808 -270.523716)
		(mid 144.034764 -270.599893)
		(end 144.31772 -270.523716)
		(width 0.0889)
		(layer "In4.Cu")
		(net "M_J_CPU1_SB_CB<7>")
	)
	(arc
		(start 134.92607 -270.51889)
		(mid 135.109578 -270.473396)
		(end 135.29183 -270.523716)
		(width 0.0889)
		(layer "In4.Cu")
		(net "M_J_CPU1_SB_CB<7>")
	)
	(arc
		(start 144.600168 -270.03629)
		(mid 144.641717 -269.864868)
		(end 144.75714 -269.73149)
		(width 0.0889)
		(layer "In4.Cu")
		(net "M_J_CPU1_SB_CB<7>")
	)
	(arc
		(start 136.231884 -270.523716)
		(mid 136.51484 -270.599893)
		(end 136.797796 -270.523716)
		(width 0.0889)
		(layer "In4.Cu")
		(net "M_J_CPU1_SB_CB<7>")
	)
	(arc
		(start 141.497812 -270.523716)
		(mid 141.684756 -270.473461)
		(end 141.8717 -270.523716)
		(width 0.0889)
		(layer "In4.Cu")
		(net "M_J_CPU1_SB_CB<7>")
	)
	(arc
		(start 139.991846 -270.523716)
		(mid 140.274802 -270.599893)
		(end 140.557758 -270.523716)
		(width 0.0889)
		(layer "In4.Cu")
		(net "M_J_CPU1_SB_CB<7>")
	)
	(arc
		(start 141.8717 -270.523716)
		(mid 142.154656 -270.599893)
		(end 142.437612 -270.523716)
		(width 0.0889)
		(layer "In4.Cu")
		(net "M_J_CPU1_SB_CB<7>")
	)
	(arc
		(start 139.626086 -270.51889)
		(mid 139.809594 -270.473396)
		(end 139.991846 -270.523716)
		(width 0.0889)
		(layer "In4.Cu")
		(net "M_J_CPU1_SB_CB<7>")
	)
	(arc
		(start 144.356836 -270.500856)
		(mid 144.535649 -270.298506)
		(end 144.600168 -270.03629)
		(width 0.0889)
		(layer "In4.Cu")
		(net "M_J_CPU1_SB_CB<7>")
	)
	(arc
		(start 140.56614 -270.51889)
		(mid 140.749648 -270.473396)
		(end 140.9319 -270.523716)
		(width 0.0889)
		(layer "In4.Cu")
		(net "M_J_CPU1_SB_CB<7>")
	)
	(arc
		(start 133.977634 -270.523716)
		(mid 134.159885 -270.473366)
		(end 134.343394 -270.51889)
		(width 0.0889)
		(layer "In4.Cu")
		(net "M_J_CPU1_SB_CB<7>")
	)
	(arc
		(start 142.811754 -270.523716)
		(mid 143.09471 -270.599893)
		(end 143.377666 -270.523716)
		(width 0.0889)
		(layer "In4.Cu")
		(net "M_J_CPU1_SB_CB<7>")
	)
	(arc
		(start 135.866124 -270.51889)
		(mid 136.049632 -270.473396)
		(end 136.231884 -270.523716)
		(width 0.0889)
		(layer "In4.Cu")
		(net "M_J_CPU1_SB_CB<7>")
	)
	(arc
		(start 133.411722 -270.523716)
		(mid 133.694678 -270.599893)
		(end 133.977634 -270.523716)
		(width 0.0889)
		(layer "In4.Cu")
		(net "M_J_CPU1_SB_CB<7>")
	)
	(arc
		(start 137.737596 -270.523716)
		(mid 137.919847 -270.473366)
		(end 138.103356 -270.51889)
		(width 0.0889)
		(layer "In4.Cu")
		(net "M_J_CPU1_SB_CB<7>")
	)
	(arc
		(start 142.437612 -270.523716)
		(mid 142.619863 -270.473366)
		(end 142.803372 -270.51889)
		(width 0.0889)
		(layer "In4.Cu")
		(net "M_J_CPU1_SB_CB<7>")
	)
	(arc
		(start 144.78762 -269.71371)
		(mid 144.969871 -269.66336)
		(end 145.15338 -269.708884)
		(width 0.0889)
		(layer "In4.Cu")
		(net "M_J_CPU1_SB_CB<7>")
	)
	(arc
		(start 138.111738 -270.523716)
		(mid 138.394694 -270.599893)
		(end 138.67765 -270.523716)
		(width 0.0889)
		(layer "In4.Cu")
		(net "M_J_CPU1_SB_CB<7>")
	)
	(arc
		(start 139.051792 -270.523716)
		(mid 139.334748 -270.599893)
		(end 139.617704 -270.523716)
		(width 0.0889)
		(layer "In4.Cu")
		(net "M_J_CPU1_SB_CB<7>")
	)
	(arc
		(start 133.037834 -270.523716)
		(mid 133.224778 -270.473461)
		(end 133.411722 -270.523716)
		(width 0.0889)
		(layer "In4.Cu")
		(net "M_J_CPU1_SB_CB<7>")
	)
	(arc
		(start 135.29183 -270.523716)
		(mid 135.574786 -270.599893)
		(end 135.857742 -270.523716)
		(width 0.0889)
		(layer "In4.Cu")
		(net "M_J_CPU1_SB_CB<7>")
	)
	(arc
		(start 145.727674 -269.71371)
		(mid 145.7927 -269.675481)
		(end 145.850356 -269.626842)
		(width 0.0889)
		(layer "In4.Cu")
		(net "M_J_CPU1_SB_CB<7>")
	)
	(arc
		(start 137.171684 -270.523716)
		(mid 137.45464 -270.599893)
		(end 137.737596 -270.523716)
		(width 0.0889)
		(layer "In4.Cu")
		(net "M_J_CPU1_SB_CB<7>")
	)
	(segment
		(start 132.287772 -269.770352)
		(end 132.754878 -270.03629)
		(width 0.10668)
		(layer "F.Cu")
		(net "M_J_CPU1_SB_CB<6>")
	)
	(segment
		(start 144.28597 -268.921992)
		(end 144.31772 -268.903704)
		(width 0.0889)
		(layer "In4.Cu")
		(net "M_J_CPU1_SB_CB<6>")
	)
	(segment
		(start 164.265356 -272.560288)
		(end 166.243 -272.560288)
		(width 0.14478)
		(layer "In4.Cu")
		(net "M_J_CPU1_SB_CB<6>")
	)
	(segment
		(start 159.237172 -267.760704)
		(end 159.465772 -267.760704)
		(width 0.14478)
		(layer "In4.Cu")
		(net "M_J_CPU1_SB_CB<6>")
	)
	(segment
		(start 166.243 -272.560288)
		(end 167.092884 -271.710404)
		(width 0.14478)
		(layer "In4.Cu")
		(net "M_J_CPU1_SB_CB<6>")
	)
	(segment
		(start 138.20775 -269.71371)
		(end 138.216132 -269.708884)
		(width 0.0889)
		(layer "In4.Cu")
		(net "M_J_CPU1_SB_CB<6>")
	)
	(segment
		(start 141.393418 -269.708884)
		(end 141.4018 -269.71371)
		(width 0.0889)
		(layer "In4.Cu")
		(net "M_J_CPU1_SB_CB<6>")
	)
	(segment
		(start 159.075628 -267.922248)
		(end 159.237172 -267.760704)
		(width 0.14478)
		(layer "In4.Cu")
		(net "M_J_CPU1_SB_CB<6>")
	)
	(segment
		(start 144.31772 -268.903704)
		(end 144.326102 -268.898878)
		(width 0.0889)
		(layer "In4.Cu")
		(net "M_J_CPU1_SB_CB<6>")
	)
	(segment
		(start 133.507734 -269.71371)
		(end 133.516116 -269.708884)
		(width 0.0889)
		(layer "In4.Cu")
		(net "M_J_CPU1_SB_CB<6>")
	)
	(segment
		(start 146.804126 -267.770864)
		(end 148.056854 -267.770864)
		(width 0.0889)
		(layer "In4.Cu")
		(net "M_J_CPU1_SB_CB<6>")
	)
	(segment
		(start 132.908802 -269.77086)
		(end 133.004814 -269.74546)
		(width 0.0889)
		(layer "In4.Cu")
		(net "M_J_CPU1_SB_CB<6>")
	)
	(segment
		(start 146.138646 -268.436344)
		(end 146.804126 -267.770864)
		(width 0.0889)
		(layer "In4.Cu")
		(net "M_J_CPU1_SB_CB<6>")
	)
	(segment
		(start 132.754878 -270.03629)
		(end 132.908802 -269.77086)
		(width 0.0889)
		(layer "In4.Cu")
		(net "M_J_CPU1_SB_CB<6>")
	)
	(segment
		(start 140.453364 -269.708884)
		(end 140.461746 -269.71371)
		(width 0.0889)
		(layer "In4.Cu")
		(net "M_J_CPU1_SB_CB<6>")
	)
	(segment
		(start 143.847566 -269.71371)
		(end 143.886682 -269.69085)
		(width 0.0889)
		(layer "In4.Cu")
		(net "M_J_CPU1_SB_CB<6>")
	)
	(segment
		(start 157.915356 -267.770864)
		(end 160.535874 -270.391382)
		(width 0.14478)
		(layer "In4.Cu")
		(net "M_J_CPU1_SB_CB<6>")
	)
	(segment
		(start 170.551856 -272.560288)
		(end 173.787054 -272.560288)
		(width 0.14478)
		(layer "In4.Cu")
		(net "M_J_CPU1_SB_CB<6>")
	)
	(segment
		(start 135.753348 -269.708884)
		(end 135.76173 -269.71371)
		(width 0.0889)
		(layer "In4.Cu")
		(net "M_J_CPU1_SB_CB<6>")
	)
	(segment
		(start 174.636938 -271.710404)
		(end 185.785252 -271.710404)
		(width 0.14478)
		(layer "In4.Cu")
		(net "M_J_CPU1_SB_CB<6>")
	)
	(segment
		(start 173.787054 -272.560288)
		(end 174.636938 -271.710404)
		(width 0.14478)
		(layer "In4.Cu")
		(net "M_J_CPU1_SB_CB<6>")
	)
	(segment
		(start 145.751804 -268.436344)
		(end 146.138646 -268.436344)
		(width 0.0889)
		(layer "In4.Cu")
		(net "M_J_CPU1_SB_CB<6>")
	)
	(segment
		(start 137.267696 -269.71371)
		(end 137.276078 -269.708884)
		(width 0.0889)
		(layer "In4.Cu")
		(net "M_J_CPU1_SB_CB<6>")
	)
	(segment
		(start 148.056854 -267.770864)
		(end 157.915356 -267.770864)
		(width 0.14478)
		(layer "In4.Cu")
		(net "M_J_CPU1_SB_CB<6>")
	)
	(segment
		(start 160.926018 -270.001238)
		(end 159.075628 -268.150848)
		(width 0.14478)
		(layer "In4.Cu")
		(net "M_J_CPU1_SB_CB<6>")
	)
	(segment
		(start 159.465772 -267.760704)
		(end 164.265356 -272.560288)
		(width 0.14478)
		(layer "In4.Cu")
		(net "M_J_CPU1_SB_CB<6>")
	)
	(segment
		(start 160.535874 -270.391382)
		(end 160.764474 -270.391382)
		(width 0.14478)
		(layer "In4.Cu")
		(net "M_J_CPU1_SB_CB<6>")
	)
	(segment
		(start 145.373344 -268.814804)
		(end 145.751804 -268.436344)
		(width 0.0889)
		(layer "In4.Cu")
		(net "M_J_CPU1_SB_CB<6>")
	)
	(segment
		(start 160.926018 -270.229838)
		(end 160.926018 -270.001238)
		(width 0.14478)
		(layer "In4.Cu")
		(net "M_J_CPU1_SB_CB<6>")
	)
	(segment
		(start 185.785252 -271.710404)
		(end 187.060078 -272.98523)
		(width 0.14478)
		(layer "In4.Cu")
		(net "M_J_CPU1_SB_CB<6>")
	)
	(segment
		(start 136.693402 -269.708884)
		(end 136.701784 -269.71371)
		(width 0.0889)
		(layer "In4.Cu")
		(net "M_J_CPU1_SB_CB<6>")
	)
	(segment
		(start 141.967712 -269.71371)
		(end 141.976094 -269.708884)
		(width 0.0889)
		(layer "In4.Cu")
		(net "M_J_CPU1_SB_CB<6>")
	)
	(segment
		(start 160.764474 -270.391382)
		(end 160.926018 -270.229838)
		(width 0.14478)
		(layer "In4.Cu")
		(net "M_J_CPU1_SB_CB<6>")
	)
	(segment
		(start 169.701972 -271.710404)
		(end 170.551856 -272.560288)
		(width 0.14478)
		(layer "In4.Cu")
		(net "M_J_CPU1_SB_CB<6>")
	)
	(segment
		(start 159.075628 -268.150848)
		(end 159.075628 -267.922248)
		(width 0.14478)
		(layer "In4.Cu")
		(net "M_J_CPU1_SB_CB<6>")
	)
	(segment
		(start 167.092884 -271.710404)
		(end 169.701972 -271.710404)
		(width 0.14478)
		(layer "In4.Cu")
		(net "M_J_CPU1_SB_CB<6>")
	)
	(arc
		(start 142.907766 -269.71371)
		(mid 143.09471 -269.663455)
		(end 143.281654 -269.71371)
		(width 0.0889)
		(layer "In4.Cu")
		(net "M_J_CPU1_SB_CB<6>")
	)
	(arc
		(start 144.691862 -268.903704)
		(mid 144.974818 -268.979881)
		(end 145.257774 -268.903704)
		(width 0.0889)
		(layer "In4.Cu")
		(net "M_J_CPU1_SB_CB<6>")
	)
	(arc
		(start 135.76173 -269.71371)
		(mid 136.044686 -269.789887)
		(end 136.327642 -269.71371)
		(width 0.0889)
		(layer "In4.Cu")
		(net "M_J_CPU1_SB_CB<6>")
	)
	(arc
		(start 136.327642 -269.71371)
		(mid 136.509893 -269.66336)
		(end 136.693402 -269.708884)
		(width 0.0889)
		(layer "In4.Cu")
		(net "M_J_CPU1_SB_CB<6>")
	)
	(arc
		(start 137.641838 -269.71371)
		(mid 137.924794 -269.789887)
		(end 138.20775 -269.71371)
		(width 0.0889)
		(layer "In4.Cu")
		(net "M_J_CPU1_SB_CB<6>")
	)
	(arc
		(start 145.257774 -268.903704)
		(mid 145.318447 -268.863008)
		(end 145.373344 -268.814804)
		(width 0.0889)
		(layer "In4.Cu")
		(net "M_J_CPU1_SB_CB<6>")
	)
	(arc
		(start 139.147804 -269.71371)
		(mid 139.334748 -269.663455)
		(end 139.521692 -269.71371)
		(width 0.0889)
		(layer "In4.Cu")
		(net "M_J_CPU1_SB_CB<6>")
	)
	(arc
		(start 136.701784 -269.71371)
		(mid 136.98474 -269.789887)
		(end 137.267696 -269.71371)
		(width 0.0889)
		(layer "In4.Cu")
		(net "M_J_CPU1_SB_CB<6>")
	)
	(arc
		(start 138.216132 -269.708884)
		(mid 138.39964 -269.66339)
		(end 138.581892 -269.71371)
		(width 0.0889)
		(layer "In4.Cu")
		(net "M_J_CPU1_SB_CB<6>")
	)
	(arc
		(start 135.387588 -269.71371)
		(mid 135.569839 -269.66336)
		(end 135.753348 -269.708884)
		(width 0.0889)
		(layer "In4.Cu")
		(net "M_J_CPU1_SB_CB<6>")
	)
	(arc
		(start 141.4018 -269.71371)
		(mid 141.684756 -269.789887)
		(end 141.967712 -269.71371)
		(width 0.0889)
		(layer "In4.Cu")
		(net "M_J_CPU1_SB_CB<6>")
	)
	(arc
		(start 138.581892 -269.71371)
		(mid 138.864848 -269.789887)
		(end 139.147804 -269.71371)
		(width 0.0889)
		(layer "In4.Cu")
		(net "M_J_CPU1_SB_CB<6>")
	)
	(arc
		(start 133.004814 -269.74546)
		(mid 133.260022 -269.788937)
		(end 133.507734 -269.71371)
		(width 0.0889)
		(layer "In4.Cu")
		(net "M_J_CPU1_SB_CB<6>")
	)
	(arc
		(start 140.087604 -269.71371)
		(mid 140.269855 -269.66336)
		(end 140.453364 -269.708884)
		(width 0.0889)
		(layer "In4.Cu")
		(net "M_J_CPU1_SB_CB<6>")
	)
	(arc
		(start 144.130014 -269.226284)
		(mid 144.171269 -269.055313)
		(end 144.28597 -268.921992)
		(width 0.0889)
		(layer "In4.Cu")
		(net "M_J_CPU1_SB_CB<6>")
	)
	(arc
		(start 139.521692 -269.71371)
		(mid 139.804648 -269.789887)
		(end 140.087604 -269.71371)
		(width 0.0889)
		(layer "In4.Cu")
		(net "M_J_CPU1_SB_CB<6>")
	)
	(arc
		(start 134.447788 -269.71371)
		(mid 134.634732 -269.663455)
		(end 134.821676 -269.71371)
		(width 0.0889)
		(layer "In4.Cu")
		(net "M_J_CPU1_SB_CB<6>")
	)
	(arc
		(start 141.027658 -269.71371)
		(mid 141.209909 -269.66336)
		(end 141.393418 -269.708884)
		(width 0.0889)
		(layer "In4.Cu")
		(net "M_J_CPU1_SB_CB<6>")
	)
	(arc
		(start 143.281654 -269.71371)
		(mid 143.56461 -269.789887)
		(end 143.847566 -269.71371)
		(width 0.0889)
		(layer "In4.Cu")
		(net "M_J_CPU1_SB_CB<6>")
	)
	(arc
		(start 134.821676 -269.71371)
		(mid 135.104632 -269.789887)
		(end 135.387588 -269.71371)
		(width 0.0889)
		(layer "In4.Cu")
		(net "M_J_CPU1_SB_CB<6>")
	)
	(arc
		(start 143.886682 -269.69085)
		(mid 144.065495 -269.4885)
		(end 144.130014 -269.226284)
		(width 0.0889)
		(layer "In4.Cu")
		(net "M_J_CPU1_SB_CB<6>")
	)
	(arc
		(start 133.516116 -269.708884)
		(mid 133.699624 -269.66339)
		(end 133.881876 -269.71371)
		(width 0.0889)
		(layer "In4.Cu")
		(net "M_J_CPU1_SB_CB<6>")
	)
	(arc
		(start 144.326102 -268.898878)
		(mid 144.50961 -268.853384)
		(end 144.691862 -268.903704)
		(width 0.0889)
		(layer "In4.Cu")
		(net "M_J_CPU1_SB_CB<6>")
	)
	(arc
		(start 133.881876 -269.71371)
		(mid 134.164832 -269.789887)
		(end 134.447788 -269.71371)
		(width 0.0889)
		(layer "In4.Cu")
		(net "M_J_CPU1_SB_CB<6>")
	)
	(arc
		(start 141.976094 -269.708884)
		(mid 142.159602 -269.66339)
		(end 142.341854 -269.71371)
		(width 0.0889)
		(layer "In4.Cu")
		(net "M_J_CPU1_SB_CB<6>")
	)
	(arc
		(start 142.341854 -269.71371)
		(mid 142.62481 -269.789887)
		(end 142.907766 -269.71371)
		(width 0.0889)
		(layer "In4.Cu")
		(net "M_J_CPU1_SB_CB<6>")
	)
	(arc
		(start 140.461746 -269.71371)
		(mid 140.744702 -269.789887)
		(end 141.027658 -269.71371)
		(width 0.0889)
		(layer "In4.Cu")
		(net "M_J_CPU1_SB_CB<6>")
	)
	(arc
		(start 137.276078 -269.708884)
		(mid 137.459586 -269.66339)
		(end 137.641838 -269.71371)
		(width 0.0889)
		(layer "In4.Cu")
		(net "M_J_CPU1_SB_CB<6>")
	)
	(segment
		(start 131.347972 -269.770352)
		(end 131.814824 -270.03629)
		(width 0.10668)
		(layer "F.Cu")
		(net "M_J_CPU1_SB_CB<5>")
	)
	(segment
		(start 140.453364 -270.363696)
		(end 140.461746 -270.35887)
		(width 0.0889)
		(layer "In4.Cu")
		(net "M_J_CPU1_SB_CB<5>")
	)
	(segment
		(start 164.479478 -273.410426)
		(end 166.150036 -273.410426)
		(width 0.14478)
		(layer "In4.Cu")
		(net "M_J_CPU1_SB_CB<5>")
	)
	(segment
		(start 189.023752 -273.410426)
		(end 191.160146 -273.835368)
		(width 0.14478)
		(layer "In4.Cu")
		(net "M_J_CPU1_SB_CB<5>")
	)
	(segment
		(start 136.693402 -270.363696)
		(end 136.701784 -270.35887)
		(width 0.0889)
		(layer "In4.Cu")
		(net "M_J_CPU1_SB_CB<5>")
	)
	(segment
		(start 161.910014 -270.840962)
		(end 164.479478 -273.410426)
		(width 0.14478)
		(layer "In4.Cu")
		(net "M_J_CPU1_SB_CB<5>")
	)
	(segment
		(start 169.815764 -272.560288)
		(end 170.665902 -273.410426)
		(width 0.14478)
		(layer "In4.Cu")
		(net "M_J_CPU1_SB_CB<5>")
	)
	(segment
		(start 144.652746 -269.571724)
		(end 144.691862 -269.548864)
		(width 0.0889)
		(layer "In4.Cu")
		(net "M_J_CPU1_SB_CB<5>")
	)
	(segment
		(start 131.993386 -270.363696)
		(end 132.001768 -270.35887)
		(width 0.0889)
		(layer "In4.Cu")
		(net "M_J_CPU1_SB_CB<5>")
	)
	(segment
		(start 144.221708 -270.35887)
		(end 144.253458 -270.340582)
		(width 0.0889)
		(layer "In4.Cu")
		(net "M_J_CPU1_SB_CB<5>")
	)
	(segment
		(start 138.20775 -270.35887)
		(end 138.216132 -270.363696)
		(width 0.0889)
		(layer "In4.Cu")
		(net "M_J_CPU1_SB_CB<5>")
	)
	(segment
		(start 186.614816 -273.410426)
		(end 189.023752 -273.410426)
		(width 0.14478)
		(layer "In4.Cu")
		(net "M_J_CPU1_SB_CB<5>")
	)
	(segment
		(start 174.544228 -272.560288)
		(end 184.562242 -272.560288)
		(width 0.14478)
		(layer "In4.Cu")
		(net "M_J_CPU1_SB_CB<5>")
	)
	(segment
		(start 146.592036 -268.588744)
		(end 147.139406 -268.588744)
		(width 0.0889)
		(layer "In4.Cu")
		(net "M_J_CPU1_SB_CB<5>")
	)
	(segment
		(start 135.753348 -270.363696)
		(end 135.76173 -270.35887)
		(width 0.0889)
		(layer "In4.Cu")
		(net "M_J_CPU1_SB_CB<5>")
	)
	(segment
		(start 160.297622 -270.840962)
		(end 161.910014 -270.840962)
		(width 0.14478)
		(layer "In4.Cu")
		(net "M_J_CPU1_SB_CB<5>")
	)
	(segment
		(start 157.682184 -268.225524)
		(end 160.297622 -270.840962)
		(width 0.14478)
		(layer "In4.Cu")
		(net "M_J_CPU1_SB_CB<5>")
	)
	(segment
		(start 166.150036 -273.410426)
		(end 167.000174 -272.560288)
		(width 0.14478)
		(layer "In4.Cu")
		(net "M_J_CPU1_SB_CB<5>")
	)
	(segment
		(start 137.267696 -270.35887)
		(end 137.276078 -270.363696)
		(width 0.0889)
		(layer "In4.Cu")
		(net "M_J_CPU1_SB_CB<5>")
	)
	(segment
		(start 173.69409 -273.410426)
		(end 174.544228 -272.560288)
		(width 0.14478)
		(layer "In4.Cu")
		(net "M_J_CPU1_SB_CB<5>")
	)
	(segment
		(start 145.631916 -269.548864)
		(end 146.592036 -268.588744)
		(width 0.0889)
		(layer "In4.Cu")
		(net "M_J_CPU1_SB_CB<5>")
	)
	(segment
		(start 147.502626 -268.225524)
		(end 148.06676 -268.225524)
		(width 0.0889)
		(layer "In4.Cu")
		(net "M_J_CPU1_SB_CB<5>")
	)
	(segment
		(start 147.139406 -268.588744)
		(end 147.502626 -268.225524)
		(width 0.0889)
		(layer "In4.Cu")
		(net "M_J_CPU1_SB_CB<5>")
	)
	(segment
		(start 148.06676 -268.225524)
		(end 157.682184 -268.225524)
		(width 0.14478)
		(layer "In4.Cu")
		(net "M_J_CPU1_SB_CB<5>")
	)
	(segment
		(start 170.665902 -273.410426)
		(end 173.69409 -273.410426)
		(width 0.14478)
		(layer "In4.Cu")
		(net "M_J_CPU1_SB_CB<5>")
	)
	(segment
		(start 132.93344 -270.363696)
		(end 132.941822 -270.35887)
		(width 0.0889)
		(layer "In4.Cu")
		(net "M_J_CPU1_SB_CB<5>")
	)
	(segment
		(start 131.660646 -270.30172)
		(end 131.682998 -270.385032)
		(width 0.0889)
		(layer "In4.Cu")
		(net "M_J_CPU1_SB_CB<5>")
	)
	(segment
		(start 167.000174 -272.560288)
		(end 169.815764 -272.560288)
		(width 0.14478)
		(layer "In4.Cu")
		(net "M_J_CPU1_SB_CB<5>")
	)
	(segment
		(start 144.213326 -270.363696)
		(end 144.221708 -270.35887)
		(width 0.0889)
		(layer "In4.Cu")
		(net "M_J_CPU1_SB_CB<5>")
	)
	(segment
		(start 133.507734 -270.35887)
		(end 133.516116 -270.363696)
		(width 0.0889)
		(layer "In4.Cu")
		(net "M_J_CPU1_SB_CB<5>")
	)
	(segment
		(start 184.562242 -272.560288)
		(end 186.614816 -273.410426)
		(width 0.14478)
		(layer "In4.Cu")
		(net "M_J_CPU1_SB_CB<5>")
	)
	(segment
		(start 141.393418 -270.363696)
		(end 141.4018 -270.35887)
		(width 0.0889)
		(layer "In4.Cu")
		(net "M_J_CPU1_SB_CB<5>")
	)
	(segment
		(start 145.257774 -269.548864)
		(end 145.266156 -269.55369)
		(width 0.0889)
		(layer "In4.Cu")
		(net "M_J_CPU1_SB_CB<5>")
	)
	(segment
		(start 141.967712 -270.35887)
		(end 141.976094 -270.363696)
		(width 0.0889)
		(layer "In4.Cu")
		(net "M_J_CPU1_SB_CB<5>")
	)
	(segment
		(start 131.814824 -270.03629)
		(end 131.660646 -270.30172)
		(width 0.0889)
		(layer "In4.Cu")
		(net "M_J_CPU1_SB_CB<5>")
	)
	(arc
		(start 145.266156 -269.55369)
		(mid 145.449664 -269.599184)
		(end 145.631916 -269.548864)
		(width 0.0889)
		(layer "In4.Cu")
		(net "M_J_CPU1_SB_CB<5>")
	)
	(arc
		(start 142.341854 -270.35887)
		(mid 142.62481 -270.282693)
		(end 142.907766 -270.35887)
		(width 0.0889)
		(layer "In4.Cu")
		(net "M_J_CPU1_SB_CB<5>")
	)
	(arc
		(start 137.276078 -270.363696)
		(mid 137.459586 -270.40919)
		(end 137.641838 -270.35887)
		(width 0.0889)
		(layer "In4.Cu")
		(net "M_J_CPU1_SB_CB<5>")
	)
	(arc
		(start 131.682998 -270.385032)
		(mid 131.840508 -270.40823)
		(end 131.993386 -270.363696)
		(width 0.0889)
		(layer "In4.Cu")
		(net "M_J_CPU1_SB_CB<5>")
	)
	(arc
		(start 139.147804 -270.35887)
		(mid 139.334748 -270.409125)
		(end 139.521692 -270.35887)
		(width 0.0889)
		(layer "In4.Cu")
		(net "M_J_CPU1_SB_CB<5>")
	)
	(arc
		(start 135.387588 -270.35887)
		(mid 135.569839 -270.40922)
		(end 135.753348 -270.363696)
		(width 0.0889)
		(layer "In4.Cu")
		(net "M_J_CPU1_SB_CB<5>")
	)
	(arc
		(start 134.821676 -270.35887)
		(mid 135.104632 -270.282693)
		(end 135.387588 -270.35887)
		(width 0.0889)
		(layer "In4.Cu")
		(net "M_J_CPU1_SB_CB<5>")
	)
	(arc
		(start 144.253458 -270.340582)
		(mid 144.368134 -270.207248)
		(end 144.409414 -270.03629)
		(width 0.0889)
		(layer "In4.Cu")
		(net "M_J_CPU1_SB_CB<5>")
	)
	(arc
		(start 132.56768 -270.35887)
		(mid 132.749931 -270.40922)
		(end 132.93344 -270.363696)
		(width 0.0889)
		(layer "In4.Cu")
		(net "M_J_CPU1_SB_CB<5>")
	)
	(arc
		(start 141.976094 -270.363696)
		(mid 142.159602 -270.40919)
		(end 142.341854 -270.35887)
		(width 0.0889)
		(layer "In4.Cu")
		(net "M_J_CPU1_SB_CB<5>")
	)
	(arc
		(start 132.941822 -270.35887)
		(mid 133.224778 -270.282693)
		(end 133.507734 -270.35887)
		(width 0.0889)
		(layer "In4.Cu")
		(net "M_J_CPU1_SB_CB<5>")
	)
	(arc
		(start 132.001768 -270.35887)
		(mid 132.284724 -270.282693)
		(end 132.56768 -270.35887)
		(width 0.0889)
		(layer "In4.Cu")
		(net "M_J_CPU1_SB_CB<5>")
	)
	(arc
		(start 137.641838 -270.35887)
		(mid 137.924794 -270.282693)
		(end 138.20775 -270.35887)
		(width 0.0889)
		(layer "In4.Cu")
		(net "M_J_CPU1_SB_CB<5>")
	)
	(arc
		(start 140.461746 -270.35887)
		(mid 140.744702 -270.282693)
		(end 141.027658 -270.35887)
		(width 0.0889)
		(layer "In4.Cu")
		(net "M_J_CPU1_SB_CB<5>")
	)
	(arc
		(start 136.327642 -270.35887)
		(mid 136.509893 -270.40922)
		(end 136.693402 -270.363696)
		(width 0.0889)
		(layer "In4.Cu")
		(net "M_J_CPU1_SB_CB<5>")
	)
	(arc
		(start 133.881876 -270.35887)
		(mid 134.164832 -270.282693)
		(end 134.447788 -270.35887)
		(width 0.0889)
		(layer "In4.Cu")
		(net "M_J_CPU1_SB_CB<5>")
	)
	(arc
		(start 143.847566 -270.35887)
		(mid 144.029817 -270.40922)
		(end 144.213326 -270.363696)
		(width 0.0889)
		(layer "In4.Cu")
		(net "M_J_CPU1_SB_CB<5>")
	)
	(arc
		(start 138.581892 -270.35887)
		(mid 138.864848 -270.282693)
		(end 139.147804 -270.35887)
		(width 0.0889)
		(layer "In4.Cu")
		(net "M_J_CPU1_SB_CB<5>")
	)
	(arc
		(start 141.027658 -270.35887)
		(mid 141.209909 -270.40922)
		(end 141.393418 -270.363696)
		(width 0.0889)
		(layer "In4.Cu")
		(net "M_J_CPU1_SB_CB<5>")
	)
	(arc
		(start 141.4018 -270.35887)
		(mid 141.684756 -270.282693)
		(end 141.967712 -270.35887)
		(width 0.0889)
		(layer "In4.Cu")
		(net "M_J_CPU1_SB_CB<5>")
	)
	(arc
		(start 133.516116 -270.363696)
		(mid 133.699624 -270.40919)
		(end 133.881876 -270.35887)
		(width 0.0889)
		(layer "In4.Cu")
		(net "M_J_CPU1_SB_CB<5>")
	)
	(arc
		(start 144.691862 -269.548864)
		(mid 144.974818 -269.472687)
		(end 145.257774 -269.548864)
		(width 0.0889)
		(layer "In4.Cu")
		(net "M_J_CPU1_SB_CB<5>")
	)
	(arc
		(start 135.76173 -270.35887)
		(mid 136.044686 -270.282693)
		(end 136.327642 -270.35887)
		(width 0.0889)
		(layer "In4.Cu")
		(net "M_J_CPU1_SB_CB<5>")
	)
	(arc
		(start 142.907766 -270.35887)
		(mid 143.09471 -270.409125)
		(end 143.281654 -270.35887)
		(width 0.0889)
		(layer "In4.Cu")
		(net "M_J_CPU1_SB_CB<5>")
	)
	(arc
		(start 144.409414 -270.03629)
		(mid 144.473929 -269.774071)
		(end 144.652746 -269.571724)
		(width 0.0889)
		(layer "In4.Cu")
		(net "M_J_CPU1_SB_CB<5>")
	)
	(arc
		(start 139.521692 -270.35887)
		(mid 139.804648 -270.282693)
		(end 140.087604 -270.35887)
		(width 0.0889)
		(layer "In4.Cu")
		(net "M_J_CPU1_SB_CB<5>")
	)
	(arc
		(start 140.087604 -270.35887)
		(mid 140.269855 -270.40922)
		(end 140.453364 -270.363696)
		(width 0.0889)
		(layer "In4.Cu")
		(net "M_J_CPU1_SB_CB<5>")
	)
	(arc
		(start 138.216132 -270.363696)
		(mid 138.39964 -270.40919)
		(end 138.581892 -270.35887)
		(width 0.0889)
		(layer "In4.Cu")
		(net "M_J_CPU1_SB_CB<5>")
	)
	(arc
		(start 136.701784 -270.35887)
		(mid 136.98474 -270.282693)
		(end 137.267696 -270.35887)
		(width 0.0889)
		(layer "In4.Cu")
		(net "M_J_CPU1_SB_CB<5>")
	)
	(arc
		(start 134.447788 -270.35887)
		(mid 134.634732 -270.409125)
		(end 134.821676 -270.35887)
		(width 0.0889)
		(layer "In4.Cu")
		(net "M_J_CPU1_SB_CB<5>")
	)
	(arc
		(start 143.281654 -270.35887)
		(mid 143.56461 -270.282693)
		(end 143.847566 -270.35887)
		(width 0.0889)
		(layer "In4.Cu")
		(net "M_J_CPU1_SB_CB<5>")
	)
	(segment
		(start 132.757926 -268.960346)
		(end 133.224778 -269.226284)
		(width 0.10668)
		(layer "F.Cu")
		(net "M_J_CPU1_SB_CB<4>")
	)
	(segment
		(start 187.889896 -270.860266)
		(end 188.052964 -271.023334)
		(width 0.14478)
		(layer "In4.Cu")
		(net "M_J_CPU1_SB_CB<4>")
	)
	(segment
		(start 170.540172 -271.71015)
		(end 173.908974 -271.71015)
		(width 0.14478)
		(layer "In4.Cu")
		(net "M_J_CPU1_SB_CB<4>")
	)
	(segment
		(start 167.207184 -270.860266)
		(end 169.690288 -270.860266)
		(width 0.14478)
		(layer "In4.Cu")
		(net "M_J_CPU1_SB_CB<4>")
	)
	(segment
		(start 174.758858 -270.860266)
		(end 187.889896 -270.860266)
		(width 0.14478)
		(layer "In4.Cu")
		(net "M_J_CPU1_SB_CB<4>")
	)
	(segment
		(start 146.070066 -268.192758)
		(end 146.9517 -267.311124)
		(width 0.0889)
		(layer "In4.Cu")
		(net "M_J_CPU1_SB_CB<4>")
	)
	(segment
		(start 133.070854 -269.491714)
		(end 133.093206 -269.575026)
		(width 0.0889)
		(layer "In4.Cu")
		(net "M_J_CPU1_SB_CB<4>")
	)
	(segment
		(start 143.751808 -269.548864)
		(end 143.782288 -269.531084)
		(width 0.0889)
		(layer "In4.Cu")
		(net "M_J_CPU1_SB_CB<4>")
	)
	(segment
		(start 190.749682 -272.135346)
		(end 191.160146 -272.135346)
		(width 0.14478)
		(layer "In4.Cu")
		(net "M_J_CPU1_SB_CB<4>")
	)
	(segment
		(start 145.23847 -268.67993)
		(end 145.725642 -268.192758)
		(width 0.0889)
		(layer "In4.Cu")
		(net "M_J_CPU1_SB_CB<4>")
	)
	(segment
		(start 188.052964 -271.784572)
		(end 188.216032 -271.94764)
		(width 0.14478)
		(layer "In4.Cu")
		(net "M_J_CPU1_SB_CB<4>")
	)
	(segment
		(start 140.557758 -269.548864)
		(end 140.56614 -269.55369)
		(width 0.0889)
		(layer "In4.Cu")
		(net "M_J_CPU1_SB_CB<4>")
	)
	(segment
		(start 134.343394 -269.55369)
		(end 134.351776 -269.548864)
		(width 0.0889)
		(layer "In4.Cu")
		(net "M_J_CPU1_SB_CB<4>")
	)
	(segment
		(start 147.992084 -267.311124)
		(end 159.942276 -267.311124)
		(width 0.14478)
		(layer "In4.Cu")
		(net "M_J_CPU1_SB_CB<4>")
	)
	(segment
		(start 188.609478 -271.784572)
		(end 188.609478 -271.023334)
		(width 0.14478)
		(layer "In4.Cu")
		(net "M_J_CPU1_SB_CB<4>")
	)
	(segment
		(start 166.3573 -271.71015)
		(end 167.207184 -270.860266)
		(width 0.14478)
		(layer "In4.Cu")
		(net "M_J_CPU1_SB_CB<4>")
	)
	(segment
		(start 145.725642 -268.192758)
		(end 146.070066 -268.192758)
		(width 0.0889)
		(layer "In4.Cu")
		(net "M_J_CPU1_SB_CB<4>")
	)
	(segment
		(start 135.857742 -269.548864)
		(end 135.866124 -269.55369)
		(width 0.0889)
		(layer "In4.Cu")
		(net "M_J_CPU1_SB_CB<4>")
	)
	(segment
		(start 164.341302 -271.71015)
		(end 166.3573 -271.71015)
		(width 0.14478)
		(layer "In4.Cu")
		(net "M_J_CPU1_SB_CB<4>")
	)
	(segment
		(start 143.377666 -269.548864)
		(end 143.386048 -269.55369)
		(width 0.0889)
		(layer "In4.Cu")
		(net "M_J_CPU1_SB_CB<4>")
	)
	(segment
		(start 142.803372 -269.55369)
		(end 142.811754 -269.548864)
		(width 0.0889)
		(layer "In4.Cu")
		(net "M_J_CPU1_SB_CB<4>")
	)
	(segment
		(start 144.182592 -268.761718)
		(end 144.221708 -268.738858)
		(width 0.0889)
		(layer "In4.Cu")
		(net "M_J_CPU1_SB_CB<4>")
	)
	(segment
		(start 189.474602 -270.860266)
		(end 190.749682 -272.135346)
		(width 0.14478)
		(layer "In4.Cu")
		(net "M_J_CPU1_SB_CB<4>")
	)
	(segment
		(start 139.04341 -269.55369)
		(end 139.051792 -269.548864)
		(width 0.0889)
		(layer "In4.Cu")
		(net "M_J_CPU1_SB_CB<4>")
	)
	(segment
		(start 188.216032 -271.94764)
		(end 188.44641 -271.94764)
		(width 0.14478)
		(layer "In4.Cu")
		(net "M_J_CPU1_SB_CB<4>")
	)
	(segment
		(start 169.690288 -270.860266)
		(end 170.540172 -271.71015)
		(width 0.14478)
		(layer "In4.Cu")
		(net "M_J_CPU1_SB_CB<4>")
	)
	(segment
		(start 188.609478 -271.023334)
		(end 188.772546 -270.860266)
		(width 0.14478)
		(layer "In4.Cu")
		(net "M_J_CPU1_SB_CB<4>")
	)
	(segment
		(start 159.942276 -267.311124)
		(end 164.341302 -271.71015)
		(width 0.14478)
		(layer "In4.Cu")
		(net "M_J_CPU1_SB_CB<4>")
	)
	(segment
		(start 188.44641 -271.94764)
		(end 188.609478 -271.784572)
		(width 0.14478)
		(layer "In4.Cu")
		(net "M_J_CPU1_SB_CB<4>")
	)
	(segment
		(start 133.224778 -269.226284)
		(end 133.070854 -269.491714)
		(width 0.0889)
		(layer "In4.Cu")
		(net "M_J_CPU1_SB_CB<4>")
	)
	(segment
		(start 188.772546 -270.860266)
		(end 189.474602 -270.860266)
		(width 0.14478)
		(layer "In4.Cu")
		(net "M_J_CPU1_SB_CB<4>")
	)
	(segment
		(start 146.9517 -267.311124)
		(end 147.992084 -267.311124)
		(width 0.0889)
		(layer "In4.Cu")
		(net "M_J_CPU1_SB_CB<4>")
	)
	(segment
		(start 134.917688 -269.548864)
		(end 134.92607 -269.55369)
		(width 0.0889)
		(layer "In4.Cu")
		(net "M_J_CPU1_SB_CB<4>")
	)
	(segment
		(start 139.617704 -269.548864)
		(end 139.626086 -269.55369)
		(width 0.0889)
		(layer "In4.Cu")
		(net "M_J_CPU1_SB_CB<4>")
	)
	(segment
		(start 138.103356 -269.55369)
		(end 138.111738 -269.548864)
		(width 0.0889)
		(layer "In4.Cu")
		(net "M_J_CPU1_SB_CB<4>")
	)
	(segment
		(start 173.908974 -271.71015)
		(end 174.758858 -270.860266)
		(width 0.14478)
		(layer "In4.Cu")
		(net "M_J_CPU1_SB_CB<4>")
	)
	(segment
		(start 188.052964 -271.023334)
		(end 188.052964 -271.784572)
		(width 0.14478)
		(layer "In4.Cu")
		(net "M_J_CPU1_SB_CB<4>")
	)
	(arc
		(start 141.497812 -269.548864)
		(mid 141.684756 -269.599119)
		(end 141.8717 -269.548864)
		(width 0.0889)
		(layer "In4.Cu")
		(net "M_J_CPU1_SB_CB<4>")
	)
	(arc
		(start 133.093206 -269.575026)
		(mid 133.255395 -269.597761)
		(end 133.411722 -269.548864)
		(width 0.0889)
		(layer "In4.Cu")
		(net "M_J_CPU1_SB_CB<4>")
	)
	(arc
		(start 143.782288 -269.531084)
		(mid 143.897715 -269.397708)
		(end 143.93926 -269.226284)
		(width 0.0889)
		(layer "In4.Cu")
		(net "M_J_CPU1_SB_CB<4>")
	)
	(arc
		(start 144.221708 -268.738858)
		(mid 144.504664 -268.662681)
		(end 144.78762 -268.738858)
		(width 0.0889)
		(layer "In4.Cu")
		(net "M_J_CPU1_SB_CB<4>")
	)
	(arc
		(start 134.351776 -269.548864)
		(mid 134.634732 -269.472687)
		(end 134.917688 -269.548864)
		(width 0.0889)
		(layer "In4.Cu")
		(net "M_J_CPU1_SB_CB<4>")
	)
	(arc
		(start 136.231884 -269.548864)
		(mid 136.51484 -269.472687)
		(end 136.797796 -269.548864)
		(width 0.0889)
		(layer "In4.Cu")
		(net "M_J_CPU1_SB_CB<4>")
	)
	(arc
		(start 135.29183 -269.548864)
		(mid 135.574786 -269.472687)
		(end 135.857742 -269.548864)
		(width 0.0889)
		(layer "In4.Cu")
		(net "M_J_CPU1_SB_CB<4>")
	)
	(arc
		(start 133.977634 -269.548864)
		(mid 134.159885 -269.599214)
		(end 134.343394 -269.55369)
		(width 0.0889)
		(layer "In4.Cu")
		(net "M_J_CPU1_SB_CB<4>")
	)
	(arc
		(start 139.626086 -269.55369)
		(mid 139.809594 -269.599184)
		(end 139.991846 -269.548864)
		(width 0.0889)
		(layer "In4.Cu")
		(net "M_J_CPU1_SB_CB<4>")
	)
	(arc
		(start 139.991846 -269.548864)
		(mid 140.274802 -269.472687)
		(end 140.557758 -269.548864)
		(width 0.0889)
		(layer "In4.Cu")
		(net "M_J_CPU1_SB_CB<4>")
	)
	(arc
		(start 143.386048 -269.55369)
		(mid 143.569556 -269.599184)
		(end 143.751808 -269.548864)
		(width 0.0889)
		(layer "In4.Cu")
		(net "M_J_CPU1_SB_CB<4>")
	)
	(arc
		(start 134.92607 -269.55369)
		(mid 135.109578 -269.599184)
		(end 135.29183 -269.548864)
		(width 0.0889)
		(layer "In4.Cu")
		(net "M_J_CPU1_SB_CB<4>")
	)
	(arc
		(start 139.051792 -269.548864)
		(mid 139.334748 -269.472687)
		(end 139.617704 -269.548864)
		(width 0.0889)
		(layer "In4.Cu")
		(net "M_J_CPU1_SB_CB<4>")
	)
	(arc
		(start 143.93926 -269.226284)
		(mid 144.003775 -268.964065)
		(end 144.182592 -268.761718)
		(width 0.0889)
		(layer "In4.Cu")
		(net "M_J_CPU1_SB_CB<4>")
	)
	(arc
		(start 138.67765 -269.548864)
		(mid 138.859901 -269.599214)
		(end 139.04341 -269.55369)
		(width 0.0889)
		(layer "In4.Cu")
		(net "M_J_CPU1_SB_CB<4>")
	)
	(arc
		(start 142.437612 -269.548864)
		(mid 142.619863 -269.599214)
		(end 142.803372 -269.55369)
		(width 0.0889)
		(layer "In4.Cu")
		(net "M_J_CPU1_SB_CB<4>")
	)
	(arc
		(start 140.56614 -269.55369)
		(mid 140.749648 -269.599184)
		(end 140.9319 -269.548864)
		(width 0.0889)
		(layer "In4.Cu")
		(net "M_J_CPU1_SB_CB<4>")
	)
	(arc
		(start 135.866124 -269.55369)
		(mid 136.049632 -269.599184)
		(end 136.231884 -269.548864)
		(width 0.0889)
		(layer "In4.Cu")
		(net "M_J_CPU1_SB_CB<4>")
	)
	(arc
		(start 141.8717 -269.548864)
		(mid 142.154656 -269.472687)
		(end 142.437612 -269.548864)
		(width 0.0889)
		(layer "In4.Cu")
		(net "M_J_CPU1_SB_CB<4>")
	)
	(arc
		(start 144.78762 -268.738858)
		(mid 145.023089 -268.786103)
		(end 145.23847 -268.67993)
		(width 0.0889)
		(layer "In4.Cu")
		(net "M_J_CPU1_SB_CB<4>")
	)
	(arc
		(start 137.171684 -269.548864)
		(mid 137.45464 -269.472687)
		(end 137.737596 -269.548864)
		(width 0.0889)
		(layer "In4.Cu")
		(net "M_J_CPU1_SB_CB<4>")
	)
	(arc
		(start 142.811754 -269.548864)
		(mid 143.09471 -269.472687)
		(end 143.377666 -269.548864)
		(width 0.0889)
		(layer "In4.Cu")
		(net "M_J_CPU1_SB_CB<4>")
	)
	(arc
		(start 140.9319 -269.548864)
		(mid 141.214856 -269.472687)
		(end 141.497812 -269.548864)
		(width 0.0889)
		(layer "In4.Cu")
		(net "M_J_CPU1_SB_CB<4>")
	)
	(arc
		(start 136.797796 -269.548864)
		(mid 136.98474 -269.599119)
		(end 137.171684 -269.548864)
		(width 0.0889)
		(layer "In4.Cu")
		(net "M_J_CPU1_SB_CB<4>")
	)
	(arc
		(start 137.737596 -269.548864)
		(mid 137.919847 -269.599214)
		(end 138.103356 -269.55369)
		(width 0.0889)
		(layer "In4.Cu")
		(net "M_J_CPU1_SB_CB<4>")
	)
	(arc
		(start 138.111738 -269.548864)
		(mid 138.394694 -269.472687)
		(end 138.67765 -269.548864)
		(width 0.0889)
		(layer "In4.Cu")
		(net "M_J_CPU1_SB_CB<4>")
	)
	(arc
		(start 133.411722 -269.548864)
		(mid 133.694678 -269.472687)
		(end 133.977634 -269.548864)
		(width 0.0889)
		(layer "In4.Cu")
		(net "M_J_CPU1_SB_CB<4>")
	)
	(segment
		(start 130.877818 -273.820382)
		(end 131.34467 -274.08632)
		(width 0.10668)
		(layer "F.Cu")
		(net "M_J_CPU1_SB_CB<3>")
	)
	(segment
		(start 143.751808 -273.76374)
		(end 143.762222 -273.769836)
		(width 0.0889)
		(layer "In4.Cu")
		(net "M_J_CPU1_SB_CB<3>")
	)
	(segment
		(start 160.134046 -277.236174)
		(end 160.134046 -277.464774)
		(width 0.14478)
		(layer "In4.Cu")
		(net "M_J_CPU1_SB_CB<3>")
	)
	(segment
		(start 159.443166 -275.81479)
		(end 159.60471 -275.976334)
		(width 0.14478)
		(layer "In4.Cu")
		(net "M_J_CPU1_SB_CB<3>")
	)
	(segment
		(start 138.103356 -273.758914)
		(end 138.111738 -273.76374)
		(width 0.0889)
		(layer "In4.Cu")
		(net "M_J_CPU1_SB_CB<3>")
	)
	(segment
		(start 178.511454 -281.060398)
		(end 180.923184 -281.060398)
		(width 0.14478)
		(layer "In4.Cu")
		(net "M_J_CPU1_SB_CB<3>")
	)
	(segment
		(start 158.735014 -276.065742)
		(end 158.963614 -276.065742)
		(width 0.14478)
		(layer "In4.Cu")
		(net "M_J_CPU1_SB_CB<3>")
	)
	(segment
		(start 159.353758 -276.684486)
		(end 159.515302 -276.84603)
		(width 0.14478)
		(layer "In4.Cu")
		(net "M_J_CPU1_SB_CB<3>")
	)
	(segment
		(start 131.34467 -274.08632)
		(end 131.498848 -273.82089)
		(width 0.0889)
		(layer "In4.Cu")
		(net "M_J_CPU1_SB_CB<3>")
	)
	(segment
		(start 171.032678 -281.060398)
		(end 173.69409 -281.060398)
		(width 0.14478)
		(layer "In4.Cu")
		(net "M_J_CPU1_SB_CB<3>")
	)
	(segment
		(start 142.803372 -273.758914)
		(end 142.811754 -273.76374)
		(width 0.0889)
		(layer "In4.Cu")
		(net "M_J_CPU1_SB_CB<3>")
	)
	(segment
		(start 146.974052 -272.492724)
		(end 147.348702 -272.492724)
		(width 0.0889)
		(layer "In4.Cu")
		(net "M_J_CPU1_SB_CB<3>")
	)
	(segment
		(start 144.684242 -273.758914)
		(end 144.692624 -273.76374)
		(width 0.0889)
		(layer "In4.Cu")
		(net "M_J_CPU1_SB_CB<3>")
	)
	(segment
		(start 160.775142 -277.375366)
		(end 161.003742 -277.375366)
		(width 0.14478)
		(layer "In4.Cu")
		(net "M_J_CPU1_SB_CB<3>")
	)
	(segment
		(start 159.60471 -275.976334)
		(end 159.60471 -276.204934)
		(width 0.14478)
		(layer "In4.Cu")
		(net "M_J_CPU1_SB_CB<3>")
	)
	(segment
		(start 147.457922 -272.383504)
		(end 148.025104 -272.383504)
		(width 0.0889)
		(layer "In4.Cu")
		(net "M_J_CPU1_SB_CB<3>")
	)
	(segment
		(start 134.917688 -273.76374)
		(end 134.92607 -273.758914)
		(width 0.0889)
		(layer "In4.Cu")
		(net "M_J_CPU1_SB_CB<3>")
	)
	(segment
		(start 147.348702 -272.492724)
		(end 147.457922 -272.383504)
		(width 0.0889)
		(layer "In4.Cu")
		(net "M_J_CPU1_SB_CB<3>")
	)
	(segment
		(start 148.025104 -272.383504)
		(end 155.052776 -272.383504)
		(width 0.14478)
		(layer "In4.Cu")
		(net "M_J_CPU1_SB_CB<3>")
	)
	(segment
		(start 140.557758 -273.76374)
		(end 140.56614 -273.758914)
		(width 0.0889)
		(layer "In4.Cu")
		(net "M_J_CPU1_SB_CB<3>")
	)
	(segment
		(start 159.214566 -275.81479)
		(end 159.443166 -275.81479)
		(width 0.14478)
		(layer "In4.Cu")
		(net "M_J_CPU1_SB_CB<3>")
	)
	(segment
		(start 132.09778 -273.76374)
		(end 132.106162 -273.758914)
		(width 0.0889)
		(layer "In4.Cu")
		(net "M_J_CPU1_SB_CB<3>")
	)
	(segment
		(start 173.69409 -281.060398)
		(end 174.544228 -280.21026)
		(width 0.14478)
		(layer "In4.Cu")
		(net "M_J_CPU1_SB_CB<3>")
	)
	(segment
		(start 135.857742 -273.76374)
		(end 135.866124 -273.758914)
		(width 0.0889)
		(layer "In4.Cu")
		(net "M_J_CPU1_SB_CB<3>")
	)
	(segment
		(start 186.635136 -280.21026)
		(end 187.060078 -280.635202)
		(width 0.14478)
		(layer "In4.Cu")
		(net "M_J_CPU1_SB_CB<3>")
	)
	(segment
		(start 177.661316 -280.21026)
		(end 178.511454 -281.060398)
		(width 0.14478)
		(layer "In4.Cu")
		(net "M_J_CPU1_SB_CB<3>")
	)
	(segment
		(start 159.353758 -276.455886)
		(end 159.353758 -276.684486)
		(width 0.14478)
		(layer "In4.Cu")
		(net "M_J_CPU1_SB_CB<3>")
	)
	(segment
		(start 155.052776 -272.383504)
		(end 158.735014 -276.065742)
		(width 0.14478)
		(layer "In4.Cu")
		(net "M_J_CPU1_SB_CB<3>")
	)
	(segment
		(start 174.544228 -280.21026)
		(end 177.661316 -280.21026)
		(width 0.14478)
		(layer "In4.Cu")
		(net "M_J_CPU1_SB_CB<3>")
	)
	(segment
		(start 160.134046 -277.464774)
		(end 160.29559 -277.626318)
		(width 0.14478)
		(layer "In4.Cu")
		(net "M_J_CPU1_SB_CB<3>")
	)
	(segment
		(start 160.223454 -276.595078)
		(end 160.384998 -276.756622)
		(width 0.14478)
		(layer "In4.Cu")
		(net "M_J_CPU1_SB_CB<3>")
	)
	(segment
		(start 160.384998 -276.985222)
		(end 160.134046 -277.236174)
		(width 0.14478)
		(layer "In4.Cu")
		(net "M_J_CPU1_SB_CB<3>")
	)
	(segment
		(start 167.000174 -280.21026)
		(end 170.18254 -280.21026)
		(width 0.14478)
		(layer "In4.Cu")
		(net "M_J_CPU1_SB_CB<3>")
	)
	(segment
		(start 159.743902 -276.84603)
		(end 159.994854 -276.595078)
		(width 0.14478)
		(layer "In4.Cu")
		(net "M_J_CPU1_SB_CB<3>")
	)
	(segment
		(start 170.18254 -280.21026)
		(end 171.032678 -281.060398)
		(width 0.14478)
		(layer "In4.Cu")
		(net "M_J_CPU1_SB_CB<3>")
	)
	(segment
		(start 143.377666 -273.76374)
		(end 143.386048 -273.758914)
		(width 0.0889)
		(layer "In4.Cu")
		(net "M_J_CPU1_SB_CB<3>")
	)
	(segment
		(start 160.52419 -277.626318)
		(end 160.775142 -277.375366)
		(width 0.14478)
		(layer "In4.Cu")
		(net "M_J_CPU1_SB_CB<3>")
	)
	(segment
		(start 166.150036 -281.060398)
		(end 167.000174 -280.21026)
		(width 0.14478)
		(layer "In4.Cu")
		(net "M_J_CPU1_SB_CB<3>")
	)
	(segment
		(start 161.003742 -277.375366)
		(end 164.688774 -281.060398)
		(width 0.14478)
		(layer "In4.Cu")
		(net "M_J_CPU1_SB_CB<3>")
	)
	(segment
		(start 159.60471 -276.204934)
		(end 159.353758 -276.455886)
		(width 0.14478)
		(layer "In4.Cu")
		(net "M_J_CPU1_SB_CB<3>")
	)
	(segment
		(start 164.688774 -281.060398)
		(end 166.150036 -281.060398)
		(width 0.14478)
		(layer "In4.Cu")
		(net "M_J_CPU1_SB_CB<3>")
	)
	(segment
		(start 131.498848 -273.82089)
		(end 131.595114 -273.79549)
		(width 0.0889)
		(layer "In4.Cu")
		(net "M_J_CPU1_SB_CB<3>")
	)
	(segment
		(start 160.384998 -276.756622)
		(end 160.384998 -276.985222)
		(width 0.14478)
		(layer "In4.Cu")
		(net "M_J_CPU1_SB_CB<3>")
	)
	(segment
		(start 145.92173 -273.545046)
		(end 146.974052 -272.492724)
		(width 0.0889)
		(layer "In4.Cu")
		(net "M_J_CPU1_SB_CB<3>")
	)
	(segment
		(start 139.617704 -273.76374)
		(end 139.626086 -273.758914)
		(width 0.0889)
		(layer "In4.Cu")
		(net "M_J_CPU1_SB_CB<3>")
	)
	(segment
		(start 158.963614 -276.065742)
		(end 159.214566 -275.81479)
		(width 0.14478)
		(layer "In4.Cu")
		(net "M_J_CPU1_SB_CB<3>")
	)
	(segment
		(start 139.04341 -273.758914)
		(end 139.051792 -273.76374)
		(width 0.0889)
		(layer "In4.Cu")
		(net "M_J_CPU1_SB_CB<3>")
	)
	(segment
		(start 159.994854 -276.595078)
		(end 160.223454 -276.595078)
		(width 0.14478)
		(layer "In4.Cu")
		(net "M_J_CPU1_SB_CB<3>")
	)
	(segment
		(start 134.343394 -273.758914)
		(end 134.351776 -273.76374)
		(width 0.0889)
		(layer "In4.Cu")
		(net "M_J_CPU1_SB_CB<3>")
	)
	(segment
		(start 180.923184 -281.060398)
		(end 181.773322 -280.21026)
		(width 0.14478)
		(layer "In4.Cu")
		(net "M_J_CPU1_SB_CB<3>")
	)
	(segment
		(start 159.515302 -276.84603)
		(end 159.743902 -276.84603)
		(width 0.14478)
		(layer "In4.Cu")
		(net "M_J_CPU1_SB_CB<3>")
	)
	(segment
		(start 181.773322 -280.21026)
		(end 186.635136 -280.21026)
		(width 0.14478)
		(layer "In4.Cu")
		(net "M_J_CPU1_SB_CB<3>")
	)
	(segment
		(start 160.29559 -277.626318)
		(end 160.52419 -277.626318)
		(width 0.14478)
		(layer "In4.Cu")
		(net "M_J_CPU1_SB_CB<3>")
	)
	(arc
		(start 144.317974 -273.76374)
		(mid 144.500479 -273.713263)
		(end 144.684242 -273.758914)
		(width 0.0889)
		(layer "In4.Cu")
		(net "M_J_CPU1_SB_CB<3>")
	)
	(arc
		(start 145.444718 -273.71294)
		(mid 145.697563 -273.669737)
		(end 145.92173 -273.545046)
		(width 0.0889)
		(layer "In4.Cu")
		(net "M_J_CPU1_SB_CB<3>")
	)
	(arc
		(start 140.9319 -273.76374)
		(mid 141.214856 -273.839917)
		(end 141.497812 -273.76374)
		(width 0.0889)
		(layer "In4.Cu")
		(net "M_J_CPU1_SB_CB<3>")
	)
	(arc
		(start 133.977634 -273.76374)
		(mid 134.159885 -273.71339)
		(end 134.343394 -273.758914)
		(width 0.0889)
		(layer "In4.Cu")
		(net "M_J_CPU1_SB_CB<3>")
	)
	(arc
		(start 132.471922 -273.76374)
		(mid 132.754878 -273.839917)
		(end 133.037834 -273.76374)
		(width 0.0889)
		(layer "In4.Cu")
		(net "M_J_CPU1_SB_CB<3>")
	)
	(arc
		(start 137.737596 -273.76374)
		(mid 137.919847 -273.71339)
		(end 138.103356 -273.758914)
		(width 0.0889)
		(layer "In4.Cu")
		(net "M_J_CPU1_SB_CB<3>")
	)
	(arc
		(start 136.231884 -273.76374)
		(mid 136.51484 -273.839917)
		(end 136.797796 -273.76374)
		(width 0.0889)
		(layer "In4.Cu")
		(net "M_J_CPU1_SB_CB<3>")
	)
	(arc
		(start 131.595114 -273.79549)
		(mid 131.850179 -273.838841)
		(end 132.09778 -273.76374)
		(width 0.0889)
		(layer "In4.Cu")
		(net "M_J_CPU1_SB_CB<3>")
	)
	(arc
		(start 139.051792 -273.76374)
		(mid 139.334748 -273.839917)
		(end 139.617704 -273.76374)
		(width 0.0889)
		(layer "In4.Cu")
		(net "M_J_CPU1_SB_CB<3>")
	)
	(arc
		(start 138.67765 -273.76374)
		(mid 138.859901 -273.71339)
		(end 139.04341 -273.758914)
		(width 0.0889)
		(layer "In4.Cu")
		(net "M_J_CPU1_SB_CB<3>")
	)
	(arc
		(start 141.8717 -273.76374)
		(mid 142.154656 -273.839917)
		(end 142.437612 -273.76374)
		(width 0.0889)
		(layer "In4.Cu")
		(net "M_J_CPU1_SB_CB<3>")
	)
	(arc
		(start 135.29183 -273.76374)
		(mid 135.574786 -273.839917)
		(end 135.857742 -273.76374)
		(width 0.0889)
		(layer "In4.Cu")
		(net "M_J_CPU1_SB_CB<3>")
	)
	(arc
		(start 138.111738 -273.76374)
		(mid 138.394694 -273.839917)
		(end 138.67765 -273.76374)
		(width 0.0889)
		(layer "In4.Cu")
		(net "M_J_CPU1_SB_CB<3>")
	)
	(arc
		(start 143.762222 -273.769836)
		(mid 144.040908 -273.840056)
		(end 144.317974 -273.76374)
		(width 0.0889)
		(layer "In4.Cu")
		(net "M_J_CPU1_SB_CB<3>")
	)
	(arc
		(start 133.411722 -273.76374)
		(mid 133.694678 -273.839917)
		(end 133.977634 -273.76374)
		(width 0.0889)
		(layer "In4.Cu")
		(net "M_J_CPU1_SB_CB<3>")
	)
	(arc
		(start 143.386048 -273.758914)
		(mid 143.569556 -273.71342)
		(end 143.751808 -273.76374)
		(width 0.0889)
		(layer "In4.Cu")
		(net "M_J_CPU1_SB_CB<3>")
	)
	(arc
		(start 133.037834 -273.76374)
		(mid 133.224778 -273.713485)
		(end 133.411722 -273.76374)
		(width 0.0889)
		(layer "In4.Cu")
		(net "M_J_CPU1_SB_CB<3>")
	)
	(arc
		(start 145.25244 -273.767296)
		(mid 145.344872 -273.727014)
		(end 145.444718 -273.71294)
		(width 0.0889)
		(layer "In4.Cu")
		(net "M_J_CPU1_SB_CB<3>")
	)
	(arc
		(start 134.351776 -273.76374)
		(mid 134.634732 -273.839917)
		(end 134.917688 -273.76374)
		(width 0.0889)
		(layer "In4.Cu")
		(net "M_J_CPU1_SB_CB<3>")
	)
	(arc
		(start 135.866124 -273.758914)
		(mid 136.049632 -273.71342)
		(end 136.231884 -273.76374)
		(width 0.0889)
		(layer "In4.Cu")
		(net "M_J_CPU1_SB_CB<3>")
	)
	(arc
		(start 136.797796 -273.76374)
		(mid 136.98474 -273.713485)
		(end 137.171684 -273.76374)
		(width 0.0889)
		(layer "In4.Cu")
		(net "M_J_CPU1_SB_CB<3>")
	)
	(arc
		(start 132.106162 -273.758914)
		(mid 132.28967 -273.71342)
		(end 132.471922 -273.76374)
		(width 0.0889)
		(layer "In4.Cu")
		(net "M_J_CPU1_SB_CB<3>")
	)
	(arc
		(start 134.92607 -273.758914)
		(mid 135.109578 -273.71342)
		(end 135.29183 -273.76374)
		(width 0.0889)
		(layer "In4.Cu")
		(net "M_J_CPU1_SB_CB<3>")
	)
	(arc
		(start 142.437612 -273.76374)
		(mid 142.619863 -273.71339)
		(end 142.803372 -273.758914)
		(width 0.0889)
		(layer "In4.Cu")
		(net "M_J_CPU1_SB_CB<3>")
	)
	(arc
		(start 139.991846 -273.76374)
		(mid 140.274802 -273.839917)
		(end 140.557758 -273.76374)
		(width 0.0889)
		(layer "In4.Cu")
		(net "M_J_CPU1_SB_CB<3>")
	)
	(arc
		(start 144.692624 -273.76374)
		(mid 144.972052 -273.839906)
		(end 145.25244 -273.767296)
		(width 0.0889)
		(layer "In4.Cu")
		(net "M_J_CPU1_SB_CB<3>")
	)
	(arc
		(start 141.497812 -273.76374)
		(mid 141.684756 -273.713485)
		(end 141.8717 -273.76374)
		(width 0.0889)
		(layer "In4.Cu")
		(net "M_J_CPU1_SB_CB<3>")
	)
	(arc
		(start 142.811754 -273.76374)
		(mid 143.09471 -273.839917)
		(end 143.377666 -273.76374)
		(width 0.0889)
		(layer "In4.Cu")
		(net "M_J_CPU1_SB_CB<3>")
	)
	(arc
		(start 137.171684 -273.76374)
		(mid 137.45464 -273.839917)
		(end 137.737596 -273.76374)
		(width 0.0889)
		(layer "In4.Cu")
		(net "M_J_CPU1_SB_CB<3>")
	)
	(arc
		(start 139.626086 -273.758914)
		(mid 139.809594 -273.71342)
		(end 139.991846 -273.76374)
		(width 0.0889)
		(layer "In4.Cu")
		(net "M_J_CPU1_SB_CB<3>")
	)
	(arc
		(start 140.56614 -273.758914)
		(mid 140.749648 -273.71342)
		(end 140.9319 -273.76374)
		(width 0.0889)
		(layer "In4.Cu")
		(net "M_J_CPU1_SB_CB<3>")
	)
	(segment
		(start 132.287772 -273.010376)
		(end 132.754878 -273.276314)
		(width 0.10668)
		(layer "F.Cu")
		(net "M_J_CPU1_SB_CB<2>")
	)
	(segment
		(start 140.453364 -272.948908)
		(end 140.461746 -272.953734)
		(width 0.0889)
		(layer "In4.Cu")
		(net "M_J_CPU1_SB_CB<2>")
	)
	(segment
		(start 158.878778 -273.957542)
		(end 158.878778 -274.186142)
		(width 0.14478)
		(layer "In4.Cu")
		(net "M_J_CPU1_SB_CB<2>")
	)
	(segment
		(start 186.634882 -278.510238)
		(end 187.060078 -278.935434)
		(width 0.14478)
		(layer "In4.Cu")
		(net "M_J_CPU1_SB_CB<2>")
	)
	(segment
		(start 136.693402 -272.948908)
		(end 136.701784 -272.953734)
		(width 0.0889)
		(layer "In4.Cu")
		(net "M_J_CPU1_SB_CB<2>")
	)
	(segment
		(start 157.708346 -273.01571)
		(end 157.936946 -273.01571)
		(width 0.14478)
		(layer "In4.Cu")
		(net "M_J_CPU1_SB_CB<2>")
	)
	(segment
		(start 157.318202 -272.625566)
		(end 157.056836 -272.886932)
		(width 0.14478)
		(layer "In4.Cu")
		(net "M_J_CPU1_SB_CB<2>")
	)
	(segment
		(start 159.268922 -274.576286)
		(end 159.497522 -274.576286)
		(width 0.14478)
		(layer "In4.Cu")
		(net "M_J_CPU1_SB_CB<2>")
	)
	(segment
		(start 157.998668 -274.057364)
		(end 158.227268 -274.057364)
		(width 0.14478)
		(layer "In4.Cu")
		(net "M_J_CPU1_SB_CB<2>")
	)
	(segment
		(start 158.488634 -273.795998)
		(end 158.717234 -273.795998)
		(width 0.14478)
		(layer "In4.Cu")
		(net "M_J_CPU1_SB_CB<2>")
	)
	(segment
		(start 158.227268 -274.057364)
		(end 158.488634 -273.795998)
		(width 0.14478)
		(layer "In4.Cu")
		(net "M_J_CPU1_SB_CB<2>")
	)
	(segment
		(start 158.617412 -274.676108)
		(end 158.778956 -274.837652)
		(width 0.14478)
		(layer "In4.Cu")
		(net "M_J_CPU1_SB_CB<2>")
	)
	(segment
		(start 158.878778 -274.186142)
		(end 158.617412 -274.447508)
		(width 0.14478)
		(layer "In4.Cu")
		(net "M_J_CPU1_SB_CB<2>")
	)
	(segment
		(start 157.837124 -273.89582)
		(end 157.998668 -274.057364)
		(width 0.14478)
		(layer "In4.Cu")
		(net "M_J_CPU1_SB_CB<2>")
	)
	(segment
		(start 141.393418 -272.948908)
		(end 141.4018 -272.953734)
		(width 0.0889)
		(layer "In4.Cu")
		(net "M_J_CPU1_SB_CB<2>")
	)
	(segment
		(start 163.162742 -277.296626)
		(end 165.226492 -279.360376)
		(width 0.14478)
		(layer "In4.Cu")
		(net "M_J_CPU1_SB_CB<2>")
	)
	(segment
		(start 157.318202 -272.396966)
		(end 157.318202 -272.625566)
		(width 0.14478)
		(layer "In4.Cu")
		(net "M_J_CPU1_SB_CB<2>")
	)
	(segment
		(start 144.20088 -272.942558)
		(end 144.220946 -272.953988)
		(width 0.0889)
		(layer "In4.Cu")
		(net "M_J_CPU1_SB_CB<2>")
	)
	(segment
		(start 158.717234 -273.795998)
		(end 158.878778 -273.957542)
		(width 0.14478)
		(layer "In4.Cu")
		(net "M_J_CPU1_SB_CB<2>")
	)
	(segment
		(start 158.617412 -274.447508)
		(end 158.617412 -274.676108)
		(width 0.14478)
		(layer "In4.Cu")
		(net "M_J_CPU1_SB_CB<2>")
	)
	(segment
		(start 157.936946 -273.01571)
		(end 158.09849 -273.177254)
		(width 0.14478)
		(layer "In4.Cu")
		(net "M_J_CPU1_SB_CB<2>")
	)
	(segment
		(start 158.09849 -273.177254)
		(end 158.09849 -273.405854)
		(width 0.14478)
		(layer "In4.Cu")
		(net "M_J_CPU1_SB_CB<2>")
	)
	(segment
		(start 132.908802 -273.010884)
		(end 133.004814 -272.985484)
		(width 0.0889)
		(layer "In4.Cu")
		(net "M_J_CPU1_SB_CB<2>")
	)
	(segment
		(start 173.69409 -279.360376)
		(end 174.544228 -278.510238)
		(width 0.14478)
		(layer "In4.Cu")
		(net "M_J_CPU1_SB_CB<2>")
	)
	(segment
		(start 156.276548 -272.335244)
		(end 156.438092 -272.496788)
		(width 0.14478)
		(layer "In4.Cu")
		(net "M_J_CPU1_SB_CB<2>")
	)
	(segment
		(start 157.44698 -273.277076)
		(end 157.708346 -273.01571)
		(width 0.14478)
		(layer "In4.Cu")
		(net "M_J_CPU1_SB_CB<2>")
	)
	(segment
		(start 162.217862 -277.296626)
		(end 163.162742 -277.296626)
		(width 0.14478)
		(layer "In4.Cu")
		(net "M_J_CPU1_SB_CB<2>")
	)
	(segment
		(start 156.438092 -272.496788)
		(end 156.666692 -272.496788)
		(width 0.14478)
		(layer "In4.Cu")
		(net "M_J_CPU1_SB_CB<2>")
	)
	(segment
		(start 158.778956 -274.837652)
		(end 159.007556 -274.837652)
		(width 0.14478)
		(layer "In4.Cu")
		(net "M_J_CPU1_SB_CB<2>")
	)
	(segment
		(start 167.000174 -278.510238)
		(end 169.885868 -278.510238)
		(width 0.14478)
		(layer "In4.Cu")
		(net "M_J_CPU1_SB_CB<2>")
	)
	(segment
		(start 144.785334 -272.953734)
		(end 144.80413 -272.942812)
		(width 0.0889)
		(layer "In4.Cu")
		(net "M_J_CPU1_SB_CB<2>")
	)
	(segment
		(start 156.39542 -271.474184)
		(end 156.537914 -271.616678)
		(width 0.14478)
		(layer "In4.Cu")
		(net "M_J_CPU1_SB_CB<2>")
	)
	(segment
		(start 156.537914 -271.616678)
		(end 156.537914 -271.845278)
		(width 0.14478)
		(layer "In4.Cu")
		(net "M_J_CPU1_SB_CB<2>")
	)
	(segment
		(start 157.156658 -272.235422)
		(end 157.318202 -272.396966)
		(width 0.14478)
		(layer "In4.Cu")
		(net "M_J_CPU1_SB_CB<2>")
	)
	(segment
		(start 178.251612 -279.360376)
		(end 181.26456 -279.360376)
		(width 0.14478)
		(layer "In4.Cu")
		(net "M_J_CPU1_SB_CB<2>")
	)
	(segment
		(start 159.497522 -274.576286)
		(end 162.217862 -277.296626)
		(width 0.14478)
		(layer "In4.Cu")
		(net "M_J_CPU1_SB_CB<2>")
	)
	(segment
		(start 132.754878 -273.276314)
		(end 132.908802 -273.010884)
		(width 0.0889)
		(layer "In4.Cu")
		(net "M_J_CPU1_SB_CB<2>")
	)
	(segment
		(start 147.476718 -271.474184)
		(end 147.996656 -271.474184)
		(width 0.0889)
		(layer "In4.Cu")
		(net "M_J_CPU1_SB_CB<2>")
	)
	(segment
		(start 147.996656 -271.474184)
		(end 156.39542 -271.474184)
		(width 0.14478)
		(layer "In4.Cu")
		(net "M_J_CPU1_SB_CB<2>")
	)
	(segment
		(start 181.26456 -279.360376)
		(end 182.114698 -278.510238)
		(width 0.14478)
		(layer "In4.Cu")
		(net "M_J_CPU1_SB_CB<2>")
	)
	(segment
		(start 177.401474 -278.510238)
		(end 178.251612 -279.360376)
		(width 0.14478)
		(layer "In4.Cu")
		(net "M_J_CPU1_SB_CB<2>")
	)
	(segment
		(start 156.537914 -271.845278)
		(end 156.276548 -272.106644)
		(width 0.14478)
		(layer "In4.Cu")
		(net "M_J_CPU1_SB_CB<2>")
	)
	(segment
		(start 157.837124 -273.66722)
		(end 157.837124 -273.89582)
		(width 0.14478)
		(layer "In4.Cu")
		(net "M_J_CPU1_SB_CB<2>")
	)
	(segment
		(start 170.736006 -279.360376)
		(end 173.69409 -279.360376)
		(width 0.14478)
		(layer "In4.Cu")
		(net "M_J_CPU1_SB_CB<2>")
	)
	(segment
		(start 157.21838 -273.277076)
		(end 157.44698 -273.277076)
		(width 0.14478)
		(layer "In4.Cu")
		(net "M_J_CPU1_SB_CB<2>")
	)
	(segment
		(start 174.544228 -278.510238)
		(end 177.401474 -278.510238)
		(width 0.14478)
		(layer "In4.Cu")
		(net "M_J_CPU1_SB_CB<2>")
	)
	(segment
		(start 166.150036 -279.360376)
		(end 167.000174 -278.510238)
		(width 0.14478)
		(layer "In4.Cu")
		(net "M_J_CPU1_SB_CB<2>")
	)
	(segment
		(start 157.056836 -272.886932)
		(end 157.056836 -273.115532)
		(width 0.14478)
		(layer "In4.Cu")
		(net "M_J_CPU1_SB_CB<2>")
	)
	(segment
		(start 138.20775 -272.953734)
		(end 138.216132 -272.948908)
		(width 0.0889)
		(layer "In4.Cu")
		(net "M_J_CPU1_SB_CB<2>")
	)
	(segment
		(start 144.220946 -272.953988)
		(end 144.242536 -272.966434)
		(width 0.0889)
		(layer "In4.Cu")
		(net "M_J_CPU1_SB_CB<2>")
	)
	(segment
		(start 156.666692 -272.496788)
		(end 156.928058 -272.235422)
		(width 0.14478)
		(layer "In4.Cu")
		(net "M_J_CPU1_SB_CB<2>")
	)
	(segment
		(start 141.967712 -272.953734)
		(end 141.976094 -272.948908)
		(width 0.0889)
		(layer "In4.Cu")
		(net "M_J_CPU1_SB_CB<2>")
	)
	(segment
		(start 165.226492 -279.360376)
		(end 166.150036 -279.360376)
		(width 0.14478)
		(layer "In4.Cu")
		(net "M_J_CPU1_SB_CB<2>")
	)
	(segment
		(start 133.507734 -272.953734)
		(end 133.516116 -272.948908)
		(width 0.0889)
		(layer "In4.Cu")
		(net "M_J_CPU1_SB_CB<2>")
	)
	(segment
		(start 157.056836 -273.115532)
		(end 157.21838 -273.277076)
		(width 0.14478)
		(layer "In4.Cu")
		(net "M_J_CPU1_SB_CB<2>")
	)
	(segment
		(start 182.114698 -278.510238)
		(end 186.634882 -278.510238)
		(width 0.14478)
		(layer "In4.Cu")
		(net "M_J_CPU1_SB_CB<2>")
	)
	(segment
		(start 137.267696 -272.953734)
		(end 137.276078 -272.948908)
		(width 0.0889)
		(layer "In4.Cu")
		(net "M_J_CPU1_SB_CB<2>")
	)
	(segment
		(start 156.276548 -272.106644)
		(end 156.276548 -272.335244)
		(width 0.14478)
		(layer "In4.Cu")
		(net "M_J_CPU1_SB_CB<2>")
	)
	(segment
		(start 159.007556 -274.837652)
		(end 159.268922 -274.576286)
		(width 0.14478)
		(layer "In4.Cu")
		(net "M_J_CPU1_SB_CB<2>")
	)
	(segment
		(start 158.09849 -273.405854)
		(end 157.837124 -273.66722)
		(width 0.14478)
		(layer "In4.Cu")
		(net "M_J_CPU1_SB_CB<2>")
	)
	(segment
		(start 147.009358 -271.756124)
		(end 147.194778 -271.756124)
		(width 0.0889)
		(layer "In4.Cu")
		(net "M_J_CPU1_SB_CB<2>")
	)
	(segment
		(start 145.925032 -272.84045)
		(end 147.009358 -271.756124)
		(width 0.0889)
		(layer "In4.Cu")
		(net "M_J_CPU1_SB_CB<2>")
	)
	(segment
		(start 147.194778 -271.756124)
		(end 147.476718 -271.474184)
		(width 0.0889)
		(layer "In4.Cu")
		(net "M_J_CPU1_SB_CB<2>")
	)
	(segment
		(start 156.928058 -272.235422)
		(end 157.156658 -272.235422)
		(width 0.14478)
		(layer "In4.Cu")
		(net "M_J_CPU1_SB_CB<2>")
	)
	(segment
		(start 169.885868 -278.510238)
		(end 170.736006 -279.360376)
		(width 0.14478)
		(layer "In4.Cu")
		(net "M_J_CPU1_SB_CB<2>")
	)
	(segment
		(start 135.753348 -272.948908)
		(end 135.76173 -272.953734)
		(width 0.0889)
		(layer "In4.Cu")
		(net "M_J_CPU1_SB_CB<2>")
	)
	(arc
		(start 144.80413 -272.942812)
		(mid 144.983701 -272.902995)
		(end 145.160492 -272.953734)
		(width 0.0889)
		(layer "In4.Cu")
		(net "M_J_CPU1_SB_CB<2>")
	)
	(arc
		(start 133.516116 -272.948908)
		(mid 133.699624 -272.903414)
		(end 133.881876 -272.953734)
		(width 0.0889)
		(layer "In4.Cu")
		(net "M_J_CPU1_SB_CB<2>")
	)
	(arc
		(start 135.76173 -272.953734)
		(mid 136.044686 -273.029911)
		(end 136.327642 -272.953734)
		(width 0.0889)
		(layer "In4.Cu")
		(net "M_J_CPU1_SB_CB<2>")
	)
	(arc
		(start 145.6944 -272.972276)
		(mid 145.818538 -272.921797)
		(end 145.925032 -272.84045)
		(width 0.0889)
		(layer "In4.Cu")
		(net "M_J_CPU1_SB_CB<2>")
	)
	(arc
		(start 139.521692 -272.953734)
		(mid 139.804648 -273.029911)
		(end 140.087604 -272.953734)
		(width 0.0889)
		(layer "In4.Cu")
		(net "M_J_CPU1_SB_CB<2>")
	)
	(arc
		(start 141.976094 -272.948908)
		(mid 142.159602 -272.903414)
		(end 142.341854 -272.953734)
		(width 0.0889)
		(layer "In4.Cu")
		(net "M_J_CPU1_SB_CB<2>")
	)
	(arc
		(start 141.027658 -272.953734)
		(mid 141.209909 -272.903384)
		(end 141.393418 -272.948908)
		(width 0.0889)
		(layer "In4.Cu")
		(net "M_J_CPU1_SB_CB<2>")
	)
	(arc
		(start 136.327642 -272.953734)
		(mid 136.509893 -272.903384)
		(end 136.693402 -272.948908)
		(width 0.0889)
		(layer "In4.Cu")
		(net "M_J_CPU1_SB_CB<2>")
	)
	(arc
		(start 142.341854 -272.953734)
		(mid 142.62481 -273.029911)
		(end 142.907766 -272.953734)
		(width 0.0889)
		(layer "In4.Cu")
		(net "M_J_CPU1_SB_CB<2>")
	)
	(arc
		(start 135.387588 -272.953734)
		(mid 135.569839 -272.903384)
		(end 135.753348 -272.948908)
		(width 0.0889)
		(layer "In4.Cu")
		(net "M_J_CPU1_SB_CB<2>")
	)
	(arc
		(start 142.907766 -272.953734)
		(mid 143.09471 -272.903479)
		(end 143.281654 -272.953734)
		(width 0.0889)
		(layer "In4.Cu")
		(net "M_J_CPU1_SB_CB<2>")
	)
	(arc
		(start 137.641838 -272.953734)
		(mid 137.924794 -273.029911)
		(end 138.20775 -272.953734)
		(width 0.0889)
		(layer "In4.Cu")
		(net "M_J_CPU1_SB_CB<2>")
	)
	(arc
		(start 143.281654 -272.953734)
		(mid 143.56461 -273.029911)
		(end 143.847566 -272.953734)
		(width 0.0889)
		(layer "In4.Cu")
		(net "M_J_CPU1_SB_CB<2>")
	)
	(arc
		(start 145.160492 -272.953734)
		(mid 145.425115 -273.030209)
		(end 145.6944 -272.972276)
		(width 0.0889)
		(layer "In4.Cu")
		(net "M_J_CPU1_SB_CB<2>")
	)
	(arc
		(start 144.242536 -272.966434)
		(mid 144.515565 -273.029753)
		(end 144.785334 -272.953734)
		(width 0.0889)
		(layer "In4.Cu")
		(net "M_J_CPU1_SB_CB<2>")
	)
	(arc
		(start 134.821676 -272.953734)
		(mid 135.104632 -273.029911)
		(end 135.387588 -272.953734)
		(width 0.0889)
		(layer "In4.Cu")
		(net "M_J_CPU1_SB_CB<2>")
	)
	(arc
		(start 138.581892 -272.953734)
		(mid 138.864848 -273.029911)
		(end 139.147804 -272.953734)
		(width 0.0889)
		(layer "In4.Cu")
		(net "M_J_CPU1_SB_CB<2>")
	)
	(arc
		(start 136.701784 -272.953734)
		(mid 136.98474 -273.029911)
		(end 137.267696 -272.953734)
		(width 0.0889)
		(layer "In4.Cu")
		(net "M_J_CPU1_SB_CB<2>")
	)
	(arc
		(start 139.147804 -272.953734)
		(mid 139.334748 -272.903479)
		(end 139.521692 -272.953734)
		(width 0.0889)
		(layer "In4.Cu")
		(net "M_J_CPU1_SB_CB<2>")
	)
	(arc
		(start 140.461746 -272.953734)
		(mid 140.744702 -273.029911)
		(end 141.027658 -272.953734)
		(width 0.0889)
		(layer "In4.Cu")
		(net "M_J_CPU1_SB_CB<2>")
	)
	(arc
		(start 137.276078 -272.948908)
		(mid 137.459586 -272.903414)
		(end 137.641838 -272.953734)
		(width 0.0889)
		(layer "In4.Cu")
		(net "M_J_CPU1_SB_CB<2>")
	)
	(arc
		(start 133.004814 -272.985484)
		(mid 133.260022 -273.028961)
		(end 133.507734 -272.953734)
		(width 0.0889)
		(layer "In4.Cu")
		(net "M_J_CPU1_SB_CB<2>")
	)
	(arc
		(start 141.4018 -272.953734)
		(mid 141.684756 -273.029911)
		(end 141.967712 -272.953734)
		(width 0.0889)
		(layer "In4.Cu")
		(net "M_J_CPU1_SB_CB<2>")
	)
	(arc
		(start 140.087604 -272.953734)
		(mid 140.269855 -272.903384)
		(end 140.453364 -272.948908)
		(width 0.0889)
		(layer "In4.Cu")
		(net "M_J_CPU1_SB_CB<2>")
	)
	(arc
		(start 143.847566 -272.953734)
		(mid 144.022805 -272.903663)
		(end 144.20088 -272.942558)
		(width 0.0889)
		(layer "In4.Cu")
		(net "M_J_CPU1_SB_CB<2>")
	)
	(arc
		(start 138.216132 -272.948908)
		(mid 138.39964 -272.903414)
		(end 138.581892 -272.953734)
		(width 0.0889)
		(layer "In4.Cu")
		(net "M_J_CPU1_SB_CB<2>")
	)
	(arc
		(start 134.447788 -272.953734)
		(mid 134.634732 -272.903479)
		(end 134.821676 -272.953734)
		(width 0.0889)
		(layer "In4.Cu")
		(net "M_J_CPU1_SB_CB<2>")
	)
	(arc
		(start 133.881876 -272.953734)
		(mid 134.164832 -273.029911)
		(end 134.447788 -272.953734)
		(width 0.0889)
		(layer "In4.Cu")
		(net "M_J_CPU1_SB_CB<2>")
	)
	(segment
		(start 131.347972 -273.010376)
		(end 131.814824 -273.276314)
		(width 0.10668)
		(layer "F.Cu")
		(net "M_J_CPU1_SB_CB<1>")
	)
	(segment
		(start 171.53636 -280.21026)
		(end 172.99559 -280.21026)
		(width 0.14478)
		(layer "In4.Cu")
		(net "M_J_CPU1_SB_CB<1>")
	)
	(segment
		(start 131.814824 -273.276314)
		(end 131.660646 -273.541744)
		(width 0.0889)
		(layer "In4.Cu")
		(net "M_J_CPU1_SB_CB<1>")
	)
	(segment
		(start 148.025104 -271.928844)
		(end 155.234132 -271.928844)
		(width 0.14478)
		(layer "In4.Cu")
		(net "M_J_CPU1_SB_CB<1>")
	)
	(segment
		(start 165.60038 -280.37028)
		(end 166.094156 -280.37028)
		(width 0.14478)
		(layer "In4.Cu")
		(net "M_J_CPU1_SB_CB<1>")
	)
	(segment
		(start 176.900586 -279.360376)
		(end 178.952398 -280.21026)
		(width 0.14478)
		(layer "In4.Cu")
		(net "M_J_CPU1_SB_CB<1>")
	)
	(segment
		(start 145.44421 -273.522186)
		(end 145.444464 -273.522186)
		(width 0.0889)
		(layer "In4.Cu")
		(net "M_J_CPU1_SB_CB<1>")
	)
	(segment
		(start 172.99559 -280.21026)
		(end 175.047402 -279.360376)
		(width 0.14478)
		(layer "In4.Cu")
		(net "M_J_CPU1_SB_CB<1>")
	)
	(segment
		(start 180.465222 -280.21026)
		(end 182.517034 -279.360376)
		(width 0.14478)
		(layer "In4.Cu")
		(net "M_J_CPU1_SB_CB<1>")
	)
	(segment
		(start 147.455128 -271.928844)
		(end 148.025104 -271.928844)
		(width 0.0889)
		(layer "In4.Cu")
		(net "M_J_CPU1_SB_CB<1>")
	)
	(segment
		(start 135.753348 -273.60372)
		(end 135.76173 -273.598894)
		(width 0.0889)
		(layer "In4.Cu")
		(net "M_J_CPU1_SB_CB<1>")
	)
	(segment
		(start 166.094156 -280.37028)
		(end 167.10406 -279.360376)
		(width 0.14478)
		(layer "In4.Cu")
		(net "M_J_CPU1_SB_CB<1>")
	)
	(segment
		(start 169.484548 -279.360376)
		(end 171.53636 -280.21026)
		(width 0.14478)
		(layer "In4.Cu")
		(net "M_J_CPU1_SB_CB<1>")
	)
	(segment
		(start 167.10406 -279.360376)
		(end 169.484548 -279.360376)
		(width 0.14478)
		(layer "In4.Cu")
		(net "M_J_CPU1_SB_CB<1>")
	)
	(segment
		(start 131.993386 -273.60372)
		(end 132.001768 -273.598894)
		(width 0.0889)
		(layer "In4.Cu")
		(net "M_J_CPU1_SB_CB<1>")
	)
	(segment
		(start 137.267696 -273.598894)
		(end 137.276078 -273.60372)
		(width 0.0889)
		(layer "In4.Cu")
		(net "M_J_CPU1_SB_CB<1>")
	)
	(segment
		(start 147.047204 -272.149824)
		(end 147.234148 -272.149824)
		(width 0.0889)
		(layer "In4.Cu")
		(net "M_J_CPU1_SB_CB<1>")
	)
	(segment
		(start 141.393418 -273.60372)
		(end 141.4018 -273.598894)
		(width 0.0889)
		(layer "In4.Cu")
		(net "M_J_CPU1_SB_CB<1>")
	)
	(segment
		(start 141.967712 -273.598894)
		(end 141.976094 -273.60372)
		(width 0.0889)
		(layer "In4.Cu")
		(net "M_J_CPU1_SB_CB<1>")
	)
	(segment
		(start 140.453364 -273.60372)
		(end 140.461746 -273.598894)
		(width 0.0889)
		(layer "In4.Cu")
		(net "M_J_CPU1_SB_CB<1>")
	)
	(segment
		(start 159.572452 -275.287232)
		(end 162.368738 -278.083518)
		(width 0.14478)
		(layer "In4.Cu")
		(net "M_J_CPU1_SB_CB<1>")
	)
	(segment
		(start 132.93344 -273.60372)
		(end 132.941822 -273.598894)
		(width 0.0889)
		(layer "In4.Cu")
		(net "M_J_CPU1_SB_CB<1>")
	)
	(segment
		(start 162.368738 -278.083518)
		(end 163.981892 -278.751792)
		(width 0.14478)
		(layer "In4.Cu")
		(net "M_J_CPU1_SB_CB<1>")
	)
	(segment
		(start 136.693402 -273.60372)
		(end 136.701784 -273.598894)
		(width 0.0889)
		(layer "In4.Cu")
		(net "M_J_CPU1_SB_CB<1>")
	)
	(segment
		(start 131.660646 -273.541744)
		(end 131.682998 -273.625056)
		(width 0.0889)
		(layer "In4.Cu")
		(net "M_J_CPU1_SB_CB<1>")
	)
	(segment
		(start 155.234132 -271.928844)
		(end 158.59252 -275.287232)
		(width 0.14478)
		(layer "In4.Cu")
		(net "M_J_CPU1_SB_CB<1>")
	)
	(segment
		(start 144.777968 -273.592798)
		(end 144.788382 -273.598894)
		(width 0.0889)
		(layer "In4.Cu")
		(net "M_J_CPU1_SB_CB<1>")
	)
	(segment
		(start 189.023752 -279.360376)
		(end 191.160146 -279.785318)
		(width 0.14478)
		(layer "In4.Cu")
		(net "M_J_CPU1_SB_CB<1>")
	)
	(segment
		(start 143.847566 -273.598894)
		(end 143.855948 -273.60372)
		(width 0.0889)
		(layer "In4.Cu")
		(net "M_J_CPU1_SB_CB<1>")
	)
	(segment
		(start 158.59252 -275.287232)
		(end 159.572452 -275.287232)
		(width 0.14478)
		(layer "In4.Cu")
		(net "M_J_CPU1_SB_CB<1>")
	)
	(segment
		(start 138.20775 -273.598894)
		(end 138.216132 -273.60372)
		(width 0.0889)
		(layer "In4.Cu")
		(net "M_J_CPU1_SB_CB<1>")
	)
	(segment
		(start 175.047402 -279.360376)
		(end 176.900586 -279.360376)
		(width 0.14478)
		(layer "In4.Cu")
		(net "M_J_CPU1_SB_CB<1>")
	)
	(segment
		(start 163.981892 -278.751792)
		(end 165.60038 -280.37028)
		(width 0.14478)
		(layer "In4.Cu")
		(net "M_J_CPU1_SB_CB<1>")
	)
	(segment
		(start 133.507734 -273.598894)
		(end 133.516116 -273.60372)
		(width 0.0889)
		(layer "In4.Cu")
		(net "M_J_CPU1_SB_CB<1>")
	)
	(segment
		(start 182.517034 -279.360376)
		(end 189.023752 -279.360376)
		(width 0.14478)
		(layer "In4.Cu")
		(net "M_J_CPU1_SB_CB<1>")
	)
	(segment
		(start 147.234148 -272.149824)
		(end 147.455128 -271.928844)
		(width 0.0889)
		(layer "In4.Cu")
		(net "M_J_CPU1_SB_CB<1>")
	)
	(segment
		(start 178.952398 -280.21026)
		(end 180.465222 -280.21026)
		(width 0.14478)
		(layer "In4.Cu")
		(net "M_J_CPU1_SB_CB<1>")
	)
	(segment
		(start 145.79473 -273.402298)
		(end 147.047204 -272.149824)
		(width 0.0889)
		(layer "In4.Cu")
		(net "M_J_CPU1_SB_CB<1>")
	)
	(arc
		(start 133.881876 -273.598894)
		(mid 134.164832 -273.522717)
		(end 134.447788 -273.598894)
		(width 0.0889)
		(layer "In4.Cu")
		(net "M_J_CPU1_SB_CB<1>")
	)
	(arc
		(start 136.327642 -273.598894)
		(mid 136.509893 -273.649244)
		(end 136.693402 -273.60372)
		(width 0.0889)
		(layer "In4.Cu")
		(net "M_J_CPU1_SB_CB<1>")
	)
	(arc
		(start 134.821676 -273.598894)
		(mid 135.104632 -273.522717)
		(end 135.387588 -273.598894)
		(width 0.0889)
		(layer "In4.Cu")
		(net "M_J_CPU1_SB_CB<1>")
	)
	(arc
		(start 145.146014 -273.608038)
		(mid 145.252875 -273.55601)
		(end 145.368264 -273.52752)
		(width 0.0889)
		(layer "In4.Cu")
		(net "M_J_CPU1_SB_CB<1>")
	)
	(arc
		(start 141.976094 -273.60372)
		(mid 142.159602 -273.649214)
		(end 142.341854 -273.598894)
		(width 0.0889)
		(layer "In4.Cu")
		(net "M_J_CPU1_SB_CB<1>")
	)
	(arc
		(start 135.387588 -273.598894)
		(mid 135.569839 -273.649244)
		(end 135.753348 -273.60372)
		(width 0.0889)
		(layer "In4.Cu")
		(net "M_J_CPU1_SB_CB<1>")
	)
	(arc
		(start 136.701784 -273.598894)
		(mid 136.98474 -273.522717)
		(end 137.267696 -273.598894)
		(width 0.0889)
		(layer "In4.Cu")
		(net "M_J_CPU1_SB_CB<1>")
	)
	(arc
		(start 132.56768 -273.598894)
		(mid 132.749931 -273.649244)
		(end 132.93344 -273.60372)
		(width 0.0889)
		(layer "In4.Cu")
		(net "M_J_CPU1_SB_CB<1>")
	)
	(arc
		(start 145.368264 -273.52752)
		(mid 145.406147 -273.523563)
		(end 145.44421 -273.522186)
		(width 0.0889)
		(layer "In4.Cu")
		(net "M_J_CPU1_SB_CB<1>")
	)
	(arc
		(start 137.276078 -273.60372)
		(mid 137.459586 -273.649214)
		(end 137.641838 -273.598894)
		(width 0.0889)
		(layer "In4.Cu")
		(net "M_J_CPU1_SB_CB<1>")
	)
	(arc
		(start 142.341854 -273.598894)
		(mid 142.62481 -273.522717)
		(end 142.907766 -273.598894)
		(width 0.0889)
		(layer "In4.Cu")
		(net "M_J_CPU1_SB_CB<1>")
	)
	(arc
		(start 131.682998 -273.625056)
		(mid 131.840508 -273.648254)
		(end 131.993386 -273.60372)
		(width 0.0889)
		(layer "In4.Cu")
		(net "M_J_CPU1_SB_CB<1>")
	)
	(arc
		(start 132.001768 -273.598894)
		(mid 132.284724 -273.522717)
		(end 132.56768 -273.598894)
		(width 0.0889)
		(layer "In4.Cu")
		(net "M_J_CPU1_SB_CB<1>")
	)
	(arc
		(start 132.941822 -273.598894)
		(mid 133.224778 -273.522717)
		(end 133.507734 -273.598894)
		(width 0.0889)
		(layer "In4.Cu")
		(net "M_J_CPU1_SB_CB<1>")
	)
	(arc
		(start 145.444464 -273.522186)
		(mid 145.629589 -273.49143)
		(end 145.79473 -273.402298)
		(width 0.0889)
		(layer "In4.Cu")
		(net "M_J_CPU1_SB_CB<1>")
	)
	(arc
		(start 144.222216 -273.598894)
		(mid 144.499283 -273.522623)
		(end 144.777968 -273.592798)
		(width 0.0889)
		(layer "In4.Cu")
		(net "M_J_CPU1_SB_CB<1>")
	)
	(arc
		(start 133.516116 -273.60372)
		(mid 133.699624 -273.649214)
		(end 133.881876 -273.598894)
		(width 0.0889)
		(layer "In4.Cu")
		(net "M_J_CPU1_SB_CB<1>")
	)
	(arc
		(start 141.027658 -273.598894)
		(mid 141.209909 -273.649244)
		(end 141.393418 -273.60372)
		(width 0.0889)
		(layer "In4.Cu")
		(net "M_J_CPU1_SB_CB<1>")
	)
	(arc
		(start 140.087604 -273.598894)
		(mid 140.269855 -273.649244)
		(end 140.453364 -273.60372)
		(width 0.0889)
		(layer "In4.Cu")
		(net "M_J_CPU1_SB_CB<1>")
	)
	(arc
		(start 139.521692 -273.598894)
		(mid 139.804648 -273.522717)
		(end 140.087604 -273.598894)
		(width 0.0889)
		(layer "In4.Cu")
		(net "M_J_CPU1_SB_CB<1>")
	)
	(arc
		(start 142.907766 -273.598894)
		(mid 143.09471 -273.649149)
		(end 143.281654 -273.598894)
		(width 0.0889)
		(layer "In4.Cu")
		(net "M_J_CPU1_SB_CB<1>")
	)
	(arc
		(start 143.281654 -273.598894)
		(mid 143.56461 -273.522717)
		(end 143.847566 -273.598894)
		(width 0.0889)
		(layer "In4.Cu")
		(net "M_J_CPU1_SB_CB<1>")
	)
	(arc
		(start 144.788382 -273.598894)
		(mid 144.966032 -273.649154)
		(end 145.146014 -273.608038)
		(width 0.0889)
		(layer "In4.Cu")
		(net "M_J_CPU1_SB_CB<1>")
	)
	(arc
		(start 138.216132 -273.60372)
		(mid 138.39964 -273.649214)
		(end 138.581892 -273.598894)
		(width 0.0889)
		(layer "In4.Cu")
		(net "M_J_CPU1_SB_CB<1>")
	)
	(arc
		(start 134.447788 -273.598894)
		(mid 134.634732 -273.649149)
		(end 134.821676 -273.598894)
		(width 0.0889)
		(layer "In4.Cu")
		(net "M_J_CPU1_SB_CB<1>")
	)
	(arc
		(start 138.581892 -273.598894)
		(mid 138.864848 -273.522717)
		(end 139.147804 -273.598894)
		(width 0.0889)
		(layer "In4.Cu")
		(net "M_J_CPU1_SB_CB<1>")
	)
	(arc
		(start 135.76173 -273.598894)
		(mid 136.044686 -273.522717)
		(end 136.327642 -273.598894)
		(width 0.0889)
		(layer "In4.Cu")
		(net "M_J_CPU1_SB_CB<1>")
	)
	(arc
		(start 137.641838 -273.598894)
		(mid 137.924794 -273.522717)
		(end 138.20775 -273.598894)
		(width 0.0889)
		(layer "In4.Cu")
		(net "M_J_CPU1_SB_CB<1>")
	)
	(arc
		(start 140.461746 -273.598894)
		(mid 140.744702 -273.522717)
		(end 141.027658 -273.598894)
		(width 0.0889)
		(layer "In4.Cu")
		(net "M_J_CPU1_SB_CB<1>")
	)
	(arc
		(start 143.855948 -273.60372)
		(mid 144.03971 -273.649336)
		(end 144.222216 -273.598894)
		(width 0.0889)
		(layer "In4.Cu")
		(net "M_J_CPU1_SB_CB<1>")
	)
	(arc
		(start 141.4018 -273.598894)
		(mid 141.684756 -273.522717)
		(end 141.967712 -273.598894)
		(width 0.0889)
		(layer "In4.Cu")
		(net "M_J_CPU1_SB_CB<1>")
	)
	(arc
		(start 139.147804 -273.598894)
		(mid 139.334748 -273.649149)
		(end 139.521692 -273.598894)
		(width 0.0889)
		(layer "In4.Cu")
		(net "M_J_CPU1_SB_CB<1>")
	)
	(segment
		(start 132.757926 -272.20037)
		(end 133.224778 -272.466308)
		(width 0.10668)
		(layer "F.Cu")
		(net "M_J_CPU1_SB_CB<0>")
	)
	(segment
		(start 174.62754 -277.670006)
		(end 177.450496 -277.670006)
		(width 0.14478)
		(layer "In4.Cu")
		(net "M_J_CPU1_SB_CB<0>")
	)
	(segment
		(start 190.744856 -277.670006)
		(end 191.160146 -278.085296)
		(width 0.14478)
		(layer "In4.Cu")
		(net "M_J_CPU1_SB_CB<0>")
	)
	(segment
		(start 140.557758 -272.788888)
		(end 140.56614 -272.793714)
		(width 0.0889)
		(layer "In4.Cu")
		(net "M_J_CPU1_SB_CB<0>")
	)
	(segment
		(start 166.243 -278.510492)
		(end 167.092884 -277.660608)
		(width 0.14478)
		(layer "In4.Cu")
		(net "M_J_CPU1_SB_CB<0>")
	)
	(segment
		(start 182.108348 -277.670006)
		(end 190.744856 -277.670006)
		(width 0.14478)
		(layer "In4.Cu")
		(net "M_J_CPU1_SB_CB<0>")
	)
	(segment
		(start 167.092884 -277.660608)
		(end 169.75074 -277.660608)
		(width 0.14478)
		(layer "In4.Cu")
		(net "M_J_CPU1_SB_CB<0>")
	)
	(segment
		(start 162.407346 -276.847046)
		(end 163.349178 -276.847046)
		(width 0.14478)
		(layer "In4.Cu")
		(net "M_J_CPU1_SB_CB<0>")
	)
	(segment
		(start 170.610276 -278.520144)
		(end 173.777402 -278.520144)
		(width 0.14478)
		(layer "In4.Cu")
		(net "M_J_CPU1_SB_CB<0>")
	)
	(segment
		(start 173.777402 -278.520144)
		(end 174.62754 -277.670006)
		(width 0.14478)
		(layer "In4.Cu")
		(net "M_J_CPU1_SB_CB<0>")
	)
	(segment
		(start 165.012624 -278.510492)
		(end 166.243 -278.510492)
		(width 0.14478)
		(layer "In4.Cu")
		(net "M_J_CPU1_SB_CB<0>")
	)
	(segment
		(start 146.644106 -271.245584)
		(end 147.022312 -270.867378)
		(width 0.0889)
		(layer "In4.Cu")
		(net "M_J_CPU1_SB_CB<0>")
	)
	(segment
		(start 147.022312 -270.867378)
		(end 147.702016 -270.867378)
		(width 0.0889)
		(layer "In4.Cu")
		(net "M_J_CPU1_SB_CB<0>")
	)
	(segment
		(start 139.617704 -272.788888)
		(end 139.626086 -272.793714)
		(width 0.0889)
		(layer "In4.Cu")
		(net "M_J_CPU1_SB_CB<0>")
	)
	(segment
		(start 178.30038 -278.51989)
		(end 181.258464 -278.51989)
		(width 0.14478)
		(layer "In4.Cu")
		(net "M_J_CPU1_SB_CB<0>")
	)
	(segment
		(start 163.349178 -276.847046)
		(end 165.012624 -278.510492)
		(width 0.14478)
		(layer "In4.Cu")
		(net "M_J_CPU1_SB_CB<0>")
	)
	(segment
		(start 145.603214 -272.804382)
		(end 145.630646 -272.788634)
		(width 0.0889)
		(layer "In4.Cu")
		(net "M_J_CPU1_SB_CB<0>")
	)
	(segment
		(start 134.917688 -272.788888)
		(end 134.92607 -272.793714)
		(width 0.0889)
		(layer "In4.Cu")
		(net "M_J_CPU1_SB_CB<0>")
	)
	(segment
		(start 142.803372 -272.793714)
		(end 142.811754 -272.788888)
		(width 0.0889)
		(layer "In4.Cu")
		(net "M_J_CPU1_SB_CB<0>")
	)
	(segment
		(start 143.377666 -272.788888)
		(end 143.386048 -272.793714)
		(width 0.0889)
		(layer "In4.Cu")
		(net "M_J_CPU1_SB_CB<0>")
	)
	(segment
		(start 181.258464 -278.51989)
		(end 182.108348 -277.670006)
		(width 0.14478)
		(layer "In4.Cu")
		(net "M_J_CPU1_SB_CB<0>")
	)
	(segment
		(start 134.343394 -272.793714)
		(end 134.351776 -272.788888)
		(width 0.0889)
		(layer "In4.Cu")
		(net "M_J_CPU1_SB_CB<0>")
	)
	(segment
		(start 147.702016 -270.867378)
		(end 147.854162 -271.019524)
		(width 0.14478)
		(layer "In4.Cu")
		(net "M_J_CPU1_SB_CB<0>")
	)
	(segment
		(start 144.294606 -272.776188)
		(end 144.316196 -272.788634)
		(width 0.0889)
		(layer "In4.Cu")
		(net "M_J_CPU1_SB_CB<0>")
	)
	(segment
		(start 139.04341 -272.793714)
		(end 139.051792 -272.788888)
		(width 0.0889)
		(layer "In4.Cu")
		(net "M_J_CPU1_SB_CB<0>")
	)
	(segment
		(start 145.708116 -272.725388)
		(end 146.644106 -271.789398)
		(width 0.0889)
		(layer "In4.Cu")
		(net "M_J_CPU1_SB_CB<0>")
	)
	(segment
		(start 169.75074 -277.660608)
		(end 170.610276 -278.520144)
		(width 0.14478)
		(layer "In4.Cu")
		(net "M_J_CPU1_SB_CB<0>")
	)
	(segment
		(start 133.070854 -272.731738)
		(end 133.093206 -272.81505)
		(width 0.0889)
		(layer "In4.Cu")
		(net "M_J_CPU1_SB_CB<0>")
	)
	(segment
		(start 135.857742 -272.788888)
		(end 135.866124 -272.793714)
		(width 0.0889)
		(layer "In4.Cu")
		(net "M_J_CPU1_SB_CB<0>")
	)
	(segment
		(start 177.450496 -277.670006)
		(end 178.30038 -278.51989)
		(width 0.14478)
		(layer "In4.Cu")
		(net "M_J_CPU1_SB_CB<0>")
	)
	(segment
		(start 156.579824 -271.019524)
		(end 162.407346 -276.847046)
		(width 0.14478)
		(layer "In4.Cu")
		(net "M_J_CPU1_SB_CB<0>")
	)
	(segment
		(start 144.689322 -272.788888)
		(end 144.71269 -272.775172)
		(width 0.0889)
		(layer "In4.Cu")
		(net "M_J_CPU1_SB_CB<0>")
	)
	(segment
		(start 138.103356 -272.793714)
		(end 138.111738 -272.788888)
		(width 0.0889)
		(layer "In4.Cu")
		(net "M_J_CPU1_SB_CB<0>")
	)
	(segment
		(start 144.316196 -272.788634)
		(end 144.334484 -272.799048)
		(width 0.0889)
		(layer "In4.Cu")
		(net "M_J_CPU1_SB_CB<0>")
	)
	(segment
		(start 146.644106 -271.789398)
		(end 146.644106 -271.245584)
		(width 0.0889)
		(layer "In4.Cu")
		(net "M_J_CPU1_SB_CB<0>")
	)
	(segment
		(start 133.224778 -272.466308)
		(end 133.070854 -272.731738)
		(width 0.0889)
		(layer "In4.Cu")
		(net "M_J_CPU1_SB_CB<0>")
	)
	(segment
		(start 147.854162 -271.019524)
		(end 156.579824 -271.019524)
		(width 0.14478)
		(layer "In4.Cu")
		(net "M_J_CPU1_SB_CB<0>")
	)
	(arc
		(start 134.351776 -272.788888)
		(mid 134.634732 -272.712711)
		(end 134.917688 -272.788888)
		(width 0.0889)
		(layer "In4.Cu")
		(net "M_J_CPU1_SB_CB<0>")
	)
	(arc
		(start 144.334484 -272.799048)
		(mid 144.513205 -272.838971)
		(end 144.689322 -272.788888)
		(width 0.0889)
		(layer "In4.Cu")
		(net "M_J_CPU1_SB_CB<0>")
	)
	(arc
		(start 137.737596 -272.788888)
		(mid 137.919847 -272.839238)
		(end 138.103356 -272.793714)
		(width 0.0889)
		(layer "In4.Cu")
		(net "M_J_CPU1_SB_CB<0>")
	)
	(arc
		(start 143.386048 -272.793714)
		(mid 143.569556 -272.839208)
		(end 143.751808 -272.788888)
		(width 0.0889)
		(layer "In4.Cu")
		(net "M_J_CPU1_SB_CB<0>")
	)
	(arc
		(start 135.29183 -272.788888)
		(mid 135.574786 -272.712711)
		(end 135.857742 -272.788888)
		(width 0.0889)
		(layer "In4.Cu")
		(net "M_J_CPU1_SB_CB<0>")
	)
	(arc
		(start 139.991846 -272.788888)
		(mid 140.274802 -272.712711)
		(end 140.557758 -272.788888)
		(width 0.0889)
		(layer "In4.Cu")
		(net "M_J_CPU1_SB_CB<0>")
	)
	(arc
		(start 145.256504 -272.788888)
		(mid 145.427959 -272.839405)
		(end 145.603214 -272.804382)
		(width 0.0889)
		(layer "In4.Cu")
		(net "M_J_CPU1_SB_CB<0>")
	)
	(arc
		(start 136.231884 -272.788888)
		(mid 136.51484 -272.712711)
		(end 136.797796 -272.788888)
		(width 0.0889)
		(layer "In4.Cu")
		(net "M_J_CPU1_SB_CB<0>")
	)
	(arc
		(start 137.171684 -272.788888)
		(mid 137.45464 -272.712711)
		(end 137.737596 -272.788888)
		(width 0.0889)
		(layer "In4.Cu")
		(net "M_J_CPU1_SB_CB<0>")
	)
	(arc
		(start 136.797796 -272.788888)
		(mid 136.98474 -272.839143)
		(end 137.171684 -272.788888)
		(width 0.0889)
		(layer "In4.Cu")
		(net "M_J_CPU1_SB_CB<0>")
	)
	(arc
		(start 135.866124 -272.793714)
		(mid 136.049632 -272.839208)
		(end 136.231884 -272.788888)
		(width 0.0889)
		(layer "In4.Cu")
		(net "M_J_CPU1_SB_CB<0>")
	)
	(arc
		(start 141.497812 -272.788888)
		(mid 141.684756 -272.839143)
		(end 141.8717 -272.788888)
		(width 0.0889)
		(layer "In4.Cu")
		(net "M_J_CPU1_SB_CB<0>")
	)
	(arc
		(start 142.437612 -272.788888)
		(mid 142.619863 -272.839238)
		(end 142.803372 -272.793714)
		(width 0.0889)
		(layer "In4.Cu")
		(net "M_J_CPU1_SB_CB<0>")
	)
	(arc
		(start 138.111738 -272.788888)
		(mid 138.394694 -272.712711)
		(end 138.67765 -272.788888)
		(width 0.0889)
		(layer "In4.Cu")
		(net "M_J_CPU1_SB_CB<0>")
	)
	(arc
		(start 145.630646 -272.788634)
		(mid 145.670976 -272.758964)
		(end 145.708116 -272.725388)
		(width 0.0889)
		(layer "In4.Cu")
		(net "M_J_CPU1_SB_CB<0>")
	)
	(arc
		(start 133.093206 -272.81505)
		(mid 133.255395 -272.837785)
		(end 133.411722 -272.788888)
		(width 0.0889)
		(layer "In4.Cu")
		(net "M_J_CPU1_SB_CB<0>")
	)
	(arc
		(start 140.56614 -272.793714)
		(mid 140.749648 -272.839208)
		(end 140.9319 -272.788888)
		(width 0.0889)
		(layer "In4.Cu")
		(net "M_J_CPU1_SB_CB<0>")
	)
	(arc
		(start 139.051792 -272.788888)
		(mid 139.334748 -272.712711)
		(end 139.617704 -272.788888)
		(width 0.0889)
		(layer "In4.Cu")
		(net "M_J_CPU1_SB_CB<0>")
	)
	(arc
		(start 143.751808 -272.788888)
		(mid 144.021577 -272.712865)
		(end 144.294606 -272.776188)
		(width 0.0889)
		(layer "In4.Cu")
		(net "M_J_CPU1_SB_CB<0>")
	)
	(arc
		(start 138.67765 -272.788888)
		(mid 138.859901 -272.839238)
		(end 139.04341 -272.793714)
		(width 0.0889)
		(layer "In4.Cu")
		(net "M_J_CPU1_SB_CB<0>")
	)
	(arc
		(start 133.977634 -272.788888)
		(mid 134.159885 -272.839238)
		(end 134.343394 -272.793714)
		(width 0.0889)
		(layer "In4.Cu")
		(net "M_J_CPU1_SB_CB<0>")
	)
	(arc
		(start 133.411722 -272.788888)
		(mid 133.694678 -272.712711)
		(end 133.977634 -272.788888)
		(width 0.0889)
		(layer "In4.Cu")
		(net "M_J_CPU1_SB_CB<0>")
	)
	(arc
		(start 142.811754 -272.788888)
		(mid 143.09471 -272.712711)
		(end 143.377666 -272.788888)
		(width 0.0889)
		(layer "In4.Cu")
		(net "M_J_CPU1_SB_CB<0>")
	)
	(arc
		(start 141.8717 -272.788888)
		(mid 142.154656 -272.712711)
		(end 142.437612 -272.788888)
		(width 0.0889)
		(layer "In4.Cu")
		(net "M_J_CPU1_SB_CB<0>")
	)
	(arc
		(start 139.626086 -272.793714)
		(mid 139.809594 -272.839208)
		(end 139.991846 -272.788888)
		(width 0.0889)
		(layer "In4.Cu")
		(net "M_J_CPU1_SB_CB<0>")
	)
	(arc
		(start 140.9319 -272.788888)
		(mid 141.214856 -272.712711)
		(end 141.497812 -272.788888)
		(width 0.0889)
		(layer "In4.Cu")
		(net "M_J_CPU1_SB_CB<0>")
	)
	(arc
		(start 134.92607 -272.793714)
		(mid 135.109578 -272.839208)
		(end 135.29183 -272.788888)
		(width 0.0889)
		(layer "In4.Cu")
		(net "M_J_CPU1_SB_CB<0>")
	)
	(arc
		(start 144.71269 -272.775172)
		(mid 144.986344 -272.712229)
		(end 145.256504 -272.788888)
		(width 0.0889)
		(layer "In4.Cu")
		(net "M_J_CPU1_SB_CB<0>")
	)
	(segment
		(start 132.757926 -264.10031)
		(end 133.224778 -264.366248)
		(width 0.10668)
		(layer "F.Cu")
		(net "M_J_CPU1_SB_CA<6>")
	)
	(segment
		(start 140.557758 -264.688828)
		(end 140.56614 -264.693654)
		(width 0.0889)
		(layer "In4.Cu")
		(net "M_J_CPU1_SB_CA<6>")
	)
	(segment
		(start 146.177254 -264.268204)
		(end 147.774152 -264.268204)
		(width 0.0889)
		(layer "In4.Cu")
		(net "M_J_CPU1_SB_CA<6>")
	)
	(segment
		(start 139.617704 -264.688828)
		(end 139.626086 -264.693654)
		(width 0.0889)
		(layer "In4.Cu")
		(net "M_J_CPU1_SB_CA<6>")
	)
	(segment
		(start 174.636938 -265.760454)
		(end 190.735204 -265.760454)
		(width 0.14478)
		(layer "In4.Cu")
		(net "M_J_CPU1_SB_CA<6>")
	)
	(segment
		(start 144.316196 -264.688574)
		(end 144.334484 -264.698988)
		(width 0.0889)
		(layer "In4.Cu")
		(net "M_J_CPU1_SB_CA<6>")
	)
	(segment
		(start 146.018504 -264.320274)
		(end 146.114262 -264.28065)
		(width 0.0889)
		(layer "In4.Cu")
		(net "M_J_CPU1_SB_CA<6>")
	)
	(segment
		(start 143.377666 -264.688828)
		(end 143.386048 -264.693654)
		(width 0.0889)
		(layer "In4.Cu")
		(net "M_J_CPU1_SB_CA<6>")
	)
	(segment
		(start 146.114262 -264.28065)
		(end 146.177254 -264.268204)
		(width 0.0889)
		(layer "In4.Cu")
		(net "M_J_CPU1_SB_CA<6>")
	)
	(segment
		(start 190.735204 -265.760454)
		(end 191.160146 -266.185396)
		(width 0.14478)
		(layer "In4.Cu")
		(net "M_J_CPU1_SB_CA<6>")
	)
	(segment
		(start 173.787054 -266.610338)
		(end 174.636938 -265.760454)
		(width 0.14478)
		(layer "In4.Cu")
		(net "M_J_CPU1_SB_CA<6>")
	)
	(segment
		(start 144.294606 -264.676128)
		(end 144.316196 -264.688574)
		(width 0.0889)
		(layer "In4.Cu")
		(net "M_J_CPU1_SB_CA<6>")
	)
	(segment
		(start 145.603214 -264.704322)
		(end 145.630646 -264.688574)
		(width 0.0889)
		(layer "In4.Cu")
		(net "M_J_CPU1_SB_CA<6>")
	)
	(segment
		(start 139.04341 -264.693654)
		(end 139.051792 -264.688828)
		(width 0.0889)
		(layer "In4.Cu")
		(net "M_J_CPU1_SB_CA<6>")
	)
	(segment
		(start 147.845272 -264.339324)
		(end 161.994088 -264.339324)
		(width 0.14478)
		(layer "In4.Cu")
		(net "M_J_CPU1_SB_CA<6>")
	)
	(segment
		(start 170.117516 -265.760454)
		(end 170.9674 -266.610338)
		(width 0.14478)
		(layer "In4.Cu")
		(net "M_J_CPU1_SB_CA<6>")
	)
	(segment
		(start 142.803372 -264.693654)
		(end 142.811754 -264.688828)
		(width 0.0889)
		(layer "In4.Cu")
		(net "M_J_CPU1_SB_CA<6>")
	)
	(segment
		(start 133.224778 -264.366248)
		(end 133.070854 -264.631678)
		(width 0.0889)
		(layer "In4.Cu")
		(net "M_J_CPU1_SB_CA<6>")
	)
	(segment
		(start 138.103356 -264.693654)
		(end 138.111738 -264.688828)
		(width 0.0889)
		(layer "In4.Cu")
		(net "M_J_CPU1_SB_CA<6>")
	)
	(segment
		(start 164.265102 -266.610338)
		(end 166.243 -266.610338)
		(width 0.14478)
		(layer "In4.Cu")
		(net "M_J_CPU1_SB_CA<6>")
	)
	(segment
		(start 145.959322 -264.359898)
		(end 146.018504 -264.320274)
		(width 0.0889)
		(layer "In4.Cu")
		(net "M_J_CPU1_SB_CA<6>")
	)
	(segment
		(start 167.092884 -265.760454)
		(end 170.117516 -265.760454)
		(width 0.14478)
		(layer "In4.Cu")
		(net "M_J_CPU1_SB_CA<6>")
	)
	(segment
		(start 166.243 -266.610338)
		(end 167.092884 -265.760454)
		(width 0.14478)
		(layer "In4.Cu")
		(net "M_J_CPU1_SB_CA<6>")
	)
	(segment
		(start 134.917688 -264.688828)
		(end 134.92607 -264.693654)
		(width 0.0889)
		(layer "In4.Cu")
		(net "M_J_CPU1_SB_CA<6>")
	)
	(segment
		(start 134.343394 -264.693654)
		(end 134.351776 -264.688828)
		(width 0.0889)
		(layer "In4.Cu")
		(net "M_J_CPU1_SB_CA<6>")
	)
	(segment
		(start 145.630646 -264.688574)
		(end 145.959322 -264.359898)
		(width 0.0889)
		(layer "In4.Cu")
		(net "M_J_CPU1_SB_CA<6>")
	)
	(segment
		(start 147.774152 -264.268204)
		(end 147.845272 -264.339324)
		(width 0.0889)
		(layer "In4.Cu")
		(net "M_J_CPU1_SB_CA<6>")
	)
	(segment
		(start 133.070854 -264.631678)
		(end 133.093206 -264.71499)
		(width 0.0889)
		(layer "In4.Cu")
		(net "M_J_CPU1_SB_CA<6>")
	)
	(segment
		(start 170.9674 -266.610338)
		(end 173.787054 -266.610338)
		(width 0.14478)
		(layer "In4.Cu")
		(net "M_J_CPU1_SB_CA<6>")
	)
	(segment
		(start 135.857742 -264.688828)
		(end 135.866124 -264.693654)
		(width 0.0889)
		(layer "In4.Cu")
		(net "M_J_CPU1_SB_CA<6>")
	)
	(segment
		(start 161.994088 -264.339324)
		(end 164.265102 -266.610338)
		(width 0.14478)
		(layer "In4.Cu")
		(net "M_J_CPU1_SB_CA<6>")
	)
	(segment
		(start 144.689322 -264.688828)
		(end 144.71269 -264.675112)
		(width 0.0889)
		(layer "In4.Cu")
		(net "M_J_CPU1_SB_CA<6>")
	)
	(arc
		(start 133.977634 -264.688828)
		(mid 134.159885 -264.739178)
		(end 134.343394 -264.693654)
		(width 0.0889)
		(layer "In4.Cu")
		(net "M_J_CPU1_SB_CA<6>")
	)
	(arc
		(start 137.171684 -264.688828)
		(mid 137.45464 -264.612651)
		(end 137.737596 -264.688828)
		(width 0.0889)
		(layer "In4.Cu")
		(net "M_J_CPU1_SB_CA<6>")
	)
	(arc
		(start 140.9319 -264.688828)
		(mid 141.214856 -264.612651)
		(end 141.497812 -264.688828)
		(width 0.0889)
		(layer "In4.Cu")
		(net "M_J_CPU1_SB_CA<6>")
	)
	(arc
		(start 135.866124 -264.693654)
		(mid 136.049632 -264.739148)
		(end 136.231884 -264.688828)
		(width 0.0889)
		(layer "In4.Cu")
		(net "M_J_CPU1_SB_CA<6>")
	)
	(arc
		(start 139.991846 -264.688828)
		(mid 140.274802 -264.612651)
		(end 140.557758 -264.688828)
		(width 0.0889)
		(layer "In4.Cu")
		(net "M_J_CPU1_SB_CA<6>")
	)
	(arc
		(start 135.29183 -264.688828)
		(mid 135.574786 -264.612651)
		(end 135.857742 -264.688828)
		(width 0.0889)
		(layer "In4.Cu")
		(net "M_J_CPU1_SB_CA<6>")
	)
	(arc
		(start 143.751808 -264.688828)
		(mid 144.021577 -264.612805)
		(end 144.294606 -264.676128)
		(width 0.0889)
		(layer "In4.Cu")
		(net "M_J_CPU1_SB_CA<6>")
	)
	(arc
		(start 138.111738 -264.688828)
		(mid 138.394694 -264.612651)
		(end 138.67765 -264.688828)
		(width 0.0889)
		(layer "In4.Cu")
		(net "M_J_CPU1_SB_CA<6>")
	)
	(arc
		(start 136.231884 -264.688828)
		(mid 136.51484 -264.612651)
		(end 136.797796 -264.688828)
		(width 0.0889)
		(layer "In4.Cu")
		(net "M_J_CPU1_SB_CA<6>")
	)
	(arc
		(start 139.626086 -264.693654)
		(mid 139.809594 -264.739148)
		(end 139.991846 -264.688828)
		(width 0.0889)
		(layer "In4.Cu")
		(net "M_J_CPU1_SB_CA<6>")
	)
	(arc
		(start 138.67765 -264.688828)
		(mid 138.859901 -264.739178)
		(end 139.04341 -264.693654)
		(width 0.0889)
		(layer "In4.Cu")
		(net "M_J_CPU1_SB_CA<6>")
	)
	(arc
		(start 137.737596 -264.688828)
		(mid 137.919847 -264.739178)
		(end 138.103356 -264.693654)
		(width 0.0889)
		(layer "In4.Cu")
		(net "M_J_CPU1_SB_CA<6>")
	)
	(arc
		(start 142.811754 -264.688828)
		(mid 143.09471 -264.612651)
		(end 143.377666 -264.688828)
		(width 0.0889)
		(layer "In4.Cu")
		(net "M_J_CPU1_SB_CA<6>")
	)
	(arc
		(start 141.497812 -264.688828)
		(mid 141.684756 -264.739083)
		(end 141.8717 -264.688828)
		(width 0.0889)
		(layer "In4.Cu")
		(net "M_J_CPU1_SB_CA<6>")
	)
	(arc
		(start 134.351776 -264.688828)
		(mid 134.634732 -264.612651)
		(end 134.917688 -264.688828)
		(width 0.0889)
		(layer "In4.Cu")
		(net "M_J_CPU1_SB_CA<6>")
	)
	(arc
		(start 133.093206 -264.71499)
		(mid 133.255395 -264.737725)
		(end 133.411722 -264.688828)
		(width 0.0889)
		(layer "In4.Cu")
		(net "M_J_CPU1_SB_CA<6>")
	)
	(arc
		(start 136.797796 -264.688828)
		(mid 136.98474 -264.739083)
		(end 137.171684 -264.688828)
		(width 0.0889)
		(layer "In4.Cu")
		(net "M_J_CPU1_SB_CA<6>")
	)
	(arc
		(start 144.334484 -264.698988)
		(mid 144.513205 -264.738911)
		(end 144.689322 -264.688828)
		(width 0.0889)
		(layer "In4.Cu")
		(net "M_J_CPU1_SB_CA<6>")
	)
	(arc
		(start 145.256504 -264.688828)
		(mid 145.427959 -264.739345)
		(end 145.603214 -264.704322)
		(width 0.0889)
		(layer "In4.Cu")
		(net "M_J_CPU1_SB_CA<6>")
	)
	(arc
		(start 142.437612 -264.688828)
		(mid 142.619863 -264.739178)
		(end 142.803372 -264.693654)
		(width 0.0889)
		(layer "In4.Cu")
		(net "M_J_CPU1_SB_CA<6>")
	)
	(arc
		(start 141.8717 -264.688828)
		(mid 142.154656 -264.612651)
		(end 142.437612 -264.688828)
		(width 0.0889)
		(layer "In4.Cu")
		(net "M_J_CPU1_SB_CA<6>")
	)
	(arc
		(start 144.71269 -264.675112)
		(mid 144.986344 -264.612169)
		(end 145.256504 -264.688828)
		(width 0.0889)
		(layer "In4.Cu")
		(net "M_J_CPU1_SB_CA<6>")
	)
	(arc
		(start 133.411722 -264.688828)
		(mid 133.694678 -264.612651)
		(end 133.977634 -264.688828)
		(width 0.0889)
		(layer "In4.Cu")
		(net "M_J_CPU1_SB_CA<6>")
	)
	(arc
		(start 139.051792 -264.688828)
		(mid 139.334748 -264.612651)
		(end 139.617704 -264.688828)
		(width 0.0889)
		(layer "In4.Cu")
		(net "M_J_CPU1_SB_CA<6>")
	)
	(arc
		(start 134.92607 -264.693654)
		(mid 135.109578 -264.739148)
		(end 135.29183 -264.688828)
		(width 0.0889)
		(layer "In4.Cu")
		(net "M_J_CPU1_SB_CA<6>")
	)
	(arc
		(start 143.386048 -264.693654)
		(mid 143.569556 -264.739148)
		(end 143.751808 -264.688828)
		(width 0.0889)
		(layer "In4.Cu")
		(net "M_J_CPU1_SB_CA<6>")
	)
	(arc
		(start 140.56614 -264.693654)
		(mid 140.749648 -264.739148)
		(end 140.9319 -264.688828)
		(width 0.0889)
		(layer "In4.Cu")
		(net "M_J_CPU1_SB_CA<6>")
	)
	(segment
		(start 130.877818 -264.10031)
		(end 131.34467 -264.366248)
		(width 0.10668)
		(layer "F.Cu")
		(net "M_J_CPU1_SB_CA<5>")
	)
	(segment
		(start 186.635136 -264.910316)
		(end 187.060078 -265.335258)
		(width 0.14478)
		(layer "In4.Cu")
		(net "M_J_CPU1_SB_CA<5>")
	)
	(segment
		(start 180.527706 -265.218164)
		(end 180.776372 -265.218164)
		(width 0.14478)
		(layer "In4.Cu")
		(net "M_J_CPU1_SB_CA<5>")
	)
	(segment
		(start 142.803372 -264.038842)
		(end 142.811754 -264.043668)
		(width 0.0889)
		(layer "In4.Cu")
		(net "M_J_CPU1_SB_CA<5>")
	)
	(segment
		(start 140.557758 -264.043668)
		(end 140.56614 -264.038842)
		(width 0.0889)
		(layer "In4.Cu")
		(net "M_J_CPU1_SB_CA<5>")
	)
	(segment
		(start 164.479224 -265.760454)
		(end 166.150036 -265.760454)
		(width 0.14478)
		(layer "In4.Cu")
		(net "M_J_CPU1_SB_CA<5>")
	)
	(segment
		(start 180.219858 -264.910316)
		(end 180.527706 -265.218164)
		(width 0.14478)
		(layer "In4.Cu")
		(net "M_J_CPU1_SB_CA<5>")
	)
	(segment
		(start 138.103356 -264.038842)
		(end 138.111738 -264.043668)
		(width 0.0889)
		(layer "In4.Cu")
		(net "M_J_CPU1_SB_CA<5>")
	)
	(segment
		(start 166.150036 -265.760454)
		(end 167.000174 -264.910316)
		(width 0.14478)
		(layer "In4.Cu")
		(net "M_J_CPU1_SB_CA<5>")
	)
	(segment
		(start 143.751808 -264.043668)
		(end 143.762222 -264.049764)
		(width 0.0889)
		(layer "In4.Cu")
		(net "M_J_CPU1_SB_CA<5>")
	)
	(segment
		(start 182.753762 -265.218164)
		(end 183.002428 -265.218164)
		(width 0.14478)
		(layer "In4.Cu")
		(net "M_J_CPU1_SB_CA<5>")
	)
	(segment
		(start 131.34467 -264.366248)
		(end 131.498848 -264.100818)
		(width 0.0889)
		(layer "In4.Cu")
		(net "M_J_CPU1_SB_CA<5>")
	)
	(segment
		(start 170.18254 -264.910316)
		(end 171.032678 -265.760454)
		(width 0.14478)
		(layer "In4.Cu")
		(net "M_J_CPU1_SB_CA<5>")
	)
	(segment
		(start 162.603434 -263.884664)
		(end 164.479224 -265.760454)
		(width 0.14478)
		(layer "In4.Cu")
		(net "M_J_CPU1_SB_CA<5>")
	)
	(segment
		(start 147.973796 -263.884664)
		(end 162.603434 -263.884664)
		(width 0.14478)
		(layer "In4.Cu")
		(net "M_J_CPU1_SB_CA<5>")
	)
	(segment
		(start 143.377666 -264.043668)
		(end 143.386048 -264.038842)
		(width 0.0889)
		(layer "In4.Cu")
		(net "M_J_CPU1_SB_CA<5>")
	)
	(segment
		(start 139.617704 -264.043668)
		(end 139.626086 -264.038842)
		(width 0.0889)
		(layer "In4.Cu")
		(net "M_J_CPU1_SB_CA<5>")
	)
	(segment
		(start 132.09778 -264.043668)
		(end 132.106162 -264.038842)
		(width 0.0889)
		(layer "In4.Cu")
		(net "M_J_CPU1_SB_CA<5>")
	)
	(segment
		(start 147.377404 -263.884664)
		(end 147.973796 -263.884664)
		(width 0.0889)
		(layer "In4.Cu")
		(net "M_J_CPU1_SB_CA<5>")
	)
	(segment
		(start 134.343394 -264.038842)
		(end 134.351776 -264.043668)
		(width 0.0889)
		(layer "In4.Cu")
		(net "M_J_CPU1_SB_CA<5>")
	)
	(segment
		(start 135.857742 -264.043668)
		(end 135.866124 -264.038842)
		(width 0.0889)
		(layer "In4.Cu")
		(net "M_J_CPU1_SB_CA<5>")
	)
	(segment
		(start 147.2692 -263.992868)
		(end 147.377404 -263.884664)
		(width 0.0889)
		(layer "In4.Cu")
		(net "M_J_CPU1_SB_CA<5>")
	)
	(segment
		(start 183.002428 -265.218164)
		(end 183.310276 -264.910316)
		(width 0.14478)
		(layer "In4.Cu")
		(net "M_J_CPU1_SB_CA<5>")
	)
	(segment
		(start 167.000174 -264.910316)
		(end 170.18254 -264.910316)
		(width 0.14478)
		(layer "In4.Cu")
		(net "M_J_CPU1_SB_CA<5>")
	)
	(segment
		(start 182.197248 -264.910316)
		(end 182.445914 -264.910316)
		(width 0.14478)
		(layer "In4.Cu")
		(net "M_J_CPU1_SB_CA<5>")
	)
	(segment
		(start 171.032678 -265.760454)
		(end 173.69409 -265.760454)
		(width 0.14478)
		(layer "In4.Cu")
		(net "M_J_CPU1_SB_CA<5>")
	)
	(segment
		(start 183.310276 -264.910316)
		(end 186.635136 -264.910316)
		(width 0.14478)
		(layer "In4.Cu")
		(net "M_J_CPU1_SB_CA<5>")
	)
	(segment
		(start 145.444718 -263.992868)
		(end 147.2692 -263.992868)
		(width 0.0889)
		(layer "In4.Cu")
		(net "M_J_CPU1_SB_CA<5>")
	)
	(segment
		(start 173.69409 -265.760454)
		(end 174.544228 -264.910316)
		(width 0.14478)
		(layer "In4.Cu")
		(net "M_J_CPU1_SB_CA<5>")
	)
	(segment
		(start 144.684242 -264.038842)
		(end 144.692624 -264.043668)
		(width 0.0889)
		(layer "In4.Cu")
		(net "M_J_CPU1_SB_CA<5>")
	)
	(segment
		(start 181.332886 -264.910316)
		(end 181.640734 -265.218164)
		(width 0.14478)
		(layer "In4.Cu")
		(net "M_J_CPU1_SB_CA<5>")
	)
	(segment
		(start 181.8894 -265.218164)
		(end 182.197248 -264.910316)
		(width 0.14478)
		(layer "In4.Cu")
		(net "M_J_CPU1_SB_CA<5>")
	)
	(segment
		(start 182.445914 -264.910316)
		(end 182.753762 -265.218164)
		(width 0.14478)
		(layer "In4.Cu")
		(net "M_J_CPU1_SB_CA<5>")
	)
	(segment
		(start 180.776372 -265.218164)
		(end 181.08422 -264.910316)
		(width 0.14478)
		(layer "In4.Cu")
		(net "M_J_CPU1_SB_CA<5>")
	)
	(segment
		(start 134.917688 -264.043668)
		(end 134.92607 -264.038842)
		(width 0.0889)
		(layer "In4.Cu")
		(net "M_J_CPU1_SB_CA<5>")
	)
	(segment
		(start 181.640734 -265.218164)
		(end 181.8894 -265.218164)
		(width 0.14478)
		(layer "In4.Cu")
		(net "M_J_CPU1_SB_CA<5>")
	)
	(segment
		(start 139.04341 -264.038842)
		(end 139.051792 -264.043668)
		(width 0.0889)
		(layer "In4.Cu")
		(net "M_J_CPU1_SB_CA<5>")
	)
	(segment
		(start 174.544228 -264.910316)
		(end 180.219858 -264.910316)
		(width 0.14478)
		(layer "In4.Cu")
		(net "M_J_CPU1_SB_CA<5>")
	)
	(segment
		(start 181.08422 -264.910316)
		(end 181.332886 -264.910316)
		(width 0.14478)
		(layer "In4.Cu")
		(net "M_J_CPU1_SB_CA<5>")
	)
	(segment
		(start 131.498848 -264.100818)
		(end 131.595114 -264.075418)
		(width 0.0889)
		(layer "In4.Cu")
		(net "M_J_CPU1_SB_CA<5>")
	)
	(arc
		(start 144.692624 -264.043668)
		(mid 144.972052 -264.119834)
		(end 145.25244 -264.047224)
		(width 0.0889)
		(layer "In4.Cu")
		(net "M_J_CPU1_SB_CA<5>")
	)
	(arc
		(start 134.351776 -264.043668)
		(mid 134.634732 -264.119845)
		(end 134.917688 -264.043668)
		(width 0.0889)
		(layer "In4.Cu")
		(net "M_J_CPU1_SB_CA<5>")
	)
	(arc
		(start 136.231884 -264.043668)
		(mid 136.51484 -264.119845)
		(end 136.797796 -264.043668)
		(width 0.0889)
		(layer "In4.Cu")
		(net "M_J_CPU1_SB_CA<5>")
	)
	(arc
		(start 140.56614 -264.038842)
		(mid 140.749648 -263.993348)
		(end 140.9319 -264.043668)
		(width 0.0889)
		(layer "In4.Cu")
		(net "M_J_CPU1_SB_CA<5>")
	)
	(arc
		(start 144.317974 -264.043668)
		(mid 144.500479 -263.993191)
		(end 144.684242 -264.038842)
		(width 0.0889)
		(layer "In4.Cu")
		(net "M_J_CPU1_SB_CA<5>")
	)
	(arc
		(start 137.737596 -264.043668)
		(mid 137.919847 -263.993318)
		(end 138.103356 -264.038842)
		(width 0.0889)
		(layer "In4.Cu")
		(net "M_J_CPU1_SB_CA<5>")
	)
	(arc
		(start 142.437612 -264.043668)
		(mid 142.619863 -263.993318)
		(end 142.803372 -264.038842)
		(width 0.0889)
		(layer "In4.Cu")
		(net "M_J_CPU1_SB_CA<5>")
	)
	(arc
		(start 132.471922 -264.043668)
		(mid 132.754878 -264.119845)
		(end 133.037834 -264.043668)
		(width 0.0889)
		(layer "In4.Cu")
		(net "M_J_CPU1_SB_CA<5>")
	)
	(arc
		(start 145.25244 -264.047224)
		(mid 145.344872 -264.006942)
		(end 145.444718 -263.992868)
		(width 0.0889)
		(layer "In4.Cu")
		(net "M_J_CPU1_SB_CA<5>")
	)
	(arc
		(start 133.977634 -264.043668)
		(mid 134.159885 -263.993318)
		(end 134.343394 -264.038842)
		(width 0.0889)
		(layer "In4.Cu")
		(net "M_J_CPU1_SB_CA<5>")
	)
	(arc
		(start 137.171684 -264.043668)
		(mid 137.45464 -264.119845)
		(end 137.737596 -264.043668)
		(width 0.0889)
		(layer "In4.Cu")
		(net "M_J_CPU1_SB_CA<5>")
	)
	(arc
		(start 138.111738 -264.043668)
		(mid 138.394694 -264.119845)
		(end 138.67765 -264.043668)
		(width 0.0889)
		(layer "In4.Cu")
		(net "M_J_CPU1_SB_CA<5>")
	)
	(arc
		(start 141.8717 -264.043668)
		(mid 142.154656 -264.119845)
		(end 142.437612 -264.043668)
		(width 0.0889)
		(layer "In4.Cu")
		(net "M_J_CPU1_SB_CA<5>")
	)
	(arc
		(start 136.797796 -264.043668)
		(mid 136.98474 -263.993413)
		(end 137.171684 -264.043668)
		(width 0.0889)
		(layer "In4.Cu")
		(net "M_J_CPU1_SB_CA<5>")
	)
	(arc
		(start 131.595114 -264.075418)
		(mid 131.850179 -264.118769)
		(end 132.09778 -264.043668)
		(width 0.0889)
		(layer "In4.Cu")
		(net "M_J_CPU1_SB_CA<5>")
	)
	(arc
		(start 141.497812 -264.043668)
		(mid 141.684756 -263.993413)
		(end 141.8717 -264.043668)
		(width 0.0889)
		(layer "In4.Cu")
		(net "M_J_CPU1_SB_CA<5>")
	)
	(arc
		(start 143.762222 -264.049764)
		(mid 144.040908 -264.119984)
		(end 144.317974 -264.043668)
		(width 0.0889)
		(layer "In4.Cu")
		(net "M_J_CPU1_SB_CA<5>")
	)
	(arc
		(start 132.106162 -264.038842)
		(mid 132.28967 -263.993348)
		(end 132.471922 -264.043668)
		(width 0.0889)
		(layer "In4.Cu")
		(net "M_J_CPU1_SB_CA<5>")
	)
	(arc
		(start 142.811754 -264.043668)
		(mid 143.09471 -264.119845)
		(end 143.377666 -264.043668)
		(width 0.0889)
		(layer "In4.Cu")
		(net "M_J_CPU1_SB_CA<5>")
	)
	(arc
		(start 139.626086 -264.038842)
		(mid 139.809594 -263.993348)
		(end 139.991846 -264.043668)
		(width 0.0889)
		(layer "In4.Cu")
		(net "M_J_CPU1_SB_CA<5>")
	)
	(arc
		(start 133.411722 -264.043668)
		(mid 133.694678 -264.119845)
		(end 133.977634 -264.043668)
		(width 0.0889)
		(layer "In4.Cu")
		(net "M_J_CPU1_SB_CA<5>")
	)
	(arc
		(start 135.29183 -264.043668)
		(mid 135.574786 -264.119845)
		(end 135.857742 -264.043668)
		(width 0.0889)
		(layer "In4.Cu")
		(net "M_J_CPU1_SB_CA<5>")
	)
	(arc
		(start 138.67765 -264.043668)
		(mid 138.859901 -263.993318)
		(end 139.04341 -264.038842)
		(width 0.0889)
		(layer "In4.Cu")
		(net "M_J_CPU1_SB_CA<5>")
	)
	(arc
		(start 140.9319 -264.043668)
		(mid 141.214856 -264.119845)
		(end 141.497812 -264.043668)
		(width 0.0889)
		(layer "In4.Cu")
		(net "M_J_CPU1_SB_CA<5>")
	)
	(arc
		(start 135.866124 -264.038842)
		(mid 136.049632 -263.993348)
		(end 136.231884 -264.043668)
		(width 0.0889)
		(layer "In4.Cu")
		(net "M_J_CPU1_SB_CA<5>")
	)
	(arc
		(start 134.92607 -264.038842)
		(mid 135.109578 -263.993348)
		(end 135.29183 -264.043668)
		(width 0.0889)
		(layer "In4.Cu")
		(net "M_J_CPU1_SB_CA<5>")
	)
	(arc
		(start 143.386048 -264.038842)
		(mid 143.569556 -263.993348)
		(end 143.751808 -264.043668)
		(width 0.0889)
		(layer "In4.Cu")
		(net "M_J_CPU1_SB_CA<5>")
	)
	(arc
		(start 139.051792 -264.043668)
		(mid 139.334748 -264.119845)
		(end 139.617704 -264.043668)
		(width 0.0889)
		(layer "In4.Cu")
		(net "M_J_CPU1_SB_CA<5>")
	)
	(arc
		(start 139.991846 -264.043668)
		(mid 140.274802 -264.119845)
		(end 140.557758 -264.043668)
		(width 0.0889)
		(layer "In4.Cu")
		(net "M_J_CPU1_SB_CA<5>")
	)
	(arc
		(start 133.037834 -264.043668)
		(mid 133.224778 -263.993413)
		(end 133.411722 -264.043668)
		(width 0.0889)
		(layer "In4.Cu")
		(net "M_J_CPU1_SB_CA<5>")
	)
	(segment
		(start 131.347972 -263.290304)
		(end 131.814824 -263.556242)
		(width 0.10668)
		(layer "F.Cu")
		(net "M_J_CPU1_SB_CA<4>")
	)
	(segment
		(start 140.453364 -263.883648)
		(end 140.461746 -263.878822)
		(width 0.0889)
		(layer "In4.Cu")
		(net "M_J_CPU1_SB_CA<4>")
	)
	(segment
		(start 164.265102 -264.910316)
		(end 166.243 -264.910316)
		(width 0.14478)
		(layer "In4.Cu")
		(net "M_J_CPU1_SB_CA<4>")
	)
	(segment
		(start 166.243 -264.910316)
		(end 167.092884 -264.060432)
		(width 0.14478)
		(layer "In4.Cu")
		(net "M_J_CPU1_SB_CA<4>")
	)
	(segment
		(start 174.636938 -264.060432)
		(end 190.735204 -264.060432)
		(width 0.14478)
		(layer "In4.Cu")
		(net "M_J_CPU1_SB_CA<4>")
	)
	(segment
		(start 131.993386 -263.883648)
		(end 132.001768 -263.878822)
		(width 0.0889)
		(layer "In4.Cu")
		(net "M_J_CPU1_SB_CA<4>")
	)
	(segment
		(start 131.660646 -263.821672)
		(end 131.682998 -263.904984)
		(width 0.0889)
		(layer "In4.Cu")
		(net "M_J_CPU1_SB_CA<4>")
	)
	(segment
		(start 138.20775 -263.878822)
		(end 138.216132 -263.883648)
		(width 0.0889)
		(layer "In4.Cu")
		(net "M_J_CPU1_SB_CA<4>")
	)
	(segment
		(start 143.847566 -263.878822)
		(end 143.855948 -263.883648)
		(width 0.0889)
		(layer "In4.Cu")
		(net "M_J_CPU1_SB_CA<4>")
	)
	(segment
		(start 144.777968 -263.872726)
		(end 144.788382 -263.878822)
		(width 0.0889)
		(layer "In4.Cu")
		(net "M_J_CPU1_SB_CA<4>")
	)
	(segment
		(start 131.814824 -263.556242)
		(end 131.660646 -263.821672)
		(width 0.0889)
		(layer "In4.Cu")
		(net "M_J_CPU1_SB_CA<4>")
	)
	(segment
		(start 190.735204 -264.060432)
		(end 191.160146 -264.485374)
		(width 0.14478)
		(layer "In4.Cu")
		(net "M_J_CPU1_SB_CA<4>")
	)
	(segment
		(start 170.117516 -264.060432)
		(end 170.9674 -264.910316)
		(width 0.14478)
		(layer "In4.Cu")
		(net "M_J_CPU1_SB_CA<4>")
	)
	(segment
		(start 173.787054 -264.910316)
		(end 174.636938 -264.060432)
		(width 0.14478)
		(layer "In4.Cu")
		(net "M_J_CPU1_SB_CA<4>")
	)
	(segment
		(start 170.9674 -264.910316)
		(end 173.787054 -264.910316)
		(width 0.14478)
		(layer "In4.Cu")
		(net "M_J_CPU1_SB_CA<4>")
	)
	(segment
		(start 167.092884 -264.060432)
		(end 170.117516 -264.060432)
		(width 0.14478)
		(layer "In4.Cu")
		(net "M_J_CPU1_SB_CA<4>")
	)
	(segment
		(start 141.967712 -263.878822)
		(end 141.976094 -263.883648)
		(width 0.0889)
		(layer "In4.Cu")
		(net "M_J_CPU1_SB_CA<4>")
	)
	(segment
		(start 148.002244 -263.430004)
		(end 162.78479 -263.430004)
		(width 0.14478)
		(layer "In4.Cu")
		(net "M_J_CPU1_SB_CA<4>")
	)
	(segment
		(start 133.507734 -263.878822)
		(end 133.516116 -263.883648)
		(width 0.0889)
		(layer "In4.Cu")
		(net "M_J_CPU1_SB_CA<4>")
	)
	(segment
		(start 162.78479 -263.430004)
		(end 164.265102 -264.910316)
		(width 0.14478)
		(layer "In4.Cu")
		(net "M_J_CPU1_SB_CA<4>")
	)
	(segment
		(start 141.393418 -263.883648)
		(end 141.4018 -263.878822)
		(width 0.0889)
		(layer "In4.Cu")
		(net "M_J_CPU1_SB_CA<4>")
	)
	(segment
		(start 137.267696 -263.878822)
		(end 137.276078 -263.883648)
		(width 0.0889)
		(layer "In4.Cu")
		(net "M_J_CPU1_SB_CA<4>")
	)
	(segment
		(start 147.459954 -263.430004)
		(end 148.002244 -263.430004)
		(width 0.0889)
		(layer "In4.Cu")
		(net "M_J_CPU1_SB_CA<4>")
	)
	(segment
		(start 132.93344 -263.883648)
		(end 132.941822 -263.878822)
		(width 0.0889)
		(layer "In4.Cu")
		(net "M_J_CPU1_SB_CA<4>")
	)
	(segment
		(start 135.753348 -263.883648)
		(end 135.76173 -263.878822)
		(width 0.0889)
		(layer "In4.Cu")
		(net "M_J_CPU1_SB_CA<4>")
	)
	(segment
		(start 136.693402 -263.883648)
		(end 136.701784 -263.878822)
		(width 0.0889)
		(layer "In4.Cu")
		(net "M_J_CPU1_SB_CA<4>")
	)
	(segment
		(start 147.08759 -263.802368)
		(end 147.459954 -263.430004)
		(width 0.0889)
		(layer "In4.Cu")
		(net "M_J_CPU1_SB_CA<4>")
	)
	(segment
		(start 145.44421 -263.802368)
		(end 147.08759 -263.802368)
		(width 0.0889)
		(layer "In4.Cu")
		(net "M_J_CPU1_SB_CA<4>")
	)
	(arc
		(start 132.941822 -263.878822)
		(mid 133.224778 -263.802645)
		(end 133.507734 -263.878822)
		(width 0.0889)
		(layer "In4.Cu")
		(net "M_J_CPU1_SB_CA<4>")
	)
	(arc
		(start 139.521692 -263.878822)
		(mid 139.804648 -263.802645)
		(end 140.087604 -263.878822)
		(width 0.0889)
		(layer "In4.Cu")
		(net "M_J_CPU1_SB_CA<4>")
	)
	(arc
		(start 139.147804 -263.878822)
		(mid 139.334748 -263.929077)
		(end 139.521692 -263.878822)
		(width 0.0889)
		(layer "In4.Cu")
		(net "M_J_CPU1_SB_CA<4>")
	)
	(arc
		(start 138.216132 -263.883648)
		(mid 138.39964 -263.929142)
		(end 138.581892 -263.878822)
		(width 0.0889)
		(layer "In4.Cu")
		(net "M_J_CPU1_SB_CA<4>")
	)
	(arc
		(start 143.281654 -263.878822)
		(mid 143.56461 -263.802645)
		(end 143.847566 -263.878822)
		(width 0.0889)
		(layer "In4.Cu")
		(net "M_J_CPU1_SB_CA<4>")
	)
	(arc
		(start 137.276078 -263.883648)
		(mid 137.459586 -263.929142)
		(end 137.641838 -263.878822)
		(width 0.0889)
		(layer "In4.Cu")
		(net "M_J_CPU1_SB_CA<4>")
	)
	(arc
		(start 133.881876 -263.878822)
		(mid 134.164832 -263.802645)
		(end 134.447788 -263.878822)
		(width 0.0889)
		(layer "In4.Cu")
		(net "M_J_CPU1_SB_CA<4>")
	)
	(arc
		(start 142.341854 -263.878822)
		(mid 142.62481 -263.802645)
		(end 142.907766 -263.878822)
		(width 0.0889)
		(layer "In4.Cu")
		(net "M_J_CPU1_SB_CA<4>")
	)
	(arc
		(start 141.4018 -263.878822)
		(mid 141.684756 -263.802645)
		(end 141.967712 -263.878822)
		(width 0.0889)
		(layer "In4.Cu")
		(net "M_J_CPU1_SB_CA<4>")
	)
	(arc
		(start 143.855948 -263.883648)
		(mid 144.03971 -263.929264)
		(end 144.222216 -263.878822)
		(width 0.0889)
		(layer "In4.Cu")
		(net "M_J_CPU1_SB_CA<4>")
	)
	(arc
		(start 136.327642 -263.878822)
		(mid 136.509893 -263.929172)
		(end 136.693402 -263.883648)
		(width 0.0889)
		(layer "In4.Cu")
		(net "M_J_CPU1_SB_CA<4>")
	)
	(arc
		(start 134.821676 -263.878822)
		(mid 135.104632 -263.802645)
		(end 135.387588 -263.878822)
		(width 0.0889)
		(layer "In4.Cu")
		(net "M_J_CPU1_SB_CA<4>")
	)
	(arc
		(start 142.907766 -263.878822)
		(mid 143.09471 -263.929077)
		(end 143.281654 -263.878822)
		(width 0.0889)
		(layer "In4.Cu")
		(net "M_J_CPU1_SB_CA<4>")
	)
	(arc
		(start 132.001768 -263.878822)
		(mid 132.284724 -263.802645)
		(end 132.56768 -263.878822)
		(width 0.0889)
		(layer "In4.Cu")
		(net "M_J_CPU1_SB_CA<4>")
	)
	(arc
		(start 144.788382 -263.878822)
		(mid 144.966032 -263.929082)
		(end 145.146014 -263.887966)
		(width 0.0889)
		(layer "In4.Cu")
		(net "M_J_CPU1_SB_CA<4>")
	)
	(arc
		(start 136.701784 -263.878822)
		(mid 136.98474 -263.802645)
		(end 137.267696 -263.878822)
		(width 0.0889)
		(layer "In4.Cu")
		(net "M_J_CPU1_SB_CA<4>")
	)
	(arc
		(start 141.027658 -263.878822)
		(mid 141.209909 -263.929172)
		(end 141.393418 -263.883648)
		(width 0.0889)
		(layer "In4.Cu")
		(net "M_J_CPU1_SB_CA<4>")
	)
	(arc
		(start 145.146014 -263.887966)
		(mid 145.289108 -263.824249)
		(end 145.44421 -263.802368)
		(width 0.0889)
		(layer "In4.Cu")
		(net "M_J_CPU1_SB_CA<4>")
	)
	(arc
		(start 135.76173 -263.878822)
		(mid 136.044686 -263.802645)
		(end 136.327642 -263.878822)
		(width 0.0889)
		(layer "In4.Cu")
		(net "M_J_CPU1_SB_CA<4>")
	)
	(arc
		(start 141.976094 -263.883648)
		(mid 142.159602 -263.929142)
		(end 142.341854 -263.878822)
		(width 0.0889)
		(layer "In4.Cu")
		(net "M_J_CPU1_SB_CA<4>")
	)
	(arc
		(start 138.581892 -263.878822)
		(mid 138.864848 -263.802645)
		(end 139.147804 -263.878822)
		(width 0.0889)
		(layer "In4.Cu")
		(net "M_J_CPU1_SB_CA<4>")
	)
	(arc
		(start 140.461746 -263.878822)
		(mid 140.744702 -263.802645)
		(end 141.027658 -263.878822)
		(width 0.0889)
		(layer "In4.Cu")
		(net "M_J_CPU1_SB_CA<4>")
	)
	(arc
		(start 133.516116 -263.883648)
		(mid 133.699624 -263.929142)
		(end 133.881876 -263.878822)
		(width 0.0889)
		(layer "In4.Cu")
		(net "M_J_CPU1_SB_CA<4>")
	)
	(arc
		(start 140.087604 -263.878822)
		(mid 140.269855 -263.929172)
		(end 140.453364 -263.883648)
		(width 0.0889)
		(layer "In4.Cu")
		(net "M_J_CPU1_SB_CA<4>")
	)
	(arc
		(start 132.56768 -263.878822)
		(mid 132.749931 -263.929172)
		(end 132.93344 -263.883648)
		(width 0.0889)
		(layer "In4.Cu")
		(net "M_J_CPU1_SB_CA<4>")
	)
	(arc
		(start 144.222216 -263.878822)
		(mid 144.499283 -263.802551)
		(end 144.777968 -263.872726)
		(width 0.0889)
		(layer "In4.Cu")
		(net "M_J_CPU1_SB_CA<4>")
	)
	(arc
		(start 131.682998 -263.904984)
		(mid 131.840508 -263.928182)
		(end 131.993386 -263.883648)
		(width 0.0889)
		(layer "In4.Cu")
		(net "M_J_CPU1_SB_CA<4>")
	)
	(arc
		(start 135.387588 -263.878822)
		(mid 135.569839 -263.929172)
		(end 135.753348 -263.883648)
		(width 0.0889)
		(layer "In4.Cu")
		(net "M_J_CPU1_SB_CA<4>")
	)
	(arc
		(start 137.641838 -263.878822)
		(mid 137.924794 -263.802645)
		(end 138.20775 -263.878822)
		(width 0.0889)
		(layer "In4.Cu")
		(net "M_J_CPU1_SB_CA<4>")
	)
	(arc
		(start 134.447788 -263.878822)
		(mid 134.634732 -263.929077)
		(end 134.821676 -263.878822)
		(width 0.0889)
		(layer "In4.Cu")
		(net "M_J_CPU1_SB_CA<4>")
	)
	(segment
		(start 132.287772 -263.290304)
		(end 132.754878 -263.556242)
		(width 0.10668)
		(layer "F.Cu")
		(net "M_J_CPU1_SB_CA<3>")
	)
	(segment
		(start 158.298388 -262.442706)
		(end 158.526734 -262.442706)
		(width 0.14478)
		(layer "In4.Cu")
		(net "M_J_CPU1_SB_CA<3>")
	)
	(segment
		(start 144.220946 -263.233916)
		(end 144.242536 -263.246362)
		(width 0.0889)
		(layer "In4.Cu")
		(net "M_J_CPU1_SB_CA<3>")
	)
	(segment
		(start 158.136844 -262.8138)
		(end 158.136844 -262.60425)
		(width 0.14478)
		(layer "In4.Cu")
		(net "M_J_CPU1_SB_CA<3>")
	)
	(segment
		(start 170.18254 -263.210294)
		(end 171.032678 -264.060432)
		(width 0.14478)
		(layer "In4.Cu")
		(net "M_J_CPU1_SB_CA<3>")
	)
	(segment
		(start 133.507734 -263.233662)
		(end 133.516116 -263.228836)
		(width 0.0889)
		(layer "In4.Cu")
		(net "M_J_CPU1_SB_CA<3>")
	)
	(segment
		(start 141.393418 -263.228836)
		(end 141.4018 -263.233662)
		(width 0.0889)
		(layer "In4.Cu")
		(net "M_J_CPU1_SB_CA<3>")
	)
	(segment
		(start 159.95269 -262.975344)
		(end 162.973512 -262.975344)
		(width 0.14478)
		(layer "In4.Cu")
		(net "M_J_CPU1_SB_CA<3>")
	)
	(segment
		(start 157.423866 -262.442706)
		(end 157.58541 -262.60425)
		(width 0.14478)
		(layer "In4.Cu")
		(net "M_J_CPU1_SB_CA<3>")
	)
	(segment
		(start 159.239712 -262.8138)
		(end 159.239712 -262.60425)
		(width 0.14478)
		(layer "In4.Cu")
		(net "M_J_CPU1_SB_CA<3>")
	)
	(segment
		(start 132.908802 -263.290812)
		(end 133.004814 -263.265412)
		(width 0.0889)
		(layer "In4.Cu")
		(net "M_J_CPU1_SB_CA<3>")
	)
	(segment
		(start 173.69409 -264.060432)
		(end 174.544228 -263.210294)
		(width 0.14478)
		(layer "In4.Cu")
		(net "M_J_CPU1_SB_CA<3>")
	)
	(segment
		(start 158.849822 -262.975344)
		(end 159.078168 -262.975344)
		(width 0.14478)
		(layer "In4.Cu")
		(net "M_J_CPU1_SB_CA<3>")
	)
	(segment
		(start 145.444718 -263.31037)
		(end 146.141186 -263.31037)
		(width 0.0889)
		(layer "In4.Cu")
		(net "M_J_CPU1_SB_CA<3>")
	)
	(segment
		(start 167.000174 -263.210294)
		(end 170.18254 -263.210294)
		(width 0.14478)
		(layer "In4.Cu")
		(net "M_J_CPU1_SB_CA<3>")
	)
	(segment
		(start 144.785334 -263.233662)
		(end 144.80413 -263.22274)
		(width 0.0889)
		(layer "In4.Cu")
		(net "M_J_CPU1_SB_CA<3>")
	)
	(segment
		(start 157.033976 -262.60425)
		(end 157.19552 -262.442706)
		(width 0.14478)
		(layer "In4.Cu")
		(net "M_J_CPU1_SB_CA<3>")
	)
	(segment
		(start 157.19552 -262.442706)
		(end 157.423866 -262.442706)
		(width 0.14478)
		(layer "In4.Cu")
		(net "M_J_CPU1_SB_CA<3>")
	)
	(segment
		(start 157.033976 -262.8138)
		(end 157.033976 -262.60425)
		(width 0.14478)
		(layer "In4.Cu")
		(net "M_J_CPU1_SB_CA<3>")
	)
	(segment
		(start 159.078168 -262.975344)
		(end 159.239712 -262.8138)
		(width 0.14478)
		(layer "In4.Cu")
		(net "M_J_CPU1_SB_CA<3>")
	)
	(segment
		(start 157.58541 -262.8138)
		(end 157.746954 -262.975344)
		(width 0.14478)
		(layer "In4.Cu")
		(net "M_J_CPU1_SB_CA<3>")
	)
	(segment
		(start 159.791146 -262.8138)
		(end 159.95269 -262.975344)
		(width 0.14478)
		(layer "In4.Cu")
		(net "M_J_CPU1_SB_CA<3>")
	)
	(segment
		(start 164.0586 -264.060432)
		(end 166.150036 -264.060432)
		(width 0.14478)
		(layer "In4.Cu")
		(net "M_J_CPU1_SB_CA<3>")
	)
	(segment
		(start 158.526734 -262.442706)
		(end 158.688278 -262.60425)
		(width 0.14478)
		(layer "In4.Cu")
		(net "M_J_CPU1_SB_CA<3>")
	)
	(segment
		(start 157.9753 -262.975344)
		(end 158.136844 -262.8138)
		(width 0.14478)
		(layer "In4.Cu")
		(net "M_J_CPU1_SB_CA<3>")
	)
	(segment
		(start 159.791146 -262.60425)
		(end 159.791146 -262.8138)
		(width 0.14478)
		(layer "In4.Cu")
		(net "M_J_CPU1_SB_CA<3>")
	)
	(segment
		(start 159.629602 -262.442706)
		(end 159.791146 -262.60425)
		(width 0.14478)
		(layer "In4.Cu")
		(net "M_J_CPU1_SB_CA<3>")
	)
	(segment
		(start 132.754878 -263.556242)
		(end 132.908802 -263.290812)
		(width 0.0889)
		(layer "In4.Cu")
		(net "M_J_CPU1_SB_CA<3>")
	)
	(segment
		(start 148.009864 -262.975344)
		(end 156.872432 -262.975344)
		(width 0.14478)
		(layer "In4.Cu")
		(net "M_J_CPU1_SB_CA<3>")
	)
	(segment
		(start 146.141186 -263.31037)
		(end 146.527012 -262.924544)
		(width 0.0889)
		(layer "In4.Cu")
		(net "M_J_CPU1_SB_CA<3>")
	)
	(segment
		(start 147.348194 -262.975344)
		(end 148.009864 -262.975344)
		(width 0.0889)
		(layer "In4.Cu")
		(net "M_J_CPU1_SB_CA<3>")
	)
	(segment
		(start 146.527012 -262.924544)
		(end 147.297394 -262.924544)
		(width 0.0889)
		(layer "In4.Cu")
		(net "M_J_CPU1_SB_CA<3>")
	)
	(segment
		(start 159.401256 -262.442706)
		(end 159.629602 -262.442706)
		(width 0.14478)
		(layer "In4.Cu")
		(net "M_J_CPU1_SB_CA<3>")
	)
	(segment
		(start 186.635136 -263.210294)
		(end 187.060078 -263.635236)
		(width 0.14478)
		(layer "In4.Cu")
		(net "M_J_CPU1_SB_CA<3>")
	)
	(segment
		(start 147.297394 -262.924544)
		(end 147.348194 -262.975344)
		(width 0.0889)
		(layer "In4.Cu")
		(net "M_J_CPU1_SB_CA<3>")
	)
	(segment
		(start 158.688278 -262.8138)
		(end 158.849822 -262.975344)
		(width 0.14478)
		(layer "In4.Cu")
		(net "M_J_CPU1_SB_CA<3>")
	)
	(segment
		(start 157.58541 -262.60425)
		(end 157.58541 -262.8138)
		(width 0.14478)
		(layer "In4.Cu")
		(net "M_J_CPU1_SB_CA<3>")
	)
	(segment
		(start 140.453364 -263.228836)
		(end 140.461746 -263.233662)
		(width 0.0889)
		(layer "In4.Cu")
		(net "M_J_CPU1_SB_CA<3>")
	)
	(segment
		(start 157.746954 -262.975344)
		(end 157.9753 -262.975344)
		(width 0.14478)
		(layer "In4.Cu")
		(net "M_J_CPU1_SB_CA<3>")
	)
	(segment
		(start 174.544228 -263.210294)
		(end 186.635136 -263.210294)
		(width 0.14478)
		(layer "In4.Cu")
		(net "M_J_CPU1_SB_CA<3>")
	)
	(segment
		(start 162.973512 -262.975344)
		(end 164.0586 -264.060432)
		(width 0.14478)
		(layer "In4.Cu")
		(net "M_J_CPU1_SB_CA<3>")
	)
	(segment
		(start 156.872432 -262.975344)
		(end 157.033976 -262.8138)
		(width 0.14478)
		(layer "In4.Cu")
		(net "M_J_CPU1_SB_CA<3>")
	)
	(segment
		(start 136.693402 -263.228836)
		(end 136.701784 -263.233662)
		(width 0.0889)
		(layer "In4.Cu")
		(net "M_J_CPU1_SB_CA<3>")
	)
	(segment
		(start 137.267696 -263.233662)
		(end 137.276078 -263.228836)
		(width 0.0889)
		(layer "In4.Cu")
		(net "M_J_CPU1_SB_CA<3>")
	)
	(segment
		(start 166.150036 -264.060432)
		(end 167.000174 -263.210294)
		(width 0.14478)
		(layer "In4.Cu")
		(net "M_J_CPU1_SB_CA<3>")
	)
	(segment
		(start 138.20775 -263.233662)
		(end 138.216132 -263.228836)
		(width 0.0889)
		(layer "In4.Cu")
		(net "M_J_CPU1_SB_CA<3>")
	)
	(segment
		(start 158.136844 -262.60425)
		(end 158.298388 -262.442706)
		(width 0.14478)
		(layer "In4.Cu")
		(net "M_J_CPU1_SB_CA<3>")
	)
	(segment
		(start 144.20088 -263.222486)
		(end 144.220946 -263.233916)
		(width 0.0889)
		(layer "In4.Cu")
		(net "M_J_CPU1_SB_CA<3>")
	)
	(segment
		(start 141.967712 -263.233662)
		(end 141.976094 -263.228836)
		(width 0.0889)
		(layer "In4.Cu")
		(net "M_J_CPU1_SB_CA<3>")
	)
	(segment
		(start 135.753348 -263.228836)
		(end 135.76173 -263.233662)
		(width 0.0889)
		(layer "In4.Cu")
		(net "M_J_CPU1_SB_CA<3>")
	)
	(segment
		(start 158.688278 -262.60425)
		(end 158.688278 -262.8138)
		(width 0.14478)
		(layer "In4.Cu")
		(net "M_J_CPU1_SB_CA<3>")
	)
	(segment
		(start 159.239712 -262.60425)
		(end 159.401256 -262.442706)
		(width 0.14478)
		(layer "In4.Cu")
		(net "M_J_CPU1_SB_CA<3>")
	)
	(segment
		(start 171.032678 -264.060432)
		(end 173.69409 -264.060432)
		(width 0.14478)
		(layer "In4.Cu")
		(net "M_J_CPU1_SB_CA<3>")
	)
	(arc
		(start 133.516116 -263.228836)
		(mid 133.699624 -263.183342)
		(end 133.881876 -263.233662)
		(width 0.0889)
		(layer "In4.Cu")
		(net "M_J_CPU1_SB_CA<3>")
	)
	(arc
		(start 143.281654 -263.233662)
		(mid 143.56461 -263.309839)
		(end 143.847566 -263.233662)
		(width 0.0889)
		(layer "In4.Cu")
		(net "M_J_CPU1_SB_CA<3>")
	)
	(arc
		(start 140.461746 -263.233662)
		(mid 140.744702 -263.309839)
		(end 141.027658 -263.233662)
		(width 0.0889)
		(layer "In4.Cu")
		(net "M_J_CPU1_SB_CA<3>")
	)
	(arc
		(start 139.147804 -263.233662)
		(mid 139.334748 -263.183407)
		(end 139.521692 -263.233662)
		(width 0.0889)
		(layer "In4.Cu")
		(net "M_J_CPU1_SB_CA<3>")
	)
	(arc
		(start 142.341854 -263.233662)
		(mid 142.62481 -263.309839)
		(end 142.907766 -263.233662)
		(width 0.0889)
		(layer "In4.Cu")
		(net "M_J_CPU1_SB_CA<3>")
	)
	(arc
		(start 135.76173 -263.233662)
		(mid 136.044686 -263.309839)
		(end 136.327642 -263.233662)
		(width 0.0889)
		(layer "In4.Cu")
		(net "M_J_CPU1_SB_CA<3>")
	)
	(arc
		(start 134.447788 -263.233662)
		(mid 134.634732 -263.183407)
		(end 134.821676 -263.233662)
		(width 0.0889)
		(layer "In4.Cu")
		(net "M_J_CPU1_SB_CA<3>")
	)
	(arc
		(start 144.80413 -263.22274)
		(mid 144.983701 -263.182923)
		(end 145.160492 -263.233662)
		(width 0.0889)
		(layer "In4.Cu")
		(net "M_J_CPU1_SB_CA<3>")
	)
	(arc
		(start 142.907766 -263.233662)
		(mid 143.09471 -263.183407)
		(end 143.281654 -263.233662)
		(width 0.0889)
		(layer "In4.Cu")
		(net "M_J_CPU1_SB_CA<3>")
	)
	(arc
		(start 141.4018 -263.233662)
		(mid 141.684756 -263.309839)
		(end 141.967712 -263.233662)
		(width 0.0889)
		(layer "In4.Cu")
		(net "M_J_CPU1_SB_CA<3>")
	)
	(arc
		(start 136.327642 -263.233662)
		(mid 136.509893 -263.183312)
		(end 136.693402 -263.228836)
		(width 0.0889)
		(layer "In4.Cu")
		(net "M_J_CPU1_SB_CA<3>")
	)
	(arc
		(start 138.216132 -263.228836)
		(mid 138.39964 -263.183342)
		(end 138.581892 -263.233662)
		(width 0.0889)
		(layer "In4.Cu")
		(net "M_J_CPU1_SB_CA<3>")
	)
	(arc
		(start 133.004814 -263.265412)
		(mid 133.260022 -263.308889)
		(end 133.507734 -263.233662)
		(width 0.0889)
		(layer "In4.Cu")
		(net "M_J_CPU1_SB_CA<3>")
	)
	(arc
		(start 133.881876 -263.233662)
		(mid 134.164832 -263.309839)
		(end 134.447788 -263.233662)
		(width 0.0889)
		(layer "In4.Cu")
		(net "M_J_CPU1_SB_CA<3>")
	)
	(arc
		(start 140.087604 -263.233662)
		(mid 140.269855 -263.183312)
		(end 140.453364 -263.228836)
		(width 0.0889)
		(layer "In4.Cu")
		(net "M_J_CPU1_SB_CA<3>")
	)
	(arc
		(start 141.027658 -263.233662)
		(mid 141.209909 -263.183312)
		(end 141.393418 -263.228836)
		(width 0.0889)
		(layer "In4.Cu")
		(net "M_J_CPU1_SB_CA<3>")
	)
	(arc
		(start 141.976094 -263.228836)
		(mid 142.159602 -263.183342)
		(end 142.341854 -263.233662)
		(width 0.0889)
		(layer "In4.Cu")
		(net "M_J_CPU1_SB_CA<3>")
	)
	(arc
		(start 138.581892 -263.233662)
		(mid 138.864848 -263.309839)
		(end 139.147804 -263.233662)
		(width 0.0889)
		(layer "In4.Cu")
		(net "M_J_CPU1_SB_CA<3>")
	)
	(arc
		(start 144.242536 -263.246362)
		(mid 144.515565 -263.309681)
		(end 144.785334 -263.233662)
		(width 0.0889)
		(layer "In4.Cu")
		(net "M_J_CPU1_SB_CA<3>")
	)
	(arc
		(start 139.521692 -263.233662)
		(mid 139.804648 -263.309839)
		(end 140.087604 -263.233662)
		(width 0.0889)
		(layer "In4.Cu")
		(net "M_J_CPU1_SB_CA<3>")
	)
	(arc
		(start 143.847566 -263.233662)
		(mid 144.022805 -263.183591)
		(end 144.20088 -263.222486)
		(width 0.0889)
		(layer "In4.Cu")
		(net "M_J_CPU1_SB_CA<3>")
	)
	(arc
		(start 137.641838 -263.233662)
		(mid 137.924794 -263.309839)
		(end 138.20775 -263.233662)
		(width 0.0889)
		(layer "In4.Cu")
		(net "M_J_CPU1_SB_CA<3>")
	)
	(arc
		(start 134.821676 -263.233662)
		(mid 135.104632 -263.309839)
		(end 135.387588 -263.233662)
		(width 0.0889)
		(layer "In4.Cu")
		(net "M_J_CPU1_SB_CA<3>")
	)
	(arc
		(start 136.701784 -263.233662)
		(mid 136.98474 -263.309839)
		(end 137.267696 -263.233662)
		(width 0.0889)
		(layer "In4.Cu")
		(net "M_J_CPU1_SB_CA<3>")
	)
	(arc
		(start 145.160492 -263.233662)
		(mid 145.297514 -263.290873)
		(end 145.444718 -263.31037)
		(width 0.0889)
		(layer "In4.Cu")
		(net "M_J_CPU1_SB_CA<3>")
	)
	(arc
		(start 137.276078 -263.228836)
		(mid 137.459586 -263.183342)
		(end 137.641838 -263.233662)
		(width 0.0889)
		(layer "In4.Cu")
		(net "M_J_CPU1_SB_CA<3>")
	)
	(arc
		(start 135.387588 -263.233662)
		(mid 135.569839 -263.183312)
		(end 135.753348 -263.228836)
		(width 0.0889)
		(layer "In4.Cu")
		(net "M_J_CPU1_SB_CA<3>")
	)
	(segment
		(start 132.757926 -262.480298)
		(end 133.224778 -262.746236)
		(width 0.10668)
		(layer "F.Cu")
		(net "M_J_CPU1_SB_CA<2>")
	)
	(segment
		(start 190.735204 -262.36041)
		(end 191.160146 -262.785352)
		(width 0.14478)
		(layer "In4.Cu")
		(net "M_J_CPU1_SB_CA<2>")
	)
	(segment
		(start 167.092884 -262.36041)
		(end 170.117516 -262.36041)
		(width 0.14478)
		(layer "In4.Cu")
		(net "M_J_CPU1_SB_CA<2>")
	)
	(segment
		(start 170.9674 -263.210294)
		(end 173.787054 -263.210294)
		(width 0.14478)
		(layer "In4.Cu")
		(net "M_J_CPU1_SB_CA<2>")
	)
	(segment
		(start 156.25445 -262.520684)
		(end 156.782008 -261.993126)
		(width 0.14478)
		(layer "In4.Cu")
		(net "M_J_CPU1_SB_CA<2>")
	)
	(segment
		(start 160.599628 -262.525764)
		(end 163.46424 -262.525764)
		(width 0.14478)
		(layer "In4.Cu")
		(net "M_J_CPU1_SB_CA<2>")
	)
	(segment
		(start 147.169378 -262.721344)
		(end 147.370038 -262.520684)
		(width 0.0889)
		(layer "In4.Cu")
		(net "M_J_CPU1_SB_CA<2>")
	)
	(segment
		(start 170.117516 -262.36041)
		(end 170.9674 -263.210294)
		(width 0.14478)
		(layer "In4.Cu")
		(net "M_J_CPU1_SB_CA<2>")
	)
	(segment
		(start 135.857742 -263.068816)
		(end 135.866124 -263.073642)
		(width 0.0889)
		(layer "In4.Cu")
		(net "M_J_CPU1_SB_CA<2>")
	)
	(segment
		(start 139.617704 -263.068816)
		(end 139.626086 -263.073642)
		(width 0.0889)
		(layer "In4.Cu")
		(net "M_J_CPU1_SB_CA<2>")
	)
	(segment
		(start 145.444718 -263.119616)
		(end 145.444972 -263.11987)
		(width 0.0889)
		(layer "In4.Cu")
		(net "M_J_CPU1_SB_CA<2>")
	)
	(segment
		(start 173.787054 -263.210294)
		(end 174.636938 -262.36041)
		(width 0.14478)
		(layer "In4.Cu")
		(net "M_J_CPU1_SB_CA<2>")
	)
	(segment
		(start 134.917688 -263.068816)
		(end 134.92607 -263.073642)
		(width 0.0889)
		(layer "In4.Cu")
		(net "M_J_CPU1_SB_CA<2>")
	)
	(segment
		(start 146.440652 -262.721344)
		(end 147.169378 -262.721344)
		(width 0.0889)
		(layer "In4.Cu")
		(net "M_J_CPU1_SB_CA<2>")
	)
	(segment
		(start 166.243 -263.210294)
		(end 167.092884 -262.36041)
		(width 0.14478)
		(layer "In4.Cu")
		(net "M_J_CPU1_SB_CA<2>")
	)
	(segment
		(start 139.04341 -263.073642)
		(end 139.051792 -263.068816)
		(width 0.0889)
		(layer "In4.Cu")
		(net "M_J_CPU1_SB_CA<2>")
	)
	(segment
		(start 144.689322 -263.068816)
		(end 144.71269 -263.0551)
		(width 0.0889)
		(layer "In4.Cu")
		(net "M_J_CPU1_SB_CA<2>")
	)
	(segment
		(start 163.46424 -262.525764)
		(end 164.14877 -263.210294)
		(width 0.14478)
		(layer "In4.Cu")
		(net "M_J_CPU1_SB_CA<2>")
	)
	(segment
		(start 140.557758 -263.068816)
		(end 140.56614 -263.073642)
		(width 0.0889)
		(layer "In4.Cu")
		(net "M_J_CPU1_SB_CA<2>")
	)
	(segment
		(start 160.06699 -261.993126)
		(end 160.599628 -262.525764)
		(width 0.14478)
		(layer "In4.Cu")
		(net "M_J_CPU1_SB_CA<2>")
	)
	(segment
		(start 174.636938 -262.36041)
		(end 190.735204 -262.36041)
		(width 0.14478)
		(layer "In4.Cu")
		(net "M_J_CPU1_SB_CA<2>")
	)
	(segment
		(start 142.803372 -263.073642)
		(end 142.811754 -263.068816)
		(width 0.0889)
		(layer "In4.Cu")
		(net "M_J_CPU1_SB_CA<2>")
	)
	(segment
		(start 148.016468 -262.520684)
		(end 156.25445 -262.520684)
		(width 0.14478)
		(layer "In4.Cu")
		(net "M_J_CPU1_SB_CA<2>")
	)
	(segment
		(start 147.370038 -262.520684)
		(end 148.016468 -262.520684)
		(width 0.0889)
		(layer "In4.Cu")
		(net "M_J_CPU1_SB_CA<2>")
	)
	(segment
		(start 134.343394 -263.073642)
		(end 134.351776 -263.068816)
		(width 0.0889)
		(layer "In4.Cu")
		(net "M_J_CPU1_SB_CA<2>")
	)
	(segment
		(start 138.103356 -263.073642)
		(end 138.111738 -263.068816)
		(width 0.0889)
		(layer "In4.Cu")
		(net "M_J_CPU1_SB_CA<2>")
	)
	(segment
		(start 146.042126 -263.11987)
		(end 146.440652 -262.721344)
		(width 0.0889)
		(layer "In4.Cu")
		(net "M_J_CPU1_SB_CA<2>")
	)
	(segment
		(start 156.782008 -261.993126)
		(end 160.06699 -261.993126)
		(width 0.14478)
		(layer "In4.Cu")
		(net "M_J_CPU1_SB_CA<2>")
	)
	(segment
		(start 145.444972 -263.11987)
		(end 146.042126 -263.11987)
		(width 0.0889)
		(layer "In4.Cu")
		(net "M_J_CPU1_SB_CA<2>")
	)
	(segment
		(start 144.294606 -263.056116)
		(end 144.316196 -263.068562)
		(width 0.0889)
		(layer "In4.Cu")
		(net "M_J_CPU1_SB_CA<2>")
	)
	(segment
		(start 133.224778 -262.746236)
		(end 133.070854 -263.011666)
		(width 0.0889)
		(layer "In4.Cu")
		(net "M_J_CPU1_SB_CA<2>")
	)
	(segment
		(start 143.377666 -263.068816)
		(end 143.386048 -263.073642)
		(width 0.0889)
		(layer "In4.Cu")
		(net "M_J_CPU1_SB_CA<2>")
	)
	(segment
		(start 133.070854 -263.011666)
		(end 133.093206 -263.094978)
		(width 0.0889)
		(layer "In4.Cu")
		(net "M_J_CPU1_SB_CA<2>")
	)
	(segment
		(start 164.14877 -263.210294)
		(end 166.243 -263.210294)
		(width 0.14478)
		(layer "In4.Cu")
		(net "M_J_CPU1_SB_CA<2>")
	)
	(segment
		(start 144.316196 -263.068562)
		(end 144.334484 -263.078976)
		(width 0.0889)
		(layer "In4.Cu")
		(net "M_J_CPU1_SB_CA<2>")
	)
	(arc
		(start 135.866124 -263.073642)
		(mid 136.049632 -263.119136)
		(end 136.231884 -263.068816)
		(width 0.0889)
		(layer "In4.Cu")
		(net "M_J_CPU1_SB_CA<2>")
	)
	(arc
		(start 137.171684 -263.068816)
		(mid 137.45464 -262.992639)
		(end 137.737596 -263.068816)
		(width 0.0889)
		(layer "In4.Cu")
		(net "M_J_CPU1_SB_CA<2>")
	)
	(arc
		(start 142.811754 -263.068816)
		(mid 143.09471 -262.992639)
		(end 143.377666 -263.068816)
		(width 0.0889)
		(layer "In4.Cu")
		(net "M_J_CPU1_SB_CA<2>")
	)
	(arc
		(start 134.92607 -263.073642)
		(mid 135.109578 -263.119136)
		(end 135.29183 -263.068816)
		(width 0.0889)
		(layer "In4.Cu")
		(net "M_J_CPU1_SB_CA<2>")
	)
	(arc
		(start 143.751808 -263.068816)
		(mid 144.021577 -262.992793)
		(end 144.294606 -263.056116)
		(width 0.0889)
		(layer "In4.Cu")
		(net "M_J_CPU1_SB_CA<2>")
	)
	(arc
		(start 145.256504 -263.068816)
		(mid 145.347239 -263.1067)
		(end 145.444718 -263.119616)
		(width 0.0889)
		(layer "In4.Cu")
		(net "M_J_CPU1_SB_CA<2>")
	)
	(arc
		(start 141.497812 -263.068816)
		(mid 141.684756 -263.119071)
		(end 141.8717 -263.068816)
		(width 0.0889)
		(layer "In4.Cu")
		(net "M_J_CPU1_SB_CA<2>")
	)
	(arc
		(start 136.797796 -263.068816)
		(mid 136.98474 -263.119071)
		(end 137.171684 -263.068816)
		(width 0.0889)
		(layer "In4.Cu")
		(net "M_J_CPU1_SB_CA<2>")
	)
	(arc
		(start 138.67765 -263.068816)
		(mid 138.859901 -263.119166)
		(end 139.04341 -263.073642)
		(width 0.0889)
		(layer "In4.Cu")
		(net "M_J_CPU1_SB_CA<2>")
	)
	(arc
		(start 133.411722 -263.068816)
		(mid 133.694678 -262.992639)
		(end 133.977634 -263.068816)
		(width 0.0889)
		(layer "In4.Cu")
		(net "M_J_CPU1_SB_CA<2>")
	)
	(arc
		(start 140.56614 -263.073642)
		(mid 140.749648 -263.119136)
		(end 140.9319 -263.068816)
		(width 0.0889)
		(layer "In4.Cu")
		(net "M_J_CPU1_SB_CA<2>")
	)
	(arc
		(start 139.626086 -263.073642)
		(mid 139.809594 -263.119136)
		(end 139.991846 -263.068816)
		(width 0.0889)
		(layer "In4.Cu")
		(net "M_J_CPU1_SB_CA<2>")
	)
	(arc
		(start 139.051792 -263.068816)
		(mid 139.334748 -262.992639)
		(end 139.617704 -263.068816)
		(width 0.0889)
		(layer "In4.Cu")
		(net "M_J_CPU1_SB_CA<2>")
	)
	(arc
		(start 138.111738 -263.068816)
		(mid 138.394694 -262.992639)
		(end 138.67765 -263.068816)
		(width 0.0889)
		(layer "In4.Cu")
		(net "M_J_CPU1_SB_CA<2>")
	)
	(arc
		(start 139.991846 -263.068816)
		(mid 140.274802 -262.992639)
		(end 140.557758 -263.068816)
		(width 0.0889)
		(layer "In4.Cu")
		(net "M_J_CPU1_SB_CA<2>")
	)
	(arc
		(start 136.231884 -263.068816)
		(mid 136.51484 -262.992639)
		(end 136.797796 -263.068816)
		(width 0.0889)
		(layer "In4.Cu")
		(net "M_J_CPU1_SB_CA<2>")
	)
	(arc
		(start 133.093206 -263.094978)
		(mid 133.255395 -263.117713)
		(end 133.411722 -263.068816)
		(width 0.0889)
		(layer "In4.Cu")
		(net "M_J_CPU1_SB_CA<2>")
	)
	(arc
		(start 140.9319 -263.068816)
		(mid 141.214856 -262.992639)
		(end 141.497812 -263.068816)
		(width 0.0889)
		(layer "In4.Cu")
		(net "M_J_CPU1_SB_CA<2>")
	)
	(arc
		(start 144.334484 -263.078976)
		(mid 144.513205 -263.118899)
		(end 144.689322 -263.068816)
		(width 0.0889)
		(layer "In4.Cu")
		(net "M_J_CPU1_SB_CA<2>")
	)
	(arc
		(start 135.29183 -263.068816)
		(mid 135.574786 -262.992639)
		(end 135.857742 -263.068816)
		(width 0.0889)
		(layer "In4.Cu")
		(net "M_J_CPU1_SB_CA<2>")
	)
	(arc
		(start 137.737596 -263.068816)
		(mid 137.919847 -263.119166)
		(end 138.103356 -263.073642)
		(width 0.0889)
		(layer "In4.Cu")
		(net "M_J_CPU1_SB_CA<2>")
	)
	(arc
		(start 134.351776 -263.068816)
		(mid 134.634732 -262.992639)
		(end 134.917688 -263.068816)
		(width 0.0889)
		(layer "In4.Cu")
		(net "M_J_CPU1_SB_CA<2>")
	)
	(arc
		(start 143.386048 -263.073642)
		(mid 143.569556 -263.119136)
		(end 143.751808 -263.068816)
		(width 0.0889)
		(layer "In4.Cu")
		(net "M_J_CPU1_SB_CA<2>")
	)
	(arc
		(start 144.71269 -263.0551)
		(mid 144.986344 -262.992157)
		(end 145.256504 -263.068816)
		(width 0.0889)
		(layer "In4.Cu")
		(net "M_J_CPU1_SB_CA<2>")
	)
	(arc
		(start 133.977634 -263.068816)
		(mid 134.159885 -263.119166)
		(end 134.343394 -263.073642)
		(width 0.0889)
		(layer "In4.Cu")
		(net "M_J_CPU1_SB_CA<2>")
	)
	(arc
		(start 141.8717 -263.068816)
		(mid 142.154656 -262.992639)
		(end 142.437612 -263.068816)
		(width 0.0889)
		(layer "In4.Cu")
		(net "M_J_CPU1_SB_CA<2>")
	)
	(arc
		(start 142.437612 -263.068816)
		(mid 142.619863 -263.119166)
		(end 142.803372 -263.073642)
		(width 0.0889)
		(layer "In4.Cu")
		(net "M_J_CPU1_SB_CA<2>")
	)
	(segment
		(start 130.877818 -262.480298)
		(end 131.34467 -262.746236)
		(width 0.10668)
		(layer "F.Cu")
		(net "M_J_CPU1_SB_CA<1>")
	)
	(segment
		(start 139.617704 -262.423656)
		(end 139.626086 -262.41883)
		(width 0.0889)
		(layer "In4.Cu")
		(net "M_J_CPU1_SB_CA<1>")
	)
	(segment
		(start 179.63388 -261.204964)
		(end 179.939188 -261.510272)
		(width 0.14478)
		(layer "In4.Cu")
		(net "M_J_CPU1_SB_CA<1>")
	)
	(segment
		(start 131.498848 -262.480806)
		(end 131.595114 -262.455406)
		(width 0.0889)
		(layer "In4.Cu")
		(net "M_J_CPU1_SB_CA<1>")
	)
	(segment
		(start 164.136832 -262.36041)
		(end 166.150036 -262.36041)
		(width 0.14478)
		(layer "In4.Cu")
		(net "M_J_CPU1_SB_CA<1>")
	)
	(segment
		(start 186.635136 -261.510272)
		(end 187.060078 -261.935214)
		(width 0.14478)
		(layer "In4.Cu")
		(net "M_J_CPU1_SB_CA<1>")
	)
	(segment
		(start 161.975546 -261.980426)
		(end 162.203892 -261.980426)
		(width 0.14478)
		(layer "In4.Cu")
		(net "M_J_CPU1_SB_CA<1>")
	)
	(segment
		(start 177.964338 -261.510272)
		(end 178.269646 -261.204964)
		(width 0.14478)
		(layer "In4.Cu")
		(net "M_J_CPU1_SB_CA<1>")
	)
	(segment
		(start 147.4851 -262.066024)
		(end 148.019262 -262.066024)
		(width 0.0889)
		(layer "In4.Cu")
		(net "M_J_CPU1_SB_CA<1>")
	)
	(segment
		(start 182.721758 -261.204964)
		(end 182.972964 -261.204964)
		(width 0.14478)
		(layer "In4.Cu")
		(net "M_J_CPU1_SB_CA<1>")
	)
	(segment
		(start 178.269646 -261.204964)
		(end 178.520852 -261.204964)
		(width 0.14478)
		(layer "In4.Cu")
		(net "M_J_CPU1_SB_CA<1>")
	)
	(segment
		(start 142.803372 -262.41883)
		(end 142.811754 -262.423656)
		(width 0.0889)
		(layer "In4.Cu")
		(net "M_J_CPU1_SB_CA<1>")
	)
	(segment
		(start 167.000174 -261.510272)
		(end 170.18254 -261.510272)
		(width 0.14478)
		(layer "In4.Cu")
		(net "M_J_CPU1_SB_CA<1>")
	)
	(segment
		(start 178.82616 -261.510272)
		(end 179.077366 -261.510272)
		(width 0.14478)
		(layer "In4.Cu")
		(net "M_J_CPU1_SB_CA<1>")
	)
	(segment
		(start 160.711134 -261.818882)
		(end 160.872678 -261.980426)
		(width 0.14478)
		(layer "In4.Cu")
		(net "M_J_CPU1_SB_CA<1>")
	)
	(segment
		(start 177.713132 -261.510272)
		(end 177.964338 -261.510272)
		(width 0.14478)
		(layer "In4.Cu")
		(net "M_J_CPU1_SB_CA<1>")
	)
	(segment
		(start 162.52698 -261.109968)
		(end 162.88639 -261.109968)
		(width 0.14478)
		(layer "In4.Cu")
		(net "M_J_CPU1_SB_CA<1>")
	)
	(segment
		(start 162.88639 -261.109968)
		(end 164.136832 -262.36041)
		(width 0.14478)
		(layer "In4.Cu")
		(net "M_J_CPU1_SB_CA<1>")
	)
	(segment
		(start 182.41645 -261.510272)
		(end 182.721758 -261.204964)
		(width 0.14478)
		(layer "In4.Cu")
		(net "M_J_CPU1_SB_CA<1>")
	)
	(segment
		(start 161.652458 -261.109968)
		(end 161.814002 -261.271512)
		(width 0.14478)
		(layer "In4.Cu")
		(net "M_J_CPU1_SB_CA<1>")
	)
	(segment
		(start 145.444718 -262.372856)
		(end 147.178268 -262.372856)
		(width 0.0889)
		(layer "In4.Cu")
		(net "M_J_CPU1_SB_CA<1>")
	)
	(segment
		(start 179.077366 -261.510272)
		(end 179.382674 -261.204964)
		(width 0.14478)
		(layer "In4.Cu")
		(net "M_J_CPU1_SB_CA<1>")
	)
	(segment
		(start 177.407824 -261.204964)
		(end 177.713132 -261.510272)
		(width 0.14478)
		(layer "In4.Cu")
		(net "M_J_CPU1_SB_CA<1>")
	)
	(segment
		(start 131.34467 -262.746236)
		(end 131.498848 -262.480806)
		(width 0.0889)
		(layer "In4.Cu")
		(net "M_J_CPU1_SB_CA<1>")
	)
	(segment
		(start 173.69409 -262.36041)
		(end 174.544228 -261.510272)
		(width 0.14478)
		(layer "In4.Cu")
		(net "M_J_CPU1_SB_CA<1>")
	)
	(segment
		(start 161.814002 -261.818882)
		(end 161.975546 -261.980426)
		(width 0.14478)
		(layer "In4.Cu")
		(net "M_J_CPU1_SB_CA<1>")
	)
	(segment
		(start 183.278272 -261.510272)
		(end 186.635136 -261.510272)
		(width 0.14478)
		(layer "In4.Cu")
		(net "M_J_CPU1_SB_CA<1>")
	)
	(segment
		(start 148.019262 -262.066024)
		(end 155.786074 -262.066024)
		(width 0.14478)
		(layer "In4.Cu")
		(net "M_J_CPU1_SB_CA<1>")
	)
	(segment
		(start 132.09778 -262.423656)
		(end 132.106162 -262.41883)
		(width 0.0889)
		(layer "In4.Cu")
		(net "M_J_CPU1_SB_CA<1>")
	)
	(segment
		(start 143.377666 -262.423656)
		(end 143.386048 -262.41883)
		(width 0.0889)
		(layer "In4.Cu")
		(net "M_J_CPU1_SB_CA<1>")
	)
	(segment
		(start 160.54959 -261.109968)
		(end 160.711134 -261.271512)
		(width 0.14478)
		(layer "In4.Cu")
		(net "M_J_CPU1_SB_CA<1>")
	)
	(segment
		(start 134.917688 -262.423656)
		(end 134.92607 -262.41883)
		(width 0.0889)
		(layer "In4.Cu")
		(net "M_J_CPU1_SB_CA<1>")
	)
	(segment
		(start 171.032678 -262.36041)
		(end 173.69409 -262.36041)
		(width 0.14478)
		(layer "In4.Cu")
		(net "M_J_CPU1_SB_CA<1>")
	)
	(segment
		(start 138.103356 -262.41883)
		(end 138.111738 -262.423656)
		(width 0.0889)
		(layer "In4.Cu")
		(net "M_J_CPU1_SB_CA<1>")
	)
	(segment
		(start 147.178268 -262.372856)
		(end 147.4851 -262.066024)
		(width 0.0889)
		(layer "In4.Cu")
		(net "M_J_CPU1_SB_CA<1>")
	)
	(segment
		(start 170.18254 -261.510272)
		(end 171.032678 -262.36041)
		(width 0.14478)
		(layer "In4.Cu")
		(net "M_J_CPU1_SB_CA<1>")
	)
	(segment
		(start 176.85131 -261.510272)
		(end 177.156618 -261.204964)
		(width 0.14478)
		(layer "In4.Cu")
		(net "M_J_CPU1_SB_CA<1>")
	)
	(segment
		(start 181.60873 -261.204964)
		(end 181.859936 -261.204964)
		(width 0.14478)
		(layer "In4.Cu")
		(net "M_J_CPU1_SB_CA<1>")
	)
	(segment
		(start 139.04341 -262.41883)
		(end 139.051792 -262.423656)
		(width 0.0889)
		(layer "In4.Cu")
		(net "M_J_CPU1_SB_CA<1>")
	)
	(segment
		(start 162.365436 -261.818882)
		(end 162.365436 -261.271512)
		(width 0.14478)
		(layer "In4.Cu")
		(net "M_J_CPU1_SB_CA<1>")
	)
	(segment
		(start 160.711134 -261.271512)
		(end 160.711134 -261.818882)
		(width 0.14478)
		(layer "In4.Cu")
		(net "M_J_CPU1_SB_CA<1>")
	)
	(segment
		(start 135.857742 -262.423656)
		(end 135.866124 -262.41883)
		(width 0.0889)
		(layer "In4.Cu")
		(net "M_J_CPU1_SB_CA<1>")
	)
	(segment
		(start 181.303422 -261.510272)
		(end 181.60873 -261.204964)
		(width 0.14478)
		(layer "In4.Cu")
		(net "M_J_CPU1_SB_CA<1>")
	)
	(segment
		(start 182.165244 -261.510272)
		(end 182.41645 -261.510272)
		(width 0.14478)
		(layer "In4.Cu")
		(net "M_J_CPU1_SB_CA<1>")
	)
	(segment
		(start 162.203892 -261.980426)
		(end 162.365436 -261.818882)
		(width 0.14478)
		(layer "In4.Cu")
		(net "M_J_CPU1_SB_CA<1>")
	)
	(segment
		(start 180.190394 -261.510272)
		(end 180.495702 -261.204964)
		(width 0.14478)
		(layer "In4.Cu")
		(net "M_J_CPU1_SB_CA<1>")
	)
	(segment
		(start 161.262568 -261.271512)
		(end 161.424112 -261.109968)
		(width 0.14478)
		(layer "In4.Cu")
		(net "M_J_CPU1_SB_CA<1>")
	)
	(segment
		(start 181.052216 -261.510272)
		(end 181.303422 -261.510272)
		(width 0.14478)
		(layer "In4.Cu")
		(net "M_J_CPU1_SB_CA<1>")
	)
	(segment
		(start 179.382674 -261.204964)
		(end 179.63388 -261.204964)
		(width 0.14478)
		(layer "In4.Cu")
		(net "M_J_CPU1_SB_CA<1>")
	)
	(segment
		(start 177.156618 -261.204964)
		(end 177.407824 -261.204964)
		(width 0.14478)
		(layer "In4.Cu")
		(net "M_J_CPU1_SB_CA<1>")
	)
	(segment
		(start 182.972964 -261.204964)
		(end 183.278272 -261.510272)
		(width 0.14478)
		(layer "In4.Cu")
		(net "M_J_CPU1_SB_CA<1>")
	)
	(segment
		(start 155.786074 -262.066024)
		(end 156.74213 -261.109968)
		(width 0.14478)
		(layer "In4.Cu")
		(net "M_J_CPU1_SB_CA<1>")
	)
	(segment
		(start 181.859936 -261.204964)
		(end 182.165244 -261.510272)
		(width 0.14478)
		(layer "In4.Cu")
		(net "M_J_CPU1_SB_CA<1>")
	)
	(segment
		(start 156.74213 -261.109968)
		(end 160.54959 -261.109968)
		(width 0.14478)
		(layer "In4.Cu")
		(net "M_J_CPU1_SB_CA<1>")
	)
	(segment
		(start 160.872678 -261.980426)
		(end 161.101024 -261.980426)
		(width 0.14478)
		(layer "In4.Cu")
		(net "M_J_CPU1_SB_CA<1>")
	)
	(segment
		(start 180.495702 -261.204964)
		(end 180.746908 -261.204964)
		(width 0.14478)
		(layer "In4.Cu")
		(net "M_J_CPU1_SB_CA<1>")
	)
	(segment
		(start 143.751808 -262.423656)
		(end 143.762222 -262.429752)
		(width 0.0889)
		(layer "In4.Cu")
		(net "M_J_CPU1_SB_CA<1>")
	)
	(segment
		(start 179.939188 -261.510272)
		(end 180.190394 -261.510272)
		(width 0.14478)
		(layer "In4.Cu")
		(net "M_J_CPU1_SB_CA<1>")
	)
	(segment
		(start 161.424112 -261.109968)
		(end 161.652458 -261.109968)
		(width 0.14478)
		(layer "In4.Cu")
		(net "M_J_CPU1_SB_CA<1>")
	)
	(segment
		(start 174.544228 -261.510272)
		(end 176.85131 -261.510272)
		(width 0.14478)
		(layer "In4.Cu")
		(net "M_J_CPU1_SB_CA<1>")
	)
	(segment
		(start 180.746908 -261.204964)
		(end 181.052216 -261.510272)
		(width 0.14478)
		(layer "In4.Cu")
		(net "M_J_CPU1_SB_CA<1>")
	)
	(segment
		(start 161.814002 -261.271512)
		(end 161.814002 -261.818882)
		(width 0.14478)
		(layer "In4.Cu")
		(net "M_J_CPU1_SB_CA<1>")
	)
	(segment
		(start 134.343394 -262.41883)
		(end 134.351776 -262.423656)
		(width 0.0889)
		(layer "In4.Cu")
		(net "M_J_CPU1_SB_CA<1>")
	)
	(segment
		(start 161.101024 -261.980426)
		(end 161.262568 -261.818882)
		(width 0.14478)
		(layer "In4.Cu")
		(net "M_J_CPU1_SB_CA<1>")
	)
	(segment
		(start 144.684242 -262.41883)
		(end 144.692624 -262.423656)
		(width 0.0889)
		(layer "In4.Cu")
		(net "M_J_CPU1_SB_CA<1>")
	)
	(segment
		(start 161.262568 -261.818882)
		(end 161.262568 -261.271512)
		(width 0.14478)
		(layer "In4.Cu")
		(net "M_J_CPU1_SB_CA<1>")
	)
	(segment
		(start 162.365436 -261.271512)
		(end 162.52698 -261.109968)
		(width 0.14478)
		(layer "In4.Cu")
		(net "M_J_CPU1_SB_CA<1>")
	)
	(segment
		(start 178.520852 -261.204964)
		(end 178.82616 -261.510272)
		(width 0.14478)
		(layer "In4.Cu")
		(net "M_J_CPU1_SB_CA<1>")
	)
	(segment
		(start 140.557758 -262.423656)
		(end 140.56614 -262.41883)
		(width 0.0889)
		(layer "In4.Cu")
		(net "M_J_CPU1_SB_CA<1>")
	)
	(segment
		(start 166.150036 -262.36041)
		(end 167.000174 -261.510272)
		(width 0.14478)
		(layer "In4.Cu")
		(net "M_J_CPU1_SB_CA<1>")
	)
	(arc
		(start 140.9319 -262.423656)
		(mid 141.214856 -262.499833)
		(end 141.497812 -262.423656)
		(width 0.0889)
		(layer "In4.Cu")
		(net "M_J_CPU1_SB_CA<1>")
	)
	(arc
		(start 138.111738 -262.423656)
		(mid 138.394694 -262.499833)
		(end 138.67765 -262.423656)
		(width 0.0889)
		(layer "In4.Cu")
		(net "M_J_CPU1_SB_CA<1>")
	)
	(arc
		(start 135.866124 -262.41883)
		(mid 136.049632 -262.373336)
		(end 136.231884 -262.423656)
		(width 0.0889)
		(layer "In4.Cu")
		(net "M_J_CPU1_SB_CA<1>")
	)
	(arc
		(start 143.386048 -262.41883)
		(mid 143.569556 -262.373336)
		(end 143.751808 -262.423656)
		(width 0.0889)
		(layer "In4.Cu")
		(net "M_J_CPU1_SB_CA<1>")
	)
	(arc
		(start 141.8717 -262.423656)
		(mid 142.154656 -262.499833)
		(end 142.437612 -262.423656)
		(width 0.0889)
		(layer "In4.Cu")
		(net "M_J_CPU1_SB_CA<1>")
	)
	(arc
		(start 142.437612 -262.423656)
		(mid 142.619863 -262.373306)
		(end 142.803372 -262.41883)
		(width 0.0889)
		(layer "In4.Cu")
		(net "M_J_CPU1_SB_CA<1>")
	)
	(arc
		(start 135.29183 -262.423656)
		(mid 135.574786 -262.499833)
		(end 135.857742 -262.423656)
		(width 0.0889)
		(layer "In4.Cu")
		(net "M_J_CPU1_SB_CA<1>")
	)
	(arc
		(start 137.171684 -262.423656)
		(mid 137.45464 -262.499833)
		(end 137.737596 -262.423656)
		(width 0.0889)
		(layer "In4.Cu")
		(net "M_J_CPU1_SB_CA<1>")
	)
	(arc
		(start 136.797796 -262.423656)
		(mid 136.98474 -262.373401)
		(end 137.171684 -262.423656)
		(width 0.0889)
		(layer "In4.Cu")
		(net "M_J_CPU1_SB_CA<1>")
	)
	(arc
		(start 141.497812 -262.423656)
		(mid 141.684756 -262.373401)
		(end 141.8717 -262.423656)
		(width 0.0889)
		(layer "In4.Cu")
		(net "M_J_CPU1_SB_CA<1>")
	)
	(arc
		(start 140.56614 -262.41883)
		(mid 140.749648 -262.373336)
		(end 140.9319 -262.423656)
		(width 0.0889)
		(layer "In4.Cu")
		(net "M_J_CPU1_SB_CA<1>")
	)
	(arc
		(start 131.595114 -262.455406)
		(mid 131.850179 -262.498757)
		(end 132.09778 -262.423656)
		(width 0.0889)
		(layer "In4.Cu")
		(net "M_J_CPU1_SB_CA<1>")
	)
	(arc
		(start 132.106162 -262.41883)
		(mid 132.28967 -262.373336)
		(end 132.471922 -262.423656)
		(width 0.0889)
		(layer "In4.Cu")
		(net "M_J_CPU1_SB_CA<1>")
	)
	(arc
		(start 142.811754 -262.423656)
		(mid 143.09471 -262.499833)
		(end 143.377666 -262.423656)
		(width 0.0889)
		(layer "In4.Cu")
		(net "M_J_CPU1_SB_CA<1>")
	)
	(arc
		(start 137.737596 -262.423656)
		(mid 137.919847 -262.373306)
		(end 138.103356 -262.41883)
		(width 0.0889)
		(layer "In4.Cu")
		(net "M_J_CPU1_SB_CA<1>")
	)
	(arc
		(start 132.471922 -262.423656)
		(mid 132.754878 -262.499833)
		(end 133.037834 -262.423656)
		(width 0.0889)
		(layer "In4.Cu")
		(net "M_J_CPU1_SB_CA<1>")
	)
	(arc
		(start 139.051792 -262.423656)
		(mid 139.334748 -262.499833)
		(end 139.617704 -262.423656)
		(width 0.0889)
		(layer "In4.Cu")
		(net "M_J_CPU1_SB_CA<1>")
	)
	(arc
		(start 134.92607 -262.41883)
		(mid 135.109578 -262.373336)
		(end 135.29183 -262.423656)
		(width 0.0889)
		(layer "In4.Cu")
		(net "M_J_CPU1_SB_CA<1>")
	)
	(arc
		(start 133.411722 -262.423656)
		(mid 133.694678 -262.499833)
		(end 133.977634 -262.423656)
		(width 0.0889)
		(layer "In4.Cu")
		(net "M_J_CPU1_SB_CA<1>")
	)
	(arc
		(start 145.25244 -262.427212)
		(mid 145.344872 -262.38693)
		(end 145.444718 -262.372856)
		(width 0.0889)
		(layer "In4.Cu")
		(net "M_J_CPU1_SB_CA<1>")
	)
	(arc
		(start 134.351776 -262.423656)
		(mid 134.634732 -262.499833)
		(end 134.917688 -262.423656)
		(width 0.0889)
		(layer "In4.Cu")
		(net "M_J_CPU1_SB_CA<1>")
	)
	(arc
		(start 144.317974 -262.423656)
		(mid 144.500479 -262.373179)
		(end 144.684242 -262.41883)
		(width 0.0889)
		(layer "In4.Cu")
		(net "M_J_CPU1_SB_CA<1>")
	)
	(arc
		(start 136.231884 -262.423656)
		(mid 136.51484 -262.499833)
		(end 136.797796 -262.423656)
		(width 0.0889)
		(layer "In4.Cu")
		(net "M_J_CPU1_SB_CA<1>")
	)
	(arc
		(start 133.037834 -262.423656)
		(mid 133.224778 -262.373401)
		(end 133.411722 -262.423656)
		(width 0.0889)
		(layer "In4.Cu")
		(net "M_J_CPU1_SB_CA<1>")
	)
	(arc
		(start 139.991846 -262.423656)
		(mid 140.274802 -262.499833)
		(end 140.557758 -262.423656)
		(width 0.0889)
		(layer "In4.Cu")
		(net "M_J_CPU1_SB_CA<1>")
	)
	(arc
		(start 144.692624 -262.423656)
		(mid 144.972052 -262.499822)
		(end 145.25244 -262.427212)
		(width 0.0889)
		(layer "In4.Cu")
		(net "M_J_CPU1_SB_CA<1>")
	)
	(arc
		(start 133.977634 -262.423656)
		(mid 134.159885 -262.373306)
		(end 134.343394 -262.41883)
		(width 0.0889)
		(layer "In4.Cu")
		(net "M_J_CPU1_SB_CA<1>")
	)
	(arc
		(start 143.762222 -262.429752)
		(mid 144.040908 -262.499972)
		(end 144.317974 -262.423656)
		(width 0.0889)
		(layer "In4.Cu")
		(net "M_J_CPU1_SB_CA<1>")
	)
	(arc
		(start 138.67765 -262.423656)
		(mid 138.859901 -262.373306)
		(end 139.04341 -262.41883)
		(width 0.0889)
		(layer "In4.Cu")
		(net "M_J_CPU1_SB_CA<1>")
	)
	(arc
		(start 139.626086 -262.41883)
		(mid 139.809594 -262.373336)
		(end 139.991846 -262.423656)
		(width 0.0889)
		(layer "In4.Cu")
		(net "M_J_CPU1_SB_CA<1>")
	)
	(segment
		(start 131.347972 -261.670292)
		(end 131.814824 -261.93623)
		(width 0.10668)
		(layer "F.Cu")
		(net "M_J_CPU1_SB_CA<0>")
	)
	(segment
		(start 145.582132 -262.142986)
		(end 147.102068 -262.142986)
		(width 0.0889)
		(layer "In4.Cu")
		(net "M_J_CPU1_SB_CA<0>")
	)
	(segment
		(start 144.777968 -262.252714)
		(end 144.788382 -262.25881)
		(width 0.0889)
		(layer "In4.Cu")
		(net "M_J_CPU1_SB_CA<0>")
	)
	(segment
		(start 138.20775 -262.25881)
		(end 138.216132 -262.263636)
		(width 0.0889)
		(layer "In4.Cu")
		(net "M_J_CPU1_SB_CA<0>")
	)
	(segment
		(start 141.393418 -262.263636)
		(end 141.4018 -262.25881)
		(width 0.0889)
		(layer "In4.Cu")
		(net "M_J_CPU1_SB_CA<0>")
	)
	(segment
		(start 190.735204 -260.660388)
		(end 191.160146 -261.08533)
		(width 0.14478)
		(layer "In4.Cu")
		(net "M_J_CPU1_SB_CA<0>")
	)
	(segment
		(start 131.814824 -261.93623)
		(end 131.660646 -262.20166)
		(width 0.0889)
		(layer "In4.Cu")
		(net "M_J_CPU1_SB_CA<0>")
	)
	(segment
		(start 170.117516 -260.660388)
		(end 170.9674 -261.510272)
		(width 0.14478)
		(layer "In4.Cu")
		(net "M_J_CPU1_SB_CA<0>")
	)
	(segment
		(start 156.555694 -260.660388)
		(end 163.35121 -260.660388)
		(width 0.14478)
		(layer "In4.Cu")
		(net "M_J_CPU1_SB_CA<0>")
	)
	(segment
		(start 133.507734 -262.25881)
		(end 133.516116 -262.263636)
		(width 0.0889)
		(layer "In4.Cu")
		(net "M_J_CPU1_SB_CA<0>")
	)
	(segment
		(start 137.267696 -262.25881)
		(end 137.276078 -262.263636)
		(width 0.0889)
		(layer "In4.Cu")
		(net "M_J_CPU1_SB_CA<0>")
	)
	(segment
		(start 148.028152 -261.611364)
		(end 155.604718 -261.611364)
		(width 0.14478)
		(layer "In4.Cu")
		(net "M_J_CPU1_SB_CA<0>")
	)
	(segment
		(start 140.453364 -262.263636)
		(end 140.461746 -262.25881)
		(width 0.0889)
		(layer "In4.Cu")
		(net "M_J_CPU1_SB_CA<0>")
	)
	(segment
		(start 166.243 -261.510272)
		(end 167.092884 -260.660388)
		(width 0.14478)
		(layer "In4.Cu")
		(net "M_J_CPU1_SB_CA<0>")
	)
	(segment
		(start 131.993386 -262.263636)
		(end 132.001768 -262.25881)
		(width 0.0889)
		(layer "In4.Cu")
		(net "M_J_CPU1_SB_CA<0>")
	)
	(segment
		(start 147.102068 -262.142986)
		(end 147.63369 -261.611364)
		(width 0.0889)
		(layer "In4.Cu")
		(net "M_J_CPU1_SB_CA<0>")
	)
	(segment
		(start 170.9674 -261.510272)
		(end 173.787054 -261.510272)
		(width 0.14478)
		(layer "In4.Cu")
		(net "M_J_CPU1_SB_CA<0>")
	)
	(segment
		(start 174.636938 -260.660388)
		(end 190.735204 -260.660388)
		(width 0.14478)
		(layer "In4.Cu")
		(net "M_J_CPU1_SB_CA<0>")
	)
	(segment
		(start 135.753348 -262.263636)
		(end 135.76173 -262.25881)
		(width 0.0889)
		(layer "In4.Cu")
		(net "M_J_CPU1_SB_CA<0>")
	)
	(segment
		(start 141.967712 -262.25881)
		(end 141.976094 -262.263636)
		(width 0.0889)
		(layer "In4.Cu")
		(net "M_J_CPU1_SB_CA<0>")
	)
	(segment
		(start 167.092884 -260.660388)
		(end 170.117516 -260.660388)
		(width 0.14478)
		(layer "In4.Cu")
		(net "M_J_CPU1_SB_CA<0>")
	)
	(segment
		(start 143.847566 -262.25881)
		(end 143.855948 -262.263636)
		(width 0.0889)
		(layer "In4.Cu")
		(net "M_J_CPU1_SB_CA<0>")
	)
	(segment
		(start 136.693402 -262.263636)
		(end 136.701784 -262.25881)
		(width 0.0889)
		(layer "In4.Cu")
		(net "M_J_CPU1_SB_CA<0>")
	)
	(segment
		(start 132.93344 -262.263636)
		(end 132.941822 -262.25881)
		(width 0.0889)
		(layer "In4.Cu")
		(net "M_J_CPU1_SB_CA<0>")
	)
	(segment
		(start 164.201094 -261.510272)
		(end 166.243 -261.510272)
		(width 0.14478)
		(layer "In4.Cu")
		(net "M_J_CPU1_SB_CA<0>")
	)
	(segment
		(start 173.787054 -261.510272)
		(end 174.636938 -260.660388)
		(width 0.14478)
		(layer "In4.Cu")
		(net "M_J_CPU1_SB_CA<0>")
	)
	(segment
		(start 131.660646 -262.20166)
		(end 131.682998 -262.284972)
		(width 0.0889)
		(layer "In4.Cu")
		(net "M_J_CPU1_SB_CA<0>")
	)
	(segment
		(start 163.35121 -260.660388)
		(end 164.201094 -261.510272)
		(width 0.14478)
		(layer "In4.Cu")
		(net "M_J_CPU1_SB_CA<0>")
	)
	(segment
		(start 147.63369 -261.611364)
		(end 148.028152 -261.611364)
		(width 0.0889)
		(layer "In4.Cu")
		(net "M_J_CPU1_SB_CA<0>")
	)
	(segment
		(start 155.604718 -261.611364)
		(end 156.555694 -260.660388)
		(width 0.14478)
		(layer "In4.Cu")
		(net "M_J_CPU1_SB_CA<0>")
	)
	(arc
		(start 140.087604 -262.25881)
		(mid 140.269855 -262.30916)
		(end 140.453364 -262.263636)
		(width 0.0889)
		(layer "In4.Cu")
		(net "M_J_CPU1_SB_CA<0>")
	)
	(arc
		(start 132.941822 -262.25881)
		(mid 133.224778 -262.182633)
		(end 133.507734 -262.25881)
		(width 0.0889)
		(layer "In4.Cu")
		(net "M_J_CPU1_SB_CA<0>")
	)
	(arc
		(start 132.001768 -262.25881)
		(mid 132.284724 -262.182633)
		(end 132.56768 -262.25881)
		(width 0.0889)
		(layer "In4.Cu")
		(net "M_J_CPU1_SB_CA<0>")
	)
	(arc
		(start 141.4018 -262.25881)
		(mid 141.684756 -262.182633)
		(end 141.967712 -262.25881)
		(width 0.0889)
		(layer "In4.Cu")
		(net "M_J_CPU1_SB_CA<0>")
	)
	(arc
		(start 131.682998 -262.284972)
		(mid 131.840508 -262.30817)
		(end 131.993386 -262.263636)
		(width 0.0889)
		(layer "In4.Cu")
		(net "M_J_CPU1_SB_CA<0>")
	)
	(arc
		(start 142.907766 -262.25881)
		(mid 143.09471 -262.309065)
		(end 143.281654 -262.25881)
		(width 0.0889)
		(layer "In4.Cu")
		(net "M_J_CPU1_SB_CA<0>")
	)
	(arc
		(start 135.76173 -262.25881)
		(mid 136.044686 -262.182633)
		(end 136.327642 -262.25881)
		(width 0.0889)
		(layer "In4.Cu")
		(net "M_J_CPU1_SB_CA<0>")
	)
	(arc
		(start 140.461746 -262.25881)
		(mid 140.744702 -262.182633)
		(end 141.027658 -262.25881)
		(width 0.0889)
		(layer "In4.Cu")
		(net "M_J_CPU1_SB_CA<0>")
	)
	(arc
		(start 137.276078 -262.263636)
		(mid 137.459586 -262.30913)
		(end 137.641838 -262.25881)
		(width 0.0889)
		(layer "In4.Cu")
		(net "M_J_CPU1_SB_CA<0>")
	)
	(arc
		(start 138.216132 -262.263636)
		(mid 138.39964 -262.30913)
		(end 138.581892 -262.25881)
		(width 0.0889)
		(layer "In4.Cu")
		(net "M_J_CPU1_SB_CA<0>")
	)
	(arc
		(start 145.146014 -262.267954)
		(mid 145.355297 -262.174844)
		(end 145.582132 -262.142986)
		(width 0.0889)
		(layer "In4.Cu")
		(net "M_J_CPU1_SB_CA<0>")
	)
	(arc
		(start 143.281654 -262.25881)
		(mid 143.56461 -262.182633)
		(end 143.847566 -262.25881)
		(width 0.0889)
		(layer "In4.Cu")
		(net "M_J_CPU1_SB_CA<0>")
	)
	(arc
		(start 141.027658 -262.25881)
		(mid 141.209909 -262.30916)
		(end 141.393418 -262.263636)
		(width 0.0889)
		(layer "In4.Cu")
		(net "M_J_CPU1_SB_CA<0>")
	)
	(arc
		(start 141.976094 -262.263636)
		(mid 142.159602 -262.30913)
		(end 142.341854 -262.25881)
		(width 0.0889)
		(layer "In4.Cu")
		(net "M_J_CPU1_SB_CA<0>")
	)
	(arc
		(start 136.327642 -262.25881)
		(mid 136.509893 -262.30916)
		(end 136.693402 -262.263636)
		(width 0.0889)
		(layer "In4.Cu")
		(net "M_J_CPU1_SB_CA<0>")
	)
	(arc
		(start 144.222216 -262.25881)
		(mid 144.499283 -262.182539)
		(end 144.777968 -262.252714)
		(width 0.0889)
		(layer "In4.Cu")
		(net "M_J_CPU1_SB_CA<0>")
	)
	(arc
		(start 139.521692 -262.25881)
		(mid 139.804648 -262.182633)
		(end 140.087604 -262.25881)
		(width 0.0889)
		(layer "In4.Cu")
		(net "M_J_CPU1_SB_CA<0>")
	)
	(arc
		(start 135.387588 -262.25881)
		(mid 135.569839 -262.30916)
		(end 135.753348 -262.263636)
		(width 0.0889)
		(layer "In4.Cu")
		(net "M_J_CPU1_SB_CA<0>")
	)
	(arc
		(start 134.821676 -262.25881)
		(mid 135.104632 -262.182633)
		(end 135.387588 -262.25881)
		(width 0.0889)
		(layer "In4.Cu")
		(net "M_J_CPU1_SB_CA<0>")
	)
	(arc
		(start 137.641838 -262.25881)
		(mid 137.924794 -262.182633)
		(end 138.20775 -262.25881)
		(width 0.0889)
		(layer "In4.Cu")
		(net "M_J_CPU1_SB_CA<0>")
	)
	(arc
		(start 142.341854 -262.25881)
		(mid 142.62481 -262.182633)
		(end 142.907766 -262.25881)
		(width 0.0889)
		(layer "In4.Cu")
		(net "M_J_CPU1_SB_CA<0>")
	)
	(arc
		(start 132.56768 -262.25881)
		(mid 132.749931 -262.30916)
		(end 132.93344 -262.263636)
		(width 0.0889)
		(layer "In4.Cu")
		(net "M_J_CPU1_SB_CA<0>")
	)
	(arc
		(start 134.447788 -262.25881)
		(mid 134.634732 -262.309065)
		(end 134.821676 -262.25881)
		(width 0.0889)
		(layer "In4.Cu")
		(net "M_J_CPU1_SB_CA<0>")
	)
	(arc
		(start 143.855948 -262.263636)
		(mid 144.03971 -262.309252)
		(end 144.222216 -262.25881)
		(width 0.0889)
		(layer "In4.Cu")
		(net "M_J_CPU1_SB_CA<0>")
	)
	(arc
		(start 138.581892 -262.25881)
		(mid 138.864848 -262.182633)
		(end 139.147804 -262.25881)
		(width 0.0889)
		(layer "In4.Cu")
		(net "M_J_CPU1_SB_CA<0>")
	)
	(arc
		(start 133.516116 -262.263636)
		(mid 133.699624 -262.30913)
		(end 133.881876 -262.25881)
		(width 0.0889)
		(layer "In4.Cu")
		(net "M_J_CPU1_SB_CA<0>")
	)
	(arc
		(start 136.701784 -262.25881)
		(mid 136.98474 -262.182633)
		(end 137.267696 -262.25881)
		(width 0.0889)
		(layer "In4.Cu")
		(net "M_J_CPU1_SB_CA<0>")
	)
	(arc
		(start 139.147804 -262.25881)
		(mid 139.334748 -262.309065)
		(end 139.521692 -262.25881)
		(width 0.0889)
		(layer "In4.Cu")
		(net "M_J_CPU1_SB_CA<0>")
	)
	(arc
		(start 133.881876 -262.25881)
		(mid 134.164832 -262.182633)
		(end 134.447788 -262.25881)
		(width 0.0889)
		(layer "In4.Cu")
		(net "M_J_CPU1_SB_CA<0>")
	)
	(arc
		(start 144.788382 -262.25881)
		(mid 144.966032 -262.30907)
		(end 145.146014 -262.267954)
		(width 0.0889)
		(layer "In4.Cu")
		(net "M_J_CPU1_SB_CA<0>")
	)
	(segment
		(start 131.347972 -266.530328)
		(end 131.814824 -266.796266)
		(width 0.10668)
		(layer "F.Cu")
		(net "M_J_CPU1_SA_RSP<0>")
	)
	(segment
		(start 147.346416 -266.143994)
		(end 147.93849 -266.143994)
		(width 0.0889)
		(layer "In4.Cu")
		(net "M_J_CPU1_SA_RSP<0>")
	)
	(segment
		(start 165.426136 -270.010636)
		(end 167.47871 -269.160498)
		(width 0.11684)
		(layer "In4.Cu")
		(net "M_J_CPU1_SA_RSP<0>")
	)
	(segment
		(start 137.267696 -267.118846)
		(end 137.276078 -267.123672)
		(width 0.0889)
		(layer "In4.Cu")
		(net "M_J_CPU1_SA_RSP<0>")
	)
	(segment
		(start 147.307046 -266.104624)
		(end 147.346416 -266.143994)
		(width 0.0889)
		(layer "In4.Cu")
		(net "M_J_CPU1_SA_RSP<0>")
	)
	(segment
		(start 174.99076 -269.160498)
		(end 189.023752 -269.160498)
		(width 0.11684)
		(layer "In4.Cu")
		(net "M_J_CPU1_SA_RSP<0>")
	)
	(segment
		(start 140.453364 -267.123672)
		(end 140.461746 -267.118846)
		(width 0.0889)
		(layer "In4.Cu")
		(net "M_J_CPU1_SA_RSP<0>")
	)
	(segment
		(start 147.93849 -266.143994)
		(end 160.41878 -266.143994)
		(width 0.11684)
		(layer "In4.Cu")
		(net "M_J_CPU1_SA_RSP<0>")
	)
	(segment
		(start 189.023752 -269.160498)
		(end 191.160146 -269.58544)
		(width 0.11684)
		(layer "In4.Cu")
		(net "M_J_CPU1_SA_RSP<0>")
	)
	(segment
		(start 160.41878 -266.143994)
		(end 164.285422 -270.010636)
		(width 0.11684)
		(layer "In4.Cu")
		(net "M_J_CPU1_SA_RSP<0>")
	)
	(segment
		(start 172.938186 -270.010636)
		(end 174.99076 -269.160498)
		(width 0.11684)
		(layer "In4.Cu")
		(net "M_J_CPU1_SA_RSP<0>")
	)
	(segment
		(start 141.393418 -267.123672)
		(end 141.4018 -267.118846)
		(width 0.0889)
		(layer "In4.Cu")
		(net "M_J_CPU1_SA_RSP<0>")
	)
	(segment
		(start 141.967712 -267.118846)
		(end 141.976094 -267.123672)
		(width 0.0889)
		(layer "In4.Cu")
		(net "M_J_CPU1_SA_RSP<0>")
	)
	(segment
		(start 171.87799 -270.010636)
		(end 172.938186 -270.010636)
		(width 0.11684)
		(layer "In4.Cu")
		(net "M_J_CPU1_SA_RSP<0>")
	)
	(segment
		(start 144.777968 -267.11275)
		(end 144.788382 -267.118846)
		(width 0.0889)
		(layer "In4.Cu")
		(net "M_J_CPU1_SA_RSP<0>")
	)
	(segment
		(start 131.814824 -266.796266)
		(end 131.660646 -267.061696)
		(width 0.0889)
		(layer "In4.Cu")
		(net "M_J_CPU1_SA_RSP<0>")
	)
	(segment
		(start 133.507734 -267.118846)
		(end 133.516116 -267.123672)
		(width 0.0889)
		(layer "In4.Cu")
		(net "M_J_CPU1_SA_RSP<0>")
	)
	(segment
		(start 135.753348 -267.123672)
		(end 135.76173 -267.118846)
		(width 0.0889)
		(layer "In4.Cu")
		(net "M_J_CPU1_SA_RSP<0>")
	)
	(segment
		(start 138.20775 -267.118846)
		(end 138.216132 -267.123672)
		(width 0.0889)
		(layer "In4.Cu")
		(net "M_J_CPU1_SA_RSP<0>")
	)
	(segment
		(start 132.93344 -267.123672)
		(end 132.941822 -267.118846)
		(width 0.0889)
		(layer "In4.Cu")
		(net "M_J_CPU1_SA_RSP<0>")
	)
	(segment
		(start 136.693402 -267.123672)
		(end 136.701784 -267.118846)
		(width 0.0889)
		(layer "In4.Cu")
		(net "M_J_CPU1_SA_RSP<0>")
	)
	(segment
		(start 145.146014 -267.12799)
		(end 146.16938 -266.104624)
		(width 0.0889)
		(layer "In4.Cu")
		(net "M_J_CPU1_SA_RSP<0>")
	)
	(segment
		(start 169.825416 -269.160498)
		(end 171.87799 -270.010636)
		(width 0.11684)
		(layer "In4.Cu")
		(net "M_J_CPU1_SA_RSP<0>")
	)
	(segment
		(start 131.993386 -267.123672)
		(end 132.001768 -267.118846)
		(width 0.0889)
		(layer "In4.Cu")
		(net "M_J_CPU1_SA_RSP<0>")
	)
	(segment
		(start 164.285422 -270.010636)
		(end 165.426136 -270.010636)
		(width 0.11684)
		(layer "In4.Cu")
		(net "M_J_CPU1_SA_RSP<0>")
	)
	(segment
		(start 131.660646 -267.061696)
		(end 131.682998 -267.145008)
		(width 0.0889)
		(layer "In4.Cu")
		(net "M_J_CPU1_SA_RSP<0>")
	)
	(segment
		(start 143.847566 -267.118846)
		(end 143.855948 -267.123672)
		(width 0.0889)
		(layer "In4.Cu")
		(net "M_J_CPU1_SA_RSP<0>")
	)
	(segment
		(start 167.47871 -269.160498)
		(end 169.825416 -269.160498)
		(width 0.11684)
		(layer "In4.Cu")
		(net "M_J_CPU1_SA_RSP<0>")
	)
	(segment
		(start 146.16938 -266.104624)
		(end 147.307046 -266.104624)
		(width 0.0889)
		(layer "In4.Cu")
		(net "M_J_CPU1_SA_RSP<0>")
	)
	(arc
		(start 140.461746 -267.118846)
		(mid 140.744702 -267.042669)
		(end 141.027658 -267.118846)
		(width 0.0889)
		(layer "In4.Cu")
		(net "M_J_CPU1_SA_RSP<0>")
	)
	(arc
		(start 144.788382 -267.118846)
		(mid 144.966032 -267.169106)
		(end 145.146014 -267.12799)
		(width 0.0889)
		(layer "In4.Cu")
		(net "M_J_CPU1_SA_RSP<0>")
	)
	(arc
		(start 142.907766 -267.118846)
		(mid 143.09471 -267.169101)
		(end 143.281654 -267.118846)
		(width 0.0889)
		(layer "In4.Cu")
		(net "M_J_CPU1_SA_RSP<0>")
	)
	(arc
		(start 139.521692 -267.118846)
		(mid 139.804648 -267.042669)
		(end 140.087604 -267.118846)
		(width 0.0889)
		(layer "In4.Cu")
		(net "M_J_CPU1_SA_RSP<0>")
	)
	(arc
		(start 137.641838 -267.118846)
		(mid 137.924794 -267.042669)
		(end 138.20775 -267.118846)
		(width 0.0889)
		(layer "In4.Cu")
		(net "M_J_CPU1_SA_RSP<0>")
	)
	(arc
		(start 131.682998 -267.145008)
		(mid 131.840508 -267.168206)
		(end 131.993386 -267.123672)
		(width 0.0889)
		(layer "In4.Cu")
		(net "M_J_CPU1_SA_RSP<0>")
	)
	(arc
		(start 143.281654 -267.118846)
		(mid 143.56461 -267.042669)
		(end 143.847566 -267.118846)
		(width 0.0889)
		(layer "In4.Cu")
		(net "M_J_CPU1_SA_RSP<0>")
	)
	(arc
		(start 134.821676 -267.118846)
		(mid 135.104632 -267.042669)
		(end 135.387588 -267.118846)
		(width 0.0889)
		(layer "In4.Cu")
		(net "M_J_CPU1_SA_RSP<0>")
	)
	(arc
		(start 134.447788 -267.118846)
		(mid 134.634732 -267.169101)
		(end 134.821676 -267.118846)
		(width 0.0889)
		(layer "In4.Cu")
		(net "M_J_CPU1_SA_RSP<0>")
	)
	(arc
		(start 141.4018 -267.118846)
		(mid 141.684756 -267.042669)
		(end 141.967712 -267.118846)
		(width 0.0889)
		(layer "In4.Cu")
		(net "M_J_CPU1_SA_RSP<0>")
	)
	(arc
		(start 133.516116 -267.123672)
		(mid 133.699624 -267.169166)
		(end 133.881876 -267.118846)
		(width 0.0889)
		(layer "In4.Cu")
		(net "M_J_CPU1_SA_RSP<0>")
	)
	(arc
		(start 132.941822 -267.118846)
		(mid 133.224778 -267.042669)
		(end 133.507734 -267.118846)
		(width 0.0889)
		(layer "In4.Cu")
		(net "M_J_CPU1_SA_RSP<0>")
	)
	(arc
		(start 137.276078 -267.123672)
		(mid 137.459586 -267.169166)
		(end 137.641838 -267.118846)
		(width 0.0889)
		(layer "In4.Cu")
		(net "M_J_CPU1_SA_RSP<0>")
	)
	(arc
		(start 140.087604 -267.118846)
		(mid 140.269855 -267.169196)
		(end 140.453364 -267.123672)
		(width 0.0889)
		(layer "In4.Cu")
		(net "M_J_CPU1_SA_RSP<0>")
	)
	(arc
		(start 143.855948 -267.123672)
		(mid 144.03971 -267.169288)
		(end 144.222216 -267.118846)
		(width 0.0889)
		(layer "In4.Cu")
		(net "M_J_CPU1_SA_RSP<0>")
	)
	(arc
		(start 136.327642 -267.118846)
		(mid 136.509893 -267.169196)
		(end 136.693402 -267.123672)
		(width 0.0889)
		(layer "In4.Cu")
		(net "M_J_CPU1_SA_RSP<0>")
	)
	(arc
		(start 139.147804 -267.118846)
		(mid 139.334748 -267.169101)
		(end 139.521692 -267.118846)
		(width 0.0889)
		(layer "In4.Cu")
		(net "M_J_CPU1_SA_RSP<0>")
	)
	(arc
		(start 141.027658 -267.118846)
		(mid 141.209909 -267.169196)
		(end 141.393418 -267.123672)
		(width 0.0889)
		(layer "In4.Cu")
		(net "M_J_CPU1_SA_RSP<0>")
	)
	(arc
		(start 138.216132 -267.123672)
		(mid 138.39964 -267.169166)
		(end 138.581892 -267.118846)
		(width 0.0889)
		(layer "In4.Cu")
		(net "M_J_CPU1_SA_RSP<0>")
	)
	(arc
		(start 132.56768 -267.118846)
		(mid 132.749931 -267.169196)
		(end 132.93344 -267.123672)
		(width 0.0889)
		(layer "In4.Cu")
		(net "M_J_CPU1_SA_RSP<0>")
	)
	(arc
		(start 138.581892 -267.118846)
		(mid 138.864848 -267.042669)
		(end 139.147804 -267.118846)
		(width 0.0889)
		(layer "In4.Cu")
		(net "M_J_CPU1_SA_RSP<0>")
	)
	(arc
		(start 135.387588 -267.118846)
		(mid 135.569839 -267.169196)
		(end 135.753348 -267.123672)
		(width 0.0889)
		(layer "In4.Cu")
		(net "M_J_CPU1_SA_RSP<0>")
	)
	(arc
		(start 135.76173 -267.118846)
		(mid 136.044686 -267.042669)
		(end 136.327642 -267.118846)
		(width 0.0889)
		(layer "In4.Cu")
		(net "M_J_CPU1_SA_RSP<0>")
	)
	(arc
		(start 142.341854 -267.118846)
		(mid 142.62481 -267.042669)
		(end 142.907766 -267.118846)
		(width 0.0889)
		(layer "In4.Cu")
		(net "M_J_CPU1_SA_RSP<0>")
	)
	(arc
		(start 132.001768 -267.118846)
		(mid 132.284724 -267.042669)
		(end 132.56768 -267.118846)
		(width 0.0889)
		(layer "In4.Cu")
		(net "M_J_CPU1_SA_RSP<0>")
	)
	(arc
		(start 136.701784 -267.118846)
		(mid 136.98474 -267.042669)
		(end 137.267696 -267.118846)
		(width 0.0889)
		(layer "In4.Cu")
		(net "M_J_CPU1_SA_RSP<0>")
	)
	(arc
		(start 141.976094 -267.123672)
		(mid 142.159602 -267.169166)
		(end 142.341854 -267.118846)
		(width 0.0889)
		(layer "In4.Cu")
		(net "M_J_CPU1_SA_RSP<0>")
	)
	(arc
		(start 144.222216 -267.118846)
		(mid 144.499283 -267.042575)
		(end 144.777968 -267.11275)
		(width 0.0889)
		(layer "In4.Cu")
		(net "M_J_CPU1_SA_RSP<0>")
	)
	(arc
		(start 133.881876 -267.118846)
		(mid 134.164832 -267.042669)
		(end 134.447788 -267.118846)
		(width 0.0889)
		(layer "In4.Cu")
		(net "M_J_CPU1_SA_RSP<0>")
	)
	(segment
		(start 131.047998 -256.09042)
		(end 131.51485 -255.824482)
		(width 0.10668)
		(layer "F.Cu")
		(net "M_J_CPU1_SA_PAR")
	)
	(segment
		(start 141.667738 -255.501902)
		(end 141.67612 -255.497076)
		(width 0.0889)
		(layer "In4.Cu")
		(net "M_J_CPU1_SA_PAR")
	)
	(segment
		(start 144.47393 -255.510538)
		(end 144.488662 -255.501902)
		(width 0.0889)
		(layer "In4.Cu")
		(net "M_J_CPU1_SA_PAR")
	)
	(segment
		(start 156.9466 -255.743964)
		(end 184.209436 -255.743964)
		(width 0.14478)
		(layer "In4.Cu")
		(net "M_J_CPU1_SA_PAR")
	)
	(segment
		(start 147.724368 -256.625344)
		(end 150.609808 -256.625344)
		(width 0.14478)
		(layer "In4.Cu")
		(net "M_J_CPU1_SA_PAR")
	)
	(segment
		(start 185.874406 -253.010416)
		(end 188.082428 -253.010416)
		(width 0.14478)
		(layer "In4.Cu")
		(net "M_J_CPU1_SA_PAR")
	)
	(segment
		(start 184.559448 -255.393952)
		(end 185.315098 -253.569724)
		(width 0.14478)
		(layer "In4.Cu")
		(net "M_J_CPU1_SA_PAR")
	)
	(segment
		(start 133.20776 -255.501902)
		(end 133.216142 -255.497076)
		(width 0.0889)
		(layer "In4.Cu")
		(net "M_J_CPU1_SA_PAR")
	)
	(segment
		(start 131.360672 -255.559052)
		(end 131.383024 -255.47574)
		(width 0.0889)
		(layer "In4.Cu")
		(net "M_J_CPU1_SA_PAR")
	)
	(segment
		(start 131.51485 -255.824482)
		(end 131.360672 -255.559052)
		(width 0.0889)
		(layer "In4.Cu")
		(net "M_J_CPU1_SA_PAR")
	)
	(segment
		(start 131.693412 -255.497076)
		(end 131.701794 -255.501902)
		(width 0.0889)
		(layer "In4.Cu")
		(net "M_J_CPU1_SA_PAR")
	)
	(segment
		(start 143.547592 -255.501902)
		(end 143.555974 -255.497076)
		(width 0.0889)
		(layer "In4.Cu")
		(net "M_J_CPU1_SA_PAR")
	)
	(segment
		(start 144.862296 -255.502156)
		(end 144.878044 -255.5113)
		(width 0.0889)
		(layer "In4.Cu")
		(net "M_J_CPU1_SA_PAR")
	)
	(segment
		(start 184.209436 -255.743964)
		(end 184.559448 -255.393952)
		(width 0.14478)
		(layer "In4.Cu")
		(net "M_J_CPU1_SA_PAR")
	)
	(segment
		(start 132.267706 -255.501902)
		(end 132.276088 -255.497076)
		(width 0.0889)
		(layer "In4.Cu")
		(net "M_J_CPU1_SA_PAR")
	)
	(segment
		(start 141.093444 -255.497076)
		(end 141.101826 -255.501902)
		(width 0.0889)
		(layer "In4.Cu")
		(net "M_J_CPU1_SA_PAR")
	)
	(segment
		(start 150.609808 -256.625344)
		(end 152.069546 -255.165606)
		(width 0.14478)
		(layer "In4.Cu")
		(net "M_J_CPU1_SA_PAR")
	)
	(segment
		(start 152.069546 -255.165606)
		(end 156.368242 -255.165606)
		(width 0.14478)
		(layer "In4.Cu")
		(net "M_J_CPU1_SA_PAR")
	)
	(segment
		(start 145.150586 -255.584706)
		(end 145.57121 -255.584706)
		(width 0.0889)
		(layer "In4.Cu")
		(net "M_J_CPU1_SA_PAR")
	)
	(segment
		(start 140.15339 -255.497076)
		(end 140.161772 -255.501902)
		(width 0.0889)
		(layer "In4.Cu")
		(net "M_J_CPU1_SA_PAR")
	)
	(segment
		(start 144.84858 -255.494282)
		(end 144.862296 -255.502156)
		(width 0.0889)
		(layer "In4.Cu")
		(net "M_J_CPU1_SA_PAR")
	)
	(segment
		(start 136.393428 -255.497076)
		(end 136.40181 -255.501902)
		(width 0.0889)
		(layer "In4.Cu")
		(net "M_J_CPU1_SA_PAR")
	)
	(segment
		(start 135.453374 -255.497076)
		(end 135.461756 -255.501902)
		(width 0.0889)
		(layer "In4.Cu")
		(net "M_J_CPU1_SA_PAR")
	)
	(segment
		(start 145.57121 -255.584706)
		(end 146.611848 -256.625344)
		(width 0.0889)
		(layer "In4.Cu")
		(net "M_J_CPU1_SA_PAR")
	)
	(segment
		(start 146.611848 -256.625344)
		(end 147.724368 -256.625344)
		(width 0.0889)
		(layer "In4.Cu")
		(net "M_J_CPU1_SA_PAR")
	)
	(segment
		(start 156.368242 -255.165606)
		(end 156.9466 -255.743964)
		(width 0.14478)
		(layer "In4.Cu")
		(net "M_J_CPU1_SA_PAR")
	)
	(segment
		(start 137.907776 -255.501902)
		(end 137.916158 -255.497076)
		(width 0.0889)
		(layer "In4.Cu")
		(net "M_J_CPU1_SA_PAR")
	)
	(segment
		(start 185.315098 -253.569724)
		(end 185.874406 -253.010416)
		(width 0.14478)
		(layer "In4.Cu")
		(net "M_J_CPU1_SA_PAR")
	)
	(segment
		(start 136.967722 -255.501902)
		(end 136.976104 -255.497076)
		(width 0.0889)
		(layer "In4.Cu")
		(net "M_J_CPU1_SA_PAR")
	)
	(segment
		(start 188.082428 -253.010416)
		(end 191.160146 -254.285242)
		(width 0.14478)
		(layer "In4.Cu")
		(net "M_J_CPU1_SA_PAR")
	)
	(arc
		(start 137.341864 -255.501902)
		(mid 137.62482 -255.578079)
		(end 137.907776 -255.501902)
		(width 0.0889)
		(layer "In4.Cu")
		(net "M_J_CPU1_SA_PAR")
	)
	(arc
		(start 139.221718 -255.501902)
		(mid 139.504674 -255.578079)
		(end 139.78763 -255.501902)
		(width 0.0889)
		(layer "In4.Cu")
		(net "M_J_CPU1_SA_PAR")
	)
	(arc
		(start 134.147814 -255.501902)
		(mid 134.334758 -255.451647)
		(end 134.521702 -255.501902)
		(width 0.0889)
		(layer "In4.Cu")
		(net "M_J_CPU1_SA_PAR")
	)
	(arc
		(start 139.78763 -255.501902)
		(mid 139.969881 -255.451552)
		(end 140.15339 -255.497076)
		(width 0.0889)
		(layer "In4.Cu")
		(net "M_J_CPU1_SA_PAR")
	)
	(arc
		(start 138.84783 -255.501902)
		(mid 139.034774 -255.451647)
		(end 139.221718 -255.501902)
		(width 0.0889)
		(layer "In4.Cu")
		(net "M_J_CPU1_SA_PAR")
	)
	(arc
		(start 134.521702 -255.501902)
		(mid 134.804658 -255.578079)
		(end 135.087614 -255.501902)
		(width 0.0889)
		(layer "In4.Cu")
		(net "M_J_CPU1_SA_PAR")
	)
	(arc
		(start 140.161772 -255.501902)
		(mid 140.444728 -255.578079)
		(end 140.727684 -255.501902)
		(width 0.0889)
		(layer "In4.Cu")
		(net "M_J_CPU1_SA_PAR")
	)
	(arc
		(start 132.276088 -255.497076)
		(mid 132.459596 -255.451582)
		(end 132.641848 -255.501902)
		(width 0.0889)
		(layer "In4.Cu")
		(net "M_J_CPU1_SA_PAR")
	)
	(arc
		(start 140.727684 -255.501902)
		(mid 140.909935 -255.451552)
		(end 141.093444 -255.497076)
		(width 0.0889)
		(layer "In4.Cu")
		(net "M_J_CPU1_SA_PAR")
	)
	(arc
		(start 136.976104 -255.497076)
		(mid 137.159612 -255.451582)
		(end 137.341864 -255.501902)
		(width 0.0889)
		(layer "In4.Cu")
		(net "M_J_CPU1_SA_PAR")
	)
	(arc
		(start 133.581902 -255.501902)
		(mid 133.864858 -255.578079)
		(end 134.147814 -255.501902)
		(width 0.0889)
		(layer "In4.Cu")
		(net "M_J_CPU1_SA_PAR")
	)
	(arc
		(start 136.027668 -255.501902)
		(mid 136.209919 -255.451552)
		(end 136.393428 -255.497076)
		(width 0.0889)
		(layer "In4.Cu")
		(net "M_J_CPU1_SA_PAR")
	)
	(arc
		(start 131.701794 -255.501902)
		(mid 131.98475 -255.578079)
		(end 132.267706 -255.501902)
		(width 0.0889)
		(layer "In4.Cu")
		(net "M_J_CPU1_SA_PAR")
	)
	(arc
		(start 144.878044 -255.5113)
		(mid 145.009461 -255.566019)
		(end 145.150586 -255.584706)
		(width 0.0889)
		(layer "In4.Cu")
		(net "M_J_CPU1_SA_PAR")
	)
	(arc
		(start 138.281918 -255.501902)
		(mid 138.564874 -255.578079)
		(end 138.84783 -255.501902)
		(width 0.0889)
		(layer "In4.Cu")
		(net "M_J_CPU1_SA_PAR")
	)
	(arc
		(start 142.98168 -255.501902)
		(mid 143.264636 -255.578079)
		(end 143.547592 -255.501902)
		(width 0.0889)
		(layer "In4.Cu")
		(net "M_J_CPU1_SA_PAR")
	)
	(arc
		(start 132.641848 -255.501902)
		(mid 132.924804 -255.578079)
		(end 133.20776 -255.501902)
		(width 0.0889)
		(layer "In4.Cu")
		(net "M_J_CPU1_SA_PAR")
	)
	(arc
		(start 144.488662 -255.501902)
		(mid 144.667649 -255.451732)
		(end 144.84858 -255.494282)
		(width 0.0889)
		(layer "In4.Cu")
		(net "M_J_CPU1_SA_PAR")
	)
	(arc
		(start 135.461756 -255.501902)
		(mid 135.744712 -255.578079)
		(end 136.027668 -255.501902)
		(width 0.0889)
		(layer "In4.Cu")
		(net "M_J_CPU1_SA_PAR")
	)
	(arc
		(start 141.67612 -255.497076)
		(mid 141.859628 -255.451582)
		(end 142.04188 -255.501902)
		(width 0.0889)
		(layer "In4.Cu")
		(net "M_J_CPU1_SA_PAR")
	)
	(arc
		(start 141.101826 -255.501902)
		(mid 141.384782 -255.578079)
		(end 141.667738 -255.501902)
		(width 0.0889)
		(layer "In4.Cu")
		(net "M_J_CPU1_SA_PAR")
	)
	(arc
		(start 135.087614 -255.501902)
		(mid 135.269865 -255.451552)
		(end 135.453374 -255.497076)
		(width 0.0889)
		(layer "In4.Cu")
		(net "M_J_CPU1_SA_PAR")
	)
	(arc
		(start 133.216142 -255.497076)
		(mid 133.39965 -255.451582)
		(end 133.581902 -255.501902)
		(width 0.0889)
		(layer "In4.Cu")
		(net "M_J_CPU1_SA_PAR")
	)
	(arc
		(start 136.40181 -255.501902)
		(mid 136.684766 -255.578079)
		(end 136.967722 -255.501902)
		(width 0.0889)
		(layer "In4.Cu")
		(net "M_J_CPU1_SA_PAR")
	)
	(arc
		(start 143.922242 -255.501902)
		(mid 144.196948 -255.578266)
		(end 144.47393 -255.510538)
		(width 0.0889)
		(layer "In4.Cu")
		(net "M_J_CPU1_SA_PAR")
	)
	(arc
		(start 142.04188 -255.501902)
		(mid 142.324836 -255.578079)
		(end 142.607792 -255.501902)
		(width 0.0889)
		(layer "In4.Cu")
		(net "M_J_CPU1_SA_PAR")
	)
	(arc
		(start 131.383024 -255.47574)
		(mid 131.540534 -255.452542)
		(end 131.693412 -255.497076)
		(width 0.0889)
		(layer "In4.Cu")
		(net "M_J_CPU1_SA_PAR")
	)
	(arc
		(start 143.555974 -255.497076)
		(mid 143.739736 -255.45146)
		(end 143.922242 -255.501902)
		(width 0.0889)
		(layer "In4.Cu")
		(net "M_J_CPU1_SA_PAR")
	)
	(arc
		(start 142.607792 -255.501902)
		(mid 142.794736 -255.451647)
		(end 142.98168 -255.501902)
		(width 0.0889)
		(layer "In4.Cu")
		(net "M_J_CPU1_SA_PAR")
	)
	(arc
		(start 137.916158 -255.497076)
		(mid 138.099666 -255.451582)
		(end 138.281918 -255.501902)
		(width 0.0889)
		(layer "In4.Cu")
		(net "M_J_CPU1_SA_PAR")
	)
	(segment
		(start 131.047998 -247.99036)
		(end 131.51485 -247.724422)
		(width 0.12954)
		(layer "F.Cu")
		(net "M_J_CPU1_SA_DQS_DP<9>")
	)
	(segment
		(start 178.02606 -239.710468)
		(end 178.876198 -240.560606)
		(width 0.16002)
		(layer "In4.Cu")
		(net "M_J_CPU1_SA_DQS_DP<9>")
	)
	(segment
		(start 175.448976 -239.710468)
		(end 178.02606 -239.710468)
		(width 0.16002)
		(layer "In4.Cu")
		(net "M_J_CPU1_SA_DQS_DP<9>")
	)
	(segment
		(start 171.036234 -240.560606)
		(end 172.557186 -240.560606)
		(width 0.16002)
		(layer "In4.Cu")
		(net "M_J_CPU1_SA_DQS_DP<9>")
	)
	(segment
		(start 185.90514 -239.67821)
		(end 186.02198 -239.56137)
		(width 0.16002)
		(layer "In4.Cu")
		(net "M_J_CPU1_SA_DQS_DP<9>")
	)
	(segment
		(start 135.454898 -247.394476)
		(end 135.46328 -247.399302)
		(width 0.09525)
		(layer "In4.Cu")
		(net "M_J_CPU1_SA_DQS_DP<9>")
	)
	(segment
		(start 160.511236 -243.383308)
		(end 160.323276 -243.195348)
		(width 0.16002)
		(layer "In4.Cu")
		(net "M_J_CPU1_SA_DQS_DP<9>")
	)
	(segment
		(start 132.266182 -247.399302)
		(end 132.274564 -247.394476)
		(width 0.09525)
		(layer "In4.Cu")
		(net "M_J_CPU1_SA_DQS_DP<9>")
	)
	(segment
		(start 147.895564 -247.104916)
		(end 147.919186 -247.104916)
		(width 0.09525)
		(layer "In4.Cu")
		(net "M_J_CPU1_SA_DQS_DP<9>")
	)
	(segment
		(start 159.61106 -244.283484)
		(end 160.138364 -244.283484)
		(width 0.16002)
		(layer "In4.Cu")
		(net "M_J_CPU1_SA_DQS_DP<9>")
	)
	(segment
		(start 160.796732 -242.721892)
		(end 160.984692 -242.909852)
		(width 0.16002)
		(layer "In4.Cu")
		(net "M_J_CPU1_SA_DQS_DP<9>")
	)
	(segment
		(start 159.14624 -244.095524)
		(end 159.4231 -244.095524)
		(width 0.16002)
		(layer "In4.Cu")
		(net "M_J_CPU1_SA_DQS_DP<9>")
	)
	(segment
		(start 159.137604 -244.75694)
		(end 158.949644 -244.56898)
		(width 0.16002)
		(layer "In4.Cu")
		(net "M_J_CPU1_SA_DQS_DP<9>")
	)
	(segment
		(start 169.872914 -239.397286)
		(end 171.036234 -240.560606)
		(width 0.16002)
		(layer "In4.Cu")
		(net "M_J_CPU1_SA_DQS_DP<9>")
	)
	(segment
		(start 185.42508 -239.67821)
		(end 185.90514 -239.67821)
		(width 0.16002)
		(layer "In4.Cu")
		(net "M_J_CPU1_SA_DQS_DP<9>")
	)
	(segment
		(start 146.033744 -247.609614)
		(end 146.938746 -247.609614)
		(width 0.09525)
		(layer "In4.Cu")
		(net "M_J_CPU1_SA_DQS_DP<9>")
	)
	(segment
		(start 157.576012 -245.665752)
		(end 157.772608 -245.469156)
		(width 0.16002)
		(layer "In4.Cu")
		(net "M_J_CPU1_SA_DQS_DP<9>")
	)
	(segment
		(start 131.51485 -247.724422)
		(end 131.360926 -247.458992)
		(width 0.09525)
		(layer "In4.Cu")
		(net "M_J_CPU1_SA_DQS_DP<9>")
	)
	(segment
		(start 180.61559 -240.198402)
		(end 181.188106 -240.198402)
		(width 0.16002)
		(layer "In4.Cu")
		(net "M_J_CPU1_SA_DQS_DP<9>")
	)
	(segment
		(start 145.882106 -247.45823)
		(end 146.033744 -247.609614)
		(width 0.09525)
		(layer "In4.Cu")
		(net "M_J_CPU1_SA_DQS_DP<9>")
	)
	(segment
		(start 180.253386 -240.560606)
		(end 180.61559 -240.198402)
		(width 0.16002)
		(layer "In4.Cu")
		(net "M_J_CPU1_SA_DQS_DP<9>")
	)
	(segment
		(start 158.049468 -245.469156)
		(end 158.237428 -245.657116)
		(width 0.16002)
		(layer "In4.Cu")
		(net "M_J_CPU1_SA_DQS_DP<9>")
	)
	(segment
		(start 160.519872 -242.721892)
		(end 160.796732 -242.721892)
		(width 0.16002)
		(layer "In4.Cu")
		(net "M_J_CPU1_SA_DQS_DP<9>")
	)
	(segment
		(start 144.472406 -247.407938)
		(end 144.487138 -247.399302)
		(width 0.09525)
		(layer "In4.Cu")
		(net "M_J_CPU1_SA_DQS_DP<9>")
	)
	(segment
		(start 160.323276 -243.195348)
		(end 160.323276 -242.918488)
		(width 0.16002)
		(layer "In4.Cu")
		(net "M_J_CPU1_SA_DQS_DP<9>")
	)
	(segment
		(start 166.928546 -239.397286)
		(end 169.872914 -239.397286)
		(width 0.16002)
		(layer "In4.Cu")
		(net "M_J_CPU1_SA_DQS_DP<9>")
	)
	(segment
		(start 185.30824 -239.56137)
		(end 185.42508 -239.67821)
		(width 0.16002)
		(layer "In4.Cu")
		(net "M_J_CPU1_SA_DQS_DP<9>")
	)
	(segment
		(start 158.949644 -244.56898)
		(end 158.949644 -244.29212)
		(width 0.16002)
		(layer "In4.Cu")
		(net "M_J_CPU1_SA_DQS_DP<9>")
	)
	(segment
		(start 187.060078 -239.835182)
		(end 187.060078 -239.835436)
		(width 0.16002)
		(layer "In4.Cu")
		(net "M_J_CPU1_SA_DQS_DP<9>")
	)
	(segment
		(start 160.138364 -244.283484)
		(end 160.511236 -243.910612)
		(width 0.16002)
		(layer "In4.Cu")
		(net "M_J_CPU1_SA_DQS_DP<9>")
	)
	(segment
		(start 147.919186 -247.104916)
		(end 157.316932 -247.104916)
		(width 0.16002)
		(layer "In4.Cu")
		(net "M_J_CPU1_SA_DQS_DP<9>")
	)
	(segment
		(start 131.360926 -247.458992)
		(end 131.384294 -247.372124)
		(width 0.09525)
		(layer "In4.Cu")
		(net "M_J_CPU1_SA_DQS_DP<9>")
	)
	(segment
		(start 160.984692 -242.909852)
		(end 161.511996 -242.909852)
		(width 0.16002)
		(layer "In4.Cu")
		(net "M_J_CPU1_SA_DQS_DP<9>")
	)
	(segment
		(start 183.018176 -239.710468)
		(end 184.106312 -239.710468)
		(width 0.16002)
		(layer "In4.Cu")
		(net "M_J_CPU1_SA_DQS_DP<9>")
	)
	(segment
		(start 184.106312 -239.710468)
		(end 184.25541 -239.56137)
		(width 0.16002)
		(layer "In4.Cu")
		(net "M_J_CPU1_SA_DQS_DP<9>")
	)
	(segment
		(start 175.11141 -239.372902)
		(end 175.448976 -239.710468)
		(width 0.16002)
		(layer "In4.Cu")
		(net "M_J_CPU1_SA_DQS_DP<9>")
	)
	(segment
		(start 137.906252 -247.399302)
		(end 137.914634 -247.394476)
		(width 0.09525)
		(layer "In4.Cu")
		(net "M_J_CPU1_SA_DQS_DP<9>")
	)
	(segment
		(start 136.394952 -247.394476)
		(end 136.403334 -247.399302)
		(width 0.09525)
		(layer "In4.Cu")
		(net "M_J_CPU1_SA_DQS_DP<9>")
	)
	(segment
		(start 172.557186 -240.560606)
		(end 172.89653 -240.221262)
		(width 0.16002)
		(layer "In4.Cu")
		(net "M_J_CPU1_SA_DQS_DP<9>")
	)
	(segment
		(start 133.206236 -247.399302)
		(end 133.214618 -247.394476)
		(width 0.09525)
		(layer "In4.Cu")
		(net "M_J_CPU1_SA_DQS_DP<9>")
	)
	(segment
		(start 136.966198 -247.399302)
		(end 136.97458 -247.394476)
		(width 0.09525)
		(layer "In4.Cu")
		(net "M_J_CPU1_SA_DQS_DP<9>")
	)
	(segment
		(start 184.25541 -239.56137)
		(end 185.30824 -239.56137)
		(width 0.16002)
		(layer "In4.Cu")
		(net "M_J_CPU1_SA_DQS_DP<9>")
	)
	(segment
		(start 160.323276 -242.918488)
		(end 160.519872 -242.721892)
		(width 0.16002)
		(layer "In4.Cu")
		(net "M_J_CPU1_SA_DQS_DP<9>")
	)
	(segment
		(start 158.764732 -245.657116)
		(end 159.137604 -245.284244)
		(width 0.16002)
		(layer "In4.Cu")
		(net "M_J_CPU1_SA_DQS_DP<9>")
	)
	(segment
		(start 146.938746 -247.609614)
		(end 147.502372 -247.045988)
		(width 0.09525)
		(layer "In4.Cu")
		(net "M_J_CPU1_SA_DQS_DP<9>")
	)
	(segment
		(start 178.876198 -240.560606)
		(end 180.253386 -240.560606)
		(width 0.16002)
		(layer "In4.Cu")
		(net "M_J_CPU1_SA_DQS_DP<9>")
	)
	(segment
		(start 173.56455 -240.221262)
		(end 174.41291 -239.372902)
		(width 0.16002)
		(layer "In4.Cu")
		(net "M_J_CPU1_SA_DQS_DP<9>")
	)
	(segment
		(start 157.576012 -245.942612)
		(end 157.576012 -245.665752)
		(width 0.16002)
		(layer "In4.Cu")
		(net "M_J_CPU1_SA_DQS_DP<9>")
	)
	(segment
		(start 161.511996 -242.909852)
		(end 164.261546 -240.160302)
		(width 0.16002)
		(layer "In4.Cu")
		(net "M_J_CPU1_SA_DQS_DP<9>")
	)
	(segment
		(start 144.855438 -247.394476)
		(end 144.86382 -247.399302)
		(width 0.09525)
		(layer "In4.Cu")
		(net "M_J_CPU1_SA_DQS_DP<9>")
	)
	(segment
		(start 160.511236 -243.910612)
		(end 160.511236 -243.383308)
		(width 0.16002)
		(layer "In4.Cu")
		(net "M_J_CPU1_SA_DQS_DP<9>")
	)
	(segment
		(start 144.86382 -247.399302)
		(end 144.884648 -247.411494)
		(width 0.09525)
		(layer "In4.Cu")
		(net "M_J_CPU1_SA_DQS_DP<9>")
	)
	(segment
		(start 159.4231 -244.095524)
		(end 159.61106 -244.283484)
		(width 0.16002)
		(layer "In4.Cu")
		(net "M_J_CPU1_SA_DQS_DP<9>")
	)
	(segment
		(start 157.763972 -246.657876)
		(end 157.763972 -246.130572)
		(width 0.16002)
		(layer "In4.Cu")
		(net "M_J_CPU1_SA_DQS_DP<9>")
	)
	(segment
		(start 157.316932 -247.104916)
		(end 157.763972 -246.657876)
		(width 0.16002)
		(layer "In4.Cu")
		(net "M_J_CPU1_SA_DQS_DP<9>")
	)
	(segment
		(start 186.02198 -239.56137)
		(end 186.786266 -239.56137)
		(width 0.16002)
		(layer "In4.Cu")
		(net "M_J_CPU1_SA_DQS_DP<9>")
	)
	(segment
		(start 157.772608 -245.469156)
		(end 158.049468 -245.469156)
		(width 0.16002)
		(layer "In4.Cu")
		(net "M_J_CPU1_SA_DQS_DP<9>")
	)
	(segment
		(start 158.237428 -245.657116)
		(end 158.764732 -245.657116)
		(width 0.16002)
		(layer "In4.Cu")
		(net "M_J_CPU1_SA_DQS_DP<9>")
	)
	(segment
		(start 147.502372 -247.045988)
		(end 147.836636 -247.045988)
		(width 0.09525)
		(layer "In4.Cu")
		(net "M_J_CPU1_SA_DQS_DP<9>")
	)
	(segment
		(start 159.137604 -245.284244)
		(end 159.137604 -244.75694)
		(width 0.16002)
		(layer "In4.Cu")
		(net "M_J_CPU1_SA_DQS_DP<9>")
	)
	(segment
		(start 158.949644 -244.29212)
		(end 159.14624 -244.095524)
		(width 0.16002)
		(layer "In4.Cu")
		(net "M_J_CPU1_SA_DQS_DP<9>")
	)
	(segment
		(start 172.89653 -240.221262)
		(end 173.56455 -240.221262)
		(width 0.16002)
		(layer "In4.Cu")
		(net "M_J_CPU1_SA_DQS_DP<9>")
	)
	(segment
		(start 182.021226 -239.365282)
		(end 182.67299 -239.365282)
		(width 0.16002)
		(layer "In4.Cu")
		(net "M_J_CPU1_SA_DQS_DP<9>")
	)
	(segment
		(start 157.763972 -246.130572)
		(end 157.576012 -245.942612)
		(width 0.16002)
		(layer "In4.Cu")
		(net "M_J_CPU1_SA_DQS_DP<9>")
	)
	(segment
		(start 143.546068 -247.399302)
		(end 143.55445 -247.394476)
		(width 0.09525)
		(layer "In4.Cu")
		(net "M_J_CPU1_SA_DQS_DP<9>")
	)
	(segment
		(start 164.261546 -240.160302)
		(end 166.16553 -240.160302)
		(width 0.16002)
		(layer "In4.Cu")
		(net "M_J_CPU1_SA_DQS_DP<9>")
	)
	(segment
		(start 166.16553 -240.160302)
		(end 166.928546 -239.397286)
		(width 0.16002)
		(layer "In4.Cu")
		(net "M_J_CPU1_SA_DQS_DP<9>")
	)
	(segment
		(start 182.67299 -239.365282)
		(end 183.018176 -239.710468)
		(width 0.16002)
		(layer "In4.Cu")
		(net "M_J_CPU1_SA_DQS_DP<9>")
	)
	(segment
		(start 141.094968 -247.394476)
		(end 141.10335 -247.399302)
		(width 0.09525)
		(layer "In4.Cu")
		(net "M_J_CPU1_SA_DQS_DP<9>")
	)
	(segment
		(start 141.666214 -247.399302)
		(end 141.674596 -247.394476)
		(width 0.09525)
		(layer "In4.Cu")
		(net "M_J_CPU1_SA_DQS_DP<9>")
	)
	(segment
		(start 174.41291 -239.372902)
		(end 175.11141 -239.372902)
		(width 0.16002)
		(layer "In4.Cu")
		(net "M_J_CPU1_SA_DQS_DP<9>")
	)
	(segment
		(start 181.188106 -240.198402)
		(end 182.021226 -239.365282)
		(width 0.16002)
		(layer "In4.Cu")
		(net "M_J_CPU1_SA_DQS_DP<9>")
	)
	(segment
		(start 131.694936 -247.394476)
		(end 131.703318 -247.399302)
		(width 0.09525)
		(layer "In4.Cu")
		(net "M_J_CPU1_SA_DQS_DP<9>")
	)
	(segment
		(start 140.154914 -247.394476)
		(end 140.163296 -247.399302)
		(width 0.09525)
		(layer "In4.Cu")
		(net "M_J_CPU1_SA_DQS_DP<9>")
	)
	(segment
		(start 186.786266 -239.56137)
		(end 187.060078 -239.835182)
		(width 0.16002)
		(layer "In4.Cu")
		(net "M_J_CPU1_SA_DQS_DP<9>")
	)
	(segment
		(start 147.836636 -247.045988)
		(end 147.895564 -247.104916)
		(width 0.09525)
		(layer "In4.Cu")
		(net "M_J_CPU1_SA_DQS_DP<9>")
	)
	(arc
		(start 134.523226 -247.399302)
		(mid 134.804658 -247.475057)
		(end 135.08609 -247.399302)
		(width 0.09525)
		(layer "In4.Cu")
		(net "M_J_CPU1_SA_DQS_DP<9>")
	)
	(arc
		(start 135.08609 -247.399302)
		(mid 135.269865 -247.34853)
		(end 135.454898 -247.394476)
		(width 0.09525)
		(layer "In4.Cu")
		(net "M_J_CPU1_SA_DQS_DP<9>")
	)
	(arc
		(start 136.403334 -247.399302)
		(mid 136.684766 -247.475057)
		(end 136.966198 -247.399302)
		(width 0.09525)
		(layer "In4.Cu")
		(net "M_J_CPU1_SA_DQS_DP<9>")
	)
	(arc
		(start 136.97458 -247.394476)
		(mid 137.159612 -247.348562)
		(end 137.343388 -247.399302)
		(width 0.09525)
		(layer "In4.Cu")
		(net "M_J_CPU1_SA_DQS_DP<9>")
	)
	(arc
		(start 139.786106 -247.399302)
		(mid 139.969881 -247.34853)
		(end 140.154914 -247.394476)
		(width 0.09525)
		(layer "In4.Cu")
		(net "M_J_CPU1_SA_DQS_DP<9>")
	)
	(arc
		(start 145.426684 -247.399302)
		(mid 145.610713 -247.348403)
		(end 145.796 -247.394476)
		(width 0.09525)
		(layer "In4.Cu")
		(net "M_J_CPU1_SA_DQS_DP<9>")
	)
	(arc
		(start 132.274564 -247.394476)
		(mid 132.459596 -247.348562)
		(end 132.643372 -247.399302)
		(width 0.09525)
		(layer "In4.Cu")
		(net "M_J_CPU1_SA_DQS_DP<9>")
	)
	(arc
		(start 131.384294 -247.372124)
		(mid 131.542044 -247.349605)
		(end 131.694936 -247.394476)
		(width 0.09525)
		(layer "In4.Cu")
		(net "M_J_CPU1_SA_DQS_DP<9>")
	)
	(arc
		(start 143.55445 -247.394476)
		(mid 143.739736 -247.34844)
		(end 143.923766 -247.399302)
		(width 0.09525)
		(layer "In4.Cu")
		(net "M_J_CPU1_SA_DQS_DP<9>")
	)
	(arc
		(start 136.026144 -247.399302)
		(mid 136.209919 -247.34853)
		(end 136.394952 -247.394476)
		(width 0.09525)
		(layer "In4.Cu")
		(net "M_J_CPU1_SA_DQS_DP<9>")
	)
	(arc
		(start 138.283442 -247.399302)
		(mid 138.564874 -247.475057)
		(end 138.846306 -247.399302)
		(width 0.09525)
		(layer "In4.Cu")
		(net "M_J_CPU1_SA_DQS_DP<9>")
	)
	(arc
		(start 145.796 -247.394476)
		(mid 145.832308 -247.416743)
		(end 145.86585 -247.44299)
		(width 0.09525)
		(layer "In4.Cu")
		(net "M_J_CPU1_SA_DQS_DP<9>")
	)
	(arc
		(start 138.846306 -247.399302)
		(mid 139.034774 -247.348625)
		(end 139.223242 -247.399302)
		(width 0.09525)
		(layer "In4.Cu")
		(net "M_J_CPU1_SA_DQS_DP<9>")
	)
	(arc
		(start 145.86585 -247.44299)
		(mid 145.874092 -247.450488)
		(end 145.882106 -247.45823)
		(width 0.09525)
		(layer "In4.Cu")
		(net "M_J_CPU1_SA_DQS_DP<9>")
	)
	(arc
		(start 142.983204 -247.399302)
		(mid 143.264636 -247.475057)
		(end 143.546068 -247.399302)
		(width 0.09525)
		(layer "In4.Cu")
		(net "M_J_CPU1_SA_DQS_DP<9>")
	)
	(arc
		(start 133.214618 -247.394476)
		(mid 133.39965 -247.348562)
		(end 133.583426 -247.399302)
		(width 0.09525)
		(layer "In4.Cu")
		(net "M_J_CPU1_SA_DQS_DP<9>")
	)
	(arc
		(start 144.487138 -247.399302)
		(mid 144.670659 -247.348658)
		(end 144.855438 -247.394476)
		(width 0.09525)
		(layer "In4.Cu")
		(net "M_J_CPU1_SA_DQS_DP<9>")
	)
	(arc
		(start 144.884648 -247.411494)
		(mid 145.157253 -247.47529)
		(end 145.426684 -247.399302)
		(width 0.09525)
		(layer "In4.Cu")
		(net "M_J_CPU1_SA_DQS_DP<9>")
	)
	(arc
		(start 139.223242 -247.399302)
		(mid 139.504674 -247.475057)
		(end 139.786106 -247.399302)
		(width 0.09525)
		(layer "In4.Cu")
		(net "M_J_CPU1_SA_DQS_DP<9>")
	)
	(arc
		(start 140.72616 -247.399302)
		(mid 140.909935 -247.34853)
		(end 141.094968 -247.394476)
		(width 0.09525)
		(layer "In4.Cu")
		(net "M_J_CPU1_SA_DQS_DP<9>")
	)
	(arc
		(start 141.674596 -247.394476)
		(mid 141.859628 -247.348562)
		(end 142.043404 -247.399302)
		(width 0.09525)
		(layer "In4.Cu")
		(net "M_J_CPU1_SA_DQS_DP<9>")
	)
	(arc
		(start 135.46328 -247.399302)
		(mid 135.744712 -247.475057)
		(end 136.026144 -247.399302)
		(width 0.09525)
		(layer "In4.Cu")
		(net "M_J_CPU1_SA_DQS_DP<9>")
	)
	(arc
		(start 141.10335 -247.399302)
		(mid 141.384782 -247.475057)
		(end 141.666214 -247.399302)
		(width 0.09525)
		(layer "In4.Cu")
		(net "M_J_CPU1_SA_DQS_DP<9>")
	)
	(arc
		(start 142.043404 -247.399302)
		(mid 142.324836 -247.475057)
		(end 142.606268 -247.399302)
		(width 0.09525)
		(layer "In4.Cu")
		(net "M_J_CPU1_SA_DQS_DP<9>")
	)
	(arc
		(start 134.14629 -247.399302)
		(mid 134.334758 -247.348625)
		(end 134.523226 -247.399302)
		(width 0.09525)
		(layer "In4.Cu")
		(net "M_J_CPU1_SA_DQS_DP<9>")
	)
	(arc
		(start 132.643372 -247.399302)
		(mid 132.924804 -247.475057)
		(end 133.206236 -247.399302)
		(width 0.09525)
		(layer "In4.Cu")
		(net "M_J_CPU1_SA_DQS_DP<9>")
	)
	(arc
		(start 142.606268 -247.399302)
		(mid 142.794736 -247.348625)
		(end 142.983204 -247.399302)
		(width 0.09525)
		(layer "In4.Cu")
		(net "M_J_CPU1_SA_DQS_DP<9>")
	)
	(arc
		(start 140.163296 -247.399302)
		(mid 140.444728 -247.475057)
		(end 140.72616 -247.399302)
		(width 0.09525)
		(layer "In4.Cu")
		(net "M_J_CPU1_SA_DQS_DP<9>")
	)
	(arc
		(start 137.914634 -247.394476)
		(mid 138.099666 -247.348562)
		(end 138.283442 -247.399302)
		(width 0.09525)
		(layer "In4.Cu")
		(net "M_J_CPU1_SA_DQS_DP<9>")
	)
	(arc
		(start 137.343388 -247.399302)
		(mid 137.62482 -247.475057)
		(end 137.906252 -247.399302)
		(width 0.09525)
		(layer "In4.Cu")
		(net "M_J_CPU1_SA_DQS_DP<9>")
	)
	(arc
		(start 143.923766 -247.399302)
		(mid 144.196948 -247.475244)
		(end 144.472406 -247.407938)
		(width 0.09525)
		(layer "In4.Cu")
		(net "M_J_CPU1_SA_DQS_DP<9>")
	)
	(arc
		(start 131.703318 -247.399302)
		(mid 131.98475 -247.475057)
		(end 132.266182 -247.399302)
		(width 0.09525)
		(layer "In4.Cu")
		(net "M_J_CPU1_SA_DQS_DP<9>")
	)
	(arc
		(start 133.583426 -247.399302)
		(mid 133.864858 -247.475057)
		(end 134.14629 -247.399302)
		(width 0.09525)
		(layer "In4.Cu")
		(net "M_J_CPU1_SA_DQS_DP<9>")
	)
	(segment
		(start 131.047998 -243.130324)
		(end 131.51485 -242.864386)
		(width 0.12954)
		(layer "F.Cu")
		(net "M_J_CPU1_SA_DQS_DP<8>")
	)
	(segment
		(start 146.38528 -242.154456)
		(end 146.88693 -242.154456)
		(width 0.09525)
		(layer "In4.Cu")
		(net "M_J_CPU1_SA_DQS_DP<8>")
	)
	(segment
		(start 180.253386 -231.210612)
		(end 180.61559 -230.848408)
		(width 0.16002)
		(layer "In4.Cu")
		(net "M_J_CPU1_SA_DQS_DP<8>")
	)
	(segment
		(start 181.188106 -230.848408)
		(end 182.021226 -230.015288)
		(width 0.16002)
		(layer "In4.Cu")
		(net "M_J_CPU1_SA_DQS_DP<8>")
	)
	(segment
		(start 147.597368 -241.444018)
		(end 147.765008 -241.444018)
		(width 0.09525)
		(layer "In4.Cu")
		(net "M_J_CPU1_SA_DQS_DP<8>")
	)
	(segment
		(start 185.27522 -230.211376)
		(end 185.39206 -230.328216)
		(width 0.16002)
		(layer "In4.Cu")
		(net "M_J_CPU1_SA_DQS_DP<8>")
	)
	(segment
		(start 185.39206 -230.328216)
		(end 185.87212 -230.328216)
		(width 0.16002)
		(layer "In4.Cu")
		(net "M_J_CPU1_SA_DQS_DP<8>")
	)
	(segment
		(start 152.128728 -241.502946)
		(end 158.108142 -235.523532)
		(width 0.16002)
		(layer "In4.Cu")
		(net "M_J_CPU1_SA_DQS_DP<8>")
	)
	(segment
		(start 159.21863 -234.025948)
		(end 159.415226 -233.829352)
		(width 0.16002)
		(layer "In4.Cu")
		(net "M_J_CPU1_SA_DQS_DP<8>")
	)
	(segment
		(start 172.557186 -231.210612)
		(end 172.89653 -230.871268)
		(width 0.16002)
		(layer "In4.Cu")
		(net "M_J_CPU1_SA_DQS_DP<8>")
	)
	(segment
		(start 172.89653 -230.871268)
		(end 173.56455 -230.871268)
		(width 0.16002)
		(layer "In4.Cu")
		(net "M_J_CPU1_SA_DQS_DP<8>")
	)
	(segment
		(start 162.208972 -231.798622)
		(end 161.965894 -231.555544)
		(width 0.16002)
		(layer "In4.Cu")
		(net "M_J_CPU1_SA_DQS_DP<8>")
	)
	(segment
		(start 160.83534 -233.699558)
		(end 160.83534 -233.172254)
		(width 0.16002)
		(layer "In4.Cu")
		(net "M_J_CPU1_SA_DQS_DP<8>")
	)
	(segment
		(start 160.592262 -232.929176)
		(end 160.592262 -232.652316)
		(width 0.16002)
		(layer "In4.Cu")
		(net "M_J_CPU1_SA_DQS_DP<8>")
	)
	(segment
		(start 131.360926 -242.598956)
		(end 131.384294 -242.512088)
		(width 0.09525)
		(layer "In4.Cu")
		(net "M_J_CPU1_SA_DQS_DP<8>")
	)
	(segment
		(start 146.88693 -242.154456)
		(end 147.597368 -241.444018)
		(width 0.09525)
		(layer "In4.Cu")
		(net "M_J_CPU1_SA_DQS_DP<8>")
	)
	(segment
		(start 135.454898 -242.53444)
		(end 135.46328 -242.539266)
		(width 0.09525)
		(layer "In4.Cu")
		(net "M_J_CPU1_SA_DQS_DP<8>")
	)
	(segment
		(start 160.788858 -232.45572)
		(end 161.065718 -232.45572)
		(width 0.16002)
		(layer "In4.Cu")
		(net "M_J_CPU1_SA_DQS_DP<8>")
	)
	(segment
		(start 162.43935 -231.082088)
		(end 162.682428 -231.325166)
		(width 0.16002)
		(layer "In4.Cu")
		(net "M_J_CPU1_SA_DQS_DP<8>")
	)
	(segment
		(start 166.93515 -230.040688)
		(end 169.86631 -230.040688)
		(width 0.16002)
		(layer "In4.Cu")
		(net "M_J_CPU1_SA_DQS_DP<8>")
	)
	(segment
		(start 169.86631 -230.040688)
		(end 171.036234 -231.210612)
		(width 0.16002)
		(layer "In4.Cu")
		(net "M_J_CPU1_SA_DQS_DP<8>")
	)
	(segment
		(start 175.448976 -230.360474)
		(end 178.02606 -230.360474)
		(width 0.16002)
		(layer "In4.Cu")
		(net "M_J_CPU1_SA_DQS_DP<8>")
	)
	(segment
		(start 174.41291 -230.022908)
		(end 175.11141 -230.022908)
		(width 0.16002)
		(layer "In4.Cu")
		(net "M_J_CPU1_SA_DQS_DP<8>")
	)
	(segment
		(start 161.965894 -231.278684)
		(end 162.16249 -231.082088)
		(width 0.16002)
		(layer "In4.Cu")
		(net "M_J_CPU1_SA_DQS_DP<8>")
	)
	(segment
		(start 171.036234 -231.210612)
		(end 172.557186 -231.210612)
		(width 0.16002)
		(layer "In4.Cu")
		(net "M_J_CPU1_SA_DQS_DP<8>")
	)
	(segment
		(start 184.106312 -230.360474)
		(end 184.25541 -230.211376)
		(width 0.16002)
		(layer "In4.Cu")
		(net "M_J_CPU1_SA_DQS_DP<8>")
	)
	(segment
		(start 158.108142 -235.523532)
		(end 159.011366 -235.523532)
		(width 0.16002)
		(layer "In4.Cu")
		(net "M_J_CPU1_SA_DQS_DP<8>")
	)
	(segment
		(start 133.206236 -242.539266)
		(end 133.214618 -242.53444)
		(width 0.09525)
		(layer "In4.Cu")
		(net "M_J_CPU1_SA_DQS_DP<8>")
	)
	(segment
		(start 131.694936 -242.53444)
		(end 131.703318 -242.539266)
		(width 0.09525)
		(layer "In4.Cu")
		(net "M_J_CPU1_SA_DQS_DP<8>")
	)
	(segment
		(start 160.83534 -233.172254)
		(end 160.592262 -232.929176)
		(width 0.16002)
		(layer "In4.Cu")
		(net "M_J_CPU1_SA_DQS_DP<8>")
	)
	(segment
		(start 159.415226 -233.829352)
		(end 159.692086 -233.829352)
		(width 0.16002)
		(layer "In4.Cu")
		(net "M_J_CPU1_SA_DQS_DP<8>")
	)
	(segment
		(start 161.965894 -231.555544)
		(end 161.965894 -231.278684)
		(width 0.16002)
		(layer "In4.Cu")
		(net "M_J_CPU1_SA_DQS_DP<8>")
	)
	(segment
		(start 180.61559 -230.848408)
		(end 181.188106 -230.848408)
		(width 0.16002)
		(layer "In4.Cu")
		(net "M_J_CPU1_SA_DQS_DP<8>")
	)
	(segment
		(start 140.154914 -242.53444)
		(end 140.163296 -242.539266)
		(width 0.09525)
		(layer "In4.Cu")
		(net "M_J_CPU1_SA_DQS_DP<8>")
	)
	(segment
		(start 185.87212 -230.328216)
		(end 185.98896 -230.211376)
		(width 0.16002)
		(layer "In4.Cu")
		(net "M_J_CPU1_SA_DQS_DP<8>")
	)
	(segment
		(start 160.592262 -232.652316)
		(end 160.788858 -232.45572)
		(width 0.16002)
		(layer "In4.Cu")
		(net "M_J_CPU1_SA_DQS_DP<8>")
	)
	(segment
		(start 185.98896 -230.211376)
		(end 186.786266 -230.211376)
		(width 0.16002)
		(layer "In4.Cu")
		(net "M_J_CPU1_SA_DQS_DP<8>")
	)
	(segment
		(start 186.786266 -230.211376)
		(end 187.060078 -230.485188)
		(width 0.16002)
		(layer "In4.Cu")
		(net "M_J_CPU1_SA_DQS_DP<8>")
	)
	(segment
		(start 147.847558 -241.502946)
		(end 152.128728 -241.502946)
		(width 0.16002)
		(layer "In4.Cu")
		(net "M_J_CPU1_SA_DQS_DP<8>")
	)
	(segment
		(start 159.935164 -234.07243)
		(end 160.462468 -234.07243)
		(width 0.16002)
		(layer "In4.Cu")
		(net "M_J_CPU1_SA_DQS_DP<8>")
	)
	(segment
		(start 159.011366 -235.523532)
		(end 159.461708 -235.07319)
		(width 0.16002)
		(layer "In4.Cu")
		(net "M_J_CPU1_SA_DQS_DP<8>")
	)
	(segment
		(start 162.682428 -231.325166)
		(end 163.209732 -231.325166)
		(width 0.16002)
		(layer "In4.Cu")
		(net "M_J_CPU1_SA_DQS_DP<8>")
	)
	(segment
		(start 166.16553 -230.810308)
		(end 166.93515 -230.040688)
		(width 0.16002)
		(layer "In4.Cu")
		(net "M_J_CPU1_SA_DQS_DP<8>")
	)
	(segment
		(start 136.394952 -242.53444)
		(end 136.403334 -242.539266)
		(width 0.09525)
		(layer "In4.Cu")
		(net "M_J_CPU1_SA_DQS_DP<8>")
	)
	(segment
		(start 175.11141 -230.022908)
		(end 175.448976 -230.360474)
		(width 0.16002)
		(layer "In4.Cu")
		(net "M_J_CPU1_SA_DQS_DP<8>")
	)
	(segment
		(start 159.692086 -233.829352)
		(end 159.935164 -234.07243)
		(width 0.16002)
		(layer "In4.Cu")
		(net "M_J_CPU1_SA_DQS_DP<8>")
	)
	(segment
		(start 137.906252 -242.539266)
		(end 137.914634 -242.53444)
		(width 0.09525)
		(layer "In4.Cu")
		(net "M_J_CPU1_SA_DQS_DP<8>")
	)
	(segment
		(start 183.018176 -230.360474)
		(end 184.106312 -230.360474)
		(width 0.16002)
		(layer "In4.Cu")
		(net "M_J_CPU1_SA_DQS_DP<8>")
	)
	(segment
		(start 144.20596 -242.615466)
		(end 145.92427 -242.615466)
		(width 0.09525)
		(layer "In4.Cu")
		(net "M_J_CPU1_SA_DQS_DP<8>")
	)
	(segment
		(start 159.461708 -234.545886)
		(end 159.21863 -234.302808)
		(width 0.16002)
		(layer "In4.Cu")
		(net "M_J_CPU1_SA_DQS_DP<8>")
	)
	(segment
		(start 145.92427 -242.615466)
		(end 146.38528 -242.154456)
		(width 0.09525)
		(layer "In4.Cu")
		(net "M_J_CPU1_SA_DQS_DP<8>")
	)
	(segment
		(start 182.021226 -230.015288)
		(end 182.67299 -230.015288)
		(width 0.16002)
		(layer "In4.Cu")
		(net "M_J_CPU1_SA_DQS_DP<8>")
	)
	(segment
		(start 147.823936 -241.502946)
		(end 147.847558 -241.502946)
		(width 0.09525)
		(layer "In4.Cu")
		(net "M_J_CPU1_SA_DQS_DP<8>")
	)
	(segment
		(start 173.56455 -230.871268)
		(end 174.41291 -230.022908)
		(width 0.16002)
		(layer "In4.Cu")
		(net "M_J_CPU1_SA_DQS_DP<8>")
	)
	(segment
		(start 160.462468 -234.07243)
		(end 160.83534 -233.699558)
		(width 0.16002)
		(layer "In4.Cu")
		(net "M_J_CPU1_SA_DQS_DP<8>")
	)
	(segment
		(start 143.546068 -242.539266)
		(end 143.55445 -242.53444)
		(width 0.09525)
		(layer "In4.Cu")
		(net "M_J_CPU1_SA_DQS_DP<8>")
	)
	(segment
		(start 147.765008 -241.444018)
		(end 147.823936 -241.502946)
		(width 0.09525)
		(layer "In4.Cu")
		(net "M_J_CPU1_SA_DQS_DP<8>")
	)
	(segment
		(start 184.25541 -230.211376)
		(end 185.27522 -230.211376)
		(width 0.16002)
		(layer "In4.Cu")
		(net "M_J_CPU1_SA_DQS_DP<8>")
	)
	(segment
		(start 159.461708 -235.07319)
		(end 159.461708 -234.545886)
		(width 0.16002)
		(layer "In4.Cu")
		(net "M_J_CPU1_SA_DQS_DP<8>")
	)
	(segment
		(start 131.51485 -242.864386)
		(end 131.360926 -242.598956)
		(width 0.09525)
		(layer "In4.Cu")
		(net "M_J_CPU1_SA_DQS_DP<8>")
	)
	(segment
		(start 182.67299 -230.015288)
		(end 183.018176 -230.360474)
		(width 0.16002)
		(layer "In4.Cu")
		(net "M_J_CPU1_SA_DQS_DP<8>")
	)
	(segment
		(start 141.094968 -242.53444)
		(end 141.10335 -242.539266)
		(width 0.09525)
		(layer "In4.Cu")
		(net "M_J_CPU1_SA_DQS_DP<8>")
	)
	(segment
		(start 132.266182 -242.539266)
		(end 132.274564 -242.53444)
		(width 0.09525)
		(layer "In4.Cu")
		(net "M_J_CPU1_SA_DQS_DP<8>")
	)
	(segment
		(start 178.876198 -231.210612)
		(end 180.253386 -231.210612)
		(width 0.16002)
		(layer "In4.Cu")
		(net "M_J_CPU1_SA_DQS_DP<8>")
	)
	(segment
		(start 162.208972 -232.325926)
		(end 162.208972 -231.798622)
		(width 0.16002)
		(layer "In4.Cu")
		(net "M_J_CPU1_SA_DQS_DP<8>")
	)
	(segment
		(start 161.065718 -232.45572)
		(end 161.308796 -232.698798)
		(width 0.16002)
		(layer "In4.Cu")
		(net "M_J_CPU1_SA_DQS_DP<8>")
	)
	(segment
		(start 159.21863 -234.302808)
		(end 159.21863 -234.025948)
		(width 0.16002)
		(layer "In4.Cu")
		(net "M_J_CPU1_SA_DQS_DP<8>")
	)
	(segment
		(start 161.8361 -232.698798)
		(end 162.208972 -232.325926)
		(width 0.16002)
		(layer "In4.Cu")
		(net "M_J_CPU1_SA_DQS_DP<8>")
	)
	(segment
		(start 141.666214 -242.539266)
		(end 141.674596 -242.53444)
		(width 0.09525)
		(layer "In4.Cu")
		(net "M_J_CPU1_SA_DQS_DP<8>")
	)
	(segment
		(start 136.966198 -242.539266)
		(end 136.97458 -242.53444)
		(width 0.09525)
		(layer "In4.Cu")
		(net "M_J_CPU1_SA_DQS_DP<8>")
	)
	(segment
		(start 163.209732 -231.325166)
		(end 163.72459 -230.810308)
		(width 0.16002)
		(layer "In4.Cu")
		(net "M_J_CPU1_SA_DQS_DP<8>")
	)
	(segment
		(start 187.060078 -230.485188)
		(end 187.060078 -230.485442)
		(width 0.16002)
		(layer "In4.Cu")
		(net "M_J_CPU1_SA_DQS_DP<8>")
	)
	(segment
		(start 161.308796 -232.698798)
		(end 161.8361 -232.698798)
		(width 0.16002)
		(layer "In4.Cu")
		(net "M_J_CPU1_SA_DQS_DP<8>")
	)
	(segment
		(start 178.02606 -230.360474)
		(end 178.876198 -231.210612)
		(width 0.16002)
		(layer "In4.Cu")
		(net "M_J_CPU1_SA_DQS_DP<8>")
	)
	(segment
		(start 163.72459 -230.810308)
		(end 166.16553 -230.810308)
		(width 0.16002)
		(layer "In4.Cu")
		(net "M_J_CPU1_SA_DQS_DP<8>")
	)
	(segment
		(start 162.16249 -231.082088)
		(end 162.43935 -231.082088)
		(width 0.16002)
		(layer "In4.Cu")
		(net "M_J_CPU1_SA_DQS_DP<8>")
	)
	(arc
		(start 137.343388 -242.539266)
		(mid 137.62482 -242.615021)
		(end 137.906252 -242.539266)
		(width 0.09525)
		(layer "In4.Cu")
		(net "M_J_CPU1_SA_DQS_DP<8>")
	)
	(arc
		(start 135.46328 -242.539266)
		(mid 135.744712 -242.615021)
		(end 136.026144 -242.539266)
		(width 0.09525)
		(layer "In4.Cu")
		(net "M_J_CPU1_SA_DQS_DP<8>")
	)
	(arc
		(start 142.983204 -242.539266)
		(mid 143.264636 -242.615021)
		(end 143.546068 -242.539266)
		(width 0.09525)
		(layer "In4.Cu")
		(net "M_J_CPU1_SA_DQS_DP<8>")
	)
	(arc
		(start 139.786106 -242.539266)
		(mid 139.969881 -242.488494)
		(end 140.154914 -242.53444)
		(width 0.09525)
		(layer "In4.Cu")
		(net "M_J_CPU1_SA_DQS_DP<8>")
	)
	(arc
		(start 132.643372 -242.539266)
		(mid 132.924804 -242.615021)
		(end 133.206236 -242.539266)
		(width 0.09525)
		(layer "In4.Cu")
		(net "M_J_CPU1_SA_DQS_DP<8>")
	)
	(arc
		(start 141.674596 -242.53444)
		(mid 141.859628 -242.488526)
		(end 142.043404 -242.539266)
		(width 0.09525)
		(layer "In4.Cu")
		(net "M_J_CPU1_SA_DQS_DP<8>")
	)
	(arc
		(start 140.163296 -242.539266)
		(mid 140.444728 -242.615021)
		(end 140.72616 -242.539266)
		(width 0.09525)
		(layer "In4.Cu")
		(net "M_J_CPU1_SA_DQS_DP<8>")
	)
	(arc
		(start 138.283442 -242.539266)
		(mid 138.564874 -242.615021)
		(end 138.846306 -242.539266)
		(width 0.09525)
		(layer "In4.Cu")
		(net "M_J_CPU1_SA_DQS_DP<8>")
	)
	(arc
		(start 143.923766 -242.539266)
		(mid 144.059818 -242.596035)
		(end 144.20596 -242.615466)
		(width 0.09525)
		(layer "In4.Cu")
		(net "M_J_CPU1_SA_DQS_DP<8>")
	)
	(arc
		(start 136.97458 -242.53444)
		(mid 137.159612 -242.488526)
		(end 137.343388 -242.539266)
		(width 0.09525)
		(layer "In4.Cu")
		(net "M_J_CPU1_SA_DQS_DP<8>")
	)
	(arc
		(start 142.043404 -242.539266)
		(mid 142.324836 -242.615021)
		(end 142.606268 -242.539266)
		(width 0.09525)
		(layer "In4.Cu")
		(net "M_J_CPU1_SA_DQS_DP<8>")
	)
	(arc
		(start 143.55445 -242.53444)
		(mid 143.739736 -242.488404)
		(end 143.923766 -242.539266)
		(width 0.09525)
		(layer "In4.Cu")
		(net "M_J_CPU1_SA_DQS_DP<8>")
	)
	(arc
		(start 137.914634 -242.53444)
		(mid 138.099666 -242.488526)
		(end 138.283442 -242.539266)
		(width 0.09525)
		(layer "In4.Cu")
		(net "M_J_CPU1_SA_DQS_DP<8>")
	)
	(arc
		(start 138.846306 -242.539266)
		(mid 139.034774 -242.488589)
		(end 139.223242 -242.539266)
		(width 0.09525)
		(layer "In4.Cu")
		(net "M_J_CPU1_SA_DQS_DP<8>")
	)
	(arc
		(start 133.214618 -242.53444)
		(mid 133.39965 -242.488526)
		(end 133.583426 -242.539266)
		(width 0.09525)
		(layer "In4.Cu")
		(net "M_J_CPU1_SA_DQS_DP<8>")
	)
	(arc
		(start 134.523226 -242.539266)
		(mid 134.804658 -242.615021)
		(end 135.08609 -242.539266)
		(width 0.09525)
		(layer "In4.Cu")
		(net "M_J_CPU1_SA_DQS_DP<8>")
	)
	(arc
		(start 136.026144 -242.539266)
		(mid 136.209919 -242.488494)
		(end 136.394952 -242.53444)
		(width 0.09525)
		(layer "In4.Cu")
		(net "M_J_CPU1_SA_DQS_DP<8>")
	)
	(arc
		(start 134.14629 -242.539266)
		(mid 134.334758 -242.488589)
		(end 134.523226 -242.539266)
		(width 0.09525)
		(layer "In4.Cu")
		(net "M_J_CPU1_SA_DQS_DP<8>")
	)
	(arc
		(start 131.703318 -242.539266)
		(mid 131.98475 -242.615021)
		(end 132.266182 -242.539266)
		(width 0.09525)
		(layer "In4.Cu")
		(net "M_J_CPU1_SA_DQS_DP<8>")
	)
	(arc
		(start 131.384294 -242.512088)
		(mid 131.542044 -242.489569)
		(end 131.694936 -242.53444)
		(width 0.09525)
		(layer "In4.Cu")
		(net "M_J_CPU1_SA_DQS_DP<8>")
	)
	(arc
		(start 142.606268 -242.539266)
		(mid 142.794736 -242.488589)
		(end 142.983204 -242.539266)
		(width 0.09525)
		(layer "In4.Cu")
		(net "M_J_CPU1_SA_DQS_DP<8>")
	)
	(arc
		(start 132.274564 -242.53444)
		(mid 132.459596 -242.488526)
		(end 132.643372 -242.539266)
		(width 0.09525)
		(layer "In4.Cu")
		(net "M_J_CPU1_SA_DQS_DP<8>")
	)
	(arc
		(start 141.10335 -242.539266)
		(mid 141.384782 -242.615021)
		(end 141.666214 -242.539266)
		(width 0.09525)
		(layer "In4.Cu")
		(net "M_J_CPU1_SA_DQS_DP<8>")
	)
	(arc
		(start 136.403334 -242.539266)
		(mid 136.684766 -242.615021)
		(end 136.966198 -242.539266)
		(width 0.09525)
		(layer "In4.Cu")
		(net "M_J_CPU1_SA_DQS_DP<8>")
	)
	(arc
		(start 135.08609 -242.539266)
		(mid 135.269865 -242.488494)
		(end 135.454898 -242.53444)
		(width 0.09525)
		(layer "In4.Cu")
		(net "M_J_CPU1_SA_DQS_DP<8>")
	)
	(arc
		(start 133.583426 -242.539266)
		(mid 133.864858 -242.615021)
		(end 134.14629 -242.539266)
		(width 0.09525)
		(layer "In4.Cu")
		(net "M_J_CPU1_SA_DQS_DP<8>")
	)
	(arc
		(start 140.72616 -242.539266)
		(mid 140.909935 -242.488494)
		(end 141.094968 -242.53444)
		(width 0.09525)
		(layer "In4.Cu")
		(net "M_J_CPU1_SA_DQS_DP<8>")
	)
	(arc
		(start 139.223242 -242.539266)
		(mid 139.504674 -242.615021)
		(end 139.786106 -242.539266)
		(width 0.09525)
		(layer "In4.Cu")
		(net "M_J_CPU1_SA_DQS_DP<8>")
	)
	(segment
		(start 131.047998 -238.270288)
		(end 131.51485 -238.00435)
		(width 0.12954)
		(layer "F.Cu")
		(net "M_J_CPU1_SA_DQS_DP<7>")
	)
	(segment
		(start 161.71545 -221.00794)
		(end 161.911284 -220.812106)
		(width 0.16002)
		(layer "In4.Cu")
		(net "M_J_CPU1_SA_DQS_DP<7>")
	)
	(segment
		(start 146.347688 -236.78388)
		(end 146.347688 -236.516164)
		(width 0.09525)
		(layer "In4.Cu")
		(net "M_J_CPU1_SA_DQS_DP<7>")
	)
	(segment
		(start 173.56455 -221.521274)
		(end 174.41291 -220.672914)
		(width 0.16002)
		(layer "In4.Cu")
		(net "M_J_CPU1_SA_DQS_DP<7>")
	)
	(segment
		(start 166.16553 -221.460314)
		(end 166.93515 -220.690694)
		(width 0.16002)
		(layer "In4.Cu")
		(net "M_J_CPU1_SA_DQS_DP<7>")
	)
	(segment
		(start 182.67299 -220.665294)
		(end 183.018176 -221.01048)
		(width 0.16002)
		(layer "In4.Cu")
		(net "M_J_CPU1_SA_DQS_DP<7>")
	)
	(segment
		(start 136.394952 -237.674404)
		(end 136.403334 -237.67923)
		(width 0.09525)
		(layer "In4.Cu")
		(net "M_J_CPU1_SA_DQS_DP<7>")
	)
	(segment
		(start 135.454898 -237.674404)
		(end 135.46328 -237.67923)
		(width 0.09525)
		(layer "In4.Cu")
		(net "M_J_CPU1_SA_DQS_DP<7>")
	)
	(segment
		(start 163.852352 -220.812106)
		(end 164.128958 -220.812106)
		(width 0.16002)
		(layer "In4.Cu")
		(net "M_J_CPU1_SA_DQS_DP<7>")
	)
	(segment
		(start 185.2422 -220.861382)
		(end 185.35904 -220.978222)
		(width 0.16002)
		(layer "In4.Cu")
		(net "M_J_CPU1_SA_DQS_DP<7>")
	)
	(segment
		(start 178.02606 -221.01048)
		(end 178.875944 -221.860364)
		(width 0.16002)
		(layer "In4.Cu")
		(net "M_J_CPU1_SA_DQS_DP<7>")
	)
	(segment
		(start 132.266182 -237.67923)
		(end 132.274564 -237.674404)
		(width 0.09525)
		(layer "In4.Cu")
		(net "M_J_CPU1_SA_DQS_DP<7>")
	)
	(segment
		(start 143.923258 -237.67923)
		(end 143.933672 -237.685326)
		(width 0.09525)
		(layer "In4.Cu")
		(net "M_J_CPU1_SA_DQS_DP<7>")
	)
	(segment
		(start 180.25364 -221.860364)
		(end 180.61559 -221.498414)
		(width 0.16002)
		(layer "In4.Cu")
		(net "M_J_CPU1_SA_DQS_DP<7>")
	)
	(segment
		(start 180.61559 -221.498414)
		(end 181.188106 -221.498414)
		(width 0.16002)
		(layer "In4.Cu")
		(net "M_J_CPU1_SA_DQS_DP<7>")
	)
	(segment
		(start 146.347688 -236.516164)
		(end 146.585686 -236.278166)
		(width 0.09525)
		(layer "In4.Cu")
		(net "M_J_CPU1_SA_DQS_DP<7>")
	)
	(segment
		(start 162.756596 -221.851474)
		(end 163.283646 -221.851474)
		(width 0.16002)
		(layer "In4.Cu")
		(net "M_J_CPU1_SA_DQS_DP<7>")
	)
	(segment
		(start 145.540984 -237.590584)
		(end 146.347688 -236.78388)
		(width 0.09525)
		(layer "In4.Cu")
		(net "M_J_CPU1_SA_DQS_DP<7>")
	)
	(segment
		(start 160.928304 -221.851474)
		(end 161.342578 -221.851474)
		(width 0.16002)
		(layer "In4.Cu")
		(net "M_J_CPU1_SA_DQS_DP<7>")
	)
	(segment
		(start 146.585686 -236.278166)
		(end 146.94535 -236.278166)
		(width 0.09525)
		(layer "In4.Cu")
		(net "M_J_CPU1_SA_DQS_DP<7>")
	)
	(segment
		(start 131.694936 -237.674404)
		(end 131.703318 -237.67923)
		(width 0.09525)
		(layer "In4.Cu")
		(net "M_J_CPU1_SA_DQS_DP<7>")
	)
	(segment
		(start 182.021226 -220.665294)
		(end 182.67299 -220.665294)
		(width 0.16002)
		(layer "In4.Cu")
		(net "M_J_CPU1_SA_DQS_DP<7>")
	)
	(segment
		(start 137.906252 -237.67923)
		(end 137.914634 -237.674404)
		(width 0.09525)
		(layer "In4.Cu")
		(net "M_J_CPU1_SA_DQS_DP<7>")
	)
	(segment
		(start 171.03598 -221.860364)
		(end 172.55744 -221.860364)
		(width 0.16002)
		(layer "In4.Cu")
		(net "M_J_CPU1_SA_DQS_DP<7>")
	)
	(segment
		(start 147.895564 -235.764324)
		(end 147.919186 -235.764324)
		(width 0.09525)
		(layer "In4.Cu")
		(net "M_J_CPU1_SA_DQS_DP<7>")
	)
	(segment
		(start 181.188106 -221.498414)
		(end 182.021226 -220.665294)
		(width 0.16002)
		(layer "In4.Cu")
		(net "M_J_CPU1_SA_DQS_DP<7>")
	)
	(segment
		(start 184.25541 -220.861382)
		(end 185.2422 -220.861382)
		(width 0.16002)
		(layer "In4.Cu")
		(net "M_J_CPU1_SA_DQS_DP<7>")
	)
	(segment
		(start 161.911284 -220.812106)
		(end 162.18789 -220.812106)
		(width 0.16002)
		(layer "In4.Cu")
		(net "M_J_CPU1_SA_DQS_DP<7>")
	)
	(segment
		(start 147.919186 -235.764324)
		(end 149.370034 -235.764324)
		(width 0.16002)
		(layer "In4.Cu")
		(net "M_J_CPU1_SA_DQS_DP<7>")
	)
	(segment
		(start 162.383724 -221.00794)
		(end 162.383724 -221.478602)
		(width 0.16002)
		(layer "In4.Cu")
		(net "M_J_CPU1_SA_DQS_DP<7>")
	)
	(segment
		(start 164.128958 -220.812106)
		(end 164.324792 -221.00794)
		(width 0.16002)
		(layer "In4.Cu")
		(net "M_J_CPU1_SA_DQS_DP<7>")
	)
	(segment
		(start 164.697664 -221.851474)
		(end 165.281102 -221.851474)
		(width 0.16002)
		(layer "In4.Cu")
		(net "M_J_CPU1_SA_DQS_DP<7>")
	)
	(segment
		(start 166.93515 -220.690694)
		(end 169.86631 -220.690694)
		(width 0.16002)
		(layer "In4.Cu")
		(net "M_J_CPU1_SA_DQS_DP<7>")
	)
	(segment
		(start 174.41291 -220.672914)
		(end 175.11141 -220.672914)
		(width 0.16002)
		(layer "In4.Cu")
		(net "M_J_CPU1_SA_DQS_DP<7>")
	)
	(segment
		(start 161.342578 -221.851474)
		(end 161.71545 -221.478602)
		(width 0.16002)
		(layer "In4.Cu")
		(net "M_J_CPU1_SA_DQS_DP<7>")
	)
	(segment
		(start 164.324792 -221.478602)
		(end 164.697664 -221.851474)
		(width 0.16002)
		(layer "In4.Cu")
		(net "M_J_CPU1_SA_DQS_DP<7>")
	)
	(segment
		(start 156.355034 -228.779324)
		(end 156.355034 -226.424744)
		(width 0.16002)
		(layer "In4.Cu")
		(net "M_J_CPU1_SA_DQS_DP<7>")
	)
	(segment
		(start 156.355034 -226.424744)
		(end 160.928304 -221.851474)
		(width 0.16002)
		(layer "In4.Cu")
		(net "M_J_CPU1_SA_DQS_DP<7>")
	)
	(segment
		(start 161.71545 -221.478602)
		(end 161.71545 -221.00794)
		(width 0.16002)
		(layer "In4.Cu")
		(net "M_J_CPU1_SA_DQS_DP<7>")
	)
	(segment
		(start 165.672262 -221.460314)
		(end 166.16553 -221.460314)
		(width 0.16002)
		(layer "In4.Cu")
		(net "M_J_CPU1_SA_DQS_DP<7>")
	)
	(segment
		(start 162.383724 -221.478602)
		(end 162.756596 -221.851474)
		(width 0.16002)
		(layer "In4.Cu")
		(net "M_J_CPU1_SA_DQS_DP<7>")
	)
	(segment
		(start 185.95594 -220.861382)
		(end 186.786266 -220.861382)
		(width 0.16002)
		(layer "In4.Cu")
		(net "M_J_CPU1_SA_DQS_DP<7>")
	)
	(segment
		(start 185.8391 -220.978222)
		(end 185.95594 -220.861382)
		(width 0.16002)
		(layer "In4.Cu")
		(net "M_J_CPU1_SA_DQS_DP<7>")
	)
	(segment
		(start 162.18789 -220.812106)
		(end 162.383724 -221.00794)
		(width 0.16002)
		(layer "In4.Cu")
		(net "M_J_CPU1_SA_DQS_DP<7>")
	)
	(segment
		(start 185.35904 -220.978222)
		(end 185.8391 -220.978222)
		(width 0.16002)
		(layer "In4.Cu")
		(net "M_J_CPU1_SA_DQS_DP<7>")
	)
	(segment
		(start 164.324792 -221.00794)
		(end 164.324792 -221.478602)
		(width 0.16002)
		(layer "In4.Cu")
		(net "M_J_CPU1_SA_DQS_DP<7>")
	)
	(segment
		(start 141.094968 -237.674404)
		(end 141.10335 -237.67923)
		(width 0.09525)
		(layer "In4.Cu")
		(net "M_J_CPU1_SA_DQS_DP<7>")
	)
	(segment
		(start 140.154914 -237.674404)
		(end 140.163296 -237.67923)
		(width 0.09525)
		(layer "In4.Cu")
		(net "M_J_CPU1_SA_DQS_DP<7>")
	)
	(segment
		(start 165.281102 -221.851474)
		(end 165.672262 -221.460314)
		(width 0.16002)
		(layer "In4.Cu")
		(net "M_J_CPU1_SA_DQS_DP<7>")
	)
	(segment
		(start 149.370034 -235.764324)
		(end 156.355034 -228.779324)
		(width 0.16002)
		(layer "In4.Cu")
		(net "M_J_CPU1_SA_DQS_DP<7>")
	)
	(segment
		(start 172.55744 -221.860364)
		(end 172.89653 -221.521274)
		(width 0.16002)
		(layer "In4.Cu")
		(net "M_J_CPU1_SA_DQS_DP<7>")
	)
	(segment
		(start 147.51812 -235.705396)
		(end 147.836636 -235.705396)
		(width 0.09525)
		(layer "In4.Cu")
		(net "M_J_CPU1_SA_DQS_DP<7>")
	)
	(segment
		(start 131.51485 -238.00435)
		(end 131.360926 -237.73892)
		(width 0.09525)
		(layer "In4.Cu")
		(net "M_J_CPU1_SA_DQS_DP<7>")
	)
	(segment
		(start 144.485868 -237.67923)
		(end 144.49425 -237.674404)
		(width 0.09525)
		(layer "In4.Cu")
		(net "M_J_CPU1_SA_DQS_DP<7>")
	)
	(segment
		(start 169.86631 -220.690694)
		(end 171.03598 -221.860364)
		(width 0.16002)
		(layer "In4.Cu")
		(net "M_J_CPU1_SA_DQS_DP<7>")
	)
	(segment
		(start 184.106312 -221.01048)
		(end 184.25541 -220.861382)
		(width 0.16002)
		(layer "In4.Cu")
		(net "M_J_CPU1_SA_DQS_DP<7>")
	)
	(segment
		(start 143.914876 -237.674404)
		(end 143.923258 -237.67923)
		(width 0.09525)
		(layer "In4.Cu")
		(net "M_J_CPU1_SA_DQS_DP<7>")
	)
	(segment
		(start 186.786266 -220.861382)
		(end 187.060078 -221.135194)
		(width 0.16002)
		(layer "In4.Cu")
		(net "M_J_CPU1_SA_DQS_DP<7>")
	)
	(segment
		(start 175.11141 -220.672914)
		(end 175.448976 -221.01048)
		(width 0.16002)
		(layer "In4.Cu")
		(net "M_J_CPU1_SA_DQS_DP<7>")
	)
	(segment
		(start 131.360926 -237.73892)
		(end 131.384294 -237.652052)
		(width 0.09525)
		(layer "In4.Cu")
		(net "M_J_CPU1_SA_DQS_DP<7>")
	)
	(segment
		(start 163.656518 -221.00794)
		(end 163.852352 -220.812106)
		(width 0.16002)
		(layer "In4.Cu")
		(net "M_J_CPU1_SA_DQS_DP<7>")
	)
	(segment
		(start 163.283646 -221.851474)
		(end 163.656518 -221.478602)
		(width 0.16002)
		(layer "In4.Cu")
		(net "M_J_CPU1_SA_DQS_DP<7>")
	)
	(segment
		(start 175.448976 -221.01048)
		(end 178.02606 -221.01048)
		(width 0.16002)
		(layer "In4.Cu")
		(net "M_J_CPU1_SA_DQS_DP<7>")
	)
	(segment
		(start 146.94535 -236.278166)
		(end 147.51812 -235.705396)
		(width 0.09525)
		(layer "In4.Cu")
		(net "M_J_CPU1_SA_DQS_DP<7>")
	)
	(segment
		(start 163.656518 -221.478602)
		(end 163.656518 -221.00794)
		(width 0.16002)
		(layer "In4.Cu")
		(net "M_J_CPU1_SA_DQS_DP<7>")
	)
	(segment
		(start 145.41119 -237.687866)
		(end 145.425922 -237.67923)
		(width 0.09525)
		(layer "In4.Cu")
		(net "M_J_CPU1_SA_DQS_DP<7>")
	)
	(segment
		(start 133.206236 -237.67923)
		(end 133.214618 -237.674404)
		(width 0.09525)
		(layer "In4.Cu")
		(net "M_J_CPU1_SA_DQS_DP<7>")
	)
	(segment
		(start 172.89653 -221.521274)
		(end 173.56455 -221.521274)
		(width 0.16002)
		(layer "In4.Cu")
		(net "M_J_CPU1_SA_DQS_DP<7>")
	)
	(segment
		(start 183.018176 -221.01048)
		(end 184.106312 -221.01048)
		(width 0.16002)
		(layer "In4.Cu")
		(net "M_J_CPU1_SA_DQS_DP<7>")
	)
	(segment
		(start 147.836636 -235.705396)
		(end 147.895564 -235.764324)
		(width 0.09525)
		(layer "In4.Cu")
		(net "M_J_CPU1_SA_DQS_DP<7>")
	)
	(segment
		(start 136.966198 -237.67923)
		(end 136.97458 -237.674404)
		(width 0.09525)
		(layer "In4.Cu")
		(net "M_J_CPU1_SA_DQS_DP<7>")
	)
	(segment
		(start 178.875944 -221.860364)
		(end 180.25364 -221.860364)
		(width 0.16002)
		(layer "In4.Cu")
		(net "M_J_CPU1_SA_DQS_DP<7>")
	)
	(segment
		(start 141.666214 -237.67923)
		(end 141.674596 -237.674404)
		(width 0.09525)
		(layer "In4.Cu")
		(net "M_J_CPU1_SA_DQS_DP<7>")
	)
	(arc
		(start 144.49425 -237.674404)
		(mid 144.679282 -237.62849)
		(end 144.863058 -237.67923)
		(width 0.09525)
		(layer "In4.Cu")
		(net "M_J_CPU1_SA_DQS_DP<7>")
	)
	(arc
		(start 142.606268 -237.67923)
		(mid 142.794736 -237.628553)
		(end 142.983204 -237.67923)
		(width 0.09525)
		(layer "In4.Cu")
		(net "M_J_CPU1_SA_DQS_DP<7>")
	)
	(arc
		(start 142.983204 -237.67923)
		(mid 143.264636 -237.754985)
		(end 143.546068 -237.67923)
		(width 0.09525)
		(layer "In4.Cu")
		(net "M_J_CPU1_SA_DQS_DP<7>")
	)
	(arc
		(start 131.703318 -237.67923)
		(mid 131.98475 -237.754985)
		(end 132.266182 -237.67923)
		(width 0.09525)
		(layer "In4.Cu")
		(net "M_J_CPU1_SA_DQS_DP<7>")
	)
	(arc
		(start 137.343388 -237.67923)
		(mid 137.62482 -237.754985)
		(end 137.906252 -237.67923)
		(width 0.09525)
		(layer "In4.Cu")
		(net "M_J_CPU1_SA_DQS_DP<7>")
	)
	(arc
		(start 138.846306 -237.67923)
		(mid 139.034774 -237.628553)
		(end 139.223242 -237.67923)
		(width 0.09525)
		(layer "In4.Cu")
		(net "M_J_CPU1_SA_DQS_DP<7>")
	)
	(arc
		(start 141.10335 -237.67923)
		(mid 141.384782 -237.754985)
		(end 141.666214 -237.67923)
		(width 0.09525)
		(layer "In4.Cu")
		(net "M_J_CPU1_SA_DQS_DP<7>")
	)
	(arc
		(start 134.523226 -237.67923)
		(mid 134.804658 -237.754985)
		(end 135.08609 -237.67923)
		(width 0.09525)
		(layer "In4.Cu")
		(net "M_J_CPU1_SA_DQS_DP<7>")
	)
	(arc
		(start 139.223242 -237.67923)
		(mid 139.504674 -237.754985)
		(end 139.786106 -237.67923)
		(width 0.09525)
		(layer "In4.Cu")
		(net "M_J_CPU1_SA_DQS_DP<7>")
	)
	(arc
		(start 145.425922 -237.67923)
		(mid 145.486337 -237.63865)
		(end 145.540984 -237.590584)
		(width 0.09525)
		(layer "In4.Cu")
		(net "M_J_CPU1_SA_DQS_DP<7>")
	)
	(arc
		(start 135.46328 -237.67923)
		(mid 135.744712 -237.754985)
		(end 136.026144 -237.67923)
		(width 0.09525)
		(layer "In4.Cu")
		(net "M_J_CPU1_SA_DQS_DP<7>")
	)
	(arc
		(start 142.043404 -237.67923)
		(mid 142.324836 -237.754985)
		(end 142.606268 -237.67923)
		(width 0.09525)
		(layer "In4.Cu")
		(net "M_J_CPU1_SA_DQS_DP<7>")
	)
	(arc
		(start 136.403334 -237.67923)
		(mid 136.684766 -237.754985)
		(end 136.966198 -237.67923)
		(width 0.09525)
		(layer "In4.Cu")
		(net "M_J_CPU1_SA_DQS_DP<7>")
	)
	(arc
		(start 143.933672 -237.685326)
		(mid 144.21058 -237.755003)
		(end 144.485868 -237.67923)
		(width 0.09525)
		(layer "In4.Cu")
		(net "M_J_CPU1_SA_DQS_DP<7>")
	)
	(arc
		(start 143.546068 -237.67923)
		(mid 143.729843 -237.628458)
		(end 143.914876 -237.674404)
		(width 0.09525)
		(layer "In4.Cu")
		(net "M_J_CPU1_SA_DQS_DP<7>")
	)
	(arc
		(start 144.863058 -237.67923)
		(mid 145.135986 -237.755044)
		(end 145.41119 -237.687866)
		(width 0.09525)
		(layer "In4.Cu")
		(net "M_J_CPU1_SA_DQS_DP<7>")
	)
	(arc
		(start 132.274564 -237.674404)
		(mid 132.459596 -237.62849)
		(end 132.643372 -237.67923)
		(width 0.09525)
		(layer "In4.Cu")
		(net "M_J_CPU1_SA_DQS_DP<7>")
	)
	(arc
		(start 137.914634 -237.674404)
		(mid 138.099666 -237.62849)
		(end 138.283442 -237.67923)
		(width 0.09525)
		(layer "In4.Cu")
		(net "M_J_CPU1_SA_DQS_DP<7>")
	)
	(arc
		(start 140.72616 -237.67923)
		(mid 140.909935 -237.628458)
		(end 141.094968 -237.674404)
		(width 0.09525)
		(layer "In4.Cu")
		(net "M_J_CPU1_SA_DQS_DP<7>")
	)
	(arc
		(start 140.163296 -237.67923)
		(mid 140.444728 -237.754985)
		(end 140.72616 -237.67923)
		(width 0.09525)
		(layer "In4.Cu")
		(net "M_J_CPU1_SA_DQS_DP<7>")
	)
	(arc
		(start 132.643372 -237.67923)
		(mid 132.924804 -237.754985)
		(end 133.206236 -237.67923)
		(width 0.09525)
		(layer "In4.Cu")
		(net "M_J_CPU1_SA_DQS_DP<7>")
	)
	(arc
		(start 133.583426 -237.67923)
		(mid 133.864858 -237.754985)
		(end 134.14629 -237.67923)
		(width 0.09525)
		(layer "In4.Cu")
		(net "M_J_CPU1_SA_DQS_DP<7>")
	)
	(arc
		(start 134.14629 -237.67923)
		(mid 134.334758 -237.628553)
		(end 134.523226 -237.67923)
		(width 0.09525)
		(layer "In4.Cu")
		(net "M_J_CPU1_SA_DQS_DP<7>")
	)
	(arc
		(start 136.97458 -237.674404)
		(mid 137.159612 -237.62849)
		(end 137.343388 -237.67923)
		(width 0.09525)
		(layer "In4.Cu")
		(net "M_J_CPU1_SA_DQS_DP<7>")
	)
	(arc
		(start 139.786106 -237.67923)
		(mid 139.969881 -237.628458)
		(end 140.154914 -237.674404)
		(width 0.09525)
		(layer "In4.Cu")
		(net "M_J_CPU1_SA_DQS_DP<7>")
	)
	(arc
		(start 138.283442 -237.67923)
		(mid 138.564874 -237.754985)
		(end 138.846306 -237.67923)
		(width 0.09525)
		(layer "In4.Cu")
		(net "M_J_CPU1_SA_DQS_DP<7>")
	)
	(arc
		(start 135.08609 -237.67923)
		(mid 135.269865 -237.628458)
		(end 135.454898 -237.674404)
		(width 0.09525)
		(layer "In4.Cu")
		(net "M_J_CPU1_SA_DQS_DP<7>")
	)
	(arc
		(start 133.214618 -237.674404)
		(mid 133.39965 -237.62849)
		(end 133.583426 -237.67923)
		(width 0.09525)
		(layer "In4.Cu")
		(net "M_J_CPU1_SA_DQS_DP<7>")
	)
	(arc
		(start 141.674596 -237.674404)
		(mid 141.859628 -237.62849)
		(end 142.043404 -237.67923)
		(width 0.09525)
		(layer "In4.Cu")
		(net "M_J_CPU1_SA_DQS_DP<7>")
	)
	(arc
		(start 131.384294 -237.652052)
		(mid 131.542044 -237.629533)
		(end 131.694936 -237.674404)
		(width 0.09525)
		(layer "In4.Cu")
		(net "M_J_CPU1_SA_DQS_DP<7>")
	)
	(arc
		(start 136.026144 -237.67923)
		(mid 136.209919 -237.628458)
		(end 136.394952 -237.674404)
		(width 0.09525)
		(layer "In4.Cu")
		(net "M_J_CPU1_SA_DQS_DP<7>")
	)
	(segment
		(start 131.047998 -233.410252)
		(end 131.51485 -233.144314)
		(width 0.12954)
		(layer "F.Cu")
		(net "M_J_CPU1_SA_DQS_DP<6>")
	)
	(segment
		(start 161.491676 -211.63534)
		(end 161.68751 -211.439506)
		(width 0.16002)
		(layer "In4.Cu")
		(net "M_J_CPU1_SA_DQS_DP<6>")
	)
	(segment
		(start 185.49112 -211.628228)
		(end 185.97118 -211.628228)
		(width 0.16002)
		(layer "In4.Cu")
		(net "M_J_CPU1_SA_DQS_DP<6>")
	)
	(segment
		(start 162.15995 -211.63534)
		(end 162.15995 -212.351874)
		(width 0.16002)
		(layer "In4.Cu")
		(net "M_J_CPU1_SA_DQS_DP<6>")
	)
	(segment
		(start 150.817834 -222.27667)
		(end 160.369758 -212.724746)
		(width 0.16002)
		(layer "In4.Cu")
		(net "M_J_CPU1_SA_DQS_DP<6>")
	)
	(segment
		(start 140.154914 -232.814368)
		(end 140.163296 -232.819194)
		(width 0.09525)
		(layer "In4.Cu")
		(net "M_J_CPU1_SA_DQS_DP<6>")
	)
	(segment
		(start 137.906252 -232.819194)
		(end 137.914634 -232.814368)
		(width 0.09525)
		(layer "In4.Cu")
		(net "M_J_CPU1_SA_DQS_DP<6>")
	)
	(segment
		(start 180.61559 -212.14842)
		(end 181.188106 -212.14842)
		(width 0.16002)
		(layer "In4.Cu")
		(net "M_J_CPU1_SA_DQS_DP<6>")
	)
	(segment
		(start 175.11141 -211.32292)
		(end 175.448976 -211.660486)
		(width 0.16002)
		(layer "In4.Cu")
		(net "M_J_CPU1_SA_DQS_DP<6>")
	)
	(segment
		(start 146.828764 -229.490016)
		(end 147.164806 -229.490016)
		(width 0.09525)
		(layer "In4.Cu")
		(net "M_J_CPU1_SA_DQS_DP<6>")
	)
	(segment
		(start 172.89653 -212.17128)
		(end 173.56455 -212.17128)
		(width 0.16002)
		(layer "In4.Cu")
		(net "M_J_CPU1_SA_DQS_DP<6>")
	)
	(segment
		(start 131.51485 -233.144314)
		(end 131.360926 -232.878884)
		(width 0.09525)
		(layer "In4.Cu")
		(net "M_J_CPU1_SA_DQS_DP<6>")
	)
	(segment
		(start 131.360926 -232.878884)
		(end 131.384294 -232.792016)
		(width 0.09525)
		(layer "In4.Cu")
		(net "M_J_CPU1_SA_DQS_DP<6>")
	)
	(segment
		(start 161.491676 -212.351874)
		(end 161.491676 -211.63534)
		(width 0.16002)
		(layer "In4.Cu")
		(net "M_J_CPU1_SA_DQS_DP<6>")
	)
	(segment
		(start 136.394952 -232.814368)
		(end 136.403334 -232.819194)
		(width 0.09525)
		(layer "In4.Cu")
		(net "M_J_CPU1_SA_DQS_DP<6>")
	)
	(segment
		(start 141.094968 -232.814368)
		(end 141.10335 -232.819194)
		(width 0.09525)
		(layer "In4.Cu")
		(net "M_J_CPU1_SA_DQS_DP<6>")
	)
	(segment
		(start 144.183608 -232.767886)
		(end 146.286474 -230.66502)
		(width 0.09525)
		(layer "In4.Cu")
		(net "M_J_CPU1_SA_DQS_DP<6>")
	)
	(segment
		(start 182.021226 -211.3153)
		(end 182.67299 -211.3153)
		(width 0.16002)
		(layer "In4.Cu")
		(net "M_J_CPU1_SA_DQS_DP<6>")
	)
	(segment
		(start 184.106312 -211.660486)
		(end 184.25541 -211.511388)
		(width 0.16002)
		(layer "In4.Cu")
		(net "M_J_CPU1_SA_DQS_DP<6>")
	)
	(segment
		(start 164.47389 -212.724746)
		(end 165.124384 -212.724746)
		(width 0.16002)
		(layer "In4.Cu")
		(net "M_J_CPU1_SA_DQS_DP<6>")
	)
	(segment
		(start 182.67299 -211.3153)
		(end 183.018176 -211.660486)
		(width 0.16002)
		(layer "In4.Cu")
		(net "M_J_CPU1_SA_DQS_DP<6>")
	)
	(segment
		(start 135.454898 -232.814368)
		(end 135.46328 -232.819194)
		(width 0.09525)
		(layer "In4.Cu")
		(net "M_J_CPU1_SA_DQS_DP<6>")
	)
	(segment
		(start 143.73479 -232.767886)
		(end 144.183608 -232.767886)
		(width 0.09525)
		(layer "In4.Cu")
		(net "M_J_CPU1_SA_DQS_DP<6>")
	)
	(segment
		(start 183.018176 -211.660486)
		(end 184.106312 -211.660486)
		(width 0.16002)
		(layer "In4.Cu")
		(net "M_J_CPU1_SA_DQS_DP<6>")
	)
	(segment
		(start 180.25364 -212.51037)
		(end 180.61559 -212.14842)
		(width 0.16002)
		(layer "In4.Cu")
		(net "M_J_CPU1_SA_DQS_DP<6>")
	)
	(segment
		(start 165.73881 -212.11032)
		(end 166.16553 -212.11032)
		(width 0.16002)
		(layer "In4.Cu")
		(net "M_J_CPU1_SA_DQS_DP<6>")
	)
	(segment
		(start 163.905184 -211.439506)
		(end 164.101018 -211.63534)
		(width 0.16002)
		(layer "In4.Cu")
		(net "M_J_CPU1_SA_DQS_DP<6>")
	)
	(segment
		(start 162.15995 -212.351874)
		(end 162.532822 -212.724746)
		(width 0.16002)
		(layer "In4.Cu")
		(net "M_J_CPU1_SA_DQS_DP<6>")
	)
	(segment
		(start 168.28008 -211.3407)
		(end 168.39692 -211.45754)
		(width 0.16002)
		(layer "In4.Cu")
		(net "M_J_CPU1_SA_DQS_DP<6>")
	)
	(segment
		(start 141.666214 -232.819194)
		(end 141.674596 -232.814368)
		(width 0.09525)
		(layer "In4.Cu")
		(net "M_J_CPU1_SA_DQS_DP<6>")
	)
	(segment
		(start 147.164806 -229.490016)
		(end 147.801584 -228.853238)
		(width 0.09525)
		(layer "In4.Cu")
		(net "M_J_CPU1_SA_DQS_DP<6>")
	)
	(segment
		(start 171.03598 -212.51037)
		(end 172.55744 -212.51037)
		(width 0.16002)
		(layer "In4.Cu")
		(net "M_J_CPU1_SA_DQS_DP<6>")
	)
	(segment
		(start 168.39692 -211.45754)
		(end 168.87698 -211.45754)
		(width 0.16002)
		(layer "In4.Cu")
		(net "M_J_CPU1_SA_DQS_DP<6>")
	)
	(segment
		(start 163.059872 -212.724746)
		(end 163.432744 -212.351874)
		(width 0.16002)
		(layer "In4.Cu")
		(net "M_J_CPU1_SA_DQS_DP<6>")
	)
	(segment
		(start 161.118804 -212.724746)
		(end 161.491676 -212.351874)
		(width 0.16002)
		(layer "In4.Cu")
		(net "M_J_CPU1_SA_DQS_DP<6>")
	)
	(segment
		(start 175.448976 -211.660486)
		(end 178.02606 -211.660486)
		(width 0.16002)
		(layer "In4.Cu")
		(net "M_J_CPU1_SA_DQS_DP<6>")
	)
	(segment
		(start 184.25541 -211.511388)
		(end 185.37428 -211.511388)
		(width 0.16002)
		(layer "In4.Cu")
		(net "M_J_CPU1_SA_DQS_DP<6>")
	)
	(segment
		(start 132.266182 -232.819194)
		(end 132.274564 -232.814368)
		(width 0.09525)
		(layer "In4.Cu")
		(net "M_J_CPU1_SA_DQS_DP<6>")
	)
	(segment
		(start 178.875944 -212.51037)
		(end 180.25364 -212.51037)
		(width 0.16002)
		(layer "In4.Cu")
		(net "M_J_CPU1_SA_DQS_DP<6>")
	)
	(segment
		(start 185.37428 -211.511388)
		(end 185.49112 -211.628228)
		(width 0.16002)
		(layer "In4.Cu")
		(net "M_J_CPU1_SA_DQS_DP<6>")
	)
	(segment
		(start 181.188106 -212.14842)
		(end 182.021226 -211.3153)
		(width 0.16002)
		(layer "In4.Cu")
		(net "M_J_CPU1_SA_DQS_DP<6>")
	)
	(segment
		(start 147.801584 -228.853238)
		(end 147.885404 -228.853238)
		(width 0.09525)
		(layer "In4.Cu")
		(net "M_J_CPU1_SA_DQS_DP<6>")
	)
	(segment
		(start 168.99382 -211.3407)
		(end 169.86631 -211.3407)
		(width 0.16002)
		(layer "In4.Cu")
		(net "M_J_CPU1_SA_DQS_DP<6>")
	)
	(segment
		(start 147.885404 -228.853238)
		(end 147.902168 -228.836474)
		(width 0.09525)
		(layer "In4.Cu")
		(net "M_J_CPU1_SA_DQS_DP<6>")
	)
	(segment
		(start 163.628578 -211.439506)
		(end 163.905184 -211.439506)
		(width 0.16002)
		(layer "In4.Cu")
		(net "M_J_CPU1_SA_DQS_DP<6>")
	)
	(segment
		(start 166.93515 -211.3407)
		(end 168.28008 -211.3407)
		(width 0.16002)
		(layer "In4.Cu")
		(net "M_J_CPU1_SA_DQS_DP<6>")
	)
	(segment
		(start 150.817834 -225.920808)
		(end 150.817834 -222.27667)
		(width 0.16002)
		(layer "In4.Cu")
		(net "M_J_CPU1_SA_DQS_DP<6>")
	)
	(segment
		(start 185.97118 -211.628228)
		(end 186.08802 -211.511388)
		(width 0.16002)
		(layer "In4.Cu")
		(net "M_J_CPU1_SA_DQS_DP<6>")
	)
	(segment
		(start 178.02606 -211.660486)
		(end 178.875944 -212.51037)
		(width 0.16002)
		(layer "In4.Cu")
		(net "M_J_CPU1_SA_DQS_DP<6>")
	)
	(segment
		(start 161.68751 -211.439506)
		(end 161.964116 -211.439506)
		(width 0.16002)
		(layer "In4.Cu")
		(net "M_J_CPU1_SA_DQS_DP<6>")
	)
	(segment
		(start 160.369758 -212.724746)
		(end 161.118804 -212.724746)
		(width 0.16002)
		(layer "In4.Cu")
		(net "M_J_CPU1_SA_DQS_DP<6>")
	)
	(segment
		(start 173.56455 -212.17128)
		(end 174.41291 -211.32292)
		(width 0.16002)
		(layer "In4.Cu")
		(net "M_J_CPU1_SA_DQS_DP<6>")
	)
	(segment
		(start 174.41291 -211.32292)
		(end 175.11141 -211.32292)
		(width 0.16002)
		(layer "In4.Cu")
		(net "M_J_CPU1_SA_DQS_DP<6>")
	)
	(segment
		(start 186.08802 -211.511388)
		(end 186.786266 -211.511388)
		(width 0.16002)
		(layer "In4.Cu")
		(net "M_J_CPU1_SA_DQS_DP<6>")
	)
	(segment
		(start 172.55744 -212.51037)
		(end 172.89653 -212.17128)
		(width 0.16002)
		(layer "In4.Cu")
		(net "M_J_CPU1_SA_DQS_DP<6>")
	)
	(segment
		(start 166.16553 -212.11032)
		(end 166.93515 -211.3407)
		(width 0.16002)
		(layer "In4.Cu")
		(net "M_J_CPU1_SA_DQS_DP<6>")
	)
	(segment
		(start 131.694936 -232.814368)
		(end 131.703318 -232.819194)
		(width 0.09525)
		(layer "In4.Cu")
		(net "M_J_CPU1_SA_DQS_DP<6>")
	)
	(segment
		(start 168.87698 -211.45754)
		(end 168.99382 -211.3407)
		(width 0.16002)
		(layer "In4.Cu")
		(net "M_J_CPU1_SA_DQS_DP<6>")
	)
	(segment
		(start 146.286474 -230.66502)
		(end 146.286474 -230.032306)
		(width 0.09525)
		(layer "In4.Cu")
		(net "M_J_CPU1_SA_DQS_DP<6>")
	)
	(segment
		(start 164.101018 -211.63534)
		(end 164.101018 -212.351874)
		(width 0.16002)
		(layer "In4.Cu")
		(net "M_J_CPU1_SA_DQS_DP<6>")
	)
	(segment
		(start 164.101018 -212.351874)
		(end 164.47389 -212.724746)
		(width 0.16002)
		(layer "In4.Cu")
		(net "M_J_CPU1_SA_DQS_DP<6>")
	)
	(segment
		(start 136.966198 -232.819194)
		(end 136.97458 -232.814368)
		(width 0.09525)
		(layer "In4.Cu")
		(net "M_J_CPU1_SA_DQS_DP<6>")
	)
	(segment
		(start 161.964116 -211.439506)
		(end 162.15995 -211.63534)
		(width 0.16002)
		(layer "In4.Cu")
		(net "M_J_CPU1_SA_DQS_DP<6>")
	)
	(segment
		(start 169.86631 -211.3407)
		(end 171.03598 -212.51037)
		(width 0.16002)
		(layer "In4.Cu")
		(net "M_J_CPU1_SA_DQS_DP<6>")
	)
	(segment
		(start 146.286474 -230.032306)
		(end 146.828764 -229.490016)
		(width 0.09525)
		(layer "In4.Cu")
		(net "M_J_CPU1_SA_DQS_DP<6>")
	)
	(segment
		(start 165.124384 -212.724746)
		(end 165.73881 -212.11032)
		(width 0.16002)
		(layer "In4.Cu")
		(net "M_J_CPU1_SA_DQS_DP<6>")
	)
	(segment
		(start 147.902168 -228.836474)
		(end 150.817834 -225.920808)
		(width 0.16002)
		(layer "In4.Cu")
		(net "M_J_CPU1_SA_DQS_DP<6>")
	)
	(segment
		(start 163.432744 -212.351874)
		(end 163.432744 -211.63534)
		(width 0.16002)
		(layer "In4.Cu")
		(net "M_J_CPU1_SA_DQS_DP<6>")
	)
	(segment
		(start 163.432744 -211.63534)
		(end 163.628578 -211.439506)
		(width 0.16002)
		(layer "In4.Cu")
		(net "M_J_CPU1_SA_DQS_DP<6>")
	)
	(segment
		(start 186.786266 -211.511388)
		(end 187.060078 -211.7852)
		(width 0.16002)
		(layer "In4.Cu")
		(net "M_J_CPU1_SA_DQS_DP<6>")
	)
	(segment
		(start 133.206236 -232.819194)
		(end 133.214618 -232.814368)
		(width 0.09525)
		(layer "In4.Cu")
		(net "M_J_CPU1_SA_DQS_DP<6>")
	)
	(segment
		(start 162.532822 -212.724746)
		(end 163.059872 -212.724746)
		(width 0.16002)
		(layer "In4.Cu")
		(net "M_J_CPU1_SA_DQS_DP<6>")
	)
	(arc
		(start 139.223242 -232.819194)
		(mid 139.504674 -232.894949)
		(end 139.786106 -232.819194)
		(width 0.09525)
		(layer "In4.Cu")
		(net "M_J_CPU1_SA_DQS_DP<6>")
	)
	(arc
		(start 138.283442 -232.819194)
		(mid 138.564874 -232.894949)
		(end 138.846306 -232.819194)
		(width 0.09525)
		(layer "In4.Cu")
		(net "M_J_CPU1_SA_DQS_DP<6>")
	)
	(arc
		(start 133.214618 -232.814368)
		(mid 133.39965 -232.768454)
		(end 133.583426 -232.819194)
		(width 0.09525)
		(layer "In4.Cu")
		(net "M_J_CPU1_SA_DQS_DP<6>")
	)
	(arc
		(start 140.72616 -232.819194)
		(mid 140.909935 -232.768422)
		(end 141.094968 -232.814368)
		(width 0.09525)
		(layer "In4.Cu")
		(net "M_J_CPU1_SA_DQS_DP<6>")
	)
	(arc
		(start 139.786106 -232.819194)
		(mid 139.969881 -232.768422)
		(end 140.154914 -232.814368)
		(width 0.09525)
		(layer "In4.Cu")
		(net "M_J_CPU1_SA_DQS_DP<6>")
	)
	(arc
		(start 141.674596 -232.814368)
		(mid 141.859628 -232.768454)
		(end 142.043404 -232.819194)
		(width 0.09525)
		(layer "In4.Cu")
		(net "M_J_CPU1_SA_DQS_DP<6>")
	)
	(arc
		(start 143.546068 -232.819194)
		(mid 143.637034 -232.781041)
		(end 143.73479 -232.767886)
		(width 0.09525)
		(layer "In4.Cu")
		(net "M_J_CPU1_SA_DQS_DP<6>")
	)
	(arc
		(start 136.026144 -232.819194)
		(mid 136.209919 -232.768422)
		(end 136.394952 -232.814368)
		(width 0.09525)
		(layer "In4.Cu")
		(net "M_J_CPU1_SA_DQS_DP<6>")
	)
	(arc
		(start 134.14629 -232.819194)
		(mid 134.334758 -232.768517)
		(end 134.523226 -232.819194)
		(width 0.09525)
		(layer "In4.Cu")
		(net "M_J_CPU1_SA_DQS_DP<6>")
	)
	(arc
		(start 142.606268 -232.819194)
		(mid 142.794736 -232.768517)
		(end 142.983204 -232.819194)
		(width 0.09525)
		(layer "In4.Cu")
		(net "M_J_CPU1_SA_DQS_DP<6>")
	)
	(arc
		(start 132.643372 -232.819194)
		(mid 132.924804 -232.894949)
		(end 133.206236 -232.819194)
		(width 0.09525)
		(layer "In4.Cu")
		(net "M_J_CPU1_SA_DQS_DP<6>")
	)
	(arc
		(start 141.10335 -232.819194)
		(mid 141.384782 -232.894949)
		(end 141.666214 -232.819194)
		(width 0.09525)
		(layer "In4.Cu")
		(net "M_J_CPU1_SA_DQS_DP<6>")
	)
	(arc
		(start 140.163296 -232.819194)
		(mid 140.444728 -232.894949)
		(end 140.72616 -232.819194)
		(width 0.09525)
		(layer "In4.Cu")
		(net "M_J_CPU1_SA_DQS_DP<6>")
	)
	(arc
		(start 142.043404 -232.819194)
		(mid 142.324836 -232.894949)
		(end 142.606268 -232.819194)
		(width 0.09525)
		(layer "In4.Cu")
		(net "M_J_CPU1_SA_DQS_DP<6>")
	)
	(arc
		(start 131.384294 -232.792016)
		(mid 131.542044 -232.769497)
		(end 131.694936 -232.814368)
		(width 0.09525)
		(layer "In4.Cu")
		(net "M_J_CPU1_SA_DQS_DP<6>")
	)
	(arc
		(start 134.523226 -232.819194)
		(mid 134.804658 -232.894949)
		(end 135.08609 -232.819194)
		(width 0.09525)
		(layer "In4.Cu")
		(net "M_J_CPU1_SA_DQS_DP<6>")
	)
	(arc
		(start 137.343388 -232.819194)
		(mid 137.62482 -232.894949)
		(end 137.906252 -232.819194)
		(width 0.09525)
		(layer "In4.Cu")
		(net "M_J_CPU1_SA_DQS_DP<6>")
	)
	(arc
		(start 137.914634 -232.814368)
		(mid 138.099666 -232.768454)
		(end 138.283442 -232.819194)
		(width 0.09525)
		(layer "In4.Cu")
		(net "M_J_CPU1_SA_DQS_DP<6>")
	)
	(arc
		(start 138.846306 -232.819194)
		(mid 139.034774 -232.768517)
		(end 139.223242 -232.819194)
		(width 0.09525)
		(layer "In4.Cu")
		(net "M_J_CPU1_SA_DQS_DP<6>")
	)
	(arc
		(start 142.983204 -232.819194)
		(mid 143.264636 -232.894949)
		(end 143.546068 -232.819194)
		(width 0.09525)
		(layer "In4.Cu")
		(net "M_J_CPU1_SA_DQS_DP<6>")
	)
	(arc
		(start 131.703318 -232.819194)
		(mid 131.98475 -232.894949)
		(end 132.266182 -232.819194)
		(width 0.09525)
		(layer "In4.Cu")
		(net "M_J_CPU1_SA_DQS_DP<6>")
	)
	(arc
		(start 135.08609 -232.819194)
		(mid 135.269865 -232.768422)
		(end 135.454898 -232.814368)
		(width 0.09525)
		(layer "In4.Cu")
		(net "M_J_CPU1_SA_DQS_DP<6>")
	)
	(arc
		(start 136.97458 -232.814368)
		(mid 137.159612 -232.768454)
		(end 137.343388 -232.819194)
		(width 0.09525)
		(layer "In4.Cu")
		(net "M_J_CPU1_SA_DQS_DP<6>")
	)
	(arc
		(start 133.583426 -232.819194)
		(mid 133.864858 -232.894949)
		(end 134.14629 -232.819194)
		(width 0.09525)
		(layer "In4.Cu")
		(net "M_J_CPU1_SA_DQS_DP<6>")
	)
	(arc
		(start 135.46328 -232.819194)
		(mid 135.744712 -232.894949)
		(end 136.026144 -232.819194)
		(width 0.09525)
		(layer "In4.Cu")
		(net "M_J_CPU1_SA_DQS_DP<6>")
	)
	(arc
		(start 132.274564 -232.814368)
		(mid 132.459596 -232.768454)
		(end 132.643372 -232.819194)
		(width 0.09525)
		(layer "In4.Cu")
		(net "M_J_CPU1_SA_DQS_DP<6>")
	)
	(arc
		(start 136.403334 -232.819194)
		(mid 136.684766 -232.894949)
		(end 136.966198 -232.819194)
		(width 0.09525)
		(layer "In4.Cu")
		(net "M_J_CPU1_SA_DQS_DP<6>")
	)
	(segment
		(start 131.047998 -228.55047)
		(end 131.51485 -228.284532)
		(width 0.12954)
		(layer "F.Cu")
		(net "M_J_CPU1_SA_DQS_DP<5>")
	)
	(segment
		(start 144.486122 -223.099376)
		(end 144.518126 -223.080834)
		(width 0.09525)
		(layer "In4.Cu")
		(net "M_J_CPU1_SA_DQS_DP<5>")
	)
	(segment
		(start 141.094968 -227.954586)
		(end 141.10335 -227.959412)
		(width 0.09525)
		(layer "In4.Cu")
		(net "M_J_CPU1_SA_DQS_DP<5>")
	)
	(segment
		(start 131.694936 -227.954586)
		(end 131.703318 -227.959412)
		(width 0.09525)
		(layer "In4.Cu")
		(net "M_J_CPU1_SA_DQS_DP<5>")
	)
	(segment
		(start 161.268664 -203.151486)
		(end 162.327844 -203.151486)
		(width 0.16002)
		(layer "In4.Cu")
		(net "M_J_CPU1_SA_DQS_DP<5>")
	)
	(segment
		(start 155.712668 -207.939894)
		(end 156.480256 -207.939894)
		(width 0.16002)
		(layer "In4.Cu")
		(net "M_J_CPU1_SA_DQS_DP<5>")
	)
	(segment
		(start 167.47871 -201.990706)
		(end 167.59555 -202.107546)
		(width 0.16002)
		(layer "In4.Cu")
		(net "M_J_CPU1_SA_DQS_DP<5>")
	)
	(segment
		(start 156.944568 -206.75473)
		(end 157.18282 -206.516478)
		(width 0.16002)
		(layer "In4.Cu")
		(net "M_J_CPU1_SA_DQS_DP<5>")
	)
	(segment
		(start 171.03598 -203.160376)
		(end 172.55744 -203.160376)
		(width 0.16002)
		(layer "In4.Cu")
		(net "M_J_CPU1_SA_DQS_DP<5>")
	)
	(segment
		(start 173.56455 -202.821286)
		(end 174.41291 -201.972926)
		(width 0.16002)
		(layer "In4.Cu")
		(net "M_J_CPU1_SA_DQS_DP<5>")
	)
	(segment
		(start 172.55744 -203.160376)
		(end 172.89653 -202.821286)
		(width 0.16002)
		(layer "In4.Cu")
		(net "M_J_CPU1_SA_DQS_DP<5>")
	)
	(segment
		(start 166.16553 -202.760326)
		(end 166.93515 -201.990706)
		(width 0.16002)
		(layer "In4.Cu")
		(net "M_J_CPU1_SA_DQS_DP<5>")
	)
	(segment
		(start 142.104618 -227.167694)
		(end 142.136114 -227.149406)
		(width 0.09525)
		(layer "In4.Cu")
		(net "M_J_CPU1_SA_DQS_DP<5>")
	)
	(segment
		(start 175.448976 -202.310492)
		(end 178.02606 -202.310492)
		(width 0.16002)
		(layer "In4.Cu")
		(net "M_J_CPU1_SA_DQS_DP<5>")
	)
	(segment
		(start 182.021226 -201.965306)
		(end 182.67299 -201.965306)
		(width 0.16002)
		(layer "In4.Cu")
		(net "M_J_CPU1_SA_DQS_DP<5>")
	)
	(segment
		(start 169.86631 -201.990706)
		(end 171.03598 -203.160376)
		(width 0.16002)
		(layer "In4.Cu")
		(net "M_J_CPU1_SA_DQS_DP<5>")
	)
	(segment
		(start 178.875944 -203.160376)
		(end 180.25364 -203.160376)
		(width 0.16002)
		(layer "In4.Cu")
		(net "M_J_CPU1_SA_DQS_DP<5>")
	)
	(segment
		(start 160.650936 -203.769214)
		(end 161.268664 -203.151486)
		(width 0.16002)
		(layer "In4.Cu")
		(net "M_J_CPU1_SA_DQS_DP<5>")
	)
	(segment
		(start 131.360926 -228.019102)
		(end 131.384294 -227.932234)
		(width 0.09525)
		(layer "In4.Cu")
		(net "M_J_CPU1_SA_DQS_DP<5>")
	)
	(segment
		(start 144.016222 -223.909382)
		(end 144.054322 -223.887284)
		(width 0.09525)
		(layer "In4.Cu")
		(net "M_J_CPU1_SA_DQS_DP<5>")
	)
	(segment
		(start 158.3182 -205.381098)
		(end 158.556452 -205.142846)
		(width 0.16002)
		(layer "In4.Cu")
		(net "M_J_CPU1_SA_DQS_DP<5>")
	)
	(segment
		(start 145.221706 -221.442026)
		(end 145.280634 -221.383098)
		(width 0.09525)
		(layer "In4.Cu")
		(net "M_J_CPU1_SA_DQS_DP<5>")
	)
	(segment
		(start 143.043656 -225.54819)
		(end 143.076168 -225.529394)
		(width 0.09525)
		(layer "In4.Cu")
		(net "M_J_CPU1_SA_DQS_DP<5>")
	)
	(segment
		(start 135.454898 -227.954586)
		(end 135.46328 -227.959412)
		(width 0.09525)
		(layer "In4.Cu")
		(net "M_J_CPU1_SA_DQS_DP<5>")
	)
	(segment
		(start 165.34765 -203.151486)
		(end 165.73881 -202.760326)
		(width 0.16002)
		(layer "In4.Cu")
		(net "M_J_CPU1_SA_DQS_DP<5>")
	)
	(segment
		(start 162.327844 -203.151486)
		(end 162.700716 -202.778614)
		(width 0.16002)
		(layer "In4.Cu")
		(net "M_J_CPU1_SA_DQS_DP<5>")
	)
	(segment
		(start 145.280634 -221.383098)
		(end 145.280634 -221.359476)
		(width 0.09525)
		(layer "In4.Cu")
		(net "M_J_CPU1_SA_DQS_DP<5>")
	)
	(segment
		(start 145.26768 -221.977458)
		(end 145.26768 -221.667832)
		(width 0.09525)
		(layer "In4.Cu")
		(net "M_J_CPU1_SA_DQS_DP<5>")
	)
	(segment
		(start 156.944568 -207.475582)
		(end 156.944568 -206.75473)
		(width 0.16002)
		(layer "In4.Cu")
		(net "M_J_CPU1_SA_DQS_DP<5>")
	)
	(segment
		(start 157.903672 -206.516478)
		(end 158.3182 -206.10195)
		(width 0.16002)
		(layer "In4.Cu")
		(net "M_J_CPU1_SA_DQS_DP<5>")
	)
	(segment
		(start 136.394952 -227.954586)
		(end 136.403334 -227.959412)
		(width 0.09525)
		(layer "In4.Cu")
		(net "M_J_CPU1_SA_DQS_DP<5>")
	)
	(segment
		(start 158.556452 -205.142846)
		(end 159.277304 -205.142846)
		(width 0.16002)
		(layer "In4.Cu")
		(net "M_J_CPU1_SA_DQS_DP<5>")
	)
	(segment
		(start 185.84926 -202.278234)
		(end 185.9661 -202.161394)
		(width 0.16002)
		(layer "In4.Cu")
		(net "M_J_CPU1_SA_DQS_DP<5>")
	)
	(segment
		(start 143.076168 -225.529394)
		(end 143.114268 -225.507296)
		(width 0.09525)
		(layer "In4.Cu")
		(net "M_J_CPU1_SA_DQS_DP<5>")
	)
	(segment
		(start 163.36899 -202.1586)
		(end 163.36899 -202.778614)
		(width 0.16002)
		(layer "In4.Cu")
		(net "M_J_CPU1_SA_DQS_DP<5>")
	)
	(segment
		(start 185.25236 -202.161394)
		(end 185.3692 -202.278234)
		(width 0.16002)
		(layer "In4.Cu")
		(net "M_J_CPU1_SA_DQS_DP<5>")
	)
	(segment
		(start 158.3182 -206.10195)
		(end 158.3182 -205.381098)
		(width 0.16002)
		(layer "In4.Cu")
		(net "M_J_CPU1_SA_DQS_DP<5>")
	)
	(segment
		(start 175.11141 -201.972926)
		(end 175.448976 -202.310492)
		(width 0.16002)
		(layer "In4.Cu")
		(net "M_J_CPU1_SA_DQS_DP<5>")
	)
	(segment
		(start 145.26768 -221.667832)
		(end 145.221706 -221.621858)
		(width 0.09525)
		(layer "In4.Cu")
		(net "M_J_CPU1_SA_DQS_DP<5>")
	)
	(segment
		(start 184.106312 -202.310492)
		(end 184.25541 -202.161394)
		(width 0.16002)
		(layer "In4.Cu")
		(net "M_J_CPU1_SA_DQS_DP<5>")
	)
	(segment
		(start 178.02606 -202.310492)
		(end 178.875944 -203.160376)
		(width 0.16002)
		(layer "In4.Cu")
		(net "M_J_CPU1_SA_DQS_DP<5>")
	)
	(segment
		(start 174.41291 -201.972926)
		(end 175.11141 -201.972926)
		(width 0.16002)
		(layer "In4.Cu")
		(net "M_J_CPU1_SA_DQS_DP<5>")
	)
	(segment
		(start 144.955768 -222.28937)
		(end 145.26768 -221.977458)
		(width 0.09525)
		(layer "In4.Cu")
		(net "M_J_CPU1_SA_DQS_DP<5>")
	)
	(segment
		(start 142.606268 -226.3394)
		(end 142.64132 -226.318826)
		(width 0.09525)
		(layer "In4.Cu")
		(net "M_J_CPU1_SA_DQS_DP<5>")
	)
	(segment
		(start 142.573756 -226.358196)
		(end 142.606268 -226.3394)
		(width 0.09525)
		(layer "In4.Cu")
		(net "M_J_CPU1_SA_DQS_DP<5>")
	)
	(segment
		(start 145.221706 -221.621858)
		(end 145.221706 -221.442026)
		(width 0.09525)
		(layer "In4.Cu")
		(net "M_J_CPU1_SA_DQS_DP<5>")
	)
	(segment
		(start 159.691832 -204.728318)
		(end 159.691832 -204.007466)
		(width 0.16002)
		(layer "In4.Cu")
		(net "M_J_CPU1_SA_DQS_DP<5>")
	)
	(segment
		(start 183.018176 -202.310492)
		(end 184.106312 -202.310492)
		(width 0.16002)
		(layer "In4.Cu")
		(net "M_J_CPU1_SA_DQS_DP<5>")
	)
	(segment
		(start 143.546068 -224.719388)
		(end 143.584168 -224.69729)
		(width 0.09525)
		(layer "In4.Cu")
		(net "M_J_CPU1_SA_DQS_DP<5>")
	)
	(segment
		(start 144.924272 -222.307658)
		(end 144.955768 -222.28937)
		(width 0.09525)
		(layer "In4.Cu")
		(net "M_J_CPU1_SA_DQS_DP<5>")
	)
	(segment
		(start 184.25541 -202.161394)
		(end 185.25236 -202.161394)
		(width 0.16002)
		(layer "In4.Cu")
		(net "M_J_CPU1_SA_DQS_DP<5>")
	)
	(segment
		(start 168.67251 -201.990706)
		(end 168.78935 -202.107546)
		(width 0.16002)
		(layer "In4.Cu")
		(net "M_J_CPU1_SA_DQS_DP<5>")
	)
	(segment
		(start 180.25364 -203.160376)
		(end 180.61559 -202.798426)
		(width 0.16002)
		(layer "In4.Cu")
		(net "M_J_CPU1_SA_DQS_DP<5>")
	)
	(segment
		(start 186.786266 -202.161394)
		(end 187.060078 -202.435206)
		(width 0.16002)
		(layer "In4.Cu")
		(net "M_J_CPU1_SA_DQS_DP<5>")
	)
	(segment
		(start 132.266182 -227.959412)
		(end 132.274564 -227.954586)
		(width 0.09525)
		(layer "In4.Cu")
		(net "M_J_CPU1_SA_DQS_DP<5>")
	)
	(segment
		(start 142.136114 -227.149406)
		(end 142.174214 -227.127308)
		(width 0.09525)
		(layer "In4.Cu")
		(net "M_J_CPU1_SA_DQS_DP<5>")
	)
	(segment
		(start 185.9661 -202.161394)
		(end 186.786266 -202.161394)
		(width 0.16002)
		(layer "In4.Cu")
		(net "M_J_CPU1_SA_DQS_DP<5>")
	)
	(segment
		(start 166.93515 -201.990706)
		(end 167.47871 -201.990706)
		(width 0.16002)
		(layer "In4.Cu")
		(net "M_J_CPU1_SA_DQS_DP<5>")
	)
	(segment
		(start 145.280634 -218.371928)
		(end 155.712668 -207.939894)
		(width 0.16002)
		(layer "In4.Cu")
		(net "M_J_CPU1_SA_DQS_DP<5>")
	)
	(segment
		(start 185.3692 -202.278234)
		(end 185.84926 -202.278234)
		(width 0.16002)
		(layer "In4.Cu")
		(net "M_J_CPU1_SA_DQS_DP<5>")
	)
	(segment
		(start 180.61559 -202.798426)
		(end 181.188106 -202.798426)
		(width 0.16002)
		(layer "In4.Cu")
		(net "M_J_CPU1_SA_DQS_DP<5>")
	)
	(segment
		(start 167.59555 -202.107546)
		(end 168.07561 -202.107546)
		(width 0.16002)
		(layer "In4.Cu")
		(net "M_J_CPU1_SA_DQS_DP<5>")
	)
	(segment
		(start 163.173156 -201.962766)
		(end 163.36899 -202.1586)
		(width 0.16002)
		(layer "In4.Cu")
		(net "M_J_CPU1_SA_DQS_DP<5>")
	)
	(segment
		(start 156.480256 -207.939894)
		(end 156.944568 -207.475582)
		(width 0.16002)
		(layer "In4.Cu")
		(net "M_J_CPU1_SA_DQS_DP<5>")
	)
	(segment
		(start 182.67299 -201.965306)
		(end 183.018176 -202.310492)
		(width 0.16002)
		(layer "In4.Cu")
		(net "M_J_CPU1_SA_DQS_DP<5>")
	)
	(segment
		(start 168.19245 -201.990706)
		(end 168.67251 -201.990706)
		(width 0.16002)
		(layer "In4.Cu")
		(net "M_J_CPU1_SA_DQS_DP<5>")
	)
	(segment
		(start 162.700716 -202.778614)
		(end 162.700716 -202.1586)
		(width 0.16002)
		(layer "In4.Cu")
		(net "M_J_CPU1_SA_DQS_DP<5>")
	)
	(segment
		(start 163.36899 -202.778614)
		(end 163.741862 -203.151486)
		(width 0.16002)
		(layer "In4.Cu")
		(net "M_J_CPU1_SA_DQS_DP<5>")
	)
	(segment
		(start 144.454626 -223.117664)
		(end 144.486122 -223.099376)
		(width 0.09525)
		(layer "In4.Cu")
		(net "M_J_CPU1_SA_DQS_DP<5>")
	)
	(segment
		(start 140.154914 -227.954586)
		(end 140.163296 -227.959412)
		(width 0.09525)
		(layer "In4.Cu")
		(net "M_J_CPU1_SA_DQS_DP<5>")
	)
	(segment
		(start 168.78935 -202.107546)
		(end 169.26941 -202.107546)
		(width 0.16002)
		(layer "In4.Cu")
		(net "M_J_CPU1_SA_DQS_DP<5>")
	)
	(segment
		(start 168.07561 -202.107546)
		(end 168.19245 -201.990706)
		(width 0.16002)
		(layer "In4.Cu")
		(net "M_J_CPU1_SA_DQS_DP<5>")
	)
	(segment
		(start 157.18282 -206.516478)
		(end 157.903672 -206.516478)
		(width 0.16002)
		(layer "In4.Cu")
		(net "M_J_CPU1_SA_DQS_DP<5>")
	)
	(segment
		(start 136.966198 -227.959412)
		(end 136.97458 -227.954586)
		(width 0.09525)
		(layer "In4.Cu")
		(net "M_J_CPU1_SA_DQS_DP<5>")
	)
	(segment
		(start 141.666214 -227.959412)
		(end 141.704314 -227.937314)
		(width 0.09525)
		(layer "In4.Cu")
		(net "M_J_CPU1_SA_DQS_DP<5>")
	)
	(segment
		(start 159.930084 -203.769214)
		(end 160.650936 -203.769214)
		(width 0.16002)
		(layer "In4.Cu")
		(net "M_J_CPU1_SA_DQS_DP<5>")
	)
	(segment
		(start 137.906252 -227.959412)
		(end 137.914634 -227.954586)
		(width 0.09525)
		(layer "In4.Cu")
		(net "M_J_CPU1_SA_DQS_DP<5>")
	)
	(segment
		(start 172.89653 -202.821286)
		(end 173.56455 -202.821286)
		(width 0.16002)
		(layer "In4.Cu")
		(net "M_J_CPU1_SA_DQS_DP<5>")
	)
	(segment
		(start 165.73881 -202.760326)
		(end 166.16553 -202.760326)
		(width 0.16002)
		(layer "In4.Cu")
		(net "M_J_CPU1_SA_DQS_DP<5>")
	)
	(segment
		(start 181.188106 -202.798426)
		(end 182.021226 -201.965306)
		(width 0.16002)
		(layer "In4.Cu")
		(net "M_J_CPU1_SA_DQS_DP<5>")
	)
	(segment
		(start 143.98371 -223.928178)
		(end 144.016222 -223.909382)
		(width 0.09525)
		(layer "In4.Cu")
		(net "M_J_CPU1_SA_DQS_DP<5>")
	)
	(segment
		(start 133.206236 -227.959412)
		(end 133.214618 -227.954586)
		(width 0.09525)
		(layer "In4.Cu")
		(net "M_J_CPU1_SA_DQS_DP<5>")
	)
	(segment
		(start 162.700716 -202.1586)
		(end 162.89655 -201.962766)
		(width 0.16002)
		(layer "In4.Cu")
		(net "M_J_CPU1_SA_DQS_DP<5>")
	)
	(segment
		(start 162.89655 -201.962766)
		(end 163.173156 -201.962766)
		(width 0.16002)
		(layer "In4.Cu")
		(net "M_J_CPU1_SA_DQS_DP<5>")
	)
	(segment
		(start 143.514572 -224.737676)
		(end 143.546068 -224.719388)
		(width 0.09525)
		(layer "In4.Cu")
		(net "M_J_CPU1_SA_DQS_DP<5>")
	)
	(segment
		(start 163.741862 -203.151486)
		(end 165.34765 -203.151486)
		(width 0.16002)
		(layer "In4.Cu")
		(net "M_J_CPU1_SA_DQS_DP<5>")
	)
	(segment
		(start 169.38625 -201.990706)
		(end 169.86631 -201.990706)
		(width 0.16002)
		(layer "In4.Cu")
		(net "M_J_CPU1_SA_DQS_DP<5>")
	)
	(segment
		(start 131.51485 -228.284532)
		(end 131.360926 -228.019102)
		(width 0.09525)
		(layer "In4.Cu")
		(net "M_J_CPU1_SA_DQS_DP<5>")
	)
	(segment
		(start 159.277304 -205.142846)
		(end 159.691832 -204.728318)
		(width 0.16002)
		(layer "In4.Cu")
		(net "M_J_CPU1_SA_DQS_DP<5>")
	)
	(segment
		(start 159.691832 -204.007466)
		(end 159.930084 -203.769214)
		(width 0.16002)
		(layer "In4.Cu")
		(net "M_J_CPU1_SA_DQS_DP<5>")
	)
	(segment
		(start 169.26941 -202.107546)
		(end 169.38625 -201.990706)
		(width 0.16002)
		(layer "In4.Cu")
		(net "M_J_CPU1_SA_DQS_DP<5>")
	)
	(segment
		(start 145.280634 -221.359476)
		(end 145.280634 -218.371928)
		(width 0.16002)
		(layer "In4.Cu")
		(net "M_J_CPU1_SA_DQS_DP<5>")
	)
	(arc
		(start 136.026144 -227.959412)
		(mid 136.209919 -227.90864)
		(end 136.394952 -227.954586)
		(width 0.09525)
		(layer "In4.Cu")
		(net "M_J_CPU1_SA_DQS_DP<5>")
	)
	(arc
		(start 138.283442 -227.959412)
		(mid 138.564874 -228.035167)
		(end 138.846306 -227.959412)
		(width 0.09525)
		(layer "In4.Cu")
		(net "M_J_CPU1_SA_DQS_DP<5>")
	)
	(arc
		(start 142.174214 -227.127308)
		(mid 142.352664 -226.925838)
		(end 142.417038 -226.66452)
		(width 0.09525)
		(layer "In4.Cu")
		(net "M_J_CPU1_SA_DQS_DP<5>")
	)
	(arc
		(start 144.054322 -223.887284)
		(mid 144.232772 -223.685814)
		(end 144.297146 -223.424496)
		(width 0.09525)
		(layer "In4.Cu")
		(net "M_J_CPU1_SA_DQS_DP<5>")
	)
	(arc
		(start 134.523226 -227.959412)
		(mid 134.804658 -228.035167)
		(end 135.08609 -227.959412)
		(width 0.09525)
		(layer "In4.Cu")
		(net "M_J_CPU1_SA_DQS_DP<5>")
	)
	(arc
		(start 132.643372 -227.959412)
		(mid 132.924804 -228.035167)
		(end 133.206236 -227.959412)
		(width 0.09525)
		(layer "In4.Cu")
		(net "M_J_CPU1_SA_DQS_DP<5>")
	)
	(arc
		(start 143.826992 -224.234502)
		(mid 143.868449 -224.062462)
		(end 143.98371 -223.928178)
		(width 0.09525)
		(layer "In4.Cu")
		(net "M_J_CPU1_SA_DQS_DP<5>")
	)
	(arc
		(start 132.274564 -227.954586)
		(mid 132.459596 -227.908672)
		(end 132.643372 -227.959412)
		(width 0.09525)
		(layer "In4.Cu")
		(net "M_J_CPU1_SA_DQS_DP<5>")
	)
	(arc
		(start 135.46328 -227.959412)
		(mid 135.744712 -228.035167)
		(end 136.026144 -227.959412)
		(width 0.09525)
		(layer "In4.Cu")
		(net "M_J_CPU1_SA_DQS_DP<5>")
	)
	(arc
		(start 143.114268 -225.507296)
		(mid 143.292718 -225.305826)
		(end 143.357092 -225.044508)
		(width 0.09525)
		(layer "In4.Cu")
		(net "M_J_CPU1_SA_DQS_DP<5>")
	)
	(arc
		(start 144.766538 -222.61449)
		(mid 144.808289 -222.442)
		(end 144.924272 -222.307658)
		(width 0.09525)
		(layer "In4.Cu")
		(net "M_J_CPU1_SA_DQS_DP<5>")
	)
	(arc
		(start 142.417038 -226.66452)
		(mid 142.458495 -226.49248)
		(end 142.573756 -226.358196)
		(width 0.09525)
		(layer "In4.Cu")
		(net "M_J_CPU1_SA_DQS_DP<5>")
	)
	(arc
		(start 143.357092 -225.044508)
		(mid 143.398757 -224.872061)
		(end 143.514572 -224.737676)
		(width 0.09525)
		(layer "In4.Cu")
		(net "M_J_CPU1_SA_DQS_DP<5>")
	)
	(arc
		(start 142.64132 -226.318826)
		(mid 142.821711 -226.117127)
		(end 142.886938 -225.854514)
		(width 0.09525)
		(layer "In4.Cu")
		(net "M_J_CPU1_SA_DQS_DP<5>")
	)
	(arc
		(start 131.703318 -227.959412)
		(mid 131.98475 -228.035167)
		(end 132.266182 -227.959412)
		(width 0.09525)
		(layer "In4.Cu")
		(net "M_J_CPU1_SA_DQS_DP<5>")
	)
	(arc
		(start 141.10335 -227.959412)
		(mid 141.384782 -228.035167)
		(end 141.666214 -227.959412)
		(width 0.09525)
		(layer "In4.Cu")
		(net "M_J_CPU1_SA_DQS_DP<5>")
	)
	(arc
		(start 141.947138 -227.474526)
		(mid 141.988803 -227.302079)
		(end 142.104618 -227.167694)
		(width 0.09525)
		(layer "In4.Cu")
		(net "M_J_CPU1_SA_DQS_DP<5>")
	)
	(arc
		(start 139.786106 -227.959412)
		(mid 139.969881 -227.90864)
		(end 140.154914 -227.954586)
		(width 0.09525)
		(layer "In4.Cu")
		(net "M_J_CPU1_SA_DQS_DP<5>")
	)
	(arc
		(start 141.704314 -227.937314)
		(mid 141.882764 -227.735844)
		(end 141.947138 -227.474526)
		(width 0.09525)
		(layer "In4.Cu")
		(net "M_J_CPU1_SA_DQS_DP<5>")
	)
	(arc
		(start 136.403334 -227.959412)
		(mid 136.684766 -228.035167)
		(end 136.966198 -227.959412)
		(width 0.09525)
		(layer "In4.Cu")
		(net "M_J_CPU1_SA_DQS_DP<5>")
	)
	(arc
		(start 137.914634 -227.954586)
		(mid 138.099666 -227.908672)
		(end 138.283442 -227.959412)
		(width 0.09525)
		(layer "In4.Cu")
		(net "M_J_CPU1_SA_DQS_DP<5>")
	)
	(arc
		(start 143.584168 -224.69729)
		(mid 143.762618 -224.49582)
		(end 143.826992 -224.234502)
		(width 0.09525)
		(layer "In4.Cu")
		(net "M_J_CPU1_SA_DQS_DP<5>")
	)
	(arc
		(start 136.97458 -227.954586)
		(mid 137.159612 -227.908672)
		(end 137.343388 -227.959412)
		(width 0.09525)
		(layer "In4.Cu")
		(net "M_J_CPU1_SA_DQS_DP<5>")
	)
	(arc
		(start 144.518126 -223.080834)
		(mid 144.700591 -222.878689)
		(end 144.766538 -222.61449)
		(width 0.09525)
		(layer "In4.Cu")
		(net "M_J_CPU1_SA_DQS_DP<5>")
	)
	(arc
		(start 133.214618 -227.954586)
		(mid 133.39965 -227.908672)
		(end 133.583426 -227.959412)
		(width 0.09525)
		(layer "In4.Cu")
		(net "M_J_CPU1_SA_DQS_DP<5>")
	)
	(arc
		(start 144.297146 -223.424496)
		(mid 144.338811 -223.252049)
		(end 144.454626 -223.117664)
		(width 0.09525)
		(layer "In4.Cu")
		(net "M_J_CPU1_SA_DQS_DP<5>")
	)
	(arc
		(start 137.343388 -227.959412)
		(mid 137.62482 -228.035167)
		(end 137.906252 -227.959412)
		(width 0.09525)
		(layer "In4.Cu")
		(net "M_J_CPU1_SA_DQS_DP<5>")
	)
	(arc
		(start 139.223242 -227.959412)
		(mid 139.504674 -228.035167)
		(end 139.786106 -227.959412)
		(width 0.09525)
		(layer "In4.Cu")
		(net "M_J_CPU1_SA_DQS_DP<5>")
	)
	(arc
		(start 134.14629 -227.959412)
		(mid 134.334758 -227.908735)
		(end 134.523226 -227.959412)
		(width 0.09525)
		(layer "In4.Cu")
		(net "M_J_CPU1_SA_DQS_DP<5>")
	)
	(arc
		(start 133.583426 -227.959412)
		(mid 133.864858 -228.035167)
		(end 134.14629 -227.959412)
		(width 0.09525)
		(layer "In4.Cu")
		(net "M_J_CPU1_SA_DQS_DP<5>")
	)
	(arc
		(start 131.384294 -227.932234)
		(mid 131.542044 -227.909715)
		(end 131.694936 -227.954586)
		(width 0.09525)
		(layer "In4.Cu")
		(net "M_J_CPU1_SA_DQS_DP<5>")
	)
	(arc
		(start 142.886938 -225.854514)
		(mid 142.928395 -225.682474)
		(end 143.043656 -225.54819)
		(width 0.09525)
		(layer "In4.Cu")
		(net "M_J_CPU1_SA_DQS_DP<5>")
	)
	(arc
		(start 140.163296 -227.959412)
		(mid 140.444728 -228.035167)
		(end 140.72616 -227.959412)
		(width 0.09525)
		(layer "In4.Cu")
		(net "M_J_CPU1_SA_DQS_DP<5>")
	)
	(arc
		(start 140.72616 -227.959412)
		(mid 140.909935 -227.90864)
		(end 141.094968 -227.954586)
		(width 0.09525)
		(layer "In4.Cu")
		(net "M_J_CPU1_SA_DQS_DP<5>")
	)
	(arc
		(start 135.08609 -227.959412)
		(mid 135.269865 -227.90864)
		(end 135.454898 -227.954586)
		(width 0.09525)
		(layer "In4.Cu")
		(net "M_J_CPU1_SA_DQS_DP<5>")
	)
	(arc
		(start 138.846306 -227.959412)
		(mid 139.034774 -227.908735)
		(end 139.223242 -227.959412)
		(width 0.09525)
		(layer "In4.Cu")
		(net "M_J_CPU1_SA_DQS_DP<5>")
	)
	(segment
		(start 131.987798 -246.370348)
		(end 132.45465 -246.10441)
		(width 0.12954)
		(layer "F.Cu")
		(net "M_J_CPU1_SA_DQS_DP<4>")
	)
	(segment
		(start 147.834604 -245.933976)
		(end 147.858226 -245.933976)
		(width 0.09525)
		(layer "In4.Cu")
		(net "M_J_CPU1_SA_DQS_DP<4>")
	)
	(segment
		(start 137.906252 -246.42953)
		(end 137.914634 -246.434356)
		(width 0.09525)
		(layer "In4.Cu")
		(net "M_J_CPU1_SA_DQS_DP<4>")
	)
	(segment
		(start 144.47647 -246.423434)
		(end 144.486884 -246.42953)
		(width 0.09525)
		(layer "In4.Cu")
		(net "M_J_CPU1_SA_DQS_DP<4>")
	)
	(segment
		(start 187.88253 -238.590582)
		(end 188.81217 -238.590582)
		(width 0.16002)
		(layer "In4.Cu")
		(net "M_J_CPU1_SA_DQS_DP<4>")
	)
	(segment
		(start 144.851882 -246.436388)
		(end 144.86382 -246.42953)
		(width 0.09525)
		(layer "In4.Cu")
		(net "M_J_CPU1_SA_DQS_DP<4>")
	)
	(segment
		(start 184.622694 -237.410244)
		(end 185.079132 -237.866682)
		(width 0.16002)
		(layer "In4.Cu")
		(net "M_J_CPU1_SA_DQS_DP<4>")
	)
	(segment
		(start 132.608574 -246.36984)
		(end 132.709412 -246.39651)
		(width 0.09525)
		(layer "In4.Cu")
		(net "M_J_CPU1_SA_DQS_DP<4>")
	)
	(segment
		(start 145.616168 -246.481346)
		(end 146.106134 -246.481346)
		(width 0.09525)
		(layer "In4.Cu")
		(net "M_J_CPU1_SA_DQS_DP<4>")
	)
	(segment
		(start 155.651708 -245.933976)
		(end 160.034732 -241.550952)
		(width 0.16002)
		(layer "In4.Cu")
		(net "M_J_CPU1_SA_DQS_DP<4>")
	)
	(segment
		(start 136.394952 -246.434356)
		(end 136.403334 -246.42953)
		(width 0.09525)
		(layer "In4.Cu")
		(net "M_J_CPU1_SA_DQS_DP<4>")
	)
	(segment
		(start 146.377914 -246.753126)
		(end 146.895312 -246.753126)
		(width 0.09525)
		(layer "In4.Cu")
		(net "M_J_CPU1_SA_DQS_DP<4>")
	)
	(segment
		(start 161.214816 -241.550952)
		(end 164.162486 -238.603282)
		(width 0.16002)
		(layer "In4.Cu")
		(net "M_J_CPU1_SA_DQS_DP<4>")
	)
	(segment
		(start 136.966198 -246.42953)
		(end 136.97458 -246.434356)
		(width 0.09525)
		(layer "In4.Cu")
		(net "M_J_CPU1_SA_DQS_DP<4>")
	)
	(segment
		(start 188.81217 -238.590582)
		(end 188.993526 -238.409226)
		(width 0.16002)
		(layer "In4.Cu")
		(net "M_J_CPU1_SA_DQS_DP<4>")
	)
	(segment
		(start 190.886334 -238.409226)
		(end 191.160146 -238.135414)
		(width 0.16002)
		(layer "In4.Cu")
		(net "M_J_CPU1_SA_DQS_DP<4>")
	)
	(segment
		(start 175.539908 -237.410244)
		(end 177.137568 -237.410244)
		(width 0.16002)
		(layer "In4.Cu")
		(net "M_J_CPU1_SA_DQS_DP<4>")
	)
	(segment
		(start 164.162486 -238.603282)
		(end 166.00805 -238.603282)
		(width 0.16002)
		(layer "In4.Cu")
		(net "M_J_CPU1_SA_DQS_DP<4>")
	)
	(segment
		(start 140.154914 -246.434356)
		(end 140.163296 -246.42953)
		(width 0.09525)
		(layer "In4.Cu")
		(net "M_J_CPU1_SA_DQS_DP<4>")
	)
	(segment
		(start 146.895312 -246.753126)
		(end 147.59813 -245.993158)
		(width 0.09525)
		(layer "In4.Cu")
		(net "M_J_CPU1_SA_DQS_DP<4>")
	)
	(segment
		(start 141.666214 -246.42953)
		(end 141.674596 -246.434356)
		(width 0.09525)
		(layer "In4.Cu")
		(net "M_J_CPU1_SA_DQS_DP<4>")
	)
	(segment
		(start 172.568616 -238.260128)
		(end 172.92447 -238.615982)
		(width 0.16002)
		(layer "In4.Cu")
		(net "M_J_CPU1_SA_DQS_DP<4>")
	)
	(segment
		(start 166.00805 -238.603282)
		(end 166.88181 -237.729522)
		(width 0.16002)
		(layer "In4.Cu")
		(net "M_J_CPU1_SA_DQS_DP<4>")
	)
	(segment
		(start 181.843934 -237.866682)
		(end 182.552848 -237.866682)
		(width 0.16002)
		(layer "In4.Cu")
		(net "M_J_CPU1_SA_DQS_DP<4>")
	)
	(segment
		(start 180.54193 -238.636302)
		(end 181.074314 -238.636302)
		(width 0.16002)
		(layer "In4.Cu")
		(net "M_J_CPU1_SA_DQS_DP<4>")
	)
	(segment
		(start 147.775422 -245.993158)
		(end 147.834604 -245.933976)
		(width 0.09525)
		(layer "In4.Cu")
		(net "M_J_CPU1_SA_DQS_DP<4>")
	)
	(segment
		(start 143.546068 -246.42953)
		(end 143.55445 -246.434356)
		(width 0.09525)
		(layer "In4.Cu")
		(net "M_J_CPU1_SA_DQS_DP<4>")
	)
	(segment
		(start 132.45465 -246.10441)
		(end 132.608574 -246.36984)
		(width 0.09525)
		(layer "In4.Cu")
		(net "M_J_CPU1_SA_DQS_DP<4>")
	)
	(segment
		(start 146.106134 -246.481346)
		(end 146.377914 -246.753126)
		(width 0.09525)
		(layer "In4.Cu")
		(net "M_J_CPU1_SA_DQS_DP<4>")
	)
	(segment
		(start 177.987452 -238.260128)
		(end 180.165756 -238.260128)
		(width 0.16002)
		(layer "In4.Cu")
		(net "M_J_CPU1_SA_DQS_DP<4>")
	)
	(segment
		(start 187.15863 -237.866682)
		(end 187.88253 -238.590582)
		(width 0.16002)
		(layer "In4.Cu")
		(net "M_J_CPU1_SA_DQS_DP<4>")
	)
	(segment
		(start 133.206236 -246.42953)
		(end 133.214618 -246.434356)
		(width 0.09525)
		(layer "In4.Cu")
		(net "M_J_CPU1_SA_DQS_DP<4>")
	)
	(segment
		(start 183.009286 -237.410244)
		(end 184.622694 -237.410244)
		(width 0.16002)
		(layer "In4.Cu")
		(net "M_J_CPU1_SA_DQS_DP<4>")
	)
	(segment
		(start 170.661076 -238.260128)
		(end 172.568616 -238.260128)
		(width 0.16002)
		(layer "In4.Cu")
		(net "M_J_CPU1_SA_DQS_DP<4>")
	)
	(segment
		(start 172.92447 -238.615982)
		(end 173.505622 -238.615982)
		(width 0.16002)
		(layer "In4.Cu")
		(net "M_J_CPU1_SA_DQS_DP<4>")
	)
	(segment
		(start 173.505622 -238.615982)
		(end 174.183802 -237.937802)
		(width 0.16002)
		(layer "In4.Cu")
		(net "M_J_CPU1_SA_DQS_DP<4>")
	)
	(segment
		(start 160.034732 -241.550952)
		(end 161.214816 -241.550952)
		(width 0.16002)
		(layer "In4.Cu")
		(net "M_J_CPU1_SA_DQS_DP<4>")
	)
	(segment
		(start 166.88181 -237.729522)
		(end 170.13047 -237.729522)
		(width 0.16002)
		(layer "In4.Cu")
		(net "M_J_CPU1_SA_DQS_DP<4>")
	)
	(segment
		(start 170.13047 -237.729522)
		(end 170.661076 -238.260128)
		(width 0.16002)
		(layer "In4.Cu")
		(net "M_J_CPU1_SA_DQS_DP<4>")
	)
	(segment
		(start 147.59813 -245.993158)
		(end 147.775422 -245.993158)
		(width 0.09525)
		(layer "In4.Cu")
		(net "M_J_CPU1_SA_DQS_DP<4>")
	)
	(segment
		(start 174.183802 -237.937802)
		(end 175.01235 -237.937802)
		(width 0.16002)
		(layer "In4.Cu")
		(net "M_J_CPU1_SA_DQS_DP<4>")
	)
	(segment
		(start 177.137568 -237.410244)
		(end 177.987452 -238.260128)
		(width 0.16002)
		(layer "In4.Cu")
		(net "M_J_CPU1_SA_DQS_DP<4>")
	)
	(segment
		(start 175.01235 -237.937802)
		(end 175.539908 -237.410244)
		(width 0.16002)
		(layer "In4.Cu")
		(net "M_J_CPU1_SA_DQS_DP<4>")
	)
	(segment
		(start 147.858226 -245.933976)
		(end 155.651708 -245.933976)
		(width 0.16002)
		(layer "In4.Cu")
		(net "M_J_CPU1_SA_DQS_DP<4>")
	)
	(segment
		(start 141.094968 -246.434356)
		(end 141.10335 -246.42953)
		(width 0.09525)
		(layer "In4.Cu")
		(net "M_J_CPU1_SA_DQS_DP<4>")
	)
	(segment
		(start 181.074314 -238.636302)
		(end 181.843934 -237.866682)
		(width 0.16002)
		(layer "In4.Cu")
		(net "M_J_CPU1_SA_DQS_DP<4>")
	)
	(segment
		(start 185.079132 -237.866682)
		(end 187.15863 -237.866682)
		(width 0.16002)
		(layer "In4.Cu")
		(net "M_J_CPU1_SA_DQS_DP<4>")
	)
	(segment
		(start 188.993526 -238.409226)
		(end 190.886334 -238.409226)
		(width 0.16002)
		(layer "In4.Cu")
		(net "M_J_CPU1_SA_DQS_DP<4>")
	)
	(segment
		(start 182.552848 -237.866682)
		(end 183.009286 -237.410244)
		(width 0.16002)
		(layer "In4.Cu")
		(net "M_J_CPU1_SA_DQS_DP<4>")
	)
	(segment
		(start 135.454898 -246.434356)
		(end 135.46328 -246.42953)
		(width 0.09525)
		(layer "In4.Cu")
		(net "M_J_CPU1_SA_DQS_DP<4>")
	)
	(segment
		(start 144.86382 -246.42953)
		(end 144.884648 -246.417338)
		(width 0.09525)
		(layer "In4.Cu")
		(net "M_J_CPU1_SA_DQS_DP<4>")
	)
	(segment
		(start 180.165756 -238.260128)
		(end 180.54193 -238.636302)
		(width 0.16002)
		(layer "In4.Cu")
		(net "M_J_CPU1_SA_DQS_DP<4>")
	)
	(arc
		(start 137.914634 -246.434356)
		(mid 138.099666 -246.48027)
		(end 138.283442 -246.42953)
		(width 0.09525)
		(layer "In4.Cu")
		(net "M_J_CPU1_SA_DQS_DP<4>")
	)
	(arc
		(start 136.97458 -246.434356)
		(mid 137.159612 -246.48027)
		(end 137.343388 -246.42953)
		(width 0.09525)
		(layer "In4.Cu")
		(net "M_J_CPU1_SA_DQS_DP<4>")
	)
	(arc
		(start 141.674596 -246.434356)
		(mid 141.859628 -246.48027)
		(end 142.043404 -246.42953)
		(width 0.09525)
		(layer "In4.Cu")
		(net "M_J_CPU1_SA_DQS_DP<4>")
	)
	(arc
		(start 132.729986 -246.388382)
		(mid 132.972728 -246.355612)
		(end 133.206236 -246.42953)
		(width 0.09525)
		(layer "In4.Cu")
		(net "M_J_CPU1_SA_DQS_DP<4>")
	)
	(arc
		(start 134.14629 -246.42953)
		(mid 134.334758 -246.480207)
		(end 134.523226 -246.42953)
		(width 0.09525)
		(layer "In4.Cu")
		(net "M_J_CPU1_SA_DQS_DP<4>")
	)
	(arc
		(start 141.10335 -246.42953)
		(mid 141.384782 -246.353775)
		(end 141.666214 -246.42953)
		(width 0.09525)
		(layer "In4.Cu")
		(net "M_J_CPU1_SA_DQS_DP<4>")
	)
	(arc
		(start 133.214618 -246.434356)
		(mid 133.39965 -246.48027)
		(end 133.583426 -246.42953)
		(width 0.09525)
		(layer "In4.Cu")
		(net "M_J_CPU1_SA_DQS_DP<4>")
	)
	(arc
		(start 134.523226 -246.42953)
		(mid 134.804658 -246.353775)
		(end 135.08609 -246.42953)
		(width 0.09525)
		(layer "In4.Cu")
		(net "M_J_CPU1_SA_DQS_DP<4>")
	)
	(arc
		(start 137.343388 -246.42953)
		(mid 137.62482 -246.353775)
		(end 137.906252 -246.42953)
		(width 0.09525)
		(layer "In4.Cu")
		(net "M_J_CPU1_SA_DQS_DP<4>")
	)
	(arc
		(start 138.846306 -246.42953)
		(mid 139.034774 -246.480207)
		(end 139.223242 -246.42953)
		(width 0.09525)
		(layer "In4.Cu")
		(net "M_J_CPU1_SA_DQS_DP<4>")
	)
	(arc
		(start 142.043404 -246.42953)
		(mid 142.324836 -246.353775)
		(end 142.606268 -246.42953)
		(width 0.09525)
		(layer "In4.Cu")
		(net "M_J_CPU1_SA_DQS_DP<4>")
	)
	(arc
		(start 139.223242 -246.42953)
		(mid 139.504674 -246.353775)
		(end 139.786106 -246.42953)
		(width 0.09525)
		(layer "In4.Cu")
		(net "M_J_CPU1_SA_DQS_DP<4>")
	)
	(arc
		(start 142.606268 -246.42953)
		(mid 142.794736 -246.480207)
		(end 142.983204 -246.42953)
		(width 0.09525)
		(layer "In4.Cu")
		(net "M_J_CPU1_SA_DQS_DP<4>")
	)
	(arc
		(start 138.283442 -246.42953)
		(mid 138.564874 -246.353775)
		(end 138.846306 -246.42953)
		(width 0.09525)
		(layer "In4.Cu")
		(net "M_J_CPU1_SA_DQS_DP<4>")
	)
	(arc
		(start 132.709412 -246.39651)
		(mid 132.71966 -246.392347)
		(end 132.729986 -246.388382)
		(width 0.09525)
		(layer "In4.Cu")
		(net "M_J_CPU1_SA_DQS_DP<4>")
	)
	(arc
		(start 136.403334 -246.42953)
		(mid 136.684766 -246.353775)
		(end 136.966198 -246.42953)
		(width 0.09525)
		(layer "In4.Cu")
		(net "M_J_CPU1_SA_DQS_DP<4>")
	)
	(arc
		(start 145.426684 -246.42953)
		(mid 145.517981 -246.468055)
		(end 145.616168 -246.481346)
		(width 0.09525)
		(layer "In4.Cu")
		(net "M_J_CPU1_SA_DQS_DP<4>")
	)
	(arc
		(start 144.884648 -246.417338)
		(mid 145.157253 -246.353542)
		(end 145.426684 -246.42953)
		(width 0.09525)
		(layer "In4.Cu")
		(net "M_J_CPU1_SA_DQS_DP<4>")
	)
	(arc
		(start 135.08609 -246.42953)
		(mid 135.269865 -246.480302)
		(end 135.454898 -246.434356)
		(width 0.09525)
		(layer "In4.Cu")
		(net "M_J_CPU1_SA_DQS_DP<4>")
	)
	(arc
		(start 143.55445 -246.434356)
		(mid 143.739736 -246.480392)
		(end 143.923766 -246.42953)
		(width 0.09525)
		(layer "In4.Cu")
		(net "M_J_CPU1_SA_DQS_DP<4>")
	)
	(arc
		(start 139.786106 -246.42953)
		(mid 139.969881 -246.480302)
		(end 140.154914 -246.434356)
		(width 0.09525)
		(layer "In4.Cu")
		(net "M_J_CPU1_SA_DQS_DP<4>")
	)
	(arc
		(start 135.46328 -246.42953)
		(mid 135.744712 -246.353775)
		(end 136.026144 -246.42953)
		(width 0.09525)
		(layer "In4.Cu")
		(net "M_J_CPU1_SA_DQS_DP<4>")
	)
	(arc
		(start 140.72616 -246.42953)
		(mid 140.909935 -246.480302)
		(end 141.094968 -246.434356)
		(width 0.09525)
		(layer "In4.Cu")
		(net "M_J_CPU1_SA_DQS_DP<4>")
	)
	(arc
		(start 133.583426 -246.42953)
		(mid 133.864858 -246.353775)
		(end 134.14629 -246.42953)
		(width 0.09525)
		(layer "In4.Cu")
		(net "M_J_CPU1_SA_DQS_DP<4>")
	)
	(arc
		(start 144.486884 -246.42953)
		(mid 144.6685 -246.480267)
		(end 144.851882 -246.436388)
		(width 0.09525)
		(layer "In4.Cu")
		(net "M_J_CPU1_SA_DQS_DP<4>")
	)
	(arc
		(start 143.923766 -246.42953)
		(mid 144.199309 -246.353681)
		(end 144.47647 -246.423434)
		(width 0.09525)
		(layer "In4.Cu")
		(net "M_J_CPU1_SA_DQS_DP<4>")
	)
	(arc
		(start 136.026144 -246.42953)
		(mid 136.209919 -246.480302)
		(end 136.394952 -246.434356)
		(width 0.09525)
		(layer "In4.Cu")
		(net "M_J_CPU1_SA_DQS_DP<4>")
	)
	(arc
		(start 140.163296 -246.42953)
		(mid 140.444728 -246.353775)
		(end 140.72616 -246.42953)
		(width 0.09525)
		(layer "In4.Cu")
		(net "M_J_CPU1_SA_DQS_DP<4>")
	)
	(arc
		(start 142.983204 -246.42953)
		(mid 143.264636 -246.353775)
		(end 143.546068 -246.42953)
		(width 0.09525)
		(layer "In4.Cu")
		(net "M_J_CPU1_SA_DQS_DP<4>")
	)
	(segment
		(start 131.987798 -241.510312)
		(end 132.45465 -241.244374)
		(width 0.12954)
		(layer "F.Cu")
		(net "M_J_CPU1_SA_DQS_DP<3>")
	)
	(segment
		(start 181.843934 -228.516688)
		(end 182.552848 -228.516688)
		(width 0.16002)
		(layer "In4.Cu")
		(net "M_J_CPU1_SA_DQS_DP<3>")
	)
	(segment
		(start 172.568616 -228.910134)
		(end 172.92447 -229.265988)
		(width 0.16002)
		(layer "In4.Cu")
		(net "M_J_CPU1_SA_DQS_DP<3>")
	)
	(segment
		(start 182.552848 -228.516688)
		(end 183.009286 -228.06025)
		(width 0.16002)
		(layer "In4.Cu")
		(net "M_J_CPU1_SA_DQS_DP<3>")
	)
	(segment
		(start 140.154914 -241.57432)
		(end 140.163296 -241.569494)
		(width 0.09525)
		(layer "In4.Cu")
		(net "M_J_CPU1_SA_DQS_DP<3>")
	)
	(segment
		(start 147.363434 -240.356136)
		(end 147.82927 -240.356136)
		(width 0.09525)
		(layer "In4.Cu")
		(net "M_J_CPU1_SA_DQS_DP<3>")
	)
	(segment
		(start 175.539908 -228.06025)
		(end 177.137568 -228.06025)
		(width 0.16002)
		(layer "In4.Cu")
		(net "M_J_CPU1_SA_DQS_DP<3>")
	)
	(segment
		(start 187.88253 -229.240588)
		(end 188.81217 -229.240588)
		(width 0.16002)
		(layer "In4.Cu")
		(net "M_J_CPU1_SA_DQS_DP<3>")
	)
	(segment
		(start 133.206236 -241.569494)
		(end 133.214618 -241.57432)
		(width 0.09525)
		(layer "In4.Cu")
		(net "M_J_CPU1_SA_DQS_DP<3>")
	)
	(segment
		(start 141.094968 -241.57432)
		(end 141.10335 -241.569494)
		(width 0.09525)
		(layer "In4.Cu")
		(net "M_J_CPU1_SA_DQS_DP<3>")
	)
	(segment
		(start 144.47647 -241.563398)
		(end 144.486884 -241.569494)
		(width 0.09525)
		(layer "In4.Cu")
		(net "M_J_CPU1_SA_DQS_DP<3>")
	)
	(segment
		(start 172.92447 -229.265988)
		(end 173.505622 -229.265988)
		(width 0.16002)
		(layer "In4.Cu")
		(net "M_J_CPU1_SA_DQS_DP<3>")
	)
	(segment
		(start 173.505622 -229.265988)
		(end 174.183802 -228.587808)
		(width 0.16002)
		(layer "In4.Cu")
		(net "M_J_CPU1_SA_DQS_DP<3>")
	)
	(segment
		(start 146.36496 -240.923064)
		(end 146.796506 -240.923064)
		(width 0.09525)
		(layer "In4.Cu")
		(net "M_J_CPU1_SA_DQS_DP<3>")
	)
	(segment
		(start 174.183802 -228.587808)
		(end 175.01235 -228.587808)
		(width 0.16002)
		(layer "In4.Cu")
		(net "M_J_CPU1_SA_DQS_DP<3>")
	)
	(segment
		(start 147.912074 -240.296954)
		(end 151.67864 -240.296954)
		(width 0.16002)
		(layer "In4.Cu")
		(net "M_J_CPU1_SA_DQS_DP<3>")
	)
	(segment
		(start 166.88181 -228.379528)
		(end 170.13047 -228.379528)
		(width 0.16002)
		(layer "In4.Cu")
		(net "M_J_CPU1_SA_DQS_DP<3>")
	)
	(segment
		(start 190.886334 -229.059232)
		(end 191.160146 -228.78542)
		(width 0.16002)
		(layer "In4.Cu")
		(net "M_J_CPU1_SA_DQS_DP<3>")
	)
	(segment
		(start 141.666214 -241.569494)
		(end 141.674596 -241.57432)
		(width 0.09525)
		(layer "In4.Cu")
		(net "M_J_CPU1_SA_DQS_DP<3>")
	)
	(segment
		(start 185.079132 -228.516688)
		(end 187.15863 -228.516688)
		(width 0.16002)
		(layer "In4.Cu")
		(net "M_J_CPU1_SA_DQS_DP<3>")
	)
	(segment
		(start 147.888452 -240.296954)
		(end 147.912074 -240.296954)
		(width 0.09525)
		(layer "In4.Cu")
		(net "M_J_CPU1_SA_DQS_DP<3>")
	)
	(segment
		(start 145.144744 -241.493802)
		(end 145.794222 -241.493802)
		(width 0.09525)
		(layer "In4.Cu")
		(net "M_J_CPU1_SA_DQS_DP<3>")
	)
	(segment
		(start 147.82927 -240.356136)
		(end 147.888452 -240.296954)
		(width 0.09525)
		(layer "In4.Cu")
		(net "M_J_CPU1_SA_DQS_DP<3>")
	)
	(segment
		(start 132.45465 -241.244374)
		(end 132.608574 -241.509804)
		(width 0.09525)
		(layer "In4.Cu")
		(net "M_J_CPU1_SA_DQS_DP<3>")
	)
	(segment
		(start 187.15863 -228.516688)
		(end 187.88253 -229.240588)
		(width 0.16002)
		(layer "In4.Cu")
		(net "M_J_CPU1_SA_DQS_DP<3>")
	)
	(segment
		(start 188.81217 -229.240588)
		(end 188.993526 -229.059232)
		(width 0.16002)
		(layer "In4.Cu")
		(net "M_J_CPU1_SA_DQS_DP<3>")
	)
	(segment
		(start 170.661076 -228.910134)
		(end 172.568616 -228.910134)
		(width 0.16002)
		(layer "In4.Cu")
		(net "M_J_CPU1_SA_DQS_DP<3>")
	)
	(segment
		(start 183.009286 -228.06025)
		(end 184.622694 -228.06025)
		(width 0.16002)
		(layer "In4.Cu")
		(net "M_J_CPU1_SA_DQS_DP<3>")
	)
	(segment
		(start 177.987452 -228.910134)
		(end 180.165756 -228.910134)
		(width 0.16002)
		(layer "In4.Cu")
		(net "M_J_CPU1_SA_DQS_DP<3>")
	)
	(segment
		(start 146.796506 -240.923064)
		(end 147.363434 -240.356136)
		(width 0.09525)
		(layer "In4.Cu")
		(net "M_J_CPU1_SA_DQS_DP<3>")
	)
	(segment
		(start 158.04769 -233.443272)
		(end 162.237674 -229.253288)
		(width 0.16002)
		(layer "In4.Cu")
		(net "M_J_CPU1_SA_DQS_DP<3>")
	)
	(segment
		(start 166.00805 -229.253288)
		(end 166.88181 -228.379528)
		(width 0.16002)
		(layer "In4.Cu")
		(net "M_J_CPU1_SA_DQS_DP<3>")
	)
	(segment
		(start 175.01235 -228.587808)
		(end 175.539908 -228.06025)
		(width 0.16002)
		(layer "In4.Cu")
		(net "M_J_CPU1_SA_DQS_DP<3>")
	)
	(segment
		(start 188.993526 -229.059232)
		(end 190.886334 -229.059232)
		(width 0.16002)
		(layer "In4.Cu")
		(net "M_J_CPU1_SA_DQS_DP<3>")
	)
	(segment
		(start 136.394952 -241.57432)
		(end 136.403334 -241.569494)
		(width 0.09525)
		(layer "In4.Cu")
		(net "M_J_CPU1_SA_DQS_DP<3>")
	)
	(segment
		(start 151.67864 -240.296954)
		(end 158.04769 -233.927904)
		(width 0.16002)
		(layer "In4.Cu")
		(net "M_J_CPU1_SA_DQS_DP<3>")
	)
	(segment
		(start 170.13047 -228.379528)
		(end 170.661076 -228.910134)
		(width 0.16002)
		(layer "In4.Cu")
		(net "M_J_CPU1_SA_DQS_DP<3>")
	)
	(segment
		(start 181.074314 -229.286308)
		(end 181.843934 -228.516688)
		(width 0.16002)
		(layer "In4.Cu")
		(net "M_J_CPU1_SA_DQS_DP<3>")
	)
	(segment
		(start 136.966198 -241.569494)
		(end 136.97458 -241.57432)
		(width 0.09525)
		(layer "In4.Cu")
		(net "M_J_CPU1_SA_DQS_DP<3>")
	)
	(segment
		(start 158.04769 -233.927904)
		(end 158.04769 -233.443272)
		(width 0.16002)
		(layer "In4.Cu")
		(net "M_J_CPU1_SA_DQS_DP<3>")
	)
	(segment
		(start 137.906252 -241.569494)
		(end 137.914634 -241.57432)
		(width 0.09525)
		(layer "In4.Cu")
		(net "M_J_CPU1_SA_DQS_DP<3>")
	)
	(segment
		(start 180.54193 -229.286308)
		(end 181.074314 -229.286308)
		(width 0.16002)
		(layer "In4.Cu")
		(net "M_J_CPU1_SA_DQS_DP<3>")
	)
	(segment
		(start 180.165756 -228.910134)
		(end 180.54193 -229.286308)
		(width 0.16002)
		(layer "In4.Cu")
		(net "M_J_CPU1_SA_DQS_DP<3>")
	)
	(segment
		(start 177.137568 -228.06025)
		(end 177.987452 -228.910134)
		(width 0.16002)
		(layer "In4.Cu")
		(net "M_J_CPU1_SA_DQS_DP<3>")
	)
	(segment
		(start 132.608574 -241.509804)
		(end 132.709412 -241.536474)
		(width 0.09525)
		(layer "In4.Cu")
		(net "M_J_CPU1_SA_DQS_DP<3>")
	)
	(segment
		(start 135.454898 -241.57432)
		(end 135.46328 -241.569494)
		(width 0.09525)
		(layer "In4.Cu")
		(net "M_J_CPU1_SA_DQS_DP<3>")
	)
	(segment
		(start 162.237674 -229.253288)
		(end 166.00805 -229.253288)
		(width 0.16002)
		(layer "In4.Cu")
		(net "M_J_CPU1_SA_DQS_DP<3>")
	)
	(segment
		(start 145.794222 -241.493802)
		(end 146.36496 -240.923064)
		(width 0.09525)
		(layer "In4.Cu")
		(net "M_J_CPU1_SA_DQS_DP<3>")
	)
	(segment
		(start 143.546068 -241.569494)
		(end 143.55445 -241.57432)
		(width 0.09525)
		(layer "In4.Cu")
		(net "M_J_CPU1_SA_DQS_DP<3>")
	)
	(segment
		(start 184.622694 -228.06025)
		(end 185.079132 -228.516688)
		(width 0.16002)
		(layer "In4.Cu")
		(net "M_J_CPU1_SA_DQS_DP<3>")
	)
	(arc
		(start 136.97458 -241.57432)
		(mid 137.159612 -241.620234)
		(end 137.343388 -241.569494)
		(width 0.09525)
		(layer "In4.Cu")
		(net "M_J_CPU1_SA_DQS_DP<3>")
	)
	(arc
		(start 133.214618 -241.57432)
		(mid 133.39965 -241.620234)
		(end 133.583426 -241.569494)
		(width 0.09525)
		(layer "In4.Cu")
		(net "M_J_CPU1_SA_DQS_DP<3>")
	)
	(arc
		(start 133.583426 -241.569494)
		(mid 133.864858 -241.493739)
		(end 134.14629 -241.569494)
		(width 0.09525)
		(layer "In4.Cu")
		(net "M_J_CPU1_SA_DQS_DP<3>")
	)
	(arc
		(start 144.851882 -241.576352)
		(mid 144.992608 -241.514841)
		(end 145.144744 -241.493802)
		(width 0.09525)
		(layer "In4.Cu")
		(net "M_J_CPU1_SA_DQS_DP<3>")
	)
	(arc
		(start 132.709412 -241.536474)
		(mid 132.71966 -241.532311)
		(end 132.729986 -241.528346)
		(width 0.09525)
		(layer "In4.Cu")
		(net "M_J_CPU1_SA_DQS_DP<3>")
	)
	(arc
		(start 137.914634 -241.57432)
		(mid 138.099666 -241.620234)
		(end 138.283442 -241.569494)
		(width 0.09525)
		(layer "In4.Cu")
		(net "M_J_CPU1_SA_DQS_DP<3>")
	)
	(arc
		(start 141.10335 -241.569494)
		(mid 141.384782 -241.493739)
		(end 141.666214 -241.569494)
		(width 0.09525)
		(layer "In4.Cu")
		(net "M_J_CPU1_SA_DQS_DP<3>")
	)
	(arc
		(start 140.72616 -241.569494)
		(mid 140.909935 -241.620266)
		(end 141.094968 -241.57432)
		(width 0.09525)
		(layer "In4.Cu")
		(net "M_J_CPU1_SA_DQS_DP<3>")
	)
	(arc
		(start 144.486884 -241.569494)
		(mid 144.6685 -241.620231)
		(end 144.851882 -241.576352)
		(width 0.09525)
		(layer "In4.Cu")
		(net "M_J_CPU1_SA_DQS_DP<3>")
	)
	(arc
		(start 137.343388 -241.569494)
		(mid 137.62482 -241.493739)
		(end 137.906252 -241.569494)
		(width 0.09525)
		(layer "In4.Cu")
		(net "M_J_CPU1_SA_DQS_DP<3>")
	)
	(arc
		(start 142.983204 -241.569494)
		(mid 143.264636 -241.493739)
		(end 143.546068 -241.569494)
		(width 0.09525)
		(layer "In4.Cu")
		(net "M_J_CPU1_SA_DQS_DP<3>")
	)
	(arc
		(start 136.403334 -241.569494)
		(mid 136.684766 -241.493739)
		(end 136.966198 -241.569494)
		(width 0.09525)
		(layer "In4.Cu")
		(net "M_J_CPU1_SA_DQS_DP<3>")
	)
	(arc
		(start 132.729986 -241.528346)
		(mid 132.972728 -241.495576)
		(end 133.206236 -241.569494)
		(width 0.09525)
		(layer "In4.Cu")
		(net "M_J_CPU1_SA_DQS_DP<3>")
	)
	(arc
		(start 139.223242 -241.569494)
		(mid 139.504674 -241.493739)
		(end 139.786106 -241.569494)
		(width 0.09525)
		(layer "In4.Cu")
		(net "M_J_CPU1_SA_DQS_DP<3>")
	)
	(arc
		(start 134.523226 -241.569494)
		(mid 134.804658 -241.493739)
		(end 135.08609 -241.569494)
		(width 0.09525)
		(layer "In4.Cu")
		(net "M_J_CPU1_SA_DQS_DP<3>")
	)
	(arc
		(start 135.08609 -241.569494)
		(mid 135.269865 -241.620266)
		(end 135.454898 -241.57432)
		(width 0.09525)
		(layer "In4.Cu")
		(net "M_J_CPU1_SA_DQS_DP<3>")
	)
	(arc
		(start 143.55445 -241.57432)
		(mid 143.739736 -241.620356)
		(end 143.923766 -241.569494)
		(width 0.09525)
		(layer "In4.Cu")
		(net "M_J_CPU1_SA_DQS_DP<3>")
	)
	(arc
		(start 138.846306 -241.569494)
		(mid 139.034774 -241.620171)
		(end 139.223242 -241.569494)
		(width 0.09525)
		(layer "In4.Cu")
		(net "M_J_CPU1_SA_DQS_DP<3>")
	)
	(arc
		(start 135.46328 -241.569494)
		(mid 135.744712 -241.493739)
		(end 136.026144 -241.569494)
		(width 0.09525)
		(layer "In4.Cu")
		(net "M_J_CPU1_SA_DQS_DP<3>")
	)
	(arc
		(start 139.786106 -241.569494)
		(mid 139.969881 -241.620266)
		(end 140.154914 -241.57432)
		(width 0.09525)
		(layer "In4.Cu")
		(net "M_J_CPU1_SA_DQS_DP<3>")
	)
	(arc
		(start 143.923766 -241.569494)
		(mid 144.199309 -241.493645)
		(end 144.47647 -241.563398)
		(width 0.09525)
		(layer "In4.Cu")
		(net "M_J_CPU1_SA_DQS_DP<3>")
	)
	(arc
		(start 141.674596 -241.57432)
		(mid 141.859628 -241.620234)
		(end 142.043404 -241.569494)
		(width 0.09525)
		(layer "In4.Cu")
		(net "M_J_CPU1_SA_DQS_DP<3>")
	)
	(arc
		(start 136.026144 -241.569494)
		(mid 136.209919 -241.620266)
		(end 136.394952 -241.57432)
		(width 0.09525)
		(layer "In4.Cu")
		(net "M_J_CPU1_SA_DQS_DP<3>")
	)
	(arc
		(start 134.14629 -241.569494)
		(mid 134.334758 -241.620171)
		(end 134.523226 -241.569494)
		(width 0.09525)
		(layer "In4.Cu")
		(net "M_J_CPU1_SA_DQS_DP<3>")
	)
	(arc
		(start 140.163296 -241.569494)
		(mid 140.444728 -241.493739)
		(end 140.72616 -241.569494)
		(width 0.09525)
		(layer "In4.Cu")
		(net "M_J_CPU1_SA_DQS_DP<3>")
	)
	(arc
		(start 142.606268 -241.569494)
		(mid 142.794736 -241.620171)
		(end 142.983204 -241.569494)
		(width 0.09525)
		(layer "In4.Cu")
		(net "M_J_CPU1_SA_DQS_DP<3>")
	)
	(arc
		(start 138.283442 -241.569494)
		(mid 138.564874 -241.493739)
		(end 138.846306 -241.569494)
		(width 0.09525)
		(layer "In4.Cu")
		(net "M_J_CPU1_SA_DQS_DP<3>")
	)
	(arc
		(start 142.043404 -241.569494)
		(mid 142.324836 -241.493739)
		(end 142.606268 -241.569494)
		(width 0.09525)
		(layer "In4.Cu")
		(net "M_J_CPU1_SA_DQS_DP<3>")
	)
	(segment
		(start 131.987798 -236.650276)
		(end 132.45465 -236.384338)
		(width 0.12954)
		(layer "F.Cu")
		(net "M_J_CPU1_SA_DQS_DP<2>")
	)
	(segment
		(start 144.485868 -236.709458)
		(end 144.49425 -236.714284)
		(width 0.09525)
		(layer "In4.Cu")
		(net "M_J_CPU1_SA_DQS_DP<2>")
	)
	(segment
		(start 164.970206 -219.580206)
		(end 165.293294 -219.903294)
		(width 0.16002)
		(layer "In4.Cu")
		(net "M_J_CPU1_SA_DQS_DP<2>")
	)
	(segment
		(start 141.094968 -236.714284)
		(end 141.10335 -236.709458)
		(width 0.09525)
		(layer "In4.Cu")
		(net "M_J_CPU1_SA_DQS_DP<2>")
	)
	(segment
		(start 145.412206 -236.570266)
		(end 146.500596 -235.481876)
		(width 0.09525)
		(layer "In4.Cu")
		(net "M_J_CPU1_SA_DQS_DP<2>")
	)
	(segment
		(start 145.1991 -236.570266)
		(end 145.412206 -236.570266)
		(width 0.09525)
		(layer "In4.Cu")
		(net "M_J_CPU1_SA_DQS_DP<2>")
	)
	(segment
		(start 165.293294 -219.903294)
		(end 166.00805 -219.903294)
		(width 0.16002)
		(layer "In4.Cu")
		(net "M_J_CPU1_SA_DQS_DP<2>")
	)
	(segment
		(start 180.54193 -219.936314)
		(end 181.074314 -219.936314)
		(width 0.16002)
		(layer "In4.Cu")
		(net "M_J_CPU1_SA_DQS_DP<2>")
	)
	(segment
		(start 142.955264 -236.72419)
		(end 142.96898 -236.71784)
		(width 0.09525)
		(layer "In4.Cu")
		(net "M_J_CPU1_SA_DQS_DP<2>")
	)
	(segment
		(start 155.184094 -225.882962)
		(end 161.48685 -219.580206)
		(width 0.16002)
		(layer "In4.Cu")
		(net "M_J_CPU1_SA_DQS_DP<2>")
	)
	(segment
		(start 181.074314 -219.936314)
		(end 181.843934 -219.166694)
		(width 0.16002)
		(layer "In4.Cu")
		(net "M_J_CPU1_SA_DQS_DP<2>")
	)
	(segment
		(start 187.15863 -219.166694)
		(end 187.88253 -219.890594)
		(width 0.16002)
		(layer "In4.Cu")
		(net "M_J_CPU1_SA_DQS_DP<2>")
	)
	(segment
		(start 185.079132 -219.166694)
		(end 187.15863 -219.166694)
		(width 0.16002)
		(layer "In4.Cu")
		(net "M_J_CPU1_SA_DQS_DP<2>")
	)
	(segment
		(start 143.923258 -236.709458)
		(end 143.933672 -236.703362)
		(width 0.09525)
		(layer "In4.Cu")
		(net "M_J_CPU1_SA_DQS_DP<2>")
	)
	(segment
		(start 181.843934 -219.166694)
		(end 182.552848 -219.166694)
		(width 0.16002)
		(layer "In4.Cu")
		(net "M_J_CPU1_SA_DQS_DP<2>")
	)
	(segment
		(start 188.993526 -219.709238)
		(end 190.886334 -219.709238)
		(width 0.16002)
		(layer "In4.Cu")
		(net "M_J_CPU1_SA_DQS_DP<2>")
	)
	(segment
		(start 147.885658 -234.567476)
		(end 147.90928 -234.567476)
		(width 0.09525)
		(layer "In4.Cu")
		(net "M_J_CPU1_SA_DQS_DP<2>")
	)
	(segment
		(start 174.183802 -219.237814)
		(end 175.01235 -219.237814)
		(width 0.16002)
		(layer "In4.Cu")
		(net "M_J_CPU1_SA_DQS_DP<2>")
	)
	(segment
		(start 183.009286 -218.710256)
		(end 184.622694 -218.710256)
		(width 0.16002)
		(layer "In4.Cu")
		(net "M_J_CPU1_SA_DQS_DP<2>")
	)
	(segment
		(start 188.81217 -219.890594)
		(end 188.993526 -219.709238)
		(width 0.16002)
		(layer "In4.Cu")
		(net "M_J_CPU1_SA_DQS_DP<2>")
	)
	(segment
		(start 175.539908 -218.710256)
		(end 177.137568 -218.710256)
		(width 0.16002)
		(layer "In4.Cu")
		(net "M_J_CPU1_SA_DQS_DP<2>")
	)
	(segment
		(start 147.569428 -234.626658)
		(end 147.826476 -234.626658)
		(width 0.09525)
		(layer "In4.Cu")
		(net "M_J_CPU1_SA_DQS_DP<2>")
	)
	(segment
		(start 136.394952 -236.714284)
		(end 136.403334 -236.709458)
		(width 0.09525)
		(layer "In4.Cu")
		(net "M_J_CPU1_SA_DQS_DP<2>")
	)
	(segment
		(start 147.826476 -234.626658)
		(end 147.885658 -234.567476)
		(width 0.09525)
		(layer "In4.Cu")
		(net "M_J_CPU1_SA_DQS_DP<2>")
	)
	(segment
		(start 166.00805 -219.903294)
		(end 166.88181 -219.029534)
		(width 0.16002)
		(layer "In4.Cu")
		(net "M_J_CPU1_SA_DQS_DP<2>")
	)
	(segment
		(start 190.886334 -219.709238)
		(end 191.160146 -219.435426)
		(width 0.16002)
		(layer "In4.Cu")
		(net "M_J_CPU1_SA_DQS_DP<2>")
	)
	(segment
		(start 187.88253 -219.890594)
		(end 188.81217 -219.890594)
		(width 0.16002)
		(layer "In4.Cu")
		(net "M_J_CPU1_SA_DQS_DP<2>")
	)
	(segment
		(start 177.137568 -218.710256)
		(end 177.987452 -219.56014)
		(width 0.16002)
		(layer "In4.Cu")
		(net "M_J_CPU1_SA_DQS_DP<2>")
	)
	(segment
		(start 137.906252 -236.709458)
		(end 137.914634 -236.714284)
		(width 0.09525)
		(layer "In4.Cu")
		(net "M_J_CPU1_SA_DQS_DP<2>")
	)
	(segment
		(start 173.505622 -219.915994)
		(end 174.183802 -219.237814)
		(width 0.16002)
		(layer "In4.Cu")
		(net "M_J_CPU1_SA_DQS_DP<2>")
	)
	(segment
		(start 175.01235 -219.237814)
		(end 175.539908 -218.710256)
		(width 0.16002)
		(layer "In4.Cu")
		(net "M_J_CPU1_SA_DQS_DP<2>")
	)
	(segment
		(start 147.90928 -234.567476)
		(end 148.909786 -234.567476)
		(width 0.16002)
		(layer "In4.Cu")
		(net "M_J_CPU1_SA_DQS_DP<2>")
	)
	(segment
		(start 170.661076 -219.56014)
		(end 172.568616 -219.56014)
		(width 0.16002)
		(layer "In4.Cu")
		(net "M_J_CPU1_SA_DQS_DP<2>")
	)
	(segment
		(start 172.92447 -219.915994)
		(end 173.505622 -219.915994)
		(width 0.16002)
		(layer "In4.Cu")
		(net "M_J_CPU1_SA_DQS_DP<2>")
	)
	(segment
		(start 132.608574 -236.649768)
		(end 132.709412 -236.676438)
		(width 0.09525)
		(layer "In4.Cu")
		(net "M_J_CPU1_SA_DQS_DP<2>")
	)
	(segment
		(start 172.568616 -219.56014)
		(end 172.92447 -219.915994)
		(width 0.16002)
		(layer "In4.Cu")
		(net "M_J_CPU1_SA_DQS_DP<2>")
	)
	(segment
		(start 177.987452 -219.56014)
		(end 180.165756 -219.56014)
		(width 0.16002)
		(layer "In4.Cu")
		(net "M_J_CPU1_SA_DQS_DP<2>")
	)
	(segment
		(start 155.184094 -228.293168)
		(end 155.184094 -225.882962)
		(width 0.16002)
		(layer "In4.Cu")
		(net "M_J_CPU1_SA_DQS_DP<2>")
	)
	(segment
		(start 166.88181 -219.029534)
		(end 170.13047 -219.029534)
		(width 0.16002)
		(layer "In4.Cu")
		(net "M_J_CPU1_SA_DQS_DP<2>")
	)
	(segment
		(start 146.86153 -235.481876)
		(end 147.569428 -234.626658)
		(width 0.09525)
		(layer "In4.Cu")
		(net "M_J_CPU1_SA_DQS_DP<2>")
	)
	(segment
		(start 180.165756 -219.56014)
		(end 180.54193 -219.936314)
		(width 0.16002)
		(layer "In4.Cu")
		(net "M_J_CPU1_SA_DQS_DP<2>")
	)
	(segment
		(start 143.914876 -236.714284)
		(end 143.923258 -236.709458)
		(width 0.09525)
		(layer "In4.Cu")
		(net "M_J_CPU1_SA_DQS_DP<2>")
	)
	(segment
		(start 136.966198 -236.709458)
		(end 136.97458 -236.714284)
		(width 0.09525)
		(layer "In4.Cu")
		(net "M_J_CPU1_SA_DQS_DP<2>")
	)
	(segment
		(start 184.622694 -218.710256)
		(end 185.079132 -219.166694)
		(width 0.16002)
		(layer "In4.Cu")
		(net "M_J_CPU1_SA_DQS_DP<2>")
	)
	(segment
		(start 140.154914 -236.714284)
		(end 140.163296 -236.709458)
		(width 0.09525)
		(layer "In4.Cu")
		(net "M_J_CPU1_SA_DQS_DP<2>")
	)
	(segment
		(start 161.48685 -219.580206)
		(end 164.970206 -219.580206)
		(width 0.16002)
		(layer "In4.Cu")
		(net "M_J_CPU1_SA_DQS_DP<2>")
	)
	(segment
		(start 148.909786 -234.567476)
		(end 155.184094 -228.293168)
		(width 0.16002)
		(layer "In4.Cu")
		(net "M_J_CPU1_SA_DQS_DP<2>")
	)
	(segment
		(start 132.45465 -236.384338)
		(end 132.608574 -236.649768)
		(width 0.09525)
		(layer "In4.Cu")
		(net "M_J_CPU1_SA_DQS_DP<2>")
	)
	(segment
		(start 182.552848 -219.166694)
		(end 183.009286 -218.710256)
		(width 0.16002)
		(layer "In4.Cu")
		(net "M_J_CPU1_SA_DQS_DP<2>")
	)
	(segment
		(start 142.96898 -236.71784)
		(end 142.983204 -236.709458)
		(width 0.09525)
		(layer "In4.Cu")
		(net "M_J_CPU1_SA_DQS_DP<2>")
	)
	(segment
		(start 141.666214 -236.709458)
		(end 141.674596 -236.714284)
		(width 0.09525)
		(layer "In4.Cu")
		(net "M_J_CPU1_SA_DQS_DP<2>")
	)
	(segment
		(start 135.454898 -236.714284)
		(end 135.46328 -236.709458)
		(width 0.09525)
		(layer "In4.Cu")
		(net "M_J_CPU1_SA_DQS_DP<2>")
	)
	(segment
		(start 133.206236 -236.709458)
		(end 133.214618 -236.714284)
		(width 0.09525)
		(layer "In4.Cu")
		(net "M_J_CPU1_SA_DQS_DP<2>")
	)
	(segment
		(start 170.13047 -219.029534)
		(end 170.661076 -219.56014)
		(width 0.16002)
		(layer "In4.Cu")
		(net "M_J_CPU1_SA_DQS_DP<2>")
	)
	(segment
		(start 146.500596 -235.481876)
		(end 146.86153 -235.481876)
		(width 0.09525)
		(layer "In4.Cu")
		(net "M_J_CPU1_SA_DQS_DP<2>")
	)
	(segment
		(start 144.863058 -236.709458)
		(end 145.1991 -236.570266)
		(width 0.09525)
		(layer "In4.Cu")
		(net "M_J_CPU1_SA_DQS_DP<2>")
	)
	(arc
		(start 142.043404 -236.709458)
		(mid 142.324836 -236.633703)
		(end 142.606268 -236.709458)
		(width 0.09525)
		(layer "In4.Cu")
		(net "M_J_CPU1_SA_DQS_DP<2>")
	)
	(arc
		(start 141.674596 -236.714284)
		(mid 141.859628 -236.760198)
		(end 142.043404 -236.709458)
		(width 0.09525)
		(layer "In4.Cu")
		(net "M_J_CPU1_SA_DQS_DP<2>")
	)
	(arc
		(start 132.709412 -236.676438)
		(mid 132.71966 -236.672275)
		(end 132.729986 -236.66831)
		(width 0.09525)
		(layer "In4.Cu")
		(net "M_J_CPU1_SA_DQS_DP<2>")
	)
	(arc
		(start 137.343388 -236.709458)
		(mid 137.62482 -236.633703)
		(end 137.906252 -236.709458)
		(width 0.09525)
		(layer "In4.Cu")
		(net "M_J_CPU1_SA_DQS_DP<2>")
	)
	(arc
		(start 140.72616 -236.709458)
		(mid 140.909935 -236.76023)
		(end 141.094968 -236.714284)
		(width 0.09525)
		(layer "In4.Cu")
		(net "M_J_CPU1_SA_DQS_DP<2>")
	)
	(arc
		(start 132.729986 -236.66831)
		(mid 132.972728 -236.63554)
		(end 133.206236 -236.709458)
		(width 0.09525)
		(layer "In4.Cu")
		(net "M_J_CPU1_SA_DQS_DP<2>")
	)
	(arc
		(start 135.08609 -236.709458)
		(mid 135.269865 -236.76023)
		(end 135.454898 -236.714284)
		(width 0.09525)
		(layer "In4.Cu")
		(net "M_J_CPU1_SA_DQS_DP<2>")
	)
	(arc
		(start 140.163296 -236.709458)
		(mid 140.444728 -236.633703)
		(end 140.72616 -236.709458)
		(width 0.09525)
		(layer "In4.Cu")
		(net "M_J_CPU1_SA_DQS_DP<2>")
	)
	(arc
		(start 135.46328 -236.709458)
		(mid 135.744712 -236.633703)
		(end 136.026144 -236.709458)
		(width 0.09525)
		(layer "In4.Cu")
		(net "M_J_CPU1_SA_DQS_DP<2>")
	)
	(arc
		(start 138.283442 -236.709458)
		(mid 138.564874 -236.633703)
		(end 138.846306 -236.709458)
		(width 0.09525)
		(layer "In4.Cu")
		(net "M_J_CPU1_SA_DQS_DP<2>")
	)
	(arc
		(start 144.49425 -236.714284)
		(mid 144.679282 -236.760198)
		(end 144.863058 -236.709458)
		(width 0.09525)
		(layer "In4.Cu")
		(net "M_J_CPU1_SA_DQS_DP<2>")
	)
	(arc
		(start 134.523226 -236.709458)
		(mid 134.804658 -236.633703)
		(end 135.08609 -236.709458)
		(width 0.09525)
		(layer "In4.Cu")
		(net "M_J_CPU1_SA_DQS_DP<2>")
	)
	(arc
		(start 139.786106 -236.709458)
		(mid 139.969881 -236.76023)
		(end 140.154914 -236.714284)
		(width 0.09525)
		(layer "In4.Cu")
		(net "M_J_CPU1_SA_DQS_DP<2>")
	)
	(arc
		(start 138.846306 -236.709458)
		(mid 139.034774 -236.760135)
		(end 139.223242 -236.709458)
		(width 0.09525)
		(layer "In4.Cu")
		(net "M_J_CPU1_SA_DQS_DP<2>")
	)
	(arc
		(start 139.223242 -236.709458)
		(mid 139.504674 -236.633703)
		(end 139.786106 -236.709458)
		(width 0.09525)
		(layer "In4.Cu")
		(net "M_J_CPU1_SA_DQS_DP<2>")
	)
	(arc
		(start 136.97458 -236.714284)
		(mid 137.159612 -236.760198)
		(end 137.343388 -236.709458)
		(width 0.09525)
		(layer "In4.Cu")
		(net "M_J_CPU1_SA_DQS_DP<2>")
	)
	(arc
		(start 133.583426 -236.709458)
		(mid 133.864858 -236.633703)
		(end 134.14629 -236.709458)
		(width 0.09525)
		(layer "In4.Cu")
		(net "M_J_CPU1_SA_DQS_DP<2>")
	)
	(arc
		(start 143.933672 -236.703362)
		(mid 144.21058 -236.633685)
		(end 144.485868 -236.709458)
		(width 0.09525)
		(layer "In4.Cu")
		(net "M_J_CPU1_SA_DQS_DP<2>")
	)
	(arc
		(start 136.403334 -236.709458)
		(mid 136.684766 -236.633703)
		(end 136.966198 -236.709458)
		(width 0.09525)
		(layer "In4.Cu")
		(net "M_J_CPU1_SA_DQS_DP<2>")
	)
	(arc
		(start 133.214618 -236.714284)
		(mid 133.39965 -236.760198)
		(end 133.583426 -236.709458)
		(width 0.09525)
		(layer "In4.Cu")
		(net "M_J_CPU1_SA_DQS_DP<2>")
	)
	(arc
		(start 134.14629 -236.709458)
		(mid 134.334758 -236.760135)
		(end 134.523226 -236.709458)
		(width 0.09525)
		(layer "In4.Cu")
		(net "M_J_CPU1_SA_DQS_DP<2>")
	)
	(arc
		(start 142.606268 -236.709458)
		(mid 142.778944 -236.759803)
		(end 142.955264 -236.72419)
		(width 0.09525)
		(layer "In4.Cu")
		(net "M_J_CPU1_SA_DQS_DP<2>")
	)
	(arc
		(start 137.914634 -236.714284)
		(mid 138.099666 -236.760198)
		(end 138.283442 -236.709458)
		(width 0.09525)
		(layer "In4.Cu")
		(net "M_J_CPU1_SA_DQS_DP<2>")
	)
	(arc
		(start 143.546068 -236.709458)
		(mid 143.729843 -236.76023)
		(end 143.914876 -236.714284)
		(width 0.09525)
		(layer "In4.Cu")
		(net "M_J_CPU1_SA_DQS_DP<2>")
	)
	(arc
		(start 141.10335 -236.709458)
		(mid 141.384782 -236.633703)
		(end 141.666214 -236.709458)
		(width 0.09525)
		(layer "In4.Cu")
		(net "M_J_CPU1_SA_DQS_DP<2>")
	)
	(arc
		(start 136.026144 -236.709458)
		(mid 136.209919 -236.76023)
		(end 136.394952 -236.714284)
		(width 0.09525)
		(layer "In4.Cu")
		(net "M_J_CPU1_SA_DQS_DP<2>")
	)
	(arc
		(start 142.983204 -236.709458)
		(mid 143.264636 -236.633703)
		(end 143.546068 -236.709458)
		(width 0.09525)
		(layer "In4.Cu")
		(net "M_J_CPU1_SA_DQS_DP<2>")
	)
	(segment
		(start 131.987798 -231.79024)
		(end 132.45465 -231.524302)
		(width 0.12954)
		(layer "F.Cu")
		(net "M_J_CPU1_SA_DQS_DP<1>")
	)
	(segment
		(start 173.505622 -210.566)
		(end 174.183802 -209.88782)
		(width 0.16002)
		(layer "In4.Cu")
		(net "M_J_CPU1_SA_DQS_DP<1>")
	)
	(segment
		(start 147.070318 -228.355398)
		(end 147.070318 -227.986082)
		(width 0.09525)
		(layer "In4.Cu")
		(net "M_J_CPU1_SA_DQS_DP<1>")
	)
	(segment
		(start 149.646894 -225.325686)
		(end 149.646894 -221.79153)
		(width 0.16002)
		(layer "In4.Cu")
		(net "M_J_CPU1_SA_DQS_DP<1>")
	)
	(segment
		(start 136.394952 -231.854248)
		(end 136.403334 -231.849422)
		(width 0.09525)
		(layer "In4.Cu")
		(net "M_J_CPU1_SA_DQS_DP<1>")
	)
	(segment
		(start 181.074314 -210.58632)
		(end 181.733952 -209.926682)
		(width 0.16002)
		(layer "In4.Cu")
		(net "M_J_CPU1_SA_DQS_DP<1>")
	)
	(segment
		(start 174.183802 -209.88782)
		(end 175.01235 -209.88782)
		(width 0.16002)
		(layer "In4.Cu")
		(net "M_J_CPU1_SA_DQS_DP<1>")
	)
	(segment
		(start 175.539908 -209.360262)
		(end 177.137568 -209.360262)
		(width 0.16002)
		(layer "In4.Cu")
		(net "M_J_CPU1_SA_DQS_DP<1>")
	)
	(segment
		(start 143.914876 -231.854248)
		(end 143.923258 -231.849422)
		(width 0.09525)
		(layer "In4.Cu")
		(net "M_J_CPU1_SA_DQS_DP<1>")
	)
	(segment
		(start 145.307812 -230.117904)
		(end 147.070318 -228.355398)
		(width 0.09525)
		(layer "In4.Cu")
		(net "M_J_CPU1_SA_DQS_DP<1>")
	)
	(segment
		(start 149.646894 -221.79153)
		(end 161.190178 -210.248246)
		(width 0.16002)
		(layer "In4.Cu")
		(net "M_J_CPU1_SA_DQS_DP<1>")
	)
	(segment
		(start 147.42668 -227.5459)
		(end 147.443444 -227.529136)
		(width 0.09525)
		(layer "In4.Cu")
		(net "M_J_CPU1_SA_DQS_DP<1>")
	)
	(segment
		(start 141.666214 -231.849422)
		(end 141.674596 -231.854248)
		(width 0.09525)
		(layer "In4.Cu")
		(net "M_J_CPU1_SA_DQS_DP<1>")
	)
	(segment
		(start 147.443444 -227.529136)
		(end 149.646894 -225.325686)
		(width 0.16002)
		(layer "In4.Cu")
		(net "M_J_CPU1_SA_DQS_DP<1>")
	)
	(segment
		(start 161.190178 -210.248246)
		(end 165.099492 -210.248246)
		(width 0.16002)
		(layer "In4.Cu")
		(net "M_J_CPU1_SA_DQS_DP<1>")
	)
	(segment
		(start 170.661076 -210.210146)
		(end 172.568616 -210.210146)
		(width 0.16002)
		(layer "In4.Cu")
		(net "M_J_CPU1_SA_DQS_DP<1>")
	)
	(segment
		(start 177.137568 -209.360262)
		(end 177.987452 -210.210146)
		(width 0.16002)
		(layer "In4.Cu")
		(net "M_J_CPU1_SA_DQS_DP<1>")
	)
	(segment
		(start 166.88181 -209.67954)
		(end 170.13047 -209.67954)
		(width 0.16002)
		(layer "In4.Cu")
		(net "M_J_CPU1_SA_DQS_DP<1>")
	)
	(segment
		(start 172.92447 -210.566)
		(end 173.505622 -210.566)
		(width 0.16002)
		(layer "In4.Cu")
		(net "M_J_CPU1_SA_DQS_DP<1>")
	)
	(segment
		(start 184.062116 -209.360262)
		(end 185.164222 -209.8167)
		(width 0.16002)
		(layer "In4.Cu")
		(net "M_J_CPU1_SA_DQS_DP<1>")
	)
	(segment
		(start 165.099492 -210.248246)
		(end 165.404546 -210.5533)
		(width 0.16002)
		(layer "In4.Cu")
		(net "M_J_CPU1_SA_DQS_DP<1>")
	)
	(segment
		(start 181.733952 -209.926682)
		(end 183.101234 -209.360262)
		(width 0.16002)
		(layer "In4.Cu")
		(net "M_J_CPU1_SA_DQS_DP<1>")
	)
	(segment
		(start 136.966198 -231.849422)
		(end 136.97458 -231.854248)
		(width 0.09525)
		(layer "In4.Cu")
		(net "M_J_CPU1_SA_DQS_DP<1>")
	)
	(segment
		(start 137.906252 -231.849422)
		(end 137.914634 -231.854248)
		(width 0.09525)
		(layer "In4.Cu")
		(net "M_J_CPU1_SA_DQS_DP<1>")
	)
	(segment
		(start 187.88253 -210.5406)
		(end 188.81217 -210.5406)
		(width 0.16002)
		(layer "In4.Cu")
		(net "M_J_CPU1_SA_DQS_DP<1>")
	)
	(segment
		(start 135.454898 -231.854248)
		(end 135.46328 -231.849422)
		(width 0.09525)
		(layer "In4.Cu")
		(net "M_J_CPU1_SA_DQS_DP<1>")
	)
	(segment
		(start 144.000728 -231.79024)
		(end 144.460468 -231.3305)
		(width 0.09525)
		(layer "In4.Cu")
		(net "M_J_CPU1_SA_DQS_DP<1>")
	)
	(segment
		(start 180.165756 -210.210146)
		(end 180.54193 -210.58632)
		(width 0.16002)
		(layer "In4.Cu")
		(net "M_J_CPU1_SA_DQS_DP<1>")
	)
	(segment
		(start 185.164222 -209.8167)
		(end 187.15863 -209.8167)
		(width 0.16002)
		(layer "In4.Cu")
		(net "M_J_CPU1_SA_DQS_DP<1>")
	)
	(segment
		(start 144.460468 -230.607616)
		(end 144.95018 -230.117904)
		(width 0.09525)
		(layer "In4.Cu")
		(net "M_J_CPU1_SA_DQS_DP<1>")
	)
	(segment
		(start 147.070318 -227.986082)
		(end 147.42668 -227.62972)
		(width 0.09525)
		(layer "In4.Cu")
		(net "M_J_CPU1_SA_DQS_DP<1>")
	)
	(segment
		(start 172.568616 -210.210146)
		(end 172.92447 -210.566)
		(width 0.16002)
		(layer "In4.Cu")
		(net "M_J_CPU1_SA_DQS_DP<1>")
	)
	(segment
		(start 165.404546 -210.5533)
		(end 166.00805 -210.5533)
		(width 0.16002)
		(layer "In4.Cu")
		(net "M_J_CPU1_SA_DQS_DP<1>")
	)
	(segment
		(start 190.886334 -210.359244)
		(end 191.160146 -210.085432)
		(width 0.16002)
		(layer "In4.Cu")
		(net "M_J_CPU1_SA_DQS_DP<1>")
	)
	(segment
		(start 180.54193 -210.58632)
		(end 181.074314 -210.58632)
		(width 0.16002)
		(layer "In4.Cu")
		(net "M_J_CPU1_SA_DQS_DP<1>")
	)
	(segment
		(start 132.45465 -231.524302)
		(end 132.608574 -231.789732)
		(width 0.09525)
		(layer "In4.Cu")
		(net "M_J_CPU1_SA_DQS_DP<1>")
	)
	(segment
		(start 140.154914 -231.854248)
		(end 140.163296 -231.849422)
		(width 0.09525)
		(layer "In4.Cu")
		(net "M_J_CPU1_SA_DQS_DP<1>")
	)
	(segment
		(start 187.15863 -209.8167)
		(end 187.88253 -210.5406)
		(width 0.16002)
		(layer "In4.Cu")
		(net "M_J_CPU1_SA_DQS_DP<1>")
	)
	(segment
		(start 177.987452 -210.210146)
		(end 180.165756 -210.210146)
		(width 0.16002)
		(layer "In4.Cu")
		(net "M_J_CPU1_SA_DQS_DP<1>")
	)
	(segment
		(start 188.81217 -210.5406)
		(end 188.993526 -210.359244)
		(width 0.16002)
		(layer "In4.Cu")
		(net "M_J_CPU1_SA_DQS_DP<1>")
	)
	(segment
		(start 141.094968 -231.854248)
		(end 141.10335 -231.849422)
		(width 0.09525)
		(layer "In4.Cu")
		(net "M_J_CPU1_SA_DQS_DP<1>")
	)
	(segment
		(start 147.42668 -227.62972)
		(end 147.42668 -227.5459)
		(width 0.09525)
		(layer "In4.Cu")
		(net "M_J_CPU1_SA_DQS_DP<1>")
	)
	(segment
		(start 133.206236 -231.849422)
		(end 133.214618 -231.854248)
		(width 0.09525)
		(layer "In4.Cu")
		(net "M_J_CPU1_SA_DQS_DP<1>")
	)
	(segment
		(start 132.608574 -231.789732)
		(end 132.709412 -231.816402)
		(width 0.09525)
		(layer "In4.Cu")
		(net "M_J_CPU1_SA_DQS_DP<1>")
	)
	(segment
		(start 144.95018 -230.117904)
		(end 145.307812 -230.117904)
		(width 0.09525)
		(layer "In4.Cu")
		(net "M_J_CPU1_SA_DQS_DP<1>")
	)
	(segment
		(start 188.993526 -210.359244)
		(end 190.886334 -210.359244)
		(width 0.16002)
		(layer "In4.Cu")
		(net "M_J_CPU1_SA_DQS_DP<1>")
	)
	(segment
		(start 170.13047 -209.67954)
		(end 170.661076 -210.210146)
		(width 0.16002)
		(layer "In4.Cu")
		(net "M_J_CPU1_SA_DQS_DP<1>")
	)
	(segment
		(start 175.01235 -209.88782)
		(end 175.539908 -209.360262)
		(width 0.16002)
		(layer "In4.Cu")
		(net "M_J_CPU1_SA_DQS_DP<1>")
	)
	(segment
		(start 144.460468 -231.3305)
		(end 144.460468 -230.607616)
		(width 0.09525)
		(layer "In4.Cu")
		(net "M_J_CPU1_SA_DQS_DP<1>")
	)
	(segment
		(start 166.00805 -210.5533)
		(end 166.88181 -209.67954)
		(width 0.16002)
		(layer "In4.Cu")
		(net "M_J_CPU1_SA_DQS_DP<1>")
	)
	(segment
		(start 183.101234 -209.360262)
		(end 184.062116 -209.360262)
		(width 0.16002)
		(layer "In4.Cu")
		(net "M_J_CPU1_SA_DQS_DP<1>")
	)
	(arc
		(start 139.223242 -231.849422)
		(mid 139.504674 -231.773667)
		(end 139.786106 -231.849422)
		(width 0.09525)
		(layer "In4.Cu")
		(net "M_J_CPU1_SA_DQS_DP<1>")
	)
	(arc
		(start 136.97458 -231.854248)
		(mid 137.159612 -231.900162)
		(end 137.343388 -231.849422)
		(width 0.09525)
		(layer "In4.Cu")
		(net "M_J_CPU1_SA_DQS_DP<1>")
	)
	(arc
		(start 136.026144 -231.849422)
		(mid 136.209919 -231.900194)
		(end 136.394952 -231.854248)
		(width 0.09525)
		(layer "In4.Cu")
		(net "M_J_CPU1_SA_DQS_DP<1>")
	)
	(arc
		(start 136.403334 -231.849422)
		(mid 136.684766 -231.773667)
		(end 136.966198 -231.849422)
		(width 0.09525)
		(layer "In4.Cu")
		(net "M_J_CPU1_SA_DQS_DP<1>")
	)
	(arc
		(start 135.46328 -231.849422)
		(mid 135.744712 -231.773667)
		(end 136.026144 -231.849422)
		(width 0.09525)
		(layer "In4.Cu")
		(net "M_J_CPU1_SA_DQS_DP<1>")
	)
	(arc
		(start 137.343388 -231.849422)
		(mid 137.62482 -231.773667)
		(end 137.906252 -231.849422)
		(width 0.09525)
		(layer "In4.Cu")
		(net "M_J_CPU1_SA_DQS_DP<1>")
	)
	(arc
		(start 133.214618 -231.854248)
		(mid 133.39965 -231.900162)
		(end 133.583426 -231.849422)
		(width 0.09525)
		(layer "In4.Cu")
		(net "M_J_CPU1_SA_DQS_DP<1>")
	)
	(arc
		(start 142.043404 -231.849422)
		(mid 142.324836 -231.773667)
		(end 142.606268 -231.849422)
		(width 0.09525)
		(layer "In4.Cu")
		(net "M_J_CPU1_SA_DQS_DP<1>")
	)
	(arc
		(start 134.14629 -231.849422)
		(mid 134.334758 -231.900099)
		(end 134.523226 -231.849422)
		(width 0.09525)
		(layer "In4.Cu")
		(net "M_J_CPU1_SA_DQS_DP<1>")
	)
	(arc
		(start 139.786106 -231.849422)
		(mid 139.969881 -231.900194)
		(end 140.154914 -231.854248)
		(width 0.09525)
		(layer "In4.Cu")
		(net "M_J_CPU1_SA_DQS_DP<1>")
	)
	(arc
		(start 133.583426 -231.849422)
		(mid 133.864858 -231.773667)
		(end 134.14629 -231.849422)
		(width 0.09525)
		(layer "In4.Cu")
		(net "M_J_CPU1_SA_DQS_DP<1>")
	)
	(arc
		(start 142.983204 -231.849422)
		(mid 143.264636 -231.773667)
		(end 143.546068 -231.849422)
		(width 0.09525)
		(layer "In4.Cu")
		(net "M_J_CPU1_SA_DQS_DP<1>")
	)
	(arc
		(start 141.10335 -231.849422)
		(mid 141.384782 -231.773667)
		(end 141.666214 -231.849422)
		(width 0.09525)
		(layer "In4.Cu")
		(net "M_J_CPU1_SA_DQS_DP<1>")
	)
	(arc
		(start 143.923258 -231.849422)
		(mid 143.96393 -231.822365)
		(end 144.000728 -231.79024)
		(width 0.09525)
		(layer "In4.Cu")
		(net "M_J_CPU1_SA_DQS_DP<1>")
	)
	(arc
		(start 141.674596 -231.854248)
		(mid 141.859628 -231.900162)
		(end 142.043404 -231.849422)
		(width 0.09525)
		(layer "In4.Cu")
		(net "M_J_CPU1_SA_DQS_DP<1>")
	)
	(arc
		(start 137.914634 -231.854248)
		(mid 138.099666 -231.900162)
		(end 138.283442 -231.849422)
		(width 0.09525)
		(layer "In4.Cu")
		(net "M_J_CPU1_SA_DQS_DP<1>")
	)
	(arc
		(start 135.08609 -231.849422)
		(mid 135.269865 -231.900194)
		(end 135.454898 -231.854248)
		(width 0.09525)
		(layer "In4.Cu")
		(net "M_J_CPU1_SA_DQS_DP<1>")
	)
	(arc
		(start 143.546068 -231.849422)
		(mid 143.729843 -231.900194)
		(end 143.914876 -231.854248)
		(width 0.09525)
		(layer "In4.Cu")
		(net "M_J_CPU1_SA_DQS_DP<1>")
	)
	(arc
		(start 138.283442 -231.849422)
		(mid 138.564874 -231.773667)
		(end 138.846306 -231.849422)
		(width 0.09525)
		(layer "In4.Cu")
		(net "M_J_CPU1_SA_DQS_DP<1>")
	)
	(arc
		(start 132.709412 -231.816402)
		(mid 132.961696 -231.774708)
		(end 133.206236 -231.849422)
		(width 0.09525)
		(layer "In4.Cu")
		(net "M_J_CPU1_SA_DQS_DP<1>")
	)
	(arc
		(start 140.163296 -231.849422)
		(mid 140.444728 -231.773667)
		(end 140.72616 -231.849422)
		(width 0.09525)
		(layer "In4.Cu")
		(net "M_J_CPU1_SA_DQS_DP<1>")
	)
	(arc
		(start 140.72616 -231.849422)
		(mid 140.909935 -231.900194)
		(end 141.094968 -231.854248)
		(width 0.09525)
		(layer "In4.Cu")
		(net "M_J_CPU1_SA_DQS_DP<1>")
	)
	(arc
		(start 134.523226 -231.849422)
		(mid 134.804658 -231.773667)
		(end 135.08609 -231.849422)
		(width 0.09525)
		(layer "In4.Cu")
		(net "M_J_CPU1_SA_DQS_DP<1>")
	)
	(arc
		(start 142.606268 -231.849422)
		(mid 142.794736 -231.900099)
		(end 142.983204 -231.849422)
		(width 0.09525)
		(layer "In4.Cu")
		(net "M_J_CPU1_SA_DQS_DP<1>")
	)
	(arc
		(start 138.846306 -231.849422)
		(mid 139.034774 -231.900099)
		(end 139.223242 -231.849422)
		(width 0.09525)
		(layer "In4.Cu")
		(net "M_J_CPU1_SA_DQS_DP<1>")
	)
	(segment
		(start 131.987798 -226.930458)
		(end 132.45465 -226.66452)
		(width 0.12954)
		(layer "F.Cu")
		(net "M_J_CPU1_SA_DQS_DP<0>")
	)
	(segment
		(start 142.475204 -224.58172)
		(end 142.513304 -224.559622)
		(width 0.09525)
		(layer "In4.Cu")
		(net "M_J_CPU1_SA_DQS_DP<0>")
	)
	(segment
		(start 143.886428 -222.15094)
		(end 143.923004 -222.129604)
		(width 0.09525)
		(layer "In4.Cu")
		(net "M_J_CPU1_SA_DQS_DP<0>")
	)
	(segment
		(start 142.005304 -225.391726)
		(end 142.043404 -225.369628)
		(width 0.09525)
		(layer "In4.Cu")
		(net "M_J_CPU1_SA_DQS_DP<0>")
	)
	(segment
		(start 166.88181 -200.329546)
		(end 170.13047 -200.329546)
		(width 0.16002)
		(layer "In4.Cu")
		(net "M_J_CPU1_SA_DQS_DP<0>")
	)
	(segment
		(start 182.552848 -200.466706)
		(end 183.009286 -200.010268)
		(width 0.16002)
		(layer "In4.Cu")
		(net "M_J_CPU1_SA_DQS_DP<0>")
	)
	(segment
		(start 170.13047 -200.329546)
		(end 170.661076 -200.860152)
		(width 0.16002)
		(layer "In4.Cu")
		(net "M_J_CPU1_SA_DQS_DP<0>")
	)
	(segment
		(start 175.01235 -200.537826)
		(end 175.539908 -200.010268)
		(width 0.16002)
		(layer "In4.Cu")
		(net "M_J_CPU1_SA_DQS_DP<0>")
	)
	(segment
		(start 142.983204 -223.749616)
		(end 143.015716 -223.73082)
		(width 0.09525)
		(layer "In4.Cu")
		(net "M_J_CPU1_SA_DQS_DP<0>")
	)
	(segment
		(start 187.15863 -200.466706)
		(end 187.88253 -201.190606)
		(width 0.16002)
		(layer "In4.Cu")
		(net "M_J_CPU1_SA_DQS_DP<0>")
	)
	(segment
		(start 164.62248 -200.622916)
		(end 165.20287 -201.203306)
		(width 0.16002)
		(layer "In4.Cu")
		(net "M_J_CPU1_SA_DQS_DP<0>")
	)
	(segment
		(start 166.00805 -201.203306)
		(end 166.88181 -200.329546)
		(width 0.16002)
		(layer "In4.Cu")
		(net "M_J_CPU1_SA_DQS_DP<0>")
	)
	(segment
		(start 174.183802 -200.537826)
		(end 175.01235 -200.537826)
		(width 0.16002)
		(layer "In4.Cu")
		(net "M_J_CPU1_SA_DQS_DP<0>")
	)
	(segment
		(start 140.154914 -226.994466)
		(end 140.163296 -226.98964)
		(width 0.09525)
		(layer "In4.Cu")
		(net "M_J_CPU1_SA_DQS_DP<0>")
	)
	(segment
		(start 142.043404 -225.369628)
		(end 142.0749 -225.35134)
		(width 0.09525)
		(layer "In4.Cu")
		(net "M_J_CPU1_SA_DQS_DP<0>")
	)
	(segment
		(start 175.539908 -200.010268)
		(end 177.137568 -200.010268)
		(width 0.16002)
		(layer "In4.Cu")
		(net "M_J_CPU1_SA_DQS_DP<0>")
	)
	(segment
		(start 141.538198 -226.200208)
		(end 141.57325 -226.179634)
		(width 0.09525)
		(layer "In4.Cu")
		(net "M_J_CPU1_SA_DQS_DP<0>")
	)
	(segment
		(start 141.10335 -226.98964)
		(end 141.135862 -226.970844)
		(width 0.09525)
		(layer "In4.Cu")
		(net "M_J_CPU1_SA_DQS_DP<0>")
	)
	(segment
		(start 137.906252 -226.98964)
		(end 137.914634 -226.994466)
		(width 0.09525)
		(layer "In4.Cu")
		(net "M_J_CPU1_SA_DQS_DP<0>")
	)
	(segment
		(start 177.987452 -200.860152)
		(end 180.165756 -200.860152)
		(width 0.16002)
		(layer "In4.Cu")
		(net "M_J_CPU1_SA_DQS_DP<0>")
	)
	(segment
		(start 161.373312 -200.622916)
		(end 164.62248 -200.622916)
		(width 0.16002)
		(layer "In4.Cu")
		(net "M_J_CPU1_SA_DQS_DP<0>")
	)
	(segment
		(start 181.843934 -200.466706)
		(end 182.552848 -200.466706)
		(width 0.16002)
		(layer "In4.Cu")
		(net "M_J_CPU1_SA_DQS_DP<0>")
	)
	(segment
		(start 181.074314 -201.236326)
		(end 181.843934 -200.466706)
		(width 0.16002)
		(layer "In4.Cu")
		(net "M_J_CPU1_SA_DQS_DP<0>")
	)
	(segment
		(start 132.45465 -226.66452)
		(end 132.608574 -226.92995)
		(width 0.09525)
		(layer "In4.Cu")
		(net "M_J_CPU1_SA_DQS_DP<0>")
	)
	(segment
		(start 185.079132 -200.466706)
		(end 187.15863 -200.466706)
		(width 0.16002)
		(layer "In4.Cu")
		(net "M_J_CPU1_SA_DQS_DP<0>")
	)
	(segment
		(start 144.053814 -217.942414)
		(end 161.373312 -200.622916)
		(width 0.16002)
		(layer "In4.Cu")
		(net "M_J_CPU1_SA_DQS_DP<0>")
	)
	(segment
		(start 141.57325 -226.179634)
		(end 141.605762 -226.160838)
		(width 0.09525)
		(layer "In4.Cu")
		(net "M_J_CPU1_SA_DQS_DP<0>")
	)
	(segment
		(start 142.948152 -223.77019)
		(end 142.983204 -223.749616)
		(width 0.09525)
		(layer "In4.Cu")
		(net "M_J_CPU1_SA_DQS_DP<0>")
	)
	(segment
		(start 177.137568 -200.010268)
		(end 177.987452 -200.860152)
		(width 0.16002)
		(layer "In4.Cu")
		(net "M_J_CPU1_SA_DQS_DP<0>")
	)
	(segment
		(start 183.009286 -200.010268)
		(end 184.622694 -200.010268)
		(width 0.16002)
		(layer "In4.Cu")
		(net "M_J_CPU1_SA_DQS_DP<0>")
	)
	(segment
		(start 172.568616 -200.860152)
		(end 172.92447 -201.216006)
		(width 0.16002)
		(layer "In4.Cu")
		(net "M_J_CPU1_SA_DQS_DP<0>")
	)
	(segment
		(start 136.394952 -226.994466)
		(end 136.403334 -226.98964)
		(width 0.09525)
		(layer "In4.Cu")
		(net "M_J_CPU1_SA_DQS_DP<0>")
	)
	(segment
		(start 141.094968 -226.994466)
		(end 141.10335 -226.98964)
		(width 0.09525)
		(layer "In4.Cu")
		(net "M_J_CPU1_SA_DQS_DP<0>")
	)
	(segment
		(start 165.20287 -201.203306)
		(end 166.00805 -201.203306)
		(width 0.16002)
		(layer "In4.Cu")
		(net "M_J_CPU1_SA_DQS_DP<0>")
	)
	(segment
		(start 136.966198 -226.98964)
		(end 136.97458 -226.994466)
		(width 0.09525)
		(layer "In4.Cu")
		(net "M_J_CPU1_SA_DQS_DP<0>")
	)
	(segment
		(start 144.112234 -221.804484)
		(end 144.112234 -221.256606)
		(width 0.09525)
		(layer "In4.Cu")
		(net "M_J_CPU1_SA_DQS_DP<0>")
	)
	(segment
		(start 133.206236 -226.98964)
		(end 133.214618 -226.994466)
		(width 0.09525)
		(layer "In4.Cu")
		(net "M_J_CPU1_SA_DQS_DP<0>")
	)
	(segment
		(start 170.661076 -200.860152)
		(end 172.568616 -200.860152)
		(width 0.16002)
		(layer "In4.Cu")
		(net "M_J_CPU1_SA_DQS_DP<0>")
	)
	(segment
		(start 188.81217 -201.190606)
		(end 188.993526 -201.00925)
		(width 0.16002)
		(layer "In4.Cu")
		(net "M_J_CPU1_SA_DQS_DP<0>")
	)
	(segment
		(start 188.993526 -201.00925)
		(end 190.886334 -201.00925)
		(width 0.16002)
		(layer "In4.Cu")
		(net "M_J_CPU1_SA_DQS_DP<0>")
	)
	(segment
		(start 180.54193 -201.236326)
		(end 181.074314 -201.236326)
		(width 0.16002)
		(layer "In4.Cu")
		(net "M_J_CPU1_SA_DQS_DP<0>")
	)
	(segment
		(start 144.112234 -221.256606)
		(end 144.053814 -221.198186)
		(width 0.09525)
		(layer "In4.Cu")
		(net "M_J_CPU1_SA_DQS_DP<0>")
	)
	(segment
		(start 143.453358 -222.93961)
		(end 143.484854 -222.921322)
		(width 0.09525)
		(layer "In4.Cu")
		(net "M_J_CPU1_SA_DQS_DP<0>")
	)
	(segment
		(start 173.505622 -201.216006)
		(end 174.183802 -200.537826)
		(width 0.16002)
		(layer "In4.Cu")
		(net "M_J_CPU1_SA_DQS_DP<0>")
	)
	(segment
		(start 143.923004 -222.129604)
		(end 143.956786 -222.110046)
		(width 0.09525)
		(layer "In4.Cu")
		(net "M_J_CPU1_SA_DQS_DP<0>")
	)
	(segment
		(start 190.886334 -201.00925)
		(end 191.160146 -200.735438)
		(width 0.16002)
		(layer "In4.Cu")
		(net "M_J_CPU1_SA_DQS_DP<0>")
	)
	(segment
		(start 144.053814 -221.198186)
		(end 144.053814 -221.174564)
		(width 0.09525)
		(layer "In4.Cu")
		(net "M_J_CPU1_SA_DQS_DP<0>")
	)
	(segment
		(start 184.622694 -200.010268)
		(end 185.079132 -200.466706)
		(width 0.16002)
		(layer "In4.Cu")
		(net "M_J_CPU1_SA_DQS_DP<0>")
	)
	(segment
		(start 187.88253 -201.190606)
		(end 188.81217 -201.190606)
		(width 0.16002)
		(layer "In4.Cu")
		(net "M_J_CPU1_SA_DQS_DP<0>")
	)
	(segment
		(start 172.92447 -201.216006)
		(end 173.505622 -201.216006)
		(width 0.16002)
		(layer "In4.Cu")
		(net "M_J_CPU1_SA_DQS_DP<0>")
	)
	(segment
		(start 143.415258 -222.961708)
		(end 143.453358 -222.93961)
		(width 0.09525)
		(layer "In4.Cu")
		(net "M_J_CPU1_SA_DQS_DP<0>")
	)
	(segment
		(start 135.454898 -226.994466)
		(end 135.46328 -226.98964)
		(width 0.09525)
		(layer "In4.Cu")
		(net "M_J_CPU1_SA_DQS_DP<0>")
	)
	(segment
		(start 142.513304 -224.559622)
		(end 142.545816 -224.540826)
		(width 0.09525)
		(layer "In4.Cu")
		(net "M_J_CPU1_SA_DQS_DP<0>")
	)
	(segment
		(start 180.165756 -200.860152)
		(end 180.54193 -201.236326)
		(width 0.16002)
		(layer "In4.Cu")
		(net "M_J_CPU1_SA_DQS_DP<0>")
	)
	(segment
		(start 132.608574 -226.92995)
		(end 132.709412 -226.95662)
		(width 0.09525)
		(layer "In4.Cu")
		(net "M_J_CPU1_SA_DQS_DP<0>")
	)
	(segment
		(start 144.053814 -221.174564)
		(end 144.053814 -217.942414)
		(width 0.16002)
		(layer "In4.Cu")
		(net "M_J_CPU1_SA_DQS_DP<0>")
	)
	(arc
		(start 141.605762 -226.160838)
		(mid 141.721036 -226.02656)
		(end 141.76248 -225.854514)
		(width 0.09525)
		(layer "In4.Cu")
		(net "M_J_CPU1_SA_DQS_DP<0>")
	)
	(arc
		(start 140.163296 -226.98964)
		(mid 140.444728 -226.913885)
		(end 140.72616 -226.98964)
		(width 0.09525)
		(layer "In4.Cu")
		(net "M_J_CPU1_SA_DQS_DP<0>")
	)
	(arc
		(start 137.343388 -226.98964)
		(mid 137.62482 -226.913885)
		(end 137.906252 -226.98964)
		(width 0.09525)
		(layer "In4.Cu")
		(net "M_J_CPU1_SA_DQS_DP<0>")
	)
	(arc
		(start 141.29258 -226.66452)
		(mid 141.357827 -226.401917)
		(end 141.538198 -226.200208)
		(width 0.09525)
		(layer "In4.Cu")
		(net "M_J_CPU1_SA_DQS_DP<0>")
	)
	(arc
		(start 142.545816 -224.540826)
		(mid 142.66109 -224.406548)
		(end 142.702534 -224.234502)
		(width 0.09525)
		(layer "In4.Cu")
		(net "M_J_CPU1_SA_DQS_DP<0>")
	)
	(arc
		(start 143.484854 -222.921322)
		(mid 143.600652 -222.786928)
		(end 143.642334 -222.61449)
		(width 0.09525)
		(layer "In4.Cu")
		(net "M_J_CPU1_SA_DQS_DP<0>")
	)
	(arc
		(start 135.08609 -226.98964)
		(mid 135.269865 -227.040412)
		(end 135.454898 -226.994466)
		(width 0.09525)
		(layer "In4.Cu")
		(net "M_J_CPU1_SA_DQS_DP<0>")
	)
	(arc
		(start 134.14629 -226.98964)
		(mid 134.334758 -227.040317)
		(end 134.523226 -226.98964)
		(width 0.09525)
		(layer "In4.Cu")
		(net "M_J_CPU1_SA_DQS_DP<0>")
	)
	(arc
		(start 133.214618 -226.994466)
		(mid 133.39965 -227.04038)
		(end 133.583426 -226.98964)
		(width 0.09525)
		(layer "In4.Cu")
		(net "M_J_CPU1_SA_DQS_DP<0>")
	)
	(arc
		(start 136.403334 -226.98964)
		(mid 136.684766 -226.913885)
		(end 136.966198 -226.98964)
		(width 0.09525)
		(layer "In4.Cu")
		(net "M_J_CPU1_SA_DQS_DP<0>")
	)
	(arc
		(start 134.523226 -226.98964)
		(mid 134.804658 -226.913885)
		(end 135.08609 -226.98964)
		(width 0.09525)
		(layer "In4.Cu")
		(net "M_J_CPU1_SA_DQS_DP<0>")
	)
	(arc
		(start 139.223242 -226.98964)
		(mid 139.504674 -226.913885)
		(end 139.786106 -226.98964)
		(width 0.09525)
		(layer "In4.Cu")
		(net "M_J_CPU1_SA_DQS_DP<0>")
	)
	(arc
		(start 135.46328 -226.98964)
		(mid 135.744712 -226.913885)
		(end 136.026144 -226.98964)
		(width 0.09525)
		(layer "In4.Cu")
		(net "M_J_CPU1_SA_DQS_DP<0>")
	)
	(arc
		(start 139.786106 -226.98964)
		(mid 139.969881 -227.040412)
		(end 140.154914 -226.994466)
		(width 0.09525)
		(layer "In4.Cu")
		(net "M_J_CPU1_SA_DQS_DP<0>")
	)
	(arc
		(start 138.283442 -226.98964)
		(mid 138.564874 -226.913885)
		(end 138.846306 -226.98964)
		(width 0.09525)
		(layer "In4.Cu")
		(net "M_J_CPU1_SA_DQS_DP<0>")
	)
	(arc
		(start 142.702534 -224.234502)
		(mid 142.767781 -223.971899)
		(end 142.948152 -223.77019)
		(width 0.09525)
		(layer "In4.Cu")
		(net "M_J_CPU1_SA_DQS_DP<0>")
	)
	(arc
		(start 143.015716 -223.73082)
		(mid 143.13099 -223.596542)
		(end 143.172434 -223.424496)
		(width 0.09525)
		(layer "In4.Cu")
		(net "M_J_CPU1_SA_DQS_DP<0>")
	)
	(arc
		(start 136.026144 -226.98964)
		(mid 136.209919 -227.040412)
		(end 136.394952 -226.994466)
		(width 0.09525)
		(layer "In4.Cu")
		(net "M_J_CPU1_SA_DQS_DP<0>")
	)
	(arc
		(start 142.0749 -225.35134)
		(mid 142.190698 -225.216946)
		(end 142.23238 -225.044508)
		(width 0.09525)
		(layer "In4.Cu")
		(net "M_J_CPU1_SA_DQS_DP<0>")
	)
	(arc
		(start 137.914634 -226.994466)
		(mid 138.099666 -227.04038)
		(end 138.283442 -226.98964)
		(width 0.09525)
		(layer "In4.Cu")
		(net "M_J_CPU1_SA_DQS_DP<0>")
	)
	(arc
		(start 136.97458 -226.994466)
		(mid 137.159612 -227.04038)
		(end 137.343388 -226.98964)
		(width 0.09525)
		(layer "In4.Cu")
		(net "M_J_CPU1_SA_DQS_DP<0>")
	)
	(arc
		(start 141.135862 -226.970844)
		(mid 141.251136 -226.836566)
		(end 141.29258 -226.66452)
		(width 0.09525)
		(layer "In4.Cu")
		(net "M_J_CPU1_SA_DQS_DP<0>")
	)
	(arc
		(start 142.23238 -225.044508)
		(mid 142.296777 -224.783202)
		(end 142.475204 -224.58172)
		(width 0.09525)
		(layer "In4.Cu")
		(net "M_J_CPU1_SA_DQS_DP<0>")
	)
	(arc
		(start 143.172434 -223.424496)
		(mid 143.236831 -223.16319)
		(end 143.415258 -222.961708)
		(width 0.09525)
		(layer "In4.Cu")
		(net "M_J_CPU1_SA_DQS_DP<0>")
	)
	(arc
		(start 132.709412 -226.95662)
		(mid 132.961696 -226.914926)
		(end 133.206236 -226.98964)
		(width 0.09525)
		(layer "In4.Cu")
		(net "M_J_CPU1_SA_DQS_DP<0>")
	)
	(arc
		(start 133.583426 -226.98964)
		(mid 133.864858 -226.913885)
		(end 134.14629 -226.98964)
		(width 0.09525)
		(layer "In4.Cu")
		(net "M_J_CPU1_SA_DQS_DP<0>")
	)
	(arc
		(start 140.72616 -226.98964)
		(mid 140.909935 -227.040412)
		(end 141.094968 -226.994466)
		(width 0.09525)
		(layer "In4.Cu")
		(net "M_J_CPU1_SA_DQS_DP<0>")
	)
	(arc
		(start 138.846306 -226.98964)
		(mid 139.034774 -227.040317)
		(end 139.223242 -226.98964)
		(width 0.09525)
		(layer "In4.Cu")
		(net "M_J_CPU1_SA_DQS_DP<0>")
	)
	(arc
		(start 143.956786 -222.110046)
		(mid 144.071165 -221.975907)
		(end 144.112234 -221.804484)
		(width 0.09525)
		(layer "In4.Cu")
		(net "M_J_CPU1_SA_DQS_DP<0>")
	)
	(arc
		(start 143.642334 -222.61449)
		(mid 143.707094 -222.352555)
		(end 143.886428 -222.15094)
		(width 0.09525)
		(layer "In4.Cu")
		(net "M_J_CPU1_SA_DQS_DP<0>")
	)
	(arc
		(start 141.76248 -225.854514)
		(mid 141.826877 -225.593208)
		(end 142.005304 -225.391726)
		(width 0.09525)
		(layer "In4.Cu")
		(net "M_J_CPU1_SA_DQS_DP<0>")
	)
	(segment
		(start 130.577844 -247.180354)
		(end 131.044696 -246.914416)
		(width 0.12954)
		(layer "F.Cu")
		(net "M_J_CPU1_SA_DQS_DN<9>")
	)
	(segment
		(start 140.25626 -247.239536)
		(end 140.264642 -247.244362)
		(width 0.09525)
		(layer "In4.Cu")
		(net "M_J_CPU1_SA_DQS_DN<9>")
	)
	(segment
		(start 157.19171 -246.802656)
		(end 157.461712 -246.532654)
		(width 0.16002)
		(layer "In4.Cu")
		(net "M_J_CPU1_SA_DQS_DN<9>")
	)
	(segment
		(start 144.382236 -247.246394)
		(end 144.394174 -247.239536)
		(width 0.09525)
		(layer "In4.Cu")
		(net "M_J_CPU1_SA_DQS_DN<9>")
	)
	(segment
		(start 157.461712 -246.255794)
		(end 157.273752 -246.067834)
		(width 0.16002)
		(layer "In4.Cu")
		(net "M_J_CPU1_SA_DQS_DN<9>")
	)
	(segment
		(start 139.316206 -247.239536)
		(end 139.324588 -247.244362)
		(width 0.09525)
		(layer "In4.Cu")
		(net "M_J_CPU1_SA_DQS_DN<9>")
	)
	(segment
		(start 147.919186 -246.802656)
		(end 157.19171 -246.802656)
		(width 0.16002)
		(layer "In4.Cu")
		(net "M_J_CPU1_SA_DQS_DN<9>")
	)
	(segment
		(start 180.128164 -240.258346)
		(end 180.490368 -239.896142)
		(width 0.16002)
		(layer "In4.Cu")
		(net "M_J_CPU1_SA_DQS_DN<9>")
	)
	(segment
		(start 171.161456 -240.258346)
		(end 172.431964 -240.258346)
		(width 0.16002)
		(layer "In4.Cu")
		(net "M_J_CPU1_SA_DQS_DN<9>")
	)
	(segment
		(start 131.044696 -246.914416)
		(end 131.19862 -247.179846)
		(width 0.09525)
		(layer "In4.Cu")
		(net "M_J_CPU1_SA_DQS_DN<9>")
	)
	(segment
		(start 135.556244 -247.239536)
		(end 135.564626 -247.244362)
		(width 0.09525)
		(layer "In4.Cu")
		(net "M_J_CPU1_SA_DQS_DN<9>")
	)
	(segment
		(start 179.00142 -240.258346)
		(end 180.128164 -240.258346)
		(width 0.16002)
		(layer "In4.Cu")
		(net "M_J_CPU1_SA_DQS_DN<9>")
	)
	(segment
		(start 157.461712 -246.532654)
		(end 157.461712 -246.255794)
		(width 0.16002)
		(layer "In4.Cu")
		(net "M_J_CPU1_SA_DQS_DN<9>")
	)
	(segment
		(start 160.39465 -242.419632)
		(end 160.921954 -242.419632)
		(width 0.16002)
		(layer "In4.Cu")
		(net "M_J_CPU1_SA_DQS_DN<9>")
	)
	(segment
		(start 158.835344 -245.159022)
		(end 158.835344 -244.882162)
		(width 0.16002)
		(layer "In4.Cu")
		(net "M_J_CPU1_SA_DQS_DN<9>")
	)
	(segment
		(start 159.548322 -243.793264)
		(end 159.736282 -243.981224)
		(width 0.16002)
		(layer "In4.Cu")
		(net "M_J_CPU1_SA_DQS_DN<9>")
	)
	(segment
		(start 159.021018 -243.793264)
		(end 159.548322 -243.793264)
		(width 0.16002)
		(layer "In4.Cu")
		(net "M_J_CPU1_SA_DQS_DN<9>")
	)
	(segment
		(start 160.921954 -242.419632)
		(end 161.109914 -242.607592)
		(width 0.16002)
		(layer "In4.Cu")
		(net "M_J_CPU1_SA_DQS_DN<9>")
	)
	(segment
		(start 175.574198 -239.408208)
		(end 178.151282 -239.408208)
		(width 0.16002)
		(layer "In4.Cu")
		(net "M_J_CPU1_SA_DQS_DN<9>")
	)
	(segment
		(start 159.736282 -243.981224)
		(end 160.013142 -243.981224)
		(width 0.16002)
		(layer "In4.Cu")
		(net "M_J_CPU1_SA_DQS_DN<9>")
	)
	(segment
		(start 146.862292 -247.425464)
		(end 147.425918 -246.861838)
		(width 0.09525)
		(layer "In4.Cu")
		(net "M_J_CPU1_SA_DQS_DN<9>")
	)
	(segment
		(start 131.19862 -247.179846)
		(end 131.299458 -247.206516)
		(width 0.09525)
		(layer "In4.Cu")
		(net "M_J_CPU1_SA_DQS_DN<9>")
	)
	(segment
		(start 160.021016 -242.793266)
		(end 160.39465 -242.419632)
		(width 0.16002)
		(layer "In4.Cu")
		(net "M_J_CPU1_SA_DQS_DN<9>")
	)
	(segment
		(start 133.10489 -247.244362)
		(end 133.113272 -247.239536)
		(width 0.09525)
		(layer "In4.Cu")
		(net "M_J_CPU1_SA_DQS_DN<9>")
	)
	(segment
		(start 157.273752 -245.54053)
		(end 157.647386 -245.166896)
		(width 0.16002)
		(layer "In4.Cu")
		(net "M_J_CPU1_SA_DQS_DN<9>")
	)
	(segment
		(start 166.803324 -239.095026)
		(end 169.998136 -239.095026)
		(width 0.16002)
		(layer "In4.Cu")
		(net "M_J_CPU1_SA_DQS_DN<9>")
	)
	(segment
		(start 183.98109 -239.408208)
		(end 184.130188 -239.25911)
		(width 0.16002)
		(layer "In4.Cu")
		(net "M_J_CPU1_SA_DQS_DN<9>")
	)
	(segment
		(start 181.896004 -239.063022)
		(end 182.798212 -239.063022)
		(width 0.16002)
		(layer "In4.Cu")
		(net "M_J_CPU1_SA_DQS_DN<9>")
	)
	(segment
		(start 147.836382 -246.861838)
		(end 147.895564 -246.802656)
		(width 0.09525)
		(layer "In4.Cu")
		(net "M_J_CPU1_SA_DQS_DN<9>")
	)
	(segment
		(start 183.143398 -239.408208)
		(end 183.98109 -239.408208)
		(width 0.16002)
		(layer "In4.Cu")
		(net "M_J_CPU1_SA_DQS_DN<9>")
	)
	(segment
		(start 169.998136 -239.095026)
		(end 171.161456 -240.258346)
		(width 0.16002)
		(layer "In4.Cu")
		(net "M_J_CPU1_SA_DQS_DN<9>")
	)
	(segment
		(start 146.012408 -247.327674)
		(end 146.110198 -247.425464)
		(width 0.09525)
		(layer "In4.Cu")
		(net "M_J_CPU1_SA_DQS_DN<9>")
	)
	(segment
		(start 182.798212 -239.063022)
		(end 183.143398 -239.408208)
		(width 0.16002)
		(layer "In4.Cu")
		(net "M_J_CPU1_SA_DQS_DN<9>")
	)
	(segment
		(start 146.110198 -247.425464)
		(end 146.862292 -247.425464)
		(width 0.09525)
		(layer "In4.Cu")
		(net "M_J_CPU1_SA_DQS_DN<9>")
	)
	(segment
		(start 175.236632 -239.070642)
		(end 175.574198 -239.408208)
		(width 0.16002)
		(layer "In4.Cu")
		(net "M_J_CPU1_SA_DQS_DN<9>")
	)
	(segment
		(start 161.109914 -242.607592)
		(end 161.386774 -242.607592)
		(width 0.16002)
		(layer "In4.Cu")
		(net "M_J_CPU1_SA_DQS_DN<9>")
	)
	(segment
		(start 147.895564 -246.802656)
		(end 147.919186 -246.802656)
		(width 0.09525)
		(layer "In4.Cu")
		(net "M_J_CPU1_SA_DQS_DN<9>")
	)
	(segment
		(start 181.062884 -239.896142)
		(end 181.896004 -239.063022)
		(width 0.16002)
		(layer "In4.Cu")
		(net "M_J_CPU1_SA_DQS_DN<9>")
	)
	(segment
		(start 142.504922 -247.244362)
		(end 142.513304 -247.239536)
		(width 0.09525)
		(layer "In4.Cu")
		(net "M_J_CPU1_SA_DQS_DN<9>")
	)
	(segment
		(start 158.36265 -245.354856)
		(end 158.63951 -245.354856)
		(width 0.16002)
		(layer "In4.Cu")
		(net "M_J_CPU1_SA_DQS_DN<9>")
	)
	(segment
		(start 158.835344 -244.882162)
		(end 158.647384 -244.694202)
		(width 0.16002)
		(layer "In4.Cu")
		(net "M_J_CPU1_SA_DQS_DN<9>")
	)
	(segment
		(start 158.647384 -244.166898)
		(end 159.021018 -243.793264)
		(width 0.16002)
		(layer "In4.Cu")
		(net "M_J_CPU1_SA_DQS_DN<9>")
	)
	(segment
		(start 138.74496 -247.244362)
		(end 138.753342 -247.239536)
		(width 0.09525)
		(layer "In4.Cu")
		(net "M_J_CPU1_SA_DQS_DN<9>")
	)
	(segment
		(start 158.63951 -245.354856)
		(end 158.835344 -245.159022)
		(width 0.16002)
		(layer "In4.Cu")
		(net "M_J_CPU1_SA_DQS_DN<9>")
	)
	(segment
		(start 186.786266 -239.25911)
		(end 187.060078 -238.985298)
		(width 0.16002)
		(layer "In4.Cu")
		(net "M_J_CPU1_SA_DQS_DN<9>")
	)
	(segment
		(start 158.17469 -245.166896)
		(end 158.36265 -245.354856)
		(width 0.16002)
		(layer "In4.Cu")
		(net "M_J_CPU1_SA_DQS_DN<9>")
	)
	(segment
		(start 144.941798 -247.2309)
		(end 144.95653 -247.239536)
		(width 0.09525)
		(layer "In4.Cu")
		(net "M_J_CPU1_SA_DQS_DN<9>")
	)
	(segment
		(start 173.439328 -239.919002)
		(end 174.287688 -239.070642)
		(width 0.16002)
		(layer "In4.Cu")
		(net "M_J_CPU1_SA_DQS_DN<9>")
	)
	(segment
		(start 161.386774 -242.607592)
		(end 164.136324 -239.858042)
		(width 0.16002)
		(layer "In4.Cu")
		(net "M_J_CPU1_SA_DQS_DN<9>")
	)
	(segment
		(start 157.647386 -245.166896)
		(end 158.17469 -245.166896)
		(width 0.16002)
		(layer "In4.Cu")
		(net "M_J_CPU1_SA_DQS_DN<9>")
	)
	(segment
		(start 143.076168 -247.239536)
		(end 143.08455 -247.244362)
		(width 0.09525)
		(layer "In4.Cu")
		(net "M_J_CPU1_SA_DQS_DN<9>")
	)
	(segment
		(start 174.287688 -239.070642)
		(end 175.236632 -239.070642)
		(width 0.16002)
		(layer "In4.Cu")
		(net "M_J_CPU1_SA_DQS_DN<9>")
	)
	(segment
		(start 160.013142 -243.981224)
		(end 160.208976 -243.78539)
		(width 0.16002)
		(layer "In4.Cu")
		(net "M_J_CPU1_SA_DQS_DN<9>")
	)
	(segment
		(start 160.208976 -243.50853)
		(end 160.021016 -243.32057)
		(width 0.16002)
		(layer "In4.Cu")
		(net "M_J_CPU1_SA_DQS_DN<9>")
	)
	(segment
		(start 160.208976 -243.78539)
		(end 160.208976 -243.50853)
		(width 0.16002)
		(layer "In4.Cu")
		(net "M_J_CPU1_SA_DQS_DN<9>")
	)
	(segment
		(start 157.273752 -246.067834)
		(end 157.273752 -245.54053)
		(width 0.16002)
		(layer "In4.Cu")
		(net "M_J_CPU1_SA_DQS_DN<9>")
	)
	(segment
		(start 134.044944 -247.244362)
		(end 134.053326 -247.239536)
		(width 0.09525)
		(layer "In4.Cu")
		(net "M_J_CPU1_SA_DQS_DN<9>")
	)
	(segment
		(start 164.136324 -239.858042)
		(end 166.040308 -239.858042)
		(width 0.16002)
		(layer "In4.Cu")
		(net "M_J_CPU1_SA_DQS_DN<9>")
	)
	(segment
		(start 137.804906 -247.244362)
		(end 137.813288 -247.239536)
		(width 0.09525)
		(layer "In4.Cu")
		(net "M_J_CPU1_SA_DQS_DN<9>")
	)
	(segment
		(start 160.021016 -243.32057)
		(end 160.021016 -242.793266)
		(width 0.16002)
		(layer "In4.Cu")
		(net "M_J_CPU1_SA_DQS_DN<9>")
	)
	(segment
		(start 172.431964 -240.258346)
		(end 172.771308 -239.919002)
		(width 0.16002)
		(layer "In4.Cu")
		(net "M_J_CPU1_SA_DQS_DN<9>")
	)
	(segment
		(start 166.040308 -239.858042)
		(end 166.803324 -239.095026)
		(width 0.16002)
		(layer "In4.Cu")
		(net "M_J_CPU1_SA_DQS_DN<9>")
	)
	(segment
		(start 144.95653 -247.239536)
		(end 144.971008 -247.247918)
		(width 0.09525)
		(layer "In4.Cu")
		(net "M_J_CPU1_SA_DQS_DN<9>")
	)
	(segment
		(start 147.425918 -246.861838)
		(end 147.836382 -246.861838)
		(width 0.09525)
		(layer "In4.Cu")
		(net "M_J_CPU1_SA_DQS_DN<9>")
	)
	(segment
		(start 143.453358 -247.239536)
		(end 143.46809 -247.2309)
		(width 0.09525)
		(layer "In4.Cu")
		(net "M_J_CPU1_SA_DQS_DN<9>")
	)
	(segment
		(start 172.771308 -239.919002)
		(end 173.439328 -239.919002)
		(width 0.16002)
		(layer "In4.Cu")
		(net "M_J_CPU1_SA_DQS_DN<9>")
	)
	(segment
		(start 184.130188 -239.25911)
		(end 186.786266 -239.25911)
		(width 0.16002)
		(layer "In4.Cu")
		(net "M_J_CPU1_SA_DQS_DN<9>")
	)
	(segment
		(start 178.151282 -239.408208)
		(end 179.00142 -240.258346)
		(width 0.16002)
		(layer "In4.Cu")
		(net "M_J_CPU1_SA_DQS_DN<9>")
	)
	(segment
		(start 134.61619 -247.239536)
		(end 134.624572 -247.244362)
		(width 0.09525)
		(layer "In4.Cu")
		(net "M_J_CPU1_SA_DQS_DN<9>")
	)
	(segment
		(start 158.647384 -244.694202)
		(end 158.647384 -244.166898)
		(width 0.16002)
		(layer "In4.Cu")
		(net "M_J_CPU1_SA_DQS_DN<9>")
	)
	(segment
		(start 180.490368 -239.896142)
		(end 181.062884 -239.896142)
		(width 0.16002)
		(layer "In4.Cu")
		(net "M_J_CPU1_SA_DQS_DN<9>")
	)
	(arc
		(start 134.053326 -247.239536)
		(mid 134.334758 -247.163781)
		(end 134.61619 -247.239536)
		(width 0.09525)
		(layer "In4.Cu")
		(net "M_J_CPU1_SA_DQS_DN<9>")
	)
	(arc
		(start 140.63345 -247.239536)
		(mid 140.914882 -247.163781)
		(end 141.196314 -247.239536)
		(width 0.09525)
		(layer "In4.Cu")
		(net "M_J_CPU1_SA_DQS_DN<9>")
	)
	(arc
		(start 142.136114 -247.239536)
		(mid 142.319889 -247.290308)
		(end 142.504922 -247.244362)
		(width 0.09525)
		(layer "In4.Cu")
		(net "M_J_CPU1_SA_DQS_DN<9>")
	)
	(arc
		(start 141.57325 -247.239536)
		(mid 141.854682 -247.163781)
		(end 142.136114 -247.239536)
		(width 0.09525)
		(layer "In4.Cu")
		(net "M_J_CPU1_SA_DQS_DN<9>")
	)
	(arc
		(start 137.436098 -247.239536)
		(mid 137.619873 -247.290308)
		(end 137.804906 -247.244362)
		(width 0.09525)
		(layer "In4.Cu")
		(net "M_J_CPU1_SA_DQS_DN<9>")
	)
	(arc
		(start 145.33372 -247.239536)
		(mid 145.60821 -247.163575)
		(end 145.884646 -247.23217)
		(width 0.09525)
		(layer "In4.Cu")
		(net "M_J_CPU1_SA_DQS_DN<9>")
	)
	(arc
		(start 142.513304 -247.239536)
		(mid 142.794736 -247.163781)
		(end 143.076168 -247.239536)
		(width 0.09525)
		(layer "In4.Cu")
		(net "M_J_CPU1_SA_DQS_DN<9>")
	)
	(arc
		(start 138.753342 -247.239536)
		(mid 139.034774 -247.163781)
		(end 139.316206 -247.239536)
		(width 0.09525)
		(layer "In4.Cu")
		(net "M_J_CPU1_SA_DQS_DN<9>")
	)
	(arc
		(start 132.736082 -247.239536)
		(mid 132.919857 -247.290308)
		(end 133.10489 -247.244362)
		(width 0.09525)
		(layer "In4.Cu")
		(net "M_J_CPU1_SA_DQS_DN<9>")
	)
	(arc
		(start 136.873234 -247.239536)
		(mid 137.154666 -247.163781)
		(end 137.436098 -247.239536)
		(width 0.09525)
		(layer "In4.Cu")
		(net "M_J_CPU1_SA_DQS_DN<9>")
	)
	(arc
		(start 144.01673 -247.239536)
		(mid 144.1986 -247.290401)
		(end 144.382236 -247.246394)
		(width 0.09525)
		(layer "In4.Cu")
		(net "M_J_CPU1_SA_DQS_DN<9>")
	)
	(arc
		(start 141.196314 -247.239536)
		(mid 141.384782 -247.290213)
		(end 141.57325 -247.239536)
		(width 0.09525)
		(layer "In4.Cu")
		(net "M_J_CPU1_SA_DQS_DN<9>")
	)
	(arc
		(start 133.113272 -247.239536)
		(mid 133.394704 -247.163781)
		(end 133.676136 -247.239536)
		(width 0.09525)
		(layer "In4.Cu")
		(net "M_J_CPU1_SA_DQS_DN<9>")
	)
	(arc
		(start 139.693396 -247.239536)
		(mid 139.974828 -247.163781)
		(end 140.25626 -247.239536)
		(width 0.09525)
		(layer "In4.Cu")
		(net "M_J_CPU1_SA_DQS_DN<9>")
	)
	(arc
		(start 131.299458 -247.206516)
		(mid 131.309706 -247.202353)
		(end 131.320032 -247.198388)
		(width 0.09525)
		(layer "In4.Cu")
		(net "M_J_CPU1_SA_DQS_DN<9>")
	)
	(arc
		(start 134.99338 -247.239536)
		(mid 135.274812 -247.163781)
		(end 135.556244 -247.239536)
		(width 0.09525)
		(layer "In4.Cu")
		(net "M_J_CPU1_SA_DQS_DN<9>")
	)
	(arc
		(start 144.971008 -247.247918)
		(mid 145.15344 -247.290358)
		(end 145.33372 -247.239536)
		(width 0.09525)
		(layer "In4.Cu")
		(net "M_J_CPU1_SA_DQS_DN<9>")
	)
	(arc
		(start 143.08455 -247.244362)
		(mid 143.269582 -247.290276)
		(end 143.453358 -247.239536)
		(width 0.09525)
		(layer "In4.Cu")
		(net "M_J_CPU1_SA_DQS_DN<9>")
	)
	(arc
		(start 144.394174 -247.239536)
		(mid 144.666848 -247.163849)
		(end 144.941798 -247.2309)
		(width 0.09525)
		(layer "In4.Cu")
		(net "M_J_CPU1_SA_DQS_DN<9>")
	)
	(arc
		(start 145.884646 -247.23217)
		(mid 145.951947 -247.275348)
		(end 146.012408 -247.327674)
		(width 0.09525)
		(layer "In4.Cu")
		(net "M_J_CPU1_SA_DQS_DN<9>")
	)
	(arc
		(start 139.324588 -247.244362)
		(mid 139.50962 -247.290276)
		(end 139.693396 -247.239536)
		(width 0.09525)
		(layer "In4.Cu")
		(net "M_J_CPU1_SA_DQS_DN<9>")
	)
	(arc
		(start 132.173218 -247.239536)
		(mid 132.45465 -247.163781)
		(end 132.736082 -247.239536)
		(width 0.09525)
		(layer "In4.Cu")
		(net "M_J_CPU1_SA_DQS_DN<9>")
	)
	(arc
		(start 136.496298 -247.239536)
		(mid 136.684766 -247.290213)
		(end 136.873234 -247.239536)
		(width 0.09525)
		(layer "In4.Cu")
		(net "M_J_CPU1_SA_DQS_DN<9>")
	)
	(arc
		(start 133.676136 -247.239536)
		(mid 133.859911 -247.290308)
		(end 134.044944 -247.244362)
		(width 0.09525)
		(layer "In4.Cu")
		(net "M_J_CPU1_SA_DQS_DN<9>")
	)
	(arc
		(start 131.320032 -247.198388)
		(mid 131.562774 -247.165618)
		(end 131.796282 -247.239536)
		(width 0.09525)
		(layer "In4.Cu")
		(net "M_J_CPU1_SA_DQS_DN<9>")
	)
	(arc
		(start 134.624572 -247.244362)
		(mid 134.809604 -247.290276)
		(end 134.99338 -247.239536)
		(width 0.09525)
		(layer "In4.Cu")
		(net "M_J_CPU1_SA_DQS_DN<9>")
	)
	(arc
		(start 140.264642 -247.244362)
		(mid 140.449674 -247.290276)
		(end 140.63345 -247.239536)
		(width 0.09525)
		(layer "In4.Cu")
		(net "M_J_CPU1_SA_DQS_DN<9>")
	)
	(arc
		(start 138.376152 -247.239536)
		(mid 138.559927 -247.290308)
		(end 138.74496 -247.244362)
		(width 0.09525)
		(layer "In4.Cu")
		(net "M_J_CPU1_SA_DQS_DN<9>")
	)
	(arc
		(start 135.933434 -247.239536)
		(mid 136.214866 -247.163781)
		(end 136.496298 -247.239536)
		(width 0.09525)
		(layer "In4.Cu")
		(net "M_J_CPU1_SA_DQS_DN<9>")
	)
	(arc
		(start 135.564626 -247.244362)
		(mid 135.749658 -247.290276)
		(end 135.933434 -247.239536)
		(width 0.09525)
		(layer "In4.Cu")
		(net "M_J_CPU1_SA_DQS_DN<9>")
	)
	(arc
		(start 131.796282 -247.239536)
		(mid 131.98475 -247.290213)
		(end 132.173218 -247.239536)
		(width 0.09525)
		(layer "In4.Cu")
		(net "M_J_CPU1_SA_DQS_DN<9>")
	)
	(arc
		(start 137.813288 -247.239536)
		(mid 138.09472 -247.163781)
		(end 138.376152 -247.239536)
		(width 0.09525)
		(layer "In4.Cu")
		(net "M_J_CPU1_SA_DQS_DN<9>")
	)
	(arc
		(start 143.46809 -247.2309)
		(mid 143.743549 -247.163515)
		(end 144.01673 -247.239536)
		(width 0.09525)
		(layer "In4.Cu")
		(net "M_J_CPU1_SA_DQS_DN<9>")
	)
	(segment
		(start 130.577844 -242.320318)
		(end 131.044696 -242.05438)
		(width 0.12954)
		(layer "F.Cu")
		(net "M_J_CPU1_SA_DQS_DN<8>")
	)
	(segment
		(start 160.290002 -232.527094)
		(end 160.663636 -232.15346)
		(width 0.16002)
		(layer "In4.Cu")
		(net "M_J_CPU1_SA_DQS_DN<8>")
	)
	(segment
		(start 173.439328 -230.569008)
		(end 174.287688 -229.720648)
		(width 0.16002)
		(layer "In4.Cu")
		(net "M_J_CPU1_SA_DQS_DN<8>")
	)
	(segment
		(start 158.91637 -234.42803)
		(end 158.91637 -233.900726)
		(width 0.16002)
		(layer "In4.Cu")
		(net "M_J_CPU1_SA_DQS_DN<8>")
	)
	(segment
		(start 159.159448 -234.947968)
		(end 159.159448 -234.671108)
		(width 0.16002)
		(layer "In4.Cu")
		(net "M_J_CPU1_SA_DQS_DN<8>")
	)
	(segment
		(start 166.040308 -230.508048)
		(end 166.809928 -229.738428)
		(width 0.16002)
		(layer "In4.Cu")
		(net "M_J_CPU1_SA_DQS_DN<8>")
	)
	(segment
		(start 162.564572 -230.779828)
		(end 162.80765 -231.022906)
		(width 0.16002)
		(layer "In4.Cu")
		(net "M_J_CPU1_SA_DQS_DN<8>")
	)
	(segment
		(start 152.003506 -241.200686)
		(end 157.98292 -235.221272)
		(width 0.16002)
		(layer "In4.Cu")
		(net "M_J_CPU1_SA_DQS_DN<8>")
	)
	(segment
		(start 161.906712 -231.923844)
		(end 161.663634 -231.680766)
		(width 0.16002)
		(layer "In4.Cu")
		(net "M_J_CPU1_SA_DQS_DN<8>")
	)
	(segment
		(start 178.151282 -230.058214)
		(end 179.00142 -230.908352)
		(width 0.16002)
		(layer "In4.Cu")
		(net "M_J_CPU1_SA_DQS_DN<8>")
	)
	(segment
		(start 147.520914 -241.259868)
		(end 147.764754 -241.259868)
		(width 0.09525)
		(layer "In4.Cu")
		(net "M_J_CPU1_SA_DQS_DN<8>")
	)
	(segment
		(start 131.19862 -242.31981)
		(end 131.299458 -242.34648)
		(width 0.09525)
		(layer "In4.Cu")
		(net "M_J_CPU1_SA_DQS_DN<8>")
	)
	(segment
		(start 186.786266 -229.909116)
		(end 187.060078 -229.635304)
		(width 0.16002)
		(layer "In4.Cu")
		(net "M_J_CPU1_SA_DQS_DN<8>")
	)
	(segment
		(start 161.663634 -231.153462)
		(end 162.037268 -230.779828)
		(width 0.16002)
		(layer "In4.Cu")
		(net "M_J_CPU1_SA_DQS_DN<8>")
	)
	(segment
		(start 161.19094 -232.15346)
		(end 161.434018 -232.396538)
		(width 0.16002)
		(layer "In4.Cu")
		(net "M_J_CPU1_SA_DQS_DN<8>")
	)
	(segment
		(start 144.20596 -242.431316)
		(end 145.847816 -242.431316)
		(width 0.09525)
		(layer "In4.Cu")
		(net "M_J_CPU1_SA_DQS_DN<8>")
	)
	(segment
		(start 160.53308 -233.297476)
		(end 160.290002 -233.054398)
		(width 0.16002)
		(layer "In4.Cu")
		(net "M_J_CPU1_SA_DQS_DN<8>")
	)
	(segment
		(start 135.556244 -242.3795)
		(end 135.564626 -242.384326)
		(width 0.09525)
		(layer "In4.Cu")
		(net "M_J_CPU1_SA_DQS_DN<8>")
	)
	(segment
		(start 143.076168 -242.3795)
		(end 143.08455 -242.384326)
		(width 0.09525)
		(layer "In4.Cu")
		(net "M_J_CPU1_SA_DQS_DN<8>")
	)
	(segment
		(start 131.044696 -242.05438)
		(end 131.19862 -242.31981)
		(width 0.09525)
		(layer "In4.Cu")
		(net "M_J_CPU1_SA_DQS_DN<8>")
	)
	(segment
		(start 140.25626 -242.3795)
		(end 140.264642 -242.384326)
		(width 0.09525)
		(layer "In4.Cu")
		(net "M_J_CPU1_SA_DQS_DN<8>")
	)
	(segment
		(start 163.599368 -230.508048)
		(end 166.040308 -230.508048)
		(width 0.16002)
		(layer "In4.Cu")
		(net "M_J_CPU1_SA_DQS_DN<8>")
	)
	(segment
		(start 134.044944 -242.384326)
		(end 134.053326 -242.3795)
		(width 0.09525)
		(layer "In4.Cu")
		(net "M_J_CPU1_SA_DQS_DN<8>")
	)
	(segment
		(start 160.663636 -232.15346)
		(end 161.19094 -232.15346)
		(width 0.16002)
		(layer "In4.Cu")
		(net "M_J_CPU1_SA_DQS_DN<8>")
	)
	(segment
		(start 145.847816 -242.431316)
		(end 146.308826 -241.970306)
		(width 0.09525)
		(layer "In4.Cu")
		(net "M_J_CPU1_SA_DQS_DN<8>")
	)
	(segment
		(start 161.710878 -232.396538)
		(end 161.906712 -232.200704)
		(width 0.16002)
		(layer "In4.Cu")
		(net "M_J_CPU1_SA_DQS_DN<8>")
	)
	(segment
		(start 139.316206 -242.3795)
		(end 139.324588 -242.384326)
		(width 0.09525)
		(layer "In4.Cu")
		(net "M_J_CPU1_SA_DQS_DN<8>")
	)
	(segment
		(start 161.906712 -232.200704)
		(end 161.906712 -231.923844)
		(width 0.16002)
		(layer "In4.Cu")
		(net "M_J_CPU1_SA_DQS_DN<8>")
	)
	(segment
		(start 182.798212 -229.713028)
		(end 183.143398 -230.058214)
		(width 0.16002)
		(layer "In4.Cu")
		(net "M_J_CPU1_SA_DQS_DN<8>")
	)
	(segment
		(start 171.161456 -230.908352)
		(end 172.431964 -230.908352)
		(width 0.16002)
		(layer "In4.Cu")
		(net "M_J_CPU1_SA_DQS_DN<8>")
	)
	(segment
		(start 160.53308 -233.574336)
		(end 160.53308 -233.297476)
		(width 0.16002)
		(layer "In4.Cu")
		(net "M_J_CPU1_SA_DQS_DN<8>")
	)
	(segment
		(start 175.236632 -229.720648)
		(end 175.574198 -230.058214)
		(width 0.16002)
		(layer "In4.Cu")
		(net "M_J_CPU1_SA_DQS_DN<8>")
	)
	(segment
		(start 172.431964 -230.908352)
		(end 172.771308 -230.569008)
		(width 0.16002)
		(layer "In4.Cu")
		(net "M_J_CPU1_SA_DQS_DN<8>")
	)
	(segment
		(start 160.060386 -233.77017)
		(end 160.337246 -233.77017)
		(width 0.16002)
		(layer "In4.Cu")
		(net "M_J_CPU1_SA_DQS_DN<8>")
	)
	(segment
		(start 147.847558 -241.200686)
		(end 152.003506 -241.200686)
		(width 0.16002)
		(layer "In4.Cu")
		(net "M_J_CPU1_SA_DQS_DN<8>")
	)
	(segment
		(start 161.663634 -231.680766)
		(end 161.663634 -231.153462)
		(width 0.16002)
		(layer "In4.Cu")
		(net "M_J_CPU1_SA_DQS_DN<8>")
	)
	(segment
		(start 137.804906 -242.384326)
		(end 137.813288 -242.3795)
		(width 0.09525)
		(layer "In4.Cu")
		(net "M_J_CPU1_SA_DQS_DN<8>")
	)
	(segment
		(start 184.130188 -229.909116)
		(end 186.786266 -229.909116)
		(width 0.16002)
		(layer "In4.Cu")
		(net "M_J_CPU1_SA_DQS_DN<8>")
	)
	(segment
		(start 180.128164 -230.908352)
		(end 180.490368 -230.546148)
		(width 0.16002)
		(layer "In4.Cu")
		(net "M_J_CPU1_SA_DQS_DN<8>")
	)
	(segment
		(start 181.062884 -230.546148)
		(end 181.896004 -229.713028)
		(width 0.16002)
		(layer "In4.Cu")
		(net "M_J_CPU1_SA_DQS_DN<8>")
	)
	(segment
		(start 160.290002 -233.054398)
		(end 160.290002 -232.527094)
		(width 0.16002)
		(layer "In4.Cu")
		(net "M_J_CPU1_SA_DQS_DN<8>")
	)
	(segment
		(start 161.434018 -232.396538)
		(end 161.710878 -232.396538)
		(width 0.16002)
		(layer "In4.Cu")
		(net "M_J_CPU1_SA_DQS_DN<8>")
	)
	(segment
		(start 134.61619 -242.3795)
		(end 134.624572 -242.384326)
		(width 0.09525)
		(layer "In4.Cu")
		(net "M_J_CPU1_SA_DQS_DN<8>")
	)
	(segment
		(start 175.574198 -230.058214)
		(end 178.151282 -230.058214)
		(width 0.16002)
		(layer "In4.Cu")
		(net "M_J_CPU1_SA_DQS_DN<8>")
	)
	(segment
		(start 174.287688 -229.720648)
		(end 175.236632 -229.720648)
		(width 0.16002)
		(layer "In4.Cu")
		(net "M_J_CPU1_SA_DQS_DN<8>")
	)
	(segment
		(start 138.74496 -242.384326)
		(end 138.753342 -242.3795)
		(width 0.09525)
		(layer "In4.Cu")
		(net "M_J_CPU1_SA_DQS_DN<8>")
	)
	(segment
		(start 183.143398 -230.058214)
		(end 183.98109 -230.058214)
		(width 0.16002)
		(layer "In4.Cu")
		(net "M_J_CPU1_SA_DQS_DN<8>")
	)
	(segment
		(start 169.991532 -229.738428)
		(end 171.161456 -230.908352)
		(width 0.16002)
		(layer "In4.Cu")
		(net "M_J_CPU1_SA_DQS_DN<8>")
	)
	(segment
		(start 157.98292 -235.221272)
		(end 158.886144 -235.221272)
		(width 0.16002)
		(layer "In4.Cu")
		(net "M_J_CPU1_SA_DQS_DN<8>")
	)
	(segment
		(start 159.817308 -233.527092)
		(end 160.060386 -233.77017)
		(width 0.16002)
		(layer "In4.Cu")
		(net "M_J_CPU1_SA_DQS_DN<8>")
	)
	(segment
		(start 146.308826 -241.970306)
		(end 146.810476 -241.970306)
		(width 0.09525)
		(layer "In4.Cu")
		(net "M_J_CPU1_SA_DQS_DN<8>")
	)
	(segment
		(start 163.08451 -231.022906)
		(end 163.599368 -230.508048)
		(width 0.16002)
		(layer "In4.Cu")
		(net "M_J_CPU1_SA_DQS_DN<8>")
	)
	(segment
		(start 183.98109 -230.058214)
		(end 184.130188 -229.909116)
		(width 0.16002)
		(layer "In4.Cu")
		(net "M_J_CPU1_SA_DQS_DN<8>")
	)
	(segment
		(start 162.80765 -231.022906)
		(end 163.08451 -231.022906)
		(width 0.16002)
		(layer "In4.Cu")
		(net "M_J_CPU1_SA_DQS_DN<8>")
	)
	(segment
		(start 179.00142 -230.908352)
		(end 180.128164 -230.908352)
		(width 0.16002)
		(layer "In4.Cu")
		(net "M_J_CPU1_SA_DQS_DN<8>")
	)
	(segment
		(start 159.290004 -233.527092)
		(end 159.817308 -233.527092)
		(width 0.16002)
		(layer "In4.Cu")
		(net "M_J_CPU1_SA_DQS_DN<8>")
	)
	(segment
		(start 160.337246 -233.77017)
		(end 160.53308 -233.574336)
		(width 0.16002)
		(layer "In4.Cu")
		(net "M_J_CPU1_SA_DQS_DN<8>")
	)
	(segment
		(start 180.490368 -230.546148)
		(end 181.062884 -230.546148)
		(width 0.16002)
		(layer "In4.Cu")
		(net "M_J_CPU1_SA_DQS_DN<8>")
	)
	(segment
		(start 166.809928 -229.738428)
		(end 169.991532 -229.738428)
		(width 0.16002)
		(layer "In4.Cu")
		(net "M_J_CPU1_SA_DQS_DN<8>")
	)
	(segment
		(start 146.810476 -241.970306)
		(end 147.520914 -241.259868)
		(width 0.09525)
		(layer "In4.Cu")
		(net "M_J_CPU1_SA_DQS_DN<8>")
	)
	(segment
		(start 162.037268 -230.779828)
		(end 162.564572 -230.779828)
		(width 0.16002)
		(layer "In4.Cu")
		(net "M_J_CPU1_SA_DQS_DN<8>")
	)
	(segment
		(start 147.764754 -241.259868)
		(end 147.823936 -241.200686)
		(width 0.09525)
		(layer "In4.Cu")
		(net "M_J_CPU1_SA_DQS_DN<8>")
	)
	(segment
		(start 147.823936 -241.200686)
		(end 147.847558 -241.200686)
		(width 0.09525)
		(layer "In4.Cu")
		(net "M_J_CPU1_SA_DQS_DN<8>")
	)
	(segment
		(start 172.771308 -230.569008)
		(end 173.439328 -230.569008)
		(width 0.16002)
		(layer "In4.Cu")
		(net "M_J_CPU1_SA_DQS_DN<8>")
	)
	(segment
		(start 159.159448 -234.671108)
		(end 158.91637 -234.42803)
		(width 0.16002)
		(layer "In4.Cu")
		(net "M_J_CPU1_SA_DQS_DN<8>")
	)
	(segment
		(start 142.504922 -242.384326)
		(end 142.513304 -242.3795)
		(width 0.09525)
		(layer "In4.Cu")
		(net "M_J_CPU1_SA_DQS_DN<8>")
	)
	(segment
		(start 143.453358 -242.3795)
		(end 143.46809 -242.370864)
		(width 0.09525)
		(layer "In4.Cu")
		(net "M_J_CPU1_SA_DQS_DN<8>")
	)
	(segment
		(start 181.896004 -229.713028)
		(end 182.798212 -229.713028)
		(width 0.16002)
		(layer "In4.Cu")
		(net "M_J_CPU1_SA_DQS_DN<8>")
	)
	(segment
		(start 133.10489 -242.384326)
		(end 133.113272 -242.3795)
		(width 0.09525)
		(layer "In4.Cu")
		(net "M_J_CPU1_SA_DQS_DN<8>")
	)
	(segment
		(start 158.91637 -233.900726)
		(end 159.290004 -233.527092)
		(width 0.16002)
		(layer "In4.Cu")
		(net "M_J_CPU1_SA_DQS_DN<8>")
	)
	(segment
		(start 158.886144 -235.221272)
		(end 159.159448 -234.947968)
		(width 0.16002)
		(layer "In4.Cu")
		(net "M_J_CPU1_SA_DQS_DN<8>")
	)
	(arc
		(start 139.324588 -242.384326)
		(mid 139.50962 -242.43024)
		(end 139.693396 -242.3795)
		(width 0.09525)
		(layer "In4.Cu")
		(net "M_J_CPU1_SA_DQS_DN<8>")
	)
	(arc
		(start 136.873234 -242.3795)
		(mid 137.154666 -242.303745)
		(end 137.436098 -242.3795)
		(width 0.09525)
		(layer "In4.Cu")
		(net "M_J_CPU1_SA_DQS_DN<8>")
	)
	(arc
		(start 131.796282 -242.3795)
		(mid 131.98475 -242.430177)
		(end 132.173218 -242.3795)
		(width 0.09525)
		(layer "In4.Cu")
		(net "M_J_CPU1_SA_DQS_DN<8>")
	)
	(arc
		(start 140.63345 -242.3795)
		(mid 140.914882 -242.303745)
		(end 141.196314 -242.3795)
		(width 0.09525)
		(layer "In4.Cu")
		(net "M_J_CPU1_SA_DQS_DN<8>")
	)
	(arc
		(start 137.813288 -242.3795)
		(mid 138.09472 -242.303745)
		(end 138.376152 -242.3795)
		(width 0.09525)
		(layer "In4.Cu")
		(net "M_J_CPU1_SA_DQS_DN<8>")
	)
	(arc
		(start 141.196314 -242.3795)
		(mid 141.384782 -242.430177)
		(end 141.57325 -242.3795)
		(width 0.09525)
		(layer "In4.Cu")
		(net "M_J_CPU1_SA_DQS_DN<8>")
	)
	(arc
		(start 133.676136 -242.3795)
		(mid 133.859911 -242.430272)
		(end 134.044944 -242.384326)
		(width 0.09525)
		(layer "In4.Cu")
		(net "M_J_CPU1_SA_DQS_DN<8>")
	)
	(arc
		(start 133.113272 -242.3795)
		(mid 133.394704 -242.303745)
		(end 133.676136 -242.3795)
		(width 0.09525)
		(layer "In4.Cu")
		(net "M_J_CPU1_SA_DQS_DN<8>")
	)
	(arc
		(start 134.053326 -242.3795)
		(mid 134.334758 -242.303745)
		(end 134.61619 -242.3795)
		(width 0.09525)
		(layer "In4.Cu")
		(net "M_J_CPU1_SA_DQS_DN<8>")
	)
	(arc
		(start 137.436098 -242.3795)
		(mid 137.619873 -242.430272)
		(end 137.804906 -242.384326)
		(width 0.09525)
		(layer "In4.Cu")
		(net "M_J_CPU1_SA_DQS_DN<8>")
	)
	(arc
		(start 143.08455 -242.384326)
		(mid 143.269582 -242.43024)
		(end 143.453358 -242.3795)
		(width 0.09525)
		(layer "In4.Cu")
		(net "M_J_CPU1_SA_DQS_DN<8>")
	)
	(arc
		(start 134.624572 -242.384326)
		(mid 134.809604 -242.43024)
		(end 134.99338 -242.3795)
		(width 0.09525)
		(layer "In4.Cu")
		(net "M_J_CPU1_SA_DQS_DN<8>")
	)
	(arc
		(start 141.57325 -242.3795)
		(mid 141.854682 -242.303745)
		(end 142.136114 -242.3795)
		(width 0.09525)
		(layer "In4.Cu")
		(net "M_J_CPU1_SA_DQS_DN<8>")
	)
	(arc
		(start 140.264642 -242.384326)
		(mid 140.449674 -242.43024)
		(end 140.63345 -242.3795)
		(width 0.09525)
		(layer "In4.Cu")
		(net "M_J_CPU1_SA_DQS_DN<8>")
	)
	(arc
		(start 132.736082 -242.3795)
		(mid 132.919857 -242.430272)
		(end 133.10489 -242.384326)
		(width 0.09525)
		(layer "In4.Cu")
		(net "M_J_CPU1_SA_DQS_DN<8>")
	)
	(arc
		(start 131.299458 -242.34648)
		(mid 131.551742 -242.304786)
		(end 131.796282 -242.3795)
		(width 0.09525)
		(layer "In4.Cu")
		(net "M_J_CPU1_SA_DQS_DN<8>")
	)
	(arc
		(start 142.513304 -242.3795)
		(mid 142.794736 -242.303745)
		(end 143.076168 -242.3795)
		(width 0.09525)
		(layer "In4.Cu")
		(net "M_J_CPU1_SA_DQS_DN<8>")
	)
	(arc
		(start 143.46809 -242.370864)
		(mid 143.743549 -242.303479)
		(end 144.01673 -242.3795)
		(width 0.09525)
		(layer "In4.Cu")
		(net "M_J_CPU1_SA_DQS_DN<8>")
	)
	(arc
		(start 136.496298 -242.3795)
		(mid 136.684766 -242.430177)
		(end 136.873234 -242.3795)
		(width 0.09525)
		(layer "In4.Cu")
		(net "M_J_CPU1_SA_DQS_DN<8>")
	)
	(arc
		(start 132.173218 -242.3795)
		(mid 132.45465 -242.303745)
		(end 132.736082 -242.3795)
		(width 0.09525)
		(layer "In4.Cu")
		(net "M_J_CPU1_SA_DQS_DN<8>")
	)
	(arc
		(start 144.01673 -242.3795)
		(mid 144.107905 -242.417991)
		(end 144.20596 -242.431316)
		(width 0.09525)
		(layer "In4.Cu")
		(net "M_J_CPU1_SA_DQS_DN<8>")
	)
	(arc
		(start 134.99338 -242.3795)
		(mid 135.274812 -242.303745)
		(end 135.556244 -242.3795)
		(width 0.09525)
		(layer "In4.Cu")
		(net "M_J_CPU1_SA_DQS_DN<8>")
	)
	(arc
		(start 138.753342 -242.3795)
		(mid 139.034774 -242.303745)
		(end 139.316206 -242.3795)
		(width 0.09525)
		(layer "In4.Cu")
		(net "M_J_CPU1_SA_DQS_DN<8>")
	)
	(arc
		(start 142.136114 -242.3795)
		(mid 142.319889 -242.430272)
		(end 142.504922 -242.384326)
		(width 0.09525)
		(layer "In4.Cu")
		(net "M_J_CPU1_SA_DQS_DN<8>")
	)
	(arc
		(start 135.933434 -242.3795)
		(mid 136.214866 -242.303745)
		(end 136.496298 -242.3795)
		(width 0.09525)
		(layer "In4.Cu")
		(net "M_J_CPU1_SA_DQS_DN<8>")
	)
	(arc
		(start 135.564626 -242.384326)
		(mid 135.749658 -242.43024)
		(end 135.933434 -242.3795)
		(width 0.09525)
		(layer "In4.Cu")
		(net "M_J_CPU1_SA_DQS_DN<8>")
	)
	(arc
		(start 139.693396 -242.3795)
		(mid 139.974828 -242.303745)
		(end 140.25626 -242.3795)
		(width 0.09525)
		(layer "In4.Cu")
		(net "M_J_CPU1_SA_DQS_DN<8>")
	)
	(arc
		(start 138.376152 -242.3795)
		(mid 138.559927 -242.430272)
		(end 138.74496 -242.384326)
		(width 0.09525)
		(layer "In4.Cu")
		(net "M_J_CPU1_SA_DQS_DN<8>")
	)
	(segment
		(start 130.577844 -237.460282)
		(end 131.044696 -237.194344)
		(width 0.12954)
		(layer "F.Cu")
		(net "M_J_CPU1_SA_DQS_DN<7>")
	)
	(segment
		(start 172.432218 -221.558104)
		(end 172.771308 -221.219014)
		(width 0.16002)
		(layer "In4.Cu")
		(net "M_J_CPU1_SA_DQS_DN<7>")
	)
	(segment
		(start 147.895564 -235.462064)
		(end 147.919186 -235.462064)
		(width 0.09525)
		(layer "In4.Cu")
		(net "M_J_CPU1_SA_DQS_DN<7>")
	)
	(segment
		(start 166.040308 -221.158054)
		(end 166.809928 -220.388434)
		(width 0.16002)
		(layer "In4.Cu")
		(net "M_J_CPU1_SA_DQS_DN<7>")
	)
	(segment
		(start 164.627052 -220.882718)
		(end 164.627052 -221.35338)
		(width 0.16002)
		(layer "In4.Cu")
		(net "M_J_CPU1_SA_DQS_DN<7>")
	)
	(segment
		(start 163.354258 -221.35338)
		(end 163.354258 -220.882718)
		(width 0.16002)
		(layer "In4.Cu")
		(net "M_J_CPU1_SA_DQS_DN<7>")
	)
	(segment
		(start 131.044696 -237.194344)
		(end 131.19862 -237.459774)
		(width 0.09525)
		(layer "In4.Cu")
		(net "M_J_CPU1_SA_DQS_DN<7>")
	)
	(segment
		(start 138.74496 -237.52429)
		(end 138.753342 -237.519464)
		(width 0.09525)
		(layer "In4.Cu")
		(net "M_J_CPU1_SA_DQS_DN<7>")
	)
	(segment
		(start 145.410428 -237.460282)
		(end 146.163538 -236.707426)
		(width 0.09525)
		(layer "In4.Cu")
		(net "M_J_CPU1_SA_DQS_DN<7>")
	)
	(segment
		(start 184.130188 -220.559122)
		(end 186.786266 -220.559122)
		(width 0.16002)
		(layer "In4.Cu")
		(net "M_J_CPU1_SA_DQS_DN<7>")
	)
	(segment
		(start 146.868896 -236.094016)
		(end 147.441666 -235.521246)
		(width 0.09525)
		(layer "In4.Cu")
		(net "M_J_CPU1_SA_DQS_DN<7>")
	)
	(segment
		(start 145.327116 -237.522766)
		(end 145.332958 -237.519464)
		(width 0.09525)
		(layer "In4.Cu")
		(net "M_J_CPU1_SA_DQS_DN<7>")
	)
	(segment
		(start 142.504922 -237.52429)
		(end 142.505938 -237.523782)
		(width 0.09525)
		(layer "In4.Cu")
		(net "M_J_CPU1_SA_DQS_DN<7>")
	)
	(segment
		(start 166.809928 -220.388434)
		(end 169.991532 -220.388434)
		(width 0.16002)
		(layer "In4.Cu")
		(net "M_J_CPU1_SA_DQS_DN<7>")
	)
	(segment
		(start 134.61619 -237.519464)
		(end 134.624572 -237.52429)
		(width 0.09525)
		(layer "In4.Cu")
		(net "M_J_CPU1_SA_DQS_DN<7>")
	)
	(segment
		(start 149.244812 -235.462064)
		(end 156.052774 -228.654102)
		(width 0.16002)
		(layer "In4.Cu")
		(net "M_J_CPU1_SA_DQS_DN<7>")
	)
	(segment
		(start 156.052774 -228.654102)
		(end 156.052774 -226.299522)
		(width 0.16002)
		(layer "In4.Cu")
		(net "M_J_CPU1_SA_DQS_DN<7>")
	)
	(segment
		(start 156.052774 -226.299522)
		(end 160.803082 -221.549214)
		(width 0.16002)
		(layer "In4.Cu")
		(net "M_J_CPU1_SA_DQS_DN<7>")
	)
	(segment
		(start 179.001166 -221.558104)
		(end 180.128418 -221.558104)
		(width 0.16002)
		(layer "In4.Cu")
		(net "M_J_CPU1_SA_DQS_DN<7>")
	)
	(segment
		(start 161.41319 -221.35338)
		(end 161.41319 -220.882718)
		(width 0.16002)
		(layer "In4.Cu")
		(net "M_J_CPU1_SA_DQS_DN<7>")
	)
	(segment
		(start 165.54704 -221.158054)
		(end 166.040308 -221.158054)
		(width 0.16002)
		(layer "In4.Cu")
		(net "M_J_CPU1_SA_DQS_DN<7>")
	)
	(segment
		(start 161.217356 -221.549214)
		(end 161.41319 -221.35338)
		(width 0.16002)
		(layer "In4.Cu")
		(net "M_J_CPU1_SA_DQS_DN<7>")
	)
	(segment
		(start 135.556244 -237.519464)
		(end 135.564626 -237.52429)
		(width 0.09525)
		(layer "In4.Cu")
		(net "M_J_CPU1_SA_DQS_DN<7>")
	)
	(segment
		(start 164.822886 -221.549214)
		(end 165.15588 -221.549214)
		(width 0.16002)
		(layer "In4.Cu")
		(net "M_J_CPU1_SA_DQS_DN<7>")
	)
	(segment
		(start 172.771308 -221.219014)
		(end 173.439328 -221.219014)
		(width 0.16002)
		(layer "In4.Cu")
		(net "M_J_CPU1_SA_DQS_DN<7>")
	)
	(segment
		(start 180.490368 -221.196154)
		(end 181.062884 -221.196154)
		(width 0.16002)
		(layer "In4.Cu")
		(net "M_J_CPU1_SA_DQS_DN<7>")
	)
	(segment
		(start 147.441666 -235.521246)
		(end 147.836382 -235.521246)
		(width 0.09525)
		(layer "In4.Cu")
		(net "M_J_CPU1_SA_DQS_DN<7>")
	)
	(segment
		(start 163.72713 -220.509846)
		(end 164.25418 -220.509846)
		(width 0.16002)
		(layer "In4.Cu")
		(net "M_J_CPU1_SA_DQS_DN<7>")
	)
	(segment
		(start 144.392904 -237.519464)
		(end 144.403318 -237.513368)
		(width 0.09525)
		(layer "In4.Cu")
		(net "M_J_CPU1_SA_DQS_DN<7>")
	)
	(segment
		(start 134.044944 -237.52429)
		(end 134.053326 -237.519464)
		(width 0.09525)
		(layer "In4.Cu")
		(net "M_J_CPU1_SA_DQS_DN<7>")
	)
	(segment
		(start 163.158424 -221.549214)
		(end 163.354258 -221.35338)
		(width 0.16002)
		(layer "In4.Cu")
		(net "M_J_CPU1_SA_DQS_DN<7>")
	)
	(segment
		(start 140.25626 -237.519464)
		(end 140.264642 -237.52429)
		(width 0.09525)
		(layer "In4.Cu")
		(net "M_J_CPU1_SA_DQS_DN<7>")
	)
	(segment
		(start 164.627052 -221.35338)
		(end 164.822886 -221.549214)
		(width 0.16002)
		(layer "In4.Cu")
		(net "M_J_CPU1_SA_DQS_DN<7>")
	)
	(segment
		(start 173.439328 -221.219014)
		(end 174.287688 -220.370654)
		(width 0.16002)
		(layer "In4.Cu")
		(net "M_J_CPU1_SA_DQS_DN<7>")
	)
	(segment
		(start 143.076168 -237.519464)
		(end 143.08455 -237.52429)
		(width 0.09525)
		(layer "In4.Cu")
		(net "M_J_CPU1_SA_DQS_DN<7>")
	)
	(segment
		(start 183.98109 -220.70822)
		(end 184.130188 -220.559122)
		(width 0.16002)
		(layer "In4.Cu")
		(net "M_J_CPU1_SA_DQS_DN<7>")
	)
	(segment
		(start 178.151282 -220.70822)
		(end 179.001166 -221.558104)
		(width 0.16002)
		(layer "In4.Cu")
		(net "M_J_CPU1_SA_DQS_DN<7>")
	)
	(segment
		(start 169.991532 -220.388434)
		(end 171.161202 -221.558104)
		(width 0.16002)
		(layer "In4.Cu")
		(net "M_J_CPU1_SA_DQS_DN<7>")
	)
	(segment
		(start 145.32102 -237.526322)
		(end 145.327116 -237.522766)
		(width 0.09525)
		(layer "In4.Cu")
		(net "M_J_CPU1_SA_DQS_DN<7>")
	)
	(segment
		(start 164.25418 -220.509846)
		(end 164.627052 -220.882718)
		(width 0.16002)
		(layer "In4.Cu")
		(net "M_J_CPU1_SA_DQS_DN<7>")
	)
	(segment
		(start 146.163538 -236.43971)
		(end 146.509232 -236.094016)
		(width 0.09525)
		(layer "In4.Cu")
		(net "M_J_CPU1_SA_DQS_DN<7>")
	)
	(segment
		(start 171.161202 -221.558104)
		(end 172.432218 -221.558104)
		(width 0.16002)
		(layer "In4.Cu")
		(net "M_J_CPU1_SA_DQS_DN<7>")
	)
	(segment
		(start 133.10489 -237.52429)
		(end 133.113272 -237.519464)
		(width 0.09525)
		(layer "In4.Cu")
		(net "M_J_CPU1_SA_DQS_DN<7>")
	)
	(segment
		(start 144.005554 -237.513368)
		(end 144.015968 -237.519464)
		(width 0.09525)
		(layer "In4.Cu")
		(net "M_J_CPU1_SA_DQS_DN<7>")
	)
	(segment
		(start 162.685984 -221.35338)
		(end 162.881818 -221.549214)
		(width 0.16002)
		(layer "In4.Cu")
		(net "M_J_CPU1_SA_DQS_DN<7>")
	)
	(segment
		(start 131.19862 -237.459774)
		(end 131.299458 -237.486444)
		(width 0.09525)
		(layer "In4.Cu")
		(net "M_J_CPU1_SA_DQS_DN<7>")
	)
	(segment
		(start 146.163538 -236.707426)
		(end 146.163538 -236.43971)
		(width 0.09525)
		(layer "In4.Cu")
		(net "M_J_CPU1_SA_DQS_DN<7>")
	)
	(segment
		(start 162.685984 -220.882718)
		(end 162.685984 -221.35338)
		(width 0.16002)
		(layer "In4.Cu")
		(net "M_J_CPU1_SA_DQS_DN<7>")
	)
	(segment
		(start 162.881818 -221.549214)
		(end 163.158424 -221.549214)
		(width 0.16002)
		(layer "In4.Cu")
		(net "M_J_CPU1_SA_DQS_DN<7>")
	)
	(segment
		(start 162.313112 -220.509846)
		(end 162.685984 -220.882718)
		(width 0.16002)
		(layer "In4.Cu")
		(net "M_J_CPU1_SA_DQS_DN<7>")
	)
	(segment
		(start 163.354258 -220.882718)
		(end 163.72713 -220.509846)
		(width 0.16002)
		(layer "In4.Cu")
		(net "M_J_CPU1_SA_DQS_DN<7>")
	)
	(segment
		(start 175.574198 -220.70822)
		(end 178.151282 -220.70822)
		(width 0.16002)
		(layer "In4.Cu")
		(net "M_J_CPU1_SA_DQS_DN<7>")
	)
	(segment
		(start 165.15588 -221.549214)
		(end 165.54704 -221.158054)
		(width 0.16002)
		(layer "In4.Cu")
		(net "M_J_CPU1_SA_DQS_DN<7>")
	)
	(segment
		(start 161.41319 -220.882718)
		(end 161.786062 -220.509846)
		(width 0.16002)
		(layer "In4.Cu")
		(net "M_J_CPU1_SA_DQS_DN<7>")
	)
	(segment
		(start 181.896004 -220.363034)
		(end 182.798212 -220.363034)
		(width 0.16002)
		(layer "In4.Cu")
		(net "M_J_CPU1_SA_DQS_DN<7>")
	)
	(segment
		(start 161.786062 -220.509846)
		(end 162.313112 -220.509846)
		(width 0.16002)
		(layer "In4.Cu")
		(net "M_J_CPU1_SA_DQS_DN<7>")
	)
	(segment
		(start 160.803082 -221.549214)
		(end 161.217356 -221.549214)
		(width 0.16002)
		(layer "In4.Cu")
		(net "M_J_CPU1_SA_DQS_DN<7>")
	)
	(segment
		(start 183.143398 -220.70822)
		(end 183.98109 -220.70822)
		(width 0.16002)
		(layer "In4.Cu")
		(net "M_J_CPU1_SA_DQS_DN<7>")
	)
	(segment
		(start 181.062884 -221.196154)
		(end 181.896004 -220.363034)
		(width 0.16002)
		(layer "In4.Cu")
		(net "M_J_CPU1_SA_DQS_DN<7>")
	)
	(segment
		(start 147.836382 -235.521246)
		(end 147.895564 -235.462064)
		(width 0.09525)
		(layer "In4.Cu")
		(net "M_J_CPU1_SA_DQS_DN<7>")
	)
	(segment
		(start 139.316206 -237.519464)
		(end 139.324588 -237.52429)
		(width 0.09525)
		(layer "In4.Cu")
		(net "M_J_CPU1_SA_DQS_DN<7>")
	)
	(segment
		(start 174.287688 -220.370654)
		(end 175.236632 -220.370654)
		(width 0.16002)
		(layer "In4.Cu")
		(net "M_J_CPU1_SA_DQS_DN<7>")
	)
	(segment
		(start 186.786266 -220.559122)
		(end 187.060078 -220.28531)
		(width 0.16002)
		(layer "In4.Cu")
		(net "M_J_CPU1_SA_DQS_DN<7>")
	)
	(segment
		(start 182.798212 -220.363034)
		(end 183.143398 -220.70822)
		(width 0.16002)
		(layer "In4.Cu")
		(net "M_J_CPU1_SA_DQS_DN<7>")
	)
	(segment
		(start 145.332958 -237.519464)
		(end 145.333212 -237.519718)
		(width 0.09525)
		(layer "In4.Cu")
		(net "M_J_CPU1_SA_DQS_DN<7>")
	)
	(segment
		(start 147.919186 -235.462064)
		(end 149.244812 -235.462064)
		(width 0.16002)
		(layer "In4.Cu")
		(net "M_J_CPU1_SA_DQS_DN<7>")
	)
	(segment
		(start 142.505938 -237.523782)
		(end 142.513304 -237.519464)
		(width 0.09525)
		(layer "In4.Cu")
		(net "M_J_CPU1_SA_DQS_DN<7>")
	)
	(segment
		(start 137.804906 -237.52429)
		(end 137.813288 -237.519464)
		(width 0.09525)
		(layer "In4.Cu")
		(net "M_J_CPU1_SA_DQS_DN<7>")
	)
	(segment
		(start 175.236632 -220.370654)
		(end 175.574198 -220.70822)
		(width 0.16002)
		(layer "In4.Cu")
		(net "M_J_CPU1_SA_DQS_DN<7>")
	)
	(segment
		(start 146.509232 -236.094016)
		(end 146.868896 -236.094016)
		(width 0.09525)
		(layer "In4.Cu")
		(net "M_J_CPU1_SA_DQS_DN<7>")
	)
	(segment
		(start 180.128418 -221.558104)
		(end 180.490368 -221.196154)
		(width 0.16002)
		(layer "In4.Cu")
		(net "M_J_CPU1_SA_DQS_DN<7>")
	)
	(arc
		(start 134.99338 -237.519464)
		(mid 135.274812 -237.443709)
		(end 135.556244 -237.519464)
		(width 0.09525)
		(layer "In4.Cu")
		(net "M_J_CPU1_SA_DQS_DN<7>")
	)
	(arc
		(start 136.873234 -237.519464)
		(mid 137.154666 -237.443709)
		(end 137.436098 -237.519464)
		(width 0.09525)
		(layer "In4.Cu")
		(net "M_J_CPU1_SA_DQS_DN<7>")
	)
	(arc
		(start 141.57325 -237.519464)
		(mid 141.854682 -237.443709)
		(end 142.136114 -237.519464)
		(width 0.09525)
		(layer "In4.Cu")
		(net "M_J_CPU1_SA_DQS_DN<7>")
	)
	(arc
		(start 132.736082 -237.519464)
		(mid 132.919857 -237.570236)
		(end 133.10489 -237.52429)
		(width 0.09525)
		(layer "In4.Cu")
		(net "M_J_CPU1_SA_DQS_DN<7>")
	)
	(arc
		(start 131.796282 -237.519464)
		(mid 131.98475 -237.570141)
		(end 132.173218 -237.519464)
		(width 0.09525)
		(layer "In4.Cu")
		(net "M_J_CPU1_SA_DQS_DN<7>")
	)
	(arc
		(start 135.564626 -237.52429)
		(mid 135.749658 -237.570204)
		(end 135.933434 -237.519464)
		(width 0.09525)
		(layer "In4.Cu")
		(net "M_J_CPU1_SA_DQS_DN<7>")
	)
	(arc
		(start 134.624572 -237.52429)
		(mid 134.809604 -237.570204)
		(end 134.99338 -237.519464)
		(width 0.09525)
		(layer "In4.Cu")
		(net "M_J_CPU1_SA_DQS_DN<7>")
	)
	(arc
		(start 136.496298 -237.519464)
		(mid 136.684766 -237.570141)
		(end 136.873234 -237.519464)
		(width 0.09525)
		(layer "In4.Cu")
		(net "M_J_CPU1_SA_DQS_DN<7>")
	)
	(arc
		(start 134.053326 -237.519464)
		(mid 134.334758 -237.443709)
		(end 134.61619 -237.519464)
		(width 0.09525)
		(layer "In4.Cu")
		(net "M_J_CPU1_SA_DQS_DN<7>")
	)
	(arc
		(start 138.753342 -237.519464)
		(mid 139.034774 -237.443709)
		(end 139.316206 -237.519464)
		(width 0.09525)
		(layer "In4.Cu")
		(net "M_J_CPU1_SA_DQS_DN<7>")
	)
	(arc
		(start 132.173218 -237.519464)
		(mid 132.45465 -237.443709)
		(end 132.736082 -237.519464)
		(width 0.09525)
		(layer "In4.Cu")
		(net "M_J_CPU1_SA_DQS_DN<7>")
	)
	(arc
		(start 144.956022 -237.519464)
		(mid 145.137638 -237.570201)
		(end 145.32102 -237.526322)
		(width 0.09525)
		(layer "In4.Cu")
		(net "M_J_CPU1_SA_DQS_DN<7>")
	)
	(arc
		(start 131.320032 -237.478316)
		(mid 131.562774 -237.445546)
		(end 131.796282 -237.519464)
		(width 0.09525)
		(layer "In4.Cu")
		(net "M_J_CPU1_SA_DQS_DN<7>")
	)
	(arc
		(start 138.376152 -237.519464)
		(mid 138.559927 -237.570236)
		(end 138.74496 -237.52429)
		(width 0.09525)
		(layer "In4.Cu")
		(net "M_J_CPU1_SA_DQS_DN<7>")
	)
	(arc
		(start 133.113272 -237.519464)
		(mid 133.394704 -237.443709)
		(end 133.676136 -237.519464)
		(width 0.09525)
		(layer "In4.Cu")
		(net "M_J_CPU1_SA_DQS_DN<7>")
	)
	(arc
		(start 137.813288 -237.519464)
		(mid 138.09472 -237.443709)
		(end 138.376152 -237.519464)
		(width 0.09525)
		(layer "In4.Cu")
		(net "M_J_CPU1_SA_DQS_DN<7>")
	)
	(arc
		(start 141.196314 -237.519464)
		(mid 141.384782 -237.570141)
		(end 141.57325 -237.519464)
		(width 0.09525)
		(layer "In4.Cu")
		(net "M_J_CPU1_SA_DQS_DN<7>")
	)
	(arc
		(start 133.676136 -237.519464)
		(mid 133.859911 -237.570236)
		(end 134.044944 -237.52429)
		(width 0.09525)
		(layer "In4.Cu")
		(net "M_J_CPU1_SA_DQS_DN<7>")
	)
	(arc
		(start 140.63345 -237.519464)
		(mid 140.914882 -237.443709)
		(end 141.196314 -237.519464)
		(width 0.09525)
		(layer "In4.Cu")
		(net "M_J_CPU1_SA_DQS_DN<7>")
	)
	(arc
		(start 144.403318 -237.513368)
		(mid 144.68048 -237.443568)
		(end 144.956022 -237.519464)
		(width 0.09525)
		(layer "In4.Cu")
		(net "M_J_CPU1_SA_DQS_DN<7>")
	)
	(arc
		(start 143.08455 -237.52429)
		(mid 143.269582 -237.570204)
		(end 143.453358 -237.519464)
		(width 0.09525)
		(layer "In4.Cu")
		(net "M_J_CPU1_SA_DQS_DN<7>")
	)
	(arc
		(start 131.299458 -237.486444)
		(mid 131.309706 -237.482281)
		(end 131.320032 -237.478316)
		(width 0.09525)
		(layer "In4.Cu")
		(net "M_J_CPU1_SA_DQS_DN<7>")
	)
	(arc
		(start 142.136114 -237.519464)
		(mid 142.319889 -237.570236)
		(end 142.504922 -237.52429)
		(width 0.09525)
		(layer "In4.Cu")
		(net "M_J_CPU1_SA_DQS_DN<7>")
	)
	(arc
		(start 139.693396 -237.519464)
		(mid 139.974828 -237.443709)
		(end 140.25626 -237.519464)
		(width 0.09525)
		(layer "In4.Cu")
		(net "M_J_CPU1_SA_DQS_DN<7>")
	)
	(arc
		(start 145.333212 -237.519718)
		(mid 145.373739 -237.492496)
		(end 145.410428 -237.460282)
		(width 0.09525)
		(layer "In4.Cu")
		(net "M_J_CPU1_SA_DQS_DN<7>")
	)
	(arc
		(start 137.436098 -237.519464)
		(mid 137.619873 -237.570236)
		(end 137.804906 -237.52429)
		(width 0.09525)
		(layer "In4.Cu")
		(net "M_J_CPU1_SA_DQS_DN<7>")
	)
	(arc
		(start 142.513304 -237.519464)
		(mid 142.794736 -237.443709)
		(end 143.076168 -237.519464)
		(width 0.09525)
		(layer "In4.Cu")
		(net "M_J_CPU1_SA_DQS_DN<7>")
	)
	(arc
		(start 135.933434 -237.519464)
		(mid 136.214866 -237.443709)
		(end 136.496298 -237.519464)
		(width 0.09525)
		(layer "In4.Cu")
		(net "M_J_CPU1_SA_DQS_DN<7>")
	)
	(arc
		(start 144.015968 -237.519464)
		(mid 144.204436 -237.570141)
		(end 144.392904 -237.519464)
		(width 0.09525)
		(layer "In4.Cu")
		(net "M_J_CPU1_SA_DQS_DN<7>")
	)
	(arc
		(start 140.264642 -237.52429)
		(mid 140.449674 -237.570204)
		(end 140.63345 -237.519464)
		(width 0.09525)
		(layer "In4.Cu")
		(net "M_J_CPU1_SA_DQS_DN<7>")
	)
	(arc
		(start 139.324588 -237.52429)
		(mid 139.50962 -237.570204)
		(end 139.693396 -237.519464)
		(width 0.09525)
		(layer "In4.Cu")
		(net "M_J_CPU1_SA_DQS_DN<7>")
	)
	(arc
		(start 143.453358 -237.519464)
		(mid 143.728647 -237.443743)
		(end 144.005554 -237.513368)
		(width 0.09525)
		(layer "In4.Cu")
		(net "M_J_CPU1_SA_DQS_DN<7>")
	)
	(segment
		(start 130.577844 -232.600246)
		(end 131.044696 -232.334308)
		(width 0.12954)
		(layer "F.Cu")
		(net "M_J_CPU1_SA_DQS_DN<6>")
	)
	(segment
		(start 166.809928 -211.03844)
		(end 169.991532 -211.03844)
		(width 0.16002)
		(layer "In4.Cu")
		(net "M_J_CPU1_SA_DQS_DN<6>")
	)
	(segment
		(start 143.73479 -232.583736)
		(end 144.107154 -232.583736)
		(width 0.09525)
		(layer "In4.Cu")
		(net "M_J_CPU1_SA_DQS_DN<6>")
	)
	(segment
		(start 161.189416 -211.510118)
		(end 161.562288 -211.137246)
		(width 0.16002)
		(layer "In4.Cu")
		(net "M_J_CPU1_SA_DQS_DN<6>")
	)
	(segment
		(start 173.439328 -211.86902)
		(end 174.287688 -211.02066)
		(width 0.16002)
		(layer "In4.Cu")
		(net "M_J_CPU1_SA_DQS_DN<6>")
	)
	(segment
		(start 164.599112 -212.422486)
		(end 164.999162 -212.422486)
		(width 0.16002)
		(layer "In4.Cu")
		(net "M_J_CPU1_SA_DQS_DN<6>")
	)
	(segment
		(start 131.19862 -232.599738)
		(end 131.299458 -232.626408)
		(width 0.09525)
		(layer "In4.Cu")
		(net "M_J_CPU1_SA_DQS_DN<6>")
	)
	(segment
		(start 181.062884 -211.84616)
		(end 181.896004 -211.01304)
		(width 0.16002)
		(layer "In4.Cu")
		(net "M_J_CPU1_SA_DQS_DN<6>")
	)
	(segment
		(start 163.130484 -212.226652)
		(end 163.130484 -211.510118)
		(width 0.16002)
		(layer "In4.Cu")
		(net "M_J_CPU1_SA_DQS_DN<6>")
	)
	(segment
		(start 163.503356 -211.137246)
		(end 164.030406 -211.137246)
		(width 0.16002)
		(layer "In4.Cu")
		(net "M_J_CPU1_SA_DQS_DN<6>")
	)
	(segment
		(start 134.61619 -232.659428)
		(end 134.624572 -232.664254)
		(width 0.09525)
		(layer "In4.Cu")
		(net "M_J_CPU1_SA_DQS_DN<6>")
	)
	(segment
		(start 150.515574 -222.151448)
		(end 160.244536 -212.422486)
		(width 0.16002)
		(layer "In4.Cu")
		(net "M_J_CPU1_SA_DQS_DN<6>")
	)
	(segment
		(start 180.490368 -211.84616)
		(end 181.062884 -211.84616)
		(width 0.16002)
		(layer "In4.Cu")
		(net "M_J_CPU1_SA_DQS_DN<6>")
	)
	(segment
		(start 137.804906 -232.664254)
		(end 137.813288 -232.659428)
		(width 0.09525)
		(layer "In4.Cu")
		(net "M_J_CPU1_SA_DQS_DN<6>")
	)
	(segment
		(start 180.128418 -212.20811)
		(end 180.490368 -211.84616)
		(width 0.16002)
		(layer "In4.Cu")
		(net "M_J_CPU1_SA_DQS_DN<6>")
	)
	(segment
		(start 181.896004 -211.01304)
		(end 182.798212 -211.01304)
		(width 0.16002)
		(layer "In4.Cu")
		(net "M_J_CPU1_SA_DQS_DN<6>")
	)
	(segment
		(start 172.771308 -211.86902)
		(end 173.439328 -211.86902)
		(width 0.16002)
		(layer "In4.Cu")
		(net "M_J_CPU1_SA_DQS_DN<6>")
	)
	(segment
		(start 186.786266 -211.209128)
		(end 187.060078 -210.935316)
		(width 0.16002)
		(layer "In4.Cu")
		(net "M_J_CPU1_SA_DQS_DN<6>")
	)
	(segment
		(start 175.236632 -211.02066)
		(end 175.574198 -211.358226)
		(width 0.16002)
		(layer "In4.Cu")
		(net "M_J_CPU1_SA_DQS_DN<6>")
	)
	(segment
		(start 183.143398 -211.358226)
		(end 183.98109 -211.358226)
		(width 0.16002)
		(layer "In4.Cu")
		(net "M_J_CPU1_SA_DQS_DN<6>")
	)
	(segment
		(start 131.044696 -232.334308)
		(end 131.19862 -232.599738)
		(width 0.09525)
		(layer "In4.Cu")
		(net "M_J_CPU1_SA_DQS_DN<6>")
	)
	(segment
		(start 147.088352 -229.305866)
		(end 147.671536 -228.722428)
		(width 0.09525)
		(layer "In4.Cu")
		(net "M_J_CPU1_SA_DQS_DN<6>")
	)
	(segment
		(start 139.316206 -232.659428)
		(end 139.324588 -232.664254)
		(width 0.09525)
		(layer "In4.Cu")
		(net "M_J_CPU1_SA_DQS_DN<6>")
	)
	(segment
		(start 162.658044 -212.422486)
		(end 162.93465 -212.422486)
		(width 0.16002)
		(layer "In4.Cu")
		(net "M_J_CPU1_SA_DQS_DN<6>")
	)
	(segment
		(start 165.613588 -211.80806)
		(end 166.040308 -211.80806)
		(width 0.16002)
		(layer "In4.Cu")
		(net "M_J_CPU1_SA_DQS_DN<6>")
	)
	(segment
		(start 162.93465 -212.422486)
		(end 163.130484 -212.226652)
		(width 0.16002)
		(layer "In4.Cu")
		(net "M_J_CPU1_SA_DQS_DN<6>")
	)
	(segment
		(start 172.432218 -212.20811)
		(end 172.771308 -211.86902)
		(width 0.16002)
		(layer "In4.Cu")
		(net "M_J_CPU1_SA_DQS_DN<6>")
	)
	(segment
		(start 160.993582 -212.422486)
		(end 161.189416 -212.226652)
		(width 0.16002)
		(layer "In4.Cu")
		(net "M_J_CPU1_SA_DQS_DN<6>")
	)
	(segment
		(start 133.10489 -232.664254)
		(end 133.113272 -232.659428)
		(width 0.09525)
		(layer "In4.Cu")
		(net "M_J_CPU1_SA_DQS_DN<6>")
	)
	(segment
		(start 134.044944 -232.664254)
		(end 134.053326 -232.659428)
		(width 0.09525)
		(layer "In4.Cu")
		(net "M_J_CPU1_SA_DQS_DN<6>")
	)
	(segment
		(start 138.74496 -232.664254)
		(end 138.753342 -232.659428)
		(width 0.09525)
		(layer "In4.Cu")
		(net "M_J_CPU1_SA_DQS_DN<6>")
	)
	(segment
		(start 162.46221 -211.510118)
		(end 162.46221 -212.226652)
		(width 0.16002)
		(layer "In4.Cu")
		(net "M_J_CPU1_SA_DQS_DN<6>")
	)
	(segment
		(start 147.6883 -228.62286)
		(end 150.515574 -225.795586)
		(width 0.16002)
		(layer "In4.Cu")
		(net "M_J_CPU1_SA_DQS_DN<6>")
	)
	(segment
		(start 164.403278 -211.510118)
		(end 164.403278 -212.226652)
		(width 0.16002)
		(layer "In4.Cu")
		(net "M_J_CPU1_SA_DQS_DN<6>")
	)
	(segment
		(start 178.151282 -211.358226)
		(end 179.001166 -212.20811)
		(width 0.16002)
		(layer "In4.Cu")
		(net "M_J_CPU1_SA_DQS_DN<6>")
	)
	(segment
		(start 169.991532 -211.03844)
		(end 171.161202 -212.20811)
		(width 0.16002)
		(layer "In4.Cu")
		(net "M_J_CPU1_SA_DQS_DN<6>")
	)
	(segment
		(start 162.089338 -211.137246)
		(end 162.46221 -211.510118)
		(width 0.16002)
		(layer "In4.Cu")
		(net "M_J_CPU1_SA_DQS_DN<6>")
	)
	(segment
		(start 166.040308 -211.80806)
		(end 166.809928 -211.03844)
		(width 0.16002)
		(layer "In4.Cu")
		(net "M_J_CPU1_SA_DQS_DN<6>")
	)
	(segment
		(start 142.504922 -232.664254)
		(end 142.513304 -232.659428)
		(width 0.09525)
		(layer "In4.Cu")
		(net "M_J_CPU1_SA_DQS_DN<6>")
	)
	(segment
		(start 161.189416 -212.226652)
		(end 161.189416 -211.510118)
		(width 0.16002)
		(layer "In4.Cu")
		(net "M_J_CPU1_SA_DQS_DN<6>")
	)
	(segment
		(start 175.574198 -211.358226)
		(end 178.151282 -211.358226)
		(width 0.16002)
		(layer "In4.Cu")
		(net "M_J_CPU1_SA_DQS_DN<6>")
	)
	(segment
		(start 179.001166 -212.20811)
		(end 180.128418 -212.20811)
		(width 0.16002)
		(layer "In4.Cu")
		(net "M_J_CPU1_SA_DQS_DN<6>")
	)
	(segment
		(start 164.999162 -212.422486)
		(end 165.613588 -211.80806)
		(width 0.16002)
		(layer "In4.Cu")
		(net "M_J_CPU1_SA_DQS_DN<6>")
	)
	(segment
		(start 182.798212 -211.01304)
		(end 183.143398 -211.358226)
		(width 0.16002)
		(layer "In4.Cu")
		(net "M_J_CPU1_SA_DQS_DN<6>")
	)
	(segment
		(start 174.287688 -211.02066)
		(end 175.236632 -211.02066)
		(width 0.16002)
		(layer "In4.Cu")
		(net "M_J_CPU1_SA_DQS_DN<6>")
	)
	(segment
		(start 163.130484 -211.510118)
		(end 163.503356 -211.137246)
		(width 0.16002)
		(layer "In4.Cu")
		(net "M_J_CPU1_SA_DQS_DN<6>")
	)
	(segment
		(start 162.46221 -212.226652)
		(end 162.658044 -212.422486)
		(width 0.16002)
		(layer "In4.Cu")
		(net "M_J_CPU1_SA_DQS_DN<6>")
	)
	(segment
		(start 164.403278 -212.226652)
		(end 164.599112 -212.422486)
		(width 0.16002)
		(layer "In4.Cu")
		(net "M_J_CPU1_SA_DQS_DN<6>")
	)
	(segment
		(start 146.102324 -229.955852)
		(end 146.75231 -229.305866)
		(width 0.09525)
		(layer "In4.Cu")
		(net "M_J_CPU1_SA_DQS_DN<6>")
	)
	(segment
		(start 183.98109 -211.358226)
		(end 184.130188 -211.209128)
		(width 0.16002)
		(layer "In4.Cu")
		(net "M_J_CPU1_SA_DQS_DN<6>")
	)
	(segment
		(start 146.75231 -229.305866)
		(end 147.088352 -229.305866)
		(width 0.09525)
		(layer "In4.Cu")
		(net "M_J_CPU1_SA_DQS_DN<6>")
	)
	(segment
		(start 147.671536 -228.722428)
		(end 147.671536 -228.639624)
		(width 0.09525)
		(layer "In4.Cu")
		(net "M_J_CPU1_SA_DQS_DN<6>")
	)
	(segment
		(start 146.102324 -230.588566)
		(end 146.102324 -229.955852)
		(width 0.09525)
		(layer "In4.Cu")
		(net "M_J_CPU1_SA_DQS_DN<6>")
	)
	(segment
		(start 184.130188 -211.209128)
		(end 186.786266 -211.209128)
		(width 0.16002)
		(layer "In4.Cu")
		(net "M_J_CPU1_SA_DQS_DN<6>")
	)
	(segment
		(start 147.671536 -228.639624)
		(end 147.6883 -228.62286)
		(width 0.09525)
		(layer "In4.Cu")
		(net "M_J_CPU1_SA_DQS_DN<6>")
	)
	(segment
		(start 171.161202 -212.20811)
		(end 172.432218 -212.20811)
		(width 0.16002)
		(layer "In4.Cu")
		(net "M_J_CPU1_SA_DQS_DN<6>")
	)
	(segment
		(start 143.076168 -232.659428)
		(end 143.08455 -232.664254)
		(width 0.09525)
		(layer "In4.Cu")
		(net "M_J_CPU1_SA_DQS_DN<6>")
	)
	(segment
		(start 140.25626 -232.659428)
		(end 140.264642 -232.664254)
		(width 0.09525)
		(layer "In4.Cu")
		(net "M_J_CPU1_SA_DQS_DN<6>")
	)
	(segment
		(start 164.030406 -211.137246)
		(end 164.403278 -211.510118)
		(width 0.16002)
		(layer "In4.Cu")
		(net "M_J_CPU1_SA_DQS_DN<6>")
	)
	(segment
		(start 161.562288 -211.137246)
		(end 162.089338 -211.137246)
		(width 0.16002)
		(layer "In4.Cu")
		(net "M_J_CPU1_SA_DQS_DN<6>")
	)
	(segment
		(start 144.107154 -232.583736)
		(end 146.102324 -230.588566)
		(width 0.09525)
		(layer "In4.Cu")
		(net "M_J_CPU1_SA_DQS_DN<6>")
	)
	(segment
		(start 135.556244 -232.659428)
		(end 135.564626 -232.664254)
		(width 0.09525)
		(layer "In4.Cu")
		(net "M_J_CPU1_SA_DQS_DN<6>")
	)
	(segment
		(start 160.244536 -212.422486)
		(end 160.993582 -212.422486)
		(width 0.16002)
		(layer "In4.Cu")
		(net "M_J_CPU1_SA_DQS_DN<6>")
	)
	(segment
		(start 150.515574 -225.795586)
		(end 150.515574 -222.151448)
		(width 0.16002)
		(layer "In4.Cu")
		(net "M_J_CPU1_SA_DQS_DN<6>")
	)
	(arc
		(start 132.173218 -232.659428)
		(mid 132.45465 -232.583673)
		(end 132.736082 -232.659428)
		(width 0.09525)
		(layer "In4.Cu")
		(net "M_J_CPU1_SA_DQS_DN<6>")
	)
	(arc
		(start 142.136114 -232.659428)
		(mid 142.319889 -232.7102)
		(end 142.504922 -232.664254)
		(width 0.09525)
		(layer "In4.Cu")
		(net "M_J_CPU1_SA_DQS_DN<6>")
	)
	(arc
		(start 133.676136 -232.659428)
		(mid 133.859911 -232.7102)
		(end 134.044944 -232.664254)
		(width 0.09525)
		(layer "In4.Cu")
		(net "M_J_CPU1_SA_DQS_DN<6>")
	)
	(arc
		(start 134.053326 -232.659428)
		(mid 134.334758 -232.583673)
		(end 134.61619 -232.659428)
		(width 0.09525)
		(layer "In4.Cu")
		(net "M_J_CPU1_SA_DQS_DN<6>")
	)
	(arc
		(start 137.813288 -232.659428)
		(mid 138.09472 -232.583673)
		(end 138.376152 -232.659428)
		(width 0.09525)
		(layer "In4.Cu")
		(net "M_J_CPU1_SA_DQS_DN<6>")
	)
	(arc
		(start 133.113272 -232.659428)
		(mid 133.394704 -232.583673)
		(end 133.676136 -232.659428)
		(width 0.09525)
		(layer "In4.Cu")
		(net "M_J_CPU1_SA_DQS_DN<6>")
	)
	(arc
		(start 134.99338 -232.659428)
		(mid 135.274812 -232.583673)
		(end 135.556244 -232.659428)
		(width 0.09525)
		(layer "In4.Cu")
		(net "M_J_CPU1_SA_DQS_DN<6>")
	)
	(arc
		(start 132.736082 -232.659428)
		(mid 132.919857 -232.7102)
		(end 133.10489 -232.664254)
		(width 0.09525)
		(layer "In4.Cu")
		(net "M_J_CPU1_SA_DQS_DN<6>")
	)
	(arc
		(start 137.436098 -232.659428)
		(mid 137.619873 -232.7102)
		(end 137.804906 -232.664254)
		(width 0.09525)
		(layer "In4.Cu")
		(net "M_J_CPU1_SA_DQS_DN<6>")
	)
	(arc
		(start 135.933434 -232.659428)
		(mid 136.214866 -232.583673)
		(end 136.496298 -232.659428)
		(width 0.09525)
		(layer "In4.Cu")
		(net "M_J_CPU1_SA_DQS_DN<6>")
	)
	(arc
		(start 131.299458 -232.626408)
		(mid 131.309706 -232.622245)
		(end 131.320032 -232.61828)
		(width 0.09525)
		(layer "In4.Cu")
		(net "M_J_CPU1_SA_DQS_DN<6>")
	)
	(arc
		(start 142.513304 -232.659428)
		(mid 142.794736 -232.583673)
		(end 143.076168 -232.659428)
		(width 0.09525)
		(layer "In4.Cu")
		(net "M_J_CPU1_SA_DQS_DN<6>")
	)
	(arc
		(start 135.564626 -232.664254)
		(mid 135.749658 -232.710168)
		(end 135.933434 -232.659428)
		(width 0.09525)
		(layer "In4.Cu")
		(net "M_J_CPU1_SA_DQS_DN<6>")
	)
	(arc
		(start 136.496298 -232.659428)
		(mid 136.684766 -232.710105)
		(end 136.873234 -232.659428)
		(width 0.09525)
		(layer "In4.Cu")
		(net "M_J_CPU1_SA_DQS_DN<6>")
	)
	(arc
		(start 131.320032 -232.61828)
		(mid 131.562774 -232.58551)
		(end 131.796282 -232.659428)
		(width 0.09525)
		(layer "In4.Cu")
		(net "M_J_CPU1_SA_DQS_DN<6>")
	)
	(arc
		(start 136.873234 -232.659428)
		(mid 137.154666 -232.583673)
		(end 137.436098 -232.659428)
		(width 0.09525)
		(layer "In4.Cu")
		(net "M_J_CPU1_SA_DQS_DN<6>")
	)
	(arc
		(start 141.196314 -232.659428)
		(mid 141.384782 -232.710105)
		(end 141.57325 -232.659428)
		(width 0.09525)
		(layer "In4.Cu")
		(net "M_J_CPU1_SA_DQS_DN<6>")
	)
	(arc
		(start 141.57325 -232.659428)
		(mid 141.854682 -232.583673)
		(end 142.136114 -232.659428)
		(width 0.09525)
		(layer "In4.Cu")
		(net "M_J_CPU1_SA_DQS_DN<6>")
	)
	(arc
		(start 143.08455 -232.664254)
		(mid 143.269582 -232.710168)
		(end 143.453358 -232.659428)
		(width 0.09525)
		(layer "In4.Cu")
		(net "M_J_CPU1_SA_DQS_DN<6>")
	)
	(arc
		(start 143.453358 -232.659428)
		(mid 143.589065 -232.602943)
		(end 143.73479 -232.583736)
		(width 0.09525)
		(layer "In4.Cu")
		(net "M_J_CPU1_SA_DQS_DN<6>")
	)
	(arc
		(start 138.753342 -232.659428)
		(mid 139.034774 -232.583673)
		(end 139.316206 -232.659428)
		(width 0.09525)
		(layer "In4.Cu")
		(net "M_J_CPU1_SA_DQS_DN<6>")
	)
	(arc
		(start 139.693396 -232.659428)
		(mid 139.974828 -232.583673)
		(end 140.25626 -232.659428)
		(width 0.09525)
		(layer "In4.Cu")
		(net "M_J_CPU1_SA_DQS_DN<6>")
	)
	(arc
		(start 140.264642 -232.664254)
		(mid 140.449674 -232.710168)
		(end 140.63345 -232.659428)
		(width 0.09525)
		(layer "In4.Cu")
		(net "M_J_CPU1_SA_DQS_DN<6>")
	)
	(arc
		(start 139.324588 -232.664254)
		(mid 139.50962 -232.710168)
		(end 139.693396 -232.659428)
		(width 0.09525)
		(layer "In4.Cu")
		(net "M_J_CPU1_SA_DQS_DN<6>")
	)
	(arc
		(start 134.624572 -232.664254)
		(mid 134.809604 -232.710168)
		(end 134.99338 -232.659428)
		(width 0.09525)
		(layer "In4.Cu")
		(net "M_J_CPU1_SA_DQS_DN<6>")
	)
	(arc
		(start 140.63345 -232.659428)
		(mid 140.914882 -232.583673)
		(end 141.196314 -232.659428)
		(width 0.09525)
		(layer "In4.Cu")
		(net "M_J_CPU1_SA_DQS_DN<6>")
	)
	(arc
		(start 138.376152 -232.659428)
		(mid 138.559927 -232.7102)
		(end 138.74496 -232.664254)
		(width 0.09525)
		(layer "In4.Cu")
		(net "M_J_CPU1_SA_DQS_DN<6>")
	)
	(arc
		(start 131.796282 -232.659428)
		(mid 131.98475 -232.710105)
		(end 132.173218 -232.659428)
		(width 0.09525)
		(layer "In4.Cu")
		(net "M_J_CPU1_SA_DQS_DN<6>")
	)
	(segment
		(start 130.577844 -227.740464)
		(end 131.044696 -227.474526)
		(width 0.12954)
		(layer "F.Cu")
		(net "M_J_CPU1_SA_DQS_DN<5>")
	)
	(segment
		(start 173.439328 -202.519026)
		(end 174.287688 -201.670666)
		(width 0.16002)
		(layer "In4.Cu")
		(net "M_J_CPU1_SA_DQS_DN<5>")
	)
	(segment
		(start 178.151282 -202.008232)
		(end 179.001166 -202.858116)
		(width 0.16002)
		(layer "In4.Cu")
		(net "M_J_CPU1_SA_DQS_DN<5>")
	)
	(segment
		(start 184.130188 -201.859134)
		(end 186.786266 -201.859134)
		(width 0.16002)
		(layer "In4.Cu")
		(net "M_J_CPU1_SA_DQS_DN<5>")
	)
	(segment
		(start 169.991532 -201.688446)
		(end 171.161202 -202.858116)
		(width 0.16002)
		(layer "In4.Cu")
		(net "M_J_CPU1_SA_DQS_DN<5>")
	)
	(segment
		(start 159.389572 -203.882244)
		(end 159.804862 -203.466954)
		(width 0.16002)
		(layer "In4.Cu")
		(net "M_J_CPU1_SA_DQS_DN<5>")
	)
	(segment
		(start 172.432218 -202.858116)
		(end 172.771308 -202.519026)
		(width 0.16002)
		(layer "In4.Cu")
		(net "M_J_CPU1_SA_DQS_DN<5>")
	)
	(segment
		(start 163.67125 -202.653392)
		(end 163.867084 -202.849226)
		(width 0.16002)
		(layer "In4.Cu")
		(net "M_J_CPU1_SA_DQS_DN<5>")
	)
	(segment
		(start 179.001166 -202.858116)
		(end 180.128418 -202.858116)
		(width 0.16002)
		(layer "In4.Cu")
		(net "M_J_CPU1_SA_DQS_DN<5>")
	)
	(segment
		(start 183.143398 -202.008232)
		(end 183.98109 -202.008232)
		(width 0.16002)
		(layer "In4.Cu")
		(net "M_J_CPU1_SA_DQS_DN<5>")
	)
	(segment
		(start 159.804862 -203.466954)
		(end 160.525714 -203.466954)
		(width 0.16002)
		(layer "In4.Cu")
		(net "M_J_CPU1_SA_DQS_DN<5>")
	)
	(segment
		(start 142.043404 -226.98964)
		(end 142.0749 -226.971352)
		(width 0.09525)
		(layer "In4.Cu")
		(net "M_J_CPU1_SA_DQS_DN<5>")
	)
	(segment
		(start 183.98109 -202.008232)
		(end 184.130188 -201.859134)
		(width 0.16002)
		(layer "In4.Cu")
		(net "M_J_CPU1_SA_DQS_DN<5>")
	)
	(segment
		(start 157.77845 -206.214218)
		(end 158.01594 -205.976728)
		(width 0.16002)
		(layer "In4.Cu")
		(net "M_J_CPU1_SA_DQS_DN<5>")
	)
	(segment
		(start 131.044696 -227.474526)
		(end 131.19862 -227.739956)
		(width 0.09525)
		(layer "In4.Cu")
		(net "M_J_CPU1_SA_DQS_DN<5>")
	)
	(segment
		(start 159.152082 -204.840586)
		(end 159.389572 -204.603096)
		(width 0.16002)
		(layer "In4.Cu")
		(net "M_J_CPU1_SA_DQS_DN<5>")
	)
	(segment
		(start 143.923258 -223.749616)
		(end 143.95577 -223.73082)
		(width 0.09525)
		(layer "In4.Cu")
		(net "M_J_CPU1_SA_DQS_DN<5>")
	)
	(segment
		(start 166.040308 -202.458066)
		(end 166.809928 -201.688446)
		(width 0.16002)
		(layer "In4.Cu")
		(net "M_J_CPU1_SA_DQS_DN<5>")
	)
	(segment
		(start 144.978374 -221.359476)
		(end 144.978374 -218.246706)
		(width 0.16002)
		(layer "In4.Cu")
		(net "M_J_CPU1_SA_DQS_DN<5>")
	)
	(segment
		(start 133.10489 -227.804472)
		(end 133.113272 -227.799646)
		(width 0.09525)
		(layer "In4.Cu")
		(net "M_J_CPU1_SA_DQS_DN<5>")
	)
	(segment
		(start 158.01594 -205.255876)
		(end 158.43123 -204.840586)
		(width 0.16002)
		(layer "In4.Cu")
		(net "M_J_CPU1_SA_DQS_DN<5>")
	)
	(segment
		(start 143.415258 -224.58172)
		(end 143.453358 -224.559622)
		(width 0.09525)
		(layer "In4.Cu")
		(net "M_J_CPU1_SA_DQS_DN<5>")
	)
	(segment
		(start 172.771308 -202.519026)
		(end 173.439328 -202.519026)
		(width 0.16002)
		(layer "In4.Cu")
		(net "M_J_CPU1_SA_DQS_DN<5>")
	)
	(segment
		(start 180.128418 -202.858116)
		(end 180.490368 -202.496166)
		(width 0.16002)
		(layer "In4.Cu")
		(net "M_J_CPU1_SA_DQS_DN<5>")
	)
	(segment
		(start 144.393412 -222.93961)
		(end 144.422622 -222.922846)
		(width 0.09525)
		(layer "In4.Cu")
		(net "M_J_CPU1_SA_DQS_DN<5>")
	)
	(segment
		(start 166.809928 -201.688446)
		(end 169.991532 -201.688446)
		(width 0.16002)
		(layer "In4.Cu")
		(net "M_J_CPU1_SA_DQS_DN<5>")
	)
	(segment
		(start 156.642308 -207.35036)
		(end 156.642308 -206.629508)
		(width 0.16002)
		(layer "In4.Cu")
		(net "M_J_CPU1_SA_DQS_DN<5>")
	)
	(segment
		(start 144.824958 -222.15221)
		(end 144.848834 -222.1357)
		(width 0.09525)
		(layer "In4.Cu")
		(net "M_J_CPU1_SA_DQS_DN<5>")
	)
	(segment
		(start 181.062884 -202.496166)
		(end 181.896004 -201.663046)
		(width 0.16002)
		(layer "In4.Cu")
		(net "M_J_CPU1_SA_DQS_DN<5>")
	)
	(segment
		(start 159.389572 -204.603096)
		(end 159.389572 -203.882244)
		(width 0.16002)
		(layer "In4.Cu")
		(net "M_J_CPU1_SA_DQS_DN<5>")
	)
	(segment
		(start 174.287688 -201.670666)
		(end 175.236632 -201.670666)
		(width 0.16002)
		(layer "In4.Cu")
		(net "M_J_CPU1_SA_DQS_DN<5>")
	)
	(segment
		(start 134.61619 -227.799646)
		(end 134.624572 -227.804472)
		(width 0.09525)
		(layer "In4.Cu")
		(net "M_J_CPU1_SA_DQS_DN<5>")
	)
	(segment
		(start 163.298378 -201.660506)
		(end 163.67125 -202.033378)
		(width 0.16002)
		(layer "In4.Cu")
		(net "M_J_CPU1_SA_DQS_DN<5>")
	)
	(segment
		(start 134.044944 -227.804472)
		(end 134.053326 -227.799646)
		(width 0.09525)
		(layer "In4.Cu")
		(net "M_J_CPU1_SA_DQS_DN<5>")
	)
	(segment
		(start 162.202622 -202.849226)
		(end 162.398456 -202.653392)
		(width 0.16002)
		(layer "In4.Cu")
		(net "M_J_CPU1_SA_DQS_DN<5>")
	)
	(segment
		(start 162.398456 -202.653392)
		(end 162.398456 -202.033378)
		(width 0.16002)
		(layer "In4.Cu")
		(net "M_J_CPU1_SA_DQS_DN<5>")
	)
	(segment
		(start 163.67125 -202.033378)
		(end 163.67125 -202.653392)
		(width 0.16002)
		(layer "In4.Cu")
		(net "M_J_CPU1_SA_DQS_DN<5>")
	)
	(segment
		(start 156.642308 -206.629508)
		(end 157.057598 -206.214218)
		(width 0.16002)
		(layer "In4.Cu")
		(net "M_J_CPU1_SA_DQS_DN<5>")
	)
	(segment
		(start 155.587446 -207.637634)
		(end 156.355034 -207.637634)
		(width 0.16002)
		(layer "In4.Cu")
		(net "M_J_CPU1_SA_DQS_DN<5>")
	)
	(segment
		(start 138.74496 -227.804472)
		(end 138.753342 -227.799646)
		(width 0.09525)
		(layer "In4.Cu")
		(net "M_J_CPU1_SA_DQS_DN<5>")
	)
	(segment
		(start 158.01594 -205.976728)
		(end 158.01594 -205.255876)
		(width 0.16002)
		(layer "In4.Cu")
		(net "M_J_CPU1_SA_DQS_DN<5>")
	)
	(segment
		(start 145.08353 -221.744286)
		(end 145.037556 -221.698312)
		(width 0.09525)
		(layer "In4.Cu")
		(net "M_J_CPU1_SA_DQS_DN<5>")
	)
	(segment
		(start 143.885158 -223.771714)
		(end 143.923258 -223.749616)
		(width 0.09525)
		(layer "In4.Cu")
		(net "M_J_CPU1_SA_DQS_DN<5>")
	)
	(segment
		(start 135.556244 -227.799646)
		(end 135.564626 -227.804472)
		(width 0.09525)
		(layer "In4.Cu")
		(net "M_J_CPU1_SA_DQS_DN<5>")
	)
	(segment
		(start 165.613588 -202.458066)
		(end 166.040308 -202.458066)
		(width 0.16002)
		(layer "In4.Cu")
		(net "M_J_CPU1_SA_DQS_DN<5>")
	)
	(segment
		(start 142.005304 -227.011738)
		(end 142.043404 -226.98964)
		(width 0.09525)
		(layer "In4.Cu")
		(net "M_J_CPU1_SA_DQS_DN<5>")
	)
	(segment
		(start 144.355312 -222.961708)
		(end 144.393412 -222.93961)
		(width 0.09525)
		(layer "In4.Cu")
		(net "M_J_CPU1_SA_DQS_DN<5>")
	)
	(segment
		(start 182.798212 -201.663046)
		(end 183.143398 -202.008232)
		(width 0.16002)
		(layer "In4.Cu")
		(net "M_J_CPU1_SA_DQS_DN<5>")
	)
	(segment
		(start 144.978374 -221.383098)
		(end 144.978374 -221.359476)
		(width 0.09525)
		(layer "In4.Cu")
		(net "M_J_CPU1_SA_DQS_DN<5>")
	)
	(segment
		(start 156.355034 -207.637634)
		(end 156.642308 -207.35036)
		(width 0.16002)
		(layer "In4.Cu")
		(net "M_J_CPU1_SA_DQS_DN<5>")
	)
	(segment
		(start 186.786266 -201.859134)
		(end 187.060078 -201.585322)
		(width 0.16002)
		(layer "In4.Cu")
		(net "M_J_CPU1_SA_DQS_DN<5>")
	)
	(segment
		(start 143.453358 -224.559622)
		(end 143.484854 -224.541334)
		(width 0.09525)
		(layer "In4.Cu")
		(net "M_J_CPU1_SA_DQS_DN<5>")
	)
	(segment
		(start 144.978374 -218.246706)
		(end 155.587446 -207.637634)
		(width 0.16002)
		(layer "In4.Cu")
		(net "M_J_CPU1_SA_DQS_DN<5>")
	)
	(segment
		(start 181.896004 -201.663046)
		(end 182.798212 -201.663046)
		(width 0.16002)
		(layer "In4.Cu")
		(net "M_J_CPU1_SA_DQS_DN<5>")
	)
	(segment
		(start 142.983204 -225.369628)
		(end 143.015716 -225.350832)
		(width 0.09525)
		(layer "In4.Cu")
		(net "M_J_CPU1_SA_DQS_DN<5>")
	)
	(segment
		(start 144.582134 -222.61449)
		(end 144.582388 -222.61449)
		(width 0.09525)
		(layer "In4.Cu")
		(net "M_J_CPU1_SA_DQS_DN<5>")
	)
	(segment
		(start 144.848834 -222.1357)
		(end 145.08353 -221.901004)
		(width 0.09525)
		(layer "In4.Cu")
		(net "M_J_CPU1_SA_DQS_DN<5>")
	)
	(segment
		(start 145.037556 -221.44228)
		(end 144.978374 -221.383098)
		(width 0.09525)
		(layer "In4.Cu")
		(net "M_J_CPU1_SA_DQS_DN<5>")
	)
	(segment
		(start 145.037556 -221.698312)
		(end 145.037556 -221.44228)
		(width 0.09525)
		(layer "In4.Cu")
		(net "M_J_CPU1_SA_DQS_DN<5>")
	)
	(segment
		(start 160.525714 -203.466954)
		(end 161.143442 -202.849226)
		(width 0.16002)
		(layer "In4.Cu")
		(net "M_J_CPU1_SA_DQS_DN<5>")
	)
	(segment
		(start 162.398456 -202.033378)
		(end 162.771328 -201.660506)
		(width 0.16002)
		(layer "In4.Cu")
		(net "M_J_CPU1_SA_DQS_DN<5>")
	)
	(segment
		(start 142.513304 -226.179634)
		(end 142.545816 -226.160838)
		(width 0.09525)
		(layer "In4.Cu")
		(net "M_J_CPU1_SA_DQS_DN<5>")
	)
	(segment
		(start 175.574198 -202.008232)
		(end 178.151282 -202.008232)
		(width 0.16002)
		(layer "In4.Cu")
		(net "M_J_CPU1_SA_DQS_DN<5>")
	)
	(segment
		(start 161.143442 -202.849226)
		(end 162.202622 -202.849226)
		(width 0.16002)
		(layer "In4.Cu")
		(net "M_J_CPU1_SA_DQS_DN<5>")
	)
	(segment
		(start 157.057598 -206.214218)
		(end 157.77845 -206.214218)
		(width 0.16002)
		(layer "In4.Cu")
		(net "M_J_CPU1_SA_DQS_DN<5>")
	)
	(segment
		(start 158.43123 -204.840586)
		(end 159.152082 -204.840586)
		(width 0.16002)
		(layer "In4.Cu")
		(net "M_J_CPU1_SA_DQS_DN<5>")
	)
	(segment
		(start 180.490368 -202.496166)
		(end 181.062884 -202.496166)
		(width 0.16002)
		(layer "In4.Cu")
		(net "M_J_CPU1_SA_DQS_DN<5>")
	)
	(segment
		(start 139.316206 -227.799646)
		(end 139.324588 -227.804472)
		(width 0.09525)
		(layer "In4.Cu")
		(net "M_J_CPU1_SA_DQS_DN<5>")
	)
	(segment
		(start 171.161202 -202.858116)
		(end 172.432218 -202.858116)
		(width 0.16002)
		(layer "In4.Cu")
		(net "M_J_CPU1_SA_DQS_DN<5>")
	)
	(segment
		(start 163.867084 -202.849226)
		(end 165.222428 -202.849226)
		(width 0.16002)
		(layer "In4.Cu")
		(net "M_J_CPU1_SA_DQS_DN<5>")
	)
	(segment
		(start 162.771328 -201.660506)
		(end 163.298378 -201.660506)
		(width 0.16002)
		(layer "In4.Cu")
		(net "M_J_CPU1_SA_DQS_DN<5>")
	)
	(segment
		(start 145.08353 -221.901004)
		(end 145.08353 -221.744286)
		(width 0.09525)
		(layer "In4.Cu")
		(net "M_J_CPU1_SA_DQS_DN<5>")
	)
	(segment
		(start 131.19862 -227.739956)
		(end 131.299458 -227.766626)
		(width 0.09525)
		(layer "In4.Cu")
		(net "M_J_CPU1_SA_DQS_DN<5>")
	)
	(segment
		(start 141.57325 -227.799646)
		(end 141.605762 -227.78085)
		(width 0.09525)
		(layer "In4.Cu")
		(net "M_J_CPU1_SA_DQS_DN<5>")
	)
	(segment
		(start 142.948152 -225.390202)
		(end 142.983204 -225.369628)
		(width 0.09525)
		(layer "In4.Cu")
		(net "M_J_CPU1_SA_DQS_DN<5>")
	)
	(segment
		(start 165.222428 -202.849226)
		(end 165.613588 -202.458066)
		(width 0.16002)
		(layer "In4.Cu")
		(net "M_J_CPU1_SA_DQS_DN<5>")
	)
	(segment
		(start 137.804906 -227.804472)
		(end 137.813288 -227.799646)
		(width 0.09525)
		(layer "In4.Cu")
		(net "M_J_CPU1_SA_DQS_DN<5>")
	)
	(segment
		(start 140.25626 -227.799646)
		(end 140.264642 -227.804472)
		(width 0.09525)
		(layer "In4.Cu")
		(net "M_J_CPU1_SA_DQS_DN<5>")
	)
	(segment
		(start 175.236632 -201.670666)
		(end 175.574198 -202.008232)
		(width 0.16002)
		(layer "In4.Cu")
		(net "M_J_CPU1_SA_DQS_DN<5>")
	)
	(segment
		(start 142.475204 -226.201732)
		(end 142.513304 -226.179634)
		(width 0.09525)
		(layer "In4.Cu")
		(net "M_J_CPU1_SA_DQS_DN<5>")
	)
	(arc
		(start 136.873234 -227.799646)
		(mid 137.154666 -227.723891)
		(end 137.436098 -227.799646)
		(width 0.09525)
		(layer "In4.Cu")
		(net "M_J_CPU1_SA_DQS_DN<5>")
	)
	(arc
		(start 143.642334 -224.234502)
		(mid 143.706731 -223.973196)
		(end 143.885158 -223.771714)
		(width 0.09525)
		(layer "In4.Cu")
		(net "M_J_CPU1_SA_DQS_DN<5>")
	)
	(arc
		(start 143.172434 -225.044508)
		(mid 143.236831 -224.783202)
		(end 143.415258 -224.58172)
		(width 0.09525)
		(layer "In4.Cu")
		(net "M_J_CPU1_SA_DQS_DN<5>")
	)
	(arc
		(start 132.736082 -227.799646)
		(mid 132.919857 -227.850418)
		(end 133.10489 -227.804472)
		(width 0.09525)
		(layer "In4.Cu")
		(net "M_J_CPU1_SA_DQS_DN<5>")
	)
	(arc
		(start 141.196314 -227.799646)
		(mid 141.384782 -227.850323)
		(end 141.57325 -227.799646)
		(width 0.09525)
		(layer "In4.Cu")
		(net "M_J_CPU1_SA_DQS_DN<5>")
	)
	(arc
		(start 139.324588 -227.804472)
		(mid 139.50962 -227.850386)
		(end 139.693396 -227.799646)
		(width 0.09525)
		(layer "In4.Cu")
		(net "M_J_CPU1_SA_DQS_DN<5>")
	)
	(arc
		(start 143.484854 -224.541334)
		(mid 143.600652 -224.40694)
		(end 143.642334 -224.234502)
		(width 0.09525)
		(layer "In4.Cu")
		(net "M_J_CPU1_SA_DQS_DN<5>")
	)
	(arc
		(start 140.63345 -227.799646)
		(mid 140.914882 -227.723891)
		(end 141.196314 -227.799646)
		(width 0.09525)
		(layer "In4.Cu")
		(net "M_J_CPU1_SA_DQS_DN<5>")
	)
	(arc
		(start 144.112488 -223.424496)
		(mid 144.176885 -223.16319)
		(end 144.355312 -222.961708)
		(width 0.09525)
		(layer "In4.Cu")
		(net "M_J_CPU1_SA_DQS_DN<5>")
	)
	(arc
		(start 132.173218 -227.799646)
		(mid 132.45465 -227.723891)
		(end 132.736082 -227.799646)
		(width 0.09525)
		(layer "In4.Cu")
		(net "M_J_CPU1_SA_DQS_DN<5>")
	)
	(arc
		(start 137.813288 -227.799646)
		(mid 138.09472 -227.723891)
		(end 138.376152 -227.799646)
		(width 0.09525)
		(layer "In4.Cu")
		(net "M_J_CPU1_SA_DQS_DN<5>")
	)
	(arc
		(start 138.376152 -227.799646)
		(mid 138.559927 -227.850418)
		(end 138.74496 -227.804472)
		(width 0.09525)
		(layer "In4.Cu")
		(net "M_J_CPU1_SA_DQS_DN<5>")
	)
	(arc
		(start 142.702534 -225.854514)
		(mid 142.767781 -225.591911)
		(end 142.948152 -225.390202)
		(width 0.09525)
		(layer "In4.Cu")
		(net "M_J_CPU1_SA_DQS_DN<5>")
	)
	(arc
		(start 136.496298 -227.799646)
		(mid 136.684766 -227.850323)
		(end 136.873234 -227.799646)
		(width 0.09525)
		(layer "In4.Cu")
		(net "M_J_CPU1_SA_DQS_DN<5>")
	)
	(arc
		(start 142.23238 -226.66452)
		(mid 142.296777 -226.403214)
		(end 142.475204 -226.201732)
		(width 0.09525)
		(layer "In4.Cu")
		(net "M_J_CPU1_SA_DQS_DN<5>")
	)
	(arc
		(start 131.299458 -227.766626)
		(mid 131.551742 -227.724932)
		(end 131.796282 -227.799646)
		(width 0.09525)
		(layer "In4.Cu")
		(net "M_J_CPU1_SA_DQS_DN<5>")
	)
	(arc
		(start 138.753342 -227.799646)
		(mid 139.034774 -227.723891)
		(end 139.316206 -227.799646)
		(width 0.09525)
		(layer "In4.Cu")
		(net "M_J_CPU1_SA_DQS_DN<5>")
	)
	(arc
		(start 133.113272 -227.799646)
		(mid 133.394704 -227.723891)
		(end 133.676136 -227.799646)
		(width 0.09525)
		(layer "In4.Cu")
		(net "M_J_CPU1_SA_DQS_DN<5>")
	)
	(arc
		(start 142.0749 -226.971352)
		(mid 142.190698 -226.836958)
		(end 142.23238 -226.66452)
		(width 0.09525)
		(layer "In4.Cu")
		(net "M_J_CPU1_SA_DQS_DN<5>")
	)
	(arc
		(start 134.99338 -227.799646)
		(mid 135.274812 -227.723891)
		(end 135.556244 -227.799646)
		(width 0.09525)
		(layer "In4.Cu")
		(net "M_J_CPU1_SA_DQS_DN<5>")
	)
	(arc
		(start 143.95577 -223.73082)
		(mid 144.071044 -223.596542)
		(end 144.112488 -223.424496)
		(width 0.09525)
		(layer "In4.Cu")
		(net "M_J_CPU1_SA_DQS_DN<5>")
	)
	(arc
		(start 135.564626 -227.804472)
		(mid 135.749658 -227.850386)
		(end 135.933434 -227.799646)
		(width 0.09525)
		(layer "In4.Cu")
		(net "M_J_CPU1_SA_DQS_DN<5>")
	)
	(arc
		(start 141.605762 -227.78085)
		(mid 141.721036 -227.646572)
		(end 141.76248 -227.474526)
		(width 0.09525)
		(layer "In4.Cu")
		(net "M_J_CPU1_SA_DQS_DN<5>")
	)
	(arc
		(start 140.264642 -227.804472)
		(mid 140.449674 -227.850386)
		(end 140.63345 -227.799646)
		(width 0.09525)
		(layer "In4.Cu")
		(net "M_J_CPU1_SA_DQS_DN<5>")
	)
	(arc
		(start 141.76248 -227.474526)
		(mid 141.826877 -227.21322)
		(end 142.005304 -227.011738)
		(width 0.09525)
		(layer "In4.Cu")
		(net "M_J_CPU1_SA_DQS_DN<5>")
	)
	(arc
		(start 137.436098 -227.799646)
		(mid 137.619873 -227.850418)
		(end 137.804906 -227.804472)
		(width 0.09525)
		(layer "In4.Cu")
		(net "M_J_CPU1_SA_DQS_DN<5>")
	)
	(arc
		(start 133.676136 -227.799646)
		(mid 133.859911 -227.850418)
		(end 134.044944 -227.804472)
		(width 0.09525)
		(layer "In4.Cu")
		(net "M_J_CPU1_SA_DQS_DN<5>")
	)
	(arc
		(start 134.053326 -227.799646)
		(mid 134.334758 -227.723891)
		(end 134.61619 -227.799646)
		(width 0.09525)
		(layer "In4.Cu")
		(net "M_J_CPU1_SA_DQS_DN<5>")
	)
	(arc
		(start 143.015716 -225.350832)
		(mid 143.13099 -225.216554)
		(end 143.172434 -225.044508)
		(width 0.09525)
		(layer "In4.Cu")
		(net "M_J_CPU1_SA_DQS_DN<5>")
	)
	(arc
		(start 134.624572 -227.804472)
		(mid 134.809604 -227.850386)
		(end 134.99338 -227.799646)
		(width 0.09525)
		(layer "In4.Cu")
		(net "M_J_CPU1_SA_DQS_DN<5>")
	)
	(arc
		(start 135.933434 -227.799646)
		(mid 136.214866 -227.723891)
		(end 136.496298 -227.799646)
		(width 0.09525)
		(layer "In4.Cu")
		(net "M_J_CPU1_SA_DQS_DN<5>")
	)
	(arc
		(start 144.582388 -222.61449)
		(mid 144.646708 -222.353455)
		(end 144.824958 -222.15221)
		(width 0.09525)
		(layer "In4.Cu")
		(net "M_J_CPU1_SA_DQS_DN<5>")
	)
	(arc
		(start 144.422622 -222.922846)
		(mid 144.539926 -222.788085)
		(end 144.582134 -222.61449)
		(width 0.09525)
		(layer "In4.Cu")
		(net "M_J_CPU1_SA_DQS_DN<5>")
	)
	(arc
		(start 142.545816 -226.160838)
		(mid 142.66109 -226.02656)
		(end 142.702534 -225.854514)
		(width 0.09525)
		(layer "In4.Cu")
		(net "M_J_CPU1_SA_DQS_DN<5>")
	)
	(arc
		(start 139.693396 -227.799646)
		(mid 139.974828 -227.723891)
		(end 140.25626 -227.799646)
		(width 0.09525)
		(layer "In4.Cu")
		(net "M_J_CPU1_SA_DQS_DN<5>")
	)
	(arc
		(start 131.796282 -227.799646)
		(mid 131.98475 -227.850323)
		(end 132.173218 -227.799646)
		(width 0.09525)
		(layer "In4.Cu")
		(net "M_J_CPU1_SA_DQS_DN<5>")
	)
	(segment
		(start 132.457952 -247.180354)
		(end 132.924804 -246.914416)
		(width 0.12954)
		(layer "F.Cu")
		(net "M_J_CPU1_SA_DQS_DN<4>")
	)
	(segment
		(start 142.504922 -246.58447)
		(end 142.513304 -246.589296)
		(width 0.09525)
		(layer "In4.Cu")
		(net "M_J_CPU1_SA_DQS_DN<4>")
	)
	(segment
		(start 175.66513 -237.712504)
		(end 177.012346 -237.712504)
		(width 0.16002)
		(layer "In4.Cu")
		(net "M_J_CPU1_SA_DQS_DN<4>")
	)
	(segment
		(start 147.834604 -246.236236)
		(end 147.858226 -246.236236)
		(width 0.09525)
		(layer "In4.Cu")
		(net "M_J_CPU1_SA_DQS_DN<4>")
	)
	(segment
		(start 190.886334 -238.711486)
		(end 191.160146 -238.985298)
		(width 0.16002)
		(layer "In4.Cu")
		(net "M_J_CPU1_SA_DQS_DN<4>")
	)
	(segment
		(start 147.858226 -246.236236)
		(end 155.77693 -246.236236)
		(width 0.16002)
		(layer "In4.Cu")
		(net "M_J_CPU1_SA_DQS_DN<4>")
	)
	(segment
		(start 190.406274 -238.711486)
		(end 190.886334 -238.711486)
		(width 0.16002)
		(layer "In4.Cu")
		(net "M_J_CPU1_SA_DQS_DN<4>")
	)
	(segment
		(start 177.012346 -237.712504)
		(end 177.86223 -238.562388)
		(width 0.16002)
		(layer "In4.Cu")
		(net "M_J_CPU1_SA_DQS_DN<4>")
	)
	(segment
		(start 146.02968 -246.665496)
		(end 146.30146 -246.937276)
		(width 0.09525)
		(layer "In4.Cu")
		(net "M_J_CPU1_SA_DQS_DN<4>")
	)
	(segment
		(start 140.25626 -246.589296)
		(end 140.264642 -246.58447)
		(width 0.09525)
		(layer "In4.Cu")
		(net "M_J_CPU1_SA_DQS_DN<4>")
	)
	(segment
		(start 189.692534 -238.711486)
		(end 189.809374 -238.828326)
		(width 0.16002)
		(layer "In4.Cu")
		(net "M_J_CPU1_SA_DQS_DN<4>")
	)
	(segment
		(start 134.044944 -246.58447)
		(end 134.053326 -246.589296)
		(width 0.09525)
		(layer "In4.Cu")
		(net "M_J_CPU1_SA_DQS_DN<4>")
	)
	(segment
		(start 146.30146 -246.937276)
		(end 146.976084 -246.937276)
		(width 0.09525)
		(layer "In4.Cu")
		(net "M_J_CPU1_SA_DQS_DN<4>")
	)
	(segment
		(start 133.10489 -246.58447)
		(end 133.113272 -246.589296)
		(width 0.09525)
		(layer "In4.Cu")
		(net "M_J_CPU1_SA_DQS_DN<4>")
	)
	(segment
		(start 144.95653 -246.589296)
		(end 144.971008 -246.580914)
		(width 0.09525)
		(layer "In4.Cu")
		(net "M_J_CPU1_SA_DQS_DN<4>")
	)
	(segment
		(start 146.976084 -246.937276)
		(end 147.678902 -246.177308)
		(width 0.09525)
		(layer "In4.Cu")
		(net "M_J_CPU1_SA_DQS_DN<4>")
	)
	(segment
		(start 190.289434 -238.828326)
		(end 190.406274 -238.711486)
		(width 0.16002)
		(layer "In4.Cu")
		(net "M_J_CPU1_SA_DQS_DN<4>")
	)
	(segment
		(start 147.678902 -246.177308)
		(end 147.775676 -246.177308)
		(width 0.09525)
		(layer "In4.Cu")
		(net "M_J_CPU1_SA_DQS_DN<4>")
	)
	(segment
		(start 188.937392 -238.892842)
		(end 189.118748 -238.711486)
		(width 0.16002)
		(layer "In4.Cu")
		(net "M_J_CPU1_SA_DQS_DN<4>")
	)
	(segment
		(start 180.416708 -238.938562)
		(end 181.199536 -238.938562)
		(width 0.16002)
		(layer "In4.Cu")
		(net "M_J_CPU1_SA_DQS_DN<4>")
	)
	(segment
		(start 177.86223 -238.562388)
		(end 180.040534 -238.562388)
		(width 0.16002)
		(layer "In4.Cu")
		(net "M_J_CPU1_SA_DQS_DN<4>")
	)
	(segment
		(start 161.340038 -241.853212)
		(end 164.287708 -238.905542)
		(width 0.16002)
		(layer "In4.Cu")
		(net "M_J_CPU1_SA_DQS_DN<4>")
	)
	(segment
		(start 187.757308 -238.892842)
		(end 188.937392 -238.892842)
		(width 0.16002)
		(layer "In4.Cu")
		(net "M_J_CPU1_SA_DQS_DN<4>")
	)
	(segment
		(start 181.969156 -238.168942)
		(end 182.67807 -238.168942)
		(width 0.16002)
		(layer "In4.Cu")
		(net "M_J_CPU1_SA_DQS_DN<4>")
	)
	(segment
		(start 144.941798 -246.597932)
		(end 144.95653 -246.589296)
		(width 0.09525)
		(layer "In4.Cu")
		(net "M_J_CPU1_SA_DQS_DN<4>")
	)
	(segment
		(start 155.77693 -246.236236)
		(end 160.159954 -241.853212)
		(width 0.16002)
		(layer "In4.Cu")
		(net "M_J_CPU1_SA_DQS_DN<4>")
	)
	(segment
		(start 172.799248 -238.918242)
		(end 173.630844 -238.918242)
		(width 0.16002)
		(layer "In4.Cu")
		(net "M_J_CPU1_SA_DQS_DN<4>")
	)
	(segment
		(start 166.133272 -238.905542)
		(end 167.007032 -238.031782)
		(width 0.16002)
		(layer "In4.Cu")
		(net "M_J_CPU1_SA_DQS_DN<4>")
	)
	(segment
		(start 138.74496 -246.58447)
		(end 138.753342 -246.589296)
		(width 0.09525)
		(layer "In4.Cu")
		(net "M_J_CPU1_SA_DQS_DN<4>")
	)
	(segment
		(start 189.118748 -238.711486)
		(end 189.692534 -238.711486)
		(width 0.16002)
		(layer "In4.Cu")
		(net "M_J_CPU1_SA_DQS_DN<4>")
	)
	(segment
		(start 183.134508 -237.712504)
		(end 184.497472 -237.712504)
		(width 0.16002)
		(layer "In4.Cu")
		(net "M_J_CPU1_SA_DQS_DN<4>")
	)
	(segment
		(start 172.443394 -238.562388)
		(end 172.799248 -238.918242)
		(width 0.16002)
		(layer "In4.Cu")
		(net "M_J_CPU1_SA_DQS_DN<4>")
	)
	(segment
		(start 173.630844 -238.918242)
		(end 174.309024 -238.240062)
		(width 0.16002)
		(layer "In4.Cu")
		(net "M_J_CPU1_SA_DQS_DN<4>")
	)
	(segment
		(start 135.556244 -246.589296)
		(end 135.564626 -246.58447)
		(width 0.09525)
		(layer "In4.Cu")
		(net "M_J_CPU1_SA_DQS_DN<4>")
	)
	(segment
		(start 132.924804 -246.914416)
		(end 132.77088 -246.648986)
		(width 0.09525)
		(layer "In4.Cu")
		(net "M_J_CPU1_SA_DQS_DN<4>")
	)
	(segment
		(start 167.007032 -238.031782)
		(end 170.005248 -238.031782)
		(width 0.16002)
		(layer "In4.Cu")
		(net "M_J_CPU1_SA_DQS_DN<4>")
	)
	(segment
		(start 144.385792 -246.58447)
		(end 144.394174 -246.589296)
		(width 0.09525)
		(layer "In4.Cu")
		(net "M_J_CPU1_SA_DQS_DN<4>")
	)
	(segment
		(start 139.316206 -246.589296)
		(end 139.324588 -246.58447)
		(width 0.09525)
		(layer "In4.Cu")
		(net "M_J_CPU1_SA_DQS_DN<4>")
	)
	(segment
		(start 187.033408 -238.168942)
		(end 187.757308 -238.892842)
		(width 0.16002)
		(layer "In4.Cu")
		(net "M_J_CPU1_SA_DQS_DN<4>")
	)
	(segment
		(start 181.199536 -238.938562)
		(end 181.969156 -238.168942)
		(width 0.16002)
		(layer "In4.Cu")
		(net "M_J_CPU1_SA_DQS_DN<4>")
	)
	(segment
		(start 174.309024 -238.240062)
		(end 175.137572 -238.240062)
		(width 0.16002)
		(layer "In4.Cu")
		(net "M_J_CPU1_SA_DQS_DN<4>")
	)
	(segment
		(start 180.040534 -238.562388)
		(end 180.416708 -238.938562)
		(width 0.16002)
		(layer "In4.Cu")
		(net "M_J_CPU1_SA_DQS_DN<4>")
	)
	(segment
		(start 164.287708 -238.905542)
		(end 166.133272 -238.905542)
		(width 0.16002)
		(layer "In4.Cu")
		(net "M_J_CPU1_SA_DQS_DN<4>")
	)
	(segment
		(start 147.775676 -246.177308)
		(end 147.834604 -246.236236)
		(width 0.09525)
		(layer "In4.Cu")
		(net "M_J_CPU1_SA_DQS_DN<4>")
	)
	(segment
		(start 184.497472 -237.712504)
		(end 184.95391 -238.168942)
		(width 0.16002)
		(layer "In4.Cu")
		(net "M_J_CPU1_SA_DQS_DN<4>")
	)
	(segment
		(start 175.137572 -238.240062)
		(end 175.66513 -237.712504)
		(width 0.16002)
		(layer "In4.Cu")
		(net "M_J_CPU1_SA_DQS_DN<4>")
	)
	(segment
		(start 189.809374 -238.828326)
		(end 190.289434 -238.828326)
		(width 0.16002)
		(layer "In4.Cu")
		(net "M_J_CPU1_SA_DQS_DN<4>")
	)
	(segment
		(start 184.95391 -238.168942)
		(end 187.033408 -238.168942)
		(width 0.16002)
		(layer "In4.Cu")
		(net "M_J_CPU1_SA_DQS_DN<4>")
	)
	(segment
		(start 132.77088 -246.648986)
		(end 132.794248 -246.562118)
		(width 0.09525)
		(layer "In4.Cu")
		(net "M_J_CPU1_SA_DQS_DN<4>")
	)
	(segment
		(start 170.535854 -238.562388)
		(end 172.443394 -238.562388)
		(width 0.16002)
		(layer "In4.Cu")
		(net "M_J_CPU1_SA_DQS_DN<4>")
	)
	(segment
		(start 182.67807 -238.168942)
		(end 183.134508 -237.712504)
		(width 0.16002)
		(layer "In4.Cu")
		(net "M_J_CPU1_SA_DQS_DN<4>")
	)
	(segment
		(start 143.076168 -246.589296)
		(end 143.08455 -246.58447)
		(width 0.09525)
		(layer "In4.Cu")
		(net "M_J_CPU1_SA_DQS_DN<4>")
	)
	(segment
		(start 143.453358 -246.589296)
		(end 143.463772 -246.595392)
		(width 0.09525)
		(layer "In4.Cu")
		(net "M_J_CPU1_SA_DQS_DN<4>")
	)
	(segment
		(start 134.61619 -246.589296)
		(end 134.624572 -246.58447)
		(width 0.09525)
		(layer "In4.Cu")
		(net "M_J_CPU1_SA_DQS_DN<4>")
	)
	(segment
		(start 160.159954 -241.853212)
		(end 161.340038 -241.853212)
		(width 0.16002)
		(layer "In4.Cu")
		(net "M_J_CPU1_SA_DQS_DN<4>")
	)
	(segment
		(start 137.804906 -246.58447)
		(end 137.813288 -246.589296)
		(width 0.09525)
		(layer "In4.Cu")
		(net "M_J_CPU1_SA_DQS_DN<4>")
	)
	(segment
		(start 170.005248 -238.031782)
		(end 170.535854 -238.562388)
		(width 0.16002)
		(layer "In4.Cu")
		(net "M_J_CPU1_SA_DQS_DN<4>")
	)
	(segment
		(start 145.615914 -246.665496)
		(end 146.02968 -246.665496)
		(width 0.09525)
		(layer "In4.Cu")
		(net "M_J_CPU1_SA_DQS_DN<4>")
	)
	(arc
		(start 145.33372 -246.589296)
		(mid 145.469772 -246.646065)
		(end 145.615914 -246.665496)
		(width 0.09525)
		(layer "In4.Cu")
		(net "M_J_CPU1_SA_DQS_DN<4>")
	)
	(arc
		(start 143.463772 -246.595392)
		(mid 143.740934 -246.665192)
		(end 144.016476 -246.589296)
		(width 0.09525)
		(layer "In4.Cu")
		(net "M_J_CPU1_SA_DQS_DN<4>")
	)
	(arc
		(start 133.676136 -246.589296)
		(mid 133.859911 -246.538524)
		(end 134.044944 -246.58447)
		(width 0.09525)
		(layer "In4.Cu")
		(net "M_J_CPU1_SA_DQS_DN<4>")
	)
	(arc
		(start 134.053326 -246.589296)
		(mid 134.334758 -246.665051)
		(end 134.61619 -246.589296)
		(width 0.09525)
		(layer "In4.Cu")
		(net "M_J_CPU1_SA_DQS_DN<4>")
	)
	(arc
		(start 137.813288 -246.589296)
		(mid 138.09472 -246.665051)
		(end 138.376152 -246.589296)
		(width 0.09525)
		(layer "In4.Cu")
		(net "M_J_CPU1_SA_DQS_DN<4>")
	)
	(arc
		(start 135.933434 -246.589296)
		(mid 136.214866 -246.665051)
		(end 136.496298 -246.589296)
		(width 0.09525)
		(layer "In4.Cu")
		(net "M_J_CPU1_SA_DQS_DN<4>")
	)
	(arc
		(start 138.376152 -246.589296)
		(mid 138.559927 -246.538524)
		(end 138.74496 -246.58447)
		(width 0.09525)
		(layer "In4.Cu")
		(net "M_J_CPU1_SA_DQS_DN<4>")
	)
	(arc
		(start 140.63345 -246.589296)
		(mid 140.914882 -246.665051)
		(end 141.196314 -246.589296)
		(width 0.09525)
		(layer "In4.Cu")
		(net "M_J_CPU1_SA_DQS_DN<4>")
	)
	(arc
		(start 139.693396 -246.589296)
		(mid 139.974828 -246.665051)
		(end 140.25626 -246.589296)
		(width 0.09525)
		(layer "In4.Cu")
		(net "M_J_CPU1_SA_DQS_DN<4>")
	)
	(arc
		(start 140.264642 -246.58447)
		(mid 140.449674 -246.538556)
		(end 140.63345 -246.589296)
		(width 0.09525)
		(layer "In4.Cu")
		(net "M_J_CPU1_SA_DQS_DN<4>")
	)
	(arc
		(start 142.136114 -246.589296)
		(mid 142.319889 -246.538524)
		(end 142.504922 -246.58447)
		(width 0.09525)
		(layer "In4.Cu")
		(net "M_J_CPU1_SA_DQS_DN<4>")
	)
	(arc
		(start 144.016476 -246.589296)
		(mid 144.200505 -246.538397)
		(end 144.385792 -246.58447)
		(width 0.09525)
		(layer "In4.Cu")
		(net "M_J_CPU1_SA_DQS_DN<4>")
	)
	(arc
		(start 137.436098 -246.589296)
		(mid 137.619873 -246.538524)
		(end 137.804906 -246.58447)
		(width 0.09525)
		(layer "In4.Cu")
		(net "M_J_CPU1_SA_DQS_DN<4>")
	)
	(arc
		(start 135.564626 -246.58447)
		(mid 135.749658 -246.538556)
		(end 135.933434 -246.589296)
		(width 0.09525)
		(layer "In4.Cu")
		(net "M_J_CPU1_SA_DQS_DN<4>")
	)
	(arc
		(start 142.513304 -246.589296)
		(mid 142.794736 -246.665051)
		(end 143.076168 -246.589296)
		(width 0.09525)
		(layer "In4.Cu")
		(net "M_J_CPU1_SA_DQS_DN<4>")
	)
	(arc
		(start 141.57325 -246.589296)
		(mid 141.854682 -246.665051)
		(end 142.136114 -246.589296)
		(width 0.09525)
		(layer "In4.Cu")
		(net "M_J_CPU1_SA_DQS_DN<4>")
	)
	(arc
		(start 136.496298 -246.589296)
		(mid 136.684766 -246.538619)
		(end 136.873234 -246.589296)
		(width 0.09525)
		(layer "In4.Cu")
		(net "M_J_CPU1_SA_DQS_DN<4>")
	)
	(arc
		(start 132.794248 -246.562118)
		(mid 132.951998 -246.539599)
		(end 133.10489 -246.58447)
		(width 0.09525)
		(layer "In4.Cu")
		(net "M_J_CPU1_SA_DQS_DN<4>")
	)
	(arc
		(start 143.08455 -246.58447)
		(mid 143.269582 -246.538556)
		(end 143.453358 -246.589296)
		(width 0.09525)
		(layer "In4.Cu")
		(net "M_J_CPU1_SA_DQS_DN<4>")
	)
	(arc
		(start 144.971008 -246.580914)
		(mid 145.15344 -246.538474)
		(end 145.33372 -246.589296)
		(width 0.09525)
		(layer "In4.Cu")
		(net "M_J_CPU1_SA_DQS_DN<4>")
	)
	(arc
		(start 134.99338 -246.589296)
		(mid 135.274812 -246.665051)
		(end 135.556244 -246.589296)
		(width 0.09525)
		(layer "In4.Cu")
		(net "M_J_CPU1_SA_DQS_DN<4>")
	)
	(arc
		(start 133.113272 -246.589296)
		(mid 133.394704 -246.665051)
		(end 133.676136 -246.589296)
		(width 0.09525)
		(layer "In4.Cu")
		(net "M_J_CPU1_SA_DQS_DN<4>")
	)
	(arc
		(start 138.753342 -246.589296)
		(mid 139.034774 -246.665051)
		(end 139.316206 -246.589296)
		(width 0.09525)
		(layer "In4.Cu")
		(net "M_J_CPU1_SA_DQS_DN<4>")
	)
	(arc
		(start 141.196314 -246.589296)
		(mid 141.384782 -246.538619)
		(end 141.57325 -246.589296)
		(width 0.09525)
		(layer "In4.Cu")
		(net "M_J_CPU1_SA_DQS_DN<4>")
	)
	(arc
		(start 134.624572 -246.58447)
		(mid 134.809604 -246.538556)
		(end 134.99338 -246.589296)
		(width 0.09525)
		(layer "In4.Cu")
		(net "M_J_CPU1_SA_DQS_DN<4>")
	)
	(arc
		(start 139.324588 -246.58447)
		(mid 139.50962 -246.538556)
		(end 139.693396 -246.589296)
		(width 0.09525)
		(layer "In4.Cu")
		(net "M_J_CPU1_SA_DQS_DN<4>")
	)
	(arc
		(start 144.394174 -246.589296)
		(mid 144.666848 -246.664983)
		(end 144.941798 -246.597932)
		(width 0.09525)
		(layer "In4.Cu")
		(net "M_J_CPU1_SA_DQS_DN<4>")
	)
	(arc
		(start 136.873234 -246.589296)
		(mid 137.154666 -246.665051)
		(end 137.436098 -246.589296)
		(width 0.09525)
		(layer "In4.Cu")
		(net "M_J_CPU1_SA_DQS_DN<4>")
	)
	(segment
		(start 132.457952 -242.320318)
		(end 132.924804 -242.05438)
		(width 0.12954)
		(layer "F.Cu")
		(net "M_J_CPU1_SA_DQS_DN<3>")
	)
	(segment
		(start 184.497472 -228.36251)
		(end 184.95391 -228.818948)
		(width 0.16002)
		(layer "In4.Cu")
		(net "M_J_CPU1_SA_DQS_DN<3>")
	)
	(segment
		(start 189.715648 -229.478332)
		(end 190.195708 -229.478332)
		(width 0.16002)
		(layer "In4.Cu")
		(net "M_J_CPU1_SA_DQS_DN<3>")
	)
	(segment
		(start 167.007032 -228.681788)
		(end 170.005248 -228.681788)
		(width 0.16002)
		(layer "In4.Cu")
		(net "M_J_CPU1_SA_DQS_DN<3>")
	)
	(segment
		(start 133.10489 -241.724434)
		(end 133.113272 -241.72926)
		(width 0.09525)
		(layer "In4.Cu")
		(net "M_J_CPU1_SA_DQS_DN<3>")
	)
	(segment
		(start 158.34995 -234.053126)
		(end 158.34995 -233.568494)
		(width 0.16002)
		(layer "In4.Cu")
		(net "M_J_CPU1_SA_DQS_DN<3>")
	)
	(segment
		(start 139.316206 -241.72926)
		(end 139.324588 -241.724434)
		(width 0.09525)
		(layer "In4.Cu")
		(net "M_J_CPU1_SA_DQS_DN<3>")
	)
	(segment
		(start 188.937392 -229.542848)
		(end 189.118748 -229.361492)
		(width 0.16002)
		(layer "In4.Cu")
		(net "M_J_CPU1_SA_DQS_DN<3>")
	)
	(segment
		(start 134.61619 -241.72926)
		(end 134.624572 -241.724434)
		(width 0.09525)
		(layer "In4.Cu")
		(net "M_J_CPU1_SA_DQS_DN<3>")
	)
	(segment
		(start 175.66513 -228.36251)
		(end 177.012346 -228.36251)
		(width 0.16002)
		(layer "In4.Cu")
		(net "M_J_CPU1_SA_DQS_DN<3>")
	)
	(segment
		(start 181.199536 -229.588568)
		(end 181.969156 -228.818948)
		(width 0.16002)
		(layer "In4.Cu")
		(net "M_J_CPU1_SA_DQS_DN<3>")
	)
	(segment
		(start 151.803862 -240.599214)
		(end 158.34995 -234.053126)
		(width 0.16002)
		(layer "In4.Cu")
		(net "M_J_CPU1_SA_DQS_DN<3>")
	)
	(segment
		(start 145.144744 -241.677952)
		(end 145.870676 -241.677952)
		(width 0.09525)
		(layer "In4.Cu")
		(net "M_J_CPU1_SA_DQS_DN<3>")
	)
	(segment
		(start 190.195708 -229.478332)
		(end 190.312548 -229.361492)
		(width 0.16002)
		(layer "In4.Cu")
		(net "M_J_CPU1_SA_DQS_DN<3>")
	)
	(segment
		(start 170.535854 -229.212394)
		(end 172.443394 -229.212394)
		(width 0.16002)
		(layer "In4.Cu")
		(net "M_J_CPU1_SA_DQS_DN<3>")
	)
	(segment
		(start 181.969156 -228.818948)
		(end 182.67807 -228.818948)
		(width 0.16002)
		(layer "In4.Cu")
		(net "M_J_CPU1_SA_DQS_DN<3>")
	)
	(segment
		(start 190.886334 -229.361492)
		(end 191.160146 -229.635304)
		(width 0.16002)
		(layer "In4.Cu")
		(net "M_J_CPU1_SA_DQS_DN<3>")
	)
	(segment
		(start 172.443394 -229.212394)
		(end 172.799248 -229.568248)
		(width 0.16002)
		(layer "In4.Cu")
		(net "M_J_CPU1_SA_DQS_DN<3>")
	)
	(segment
		(start 140.25626 -241.72926)
		(end 140.264642 -241.724434)
		(width 0.09525)
		(layer "In4.Cu")
		(net "M_J_CPU1_SA_DQS_DN<3>")
	)
	(segment
		(start 135.556244 -241.72926)
		(end 135.564626 -241.724434)
		(width 0.09525)
		(layer "In4.Cu")
		(net "M_J_CPU1_SA_DQS_DN<3>")
	)
	(segment
		(start 175.137572 -228.890068)
		(end 175.66513 -228.36251)
		(width 0.16002)
		(layer "In4.Cu")
		(net "M_J_CPU1_SA_DQS_DN<3>")
	)
	(segment
		(start 172.799248 -229.568248)
		(end 173.630844 -229.568248)
		(width 0.16002)
		(layer "In4.Cu")
		(net "M_J_CPU1_SA_DQS_DN<3>")
	)
	(segment
		(start 180.416708 -229.588568)
		(end 181.199536 -229.588568)
		(width 0.16002)
		(layer "In4.Cu")
		(net "M_J_CPU1_SA_DQS_DN<3>")
	)
	(segment
		(start 137.804906 -241.724434)
		(end 137.813288 -241.72926)
		(width 0.09525)
		(layer "In4.Cu")
		(net "M_J_CPU1_SA_DQS_DN<3>")
	)
	(segment
		(start 146.87296 -241.107214)
		(end 147.439888 -240.540286)
		(width 0.09525)
		(layer "In4.Cu")
		(net "M_J_CPU1_SA_DQS_DN<3>")
	)
	(segment
		(start 147.888452 -240.599214)
		(end 147.912074 -240.599214)
		(width 0.09525)
		(layer "In4.Cu")
		(net "M_J_CPU1_SA_DQS_DN<3>")
	)
	(segment
		(start 138.74496 -241.724434)
		(end 138.753342 -241.72926)
		(width 0.09525)
		(layer "In4.Cu")
		(net "M_J_CPU1_SA_DQS_DN<3>")
	)
	(segment
		(start 174.309024 -228.890068)
		(end 175.137572 -228.890068)
		(width 0.16002)
		(layer "In4.Cu")
		(net "M_J_CPU1_SA_DQS_DN<3>")
	)
	(segment
		(start 132.77088 -241.78895)
		(end 132.794248 -241.702082)
		(width 0.09525)
		(layer "In4.Cu")
		(net "M_J_CPU1_SA_DQS_DN<3>")
	)
	(segment
		(start 134.044944 -241.724434)
		(end 134.053326 -241.72926)
		(width 0.09525)
		(layer "In4.Cu")
		(net "M_J_CPU1_SA_DQS_DN<3>")
	)
	(segment
		(start 162.362896 -229.555548)
		(end 166.133272 -229.555548)
		(width 0.16002)
		(layer "In4.Cu")
		(net "M_J_CPU1_SA_DQS_DN<3>")
	)
	(segment
		(start 189.118748 -229.361492)
		(end 189.598808 -229.361492)
		(width 0.16002)
		(layer "In4.Cu")
		(net "M_J_CPU1_SA_DQS_DN<3>")
	)
	(segment
		(start 183.134508 -228.36251)
		(end 184.497472 -228.36251)
		(width 0.16002)
		(layer "In4.Cu")
		(net "M_J_CPU1_SA_DQS_DN<3>")
	)
	(segment
		(start 147.439888 -240.540286)
		(end 147.829524 -240.540286)
		(width 0.09525)
		(layer "In4.Cu")
		(net "M_J_CPU1_SA_DQS_DN<3>")
	)
	(segment
		(start 146.441414 -241.107214)
		(end 146.87296 -241.107214)
		(width 0.09525)
		(layer "In4.Cu")
		(net "M_J_CPU1_SA_DQS_DN<3>")
	)
	(segment
		(start 145.870676 -241.677952)
		(end 146.441414 -241.107214)
		(width 0.09525)
		(layer "In4.Cu")
		(net "M_J_CPU1_SA_DQS_DN<3>")
	)
	(segment
		(start 147.912074 -240.599214)
		(end 151.803862 -240.599214)
		(width 0.16002)
		(layer "In4.Cu")
		(net "M_J_CPU1_SA_DQS_DN<3>")
	)
	(segment
		(start 189.598808 -229.361492)
		(end 189.715648 -229.478332)
		(width 0.16002)
		(layer "In4.Cu")
		(net "M_J_CPU1_SA_DQS_DN<3>")
	)
	(segment
		(start 132.924804 -242.05438)
		(end 132.77088 -241.78895)
		(width 0.09525)
		(layer "In4.Cu")
		(net "M_J_CPU1_SA_DQS_DN<3>")
	)
	(segment
		(start 143.453358 -241.72926)
		(end 143.463772 -241.735356)
		(width 0.09525)
		(layer "In4.Cu")
		(net "M_J_CPU1_SA_DQS_DN<3>")
	)
	(segment
		(start 184.95391 -228.818948)
		(end 187.033408 -228.818948)
		(width 0.16002)
		(layer "In4.Cu")
		(net "M_J_CPU1_SA_DQS_DN<3>")
	)
	(segment
		(start 177.86223 -229.212394)
		(end 180.040534 -229.212394)
		(width 0.16002)
		(layer "In4.Cu")
		(net "M_J_CPU1_SA_DQS_DN<3>")
	)
	(segment
		(start 143.076168 -241.72926)
		(end 143.08455 -241.724434)
		(width 0.09525)
		(layer "In4.Cu")
		(net "M_J_CPU1_SA_DQS_DN<3>")
	)
	(segment
		(start 180.040534 -229.212394)
		(end 180.416708 -229.588568)
		(width 0.16002)
		(layer "In4.Cu")
		(net "M_J_CPU1_SA_DQS_DN<3>")
	)
	(segment
		(start 173.630844 -229.568248)
		(end 174.309024 -228.890068)
		(width 0.16002)
		(layer "In4.Cu")
		(net "M_J_CPU1_SA_DQS_DN<3>")
	)
	(segment
		(start 177.012346 -228.36251)
		(end 177.86223 -229.212394)
		(width 0.16002)
		(layer "In4.Cu")
		(net "M_J_CPU1_SA_DQS_DN<3>")
	)
	(segment
		(start 166.133272 -229.555548)
		(end 167.007032 -228.681788)
		(width 0.16002)
		(layer "In4.Cu")
		(net "M_J_CPU1_SA_DQS_DN<3>")
	)
	(segment
		(start 158.34995 -233.568494)
		(end 162.362896 -229.555548)
		(width 0.16002)
		(layer "In4.Cu")
		(net "M_J_CPU1_SA_DQS_DN<3>")
	)
	(segment
		(start 144.385792 -241.724434)
		(end 144.394174 -241.72926)
		(width 0.09525)
		(layer "In4.Cu")
		(net "M_J_CPU1_SA_DQS_DN<3>")
	)
	(segment
		(start 147.829524 -240.540286)
		(end 147.888452 -240.599214)
		(width 0.09525)
		(layer "In4.Cu")
		(net "M_J_CPU1_SA_DQS_DN<3>")
	)
	(segment
		(start 187.757308 -229.542848)
		(end 188.937392 -229.542848)
		(width 0.16002)
		(layer "In4.Cu")
		(net "M_J_CPU1_SA_DQS_DN<3>")
	)
	(segment
		(start 170.005248 -228.681788)
		(end 170.535854 -229.212394)
		(width 0.16002)
		(layer "In4.Cu")
		(net "M_J_CPU1_SA_DQS_DN<3>")
	)
	(segment
		(start 142.504922 -241.724434)
		(end 142.513304 -241.72926)
		(width 0.09525)
		(layer "In4.Cu")
		(net "M_J_CPU1_SA_DQS_DN<3>")
	)
	(segment
		(start 182.67807 -228.818948)
		(end 183.134508 -228.36251)
		(width 0.16002)
		(layer "In4.Cu")
		(net "M_J_CPU1_SA_DQS_DN<3>")
	)
	(segment
		(start 190.312548 -229.361492)
		(end 190.886334 -229.361492)
		(width 0.16002)
		(layer "In4.Cu")
		(net "M_J_CPU1_SA_DQS_DN<3>")
	)
	(segment
		(start 187.033408 -228.818948)
		(end 187.757308 -229.542848)
		(width 0.16002)
		(layer "In4.Cu")
		(net "M_J_CPU1_SA_DQS_DN<3>")
	)
	(arc
		(start 132.794248 -241.702082)
		(mid 132.951998 -241.679563)
		(end 133.10489 -241.724434)
		(width 0.09525)
		(layer "In4.Cu")
		(net "M_J_CPU1_SA_DQS_DN<3>")
	)
	(arc
		(start 138.753342 -241.72926)
		(mid 139.034774 -241.805015)
		(end 139.316206 -241.72926)
		(width 0.09525)
		(layer "In4.Cu")
		(net "M_J_CPU1_SA_DQS_DN<3>")
	)
	(arc
		(start 134.99338 -241.72926)
		(mid 135.274812 -241.805015)
		(end 135.556244 -241.72926)
		(width 0.09525)
		(layer "In4.Cu")
		(net "M_J_CPU1_SA_DQS_DN<3>")
	)
	(arc
		(start 133.676136 -241.72926)
		(mid 133.859911 -241.678488)
		(end 134.044944 -241.724434)
		(width 0.09525)
		(layer "In4.Cu")
		(net "M_J_CPU1_SA_DQS_DN<3>")
	)
	(arc
		(start 143.463772 -241.735356)
		(mid 143.740934 -241.805156)
		(end 144.016476 -241.72926)
		(width 0.09525)
		(layer "In4.Cu")
		(net "M_J_CPU1_SA_DQS_DN<3>")
	)
	(arc
		(start 136.496298 -241.72926)
		(mid 136.684766 -241.678583)
		(end 136.873234 -241.72926)
		(width 0.09525)
		(layer "In4.Cu")
		(net "M_J_CPU1_SA_DQS_DN<3>")
	)
	(arc
		(start 139.693396 -241.72926)
		(mid 139.974828 -241.805015)
		(end 140.25626 -241.72926)
		(width 0.09525)
		(layer "In4.Cu")
		(net "M_J_CPU1_SA_DQS_DN<3>")
	)
	(arc
		(start 134.053326 -241.72926)
		(mid 134.334758 -241.805015)
		(end 134.61619 -241.72926)
		(width 0.09525)
		(layer "In4.Cu")
		(net "M_J_CPU1_SA_DQS_DN<3>")
	)
	(arc
		(start 141.196314 -241.72926)
		(mid 141.384782 -241.678583)
		(end 141.57325 -241.72926)
		(width 0.09525)
		(layer "In4.Cu")
		(net "M_J_CPU1_SA_DQS_DN<3>")
	)
	(arc
		(start 144.016476 -241.72926)
		(mid 144.200505 -241.678361)
		(end 144.385792 -241.724434)
		(width 0.09525)
		(layer "In4.Cu")
		(net "M_J_CPU1_SA_DQS_DN<3>")
	)
	(arc
		(start 134.624572 -241.724434)
		(mid 134.809604 -241.67852)
		(end 134.99338 -241.72926)
		(width 0.09525)
		(layer "In4.Cu")
		(net "M_J_CPU1_SA_DQS_DN<3>")
	)
	(arc
		(start 135.933434 -241.72926)
		(mid 136.214866 -241.805015)
		(end 136.496298 -241.72926)
		(width 0.09525)
		(layer "In4.Cu")
		(net "M_J_CPU1_SA_DQS_DN<3>")
	)
	(arc
		(start 135.564626 -241.724434)
		(mid 135.749658 -241.67852)
		(end 135.933434 -241.72926)
		(width 0.09525)
		(layer "In4.Cu")
		(net "M_J_CPU1_SA_DQS_DN<3>")
	)
	(arc
		(start 140.63345 -241.72926)
		(mid 140.914882 -241.805015)
		(end 141.196314 -241.72926)
		(width 0.09525)
		(layer "In4.Cu")
		(net "M_J_CPU1_SA_DQS_DN<3>")
	)
	(arc
		(start 137.813288 -241.72926)
		(mid 138.09472 -241.805015)
		(end 138.376152 -241.72926)
		(width 0.09525)
		(layer "In4.Cu")
		(net "M_J_CPU1_SA_DQS_DN<3>")
	)
	(arc
		(start 141.57325 -241.72926)
		(mid 141.854682 -241.805015)
		(end 142.136114 -241.72926)
		(width 0.09525)
		(layer "In4.Cu")
		(net "M_J_CPU1_SA_DQS_DN<3>")
	)
	(arc
		(start 142.513304 -241.72926)
		(mid 142.794736 -241.805015)
		(end 143.076168 -241.72926)
		(width 0.09525)
		(layer "In4.Cu")
		(net "M_J_CPU1_SA_DQS_DN<3>")
	)
	(arc
		(start 137.436098 -241.72926)
		(mid 137.619873 -241.678488)
		(end 137.804906 -241.724434)
		(width 0.09525)
		(layer "In4.Cu")
		(net "M_J_CPU1_SA_DQS_DN<3>")
	)
	(arc
		(start 140.264642 -241.724434)
		(mid 140.449674 -241.67852)
		(end 140.63345 -241.72926)
		(width 0.09525)
		(layer "In4.Cu")
		(net "M_J_CPU1_SA_DQS_DN<3>")
	)
	(arc
		(start 144.941798 -241.737896)
		(mid 145.03897 -241.693365)
		(end 145.144744 -241.677952)
		(width 0.09525)
		(layer "In4.Cu")
		(net "M_J_CPU1_SA_DQS_DN<3>")
	)
	(arc
		(start 144.394174 -241.72926)
		(mid 144.666848 -241.804947)
		(end 144.941798 -241.737896)
		(width 0.09525)
		(layer "In4.Cu")
		(net "M_J_CPU1_SA_DQS_DN<3>")
	)
	(arc
		(start 139.324588 -241.724434)
		(mid 139.50962 -241.67852)
		(end 139.693396 -241.72926)
		(width 0.09525)
		(layer "In4.Cu")
		(net "M_J_CPU1_SA_DQS_DN<3>")
	)
	(arc
		(start 143.08455 -241.724434)
		(mid 143.269582 -241.67852)
		(end 143.453358 -241.72926)
		(width 0.09525)
		(layer "In4.Cu")
		(net "M_J_CPU1_SA_DQS_DN<3>")
	)
	(arc
		(start 133.113272 -241.72926)
		(mid 133.394704 -241.805015)
		(end 133.676136 -241.72926)
		(width 0.09525)
		(layer "In4.Cu")
		(net "M_J_CPU1_SA_DQS_DN<3>")
	)
	(arc
		(start 142.136114 -241.72926)
		(mid 142.319889 -241.678488)
		(end 142.504922 -241.724434)
		(width 0.09525)
		(layer "In4.Cu")
		(net "M_J_CPU1_SA_DQS_DN<3>")
	)
	(arc
		(start 136.873234 -241.72926)
		(mid 137.154666 -241.805015)
		(end 137.436098 -241.72926)
		(width 0.09525)
		(layer "In4.Cu")
		(net "M_J_CPU1_SA_DQS_DN<3>")
	)
	(arc
		(start 138.376152 -241.72926)
		(mid 138.559927 -241.678488)
		(end 138.74496 -241.724434)
		(width 0.09525)
		(layer "In4.Cu")
		(net "M_J_CPU1_SA_DQS_DN<3>")
	)
	(segment
		(start 132.457952 -237.460282)
		(end 132.924804 -237.194344)
		(width 0.12954)
		(layer "F.Cu")
		(net "M_J_CPU1_SA_DQS_DN<2>")
	)
	(segment
		(start 177.012346 -219.012516)
		(end 177.86223 -219.8624)
		(width 0.16002)
		(layer "In4.Cu")
		(net "M_J_CPU1_SA_DQS_DN<2>")
	)
	(segment
		(start 164.844984 -219.882466)
		(end 165.168072 -220.205554)
		(width 0.16002)
		(layer "In4.Cu")
		(net "M_J_CPU1_SA_DQS_DN<2>")
	)
	(segment
		(start 183.134508 -219.012516)
		(end 184.497472 -219.012516)
		(width 0.16002)
		(layer "In4.Cu")
		(net "M_J_CPU1_SA_DQS_DN<2>")
	)
	(segment
		(start 190.39586 -220.011498)
		(end 190.886334 -220.011498)
		(width 0.16002)
		(layer "In4.Cu")
		(net "M_J_CPU1_SA_DQS_DN<2>")
	)
	(segment
		(start 161.612072 -219.882466)
		(end 164.844984 -219.882466)
		(width 0.16002)
		(layer "In4.Cu")
		(net "M_J_CPU1_SA_DQS_DN<2>")
	)
	(segment
		(start 144.393158 -236.869224)
		(end 144.403826 -236.875066)
		(width 0.09525)
		(layer "In4.Cu")
		(net "M_J_CPU1_SA_DQS_DN<2>")
	)
	(segment
		(start 177.86223 -219.8624)
		(end 180.040534 -219.8624)
		(width 0.16002)
		(layer "In4.Cu")
		(net "M_J_CPU1_SA_DQS_DN<2>")
	)
	(segment
		(start 187.033408 -219.468954)
		(end 187.757308 -220.192854)
		(width 0.16002)
		(layer "In4.Cu")
		(net "M_J_CPU1_SA_DQS_DN<2>")
	)
	(segment
		(start 142.504922 -236.864398)
		(end 142.513304 -236.869224)
		(width 0.09525)
		(layer "In4.Cu")
		(net "M_J_CPU1_SA_DQS_DN<2>")
	)
	(segment
		(start 172.443394 -219.8624)
		(end 172.799248 -220.218254)
		(width 0.16002)
		(layer "In4.Cu")
		(net "M_J_CPU1_SA_DQS_DN<2>")
	)
	(segment
		(start 147.82673 -234.810808)
		(end 147.885658 -234.869736)
		(width 0.09525)
		(layer "In4.Cu")
		(net "M_J_CPU1_SA_DQS_DN<2>")
	)
	(segment
		(start 182.67807 -219.468954)
		(end 183.134508 -219.012516)
		(width 0.16002)
		(layer "In4.Cu")
		(net "M_J_CPU1_SA_DQS_DN<2>")
	)
	(segment
		(start 155.486354 -228.41839)
		(end 155.486354 -226.008184)
		(width 0.16002)
		(layer "In4.Cu")
		(net "M_J_CPU1_SA_DQS_DN<2>")
	)
	(segment
		(start 187.757308 -220.192854)
		(end 188.937392 -220.192854)
		(width 0.16002)
		(layer "In4.Cu")
		(net "M_J_CPU1_SA_DQS_DN<2>")
	)
	(segment
		(start 138.74496 -236.864398)
		(end 138.753342 -236.869224)
		(width 0.09525)
		(layer "In4.Cu")
		(net "M_J_CPU1_SA_DQS_DN<2>")
	)
	(segment
		(start 143.076168 -236.869224)
		(end 143.08455 -236.864398)
		(width 0.09525)
		(layer "In4.Cu")
		(net "M_J_CPU1_SA_DQS_DN<2>")
	)
	(segment
		(start 189.68212 -220.011498)
		(end 189.79896 -220.128338)
		(width 0.16002)
		(layer "In4.Cu")
		(net "M_J_CPU1_SA_DQS_DN<2>")
	)
	(segment
		(start 146.57705 -235.666026)
		(end 146.948398 -235.666026)
		(width 0.09525)
		(layer "In4.Cu")
		(net "M_J_CPU1_SA_DQS_DN<2>")
	)
	(segment
		(start 167.007032 -219.331794)
		(end 170.005248 -219.331794)
		(width 0.16002)
		(layer "In4.Cu")
		(net "M_J_CPU1_SA_DQS_DN<2>")
	)
	(segment
		(start 181.199536 -220.238574)
		(end 181.969156 -219.468954)
		(width 0.16002)
		(layer "In4.Cu")
		(net "M_J_CPU1_SA_DQS_DN<2>")
	)
	(segment
		(start 146.948398 -235.666026)
		(end 147.656296 -234.810808)
		(width 0.09525)
		(layer "In4.Cu")
		(net "M_J_CPU1_SA_DQS_DN<2>")
	)
	(segment
		(start 189.118748 -220.011498)
		(end 189.68212 -220.011498)
		(width 0.16002)
		(layer "In4.Cu")
		(net "M_J_CPU1_SA_DQS_DN<2>")
	)
	(segment
		(start 184.95391 -219.468954)
		(end 187.033408 -219.468954)
		(width 0.16002)
		(layer "In4.Cu")
		(net "M_J_CPU1_SA_DQS_DN<2>")
	)
	(segment
		(start 172.799248 -220.218254)
		(end 173.630844 -220.218254)
		(width 0.16002)
		(layer "In4.Cu")
		(net "M_J_CPU1_SA_DQS_DN<2>")
	)
	(segment
		(start 144.392904 -236.869224)
		(end 144.393158 -236.869224)
		(width 0.09525)
		(layer "In4.Cu")
		(net "M_J_CPU1_SA_DQS_DN<2>")
	)
	(segment
		(start 145.23593 -236.754416)
		(end 145.48866 -236.754416)
		(width 0.09525)
		(layer "In4.Cu")
		(net "M_J_CPU1_SA_DQS_DN<2>")
	)
	(segment
		(start 134.044944 -236.864398)
		(end 134.053326 -236.869224)
		(width 0.09525)
		(layer "In4.Cu")
		(net "M_J_CPU1_SA_DQS_DN<2>")
	)
	(segment
		(start 166.133272 -220.205554)
		(end 167.007032 -219.331794)
		(width 0.16002)
		(layer "In4.Cu")
		(net "M_J_CPU1_SA_DQS_DN<2>")
	)
	(segment
		(start 143.034258 -236.891322)
		(end 143.053816 -236.881924)
		(width 0.09525)
		(layer "In4.Cu")
		(net "M_J_CPU1_SA_DQS_DN<2>")
	)
	(segment
		(start 170.535854 -219.8624)
		(end 172.443394 -219.8624)
		(width 0.16002)
		(layer "In4.Cu")
		(net "M_J_CPU1_SA_DQS_DN<2>")
	)
	(segment
		(start 190.886334 -220.011498)
		(end 191.160146 -220.28531)
		(width 0.16002)
		(layer "In4.Cu")
		(net "M_J_CPU1_SA_DQS_DN<2>")
	)
	(segment
		(start 184.497472 -219.012516)
		(end 184.95391 -219.468954)
		(width 0.16002)
		(layer "In4.Cu")
		(net "M_J_CPU1_SA_DQS_DN<2>")
	)
	(segment
		(start 144.94383 -236.875574)
		(end 145.23593 -236.754416)
		(width 0.09525)
		(layer "In4.Cu")
		(net "M_J_CPU1_SA_DQS_DN<2>")
	)
	(segment
		(start 181.969156 -219.468954)
		(end 182.67807 -219.468954)
		(width 0.16002)
		(layer "In4.Cu")
		(net "M_J_CPU1_SA_DQS_DN<2>")
	)
	(segment
		(start 175.66513 -219.012516)
		(end 177.012346 -219.012516)
		(width 0.16002)
		(layer "In4.Cu")
		(net "M_J_CPU1_SA_DQS_DN<2>")
	)
	(segment
		(start 132.77088 -236.928914)
		(end 132.794248 -236.842046)
		(width 0.09525)
		(layer "In4.Cu")
		(net "M_J_CPU1_SA_DQS_DN<2>")
	)
	(segment
		(start 165.168072 -220.205554)
		(end 166.133272 -220.205554)
		(width 0.16002)
		(layer "In4.Cu")
		(net "M_J_CPU1_SA_DQS_DN<2>")
	)
	(segment
		(start 188.937392 -220.192854)
		(end 189.118748 -220.011498)
		(width 0.16002)
		(layer "In4.Cu")
		(net "M_J_CPU1_SA_DQS_DN<2>")
	)
	(segment
		(start 189.79896 -220.128338)
		(end 190.27902 -220.128338)
		(width 0.16002)
		(layer "In4.Cu")
		(net "M_J_CPU1_SA_DQS_DN<2>")
	)
	(segment
		(start 170.005248 -219.331794)
		(end 170.535854 -219.8624)
		(width 0.16002)
		(layer "In4.Cu")
		(net "M_J_CPU1_SA_DQS_DN<2>")
	)
	(segment
		(start 133.10489 -236.864398)
		(end 133.113272 -236.869224)
		(width 0.09525)
		(layer "In4.Cu")
		(net "M_J_CPU1_SA_DQS_DN<2>")
	)
	(segment
		(start 173.630844 -220.218254)
		(end 174.309024 -219.540074)
		(width 0.16002)
		(layer "In4.Cu")
		(net "M_J_CPU1_SA_DQS_DN<2>")
	)
	(segment
		(start 180.040534 -219.8624)
		(end 180.416708 -220.238574)
		(width 0.16002)
		(layer "In4.Cu")
		(net "M_J_CPU1_SA_DQS_DN<2>")
	)
	(segment
		(start 143.053816 -236.881924)
		(end 143.076168 -236.869224)
		(width 0.09525)
		(layer "In4.Cu")
		(net "M_J_CPU1_SA_DQS_DN<2>")
	)
	(segment
		(start 144.005554 -236.87532)
		(end 144.015968 -236.869224)
		(width 0.09525)
		(layer "In4.Cu")
		(net "M_J_CPU1_SA_DQS_DN<2>")
	)
	(segment
		(start 175.137572 -219.540074)
		(end 175.66513 -219.012516)
		(width 0.16002)
		(layer "In4.Cu")
		(net "M_J_CPU1_SA_DQS_DN<2>")
	)
	(segment
		(start 190.27902 -220.128338)
		(end 190.39586 -220.011498)
		(width 0.16002)
		(layer "In4.Cu")
		(net "M_J_CPU1_SA_DQS_DN<2>")
	)
	(segment
		(start 147.656296 -234.810808)
		(end 147.82673 -234.810808)
		(width 0.09525)
		(layer "In4.Cu")
		(net "M_J_CPU1_SA_DQS_DN<2>")
	)
	(segment
		(start 149.035008 -234.869736)
		(end 155.486354 -228.41839)
		(width 0.16002)
		(layer "In4.Cu")
		(net "M_J_CPU1_SA_DQS_DN<2>")
	)
	(segment
		(start 139.316206 -236.869224)
		(end 139.324588 -236.864398)
		(width 0.09525)
		(layer "In4.Cu")
		(net "M_J_CPU1_SA_DQS_DN<2>")
	)
	(segment
		(start 147.885658 -234.869736)
		(end 147.90928 -234.869736)
		(width 0.09525)
		(layer "In4.Cu")
		(net "M_J_CPU1_SA_DQS_DN<2>")
	)
	(segment
		(start 132.924804 -237.194344)
		(end 132.77088 -236.928914)
		(width 0.09525)
		(layer "In4.Cu")
		(net "M_J_CPU1_SA_DQS_DN<2>")
	)
	(segment
		(start 174.309024 -219.540074)
		(end 175.137572 -219.540074)
		(width 0.16002)
		(layer "In4.Cu")
		(net "M_J_CPU1_SA_DQS_DN<2>")
	)
	(segment
		(start 140.25626 -236.869224)
		(end 140.264642 -236.864398)
		(width 0.09525)
		(layer "In4.Cu")
		(net "M_J_CPU1_SA_DQS_DN<2>")
	)
	(segment
		(start 134.61619 -236.869224)
		(end 134.624572 -236.864398)
		(width 0.09525)
		(layer "In4.Cu")
		(net "M_J_CPU1_SA_DQS_DN<2>")
	)
	(segment
		(start 135.556244 -236.869224)
		(end 135.564626 -236.864398)
		(width 0.09525)
		(layer "In4.Cu")
		(net "M_J_CPU1_SA_DQS_DN<2>")
	)
	(segment
		(start 180.416708 -220.238574)
		(end 181.199536 -220.238574)
		(width 0.16002)
		(layer "In4.Cu")
		(net "M_J_CPU1_SA_DQS_DN<2>")
	)
	(segment
		(start 147.90928 -234.869736)
		(end 149.035008 -234.869736)
		(width 0.16002)
		(layer "In4.Cu")
		(net "M_J_CPU1_SA_DQS_DN<2>")
	)
	(segment
		(start 155.486354 -226.008184)
		(end 161.612072 -219.882466)
		(width 0.16002)
		(layer "In4.Cu")
		(net "M_J_CPU1_SA_DQS_DN<2>")
	)
	(segment
		(start 145.48866 -236.754416)
		(end 146.57705 -235.666026)
		(width 0.09525)
		(layer "In4.Cu")
		(net "M_J_CPU1_SA_DQS_DN<2>")
	)
	(segment
		(start 137.804906 -236.864398)
		(end 137.813288 -236.869224)
		(width 0.09525)
		(layer "In4.Cu")
		(net "M_J_CPU1_SA_DQS_DN<2>")
	)
	(arc
		(start 139.324588 -236.864398)
		(mid 139.50962 -236.818484)
		(end 139.693396 -236.869224)
		(width 0.09525)
		(layer "In4.Cu")
		(net "M_J_CPU1_SA_DQS_DN<2>")
	)
	(arc
		(start 140.63345 -236.869224)
		(mid 140.914882 -236.944979)
		(end 141.196314 -236.869224)
		(width 0.09525)
		(layer "In4.Cu")
		(net "M_J_CPU1_SA_DQS_DN<2>")
	)
	(arc
		(start 136.873234 -236.869224)
		(mid 137.154666 -236.944979)
		(end 137.436098 -236.869224)
		(width 0.09525)
		(layer "In4.Cu")
		(net "M_J_CPU1_SA_DQS_DN<2>")
	)
	(arc
		(start 134.99338 -236.869224)
		(mid 135.274812 -236.944979)
		(end 135.556244 -236.869224)
		(width 0.09525)
		(layer "In4.Cu")
		(net "M_J_CPU1_SA_DQS_DN<2>")
	)
	(arc
		(start 137.813288 -236.869224)
		(mid 138.09472 -236.944979)
		(end 138.376152 -236.869224)
		(width 0.09525)
		(layer "In4.Cu")
		(net "M_J_CPU1_SA_DQS_DN<2>")
	)
	(arc
		(start 143.08455 -236.864398)
		(mid 143.269582 -236.818484)
		(end 143.453358 -236.869224)
		(width 0.09525)
		(layer "In4.Cu")
		(net "M_J_CPU1_SA_DQS_DN<2>")
	)
	(arc
		(start 137.436098 -236.869224)
		(mid 137.619873 -236.818452)
		(end 137.804906 -236.864398)
		(width 0.09525)
		(layer "In4.Cu")
		(net "M_J_CPU1_SA_DQS_DN<2>")
	)
	(arc
		(start 134.053326 -236.869224)
		(mid 134.334758 -236.944979)
		(end 134.61619 -236.869224)
		(width 0.09525)
		(layer "In4.Cu")
		(net "M_J_CPU1_SA_DQS_DN<2>")
	)
	(arc
		(start 136.496298 -236.869224)
		(mid 136.684766 -236.818547)
		(end 136.873234 -236.869224)
		(width 0.09525)
		(layer "In4.Cu")
		(net "M_J_CPU1_SA_DQS_DN<2>")
	)
	(arc
		(start 134.624572 -236.864398)
		(mid 134.809604 -236.818484)
		(end 134.99338 -236.869224)
		(width 0.09525)
		(layer "In4.Cu")
		(net "M_J_CPU1_SA_DQS_DN<2>")
	)
	(arc
		(start 135.564626 -236.864398)
		(mid 135.749658 -236.818484)
		(end 135.933434 -236.869224)
		(width 0.09525)
		(layer "In4.Cu")
		(net "M_J_CPU1_SA_DQS_DN<2>")
	)
	(arc
		(start 138.376152 -236.869224)
		(mid 138.559927 -236.818452)
		(end 138.74496 -236.864398)
		(width 0.09525)
		(layer "In4.Cu")
		(net "M_J_CPU1_SA_DQS_DN<2>")
	)
	(arc
		(start 133.113272 -236.869224)
		(mid 133.394704 -236.944979)
		(end 133.676136 -236.869224)
		(width 0.09525)
		(layer "In4.Cu")
		(net "M_J_CPU1_SA_DQS_DN<2>")
	)
	(arc
		(start 142.513304 -236.869224)
		(mid 142.771048 -236.944478)
		(end 143.034258 -236.891322)
		(width 0.09525)
		(layer "In4.Cu")
		(net "M_J_CPU1_SA_DQS_DN<2>")
	)
	(arc
		(start 135.933434 -236.869224)
		(mid 136.214866 -236.944979)
		(end 136.496298 -236.869224)
		(width 0.09525)
		(layer "In4.Cu")
		(net "M_J_CPU1_SA_DQS_DN<2>")
	)
	(arc
		(start 133.676136 -236.869224)
		(mid 133.859911 -236.818452)
		(end 134.044944 -236.864398)
		(width 0.09525)
		(layer "In4.Cu")
		(net "M_J_CPU1_SA_DQS_DN<2>")
	)
	(arc
		(start 144.403826 -236.875066)
		(mid 144.404968 -236.875575)
		(end 144.406112 -236.876082)
		(width 0.09525)
		(layer "In4.Cu")
		(net "M_J_CPU1_SA_DQS_DN<2>")
	)
	(arc
		(start 142.136114 -236.869224)
		(mid 142.319889 -236.818452)
		(end 142.504922 -236.864398)
		(width 0.09525)
		(layer "In4.Cu")
		(net "M_J_CPU1_SA_DQS_DN<2>")
	)
	(arc
		(start 132.794248 -236.842046)
		(mid 132.951998 -236.819527)
		(end 133.10489 -236.864398)
		(width 0.09525)
		(layer "In4.Cu")
		(net "M_J_CPU1_SA_DQS_DN<2>")
	)
	(arc
		(start 144.015968 -236.869224)
		(mid 144.204436 -236.818547)
		(end 144.392904 -236.869224)
		(width 0.09525)
		(layer "In4.Cu")
		(net "M_J_CPU1_SA_DQS_DN<2>")
	)
	(arc
		(start 141.57325 -236.869224)
		(mid 141.854682 -236.944979)
		(end 142.136114 -236.869224)
		(width 0.09525)
		(layer "In4.Cu")
		(net "M_J_CPU1_SA_DQS_DN<2>")
	)
	(arc
		(start 144.406112 -236.876082)
		(mid 144.675046 -236.944599)
		(end 144.94383 -236.875574)
		(width 0.09525)
		(layer "In4.Cu")
		(net "M_J_CPU1_SA_DQS_DN<2>")
	)
	(arc
		(start 143.453358 -236.869224)
		(mid 143.728647 -236.944945)
		(end 144.005554 -236.87532)
		(width 0.09525)
		(layer "In4.Cu")
		(net "M_J_CPU1_SA_DQS_DN<2>")
	)
	(arc
		(start 138.753342 -236.869224)
		(mid 139.034774 -236.944979)
		(end 139.316206 -236.869224)
		(width 0.09525)
		(layer "In4.Cu")
		(net "M_J_CPU1_SA_DQS_DN<2>")
	)
	(arc
		(start 140.264642 -236.864398)
		(mid 140.449674 -236.818484)
		(end 140.63345 -236.869224)
		(width 0.09525)
		(layer "In4.Cu")
		(net "M_J_CPU1_SA_DQS_DN<2>")
	)
	(arc
		(start 141.196314 -236.869224)
		(mid 141.384782 -236.818547)
		(end 141.57325 -236.869224)
		(width 0.09525)
		(layer "In4.Cu")
		(net "M_J_CPU1_SA_DQS_DN<2>")
	)
	(arc
		(start 139.693396 -236.869224)
		(mid 139.974828 -236.944979)
		(end 140.25626 -236.869224)
		(width 0.09525)
		(layer "In4.Cu")
		(net "M_J_CPU1_SA_DQS_DN<2>")
	)
	(segment
		(start 132.457952 -232.600246)
		(end 132.924804 -232.334308)
		(width 0.12954)
		(layer "F.Cu")
		(net "M_J_CPU1_SA_DQS_DN<1>")
	)
	(segment
		(start 180.040534 -210.512406)
		(end 180.416708 -210.88858)
		(width 0.16002)
		(layer "In4.Cu")
		(net "M_J_CPU1_SA_DQS_DN<1>")
	)
	(segment
		(start 145.384266 -230.302054)
		(end 147.254468 -228.431852)
		(width 0.09525)
		(layer "In4.Cu")
		(net "M_J_CPU1_SA_DQS_DN<1>")
	)
	(segment
		(start 132.924804 -232.334308)
		(end 132.77088 -232.068878)
		(width 0.09525)
		(layer "In4.Cu")
		(net "M_J_CPU1_SA_DQS_DN<1>")
	)
	(segment
		(start 190.21806 -210.778344)
		(end 190.3349 -210.661504)
		(width 0.16002)
		(layer "In4.Cu")
		(net "M_J_CPU1_SA_DQS_DN<1>")
	)
	(segment
		(start 172.799248 -210.86826)
		(end 173.630844 -210.86826)
		(width 0.16002)
		(layer "In4.Cu")
		(net "M_J_CPU1_SA_DQS_DN<1>")
	)
	(segment
		(start 142.505938 -232.00487)
		(end 142.513304 -232.009188)
		(width 0.09525)
		(layer "In4.Cu")
		(net "M_J_CPU1_SA_DQS_DN<1>")
	)
	(segment
		(start 174.309024 -210.19008)
		(end 175.137572 -210.19008)
		(width 0.16002)
		(layer "In4.Cu")
		(net "M_J_CPU1_SA_DQS_DN<1>")
	)
	(segment
		(start 147.254468 -228.062536)
		(end 147.557236 -227.759768)
		(width 0.09525)
		(layer "In4.Cu")
		(net "M_J_CPU1_SA_DQS_DN<1>")
	)
	(segment
		(start 189.118748 -210.661504)
		(end 189.62116 -210.661504)
		(width 0.16002)
		(layer "In4.Cu")
		(net "M_J_CPU1_SA_DQS_DN<1>")
	)
	(segment
		(start 167.007032 -209.9818)
		(end 170.005248 -209.9818)
		(width 0.16002)
		(layer "In4.Cu")
		(net "M_J_CPU1_SA_DQS_DN<1>")
	)
	(segment
		(start 137.804906 -232.004362)
		(end 137.813288 -232.009188)
		(width 0.09525)
		(layer "In4.Cu")
		(net "M_J_CPU1_SA_DQS_DN<1>")
	)
	(segment
		(start 134.044944 -232.004362)
		(end 134.053326 -232.009188)
		(width 0.09525)
		(layer "In4.Cu")
		(net "M_J_CPU1_SA_DQS_DN<1>")
	)
	(segment
		(start 149.949154 -225.450908)
		(end 149.949154 -221.916752)
		(width 0.16002)
		(layer "In4.Cu")
		(net "M_J_CPU1_SA_DQS_DN<1>")
	)
	(segment
		(start 149.949154 -221.916752)
		(end 161.3154 -210.550506)
		(width 0.16002)
		(layer "In4.Cu")
		(net "M_J_CPU1_SA_DQS_DN<1>")
	)
	(segment
		(start 144.005554 -232.015284)
		(end 144.015968 -232.009188)
		(width 0.09525)
		(layer "In4.Cu")
		(net "M_J_CPU1_SA_DQS_DN<1>")
	)
	(segment
		(start 140.25626 -232.009188)
		(end 140.264642 -232.004362)
		(width 0.09525)
		(layer "In4.Cu")
		(net "M_J_CPU1_SA_DQS_DN<1>")
	)
	(segment
		(start 144.644618 -231.406954)
		(end 144.644618 -230.68407)
		(width 0.09525)
		(layer "In4.Cu")
		(net "M_J_CPU1_SA_DQS_DN<1>")
	)
	(segment
		(start 186.30138 -210.2358)
		(end 186.41822 -210.11896)
		(width 0.16002)
		(layer "In4.Cu")
		(net "M_J_CPU1_SA_DQS_DN<1>")
	)
	(segment
		(start 145.026634 -230.302054)
		(end 145.384266 -230.302054)
		(width 0.09525)
		(layer "In4.Cu")
		(net "M_J_CPU1_SA_DQS_DN<1>")
	)
	(segment
		(start 170.005248 -209.9818)
		(end 170.535854 -210.512406)
		(width 0.16002)
		(layer "In4.Cu")
		(net "M_J_CPU1_SA_DQS_DN<1>")
	)
	(segment
		(start 165.279324 -210.85556)
		(end 166.133272 -210.85556)
		(width 0.16002)
		(layer "In4.Cu")
		(net "M_J_CPU1_SA_DQS_DN<1>")
	)
	(segment
		(start 177.86223 -210.512406)
		(end 180.040534 -210.512406)
		(width 0.16002)
		(layer "In4.Cu")
		(net "M_J_CPU1_SA_DQS_DN<1>")
	)
	(segment
		(start 175.137572 -210.19008)
		(end 175.66513 -209.662522)
		(width 0.16002)
		(layer "In4.Cu")
		(net "M_J_CPU1_SA_DQS_DN<1>")
	)
	(segment
		(start 189.62116 -210.661504)
		(end 189.738 -210.778344)
		(width 0.16002)
		(layer "In4.Cu")
		(net "M_J_CPU1_SA_DQS_DN<1>")
	)
	(segment
		(start 133.10489 -232.004362)
		(end 133.113272 -232.009188)
		(width 0.09525)
		(layer "In4.Cu")
		(net "M_J_CPU1_SA_DQS_DN<1>")
	)
	(segment
		(start 184.001918 -209.662522)
		(end 185.104024 -210.11896)
		(width 0.16002)
		(layer "In4.Cu")
		(net "M_J_CPU1_SA_DQS_DN<1>")
	)
	(segment
		(start 185.70448 -210.11896)
		(end 185.82132 -210.2358)
		(width 0.16002)
		(layer "In4.Cu")
		(net "M_J_CPU1_SA_DQS_DN<1>")
	)
	(segment
		(start 147.640294 -227.759768)
		(end 147.657058 -227.743004)
		(width 0.09525)
		(layer "In4.Cu")
		(net "M_J_CPU1_SA_DQS_DN<1>")
	)
	(segment
		(start 172.443394 -210.512406)
		(end 172.799248 -210.86826)
		(width 0.16002)
		(layer "In4.Cu")
		(net "M_J_CPU1_SA_DQS_DN<1>")
	)
	(segment
		(start 188.937392 -210.84286)
		(end 189.118748 -210.661504)
		(width 0.16002)
		(layer "In4.Cu")
		(net "M_J_CPU1_SA_DQS_DN<1>")
	)
	(segment
		(start 138.74496 -232.004362)
		(end 138.753342 -232.009188)
		(width 0.09525)
		(layer "In4.Cu")
		(net "M_J_CPU1_SA_DQS_DN<1>")
	)
	(segment
		(start 147.254468 -228.431852)
		(end 147.254468 -228.062536)
		(width 0.09525)
		(layer "In4.Cu")
		(net "M_J_CPU1_SA_DQS_DN<1>")
	)
	(segment
		(start 180.416708 -210.88858)
		(end 181.199536 -210.88858)
		(width 0.16002)
		(layer "In4.Cu")
		(net "M_J_CPU1_SA_DQS_DN<1>")
	)
	(segment
		(start 183.161432 -209.662522)
		(end 184.001918 -209.662522)
		(width 0.16002)
		(layer "In4.Cu")
		(net "M_J_CPU1_SA_DQS_DN<1>")
	)
	(segment
		(start 170.535854 -210.512406)
		(end 172.443394 -210.512406)
		(width 0.16002)
		(layer "In4.Cu")
		(net "M_J_CPU1_SA_DQS_DN<1>")
	)
	(segment
		(start 189.738 -210.778344)
		(end 190.21806 -210.778344)
		(width 0.16002)
		(layer "In4.Cu")
		(net "M_J_CPU1_SA_DQS_DN<1>")
	)
	(segment
		(start 187.033408 -210.11896)
		(end 187.757308 -210.84286)
		(width 0.16002)
		(layer "In4.Cu")
		(net "M_J_CPU1_SA_DQS_DN<1>")
	)
	(segment
		(start 142.504922 -232.004362)
		(end 142.505938 -232.00487)
		(width 0.09525)
		(layer "In4.Cu")
		(net "M_J_CPU1_SA_DQS_DN<1>")
	)
	(segment
		(start 147.657058 -227.743004)
		(end 149.949154 -225.450908)
		(width 0.16002)
		(layer "In4.Cu")
		(net "M_J_CPU1_SA_DQS_DN<1>")
	)
	(segment
		(start 186.41822 -210.11896)
		(end 187.033408 -210.11896)
		(width 0.16002)
		(layer "In4.Cu")
		(net "M_J_CPU1_SA_DQS_DN<1>")
	)
	(segment
		(start 177.012346 -209.662522)
		(end 177.86223 -210.512406)
		(width 0.16002)
		(layer "In4.Cu")
		(net "M_J_CPU1_SA_DQS_DN<1>")
	)
	(segment
		(start 185.104024 -210.11896)
		(end 185.70448 -210.11896)
		(width 0.16002)
		(layer "In4.Cu")
		(net "M_J_CPU1_SA_DQS_DN<1>")
	)
	(segment
		(start 173.630844 -210.86826)
		(end 174.309024 -210.19008)
		(width 0.16002)
		(layer "In4.Cu")
		(net "M_J_CPU1_SA_DQS_DN<1>")
	)
	(segment
		(start 190.886334 -210.661504)
		(end 191.160146 -210.935316)
		(width 0.16002)
		(layer "In4.Cu")
		(net "M_J_CPU1_SA_DQS_DN<1>")
	)
	(segment
		(start 134.61619 -232.009188)
		(end 134.624572 -232.004362)
		(width 0.09525)
		(layer "In4.Cu")
		(net "M_J_CPU1_SA_DQS_DN<1>")
	)
	(segment
		(start 175.66513 -209.662522)
		(end 177.012346 -209.662522)
		(width 0.16002)
		(layer "In4.Cu")
		(net "M_J_CPU1_SA_DQS_DN<1>")
	)
	(segment
		(start 181.905148 -210.182968)
		(end 183.161432 -209.662522)
		(width 0.16002)
		(layer "In4.Cu")
		(net "M_J_CPU1_SA_DQS_DN<1>")
	)
	(segment
		(start 181.199536 -210.88858)
		(end 181.905148 -210.182968)
		(width 0.16002)
		(layer "In4.Cu")
		(net "M_J_CPU1_SA_DQS_DN<1>")
	)
	(segment
		(start 132.77088 -232.068878)
		(end 132.794248 -231.98201)
		(width 0.09525)
		(layer "In4.Cu")
		(net "M_J_CPU1_SA_DQS_DN<1>")
	)
	(segment
		(start 190.3349 -210.661504)
		(end 190.886334 -210.661504)
		(width 0.16002)
		(layer "In4.Cu")
		(net "M_J_CPU1_SA_DQS_DN<1>")
	)
	(segment
		(start 166.133272 -210.85556)
		(end 167.007032 -209.9818)
		(width 0.16002)
		(layer "In4.Cu")
		(net "M_J_CPU1_SA_DQS_DN<1>")
	)
	(segment
		(start 144.644618 -230.68407)
		(end 145.026634 -230.302054)
		(width 0.09525)
		(layer "In4.Cu")
		(net "M_J_CPU1_SA_DQS_DN<1>")
	)
	(segment
		(start 143.076168 -232.009188)
		(end 143.08455 -232.004362)
		(width 0.09525)
		(layer "In4.Cu")
		(net "M_J_CPU1_SA_DQS_DN<1>")
	)
	(segment
		(start 135.556244 -232.009188)
		(end 135.564626 -232.004362)
		(width 0.09525)
		(layer "In4.Cu")
		(net "M_J_CPU1_SA_DQS_DN<1>")
	)
	(segment
		(start 161.3154 -210.550506)
		(end 164.97427 -210.550506)
		(width 0.16002)
		(layer "In4.Cu")
		(net "M_J_CPU1_SA_DQS_DN<1>")
	)
	(segment
		(start 164.97427 -210.550506)
		(end 165.279324 -210.85556)
		(width 0.16002)
		(layer "In4.Cu")
		(net "M_J_CPU1_SA_DQS_DN<1>")
	)
	(segment
		(start 144.13103 -231.920796)
		(end 144.644618 -231.406954)
		(width 0.09525)
		(layer "In4.Cu")
		(net "M_J_CPU1_SA_DQS_DN<1>")
	)
	(segment
		(start 187.757308 -210.84286)
		(end 188.937392 -210.84286)
		(width 0.16002)
		(layer "In4.Cu")
		(net "M_J_CPU1_SA_DQS_DN<1>")
	)
	(segment
		(start 147.557236 -227.759768)
		(end 147.640294 -227.759768)
		(width 0.09525)
		(layer "In4.Cu")
		(net "M_J_CPU1_SA_DQS_DN<1>")
	)
	(segment
		(start 139.316206 -232.009188)
		(end 139.324588 -232.004362)
		(width 0.09525)
		(layer "In4.Cu")
		(net "M_J_CPU1_SA_DQS_DN<1>")
	)
	(segment
		(start 185.82132 -210.2358)
		(end 186.30138 -210.2358)
		(width 0.16002)
		(layer "In4.Cu")
		(net "M_J_CPU1_SA_DQS_DN<1>")
	)
	(arc
		(start 135.564626 -232.004362)
		(mid 135.749658 -231.958448)
		(end 135.933434 -232.009188)
		(width 0.09525)
		(layer "In4.Cu")
		(net "M_J_CPU1_SA_DQS_DN<1>")
	)
	(arc
		(start 142.513304 -232.009188)
		(mid 142.794736 -232.084943)
		(end 143.076168 -232.009188)
		(width 0.09525)
		(layer "In4.Cu")
		(net "M_J_CPU1_SA_DQS_DN<1>")
	)
	(arc
		(start 133.113272 -232.009188)
		(mid 133.394704 -232.084943)
		(end 133.676136 -232.009188)
		(width 0.09525)
		(layer "In4.Cu")
		(net "M_J_CPU1_SA_DQS_DN<1>")
	)
	(arc
		(start 136.496298 -232.009188)
		(mid 136.684766 -231.958511)
		(end 136.873234 -232.009188)
		(width 0.09525)
		(layer "In4.Cu")
		(net "M_J_CPU1_SA_DQS_DN<1>")
	)
	(arc
		(start 132.794248 -231.98201)
		(mid 132.951998 -231.959491)
		(end 133.10489 -232.004362)
		(width 0.09525)
		(layer "In4.Cu")
		(net "M_J_CPU1_SA_DQS_DN<1>")
	)
	(arc
		(start 137.436098 -232.009188)
		(mid 137.619873 -231.958416)
		(end 137.804906 -232.004362)
		(width 0.09525)
		(layer "In4.Cu")
		(net "M_J_CPU1_SA_DQS_DN<1>")
	)
	(arc
		(start 140.63345 -232.009188)
		(mid 140.914882 -232.084943)
		(end 141.196314 -232.009188)
		(width 0.09525)
		(layer "In4.Cu")
		(net "M_J_CPU1_SA_DQS_DN<1>")
	)
	(arc
		(start 135.933434 -232.009188)
		(mid 136.214866 -232.084943)
		(end 136.496298 -232.009188)
		(width 0.09525)
		(layer "In4.Cu")
		(net "M_J_CPU1_SA_DQS_DN<1>")
	)
	(arc
		(start 133.676136 -232.009188)
		(mid 133.859911 -231.958416)
		(end 134.044944 -232.004362)
		(width 0.09525)
		(layer "In4.Cu")
		(net "M_J_CPU1_SA_DQS_DN<1>")
	)
	(arc
		(start 139.324588 -232.004362)
		(mid 139.50962 -231.958448)
		(end 139.693396 -232.009188)
		(width 0.09525)
		(layer "In4.Cu")
		(net "M_J_CPU1_SA_DQS_DN<1>")
	)
	(arc
		(start 144.12468 -231.927146)
		(mid 144.127868 -231.923984)
		(end 144.13103 -231.920796)
		(width 0.09525)
		(layer "In4.Cu")
		(net "M_J_CPU1_SA_DQS_DN<1>")
	)
	(arc
		(start 141.196314 -232.009188)
		(mid 141.384782 -231.958511)
		(end 141.57325 -232.009188)
		(width 0.09525)
		(layer "In4.Cu")
		(net "M_J_CPU1_SA_DQS_DN<1>")
	)
	(arc
		(start 134.053326 -232.009188)
		(mid 134.334758 -232.084943)
		(end 134.61619 -232.009188)
		(width 0.09525)
		(layer "In4.Cu")
		(net "M_J_CPU1_SA_DQS_DN<1>")
	)
	(arc
		(start 138.753342 -232.009188)
		(mid 139.034774 -232.084943)
		(end 139.316206 -232.009188)
		(width 0.09525)
		(layer "In4.Cu")
		(net "M_J_CPU1_SA_DQS_DN<1>")
	)
	(arc
		(start 139.693396 -232.009188)
		(mid 139.974828 -232.084943)
		(end 140.25626 -232.009188)
		(width 0.09525)
		(layer "In4.Cu")
		(net "M_J_CPU1_SA_DQS_DN<1>")
	)
	(arc
		(start 143.08455 -232.004362)
		(mid 143.269582 -231.958448)
		(end 143.453358 -232.009188)
		(width 0.09525)
		(layer "In4.Cu")
		(net "M_J_CPU1_SA_DQS_DN<1>")
	)
	(arc
		(start 134.99338 -232.009188)
		(mid 135.274812 -232.084943)
		(end 135.556244 -232.009188)
		(width 0.09525)
		(layer "In4.Cu")
		(net "M_J_CPU1_SA_DQS_DN<1>")
	)
	(arc
		(start 136.873234 -232.009188)
		(mid 137.154666 -232.084943)
		(end 137.436098 -232.009188)
		(width 0.09525)
		(layer "In4.Cu")
		(net "M_J_CPU1_SA_DQS_DN<1>")
	)
	(arc
		(start 144.015968 -232.009188)
		(mid 144.072817 -231.971472)
		(end 144.12468 -231.927146)
		(width 0.09525)
		(layer "In4.Cu")
		(net "M_J_CPU1_SA_DQS_DN<1>")
	)
	(arc
		(start 141.57325 -232.009188)
		(mid 141.854682 -232.084943)
		(end 142.136114 -232.009188)
		(width 0.09525)
		(layer "In4.Cu")
		(net "M_J_CPU1_SA_DQS_DN<1>")
	)
	(arc
		(start 142.136114 -232.009188)
		(mid 142.319889 -231.958416)
		(end 142.504922 -232.004362)
		(width 0.09525)
		(layer "In4.Cu")
		(net "M_J_CPU1_SA_DQS_DN<1>")
	)
	(arc
		(start 137.813288 -232.009188)
		(mid 138.09472 -232.084943)
		(end 138.376152 -232.009188)
		(width 0.09525)
		(layer "In4.Cu")
		(net "M_J_CPU1_SA_DQS_DN<1>")
	)
	(arc
		(start 140.264642 -232.004362)
		(mid 140.449674 -231.958448)
		(end 140.63345 -232.009188)
		(width 0.09525)
		(layer "In4.Cu")
		(net "M_J_CPU1_SA_DQS_DN<1>")
	)
	(arc
		(start 143.453358 -232.009188)
		(mid 143.728647 -232.084909)
		(end 144.005554 -232.015284)
		(width 0.09525)
		(layer "In4.Cu")
		(net "M_J_CPU1_SA_DQS_DN<1>")
	)
	(arc
		(start 138.376152 -232.009188)
		(mid 138.559927 -231.958416)
		(end 138.74496 -232.004362)
		(width 0.09525)
		(layer "In4.Cu")
		(net "M_J_CPU1_SA_DQS_DN<1>")
	)
	(arc
		(start 134.624572 -232.004362)
		(mid 134.809604 -231.958448)
		(end 134.99338 -232.009188)
		(width 0.09525)
		(layer "In4.Cu")
		(net "M_J_CPU1_SA_DQS_DN<1>")
	)
	(segment
		(start 132.457952 -227.740464)
		(end 132.924804 -227.474526)
		(width 0.12954)
		(layer "F.Cu")
		(net "M_J_CPU1_SA_DQS_DN<0>")
	)
	(segment
		(start 142.104618 -225.547682)
		(end 142.136114 -225.529394)
		(width 0.09525)
		(layer "In4.Cu")
		(net "M_J_CPU1_SA_DQS_DN<0>")
	)
	(segment
		(start 144.296384 -221.257876)
		(end 144.356074 -221.198186)
		(width 0.09525)
		(layer "In4.Cu")
		(net "M_J_CPU1_SA_DQS_DN<0>")
	)
	(segment
		(start 181.199536 -201.538586)
		(end 181.969156 -200.768966)
		(width 0.16002)
		(layer "In4.Cu")
		(net "M_J_CPU1_SA_DQS_DN<0>")
	)
	(segment
		(start 143.076168 -223.909382)
		(end 143.114268 -223.887284)
		(width 0.09525)
		(layer "In4.Cu")
		(net "M_J_CPU1_SA_DQS_DN<0>")
	)
	(segment
		(start 164.497258 -200.925176)
		(end 165.077648 -201.505566)
		(width 0.16002)
		(layer "In4.Cu")
		(net "M_J_CPU1_SA_DQS_DN<0>")
	)
	(segment
		(start 190.195708 -201.42835)
		(end 190.312548 -201.31151)
		(width 0.16002)
		(layer "In4.Cu")
		(net "M_J_CPU1_SA_DQS_DN<0>")
	)
	(segment
		(start 189.715648 -201.42835)
		(end 190.195708 -201.42835)
		(width 0.16002)
		(layer "In4.Cu")
		(net "M_J_CPU1_SA_DQS_DN<0>")
	)
	(segment
		(start 186.50966 -200.768966)
		(end 187.033408 -200.768966)
		(width 0.16002)
		(layer "In4.Cu")
		(net "M_J_CPU1_SA_DQS_DN<0>")
	)
	(segment
		(start 141.666214 -226.3394)
		(end 141.704314 -226.317302)
		(width 0.09525)
		(layer "In4.Cu")
		(net "M_J_CPU1_SA_DQS_DN<0>")
	)
	(segment
		(start 141.633702 -226.358196)
		(end 141.666214 -226.3394)
		(width 0.09525)
		(layer "In4.Cu")
		(net "M_J_CPU1_SA_DQS_DN<0>")
	)
	(segment
		(start 188.937392 -201.492866)
		(end 189.118748 -201.31151)
		(width 0.16002)
		(layer "In4.Cu")
		(net "M_J_CPU1_SA_DQS_DN<0>")
	)
	(segment
		(start 135.556244 -227.149406)
		(end 135.564626 -227.14458)
		(width 0.09525)
		(layer "In4.Cu")
		(net "M_J_CPU1_SA_DQS_DN<0>")
	)
	(segment
		(start 186.39282 -200.885806)
		(end 186.50966 -200.768966)
		(width 0.16002)
		(layer "In4.Cu")
		(net "M_J_CPU1_SA_DQS_DN<0>")
	)
	(segment
		(start 190.886334 -201.31151)
		(end 191.160146 -201.585322)
		(width 0.16002)
		(layer "In4.Cu")
		(net "M_J_CPU1_SA_DQS_DN<0>")
	)
	(segment
		(start 187.757308 -201.492866)
		(end 188.937392 -201.492866)
		(width 0.16002)
		(layer "In4.Cu")
		(net "M_J_CPU1_SA_DQS_DN<0>")
	)
	(segment
		(start 161.498534 -200.925176)
		(end 164.497258 -200.925176)
		(width 0.16002)
		(layer "In4.Cu")
		(net "M_J_CPU1_SA_DQS_DN<0>")
	)
	(segment
		(start 142.573756 -224.738184)
		(end 142.606268 -224.719388)
		(width 0.09525)
		(layer "In4.Cu")
		(net "M_J_CPU1_SA_DQS_DN<0>")
	)
	(segment
		(start 142.136114 -225.529394)
		(end 142.174214 -225.507296)
		(width 0.09525)
		(layer "In4.Cu")
		(net "M_J_CPU1_SA_DQS_DN<0>")
	)
	(segment
		(start 144.296384 -221.803976)
		(end 144.296384 -221.257876)
		(width 0.09525)
		(layer "In4.Cu")
		(net "M_J_CPU1_SA_DQS_DN<0>")
	)
	(segment
		(start 190.312548 -201.31151)
		(end 190.886334 -201.31151)
		(width 0.16002)
		(layer "In4.Cu")
		(net "M_J_CPU1_SA_DQS_DN<0>")
	)
	(segment
		(start 175.66513 -200.312528)
		(end 177.012346 -200.312528)
		(width 0.16002)
		(layer "In4.Cu")
		(net "M_J_CPU1_SA_DQS_DN<0>")
	)
	(segment
		(start 134.61619 -227.149406)
		(end 134.624572 -227.14458)
		(width 0.09525)
		(layer "In4.Cu")
		(net "M_J_CPU1_SA_DQS_DN<0>")
	)
	(segment
		(start 185.79592 -200.768966)
		(end 185.91276 -200.885806)
		(width 0.16002)
		(layer "In4.Cu")
		(net "M_J_CPU1_SA_DQS_DN<0>")
	)
	(segment
		(start 182.67807 -200.768966)
		(end 183.134508 -200.312528)
		(width 0.16002)
		(layer "In4.Cu")
		(net "M_J_CPU1_SA_DQS_DN<0>")
	)
	(segment
		(start 133.10489 -227.14458)
		(end 133.113272 -227.149406)
		(width 0.09525)
		(layer "In4.Cu")
		(net "M_J_CPU1_SA_DQS_DN<0>")
	)
	(segment
		(start 178.45913 -201.279252)
		(end 178.93919 -201.279252)
		(width 0.16002)
		(layer "In4.Cu")
		(net "M_J_CPU1_SA_DQS_DN<0>")
	)
	(segment
		(start 144.356074 -221.174564)
		(end 144.356074 -218.067636)
		(width 0.16002)
		(layer "In4.Cu")
		(net "M_J_CPU1_SA_DQS_DN<0>")
	)
	(segment
		(start 143.984472 -222.307658)
		(end 144.055338 -222.26651)
		(width 0.09525)
		(layer "In4.Cu")
		(net "M_J_CPU1_SA_DQS_DN<0>")
	)
	(segment
		(start 177.012346 -200.312528)
		(end 177.86223 -201.162412)
		(width 0.16002)
		(layer "In4.Cu")
		(net "M_J_CPU1_SA_DQS_DN<0>")
	)
	(segment
		(start 185.91276 -200.885806)
		(end 186.39282 -200.885806)
		(width 0.16002)
		(layer "In4.Cu")
		(net "M_J_CPU1_SA_DQS_DN<0>")
	)
	(segment
		(start 189.598808 -201.31151)
		(end 189.715648 -201.42835)
		(width 0.16002)
		(layer "In4.Cu")
		(net "M_J_CPU1_SA_DQS_DN<0>")
	)
	(segment
		(start 181.969156 -200.768966)
		(end 182.67807 -200.768966)
		(width 0.16002)
		(layer "In4.Cu")
		(net "M_J_CPU1_SA_DQS_DN<0>")
	)
	(segment
		(start 143.043656 -223.928178)
		(end 143.076168 -223.909382)
		(width 0.09525)
		(layer "In4.Cu")
		(net "M_J_CPU1_SA_DQS_DN<0>")
	)
	(segment
		(start 184.95391 -200.768966)
		(end 185.79592 -200.768966)
		(width 0.16002)
		(layer "In4.Cu")
		(net "M_J_CPU1_SA_DQS_DN<0>")
	)
	(segment
		(start 138.74496 -227.14458)
		(end 138.753342 -227.149406)
		(width 0.09525)
		(layer "In4.Cu")
		(net "M_J_CPU1_SA_DQS_DN<0>")
	)
	(segment
		(start 170.535854 -201.162412)
		(end 172.443394 -201.162412)
		(width 0.16002)
		(layer "In4.Cu")
		(net "M_J_CPU1_SA_DQS_DN<0>")
	)
	(segment
		(start 140.25626 -227.149406)
		(end 140.264642 -227.14458)
		(width 0.09525)
		(layer "In4.Cu")
		(net "M_J_CPU1_SA_DQS_DN<0>")
	)
	(segment
		(start 178.93919 -201.279252)
		(end 179.05603 -201.162412)
		(width 0.16002)
		(layer "In4.Cu")
		(net "M_J_CPU1_SA_DQS_DN<0>")
	)
	(segment
		(start 132.77088 -227.209096)
		(end 132.794248 -227.122228)
		(width 0.09525)
		(layer "In4.Cu")
		(net "M_J_CPU1_SA_DQS_DN<0>")
	)
	(segment
		(start 142.606268 -224.719388)
		(end 142.64132 -224.698814)
		(width 0.09525)
		(layer "In4.Cu")
		(net "M_J_CPU1_SA_DQS_DN<0>")
	)
	(segment
		(start 165.077648 -201.505566)
		(end 166.133272 -201.505566)
		(width 0.16002)
		(layer "In4.Cu")
		(net "M_J_CPU1_SA_DQS_DN<0>")
	)
	(segment
		(start 170.005248 -200.631806)
		(end 170.535854 -201.162412)
		(width 0.16002)
		(layer "In4.Cu")
		(net "M_J_CPU1_SA_DQS_DN<0>")
	)
	(segment
		(start 179.05603 -201.162412)
		(end 180.040534 -201.162412)
		(width 0.16002)
		(layer "In4.Cu")
		(net "M_J_CPU1_SA_DQS_DN<0>")
	)
	(segment
		(start 144.356074 -218.067636)
		(end 161.498534 -200.925176)
		(width 0.16002)
		(layer "In4.Cu")
		(net "M_J_CPU1_SA_DQS_DN<0>")
	)
	(segment
		(start 144.356074 -221.198186)
		(end 144.356074 -221.174564)
		(width 0.09525)
		(layer "In4.Cu")
		(net "M_J_CPU1_SA_DQS_DN<0>")
	)
	(segment
		(start 143.546068 -223.099376)
		(end 143.584168 -223.077278)
		(width 0.09525)
		(layer "In4.Cu")
		(net "M_J_CPU1_SA_DQS_DN<0>")
	)
	(segment
		(start 132.924804 -227.474526)
		(end 132.77088 -227.209096)
		(width 0.09525)
		(layer "In4.Cu")
		(net "M_J_CPU1_SA_DQS_DN<0>")
	)
	(segment
		(start 189.118748 -201.31151)
		(end 189.598808 -201.31151)
		(width 0.16002)
		(layer "In4.Cu")
		(net "M_J_CPU1_SA_DQS_DN<0>")
	)
	(segment
		(start 137.804906 -227.14458)
		(end 137.813288 -227.149406)
		(width 0.09525)
		(layer "In4.Cu")
		(net "M_J_CPU1_SA_DQS_DN<0>")
	)
	(segment
		(start 143.514572 -223.117664)
		(end 143.546068 -223.099376)
		(width 0.09525)
		(layer "In4.Cu")
		(net "M_J_CPU1_SA_DQS_DN<0>")
	)
	(segment
		(start 141.196314 -227.149406)
		(end 141.231366 -227.128832)
		(width 0.09525)
		(layer "In4.Cu")
		(net "M_J_CPU1_SA_DQS_DN<0>")
	)
	(segment
		(start 178.34229 -201.162412)
		(end 178.45913 -201.279252)
		(width 0.16002)
		(layer "In4.Cu")
		(net "M_J_CPU1_SA_DQS_DN<0>")
	)
	(segment
		(start 180.416708 -201.538586)
		(end 181.199536 -201.538586)
		(width 0.16002)
		(layer "In4.Cu")
		(net "M_J_CPU1_SA_DQS_DN<0>")
	)
	(segment
		(start 172.799248 -201.518266)
		(end 173.630844 -201.518266)
		(width 0.16002)
		(layer "In4.Cu")
		(net "M_J_CPU1_SA_DQS_DN<0>")
	)
	(segment
		(start 187.033408 -200.768966)
		(end 187.757308 -201.492866)
		(width 0.16002)
		(layer "In4.Cu")
		(net "M_J_CPU1_SA_DQS_DN<0>")
	)
	(segment
		(start 175.137572 -200.840086)
		(end 175.66513 -200.312528)
		(width 0.16002)
		(layer "In4.Cu")
		(net "M_J_CPU1_SA_DQS_DN<0>")
	)
	(segment
		(start 177.86223 -201.162412)
		(end 178.34229 -201.162412)
		(width 0.16002)
		(layer "In4.Cu")
		(net "M_J_CPU1_SA_DQS_DN<0>")
	)
	(segment
		(start 172.443394 -201.162412)
		(end 172.799248 -201.518266)
		(width 0.16002)
		(layer "In4.Cu")
		(net "M_J_CPU1_SA_DQS_DN<0>")
	)
	(segment
		(start 174.309024 -200.840086)
		(end 175.137572 -200.840086)
		(width 0.16002)
		(layer "In4.Cu")
		(net "M_J_CPU1_SA_DQS_DN<0>")
	)
	(segment
		(start 134.044944 -227.14458)
		(end 134.053326 -227.149406)
		(width 0.09525)
		(layer "In4.Cu")
		(net "M_J_CPU1_SA_DQS_DN<0>")
	)
	(segment
		(start 139.316206 -227.149406)
		(end 139.324588 -227.14458)
		(width 0.09525)
		(layer "In4.Cu")
		(net "M_J_CPU1_SA_DQS_DN<0>")
	)
	(segment
		(start 144.296892 -221.804484)
		(end 144.296384 -221.803976)
		(width 0.09525)
		(layer "In4.Cu")
		(net "M_J_CPU1_SA_DQS_DN<0>")
	)
	(segment
		(start 180.040534 -201.162412)
		(end 180.416708 -201.538586)
		(width 0.16002)
		(layer "In4.Cu")
		(net "M_J_CPU1_SA_DQS_DN<0>")
	)
	(segment
		(start 167.007032 -200.631806)
		(end 170.005248 -200.631806)
		(width 0.16002)
		(layer "In4.Cu")
		(net "M_J_CPU1_SA_DQS_DN<0>")
	)
	(segment
		(start 183.134508 -200.312528)
		(end 184.497472 -200.312528)
		(width 0.16002)
		(layer "In4.Cu")
		(net "M_J_CPU1_SA_DQS_DN<0>")
	)
	(segment
		(start 166.133272 -201.505566)
		(end 167.007032 -200.631806)
		(width 0.16002)
		(layer "In4.Cu")
		(net "M_J_CPU1_SA_DQS_DN<0>")
	)
	(segment
		(start 184.497472 -200.312528)
		(end 184.95391 -200.768966)
		(width 0.16002)
		(layer "In4.Cu")
		(net "M_J_CPU1_SA_DQS_DN<0>")
	)
	(segment
		(start 173.630844 -201.518266)
		(end 174.309024 -200.840086)
		(width 0.16002)
		(layer "In4.Cu")
		(net "M_J_CPU1_SA_DQS_DN<0>")
	)
	(arc
		(start 141.231366 -227.128832)
		(mid 141.411757 -226.927133)
		(end 141.476984 -226.66452)
		(width 0.09525)
		(layer "In4.Cu")
		(net "M_J_CPU1_SA_DQS_DN<0>")
	)
	(arc
		(start 135.933434 -227.149406)
		(mid 136.214866 -227.225161)
		(end 136.496298 -227.149406)
		(width 0.09525)
		(layer "In4.Cu")
		(net "M_J_CPU1_SA_DQS_DN<0>")
	)
	(arc
		(start 135.564626 -227.14458)
		(mid 135.749658 -227.098666)
		(end 135.933434 -227.149406)
		(width 0.09525)
		(layer "In4.Cu")
		(net "M_J_CPU1_SA_DQS_DN<0>")
	)
	(arc
		(start 133.113272 -227.149406)
		(mid 133.394704 -227.225161)
		(end 133.676136 -227.149406)
		(width 0.09525)
		(layer "In4.Cu")
		(net "M_J_CPU1_SA_DQS_DN<0>")
	)
	(arc
		(start 143.357092 -223.424496)
		(mid 143.398757 -223.252049)
		(end 143.514572 -223.117664)
		(width 0.09525)
		(layer "In4.Cu")
		(net "M_J_CPU1_SA_DQS_DN<0>")
	)
	(arc
		(start 138.753342 -227.149406)
		(mid 139.034774 -227.225161)
		(end 139.316206 -227.149406)
		(width 0.09525)
		(layer "In4.Cu")
		(net "M_J_CPU1_SA_DQS_DN<0>")
	)
	(arc
		(start 140.63345 -227.149406)
		(mid 140.914882 -227.225161)
		(end 141.196314 -227.149406)
		(width 0.09525)
		(layer "In4.Cu")
		(net "M_J_CPU1_SA_DQS_DN<0>")
	)
	(arc
		(start 134.624572 -227.14458)
		(mid 134.809604 -227.098666)
		(end 134.99338 -227.149406)
		(width 0.09525)
		(layer "In4.Cu")
		(net "M_J_CPU1_SA_DQS_DN<0>")
	)
	(arc
		(start 142.64132 -224.698814)
		(mid 142.821711 -224.497115)
		(end 142.886938 -224.234502)
		(width 0.09525)
		(layer "In4.Cu")
		(net "M_J_CPU1_SA_DQS_DN<0>")
	)
	(arc
		(start 136.873234 -227.149406)
		(mid 137.154666 -227.225161)
		(end 137.436098 -227.149406)
		(width 0.09525)
		(layer "In4.Cu")
		(net "M_J_CPU1_SA_DQS_DN<0>")
	)
	(arc
		(start 134.99338 -227.149406)
		(mid 135.274812 -227.225161)
		(end 135.556244 -227.149406)
		(width 0.09525)
		(layer "In4.Cu")
		(net "M_J_CPU1_SA_DQS_DN<0>")
	)
	(arc
		(start 141.476984 -226.66452)
		(mid 141.518441 -226.49248)
		(end 141.633702 -226.358196)
		(width 0.09525)
		(layer "In4.Cu")
		(net "M_J_CPU1_SA_DQS_DN<0>")
	)
	(arc
		(start 142.417038 -225.044508)
		(mid 142.458495 -224.872468)
		(end 142.573756 -224.738184)
		(width 0.09525)
		(layer "In4.Cu")
		(net "M_J_CPU1_SA_DQS_DN<0>")
	)
	(arc
		(start 133.676136 -227.149406)
		(mid 133.859911 -227.098634)
		(end 134.044944 -227.14458)
		(width 0.09525)
		(layer "In4.Cu")
		(net "M_J_CPU1_SA_DQS_DN<0>")
	)
	(arc
		(start 140.264642 -227.14458)
		(mid 140.449674 -227.098666)
		(end 140.63345 -227.149406)
		(width 0.09525)
		(layer "In4.Cu")
		(net "M_J_CPU1_SA_DQS_DN<0>")
	)
	(arc
		(start 139.693396 -227.149406)
		(mid 139.974828 -227.225161)
		(end 140.25626 -227.149406)
		(width 0.09525)
		(layer "In4.Cu")
		(net "M_J_CPU1_SA_DQS_DN<0>")
	)
	(arc
		(start 142.886938 -224.234502)
		(mid 142.928395 -224.062462)
		(end 143.043656 -223.928178)
		(width 0.09525)
		(layer "In4.Cu")
		(net "M_J_CPU1_SA_DQS_DN<0>")
	)
	(arc
		(start 137.436098 -227.149406)
		(mid 137.619873 -227.098634)
		(end 137.804906 -227.14458)
		(width 0.09525)
		(layer "In4.Cu")
		(net "M_J_CPU1_SA_DQS_DN<0>")
	)
	(arc
		(start 134.053326 -227.149406)
		(mid 134.334758 -227.225161)
		(end 134.61619 -227.149406)
		(width 0.09525)
		(layer "In4.Cu")
		(net "M_J_CPU1_SA_DQS_DN<0>")
	)
	(arc
		(start 138.376152 -227.149406)
		(mid 138.559927 -227.098634)
		(end 138.74496 -227.14458)
		(width 0.09525)
		(layer "In4.Cu")
		(net "M_J_CPU1_SA_DQS_DN<0>")
	)
	(arc
		(start 136.496298 -227.149406)
		(mid 136.684766 -227.098729)
		(end 136.873234 -227.149406)
		(width 0.09525)
		(layer "In4.Cu")
		(net "M_J_CPU1_SA_DQS_DN<0>")
	)
	(arc
		(start 143.114268 -223.887284)
		(mid 143.292718 -223.685814)
		(end 143.357092 -223.424496)
		(width 0.09525)
		(layer "In4.Cu")
		(net "M_J_CPU1_SA_DQS_DN<0>")
	)
	(arc
		(start 132.794248 -227.122228)
		(mid 132.951998 -227.099709)
		(end 133.10489 -227.14458)
		(width 0.09525)
		(layer "In4.Cu")
		(net "M_J_CPU1_SA_DQS_DN<0>")
	)
	(arc
		(start 139.324588 -227.14458)
		(mid 139.50962 -227.098666)
		(end 139.693396 -227.149406)
		(width 0.09525)
		(layer "In4.Cu")
		(net "M_J_CPU1_SA_DQS_DN<0>")
	)
	(arc
		(start 137.813288 -227.149406)
		(mid 138.09472 -227.225161)
		(end 138.376152 -227.149406)
		(width 0.09525)
		(layer "In4.Cu")
		(net "M_J_CPU1_SA_DQS_DN<0>")
	)
	(arc
		(start 141.947138 -225.854514)
		(mid 141.988803 -225.682067)
		(end 142.104618 -225.547682)
		(width 0.09525)
		(layer "In4.Cu")
		(net "M_J_CPU1_SA_DQS_DN<0>")
	)
	(arc
		(start 144.055338 -222.26651)
		(mid 144.232869 -222.065167)
		(end 144.296892 -221.804484)
		(width 0.09525)
		(layer "In4.Cu")
		(net "M_J_CPU1_SA_DQS_DN<0>")
	)
	(arc
		(start 141.704314 -226.317302)
		(mid 141.882764 -226.115832)
		(end 141.947138 -225.854514)
		(width 0.09525)
		(layer "In4.Cu")
		(net "M_J_CPU1_SA_DQS_DN<0>")
	)
	(arc
		(start 143.826992 -222.61449)
		(mid 143.868657 -222.442043)
		(end 143.984472 -222.307658)
		(width 0.09525)
		(layer "In4.Cu")
		(net "M_J_CPU1_SA_DQS_DN<0>")
	)
	(arc
		(start 142.174214 -225.507296)
		(mid 142.352664 -225.305826)
		(end 142.417038 -225.044508)
		(width 0.09525)
		(layer "In4.Cu")
		(net "M_J_CPU1_SA_DQS_DN<0>")
	)
	(arc
		(start 143.584168 -223.077278)
		(mid 143.762618 -222.875808)
		(end 143.826992 -222.61449)
		(width 0.09525)
		(layer "In4.Cu")
		(net "M_J_CPU1_SA_DQS_DN<0>")
	)
	(segment
		(start 130.577844 -230.980234)
		(end 131.044696 -230.71455)
		(width 0.10668)
		(layer "F.Cu")
		(net "M_J_CPU1_SA_DQ<9>")
	)
	(segment
		(start 153.145236 -216.866724)
		(end 161.201608 -208.810352)
		(width 0.14478)
		(layer "In4.Cu")
		(net "M_J_CPU1_SA_DQ<9>")
	)
	(segment
		(start 143.451834 -231.036876)
		(end 143.486378 -231.01681)
		(width 0.0889)
		(layer "In4.Cu")
		(net "M_J_CPU1_SA_DQ<9>")
	)
	(segment
		(start 165.535356 -208.810352)
		(end 167.587168 -207.960468)
		(width 0.14478)
		(layer "In4.Cu")
		(net "M_J_CPU1_SA_DQ<9>")
	)
	(segment
		(start 131.044696 -230.71455)
		(end 131.198874 -230.97998)
		(width 0.0889)
		(layer "In4.Cu")
		(net "M_J_CPU1_SA_DQ<9>")
	)
	(segment
		(start 139.31773 -231.036876)
		(end 139.326112 -231.041702)
		(width 0.0889)
		(layer "In4.Cu")
		(net "M_J_CPU1_SA_DQ<9>")
	)
	(segment
		(start 134.04342 -231.041702)
		(end 134.051802 -231.036876)
		(width 0.0889)
		(layer "In4.Cu")
		(net "M_J_CPU1_SA_DQ<9>")
	)
	(segment
		(start 134.617714 -231.036876)
		(end 134.626096 -231.041702)
		(width 0.0889)
		(layer "In4.Cu")
		(net "M_J_CPU1_SA_DQ<9>")
	)
	(segment
		(start 171.616624 -208.810352)
		(end 172.903388 -208.810352)
		(width 0.14478)
		(layer "In4.Cu")
		(net "M_J_CPU1_SA_DQ<9>")
	)
	(segment
		(start 131.198874 -230.97998)
		(end 131.294632 -231.00538)
		(width 0.0889)
		(layer "In4.Cu")
		(net "M_J_CPU1_SA_DQ<9>")
	)
	(segment
		(start 144.10309 -229.60457)
		(end 145.057876 -228.649784)
		(width 0.0889)
		(layer "In4.Cu")
		(net "M_J_CPU1_SA_DQ<9>")
	)
	(segment
		(start 133.103366 -231.041702)
		(end 133.111748 -231.036876)
		(width 0.0889)
		(layer "In4.Cu")
		(net "M_J_CPU1_SA_DQ<9>")
	)
	(segment
		(start 145.122646 -228.649784)
		(end 147.04187 -226.73056)
		(width 0.0889)
		(layer "In4.Cu")
		(net "M_J_CPU1_SA_DQ<9>")
	)
	(segment
		(start 135.557768 -231.036876)
		(end 135.56615 -231.041702)
		(width 0.0889)
		(layer "In4.Cu")
		(net "M_J_CPU1_SA_DQ<9>")
	)
	(segment
		(start 167.587168 -207.960468)
		(end 169.564812 -207.960468)
		(width 0.14478)
		(layer "In4.Cu")
		(net "M_J_CPU1_SA_DQ<9>")
	)
	(segment
		(start 147.04187 -226.483164)
		(end 147.30349 -226.221544)
		(width 0.0889)
		(layer "In4.Cu")
		(net "M_J_CPU1_SA_DQ<9>")
	)
	(segment
		(start 172.903388 -208.810352)
		(end 174.9552 -207.960468)
		(width 0.14478)
		(layer "In4.Cu")
		(net "M_J_CPU1_SA_DQ<9>")
	)
	(segment
		(start 182.570374 -207.960468)
		(end 189.023752 -207.960468)
		(width 0.14478)
		(layer "In4.Cu")
		(net "M_J_CPU1_SA_DQ<9>")
	)
	(segment
		(start 147.30349 -226.221544)
		(end 148.638514 -224.88652)
		(width 0.14478)
		(layer "In4.Cu")
		(net "M_J_CPU1_SA_DQ<9>")
	)
	(segment
		(start 169.564812 -207.960468)
		(end 171.616624 -208.810352)
		(width 0.14478)
		(layer "In4.Cu")
		(net "M_J_CPU1_SA_DQ<9>")
	)
	(segment
		(start 174.9552 -207.960468)
		(end 177.284634 -207.960468)
		(width 0.14478)
		(layer "In4.Cu")
		(net "M_J_CPU1_SA_DQ<9>")
	)
	(segment
		(start 177.284634 -207.960468)
		(end 179.336446 -208.810352)
		(width 0.14478)
		(layer "In4.Cu")
		(net "M_J_CPU1_SA_DQ<9>")
	)
	(segment
		(start 145.057876 -228.649784)
		(end 145.122646 -228.649784)
		(width 0.0889)
		(layer "In4.Cu")
		(net "M_J_CPU1_SA_DQ<9>")
	)
	(segment
		(start 140.257784 -231.036876)
		(end 140.266166 -231.041702)
		(width 0.0889)
		(layer "In4.Cu")
		(net "M_J_CPU1_SA_DQ<9>")
	)
	(segment
		(start 147.04187 -226.73056)
		(end 147.04187 -226.483164)
		(width 0.0889)
		(layer "In4.Cu")
		(net "M_J_CPU1_SA_DQ<9>")
	)
	(segment
		(start 142.503398 -231.041702)
		(end 142.51178 -231.036876)
		(width 0.0889)
		(layer "In4.Cu")
		(net "M_J_CPU1_SA_DQ<9>")
	)
	(segment
		(start 137.803382 -231.041702)
		(end 137.811764 -231.036876)
		(width 0.0889)
		(layer "In4.Cu")
		(net "M_J_CPU1_SA_DQ<9>")
	)
	(segment
		(start 152.327356 -216.866724)
		(end 153.145236 -216.866724)
		(width 0.14478)
		(layer "In4.Cu")
		(net "M_J_CPU1_SA_DQ<9>")
	)
	(segment
		(start 180.518562 -208.810352)
		(end 182.570374 -207.960468)
		(width 0.14478)
		(layer "In4.Cu")
		(net "M_J_CPU1_SA_DQ<9>")
	)
	(segment
		(start 148.638514 -220.555566)
		(end 152.327356 -216.866724)
		(width 0.14478)
		(layer "In4.Cu")
		(net "M_J_CPU1_SA_DQ<9>")
	)
	(segment
		(start 189.023752 -207.960468)
		(end 191.160146 -208.38541)
		(width 0.14478)
		(layer "In4.Cu")
		(net "M_J_CPU1_SA_DQ<9>")
	)
	(segment
		(start 143.077692 -231.036876)
		(end 143.086074 -231.041702)
		(width 0.0889)
		(layer "In4.Cu")
		(net "M_J_CPU1_SA_DQ<9>")
	)
	(segment
		(start 161.201608 -208.810352)
		(end 165.535356 -208.810352)
		(width 0.14478)
		(layer "In4.Cu")
		(net "M_J_CPU1_SA_DQ<9>")
	)
	(segment
		(start 179.336446 -208.810352)
		(end 180.518562 -208.810352)
		(width 0.14478)
		(layer "In4.Cu")
		(net "M_J_CPU1_SA_DQ<9>")
	)
	(segment
		(start 148.638514 -224.88652)
		(end 148.638514 -220.555566)
		(width 0.14478)
		(layer "In4.Cu")
		(net "M_J_CPU1_SA_DQ<9>")
	)
	(segment
		(start 138.743436 -231.041702)
		(end 138.751818 -231.036876)
		(width 0.0889)
		(layer "In4.Cu")
		(net "M_J_CPU1_SA_DQ<9>")
	)
	(segment
		(start 144.10309 -229.911656)
		(end 144.10309 -229.60457)
		(width 0.0889)
		(layer "In4.Cu")
		(net "M_J_CPU1_SA_DQ<9>")
	)
	(segment
		(start 143.885412 -230.248206)
		(end 143.921988 -230.22687)
		(width 0.0889)
		(layer "In4.Cu")
		(net "M_J_CPU1_SA_DQ<9>")
	)
	(arc
		(start 132.737606 -231.036876)
		(mid 132.919857 -231.08726)
		(end 133.103366 -231.041702)
		(width 0.0889)
		(layer "In4.Cu")
		(net "M_J_CPU1_SA_DQ<9>")
	)
	(arc
		(start 134.991856 -231.036876)
		(mid 135.274812 -230.960699)
		(end 135.557768 -231.036876)
		(width 0.0889)
		(layer "In4.Cu")
		(net "M_J_CPU1_SA_DQ<9>")
	)
	(arc
		(start 143.921988 -230.22687)
		(mid 144.054547 -230.093408)
		(end 144.10309 -229.911656)
		(width 0.0889)
		(layer "In4.Cu")
		(net "M_J_CPU1_SA_DQ<9>")
	)
	(arc
		(start 142.137638 -231.036876)
		(mid 142.319889 -231.08726)
		(end 142.503398 -231.041702)
		(width 0.0889)
		(layer "In4.Cu")
		(net "M_J_CPU1_SA_DQ<9>")
	)
	(arc
		(start 136.87171 -231.036876)
		(mid 137.154666 -230.960699)
		(end 137.437622 -231.036876)
		(width 0.0889)
		(layer "In4.Cu")
		(net "M_J_CPU1_SA_DQ<9>")
	)
	(arc
		(start 143.63954 -230.71455)
		(mid 143.704776 -230.450959)
		(end 143.885412 -230.248206)
		(width 0.0889)
		(layer "In4.Cu")
		(net "M_J_CPU1_SA_DQ<9>")
	)
	(arc
		(start 137.811764 -231.036876)
		(mid 138.09472 -230.960699)
		(end 138.377676 -231.036876)
		(width 0.0889)
		(layer "In4.Cu")
		(net "M_J_CPU1_SA_DQ<9>")
	)
	(arc
		(start 133.111748 -231.036876)
		(mid 133.394704 -230.960699)
		(end 133.67766 -231.036876)
		(width 0.0889)
		(layer "In4.Cu")
		(net "M_J_CPU1_SA_DQ<9>")
	)
	(arc
		(start 143.486378 -231.01681)
		(mid 143.599043 -230.883969)
		(end 143.63954 -230.71455)
		(width 0.0889)
		(layer "In4.Cu")
		(net "M_J_CPU1_SA_DQ<9>")
	)
	(arc
		(start 131.294632 -231.00538)
		(mid 131.549954 -230.96168)
		(end 131.797806 -231.036876)
		(width 0.0889)
		(layer "In4.Cu")
		(net "M_J_CPU1_SA_DQ<9>")
	)
	(arc
		(start 141.571726 -231.036876)
		(mid 141.854682 -230.960699)
		(end 142.137638 -231.036876)
		(width 0.0889)
		(layer "In4.Cu")
		(net "M_J_CPU1_SA_DQ<9>")
	)
	(arc
		(start 134.051802 -231.036876)
		(mid 134.334758 -230.960699)
		(end 134.617714 -231.036876)
		(width 0.0889)
		(layer "In4.Cu")
		(net "M_J_CPU1_SA_DQ<9>")
	)
	(arc
		(start 134.626096 -231.041702)
		(mid 134.809604 -231.087227)
		(end 134.991856 -231.036876)
		(width 0.0889)
		(layer "In4.Cu")
		(net "M_J_CPU1_SA_DQ<9>")
	)
	(arc
		(start 138.751818 -231.036876)
		(mid 139.034774 -230.960699)
		(end 139.31773 -231.036876)
		(width 0.0889)
		(layer "In4.Cu")
		(net "M_J_CPU1_SA_DQ<9>")
	)
	(arc
		(start 137.437622 -231.036876)
		(mid 137.619873 -231.08726)
		(end 137.803382 -231.041702)
		(width 0.0889)
		(layer "In4.Cu")
		(net "M_J_CPU1_SA_DQ<9>")
	)
	(arc
		(start 131.797806 -231.036876)
		(mid 131.98475 -231.087165)
		(end 132.171694 -231.036876)
		(width 0.0889)
		(layer "In4.Cu")
		(net "M_J_CPU1_SA_DQ<9>")
	)
	(arc
		(start 135.93191 -231.036876)
		(mid 136.214866 -230.960699)
		(end 136.497822 -231.036876)
		(width 0.0889)
		(layer "In4.Cu")
		(net "M_J_CPU1_SA_DQ<9>")
	)
	(arc
		(start 132.171694 -231.036876)
		(mid 132.45465 -230.960699)
		(end 132.737606 -231.036876)
		(width 0.0889)
		(layer "In4.Cu")
		(net "M_J_CPU1_SA_DQ<9>")
	)
	(arc
		(start 142.51178 -231.036876)
		(mid 142.794736 -230.960699)
		(end 143.077692 -231.036876)
		(width 0.0889)
		(layer "In4.Cu")
		(net "M_J_CPU1_SA_DQ<9>")
	)
	(arc
		(start 133.67766 -231.036876)
		(mid 133.859911 -231.08726)
		(end 134.04342 -231.041702)
		(width 0.0889)
		(layer "In4.Cu")
		(net "M_J_CPU1_SA_DQ<9>")
	)
	(arc
		(start 135.56615 -231.041702)
		(mid 135.749658 -231.087227)
		(end 135.93191 -231.036876)
		(width 0.0889)
		(layer "In4.Cu")
		(net "M_J_CPU1_SA_DQ<9>")
	)
	(arc
		(start 141.197838 -231.036876)
		(mid 141.384782 -231.087165)
		(end 141.571726 -231.036876)
		(width 0.0889)
		(layer "In4.Cu")
		(net "M_J_CPU1_SA_DQ<9>")
	)
	(arc
		(start 143.086074 -231.041702)
		(mid 143.269582 -231.087227)
		(end 143.451834 -231.036876)
		(width 0.0889)
		(layer "In4.Cu")
		(net "M_J_CPU1_SA_DQ<9>")
	)
	(arc
		(start 140.631926 -231.036876)
		(mid 140.914882 -230.960699)
		(end 141.197838 -231.036876)
		(width 0.0889)
		(layer "In4.Cu")
		(net "M_J_CPU1_SA_DQ<9>")
	)
	(arc
		(start 140.266166 -231.041702)
		(mid 140.449674 -231.087227)
		(end 140.631926 -231.036876)
		(width 0.0889)
		(layer "In4.Cu")
		(net "M_J_CPU1_SA_DQ<9>")
	)
	(arc
		(start 139.326112 -231.041702)
		(mid 139.50962 -231.087227)
		(end 139.691872 -231.036876)
		(width 0.0889)
		(layer "In4.Cu")
		(net "M_J_CPU1_SA_DQ<9>")
	)
	(arc
		(start 138.377676 -231.036876)
		(mid 138.559927 -231.08726)
		(end 138.743436 -231.041702)
		(width 0.0889)
		(layer "In4.Cu")
		(net "M_J_CPU1_SA_DQ<9>")
	)
	(arc
		(start 136.497822 -231.036876)
		(mid 136.684766 -231.087165)
		(end 136.87171 -231.036876)
		(width 0.0889)
		(layer "In4.Cu")
		(net "M_J_CPU1_SA_DQ<9>")
	)
	(arc
		(start 139.691872 -231.036876)
		(mid 139.974828 -230.960699)
		(end 140.257784 -231.036876)
		(width 0.0889)
		(layer "In4.Cu")
		(net "M_J_CPU1_SA_DQ<9>")
	)
	(segment
		(start 131.987798 -230.170228)
		(end 132.45465 -229.90429)
		(width 0.10668)
		(layer "F.Cu")
		(net "M_J_CPU1_SA_DQ<8>")
	)
	(segment
		(start 133.20776 -230.22687)
		(end 133.216142 -230.231696)
		(width 0.0889)
		(layer "In4.Cu")
		(net "M_J_CPU1_SA_DQ<8>")
	)
	(segment
		(start 182.07736 -206.260446)
		(end 189.023752 -206.260446)
		(width 0.14478)
		(layer "In4.Cu")
		(net "M_J_CPU1_SA_DQ<8>")
	)
	(segment
		(start 146.971766 -225.14433)
		(end 146.971766 -224.71507)
		(width 0.0889)
		(layer "In4.Cu")
		(net "M_J_CPU1_SA_DQ<8>")
	)
	(segment
		(start 146.971766 -224.71507)
		(end 147.739354 -223.947482)
		(width 0.0889)
		(layer "In4.Cu")
		(net "M_J_CPU1_SA_DQ<8>")
	)
	(segment
		(start 143.73479 -229.332536)
		(end 144.32788 -228.739446)
		(width 0.0889)
		(layer "In4.Cu")
		(net "M_J_CPU1_SA_DQ<8>")
	)
	(segment
		(start 170.626786 -207.11033)
		(end 173.684946 -207.11033)
		(width 0.14478)
		(layer "In4.Cu")
		(net "M_J_CPU1_SA_DQ<8>")
	)
	(segment
		(start 181.227476 -207.11033)
		(end 182.07736 -206.260446)
		(width 0.14478)
		(layer "In4.Cu")
		(net "M_J_CPU1_SA_DQ<8>")
	)
	(segment
		(start 166.17442 -207.11033)
		(end 167.024304 -206.260446)
		(width 0.14478)
		(layer "In4.Cu")
		(net "M_J_CPU1_SA_DQ<8>")
	)
	(segment
		(start 147.739354 -220.179646)
		(end 157.004766 -210.914234)
		(width 0.14478)
		(layer "In4.Cu")
		(net "M_J_CPU1_SA_DQ<8>")
	)
	(segment
		(start 178.62169 -207.11033)
		(end 181.227476 -207.11033)
		(width 0.14478)
		(layer "In4.Cu")
		(net "M_J_CPU1_SA_DQ<8>")
	)
	(segment
		(start 137.907776 -230.22687)
		(end 137.916158 -230.231696)
		(width 0.0889)
		(layer "In4.Cu")
		(net "M_J_CPU1_SA_DQ<8>")
	)
	(segment
		(start 132.608828 -230.16972)
		(end 132.705094 -230.19512)
		(width 0.0889)
		(layer "In4.Cu")
		(net "M_J_CPU1_SA_DQ<8>")
	)
	(segment
		(start 161.623502 -207.11033)
		(end 166.17442 -207.11033)
		(width 0.14478)
		(layer "In4.Cu")
		(net "M_J_CPU1_SA_DQ<8>")
	)
	(segment
		(start 136.393428 -230.231696)
		(end 136.40181 -230.22687)
		(width 0.0889)
		(layer "In4.Cu")
		(net "M_J_CPU1_SA_DQ<8>")
	)
	(segment
		(start 189.023752 -206.260446)
		(end 191.160146 -206.685388)
		(width 0.14478)
		(layer "In4.Cu")
		(net "M_J_CPU1_SA_DQ<8>")
	)
	(segment
		(start 174.53483 -206.260446)
		(end 177.771806 -206.260446)
		(width 0.14478)
		(layer "In4.Cu")
		(net "M_J_CPU1_SA_DQ<8>")
	)
	(segment
		(start 177.771806 -206.260446)
		(end 178.62169 -207.11033)
		(width 0.14478)
		(layer "In4.Cu")
		(net "M_J_CPU1_SA_DQ<8>")
	)
	(segment
		(start 144.32788 -227.788216)
		(end 146.971766 -225.14433)
		(width 0.0889)
		(layer "In4.Cu")
		(net "M_J_CPU1_SA_DQ<8>")
	)
	(segment
		(start 143.73479 -229.338886)
		(end 143.73479 -229.332536)
		(width 0.0889)
		(layer "In4.Cu")
		(net "M_J_CPU1_SA_DQ<8>")
	)
	(segment
		(start 142.98168 -230.22687)
		(end 143.01343 -230.208582)
		(width 0.0889)
		(layer "In4.Cu")
		(net "M_J_CPU1_SA_DQ<8>")
	)
	(segment
		(start 157.004766 -210.914234)
		(end 157.819598 -210.914234)
		(width 0.14478)
		(layer "In4.Cu")
		(net "M_J_CPU1_SA_DQ<8>")
	)
	(segment
		(start 144.32788 -228.739446)
		(end 144.32788 -227.788216)
		(width 0.0889)
		(layer "In4.Cu")
		(net "M_J_CPU1_SA_DQ<8>")
	)
	(segment
		(start 173.684946 -207.11033)
		(end 174.53483 -206.260446)
		(width 0.14478)
		(layer "In4.Cu")
		(net "M_J_CPU1_SA_DQ<8>")
	)
	(segment
		(start 136.967722 -230.22687)
		(end 136.976104 -230.231696)
		(width 0.0889)
		(layer "In4.Cu")
		(net "M_J_CPU1_SA_DQ<8>")
	)
	(segment
		(start 141.093444 -230.231696)
		(end 141.101826 -230.22687)
		(width 0.0889)
		(layer "In4.Cu")
		(net "M_J_CPU1_SA_DQ<8>")
	)
	(segment
		(start 157.819598 -210.914234)
		(end 161.623502 -207.11033)
		(width 0.14478)
		(layer "In4.Cu")
		(net "M_J_CPU1_SA_DQ<8>")
	)
	(segment
		(start 169.776902 -206.260446)
		(end 170.626786 -207.11033)
		(width 0.14478)
		(layer "In4.Cu")
		(net "M_J_CPU1_SA_DQ<8>")
	)
	(segment
		(start 167.024304 -206.260446)
		(end 169.776902 -206.260446)
		(width 0.14478)
		(layer "In4.Cu")
		(net "M_J_CPU1_SA_DQ<8>")
	)
	(segment
		(start 140.15339 -230.231696)
		(end 140.161772 -230.22687)
		(width 0.0889)
		(layer "In4.Cu")
		(net "M_J_CPU1_SA_DQ<8>")
	)
	(segment
		(start 132.45465 -229.90429)
		(end 132.608828 -230.16972)
		(width 0.0889)
		(layer "In4.Cu")
		(net "M_J_CPU1_SA_DQ<8>")
	)
	(segment
		(start 141.667738 -230.22687)
		(end 141.67612 -230.231696)
		(width 0.0889)
		(layer "In4.Cu")
		(net "M_J_CPU1_SA_DQ<8>")
	)
	(segment
		(start 147.739354 -223.947482)
		(end 147.739354 -220.179646)
		(width 0.14478)
		(layer "In4.Cu")
		(net "M_J_CPU1_SA_DQ<8>")
	)
	(segment
		(start 135.453374 -230.231696)
		(end 135.461756 -230.22687)
		(width 0.0889)
		(layer "In4.Cu")
		(net "M_J_CPU1_SA_DQ<8>")
	)
	(arc
		(start 134.147814 -230.22687)
		(mid 134.334758 -230.277125)
		(end 134.521702 -230.22687)
		(width 0.0889)
		(layer "In4.Cu")
		(net "M_J_CPU1_SA_DQ<8>")
	)
	(arc
		(start 136.40181 -230.22687)
		(mid 136.684766 -230.150727)
		(end 136.967722 -230.22687)
		(width 0.0889)
		(layer "In4.Cu")
		(net "M_J_CPU1_SA_DQ<8>")
	)
	(arc
		(start 134.521702 -230.22687)
		(mid 134.804658 -230.150727)
		(end 135.087614 -230.22687)
		(width 0.0889)
		(layer "In4.Cu")
		(net "M_J_CPU1_SA_DQ<8>")
	)
	(arc
		(start 137.341864 -230.22687)
		(mid 137.62482 -230.150727)
		(end 137.907776 -230.22687)
		(width 0.0889)
		(layer "In4.Cu")
		(net "M_J_CPU1_SA_DQ<8>")
	)
	(arc
		(start 143.169386 -229.90429)
		(mid 143.233901 -229.642071)
		(end 143.412718 -229.439724)
		(width 0.0889)
		(layer "In4.Cu")
		(net "M_J_CPU1_SA_DQ<8>")
	)
	(arc
		(start 135.087614 -230.22687)
		(mid 135.269865 -230.27722)
		(end 135.453374 -230.231696)
		(width 0.0889)
		(layer "In4.Cu")
		(net "M_J_CPU1_SA_DQ<8>")
	)
	(arc
		(start 136.027668 -230.22687)
		(mid 136.209919 -230.27722)
		(end 136.393428 -230.231696)
		(width 0.0889)
		(layer "In4.Cu")
		(net "M_J_CPU1_SA_DQ<8>")
	)
	(arc
		(start 141.101826 -230.22687)
		(mid 141.384782 -230.150727)
		(end 141.667738 -230.22687)
		(width 0.0889)
		(layer "In4.Cu")
		(net "M_J_CPU1_SA_DQ<8>")
	)
	(arc
		(start 140.727684 -230.22687)
		(mid 140.909935 -230.27722)
		(end 141.093444 -230.231696)
		(width 0.0889)
		(layer "In4.Cu")
		(net "M_J_CPU1_SA_DQ<8>")
	)
	(arc
		(start 136.976104 -230.231696)
		(mid 137.159612 -230.27719)
		(end 137.341864 -230.22687)
		(width 0.0889)
		(layer "In4.Cu")
		(net "M_J_CPU1_SA_DQ<8>")
	)
	(arc
		(start 133.216142 -230.231696)
		(mid 133.39965 -230.27719)
		(end 133.581902 -230.22687)
		(width 0.0889)
		(layer "In4.Cu")
		(net "M_J_CPU1_SA_DQ<8>")
	)
	(arc
		(start 132.705094 -230.19512)
		(mid 132.960159 -230.151789)
		(end 133.20776 -230.22687)
		(width 0.0889)
		(layer "In4.Cu")
		(net "M_J_CPU1_SA_DQ<8>")
	)
	(arc
		(start 143.01343 -230.208582)
		(mid 143.128106 -230.075248)
		(end 143.169386 -229.90429)
		(width 0.0889)
		(layer "In4.Cu")
		(net "M_J_CPU1_SA_DQ<8>")
	)
	(arc
		(start 133.581902 -230.22687)
		(mid 133.864858 -230.150727)
		(end 134.147814 -230.22687)
		(width 0.0889)
		(layer "In4.Cu")
		(net "M_J_CPU1_SA_DQ<8>")
	)
	(arc
		(start 138.84783 -230.22687)
		(mid 139.034774 -230.277125)
		(end 139.221718 -230.22687)
		(width 0.0889)
		(layer "In4.Cu")
		(net "M_J_CPU1_SA_DQ<8>")
	)
	(arc
		(start 140.161772 -230.22687)
		(mid 140.444728 -230.150727)
		(end 140.727684 -230.22687)
		(width 0.0889)
		(layer "In4.Cu")
		(net "M_J_CPU1_SA_DQ<8>")
	)
	(arc
		(start 142.04188 -230.22687)
		(mid 142.324836 -230.150727)
		(end 142.607792 -230.22687)
		(width 0.0889)
		(layer "In4.Cu")
		(net "M_J_CPU1_SA_DQ<8>")
	)
	(arc
		(start 137.916158 -230.231696)
		(mid 138.099666 -230.27719)
		(end 138.281918 -230.22687)
		(width 0.0889)
		(layer "In4.Cu")
		(net "M_J_CPU1_SA_DQ<8>")
	)
	(arc
		(start 138.281918 -230.22687)
		(mid 138.564874 -230.150727)
		(end 138.84783 -230.22687)
		(width 0.0889)
		(layer "In4.Cu")
		(net "M_J_CPU1_SA_DQ<8>")
	)
	(arc
		(start 142.607792 -230.22687)
		(mid 142.794736 -230.277125)
		(end 142.98168 -230.22687)
		(width 0.0889)
		(layer "In4.Cu")
		(net "M_J_CPU1_SA_DQ<8>")
	)
	(arc
		(start 139.221718 -230.22687)
		(mid 139.504674 -230.150727)
		(end 139.78763 -230.22687)
		(width 0.0889)
		(layer "In4.Cu")
		(net "M_J_CPU1_SA_DQ<8>")
	)
	(arc
		(start 139.78763 -230.22687)
		(mid 139.969881 -230.27722)
		(end 140.15339 -230.231696)
		(width 0.0889)
		(layer "In4.Cu")
		(net "M_J_CPU1_SA_DQ<8>")
	)
	(arc
		(start 143.412718 -229.439724)
		(mid 143.566053 -229.3647)
		(end 143.73479 -229.338886)
		(width 0.0889)
		(layer "In4.Cu")
		(net "M_J_CPU1_SA_DQ<8>")
	)
	(arc
		(start 135.461756 -230.22687)
		(mid 135.744712 -230.150727)
		(end 136.027668 -230.22687)
		(width 0.0889)
		(layer "In4.Cu")
		(net "M_J_CPU1_SA_DQ<8>")
	)
	(arc
		(start 141.67612 -230.231696)
		(mid 141.859628 -230.27719)
		(end 142.04188 -230.22687)
		(width 0.0889)
		(layer "In4.Cu")
		(net "M_J_CPU1_SA_DQ<8>")
	)
	(segment
		(start 131.047998 -230.170228)
		(end 131.51485 -229.90429)
		(width 0.10668)
		(layer "F.Cu")
		(net "M_J_CPU1_SA_DQ<7>")
	)
	(segment
		(start 181.214522 -206.260446)
		(end 182.06466 -205.410308)
		(width 0.14478)
		(layer "In4.Cu")
		(net "M_J_CPU1_SA_DQ<7>")
	)
	(segment
		(start 158.021274 -209.890614)
		(end 158.021274 -209.662522)
		(width 0.14478)
		(layer "In4.Cu")
		(net "M_J_CPU1_SA_DQ<7>")
	)
	(segment
		(start 148.25853 -218.107514)
		(end 148.420582 -217.945462)
		(width 0.14478)
		(layer "In4.Cu")
		(net "M_J_CPU1_SA_DQ<7>")
	)
	(segment
		(start 158.64332 -208.495646)
		(end 158.805372 -208.333594)
		(width 0.14478)
		(layer "In4.Cu")
		(net "M_J_CPU1_SA_DQ<7>")
	)
	(segment
		(start 148.25472 -218.884246)
		(end 148.416772 -218.722194)
		(width 0.14478)
		(layer "In4.Cu")
		(net "M_J_CPU1_SA_DQ<7>")
	)
	(segment
		(start 147.478242 -219.116148)
		(end 147.478242 -218.887802)
		(width 0.14478)
		(layer "In4.Cu")
		(net "M_J_CPU1_SA_DQ<7>")
	)
	(segment
		(start 131.693412 -229.577138)
		(end 131.701794 -229.581964)
		(width 0.0889)
		(layer "In4.Cu")
		(net "M_J_CPU1_SA_DQ<7>")
	)
	(segment
		(start 141.667738 -229.581964)
		(end 141.67612 -229.577138)
		(width 0.0889)
		(layer "In4.Cu")
		(net "M_J_CPU1_SA_DQ<7>")
	)
	(segment
		(start 143.811752 -227.91166)
		(end 145.647664 -226.075748)
		(width 0.0889)
		(layer "In4.Cu")
		(net "M_J_CPU1_SA_DQ<7>")
	)
	(segment
		(start 185.37428 -205.410308)
		(end 185.682382 -205.102206)
		(width 0.14478)
		(layer "In4.Cu")
		(net "M_J_CPU1_SA_DQ<7>")
	)
	(segment
		(start 147.868386 -218.72575)
		(end 148.026628 -218.884246)
		(width 0.14478)
		(layer "In4.Cu")
		(net "M_J_CPU1_SA_DQ<7>")
	)
	(segment
		(start 157.63113 -210.052666)
		(end 157.859222 -210.052666)
		(width 0.14478)
		(layer "In4.Cu")
		(net "M_J_CPU1_SA_DQ<7>")
	)
	(segment
		(start 184.271412 -205.410308)
		(end 184.579514 -205.102206)
		(width 0.14478)
		(layer "In4.Cu")
		(net "M_J_CPU1_SA_DQ<7>")
	)
	(segment
		(start 148.648674 -217.945462)
		(end 148.806916 -218.103958)
		(width 0.14478)
		(layer "In4.Cu")
		(net "M_J_CPU1_SA_DQ<7>")
	)
	(segment
		(start 143.077692 -228.771958)
		(end 143.116808 -228.749098)
		(width 0.0889)
		(layer "In4.Cu")
		(net "M_J_CPU1_SA_DQ<7>")
	)
	(segment
		(start 157.472888 -209.89417)
		(end 157.63113 -210.052666)
		(width 0.14478)
		(layer "In4.Cu")
		(net "M_J_CPU1_SA_DQ<7>")
	)
	(segment
		(start 184.579514 -205.102206)
		(end 184.822846 -205.102206)
		(width 0.14478)
		(layer "In4.Cu")
		(net "M_J_CPU1_SA_DQ<7>")
	)
	(segment
		(start 159.58185 -208.101946)
		(end 159.423608 -207.943704)
		(width 0.14478)
		(layer "In4.Cu")
		(net "M_J_CPU1_SA_DQ<7>")
	)
	(segment
		(start 132.267706 -229.581964)
		(end 132.276088 -229.577138)
		(width 0.0889)
		(layer "In4.Cu")
		(net "M_J_CPU1_SA_DQ<7>")
	)
	(segment
		(start 147.188174 -222.544894)
		(end 147.188174 -219.950792)
		(width 0.14478)
		(layer "In4.Cu")
		(net "M_J_CPU1_SA_DQ<7>")
	)
	(segment
		(start 184.822846 -205.102206)
		(end 185.130948 -205.410308)
		(width 0.14478)
		(layer "In4.Cu")
		(net "M_J_CPU1_SA_DQ<7>")
	)
	(segment
		(start 159.423608 -207.943704)
		(end 159.423608 -207.715358)
		(width 0.14478)
		(layer "In4.Cu")
		(net "M_J_CPU1_SA_DQ<7>")
	)
	(segment
		(start 157.863032 -209.50428)
		(end 157.863032 -209.275934)
		(width 0.14478)
		(layer "In4.Cu")
		(net "M_J_CPU1_SA_DQ<7>")
	)
	(segment
		(start 159.423608 -207.715358)
		(end 159.58566 -207.553306)
		(width 0.14478)
		(layer "In4.Cu")
		(net "M_J_CPU1_SA_DQ<7>")
	)
	(segment
		(start 160.362138 -207.321658)
		(end 160.203896 -207.163416)
		(width 0.14478)
		(layer "In4.Cu")
		(net "M_J_CPU1_SA_DQ<7>")
	)
	(segment
		(start 149.428962 -217.165174)
		(end 149.587204 -217.32367)
		(width 0.14478)
		(layer "In4.Cu")
		(net "M_J_CPU1_SA_DQ<7>")
	)
	(segment
		(start 158.805372 -208.333594)
		(end 159.033464 -208.333594)
		(width 0.14478)
		(layer "In4.Cu")
		(net "M_J_CPU1_SA_DQ<7>")
	)
	(segment
		(start 170.611038 -206.260446)
		(end 173.662594 -206.260446)
		(width 0.14478)
		(layer "In4.Cu")
		(net "M_J_CPU1_SA_DQ<7>")
	)
	(segment
		(start 159.191706 -208.49209)
		(end 159.419798 -208.49209)
		(width 0.14478)
		(layer "In4.Cu")
		(net "M_J_CPU1_SA_DQ<7>")
	)
	(segment
		(start 159.58185 -208.330038)
		(end 159.58185 -208.101946)
		(width 0.14478)
		(layer "In4.Cu")
		(net "M_J_CPU1_SA_DQ<7>")
	)
	(segment
		(start 131.51485 -229.90429)
		(end 131.360672 -229.63886)
		(width 0.0889)
		(layer "In4.Cu")
		(net "M_J_CPU1_SA_DQ<7>")
	)
	(segment
		(start 148.420582 -217.945462)
		(end 148.648674 -217.945462)
		(width 0.14478)
		(layer "In4.Cu")
		(net "M_J_CPU1_SA_DQ<7>")
	)
	(segment
		(start 158.253176 -209.113882)
		(end 158.411418 -209.272378)
		(width 0.14478)
		(layer "In4.Cu")
		(net "M_J_CPU1_SA_DQ<7>")
	)
	(segment
		(start 148.416772 -218.494102)
		(end 148.25853 -218.33586)
		(width 0.14478)
		(layer "In4.Cu")
		(net "M_J_CPU1_SA_DQ<7>")
	)
	(segment
		(start 158.801562 -209.110326)
		(end 158.801562 -208.882234)
		(width 0.14478)
		(layer "In4.Cu")
		(net "M_J_CPU1_SA_DQ<7>")
	)
	(segment
		(start 159.813752 -207.553306)
		(end 159.971994 -207.711802)
		(width 0.14478)
		(layer "In4.Cu")
		(net "M_J_CPU1_SA_DQ<7>")
	)
	(segment
		(start 157.244796 -209.89417)
		(end 157.472888 -209.89417)
		(width 0.14478)
		(layer "In4.Cu")
		(net "M_J_CPU1_SA_DQ<7>")
	)
	(segment
		(start 160.200086 -207.711802)
		(end 160.362138 -207.54975)
		(width 0.14478)
		(layer "In4.Cu")
		(net "M_J_CPU1_SA_DQ<7>")
	)
	(segment
		(start 169.7609 -205.410308)
		(end 170.611038 -206.260446)
		(width 0.14478)
		(layer "In4.Cu")
		(net "M_J_CPU1_SA_DQ<7>")
	)
	(segment
		(start 145.647664 -226.075748)
		(end 145.647664 -225.194368)
		(width 0.0889)
		(layer "In4.Cu")
		(net "M_J_CPU1_SA_DQ<7>")
	)
	(segment
		(start 158.801562 -208.882234)
		(end 158.64332 -208.723992)
		(width 0.14478)
		(layer "In4.Cu")
		(net "M_J_CPU1_SA_DQ<7>")
	)
	(segment
		(start 140.15339 -229.577138)
		(end 140.161772 -229.581964)
		(width 0.0889)
		(layer "In4.Cu")
		(net "M_J_CPU1_SA_DQ<7>")
	)
	(segment
		(start 157.863032 -209.275934)
		(end 158.025084 -209.113882)
		(width 0.14478)
		(layer "In4.Cu")
		(net "M_J_CPU1_SA_DQ<7>")
	)
	(segment
		(start 147.188174 -223.653858)
		(end 147.188174 -222.544894)
		(width 0.0889)
		(layer "In4.Cu")
		(net "M_J_CPU1_SA_DQ<7>")
	)
	(segment
		(start 186.233816 -205.410308)
		(end 186.635136 -205.410308)
		(width 0.14478)
		(layer "In4.Cu")
		(net "M_J_CPU1_SA_DQ<7>")
	)
	(segment
		(start 131.360672 -229.63886)
		(end 131.38277 -229.555802)
		(width 0.0889)
		(layer "In4.Cu")
		(net "M_J_CPU1_SA_DQ<7>")
	)
	(segment
		(start 158.411418 -209.272378)
		(end 158.63951 -209.272378)
		(width 0.14478)
		(layer "In4.Cu")
		(net "M_J_CPU1_SA_DQ<7>")
	)
	(segment
		(start 145.647664 -225.194368)
		(end 147.188174 -223.653858)
		(width 0.0889)
		(layer "In4.Cu")
		(net "M_J_CPU1_SA_DQ<7>")
	)
	(segment
		(start 166.065708 -206.260446)
		(end 166.915846 -205.410308)
		(width 0.14478)
		(layer "In4.Cu")
		(net "M_J_CPU1_SA_DQ<7>")
	)
	(segment
		(start 158.025084 -209.113882)
		(end 158.253176 -209.113882)
		(width 0.14478)
		(layer "In4.Cu")
		(net "M_J_CPU1_SA_DQ<7>")
	)
	(segment
		(start 158.021274 -209.662522)
		(end 157.863032 -209.50428)
		(width 0.14478)
		(layer "In4.Cu")
		(net "M_J_CPU1_SA_DQ<7>")
	)
	(segment
		(start 143.045942 -228.790246)
		(end 143.077692 -228.771958)
		(width 0.0889)
		(layer "In4.Cu")
		(net "M_J_CPU1_SA_DQ<7>")
	)
	(segment
		(start 147.188174 -219.950792)
		(end 147.636484 -219.502482)
		(width 0.14478)
		(layer "In4.Cu")
		(net "M_J_CPU1_SA_DQ<7>")
	)
	(segment
		(start 148.25853 -218.33586)
		(end 148.25853 -218.107514)
		(width 0.14478)
		(layer "In4.Cu")
		(net "M_J_CPU1_SA_DQ<7>")
	)
	(segment
		(start 148.416772 -218.722194)
		(end 148.416772 -218.494102)
		(width 0.14478)
		(layer "In4.Cu")
		(net "M_J_CPU1_SA_DQ<7>")
	)
	(segment
		(start 149.038818 -217.327226)
		(end 149.20087 -217.165174)
		(width 0.14478)
		(layer "In4.Cu")
		(net "M_J_CPU1_SA_DQ<7>")
	)
	(segment
		(start 160.203896 -207.163416)
		(end 160.203896 -206.93507)
		(width 0.14478)
		(layer "In4.Cu")
		(net "M_J_CPU1_SA_DQ<7>")
	)
	(segment
		(start 149.19706 -217.713814)
		(end 149.038818 -217.555572)
		(width 0.14478)
		(layer "In4.Cu")
		(net "M_J_CPU1_SA_DQ<7>")
	)
	(segment
		(start 182.06466 -205.410308)
		(end 184.271412 -205.410308)
		(width 0.14478)
		(layer "In4.Cu")
		(net "M_J_CPU1_SA_DQ<7>")
	)
	(segment
		(start 177.731166 -205.410308)
		(end 178.581304 -206.260446)
		(width 0.14478)
		(layer "In4.Cu")
		(net "M_J_CPU1_SA_DQ<7>")
	)
	(segment
		(start 159.033464 -208.333594)
		(end 159.191706 -208.49209)
		(width 0.14478)
		(layer "In4.Cu")
		(net "M_J_CPU1_SA_DQ<7>")
	)
	(segment
		(start 158.64332 -208.723992)
		(end 158.64332 -208.495646)
		(width 0.14478)
		(layer "In4.Cu")
		(net "M_J_CPU1_SA_DQ<7>")
	)
	(segment
		(start 136.393428 -229.577138)
		(end 136.40181 -229.581964)
		(width 0.0889)
		(layer "In4.Cu")
		(net "M_J_CPU1_SA_DQ<7>")
	)
	(segment
		(start 133.20776 -229.581964)
		(end 133.216142 -229.577138)
		(width 0.0889)
		(layer "In4.Cu")
		(net "M_J_CPU1_SA_DQ<7>")
	)
	(segment
		(start 186.635136 -205.410308)
		(end 187.060078 -205.83525)
		(width 0.14478)
		(layer "In4.Cu")
		(net "M_J_CPU1_SA_DQ<7>")
	)
	(segment
		(start 149.19706 -217.941906)
		(end 149.19706 -217.713814)
		(width 0.14478)
		(layer "In4.Cu")
		(net "M_J_CPU1_SA_DQ<7>")
	)
	(segment
		(start 185.130948 -205.410308)
		(end 185.37428 -205.410308)
		(width 0.14478)
		(layer "In4.Cu")
		(net "M_J_CPU1_SA_DQ<7>")
	)
	(segment
		(start 142.607792 -229.581964)
		(end 142.644114 -229.560882)
		(width 0.0889)
		(layer "In4.Cu")
		(net "M_J_CPU1_SA_DQ<7>")
	)
	(segment
		(start 147.636484 -219.502482)
		(end 147.636484 -219.27439)
		(width 0.14478)
		(layer "In4.Cu")
		(net "M_J_CPU1_SA_DQ<7>")
	)
	(segment
		(start 135.453374 -229.577138)
		(end 135.461756 -229.581964)
		(width 0.0889)
		(layer "In4.Cu")
		(net "M_J_CPU1_SA_DQ<7>")
	)
	(segment
		(start 149.035008 -218.103958)
		(end 149.19706 -217.941906)
		(width 0.14478)
		(layer "In4.Cu")
		(net "M_J_CPU1_SA_DQ<7>")
	)
	(segment
		(start 185.682382 -205.102206)
		(end 185.925714 -205.102206)
		(width 0.14478)
		(layer "In4.Cu")
		(net "M_J_CPU1_SA_DQ<7>")
	)
	(segment
		(start 149.20087 -217.165174)
		(end 149.428962 -217.165174)
		(width 0.14478)
		(layer "In4.Cu")
		(net "M_J_CPU1_SA_DQ<7>")
	)
	(segment
		(start 159.419798 -208.49209)
		(end 159.58185 -208.330038)
		(width 0.14478)
		(layer "In4.Cu")
		(net "M_J_CPU1_SA_DQ<7>")
	)
	(segment
		(start 147.640294 -218.72575)
		(end 147.868386 -218.72575)
		(width 0.14478)
		(layer "In4.Cu")
		(net "M_J_CPU1_SA_DQ<7>")
	)
	(segment
		(start 137.907776 -229.581964)
		(end 137.916158 -229.577138)
		(width 0.0889)
		(layer "In4.Cu")
		(net "M_J_CPU1_SA_DQ<7>")
	)
	(segment
		(start 160.362138 -207.54975)
		(end 160.362138 -207.321658)
		(width 0.14478)
		(layer "In4.Cu")
		(net "M_J_CPU1_SA_DQ<7>")
	)
	(segment
		(start 143.73479 -227.91166)
		(end 143.811752 -227.91166)
		(width 0.0889)
		(layer "In4.Cu")
		(net "M_J_CPU1_SA_DQ<7>")
	)
	(segment
		(start 160.203896 -206.93507)
		(end 160.87852 -206.260446)
		(width 0.14478)
		(layer "In4.Cu")
		(net "M_J_CPU1_SA_DQ<7>")
	)
	(segment
		(start 149.038818 -217.555572)
		(end 149.038818 -217.327226)
		(width 0.14478)
		(layer "In4.Cu")
		(net "M_J_CPU1_SA_DQ<7>")
	)
	(segment
		(start 173.662594 -206.260446)
		(end 174.512732 -205.410308)
		(width 0.14478)
		(layer "In4.Cu")
		(net "M_J_CPU1_SA_DQ<7>")
	)
	(segment
		(start 147.636484 -219.27439)
		(end 147.478242 -219.116148)
		(width 0.14478)
		(layer "In4.Cu")
		(net "M_J_CPU1_SA_DQ<7>")
	)
	(segment
		(start 166.915846 -205.410308)
		(end 169.7609 -205.410308)
		(width 0.14478)
		(layer "In4.Cu")
		(net "M_J_CPU1_SA_DQ<7>")
	)
	(segment
		(start 148.026628 -218.884246)
		(end 148.25472 -218.884246)
		(width 0.14478)
		(layer "In4.Cu")
		(net "M_J_CPU1_SA_DQ<7>")
	)
	(segment
		(start 149.815296 -217.32367)
		(end 157.244796 -209.89417)
		(width 0.14478)
		(layer "In4.Cu")
		(net "M_J_CPU1_SA_DQ<7>")
	)
	(segment
		(start 148.806916 -218.103958)
		(end 149.035008 -218.103958)
		(width 0.14478)
		(layer "In4.Cu")
		(net "M_J_CPU1_SA_DQ<7>")
	)
	(segment
		(start 149.587204 -217.32367)
		(end 149.815296 -217.32367)
		(width 0.14478)
		(layer "In4.Cu")
		(net "M_J_CPU1_SA_DQ<7>")
	)
	(segment
		(start 158.63951 -209.272378)
		(end 158.801562 -209.110326)
		(width 0.14478)
		(layer "In4.Cu")
		(net "M_J_CPU1_SA_DQ<7>")
	)
	(segment
		(start 159.971994 -207.711802)
		(end 160.200086 -207.711802)
		(width 0.14478)
		(layer "In4.Cu")
		(net "M_J_CPU1_SA_DQ<7>")
	)
	(segment
		(start 185.925714 -205.102206)
		(end 186.233816 -205.410308)
		(width 0.14478)
		(layer "In4.Cu")
		(net "M_J_CPU1_SA_DQ<7>")
	)
	(segment
		(start 143.517112 -227.979732)
		(end 143.547592 -227.961952)
		(width 0.0889)
		(layer "In4.Cu")
		(net "M_J_CPU1_SA_DQ<7>")
	)
	(segment
		(start 141.093444 -229.577138)
		(end 141.101826 -229.581964)
		(width 0.0889)
		(layer "In4.Cu")
		(net "M_J_CPU1_SA_DQ<7>")
	)
	(segment
		(start 159.58566 -207.553306)
		(end 159.813752 -207.553306)
		(width 0.14478)
		(layer "In4.Cu")
		(net "M_J_CPU1_SA_DQ<7>")
	)
	(segment
		(start 147.478242 -218.887802)
		(end 147.640294 -218.72575)
		(width 0.14478)
		(layer "In4.Cu")
		(net "M_J_CPU1_SA_DQ<7>")
	)
	(segment
		(start 157.859222 -210.052666)
		(end 158.021274 -209.890614)
		(width 0.14478)
		(layer "In4.Cu")
		(net "M_J_CPU1_SA_DQ<7>")
	)
	(segment
		(start 174.512732 -205.410308)
		(end 177.731166 -205.410308)
		(width 0.14478)
		(layer "In4.Cu")
		(net "M_J_CPU1_SA_DQ<7>")
	)
	(segment
		(start 136.967722 -229.581964)
		(end 136.976104 -229.577138)
		(width 0.0889)
		(layer "In4.Cu")
		(net "M_J_CPU1_SA_DQ<7>")
	)
	(segment
		(start 160.87852 -206.260446)
		(end 166.065708 -206.260446)
		(width 0.14478)
		(layer "In4.Cu")
		(net "M_J_CPU1_SA_DQ<7>")
	)
	(segment
		(start 178.581304 -206.260446)
		(end 181.214522 -206.260446)
		(width 0.14478)
		(layer "In4.Cu")
		(net "M_J_CPU1_SA_DQ<7>")
	)
	(arc
		(start 136.40181 -229.581964)
		(mid 136.684766 -229.658141)
		(end 136.967722 -229.581964)
		(width 0.0889)
		(layer "In4.Cu")
		(net "M_J_CPU1_SA_DQ<7>")
	)
	(arc
		(start 137.341864 -229.581964)
		(mid 137.62482 -229.658141)
		(end 137.907776 -229.581964)
		(width 0.0889)
		(layer "In4.Cu")
		(net "M_J_CPU1_SA_DQ<7>")
	)
	(arc
		(start 143.36014 -228.284532)
		(mid 143.401689 -228.11311)
		(end 143.517112 -227.979732)
		(width 0.0889)
		(layer "In4.Cu")
		(net "M_J_CPU1_SA_DQ<7>")
	)
	(arc
		(start 139.221718 -229.581964)
		(mid 139.504674 -229.658141)
		(end 139.78763 -229.581964)
		(width 0.0889)
		(layer "In4.Cu")
		(net "M_J_CPU1_SA_DQ<7>")
	)
	(arc
		(start 138.84783 -229.581964)
		(mid 139.034774 -229.531675)
		(end 139.221718 -229.581964)
		(width 0.0889)
		(layer "In4.Cu")
		(net "M_J_CPU1_SA_DQ<7>")
	)
	(arc
		(start 143.547592 -227.961952)
		(mid 143.637868 -227.924447)
		(end 143.73479 -227.91166)
		(width 0.0889)
		(layer "In4.Cu")
		(net "M_J_CPU1_SA_DQ<7>")
	)
	(arc
		(start 143.116808 -228.749098)
		(mid 143.295621 -228.546748)
		(end 143.36014 -228.284532)
		(width 0.0889)
		(layer "In4.Cu")
		(net "M_J_CPU1_SA_DQ<7>")
	)
	(arc
		(start 140.727684 -229.581964)
		(mid 140.909935 -229.53158)
		(end 141.093444 -229.577138)
		(width 0.0889)
		(layer "In4.Cu")
		(net "M_J_CPU1_SA_DQ<7>")
	)
	(arc
		(start 135.461756 -229.581964)
		(mid 135.744712 -229.658141)
		(end 136.027668 -229.581964)
		(width 0.0889)
		(layer "In4.Cu")
		(net "M_J_CPU1_SA_DQ<7>")
	)
	(arc
		(start 142.04188 -229.581964)
		(mid 142.324836 -229.658141)
		(end 142.607792 -229.581964)
		(width 0.0889)
		(layer "In4.Cu")
		(net "M_J_CPU1_SA_DQ<7>")
	)
	(arc
		(start 132.641848 -229.581964)
		(mid 132.924804 -229.658141)
		(end 133.20776 -229.581964)
		(width 0.0889)
		(layer "In4.Cu")
		(net "M_J_CPU1_SA_DQ<7>")
	)
	(arc
		(start 138.281918 -229.581964)
		(mid 138.564874 -229.658141)
		(end 138.84783 -229.581964)
		(width 0.0889)
		(layer "In4.Cu")
		(net "M_J_CPU1_SA_DQ<7>")
	)
	(arc
		(start 135.087614 -229.581964)
		(mid 135.269865 -229.53158)
		(end 135.453374 -229.577138)
		(width 0.0889)
		(layer "In4.Cu")
		(net "M_J_CPU1_SA_DQ<7>")
	)
	(arc
		(start 134.521702 -229.581964)
		(mid 134.804658 -229.658141)
		(end 135.087614 -229.581964)
		(width 0.0889)
		(layer "In4.Cu")
		(net "M_J_CPU1_SA_DQ<7>")
	)
	(arc
		(start 132.276088 -229.577138)
		(mid 132.459596 -229.531613)
		(end 132.641848 -229.581964)
		(width 0.0889)
		(layer "In4.Cu")
		(net "M_J_CPU1_SA_DQ<7>")
	)
	(arc
		(start 142.644114 -229.560882)
		(mid 142.824766 -229.358137)
		(end 142.889986 -229.094538)
		(width 0.0889)
		(layer "In4.Cu")
		(net "M_J_CPU1_SA_DQ<7>")
	)
	(arc
		(start 141.101826 -229.581964)
		(mid 141.384782 -229.658141)
		(end 141.667738 -229.581964)
		(width 0.0889)
		(layer "In4.Cu")
		(net "M_J_CPU1_SA_DQ<7>")
	)
	(arc
		(start 133.216142 -229.577138)
		(mid 133.39965 -229.531613)
		(end 133.581902 -229.581964)
		(width 0.0889)
		(layer "In4.Cu")
		(net "M_J_CPU1_SA_DQ<7>")
	)
	(arc
		(start 136.976104 -229.577138)
		(mid 137.159612 -229.531613)
		(end 137.341864 -229.581964)
		(width 0.0889)
		(layer "In4.Cu")
		(net "M_J_CPU1_SA_DQ<7>")
	)
	(arc
		(start 142.889986 -229.094538)
		(mid 142.931241 -228.923567)
		(end 143.045942 -228.790246)
		(width 0.0889)
		(layer "In4.Cu")
		(net "M_J_CPU1_SA_DQ<7>")
	)
	(arc
		(start 137.916158 -229.577138)
		(mid 138.099666 -229.531613)
		(end 138.281918 -229.581964)
		(width 0.0889)
		(layer "In4.Cu")
		(net "M_J_CPU1_SA_DQ<7>")
	)
	(arc
		(start 140.161772 -229.581964)
		(mid 140.444728 -229.658141)
		(end 140.727684 -229.581964)
		(width 0.0889)
		(layer "In4.Cu")
		(net "M_J_CPU1_SA_DQ<7>")
	)
	(arc
		(start 133.581902 -229.581964)
		(mid 133.864858 -229.658141)
		(end 134.147814 -229.581964)
		(width 0.0889)
		(layer "In4.Cu")
		(net "M_J_CPU1_SA_DQ<7>")
	)
	(arc
		(start 131.701794 -229.581964)
		(mid 131.98475 -229.658141)
		(end 132.267706 -229.581964)
		(width 0.0889)
		(layer "In4.Cu")
		(net "M_J_CPU1_SA_DQ<7>")
	)
	(arc
		(start 131.38277 -229.555802)
		(mid 131.540421 -229.53249)
		(end 131.693412 -229.577138)
		(width 0.0889)
		(layer "In4.Cu")
		(net "M_J_CPU1_SA_DQ<7>")
	)
	(arc
		(start 136.027668 -229.581964)
		(mid 136.209919 -229.53158)
		(end 136.393428 -229.577138)
		(width 0.0889)
		(layer "In4.Cu")
		(net "M_J_CPU1_SA_DQ<7>")
	)
	(arc
		(start 134.147814 -229.581964)
		(mid 134.334758 -229.531675)
		(end 134.521702 -229.581964)
		(width 0.0889)
		(layer "In4.Cu")
		(net "M_J_CPU1_SA_DQ<7>")
	)
	(arc
		(start 141.67612 -229.577138)
		(mid 141.859628 -229.531613)
		(end 142.04188 -229.581964)
		(width 0.0889)
		(layer "In4.Cu")
		(net "M_J_CPU1_SA_DQ<7>")
	)
	(arc
		(start 139.78763 -229.581964)
		(mid 139.969881 -229.53158)
		(end 140.15339 -229.577138)
		(width 0.0889)
		(layer "In4.Cu")
		(net "M_J_CPU1_SA_DQ<7>")
	)
	(segment
		(start 132.457952 -229.360476)
		(end 132.924804 -229.094538)
		(width 0.10668)
		(layer "F.Cu")
		(net "M_J_CPU1_SA_DQ<6>")
	)
	(segment
		(start 153.01087 -212.835998)
		(end 153.01087 -212.607906)
		(width 0.14478)
		(layer "In4.Cu")
		(net "M_J_CPU1_SA_DQ<6>")
	)
	(segment
		(start 149.122892 -215.970866)
		(end 149.350984 -215.970866)
		(width 0.14478)
		(layer "In4.Cu")
		(net "M_J_CPU1_SA_DQ<6>")
	)
	(segment
		(start 142.137638 -228.771958)
		(end 142.176754 -228.749098)
		(width 0.0889)
		(layer "In4.Cu")
		(net "M_J_CPU1_SA_DQ<6>")
	)
	(segment
		(start 132.924804 -229.094538)
		(end 132.770626 -228.829108)
		(width 0.0889)
		(layer "In4.Cu")
		(net "M_J_CPU1_SA_DQ<6>")
	)
	(segment
		(start 153.642568 -211.45119)
		(end 153.80462 -211.289138)
		(width 0.14478)
		(layer "In4.Cu")
		(net "M_J_CPU1_SA_DQ<6>")
	)
	(segment
		(start 149.889718 -215.729058)
		(end 149.741128 -215.580722)
		(width 0.14478)
		(layer "In4.Cu")
		(net "M_J_CPU1_SA_DQ<6>")
	)
	(segment
		(start 143.077692 -227.151946)
		(end 143.116808 -227.129086)
		(width 0.0889)
		(layer "In4.Cu")
		(net "M_J_CPU1_SA_DQ<6>")
	)
	(segment
		(start 152.230582 -213.616286)
		(end 152.230582 -213.388194)
		(width 0.14478)
		(layer "In4.Cu")
		(net "M_J_CPU1_SA_DQ<6>")
	)
	(segment
		(start 152.081992 -213.239858)
		(end 152.081992 -213.011766)
		(width 0.14478)
		(layer "In4.Cu")
		(net "M_J_CPU1_SA_DQ<6>")
	)
	(segment
		(start 181.391814 -204.560424)
		(end 182.241952 -203.710286)
		(width 0.14478)
		(layer "In4.Cu")
		(net "M_J_CPU1_SA_DQ<6>")
	)
	(segment
		(start 152.86228 -212.231478)
		(end 153.024332 -212.069426)
		(width 0.14478)
		(layer "In4.Cu")
		(net "M_J_CPU1_SA_DQ<6>")
	)
	(segment
		(start 153.024332 -212.069426)
		(end 153.252424 -212.069426)
		(width 0.14478)
		(layer "In4.Cu")
		(net "M_J_CPU1_SA_DQ<6>")
	)
	(segment
		(start 139.31773 -228.771958)
		(end 139.326112 -228.767132)
		(width 0.0889)
		(layer "In4.Cu")
		(net "M_J_CPU1_SA_DQ<6>")
	)
	(segment
		(start 154.422856 -210.898994)
		(end 154.422856 -210.670902)
		(width 0.14478)
		(layer "In4.Cu")
		(net "M_J_CPU1_SA_DQ<6>")
	)
	(segment
		(start 153.791158 -212.05571)
		(end 153.791158 -211.827618)
		(width 0.14478)
		(layer "In4.Cu")
		(net "M_J_CPU1_SA_DQ<6>")
	)
	(segment
		(start 152.06853 -213.778338)
		(end 152.230582 -213.616286)
		(width 0.14478)
		(layer "In4.Cu")
		(net "M_J_CPU1_SA_DQ<6>")
	)
	(segment
		(start 161.286444 -204.560424)
		(end 166.228014 -204.560424)
		(width 0.14478)
		(layer "In4.Cu")
		(net "M_J_CPU1_SA_DQ<6>")
	)
	(segment
		(start 144.92605 -223.93021)
		(end 144.9578 -223.911922)
		(width 0.0889)
		(layer "In4.Cu")
		(net "M_J_CPU1_SA_DQ<6>")
	)
	(segment
		(start 155.983432 -209.110326)
		(end 156.145484 -208.948274)
		(width 0.14478)
		(layer "In4.Cu")
		(net "M_J_CPU1_SA_DQ<6>")
	)
	(segment
		(start 155.96997 -209.876898)
		(end 156.132022 -209.714846)
		(width 0.14478)
		(layer "In4.Cu")
		(net "M_J_CPU1_SA_DQ<6>")
	)
	(segment
		(start 151.450294 -214.168482)
		(end 151.301704 -214.020146)
		(width 0.14478)
		(layer "In4.Cu")
		(net "M_J_CPU1_SA_DQ<6>")
	)
	(segment
		(start 166.228014 -204.560424)
		(end 167.078152 -203.710286)
		(width 0.14478)
		(layer "In4.Cu")
		(net "M_J_CPU1_SA_DQ<6>")
	)
	(segment
		(start 155.983432 -209.338418)
		(end 155.983432 -209.110326)
		(width 0.14478)
		(layer "In4.Cu")
		(net "M_J_CPU1_SA_DQ<6>")
	)
	(segment
		(start 146.289014 -218.804744)
		(end 149.122892 -215.970866)
		(width 0.14478)
		(layer "In4.Cu")
		(net "M_J_CPU1_SA_DQ<6>")
	)
	(segment
		(start 144.487646 -224.721928)
		(end 144.526762 -224.699068)
		(width 0.0889)
		(layer "In4.Cu")
		(net "M_J_CPU1_SA_DQ<6>")
	)
	(segment
		(start 152.472136 -212.849714)
		(end 152.620472 -212.99805)
		(width 0.14478)
		(layer "In4.Cu")
		(net "M_J_CPU1_SA_DQ<6>")
	)
	(segment
		(start 156.145484 -208.948274)
		(end 156.373576 -208.948274)
		(width 0.14478)
		(layer "In4.Cu")
		(net "M_J_CPU1_SA_DQ<6>")
	)
	(segment
		(start 146.289014 -222.085408)
		(end 146.289014 -218.804744)
		(width 0.14478)
		(layer "In4.Cu")
		(net "M_J_CPU1_SA_DQ<6>")
	)
	(segment
		(start 150.91156 -214.41029)
		(end 151.059896 -214.558626)
		(width 0.14478)
		(layer "In4.Cu")
		(net "M_J_CPU1_SA_DQ<6>")
	)
	(segment
		(start 152.230582 -213.388194)
		(end 152.081992 -213.239858)
		(width 0.14478)
		(layer "In4.Cu")
		(net "M_J_CPU1_SA_DQ<6>")
	)
	(segment
		(start 149.741128 -215.580722)
		(end 149.741128 -215.35263)
		(width 0.14478)
		(layer "In4.Cu")
		(net "M_J_CPU1_SA_DQ<6>")
	)
	(segment
		(start 146.289014 -222.355664)
		(end 146.289014 -222.085408)
		(width 0.0889)
		(layer "In4.Cu")
		(net "M_J_CPU1_SA_DQ<6>")
	)
	(segment
		(start 153.642568 -211.679282)
		(end 153.642568 -211.45119)
		(width 0.14478)
		(layer "In4.Cu")
		(net "M_J_CPU1_SA_DQ<6>")
	)
	(segment
		(start 143.517112 -226.35972)
		(end 143.547592 -226.34194)
		(width 0.0889)
		(layer "In4.Cu")
		(net "M_J_CPU1_SA_DQ<6>")
	)
	(segment
		(start 153.40076 -212.217762)
		(end 153.629106 -212.217762)
		(width 0.14478)
		(layer "In4.Cu")
		(net "M_J_CPU1_SA_DQ<6>")
	)
	(segment
		(start 154.571446 -211.275422)
		(end 154.571446 -211.04733)
		(width 0.14478)
		(layer "In4.Cu")
		(net "M_J_CPU1_SA_DQ<6>")
	)
	(segment
		(start 142.576042 -227.98024)
		(end 142.607792 -227.961952)
		(width 0.0889)
		(layer "In4.Cu")
		(net "M_J_CPU1_SA_DQ<6>")
	)
	(segment
		(start 151.301704 -213.792054)
		(end 151.463756 -213.630002)
		(width 0.14478)
		(layer "In4.Cu")
		(net "M_J_CPU1_SA_DQ<6>")
	)
	(segment
		(start 142.607792 -227.961952)
		(end 142.644114 -227.94087)
		(width 0.0889)
		(layer "In4.Cu")
		(net "M_J_CPU1_SA_DQ<6>")
	)
	(segment
		(start 149.889718 -215.95715)
		(end 149.889718 -215.729058)
		(width 0.14478)
		(layer "In4.Cu")
		(net "M_J_CPU1_SA_DQ<6>")
	)
	(segment
		(start 155.593288 -209.728562)
		(end 155.741624 -209.876898)
		(width 0.14478)
		(layer "In4.Cu")
		(net "M_J_CPU1_SA_DQ<6>")
	)
	(segment
		(start 155.351734 -210.495134)
		(end 155.351734 -210.267042)
		(width 0.14478)
		(layer "In4.Cu")
		(net "M_J_CPU1_SA_DQ<6>")
	)
	(segment
		(start 155.365196 -209.728562)
		(end 155.593288 -209.728562)
		(width 0.14478)
		(layer "In4.Cu")
		(net "M_J_CPU1_SA_DQ<6>")
	)
	(segment
		(start 167.078152 -203.710286)
		(end 169.588942 -203.710286)
		(width 0.14478)
		(layer "In4.Cu")
		(net "M_J_CPU1_SA_DQ<6>")
	)
	(segment
		(start 155.351734 -210.267042)
		(end 155.203144 -210.118706)
		(width 0.14478)
		(layer "In4.Cu")
		(net "M_J_CPU1_SA_DQ<6>")
	)
	(segment
		(start 154.422856 -210.670902)
		(end 154.584908 -210.50885)
		(width 0.14478)
		(layer "In4.Cu")
		(net "M_J_CPU1_SA_DQ<6>")
	)
	(segment
		(start 154.571446 -211.04733)
		(end 154.422856 -210.898994)
		(width 0.14478)
		(layer "In4.Cu")
		(net "M_J_CPU1_SA_DQ<6>")
	)
	(segment
		(start 132.770626 -228.829108)
		(end 132.792978 -228.745796)
		(width 0.0889)
		(layer "In4.Cu")
		(net "M_J_CPU1_SA_DQ<6>")
	)
	(segment
		(start 150.670006 -215.176862)
		(end 150.670006 -214.94877)
		(width 0.14478)
		(layer "In4.Cu")
		(net "M_J_CPU1_SA_DQ<6>")
	)
	(segment
		(start 151.059896 -214.558626)
		(end 151.288242 -214.558626)
		(width 0.14478)
		(layer "In4.Cu")
		(net "M_J_CPU1_SA_DQ<6>")
	)
	(segment
		(start 153.629106 -212.217762)
		(end 153.791158 -212.05571)
		(width 0.14478)
		(layer "In4.Cu")
		(net "M_J_CPU1_SA_DQ<6>")
	)
	(segment
		(start 177.49647 -203.710286)
		(end 178.346608 -204.560424)
		(width 0.14478)
		(layer "In4.Cu")
		(net "M_J_CPU1_SA_DQ<6>")
	)
	(segment
		(start 156.750258 -209.09661)
		(end 161.286444 -204.560424)
		(width 0.14478)
		(layer "In4.Cu")
		(net "M_J_CPU1_SA_DQ<6>")
	)
	(segment
		(start 152.86228 -212.45957)
		(end 152.86228 -212.231478)
		(width 0.14478)
		(layer "In4.Cu")
		(net "M_J_CPU1_SA_DQ<6>")
	)
	(segment
		(start 155.203144 -209.890614)
		(end 155.365196 -209.728562)
		(width 0.14478)
		(layer "In4.Cu")
		(net "M_J_CPU1_SA_DQ<6>")
	)
	(segment
		(start 150.683468 -214.41029)
		(end 150.91156 -214.41029)
		(width 0.14478)
		(layer "In4.Cu")
		(net "M_J_CPU1_SA_DQ<6>")
	)
	(segment
		(start 152.848818 -212.99805)
		(end 153.01087 -212.835998)
		(width 0.14478)
		(layer "In4.Cu")
		(net "M_J_CPU1_SA_DQ<6>")
	)
	(segment
		(start 154.813 -210.50885)
		(end 154.961336 -210.657186)
		(width 0.14478)
		(layer "In4.Cu")
		(net "M_J_CPU1_SA_DQ<6>")
	)
	(segment
		(start 144.017746 -225.531934)
		(end 144.056862 -225.509074)
		(width 0.0889)
		(layer "In4.Cu")
		(net "M_J_CPU1_SA_DQ<6>")
	)
	(segment
		(start 150.131272 -215.190578)
		(end 150.279608 -215.338914)
		(width 0.14478)
		(layer "In4.Cu")
		(net "M_J_CPU1_SA_DQ<6>")
	)
	(segment
		(start 154.584908 -210.50885)
		(end 154.813 -210.50885)
		(width 0.14478)
		(layer "In4.Cu")
		(net "M_J_CPU1_SA_DQ<6>")
	)
	(segment
		(start 149.90318 -215.190578)
		(end 150.131272 -215.190578)
		(width 0.14478)
		(layer "In4.Cu")
		(net "M_J_CPU1_SA_DQ<6>")
	)
	(segment
		(start 143.985996 -225.550222)
		(end 144.017746 -225.531934)
		(width 0.0889)
		(layer "In4.Cu")
		(net "M_J_CPU1_SA_DQ<6>")
	)
	(segment
		(start 149.727666 -216.119202)
		(end 149.889718 -215.95715)
		(width 0.14478)
		(layer "In4.Cu")
		(net "M_J_CPU1_SA_DQ<6>")
	)
	(segment
		(start 138.743436 -228.767132)
		(end 138.751818 -228.771958)
		(width 0.0889)
		(layer "In4.Cu")
		(net "M_J_CPU1_SA_DQ<6>")
	)
	(segment
		(start 170.43908 -204.560424)
		(end 173.496986 -204.560424)
		(width 0.14478)
		(layer "In4.Cu")
		(net "M_J_CPU1_SA_DQ<6>")
	)
	(segment
		(start 153.01087 -212.607906)
		(end 152.86228 -212.45957)
		(width 0.14478)
		(layer "In4.Cu")
		(net "M_J_CPU1_SA_DQ<6>")
	)
	(segment
		(start 145.684494 -222.960184)
		(end 146.289014 -222.355664)
		(width 0.0889)
		(layer "In4.Cu")
		(net "M_J_CPU1_SA_DQ<6>")
	)
	(segment
		(start 144.457166 -224.739708)
		(end 144.487646 -224.721928)
		(width 0.0889)
		(layer "In4.Cu")
		(net "M_J_CPU1_SA_DQ<6>")
	)
	(segment
		(start 150.507954 -215.338914)
		(end 150.670006 -215.176862)
		(width 0.14478)
		(layer "In4.Cu")
		(net "M_J_CPU1_SA_DQ<6>")
	)
	(segment
		(start 154.961336 -210.657186)
		(end 155.189682 -210.657186)
		(width 0.14478)
		(layer "In4.Cu")
		(net "M_J_CPU1_SA_DQ<6>")
	)
	(segment
		(start 182.241952 -203.710286)
		(end 186.635136 -203.710286)
		(width 0.14478)
		(layer "In4.Cu")
		(net "M_J_CPU1_SA_DQ<6>")
	)
	(segment
		(start 153.252424 -212.069426)
		(end 153.40076 -212.217762)
		(width 0.14478)
		(layer "In4.Cu")
		(net "M_J_CPU1_SA_DQ<6>")
	)
	(segment
		(start 144.9578 -223.911922)
		(end 144.994122 -223.89084)
		(width 0.0889)
		(layer "In4.Cu")
		(net "M_J_CPU1_SA_DQ<6>")
	)
	(segment
		(start 149.350984 -215.970866)
		(end 149.49932 -216.119202)
		(width 0.14478)
		(layer "In4.Cu")
		(net "M_J_CPU1_SA_DQ<6>")
	)
	(segment
		(start 155.203144 -210.118706)
		(end 155.203144 -209.890614)
		(width 0.14478)
		(layer "In4.Cu")
		(net "M_J_CPU1_SA_DQ<6>")
	)
	(segment
		(start 140.257784 -228.771958)
		(end 140.266166 -228.767132)
		(width 0.0889)
		(layer "In4.Cu")
		(net "M_J_CPU1_SA_DQ<6>")
	)
	(segment
		(start 149.741128 -215.35263)
		(end 149.90318 -215.190578)
		(width 0.14478)
		(layer "In4.Cu")
		(net "M_J_CPU1_SA_DQ<6>")
	)
	(segment
		(start 155.189682 -210.657186)
		(end 155.351734 -210.495134)
		(width 0.14478)
		(layer "In4.Cu")
		(net "M_J_CPU1_SA_DQ<6>")
	)
	(segment
		(start 156.521912 -209.09661)
		(end 156.750258 -209.09661)
		(width 0.14478)
		(layer "In4.Cu")
		(net "M_J_CPU1_SA_DQ<6>")
	)
	(segment
		(start 134.617714 -228.771958)
		(end 134.626096 -228.767132)
		(width 0.0889)
		(layer "In4.Cu")
		(net "M_J_CPU1_SA_DQ<6>")
	)
	(segment
		(start 156.132022 -209.486754)
		(end 155.983432 -209.338418)
		(width 0.14478)
		(layer "In4.Cu")
		(net "M_J_CPU1_SA_DQ<6>")
	)
	(segment
		(start 151.288242 -214.558626)
		(end 151.450294 -214.396574)
		(width 0.14478)
		(layer "In4.Cu")
		(net "M_J_CPU1_SA_DQ<6>")
	)
	(segment
		(start 133.103366 -228.767132)
		(end 133.111748 -228.771958)
		(width 0.0889)
		(layer "In4.Cu")
		(net "M_J_CPU1_SA_DQ<6>")
	)
	(segment
		(start 151.301704 -214.020146)
		(end 151.301704 -213.792054)
		(width 0.14478)
		(layer "In4.Cu")
		(net "M_J_CPU1_SA_DQ<6>")
	)
	(segment
		(start 173.496986 -204.560424)
		(end 174.347124 -203.710286)
		(width 0.14478)
		(layer "In4.Cu")
		(net "M_J_CPU1_SA_DQ<6>")
	)
	(segment
		(start 152.244044 -212.849714)
		(end 152.472136 -212.849714)
		(width 0.14478)
		(layer "In4.Cu")
		(net "M_J_CPU1_SA_DQ<6>")
	)
	(segment
		(start 151.840184 -213.778338)
		(end 152.06853 -213.778338)
		(width 0.14478)
		(layer "In4.Cu")
		(net "M_J_CPU1_SA_DQ<6>")
	)
	(segment
		(start 174.347124 -203.710286)
		(end 177.49647 -203.710286)
		(width 0.14478)
		(layer "In4.Cu")
		(net "M_J_CPU1_SA_DQ<6>")
	)
	(segment
		(start 152.081992 -213.011766)
		(end 152.244044 -212.849714)
		(width 0.14478)
		(layer "In4.Cu")
		(net "M_J_CPU1_SA_DQ<6>")
	)
	(segment
		(start 154.409394 -211.437474)
		(end 154.571446 -211.275422)
		(width 0.14478)
		(layer "In4.Cu")
		(net "M_J_CPU1_SA_DQ<6>")
	)
	(segment
		(start 156.373576 -208.948274)
		(end 156.521912 -209.09661)
		(width 0.14478)
		(layer "In4.Cu")
		(net "M_J_CPU1_SA_DQ<6>")
	)
	(segment
		(start 150.279608 -215.338914)
		(end 150.507954 -215.338914)
		(width 0.14478)
		(layer "In4.Cu")
		(net "M_J_CPU1_SA_DQ<6>")
	)
	(segment
		(start 153.791158 -211.827618)
		(end 153.642568 -211.679282)
		(width 0.14478)
		(layer "In4.Cu")
		(net "M_J_CPU1_SA_DQ<6>")
	)
	(segment
		(start 151.691848 -213.630002)
		(end 151.840184 -213.778338)
		(width 0.14478)
		(layer "In4.Cu")
		(net "M_J_CPU1_SA_DQ<6>")
	)
	(segment
		(start 143.045942 -227.170234)
		(end 143.077692 -227.151946)
		(width 0.0889)
		(layer "In4.Cu")
		(net "M_J_CPU1_SA_DQ<6>")
	)
	(segment
		(start 178.346608 -204.560424)
		(end 181.391814 -204.560424)
		(width 0.14478)
		(layer "In4.Cu")
		(net "M_J_CPU1_SA_DQ<6>")
	)
	(segment
		(start 150.521416 -214.572342)
		(end 150.683468 -214.41029)
		(width 0.14478)
		(layer "In4.Cu")
		(net "M_J_CPU1_SA_DQ<6>")
	)
	(segment
		(start 135.557768 -228.771958)
		(end 135.56615 -228.767132)
		(width 0.0889)
		(layer "In4.Cu")
		(net "M_J_CPU1_SA_DQ<6>")
	)
	(segment
		(start 151.450294 -214.396574)
		(end 151.450294 -214.168482)
		(width 0.14478)
		(layer "In4.Cu")
		(net "M_J_CPU1_SA_DQ<6>")
	)
	(segment
		(start 145.428208 -223.10217)
		(end 145.684494 -222.960184)
		(width 0.0889)
		(layer "In4.Cu")
		(net "M_J_CPU1_SA_DQ<6>")
	)
	(segment
		(start 145.392648 -223.122744)
		(end 145.428208 -223.10217)
		(width 0.0889)
		(layer "In4.Cu")
		(net "M_J_CPU1_SA_DQ<6>")
	)
	(segment
		(start 151.463756 -213.630002)
		(end 151.691848 -213.630002)
		(width 0.14478)
		(layer "In4.Cu")
		(net "M_J_CPU1_SA_DQ<6>")
	)
	(segment
		(start 143.547592 -226.34194)
		(end 143.586708 -226.31908)
		(width 0.0889)
		(layer "In4.Cu")
		(net "M_J_CPU1_SA_DQ<6>")
	)
	(segment
		(start 137.803382 -228.767132)
		(end 137.811764 -228.771958)
		(width 0.0889)
		(layer "In4.Cu")
		(net "M_J_CPU1_SA_DQ<6>")
	)
	(segment
		(start 154.032712 -211.289138)
		(end 154.181048 -211.437474)
		(width 0.14478)
		(layer "In4.Cu")
		(net "M_J_CPU1_SA_DQ<6>")
	)
	(segment
		(start 155.741624 -209.876898)
		(end 155.96997 -209.876898)
		(width 0.14478)
		(layer "In4.Cu")
		(net "M_J_CPU1_SA_DQ<6>")
	)
	(segment
		(start 154.181048 -211.437474)
		(end 154.409394 -211.437474)
		(width 0.14478)
		(layer "In4.Cu")
		(net "M_J_CPU1_SA_DQ<6>")
	)
	(segment
		(start 149.49932 -216.119202)
		(end 149.727666 -216.119202)
		(width 0.14478)
		(layer "In4.Cu")
		(net "M_J_CPU1_SA_DQ<6>")
	)
	(segment
		(start 150.521416 -214.800434)
		(end 150.521416 -214.572342)
		(width 0.14478)
		(layer "In4.Cu")
		(net "M_J_CPU1_SA_DQ<6>")
	)
	(segment
		(start 153.80462 -211.289138)
		(end 154.032712 -211.289138)
		(width 0.14478)
		(layer "In4.Cu")
		(net "M_J_CPU1_SA_DQ<6>")
	)
	(segment
		(start 156.132022 -209.714846)
		(end 156.132022 -209.486754)
		(width 0.14478)
		(layer "In4.Cu")
		(net "M_J_CPU1_SA_DQ<6>")
	)
	(segment
		(start 169.588942 -203.710286)
		(end 170.43908 -204.560424)
		(width 0.14478)
		(layer "In4.Cu")
		(net "M_J_CPU1_SA_DQ<6>")
	)
	(segment
		(start 150.670006 -214.94877)
		(end 150.521416 -214.800434)
		(width 0.14478)
		(layer "In4.Cu")
		(net "M_J_CPU1_SA_DQ<6>")
	)
	(segment
		(start 134.04342 -228.767132)
		(end 134.051802 -228.771958)
		(width 0.0889)
		(layer "In4.Cu")
		(net "M_J_CPU1_SA_DQ<6>")
	)
	(segment
		(start 186.635136 -203.710286)
		(end 187.060078 -204.135228)
		(width 0.14478)
		(layer "In4.Cu")
		(net "M_J_CPU1_SA_DQ<6>")
	)
	(segment
		(start 152.620472 -212.99805)
		(end 152.848818 -212.99805)
		(width 0.14478)
		(layer "In4.Cu")
		(net "M_J_CPU1_SA_DQ<6>")
	)
	(arc
		(start 144.770094 -224.234502)
		(mid 144.811349 -224.063531)
		(end 144.92605 -223.93021)
		(width 0.0889)
		(layer "In4.Cu")
		(net "M_J_CPU1_SA_DQ<6>")
	)
	(arc
		(start 145.239994 -223.424496)
		(mid 145.280323 -223.255404)
		(end 145.392648 -223.122744)
		(width 0.0889)
		(layer "In4.Cu")
		(net "M_J_CPU1_SA_DQ<6>")
	)
	(arc
		(start 141.571726 -228.771958)
		(mid 141.854682 -228.848135)
		(end 142.137638 -228.771958)
		(width 0.0889)
		(layer "In4.Cu")
		(net "M_J_CPU1_SA_DQ<6>")
	)
	(arc
		(start 142.420086 -228.284532)
		(mid 142.461341 -228.113561)
		(end 142.576042 -227.98024)
		(width 0.0889)
		(layer "In4.Cu")
		(net "M_J_CPU1_SA_DQ<6>")
	)
	(arc
		(start 139.691872 -228.771958)
		(mid 139.974828 -228.848135)
		(end 140.257784 -228.771958)
		(width 0.0889)
		(layer "In4.Cu")
		(net "M_J_CPU1_SA_DQ<6>")
	)
	(arc
		(start 143.83004 -225.854514)
		(mid 143.871295 -225.683543)
		(end 143.985996 -225.550222)
		(width 0.0889)
		(layer "In4.Cu")
		(net "M_J_CPU1_SA_DQ<6>")
	)
	(arc
		(start 144.300194 -225.044508)
		(mid 144.341743 -224.873086)
		(end 144.457166 -224.739708)
		(width 0.0889)
		(layer "In4.Cu")
		(net "M_J_CPU1_SA_DQ<6>")
	)
	(arc
		(start 141.197838 -228.771958)
		(mid 141.384782 -228.721703)
		(end 141.571726 -228.771958)
		(width 0.0889)
		(layer "In4.Cu")
		(net "M_J_CPU1_SA_DQ<6>")
	)
	(arc
		(start 142.889986 -227.474526)
		(mid 142.931241 -227.303555)
		(end 143.045942 -227.170234)
		(width 0.0889)
		(layer "In4.Cu")
		(net "M_J_CPU1_SA_DQ<6>")
	)
	(arc
		(start 138.751818 -228.771958)
		(mid 139.034774 -228.848135)
		(end 139.31773 -228.771958)
		(width 0.0889)
		(layer "In4.Cu")
		(net "M_J_CPU1_SA_DQ<6>")
	)
	(arc
		(start 143.36014 -226.66452)
		(mid 143.401689 -226.493098)
		(end 143.517112 -226.35972)
		(width 0.0889)
		(layer "In4.Cu")
		(net "M_J_CPU1_SA_DQ<6>")
	)
	(arc
		(start 137.437622 -228.771958)
		(mid 137.619873 -228.721608)
		(end 137.803382 -228.767132)
		(width 0.0889)
		(layer "In4.Cu")
		(net "M_J_CPU1_SA_DQ<6>")
	)
	(arc
		(start 144.526762 -224.699068)
		(mid 144.705575 -224.496718)
		(end 144.770094 -224.234502)
		(width 0.0889)
		(layer "In4.Cu")
		(net "M_J_CPU1_SA_DQ<6>")
	)
	(arc
		(start 133.111748 -228.771958)
		(mid 133.394704 -228.848135)
		(end 133.67766 -228.771958)
		(width 0.0889)
		(layer "In4.Cu")
		(net "M_J_CPU1_SA_DQ<6>")
	)
	(arc
		(start 132.792978 -228.745796)
		(mid 132.950488 -228.722598)
		(end 133.103366 -228.767132)
		(width 0.0889)
		(layer "In4.Cu")
		(net "M_J_CPU1_SA_DQ<6>")
	)
	(arc
		(start 143.586708 -226.31908)
		(mid 143.765521 -226.11673)
		(end 143.83004 -225.854514)
		(width 0.0889)
		(layer "In4.Cu")
		(net "M_J_CPU1_SA_DQ<6>")
	)
	(arc
		(start 136.87171 -228.771958)
		(mid 137.154666 -228.848135)
		(end 137.437622 -228.771958)
		(width 0.0889)
		(layer "In4.Cu")
		(net "M_J_CPU1_SA_DQ<6>")
	)
	(arc
		(start 142.644114 -227.94087)
		(mid 142.824766 -227.738125)
		(end 142.889986 -227.474526)
		(width 0.0889)
		(layer "In4.Cu")
		(net "M_J_CPU1_SA_DQ<6>")
	)
	(arc
		(start 134.626096 -228.767132)
		(mid 134.809604 -228.721638)
		(end 134.991856 -228.771958)
		(width 0.0889)
		(layer "In4.Cu")
		(net "M_J_CPU1_SA_DQ<6>")
	)
	(arc
		(start 142.176754 -228.749098)
		(mid 142.355567 -228.546748)
		(end 142.420086 -228.284532)
		(width 0.0889)
		(layer "In4.Cu")
		(net "M_J_CPU1_SA_DQ<6>")
	)
	(arc
		(start 135.93191 -228.771958)
		(mid 136.214866 -228.848135)
		(end 136.497822 -228.771958)
		(width 0.0889)
		(layer "In4.Cu")
		(net "M_J_CPU1_SA_DQ<6>")
	)
	(arc
		(start 139.326112 -228.767132)
		(mid 139.50962 -228.721638)
		(end 139.691872 -228.771958)
		(width 0.0889)
		(layer "In4.Cu")
		(net "M_J_CPU1_SA_DQ<6>")
	)
	(arc
		(start 133.67766 -228.771958)
		(mid 133.859911 -228.721608)
		(end 134.04342 -228.767132)
		(width 0.0889)
		(layer "In4.Cu")
		(net "M_J_CPU1_SA_DQ<6>")
	)
	(arc
		(start 134.991856 -228.771958)
		(mid 135.274812 -228.848135)
		(end 135.557768 -228.771958)
		(width 0.0889)
		(layer "In4.Cu")
		(net "M_J_CPU1_SA_DQ<6>")
	)
	(arc
		(start 137.811764 -228.771958)
		(mid 138.09472 -228.848135)
		(end 138.377676 -228.771958)
		(width 0.0889)
		(layer "In4.Cu")
		(net "M_J_CPU1_SA_DQ<6>")
	)
	(arc
		(start 135.56615 -228.767132)
		(mid 135.749658 -228.721638)
		(end 135.93191 -228.771958)
		(width 0.0889)
		(layer "In4.Cu")
		(net "M_J_CPU1_SA_DQ<6>")
	)
	(arc
		(start 143.116808 -227.129086)
		(mid 143.295621 -226.926736)
		(end 143.36014 -226.66452)
		(width 0.0889)
		(layer "In4.Cu")
		(net "M_J_CPU1_SA_DQ<6>")
	)
	(arc
		(start 144.994122 -223.89084)
		(mid 145.174774 -223.688095)
		(end 145.239994 -223.424496)
		(width 0.0889)
		(layer "In4.Cu")
		(net "M_J_CPU1_SA_DQ<6>")
	)
	(arc
		(start 136.497822 -228.771958)
		(mid 136.684766 -228.721703)
		(end 136.87171 -228.771958)
		(width 0.0889)
		(layer "In4.Cu")
		(net "M_J_CPU1_SA_DQ<6>")
	)
	(arc
		(start 140.266166 -228.767132)
		(mid 140.449674 -228.721638)
		(end 140.631926 -228.771958)
		(width 0.0889)
		(layer "In4.Cu")
		(net "M_J_CPU1_SA_DQ<6>")
	)
	(arc
		(start 134.051802 -228.771958)
		(mid 134.334758 -228.848135)
		(end 134.617714 -228.771958)
		(width 0.0889)
		(layer "In4.Cu")
		(net "M_J_CPU1_SA_DQ<6>")
	)
	(arc
		(start 138.377676 -228.771958)
		(mid 138.559927 -228.721608)
		(end 138.743436 -228.767132)
		(width 0.0889)
		(layer "In4.Cu")
		(net "M_J_CPU1_SA_DQ<6>")
	)
	(arc
		(start 144.056862 -225.509074)
		(mid 144.235675 -225.306724)
		(end 144.300194 -225.044508)
		(width 0.0889)
		(layer "In4.Cu")
		(net "M_J_CPU1_SA_DQ<6>")
	)
	(arc
		(start 140.631926 -228.771958)
		(mid 140.914882 -228.848135)
		(end 141.197838 -228.771958)
		(width 0.0889)
		(layer "In4.Cu")
		(net "M_J_CPU1_SA_DQ<6>")
	)
	(segment
		(start 130.577844 -229.360476)
		(end 131.044696 -229.094538)
		(width 0.10668)
		(layer "F.Cu")
		(net "M_J_CPU1_SA_DQ<5>")
	)
	(segment
		(start 146.738594 -222.067374)
		(end 146.738594 -218.991434)
		(width 0.14478)
		(layer "In4.Cu")
		(net "M_J_CPU1_SA_DQ<5>")
	)
	(segment
		(start 145.595848 -224.120964)
		(end 146.129248 -223.587564)
		(width 0.0889)
		(layer "In4.Cu")
		(net "M_J_CPU1_SA_DQ<5>")
	)
	(segment
		(start 181.29631 -205.410308)
		(end 182.146194 -204.560424)
		(width 0.14478)
		(layer "In4.Cu")
		(net "M_J_CPU1_SA_DQ<5>")
	)
	(segment
		(start 142.98168 -228.607112)
		(end 143.01343 -228.588824)
		(width 0.0889)
		(layer "In4.Cu")
		(net "M_J_CPU1_SA_DQ<5>")
	)
	(segment
		(start 135.557768 -229.416864)
		(end 135.56615 -229.42169)
		(width 0.0889)
		(layer "In4.Cu")
		(net "M_J_CPU1_SA_DQ<5>")
	)
	(segment
		(start 182.146194 -204.560424)
		(end 190.735204 -204.560424)
		(width 0.14478)
		(layer "In4.Cu")
		(net "M_J_CPU1_SA_DQ<5>")
	)
	(segment
		(start 166.222172 -205.410308)
		(end 167.072056 -204.560424)
		(width 0.14478)
		(layer "In4.Cu")
		(net "M_J_CPU1_SA_DQ<5>")
	)
	(segment
		(start 143.451834 -227.797106)
		(end 143.523716 -227.733606)
		(width 0.0889)
		(layer "In4.Cu")
		(net "M_J_CPU1_SA_DQ<5>")
	)
	(segment
		(start 140.257784 -229.416864)
		(end 140.266166 -229.42169)
		(width 0.0889)
		(layer "In4.Cu")
		(net "M_J_CPU1_SA_DQ<5>")
	)
	(segment
		(start 149.014434 -216.715594)
		(end 149.787102 -216.715594)
		(width 0.14478)
		(layer "In4.Cu")
		(net "M_J_CPU1_SA_DQ<5>")
	)
	(segment
		(start 144.714468 -226.542854)
		(end 144.714468 -225.525584)
		(width 0.0889)
		(layer "In4.Cu")
		(net "M_J_CPU1_SA_DQ<5>")
	)
	(segment
		(start 131.044696 -229.094538)
		(end 131.198874 -229.359968)
		(width 0.0889)
		(layer "In4.Cu")
		(net "M_J_CPU1_SA_DQ<5>")
	)
	(segment
		(start 142.503398 -229.42169)
		(end 142.51178 -229.416864)
		(width 0.0889)
		(layer "In4.Cu")
		(net "M_J_CPU1_SA_DQ<5>")
	)
	(segment
		(start 139.31773 -229.416864)
		(end 139.326112 -229.42169)
		(width 0.0889)
		(layer "In4.Cu")
		(net "M_J_CPU1_SA_DQ<5>")
	)
	(segment
		(start 174.641002 -204.560424)
		(end 177.682906 -204.560424)
		(width 0.14478)
		(layer "In4.Cu")
		(net "M_J_CPU1_SA_DQ<5>")
	)
	(segment
		(start 167.072056 -204.560424)
		(end 169.67962 -204.560424)
		(width 0.14478)
		(layer "In4.Cu")
		(net "M_J_CPU1_SA_DQ<5>")
	)
	(segment
		(start 142.51178 -229.416864)
		(end 142.545308 -229.397306)
		(width 0.0889)
		(layer "In4.Cu")
		(net "M_J_CPU1_SA_DQ<5>")
	)
	(segment
		(start 143.523716 -227.733606)
		(end 144.714468 -226.542854)
		(width 0.0889)
		(layer "In4.Cu")
		(net "M_J_CPU1_SA_DQ<5>")
	)
	(segment
		(start 142.945358 -228.628194)
		(end 142.98168 -228.607112)
		(width 0.0889)
		(layer "In4.Cu")
		(net "M_J_CPU1_SA_DQ<5>")
	)
	(segment
		(start 161.092388 -205.410308)
		(end 166.222172 -205.410308)
		(width 0.14478)
		(layer "In4.Cu")
		(net "M_J_CPU1_SA_DQ<5>")
	)
	(segment
		(start 190.735204 -204.560424)
		(end 191.160146 -204.985366)
		(width 0.14478)
		(layer "In4.Cu")
		(net "M_J_CPU1_SA_DQ<5>")
	)
	(segment
		(start 133.103366 -229.42169)
		(end 133.111748 -229.416864)
		(width 0.0889)
		(layer "In4.Cu")
		(net "M_J_CPU1_SA_DQ<5>")
	)
	(segment
		(start 134.04342 -229.42169)
		(end 134.051802 -229.416864)
		(width 0.0889)
		(layer "In4.Cu")
		(net "M_J_CPU1_SA_DQ<5>")
	)
	(segment
		(start 146.129248 -223.587564)
		(end 146.129248 -223.287844)
		(width 0.0889)
		(layer "In4.Cu")
		(net "M_J_CPU1_SA_DQ<5>")
	)
	(segment
		(start 146.129248 -223.287844)
		(end 146.738594 -222.678498)
		(width 0.0889)
		(layer "In4.Cu")
		(net "M_J_CPU1_SA_DQ<5>")
	)
	(segment
		(start 143.412718 -227.819966)
		(end 143.451834 -227.797106)
		(width 0.0889)
		(layer "In4.Cu")
		(net "M_J_CPU1_SA_DQ<5>")
	)
	(segment
		(start 178.53279 -205.410308)
		(end 181.29631 -205.410308)
		(width 0.14478)
		(layer "In4.Cu")
		(net "M_J_CPU1_SA_DQ<5>")
	)
	(segment
		(start 145.595848 -224.644204)
		(end 145.595848 -224.120964)
		(width 0.0889)
		(layer "In4.Cu")
		(net "M_J_CPU1_SA_DQ<5>")
	)
	(segment
		(start 146.738594 -222.678498)
		(end 146.738594 -222.067374)
		(width 0.0889)
		(layer "In4.Cu")
		(net "M_J_CPU1_SA_DQ<5>")
	)
	(segment
		(start 177.682906 -204.560424)
		(end 178.53279 -205.410308)
		(width 0.14478)
		(layer "In4.Cu")
		(net "M_J_CPU1_SA_DQ<5>")
	)
	(segment
		(start 173.791118 -205.410308)
		(end 174.641002 -204.560424)
		(width 0.14478)
		(layer "In4.Cu")
		(net "M_J_CPU1_SA_DQ<5>")
	)
	(segment
		(start 138.743436 -229.42169)
		(end 138.751818 -229.416864)
		(width 0.0889)
		(layer "In4.Cu")
		(net "M_J_CPU1_SA_DQ<5>")
	)
	(segment
		(start 170.529504 -205.410308)
		(end 173.791118 -205.410308)
		(width 0.14478)
		(layer "In4.Cu")
		(net "M_J_CPU1_SA_DQ<5>")
	)
	(segment
		(start 149.787102 -216.715594)
		(end 161.092388 -205.410308)
		(width 0.14478)
		(layer "In4.Cu")
		(net "M_J_CPU1_SA_DQ<5>")
	)
	(segment
		(start 144.714468 -225.525584)
		(end 145.595848 -224.644204)
		(width 0.0889)
		(layer "In4.Cu")
		(net "M_J_CPU1_SA_DQ<5>")
	)
	(segment
		(start 134.617714 -229.416864)
		(end 134.626096 -229.42169)
		(width 0.0889)
		(layer "In4.Cu")
		(net "M_J_CPU1_SA_DQ<5>")
	)
	(segment
		(start 137.803382 -229.42169)
		(end 137.811764 -229.416864)
		(width 0.0889)
		(layer "In4.Cu")
		(net "M_J_CPU1_SA_DQ<5>")
	)
	(segment
		(start 146.738594 -218.991434)
		(end 149.014434 -216.715594)
		(width 0.14478)
		(layer "In4.Cu")
		(net "M_J_CPU1_SA_DQ<5>")
	)
	(segment
		(start 131.198874 -229.359968)
		(end 131.294632 -229.385368)
		(width 0.0889)
		(layer "In4.Cu")
		(net "M_J_CPU1_SA_DQ<5>")
	)
	(segment
		(start 169.67962 -204.560424)
		(end 170.529504 -205.410308)
		(width 0.14478)
		(layer "In4.Cu")
		(net "M_J_CPU1_SA_DQ<5>")
	)
	(arc
		(start 132.737606 -229.416864)
		(mid 132.919857 -229.467248)
		(end 133.103366 -229.42169)
		(width 0.0889)
		(layer "In4.Cu")
		(net "M_J_CPU1_SA_DQ<5>")
	)
	(arc
		(start 132.171694 -229.416864)
		(mid 132.45465 -229.340687)
		(end 132.737606 -229.416864)
		(width 0.0889)
		(layer "In4.Cu")
		(net "M_J_CPU1_SA_DQ<5>")
	)
	(arc
		(start 139.691872 -229.416864)
		(mid 139.974828 -229.340687)
		(end 140.257784 -229.416864)
		(width 0.0889)
		(layer "In4.Cu")
		(net "M_J_CPU1_SA_DQ<5>")
	)
	(arc
		(start 138.751818 -229.416864)
		(mid 139.034774 -229.340687)
		(end 139.31773 -229.416864)
		(width 0.0889)
		(layer "In4.Cu")
		(net "M_J_CPU1_SA_DQ<5>")
	)
	(arc
		(start 136.87171 -229.416864)
		(mid 137.154666 -229.340687)
		(end 137.437622 -229.416864)
		(width 0.0889)
		(layer "In4.Cu")
		(net "M_J_CPU1_SA_DQ<5>")
	)
	(arc
		(start 134.626096 -229.42169)
		(mid 134.809604 -229.467215)
		(end 134.991856 -229.416864)
		(width 0.0889)
		(layer "In4.Cu")
		(net "M_J_CPU1_SA_DQ<5>")
	)
	(arc
		(start 138.377676 -229.416864)
		(mid 138.559927 -229.467248)
		(end 138.743436 -229.42169)
		(width 0.0889)
		(layer "In4.Cu")
		(net "M_J_CPU1_SA_DQ<5>")
	)
	(arc
		(start 139.326112 -229.42169)
		(mid 139.50962 -229.467215)
		(end 139.691872 -229.416864)
		(width 0.0889)
		(layer "In4.Cu")
		(net "M_J_CPU1_SA_DQ<5>")
	)
	(arc
		(start 134.051802 -229.416864)
		(mid 134.334758 -229.340687)
		(end 134.617714 -229.416864)
		(width 0.0889)
		(layer "In4.Cu")
		(net "M_J_CPU1_SA_DQ<5>")
	)
	(arc
		(start 143.169386 -228.284532)
		(mid 143.233901 -228.022313)
		(end 143.412718 -227.819966)
		(width 0.0889)
		(layer "In4.Cu")
		(net "M_J_CPU1_SA_DQ<5>")
	)
	(arc
		(start 136.497822 -229.416864)
		(mid 136.684766 -229.467153)
		(end 136.87171 -229.416864)
		(width 0.0889)
		(layer "In4.Cu")
		(net "M_J_CPU1_SA_DQ<5>")
	)
	(arc
		(start 131.294632 -229.385368)
		(mid 131.549954 -229.341668)
		(end 131.797806 -229.416864)
		(width 0.0889)
		(layer "In4.Cu")
		(net "M_J_CPU1_SA_DQ<5>")
	)
	(arc
		(start 133.67766 -229.416864)
		(mid 133.859911 -229.467248)
		(end 134.04342 -229.42169)
		(width 0.0889)
		(layer "In4.Cu")
		(net "M_J_CPU1_SA_DQ<5>")
	)
	(arc
		(start 134.991856 -229.416864)
		(mid 135.274812 -229.340687)
		(end 135.557768 -229.416864)
		(width 0.0889)
		(layer "In4.Cu")
		(net "M_J_CPU1_SA_DQ<5>")
	)
	(arc
		(start 137.437622 -229.416864)
		(mid 137.619873 -229.467248)
		(end 137.803382 -229.42169)
		(width 0.0889)
		(layer "In4.Cu")
		(net "M_J_CPU1_SA_DQ<5>")
	)
	(arc
		(start 141.571726 -229.416864)
		(mid 141.854682 -229.340687)
		(end 142.137638 -229.416864)
		(width 0.0889)
		(layer "In4.Cu")
		(net "M_J_CPU1_SA_DQ<5>")
	)
	(arc
		(start 142.137638 -229.416864)
		(mid 142.319889 -229.467248)
		(end 142.503398 -229.42169)
		(width 0.0889)
		(layer "In4.Cu")
		(net "M_J_CPU1_SA_DQ<5>")
	)
	(arc
		(start 133.111748 -229.416864)
		(mid 133.394704 -229.340687)
		(end 133.67766 -229.416864)
		(width 0.0889)
		(layer "In4.Cu")
		(net "M_J_CPU1_SA_DQ<5>")
	)
	(arc
		(start 140.631926 -229.416864)
		(mid 140.914882 -229.340687)
		(end 141.197838 -229.416864)
		(width 0.0889)
		(layer "In4.Cu")
		(net "M_J_CPU1_SA_DQ<5>")
	)
	(arc
		(start 135.93191 -229.416864)
		(mid 136.214866 -229.340687)
		(end 136.497822 -229.416864)
		(width 0.0889)
		(layer "In4.Cu")
		(net "M_J_CPU1_SA_DQ<5>")
	)
	(arc
		(start 135.56615 -229.42169)
		(mid 135.749658 -229.467215)
		(end 135.93191 -229.416864)
		(width 0.0889)
		(layer "In4.Cu")
		(net "M_J_CPU1_SA_DQ<5>")
	)
	(arc
		(start 143.01343 -228.588824)
		(mid 143.128106 -228.45549)
		(end 143.169386 -228.284532)
		(width 0.0889)
		(layer "In4.Cu")
		(net "M_J_CPU1_SA_DQ<5>")
	)
	(arc
		(start 141.197838 -229.416864)
		(mid 141.384782 -229.467153)
		(end 141.571726 -229.416864)
		(width 0.0889)
		(layer "In4.Cu")
		(net "M_J_CPU1_SA_DQ<5>")
	)
	(arc
		(start 142.545308 -229.397306)
		(mid 142.658715 -229.264417)
		(end 142.699486 -229.094538)
		(width 0.0889)
		(layer "In4.Cu")
		(net "M_J_CPU1_SA_DQ<5>")
	)
	(arc
		(start 140.266166 -229.42169)
		(mid 140.449674 -229.467215)
		(end 140.631926 -229.416864)
		(width 0.0889)
		(layer "In4.Cu")
		(net "M_J_CPU1_SA_DQ<5>")
	)
	(arc
		(start 142.699486 -229.094538)
		(mid 142.764722 -228.830947)
		(end 142.945358 -228.628194)
		(width 0.0889)
		(layer "In4.Cu")
		(net "M_J_CPU1_SA_DQ<5>")
	)
	(arc
		(start 137.811764 -229.416864)
		(mid 138.09472 -229.340687)
		(end 138.377676 -229.416864)
		(width 0.0889)
		(layer "In4.Cu")
		(net "M_J_CPU1_SA_DQ<5>")
	)
	(arc
		(start 131.797806 -229.416864)
		(mid 131.98475 -229.467153)
		(end 132.171694 -229.416864)
		(width 0.0889)
		(layer "In4.Cu")
		(net "M_J_CPU1_SA_DQ<5>")
	)
	(segment
		(start 131.987798 -228.55047)
		(end 132.45465 -228.284532)
		(width 0.10668)
		(layer "F.Cu")
		(net "M_J_CPU1_SA_DQ<4>")
	)
	(segment
		(start 189.269624 -202.870054)
		(end 189.42304 -203.02347)
		(width 0.14478)
		(layer "In4.Cu")
		(net "M_J_CPU1_SA_DQ<4>")
	)
	(segment
		(start 177.365914 -202.870054)
		(end 178.215798 -203.719938)
		(width 0.14478)
		(layer "In4.Cu")
		(net "M_J_CPU1_SA_DQ<4>")
	)
	(segment
		(start 142.04188 -228.607112)
		(end 142.07236 -228.589332)
		(width 0.0889)
		(layer "In4.Cu")
		(net "M_J_CPU1_SA_DQ<4>")
	)
	(segment
		(start 132.45465 -228.284532)
		(end 132.608828 -228.549962)
		(width 0.0889)
		(layer "In4.Cu")
		(net "M_J_CPU1_SA_DQ<4>")
	)
	(segment
		(start 145.839434 -222.43796)
		(end 145.839434 -221.866206)
		(width 0.0889)
		(layer "In4.Cu")
		(net "M_J_CPU1_SA_DQ<4>")
	)
	(segment
		(start 190.142622 -202.860402)
		(end 190.735204 -202.860402)
		(width 0.14478)
		(layer "In4.Cu")
		(net "M_J_CPU1_SA_DQ<4>")
	)
	(segment
		(start 145.29435 -222.958914)
		(end 145.33245 -222.936816)
		(width 0.0889)
		(layer "In4.Cu")
		(net "M_J_CPU1_SA_DQ<4>")
	)
	(segment
		(start 145.839434 -218.618054)
		(end 155.958794 -208.498694)
		(width 0.14478)
		(layer "In4.Cu")
		(net "M_J_CPU1_SA_DQ<4>")
	)
	(segment
		(start 189.816486 -203.62418)
		(end 189.979554 -203.461112)
		(width 0.14478)
		(layer "In4.Cu")
		(net "M_J_CPU1_SA_DQ<4>")
	)
	(segment
		(start 144.861788 -223.747076)
		(end 144.893538 -223.728788)
		(width 0.0889)
		(layer "In4.Cu")
		(net "M_J_CPU1_SA_DQ<4>")
	)
	(segment
		(start 141.093444 -228.611938)
		(end 141.101826 -228.607112)
		(width 0.0889)
		(layer "In4.Cu")
		(net "M_J_CPU1_SA_DQ<4>")
	)
	(segment
		(start 166.330376 -203.710286)
		(end 167.18026 -202.860402)
		(width 0.14478)
		(layer "In4.Cu")
		(net "M_J_CPU1_SA_DQ<4>")
	)
	(segment
		(start 145.839434 -221.866206)
		(end 145.839434 -218.618054)
		(width 0.14478)
		(layer "In4.Cu")
		(net "M_J_CPU1_SA_DQ<4>")
	)
	(segment
		(start 135.453374 -228.611938)
		(end 135.461756 -228.607112)
		(width 0.0889)
		(layer "In4.Cu")
		(net "M_J_CPU1_SA_DQ<4>")
	)
	(segment
		(start 173.643544 -203.719938)
		(end 174.493428 -202.870054)
		(width 0.14478)
		(layer "In4.Cu")
		(net "M_J_CPU1_SA_DQ<4>")
	)
	(segment
		(start 145.33245 -222.936816)
		(end 145.403824 -222.87357)
		(width 0.0889)
		(layer "In4.Cu")
		(net "M_J_CPU1_SA_DQ<4>")
	)
	(segment
		(start 142.98168 -226.9871)
		(end 143.01343 -226.968812)
		(width 0.0889)
		(layer "In4.Cu")
		(net "M_J_CPU1_SA_DQ<4>")
	)
	(segment
		(start 142.472664 -227.819966)
		(end 142.51178 -227.797106)
		(width 0.0889)
		(layer "In4.Cu")
		(net "M_J_CPU1_SA_DQ<4>")
	)
	(segment
		(start 145.403824 -222.87357)
		(end 145.839434 -222.43796)
		(width 0.0889)
		(layer "In4.Cu")
		(net "M_J_CPU1_SA_DQ<4>")
	)
	(segment
		(start 182.375556 -202.870054)
		(end 189.269624 -202.870054)
		(width 0.14478)
		(layer "In4.Cu")
		(net "M_J_CPU1_SA_DQ<4>")
	)
	(segment
		(start 136.967722 -228.607112)
		(end 136.976104 -228.611938)
		(width 0.0889)
		(layer "In4.Cu")
		(net "M_J_CPU1_SA_DQ<4>")
	)
	(segment
		(start 161.500566 -203.710286)
		(end 166.330376 -203.710286)
		(width 0.14478)
		(layer "In4.Cu")
		(net "M_J_CPU1_SA_DQ<4>")
	)
	(segment
		(start 142.51178 -227.797106)
		(end 142.54353 -227.778818)
		(width 0.0889)
		(layer "In4.Cu")
		(net "M_J_CPU1_SA_DQ<4>")
	)
	(segment
		(start 137.907776 -228.607112)
		(end 137.916158 -228.611938)
		(width 0.0889)
		(layer "In4.Cu")
		(net "M_J_CPU1_SA_DQ<4>")
	)
	(segment
		(start 143.921734 -225.367088)
		(end 143.953484 -225.3488)
		(width 0.0889)
		(layer "In4.Cu")
		(net "M_J_CPU1_SA_DQ<4>")
	)
	(segment
		(start 189.42304 -203.461112)
		(end 189.586108 -203.62418)
		(width 0.14478)
		(layer "In4.Cu")
		(net "M_J_CPU1_SA_DQ<4>")
	)
	(segment
		(start 133.20776 -228.607112)
		(end 133.216142 -228.611938)
		(width 0.0889)
		(layer "In4.Cu")
		(net "M_J_CPU1_SA_DQ<4>")
	)
	(segment
		(start 132.608828 -228.549962)
		(end 132.705094 -228.575362)
		(width 0.0889)
		(layer "In4.Cu")
		(net "M_J_CPU1_SA_DQ<4>")
	)
	(segment
		(start 143.412718 -226.199954)
		(end 143.451834 -226.177094)
		(width 0.0889)
		(layer "In4.Cu")
		(net "M_J_CPU1_SA_DQ<4>")
	)
	(segment
		(start 174.493428 -202.870054)
		(end 177.365914 -202.870054)
		(width 0.14478)
		(layer "In4.Cu")
		(net "M_J_CPU1_SA_DQ<4>")
	)
	(segment
		(start 136.393428 -228.611938)
		(end 136.40181 -228.607112)
		(width 0.0889)
		(layer "In4.Cu")
		(net "M_J_CPU1_SA_DQ<4>")
	)
	(segment
		(start 189.979554 -203.461112)
		(end 189.979554 -203.02347)
		(width 0.14478)
		(layer "In4.Cu")
		(net "M_J_CPU1_SA_DQ<4>")
	)
	(segment
		(start 189.586108 -203.62418)
		(end 189.816486 -203.62418)
		(width 0.14478)
		(layer "In4.Cu")
		(net "M_J_CPU1_SA_DQ<4>")
	)
	(segment
		(start 178.215798 -203.719938)
		(end 181.525672 -203.719938)
		(width 0.14478)
		(layer "In4.Cu")
		(net "M_J_CPU1_SA_DQ<4>")
	)
	(segment
		(start 141.667738 -228.607112)
		(end 141.67612 -228.611938)
		(width 0.0889)
		(layer "In4.Cu")
		(net "M_J_CPU1_SA_DQ<4>")
	)
	(segment
		(start 189.42304 -203.02347)
		(end 189.42304 -203.461112)
		(width 0.14478)
		(layer "In4.Cu")
		(net "M_J_CPU1_SA_DQ<4>")
	)
	(segment
		(start 156.712158 -208.498694)
		(end 161.500566 -203.710286)
		(width 0.14478)
		(layer "In4.Cu")
		(net "M_J_CPU1_SA_DQ<4>")
	)
	(segment
		(start 189.979554 -203.02347)
		(end 190.142622 -202.860402)
		(width 0.14478)
		(layer "In4.Cu")
		(net "M_J_CPU1_SA_DQ<4>")
	)
	(segment
		(start 190.735204 -202.860402)
		(end 191.160146 -203.285344)
		(width 0.14478)
		(layer "In4.Cu")
		(net "M_J_CPU1_SA_DQ<4>")
	)
	(segment
		(start 155.958794 -208.498694)
		(end 156.712158 -208.498694)
		(width 0.14478)
		(layer "In4.Cu")
		(net "M_J_CPU1_SA_DQ<4>")
	)
	(segment
		(start 144.822672 -223.769936)
		(end 144.861788 -223.747076)
		(width 0.0889)
		(layer "In4.Cu")
		(net "M_J_CPU1_SA_DQ<4>")
	)
	(segment
		(start 144.391888 -224.557082)
		(end 144.422368 -224.539302)
		(width 0.0889)
		(layer "In4.Cu")
		(net "M_J_CPU1_SA_DQ<4>")
	)
	(segment
		(start 144.352772 -224.579942)
		(end 144.391888 -224.557082)
		(width 0.0889)
		(layer "In4.Cu")
		(net "M_J_CPU1_SA_DQ<4>")
	)
	(segment
		(start 167.18026 -202.860402)
		(end 169.546016 -202.860402)
		(width 0.14478)
		(layer "In4.Cu")
		(net "M_J_CPU1_SA_DQ<4>")
	)
	(segment
		(start 181.525672 -203.719938)
		(end 182.375556 -202.870054)
		(width 0.14478)
		(layer "In4.Cu")
		(net "M_J_CPU1_SA_DQ<4>")
	)
	(segment
		(start 170.405552 -203.719938)
		(end 173.643544 -203.719938)
		(width 0.14478)
		(layer "In4.Cu")
		(net "M_J_CPU1_SA_DQ<4>")
	)
	(segment
		(start 169.546016 -202.860402)
		(end 170.405552 -203.719938)
		(width 0.14478)
		(layer "In4.Cu")
		(net "M_J_CPU1_SA_DQ<4>")
	)
	(segment
		(start 142.945358 -227.008182)
		(end 142.98168 -226.9871)
		(width 0.0889)
		(layer "In4.Cu")
		(net "M_J_CPU1_SA_DQ<4>")
	)
	(segment
		(start 140.15339 -228.611938)
		(end 140.161772 -228.607112)
		(width 0.0889)
		(layer "In4.Cu")
		(net "M_J_CPU1_SA_DQ<4>")
	)
	(segment
		(start 143.451834 -226.177094)
		(end 143.482314 -226.159314)
		(width 0.0889)
		(layer "In4.Cu")
		(net "M_J_CPU1_SA_DQ<4>")
	)
	(segment
		(start 143.882618 -225.389948)
		(end 143.921734 -225.367088)
		(width 0.0889)
		(layer "In4.Cu")
		(net "M_J_CPU1_SA_DQ<4>")
	)
	(arc
		(start 145.049494 -223.424496)
		(mid 145.114434 -223.161466)
		(end 145.29435 -222.958914)
		(width 0.0889)
		(layer "In4.Cu")
		(net "M_J_CPU1_SA_DQ<4>")
	)
	(arc
		(start 142.07236 -228.589332)
		(mid 142.187787 -228.455956)
		(end 142.229332 -228.284532)
		(width 0.0889)
		(layer "In4.Cu")
		(net "M_J_CPU1_SA_DQ<4>")
	)
	(arc
		(start 137.341864 -228.607112)
		(mid 137.62482 -228.530935)
		(end 137.907776 -228.607112)
		(width 0.0889)
		(layer "In4.Cu")
		(net "M_J_CPU1_SA_DQ<4>")
	)
	(arc
		(start 139.78763 -228.607112)
		(mid 139.969881 -228.657462)
		(end 140.15339 -228.611938)
		(width 0.0889)
		(layer "In4.Cu")
		(net "M_J_CPU1_SA_DQ<4>")
	)
	(arc
		(start 144.57934 -224.234502)
		(mid 144.643855 -223.972283)
		(end 144.822672 -223.769936)
		(width 0.0889)
		(layer "In4.Cu")
		(net "M_J_CPU1_SA_DQ<4>")
	)
	(arc
		(start 140.727684 -228.607112)
		(mid 140.909935 -228.657462)
		(end 141.093444 -228.611938)
		(width 0.0889)
		(layer "In4.Cu")
		(net "M_J_CPU1_SA_DQ<4>")
	)
	(arc
		(start 133.216142 -228.611938)
		(mid 133.39965 -228.657432)
		(end 133.581902 -228.607112)
		(width 0.0889)
		(layer "In4.Cu")
		(net "M_J_CPU1_SA_DQ<4>")
	)
	(arc
		(start 136.40181 -228.607112)
		(mid 136.684766 -228.530935)
		(end 136.967722 -228.607112)
		(width 0.0889)
		(layer "In4.Cu")
		(net "M_J_CPU1_SA_DQ<4>")
	)
	(arc
		(start 135.461756 -228.607112)
		(mid 135.744712 -228.530935)
		(end 136.027668 -228.607112)
		(width 0.0889)
		(layer "In4.Cu")
		(net "M_J_CPU1_SA_DQ<4>")
	)
	(arc
		(start 133.581902 -228.607112)
		(mid 133.864858 -228.530935)
		(end 134.147814 -228.607112)
		(width 0.0889)
		(layer "In4.Cu")
		(net "M_J_CPU1_SA_DQ<4>")
	)
	(arc
		(start 137.916158 -228.611938)
		(mid 138.099666 -228.657432)
		(end 138.281918 -228.607112)
		(width 0.0889)
		(layer "In4.Cu")
		(net "M_J_CPU1_SA_DQ<4>")
	)
	(arc
		(start 140.161772 -228.607112)
		(mid 140.444728 -228.530935)
		(end 140.727684 -228.607112)
		(width 0.0889)
		(layer "In4.Cu")
		(net "M_J_CPU1_SA_DQ<4>")
	)
	(arc
		(start 143.482314 -226.159314)
		(mid 143.597741 -226.025938)
		(end 143.639286 -225.854514)
		(width 0.0889)
		(layer "In4.Cu")
		(net "M_J_CPU1_SA_DQ<4>")
	)
	(arc
		(start 134.147814 -228.607112)
		(mid 134.334758 -228.657367)
		(end 134.521702 -228.607112)
		(width 0.0889)
		(layer "In4.Cu")
		(net "M_J_CPU1_SA_DQ<4>")
	)
	(arc
		(start 138.84783 -228.607112)
		(mid 139.034774 -228.657367)
		(end 139.221718 -228.607112)
		(width 0.0889)
		(layer "In4.Cu")
		(net "M_J_CPU1_SA_DQ<4>")
	)
	(arc
		(start 138.281918 -228.607112)
		(mid 138.564874 -228.530935)
		(end 138.84783 -228.607112)
		(width 0.0889)
		(layer "In4.Cu")
		(net "M_J_CPU1_SA_DQ<4>")
	)
	(arc
		(start 144.422368 -224.539302)
		(mid 144.537795 -224.405926)
		(end 144.57934 -224.234502)
		(width 0.0889)
		(layer "In4.Cu")
		(net "M_J_CPU1_SA_DQ<4>")
	)
	(arc
		(start 136.976104 -228.611938)
		(mid 137.159612 -228.657432)
		(end 137.341864 -228.607112)
		(width 0.0889)
		(layer "In4.Cu")
		(net "M_J_CPU1_SA_DQ<4>")
	)
	(arc
		(start 136.027668 -228.607112)
		(mid 136.209919 -228.657462)
		(end 136.393428 -228.611938)
		(width 0.0889)
		(layer "In4.Cu")
		(net "M_J_CPU1_SA_DQ<4>")
	)
	(arc
		(start 141.101826 -228.607112)
		(mid 141.384782 -228.530935)
		(end 141.667738 -228.607112)
		(width 0.0889)
		(layer "In4.Cu")
		(net "M_J_CPU1_SA_DQ<4>")
	)
	(arc
		(start 144.893538 -223.728788)
		(mid 145.008214 -223.595454)
		(end 145.049494 -223.424496)
		(width 0.0889)
		(layer "In4.Cu")
		(net "M_J_CPU1_SA_DQ<4>")
	)
	(arc
		(start 143.01343 -226.968812)
		(mid 143.128106 -226.835478)
		(end 143.169386 -226.66452)
		(width 0.0889)
		(layer "In4.Cu")
		(net "M_J_CPU1_SA_DQ<4>")
	)
	(arc
		(start 134.521702 -228.607112)
		(mid 134.804658 -228.530935)
		(end 135.087614 -228.607112)
		(width 0.0889)
		(layer "In4.Cu")
		(net "M_J_CPU1_SA_DQ<4>")
	)
	(arc
		(start 132.705094 -228.575362)
		(mid 132.960159 -228.532011)
		(end 133.20776 -228.607112)
		(width 0.0889)
		(layer "In4.Cu")
		(net "M_J_CPU1_SA_DQ<4>")
	)
	(arc
		(start 142.229332 -228.284532)
		(mid 142.293847 -228.022313)
		(end 142.472664 -227.819966)
		(width 0.0889)
		(layer "In4.Cu")
		(net "M_J_CPU1_SA_DQ<4>")
	)
	(arc
		(start 144.10944 -225.044508)
		(mid 144.173955 -224.782289)
		(end 144.352772 -224.579942)
		(width 0.0889)
		(layer "In4.Cu")
		(net "M_J_CPU1_SA_DQ<4>")
	)
	(arc
		(start 142.54353 -227.778818)
		(mid 142.658206 -227.645484)
		(end 142.699486 -227.474526)
		(width 0.0889)
		(layer "In4.Cu")
		(net "M_J_CPU1_SA_DQ<4>")
	)
	(arc
		(start 143.639286 -225.854514)
		(mid 143.703801 -225.592295)
		(end 143.882618 -225.389948)
		(width 0.0889)
		(layer "In4.Cu")
		(net "M_J_CPU1_SA_DQ<4>")
	)
	(arc
		(start 139.221718 -228.607112)
		(mid 139.504674 -228.530935)
		(end 139.78763 -228.607112)
		(width 0.0889)
		(layer "In4.Cu")
		(net "M_J_CPU1_SA_DQ<4>")
	)
	(arc
		(start 143.953484 -225.3488)
		(mid 144.06816 -225.215466)
		(end 144.10944 -225.044508)
		(width 0.0889)
		(layer "In4.Cu")
		(net "M_J_CPU1_SA_DQ<4>")
	)
	(arc
		(start 141.67612 -228.611938)
		(mid 141.859628 -228.657432)
		(end 142.04188 -228.607112)
		(width 0.0889)
		(layer "In4.Cu")
		(net "M_J_CPU1_SA_DQ<4>")
	)
	(arc
		(start 135.087614 -228.607112)
		(mid 135.269865 -228.657462)
		(end 135.453374 -228.611938)
		(width 0.0889)
		(layer "In4.Cu")
		(net "M_J_CPU1_SA_DQ<4>")
	)
	(arc
		(start 143.169386 -226.66452)
		(mid 143.233901 -226.402301)
		(end 143.412718 -226.199954)
		(width 0.0889)
		(layer "In4.Cu")
		(net "M_J_CPU1_SA_DQ<4>")
	)
	(arc
		(start 142.699486 -227.474526)
		(mid 142.764722 -227.210935)
		(end 142.945358 -227.008182)
		(width 0.0889)
		(layer "In4.Cu")
		(net "M_J_CPU1_SA_DQ<4>")
	)
	(segment
		(start 131.047998 -226.930458)
		(end 131.51485 -226.66452)
		(width 0.10668)
		(layer "F.Cu")
		(net "M_J_CPU1_SA_DQ<3>")
	)
	(segment
		(start 178.974496 -200.300844)
		(end 181.125622 -200.300844)
		(width 0.14478)
		(layer "In4.Cu")
		(net "M_J_CPU1_SA_DQ<3>")
	)
	(segment
		(start 160.102296 -199.99198)
		(end 160.4518 -200.341484)
		(width 0.14478)
		(layer "In4.Cu")
		(net "M_J_CPU1_SA_DQ<3>")
	)
	(segment
		(start 160.061656 -200.960228)
		(end 160.061656 -200.731628)
		(width 0.14478)
		(layer "In4.Cu")
		(net "M_J_CPU1_SA_DQ<3>")
	)
	(segment
		(start 166.361872 -200.014586)
		(end 166.9161 -199.460358)
		(width 0.14478)
		(layer "In4.Cu")
		(net "M_J_CPU1_SA_DQ<3>")
	)
	(segment
		(start 174.256192 -199.450706)
		(end 178.124358 -199.450706)
		(width 0.14478)
		(layer "In4.Cu")
		(net "M_J_CPU1_SA_DQ<3>")
	)
	(segment
		(start 137.907776 -226.34194)
		(end 137.916158 -226.337114)
		(width 0.0889)
		(layer "In4.Cu")
		(net "M_J_CPU1_SA_DQ<3>")
	)
	(segment
		(start 159.900112 -201.121772)
		(end 160.061656 -200.960228)
		(width 0.14478)
		(layer "In4.Cu")
		(net "M_J_CPU1_SA_DQ<3>")
	)
	(segment
		(start 166.9161 -199.460358)
		(end 170.199812 -199.460358)
		(width 0.14478)
		(layer "In4.Cu")
		(net "M_J_CPU1_SA_DQ<3>")
	)
	(segment
		(start 159.281368 -201.740516)
		(end 159.281368 -201.511916)
		(width 0.14478)
		(layer "In4.Cu")
		(net "M_J_CPU1_SA_DQ<3>")
	)
	(segment
		(start 160.061656 -200.731628)
		(end 159.712152 -200.382124)
		(width 0.14478)
		(layer "In4.Cu")
		(net "M_J_CPU1_SA_DQ<3>")
	)
	(segment
		(start 171.040044 -200.30059)
		(end 173.406308 -200.30059)
		(width 0.14478)
		(layer "In4.Cu")
		(net "M_J_CPU1_SA_DQ<3>")
	)
	(segment
		(start 158.50108 -202.655424)
		(end 158.50108 -202.292204)
		(width 0.14478)
		(layer "In4.Cu")
		(net "M_J_CPU1_SA_DQ<3>")
	)
	(segment
		(start 160.6804 -200.341484)
		(end 161.007298 -200.014586)
		(width 0.14478)
		(layer "In4.Cu")
		(net "M_J_CPU1_SA_DQ<3>")
	)
	(segment
		(start 140.15339 -226.337114)
		(end 140.161772 -226.34194)
		(width 0.0889)
		(layer "In4.Cu")
		(net "M_J_CPU1_SA_DQ<3>")
	)
	(segment
		(start 181.125622 -200.300844)
		(end 181.97576 -199.450706)
		(width 0.14478)
		(layer "In4.Cu")
		(net "M_J_CPU1_SA_DQ<3>")
	)
	(segment
		(start 142.608046 -223.10217)
		(end 142.641574 -223.082612)
		(width 0.0889)
		(layer "In4.Cu")
		(net "M_J_CPU1_SA_DQ<3>")
	)
	(segment
		(start 158.151576 -201.9427)
		(end 158.151576 -201.7141)
		(width 0.14478)
		(layer "In4.Cu")
		(net "M_J_CPU1_SA_DQ<3>")
	)
	(segment
		(start 159.712152 -200.382124)
		(end 159.712152 -200.153524)
		(width 0.14478)
		(layer "In4.Cu")
		(net "M_J_CPU1_SA_DQ<3>")
	)
	(segment
		(start 159.671512 -201.121772)
		(end 159.900112 -201.121772)
		(width 0.14478)
		(layer "In4.Cu")
		(net "M_J_CPU1_SA_DQ<3>")
	)
	(segment
		(start 158.891224 -201.90206)
		(end 159.119824 -201.90206)
		(width 0.14478)
		(layer "In4.Cu")
		(net "M_J_CPU1_SA_DQ<3>")
	)
	(segment
		(start 178.124358 -199.450706)
		(end 178.974496 -200.300844)
		(width 0.14478)
		(layer "In4.Cu")
		(net "M_J_CPU1_SA_DQ<3>")
	)
	(segment
		(start 142.10538 -223.930972)
		(end 142.138146 -223.911922)
		(width 0.0889)
		(layer "In4.Cu")
		(net "M_J_CPU1_SA_DQ<3>")
	)
	(segment
		(start 143.361156 -221.537276)
		(end 143.480028 -221.418404)
		(width 0.0889)
		(layer "In4.Cu")
		(net "M_J_CPU1_SA_DQ<3>")
	)
	(segment
		(start 132.267706 -226.34194)
		(end 132.276088 -226.337114)
		(width 0.0889)
		(layer "In4.Cu")
		(net "M_J_CPU1_SA_DQ<3>")
	)
	(segment
		(start 133.20776 -226.34194)
		(end 133.216142 -226.337114)
		(width 0.0889)
		(layer "In4.Cu")
		(net "M_J_CPU1_SA_DQ<3>")
	)
	(segment
		(start 159.712152 -200.153524)
		(end 159.873696 -199.99198)
		(width 0.14478)
		(layer "In4.Cu")
		(net "M_J_CPU1_SA_DQ<3>")
	)
	(segment
		(start 131.51485 -226.66452)
		(end 131.360672 -226.39909)
		(width 0.0889)
		(layer "In4.Cu")
		(net "M_J_CPU1_SA_DQ<3>")
	)
	(segment
		(start 158.931864 -200.933812)
		(end 159.093408 -200.772268)
		(width 0.14478)
		(layer "In4.Cu")
		(net "M_J_CPU1_SA_DQ<3>")
	)
	(segment
		(start 143.480028 -217.676476)
		(end 158.50108 -202.655424)
		(width 0.14478)
		(layer "In4.Cu")
		(net "M_J_CPU1_SA_DQ<3>")
	)
	(segment
		(start 131.693412 -226.337114)
		(end 131.701794 -226.34194)
		(width 0.0889)
		(layer "In4.Cu")
		(net "M_J_CPU1_SA_DQ<3>")
	)
	(segment
		(start 159.093408 -200.772268)
		(end 159.322008 -200.772268)
		(width 0.14478)
		(layer "In4.Cu")
		(net "M_J_CPU1_SA_DQ<3>")
	)
	(segment
		(start 141.667738 -224.721928)
		(end 141.706854 -224.699068)
		(width 0.0889)
		(layer "In4.Cu")
		(net "M_J_CPU1_SA_DQ<3>")
	)
	(segment
		(start 140.727684 -226.34194)
		(end 140.7668 -226.31908)
		(width 0.0889)
		(layer "In4.Cu")
		(net "M_J_CPU1_SA_DQ<3>")
	)
	(segment
		(start 158.50108 -202.292204)
		(end 158.151576 -201.9427)
		(width 0.14478)
		(layer "In4.Cu")
		(net "M_J_CPU1_SA_DQ<3>")
	)
	(segment
		(start 141.166088 -225.550222)
		(end 141.197838 -225.531934)
		(width 0.0889)
		(layer "In4.Cu")
		(net "M_J_CPU1_SA_DQ<3>")
	)
	(segment
		(start 142.138146 -223.911922)
		(end 142.172944 -223.891602)
		(width 0.0889)
		(layer "In4.Cu")
		(net "M_J_CPU1_SA_DQ<3>")
	)
	(segment
		(start 136.393428 -226.337114)
		(end 136.40181 -226.34194)
		(width 0.0889)
		(layer "In4.Cu")
		(net "M_J_CPU1_SA_DQ<3>")
	)
	(segment
		(start 161.007298 -200.014586)
		(end 166.361872 -200.014586)
		(width 0.14478)
		(layer "In4.Cu")
		(net "M_J_CPU1_SA_DQ<3>")
	)
	(segment
		(start 141.635988 -224.740216)
		(end 141.667738 -224.721928)
		(width 0.0889)
		(layer "In4.Cu")
		(net "M_J_CPU1_SA_DQ<3>")
	)
	(segment
		(start 170.199812 -199.460358)
		(end 171.040044 -200.30059)
		(width 0.14478)
		(layer "In4.Cu")
		(net "M_J_CPU1_SA_DQ<3>")
	)
	(segment
		(start 158.31312 -201.552556)
		(end 158.54172 -201.552556)
		(width 0.14478)
		(layer "In4.Cu")
		(net "M_J_CPU1_SA_DQ<3>")
	)
	(segment
		(start 143.480028 -221.235524)
		(end 143.480028 -217.676476)
		(width 0.14478)
		(layer "In4.Cu")
		(net "M_J_CPU1_SA_DQ<3>")
	)
	(segment
		(start 143.077946 -222.292164)
		(end 143.11884 -222.268542)
		(width 0.0889)
		(layer "In4.Cu")
		(net "M_J_CPU1_SA_DQ<3>")
	)
	(segment
		(start 159.119824 -201.90206)
		(end 159.281368 -201.740516)
		(width 0.14478)
		(layer "In4.Cu")
		(net "M_J_CPU1_SA_DQ<3>")
	)
	(segment
		(start 159.873696 -199.99198)
		(end 160.102296 -199.99198)
		(width 0.14478)
		(layer "In4.Cu")
		(net "M_J_CPU1_SA_DQ<3>")
	)
	(segment
		(start 181.97576 -199.450706)
		(end 186.625484 -199.450706)
		(width 0.14478)
		(layer "In4.Cu")
		(net "M_J_CPU1_SA_DQ<3>")
	)
	(segment
		(start 186.625484 -199.450706)
		(end 187.060078 -199.8853)
		(width 0.14478)
		(layer "In4.Cu")
		(net "M_J_CPU1_SA_DQ<3>")
	)
	(segment
		(start 159.322008 -200.772268)
		(end 159.671512 -201.121772)
		(width 0.14478)
		(layer "In4.Cu")
		(net "M_J_CPU1_SA_DQ<3>")
	)
	(segment
		(start 131.360672 -226.39909)
		(end 131.383024 -226.315778)
		(width 0.0889)
		(layer "In4.Cu")
		(net "M_J_CPU1_SA_DQ<3>")
	)
	(segment
		(start 143.480028 -221.418404)
		(end 143.480028 -221.235524)
		(width 0.0889)
		(layer "In4.Cu")
		(net "M_J_CPU1_SA_DQ<3>")
	)
	(segment
		(start 143.361156 -221.804484)
		(end 143.361156 -221.537276)
		(width 0.0889)
		(layer "In4.Cu")
		(net "M_J_CPU1_SA_DQ<3>")
	)
	(segment
		(start 158.931864 -201.162412)
		(end 158.931864 -200.933812)
		(width 0.14478)
		(layer "In4.Cu")
		(net "M_J_CPU1_SA_DQ<3>")
	)
	(segment
		(start 158.54172 -201.552556)
		(end 158.891224 -201.90206)
		(width 0.14478)
		(layer "In4.Cu")
		(net "M_J_CPU1_SA_DQ<3>")
	)
	(segment
		(start 143.04772 -222.30969)
		(end 143.077946 -222.292164)
		(width 0.0889)
		(layer "In4.Cu")
		(net "M_J_CPU1_SA_DQ<3>")
	)
	(segment
		(start 135.453374 -226.337114)
		(end 135.461756 -226.34194)
		(width 0.0889)
		(layer "In4.Cu")
		(net "M_J_CPU1_SA_DQ<3>")
	)
	(segment
		(start 136.967722 -226.34194)
		(end 136.976104 -226.337114)
		(width 0.0889)
		(layer "In4.Cu")
		(net "M_J_CPU1_SA_DQ<3>")
	)
	(segment
		(start 141.197838 -225.531934)
		(end 141.23416 -225.510852)
		(width 0.0889)
		(layer "In4.Cu")
		(net "M_J_CPU1_SA_DQ<3>")
	)
	(segment
		(start 158.151576 -201.7141)
		(end 158.31312 -201.552556)
		(width 0.14478)
		(layer "In4.Cu")
		(net "M_J_CPU1_SA_DQ<3>")
	)
	(segment
		(start 173.406308 -200.30059)
		(end 174.256192 -199.450706)
		(width 0.14478)
		(layer "In4.Cu")
		(net "M_J_CPU1_SA_DQ<3>")
	)
	(segment
		(start 142.575534 -223.120966)
		(end 142.608046 -223.10217)
		(width 0.0889)
		(layer "In4.Cu")
		(net "M_J_CPU1_SA_DQ<3>")
	)
	(segment
		(start 160.4518 -200.341484)
		(end 160.6804 -200.341484)
		(width 0.14478)
		(layer "In4.Cu")
		(net "M_J_CPU1_SA_DQ<3>")
	)
	(segment
		(start 159.281368 -201.511916)
		(end 158.931864 -201.162412)
		(width 0.14478)
		(layer "In4.Cu")
		(net "M_J_CPU1_SA_DQ<3>")
	)
	(arc
		(start 131.383024 -226.315778)
		(mid 131.540534 -226.29258)
		(end 131.693412 -226.337114)
		(width 0.0889)
		(layer "In4.Cu")
		(net "M_J_CPU1_SA_DQ<3>")
	)
	(arc
		(start 136.40181 -226.34194)
		(mid 136.684766 -226.418117)
		(end 136.967722 -226.34194)
		(width 0.0889)
		(layer "In4.Cu")
		(net "M_J_CPU1_SA_DQ<3>")
	)
	(arc
		(start 139.78763 -226.34194)
		(mid 139.969881 -226.29159)
		(end 140.15339 -226.337114)
		(width 0.0889)
		(layer "In4.Cu")
		(net "M_J_CPU1_SA_DQ<3>")
	)
	(arc
		(start 133.216142 -226.337114)
		(mid 133.39965 -226.29162)
		(end 133.581902 -226.34194)
		(width 0.0889)
		(layer "In4.Cu")
		(net "M_J_CPU1_SA_DQ<3>")
	)
	(arc
		(start 141.950186 -224.234502)
		(mid 141.991236 -224.064052)
		(end 142.10538 -223.930972)
		(width 0.0889)
		(layer "In4.Cu")
		(net "M_J_CPU1_SA_DQ<3>")
	)
	(arc
		(start 140.161772 -226.34194)
		(mid 140.444728 -226.418117)
		(end 140.727684 -226.34194)
		(width 0.0889)
		(layer "In4.Cu")
		(net "M_J_CPU1_SA_DQ<3>")
	)
	(arc
		(start 138.84783 -226.34194)
		(mid 139.034774 -226.291685)
		(end 139.221718 -226.34194)
		(width 0.0889)
		(layer "In4.Cu")
		(net "M_J_CPU1_SA_DQ<3>")
	)
	(arc
		(start 140.7668 -226.31908)
		(mid 140.945613 -226.11673)
		(end 141.010132 -225.854514)
		(width 0.0889)
		(layer "In4.Cu")
		(net "M_J_CPU1_SA_DQ<3>")
	)
	(arc
		(start 135.087614 -226.34194)
		(mid 135.269865 -226.29159)
		(end 135.453374 -226.337114)
		(width 0.0889)
		(layer "In4.Cu")
		(net "M_J_CPU1_SA_DQ<3>")
	)
	(arc
		(start 142.172944 -223.891602)
		(mid 142.35468 -223.688787)
		(end 142.42034 -223.424496)
		(width 0.0889)
		(layer "In4.Cu")
		(net "M_J_CPU1_SA_DQ<3>")
	)
	(arc
		(start 139.221718 -226.34194)
		(mid 139.504674 -226.418117)
		(end 139.78763 -226.34194)
		(width 0.0889)
		(layer "In4.Cu")
		(net "M_J_CPU1_SA_DQ<3>")
	)
	(arc
		(start 133.581902 -226.34194)
		(mid 133.864858 -226.418117)
		(end 134.147814 -226.34194)
		(width 0.0889)
		(layer "In4.Cu")
		(net "M_J_CPU1_SA_DQ<3>")
	)
	(arc
		(start 136.027668 -226.34194)
		(mid 136.209919 -226.29159)
		(end 136.393428 -226.337114)
		(width 0.0889)
		(layer "In4.Cu")
		(net "M_J_CPU1_SA_DQ<3>")
	)
	(arc
		(start 132.641848 -226.34194)
		(mid 132.924804 -226.418117)
		(end 133.20776 -226.34194)
		(width 0.0889)
		(layer "In4.Cu")
		(net "M_J_CPU1_SA_DQ<3>")
	)
	(arc
		(start 132.276088 -226.337114)
		(mid 132.459596 -226.29162)
		(end 132.641848 -226.34194)
		(width 0.0889)
		(layer "In4.Cu")
		(net "M_J_CPU1_SA_DQ<3>")
	)
	(arc
		(start 136.976104 -226.337114)
		(mid 137.159612 -226.29162)
		(end 137.341864 -226.34194)
		(width 0.0889)
		(layer "In4.Cu")
		(net "M_J_CPU1_SA_DQ<3>")
	)
	(arc
		(start 142.890494 -222.61449)
		(mid 142.93211 -222.443001)
		(end 143.04772 -222.30969)
		(width 0.0889)
		(layer "In4.Cu")
		(net "M_J_CPU1_SA_DQ<3>")
	)
	(arc
		(start 141.480032 -225.044508)
		(mid 141.521287 -224.873537)
		(end 141.635988 -224.740216)
		(width 0.0889)
		(layer "In4.Cu")
		(net "M_J_CPU1_SA_DQ<3>")
	)
	(arc
		(start 134.147814 -226.34194)
		(mid 134.334758 -226.291685)
		(end 134.521702 -226.34194)
		(width 0.0889)
		(layer "In4.Cu")
		(net "M_J_CPU1_SA_DQ<3>")
	)
	(arc
		(start 131.701794 -226.34194)
		(mid 131.98475 -226.418117)
		(end 132.267706 -226.34194)
		(width 0.0889)
		(layer "In4.Cu")
		(net "M_J_CPU1_SA_DQ<3>")
	)
	(arc
		(start 141.706854 -224.699068)
		(mid 141.885667 -224.496718)
		(end 141.950186 -224.234502)
		(width 0.0889)
		(layer "In4.Cu")
		(net "M_J_CPU1_SA_DQ<3>")
	)
	(arc
		(start 141.010132 -225.854514)
		(mid 141.051387 -225.683543)
		(end 141.166088 -225.550222)
		(width 0.0889)
		(layer "In4.Cu")
		(net "M_J_CPU1_SA_DQ<3>")
	)
	(arc
		(start 135.461756 -226.34194)
		(mid 135.744712 -226.418117)
		(end 136.027668 -226.34194)
		(width 0.0889)
		(layer "In4.Cu")
		(net "M_J_CPU1_SA_DQ<3>")
	)
	(arc
		(start 142.641574 -223.082612)
		(mid 142.824394 -222.879584)
		(end 142.890494 -222.61449)
		(width 0.0889)
		(layer "In4.Cu")
		(net "M_J_CPU1_SA_DQ<3>")
	)
	(arc
		(start 137.916158 -226.337114)
		(mid 138.099666 -226.29162)
		(end 138.281918 -226.34194)
		(width 0.0889)
		(layer "In4.Cu")
		(net "M_J_CPU1_SA_DQ<3>")
	)
	(arc
		(start 141.23416 -225.510852)
		(mid 141.414812 -225.308107)
		(end 141.480032 -225.044508)
		(width 0.0889)
		(layer "In4.Cu")
		(net "M_J_CPU1_SA_DQ<3>")
	)
	(arc
		(start 142.42034 -223.424496)
		(mid 142.46139 -223.254046)
		(end 142.575534 -223.120966)
		(width 0.0889)
		(layer "In4.Cu")
		(net "M_J_CPU1_SA_DQ<3>")
	)
	(arc
		(start 134.521702 -226.34194)
		(mid 134.804658 -226.418117)
		(end 135.087614 -226.34194)
		(width 0.0889)
		(layer "In4.Cu")
		(net "M_J_CPU1_SA_DQ<3>")
	)
	(arc
		(start 143.11884 -222.268542)
		(mid 143.296964 -222.066252)
		(end 143.361156 -221.804484)
		(width 0.0889)
		(layer "In4.Cu")
		(net "M_J_CPU1_SA_DQ<3>")
	)
	(arc
		(start 137.341864 -226.34194)
		(mid 137.62482 -226.418117)
		(end 137.907776 -226.34194)
		(width 0.0889)
		(layer "In4.Cu")
		(net "M_J_CPU1_SA_DQ<3>")
	)
	(arc
		(start 138.281918 -226.34194)
		(mid 138.564874 -226.418117)
		(end 138.84783 -226.34194)
		(width 0.0889)
		(layer "In4.Cu")
		(net "M_J_CPU1_SA_DQ<3>")
	)
	(segment
		(start 131.047998 -244.750336)
		(end 131.51485 -244.484398)
		(width 0.10668)
		(layer "F.Cu")
		(net "M_J_CPU1_SA_DQ<31>")
	)
	(segment
		(start 174.512732 -233.460544)
		(end 177.743358 -233.460544)
		(width 0.14478)
		(layer "In4.Cu")
		(net "M_J_CPU1_SA_DQ<31>")
	)
	(segment
		(start 158.900622 -239.194594)
		(end 159.062166 -239.03305)
		(width 0.14478)
		(layer "In4.Cu")
		(net "M_J_CPU1_SA_DQ<31>")
	)
	(segment
		(start 146.969988 -244.100604)
		(end 147.631658 -243.438934)
		(width 0.0889)
		(layer "In4.Cu")
		(net "M_J_CPU1_SA_DQ<31>")
	)
	(segment
		(start 162.142678 -235.09097)
		(end 162.371278 -235.09097)
		(width 0.14478)
		(layer "In4.Cu")
		(net "M_J_CPU1_SA_DQ<31>")
	)
	(segment
		(start 177.743358 -233.460544)
		(end 178.593496 -234.310682)
		(width 0.14478)
		(layer "In4.Cu")
		(net "M_J_CPU1_SA_DQ<31>")
	)
	(segment
		(start 162.021774 -236.073442)
		(end 162.183318 -235.911898)
		(width 0.14478)
		(layer "In4.Cu")
		(net "M_J_CPU1_SA_DQ<31>")
	)
	(segment
		(start 141.093444 -244.156992)
		(end 141.101826 -244.161818)
		(width 0.0889)
		(layer "In4.Cu")
		(net "M_J_CPU1_SA_DQ<31>")
	)
	(segment
		(start 166.569136 -234.310682)
		(end 167.419274 -233.460544)
		(width 0.14478)
		(layer "In4.Cu")
		(net "M_J_CPU1_SA_DQ<31>")
	)
	(segment
		(start 131.360672 -244.218968)
		(end 131.383024 -244.135656)
		(width 0.0889)
		(layer "In4.Cu")
		(net "M_J_CPU1_SA_DQ<31>")
	)
	(segment
		(start 160.232598 -237.634018)
		(end 160.461198 -237.634018)
		(width 0.14478)
		(layer "In4.Cu")
		(net "M_J_CPU1_SA_DQ<31>")
	)
	(segment
		(start 161.241486 -236.85373)
		(end 161.40303 -236.692186)
		(width 0.14478)
		(layer "In4.Cu")
		(net "M_J_CPU1_SA_DQ<31>")
	)
	(segment
		(start 161.793174 -236.073442)
		(end 162.021774 -236.073442)
		(width 0.14478)
		(layer "In4.Cu")
		(net "M_J_CPU1_SA_DQ<31>")
	)
	(segment
		(start 146.17446 -244.238272)
		(end 146.312128 -244.100604)
		(width 0.0889)
		(layer "In4.Cu")
		(net "M_J_CPU1_SA_DQ<31>")
	)
	(segment
		(start 162.183318 -235.911898)
		(end 162.183318 -235.683298)
		(width 0.14478)
		(layer "In4.Cu")
		(net "M_J_CPU1_SA_DQ<31>")
	)
	(segment
		(start 143.547592 -244.161818)
		(end 143.555974 -244.156992)
		(width 0.0889)
		(layer "In4.Cu")
		(net "M_J_CPU1_SA_DQ<31>")
	)
	(segment
		(start 182.06466 -233.460544)
		(end 186.63539 -233.460544)
		(width 0.14478)
		(layer "In4.Cu")
		(net "M_J_CPU1_SA_DQ<31>")
	)
	(segment
		(start 161.40303 -236.463586)
		(end 161.200846 -236.261402)
		(width 0.14478)
		(layer "In4.Cu")
		(net "M_J_CPU1_SA_DQ<31>")
	)
	(segment
		(start 159.64027 -237.821978)
		(end 159.64027 -237.593378)
		(width 0.14478)
		(layer "In4.Cu")
		(net "M_J_CPU1_SA_DQ<31>")
	)
	(segment
		(start 159.842454 -238.252762)
		(end 159.842454 -238.024162)
		(width 0.14478)
		(layer "In4.Cu")
		(net "M_J_CPU1_SA_DQ<31>")
	)
	(segment
		(start 161.981134 -235.252514)
		(end 162.142678 -235.09097)
		(width 0.14478)
		(layer "In4.Cu")
		(net "M_J_CPU1_SA_DQ<31>")
	)
	(segment
		(start 131.693412 -244.156992)
		(end 131.701794 -244.161818)
		(width 0.0889)
		(layer "In4.Cu")
		(net "M_J_CPU1_SA_DQ<31>")
	)
	(segment
		(start 158.241238 -238.99241)
		(end 158.469838 -238.99241)
		(width 0.14478)
		(layer "In4.Cu")
		(net "M_J_CPU1_SA_DQ<31>")
	)
	(segment
		(start 160.622742 -237.243874)
		(end 160.420558 -237.04169)
		(width 0.14478)
		(layer "In4.Cu")
		(net "M_J_CPU1_SA_DQ<31>")
	)
	(segment
		(start 169.7609 -233.460544)
		(end 170.611038 -234.310682)
		(width 0.14478)
		(layer "In4.Cu")
		(net "M_J_CPU1_SA_DQ<31>")
	)
	(segment
		(start 159.021526 -238.212122)
		(end 159.250126 -238.212122)
		(width 0.14478)
		(layer "In4.Cu")
		(net "M_J_CPU1_SA_DQ<31>")
	)
	(segment
		(start 162.761422 -234.472226)
		(end 162.922966 -234.310682)
		(width 0.14478)
		(layer "In4.Cu")
		(net "M_J_CPU1_SA_DQ<31>")
	)
	(segment
		(start 136.967722 -244.161818)
		(end 136.976104 -244.156992)
		(width 0.0889)
		(layer "In4.Cu")
		(net "M_J_CPU1_SA_DQ<31>")
	)
	(segment
		(start 133.20776 -244.161818)
		(end 133.216142 -244.156992)
		(width 0.0889)
		(layer "In4.Cu")
		(net "M_J_CPU1_SA_DQ<31>")
	)
	(segment
		(start 160.810702 -236.651546)
		(end 161.012886 -236.85373)
		(width 0.14478)
		(layer "In4.Cu")
		(net "M_J_CPU1_SA_DQ<31>")
	)
	(segment
		(start 161.36239 -235.871258)
		(end 161.59099 -235.871258)
		(width 0.14478)
		(layer "In4.Cu")
		(net "M_J_CPU1_SA_DQ<31>")
	)
	(segment
		(start 161.59099 -235.871258)
		(end 161.793174 -236.073442)
		(width 0.14478)
		(layer "In4.Cu")
		(net "M_J_CPU1_SA_DQ<31>")
	)
	(segment
		(start 186.63539 -233.460544)
		(end 187.060078 -233.885232)
		(width 0.14478)
		(layer "In4.Cu")
		(net "M_J_CPU1_SA_DQ<31>")
	)
	(segment
		(start 136.393428 -244.156992)
		(end 136.40181 -244.161818)
		(width 0.0889)
		(layer "In4.Cu")
		(net "M_J_CPU1_SA_DQ<31>")
	)
	(segment
		(start 137.907776 -244.161818)
		(end 137.916158 -244.156992)
		(width 0.0889)
		(layer "In4.Cu")
		(net "M_J_CPU1_SA_DQ<31>")
	)
	(segment
		(start 132.267706 -244.161818)
		(end 132.276088 -244.156992)
		(width 0.0889)
		(layer "In4.Cu")
		(net "M_J_CPU1_SA_DQ<31>")
	)
	(segment
		(start 131.51485 -244.484398)
		(end 131.360672 -244.218968)
		(width 0.0889)
		(layer "In4.Cu")
		(net "M_J_CPU1_SA_DQ<31>")
	)
	(segment
		(start 159.801814 -237.431834)
		(end 160.030414 -237.431834)
		(width 0.14478)
		(layer "In4.Cu")
		(net "M_J_CPU1_SA_DQ<31>")
	)
	(segment
		(start 145.144744 -244.238272)
		(end 146.17446 -244.238272)
		(width 0.0889)
		(layer "In4.Cu")
		(net "M_J_CPU1_SA_DQ<31>")
	)
	(segment
		(start 161.40303 -236.692186)
		(end 161.40303 -236.463586)
		(width 0.14478)
		(layer "In4.Cu")
		(net "M_J_CPU1_SA_DQ<31>")
	)
	(segment
		(start 160.030414 -237.431834)
		(end 160.232598 -237.634018)
		(width 0.14478)
		(layer "In4.Cu")
		(net "M_J_CPU1_SA_DQ<31>")
	)
	(segment
		(start 160.420558 -237.04169)
		(end 160.420558 -236.81309)
		(width 0.14478)
		(layer "In4.Cu")
		(net "M_J_CPU1_SA_DQ<31>")
	)
	(segment
		(start 147.92071 -243.438934)
		(end 153.794714 -243.438934)
		(width 0.14478)
		(layer "In4.Cu")
		(net "M_J_CPU1_SA_DQ<31>")
	)
	(segment
		(start 173.662594 -234.310682)
		(end 174.512732 -233.460544)
		(width 0.14478)
		(layer "In4.Cu")
		(net "M_J_CPU1_SA_DQ<31>")
	)
	(segment
		(start 144.47393 -244.170454)
		(end 144.488662 -244.161818)
		(width 0.0889)
		(layer "In4.Cu")
		(net "M_J_CPU1_SA_DQ<31>")
	)
	(segment
		(start 162.183318 -235.683298)
		(end 161.981134 -235.481114)
		(width 0.14478)
		(layer "In4.Cu")
		(net "M_J_CPU1_SA_DQ<31>")
	)
	(segment
		(start 162.922966 -234.310682)
		(end 166.569136 -234.310682)
		(width 0.14478)
		(layer "In4.Cu")
		(net "M_J_CPU1_SA_DQ<31>")
	)
	(segment
		(start 160.461198 -237.634018)
		(end 160.622742 -237.472474)
		(width 0.14478)
		(layer "In4.Cu")
		(net "M_J_CPU1_SA_DQ<31>")
	)
	(segment
		(start 158.859982 -238.602266)
		(end 158.859982 -238.373666)
		(width 0.14478)
		(layer "In4.Cu")
		(net "M_J_CPU1_SA_DQ<31>")
	)
	(segment
		(start 153.794714 -243.438934)
		(end 158.241238 -238.99241)
		(width 0.14478)
		(layer "In4.Cu")
		(net "M_J_CPU1_SA_DQ<31>")
	)
	(segment
		(start 158.859982 -238.373666)
		(end 159.021526 -238.212122)
		(width 0.14478)
		(layer "In4.Cu")
		(net "M_J_CPU1_SA_DQ<31>")
	)
	(segment
		(start 140.15339 -244.156992)
		(end 140.161772 -244.161818)
		(width 0.0889)
		(layer "In4.Cu")
		(net "M_J_CPU1_SA_DQ<31>")
	)
	(segment
		(start 161.200846 -236.032802)
		(end 161.36239 -235.871258)
		(width 0.14478)
		(layer "In4.Cu")
		(net "M_J_CPU1_SA_DQ<31>")
	)
	(segment
		(start 159.68091 -238.414306)
		(end 159.842454 -238.252762)
		(width 0.14478)
		(layer "In4.Cu")
		(net "M_J_CPU1_SA_DQ<31>")
	)
	(segment
		(start 178.593496 -234.310682)
		(end 181.214522 -234.310682)
		(width 0.14478)
		(layer "In4.Cu")
		(net "M_J_CPU1_SA_DQ<31>")
	)
	(segment
		(start 147.631658 -243.438934)
		(end 147.92071 -243.438934)
		(width 0.0889)
		(layer "In4.Cu")
		(net "M_J_CPU1_SA_DQ<31>")
	)
	(segment
		(start 181.214522 -234.310682)
		(end 182.06466 -233.460544)
		(width 0.14478)
		(layer "In4.Cu")
		(net "M_J_CPU1_SA_DQ<31>")
	)
	(segment
		(start 162.371278 -235.09097)
		(end 162.573462 -235.293154)
		(width 0.14478)
		(layer "In4.Cu")
		(net "M_J_CPU1_SA_DQ<31>")
	)
	(segment
		(start 162.802062 -235.293154)
		(end 162.963606 -235.13161)
		(width 0.14478)
		(layer "In4.Cu")
		(net "M_J_CPU1_SA_DQ<31>")
	)
	(segment
		(start 159.062166 -239.03305)
		(end 159.062166 -238.80445)
		(width 0.14478)
		(layer "In4.Cu")
		(net "M_J_CPU1_SA_DQ<31>")
	)
	(segment
		(start 159.062166 -238.80445)
		(end 158.859982 -238.602266)
		(width 0.14478)
		(layer "In4.Cu")
		(net "M_J_CPU1_SA_DQ<31>")
	)
	(segment
		(start 159.250126 -238.212122)
		(end 159.45231 -238.414306)
		(width 0.14478)
		(layer "In4.Cu")
		(net "M_J_CPU1_SA_DQ<31>")
	)
	(segment
		(start 162.573462 -235.293154)
		(end 162.802062 -235.293154)
		(width 0.14478)
		(layer "In4.Cu")
		(net "M_J_CPU1_SA_DQ<31>")
	)
	(segment
		(start 162.963606 -235.13161)
		(end 162.963606 -234.90301)
		(width 0.14478)
		(layer "In4.Cu")
		(net "M_J_CPU1_SA_DQ<31>")
	)
	(segment
		(start 160.582102 -236.651546)
		(end 160.810702 -236.651546)
		(width 0.14478)
		(layer "In4.Cu")
		(net "M_J_CPU1_SA_DQ<31>")
	)
	(segment
		(start 159.64027 -237.593378)
		(end 159.801814 -237.431834)
		(width 0.14478)
		(layer "In4.Cu")
		(net "M_J_CPU1_SA_DQ<31>")
	)
	(segment
		(start 170.611038 -234.310682)
		(end 173.662594 -234.310682)
		(width 0.14478)
		(layer "In4.Cu")
		(net "M_J_CPU1_SA_DQ<31>")
	)
	(segment
		(start 161.012886 -236.85373)
		(end 161.241486 -236.85373)
		(width 0.14478)
		(layer "In4.Cu")
		(net "M_J_CPU1_SA_DQ<31>")
	)
	(segment
		(start 161.981134 -235.481114)
		(end 161.981134 -235.252514)
		(width 0.14478)
		(layer "In4.Cu")
		(net "M_J_CPU1_SA_DQ<31>")
	)
	(segment
		(start 158.469838 -238.99241)
		(end 158.672022 -239.194594)
		(width 0.14478)
		(layer "In4.Cu")
		(net "M_J_CPU1_SA_DQ<31>")
	)
	(segment
		(start 158.672022 -239.194594)
		(end 158.900622 -239.194594)
		(width 0.14478)
		(layer "In4.Cu")
		(net "M_J_CPU1_SA_DQ<31>")
	)
	(segment
		(start 141.667738 -244.161818)
		(end 141.67612 -244.156992)
		(width 0.0889)
		(layer "In4.Cu")
		(net "M_J_CPU1_SA_DQ<31>")
	)
	(segment
		(start 167.419274 -233.460544)
		(end 169.7609 -233.460544)
		(width 0.14478)
		(layer "In4.Cu")
		(net "M_J_CPU1_SA_DQ<31>")
	)
	(segment
		(start 135.453374 -244.156992)
		(end 135.461756 -244.161818)
		(width 0.0889)
		(layer "In4.Cu")
		(net "M_J_CPU1_SA_DQ<31>")
	)
	(segment
		(start 162.761422 -234.700826)
		(end 162.761422 -234.472226)
		(width 0.14478)
		(layer "In4.Cu")
		(net "M_J_CPU1_SA_DQ<31>")
	)
	(segment
		(start 159.842454 -238.024162)
		(end 159.64027 -237.821978)
		(width 0.14478)
		(layer "In4.Cu")
		(net "M_J_CPU1_SA_DQ<31>")
	)
	(segment
		(start 160.420558 -236.81309)
		(end 160.582102 -236.651546)
		(width 0.14478)
		(layer "In4.Cu")
		(net "M_J_CPU1_SA_DQ<31>")
	)
	(segment
		(start 146.312128 -244.100604)
		(end 146.969988 -244.100604)
		(width 0.0889)
		(layer "In4.Cu")
		(net "M_J_CPU1_SA_DQ<31>")
	)
	(segment
		(start 159.45231 -238.414306)
		(end 159.68091 -238.414306)
		(width 0.14478)
		(layer "In4.Cu")
		(net "M_J_CPU1_SA_DQ<31>")
	)
	(segment
		(start 160.622742 -237.472474)
		(end 160.622742 -237.243874)
		(width 0.14478)
		(layer "In4.Cu")
		(net "M_J_CPU1_SA_DQ<31>")
	)
	(segment
		(start 161.200846 -236.261402)
		(end 161.200846 -236.032802)
		(width 0.14478)
		(layer "In4.Cu")
		(net "M_J_CPU1_SA_DQ<31>")
	)
	(segment
		(start 162.963606 -234.90301)
		(end 162.761422 -234.700826)
		(width 0.14478)
		(layer "In4.Cu")
		(net "M_J_CPU1_SA_DQ<31>")
	)
	(arc
		(start 139.221718 -244.161818)
		(mid 139.504674 -244.237995)
		(end 139.78763 -244.161818)
		(width 0.0889)
		(layer "In4.Cu")
		(net "M_J_CPU1_SA_DQ<31>")
	)
	(arc
		(start 138.84783 -244.161818)
		(mid 139.034774 -244.111563)
		(end 139.221718 -244.161818)
		(width 0.0889)
		(layer "In4.Cu")
		(net "M_J_CPU1_SA_DQ<31>")
	)
	(arc
		(start 142.98168 -244.161818)
		(mid 143.264636 -244.237995)
		(end 143.547592 -244.161818)
		(width 0.0889)
		(layer "In4.Cu")
		(net "M_J_CPU1_SA_DQ<31>")
	)
	(arc
		(start 141.101826 -244.161818)
		(mid 141.384782 -244.237995)
		(end 141.667738 -244.161818)
		(width 0.0889)
		(layer "In4.Cu")
		(net "M_J_CPU1_SA_DQ<31>")
	)
	(arc
		(start 137.341864 -244.161818)
		(mid 137.62482 -244.237995)
		(end 137.907776 -244.161818)
		(width 0.0889)
		(layer "In4.Cu")
		(net "M_J_CPU1_SA_DQ<31>")
	)
	(arc
		(start 138.281918 -244.161818)
		(mid 138.564874 -244.237995)
		(end 138.84783 -244.161818)
		(width 0.0889)
		(layer "In4.Cu")
		(net "M_J_CPU1_SA_DQ<31>")
	)
	(arc
		(start 142.607792 -244.161818)
		(mid 142.794736 -244.111563)
		(end 142.98168 -244.161818)
		(width 0.0889)
		(layer "In4.Cu")
		(net "M_J_CPU1_SA_DQ<31>")
	)
	(arc
		(start 136.40181 -244.161818)
		(mid 136.684766 -244.237995)
		(end 136.967722 -244.161818)
		(width 0.0889)
		(layer "In4.Cu")
		(net "M_J_CPU1_SA_DQ<31>")
	)
	(arc
		(start 144.84858 -244.154198)
		(mid 144.99081 -244.216852)
		(end 145.144744 -244.238272)
		(width 0.0889)
		(layer "In4.Cu")
		(net "M_J_CPU1_SA_DQ<31>")
	)
	(arc
		(start 143.922242 -244.161818)
		(mid 144.196948 -244.238182)
		(end 144.47393 -244.170454)
		(width 0.0889)
		(layer "In4.Cu")
		(net "M_J_CPU1_SA_DQ<31>")
	)
	(arc
		(start 140.727684 -244.161818)
		(mid 140.909935 -244.111468)
		(end 141.093444 -244.156992)
		(width 0.0889)
		(layer "In4.Cu")
		(net "M_J_CPU1_SA_DQ<31>")
	)
	(arc
		(start 132.641848 -244.161818)
		(mid 132.924804 -244.237995)
		(end 133.20776 -244.161818)
		(width 0.0889)
		(layer "In4.Cu")
		(net "M_J_CPU1_SA_DQ<31>")
	)
	(arc
		(start 131.701794 -244.161818)
		(mid 131.98475 -244.237995)
		(end 132.267706 -244.161818)
		(width 0.0889)
		(layer "In4.Cu")
		(net "M_J_CPU1_SA_DQ<31>")
	)
	(arc
		(start 132.276088 -244.156992)
		(mid 132.459596 -244.111498)
		(end 132.641848 -244.161818)
		(width 0.0889)
		(layer "In4.Cu")
		(net "M_J_CPU1_SA_DQ<31>")
	)
	(arc
		(start 144.488662 -244.161818)
		(mid 144.667649 -244.111648)
		(end 144.84858 -244.154198)
		(width 0.0889)
		(layer "In4.Cu")
		(net "M_J_CPU1_SA_DQ<31>")
	)
	(arc
		(start 133.581902 -244.161818)
		(mid 133.864858 -244.237995)
		(end 134.147814 -244.161818)
		(width 0.0889)
		(layer "In4.Cu")
		(net "M_J_CPU1_SA_DQ<31>")
	)
	(arc
		(start 131.383024 -244.135656)
		(mid 131.540534 -244.112458)
		(end 131.693412 -244.156992)
		(width 0.0889)
		(layer "In4.Cu")
		(net "M_J_CPU1_SA_DQ<31>")
	)
	(arc
		(start 140.161772 -244.161818)
		(mid 140.444728 -244.237995)
		(end 140.727684 -244.161818)
		(width 0.0889)
		(layer "In4.Cu")
		(net "M_J_CPU1_SA_DQ<31>")
	)
	(arc
		(start 137.916158 -244.156992)
		(mid 138.099666 -244.111498)
		(end 138.281918 -244.161818)
		(width 0.0889)
		(layer "In4.Cu")
		(net "M_J_CPU1_SA_DQ<31>")
	)
	(arc
		(start 135.087614 -244.161818)
		(mid 135.269865 -244.111468)
		(end 135.453374 -244.156992)
		(width 0.0889)
		(layer "In4.Cu")
		(net "M_J_CPU1_SA_DQ<31>")
	)
	(arc
		(start 143.555974 -244.156992)
		(mid 143.739736 -244.111376)
		(end 143.922242 -244.161818)
		(width 0.0889)
		(layer "In4.Cu")
		(net "M_J_CPU1_SA_DQ<31>")
	)
	(arc
		(start 136.976104 -244.156992)
		(mid 137.159612 -244.111498)
		(end 137.341864 -244.161818)
		(width 0.0889)
		(layer "In4.Cu")
		(net "M_J_CPU1_SA_DQ<31>")
	)
	(arc
		(start 136.027668 -244.161818)
		(mid 136.209919 -244.111468)
		(end 136.393428 -244.156992)
		(width 0.0889)
		(layer "In4.Cu")
		(net "M_J_CPU1_SA_DQ<31>")
	)
	(arc
		(start 134.521702 -244.161818)
		(mid 134.804658 -244.237995)
		(end 135.087614 -244.161818)
		(width 0.0889)
		(layer "In4.Cu")
		(net "M_J_CPU1_SA_DQ<31>")
	)
	(arc
		(start 133.216142 -244.156992)
		(mid 133.39965 -244.111498)
		(end 133.581902 -244.161818)
		(width 0.0889)
		(layer "In4.Cu")
		(net "M_J_CPU1_SA_DQ<31>")
	)
	(arc
		(start 139.78763 -244.161818)
		(mid 139.969881 -244.111468)
		(end 140.15339 -244.156992)
		(width 0.0889)
		(layer "In4.Cu")
		(net "M_J_CPU1_SA_DQ<31>")
	)
	(arc
		(start 142.04188 -244.161818)
		(mid 142.324836 -244.237995)
		(end 142.607792 -244.161818)
		(width 0.0889)
		(layer "In4.Cu")
		(net "M_J_CPU1_SA_DQ<31>")
	)
	(arc
		(start 135.461756 -244.161818)
		(mid 135.744712 -244.237995)
		(end 136.027668 -244.161818)
		(width 0.0889)
		(layer "In4.Cu")
		(net "M_J_CPU1_SA_DQ<31>")
	)
	(arc
		(start 134.147814 -244.161818)
		(mid 134.334758 -244.111563)
		(end 134.521702 -244.161818)
		(width 0.0889)
		(layer "In4.Cu")
		(net "M_J_CPU1_SA_DQ<31>")
	)
	(arc
		(start 141.67612 -244.156992)
		(mid 141.859628 -244.111498)
		(end 142.04188 -244.161818)
		(width 0.0889)
		(layer "In4.Cu")
		(net "M_J_CPU1_SA_DQ<31>")
	)
	(segment
		(start 132.457952 -243.94033)
		(end 132.924804 -243.674392)
		(width 0.10668)
		(layer "F.Cu")
		(net "M_J_CPU1_SA_DQ<30>")
	)
	(segment
		(start 153.644092 -242.088924)
		(end 153.445972 -241.890804)
		(width 0.14478)
		(layer "In4.Cu")
		(net "M_J_CPU1_SA_DQ<30>")
	)
	(segment
		(start 153.644092 -242.317524)
		(end 153.644092 -242.088924)
		(width 0.14478)
		(layer "In4.Cu")
		(net "M_J_CPU1_SA_DQ<30>")
	)
	(segment
		(start 166.982394 -232.61066)
		(end 167.832532 -231.760522)
		(width 0.14478)
		(layer "In4.Cu")
		(net "M_J_CPU1_SA_DQ<30>")
	)
	(segment
		(start 155.823412 -240.138204)
		(end 155.984956 -239.97666)
		(width 0.14478)
		(layer "In4.Cu")
		(net "M_J_CPU1_SA_DQ<30>")
	)
	(segment
		(start 163.350956 -232.61066)
		(end 166.982394 -232.61066)
		(width 0.14478)
		(layer "In4.Cu")
		(net "M_J_CPU1_SA_DQ<30>")
	)
	(segment
		(start 154.262836 -241.69878)
		(end 154.42438 -241.537236)
		(width 0.14478)
		(layer "In4.Cu")
		(net "M_J_CPU1_SA_DQ<30>")
	)
	(segment
		(start 143.077692 -243.351812)
		(end 143.086074 -243.346986)
		(width 0.0889)
		(layer "In4.Cu")
		(net "M_J_CPU1_SA_DQ<30>")
	)
	(segment
		(start 157.545532 -238.416084)
		(end 157.545532 -238.187484)
		(width 0.14478)
		(layer "In4.Cu")
		(net "M_J_CPU1_SA_DQ<30>")
	)
	(segment
		(start 155.204668 -240.756948)
		(end 155.204668 -240.528348)
		(width 0.14478)
		(layer "In4.Cu")
		(net "M_J_CPU1_SA_DQ<30>")
	)
	(segment
		(start 153.445972 -241.662204)
		(end 153.607516 -241.50066)
		(width 0.14478)
		(layer "In4.Cu")
		(net "M_J_CPU1_SA_DQ<30>")
	)
	(segment
		(start 153.836116 -241.50066)
		(end 154.034236 -241.69878)
		(width 0.14478)
		(layer "In4.Cu")
		(net "M_J_CPU1_SA_DQ<30>")
	)
	(segment
		(start 140.257784 -243.351812)
		(end 140.266166 -243.346986)
		(width 0.0889)
		(layer "In4.Cu")
		(net "M_J_CPU1_SA_DQ<30>")
	)
	(segment
		(start 155.786836 -239.54994)
		(end 155.786836 -239.32134)
		(width 0.14478)
		(layer "In4.Cu")
		(net "M_J_CPU1_SA_DQ<30>")
	)
	(segment
		(start 145.144744 -243.301012)
		(end 146.21256 -243.301012)
		(width 0.0889)
		(layer "In4.Cu")
		(net "M_J_CPU1_SA_DQ<30>")
	)
	(segment
		(start 177.53203 -231.760522)
		(end 178.382168 -232.61066)
		(width 0.14478)
		(layer "In4.Cu")
		(net "M_J_CPU1_SA_DQ<30>")
	)
	(segment
		(start 146.886168 -243.493544)
		(end 147.226528 -243.153184)
		(width 0.0889)
		(layer "In4.Cu")
		(net "M_J_CPU1_SA_DQ<30>")
	)
	(segment
		(start 132.770626 -243.408962)
		(end 132.792978 -243.32565)
		(width 0.0889)
		(layer "In4.Cu")
		(net "M_J_CPU1_SA_DQ<30>")
	)
	(segment
		(start 154.034236 -241.69878)
		(end 154.262836 -241.69878)
		(width 0.14478)
		(layer "In4.Cu")
		(net "M_J_CPU1_SA_DQ<30>")
	)
	(segment
		(start 173.496986 -232.61066)
		(end 174.347124 -231.760522)
		(width 0.14478)
		(layer "In4.Cu")
		(net "M_J_CPU1_SA_DQ<30>")
	)
	(segment
		(start 143.451834 -243.351812)
		(end 143.462248 -243.357908)
		(width 0.0889)
		(layer "In4.Cu")
		(net "M_J_CPU1_SA_DQ<30>")
	)
	(segment
		(start 158.289244 -236.818932)
		(end 158.517844 -236.818932)
		(width 0.14478)
		(layer "In4.Cu")
		(net "M_J_CPU1_SA_DQ<30>")
	)
	(segment
		(start 182.242968 -231.760522)
		(end 186.63539 -231.760522)
		(width 0.14478)
		(layer "In4.Cu")
		(net "M_J_CPU1_SA_DQ<30>")
	)
	(segment
		(start 156.3751 -239.357916)
		(end 156.6037 -239.357916)
		(width 0.14478)
		(layer "In4.Cu")
		(net "M_J_CPU1_SA_DQ<30>")
	)
	(segment
		(start 156.17698 -239.159796)
		(end 156.3751 -239.357916)
		(width 0.14478)
		(layer "In4.Cu")
		(net "M_J_CPU1_SA_DQ<30>")
	)
	(segment
		(start 154.814524 -240.918492)
		(end 155.043124 -240.918492)
		(width 0.14478)
		(layer "In4.Cu")
		(net "M_J_CPU1_SA_DQ<30>")
	)
	(segment
		(start 154.616404 -240.720372)
		(end 154.814524 -240.918492)
		(width 0.14478)
		(layer "In4.Cu")
		(net "M_J_CPU1_SA_DQ<30>")
	)
	(segment
		(start 156.765244 -239.196372)
		(end 156.765244 -238.967772)
		(width 0.14478)
		(layer "In4.Cu")
		(net "M_J_CPU1_SA_DQ<30>")
	)
	(segment
		(start 158.32582 -237.635796)
		(end 158.32582 -237.407196)
		(width 0.14478)
		(layer "In4.Cu")
		(net "M_J_CPU1_SA_DQ<30>")
	)
	(segment
		(start 154.42438 -241.308636)
		(end 154.22626 -241.110516)
		(width 0.14478)
		(layer "In4.Cu")
		(net "M_J_CPU1_SA_DQ<30>")
	)
	(segment
		(start 181.39283 -232.61066)
		(end 182.242968 -231.760522)
		(width 0.14478)
		(layer "In4.Cu")
		(net "M_J_CPU1_SA_DQ<30>")
	)
	(segment
		(start 147.95627 -242.524534)
		(end 153.437082 -242.524534)
		(width 0.14478)
		(layer "In4.Cu")
		(net "M_J_CPU1_SA_DQ<30>")
	)
	(segment
		(start 158.32582 -237.407196)
		(end 158.1277 -237.209076)
		(width 0.14478)
		(layer "In4.Cu")
		(net "M_J_CPU1_SA_DQ<30>")
	)
	(segment
		(start 156.765244 -238.967772)
		(end 156.567124 -238.769652)
		(width 0.14478)
		(layer "In4.Cu")
		(net "M_J_CPU1_SA_DQ<30>")
	)
	(segment
		(start 154.22626 -241.110516)
		(end 154.22626 -240.881916)
		(width 0.14478)
		(layer "In4.Cu")
		(net "M_J_CPU1_SA_DQ<30>")
	)
	(segment
		(start 154.387804 -240.720372)
		(end 154.616404 -240.720372)
		(width 0.14478)
		(layer "In4.Cu")
		(net "M_J_CPU1_SA_DQ<30>")
	)
	(segment
		(start 134.617714 -243.351812)
		(end 134.626096 -243.346986)
		(width 0.0889)
		(layer "In4.Cu")
		(net "M_J_CPU1_SA_DQ<30>")
	)
	(segment
		(start 157.347412 -237.989364)
		(end 157.347412 -237.760764)
		(width 0.14478)
		(layer "In4.Cu")
		(net "M_J_CPU1_SA_DQ<30>")
	)
	(segment
		(start 147.595082 -242.524534)
		(end 147.95627 -242.524534)
		(width 0.0889)
		(layer "In4.Cu")
		(net "M_J_CPU1_SA_DQ<30>")
	)
	(segment
		(start 157.383988 -238.577628)
		(end 157.545532 -238.416084)
		(width 0.14478)
		(layer "In4.Cu")
		(net "M_J_CPU1_SA_DQ<30>")
	)
	(segment
		(start 138.743436 -243.346986)
		(end 138.751818 -243.351812)
		(width 0.0889)
		(layer "In4.Cu")
		(net "M_J_CPU1_SA_DQ<30>")
	)
	(segment
		(start 135.557768 -243.351812)
		(end 135.56615 -243.346986)
		(width 0.0889)
		(layer "In4.Cu")
		(net "M_J_CPU1_SA_DQ<30>")
	)
	(segment
		(start 155.984956 -239.74806)
		(end 155.786836 -239.54994)
		(width 0.14478)
		(layer "In4.Cu")
		(net "M_J_CPU1_SA_DQ<30>")
	)
	(segment
		(start 155.94838 -239.159796)
		(end 156.17698 -239.159796)
		(width 0.14478)
		(layer "In4.Cu")
		(net "M_J_CPU1_SA_DQ<30>")
	)
	(segment
		(start 155.168092 -239.940084)
		(end 155.396692 -239.940084)
		(width 0.14478)
		(layer "In4.Cu")
		(net "M_J_CPU1_SA_DQ<30>")
	)
	(segment
		(start 153.437082 -242.524534)
		(end 153.644092 -242.317524)
		(width 0.14478)
		(layer "In4.Cu")
		(net "M_J_CPU1_SA_DQ<30>")
	)
	(segment
		(start 170.43908 -232.61066)
		(end 173.496986 -232.61066)
		(width 0.14478)
		(layer "In4.Cu")
		(net "M_J_CPU1_SA_DQ<30>")
	)
	(segment
		(start 155.984956 -239.97666)
		(end 155.984956 -239.74806)
		(width 0.14478)
		(layer "In4.Cu")
		(net "M_J_CPU1_SA_DQ<30>")
	)
	(segment
		(start 167.832532 -231.760522)
		(end 169.588942 -231.760522)
		(width 0.14478)
		(layer "In4.Cu")
		(net "M_J_CPU1_SA_DQ<30>")
	)
	(segment
		(start 146.405092 -243.493544)
		(end 146.886168 -243.493544)
		(width 0.0889)
		(layer "In4.Cu")
		(net "M_J_CPU1_SA_DQ<30>")
	)
	(segment
		(start 169.588942 -231.760522)
		(end 170.43908 -232.61066)
		(width 0.14478)
		(layer "In4.Cu")
		(net "M_J_CPU1_SA_DQ<30>")
	)
	(segment
		(start 158.715964 -237.017052)
		(end 158.944564 -237.017052)
		(width 0.14478)
		(layer "In4.Cu")
		(net "M_J_CPU1_SA_DQ<30>")
	)
	(segment
		(start 134.04342 -243.346986)
		(end 134.051802 -243.351812)
		(width 0.0889)
		(layer "In4.Cu")
		(net "M_J_CPU1_SA_DQ<30>")
	)
	(segment
		(start 155.006548 -240.330228)
		(end 155.006548 -240.101628)
		(width 0.14478)
		(layer "In4.Cu")
		(net "M_J_CPU1_SA_DQ<30>")
	)
	(segment
		(start 157.347412 -237.760764)
		(end 157.508956 -237.59922)
		(width 0.14478)
		(layer "In4.Cu")
		(net "M_J_CPU1_SA_DQ<30>")
	)
	(segment
		(start 158.1277 -236.980476)
		(end 158.289244 -236.818932)
		(width 0.14478)
		(layer "In4.Cu")
		(net "M_J_CPU1_SA_DQ<30>")
	)
	(segment
		(start 155.594812 -240.138204)
		(end 155.823412 -240.138204)
		(width 0.14478)
		(layer "In4.Cu")
		(net "M_J_CPU1_SA_DQ<30>")
	)
	(segment
		(start 157.508956 -237.59922)
		(end 157.737556 -237.59922)
		(width 0.14478)
		(layer "In4.Cu")
		(net "M_J_CPU1_SA_DQ<30>")
	)
	(segment
		(start 153.607516 -241.50066)
		(end 153.836116 -241.50066)
		(width 0.14478)
		(layer "In4.Cu")
		(net "M_J_CPU1_SA_DQ<30>")
	)
	(segment
		(start 174.347124 -231.760522)
		(end 177.53203 -231.760522)
		(width 0.14478)
		(layer "In4.Cu")
		(net "M_J_CPU1_SA_DQ<30>")
	)
	(segment
		(start 147.226528 -243.153184)
		(end 147.226528 -242.893088)
		(width 0.0889)
		(layer "In4.Cu")
		(net "M_J_CPU1_SA_DQ<30>")
	)
	(segment
		(start 156.567124 -238.769652)
		(end 156.567124 -238.541052)
		(width 0.14478)
		(layer "In4.Cu")
		(net "M_J_CPU1_SA_DQ<30>")
	)
	(segment
		(start 155.396692 -239.940084)
		(end 155.594812 -240.138204)
		(width 0.14478)
		(layer "In4.Cu")
		(net "M_J_CPU1_SA_DQ<30>")
	)
	(segment
		(start 154.42438 -241.537236)
		(end 154.42438 -241.308636)
		(width 0.14478)
		(layer "In4.Cu")
		(net "M_J_CPU1_SA_DQ<30>")
	)
	(segment
		(start 133.103366 -243.346986)
		(end 133.111748 -243.351812)
		(width 0.0889)
		(layer "In4.Cu")
		(net "M_J_CPU1_SA_DQ<30>")
	)
	(segment
		(start 154.22626 -240.881916)
		(end 154.387804 -240.720372)
		(width 0.14478)
		(layer "In4.Cu")
		(net "M_J_CPU1_SA_DQ<30>")
	)
	(segment
		(start 153.445972 -241.890804)
		(end 153.445972 -241.662204)
		(width 0.14478)
		(layer "In4.Cu")
		(net "M_J_CPU1_SA_DQ<30>")
	)
	(segment
		(start 155.786836 -239.32134)
		(end 155.94838 -239.159796)
		(width 0.14478)
		(layer "In4.Cu")
		(net "M_J_CPU1_SA_DQ<30>")
	)
	(segment
		(start 146.21256 -243.301012)
		(end 146.405092 -243.493544)
		(width 0.0889)
		(layer "In4.Cu")
		(net "M_J_CPU1_SA_DQ<30>")
	)
	(segment
		(start 186.63539 -231.760522)
		(end 187.060078 -232.18521)
		(width 0.14478)
		(layer "In4.Cu")
		(net "M_J_CPU1_SA_DQ<30>")
	)
	(segment
		(start 157.935676 -237.79734)
		(end 158.164276 -237.79734)
		(width 0.14478)
		(layer "In4.Cu")
		(net "M_J_CPU1_SA_DQ<30>")
	)
	(segment
		(start 137.803382 -243.346986)
		(end 137.811764 -243.351812)
		(width 0.0889)
		(layer "In4.Cu")
		(net "M_J_CPU1_SA_DQ<30>")
	)
	(segment
		(start 158.517844 -236.818932)
		(end 158.715964 -237.017052)
		(width 0.14478)
		(layer "In4.Cu")
		(net "M_J_CPU1_SA_DQ<30>")
	)
	(segment
		(start 132.924804 -243.674392)
		(end 132.770626 -243.408962)
		(width 0.0889)
		(layer "In4.Cu")
		(net "M_J_CPU1_SA_DQ<30>")
	)
	(segment
		(start 158.164276 -237.79734)
		(end 158.32582 -237.635796)
		(width 0.14478)
		(layer "In4.Cu")
		(net "M_J_CPU1_SA_DQ<30>")
	)
	(segment
		(start 155.043124 -240.918492)
		(end 155.204668 -240.756948)
		(width 0.14478)
		(layer "In4.Cu")
		(net "M_J_CPU1_SA_DQ<30>")
	)
	(segment
		(start 156.6037 -239.357916)
		(end 156.765244 -239.196372)
		(width 0.14478)
		(layer "In4.Cu")
		(net "M_J_CPU1_SA_DQ<30>")
	)
	(segment
		(start 156.957268 -238.379508)
		(end 157.155388 -238.577628)
		(width 0.14478)
		(layer "In4.Cu")
		(net "M_J_CPU1_SA_DQ<30>")
	)
	(segment
		(start 142.503398 -243.346986)
		(end 142.51178 -243.351812)
		(width 0.0889)
		(layer "In4.Cu")
		(net "M_J_CPU1_SA_DQ<30>")
	)
	(segment
		(start 157.155388 -238.577628)
		(end 157.383988 -238.577628)
		(width 0.14478)
		(layer "In4.Cu")
		(net "M_J_CPU1_SA_DQ<30>")
	)
	(segment
		(start 156.728668 -238.379508)
		(end 156.957268 -238.379508)
		(width 0.14478)
		(layer "In4.Cu")
		(net "M_J_CPU1_SA_DQ<30>")
	)
	(segment
		(start 157.545532 -238.187484)
		(end 157.347412 -237.989364)
		(width 0.14478)
		(layer "In4.Cu")
		(net "M_J_CPU1_SA_DQ<30>")
	)
	(segment
		(start 158.944564 -237.017052)
		(end 163.350956 -232.61066)
		(width 0.14478)
		(layer "In4.Cu")
		(net "M_J_CPU1_SA_DQ<30>")
	)
	(segment
		(start 147.226528 -242.893088)
		(end 147.595082 -242.524534)
		(width 0.0889)
		(layer "In4.Cu")
		(net "M_J_CPU1_SA_DQ<30>")
	)
	(segment
		(start 158.1277 -237.209076)
		(end 158.1277 -236.980476)
		(width 0.14478)
		(layer "In4.Cu")
		(net "M_J_CPU1_SA_DQ<30>")
	)
	(segment
		(start 157.737556 -237.59922)
		(end 157.935676 -237.79734)
		(width 0.14478)
		(layer "In4.Cu")
		(net "M_J_CPU1_SA_DQ<30>")
	)
	(segment
		(start 155.006548 -240.101628)
		(end 155.168092 -239.940084)
		(width 0.14478)
		(layer "In4.Cu")
		(net "M_J_CPU1_SA_DQ<30>")
	)
	(segment
		(start 144.384268 -243.346986)
		(end 144.39265 -243.351812)
		(width 0.0889)
		(layer "In4.Cu")
		(net "M_J_CPU1_SA_DQ<30>")
	)
	(segment
		(start 139.31773 -243.351812)
		(end 139.326112 -243.346986)
		(width 0.0889)
		(layer "In4.Cu")
		(net "M_J_CPU1_SA_DQ<30>")
	)
	(segment
		(start 178.382168 -232.61066)
		(end 181.39283 -232.61066)
		(width 0.14478)
		(layer "In4.Cu")
		(net "M_J_CPU1_SA_DQ<30>")
	)
	(segment
		(start 155.204668 -240.528348)
		(end 155.006548 -240.330228)
		(width 0.14478)
		(layer "In4.Cu")
		(net "M_J_CPU1_SA_DQ<30>")
	)
	(segment
		(start 156.567124 -238.541052)
		(end 156.728668 -238.379508)
		(width 0.14478)
		(layer "In4.Cu")
		(net "M_J_CPU1_SA_DQ<30>")
	)
	(arc
		(start 134.626096 -243.346986)
		(mid 134.809604 -243.301492)
		(end 134.991856 -243.351812)
		(width 0.0889)
		(layer "In4.Cu")
		(net "M_J_CPU1_SA_DQ<30>")
	)
	(arc
		(start 139.326112 -243.346986)
		(mid 139.50962 -243.301492)
		(end 139.691872 -243.351812)
		(width 0.0889)
		(layer "In4.Cu")
		(net "M_J_CPU1_SA_DQ<30>")
	)
	(arc
		(start 141.197838 -243.351812)
		(mid 141.384782 -243.301557)
		(end 141.571726 -243.351812)
		(width 0.0889)
		(layer "In4.Cu")
		(net "M_J_CPU1_SA_DQ<30>")
	)
	(arc
		(start 143.086074 -243.346986)
		(mid 143.269582 -243.301492)
		(end 143.451834 -243.351812)
		(width 0.0889)
		(layer "In4.Cu")
		(net "M_J_CPU1_SA_DQ<30>")
	)
	(arc
		(start 137.811764 -243.351812)
		(mid 138.09472 -243.427989)
		(end 138.377676 -243.351812)
		(width 0.0889)
		(layer "In4.Cu")
		(net "M_J_CPU1_SA_DQ<30>")
	)
	(arc
		(start 142.137638 -243.351812)
		(mid 142.319889 -243.301462)
		(end 142.503398 -243.346986)
		(width 0.0889)
		(layer "In4.Cu")
		(net "M_J_CPU1_SA_DQ<30>")
	)
	(arc
		(start 133.111748 -243.351812)
		(mid 133.394704 -243.427989)
		(end 133.67766 -243.351812)
		(width 0.0889)
		(layer "In4.Cu")
		(net "M_J_CPU1_SA_DQ<30>")
	)
	(arc
		(start 137.437622 -243.351812)
		(mid 137.619873 -243.301462)
		(end 137.803382 -243.346986)
		(width 0.0889)
		(layer "In4.Cu")
		(net "M_J_CPU1_SA_DQ<30>")
	)
	(arc
		(start 134.051802 -243.351812)
		(mid 134.334758 -243.427989)
		(end 134.617714 -243.351812)
		(width 0.0889)
		(layer "In4.Cu")
		(net "M_J_CPU1_SA_DQ<30>")
	)
	(arc
		(start 140.266166 -243.346986)
		(mid 140.449674 -243.301492)
		(end 140.631926 -243.351812)
		(width 0.0889)
		(layer "In4.Cu")
		(net "M_J_CPU1_SA_DQ<30>")
	)
	(arc
		(start 144.39265 -243.351812)
		(mid 144.672078 -243.427978)
		(end 144.952466 -243.355368)
		(width 0.0889)
		(layer "In4.Cu")
		(net "M_J_CPU1_SA_DQ<30>")
	)
	(arc
		(start 138.377676 -243.351812)
		(mid 138.559927 -243.301462)
		(end 138.743436 -243.346986)
		(width 0.0889)
		(layer "In4.Cu")
		(net "M_J_CPU1_SA_DQ<30>")
	)
	(arc
		(start 135.93191 -243.351812)
		(mid 136.214866 -243.427989)
		(end 136.497822 -243.351812)
		(width 0.0889)
		(layer "In4.Cu")
		(net "M_J_CPU1_SA_DQ<30>")
	)
	(arc
		(start 144.018 -243.351812)
		(mid 144.200505 -243.301335)
		(end 144.384268 -243.346986)
		(width 0.0889)
		(layer "In4.Cu")
		(net "M_J_CPU1_SA_DQ<30>")
	)
	(arc
		(start 143.462248 -243.357908)
		(mid 143.740934 -243.428128)
		(end 144.018 -243.351812)
		(width 0.0889)
		(layer "In4.Cu")
		(net "M_J_CPU1_SA_DQ<30>")
	)
	(arc
		(start 133.67766 -243.351812)
		(mid 133.859911 -243.301462)
		(end 134.04342 -243.346986)
		(width 0.0889)
		(layer "In4.Cu")
		(net "M_J_CPU1_SA_DQ<30>")
	)
	(arc
		(start 141.571726 -243.351812)
		(mid 141.854682 -243.427989)
		(end 142.137638 -243.351812)
		(width 0.0889)
		(layer "In4.Cu")
		(net "M_J_CPU1_SA_DQ<30>")
	)
	(arc
		(start 134.991856 -243.351812)
		(mid 135.274812 -243.427989)
		(end 135.557768 -243.351812)
		(width 0.0889)
		(layer "In4.Cu")
		(net "M_J_CPU1_SA_DQ<30>")
	)
	(arc
		(start 144.952466 -243.355368)
		(mid 145.044898 -243.315086)
		(end 145.144744 -243.301012)
		(width 0.0889)
		(layer "In4.Cu")
		(net "M_J_CPU1_SA_DQ<30>")
	)
	(arc
		(start 135.56615 -243.346986)
		(mid 135.749658 -243.301492)
		(end 135.93191 -243.351812)
		(width 0.0889)
		(layer "In4.Cu")
		(net "M_J_CPU1_SA_DQ<30>")
	)
	(arc
		(start 140.631926 -243.351812)
		(mid 140.914882 -243.427989)
		(end 141.197838 -243.351812)
		(width 0.0889)
		(layer "In4.Cu")
		(net "M_J_CPU1_SA_DQ<30>")
	)
	(arc
		(start 136.497822 -243.351812)
		(mid 136.684766 -243.301557)
		(end 136.87171 -243.351812)
		(width 0.0889)
		(layer "In4.Cu")
		(net "M_J_CPU1_SA_DQ<30>")
	)
	(arc
		(start 136.87171 -243.351812)
		(mid 137.154666 -243.427989)
		(end 137.437622 -243.351812)
		(width 0.0889)
		(layer "In4.Cu")
		(net "M_J_CPU1_SA_DQ<30>")
	)
	(arc
		(start 142.51178 -243.351812)
		(mid 142.794736 -243.427989)
		(end 143.077692 -243.351812)
		(width 0.0889)
		(layer "In4.Cu")
		(net "M_J_CPU1_SA_DQ<30>")
	)
	(arc
		(start 139.691872 -243.351812)
		(mid 139.974828 -243.427989)
		(end 140.257784 -243.351812)
		(width 0.0889)
		(layer "In4.Cu")
		(net "M_J_CPU1_SA_DQ<30>")
	)
	(arc
		(start 132.792978 -243.32565)
		(mid 132.950488 -243.302452)
		(end 133.103366 -243.346986)
		(width 0.0889)
		(layer "In4.Cu")
		(net "M_J_CPU1_SA_DQ<30>")
	)
	(arc
		(start 138.751818 -243.351812)
		(mid 139.034774 -243.427989)
		(end 139.31773 -243.351812)
		(width 0.0889)
		(layer "In4.Cu")
		(net "M_J_CPU1_SA_DQ<30>")
	)
	(segment
		(start 132.457952 -226.120452)
		(end 132.924804 -225.854514)
		(width 0.10668)
		(layer "F.Cu")
		(net "M_J_CPU1_SA_DQ<2>")
	)
	(segment
		(start 178.83124 -198.610474)
		(end 181.391814 -198.610474)
		(width 0.14478)
		(layer "In4.Cu")
		(net "M_J_CPU1_SA_DQ<2>")
	)
	(segment
		(start 154.52725 -204.066394)
		(end 154.75585 -204.066394)
		(width 0.14478)
		(layer "In4.Cu")
		(net "M_J_CPU1_SA_DQ<2>")
	)
	(segment
		(start 138.743436 -225.527108)
		(end 138.751818 -225.531934)
		(width 0.0889)
		(layer "In4.Cu")
		(net "M_J_CPU1_SA_DQ<2>")
	)
	(segment
		(start 132.924804 -225.854514)
		(end 132.770626 -225.589084)
		(width 0.0889)
		(layer "In4.Cu")
		(net "M_J_CPU1_SA_DQ<2>")
	)
	(segment
		(start 132.770626 -225.589084)
		(end 132.792978 -225.505772)
		(width 0.0889)
		(layer "In4.Cu")
		(net "M_J_CPU1_SA_DQ<2>")
	)
	(segment
		(start 142.461488 -221.527878)
		(end 142.461488 -221.304104)
		(width 0.0889)
		(layer "In4.Cu")
		(net "M_J_CPU1_SA_DQ<2>")
	)
	(segment
		(start 162.213036 -198.886826)
		(end 162.488118 -198.886826)
		(width 0.14478)
		(layer "In4.Cu")
		(net "M_J_CPU1_SA_DQ<2>")
	)
	(segment
		(start 171.16552 -198.610474)
		(end 173.316138 -198.610474)
		(width 0.14478)
		(layer "In4.Cu")
		(net "M_J_CPU1_SA_DQ<2>")
	)
	(segment
		(start 134.617714 -225.531934)
		(end 134.626096 -225.527108)
		(width 0.0889)
		(layer "In4.Cu")
		(net "M_J_CPU1_SA_DQ<2>")
	)
	(segment
		(start 135.557768 -225.531934)
		(end 135.56615 -225.527108)
		(width 0.0889)
		(layer "In4.Cu")
		(net "M_J_CPU1_SA_DQ<2>")
	)
	(segment
		(start 156.617162 -202.806554)
		(end 156.845762 -202.806554)
		(width 0.14478)
		(layer "In4.Cu")
		(net "M_J_CPU1_SA_DQ<2>")
	)
	(segment
		(start 134.04342 -225.527108)
		(end 134.051802 -225.531934)
		(width 0.0889)
		(layer "In4.Cu")
		(net "M_J_CPU1_SA_DQ<2>")
	)
	(segment
		(start 177.981102 -197.760336)
		(end 178.83124 -198.610474)
		(width 0.14478)
		(layer "In4.Cu")
		(net "M_J_CPU1_SA_DQ<2>")
	)
	(segment
		(start 182.241952 -197.760336)
		(end 186.635136 -197.760336)
		(width 0.14478)
		(layer "In4.Cu")
		(net "M_J_CPU1_SA_DQ<2>")
	)
	(segment
		(start 186.635136 -197.760336)
		(end 187.060078 -198.185278)
		(width 0.14478)
		(layer "In4.Cu")
		(net "M_J_CPU1_SA_DQ<2>")
	)
	(segment
		(start 155.44673 -203.976986)
		(end 155.145994 -203.67625)
		(width 0.14478)
		(layer "In4.Cu")
		(net "M_J_CPU1_SA_DQ<2>")
	)
	(segment
		(start 157.007306 -202.41641)
		(end 156.70657 -202.115674)
		(width 0.14478)
		(layer "In4.Cu")
		(net "M_J_CPU1_SA_DQ<2>")
	)
	(segment
		(start 156.087826 -202.505818)
		(end 156.316426 -202.505818)
		(width 0.14478)
		(layer "In4.Cu")
		(net "M_J_CPU1_SA_DQ<2>")
	)
	(segment
		(start 141.95044 -222.038926)
		(end 142.461488 -221.527878)
		(width 0.0889)
		(layer "In4.Cu")
		(net "M_J_CPU1_SA_DQ<2>")
	)
	(segment
		(start 155.44673 -204.205586)
		(end 155.44673 -203.976986)
		(width 0.14478)
		(layer "In4.Cu")
		(net "M_J_CPU1_SA_DQ<2>")
	)
	(segment
		(start 141.637512 -223.119696)
		(end 141.667992 -223.101916)
		(width 0.0889)
		(layer "In4.Cu")
		(net "M_J_CPU1_SA_DQ<2>")
	)
	(segment
		(start 137.803382 -225.527108)
		(end 137.811764 -225.531934)
		(width 0.0889)
		(layer "In4.Cu")
		(net "M_J_CPU1_SA_DQ<2>")
	)
	(segment
		(start 174.166276 -197.760336)
		(end 177.981102 -197.760336)
		(width 0.14478)
		(layer "In4.Cu")
		(net "M_J_CPU1_SA_DQ<2>")
	)
	(segment
		(start 156.227018 -203.196698)
		(end 155.926282 -202.895962)
		(width 0.14478)
		(layer "In4.Cu")
		(net "M_J_CPU1_SA_DQ<2>")
	)
	(segment
		(start 155.285186 -204.36713)
		(end 155.44673 -204.205586)
		(width 0.14478)
		(layer "In4.Cu")
		(net "M_J_CPU1_SA_DQ<2>")
	)
	(segment
		(start 155.307538 -203.286106)
		(end 155.536138 -203.286106)
		(width 0.14478)
		(layer "In4.Cu")
		(net "M_J_CPU1_SA_DQ<2>")
	)
	(segment
		(start 141.95044 -222.61449)
		(end 141.95044 -222.038926)
		(width 0.0889)
		(layer "In4.Cu")
		(net "M_J_CPU1_SA_DQ<2>")
	)
	(segment
		(start 161.661602 -198.610474)
		(end 161.936684 -198.610474)
		(width 0.14478)
		(layer "In4.Cu")
		(net "M_J_CPU1_SA_DQ<2>")
	)
	(segment
		(start 155.836874 -203.586842)
		(end 156.065474 -203.586842)
		(width 0.14478)
		(layer "In4.Cu")
		(net "M_J_CPU1_SA_DQ<2>")
	)
	(segment
		(start 139.31773 -225.531934)
		(end 139.326112 -225.527108)
		(width 0.0889)
		(layer "In4.Cu")
		(net "M_J_CPU1_SA_DQ<2>")
	)
	(segment
		(start 161.936684 -198.610474)
		(end 162.213036 -198.886826)
		(width 0.14478)
		(layer "In4.Cu")
		(net "M_J_CPU1_SA_DQ<2>")
	)
	(segment
		(start 142.461488 -217.422984)
		(end 154.666442 -205.21803)
		(width 0.14478)
		(layer "In4.Cu")
		(net "M_J_CPU1_SA_DQ<2>")
	)
	(segment
		(start 162.488118 -198.886826)
		(end 162.76447 -198.610474)
		(width 0.14478)
		(layer "In4.Cu")
		(net "M_J_CPU1_SA_DQ<2>")
	)
	(segment
		(start 141.166088 -223.93021)
		(end 141.197838 -223.911922)
		(width 0.0889)
		(layer "In4.Cu")
		(net "M_J_CPU1_SA_DQ<2>")
	)
	(segment
		(start 154.365706 -204.456538)
		(end 154.365706 -204.227938)
		(width 0.14478)
		(layer "In4.Cu")
		(net "M_J_CPU1_SA_DQ<2>")
	)
	(segment
		(start 154.365706 -204.227938)
		(end 154.52725 -204.066394)
		(width 0.14478)
		(layer "In4.Cu")
		(net "M_J_CPU1_SA_DQ<2>")
	)
	(segment
		(start 140.257784 -225.531934)
		(end 140.2969 -225.509074)
		(width 0.0889)
		(layer "In4.Cu")
		(net "M_J_CPU1_SA_DQ<2>")
	)
	(segment
		(start 140.696188 -224.740216)
		(end 140.727938 -224.721928)
		(width 0.0889)
		(layer "In4.Cu")
		(net "M_J_CPU1_SA_DQ<2>")
	)
	(segment
		(start 160.833816 -198.610474)
		(end 161.110168 -198.886826)
		(width 0.14478)
		(layer "In4.Cu")
		(net "M_J_CPU1_SA_DQ<2>")
	)
	(segment
		(start 141.197838 -223.911922)
		(end 141.238224 -223.8883)
		(width 0.0889)
		(layer "In4.Cu")
		(net "M_J_CPU1_SA_DQ<2>")
	)
	(segment
		(start 154.666442 -205.21803)
		(end 154.666442 -204.757274)
		(width 0.14478)
		(layer "In4.Cu")
		(net "M_J_CPU1_SA_DQ<2>")
	)
	(segment
		(start 155.145994 -203.67625)
		(end 155.145994 -203.44765)
		(width 0.14478)
		(layer "In4.Cu")
		(net "M_J_CPU1_SA_DQ<2>")
	)
	(segment
		(start 170.315382 -197.760336)
		(end 171.16552 -198.610474)
		(width 0.14478)
		(layer "In4.Cu")
		(net "M_J_CPU1_SA_DQ<2>")
	)
	(segment
		(start 155.145994 -203.44765)
		(end 155.307538 -203.286106)
		(width 0.14478)
		(layer "In4.Cu")
		(net "M_J_CPU1_SA_DQ<2>")
	)
	(segment
		(start 161.110168 -198.886826)
		(end 161.38525 -198.886826)
		(width 0.14478)
		(layer "In4.Cu")
		(net "M_J_CPU1_SA_DQ<2>")
	)
	(segment
		(start 166.228014 -198.610474)
		(end 167.078152 -197.760336)
		(width 0.14478)
		(layer "In4.Cu")
		(net "M_J_CPU1_SA_DQ<2>")
	)
	(segment
		(start 156.70657 -201.887074)
		(end 159.98317 -198.610474)
		(width 0.14478)
		(layer "In4.Cu")
		(net "M_J_CPU1_SA_DQ<2>")
	)
	(segment
		(start 155.926282 -202.667362)
		(end 156.087826 -202.505818)
		(width 0.14478)
		(layer "In4.Cu")
		(net "M_J_CPU1_SA_DQ<2>")
	)
	(segment
		(start 156.065474 -203.586842)
		(end 156.227018 -203.425298)
		(width 0.14478)
		(layer "In4.Cu")
		(net "M_J_CPU1_SA_DQ<2>")
	)
	(segment
		(start 159.98317 -198.610474)
		(end 160.833816 -198.610474)
		(width 0.14478)
		(layer "In4.Cu")
		(net "M_J_CPU1_SA_DQ<2>")
	)
	(segment
		(start 173.316138 -198.610474)
		(end 174.166276 -197.760336)
		(width 0.14478)
		(layer "In4.Cu")
		(net "M_J_CPU1_SA_DQ<2>")
	)
	(segment
		(start 154.666442 -204.757274)
		(end 154.365706 -204.456538)
		(width 0.14478)
		(layer "In4.Cu")
		(net "M_J_CPU1_SA_DQ<2>")
	)
	(segment
		(start 162.76447 -198.610474)
		(end 166.228014 -198.610474)
		(width 0.14478)
		(layer "In4.Cu")
		(net "M_J_CPU1_SA_DQ<2>")
	)
	(segment
		(start 161.38525 -198.886826)
		(end 161.661602 -198.610474)
		(width 0.14478)
		(layer "In4.Cu")
		(net "M_J_CPU1_SA_DQ<2>")
	)
	(segment
		(start 157.007306 -202.64501)
		(end 157.007306 -202.41641)
		(width 0.14478)
		(layer "In4.Cu")
		(net "M_J_CPU1_SA_DQ<2>")
	)
	(segment
		(start 155.536138 -203.286106)
		(end 155.836874 -203.586842)
		(width 0.14478)
		(layer "In4.Cu")
		(net "M_J_CPU1_SA_DQ<2>")
	)
	(segment
		(start 142.461488 -221.304104)
		(end 142.461488 -217.422984)
		(width 0.14478)
		(layer "In4.Cu")
		(net "M_J_CPU1_SA_DQ<2>")
	)
	(segment
		(start 141.667992 -223.101916)
		(end 141.708378 -223.078294)
		(width 0.0889)
		(layer "In4.Cu")
		(net "M_J_CPU1_SA_DQ<2>")
	)
	(segment
		(start 156.316426 -202.505818)
		(end 156.617162 -202.806554)
		(width 0.14478)
		(layer "In4.Cu")
		(net "M_J_CPU1_SA_DQ<2>")
	)
	(segment
		(start 140.727938 -224.721928)
		(end 140.76426 -224.700846)
		(width 0.0889)
		(layer "In4.Cu")
		(net "M_J_CPU1_SA_DQ<2>")
	)
	(segment
		(start 156.70657 -202.115674)
		(end 156.70657 -201.887074)
		(width 0.14478)
		(layer "In4.Cu")
		(net "M_J_CPU1_SA_DQ<2>")
	)
	(segment
		(start 154.75585 -204.066394)
		(end 155.056586 -204.36713)
		(width 0.14478)
		(layer "In4.Cu")
		(net "M_J_CPU1_SA_DQ<2>")
	)
	(segment
		(start 156.227018 -203.425298)
		(end 156.227018 -203.196698)
		(width 0.14478)
		(layer "In4.Cu")
		(net "M_J_CPU1_SA_DQ<2>")
	)
	(segment
		(start 155.926282 -202.895962)
		(end 155.926282 -202.667362)
		(width 0.14478)
		(layer "In4.Cu")
		(net "M_J_CPU1_SA_DQ<2>")
	)
	(segment
		(start 167.078152 -197.760336)
		(end 170.315382 -197.760336)
		(width 0.14478)
		(layer "In4.Cu")
		(net "M_J_CPU1_SA_DQ<2>")
	)
	(segment
		(start 156.845762 -202.806554)
		(end 157.007306 -202.64501)
		(width 0.14478)
		(layer "In4.Cu")
		(net "M_J_CPU1_SA_DQ<2>")
	)
	(segment
		(start 181.391814 -198.610474)
		(end 182.241952 -197.760336)
		(width 0.14478)
		(layer "In4.Cu")
		(net "M_J_CPU1_SA_DQ<2>")
	)
	(segment
		(start 155.056586 -204.36713)
		(end 155.285186 -204.36713)
		(width 0.14478)
		(layer "In4.Cu")
		(net "M_J_CPU1_SA_DQ<2>")
	)
	(segment
		(start 133.103366 -225.527108)
		(end 133.111748 -225.531934)
		(width 0.0889)
		(layer "In4.Cu")
		(net "M_J_CPU1_SA_DQ<2>")
	)
	(arc
		(start 133.67766 -225.531934)
		(mid 133.859911 -225.481584)
		(end 134.04342 -225.527108)
		(width 0.0889)
		(layer "In4.Cu")
		(net "M_J_CPU1_SA_DQ<2>")
	)
	(arc
		(start 139.326112 -225.527108)
		(mid 139.50962 -225.481614)
		(end 139.691872 -225.531934)
		(width 0.0889)
		(layer "In4.Cu")
		(net "M_J_CPU1_SA_DQ<2>")
	)
	(arc
		(start 141.238224 -223.8883)
		(mid 141.416289 -223.686123)
		(end 141.48054 -223.424496)
		(width 0.0889)
		(layer "In4.Cu")
		(net "M_J_CPU1_SA_DQ<2>")
	)
	(arc
		(start 133.111748 -225.531934)
		(mid 133.394704 -225.608111)
		(end 133.67766 -225.531934)
		(width 0.0889)
		(layer "In4.Cu")
		(net "M_J_CPU1_SA_DQ<2>")
	)
	(arc
		(start 137.811764 -225.531934)
		(mid 138.09472 -225.608111)
		(end 138.377676 -225.531934)
		(width 0.0889)
		(layer "In4.Cu")
		(net "M_J_CPU1_SA_DQ<2>")
	)
	(arc
		(start 132.792978 -225.505772)
		(mid 132.950488 -225.482574)
		(end 133.103366 -225.527108)
		(width 0.0889)
		(layer "In4.Cu")
		(net "M_J_CPU1_SA_DQ<2>")
	)
	(arc
		(start 135.93191 -225.531934)
		(mid 136.214866 -225.608111)
		(end 136.497822 -225.531934)
		(width 0.0889)
		(layer "In4.Cu")
		(net "M_J_CPU1_SA_DQ<2>")
	)
	(arc
		(start 138.751818 -225.531934)
		(mid 139.034774 -225.608111)
		(end 139.31773 -225.531934)
		(width 0.0889)
		(layer "In4.Cu")
		(net "M_J_CPU1_SA_DQ<2>")
	)
	(arc
		(start 140.2969 -225.509074)
		(mid 140.475713 -225.306724)
		(end 140.540232 -225.044508)
		(width 0.0889)
		(layer "In4.Cu")
		(net "M_J_CPU1_SA_DQ<2>")
	)
	(arc
		(start 136.87171 -225.531934)
		(mid 137.154666 -225.608111)
		(end 137.437622 -225.531934)
		(width 0.0889)
		(layer "In4.Cu")
		(net "M_J_CPU1_SA_DQ<2>")
	)
	(arc
		(start 140.76426 -224.700846)
		(mid 140.944912 -224.498101)
		(end 141.010132 -224.234502)
		(width 0.0889)
		(layer "In4.Cu")
		(net "M_J_CPU1_SA_DQ<2>")
	)
	(arc
		(start 134.991856 -225.531934)
		(mid 135.274812 -225.608111)
		(end 135.557768 -225.531934)
		(width 0.0889)
		(layer "In4.Cu")
		(net "M_J_CPU1_SA_DQ<2>")
	)
	(arc
		(start 141.708378 -223.078294)
		(mid 141.886273 -222.876072)
		(end 141.95044 -222.61449)
		(width 0.0889)
		(layer "In4.Cu")
		(net "M_J_CPU1_SA_DQ<2>")
	)
	(arc
		(start 136.497822 -225.531934)
		(mid 136.684766 -225.481679)
		(end 136.87171 -225.531934)
		(width 0.0889)
		(layer "In4.Cu")
		(net "M_J_CPU1_SA_DQ<2>")
	)
	(arc
		(start 138.377676 -225.531934)
		(mid 138.559927 -225.481584)
		(end 138.743436 -225.527108)
		(width 0.0889)
		(layer "In4.Cu")
		(net "M_J_CPU1_SA_DQ<2>")
	)
	(arc
		(start 134.051802 -225.531934)
		(mid 134.334758 -225.608111)
		(end 134.617714 -225.531934)
		(width 0.0889)
		(layer "In4.Cu")
		(net "M_J_CPU1_SA_DQ<2>")
	)
	(arc
		(start 139.691872 -225.531934)
		(mid 139.974828 -225.608111)
		(end 140.257784 -225.531934)
		(width 0.0889)
		(layer "In4.Cu")
		(net "M_J_CPU1_SA_DQ<2>")
	)
	(arc
		(start 141.48054 -223.424496)
		(mid 141.522089 -223.253074)
		(end 141.637512 -223.119696)
		(width 0.0889)
		(layer "In4.Cu")
		(net "M_J_CPU1_SA_DQ<2>")
	)
	(arc
		(start 141.010132 -224.234502)
		(mid 141.051387 -224.063531)
		(end 141.166088 -223.93021)
		(width 0.0889)
		(layer "In4.Cu")
		(net "M_J_CPU1_SA_DQ<2>")
	)
	(arc
		(start 137.437622 -225.531934)
		(mid 137.619873 -225.481584)
		(end 137.803382 -225.527108)
		(width 0.0889)
		(layer "In4.Cu")
		(net "M_J_CPU1_SA_DQ<2>")
	)
	(arc
		(start 140.540232 -225.044508)
		(mid 140.581487 -224.873537)
		(end 140.696188 -224.740216)
		(width 0.0889)
		(layer "In4.Cu")
		(net "M_J_CPU1_SA_DQ<2>")
	)
	(arc
		(start 135.56615 -225.527108)
		(mid 135.749658 -225.481614)
		(end 135.93191 -225.531934)
		(width 0.0889)
		(layer "In4.Cu")
		(net "M_J_CPU1_SA_DQ<2>")
	)
	(arc
		(start 134.626096 -225.527108)
		(mid 134.809604 -225.481614)
		(end 134.991856 -225.531934)
		(width 0.0889)
		(layer "In4.Cu")
		(net "M_J_CPU1_SA_DQ<2>")
	)
	(segment
		(start 130.577844 -243.94033)
		(end 131.044696 -243.674392)
		(width 0.10668)
		(layer "F.Cu")
		(net "M_J_CPU1_SA_DQ<29>")
	)
	(segment
		(start 137.803382 -244.001798)
		(end 137.811764 -243.996972)
		(width 0.0889)
		(layer "In4.Cu")
		(net "M_J_CPU1_SA_DQ<29>")
	)
	(segment
		(start 167.625776 -232.61066)
		(end 169.67962 -232.61066)
		(width 0.14478)
		(layer "In4.Cu")
		(net "M_J_CPU1_SA_DQ<29>")
	)
	(segment
		(start 145.929604 -244.047772)
		(end 146.184112 -243.793264)
		(width 0.0889)
		(layer "In4.Cu")
		(net "M_J_CPU1_SA_DQ<29>")
	)
	(segment
		(start 131.044696 -243.674392)
		(end 131.198874 -243.939822)
		(width 0.0889)
		(layer "In4.Cu")
		(net "M_J_CPU1_SA_DQ<29>")
	)
	(segment
		(start 143.451834 -243.996972)
		(end 143.466566 -243.988336)
		(width 0.0889)
		(layer "In4.Cu")
		(net "M_J_CPU1_SA_DQ<29>")
	)
	(segment
		(start 145.144744 -244.047772)
		(end 145.929604 -244.047772)
		(width 0.0889)
		(layer "In4.Cu")
		(net "M_J_CPU1_SA_DQ<29>")
	)
	(segment
		(start 140.257784 -243.996972)
		(end 140.266166 -244.001798)
		(width 0.0889)
		(layer "In4.Cu")
		(net "M_J_CPU1_SA_DQ<29>")
	)
	(segment
		(start 170.529504 -233.460544)
		(end 173.791118 -233.460544)
		(width 0.14478)
		(layer "In4.Cu")
		(net "M_J_CPU1_SA_DQ<29>")
	)
	(segment
		(start 144.380966 -244.00383)
		(end 144.39265 -243.996972)
		(width 0.0889)
		(layer "In4.Cu")
		(net "M_J_CPU1_SA_DQ<29>")
	)
	(segment
		(start 153.618438 -242.979194)
		(end 163.137088 -233.460544)
		(width 0.14478)
		(layer "In4.Cu")
		(net "M_J_CPU1_SA_DQ<29>")
	)
	(segment
		(start 174.641002 -232.61066)
		(end 177.621438 -232.61066)
		(width 0.14478)
		(layer "In4.Cu")
		(net "M_J_CPU1_SA_DQ<29>")
	)
	(segment
		(start 178.471322 -233.460544)
		(end 181.29631 -233.460544)
		(width 0.14478)
		(layer "In4.Cu")
		(net "M_J_CPU1_SA_DQ<29>")
	)
	(segment
		(start 139.31773 -243.996972)
		(end 139.326112 -244.001798)
		(width 0.0889)
		(layer "In4.Cu")
		(net "M_J_CPU1_SA_DQ<29>")
	)
	(segment
		(start 134.617714 -243.996972)
		(end 134.626096 -244.001798)
		(width 0.0889)
		(layer "In4.Cu")
		(net "M_J_CPU1_SA_DQ<29>")
	)
	(segment
		(start 169.67962 -232.61066)
		(end 170.529504 -233.460544)
		(width 0.14478)
		(layer "In4.Cu")
		(net "M_J_CPU1_SA_DQ<29>")
	)
	(segment
		(start 177.621438 -232.61066)
		(end 178.471322 -233.460544)
		(width 0.14478)
		(layer "In4.Cu")
		(net "M_J_CPU1_SA_DQ<29>")
	)
	(segment
		(start 181.29631 -233.460544)
		(end 182.146194 -232.61066)
		(width 0.14478)
		(layer "In4.Cu")
		(net "M_J_CPU1_SA_DQ<29>")
	)
	(segment
		(start 146.184112 -243.793264)
		(end 146.929348 -243.793264)
		(width 0.0889)
		(layer "In4.Cu")
		(net "M_J_CPU1_SA_DQ<29>")
	)
	(segment
		(start 134.04342 -244.001798)
		(end 134.051802 -243.996972)
		(width 0.0889)
		(layer "In4.Cu")
		(net "M_J_CPU1_SA_DQ<29>")
	)
	(segment
		(start 147.937982 -242.979194)
		(end 153.618438 -242.979194)
		(width 0.14478)
		(layer "In4.Cu")
		(net "M_J_CPU1_SA_DQ<29>")
	)
	(segment
		(start 147.743418 -242.979194)
		(end 147.937982 -242.979194)
		(width 0.0889)
		(layer "In4.Cu")
		(net "M_J_CPU1_SA_DQ<29>")
	)
	(segment
		(start 131.198874 -243.939822)
		(end 131.29514 -243.965222)
		(width 0.0889)
		(layer "In4.Cu")
		(net "M_J_CPU1_SA_DQ<29>")
	)
	(segment
		(start 146.929348 -243.793264)
		(end 147.743418 -242.979194)
		(width 0.0889)
		(layer "In4.Cu")
		(net "M_J_CPU1_SA_DQ<29>")
	)
	(segment
		(start 143.077692 -243.996972)
		(end 143.086074 -244.001798)
		(width 0.0889)
		(layer "In4.Cu")
		(net "M_J_CPU1_SA_DQ<29>")
	)
	(segment
		(start 142.503398 -244.001798)
		(end 142.51178 -243.996972)
		(width 0.0889)
		(layer "In4.Cu")
		(net "M_J_CPU1_SA_DQ<29>")
	)
	(segment
		(start 135.557768 -243.996972)
		(end 135.56615 -244.001798)
		(width 0.0889)
		(layer "In4.Cu")
		(net "M_J_CPU1_SA_DQ<29>")
	)
	(segment
		(start 173.791118 -233.460544)
		(end 174.641002 -232.61066)
		(width 0.14478)
		(layer "In4.Cu")
		(net "M_J_CPU1_SA_DQ<29>")
	)
	(segment
		(start 182.146194 -232.61066)
		(end 190.735458 -232.61066)
		(width 0.14478)
		(layer "In4.Cu")
		(net "M_J_CPU1_SA_DQ<29>")
	)
	(segment
		(start 138.743436 -244.001798)
		(end 138.751818 -243.996972)
		(width 0.0889)
		(layer "In4.Cu")
		(net "M_J_CPU1_SA_DQ<29>")
	)
	(segment
		(start 190.735458 -232.61066)
		(end 191.160146 -233.035348)
		(width 0.14478)
		(layer "In4.Cu")
		(net "M_J_CPU1_SA_DQ<29>")
	)
	(segment
		(start 133.103366 -244.001798)
		(end 133.111748 -243.996972)
		(width 0.0889)
		(layer "In4.Cu")
		(net "M_J_CPU1_SA_DQ<29>")
	)
	(segment
		(start 163.137088 -233.460544)
		(end 166.775892 -233.460544)
		(width 0.14478)
		(layer "In4.Cu")
		(net "M_J_CPU1_SA_DQ<29>")
	)
	(segment
		(start 166.775892 -233.460544)
		(end 167.625776 -232.61066)
		(width 0.14478)
		(layer "In4.Cu")
		(net "M_J_CPU1_SA_DQ<29>")
	)
	(arc
		(start 137.437622 -243.996972)
		(mid 137.619873 -244.047322)
		(end 137.803382 -244.001798)
		(width 0.0889)
		(layer "In4.Cu")
		(net "M_J_CPU1_SA_DQ<29>")
	)
	(arc
		(start 131.797806 -243.996972)
		(mid 131.98475 -244.047227)
		(end 132.171694 -243.996972)
		(width 0.0889)
		(layer "In4.Cu")
		(net "M_J_CPU1_SA_DQ<29>")
	)
	(arc
		(start 133.111748 -243.996972)
		(mid 133.394704 -243.920795)
		(end 133.67766 -243.996972)
		(width 0.0889)
		(layer "In4.Cu")
		(net "M_J_CPU1_SA_DQ<29>")
	)
	(arc
		(start 134.991856 -243.996972)
		(mid 135.274812 -243.920795)
		(end 135.557768 -243.996972)
		(width 0.0889)
		(layer "In4.Cu")
		(net "M_J_CPU1_SA_DQ<29>")
	)
	(arc
		(start 140.266166 -244.001798)
		(mid 140.449674 -244.047292)
		(end 140.631926 -243.996972)
		(width 0.0889)
		(layer "In4.Cu")
		(net "M_J_CPU1_SA_DQ<29>")
	)
	(arc
		(start 135.93191 -243.996972)
		(mid 136.214866 -243.920795)
		(end 136.497822 -243.996972)
		(width 0.0889)
		(layer "In4.Cu")
		(net "M_J_CPU1_SA_DQ<29>")
	)
	(arc
		(start 143.086074 -244.001798)
		(mid 143.269582 -244.047292)
		(end 143.451834 -243.996972)
		(width 0.0889)
		(layer "In4.Cu")
		(net "M_J_CPU1_SA_DQ<29>")
	)
	(arc
		(start 142.51178 -243.996972)
		(mid 142.794736 -243.920795)
		(end 143.077692 -243.996972)
		(width 0.0889)
		(layer "In4.Cu")
		(net "M_J_CPU1_SA_DQ<29>")
	)
	(arc
		(start 138.377676 -243.996972)
		(mid 138.559927 -244.047322)
		(end 138.743436 -244.001798)
		(width 0.0889)
		(layer "In4.Cu")
		(net "M_J_CPU1_SA_DQ<29>")
	)
	(arc
		(start 142.137638 -243.996972)
		(mid 142.319889 -244.047322)
		(end 142.503398 -244.001798)
		(width 0.0889)
		(layer "In4.Cu")
		(net "M_J_CPU1_SA_DQ<29>")
	)
	(arc
		(start 143.466566 -243.988336)
		(mid 143.743549 -243.920532)
		(end 144.018254 -243.996972)
		(width 0.0889)
		(layer "In4.Cu")
		(net "M_J_CPU1_SA_DQ<29>")
	)
	(arc
		(start 137.811764 -243.996972)
		(mid 138.09472 -243.920795)
		(end 138.377676 -243.996972)
		(width 0.0889)
		(layer "In4.Cu")
		(net "M_J_CPU1_SA_DQ<29>")
	)
	(arc
		(start 136.87171 -243.996972)
		(mid 137.154666 -243.920795)
		(end 137.437622 -243.996972)
		(width 0.0889)
		(layer "In4.Cu")
		(net "M_J_CPU1_SA_DQ<29>")
	)
	(arc
		(start 141.197838 -243.996972)
		(mid 141.384782 -244.047227)
		(end 141.571726 -243.996972)
		(width 0.0889)
		(layer "In4.Cu")
		(net "M_J_CPU1_SA_DQ<29>")
	)
	(arc
		(start 134.051802 -243.996972)
		(mid 134.334758 -243.920795)
		(end 134.617714 -243.996972)
		(width 0.0889)
		(layer "In4.Cu")
		(net "M_J_CPU1_SA_DQ<29>")
	)
	(arc
		(start 139.691872 -243.996972)
		(mid 139.974828 -243.920795)
		(end 140.257784 -243.996972)
		(width 0.0889)
		(layer "In4.Cu")
		(net "M_J_CPU1_SA_DQ<29>")
	)
	(arc
		(start 132.171694 -243.996972)
		(mid 132.45465 -243.920795)
		(end 132.737606 -243.996972)
		(width 0.0889)
		(layer "In4.Cu")
		(net "M_J_CPU1_SA_DQ<29>")
	)
	(arc
		(start 144.018254 -243.996972)
		(mid 144.198712 -244.047416)
		(end 144.380966 -244.00383)
		(width 0.0889)
		(layer "In4.Cu")
		(net "M_J_CPU1_SA_DQ<29>")
	)
	(arc
		(start 139.326112 -244.001798)
		(mid 139.50962 -244.047292)
		(end 139.691872 -243.996972)
		(width 0.0889)
		(layer "In4.Cu")
		(net "M_J_CPU1_SA_DQ<29>")
	)
	(arc
		(start 144.952466 -243.993416)
		(mid 145.044898 -244.033698)
		(end 145.144744 -244.047772)
		(width 0.0889)
		(layer "In4.Cu")
		(net "M_J_CPU1_SA_DQ<29>")
	)
	(arc
		(start 141.571726 -243.996972)
		(mid 141.854682 -243.920795)
		(end 142.137638 -243.996972)
		(width 0.0889)
		(layer "In4.Cu")
		(net "M_J_CPU1_SA_DQ<29>")
	)
	(arc
		(start 134.626096 -244.001798)
		(mid 134.809604 -244.047292)
		(end 134.991856 -243.996972)
		(width 0.0889)
		(layer "In4.Cu")
		(net "M_J_CPU1_SA_DQ<29>")
	)
	(arc
		(start 131.29514 -243.965222)
		(mid 131.550205 -243.921871)
		(end 131.797806 -243.996972)
		(width 0.0889)
		(layer "In4.Cu")
		(net "M_J_CPU1_SA_DQ<29>")
	)
	(arc
		(start 136.497822 -243.996972)
		(mid 136.684766 -244.047227)
		(end 136.87171 -243.996972)
		(width 0.0889)
		(layer "In4.Cu")
		(net "M_J_CPU1_SA_DQ<29>")
	)
	(arc
		(start 144.39265 -243.996972)
		(mid 144.672078 -243.920806)
		(end 144.952466 -243.993416)
		(width 0.0889)
		(layer "In4.Cu")
		(net "M_J_CPU1_SA_DQ<29>")
	)
	(arc
		(start 132.737606 -243.996972)
		(mid 132.919857 -244.047322)
		(end 133.103366 -244.001798)
		(width 0.0889)
		(layer "In4.Cu")
		(net "M_J_CPU1_SA_DQ<29>")
	)
	(arc
		(start 138.751818 -243.996972)
		(mid 139.034774 -243.920795)
		(end 139.31773 -243.996972)
		(width 0.0889)
		(layer "In4.Cu")
		(net "M_J_CPU1_SA_DQ<29>")
	)
	(arc
		(start 133.67766 -243.996972)
		(mid 133.859911 -244.047322)
		(end 134.04342 -244.001798)
		(width 0.0889)
		(layer "In4.Cu")
		(net "M_J_CPU1_SA_DQ<29>")
	)
	(arc
		(start 135.56615 -244.001798)
		(mid 135.749658 -244.047292)
		(end 135.93191 -243.996972)
		(width 0.0889)
		(layer "In4.Cu")
		(net "M_J_CPU1_SA_DQ<29>")
	)
	(arc
		(start 140.631926 -243.996972)
		(mid 140.914882 -243.920795)
		(end 141.197838 -243.996972)
		(width 0.0889)
		(layer "In4.Cu")
		(net "M_J_CPU1_SA_DQ<29>")
	)
	(segment
		(start 131.987798 -243.130324)
		(end 132.45465 -242.864386)
		(width 0.10668)
		(layer "F.Cu")
		(net "M_J_CPU1_SA_DQ<28>")
	)
	(segment
		(start 186.71032 -231.177846)
		(end 187.57138 -231.177846)
		(width 0.14478)
		(layer "In4.Cu")
		(net "M_J_CPU1_SA_DQ<28>")
	)
	(segment
		(start 182.375556 -230.920036)
		(end 186.45251 -230.920036)
		(width 0.14478)
		(layer "In4.Cu")
		(net "M_J_CPU1_SA_DQ<28>")
	)
	(segment
		(start 190.735204 -230.910384)
		(end 191.160146 -231.335326)
		(width 0.14478)
		(layer "In4.Cu")
		(net "M_J_CPU1_SA_DQ<28>")
	)
	(segment
		(start 167.18026 -230.910384)
		(end 169.546016 -230.910384)
		(width 0.14478)
		(layer "In4.Cu")
		(net "M_J_CPU1_SA_DQ<28>")
	)
	(segment
		(start 178.215798 -231.76992)
		(end 181.525672 -231.76992)
		(width 0.14478)
		(layer "In4.Cu")
		(net "M_J_CPU1_SA_DQ<28>")
	)
	(segment
		(start 189.269624 -230.920036)
		(end 189.42304 -231.073452)
		(width 0.14478)
		(layer "In4.Cu")
		(net "M_J_CPU1_SA_DQ<28>")
	)
	(segment
		(start 136.967722 -243.186966)
		(end 136.976104 -243.191792)
		(width 0.0889)
		(layer "In4.Cu")
		(net "M_J_CPU1_SA_DQ<28>")
	)
	(segment
		(start 135.453374 -243.191792)
		(end 135.461756 -243.186966)
		(width 0.0889)
		(layer "In4.Cu")
		(net "M_J_CPU1_SA_DQ<28>")
	)
	(segment
		(start 140.15339 -243.191792)
		(end 140.161772 -243.186966)
		(width 0.0889)
		(layer "In4.Cu")
		(net "M_J_CPU1_SA_DQ<28>")
	)
	(segment
		(start 158.956248 -236.369352)
		(end 163.565332 -231.760268)
		(width 0.14478)
		(layer "In4.Cu")
		(net "M_J_CPU1_SA_DQ<28>")
	)
	(segment
		(start 189.979554 -231.511094)
		(end 189.979554 -231.073452)
		(width 0.14478)
		(layer "In4.Cu")
		(net "M_J_CPU1_SA_DQ<28>")
	)
	(segment
		(start 189.586108 -231.674162)
		(end 189.816486 -231.674162)
		(width 0.14478)
		(layer "In4.Cu")
		(net "M_J_CPU1_SA_DQ<28>")
	)
	(segment
		(start 189.42304 -231.511094)
		(end 189.586108 -231.674162)
		(width 0.14478)
		(layer "In4.Cu")
		(net "M_J_CPU1_SA_DQ<28>")
	)
	(segment
		(start 136.393428 -243.191792)
		(end 136.40181 -243.186966)
		(width 0.0889)
		(layer "In4.Cu")
		(net "M_J_CPU1_SA_DQ<28>")
	)
	(segment
		(start 174.493428 -230.920036)
		(end 177.365914 -230.920036)
		(width 0.14478)
		(layer "In4.Cu")
		(net "M_J_CPU1_SA_DQ<28>")
	)
	(segment
		(start 133.20776 -243.186966)
		(end 133.216142 -243.191792)
		(width 0.0889)
		(layer "In4.Cu")
		(net "M_J_CPU1_SA_DQ<28>")
	)
	(segment
		(start 186.45251 -230.920036)
		(end 186.71032 -231.177846)
		(width 0.14478)
		(layer "In4.Cu")
		(net "M_J_CPU1_SA_DQ<28>")
	)
	(segment
		(start 189.816486 -231.674162)
		(end 189.979554 -231.511094)
		(width 0.14478)
		(layer "In4.Cu")
		(net "M_J_CPU1_SA_DQ<28>")
	)
	(segment
		(start 163.565332 -231.760268)
		(end 166.330376 -231.760268)
		(width 0.14478)
		(layer "In4.Cu")
		(net "M_J_CPU1_SA_DQ<28>")
	)
	(segment
		(start 190.142622 -230.910384)
		(end 190.735204 -230.910384)
		(width 0.14478)
		(layer "In4.Cu")
		(net "M_J_CPU1_SA_DQ<28>")
	)
	(segment
		(start 189.42304 -231.073452)
		(end 189.42304 -231.511094)
		(width 0.14478)
		(layer "In4.Cu")
		(net "M_J_CPU1_SA_DQ<28>")
	)
	(segment
		(start 132.45465 -242.864386)
		(end 132.608828 -243.129816)
		(width 0.0889)
		(layer "In4.Cu")
		(net "M_J_CPU1_SA_DQ<28>")
	)
	(segment
		(start 187.82919 -230.920036)
		(end 189.269624 -230.920036)
		(width 0.14478)
		(layer "In4.Cu")
		(net "M_J_CPU1_SA_DQ<28>")
	)
	(segment
		(start 141.093444 -243.191792)
		(end 141.101826 -243.186966)
		(width 0.0889)
		(layer "In4.Cu")
		(net "M_J_CPU1_SA_DQ<28>")
	)
	(segment
		(start 147.591018 -242.069874)
		(end 152.352502 -242.069874)
		(width 0.14478)
		(layer "In4.Cu")
		(net "M_J_CPU1_SA_DQ<28>")
	)
	(segment
		(start 181.525672 -231.76992)
		(end 182.375556 -230.920036)
		(width 0.14478)
		(layer "In4.Cu")
		(net "M_J_CPU1_SA_DQ<28>")
	)
	(segment
		(start 137.907776 -243.186966)
		(end 137.916158 -243.191792)
		(width 0.0889)
		(layer "In4.Cu")
		(net "M_J_CPU1_SA_DQ<28>")
	)
	(segment
		(start 189.979554 -231.073452)
		(end 190.142622 -230.910384)
		(width 0.14478)
		(layer "In4.Cu")
		(net "M_J_CPU1_SA_DQ<28>")
	)
	(segment
		(start 146.735038 -242.635024)
		(end 147.025868 -242.635024)
		(width 0.0889)
		(layer "In4.Cu")
		(net "M_J_CPU1_SA_DQ<28>")
	)
	(segment
		(start 158.053024 -236.369352)
		(end 158.956248 -236.369352)
		(width 0.14478)
		(layer "In4.Cu")
		(net "M_J_CPU1_SA_DQ<28>")
	)
	(segment
		(start 132.608828 -243.129816)
		(end 132.705094 -243.155216)
		(width 0.0889)
		(layer "In4.Cu")
		(net "M_J_CPU1_SA_DQ<28>")
	)
	(segment
		(start 143.547592 -243.186966)
		(end 143.555974 -243.191792)
		(width 0.0889)
		(layer "In4.Cu")
		(net "M_J_CPU1_SA_DQ<28>")
	)
	(segment
		(start 177.365914 -230.920036)
		(end 178.215798 -231.76992)
		(width 0.14478)
		(layer "In4.Cu")
		(net "M_J_CPU1_SA_DQ<28>")
	)
	(segment
		(start 173.643544 -231.76992)
		(end 174.493428 -230.920036)
		(width 0.14478)
		(layer "In4.Cu")
		(net "M_J_CPU1_SA_DQ<28>")
	)
	(segment
		(start 170.405552 -231.76992)
		(end 173.643544 -231.76992)
		(width 0.14478)
		(layer "In4.Cu")
		(net "M_J_CPU1_SA_DQ<28>")
	)
	(segment
		(start 141.667738 -243.186966)
		(end 141.67612 -243.191792)
		(width 0.0889)
		(layer "In4.Cu")
		(net "M_J_CPU1_SA_DQ<28>")
	)
	(segment
		(start 147.486878 -242.174014)
		(end 147.591018 -242.069874)
		(width 0.14478)
		(layer "In4.Cu")
		(net "M_J_CPU1_SA_DQ<28>")
	)
	(segment
		(start 147.025868 -242.635024)
		(end 147.486878 -242.174014)
		(width 0.0889)
		(layer "In4.Cu")
		(net "M_J_CPU1_SA_DQ<28>")
	)
	(segment
		(start 187.57138 -231.177846)
		(end 187.82919 -230.920036)
		(width 0.14478)
		(layer "In4.Cu")
		(net "M_J_CPU1_SA_DQ<28>")
	)
	(segment
		(start 144.477994 -243.18087)
		(end 144.488408 -243.186966)
		(width 0.0889)
		(layer "In4.Cu")
		(net "M_J_CPU1_SA_DQ<28>")
	)
	(segment
		(start 169.546016 -230.910384)
		(end 170.405552 -231.76992)
		(width 0.14478)
		(layer "In4.Cu")
		(net "M_J_CPU1_SA_DQ<28>")
	)
	(segment
		(start 152.352502 -242.069874)
		(end 158.053024 -236.369352)
		(width 0.14478)
		(layer "In4.Cu")
		(net "M_J_CPU1_SA_DQ<28>")
	)
	(segment
		(start 146.25955 -243.110512)
		(end 146.735038 -242.635024)
		(width 0.0889)
		(layer "In4.Cu")
		(net "M_J_CPU1_SA_DQ<28>")
	)
	(segment
		(start 166.330376 -231.760268)
		(end 167.18026 -230.910384)
		(width 0.14478)
		(layer "In4.Cu")
		(net "M_J_CPU1_SA_DQ<28>")
	)
	(segment
		(start 145.144744 -243.110512)
		(end 146.25955 -243.110512)
		(width 0.0889)
		(layer "In4.Cu")
		(net "M_J_CPU1_SA_DQ<28>")
	)
	(arc
		(start 137.916158 -243.191792)
		(mid 138.099666 -243.237286)
		(end 138.281918 -243.186966)
		(width 0.0889)
		(layer "In4.Cu")
		(net "M_J_CPU1_SA_DQ<28>")
	)
	(arc
		(start 136.027668 -243.186966)
		(mid 136.209919 -243.237316)
		(end 136.393428 -243.191792)
		(width 0.0889)
		(layer "In4.Cu")
		(net "M_J_CPU1_SA_DQ<28>")
	)
	(arc
		(start 141.67612 -243.191792)
		(mid 141.859628 -243.237286)
		(end 142.04188 -243.186966)
		(width 0.0889)
		(layer "In4.Cu")
		(net "M_J_CPU1_SA_DQ<28>")
	)
	(arc
		(start 137.341864 -243.186966)
		(mid 137.62482 -243.110789)
		(end 137.907776 -243.186966)
		(width 0.0889)
		(layer "In4.Cu")
		(net "M_J_CPU1_SA_DQ<28>")
	)
	(arc
		(start 140.727684 -243.186966)
		(mid 140.909935 -243.237316)
		(end 141.093444 -243.191792)
		(width 0.0889)
		(layer "In4.Cu")
		(net "M_J_CPU1_SA_DQ<28>")
	)
	(arc
		(start 144.488408 -243.186966)
		(mid 144.666058 -243.237226)
		(end 144.84604 -243.19611)
		(width 0.0889)
		(layer "In4.Cu")
		(net "M_J_CPU1_SA_DQ<28>")
	)
	(arc
		(start 141.101826 -243.186966)
		(mid 141.384782 -243.110789)
		(end 141.667738 -243.186966)
		(width 0.0889)
		(layer "In4.Cu")
		(net "M_J_CPU1_SA_DQ<28>")
	)
	(arc
		(start 139.221718 -243.186966)
		(mid 139.504674 -243.110789)
		(end 139.78763 -243.186966)
		(width 0.0889)
		(layer "In4.Cu")
		(net "M_J_CPU1_SA_DQ<28>")
	)
	(arc
		(start 142.04188 -243.186966)
		(mid 142.324836 -243.110789)
		(end 142.607792 -243.186966)
		(width 0.0889)
		(layer "In4.Cu")
		(net "M_J_CPU1_SA_DQ<28>")
	)
	(arc
		(start 136.976104 -243.191792)
		(mid 137.159612 -243.237286)
		(end 137.341864 -243.186966)
		(width 0.0889)
		(layer "In4.Cu")
		(net "M_J_CPU1_SA_DQ<28>")
	)
	(arc
		(start 138.281918 -243.186966)
		(mid 138.564874 -243.110789)
		(end 138.84783 -243.186966)
		(width 0.0889)
		(layer "In4.Cu")
		(net "M_J_CPU1_SA_DQ<28>")
	)
	(arc
		(start 142.607792 -243.186966)
		(mid 142.794736 -243.237221)
		(end 142.98168 -243.186966)
		(width 0.0889)
		(layer "In4.Cu")
		(net "M_J_CPU1_SA_DQ<28>")
	)
	(arc
		(start 135.461756 -243.186966)
		(mid 135.744712 -243.110789)
		(end 136.027668 -243.186966)
		(width 0.0889)
		(layer "In4.Cu")
		(net "M_J_CPU1_SA_DQ<28>")
	)
	(arc
		(start 138.84783 -243.186966)
		(mid 139.034774 -243.237221)
		(end 139.221718 -243.186966)
		(width 0.0889)
		(layer "In4.Cu")
		(net "M_J_CPU1_SA_DQ<28>")
	)
	(arc
		(start 133.216142 -243.191792)
		(mid 133.39965 -243.237286)
		(end 133.581902 -243.186966)
		(width 0.0889)
		(layer "In4.Cu")
		(net "M_J_CPU1_SA_DQ<28>")
	)
	(arc
		(start 143.555974 -243.191792)
		(mid 143.739736 -243.237408)
		(end 143.922242 -243.186966)
		(width 0.0889)
		(layer "In4.Cu")
		(net "M_J_CPU1_SA_DQ<28>")
	)
	(arc
		(start 133.581902 -243.186966)
		(mid 133.864858 -243.110789)
		(end 134.147814 -243.186966)
		(width 0.0889)
		(layer "In4.Cu")
		(net "M_J_CPU1_SA_DQ<28>")
	)
	(arc
		(start 143.922242 -243.186966)
		(mid 144.199309 -243.110695)
		(end 144.477994 -243.18087)
		(width 0.0889)
		(layer "In4.Cu")
		(net "M_J_CPU1_SA_DQ<28>")
	)
	(arc
		(start 140.161772 -243.186966)
		(mid 140.444728 -243.110789)
		(end 140.727684 -243.186966)
		(width 0.0889)
		(layer "In4.Cu")
		(net "M_J_CPU1_SA_DQ<28>")
	)
	(arc
		(start 139.78763 -243.186966)
		(mid 139.969881 -243.237316)
		(end 140.15339 -243.191792)
		(width 0.0889)
		(layer "In4.Cu")
		(net "M_J_CPU1_SA_DQ<28>")
	)
	(arc
		(start 132.705094 -243.155216)
		(mid 132.960159 -243.111865)
		(end 133.20776 -243.186966)
		(width 0.0889)
		(layer "In4.Cu")
		(net "M_J_CPU1_SA_DQ<28>")
	)
	(arc
		(start 142.98168 -243.186966)
		(mid 143.264636 -243.110789)
		(end 143.547592 -243.186966)
		(width 0.0889)
		(layer "In4.Cu")
		(net "M_J_CPU1_SA_DQ<28>")
	)
	(arc
		(start 134.521702 -243.186966)
		(mid 134.804658 -243.110789)
		(end 135.087614 -243.186966)
		(width 0.0889)
		(layer "In4.Cu")
		(net "M_J_CPU1_SA_DQ<28>")
	)
	(arc
		(start 144.84604 -243.19611)
		(mid 144.989379 -243.132323)
		(end 145.144744 -243.110512)
		(width 0.0889)
		(layer "In4.Cu")
		(net "M_J_CPU1_SA_DQ<28>")
	)
	(arc
		(start 136.40181 -243.186966)
		(mid 136.684766 -243.110789)
		(end 136.967722 -243.186966)
		(width 0.0889)
		(layer "In4.Cu")
		(net "M_J_CPU1_SA_DQ<28>")
	)
	(arc
		(start 134.147814 -243.186966)
		(mid 134.334758 -243.237221)
		(end 134.521702 -243.186966)
		(width 0.0889)
		(layer "In4.Cu")
		(net "M_J_CPU1_SA_DQ<28>")
	)
	(arc
		(start 135.087614 -243.186966)
		(mid 135.269865 -243.237316)
		(end 135.453374 -243.191792)
		(width 0.0889)
		(layer "In4.Cu")
		(net "M_J_CPU1_SA_DQ<28>")
	)
	(segment
		(start 131.047998 -241.510312)
		(end 131.51485 -241.244374)
		(width 0.10668)
		(layer "F.Cu")
		(net "M_J_CPU1_SA_DQ<27>")
	)
	(segment
		(start 145.887948 -241.011964)
		(end 146.228308 -240.671604)
		(width 0.0889)
		(layer "In4.Cu")
		(net "M_J_CPU1_SA_DQ<27>")
	)
	(segment
		(start 185.322972 -227.770182)
		(end 185.484516 -227.931726)
		(width 0.14478)
		(layer "In4.Cu")
		(net "M_J_CPU1_SA_DQ<27>")
	)
	(segment
		(start 173.406308 -228.350572)
		(end 174.256192 -227.500688)
		(width 0.14478)
		(layer "In4.Cu")
		(net "M_J_CPU1_SA_DQ<27>")
	)
	(segment
		(start 131.360672 -240.978944)
		(end 131.383024 -240.895632)
		(width 0.0889)
		(layer "In4.Cu")
		(net "M_J_CPU1_SA_DQ<27>")
	)
	(segment
		(start 155.62199 -235.472986)
		(end 155.62199 -235.062014)
		(width 0.14478)
		(layer "In4.Cu")
		(net "M_J_CPU1_SA_DQ<27>")
	)
	(segment
		(start 152.31618 -238.778796)
		(end 152.500838 -238.594138)
		(width 0.14478)
		(layer "In4.Cu")
		(net "M_J_CPU1_SA_DQ<27>")
	)
	(segment
		(start 153.096468 -237.998508)
		(end 153.281126 -237.81385)
		(width 0.14478)
		(layer "In4.Cu")
		(net "M_J_CPU1_SA_DQ<27>")
	)
	(segment
		(start 185.712862 -227.931726)
		(end 185.874406 -227.770182)
		(width 0.14478)
		(layer "In4.Cu")
		(net "M_J_CPU1_SA_DQ<27>")
	)
	(segment
		(start 151.535892 -239.559084)
		(end 151.72055 -239.374426)
		(width 0.14478)
		(layer "In4.Cu")
		(net "M_J_CPU1_SA_DQ<27>")
	)
	(segment
		(start 144.87017 -240.935764)
		(end 144.985486 -240.983516)
		(width 0.0889)
		(layer "In4.Cu")
		(net "M_J_CPU1_SA_DQ<27>")
	)
	(segment
		(start 146.623532 -240.671604)
		(end 147.583652 -239.711484)
		(width 0.0889)
		(layer "In4.Cu")
		(net "M_J_CPU1_SA_DQ<27>")
	)
	(segment
		(start 137.907776 -240.921794)
		(end 137.916158 -240.916968)
		(width 0.0889)
		(layer "In4.Cu")
		(net "M_J_CPU1_SA_DQ<27>")
	)
	(segment
		(start 183.901842 -227.500688)
		(end 184.292494 -227.110036)
		(width 0.14478)
		(layer "In4.Cu")
		(net "M_J_CPU1_SA_DQ<27>")
	)
	(segment
		(start 152.500838 -238.594138)
		(end 152.500838 -238.183166)
		(width 0.14478)
		(layer "In4.Cu")
		(net "M_J_CPU1_SA_DQ<27>")
	)
	(segment
		(start 151.905208 -238.778796)
		(end 152.31618 -238.778796)
		(width 0.14478)
		(layer "In4.Cu")
		(net "M_J_CPU1_SA_DQ<27>")
	)
	(segment
		(start 157.182566 -233.501438)
		(end 162.323526 -228.360478)
		(width 0.14478)
		(layer "In4.Cu")
		(net "M_J_CPU1_SA_DQ<27>")
	)
	(segment
		(start 157.182566 -233.91241)
		(end 157.182566 -233.501438)
		(width 0.14478)
		(layer "In4.Cu")
		(net "M_J_CPU1_SA_DQ<27>")
	)
	(segment
		(start 156.586936 -234.097068)
		(end 156.997908 -234.097068)
		(width 0.14478)
		(layer "In4.Cu")
		(net "M_J_CPU1_SA_DQ<27>")
	)
	(segment
		(start 141.093444 -240.916968)
		(end 141.101826 -240.921794)
		(width 0.0889)
		(layer "In4.Cu")
		(net "M_J_CPU1_SA_DQ<27>")
	)
	(segment
		(start 151.12492 -239.559084)
		(end 151.535892 -239.559084)
		(width 0.14478)
		(layer "In4.Cu")
		(net "M_J_CPU1_SA_DQ<27>")
	)
	(segment
		(start 181.97576 -227.500688)
		(end 183.901842 -227.500688)
		(width 0.14478)
		(layer "In4.Cu")
		(net "M_J_CPU1_SA_DQ<27>")
	)
	(segment
		(start 144.985486 -240.983516)
		(end 145.128488 -241.011964)
		(width 0.0889)
		(layer "In4.Cu")
		(net "M_J_CPU1_SA_DQ<27>")
	)
	(segment
		(start 185.484516 -227.931726)
		(end 185.712862 -227.931726)
		(width 0.14478)
		(layer "In4.Cu")
		(net "M_J_CPU1_SA_DQ<27>")
	)
	(segment
		(start 154.841702 -236.253274)
		(end 154.841702 -235.842302)
		(width 0.14478)
		(layer "In4.Cu")
		(net "M_J_CPU1_SA_DQ<27>")
	)
	(segment
		(start 181.125622 -228.350826)
		(end 181.97576 -227.500688)
		(width 0.14478)
		(layer "In4.Cu")
		(net "M_J_CPU1_SA_DQ<27>")
	)
	(segment
		(start 147.583652 -239.711484)
		(end 147.937982 -239.711484)
		(width 0.0889)
		(layer "In4.Cu")
		(net "M_J_CPU1_SA_DQ<27>")
	)
	(segment
		(start 185.322972 -227.27158)
		(end 185.322972 -227.770182)
		(width 0.14478)
		(layer "In4.Cu")
		(net "M_J_CPU1_SA_DQ<27>")
	)
	(segment
		(start 136.393428 -240.916968)
		(end 136.40181 -240.921794)
		(width 0.0889)
		(layer "In4.Cu")
		(net "M_J_CPU1_SA_DQ<27>")
	)
	(segment
		(start 153.281126 -237.402878)
		(end 153.465784 -237.21822)
		(width 0.14478)
		(layer "In4.Cu")
		(net "M_J_CPU1_SA_DQ<27>")
	)
	(segment
		(start 155.02636 -235.657644)
		(end 155.437332 -235.657644)
		(width 0.14478)
		(layer "In4.Cu")
		(net "M_J_CPU1_SA_DQ<27>")
	)
	(segment
		(start 154.061414 -237.033562)
		(end 154.061414 -236.62259)
		(width 0.14478)
		(layer "In4.Cu")
		(net "M_J_CPU1_SA_DQ<27>")
	)
	(segment
		(start 156.402278 -234.692698)
		(end 156.402278 -234.281726)
		(width 0.14478)
		(layer "In4.Cu")
		(net "M_J_CPU1_SA_DQ<27>")
	)
	(segment
		(start 166.915846 -227.51034)
		(end 170.199812 -227.51034)
		(width 0.14478)
		(layer "In4.Cu")
		(net "M_J_CPU1_SA_DQ<27>")
	)
	(segment
		(start 156.21762 -234.877356)
		(end 156.402278 -234.692698)
		(width 0.14478)
		(layer "In4.Cu")
		(net "M_J_CPU1_SA_DQ<27>")
	)
	(segment
		(start 153.876756 -237.21822)
		(end 154.061414 -237.033562)
		(width 0.14478)
		(layer "In4.Cu")
		(net "M_J_CPU1_SA_DQ<27>")
	)
	(segment
		(start 154.061414 -236.62259)
		(end 154.246072 -236.437932)
		(width 0.14478)
		(layer "In4.Cu")
		(net "M_J_CPU1_SA_DQ<27>")
	)
	(segment
		(start 154.657044 -236.437932)
		(end 154.841702 -236.253274)
		(width 0.14478)
		(layer "In4.Cu")
		(net "M_J_CPU1_SA_DQ<27>")
	)
	(segment
		(start 154.841702 -235.842302)
		(end 155.02636 -235.657644)
		(width 0.14478)
		(layer "In4.Cu")
		(net "M_J_CPU1_SA_DQ<27>")
	)
	(segment
		(start 178.796696 -228.350826)
		(end 181.125622 -228.350826)
		(width 0.14478)
		(layer "In4.Cu")
		(net "M_J_CPU1_SA_DQ<27>")
	)
	(segment
		(start 144.47393 -240.93043)
		(end 144.488662 -240.921794)
		(width 0.0889)
		(layer "In4.Cu")
		(net "M_J_CPU1_SA_DQ<27>")
	)
	(segment
		(start 185.161428 -227.110036)
		(end 185.322972 -227.27158)
		(width 0.14478)
		(layer "In4.Cu")
		(net "M_J_CPU1_SA_DQ<27>")
	)
	(segment
		(start 184.292494 -227.110036)
		(end 185.161428 -227.110036)
		(width 0.14478)
		(layer "In4.Cu")
		(net "M_J_CPU1_SA_DQ<27>")
	)
	(segment
		(start 153.281126 -237.81385)
		(end 153.281126 -237.402878)
		(width 0.14478)
		(layer "In4.Cu")
		(net "M_J_CPU1_SA_DQ<27>")
	)
	(segment
		(start 152.685496 -237.998508)
		(end 153.096468 -237.998508)
		(width 0.14478)
		(layer "In4.Cu")
		(net "M_J_CPU1_SA_DQ<27>")
	)
	(segment
		(start 156.402278 -234.281726)
		(end 156.586936 -234.097068)
		(width 0.14478)
		(layer "In4.Cu")
		(net "M_J_CPU1_SA_DQ<27>")
	)
	(segment
		(start 143.547592 -240.921794)
		(end 143.555974 -240.916968)
		(width 0.0889)
		(layer "In4.Cu")
		(net "M_J_CPU1_SA_DQ<27>")
	)
	(segment
		(start 186.234832 -227.110036)
		(end 187.060078 -227.935282)
		(width 0.14478)
		(layer "In4.Cu")
		(net "M_J_CPU1_SA_DQ<27>")
	)
	(segment
		(start 131.51485 -241.244374)
		(end 131.360672 -240.978944)
		(width 0.0889)
		(layer "In4.Cu")
		(net "M_J_CPU1_SA_DQ<27>")
	)
	(segment
		(start 151.72055 -238.963454)
		(end 151.905208 -238.778796)
		(width 0.14478)
		(layer "In4.Cu")
		(net "M_J_CPU1_SA_DQ<27>")
	)
	(segment
		(start 131.693412 -240.916968)
		(end 131.701794 -240.921794)
		(width 0.0889)
		(layer "In4.Cu")
		(net "M_J_CPU1_SA_DQ<27>")
	)
	(segment
		(start 177.946558 -227.500688)
		(end 178.796696 -228.350826)
		(width 0.14478)
		(layer "In4.Cu")
		(net "M_J_CPU1_SA_DQ<27>")
	)
	(segment
		(start 186.03595 -227.110036)
		(end 186.234832 -227.110036)
		(width 0.14478)
		(layer "In4.Cu")
		(net "M_J_CPU1_SA_DQ<27>")
	)
	(segment
		(start 153.465784 -237.21822)
		(end 153.876756 -237.21822)
		(width 0.14478)
		(layer "In4.Cu")
		(net "M_J_CPU1_SA_DQ<27>")
	)
	(segment
		(start 144.84858 -240.914174)
		(end 144.87017 -240.935764)
		(width 0.0889)
		(layer "In4.Cu")
		(net "M_J_CPU1_SA_DQ<27>")
	)
	(segment
		(start 174.256192 -227.500688)
		(end 177.946558 -227.500688)
		(width 0.14478)
		(layer "In4.Cu")
		(net "M_J_CPU1_SA_DQ<27>")
	)
	(segment
		(start 132.267706 -240.921794)
		(end 132.276088 -240.916968)
		(width 0.0889)
		(layer "In4.Cu")
		(net "M_J_CPU1_SA_DQ<27>")
	)
	(segment
		(start 151.72055 -239.374426)
		(end 151.72055 -238.963454)
		(width 0.14478)
		(layer "In4.Cu")
		(net "M_J_CPU1_SA_DQ<27>")
	)
	(segment
		(start 155.806648 -234.877356)
		(end 156.21762 -234.877356)
		(width 0.14478)
		(layer "In4.Cu")
		(net "M_J_CPU1_SA_DQ<27>")
	)
	(segment
		(start 154.246072 -236.437932)
		(end 154.657044 -236.437932)
		(width 0.14478)
		(layer "In4.Cu")
		(net "M_J_CPU1_SA_DQ<27>")
	)
	(segment
		(start 162.323526 -228.360478)
		(end 166.065708 -228.360478)
		(width 0.14478)
		(layer "In4.Cu")
		(net "M_J_CPU1_SA_DQ<27>")
	)
	(segment
		(start 133.20776 -240.921794)
		(end 133.216142 -240.916968)
		(width 0.0889)
		(layer "In4.Cu")
		(net "M_J_CPU1_SA_DQ<27>")
	)
	(segment
		(start 171.040044 -228.350572)
		(end 173.406308 -228.350572)
		(width 0.14478)
		(layer "In4.Cu")
		(net "M_J_CPU1_SA_DQ<27>")
	)
	(segment
		(start 141.667738 -240.921794)
		(end 141.67612 -240.916968)
		(width 0.0889)
		(layer "In4.Cu")
		(net "M_J_CPU1_SA_DQ<27>")
	)
	(segment
		(start 152.500838 -238.183166)
		(end 152.685496 -237.998508)
		(width 0.14478)
		(layer "In4.Cu")
		(net "M_J_CPU1_SA_DQ<27>")
	)
	(segment
		(start 166.065708 -228.360478)
		(end 166.915846 -227.51034)
		(width 0.14478)
		(layer "In4.Cu")
		(net "M_J_CPU1_SA_DQ<27>")
	)
	(segment
		(start 156.997908 -234.097068)
		(end 157.182566 -233.91241)
		(width 0.14478)
		(layer "In4.Cu")
		(net "M_J_CPU1_SA_DQ<27>")
	)
	(segment
		(start 185.874406 -227.770182)
		(end 185.874406 -227.27158)
		(width 0.14478)
		(layer "In4.Cu")
		(net "M_J_CPU1_SA_DQ<27>")
	)
	(segment
		(start 136.967722 -240.921794)
		(end 136.976104 -240.916968)
		(width 0.0889)
		(layer "In4.Cu")
		(net "M_J_CPU1_SA_DQ<27>")
	)
	(segment
		(start 145.128488 -241.011964)
		(end 145.887948 -241.011964)
		(width 0.0889)
		(layer "In4.Cu")
		(net "M_J_CPU1_SA_DQ<27>")
	)
	(segment
		(start 140.15339 -240.916968)
		(end 140.161772 -240.921794)
		(width 0.0889)
		(layer "In4.Cu")
		(net "M_J_CPU1_SA_DQ<27>")
	)
	(segment
		(start 170.199812 -227.51034)
		(end 171.040044 -228.350572)
		(width 0.14478)
		(layer "In4.Cu")
		(net "M_J_CPU1_SA_DQ<27>")
	)
	(segment
		(start 155.437332 -235.657644)
		(end 155.62199 -235.472986)
		(width 0.14478)
		(layer "In4.Cu")
		(net "M_J_CPU1_SA_DQ<27>")
	)
	(segment
		(start 146.228308 -240.671604)
		(end 146.623532 -240.671604)
		(width 0.0889)
		(layer "In4.Cu")
		(net "M_J_CPU1_SA_DQ<27>")
	)
	(segment
		(start 185.874406 -227.27158)
		(end 186.03595 -227.110036)
		(width 0.14478)
		(layer "In4.Cu")
		(net "M_J_CPU1_SA_DQ<27>")
	)
	(segment
		(start 147.937982 -239.711484)
		(end 150.97252 -239.711484)
		(width 0.14478)
		(layer "In4.Cu")
		(net "M_J_CPU1_SA_DQ<27>")
	)
	(segment
		(start 155.62199 -235.062014)
		(end 155.806648 -234.877356)
		(width 0.14478)
		(layer "In4.Cu")
		(net "M_J_CPU1_SA_DQ<27>")
	)
	(segment
		(start 150.97252 -239.711484)
		(end 151.12492 -239.559084)
		(width 0.14478)
		(layer "In4.Cu")
		(net "M_J_CPU1_SA_DQ<27>")
	)
	(segment
		(start 135.453374 -240.916968)
		(end 135.461756 -240.921794)
		(width 0.0889)
		(layer "In4.Cu")
		(net "M_J_CPU1_SA_DQ<27>")
	)
	(arc
		(start 143.922242 -240.921794)
		(mid 144.196948 -240.998158)
		(end 144.47393 -240.93043)
		(width 0.0889)
		(layer "In4.Cu")
		(net "M_J_CPU1_SA_DQ<27>")
	)
	(arc
		(start 134.147814 -240.921794)
		(mid 134.334758 -240.871539)
		(end 134.521702 -240.921794)
		(width 0.0889)
		(layer "In4.Cu")
		(net "M_J_CPU1_SA_DQ<27>")
	)
	(arc
		(start 139.221718 -240.921794)
		(mid 139.504674 -240.997971)
		(end 139.78763 -240.921794)
		(width 0.0889)
		(layer "In4.Cu")
		(net "M_J_CPU1_SA_DQ<27>")
	)
	(arc
		(start 132.276088 -240.916968)
		(mid 132.459596 -240.871474)
		(end 132.641848 -240.921794)
		(width 0.0889)
		(layer "In4.Cu")
		(net "M_J_CPU1_SA_DQ<27>")
	)
	(arc
		(start 131.701794 -240.921794)
		(mid 131.98475 -240.997971)
		(end 132.267706 -240.921794)
		(width 0.0889)
		(layer "In4.Cu")
		(net "M_J_CPU1_SA_DQ<27>")
	)
	(arc
		(start 133.216142 -240.916968)
		(mid 133.39965 -240.871474)
		(end 133.581902 -240.921794)
		(width 0.0889)
		(layer "In4.Cu")
		(net "M_J_CPU1_SA_DQ<27>")
	)
	(arc
		(start 142.98168 -240.921794)
		(mid 143.264636 -240.997971)
		(end 143.547592 -240.921794)
		(width 0.0889)
		(layer "In4.Cu")
		(net "M_J_CPU1_SA_DQ<27>")
	)
	(arc
		(start 133.581902 -240.921794)
		(mid 133.864858 -240.997971)
		(end 134.147814 -240.921794)
		(width 0.0889)
		(layer "In4.Cu")
		(net "M_J_CPU1_SA_DQ<27>")
	)
	(arc
		(start 136.027668 -240.921794)
		(mid 136.209919 -240.871444)
		(end 136.393428 -240.916968)
		(width 0.0889)
		(layer "In4.Cu")
		(net "M_J_CPU1_SA_DQ<27>")
	)
	(arc
		(start 135.461756 -240.921794)
		(mid 135.744712 -240.997971)
		(end 136.027668 -240.921794)
		(width 0.0889)
		(layer "In4.Cu")
		(net "M_J_CPU1_SA_DQ<27>")
	)
	(arc
		(start 140.161772 -240.921794)
		(mid 140.444728 -240.997971)
		(end 140.727684 -240.921794)
		(width 0.0889)
		(layer "In4.Cu")
		(net "M_J_CPU1_SA_DQ<27>")
	)
	(arc
		(start 132.641848 -240.921794)
		(mid 132.924804 -240.997971)
		(end 133.20776 -240.921794)
		(width 0.0889)
		(layer "In4.Cu")
		(net "M_J_CPU1_SA_DQ<27>")
	)
	(arc
		(start 140.727684 -240.921794)
		(mid 140.909935 -240.871444)
		(end 141.093444 -240.916968)
		(width 0.0889)
		(layer "In4.Cu")
		(net "M_J_CPU1_SA_DQ<27>")
	)
	(arc
		(start 141.101826 -240.921794)
		(mid 141.384782 -240.997971)
		(end 141.667738 -240.921794)
		(width 0.0889)
		(layer "In4.Cu")
		(net "M_J_CPU1_SA_DQ<27>")
	)
	(arc
		(start 137.916158 -240.916968)
		(mid 138.099666 -240.871474)
		(end 138.281918 -240.921794)
		(width 0.0889)
		(layer "In4.Cu")
		(net "M_J_CPU1_SA_DQ<27>")
	)
	(arc
		(start 142.04188 -240.921794)
		(mid 142.324836 -240.997971)
		(end 142.607792 -240.921794)
		(width 0.0889)
		(layer "In4.Cu")
		(net "M_J_CPU1_SA_DQ<27>")
	)
	(arc
		(start 136.976104 -240.916968)
		(mid 137.159612 -240.871474)
		(end 137.341864 -240.921794)
		(width 0.0889)
		(layer "In4.Cu")
		(net "M_J_CPU1_SA_DQ<27>")
	)
	(arc
		(start 142.607792 -240.921794)
		(mid 142.794736 -240.871539)
		(end 142.98168 -240.921794)
		(width 0.0889)
		(layer "In4.Cu")
		(net "M_J_CPU1_SA_DQ<27>")
	)
	(arc
		(start 135.087614 -240.921794)
		(mid 135.269865 -240.871444)
		(end 135.453374 -240.916968)
		(width 0.0889)
		(layer "In4.Cu")
		(net "M_J_CPU1_SA_DQ<27>")
	)
	(arc
		(start 138.281918 -240.921794)
		(mid 138.564874 -240.997971)
		(end 138.84783 -240.921794)
		(width 0.0889)
		(layer "In4.Cu")
		(net "M_J_CPU1_SA_DQ<27>")
	)
	(arc
		(start 131.383024 -240.895632)
		(mid 131.540534 -240.872434)
		(end 131.693412 -240.916968)
		(width 0.0889)
		(layer "In4.Cu")
		(net "M_J_CPU1_SA_DQ<27>")
	)
	(arc
		(start 134.521702 -240.921794)
		(mid 134.804658 -240.997971)
		(end 135.087614 -240.921794)
		(width 0.0889)
		(layer "In4.Cu")
		(net "M_J_CPU1_SA_DQ<27>")
	)
	(arc
		(start 138.84783 -240.921794)
		(mid 139.034774 -240.871539)
		(end 139.221718 -240.921794)
		(width 0.0889)
		(layer "In4.Cu")
		(net "M_J_CPU1_SA_DQ<27>")
	)
	(arc
		(start 136.40181 -240.921794)
		(mid 136.684766 -240.997971)
		(end 136.967722 -240.921794)
		(width 0.0889)
		(layer "In4.Cu")
		(net "M_J_CPU1_SA_DQ<27>")
	)
	(arc
		(start 137.341864 -240.921794)
		(mid 137.62482 -240.997971)
		(end 137.907776 -240.921794)
		(width 0.0889)
		(layer "In4.Cu")
		(net "M_J_CPU1_SA_DQ<27>")
	)
	(arc
		(start 143.555974 -240.916968)
		(mid 143.739736 -240.871352)
		(end 143.922242 -240.921794)
		(width 0.0889)
		(layer "In4.Cu")
		(net "M_J_CPU1_SA_DQ<27>")
	)
	(arc
		(start 139.78763 -240.921794)
		(mid 139.969881 -240.871444)
		(end 140.15339 -240.916968)
		(width 0.0889)
		(layer "In4.Cu")
		(net "M_J_CPU1_SA_DQ<27>")
	)
	(arc
		(start 141.67612 -240.916968)
		(mid 141.859628 -240.871474)
		(end 142.04188 -240.921794)
		(width 0.0889)
		(layer "In4.Cu")
		(net "M_J_CPU1_SA_DQ<27>")
	)
	(arc
		(start 144.488662 -240.921794)
		(mid 144.667649 -240.871624)
		(end 144.84858 -240.914174)
		(width 0.0889)
		(layer "In4.Cu")
		(net "M_J_CPU1_SA_DQ<27>")
	)
	(segment
		(start 132.457952 -240.700306)
		(end 132.924804 -240.434368)
		(width 0.10668)
		(layer "F.Cu")
		(net "M_J_CPU1_SA_DQ<26>")
	)
	(segment
		(start 162.43808 -226.959414)
		(end 162.737038 -226.660456)
		(width 0.14478)
		(layer "In4.Cu")
		(net "M_J_CPU1_SA_DQ<26>")
	)
	(segment
		(start 164.272722 -226.349306)
		(end 164.583872 -226.660456)
		(width 0.14478)
		(layer "In4.Cu")
		(net "M_J_CPU1_SA_DQ<26>")
	)
	(segment
		(start 160.82391 -227.685854)
		(end 160.985962 -227.523802)
		(width 0.14478)
		(layer "In4.Cu")
		(net "M_J_CPU1_SA_DQ<26>")
	)
	(segment
		(start 132.770626 -240.168938)
		(end 132.792978 -240.085626)
		(width 0.0889)
		(layer "In4.Cu")
		(net "M_J_CPU1_SA_DQ<26>")
	)
	(segment
		(start 135.557768 -240.111788)
		(end 135.56615 -240.106962)
		(width 0.0889)
		(layer "In4.Cu")
		(net "M_J_CPU1_SA_DQ<26>")
	)
	(segment
		(start 164.032438 -226.349306)
		(end 164.272722 -226.349306)
		(width 0.14478)
		(layer "In4.Cu")
		(net "M_J_CPU1_SA_DQ<26>")
	)
	(segment
		(start 160.259268 -228.910134)
		(end 160.043622 -228.694234)
		(width 0.14478)
		(layer "In4.Cu")
		(net "M_J_CPU1_SA_DQ<26>")
	)
	(segment
		(start 132.924804 -240.434368)
		(end 132.770626 -240.168938)
		(width 0.0889)
		(layer "In4.Cu")
		(net "M_J_CPU1_SA_DQ<26>")
	)
	(segment
		(start 133.103366 -240.106962)
		(end 133.111748 -240.111788)
		(width 0.0889)
		(layer "In4.Cu")
		(net "M_J_CPU1_SA_DQ<26>")
	)
	(segment
		(start 146.558508 -239.251744)
		(end 147.165568 -239.251744)
		(width 0.0889)
		(layer "In4.Cu")
		(net "M_J_CPU1_SA_DQ<26>")
	)
	(segment
		(start 165.68674 -226.660456)
		(end 166.299388 -226.660456)
		(width 0.14478)
		(layer "In4.Cu")
		(net "M_J_CPU1_SA_DQ<26>")
	)
	(segment
		(start 161.604198 -227.133658)
		(end 161.604198 -226.905566)
		(width 0.14478)
		(layer "In4.Cu")
		(net "M_J_CPU1_SA_DQ<26>")
	)
	(segment
		(start 162.737038 -226.660456)
		(end 163.721288 -226.660456)
		(width 0.14478)
		(layer "In4.Cu")
		(net "M_J_CPU1_SA_DQ<26>")
	)
	(segment
		(start 163.721288 -226.660456)
		(end 164.032438 -226.349306)
		(width 0.14478)
		(layer "In4.Cu")
		(net "M_J_CPU1_SA_DQ<26>")
	)
	(segment
		(start 160.205674 -228.30409)
		(end 160.433766 -228.30409)
		(width 0.14478)
		(layer "In4.Cu")
		(net "M_J_CPU1_SA_DQ<26>")
	)
	(segment
		(start 134.617714 -240.111788)
		(end 134.626096 -240.106962)
		(width 0.0889)
		(layer "In4.Cu")
		(net "M_J_CPU1_SA_DQ<26>")
	)
	(segment
		(start 162.209988 -226.959414)
		(end 162.43808 -226.959414)
		(width 0.14478)
		(layer "In4.Cu")
		(net "M_J_CPU1_SA_DQ<26>")
	)
	(segment
		(start 164.824156 -226.660456)
		(end 165.135306 -226.349306)
		(width 0.14478)
		(layer "In4.Cu")
		(net "M_J_CPU1_SA_DQ<26>")
	)
	(segment
		(start 160.82391 -227.913946)
		(end 160.82391 -227.685854)
		(width 0.14478)
		(layer "In4.Cu")
		(net "M_J_CPU1_SA_DQ<26>")
	)
	(segment
		(start 161.039556 -228.129846)
		(end 160.82391 -227.913946)
		(width 0.14478)
		(layer "In4.Cu")
		(net "M_J_CPU1_SA_DQ<26>")
	)
	(segment
		(start 178.772058 -226.660456)
		(end 181.0639 -226.660456)
		(width 0.14478)
		(layer "In4.Cu")
		(net "M_J_CPU1_SA_DQ<26>")
	)
	(segment
		(start 159.869124 -229.300278)
		(end 160.097216 -229.300278)
		(width 0.14478)
		(layer "In4.Cu")
		(net "M_J_CPU1_SA_DQ<26>")
	)
	(segment
		(start 147.165568 -239.251744)
		(end 147.615148 -238.802164)
		(width 0.0889)
		(layer "In4.Cu")
		(net "M_J_CPU1_SA_DQ<26>")
	)
	(segment
		(start 143.077692 -240.111788)
		(end 143.086074 -240.106962)
		(width 0.0889)
		(layer "In4.Cu")
		(net "M_J_CPU1_SA_DQ<26>")
	)
	(segment
		(start 159.263334 -229.24643)
		(end 159.425386 -229.084378)
		(width 0.14478)
		(layer "In4.Cu")
		(net "M_J_CPU1_SA_DQ<26>")
	)
	(segment
		(start 138.743436 -240.106962)
		(end 138.751818 -240.111788)
		(width 0.0889)
		(layer "In4.Cu")
		(net "M_J_CPU1_SA_DQ<26>")
	)
	(segment
		(start 165.135306 -226.349306)
		(end 165.37559 -226.349306)
		(width 0.14478)
		(layer "In4.Cu")
		(net "M_J_CPU1_SA_DQ<26>")
	)
	(segment
		(start 161.214054 -227.523802)
		(end 161.4297 -227.739702)
		(width 0.14478)
		(layer "In4.Cu")
		(net "M_J_CPU1_SA_DQ<26>")
	)
	(segment
		(start 145.144744 -240.060988)
		(end 145.749264 -240.060988)
		(width 0.0889)
		(layer "In4.Cu")
		(net "M_J_CPU1_SA_DQ<26>")
	)
	(segment
		(start 169.942256 -225.810318)
		(end 170.792394 -226.660456)
		(width 0.14478)
		(layer "In4.Cu")
		(net "M_J_CPU1_SA_DQ<26>")
	)
	(segment
		(start 174.490888 -225.810318)
		(end 177.92192 -225.810318)
		(width 0.14478)
		(layer "In4.Cu")
		(net "M_J_CPU1_SA_DQ<26>")
	)
	(segment
		(start 161.819844 -227.57765)
		(end 161.819844 -227.349558)
		(width 0.14478)
		(layer "In4.Cu")
		(net "M_J_CPU1_SA_DQ<26>")
	)
	(segment
		(start 170.792394 -226.660456)
		(end 173.64075 -226.660456)
		(width 0.14478)
		(layer "In4.Cu")
		(net "M_J_CPU1_SA_DQ<26>")
	)
	(segment
		(start 164.583872 -226.660456)
		(end 164.824156 -226.660456)
		(width 0.14478)
		(layer "In4.Cu")
		(net "M_J_CPU1_SA_DQ<26>")
	)
	(segment
		(start 160.097216 -229.300278)
		(end 160.259268 -229.138226)
		(width 0.14478)
		(layer "In4.Cu")
		(net "M_J_CPU1_SA_DQ<26>")
	)
	(segment
		(start 160.259268 -229.138226)
		(end 160.259268 -228.910134)
		(width 0.14478)
		(layer "In4.Cu")
		(net "M_J_CPU1_SA_DQ<26>")
	)
	(segment
		(start 161.4297 -227.739702)
		(end 161.657792 -227.739702)
		(width 0.14478)
		(layer "In4.Cu")
		(net "M_J_CPU1_SA_DQ<26>")
	)
	(segment
		(start 160.433766 -228.30409)
		(end 160.649412 -228.51999)
		(width 0.14478)
		(layer "In4.Cu")
		(net "M_J_CPU1_SA_DQ<26>")
	)
	(segment
		(start 181.0639 -226.660456)
		(end 181.914038 -225.810318)
		(width 0.14478)
		(layer "In4.Cu")
		(net "M_J_CPU1_SA_DQ<26>")
	)
	(segment
		(start 161.604198 -226.905566)
		(end 161.76625 -226.743514)
		(width 0.14478)
		(layer "In4.Cu")
		(net "M_J_CPU1_SA_DQ<26>")
	)
	(segment
		(start 177.92192 -225.810318)
		(end 178.772058 -226.660456)
		(width 0.14478)
		(layer "In4.Cu")
		(net "M_J_CPU1_SA_DQ<26>")
	)
	(segment
		(start 165.37559 -226.349306)
		(end 165.68674 -226.660456)
		(width 0.14478)
		(layer "In4.Cu")
		(net "M_J_CPU1_SA_DQ<26>")
	)
	(segment
		(start 181.914038 -225.810318)
		(end 186.635136 -225.810318)
		(width 0.14478)
		(layer "In4.Cu")
		(net "M_J_CPU1_SA_DQ<26>")
	)
	(segment
		(start 159.47898 -229.690422)
		(end 159.263334 -229.474522)
		(width 0.14478)
		(layer "In4.Cu")
		(net "M_J_CPU1_SA_DQ<26>")
	)
	(segment
		(start 150.59533 -238.802164)
		(end 159.47898 -229.918514)
		(width 0.14478)
		(layer "In4.Cu")
		(net "M_J_CPU1_SA_DQ<26>")
	)
	(segment
		(start 186.635136 -225.810318)
		(end 187.060078 -226.23526)
		(width 0.14478)
		(layer "In4.Cu")
		(net "M_J_CPU1_SA_DQ<26>")
	)
	(segment
		(start 159.653478 -229.084378)
		(end 159.869124 -229.300278)
		(width 0.14478)
		(layer "In4.Cu")
		(net "M_J_CPU1_SA_DQ<26>")
	)
	(segment
		(start 160.043622 -228.466142)
		(end 160.205674 -228.30409)
		(width 0.14478)
		(layer "In4.Cu")
		(net "M_J_CPU1_SA_DQ<26>")
	)
	(segment
		(start 143.451834 -240.111788)
		(end 143.462248 -240.117884)
		(width 0.0889)
		(layer "In4.Cu")
		(net "M_J_CPU1_SA_DQ<26>")
	)
	(segment
		(start 145.749264 -240.060988)
		(end 146.558508 -239.251744)
		(width 0.0889)
		(layer "In4.Cu")
		(net "M_J_CPU1_SA_DQ<26>")
	)
	(segment
		(start 159.263334 -229.474522)
		(end 159.263334 -229.24643)
		(width 0.14478)
		(layer "In4.Cu")
		(net "M_J_CPU1_SA_DQ<26>")
	)
	(segment
		(start 134.04342 -240.106962)
		(end 134.051802 -240.111788)
		(width 0.0889)
		(layer "In4.Cu")
		(net "M_J_CPU1_SA_DQ<26>")
	)
	(segment
		(start 166.299388 -226.660456)
		(end 167.149526 -225.810318)
		(width 0.14478)
		(layer "In4.Cu")
		(net "M_J_CPU1_SA_DQ<26>")
	)
	(segment
		(start 142.503398 -240.106962)
		(end 142.51178 -240.111788)
		(width 0.0889)
		(layer "In4.Cu")
		(net "M_J_CPU1_SA_DQ<26>")
	)
	(segment
		(start 144.384268 -240.106962)
		(end 144.39265 -240.111788)
		(width 0.0889)
		(layer "In4.Cu")
		(net "M_J_CPU1_SA_DQ<26>")
	)
	(segment
		(start 160.043622 -228.694234)
		(end 160.043622 -228.466142)
		(width 0.14478)
		(layer "In4.Cu")
		(net "M_J_CPU1_SA_DQ<26>")
	)
	(segment
		(start 159.47898 -229.918514)
		(end 159.47898 -229.690422)
		(width 0.14478)
		(layer "In4.Cu")
		(net "M_J_CPU1_SA_DQ<26>")
	)
	(segment
		(start 160.649412 -228.51999)
		(end 160.877504 -228.51999)
		(width 0.14478)
		(layer "In4.Cu")
		(net "M_J_CPU1_SA_DQ<26>")
	)
	(segment
		(start 147.945094 -238.802164)
		(end 150.59533 -238.802164)
		(width 0.14478)
		(layer "In4.Cu")
		(net "M_J_CPU1_SA_DQ<26>")
	)
	(segment
		(start 147.615148 -238.802164)
		(end 147.945094 -238.802164)
		(width 0.0889)
		(layer "In4.Cu")
		(net "M_J_CPU1_SA_DQ<26>")
	)
	(segment
		(start 167.149526 -225.810318)
		(end 169.942256 -225.810318)
		(width 0.14478)
		(layer "In4.Cu")
		(net "M_J_CPU1_SA_DQ<26>")
	)
	(segment
		(start 161.76625 -226.743514)
		(end 161.994342 -226.743514)
		(width 0.14478)
		(layer "In4.Cu")
		(net "M_J_CPU1_SA_DQ<26>")
	)
	(segment
		(start 161.994342 -226.743514)
		(end 162.209988 -226.959414)
		(width 0.14478)
		(layer "In4.Cu")
		(net "M_J_CPU1_SA_DQ<26>")
	)
	(segment
		(start 161.819844 -227.349558)
		(end 161.604198 -227.133658)
		(width 0.14478)
		(layer "In4.Cu")
		(net "M_J_CPU1_SA_DQ<26>")
	)
	(segment
		(start 173.64075 -226.660456)
		(end 174.490888 -225.810318)
		(width 0.14478)
		(layer "In4.Cu")
		(net "M_J_CPU1_SA_DQ<26>")
	)
	(segment
		(start 161.039556 -228.357938)
		(end 161.039556 -228.129846)
		(width 0.14478)
		(layer "In4.Cu")
		(net "M_J_CPU1_SA_DQ<26>")
	)
	(segment
		(start 160.985962 -227.523802)
		(end 161.214054 -227.523802)
		(width 0.14478)
		(layer "In4.Cu")
		(net "M_J_CPU1_SA_DQ<26>")
	)
	(segment
		(start 160.877504 -228.51999)
		(end 161.039556 -228.357938)
		(width 0.14478)
		(layer "In4.Cu")
		(net "M_J_CPU1_SA_DQ<26>")
	)
	(segment
		(start 161.657792 -227.739702)
		(end 161.819844 -227.57765)
		(width 0.14478)
		(layer "In4.Cu")
		(net "M_J_CPU1_SA_DQ<26>")
	)
	(segment
		(start 140.257784 -240.111788)
		(end 140.266166 -240.106962)
		(width 0.0889)
		(layer "In4.Cu")
		(net "M_J_CPU1_SA_DQ<26>")
	)
	(segment
		(start 159.425386 -229.084378)
		(end 159.653478 -229.084378)
		(width 0.14478)
		(layer "In4.Cu")
		(net "M_J_CPU1_SA_DQ<26>")
	)
	(segment
		(start 137.803382 -240.106962)
		(end 137.811764 -240.111788)
		(width 0.0889)
		(layer "In4.Cu")
		(net "M_J_CPU1_SA_DQ<26>")
	)
	(segment
		(start 139.31773 -240.111788)
		(end 139.326112 -240.106962)
		(width 0.0889)
		(layer "In4.Cu")
		(net "M_J_CPU1_SA_DQ<26>")
	)
	(arc
		(start 134.626096 -240.106962)
		(mid 134.809604 -240.061468)
		(end 134.991856 -240.111788)
		(width 0.0889)
		(layer "In4.Cu")
		(net "M_J_CPU1_SA_DQ<26>")
	)
	(arc
		(start 139.326112 -240.106962)
		(mid 139.50962 -240.061468)
		(end 139.691872 -240.111788)
		(width 0.0889)
		(layer "In4.Cu")
		(net "M_J_CPU1_SA_DQ<26>")
	)
	(arc
		(start 136.87171 -240.111788)
		(mid 137.154666 -240.187965)
		(end 137.437622 -240.111788)
		(width 0.0889)
		(layer "In4.Cu")
		(net "M_J_CPU1_SA_DQ<26>")
	)
	(arc
		(start 137.811764 -240.111788)
		(mid 138.09472 -240.187965)
		(end 138.377676 -240.111788)
		(width 0.0889)
		(layer "In4.Cu")
		(net "M_J_CPU1_SA_DQ<26>")
	)
	(arc
		(start 134.991856 -240.111788)
		(mid 135.274812 -240.187965)
		(end 135.557768 -240.111788)
		(width 0.0889)
		(layer "In4.Cu")
		(net "M_J_CPU1_SA_DQ<26>")
	)
	(arc
		(start 135.56615 -240.106962)
		(mid 135.749658 -240.061468)
		(end 135.93191 -240.111788)
		(width 0.0889)
		(layer "In4.Cu")
		(net "M_J_CPU1_SA_DQ<26>")
	)
	(arc
		(start 143.086074 -240.106962)
		(mid 143.269582 -240.061468)
		(end 143.451834 -240.111788)
		(width 0.0889)
		(layer "In4.Cu")
		(net "M_J_CPU1_SA_DQ<26>")
	)
	(arc
		(start 139.691872 -240.111788)
		(mid 139.974828 -240.187965)
		(end 140.257784 -240.111788)
		(width 0.0889)
		(layer "In4.Cu")
		(net "M_J_CPU1_SA_DQ<26>")
	)
	(arc
		(start 132.792978 -240.085626)
		(mid 132.950488 -240.062428)
		(end 133.103366 -240.106962)
		(width 0.0889)
		(layer "In4.Cu")
		(net "M_J_CPU1_SA_DQ<26>")
	)
	(arc
		(start 136.497822 -240.111788)
		(mid 136.684766 -240.061533)
		(end 136.87171 -240.111788)
		(width 0.0889)
		(layer "In4.Cu")
		(net "M_J_CPU1_SA_DQ<26>")
	)
	(arc
		(start 143.462248 -240.117884)
		(mid 143.740934 -240.188104)
		(end 144.018 -240.111788)
		(width 0.0889)
		(layer "In4.Cu")
		(net "M_J_CPU1_SA_DQ<26>")
	)
	(arc
		(start 138.751818 -240.111788)
		(mid 139.034774 -240.187965)
		(end 139.31773 -240.111788)
		(width 0.0889)
		(layer "In4.Cu")
		(net "M_J_CPU1_SA_DQ<26>")
	)
	(arc
		(start 142.137638 -240.111788)
		(mid 142.319889 -240.061438)
		(end 142.503398 -240.106962)
		(width 0.0889)
		(layer "In4.Cu")
		(net "M_J_CPU1_SA_DQ<26>")
	)
	(arc
		(start 137.437622 -240.111788)
		(mid 137.619873 -240.061438)
		(end 137.803382 -240.106962)
		(width 0.0889)
		(layer "In4.Cu")
		(net "M_J_CPU1_SA_DQ<26>")
	)
	(arc
		(start 134.051802 -240.111788)
		(mid 134.334758 -240.187965)
		(end 134.617714 -240.111788)
		(width 0.0889)
		(layer "In4.Cu")
		(net "M_J_CPU1_SA_DQ<26>")
	)
	(arc
		(start 144.952466 -240.115344)
		(mid 145.044898 -240.075062)
		(end 145.144744 -240.060988)
		(width 0.0889)
		(layer "In4.Cu")
		(net "M_J_CPU1_SA_DQ<26>")
	)
	(arc
		(start 133.111748 -240.111788)
		(mid 133.394704 -240.187965)
		(end 133.67766 -240.111788)
		(width 0.0889)
		(layer "In4.Cu")
		(net "M_J_CPU1_SA_DQ<26>")
	)
	(arc
		(start 135.93191 -240.111788)
		(mid 136.214866 -240.187965)
		(end 136.497822 -240.111788)
		(width 0.0889)
		(layer "In4.Cu")
		(net "M_J_CPU1_SA_DQ<26>")
	)
	(arc
		(start 141.197838 -240.111788)
		(mid 141.384782 -240.061533)
		(end 141.571726 -240.111788)
		(width 0.0889)
		(layer "In4.Cu")
		(net "M_J_CPU1_SA_DQ<26>")
	)
	(arc
		(start 142.51178 -240.111788)
		(mid 142.794736 -240.187965)
		(end 143.077692 -240.111788)
		(width 0.0889)
		(layer "In4.Cu")
		(net "M_J_CPU1_SA_DQ<26>")
	)
	(arc
		(start 133.67766 -240.111788)
		(mid 133.859911 -240.061438)
		(end 134.04342 -240.106962)
		(width 0.0889)
		(layer "In4.Cu")
		(net "M_J_CPU1_SA_DQ<26>")
	)
	(arc
		(start 140.266166 -240.106962)
		(mid 140.449674 -240.061468)
		(end 140.631926 -240.111788)
		(width 0.0889)
		(layer "In4.Cu")
		(net "M_J_CPU1_SA_DQ<26>")
	)
	(arc
		(start 141.571726 -240.111788)
		(mid 141.854682 -240.187965)
		(end 142.137638 -240.111788)
		(width 0.0889)
		(layer "In4.Cu")
		(net "M_J_CPU1_SA_DQ<26>")
	)
	(arc
		(start 140.631926 -240.111788)
		(mid 140.914882 -240.187965)
		(end 141.197838 -240.111788)
		(width 0.0889)
		(layer "In4.Cu")
		(net "M_J_CPU1_SA_DQ<26>")
	)
	(arc
		(start 144.39265 -240.111788)
		(mid 144.672078 -240.187954)
		(end 144.952466 -240.115344)
		(width 0.0889)
		(layer "In4.Cu")
		(net "M_J_CPU1_SA_DQ<26>")
	)
	(arc
		(start 144.018 -240.111788)
		(mid 144.200505 -240.061311)
		(end 144.384268 -240.106962)
		(width 0.0889)
		(layer "In4.Cu")
		(net "M_J_CPU1_SA_DQ<26>")
	)
	(arc
		(start 138.377676 -240.111788)
		(mid 138.559927 -240.061438)
		(end 138.743436 -240.106962)
		(width 0.0889)
		(layer "In4.Cu")
		(net "M_J_CPU1_SA_DQ<26>")
	)
	(segment
		(start 130.577844 -240.700306)
		(end 131.044696 -240.434368)
		(width 0.10668)
		(layer "F.Cu")
		(net "M_J_CPU1_SA_DQ<25>")
	)
	(segment
		(start 169.512488 -226.660456)
		(end 171.5643 -227.51034)
		(width 0.14478)
		(layer "In4.Cu")
		(net "M_J_CPU1_SA_DQ<25>")
	)
	(segment
		(start 180.632862 -227.51034)
		(end 182.684928 -226.660456)
		(width 0.14478)
		(layer "In4.Cu")
		(net "M_J_CPU1_SA_DQ<25>")
	)
	(segment
		(start 150.784052 -239.256824)
		(end 162.530536 -227.51034)
		(width 0.14478)
		(layer "In4.Cu")
		(net "M_J_CPU1_SA_DQ<25>")
	)
	(segment
		(start 145.667984 -240.756948)
		(end 146.385788 -240.039144)
		(width 0.0889)
		(layer "In4.Cu")
		(net "M_J_CPU1_SA_DQ<25>")
	)
	(segment
		(start 189.023752 -226.660456)
		(end 191.160146 -227.085398)
		(width 0.14478)
		(layer "In4.Cu")
		(net "M_J_CPU1_SA_DQ<25>")
	)
	(segment
		(start 182.684928 -226.660456)
		(end 189.023752 -226.660456)
		(width 0.14478)
		(layer "In4.Cu")
		(net "M_J_CPU1_SA_DQ<25>")
	)
	(segment
		(start 172.98289 -227.51034)
		(end 175.034702 -226.660456)
		(width 0.14478)
		(layer "In4.Cu")
		(net "M_J_CPU1_SA_DQ<25>")
	)
	(segment
		(start 133.103366 -240.761774)
		(end 133.111748 -240.756948)
		(width 0.0889)
		(layer "In4.Cu")
		(net "M_J_CPU1_SA_DQ<25>")
	)
	(segment
		(start 134.617714 -240.756948)
		(end 134.626096 -240.761774)
		(width 0.0889)
		(layer "In4.Cu")
		(net "M_J_CPU1_SA_DQ<25>")
	)
	(segment
		(start 145.332196 -240.756948)
		(end 145.667984 -240.756948)
		(width 0.0889)
		(layer "In4.Cu")
		(net "M_J_CPU1_SA_DQ<25>")
	)
	(segment
		(start 147.668488 -239.256824)
		(end 147.903438 -239.256824)
		(width 0.0889)
		(layer "In4.Cu")
		(net "M_J_CPU1_SA_DQ<25>")
	)
	(segment
		(start 165.515036 -227.51034)
		(end 167.566848 -226.660456)
		(width 0.14478)
		(layer "In4.Cu")
		(net "M_J_CPU1_SA_DQ<25>")
	)
	(segment
		(start 162.530536 -227.51034)
		(end 165.515036 -227.51034)
		(width 0.14478)
		(layer "In4.Cu")
		(net "M_J_CPU1_SA_DQ<25>")
	)
	(segment
		(start 139.31773 -240.756948)
		(end 139.326112 -240.761774)
		(width 0.0889)
		(layer "In4.Cu")
		(net "M_J_CPU1_SA_DQ<25>")
	)
	(segment
		(start 134.04342 -240.761774)
		(end 134.051802 -240.756948)
		(width 0.0889)
		(layer "In4.Cu")
		(net "M_J_CPU1_SA_DQ<25>")
	)
	(segment
		(start 131.044696 -240.434368)
		(end 131.198874 -240.699798)
		(width 0.0889)
		(layer "In4.Cu")
		(net "M_J_CPU1_SA_DQ<25>")
	)
	(segment
		(start 147.404328 -239.520984)
		(end 147.668488 -239.256824)
		(width 0.0889)
		(layer "In4.Cu")
		(net "M_J_CPU1_SA_DQ<25>")
	)
	(segment
		(start 171.5643 -227.51034)
		(end 172.98289 -227.51034)
		(width 0.14478)
		(layer "In4.Cu")
		(net "M_J_CPU1_SA_DQ<25>")
	)
	(segment
		(start 135.557768 -240.756948)
		(end 135.56615 -240.761774)
		(width 0.0889)
		(layer "In4.Cu")
		(net "M_J_CPU1_SA_DQ<25>")
	)
	(segment
		(start 142.503398 -240.761774)
		(end 142.51178 -240.756948)
		(width 0.0889)
		(layer "In4.Cu")
		(net "M_J_CPU1_SA_DQ<25>")
	)
	(segment
		(start 175.034702 -226.660456)
		(end 177.27041 -226.660456)
		(width 0.14478)
		(layer "In4.Cu")
		(net "M_J_CPU1_SA_DQ<25>")
	)
	(segment
		(start 144.958054 -240.756694)
		(end 144.976342 -240.767108)
		(width 0.0889)
		(layer "In4.Cu")
		(net "M_J_CPU1_SA_DQ<25>")
	)
	(segment
		(start 179.322476 -227.51034)
		(end 180.632862 -227.51034)
		(width 0.14478)
		(layer "In4.Cu")
		(net "M_J_CPU1_SA_DQ<25>")
	)
	(segment
		(start 131.198874 -240.699798)
		(end 131.29514 -240.725198)
		(width 0.0889)
		(layer "In4.Cu")
		(net "M_J_CPU1_SA_DQ<25>")
	)
	(segment
		(start 146.596608 -239.520984)
		(end 147.404328 -239.520984)
		(width 0.0889)
		(layer "In4.Cu")
		(net "M_J_CPU1_SA_DQ<25>")
	)
	(segment
		(start 144.380966 -240.763806)
		(end 144.39265 -240.756948)
		(width 0.0889)
		(layer "In4.Cu")
		(net "M_J_CPU1_SA_DQ<25>")
	)
	(segment
		(start 146.385788 -239.731804)
		(end 146.596608 -239.520984)
		(width 0.0889)
		(layer "In4.Cu")
		(net "M_J_CPU1_SA_DQ<25>")
	)
	(segment
		(start 144.952466 -240.753392)
		(end 144.958054 -240.756694)
		(width 0.0889)
		(layer "In4.Cu")
		(net "M_J_CPU1_SA_DQ<25>")
	)
	(segment
		(start 146.385788 -240.039144)
		(end 146.385788 -239.731804)
		(width 0.0889)
		(layer "In4.Cu")
		(net "M_J_CPU1_SA_DQ<25>")
	)
	(segment
		(start 138.743436 -240.761774)
		(end 138.751818 -240.756948)
		(width 0.0889)
		(layer "In4.Cu")
		(net "M_J_CPU1_SA_DQ<25>")
	)
	(segment
		(start 167.566848 -226.660456)
		(end 169.512488 -226.660456)
		(width 0.14478)
		(layer "In4.Cu")
		(net "M_J_CPU1_SA_DQ<25>")
	)
	(segment
		(start 137.803382 -240.761774)
		(end 137.811764 -240.756948)
		(width 0.0889)
		(layer "In4.Cu")
		(net "M_J_CPU1_SA_DQ<25>")
	)
	(segment
		(start 147.903438 -239.256824)
		(end 150.784052 -239.256824)
		(width 0.14478)
		(layer "In4.Cu")
		(net "M_J_CPU1_SA_DQ<25>")
	)
	(segment
		(start 140.257784 -240.756948)
		(end 140.266166 -240.761774)
		(width 0.0889)
		(layer "In4.Cu")
		(net "M_J_CPU1_SA_DQ<25>")
	)
	(segment
		(start 143.077692 -240.756948)
		(end 143.086074 -240.761774)
		(width 0.0889)
		(layer "In4.Cu")
		(net "M_J_CPU1_SA_DQ<25>")
	)
	(segment
		(start 177.27041 -226.660456)
		(end 179.322476 -227.51034)
		(width 0.14478)
		(layer "In4.Cu")
		(net "M_J_CPU1_SA_DQ<25>")
	)
	(segment
		(start 143.451834 -240.756948)
		(end 143.466566 -240.748312)
		(width 0.0889)
		(layer "In4.Cu")
		(net "M_J_CPU1_SA_DQ<25>")
	)
	(arc
		(start 133.111748 -240.756948)
		(mid 133.394704 -240.680771)
		(end 133.67766 -240.756948)
		(width 0.0889)
		(layer "In4.Cu")
		(net "M_J_CPU1_SA_DQ<25>")
	)
	(arc
		(start 132.171694 -240.756948)
		(mid 132.45465 -240.680771)
		(end 132.737606 -240.756948)
		(width 0.0889)
		(layer "In4.Cu")
		(net "M_J_CPU1_SA_DQ<25>")
	)
	(arc
		(start 142.51178 -240.756948)
		(mid 142.794736 -240.680771)
		(end 143.077692 -240.756948)
		(width 0.0889)
		(layer "In4.Cu")
		(net "M_J_CPU1_SA_DQ<25>")
	)
	(arc
		(start 133.67766 -240.756948)
		(mid 133.859911 -240.807298)
		(end 134.04342 -240.761774)
		(width 0.0889)
		(layer "In4.Cu")
		(net "M_J_CPU1_SA_DQ<25>")
	)
	(arc
		(start 143.466566 -240.748312)
		(mid 143.743549 -240.680508)
		(end 144.018254 -240.756948)
		(width 0.0889)
		(layer "In4.Cu")
		(net "M_J_CPU1_SA_DQ<25>")
	)
	(arc
		(start 139.326112 -240.761774)
		(mid 139.50962 -240.807268)
		(end 139.691872 -240.756948)
		(width 0.0889)
		(layer "In4.Cu")
		(net "M_J_CPU1_SA_DQ<25>")
	)
	(arc
		(start 131.29514 -240.725198)
		(mid 131.550205 -240.681847)
		(end 131.797806 -240.756948)
		(width 0.0889)
		(layer "In4.Cu")
		(net "M_J_CPU1_SA_DQ<25>")
	)
	(arc
		(start 140.631926 -240.756948)
		(mid 140.914882 -240.680771)
		(end 141.197838 -240.756948)
		(width 0.0889)
		(layer "In4.Cu")
		(net "M_J_CPU1_SA_DQ<25>")
	)
	(arc
		(start 144.39265 -240.756948)
		(mid 144.672078 -240.680782)
		(end 144.952466 -240.753392)
		(width 0.0889)
		(layer "In4.Cu")
		(net "M_J_CPU1_SA_DQ<25>")
	)
	(arc
		(start 141.197838 -240.756948)
		(mid 141.384782 -240.807203)
		(end 141.571726 -240.756948)
		(width 0.0889)
		(layer "In4.Cu")
		(net "M_J_CPU1_SA_DQ<25>")
	)
	(arc
		(start 135.93191 -240.756948)
		(mid 136.214866 -240.680771)
		(end 136.497822 -240.756948)
		(width 0.0889)
		(layer "In4.Cu")
		(net "M_J_CPU1_SA_DQ<25>")
	)
	(arc
		(start 144.018254 -240.756948)
		(mid 144.198712 -240.807392)
		(end 144.380966 -240.763806)
		(width 0.0889)
		(layer "In4.Cu")
		(net "M_J_CPU1_SA_DQ<25>")
	)
	(arc
		(start 137.437622 -240.756948)
		(mid 137.619873 -240.807298)
		(end 137.803382 -240.761774)
		(width 0.0889)
		(layer "In4.Cu")
		(net "M_J_CPU1_SA_DQ<25>")
	)
	(arc
		(start 143.086074 -240.761774)
		(mid 143.269582 -240.807268)
		(end 143.451834 -240.756948)
		(width 0.0889)
		(layer "In4.Cu")
		(net "M_J_CPU1_SA_DQ<25>")
	)
	(arc
		(start 138.377676 -240.756948)
		(mid 138.559927 -240.807298)
		(end 138.743436 -240.761774)
		(width 0.0889)
		(layer "In4.Cu")
		(net "M_J_CPU1_SA_DQ<25>")
	)
	(arc
		(start 135.56615 -240.761774)
		(mid 135.749658 -240.807268)
		(end 135.93191 -240.756948)
		(width 0.0889)
		(layer "In4.Cu")
		(net "M_J_CPU1_SA_DQ<25>")
	)
	(arc
		(start 144.976342 -240.767108)
		(mid 145.155571 -240.807261)
		(end 145.332196 -240.756948)
		(width 0.0889)
		(layer "In4.Cu")
		(net "M_J_CPU1_SA_DQ<25>")
	)
	(arc
		(start 142.137638 -240.756948)
		(mid 142.319889 -240.807298)
		(end 142.503398 -240.761774)
		(width 0.0889)
		(layer "In4.Cu")
		(net "M_J_CPU1_SA_DQ<25>")
	)
	(arc
		(start 134.051802 -240.756948)
		(mid 134.334758 -240.680771)
		(end 134.617714 -240.756948)
		(width 0.0889)
		(layer "In4.Cu")
		(net "M_J_CPU1_SA_DQ<25>")
	)
	(arc
		(start 140.266166 -240.761774)
		(mid 140.449674 -240.807268)
		(end 140.631926 -240.756948)
		(width 0.0889)
		(layer "In4.Cu")
		(net "M_J_CPU1_SA_DQ<25>")
	)
	(arc
		(start 132.737606 -240.756948)
		(mid 132.919857 -240.807298)
		(end 133.103366 -240.761774)
		(width 0.0889)
		(layer "In4.Cu")
		(net "M_J_CPU1_SA_DQ<25>")
	)
	(arc
		(start 141.571726 -240.756948)
		(mid 141.854682 -240.680771)
		(end 142.137638 -240.756948)
		(width 0.0889)
		(layer "In4.Cu")
		(net "M_J_CPU1_SA_DQ<25>")
	)
	(arc
		(start 134.991856 -240.756948)
		(mid 135.274812 -240.680771)
		(end 135.557768 -240.756948)
		(width 0.0889)
		(layer "In4.Cu")
		(net "M_J_CPU1_SA_DQ<25>")
	)
	(arc
		(start 139.691872 -240.756948)
		(mid 139.974828 -240.680771)
		(end 140.257784 -240.756948)
		(width 0.0889)
		(layer "In4.Cu")
		(net "M_J_CPU1_SA_DQ<25>")
	)
	(arc
		(start 134.626096 -240.761774)
		(mid 134.809604 -240.807268)
		(end 134.991856 -240.756948)
		(width 0.0889)
		(layer "In4.Cu")
		(net "M_J_CPU1_SA_DQ<25>")
	)
	(arc
		(start 131.797806 -240.756948)
		(mid 131.98475 -240.807203)
		(end 132.171694 -240.756948)
		(width 0.0889)
		(layer "In4.Cu")
		(net "M_J_CPU1_SA_DQ<25>")
	)
	(arc
		(start 136.87171 -240.756948)
		(mid 137.154666 -240.680771)
		(end 137.437622 -240.756948)
		(width 0.0889)
		(layer "In4.Cu")
		(net "M_J_CPU1_SA_DQ<25>")
	)
	(arc
		(start 136.497822 -240.756948)
		(mid 136.684766 -240.807203)
		(end 136.87171 -240.756948)
		(width 0.0889)
		(layer "In4.Cu")
		(net "M_J_CPU1_SA_DQ<25>")
	)
	(arc
		(start 137.811764 -240.756948)
		(mid 138.09472 -240.680771)
		(end 138.377676 -240.756948)
		(width 0.0889)
		(layer "In4.Cu")
		(net "M_J_CPU1_SA_DQ<25>")
	)
	(arc
		(start 138.751818 -240.756948)
		(mid 139.034774 -240.680771)
		(end 139.31773 -240.756948)
		(width 0.0889)
		(layer "In4.Cu")
		(net "M_J_CPU1_SA_DQ<25>")
	)
	(segment
		(start 131.987798 -239.8903)
		(end 132.45465 -239.624362)
		(width 0.10668)
		(layer "F.Cu")
		(net "M_J_CPU1_SA_DQ<24>")
	)
	(segment
		(start 137.907776 -239.946942)
		(end 137.916158 -239.951768)
		(width 0.0889)
		(layer "In4.Cu")
		(net "M_J_CPU1_SA_DQ<24>")
	)
	(segment
		(start 132.608828 -239.889792)
		(end 132.705094 -239.915192)
		(width 0.0889)
		(layer "In4.Cu")
		(net "M_J_CPU1_SA_DQ<24>")
	)
	(segment
		(start 146.454368 -239.010444)
		(end 146.934428 -239.010444)
		(width 0.0889)
		(layer "In4.Cu")
		(net "M_J_CPU1_SA_DQ<24>")
	)
	(segment
		(start 145.594324 -239.870488)
		(end 146.454368 -239.010444)
		(width 0.0889)
		(layer "In4.Cu")
		(net "M_J_CPU1_SA_DQ<24>")
	)
	(segment
		(start 141.667738 -239.946942)
		(end 141.67612 -239.951768)
		(width 0.0889)
		(layer "In4.Cu")
		(net "M_J_CPU1_SA_DQ<24>")
	)
	(segment
		(start 140.15339 -239.951768)
		(end 140.161772 -239.946942)
		(width 0.0889)
		(layer "In4.Cu")
		(net "M_J_CPU1_SA_DQ<24>")
	)
	(segment
		(start 132.45465 -239.624362)
		(end 132.608828 -239.889792)
		(width 0.0889)
		(layer "In4.Cu")
		(net "M_J_CPU1_SA_DQ<24>")
	)
	(segment
		(start 136.967722 -239.946942)
		(end 136.976104 -239.951768)
		(width 0.0889)
		(layer "In4.Cu")
		(net "M_J_CPU1_SA_DQ<24>")
	)
	(segment
		(start 147.95881 -238.347504)
		(end 150.407878 -238.347504)
		(width 0.14478)
		(layer "In4.Cu")
		(net "M_J_CPU1_SA_DQ<24>")
	)
	(segment
		(start 170.626786 -225.810318)
		(end 173.684946 -225.810318)
		(width 0.14478)
		(layer "In4.Cu")
		(net "M_J_CPU1_SA_DQ<24>")
	)
	(segment
		(start 150.407878 -238.347504)
		(end 158.813754 -229.941628)
		(width 0.14478)
		(layer "In4.Cu")
		(net "M_J_CPU1_SA_DQ<24>")
	)
	(segment
		(start 173.684946 -225.810318)
		(end 174.53483 -224.960434)
		(width 0.14478)
		(layer "In4.Cu")
		(net "M_J_CPU1_SA_DQ<24>")
	)
	(segment
		(start 145.144744 -239.870488)
		(end 145.594324 -239.870488)
		(width 0.0889)
		(layer "In4.Cu")
		(net "M_J_CPU1_SA_DQ<24>")
	)
	(segment
		(start 182.07736 -224.960434)
		(end 190.735204 -224.960434)
		(width 0.14478)
		(layer "In4.Cu")
		(net "M_J_CPU1_SA_DQ<24>")
	)
	(segment
		(start 166.17442 -225.810318)
		(end 167.024304 -224.960434)
		(width 0.14478)
		(layer "In4.Cu")
		(net "M_J_CPU1_SA_DQ<24>")
	)
	(segment
		(start 177.751994 -224.960434)
		(end 178.601878 -225.810318)
		(width 0.14478)
		(layer "In4.Cu")
		(net "M_J_CPU1_SA_DQ<24>")
	)
	(segment
		(start 135.453374 -239.951768)
		(end 135.461756 -239.946942)
		(width 0.0889)
		(layer "In4.Cu")
		(net "M_J_CPU1_SA_DQ<24>")
	)
	(segment
		(start 158.813754 -229.05974)
		(end 162.063176 -225.810318)
		(width 0.14478)
		(layer "In4.Cu")
		(net "M_J_CPU1_SA_DQ<24>")
	)
	(segment
		(start 136.393428 -239.951768)
		(end 136.40181 -239.946942)
		(width 0.0889)
		(layer "In4.Cu")
		(net "M_J_CPU1_SA_DQ<24>")
	)
	(segment
		(start 178.601878 -225.810318)
		(end 181.227476 -225.810318)
		(width 0.14478)
		(layer "In4.Cu")
		(net "M_J_CPU1_SA_DQ<24>")
	)
	(segment
		(start 133.20776 -239.946942)
		(end 133.216142 -239.951768)
		(width 0.0889)
		(layer "In4.Cu")
		(net "M_J_CPU1_SA_DQ<24>")
	)
	(segment
		(start 167.024304 -224.960434)
		(end 169.776902 -224.960434)
		(width 0.14478)
		(layer "In4.Cu")
		(net "M_J_CPU1_SA_DQ<24>")
	)
	(segment
		(start 190.735204 -224.960434)
		(end 191.160146 -225.385376)
		(width 0.14478)
		(layer "In4.Cu")
		(net "M_J_CPU1_SA_DQ<24>")
	)
	(segment
		(start 181.227476 -225.810318)
		(end 182.07736 -224.960434)
		(width 0.14478)
		(layer "In4.Cu")
		(net "M_J_CPU1_SA_DQ<24>")
	)
	(segment
		(start 158.813754 -229.941628)
		(end 158.813754 -229.05974)
		(width 0.14478)
		(layer "In4.Cu")
		(net "M_J_CPU1_SA_DQ<24>")
	)
	(segment
		(start 143.547592 -239.946942)
		(end 143.555974 -239.951768)
		(width 0.0889)
		(layer "In4.Cu")
		(net "M_J_CPU1_SA_DQ<24>")
	)
	(segment
		(start 174.53483 -224.960434)
		(end 177.751994 -224.960434)
		(width 0.14478)
		(layer "In4.Cu")
		(net "M_J_CPU1_SA_DQ<24>")
	)
	(segment
		(start 169.776902 -224.960434)
		(end 170.626786 -225.810318)
		(width 0.14478)
		(layer "In4.Cu")
		(net "M_J_CPU1_SA_DQ<24>")
	)
	(segment
		(start 141.093444 -239.951768)
		(end 141.101826 -239.946942)
		(width 0.0889)
		(layer "In4.Cu")
		(net "M_J_CPU1_SA_DQ<24>")
	)
	(segment
		(start 144.477994 -239.940846)
		(end 144.488408 -239.946942)
		(width 0.0889)
		(layer "In4.Cu")
		(net "M_J_CPU1_SA_DQ<24>")
	)
	(segment
		(start 162.063176 -225.810318)
		(end 166.17442 -225.810318)
		(width 0.14478)
		(layer "In4.Cu")
		(net "M_J_CPU1_SA_DQ<24>")
	)
	(segment
		(start 147.597368 -238.347504)
		(end 147.95881 -238.347504)
		(width 0.0889)
		(layer "In4.Cu")
		(net "M_J_CPU1_SA_DQ<24>")
	)
	(segment
		(start 146.934428 -239.010444)
		(end 147.597368 -238.347504)
		(width 0.0889)
		(layer "In4.Cu")
		(net "M_J_CPU1_SA_DQ<24>")
	)
	(arc
		(start 141.101826 -239.946942)
		(mid 141.384782 -239.870765)
		(end 141.667738 -239.946942)
		(width 0.0889)
		(layer "In4.Cu")
		(net "M_J_CPU1_SA_DQ<24>")
	)
	(arc
		(start 141.67612 -239.951768)
		(mid 141.859628 -239.997262)
		(end 142.04188 -239.946942)
		(width 0.0889)
		(layer "In4.Cu")
		(net "M_J_CPU1_SA_DQ<24>")
	)
	(arc
		(start 143.555974 -239.951768)
		(mid 143.739736 -239.997384)
		(end 143.922242 -239.946942)
		(width 0.0889)
		(layer "In4.Cu")
		(net "M_J_CPU1_SA_DQ<24>")
	)
	(arc
		(start 135.461756 -239.946942)
		(mid 135.744712 -239.870765)
		(end 136.027668 -239.946942)
		(width 0.0889)
		(layer "In4.Cu")
		(net "M_J_CPU1_SA_DQ<24>")
	)
	(arc
		(start 142.98168 -239.946942)
		(mid 143.264636 -239.870765)
		(end 143.547592 -239.946942)
		(width 0.0889)
		(layer "In4.Cu")
		(net "M_J_CPU1_SA_DQ<24>")
	)
	(arc
		(start 140.727684 -239.946942)
		(mid 140.909935 -239.997292)
		(end 141.093444 -239.951768)
		(width 0.0889)
		(layer "In4.Cu")
		(net "M_J_CPU1_SA_DQ<24>")
	)
	(arc
		(start 136.976104 -239.951768)
		(mid 137.159612 -239.997262)
		(end 137.341864 -239.946942)
		(width 0.0889)
		(layer "In4.Cu")
		(net "M_J_CPU1_SA_DQ<24>")
	)
	(arc
		(start 134.147814 -239.946942)
		(mid 134.334758 -239.997197)
		(end 134.521702 -239.946942)
		(width 0.0889)
		(layer "In4.Cu")
		(net "M_J_CPU1_SA_DQ<24>")
	)
	(arc
		(start 140.161772 -239.946942)
		(mid 140.444728 -239.870765)
		(end 140.727684 -239.946942)
		(width 0.0889)
		(layer "In4.Cu")
		(net "M_J_CPU1_SA_DQ<24>")
	)
	(arc
		(start 138.281918 -239.946942)
		(mid 138.564874 -239.870765)
		(end 138.84783 -239.946942)
		(width 0.0889)
		(layer "In4.Cu")
		(net "M_J_CPU1_SA_DQ<24>")
	)
	(arc
		(start 144.488408 -239.946942)
		(mid 144.666058 -239.997202)
		(end 144.84604 -239.956086)
		(width 0.0889)
		(layer "In4.Cu")
		(net "M_J_CPU1_SA_DQ<24>")
	)
	(arc
		(start 135.087614 -239.946942)
		(mid 135.269865 -239.997292)
		(end 135.453374 -239.951768)
		(width 0.0889)
		(layer "In4.Cu")
		(net "M_J_CPU1_SA_DQ<24>")
	)
	(arc
		(start 139.78763 -239.946942)
		(mid 139.969881 -239.997292)
		(end 140.15339 -239.951768)
		(width 0.0889)
		(layer "In4.Cu")
		(net "M_J_CPU1_SA_DQ<24>")
	)
	(arc
		(start 144.84604 -239.956086)
		(mid 144.989379 -239.892299)
		(end 145.144744 -239.870488)
		(width 0.0889)
		(layer "In4.Cu")
		(net "M_J_CPU1_SA_DQ<24>")
	)
	(arc
		(start 137.916158 -239.951768)
		(mid 138.099666 -239.997262)
		(end 138.281918 -239.946942)
		(width 0.0889)
		(layer "In4.Cu")
		(net "M_J_CPU1_SA_DQ<24>")
	)
	(arc
		(start 134.521702 -239.946942)
		(mid 134.804658 -239.870765)
		(end 135.087614 -239.946942)
		(width 0.0889)
		(layer "In4.Cu")
		(net "M_J_CPU1_SA_DQ<24>")
	)
	(arc
		(start 136.40181 -239.946942)
		(mid 136.684766 -239.870765)
		(end 136.967722 -239.946942)
		(width 0.0889)
		(layer "In4.Cu")
		(net "M_J_CPU1_SA_DQ<24>")
	)
	(arc
		(start 142.607792 -239.946942)
		(mid 142.794736 -239.997197)
		(end 142.98168 -239.946942)
		(width 0.0889)
		(layer "In4.Cu")
		(net "M_J_CPU1_SA_DQ<24>")
	)
	(arc
		(start 137.341864 -239.946942)
		(mid 137.62482 -239.870765)
		(end 137.907776 -239.946942)
		(width 0.0889)
		(layer "In4.Cu")
		(net "M_J_CPU1_SA_DQ<24>")
	)
	(arc
		(start 142.04188 -239.946942)
		(mid 142.324836 -239.870765)
		(end 142.607792 -239.946942)
		(width 0.0889)
		(layer "In4.Cu")
		(net "M_J_CPU1_SA_DQ<24>")
	)
	(arc
		(start 132.705094 -239.915192)
		(mid 132.960159 -239.871841)
		(end 133.20776 -239.946942)
		(width 0.0889)
		(layer "In4.Cu")
		(net "M_J_CPU1_SA_DQ<24>")
	)
	(arc
		(start 133.581902 -239.946942)
		(mid 133.864858 -239.870765)
		(end 134.147814 -239.946942)
		(width 0.0889)
		(layer "In4.Cu")
		(net "M_J_CPU1_SA_DQ<24>")
	)
	(arc
		(start 139.221718 -239.946942)
		(mid 139.504674 -239.870765)
		(end 139.78763 -239.946942)
		(width 0.0889)
		(layer "In4.Cu")
		(net "M_J_CPU1_SA_DQ<24>")
	)
	(arc
		(start 133.216142 -239.951768)
		(mid 133.39965 -239.997262)
		(end 133.581902 -239.946942)
		(width 0.0889)
		(layer "In4.Cu")
		(net "M_J_CPU1_SA_DQ<24>")
	)
	(arc
		(start 143.922242 -239.946942)
		(mid 144.199309 -239.870671)
		(end 144.477994 -239.940846)
		(width 0.0889)
		(layer "In4.Cu")
		(net "M_J_CPU1_SA_DQ<24>")
	)
	(arc
		(start 138.84783 -239.946942)
		(mid 139.034774 -239.997197)
		(end 139.221718 -239.946942)
		(width 0.0889)
		(layer "In4.Cu")
		(net "M_J_CPU1_SA_DQ<24>")
	)
	(arc
		(start 136.027668 -239.946942)
		(mid 136.209919 -239.997292)
		(end 136.393428 -239.951768)
		(width 0.0889)
		(layer "In4.Cu")
		(net "M_J_CPU1_SA_DQ<24>")
	)
	(segment
		(start 131.047998 -239.8903)
		(end 131.51485 -239.624362)
		(width 0.10668)
		(layer "F.Cu")
		(net "M_J_CPU1_SA_DQ<23>")
	)
	(segment
		(start 185.406538 -224.110296)
		(end 185.568082 -223.948752)
		(width 0.14478)
		(layer "In4.Cu")
		(net "M_J_CPU1_SA_DQ<23>")
	)
	(segment
		(start 161.35477 -225.739198)
		(end 161.35477 -225.510598)
		(width 0.14478)
		(layer "In4.Cu")
		(net "M_J_CPU1_SA_DQ<23>")
	)
	(segment
		(start 186.119516 -223.94545)
		(end 186.119516 -223.948752)
		(width 0.14478)
		(layer "In4.Cu")
		(net "M_J_CPU1_SA_DQ<23>")
	)
	(segment
		(start 131.360672 -239.358932)
		(end 131.383024 -239.27562)
		(width 0.0889)
		(layer "In4.Cu")
		(net "M_J_CPU1_SA_DQ<23>")
	)
	(segment
		(start 158.623762 -228.241606)
		(end 158.852362 -228.241606)
		(width 0.14478)
		(layer "In4.Cu")
		(net "M_J_CPU1_SA_DQ<23>")
	)
	(segment
		(start 184.465214 -223.948752)
		(end 184.465214 -223.94545)
		(width 0.14478)
		(layer "In4.Cu")
		(net "M_J_CPU1_SA_DQ<23>")
	)
	(segment
		(start 158.262574 -229.692962)
		(end 158.262574 -228.602794)
		(width 0.14478)
		(layer "In4.Cu")
		(net "M_J_CPU1_SA_DQ<23>")
	)
	(segment
		(start 160.47466 -225.639376)
		(end 160.70326 -225.639376)
		(width 0.14478)
		(layer "In4.Cu")
		(net "M_J_CPU1_SA_DQ<23>")
	)
	(segment
		(start 159.532828 -226.581208)
		(end 159.694372 -226.419664)
		(width 0.14478)
		(layer "In4.Cu")
		(net "M_J_CPU1_SA_DQ<23>")
	)
	(segment
		(start 131.51485 -239.624362)
		(end 131.360672 -239.358932)
		(width 0.0889)
		(layer "In4.Cu")
		(net "M_J_CPU1_SA_DQ<23>")
	)
	(segment
		(start 159.922972 -226.419664)
		(end 160.184338 -226.68103)
		(width 0.14478)
		(layer "In4.Cu")
		(net "M_J_CPU1_SA_DQ<23>")
	)
	(segment
		(start 165.413436 -224.650046)
		(end 165.723824 -224.960434)
		(width 0.14478)
		(layer "In4.Cu")
		(net "M_J_CPU1_SA_DQ<23>")
	)
	(segment
		(start 161.093404 -225.020632)
		(end 161.254948 -224.859088)
		(width 0.14478)
		(layer "In4.Cu")
		(net "M_J_CPU1_SA_DQ<23>")
	)
	(segment
		(start 159.013906 -227.851462)
		(end 158.75254 -227.590096)
		(width 0.14478)
		(layer "In4.Cu")
		(net "M_J_CPU1_SA_DQ<23>")
	)
	(segment
		(start 160.184338 -226.68103)
		(end 160.412938 -226.68103)
		(width 0.14478)
		(layer "In4.Cu")
		(net "M_J_CPU1_SA_DQ<23>")
	)
	(segment
		(start 143.547592 -239.301782)
		(end 143.555974 -239.296956)
		(width 0.0889)
		(layer "In4.Cu")
		(net "M_J_CPU1_SA_DQ<23>")
	)
	(segment
		(start 178.593496 -224.960434)
		(end 181.214522 -224.960434)
		(width 0.14478)
		(layer "In4.Cu")
		(net "M_J_CPU1_SA_DQ<23>")
	)
	(segment
		(start 184.626758 -223.783906)
		(end 184.855104 -223.783906)
		(width 0.14478)
		(layer "In4.Cu")
		(net "M_J_CPU1_SA_DQ<23>")
	)
	(segment
		(start 185.016648 -223.94545)
		(end 185.016648 -223.948752)
		(width 0.14478)
		(layer "In4.Cu")
		(net "M_J_CPU1_SA_DQ<23>")
	)
	(segment
		(start 136.393428 -239.296956)
		(end 136.40181 -239.301782)
		(width 0.0889)
		(layer "In4.Cu")
		(net "M_J_CPU1_SA_DQ<23>")
	)
	(segment
		(start 170.611038 -224.960434)
		(end 173.662594 -224.960434)
		(width 0.14478)
		(layer "In4.Cu")
		(net "M_J_CPU1_SA_DQ<23>")
	)
	(segment
		(start 144.47393 -239.310418)
		(end 144.488662 -239.301782)
		(width 0.0889)
		(layer "In4.Cu")
		(net "M_J_CPU1_SA_DQ<23>")
	)
	(segment
		(start 147.728686 -237.787434)
		(end 147.856194 -237.787434)
		(width 0.0889)
		(layer "In4.Cu")
		(net "M_J_CPU1_SA_DQ<23>")
	)
	(segment
		(start 158.914084 -227.199952)
		(end 159.142684 -227.199952)
		(width 0.14478)
		(layer "In4.Cu")
		(net "M_J_CPU1_SA_DQ<23>")
	)
	(segment
		(start 165.723824 -224.960434)
		(end 166.065708 -224.960434)
		(width 0.14478)
		(layer "In4.Cu")
		(net "M_J_CPU1_SA_DQ<23>")
	)
	(segment
		(start 166.915846 -224.110296)
		(end 169.7609 -224.110296)
		(width 0.14478)
		(layer "In4.Cu")
		(net "M_J_CPU1_SA_DQ<23>")
	)
	(segment
		(start 145.111724 -239.392206)
		(end 145.678906 -239.392206)
		(width 0.0889)
		(layer "In4.Cu")
		(net "M_J_CPU1_SA_DQ<23>")
	)
	(segment
		(start 140.15339 -239.296956)
		(end 140.161772 -239.301782)
		(width 0.0889)
		(layer "In4.Cu")
		(net "M_J_CPU1_SA_DQ<23>")
	)
	(segment
		(start 160.412938 -226.68103)
		(end 160.574482 -226.519486)
		(width 0.14478)
		(layer "In4.Cu")
		(net "M_J_CPU1_SA_DQ<23>")
	)
	(segment
		(start 185.178192 -224.110296)
		(end 185.406538 -224.110296)
		(width 0.14478)
		(layer "In4.Cu")
		(net "M_J_CPU1_SA_DQ<23>")
	)
	(segment
		(start 173.662594 -224.960434)
		(end 174.512732 -224.110296)
		(width 0.14478)
		(layer "In4.Cu")
		(net "M_J_CPU1_SA_DQ<23>")
	)
	(segment
		(start 161.093404 -225.249232)
		(end 161.093404 -225.020632)
		(width 0.14478)
		(layer "In4.Cu")
		(net "M_J_CPU1_SA_DQ<23>")
	)
	(segment
		(start 186.28106 -224.110296)
		(end 186.635136 -224.110296)
		(width 0.14478)
		(layer "In4.Cu")
		(net "M_J_CPU1_SA_DQ<23>")
	)
	(segment
		(start 185.568082 -223.948752)
		(end 185.568082 -223.94545)
		(width 0.14478)
		(layer "In4.Cu")
		(net "M_J_CPU1_SA_DQ<23>")
	)
	(segment
		(start 163.759134 -224.960434)
		(end 164.069522 -224.650046)
		(width 0.14478)
		(layer "In4.Cu")
		(net "M_J_CPU1_SA_DQ<23>")
	)
	(segment
		(start 174.512732 -224.110296)
		(end 177.743358 -224.110296)
		(width 0.14478)
		(layer "In4.Cu")
		(net "M_J_CPU1_SA_DQ<23>")
	)
	(segment
		(start 158.75254 -227.590096)
		(end 158.75254 -227.361496)
		(width 0.14478)
		(layer "In4.Cu")
		(net "M_J_CPU1_SA_DQ<23>")
	)
	(segment
		(start 146.840956 -238.675164)
		(end 147.728686 -237.787434)
		(width 0.0889)
		(layer "In4.Cu")
		(net "M_J_CPU1_SA_DQ<23>")
	)
	(segment
		(start 166.065708 -224.960434)
		(end 166.915846 -224.110296)
		(width 0.14478)
		(layer "In4.Cu")
		(net "M_J_CPU1_SA_DQ<23>")
	)
	(segment
		(start 141.093444 -239.296956)
		(end 141.101826 -239.301782)
		(width 0.0889)
		(layer "In4.Cu")
		(net "M_J_CPU1_SA_DQ<23>")
	)
	(segment
		(start 158.262574 -228.602794)
		(end 158.623762 -228.241606)
		(width 0.14478)
		(layer "In4.Cu")
		(net "M_J_CPU1_SA_DQ<23>")
	)
	(segment
		(start 160.313116 -226.02952)
		(end 160.313116 -225.80092)
		(width 0.14478)
		(layer "In4.Cu")
		(net "M_J_CPU1_SA_DQ<23>")
	)
	(segment
		(start 164.310568 -224.650046)
		(end 164.620956 -224.960434)
		(width 0.14478)
		(layer "In4.Cu")
		(net "M_J_CPU1_SA_DQ<23>")
	)
	(segment
		(start 177.743358 -224.110296)
		(end 178.593496 -224.960434)
		(width 0.14478)
		(layer "In4.Cu")
		(net "M_J_CPU1_SA_DQ<23>")
	)
	(segment
		(start 150.168102 -237.787434)
		(end 158.262574 -229.692962)
		(width 0.14478)
		(layer "In4.Cu")
		(net "M_J_CPU1_SA_DQ<23>")
	)
	(segment
		(start 163.518088 -224.960434)
		(end 163.759134 -224.960434)
		(width 0.14478)
		(layer "In4.Cu")
		(net "M_J_CPU1_SA_DQ<23>")
	)
	(segment
		(start 137.907776 -239.301782)
		(end 137.916158 -239.296956)
		(width 0.0889)
		(layer "In4.Cu")
		(net "M_J_CPU1_SA_DQ<23>")
	)
	(segment
		(start 159.40405 -227.461318)
		(end 159.63265 -227.461318)
		(width 0.14478)
		(layer "In4.Cu")
		(net "M_J_CPU1_SA_DQ<23>")
	)
	(segment
		(start 164.069522 -224.650046)
		(end 164.310568 -224.650046)
		(width 0.14478)
		(layer "In4.Cu")
		(net "M_J_CPU1_SA_DQ<23>")
	)
	(segment
		(start 159.794194 -227.071174)
		(end 159.532828 -226.809808)
		(width 0.14478)
		(layer "In4.Cu")
		(net "M_J_CPU1_SA_DQ<23>")
	)
	(segment
		(start 162.656266 -224.960434)
		(end 162.966654 -224.650046)
		(width 0.14478)
		(layer "In4.Cu")
		(net "M_J_CPU1_SA_DQ<23>")
	)
	(segment
		(start 185.568082 -223.94545)
		(end 185.729626 -223.783906)
		(width 0.14478)
		(layer "In4.Cu")
		(net "M_J_CPU1_SA_DQ<23>")
	)
	(segment
		(start 182.06466 -224.110296)
		(end 184.30367 -224.110296)
		(width 0.14478)
		(layer "In4.Cu")
		(net "M_J_CPU1_SA_DQ<23>")
	)
	(segment
		(start 186.119516 -223.948752)
		(end 186.28106 -224.110296)
		(width 0.14478)
		(layer "In4.Cu")
		(net "M_J_CPU1_SA_DQ<23>")
	)
	(segment
		(start 161.973514 -225.120454)
		(end 162.133534 -224.960434)
		(width 0.14478)
		(layer "In4.Cu")
		(net "M_J_CPU1_SA_DQ<23>")
	)
	(segment
		(start 181.214522 -224.960434)
		(end 182.06466 -224.110296)
		(width 0.14478)
		(layer "In4.Cu")
		(net "M_J_CPU1_SA_DQ<23>")
	)
	(segment
		(start 144.871186 -239.316768)
		(end 144.999456 -239.369854)
		(width 0.0889)
		(layer "In4.Cu")
		(net "M_J_CPU1_SA_DQ<23>")
	)
	(segment
		(start 159.694372 -226.419664)
		(end 159.922972 -226.419664)
		(width 0.14478)
		(layer "In4.Cu")
		(net "M_J_CPU1_SA_DQ<23>")
	)
	(segment
		(start 158.852362 -228.241606)
		(end 159.013906 -228.080062)
		(width 0.14478)
		(layer "In4.Cu")
		(net "M_J_CPU1_SA_DQ<23>")
	)
	(segment
		(start 160.574482 -226.290886)
		(end 160.313116 -226.02952)
		(width 0.14478)
		(layer "In4.Cu")
		(net "M_J_CPU1_SA_DQ<23>")
	)
	(segment
		(start 141.667738 -239.301782)
		(end 141.67612 -239.296956)
		(width 0.0889)
		(layer "In4.Cu")
		(net "M_J_CPU1_SA_DQ<23>")
	)
	(segment
		(start 133.20776 -239.301782)
		(end 133.216142 -239.296956)
		(width 0.0889)
		(layer "In4.Cu")
		(net "M_J_CPU1_SA_DQ<23>")
	)
	(segment
		(start 160.964626 -225.900742)
		(end 161.193226 -225.900742)
		(width 0.14478)
		(layer "In4.Cu")
		(net "M_J_CPU1_SA_DQ<23>")
	)
	(segment
		(start 165.17239 -224.650046)
		(end 165.413436 -224.650046)
		(width 0.14478)
		(layer "In4.Cu")
		(net "M_J_CPU1_SA_DQ<23>")
	)
	(segment
		(start 158.75254 -227.361496)
		(end 158.914084 -227.199952)
		(width 0.14478)
		(layer "In4.Cu")
		(net "M_J_CPU1_SA_DQ<23>")
	)
	(segment
		(start 146.395948 -238.675164)
		(end 146.840956 -238.675164)
		(width 0.0889)
		(layer "In4.Cu")
		(net "M_J_CPU1_SA_DQ<23>")
	)
	(segment
		(start 185.957972 -223.783906)
		(end 186.119516 -223.94545)
		(width 0.14478)
		(layer "In4.Cu")
		(net "M_J_CPU1_SA_DQ<23>")
	)
	(segment
		(start 160.313116 -225.80092)
		(end 160.47466 -225.639376)
		(width 0.14478)
		(layer "In4.Cu")
		(net "M_J_CPU1_SA_DQ<23>")
	)
	(segment
		(start 144.84858 -239.294162)
		(end 144.871186 -239.316768)
		(width 0.0889)
		(layer "In4.Cu")
		(net "M_J_CPU1_SA_DQ<23>")
	)
	(segment
		(start 136.967722 -239.301782)
		(end 136.976104 -239.296956)
		(width 0.0889)
		(layer "In4.Cu")
		(net "M_J_CPU1_SA_DQ<23>")
	)
	(segment
		(start 159.532828 -226.809808)
		(end 159.532828 -226.581208)
		(width 0.14478)
		(layer "In4.Cu")
		(net "M_J_CPU1_SA_DQ<23>")
	)
	(segment
		(start 185.729626 -223.783906)
		(end 185.957972 -223.783906)
		(width 0.14478)
		(layer "In4.Cu")
		(net "M_J_CPU1_SA_DQ<23>")
	)
	(segment
		(start 161.35477 -225.510598)
		(end 161.093404 -225.249232)
		(width 0.14478)
		(layer "In4.Cu")
		(net "M_J_CPU1_SA_DQ<23>")
	)
	(segment
		(start 169.7609 -224.110296)
		(end 170.611038 -224.960434)
		(width 0.14478)
		(layer "In4.Cu")
		(net "M_J_CPU1_SA_DQ<23>")
	)
	(segment
		(start 161.193226 -225.900742)
		(end 161.35477 -225.739198)
		(width 0.14478)
		(layer "In4.Cu")
		(net "M_J_CPU1_SA_DQ<23>")
	)
	(segment
		(start 162.966654 -224.650046)
		(end 163.2077 -224.650046)
		(width 0.14478)
		(layer "In4.Cu")
		(net "M_J_CPU1_SA_DQ<23>")
	)
	(segment
		(start 163.2077 -224.650046)
		(end 163.518088 -224.960434)
		(width 0.14478)
		(layer "In4.Cu")
		(net "M_J_CPU1_SA_DQ<23>")
	)
	(segment
		(start 185.016648 -223.948752)
		(end 185.178192 -224.110296)
		(width 0.14478)
		(layer "In4.Cu")
		(net "M_J_CPU1_SA_DQ<23>")
	)
	(segment
		(start 160.574482 -226.519486)
		(end 160.574482 -226.290886)
		(width 0.14478)
		(layer "In4.Cu")
		(net "M_J_CPU1_SA_DQ<23>")
	)
	(segment
		(start 132.267706 -239.301782)
		(end 132.276088 -239.296956)
		(width 0.0889)
		(layer "In4.Cu")
		(net "M_J_CPU1_SA_DQ<23>")
	)
	(segment
		(start 159.142684 -227.199952)
		(end 159.40405 -227.461318)
		(width 0.14478)
		(layer "In4.Cu")
		(net "M_J_CPU1_SA_DQ<23>")
	)
	(segment
		(start 147.856194 -237.787434)
		(end 150.168102 -237.787434)
		(width 0.14478)
		(layer "In4.Cu")
		(net "M_J_CPU1_SA_DQ<23>")
	)
	(segment
		(start 164.620956 -224.960434)
		(end 164.862002 -224.960434)
		(width 0.14478)
		(layer "In4.Cu")
		(net "M_J_CPU1_SA_DQ<23>")
	)
	(segment
		(start 161.483548 -224.859088)
		(end 161.744914 -225.120454)
		(width 0.14478)
		(layer "In4.Cu")
		(net "M_J_CPU1_SA_DQ<23>")
	)
	(segment
		(start 186.635136 -224.110296)
		(end 187.060078 -224.535238)
		(width 0.14478)
		(layer "In4.Cu")
		(net "M_J_CPU1_SA_DQ<23>")
	)
	(segment
		(start 164.862002 -224.960434)
		(end 165.17239 -224.650046)
		(width 0.14478)
		(layer "In4.Cu")
		(net "M_J_CPU1_SA_DQ<23>")
	)
	(segment
		(start 184.465214 -223.94545)
		(end 184.626758 -223.783906)
		(width 0.14478)
		(layer "In4.Cu")
		(net "M_J_CPU1_SA_DQ<23>")
	)
	(segment
		(start 159.794194 -227.299774)
		(end 159.794194 -227.071174)
		(width 0.14478)
		(layer "In4.Cu")
		(net "M_J_CPU1_SA_DQ<23>")
	)
	(segment
		(start 184.30367 -224.110296)
		(end 184.465214 -223.948752)
		(width 0.14478)
		(layer "In4.Cu")
		(net "M_J_CPU1_SA_DQ<23>")
	)
	(segment
		(start 184.855104 -223.783906)
		(end 185.016648 -223.94545)
		(width 0.14478)
		(layer "In4.Cu")
		(net "M_J_CPU1_SA_DQ<23>")
	)
	(segment
		(start 144.999456 -239.369854)
		(end 145.111724 -239.392206)
		(width 0.0889)
		(layer "In4.Cu")
		(net "M_J_CPU1_SA_DQ<23>")
	)
	(segment
		(start 160.70326 -225.639376)
		(end 160.964626 -225.900742)
		(width 0.14478)
		(layer "In4.Cu")
		(net "M_J_CPU1_SA_DQ<23>")
	)
	(segment
		(start 135.453374 -239.296956)
		(end 135.461756 -239.301782)
		(width 0.0889)
		(layer "In4.Cu")
		(net "M_J_CPU1_SA_DQ<23>")
	)
	(segment
		(start 159.013906 -228.080062)
		(end 159.013906 -227.851462)
		(width 0.14478)
		(layer "In4.Cu")
		(net "M_J_CPU1_SA_DQ<23>")
	)
	(segment
		(start 162.133534 -224.960434)
		(end 162.656266 -224.960434)
		(width 0.14478)
		(layer "In4.Cu")
		(net "M_J_CPU1_SA_DQ<23>")
	)
	(segment
		(start 131.693412 -239.296956)
		(end 131.701794 -239.301782)
		(width 0.0889)
		(layer "In4.Cu")
		(net "M_J_CPU1_SA_DQ<23>")
	)
	(segment
		(start 145.678906 -239.392206)
		(end 146.395948 -238.675164)
		(width 0.0889)
		(layer "In4.Cu")
		(net "M_J_CPU1_SA_DQ<23>")
	)
	(segment
		(start 161.744914 -225.120454)
		(end 161.973514 -225.120454)
		(width 0.14478)
		(layer "In4.Cu")
		(net "M_J_CPU1_SA_DQ<23>")
	)
	(segment
		(start 159.63265 -227.461318)
		(end 159.794194 -227.299774)
		(width 0.14478)
		(layer "In4.Cu")
		(net "M_J_CPU1_SA_DQ<23>")
	)
	(segment
		(start 161.254948 -224.859088)
		(end 161.483548 -224.859088)
		(width 0.14478)
		(layer "In4.Cu")
		(net "M_J_CPU1_SA_DQ<23>")
	)
	(arc
		(start 142.04188 -239.301782)
		(mid 142.324836 -239.377959)
		(end 142.607792 -239.301782)
		(width 0.0889)
		(layer "In4.Cu")
		(net "M_J_CPU1_SA_DQ<23>")
	)
	(arc
		(start 131.383024 -239.27562)
		(mid 131.540534 -239.252422)
		(end 131.693412 -239.296956)
		(width 0.0889)
		(layer "In4.Cu")
		(net "M_J_CPU1_SA_DQ<23>")
	)
	(arc
		(start 140.161772 -239.301782)
		(mid 140.444728 -239.377959)
		(end 140.727684 -239.301782)
		(width 0.0889)
		(layer "In4.Cu")
		(net "M_J_CPU1_SA_DQ<23>")
	)
	(arc
		(start 134.147814 -239.301782)
		(mid 134.334758 -239.251527)
		(end 134.521702 -239.301782)
		(width 0.0889)
		(layer "In4.Cu")
		(net "M_J_CPU1_SA_DQ<23>")
	)
	(arc
		(start 142.607792 -239.301782)
		(mid 142.794736 -239.251527)
		(end 142.98168 -239.301782)
		(width 0.0889)
		(layer "In4.Cu")
		(net "M_J_CPU1_SA_DQ<23>")
	)
	(arc
		(start 131.701794 -239.301782)
		(mid 131.98475 -239.377959)
		(end 132.267706 -239.301782)
		(width 0.0889)
		(layer "In4.Cu")
		(net "M_J_CPU1_SA_DQ<23>")
	)
	(arc
		(start 140.727684 -239.301782)
		(mid 140.909935 -239.251432)
		(end 141.093444 -239.296956)
		(width 0.0889)
		(layer "In4.Cu")
		(net "M_J_CPU1_SA_DQ<23>")
	)
	(arc
		(start 143.922242 -239.301782)
		(mid 144.196948 -239.378146)
		(end 144.47393 -239.310418)
		(width 0.0889)
		(layer "In4.Cu")
		(net "M_J_CPU1_SA_DQ<23>")
	)
	(arc
		(start 132.276088 -239.296956)
		(mid 132.459596 -239.251462)
		(end 132.641848 -239.301782)
		(width 0.0889)
		(layer "In4.Cu")
		(net "M_J_CPU1_SA_DQ<23>")
	)
	(arc
		(start 133.581902 -239.301782)
		(mid 133.864858 -239.377959)
		(end 134.147814 -239.301782)
		(width 0.0889)
		(layer "In4.Cu")
		(net "M_J_CPU1_SA_DQ<23>")
	)
	(arc
		(start 141.101826 -239.301782)
		(mid 141.384782 -239.377959)
		(end 141.667738 -239.301782)
		(width 0.0889)
		(layer "In4.Cu")
		(net "M_J_CPU1_SA_DQ<23>")
	)
	(arc
		(start 132.641848 -239.301782)
		(mid 132.924804 -239.377959)
		(end 133.20776 -239.301782)
		(width 0.0889)
		(layer "In4.Cu")
		(net "M_J_CPU1_SA_DQ<23>")
	)
	(arc
		(start 144.488662 -239.301782)
		(mid 144.667649 -239.251612)
		(end 144.84858 -239.294162)
		(width 0.0889)
		(layer "In4.Cu")
		(net "M_J_CPU1_SA_DQ<23>")
	)
	(arc
		(start 136.027668 -239.301782)
		(mid 136.209919 -239.251432)
		(end 136.393428 -239.296956)
		(width 0.0889)
		(layer "In4.Cu")
		(net "M_J_CPU1_SA_DQ<23>")
	)
	(arc
		(start 135.087614 -239.301782)
		(mid 135.269865 -239.251432)
		(end 135.453374 -239.296956)
		(width 0.0889)
		(layer "In4.Cu")
		(net "M_J_CPU1_SA_DQ<23>")
	)
	(arc
		(start 142.98168 -239.301782)
		(mid 143.264636 -239.377959)
		(end 143.547592 -239.301782)
		(width 0.0889)
		(layer "In4.Cu")
		(net "M_J_CPU1_SA_DQ<23>")
	)
	(arc
		(start 139.78763 -239.301782)
		(mid 139.969881 -239.251432)
		(end 140.15339 -239.296956)
		(width 0.0889)
		(layer "In4.Cu")
		(net "M_J_CPU1_SA_DQ<23>")
	)
	(arc
		(start 138.84783 -239.301782)
		(mid 139.034774 -239.251527)
		(end 139.221718 -239.301782)
		(width 0.0889)
		(layer "In4.Cu")
		(net "M_J_CPU1_SA_DQ<23>")
	)
	(arc
		(start 136.40181 -239.301782)
		(mid 136.684766 -239.377959)
		(end 136.967722 -239.301782)
		(width 0.0889)
		(layer "In4.Cu")
		(net "M_J_CPU1_SA_DQ<23>")
	)
	(arc
		(start 134.521702 -239.301782)
		(mid 134.804658 -239.377959)
		(end 135.087614 -239.301782)
		(width 0.0889)
		(layer "In4.Cu")
		(net "M_J_CPU1_SA_DQ<23>")
	)
	(arc
		(start 135.461756 -239.301782)
		(mid 135.744712 -239.377959)
		(end 136.027668 -239.301782)
		(width 0.0889)
		(layer "In4.Cu")
		(net "M_J_CPU1_SA_DQ<23>")
	)
	(arc
		(start 137.341864 -239.301782)
		(mid 137.62482 -239.377959)
		(end 137.907776 -239.301782)
		(width 0.0889)
		(layer "In4.Cu")
		(net "M_J_CPU1_SA_DQ<23>")
	)
	(arc
		(start 139.221718 -239.301782)
		(mid 139.504674 -239.377959)
		(end 139.78763 -239.301782)
		(width 0.0889)
		(layer "In4.Cu")
		(net "M_J_CPU1_SA_DQ<23>")
	)
	(arc
		(start 133.216142 -239.296956)
		(mid 133.39965 -239.251462)
		(end 133.581902 -239.301782)
		(width 0.0889)
		(layer "In4.Cu")
		(net "M_J_CPU1_SA_DQ<23>")
	)
	(arc
		(start 143.555974 -239.296956)
		(mid 143.739736 -239.25134)
		(end 143.922242 -239.301782)
		(width 0.0889)
		(layer "In4.Cu")
		(net "M_J_CPU1_SA_DQ<23>")
	)
	(arc
		(start 136.976104 -239.296956)
		(mid 137.159612 -239.251462)
		(end 137.341864 -239.301782)
		(width 0.0889)
		(layer "In4.Cu")
		(net "M_J_CPU1_SA_DQ<23>")
	)
	(arc
		(start 137.916158 -239.296956)
		(mid 138.099666 -239.251462)
		(end 138.281918 -239.301782)
		(width 0.0889)
		(layer "In4.Cu")
		(net "M_J_CPU1_SA_DQ<23>")
	)
	(arc
		(start 141.67612 -239.296956)
		(mid 141.859628 -239.251462)
		(end 142.04188 -239.301782)
		(width 0.0889)
		(layer "In4.Cu")
		(net "M_J_CPU1_SA_DQ<23>")
	)
	(arc
		(start 138.281918 -239.301782)
		(mid 138.564874 -239.377959)
		(end 138.84783 -239.301782)
		(width 0.0889)
		(layer "In4.Cu")
		(net "M_J_CPU1_SA_DQ<23>")
	)
	(segment
		(start 132.457952 -239.080294)
		(end 132.924804 -238.814356)
		(width 0.10668)
		(layer "F.Cu")
		(net "M_J_CPU1_SA_DQ<22>")
	)
	(segment
		(start 185.428382 -222.635318)
		(end 185.428382 -222.18523)
		(width 0.14478)
		(layer "In4.Cu")
		(net "M_J_CPU1_SA_DQ<22>")
	)
	(segment
		(start 142.503398 -238.48695)
		(end 142.51178 -238.491776)
		(width 0.0889)
		(layer "In4.Cu")
		(net "M_J_CPU1_SA_DQ<22>")
	)
	(segment
		(start 184.876948 -222.18523)
		(end 184.876948 -222.635318)
		(width 0.14478)
		(layer "In4.Cu")
		(net "M_J_CPU1_SA_DQ<22>")
	)
	(segment
		(start 163.422076 -222.861886)
		(end 163.58362 -223.02343)
		(width 0.14478)
		(layer "In4.Cu")
		(net "M_J_CPU1_SA_DQ<22>")
	)
	(segment
		(start 157.642306 -226.971098)
		(end 157.553152 -226.881944)
		(width 0.14478)
		(layer "In4.Cu")
		(net "M_J_CPU1_SA_DQ<22>")
	)
	(segment
		(start 159.593026 -225.020378)
		(end 159.821626 -225.020378)
		(width 0.14478)
		(layer "In4.Cu")
		(net "M_J_CPU1_SA_DQ<22>")
	)
	(segment
		(start 160.601914 -224.24009)
		(end 160.763458 -224.078546)
		(width 0.14478)
		(layer "In4.Cu")
		(net "M_J_CPU1_SA_DQ<22>")
	)
	(segment
		(start 158.422594 -226.19081)
		(end 158.33344 -226.101656)
		(width 0.14478)
		(layer "In4.Cu")
		(net "M_J_CPU1_SA_DQ<22>")
	)
	(segment
		(start 162.319208 -222.861886)
		(end 162.480752 -223.02343)
		(width 0.14478)
		(layer "In4.Cu")
		(net "M_J_CPU1_SA_DQ<22>")
	)
	(segment
		(start 157.642306 -227.199698)
		(end 157.642306 -226.971098)
		(width 0.14478)
		(layer "In4.Cu")
		(net "M_J_CPU1_SA_DQ<22>")
	)
	(segment
		(start 184.876948 -222.635318)
		(end 185.038492 -222.796862)
		(width 0.14478)
		(layer "In4.Cu")
		(net "M_J_CPU1_SA_DQ<22>")
	)
	(segment
		(start 185.038492 -222.796862)
		(end 185.266838 -222.796862)
		(width 0.14478)
		(layer "In4.Cu")
		(net "M_J_CPU1_SA_DQ<22>")
	)
	(segment
		(start 158.812738 -225.800666)
		(end 159.041338 -225.800666)
		(width 0.14478)
		(layer "In4.Cu")
		(net "M_J_CPU1_SA_DQ<22>")
	)
	(segment
		(start 157.714696 -226.4918)
		(end 157.943296 -226.4918)
		(width 0.14478)
		(layer "In4.Cu")
		(net "M_J_CPU1_SA_DQ<22>")
	)
	(segment
		(start 132.770626 -238.548926)
		(end 132.792978 -238.465614)
		(width 0.0889)
		(layer "In4.Cu")
		(net "M_J_CPU1_SA_DQ<22>")
	)
	(segment
		(start 161.929318 -223.02343)
		(end 162.090862 -222.861886)
		(width 0.14478)
		(layer "In4.Cu")
		(net "M_J_CPU1_SA_DQ<22>")
	)
	(segment
		(start 185.428382 -222.18523)
		(end 185.589926 -222.023686)
		(width 0.14478)
		(layer "In4.Cu")
		(net "M_J_CPU1_SA_DQ<22>")
	)
	(segment
		(start 184.487058 -222.023686)
		(end 184.715404 -222.023686)
		(width 0.14478)
		(layer "In4.Cu")
		(net "M_J_CPU1_SA_DQ<22>")
	)
	(segment
		(start 144.384268 -238.48695)
		(end 144.39265 -238.491776)
		(width 0.0889)
		(layer "In4.Cu")
		(net "M_J_CPU1_SA_DQ<22>")
	)
	(segment
		(start 133.103366 -238.48695)
		(end 133.111748 -238.491776)
		(width 0.0889)
		(layer "In4.Cu")
		(net "M_J_CPU1_SA_DQ<22>")
	)
	(segment
		(start 143.077692 -238.491776)
		(end 143.086074 -238.48695)
		(width 0.0889)
		(layer "In4.Cu")
		(net "M_J_CPU1_SA_DQ<22>")
	)
	(segment
		(start 157.553152 -226.881944)
		(end 157.553152 -226.653344)
		(width 0.14478)
		(layer "In4.Cu")
		(net "M_J_CPU1_SA_DQ<22>")
	)
	(segment
		(start 134.617714 -238.491776)
		(end 134.626096 -238.48695)
		(width 0.0889)
		(layer "In4.Cu")
		(net "M_J_CPU1_SA_DQ<22>")
	)
	(segment
		(start 162.870642 -223.658938)
		(end 163.032186 -223.497394)
		(width 0.14478)
		(layer "In4.Cu")
		(net "M_J_CPU1_SA_DQ<22>")
	)
	(segment
		(start 147.835366 -236.878114)
		(end 149.731222 -236.878114)
		(width 0.14478)
		(layer "In4.Cu")
		(net "M_J_CPU1_SA_DQ<22>")
	)
	(segment
		(start 157.363414 -229.245922)
		(end 157.363414 -227.47859)
		(width 0.14478)
		(layer "In4.Cu")
		(net "M_J_CPU1_SA_DQ<22>")
	)
	(segment
		(start 159.113728 -225.092768)
		(end 159.275272 -224.931224)
		(width 0.14478)
		(layer "In4.Cu")
		(net "M_J_CPU1_SA_DQ<22>")
	)
	(segment
		(start 174.347124 -222.410274)
		(end 177.53203 -222.410274)
		(width 0.14478)
		(layer "In4.Cu")
		(net "M_J_CPU1_SA_DQ<22>")
	)
	(segment
		(start 161.929318 -223.474026)
		(end 161.929318 -223.02343)
		(width 0.14478)
		(layer "In4.Cu")
		(net "M_J_CPU1_SA_DQ<22>")
	)
	(segment
		(start 185.818272 -222.023686)
		(end 185.979816 -222.18523)
		(width 0.14478)
		(layer "In4.Cu")
		(net "M_J_CPU1_SA_DQ<22>")
	)
	(segment
		(start 163.032186 -223.02343)
		(end 163.19373 -222.861886)
		(width 0.14478)
		(layer "In4.Cu")
		(net "M_J_CPU1_SA_DQ<22>")
	)
	(segment
		(start 132.924804 -238.814356)
		(end 132.770626 -238.548926)
		(width 0.0889)
		(layer "In4.Cu")
		(net "M_J_CPU1_SA_DQ<22>")
	)
	(segment
		(start 145.76933 -238.440976)
		(end 147.332192 -236.878114)
		(width 0.0889)
		(layer "In4.Cu")
		(net "M_J_CPU1_SA_DQ<22>")
	)
	(segment
		(start 158.33344 -225.873056)
		(end 158.494984 -225.711512)
		(width 0.14478)
		(layer "In4.Cu")
		(net "M_J_CPU1_SA_DQ<22>")
	)
	(segment
		(start 159.98317 -224.858834)
		(end 159.98317 -224.630234)
		(width 0.14478)
		(layer "In4.Cu")
		(net "M_J_CPU1_SA_DQ<22>")
	)
	(segment
		(start 178.382168 -223.260412)
		(end 181.391814 -223.260412)
		(width 0.14478)
		(layer "In4.Cu")
		(net "M_J_CPU1_SA_DQ<22>")
	)
	(segment
		(start 159.041338 -225.800666)
		(end 159.202882 -225.639122)
		(width 0.14478)
		(layer "In4.Cu")
		(net "M_J_CPU1_SA_DQ<22>")
	)
	(segment
		(start 158.33344 -226.101656)
		(end 158.33344 -225.873056)
		(width 0.14478)
		(layer "In4.Cu")
		(net "M_J_CPU1_SA_DQ<22>")
	)
	(segment
		(start 160.05556 -224.150936)
		(end 160.28416 -224.150936)
		(width 0.14478)
		(layer "In4.Cu")
		(net "M_J_CPU1_SA_DQ<22>")
	)
	(segment
		(start 160.373314 -224.24009)
		(end 160.601914 -224.24009)
		(width 0.14478)
		(layer "In4.Cu")
		(net "M_J_CPU1_SA_DQ<22>")
	)
	(segment
		(start 158.494984 -225.711512)
		(end 158.723584 -225.711512)
		(width 0.14478)
		(layer "In4.Cu")
		(net "M_J_CPU1_SA_DQ<22>")
	)
	(segment
		(start 163.19373 -222.861886)
		(end 163.422076 -222.861886)
		(width 0.14478)
		(layer "In4.Cu")
		(net "M_J_CPU1_SA_DQ<22>")
	)
	(segment
		(start 157.553152 -226.653344)
		(end 157.714696 -226.4918)
		(width 0.14478)
		(layer "In4.Cu")
		(net "M_J_CPU1_SA_DQ<22>")
	)
	(segment
		(start 181.391814 -223.260412)
		(end 182.241952 -222.410274)
		(width 0.14478)
		(layer "In4.Cu")
		(net "M_J_CPU1_SA_DQ<22>")
	)
	(segment
		(start 186.14136 -222.410274)
		(end 186.635136 -222.410274)
		(width 0.14478)
		(layer "In4.Cu")
		(net "M_J_CPU1_SA_DQ<22>")
	)
	(segment
		(start 159.894016 -224.54108)
		(end 159.894016 -224.31248)
		(width 0.14478)
		(layer "In4.Cu")
		(net "M_J_CPU1_SA_DQ<22>")
	)
	(segment
		(start 165.682168 -222.968566)
		(end 165.974014 -223.260412)
		(width 0.14478)
		(layer "In4.Cu")
		(net "M_J_CPU1_SA_DQ<22>")
	)
	(segment
		(start 162.480752 -223.02343)
		(end 162.480752 -223.497394)
		(width 0.14478)
		(layer "In4.Cu")
		(net "M_J_CPU1_SA_DQ<22>")
	)
	(segment
		(start 184.715404 -222.023686)
		(end 184.876948 -222.18523)
		(width 0.14478)
		(layer "In4.Cu")
		(net "M_J_CPU1_SA_DQ<22>")
	)
	(segment
		(start 160.763458 -224.078546)
		(end 160.763458 -223.849946)
		(width 0.14478)
		(layer "In4.Cu")
		(net "M_J_CPU1_SA_DQ<22>")
	)
	(segment
		(start 170.43908 -223.260412)
		(end 173.496986 -223.260412)
		(width 0.14478)
		(layer "In4.Cu")
		(net "M_J_CPU1_SA_DQ<22>")
	)
	(segment
		(start 167.078152 -222.410274)
		(end 169.588942 -222.410274)
		(width 0.14478)
		(layer "In4.Cu")
		(net "M_J_CPU1_SA_DQ<22>")
	)
	(segment
		(start 160.835848 -223.370648)
		(end 161.064448 -223.370648)
		(width 0.14478)
		(layer "In4.Cu")
		(net "M_J_CPU1_SA_DQ<22>")
	)
	(segment
		(start 186.635136 -222.410274)
		(end 187.060078 -222.835216)
		(width 0.14478)
		(layer "In4.Cu")
		(net "M_J_CPU1_SA_DQ<22>")
	)
	(segment
		(start 185.266838 -222.796862)
		(end 185.428382 -222.635318)
		(width 0.14478)
		(layer "In4.Cu")
		(net "M_J_CPU1_SA_DQ<22>")
	)
	(segment
		(start 159.503872 -224.931224)
		(end 159.593026 -225.020378)
		(width 0.14478)
		(layer "In4.Cu")
		(net "M_J_CPU1_SA_DQ<22>")
	)
	(segment
		(start 165.42258 -222.968566)
		(end 165.682168 -222.968566)
		(width 0.14478)
		(layer "In4.Cu")
		(net "M_J_CPU1_SA_DQ<22>")
	)
	(segment
		(start 164.5793 -222.968566)
		(end 164.871146 -223.260412)
		(width 0.14478)
		(layer "In4.Cu")
		(net "M_J_CPU1_SA_DQ<22>")
	)
	(segment
		(start 177.53203 -222.410274)
		(end 178.382168 -223.260412)
		(width 0.14478)
		(layer "In4.Cu")
		(net "M_J_CPU1_SA_DQ<22>")
	)
	(segment
		(start 161.064448 -223.370648)
		(end 161.312606 -223.618806)
		(width 0.14478)
		(layer "In4.Cu")
		(net "M_J_CPU1_SA_DQ<22>")
	)
	(segment
		(start 164.319712 -222.968566)
		(end 164.5793 -222.968566)
		(width 0.14478)
		(layer "In4.Cu")
		(net "M_J_CPU1_SA_DQ<22>")
	)
	(segment
		(start 157.943296 -226.4918)
		(end 158.03245 -226.580954)
		(width 0.14478)
		(layer "In4.Cu")
		(net "M_J_CPU1_SA_DQ<22>")
	)
	(segment
		(start 158.723584 -225.711512)
		(end 158.812738 -225.800666)
		(width 0.14478)
		(layer "In4.Cu")
		(net "M_J_CPU1_SA_DQ<22>")
	)
	(segment
		(start 185.979816 -222.18523)
		(end 185.979816 -222.24873)
		(width 0.14478)
		(layer "In4.Cu")
		(net "M_J_CPU1_SA_DQ<22>")
	)
	(segment
		(start 164.871146 -223.260412)
		(end 165.130734 -223.260412)
		(width 0.14478)
		(layer "In4.Cu")
		(net "M_J_CPU1_SA_DQ<22>")
	)
	(segment
		(start 158.03245 -226.580954)
		(end 158.26105 -226.580954)
		(width 0.14478)
		(layer "In4.Cu")
		(net "M_J_CPU1_SA_DQ<22>")
	)
	(segment
		(start 139.31773 -238.491776)
		(end 139.326112 -238.48695)
		(width 0.0889)
		(layer "In4.Cu")
		(net "M_J_CPU1_SA_DQ<22>")
	)
	(segment
		(start 159.98317 -224.630234)
		(end 159.894016 -224.54108)
		(width 0.14478)
		(layer "In4.Cu")
		(net "M_J_CPU1_SA_DQ<22>")
	)
	(segment
		(start 173.496986 -223.260412)
		(end 174.347124 -222.410274)
		(width 0.14478)
		(layer "In4.Cu")
		(net "M_J_CPU1_SA_DQ<22>")
	)
	(segment
		(start 161.312606 -223.618806)
		(end 161.784538 -223.618806)
		(width 0.14478)
		(layer "In4.Cu")
		(net "M_J_CPU1_SA_DQ<22>")
	)
	(segment
		(start 184.16397 -222.410274)
		(end 184.325514 -222.24873)
		(width 0.14478)
		(layer "In4.Cu")
		(net "M_J_CPU1_SA_DQ<22>")
	)
	(segment
		(start 184.325514 -222.18523)
		(end 184.487058 -222.023686)
		(width 0.14478)
		(layer "In4.Cu")
		(net "M_J_CPU1_SA_DQ<22>")
	)
	(segment
		(start 182.241952 -222.410274)
		(end 184.16397 -222.410274)
		(width 0.14478)
		(layer "In4.Cu")
		(net "M_J_CPU1_SA_DQ<22>")
	)
	(segment
		(start 138.743436 -238.48695)
		(end 138.751818 -238.491776)
		(width 0.0889)
		(layer "In4.Cu")
		(net "M_J_CPU1_SA_DQ<22>")
	)
	(segment
		(start 149.731222 -236.878114)
		(end 157.363414 -229.245922)
		(width 0.14478)
		(layer "In4.Cu")
		(net "M_J_CPU1_SA_DQ<22>")
	)
	(segment
		(start 147.332192 -236.878114)
		(end 147.835366 -236.878114)
		(width 0.0889)
		(layer "In4.Cu")
		(net "M_J_CPU1_SA_DQ<22>")
	)
	(segment
		(start 163.58362 -223.098868)
		(end 163.745164 -223.260412)
		(width 0.14478)
		(layer "In4.Cu")
		(net "M_J_CPU1_SA_DQ<22>")
	)
	(segment
		(start 137.803382 -238.48695)
		(end 137.811764 -238.491776)
		(width 0.0889)
		(layer "In4.Cu")
		(net "M_J_CPU1_SA_DQ<22>")
	)
	(segment
		(start 166.228014 -223.260412)
		(end 167.078152 -222.410274)
		(width 0.14478)
		(layer "In4.Cu")
		(net "M_J_CPU1_SA_DQ<22>")
	)
	(segment
		(start 140.257784 -238.491776)
		(end 140.266166 -238.48695)
		(width 0.0889)
		(layer "In4.Cu")
		(net "M_J_CPU1_SA_DQ<22>")
	)
	(segment
		(start 160.674304 -223.532192)
		(end 160.835848 -223.370648)
		(width 0.14478)
		(layer "In4.Cu")
		(net "M_J_CPU1_SA_DQ<22>")
	)
	(segment
		(start 159.202882 -225.410522)
		(end 159.113728 -225.321368)
		(width 0.14478)
		(layer "In4.Cu")
		(net "M_J_CPU1_SA_DQ<22>")
	)
	(segment
		(start 159.275272 -224.931224)
		(end 159.503872 -224.931224)
		(width 0.14478)
		(layer "In4.Cu")
		(net "M_J_CPU1_SA_DQ<22>")
	)
	(segment
		(start 163.032186 -223.497394)
		(end 163.032186 -223.02343)
		(width 0.14478)
		(layer "In4.Cu")
		(net "M_J_CPU1_SA_DQ<22>")
	)
	(segment
		(start 159.894016 -224.31248)
		(end 160.05556 -224.150936)
		(width 0.14478)
		(layer "In4.Cu")
		(net "M_J_CPU1_SA_DQ<22>")
	)
	(segment
		(start 159.113728 -225.321368)
		(end 159.113728 -225.092768)
		(width 0.14478)
		(layer "In4.Cu")
		(net "M_J_CPU1_SA_DQ<22>")
	)
	(segment
		(start 165.130734 -223.260412)
		(end 165.42258 -222.968566)
		(width 0.14478)
		(layer "In4.Cu")
		(net "M_J_CPU1_SA_DQ<22>")
	)
	(segment
		(start 163.58362 -223.02343)
		(end 163.58362 -223.098868)
		(width 0.14478)
		(layer "In4.Cu")
		(net "M_J_CPU1_SA_DQ<22>")
	)
	(segment
		(start 134.04342 -238.48695)
		(end 134.051802 -238.491776)
		(width 0.0889)
		(layer "In4.Cu")
		(net "M_J_CPU1_SA_DQ<22>")
	)
	(segment
		(start 157.363414 -227.47859)
		(end 157.642306 -227.199698)
		(width 0.14478)
		(layer "In4.Cu")
		(net "M_J_CPU1_SA_DQ<22>")
	)
	(segment
		(start 162.090862 -222.861886)
		(end 162.319208 -222.861886)
		(width 0.14478)
		(layer "In4.Cu")
		(net "M_J_CPU1_SA_DQ<22>")
	)
	(segment
		(start 164.027866 -223.260412)
		(end 164.319712 -222.968566)
		(width 0.14478)
		(layer "In4.Cu")
		(net "M_J_CPU1_SA_DQ<22>")
	)
	(segment
		(start 184.325514 -222.24873)
		(end 184.325514 -222.18523)
		(width 0.14478)
		(layer "In4.Cu")
		(net "M_J_CPU1_SA_DQ<22>")
	)
	(segment
		(start 185.979816 -222.24873)
		(end 186.14136 -222.410274)
		(width 0.14478)
		(layer "In4.Cu")
		(net "M_J_CPU1_SA_DQ<22>")
	)
	(segment
		(start 160.763458 -223.849946)
		(end 160.674304 -223.760792)
		(width 0.14478)
		(layer "In4.Cu")
		(net "M_J_CPU1_SA_DQ<22>")
	)
	(segment
		(start 158.26105 -226.580954)
		(end 158.422594 -226.41941)
		(width 0.14478)
		(layer "In4.Cu")
		(net "M_J_CPU1_SA_DQ<22>")
	)
	(segment
		(start 162.480752 -223.497394)
		(end 162.642296 -223.658938)
		(width 0.14478)
		(layer "In4.Cu")
		(net "M_J_CPU1_SA_DQ<22>")
	)
	(segment
		(start 161.784538 -223.618806)
		(end 161.929318 -223.474026)
		(width 0.14478)
		(layer "In4.Cu")
		(net "M_J_CPU1_SA_DQ<22>")
	)
	(segment
		(start 162.642296 -223.658938)
		(end 162.870642 -223.658938)
		(width 0.14478)
		(layer "In4.Cu")
		(net "M_J_CPU1_SA_DQ<22>")
	)
	(segment
		(start 185.589926 -222.023686)
		(end 185.818272 -222.023686)
		(width 0.14478)
		(layer "In4.Cu")
		(net "M_J_CPU1_SA_DQ<22>")
	)
	(segment
		(start 169.588942 -222.410274)
		(end 170.43908 -223.260412)
		(width 0.14478)
		(layer "In4.Cu")
		(net "M_J_CPU1_SA_DQ<22>")
	)
	(segment
		(start 135.557768 -238.491776)
		(end 135.56615 -238.48695)
		(width 0.0889)
		(layer "In4.Cu")
		(net "M_J_CPU1_SA_DQ<22>")
	)
	(segment
		(start 158.422594 -226.41941)
		(end 158.422594 -226.19081)
		(width 0.14478)
		(layer "In4.Cu")
		(net "M_J_CPU1_SA_DQ<22>")
	)
	(segment
		(start 160.28416 -224.150936)
		(end 160.373314 -224.24009)
		(width 0.14478)
		(layer "In4.Cu")
		(net "M_J_CPU1_SA_DQ<22>")
	)
	(segment
		(start 165.974014 -223.260412)
		(end 166.228014 -223.260412)
		(width 0.14478)
		(layer "In4.Cu")
		(net "M_J_CPU1_SA_DQ<22>")
	)
	(segment
		(start 160.674304 -223.760792)
		(end 160.674304 -223.532192)
		(width 0.14478)
		(layer "In4.Cu")
		(net "M_J_CPU1_SA_DQ<22>")
	)
	(segment
		(start 163.745164 -223.260412)
		(end 164.027866 -223.260412)
		(width 0.14478)
		(layer "In4.Cu")
		(net "M_J_CPU1_SA_DQ<22>")
	)
	(segment
		(start 159.202882 -225.639122)
		(end 159.202882 -225.410522)
		(width 0.14478)
		(layer "In4.Cu")
		(net "M_J_CPU1_SA_DQ<22>")
	)
	(segment
		(start 159.821626 -225.020378)
		(end 159.98317 -224.858834)
		(width 0.14478)
		(layer "In4.Cu")
		(net "M_J_CPU1_SA_DQ<22>")
	)
	(segment
		(start 145.144744 -238.440976)
		(end 145.76933 -238.440976)
		(width 0.0889)
		(layer "In4.Cu")
		(net "M_J_CPU1_SA_DQ<22>")
	)
	(segment
		(start 143.451834 -238.491776)
		(end 143.462248 -238.497872)
		(width 0.0889)
		(layer "In4.Cu")
		(net "M_J_CPU1_SA_DQ<22>")
	)
	(arc
		(start 133.111748 -238.491776)
		(mid 133.394704 -238.567953)
		(end 133.67766 -238.491776)
		(width 0.0889)
		(layer "In4.Cu")
		(net "M_J_CPU1_SA_DQ<22>")
	)
	(arc
		(start 139.691872 -238.491776)
		(mid 139.974828 -238.567953)
		(end 140.257784 -238.491776)
		(width 0.0889)
		(layer "In4.Cu")
		(net "M_J_CPU1_SA_DQ<22>")
	)
	(arc
		(start 135.93191 -238.491776)
		(mid 136.214866 -238.567953)
		(end 136.497822 -238.491776)
		(width 0.0889)
		(layer "In4.Cu")
		(net "M_J_CPU1_SA_DQ<22>")
	)
	(arc
		(start 144.952466 -238.495332)
		(mid 145.044898 -238.45505)
		(end 145.144744 -238.440976)
		(width 0.0889)
		(layer "In4.Cu")
		(net "M_J_CPU1_SA_DQ<22>")
	)
	(arc
		(start 135.56615 -238.48695)
		(mid 135.749658 -238.441456)
		(end 135.93191 -238.491776)
		(width 0.0889)
		(layer "In4.Cu")
		(net "M_J_CPU1_SA_DQ<22>")
	)
	(arc
		(start 137.437622 -238.491776)
		(mid 137.619873 -238.441426)
		(end 137.803382 -238.48695)
		(width 0.0889)
		(layer "In4.Cu")
		(net "M_J_CPU1_SA_DQ<22>")
	)
	(arc
		(start 136.497822 -238.491776)
		(mid 136.684766 -238.441521)
		(end 136.87171 -238.491776)
		(width 0.0889)
		(layer "In4.Cu")
		(net "M_J_CPU1_SA_DQ<22>")
	)
	(arc
		(start 141.197838 -238.491776)
		(mid 141.384782 -238.441521)
		(end 141.571726 -238.491776)
		(width 0.0889)
		(layer "In4.Cu")
		(net "M_J_CPU1_SA_DQ<22>")
	)
	(arc
		(start 139.326112 -238.48695)
		(mid 139.50962 -238.441456)
		(end 139.691872 -238.491776)
		(width 0.0889)
		(layer "In4.Cu")
		(net "M_J_CPU1_SA_DQ<22>")
	)
	(arc
		(start 134.991856 -238.491776)
		(mid 135.274812 -238.567953)
		(end 135.557768 -238.491776)
		(width 0.0889)
		(layer "In4.Cu")
		(net "M_J_CPU1_SA_DQ<22>")
	)
	(arc
		(start 138.751818 -238.491776)
		(mid 139.034774 -238.567953)
		(end 139.31773 -238.491776)
		(width 0.0889)
		(layer "In4.Cu")
		(net "M_J_CPU1_SA_DQ<22>")
	)
	(arc
		(start 134.626096 -238.48695)
		(mid 134.809604 -238.441456)
		(end 134.991856 -238.491776)
		(width 0.0889)
		(layer "In4.Cu")
		(net "M_J_CPU1_SA_DQ<22>")
	)
	(arc
		(start 144.39265 -238.491776)
		(mid 144.672078 -238.567942)
		(end 144.952466 -238.495332)
		(width 0.0889)
		(layer "In4.Cu")
		(net "M_J_CPU1_SA_DQ<22>")
	)
	(arc
		(start 144.018 -238.491776)
		(mid 144.200505 -238.441299)
		(end 144.384268 -238.48695)
		(width 0.0889)
		(layer "In4.Cu")
		(net "M_J_CPU1_SA_DQ<22>")
	)
	(arc
		(start 143.086074 -238.48695)
		(mid 143.269582 -238.441456)
		(end 143.451834 -238.491776)
		(width 0.0889)
		(layer "In4.Cu")
		(net "M_J_CPU1_SA_DQ<22>")
	)
	(arc
		(start 142.137638 -238.491776)
		(mid 142.319889 -238.441426)
		(end 142.503398 -238.48695)
		(width 0.0889)
		(layer "In4.Cu")
		(net "M_J_CPU1_SA_DQ<22>")
	)
	(arc
		(start 132.792978 -238.465614)
		(mid 132.950488 -238.442416)
		(end 133.103366 -238.48695)
		(width 0.0889)
		(layer "In4.Cu")
		(net "M_J_CPU1_SA_DQ<22>")
	)
	(arc
		(start 143.462248 -238.497872)
		(mid 143.740934 -238.568092)
		(end 144.018 -238.491776)
		(width 0.0889)
		(layer "In4.Cu")
		(net "M_J_CPU1_SA_DQ<22>")
	)
	(arc
		(start 140.266166 -238.48695)
		(mid 140.449674 -238.441456)
		(end 140.631926 -238.491776)
		(width 0.0889)
		(layer "In4.Cu")
		(net "M_J_CPU1_SA_DQ<22>")
	)
	(arc
		(start 134.051802 -238.491776)
		(mid 134.334758 -238.567953)
		(end 134.617714 -238.491776)
		(width 0.0889)
		(layer "In4.Cu")
		(net "M_J_CPU1_SA_DQ<22>")
	)
	(arc
		(start 133.67766 -238.491776)
		(mid 133.859911 -238.441426)
		(end 134.04342 -238.48695)
		(width 0.0889)
		(layer "In4.Cu")
		(net "M_J_CPU1_SA_DQ<22>")
	)
	(arc
		(start 138.377676 -238.491776)
		(mid 138.559927 -238.441426)
		(end 138.743436 -238.48695)
		(width 0.0889)
		(layer "In4.Cu")
		(net "M_J_CPU1_SA_DQ<22>")
	)
	(arc
		(start 142.51178 -238.491776)
		(mid 142.794736 -238.567953)
		(end 143.077692 -238.491776)
		(width 0.0889)
		(layer "In4.Cu")
		(net "M_J_CPU1_SA_DQ<22>")
	)
	(arc
		(start 137.811764 -238.491776)
		(mid 138.09472 -238.567953)
		(end 138.377676 -238.491776)
		(width 0.0889)
		(layer "In4.Cu")
		(net "M_J_CPU1_SA_DQ<22>")
	)
	(arc
		(start 136.87171 -238.491776)
		(mid 137.154666 -238.567953)
		(end 137.437622 -238.491776)
		(width 0.0889)
		(layer "In4.Cu")
		(net "M_J_CPU1_SA_DQ<22>")
	)
	(arc
		(start 140.631926 -238.491776)
		(mid 140.914882 -238.567953)
		(end 141.197838 -238.491776)
		(width 0.0889)
		(layer "In4.Cu")
		(net "M_J_CPU1_SA_DQ<22>")
	)
	(arc
		(start 141.571726 -238.491776)
		(mid 141.854682 -238.567953)
		(end 142.137638 -238.491776)
		(width 0.0889)
		(layer "In4.Cu")
		(net "M_J_CPU1_SA_DQ<22>")
	)
	(segment
		(start 130.577844 -239.080294)
		(end 131.044696 -238.814356)
		(width 0.10668)
		(layer "F.Cu")
		(net "M_J_CPU1_SA_DQ<21>")
	)
	(segment
		(start 137.803382 -239.141762)
		(end 137.811764 -239.136936)
		(width 0.0889)
		(layer "In4.Cu")
		(net "M_J_CPU1_SA_DQ<21>")
	)
	(segment
		(start 143.077692 -239.136936)
		(end 143.086074 -239.141762)
		(width 0.0889)
		(layer "In4.Cu")
		(net "M_J_CPU1_SA_DQ<21>")
	)
	(segment
		(start 188.014102 -223.905826)
		(end 188.175646 -223.744282)
		(width 0.14478)
		(layer "In4.Cu")
		(net "M_J_CPU1_SA_DQ<21>")
	)
	(segment
		(start 161.367724 -224.110296)
		(end 166.222172 -224.110296)
		(width 0.14478)
		(layer "In4.Cu")
		(net "M_J_CPU1_SA_DQ<21>")
	)
	(segment
		(start 144.958054 -239.136682)
		(end 144.976342 -239.147096)
		(width 0.0889)
		(layer "In4.Cu")
		(net "M_J_CPU1_SA_DQ<21>")
	)
	(segment
		(start 178.471322 -224.110296)
		(end 181.29631 -224.110296)
		(width 0.14478)
		(layer "In4.Cu")
		(net "M_J_CPU1_SA_DQ<21>")
	)
	(segment
		(start 170.529504 -224.110296)
		(end 173.791118 -224.110296)
		(width 0.14478)
		(layer "In4.Cu")
		(net "M_J_CPU1_SA_DQ<21>")
	)
	(segment
		(start 143.451834 -239.136936)
		(end 143.466566 -239.1283)
		(width 0.0889)
		(layer "In4.Cu")
		(net "M_J_CPU1_SA_DQ<21>")
	)
	(segment
		(start 144.380966 -239.143794)
		(end 144.39265 -239.136936)
		(width 0.0889)
		(layer "In4.Cu")
		(net "M_J_CPU1_SA_DQ<21>")
	)
	(segment
		(start 187.462668 -223.260412)
		(end 187.624212 -223.421956)
		(width 0.14478)
		(layer "In4.Cu")
		(net "M_J_CPU1_SA_DQ<21>")
	)
	(segment
		(start 142.503398 -239.141762)
		(end 142.51178 -239.136936)
		(width 0.0889)
		(layer "In4.Cu")
		(net "M_J_CPU1_SA_DQ<21>")
	)
	(segment
		(start 188.175646 -223.744282)
		(end 188.175646 -223.421956)
		(width 0.14478)
		(layer "In4.Cu")
		(net "M_J_CPU1_SA_DQ<21>")
	)
	(segment
		(start 173.791118 -224.110296)
		(end 174.641002 -223.260412)
		(width 0.14478)
		(layer "In4.Cu")
		(net "M_J_CPU1_SA_DQ<21>")
	)
	(segment
		(start 167.072056 -223.260412)
		(end 169.67962 -223.260412)
		(width 0.14478)
		(layer "In4.Cu")
		(net "M_J_CPU1_SA_DQ<21>")
	)
	(segment
		(start 145.373344 -239.136936)
		(end 147.177506 -237.332774)
		(width 0.0889)
		(layer "In4.Cu")
		(net "M_J_CPU1_SA_DQ<21>")
	)
	(segment
		(start 182.146194 -223.260412)
		(end 187.462668 -223.260412)
		(width 0.14478)
		(layer "In4.Cu")
		(net "M_J_CPU1_SA_DQ<21>")
	)
	(segment
		(start 149.914102 -237.332774)
		(end 157.812994 -229.433882)
		(width 0.14478)
		(layer "In4.Cu")
		(net "M_J_CPU1_SA_DQ<21>")
	)
	(segment
		(start 188.33719 -223.260412)
		(end 189.023752 -223.260412)
		(width 0.14478)
		(layer "In4.Cu")
		(net "M_J_CPU1_SA_DQ<21>")
	)
	(segment
		(start 157.812994 -229.433882)
		(end 157.812994 -227.665026)
		(width 0.14478)
		(layer "In4.Cu")
		(net "M_J_CPU1_SA_DQ<21>")
	)
	(segment
		(start 134.04342 -239.141762)
		(end 134.051802 -239.136936)
		(width 0.0889)
		(layer "In4.Cu")
		(net "M_J_CPU1_SA_DQ<21>")
	)
	(segment
		(start 174.641002 -223.260412)
		(end 177.621438 -223.260412)
		(width 0.14478)
		(layer "In4.Cu")
		(net "M_J_CPU1_SA_DQ<21>")
	)
	(segment
		(start 166.222172 -224.110296)
		(end 167.072056 -223.260412)
		(width 0.14478)
		(layer "In4.Cu")
		(net "M_J_CPU1_SA_DQ<21>")
	)
	(segment
		(start 147.177506 -237.332774)
		(end 147.866608 -237.332774)
		(width 0.0889)
		(layer "In4.Cu")
		(net "M_J_CPU1_SA_DQ<21>")
	)
	(segment
		(start 135.557768 -239.136936)
		(end 135.56615 -239.141762)
		(width 0.0889)
		(layer "In4.Cu")
		(net "M_J_CPU1_SA_DQ<21>")
	)
	(segment
		(start 187.624212 -223.421956)
		(end 187.624212 -223.744282)
		(width 0.14478)
		(layer "In4.Cu")
		(net "M_J_CPU1_SA_DQ<21>")
	)
	(segment
		(start 177.621438 -223.260412)
		(end 178.471322 -224.110296)
		(width 0.14478)
		(layer "In4.Cu")
		(net "M_J_CPU1_SA_DQ<21>")
	)
	(segment
		(start 188.175646 -223.421956)
		(end 188.33719 -223.260412)
		(width 0.14478)
		(layer "In4.Cu")
		(net "M_J_CPU1_SA_DQ<21>")
	)
	(segment
		(start 138.743436 -239.141762)
		(end 138.751818 -239.136936)
		(width 0.0889)
		(layer "In4.Cu")
		(net "M_J_CPU1_SA_DQ<21>")
	)
	(segment
		(start 189.023752 -223.260412)
		(end 191.160146 -223.685354)
		(width 0.14478)
		(layer "In4.Cu")
		(net "M_J_CPU1_SA_DQ<21>")
	)
	(segment
		(start 181.29631 -224.110296)
		(end 182.146194 -223.260412)
		(width 0.14478)
		(layer "In4.Cu")
		(net "M_J_CPU1_SA_DQ<21>")
	)
	(segment
		(start 144.952466 -239.13338)
		(end 144.958054 -239.136682)
		(width 0.0889)
		(layer "In4.Cu")
		(net "M_J_CPU1_SA_DQ<21>")
	)
	(segment
		(start 134.617714 -239.136936)
		(end 134.626096 -239.141762)
		(width 0.0889)
		(layer "In4.Cu")
		(net "M_J_CPU1_SA_DQ<21>")
	)
	(segment
		(start 147.866608 -237.332774)
		(end 149.914102 -237.332774)
		(width 0.14478)
		(layer "In4.Cu")
		(net "M_J_CPU1_SA_DQ<21>")
	)
	(segment
		(start 140.257784 -239.136936)
		(end 140.266166 -239.141762)
		(width 0.0889)
		(layer "In4.Cu")
		(net "M_J_CPU1_SA_DQ<21>")
	)
	(segment
		(start 131.198874 -239.079786)
		(end 131.29514 -239.105186)
		(width 0.0889)
		(layer "In4.Cu")
		(net "M_J_CPU1_SA_DQ<21>")
	)
	(segment
		(start 131.044696 -238.814356)
		(end 131.198874 -239.079786)
		(width 0.0889)
		(layer "In4.Cu")
		(net "M_J_CPU1_SA_DQ<21>")
	)
	(segment
		(start 187.785756 -223.905826)
		(end 188.014102 -223.905826)
		(width 0.14478)
		(layer "In4.Cu")
		(net "M_J_CPU1_SA_DQ<21>")
	)
	(segment
		(start 157.812994 -227.665026)
		(end 161.367724 -224.110296)
		(width 0.14478)
		(layer "In4.Cu")
		(net "M_J_CPU1_SA_DQ<21>")
	)
	(segment
		(start 169.67962 -223.260412)
		(end 170.529504 -224.110296)
		(width 0.14478)
		(layer "In4.Cu")
		(net "M_J_CPU1_SA_DQ<21>")
	)
	(segment
		(start 187.624212 -223.744282)
		(end 187.785756 -223.905826)
		(width 0.14478)
		(layer "In4.Cu")
		(net "M_J_CPU1_SA_DQ<21>")
	)
	(segment
		(start 145.332196 -239.136936)
		(end 145.373344 -239.136936)
		(width 0.0889)
		(layer "In4.Cu")
		(net "M_J_CPU1_SA_DQ<21>")
	)
	(segment
		(start 133.103366 -239.141762)
		(end 133.111748 -239.136936)
		(width 0.0889)
		(layer "In4.Cu")
		(net "M_J_CPU1_SA_DQ<21>")
	)
	(segment
		(start 139.31773 -239.136936)
		(end 139.326112 -239.141762)
		(width 0.0889)
		(layer "In4.Cu")
		(net "M_J_CPU1_SA_DQ<21>")
	)
	(arc
		(start 140.631926 -239.136936)
		(mid 140.914882 -239.060759)
		(end 141.197838 -239.136936)
		(width 0.0889)
		(layer "In4.Cu")
		(net "M_J_CPU1_SA_DQ<21>")
	)
	(arc
		(start 144.976342 -239.147096)
		(mid 145.155571 -239.187249)
		(end 145.332196 -239.136936)
		(width 0.0889)
		(layer "In4.Cu")
		(net "M_J_CPU1_SA_DQ<21>")
	)
	(arc
		(start 131.797806 -239.136936)
		(mid 131.98475 -239.187191)
		(end 132.171694 -239.136936)
		(width 0.0889)
		(layer "In4.Cu")
		(net "M_J_CPU1_SA_DQ<21>")
	)
	(arc
		(start 135.93191 -239.136936)
		(mid 136.214866 -239.060759)
		(end 136.497822 -239.136936)
		(width 0.0889)
		(layer "In4.Cu")
		(net "M_J_CPU1_SA_DQ<21>")
	)
	(arc
		(start 134.051802 -239.136936)
		(mid 134.334758 -239.060759)
		(end 134.617714 -239.136936)
		(width 0.0889)
		(layer "In4.Cu")
		(net "M_J_CPU1_SA_DQ<21>")
	)
	(arc
		(start 139.326112 -239.141762)
		(mid 139.50962 -239.187256)
		(end 139.691872 -239.136936)
		(width 0.0889)
		(layer "In4.Cu")
		(net "M_J_CPU1_SA_DQ<21>")
	)
	(arc
		(start 142.137638 -239.136936)
		(mid 142.319889 -239.187286)
		(end 142.503398 -239.141762)
		(width 0.0889)
		(layer "In4.Cu")
		(net "M_J_CPU1_SA_DQ<21>")
	)
	(arc
		(start 141.571726 -239.136936)
		(mid 141.854682 -239.060759)
		(end 142.137638 -239.136936)
		(width 0.0889)
		(layer "In4.Cu")
		(net "M_J_CPU1_SA_DQ<21>")
	)
	(arc
		(start 138.377676 -239.136936)
		(mid 138.559927 -239.187286)
		(end 138.743436 -239.141762)
		(width 0.0889)
		(layer "In4.Cu")
		(net "M_J_CPU1_SA_DQ<21>")
	)
	(arc
		(start 133.111748 -239.136936)
		(mid 133.394704 -239.060759)
		(end 133.67766 -239.136936)
		(width 0.0889)
		(layer "In4.Cu")
		(net "M_J_CPU1_SA_DQ<21>")
	)
	(arc
		(start 144.018254 -239.136936)
		(mid 144.198712 -239.18738)
		(end 144.380966 -239.143794)
		(width 0.0889)
		(layer "In4.Cu")
		(net "M_J_CPU1_SA_DQ<21>")
	)
	(arc
		(start 132.737606 -239.136936)
		(mid 132.919857 -239.187286)
		(end 133.103366 -239.141762)
		(width 0.0889)
		(layer "In4.Cu")
		(net "M_J_CPU1_SA_DQ<21>")
	)
	(arc
		(start 137.437622 -239.136936)
		(mid 137.619873 -239.187286)
		(end 137.803382 -239.141762)
		(width 0.0889)
		(layer "In4.Cu")
		(net "M_J_CPU1_SA_DQ<21>")
	)
	(arc
		(start 143.466566 -239.1283)
		(mid 143.743549 -239.060496)
		(end 144.018254 -239.136936)
		(width 0.0889)
		(layer "In4.Cu")
		(net "M_J_CPU1_SA_DQ<21>")
	)
	(arc
		(start 134.626096 -239.141762)
		(mid 134.809604 -239.187256)
		(end 134.991856 -239.136936)
		(width 0.0889)
		(layer "In4.Cu")
		(net "M_J_CPU1_SA_DQ<21>")
	)
	(arc
		(start 134.991856 -239.136936)
		(mid 135.274812 -239.060759)
		(end 135.557768 -239.136936)
		(width 0.0889)
		(layer "In4.Cu")
		(net "M_J_CPU1_SA_DQ<21>")
	)
	(arc
		(start 143.086074 -239.141762)
		(mid 143.269582 -239.187256)
		(end 143.451834 -239.136936)
		(width 0.0889)
		(layer "In4.Cu")
		(net "M_J_CPU1_SA_DQ<21>")
	)
	(arc
		(start 135.56615 -239.141762)
		(mid 135.749658 -239.187256)
		(end 135.93191 -239.136936)
		(width 0.0889)
		(layer "In4.Cu")
		(net "M_J_CPU1_SA_DQ<21>")
	)
	(arc
		(start 141.197838 -239.136936)
		(mid 141.384782 -239.187191)
		(end 141.571726 -239.136936)
		(width 0.0889)
		(layer "In4.Cu")
		(net "M_J_CPU1_SA_DQ<21>")
	)
	(arc
		(start 136.497822 -239.136936)
		(mid 136.684766 -239.187191)
		(end 136.87171 -239.136936)
		(width 0.0889)
		(layer "In4.Cu")
		(net "M_J_CPU1_SA_DQ<21>")
	)
	(arc
		(start 132.171694 -239.136936)
		(mid 132.45465 -239.060759)
		(end 132.737606 -239.136936)
		(width 0.0889)
		(layer "In4.Cu")
		(net "M_J_CPU1_SA_DQ<21>")
	)
	(arc
		(start 131.29514 -239.105186)
		(mid 131.550205 -239.061835)
		(end 131.797806 -239.136936)
		(width 0.0889)
		(layer "In4.Cu")
		(net "M_J_CPU1_SA_DQ<21>")
	)
	(arc
		(start 142.51178 -239.136936)
		(mid 142.794736 -239.060759)
		(end 143.077692 -239.136936)
		(width 0.0889)
		(layer "In4.Cu")
		(net "M_J_CPU1_SA_DQ<21>")
	)
	(arc
		(start 140.266166 -239.141762)
		(mid 140.449674 -239.187256)
		(end 140.631926 -239.136936)
		(width 0.0889)
		(layer "In4.Cu")
		(net "M_J_CPU1_SA_DQ<21>")
	)
	(arc
		(start 137.811764 -239.136936)
		(mid 138.09472 -239.060759)
		(end 138.377676 -239.136936)
		(width 0.0889)
		(layer "In4.Cu")
		(net "M_J_CPU1_SA_DQ<21>")
	)
	(arc
		(start 144.39265 -239.136936)
		(mid 144.672078 -239.06077)
		(end 144.952466 -239.13338)
		(width 0.0889)
		(layer "In4.Cu")
		(net "M_J_CPU1_SA_DQ<21>")
	)
	(arc
		(start 133.67766 -239.136936)
		(mid 133.859911 -239.187286)
		(end 134.04342 -239.141762)
		(width 0.0889)
		(layer "In4.Cu")
		(net "M_J_CPU1_SA_DQ<21>")
	)
	(arc
		(start 139.691872 -239.136936)
		(mid 139.974828 -239.060759)
		(end 140.257784 -239.136936)
		(width 0.0889)
		(layer "In4.Cu")
		(net "M_J_CPU1_SA_DQ<21>")
	)
	(arc
		(start 138.751818 -239.136936)
		(mid 139.034774 -239.060759)
		(end 139.31773 -239.136936)
		(width 0.0889)
		(layer "In4.Cu")
		(net "M_J_CPU1_SA_DQ<21>")
	)
	(arc
		(start 136.87171 -239.136936)
		(mid 137.154666 -239.060759)
		(end 137.437622 -239.136936)
		(width 0.0889)
		(layer "In4.Cu")
		(net "M_J_CPU1_SA_DQ<21>")
	)
	(segment
		(start 131.987798 -238.270288)
		(end 132.45465 -238.00435)
		(width 0.10668)
		(layer "F.Cu")
		(net "M_J_CPU1_SA_DQ<20>")
	)
	(segment
		(start 170.405552 -222.419926)
		(end 173.643544 -222.419926)
		(width 0.14478)
		(layer "In4.Cu")
		(net "M_J_CPU1_SA_DQ<20>")
	)
	(segment
		(start 189.42304 -221.723458)
		(end 189.42304 -222.1611)
		(width 0.14478)
		(layer "In4.Cu")
		(net "M_J_CPU1_SA_DQ<20>")
	)
	(segment
		(start 149.515322 -236.423454)
		(end 156.913834 -229.024942)
		(width 0.14478)
		(layer "In4.Cu")
		(net "M_J_CPU1_SA_DQ<20>")
	)
	(segment
		(start 167.18026 -221.56039)
		(end 169.546016 -221.56039)
		(width 0.14478)
		(layer "In4.Cu")
		(net "M_J_CPU1_SA_DQ<20>")
	)
	(segment
		(start 140.15339 -238.331756)
		(end 140.161772 -238.32693)
		(width 0.0889)
		(layer "In4.Cu")
		(net "M_J_CPU1_SA_DQ<20>")
	)
	(segment
		(start 132.608828 -238.26978)
		(end 132.705094 -238.29518)
		(width 0.0889)
		(layer "In4.Cu")
		(net "M_J_CPU1_SA_DQ<20>")
	)
	(segment
		(start 143.547592 -238.32693)
		(end 143.555974 -238.331756)
		(width 0.0889)
		(layer "In4.Cu")
		(net "M_J_CPU1_SA_DQ<20>")
	)
	(segment
		(start 136.967722 -238.32693)
		(end 136.976104 -238.331756)
		(width 0.0889)
		(layer "In4.Cu")
		(net "M_J_CPU1_SA_DQ<20>")
	)
	(segment
		(start 181.525672 -222.419926)
		(end 182.375556 -221.570042)
		(width 0.14478)
		(layer "In4.Cu")
		(net "M_J_CPU1_SA_DQ<20>")
	)
	(segment
		(start 141.667738 -238.32693)
		(end 141.67612 -238.331756)
		(width 0.0889)
		(layer "In4.Cu")
		(net "M_J_CPU1_SA_DQ<20>")
	)
	(segment
		(start 136.393428 -238.331756)
		(end 136.40181 -238.32693)
		(width 0.0889)
		(layer "In4.Cu")
		(net "M_J_CPU1_SA_DQ<20>")
	)
	(segment
		(start 169.546016 -221.56039)
		(end 170.405552 -222.419926)
		(width 0.14478)
		(layer "In4.Cu")
		(net "M_J_CPU1_SA_DQ<20>")
	)
	(segment
		(start 182.375556 -221.570042)
		(end 189.269624 -221.570042)
		(width 0.14478)
		(layer "In4.Cu")
		(net "M_J_CPU1_SA_DQ<20>")
	)
	(segment
		(start 178.215798 -222.419926)
		(end 181.525672 -222.419926)
		(width 0.14478)
		(layer "In4.Cu")
		(net "M_J_CPU1_SA_DQ<20>")
	)
	(segment
		(start 144.477994 -238.320834)
		(end 144.488408 -238.32693)
		(width 0.0889)
		(layer "In4.Cu")
		(net "M_J_CPU1_SA_DQ<20>")
	)
	(segment
		(start 174.493428 -221.570042)
		(end 177.365914 -221.570042)
		(width 0.14478)
		(layer "In4.Cu")
		(net "M_J_CPU1_SA_DQ<20>")
	)
	(segment
		(start 141.093444 -238.331756)
		(end 141.101826 -238.32693)
		(width 0.0889)
		(layer "In4.Cu")
		(net "M_J_CPU1_SA_DQ<20>")
	)
	(segment
		(start 177.365914 -221.570042)
		(end 178.215798 -222.419926)
		(width 0.14478)
		(layer "In4.Cu")
		(net "M_J_CPU1_SA_DQ<20>")
	)
	(segment
		(start 147.499324 -236.423454)
		(end 147.856194 -236.423454)
		(width 0.0889)
		(layer "In4.Cu")
		(net "M_J_CPU1_SA_DQ<20>")
	)
	(segment
		(start 189.979554 -222.1611)
		(end 189.979554 -221.723458)
		(width 0.14478)
		(layer "In4.Cu")
		(net "M_J_CPU1_SA_DQ<20>")
	)
	(segment
		(start 135.453374 -238.331756)
		(end 135.461756 -238.32693)
		(width 0.0889)
		(layer "In4.Cu")
		(net "M_J_CPU1_SA_DQ<20>")
	)
	(segment
		(start 147.856194 -236.423454)
		(end 149.515322 -236.423454)
		(width 0.14478)
		(layer "In4.Cu")
		(net "M_J_CPU1_SA_DQ<20>")
	)
	(segment
		(start 189.979554 -221.723458)
		(end 190.142622 -221.56039)
		(width 0.14478)
		(layer "In4.Cu")
		(net "M_J_CPU1_SA_DQ<20>")
	)
	(segment
		(start 189.42304 -222.1611)
		(end 189.586108 -222.324168)
		(width 0.14478)
		(layer "In4.Cu")
		(net "M_J_CPU1_SA_DQ<20>")
	)
	(segment
		(start 166.330376 -222.410274)
		(end 167.18026 -221.56039)
		(width 0.14478)
		(layer "In4.Cu")
		(net "M_J_CPU1_SA_DQ<20>")
	)
	(segment
		(start 161.160206 -222.410274)
		(end 166.330376 -222.410274)
		(width 0.14478)
		(layer "In4.Cu")
		(net "M_J_CPU1_SA_DQ<20>")
	)
	(segment
		(start 189.816486 -222.324168)
		(end 189.979554 -222.1611)
		(width 0.14478)
		(layer "In4.Cu")
		(net "M_J_CPU1_SA_DQ<20>")
	)
	(segment
		(start 145.144744 -238.250476)
		(end 145.672302 -238.250476)
		(width 0.0889)
		(layer "In4.Cu")
		(net "M_J_CPU1_SA_DQ<20>")
	)
	(segment
		(start 189.586108 -222.324168)
		(end 189.816486 -222.324168)
		(width 0.14478)
		(layer "In4.Cu")
		(net "M_J_CPU1_SA_DQ<20>")
	)
	(segment
		(start 156.913834 -229.024942)
		(end 156.913834 -226.656646)
		(width 0.14478)
		(layer "In4.Cu")
		(net "M_J_CPU1_SA_DQ<20>")
	)
	(segment
		(start 156.913834 -226.656646)
		(end 161.160206 -222.410274)
		(width 0.14478)
		(layer "In4.Cu")
		(net "M_J_CPU1_SA_DQ<20>")
	)
	(segment
		(start 145.672302 -238.250476)
		(end 147.499324 -236.423454)
		(width 0.0889)
		(layer "In4.Cu")
		(net "M_J_CPU1_SA_DQ<20>")
	)
	(segment
		(start 132.45465 -238.00435)
		(end 132.608828 -238.26978)
		(width 0.0889)
		(layer "In4.Cu")
		(net "M_J_CPU1_SA_DQ<20>")
	)
	(segment
		(start 189.269624 -221.570042)
		(end 189.42304 -221.723458)
		(width 0.14478)
		(layer "In4.Cu")
		(net "M_J_CPU1_SA_DQ<20>")
	)
	(segment
		(start 190.735204 -221.56039)
		(end 191.160146 -221.985332)
		(width 0.14478)
		(layer "In4.Cu")
		(net "M_J_CPU1_SA_DQ<20>")
	)
	(segment
		(start 190.142622 -221.56039)
		(end 190.735204 -221.56039)
		(width 0.14478)
		(layer "In4.Cu")
		(net "M_J_CPU1_SA_DQ<20>")
	)
	(segment
		(start 133.20776 -238.32693)
		(end 133.216142 -238.331756)
		(width 0.0889)
		(layer "In4.Cu")
		(net "M_J_CPU1_SA_DQ<20>")
	)
	(segment
		(start 137.907776 -238.32693)
		(end 137.916158 -238.331756)
		(width 0.0889)
		(layer "In4.Cu")
		(net "M_J_CPU1_SA_DQ<20>")
	)
	(segment
		(start 173.643544 -222.419926)
		(end 174.493428 -221.570042)
		(width 0.14478)
		(layer "In4.Cu")
		(net "M_J_CPU1_SA_DQ<20>")
	)
	(arc
		(start 134.521702 -238.32693)
		(mid 134.804658 -238.250753)
		(end 135.087614 -238.32693)
		(width 0.0889)
		(layer "In4.Cu")
		(net "M_J_CPU1_SA_DQ<20>")
	)
	(arc
		(start 143.922242 -238.32693)
		(mid 144.199309 -238.250659)
		(end 144.477994 -238.320834)
		(width 0.0889)
		(layer "In4.Cu")
		(net "M_J_CPU1_SA_DQ<20>")
	)
	(arc
		(start 136.976104 -238.331756)
		(mid 137.159612 -238.37725)
		(end 137.341864 -238.32693)
		(width 0.0889)
		(layer "In4.Cu")
		(net "M_J_CPU1_SA_DQ<20>")
	)
	(arc
		(start 134.147814 -238.32693)
		(mid 134.334758 -238.377185)
		(end 134.521702 -238.32693)
		(width 0.0889)
		(layer "In4.Cu")
		(net "M_J_CPU1_SA_DQ<20>")
	)
	(arc
		(start 138.84783 -238.32693)
		(mid 139.034774 -238.377185)
		(end 139.221718 -238.32693)
		(width 0.0889)
		(layer "In4.Cu")
		(net "M_J_CPU1_SA_DQ<20>")
	)
	(arc
		(start 137.916158 -238.331756)
		(mid 138.099666 -238.37725)
		(end 138.281918 -238.32693)
		(width 0.0889)
		(layer "In4.Cu")
		(net "M_J_CPU1_SA_DQ<20>")
	)
	(arc
		(start 142.04188 -238.32693)
		(mid 142.324836 -238.250753)
		(end 142.607792 -238.32693)
		(width 0.0889)
		(layer "In4.Cu")
		(net "M_J_CPU1_SA_DQ<20>")
	)
	(arc
		(start 142.607792 -238.32693)
		(mid 142.794736 -238.377185)
		(end 142.98168 -238.32693)
		(width 0.0889)
		(layer "In4.Cu")
		(net "M_J_CPU1_SA_DQ<20>")
	)
	(arc
		(start 139.221718 -238.32693)
		(mid 139.504674 -238.250753)
		(end 139.78763 -238.32693)
		(width 0.0889)
		(layer "In4.Cu")
		(net "M_J_CPU1_SA_DQ<20>")
	)
	(arc
		(start 140.727684 -238.32693)
		(mid 140.909935 -238.37728)
		(end 141.093444 -238.331756)
		(width 0.0889)
		(layer "In4.Cu")
		(net "M_J_CPU1_SA_DQ<20>")
	)
	(arc
		(start 142.98168 -238.32693)
		(mid 143.264636 -238.250753)
		(end 143.547592 -238.32693)
		(width 0.0889)
		(layer "In4.Cu")
		(net "M_J_CPU1_SA_DQ<20>")
	)
	(arc
		(start 137.341864 -238.32693)
		(mid 137.62482 -238.250753)
		(end 137.907776 -238.32693)
		(width 0.0889)
		(layer "In4.Cu")
		(net "M_J_CPU1_SA_DQ<20>")
	)
	(arc
		(start 139.78763 -238.32693)
		(mid 139.969881 -238.37728)
		(end 140.15339 -238.331756)
		(width 0.0889)
		(layer "In4.Cu")
		(net "M_J_CPU1_SA_DQ<20>")
	)
	(arc
		(start 144.488408 -238.32693)
		(mid 144.666058 -238.37719)
		(end 144.84604 -238.336074)
		(width 0.0889)
		(layer "In4.Cu")
		(net "M_J_CPU1_SA_DQ<20>")
	)
	(arc
		(start 132.705094 -238.29518)
		(mid 132.960159 -238.251829)
		(end 133.20776 -238.32693)
		(width 0.0889)
		(layer "In4.Cu")
		(net "M_J_CPU1_SA_DQ<20>")
	)
	(arc
		(start 135.087614 -238.32693)
		(mid 135.269865 -238.37728)
		(end 135.453374 -238.331756)
		(width 0.0889)
		(layer "In4.Cu")
		(net "M_J_CPU1_SA_DQ<20>")
	)
	(arc
		(start 133.216142 -238.331756)
		(mid 133.39965 -238.37725)
		(end 133.581902 -238.32693)
		(width 0.0889)
		(layer "In4.Cu")
		(net "M_J_CPU1_SA_DQ<20>")
	)
	(arc
		(start 136.40181 -238.32693)
		(mid 136.684766 -238.250753)
		(end 136.967722 -238.32693)
		(width 0.0889)
		(layer "In4.Cu")
		(net "M_J_CPU1_SA_DQ<20>")
	)
	(arc
		(start 136.027668 -238.32693)
		(mid 136.209919 -238.37728)
		(end 136.393428 -238.331756)
		(width 0.0889)
		(layer "In4.Cu")
		(net "M_J_CPU1_SA_DQ<20>")
	)
	(arc
		(start 144.84604 -238.336074)
		(mid 144.989379 -238.272287)
		(end 145.144744 -238.250476)
		(width 0.0889)
		(layer "In4.Cu")
		(net "M_J_CPU1_SA_DQ<20>")
	)
	(arc
		(start 143.555974 -238.331756)
		(mid 143.739736 -238.377372)
		(end 143.922242 -238.32693)
		(width 0.0889)
		(layer "In4.Cu")
		(net "M_J_CPU1_SA_DQ<20>")
	)
	(arc
		(start 138.281918 -238.32693)
		(mid 138.564874 -238.250753)
		(end 138.84783 -238.32693)
		(width 0.0889)
		(layer "In4.Cu")
		(net "M_J_CPU1_SA_DQ<20>")
	)
	(arc
		(start 140.161772 -238.32693)
		(mid 140.444728 -238.250753)
		(end 140.727684 -238.32693)
		(width 0.0889)
		(layer "In4.Cu")
		(net "M_J_CPU1_SA_DQ<20>")
	)
	(arc
		(start 133.581902 -238.32693)
		(mid 133.864858 -238.250753)
		(end 134.147814 -238.32693)
		(width 0.0889)
		(layer "In4.Cu")
		(net "M_J_CPU1_SA_DQ<20>")
	)
	(arc
		(start 141.101826 -238.32693)
		(mid 141.384782 -238.250753)
		(end 141.667738 -238.32693)
		(width 0.0889)
		(layer "In4.Cu")
		(net "M_J_CPU1_SA_DQ<20>")
	)
	(arc
		(start 141.67612 -238.331756)
		(mid 141.859628 -238.37725)
		(end 142.04188 -238.32693)
		(width 0.0889)
		(layer "In4.Cu")
		(net "M_J_CPU1_SA_DQ<20>")
	)
	(arc
		(start 135.461756 -238.32693)
		(mid 135.744712 -238.250753)
		(end 136.027668 -238.32693)
		(width 0.0889)
		(layer "In4.Cu")
		(net "M_J_CPU1_SA_DQ<20>")
	)
	(segment
		(start 130.577844 -226.120452)
		(end 131.044696 -225.854514)
		(width 0.10668)
		(layer "F.Cu")
		(net "M_J_CPU1_SA_DQ<1>")
	)
	(segment
		(start 157.701996 -202.818492)
		(end 157.701996 -201.527664)
		(width 0.14478)
		(layer "In4.Cu")
		(net "M_J_CPU1_SA_DQ<1>")
	)
	(segment
		(start 139.31773 -226.177094)
		(end 139.326112 -226.18192)
		(width 0.0889)
		(layer "In4.Cu")
		(net "M_J_CPU1_SA_DQ<1>")
	)
	(segment
		(start 142.001748 -223.770698)
		(end 142.042134 -223.747076)
		(width 0.0889)
		(layer "In4.Cu")
		(net "M_J_CPU1_SA_DQ<1>")
	)
	(segment
		(start 142.47876 -222.956374)
		(end 142.512288 -222.936816)
		(width 0.0889)
		(layer "In4.Cu")
		(net "M_J_CPU1_SA_DQ<1>")
	)
	(segment
		(start 141.101826 -225.367088)
		(end 141.133576 -225.3488)
		(width 0.0889)
		(layer "In4.Cu")
		(net "M_J_CPU1_SA_DQ<1>")
	)
	(segment
		(start 157.701996 -201.527664)
		(end 159.769302 -199.460358)
		(width 0.14478)
		(layer "In4.Cu")
		(net "M_J_CPU1_SA_DQ<1>")
	)
	(segment
		(start 180.682646 -199.460358)
		(end 182.734458 -198.610474)
		(width 0.14478)
		(layer "In4.Cu")
		(net "M_J_CPU1_SA_DQ<1>")
	)
	(segment
		(start 131.044696 -225.854514)
		(end 131.198874 -226.119944)
		(width 0.0889)
		(layer "In4.Cu")
		(net "M_J_CPU1_SA_DQ<1>")
	)
	(segment
		(start 143.022828 -221.288864)
		(end 143.022828 -217.49766)
		(width 0.14478)
		(layer "In4.Cu")
		(net "M_J_CPU1_SA_DQ<1>")
	)
	(segment
		(start 134.617714 -226.177094)
		(end 134.626096 -226.18192)
		(width 0.0889)
		(layer "In4.Cu")
		(net "M_J_CPU1_SA_DQ<1>")
	)
	(segment
		(start 134.04342 -226.18192)
		(end 134.051802 -226.177094)
		(width 0.0889)
		(layer "In4.Cu")
		(net "M_J_CPU1_SA_DQ<1>")
	)
	(segment
		(start 182.734458 -198.610474)
		(end 189.023752 -198.610474)
		(width 0.14478)
		(layer "In4.Cu")
		(net "M_J_CPU1_SA_DQ<1>")
	)
	(segment
		(start 172.753528 -199.460358)
		(end 174.80534 -198.610474)
		(width 0.14478)
		(layer "In4.Cu")
		(net "M_J_CPU1_SA_DQ<1>")
	)
	(segment
		(start 133.103366 -226.18192)
		(end 133.111748 -226.177094)
		(width 0.0889)
		(layer "In4.Cu")
		(net "M_J_CPU1_SA_DQ<1>")
	)
	(segment
		(start 143.170402 -221.545658)
		(end 143.022828 -221.398084)
		(width 0.0889)
		(layer "In4.Cu")
		(net "M_J_CPU1_SA_DQ<1>")
	)
	(segment
		(start 171.766484 -199.460358)
		(end 172.753528 -199.460358)
		(width 0.14478)
		(layer "In4.Cu")
		(net "M_J_CPU1_SA_DQ<1>")
	)
	(segment
		(start 142.512288 -222.936816)
		(end 142.542514 -222.91929)
		(width 0.0889)
		(layer "In4.Cu")
		(net "M_J_CPU1_SA_DQ<1>")
	)
	(segment
		(start 167.65524 -198.610474)
		(end 169.714672 -198.610474)
		(width 0.14478)
		(layer "In4.Cu")
		(net "M_J_CPU1_SA_DQ<1>")
	)
	(segment
		(start 135.557768 -226.177094)
		(end 135.56615 -226.18192)
		(width 0.0889)
		(layer "In4.Cu")
		(net "M_J_CPU1_SA_DQ<1>")
	)
	(segment
		(start 174.80534 -198.610474)
		(end 177.361342 -198.610474)
		(width 0.14478)
		(layer "In4.Cu")
		(net "M_J_CPU1_SA_DQ<1>")
	)
	(segment
		(start 141.535404 -224.578164)
		(end 141.571726 -224.557082)
		(width 0.0889)
		(layer "In4.Cu")
		(net "M_J_CPU1_SA_DQ<1>")
	)
	(segment
		(start 165.603428 -199.460358)
		(end 167.65524 -198.610474)
		(width 0.14478)
		(layer "In4.Cu")
		(net "M_J_CPU1_SA_DQ<1>")
	)
	(segment
		(start 169.714672 -198.610474)
		(end 171.766484 -199.460358)
		(width 0.14478)
		(layer "In4.Cu")
		(net "M_J_CPU1_SA_DQ<1>")
	)
	(segment
		(start 142.947136 -222.14713)
		(end 142.982442 -222.12681)
		(width 0.0889)
		(layer "In4.Cu")
		(net "M_J_CPU1_SA_DQ<1>")
	)
	(segment
		(start 142.042134 -223.747076)
		(end 142.072868 -223.729296)
		(width 0.0889)
		(layer "In4.Cu")
		(net "M_J_CPU1_SA_DQ<1>")
	)
	(segment
		(start 141.06271 -225.389948)
		(end 141.101826 -225.367088)
		(width 0.0889)
		(layer "In4.Cu")
		(net "M_J_CPU1_SA_DQ<1>")
	)
	(segment
		(start 137.803382 -226.18192)
		(end 137.811764 -226.177094)
		(width 0.0889)
		(layer "In4.Cu")
		(net "M_J_CPU1_SA_DQ<1>")
	)
	(segment
		(start 177.361342 -198.610474)
		(end 179.413154 -199.460358)
		(width 0.14478)
		(layer "In4.Cu")
		(net "M_J_CPU1_SA_DQ<1>")
	)
	(segment
		(start 179.413154 -199.460358)
		(end 180.682646 -199.460358)
		(width 0.14478)
		(layer "In4.Cu")
		(net "M_J_CPU1_SA_DQ<1>")
	)
	(segment
		(start 140.631926 -226.177094)
		(end 140.662406 -226.159314)
		(width 0.0889)
		(layer "In4.Cu")
		(net "M_J_CPU1_SA_DQ<1>")
	)
	(segment
		(start 143.170402 -221.804484)
		(end 143.170402 -221.545658)
		(width 0.0889)
		(layer "In4.Cu")
		(net "M_J_CPU1_SA_DQ<1>")
	)
	(segment
		(start 143.022828 -221.398084)
		(end 143.022828 -221.288864)
		(width 0.0889)
		(layer "In4.Cu")
		(net "M_J_CPU1_SA_DQ<1>")
	)
	(segment
		(start 189.023752 -198.610474)
		(end 191.160146 -199.035416)
		(width 0.14478)
		(layer "In4.Cu")
		(net "M_J_CPU1_SA_DQ<1>")
	)
	(segment
		(start 159.769302 -199.460358)
		(end 165.603428 -199.460358)
		(width 0.14478)
		(layer "In4.Cu")
		(net "M_J_CPU1_SA_DQ<1>")
	)
	(segment
		(start 141.571726 -224.557082)
		(end 141.603476 -224.538794)
		(width 0.0889)
		(layer "In4.Cu")
		(net "M_J_CPU1_SA_DQ<1>")
	)
	(segment
		(start 131.198874 -226.119944)
		(end 131.29514 -226.145344)
		(width 0.0889)
		(layer "In4.Cu")
		(net "M_J_CPU1_SA_DQ<1>")
	)
	(segment
		(start 138.743436 -226.18192)
		(end 138.751818 -226.177094)
		(width 0.0889)
		(layer "In4.Cu")
		(net "M_J_CPU1_SA_DQ<1>")
	)
	(segment
		(start 143.022828 -217.49766)
		(end 157.701996 -202.818492)
		(width 0.14478)
		(layer "In4.Cu")
		(net "M_J_CPU1_SA_DQ<1>")
	)
	(segment
		(start 140.257784 -226.177094)
		(end 140.266166 -226.18192)
		(width 0.0889)
		(layer "In4.Cu")
		(net "M_J_CPU1_SA_DQ<1>")
	)
	(segment
		(start 142.982442 -222.12681)
		(end 143.016986 -222.106744)
		(width 0.0889)
		(layer "In4.Cu")
		(net "M_J_CPU1_SA_DQ<1>")
	)
	(arc
		(start 134.051802 -226.177094)
		(mid 134.334758 -226.100917)
		(end 134.617714 -226.177094)
		(width 0.0889)
		(layer "In4.Cu")
		(net "M_J_CPU1_SA_DQ<1>")
	)
	(arc
		(start 141.133576 -225.3488)
		(mid 141.248252 -225.215466)
		(end 141.289532 -225.044508)
		(width 0.0889)
		(layer "In4.Cu")
		(net "M_J_CPU1_SA_DQ<1>")
	)
	(arc
		(start 142.542514 -222.91929)
		(mid 142.658093 -222.785963)
		(end 142.69974 -222.61449)
		(width 0.0889)
		(layer "In4.Cu")
		(net "M_J_CPU1_SA_DQ<1>")
	)
	(arc
		(start 134.991856 -226.177094)
		(mid 135.274812 -226.100917)
		(end 135.557768 -226.177094)
		(width 0.0889)
		(layer "In4.Cu")
		(net "M_J_CPU1_SA_DQ<1>")
	)
	(arc
		(start 135.56615 -226.18192)
		(mid 135.749658 -226.227414)
		(end 135.93191 -226.177094)
		(width 0.0889)
		(layer "In4.Cu")
		(net "M_J_CPU1_SA_DQ<1>")
	)
	(arc
		(start 134.626096 -226.18192)
		(mid 134.809604 -226.227414)
		(end 134.991856 -226.177094)
		(width 0.0889)
		(layer "In4.Cu")
		(net "M_J_CPU1_SA_DQ<1>")
	)
	(arc
		(start 131.797806 -226.177094)
		(mid 131.98475 -226.227349)
		(end 132.171694 -226.177094)
		(width 0.0889)
		(layer "In4.Cu")
		(net "M_J_CPU1_SA_DQ<1>")
	)
	(arc
		(start 140.662406 -226.159314)
		(mid 140.777833 -226.025938)
		(end 140.819378 -225.854514)
		(width 0.0889)
		(layer "In4.Cu")
		(net "M_J_CPU1_SA_DQ<1>")
	)
	(arc
		(start 141.759432 -224.234502)
		(mid 141.823725 -223.972897)
		(end 142.001748 -223.770698)
		(width 0.0889)
		(layer "In4.Cu")
		(net "M_J_CPU1_SA_DQ<1>")
	)
	(arc
		(start 139.326112 -226.18192)
		(mid 139.50962 -226.227414)
		(end 139.691872 -226.177094)
		(width 0.0889)
		(layer "In4.Cu")
		(net "M_J_CPU1_SA_DQ<1>")
	)
	(arc
		(start 137.437622 -226.177094)
		(mid 137.619873 -226.227444)
		(end 137.803382 -226.18192)
		(width 0.0889)
		(layer "In4.Cu")
		(net "M_J_CPU1_SA_DQ<1>")
	)
	(arc
		(start 138.377676 -226.177094)
		(mid 138.559927 -226.227444)
		(end 138.743436 -226.18192)
		(width 0.0889)
		(layer "In4.Cu")
		(net "M_J_CPU1_SA_DQ<1>")
	)
	(arc
		(start 133.67766 -226.177094)
		(mid 133.859911 -226.227444)
		(end 134.04342 -226.18192)
		(width 0.0889)
		(layer "In4.Cu")
		(net "M_J_CPU1_SA_DQ<1>")
	)
	(arc
		(start 132.737606 -226.177094)
		(mid 132.919857 -226.227444)
		(end 133.103366 -226.18192)
		(width 0.0889)
		(layer "In4.Cu")
		(net "M_J_CPU1_SA_DQ<1>")
	)
	(arc
		(start 141.603476 -224.538794)
		(mid 141.718152 -224.40546)
		(end 141.759432 -224.234502)
		(width 0.0889)
		(layer "In4.Cu")
		(net "M_J_CPU1_SA_DQ<1>")
	)
	(arc
		(start 142.69974 -222.61449)
		(mid 142.765403 -222.350089)
		(end 142.947136 -222.14713)
		(width 0.0889)
		(layer "In4.Cu")
		(net "M_J_CPU1_SA_DQ<1>")
	)
	(arc
		(start 136.497822 -226.177094)
		(mid 136.684766 -226.227349)
		(end 136.87171 -226.177094)
		(width 0.0889)
		(layer "In4.Cu")
		(net "M_J_CPU1_SA_DQ<1>")
	)
	(arc
		(start 138.751818 -226.177094)
		(mid 139.034774 -226.100917)
		(end 139.31773 -226.177094)
		(width 0.0889)
		(layer "In4.Cu")
		(net "M_J_CPU1_SA_DQ<1>")
	)
	(arc
		(start 131.29514 -226.145344)
		(mid 131.550205 -226.101993)
		(end 131.797806 -226.177094)
		(width 0.0889)
		(layer "In4.Cu")
		(net "M_J_CPU1_SA_DQ<1>")
	)
	(arc
		(start 140.819378 -225.854514)
		(mid 140.883893 -225.592295)
		(end 141.06271 -225.389948)
		(width 0.0889)
		(layer "In4.Cu")
		(net "M_J_CPU1_SA_DQ<1>")
	)
	(arc
		(start 137.811764 -226.177094)
		(mid 138.09472 -226.100917)
		(end 138.377676 -226.177094)
		(width 0.0889)
		(layer "In4.Cu")
		(net "M_J_CPU1_SA_DQ<1>")
	)
	(arc
		(start 142.072868 -223.729296)
		(mid 142.188295 -223.59592)
		(end 142.22984 -223.424496)
		(width 0.0889)
		(layer "In4.Cu")
		(net "M_J_CPU1_SA_DQ<1>")
	)
	(arc
		(start 133.111748 -226.177094)
		(mid 133.394704 -226.100917)
		(end 133.67766 -226.177094)
		(width 0.0889)
		(layer "In4.Cu")
		(net "M_J_CPU1_SA_DQ<1>")
	)
	(arc
		(start 141.289532 -225.044508)
		(mid 141.354768 -224.780917)
		(end 141.535404 -224.578164)
		(width 0.0889)
		(layer "In4.Cu")
		(net "M_J_CPU1_SA_DQ<1>")
	)
	(arc
		(start 143.016986 -222.106744)
		(mid 143.129872 -221.973973)
		(end 143.170402 -221.804484)
		(width 0.0889)
		(layer "In4.Cu")
		(net "M_J_CPU1_SA_DQ<1>")
	)
	(arc
		(start 132.171694 -226.177094)
		(mid 132.45465 -226.100917)
		(end 132.737606 -226.177094)
		(width 0.0889)
		(layer "In4.Cu")
		(net "M_J_CPU1_SA_DQ<1>")
	)
	(arc
		(start 135.93191 -226.177094)
		(mid 136.214866 -226.100917)
		(end 136.497822 -226.177094)
		(width 0.0889)
		(layer "In4.Cu")
		(net "M_J_CPU1_SA_DQ<1>")
	)
	(arc
		(start 142.22984 -223.424496)
		(mid 142.295939 -223.159402)
		(end 142.47876 -222.956374)
		(width 0.0889)
		(layer "In4.Cu")
		(net "M_J_CPU1_SA_DQ<1>")
	)
	(arc
		(start 136.87171 -226.177094)
		(mid 137.154666 -226.100917)
		(end 137.437622 -226.177094)
		(width 0.0889)
		(layer "In4.Cu")
		(net "M_J_CPU1_SA_DQ<1>")
	)
	(arc
		(start 140.266166 -226.18192)
		(mid 140.449674 -226.227414)
		(end 140.631926 -226.177094)
		(width 0.0889)
		(layer "In4.Cu")
		(net "M_J_CPU1_SA_DQ<1>")
	)
	(arc
		(start 139.691872 -226.177094)
		(mid 139.974828 -226.100917)
		(end 140.257784 -226.177094)
		(width 0.0889)
		(layer "In4.Cu")
		(net "M_J_CPU1_SA_DQ<1>")
	)
	(segment
		(start 131.047998 -236.650276)
		(end 131.51485 -236.384338)
		(width 0.10668)
		(layer "F.Cu")
		(net "M_J_CPU1_SA_DQ<19>")
	)
	(segment
		(start 154.625294 -225.651314)
		(end 154.92984 -225.346768)
		(width 0.14478)
		(layer "In4.Cu")
		(net "M_J_CPU1_SA_DQ<19>")
	)
	(segment
		(start 141.667738 -236.061758)
		(end 141.67612 -236.056932)
		(width 0.0889)
		(layer "In4.Cu")
		(net "M_J_CPU1_SA_DQ<19>")
	)
	(segment
		(start 174.256192 -218.150694)
		(end 178.124358 -218.150694)
		(width 0.14478)
		(layer "In4.Cu")
		(net "M_J_CPU1_SA_DQ<19>")
	)
	(segment
		(start 157.889448 -222.38716)
		(end 161.266124 -219.010484)
		(width 0.14478)
		(layer "In4.Cu")
		(net "M_J_CPU1_SA_DQ<19>")
	)
	(segment
		(start 178.124358 -218.150694)
		(end 178.974496 -219.000832)
		(width 0.14478)
		(layer "In4.Cu")
		(net "M_J_CPU1_SA_DQ<19>")
	)
	(segment
		(start 157.445202 -222.171514)
		(end 157.660848 -222.38716)
		(width 0.14478)
		(layer "In4.Cu")
		(net "M_J_CPU1_SA_DQ<19>")
	)
	(segment
		(start 146.357848 -235.211112)
		(end 146.357848 -234.865672)
		(width 0.0889)
		(layer "In4.Cu")
		(net "M_J_CPU1_SA_DQ<19>")
	)
	(segment
		(start 155.104338 -224.512378)
		(end 155.319984 -224.728024)
		(width 0.14478)
		(layer "In4.Cu")
		(net "M_J_CPU1_SA_DQ<19>")
	)
	(segment
		(start 157.10916 -223.167448)
		(end 157.270704 -223.005904)
		(width 0.14478)
		(layer "In4.Cu")
		(net "M_J_CPU1_SA_DQ<19>")
	)
	(segment
		(start 144.20596 -236.138212)
		(end 145.430748 -236.138212)
		(width 0.0889)
		(layer "In4.Cu")
		(net "M_J_CPU1_SA_DQ<19>")
	)
	(segment
		(start 133.20776 -236.061758)
		(end 133.216142 -236.056932)
		(width 0.0889)
		(layer "In4.Cu")
		(net "M_J_CPU1_SA_DQ<19>")
	)
	(segment
		(start 131.360672 -236.118908)
		(end 131.383024 -236.035596)
		(width 0.0889)
		(layer "In4.Cu")
		(net "M_J_CPU1_SA_DQ<19>")
	)
	(segment
		(start 155.494482 -223.893634)
		(end 155.656026 -223.73209)
		(width 0.14478)
		(layer "In4.Cu")
		(net "M_J_CPU1_SA_DQ<19>")
	)
	(segment
		(start 154.625294 -228.046026)
		(end 154.625294 -225.651314)
		(width 0.14478)
		(layer "In4.Cu")
		(net "M_J_CPU1_SA_DQ<19>")
	)
	(segment
		(start 147.51685 -233.962194)
		(end 147.828254 -233.962194)
		(width 0.0889)
		(layer "In4.Cu")
		(net "M_J_CPU1_SA_DQ<19>")
	)
	(segment
		(start 155.319984 -224.728024)
		(end 155.548584 -224.728024)
		(width 0.14478)
		(layer "In4.Cu")
		(net "M_J_CPU1_SA_DQ<19>")
	)
	(segment
		(start 156.490416 -223.557592)
		(end 156.27477 -223.341946)
		(width 0.14478)
		(layer "In4.Cu")
		(net "M_J_CPU1_SA_DQ<19>")
	)
	(segment
		(start 155.656026 -223.73209)
		(end 155.884626 -223.73209)
		(width 0.14478)
		(layer "In4.Cu")
		(net "M_J_CPU1_SA_DQ<19>")
	)
	(segment
		(start 143.547592 -236.061758)
		(end 143.555974 -236.056932)
		(width 0.0889)
		(layer "In4.Cu")
		(net "M_J_CPU1_SA_DQ<19>")
	)
	(segment
		(start 155.494482 -224.122234)
		(end 155.494482 -223.893634)
		(width 0.14478)
		(layer "In4.Cu")
		(net "M_J_CPU1_SA_DQ<19>")
	)
	(segment
		(start 155.710128 -224.33788)
		(end 155.494482 -224.122234)
		(width 0.14478)
		(layer "In4.Cu")
		(net "M_J_CPU1_SA_DQ<19>")
	)
	(segment
		(start 156.100272 -223.947736)
		(end 156.328872 -223.947736)
		(width 0.14478)
		(layer "In4.Cu")
		(net "M_J_CPU1_SA_DQ<19>")
	)
	(segment
		(start 131.693412 -236.056932)
		(end 131.701794 -236.061758)
		(width 0.0889)
		(layer "In4.Cu")
		(net "M_J_CPU1_SA_DQ<19>")
	)
	(segment
		(start 156.436314 -222.951802)
		(end 156.664914 -222.951802)
		(width 0.14478)
		(layer "In4.Cu")
		(net "M_J_CPU1_SA_DQ<19>")
	)
	(segment
		(start 161.266124 -219.010484)
		(end 166.065708 -219.010484)
		(width 0.14478)
		(layer "In4.Cu")
		(net "M_J_CPU1_SA_DQ<19>")
	)
	(segment
		(start 156.88056 -223.167448)
		(end 157.10916 -223.167448)
		(width 0.14478)
		(layer "In4.Cu")
		(net "M_J_CPU1_SA_DQ<19>")
	)
	(segment
		(start 154.875738 -224.512378)
		(end 155.104338 -224.512378)
		(width 0.14478)
		(layer "In4.Cu")
		(net "M_J_CPU1_SA_DQ<19>")
	)
	(segment
		(start 141.093444 -236.056932)
		(end 141.101826 -236.061758)
		(width 0.0889)
		(layer "In4.Cu")
		(net "M_J_CPU1_SA_DQ<19>")
	)
	(segment
		(start 178.974496 -219.000832)
		(end 181.125622 -219.000832)
		(width 0.14478)
		(layer "In4.Cu")
		(net "M_J_CPU1_SA_DQ<19>")
	)
	(segment
		(start 156.27477 -223.341946)
		(end 156.27477 -223.113346)
		(width 0.14478)
		(layer "In4.Cu")
		(net "M_J_CPU1_SA_DQ<19>")
	)
	(segment
		(start 135.453374 -236.056932)
		(end 135.461756 -236.061758)
		(width 0.0889)
		(layer "In4.Cu")
		(net "M_J_CPU1_SA_DQ<19>")
	)
	(segment
		(start 132.267706 -236.061758)
		(end 132.276088 -236.056932)
		(width 0.0889)
		(layer "In4.Cu")
		(net "M_J_CPU1_SA_DQ<19>")
	)
	(segment
		(start 156.27477 -223.113346)
		(end 156.436314 -222.951802)
		(width 0.14478)
		(layer "In4.Cu")
		(net "M_J_CPU1_SA_DQ<19>")
	)
	(segment
		(start 166.915846 -218.160346)
		(end 170.199812 -218.160346)
		(width 0.14478)
		(layer "In4.Cu")
		(net "M_J_CPU1_SA_DQ<19>")
	)
	(segment
		(start 147.828254 -233.962194)
		(end 148.709126 -233.962194)
		(width 0.14478)
		(layer "In4.Cu")
		(net "M_J_CPU1_SA_DQ<19>")
	)
	(segment
		(start 154.714194 -224.673922)
		(end 154.875738 -224.512378)
		(width 0.14478)
		(layer "In4.Cu")
		(net "M_J_CPU1_SA_DQ<19>")
	)
	(segment
		(start 156.328872 -223.947736)
		(end 156.490416 -223.786192)
		(width 0.14478)
		(layer "In4.Cu")
		(net "M_J_CPU1_SA_DQ<19>")
	)
	(segment
		(start 155.710128 -224.56648)
		(end 155.710128 -224.33788)
		(width 0.14478)
		(layer "In4.Cu")
		(net "M_J_CPU1_SA_DQ<19>")
	)
	(segment
		(start 140.15339 -236.056932)
		(end 140.161772 -236.061758)
		(width 0.0889)
		(layer "In4.Cu")
		(net "M_J_CPU1_SA_DQ<19>")
	)
	(segment
		(start 170.199812 -218.160346)
		(end 171.040044 -219.000578)
		(width 0.14478)
		(layer "In4.Cu")
		(net "M_J_CPU1_SA_DQ<19>")
	)
	(segment
		(start 148.709126 -233.962194)
		(end 154.625294 -228.046026)
		(width 0.14478)
		(layer "In4.Cu")
		(net "M_J_CPU1_SA_DQ<19>")
	)
	(segment
		(start 181.125622 -219.000832)
		(end 181.97576 -218.150694)
		(width 0.14478)
		(layer "In4.Cu")
		(net "M_J_CPU1_SA_DQ<19>")
	)
	(segment
		(start 157.055058 -222.333058)
		(end 157.216602 -222.171514)
		(width 0.14478)
		(layer "In4.Cu")
		(net "M_J_CPU1_SA_DQ<19>")
	)
	(segment
		(start 136.967722 -236.061758)
		(end 136.976104 -236.056932)
		(width 0.0889)
		(layer "In4.Cu")
		(net "M_J_CPU1_SA_DQ<19>")
	)
	(segment
		(start 146.357848 -234.865672)
		(end 146.645376 -234.578144)
		(width 0.0889)
		(layer "In4.Cu")
		(net "M_J_CPU1_SA_DQ<19>")
	)
	(segment
		(start 154.714194 -224.902522)
		(end 154.714194 -224.673922)
		(width 0.14478)
		(layer "In4.Cu")
		(net "M_J_CPU1_SA_DQ<19>")
	)
	(segment
		(start 156.490416 -223.786192)
		(end 156.490416 -223.557592)
		(width 0.14478)
		(layer "In4.Cu")
		(net "M_J_CPU1_SA_DQ<19>")
	)
	(segment
		(start 156.664914 -222.951802)
		(end 156.88056 -223.167448)
		(width 0.14478)
		(layer "In4.Cu")
		(net "M_J_CPU1_SA_DQ<19>")
	)
	(segment
		(start 136.393428 -236.056932)
		(end 136.40181 -236.061758)
		(width 0.0889)
		(layer "In4.Cu")
		(net "M_J_CPU1_SA_DQ<19>")
	)
	(segment
		(start 146.9009 -234.578144)
		(end 147.51685 -233.962194)
		(width 0.0889)
		(layer "In4.Cu")
		(net "M_J_CPU1_SA_DQ<19>")
	)
	(segment
		(start 157.270704 -223.005904)
		(end 157.270704 -222.777304)
		(width 0.14478)
		(layer "In4.Cu")
		(net "M_J_CPU1_SA_DQ<19>")
	)
	(segment
		(start 157.216602 -222.171514)
		(end 157.445202 -222.171514)
		(width 0.14478)
		(layer "In4.Cu")
		(net "M_J_CPU1_SA_DQ<19>")
	)
	(segment
		(start 157.270704 -222.777304)
		(end 157.055058 -222.561658)
		(width 0.14478)
		(layer "In4.Cu")
		(net "M_J_CPU1_SA_DQ<19>")
	)
	(segment
		(start 186.625484 -218.150694)
		(end 187.060078 -218.585288)
		(width 0.14478)
		(layer "In4.Cu")
		(net "M_J_CPU1_SA_DQ<19>")
	)
	(segment
		(start 146.645376 -234.578144)
		(end 146.9009 -234.578144)
		(width 0.0889)
		(layer "In4.Cu")
		(net "M_J_CPU1_SA_DQ<19>")
	)
	(segment
		(start 157.660848 -222.38716)
		(end 157.889448 -222.38716)
		(width 0.14478)
		(layer "In4.Cu")
		(net "M_J_CPU1_SA_DQ<19>")
	)
	(segment
		(start 171.040044 -219.000578)
		(end 173.406308 -219.000578)
		(width 0.14478)
		(layer "In4.Cu")
		(net "M_J_CPU1_SA_DQ<19>")
	)
	(segment
		(start 166.065708 -219.010484)
		(end 166.915846 -218.160346)
		(width 0.14478)
		(layer "In4.Cu")
		(net "M_J_CPU1_SA_DQ<19>")
	)
	(segment
		(start 173.406308 -219.000578)
		(end 174.256192 -218.150694)
		(width 0.14478)
		(layer "In4.Cu")
		(net "M_J_CPU1_SA_DQ<19>")
	)
	(segment
		(start 181.97576 -218.150694)
		(end 186.625484 -218.150694)
		(width 0.14478)
		(layer "In4.Cu")
		(net "M_J_CPU1_SA_DQ<19>")
	)
	(segment
		(start 155.884626 -223.73209)
		(end 156.100272 -223.947736)
		(width 0.14478)
		(layer "In4.Cu")
		(net "M_J_CPU1_SA_DQ<19>")
	)
	(segment
		(start 145.430748 -236.138212)
		(end 146.357848 -235.211112)
		(width 0.0889)
		(layer "In4.Cu")
		(net "M_J_CPU1_SA_DQ<19>")
	)
	(segment
		(start 154.92984 -225.118168)
		(end 154.714194 -224.902522)
		(width 0.14478)
		(layer "In4.Cu")
		(net "M_J_CPU1_SA_DQ<19>")
	)
	(segment
		(start 154.92984 -225.346768)
		(end 154.92984 -225.118168)
		(width 0.14478)
		(layer "In4.Cu")
		(net "M_J_CPU1_SA_DQ<19>")
	)
	(segment
		(start 131.51485 -236.384338)
		(end 131.360672 -236.118908)
		(width 0.0889)
		(layer "In4.Cu")
		(net "M_J_CPU1_SA_DQ<19>")
	)
	(segment
		(start 155.548584 -224.728024)
		(end 155.710128 -224.56648)
		(width 0.14478)
		(layer "In4.Cu")
		(net "M_J_CPU1_SA_DQ<19>")
	)
	(segment
		(start 157.055058 -222.561658)
		(end 157.055058 -222.333058)
		(width 0.14478)
		(layer "In4.Cu")
		(net "M_J_CPU1_SA_DQ<19>")
	)
	(segment
		(start 137.907776 -236.061758)
		(end 137.916158 -236.056932)
		(width 0.0889)
		(layer "In4.Cu")
		(net "M_J_CPU1_SA_DQ<19>")
	)
	(arc
		(start 142.04188 -236.061758)
		(mid 142.324836 -236.137935)
		(end 142.607792 -236.061758)
		(width 0.0889)
		(layer "In4.Cu")
		(net "M_J_CPU1_SA_DQ<19>")
	)
	(arc
		(start 132.641848 -236.061758)
		(mid 132.924804 -236.137935)
		(end 133.20776 -236.061758)
		(width 0.0889)
		(layer "In4.Cu")
		(net "M_J_CPU1_SA_DQ<19>")
	)
	(arc
		(start 143.555974 -236.056932)
		(mid 143.739736 -236.011316)
		(end 143.922242 -236.061758)
		(width 0.0889)
		(layer "In4.Cu")
		(net "M_J_CPU1_SA_DQ<19>")
	)
	(arc
		(start 133.216142 -236.056932)
		(mid 133.39965 -236.011438)
		(end 133.581902 -236.061758)
		(width 0.0889)
		(layer "In4.Cu")
		(net "M_J_CPU1_SA_DQ<19>")
	)
	(arc
		(start 131.701794 -236.061758)
		(mid 131.98475 -236.137935)
		(end 132.267706 -236.061758)
		(width 0.0889)
		(layer "In4.Cu")
		(net "M_J_CPU1_SA_DQ<19>")
	)
	(arc
		(start 134.147814 -236.061758)
		(mid 134.334758 -236.011503)
		(end 134.521702 -236.061758)
		(width 0.0889)
		(layer "In4.Cu")
		(net "M_J_CPU1_SA_DQ<19>")
	)
	(arc
		(start 139.221718 -236.061758)
		(mid 139.504674 -236.137935)
		(end 139.78763 -236.061758)
		(width 0.0889)
		(layer "In4.Cu")
		(net "M_J_CPU1_SA_DQ<19>")
	)
	(arc
		(start 141.67612 -236.056932)
		(mid 141.859628 -236.011438)
		(end 142.04188 -236.061758)
		(width 0.0889)
		(layer "In4.Cu")
		(net "M_J_CPU1_SA_DQ<19>")
	)
	(arc
		(start 133.581902 -236.061758)
		(mid 133.864858 -236.137935)
		(end 134.147814 -236.061758)
		(width 0.0889)
		(layer "In4.Cu")
		(net "M_J_CPU1_SA_DQ<19>")
	)
	(arc
		(start 137.341864 -236.061758)
		(mid 137.62482 -236.137935)
		(end 137.907776 -236.061758)
		(width 0.0889)
		(layer "In4.Cu")
		(net "M_J_CPU1_SA_DQ<19>")
	)
	(arc
		(start 131.383024 -236.035596)
		(mid 131.540534 -236.012398)
		(end 131.693412 -236.056932)
		(width 0.0889)
		(layer "In4.Cu")
		(net "M_J_CPU1_SA_DQ<19>")
	)
	(arc
		(start 142.607792 -236.061758)
		(mid 142.794736 -236.011503)
		(end 142.98168 -236.061758)
		(width 0.0889)
		(layer "In4.Cu")
		(net "M_J_CPU1_SA_DQ<19>")
	)
	(arc
		(start 136.40181 -236.061758)
		(mid 136.684766 -236.137935)
		(end 136.967722 -236.061758)
		(width 0.0889)
		(layer "In4.Cu")
		(net "M_J_CPU1_SA_DQ<19>")
	)
	(arc
		(start 141.101826 -236.061758)
		(mid 141.384782 -236.137935)
		(end 141.667738 -236.061758)
		(width 0.0889)
		(layer "In4.Cu")
		(net "M_J_CPU1_SA_DQ<19>")
	)
	(arc
		(start 132.276088 -236.056932)
		(mid 132.459596 -236.011438)
		(end 132.641848 -236.061758)
		(width 0.0889)
		(layer "In4.Cu")
		(net "M_J_CPU1_SA_DQ<19>")
	)
	(arc
		(start 135.461756 -236.061758)
		(mid 135.744712 -236.137935)
		(end 136.027668 -236.061758)
		(width 0.0889)
		(layer "In4.Cu")
		(net "M_J_CPU1_SA_DQ<19>")
	)
	(arc
		(start 135.087614 -236.061758)
		(mid 135.269865 -236.011408)
		(end 135.453374 -236.056932)
		(width 0.0889)
		(layer "In4.Cu")
		(net "M_J_CPU1_SA_DQ<19>")
	)
	(arc
		(start 136.027668 -236.061758)
		(mid 136.209919 -236.011408)
		(end 136.393428 -236.056932)
		(width 0.0889)
		(layer "In4.Cu")
		(net "M_J_CPU1_SA_DQ<19>")
	)
	(arc
		(start 140.727684 -236.061758)
		(mid 140.909935 -236.011408)
		(end 141.093444 -236.056932)
		(width 0.0889)
		(layer "In4.Cu")
		(net "M_J_CPU1_SA_DQ<19>")
	)
	(arc
		(start 139.78763 -236.061758)
		(mid 139.969881 -236.011408)
		(end 140.15339 -236.056932)
		(width 0.0889)
		(layer "In4.Cu")
		(net "M_J_CPU1_SA_DQ<19>")
	)
	(arc
		(start 142.98168 -236.061758)
		(mid 143.264636 -236.137935)
		(end 143.547592 -236.061758)
		(width 0.0889)
		(layer "In4.Cu")
		(net "M_J_CPU1_SA_DQ<19>")
	)
	(arc
		(start 138.84783 -236.061758)
		(mid 139.034774 -236.011503)
		(end 139.221718 -236.061758)
		(width 0.0889)
		(layer "In4.Cu")
		(net "M_J_CPU1_SA_DQ<19>")
	)
	(arc
		(start 138.281918 -236.061758)
		(mid 138.564874 -236.137935)
		(end 138.84783 -236.061758)
		(width 0.0889)
		(layer "In4.Cu")
		(net "M_J_CPU1_SA_DQ<19>")
	)
	(arc
		(start 134.521702 -236.061758)
		(mid 134.804658 -236.137935)
		(end 135.087614 -236.061758)
		(width 0.0889)
		(layer "In4.Cu")
		(net "M_J_CPU1_SA_DQ<19>")
	)
	(arc
		(start 143.922242 -236.061758)
		(mid 144.059035 -236.11878)
		(end 144.20596 -236.138212)
		(width 0.0889)
		(layer "In4.Cu")
		(net "M_J_CPU1_SA_DQ<19>")
	)
	(arc
		(start 140.161772 -236.061758)
		(mid 140.444728 -236.137935)
		(end 140.727684 -236.061758)
		(width 0.0889)
		(layer "In4.Cu")
		(net "M_J_CPU1_SA_DQ<19>")
	)
	(arc
		(start 137.916158 -236.056932)
		(mid 138.099666 -236.011438)
		(end 138.281918 -236.061758)
		(width 0.0889)
		(layer "In4.Cu")
		(net "M_J_CPU1_SA_DQ<19>")
	)
	(arc
		(start 136.976104 -236.056932)
		(mid 137.159612 -236.011438)
		(end 137.341864 -236.061758)
		(width 0.0889)
		(layer "In4.Cu")
		(net "M_J_CPU1_SA_DQ<19>")
	)
	(segment
		(start 132.457952 -235.84027)
		(end 132.924804 -235.574332)
		(width 0.10668)
		(layer "F.Cu")
		(net "M_J_CPU1_SA_DQ<18>")
	)
	(segment
		(start 158.296356 -220.45168)
		(end 158.524956 -220.45168)
		(width 0.14478)
		(layer "In4.Cu")
		(net "M_J_CPU1_SA_DQ<18>")
	)
	(segment
		(start 161.526474 -217.683842)
		(end 161.688018 -217.845386)
		(width 0.14478)
		(layer "In4.Cu")
		(net "M_J_CPU1_SA_DQ<18>")
	)
	(segment
		(start 146.60372 -234.057444)
		(end 147.61083 -233.050334)
		(width 0.0889)
		(layer "In4.Cu")
		(net "M_J_CPU1_SA_DQ<18>")
	)
	(segment
		(start 157.516068 -221.231968)
		(end 157.744668 -221.231968)
		(width 0.14478)
		(layer "In4.Cu")
		(net "M_J_CPU1_SA_DQ<18>")
	)
	(segment
		(start 160.0454 -218.299284)
		(end 160.0454 -218.070684)
		(width 0.14478)
		(layer "In4.Cu")
		(net "M_J_CPU1_SA_DQ<18>")
	)
	(segment
		(start 186.635136 -216.460324)
		(end 187.060078 -216.885266)
		(width 0.14478)
		(layer "In4.Cu")
		(net "M_J_CPU1_SA_DQ<18>")
	)
	(segment
		(start 157.314392 -221.030292)
		(end 157.516068 -221.231968)
		(width 0.14478)
		(layer "In4.Cu")
		(net "M_J_CPU1_SA_DQ<18>")
	)
	(segment
		(start 159.655256 -218.689428)
		(end 159.856932 -218.891104)
		(width 0.14478)
		(layer "In4.Cu")
		(net "M_J_CPU1_SA_DQ<18>")
	)
	(segment
		(start 146.159728 -234.057444)
		(end 146.60372 -234.057444)
		(width 0.0889)
		(layer "In4.Cu")
		(net "M_J_CPU1_SA_DQ<18>")
	)
	(segment
		(start 166.299388 -217.310462)
		(end 167.149526 -216.460324)
		(width 0.14478)
		(layer "In4.Cu")
		(net "M_J_CPU1_SA_DQ<18>")
	)
	(segment
		(start 159.426656 -218.689428)
		(end 159.655256 -218.689428)
		(width 0.14478)
		(layer "In4.Cu")
		(net "M_J_CPU1_SA_DQ<18>")
	)
	(segment
		(start 169.942256 -216.460324)
		(end 170.792394 -217.310462)
		(width 0.14478)
		(layer "In4.Cu")
		(net "M_J_CPU1_SA_DQ<18>")
	)
	(segment
		(start 174.490888 -216.460324)
		(end 177.92192 -216.460324)
		(width 0.14478)
		(layer "In4.Cu")
		(net "M_J_CPU1_SA_DQ<18>")
	)
	(segment
		(start 157.906212 -221.070424)
		(end 157.906212 -220.841824)
		(width 0.14478)
		(layer "In4.Cu")
		(net "M_J_CPU1_SA_DQ<18>")
	)
	(segment
		(start 162.467798 -217.310462)
		(end 162.629342 -217.472006)
		(width 0.14478)
		(layer "In4.Cu")
		(net "M_J_CPU1_SA_DQ<18>")
	)
	(segment
		(start 143.955262 -235.28782)
		(end 144.942814 -234.890564)
		(width 0.0889)
		(layer "In4.Cu")
		(net "M_J_CPU1_SA_DQ<18>")
	)
	(segment
		(start 134.04342 -235.246926)
		(end 134.051802 -235.251752)
		(width 0.0889)
		(layer "In4.Cu")
		(net "M_J_CPU1_SA_DQ<18>")
	)
	(segment
		(start 135.557768 -235.251752)
		(end 135.56615 -235.246926)
		(width 0.0889)
		(layer "In4.Cu")
		(net "M_J_CPU1_SA_DQ<18>")
	)
	(segment
		(start 157.906212 -220.841824)
		(end 157.704536 -220.640148)
		(width 0.14478)
		(layer "In4.Cu")
		(net "M_J_CPU1_SA_DQ<18>")
	)
	(segment
		(start 170.792394 -217.310462)
		(end 173.64075 -217.310462)
		(width 0.14478)
		(layer "In4.Cu")
		(net "M_J_CPU1_SA_DQ<18>")
	)
	(segment
		(start 162.629342 -217.472006)
		(end 162.629342 -217.683842)
		(width 0.14478)
		(layer "In4.Cu")
		(net "M_J_CPU1_SA_DQ<18>")
	)
	(segment
		(start 160.085532 -218.891104)
		(end 160.247076 -218.72956)
		(width 0.14478)
		(layer "In4.Cu")
		(net "M_J_CPU1_SA_DQ<18>")
	)
	(segment
		(start 158.09468 -220.250004)
		(end 158.296356 -220.45168)
		(width 0.14478)
		(layer "In4.Cu")
		(net "M_J_CPU1_SA_DQ<18>")
	)
	(segment
		(start 159.466788 -219.509848)
		(end 159.466788 -219.281248)
		(width 0.14478)
		(layer "In4.Cu")
		(net "M_J_CPU1_SA_DQ<18>")
	)
	(segment
		(start 157.744668 -221.231968)
		(end 157.906212 -221.070424)
		(width 0.14478)
		(layer "In4.Cu")
		(net "M_J_CPU1_SA_DQ<18>")
	)
	(segment
		(start 159.466788 -219.281248)
		(end 159.265112 -219.079572)
		(width 0.14478)
		(layer "In4.Cu")
		(net "M_J_CPU1_SA_DQ<18>")
	)
	(segment
		(start 159.856932 -218.891104)
		(end 160.085532 -218.891104)
		(width 0.14478)
		(layer "In4.Cu")
		(net "M_J_CPU1_SA_DQ<18>")
	)
	(segment
		(start 162.239452 -217.310462)
		(end 162.467798 -217.310462)
		(width 0.14478)
		(layer "In4.Cu")
		(net "M_J_CPU1_SA_DQ<18>")
	)
	(segment
		(start 161.916364 -217.845386)
		(end 162.077908 -217.683842)
		(width 0.14478)
		(layer "In4.Cu")
		(net "M_J_CPU1_SA_DQ<18>")
	)
	(segment
		(start 157.704536 -220.411548)
		(end 157.86608 -220.250004)
		(width 0.14478)
		(layer "In4.Cu")
		(net "M_J_CPU1_SA_DQ<18>")
	)
	(segment
		(start 134.617714 -235.251752)
		(end 134.626096 -235.246926)
		(width 0.0889)
		(layer "In4.Cu")
		(net "M_J_CPU1_SA_DQ<18>")
	)
	(segment
		(start 157.085792 -221.030292)
		(end 157.314392 -221.030292)
		(width 0.14478)
		(layer "In4.Cu")
		(net "M_J_CPU1_SA_DQ<18>")
	)
	(segment
		(start 158.646368 -219.469716)
		(end 158.874968 -219.469716)
		(width 0.14478)
		(layer "In4.Cu")
		(net "M_J_CPU1_SA_DQ<18>")
	)
	(segment
		(start 163.019232 -217.845386)
		(end 163.180776 -217.683842)
		(width 0.14478)
		(layer "In4.Cu")
		(net "M_J_CPU1_SA_DQ<18>")
	)
	(segment
		(start 158.484824 -219.63126)
		(end 158.646368 -219.469716)
		(width 0.14478)
		(layer "In4.Cu")
		(net "M_J_CPU1_SA_DQ<18>")
	)
	(segment
		(start 158.874968 -219.469716)
		(end 159.076644 -219.671392)
		(width 0.14478)
		(layer "In4.Cu")
		(net "M_J_CPU1_SA_DQ<18>")
	)
	(segment
		(start 178.772058 -217.310462)
		(end 181.0639 -217.310462)
		(width 0.14478)
		(layer "In4.Cu")
		(net "M_J_CPU1_SA_DQ<18>")
	)
	(segment
		(start 159.265112 -218.850972)
		(end 159.426656 -218.689428)
		(width 0.14478)
		(layer "In4.Cu")
		(net "M_J_CPU1_SA_DQ<18>")
	)
	(segment
		(start 160.805622 -217.310462)
		(end 161.36493 -217.310462)
		(width 0.14478)
		(layer "In4.Cu")
		(net "M_J_CPU1_SA_DQ<18>")
	)
	(segment
		(start 158.484824 -219.85986)
		(end 158.484824 -219.63126)
		(width 0.14478)
		(layer "In4.Cu")
		(net "M_J_CPU1_SA_DQ<18>")
	)
	(segment
		(start 132.770626 -235.308902)
		(end 132.792978 -235.22559)
		(width 0.0889)
		(layer "In4.Cu")
		(net "M_J_CPU1_SA_DQ<18>")
	)
	(segment
		(start 137.803382 -235.246926)
		(end 137.811764 -235.251752)
		(width 0.0889)
		(layer "In4.Cu")
		(net "M_J_CPU1_SA_DQ<18>")
	)
	(segment
		(start 143.077692 -235.251752)
		(end 143.086074 -235.246926)
		(width 0.0889)
		(layer "In4.Cu")
		(net "M_J_CPU1_SA_DQ<18>")
	)
	(segment
		(start 157.704536 -220.640148)
		(end 157.704536 -220.411548)
		(width 0.14478)
		(layer "In4.Cu")
		(net "M_J_CPU1_SA_DQ<18>")
	)
	(segment
		(start 161.688018 -217.845386)
		(end 161.916364 -217.845386)
		(width 0.14478)
		(layer "In4.Cu")
		(net "M_J_CPU1_SA_DQ<18>")
	)
	(segment
		(start 159.265112 -219.079572)
		(end 159.265112 -218.850972)
		(width 0.14478)
		(layer "In4.Cu")
		(net "M_J_CPU1_SA_DQ<18>")
	)
	(segment
		(start 181.914038 -216.460324)
		(end 186.635136 -216.460324)
		(width 0.14478)
		(layer "In4.Cu")
		(net "M_J_CPU1_SA_DQ<18>")
	)
	(segment
		(start 157.86608 -220.250004)
		(end 158.09468 -220.250004)
		(width 0.14478)
		(layer "In4.Cu")
		(net "M_J_CPU1_SA_DQ<18>")
	)
	(segment
		(start 167.149526 -216.460324)
		(end 169.942256 -216.460324)
		(width 0.14478)
		(layer "In4.Cu")
		(net "M_J_CPU1_SA_DQ<18>")
	)
	(segment
		(start 163.180776 -217.683842)
		(end 163.180776 -217.472006)
		(width 0.14478)
		(layer "In4.Cu")
		(net "M_J_CPU1_SA_DQ<18>")
	)
	(segment
		(start 162.629342 -217.683842)
		(end 162.790886 -217.845386)
		(width 0.14478)
		(layer "In4.Cu")
		(net "M_J_CPU1_SA_DQ<18>")
	)
	(segment
		(start 142.503398 -235.246926)
		(end 142.51178 -235.251752)
		(width 0.0889)
		(layer "In4.Cu")
		(net "M_J_CPU1_SA_DQ<18>")
	)
	(segment
		(start 163.34232 -217.310462)
		(end 166.299388 -217.310462)
		(width 0.14478)
		(layer "In4.Cu")
		(net "M_J_CPU1_SA_DQ<18>")
	)
	(segment
		(start 153.726134 -224.38995)
		(end 157.085792 -221.030292)
		(width 0.14478)
		(layer "In4.Cu")
		(net "M_J_CPU1_SA_DQ<18>")
	)
	(segment
		(start 140.257784 -235.251752)
		(end 140.266166 -235.246926)
		(width 0.0889)
		(layer "In4.Cu")
		(net "M_J_CPU1_SA_DQ<18>")
	)
	(segment
		(start 158.524956 -220.45168)
		(end 158.6865 -220.290136)
		(width 0.14478)
		(layer "In4.Cu")
		(net "M_J_CPU1_SA_DQ<18>")
	)
	(segment
		(start 138.743436 -235.246926)
		(end 138.751818 -235.251752)
		(width 0.0889)
		(layer "In4.Cu")
		(net "M_J_CPU1_SA_DQ<18>")
	)
	(segment
		(start 181.0639 -217.310462)
		(end 181.914038 -216.460324)
		(width 0.14478)
		(layer "In4.Cu")
		(net "M_J_CPU1_SA_DQ<18>")
	)
	(segment
		(start 147.61083 -233.050334)
		(end 147.842224 -233.050334)
		(width 0.0889)
		(layer "In4.Cu")
		(net "M_J_CPU1_SA_DQ<18>")
	)
	(segment
		(start 162.790886 -217.845386)
		(end 163.019232 -217.845386)
		(width 0.14478)
		(layer "In4.Cu")
		(net "M_J_CPU1_SA_DQ<18>")
	)
	(segment
		(start 159.305244 -219.671392)
		(end 159.466788 -219.509848)
		(width 0.14478)
		(layer "In4.Cu")
		(net "M_J_CPU1_SA_DQ<18>")
	)
	(segment
		(start 163.180776 -217.472006)
		(end 163.34232 -217.310462)
		(width 0.14478)
		(layer "In4.Cu")
		(net "M_J_CPU1_SA_DQ<18>")
	)
	(segment
		(start 161.36493 -217.310462)
		(end 161.526474 -217.472006)
		(width 0.14478)
		(layer "In4.Cu")
		(net "M_J_CPU1_SA_DQ<18>")
	)
	(segment
		(start 160.0454 -218.070684)
		(end 160.805622 -217.310462)
		(width 0.14478)
		(layer "In4.Cu")
		(net "M_J_CPU1_SA_DQ<18>")
	)
	(segment
		(start 160.247076 -218.72956)
		(end 160.247076 -218.50096)
		(width 0.14478)
		(layer "In4.Cu")
		(net "M_J_CPU1_SA_DQ<18>")
	)
	(segment
		(start 147.842224 -233.050334)
		(end 148.33473 -233.050334)
		(width 0.14478)
		(layer "In4.Cu")
		(net "M_J_CPU1_SA_DQ<18>")
	)
	(segment
		(start 133.103366 -235.246926)
		(end 133.111748 -235.251752)
		(width 0.0889)
		(layer "In4.Cu")
		(net "M_J_CPU1_SA_DQ<18>")
	)
	(segment
		(start 143.451834 -235.251752)
		(end 143.462248 -235.257848)
		(width 0.0889)
		(layer "In4.Cu")
		(net "M_J_CPU1_SA_DQ<18>")
	)
	(segment
		(start 148.33473 -233.050334)
		(end 153.726134 -227.65893)
		(width 0.14478)
		(layer "In4.Cu")
		(net "M_J_CPU1_SA_DQ<18>")
	)
	(segment
		(start 158.6865 -220.061536)
		(end 158.484824 -219.85986)
		(width 0.14478)
		(layer "In4.Cu")
		(net "M_J_CPU1_SA_DQ<18>")
	)
	(segment
		(start 160.247076 -218.50096)
		(end 160.0454 -218.299284)
		(width 0.14478)
		(layer "In4.Cu")
		(net "M_J_CPU1_SA_DQ<18>")
	)
	(segment
		(start 173.64075 -217.310462)
		(end 174.490888 -216.460324)
		(width 0.14478)
		(layer "In4.Cu")
		(net "M_J_CPU1_SA_DQ<18>")
	)
	(segment
		(start 161.526474 -217.472006)
		(end 161.526474 -217.683842)
		(width 0.14478)
		(layer "In4.Cu")
		(net "M_J_CPU1_SA_DQ<18>")
	)
	(segment
		(start 153.726134 -227.65893)
		(end 153.726134 -224.38995)
		(width 0.14478)
		(layer "In4.Cu")
		(net "M_J_CPU1_SA_DQ<18>")
	)
	(segment
		(start 162.077908 -217.472006)
		(end 162.239452 -217.310462)
		(width 0.14478)
		(layer "In4.Cu")
		(net "M_J_CPU1_SA_DQ<18>")
	)
	(segment
		(start 144.942814 -234.890564)
		(end 145.326608 -234.890564)
		(width 0.0889)
		(layer "In4.Cu")
		(net "M_J_CPU1_SA_DQ<18>")
	)
	(segment
		(start 159.076644 -219.671392)
		(end 159.305244 -219.671392)
		(width 0.14478)
		(layer "In4.Cu")
		(net "M_J_CPU1_SA_DQ<18>")
	)
	(segment
		(start 162.077908 -217.683842)
		(end 162.077908 -217.472006)
		(width 0.14478)
		(layer "In4.Cu")
		(net "M_J_CPU1_SA_DQ<18>")
	)
	(segment
		(start 132.924804 -235.574332)
		(end 132.770626 -235.308902)
		(width 0.0889)
		(layer "In4.Cu")
		(net "M_J_CPU1_SA_DQ<18>")
	)
	(segment
		(start 177.92192 -216.460324)
		(end 178.772058 -217.310462)
		(width 0.14478)
		(layer "In4.Cu")
		(net "M_J_CPU1_SA_DQ<18>")
	)
	(segment
		(start 139.31773 -235.251752)
		(end 139.326112 -235.246926)
		(width 0.0889)
		(layer "In4.Cu")
		(net "M_J_CPU1_SA_DQ<18>")
	)
	(segment
		(start 145.326608 -234.890564)
		(end 146.159728 -234.057444)
		(width 0.0889)
		(layer "In4.Cu")
		(net "M_J_CPU1_SA_DQ<18>")
	)
	(segment
		(start 158.6865 -220.290136)
		(end 158.6865 -220.061536)
		(width 0.14478)
		(layer "In4.Cu")
		(net "M_J_CPU1_SA_DQ<18>")
	)
	(arc
		(start 142.137638 -235.251752)
		(mid 142.319889 -235.201402)
		(end 142.503398 -235.246926)
		(width 0.0889)
		(layer "In4.Cu")
		(net "M_J_CPU1_SA_DQ<18>")
	)
	(arc
		(start 133.67766 -235.251752)
		(mid 133.859911 -235.201402)
		(end 134.04342 -235.246926)
		(width 0.0889)
		(layer "In4.Cu")
		(net "M_J_CPU1_SA_DQ<18>")
	)
	(arc
		(start 135.56615 -235.246926)
		(mid 135.749658 -235.201432)
		(end 135.93191 -235.251752)
		(width 0.0889)
		(layer "In4.Cu")
		(net "M_J_CPU1_SA_DQ<18>")
	)
	(arc
		(start 137.811764 -235.251752)
		(mid 138.09472 -235.327929)
		(end 138.377676 -235.251752)
		(width 0.0889)
		(layer "In4.Cu")
		(net "M_J_CPU1_SA_DQ<18>")
	)
	(arc
		(start 139.326112 -235.246926)
		(mid 139.50962 -235.201432)
		(end 139.691872 -235.251752)
		(width 0.0889)
		(layer "In4.Cu")
		(net "M_J_CPU1_SA_DQ<18>")
	)
	(arc
		(start 135.93191 -235.251752)
		(mid 136.214866 -235.327929)
		(end 136.497822 -235.251752)
		(width 0.0889)
		(layer "In4.Cu")
		(net "M_J_CPU1_SA_DQ<18>")
	)
	(arc
		(start 136.497822 -235.251752)
		(mid 136.684766 -235.201497)
		(end 136.87171 -235.251752)
		(width 0.0889)
		(layer "In4.Cu")
		(net "M_J_CPU1_SA_DQ<18>")
	)
	(arc
		(start 142.51178 -235.251752)
		(mid 142.794736 -235.327929)
		(end 143.077692 -235.251752)
		(width 0.0889)
		(layer "In4.Cu")
		(net "M_J_CPU1_SA_DQ<18>")
	)
	(arc
		(start 140.631926 -235.251752)
		(mid 140.914882 -235.327929)
		(end 141.197838 -235.251752)
		(width 0.0889)
		(layer "In4.Cu")
		(net "M_J_CPU1_SA_DQ<18>")
	)
	(arc
		(start 138.377676 -235.251752)
		(mid 138.559927 -235.201402)
		(end 138.743436 -235.246926)
		(width 0.0889)
		(layer "In4.Cu")
		(net "M_J_CPU1_SA_DQ<18>")
	)
	(arc
		(start 133.111748 -235.251752)
		(mid 133.394704 -235.327929)
		(end 133.67766 -235.251752)
		(width 0.0889)
		(layer "In4.Cu")
		(net "M_J_CPU1_SA_DQ<18>")
	)
	(arc
		(start 143.462248 -235.257848)
		(mid 143.705381 -235.328472)
		(end 143.955262 -235.28782)
		(width 0.0889)
		(layer "In4.Cu")
		(net "M_J_CPU1_SA_DQ<18>")
	)
	(arc
		(start 137.437622 -235.251752)
		(mid 137.619873 -235.201402)
		(end 137.803382 -235.246926)
		(width 0.0889)
		(layer "In4.Cu")
		(net "M_J_CPU1_SA_DQ<18>")
	)
	(arc
		(start 143.086074 -235.246926)
		(mid 143.269582 -235.201432)
		(end 143.451834 -235.251752)
		(width 0.0889)
		(layer "In4.Cu")
		(net "M_J_CPU1_SA_DQ<18>")
	)
	(arc
		(start 134.991856 -235.251752)
		(mid 135.274812 -235.327929)
		(end 135.557768 -235.251752)
		(width 0.0889)
		(layer "In4.Cu")
		(net "M_J_CPU1_SA_DQ<18>")
	)
	(arc
		(start 136.87171 -235.251752)
		(mid 137.154666 -235.327929)
		(end 137.437622 -235.251752)
		(width 0.0889)
		(layer "In4.Cu")
		(net "M_J_CPU1_SA_DQ<18>")
	)
	(arc
		(start 139.691872 -235.251752)
		(mid 139.974828 -235.327929)
		(end 140.257784 -235.251752)
		(width 0.0889)
		(layer "In4.Cu")
		(net "M_J_CPU1_SA_DQ<18>")
	)
	(arc
		(start 134.051802 -235.251752)
		(mid 134.334758 -235.327929)
		(end 134.617714 -235.251752)
		(width 0.0889)
		(layer "In4.Cu")
		(net "M_J_CPU1_SA_DQ<18>")
	)
	(arc
		(start 132.792978 -235.22559)
		(mid 132.950488 -235.202392)
		(end 133.103366 -235.246926)
		(width 0.0889)
		(layer "In4.Cu")
		(net "M_J_CPU1_SA_DQ<18>")
	)
	(arc
		(start 138.751818 -235.251752)
		(mid 139.034774 -235.327929)
		(end 139.31773 -235.251752)
		(width 0.0889)
		(layer "In4.Cu")
		(net "M_J_CPU1_SA_DQ<18>")
	)
	(arc
		(start 141.571726 -235.251752)
		(mid 141.854682 -235.327929)
		(end 142.137638 -235.251752)
		(width 0.0889)
		(layer "In4.Cu")
		(net "M_J_CPU1_SA_DQ<18>")
	)
	(arc
		(start 134.626096 -235.246926)
		(mid 134.809604 -235.201432)
		(end 134.991856 -235.251752)
		(width 0.0889)
		(layer "In4.Cu")
		(net "M_J_CPU1_SA_DQ<18>")
	)
	(arc
		(start 141.197838 -235.251752)
		(mid 141.384782 -235.201497)
		(end 141.571726 -235.251752)
		(width 0.0889)
		(layer "In4.Cu")
		(net "M_J_CPU1_SA_DQ<18>")
	)
	(arc
		(start 140.266166 -235.246926)
		(mid 140.449674 -235.201432)
		(end 140.631926 -235.251752)
		(width 0.0889)
		(layer "In4.Cu")
		(net "M_J_CPU1_SA_DQ<18>")
	)
	(segment
		(start 130.577844 -235.84027)
		(end 131.044696 -235.574332)
		(width 0.10668)
		(layer "F.Cu")
		(net "M_J_CPU1_SA_DQ<17>")
	)
	(segment
		(start 139.31773 -235.896912)
		(end 139.326112 -235.901738)
		(width 0.0889)
		(layer "In4.Cu")
		(net "M_J_CPU1_SA_DQ<17>")
	)
	(segment
		(start 161.345626 -218.294966)
		(end 165.185344 -218.294966)
		(width 0.14478)
		(layer "In4.Cu")
		(net "M_J_CPU1_SA_DQ<17>")
	)
	(segment
		(start 148.523198 -233.504994)
		(end 154.175714 -227.852478)
		(width 0.14478)
		(layer "In4.Cu")
		(net "M_J_CPU1_SA_DQ<17>")
	)
	(segment
		(start 172.891958 -218.160346)
		(end 174.94377 -217.310462)
		(width 0.14478)
		(layer "In4.Cu")
		(net "M_J_CPU1_SA_DQ<17>")
	)
	(segment
		(start 131.044696 -235.574332)
		(end 131.198874 -235.839762)
		(width 0.0889)
		(layer "In4.Cu")
		(net "M_J_CPU1_SA_DQ<17>")
	)
	(segment
		(start 134.04342 -235.901738)
		(end 134.051802 -235.896912)
		(width 0.0889)
		(layer "In4.Cu")
		(net "M_J_CPU1_SA_DQ<17>")
	)
	(segment
		(start 146.154648 -235.126784)
		(end 146.154648 -234.641644)
		(width 0.0889)
		(layer "In4.Cu")
		(net "M_J_CPU1_SA_DQ<17>")
	)
	(segment
		(start 179.429918 -218.160346)
		(end 180.601874 -218.160346)
		(width 0.14478)
		(layer "In4.Cu")
		(net "M_J_CPU1_SA_DQ<17>")
	)
	(segment
		(start 167.562022 -217.310462)
		(end 169.516044 -217.310462)
		(width 0.14478)
		(layer "In4.Cu")
		(net "M_J_CPU1_SA_DQ<17>")
	)
	(segment
		(start 131.198874 -235.839762)
		(end 131.29514 -235.865162)
		(width 0.0889)
		(layer "In4.Cu")
		(net "M_J_CPU1_SA_DQ<17>")
	)
	(segment
		(start 180.601874 -218.160346)
		(end 182.653432 -217.310462)
		(width 0.14478)
		(layer "In4.Cu")
		(net "M_J_CPU1_SA_DQ<17>")
	)
	(segment
		(start 157.030166 -221.721934)
		(end 157.918658 -221.721934)
		(width 0.14478)
		(layer "In4.Cu")
		(net "M_J_CPU1_SA_DQ<17>")
	)
	(segment
		(start 147.842224 -233.504994)
		(end 148.523198 -233.504994)
		(width 0.14478)
		(layer "In4.Cu")
		(net "M_J_CPU1_SA_DQ<17>")
	)
	(segment
		(start 177.378106 -217.310462)
		(end 179.429918 -218.160346)
		(width 0.14478)
		(layer "In4.Cu")
		(net "M_J_CPU1_SA_DQ<17>")
	)
	(segment
		(start 146.454368 -234.341924)
		(end 146.699732 -234.341924)
		(width 0.0889)
		(layer "In4.Cu")
		(net "M_J_CPU1_SA_DQ<17>")
	)
	(segment
		(start 174.94377 -217.310462)
		(end 177.378106 -217.310462)
		(width 0.14478)
		(layer "In4.Cu")
		(net "M_J_CPU1_SA_DQ<17>")
	)
	(segment
		(start 144.205706 -235.947712)
		(end 145.33372 -235.947712)
		(width 0.0889)
		(layer "In4.Cu")
		(net "M_J_CPU1_SA_DQ<17>")
	)
	(segment
		(start 143.451834 -235.896912)
		(end 143.466566 -235.888276)
		(width 0.0889)
		(layer "In4.Cu")
		(net "M_J_CPU1_SA_DQ<17>")
	)
	(segment
		(start 134.617714 -235.896912)
		(end 134.626096 -235.901738)
		(width 0.0889)
		(layer "In4.Cu")
		(net "M_J_CPU1_SA_DQ<17>")
	)
	(segment
		(start 138.743436 -235.901738)
		(end 138.751818 -235.896912)
		(width 0.0889)
		(layer "In4.Cu")
		(net "M_J_CPU1_SA_DQ<17>")
	)
	(segment
		(start 146.699732 -234.341924)
		(end 147.536662 -233.504994)
		(width 0.0889)
		(layer "In4.Cu")
		(net "M_J_CPU1_SA_DQ<17>")
	)
	(segment
		(start 143.077692 -235.896912)
		(end 143.086074 -235.901738)
		(width 0.0889)
		(layer "In4.Cu")
		(net "M_J_CPU1_SA_DQ<17>")
	)
	(segment
		(start 169.516044 -217.310462)
		(end 171.567856 -218.160346)
		(width 0.14478)
		(layer "In4.Cu")
		(net "M_J_CPU1_SA_DQ<17>")
	)
	(segment
		(start 140.257784 -235.896912)
		(end 140.266166 -235.901738)
		(width 0.0889)
		(layer "In4.Cu")
		(net "M_J_CPU1_SA_DQ<17>")
	)
	(segment
		(start 165.185344 -218.294966)
		(end 167.562022 -217.310462)
		(width 0.14478)
		(layer "In4.Cu")
		(net "M_J_CPU1_SA_DQ<17>")
	)
	(segment
		(start 146.154648 -234.641644)
		(end 146.454368 -234.341924)
		(width 0.0889)
		(layer "In4.Cu")
		(net "M_J_CPU1_SA_DQ<17>")
	)
	(segment
		(start 135.557768 -235.896912)
		(end 135.56615 -235.901738)
		(width 0.0889)
		(layer "In4.Cu")
		(net "M_J_CPU1_SA_DQ<17>")
	)
	(segment
		(start 171.567856 -218.160346)
		(end 172.891958 -218.160346)
		(width 0.14478)
		(layer "In4.Cu")
		(net "M_J_CPU1_SA_DQ<17>")
	)
	(segment
		(start 157.918658 -221.721934)
		(end 161.345626 -218.294966)
		(width 0.14478)
		(layer "In4.Cu")
		(net "M_J_CPU1_SA_DQ<17>")
	)
	(segment
		(start 137.803382 -235.901738)
		(end 137.811764 -235.896912)
		(width 0.0889)
		(layer "In4.Cu")
		(net "M_J_CPU1_SA_DQ<17>")
	)
	(segment
		(start 154.175714 -227.852478)
		(end 154.175714 -224.576386)
		(width 0.14478)
		(layer "In4.Cu")
		(net "M_J_CPU1_SA_DQ<17>")
	)
	(segment
		(start 189.023752 -217.310462)
		(end 191.160146 -217.735404)
		(width 0.14478)
		(layer "In4.Cu")
		(net "M_J_CPU1_SA_DQ<17>")
	)
	(segment
		(start 182.653432 -217.310462)
		(end 189.023752 -217.310462)
		(width 0.14478)
		(layer "In4.Cu")
		(net "M_J_CPU1_SA_DQ<17>")
	)
	(segment
		(start 133.103366 -235.901738)
		(end 133.111748 -235.896912)
		(width 0.0889)
		(layer "In4.Cu")
		(net "M_J_CPU1_SA_DQ<17>")
	)
	(segment
		(start 154.175714 -224.576386)
		(end 157.030166 -221.721934)
		(width 0.14478)
		(layer "In4.Cu")
		(net "M_J_CPU1_SA_DQ<17>")
	)
	(segment
		(start 145.33372 -235.947712)
		(end 146.154648 -235.126784)
		(width 0.0889)
		(layer "In4.Cu")
		(net "M_J_CPU1_SA_DQ<17>")
	)
	(segment
		(start 144.018254 -235.896912)
		(end 144.018 -235.896912)
		(width 0.0889)
		(layer "In4.Cu")
		(net "M_J_CPU1_SA_DQ<17>")
	)
	(segment
		(start 147.536662 -233.504994)
		(end 147.842224 -233.504994)
		(width 0.0889)
		(layer "In4.Cu")
		(net "M_J_CPU1_SA_DQ<17>")
	)
	(segment
		(start 142.503398 -235.901738)
		(end 142.51178 -235.896912)
		(width 0.0889)
		(layer "In4.Cu")
		(net "M_J_CPU1_SA_DQ<17>")
	)
	(arc
		(start 137.811764 -235.896912)
		(mid 138.09472 -235.820735)
		(end 138.377676 -235.896912)
		(width 0.0889)
		(layer "In4.Cu")
		(net "M_J_CPU1_SA_DQ<17>")
	)
	(arc
		(start 133.67766 -235.896912)
		(mid 133.859911 -235.947262)
		(end 134.04342 -235.901738)
		(width 0.0889)
		(layer "In4.Cu")
		(net "M_J_CPU1_SA_DQ<17>")
	)
	(arc
		(start 134.991856 -235.896912)
		(mid 135.274812 -235.820735)
		(end 135.557768 -235.896912)
		(width 0.0889)
		(layer "In4.Cu")
		(net "M_J_CPU1_SA_DQ<17>")
	)
	(arc
		(start 140.631926 -235.896912)
		(mid 140.914882 -235.820735)
		(end 141.197838 -235.896912)
		(width 0.0889)
		(layer "In4.Cu")
		(net "M_J_CPU1_SA_DQ<17>")
	)
	(arc
		(start 139.691872 -235.896912)
		(mid 139.974828 -235.820735)
		(end 140.257784 -235.896912)
		(width 0.0889)
		(layer "In4.Cu")
		(net "M_J_CPU1_SA_DQ<17>")
	)
	(arc
		(start 138.377676 -235.896912)
		(mid 138.559927 -235.947262)
		(end 138.743436 -235.901738)
		(width 0.0889)
		(layer "In4.Cu")
		(net "M_J_CPU1_SA_DQ<17>")
	)
	(arc
		(start 135.93191 -235.896912)
		(mid 136.214866 -235.820735)
		(end 136.497822 -235.896912)
		(width 0.0889)
		(layer "In4.Cu")
		(net "M_J_CPU1_SA_DQ<17>")
	)
	(arc
		(start 140.266166 -235.901738)
		(mid 140.449674 -235.947232)
		(end 140.631926 -235.896912)
		(width 0.0889)
		(layer "In4.Cu")
		(net "M_J_CPU1_SA_DQ<17>")
	)
	(arc
		(start 141.571726 -235.896912)
		(mid 141.854682 -235.820735)
		(end 142.137638 -235.896912)
		(width 0.0889)
		(layer "In4.Cu")
		(net "M_J_CPU1_SA_DQ<17>")
	)
	(arc
		(start 143.466566 -235.888276)
		(mid 143.743549 -235.820472)
		(end 144.018254 -235.896912)
		(width 0.0889)
		(layer "In4.Cu")
		(net "M_J_CPU1_SA_DQ<17>")
	)
	(arc
		(start 144.018 -235.896912)
		(mid 144.10849 -235.93473)
		(end 144.205706 -235.947712)
		(width 0.0889)
		(layer "In4.Cu")
		(net "M_J_CPU1_SA_DQ<17>")
	)
	(arc
		(start 142.137638 -235.896912)
		(mid 142.319889 -235.947262)
		(end 142.503398 -235.901738)
		(width 0.0889)
		(layer "In4.Cu")
		(net "M_J_CPU1_SA_DQ<17>")
	)
	(arc
		(start 136.497822 -235.896912)
		(mid 136.684766 -235.947167)
		(end 136.87171 -235.896912)
		(width 0.0889)
		(layer "In4.Cu")
		(net "M_J_CPU1_SA_DQ<17>")
	)
	(arc
		(start 143.086074 -235.901738)
		(mid 143.269582 -235.947232)
		(end 143.451834 -235.896912)
		(width 0.0889)
		(layer "In4.Cu")
		(net "M_J_CPU1_SA_DQ<17>")
	)
	(arc
		(start 139.326112 -235.901738)
		(mid 139.50962 -235.947232)
		(end 139.691872 -235.896912)
		(width 0.0889)
		(layer "In4.Cu")
		(net "M_J_CPU1_SA_DQ<17>")
	)
	(arc
		(start 133.111748 -235.896912)
		(mid 133.394704 -235.820735)
		(end 133.67766 -235.896912)
		(width 0.0889)
		(layer "In4.Cu")
		(net "M_J_CPU1_SA_DQ<17>")
	)
	(arc
		(start 132.737606 -235.896912)
		(mid 132.919857 -235.947262)
		(end 133.103366 -235.901738)
		(width 0.0889)
		(layer "In4.Cu")
		(net "M_J_CPU1_SA_DQ<17>")
	)
	(arc
		(start 131.797806 -235.896912)
		(mid 131.98475 -235.947167)
		(end 132.171694 -235.896912)
		(width 0.0889)
		(layer "In4.Cu")
		(net "M_J_CPU1_SA_DQ<17>")
	)
	(arc
		(start 136.87171 -235.896912)
		(mid 137.154666 -235.820735)
		(end 137.437622 -235.896912)
		(width 0.0889)
		(layer "In4.Cu")
		(net "M_J_CPU1_SA_DQ<17>")
	)
	(arc
		(start 131.29514 -235.865162)
		(mid 131.550205 -235.821811)
		(end 131.797806 -235.896912)
		(width 0.0889)
		(layer "In4.Cu")
		(net "M_J_CPU1_SA_DQ<17>")
	)
	(arc
		(start 137.437622 -235.896912)
		(mid 137.619873 -235.947262)
		(end 137.803382 -235.901738)
		(width 0.0889)
		(layer "In4.Cu")
		(net "M_J_CPU1_SA_DQ<17>")
	)
	(arc
		(start 135.56615 -235.901738)
		(mid 135.749658 -235.947232)
		(end 135.93191 -235.896912)
		(width 0.0889)
		(layer "In4.Cu")
		(net "M_J_CPU1_SA_DQ<17>")
	)
	(arc
		(start 141.197838 -235.896912)
		(mid 141.384782 -235.947167)
		(end 141.571726 -235.896912)
		(width 0.0889)
		(layer "In4.Cu")
		(net "M_J_CPU1_SA_DQ<17>")
	)
	(arc
		(start 134.626096 -235.901738)
		(mid 134.809604 -235.947232)
		(end 134.991856 -235.896912)
		(width 0.0889)
		(layer "In4.Cu")
		(net "M_J_CPU1_SA_DQ<17>")
	)
	(arc
		(start 142.51178 -235.896912)
		(mid 142.794736 -235.820735)
		(end 143.077692 -235.896912)
		(width 0.0889)
		(layer "In4.Cu")
		(net "M_J_CPU1_SA_DQ<17>")
	)
	(arc
		(start 138.751818 -235.896912)
		(mid 139.034774 -235.820735)
		(end 139.31773 -235.896912)
		(width 0.0889)
		(layer "In4.Cu")
		(net "M_J_CPU1_SA_DQ<17>")
	)
	(arc
		(start 132.171694 -235.896912)
		(mid 132.45465 -235.820735)
		(end 132.737606 -235.896912)
		(width 0.0889)
		(layer "In4.Cu")
		(net "M_J_CPU1_SA_DQ<17>")
	)
	(arc
		(start 134.051802 -235.896912)
		(mid 134.334758 -235.820735)
		(end 134.617714 -235.896912)
		(width 0.0889)
		(layer "In4.Cu")
		(net "M_J_CPU1_SA_DQ<17>")
	)
	(segment
		(start 131.987798 -235.030264)
		(end 132.45465 -234.764326)
		(width 0.10668)
		(layer "F.Cu")
		(net "M_J_CPU1_SA_DQ<16>")
	)
	(segment
		(start 170.626786 -216.460324)
		(end 173.684946 -216.460324)
		(width 0.14478)
		(layer "In4.Cu")
		(net "M_J_CPU1_SA_DQ<16>")
	)
	(segment
		(start 180.662072 -216.460324)
		(end 182.713884 -215.61044)
		(width 0.14478)
		(layer "In4.Cu")
		(net "M_J_CPU1_SA_DQ<16>")
	)
	(segment
		(start 169.776902 -215.61044)
		(end 170.626786 -216.460324)
		(width 0.14478)
		(layer "In4.Cu")
		(net "M_J_CPU1_SA_DQ<16>")
	)
	(segment
		(start 140.15339 -235.091732)
		(end 140.161772 -235.086906)
		(width 0.0889)
		(layer "In4.Cu")
		(net "M_J_CPU1_SA_DQ<16>")
	)
	(segment
		(start 146.373088 -233.422444)
		(end 146.373088 -233.277156)
		(width 0.0889)
		(layer "In4.Cu")
		(net "M_J_CPU1_SA_DQ<16>")
	)
	(segment
		(start 153.276554 -227.371402)
		(end 153.276554 -224.203514)
		(width 0.14478)
		(layer "In4.Cu")
		(net "M_J_CPU1_SA_DQ<16>")
	)
	(segment
		(start 161.019744 -216.460324)
		(end 166.17442 -216.460324)
		(width 0.14478)
		(layer "In4.Cu")
		(net "M_J_CPU1_SA_DQ<16>")
	)
	(segment
		(start 177.751994 -215.61044)
		(end 178.601878 -216.460324)
		(width 0.14478)
		(layer "In4.Cu")
		(net "M_J_CPU1_SA_DQ<16>")
	)
	(segment
		(start 135.453374 -235.091732)
		(end 135.461756 -235.086906)
		(width 0.0889)
		(layer "In4.Cu")
		(net "M_J_CPU1_SA_DQ<16>")
	)
	(segment
		(start 167.024304 -215.61044)
		(end 169.776902 -215.61044)
		(width 0.14478)
		(layer "In4.Cu")
		(net "M_J_CPU1_SA_DQ<16>")
	)
	(segment
		(start 166.17442 -216.460324)
		(end 167.024304 -215.61044)
		(width 0.14478)
		(layer "In4.Cu")
		(net "M_J_CPU1_SA_DQ<16>")
	)
	(segment
		(start 141.667738 -235.086906)
		(end 141.67612 -235.091732)
		(width 0.0889)
		(layer "In4.Cu")
		(net "M_J_CPU1_SA_DQ<16>")
	)
	(segment
		(start 143.547592 -235.086906)
		(end 143.555974 -235.091732)
		(width 0.0889)
		(layer "In4.Cu")
		(net "M_J_CPU1_SA_DQ<16>")
	)
	(segment
		(start 143.922242 -235.086906)
		(end 144.830546 -234.616244)
		(width 0.0889)
		(layer "In4.Cu")
		(net "M_J_CPU1_SA_DQ<16>")
	)
	(segment
		(start 132.45465 -234.764326)
		(end 132.608828 -235.029756)
		(width 0.0889)
		(layer "In4.Cu")
		(net "M_J_CPU1_SA_DQ<16>")
	)
	(segment
		(start 133.20776 -235.086906)
		(end 133.216142 -235.091732)
		(width 0.0889)
		(layer "In4.Cu")
		(net "M_J_CPU1_SA_DQ<16>")
	)
	(segment
		(start 132.608828 -235.029756)
		(end 132.705094 -235.055156)
		(width 0.0889)
		(layer "In4.Cu")
		(net "M_J_CPU1_SA_DQ<16>")
	)
	(segment
		(start 189.023752 -215.61044)
		(end 191.160146 -216.035382)
		(width 0.14478)
		(layer "In4.Cu")
		(net "M_J_CPU1_SA_DQ<16>")
	)
	(segment
		(start 136.967722 -235.086906)
		(end 136.976104 -235.091732)
		(width 0.0889)
		(layer "In4.Cu")
		(net "M_J_CPU1_SA_DQ<16>")
	)
	(segment
		(start 136.393428 -235.091732)
		(end 136.40181 -235.086906)
		(width 0.0889)
		(layer "In4.Cu")
		(net "M_J_CPU1_SA_DQ<16>")
	)
	(segment
		(start 137.907776 -235.086906)
		(end 137.916158 -235.091732)
		(width 0.0889)
		(layer "In4.Cu")
		(net "M_J_CPU1_SA_DQ<16>")
	)
	(segment
		(start 148.073872 -232.574084)
		(end 153.276554 -227.371402)
		(width 0.14478)
		(layer "In4.Cu")
		(net "M_J_CPU1_SA_DQ<16>")
	)
	(segment
		(start 145.179288 -234.616244)
		(end 146.373088 -233.422444)
		(width 0.0889)
		(layer "In4.Cu")
		(net "M_J_CPU1_SA_DQ<16>")
	)
	(segment
		(start 147.07616 -232.574084)
		(end 147.94611 -232.574084)
		(width 0.0889)
		(layer "In4.Cu")
		(net "M_J_CPU1_SA_DQ<16>")
	)
	(segment
		(start 173.684946 -216.460324)
		(end 174.53483 -215.61044)
		(width 0.14478)
		(layer "In4.Cu")
		(net "M_J_CPU1_SA_DQ<16>")
	)
	(segment
		(start 147.94611 -232.574084)
		(end 148.073872 -232.574084)
		(width 0.14478)
		(layer "In4.Cu")
		(net "M_J_CPU1_SA_DQ<16>")
	)
	(segment
		(start 144.830546 -234.616244)
		(end 145.179288 -234.616244)
		(width 0.0889)
		(layer "In4.Cu")
		(net "M_J_CPU1_SA_DQ<16>")
	)
	(segment
		(start 174.53483 -215.61044)
		(end 177.751994 -215.61044)
		(width 0.14478)
		(layer "In4.Cu")
		(net "M_J_CPU1_SA_DQ<16>")
	)
	(segment
		(start 153.276554 -224.203514)
		(end 161.019744 -216.460324)
		(width 0.14478)
		(layer "In4.Cu")
		(net "M_J_CPU1_SA_DQ<16>")
	)
	(segment
		(start 178.601878 -216.460324)
		(end 180.662072 -216.460324)
		(width 0.14478)
		(layer "In4.Cu")
		(net "M_J_CPU1_SA_DQ<16>")
	)
	(segment
		(start 182.713884 -215.61044)
		(end 189.023752 -215.61044)
		(width 0.14478)
		(layer "In4.Cu")
		(net "M_J_CPU1_SA_DQ<16>")
	)
	(segment
		(start 146.373088 -233.277156)
		(end 147.07616 -232.574084)
		(width 0.0889)
		(layer "In4.Cu")
		(net "M_J_CPU1_SA_DQ<16>")
	)
	(segment
		(start 141.093444 -235.091732)
		(end 141.101826 -235.086906)
		(width 0.0889)
		(layer "In4.Cu")
		(net "M_J_CPU1_SA_DQ<16>")
	)
	(arc
		(start 143.555974 -235.091732)
		(mid 143.739736 -235.137348)
		(end 143.922242 -235.086906)
		(width 0.0889)
		(layer "In4.Cu")
		(net "M_J_CPU1_SA_DQ<16>")
	)
	(arc
		(start 139.221718 -235.086906)
		(mid 139.504674 -235.010729)
		(end 139.78763 -235.086906)
		(width 0.0889)
		(layer "In4.Cu")
		(net "M_J_CPU1_SA_DQ<16>")
	)
	(arc
		(start 134.521702 -235.086906)
		(mid 134.804658 -235.010729)
		(end 135.087614 -235.086906)
		(width 0.0889)
		(layer "In4.Cu")
		(net "M_J_CPU1_SA_DQ<16>")
	)
	(arc
		(start 141.101826 -235.086906)
		(mid 141.384782 -235.010729)
		(end 141.667738 -235.086906)
		(width 0.0889)
		(layer "In4.Cu")
		(net "M_J_CPU1_SA_DQ<16>")
	)
	(arc
		(start 140.161772 -235.086906)
		(mid 140.444728 -235.010729)
		(end 140.727684 -235.086906)
		(width 0.0889)
		(layer "In4.Cu")
		(net "M_J_CPU1_SA_DQ<16>")
	)
	(arc
		(start 142.04188 -235.086906)
		(mid 142.324836 -235.010729)
		(end 142.607792 -235.086906)
		(width 0.0889)
		(layer "In4.Cu")
		(net "M_J_CPU1_SA_DQ<16>")
	)
	(arc
		(start 139.78763 -235.086906)
		(mid 139.969881 -235.137256)
		(end 140.15339 -235.091732)
		(width 0.0889)
		(layer "In4.Cu")
		(net "M_J_CPU1_SA_DQ<16>")
	)
	(arc
		(start 133.581902 -235.086906)
		(mid 133.864858 -235.010729)
		(end 134.147814 -235.086906)
		(width 0.0889)
		(layer "In4.Cu")
		(net "M_J_CPU1_SA_DQ<16>")
	)
	(arc
		(start 134.147814 -235.086906)
		(mid 134.334758 -235.137161)
		(end 134.521702 -235.086906)
		(width 0.0889)
		(layer "In4.Cu")
		(net "M_J_CPU1_SA_DQ<16>")
	)
	(arc
		(start 136.027668 -235.086906)
		(mid 136.209919 -235.137256)
		(end 136.393428 -235.091732)
		(width 0.0889)
		(layer "In4.Cu")
		(net "M_J_CPU1_SA_DQ<16>")
	)
	(arc
		(start 140.727684 -235.086906)
		(mid 140.909935 -235.137256)
		(end 141.093444 -235.091732)
		(width 0.0889)
		(layer "In4.Cu")
		(net "M_J_CPU1_SA_DQ<16>")
	)
	(arc
		(start 136.976104 -235.091732)
		(mid 137.159612 -235.137226)
		(end 137.341864 -235.086906)
		(width 0.0889)
		(layer "In4.Cu")
		(net "M_J_CPU1_SA_DQ<16>")
	)
	(arc
		(start 138.281918 -235.086906)
		(mid 138.564874 -235.010729)
		(end 138.84783 -235.086906)
		(width 0.0889)
		(layer "In4.Cu")
		(net "M_J_CPU1_SA_DQ<16>")
	)
	(arc
		(start 132.705094 -235.055156)
		(mid 132.960159 -235.011805)
		(end 133.20776 -235.086906)
		(width 0.0889)
		(layer "In4.Cu")
		(net "M_J_CPU1_SA_DQ<16>")
	)
	(arc
		(start 136.40181 -235.086906)
		(mid 136.684766 -235.010729)
		(end 136.967722 -235.086906)
		(width 0.0889)
		(layer "In4.Cu")
		(net "M_J_CPU1_SA_DQ<16>")
	)
	(arc
		(start 142.98168 -235.086906)
		(mid 143.264636 -235.010729)
		(end 143.547592 -235.086906)
		(width 0.0889)
		(layer "In4.Cu")
		(net "M_J_CPU1_SA_DQ<16>")
	)
	(arc
		(start 135.087614 -235.086906)
		(mid 135.269865 -235.137256)
		(end 135.453374 -235.091732)
		(width 0.0889)
		(layer "In4.Cu")
		(net "M_J_CPU1_SA_DQ<16>")
	)
	(arc
		(start 137.341864 -235.086906)
		(mid 137.62482 -235.010729)
		(end 137.907776 -235.086906)
		(width 0.0889)
		(layer "In4.Cu")
		(net "M_J_CPU1_SA_DQ<16>")
	)
	(arc
		(start 142.607792 -235.086906)
		(mid 142.794736 -235.137161)
		(end 142.98168 -235.086906)
		(width 0.0889)
		(layer "In4.Cu")
		(net "M_J_CPU1_SA_DQ<16>")
	)
	(arc
		(start 137.916158 -235.091732)
		(mid 138.099666 -235.137226)
		(end 138.281918 -235.086906)
		(width 0.0889)
		(layer "In4.Cu")
		(net "M_J_CPU1_SA_DQ<16>")
	)
	(arc
		(start 141.67612 -235.091732)
		(mid 141.859628 -235.137226)
		(end 142.04188 -235.086906)
		(width 0.0889)
		(layer "In4.Cu")
		(net "M_J_CPU1_SA_DQ<16>")
	)
	(arc
		(start 138.84783 -235.086906)
		(mid 139.034774 -235.137161)
		(end 139.221718 -235.086906)
		(width 0.0889)
		(layer "In4.Cu")
		(net "M_J_CPU1_SA_DQ<16>")
	)
	(arc
		(start 133.216142 -235.091732)
		(mid 133.39965 -235.137226)
		(end 133.581902 -235.086906)
		(width 0.0889)
		(layer "In4.Cu")
		(net "M_J_CPU1_SA_DQ<16>")
	)
	(arc
		(start 135.461756 -235.086906)
		(mid 135.744712 -235.010729)
		(end 136.027668 -235.086906)
		(width 0.0889)
		(layer "In4.Cu")
		(net "M_J_CPU1_SA_DQ<16>")
	)
	(segment
		(start 131.047998 -235.030264)
		(end 131.51485 -234.764326)
		(width 0.10668)
		(layer "F.Cu")
		(net "M_J_CPU1_SA_DQ<15>")
	)
	(segment
		(start 145.762726 -233.595164)
		(end 147.337526 -232.020364)
		(width 0.0889)
		(layer "In4.Cu")
		(net "M_J_CPU1_SA_DQ<15>")
	)
	(segment
		(start 153.783792 -222.00997)
		(end 154.012392 -222.00997)
		(width 0.14478)
		(layer "In4.Cu")
		(net "M_J_CPU1_SA_DQ<15>")
	)
	(segment
		(start 152.84196 -222.951802)
		(end 153.003504 -222.790258)
		(width 0.14478)
		(layer "In4.Cu")
		(net "M_J_CPU1_SA_DQ<15>")
	)
	(segment
		(start 177.743358 -214.760302)
		(end 178.593496 -215.61044)
		(width 0.14478)
		(layer "In4.Cu")
		(net "M_J_CPU1_SA_DQ<15>")
	)
	(segment
		(start 153.232104 -222.790258)
		(end 153.456894 -223.015048)
		(width 0.14478)
		(layer "In4.Cu")
		(net "M_J_CPU1_SA_DQ<15>")
	)
	(segment
		(start 136.967722 -234.441746)
		(end 136.976104 -234.43692)
		(width 0.0889)
		(layer "In4.Cu")
		(net "M_J_CPU1_SA_DQ<15>")
	)
	(segment
		(start 131.693412 -234.43692)
		(end 131.701794 -234.441746)
		(width 0.0889)
		(layer "In4.Cu")
		(net "M_J_CPU1_SA_DQ<15>")
	)
	(segment
		(start 143.73479 -234.391454)
		(end 144.195038 -234.391454)
		(width 0.0889)
		(layer "In4.Cu")
		(net "M_J_CPU1_SA_DQ<15>")
	)
	(segment
		(start 154.627326 -221.844616)
		(end 154.402536 -221.619826)
		(width 0.14478)
		(layer "In4.Cu")
		(net "M_J_CPU1_SA_DQ<15>")
	)
	(segment
		(start 147.337526 -232.020364)
		(end 147.761706 -232.020364)
		(width 0.0889)
		(layer "In4.Cu")
		(net "M_J_CPU1_SA_DQ<15>")
	)
	(segment
		(start 155.344368 -220.449394)
		(end 155.572968 -220.449394)
		(width 0.14478)
		(layer "In4.Cu")
		(net "M_J_CPU1_SA_DQ<15>")
	)
	(segment
		(start 153.06675 -223.405192)
		(end 152.84196 -223.180402)
		(width 0.14478)
		(layer "In4.Cu")
		(net "M_J_CPU1_SA_DQ<15>")
	)
	(segment
		(start 131.360672 -234.498896)
		(end 131.383024 -234.415584)
		(width 0.0889)
		(layer "In4.Cu")
		(net "M_J_CPU1_SA_DQ<15>")
	)
	(segment
		(start 132.267706 -234.441746)
		(end 132.276088 -234.43692)
		(width 0.0889)
		(layer "In4.Cu")
		(net "M_J_CPU1_SA_DQ<15>")
	)
	(segment
		(start 156.187902 -220.28404)
		(end 155.963112 -220.05925)
		(width 0.14478)
		(layer "In4.Cu")
		(net "M_J_CPU1_SA_DQ<15>")
	)
	(segment
		(start 141.667738 -234.441746)
		(end 141.67612 -234.43692)
		(width 0.0889)
		(layer "In4.Cu")
		(net "M_J_CPU1_SA_DQ<15>")
	)
	(segment
		(start 153.003504 -222.790258)
		(end 153.232104 -222.790258)
		(width 0.14478)
		(layer "In4.Cu")
		(net "M_J_CPU1_SA_DQ<15>")
	)
	(segment
		(start 155.182824 -220.839538)
		(end 155.182824 -220.610938)
		(width 0.14478)
		(layer "In4.Cu")
		(net "M_J_CPU1_SA_DQ<15>")
	)
	(segment
		(start 155.407614 -221.292928)
		(end 155.407614 -221.064328)
		(width 0.14478)
		(layer "In4.Cu")
		(net "M_J_CPU1_SA_DQ<15>")
	)
	(segment
		(start 135.453374 -234.43692)
		(end 135.461756 -234.441746)
		(width 0.0889)
		(layer "In4.Cu")
		(net "M_J_CPU1_SA_DQ<15>")
	)
	(segment
		(start 154.012392 -222.00997)
		(end 154.237182 -222.23476)
		(width 0.14478)
		(layer "In4.Cu")
		(net "M_J_CPU1_SA_DQ<15>")
	)
	(segment
		(start 184.490106 -214.760302)
		(end 184.793382 -214.457026)
		(width 0.14478)
		(layer "In4.Cu")
		(net "M_J_CPU1_SA_DQ<15>")
	)
	(segment
		(start 144.991328 -233.595164)
		(end 145.762726 -233.595164)
		(width 0.0889)
		(layer "In4.Cu")
		(net "M_J_CPU1_SA_DQ<15>")
	)
	(segment
		(start 154.627326 -222.073216)
		(end 154.627326 -221.844616)
		(width 0.14478)
		(layer "In4.Cu")
		(net "M_J_CPU1_SA_DQ<15>")
	)
	(segment
		(start 153.685494 -223.015048)
		(end 153.847038 -222.853504)
		(width 0.14478)
		(layer "In4.Cu")
		(net "M_J_CPU1_SA_DQ<15>")
	)
	(segment
		(start 185.592974 -214.760302)
		(end 185.89625 -214.457026)
		(width 0.14478)
		(layer "In4.Cu")
		(net "M_J_CPU1_SA_DQ<15>")
	)
	(segment
		(start 155.963112 -220.05925)
		(end 155.963112 -219.83065)
		(width 0.14478)
		(layer "In4.Cu")
		(net "M_J_CPU1_SA_DQ<15>")
	)
	(segment
		(start 144.195038 -234.391454)
		(end 144.991328 -233.595164)
		(width 0.0889)
		(layer "In4.Cu")
		(net "M_J_CPU1_SA_DQ<15>")
	)
	(segment
		(start 155.407614 -221.064328)
		(end 155.182824 -220.839538)
		(width 0.14478)
		(layer "In4.Cu")
		(net "M_J_CPU1_SA_DQ<15>")
	)
	(segment
		(start 166.065708 -215.61044)
		(end 166.915846 -214.760302)
		(width 0.14478)
		(layer "In4.Cu")
		(net "M_J_CPU1_SA_DQ<15>")
	)
	(segment
		(start 169.7609 -214.760302)
		(end 170.611038 -215.61044)
		(width 0.14478)
		(layer "In4.Cu")
		(net "M_J_CPU1_SA_DQ<15>")
	)
	(segment
		(start 155.01747 -221.454472)
		(end 155.24607 -221.454472)
		(width 0.14478)
		(layer "In4.Cu")
		(net "M_J_CPU1_SA_DQ<15>")
	)
	(segment
		(start 185.89625 -214.457026)
		(end 186.144408 -214.457026)
		(width 0.14478)
		(layer "In4.Cu")
		(net "M_J_CPU1_SA_DQ<15>")
	)
	(segment
		(start 186.447684 -214.760302)
		(end 186.635136 -214.760302)
		(width 0.14478)
		(layer "In4.Cu")
		(net "M_J_CPU1_SA_DQ<15>")
	)
	(segment
		(start 156.026358 -220.674184)
		(end 156.187902 -220.51264)
		(width 0.14478)
		(layer "In4.Cu")
		(net "M_J_CPU1_SA_DQ<15>")
	)
	(segment
		(start 184.793382 -214.457026)
		(end 185.04154 -214.457026)
		(width 0.14478)
		(layer "In4.Cu")
		(net "M_J_CPU1_SA_DQ<15>")
	)
	(segment
		(start 155.963112 -219.83065)
		(end 156.124656 -219.669106)
		(width 0.14478)
		(layer "In4.Cu")
		(net "M_J_CPU1_SA_DQ<15>")
	)
	(segment
		(start 166.915846 -214.760302)
		(end 169.7609 -214.760302)
		(width 0.14478)
		(layer "In4.Cu")
		(net "M_J_CPU1_SA_DQ<15>")
	)
	(segment
		(start 131.51485 -234.764326)
		(end 131.360672 -234.498896)
		(width 0.0889)
		(layer "In4.Cu")
		(net "M_J_CPU1_SA_DQ<15>")
	)
	(segment
		(start 153.847038 -222.853504)
		(end 153.847038 -222.624904)
		(width 0.14478)
		(layer "In4.Cu")
		(net "M_J_CPU1_SA_DQ<15>")
	)
	(segment
		(start 185.04154 -214.457026)
		(end 185.344816 -214.760302)
		(width 0.14478)
		(layer "In4.Cu")
		(net "M_J_CPU1_SA_DQ<15>")
	)
	(segment
		(start 156.187902 -220.51264)
		(end 156.187902 -220.28404)
		(width 0.14478)
		(layer "In4.Cu")
		(net "M_J_CPU1_SA_DQ<15>")
	)
	(segment
		(start 185.344816 -214.760302)
		(end 185.592974 -214.760302)
		(width 0.14478)
		(layer "In4.Cu")
		(net "M_J_CPU1_SA_DQ<15>")
	)
	(segment
		(start 178.593496 -215.61044)
		(end 181.214522 -215.61044)
		(width 0.14478)
		(layer "In4.Cu")
		(net "M_J_CPU1_SA_DQ<15>")
	)
	(segment
		(start 155.572968 -220.449394)
		(end 155.797758 -220.674184)
		(width 0.14478)
		(layer "In4.Cu")
		(net "M_J_CPU1_SA_DQ<15>")
	)
	(segment
		(start 181.214522 -215.61044)
		(end 182.06466 -214.760302)
		(width 0.14478)
		(layer "In4.Cu")
		(net "M_J_CPU1_SA_DQ<15>")
	)
	(segment
		(start 186.144408 -214.457026)
		(end 186.447684 -214.760302)
		(width 0.14478)
		(layer "In4.Cu")
		(net "M_J_CPU1_SA_DQ<15>")
	)
	(segment
		(start 154.56408 -221.229682)
		(end 154.79268 -221.229682)
		(width 0.14478)
		(layer "In4.Cu")
		(net "M_J_CPU1_SA_DQ<15>")
	)
	(segment
		(start 147.761706 -232.020364)
		(end 152.725374 -227.056696)
		(width 0.14478)
		(layer "In4.Cu")
		(net "M_J_CPU1_SA_DQ<15>")
	)
	(segment
		(start 154.237182 -222.23476)
		(end 154.465782 -222.23476)
		(width 0.14478)
		(layer "In4.Cu")
		(net "M_J_CPU1_SA_DQ<15>")
	)
	(segment
		(start 156.124656 -219.669106)
		(end 156.353256 -219.669106)
		(width 0.14478)
		(layer "In4.Cu")
		(net "M_J_CPU1_SA_DQ<15>")
	)
	(segment
		(start 152.84196 -223.180402)
		(end 152.84196 -222.951802)
		(width 0.14478)
		(layer "In4.Cu")
		(net "M_J_CPU1_SA_DQ<15>")
	)
	(segment
		(start 186.635136 -214.760302)
		(end 187.060078 -215.185244)
		(width 0.14478)
		(layer "In4.Cu")
		(net "M_J_CPU1_SA_DQ<15>")
	)
	(segment
		(start 137.907776 -234.441746)
		(end 137.916158 -234.43692)
		(width 0.0889)
		(layer "In4.Cu")
		(net "M_J_CPU1_SA_DQ<15>")
	)
	(segment
		(start 133.20776 -234.441746)
		(end 133.216142 -234.43692)
		(width 0.0889)
		(layer "In4.Cu")
		(net "M_J_CPU1_SA_DQ<15>")
	)
	(segment
		(start 154.402536 -221.391226)
		(end 154.56408 -221.229682)
		(width 0.14478)
		(layer "In4.Cu")
		(net "M_J_CPU1_SA_DQ<15>")
	)
	(segment
		(start 170.611038 -215.61044)
		(end 173.662594 -215.61044)
		(width 0.14478)
		(layer "In4.Cu")
		(net "M_J_CPU1_SA_DQ<15>")
	)
	(segment
		(start 153.847038 -222.624904)
		(end 153.622248 -222.400114)
		(width 0.14478)
		(layer "In4.Cu")
		(net "M_J_CPU1_SA_DQ<15>")
	)
	(segment
		(start 154.465782 -222.23476)
		(end 154.627326 -222.073216)
		(width 0.14478)
		(layer "In4.Cu")
		(net "M_J_CPU1_SA_DQ<15>")
	)
	(segment
		(start 152.725374 -223.975168)
		(end 153.06675 -223.633792)
		(width 0.14478)
		(layer "In4.Cu")
		(net "M_J_CPU1_SA_DQ<15>")
	)
	(segment
		(start 155.24607 -221.454472)
		(end 155.407614 -221.292928)
		(width 0.14478)
		(layer "In4.Cu")
		(net "M_J_CPU1_SA_DQ<15>")
	)
	(segment
		(start 182.06466 -214.760302)
		(end 184.490106 -214.760302)
		(width 0.14478)
		(layer "In4.Cu")
		(net "M_J_CPU1_SA_DQ<15>")
	)
	(segment
		(start 152.725374 -227.056696)
		(end 152.725374 -223.975168)
		(width 0.14478)
		(layer "In4.Cu")
		(net "M_J_CPU1_SA_DQ<15>")
	)
	(segment
		(start 154.79268 -221.229682)
		(end 155.01747 -221.454472)
		(width 0.14478)
		(layer "In4.Cu")
		(net "M_J_CPU1_SA_DQ<15>")
	)
	(segment
		(start 141.093444 -234.43692)
		(end 141.101826 -234.441746)
		(width 0.0889)
		(layer "In4.Cu")
		(net "M_J_CPU1_SA_DQ<15>")
	)
	(segment
		(start 153.456894 -223.015048)
		(end 153.685494 -223.015048)
		(width 0.14478)
		(layer "In4.Cu")
		(net "M_J_CPU1_SA_DQ<15>")
	)
	(segment
		(start 161.090102 -215.61044)
		(end 166.065708 -215.61044)
		(width 0.14478)
		(layer "In4.Cu")
		(net "M_J_CPU1_SA_DQ<15>")
	)
	(segment
		(start 156.806646 -219.893896)
		(end 161.090102 -215.61044)
		(width 0.14478)
		(layer "In4.Cu")
		(net "M_J_CPU1_SA_DQ<15>")
	)
	(segment
		(start 156.353256 -219.669106)
		(end 156.578046 -219.893896)
		(width 0.14478)
		(layer "In4.Cu")
		(net "M_J_CPU1_SA_DQ<15>")
	)
	(segment
		(start 173.662594 -215.61044)
		(end 174.512732 -214.760302)
		(width 0.14478)
		(layer "In4.Cu")
		(net "M_J_CPU1_SA_DQ<15>")
	)
	(segment
		(start 153.06675 -223.633792)
		(end 153.06675 -223.405192)
		(width 0.14478)
		(layer "In4.Cu")
		(net "M_J_CPU1_SA_DQ<15>")
	)
	(segment
		(start 174.512732 -214.760302)
		(end 177.743358 -214.760302)
		(width 0.14478)
		(layer "In4.Cu")
		(net "M_J_CPU1_SA_DQ<15>")
	)
	(segment
		(start 136.393428 -234.43692)
		(end 136.40181 -234.441746)
		(width 0.0889)
		(layer "In4.Cu")
		(net "M_J_CPU1_SA_DQ<15>")
	)
	(segment
		(start 156.578046 -219.893896)
		(end 156.806646 -219.893896)
		(width 0.14478)
		(layer "In4.Cu")
		(net "M_J_CPU1_SA_DQ<15>")
	)
	(segment
		(start 154.402536 -221.619826)
		(end 154.402536 -221.391226)
		(width 0.14478)
		(layer "In4.Cu")
		(net "M_J_CPU1_SA_DQ<15>")
	)
	(segment
		(start 155.797758 -220.674184)
		(end 156.026358 -220.674184)
		(width 0.14478)
		(layer "In4.Cu")
		(net "M_J_CPU1_SA_DQ<15>")
	)
	(segment
		(start 155.182824 -220.610938)
		(end 155.344368 -220.449394)
		(width 0.14478)
		(layer "In4.Cu")
		(net "M_J_CPU1_SA_DQ<15>")
	)
	(segment
		(start 140.15339 -234.43692)
		(end 140.161772 -234.441746)
		(width 0.0889)
		(layer "In4.Cu")
		(net "M_J_CPU1_SA_DQ<15>")
	)
	(segment
		(start 153.622248 -222.171514)
		(end 153.783792 -222.00997)
		(width 0.14478)
		(layer "In4.Cu")
		(net "M_J_CPU1_SA_DQ<15>")
	)
	(segment
		(start 153.622248 -222.400114)
		(end 153.622248 -222.171514)
		(width 0.14478)
		(layer "In4.Cu")
		(net "M_J_CPU1_SA_DQ<15>")
	)
	(arc
		(start 136.027668 -234.441746)
		(mid 136.209919 -234.391396)
		(end 136.393428 -234.43692)
		(width 0.0889)
		(layer "In4.Cu")
		(net "M_J_CPU1_SA_DQ<15>")
	)
	(arc
		(start 132.276088 -234.43692)
		(mid 132.459596 -234.391426)
		(end 132.641848 -234.441746)
		(width 0.0889)
		(layer "In4.Cu")
		(net "M_J_CPU1_SA_DQ<15>")
	)
	(arc
		(start 139.221718 -234.441746)
		(mid 139.504674 -234.517923)
		(end 139.78763 -234.441746)
		(width 0.0889)
		(layer "In4.Cu")
		(net "M_J_CPU1_SA_DQ<15>")
	)
	(arc
		(start 141.101826 -234.441746)
		(mid 141.384782 -234.517923)
		(end 141.667738 -234.441746)
		(width 0.0889)
		(layer "In4.Cu")
		(net "M_J_CPU1_SA_DQ<15>")
	)
	(arc
		(start 137.341864 -234.441746)
		(mid 137.62482 -234.517923)
		(end 137.907776 -234.441746)
		(width 0.0889)
		(layer "In4.Cu")
		(net "M_J_CPU1_SA_DQ<15>")
	)
	(arc
		(start 137.916158 -234.43692)
		(mid 138.099666 -234.391426)
		(end 138.281918 -234.441746)
		(width 0.0889)
		(layer "In4.Cu")
		(net "M_J_CPU1_SA_DQ<15>")
	)
	(arc
		(start 132.641848 -234.441746)
		(mid 132.924804 -234.517923)
		(end 133.20776 -234.441746)
		(width 0.0889)
		(layer "In4.Cu")
		(net "M_J_CPU1_SA_DQ<15>")
	)
	(arc
		(start 143.547592 -234.441746)
		(mid 143.637868 -234.404241)
		(end 143.73479 -234.391454)
		(width 0.0889)
		(layer "In4.Cu")
		(net "M_J_CPU1_SA_DQ<15>")
	)
	(arc
		(start 136.976104 -234.43692)
		(mid 137.159612 -234.391426)
		(end 137.341864 -234.441746)
		(width 0.0889)
		(layer "In4.Cu")
		(net "M_J_CPU1_SA_DQ<15>")
	)
	(arc
		(start 136.40181 -234.441746)
		(mid 136.684766 -234.517923)
		(end 136.967722 -234.441746)
		(width 0.0889)
		(layer "In4.Cu")
		(net "M_J_CPU1_SA_DQ<15>")
	)
	(arc
		(start 135.087614 -234.441746)
		(mid 135.269865 -234.391396)
		(end 135.453374 -234.43692)
		(width 0.0889)
		(layer "In4.Cu")
		(net "M_J_CPU1_SA_DQ<15>")
	)
	(arc
		(start 142.04188 -234.441746)
		(mid 142.324836 -234.517923)
		(end 142.607792 -234.441746)
		(width 0.0889)
		(layer "In4.Cu")
		(net "M_J_CPU1_SA_DQ<15>")
	)
	(arc
		(start 134.521702 -234.441746)
		(mid 134.804658 -234.517923)
		(end 135.087614 -234.441746)
		(width 0.0889)
		(layer "In4.Cu")
		(net "M_J_CPU1_SA_DQ<15>")
	)
	(arc
		(start 138.281918 -234.441746)
		(mid 138.564874 -234.517923)
		(end 138.84783 -234.441746)
		(width 0.0889)
		(layer "In4.Cu")
		(net "M_J_CPU1_SA_DQ<15>")
	)
	(arc
		(start 140.727684 -234.441746)
		(mid 140.909935 -234.391396)
		(end 141.093444 -234.43692)
		(width 0.0889)
		(layer "In4.Cu")
		(net "M_J_CPU1_SA_DQ<15>")
	)
	(arc
		(start 133.581902 -234.441746)
		(mid 133.864858 -234.517923)
		(end 134.147814 -234.441746)
		(width 0.0889)
		(layer "In4.Cu")
		(net "M_J_CPU1_SA_DQ<15>")
	)
	(arc
		(start 140.161772 -234.441746)
		(mid 140.444728 -234.517923)
		(end 140.727684 -234.441746)
		(width 0.0889)
		(layer "In4.Cu")
		(net "M_J_CPU1_SA_DQ<15>")
	)
	(arc
		(start 141.67612 -234.43692)
		(mid 141.859628 -234.391426)
		(end 142.04188 -234.441746)
		(width 0.0889)
		(layer "In4.Cu")
		(net "M_J_CPU1_SA_DQ<15>")
	)
	(arc
		(start 139.78763 -234.441746)
		(mid 139.969881 -234.391396)
		(end 140.15339 -234.43692)
		(width 0.0889)
		(layer "In4.Cu")
		(net "M_J_CPU1_SA_DQ<15>")
	)
	(arc
		(start 142.607792 -234.441746)
		(mid 142.794736 -234.391491)
		(end 142.98168 -234.441746)
		(width 0.0889)
		(layer "In4.Cu")
		(net "M_J_CPU1_SA_DQ<15>")
	)
	(arc
		(start 133.216142 -234.43692)
		(mid 133.39965 -234.391426)
		(end 133.581902 -234.441746)
		(width 0.0889)
		(layer "In4.Cu")
		(net "M_J_CPU1_SA_DQ<15>")
	)
	(arc
		(start 142.98168 -234.441746)
		(mid 143.264636 -234.517923)
		(end 143.547592 -234.441746)
		(width 0.0889)
		(layer "In4.Cu")
		(net "M_J_CPU1_SA_DQ<15>")
	)
	(arc
		(start 134.147814 -234.441746)
		(mid 134.334758 -234.391491)
		(end 134.521702 -234.441746)
		(width 0.0889)
		(layer "In4.Cu")
		(net "M_J_CPU1_SA_DQ<15>")
	)
	(arc
		(start 135.461756 -234.441746)
		(mid 135.744712 -234.517923)
		(end 136.027668 -234.441746)
		(width 0.0889)
		(layer "In4.Cu")
		(net "M_J_CPU1_SA_DQ<15>")
	)
	(arc
		(start 138.84783 -234.441746)
		(mid 139.034774 -234.391491)
		(end 139.221718 -234.441746)
		(width 0.0889)
		(layer "In4.Cu")
		(net "M_J_CPU1_SA_DQ<15>")
	)
	(arc
		(start 131.383024 -234.415584)
		(mid 131.540534 -234.392386)
		(end 131.693412 -234.43692)
		(width 0.0889)
		(layer "In4.Cu")
		(net "M_J_CPU1_SA_DQ<15>")
	)
	(arc
		(start 131.701794 -234.441746)
		(mid 131.98475 -234.517923)
		(end 132.267706 -234.441746)
		(width 0.0889)
		(layer "In4.Cu")
		(net "M_J_CPU1_SA_DQ<15>")
	)
	(segment
		(start 132.457952 -234.220258)
		(end 132.924804 -233.95432)
		(width 0.10668)
		(layer "F.Cu")
		(net "M_J_CPU1_SA_DQ<14>")
	)
	(segment
		(start 144.655032 -233.018584)
		(end 145.494756 -233.018584)
		(width 0.0889)
		(layer "In4.Cu")
		(net "M_J_CPU1_SA_DQ<14>")
	)
	(segment
		(start 142.503398 -233.626914)
		(end 142.51178 -233.63174)
		(width 0.0889)
		(layer "In4.Cu")
		(net "M_J_CPU1_SA_DQ<14>")
	)
	(segment
		(start 159.193992 -215.975184)
		(end 158.984442 -215.765634)
		(width 0.14478)
		(layer "In4.Cu")
		(net "M_J_CPU1_SA_DQ<14>")
	)
	(segment
		(start 159.76473 -214.985346)
		(end 159.76473 -214.756746)
		(width 0.14478)
		(layer "In4.Cu")
		(net "M_J_CPU1_SA_DQ<14>")
	)
	(segment
		(start 158.594298 -216.155778)
		(end 158.803848 -216.365328)
		(width 0.14478)
		(layer "In4.Cu")
		(net "M_J_CPU1_SA_DQ<14>")
	)
	(segment
		(start 180.485288 -214.205566)
		(end 180.741574 -214.205566)
		(width 0.14478)
		(layer "In4.Cu")
		(net "M_J_CPU1_SA_DQ<14>")
	)
	(segment
		(start 159.584136 -215.58504)
		(end 159.812736 -215.58504)
		(width 0.14478)
		(layer "In4.Cu")
		(net "M_J_CPU1_SA_DQ<14>")
	)
	(segment
		(start 174.347124 -213.06028)
		(end 177.53203 -213.06028)
		(width 0.14478)
		(layer "In4.Cu")
		(net "M_J_CPU1_SA_DQ<14>")
	)
	(segment
		(start 143.077692 -233.63174)
		(end 143.086074 -233.626914)
		(width 0.0889)
		(layer "In4.Cu")
		(net "M_J_CPU1_SA_DQ<14>")
	)
	(segment
		(start 156.024834 -218.496642)
		(end 156.253434 -218.496642)
		(width 0.14478)
		(layer "In4.Cu")
		(net "M_J_CPU1_SA_DQ<14>")
	)
	(segment
		(start 184.620662 -212.757766)
		(end 184.869582 -212.757766)
		(width 0.14478)
		(layer "In4.Cu")
		(net "M_J_CPU1_SA_DQ<14>")
	)
	(segment
		(start 157.633416 -217.53576)
		(end 157.423866 -217.32621)
		(width 0.14478)
		(layer "In4.Cu")
		(net "M_J_CPU1_SA_DQ<14>")
	)
	(segment
		(start 184.869582 -212.757766)
		(end 185.172096 -213.06028)
		(width 0.14478)
		(layer "In4.Cu")
		(net "M_J_CPU1_SA_DQ<14>")
	)
	(segment
		(start 147.69338 -230.658416)
		(end 151.826214 -226.525582)
		(width 0.14478)
		(layer "In4.Cu")
		(net "M_J_CPU1_SA_DQ<14>")
	)
	(segment
		(start 156.643578 -217.877898)
		(end 156.805122 -217.716354)
		(width 0.14478)
		(layer "In4.Cu")
		(net "M_J_CPU1_SA_DQ<14>")
	)
	(segment
		(start 156.691584 -218.706192)
		(end 156.853128 -218.544648)
		(width 0.14478)
		(layer "In4.Cu")
		(net "M_J_CPU1_SA_DQ<14>")
	)
	(segment
		(start 173.496986 -213.910418)
		(end 174.347124 -213.06028)
		(width 0.14478)
		(layer "In4.Cu")
		(net "M_J_CPU1_SA_DQ<14>")
	)
	(segment
		(start 161.933636 -214.197946)
		(end 162.221164 -213.910418)
		(width 0.14478)
		(layer "In4.Cu")
		(net "M_J_CPU1_SA_DQ<14>")
	)
	(segment
		(start 143.451834 -233.63174)
		(end 143.462248 -233.637836)
		(width 0.0889)
		(layer "In4.Cu")
		(net "M_J_CPU1_SA_DQ<14>")
	)
	(segment
		(start 182.241952 -213.06028)
		(end 184.318148 -213.06028)
		(width 0.14478)
		(layer "In4.Cu")
		(net "M_J_CPU1_SA_DQ<14>")
	)
	(segment
		(start 185.172096 -213.06028)
		(end 185.421016 -213.06028)
		(width 0.14478)
		(layer "In4.Cu")
		(net "M_J_CPU1_SA_DQ<14>")
	)
	(segment
		(start 185.72353 -212.757766)
		(end 185.97245 -212.757766)
		(width 0.14478)
		(layer "In4.Cu")
		(net "M_J_CPU1_SA_DQ<14>")
	)
	(segment
		(start 180.19014 -213.910418)
		(end 180.485288 -214.205566)
		(width 0.14478)
		(layer "In4.Cu")
		(net "M_J_CPU1_SA_DQ<14>")
	)
	(segment
		(start 185.421016 -213.06028)
		(end 185.72353 -212.757766)
		(width 0.14478)
		(layer "In4.Cu")
		(net "M_J_CPU1_SA_DQ<14>")
	)
	(segment
		(start 162.772598 -214.197946)
		(end 163.036504 -214.197946)
		(width 0.14478)
		(layer "In4.Cu")
		(net "M_J_CPU1_SA_DQ<14>")
	)
	(segment
		(start 158.413704 -216.984072)
		(end 158.413704 -216.755472)
		(width 0.14478)
		(layer "In4.Cu")
		(net "M_J_CPU1_SA_DQ<14>")
	)
	(segment
		(start 144.074896 -233.59872)
		(end 144.655032 -233.018584)
		(width 0.0889)
		(layer "In4.Cu")
		(net "M_J_CPU1_SA_DQ<14>")
	)
	(segment
		(start 138.743436 -233.626914)
		(end 138.751818 -233.63174)
		(width 0.0889)
		(layer "In4.Cu")
		(net "M_J_CPU1_SA_DQ<14>")
	)
	(segment
		(start 146.324828 -231.665272)
		(end 146.749516 -231.240584)
		(width 0.0889)
		(layer "In4.Cu")
		(net "M_J_CPU1_SA_DQ<14>")
	)
	(segment
		(start 159.374586 -215.37549)
		(end 159.584136 -215.58504)
		(width 0.14478)
		(layer "In4.Cu")
		(net "M_J_CPU1_SA_DQ<14>")
	)
	(segment
		(start 161.382202 -213.910418)
		(end 161.66973 -214.197946)
		(width 0.14478)
		(layer "In4.Cu")
		(net "M_J_CPU1_SA_DQ<14>")
	)
	(segment
		(start 157.58541 -216.936066)
		(end 157.81401 -216.936066)
		(width 0.14478)
		(layer "In4.Cu")
		(net "M_J_CPU1_SA_DQ<14>")
	)
	(segment
		(start 158.25216 -217.145616)
		(end 158.413704 -216.984072)
		(width 0.14478)
		(layer "In4.Cu")
		(net "M_J_CPU1_SA_DQ<14>")
	)
	(segment
		(start 158.984442 -215.537034)
		(end 159.145986 -215.37549)
		(width 0.14478)
		(layer "In4.Cu")
		(net "M_J_CPU1_SA_DQ<14>")
	)
	(segment
		(start 159.145986 -215.37549)
		(end 159.374586 -215.37549)
		(width 0.14478)
		(layer "In4.Cu")
		(net "M_J_CPU1_SA_DQ<14>")
	)
	(segment
		(start 157.633416 -217.76436)
		(end 157.633416 -217.53576)
		(width 0.14478)
		(layer "In4.Cu")
		(net "M_J_CPU1_SA_DQ<14>")
	)
	(segment
		(start 186.274964 -213.06028)
		(end 186.635136 -213.06028)
		(width 0.14478)
		(layer "In4.Cu")
		(net "M_J_CPU1_SA_DQ<14>")
	)
	(segment
		(start 157.423866 -217.32621)
		(end 157.423866 -217.09761)
		(width 0.14478)
		(layer "In4.Cu")
		(net "M_J_CPU1_SA_DQ<14>")
	)
	(segment
		(start 135.557768 -233.63174)
		(end 135.56615 -233.626914)
		(width 0.0889)
		(layer "In4.Cu")
		(net "M_J_CPU1_SA_DQ<14>")
	)
	(segment
		(start 157.033722 -217.716354)
		(end 157.243272 -217.925904)
		(width 0.14478)
		(layer "In4.Cu")
		(net "M_J_CPU1_SA_DQ<14>")
	)
	(segment
		(start 158.204154 -216.545922)
		(end 158.204154 -216.317322)
		(width 0.14478)
		(layer "In4.Cu")
		(net "M_J_CPU1_SA_DQ<14>")
	)
	(segment
		(start 181.036722 -213.910418)
		(end 181.391814 -213.910418)
		(width 0.14478)
		(layer "In4.Cu")
		(net "M_J_CPU1_SA_DQ<14>")
	)
	(segment
		(start 159.97428 -215.194896)
		(end 159.76473 -214.985346)
		(width 0.14478)
		(layer "In4.Cu")
		(net "M_J_CPU1_SA_DQ<14>")
	)
	(segment
		(start 158.204154 -216.317322)
		(end 158.365698 -216.155778)
		(width 0.14478)
		(layer "In4.Cu")
		(net "M_J_CPU1_SA_DQ<14>")
	)
	(segment
		(start 162.48507 -213.910418)
		(end 162.772598 -214.197946)
		(width 0.14478)
		(layer "In4.Cu")
		(net "M_J_CPU1_SA_DQ<14>")
	)
	(segment
		(start 159.032448 -216.365328)
		(end 159.193992 -216.203784)
		(width 0.14478)
		(layer "In4.Cu")
		(net "M_J_CPU1_SA_DQ<14>")
	)
	(segment
		(start 140.257784 -233.63174)
		(end 140.266166 -233.626914)
		(width 0.0889)
		(layer "In4.Cu")
		(net "M_J_CPU1_SA_DQ<14>")
	)
	(segment
		(start 160.611058 -213.910418)
		(end 161.382202 -213.910418)
		(width 0.14478)
		(layer "In4.Cu")
		(net "M_J_CPU1_SA_DQ<14>")
	)
	(segment
		(start 157.243272 -217.925904)
		(end 157.471872 -217.925904)
		(width 0.14478)
		(layer "In4.Cu")
		(net "M_J_CPU1_SA_DQ<14>")
	)
	(segment
		(start 163.036504 -214.197946)
		(end 163.324032 -213.910418)
		(width 0.14478)
		(layer "In4.Cu")
		(net "M_J_CPU1_SA_DQ<14>")
	)
	(segment
		(start 156.643578 -218.106498)
		(end 156.643578 -217.877898)
		(width 0.14478)
		(layer "In4.Cu")
		(net "M_J_CPU1_SA_DQ<14>")
	)
	(segment
		(start 186.635136 -213.06028)
		(end 187.060078 -213.485222)
		(width 0.14478)
		(layer "In4.Cu")
		(net "M_J_CPU1_SA_DQ<14>")
	)
	(segment
		(start 159.193992 -216.203784)
		(end 159.193992 -215.975184)
		(width 0.14478)
		(layer "In4.Cu")
		(net "M_J_CPU1_SA_DQ<14>")
	)
	(segment
		(start 134.04342 -233.626914)
		(end 134.051802 -233.63174)
		(width 0.0889)
		(layer "In4.Cu")
		(net "M_J_CPU1_SA_DQ<14>")
	)
	(segment
		(start 158.02356 -217.145616)
		(end 158.25216 -217.145616)
		(width 0.14478)
		(layer "In4.Cu")
		(net "M_J_CPU1_SA_DQ<14>")
	)
	(segment
		(start 156.853128 -218.544648)
		(end 156.853128 -218.316048)
		(width 0.14478)
		(layer "In4.Cu")
		(net "M_J_CPU1_SA_DQ<14>")
	)
	(segment
		(start 159.97428 -215.423496)
		(end 159.97428 -215.194896)
		(width 0.14478)
		(layer "In4.Cu")
		(net "M_J_CPU1_SA_DQ<14>")
	)
	(segment
		(start 166.228014 -213.910418)
		(end 167.078152 -213.06028)
		(width 0.14478)
		(layer "In4.Cu")
		(net "M_J_CPU1_SA_DQ<14>")
	)
	(segment
		(start 157.81401 -216.936066)
		(end 158.02356 -217.145616)
		(width 0.14478)
		(layer "In4.Cu")
		(net "M_J_CPU1_SA_DQ<14>")
	)
	(segment
		(start 137.803382 -233.626914)
		(end 137.811764 -233.63174)
		(width 0.0889)
		(layer "In4.Cu")
		(net "M_J_CPU1_SA_DQ<14>")
	)
	(segment
		(start 145.494756 -233.018584)
		(end 146.324828 -232.188512)
		(width 0.0889)
		(layer "In4.Cu")
		(net "M_J_CPU1_SA_DQ<14>")
	)
	(segment
		(start 180.741574 -214.205566)
		(end 181.036722 -213.910418)
		(width 0.14478)
		(layer "In4.Cu")
		(net "M_J_CPU1_SA_DQ<14>")
	)
	(segment
		(start 156.253434 -218.496642)
		(end 156.462984 -218.706192)
		(width 0.14478)
		(layer "In4.Cu")
		(net "M_J_CPU1_SA_DQ<14>")
	)
	(segment
		(start 178.382168 -213.910418)
		(end 180.19014 -213.910418)
		(width 0.14478)
		(layer "In4.Cu")
		(net "M_J_CPU1_SA_DQ<14>")
	)
	(segment
		(start 158.413704 -216.755472)
		(end 158.204154 -216.545922)
		(width 0.14478)
		(layer "In4.Cu")
		(net "M_J_CPU1_SA_DQ<14>")
	)
	(segment
		(start 132.770626 -233.68889)
		(end 132.792978 -233.605578)
		(width 0.0889)
		(layer "In4.Cu")
		(net "M_J_CPU1_SA_DQ<14>")
	)
	(segment
		(start 144.018 -233.63174)
		(end 144.074896 -233.59872)
		(width 0.0889)
		(layer "In4.Cu")
		(net "M_J_CPU1_SA_DQ<14>")
	)
	(segment
		(start 156.805122 -217.716354)
		(end 157.033722 -217.716354)
		(width 0.14478)
		(layer "In4.Cu")
		(net "M_J_CPU1_SA_DQ<14>")
	)
	(segment
		(start 169.588942 -213.06028)
		(end 170.43908 -213.910418)
		(width 0.14478)
		(layer "In4.Cu")
		(net "M_J_CPU1_SA_DQ<14>")
	)
	(segment
		(start 167.078152 -213.06028)
		(end 169.588942 -213.06028)
		(width 0.14478)
		(layer "In4.Cu")
		(net "M_J_CPU1_SA_DQ<14>")
	)
	(segment
		(start 133.103366 -233.626914)
		(end 133.111748 -233.63174)
		(width 0.0889)
		(layer "In4.Cu")
		(net "M_J_CPU1_SA_DQ<14>")
	)
	(segment
		(start 159.76473 -214.756746)
		(end 160.611058 -213.910418)
		(width 0.14478)
		(layer "In4.Cu")
		(net "M_J_CPU1_SA_DQ<14>")
	)
	(segment
		(start 151.826214 -222.695262)
		(end 156.024834 -218.496642)
		(width 0.14478)
		(layer "In4.Cu")
		(net "M_J_CPU1_SA_DQ<14>")
	)
	(segment
		(start 170.43908 -213.910418)
		(end 173.496986 -213.910418)
		(width 0.14478)
		(layer "In4.Cu")
		(net "M_J_CPU1_SA_DQ<14>")
	)
	(segment
		(start 134.617714 -233.63174)
		(end 134.626096 -233.626914)
		(width 0.0889)
		(layer "In4.Cu")
		(net "M_J_CPU1_SA_DQ<14>")
	)
	(segment
		(start 158.365698 -216.155778)
		(end 158.594298 -216.155778)
		(width 0.14478)
		(layer "In4.Cu")
		(net "M_J_CPU1_SA_DQ<14>")
	)
	(segment
		(start 157.423866 -217.09761)
		(end 157.58541 -216.936066)
		(width 0.14478)
		(layer "In4.Cu")
		(net "M_J_CPU1_SA_DQ<14>")
	)
	(segment
		(start 185.97245 -212.757766)
		(end 186.274964 -213.06028)
		(width 0.14478)
		(layer "In4.Cu")
		(net "M_J_CPU1_SA_DQ<14>")
	)
	(segment
		(start 146.324828 -232.188512)
		(end 146.324828 -231.665272)
		(width 0.0889)
		(layer "In4.Cu")
		(net "M_J_CPU1_SA_DQ<14>")
	)
	(segment
		(start 161.66973 -214.197946)
		(end 161.933636 -214.197946)
		(width 0.14478)
		(layer "In4.Cu")
		(net "M_J_CPU1_SA_DQ<14>")
	)
	(segment
		(start 157.471872 -217.925904)
		(end 157.633416 -217.76436)
		(width 0.14478)
		(layer "In4.Cu")
		(net "M_J_CPU1_SA_DQ<14>")
	)
	(segment
		(start 156.853128 -218.316048)
		(end 156.643578 -218.106498)
		(width 0.14478)
		(layer "In4.Cu")
		(net "M_J_CPU1_SA_DQ<14>")
	)
	(segment
		(start 139.31773 -233.63174)
		(end 139.326112 -233.626914)
		(width 0.0889)
		(layer "In4.Cu")
		(net "M_J_CPU1_SA_DQ<14>")
	)
	(segment
		(start 147.111212 -231.240584)
		(end 147.69338 -230.658416)
		(width 0.0889)
		(layer "In4.Cu")
		(net "M_J_CPU1_SA_DQ<14>")
	)
	(segment
		(start 159.812736 -215.58504)
		(end 159.97428 -215.423496)
		(width 0.14478)
		(layer "In4.Cu")
		(net "M_J_CPU1_SA_DQ<14>")
	)
	(segment
		(start 156.462984 -218.706192)
		(end 156.691584 -218.706192)
		(width 0.14478)
		(layer "In4.Cu")
		(net "M_J_CPU1_SA_DQ<14>")
	)
	(segment
		(start 158.803848 -216.365328)
		(end 159.032448 -216.365328)
		(width 0.14478)
		(layer "In4.Cu")
		(net "M_J_CPU1_SA_DQ<14>")
	)
	(segment
		(start 184.318148 -213.06028)
		(end 184.620662 -212.757766)
		(width 0.14478)
		(layer "In4.Cu")
		(net "M_J_CPU1_SA_DQ<14>")
	)
	(segment
		(start 158.984442 -215.765634)
		(end 158.984442 -215.537034)
		(width 0.14478)
		(layer "In4.Cu")
		(net "M_J_CPU1_SA_DQ<14>")
	)
	(segment
		(start 163.324032 -213.910418)
		(end 166.228014 -213.910418)
		(width 0.14478)
		(layer "In4.Cu")
		(net "M_J_CPU1_SA_DQ<14>")
	)
	(segment
		(start 181.391814 -213.910418)
		(end 182.241952 -213.06028)
		(width 0.14478)
		(layer "In4.Cu")
		(net "M_J_CPU1_SA_DQ<14>")
	)
	(segment
		(start 177.53203 -213.06028)
		(end 178.382168 -213.910418)
		(width 0.14478)
		(layer "In4.Cu")
		(net "M_J_CPU1_SA_DQ<14>")
	)
	(segment
		(start 132.924804 -233.95432)
		(end 132.770626 -233.68889)
		(width 0.0889)
		(layer "In4.Cu")
		(net "M_J_CPU1_SA_DQ<14>")
	)
	(segment
		(start 146.749516 -231.240584)
		(end 147.111212 -231.240584)
		(width 0.0889)
		(layer "In4.Cu")
		(net "M_J_CPU1_SA_DQ<14>")
	)
	(segment
		(start 151.826214 -226.525582)
		(end 151.826214 -222.695262)
		(width 0.14478)
		(layer "In4.Cu")
		(net "M_J_CPU1_SA_DQ<14>")
	)
	(segment
		(start 162.221164 -213.910418)
		(end 162.48507 -213.910418)
		(width 0.14478)
		(layer "In4.Cu")
		(net "M_J_CPU1_SA_DQ<14>")
	)
	(arc
		(start 140.631926 -233.63174)
		(mid 140.914882 -233.707917)
		(end 141.197838 -233.63174)
		(width 0.0889)
		(layer "In4.Cu")
		(net "M_J_CPU1_SA_DQ<14>")
	)
	(arc
		(start 139.326112 -233.626914)
		(mid 139.50962 -233.58142)
		(end 139.691872 -233.63174)
		(width 0.0889)
		(layer "In4.Cu")
		(net "M_J_CPU1_SA_DQ<14>")
	)
	(arc
		(start 135.93191 -233.63174)
		(mid 136.214866 -233.707917)
		(end 136.497822 -233.63174)
		(width 0.0889)
		(layer "In4.Cu")
		(net "M_J_CPU1_SA_DQ<14>")
	)
	(arc
		(start 134.626096 -233.626914)
		(mid 134.809604 -233.58142)
		(end 134.991856 -233.63174)
		(width 0.0889)
		(layer "In4.Cu")
		(net "M_J_CPU1_SA_DQ<14>")
	)
	(arc
		(start 136.87171 -233.63174)
		(mid 137.154666 -233.707917)
		(end 137.437622 -233.63174)
		(width 0.0889)
		(layer "In4.Cu")
		(net "M_J_CPU1_SA_DQ<14>")
	)
	(arc
		(start 141.197838 -233.63174)
		(mid 141.384782 -233.581485)
		(end 141.571726 -233.63174)
		(width 0.0889)
		(layer "In4.Cu")
		(net "M_J_CPU1_SA_DQ<14>")
	)
	(arc
		(start 136.497822 -233.63174)
		(mid 136.684766 -233.581485)
		(end 136.87171 -233.63174)
		(width 0.0889)
		(layer "In4.Cu")
		(net "M_J_CPU1_SA_DQ<14>")
	)
	(arc
		(start 132.792978 -233.605578)
		(mid 132.950488 -233.58238)
		(end 133.103366 -233.626914)
		(width 0.0889)
		(layer "In4.Cu")
		(net "M_J_CPU1_SA_DQ<14>")
	)
	(arc
		(start 140.266166 -233.626914)
		(mid 140.449674 -233.58142)
		(end 140.631926 -233.63174)
		(width 0.0889)
		(layer "In4.Cu")
		(net "M_J_CPU1_SA_DQ<14>")
	)
	(arc
		(start 142.137638 -233.63174)
		(mid 142.319889 -233.58139)
		(end 142.503398 -233.626914)
		(width 0.0889)
		(layer "In4.Cu")
		(net "M_J_CPU1_SA_DQ<14>")
	)
	(arc
		(start 134.051802 -233.63174)
		(mid 134.334758 -233.707917)
		(end 134.617714 -233.63174)
		(width 0.0889)
		(layer "In4.Cu")
		(net "M_J_CPU1_SA_DQ<14>")
	)
	(arc
		(start 142.51178 -233.63174)
		(mid 142.794736 -233.707917)
		(end 143.077692 -233.63174)
		(width 0.0889)
		(layer "In4.Cu")
		(net "M_J_CPU1_SA_DQ<14>")
	)
	(arc
		(start 138.377676 -233.63174)
		(mid 138.559927 -233.58139)
		(end 138.743436 -233.626914)
		(width 0.0889)
		(layer "In4.Cu")
		(net "M_J_CPU1_SA_DQ<14>")
	)
	(arc
		(start 133.67766 -233.63174)
		(mid 133.859911 -233.58139)
		(end 134.04342 -233.626914)
		(width 0.0889)
		(layer "In4.Cu")
		(net "M_J_CPU1_SA_DQ<14>")
	)
	(arc
		(start 133.111748 -233.63174)
		(mid 133.394704 -233.707917)
		(end 133.67766 -233.63174)
		(width 0.0889)
		(layer "In4.Cu")
		(net "M_J_CPU1_SA_DQ<14>")
	)
	(arc
		(start 138.751818 -233.63174)
		(mid 139.034774 -233.707917)
		(end 139.31773 -233.63174)
		(width 0.0889)
		(layer "In4.Cu")
		(net "M_J_CPU1_SA_DQ<14>")
	)
	(arc
		(start 141.571726 -233.63174)
		(mid 141.854682 -233.707917)
		(end 142.137638 -233.63174)
		(width 0.0889)
		(layer "In4.Cu")
		(net "M_J_CPU1_SA_DQ<14>")
	)
	(arc
		(start 137.811764 -233.63174)
		(mid 138.09472 -233.707917)
		(end 138.377676 -233.63174)
		(width 0.0889)
		(layer "In4.Cu")
		(net "M_J_CPU1_SA_DQ<14>")
	)
	(arc
		(start 134.991856 -233.63174)
		(mid 135.274812 -233.707917)
		(end 135.557768 -233.63174)
		(width 0.0889)
		(layer "In4.Cu")
		(net "M_J_CPU1_SA_DQ<14>")
	)
	(arc
		(start 143.462248 -233.637836)
		(mid 143.740934 -233.708056)
		(end 144.018 -233.63174)
		(width 0.0889)
		(layer "In4.Cu")
		(net "M_J_CPU1_SA_DQ<14>")
	)
	(arc
		(start 143.086074 -233.626914)
		(mid 143.269582 -233.58142)
		(end 143.451834 -233.63174)
		(width 0.0889)
		(layer "In4.Cu")
		(net "M_J_CPU1_SA_DQ<14>")
	)
	(arc
		(start 135.56615 -233.626914)
		(mid 135.749658 -233.58142)
		(end 135.93191 -233.63174)
		(width 0.0889)
		(layer "In4.Cu")
		(net "M_J_CPU1_SA_DQ<14>")
	)
	(arc
		(start 139.691872 -233.63174)
		(mid 139.974828 -233.707917)
		(end 140.257784 -233.63174)
		(width 0.0889)
		(layer "In4.Cu")
		(net "M_J_CPU1_SA_DQ<14>")
	)
	(arc
		(start 137.437622 -233.63174)
		(mid 137.619873 -233.58139)
		(end 137.803382 -233.626914)
		(width 0.0889)
		(layer "In4.Cu")
		(net "M_J_CPU1_SA_DQ<14>")
	)
	(segment
		(start 130.577844 -234.220258)
		(end 131.044696 -233.95432)
		(width 0.10668)
		(layer "F.Cu")
		(net "M_J_CPU1_SA_DQ<13>")
	)
	(segment
		(start 133.103366 -234.281726)
		(end 133.111748 -234.2769)
		(width 0.0889)
		(layer "In4.Cu")
		(net "M_J_CPU1_SA_DQ<13>")
	)
	(segment
		(start 189.734698 -214.496142)
		(end 189.734698 -214.071962)
		(width 0.14478)
		(layer "In4.Cu")
		(net "M_J_CPU1_SA_DQ<13>")
	)
	(segment
		(start 189.183264 -214.496142)
		(end 189.344808 -214.657686)
		(width 0.14478)
		(layer "In4.Cu")
		(net "M_J_CPU1_SA_DQ<13>")
	)
	(segment
		(start 131.044696 -233.95432)
		(end 131.198874 -234.21975)
		(width 0.0889)
		(layer "In4.Cu")
		(net "M_J_CPU1_SA_DQ<13>")
	)
	(segment
		(start 190.735204 -213.910418)
		(end 191.160146 -214.33536)
		(width 0.14478)
		(layer "In4.Cu")
		(net "M_J_CPU1_SA_DQ<13>")
	)
	(segment
		(start 189.02172 -213.910418)
		(end 189.183264 -214.071962)
		(width 0.14478)
		(layer "In4.Cu")
		(net "M_J_CPU1_SA_DQ<13>")
	)
	(segment
		(start 143.077692 -234.2769)
		(end 143.086074 -234.281726)
		(width 0.0889)
		(layer "In4.Cu")
		(net "M_J_CPU1_SA_DQ<13>")
	)
	(segment
		(start 161.30397 -214.760302)
		(end 166.222172 -214.760302)
		(width 0.14478)
		(layer "In4.Cu")
		(net "M_J_CPU1_SA_DQ<13>")
	)
	(segment
		(start 144.044162 -234.200446)
		(end 144.926304 -233.318304)
		(width 0.0889)
		(layer "In4.Cu")
		(net "M_J_CPU1_SA_DQ<13>")
	)
	(segment
		(start 189.573154 -214.657686)
		(end 189.734698 -214.496142)
		(width 0.14478)
		(layer "In4.Cu")
		(net "M_J_CPU1_SA_DQ<13>")
	)
	(segment
		(start 152.275794 -222.881698)
		(end 155.937966 -219.219526)
		(width 0.14478)
		(layer "In4.Cu")
		(net "M_J_CPU1_SA_DQ<13>")
	)
	(segment
		(start 134.617714 -234.2769)
		(end 134.626096 -234.281726)
		(width 0.0889)
		(layer "In4.Cu")
		(net "M_J_CPU1_SA_DQ<13>")
	)
	(segment
		(start 174.641002 -213.910418)
		(end 177.621438 -213.910418)
		(width 0.14478)
		(layer "In4.Cu")
		(net "M_J_CPU1_SA_DQ<13>")
	)
	(segment
		(start 140.257784 -234.2769)
		(end 140.266166 -234.281726)
		(width 0.0889)
		(layer "In4.Cu")
		(net "M_J_CPU1_SA_DQ<13>")
	)
	(segment
		(start 147.95627 -231.114346)
		(end 152.275794 -226.794822)
		(width 0.14478)
		(layer "In4.Cu")
		(net "M_J_CPU1_SA_DQ<13>")
	)
	(segment
		(start 137.803382 -234.281726)
		(end 137.811764 -234.2769)
		(width 0.0889)
		(layer "In4.Cu")
		(net "M_J_CPU1_SA_DQ<13>")
	)
	(segment
		(start 189.344808 -214.657686)
		(end 189.573154 -214.657686)
		(width 0.14478)
		(layer "In4.Cu")
		(net "M_J_CPU1_SA_DQ<13>")
	)
	(segment
		(start 182.146194 -213.910418)
		(end 189.02172 -213.910418)
		(width 0.14478)
		(layer "In4.Cu")
		(net "M_J_CPU1_SA_DQ<13>")
	)
	(segment
		(start 166.222172 -214.760302)
		(end 167.072056 -213.910418)
		(width 0.14478)
		(layer "In4.Cu")
		(net "M_J_CPU1_SA_DQ<13>")
	)
	(segment
		(start 139.31773 -234.2769)
		(end 139.326112 -234.281726)
		(width 0.0889)
		(layer "In4.Cu")
		(net "M_J_CPU1_SA_DQ<13>")
	)
	(segment
		(start 145.74647 -233.318304)
		(end 147.389088 -231.675686)
		(width 0.0889)
		(layer "In4.Cu")
		(net "M_J_CPU1_SA_DQ<13>")
	)
	(segment
		(start 142.503398 -234.281726)
		(end 142.51178 -234.2769)
		(width 0.0889)
		(layer "In4.Cu")
		(net "M_J_CPU1_SA_DQ<13>")
	)
	(segment
		(start 147.39493 -231.675686)
		(end 147.95627 -231.114346)
		(width 0.0889)
		(layer "In4.Cu")
		(net "M_J_CPU1_SA_DQ<13>")
	)
	(segment
		(start 177.621438 -213.910418)
		(end 178.471322 -214.760302)
		(width 0.14478)
		(layer "In4.Cu")
		(net "M_J_CPU1_SA_DQ<13>")
	)
	(segment
		(start 167.072056 -213.910418)
		(end 169.67962 -213.910418)
		(width 0.14478)
		(layer "In4.Cu")
		(net "M_J_CPU1_SA_DQ<13>")
	)
	(segment
		(start 135.557768 -234.2769)
		(end 135.56615 -234.281726)
		(width 0.0889)
		(layer "In4.Cu")
		(net "M_J_CPU1_SA_DQ<13>")
	)
	(segment
		(start 178.471322 -214.760302)
		(end 181.29631 -214.760302)
		(width 0.14478)
		(layer "In4.Cu")
		(net "M_J_CPU1_SA_DQ<13>")
	)
	(segment
		(start 143.451834 -234.2769)
		(end 143.466566 -234.268264)
		(width 0.0889)
		(layer "In4.Cu")
		(net "M_J_CPU1_SA_DQ<13>")
	)
	(segment
		(start 189.183264 -214.071962)
		(end 189.183264 -214.496142)
		(width 0.14478)
		(layer "In4.Cu")
		(net "M_J_CPU1_SA_DQ<13>")
	)
	(segment
		(start 156.844746 -219.219526)
		(end 161.30397 -214.760302)
		(width 0.14478)
		(layer "In4.Cu")
		(net "M_J_CPU1_SA_DQ<13>")
	)
	(segment
		(start 189.734698 -214.071962)
		(end 189.896242 -213.910418)
		(width 0.14478)
		(layer "In4.Cu")
		(net "M_J_CPU1_SA_DQ<13>")
	)
	(segment
		(start 189.896242 -213.910418)
		(end 190.735204 -213.910418)
		(width 0.14478)
		(layer "In4.Cu")
		(net "M_J_CPU1_SA_DQ<13>")
	)
	(segment
		(start 169.67962 -213.910418)
		(end 170.529504 -214.760302)
		(width 0.14478)
		(layer "In4.Cu")
		(net "M_J_CPU1_SA_DQ<13>")
	)
	(segment
		(start 134.04342 -234.281726)
		(end 134.051802 -234.2769)
		(width 0.0889)
		(layer "In4.Cu")
		(net "M_J_CPU1_SA_DQ<13>")
	)
	(segment
		(start 173.791118 -214.760302)
		(end 174.641002 -213.910418)
		(width 0.14478)
		(layer "In4.Cu")
		(net "M_J_CPU1_SA_DQ<13>")
	)
	(segment
		(start 181.29631 -214.760302)
		(end 182.146194 -213.910418)
		(width 0.14478)
		(layer "In4.Cu")
		(net "M_J_CPU1_SA_DQ<13>")
	)
	(segment
		(start 170.529504 -214.760302)
		(end 173.791118 -214.760302)
		(width 0.14478)
		(layer "In4.Cu")
		(net "M_J_CPU1_SA_DQ<13>")
	)
	(segment
		(start 131.198874 -234.21975)
		(end 131.29514 -234.24515)
		(width 0.0889)
		(layer "In4.Cu")
		(net "M_J_CPU1_SA_DQ<13>")
	)
	(segment
		(start 143.73479 -234.200446)
		(end 144.044162 -234.200446)
		(width 0.0889)
		(layer "In4.Cu")
		(net "M_J_CPU1_SA_DQ<13>")
	)
	(segment
		(start 144.926304 -233.318304)
		(end 145.74647 -233.318304)
		(width 0.0889)
		(layer "In4.Cu")
		(net "M_J_CPU1_SA_DQ<13>")
	)
	(segment
		(start 152.275794 -226.794822)
		(end 152.275794 -222.881698)
		(width 0.14478)
		(layer "In4.Cu")
		(net "M_J_CPU1_SA_DQ<13>")
	)
	(segment
		(start 155.937966 -219.219526)
		(end 156.844746 -219.219526)
		(width 0.14478)
		(layer "In4.Cu")
		(net "M_J_CPU1_SA_DQ<13>")
	)
	(segment
		(start 147.389088 -231.675686)
		(end 147.39493 -231.675686)
		(width 0.0889)
		(layer "In4.Cu")
		(net "M_J_CPU1_SA_DQ<13>")
	)
	(segment
		(start 138.743436 -234.281726)
		(end 138.751818 -234.2769)
		(width 0.0889)
		(layer "In4.Cu")
		(net "M_J_CPU1_SA_DQ<13>")
	)
	(arc
		(start 141.197838 -234.2769)
		(mid 141.384782 -234.327155)
		(end 141.571726 -234.2769)
		(width 0.0889)
		(layer "In4.Cu")
		(net "M_J_CPU1_SA_DQ<13>")
	)
	(arc
		(start 142.51178 -234.2769)
		(mid 142.794736 -234.200723)
		(end 143.077692 -234.2769)
		(width 0.0889)
		(layer "In4.Cu")
		(net "M_J_CPU1_SA_DQ<13>")
	)
	(arc
		(start 139.691872 -234.2769)
		(mid 139.974828 -234.200723)
		(end 140.257784 -234.2769)
		(width 0.0889)
		(layer "In4.Cu")
		(net "M_J_CPU1_SA_DQ<13>")
	)
	(arc
		(start 134.991856 -234.2769)
		(mid 135.274812 -234.200723)
		(end 135.557768 -234.2769)
		(width 0.0889)
		(layer "In4.Cu")
		(net "M_J_CPU1_SA_DQ<13>")
	)
	(arc
		(start 140.631926 -234.2769)
		(mid 140.914882 -234.200723)
		(end 141.197838 -234.2769)
		(width 0.0889)
		(layer "In4.Cu")
		(net "M_J_CPU1_SA_DQ<13>")
	)
	(arc
		(start 133.111748 -234.2769)
		(mid 133.394704 -234.200723)
		(end 133.67766 -234.2769)
		(width 0.0889)
		(layer "In4.Cu")
		(net "M_J_CPU1_SA_DQ<13>")
	)
	(arc
		(start 136.87171 -234.2769)
		(mid 137.154666 -234.200723)
		(end 137.437622 -234.2769)
		(width 0.0889)
		(layer "In4.Cu")
		(net "M_J_CPU1_SA_DQ<13>")
	)
	(arc
		(start 135.56615 -234.281726)
		(mid 135.749658 -234.32722)
		(end 135.93191 -234.2769)
		(width 0.0889)
		(layer "In4.Cu")
		(net "M_J_CPU1_SA_DQ<13>")
	)
	(arc
		(start 141.571726 -234.2769)
		(mid 141.854682 -234.200723)
		(end 142.137638 -234.2769)
		(width 0.0889)
		(layer "In4.Cu")
		(net "M_J_CPU1_SA_DQ<13>")
	)
	(arc
		(start 138.377676 -234.2769)
		(mid 138.559927 -234.32725)
		(end 138.743436 -234.281726)
		(width 0.0889)
		(layer "In4.Cu")
		(net "M_J_CPU1_SA_DQ<13>")
	)
	(arc
		(start 137.437622 -234.2769)
		(mid 137.619873 -234.32725)
		(end 137.803382 -234.281726)
		(width 0.0889)
		(layer "In4.Cu")
		(net "M_J_CPU1_SA_DQ<13>")
	)
	(arc
		(start 132.737606 -234.2769)
		(mid 132.919857 -234.32725)
		(end 133.103366 -234.281726)
		(width 0.0889)
		(layer "In4.Cu")
		(net "M_J_CPU1_SA_DQ<13>")
	)
	(arc
		(start 135.93191 -234.2769)
		(mid 136.214866 -234.200723)
		(end 136.497822 -234.2769)
		(width 0.0889)
		(layer "In4.Cu")
		(net "M_J_CPU1_SA_DQ<13>")
	)
	(arc
		(start 140.266166 -234.281726)
		(mid 140.449674 -234.32722)
		(end 140.631926 -234.2769)
		(width 0.0889)
		(layer "In4.Cu")
		(net "M_J_CPU1_SA_DQ<13>")
	)
	(arc
		(start 134.051802 -234.2769)
		(mid 134.334758 -234.200723)
		(end 134.617714 -234.2769)
		(width 0.0889)
		(layer "In4.Cu")
		(net "M_J_CPU1_SA_DQ<13>")
	)
	(arc
		(start 131.797806 -234.2769)
		(mid 131.98475 -234.327155)
		(end 132.171694 -234.2769)
		(width 0.0889)
		(layer "In4.Cu")
		(net "M_J_CPU1_SA_DQ<13>")
	)
	(arc
		(start 137.811764 -234.2769)
		(mid 138.09472 -234.200723)
		(end 138.377676 -234.2769)
		(width 0.0889)
		(layer "In4.Cu")
		(net "M_J_CPU1_SA_DQ<13>")
	)
	(arc
		(start 138.751818 -234.2769)
		(mid 139.034774 -234.200723)
		(end 139.31773 -234.2769)
		(width 0.0889)
		(layer "In4.Cu")
		(net "M_J_CPU1_SA_DQ<13>")
	)
	(arc
		(start 139.326112 -234.281726)
		(mid 139.50962 -234.32722)
		(end 139.691872 -234.2769)
		(width 0.0889)
		(layer "In4.Cu")
		(net "M_J_CPU1_SA_DQ<13>")
	)
	(arc
		(start 132.171694 -234.2769)
		(mid 132.45465 -234.200723)
		(end 132.737606 -234.2769)
		(width 0.0889)
		(layer "In4.Cu")
		(net "M_J_CPU1_SA_DQ<13>")
	)
	(arc
		(start 143.466566 -234.268264)
		(mid 143.596451 -234.217623)
		(end 143.73479 -234.200446)
		(width 0.0889)
		(layer "In4.Cu")
		(net "M_J_CPU1_SA_DQ<13>")
	)
	(arc
		(start 142.137638 -234.2769)
		(mid 142.319889 -234.32725)
		(end 142.503398 -234.281726)
		(width 0.0889)
		(layer "In4.Cu")
		(net "M_J_CPU1_SA_DQ<13>")
	)
	(arc
		(start 143.086074 -234.281726)
		(mid 143.269582 -234.32722)
		(end 143.451834 -234.2769)
		(width 0.0889)
		(layer "In4.Cu")
		(net "M_J_CPU1_SA_DQ<13>")
	)
	(arc
		(start 131.29514 -234.24515)
		(mid 131.550205 -234.201799)
		(end 131.797806 -234.2769)
		(width 0.0889)
		(layer "In4.Cu")
		(net "M_J_CPU1_SA_DQ<13>")
	)
	(arc
		(start 133.67766 -234.2769)
		(mid 133.859911 -234.32725)
		(end 134.04342 -234.281726)
		(width 0.0889)
		(layer "In4.Cu")
		(net "M_J_CPU1_SA_DQ<13>")
	)
	(arc
		(start 134.626096 -234.281726)
		(mid 134.809604 -234.32722)
		(end 134.991856 -234.2769)
		(width 0.0889)
		(layer "In4.Cu")
		(net "M_J_CPU1_SA_DQ<13>")
	)
	(arc
		(start 136.497822 -234.2769)
		(mid 136.684766 -234.327155)
		(end 136.87171 -234.2769)
		(width 0.0889)
		(layer "In4.Cu")
		(net "M_J_CPU1_SA_DQ<13>")
	)
	(segment
		(start 131.987798 -233.410252)
		(end 132.45465 -233.144314)
		(width 0.10668)
		(layer "F.Cu")
		(net "M_J_CPU1_SA_DQ<12>")
	)
	(segment
		(start 146.050508 -232.053384)
		(end 146.050508 -231.563164)
		(width 0.0889)
		(layer "In4.Cu")
		(net "M_J_CPU1_SA_DQ<12>")
	)
	(segment
		(start 146.050508 -231.563164)
		(end 147.245578 -230.368094)
		(width 0.0889)
		(layer "In4.Cu")
		(net "M_J_CPU1_SA_DQ<12>")
	)
	(segment
		(start 178.215798 -213.069932)
		(end 181.525672 -213.069932)
		(width 0.14478)
		(layer "In4.Cu")
		(net "M_J_CPU1_SA_DQ<12>")
	)
	(segment
		(start 189.546484 -212.220048)
		(end 189.708028 -212.381592)
		(width 0.14478)
		(layer "In4.Cu")
		(net "M_J_CPU1_SA_DQ<12>")
	)
	(segment
		(start 151.376634 -226.237038)
		(end 151.376634 -222.508826)
		(width 0.14478)
		(layer "In4.Cu")
		(net "M_J_CPU1_SA_DQ<12>")
	)
	(segment
		(start 177.365914 -212.220048)
		(end 178.215798 -213.069932)
		(width 0.14478)
		(layer "In4.Cu")
		(net "M_J_CPU1_SA_DQ<12>")
	)
	(segment
		(start 166.10711 -213.283546)
		(end 167.18026 -212.210396)
		(width 0.14478)
		(layer "In4.Cu")
		(net "M_J_CPU1_SA_DQ<12>")
	)
	(segment
		(start 167.18026 -212.210396)
		(end 169.546016 -212.210396)
		(width 0.14478)
		(layer "In4.Cu")
		(net "M_J_CPU1_SA_DQ<12>")
	)
	(segment
		(start 169.546016 -212.210396)
		(end 170.405552 -213.069932)
		(width 0.14478)
		(layer "In4.Cu")
		(net "M_J_CPU1_SA_DQ<12>")
	)
	(segment
		(start 189.869572 -212.996526)
		(end 190.097918 -212.996526)
		(width 0.14478)
		(layer "In4.Cu")
		(net "M_J_CPU1_SA_DQ<12>")
	)
	(segment
		(start 135.453374 -233.47172)
		(end 135.461756 -233.466894)
		(width 0.0889)
		(layer "In4.Cu")
		(net "M_J_CPU1_SA_DQ<12>")
	)
	(segment
		(start 174.493428 -212.220048)
		(end 177.365914 -212.220048)
		(width 0.14478)
		(layer "In4.Cu")
		(net "M_J_CPU1_SA_DQ<12>")
	)
	(segment
		(start 144.652492 -232.736644)
		(end 145.367248 -232.736644)
		(width 0.0889)
		(layer "In4.Cu")
		(net "M_J_CPU1_SA_DQ<12>")
	)
	(segment
		(start 160.601914 -213.283546)
		(end 166.10711 -213.283546)
		(width 0.14478)
		(layer "In4.Cu")
		(net "M_J_CPU1_SA_DQ<12>")
	)
	(segment
		(start 141.667738 -233.466894)
		(end 141.67612 -233.47172)
		(width 0.0889)
		(layer "In4.Cu")
		(net "M_J_CPU1_SA_DQ<12>")
	)
	(segment
		(start 132.608828 -233.409744)
		(end 132.705094 -233.435144)
		(width 0.0889)
		(layer "In4.Cu")
		(net "M_J_CPU1_SA_DQ<12>")
	)
	(segment
		(start 137.907776 -233.466894)
		(end 137.916158 -233.47172)
		(width 0.0889)
		(layer "In4.Cu")
		(net "M_J_CPU1_SA_DQ<12>")
	)
	(segment
		(start 190.744856 -212.220048)
		(end 191.160146 -212.635338)
		(width 0.14478)
		(layer "In4.Cu")
		(net "M_J_CPU1_SA_DQ<12>")
	)
	(segment
		(start 143.547592 -233.466894)
		(end 143.555974 -233.47172)
		(width 0.0889)
		(layer "In4.Cu")
		(net "M_J_CPU1_SA_DQ<12>")
	)
	(segment
		(start 151.376634 -222.508826)
		(end 160.601914 -213.283546)
		(width 0.14478)
		(layer "In4.Cu")
		(net "M_J_CPU1_SA_DQ<12>")
	)
	(segment
		(start 190.259462 -212.834982)
		(end 190.259462 -212.381592)
		(width 0.14478)
		(layer "In4.Cu")
		(net "M_J_CPU1_SA_DQ<12>")
	)
	(segment
		(start 136.393428 -233.47172)
		(end 136.40181 -233.466894)
		(width 0.0889)
		(layer "In4.Cu")
		(net "M_J_CPU1_SA_DQ<12>")
	)
	(segment
		(start 170.405552 -213.069932)
		(end 173.643544 -213.069932)
		(width 0.14478)
		(layer "In4.Cu")
		(net "M_J_CPU1_SA_DQ<12>")
	)
	(segment
		(start 181.525672 -213.069932)
		(end 182.375556 -212.220048)
		(width 0.14478)
		(layer "In4.Cu")
		(net "M_J_CPU1_SA_DQ<12>")
	)
	(segment
		(start 173.643544 -213.069932)
		(end 174.493428 -212.220048)
		(width 0.14478)
		(layer "In4.Cu")
		(net "M_J_CPU1_SA_DQ<12>")
	)
	(segment
		(start 190.421006 -212.220048)
		(end 190.744856 -212.220048)
		(width 0.14478)
		(layer "In4.Cu")
		(net "M_J_CPU1_SA_DQ<12>")
	)
	(segment
		(start 133.20776 -233.466894)
		(end 133.216142 -233.47172)
		(width 0.0889)
		(layer "In4.Cu")
		(net "M_J_CPU1_SA_DQ<12>")
	)
	(segment
		(start 147.245578 -230.368094)
		(end 151.376634 -226.237038)
		(width 0.14478)
		(layer "In4.Cu")
		(net "M_J_CPU1_SA_DQ<12>")
	)
	(segment
		(start 145.367248 -232.736644)
		(end 146.050508 -232.053384)
		(width 0.0889)
		(layer "In4.Cu")
		(net "M_J_CPU1_SA_DQ<12>")
	)
	(segment
		(start 190.097918 -212.996526)
		(end 190.259462 -212.834982)
		(width 0.14478)
		(layer "In4.Cu")
		(net "M_J_CPU1_SA_DQ<12>")
	)
	(segment
		(start 190.259462 -212.381592)
		(end 190.421006 -212.220048)
		(width 0.14478)
		(layer "In4.Cu")
		(net "M_J_CPU1_SA_DQ<12>")
	)
	(segment
		(start 141.093444 -233.47172)
		(end 141.101826 -233.466894)
		(width 0.0889)
		(layer "In4.Cu")
		(net "M_J_CPU1_SA_DQ<12>")
	)
	(segment
		(start 182.375556 -212.220048)
		(end 189.546484 -212.220048)
		(width 0.14478)
		(layer "In4.Cu")
		(net "M_J_CPU1_SA_DQ<12>")
	)
	(segment
		(start 143.922242 -233.466894)
		(end 144.652492 -232.736644)
		(width 0.0889)
		(layer "In4.Cu")
		(net "M_J_CPU1_SA_DQ<12>")
	)
	(segment
		(start 140.15339 -233.47172)
		(end 140.161772 -233.466894)
		(width 0.0889)
		(layer "In4.Cu")
		(net "M_J_CPU1_SA_DQ<12>")
	)
	(segment
		(start 132.45465 -233.144314)
		(end 132.608828 -233.409744)
		(width 0.0889)
		(layer "In4.Cu")
		(net "M_J_CPU1_SA_DQ<12>")
	)
	(segment
		(start 189.708028 -212.381592)
		(end 189.708028 -212.834982)
		(width 0.14478)
		(layer "In4.Cu")
		(net "M_J_CPU1_SA_DQ<12>")
	)
	(segment
		(start 189.708028 -212.834982)
		(end 189.869572 -212.996526)
		(width 0.14478)
		(layer "In4.Cu")
		(net "M_J_CPU1_SA_DQ<12>")
	)
	(segment
		(start 136.967722 -233.466894)
		(end 136.976104 -233.47172)
		(width 0.0889)
		(layer "In4.Cu")
		(net "M_J_CPU1_SA_DQ<12>")
	)
	(arc
		(start 136.976104 -233.47172)
		(mid 137.159612 -233.517214)
		(end 137.341864 -233.466894)
		(width 0.0889)
		(layer "In4.Cu")
		(net "M_J_CPU1_SA_DQ<12>")
	)
	(arc
		(start 135.087614 -233.466894)
		(mid 135.269865 -233.517244)
		(end 135.453374 -233.47172)
		(width 0.0889)
		(layer "In4.Cu")
		(net "M_J_CPU1_SA_DQ<12>")
	)
	(arc
		(start 133.216142 -233.47172)
		(mid 133.39965 -233.517214)
		(end 133.581902 -233.466894)
		(width 0.0889)
		(layer "In4.Cu")
		(net "M_J_CPU1_SA_DQ<12>")
	)
	(arc
		(start 134.147814 -233.466894)
		(mid 134.334758 -233.517149)
		(end 134.521702 -233.466894)
		(width 0.0889)
		(layer "In4.Cu")
		(net "M_J_CPU1_SA_DQ<12>")
	)
	(arc
		(start 143.555974 -233.47172)
		(mid 143.739736 -233.517336)
		(end 143.922242 -233.466894)
		(width 0.0889)
		(layer "In4.Cu")
		(net "M_J_CPU1_SA_DQ<12>")
	)
	(arc
		(start 137.341864 -233.466894)
		(mid 137.62482 -233.390717)
		(end 137.907776 -233.466894)
		(width 0.0889)
		(layer "In4.Cu")
		(net "M_J_CPU1_SA_DQ<12>")
	)
	(arc
		(start 142.98168 -233.466894)
		(mid 143.264636 -233.390717)
		(end 143.547592 -233.466894)
		(width 0.0889)
		(layer "In4.Cu")
		(net "M_J_CPU1_SA_DQ<12>")
	)
	(arc
		(start 134.521702 -233.466894)
		(mid 134.804658 -233.390717)
		(end 135.087614 -233.466894)
		(width 0.0889)
		(layer "In4.Cu")
		(net "M_J_CPU1_SA_DQ<12>")
	)
	(arc
		(start 135.461756 -233.466894)
		(mid 135.744712 -233.390717)
		(end 136.027668 -233.466894)
		(width 0.0889)
		(layer "In4.Cu")
		(net "M_J_CPU1_SA_DQ<12>")
	)
	(arc
		(start 138.84783 -233.466894)
		(mid 139.034774 -233.517149)
		(end 139.221718 -233.466894)
		(width 0.0889)
		(layer "In4.Cu")
		(net "M_J_CPU1_SA_DQ<12>")
	)
	(arc
		(start 138.281918 -233.466894)
		(mid 138.564874 -233.390717)
		(end 138.84783 -233.466894)
		(width 0.0889)
		(layer "In4.Cu")
		(net "M_J_CPU1_SA_DQ<12>")
	)
	(arc
		(start 133.581902 -233.466894)
		(mid 133.864858 -233.390717)
		(end 134.147814 -233.466894)
		(width 0.0889)
		(layer "In4.Cu")
		(net "M_J_CPU1_SA_DQ<12>")
	)
	(arc
		(start 141.101826 -233.466894)
		(mid 141.384782 -233.390717)
		(end 141.667738 -233.466894)
		(width 0.0889)
		(layer "In4.Cu")
		(net "M_J_CPU1_SA_DQ<12>")
	)
	(arc
		(start 142.04188 -233.466894)
		(mid 142.324836 -233.390717)
		(end 142.607792 -233.466894)
		(width 0.0889)
		(layer "In4.Cu")
		(net "M_J_CPU1_SA_DQ<12>")
	)
	(arc
		(start 132.705094 -233.435144)
		(mid 132.960159 -233.391793)
		(end 133.20776 -233.466894)
		(width 0.0889)
		(layer "In4.Cu")
		(net "M_J_CPU1_SA_DQ<12>")
	)
	(arc
		(start 139.78763 -233.466894)
		(mid 139.969881 -233.517244)
		(end 140.15339 -233.47172)
		(width 0.0889)
		(layer "In4.Cu")
		(net "M_J_CPU1_SA_DQ<12>")
	)
	(arc
		(start 136.027668 -233.466894)
		(mid 136.209919 -233.517244)
		(end 136.393428 -233.47172)
		(width 0.0889)
		(layer "In4.Cu")
		(net "M_J_CPU1_SA_DQ<12>")
	)
	(arc
		(start 139.221718 -233.466894)
		(mid 139.504674 -233.390717)
		(end 139.78763 -233.466894)
		(width 0.0889)
		(layer "In4.Cu")
		(net "M_J_CPU1_SA_DQ<12>")
	)
	(arc
		(start 140.727684 -233.466894)
		(mid 140.909935 -233.517244)
		(end 141.093444 -233.47172)
		(width 0.0889)
		(layer "In4.Cu")
		(net "M_J_CPU1_SA_DQ<12>")
	)
	(arc
		(start 136.40181 -233.466894)
		(mid 136.684766 -233.390717)
		(end 136.967722 -233.466894)
		(width 0.0889)
		(layer "In4.Cu")
		(net "M_J_CPU1_SA_DQ<12>")
	)
	(arc
		(start 141.67612 -233.47172)
		(mid 141.859628 -233.517214)
		(end 142.04188 -233.466894)
		(width 0.0889)
		(layer "In4.Cu")
		(net "M_J_CPU1_SA_DQ<12>")
	)
	(arc
		(start 137.916158 -233.47172)
		(mid 138.099666 -233.517214)
		(end 138.281918 -233.466894)
		(width 0.0889)
		(layer "In4.Cu")
		(net "M_J_CPU1_SA_DQ<12>")
	)
	(arc
		(start 140.161772 -233.466894)
		(mid 140.444728 -233.390717)
		(end 140.727684 -233.466894)
		(width 0.0889)
		(layer "In4.Cu")
		(net "M_J_CPU1_SA_DQ<12>")
	)
	(arc
		(start 142.607792 -233.466894)
		(mid 142.794736 -233.517149)
		(end 142.98168 -233.466894)
		(width 0.0889)
		(layer "In4.Cu")
		(net "M_J_CPU1_SA_DQ<12>")
	)
	(segment
		(start 131.047998 -231.79024)
		(end 131.51485 -231.524302)
		(width 0.10668)
		(layer "F.Cu")
		(net "M_J_CPU1_SA_DQ<11>")
	)
	(segment
		(start 150.011384 -220.047312)
		(end 150.011384 -219.818712)
		(width 0.14478)
		(layer "In4.Cu")
		(net "M_J_CPU1_SA_DQ<11>")
	)
	(segment
		(start 150.011384 -219.818712)
		(end 150.172928 -219.657168)
		(width 0.14478)
		(layer "In4.Cu")
		(net "M_J_CPU1_SA_DQ<11>")
	)
	(segment
		(start 152.371044 -218.276932)
		(end 152.532588 -218.115388)
		(width 0.14478)
		(layer "In4.Cu")
		(net "M_J_CPU1_SA_DQ<11>")
	)
	(segment
		(start 149.231096 -220.8276)
		(end 149.231096 -220.599)
		(width 0.14478)
		(layer "In4.Cu")
		(net "M_J_CPU1_SA_DQ<11>")
	)
	(segment
		(start 133.20776 -231.201976)
		(end 133.216142 -231.19715)
		(width 0.0889)
		(layer "In4.Cu")
		(net "M_J_CPU1_SA_DQ<11>")
	)
	(segment
		(start 152.532588 -217.886788)
		(end 152.352248 -217.706448)
		(width 0.14478)
		(layer "In4.Cu")
		(net "M_J_CPU1_SA_DQ<11>")
	)
	(segment
		(start 151.733504 -218.096592)
		(end 151.962104 -218.096592)
		(width 0.14478)
		(layer "In4.Cu")
		(net "M_J_CPU1_SA_DQ<11>")
	)
	(segment
		(start 181.97576 -208.8007)
		(end 186.625484 -208.8007)
		(width 0.14478)
		(layer "In4.Cu")
		(net "M_J_CPU1_SA_DQ<11>")
	)
	(segment
		(start 150.972012 -219.675964)
		(end 150.972012 -219.447364)
		(width 0.14478)
		(layer "In4.Cu")
		(net "M_J_CPU1_SA_DQ<11>")
	)
	(segment
		(start 186.625484 -208.8007)
		(end 187.060078 -209.235294)
		(width 0.14478)
		(layer "In4.Cu")
		(net "M_J_CPU1_SA_DQ<11>")
	)
	(segment
		(start 144.39265 -230.182166)
		(end 144.769332 -229.805484)
		(width 0.0889)
		(layer "In4.Cu")
		(net "M_J_CPU1_SA_DQ<11>")
	)
	(segment
		(start 151.57196 -218.486736)
		(end 151.57196 -218.258136)
		(width 0.14478)
		(layer "In4.Cu")
		(net "M_J_CPU1_SA_DQ<11>")
	)
	(segment
		(start 137.907776 -231.201976)
		(end 137.916158 -231.19715)
		(width 0.0889)
		(layer "In4.Cu")
		(net "M_J_CPU1_SA_DQ<11>")
	)
	(segment
		(start 136.393428 -231.19715)
		(end 136.40181 -231.201976)
		(width 0.0889)
		(layer "In4.Cu")
		(net "M_J_CPU1_SA_DQ<11>")
	)
	(segment
		(start 149.411436 -221.23654)
		(end 149.411436 -221.00794)
		(width 0.14478)
		(layer "In4.Cu")
		(net "M_J_CPU1_SA_DQ<11>")
	)
	(segment
		(start 152.352248 -217.477848)
		(end 152.513792 -217.316304)
		(width 0.14478)
		(layer "In4.Cu")
		(net "M_J_CPU1_SA_DQ<11>")
	)
	(segment
		(start 152.532588 -218.115388)
		(end 152.532588 -217.886788)
		(width 0.14478)
		(layer "In4.Cu")
		(net "M_J_CPU1_SA_DQ<11>")
	)
	(segment
		(start 173.406308 -209.650584)
		(end 174.256192 -208.8007)
		(width 0.14478)
		(layer "In4.Cu")
		(net "M_J_CPU1_SA_DQ<11>")
	)
	(segment
		(start 149.80158 -220.617796)
		(end 150.03018 -220.617796)
		(width 0.14478)
		(layer "In4.Cu")
		(net "M_J_CPU1_SA_DQ<11>")
	)
	(segment
		(start 178.124358 -208.8007)
		(end 178.974496 -209.650838)
		(width 0.14478)
		(layer "In4.Cu")
		(net "M_J_CPU1_SA_DQ<11>")
	)
	(segment
		(start 145.63471 -229.136702)
		(end 145.63471 -228.52634)
		(width 0.0889)
		(layer "In4.Cu")
		(net "M_J_CPU1_SA_DQ<11>")
	)
	(segment
		(start 152.352248 -217.706448)
		(end 152.352248 -217.477848)
		(width 0.14478)
		(layer "In4.Cu")
		(net "M_J_CPU1_SA_DQ<11>")
	)
	(segment
		(start 136.967722 -231.201976)
		(end 136.976104 -231.19715)
		(width 0.0889)
		(layer "In4.Cu")
		(net "M_J_CPU1_SA_DQ<11>")
	)
	(segment
		(start 170.199812 -208.810352)
		(end 171.040044 -209.650584)
		(width 0.14478)
		(layer "In4.Cu")
		(net "M_J_CPU1_SA_DQ<11>")
	)
	(segment
		(start 135.453374 -231.19715)
		(end 135.461756 -231.201976)
		(width 0.0889)
		(layer "In4.Cu")
		(net "M_J_CPU1_SA_DQ<11>")
	)
	(segment
		(start 131.360672 -231.258872)
		(end 131.38277 -231.175814)
		(width 0.0889)
		(layer "In4.Cu")
		(net "M_J_CPU1_SA_DQ<11>")
	)
	(segment
		(start 151.590756 -219.05722)
		(end 151.7523 -218.895676)
		(width 0.14478)
		(layer "In4.Cu")
		(net "M_J_CPU1_SA_DQ<11>")
	)
	(segment
		(start 150.810468 -219.837508)
		(end 150.972012 -219.675964)
		(width 0.14478)
		(layer "In4.Cu")
		(net "M_J_CPU1_SA_DQ<11>")
	)
	(segment
		(start 150.03018 -220.617796)
		(end 150.191724 -220.456252)
		(width 0.14478)
		(layer "In4.Cu")
		(net "M_J_CPU1_SA_DQ<11>")
	)
	(segment
		(start 151.7523 -218.895676)
		(end 151.7523 -218.667076)
		(width 0.14478)
		(layer "In4.Cu")
		(net "M_J_CPU1_SA_DQ<11>")
	)
	(segment
		(start 150.972012 -219.447364)
		(end 150.791672 -219.267024)
		(width 0.14478)
		(layer "In4.Cu")
		(net "M_J_CPU1_SA_DQ<11>")
	)
	(segment
		(start 151.181816 -218.87688)
		(end 151.362156 -219.05722)
		(width 0.14478)
		(layer "In4.Cu")
		(net "M_J_CPU1_SA_DQ<11>")
	)
	(segment
		(start 178.974496 -209.650838)
		(end 181.125622 -209.650838)
		(width 0.14478)
		(layer "In4.Cu")
		(net "M_J_CPU1_SA_DQ<11>")
	)
	(segment
		(start 152.922732 -217.496644)
		(end 153.151332 -217.496644)
		(width 0.14478)
		(layer "In4.Cu")
		(net "M_J_CPU1_SA_DQ<11>")
	)
	(segment
		(start 131.693412 -231.19715)
		(end 131.701794 -231.201976)
		(width 0.0889)
		(layer "In4.Cu")
		(net "M_J_CPU1_SA_DQ<11>")
	)
	(segment
		(start 151.962104 -218.096592)
		(end 152.142444 -218.276932)
		(width 0.14478)
		(layer "In4.Cu")
		(net "M_J_CPU1_SA_DQ<11>")
	)
	(segment
		(start 166.065708 -209.66049)
		(end 166.915846 -208.810352)
		(width 0.14478)
		(layer "In4.Cu")
		(net "M_J_CPU1_SA_DQ<11>")
	)
	(segment
		(start 140.15339 -231.19715)
		(end 140.161772 -231.201976)
		(width 0.0889)
		(layer "In4.Cu")
		(net "M_J_CPU1_SA_DQ<11>")
	)
	(segment
		(start 144.769332 -229.805484)
		(end 144.965928 -229.805484)
		(width 0.0889)
		(layer "In4.Cu")
		(net "M_J_CPU1_SA_DQ<11>")
	)
	(segment
		(start 143.547592 -231.201976)
		(end 143.586708 -231.179116)
		(width 0.0889)
		(layer "In4.Cu")
		(net "M_J_CPU1_SA_DQ<11>")
	)
	(segment
		(start 150.401528 -219.657168)
		(end 150.581868 -219.837508)
		(width 0.14478)
		(layer "In4.Cu")
		(net "M_J_CPU1_SA_DQ<11>")
	)
	(segment
		(start 150.191724 -220.227652)
		(end 150.011384 -220.047312)
		(width 0.14478)
		(layer "In4.Cu")
		(net "M_J_CPU1_SA_DQ<11>")
	)
	(segment
		(start 153.151332 -217.496644)
		(end 160.987486 -209.66049)
		(width 0.14478)
		(layer "In4.Cu")
		(net "M_J_CPU1_SA_DQ<11>")
	)
	(segment
		(start 132.267706 -231.201976)
		(end 132.276088 -231.19715)
		(width 0.0889)
		(layer "In4.Cu")
		(net "M_J_CPU1_SA_DQ<11>")
	)
	(segment
		(start 166.915846 -208.810352)
		(end 170.199812 -208.810352)
		(width 0.14478)
		(layer "In4.Cu")
		(net "M_J_CPU1_SA_DQ<11>")
	)
	(segment
		(start 131.51485 -231.524302)
		(end 131.360672 -231.258872)
		(width 0.0889)
		(layer "In4.Cu")
		(net "M_J_CPU1_SA_DQ<11>")
	)
	(segment
		(start 149.411436 -221.00794)
		(end 149.231096 -220.8276)
		(width 0.14478)
		(layer "In4.Cu")
		(net "M_J_CPU1_SA_DQ<11>")
	)
	(segment
		(start 174.256192 -208.8007)
		(end 178.124358 -208.8007)
		(width 0.14478)
		(layer "In4.Cu")
		(net "M_J_CPU1_SA_DQ<11>")
	)
	(segment
		(start 160.987486 -209.66049)
		(end 166.065708 -209.66049)
		(width 0.14478)
		(layer "In4.Cu")
		(net "M_J_CPU1_SA_DQ<11>")
	)
	(segment
		(start 143.98498 -230.41102)
		(end 144.39265 -230.182166)
		(width 0.0889)
		(layer "In4.Cu")
		(net "M_J_CPU1_SA_DQ<11>")
	)
	(segment
		(start 149.62124 -220.437456)
		(end 149.80158 -220.617796)
		(width 0.14478)
		(layer "In4.Cu")
		(net "M_J_CPU1_SA_DQ<11>")
	)
	(segment
		(start 181.125622 -209.650838)
		(end 181.97576 -208.8007)
		(width 0.14478)
		(layer "In4.Cu")
		(net "M_J_CPU1_SA_DQ<11>")
	)
	(segment
		(start 149.088094 -225.072956)
		(end 149.088094 -221.559882)
		(width 0.14478)
		(layer "In4.Cu")
		(net "M_J_CPU1_SA_DQ<11>")
	)
	(segment
		(start 147.586192 -226.574858)
		(end 149.088094 -225.072956)
		(width 0.14478)
		(layer "In4.Cu")
		(net "M_J_CPU1_SA_DQ<11>")
	)
	(segment
		(start 144.965928 -229.805484)
		(end 145.63471 -229.136702)
		(width 0.0889)
		(layer "In4.Cu")
		(net "M_J_CPU1_SA_DQ<11>")
	)
	(segment
		(start 150.172928 -219.657168)
		(end 150.401528 -219.657168)
		(width 0.14478)
		(layer "In4.Cu")
		(net "M_J_CPU1_SA_DQ<11>")
	)
	(segment
		(start 151.362156 -219.05722)
		(end 151.590756 -219.05722)
		(width 0.14478)
		(layer "In4.Cu")
		(net "M_J_CPU1_SA_DQ<11>")
	)
	(segment
		(start 141.667738 -231.201976)
		(end 141.67612 -231.19715)
		(width 0.0889)
		(layer "In4.Cu")
		(net "M_J_CPU1_SA_DQ<11>")
	)
	(segment
		(start 171.040044 -209.650584)
		(end 173.406308 -209.650584)
		(width 0.14478)
		(layer "In4.Cu")
		(net "M_J_CPU1_SA_DQ<11>")
	)
	(segment
		(start 141.093444 -231.19715)
		(end 141.101826 -231.201976)
		(width 0.0889)
		(layer "In4.Cu")
		(net "M_J_CPU1_SA_DQ<11>")
	)
	(segment
		(start 150.581868 -219.837508)
		(end 150.810468 -219.837508)
		(width 0.14478)
		(layer "In4.Cu")
		(net "M_J_CPU1_SA_DQ<11>")
	)
	(segment
		(start 150.953216 -218.87688)
		(end 151.181816 -218.87688)
		(width 0.14478)
		(layer "In4.Cu")
		(net "M_J_CPU1_SA_DQ<11>")
	)
	(segment
		(start 152.742392 -217.316304)
		(end 152.922732 -217.496644)
		(width 0.14478)
		(layer "In4.Cu")
		(net "M_J_CPU1_SA_DQ<11>")
	)
	(segment
		(start 150.791672 -219.267024)
		(end 150.791672 -219.038424)
		(width 0.14478)
		(layer "In4.Cu")
		(net "M_J_CPU1_SA_DQ<11>")
	)
	(segment
		(start 151.57196 -218.258136)
		(end 151.733504 -218.096592)
		(width 0.14478)
		(layer "In4.Cu")
		(net "M_J_CPU1_SA_DQ<11>")
	)
	(segment
		(start 145.63471 -228.52634)
		(end 147.586192 -226.574858)
		(width 0.0889)
		(layer "In4.Cu")
		(net "M_J_CPU1_SA_DQ<11>")
	)
	(segment
		(start 149.39264 -220.437456)
		(end 149.62124 -220.437456)
		(width 0.14478)
		(layer "In4.Cu")
		(net "M_J_CPU1_SA_DQ<11>")
	)
	(segment
		(start 150.191724 -220.456252)
		(end 150.191724 -220.227652)
		(width 0.14478)
		(layer "In4.Cu")
		(net "M_J_CPU1_SA_DQ<11>")
	)
	(segment
		(start 152.513792 -217.316304)
		(end 152.742392 -217.316304)
		(width 0.14478)
		(layer "In4.Cu")
		(net "M_J_CPU1_SA_DQ<11>")
	)
	(segment
		(start 152.142444 -218.276932)
		(end 152.371044 -218.276932)
		(width 0.14478)
		(layer "In4.Cu")
		(net "M_J_CPU1_SA_DQ<11>")
	)
	(segment
		(start 149.088094 -221.559882)
		(end 149.411436 -221.23654)
		(width 0.14478)
		(layer "In4.Cu")
		(net "M_J_CPU1_SA_DQ<11>")
	)
	(segment
		(start 149.231096 -220.599)
		(end 149.39264 -220.437456)
		(width 0.14478)
		(layer "In4.Cu")
		(net "M_J_CPU1_SA_DQ<11>")
	)
	(segment
		(start 151.7523 -218.667076)
		(end 151.57196 -218.486736)
		(width 0.14478)
		(layer "In4.Cu")
		(net "M_J_CPU1_SA_DQ<11>")
	)
	(segment
		(start 150.791672 -219.038424)
		(end 150.953216 -218.87688)
		(width 0.14478)
		(layer "In4.Cu")
		(net "M_J_CPU1_SA_DQ<11>")
	)
	(arc
		(start 135.461756 -231.201976)
		(mid 135.744712 -231.278153)
		(end 136.027668 -231.201976)
		(width 0.0889)
		(layer "In4.Cu")
		(net "M_J_CPU1_SA_DQ<11>")
	)
	(arc
		(start 134.521702 -231.201976)
		(mid 134.804658 -231.278153)
		(end 135.087614 -231.201976)
		(width 0.0889)
		(layer "In4.Cu")
		(net "M_J_CPU1_SA_DQ<11>")
	)
	(arc
		(start 141.101826 -231.201976)
		(mid 141.384782 -231.278153)
		(end 141.667738 -231.201976)
		(width 0.0889)
		(layer "In4.Cu")
		(net "M_J_CPU1_SA_DQ<11>")
	)
	(arc
		(start 143.586708 -231.179116)
		(mid 143.765521 -230.976766)
		(end 143.83004 -230.71455)
		(width 0.0889)
		(layer "In4.Cu")
		(net "M_J_CPU1_SA_DQ<11>")
	)
	(arc
		(start 142.04188 -231.201976)
		(mid 142.324836 -231.278153)
		(end 142.607792 -231.201976)
		(width 0.0889)
		(layer "In4.Cu")
		(net "M_J_CPU1_SA_DQ<11>")
	)
	(arc
		(start 136.976104 -231.19715)
		(mid 137.159612 -231.151625)
		(end 137.341864 -231.201976)
		(width 0.0889)
		(layer "In4.Cu")
		(net "M_J_CPU1_SA_DQ<11>")
	)
	(arc
		(start 137.341864 -231.201976)
		(mid 137.62482 -231.278153)
		(end 137.907776 -231.201976)
		(width 0.0889)
		(layer "In4.Cu")
		(net "M_J_CPU1_SA_DQ<11>")
	)
	(arc
		(start 140.161772 -231.201976)
		(mid 140.444728 -231.278153)
		(end 140.727684 -231.201976)
		(width 0.0889)
		(layer "In4.Cu")
		(net "M_J_CPU1_SA_DQ<11>")
	)
	(arc
		(start 138.281918 -231.201976)
		(mid 138.564874 -231.278153)
		(end 138.84783 -231.201976)
		(width 0.0889)
		(layer "In4.Cu")
		(net "M_J_CPU1_SA_DQ<11>")
	)
	(arc
		(start 143.83004 -230.71455)
		(mid 143.871006 -230.544144)
		(end 143.98498 -230.41102)
		(width 0.0889)
		(layer "In4.Cu")
		(net "M_J_CPU1_SA_DQ<11>")
	)
	(arc
		(start 137.916158 -231.19715)
		(mid 138.099666 -231.151625)
		(end 138.281918 -231.201976)
		(width 0.0889)
		(layer "In4.Cu")
		(net "M_J_CPU1_SA_DQ<11>")
	)
	(arc
		(start 142.98168 -231.201976)
		(mid 143.264636 -231.278153)
		(end 143.547592 -231.201976)
		(width 0.0889)
		(layer "In4.Cu")
		(net "M_J_CPU1_SA_DQ<11>")
	)
	(arc
		(start 139.78763 -231.201976)
		(mid 139.969881 -231.151592)
		(end 140.15339 -231.19715)
		(width 0.0889)
		(layer "In4.Cu")
		(net "M_J_CPU1_SA_DQ<11>")
	)
	(arc
		(start 132.641848 -231.201976)
		(mid 132.924804 -231.278153)
		(end 133.20776 -231.201976)
		(width 0.0889)
		(layer "In4.Cu")
		(net "M_J_CPU1_SA_DQ<11>")
	)
	(arc
		(start 132.276088 -231.19715)
		(mid 132.459596 -231.151625)
		(end 132.641848 -231.201976)
		(width 0.0889)
		(layer "In4.Cu")
		(net "M_J_CPU1_SA_DQ<11>")
	)
	(arc
		(start 131.701794 -231.201976)
		(mid 131.98475 -231.278153)
		(end 132.267706 -231.201976)
		(width 0.0889)
		(layer "In4.Cu")
		(net "M_J_CPU1_SA_DQ<11>")
	)
	(arc
		(start 133.581902 -231.201976)
		(mid 133.864858 -231.278153)
		(end 134.147814 -231.201976)
		(width 0.0889)
		(layer "In4.Cu")
		(net "M_J_CPU1_SA_DQ<11>")
	)
	(arc
		(start 136.027668 -231.201976)
		(mid 136.209919 -231.151592)
		(end 136.393428 -231.19715)
		(width 0.0889)
		(layer "In4.Cu")
		(net "M_J_CPU1_SA_DQ<11>")
	)
	(arc
		(start 131.38277 -231.175814)
		(mid 131.540421 -231.152502)
		(end 131.693412 -231.19715)
		(width 0.0889)
		(layer "In4.Cu")
		(net "M_J_CPU1_SA_DQ<11>")
	)
	(arc
		(start 141.67612 -231.19715)
		(mid 141.859628 -231.151625)
		(end 142.04188 -231.201976)
		(width 0.0889)
		(layer "In4.Cu")
		(net "M_J_CPU1_SA_DQ<11>")
	)
	(arc
		(start 133.216142 -231.19715)
		(mid 133.39965 -231.151625)
		(end 133.581902 -231.201976)
		(width 0.0889)
		(layer "In4.Cu")
		(net "M_J_CPU1_SA_DQ<11>")
	)
	(arc
		(start 140.727684 -231.201976)
		(mid 140.909935 -231.151592)
		(end 141.093444 -231.19715)
		(width 0.0889)
		(layer "In4.Cu")
		(net "M_J_CPU1_SA_DQ<11>")
	)
	(arc
		(start 139.221718 -231.201976)
		(mid 139.504674 -231.278153)
		(end 139.78763 -231.201976)
		(width 0.0889)
		(layer "In4.Cu")
		(net "M_J_CPU1_SA_DQ<11>")
	)
	(arc
		(start 135.087614 -231.201976)
		(mid 135.269865 -231.151592)
		(end 135.453374 -231.19715)
		(width 0.0889)
		(layer "In4.Cu")
		(net "M_J_CPU1_SA_DQ<11>")
	)
	(arc
		(start 142.607792 -231.201976)
		(mid 142.794736 -231.151687)
		(end 142.98168 -231.201976)
		(width 0.0889)
		(layer "In4.Cu")
		(net "M_J_CPU1_SA_DQ<11>")
	)
	(arc
		(start 134.147814 -231.201976)
		(mid 134.334758 -231.151687)
		(end 134.521702 -231.201976)
		(width 0.0889)
		(layer "In4.Cu")
		(net "M_J_CPU1_SA_DQ<11>")
	)
	(arc
		(start 138.84783 -231.201976)
		(mid 139.034774 -231.151687)
		(end 139.221718 -231.201976)
		(width 0.0889)
		(layer "In4.Cu")
		(net "M_J_CPU1_SA_DQ<11>")
	)
	(arc
		(start 136.40181 -231.201976)
		(mid 136.684766 -231.278153)
		(end 136.967722 -231.201976)
		(width 0.0889)
		(layer "In4.Cu")
		(net "M_J_CPU1_SA_DQ<11>")
	)
	(segment
		(start 132.457952 -230.980234)
		(end 132.924804 -230.71455)
		(width 0.10668)
		(layer "F.Cu")
		(net "M_J_CPU1_SA_DQ<10>")
	)
	(segment
		(start 134.04342 -230.387144)
		(end 134.051802 -230.39197)
		(width 0.0889)
		(layer "In4.Cu")
		(net "M_J_CPU1_SA_DQ<10>")
	)
	(segment
		(start 155.259278 -213.88197)
		(end 155.487878 -213.88197)
		(width 0.14478)
		(layer "In4.Cu")
		(net "M_J_CPU1_SA_DQ<10>")
	)
	(segment
		(start 144.582388 -228.578664)
		(end 145.90395 -227.257102)
		(width 0.0889)
		(layer "In4.Cu")
		(net "M_J_CPU1_SA_DQ<10>")
	)
	(segment
		(start 143.73479 -229.531672)
		(end 143.824706 -229.531672)
		(width 0.0889)
		(layer "In4.Cu")
		(net "M_J_CPU1_SA_DQ<10>")
	)
	(segment
		(start 157.42285 -211.363814)
		(end 157.600142 -211.541106)
		(width 0.14478)
		(layer "In4.Cu")
		(net "M_J_CPU1_SA_DQ<10>")
	)
	(segment
		(start 169.942256 -207.11033)
		(end 170.792394 -207.960468)
		(width 0.14478)
		(layer "In4.Cu")
		(net "M_J_CPU1_SA_DQ<10>")
	)
	(segment
		(start 155.649422 -213.491826)
		(end 155.47213 -213.314534)
		(width 0.14478)
		(layer "In4.Cu")
		(net "M_J_CPU1_SA_DQ<10>")
	)
	(segment
		(start 178.66233 -207.960468)
		(end 181.0639 -207.960468)
		(width 0.14478)
		(layer "In4.Cu")
		(net "M_J_CPU1_SA_DQ<10>")
	)
	(segment
		(start 156.819854 -212.321394)
		(end 157.048454 -212.321394)
		(width 0.14478)
		(layer "In4.Cu")
		(net "M_J_CPU1_SA_DQ<10>")
	)
	(segment
		(start 153.52141 -215.265254)
		(end 153.698702 -215.442546)
		(width 0.14478)
		(layer "In4.Cu")
		(net "M_J_CPU1_SA_DQ<10>")
	)
	(segment
		(start 139.31773 -230.39197)
		(end 139.326112 -230.387144)
		(width 0.0889)
		(layer "In4.Cu")
		(net "M_J_CPU1_SA_DQ<10>")
	)
	(segment
		(start 154.088846 -215.052402)
		(end 153.911554 -214.87511)
		(width 0.14478)
		(layer "In4.Cu")
		(net "M_J_CPU1_SA_DQ<10>")
	)
	(segment
		(start 156.268166 -213.101682)
		(end 156.42971 -212.940138)
		(width 0.14478)
		(layer "In4.Cu")
		(net "M_J_CPU1_SA_DQ<10>")
	)
	(segment
		(start 155.862274 -212.92439)
		(end 156.039566 -213.101682)
		(width 0.14478)
		(layer "In4.Cu")
		(net "M_J_CPU1_SA_DQ<10>")
	)
	(segment
		(start 152.918414 -216.222834)
		(end 153.147014 -216.222834)
		(width 0.14478)
		(layer "In4.Cu")
		(net "M_J_CPU1_SA_DQ<10>")
	)
	(segment
		(start 144.582388 -228.77399)
		(end 144.582388 -228.578664)
		(width 0.0889)
		(layer "In4.Cu")
		(net "M_J_CPU1_SA_DQ<10>")
	)
	(segment
		(start 157.600142 -211.541106)
		(end 157.828742 -211.541106)
		(width 0.14478)
		(layer "In4.Cu")
		(net "M_J_CPU1_SA_DQ<10>")
	)
	(segment
		(start 134.617714 -230.39197)
		(end 134.626096 -230.387144)
		(width 0.0889)
		(layer "In4.Cu")
		(net "M_J_CPU1_SA_DQ<10>")
	)
	(segment
		(start 173.64075 -207.960468)
		(end 174.490888 -207.11033)
		(width 0.14478)
		(layer "In4.Cu")
		(net "M_J_CPU1_SA_DQ<10>")
	)
	(segment
		(start 157.048454 -212.321394)
		(end 157.209998 -212.15985)
		(width 0.14478)
		(layer "In4.Cu")
		(net "M_J_CPU1_SA_DQ<10>")
	)
	(segment
		(start 155.47213 -213.085934)
		(end 155.633674 -212.92439)
		(width 0.14478)
		(layer "In4.Cu")
		(net "M_J_CPU1_SA_DQ<10>")
	)
	(segment
		(start 135.557768 -230.39197)
		(end 135.56615 -230.387144)
		(width 0.0889)
		(layer "In4.Cu")
		(net "M_J_CPU1_SA_DQ<10>")
	)
	(segment
		(start 138.743436 -230.387144)
		(end 138.751818 -230.39197)
		(width 0.0889)
		(layer "In4.Cu")
		(net "M_J_CPU1_SA_DQ<10>")
	)
	(segment
		(start 155.649422 -213.720426)
		(end 155.649422 -213.491826)
		(width 0.14478)
		(layer "In4.Cu")
		(net "M_J_CPU1_SA_DQ<10>")
	)
	(segment
		(start 132.770626 -230.44912)
		(end 132.792978 -230.365808)
		(width 0.0889)
		(layer "In4.Cu")
		(net "M_J_CPU1_SA_DQ<10>")
	)
	(segment
		(start 145.90395 -226.63658)
		(end 147.75307 -224.78746)
		(width 0.0889)
		(layer "In4.Cu")
		(net "M_J_CPU1_SA_DQ<10>")
	)
	(segment
		(start 156.252418 -212.305646)
		(end 156.413962 -212.144102)
		(width 0.14478)
		(layer "In4.Cu")
		(net "M_J_CPU1_SA_DQ<10>")
	)
	(segment
		(start 152.512522 -216.045542)
		(end 152.741122 -216.045542)
		(width 0.14478)
		(layer "In4.Cu")
		(net "M_J_CPU1_SA_DQ<10>")
	)
	(segment
		(start 143.824706 -229.531672)
		(end 144.582388 -228.77399)
		(width 0.0889)
		(layer "In4.Cu")
		(net "M_J_CPU1_SA_DQ<10>")
	)
	(segment
		(start 137.803382 -230.387144)
		(end 137.811764 -230.39197)
		(width 0.0889)
		(layer "In4.Cu")
		(net "M_J_CPU1_SA_DQ<10>")
	)
	(segment
		(start 154.088846 -215.281002)
		(end 154.088846 -215.052402)
		(width 0.14478)
		(layer "In4.Cu")
		(net "M_J_CPU1_SA_DQ<10>")
	)
	(segment
		(start 157.209998 -212.15985)
		(end 157.209998 -211.93125)
		(width 0.14478)
		(layer "In4.Cu")
		(net "M_J_CPU1_SA_DQ<10>")
	)
	(segment
		(start 148.188934 -224.351596)
		(end 148.188934 -220.36913)
		(width 0.14478)
		(layer "In4.Cu")
		(net "M_J_CPU1_SA_DQ<10>")
	)
	(segment
		(start 154.853386 -213.704678)
		(end 155.081986 -213.704678)
		(width 0.14478)
		(layer "In4.Cu")
		(net "M_J_CPU1_SA_DQ<10>")
	)
	(segment
		(start 154.47899 -214.662258)
		(end 154.70759 -214.662258)
		(width 0.14478)
		(layer "In4.Cu")
		(net "M_J_CPU1_SA_DQ<10>")
	)
	(segment
		(start 154.073098 -214.484966)
		(end 154.301698 -214.484966)
		(width 0.14478)
		(layer "In4.Cu")
		(net "M_J_CPU1_SA_DQ<10>")
	)
	(segment
		(start 181.0639 -207.960468)
		(end 181.914038 -207.11033)
		(width 0.14478)
		(layer "In4.Cu")
		(net "M_J_CPU1_SA_DQ<10>")
	)
	(segment
		(start 157.032706 -211.525358)
		(end 157.19425 -211.363814)
		(width 0.14478)
		(layer "In4.Cu")
		(net "M_J_CPU1_SA_DQ<10>")
	)
	(segment
		(start 156.252418 -212.534246)
		(end 156.252418 -212.305646)
		(width 0.14478)
		(layer "In4.Cu")
		(net "M_J_CPU1_SA_DQ<10>")
	)
	(segment
		(start 157.032706 -211.753958)
		(end 157.032706 -211.525358)
		(width 0.14478)
		(layer "In4.Cu")
		(net "M_J_CPU1_SA_DQ<10>")
	)
	(segment
		(start 153.308558 -215.83269)
		(end 153.131266 -215.655398)
		(width 0.14478)
		(layer "In4.Cu")
		(net "M_J_CPU1_SA_DQ<10>")
	)
	(segment
		(start 154.691842 -214.094822)
		(end 154.691842 -213.866222)
		(width 0.14478)
		(layer "In4.Cu")
		(net "M_J_CPU1_SA_DQ<10>")
	)
	(segment
		(start 177.812192 -207.11033)
		(end 178.66233 -207.960468)
		(width 0.14478)
		(layer "In4.Cu")
		(net "M_J_CPU1_SA_DQ<10>")
	)
	(segment
		(start 153.131266 -215.655398)
		(end 153.131266 -215.426798)
		(width 0.14478)
		(layer "In4.Cu")
		(net "M_J_CPU1_SA_DQ<10>")
	)
	(segment
		(start 140.257784 -230.39197)
		(end 140.266166 -230.387144)
		(width 0.0889)
		(layer "In4.Cu")
		(net "M_J_CPU1_SA_DQ<10>")
	)
	(segment
		(start 155.487878 -213.88197)
		(end 155.649422 -213.720426)
		(width 0.14478)
		(layer "In4.Cu")
		(net "M_J_CPU1_SA_DQ<10>")
	)
	(segment
		(start 153.131266 -215.426798)
		(end 153.29281 -215.265254)
		(width 0.14478)
		(layer "In4.Cu")
		(net "M_J_CPU1_SA_DQ<10>")
	)
	(segment
		(start 153.911554 -214.64651)
		(end 154.073098 -214.484966)
		(width 0.14478)
		(layer "In4.Cu")
		(net "M_J_CPU1_SA_DQ<10>")
	)
	(segment
		(start 156.42971 -212.711538)
		(end 156.252418 -212.534246)
		(width 0.14478)
		(layer "In4.Cu")
		(net "M_J_CPU1_SA_DQ<10>")
	)
	(segment
		(start 143.51508 -229.60076)
		(end 143.547592 -229.581964)
		(width 0.0889)
		(layer "In4.Cu")
		(net "M_J_CPU1_SA_DQ<10>")
	)
	(segment
		(start 161.40938 -207.960468)
		(end 166.299388 -207.960468)
		(width 0.14478)
		(layer "In4.Cu")
		(net "M_J_CPU1_SA_DQ<10>")
	)
	(segment
		(start 143.077692 -230.39197)
		(end 143.114268 -230.370634)
		(width 0.0889)
		(layer "In4.Cu")
		(net "M_J_CPU1_SA_DQ<10>")
	)
	(segment
		(start 153.911554 -214.87511)
		(end 153.911554 -214.64651)
		(width 0.14478)
		(layer "In4.Cu")
		(net "M_J_CPU1_SA_DQ<10>")
	)
	(segment
		(start 154.301698 -214.484966)
		(end 154.47899 -214.662258)
		(width 0.14478)
		(layer "In4.Cu")
		(net "M_J_CPU1_SA_DQ<10>")
	)
	(segment
		(start 156.42971 -212.940138)
		(end 156.42971 -212.711538)
		(width 0.14478)
		(layer "In4.Cu")
		(net "M_J_CPU1_SA_DQ<10>")
	)
	(segment
		(start 174.490888 -207.11033)
		(end 177.812192 -207.11033)
		(width 0.14478)
		(layer "In4.Cu")
		(net "M_J_CPU1_SA_DQ<10>")
	)
	(segment
		(start 148.188934 -220.36913)
		(end 152.512522 -216.045542)
		(width 0.14478)
		(layer "In4.Cu")
		(net "M_J_CPU1_SA_DQ<10>")
	)
	(segment
		(start 156.039566 -213.101682)
		(end 156.268166 -213.101682)
		(width 0.14478)
		(layer "In4.Cu")
		(net "M_J_CPU1_SA_DQ<10>")
	)
	(segment
		(start 156.642562 -212.144102)
		(end 156.819854 -212.321394)
		(width 0.14478)
		(layer "In4.Cu")
		(net "M_J_CPU1_SA_DQ<10>")
	)
	(segment
		(start 153.698702 -215.442546)
		(end 153.927302 -215.442546)
		(width 0.14478)
		(layer "In4.Cu")
		(net "M_J_CPU1_SA_DQ<10>")
	)
	(segment
		(start 142.503398 -230.387144)
		(end 142.51178 -230.39197)
		(width 0.0889)
		(layer "In4.Cu")
		(net "M_J_CPU1_SA_DQ<10>")
	)
	(segment
		(start 154.869134 -214.272114)
		(end 154.691842 -214.094822)
		(width 0.14478)
		(layer "In4.Cu")
		(net "M_J_CPU1_SA_DQ<10>")
	)
	(segment
		(start 132.924804 -230.71455)
		(end 132.770626 -230.44912)
		(width 0.0889)
		(layer "In4.Cu")
		(net "M_J_CPU1_SA_DQ<10>")
	)
	(segment
		(start 155.47213 -213.314534)
		(end 155.47213 -213.085934)
		(width 0.14478)
		(layer "In4.Cu")
		(net "M_J_CPU1_SA_DQ<10>")
	)
	(segment
		(start 153.29281 -215.265254)
		(end 153.52141 -215.265254)
		(width 0.14478)
		(layer "In4.Cu")
		(net "M_J_CPU1_SA_DQ<10>")
	)
	(segment
		(start 154.691842 -213.866222)
		(end 154.853386 -213.704678)
		(width 0.14478)
		(layer "In4.Cu")
		(net "M_J_CPU1_SA_DQ<10>")
	)
	(segment
		(start 153.308558 -216.06129)
		(end 153.308558 -215.83269)
		(width 0.14478)
		(layer "In4.Cu")
		(net "M_J_CPU1_SA_DQ<10>")
	)
	(segment
		(start 145.90395 -227.257102)
		(end 145.90395 -226.63658)
		(width 0.0889)
		(layer "In4.Cu")
		(net "M_J_CPU1_SA_DQ<10>")
	)
	(segment
		(start 167.149526 -207.11033)
		(end 169.942256 -207.11033)
		(width 0.14478)
		(layer "In4.Cu")
		(net "M_J_CPU1_SA_DQ<10>")
	)
	(segment
		(start 157.19425 -211.363814)
		(end 157.42285 -211.363814)
		(width 0.14478)
		(layer "In4.Cu")
		(net "M_J_CPU1_SA_DQ<10>")
	)
	(segment
		(start 147.75307 -224.78746)
		(end 148.188934 -224.351596)
		(width 0.14478)
		(layer "In4.Cu")
		(net "M_J_CPU1_SA_DQ<10>")
	)
	(segment
		(start 152.741122 -216.045542)
		(end 152.918414 -216.222834)
		(width 0.14478)
		(layer "In4.Cu")
		(net "M_J_CPU1_SA_DQ<10>")
	)
	(segment
		(start 181.914038 -207.11033)
		(end 186.635136 -207.11033)
		(width 0.14478)
		(layer "In4.Cu")
		(net "M_J_CPU1_SA_DQ<10>")
	)
	(segment
		(start 153.927302 -215.442546)
		(end 154.088846 -215.281002)
		(width 0.14478)
		(layer "In4.Cu")
		(net "M_J_CPU1_SA_DQ<10>")
	)
	(segment
		(start 156.413962 -212.144102)
		(end 156.642562 -212.144102)
		(width 0.14478)
		(layer "In4.Cu")
		(net "M_J_CPU1_SA_DQ<10>")
	)
	(segment
		(start 170.792394 -207.960468)
		(end 173.64075 -207.960468)
		(width 0.14478)
		(layer "In4.Cu")
		(net "M_J_CPU1_SA_DQ<10>")
	)
	(segment
		(start 166.299388 -207.960468)
		(end 167.149526 -207.11033)
		(width 0.14478)
		(layer "In4.Cu")
		(net "M_J_CPU1_SA_DQ<10>")
	)
	(segment
		(start 157.209998 -211.93125)
		(end 157.032706 -211.753958)
		(width 0.14478)
		(layer "In4.Cu")
		(net "M_J_CPU1_SA_DQ<10>")
	)
	(segment
		(start 154.869134 -214.500714)
		(end 154.869134 -214.272114)
		(width 0.14478)
		(layer "In4.Cu")
		(net "M_J_CPU1_SA_DQ<10>")
	)
	(segment
		(start 155.081986 -213.704678)
		(end 155.259278 -213.88197)
		(width 0.14478)
		(layer "In4.Cu")
		(net "M_J_CPU1_SA_DQ<10>")
	)
	(segment
		(start 157.828742 -211.541106)
		(end 161.40938 -207.960468)
		(width 0.14478)
		(layer "In4.Cu")
		(net "M_J_CPU1_SA_DQ<10>")
	)
	(segment
		(start 186.635136 -207.11033)
		(end 187.060078 -207.535272)
		(width 0.14478)
		(layer "In4.Cu")
		(net "M_J_CPU1_SA_DQ<10>")
	)
	(segment
		(start 155.633674 -212.92439)
		(end 155.862274 -212.92439)
		(width 0.14478)
		(layer "In4.Cu")
		(net "M_J_CPU1_SA_DQ<10>")
	)
	(segment
		(start 133.103366 -230.387144)
		(end 133.111748 -230.39197)
		(width 0.0889)
		(layer "In4.Cu")
		(net "M_J_CPU1_SA_DQ<10>")
	)
	(segment
		(start 154.70759 -214.662258)
		(end 154.869134 -214.500714)
		(width 0.14478)
		(layer "In4.Cu")
		(net "M_J_CPU1_SA_DQ<10>")
	)
	(segment
		(start 153.147014 -216.222834)
		(end 153.308558 -216.06129)
		(width 0.14478)
		(layer "In4.Cu")
		(net "M_J_CPU1_SA_DQ<10>")
	)
	(arc
		(start 143.114268 -230.370634)
		(mid 143.29492 -230.167889)
		(end 143.36014 -229.90429)
		(width 0.0889)
		(layer "In4.Cu")
		(net "M_J_CPU1_SA_DQ<10>")
	)
	(arc
		(start 137.437622 -230.39197)
		(mid 137.619873 -230.34162)
		(end 137.803382 -230.387144)
		(width 0.0889)
		(layer "In4.Cu")
		(net "M_J_CPU1_SA_DQ<10>")
	)
	(arc
		(start 134.626096 -230.387144)
		(mid 134.809604 -230.34165)
		(end 134.991856 -230.39197)
		(width 0.0889)
		(layer "In4.Cu")
		(net "M_J_CPU1_SA_DQ<10>")
	)
	(arc
		(start 141.197838 -230.39197)
		(mid 141.384782 -230.341715)
		(end 141.571726 -230.39197)
		(width 0.0889)
		(layer "In4.Cu")
		(net "M_J_CPU1_SA_DQ<10>")
	)
	(arc
		(start 141.571726 -230.39197)
		(mid 141.854682 -230.468113)
		(end 142.137638 -230.39197)
		(width 0.0889)
		(layer "In4.Cu")
		(net "M_J_CPU1_SA_DQ<10>")
	)
	(arc
		(start 135.93191 -230.39197)
		(mid 136.214866 -230.468113)
		(end 136.497822 -230.39197)
		(width 0.0889)
		(layer "In4.Cu")
		(net "M_J_CPU1_SA_DQ<10>")
	)
	(arc
		(start 135.56615 -230.387144)
		(mid 135.749658 -230.34165)
		(end 135.93191 -230.39197)
		(width 0.0889)
		(layer "In4.Cu")
		(net "M_J_CPU1_SA_DQ<10>")
	)
	(arc
		(start 136.87171 -230.39197)
		(mid 137.154666 -230.468113)
		(end 137.437622 -230.39197)
		(width 0.0889)
		(layer "In4.Cu")
		(net "M_J_CPU1_SA_DQ<10>")
	)
	(arc
		(start 137.811764 -230.39197)
		(mid 138.09472 -230.468113)
		(end 138.377676 -230.39197)
		(width 0.0889)
		(layer "In4.Cu")
		(net "M_J_CPU1_SA_DQ<10>")
	)
	(arc
		(start 138.377676 -230.39197)
		(mid 138.559927 -230.34162)
		(end 138.743436 -230.387144)
		(width 0.0889)
		(layer "In4.Cu")
		(net "M_J_CPU1_SA_DQ<10>")
	)
	(arc
		(start 133.67766 -230.39197)
		(mid 133.859911 -230.34162)
		(end 134.04342 -230.387144)
		(width 0.0889)
		(layer "In4.Cu")
		(net "M_J_CPU1_SA_DQ<10>")
	)
	(arc
		(start 133.111748 -230.39197)
		(mid 133.394704 -230.468113)
		(end 133.67766 -230.39197)
		(width 0.0889)
		(layer "In4.Cu")
		(net "M_J_CPU1_SA_DQ<10>")
	)
	(arc
		(start 134.991856 -230.39197)
		(mid 135.274812 -230.468113)
		(end 135.557768 -230.39197)
		(width 0.0889)
		(layer "In4.Cu")
		(net "M_J_CPU1_SA_DQ<10>")
	)
	(arc
		(start 139.691872 -230.39197)
		(mid 139.974828 -230.468113)
		(end 140.257784 -230.39197)
		(width 0.0889)
		(layer "In4.Cu")
		(net "M_J_CPU1_SA_DQ<10>")
	)
	(arc
		(start 140.266166 -230.387144)
		(mid 140.449674 -230.34165)
		(end 140.631926 -230.39197)
		(width 0.0889)
		(layer "In4.Cu")
		(net "M_J_CPU1_SA_DQ<10>")
	)
	(arc
		(start 136.497822 -230.39197)
		(mid 136.684766 -230.341715)
		(end 136.87171 -230.39197)
		(width 0.0889)
		(layer "In4.Cu")
		(net "M_J_CPU1_SA_DQ<10>")
	)
	(arc
		(start 139.326112 -230.387144)
		(mid 139.50962 -230.34165)
		(end 139.691872 -230.39197)
		(width 0.0889)
		(layer "In4.Cu")
		(net "M_J_CPU1_SA_DQ<10>")
	)
	(arc
		(start 140.631926 -230.39197)
		(mid 140.914882 -230.468113)
		(end 141.197838 -230.39197)
		(width 0.0889)
		(layer "In4.Cu")
		(net "M_J_CPU1_SA_DQ<10>")
	)
	(arc
		(start 142.51178 -230.39197)
		(mid 142.794736 -230.468113)
		(end 143.077692 -230.39197)
		(width 0.0889)
		(layer "In4.Cu")
		(net "M_J_CPU1_SA_DQ<10>")
	)
	(arc
		(start 132.792978 -230.365808)
		(mid 132.950488 -230.34261)
		(end 133.103366 -230.387144)
		(width 0.0889)
		(layer "In4.Cu")
		(net "M_J_CPU1_SA_DQ<10>")
	)
	(arc
		(start 143.547592 -229.581964)
		(mid 143.637864 -229.544434)
		(end 143.73479 -229.531672)
		(width 0.0889)
		(layer "In4.Cu")
		(net "M_J_CPU1_SA_DQ<10>")
	)
	(arc
		(start 142.137638 -230.39197)
		(mid 142.319889 -230.34162)
		(end 142.503398 -230.387144)
		(width 0.0889)
		(layer "In4.Cu")
		(net "M_J_CPU1_SA_DQ<10>")
	)
	(arc
		(start 143.36014 -229.90429)
		(mid 143.401106 -229.733884)
		(end 143.51508 -229.60076)
		(width 0.0889)
		(layer "In4.Cu")
		(net "M_J_CPU1_SA_DQ<10>")
	)
	(arc
		(start 134.051802 -230.39197)
		(mid 134.334758 -230.468113)
		(end 134.617714 -230.39197)
		(width 0.0889)
		(layer "In4.Cu")
		(net "M_J_CPU1_SA_DQ<10>")
	)
	(arc
		(start 138.751818 -230.39197)
		(mid 139.034774 -230.468113)
		(end 139.31773 -230.39197)
		(width 0.0889)
		(layer "In4.Cu")
		(net "M_J_CPU1_SA_DQ<10>")
	)
	(segment
		(start 131.987798 -225.310446)
		(end 132.45465 -225.044508)
		(width 0.10668)
		(layer "F.Cu")
		(net "M_J_CPU1_SA_DQ<0>")
	)
	(segment
		(start 137.907776 -225.367088)
		(end 137.916158 -225.371914)
		(width 0.0889)
		(layer "In4.Cu")
		(net "M_J_CPU1_SA_DQ<0>")
	)
	(segment
		(start 187.935362 -197.335902)
		(end 188.096906 -197.497446)
		(width 0.14478)
		(layer "In4.Cu")
		(net "M_J_CPU1_SA_DQ<0>")
	)
	(segment
		(start 140.631926 -224.557082)
		(end 140.663676 -224.538794)
		(width 0.0889)
		(layer "In4.Cu")
		(net "M_J_CPU1_SA_DQ<0>")
	)
	(segment
		(start 136.393428 -225.371914)
		(end 136.40181 -225.367088)
		(width 0.0889)
		(layer "In4.Cu")
		(net "M_J_CPU1_SA_DQ<0>")
	)
	(segment
		(start 135.453374 -225.371914)
		(end 135.461756 -225.367088)
		(width 0.0889)
		(layer "In4.Cu")
		(net "M_J_CPU1_SA_DQ<0>")
	)
	(segment
		(start 172.761656 -197.760336)
		(end 174.813468 -196.910452)
		(width 0.14478)
		(layer "In4.Cu")
		(net "M_J_CPU1_SA_DQ<0>")
	)
	(segment
		(start 141.753082 -221.381066)
		(end 141.753082 -217.495374)
		(width 0.14478)
		(layer "In4.Cu")
		(net "M_J_CPU1_SA_DQ<0>")
	)
	(segment
		(start 141.759686 -222.61449)
		(end 141.753082 -222.607886)
		(width 0.0889)
		(layer "In4.Cu")
		(net "M_J_CPU1_SA_DQ<0>")
	)
	(segment
		(start 187.773818 -196.910452)
		(end 187.935362 -197.071996)
		(width 0.14478)
		(layer "In4.Cu")
		(net "M_J_CPU1_SA_DQ<0>")
	)
	(segment
		(start 132.45465 -225.044508)
		(end 132.608828 -225.309938)
		(width 0.0889)
		(layer "In4.Cu")
		(net "M_J_CPU1_SA_DQ<0>")
	)
	(segment
		(start 169.755058 -196.910452)
		(end 171.80687 -197.760336)
		(width 0.14478)
		(layer "In4.Cu")
		(net "M_J_CPU1_SA_DQ<0>")
	)
	(segment
		(start 167.41394 -196.910452)
		(end 169.755058 -196.910452)
		(width 0.14478)
		(layer "In4.Cu")
		(net "M_J_CPU1_SA_DQ<0>")
	)
	(segment
		(start 141.753082 -217.495374)
		(end 153.916126 -205.33233)
		(width 0.14478)
		(layer "In4.Cu")
		(net "M_J_CPU1_SA_DQ<0>")
	)
	(segment
		(start 188.325252 -197.497446)
		(end 188.486796 -197.335902)
		(width 0.14478)
		(layer "In4.Cu")
		(net "M_J_CPU1_SA_DQ<0>")
	)
	(segment
		(start 188.096906 -197.497446)
		(end 188.325252 -197.497446)
		(width 0.14478)
		(layer "In4.Cu")
		(net "M_J_CPU1_SA_DQ<0>")
	)
	(segment
		(start 141.57198 -222.93707)
		(end 141.604746 -222.91802)
		(width 0.0889)
		(layer "In4.Cu")
		(net "M_J_CPU1_SA_DQ<0>")
	)
	(segment
		(start 153.916126 -205.33233)
		(end 153.916126 -204.041502)
		(width 0.14478)
		(layer "In4.Cu")
		(net "M_J_CPU1_SA_DQ<0>")
	)
	(segment
		(start 140.15339 -225.371914)
		(end 140.161772 -225.367088)
		(width 0.0889)
		(layer "In4.Cu")
		(net "M_J_CPU1_SA_DQ<0>")
	)
	(segment
		(start 165.362128 -197.760336)
		(end 167.41394 -196.910452)
		(width 0.14478)
		(layer "In4.Cu")
		(net "M_J_CPU1_SA_DQ<0>")
	)
	(segment
		(start 136.967722 -225.367088)
		(end 136.976104 -225.371914)
		(width 0.0889)
		(layer "In4.Cu")
		(net "M_J_CPU1_SA_DQ<0>")
	)
	(segment
		(start 160.197292 -197.760336)
		(end 165.362128 -197.760336)
		(width 0.14478)
		(layer "In4.Cu")
		(net "M_J_CPU1_SA_DQ<0>")
	)
	(segment
		(start 180.68036 -197.760336)
		(end 182.732426 -196.910452)
		(width 0.14478)
		(layer "In4.Cu")
		(net "M_J_CPU1_SA_DQ<0>")
	)
	(segment
		(start 140.161772 -225.367088)
		(end 140.193522 -225.3488)
		(width 0.0889)
		(layer "In4.Cu")
		(net "M_J_CPU1_SA_DQ<0>")
	)
	(segment
		(start 188.486796 -197.071996)
		(end 188.64834 -196.910452)
		(width 0.14478)
		(layer "In4.Cu")
		(net "M_J_CPU1_SA_DQ<0>")
	)
	(segment
		(start 177.380646 -196.910452)
		(end 179.432458 -197.760336)
		(width 0.14478)
		(layer "In4.Cu")
		(net "M_J_CPU1_SA_DQ<0>")
	)
	(segment
		(start 133.20776 -225.367088)
		(end 133.216142 -225.371914)
		(width 0.0889)
		(layer "In4.Cu")
		(net "M_J_CPU1_SA_DQ<0>")
	)
	(segment
		(start 174.813468 -196.910452)
		(end 177.380646 -196.910452)
		(width 0.14478)
		(layer "In4.Cu")
		(net "M_J_CPU1_SA_DQ<0>")
	)
	(segment
		(start 189.023752 -196.910452)
		(end 191.160146 -197.335394)
		(width 0.14478)
		(layer "In4.Cu")
		(net "M_J_CPU1_SA_DQ<0>")
	)
	(segment
		(start 132.608828 -225.309938)
		(end 132.705094 -225.335338)
		(width 0.0889)
		(layer "In4.Cu")
		(net "M_J_CPU1_SA_DQ<0>")
	)
	(segment
		(start 188.64834 -196.910452)
		(end 189.023752 -196.910452)
		(width 0.14478)
		(layer "In4.Cu")
		(net "M_J_CPU1_SA_DQ<0>")
	)
	(segment
		(start 141.10208 -223.747076)
		(end 141.13383 -223.728788)
		(width 0.0889)
		(layer "In4.Cu")
		(net "M_J_CPU1_SA_DQ<0>")
	)
	(segment
		(start 182.732426 -196.910452)
		(end 187.773818 -196.910452)
		(width 0.14478)
		(layer "In4.Cu")
		(net "M_J_CPU1_SA_DQ<0>")
	)
	(segment
		(start 171.80687 -197.760336)
		(end 172.761656 -197.760336)
		(width 0.14478)
		(layer "In4.Cu")
		(net "M_J_CPU1_SA_DQ<0>")
	)
	(segment
		(start 141.064234 -223.76892)
		(end 141.10208 -223.747076)
		(width 0.0889)
		(layer "In4.Cu")
		(net "M_J_CPU1_SA_DQ<0>")
	)
	(segment
		(start 140.59281 -224.579942)
		(end 140.631926 -224.557082)
		(width 0.0889)
		(layer "In4.Cu")
		(net "M_J_CPU1_SA_DQ<0>")
	)
	(segment
		(start 141.534388 -222.958914)
		(end 141.57198 -222.93707)
		(width 0.0889)
		(layer "In4.Cu")
		(net "M_J_CPU1_SA_DQ<0>")
	)
	(segment
		(start 188.486796 -197.335902)
		(end 188.486796 -197.071996)
		(width 0.14478)
		(layer "In4.Cu")
		(net "M_J_CPU1_SA_DQ<0>")
	)
	(segment
		(start 153.916126 -204.041502)
		(end 160.197292 -197.760336)
		(width 0.14478)
		(layer "In4.Cu")
		(net "M_J_CPU1_SA_DQ<0>")
	)
	(segment
		(start 141.753082 -222.607886)
		(end 141.753082 -221.381066)
		(width 0.0889)
		(layer "In4.Cu")
		(net "M_J_CPU1_SA_DQ<0>")
	)
	(segment
		(start 179.432458 -197.760336)
		(end 180.68036 -197.760336)
		(width 0.14478)
		(layer "In4.Cu")
		(net "M_J_CPU1_SA_DQ<0>")
	)
	(segment
		(start 187.935362 -197.071996)
		(end 187.935362 -197.335902)
		(width 0.14478)
		(layer "In4.Cu")
		(net "M_J_CPU1_SA_DQ<0>")
	)
	(arc
		(start 136.976104 -225.371914)
		(mid 137.159612 -225.417408)
		(end 137.341864 -225.367088)
		(width 0.0889)
		(layer "In4.Cu")
		(net "M_J_CPU1_SA_DQ<0>")
	)
	(arc
		(start 141.289786 -223.424496)
		(mid 141.354658 -223.161533)
		(end 141.534388 -222.958914)
		(width 0.0889)
		(layer "In4.Cu")
		(net "M_J_CPU1_SA_DQ<0>")
	)
	(arc
		(start 140.193522 -225.3488)
		(mid 140.308198 -225.215466)
		(end 140.349478 -225.044508)
		(width 0.0889)
		(layer "In4.Cu")
		(net "M_J_CPU1_SA_DQ<0>")
	)
	(arc
		(start 139.221718 -225.367088)
		(mid 139.504674 -225.290911)
		(end 139.78763 -225.367088)
		(width 0.0889)
		(layer "In4.Cu")
		(net "M_J_CPU1_SA_DQ<0>")
	)
	(arc
		(start 135.087614 -225.367088)
		(mid 135.269865 -225.417438)
		(end 135.453374 -225.371914)
		(width 0.0889)
		(layer "In4.Cu")
		(net "M_J_CPU1_SA_DQ<0>")
	)
	(arc
		(start 136.40181 -225.367088)
		(mid 136.684766 -225.290911)
		(end 136.967722 -225.367088)
		(width 0.0889)
		(layer "In4.Cu")
		(net "M_J_CPU1_SA_DQ<0>")
	)
	(arc
		(start 141.604746 -222.91802)
		(mid 141.718675 -222.784873)
		(end 141.759686 -222.61449)
		(width 0.0889)
		(layer "In4.Cu")
		(net "M_J_CPU1_SA_DQ<0>")
	)
	(arc
		(start 134.147814 -225.367088)
		(mid 134.334758 -225.417343)
		(end 134.521702 -225.367088)
		(width 0.0889)
		(layer "In4.Cu")
		(net "M_J_CPU1_SA_DQ<0>")
	)
	(arc
		(start 133.581902 -225.367088)
		(mid 133.864858 -225.290911)
		(end 134.147814 -225.367088)
		(width 0.0889)
		(layer "In4.Cu")
		(net "M_J_CPU1_SA_DQ<0>")
	)
	(arc
		(start 132.705094 -225.335338)
		(mid 132.960159 -225.291987)
		(end 133.20776 -225.367088)
		(width 0.0889)
		(layer "In4.Cu")
		(net "M_J_CPU1_SA_DQ<0>")
	)
	(arc
		(start 138.84783 -225.367088)
		(mid 139.034774 -225.417343)
		(end 139.221718 -225.367088)
		(width 0.0889)
		(layer "In4.Cu")
		(net "M_J_CPU1_SA_DQ<0>")
	)
	(arc
		(start 133.216142 -225.371914)
		(mid 133.39965 -225.417408)
		(end 133.581902 -225.367088)
		(width 0.0889)
		(layer "In4.Cu")
		(net "M_J_CPU1_SA_DQ<0>")
	)
	(arc
		(start 140.819632 -224.234502)
		(mid 140.884504 -223.971539)
		(end 141.064234 -223.76892)
		(width 0.0889)
		(layer "In4.Cu")
		(net "M_J_CPU1_SA_DQ<0>")
	)
	(arc
		(start 140.663676 -224.538794)
		(mid 140.778352 -224.40546)
		(end 140.819632 -224.234502)
		(width 0.0889)
		(layer "In4.Cu")
		(net "M_J_CPU1_SA_DQ<0>")
	)
	(arc
		(start 134.521702 -225.367088)
		(mid 134.804658 -225.290911)
		(end 135.087614 -225.367088)
		(width 0.0889)
		(layer "In4.Cu")
		(net "M_J_CPU1_SA_DQ<0>")
	)
	(arc
		(start 140.349478 -225.044508)
		(mid 140.413993 -224.782289)
		(end 140.59281 -224.579942)
		(width 0.0889)
		(layer "In4.Cu")
		(net "M_J_CPU1_SA_DQ<0>")
	)
	(arc
		(start 137.341864 -225.367088)
		(mid 137.62482 -225.290911)
		(end 137.907776 -225.367088)
		(width 0.0889)
		(layer "In4.Cu")
		(net "M_J_CPU1_SA_DQ<0>")
	)
	(arc
		(start 136.027668 -225.367088)
		(mid 136.209919 -225.417438)
		(end 136.393428 -225.371914)
		(width 0.0889)
		(layer "In4.Cu")
		(net "M_J_CPU1_SA_DQ<0>")
	)
	(arc
		(start 141.13383 -223.728788)
		(mid 141.248506 -223.595454)
		(end 141.289786 -223.424496)
		(width 0.0889)
		(layer "In4.Cu")
		(net "M_J_CPU1_SA_DQ<0>")
	)
	(arc
		(start 135.461756 -225.367088)
		(mid 135.744712 -225.290911)
		(end 136.027668 -225.367088)
		(width 0.0889)
		(layer "In4.Cu")
		(net "M_J_CPU1_SA_DQ<0>")
	)
	(arc
		(start 139.78763 -225.367088)
		(mid 139.969881 -225.417438)
		(end 140.15339 -225.371914)
		(width 0.0889)
		(layer "In4.Cu")
		(net "M_J_CPU1_SA_DQ<0>")
	)
	(arc
		(start 137.916158 -225.371914)
		(mid 138.099666 -225.417408)
		(end 138.281918 -225.367088)
		(width 0.0889)
		(layer "In4.Cu")
		(net "M_J_CPU1_SA_DQ<0>")
	)
	(arc
		(start 138.281918 -225.367088)
		(mid 138.564874 -225.290911)
		(end 138.84783 -225.367088)
		(width 0.0889)
		(layer "In4.Cu")
		(net "M_J_CPU1_SA_DQ<0>")
	)
	(segment
		(start 130.577844 -252.04039)
		(end 131.044696 -251.774452)
		(width 0.10668)
		(layer "F.Cu")
		(net "M_J_CPU1_SA_CS_N<1>")
	)
	(segment
		(start 144.958054 -252.096778)
		(end 144.976342 -252.107192)
		(width 0.0889)
		(layer "In4.Cu")
		(net "M_J_CPU1_SA_CS_N<1>")
	)
	(segment
		(start 131.198874 -252.039882)
		(end 131.29514 -252.065282)
		(width 0.0889)
		(layer "In4.Cu")
		(net "M_J_CPU1_SA_CS_N<1>")
	)
	(segment
		(start 135.557768 -252.097032)
		(end 135.56615 -252.101858)
		(width 0.0889)
		(layer "In4.Cu")
		(net "M_J_CPU1_SA_CS_N<1>")
	)
	(segment
		(start 147.136612 -251.997464)
		(end 147.21967 -251.914406)
		(width 0.0889)
		(layer "In4.Cu")
		(net "M_J_CPU1_SA_CS_N<1>")
	)
	(segment
		(start 144.952466 -252.093476)
		(end 144.958054 -252.096778)
		(width 0.0889)
		(layer "In4.Cu")
		(net "M_J_CPU1_SA_CS_N<1>")
	)
	(segment
		(start 142.503398 -252.101858)
		(end 142.51178 -252.097032)
		(width 0.0889)
		(layer "In4.Cu")
		(net "M_J_CPU1_SA_CS_N<1>")
	)
	(segment
		(start 147.21967 -251.914406)
		(end 147.59051 -251.914406)
		(width 0.0889)
		(layer "In4.Cu")
		(net "M_J_CPU1_SA_CS_N<1>")
	)
	(segment
		(start 181.293262 -248.760488)
		(end 182.993284 -247.060466)
		(width 0.14478)
		(layer "In4.Cu")
		(net "M_J_CPU1_SA_CS_N<1>")
	)
	(segment
		(start 137.803382 -252.101858)
		(end 137.811764 -252.097032)
		(width 0.0889)
		(layer "In4.Cu")
		(net "M_J_CPU1_SA_CS_N<1>")
	)
	(segment
		(start 134.04342 -252.101858)
		(end 134.051802 -252.097032)
		(width 0.0889)
		(layer "In4.Cu")
		(net "M_J_CPU1_SA_CS_N<1>")
	)
	(segment
		(start 149.986746 -251.914406)
		(end 150.332186 -251.568966)
		(width 0.14478)
		(layer "In4.Cu")
		(net "M_J_CPU1_SA_CS_N<1>")
	)
	(segment
		(start 147.59051 -251.914406)
		(end 149.986746 -251.914406)
		(width 0.14478)
		(layer "In4.Cu")
		(net "M_J_CPU1_SA_CS_N<1>")
	)
	(segment
		(start 140.257784 -252.097032)
		(end 140.266166 -252.101858)
		(width 0.0889)
		(layer "In4.Cu")
		(net "M_J_CPU1_SA_CS_N<1>")
	)
	(segment
		(start 133.103366 -252.101858)
		(end 133.111748 -252.097032)
		(width 0.0889)
		(layer "In4.Cu")
		(net "M_J_CPU1_SA_CS_N<1>")
	)
	(segment
		(start 138.743436 -252.101858)
		(end 138.751818 -252.097032)
		(width 0.0889)
		(layer "In4.Cu")
		(net "M_J_CPU1_SA_CS_N<1>")
	)
	(segment
		(start 144.380966 -252.10389)
		(end 144.39265 -252.097032)
		(width 0.0889)
		(layer "In4.Cu")
		(net "M_J_CPU1_SA_CS_N<1>")
	)
	(segment
		(start 161.02584 -251.568966)
		(end 163.834318 -248.760488)
		(width 0.14478)
		(layer "In4.Cu")
		(net "M_J_CPU1_SA_CS_N<1>")
	)
	(segment
		(start 143.451834 -252.097032)
		(end 143.466566 -252.088396)
		(width 0.0889)
		(layer "In4.Cu")
		(net "M_J_CPU1_SA_CS_N<1>")
	)
	(segment
		(start 182.993284 -247.060466)
		(end 186.634882 -247.060466)
		(width 0.14478)
		(layer "In4.Cu")
		(net "M_J_CPU1_SA_CS_N<1>")
	)
	(segment
		(start 143.077692 -252.097032)
		(end 143.086074 -252.101858)
		(width 0.0889)
		(layer "In4.Cu")
		(net "M_J_CPU1_SA_CS_N<1>")
	)
	(segment
		(start 145.555716 -251.997464)
		(end 147.136612 -251.997464)
		(width 0.0889)
		(layer "In4.Cu")
		(net "M_J_CPU1_SA_CS_N<1>")
	)
	(segment
		(start 134.617714 -252.097032)
		(end 134.626096 -252.101858)
		(width 0.0889)
		(layer "In4.Cu")
		(net "M_J_CPU1_SA_CS_N<1>")
	)
	(segment
		(start 139.31773 -252.097032)
		(end 139.326112 -252.101858)
		(width 0.0889)
		(layer "In4.Cu")
		(net "M_J_CPU1_SA_CS_N<1>")
	)
	(segment
		(start 145.332196 -252.097032)
		(end 145.555716 -251.997464)
		(width 0.0889)
		(layer "In4.Cu")
		(net "M_J_CPU1_SA_CS_N<1>")
	)
	(segment
		(start 150.332186 -251.568966)
		(end 161.02584 -251.568966)
		(width 0.14478)
		(layer "In4.Cu")
		(net "M_J_CPU1_SA_CS_N<1>")
	)
	(segment
		(start 163.834318 -248.760488)
		(end 181.293262 -248.760488)
		(width 0.14478)
		(layer "In4.Cu")
		(net "M_J_CPU1_SA_CS_N<1>")
	)
	(segment
		(start 186.634882 -247.060466)
		(end 187.060078 -246.63527)
		(width 0.14478)
		(layer "In4.Cu")
		(net "M_J_CPU1_SA_CS_N<1>")
	)
	(segment
		(start 131.044696 -251.774452)
		(end 131.198874 -252.039882)
		(width 0.0889)
		(layer "In4.Cu")
		(net "M_J_CPU1_SA_CS_N<1>")
	)
	(arc
		(start 134.626096 -252.101858)
		(mid 134.809604 -252.147352)
		(end 134.991856 -252.097032)
		(width 0.0889)
		(layer "In4.Cu")
		(net "M_J_CPU1_SA_CS_N<1>")
	)
	(arc
		(start 131.797806 -252.097032)
		(mid 131.98475 -252.147287)
		(end 132.171694 -252.097032)
		(width 0.0889)
		(layer "In4.Cu")
		(net "M_J_CPU1_SA_CS_N<1>")
	)
	(arc
		(start 144.976342 -252.107192)
		(mid 145.155571 -252.147345)
		(end 145.332196 -252.097032)
		(width 0.0889)
		(layer "In4.Cu")
		(net "M_J_CPU1_SA_CS_N<1>")
	)
	(arc
		(start 133.67766 -252.097032)
		(mid 133.859911 -252.147382)
		(end 134.04342 -252.101858)
		(width 0.0889)
		(layer "In4.Cu")
		(net "M_J_CPU1_SA_CS_N<1>")
	)
	(arc
		(start 132.171694 -252.097032)
		(mid 132.45465 -252.020855)
		(end 132.737606 -252.097032)
		(width 0.0889)
		(layer "In4.Cu")
		(net "M_J_CPU1_SA_CS_N<1>")
	)
	(arc
		(start 140.266166 -252.101858)
		(mid 140.449674 -252.147352)
		(end 140.631926 -252.097032)
		(width 0.0889)
		(layer "In4.Cu")
		(net "M_J_CPU1_SA_CS_N<1>")
	)
	(arc
		(start 131.29514 -252.065282)
		(mid 131.550205 -252.021931)
		(end 131.797806 -252.097032)
		(width 0.0889)
		(layer "In4.Cu")
		(net "M_J_CPU1_SA_CS_N<1>")
	)
	(arc
		(start 137.811764 -252.097032)
		(mid 138.09472 -252.020855)
		(end 138.377676 -252.097032)
		(width 0.0889)
		(layer "In4.Cu")
		(net "M_J_CPU1_SA_CS_N<1>")
	)
	(arc
		(start 136.497822 -252.097032)
		(mid 136.684766 -252.147287)
		(end 136.87171 -252.097032)
		(width 0.0889)
		(layer "In4.Cu")
		(net "M_J_CPU1_SA_CS_N<1>")
	)
	(arc
		(start 135.56615 -252.101858)
		(mid 135.749658 -252.147352)
		(end 135.93191 -252.097032)
		(width 0.0889)
		(layer "In4.Cu")
		(net "M_J_CPU1_SA_CS_N<1>")
	)
	(arc
		(start 142.137638 -252.097032)
		(mid 142.319889 -252.147382)
		(end 142.503398 -252.101858)
		(width 0.0889)
		(layer "In4.Cu")
		(net "M_J_CPU1_SA_CS_N<1>")
	)
	(arc
		(start 134.991856 -252.097032)
		(mid 135.274812 -252.020855)
		(end 135.557768 -252.097032)
		(width 0.0889)
		(layer "In4.Cu")
		(net "M_J_CPU1_SA_CS_N<1>")
	)
	(arc
		(start 144.018254 -252.097032)
		(mid 144.198712 -252.147476)
		(end 144.380966 -252.10389)
		(width 0.0889)
		(layer "In4.Cu")
		(net "M_J_CPU1_SA_CS_N<1>")
	)
	(arc
		(start 140.631926 -252.097032)
		(mid 140.914882 -252.020855)
		(end 141.197838 -252.097032)
		(width 0.0889)
		(layer "In4.Cu")
		(net "M_J_CPU1_SA_CS_N<1>")
	)
	(arc
		(start 138.751818 -252.097032)
		(mid 139.034774 -252.020855)
		(end 139.31773 -252.097032)
		(width 0.0889)
		(layer "In4.Cu")
		(net "M_J_CPU1_SA_CS_N<1>")
	)
	(arc
		(start 139.326112 -252.101858)
		(mid 139.50962 -252.147352)
		(end 139.691872 -252.097032)
		(width 0.0889)
		(layer "In4.Cu")
		(net "M_J_CPU1_SA_CS_N<1>")
	)
	(arc
		(start 132.737606 -252.097032)
		(mid 132.919857 -252.147382)
		(end 133.103366 -252.101858)
		(width 0.0889)
		(layer "In4.Cu")
		(net "M_J_CPU1_SA_CS_N<1>")
	)
	(arc
		(start 134.051802 -252.097032)
		(mid 134.334758 -252.020855)
		(end 134.617714 -252.097032)
		(width 0.0889)
		(layer "In4.Cu")
		(net "M_J_CPU1_SA_CS_N<1>")
	)
	(arc
		(start 142.51178 -252.097032)
		(mid 142.794736 -252.020855)
		(end 143.077692 -252.097032)
		(width 0.0889)
		(layer "In4.Cu")
		(net "M_J_CPU1_SA_CS_N<1>")
	)
	(arc
		(start 141.197838 -252.097032)
		(mid 141.384782 -252.147287)
		(end 141.571726 -252.097032)
		(width 0.0889)
		(layer "In4.Cu")
		(net "M_J_CPU1_SA_CS_N<1>")
	)
	(arc
		(start 138.377676 -252.097032)
		(mid 138.559927 -252.147382)
		(end 138.743436 -252.101858)
		(width 0.0889)
		(layer "In4.Cu")
		(net "M_J_CPU1_SA_CS_N<1>")
	)
	(arc
		(start 137.437622 -252.097032)
		(mid 137.619873 -252.147382)
		(end 137.803382 -252.101858)
		(width 0.0889)
		(layer "In4.Cu")
		(net "M_J_CPU1_SA_CS_N<1>")
	)
	(arc
		(start 139.691872 -252.097032)
		(mid 139.974828 -252.020855)
		(end 140.257784 -252.097032)
		(width 0.0889)
		(layer "In4.Cu")
		(net "M_J_CPU1_SA_CS_N<1>")
	)
	(arc
		(start 136.87171 -252.097032)
		(mid 137.154666 -252.020855)
		(end 137.437622 -252.097032)
		(width 0.0889)
		(layer "In4.Cu")
		(net "M_J_CPU1_SA_CS_N<1>")
	)
	(arc
		(start 144.39265 -252.097032)
		(mid 144.672078 -252.020866)
		(end 144.952466 -252.093476)
		(width 0.0889)
		(layer "In4.Cu")
		(net "M_J_CPU1_SA_CS_N<1>")
	)
	(arc
		(start 143.086074 -252.101858)
		(mid 143.269582 -252.147352)
		(end 143.451834 -252.097032)
		(width 0.0889)
		(layer "In4.Cu")
		(net "M_J_CPU1_SA_CS_N<1>")
	)
	(arc
		(start 135.93191 -252.097032)
		(mid 136.214866 -252.020855)
		(end 136.497822 -252.097032)
		(width 0.0889)
		(layer "In4.Cu")
		(net "M_J_CPU1_SA_CS_N<1>")
	)
	(arc
		(start 141.571726 -252.097032)
		(mid 141.854682 -252.020855)
		(end 142.137638 -252.097032)
		(width 0.0889)
		(layer "In4.Cu")
		(net "M_J_CPU1_SA_CS_N<1>")
	)
	(arc
		(start 133.111748 -252.097032)
		(mid 133.394704 -252.020855)
		(end 133.67766 -252.097032)
		(width 0.0889)
		(layer "In4.Cu")
		(net "M_J_CPU1_SA_CS_N<1>")
	)
	(arc
		(start 143.466566 -252.088396)
		(mid 143.743549 -252.020592)
		(end 144.018254 -252.097032)
		(width 0.0889)
		(layer "In4.Cu")
		(net "M_J_CPU1_SA_CS_N<1>")
	)
	(segment
		(start 131.987798 -251.230384)
		(end 132.45465 -250.964446)
		(width 0.10668)
		(layer "F.Cu")
		(net "M_J_CPU1_SA_CS_N<0>")
	)
	(segment
		(start 160.83915 -251.119386)
		(end 164.048186 -247.91035)
		(width 0.14478)
		(layer "In4.Cu")
		(net "M_J_CPU1_SA_CS_N<0>")
	)
	(segment
		(start 135.453374 -251.291852)
		(end 135.461756 -251.287026)
		(width 0.0889)
		(layer "In4.Cu")
		(net "M_J_CPU1_SA_CS_N<0>")
	)
	(segment
		(start 147.500848 -251.453904)
		(end 149.799548 -251.453904)
		(width 0.14478)
		(layer "In4.Cu")
		(net "M_J_CPU1_SA_CS_N<0>")
	)
	(segment
		(start 140.15339 -251.291852)
		(end 140.161772 -251.287026)
		(width 0.0889)
		(layer "In4.Cu")
		(net "M_J_CPU1_SA_CS_N<0>")
	)
	(segment
		(start 149.799548 -251.453904)
		(end 150.134066 -251.119386)
		(width 0.14478)
		(layer "In4.Cu")
		(net "M_J_CPU1_SA_CS_N<0>")
	)
	(segment
		(start 146.269456 -251.593604)
		(end 147.069048 -251.593604)
		(width 0.0889)
		(layer "In4.Cu")
		(net "M_J_CPU1_SA_CS_N<0>")
	)
	(segment
		(start 190.735204 -246.210328)
		(end 191.160146 -245.785386)
		(width 0.14478)
		(layer "In4.Cu")
		(net "M_J_CPU1_SA_CS_N<0>")
	)
	(segment
		(start 144.84604 -251.29617)
		(end 144.862296 -251.286772)
		(width 0.0889)
		(layer "In4.Cu")
		(net "M_J_CPU1_SA_CS_N<0>")
	)
	(segment
		(start 144.477994 -251.28093)
		(end 144.488408 -251.287026)
		(width 0.0889)
		(layer "In4.Cu")
		(net "M_J_CPU1_SA_CS_N<0>")
	)
	(segment
		(start 133.20776 -251.287026)
		(end 133.216142 -251.291852)
		(width 0.0889)
		(layer "In4.Cu")
		(net "M_J_CPU1_SA_CS_N<0>")
	)
	(segment
		(start 141.093444 -251.291852)
		(end 141.101826 -251.287026)
		(width 0.0889)
		(layer "In4.Cu")
		(net "M_J_CPU1_SA_CS_N<0>")
	)
	(segment
		(start 141.667738 -251.287026)
		(end 141.67612 -251.291852)
		(width 0.0889)
		(layer "In4.Cu")
		(net "M_J_CPU1_SA_CS_N<0>")
	)
	(segment
		(start 145.95729 -251.281438)
		(end 146.269456 -251.593604)
		(width 0.0889)
		(layer "In4.Cu")
		(net "M_J_CPU1_SA_CS_N<0>")
	)
	(segment
		(start 164.048186 -247.91035)
		(end 181.027832 -247.91035)
		(width 0.14478)
		(layer "In4.Cu")
		(net "M_J_CPU1_SA_CS_N<0>")
	)
	(segment
		(start 182.727854 -246.210328)
		(end 190.735204 -246.210328)
		(width 0.14478)
		(layer "In4.Cu")
		(net "M_J_CPU1_SA_CS_N<0>")
	)
	(segment
		(start 136.967722 -251.287026)
		(end 136.976104 -251.291852)
		(width 0.0889)
		(layer "In4.Cu")
		(net "M_J_CPU1_SA_CS_N<0>")
	)
	(segment
		(start 145.428208 -251.287026)
		(end 145.95729 -251.281438)
		(width 0.0889)
		(layer "In4.Cu")
		(net "M_J_CPU1_SA_CS_N<0>")
	)
	(segment
		(start 181.027832 -247.91035)
		(end 182.727854 -246.210328)
		(width 0.14478)
		(layer "In4.Cu")
		(net "M_J_CPU1_SA_CS_N<0>")
	)
	(segment
		(start 136.393428 -251.291852)
		(end 136.40181 -251.287026)
		(width 0.0889)
		(layer "In4.Cu")
		(net "M_J_CPU1_SA_CS_N<0>")
	)
	(segment
		(start 147.208748 -251.453904)
		(end 147.500848 -251.453904)
		(width 0.0889)
		(layer "In4.Cu")
		(net "M_J_CPU1_SA_CS_N<0>")
	)
	(segment
		(start 144.862296 -251.286772)
		(end 144.878044 -251.277628)
		(width 0.0889)
		(layer "In4.Cu")
		(net "M_J_CPU1_SA_CS_N<0>")
	)
	(segment
		(start 132.608828 -251.229876)
		(end 132.705094 -251.255276)
		(width 0.0889)
		(layer "In4.Cu")
		(net "M_J_CPU1_SA_CS_N<0>")
	)
	(segment
		(start 143.547592 -251.287026)
		(end 143.555974 -251.291852)
		(width 0.0889)
		(layer "In4.Cu")
		(net "M_J_CPU1_SA_CS_N<0>")
	)
	(segment
		(start 132.45465 -250.964446)
		(end 132.608828 -251.229876)
		(width 0.0889)
		(layer "In4.Cu")
		(net "M_J_CPU1_SA_CS_N<0>")
	)
	(segment
		(start 137.907776 -251.287026)
		(end 137.916158 -251.291852)
		(width 0.0889)
		(layer "In4.Cu")
		(net "M_J_CPU1_SA_CS_N<0>")
	)
	(segment
		(start 150.134066 -251.119386)
		(end 160.83915 -251.119386)
		(width 0.14478)
		(layer "In4.Cu")
		(net "M_J_CPU1_SA_CS_N<0>")
	)
	(segment
		(start 147.069048 -251.593604)
		(end 147.208748 -251.453904)
		(width 0.0889)
		(layer "In4.Cu")
		(net "M_J_CPU1_SA_CS_N<0>")
	)
	(arc
		(start 142.607792 -251.287026)
		(mid 142.794736 -251.337281)
		(end 142.98168 -251.287026)
		(width 0.0889)
		(layer "In4.Cu")
		(net "M_J_CPU1_SA_CS_N<0>")
	)
	(arc
		(start 138.281918 -251.287026)
		(mid 138.564874 -251.210849)
		(end 138.84783 -251.287026)
		(width 0.0889)
		(layer "In4.Cu")
		(net "M_J_CPU1_SA_CS_N<0>")
	)
	(arc
		(start 133.216142 -251.291852)
		(mid 133.39965 -251.337346)
		(end 133.581902 -251.287026)
		(width 0.0889)
		(layer "In4.Cu")
		(net "M_J_CPU1_SA_CS_N<0>")
	)
	(arc
		(start 143.555974 -251.291852)
		(mid 143.739736 -251.337468)
		(end 143.922242 -251.287026)
		(width 0.0889)
		(layer "In4.Cu")
		(net "M_J_CPU1_SA_CS_N<0>")
	)
	(arc
		(start 136.976104 -251.291852)
		(mid 137.159612 -251.337346)
		(end 137.341864 -251.287026)
		(width 0.0889)
		(layer "In4.Cu")
		(net "M_J_CPU1_SA_CS_N<0>")
	)
	(arc
		(start 139.78763 -251.287026)
		(mid 139.969881 -251.337376)
		(end 140.15339 -251.291852)
		(width 0.0889)
		(layer "In4.Cu")
		(net "M_J_CPU1_SA_CS_N<0>")
	)
	(arc
		(start 134.521702 -251.287026)
		(mid 134.804658 -251.210849)
		(end 135.087614 -251.287026)
		(width 0.0889)
		(layer "In4.Cu")
		(net "M_J_CPU1_SA_CS_N<0>")
	)
	(arc
		(start 138.84783 -251.287026)
		(mid 139.034774 -251.337281)
		(end 139.221718 -251.287026)
		(width 0.0889)
		(layer "In4.Cu")
		(net "M_J_CPU1_SA_CS_N<0>")
	)
	(arc
		(start 137.916158 -251.291852)
		(mid 138.099666 -251.337346)
		(end 138.281918 -251.287026)
		(width 0.0889)
		(layer "In4.Cu")
		(net "M_J_CPU1_SA_CS_N<0>")
	)
	(arc
		(start 140.727684 -251.287026)
		(mid 140.909935 -251.337376)
		(end 141.093444 -251.291852)
		(width 0.0889)
		(layer "In4.Cu")
		(net "M_J_CPU1_SA_CS_N<0>")
	)
	(arc
		(start 142.04188 -251.287026)
		(mid 142.324836 -251.210849)
		(end 142.607792 -251.287026)
		(width 0.0889)
		(layer "In4.Cu")
		(net "M_J_CPU1_SA_CS_N<0>")
	)
	(arc
		(start 135.087614 -251.287026)
		(mid 135.269865 -251.337376)
		(end 135.453374 -251.291852)
		(width 0.0889)
		(layer "In4.Cu")
		(net "M_J_CPU1_SA_CS_N<0>")
	)
	(arc
		(start 137.341864 -251.287026)
		(mid 137.62482 -251.210849)
		(end 137.907776 -251.287026)
		(width 0.0889)
		(layer "In4.Cu")
		(net "M_J_CPU1_SA_CS_N<0>")
	)
	(arc
		(start 134.147814 -251.287026)
		(mid 134.334758 -251.337281)
		(end 134.521702 -251.287026)
		(width 0.0889)
		(layer "In4.Cu")
		(net "M_J_CPU1_SA_CS_N<0>")
	)
	(arc
		(start 133.581902 -251.287026)
		(mid 133.864858 -251.210849)
		(end 134.147814 -251.287026)
		(width 0.0889)
		(layer "In4.Cu")
		(net "M_J_CPU1_SA_CS_N<0>")
	)
	(arc
		(start 140.161772 -251.287026)
		(mid 140.444728 -251.210849)
		(end 140.727684 -251.287026)
		(width 0.0889)
		(layer "In4.Cu")
		(net "M_J_CPU1_SA_CS_N<0>")
	)
	(arc
		(start 135.461756 -251.287026)
		(mid 135.744712 -251.210849)
		(end 136.027668 -251.287026)
		(width 0.0889)
		(layer "In4.Cu")
		(net "M_J_CPU1_SA_CS_N<0>")
	)
	(arc
		(start 142.98168 -251.287026)
		(mid 143.264636 -251.210849)
		(end 143.547592 -251.287026)
		(width 0.0889)
		(layer "In4.Cu")
		(net "M_J_CPU1_SA_CS_N<0>")
	)
	(arc
		(start 144.878044 -251.277628)
		(mid 145.154353 -251.210652)
		(end 145.428208 -251.287026)
		(width 0.0889)
		(layer "In4.Cu")
		(net "M_J_CPU1_SA_CS_N<0>")
	)
	(arc
		(start 141.101826 -251.287026)
		(mid 141.384782 -251.210849)
		(end 141.667738 -251.287026)
		(width 0.0889)
		(layer "In4.Cu")
		(net "M_J_CPU1_SA_CS_N<0>")
	)
	(arc
		(start 136.027668 -251.287026)
		(mid 136.209919 -251.337376)
		(end 136.393428 -251.291852)
		(width 0.0889)
		(layer "In4.Cu")
		(net "M_J_CPU1_SA_CS_N<0>")
	)
	(arc
		(start 132.705094 -251.255276)
		(mid 132.960159 -251.211925)
		(end 133.20776 -251.287026)
		(width 0.0889)
		(layer "In4.Cu")
		(net "M_J_CPU1_SA_CS_N<0>")
	)
	(arc
		(start 144.488408 -251.287026)
		(mid 144.666058 -251.337286)
		(end 144.84604 -251.29617)
		(width 0.0889)
		(layer "In4.Cu")
		(net "M_J_CPU1_SA_CS_N<0>")
	)
	(arc
		(start 141.67612 -251.291852)
		(mid 141.859628 -251.337346)
		(end 142.04188 -251.287026)
		(width 0.0889)
		(layer "In4.Cu")
		(net "M_J_CPU1_SA_CS_N<0>")
	)
	(arc
		(start 136.40181 -251.287026)
		(mid 136.684766 -251.210849)
		(end 136.967722 -251.287026)
		(width 0.0889)
		(layer "In4.Cu")
		(net "M_J_CPU1_SA_CS_N<0>")
	)
	(arc
		(start 143.922242 -251.287026)
		(mid 144.199309 -251.210755)
		(end 144.477994 -251.28093)
		(width 0.0889)
		(layer "In4.Cu")
		(net "M_J_CPU1_SA_CS_N<0>")
	)
	(arc
		(start 139.221718 -251.287026)
		(mid 139.504674 -251.210849)
		(end 139.78763 -251.287026)
		(width 0.0889)
		(layer "In4.Cu")
		(net "M_J_CPU1_SA_CS_N<0>")
	)
	(segment
		(start 131.047998 -249.610372)
		(end 131.51485 -249.344434)
		(width 0.10668)
		(layer "F.Cu")
		(net "M_J_CPU1_SA_CB<7>")
	)
	(segment
		(start 180.242718 -245.360444)
		(end 181.94274 -243.660422)
		(width 0.14478)
		(layer "In4.Cu")
		(net "M_J_CPU1_SA_CB<7>")
	)
	(segment
		(start 136.393428 -249.017028)
		(end 136.40181 -249.021854)
		(width 0.0889)
		(layer "In4.Cu")
		(net "M_J_CPU1_SA_CB<7>")
	)
	(segment
		(start 181.94274 -243.660422)
		(end 186.634882 -243.660422)
		(width 0.14478)
		(layer "In4.Cu")
		(net "M_J_CPU1_SA_CB<7>")
	)
	(segment
		(start 144.47393 -249.03049)
		(end 144.488662 -249.021854)
		(width 0.0889)
		(layer "In4.Cu")
		(net "M_J_CPU1_SA_CB<7>")
	)
	(segment
		(start 146.906488 -249.244104)
		(end 147.122388 -249.460004)
		(width 0.0889)
		(layer "In4.Cu")
		(net "M_J_CPU1_SA_CB<7>")
	)
	(segment
		(start 147.752054 -249.460004)
		(end 148.974048 -249.460004)
		(width 0.14478)
		(layer "In4.Cu")
		(net "M_J_CPU1_SA_CB<7>")
	)
	(segment
		(start 146.016218 -249.244104)
		(end 146.906488 -249.244104)
		(width 0.0889)
		(layer "In4.Cu")
		(net "M_J_CPU1_SA_CB<7>")
	)
	(segment
		(start 161.435542 -247.05183)
		(end 159.66059 -248.826782)
		(width 0.14478)
		(layer "In4.Cu")
		(net "M_J_CPU1_SA_CB<7>")
	)
	(segment
		(start 131.360672 -249.079004)
		(end 131.383024 -248.995692)
		(width 0.0889)
		(layer "In4.Cu")
		(net "M_J_CPU1_SA_CB<7>")
	)
	(segment
		(start 159.822388 -249.216926)
		(end 160.05048 -249.216926)
		(width 0.14478)
		(layer "In4.Cu")
		(net "M_J_CPU1_SA_CB<7>")
	)
	(segment
		(start 141.667738 -249.021854)
		(end 141.67612 -249.017028)
		(width 0.0889)
		(layer "In4.Cu")
		(net "M_J_CPU1_SA_CB<7>")
	)
	(segment
		(start 161.045652 -246.661686)
		(end 161.273744 -246.661686)
		(width 0.14478)
		(layer "In4.Cu")
		(net "M_J_CPU1_SA_CB<7>")
	)
	(segment
		(start 158.490412 -249.216926)
		(end 161.045652 -246.661686)
		(width 0.14478)
		(layer "In4.Cu")
		(net "M_J_CPU1_SA_CB<7>")
	)
	(segment
		(start 163.906962 -245.360444)
		(end 180.242718 -245.360444)
		(width 0.14478)
		(layer "In4.Cu")
		(net "M_J_CPU1_SA_CB<7>")
	)
	(segment
		(start 148.974048 -249.460004)
		(end 149.217126 -249.216926)
		(width 0.14478)
		(layer "In4.Cu")
		(net "M_J_CPU1_SA_CB<7>")
	)
	(segment
		(start 144.84858 -249.014234)
		(end 144.862296 -249.022108)
		(width 0.0889)
		(layer "In4.Cu")
		(net "M_J_CPU1_SA_CB<7>")
	)
	(segment
		(start 159.66059 -248.826782)
		(end 159.66059 -249.055128)
		(width 0.14478)
		(layer "In4.Cu")
		(net "M_J_CPU1_SA_CB<7>")
	)
	(segment
		(start 149.217126 -249.216926)
		(end 158.490412 -249.216926)
		(width 0.14478)
		(layer "In4.Cu")
		(net "M_J_CPU1_SA_CB<7>")
	)
	(segment
		(start 159.66059 -249.055128)
		(end 159.822388 -249.216926)
		(width 0.14478)
		(layer "In4.Cu")
		(net "M_J_CPU1_SA_CB<7>")
	)
	(segment
		(start 136.967722 -249.021854)
		(end 136.976104 -249.017028)
		(width 0.0889)
		(layer "In4.Cu")
		(net "M_J_CPU1_SA_CB<7>")
	)
	(segment
		(start 186.634882 -243.660422)
		(end 187.060078 -243.235226)
		(width 0.14478)
		(layer "In4.Cu")
		(net "M_J_CPU1_SA_CB<7>")
	)
	(segment
		(start 145.794476 -249.017028)
		(end 145.794476 -249.022362)
		(width 0.0889)
		(layer "In4.Cu")
		(net "M_J_CPU1_SA_CB<7>")
	)
	(segment
		(start 131.693412 -249.017028)
		(end 131.701794 -249.021854)
		(width 0.0889)
		(layer "In4.Cu")
		(net "M_J_CPU1_SA_CB<7>")
	)
	(segment
		(start 141.093444 -249.017028)
		(end 141.101826 -249.021854)
		(width 0.0889)
		(layer "In4.Cu")
		(net "M_J_CPU1_SA_CB<7>")
	)
	(segment
		(start 140.15339 -249.017028)
		(end 140.161772 -249.021854)
		(width 0.0889)
		(layer "In4.Cu")
		(net "M_J_CPU1_SA_CB<7>")
	)
	(segment
		(start 143.547592 -249.021854)
		(end 143.555974 -249.017028)
		(width 0.0889)
		(layer "In4.Cu")
		(net "M_J_CPU1_SA_CB<7>")
	)
	(segment
		(start 132.267706 -249.021854)
		(end 132.276088 -249.017028)
		(width 0.0889)
		(layer "In4.Cu")
		(net "M_J_CPU1_SA_CB<7>")
	)
	(segment
		(start 131.51485 -249.344434)
		(end 131.360672 -249.079004)
		(width 0.0889)
		(layer "In4.Cu")
		(net "M_J_CPU1_SA_CB<7>")
	)
	(segment
		(start 161.435542 -246.823484)
		(end 161.435542 -247.05183)
		(width 0.14478)
		(layer "In4.Cu")
		(net "M_J_CPU1_SA_CB<7>")
	)
	(segment
		(start 137.907776 -249.021854)
		(end 137.916158 -249.017028)
		(width 0.0889)
		(layer "In4.Cu")
		(net "M_J_CPU1_SA_CB<7>")
	)
	(segment
		(start 147.122388 -249.460004)
		(end 147.752054 -249.460004)
		(width 0.0889)
		(layer "In4.Cu")
		(net "M_J_CPU1_SA_CB<7>")
	)
	(segment
		(start 135.453374 -249.017028)
		(end 135.461756 -249.021854)
		(width 0.0889)
		(layer "In4.Cu")
		(net "M_J_CPU1_SA_CB<7>")
	)
	(segment
		(start 161.273744 -246.661686)
		(end 161.435542 -246.823484)
		(width 0.14478)
		(layer "In4.Cu")
		(net "M_J_CPU1_SA_CB<7>")
	)
	(segment
		(start 160.05048 -249.216926)
		(end 163.906962 -245.360444)
		(width 0.14478)
		(layer "In4.Cu")
		(net "M_J_CPU1_SA_CB<7>")
	)
	(segment
		(start 144.862296 -249.022108)
		(end 144.878044 -249.031252)
		(width 0.0889)
		(layer "In4.Cu")
		(net "M_J_CPU1_SA_CB<7>")
	)
	(segment
		(start 145.794476 -249.022362)
		(end 146.016218 -249.244104)
		(width 0.0889)
		(layer "In4.Cu")
		(net "M_J_CPU1_SA_CB<7>")
	)
	(segment
		(start 133.20776 -249.021854)
		(end 133.216142 -249.017028)
		(width 0.0889)
		(layer "In4.Cu")
		(net "M_J_CPU1_SA_CB<7>")
	)
	(arc
		(start 133.216142 -249.017028)
		(mid 133.39965 -248.971534)
		(end 133.581902 -249.021854)
		(width 0.0889)
		(layer "In4.Cu")
		(net "M_J_CPU1_SA_CB<7>")
	)
	(arc
		(start 131.701794 -249.021854)
		(mid 131.98475 -249.098031)
		(end 132.267706 -249.021854)
		(width 0.0889)
		(layer "In4.Cu")
		(net "M_J_CPU1_SA_CB<7>")
	)
	(arc
		(start 135.461756 -249.021854)
		(mid 135.744712 -249.098031)
		(end 136.027668 -249.021854)
		(width 0.0889)
		(layer "In4.Cu")
		(net "M_J_CPU1_SA_CB<7>")
	)
	(arc
		(start 138.84783 -249.021854)
		(mid 139.034774 -248.971599)
		(end 139.221718 -249.021854)
		(width 0.0889)
		(layer "In4.Cu")
		(net "M_J_CPU1_SA_CB<7>")
	)
	(arc
		(start 141.101826 -249.021854)
		(mid 141.384782 -249.098031)
		(end 141.667738 -249.021854)
		(width 0.0889)
		(layer "In4.Cu")
		(net "M_J_CPU1_SA_CB<7>")
	)
	(arc
		(start 133.581902 -249.021854)
		(mid 133.864858 -249.098031)
		(end 134.147814 -249.021854)
		(width 0.0889)
		(layer "In4.Cu")
		(net "M_J_CPU1_SA_CB<7>")
	)
	(arc
		(start 131.383024 -248.995692)
		(mid 131.540534 -248.972494)
		(end 131.693412 -249.017028)
		(width 0.0889)
		(layer "In4.Cu")
		(net "M_J_CPU1_SA_CB<7>")
	)
	(arc
		(start 137.341864 -249.021854)
		(mid 137.62482 -249.098031)
		(end 137.907776 -249.021854)
		(width 0.0889)
		(layer "In4.Cu")
		(net "M_J_CPU1_SA_CB<7>")
	)
	(arc
		(start 142.98168 -249.021854)
		(mid 143.264636 -249.098031)
		(end 143.547592 -249.021854)
		(width 0.0889)
		(layer "In4.Cu")
		(net "M_J_CPU1_SA_CB<7>")
	)
	(arc
		(start 144.878044 -249.031252)
		(mid 145.154353 -249.098228)
		(end 145.428208 -249.021854)
		(width 0.0889)
		(layer "In4.Cu")
		(net "M_J_CPU1_SA_CB<7>")
	)
	(arc
		(start 138.281918 -249.021854)
		(mid 138.564874 -249.098031)
		(end 138.84783 -249.021854)
		(width 0.0889)
		(layer "In4.Cu")
		(net "M_J_CPU1_SA_CB<7>")
	)
	(arc
		(start 140.727684 -249.021854)
		(mid 140.909935 -248.971504)
		(end 141.093444 -249.017028)
		(width 0.0889)
		(layer "In4.Cu")
		(net "M_J_CPU1_SA_CB<7>")
	)
	(arc
		(start 137.916158 -249.017028)
		(mid 138.099666 -248.971534)
		(end 138.281918 -249.021854)
		(width 0.0889)
		(layer "In4.Cu")
		(net "M_J_CPU1_SA_CB<7>")
	)
	(arc
		(start 136.40181 -249.021854)
		(mid 136.684766 -249.098031)
		(end 136.967722 -249.021854)
		(width 0.0889)
		(layer "In4.Cu")
		(net "M_J_CPU1_SA_CB<7>")
	)
	(arc
		(start 132.641848 -249.021854)
		(mid 132.924804 -249.098031)
		(end 133.20776 -249.021854)
		(width 0.0889)
		(layer "In4.Cu")
		(net "M_J_CPU1_SA_CB<7>")
	)
	(arc
		(start 145.428208 -249.021854)
		(mid 145.610713 -248.971377)
		(end 145.794476 -249.017028)
		(width 0.0889)
		(layer "In4.Cu")
		(net "M_J_CPU1_SA_CB<7>")
	)
	(arc
		(start 140.161772 -249.021854)
		(mid 140.444728 -249.098031)
		(end 140.727684 -249.021854)
		(width 0.0889)
		(layer "In4.Cu")
		(net "M_J_CPU1_SA_CB<7>")
	)
	(arc
		(start 134.521702 -249.021854)
		(mid 134.804658 -249.098031)
		(end 135.087614 -249.021854)
		(width 0.0889)
		(layer "In4.Cu")
		(net "M_J_CPU1_SA_CB<7>")
	)
	(arc
		(start 144.488662 -249.021854)
		(mid 144.667649 -248.971684)
		(end 144.84858 -249.014234)
		(width 0.0889)
		(layer "In4.Cu")
		(net "M_J_CPU1_SA_CB<7>")
	)
	(arc
		(start 143.922242 -249.021854)
		(mid 144.196948 -249.098218)
		(end 144.47393 -249.03049)
		(width 0.0889)
		(layer "In4.Cu")
		(net "M_J_CPU1_SA_CB<7>")
	)
	(arc
		(start 143.555974 -249.017028)
		(mid 143.739736 -248.971412)
		(end 143.922242 -249.021854)
		(width 0.0889)
		(layer "In4.Cu")
		(net "M_J_CPU1_SA_CB<7>")
	)
	(arc
		(start 132.276088 -249.017028)
		(mid 132.459596 -248.971534)
		(end 132.641848 -249.021854)
		(width 0.0889)
		(layer "In4.Cu")
		(net "M_J_CPU1_SA_CB<7>")
	)
	(arc
		(start 141.67612 -249.017028)
		(mid 141.859628 -248.971534)
		(end 142.04188 -249.021854)
		(width 0.0889)
		(layer "In4.Cu")
		(net "M_J_CPU1_SA_CB<7>")
	)
	(arc
		(start 136.027668 -249.021854)
		(mid 136.209919 -248.971504)
		(end 136.393428 -249.017028)
		(width 0.0889)
		(layer "In4.Cu")
		(net "M_J_CPU1_SA_CB<7>")
	)
	(arc
		(start 139.78763 -249.021854)
		(mid 139.969881 -248.971504)
		(end 140.15339 -249.017028)
		(width 0.0889)
		(layer "In4.Cu")
		(net "M_J_CPU1_SA_CB<7>")
	)
	(arc
		(start 135.087614 -249.021854)
		(mid 135.269865 -248.971504)
		(end 135.453374 -249.017028)
		(width 0.0889)
		(layer "In4.Cu")
		(net "M_J_CPU1_SA_CB<7>")
	)
	(arc
		(start 142.04188 -249.021854)
		(mid 142.324836 -249.098031)
		(end 142.607792 -249.021854)
		(width 0.0889)
		(layer "In4.Cu")
		(net "M_J_CPU1_SA_CB<7>")
	)
	(arc
		(start 136.976104 -249.017028)
		(mid 137.159612 -248.971534)
		(end 137.341864 -249.021854)
		(width 0.0889)
		(layer "In4.Cu")
		(net "M_J_CPU1_SA_CB<7>")
	)
	(arc
		(start 139.221718 -249.021854)
		(mid 139.504674 -249.098031)
		(end 139.78763 -249.021854)
		(width 0.0889)
		(layer "In4.Cu")
		(net "M_J_CPU1_SA_CB<7>")
	)
	(arc
		(start 134.147814 -249.021854)
		(mid 134.334758 -248.971599)
		(end 134.521702 -249.021854)
		(width 0.0889)
		(layer "In4.Cu")
		(net "M_J_CPU1_SA_CB<7>")
	)
	(arc
		(start 142.607792 -249.021854)
		(mid 142.794736 -248.971599)
		(end 142.98168 -249.021854)
		(width 0.0889)
		(layer "In4.Cu")
		(net "M_J_CPU1_SA_CB<7>")
	)
	(segment
		(start 132.457952 -248.800366)
		(end 132.924804 -248.534428)
		(width 0.10668)
		(layer "F.Cu")
		(net "M_J_CPU1_SA_CB<6>")
	)
	(segment
		(start 144.384268 -248.207022)
		(end 144.39265 -248.211848)
		(width 0.0889)
		(layer "In4.Cu")
		(net "M_J_CPU1_SA_CB<6>")
	)
	(segment
		(start 158.199328 -248.16562)
		(end 163.538916 -242.826032)
		(width 0.14478)
		(layer "In4.Cu")
		(net "M_J_CPU1_SA_CB<6>")
	)
	(segment
		(start 182.113428 -241.9604)
		(end 186.634882 -241.9604)
		(width 0.14478)
		(layer "In4.Cu")
		(net "M_J_CPU1_SA_CB<6>")
	)
	(segment
		(start 162.162998 -245.762526)
		(end 165.11524 -242.810284)
		(width 0.14478)
		(layer "In4.Cu")
		(net "M_J_CPU1_SA_CB<6>")
	)
	(segment
		(start 148.960332 -248.16562)
		(end 158.199328 -248.16562)
		(width 0.14478)
		(layer "In4.Cu")
		(net "M_J_CPU1_SA_CB<6>")
	)
	(segment
		(start 147.239228 -248.543064)
		(end 147.79371 -248.543064)
		(width 0.0889)
		(layer "In4.Cu")
		(net "M_J_CPU1_SA_CB<6>")
	)
	(segment
		(start 161.934398 -245.762526)
		(end 162.162998 -245.762526)
		(width 0.14478)
		(layer "In4.Cu")
		(net "M_J_CPU1_SA_CB<6>")
	)
	(segment
		(start 133.103366 -248.207022)
		(end 133.111748 -248.211848)
		(width 0.0889)
		(layer "In4.Cu")
		(net "M_J_CPU1_SA_CB<6>")
	)
	(segment
		(start 145.52168 -248.280428)
		(end 145.725896 -248.484644)
		(width 0.0889)
		(layer "In4.Cu")
		(net "M_J_CPU1_SA_CB<6>")
	)
	(segment
		(start 132.770626 -248.268998)
		(end 132.792978 -248.185686)
		(width 0.0889)
		(layer "In4.Cu")
		(net "M_J_CPU1_SA_CB<6>")
	)
	(segment
		(start 186.634882 -241.9604)
		(end 187.060078 -241.535204)
		(width 0.14478)
		(layer "In4.Cu")
		(net "M_J_CPU1_SA_CB<6>")
	)
	(segment
		(start 147.155408 -248.626884)
		(end 147.239228 -248.543064)
		(width 0.0889)
		(layer "In4.Cu")
		(net "M_J_CPU1_SA_CB<6>")
	)
	(segment
		(start 146.098768 -248.626884)
		(end 147.155408 -248.626884)
		(width 0.0889)
		(layer "In4.Cu")
		(net "M_J_CPU1_SA_CB<6>")
	)
	(segment
		(start 132.924804 -248.534428)
		(end 132.770626 -248.268998)
		(width 0.0889)
		(layer "In4.Cu")
		(net "M_J_CPU1_SA_CB<6>")
	)
	(segment
		(start 163.92906 -242.987576)
		(end 163.92906 -243.216176)
		(width 0.14478)
		(layer "In4.Cu")
		(net "M_J_CPU1_SA_CB<6>")
	)
	(segment
		(start 140.257784 -248.211848)
		(end 140.266166 -248.207022)
		(width 0.0889)
		(layer "In4.Cu")
		(net "M_J_CPU1_SA_CB<6>")
	)
	(segment
		(start 148.582888 -248.543064)
		(end 148.960332 -248.16562)
		(width 0.14478)
		(layer "In4.Cu")
		(net "M_J_CPU1_SA_CB<6>")
	)
	(segment
		(start 135.557768 -248.211848)
		(end 135.56615 -248.207022)
		(width 0.0889)
		(layer "In4.Cu")
		(net "M_J_CPU1_SA_CB<6>")
	)
	(segment
		(start 181.263544 -242.810284)
		(end 182.113428 -241.9604)
		(width 0.14478)
		(layer "In4.Cu")
		(net "M_J_CPU1_SA_CB<6>")
	)
	(segment
		(start 145.725896 -248.484644)
		(end 145.956528 -248.484644)
		(width 0.0889)
		(layer "In4.Cu")
		(net "M_J_CPU1_SA_CB<6>")
	)
	(segment
		(start 134.04342 -248.207022)
		(end 134.051802 -248.211848)
		(width 0.0889)
		(layer "In4.Cu")
		(net "M_J_CPU1_SA_CB<6>")
	)
	(segment
		(start 134.617714 -248.211848)
		(end 134.626096 -248.207022)
		(width 0.0889)
		(layer "In4.Cu")
		(net "M_J_CPU1_SA_CB<6>")
	)
	(segment
		(start 161.772854 -245.600982)
		(end 161.934398 -245.762526)
		(width 0.14478)
		(layer "In4.Cu")
		(net "M_J_CPU1_SA_CB<6>")
	)
	(segment
		(start 144.952466 -248.215404)
		(end 144.958054 -248.212102)
		(width 0.0889)
		(layer "In4.Cu")
		(net "M_J_CPU1_SA_CB<6>")
	)
	(segment
		(start 161.772854 -245.372382)
		(end 161.772854 -245.600982)
		(width 0.14478)
		(layer "In4.Cu")
		(net "M_J_CPU1_SA_CB<6>")
	)
	(segment
		(start 163.767516 -242.826032)
		(end 163.92906 -242.987576)
		(width 0.14478)
		(layer "In4.Cu")
		(net "M_J_CPU1_SA_CB<6>")
	)
	(segment
		(start 147.79371 -248.543064)
		(end 148.582888 -248.543064)
		(width 0.14478)
		(layer "In4.Cu")
		(net "M_J_CPU1_SA_CB<6>")
	)
	(segment
		(start 142.503398 -248.207022)
		(end 142.51178 -248.211848)
		(width 0.0889)
		(layer "In4.Cu")
		(net "M_J_CPU1_SA_CB<6>")
	)
	(segment
		(start 143.077692 -248.211848)
		(end 143.086074 -248.207022)
		(width 0.0889)
		(layer "In4.Cu")
		(net "M_J_CPU1_SA_CB<6>")
	)
	(segment
		(start 143.451834 -248.211848)
		(end 143.462248 -248.217944)
		(width 0.0889)
		(layer "In4.Cu")
		(net "M_J_CPU1_SA_CB<6>")
	)
	(segment
		(start 163.92906 -243.216176)
		(end 161.772854 -245.372382)
		(width 0.14478)
		(layer "In4.Cu")
		(net "M_J_CPU1_SA_CB<6>")
	)
	(segment
		(start 144.958054 -248.212102)
		(end 144.976342 -248.201688)
		(width 0.0889)
		(layer "In4.Cu")
		(net "M_J_CPU1_SA_CB<6>")
	)
	(segment
		(start 165.11524 -242.810284)
		(end 181.263544 -242.810284)
		(width 0.14478)
		(layer "In4.Cu")
		(net "M_J_CPU1_SA_CB<6>")
	)
	(segment
		(start 138.743436 -248.207022)
		(end 138.751818 -248.211848)
		(width 0.0889)
		(layer "In4.Cu")
		(net "M_J_CPU1_SA_CB<6>")
	)
	(segment
		(start 163.538916 -242.826032)
		(end 163.767516 -242.826032)
		(width 0.14478)
		(layer "In4.Cu")
		(net "M_J_CPU1_SA_CB<6>")
	)
	(segment
		(start 137.803382 -248.207022)
		(end 137.811764 -248.211848)
		(width 0.0889)
		(layer "In4.Cu")
		(net "M_J_CPU1_SA_CB<6>")
	)
	(segment
		(start 145.956528 -248.484644)
		(end 146.098768 -248.626884)
		(width 0.0889)
		(layer "In4.Cu")
		(net "M_J_CPU1_SA_CB<6>")
	)
	(segment
		(start 139.31773 -248.211848)
		(end 139.326112 -248.207022)
		(width 0.0889)
		(layer "In4.Cu")
		(net "M_J_CPU1_SA_CB<6>")
	)
	(arc
		(start 139.691872 -248.211848)
		(mid 139.974828 -248.288025)
		(end 140.257784 -248.211848)
		(width 0.0889)
		(layer "In4.Cu")
		(net "M_J_CPU1_SA_CB<6>")
	)
	(arc
		(start 133.67766 -248.211848)
		(mid 133.859911 -248.161498)
		(end 134.04342 -248.207022)
		(width 0.0889)
		(layer "In4.Cu")
		(net "M_J_CPU1_SA_CB<6>")
	)
	(arc
		(start 144.018 -248.211848)
		(mid 144.200505 -248.161371)
		(end 144.384268 -248.207022)
		(width 0.0889)
		(layer "In4.Cu")
		(net "M_J_CPU1_SA_CB<6>")
	)
	(arc
		(start 143.462248 -248.217944)
		(mid 143.740934 -248.288164)
		(end 144.018 -248.211848)
		(width 0.0889)
		(layer "In4.Cu")
		(net "M_J_CPU1_SA_CB<6>")
	)
	(arc
		(start 141.197838 -248.211848)
		(mid 141.384782 -248.161593)
		(end 141.571726 -248.211848)
		(width 0.0889)
		(layer "In4.Cu")
		(net "M_J_CPU1_SA_CB<6>")
	)
	(arc
		(start 135.56615 -248.207022)
		(mid 135.749658 -248.161528)
		(end 135.93191 -248.211848)
		(width 0.0889)
		(layer "In4.Cu")
		(net "M_J_CPU1_SA_CB<6>")
	)
	(arc
		(start 134.991856 -248.211848)
		(mid 135.274812 -248.288025)
		(end 135.557768 -248.211848)
		(width 0.0889)
		(layer "In4.Cu")
		(net "M_J_CPU1_SA_CB<6>")
	)
	(arc
		(start 144.39265 -248.211848)
		(mid 144.672078 -248.288014)
		(end 144.952466 -248.215404)
		(width 0.0889)
		(layer "In4.Cu")
		(net "M_J_CPU1_SA_CB<6>")
	)
	(arc
		(start 135.93191 -248.211848)
		(mid 136.214866 -248.288025)
		(end 136.497822 -248.211848)
		(width 0.0889)
		(layer "In4.Cu")
		(net "M_J_CPU1_SA_CB<6>")
	)
	(arc
		(start 137.437622 -248.211848)
		(mid 137.619873 -248.161498)
		(end 137.803382 -248.207022)
		(width 0.0889)
		(layer "In4.Cu")
		(net "M_J_CPU1_SA_CB<6>")
	)
	(arc
		(start 136.497822 -248.211848)
		(mid 136.684766 -248.161593)
		(end 136.87171 -248.211848)
		(width 0.0889)
		(layer "In4.Cu")
		(net "M_J_CPU1_SA_CB<6>")
	)
	(arc
		(start 137.811764 -248.211848)
		(mid 138.09472 -248.288025)
		(end 138.377676 -248.211848)
		(width 0.0889)
		(layer "In4.Cu")
		(net "M_J_CPU1_SA_CB<6>")
	)
	(arc
		(start 144.976342 -248.201688)
		(mid 145.155571 -248.161535)
		(end 145.332196 -248.211848)
		(width 0.0889)
		(layer "In4.Cu")
		(net "M_J_CPU1_SA_CB<6>")
	)
	(arc
		(start 141.571726 -248.211848)
		(mid 141.854682 -248.288025)
		(end 142.137638 -248.211848)
		(width 0.0889)
		(layer "In4.Cu")
		(net "M_J_CPU1_SA_CB<6>")
	)
	(arc
		(start 139.326112 -248.207022)
		(mid 139.50962 -248.161528)
		(end 139.691872 -248.211848)
		(width 0.0889)
		(layer "In4.Cu")
		(net "M_J_CPU1_SA_CB<6>")
	)
	(arc
		(start 140.631926 -248.211848)
		(mid 140.914882 -248.288025)
		(end 141.197838 -248.211848)
		(width 0.0889)
		(layer "In4.Cu")
		(net "M_J_CPU1_SA_CB<6>")
	)
	(arc
		(start 138.751818 -248.211848)
		(mid 139.034774 -248.288025)
		(end 139.31773 -248.211848)
		(width 0.0889)
		(layer "In4.Cu")
		(net "M_J_CPU1_SA_CB<6>")
	)
	(arc
		(start 133.111748 -248.211848)
		(mid 133.394704 -248.288025)
		(end 133.67766 -248.211848)
		(width 0.0889)
		(layer "In4.Cu")
		(net "M_J_CPU1_SA_CB<6>")
	)
	(arc
		(start 145.332196 -248.211848)
		(mid 145.423854 -248.254654)
		(end 145.52168 -248.280428)
		(width 0.0889)
		(layer "In4.Cu")
		(net "M_J_CPU1_SA_CB<6>")
	)
	(arc
		(start 136.87171 -248.211848)
		(mid 137.154666 -248.288025)
		(end 137.437622 -248.211848)
		(width 0.0889)
		(layer "In4.Cu")
		(net "M_J_CPU1_SA_CB<6>")
	)
	(arc
		(start 138.377676 -248.211848)
		(mid 138.559927 -248.161498)
		(end 138.743436 -248.207022)
		(width 0.0889)
		(layer "In4.Cu")
		(net "M_J_CPU1_SA_CB<6>")
	)
	(arc
		(start 132.792978 -248.185686)
		(mid 132.950488 -248.162488)
		(end 133.103366 -248.207022)
		(width 0.0889)
		(layer "In4.Cu")
		(net "M_J_CPU1_SA_CB<6>")
	)
	(arc
		(start 134.051802 -248.211848)
		(mid 134.334758 -248.288025)
		(end 134.617714 -248.211848)
		(width 0.0889)
		(layer "In4.Cu")
		(net "M_J_CPU1_SA_CB<6>")
	)
	(arc
		(start 140.266166 -248.207022)
		(mid 140.449674 -248.161528)
		(end 140.631926 -248.211848)
		(width 0.0889)
		(layer "In4.Cu")
		(net "M_J_CPU1_SA_CB<6>")
	)
	(arc
		(start 142.51178 -248.211848)
		(mid 142.794736 -248.288025)
		(end 143.077692 -248.211848)
		(width 0.0889)
		(layer "In4.Cu")
		(net "M_J_CPU1_SA_CB<6>")
	)
	(arc
		(start 143.086074 -248.207022)
		(mid 143.269582 -248.161528)
		(end 143.451834 -248.211848)
		(width 0.0889)
		(layer "In4.Cu")
		(net "M_J_CPU1_SA_CB<6>")
	)
	(arc
		(start 134.626096 -248.207022)
		(mid 134.809604 -248.161528)
		(end 134.991856 -248.211848)
		(width 0.0889)
		(layer "In4.Cu")
		(net "M_J_CPU1_SA_CB<6>")
	)
	(arc
		(start 142.137638 -248.211848)
		(mid 142.319889 -248.161498)
		(end 142.503398 -248.207022)
		(width 0.0889)
		(layer "In4.Cu")
		(net "M_J_CPU1_SA_CB<6>")
	)
	(segment
		(start 130.577844 -248.800366)
		(end 131.044696 -248.534428)
		(width 0.10668)
		(layer "F.Cu")
		(net "M_J_CPU1_SA_CB<5>")
	)
	(segment
		(start 188.560456 -242.104418)
		(end 188.790834 -242.104418)
		(width 0.14478)
		(layer "In4.Cu")
		(net "M_J_CPU1_SA_CB<5>")
	)
	(segment
		(start 144.952466 -248.853452)
		(end 144.958054 -248.856754)
		(width 0.0889)
		(layer "In4.Cu")
		(net "M_J_CPU1_SA_CB<5>")
	)
	(segment
		(start 164.12083 -244.510306)
		(end 180.335936 -244.510306)
		(width 0.14478)
		(layer "In4.Cu")
		(net "M_J_CPU1_SA_CB<5>")
	)
	(segment
		(start 145.883884 -248.848372)
		(end 146.056858 -248.941844)
		(width 0.0889)
		(layer "In4.Cu")
		(net "M_J_CPU1_SA_CB<5>")
	)
	(segment
		(start 144.958054 -248.856754)
		(end 144.976342 -248.867168)
		(width 0.0889)
		(layer "In4.Cu")
		(net "M_J_CPU1_SA_CB<5>")
	)
	(segment
		(start 188.790834 -242.104418)
		(end 188.953902 -242.267486)
		(width 0.14478)
		(layer "In4.Cu")
		(net "M_J_CPU1_SA_CB<5>")
	)
	(segment
		(start 188.23432 -242.810284)
		(end 188.397388 -242.647216)
		(width 0.14478)
		(layer "In4.Cu")
		(net "M_J_CPU1_SA_CB<5>")
	)
	(segment
		(start 142.503398 -248.861834)
		(end 142.51178 -248.857008)
		(width 0.0889)
		(layer "In4.Cu")
		(net "M_J_CPU1_SA_CB<5>")
	)
	(segment
		(start 188.953902 -242.647216)
		(end 189.11697 -242.810284)
		(width 0.14478)
		(layer "In4.Cu")
		(net "M_J_CPU1_SA_CB<5>")
	)
	(segment
		(start 131.198874 -248.799858)
		(end 131.29514 -248.825258)
		(width 0.0889)
		(layer "In4.Cu")
		(net "M_J_CPU1_SA_CB<5>")
	)
	(segment
		(start 190.735204 -242.810284)
		(end 191.160146 -242.385342)
		(width 0.14478)
		(layer "In4.Cu")
		(net "M_J_CPU1_SA_CB<5>")
	)
	(segment
		(start 160.858962 -246.212106)
		(end 162.41903 -246.212106)
		(width 0.14478)
		(layer "In4.Cu")
		(net "M_J_CPU1_SA_CB<5>")
	)
	(segment
		(start 138.743436 -248.861834)
		(end 138.751818 -248.857008)
		(width 0.0889)
		(layer "In4.Cu")
		(net "M_J_CPU1_SA_CB<5>")
	)
	(segment
		(start 162.41903 -246.212106)
		(end 164.12083 -244.510306)
		(width 0.14478)
		(layer "In4.Cu")
		(net "M_J_CPU1_SA_CB<5>")
	)
	(segment
		(start 134.04342 -248.861834)
		(end 134.051802 -248.857008)
		(width 0.0889)
		(layer "In4.Cu")
		(net "M_J_CPU1_SA_CB<5>")
	)
	(segment
		(start 190.06693 -242.267486)
		(end 190.06693 -242.647216)
		(width 0.14478)
		(layer "In4.Cu")
		(net "M_J_CPU1_SA_CB<5>")
	)
	(segment
		(start 182.035958 -242.810284)
		(end 188.23432 -242.810284)
		(width 0.14478)
		(layer "In4.Cu")
		(net "M_J_CPU1_SA_CB<5>")
	)
	(segment
		(start 149.016466 -248.767346)
		(end 158.303722 -248.767346)
		(width 0.14478)
		(layer "In4.Cu")
		(net "M_J_CPU1_SA_CB<5>")
	)
	(segment
		(start 147.828254 -249.002804)
		(end 148.781008 -249.002804)
		(width 0.14478)
		(layer "In4.Cu")
		(net "M_J_CPU1_SA_CB<5>")
	)
	(segment
		(start 189.347348 -242.810284)
		(end 189.510416 -242.647216)
		(width 0.14478)
		(layer "In4.Cu")
		(net "M_J_CPU1_SA_CB<5>")
	)
	(segment
		(start 189.903862 -242.104418)
		(end 190.06693 -242.267486)
		(width 0.14478)
		(layer "In4.Cu")
		(net "M_J_CPU1_SA_CB<5>")
	)
	(segment
		(start 189.11697 -242.810284)
		(end 189.347348 -242.810284)
		(width 0.14478)
		(layer "In4.Cu")
		(net "M_J_CPU1_SA_CB<5>")
	)
	(segment
		(start 158.303722 -248.767346)
		(end 160.858962 -246.212106)
		(width 0.14478)
		(layer "In4.Cu")
		(net "M_J_CPU1_SA_CB<5>")
	)
	(segment
		(start 146.056858 -248.941844)
		(end 147.394168 -248.941844)
		(width 0.0889)
		(layer "In4.Cu")
		(net "M_J_CPU1_SA_CB<5>")
	)
	(segment
		(start 147.394168 -248.941844)
		(end 147.455128 -249.002804)
		(width 0.0889)
		(layer "In4.Cu")
		(net "M_J_CPU1_SA_CB<5>")
	)
	(segment
		(start 137.803382 -248.861834)
		(end 137.811764 -248.857008)
		(width 0.0889)
		(layer "In4.Cu")
		(net "M_J_CPU1_SA_CB<5>")
	)
	(segment
		(start 135.557768 -248.857008)
		(end 135.56615 -248.861834)
		(width 0.0889)
		(layer "In4.Cu")
		(net "M_J_CPU1_SA_CB<5>")
	)
	(segment
		(start 134.617714 -248.857008)
		(end 134.626096 -248.861834)
		(width 0.0889)
		(layer "In4.Cu")
		(net "M_J_CPU1_SA_CB<5>")
	)
	(segment
		(start 143.451834 -248.857008)
		(end 143.466566 -248.848372)
		(width 0.0889)
		(layer "In4.Cu")
		(net "M_J_CPU1_SA_CB<5>")
	)
	(segment
		(start 139.31773 -248.857008)
		(end 139.326112 -248.861834)
		(width 0.0889)
		(layer "In4.Cu")
		(net "M_J_CPU1_SA_CB<5>")
	)
	(segment
		(start 180.335936 -244.510306)
		(end 182.035958 -242.810284)
		(width 0.14478)
		(layer "In4.Cu")
		(net "M_J_CPU1_SA_CB<5>")
	)
	(segment
		(start 190.229998 -242.810284)
		(end 190.735204 -242.810284)
		(width 0.14478)
		(layer "In4.Cu")
		(net "M_J_CPU1_SA_CB<5>")
	)
	(segment
		(start 188.397388 -242.647216)
		(end 188.397388 -242.267486)
		(width 0.14478)
		(layer "In4.Cu")
		(net "M_J_CPU1_SA_CB<5>")
	)
	(segment
		(start 189.510416 -242.267486)
		(end 189.673484 -242.104418)
		(width 0.14478)
		(layer "In4.Cu")
		(net "M_J_CPU1_SA_CB<5>")
	)
	(segment
		(start 131.044696 -248.534428)
		(end 131.198874 -248.799858)
		(width 0.0889)
		(layer "In4.Cu")
		(net "M_J_CPU1_SA_CB<5>")
	)
	(segment
		(start 143.077692 -248.857008)
		(end 143.086074 -248.861834)
		(width 0.0889)
		(layer "In4.Cu")
		(net "M_J_CPU1_SA_CB<5>")
	)
	(segment
		(start 147.455128 -249.002804)
		(end 147.828254 -249.002804)
		(width 0.0889)
		(layer "In4.Cu")
		(net "M_J_CPU1_SA_CB<5>")
	)
	(segment
		(start 140.257784 -248.857008)
		(end 140.266166 -248.861834)
		(width 0.0889)
		(layer "In4.Cu")
		(net "M_J_CPU1_SA_CB<5>")
	)
	(segment
		(start 189.510416 -242.647216)
		(end 189.510416 -242.267486)
		(width 0.14478)
		(layer "In4.Cu")
		(net "M_J_CPU1_SA_CB<5>")
	)
	(segment
		(start 188.953902 -242.267486)
		(end 188.953902 -242.647216)
		(width 0.14478)
		(layer "In4.Cu")
		(net "M_J_CPU1_SA_CB<5>")
	)
	(segment
		(start 148.781008 -249.002804)
		(end 149.016466 -248.767346)
		(width 0.14478)
		(layer "In4.Cu")
		(net "M_J_CPU1_SA_CB<5>")
	)
	(segment
		(start 133.103366 -248.861834)
		(end 133.111748 -248.857008)
		(width 0.0889)
		(layer "In4.Cu")
		(net "M_J_CPU1_SA_CB<5>")
	)
	(segment
		(start 144.380966 -248.863866)
		(end 144.39265 -248.857008)
		(width 0.0889)
		(layer "In4.Cu")
		(net "M_J_CPU1_SA_CB<5>")
	)
	(segment
		(start 190.06693 -242.647216)
		(end 190.229998 -242.810284)
		(width 0.14478)
		(layer "In4.Cu")
		(net "M_J_CPU1_SA_CB<5>")
	)
	(segment
		(start 189.673484 -242.104418)
		(end 189.903862 -242.104418)
		(width 0.14478)
		(layer "In4.Cu")
		(net "M_J_CPU1_SA_CB<5>")
	)
	(segment
		(start 188.397388 -242.267486)
		(end 188.560456 -242.104418)
		(width 0.14478)
		(layer "In4.Cu")
		(net "M_J_CPU1_SA_CB<5>")
	)
	(arc
		(start 133.111748 -248.857008)
		(mid 133.394704 -248.780831)
		(end 133.67766 -248.857008)
		(width 0.0889)
		(layer "In4.Cu")
		(net "M_J_CPU1_SA_CB<5>")
	)
	(arc
		(start 133.67766 -248.857008)
		(mid 133.859911 -248.907358)
		(end 134.04342 -248.861834)
		(width 0.0889)
		(layer "In4.Cu")
		(net "M_J_CPU1_SA_CB<5>")
	)
	(arc
		(start 140.631926 -248.857008)
		(mid 140.914882 -248.780831)
		(end 141.197838 -248.857008)
		(width 0.0889)
		(layer "In4.Cu")
		(net "M_J_CPU1_SA_CB<5>")
	)
	(arc
		(start 131.797806 -248.857008)
		(mid 131.98475 -248.907263)
		(end 132.171694 -248.857008)
		(width 0.0889)
		(layer "In4.Cu")
		(net "M_J_CPU1_SA_CB<5>")
	)
	(arc
		(start 132.171694 -248.857008)
		(mid 132.45465 -248.780831)
		(end 132.737606 -248.857008)
		(width 0.0889)
		(layer "In4.Cu")
		(net "M_J_CPU1_SA_CB<5>")
	)
	(arc
		(start 141.197838 -248.857008)
		(mid 141.384782 -248.907263)
		(end 141.571726 -248.857008)
		(width 0.0889)
		(layer "In4.Cu")
		(net "M_J_CPU1_SA_CB<5>")
	)
	(arc
		(start 139.691872 -248.857008)
		(mid 139.974828 -248.780831)
		(end 140.257784 -248.857008)
		(width 0.0889)
		(layer "In4.Cu")
		(net "M_J_CPU1_SA_CB<5>")
	)
	(arc
		(start 141.571726 -248.857008)
		(mid 141.854682 -248.780831)
		(end 142.137638 -248.857008)
		(width 0.0889)
		(layer "In4.Cu")
		(net "M_J_CPU1_SA_CB<5>")
	)
	(arc
		(start 139.326112 -248.861834)
		(mid 139.50962 -248.907328)
		(end 139.691872 -248.857008)
		(width 0.0889)
		(layer "In4.Cu")
		(net "M_J_CPU1_SA_CB<5>")
	)
	(arc
		(start 144.39265 -248.857008)
		(mid 144.672078 -248.780842)
		(end 144.952466 -248.853452)
		(width 0.0889)
		(layer "In4.Cu")
		(net "M_J_CPU1_SA_CB<5>")
	)
	(arc
		(start 136.87171 -248.857008)
		(mid 137.154666 -248.780831)
		(end 137.437622 -248.857008)
		(width 0.0889)
		(layer "In4.Cu")
		(net "M_J_CPU1_SA_CB<5>")
	)
	(arc
		(start 135.56615 -248.861834)
		(mid 135.749658 -248.907328)
		(end 135.93191 -248.857008)
		(width 0.0889)
		(layer "In4.Cu")
		(net "M_J_CPU1_SA_CB<5>")
	)
	(arc
		(start 132.737606 -248.857008)
		(mid 132.919857 -248.907358)
		(end 133.103366 -248.861834)
		(width 0.0889)
		(layer "In4.Cu")
		(net "M_J_CPU1_SA_CB<5>")
	)
	(arc
		(start 135.93191 -248.857008)
		(mid 136.214866 -248.780831)
		(end 136.497822 -248.857008)
		(width 0.0889)
		(layer "In4.Cu")
		(net "M_J_CPU1_SA_CB<5>")
	)
	(arc
		(start 136.497822 -248.857008)
		(mid 136.684766 -248.907263)
		(end 136.87171 -248.857008)
		(width 0.0889)
		(layer "In4.Cu")
		(net "M_J_CPU1_SA_CB<5>")
	)
	(arc
		(start 138.751818 -248.857008)
		(mid 139.034774 -248.780831)
		(end 139.31773 -248.857008)
		(width 0.0889)
		(layer "In4.Cu")
		(net "M_J_CPU1_SA_CB<5>")
	)
	(arc
		(start 134.991856 -248.857008)
		(mid 135.274812 -248.780831)
		(end 135.557768 -248.857008)
		(width 0.0889)
		(layer "In4.Cu")
		(net "M_J_CPU1_SA_CB<5>")
	)
	(arc
		(start 142.137638 -248.857008)
		(mid 142.319889 -248.907358)
		(end 142.503398 -248.861834)
		(width 0.0889)
		(layer "In4.Cu")
		(net "M_J_CPU1_SA_CB<5>")
	)
	(arc
		(start 144.976342 -248.867168)
		(mid 145.155571 -248.907321)
		(end 145.332196 -248.857008)
		(width 0.0889)
		(layer "In4.Cu")
		(net "M_J_CPU1_SA_CB<5>")
	)
	(arc
		(start 144.018254 -248.857008)
		(mid 144.198712 -248.907452)
		(end 144.380966 -248.863866)
		(width 0.0889)
		(layer "In4.Cu")
		(net "M_J_CPU1_SA_CB<5>")
	)
	(arc
		(start 134.051802 -248.857008)
		(mid 134.334758 -248.780831)
		(end 134.617714 -248.857008)
		(width 0.0889)
		(layer "In4.Cu")
		(net "M_J_CPU1_SA_CB<5>")
	)
	(arc
		(start 138.377676 -248.857008)
		(mid 138.559927 -248.907358)
		(end 138.743436 -248.861834)
		(width 0.0889)
		(layer "In4.Cu")
		(net "M_J_CPU1_SA_CB<5>")
	)
	(arc
		(start 145.332196 -248.857008)
		(mid 145.606902 -248.780644)
		(end 145.883884 -248.848372)
		(width 0.0889)
		(layer "In4.Cu")
		(net "M_J_CPU1_SA_CB<5>")
	)
	(arc
		(start 143.086074 -248.861834)
		(mid 143.269582 -248.907328)
		(end 143.451834 -248.857008)
		(width 0.0889)
		(layer "In4.Cu")
		(net "M_J_CPU1_SA_CB<5>")
	)
	(arc
		(start 134.626096 -248.861834)
		(mid 134.809604 -248.907328)
		(end 134.991856 -248.857008)
		(width 0.0889)
		(layer "In4.Cu")
		(net "M_J_CPU1_SA_CB<5>")
	)
	(arc
		(start 143.466566 -248.848372)
		(mid 143.743549 -248.780568)
		(end 144.018254 -248.857008)
		(width 0.0889)
		(layer "In4.Cu")
		(net "M_J_CPU1_SA_CB<5>")
	)
	(arc
		(start 131.29514 -248.825258)
		(mid 131.550205 -248.781907)
		(end 131.797806 -248.857008)
		(width 0.0889)
		(layer "In4.Cu")
		(net "M_J_CPU1_SA_CB<5>")
	)
	(arc
		(start 140.266166 -248.861834)
		(mid 140.449674 -248.907328)
		(end 140.631926 -248.857008)
		(width 0.0889)
		(layer "In4.Cu")
		(net "M_J_CPU1_SA_CB<5>")
	)
	(arc
		(start 137.437622 -248.857008)
		(mid 137.619873 -248.907358)
		(end 137.803382 -248.861834)
		(width 0.0889)
		(layer "In4.Cu")
		(net "M_J_CPU1_SA_CB<5>")
	)
	(arc
		(start 137.811764 -248.857008)
		(mid 138.09472 -248.780831)
		(end 138.377676 -248.857008)
		(width 0.0889)
		(layer "In4.Cu")
		(net "M_J_CPU1_SA_CB<5>")
	)
	(arc
		(start 142.51178 -248.857008)
		(mid 142.794736 -248.780831)
		(end 143.077692 -248.857008)
		(width 0.0889)
		(layer "In4.Cu")
		(net "M_J_CPU1_SA_CB<5>")
	)
	(segment
		(start 131.987798 -247.99036)
		(end 132.45465 -247.724422)
		(width 0.10668)
		(layer "F.Cu")
		(net "M_J_CPU1_SA_CB<4>")
	)
	(segment
		(start 166.89451 -241.9604)
		(end 167.056054 -241.798856)
		(width 0.14478)
		(layer "In4.Cu")
		(net "M_J_CPU1_SA_CB<4>")
	)
	(segment
		(start 166.50462 -241.798856)
		(end 166.666164 -241.9604)
		(width 0.14478)
		(layer "In4.Cu")
		(net "M_J_CPU1_SA_CB<4>")
	)
	(segment
		(start 166.343076 -241.320066)
		(end 166.50462 -241.48161)
		(width 0.14478)
		(layer "In4.Cu")
		(net "M_J_CPU1_SA_CB<4>")
	)
	(segment
		(start 144.862296 -248.046748)
		(end 144.878044 -248.037604)
		(width 0.0889)
		(layer "In4.Cu")
		(net "M_J_CPU1_SA_CB<4>")
	)
	(segment
		(start 165.401752 -241.798856)
		(end 165.563296 -241.9604)
		(width 0.14478)
		(layer "In4.Cu")
		(net "M_J_CPU1_SA_CB<4>")
	)
	(segment
		(start 144.477994 -248.040906)
		(end 144.488408 -248.047002)
		(width 0.0889)
		(layer "In4.Cu")
		(net "M_J_CPU1_SA_CB<4>")
	)
	(segment
		(start 144.84604 -248.056146)
		(end 144.862296 -248.046748)
		(width 0.0889)
		(layer "In4.Cu")
		(net "M_J_CPU1_SA_CB<4>")
	)
	(segment
		(start 148.754592 -247.71604)
		(end 157.49651 -247.71604)
		(width 0.14478)
		(layer "In4.Cu")
		(net "M_J_CPU1_SA_CB<4>")
	)
	(segment
		(start 148.387308 -248.083324)
		(end 148.754592 -247.71604)
		(width 0.14478)
		(layer "In4.Cu")
		(net "M_J_CPU1_SA_CB<4>")
	)
	(segment
		(start 135.453374 -248.051828)
		(end 135.461756 -248.047002)
		(width 0.0889)
		(layer "In4.Cu")
		(net "M_J_CPU1_SA_CB<4>")
	)
	(segment
		(start 136.393428 -248.051828)
		(end 136.40181 -248.047002)
		(width 0.0889)
		(layer "In4.Cu")
		(net "M_J_CPU1_SA_CB<4>")
	)
	(segment
		(start 190.735204 -241.110262)
		(end 191.160146 -240.68532)
		(width 0.14478)
		(layer "In4.Cu")
		(net "M_J_CPU1_SA_CB<4>")
	)
	(segment
		(start 147.79371 -248.083324)
		(end 148.387308 -248.083324)
		(width 0.14478)
		(layer "In4.Cu")
		(net "M_J_CPU1_SA_CB<4>")
	)
	(segment
		(start 165.791642 -241.9604)
		(end 165.953186 -241.798856)
		(width 0.14478)
		(layer "In4.Cu")
		(net "M_J_CPU1_SA_CB<4>")
	)
	(segment
		(start 165.240208 -241.320066)
		(end 165.401752 -241.48161)
		(width 0.14478)
		(layer "In4.Cu")
		(net "M_J_CPU1_SA_CB<4>")
	)
	(segment
		(start 165.563296 -241.9604)
		(end 165.791642 -241.9604)
		(width 0.14478)
		(layer "In4.Cu")
		(net "M_J_CPU1_SA_CB<4>")
	)
	(segment
		(start 163.25215 -241.9604)
		(end 164.688774 -241.9604)
		(width 0.14478)
		(layer "In4.Cu")
		(net "M_J_CPU1_SA_CB<4>")
	)
	(segment
		(start 147.236688 -248.083324)
		(end 147.79371 -248.083324)
		(width 0.0889)
		(layer "In4.Cu")
		(net "M_J_CPU1_SA_CB<4>")
	)
	(segment
		(start 157.49651 -247.71604)
		(end 163.25215 -241.9604)
		(width 0.14478)
		(layer "In4.Cu")
		(net "M_J_CPU1_SA_CB<4>")
	)
	(segment
		(start 167.056054 -241.48161)
		(end 167.217598 -241.320066)
		(width 0.14478)
		(layer "In4.Cu")
		(net "M_J_CPU1_SA_CB<4>")
	)
	(segment
		(start 165.953186 -241.798856)
		(end 165.953186 -241.48161)
		(width 0.14478)
		(layer "In4.Cu")
		(net "M_J_CPU1_SA_CB<4>")
	)
	(segment
		(start 180.614066 -241.9604)
		(end 181.464204 -241.110262)
		(width 0.14478)
		(layer "In4.Cu")
		(net "M_J_CPU1_SA_CB<4>")
	)
	(segment
		(start 167.769032 -241.9604)
		(end 180.614066 -241.9604)
		(width 0.14478)
		(layer "In4.Cu")
		(net "M_J_CPU1_SA_CB<4>")
	)
	(segment
		(start 165.401752 -241.48161)
		(end 165.401752 -241.798856)
		(width 0.14478)
		(layer "In4.Cu")
		(net "M_J_CPU1_SA_CB<4>")
	)
	(segment
		(start 164.850318 -241.48161)
		(end 165.011862 -241.320066)
		(width 0.14478)
		(layer "In4.Cu")
		(net "M_J_CPU1_SA_CB<4>")
	)
	(segment
		(start 140.15339 -248.051828)
		(end 140.161772 -248.047002)
		(width 0.0889)
		(layer "In4.Cu")
		(net "M_J_CPU1_SA_CB<4>")
	)
	(segment
		(start 137.907776 -248.047002)
		(end 137.916158 -248.051828)
		(width 0.0889)
		(layer "In4.Cu")
		(net "M_J_CPU1_SA_CB<4>")
	)
	(segment
		(start 167.445944 -241.320066)
		(end 167.607488 -241.48161)
		(width 0.14478)
		(layer "In4.Cu")
		(net "M_J_CPU1_SA_CB<4>")
	)
	(segment
		(start 166.50462 -241.48161)
		(end 166.50462 -241.798856)
		(width 0.14478)
		(layer "In4.Cu")
		(net "M_J_CPU1_SA_CB<4>")
	)
	(segment
		(start 167.056054 -241.798856)
		(end 167.056054 -241.48161)
		(width 0.14478)
		(layer "In4.Cu")
		(net "M_J_CPU1_SA_CB<4>")
	)
	(segment
		(start 136.967722 -248.047002)
		(end 136.976104 -248.051828)
		(width 0.0889)
		(layer "In4.Cu")
		(net "M_J_CPU1_SA_CB<4>")
	)
	(segment
		(start 146.187668 -248.230644)
		(end 146.310858 -248.353834)
		(width 0.0889)
		(layer "In4.Cu")
		(net "M_J_CPU1_SA_CB<4>")
	)
	(segment
		(start 141.093444 -248.051828)
		(end 141.101826 -248.047002)
		(width 0.0889)
		(layer "In4.Cu")
		(net "M_J_CPU1_SA_CB<4>")
	)
	(segment
		(start 145.612104 -248.097802)
		(end 145.744946 -248.230644)
		(width 0.0889)
		(layer "In4.Cu")
		(net "M_J_CPU1_SA_CB<4>")
	)
	(segment
		(start 145.744946 -248.230644)
		(end 146.187668 -248.230644)
		(width 0.0889)
		(layer "In4.Cu")
		(net "M_J_CPU1_SA_CB<4>")
	)
	(segment
		(start 167.607488 -241.48161)
		(end 167.607488 -241.798856)
		(width 0.14478)
		(layer "In4.Cu")
		(net "M_J_CPU1_SA_CB<4>")
	)
	(segment
		(start 164.850318 -241.798856)
		(end 164.850318 -241.48161)
		(width 0.14478)
		(layer "In4.Cu")
		(net "M_J_CPU1_SA_CB<4>")
	)
	(segment
		(start 166.11473 -241.320066)
		(end 166.343076 -241.320066)
		(width 0.14478)
		(layer "In4.Cu")
		(net "M_J_CPU1_SA_CB<4>")
	)
	(segment
		(start 167.217598 -241.320066)
		(end 167.445944 -241.320066)
		(width 0.14478)
		(layer "In4.Cu")
		(net "M_J_CPU1_SA_CB<4>")
	)
	(segment
		(start 145.428208 -248.047002)
		(end 145.427954 -248.047002)
		(width 0.0889)
		(layer "In4.Cu")
		(net "M_J_CPU1_SA_CB<4>")
	)
	(segment
		(start 181.464204 -241.110262)
		(end 190.735204 -241.110262)
		(width 0.14478)
		(layer "In4.Cu")
		(net "M_J_CPU1_SA_CB<4>")
	)
	(segment
		(start 132.45465 -247.724422)
		(end 132.608828 -247.989852)
		(width 0.0889)
		(layer "In4.Cu")
		(net "M_J_CPU1_SA_CB<4>")
	)
	(segment
		(start 146.310858 -248.353834)
		(end 146.966178 -248.353834)
		(width 0.0889)
		(layer "In4.Cu")
		(net "M_J_CPU1_SA_CB<4>")
	)
	(segment
		(start 167.607488 -241.798856)
		(end 167.769032 -241.9604)
		(width 0.14478)
		(layer "In4.Cu")
		(net "M_J_CPU1_SA_CB<4>")
	)
	(segment
		(start 146.966178 -248.353834)
		(end 147.236688 -248.083324)
		(width 0.0889)
		(layer "In4.Cu")
		(net "M_J_CPU1_SA_CB<4>")
	)
	(segment
		(start 164.688774 -241.9604)
		(end 164.850318 -241.798856)
		(width 0.14478)
		(layer "In4.Cu")
		(net "M_J_CPU1_SA_CB<4>")
	)
	(segment
		(start 132.608828 -247.989852)
		(end 132.705094 -248.015252)
		(width 0.0889)
		(layer "In4.Cu")
		(net "M_J_CPU1_SA_CB<4>")
	)
	(segment
		(start 165.953186 -241.48161)
		(end 166.11473 -241.320066)
		(width 0.14478)
		(layer "In4.Cu")
		(net "M_J_CPU1_SA_CB<4>")
	)
	(segment
		(start 141.667738 -248.047002)
		(end 141.67612 -248.051828)
		(width 0.0889)
		(layer "In4.Cu")
		(net "M_J_CPU1_SA_CB<4>")
	)
	(segment
		(start 165.011862 -241.320066)
		(end 165.240208 -241.320066)
		(width 0.14478)
		(layer "In4.Cu")
		(net "M_J_CPU1_SA_CB<4>")
	)
	(segment
		(start 143.547592 -248.047002)
		(end 143.555974 -248.051828)
		(width 0.0889)
		(layer "In4.Cu")
		(net "M_J_CPU1_SA_CB<4>")
	)
	(segment
		(start 166.666164 -241.9604)
		(end 166.89451 -241.9604)
		(width 0.14478)
		(layer "In4.Cu")
		(net "M_J_CPU1_SA_CB<4>")
	)
	(segment
		(start 133.20776 -248.047002)
		(end 133.216142 -248.051828)
		(width 0.0889)
		(layer "In4.Cu")
		(net "M_J_CPU1_SA_CB<4>")
	)
	(arc
		(start 133.581902 -248.047002)
		(mid 133.864858 -247.970825)
		(end 134.147814 -248.047002)
		(width 0.0889)
		(layer "In4.Cu")
		(net "M_J_CPU1_SA_CB<4>")
	)
	(arc
		(start 142.607792 -248.047002)
		(mid 142.794736 -248.097257)
		(end 142.98168 -248.047002)
		(width 0.0889)
		(layer "In4.Cu")
		(net "M_J_CPU1_SA_CB<4>")
	)
	(arc
		(start 136.40181 -248.047002)
		(mid 136.684766 -247.970825)
		(end 136.967722 -248.047002)
		(width 0.0889)
		(layer "In4.Cu")
		(net "M_J_CPU1_SA_CB<4>")
	)
	(arc
		(start 141.67612 -248.051828)
		(mid 141.859628 -248.097322)
		(end 142.04188 -248.047002)
		(width 0.0889)
		(layer "In4.Cu")
		(net "M_J_CPU1_SA_CB<4>")
	)
	(arc
		(start 144.488408 -248.047002)
		(mid 144.666058 -248.097262)
		(end 144.84604 -248.056146)
		(width 0.0889)
		(layer "In4.Cu")
		(net "M_J_CPU1_SA_CB<4>")
	)
	(arc
		(start 142.04188 -248.047002)
		(mid 142.324836 -247.970825)
		(end 142.607792 -248.047002)
		(width 0.0889)
		(layer "In4.Cu")
		(net "M_J_CPU1_SA_CB<4>")
	)
	(arc
		(start 134.521702 -248.047002)
		(mid 134.804658 -247.970825)
		(end 135.087614 -248.047002)
		(width 0.0889)
		(layer "In4.Cu")
		(net "M_J_CPU1_SA_CB<4>")
	)
	(arc
		(start 143.922242 -248.047002)
		(mid 144.199309 -247.970731)
		(end 144.477994 -248.040906)
		(width 0.0889)
		(layer "In4.Cu")
		(net "M_J_CPU1_SA_CB<4>")
	)
	(arc
		(start 132.705094 -248.015252)
		(mid 132.960159 -247.971901)
		(end 133.20776 -248.047002)
		(width 0.0889)
		(layer "In4.Cu")
		(net "M_J_CPU1_SA_CB<4>")
	)
	(arc
		(start 137.916158 -248.051828)
		(mid 138.099666 -248.097322)
		(end 138.281918 -248.047002)
		(width 0.0889)
		(layer "In4.Cu")
		(net "M_J_CPU1_SA_CB<4>")
	)
	(arc
		(start 139.221718 -248.047002)
		(mid 139.504674 -247.970825)
		(end 139.78763 -248.047002)
		(width 0.0889)
		(layer "In4.Cu")
		(net "M_J_CPU1_SA_CB<4>")
	)
	(arc
		(start 144.878044 -248.037604)
		(mid 145.154353 -247.970628)
		(end 145.428208 -248.047002)
		(width 0.0889)
		(layer "In4.Cu")
		(net "M_J_CPU1_SA_CB<4>")
	)
	(arc
		(start 135.087614 -248.047002)
		(mid 135.269865 -248.097352)
		(end 135.453374 -248.051828)
		(width 0.0889)
		(layer "In4.Cu")
		(net "M_J_CPU1_SA_CB<4>")
	)
	(arc
		(start 134.147814 -248.047002)
		(mid 134.334758 -248.097257)
		(end 134.521702 -248.047002)
		(width 0.0889)
		(layer "In4.Cu")
		(net "M_J_CPU1_SA_CB<4>")
	)
	(arc
		(start 140.727684 -248.047002)
		(mid 140.909935 -248.097352)
		(end 141.093444 -248.051828)
		(width 0.0889)
		(layer "In4.Cu")
		(net "M_J_CPU1_SA_CB<4>")
	)
	(arc
		(start 135.461756 -248.047002)
		(mid 135.744712 -247.970825)
		(end 136.027668 -248.047002)
		(width 0.0889)
		(layer "In4.Cu")
		(net "M_J_CPU1_SA_CB<4>")
	)
	(arc
		(start 139.78763 -248.047002)
		(mid 139.969881 -248.097352)
		(end 140.15339 -248.051828)
		(width 0.0889)
		(layer "In4.Cu")
		(net "M_J_CPU1_SA_CB<4>")
	)
	(arc
		(start 138.84783 -248.047002)
		(mid 139.034774 -248.097257)
		(end 139.221718 -248.047002)
		(width 0.0889)
		(layer "In4.Cu")
		(net "M_J_CPU1_SA_CB<4>")
	)
	(arc
		(start 140.161772 -248.047002)
		(mid 140.444728 -247.970825)
		(end 140.727684 -248.047002)
		(width 0.0889)
		(layer "In4.Cu")
		(net "M_J_CPU1_SA_CB<4>")
	)
	(arc
		(start 136.027668 -248.047002)
		(mid 136.209919 -248.097352)
		(end 136.393428 -248.051828)
		(width 0.0889)
		(layer "In4.Cu")
		(net "M_J_CPU1_SA_CB<4>")
	)
	(arc
		(start 136.976104 -248.051828)
		(mid 137.159612 -248.097322)
		(end 137.341864 -248.047002)
		(width 0.0889)
		(layer "In4.Cu")
		(net "M_J_CPU1_SA_CB<4>")
	)
	(arc
		(start 141.101826 -248.047002)
		(mid 141.384782 -247.970825)
		(end 141.667738 -248.047002)
		(width 0.0889)
		(layer "In4.Cu")
		(net "M_J_CPU1_SA_CB<4>")
	)
	(arc
		(start 142.98168 -248.047002)
		(mid 143.264636 -247.970825)
		(end 143.547592 -248.047002)
		(width 0.0889)
		(layer "In4.Cu")
		(net "M_J_CPU1_SA_CB<4>")
	)
	(arc
		(start 145.427954 -248.047002)
		(mid 145.516729 -248.084351)
		(end 145.612104 -248.097802)
		(width 0.0889)
		(layer "In4.Cu")
		(net "M_J_CPU1_SA_CB<4>")
	)
	(arc
		(start 133.216142 -248.051828)
		(mid 133.39965 -248.097322)
		(end 133.581902 -248.047002)
		(width 0.0889)
		(layer "In4.Cu")
		(net "M_J_CPU1_SA_CB<4>")
	)
	(arc
		(start 137.341864 -248.047002)
		(mid 137.62482 -247.970825)
		(end 137.907776 -248.047002)
		(width 0.0889)
		(layer "In4.Cu")
		(net "M_J_CPU1_SA_CB<4>")
	)
	(arc
		(start 143.555974 -248.051828)
		(mid 143.739736 -248.097444)
		(end 143.922242 -248.047002)
		(width 0.0889)
		(layer "In4.Cu")
		(net "M_J_CPU1_SA_CB<4>")
	)
	(arc
		(start 138.281918 -248.047002)
		(mid 138.564874 -247.970825)
		(end 138.84783 -248.047002)
		(width 0.0889)
		(layer "In4.Cu")
		(net "M_J_CPU1_SA_CB<4>")
	)
	(segment
		(start 131.047998 -246.370348)
		(end 131.51485 -246.10441)
		(width 0.10668)
		(layer "F.Cu")
		(net "M_J_CPU1_SA_CB<3>")
	)
	(segment
		(start 163.084764 -237.710472)
		(end 166.065708 -237.710472)
		(width 0.14478)
		(layer "In4.Cu")
		(net "M_J_CPU1_SA_CB<3>")
	)
	(segment
		(start 161.480246 -240.14811)
		(end 161.708846 -240.14811)
		(width 0.14478)
		(layer "In4.Cu")
		(net "M_J_CPU1_SA_CB<3>")
	)
	(segment
		(start 144.47393 -245.790466)
		(end 144.488662 -245.78183)
		(width 0.0889)
		(layer "In4.Cu")
		(net "M_J_CPU1_SA_CB<3>")
	)
	(segment
		(start 160.169098 -240.626138)
		(end 160.397698 -240.626138)
		(width 0.14478)
		(layer "In4.Cu")
		(net "M_J_CPU1_SA_CB<3>")
	)
	(segment
		(start 160.949386 -239.84585)
		(end 161.177986 -239.84585)
		(width 0.14478)
		(layer "In4.Cu")
		(net "M_J_CPU1_SA_CB<3>")
	)
	(segment
		(start 155.423616 -245.37162)
		(end 160.169098 -240.626138)
		(width 0.14478)
		(layer "In4.Cu")
		(net "M_J_CPU1_SA_CB<3>")
	)
	(segment
		(start 161.090102 -240.766854)
		(end 161.090102 -240.538254)
		(width 0.14478)
		(layer "In4.Cu")
		(net "M_J_CPU1_SA_CB<3>")
	)
	(segment
		(start 161.56813 -239.455706)
		(end 161.56813 -239.227106)
		(width 0.14478)
		(layer "In4.Cu")
		(net "M_J_CPU1_SA_CB<3>")
	)
	(segment
		(start 161.87039 -239.757966)
		(end 161.56813 -239.455706)
		(width 0.14478)
		(layer "In4.Cu")
		(net "M_J_CPU1_SA_CB<3>")
	)
	(segment
		(start 131.693412 -245.777004)
		(end 131.701794 -245.78183)
		(width 0.0889)
		(layer "In4.Cu")
		(net "M_J_CPU1_SA_CB<3>")
	)
	(segment
		(start 145.794476 -245.777004)
		(end 146.005296 -245.987824)
		(width 0.0889)
		(layer "In4.Cu")
		(net "M_J_CPU1_SA_CB<3>")
	)
	(segment
		(start 160.928558 -240.928398)
		(end 161.090102 -240.766854)
		(width 0.14478)
		(layer "In4.Cu")
		(net "M_J_CPU1_SA_CB<3>")
	)
	(segment
		(start 161.177986 -239.84585)
		(end 161.480246 -240.14811)
		(width 0.14478)
		(layer "In4.Cu")
		(net "M_J_CPU1_SA_CB<3>")
	)
	(segment
		(start 131.51485 -246.10441)
		(end 131.360672 -245.83898)
		(width 0.0889)
		(layer "In4.Cu")
		(net "M_J_CPU1_SA_CB<3>")
	)
	(segment
		(start 162.489134 -239.367822)
		(end 162.650678 -239.206278)
		(width 0.14478)
		(layer "In4.Cu")
		(net "M_J_CPU1_SA_CB<3>")
	)
	(segment
		(start 161.958274 -239.065562)
		(end 162.260534 -239.367822)
		(width 0.14478)
		(layer "In4.Cu")
		(net "M_J_CPU1_SA_CB<3>")
	)
	(segment
		(start 162.260534 -239.367822)
		(end 162.489134 -239.367822)
		(width 0.14478)
		(layer "In4.Cu")
		(net "M_J_CPU1_SA_CB<3>")
	)
	(segment
		(start 166.065708 -237.710472)
		(end 166.915846 -236.860334)
		(width 0.14478)
		(layer "In4.Cu")
		(net "M_J_CPU1_SA_CB<3>")
	)
	(segment
		(start 132.267706 -245.78183)
		(end 132.276088 -245.777004)
		(width 0.0889)
		(layer "In4.Cu")
		(net "M_J_CPU1_SA_CB<3>")
	)
	(segment
		(start 171.040044 -237.700566)
		(end 173.406308 -237.700566)
		(width 0.14478)
		(layer "In4.Cu")
		(net "M_J_CPU1_SA_CB<3>")
	)
	(segment
		(start 181.97576 -236.850682)
		(end 186.625484 -236.850682)
		(width 0.14478)
		(layer "In4.Cu")
		(net "M_J_CPU1_SA_CB<3>")
	)
	(segment
		(start 161.56813 -239.227106)
		(end 161.729674 -239.065562)
		(width 0.14478)
		(layer "In4.Cu")
		(net "M_J_CPU1_SA_CB<3>")
	)
	(segment
		(start 161.729674 -239.065562)
		(end 161.958274 -239.065562)
		(width 0.14478)
		(layer "In4.Cu")
		(net "M_J_CPU1_SA_CB<3>")
	)
	(segment
		(start 162.348418 -238.446818)
		(end 163.084764 -237.710472)
		(width 0.14478)
		(layer "In4.Cu")
		(net "M_J_CPU1_SA_CB<3>")
	)
	(segment
		(start 160.787842 -240.007394)
		(end 160.949386 -239.84585)
		(width 0.14478)
		(layer "In4.Cu")
		(net "M_J_CPU1_SA_CB<3>")
	)
	(segment
		(start 146.005296 -245.987824)
		(end 146.943572 -245.987824)
		(width 0.0889)
		(layer "In4.Cu")
		(net "M_J_CPU1_SA_CB<3>")
	)
	(segment
		(start 162.348418 -238.675418)
		(end 162.348418 -238.446818)
		(width 0.14478)
		(layer "In4.Cu")
		(net "M_J_CPU1_SA_CB<3>")
	)
	(segment
		(start 170.199812 -236.860334)
		(end 171.040044 -237.700566)
		(width 0.14478)
		(layer "In4.Cu")
		(net "M_J_CPU1_SA_CB<3>")
	)
	(segment
		(start 136.393428 -245.777004)
		(end 136.40181 -245.78183)
		(width 0.0889)
		(layer "In4.Cu")
		(net "M_J_CPU1_SA_CB<3>")
	)
	(segment
		(start 144.862296 -245.782084)
		(end 144.878044 -245.791228)
		(width 0.0889)
		(layer "In4.Cu")
		(net "M_J_CPU1_SA_CB<3>")
	)
	(segment
		(start 135.453374 -245.777004)
		(end 135.461756 -245.78183)
		(width 0.0889)
		(layer "In4.Cu")
		(net "M_J_CPU1_SA_CB<3>")
	)
	(segment
		(start 162.650678 -239.206278)
		(end 162.650678 -238.977678)
		(width 0.14478)
		(layer "In4.Cu")
		(net "M_J_CPU1_SA_CB<3>")
	)
	(segment
		(start 161.090102 -240.538254)
		(end 160.787842 -240.235994)
		(width 0.14478)
		(layer "In4.Cu")
		(net "M_J_CPU1_SA_CB<3>")
	)
	(segment
		(start 141.667738 -245.78183)
		(end 141.67612 -245.777004)
		(width 0.0889)
		(layer "In4.Cu")
		(net "M_J_CPU1_SA_CB<3>")
	)
	(segment
		(start 140.15339 -245.777004)
		(end 140.161772 -245.78183)
		(width 0.0889)
		(layer "In4.Cu")
		(net "M_J_CPU1_SA_CB<3>")
	)
	(segment
		(start 131.360672 -245.83898)
		(end 131.383024 -245.755668)
		(width 0.0889)
		(layer "In4.Cu")
		(net "M_J_CPU1_SA_CB<3>")
	)
	(segment
		(start 146.943572 -245.987824)
		(end 147.559776 -245.37162)
		(width 0.0889)
		(layer "In4.Cu")
		(net "M_J_CPU1_SA_CB<3>")
	)
	(segment
		(start 143.547592 -245.78183)
		(end 143.555974 -245.777004)
		(width 0.0889)
		(layer "In4.Cu")
		(net "M_J_CPU1_SA_CB<3>")
	)
	(segment
		(start 137.907776 -245.78183)
		(end 137.916158 -245.777004)
		(width 0.0889)
		(layer "In4.Cu")
		(net "M_J_CPU1_SA_CB<3>")
	)
	(segment
		(start 160.787842 -240.235994)
		(end 160.787842 -240.007394)
		(width 0.14478)
		(layer "In4.Cu")
		(net "M_J_CPU1_SA_CB<3>")
	)
	(segment
		(start 178.124358 -236.850682)
		(end 178.974496 -237.70082)
		(width 0.14478)
		(layer "In4.Cu")
		(net "M_J_CPU1_SA_CB<3>")
	)
	(segment
		(start 133.20776 -245.78183)
		(end 133.216142 -245.777004)
		(width 0.0889)
		(layer "In4.Cu")
		(net "M_J_CPU1_SA_CB<3>")
	)
	(segment
		(start 174.256192 -236.850682)
		(end 178.124358 -236.850682)
		(width 0.14478)
		(layer "In4.Cu")
		(net "M_J_CPU1_SA_CB<3>")
	)
	(segment
		(start 161.708846 -240.14811)
		(end 161.87039 -239.986566)
		(width 0.14478)
		(layer "In4.Cu")
		(net "M_J_CPU1_SA_CB<3>")
	)
	(segment
		(start 144.84858 -245.77421)
		(end 144.862296 -245.782084)
		(width 0.0889)
		(layer "In4.Cu")
		(net "M_J_CPU1_SA_CB<3>")
	)
	(segment
		(start 160.699958 -240.928398)
		(end 160.928558 -240.928398)
		(width 0.14478)
		(layer "In4.Cu")
		(net "M_J_CPU1_SA_CB<3>")
	)
	(segment
		(start 161.87039 -239.986566)
		(end 161.87039 -239.757966)
		(width 0.14478)
		(layer "In4.Cu")
		(net "M_J_CPU1_SA_CB<3>")
	)
	(segment
		(start 173.406308 -237.700566)
		(end 174.256192 -236.850682)
		(width 0.14478)
		(layer "In4.Cu")
		(net "M_J_CPU1_SA_CB<3>")
	)
	(segment
		(start 181.125622 -237.70082)
		(end 181.97576 -236.850682)
		(width 0.14478)
		(layer "In4.Cu")
		(net "M_J_CPU1_SA_CB<3>")
	)
	(segment
		(start 136.967722 -245.78183)
		(end 136.976104 -245.777004)
		(width 0.0889)
		(layer "In4.Cu")
		(net "M_J_CPU1_SA_CB<3>")
	)
	(segment
		(start 186.625484 -236.850682)
		(end 187.060078 -237.285276)
		(width 0.14478)
		(layer "In4.Cu")
		(net "M_J_CPU1_SA_CB<3>")
	)
	(segment
		(start 166.915846 -236.860334)
		(end 170.199812 -236.860334)
		(width 0.14478)
		(layer "In4.Cu")
		(net "M_J_CPU1_SA_CB<3>")
	)
	(segment
		(start 141.093444 -245.777004)
		(end 141.101826 -245.78183)
		(width 0.0889)
		(layer "In4.Cu")
		(net "M_J_CPU1_SA_CB<3>")
	)
	(segment
		(start 162.650678 -238.977678)
		(end 162.348418 -238.675418)
		(width 0.14478)
		(layer "In4.Cu")
		(net "M_J_CPU1_SA_CB<3>")
	)
	(segment
		(start 147.559776 -245.37162)
		(end 147.937982 -245.37162)
		(width 0.0889)
		(layer "In4.Cu")
		(net "M_J_CPU1_SA_CB<3>")
	)
	(segment
		(start 147.937982 -245.37162)
		(end 155.423616 -245.37162)
		(width 0.14478)
		(layer "In4.Cu")
		(net "M_J_CPU1_SA_CB<3>")
	)
	(segment
		(start 160.397698 -240.626138)
		(end 160.699958 -240.928398)
		(width 0.14478)
		(layer "In4.Cu")
		(net "M_J_CPU1_SA_CB<3>")
	)
	(segment
		(start 178.974496 -237.70082)
		(end 181.125622 -237.70082)
		(width 0.14478)
		(layer "In4.Cu")
		(net "M_J_CPU1_SA_CB<3>")
	)
	(arc
		(start 131.383024 -245.755668)
		(mid 131.540534 -245.73247)
		(end 131.693412 -245.777004)
		(width 0.0889)
		(layer "In4.Cu")
		(net "M_J_CPU1_SA_CB<3>")
	)
	(arc
		(start 141.101826 -245.78183)
		(mid 141.384782 -245.858007)
		(end 141.667738 -245.78183)
		(width 0.0889)
		(layer "In4.Cu")
		(net "M_J_CPU1_SA_CB<3>")
	)
	(arc
		(start 145.428208 -245.78183)
		(mid 145.610713 -245.731353)
		(end 145.794476 -245.777004)
		(width 0.0889)
		(layer "In4.Cu")
		(net "M_J_CPU1_SA_CB<3>")
	)
	(arc
		(start 134.521702 -245.78183)
		(mid 134.804658 -245.858007)
		(end 135.087614 -245.78183)
		(width 0.0889)
		(layer "In4.Cu")
		(net "M_J_CPU1_SA_CB<3>")
	)
	(arc
		(start 138.281918 -245.78183)
		(mid 138.564874 -245.858007)
		(end 138.84783 -245.78183)
		(width 0.0889)
		(layer "In4.Cu")
		(net "M_J_CPU1_SA_CB<3>")
	)
	(arc
		(start 132.641848 -245.78183)
		(mid 132.924804 -245.858007)
		(end 133.20776 -245.78183)
		(width 0.0889)
		(layer "In4.Cu")
		(net "M_J_CPU1_SA_CB<3>")
	)
	(arc
		(start 142.98168 -245.78183)
		(mid 143.264636 -245.858007)
		(end 143.547592 -245.78183)
		(width 0.0889)
		(layer "In4.Cu")
		(net "M_J_CPU1_SA_CB<3>")
	)
	(arc
		(start 143.922242 -245.78183)
		(mid 144.196948 -245.858194)
		(end 144.47393 -245.790466)
		(width 0.0889)
		(layer "In4.Cu")
		(net "M_J_CPU1_SA_CB<3>")
	)
	(arc
		(start 133.216142 -245.777004)
		(mid 133.39965 -245.73151)
		(end 133.581902 -245.78183)
		(width 0.0889)
		(layer "In4.Cu")
		(net "M_J_CPU1_SA_CB<3>")
	)
	(arc
		(start 131.701794 -245.78183)
		(mid 131.98475 -245.858007)
		(end 132.267706 -245.78183)
		(width 0.0889)
		(layer "In4.Cu")
		(net "M_J_CPU1_SA_CB<3>")
	)
	(arc
		(start 142.607792 -245.78183)
		(mid 142.794736 -245.731575)
		(end 142.98168 -245.78183)
		(width 0.0889)
		(layer "In4.Cu")
		(net "M_J_CPU1_SA_CB<3>")
	)
	(arc
		(start 134.147814 -245.78183)
		(mid 134.334758 -245.731575)
		(end 134.521702 -245.78183)
		(width 0.0889)
		(layer "In4.Cu")
		(net "M_J_CPU1_SA_CB<3>")
	)
	(arc
		(start 140.727684 -245.78183)
		(mid 140.909935 -245.73148)
		(end 141.093444 -245.777004)
		(width 0.0889)
		(layer "In4.Cu")
		(net "M_J_CPU1_SA_CB<3>")
	)
	(arc
		(start 136.40181 -245.78183)
		(mid 136.684766 -245.858007)
		(end 136.967722 -245.78183)
		(width 0.0889)
		(layer "In4.Cu")
		(net "M_J_CPU1_SA_CB<3>")
	)
	(arc
		(start 143.555974 -245.777004)
		(mid 143.739736 -245.731388)
		(end 143.922242 -245.78183)
		(width 0.0889)
		(layer "In4.Cu")
		(net "M_J_CPU1_SA_CB<3>")
	)
	(arc
		(start 133.581902 -245.78183)
		(mid 133.864858 -245.858007)
		(end 134.147814 -245.78183)
		(width 0.0889)
		(layer "In4.Cu")
		(net "M_J_CPU1_SA_CB<3>")
	)
	(arc
		(start 140.161772 -245.78183)
		(mid 140.444728 -245.858007)
		(end 140.727684 -245.78183)
		(width 0.0889)
		(layer "In4.Cu")
		(net "M_J_CPU1_SA_CB<3>")
	)
	(arc
		(start 142.04188 -245.78183)
		(mid 142.324836 -245.858007)
		(end 142.607792 -245.78183)
		(width 0.0889)
		(layer "In4.Cu")
		(net "M_J_CPU1_SA_CB<3>")
	)
	(arc
		(start 136.027668 -245.78183)
		(mid 136.209919 -245.73148)
		(end 136.393428 -245.777004)
		(width 0.0889)
		(layer "In4.Cu")
		(net "M_J_CPU1_SA_CB<3>")
	)
	(arc
		(start 141.67612 -245.777004)
		(mid 141.859628 -245.73151)
		(end 142.04188 -245.78183)
		(width 0.0889)
		(layer "In4.Cu")
		(net "M_J_CPU1_SA_CB<3>")
	)
	(arc
		(start 132.276088 -245.777004)
		(mid 132.459596 -245.73151)
		(end 132.641848 -245.78183)
		(width 0.0889)
		(layer "In4.Cu")
		(net "M_J_CPU1_SA_CB<3>")
	)
	(arc
		(start 136.976104 -245.777004)
		(mid 137.159612 -245.73151)
		(end 137.341864 -245.78183)
		(width 0.0889)
		(layer "In4.Cu")
		(net "M_J_CPU1_SA_CB<3>")
	)
	(arc
		(start 135.461756 -245.78183)
		(mid 135.744712 -245.858007)
		(end 136.027668 -245.78183)
		(width 0.0889)
		(layer "In4.Cu")
		(net "M_J_CPU1_SA_CB<3>")
	)
	(arc
		(start 137.341864 -245.78183)
		(mid 137.62482 -245.858007)
		(end 137.907776 -245.78183)
		(width 0.0889)
		(layer "In4.Cu")
		(net "M_J_CPU1_SA_CB<3>")
	)
	(arc
		(start 144.878044 -245.791228)
		(mid 145.154353 -245.858204)
		(end 145.428208 -245.78183)
		(width 0.0889)
		(layer "In4.Cu")
		(net "M_J_CPU1_SA_CB<3>")
	)
	(arc
		(start 135.087614 -245.78183)
		(mid 135.269865 -245.73148)
		(end 135.453374 -245.777004)
		(width 0.0889)
		(layer "In4.Cu")
		(net "M_J_CPU1_SA_CB<3>")
	)
	(arc
		(start 139.78763 -245.78183)
		(mid 139.969881 -245.73148)
		(end 140.15339 -245.777004)
		(width 0.0889)
		(layer "In4.Cu")
		(net "M_J_CPU1_SA_CB<3>")
	)
	(arc
		(start 139.221718 -245.78183)
		(mid 139.504674 -245.858007)
		(end 139.78763 -245.78183)
		(width 0.0889)
		(layer "In4.Cu")
		(net "M_J_CPU1_SA_CB<3>")
	)
	(arc
		(start 137.916158 -245.777004)
		(mid 138.099666 -245.73151)
		(end 138.281918 -245.78183)
		(width 0.0889)
		(layer "In4.Cu")
		(net "M_J_CPU1_SA_CB<3>")
	)
	(arc
		(start 144.488662 -245.78183)
		(mid 144.667649 -245.73166)
		(end 144.84858 -245.77421)
		(width 0.0889)
		(layer "In4.Cu")
		(net "M_J_CPU1_SA_CB<3>")
	)
	(arc
		(start 138.84783 -245.78183)
		(mid 139.034774 -245.731575)
		(end 139.221718 -245.78183)
		(width 0.0889)
		(layer "In4.Cu")
		(net "M_J_CPU1_SA_CB<3>")
	)
	(segment
		(start 132.457952 -245.560342)
		(end 132.924804 -245.294404)
		(width 0.10668)
		(layer "F.Cu")
		(net "M_J_CPU1_SA_CB<2>")
	)
	(segment
		(start 134.04342 -244.966998)
		(end 134.051802 -244.971824)
		(width 0.0889)
		(layer "In4.Cu")
		(net "M_J_CPU1_SA_CB<2>")
	)
	(segment
		(start 156.092398 -242.557046)
		(end 156.32049 -242.557046)
		(width 0.14478)
		(layer "In4.Cu")
		(net "M_J_CPU1_SA_CB<2>")
	)
	(segment
		(start 156.32049 -242.557046)
		(end 156.529024 -242.765834)
		(width 0.14478)
		(layer "In4.Cu")
		(net "M_J_CPU1_SA_CB<2>")
	)
	(segment
		(start 155.358592 -243.936266)
		(end 155.150058 -243.727478)
		(width 0.14478)
		(layer "In4.Cu")
		(net "M_J_CPU1_SA_CB<2>")
	)
	(segment
		(start 155.540202 -243.337334)
		(end 155.748736 -243.546122)
		(width 0.14478)
		(layer "In4.Cu")
		(net "M_J_CPU1_SA_CB<2>")
	)
	(segment
		(start 186.63539 -235.160566)
		(end 187.060078 -235.585254)
		(width 0.14478)
		(layer "In4.Cu")
		(net "M_J_CPU1_SA_CB<2>")
	)
	(segment
		(start 157.537404 -241.985546)
		(end 157.699456 -241.823494)
		(width 0.14478)
		(layer "In4.Cu")
		(net "M_J_CPU1_SA_CB<2>")
	)
	(segment
		(start 158.27121 -240.378234)
		(end 158.433262 -240.216182)
		(width 0.14478)
		(layer "In4.Cu")
		(net "M_J_CPU1_SA_CB<2>")
	)
	(segment
		(start 181.914038 -235.160566)
		(end 186.63539 -235.160566)
		(width 0.14478)
		(layer "In4.Cu")
		(net "M_J_CPU1_SA_CB<2>")
	)
	(segment
		(start 174.490888 -235.160566)
		(end 177.92192 -235.160566)
		(width 0.14478)
		(layer "In4.Cu")
		(net "M_J_CPU1_SA_CB<2>")
	)
	(segment
		(start 139.31773 -244.971824)
		(end 139.326112 -244.966998)
		(width 0.0889)
		(layer "In4.Cu")
		(net "M_J_CPU1_SA_CB<2>")
	)
	(segment
		(start 145.144744 -244.921024)
		(end 146.013932 -244.921024)
		(width 0.0889)
		(layer "In4.Cu")
		(net "M_J_CPU1_SA_CB<2>")
	)
	(segment
		(start 158.317692 -241.205258)
		(end 158.479744 -241.043206)
		(width 0.14478)
		(layer "In4.Cu")
		(net "M_J_CPU1_SA_CB<2>")
	)
	(segment
		(start 146.303492 -245.210584)
		(end 146.94408 -245.210584)
		(width 0.0889)
		(layer "In4.Cu")
		(net "M_J_CPU1_SA_CB<2>")
	)
	(segment
		(start 146.94408 -245.210584)
		(end 147.692364 -244.4623)
		(width 0.0889)
		(layer "In4.Cu")
		(net "M_J_CPU1_SA_CB<2>")
	)
	(segment
		(start 155.748736 -243.546122)
		(end 155.976828 -243.546122)
		(width 0.14478)
		(layer "In4.Cu")
		(net "M_J_CPU1_SA_CB<2>")
	)
	(segment
		(start 163.512246 -236.010704)
		(end 166.299388 -236.010704)
		(width 0.14478)
		(layer "In4.Cu")
		(net "M_J_CPU1_SA_CB<2>")
	)
	(segment
		(start 173.64075 -236.010704)
		(end 174.490888 -235.160566)
		(width 0.14478)
		(layer "In4.Cu")
		(net "M_J_CPU1_SA_CB<2>")
	)
	(segment
		(start 157.881066 -240.99647)
		(end 158.0896 -241.205258)
		(width 0.14478)
		(layer "In4.Cu")
		(net "M_J_CPU1_SA_CB<2>")
	)
	(segment
		(start 170.792394 -236.010704)
		(end 173.64075 -236.010704)
		(width 0.14478)
		(layer "In4.Cu")
		(net "M_J_CPU1_SA_CB<2>")
	)
	(segment
		(start 158.479744 -240.815114)
		(end 158.27121 -240.606326)
		(width 0.14478)
		(layer "In4.Cu")
		(net "M_J_CPU1_SA_CB<2>")
	)
	(segment
		(start 147.692364 -244.4623)
		(end 147.913852 -244.4623)
		(width 0.0889)
		(layer "In4.Cu")
		(net "M_J_CPU1_SA_CB<2>")
	)
	(segment
		(start 177.92192 -235.160566)
		(end 178.772058 -236.010704)
		(width 0.14478)
		(layer "In4.Cu")
		(net "M_J_CPU1_SA_CB<2>")
	)
	(segment
		(start 138.743436 -244.966998)
		(end 138.751818 -244.971824)
		(width 0.0889)
		(layer "In4.Cu")
		(net "M_J_CPU1_SA_CB<2>")
	)
	(segment
		(start 155.358592 -244.164358)
		(end 155.358592 -243.936266)
		(width 0.14478)
		(layer "In4.Cu")
		(net "M_J_CPU1_SA_CB<2>")
	)
	(segment
		(start 157.699456 -241.823494)
		(end 157.699456 -241.595402)
		(width 0.14478)
		(layer "In4.Cu")
		(net "M_J_CPU1_SA_CB<2>")
	)
	(segment
		(start 143.451834 -244.971824)
		(end 143.462248 -244.97792)
		(width 0.0889)
		(layer "In4.Cu")
		(net "M_J_CPU1_SA_CB<2>")
	)
	(segment
		(start 143.077692 -244.971824)
		(end 143.086074 -244.966998)
		(width 0.0889)
		(layer "In4.Cu")
		(net "M_J_CPU1_SA_CB<2>")
	)
	(segment
		(start 137.803382 -244.966998)
		(end 137.811764 -244.971824)
		(width 0.0889)
		(layer "In4.Cu")
		(net "M_J_CPU1_SA_CB<2>")
	)
	(segment
		(start 135.557768 -244.971824)
		(end 135.56615 -244.966998)
		(width 0.0889)
		(layer "In4.Cu")
		(net "M_J_CPU1_SA_CB<2>")
	)
	(segment
		(start 158.661354 -240.216182)
		(end 158.869888 -240.42497)
		(width 0.14478)
		(layer "In4.Cu")
		(net "M_J_CPU1_SA_CB<2>")
	)
	(segment
		(start 142.503398 -244.966998)
		(end 142.51178 -244.971824)
		(width 0.0889)
		(layer "In4.Cu")
		(net "M_J_CPU1_SA_CB<2>")
	)
	(segment
		(start 147.913852 -244.4623)
		(end 155.06065 -244.4623)
		(width 0.14478)
		(layer "In4.Cu")
		(net "M_J_CPU1_SA_CB<2>")
	)
	(segment
		(start 156.757116 -242.765834)
		(end 156.919168 -242.603782)
		(width 0.14478)
		(layer "In4.Cu")
		(net "M_J_CPU1_SA_CB<2>")
	)
	(segment
		(start 132.924804 -245.294404)
		(end 132.770626 -245.028974)
		(width 0.0889)
		(layer "In4.Cu")
		(net "M_J_CPU1_SA_CB<2>")
	)
	(segment
		(start 169.942256 -235.160566)
		(end 170.792394 -236.010704)
		(width 0.14478)
		(layer "In4.Cu")
		(net "M_J_CPU1_SA_CB<2>")
	)
	(segment
		(start 156.529024 -242.765834)
		(end 156.757116 -242.765834)
		(width 0.14478)
		(layer "In4.Cu")
		(net "M_J_CPU1_SA_CB<2>")
	)
	(segment
		(start 156.13888 -243.155978)
		(end 155.930346 -242.94719)
		(width 0.14478)
		(layer "In4.Cu")
		(net "M_J_CPU1_SA_CB<2>")
	)
	(segment
		(start 157.699456 -241.595402)
		(end 157.490922 -241.386614)
		(width 0.14478)
		(layer "In4.Cu")
		(net "M_J_CPU1_SA_CB<2>")
	)
	(segment
		(start 157.100778 -241.776758)
		(end 157.309312 -241.985546)
		(width 0.14478)
		(layer "In4.Cu")
		(net "M_J_CPU1_SA_CB<2>")
	)
	(segment
		(start 159.09798 -240.42497)
		(end 163.512246 -236.010704)
		(width 0.14478)
		(layer "In4.Cu")
		(net "M_J_CPU1_SA_CB<2>")
	)
	(segment
		(start 144.384268 -244.966998)
		(end 144.39265 -244.971824)
		(width 0.0889)
		(layer "In4.Cu")
		(net "M_J_CPU1_SA_CB<2>")
	)
	(segment
		(start 167.149526 -235.160566)
		(end 169.942256 -235.160566)
		(width 0.14478)
		(layer "In4.Cu")
		(net "M_J_CPU1_SA_CB<2>")
	)
	(segment
		(start 155.976828 -243.546122)
		(end 156.13888 -243.38407)
		(width 0.14478)
		(layer "In4.Cu")
		(net "M_J_CPU1_SA_CB<2>")
	)
	(segment
		(start 132.770626 -245.028974)
		(end 132.792978 -244.945662)
		(width 0.0889)
		(layer "In4.Cu")
		(net "M_J_CPU1_SA_CB<2>")
	)
	(segment
		(start 155.06065 -244.4623)
		(end 155.358592 -244.164358)
		(width 0.14478)
		(layer "In4.Cu")
		(net "M_J_CPU1_SA_CB<2>")
	)
	(segment
		(start 157.490922 -241.158522)
		(end 157.652974 -240.99647)
		(width 0.14478)
		(layer "In4.Cu")
		(net "M_J_CPU1_SA_CB<2>")
	)
	(segment
		(start 146.013932 -244.921024)
		(end 146.303492 -245.210584)
		(width 0.0889)
		(layer "In4.Cu")
		(net "M_J_CPU1_SA_CB<2>")
	)
	(segment
		(start 156.13888 -243.38407)
		(end 156.13888 -243.155978)
		(width 0.14478)
		(layer "In4.Cu")
		(net "M_J_CPU1_SA_CB<2>")
	)
	(segment
		(start 157.490922 -241.386614)
		(end 157.490922 -241.158522)
		(width 0.14478)
		(layer "In4.Cu")
		(net "M_J_CPU1_SA_CB<2>")
	)
	(segment
		(start 158.0896 -241.205258)
		(end 158.317692 -241.205258)
		(width 0.14478)
		(layer "In4.Cu")
		(net "M_J_CPU1_SA_CB<2>")
	)
	(segment
		(start 178.772058 -236.010704)
		(end 181.0639 -236.010704)
		(width 0.14478)
		(layer "In4.Cu")
		(net "M_J_CPU1_SA_CB<2>")
	)
	(segment
		(start 156.872686 -241.776758)
		(end 157.100778 -241.776758)
		(width 0.14478)
		(layer "In4.Cu")
		(net "M_J_CPU1_SA_CB<2>")
	)
	(segment
		(start 156.710634 -241.93881)
		(end 156.872686 -241.776758)
		(width 0.14478)
		(layer "In4.Cu")
		(net "M_J_CPU1_SA_CB<2>")
	)
	(segment
		(start 157.309312 -241.985546)
		(end 157.537404 -241.985546)
		(width 0.14478)
		(layer "In4.Cu")
		(net "M_J_CPU1_SA_CB<2>")
	)
	(segment
		(start 156.710634 -242.166902)
		(end 156.710634 -241.93881)
		(width 0.14478)
		(layer "In4.Cu")
		(net "M_J_CPU1_SA_CB<2>")
	)
	(segment
		(start 140.257784 -244.971824)
		(end 140.266166 -244.966998)
		(width 0.0889)
		(layer "In4.Cu")
		(net "M_J_CPU1_SA_CB<2>")
	)
	(segment
		(start 158.479744 -241.043206)
		(end 158.479744 -240.815114)
		(width 0.14478)
		(layer "In4.Cu")
		(net "M_J_CPU1_SA_CB<2>")
	)
	(segment
		(start 155.31211 -243.337334)
		(end 155.540202 -243.337334)
		(width 0.14478)
		(layer "In4.Cu")
		(net "M_J_CPU1_SA_CB<2>")
	)
	(segment
		(start 181.0639 -236.010704)
		(end 181.914038 -235.160566)
		(width 0.14478)
		(layer "In4.Cu")
		(net "M_J_CPU1_SA_CB<2>")
	)
	(segment
		(start 155.150058 -243.727478)
		(end 155.150058 -243.499386)
		(width 0.14478)
		(layer "In4.Cu")
		(net "M_J_CPU1_SA_CB<2>")
	)
	(segment
		(start 155.930346 -242.94719)
		(end 155.930346 -242.719098)
		(width 0.14478)
		(layer "In4.Cu")
		(net "M_J_CPU1_SA_CB<2>")
	)
	(segment
		(start 166.299388 -236.010704)
		(end 167.149526 -235.160566)
		(width 0.14478)
		(layer "In4.Cu")
		(net "M_J_CPU1_SA_CB<2>")
	)
	(segment
		(start 158.27121 -240.606326)
		(end 158.27121 -240.378234)
		(width 0.14478)
		(layer "In4.Cu")
		(net "M_J_CPU1_SA_CB<2>")
	)
	(segment
		(start 158.869888 -240.42497)
		(end 159.09798 -240.42497)
		(width 0.14478)
		(layer "In4.Cu")
		(net "M_J_CPU1_SA_CB<2>")
	)
	(segment
		(start 156.919168 -242.603782)
		(end 156.919168 -242.37569)
		(width 0.14478)
		(layer "In4.Cu")
		(net "M_J_CPU1_SA_CB<2>")
	)
	(segment
		(start 157.652974 -240.99647)
		(end 157.881066 -240.99647)
		(width 0.14478)
		(layer "In4.Cu")
		(net "M_J_CPU1_SA_CB<2>")
	)
	(segment
		(start 133.103366 -244.966998)
		(end 133.111748 -244.971824)
		(width 0.0889)
		(layer "In4.Cu")
		(net "M_J_CPU1_SA_CB<2>")
	)
	(segment
		(start 156.919168 -242.37569)
		(end 156.710634 -242.166902)
		(width 0.14478)
		(layer "In4.Cu")
		(net "M_J_CPU1_SA_CB<2>")
	)
	(segment
		(start 158.433262 -240.216182)
		(end 158.661354 -240.216182)
		(width 0.14478)
		(layer "In4.Cu")
		(net "M_J_CPU1_SA_CB<2>")
	)
	(segment
		(start 134.617714 -244.971824)
		(end 134.626096 -244.966998)
		(width 0.0889)
		(layer "In4.Cu")
		(net "M_J_CPU1_SA_CB<2>")
	)
	(segment
		(start 155.150058 -243.499386)
		(end 155.31211 -243.337334)
		(width 0.14478)
		(layer "In4.Cu")
		(net "M_J_CPU1_SA_CB<2>")
	)
	(segment
		(start 155.930346 -242.719098)
		(end 156.092398 -242.557046)
		(width 0.14478)
		(layer "In4.Cu")
		(net "M_J_CPU1_SA_CB<2>")
	)
	(arc
		(start 144.952466 -244.97538)
		(mid 145.044898 -244.935098)
		(end 145.144744 -244.921024)
		(width 0.0889)
		(layer "In4.Cu")
		(net "M_J_CPU1_SA_CB<2>")
	)
	(arc
		(start 137.437622 -244.971824)
		(mid 137.619873 -244.921474)
		(end 137.803382 -244.966998)
		(width 0.0889)
		(layer "In4.Cu")
		(net "M_J_CPU1_SA_CB<2>")
	)
	(arc
		(start 140.266166 -244.966998)
		(mid 140.449674 -244.921504)
		(end 140.631926 -244.971824)
		(width 0.0889)
		(layer "In4.Cu")
		(net "M_J_CPU1_SA_CB<2>")
	)
	(arc
		(start 134.051802 -244.971824)
		(mid 134.334758 -245.048001)
		(end 134.617714 -244.971824)
		(width 0.0889)
		(layer "In4.Cu")
		(net "M_J_CPU1_SA_CB<2>")
	)
	(arc
		(start 139.691872 -244.971824)
		(mid 139.974828 -245.048001)
		(end 140.257784 -244.971824)
		(width 0.0889)
		(layer "In4.Cu")
		(net "M_J_CPU1_SA_CB<2>")
	)
	(arc
		(start 133.67766 -244.971824)
		(mid 133.859911 -244.921474)
		(end 134.04342 -244.966998)
		(width 0.0889)
		(layer "In4.Cu")
		(net "M_J_CPU1_SA_CB<2>")
	)
	(arc
		(start 142.51178 -244.971824)
		(mid 142.794736 -245.048001)
		(end 143.077692 -244.971824)
		(width 0.0889)
		(layer "In4.Cu")
		(net "M_J_CPU1_SA_CB<2>")
	)
	(arc
		(start 144.018 -244.971824)
		(mid 144.200505 -244.921347)
		(end 144.384268 -244.966998)
		(width 0.0889)
		(layer "In4.Cu")
		(net "M_J_CPU1_SA_CB<2>")
	)
	(arc
		(start 143.462248 -244.97792)
		(mid 143.740934 -245.04814)
		(end 144.018 -244.971824)
		(width 0.0889)
		(layer "In4.Cu")
		(net "M_J_CPU1_SA_CB<2>")
	)
	(arc
		(start 137.811764 -244.971824)
		(mid 138.09472 -245.048001)
		(end 138.377676 -244.971824)
		(width 0.0889)
		(layer "In4.Cu")
		(net "M_J_CPU1_SA_CB<2>")
	)
	(arc
		(start 144.39265 -244.971824)
		(mid 144.672078 -245.04799)
		(end 144.952466 -244.97538)
		(width 0.0889)
		(layer "In4.Cu")
		(net "M_J_CPU1_SA_CB<2>")
	)
	(arc
		(start 133.111748 -244.971824)
		(mid 133.394704 -245.048001)
		(end 133.67766 -244.971824)
		(width 0.0889)
		(layer "In4.Cu")
		(net "M_J_CPU1_SA_CB<2>")
	)
	(arc
		(start 143.086074 -244.966998)
		(mid 143.269582 -244.921504)
		(end 143.451834 -244.971824)
		(width 0.0889)
		(layer "In4.Cu")
		(net "M_J_CPU1_SA_CB<2>")
	)
	(arc
		(start 139.326112 -244.966998)
		(mid 139.50962 -244.921504)
		(end 139.691872 -244.971824)
		(width 0.0889)
		(layer "In4.Cu")
		(net "M_J_CPU1_SA_CB<2>")
	)
	(arc
		(start 141.571726 -244.971824)
		(mid 141.854682 -245.048001)
		(end 142.137638 -244.971824)
		(width 0.0889)
		(layer "In4.Cu")
		(net "M_J_CPU1_SA_CB<2>")
	)
	(arc
		(start 135.93191 -244.971824)
		(mid 136.214866 -245.048001)
		(end 136.497822 -244.971824)
		(width 0.0889)
		(layer "In4.Cu")
		(net "M_J_CPU1_SA_CB<2>")
	)
	(arc
		(start 142.137638 -244.971824)
		(mid 142.319889 -244.921474)
		(end 142.503398 -244.966998)
		(width 0.0889)
		(layer "In4.Cu")
		(net "M_J_CPU1_SA_CB<2>")
	)
	(arc
		(start 138.751818 -244.971824)
		(mid 139.034774 -245.048001)
		(end 139.31773 -244.971824)
		(width 0.0889)
		(layer "In4.Cu")
		(net "M_J_CPU1_SA_CB<2>")
	)
	(arc
		(start 138.377676 -244.971824)
		(mid 138.559927 -244.921474)
		(end 138.743436 -244.966998)
		(width 0.0889)
		(layer "In4.Cu")
		(net "M_J_CPU1_SA_CB<2>")
	)
	(arc
		(start 132.792978 -244.945662)
		(mid 132.950488 -244.922464)
		(end 133.103366 -244.966998)
		(width 0.0889)
		(layer "In4.Cu")
		(net "M_J_CPU1_SA_CB<2>")
	)
	(arc
		(start 134.991856 -244.971824)
		(mid 135.274812 -245.048001)
		(end 135.557768 -244.971824)
		(width 0.0889)
		(layer "In4.Cu")
		(net "M_J_CPU1_SA_CB<2>")
	)
	(arc
		(start 134.626096 -244.966998)
		(mid 134.809604 -244.921504)
		(end 134.991856 -244.971824)
		(width 0.0889)
		(layer "In4.Cu")
		(net "M_J_CPU1_SA_CB<2>")
	)
	(arc
		(start 135.56615 -244.966998)
		(mid 135.749658 -244.921504)
		(end 135.93191 -244.971824)
		(width 0.0889)
		(layer "In4.Cu")
		(net "M_J_CPU1_SA_CB<2>")
	)
	(arc
		(start 140.631926 -244.971824)
		(mid 140.914882 -245.048001)
		(end 141.197838 -244.971824)
		(width 0.0889)
		(layer "In4.Cu")
		(net "M_J_CPU1_SA_CB<2>")
	)
	(arc
		(start 136.497822 -244.971824)
		(mid 136.684766 -244.921569)
		(end 136.87171 -244.971824)
		(width 0.0889)
		(layer "In4.Cu")
		(net "M_J_CPU1_SA_CB<2>")
	)
	(arc
		(start 136.87171 -244.971824)
		(mid 137.154666 -245.048001)
		(end 137.437622 -244.971824)
		(width 0.0889)
		(layer "In4.Cu")
		(net "M_J_CPU1_SA_CB<2>")
	)
	(arc
		(start 141.197838 -244.971824)
		(mid 141.384782 -244.921569)
		(end 141.571726 -244.971824)
		(width 0.0889)
		(layer "In4.Cu")
		(net "M_J_CPU1_SA_CB<2>")
	)
	(segment
		(start 130.577844 -245.560342)
		(end 131.044696 -245.294404)
		(width 0.10668)
		(layer "F.Cu")
		(net "M_J_CPU1_SA_CB<1>")
	)
	(segment
		(start 134.617714 -245.616984)
		(end 134.626096 -245.62181)
		(width 0.0889)
		(layer "In4.Cu")
		(net "M_J_CPU1_SA_CB<1>")
	)
	(segment
		(start 182.560214 -236.010704)
		(end 189.024768 -236.010704)
		(width 0.14478)
		(layer "In4.Cu")
		(net "M_J_CPU1_SA_CB<1>")
	)
	(segment
		(start 144.958054 -245.61673)
		(end 144.976342 -245.627144)
		(width 0.0889)
		(layer "In4.Cu")
		(net "M_J_CPU1_SA_CB<1>")
	)
	(segment
		(start 131.044696 -245.294404)
		(end 131.198874 -245.559834)
		(width 0.0889)
		(layer "In4.Cu")
		(net "M_J_CPU1_SA_CB<1>")
	)
	(segment
		(start 146.960844 -245.608348)
		(end 147.652232 -244.91696)
		(width 0.0889)
		(layer "In4.Cu")
		(net "M_J_CPU1_SA_CB<1>")
	)
	(segment
		(start 145.883884 -245.608348)
		(end 146.960844 -245.608348)
		(width 0.0889)
		(layer "In4.Cu")
		(net "M_J_CPU1_SA_CB<1>")
	)
	(segment
		(start 140.257784 -245.616984)
		(end 140.266166 -245.62181)
		(width 0.0889)
		(layer "In4.Cu")
		(net "M_J_CPU1_SA_CB<1>")
	)
	(segment
		(start 163.298632 -236.860588)
		(end 165.47211 -236.860588)
		(width 0.14478)
		(layer "In4.Cu")
		(net "M_J_CPU1_SA_CB<1>")
	)
	(segment
		(start 147.652232 -244.91696)
		(end 147.910296 -244.91696)
		(width 0.0889)
		(layer "In4.Cu")
		(net "M_J_CPU1_SA_CB<1>")
	)
	(segment
		(start 137.803382 -245.62181)
		(end 137.811764 -245.616984)
		(width 0.0889)
		(layer "In4.Cu")
		(net "M_J_CPU1_SA_CB<1>")
	)
	(segment
		(start 172.970952 -236.860588)
		(end 175.022764 -236.010704)
		(width 0.14478)
		(layer "In4.Cu")
		(net "M_J_CPU1_SA_CB<1>")
	)
	(segment
		(start 147.910296 -244.91696)
		(end 155.24226 -244.91696)
		(width 0.14478)
		(layer "In4.Cu")
		(net "M_J_CPU1_SA_CB<1>")
	)
	(segment
		(start 134.04342 -245.62181)
		(end 134.051802 -245.616984)
		(width 0.0889)
		(layer "In4.Cu")
		(net "M_J_CPU1_SA_CB<1>")
	)
	(segment
		(start 138.743436 -245.62181)
		(end 138.751818 -245.616984)
		(width 0.0889)
		(layer "In4.Cu")
		(net "M_J_CPU1_SA_CB<1>")
	)
	(segment
		(start 135.557768 -245.616984)
		(end 135.56615 -245.62181)
		(width 0.0889)
		(layer "In4.Cu")
		(net "M_J_CPU1_SA_CB<1>")
	)
	(segment
		(start 131.198874 -245.559834)
		(end 131.29514 -245.585234)
		(width 0.0889)
		(layer "In4.Cu")
		(net "M_J_CPU1_SA_CB<1>")
	)
	(segment
		(start 177.362612 -236.010704)
		(end 179.414424 -236.860588)
		(width 0.14478)
		(layer "In4.Cu")
		(net "M_J_CPU1_SA_CB<1>")
	)
	(segment
		(start 171.506388 -236.860588)
		(end 172.970952 -236.860588)
		(width 0.14478)
		(layer "In4.Cu")
		(net "M_J_CPU1_SA_CB<1>")
	)
	(segment
		(start 175.022764 -236.010704)
		(end 177.362612 -236.010704)
		(width 0.14478)
		(layer "In4.Cu")
		(net "M_J_CPU1_SA_CB<1>")
	)
	(segment
		(start 143.077692 -245.616984)
		(end 143.086074 -245.62181)
		(width 0.0889)
		(layer "In4.Cu")
		(net "M_J_CPU1_SA_CB<1>")
	)
	(segment
		(start 169.454576 -236.010704)
		(end 171.506388 -236.860588)
		(width 0.14478)
		(layer "In4.Cu")
		(net "M_J_CPU1_SA_CB<1>")
	)
	(segment
		(start 143.451834 -245.616984)
		(end 143.466566 -245.608348)
		(width 0.0889)
		(layer "In4.Cu")
		(net "M_J_CPU1_SA_CB<1>")
	)
	(segment
		(start 165.47211 -236.860588)
		(end 167.523922 -236.010704)
		(width 0.14478)
		(layer "In4.Cu")
		(net "M_J_CPU1_SA_CB<1>")
	)
	(segment
		(start 155.24226 -244.91696)
		(end 163.298632 -236.860588)
		(width 0.14478)
		(layer "In4.Cu")
		(net "M_J_CPU1_SA_CB<1>")
	)
	(segment
		(start 180.508402 -236.860588)
		(end 182.560214 -236.010704)
		(width 0.14478)
		(layer "In4.Cu")
		(net "M_J_CPU1_SA_CB<1>")
	)
	(segment
		(start 144.380966 -245.623842)
		(end 144.39265 -245.616984)
		(width 0.0889)
		(layer "In4.Cu")
		(net "M_J_CPU1_SA_CB<1>")
	)
	(segment
		(start 167.523922 -236.010704)
		(end 169.454576 -236.010704)
		(width 0.14478)
		(layer "In4.Cu")
		(net "M_J_CPU1_SA_CB<1>")
	)
	(segment
		(start 142.503398 -245.62181)
		(end 142.51178 -245.616984)
		(width 0.0889)
		(layer "In4.Cu")
		(net "M_J_CPU1_SA_CB<1>")
	)
	(segment
		(start 144.952466 -245.613428)
		(end 144.958054 -245.61673)
		(width 0.0889)
		(layer "In4.Cu")
		(net "M_J_CPU1_SA_CB<1>")
	)
	(segment
		(start 189.024768 -236.010704)
		(end 191.160146 -236.435392)
		(width 0.14478)
		(layer "In4.Cu")
		(net "M_J_CPU1_SA_CB<1>")
	)
	(segment
		(start 133.103366 -245.62181)
		(end 133.111748 -245.616984)
		(width 0.0889)
		(layer "In4.Cu")
		(net "M_J_CPU1_SA_CB<1>")
	)
	(segment
		(start 139.31773 -245.616984)
		(end 139.326112 -245.62181)
		(width 0.0889)
		(layer "In4.Cu")
		(net "M_J_CPU1_SA_CB<1>")
	)
	(segment
		(start 179.414424 -236.860588)
		(end 180.508402 -236.860588)
		(width 0.14478)
		(layer "In4.Cu")
		(net "M_J_CPU1_SA_CB<1>")
	)
	(arc
		(start 137.437622 -245.616984)
		(mid 137.619873 -245.667334)
		(end 137.803382 -245.62181)
		(width 0.0889)
		(layer "In4.Cu")
		(net "M_J_CPU1_SA_CB<1>")
	)
	(arc
		(start 137.811764 -245.616984)
		(mid 138.09472 -245.540807)
		(end 138.377676 -245.616984)
		(width 0.0889)
		(layer "In4.Cu")
		(net "M_J_CPU1_SA_CB<1>")
	)
	(arc
		(start 133.67766 -245.616984)
		(mid 133.859911 -245.667334)
		(end 134.04342 -245.62181)
		(width 0.0889)
		(layer "In4.Cu")
		(net "M_J_CPU1_SA_CB<1>")
	)
	(arc
		(start 140.631926 -245.616984)
		(mid 140.914882 -245.540807)
		(end 141.197838 -245.616984)
		(width 0.0889)
		(layer "In4.Cu")
		(net "M_J_CPU1_SA_CB<1>")
	)
	(arc
		(start 142.137638 -245.616984)
		(mid 142.319889 -245.667334)
		(end 142.503398 -245.62181)
		(width 0.0889)
		(layer "In4.Cu")
		(net "M_J_CPU1_SA_CB<1>")
	)
	(arc
		(start 139.326112 -245.62181)
		(mid 139.50962 -245.667304)
		(end 139.691872 -245.616984)
		(width 0.0889)
		(layer "In4.Cu")
		(net "M_J_CPU1_SA_CB<1>")
	)
	(arc
		(start 141.571726 -245.616984)
		(mid 141.854682 -245.540807)
		(end 142.137638 -245.616984)
		(width 0.0889)
		(layer "In4.Cu")
		(net "M_J_CPU1_SA_CB<1>")
	)
	(arc
		(start 142.51178 -245.616984)
		(mid 142.794736 -245.540807)
		(end 143.077692 -245.616984)
		(width 0.0889)
		(layer "In4.Cu")
		(net "M_J_CPU1_SA_CB<1>")
	)
	(arc
		(start 131.29514 -245.585234)
		(mid 131.550205 -245.541883)
		(end 131.797806 -245.616984)
		(width 0.0889)
		(layer "In4.Cu")
		(net "M_J_CPU1_SA_CB<1>")
	)
	(arc
		(start 143.086074 -245.62181)
		(mid 143.269582 -245.667304)
		(end 143.451834 -245.616984)
		(width 0.0889)
		(layer "In4.Cu")
		(net "M_J_CPU1_SA_CB<1>")
	)
	(arc
		(start 139.691872 -245.616984)
		(mid 139.974828 -245.540807)
		(end 140.257784 -245.616984)
		(width 0.0889)
		(layer "In4.Cu")
		(net "M_J_CPU1_SA_CB<1>")
	)
	(arc
		(start 134.991856 -245.616984)
		(mid 135.274812 -245.540807)
		(end 135.557768 -245.616984)
		(width 0.0889)
		(layer "In4.Cu")
		(net "M_J_CPU1_SA_CB<1>")
	)
	(arc
		(start 135.56615 -245.62181)
		(mid 135.749658 -245.667304)
		(end 135.93191 -245.616984)
		(width 0.0889)
		(layer "In4.Cu")
		(net "M_J_CPU1_SA_CB<1>")
	)
	(arc
		(start 136.87171 -245.616984)
		(mid 137.154666 -245.540807)
		(end 137.437622 -245.616984)
		(width 0.0889)
		(layer "In4.Cu")
		(net "M_J_CPU1_SA_CB<1>")
	)
	(arc
		(start 133.111748 -245.616984)
		(mid 133.394704 -245.540807)
		(end 133.67766 -245.616984)
		(width 0.0889)
		(layer "In4.Cu")
		(net "M_J_CPU1_SA_CB<1>")
	)
	(arc
		(start 135.93191 -245.616984)
		(mid 136.214866 -245.540807)
		(end 136.497822 -245.616984)
		(width 0.0889)
		(layer "In4.Cu")
		(net "M_J_CPU1_SA_CB<1>")
	)
	(arc
		(start 138.751818 -245.616984)
		(mid 139.034774 -245.540807)
		(end 139.31773 -245.616984)
		(width 0.0889)
		(layer "In4.Cu")
		(net "M_J_CPU1_SA_CB<1>")
	)
	(arc
		(start 134.051802 -245.616984)
		(mid 134.334758 -245.540807)
		(end 134.617714 -245.616984)
		(width 0.0889)
		(layer "In4.Cu")
		(net "M_J_CPU1_SA_CB<1>")
	)
	(arc
		(start 136.497822 -245.616984)
		(mid 136.684766 -245.667239)
		(end 136.87171 -245.616984)
		(width 0.0889)
		(layer "In4.Cu")
		(net "M_J_CPU1_SA_CB<1>")
	)
	(arc
		(start 138.377676 -245.616984)
		(mid 138.559927 -245.667334)
		(end 138.743436 -245.62181)
		(width 0.0889)
		(layer "In4.Cu")
		(net "M_J_CPU1_SA_CB<1>")
	)
	(arc
		(start 145.332196 -245.616984)
		(mid 145.606902 -245.54062)
		(end 145.883884 -245.608348)
		(width 0.0889)
		(layer "In4.Cu")
		(net "M_J_CPU1_SA_CB<1>")
	)
	(arc
		(start 141.197838 -245.616984)
		(mid 141.384782 -245.667239)
		(end 141.571726 -245.616984)
		(width 0.0889)
		(layer "In4.Cu")
		(net "M_J_CPU1_SA_CB<1>")
	)
	(arc
		(start 144.976342 -245.627144)
		(mid 145.155571 -245.667297)
		(end 145.332196 -245.616984)
		(width 0.0889)
		(layer "In4.Cu")
		(net "M_J_CPU1_SA_CB<1>")
	)
	(arc
		(start 143.466566 -245.608348)
		(mid 143.743549 -245.540544)
		(end 144.018254 -245.616984)
		(width 0.0889)
		(layer "In4.Cu")
		(net "M_J_CPU1_SA_CB<1>")
	)
	(arc
		(start 132.737606 -245.616984)
		(mid 132.919857 -245.667334)
		(end 133.103366 -245.62181)
		(width 0.0889)
		(layer "In4.Cu")
		(net "M_J_CPU1_SA_CB<1>")
	)
	(arc
		(start 134.626096 -245.62181)
		(mid 134.809604 -245.667304)
		(end 134.991856 -245.616984)
		(width 0.0889)
		(layer "In4.Cu")
		(net "M_J_CPU1_SA_CB<1>")
	)
	(arc
		(start 144.39265 -245.616984)
		(mid 144.672078 -245.540818)
		(end 144.952466 -245.613428)
		(width 0.0889)
		(layer "In4.Cu")
		(net "M_J_CPU1_SA_CB<1>")
	)
	(arc
		(start 144.018254 -245.616984)
		(mid 144.198712 -245.667428)
		(end 144.380966 -245.623842)
		(width 0.0889)
		(layer "In4.Cu")
		(net "M_J_CPU1_SA_CB<1>")
	)
	(arc
		(start 131.797806 -245.616984)
		(mid 131.98475 -245.667239)
		(end 132.171694 -245.616984)
		(width 0.0889)
		(layer "In4.Cu")
		(net "M_J_CPU1_SA_CB<1>")
	)
	(arc
		(start 132.171694 -245.616984)
		(mid 132.45465 -245.540807)
		(end 132.737606 -245.616984)
		(width 0.0889)
		(layer "In4.Cu")
		(net "M_J_CPU1_SA_CB<1>")
	)
	(arc
		(start 140.266166 -245.62181)
		(mid 140.449674 -245.667304)
		(end 140.631926 -245.616984)
		(width 0.0889)
		(layer "In4.Cu")
		(net "M_J_CPU1_SA_CB<1>")
	)
	(segment
		(start 131.987798 -244.750336)
		(end 132.45465 -244.484398)
		(width 0.10668)
		(layer "F.Cu")
		(net "M_J_CPU1_SA_CB<0>")
	)
	(segment
		(start 178.601878 -235.160566)
		(end 181.227476 -235.160566)
		(width 0.14478)
		(layer "In4.Cu")
		(net "M_J_CPU1_SA_CB<0>")
	)
	(segment
		(start 137.907776 -244.806978)
		(end 137.916158 -244.811804)
		(width 0.0889)
		(layer "In4.Cu")
		(net "M_J_CPU1_SA_CB<0>")
	)
	(segment
		(start 135.453374 -244.811804)
		(end 135.461756 -244.806978)
		(width 0.0889)
		(layer "In4.Cu")
		(net "M_J_CPU1_SA_CB<0>")
	)
	(segment
		(start 147.702778 -243.995194)
		(end 154.018234 -243.995194)
		(width 0.14478)
		(layer "In4.Cu")
		(net "M_J_CPU1_SA_CB<0>")
	)
	(segment
		(start 136.967722 -244.806978)
		(end 136.976104 -244.811804)
		(width 0.0889)
		(layer "In4.Cu")
		(net "M_J_CPU1_SA_CB<0>")
	)
	(segment
		(start 163.726114 -235.160566)
		(end 166.506144 -235.160566)
		(width 0.14478)
		(layer "In4.Cu")
		(net "M_J_CPU1_SA_CB<0>")
	)
	(segment
		(start 136.393428 -244.811804)
		(end 136.40181 -244.806978)
		(width 0.0889)
		(layer "In4.Cu")
		(net "M_J_CPU1_SA_CB<0>")
	)
	(segment
		(start 146.479768 -244.390164)
		(end 147.098512 -244.390164)
		(width 0.0889)
		(layer "In4.Cu")
		(net "M_J_CPU1_SA_CB<0>")
	)
	(segment
		(start 147.493482 -243.995194)
		(end 147.702778 -243.995194)
		(width 0.0889)
		(layer "In4.Cu")
		(net "M_J_CPU1_SA_CB<0>")
	)
	(segment
		(start 158.246826 -239.766602)
		(end 159.120078 -239.766602)
		(width 0.14478)
		(layer "In4.Cu")
		(net "M_J_CPU1_SA_CB<0>")
	)
	(segment
		(start 189.024768 -234.310682)
		(end 191.160146 -234.73537)
		(width 0.14478)
		(layer "In4.Cu")
		(net "M_J_CPU1_SA_CB<0>")
	)
	(segment
		(start 174.53483 -234.310682)
		(end 177.751994 -234.310682)
		(width 0.14478)
		(layer "In4.Cu")
		(net "M_J_CPU1_SA_CB<0>")
	)
	(segment
		(start 181.227476 -235.160566)
		(end 182.07736 -234.310682)
		(width 0.14478)
		(layer "In4.Cu")
		(net "M_J_CPU1_SA_CB<0>")
	)
	(segment
		(start 132.608828 -244.749828)
		(end 132.705094 -244.775228)
		(width 0.0889)
		(layer "In4.Cu")
		(net "M_J_CPU1_SA_CB<0>")
	)
	(segment
		(start 133.20776 -244.806978)
		(end 133.216142 -244.811804)
		(width 0.0889)
		(layer "In4.Cu")
		(net "M_J_CPU1_SA_CB<0>")
	)
	(segment
		(start 145.144744 -244.730524)
		(end 146.139408 -244.730524)
		(width 0.0889)
		(layer "In4.Cu")
		(net "M_J_CPU1_SA_CB<0>")
	)
	(segment
		(start 141.667738 -244.806978)
		(end 141.67612 -244.811804)
		(width 0.0889)
		(layer "In4.Cu")
		(net "M_J_CPU1_SA_CB<0>")
	)
	(segment
		(start 166.506144 -235.160566)
		(end 167.356028 -234.310682)
		(width 0.14478)
		(layer "In4.Cu")
		(net "M_J_CPU1_SA_CB<0>")
	)
	(segment
		(start 144.477994 -244.800882)
		(end 144.488408 -244.806978)
		(width 0.0889)
		(layer "In4.Cu")
		(net "M_J_CPU1_SA_CB<0>")
	)
	(segment
		(start 132.45465 -244.484398)
		(end 132.608828 -244.749828)
		(width 0.0889)
		(layer "In4.Cu")
		(net "M_J_CPU1_SA_CB<0>")
	)
	(segment
		(start 169.776902 -234.310682)
		(end 170.626786 -235.160566)
		(width 0.14478)
		(layer "In4.Cu")
		(net "M_J_CPU1_SA_CB<0>")
	)
	(segment
		(start 170.626786 -235.160566)
		(end 173.684946 -235.160566)
		(width 0.14478)
		(layer "In4.Cu")
		(net "M_J_CPU1_SA_CB<0>")
	)
	(segment
		(start 140.15339 -244.811804)
		(end 140.161772 -244.806978)
		(width 0.0889)
		(layer "In4.Cu")
		(net "M_J_CPU1_SA_CB<0>")
	)
	(segment
		(start 146.139408 -244.730524)
		(end 146.479768 -244.390164)
		(width 0.0889)
		(layer "In4.Cu")
		(net "M_J_CPU1_SA_CB<0>")
	)
	(segment
		(start 177.751994 -234.310682)
		(end 178.601878 -235.160566)
		(width 0.14478)
		(layer "In4.Cu")
		(net "M_J_CPU1_SA_CB<0>")
	)
	(segment
		(start 147.098512 -244.390164)
		(end 147.493482 -243.995194)
		(width 0.0889)
		(layer "In4.Cu")
		(net "M_J_CPU1_SA_CB<0>")
	)
	(segment
		(start 159.120078 -239.766602)
		(end 163.726114 -235.160566)
		(width 0.14478)
		(layer "In4.Cu")
		(net "M_J_CPU1_SA_CB<0>")
	)
	(segment
		(start 141.093444 -244.811804)
		(end 141.101826 -244.806978)
		(width 0.0889)
		(layer "In4.Cu")
		(net "M_J_CPU1_SA_CB<0>")
	)
	(segment
		(start 154.018234 -243.995194)
		(end 158.246826 -239.766602)
		(width 0.14478)
		(layer "In4.Cu")
		(net "M_J_CPU1_SA_CB<0>")
	)
	(segment
		(start 173.684946 -235.160566)
		(end 174.53483 -234.310682)
		(width 0.14478)
		(layer "In4.Cu")
		(net "M_J_CPU1_SA_CB<0>")
	)
	(segment
		(start 167.356028 -234.310682)
		(end 169.776902 -234.310682)
		(width 0.14478)
		(layer "In4.Cu")
		(net "M_J_CPU1_SA_CB<0>")
	)
	(segment
		(start 143.547592 -244.806978)
		(end 143.555974 -244.811804)
		(width 0.0889)
		(layer "In4.Cu")
		(net "M_J_CPU1_SA_CB<0>")
	)
	(segment
		(start 182.07736 -234.310682)
		(end 189.024768 -234.310682)
		(width 0.14478)
		(layer "In4.Cu")
		(net "M_J_CPU1_SA_CB<0>")
	)
	(arc
		(start 136.40181 -244.806978)
		(mid 136.684766 -244.730801)
		(end 136.967722 -244.806978)
		(width 0.0889)
		(layer "In4.Cu")
		(net "M_J_CPU1_SA_CB<0>")
	)
	(arc
		(start 138.84783 -244.806978)
		(mid 139.034774 -244.857233)
		(end 139.221718 -244.806978)
		(width 0.0889)
		(layer "In4.Cu")
		(net "M_J_CPU1_SA_CB<0>")
	)
	(arc
		(start 142.607792 -244.806978)
		(mid 142.794736 -244.857233)
		(end 142.98168 -244.806978)
		(width 0.0889)
		(layer "In4.Cu")
		(net "M_J_CPU1_SA_CB<0>")
	)
	(arc
		(start 137.341864 -244.806978)
		(mid 137.62482 -244.730801)
		(end 137.907776 -244.806978)
		(width 0.0889)
		(layer "In4.Cu")
		(net "M_J_CPU1_SA_CB<0>")
	)
	(arc
		(start 143.555974 -244.811804)
		(mid 143.739736 -244.85742)
		(end 143.922242 -244.806978)
		(width 0.0889)
		(layer "In4.Cu")
		(net "M_J_CPU1_SA_CB<0>")
	)
	(arc
		(start 141.101826 -244.806978)
		(mid 141.384782 -244.730801)
		(end 141.667738 -244.806978)
		(width 0.0889)
		(layer "In4.Cu")
		(net "M_J_CPU1_SA_CB<0>")
	)
	(arc
		(start 135.461756 -244.806978)
		(mid 135.744712 -244.730801)
		(end 136.027668 -244.806978)
		(width 0.0889)
		(layer "In4.Cu")
		(net "M_J_CPU1_SA_CB<0>")
	)
	(arc
		(start 142.98168 -244.806978)
		(mid 143.264636 -244.730801)
		(end 143.547592 -244.806978)
		(width 0.0889)
		(layer "In4.Cu")
		(net "M_J_CPU1_SA_CB<0>")
	)
	(arc
		(start 134.147814 -244.806978)
		(mid 134.334758 -244.857233)
		(end 134.521702 -244.806978)
		(width 0.0889)
		(layer "In4.Cu")
		(net "M_J_CPU1_SA_CB<0>")
	)
	(arc
		(start 139.78763 -244.806978)
		(mid 139.969881 -244.857328)
		(end 140.15339 -244.811804)
		(width 0.0889)
		(layer "In4.Cu")
		(net "M_J_CPU1_SA_CB<0>")
	)
	(arc
		(start 138.281918 -244.806978)
		(mid 138.564874 -244.730801)
		(end 138.84783 -244.806978)
		(width 0.0889)
		(layer "In4.Cu")
		(net "M_J_CPU1_SA_CB<0>")
	)
	(arc
		(start 135.087614 -244.806978)
		(mid 135.269865 -244.857328)
		(end 135.453374 -244.811804)
		(width 0.0889)
		(layer "In4.Cu")
		(net "M_J_CPU1_SA_CB<0>")
	)
	(arc
		(start 142.04188 -244.806978)
		(mid 142.324836 -244.730801)
		(end 142.607792 -244.806978)
		(width 0.0889)
		(layer "In4.Cu")
		(net "M_J_CPU1_SA_CB<0>")
	)
	(arc
		(start 133.581902 -244.806978)
		(mid 133.864858 -244.730801)
		(end 134.147814 -244.806978)
		(width 0.0889)
		(layer "In4.Cu")
		(net "M_J_CPU1_SA_CB<0>")
	)
	(arc
		(start 136.976104 -244.811804)
		(mid 137.159612 -244.857298)
		(end 137.341864 -244.806978)
		(width 0.0889)
		(layer "In4.Cu")
		(net "M_J_CPU1_SA_CB<0>")
	)
	(arc
		(start 144.84604 -244.816122)
		(mid 144.989379 -244.752335)
		(end 145.144744 -244.730524)
		(width 0.0889)
		(layer "In4.Cu")
		(net "M_J_CPU1_SA_CB<0>")
	)
	(arc
		(start 139.221718 -244.806978)
		(mid 139.504674 -244.730801)
		(end 139.78763 -244.806978)
		(width 0.0889)
		(layer "In4.Cu")
		(net "M_J_CPU1_SA_CB<0>")
	)
	(arc
		(start 140.727684 -244.806978)
		(mid 140.909935 -244.857328)
		(end 141.093444 -244.811804)
		(width 0.0889)
		(layer "In4.Cu")
		(net "M_J_CPU1_SA_CB<0>")
	)
	(arc
		(start 132.705094 -244.775228)
		(mid 132.960159 -244.731877)
		(end 133.20776 -244.806978)
		(width 0.0889)
		(layer "In4.Cu")
		(net "M_J_CPU1_SA_CB<0>")
	)
	(arc
		(start 133.216142 -244.811804)
		(mid 133.39965 -244.857298)
		(end 133.581902 -244.806978)
		(width 0.0889)
		(layer "In4.Cu")
		(net "M_J_CPU1_SA_CB<0>")
	)
	(arc
		(start 141.67612 -244.811804)
		(mid 141.859628 -244.857298)
		(end 142.04188 -244.806978)
		(width 0.0889)
		(layer "In4.Cu")
		(net "M_J_CPU1_SA_CB<0>")
	)
	(arc
		(start 136.027668 -244.806978)
		(mid 136.209919 -244.857328)
		(end 136.393428 -244.811804)
		(width 0.0889)
		(layer "In4.Cu")
		(net "M_J_CPU1_SA_CB<0>")
	)
	(arc
		(start 143.922242 -244.806978)
		(mid 144.199309 -244.730707)
		(end 144.477994 -244.800882)
		(width 0.0889)
		(layer "In4.Cu")
		(net "M_J_CPU1_SA_CB<0>")
	)
	(arc
		(start 134.521702 -244.806978)
		(mid 134.804658 -244.730801)
		(end 135.087614 -244.806978)
		(width 0.0889)
		(layer "In4.Cu")
		(net "M_J_CPU1_SA_CB<0>")
	)
	(arc
		(start 140.161772 -244.806978)
		(mid 140.444728 -244.730801)
		(end 140.727684 -244.806978)
		(width 0.0889)
		(layer "In4.Cu")
		(net "M_J_CPU1_SA_CB<0>")
	)
	(arc
		(start 144.488408 -244.806978)
		(mid 144.666058 -244.857238)
		(end 144.84604 -244.816122)
		(width 0.0889)
		(layer "In4.Cu")
		(net "M_J_CPU1_SA_CB<0>")
	)
	(arc
		(start 137.916158 -244.811804)
		(mid 138.099666 -244.857298)
		(end 138.281918 -244.806978)
		(width 0.0889)
		(layer "In4.Cu")
		(net "M_J_CPU1_SA_CB<0>")
	)
	(segment
		(start 130.577844 -255.280414)
		(end 131.044696 -255.014476)
		(width 0.10668)
		(layer "F.Cu")
		(net "M_J_CPU1_SA_CA<6>")
	)
	(segment
		(start 145.848832 -255.331468)
		(end 146.215608 -255.698244)
		(width 0.0889)
		(layer "In4.Cu")
		(net "M_J_CPU1_SA_CA<6>")
	)
	(segment
		(start 143.077692 -255.337056)
		(end 143.086074 -255.341882)
		(width 0.0889)
		(layer "In4.Cu")
		(net "M_J_CPU1_SA_CA<6>")
	)
	(segment
		(start 164.044884 -254.710438)
		(end 183.856376 -254.710438)
		(width 0.14478)
		(layer "In4.Cu")
		(net "M_J_CPU1_SA_CA<6>")
	)
	(segment
		(start 187.245498 -252.160278)
		(end 190.735204 -252.160278)
		(width 0.14478)
		(layer "In4.Cu")
		(net "M_J_CPU1_SA_CA<6>")
	)
	(segment
		(start 139.31773 -255.337056)
		(end 139.326112 -255.341882)
		(width 0.0889)
		(layer "In4.Cu")
		(net "M_J_CPU1_SA_CA<6>")
	)
	(segment
		(start 183.856376 -254.710438)
		(end 184.437528 -254.129286)
		(width 0.14478)
		(layer "In4.Cu")
		(net "M_J_CPU1_SA_CA<6>")
	)
	(segment
		(start 156.554932 -254.716026)
		(end 157.10027 -255.261364)
		(width 0.14478)
		(layer "In4.Cu")
		(net "M_J_CPU1_SA_CA<6>")
	)
	(segment
		(start 142.503398 -255.341882)
		(end 142.51178 -255.337056)
		(width 0.0889)
		(layer "In4.Cu")
		(net "M_J_CPU1_SA_CA<6>")
	)
	(segment
		(start 144.380966 -255.343914)
		(end 144.39265 -255.337056)
		(width 0.0889)
		(layer "In4.Cu")
		(net "M_J_CPU1_SA_CA<6>")
	)
	(segment
		(start 146.215608 -255.698244)
		(end 147.554188 -255.698244)
		(width 0.0889)
		(layer "In4.Cu")
		(net "M_J_CPU1_SA_CA<6>")
	)
	(segment
		(start 143.451834 -255.337056)
		(end 143.466566 -255.32842)
		(width 0.0889)
		(layer "In4.Cu")
		(net "M_J_CPU1_SA_CA<6>")
	)
	(segment
		(start 186.63158 -252.408944)
		(end 186.823096 -252.217428)
		(width 0.14478)
		(layer "In4.Cu")
		(net "M_J_CPU1_SA_CA<6>")
	)
	(segment
		(start 135.557768 -255.337056)
		(end 135.56615 -255.341882)
		(width 0.0889)
		(layer "In4.Cu")
		(net "M_J_CPU1_SA_CA<6>")
	)
	(segment
		(start 184.437528 -254.129286)
		(end 184.437528 -253.611888)
		(width 0.14478)
		(layer "In4.Cu")
		(net "M_J_CPU1_SA_CA<6>")
	)
	(segment
		(start 186.823096 -252.217428)
		(end 186.8297 -252.217428)
		(width 0.0889)
		(layer "In4.Cu")
		(net "M_J_CPU1_SA_CA<6>")
	)
	(segment
		(start 157.10027 -255.261364)
		(end 163.493958 -255.261364)
		(width 0.14478)
		(layer "In4.Cu")
		(net "M_J_CPU1_SA_CA<6>")
	)
	(segment
		(start 150.866348 -255.698244)
		(end 151.848566 -254.716026)
		(width 0.14478)
		(layer "In4.Cu")
		(net "M_J_CPU1_SA_CA<6>")
	)
	(segment
		(start 133.103366 -255.341882)
		(end 133.111748 -255.337056)
		(width 0.0889)
		(layer "In4.Cu")
		(net "M_J_CPU1_SA_CA<6>")
	)
	(segment
		(start 190.735204 -252.160278)
		(end 191.160146 -252.58522)
		(width 0.14478)
		(layer "In4.Cu")
		(net "M_J_CPU1_SA_CA<6>")
	)
	(segment
		(start 185.640472 -252.408944)
		(end 186.63158 -252.408944)
		(width 0.14478)
		(layer "In4.Cu")
		(net "M_J_CPU1_SA_CA<6>")
	)
	(segment
		(start 151.848566 -254.716026)
		(end 156.554932 -254.716026)
		(width 0.14478)
		(layer "In4.Cu")
		(net "M_J_CPU1_SA_CA<6>")
	)
	(segment
		(start 147.554188 -255.698244)
		(end 150.866348 -255.698244)
		(width 0.14478)
		(layer "In4.Cu")
		(net "M_J_CPU1_SA_CA<6>")
	)
	(segment
		(start 137.803382 -255.341882)
		(end 137.811764 -255.337056)
		(width 0.0889)
		(layer "In4.Cu")
		(net "M_J_CPU1_SA_CA<6>")
	)
	(segment
		(start 144.952466 -255.3335)
		(end 144.958054 -255.336802)
		(width 0.0889)
		(layer "In4.Cu")
		(net "M_J_CPU1_SA_CA<6>")
	)
	(segment
		(start 138.743436 -255.341882)
		(end 138.751818 -255.337056)
		(width 0.0889)
		(layer "In4.Cu")
		(net "M_J_CPU1_SA_CA<6>")
	)
	(segment
		(start 144.958054 -255.336802)
		(end 144.976342 -255.347216)
		(width 0.0889)
		(layer "In4.Cu")
		(net "M_J_CPU1_SA_CA<6>")
	)
	(segment
		(start 131.198874 -255.279906)
		(end 131.29514 -255.305306)
		(width 0.0889)
		(layer "In4.Cu")
		(net "M_J_CPU1_SA_CA<6>")
	)
	(segment
		(start 145.337784 -255.331468)
		(end 145.848832 -255.331468)
		(width 0.0889)
		(layer "In4.Cu")
		(net "M_J_CPU1_SA_CA<6>")
	)
	(segment
		(start 163.493958 -255.261364)
		(end 164.044884 -254.710438)
		(width 0.14478)
		(layer "In4.Cu")
		(net "M_J_CPU1_SA_CA<6>")
	)
	(segment
		(start 186.8297 -252.217428)
		(end 186.88685 -252.160278)
		(width 0.0889)
		(layer "In4.Cu")
		(net "M_J_CPU1_SA_CA<6>")
	)
	(segment
		(start 134.04342 -255.341882)
		(end 134.051802 -255.337056)
		(width 0.0889)
		(layer "In4.Cu")
		(net "M_J_CPU1_SA_CA<6>")
	)
	(segment
		(start 184.437528 -253.611888)
		(end 185.640472 -252.408944)
		(width 0.14478)
		(layer "In4.Cu")
		(net "M_J_CPU1_SA_CA<6>")
	)
	(segment
		(start 145.332196 -255.337056)
		(end 145.337784 -255.331468)
		(width 0.0889)
		(layer "In4.Cu")
		(net "M_J_CPU1_SA_CA<6>")
	)
	(segment
		(start 131.044696 -255.014476)
		(end 131.198874 -255.279906)
		(width 0.0889)
		(layer "In4.Cu")
		(net "M_J_CPU1_SA_CA<6>")
	)
	(segment
		(start 186.88685 -252.160278)
		(end 187.245498 -252.160278)
		(width 0.0889)
		(layer "In4.Cu")
		(net "M_J_CPU1_SA_CA<6>")
	)
	(segment
		(start 140.257784 -255.337056)
		(end 140.266166 -255.341882)
		(width 0.0889)
		(layer "In4.Cu")
		(net "M_J_CPU1_SA_CA<6>")
	)
	(segment
		(start 134.617714 -255.337056)
		(end 134.626096 -255.341882)
		(width 0.0889)
		(layer "In4.Cu")
		(net "M_J_CPU1_SA_CA<6>")
	)
	(arc
		(start 140.266166 -255.341882)
		(mid 140.449674 -255.387376)
		(end 140.631926 -255.337056)
		(width 0.0889)
		(layer "In4.Cu")
		(net "M_J_CPU1_SA_CA<6>")
	)
	(arc
		(start 144.976342 -255.347216)
		(mid 145.155571 -255.387369)
		(end 145.332196 -255.337056)
		(width 0.0889)
		(layer "In4.Cu")
		(net "M_J_CPU1_SA_CA<6>")
	)
	(arc
		(start 131.797806 -255.337056)
		(mid 131.98475 -255.387311)
		(end 132.171694 -255.337056)
		(width 0.0889)
		(layer "In4.Cu")
		(net "M_J_CPU1_SA_CA<6>")
	)
	(arc
		(start 142.51178 -255.337056)
		(mid 142.794736 -255.260879)
		(end 143.077692 -255.337056)
		(width 0.0889)
		(layer "In4.Cu")
		(net "M_J_CPU1_SA_CA<6>")
	)
	(arc
		(start 133.67766 -255.337056)
		(mid 133.859911 -255.387406)
		(end 134.04342 -255.341882)
		(width 0.0889)
		(layer "In4.Cu")
		(net "M_J_CPU1_SA_CA<6>")
	)
	(arc
		(start 132.737606 -255.337056)
		(mid 132.919857 -255.387406)
		(end 133.103366 -255.341882)
		(width 0.0889)
		(layer "In4.Cu")
		(net "M_J_CPU1_SA_CA<6>")
	)
	(arc
		(start 135.56615 -255.341882)
		(mid 135.749658 -255.387376)
		(end 135.93191 -255.337056)
		(width 0.0889)
		(layer "In4.Cu")
		(net "M_J_CPU1_SA_CA<6>")
	)
	(arc
		(start 141.571726 -255.337056)
		(mid 141.854682 -255.260879)
		(end 142.137638 -255.337056)
		(width 0.0889)
		(layer "In4.Cu")
		(net "M_J_CPU1_SA_CA<6>")
	)
	(arc
		(start 134.051802 -255.337056)
		(mid 134.334758 -255.260879)
		(end 134.617714 -255.337056)
		(width 0.0889)
		(layer "In4.Cu")
		(net "M_J_CPU1_SA_CA<6>")
	)
	(arc
		(start 139.326112 -255.341882)
		(mid 139.50962 -255.387376)
		(end 139.691872 -255.337056)
		(width 0.0889)
		(layer "In4.Cu")
		(net "M_J_CPU1_SA_CA<6>")
	)
	(arc
		(start 141.197838 -255.337056)
		(mid 141.384782 -255.387311)
		(end 141.571726 -255.337056)
		(width 0.0889)
		(layer "In4.Cu")
		(net "M_J_CPU1_SA_CA<6>")
	)
	(arc
		(start 144.018254 -255.337056)
		(mid 144.198712 -255.3875)
		(end 144.380966 -255.343914)
		(width 0.0889)
		(layer "In4.Cu")
		(net "M_J_CPU1_SA_CA<6>")
	)
	(arc
		(start 132.171694 -255.337056)
		(mid 132.45465 -255.260879)
		(end 132.737606 -255.337056)
		(width 0.0889)
		(layer "In4.Cu")
		(net "M_J_CPU1_SA_CA<6>")
	)
	(arc
		(start 139.691872 -255.337056)
		(mid 139.974828 -255.260879)
		(end 140.257784 -255.337056)
		(width 0.0889)
		(layer "In4.Cu")
		(net "M_J_CPU1_SA_CA<6>")
	)
	(arc
		(start 137.437622 -255.337056)
		(mid 137.619873 -255.387406)
		(end 137.803382 -255.341882)
		(width 0.0889)
		(layer "In4.Cu")
		(net "M_J_CPU1_SA_CA<6>")
	)
	(arc
		(start 142.137638 -255.337056)
		(mid 142.319889 -255.387406)
		(end 142.503398 -255.341882)
		(width 0.0889)
		(layer "In4.Cu")
		(net "M_J_CPU1_SA_CA<6>")
	)
	(arc
		(start 143.086074 -255.341882)
		(mid 143.269582 -255.387376)
		(end 143.451834 -255.337056)
		(width 0.0889)
		(layer "In4.Cu")
		(net "M_J_CPU1_SA_CA<6>")
	)
	(arc
		(start 136.497822 -255.337056)
		(mid 136.684766 -255.387311)
		(end 136.87171 -255.337056)
		(width 0.0889)
		(layer "In4.Cu")
		(net "M_J_CPU1_SA_CA<6>")
	)
	(arc
		(start 140.631926 -255.337056)
		(mid 140.914882 -255.260879)
		(end 141.197838 -255.337056)
		(width 0.0889)
		(layer "In4.Cu")
		(net "M_J_CPU1_SA_CA<6>")
	)
	(arc
		(start 138.377676 -255.337056)
		(mid 138.559927 -255.387406)
		(end 138.743436 -255.341882)
		(width 0.0889)
		(layer "In4.Cu")
		(net "M_J_CPU1_SA_CA<6>")
	)
	(arc
		(start 131.29514 -255.305306)
		(mid 131.550205 -255.261955)
		(end 131.797806 -255.337056)
		(width 0.0889)
		(layer "In4.Cu")
		(net "M_J_CPU1_SA_CA<6>")
	)
	(arc
		(start 138.751818 -255.337056)
		(mid 139.034774 -255.260879)
		(end 139.31773 -255.337056)
		(width 0.0889)
		(layer "In4.Cu")
		(net "M_J_CPU1_SA_CA<6>")
	)
	(arc
		(start 135.93191 -255.337056)
		(mid 136.214866 -255.260879)
		(end 136.497822 -255.337056)
		(width 0.0889)
		(layer "In4.Cu")
		(net "M_J_CPU1_SA_CA<6>")
	)
	(arc
		(start 133.111748 -255.337056)
		(mid 133.394704 -255.260879)
		(end 133.67766 -255.337056)
		(width 0.0889)
		(layer "In4.Cu")
		(net "M_J_CPU1_SA_CA<6>")
	)
	(arc
		(start 136.87171 -255.337056)
		(mid 137.154666 -255.260879)
		(end 137.437622 -255.337056)
		(width 0.0889)
		(layer "In4.Cu")
		(net "M_J_CPU1_SA_CA<6>")
	)
	(arc
		(start 134.991856 -255.337056)
		(mid 135.274812 -255.260879)
		(end 135.557768 -255.337056)
		(width 0.0889)
		(layer "In4.Cu")
		(net "M_J_CPU1_SA_CA<6>")
	)
	(arc
		(start 143.466566 -255.32842)
		(mid 143.743549 -255.260616)
		(end 144.018254 -255.337056)
		(width 0.0889)
		(layer "In4.Cu")
		(net "M_J_CPU1_SA_CA<6>")
	)
	(arc
		(start 134.626096 -255.341882)
		(mid 134.809604 -255.387376)
		(end 134.991856 -255.337056)
		(width 0.0889)
		(layer "In4.Cu")
		(net "M_J_CPU1_SA_CA<6>")
	)
	(arc
		(start 137.811764 -255.337056)
		(mid 138.09472 -255.260879)
		(end 138.377676 -255.337056)
		(width 0.0889)
		(layer "In4.Cu")
		(net "M_J_CPU1_SA_CA<6>")
	)
	(arc
		(start 144.39265 -255.337056)
		(mid 144.672078 -255.26089)
		(end 144.952466 -255.3335)
		(width 0.0889)
		(layer "In4.Cu")
		(net "M_J_CPU1_SA_CA<6>")
	)
	(segment
		(start 132.457952 -255.280414)
		(end 132.924804 -255.014476)
		(width 0.10668)
		(layer "F.Cu")
		(net "M_J_CPU1_SA_CA<5>")
	)
	(segment
		(start 145.332196 -254.691896)
		(end 145.41627 -254.740664)
		(width 0.0889)
		(layer "In4.Cu")
		(net "M_J_CPU1_SA_CA<5>")
	)
	(segment
		(start 143.077692 -254.691896)
		(end 143.086074 -254.68707)
		(width 0.0889)
		(layer "In4.Cu")
		(net "M_J_CPU1_SA_CA<5>")
	)
	(segment
		(start 160.709356 -254.42799)
		(end 160.709356 -254.602742)
		(width 0.14478)
		(layer "In4.Cu")
		(net "M_J_CPU1_SA_CA<5>")
	)
	(segment
		(start 160.547812 -254.266446)
		(end 160.709356 -254.42799)
		(width 0.14478)
		(layer "In4.Cu")
		(net "M_J_CPU1_SA_CA<5>")
	)
	(segment
		(start 158.665164 -254.764286)
		(end 158.89351 -254.764286)
		(width 0.14478)
		(layer "In4.Cu")
		(net "M_J_CPU1_SA_CA<5>")
	)
	(segment
		(start 157.400752 -254.602742)
		(end 157.562296 -254.764286)
		(width 0.14478)
		(layer "In4.Cu")
		(net "M_J_CPU1_SA_CA<5>")
	)
	(segment
		(start 157.952186 -254.602742)
		(end 157.952186 -254.42799)
		(width 0.14478)
		(layer "In4.Cu")
		(net "M_J_CPU1_SA_CA<5>")
	)
	(segment
		(start 150.650702 -255.241044)
		(end 151.6253 -254.266446)
		(width 0.14478)
		(layer "In4.Cu")
		(net "M_J_CPU1_SA_CA<5>")
	)
	(segment
		(start 139.31773 -254.691896)
		(end 139.326112 -254.68707)
		(width 0.0889)
		(layer "In4.Cu")
		(net "M_J_CPU1_SA_CA<5>")
	)
	(segment
		(start 159.996378 -254.764286)
		(end 160.157922 -254.602742)
		(width 0.14478)
		(layer "In4.Cu")
		(net "M_J_CPU1_SA_CA<5>")
	)
	(segment
		(start 158.89351 -254.764286)
		(end 159.055054 -254.602742)
		(width 0.14478)
		(layer "In4.Cu")
		(net "M_J_CPU1_SA_CA<5>")
	)
	(segment
		(start 162.144964 -254.266446)
		(end 162.55111 -253.8603)
		(width 0.14478)
		(layer "In4.Cu")
		(net "M_J_CPU1_SA_CA<5>")
	)
	(segment
		(start 132.924804 -255.014476)
		(end 132.770626 -254.749046)
		(width 0.0889)
		(layer "In4.Cu")
		(net "M_J_CPU1_SA_CA<5>")
	)
	(segment
		(start 162.55111 -253.8603)
		(end 181.55285 -253.8603)
		(width 0.14478)
		(layer "In4.Cu")
		(net "M_J_CPU1_SA_CA<5>")
	)
	(segment
		(start 158.342076 -254.266446)
		(end 158.50362 -254.42799)
		(width 0.14478)
		(layer "In4.Cu")
		(net "M_J_CPU1_SA_CA<5>")
	)
	(segment
		(start 151.6253 -254.266446)
		(end 157.239208 -254.266446)
		(width 0.14478)
		(layer "In4.Cu")
		(net "M_J_CPU1_SA_CA<5>")
	)
	(segment
		(start 159.606488 -254.42799)
		(end 159.606488 -254.602742)
		(width 0.14478)
		(layer "In4.Cu")
		(net "M_J_CPU1_SA_CA<5>")
	)
	(segment
		(start 146.010122 -254.761238)
		(end 146.489928 -255.241044)
		(width 0.0889)
		(layer "In4.Cu")
		(net "M_J_CPU1_SA_CA<5>")
	)
	(segment
		(start 133.103366 -254.68707)
		(end 133.111748 -254.691896)
		(width 0.0889)
		(layer "In4.Cu")
		(net "M_J_CPU1_SA_CA<5>")
	)
	(segment
		(start 185.41873 -251.735336)
		(end 187.060078 -251.735336)
		(width 0.14478)
		(layer "In4.Cu")
		(net "M_J_CPU1_SA_CA<5>")
	)
	(segment
		(start 145.492724 -254.761238)
		(end 146.010122 -254.761238)
		(width 0.0889)
		(layer "In4.Cu")
		(net "M_J_CPU1_SA_CA<5>")
	)
	(segment
		(start 134.617714 -254.691896)
		(end 134.626096 -254.68707)
		(width 0.0889)
		(layer "In4.Cu")
		(net "M_J_CPU1_SA_CA<5>")
	)
	(segment
		(start 161.422334 -254.266446)
		(end 162.144964 -254.266446)
		(width 0.14478)
		(layer "In4.Cu")
		(net "M_J_CPU1_SA_CA<5>")
	)
	(segment
		(start 144.958054 -254.69215)
		(end 144.976342 -254.681736)
		(width 0.0889)
		(layer "In4.Cu")
		(net "M_J_CPU1_SA_CA<5>")
	)
	(segment
		(start 158.50362 -254.42799)
		(end 158.50362 -254.602742)
		(width 0.14478)
		(layer "In4.Cu")
		(net "M_J_CPU1_SA_CA<5>")
	)
	(segment
		(start 159.444944 -254.266446)
		(end 159.606488 -254.42799)
		(width 0.14478)
		(layer "In4.Cu")
		(net "M_J_CPU1_SA_CA<5>")
	)
	(segment
		(start 142.503398 -254.68707)
		(end 142.51178 -254.691896)
		(width 0.0889)
		(layer "In4.Cu")
		(net "M_J_CPU1_SA_CA<5>")
	)
	(segment
		(start 161.26079 -254.42799)
		(end 161.422334 -254.266446)
		(width 0.14478)
		(layer "In4.Cu")
		(net "M_J_CPU1_SA_CA<5>")
	)
	(segment
		(start 157.562296 -254.764286)
		(end 157.790642 -254.764286)
		(width 0.14478)
		(layer "In4.Cu")
		(net "M_J_CPU1_SA_CA<5>")
	)
	(segment
		(start 138.743436 -254.68707)
		(end 138.751818 -254.691896)
		(width 0.0889)
		(layer "In4.Cu")
		(net "M_J_CPU1_SA_CA<5>")
	)
	(segment
		(start 147.582128 -255.241044)
		(end 150.650702 -255.241044)
		(width 0.14478)
		(layer "In4.Cu")
		(net "M_J_CPU1_SA_CA<5>")
	)
	(segment
		(start 144.952466 -254.695452)
		(end 144.958054 -254.69215)
		(width 0.0889)
		(layer "In4.Cu")
		(net "M_J_CPU1_SA_CA<5>")
	)
	(segment
		(start 157.239208 -254.266446)
		(end 157.400752 -254.42799)
		(width 0.14478)
		(layer "In4.Cu")
		(net "M_J_CPU1_SA_CA<5>")
	)
	(segment
		(start 143.451834 -254.691896)
		(end 143.462248 -254.697992)
		(width 0.0889)
		(layer "In4.Cu")
		(net "M_J_CPU1_SA_CA<5>")
	)
	(segment
		(start 134.04342 -254.68707)
		(end 134.051802 -254.691896)
		(width 0.0889)
		(layer "In4.Cu")
		(net "M_J_CPU1_SA_CA<5>")
	)
	(segment
		(start 137.803382 -254.68707)
		(end 137.811764 -254.691896)
		(width 0.0889)
		(layer "In4.Cu")
		(net "M_J_CPU1_SA_CA<5>")
	)
	(segment
		(start 159.055054 -254.602742)
		(end 159.055054 -254.42799)
		(width 0.14478)
		(layer "In4.Cu")
		(net "M_J_CPU1_SA_CA<5>")
	)
	(segment
		(start 161.26079 -254.602742)
		(end 161.26079 -254.42799)
		(width 0.14478)
		(layer "In4.Cu")
		(net "M_J_CPU1_SA_CA<5>")
	)
	(segment
		(start 158.50362 -254.602742)
		(end 158.665164 -254.764286)
		(width 0.14478)
		(layer "In4.Cu")
		(net "M_J_CPU1_SA_CA<5>")
	)
	(segment
		(start 182.402734 -253.010416)
		(end 184.14365 -253.010416)
		(width 0.14478)
		(layer "In4.Cu")
		(net "M_J_CPU1_SA_CA<5>")
	)
	(segment
		(start 160.709356 -254.602742)
		(end 160.8709 -254.764286)
		(width 0.14478)
		(layer "In4.Cu")
		(net "M_J_CPU1_SA_CA<5>")
	)
	(segment
		(start 160.157922 -254.42799)
		(end 160.319466 -254.266446)
		(width 0.14478)
		(layer "In4.Cu")
		(net "M_J_CPU1_SA_CA<5>")
	)
	(segment
		(start 159.606488 -254.602742)
		(end 159.768032 -254.764286)
		(width 0.14478)
		(layer "In4.Cu")
		(net "M_J_CPU1_SA_CA<5>")
	)
	(segment
		(start 181.55285 -253.8603)
		(end 182.402734 -253.010416)
		(width 0.14478)
		(layer "In4.Cu")
		(net "M_J_CPU1_SA_CA<5>")
	)
	(segment
		(start 161.099246 -254.764286)
		(end 161.26079 -254.602742)
		(width 0.14478)
		(layer "In4.Cu")
		(net "M_J_CPU1_SA_CA<5>")
	)
	(segment
		(start 157.952186 -254.42799)
		(end 158.11373 -254.266446)
		(width 0.14478)
		(layer "In4.Cu")
		(net "M_J_CPU1_SA_CA<5>")
	)
	(segment
		(start 157.790642 -254.764286)
		(end 157.952186 -254.602742)
		(width 0.14478)
		(layer "In4.Cu")
		(net "M_J_CPU1_SA_CA<5>")
	)
	(segment
		(start 160.8709 -254.764286)
		(end 161.099246 -254.764286)
		(width 0.14478)
		(layer "In4.Cu")
		(net "M_J_CPU1_SA_CA<5>")
	)
	(segment
		(start 160.319466 -254.266446)
		(end 160.547812 -254.266446)
		(width 0.14478)
		(layer "In4.Cu")
		(net "M_J_CPU1_SA_CA<5>")
	)
	(segment
		(start 135.557768 -254.691896)
		(end 135.56615 -254.68707)
		(width 0.0889)
		(layer "In4.Cu")
		(net "M_J_CPU1_SA_CA<5>")
	)
	(segment
		(start 159.055054 -254.42799)
		(end 159.216598 -254.266446)
		(width 0.14478)
		(layer "In4.Cu")
		(net "M_J_CPU1_SA_CA<5>")
	)
	(segment
		(start 159.768032 -254.764286)
		(end 159.996378 -254.764286)
		(width 0.14478)
		(layer "In4.Cu")
		(net "M_J_CPU1_SA_CA<5>")
	)
	(segment
		(start 144.384268 -254.68707)
		(end 144.39265 -254.691896)
		(width 0.0889)
		(layer "In4.Cu")
		(net "M_J_CPU1_SA_CA<5>")
	)
	(segment
		(start 184.14365 -253.010416)
		(end 185.41873 -251.735336)
		(width 0.14478)
		(layer "In4.Cu")
		(net "M_J_CPU1_SA_CA<5>")
	)
	(segment
		(start 160.157922 -254.602742)
		(end 160.157922 -254.42799)
		(width 0.14478)
		(layer "In4.Cu")
		(net "M_J_CPU1_SA_CA<5>")
	)
	(segment
		(start 158.11373 -254.266446)
		(end 158.342076 -254.266446)
		(width 0.14478)
		(layer "In4.Cu")
		(net "M_J_CPU1_SA_CA<5>")
	)
	(segment
		(start 157.400752 -254.42799)
		(end 157.400752 -254.602742)
		(width 0.14478)
		(layer "In4.Cu")
		(net "M_J_CPU1_SA_CA<5>")
	)
	(segment
		(start 140.257784 -254.691896)
		(end 140.266166 -254.68707)
		(width 0.0889)
		(layer "In4.Cu")
		(net "M_J_CPU1_SA_CA<5>")
	)
	(segment
		(start 132.770626 -254.749046)
		(end 132.792978 -254.665734)
		(width 0.0889)
		(layer "In4.Cu")
		(net "M_J_CPU1_SA_CA<5>")
	)
	(segment
		(start 159.216598 -254.266446)
		(end 159.444944 -254.266446)
		(width 0.14478)
		(layer "In4.Cu")
		(net "M_J_CPU1_SA_CA<5>")
	)
	(segment
		(start 146.489928 -255.241044)
		(end 147.582128 -255.241044)
		(width 0.0889)
		(layer "In4.Cu")
		(net "M_J_CPU1_SA_CA<5>")
	)
	(arc
		(start 141.571726 -254.691896)
		(mid 141.854682 -254.768073)
		(end 142.137638 -254.691896)
		(width 0.0889)
		(layer "In4.Cu")
		(net "M_J_CPU1_SA_CA<5>")
	)
	(arc
		(start 134.991856 -254.691896)
		(mid 135.274812 -254.768073)
		(end 135.557768 -254.691896)
		(width 0.0889)
		(layer "In4.Cu")
		(net "M_J_CPU1_SA_CA<5>")
	)
	(arc
		(start 134.626096 -254.68707)
		(mid 134.809604 -254.641576)
		(end 134.991856 -254.691896)
		(width 0.0889)
		(layer "In4.Cu")
		(net "M_J_CPU1_SA_CA<5>")
	)
	(arc
		(start 133.67766 -254.691896)
		(mid 133.859911 -254.641546)
		(end 134.04342 -254.68707)
		(width 0.0889)
		(layer "In4.Cu")
		(net "M_J_CPU1_SA_CA<5>")
	)
	(arc
		(start 137.437622 -254.691896)
		(mid 137.619873 -254.641546)
		(end 137.803382 -254.68707)
		(width 0.0889)
		(layer "In4.Cu")
		(net "M_J_CPU1_SA_CA<5>")
	)
	(arc
		(start 144.39265 -254.691896)
		(mid 144.672078 -254.768062)
		(end 144.952466 -254.695452)
		(width 0.0889)
		(layer "In4.Cu")
		(net "M_J_CPU1_SA_CA<5>")
	)
	(arc
		(start 141.197838 -254.691896)
		(mid 141.384782 -254.641641)
		(end 141.571726 -254.691896)
		(width 0.0889)
		(layer "In4.Cu")
		(net "M_J_CPU1_SA_CA<5>")
	)
	(arc
		(start 139.691872 -254.691896)
		(mid 139.974828 -254.768073)
		(end 140.257784 -254.691896)
		(width 0.0889)
		(layer "In4.Cu")
		(net "M_J_CPU1_SA_CA<5>")
	)
	(arc
		(start 145.41627 -254.740664)
		(mid 145.453138 -254.755999)
		(end 145.492724 -254.761238)
		(width 0.0889)
		(layer "In4.Cu")
		(net "M_J_CPU1_SA_CA<5>")
	)
	(arc
		(start 138.751818 -254.691896)
		(mid 139.034774 -254.768073)
		(end 139.31773 -254.691896)
		(width 0.0889)
		(layer "In4.Cu")
		(net "M_J_CPU1_SA_CA<5>")
	)
	(arc
		(start 144.976342 -254.681736)
		(mid 145.155571 -254.641583)
		(end 145.332196 -254.691896)
		(width 0.0889)
		(layer "In4.Cu")
		(net "M_J_CPU1_SA_CA<5>")
	)
	(arc
		(start 142.137638 -254.691896)
		(mid 142.319889 -254.641546)
		(end 142.503398 -254.68707)
		(width 0.0889)
		(layer "In4.Cu")
		(net "M_J_CPU1_SA_CA<5>")
	)
	(arc
		(start 133.111748 -254.691896)
		(mid 133.394704 -254.768073)
		(end 133.67766 -254.691896)
		(width 0.0889)
		(layer "In4.Cu")
		(net "M_J_CPU1_SA_CA<5>")
	)
	(arc
		(start 143.462248 -254.697992)
		(mid 143.740934 -254.768212)
		(end 144.018 -254.691896)
		(width 0.0889)
		(layer "In4.Cu")
		(net "M_J_CPU1_SA_CA<5>")
	)
	(arc
		(start 136.497822 -254.691896)
		(mid 136.684766 -254.641641)
		(end 136.87171 -254.691896)
		(width 0.0889)
		(layer "In4.Cu")
		(net "M_J_CPU1_SA_CA<5>")
	)
	(arc
		(start 134.051802 -254.691896)
		(mid 134.334758 -254.768073)
		(end 134.617714 -254.691896)
		(width 0.0889)
		(layer "In4.Cu")
		(net "M_J_CPU1_SA_CA<5>")
	)
	(arc
		(start 137.811764 -254.691896)
		(mid 138.09472 -254.768073)
		(end 138.377676 -254.691896)
		(width 0.0889)
		(layer "In4.Cu")
		(net "M_J_CPU1_SA_CA<5>")
	)
	(arc
		(start 132.792978 -254.665734)
		(mid 132.950488 -254.642536)
		(end 133.103366 -254.68707)
		(width 0.0889)
		(layer "In4.Cu")
		(net "M_J_CPU1_SA_CA<5>")
	)
	(arc
		(start 142.51178 -254.691896)
		(mid 142.794736 -254.768073)
		(end 143.077692 -254.691896)
		(width 0.0889)
		(layer "In4.Cu")
		(net "M_J_CPU1_SA_CA<5>")
	)
	(arc
		(start 136.87171 -254.691896)
		(mid 137.154666 -254.768073)
		(end 137.437622 -254.691896)
		(width 0.0889)
		(layer "In4.Cu")
		(net "M_J_CPU1_SA_CA<5>")
	)
	(arc
		(start 140.266166 -254.68707)
		(mid 140.449674 -254.641576)
		(end 140.631926 -254.691896)
		(width 0.0889)
		(layer "In4.Cu")
		(net "M_J_CPU1_SA_CA<5>")
	)
	(arc
		(start 144.018 -254.691896)
		(mid 144.200505 -254.641419)
		(end 144.384268 -254.68707)
		(width 0.0889)
		(layer "In4.Cu")
		(net "M_J_CPU1_SA_CA<5>")
	)
	(arc
		(start 135.93191 -254.691896)
		(mid 136.214866 -254.768073)
		(end 136.497822 -254.691896)
		(width 0.0889)
		(layer "In4.Cu")
		(net "M_J_CPU1_SA_CA<5>")
	)
	(arc
		(start 135.56615 -254.68707)
		(mid 135.749658 -254.641576)
		(end 135.93191 -254.691896)
		(width 0.0889)
		(layer "In4.Cu")
		(net "M_J_CPU1_SA_CA<5>")
	)
	(arc
		(start 140.631926 -254.691896)
		(mid 140.914882 -254.768073)
		(end 141.197838 -254.691896)
		(width 0.0889)
		(layer "In4.Cu")
		(net "M_J_CPU1_SA_CA<5>")
	)
	(arc
		(start 139.326112 -254.68707)
		(mid 139.50962 -254.641576)
		(end 139.691872 -254.691896)
		(width 0.0889)
		(layer "In4.Cu")
		(net "M_J_CPU1_SA_CA<5>")
	)
	(arc
		(start 143.086074 -254.68707)
		(mid 143.269582 -254.641576)
		(end 143.451834 -254.691896)
		(width 0.0889)
		(layer "In4.Cu")
		(net "M_J_CPU1_SA_CA<5>")
	)
	(arc
		(start 138.377676 -254.691896)
		(mid 138.559927 -254.641546)
		(end 138.743436 -254.68707)
		(width 0.0889)
		(layer "In4.Cu")
		(net "M_J_CPU1_SA_CA<5>")
	)
	(segment
		(start 131.987798 -254.470408)
		(end 132.45465 -254.20447)
		(width 0.10668)
		(layer "F.Cu")
		(net "M_J_CPU1_SA_CA<4>")
	)
	(segment
		(start 151.393906 -253.816866)
		(end 161.958274 -253.816866)
		(width 0.14478)
		(layer "In4.Cu")
		(net "M_J_CPU1_SA_CA<4>")
	)
	(segment
		(start 141.667738 -254.52705)
		(end 141.67612 -254.531876)
		(width 0.0889)
		(layer "In4.Cu")
		(net "M_J_CPU1_SA_CA<4>")
	)
	(segment
		(start 181.402736 -253.010416)
		(end 182.252874 -252.160278)
		(width 0.14478)
		(layer "In4.Cu")
		(net "M_J_CPU1_SA_CA<4>")
	)
	(segment
		(start 147.863052 -254.776224)
		(end 150.434548 -254.776224)
		(width 0.14478)
		(layer "In4.Cu")
		(net "M_J_CPU1_SA_CA<4>")
	)
	(segment
		(start 137.907776 -254.52705)
		(end 137.916158 -254.531876)
		(width 0.0889)
		(layer "In4.Cu")
		(net "M_J_CPU1_SA_CA<4>")
	)
	(segment
		(start 132.45465 -254.20447)
		(end 132.608828 -254.4699)
		(width 0.0889)
		(layer "In4.Cu")
		(net "M_J_CPU1_SA_CA<4>")
	)
	(segment
		(start 186.88685 -251.310394)
		(end 187.245498 -251.310394)
		(width 0.0889)
		(layer "In4.Cu")
		(net "M_J_CPU1_SA_CA<4>")
	)
	(segment
		(start 183.903112 -252.160278)
		(end 184.982866 -251.080524)
		(width 0.14478)
		(layer "In4.Cu")
		(net "M_J_CPU1_SA_CA<4>")
	)
	(segment
		(start 146.586448 -254.877824)
		(end 147.04695 -254.877824)
		(width 0.0889)
		(layer "In4.Cu")
		(net "M_J_CPU1_SA_CA<4>")
	)
	(segment
		(start 136.393428 -254.531876)
		(end 136.40181 -254.52705)
		(width 0.0889)
		(layer "In4.Cu")
		(net "M_J_CPU1_SA_CA<4>")
	)
	(segment
		(start 147.04695 -254.877824)
		(end 147.14855 -254.776224)
		(width 0.0889)
		(layer "In4.Cu")
		(net "M_J_CPU1_SA_CA<4>")
	)
	(segment
		(start 144.477994 -254.520954)
		(end 144.488408 -254.52705)
		(width 0.0889)
		(layer "In4.Cu")
		(net "M_J_CPU1_SA_CA<4>")
	)
	(segment
		(start 145.589244 -254.570484)
		(end 146.279108 -254.570484)
		(width 0.0889)
		(layer "In4.Cu")
		(net "M_J_CPU1_SA_CA<4>")
	)
	(segment
		(start 190.73495 -251.310394)
		(end 191.160146 -250.885198)
		(width 0.14478)
		(layer "In4.Cu")
		(net "M_J_CPU1_SA_CA<4>")
	)
	(segment
		(start 135.453374 -254.531876)
		(end 135.461756 -254.52705)
		(width 0.0889)
		(layer "In4.Cu")
		(net "M_J_CPU1_SA_CA<4>")
	)
	(segment
		(start 147.14855 -254.776224)
		(end 147.863052 -254.776224)
		(width 0.0889)
		(layer "In4.Cu")
		(net "M_J_CPU1_SA_CA<4>")
	)
	(segment
		(start 182.252874 -252.160278)
		(end 183.903112 -252.160278)
		(width 0.14478)
		(layer "In4.Cu")
		(net "M_J_CPU1_SA_CA<4>")
	)
	(segment
		(start 186.8297 -251.253244)
		(end 186.88685 -251.310394)
		(width 0.0889)
		(layer "In4.Cu")
		(net "M_J_CPU1_SA_CA<4>")
	)
	(segment
		(start 162.764724 -253.010416)
		(end 181.402736 -253.010416)
		(width 0.14478)
		(layer "In4.Cu")
		(net "M_J_CPU1_SA_CA<4>")
	)
	(segment
		(start 144.84604 -254.536194)
		(end 144.862296 -254.526796)
		(width 0.0889)
		(layer "In4.Cu")
		(net "M_J_CPU1_SA_CA<4>")
	)
	(segment
		(start 140.15339 -254.531876)
		(end 140.161772 -254.52705)
		(width 0.0889)
		(layer "In4.Cu")
		(net "M_J_CPU1_SA_CA<4>")
	)
	(segment
		(start 161.958274 -253.816866)
		(end 162.764724 -253.010416)
		(width 0.14478)
		(layer "In4.Cu")
		(net "M_J_CPU1_SA_CA<4>")
	)
	(segment
		(start 186.650376 -251.080524)
		(end 186.823096 -251.253244)
		(width 0.14478)
		(layer "In4.Cu")
		(net "M_J_CPU1_SA_CA<4>")
	)
	(segment
		(start 133.20776 -254.52705)
		(end 133.216142 -254.531876)
		(width 0.0889)
		(layer "In4.Cu")
		(net "M_J_CPU1_SA_CA<4>")
	)
	(segment
		(start 136.967722 -254.52705)
		(end 136.976104 -254.531876)
		(width 0.0889)
		(layer "In4.Cu")
		(net "M_J_CPU1_SA_CA<4>")
	)
	(segment
		(start 150.434548 -254.776224)
		(end 151.393906 -253.816866)
		(width 0.14478)
		(layer "In4.Cu")
		(net "M_J_CPU1_SA_CA<4>")
	)
	(segment
		(start 146.279108 -254.570484)
		(end 146.586448 -254.877824)
		(width 0.0889)
		(layer "In4.Cu")
		(net "M_J_CPU1_SA_CA<4>")
	)
	(segment
		(start 132.608828 -254.4699)
		(end 132.705094 -254.4953)
		(width 0.0889)
		(layer "In4.Cu")
		(net "M_J_CPU1_SA_CA<4>")
	)
	(segment
		(start 184.982866 -251.080524)
		(end 186.650376 -251.080524)
		(width 0.14478)
		(layer "In4.Cu")
		(net "M_J_CPU1_SA_CA<4>")
	)
	(segment
		(start 187.245498 -251.310394)
		(end 190.73495 -251.310394)
		(width 0.14478)
		(layer "In4.Cu")
		(net "M_J_CPU1_SA_CA<4>")
	)
	(segment
		(start 144.862296 -254.526796)
		(end 144.878044 -254.517652)
		(width 0.0889)
		(layer "In4.Cu")
		(net "M_J_CPU1_SA_CA<4>")
	)
	(segment
		(start 141.093444 -254.531876)
		(end 141.101826 -254.52705)
		(width 0.0889)
		(layer "In4.Cu")
		(net "M_J_CPU1_SA_CA<4>")
	)
	(segment
		(start 143.547592 -254.52705)
		(end 143.555974 -254.531876)
		(width 0.0889)
		(layer "In4.Cu")
		(net "M_J_CPU1_SA_CA<4>")
	)
	(segment
		(start 186.823096 -251.253244)
		(end 186.8297 -251.253244)
		(width 0.0889)
		(layer "In4.Cu")
		(net "M_J_CPU1_SA_CA<4>")
	)
	(arc
		(start 141.67612 -254.531876)
		(mid 141.859628 -254.57737)
		(end 142.04188 -254.52705)
		(width 0.0889)
		(layer "In4.Cu")
		(net "M_J_CPU1_SA_CA<4>")
	)
	(arc
		(start 139.78763 -254.52705)
		(mid 139.969881 -254.5774)
		(end 140.15339 -254.531876)
		(width 0.0889)
		(layer "In4.Cu")
		(net "M_J_CPU1_SA_CA<4>")
	)
	(arc
		(start 142.607792 -254.52705)
		(mid 142.794736 -254.577305)
		(end 142.98168 -254.52705)
		(width 0.0889)
		(layer "In4.Cu")
		(net "M_J_CPU1_SA_CA<4>")
	)
	(arc
		(start 138.281918 -254.52705)
		(mid 138.564874 -254.450873)
		(end 138.84783 -254.52705)
		(width 0.0889)
		(layer "In4.Cu")
		(net "M_J_CPU1_SA_CA<4>")
	)
	(arc
		(start 135.461756 -254.52705)
		(mid 135.744712 -254.450873)
		(end 136.027668 -254.52705)
		(width 0.0889)
		(layer "In4.Cu")
		(net "M_J_CPU1_SA_CA<4>")
	)
	(arc
		(start 139.221718 -254.52705)
		(mid 139.504674 -254.450873)
		(end 139.78763 -254.52705)
		(width 0.0889)
		(layer "In4.Cu")
		(net "M_J_CPU1_SA_CA<4>")
	)
	(arc
		(start 144.878044 -254.517652)
		(mid 145.154353 -254.450676)
		(end 145.428208 -254.52705)
		(width 0.0889)
		(layer "In4.Cu")
		(net "M_J_CPU1_SA_CA<4>")
	)
	(arc
		(start 135.087614 -254.52705)
		(mid 135.269865 -254.5774)
		(end 135.453374 -254.531876)
		(width 0.0889)
		(layer "In4.Cu")
		(net "M_J_CPU1_SA_CA<4>")
	)
	(arc
		(start 134.147814 -254.52705)
		(mid 134.334758 -254.577305)
		(end 134.521702 -254.52705)
		(width 0.0889)
		(layer "In4.Cu")
		(net "M_J_CPU1_SA_CA<4>")
	)
	(arc
		(start 143.555974 -254.531876)
		(mid 143.739736 -254.577492)
		(end 143.922242 -254.52705)
		(width 0.0889)
		(layer "In4.Cu")
		(net "M_J_CPU1_SA_CA<4>")
	)
	(arc
		(start 136.027668 -254.52705)
		(mid 136.209919 -254.5774)
		(end 136.393428 -254.531876)
		(width 0.0889)
		(layer "In4.Cu")
		(net "M_J_CPU1_SA_CA<4>")
	)
	(arc
		(start 137.916158 -254.531876)
		(mid 138.099666 -254.57737)
		(end 138.281918 -254.52705)
		(width 0.0889)
		(layer "In4.Cu")
		(net "M_J_CPU1_SA_CA<4>")
	)
	(arc
		(start 143.922242 -254.52705)
		(mid 144.199309 -254.450779)
		(end 144.477994 -254.520954)
		(width 0.0889)
		(layer "In4.Cu")
		(net "M_J_CPU1_SA_CA<4>")
	)
	(arc
		(start 140.727684 -254.52705)
		(mid 140.909935 -254.5774)
		(end 141.093444 -254.531876)
		(width 0.0889)
		(layer "In4.Cu")
		(net "M_J_CPU1_SA_CA<4>")
	)
	(arc
		(start 133.216142 -254.531876)
		(mid 133.39965 -254.57737)
		(end 133.581902 -254.52705)
		(width 0.0889)
		(layer "In4.Cu")
		(net "M_J_CPU1_SA_CA<4>")
	)
	(arc
		(start 142.04188 -254.52705)
		(mid 142.324836 -254.450873)
		(end 142.607792 -254.52705)
		(width 0.0889)
		(layer "In4.Cu")
		(net "M_J_CPU1_SA_CA<4>")
	)
	(arc
		(start 140.161772 -254.52705)
		(mid 140.444728 -254.450873)
		(end 140.727684 -254.52705)
		(width 0.0889)
		(layer "In4.Cu")
		(net "M_J_CPU1_SA_CA<4>")
	)
	(arc
		(start 141.101826 -254.52705)
		(mid 141.384782 -254.450873)
		(end 141.667738 -254.52705)
		(width 0.0889)
		(layer "In4.Cu")
		(net "M_J_CPU1_SA_CA<4>")
	)
	(arc
		(start 145.428208 -254.52705)
		(mid 145.505854 -254.559405)
		(end 145.589244 -254.570484)
		(width 0.0889)
		(layer "In4.Cu")
		(net "M_J_CPU1_SA_CA<4>")
	)
	(arc
		(start 138.84783 -254.52705)
		(mid 139.034774 -254.577305)
		(end 139.221718 -254.52705)
		(width 0.0889)
		(layer "In4.Cu")
		(net "M_J_CPU1_SA_CA<4>")
	)
	(arc
		(start 142.98168 -254.52705)
		(mid 143.264636 -254.450873)
		(end 143.547592 -254.52705)
		(width 0.0889)
		(layer "In4.Cu")
		(net "M_J_CPU1_SA_CA<4>")
	)
	(arc
		(start 133.581902 -254.52705)
		(mid 133.864858 -254.450873)
		(end 134.147814 -254.52705)
		(width 0.0889)
		(layer "In4.Cu")
		(net "M_J_CPU1_SA_CA<4>")
	)
	(arc
		(start 132.705094 -254.4953)
		(mid 132.960159 -254.451949)
		(end 133.20776 -254.52705)
		(width 0.0889)
		(layer "In4.Cu")
		(net "M_J_CPU1_SA_CA<4>")
	)
	(arc
		(start 137.341864 -254.52705)
		(mid 137.62482 -254.450873)
		(end 137.907776 -254.52705)
		(width 0.0889)
		(layer "In4.Cu")
		(net "M_J_CPU1_SA_CA<4>")
	)
	(arc
		(start 144.488408 -254.52705)
		(mid 144.666058 -254.57731)
		(end 144.84604 -254.536194)
		(width 0.0889)
		(layer "In4.Cu")
		(net "M_J_CPU1_SA_CA<4>")
	)
	(arc
		(start 134.521702 -254.52705)
		(mid 134.804658 -254.450873)
		(end 135.087614 -254.52705)
		(width 0.0889)
		(layer "In4.Cu")
		(net "M_J_CPU1_SA_CA<4>")
	)
	(arc
		(start 136.40181 -254.52705)
		(mid 136.684766 -254.450873)
		(end 136.967722 -254.52705)
		(width 0.0889)
		(layer "In4.Cu")
		(net "M_J_CPU1_SA_CA<4>")
	)
	(arc
		(start 136.976104 -254.531876)
		(mid 137.159612 -254.57737)
		(end 137.341864 -254.52705)
		(width 0.0889)
		(layer "In4.Cu")
		(net "M_J_CPU1_SA_CA<4>")
	)
	(segment
		(start 131.047998 -254.470408)
		(end 131.51485 -254.20447)
		(width 0.10668)
		(layer "F.Cu")
		(net "M_J_CPU1_SA_CA<3>")
	)
	(segment
		(start 147.758912 -254.316484)
		(end 150.228808 -254.316484)
		(width 0.14478)
		(layer "In4.Cu")
		(net "M_J_CPU1_SA_CA<3>")
	)
	(segment
		(start 147.269708 -254.316484)
		(end 147.758912 -254.316484)
		(width 0.0889)
		(layer "In4.Cu")
		(net "M_J_CPU1_SA_CA<3>")
	)
	(segment
		(start 168.184576 -252.460506)
		(end 168.484804 -252.160278)
		(width 0.14478)
		(layer "In4.Cu")
		(net "M_J_CPU1_SA_CA<3>")
	)
	(segment
		(start 131.693412 -253.877064)
		(end 131.701794 -253.88189)
		(width 0.0889)
		(layer "In4.Cu")
		(net "M_J_CPU1_SA_CA<3>")
	)
	(segment
		(start 144.47393 -253.890526)
		(end 144.488662 -253.88189)
		(width 0.0889)
		(layer "In4.Cu")
		(net "M_J_CPU1_SA_CA<3>")
	)
	(segment
		(start 144.84858 -253.87427)
		(end 144.862296 -253.882144)
		(width 0.0889)
		(layer "In4.Cu")
		(net "M_J_CPU1_SA_CA<3>")
	)
	(segment
		(start 168.73601 -252.160278)
		(end 169.036238 -252.460506)
		(width 0.14478)
		(layer "In4.Cu")
		(net "M_J_CPU1_SA_CA<3>")
	)
	(segment
		(start 169.287444 -252.460506)
		(end 169.587672 -252.160278)
		(width 0.14478)
		(layer "In4.Cu")
		(net "M_J_CPU1_SA_CA<3>")
	)
	(segment
		(start 165.97884 -252.460506)
		(end 166.279068 -252.160278)
		(width 0.14478)
		(layer "In4.Cu")
		(net "M_J_CPU1_SA_CA<3>")
	)
	(segment
		(start 136.393428 -253.877064)
		(end 136.40181 -253.88189)
		(width 0.0889)
		(layer "In4.Cu")
		(net "M_J_CPU1_SA_CA<3>")
	)
	(segment
		(start 147.053808 -254.100584)
		(end 147.269708 -254.316484)
		(width 0.0889)
		(layer "In4.Cu")
		(net "M_J_CPU1_SA_CA<3>")
	)
	(segment
		(start 144.862296 -253.882144)
		(end 144.878044 -253.891288)
		(width 0.0889)
		(layer "In4.Cu")
		(net "M_J_CPU1_SA_CA<3>")
	)
	(segment
		(start 131.51485 -254.20447)
		(end 131.360672 -253.93904)
		(width 0.0889)
		(layer "In4.Cu")
		(net "M_J_CPU1_SA_CA<3>")
	)
	(segment
		(start 186.635136 -250.460256)
		(end 187.060078 -250.035314)
		(width 0.14478)
		(layer "In4.Cu")
		(net "M_J_CPU1_SA_CA<3>")
	)
	(segment
		(start 169.036238 -252.460506)
		(end 169.287444 -252.460506)
		(width 0.14478)
		(layer "In4.Cu")
		(net "M_J_CPU1_SA_CA<3>")
	)
	(segment
		(start 141.093444 -253.877064)
		(end 141.101826 -253.88189)
		(width 0.0889)
		(layer "In4.Cu")
		(net "M_J_CPU1_SA_CA<3>")
	)
	(segment
		(start 166.830502 -252.460506)
		(end 167.081708 -252.460506)
		(width 0.14478)
		(layer "In4.Cu")
		(net "M_J_CPU1_SA_CA<3>")
	)
	(segment
		(start 140.15339 -253.877064)
		(end 140.161772 -253.88189)
		(width 0.0889)
		(layer "In4.Cu")
		(net "M_J_CPU1_SA_CA<3>")
	)
	(segment
		(start 167.93337 -252.460506)
		(end 168.184576 -252.460506)
		(width 0.14478)
		(layer "In4.Cu")
		(net "M_J_CPU1_SA_CA<3>")
	)
	(segment
		(start 166.530274 -252.160278)
		(end 166.830502 -252.460506)
		(width 0.14478)
		(layer "In4.Cu")
		(net "M_J_CPU1_SA_CA<3>")
	)
	(segment
		(start 136.967722 -253.88189)
		(end 136.976104 -253.877064)
		(width 0.0889)
		(layer "In4.Cu")
		(net "M_J_CPU1_SA_CA<3>")
	)
	(segment
		(start 167.381936 -252.160278)
		(end 167.633142 -252.160278)
		(width 0.14478)
		(layer "In4.Cu")
		(net "M_J_CPU1_SA_CA<3>")
	)
	(segment
		(start 161.771838 -253.367286)
		(end 162.978846 -252.160278)
		(width 0.14478)
		(layer "In4.Cu")
		(net "M_J_CPU1_SA_CA<3>")
	)
	(segment
		(start 183.05272 -250.460256)
		(end 186.635136 -250.460256)
		(width 0.14478)
		(layer "In4.Cu")
		(net "M_J_CPU1_SA_CA<3>")
	)
	(segment
		(start 146.017996 -254.100584)
		(end 147.053808 -254.100584)
		(width 0.0889)
		(layer "In4.Cu")
		(net "M_J_CPU1_SA_CA<3>")
	)
	(segment
		(start 133.20776 -253.88189)
		(end 133.216142 -253.877064)
		(width 0.0889)
		(layer "In4.Cu")
		(net "M_J_CPU1_SA_CA<3>")
	)
	(segment
		(start 167.081708 -252.460506)
		(end 167.381936 -252.160278)
		(width 0.14478)
		(layer "In4.Cu")
		(net "M_J_CPU1_SA_CA<3>")
	)
	(segment
		(start 165.727634 -252.460506)
		(end 165.97884 -252.460506)
		(width 0.14478)
		(layer "In4.Cu")
		(net "M_J_CPU1_SA_CA<3>")
	)
	(segment
		(start 167.633142 -252.160278)
		(end 167.93337 -252.460506)
		(width 0.14478)
		(layer "In4.Cu")
		(net "M_J_CPU1_SA_CA<3>")
	)
	(segment
		(start 135.453374 -253.877064)
		(end 135.461756 -253.88189)
		(width 0.0889)
		(layer "In4.Cu")
		(net "M_J_CPU1_SA_CA<3>")
	)
	(segment
		(start 137.907776 -253.88189)
		(end 137.916158 -253.877064)
		(width 0.0889)
		(layer "In4.Cu")
		(net "M_J_CPU1_SA_CA<3>")
	)
	(segment
		(start 181.352698 -252.160278)
		(end 183.05272 -250.460256)
		(width 0.14478)
		(layer "In4.Cu")
		(net "M_J_CPU1_SA_CA<3>")
	)
	(segment
		(start 169.587672 -252.160278)
		(end 181.352698 -252.160278)
		(width 0.14478)
		(layer "In4.Cu")
		(net "M_J_CPU1_SA_CA<3>")
	)
	(segment
		(start 132.267706 -253.88189)
		(end 132.276088 -253.877064)
		(width 0.0889)
		(layer "In4.Cu")
		(net "M_J_CPU1_SA_CA<3>")
	)
	(segment
		(start 131.360672 -253.93904)
		(end 131.383024 -253.855728)
		(width 0.0889)
		(layer "In4.Cu")
		(net "M_J_CPU1_SA_CA<3>")
	)
	(segment
		(start 162.978846 -252.160278)
		(end 165.427406 -252.160278)
		(width 0.14478)
		(layer "In4.Cu")
		(net "M_J_CPU1_SA_CA<3>")
	)
	(segment
		(start 150.228808 -254.316484)
		(end 151.178006 -253.367286)
		(width 0.14478)
		(layer "In4.Cu")
		(net "M_J_CPU1_SA_CA<3>")
	)
	(segment
		(start 143.547592 -253.88189)
		(end 143.555974 -253.877064)
		(width 0.0889)
		(layer "In4.Cu")
		(net "M_J_CPU1_SA_CA<3>")
	)
	(segment
		(start 151.178006 -253.367286)
		(end 161.771838 -253.367286)
		(width 0.14478)
		(layer "In4.Cu")
		(net "M_J_CPU1_SA_CA<3>")
	)
	(segment
		(start 165.427406 -252.160278)
		(end 165.727634 -252.460506)
		(width 0.14478)
		(layer "In4.Cu")
		(net "M_J_CPU1_SA_CA<3>")
	)
	(segment
		(start 145.794476 -253.877064)
		(end 146.017996 -254.100584)
		(width 0.0889)
		(layer "In4.Cu")
		(net "M_J_CPU1_SA_CA<3>")
	)
	(segment
		(start 141.667738 -253.88189)
		(end 141.67612 -253.877064)
		(width 0.0889)
		(layer "In4.Cu")
		(net "M_J_CPU1_SA_CA<3>")
	)
	(segment
		(start 166.279068 -252.160278)
		(end 166.530274 -252.160278)
		(width 0.14478)
		(layer "In4.Cu")
		(net "M_J_CPU1_SA_CA<3>")
	)
	(segment
		(start 168.484804 -252.160278)
		(end 168.73601 -252.160278)
		(width 0.14478)
		(layer "In4.Cu")
		(net "M_J_CPU1_SA_CA<3>")
	)
	(arc
		(start 143.555974 -253.877064)
		(mid 143.739736 -253.831448)
		(end 143.922242 -253.88189)
		(width 0.0889)
		(layer "In4.Cu")
		(net "M_J_CPU1_SA_CA<3>")
	)
	(arc
		(start 142.607792 -253.88189)
		(mid 142.794736 -253.831635)
		(end 142.98168 -253.88189)
		(width 0.0889)
		(layer "In4.Cu")
		(net "M_J_CPU1_SA_CA<3>")
	)
	(arc
		(start 131.383024 -253.855728)
		(mid 131.540534 -253.83253)
		(end 131.693412 -253.877064)
		(width 0.0889)
		(layer "In4.Cu")
		(net "M_J_CPU1_SA_CA<3>")
	)
	(arc
		(start 141.101826 -253.88189)
		(mid 141.384782 -253.958067)
		(end 141.667738 -253.88189)
		(width 0.0889)
		(layer "In4.Cu")
		(net "M_J_CPU1_SA_CA<3>")
	)
	(arc
		(start 136.40181 -253.88189)
		(mid 136.684766 -253.958067)
		(end 136.967722 -253.88189)
		(width 0.0889)
		(layer "In4.Cu")
		(net "M_J_CPU1_SA_CA<3>")
	)
	(arc
		(start 142.98168 -253.88189)
		(mid 143.264636 -253.958067)
		(end 143.547592 -253.88189)
		(width 0.0889)
		(layer "In4.Cu")
		(net "M_J_CPU1_SA_CA<3>")
	)
	(arc
		(start 138.281918 -253.88189)
		(mid 138.564874 -253.958067)
		(end 138.84783 -253.88189)
		(width 0.0889)
		(layer "In4.Cu")
		(net "M_J_CPU1_SA_CA<3>")
	)
	(arc
		(start 134.521702 -253.88189)
		(mid 134.804658 -253.958067)
		(end 135.087614 -253.88189)
		(width 0.0889)
		(layer "In4.Cu")
		(net "M_J_CPU1_SA_CA<3>")
	)
	(arc
		(start 135.461756 -253.88189)
		(mid 135.744712 -253.958067)
		(end 136.027668 -253.88189)
		(width 0.0889)
		(layer "In4.Cu")
		(net "M_J_CPU1_SA_CA<3>")
	)
	(arc
		(start 134.147814 -253.88189)
		(mid 134.334758 -253.831635)
		(end 134.521702 -253.88189)
		(width 0.0889)
		(layer "In4.Cu")
		(net "M_J_CPU1_SA_CA<3>")
	)
	(arc
		(start 135.087614 -253.88189)
		(mid 135.269865 -253.83154)
		(end 135.453374 -253.877064)
		(width 0.0889)
		(layer "In4.Cu")
		(net "M_J_CPU1_SA_CA<3>")
	)
	(arc
		(start 138.84783 -253.88189)
		(mid 139.034774 -253.831635)
		(end 139.221718 -253.88189)
		(width 0.0889)
		(layer "In4.Cu")
		(net "M_J_CPU1_SA_CA<3>")
	)
	(arc
		(start 140.161772 -253.88189)
		(mid 140.444728 -253.958067)
		(end 140.727684 -253.88189)
		(width 0.0889)
		(layer "In4.Cu")
		(net "M_J_CPU1_SA_CA<3>")
	)
	(arc
		(start 133.216142 -253.877064)
		(mid 133.39965 -253.83157)
		(end 133.581902 -253.88189)
		(width 0.0889)
		(layer "In4.Cu")
		(net "M_J_CPU1_SA_CA<3>")
	)
	(arc
		(start 140.727684 -253.88189)
		(mid 140.909935 -253.83154)
		(end 141.093444 -253.877064)
		(width 0.0889)
		(layer "In4.Cu")
		(net "M_J_CPU1_SA_CA<3>")
	)
	(arc
		(start 137.341864 -253.88189)
		(mid 137.62482 -253.958067)
		(end 137.907776 -253.88189)
		(width 0.0889)
		(layer "In4.Cu")
		(net "M_J_CPU1_SA_CA<3>")
	)
	(arc
		(start 133.581902 -253.88189)
		(mid 133.864858 -253.958067)
		(end 134.147814 -253.88189)
		(width 0.0889)
		(layer "In4.Cu")
		(net "M_J_CPU1_SA_CA<3>")
	)
	(arc
		(start 132.641848 -253.88189)
		(mid 132.924804 -253.958067)
		(end 133.20776 -253.88189)
		(width 0.0889)
		(layer "In4.Cu")
		(net "M_J_CPU1_SA_CA<3>")
	)
	(arc
		(start 145.428208 -253.88189)
		(mid 145.610713 -253.831413)
		(end 145.794476 -253.877064)
		(width 0.0889)
		(layer "In4.Cu")
		(net "M_J_CPU1_SA_CA<3>")
	)
	(arc
		(start 139.221718 -253.88189)
		(mid 139.504674 -253.958067)
		(end 139.78763 -253.88189)
		(width 0.0889)
		(layer "In4.Cu")
		(net "M_J_CPU1_SA_CA<3>")
	)
	(arc
		(start 131.701794 -253.88189)
		(mid 131.98475 -253.958067)
		(end 132.267706 -253.88189)
		(width 0.0889)
		(layer "In4.Cu")
		(net "M_J_CPU1_SA_CA<3>")
	)
	(arc
		(start 144.488662 -253.88189)
		(mid 144.667649 -253.83172)
		(end 144.84858 -253.87427)
		(width 0.0889)
		(layer "In4.Cu")
		(net "M_J_CPU1_SA_CA<3>")
	)
	(arc
		(start 137.916158 -253.877064)
		(mid 138.099666 -253.83157)
		(end 138.281918 -253.88189)
		(width 0.0889)
		(layer "In4.Cu")
		(net "M_J_CPU1_SA_CA<3>")
	)
	(arc
		(start 141.67612 -253.877064)
		(mid 141.859628 -253.83157)
		(end 142.04188 -253.88189)
		(width 0.0889)
		(layer "In4.Cu")
		(net "M_J_CPU1_SA_CA<3>")
	)
	(arc
		(start 136.027668 -253.88189)
		(mid 136.209919 -253.83154)
		(end 136.393428 -253.877064)
		(width 0.0889)
		(layer "In4.Cu")
		(net "M_J_CPU1_SA_CA<3>")
	)
	(arc
		(start 139.78763 -253.88189)
		(mid 139.969881 -253.83154)
		(end 140.15339 -253.877064)
		(width 0.0889)
		(layer "In4.Cu")
		(net "M_J_CPU1_SA_CA<3>")
	)
	(arc
		(start 142.04188 -253.88189)
		(mid 142.324836 -253.958067)
		(end 142.607792 -253.88189)
		(width 0.0889)
		(layer "In4.Cu")
		(net "M_J_CPU1_SA_CA<3>")
	)
	(arc
		(start 144.878044 -253.891288)
		(mid 145.154353 -253.958264)
		(end 145.428208 -253.88189)
		(width 0.0889)
		(layer "In4.Cu")
		(net "M_J_CPU1_SA_CA<3>")
	)
	(arc
		(start 136.976104 -253.877064)
		(mid 137.159612 -253.83157)
		(end 137.341864 -253.88189)
		(width 0.0889)
		(layer "In4.Cu")
		(net "M_J_CPU1_SA_CA<3>")
	)
	(arc
		(start 132.276088 -253.877064)
		(mid 132.459596 -253.83157)
		(end 132.641848 -253.88189)
		(width 0.0889)
		(layer "In4.Cu")
		(net "M_J_CPU1_SA_CA<3>")
	)
	(arc
		(start 143.922242 -253.88189)
		(mid 144.196948 -253.958254)
		(end 144.47393 -253.890526)
		(width 0.0889)
		(layer "In4.Cu")
		(net "M_J_CPU1_SA_CA<3>")
	)
	(segment
		(start 130.577844 -253.660402)
		(end 131.044696 -253.394464)
		(width 0.10668)
		(layer "F.Cu")
		(net "M_J_CPU1_SA_CA<2>")
	)
	(segment
		(start 137.803382 -253.72187)
		(end 137.811764 -253.717044)
		(width 0.0889)
		(layer "In4.Cu")
		(net "M_J_CPU1_SA_CA<2>")
	)
	(segment
		(start 131.198874 -253.659894)
		(end 131.29514 -253.685294)
		(width 0.0889)
		(layer "In4.Cu")
		(net "M_J_CPU1_SA_CA<2>")
	)
	(segment
		(start 183.050434 -249.610372)
		(end 190.735204 -249.610372)
		(width 0.14478)
		(layer "In4.Cu")
		(net "M_J_CPU1_SA_CA<2>")
	)
	(segment
		(start 131.044696 -253.394464)
		(end 131.198874 -253.659894)
		(width 0.0889)
		(layer "In4.Cu")
		(net "M_J_CPU1_SA_CA<2>")
	)
	(segment
		(start 139.31773 -253.717044)
		(end 139.326112 -253.72187)
		(width 0.0889)
		(layer "In4.Cu")
		(net "M_J_CPU1_SA_CA<2>")
	)
	(segment
		(start 147.213828 -253.785624)
		(end 147.287488 -253.859284)
		(width 0.0889)
		(layer "In4.Cu")
		(net "M_J_CPU1_SA_CA<2>")
	)
	(segment
		(start 140.257784 -253.717044)
		(end 140.266166 -253.72187)
		(width 0.0889)
		(layer "In4.Cu")
		(net "M_J_CPU1_SA_CA<2>")
	)
	(segment
		(start 143.451834 -253.717044)
		(end 143.466566 -253.708408)
		(width 0.0889)
		(layer "In4.Cu")
		(net "M_J_CPU1_SA_CA<2>")
	)
	(segment
		(start 150.012908 -253.859284)
		(end 150.954486 -252.917706)
		(width 0.14478)
		(layer "In4.Cu")
		(net "M_J_CPU1_SA_CA<2>")
	)
	(segment
		(start 146.025616 -253.791466)
		(end 146.031458 -253.785624)
		(width 0.0889)
		(layer "In4.Cu")
		(net "M_J_CPU1_SA_CA<2>")
	)
	(segment
		(start 144.380966 -253.723902)
		(end 144.39265 -253.717044)
		(width 0.0889)
		(layer "In4.Cu")
		(net "M_J_CPU1_SA_CA<2>")
	)
	(segment
		(start 181.350412 -251.310394)
		(end 183.050434 -249.610372)
		(width 0.14478)
		(layer "In4.Cu")
		(net "M_J_CPU1_SA_CA<2>")
	)
	(segment
		(start 134.04342 -253.72187)
		(end 134.051802 -253.717044)
		(width 0.0889)
		(layer "In4.Cu")
		(net "M_J_CPU1_SA_CA<2>")
	)
	(segment
		(start 144.958054 -253.71679)
		(end 144.976342 -253.727204)
		(width 0.0889)
		(layer "In4.Cu")
		(net "M_J_CPU1_SA_CA<2>")
	)
	(segment
		(start 145.883884 -253.708408)
		(end 146.025616 -253.791466)
		(width 0.0889)
		(layer "In4.Cu")
		(net "M_J_CPU1_SA_CA<2>")
	)
	(segment
		(start 133.103366 -253.72187)
		(end 133.111748 -253.717044)
		(width 0.0889)
		(layer "In4.Cu")
		(net "M_J_CPU1_SA_CA<2>")
	)
	(segment
		(start 147.724114 -253.859284)
		(end 150.012908 -253.859284)
		(width 0.14478)
		(layer "In4.Cu")
		(net "M_J_CPU1_SA_CA<2>")
	)
	(segment
		(start 134.617714 -253.717044)
		(end 134.626096 -253.72187)
		(width 0.0889)
		(layer "In4.Cu")
		(net "M_J_CPU1_SA_CA<2>")
	)
	(segment
		(start 150.954486 -252.917706)
		(end 161.585402 -252.917706)
		(width 0.14478)
		(layer "In4.Cu")
		(net "M_J_CPU1_SA_CA<2>")
	)
	(segment
		(start 144.952466 -253.713488)
		(end 144.958054 -253.71679)
		(width 0.0889)
		(layer "In4.Cu")
		(net "M_J_CPU1_SA_CA<2>")
	)
	(segment
		(start 143.077692 -253.717044)
		(end 143.086074 -253.72187)
		(width 0.0889)
		(layer "In4.Cu")
		(net "M_J_CPU1_SA_CA<2>")
	)
	(segment
		(start 163.192714 -251.310394)
		(end 181.350412 -251.310394)
		(width 0.14478)
		(layer "In4.Cu")
		(net "M_J_CPU1_SA_CA<2>")
	)
	(segment
		(start 161.585402 -252.917706)
		(end 163.192714 -251.310394)
		(width 0.14478)
		(layer "In4.Cu")
		(net "M_J_CPU1_SA_CA<2>")
	)
	(segment
		(start 190.735204 -249.610372)
		(end 191.160146 -249.18543)
		(width 0.14478)
		(layer "In4.Cu")
		(net "M_J_CPU1_SA_CA<2>")
	)
	(segment
		(start 142.503398 -253.72187)
		(end 142.51178 -253.717044)
		(width 0.0889)
		(layer "In4.Cu")
		(net "M_J_CPU1_SA_CA<2>")
	)
	(segment
		(start 146.031458 -253.785624)
		(end 147.213828 -253.785624)
		(width 0.0889)
		(layer "In4.Cu")
		(net "M_J_CPU1_SA_CA<2>")
	)
	(segment
		(start 138.743436 -253.72187)
		(end 138.751818 -253.717044)
		(width 0.0889)
		(layer "In4.Cu")
		(net "M_J_CPU1_SA_CA<2>")
	)
	(segment
		(start 147.287488 -253.859284)
		(end 147.724114 -253.859284)
		(width 0.0889)
		(layer "In4.Cu")
		(net "M_J_CPU1_SA_CA<2>")
	)
	(segment
		(start 135.557768 -253.717044)
		(end 135.56615 -253.72187)
		(width 0.0889)
		(layer "In4.Cu")
		(net "M_J_CPU1_SA_CA<2>")
	)
	(arc
		(start 133.111748 -253.717044)
		(mid 133.394704 -253.640867)
		(end 133.67766 -253.717044)
		(width 0.0889)
		(layer "In4.Cu")
		(net "M_J_CPU1_SA_CA<2>")
	)
	(arc
		(start 144.976342 -253.727204)
		(mid 145.155571 -253.767357)
		(end 145.332196 -253.717044)
		(width 0.0889)
		(layer "In4.Cu")
		(net "M_J_CPU1_SA_CA<2>")
	)
	(arc
		(start 134.991856 -253.717044)
		(mid 135.274812 -253.640867)
		(end 135.557768 -253.717044)
		(width 0.0889)
		(layer "In4.Cu")
		(net "M_J_CPU1_SA_CA<2>")
	)
	(arc
		(start 132.737606 -253.717044)
		(mid 132.919857 -253.767394)
		(end 133.103366 -253.72187)
		(width 0.0889)
		(layer "In4.Cu")
		(net "M_J_CPU1_SA_CA<2>")
	)
	(arc
		(start 134.626096 -253.72187)
		(mid 134.809604 -253.767364)
		(end 134.991856 -253.717044)
		(width 0.0889)
		(layer "In4.Cu")
		(net "M_J_CPU1_SA_CA<2>")
	)
	(arc
		(start 140.266166 -253.72187)
		(mid 140.449674 -253.767364)
		(end 140.631926 -253.717044)
		(width 0.0889)
		(layer "In4.Cu")
		(net "M_J_CPU1_SA_CA<2>")
	)
	(arc
		(start 139.691872 -253.717044)
		(mid 139.974828 -253.640867)
		(end 140.257784 -253.717044)
		(width 0.0889)
		(layer "In4.Cu")
		(net "M_J_CPU1_SA_CA<2>")
	)
	(arc
		(start 143.466566 -253.708408)
		(mid 143.743549 -253.640604)
		(end 144.018254 -253.717044)
		(width 0.0889)
		(layer "In4.Cu")
		(net "M_J_CPU1_SA_CA<2>")
	)
	(arc
		(start 138.377676 -253.717044)
		(mid 138.559927 -253.767394)
		(end 138.743436 -253.72187)
		(width 0.0889)
		(layer "In4.Cu")
		(net "M_J_CPU1_SA_CA<2>")
	)
	(arc
		(start 137.437622 -253.717044)
		(mid 137.619873 -253.767394)
		(end 137.803382 -253.72187)
		(width 0.0889)
		(layer "In4.Cu")
		(net "M_J_CPU1_SA_CA<2>")
	)
	(arc
		(start 136.87171 -253.717044)
		(mid 137.154666 -253.640867)
		(end 137.437622 -253.717044)
		(width 0.0889)
		(layer "In4.Cu")
		(net "M_J_CPU1_SA_CA<2>")
	)
	(arc
		(start 137.811764 -253.717044)
		(mid 138.09472 -253.640867)
		(end 138.377676 -253.717044)
		(width 0.0889)
		(layer "In4.Cu")
		(net "M_J_CPU1_SA_CA<2>")
	)
	(arc
		(start 131.797806 -253.717044)
		(mid 131.98475 -253.767299)
		(end 132.171694 -253.717044)
		(width 0.0889)
		(layer "In4.Cu")
		(net "M_J_CPU1_SA_CA<2>")
	)
	(arc
		(start 132.171694 -253.717044)
		(mid 132.45465 -253.640867)
		(end 132.737606 -253.717044)
		(width 0.0889)
		(layer "In4.Cu")
		(net "M_J_CPU1_SA_CA<2>")
	)
	(arc
		(start 141.197838 -253.717044)
		(mid 141.384782 -253.767299)
		(end 141.571726 -253.717044)
		(width 0.0889)
		(layer "In4.Cu")
		(net "M_J_CPU1_SA_CA<2>")
	)
	(arc
		(start 145.332196 -253.717044)
		(mid 145.606902 -253.64068)
		(end 145.883884 -253.708408)
		(width 0.0889)
		(layer "In4.Cu")
		(net "M_J_CPU1_SA_CA<2>")
	)
	(arc
		(start 139.326112 -253.72187)
		(mid 139.50962 -253.767364)
		(end 139.691872 -253.717044)
		(width 0.0889)
		(layer "In4.Cu")
		(net "M_J_CPU1_SA_CA<2>")
	)
	(arc
		(start 144.018254 -253.717044)
		(mid 144.198712 -253.767488)
		(end 144.380966 -253.723902)
		(width 0.0889)
		(layer "In4.Cu")
		(net "M_J_CPU1_SA_CA<2>")
	)
	(arc
		(start 142.137638 -253.717044)
		(mid 142.319889 -253.767394)
		(end 142.503398 -253.72187)
		(width 0.0889)
		(layer "In4.Cu")
		(net "M_J_CPU1_SA_CA<2>")
	)
	(arc
		(start 133.67766 -253.717044)
		(mid 133.859911 -253.767394)
		(end 134.04342 -253.72187)
		(width 0.0889)
		(layer "In4.Cu")
		(net "M_J_CPU1_SA_CA<2>")
	)
	(arc
		(start 135.56615 -253.72187)
		(mid 135.749658 -253.767364)
		(end 135.93191 -253.717044)
		(width 0.0889)
		(layer "In4.Cu")
		(net "M_J_CPU1_SA_CA<2>")
	)
	(arc
		(start 134.051802 -253.717044)
		(mid 134.334758 -253.640867)
		(end 134.617714 -253.717044)
		(width 0.0889)
		(layer "In4.Cu")
		(net "M_J_CPU1_SA_CA<2>")
	)
	(arc
		(start 142.51178 -253.717044)
		(mid 142.794736 -253.640867)
		(end 143.077692 -253.717044)
		(width 0.0889)
		(layer "In4.Cu")
		(net "M_J_CPU1_SA_CA<2>")
	)
	(arc
		(start 144.39265 -253.717044)
		(mid 144.672078 -253.640878)
		(end 144.952466 -253.713488)
		(width 0.0889)
		(layer "In4.Cu")
		(net "M_J_CPU1_SA_CA<2>")
	)
	(arc
		(start 141.571726 -253.717044)
		(mid 141.854682 -253.640867)
		(end 142.137638 -253.717044)
		(width 0.0889)
		(layer "In4.Cu")
		(net "M_J_CPU1_SA_CA<2>")
	)
	(arc
		(start 140.631926 -253.717044)
		(mid 140.914882 -253.640867)
		(end 141.197838 -253.717044)
		(width 0.0889)
		(layer "In4.Cu")
		(net "M_J_CPU1_SA_CA<2>")
	)
	(arc
		(start 136.497822 -253.717044)
		(mid 136.684766 -253.767299)
		(end 136.87171 -253.717044)
		(width 0.0889)
		(layer "In4.Cu")
		(net "M_J_CPU1_SA_CA<2>")
	)
	(arc
		(start 131.29514 -253.685294)
		(mid 131.550205 -253.641943)
		(end 131.797806 -253.717044)
		(width 0.0889)
		(layer "In4.Cu")
		(net "M_J_CPU1_SA_CA<2>")
	)
	(arc
		(start 138.751818 -253.717044)
		(mid 139.034774 -253.640867)
		(end 139.31773 -253.717044)
		(width 0.0889)
		(layer "In4.Cu")
		(net "M_J_CPU1_SA_CA<2>")
	)
	(arc
		(start 143.086074 -253.72187)
		(mid 143.269582 -253.767364)
		(end 143.451834 -253.717044)
		(width 0.0889)
		(layer "In4.Cu")
		(net "M_J_CPU1_SA_CA<2>")
	)
	(arc
		(start 135.93191 -253.717044)
		(mid 136.214866 -253.640867)
		(end 136.497822 -253.717044)
		(width 0.0889)
		(layer "In4.Cu")
		(net "M_J_CPU1_SA_CA<2>")
	)
	(segment
		(start 132.457952 -253.660402)
		(end 132.924804 -253.394464)
		(width 0.10668)
		(layer "F.Cu")
		(net "M_J_CPU1_SA_CA<1>")
	)
	(segment
		(start 147.417028 -253.110746)
		(end 150.101046 -253.110746)
		(width 0.14478)
		(layer "In4.Cu")
		(net "M_J_CPU1_SA_CA<1>")
	)
	(segment
		(start 140.257784 -253.071884)
		(end 140.266166 -253.067058)
		(width 0.0889)
		(layer "In4.Cu")
		(net "M_J_CPU1_SA_CA<1>")
	)
	(segment
		(start 167.422068 -250.460256)
		(end 167.743378 -250.781566)
		(width 0.14478)
		(layer "In4.Cu")
		(net "M_J_CPU1_SA_CA<1>")
	)
	(segment
		(start 150.743666 -252.468126)
		(end 161.398966 -252.468126)
		(width 0.14478)
		(layer "In4.Cu")
		(net "M_J_CPU1_SA_CA<1>")
	)
	(segment
		(start 133.103366 -253.067058)
		(end 133.111748 -253.071884)
		(width 0.0889)
		(layer "In4.Cu")
		(net "M_J_CPU1_SA_CA<1>")
	)
	(segment
		(start 165.216332 -250.460256)
		(end 165.537642 -250.781566)
		(width 0.14478)
		(layer "In4.Cu")
		(net "M_J_CPU1_SA_CA<1>")
	)
	(segment
		(start 132.924804 -253.394464)
		(end 132.770626 -253.129034)
		(width 0.0889)
		(layer "In4.Cu")
		(net "M_J_CPU1_SA_CA<1>")
	)
	(segment
		(start 167.191944 -250.460256)
		(end 167.422068 -250.460256)
		(width 0.14478)
		(layer "In4.Cu")
		(net "M_J_CPU1_SA_CA<1>")
	)
	(segment
		(start 137.803382 -253.067058)
		(end 137.811764 -253.071884)
		(width 0.0889)
		(layer "In4.Cu")
		(net "M_J_CPU1_SA_CA<1>")
	)
	(segment
		(start 134.617714 -253.071884)
		(end 134.626096 -253.067058)
		(width 0.0889)
		(layer "In4.Cu")
		(net "M_J_CPU1_SA_CA<1>")
	)
	(segment
		(start 142.503398 -253.067058)
		(end 142.51178 -253.071884)
		(width 0.0889)
		(layer "In4.Cu")
		(net "M_J_CPU1_SA_CA<1>")
	)
	(segment
		(start 166.64051 -250.781566)
		(end 166.870634 -250.781566)
		(width 0.14478)
		(layer "In4.Cu")
		(net "M_J_CPU1_SA_CA<1>")
	)
	(segment
		(start 166.3192 -250.460256)
		(end 166.64051 -250.781566)
		(width 0.14478)
		(layer "In4.Cu")
		(net "M_J_CPU1_SA_CA<1>")
	)
	(segment
		(start 165.537642 -250.781566)
		(end 165.767766 -250.781566)
		(width 0.14478)
		(layer "In4.Cu")
		(net "M_J_CPU1_SA_CA<1>")
	)
	(segment
		(start 186.634882 -248.760488)
		(end 187.060078 -248.335292)
		(width 0.14478)
		(layer "In4.Cu")
		(net "M_J_CPU1_SA_CA<1>")
	)
	(segment
		(start 167.743378 -250.781566)
		(end 167.973502 -250.781566)
		(width 0.14478)
		(layer "In4.Cu")
		(net "M_J_CPU1_SA_CA<1>")
	)
	(segment
		(start 169.949114 -250.781566)
		(end 170.179238 -250.781566)
		(width 0.14478)
		(layer "In4.Cu")
		(net "M_J_CPU1_SA_CA<1>")
	)
	(segment
		(start 146.131788 -253.148338)
		(end 146.380454 -253.397004)
		(width 0.0889)
		(layer "In4.Cu")
		(net "M_J_CPU1_SA_CA<1>")
	)
	(segment
		(start 166.089076 -250.460256)
		(end 166.3192 -250.460256)
		(width 0.14478)
		(layer "In4.Cu")
		(net "M_J_CPU1_SA_CA<1>")
	)
	(segment
		(start 166.870634 -250.781566)
		(end 167.191944 -250.460256)
		(width 0.14478)
		(layer "In4.Cu")
		(net "M_J_CPU1_SA_CA<1>")
	)
	(segment
		(start 144.384268 -253.067058)
		(end 144.39265 -253.071884)
		(width 0.0889)
		(layer "In4.Cu")
		(net "M_J_CPU1_SA_CA<1>")
	)
	(segment
		(start 170.179238 -250.781566)
		(end 170.500548 -250.460256)
		(width 0.14478)
		(layer "In4.Cu")
		(net "M_J_CPU1_SA_CA<1>")
	)
	(segment
		(start 143.451834 -253.071884)
		(end 143.462248 -253.07798)
		(width 0.0889)
		(layer "In4.Cu")
		(net "M_J_CPU1_SA_CA<1>")
	)
	(segment
		(start 169.07637 -250.781566)
		(end 169.39768 -250.460256)
		(width 0.14478)
		(layer "In4.Cu")
		(net "M_J_CPU1_SA_CA<1>")
	)
	(segment
		(start 144.952466 -253.07544)
		(end 144.958054 -253.072138)
		(width 0.0889)
		(layer "In4.Cu")
		(net "M_J_CPU1_SA_CA<1>")
	)
	(segment
		(start 163.406836 -250.460256)
		(end 165.216332 -250.460256)
		(width 0.14478)
		(layer "In4.Cu")
		(net "M_J_CPU1_SA_CA<1>")
	)
	(segment
		(start 167.973502 -250.781566)
		(end 168.294812 -250.460256)
		(width 0.14478)
		(layer "In4.Cu")
		(net "M_J_CPU1_SA_CA<1>")
	)
	(segment
		(start 161.398966 -252.468126)
		(end 163.406836 -250.460256)
		(width 0.14478)
		(layer "In4.Cu")
		(net "M_J_CPU1_SA_CA<1>")
	)
	(segment
		(start 168.524936 -250.460256)
		(end 168.846246 -250.781566)
		(width 0.14478)
		(layer "In4.Cu")
		(net "M_J_CPU1_SA_CA<1>")
	)
	(segment
		(start 169.627804 -250.460256)
		(end 169.949114 -250.781566)
		(width 0.14478)
		(layer "In4.Cu")
		(net "M_J_CPU1_SA_CA<1>")
	)
	(segment
		(start 150.101046 -253.110746)
		(end 150.743666 -252.468126)
		(width 0.14478)
		(layer "In4.Cu")
		(net "M_J_CPU1_SA_CA<1>")
	)
	(segment
		(start 132.770626 -253.129034)
		(end 132.792978 -253.045722)
		(width 0.0889)
		(layer "In4.Cu")
		(net "M_J_CPU1_SA_CA<1>")
	)
	(segment
		(start 165.767766 -250.781566)
		(end 166.089076 -250.460256)
		(width 0.14478)
		(layer "In4.Cu")
		(net "M_J_CPU1_SA_CA<1>")
	)
	(segment
		(start 168.846246 -250.781566)
		(end 169.07637 -250.781566)
		(width 0.14478)
		(layer "In4.Cu")
		(net "M_J_CPU1_SA_CA<1>")
	)
	(segment
		(start 169.39768 -250.460256)
		(end 169.627804 -250.460256)
		(width 0.14478)
		(layer "In4.Cu")
		(net "M_J_CPU1_SA_CA<1>")
	)
	(segment
		(start 135.557768 -253.071884)
		(end 135.56615 -253.067058)
		(width 0.0889)
		(layer "In4.Cu")
		(net "M_J_CPU1_SA_CA<1>")
	)
	(segment
		(start 170.500548 -250.460256)
		(end 181.22519 -250.460256)
		(width 0.14478)
		(layer "In4.Cu")
		(net "M_J_CPU1_SA_CA<1>")
	)
	(segment
		(start 134.04342 -253.067058)
		(end 134.051802 -253.071884)
		(width 0.0889)
		(layer "In4.Cu")
		(net "M_J_CPU1_SA_CA<1>")
	)
	(segment
		(start 168.294812 -250.460256)
		(end 168.524936 -250.460256)
		(width 0.14478)
		(layer "In4.Cu")
		(net "M_J_CPU1_SA_CA<1>")
	)
	(segment
		(start 146.380454 -253.397004)
		(end 147.13077 -253.397004)
		(width 0.0889)
		(layer "In4.Cu")
		(net "M_J_CPU1_SA_CA<1>")
	)
	(segment
		(start 181.22519 -250.460256)
		(end 182.924958 -248.760488)
		(width 0.14478)
		(layer "In4.Cu")
		(net "M_J_CPU1_SA_CA<1>")
	)
	(segment
		(start 182.924958 -248.760488)
		(end 186.634882 -248.760488)
		(width 0.14478)
		(layer "In4.Cu")
		(net "M_J_CPU1_SA_CA<1>")
	)
	(segment
		(start 144.958054 -253.072138)
		(end 144.976342 -253.061724)
		(width 0.0889)
		(layer "In4.Cu")
		(net "M_J_CPU1_SA_CA<1>")
	)
	(segment
		(start 139.31773 -253.071884)
		(end 139.326112 -253.067058)
		(width 0.0889)
		(layer "In4.Cu")
		(net "M_J_CPU1_SA_CA<1>")
	)
	(segment
		(start 138.743436 -253.067058)
		(end 138.751818 -253.071884)
		(width 0.0889)
		(layer "In4.Cu")
		(net "M_J_CPU1_SA_CA<1>")
	)
	(segment
		(start 143.077692 -253.071884)
		(end 143.086074 -253.067058)
		(width 0.0889)
		(layer "In4.Cu")
		(net "M_J_CPU1_SA_CA<1>")
	)
	(segment
		(start 147.13077 -253.397004)
		(end 147.417028 -253.110746)
		(width 0.14478)
		(layer "In4.Cu")
		(net "M_J_CPU1_SA_CA<1>")
	)
	(segment
		(start 145.615914 -253.148338)
		(end 146.131788 -253.148338)
		(width 0.0889)
		(layer "In4.Cu")
		(net "M_J_CPU1_SA_CA<1>")
	)
	(arc
		(start 139.326112 -253.067058)
		(mid 139.50962 -253.021564)
		(end 139.691872 -253.071884)
		(width 0.0889)
		(layer "In4.Cu")
		(net "M_J_CPU1_SA_CA<1>")
	)
	(arc
		(start 144.018 -253.071884)
		(mid 144.200505 -253.021407)
		(end 144.384268 -253.067058)
		(width 0.0889)
		(layer "In4.Cu")
		(net "M_J_CPU1_SA_CA<1>")
	)
	(arc
		(start 140.266166 -253.067058)
		(mid 140.449674 -253.021564)
		(end 140.631926 -253.071884)
		(width 0.0889)
		(layer "In4.Cu")
		(net "M_J_CPU1_SA_CA<1>")
	)
	(arc
		(start 134.991856 -253.071884)
		(mid 135.274812 -253.148061)
		(end 135.557768 -253.071884)
		(width 0.0889)
		(layer "In4.Cu")
		(net "M_J_CPU1_SA_CA<1>")
	)
	(arc
		(start 145.332196 -253.071884)
		(mid 145.468989 -253.128906)
		(end 145.615914 -253.148338)
		(width 0.0889)
		(layer "In4.Cu")
		(net "M_J_CPU1_SA_CA<1>")
	)
	(arc
		(start 138.751818 -253.071884)
		(mid 139.034774 -253.148061)
		(end 139.31773 -253.071884)
		(width 0.0889)
		(layer "In4.Cu")
		(net "M_J_CPU1_SA_CA<1>")
	)
	(arc
		(start 140.631926 -253.071884)
		(mid 140.914882 -253.148061)
		(end 141.197838 -253.071884)
		(width 0.0889)
		(layer "In4.Cu")
		(net "M_J_CPU1_SA_CA<1>")
	)
	(arc
		(start 137.811764 -253.071884)
		(mid 138.09472 -253.148061)
		(end 138.377676 -253.071884)
		(width 0.0889)
		(layer "In4.Cu")
		(net "M_J_CPU1_SA_CA<1>")
	)
	(arc
		(start 134.051802 -253.071884)
		(mid 134.334758 -253.148061)
		(end 134.617714 -253.071884)
		(width 0.0889)
		(layer "In4.Cu")
		(net "M_J_CPU1_SA_CA<1>")
	)
	(arc
		(start 138.377676 -253.071884)
		(mid 138.559927 -253.021534)
		(end 138.743436 -253.067058)
		(width 0.0889)
		(layer "In4.Cu")
		(net "M_J_CPU1_SA_CA<1>")
	)
	(arc
		(start 139.691872 -253.071884)
		(mid 139.974828 -253.148061)
		(end 140.257784 -253.071884)
		(width 0.0889)
		(layer "In4.Cu")
		(net "M_J_CPU1_SA_CA<1>")
	)
	(arc
		(start 134.626096 -253.067058)
		(mid 134.809604 -253.021564)
		(end 134.991856 -253.071884)
		(width 0.0889)
		(layer "In4.Cu")
		(net "M_J_CPU1_SA_CA<1>")
	)
	(arc
		(start 132.792978 -253.045722)
		(mid 132.950488 -253.022524)
		(end 133.103366 -253.067058)
		(width 0.0889)
		(layer "In4.Cu")
		(net "M_J_CPU1_SA_CA<1>")
	)
	(arc
		(start 143.086074 -253.067058)
		(mid 143.269582 -253.021564)
		(end 143.451834 -253.071884)
		(width 0.0889)
		(layer "In4.Cu")
		(net "M_J_CPU1_SA_CA<1>")
	)
	(arc
		(start 137.437622 -253.071884)
		(mid 137.619873 -253.021534)
		(end 137.803382 -253.067058)
		(width 0.0889)
		(layer "In4.Cu")
		(net "M_J_CPU1_SA_CA<1>")
	)
	(arc
		(start 133.111748 -253.071884)
		(mid 133.394704 -253.148061)
		(end 133.67766 -253.071884)
		(width 0.0889)
		(layer "In4.Cu")
		(net "M_J_CPU1_SA_CA<1>")
	)
	(arc
		(start 144.39265 -253.071884)
		(mid 144.672078 -253.14805)
		(end 144.952466 -253.07544)
		(width 0.0889)
		(layer "In4.Cu")
		(net "M_J_CPU1_SA_CA<1>")
	)
	(arc
		(start 144.976342 -253.061724)
		(mid 145.155571 -253.021571)
		(end 145.332196 -253.071884)
		(width 0.0889)
		(layer "In4.Cu")
		(net "M_J_CPU1_SA_CA<1>")
	)
	(arc
		(start 143.462248 -253.07798)
		(mid 143.740934 -253.1482)
		(end 144.018 -253.071884)
		(width 0.0889)
		(layer "In4.Cu")
		(net "M_J_CPU1_SA_CA<1>")
	)
	(arc
		(start 142.51178 -253.071884)
		(mid 142.794736 -253.148061)
		(end 143.077692 -253.071884)
		(width 0.0889)
		(layer "In4.Cu")
		(net "M_J_CPU1_SA_CA<1>")
	)
	(arc
		(start 135.93191 -253.071884)
		(mid 136.214866 -253.148061)
		(end 136.497822 -253.071884)
		(width 0.0889)
		(layer "In4.Cu")
		(net "M_J_CPU1_SA_CA<1>")
	)
	(arc
		(start 141.197838 -253.071884)
		(mid 141.384782 -253.021629)
		(end 141.571726 -253.071884)
		(width 0.0889)
		(layer "In4.Cu")
		(net "M_J_CPU1_SA_CA<1>")
	)
	(arc
		(start 135.56615 -253.067058)
		(mid 135.749658 -253.021564)
		(end 135.93191 -253.071884)
		(width 0.0889)
		(layer "In4.Cu")
		(net "M_J_CPU1_SA_CA<1>")
	)
	(arc
		(start 141.571726 -253.071884)
		(mid 141.854682 -253.148061)
		(end 142.137638 -253.071884)
		(width 0.0889)
		(layer "In4.Cu")
		(net "M_J_CPU1_SA_CA<1>")
	)
	(arc
		(start 142.137638 -253.071884)
		(mid 142.319889 -253.021534)
		(end 142.503398 -253.067058)
		(width 0.0889)
		(layer "In4.Cu")
		(net "M_J_CPU1_SA_CA<1>")
	)
	(arc
		(start 136.87171 -253.071884)
		(mid 137.154666 -253.148061)
		(end 137.437622 -253.071884)
		(width 0.0889)
		(layer "In4.Cu")
		(net "M_J_CPU1_SA_CA<1>")
	)
	(arc
		(start 133.67766 -253.071884)
		(mid 133.859911 -253.021534)
		(end 134.04342 -253.067058)
		(width 0.0889)
		(layer "In4.Cu")
		(net "M_J_CPU1_SA_CA<1>")
	)
	(arc
		(start 136.497822 -253.071884)
		(mid 136.684766 -253.021629)
		(end 136.87171 -253.071884)
		(width 0.0889)
		(layer "In4.Cu")
		(net "M_J_CPU1_SA_CA<1>")
	)
	(segment
		(start 131.987798 -252.850396)
		(end 132.45465 -252.584458)
		(width 0.10668)
		(layer "F.Cu")
		(net "M_J_CPU1_SA_CA<0>")
	)
	(segment
		(start 133.20776 -252.907038)
		(end 133.216142 -252.911864)
		(width 0.0889)
		(layer "In4.Cu")
		(net "M_J_CPU1_SA_CA<0>")
	)
	(segment
		(start 181.352952 -249.610372)
		(end 183.052974 -247.91035)
		(width 0.14478)
		(layer "In4.Cu")
		(net "M_J_CPU1_SA_CA<0>")
	)
	(segment
		(start 137.907776 -252.907038)
		(end 137.916158 -252.911864)
		(width 0.0889)
		(layer "In4.Cu")
		(net "M_J_CPU1_SA_CA<0>")
	)
	(segment
		(start 140.15339 -252.911864)
		(end 140.161772 -252.907038)
		(width 0.0889)
		(layer "In4.Cu")
		(net "M_J_CPU1_SA_CA<0>")
	)
	(segment
		(start 141.667738 -252.907038)
		(end 141.67612 -252.911864)
		(width 0.0889)
		(layer "In4.Cu")
		(net "M_J_CPU1_SA_CA<0>")
	)
	(segment
		(start 144.862296 -252.906784)
		(end 144.878044 -252.89764)
		(width 0.0889)
		(layer "In4.Cu")
		(net "M_J_CPU1_SA_CA<0>")
	)
	(segment
		(start 161.21253 -252.018546)
		(end 163.620704 -249.610372)
		(width 0.14478)
		(layer "In4.Cu")
		(net "M_J_CPU1_SA_CA<0>")
	)
	(segment
		(start 150.543006 -252.018546)
		(end 161.21253 -252.018546)
		(width 0.14478)
		(layer "In4.Cu")
		(net "M_J_CPU1_SA_CA<0>")
	)
	(segment
		(start 132.45465 -252.584458)
		(end 132.608828 -252.849888)
		(width 0.0889)
		(layer "In4.Cu")
		(net "M_J_CPU1_SA_CA<0>")
	)
	(segment
		(start 150.080218 -252.481334)
		(end 150.543006 -252.018546)
		(width 0.14478)
		(layer "In4.Cu")
		(net "M_J_CPU1_SA_CA<0>")
	)
	(segment
		(start 163.620704 -249.610372)
		(end 181.352952 -249.610372)
		(width 0.14478)
		(layer "In4.Cu")
		(net "M_J_CPU1_SA_CA<0>")
	)
	(segment
		(start 144.477994 -252.900942)
		(end 144.488408 -252.907038)
		(width 0.0889)
		(layer "In4.Cu")
		(net "M_J_CPU1_SA_CA<0>")
	)
	(segment
		(start 135.453374 -252.911864)
		(end 135.461756 -252.907038)
		(width 0.0889)
		(layer "In4.Cu")
		(net "M_J_CPU1_SA_CA<0>")
	)
	(segment
		(start 141.093444 -252.911864)
		(end 141.101826 -252.907038)
		(width 0.0889)
		(layer "In4.Cu")
		(net "M_J_CPU1_SA_CA<0>")
	)
	(segment
		(start 145.61566 -252.957838)
		(end 146.04238 -252.957838)
		(width 0.0889)
		(layer "In4.Cu")
		(net "M_J_CPU1_SA_CA<0>")
	)
	(segment
		(start 147.40763 -252.481334)
		(end 150.080218 -252.481334)
		(width 0.14478)
		(layer "In4.Cu")
		(net "M_J_CPU1_SA_CA<0>")
	)
	(segment
		(start 143.547592 -252.907038)
		(end 143.555974 -252.911864)
		(width 0.0889)
		(layer "In4.Cu")
		(net "M_J_CPU1_SA_CA<0>")
	)
	(segment
		(start 144.84604 -252.916182)
		(end 144.862296 -252.906784)
		(width 0.0889)
		(layer "In4.Cu")
		(net "M_J_CPU1_SA_CA<0>")
	)
	(segment
		(start 146.518884 -252.481334)
		(end 147.40763 -252.481334)
		(width 0.0889)
		(layer "In4.Cu")
		(net "M_J_CPU1_SA_CA<0>")
	)
	(segment
		(start 183.052974 -247.91035)
		(end 190.735204 -247.91035)
		(width 0.14478)
		(layer "In4.Cu")
		(net "M_J_CPU1_SA_CA<0>")
	)
	(segment
		(start 136.967722 -252.907038)
		(end 136.976104 -252.911864)
		(width 0.0889)
		(layer "In4.Cu")
		(net "M_J_CPU1_SA_CA<0>")
	)
	(segment
		(start 136.393428 -252.911864)
		(end 136.40181 -252.907038)
		(width 0.0889)
		(layer "In4.Cu")
		(net "M_J_CPU1_SA_CA<0>")
	)
	(segment
		(start 146.04238 -252.957838)
		(end 146.518884 -252.481334)
		(width 0.0889)
		(layer "In4.Cu")
		(net "M_J_CPU1_SA_CA<0>")
	)
	(segment
		(start 190.735204 -247.91035)
		(end 191.160146 -247.485408)
		(width 0.14478)
		(layer "In4.Cu")
		(net "M_J_CPU1_SA_CA<0>")
	)
	(segment
		(start 132.608828 -252.849888)
		(end 132.705094 -252.875288)
		(width 0.0889)
		(layer "In4.Cu")
		(net "M_J_CPU1_SA_CA<0>")
	)
	(segment
		(start 145.428208 -252.907038)
		(end 145.427954 -252.907038)
		(width 0.0889)
		(layer "In4.Cu")
		(net "M_J_CPU1_SA_CA<0>")
	)
	(arc
		(start 144.878044 -252.89764)
		(mid 145.154353 -252.830664)
		(end 145.428208 -252.907038)
		(width 0.0889)
		(layer "In4.Cu")
		(net "M_J_CPU1_SA_CA<0>")
	)
	(arc
		(start 138.281918 -252.907038)
		(mid 138.564874 -252.830861)
		(end 138.84783 -252.907038)
		(width 0.0889)
		(layer "In4.Cu")
		(net "M_J_CPU1_SA_CA<0>")
	)
	(arc
		(start 141.101826 -252.907038)
		(mid 141.384782 -252.830861)
		(end 141.667738 -252.907038)
		(width 0.0889)
		(layer "In4.Cu")
		(net "M_J_CPU1_SA_CA<0>")
	)
	(arc
		(start 143.555974 -252.911864)
		(mid 143.739736 -252.95748)
		(end 143.922242 -252.907038)
		(width 0.0889)
		(layer "In4.Cu")
		(net "M_J_CPU1_SA_CA<0>")
	)
	(arc
		(start 137.916158 -252.911864)
		(mid 138.099666 -252.957358)
		(end 138.281918 -252.907038)
		(width 0.0889)
		(layer "In4.Cu")
		(net "M_J_CPU1_SA_CA<0>")
	)
	(arc
		(start 132.705094 -252.875288)
		(mid 132.960159 -252.831937)
		(end 133.20776 -252.907038)
		(width 0.0889)
		(layer "In4.Cu")
		(net "M_J_CPU1_SA_CA<0>")
	)
	(arc
		(start 136.40181 -252.907038)
		(mid 136.684766 -252.830861)
		(end 136.967722 -252.907038)
		(width 0.0889)
		(layer "In4.Cu")
		(net "M_J_CPU1_SA_CA<0>")
	)
	(arc
		(start 137.341864 -252.907038)
		(mid 137.62482 -252.830861)
		(end 137.907776 -252.907038)
		(width 0.0889)
		(layer "In4.Cu")
		(net "M_J_CPU1_SA_CA<0>")
	)
	(arc
		(start 144.488408 -252.907038)
		(mid 144.666058 -252.957298)
		(end 144.84604 -252.916182)
		(width 0.0889)
		(layer "In4.Cu")
		(net "M_J_CPU1_SA_CA<0>")
	)
	(arc
		(start 140.161772 -252.907038)
		(mid 140.444728 -252.830861)
		(end 140.727684 -252.907038)
		(width 0.0889)
		(layer "In4.Cu")
		(net "M_J_CPU1_SA_CA<0>")
	)
	(arc
		(start 142.607792 -252.907038)
		(mid 142.794736 -252.957293)
		(end 142.98168 -252.907038)
		(width 0.0889)
		(layer "In4.Cu")
		(net "M_J_CPU1_SA_CA<0>")
	)
	(arc
		(start 139.78763 -252.907038)
		(mid 139.969881 -252.957388)
		(end 140.15339 -252.911864)
		(width 0.0889)
		(layer "In4.Cu")
		(net "M_J_CPU1_SA_CA<0>")
	)
	(arc
		(start 135.461756 -252.907038)
		(mid 135.744712 -252.830861)
		(end 136.027668 -252.907038)
		(width 0.0889)
		(layer "In4.Cu")
		(net "M_J_CPU1_SA_CA<0>")
	)
	(arc
		(start 138.84783 -252.907038)
		(mid 139.034774 -252.957293)
		(end 139.221718 -252.907038)
		(width 0.0889)
		(layer "In4.Cu")
		(net "M_J_CPU1_SA_CA<0>")
	)
	(arc
		(start 133.581902 -252.907038)
		(mid 133.864858 -252.830861)
		(end 134.147814 -252.907038)
		(width 0.0889)
		(layer "In4.Cu")
		(net "M_J_CPU1_SA_CA<0>")
	)
	(arc
		(start 142.04188 -252.907038)
		(mid 142.324836 -252.830861)
		(end 142.607792 -252.907038)
		(width 0.0889)
		(layer "In4.Cu")
		(net "M_J_CPU1_SA_CA<0>")
	)
	(arc
		(start 134.521702 -252.907038)
		(mid 134.804658 -252.830861)
		(end 135.087614 -252.907038)
		(width 0.0889)
		(layer "In4.Cu")
		(net "M_J_CPU1_SA_CA<0>")
	)
	(arc
		(start 136.976104 -252.911864)
		(mid 137.159612 -252.957358)
		(end 137.341864 -252.907038)
		(width 0.0889)
		(layer "In4.Cu")
		(net "M_J_CPU1_SA_CA<0>")
	)
	(arc
		(start 145.427954 -252.907038)
		(mid 145.518444 -252.944856)
		(end 145.61566 -252.957838)
		(width 0.0889)
		(layer "In4.Cu")
		(net "M_J_CPU1_SA_CA<0>")
	)
	(arc
		(start 140.727684 -252.907038)
		(mid 140.909935 -252.957388)
		(end 141.093444 -252.911864)
		(width 0.0889)
		(layer "In4.Cu")
		(net "M_J_CPU1_SA_CA<0>")
	)
	(arc
		(start 133.216142 -252.911864)
		(mid 133.39965 -252.957358)
		(end 133.581902 -252.907038)
		(width 0.0889)
		(layer "In4.Cu")
		(net "M_J_CPU1_SA_CA<0>")
	)
	(arc
		(start 136.027668 -252.907038)
		(mid 136.209919 -252.957388)
		(end 136.393428 -252.911864)
		(width 0.0889)
		(layer "In4.Cu")
		(net "M_J_CPU1_SA_CA<0>")
	)
	(arc
		(start 134.147814 -252.907038)
		(mid 134.334758 -252.957293)
		(end 134.521702 -252.907038)
		(width 0.0889)
		(layer "In4.Cu")
		(net "M_J_CPU1_SA_CA<0>")
	)
	(arc
		(start 139.221718 -252.907038)
		(mid 139.504674 -252.830861)
		(end 139.78763 -252.907038)
		(width 0.0889)
		(layer "In4.Cu")
		(net "M_J_CPU1_SA_CA<0>")
	)
	(arc
		(start 142.98168 -252.907038)
		(mid 143.264636 -252.830861)
		(end 143.547592 -252.907038)
		(width 0.0889)
		(layer "In4.Cu")
		(net "M_J_CPU1_SA_CA<0>")
	)
	(arc
		(start 143.922242 -252.907038)
		(mid 144.199309 -252.830767)
		(end 144.477994 -252.900942)
		(width 0.0889)
		(layer "In4.Cu")
		(net "M_J_CPU1_SA_CA<0>")
	)
	(arc
		(start 135.087614 -252.907038)
		(mid 135.269865 -252.957388)
		(end 135.453374 -252.911864)
		(width 0.0889)
		(layer "In4.Cu")
		(net "M_J_CPU1_SA_CA<0>")
	)
	(arc
		(start 141.67612 -252.911864)
		(mid 141.859628 -252.957358)
		(end 142.04188 -252.907038)
		(width 0.0889)
		(layer "In4.Cu")
		(net "M_J_CPU1_SA_CA<0>")
	)
	(segment
		(start 131.047998 -251.230384)
		(end 131.51485 -250.964446)
		(width 0.10668)
		(layer "F.Cu")
		(net "M_J_CPU1_RESET_N")
	)
	(segment
		(start 141.667738 -250.641866)
		(end 141.67612 -250.63704)
		(width 0.0889)
		(layer "In4.Cu")
		(net "M_J_CPU1_RESET_N")
	)
	(segment
		(start 133.20776 -250.641866)
		(end 133.216142 -250.63704)
		(width 0.0889)
		(layer "In4.Cu")
		(net "M_J_CPU1_RESET_N")
	)
	(segment
		(start 147.35302 -250.724416)
		(end 147.400772 -250.676664)
		(width 0.0889)
		(layer "In4.Cu")
		(net "M_J_CPU1_RESET_N")
	)
	(segment
		(start 136.393428 -250.63704)
		(end 136.40181 -250.641866)
		(width 0.0889)
		(layer "In4.Cu")
		(net "M_J_CPU1_RESET_N")
	)
	(segment
		(start 131.693412 -250.63704)
		(end 131.701794 -250.641866)
		(width 0.0889)
		(layer "In4.Cu")
		(net "M_J_CPU1_RESET_N")
	)
	(segment
		(start 182.433976 -245.360444)
		(end 186.634882 -245.360444)
		(width 0.11684)
		(layer "In4.Cu")
		(net "M_J_CPU1_RESET_N")
	)
	(segment
		(start 136.967722 -250.641866)
		(end 136.976104 -250.63704)
		(width 0.0889)
		(layer "In4.Cu")
		(net "M_J_CPU1_RESET_N")
	)
	(segment
		(start 147.400772 -250.676664)
		(end 147.636484 -250.676664)
		(width 0.0889)
		(layer "In4.Cu")
		(net "M_J_CPU1_RESET_N")
	)
	(segment
		(start 132.267706 -250.641866)
		(end 132.276088 -250.63704)
		(width 0.0889)
		(layer "In4.Cu")
		(net "M_J_CPU1_RESET_N")
	)
	(segment
		(start 141.093444 -250.63704)
		(end 141.101826 -250.641866)
		(width 0.0889)
		(layer "In4.Cu")
		(net "M_J_CPU1_RESET_N")
	)
	(segment
		(start 149.529292 -250.676664)
		(end 149.82698 -250.378976)
		(width 0.11684)
		(layer "In4.Cu")
		(net "M_J_CPU1_RESET_N")
	)
	(segment
		(start 143.547592 -250.641866)
		(end 143.555974 -250.63704)
		(width 0.0889)
		(layer "In4.Cu")
		(net "M_J_CPU1_RESET_N")
	)
	(segment
		(start 135.453374 -250.63704)
		(end 135.461756 -250.641866)
		(width 0.0889)
		(layer "In4.Cu")
		(net "M_J_CPU1_RESET_N")
	)
	(segment
		(start 131.51485 -250.964446)
		(end 131.360672 -250.699016)
		(width 0.0889)
		(layer "In4.Cu")
		(net "M_J_CPU1_RESET_N")
	)
	(segment
		(start 144.84858 -250.634246)
		(end 144.862296 -250.64212)
		(width 0.0889)
		(layer "In4.Cu")
		(net "M_J_CPU1_RESET_N")
	)
	(segment
		(start 145.16735 -250.724416)
		(end 147.35302 -250.724416)
		(width 0.0889)
		(layer "In4.Cu")
		(net "M_J_CPU1_RESET_N")
	)
	(segment
		(start 137.907776 -250.641866)
		(end 137.916158 -250.63704)
		(width 0.0889)
		(layer "In4.Cu")
		(net "M_J_CPU1_RESET_N")
	)
	(segment
		(start 186.634882 -245.360444)
		(end 187.060078 -244.935248)
		(width 0.11684)
		(layer "In4.Cu")
		(net "M_J_CPU1_RESET_N")
	)
	(segment
		(start 163.850574 -247.060466)
		(end 180.733954 -247.060466)
		(width 0.11684)
		(layer "In4.Cu")
		(net "M_J_CPU1_RESET_N")
	)
	(segment
		(start 131.360672 -250.699016)
		(end 131.383024 -250.615704)
		(width 0.0889)
		(layer "In4.Cu")
		(net "M_J_CPU1_RESET_N")
	)
	(segment
		(start 180.733954 -247.060466)
		(end 182.433976 -245.360444)
		(width 0.11684)
		(layer "In4.Cu")
		(net "M_J_CPU1_RESET_N")
	)
	(segment
		(start 140.15339 -250.63704)
		(end 140.161772 -250.641866)
		(width 0.0889)
		(layer "In4.Cu")
		(net "M_J_CPU1_RESET_N")
	)
	(segment
		(start 144.862296 -250.64212)
		(end 144.878044 -250.651264)
		(width 0.0889)
		(layer "In4.Cu")
		(net "M_J_CPU1_RESET_N")
	)
	(segment
		(start 147.636484 -250.676664)
		(end 149.529292 -250.676664)
		(width 0.11684)
		(layer "In4.Cu")
		(net "M_J_CPU1_RESET_N")
	)
	(segment
		(start 160.532064 -250.378976)
		(end 163.850574 -247.060466)
		(width 0.11684)
		(layer "In4.Cu")
		(net "M_J_CPU1_RESET_N")
	)
	(segment
		(start 144.47393 -250.650502)
		(end 144.488662 -250.641866)
		(width 0.0889)
		(layer "In4.Cu")
		(net "M_J_CPU1_RESET_N")
	)
	(segment
		(start 149.82698 -250.378976)
		(end 160.532064 -250.378976)
		(width 0.11684)
		(layer "In4.Cu")
		(net "M_J_CPU1_RESET_N")
	)
	(arc
		(start 142.04188 -250.641866)
		(mid 142.324836 -250.718043)
		(end 142.607792 -250.641866)
		(width 0.0889)
		(layer "In4.Cu")
		(net "M_J_CPU1_RESET_N")
	)
	(arc
		(start 134.147814 -250.641866)
		(mid 134.334758 -250.591611)
		(end 134.521702 -250.641866)
		(width 0.0889)
		(layer "In4.Cu")
		(net "M_J_CPU1_RESET_N")
	)
	(arc
		(start 141.101826 -250.641866)
		(mid 141.384782 -250.718043)
		(end 141.667738 -250.641866)
		(width 0.0889)
		(layer "In4.Cu")
		(net "M_J_CPU1_RESET_N")
	)
	(arc
		(start 141.67612 -250.63704)
		(mid 141.859628 -250.591546)
		(end 142.04188 -250.641866)
		(width 0.0889)
		(layer "In4.Cu")
		(net "M_J_CPU1_RESET_N")
	)
	(arc
		(start 142.98168 -250.641866)
		(mid 143.264636 -250.718043)
		(end 143.547592 -250.641866)
		(width 0.0889)
		(layer "In4.Cu")
		(net "M_J_CPU1_RESET_N")
	)
	(arc
		(start 139.78763 -250.641866)
		(mid 139.969881 -250.591516)
		(end 140.15339 -250.63704)
		(width 0.0889)
		(layer "In4.Cu")
		(net "M_J_CPU1_RESET_N")
	)
	(arc
		(start 138.281918 -250.641866)
		(mid 138.564874 -250.718043)
		(end 138.84783 -250.641866)
		(width 0.0889)
		(layer "In4.Cu")
		(net "M_J_CPU1_RESET_N")
	)
	(arc
		(start 137.916158 -250.63704)
		(mid 138.099666 -250.591546)
		(end 138.281918 -250.641866)
		(width 0.0889)
		(layer "In4.Cu")
		(net "M_J_CPU1_RESET_N")
	)
	(arc
		(start 136.976104 -250.63704)
		(mid 137.159612 -250.591546)
		(end 137.341864 -250.641866)
		(width 0.0889)
		(layer "In4.Cu")
		(net "M_J_CPU1_RESET_N")
	)
	(arc
		(start 143.555974 -250.63704)
		(mid 143.739736 -250.591424)
		(end 143.922242 -250.641866)
		(width 0.0889)
		(layer "In4.Cu")
		(net "M_J_CPU1_RESET_N")
	)
	(arc
		(start 131.701794 -250.641866)
		(mid 131.98475 -250.718043)
		(end 132.267706 -250.641866)
		(width 0.0889)
		(layer "In4.Cu")
		(net "M_J_CPU1_RESET_N")
	)
	(arc
		(start 140.727684 -250.641866)
		(mid 140.909935 -250.591516)
		(end 141.093444 -250.63704)
		(width 0.0889)
		(layer "In4.Cu")
		(net "M_J_CPU1_RESET_N")
	)
	(arc
		(start 138.84783 -250.641866)
		(mid 139.034774 -250.591611)
		(end 139.221718 -250.641866)
		(width 0.0889)
		(layer "In4.Cu")
		(net "M_J_CPU1_RESET_N")
	)
	(arc
		(start 131.383024 -250.615704)
		(mid 131.540534 -250.592506)
		(end 131.693412 -250.63704)
		(width 0.0889)
		(layer "In4.Cu")
		(net "M_J_CPU1_RESET_N")
	)
	(arc
		(start 135.461756 -250.641866)
		(mid 135.744712 -250.718043)
		(end 136.027668 -250.641866)
		(width 0.0889)
		(layer "In4.Cu")
		(net "M_J_CPU1_RESET_N")
	)
	(arc
		(start 133.216142 -250.63704)
		(mid 133.39965 -250.591546)
		(end 133.581902 -250.641866)
		(width 0.0889)
		(layer "In4.Cu")
		(net "M_J_CPU1_RESET_N")
	)
	(arc
		(start 136.40181 -250.641866)
		(mid 136.684766 -250.718043)
		(end 136.967722 -250.641866)
		(width 0.0889)
		(layer "In4.Cu")
		(net "M_J_CPU1_RESET_N")
	)
	(arc
		(start 140.161772 -250.641866)
		(mid 140.444728 -250.718043)
		(end 140.727684 -250.641866)
		(width 0.0889)
		(layer "In4.Cu")
		(net "M_J_CPU1_RESET_N")
	)
	(arc
		(start 132.641848 -250.641866)
		(mid 132.924804 -250.718043)
		(end 133.20776 -250.641866)
		(width 0.0889)
		(layer "In4.Cu")
		(net "M_J_CPU1_RESET_N")
	)
	(arc
		(start 144.878044 -250.651264)
		(mid 145.017573 -250.7081)
		(end 145.16735 -250.724416)
		(width 0.0889)
		(layer "In4.Cu")
		(net "M_J_CPU1_RESET_N")
	)
	(arc
		(start 134.521702 -250.641866)
		(mid 134.804658 -250.718043)
		(end 135.087614 -250.641866)
		(width 0.0889)
		(layer "In4.Cu")
		(net "M_J_CPU1_RESET_N")
	)
	(arc
		(start 139.221718 -250.641866)
		(mid 139.504674 -250.718043)
		(end 139.78763 -250.641866)
		(width 0.0889)
		(layer "In4.Cu")
		(net "M_J_CPU1_RESET_N")
	)
	(arc
		(start 133.581902 -250.641866)
		(mid 133.864858 -250.718043)
		(end 134.147814 -250.641866)
		(width 0.0889)
		(layer "In4.Cu")
		(net "M_J_CPU1_RESET_N")
	)
	(arc
		(start 136.027668 -250.641866)
		(mid 136.209919 -250.591516)
		(end 136.393428 -250.63704)
		(width 0.0889)
		(layer "In4.Cu")
		(net "M_J_CPU1_RESET_N")
	)
	(arc
		(start 144.488662 -250.641866)
		(mid 144.667649 -250.591696)
		(end 144.84858 -250.634246)
		(width 0.0889)
		(layer "In4.Cu")
		(net "M_J_CPU1_RESET_N")
	)
	(arc
		(start 135.087614 -250.641866)
		(mid 135.269865 -250.591516)
		(end 135.453374 -250.63704)
		(width 0.0889)
		(layer "In4.Cu")
		(net "M_J_CPU1_RESET_N")
	)
	(arc
		(start 132.276088 -250.63704)
		(mid 132.459596 -250.591546)
		(end 132.641848 -250.641866)
		(width 0.0889)
		(layer "In4.Cu")
		(net "M_J_CPU1_RESET_N")
	)
	(arc
		(start 142.607792 -250.641866)
		(mid 142.794736 -250.591611)
		(end 142.98168 -250.641866)
		(width 0.0889)
		(layer "In4.Cu")
		(net "M_J_CPU1_RESET_N")
	)
	(arc
		(start 137.341864 -250.641866)
		(mid 137.62482 -250.718043)
		(end 137.907776 -250.641866)
		(width 0.0889)
		(layer "In4.Cu")
		(net "M_J_CPU1_RESET_N")
	)
	(arc
		(start 143.922242 -250.641866)
		(mid 144.196948 -250.71823)
		(end 144.47393 -250.650502)
		(width 0.0889)
		(layer "In4.Cu")
		(net "M_J_CPU1_RESET_N")
	)
	(segment
		(start 131.987798 -256.09042)
		(end 132.45465 -255.824482)
		(width 0.14732)
		(layer "F.Cu")
		(net "M_J_CPU1_CLK_DP<0>")
	)
	(segment
		(start 132.608574 -256.089912)
		(end 132.709412 -256.116582)
		(width 0.09525)
		(layer "In4.Cu")
		(net "M_J_CPU1_CLK_DP<0>")
	)
	(segment
		(start 176.995582 -257.479546)
		(end 177.314352 -257.479546)
		(width 0.16002)
		(layer "In4.Cu")
		(net "M_J_CPU1_CLK_DP<0>")
	)
	(segment
		(start 176.77003 -256.863596)
		(end 176.77003 -257.253994)
		(width 0.16002)
		(layer "In4.Cu")
		(net "M_J_CPU1_CLK_DP<0>")
	)
	(segment
		(start 140.154914 -256.154428)
		(end 140.163296 -256.149602)
		(width 0.09525)
		(layer "In4.Cu")
		(net "M_J_CPU1_CLK_DP<0>")
	)
	(segment
		(start 179.45862 -257.479546)
		(end 179.684172 -257.253994)
		(width 0.16002)
		(layer "In4.Cu")
		(net "M_J_CPU1_CLK_DP<0>")
	)
	(segment
		(start 144.86382 -256.149602)
		(end 144.884648 -256.13741)
		(width 0.09525)
		(layer "In4.Cu")
		(net "M_J_CPU1_CLK_DP<0>")
	)
	(segment
		(start 137.906252 -256.149602)
		(end 137.914634 -256.154428)
		(width 0.09525)
		(layer "In4.Cu")
		(net "M_J_CPU1_CLK_DP<0>")
	)
	(segment
		(start 144.849342 -256.157984)
		(end 144.86382 -256.149602)
		(width 0.09525)
		(layer "In4.Cu")
		(net "M_J_CPU1_CLK_DP<0>")
	)
	(segment
		(start 136.966198 -256.149602)
		(end 136.97458 -256.154428)
		(width 0.09525)
		(layer "In4.Cu")
		(net "M_J_CPU1_CLK_DP<0>")
	)
	(segment
		(start 179.13985 -257.479546)
		(end 179.45862 -257.479546)
		(width 0.16002)
		(layer "In4.Cu")
		(net "M_J_CPU1_CLK_DP<0>")
	)
	(segment
		(start 147.79879 -257.313176)
		(end 150.856188 -257.313176)
		(width 0.16002)
		(layer "In4.Cu")
		(net "M_J_CPU1_CLK_DP<0>")
	)
	(segment
		(start 176.36744 -256.461006)
		(end 176.77003 -256.863596)
		(width 0.16002)
		(layer "In4.Cu")
		(net "M_J_CPU1_CLK_DP<0>")
	)
	(segment
		(start 150.856188 -257.313176)
		(end 152.343358 -255.826006)
		(width 0.16002)
		(layer "In4.Cu")
		(net "M_J_CPU1_CLK_DP<0>")
	)
	(segment
		(start 135.454898 -256.154428)
		(end 135.46328 -256.149602)
		(width 0.09525)
		(layer "In4.Cu")
		(net "M_J_CPU1_CLK_DP<0>")
	)
	(segment
		(start 178.914298 -256.863596)
		(end 178.914298 -257.253994)
		(width 0.16002)
		(layer "In4.Cu")
		(net "M_J_CPU1_CLK_DP<0>")
	)
	(segment
		(start 156.09443 -255.826006)
		(end 156.72943 -256.461006)
		(width 0.16002)
		(layer "In4.Cu")
		(net "M_J_CPU1_CLK_DP<0>")
	)
	(segment
		(start 177.942494 -256.461006)
		(end 178.511708 -256.461006)
		(width 0.16002)
		(layer "In4.Cu")
		(net "M_J_CPU1_CLK_DP<0>")
	)
	(segment
		(start 179.684172 -256.863596)
		(end 180.086762 -256.461006)
		(width 0.16002)
		(layer "In4.Cu")
		(net "M_J_CPU1_CLK_DP<0>")
	)
	(segment
		(start 177.314352 -257.479546)
		(end 177.539904 -257.253994)
		(width 0.16002)
		(layer "In4.Cu")
		(net "M_J_CPU1_CLK_DP<0>")
	)
	(segment
		(start 178.511708 -256.461006)
		(end 178.914298 -256.863596)
		(width 0.16002)
		(layer "In4.Cu")
		(net "M_J_CPU1_CLK_DP<0>")
	)
	(segment
		(start 147.775168 -257.313176)
		(end 147.79879 -257.313176)
		(width 0.09525)
		(layer "In4.Cu")
		(net "M_J_CPU1_CLK_DP<0>")
	)
	(segment
		(start 143.914876 -256.154428)
		(end 143.923258 -256.149602)
		(width 0.09525)
		(layer "In4.Cu")
		(net "M_J_CPU1_CLK_DP<0>")
	)
	(segment
		(start 147.715986 -257.372358)
		(end 147.775168 -257.313176)
		(width 0.09525)
		(layer "In4.Cu")
		(net "M_J_CPU1_CLK_DP<0>")
	)
	(segment
		(start 177.539904 -257.253994)
		(end 177.539904 -256.863596)
		(width 0.16002)
		(layer "In4.Cu")
		(net "M_J_CPU1_CLK_DP<0>")
	)
	(segment
		(start 136.394952 -256.154428)
		(end 136.403334 -256.149602)
		(width 0.09525)
		(layer "In4.Cu")
		(net "M_J_CPU1_CLK_DP<0>")
	)
	(segment
		(start 177.539904 -256.863596)
		(end 177.942494 -256.461006)
		(width 0.16002)
		(layer "In4.Cu")
		(net "M_J_CPU1_CLK_DP<0>")
	)
	(segment
		(start 186.786266 -253.70917)
		(end 187.060078 -253.435358)
		(width 0.16002)
		(layer "In4.Cu")
		(net "M_J_CPU1_CLK_DP<0>")
	)
	(segment
		(start 143.923258 -256.149602)
		(end 143.93799 -256.140966)
		(width 0.09525)
		(layer "In4.Cu")
		(net "M_J_CPU1_CLK_DP<0>")
	)
	(segment
		(start 185.83275 -254.046228)
		(end 186.169808 -253.70917)
		(width 0.16002)
		(layer "In4.Cu")
		(net "M_J_CPU1_CLK_DP<0>")
	)
	(segment
		(start 132.45465 -255.824482)
		(end 132.608574 -256.089912)
		(width 0.09525)
		(layer "In4.Cu")
		(net "M_J_CPU1_CLK_DP<0>")
	)
	(segment
		(start 133.206236 -256.149602)
		(end 133.214618 -256.154428)
		(width 0.09525)
		(layer "In4.Cu")
		(net "M_J_CPU1_CLK_DP<0>")
	)
	(segment
		(start 185.83275 -255.173226)
		(end 185.83275 -254.046228)
		(width 0.16002)
		(layer "In4.Cu")
		(net "M_J_CPU1_CLK_DP<0>")
	)
	(segment
		(start 146.675602 -257.372358)
		(end 147.715986 -257.372358)
		(width 0.09525)
		(layer "In4.Cu")
		(net "M_J_CPU1_CLK_DP<0>")
	)
	(segment
		(start 184.54497 -256.461006)
		(end 185.83275 -255.173226)
		(width 0.16002)
		(layer "In4.Cu")
		(net "M_J_CPU1_CLK_DP<0>")
	)
	(segment
		(start 176.77003 -257.253994)
		(end 176.995582 -257.479546)
		(width 0.16002)
		(layer "In4.Cu")
		(net "M_J_CPU1_CLK_DP<0>")
	)
	(segment
		(start 180.086762 -256.461006)
		(end 184.54497 -256.461006)
		(width 0.16002)
		(layer "In4.Cu")
		(net "M_J_CPU1_CLK_DP<0>")
	)
	(segment
		(start 141.666214 -256.149602)
		(end 141.674596 -256.154428)
		(width 0.09525)
		(layer "In4.Cu")
		(net "M_J_CPU1_CLK_DP<0>")
	)
	(segment
		(start 141.094968 -256.154428)
		(end 141.10335 -256.149602)
		(width 0.09525)
		(layer "In4.Cu")
		(net "M_J_CPU1_CLK_DP<0>")
	)
	(segment
		(start 145.541238 -256.237994)
		(end 146.675602 -257.372358)
		(width 0.09525)
		(layer "In4.Cu")
		(net "M_J_CPU1_CLK_DP<0>")
	)
	(segment
		(start 178.914298 -257.253994)
		(end 179.13985 -257.479546)
		(width 0.16002)
		(layer "In4.Cu")
		(net "M_J_CPU1_CLK_DP<0>")
	)
	(segment
		(start 152.343358 -255.826006)
		(end 156.09443 -255.826006)
		(width 0.16002)
		(layer "In4.Cu")
		(net "M_J_CPU1_CLK_DP<0>")
	)
	(segment
		(start 156.72943 -256.461006)
		(end 176.36744 -256.461006)
		(width 0.16002)
		(layer "In4.Cu")
		(net "M_J_CPU1_CLK_DP<0>")
	)
	(segment
		(start 179.684172 -257.253994)
		(end 179.684172 -256.863596)
		(width 0.16002)
		(layer "In4.Cu")
		(net "M_J_CPU1_CLK_DP<0>")
	)
	(segment
		(start 186.169808 -253.70917)
		(end 186.786266 -253.70917)
		(width 0.16002)
		(layer "In4.Cu")
		(net "M_J_CPU1_CLK_DP<0>")
	)
	(arc
		(start 134.523226 -256.149602)
		(mid 134.804658 -256.073847)
		(end 135.08609 -256.149602)
		(width 0.09525)
		(layer "In4.Cu")
		(net "M_J_CPU1_CLK_DP<0>")
	)
	(arc
		(start 142.983204 -256.149602)
		(mid 143.264636 -256.073847)
		(end 143.546068 -256.149602)
		(width 0.09525)
		(layer "In4.Cu")
		(net "M_J_CPU1_CLK_DP<0>")
	)
	(arc
		(start 138.846306 -256.149602)
		(mid 139.034774 -256.200279)
		(end 139.223242 -256.149602)
		(width 0.09525)
		(layer "In4.Cu")
		(net "M_J_CPU1_CLK_DP<0>")
	)
	(arc
		(start 135.08609 -256.149602)
		(mid 135.269865 -256.200374)
		(end 135.454898 -256.154428)
		(width 0.09525)
		(layer "In4.Cu")
		(net "M_J_CPU1_CLK_DP<0>")
	)
	(arc
		(start 133.583426 -256.149602)
		(mid 133.864858 -256.073847)
		(end 134.14629 -256.149602)
		(width 0.09525)
		(layer "In4.Cu")
		(net "M_J_CPU1_CLK_DP<0>")
	)
	(arc
		(start 139.223242 -256.149602)
		(mid 139.504674 -256.073847)
		(end 139.786106 -256.149602)
		(width 0.09525)
		(layer "In4.Cu")
		(net "M_J_CPU1_CLK_DP<0>")
	)
	(arc
		(start 136.026144 -256.149602)
		(mid 136.209919 -256.200374)
		(end 136.394952 -256.154428)
		(width 0.09525)
		(layer "In4.Cu")
		(net "M_J_CPU1_CLK_DP<0>")
	)
	(arc
		(start 142.043404 -256.149602)
		(mid 142.324836 -256.073847)
		(end 142.606268 -256.149602)
		(width 0.09525)
		(layer "In4.Cu")
		(net "M_J_CPU1_CLK_DP<0>")
	)
	(arc
		(start 133.214618 -256.154428)
		(mid 133.39965 -256.200342)
		(end 133.583426 -256.149602)
		(width 0.09525)
		(layer "In4.Cu")
		(net "M_J_CPU1_CLK_DP<0>")
	)
	(arc
		(start 144.48663 -256.149602)
		(mid 144.666909 -256.200433)
		(end 144.849342 -256.157984)
		(width 0.09525)
		(layer "In4.Cu")
		(net "M_J_CPU1_CLK_DP<0>")
	)
	(arc
		(start 136.97458 -256.154428)
		(mid 137.159612 -256.200342)
		(end 137.343388 -256.149602)
		(width 0.09525)
		(layer "In4.Cu")
		(net "M_J_CPU1_CLK_DP<0>")
	)
	(arc
		(start 137.343388 -256.149602)
		(mid 137.62482 -256.073847)
		(end 137.906252 -256.149602)
		(width 0.09525)
		(layer "In4.Cu")
		(net "M_J_CPU1_CLK_DP<0>")
	)
	(arc
		(start 142.606268 -256.149602)
		(mid 142.794736 -256.200279)
		(end 142.983204 -256.149602)
		(width 0.09525)
		(layer "In4.Cu")
		(net "M_J_CPU1_CLK_DP<0>")
	)
	(arc
		(start 137.914634 -256.154428)
		(mid 138.099666 -256.200342)
		(end 138.283442 -256.149602)
		(width 0.09525)
		(layer "In4.Cu")
		(net "M_J_CPU1_CLK_DP<0>")
	)
	(arc
		(start 145.426684 -256.149602)
		(mid 145.486819 -256.190093)
		(end 145.541238 -256.237994)
		(width 0.09525)
		(layer "In4.Cu")
		(net "M_J_CPU1_CLK_DP<0>")
	)
	(arc
		(start 138.283442 -256.149602)
		(mid 138.564874 -256.073847)
		(end 138.846306 -256.149602)
		(width 0.09525)
		(layer "In4.Cu")
		(net "M_J_CPU1_CLK_DP<0>")
	)
	(arc
		(start 141.10335 -256.149602)
		(mid 141.384782 -256.073847)
		(end 141.666214 -256.149602)
		(width 0.09525)
		(layer "In4.Cu")
		(net "M_J_CPU1_CLK_DP<0>")
	)
	(arc
		(start 144.884648 -256.13741)
		(mid 145.157253 -256.073614)
		(end 145.426684 -256.149602)
		(width 0.09525)
		(layer "In4.Cu")
		(net "M_J_CPU1_CLK_DP<0>")
	)
	(arc
		(start 132.709412 -256.116582)
		(mid 132.961696 -256.074888)
		(end 133.206236 -256.149602)
		(width 0.09525)
		(layer "In4.Cu")
		(net "M_J_CPU1_CLK_DP<0>")
	)
	(arc
		(start 143.546068 -256.149602)
		(mid 143.729843 -256.200374)
		(end 143.914876 -256.154428)
		(width 0.09525)
		(layer "In4.Cu")
		(net "M_J_CPU1_CLK_DP<0>")
	)
	(arc
		(start 140.163296 -256.149602)
		(mid 140.444728 -256.073847)
		(end 140.72616 -256.149602)
		(width 0.09525)
		(layer "In4.Cu")
		(net "M_J_CPU1_CLK_DP<0>")
	)
	(arc
		(start 136.403334 -256.149602)
		(mid 136.684766 -256.073847)
		(end 136.966198 -256.149602)
		(width 0.09525)
		(layer "In4.Cu")
		(net "M_J_CPU1_CLK_DP<0>")
	)
	(arc
		(start 134.14629 -256.149602)
		(mid 134.334758 -256.200279)
		(end 134.523226 -256.149602)
		(width 0.09525)
		(layer "In4.Cu")
		(net "M_J_CPU1_CLK_DP<0>")
	)
	(arc
		(start 143.93799 -256.140966)
		(mid 144.213449 -256.073581)
		(end 144.48663 -256.149602)
		(width 0.09525)
		(layer "In4.Cu")
		(net "M_J_CPU1_CLK_DP<0>")
	)
	(arc
		(start 140.72616 -256.149602)
		(mid 140.909935 -256.200374)
		(end 141.094968 -256.154428)
		(width 0.09525)
		(layer "In4.Cu")
		(net "M_J_CPU1_CLK_DP<0>")
	)
	(arc
		(start 135.46328 -256.149602)
		(mid 135.744712 -256.073847)
		(end 136.026144 -256.149602)
		(width 0.09525)
		(layer "In4.Cu")
		(net "M_J_CPU1_CLK_DP<0>")
	)
	(arc
		(start 139.786106 -256.149602)
		(mid 139.969881 -256.200374)
		(end 140.154914 -256.154428)
		(width 0.09525)
		(layer "In4.Cu")
		(net "M_J_CPU1_CLK_DP<0>")
	)
	(arc
		(start 141.674596 -256.154428)
		(mid 141.859628 -256.200342)
		(end 142.043404 -256.149602)
		(width 0.09525)
		(layer "In4.Cu")
		(net "M_J_CPU1_CLK_DP<0>")
	)
	(segment
		(start 132.457952 -256.900426)
		(end 132.924804 -256.634488)
		(width 0.14732)
		(layer "F.Cu")
		(net "M_J_CPU1_CLK_DN<0>")
	)
	(segment
		(start 137.804906 -256.304542)
		(end 137.813288 -256.309368)
		(width 0.09525)
		(layer "In4.Cu")
		(net "M_J_CPU1_CLK_DN<0>")
	)
	(segment
		(start 139.316206 -256.309368)
		(end 139.324588 -256.304542)
		(width 0.09525)
		(layer "In4.Cu")
		(net "M_J_CPU1_CLK_DN<0>")
	)
	(segment
		(start 186.29503 -254.01143)
		(end 186.786266 -254.01143)
		(width 0.16002)
		(layer "In4.Cu")
		(net "M_J_CPU1_CLK_DN<0>")
	)
	(segment
		(start 134.044944 -256.304542)
		(end 134.053326 -256.309368)
		(width 0.09525)
		(layer "In4.Cu")
		(net "M_J_CPU1_CLK_DN<0>")
	)
	(segment
		(start 176.46777 -256.988818)
		(end 176.46777 -257.379216)
		(width 0.16002)
		(layer "In4.Cu")
		(net "M_J_CPU1_CLK_DN<0>")
	)
	(segment
		(start 185.795666 -255.637792)
		(end 186.13501 -255.298448)
		(width 0.16002)
		(layer "In4.Cu")
		(net "M_J_CPU1_CLK_DN<0>")
	)
	(segment
		(start 177.439574 -257.781806)
		(end 177.842164 -257.379216)
		(width 0.16002)
		(layer "In4.Cu")
		(net "M_J_CPU1_CLK_DN<0>")
	)
	(segment
		(start 152.46858 -256.128266)
		(end 155.969208 -256.128266)
		(width 0.16002)
		(layer "In4.Cu")
		(net "M_J_CPU1_CLK_DN<0>")
	)
	(segment
		(start 156.604208 -256.763266)
		(end 176.242218 -256.763266)
		(width 0.16002)
		(layer "In4.Cu")
		(net "M_J_CPU1_CLK_DN<0>")
	)
	(segment
		(start 186.13501 -255.298448)
		(end 186.13501 -254.17145)
		(width 0.16002)
		(layer "In4.Cu")
		(net "M_J_CPU1_CLK_DN<0>")
	)
	(segment
		(start 138.74496 -256.304542)
		(end 138.753342 -256.309368)
		(width 0.09525)
		(layer "In4.Cu")
		(net "M_J_CPU1_CLK_DN<0>")
	)
	(segment
		(start 178.612038 -256.988818)
		(end 178.612038 -257.379216)
		(width 0.16002)
		(layer "In4.Cu")
		(net "M_J_CPU1_CLK_DN<0>")
	)
	(segment
		(start 176.87036 -257.781806)
		(end 177.439574 -257.781806)
		(width 0.16002)
		(layer "In4.Cu")
		(net "M_J_CPU1_CLK_DN<0>")
	)
	(segment
		(start 147.79879 -257.615436)
		(end 150.98141 -257.615436)
		(width 0.16002)
		(layer "In4.Cu")
		(net "M_J_CPU1_CLK_DN<0>")
	)
	(segment
		(start 132.77088 -256.369058)
		(end 132.794248 -256.28219)
		(width 0.09525)
		(layer "In4.Cu")
		(net "M_J_CPU1_CLK_DN<0>")
	)
	(segment
		(start 186.13501 -254.17145)
		(end 186.29503 -254.01143)
		(width 0.16002)
		(layer "In4.Cu")
		(net "M_J_CPU1_CLK_DN<0>")
	)
	(segment
		(start 185.795666 -255.802892)
		(end 185.795666 -255.637792)
		(width 0.16002)
		(layer "In4.Cu")
		(net "M_J_CPU1_CLK_DN<0>")
	)
	(segment
		(start 179.014628 -257.781806)
		(end 179.583842 -257.781806)
		(width 0.16002)
		(layer "In4.Cu")
		(net "M_J_CPU1_CLK_DN<0>")
	)
	(segment
		(start 185.290714 -256.142744)
		(end 185.456068 -256.142744)
		(width 0.16002)
		(layer "In4.Cu")
		(net "M_J_CPU1_CLK_DN<0>")
	)
	(segment
		(start 135.556244 -256.309368)
		(end 135.564626 -256.304542)
		(width 0.09525)
		(layer "In4.Cu")
		(net "M_J_CPU1_CLK_DN<0>")
	)
	(segment
		(start 150.98141 -257.615436)
		(end 152.46858 -256.128266)
		(width 0.16002)
		(layer "In4.Cu")
		(net "M_J_CPU1_CLK_DN<0>")
	)
	(segment
		(start 177.842164 -256.988818)
		(end 178.067716 -256.763266)
		(width 0.16002)
		(layer "In4.Cu")
		(net "M_J_CPU1_CLK_DN<0>")
	)
	(segment
		(start 176.242218 -256.763266)
		(end 176.46777 -256.988818)
		(width 0.16002)
		(layer "In4.Cu")
		(net "M_J_CPU1_CLK_DN<0>")
	)
	(segment
		(start 184.670192 -256.763266)
		(end 185.290714 -256.142744)
		(width 0.16002)
		(layer "In4.Cu")
		(net "M_J_CPU1_CLK_DN<0>")
	)
	(segment
		(start 177.842164 -257.379216)
		(end 177.842164 -256.988818)
		(width 0.16002)
		(layer "In4.Cu")
		(net "M_J_CPU1_CLK_DN<0>")
	)
	(segment
		(start 146.599148 -257.556508)
		(end 147.71624 -257.556508)
		(width 0.09525)
		(layer "In4.Cu")
		(net "M_J_CPU1_CLK_DN<0>")
	)
	(segment
		(start 144.95653 -256.309368)
		(end 144.971008 -256.300986)
		(width 0.09525)
		(layer "In4.Cu")
		(net "M_J_CPU1_CLK_DN<0>")
	)
	(segment
		(start 147.71624 -257.556508)
		(end 147.775168 -257.615436)
		(width 0.09525)
		(layer "In4.Cu")
		(net "M_J_CPU1_CLK_DN<0>")
	)
	(segment
		(start 144.935702 -256.32156)
		(end 144.95653 -256.309368)
		(width 0.09525)
		(layer "In4.Cu")
		(net "M_J_CPU1_CLK_DN<0>")
	)
	(segment
		(start 178.067716 -256.763266)
		(end 178.386486 -256.763266)
		(width 0.16002)
		(layer "In4.Cu")
		(net "M_J_CPU1_CLK_DN<0>")
	)
	(segment
		(start 134.61619 -256.309368)
		(end 134.624572 -256.304542)
		(width 0.09525)
		(layer "In4.Cu")
		(net "M_J_CPU1_CLK_DN<0>")
	)
	(segment
		(start 178.612038 -257.379216)
		(end 179.014628 -257.781806)
		(width 0.16002)
		(layer "In4.Cu")
		(net "M_J_CPU1_CLK_DN<0>")
	)
	(segment
		(start 176.46777 -257.379216)
		(end 176.87036 -257.781806)
		(width 0.16002)
		(layer "In4.Cu")
		(net "M_J_CPU1_CLK_DN<0>")
	)
	(segment
		(start 145.410936 -256.368296)
		(end 146.599148 -257.556508)
		(width 0.09525)
		(layer "In4.Cu")
		(net "M_J_CPU1_CLK_DN<0>")
	)
	(segment
		(start 144.016222 -256.309368)
		(end 144.02816 -256.30251)
		(width 0.09525)
		(layer "In4.Cu")
		(net "M_J_CPU1_CLK_DN<0>")
	)
	(segment
		(start 180.211984 -256.763266)
		(end 184.670192 -256.763266)
		(width 0.16002)
		(layer "In4.Cu")
		(net "M_J_CPU1_CLK_DN<0>")
	)
	(segment
		(start 132.924804 -256.634488)
		(end 132.77088 -256.369058)
		(width 0.09525)
		(layer "In4.Cu")
		(net "M_J_CPU1_CLK_DN<0>")
	)
	(segment
		(start 133.10489 -256.304542)
		(end 133.113272 -256.309368)
		(width 0.09525)
		(layer "In4.Cu")
		(net "M_J_CPU1_CLK_DN<0>")
	)
	(segment
		(start 178.386486 -256.763266)
		(end 178.612038 -256.988818)
		(width 0.16002)
		(layer "In4.Cu")
		(net "M_J_CPU1_CLK_DN<0>")
	)
	(segment
		(start 155.969208 -256.128266)
		(end 156.604208 -256.763266)
		(width 0.16002)
		(layer "In4.Cu")
		(net "M_J_CPU1_CLK_DN<0>")
	)
	(segment
		(start 179.986432 -257.379216)
		(end 179.986432 -256.988818)
		(width 0.16002)
		(layer "In4.Cu")
		(net "M_J_CPU1_CLK_DN<0>")
	)
	(segment
		(start 147.775168 -257.615436)
		(end 147.79879 -257.615436)
		(width 0.09525)
		(layer "In4.Cu")
		(net "M_J_CPU1_CLK_DN<0>")
	)
	(segment
		(start 186.786266 -254.01143)
		(end 187.060078 -254.285242)
		(width 0.16002)
		(layer "In4.Cu")
		(net "M_J_CPU1_CLK_DN<0>")
	)
	(segment
		(start 185.456068 -256.142744)
		(end 185.795666 -255.802892)
		(width 0.16002)
		(layer "In4.Cu")
		(net "M_J_CPU1_CLK_DN<0>")
	)
	(segment
		(start 140.25626 -256.309368)
		(end 140.264642 -256.304542)
		(width 0.09525)
		(layer "In4.Cu")
		(net "M_J_CPU1_CLK_DN<0>")
	)
	(segment
		(start 179.986432 -256.988818)
		(end 180.211984 -256.763266)
		(width 0.16002)
		(layer "In4.Cu")
		(net "M_J_CPU1_CLK_DN<0>")
	)
	(segment
		(start 143.076168 -256.309368)
		(end 143.08455 -256.304542)
		(width 0.09525)
		(layer "In4.Cu")
		(net "M_J_CPU1_CLK_DN<0>")
	)
	(segment
		(start 142.504922 -256.304542)
		(end 142.513304 -256.309368)
		(width 0.09525)
		(layer "In4.Cu")
		(net "M_J_CPU1_CLK_DN<0>")
	)
	(segment
		(start 179.583842 -257.781806)
		(end 179.986432 -257.379216)
		(width 0.16002)
		(layer "In4.Cu")
		(net "M_J_CPU1_CLK_DN<0>")
	)
	(arc
		(start 134.053326 -256.309368)
		(mid 134.334758 -256.385123)
		(end 134.61619 -256.309368)
		(width 0.09525)
		(layer "In4.Cu")
		(net "M_J_CPU1_CLK_DN<0>")
	)
	(arc
		(start 133.113272 -256.309368)
		(mid 133.394704 -256.385123)
		(end 133.676136 -256.309368)
		(width 0.09525)
		(layer "In4.Cu")
		(net "M_J_CPU1_CLK_DN<0>")
	)
	(arc
		(start 141.57325 -256.309368)
		(mid 141.854682 -256.385123)
		(end 142.136114 -256.309368)
		(width 0.09525)
		(layer "In4.Cu")
		(net "M_J_CPU1_CLK_DN<0>")
	)
	(arc
		(start 141.196314 -256.309368)
		(mid 141.384782 -256.258691)
		(end 141.57325 -256.309368)
		(width 0.09525)
		(layer "In4.Cu")
		(net "M_J_CPU1_CLK_DN<0>")
	)
	(arc
		(start 137.813288 -256.309368)
		(mid 138.09472 -256.385123)
		(end 138.376152 -256.309368)
		(width 0.09525)
		(layer "In4.Cu")
		(net "M_J_CPU1_CLK_DN<0>")
	)
	(arc
		(start 144.971008 -256.300986)
		(mid 145.15344 -256.258546)
		(end 145.33372 -256.309368)
		(width 0.09525)
		(layer "In4.Cu")
		(net "M_J_CPU1_CLK_DN<0>")
	)
	(arc
		(start 145.33372 -256.309368)
		(mid 145.374244 -256.336323)
		(end 145.410936 -256.368296)
		(width 0.09525)
		(layer "In4.Cu")
		(net "M_J_CPU1_CLK_DN<0>")
	)
	(arc
		(start 136.873234 -256.309368)
		(mid 137.154666 -256.385123)
		(end 137.436098 -256.309368)
		(width 0.09525)
		(layer "In4.Cu")
		(net "M_J_CPU1_CLK_DN<0>")
	)
	(arc
		(start 140.264642 -256.304542)
		(mid 140.449674 -256.258628)
		(end 140.63345 -256.309368)
		(width 0.09525)
		(layer "In4.Cu")
		(net "M_J_CPU1_CLK_DN<0>")
	)
	(arc
		(start 143.453358 -256.309368)
		(mid 143.73479 -256.385123)
		(end 144.016222 -256.309368)
		(width 0.09525)
		(layer "In4.Cu")
		(net "M_J_CPU1_CLK_DN<0>")
	)
	(arc
		(start 137.436098 -256.309368)
		(mid 137.619873 -256.258596)
		(end 137.804906 -256.304542)
		(width 0.09525)
		(layer "In4.Cu")
		(net "M_J_CPU1_CLK_DN<0>")
	)
	(arc
		(start 138.753342 -256.309368)
		(mid 139.034774 -256.385123)
		(end 139.316206 -256.309368)
		(width 0.09525)
		(layer "In4.Cu")
		(net "M_J_CPU1_CLK_DN<0>")
	)
	(arc
		(start 138.376152 -256.309368)
		(mid 138.559927 -256.258596)
		(end 138.74496 -256.304542)
		(width 0.09525)
		(layer "In4.Cu")
		(net "M_J_CPU1_CLK_DN<0>")
	)
	(arc
		(start 135.933434 -256.309368)
		(mid 136.214866 -256.385123)
		(end 136.496298 -256.309368)
		(width 0.09525)
		(layer "In4.Cu")
		(net "M_J_CPU1_CLK_DN<0>")
	)
	(arc
		(start 142.513304 -256.309368)
		(mid 142.794736 -256.385123)
		(end 143.076168 -256.309368)
		(width 0.09525)
		(layer "In4.Cu")
		(net "M_J_CPU1_CLK_DN<0>")
	)
	(arc
		(start 142.136114 -256.309368)
		(mid 142.319889 -256.258596)
		(end 142.504922 -256.304542)
		(width 0.09525)
		(layer "In4.Cu")
		(net "M_J_CPU1_CLK_DN<0>")
	)
	(arc
		(start 140.63345 -256.309368)
		(mid 140.914882 -256.385123)
		(end 141.196314 -256.309368)
		(width 0.09525)
		(layer "In4.Cu")
		(net "M_J_CPU1_CLK_DN<0>")
	)
	(arc
		(start 132.794248 -256.28219)
		(mid 132.951998 -256.259671)
		(end 133.10489 -256.304542)
		(width 0.09525)
		(layer "In4.Cu")
		(net "M_J_CPU1_CLK_DN<0>")
	)
	(arc
		(start 134.99338 -256.309368)
		(mid 135.274812 -256.385123)
		(end 135.556244 -256.309368)
		(width 0.09525)
		(layer "In4.Cu")
		(net "M_J_CPU1_CLK_DN<0>")
	)
	(arc
		(start 136.496298 -256.309368)
		(mid 136.684766 -256.258691)
		(end 136.873234 -256.309368)
		(width 0.09525)
		(layer "In4.Cu")
		(net "M_J_CPU1_CLK_DN<0>")
	)
	(arc
		(start 133.676136 -256.309368)
		(mid 133.859911 -256.258596)
		(end 134.044944 -256.304542)
		(width 0.09525)
		(layer "In4.Cu")
		(net "M_J_CPU1_CLK_DN<0>")
	)
	(arc
		(start 135.564626 -256.304542)
		(mid 135.749658 -256.258628)
		(end 135.933434 -256.309368)
		(width 0.09525)
		(layer "In4.Cu")
		(net "M_J_CPU1_CLK_DN<0>")
	)
	(arc
		(start 134.624572 -256.304542)
		(mid 134.809604 -256.258628)
		(end 134.99338 -256.309368)
		(width 0.09525)
		(layer "In4.Cu")
		(net "M_J_CPU1_CLK_DN<0>")
	)
	(arc
		(start 144.393666 -256.309368)
		(mid 144.663099 -256.385239)
		(end 144.935702 -256.32156)
		(width 0.09525)
		(layer "In4.Cu")
		(net "M_J_CPU1_CLK_DN<0>")
	)
	(arc
		(start 143.08455 -256.304542)
		(mid 143.269582 -256.258628)
		(end 143.453358 -256.309368)
		(width 0.09525)
		(layer "In4.Cu")
		(net "M_J_CPU1_CLK_DN<0>")
	)
	(arc
		(start 139.324588 -256.304542)
		(mid 139.50962 -256.258628)
		(end 139.693396 -256.309368)
		(width 0.09525)
		(layer "In4.Cu")
		(net "M_J_CPU1_CLK_DN<0>")
	)
	(arc
		(start 144.02816 -256.30251)
		(mid 144.211795 -256.25856)
		(end 144.393666 -256.309368)
		(width 0.09525)
		(layer "In4.Cu")
		(net "M_J_CPU1_CLK_DN<0>")
	)
	(arc
		(start 139.693396 -256.309368)
		(mid 139.974828 -256.385123)
		(end 140.25626 -256.309368)
		(width 0.09525)
		(layer "In4.Cu")
		(net "M_J_CPU1_CLK_DN<0>")
	)
	(segment
		(start 130.577844 -250.420378)
		(end 131.044696 -250.15444)
		(width 0.10668)
		(layer "F.Cu")
		(net "M_J_CPU1_ALERT_R_N")
	)
	(segment
		(start 180.824378 -246.210328)
		(end 182.5244 -244.510306)
		(width 0.11684)
		(layer "In4.Cu")
		(net "M_J_CPU1_ALERT_R_N")
	)
	(segment
		(start 135.557768 -250.47702)
		(end 135.56615 -250.481846)
		(width 0.0889)
		(layer "In4.Cu")
		(net "M_J_CPU1_ALERT_R_N")
	)
	(segment
		(start 139.31773 -250.47702)
		(end 139.326112 -250.481846)
		(width 0.0889)
		(layer "In4.Cu")
		(net "M_J_CPU1_ALERT_R_N")
	)
	(segment
		(start 134.617714 -250.47702)
		(end 134.626096 -250.481846)
		(width 0.0889)
		(layer "In4.Cu")
		(net "M_J_CPU1_ALERT_R_N")
	)
	(segment
		(start 143.451834 -250.47702)
		(end 143.466566 -250.468384)
		(width 0.0889)
		(layer "In4.Cu")
		(net "M_J_CPU1_ALERT_R_N")
	)
	(segment
		(start 144.380966 -250.483878)
		(end 144.39265 -250.47702)
		(width 0.0889)
		(layer "In4.Cu")
		(net "M_J_CPU1_ALERT_R_N")
	)
	(segment
		(start 147.324318 -250.210066)
		(end 147.47875 -250.210066)
		(width 0.0889)
		(layer "In4.Cu")
		(net "M_J_CPU1_ALERT_R_N")
	)
	(segment
		(start 144.952466 -250.473464)
		(end 144.958054 -250.476766)
		(width 0.0889)
		(layer "In4.Cu")
		(net "M_J_CPU1_ALERT_R_N")
	)
	(segment
		(start 142.503398 -250.481846)
		(end 142.51178 -250.47702)
		(width 0.0889)
		(layer "In4.Cu")
		(net "M_J_CPU1_ALERT_R_N")
	)
	(segment
		(start 182.5244 -244.510306)
		(end 189.338204 -244.510306)
		(width 0.11684)
		(layer "In4.Cu")
		(net "M_J_CPU1_ALERT_R_N")
	)
	(segment
		(start 189.338204 -244.510306)
		(end 189.763146 -244.085364)
		(width 0.11684)
		(layer "In4.Cu")
		(net "M_J_CPU1_ALERT_R_N")
	)
	(segment
		(start 147.15744 -250.376944)
		(end 147.324318 -250.210066)
		(width 0.0889)
		(layer "In4.Cu")
		(net "M_J_CPU1_ALERT_R_N")
	)
	(segment
		(start 140.257784 -250.47702)
		(end 140.266166 -250.481846)
		(width 0.0889)
		(layer "In4.Cu")
		(net "M_J_CPU1_ALERT_R_N")
	)
	(segment
		(start 131.198874 -250.41987)
		(end 131.29514 -250.44527)
		(width 0.0889)
		(layer "In4.Cu")
		(net "M_J_CPU1_ALERT_R_N")
	)
	(segment
		(start 160.357312 -249.957336)
		(end 164.10432 -246.210328)
		(width 0.11684)
		(layer "In4.Cu")
		(net "M_J_CPU1_ALERT_R_N")
	)
	(segment
		(start 133.103366 -250.481846)
		(end 133.111748 -250.47702)
		(width 0.0889)
		(layer "In4.Cu")
		(net "M_J_CPU1_ALERT_R_N")
	)
	(segment
		(start 147.47875 -250.210066)
		(end 149.323806 -250.210066)
		(width 0.11684)
		(layer "In4.Cu")
		(net "M_J_CPU1_ALERT_R_N")
	)
	(segment
		(start 131.044696 -250.15444)
		(end 131.198874 -250.41987)
		(width 0.0889)
		(layer "In4.Cu")
		(net "M_J_CPU1_ALERT_R_N")
	)
	(segment
		(start 164.10432 -246.210328)
		(end 180.824378 -246.210328)
		(width 0.11684)
		(layer "In4.Cu")
		(net "M_J_CPU1_ALERT_R_N")
	)
	(segment
		(start 137.803382 -250.481846)
		(end 137.811764 -250.47702)
		(width 0.0889)
		(layer "In4.Cu")
		(net "M_J_CPU1_ALERT_R_N")
	)
	(segment
		(start 145.678906 -250.376944)
		(end 147.15744 -250.376944)
		(width 0.0889)
		(layer "In4.Cu")
		(net "M_J_CPU1_ALERT_R_N")
	)
	(segment
		(start 134.04342 -250.481846)
		(end 134.051802 -250.47702)
		(width 0.0889)
		(layer "In4.Cu")
		(net "M_J_CPU1_ALERT_R_N")
	)
	(segment
		(start 143.077692 -250.47702)
		(end 143.086074 -250.481846)
		(width 0.0889)
		(layer "In4.Cu")
		(net "M_J_CPU1_ALERT_R_N")
	)
	(segment
		(start 149.576536 -249.957336)
		(end 160.357312 -249.957336)
		(width 0.11684)
		(layer "In4.Cu")
		(net "M_J_CPU1_ALERT_R_N")
	)
	(segment
		(start 138.743436 -250.481846)
		(end 138.751818 -250.47702)
		(width 0.0889)
		(layer "In4.Cu")
		(net "M_J_CPU1_ALERT_R_N")
	)
	(segment
		(start 149.323806 -250.210066)
		(end 149.576536 -249.957336)
		(width 0.11684)
		(layer "In4.Cu")
		(net "M_J_CPU1_ALERT_R_N")
	)
	(segment
		(start 144.958054 -250.476766)
		(end 144.976342 -250.48718)
		(width 0.0889)
		(layer "In4.Cu")
		(net "M_J_CPU1_ALERT_R_N")
	)
	(arc
		(start 138.751818 -250.47702)
		(mid 139.034774 -250.400843)
		(end 139.31773 -250.47702)
		(width 0.0889)
		(layer "In4.Cu")
		(net "M_J_CPU1_ALERT_R_N")
	)
	(arc
		(start 139.326112 -250.481846)
		(mid 139.50962 -250.52734)
		(end 139.691872 -250.47702)
		(width 0.0889)
		(layer "In4.Cu")
		(net "M_J_CPU1_ALERT_R_N")
	)
	(arc
		(start 141.197838 -250.47702)
		(mid 141.384782 -250.527275)
		(end 141.571726 -250.47702)
		(width 0.0889)
		(layer "In4.Cu")
		(net "M_J_CPU1_ALERT_R_N")
	)
	(arc
		(start 136.497822 -250.47702)
		(mid 136.684766 -250.527275)
		(end 136.87171 -250.47702)
		(width 0.0889)
		(layer "In4.Cu")
		(net "M_J_CPU1_ALERT_R_N")
	)
	(arc
		(start 136.87171 -250.47702)
		(mid 137.154666 -250.400843)
		(end 137.437622 -250.47702)
		(width 0.0889)
		(layer "In4.Cu")
		(net "M_J_CPU1_ALERT_R_N")
	)
	(arc
		(start 137.437622 -250.47702)
		(mid 137.619873 -250.52737)
		(end 137.803382 -250.481846)
		(width 0.0889)
		(layer "In4.Cu")
		(net "M_J_CPU1_ALERT_R_N")
	)
	(arc
		(start 139.691872 -250.47702)
		(mid 139.974828 -250.400843)
		(end 140.257784 -250.47702)
		(width 0.0889)
		(layer "In4.Cu")
		(net "M_J_CPU1_ALERT_R_N")
	)
	(arc
		(start 134.991856 -250.47702)
		(mid 135.274812 -250.400843)
		(end 135.557768 -250.47702)
		(width 0.0889)
		(layer "In4.Cu")
		(net "M_J_CPU1_ALERT_R_N")
	)
	(arc
		(start 131.29514 -250.44527)
		(mid 131.550205 -250.401919)
		(end 131.797806 -250.47702)
		(width 0.0889)
		(layer "In4.Cu")
		(net "M_J_CPU1_ALERT_R_N")
	)
	(arc
		(start 133.67766 -250.47702)
		(mid 133.859911 -250.52737)
		(end 134.04342 -250.481846)
		(width 0.0889)
		(layer "In4.Cu")
		(net "M_J_CPU1_ALERT_R_N")
	)
	(arc
		(start 143.466566 -250.468384)
		(mid 143.743549 -250.40058)
		(end 144.018254 -250.47702)
		(width 0.0889)
		(layer "In4.Cu")
		(net "M_J_CPU1_ALERT_R_N")
	)
	(arc
		(start 143.086074 -250.481846)
		(mid 143.269582 -250.52734)
		(end 143.451834 -250.47702)
		(width 0.0889)
		(layer "In4.Cu")
		(net "M_J_CPU1_ALERT_R_N")
	)
	(arc
		(start 134.051802 -250.47702)
		(mid 134.334758 -250.400843)
		(end 134.617714 -250.47702)
		(width 0.0889)
		(layer "In4.Cu")
		(net "M_J_CPU1_ALERT_R_N")
	)
	(arc
		(start 135.93191 -250.47702)
		(mid 136.214866 -250.400843)
		(end 136.497822 -250.47702)
		(width 0.0889)
		(layer "In4.Cu")
		(net "M_J_CPU1_ALERT_R_N")
	)
	(arc
		(start 145.332196 -250.47702)
		(mid 145.499396 -250.405661)
		(end 145.678906 -250.376944)
		(width 0.0889)
		(layer "In4.Cu")
		(net "M_J_CPU1_ALERT_R_N")
	)
	(arc
		(start 142.137638 -250.47702)
		(mid 142.319889 -250.52737)
		(end 142.503398 -250.481846)
		(width 0.0889)
		(layer "In4.Cu")
		(net "M_J_CPU1_ALERT_R_N")
	)
	(arc
		(start 131.797806 -250.47702)
		(mid 131.98475 -250.527275)
		(end 132.171694 -250.47702)
		(width 0.0889)
		(layer "In4.Cu")
		(net "M_J_CPU1_ALERT_R_N")
	)
	(arc
		(start 144.976342 -250.48718)
		(mid 145.155571 -250.527333)
		(end 145.332196 -250.47702)
		(width 0.0889)
		(layer "In4.Cu")
		(net "M_J_CPU1_ALERT_R_N")
	)
	(arc
		(start 137.811764 -250.47702)
		(mid 138.09472 -250.400843)
		(end 138.377676 -250.47702)
		(width 0.0889)
		(layer "In4.Cu")
		(net "M_J_CPU1_ALERT_R_N")
	)
	(arc
		(start 133.111748 -250.47702)
		(mid 133.394704 -250.400843)
		(end 133.67766 -250.47702)
		(width 0.0889)
		(layer "In4.Cu")
		(net "M_J_CPU1_ALERT_R_N")
	)
	(arc
		(start 132.171694 -250.47702)
		(mid 132.45465 -250.400843)
		(end 132.737606 -250.47702)
		(width 0.0889)
		(layer "In4.Cu")
		(net "M_J_CPU1_ALERT_R_N")
	)
	(arc
		(start 135.56615 -250.481846)
		(mid 135.749658 -250.52734)
		(end 135.93191 -250.47702)
		(width 0.0889)
		(layer "In4.Cu")
		(net "M_J_CPU1_ALERT_R_N")
	)
	(arc
		(start 144.018254 -250.47702)
		(mid 144.198712 -250.527464)
		(end 144.380966 -250.483878)
		(width 0.0889)
		(layer "In4.Cu")
		(net "M_J_CPU1_ALERT_R_N")
	)
	(arc
		(start 142.51178 -250.47702)
		(mid 142.794736 -250.400843)
		(end 143.077692 -250.47702)
		(width 0.0889)
		(layer "In4.Cu")
		(net "M_J_CPU1_ALERT_R_N")
	)
	(arc
		(start 141.571726 -250.47702)
		(mid 141.854682 -250.400843)
		(end 142.137638 -250.47702)
		(width 0.0889)
		(layer "In4.Cu")
		(net "M_J_CPU1_ALERT_R_N")
	)
	(arc
		(start 144.39265 -250.47702)
		(mid 144.672078 -250.400854)
		(end 144.952466 -250.473464)
		(width 0.0889)
		(layer "In4.Cu")
		(net "M_J_CPU1_ALERT_R_N")
	)
	(arc
		(start 132.737606 -250.47702)
		(mid 132.919857 -250.52737)
		(end 133.103366 -250.481846)
		(width 0.0889)
		(layer "In4.Cu")
		(net "M_J_CPU1_ALERT_R_N")
	)
	(arc
		(start 134.626096 -250.481846)
		(mid 134.809604 -250.52734)
		(end 134.991856 -250.47702)
		(width 0.0889)
		(layer "In4.Cu")
		(net "M_J_CPU1_ALERT_R_N")
	)
	(arc
		(start 138.377676 -250.47702)
		(mid 138.559927 -250.52737)
		(end 138.743436 -250.481846)
		(width 0.0889)
		(layer "In4.Cu")
		(net "M_J_CPU1_ALERT_R_N")
	)
	(arc
		(start 140.266166 -250.481846)
		(mid 140.449674 -250.52734)
		(end 140.631926 -250.47702)
		(width 0.0889)
		(layer "In4.Cu")
		(net "M_J_CPU1_ALERT_R_N")
	)
	(arc
		(start 140.631926 -250.47702)
		(mid 140.914882 -250.400843)
		(end 141.197838 -250.47702)
		(width 0.0889)
		(layer "In4.Cu")
		(net "M_J_CPU1_ALERT_R_N")
	)
	(via
		(at 191.160146 -244.085364)
		(size 0.4826)
		(drill 0.254)
		(layers "F.Cu" "B.Cu")
		(net "M_J_CPU1_ALERT_N")
	)
	(segment
		(start 190.563246 -244.085364)
		(end 191.160146 -244.085364)
		(width 0.10668)
		(layer "B.Cu")
		(net "M_J_CPU1_ALERT_N")
	)
	(segment
		(start 380.697994 -267.34008)
		(end 381.164846 -267.606018)
		(width 0.10668)
		(layer "F.Cu")
		(net "M_J_CPU0_SB_RSP<0>")
	)
	(segment
		(start 412.478982 -270.860266)
		(end 413.157416 -270.860266)
		(width 0.11684)
		(layer "In4.Cu")
		(net "M_J_CPU0_SB_RSP<0>")
	)
	(segment
		(start 395.713458 -266.57046)
		(end 408.189176 -266.57046)
		(width 0.11684)
		(layer "In4.Cu")
		(net "M_J_CPU0_SB_RSP<0>")
	)
	(segment
		(start 382.857756 -267.928598)
		(end 382.866138 -267.933424)
		(width 0.0889)
		(layer "In4.Cu")
		(net "M_J_CPU0_SB_RSP<0>")
	)
	(segment
		(start 419.63721 -270.860266)
		(end 420.57955 -270.860266)
		(width 0.11684)
		(layer "In4.Cu")
		(net "M_J_CPU0_SB_RSP<0>")
	)
	(segment
		(start 413.157416 -270.860266)
		(end 415.20999 -270.010128)
		(width 0.11684)
		(layer "In4.Cu")
		(net "M_J_CPU0_SB_RSP<0>")
	)
	(segment
		(start 392.62939 -267.928598)
		(end 392.652758 -267.914882)
		(width 0.0889)
		(layer "In4.Cu")
		(net "M_J_CPU0_SB_RSP<0>")
	)
	(segment
		(start 381.010922 -267.871448)
		(end 381.033274 -267.95476)
		(width 0.0889)
		(layer "In4.Cu")
		(net "M_J_CPU0_SB_RSP<0>")
	)
	(segment
		(start 383.79781 -267.928598)
		(end 383.806192 -267.933424)
		(width 0.0889)
		(layer "In4.Cu")
		(net "M_J_CPU0_SB_RSP<0>")
	)
	(segment
		(start 390.74344 -267.933424)
		(end 390.751822 -267.928598)
		(width 0.0889)
		(layer "In4.Cu")
		(net "M_J_CPU0_SB_RSP<0>")
	)
	(segment
		(start 392.234674 -267.915898)
		(end 392.256264 -267.928344)
		(width 0.0889)
		(layer "In4.Cu")
		(net "M_J_CPU0_SB_RSP<0>")
	)
	(segment
		(start 395.493748 -266.57046)
		(end 395.713458 -266.57046)
		(width 0.0889)
		(layer "In4.Cu")
		(net "M_J_CPU0_SB_RSP<0>")
	)
	(segment
		(start 386.983478 -267.933424)
		(end 386.99186 -267.928598)
		(width 0.0889)
		(layer "In4.Cu")
		(net "M_J_CPU0_SB_RSP<0>")
	)
	(segment
		(start 393.570714 -267.928344)
		(end 394.604748 -266.89431)
		(width 0.0889)
		(layer "In4.Cu")
		(net "M_J_CPU0_SB_RSP<0>")
	)
	(segment
		(start 386.043424 -267.933424)
		(end 386.051806 -267.928598)
		(width 0.0889)
		(layer "In4.Cu")
		(net "M_J_CPU0_SB_RSP<0>")
	)
	(segment
		(start 391.317734 -267.928598)
		(end 391.326116 -267.933424)
		(width 0.0889)
		(layer "In4.Cu")
		(net "M_J_CPU0_SB_RSP<0>")
	)
	(segment
		(start 387.557772 -267.928598)
		(end 387.566154 -267.933424)
		(width 0.0889)
		(layer "In4.Cu")
		(net "M_J_CPU0_SB_RSP<0>")
	)
	(segment
		(start 394.604748 -266.89431)
		(end 395.169898 -266.89431)
		(width 0.0889)
		(layer "In4.Cu")
		(net "M_J_CPU0_SB_RSP<0>")
	)
	(segment
		(start 415.20999 -270.010128)
		(end 417.584636 -270.010128)
		(width 0.11684)
		(layer "In4.Cu")
		(net "M_J_CPU0_SB_RSP<0>")
	)
	(segment
		(start 420.57955 -270.860266)
		(end 422.632124 -270.010128)
		(width 0.11684)
		(layer "In4.Cu")
		(net "M_J_CPU0_SB_RSP<0>")
	)
	(segment
		(start 392.256264 -267.928344)
		(end 392.274552 -267.938758)
		(width 0.0889)
		(layer "In4.Cu")
		(net "M_J_CPU0_SB_RSP<0>")
	)
	(segment
		(start 381.164846 -267.606018)
		(end 381.010922 -267.871448)
		(width 0.0889)
		(layer "In4.Cu")
		(net "M_J_CPU0_SB_RSP<0>")
	)
	(segment
		(start 408.189176 -266.57046)
		(end 412.478982 -270.860266)
		(width 0.11684)
		(layer "In4.Cu")
		(net "M_J_CPU0_SB_RSP<0>")
	)
	(segment
		(start 395.169898 -266.89431)
		(end 395.493748 -266.57046)
		(width 0.0889)
		(layer "In4.Cu")
		(net "M_J_CPU0_SB_RSP<0>")
	)
	(segment
		(start 382.283462 -267.933424)
		(end 382.291844 -267.928598)
		(width 0.0889)
		(layer "In4.Cu")
		(net "M_J_CPU0_SB_RSP<0>")
	)
	(segment
		(start 422.632124 -270.010128)
		(end 436.963566 -270.010128)
		(width 0.11684)
		(layer "In4.Cu")
		(net "M_J_CPU0_SB_RSP<0>")
	)
	(segment
		(start 388.497826 -267.928598)
		(end 388.506208 -267.933424)
		(width 0.0889)
		(layer "In4.Cu")
		(net "M_J_CPU0_SB_RSP<0>")
	)
	(segment
		(start 436.963566 -270.010128)
		(end 439.100214 -270.43507)
		(width 0.11684)
		(layer "In4.Cu")
		(net "M_J_CPU0_SB_RSP<0>")
	)
	(segment
		(start 417.584636 -270.010128)
		(end 419.63721 -270.860266)
		(width 0.11684)
		(layer "In4.Cu")
		(net "M_J_CPU0_SB_RSP<0>")
	)
	(segment
		(start 393.543282 -267.944092)
		(end 393.570714 -267.928344)
		(width 0.0889)
		(layer "In4.Cu")
		(net "M_J_CPU0_SB_RSP<0>")
	)
	(arc
		(start 381.917702 -267.928598)
		(mid 382.099953 -267.978948)
		(end 382.283462 -267.933424)
		(width 0.0889)
		(layer "In4.Cu")
		(net "M_J_CPU0_SB_RSP<0>")
	)
	(arc
		(start 389.811768 -267.928598)
		(mid 390.094724 -267.852421)
		(end 390.37768 -267.928598)
		(width 0.0889)
		(layer "In4.Cu")
		(net "M_J_CPU0_SB_RSP<0>")
	)
	(arc
		(start 389.43788 -267.928598)
		(mid 389.624824 -267.978853)
		(end 389.811768 -267.928598)
		(width 0.0889)
		(layer "In4.Cu")
		(net "M_J_CPU0_SB_RSP<0>")
	)
	(arc
		(start 385.677664 -267.928598)
		(mid 385.859915 -267.978948)
		(end 386.043424 -267.933424)
		(width 0.0889)
		(layer "In4.Cu")
		(net "M_J_CPU0_SB_RSP<0>")
	)
	(arc
		(start 386.99186 -267.928598)
		(mid 387.274816 -267.852421)
		(end 387.557772 -267.928598)
		(width 0.0889)
		(layer "In4.Cu")
		(net "M_J_CPU0_SB_RSP<0>")
	)
	(arc
		(start 387.566154 -267.933424)
		(mid 387.749662 -267.978918)
		(end 387.931914 -267.928598)
		(width 0.0889)
		(layer "In4.Cu")
		(net "M_J_CPU0_SB_RSP<0>")
	)
	(arc
		(start 391.326116 -267.933424)
		(mid 391.509624 -267.978918)
		(end 391.691876 -267.928598)
		(width 0.0889)
		(layer "In4.Cu")
		(net "M_J_CPU0_SB_RSP<0>")
	)
	(arc
		(start 386.617718 -267.928598)
		(mid 386.799969 -267.978948)
		(end 386.983478 -267.933424)
		(width 0.0889)
		(layer "In4.Cu")
		(net "M_J_CPU0_SB_RSP<0>")
	)
	(arc
		(start 391.691876 -267.928598)
		(mid 391.961645 -267.852575)
		(end 392.234674 -267.915898)
		(width 0.0889)
		(layer "In4.Cu")
		(net "M_J_CPU0_SB_RSP<0>")
	)
	(arc
		(start 383.806192 -267.933424)
		(mid 383.9897 -267.978918)
		(end 384.171952 -267.928598)
		(width 0.0889)
		(layer "In4.Cu")
		(net "M_J_CPU0_SB_RSP<0>")
	)
	(arc
		(start 393.196572 -267.928598)
		(mid 393.368027 -267.979115)
		(end 393.543282 -267.944092)
		(width 0.0889)
		(layer "In4.Cu")
		(net "M_J_CPU0_SB_RSP<0>")
	)
	(arc
		(start 388.506208 -267.933424)
		(mid 388.689716 -267.978918)
		(end 388.871968 -267.928598)
		(width 0.0889)
		(layer "In4.Cu")
		(net "M_J_CPU0_SB_RSP<0>")
	)
	(arc
		(start 381.033274 -267.95476)
		(mid 381.195463 -267.977495)
		(end 381.35179 -267.928598)
		(width 0.0889)
		(layer "In4.Cu")
		(net "M_J_CPU0_SB_RSP<0>")
	)
	(arc
		(start 384.171952 -267.928598)
		(mid 384.454908 -267.852421)
		(end 384.737864 -267.928598)
		(width 0.0889)
		(layer "In4.Cu")
		(net "M_J_CPU0_SB_RSP<0>")
	)
	(arc
		(start 382.866138 -267.933424)
		(mid 383.049646 -267.978918)
		(end 383.231898 -267.928598)
		(width 0.0889)
		(layer "In4.Cu")
		(net "M_J_CPU0_SB_RSP<0>")
	)
	(arc
		(start 384.737864 -267.928598)
		(mid 384.924808 -267.978853)
		(end 385.111752 -267.928598)
		(width 0.0889)
		(layer "In4.Cu")
		(net "M_J_CPU0_SB_RSP<0>")
	)
	(arc
		(start 387.931914 -267.928598)
		(mid 388.21487 -267.852421)
		(end 388.497826 -267.928598)
		(width 0.0889)
		(layer "In4.Cu")
		(net "M_J_CPU0_SB_RSP<0>")
	)
	(arc
		(start 388.871968 -267.928598)
		(mid 389.154924 -267.852421)
		(end 389.43788 -267.928598)
		(width 0.0889)
		(layer "In4.Cu")
		(net "M_J_CPU0_SB_RSP<0>")
	)
	(arc
		(start 390.751822 -267.928598)
		(mid 391.034778 -267.852421)
		(end 391.317734 -267.928598)
		(width 0.0889)
		(layer "In4.Cu")
		(net "M_J_CPU0_SB_RSP<0>")
	)
	(arc
		(start 381.35179 -267.928598)
		(mid 381.634746 -267.852421)
		(end 381.917702 -267.928598)
		(width 0.0889)
		(layer "In4.Cu")
		(net "M_J_CPU0_SB_RSP<0>")
	)
	(arc
		(start 390.37768 -267.928598)
		(mid 390.559931 -267.978948)
		(end 390.74344 -267.933424)
		(width 0.0889)
		(layer "In4.Cu")
		(net "M_J_CPU0_SB_RSP<0>")
	)
	(arc
		(start 392.652758 -267.914882)
		(mid 392.926412 -267.851939)
		(end 393.196572 -267.928598)
		(width 0.0889)
		(layer "In4.Cu")
		(net "M_J_CPU0_SB_RSP<0>")
	)
	(arc
		(start 385.111752 -267.928598)
		(mid 385.394708 -267.852421)
		(end 385.677664 -267.928598)
		(width 0.0889)
		(layer "In4.Cu")
		(net "M_J_CPU0_SB_RSP<0>")
	)
	(arc
		(start 383.231898 -267.928598)
		(mid 383.514854 -267.852421)
		(end 383.79781 -267.928598)
		(width 0.0889)
		(layer "In4.Cu")
		(net "M_J_CPU0_SB_RSP<0>")
	)
	(arc
		(start 392.274552 -267.938758)
		(mid 392.453273 -267.978681)
		(end 392.62939 -267.928598)
		(width 0.0889)
		(layer "In4.Cu")
		(net "M_J_CPU0_SB_RSP<0>")
	)
	(arc
		(start 386.051806 -267.928598)
		(mid 386.334762 -267.852421)
		(end 386.617718 -267.928598)
		(width 0.0889)
		(layer "In4.Cu")
		(net "M_J_CPU0_SB_RSP<0>")
	)
	(arc
		(start 382.291844 -267.928598)
		(mid 382.5748 -267.852421)
		(end 382.857756 -267.928598)
		(width 0.0889)
		(layer "In4.Cu")
		(net "M_J_CPU0_SB_RSP<0>")
	)
	(segment
		(start 379.28804 -264.910062)
		(end 379.754892 -265.176)
		(width 0.10668)
		(layer "F.Cu")
		(net "M_J_CPU0_SB_PAR")
	)
	(segment
		(start 395.953742 -264.79373)
		(end 409.7528 -264.79373)
		(width 0.14478)
		(layer "In4.Cu")
		(net "M_J_CPU0_SB_PAR")
	)
	(segment
		(start 412.419292 -267.460222)
		(end 414.090104 -267.460222)
		(width 0.14478)
		(layer "In4.Cu")
		(net "M_J_CPU0_SB_PAR")
	)
	(segment
		(start 395.223492 -264.544302)
		(end 395.47292 -264.79373)
		(width 0.0889)
		(layer "In4.Cu")
		(net "M_J_CPU0_SB_PAR")
	)
	(segment
		(start 383.693416 -265.503406)
		(end 383.701798 -265.49858)
		(width 0.0889)
		(layer "In4.Cu")
		(net "M_J_CPU0_SB_PAR")
	)
	(segment
		(start 389.333486 -265.503406)
		(end 389.341868 -265.49858)
		(width 0.0889)
		(layer "In4.Cu")
		(net "M_J_CPU0_SB_PAR")
	)
	(segment
		(start 388.393432 -265.503406)
		(end 388.401814 -265.49858)
		(width 0.0889)
		(layer "In4.Cu")
		(net "M_J_CPU0_SB_PAR")
	)
	(segment
		(start 379.933454 -265.503406)
		(end 379.941836 -265.49858)
		(width 0.0889)
		(layer "In4.Cu")
		(net "M_J_CPU0_SB_PAR")
	)
	(segment
		(start 434.575204 -266.610084)
		(end 435.000146 -267.035026)
		(width 0.14478)
		(layer "In4.Cu")
		(net "M_J_CPU0_SB_PAR")
	)
	(segment
		(start 389.90778 -265.49858)
		(end 389.916162 -265.503406)
		(width 0.0889)
		(layer "In4.Cu")
		(net "M_J_CPU0_SB_PAR")
	)
	(segment
		(start 409.7528 -264.79373)
		(end 412.419292 -267.460222)
		(width 0.14478)
		(layer "In4.Cu")
		(net "M_J_CPU0_SB_PAR")
	)
	(segment
		(start 422.484296 -266.610084)
		(end 434.575204 -266.610084)
		(width 0.14478)
		(layer "In4.Cu")
		(net "M_J_CPU0_SB_PAR")
	)
	(segment
		(start 384.63347 -265.503406)
		(end 384.641852 -265.49858)
		(width 0.0889)
		(layer "In4.Cu")
		(net "M_J_CPU0_SB_PAR")
	)
	(segment
		(start 414.090104 -267.460222)
		(end 414.940242 -266.610084)
		(width 0.14478)
		(layer "In4.Cu")
		(net "M_J_CPU0_SB_PAR")
	)
	(segment
		(start 418.972746 -267.460222)
		(end 421.634158 -267.460222)
		(width 0.14478)
		(layer "In4.Cu")
		(net "M_J_CPU0_SB_PAR")
	)
	(segment
		(start 379.600714 -265.44143)
		(end 379.623066 -265.524742)
		(width 0.0889)
		(layer "In4.Cu")
		(net "M_J_CPU0_SB_PAR")
	)
	(segment
		(start 421.634158 -267.460222)
		(end 422.484296 -266.610084)
		(width 0.14478)
		(layer "In4.Cu")
		(net "M_J_CPU0_SB_PAR")
	)
	(segment
		(start 418.122608 -266.610084)
		(end 418.972746 -267.460222)
		(width 0.14478)
		(layer "In4.Cu")
		(net "M_J_CPU0_SB_PAR")
	)
	(segment
		(start 380.873508 -265.503406)
		(end 380.88189 -265.49858)
		(width 0.0889)
		(layer "In4.Cu")
		(net "M_J_CPU0_SB_PAR")
	)
	(segment
		(start 392.718036 -265.492484)
		(end 392.72845 -265.49858)
		(width 0.0889)
		(layer "In4.Cu")
		(net "M_J_CPU0_SB_PAR")
	)
	(segment
		(start 379.754892 -265.176)
		(end 379.600714 -265.44143)
		(width 0.0889)
		(layer "In4.Cu")
		(net "M_J_CPU0_SB_PAR")
	)
	(segment
		(start 385.207764 -265.49858)
		(end 385.216146 -265.503406)
		(width 0.0889)
		(layer "In4.Cu")
		(net "M_J_CPU0_SB_PAR")
	)
	(segment
		(start 381.447802 -265.49858)
		(end 381.456184 -265.503406)
		(width 0.0889)
		(layer "In4.Cu")
		(net "M_J_CPU0_SB_PAR")
	)
	(segment
		(start 395.47292 -264.79373)
		(end 395.953742 -264.79373)
		(width 0.0889)
		(layer "In4.Cu")
		(net "M_J_CPU0_SB_PAR")
	)
	(segment
		(start 393.086082 -265.507724)
		(end 394.049504 -264.544302)
		(width 0.0889)
		(layer "In4.Cu")
		(net "M_J_CPU0_SB_PAR")
	)
	(segment
		(start 386.147818 -265.49858)
		(end 386.1562 -265.503406)
		(width 0.0889)
		(layer "In4.Cu")
		(net "M_J_CPU0_SB_PAR")
	)
	(segment
		(start 391.787634 -265.49858)
		(end 391.796016 -265.503406)
		(width 0.0889)
		(layer "In4.Cu")
		(net "M_J_CPU0_SB_PAR")
	)
	(segment
		(start 414.940242 -266.610084)
		(end 418.122608 -266.610084)
		(width 0.14478)
		(layer "In4.Cu")
		(net "M_J_CPU0_SB_PAR")
	)
	(segment
		(start 394.049504 -264.544302)
		(end 395.223492 -264.544302)
		(width 0.0889)
		(layer "In4.Cu")
		(net "M_J_CPU0_SB_PAR")
	)
	(arc
		(start 379.941836 -265.49858)
		(mid 380.224792 -265.422403)
		(end 380.507748 -265.49858)
		(width 0.0889)
		(layer "In4.Cu")
		(net "M_J_CPU0_SB_PAR")
	)
	(arc
		(start 380.88189 -265.49858)
		(mid 381.164846 -265.422403)
		(end 381.447802 -265.49858)
		(width 0.0889)
		(layer "In4.Cu")
		(net "M_J_CPU0_SB_PAR")
	)
	(arc
		(start 391.796016 -265.503406)
		(mid 391.979778 -265.549022)
		(end 392.162284 -265.49858)
		(width 0.0889)
		(layer "In4.Cu")
		(net "M_J_CPU0_SB_PAR")
	)
	(arc
		(start 386.52196 -265.49858)
		(mid 386.804916 -265.422403)
		(end 387.087872 -265.49858)
		(width 0.0889)
		(layer "In4.Cu")
		(net "M_J_CPU0_SB_PAR")
	)
	(arc
		(start 389.341868 -265.49858)
		(mid 389.624824 -265.422403)
		(end 389.90778 -265.49858)
		(width 0.0889)
		(layer "In4.Cu")
		(net "M_J_CPU0_SB_PAR")
	)
	(arc
		(start 388.027672 -265.49858)
		(mid 388.209923 -265.54893)
		(end 388.393432 -265.503406)
		(width 0.0889)
		(layer "In4.Cu")
		(net "M_J_CPU0_SB_PAR")
	)
	(arc
		(start 381.456184 -265.503406)
		(mid 381.639692 -265.5489)
		(end 381.821944 -265.49858)
		(width 0.0889)
		(layer "In4.Cu")
		(net "M_J_CPU0_SB_PAR")
	)
	(arc
		(start 383.701798 -265.49858)
		(mid 383.984754 -265.422403)
		(end 384.26771 -265.49858)
		(width 0.0889)
		(layer "In4.Cu")
		(net "M_J_CPU0_SB_PAR")
	)
	(arc
		(start 382.761744 -265.49858)
		(mid 383.0447 -265.422403)
		(end 383.327656 -265.49858)
		(width 0.0889)
		(layer "In4.Cu")
		(net "M_J_CPU0_SB_PAR")
	)
	(arc
		(start 387.46176 -265.49858)
		(mid 387.744716 -265.422403)
		(end 388.027672 -265.49858)
		(width 0.0889)
		(layer "In4.Cu")
		(net "M_J_CPU0_SB_PAR")
	)
	(arc
		(start 384.641852 -265.49858)
		(mid 384.924808 -265.422403)
		(end 385.207764 -265.49858)
		(width 0.0889)
		(layer "In4.Cu")
		(net "M_J_CPU0_SB_PAR")
	)
	(arc
		(start 386.1562 -265.503406)
		(mid 386.339708 -265.5489)
		(end 386.52196 -265.49858)
		(width 0.0889)
		(layer "In4.Cu")
		(net "M_J_CPU0_SB_PAR")
	)
	(arc
		(start 392.72845 -265.49858)
		(mid 392.9061 -265.54884)
		(end 393.086082 -265.507724)
		(width 0.0889)
		(layer "In4.Cu")
		(net "M_J_CPU0_SB_PAR")
	)
	(arc
		(start 385.216146 -265.503406)
		(mid 385.399654 -265.5489)
		(end 385.581906 -265.49858)
		(width 0.0889)
		(layer "In4.Cu")
		(net "M_J_CPU0_SB_PAR")
	)
	(arc
		(start 385.581906 -265.49858)
		(mid 385.864862 -265.422403)
		(end 386.147818 -265.49858)
		(width 0.0889)
		(layer "In4.Cu")
		(net "M_J_CPU0_SB_PAR")
	)
	(arc
		(start 389.916162 -265.503406)
		(mid 390.09967 -265.5489)
		(end 390.281922 -265.49858)
		(width 0.0889)
		(layer "In4.Cu")
		(net "M_J_CPU0_SB_PAR")
	)
	(arc
		(start 380.507748 -265.49858)
		(mid 380.689999 -265.54893)
		(end 380.873508 -265.503406)
		(width 0.0889)
		(layer "In4.Cu")
		(net "M_J_CPU0_SB_PAR")
	)
	(arc
		(start 382.387856 -265.49858)
		(mid 382.5748 -265.548835)
		(end 382.761744 -265.49858)
		(width 0.0889)
		(layer "In4.Cu")
		(net "M_J_CPU0_SB_PAR")
	)
	(arc
		(start 383.327656 -265.49858)
		(mid 383.509907 -265.54893)
		(end 383.693416 -265.503406)
		(width 0.0889)
		(layer "In4.Cu")
		(net "M_J_CPU0_SB_PAR")
	)
	(arc
		(start 379.623066 -265.524742)
		(mid 379.780576 -265.54794)
		(end 379.933454 -265.503406)
		(width 0.0889)
		(layer "In4.Cu")
		(net "M_J_CPU0_SB_PAR")
	)
	(arc
		(start 388.401814 -265.49858)
		(mid 388.68477 -265.422403)
		(end 388.967726 -265.49858)
		(width 0.0889)
		(layer "In4.Cu")
		(net "M_J_CPU0_SB_PAR")
	)
	(arc
		(start 381.821944 -265.49858)
		(mid 382.1049 -265.422403)
		(end 382.387856 -265.49858)
		(width 0.0889)
		(layer "In4.Cu")
		(net "M_J_CPU0_SB_PAR")
	)
	(arc
		(start 390.847834 -265.49858)
		(mid 391.034778 -265.548835)
		(end 391.221722 -265.49858)
		(width 0.0889)
		(layer "In4.Cu")
		(net "M_J_CPU0_SB_PAR")
	)
	(arc
		(start 391.221722 -265.49858)
		(mid 391.504678 -265.422403)
		(end 391.787634 -265.49858)
		(width 0.0889)
		(layer "In4.Cu")
		(net "M_J_CPU0_SB_PAR")
	)
	(arc
		(start 388.967726 -265.49858)
		(mid 389.149977 -265.54893)
		(end 389.333486 -265.503406)
		(width 0.0889)
		(layer "In4.Cu")
		(net "M_J_CPU0_SB_PAR")
	)
	(arc
		(start 390.281922 -265.49858)
		(mid 390.564878 -265.422403)
		(end 390.847834 -265.49858)
		(width 0.0889)
		(layer "In4.Cu")
		(net "M_J_CPU0_SB_PAR")
	)
	(arc
		(start 387.087872 -265.49858)
		(mid 387.274816 -265.548835)
		(end 387.46176 -265.49858)
		(width 0.0889)
		(layer "In4.Cu")
		(net "M_J_CPU0_SB_PAR")
	)
	(arc
		(start 392.162284 -265.49858)
		(mid 392.439351 -265.422309)
		(end 392.718036 -265.492484)
		(width 0.0889)
		(layer "In4.Cu")
		(net "M_J_CPU0_SB_PAR")
	)
	(arc
		(start 384.26771 -265.49858)
		(mid 384.449961 -265.54893)
		(end 384.63347 -265.503406)
		(width 0.0889)
		(layer "In4.Cu")
		(net "M_J_CPU0_SB_PAR")
	)
	(segment
		(start 380.697994 -270.580104)
		(end 381.164846 -270.846042)
		(width 0.12954)
		(layer "F.Cu")
		(net "M_J_CPU0_SB_DQS_DP<9>")
	)
	(segment
		(start 383.796286 -271.171162)
		(end 383.804668 -271.175988)
		(width 0.09525)
		(layer "In4.Cu")
		(net "M_J_CPU0_SB_DQS_DP<9>")
	)
	(segment
		(start 393.065254 -270.383254)
		(end 393.103354 -270.361156)
		(width 0.09525)
		(layer "In4.Cu")
		(net "M_J_CPU0_SB_DQS_DP<9>")
	)
	(segment
		(start 395.835632 -269.2527)
		(end 395.859254 -269.2527)
		(width 0.09525)
		(layer "In4.Cu")
		(net "M_J_CPU0_SB_DQS_DP<9>")
	)
	(segment
		(start 429.167798 -275.972016)
		(end 429.711104 -275.42871)
		(width 0.16002)
		(layer "In4.Cu")
		(net "M_J_CPU0_SB_DQS_DP<9>")
	)
	(segment
		(start 381.010922 -271.111472)
		(end 381.034036 -271.198086)
		(width 0.09525)
		(layer "In4.Cu")
		(net "M_J_CPU0_SB_DQS_DP<9>")
	)
	(segment
		(start 429.711104 -275.42871)
		(end 430.266856 -275.42871)
		(width 0.16002)
		(layer "In4.Cu")
		(net "M_J_CPU0_SB_DQS_DP<9>")
	)
	(segment
		(start 437.813196 -275.808948)
		(end 438.826402 -275.808948)
		(width 0.16002)
		(layer "In4.Cu")
		(net "M_J_CPU0_SB_DQS_DP<9>")
	)
	(segment
		(start 414.695386 -275.220176)
		(end 418.010594 -275.220176)
		(width 0.16002)
		(layer "In4.Cu")
		(net "M_J_CPU0_SB_DQS_DP<9>")
	)
	(segment
		(start 405.200104 -269.2527)
		(end 407.796492 -271.849088)
		(width 0.16002)
		(layer "In4.Cu")
		(net "M_J_CPU0_SB_DQS_DP<9>")
	)
	(segment
		(start 391.31621 -271.171162)
		(end 391.324592 -271.175988)
		(width 0.09525)
		(layer "In4.Cu")
		(net "M_J_CPU0_SB_DQS_DP<9>")
	)
	(segment
		(start 407.796492 -271.849088)
		(end 409.004008 -271.849088)
		(width 0.16002)
		(layer "In4.Cu")
		(net "M_J_CPU0_SB_DQS_DP<9>")
	)
	(segment
		(start 421.968168 -275.488146)
		(end 422.89222 -275.488146)
		(width 0.16002)
		(layer "In4.Cu")
		(net "M_J_CPU0_SB_DQS_DP<9>")
	)
	(segment
		(start 426.05706 -275.65985)
		(end 428.129192 -275.65985)
		(width 0.16002)
		(layer "In4.Cu")
		(net "M_J_CPU0_SB_DQS_DP<9>")
	)
	(segment
		(start 394.555218 -269.17269)
		(end 395.221206 -269.17269)
		(width 0.09525)
		(layer "In4.Cu")
		(net "M_J_CPU0_SB_DQS_DP<9>")
	)
	(segment
		(start 411.964886 -274.809966)
		(end 414.285176 -274.809966)
		(width 0.16002)
		(layer "In4.Cu")
		(net "M_J_CPU0_SB_DQS_DP<9>")
	)
	(segment
		(start 386.044948 -271.175988)
		(end 386.05333 -271.171162)
		(width 0.09525)
		(layer "In4.Cu")
		(net "M_J_CPU0_SB_DQS_DP<9>")
	)
	(segment
		(start 434.878734 -275.474176)
		(end 434.995574 -275.591016)
		(width 0.16002)
		(layer "In4.Cu")
		(net "M_J_CPU0_SB_DQS_DP<9>")
	)
	(segment
		(start 386.985002 -271.175988)
		(end 386.993384 -271.171162)
		(width 0.09525)
		(layer "In4.Cu")
		(net "M_J_CPU0_SB_DQS_DP<9>")
	)
	(segment
		(start 392.256264 -271.171162)
		(end 392.264646 -271.175988)
		(width 0.09525)
		(layer "In4.Cu")
		(net "M_J_CPU0_SB_DQS_DP<9>")
	)
	(segment
		(start 382.284986 -271.175988)
		(end 382.293368 -271.171162)
		(width 0.09525)
		(layer "In4.Cu")
		(net "M_J_CPU0_SB_DQS_DP<9>")
	)
	(segment
		(start 382.856232 -271.171162)
		(end 382.864614 -271.175988)
		(width 0.09525)
		(layer "In4.Cu")
		(net "M_J_CPU0_SB_DQS_DP<9>")
	)
	(segment
		(start 435.879494 -275.994876)
		(end 437.627268 -275.994876)
		(width 0.16002)
		(layer "In4.Cu")
		(net "M_J_CPU0_SB_DQS_DP<9>")
	)
	(segment
		(start 430.8856 -274.809966)
		(end 432.656996 -274.809966)
		(width 0.16002)
		(layer "In4.Cu")
		(net "M_J_CPU0_SB_DQS_DP<9>")
	)
	(segment
		(start 388.496302 -271.171162)
		(end 388.504684 -271.175988)
		(width 0.09525)
		(layer "In4.Cu")
		(net "M_J_CPU0_SB_DQS_DP<9>")
	)
	(segment
		(start 395.859254 -269.2527)
		(end 405.200104 -269.2527)
		(width 0.16002)
		(layer "In4.Cu")
		(net "M_J_CPU0_SB_DQS_DP<9>")
	)
	(segment
		(start 392.22934 -271.15643)
		(end 392.241024 -271.162272)
		(width 0.09525)
		(layer "In4.Cu")
		(net "M_J_CPU0_SB_DQS_DP<9>")
	)
	(segment
		(start 387.556248 -271.171162)
		(end 387.56463 -271.175988)
		(width 0.09525)
		(layer "In4.Cu")
		(net "M_J_CPU0_SB_DQS_DP<9>")
	)
	(segment
		(start 425.207176 -274.809966)
		(end 426.05706 -275.65985)
		(width 0.16002)
		(layer "In4.Cu")
		(net "M_J_CPU0_SB_DQS_DP<9>")
	)
	(segment
		(start 434.281834 -275.591016)
		(end 434.398674 -275.474176)
		(width 0.16002)
		(layer "In4.Cu")
		(net "M_J_CPU0_SB_DQS_DP<9>")
	)
	(segment
		(start 432.656996 -274.809966)
		(end 433.438046 -275.591016)
		(width 0.16002)
		(layer "In4.Cu")
		(net "M_J_CPU0_SB_DQS_DP<9>")
	)
	(segment
		(start 392.241024 -271.162272)
		(end 392.256264 -271.171162)
		(width 0.09525)
		(layer "In4.Cu")
		(net "M_J_CPU0_SB_DQS_DP<9>")
	)
	(segment
		(start 437.627268 -275.994876)
		(end 437.813196 -275.808948)
		(width 0.16002)
		(layer "In4.Cu")
		(net "M_J_CPU0_SB_DQS_DP<9>")
	)
	(segment
		(start 433.438046 -275.591016)
		(end 434.281834 -275.591016)
		(width 0.16002)
		(layer "In4.Cu")
		(net "M_J_CPU0_SB_DQS_DP<9>")
	)
	(segment
		(start 428.129192 -275.65985)
		(end 428.441358 -275.972016)
		(width 0.16002)
		(layer "In4.Cu")
		(net "M_J_CPU0_SB_DQS_DP<9>")
	)
	(segment
		(start 438.826402 -275.808948)
		(end 439.100214 -275.535136)
		(width 0.16002)
		(layer "In4.Cu")
		(net "M_J_CPU0_SB_DQS_DP<9>")
	)
	(segment
		(start 421.461438 -275.994876)
		(end 421.968168 -275.488146)
		(width 0.16002)
		(layer "In4.Cu")
		(net "M_J_CPU0_SB_DQS_DP<9>")
	)
	(segment
		(start 422.89222 -275.488146)
		(end 423.5704 -274.809966)
		(width 0.16002)
		(layer "In4.Cu")
		(net "M_J_CPU0_SB_DQS_DP<9>")
	)
	(segment
		(start 428.441358 -275.972016)
		(end 429.167798 -275.972016)
		(width 0.16002)
		(layer "In4.Cu")
		(net "M_J_CPU0_SB_DQS_DP<9>")
	)
	(segment
		(start 435.475634 -275.591016)
		(end 435.879494 -275.994876)
		(width 0.16002)
		(layer "In4.Cu")
		(net "M_J_CPU0_SB_DQS_DP<9>")
	)
	(segment
		(start 390.744964 -271.175988)
		(end 390.753346 -271.171162)
		(width 0.09525)
		(layer "In4.Cu")
		(net "M_J_CPU0_SB_DQS_DP<9>")
	)
	(segment
		(start 393.60602 -270.121888)
		(end 394.555218 -269.17269)
		(width 0.09525)
		(layer "In4.Cu")
		(net "M_J_CPU0_SB_DQS_DP<9>")
	)
	(segment
		(start 414.285176 -274.809966)
		(end 414.695386 -275.220176)
		(width 0.16002)
		(layer "In4.Cu")
		(net "M_J_CPU0_SB_DQS_DP<9>")
	)
	(segment
		(start 434.995574 -275.591016)
		(end 435.475634 -275.591016)
		(width 0.16002)
		(layer "In4.Cu")
		(net "M_J_CPU0_SB_DQS_DP<9>")
	)
	(segment
		(start 418.010594 -275.220176)
		(end 418.450268 -275.65985)
		(width 0.16002)
		(layer "In4.Cu")
		(net "M_J_CPU0_SB_DQS_DP<9>")
	)
	(segment
		(start 395.360398 -269.311882)
		(end 395.77645 -269.311882)
		(width 0.09525)
		(layer "In4.Cu")
		(net "M_J_CPU0_SB_DQS_DP<9>")
	)
	(segment
		(start 418.450268 -275.65985)
		(end 420.3573 -275.65985)
		(width 0.16002)
		(layer "In4.Cu")
		(net "M_J_CPU0_SB_DQS_DP<9>")
	)
	(segment
		(start 430.266856 -275.42871)
		(end 430.8856 -274.809966)
		(width 0.16002)
		(layer "In4.Cu")
		(net "M_J_CPU0_SB_DQS_DP<9>")
	)
	(segment
		(start 420.692326 -275.994876)
		(end 421.461438 -275.994876)
		(width 0.16002)
		(layer "In4.Cu")
		(net "M_J_CPU0_SB_DQS_DP<9>")
	)
	(segment
		(start 420.3573 -275.65985)
		(end 420.692326 -275.994876)
		(width 0.16002)
		(layer "In4.Cu")
		(net "M_J_CPU0_SB_DQS_DP<9>")
	)
	(segment
		(start 395.221206 -269.17269)
		(end 395.360398 -269.311882)
		(width 0.09525)
		(layer "In4.Cu")
		(net "M_J_CPU0_SB_DQS_DP<9>")
	)
	(segment
		(start 423.5704 -274.809966)
		(end 425.207176 -274.809966)
		(width 0.16002)
		(layer "In4.Cu")
		(net "M_J_CPU0_SB_DQS_DP<9>")
	)
	(segment
		(start 395.77645 -269.311882)
		(end 395.835632 -269.2527)
		(width 0.09525)
		(layer "In4.Cu")
		(net "M_J_CPU0_SB_DQS_DP<9>")
	)
	(segment
		(start 409.004008 -271.849088)
		(end 411.964886 -274.809966)
		(width 0.16002)
		(layer "In4.Cu")
		(net "M_J_CPU0_SB_DQS_DP<9>")
	)
	(segment
		(start 392.633454 -271.171162)
		(end 392.66495 -271.152874)
		(width 0.09525)
		(layer "In4.Cu")
		(net "M_J_CPU0_SB_DQS_DP<9>")
	)
	(segment
		(start 434.398674 -275.474176)
		(end 434.878734 -275.474176)
		(width 0.16002)
		(layer "In4.Cu")
		(net "M_J_CPU0_SB_DQS_DP<9>")
	)
	(segment
		(start 381.164846 -270.846042)
		(end 381.010922 -271.111472)
		(width 0.09525)
		(layer "In4.Cu")
		(net "M_J_CPU0_SB_DQS_DP<9>")
	)
	(arc
		(start 386.05333 -271.171162)
		(mid 386.334762 -271.095407)
		(end 386.616194 -271.171162)
		(width 0.09525)
		(layer "In4.Cu")
		(net "M_J_CPU0_SB_DQS_DP<9>")
	)
	(arc
		(start 386.993384 -271.171162)
		(mid 387.274816 -271.095407)
		(end 387.556248 -271.171162)
		(width 0.09525)
		(layer "In4.Cu")
		(net "M_J_CPU0_SB_DQS_DP<9>")
	)
	(arc
		(start 383.233422 -271.171162)
		(mid 383.514854 -271.095407)
		(end 383.796286 -271.171162)
		(width 0.09525)
		(layer "In4.Cu")
		(net "M_J_CPU0_SB_DQS_DP<9>")
	)
	(arc
		(start 389.813292 -271.171162)
		(mid 390.094724 -271.095407)
		(end 390.376156 -271.171162)
		(width 0.09525)
		(layer "In4.Cu")
		(net "M_J_CPU0_SB_DQS_DP<9>")
	)
	(arc
		(start 387.56463 -271.175988)
		(mid 387.749662 -271.221902)
		(end 387.933438 -271.171162)
		(width 0.09525)
		(layer "In4.Cu")
		(net "M_J_CPU0_SB_DQS_DP<9>")
	)
	(arc
		(start 383.804668 -271.175988)
		(mid 383.9897 -271.221902)
		(end 384.173476 -271.171162)
		(width 0.09525)
		(layer "In4.Cu")
		(net "M_J_CPU0_SB_DQS_DP<9>")
	)
	(arc
		(start 385.113276 -271.171162)
		(mid 385.394708 -271.095407)
		(end 385.67614 -271.171162)
		(width 0.09525)
		(layer "In4.Cu")
		(net "M_J_CPU0_SB_DQS_DP<9>")
	)
	(arc
		(start 389.436356 -271.171162)
		(mid 389.624824 -271.221839)
		(end 389.813292 -271.171162)
		(width 0.09525)
		(layer "In4.Cu")
		(net "M_J_CPU0_SB_DQS_DP<9>")
	)
	(arc
		(start 391.6934 -271.171162)
		(mid 391.959487 -271.095617)
		(end 392.22934 -271.15643)
		(width 0.09525)
		(layer "In4.Cu")
		(net "M_J_CPU0_SB_DQS_DP<9>")
	)
	(arc
		(start 388.504684 -271.175988)
		(mid 388.689716 -271.221902)
		(end 388.873492 -271.171162)
		(width 0.09525)
		(layer "In4.Cu")
		(net "M_J_CPU0_SB_DQS_DP<9>")
	)
	(arc
		(start 393.29487 -270.292576)
		(mid 393.465136 -270.234019)
		(end 393.60602 -270.121888)
		(width 0.09525)
		(layer "In4.Cu")
		(net "M_J_CPU0_SB_DQS_DP<9>")
	)
	(arc
		(start 381.916178 -271.171162)
		(mid 382.099953 -271.221934)
		(end 382.284986 -271.175988)
		(width 0.09525)
		(layer "In4.Cu")
		(net "M_J_CPU0_SB_DQS_DP<9>")
	)
	(arc
		(start 391.324592 -271.175988)
		(mid 391.509624 -271.221902)
		(end 391.6934 -271.171162)
		(width 0.09525)
		(layer "In4.Cu")
		(net "M_J_CPU0_SB_DQS_DP<9>")
	)
	(arc
		(start 387.933438 -271.171162)
		(mid 388.21487 -271.095407)
		(end 388.496302 -271.171162)
		(width 0.09525)
		(layer "In4.Cu")
		(net "M_J_CPU0_SB_DQS_DP<9>")
	)
	(arc
		(start 390.753346 -271.171162)
		(mid 391.034778 -271.095407)
		(end 391.31621 -271.171162)
		(width 0.09525)
		(layer "In4.Cu")
		(net "M_J_CPU0_SB_DQS_DP<9>")
	)
	(arc
		(start 392.82243 -270.846042)
		(mid 392.886827 -270.584736)
		(end 393.065254 -270.383254)
		(width 0.09525)
		(layer "In4.Cu")
		(net "M_J_CPU0_SB_DQS_DP<9>")
	)
	(arc
		(start 381.353314 -271.171162)
		(mid 381.634746 -271.095407)
		(end 381.916178 -271.171162)
		(width 0.09525)
		(layer "In4.Cu")
		(net "M_J_CPU0_SB_DQS_DP<9>")
	)
	(arc
		(start 381.034036 -271.198086)
		(mid 381.196687 -271.220346)
		(end 381.353314 -271.171162)
		(width 0.09525)
		(layer "In4.Cu")
		(net "M_J_CPU0_SB_DQS_DP<9>")
	)
	(arc
		(start 382.864614 -271.175988)
		(mid 383.049646 -271.221902)
		(end 383.233422 -271.171162)
		(width 0.09525)
		(layer "In4.Cu")
		(net "M_J_CPU0_SB_DQS_DP<9>")
	)
	(arc
		(start 382.293368 -271.171162)
		(mid 382.5748 -271.095407)
		(end 382.856232 -271.171162)
		(width 0.09525)
		(layer "In4.Cu")
		(net "M_J_CPU0_SB_DQS_DP<9>")
	)
	(arc
		(start 388.873492 -271.171162)
		(mid 389.154924 -271.095407)
		(end 389.436356 -271.171162)
		(width 0.09525)
		(layer "In4.Cu")
		(net "M_J_CPU0_SB_DQS_DP<9>")
	)
	(arc
		(start 384.173476 -271.171162)
		(mid 384.454908 -271.095407)
		(end 384.73634 -271.171162)
		(width 0.09525)
		(layer "In4.Cu")
		(net "M_J_CPU0_SB_DQS_DP<9>")
	)
	(arc
		(start 384.73634 -271.171162)
		(mid 384.924808 -271.221839)
		(end 385.113276 -271.171162)
		(width 0.09525)
		(layer "In4.Cu")
		(net "M_J_CPU0_SB_DQS_DP<9>")
	)
	(arc
		(start 385.67614 -271.171162)
		(mid 385.859915 -271.221934)
		(end 386.044948 -271.175988)
		(width 0.09525)
		(layer "In4.Cu")
		(net "M_J_CPU0_SB_DQS_DP<9>")
	)
	(arc
		(start 386.616194 -271.171162)
		(mid 386.799969 -271.221934)
		(end 386.985002 -271.175988)
		(width 0.09525)
		(layer "In4.Cu")
		(net "M_J_CPU0_SB_DQS_DP<9>")
	)
	(arc
		(start 392.264646 -271.175988)
		(mid 392.449678 -271.221902)
		(end 392.633454 -271.171162)
		(width 0.09525)
		(layer "In4.Cu")
		(net "M_J_CPU0_SB_DQS_DP<9>")
	)
	(arc
		(start 390.376156 -271.171162)
		(mid 390.559931 -271.221934)
		(end 390.744964 -271.175988)
		(width 0.09525)
		(layer "In4.Cu")
		(net "M_J_CPU0_SB_DQS_DP<9>")
	)
	(arc
		(start 393.103354 -270.361156)
		(mid 393.195976 -270.318106)
		(end 393.29487 -270.292576)
		(width 0.09525)
		(layer "In4.Cu")
		(net "M_J_CPU0_SB_DQS_DP<9>")
	)
	(arc
		(start 392.66495 -271.152874)
		(mid 392.780748 -271.01848)
		(end 392.82243 -270.846042)
		(width 0.09525)
		(layer "In4.Cu")
		(net "M_J_CPU0_SB_DQS_DP<9>")
	)
	(segment
		(start 378.817886 -291.640006)
		(end 379.284738 -291.905944)
		(width 0.12954)
		(layer "F.Cu")
		(net "M_J_CPU0_SB_DQS_DP<8>")
	)
	(segment
		(start 412.103824 -314.444126)
		(end 411.90799 -314.248292)
		(width 0.16002)
		(layer "In4.Cu")
		(net "M_J_CPU0_SB_DQS_DP<8>")
	)
	(segment
		(start 434.72608 -314.361068)
		(end 432.793902 -314.361068)
		(width 0.16002)
		(layer "In4.Cu")
		(net "M_J_CPU0_SB_DQS_DP<8>")
	)
	(segment
		(start 392.264646 -291.575998)
		(end 392.256264 -291.580824)
		(width 0.09525)
		(layer "In4.Cu")
		(net "M_J_CPU0_SB_DQS_DP<8>")
	)
	(segment
		(start 423.535602 -314.741052)
		(end 422.937432 -314.142882)
		(width 0.16002)
		(layer "In4.Cu")
		(net "M_J_CPU0_SB_DQS_DP<8>")
	)
	(segment
		(start 382.864614 -291.575998)
		(end 382.856232 -291.580824)
		(width 0.09525)
		(layer "In4.Cu")
		(net "M_J_CPU0_SB_DQS_DP<8>")
	)
	(segment
		(start 380.044706 -291.575998)
		(end 380.036324 -291.580824)
		(width 0.09525)
		(layer "In4.Cu")
		(net "M_J_CPU0_SB_DQS_DP<8>")
	)
	(segment
		(start 410.162756 -314.8457)
		(end 410.162756 -314.444126)
		(width 0.16002)
		(layer "In4.Cu")
		(net "M_J_CPU0_SB_DQS_DP<8>")
	)
	(segment
		(start 392.822938 -291.906198)
		(end 392.822684 -291.905944)
		(width 0.09525)
		(layer "In4.Cu")
		(net "M_J_CPU0_SB_DQS_DP<8>")
	)
	(segment
		(start 394.798042 -295.125394)
		(end 394.232384 -294.560244)
		(width 0.09525)
		(layer "In4.Cu")
		(net "M_J_CPU0_SB_DQS_DP<8>")
	)
	(segment
		(start 394.798296 -295.208706)
		(end 394.798042 -295.125394)
		(width 0.09525)
		(layer "In4.Cu")
		(net "M_J_CPU0_SB_DQS_DP<8>")
	)
	(segment
		(start 386.05333 -291.580824)
		(end 386.044948 -291.575998)
		(width 0.09525)
		(layer "In4.Cu")
		(net "M_J_CPU0_SB_DQS_DP<8>")
	)
	(segment
		(start 382.293368 -291.580824)
		(end 382.284986 -291.575998)
		(width 0.09525)
		(layer "In4.Cu")
		(net "M_J_CPU0_SB_DQS_DP<8>")
	)
	(segment
		(start 409.690316 -314.248292)
		(end 409.494482 -314.444126)
		(width 0.16002)
		(layer "In4.Cu")
		(net "M_J_CPU0_SB_DQS_DP<8>")
	)
	(segment
		(start 411.631384 -314.248292)
		(end 411.43555 -314.444126)
		(width 0.16002)
		(layer "In4.Cu")
		(net "M_J_CPU0_SB_DQS_DP<8>")
	)
	(segment
		(start 411.062678 -315.218572)
		(end 410.535628 -315.218572)
		(width 0.16002)
		(layer "In4.Cu")
		(net "M_J_CPU0_SB_DQS_DP<8>")
	)
	(segment
		(start 425.02709 -315.360304)
		(end 424.407838 -314.741052)
		(width 0.16002)
		(layer "In4.Cu")
		(net "M_J_CPU0_SB_DQS_DP<8>")
	)
	(segment
		(start 414.854898 -314.144152)
		(end 414.001458 -314.997592)
		(width 0.16002)
		(layer "In4.Cu")
		(net "M_J_CPU0_SB_DQS_DP<8>")
	)
	(segment
		(start 409.966922 -314.248292)
		(end 409.690316 -314.248292)
		(width 0.16002)
		(layer "In4.Cu")
		(net "M_J_CPU0_SB_DQS_DP<8>")
	)
	(segment
		(start 432.793902 -314.361068)
		(end 432.609498 -314.545472)
		(width 0.16002)
		(layer "In4.Cu")
		(net "M_J_CPU0_SB_DQS_DP<8>")
	)
	(segment
		(start 383.804668 -291.575998)
		(end 383.796286 -291.580824)
		(width 0.09525)
		(layer "In4.Cu")
		(net "M_J_CPU0_SB_DQS_DP<8>")
	)
	(segment
		(start 411.43555 -314.444126)
		(end 411.43555 -314.8457)
		(width 0.16002)
		(layer "In4.Cu")
		(net "M_J_CPU0_SB_DQS_DP<8>")
	)
	(segment
		(start 394.232384 -294.560244)
		(end 394.232384 -294.335962)
		(width 0.09525)
		(layer "In4.Cu")
		(net "M_J_CPU0_SB_DQS_DP<8>")
	)
	(segment
		(start 394.81506 -295.22547)
		(end 394.798296 -295.208706)
		(width 0.09525)
		(layer "In4.Cu")
		(net "M_J_CPU0_SB_DQS_DP<8>")
	)
	(segment
		(start 422.937432 -314.142882)
		(end 422.407588 -314.142882)
		(width 0.16002)
		(layer "In4.Cu")
		(net "M_J_CPU0_SB_DQS_DP<8>")
	)
	(segment
		(start 392.66495 -291.599112)
		(end 392.633454 -291.580824)
		(width 0.09525)
		(layer "In4.Cu")
		(net "M_J_CPU0_SB_DQS_DP<8>")
	)
	(segment
		(start 411.43555 -314.8457)
		(end 411.062678 -315.218572)
		(width 0.16002)
		(layer "In4.Cu")
		(net "M_J_CPU0_SB_DQS_DP<8>")
	)
	(segment
		(start 413.315658 -315.218572)
		(end 412.476696 -315.218572)
		(width 0.16002)
		(layer "In4.Cu")
		(net "M_J_CPU0_SB_DQS_DP<8>")
	)
	(segment
		(start 417.659058 -314.144152)
		(end 414.854898 -314.144152)
		(width 0.16002)
		(layer "In4.Cu")
		(net "M_J_CPU0_SB_DQS_DP<8>")
	)
	(segment
		(start 420.959534 -315.017912)
		(end 420.617142 -315.360304)
		(width 0.16002)
		(layer "In4.Cu")
		(net "M_J_CPU0_SB_DQS_DP<8>")
	)
	(segment
		(start 394.013944 -293.993824)
		(end 394.005308 -293.988744)
		(width 0.09525)
		(layer "In4.Cu")
		(net "M_J_CPU0_SB_DQS_DP<8>")
	)
	(segment
		(start 394.074904 -294.02913)
		(end 394.014706 -293.994332)
		(width 0.09525)
		(layer "In4.Cu")
		(net "M_J_CPU0_SB_DQS_DP<8>")
	)
	(segment
		(start 388.504684 -291.575998)
		(end 388.496302 -291.580824)
		(width 0.09525)
		(layer "In4.Cu")
		(net "M_J_CPU0_SB_DQS_DP<8>")
	)
	(segment
		(start 412.103824 -314.8457)
		(end 412.103824 -314.444126)
		(width 0.16002)
		(layer "In4.Cu")
		(net "M_J_CPU0_SB_DQS_DP<8>")
	)
	(segment
		(start 418.87521 -315.360304)
		(end 417.659058 -314.144152)
		(width 0.16002)
		(layer "In4.Cu")
		(net "M_J_CPU0_SB_DQS_DP<8>")
	)
	(segment
		(start 420.617142 -315.360304)
		(end 418.87521 -315.360304)
		(width 0.16002)
		(layer "In4.Cu")
		(net "M_J_CPU0_SB_DQS_DP<8>")
	)
	(segment
		(start 393.543536 -292.877494)
		(end 393.00023 -292.334188)
		(width 0.09525)
		(layer "In4.Cu")
		(net "M_J_CPU0_SB_DQS_DP<8>")
	)
	(segment
		(start 430.036478 -314.169552)
		(end 429.188118 -315.017912)
		(width 0.16002)
		(layer "In4.Cu")
		(net "M_J_CPU0_SB_DQS_DP<8>")
	)
	(segment
		(start 428.167546 -315.360304)
		(end 425.02709 -315.360304)
		(width 0.16002)
		(layer "In4.Cu")
		(net "M_J_CPU0_SB_DQS_DP<8>")
	)
	(segment
		(start 393.762992 -293.525448)
		(end 393.762992 -293.40683)
		(width 0.09525)
		(layer "In4.Cu")
		(net "M_J_CPU0_SB_DQS_DP<8>")
	)
	(segment
		(start 386.993384 -291.580824)
		(end 386.985002 -291.575998)
		(width 0.09525)
		(layer "In4.Cu")
		(net "M_J_CPU0_SB_DQS_DP<8>")
	)
	(segment
		(start 435.000146 -314.635134)
		(end 434.72608 -314.361068)
		(width 0.16002)
		(layer "In4.Cu")
		(net "M_J_CPU0_SB_DQS_DP<8>")
	)
	(segment
		(start 428.509938 -315.017912)
		(end 428.167546 -315.360304)
		(width 0.16002)
		(layer "In4.Cu")
		(net "M_J_CPU0_SB_DQS_DP<8>")
	)
	(segment
		(start 409.148026 -315.192156)
		(end 408.671014 -315.192156)
		(width 0.16002)
		(layer "In4.Cu")
		(net "M_J_CPU0_SB_DQS_DP<8>")
	)
	(segment
		(start 387.56463 -291.575998)
		(end 387.556248 -291.580824)
		(width 0.09525)
		(layer "In4.Cu")
		(net "M_J_CPU0_SB_DQS_DP<8>")
	)
	(segment
		(start 414.001458 -314.997592)
		(end 413.536638 -314.997592)
		(width 0.16002)
		(layer "In4.Cu")
		(net "M_J_CPU0_SB_DQS_DP<8>")
	)
	(segment
		(start 409.494482 -314.444126)
		(end 409.494482 -314.8457)
		(width 0.16002)
		(layer "In4.Cu")
		(net "M_J_CPU0_SB_DQS_DP<8>")
	)
	(segment
		(start 390.753346 -291.580824)
		(end 390.744964 -291.575998)
		(width 0.09525)
		(layer "In4.Cu")
		(net "M_J_CPU0_SB_DQS_DP<8>")
	)
	(segment
		(start 379.438662 -291.640514)
		(end 379.284738 -291.905944)
		(width 0.09525)
		(layer "In4.Cu")
		(net "M_J_CPU0_SB_DQS_DP<8>")
	)
	(segment
		(start 430.856898 -314.545472)
		(end 430.480978 -314.169552)
		(width 0.16002)
		(layer "In4.Cu")
		(net "M_J_CPU0_SB_DQS_DP<8>")
	)
	(segment
		(start 422.407588 -314.142882)
		(end 421.532558 -315.017912)
		(width 0.16002)
		(layer "In4.Cu")
		(net "M_J_CPU0_SB_DQS_DP<8>")
	)
	(segment
		(start 430.480978 -314.169552)
		(end 430.036478 -314.169552)
		(width 0.16002)
		(layer "In4.Cu")
		(net "M_J_CPU0_SB_DQS_DP<8>")
	)
	(segment
		(start 424.407838 -314.741052)
		(end 423.535602 -314.741052)
		(width 0.16002)
		(layer "In4.Cu")
		(net "M_J_CPU0_SB_DQS_DP<8>")
	)
	(segment
		(start 379.5395 -291.613844)
		(end 379.438662 -291.640514)
		(width 0.09525)
		(layer "In4.Cu")
		(net "M_J_CPU0_SB_DQS_DP<8>")
	)
	(segment
		(start 395.002258 -295.411906)
		(end 394.81506 -295.22547)
		(width 0.16002)
		(layer "In4.Cu")
		(net "M_J_CPU0_SB_DQS_DP<8>")
	)
	(segment
		(start 393.762484 -293.525956)
		(end 393.762992 -293.525448)
		(width 0.09525)
		(layer "In4.Cu")
		(net "M_J_CPU0_SB_DQS_DP<8>")
	)
	(segment
		(start 409.494482 -314.8457)
		(end 409.148026 -315.192156)
		(width 0.16002)
		(layer "In4.Cu")
		(net "M_J_CPU0_SB_DQS_DP<8>")
	)
	(segment
		(start 421.532558 -315.017912)
		(end 420.959534 -315.017912)
		(width 0.16002)
		(layer "In4.Cu")
		(net "M_J_CPU0_SB_DQS_DP<8>")
	)
	(segment
		(start 391.324592 -291.575998)
		(end 391.31621 -291.580824)
		(width 0.09525)
		(layer "In4.Cu")
		(net "M_J_CPU0_SB_DQS_DP<8>")
	)
	(segment
		(start 408.671014 -315.192156)
		(end 395.002258 -301.5234)
		(width 0.16002)
		(layer "In4.Cu")
		(net "M_J_CPU0_SB_DQS_DP<8>")
	)
	(segment
		(start 395.002258 -301.5234)
		(end 395.002258 -295.411906)
		(width 0.16002)
		(layer "In4.Cu")
		(net "M_J_CPU0_SB_DQS_DP<8>")
	)
	(segment
		(start 413.536638 -314.997592)
		(end 413.315658 -315.218572)
		(width 0.16002)
		(layer "In4.Cu")
		(net "M_J_CPU0_SB_DQS_DP<8>")
	)
	(segment
		(start 432.609498 -314.545472)
		(end 430.856898 -314.545472)
		(width 0.16002)
		(layer "In4.Cu")
		(net "M_J_CPU0_SB_DQS_DP<8>")
	)
	(segment
		(start 429.188118 -315.017912)
		(end 428.509938 -315.017912)
		(width 0.16002)
		(layer "In4.Cu")
		(net "M_J_CPU0_SB_DQS_DP<8>")
	)
	(segment
		(start 393.762992 -293.40683)
		(end 393.762738 -293.407084)
		(width 0.09525)
		(layer "In4.Cu")
		(net "M_J_CPU0_SB_DQS_DP<8>")
	)
	(segment
		(start 410.535628 -315.218572)
		(end 410.162756 -314.8457)
		(width 0.16002)
		(layer "In4.Cu")
		(net "M_J_CPU0_SB_DQS_DP<8>")
	)
	(segment
		(start 412.476696 -315.218572)
		(end 412.103824 -314.8457)
		(width 0.16002)
		(layer "In4.Cu")
		(net "M_J_CPU0_SB_DQS_DP<8>")
	)
	(segment
		(start 392.822684 -291.905944)
		(end 392.82243 -291.905944)
		(width 0.09525)
		(layer "In4.Cu")
		(net "M_J_CPU0_SB_DQS_DP<8>")
	)
	(segment
		(start 411.90799 -314.248292)
		(end 411.631384 -314.248292)
		(width 0.16002)
		(layer "In4.Cu")
		(net "M_J_CPU0_SB_DQS_DP<8>")
	)
	(segment
		(start 394.014706 -293.994332)
		(end 394.013944 -293.993824)
		(width 0.09525)
		(layer "In4.Cu")
		(net "M_J_CPU0_SB_DQS_DP<8>")
	)
	(segment
		(start 410.162756 -314.444126)
		(end 409.966922 -314.248292)
		(width 0.16002)
		(layer "In4.Cu")
		(net "M_J_CPU0_SB_DQS_DP<8>")
	)
	(arc
		(start 379.560074 -291.621972)
		(mid 379.549746 -291.618012)
		(end 379.5395 -291.613844)
		(width 0.09525)
		(layer "In4.Cu")
		(net "M_J_CPU0_SB_DQS_DP<8>")
	)
	(arc
		(start 381.916178 -291.580824)
		(mid 381.634746 -291.656579)
		(end 381.353314 -291.580824)
		(width 0.09525)
		(layer "In4.Cu")
		(net "M_J_CPU0_SB_DQS_DP<8>")
	)
	(arc
		(start 391.6934 -291.580824)
		(mid 391.509625 -291.530052)
		(end 391.324592 -291.575998)
		(width 0.09525)
		(layer "In4.Cu")
		(net "M_J_CPU0_SB_DQS_DP<8>")
	)
	(arc
		(start 392.82243 -291.905944)
		(mid 392.780765 -291.733497)
		(end 392.66495 -291.599112)
		(width 0.09525)
		(layer "In4.Cu")
		(net "M_J_CPU0_SB_DQS_DP<8>")
	)
	(arc
		(start 393.00023 -292.334188)
		(mid 392.868995 -292.137825)
		(end 392.822938 -291.906198)
		(width 0.09525)
		(layer "In4.Cu")
		(net "M_J_CPU0_SB_DQS_DP<8>")
	)
	(arc
		(start 383.796286 -291.580824)
		(mid 383.514854 -291.656579)
		(end 383.233422 -291.580824)
		(width 0.09525)
		(layer "In4.Cu")
		(net "M_J_CPU0_SB_DQS_DP<8>")
	)
	(arc
		(start 386.985002 -291.575998)
		(mid 386.79997 -291.530084)
		(end 386.616194 -291.580824)
		(width 0.09525)
		(layer "In4.Cu")
		(net "M_J_CPU0_SB_DQS_DP<8>")
	)
	(arc
		(start 388.496302 -291.580824)
		(mid 388.21487 -291.656579)
		(end 387.933438 -291.580824)
		(width 0.09525)
		(layer "In4.Cu")
		(net "M_J_CPU0_SB_DQS_DP<8>")
	)
	(arc
		(start 392.256264 -291.580824)
		(mid 391.974832 -291.656579)
		(end 391.6934 -291.580824)
		(width 0.09525)
		(layer "In4.Cu")
		(net "M_J_CPU0_SB_DQS_DP<8>")
	)
	(arc
		(start 388.873492 -291.580824)
		(mid 388.689717 -291.530052)
		(end 388.504684 -291.575998)
		(width 0.09525)
		(layer "In4.Cu")
		(net "M_J_CPU0_SB_DQS_DP<8>")
	)
	(arc
		(start 380.413514 -291.580824)
		(mid 380.229739 -291.530052)
		(end 380.044706 -291.575998)
		(width 0.09525)
		(layer "In4.Cu")
		(net "M_J_CPU0_SB_DQS_DP<8>")
	)
	(arc
		(start 382.284986 -291.575998)
		(mid 382.099954 -291.530084)
		(end 381.916178 -291.580824)
		(width 0.09525)
		(layer "In4.Cu")
		(net "M_J_CPU0_SB_DQS_DP<8>")
	)
	(arc
		(start 386.044948 -291.575998)
		(mid 385.859916 -291.530084)
		(end 385.67614 -291.580824)
		(width 0.09525)
		(layer "In4.Cu")
		(net "M_J_CPU0_SB_DQS_DP<8>")
	)
	(arc
		(start 394.005308 -293.988744)
		(mid 393.826858 -293.787274)
		(end 393.762484 -293.525956)
		(width 0.09525)
		(layer "In4.Cu")
		(net "M_J_CPU0_SB_DQS_DP<8>")
	)
	(arc
		(start 382.856232 -291.580824)
		(mid 382.5748 -291.656579)
		(end 382.293368 -291.580824)
		(width 0.09525)
		(layer "In4.Cu")
		(net "M_J_CPU0_SB_DQS_DP<8>")
	)
	(arc
		(start 389.813292 -291.580824)
		(mid 389.624824 -291.530147)
		(end 389.436356 -291.580824)
		(width 0.09525)
		(layer "In4.Cu")
		(net "M_J_CPU0_SB_DQS_DP<8>")
	)
	(arc
		(start 381.353314 -291.580824)
		(mid 381.164846 -291.530147)
		(end 380.976378 -291.580824)
		(width 0.09525)
		(layer "In4.Cu")
		(net "M_J_CPU0_SB_DQS_DP<8>")
	)
	(arc
		(start 391.31621 -291.580824)
		(mid 391.034778 -291.656579)
		(end 390.753346 -291.580824)
		(width 0.09525)
		(layer "In4.Cu")
		(net "M_J_CPU0_SB_DQS_DP<8>")
	)
	(arc
		(start 390.376156 -291.580824)
		(mid 390.094724 -291.656579)
		(end 389.813292 -291.580824)
		(width 0.09525)
		(layer "In4.Cu")
		(net "M_J_CPU0_SB_DQS_DP<8>")
	)
	(arc
		(start 385.67614 -291.580824)
		(mid 385.394708 -291.656579)
		(end 385.113276 -291.580824)
		(width 0.09525)
		(layer "In4.Cu")
		(net "M_J_CPU0_SB_DQS_DP<8>")
	)
	(arc
		(start 392.633454 -291.580824)
		(mid 392.449679 -291.530052)
		(end 392.264646 -291.575998)
		(width 0.09525)
		(layer "In4.Cu")
		(net "M_J_CPU0_SB_DQS_DP<8>")
	)
	(arc
		(start 387.556248 -291.580824)
		(mid 387.274816 -291.656579)
		(end 386.993384 -291.580824)
		(width 0.09525)
		(layer "In4.Cu")
		(net "M_J_CPU0_SB_DQS_DP<8>")
	)
	(arc
		(start 380.036324 -291.580824)
		(mid 379.80281 -291.654667)
		(end 379.560074 -291.621972)
		(width 0.09525)
		(layer "In4.Cu")
		(net "M_J_CPU0_SB_DQS_DP<8>")
	)
	(arc
		(start 393.762738 -293.407084)
		(mid 393.705838 -293.120466)
		(end 393.543536 -292.877494)
		(width 0.09525)
		(layer "In4.Cu")
		(net "M_J_CPU0_SB_DQS_DP<8>")
	)
	(arc
		(start 384.73634 -291.580824)
		(mid 384.454908 -291.656579)
		(end 384.173476 -291.580824)
		(width 0.09525)
		(layer "In4.Cu")
		(net "M_J_CPU0_SB_DQS_DP<8>")
	)
	(arc
		(start 389.436356 -291.580824)
		(mid 389.154924 -291.656579)
		(end 388.873492 -291.580824)
		(width 0.09525)
		(layer "In4.Cu")
		(net "M_J_CPU0_SB_DQS_DP<8>")
	)
	(arc
		(start 390.744964 -291.575998)
		(mid 390.559932 -291.530084)
		(end 390.376156 -291.580824)
		(width 0.09525)
		(layer "In4.Cu")
		(net "M_J_CPU0_SB_DQS_DP<8>")
	)
	(arc
		(start 383.233422 -291.580824)
		(mid 383.049647 -291.530052)
		(end 382.864614 -291.575998)
		(width 0.09525)
		(layer "In4.Cu")
		(net "M_J_CPU0_SB_DQS_DP<8>")
	)
	(arc
		(start 380.976378 -291.580824)
		(mid 380.694946 -291.656579)
		(end 380.413514 -291.580824)
		(width 0.09525)
		(layer "In4.Cu")
		(net "M_J_CPU0_SB_DQS_DP<8>")
	)
	(arc
		(start 387.933438 -291.580824)
		(mid 387.749663 -291.530052)
		(end 387.56463 -291.575998)
		(width 0.09525)
		(layer "In4.Cu")
		(net "M_J_CPU0_SB_DQS_DP<8>")
	)
	(arc
		(start 386.616194 -291.580824)
		(mid 386.334762 -291.656579)
		(end 386.05333 -291.580824)
		(width 0.09525)
		(layer "In4.Cu")
		(net "M_J_CPU0_SB_DQS_DP<8>")
	)
	(arc
		(start 385.113276 -291.580824)
		(mid 384.924808 -291.530147)
		(end 384.73634 -291.580824)
		(width 0.09525)
		(layer "In4.Cu")
		(net "M_J_CPU0_SB_DQS_DP<8>")
	)
	(arc
		(start 384.173476 -291.580824)
		(mid 383.989701 -291.530052)
		(end 383.804668 -291.575998)
		(width 0.09525)
		(layer "In4.Cu")
		(net "M_J_CPU0_SB_DQS_DP<8>")
	)
	(arc
		(start 394.232384 -294.335962)
		(mid 394.190719 -294.163515)
		(end 394.074904 -294.02913)
		(width 0.09525)
		(layer "In4.Cu")
		(net "M_J_CPU0_SB_DQS_DP<8>")
	)
	(segment
		(start 378.817886 -286.780224)
		(end 379.284738 -287.045908)
		(width 0.12954)
		(layer "F.Cu")
		(net "M_J_CPU0_SB_DQS_DP<7>")
	)
	(segment
		(start 386.044948 -286.715962)
		(end 386.05333 -286.720788)
		(width 0.09525)
		(layer "In4.Cu")
		(net "M_J_CPU0_SB_DQS_DP<7>")
	)
	(segment
		(start 413.287464 -306.00142)
		(end 413.641286 -305.647598)
		(width 0.16002)
		(layer "In4.Cu")
		(net "M_J_CPU0_SB_DQS_DP<7>")
	)
	(segment
		(start 409.40101 -305.137566)
		(end 409.596844 -304.941732)
		(width 0.16002)
		(layer "In4.Cu")
		(net "M_J_CPU0_SB_DQS_DP<7>")
	)
	(segment
		(start 391.6934 -286.720788)
		(end 391.703814 -286.726884)
		(width 0.09525)
		(layer "In4.Cu")
		(net "M_J_CPU0_SB_DQS_DP<7>")
	)
	(segment
		(start 430.821592 -305.160172)
		(end 432.644804 -305.160172)
		(width 0.16002)
		(layer "In4.Cu")
		(net "M_J_CPU0_SB_DQS_DP<7>")
	)
	(segment
		(start 408.396948 -305.990498)
		(end 409.03906 -305.990498)
		(width 0.16002)
		(layer "In4.Cu")
		(net "M_J_CPU0_SB_DQS_DP<7>")
	)
	(segment
		(start 429.188118 -305.667918)
		(end 430.036478 -304.819558)
		(width 0.16002)
		(layer "In4.Cu")
		(net "M_J_CPU0_SB_DQS_DP<7>")
	)
	(segment
		(start 400.575018 -298.168568)
		(end 408.396948 -305.990498)
		(width 0.16002)
		(layer "In4.Cu")
		(net "M_J_CPU0_SB_DQS_DP<7>")
	)
	(segment
		(start 412.383224 -306.00142)
		(end 413.287464 -306.00142)
		(width 0.16002)
		(layer "In4.Cu")
		(net "M_J_CPU0_SB_DQS_DP<7>")
	)
	(segment
		(start 386.985002 -286.715962)
		(end 386.993384 -286.720788)
		(width 0.09525)
		(layer "In4.Cu")
		(net "M_J_CPU0_SB_DQS_DP<7>")
	)
	(segment
		(start 387.556248 -286.720788)
		(end 387.56463 -286.715962)
		(width 0.09525)
		(layer "In4.Cu")
		(net "M_J_CPU0_SB_DQS_DP<7>")
	)
	(segment
		(start 430.480978 -304.819558)
		(end 430.821592 -305.160172)
		(width 0.16002)
		(layer "In4.Cu")
		(net "M_J_CPU0_SB_DQS_DP<7>")
	)
	(segment
		(start 379.284738 -287.045908)
		(end 379.438662 -286.780478)
		(width 0.09525)
		(layer "In4.Cu")
		(net "M_J_CPU0_SB_DQS_DP<7>")
	)
	(segment
		(start 380.036324 -286.720788)
		(end 380.044706 -286.715962)
		(width 0.09525)
		(layer "In4.Cu")
		(net "M_J_CPU0_SB_DQS_DP<7>")
	)
	(segment
		(start 428.509938 -305.667918)
		(end 429.188118 -305.667918)
		(width 0.16002)
		(layer "In4.Cu")
		(net "M_J_CPU0_SB_DQS_DP<7>")
	)
	(segment
		(start 394.513816 -287.165542)
		(end 395.183868 -287.165542)
		(width 0.09525)
		(layer "In4.Cu")
		(net "M_J_CPU0_SB_DQS_DP<7>")
	)
	(segment
		(start 395.414246 -287.39592)
		(end 395.414246 -287.505902)
		(width 0.09525)
		(layer "In4.Cu")
		(net "M_J_CPU0_SB_DQS_DP<7>")
	)
	(segment
		(start 428.167546 -306.01031)
		(end 428.509938 -305.667918)
		(width 0.16002)
		(layer "In4.Cu")
		(net "M_J_CPU0_SB_DQS_DP<7>")
	)
	(segment
		(start 423.304716 -305.160172)
		(end 426.099224 -305.160172)
		(width 0.16002)
		(layer "In4.Cu")
		(net "M_J_CPU0_SB_DQS_DP<7>")
	)
	(segment
		(start 383.796286 -286.720788)
		(end 383.804668 -286.715962)
		(width 0.09525)
		(layer "In4.Cu")
		(net "M_J_CPU0_SB_DQS_DP<7>")
	)
	(segment
		(start 379.438662 -286.780478)
		(end 379.5395 -286.753808)
		(width 0.09525)
		(layer "In4.Cu")
		(net "M_J_CPU0_SB_DQS_DP<7>")
	)
	(segment
		(start 410.442156 -306.00142)
		(end 410.969206 -306.00142)
		(width 0.16002)
		(layer "In4.Cu")
		(net "M_J_CPU0_SB_DQS_DP<7>")
	)
	(segment
		(start 382.284986 -286.715962)
		(end 382.293368 -286.720788)
		(width 0.09525)
		(layer "In4.Cu")
		(net "M_J_CPU0_SB_DQS_DP<7>")
	)
	(segment
		(start 412.010352 -305.137566)
		(end 412.010352 -305.628548)
		(width 0.16002)
		(layer "In4.Cu")
		(net "M_J_CPU0_SB_DQS_DP<7>")
	)
	(segment
		(start 395.645386 -287.8201)
		(end 400.575018 -292.749732)
		(width 0.16002)
		(layer "In4.Cu")
		(net "M_J_CPU0_SB_DQS_DP<7>")
	)
	(segment
		(start 410.069284 -305.628548)
		(end 410.442156 -306.00142)
		(width 0.16002)
		(layer "In4.Cu")
		(net "M_J_CPU0_SB_DQS_DP<7>")
	)
	(segment
		(start 411.342078 -305.628548)
		(end 411.342078 -305.137566)
		(width 0.16002)
		(layer "In4.Cu")
		(net "M_J_CPU0_SB_DQS_DP<7>")
	)
	(segment
		(start 394.017754 -286.66948)
		(end 394.513816 -287.165542)
		(width 0.09525)
		(layer "In4.Cu")
		(net "M_J_CPU0_SB_DQS_DP<7>")
	)
	(segment
		(start 395.628622 -287.803336)
		(end 395.645386 -287.8201)
		(width 0.09525)
		(layer "In4.Cu")
		(net "M_J_CPU0_SB_DQS_DP<7>")
	)
	(segment
		(start 410.969206 -306.00142)
		(end 411.342078 -305.628548)
		(width 0.16002)
		(layer "In4.Cu")
		(net "M_J_CPU0_SB_DQS_DP<7>")
	)
	(segment
		(start 409.40101 -305.628548)
		(end 409.40101 -305.137566)
		(width 0.16002)
		(layer "In4.Cu")
		(net "M_J_CPU0_SB_DQS_DP<7>")
	)
	(segment
		(start 422.937432 -304.792888)
		(end 423.304716 -305.160172)
		(width 0.16002)
		(layer "In4.Cu")
		(net "M_J_CPU0_SB_DQS_DP<7>")
	)
	(segment
		(start 392.445494 -286.66948)
		(end 394.017754 -286.66948)
		(width 0.09525)
		(layer "In4.Cu")
		(net "M_J_CPU0_SB_DQS_DP<7>")
	)
	(segment
		(start 411.537912 -304.941732)
		(end 411.814518 -304.941732)
		(width 0.16002)
		(layer "In4.Cu")
		(net "M_J_CPU0_SB_DQS_DP<7>")
	)
	(segment
		(start 420.617142 -306.01031)
		(end 420.959534 -305.667918)
		(width 0.16002)
		(layer "In4.Cu")
		(net "M_J_CPU0_SB_DQS_DP<7>")
	)
	(segment
		(start 413.641286 -305.647598)
		(end 414.001458 -305.647598)
		(width 0.16002)
		(layer "In4.Cu")
		(net "M_J_CPU0_SB_DQS_DP<7>")
	)
	(segment
		(start 412.010352 -305.628548)
		(end 412.383224 -306.00142)
		(width 0.16002)
		(layer "In4.Cu")
		(net "M_J_CPU0_SB_DQS_DP<7>")
	)
	(segment
		(start 388.496302 -286.720788)
		(end 388.504684 -286.715962)
		(width 0.09525)
		(layer "In4.Cu")
		(net "M_J_CPU0_SB_DQS_DP<7>")
	)
	(segment
		(start 409.03906 -305.990498)
		(end 409.40101 -305.628548)
		(width 0.16002)
		(layer "In4.Cu")
		(net "M_J_CPU0_SB_DQS_DP<7>")
	)
	(segment
		(start 392.256518 -286.720788)
		(end 392.256518 -286.720534)
		(width 0.09525)
		(layer "In4.Cu")
		(net "M_J_CPU0_SB_DQS_DP<7>")
	)
	(segment
		(start 410.069284 -305.137566)
		(end 410.069284 -305.628548)
		(width 0.16002)
		(layer "In4.Cu")
		(net "M_J_CPU0_SB_DQS_DP<7>")
	)
	(segment
		(start 395.414246 -287.505902)
		(end 395.628622 -287.720532)
		(width 0.09525)
		(layer "In4.Cu")
		(net "M_J_CPU0_SB_DQS_DP<7>")
	)
	(segment
		(start 417.659058 -304.794158)
		(end 418.87521 -306.01031)
		(width 0.16002)
		(layer "In4.Cu")
		(net "M_J_CPU0_SB_DQS_DP<7>")
	)
	(segment
		(start 432.644804 -305.160172)
		(end 432.793902 -305.011074)
		(width 0.16002)
		(layer "In4.Cu")
		(net "M_J_CPU0_SB_DQS_DP<7>")
	)
	(segment
		(start 421.532558 -305.667918)
		(end 422.407588 -304.792888)
		(width 0.16002)
		(layer "In4.Cu")
		(net "M_J_CPU0_SB_DQS_DP<7>")
	)
	(segment
		(start 430.036478 -304.819558)
		(end 430.480978 -304.819558)
		(width 0.16002)
		(layer "In4.Cu")
		(net "M_J_CPU0_SB_DQS_DP<7>")
	)
	(segment
		(start 422.407588 -304.792888)
		(end 422.937432 -304.792888)
		(width 0.16002)
		(layer "In4.Cu")
		(net "M_J_CPU0_SB_DQS_DP<7>")
	)
	(segment
		(start 426.949362 -306.01031)
		(end 428.167546 -306.01031)
		(width 0.16002)
		(layer "In4.Cu")
		(net "M_J_CPU0_SB_DQS_DP<7>")
	)
	(segment
		(start 409.87345 -304.941732)
		(end 410.069284 -305.137566)
		(width 0.16002)
		(layer "In4.Cu")
		(net "M_J_CPU0_SB_DQS_DP<7>")
	)
	(segment
		(start 400.575018 -292.749732)
		(end 400.575018 -298.168568)
		(width 0.16002)
		(layer "In4.Cu")
		(net "M_J_CPU0_SB_DQS_DP<7>")
	)
	(segment
		(start 418.87521 -306.01031)
		(end 420.617142 -306.01031)
		(width 0.16002)
		(layer "In4.Cu")
		(net "M_J_CPU0_SB_DQS_DP<7>")
	)
	(segment
		(start 420.959534 -305.667918)
		(end 421.532558 -305.667918)
		(width 0.16002)
		(layer "In4.Cu")
		(net "M_J_CPU0_SB_DQS_DP<7>")
	)
	(segment
		(start 391.31621 -286.720788)
		(end 391.324592 -286.715962)
		(width 0.09525)
		(layer "In4.Cu")
		(net "M_J_CPU0_SB_DQS_DP<7>")
	)
	(segment
		(start 434.72608 -305.011074)
		(end 435.000146 -305.28514)
		(width 0.16002)
		(layer "In4.Cu")
		(net "M_J_CPU0_SB_DQS_DP<7>")
	)
	(segment
		(start 411.814518 -304.941732)
		(end 412.010352 -305.137566)
		(width 0.16002)
		(layer "In4.Cu")
		(net "M_J_CPU0_SB_DQS_DP<7>")
	)
	(segment
		(start 382.856232 -286.720788)
		(end 382.864614 -286.715962)
		(width 0.09525)
		(layer "In4.Cu")
		(net "M_J_CPU0_SB_DQS_DP<7>")
	)
	(segment
		(start 390.744964 -286.715962)
		(end 390.753346 -286.720788)
		(width 0.09525)
		(layer "In4.Cu")
		(net "M_J_CPU0_SB_DQS_DP<7>")
	)
	(segment
		(start 411.342078 -305.137566)
		(end 411.537912 -304.941732)
		(width 0.16002)
		(layer "In4.Cu")
		(net "M_J_CPU0_SB_DQS_DP<7>")
	)
	(segment
		(start 432.793902 -305.011074)
		(end 434.72608 -305.011074)
		(width 0.16002)
		(layer "In4.Cu")
		(net "M_J_CPU0_SB_DQS_DP<7>")
	)
	(segment
		(start 414.001458 -305.647598)
		(end 414.854898 -304.794158)
		(width 0.16002)
		(layer "In4.Cu")
		(net "M_J_CPU0_SB_DQS_DP<7>")
	)
	(segment
		(start 395.628622 -287.720532)
		(end 395.628622 -287.803336)
		(width 0.09525)
		(layer "In4.Cu")
		(net "M_J_CPU0_SB_DQS_DP<7>")
	)
	(segment
		(start 426.099224 -305.160172)
		(end 426.949362 -306.01031)
		(width 0.16002)
		(layer "In4.Cu")
		(net "M_J_CPU0_SB_DQS_DP<7>")
	)
	(segment
		(start 414.854898 -304.794158)
		(end 417.659058 -304.794158)
		(width 0.16002)
		(layer "In4.Cu")
		(net "M_J_CPU0_SB_DQS_DP<7>")
	)
	(segment
		(start 395.183868 -287.165542)
		(end 395.414246 -287.39592)
		(width 0.09525)
		(layer "In4.Cu")
		(net "M_J_CPU0_SB_DQS_DP<7>")
	)
	(segment
		(start 409.596844 -304.941732)
		(end 409.87345 -304.941732)
		(width 0.16002)
		(layer "In4.Cu")
		(net "M_J_CPU0_SB_DQS_DP<7>")
	)
	(arc
		(start 388.504684 -286.715962)
		(mid 388.689716 -286.670048)
		(end 388.873492 -286.720788)
		(width 0.09525)
		(layer "In4.Cu")
		(net "M_J_CPU0_SB_DQS_DP<7>")
	)
	(arc
		(start 386.616194 -286.720788)
		(mid 386.799969 -286.670016)
		(end 386.985002 -286.715962)
		(width 0.09525)
		(layer "In4.Cu")
		(net "M_J_CPU0_SB_DQS_DP<7>")
	)
	(arc
		(start 381.353314 -286.720788)
		(mid 381.634746 -286.796577)
		(end 381.916178 -286.720788)
		(width 0.09525)
		(layer "In4.Cu")
		(net "M_J_CPU0_SB_DQS_DP<7>")
	)
	(arc
		(start 388.873492 -286.720788)
		(mid 389.154924 -286.796577)
		(end 389.436356 -286.720788)
		(width 0.09525)
		(layer "In4.Cu")
		(net "M_J_CPU0_SB_DQS_DP<7>")
	)
	(arc
		(start 381.916178 -286.720788)
		(mid 382.099953 -286.670016)
		(end 382.284986 -286.715962)
		(width 0.09525)
		(layer "In4.Cu")
		(net "M_J_CPU0_SB_DQS_DP<7>")
	)
	(arc
		(start 380.413514 -286.720788)
		(mid 380.694946 -286.796577)
		(end 380.976378 -286.720788)
		(width 0.09525)
		(layer "In4.Cu")
		(net "M_J_CPU0_SB_DQS_DP<7>")
	)
	(arc
		(start 380.044706 -286.715962)
		(mid 380.229738 -286.670048)
		(end 380.413514 -286.720788)
		(width 0.09525)
		(layer "In4.Cu")
		(net "M_J_CPU0_SB_DQS_DP<7>")
	)
	(arc
		(start 379.5395 -286.753808)
		(mid 379.791783 -286.795521)
		(end 380.036324 -286.720788)
		(width 0.09525)
		(layer "In4.Cu")
		(net "M_J_CPU0_SB_DQS_DP<7>")
	)
	(arc
		(start 387.933438 -286.720788)
		(mid 388.21487 -286.796577)
		(end 388.496302 -286.720788)
		(width 0.09525)
		(layer "In4.Cu")
		(net "M_J_CPU0_SB_DQS_DP<7>")
	)
	(arc
		(start 385.67614 -286.720788)
		(mid 385.859915 -286.670016)
		(end 386.044948 -286.715962)
		(width 0.09525)
		(layer "In4.Cu")
		(net "M_J_CPU0_SB_DQS_DP<7>")
	)
	(arc
		(start 387.56463 -286.715962)
		(mid 387.749662 -286.670048)
		(end 387.933438 -286.720788)
		(width 0.09525)
		(layer "In4.Cu")
		(net "M_J_CPU0_SB_DQS_DP<7>")
	)
	(arc
		(start 384.73634 -286.720788)
		(mid 384.924808 -286.670111)
		(end 385.113276 -286.720788)
		(width 0.09525)
		(layer "In4.Cu")
		(net "M_J_CPU0_SB_DQS_DP<7>")
	)
	(arc
		(start 382.864614 -286.715962)
		(mid 383.049646 -286.670048)
		(end 383.233422 -286.720788)
		(width 0.09525)
		(layer "In4.Cu")
		(net "M_J_CPU0_SB_DQS_DP<7>")
	)
	(arc
		(start 389.436356 -286.720788)
		(mid 389.624824 -286.670111)
		(end 389.813292 -286.720788)
		(width 0.09525)
		(layer "In4.Cu")
		(net "M_J_CPU0_SB_DQS_DP<7>")
	)
	(arc
		(start 386.05333 -286.720788)
		(mid 386.334762 -286.796577)
		(end 386.616194 -286.720788)
		(width 0.09525)
		(layer "In4.Cu")
		(net "M_J_CPU0_SB_DQS_DP<7>")
	)
	(arc
		(start 392.256518 -286.720534)
		(mid 392.347636 -286.682547)
		(end 392.445494 -286.66948)
		(width 0.09525)
		(layer "In4.Cu")
		(net "M_J_CPU0_SB_DQS_DP<7>")
	)
	(arc
		(start 384.173476 -286.720788)
		(mid 384.454908 -286.796577)
		(end 384.73634 -286.720788)
		(width 0.09525)
		(layer "In4.Cu")
		(net "M_J_CPU0_SB_DQS_DP<7>")
	)
	(arc
		(start 389.813292 -286.720788)
		(mid 390.094724 -286.796577)
		(end 390.376156 -286.720788)
		(width 0.09525)
		(layer "In4.Cu")
		(net "M_J_CPU0_SB_DQS_DP<7>")
	)
	(arc
		(start 380.976378 -286.720788)
		(mid 381.164846 -286.670111)
		(end 381.353314 -286.720788)
		(width 0.09525)
		(layer "In4.Cu")
		(net "M_J_CPU0_SB_DQS_DP<7>")
	)
	(arc
		(start 382.293368 -286.720788)
		(mid 382.5748 -286.796577)
		(end 382.856232 -286.720788)
		(width 0.09525)
		(layer "In4.Cu")
		(net "M_J_CPU0_SB_DQS_DP<7>")
	)
	(arc
		(start 383.804668 -286.715962)
		(mid 383.9897 -286.670048)
		(end 384.173476 -286.720788)
		(width 0.09525)
		(layer "In4.Cu")
		(net "M_J_CPU0_SB_DQS_DP<7>")
	)
	(arc
		(start 383.233422 -286.720788)
		(mid 383.514854 -286.796577)
		(end 383.796286 -286.720788)
		(width 0.09525)
		(layer "In4.Cu")
		(net "M_J_CPU0_SB_DQS_DP<7>")
	)
	(arc
		(start 385.113276 -286.720788)
		(mid 385.394708 -286.796577)
		(end 385.67614 -286.720788)
		(width 0.09525)
		(layer "In4.Cu")
		(net "M_J_CPU0_SB_DQS_DP<7>")
	)
	(arc
		(start 386.993384 -286.720788)
		(mid 387.274816 -286.796577)
		(end 387.556248 -286.720788)
		(width 0.09525)
		(layer "In4.Cu")
		(net "M_J_CPU0_SB_DQS_DP<7>")
	)
	(arc
		(start 390.376156 -286.720788)
		(mid 390.559931 -286.670016)
		(end 390.744964 -286.715962)
		(width 0.09525)
		(layer "In4.Cu")
		(net "M_J_CPU0_SB_DQS_DP<7>")
	)
	(arc
		(start 390.753346 -286.720788)
		(mid 391.034778 -286.796577)
		(end 391.31621 -286.720788)
		(width 0.09525)
		(layer "In4.Cu")
		(net "M_J_CPU0_SB_DQS_DP<7>")
	)
	(arc
		(start 391.703814 -286.726884)
		(mid 391.980976 -286.796716)
		(end 392.256518 -286.720788)
		(width 0.09525)
		(layer "In4.Cu")
		(net "M_J_CPU0_SB_DQS_DP<7>")
	)
	(arc
		(start 391.324592 -286.715962)
		(mid 391.509624 -286.670048)
		(end 391.6934 -286.720788)
		(width 0.09525)
		(layer "In4.Cu")
		(net "M_J_CPU0_SB_DQS_DP<7>")
	)
	(segment
		(start 378.817886 -281.920188)
		(end 379.284738 -282.186126)
		(width 0.12954)
		(layer "F.Cu")
		(net "M_J_CPU0_SB_DQS_DP<6>")
	)
	(segment
		(start 417.659058 -295.444164)
		(end 418.87521 -296.660316)
		(width 0.16002)
		(layer "In4.Cu")
		(net "M_J_CPU0_SB_DQS_DP<6>")
	)
	(segment
		(start 383.796286 -281.861006)
		(end 383.804668 -281.85618)
		(width 0.09525)
		(layer "In4.Cu")
		(net "M_J_CPU0_SB_DQS_DP<6>")
	)
	(segment
		(start 382.856232 -281.861006)
		(end 382.864614 -281.85618)
		(width 0.09525)
		(layer "In4.Cu")
		(net "M_J_CPU0_SB_DQS_DP<6>")
	)
	(segment
		(start 421.532558 -296.317924)
		(end 422.407588 -295.442894)
		(width 0.16002)
		(layer "In4.Cu")
		(net "M_J_CPU0_SB_DQS_DP<6>")
	)
	(segment
		(start 428.167546 -296.660316)
		(end 428.509938 -296.317924)
		(width 0.16002)
		(layer "In4.Cu")
		(net "M_J_CPU0_SB_DQS_DP<6>")
	)
	(segment
		(start 408.600402 -294.774112)
		(end 408.877262 -294.774112)
		(width 0.16002)
		(layer "In4.Cu")
		(net "M_J_CPU0_SB_DQS_DP<6>")
	)
	(segment
		(start 397.807942 -282.12034)
		(end 406.112218 -290.424616)
		(width 0.16002)
		(layer "In4.Cu")
		(net "M_J_CPU0_SB_DQS_DP<6>")
	)
	(segment
		(start 426.949362 -296.660316)
		(end 428.167546 -296.660316)
		(width 0.16002)
		(layer "In4.Cu")
		(net "M_J_CPU0_SB_DQS_DP<6>")
	)
	(segment
		(start 428.509938 -296.317924)
		(end 429.188118 -296.317924)
		(width 0.16002)
		(layer "In4.Cu")
		(net "M_J_CPU0_SB_DQS_DP<6>")
	)
	(segment
		(start 414.854898 -295.444164)
		(end 417.659058 -295.444164)
		(width 0.16002)
		(layer "In4.Cu")
		(net "M_J_CPU0_SB_DQS_DP<6>")
	)
	(segment
		(start 407.384758 -294.18788)
		(end 407.384758 -294.715184)
		(width 0.16002)
		(layer "In4.Cu")
		(net "M_J_CPU0_SB_DQS_DP<6>")
	)
	(segment
		(start 406.112218 -293.24046)
		(end 406.485852 -293.614094)
		(width 0.16002)
		(layer "In4.Cu")
		(net "M_J_CPU0_SB_DQS_DP<6>")
	)
	(segment
		(start 382.284986 -281.85618)
		(end 382.293368 -281.861006)
		(width 0.09525)
		(layer "In4.Cu")
		(net "M_J_CPU0_SB_DQS_DP<6>")
	)
	(segment
		(start 409.974034 -296.147744)
		(end 410.250894 -296.147744)
		(width 0.16002)
		(layer "In4.Cu")
		(net "M_J_CPU0_SB_DQS_DP<6>")
	)
	(segment
		(start 406.325832 -292.222682)
		(end 406.325832 -292.499542)
		(width 0.16002)
		(layer "In4.Cu")
		(net "M_J_CPU0_SB_DQS_DP<6>")
	)
	(segment
		(start 420.617142 -296.660316)
		(end 420.959534 -296.317924)
		(width 0.16002)
		(layer "In4.Cu")
		(net "M_J_CPU0_SB_DQS_DP<6>")
	)
	(segment
		(start 407.50363 -293.40048)
		(end 407.699464 -293.596314)
		(width 0.16002)
		(layer "In4.Cu")
		(net "M_J_CPU0_SB_DQS_DP<6>")
	)
	(segment
		(start 407.699464 -293.596314)
		(end 407.699464 -293.873174)
		(width 0.16002)
		(layer "In4.Cu")
		(net "M_J_CPU0_SB_DQS_DP<6>")
	)
	(segment
		(start 386.985002 -281.85618)
		(end 386.993384 -281.861006)
		(width 0.09525)
		(layer "In4.Cu")
		(net "M_J_CPU0_SB_DQS_DP<6>")
	)
	(segment
		(start 418.87521 -296.660316)
		(end 420.617142 -296.660316)
		(width 0.16002)
		(layer "In4.Cu")
		(net "M_J_CPU0_SB_DQS_DP<6>")
	)
	(segment
		(start 409.073096 -295.246806)
		(end 408.75839 -295.561512)
		(width 0.16002)
		(layer "In4.Cu")
		(net "M_J_CPU0_SB_DQS_DP<6>")
	)
	(segment
		(start 407.699464 -293.873174)
		(end 407.384758 -294.18788)
		(width 0.16002)
		(layer "In4.Cu")
		(net "M_J_CPU0_SB_DQS_DP<6>")
	)
	(segment
		(start 432.793902 -295.66108)
		(end 434.72608 -295.66108)
		(width 0.16002)
		(layer "In4.Cu")
		(net "M_J_CPU0_SB_DQS_DP<6>")
	)
	(segment
		(start 393.384786 -281.809698)
		(end 394.42644 -281.809698)
		(width 0.09525)
		(layer "In4.Cu")
		(net "M_J_CPU0_SB_DQS_DP<6>")
	)
	(segment
		(start 409.659328 -296.46245)
		(end 409.974034 -296.147744)
		(width 0.16002)
		(layer "In4.Cu")
		(net "M_J_CPU0_SB_DQS_DP<6>")
	)
	(segment
		(start 392.625834 -281.85618)
		(end 392.634216 -281.861006)
		(width 0.09525)
		(layer "In4.Cu")
		(net "M_J_CPU0_SB_DQS_DP<6>")
	)
	(segment
		(start 409.073096 -294.969946)
		(end 409.073096 -295.246806)
		(width 0.16002)
		(layer "In4.Cu")
		(net "M_J_CPU0_SB_DQS_DP<6>")
	)
	(segment
		(start 406.112218 -292.713156)
		(end 406.112218 -293.24046)
		(width 0.16002)
		(layer "In4.Cu")
		(net "M_J_CPU0_SB_DQS_DP<6>")
	)
	(segment
		(start 394.540994 -281.845766)
		(end 394.75664 -282.061412)
		(width 0.09525)
		(layer "In4.Cu")
		(net "M_J_CPU0_SB_DQS_DP<6>")
	)
	(segment
		(start 408.877262 -294.774112)
		(end 409.073096 -294.969946)
		(width 0.16002)
		(layer "In4.Cu")
		(net "M_J_CPU0_SB_DQS_DP<6>")
	)
	(segment
		(start 420.959534 -296.317924)
		(end 421.532558 -296.317924)
		(width 0.16002)
		(layer "In4.Cu")
		(net "M_J_CPU0_SB_DQS_DP<6>")
	)
	(segment
		(start 429.188118 -296.317924)
		(end 430.036478 -295.469564)
		(width 0.16002)
		(layer "In4.Cu")
		(net "M_J_CPU0_SB_DQS_DP<6>")
	)
	(segment
		(start 422.937432 -295.442894)
		(end 423.304716 -295.810178)
		(width 0.16002)
		(layer "In4.Cu")
		(net "M_J_CPU0_SB_DQS_DP<6>")
	)
	(segment
		(start 406.112218 -290.424616)
		(end 406.112218 -292.009068)
		(width 0.16002)
		(layer "In4.Cu")
		(net "M_J_CPU0_SB_DQS_DP<6>")
	)
	(segment
		(start 394.75664 -282.061412)
		(end 395.530832 -282.061412)
		(width 0.09525)
		(layer "In4.Cu")
		(net "M_J_CPU0_SB_DQS_DP<6>")
	)
	(segment
		(start 380.036324 -281.861006)
		(end 380.044706 -281.85618)
		(width 0.09525)
		(layer "In4.Cu")
		(net "M_J_CPU0_SB_DQS_DP<6>")
	)
	(segment
		(start 408.75839 -296.088816)
		(end 409.132024 -296.46245)
		(width 0.16002)
		(layer "In4.Cu")
		(net "M_J_CPU0_SB_DQS_DP<6>")
	)
	(segment
		(start 414.001458 -296.297604)
		(end 414.854898 -295.444164)
		(width 0.16002)
		(layer "In4.Cu")
		(net "M_J_CPU0_SB_DQS_DP<6>")
	)
	(segment
		(start 379.284738 -282.186126)
		(end 379.438662 -281.920696)
		(width 0.09525)
		(layer "In4.Cu")
		(net "M_J_CPU0_SB_DQS_DP<6>")
	)
	(segment
		(start 395.613382 -282.12034)
		(end 397.807942 -282.12034)
		(width 0.16002)
		(layer "In4.Cu")
		(net "M_J_CPU0_SB_DQS_DP<6>")
	)
	(segment
		(start 410.400754 -296.297604)
		(end 414.001458 -296.297604)
		(width 0.16002)
		(layer "In4.Cu")
		(net "M_J_CPU0_SB_DQS_DP<6>")
	)
	(segment
		(start 430.036478 -295.469564)
		(end 430.480978 -295.469564)
		(width 0.16002)
		(layer "In4.Cu")
		(net "M_J_CPU0_SB_DQS_DP<6>")
	)
	(segment
		(start 407.384758 -294.715184)
		(end 407.758392 -295.088818)
		(width 0.16002)
		(layer "In4.Cu")
		(net "M_J_CPU0_SB_DQS_DP<6>")
	)
	(segment
		(start 432.644804 -295.810178)
		(end 432.793902 -295.66108)
		(width 0.16002)
		(layer "In4.Cu")
		(net "M_J_CPU0_SB_DQS_DP<6>")
	)
	(segment
		(start 391.31621 -281.861006)
		(end 391.324592 -281.85618)
		(width 0.09525)
		(layer "In4.Cu")
		(net "M_J_CPU0_SB_DQS_DP<6>")
	)
	(segment
		(start 430.480978 -295.469564)
		(end 430.821592 -295.810178)
		(width 0.16002)
		(layer "In4.Cu")
		(net "M_J_CPU0_SB_DQS_DP<6>")
	)
	(segment
		(start 408.75839 -295.561512)
		(end 408.75839 -296.088816)
		(width 0.16002)
		(layer "In4.Cu")
		(net "M_J_CPU0_SB_DQS_DP<6>")
	)
	(segment
		(start 434.72608 -295.66108)
		(end 435.000146 -295.935146)
		(width 0.16002)
		(layer "In4.Cu")
		(net "M_J_CPU0_SB_DQS_DP<6>")
	)
	(segment
		(start 406.112218 -292.009068)
		(end 406.325832 -292.222682)
		(width 0.16002)
		(layer "In4.Cu")
		(net "M_J_CPU0_SB_DQS_DP<6>")
	)
	(segment
		(start 406.325832 -292.499542)
		(end 406.112218 -292.713156)
		(width 0.16002)
		(layer "In4.Cu")
		(net "M_J_CPU0_SB_DQS_DP<6>")
	)
	(segment
		(start 386.044948 -281.85618)
		(end 386.05333 -281.861006)
		(width 0.09525)
		(layer "In4.Cu")
		(net "M_J_CPU0_SB_DQS_DP<6>")
	)
	(segment
		(start 390.744964 -281.85618)
		(end 390.753346 -281.861006)
		(width 0.09525)
		(layer "In4.Cu")
		(net "M_J_CPU0_SB_DQS_DP<6>")
	)
	(segment
		(start 407.013156 -293.614094)
		(end 407.22677 -293.40048)
		(width 0.16002)
		(layer "In4.Cu")
		(net "M_J_CPU0_SB_DQS_DP<6>")
	)
	(segment
		(start 423.304716 -295.810178)
		(end 426.099224 -295.810178)
		(width 0.16002)
		(layer "In4.Cu")
		(net "M_J_CPU0_SB_DQS_DP<6>")
	)
	(segment
		(start 379.438662 -281.920696)
		(end 379.5395 -281.894026)
		(width 0.09525)
		(layer "In4.Cu")
		(net "M_J_CPU0_SB_DQS_DP<6>")
	)
	(segment
		(start 422.407588 -295.442894)
		(end 422.937432 -295.442894)
		(width 0.16002)
		(layer "In4.Cu")
		(net "M_J_CPU0_SB_DQS_DP<6>")
	)
	(segment
		(start 395.58976 -282.12034)
		(end 395.613382 -282.12034)
		(width 0.09525)
		(layer "In4.Cu")
		(net "M_J_CPU0_SB_DQS_DP<6>")
	)
	(segment
		(start 387.556248 -281.861006)
		(end 387.56463 -281.85618)
		(width 0.09525)
		(layer "In4.Cu")
		(net "M_J_CPU0_SB_DQS_DP<6>")
	)
	(segment
		(start 388.496302 -281.861006)
		(end 388.504684 -281.85618)
		(width 0.09525)
		(layer "In4.Cu")
		(net "M_J_CPU0_SB_DQS_DP<6>")
	)
	(segment
		(start 430.821592 -295.810178)
		(end 432.644804 -295.810178)
		(width 0.16002)
		(layer "In4.Cu")
		(net "M_J_CPU0_SB_DQS_DP<6>")
	)
	(segment
		(start 395.530832 -282.061412)
		(end 395.58976 -282.12034)
		(width 0.09525)
		(layer "In4.Cu")
		(net "M_J_CPU0_SB_DQS_DP<6>")
	)
	(segment
		(start 406.485852 -293.614094)
		(end 407.013156 -293.614094)
		(width 0.16002)
		(layer "In4.Cu")
		(net "M_J_CPU0_SB_DQS_DP<6>")
	)
	(segment
		(start 408.285696 -295.088818)
		(end 408.600402 -294.774112)
		(width 0.16002)
		(layer "In4.Cu")
		(net "M_J_CPU0_SB_DQS_DP<6>")
	)
	(segment
		(start 407.22677 -293.40048)
		(end 407.50363 -293.40048)
		(width 0.16002)
		(layer "In4.Cu")
		(net "M_J_CPU0_SB_DQS_DP<6>")
	)
	(segment
		(start 407.758392 -295.088818)
		(end 408.285696 -295.088818)
		(width 0.16002)
		(layer "In4.Cu")
		(net "M_J_CPU0_SB_DQS_DP<6>")
	)
	(segment
		(start 426.099224 -295.810178)
		(end 426.949362 -296.660316)
		(width 0.16002)
		(layer "In4.Cu")
		(net "M_J_CPU0_SB_DQS_DP<6>")
	)
	(segment
		(start 410.250894 -296.147744)
		(end 410.400754 -296.297604)
		(width 0.16002)
		(layer "In4.Cu")
		(net "M_J_CPU0_SB_DQS_DP<6>")
	)
	(segment
		(start 391.6934 -281.861006)
		(end 391.703814 -281.867102)
		(width 0.09525)
		(layer "In4.Cu")
		(net "M_J_CPU0_SB_DQS_DP<6>")
	)
	(segment
		(start 409.132024 -296.46245)
		(end 409.659328 -296.46245)
		(width 0.16002)
		(layer "In4.Cu")
		(net "M_J_CPU0_SB_DQS_DP<6>")
	)
	(arc
		(start 383.233422 -281.861006)
		(mid 383.514854 -281.936761)
		(end 383.796286 -281.861006)
		(width 0.09525)
		(layer "In4.Cu")
		(net "M_J_CPU0_SB_DQS_DP<6>")
	)
	(arc
		(start 386.993384 -281.861006)
		(mid 387.274816 -281.936761)
		(end 387.556248 -281.861006)
		(width 0.09525)
		(layer "In4.Cu")
		(net "M_J_CPU0_SB_DQS_DP<6>")
	)
	(arc
		(start 384.173476 -281.861006)
		(mid 384.454908 -281.936761)
		(end 384.73634 -281.861006)
		(width 0.09525)
		(layer "In4.Cu")
		(net "M_J_CPU0_SB_DQS_DP<6>")
	)
	(arc
		(start 387.56463 -281.85618)
		(mid 387.749662 -281.810266)
		(end 387.933438 -281.861006)
		(width 0.09525)
		(layer "In4.Cu")
		(net "M_J_CPU0_SB_DQS_DP<6>")
	)
	(arc
		(start 385.113276 -281.861006)
		(mid 385.394708 -281.936761)
		(end 385.67614 -281.861006)
		(width 0.09525)
		(layer "In4.Cu")
		(net "M_J_CPU0_SB_DQS_DP<6>")
	)
	(arc
		(start 379.560074 -281.902154)
		(mid 379.802816 -281.934924)
		(end 380.036324 -281.861006)
		(width 0.09525)
		(layer "In4.Cu")
		(net "M_J_CPU0_SB_DQS_DP<6>")
	)
	(arc
		(start 382.864614 -281.85618)
		(mid 383.049646 -281.810266)
		(end 383.233422 -281.861006)
		(width 0.09525)
		(layer "In4.Cu")
		(net "M_J_CPU0_SB_DQS_DP<6>")
	)
	(arc
		(start 379.5395 -281.894026)
		(mid 379.549748 -281.898189)
		(end 379.560074 -281.902154)
		(width 0.09525)
		(layer "In4.Cu")
		(net "M_J_CPU0_SB_DQS_DP<6>")
	)
	(arc
		(start 380.976378 -281.861006)
		(mid 381.164846 -281.810329)
		(end 381.353314 -281.861006)
		(width 0.09525)
		(layer "In4.Cu")
		(net "M_J_CPU0_SB_DQS_DP<6>")
	)
	(arc
		(start 389.436356 -281.861006)
		(mid 389.624824 -281.810329)
		(end 389.813292 -281.861006)
		(width 0.09525)
		(layer "In4.Cu")
		(net "M_J_CPU0_SB_DQS_DP<6>")
	)
	(arc
		(start 390.753346 -281.861006)
		(mid 391.034778 -281.936761)
		(end 391.31621 -281.861006)
		(width 0.09525)
		(layer "In4.Cu")
		(net "M_J_CPU0_SB_DQS_DP<6>")
	)
	(arc
		(start 380.413514 -281.861006)
		(mid 380.694946 -281.936761)
		(end 380.976378 -281.861006)
		(width 0.09525)
		(layer "In4.Cu")
		(net "M_J_CPU0_SB_DQS_DP<6>")
	)
	(arc
		(start 380.044706 -281.85618)
		(mid 380.229738 -281.810266)
		(end 380.413514 -281.861006)
		(width 0.09525)
		(layer "In4.Cu")
		(net "M_J_CPU0_SB_DQS_DP<6>")
	)
	(arc
		(start 384.73634 -281.861006)
		(mid 384.924808 -281.810329)
		(end 385.113276 -281.861006)
		(width 0.09525)
		(layer "In4.Cu")
		(net "M_J_CPU0_SB_DQS_DP<6>")
	)
	(arc
		(start 383.804668 -281.85618)
		(mid 383.9897 -281.810266)
		(end 384.173476 -281.861006)
		(width 0.09525)
		(layer "In4.Cu")
		(net "M_J_CPU0_SB_DQS_DP<6>")
	)
	(arc
		(start 388.873492 -281.861006)
		(mid 389.154924 -281.936761)
		(end 389.436356 -281.861006)
		(width 0.09525)
		(layer "In4.Cu")
		(net "M_J_CPU0_SB_DQS_DP<6>")
	)
	(arc
		(start 394.42644 -281.809698)
		(mid 394.486475 -281.818969)
		(end 394.540994 -281.845766)
		(width 0.09525)
		(layer "In4.Cu")
		(net "M_J_CPU0_SB_DQS_DP<6>")
	)
	(arc
		(start 393.18184 -281.869642)
		(mid 393.279012 -281.825111)
		(end 393.384786 -281.809698)
		(width 0.09525)
		(layer "In4.Cu")
		(net "M_J_CPU0_SB_DQS_DP<6>")
	)
	(arc
		(start 386.616194 -281.861006)
		(mid 386.799969 -281.810234)
		(end 386.985002 -281.85618)
		(width 0.09525)
		(layer "In4.Cu")
		(net "M_J_CPU0_SB_DQS_DP<6>")
	)
	(arc
		(start 391.324592 -281.85618)
		(mid 391.509624 -281.810266)
		(end 391.6934 -281.861006)
		(width 0.09525)
		(layer "In4.Cu")
		(net "M_J_CPU0_SB_DQS_DP<6>")
	)
	(arc
		(start 392.256518 -281.861006)
		(mid 392.440547 -281.810107)
		(end 392.625834 -281.85618)
		(width 0.09525)
		(layer "In4.Cu")
		(net "M_J_CPU0_SB_DQS_DP<6>")
	)
	(arc
		(start 385.67614 -281.861006)
		(mid 385.859915 -281.810234)
		(end 386.044948 -281.85618)
		(width 0.09525)
		(layer "In4.Cu")
		(net "M_J_CPU0_SB_DQS_DP<6>")
	)
	(arc
		(start 382.293368 -281.861006)
		(mid 382.5748 -281.936761)
		(end 382.856232 -281.861006)
		(width 0.09525)
		(layer "In4.Cu")
		(net "M_J_CPU0_SB_DQS_DP<6>")
	)
	(arc
		(start 386.05333 -281.861006)
		(mid 386.334762 -281.936761)
		(end 386.616194 -281.861006)
		(width 0.09525)
		(layer "In4.Cu")
		(net "M_J_CPU0_SB_DQS_DP<6>")
	)
	(arc
		(start 388.504684 -281.85618)
		(mid 388.689716 -281.810266)
		(end 388.873492 -281.861006)
		(width 0.09525)
		(layer "In4.Cu")
		(net "M_J_CPU0_SB_DQS_DP<6>")
	)
	(arc
		(start 390.376156 -281.861006)
		(mid 390.559931 -281.810234)
		(end 390.744964 -281.85618)
		(width 0.09525)
		(layer "In4.Cu")
		(net "M_J_CPU0_SB_DQS_DP<6>")
	)
	(arc
		(start 381.353314 -281.861006)
		(mid 381.634746 -281.936761)
		(end 381.916178 -281.861006)
		(width 0.09525)
		(layer "In4.Cu")
		(net "M_J_CPU0_SB_DQS_DP<6>")
	)
	(arc
		(start 391.703814 -281.867102)
		(mid 391.980976 -281.936902)
		(end 392.256518 -281.861006)
		(width 0.09525)
		(layer "In4.Cu")
		(net "M_J_CPU0_SB_DQS_DP<6>")
	)
	(arc
		(start 392.634216 -281.861006)
		(mid 392.90689 -281.936693)
		(end 393.18184 -281.869642)
		(width 0.09525)
		(layer "In4.Cu")
		(net "M_J_CPU0_SB_DQS_DP<6>")
	)
	(arc
		(start 387.933438 -281.861006)
		(mid 388.21487 -281.936761)
		(end 388.496302 -281.861006)
		(width 0.09525)
		(layer "In4.Cu")
		(net "M_J_CPU0_SB_DQS_DP<6>")
	)
	(arc
		(start 389.813292 -281.861006)
		(mid 390.094724 -281.936761)
		(end 390.376156 -281.861006)
		(width 0.09525)
		(layer "In4.Cu")
		(net "M_J_CPU0_SB_DQS_DP<6>")
	)
	(arc
		(start 381.916178 -281.861006)
		(mid 382.099953 -281.810234)
		(end 382.284986 -281.85618)
		(width 0.09525)
		(layer "In4.Cu")
		(net "M_J_CPU0_SB_DQS_DP<6>")
	)
	(segment
		(start 378.817886 -277.060152)
		(end 379.284738 -277.32609)
		(width 0.12954)
		(layer "F.Cu")
		(net "M_J_CPU0_SB_DQS_DP<5>")
	)
	(segment
		(start 432.644804 -286.460184)
		(end 432.793902 -286.311086)
		(width 0.16002)
		(layer "In4.Cu")
		(net "M_J_CPU0_SB_DQS_DP<5>")
	)
	(segment
		(start 383.796286 -277.00097)
		(end 383.804668 -276.996144)
		(width 0.09525)
		(layer "In4.Cu")
		(net "M_J_CPU0_SB_DQS_DP<5>")
	)
	(segment
		(start 386.985002 -276.996144)
		(end 386.993384 -277.00097)
		(width 0.09525)
		(layer "In4.Cu")
		(net "M_J_CPU0_SB_DQS_DP<5>")
	)
	(segment
		(start 405.38781 -280.38552)
		(end 405.588216 -280.585926)
		(width 0.16002)
		(layer "In4.Cu")
		(net "M_J_CPU0_SB_DQS_DP<5>")
	)
	(segment
		(start 419.080442 -287.310322)
		(end 420.617142 -287.310322)
		(width 0.16002)
		(layer "In4.Cu")
		(net "M_J_CPU0_SB_DQS_DP<5>")
	)
	(segment
		(start 406.666954 -281.908504)
		(end 406.86736 -282.10891)
		(width 0.16002)
		(layer "In4.Cu")
		(net "M_J_CPU0_SB_DQS_DP<5>")
	)
	(segment
		(start 405.588216 -281.571446)
		(end 405.925274 -281.908504)
		(width 0.16002)
		(layer "In4.Cu")
		(net "M_J_CPU0_SB_DQS_DP<5>")
	)
	(segment
		(start 380.036324 -277.00097)
		(end 380.044706 -276.996144)
		(width 0.09525)
		(layer "In4.Cu")
		(net "M_J_CPU0_SB_DQS_DP<5>")
	)
	(segment
		(start 395.71168 -276.036278)
		(end 395.770608 -276.095206)
		(width 0.09525)
		(layer "In4.Cu")
		(net "M_J_CPU0_SB_DQS_DP<5>")
	)
	(segment
		(start 386.044948 -276.996144)
		(end 386.05333 -277.00097)
		(width 0.09525)
		(layer "In4.Cu")
		(net "M_J_CPU0_SB_DQS_DP<5>")
	)
	(segment
		(start 430.036478 -286.11957)
		(end 430.480978 -286.11957)
		(width 0.16002)
		(layer "In4.Cu")
		(net "M_J_CPU0_SB_DQS_DP<5>")
	)
	(segment
		(start 404.014178 -279.011888)
		(end 404.242016 -279.239726)
		(width 0.16002)
		(layer "In4.Cu")
		(net "M_J_CPU0_SB_DQS_DP<5>")
	)
	(segment
		(start 428.167546 -287.310322)
		(end 428.509938 -286.96793)
		(width 0.16002)
		(layer "In4.Cu")
		(net "M_J_CPU0_SB_DQS_DP<5>")
	)
	(segment
		(start 387.556248 -277.00097)
		(end 387.56463 -276.996144)
		(width 0.09525)
		(layer "In4.Cu")
		(net "M_J_CPU0_SB_DQS_DP<5>")
	)
	(segment
		(start 430.821592 -286.460184)
		(end 432.644804 -286.460184)
		(width 0.16002)
		(layer "In4.Cu")
		(net "M_J_CPU0_SB_DQS_DP<5>")
	)
	(segment
		(start 422.407588 -286.0929)
		(end 422.937432 -286.0929)
		(width 0.16002)
		(layer "In4.Cu")
		(net "M_J_CPU0_SB_DQS_DP<5>")
	)
	(segment
		(start 404.579074 -280.38552)
		(end 405.38781 -280.38552)
		(width 0.16002)
		(layer "In4.Cu")
		(net "M_J_CPU0_SB_DQS_DP<5>")
	)
	(segment
		(start 434.72608 -286.311086)
		(end 435.000146 -286.585152)
		(width 0.16002)
		(layer "In4.Cu")
		(net "M_J_CPU0_SB_DQS_DP<5>")
	)
	(segment
		(start 417.86429 -286.09417)
		(end 419.080442 -287.310322)
		(width 0.16002)
		(layer "In4.Cu")
		(net "M_J_CPU0_SB_DQS_DP<5>")
	)
	(segment
		(start 393.726162 -276.712172)
		(end 393.79398 -276.67839)
		(width 0.09525)
		(layer "In4.Cu")
		(net "M_J_CPU0_SB_DQS_DP<5>")
	)
	(segment
		(start 390.744964 -276.996144)
		(end 390.753346 -277.00097)
		(width 0.09525)
		(layer "In4.Cu")
		(net "M_J_CPU0_SB_DQS_DP<5>")
	)
	(segment
		(start 406.86736 -282.10891)
		(end 406.86736 -282.85059)
		(width 0.16002)
		(layer "In4.Cu")
		(net "M_J_CPU0_SB_DQS_DP<5>")
	)
	(segment
		(start 392.626342 -276.99589)
		(end 392.627104 -276.996398)
		(width 0.09525)
		(layer "In4.Cu")
		(net "M_J_CPU0_SB_DQS_DP<5>")
	)
	(segment
		(start 405.925274 -281.908504)
		(end 406.666954 -281.908504)
		(width 0.16002)
		(layer "In4.Cu")
		(net "M_J_CPU0_SB_DQS_DP<5>")
	)
	(segment
		(start 394.189966 -276.392894)
		(end 394.72108 -275.86178)
		(width 0.09525)
		(layer "In4.Cu")
		(net "M_J_CPU0_SB_DQS_DP<5>")
	)
	(segment
		(start 391.6934 -277.00097)
		(end 391.703814 -277.007066)
		(width 0.09525)
		(layer "In4.Cu")
		(net "M_J_CPU0_SB_DQS_DP<5>")
	)
	(segment
		(start 423.304716 -286.460184)
		(end 426.099224 -286.460184)
		(width 0.16002)
		(layer "In4.Cu")
		(net "M_J_CPU0_SB_DQS_DP<5>")
	)
	(segment
		(start 391.31621 -277.00097)
		(end 391.324592 -276.996144)
		(width 0.09525)
		(layer "In4.Cu")
		(net "M_J_CPU0_SB_DQS_DP<5>")
	)
	(segment
		(start 420.617142 -287.310322)
		(end 420.959534 -286.96793)
		(width 0.16002)
		(layer "In4.Cu")
		(net "M_J_CPU0_SB_DQS_DP<5>")
	)
	(segment
		(start 379.284738 -277.32609)
		(end 379.438662 -277.06066)
		(width 0.09525)
		(layer "In4.Cu")
		(net "M_J_CPU0_SB_DQS_DP<5>")
	)
	(segment
		(start 420.959534 -286.96793)
		(end 421.532558 -286.96793)
		(width 0.16002)
		(layer "In4.Cu")
		(net "M_J_CPU0_SB_DQS_DP<5>")
	)
	(segment
		(start 411.69717 -285.835852)
		(end 412.808928 -286.94761)
		(width 0.16002)
		(layer "In4.Cu")
		(net "M_J_CPU0_SB_DQS_DP<5>")
	)
	(segment
		(start 400.111976 -276.095206)
		(end 403.028658 -279.011888)
		(width 0.16002)
		(layer "In4.Cu")
		(net "M_J_CPU0_SB_DQS_DP<5>")
	)
	(segment
		(start 379.438662 -277.06066)
		(end 379.5395 -277.03399)
		(width 0.09525)
		(layer "In4.Cu")
		(net "M_J_CPU0_SB_DQS_DP<5>")
	)
	(segment
		(start 422.937432 -286.0929)
		(end 423.304716 -286.460184)
		(width 0.16002)
		(layer "In4.Cu")
		(net "M_J_CPU0_SB_DQS_DP<5>")
	)
	(segment
		(start 426.099224 -286.460184)
		(end 426.949362 -287.310322)
		(width 0.16002)
		(layer "In4.Cu")
		(net "M_J_CPU0_SB_DQS_DP<5>")
	)
	(segment
		(start 394.72108 -275.86178)
		(end 395.233906 -275.86178)
		(width 0.09525)
		(layer "In4.Cu")
		(net "M_J_CPU0_SB_DQS_DP<5>")
	)
	(segment
		(start 403.028658 -279.011888)
		(end 404.014178 -279.011888)
		(width 0.16002)
		(layer "In4.Cu")
		(net "M_J_CPU0_SB_DQS_DP<5>")
	)
	(segment
		(start 393.160758 -277.010876)
		(end 393.726162 -276.712172)
		(width 0.09525)
		(layer "In4.Cu")
		(net "M_J_CPU0_SB_DQS_DP<5>")
	)
	(segment
		(start 428.509938 -286.96793)
		(end 429.188118 -286.96793)
		(width 0.16002)
		(layer "In4.Cu")
		(net "M_J_CPU0_SB_DQS_DP<5>")
	)
	(segment
		(start 421.532558 -286.96793)
		(end 422.407588 -286.0929)
		(width 0.16002)
		(layer "In4.Cu")
		(net "M_J_CPU0_SB_DQS_DP<5>")
	)
	(segment
		(start 404.242016 -279.239726)
		(end 404.242016 -280.048462)
		(width 0.16002)
		(layer "In4.Cu")
		(net "M_J_CPU0_SB_DQS_DP<5>")
	)
	(segment
		(start 382.284986 -276.996144)
		(end 382.293368 -277.00097)
		(width 0.09525)
		(layer "In4.Cu")
		(net "M_J_CPU0_SB_DQS_DP<5>")
	)
	(segment
		(start 432.793902 -286.311086)
		(end 434.72608 -286.311086)
		(width 0.16002)
		(layer "In4.Cu")
		(net "M_J_CPU0_SB_DQS_DP<5>")
	)
	(segment
		(start 392.62812 -276.996906)
		(end 392.634216 -277.000462)
		(width 0.09525)
		(layer "In4.Cu")
		(net "M_J_CPU0_SB_DQS_DP<5>")
	)
	(segment
		(start 382.856232 -277.00097)
		(end 382.864614 -276.996144)
		(width 0.09525)
		(layer "In4.Cu")
		(net "M_J_CPU0_SB_DQS_DP<5>")
	)
	(segment
		(start 405.588216 -280.585926)
		(end 405.588216 -281.571446)
		(width 0.16002)
		(layer "In4.Cu")
		(net "M_J_CPU0_SB_DQS_DP<5>")
	)
	(segment
		(start 392.627104 -276.996398)
		(end 392.62812 -276.996906)
		(width 0.09525)
		(layer "In4.Cu")
		(net "M_J_CPU0_SB_DQS_DP<5>")
	)
	(segment
		(start 429.188118 -286.96793)
		(end 430.036478 -286.11957)
		(width 0.16002)
		(layer "In4.Cu")
		(net "M_J_CPU0_SB_DQS_DP<5>")
	)
	(segment
		(start 430.480978 -286.11957)
		(end 430.821592 -286.460184)
		(width 0.16002)
		(layer "In4.Cu")
		(net "M_J_CPU0_SB_DQS_DP<5>")
	)
	(segment
		(start 406.86736 -282.85059)
		(end 407.271474 -283.254704)
		(width 0.16002)
		(layer "In4.Cu")
		(net "M_J_CPU0_SB_DQS_DP<5>")
	)
	(segment
		(start 410.838142 -285.835852)
		(end 411.69717 -285.835852)
		(width 0.16002)
		(layer "In4.Cu")
		(net "M_J_CPU0_SB_DQS_DP<5>")
	)
	(segment
		(start 404.242016 -280.048462)
		(end 404.579074 -280.38552)
		(width 0.16002)
		(layer "In4.Cu")
		(net "M_J_CPU0_SB_DQS_DP<5>")
	)
	(segment
		(start 414.001458 -286.94761)
		(end 414.854898 -286.09417)
		(width 0.16002)
		(layer "In4.Cu")
		(net "M_J_CPU0_SB_DQS_DP<5>")
	)
	(segment
		(start 395.408404 -276.036278)
		(end 395.71168 -276.036278)
		(width 0.09525)
		(layer "In4.Cu")
		(net "M_J_CPU0_SB_DQS_DP<5>")
	)
	(segment
		(start 414.854898 -286.09417)
		(end 417.86429 -286.09417)
		(width 0.16002)
		(layer "In4.Cu")
		(net "M_J_CPU0_SB_DQS_DP<5>")
	)
	(segment
		(start 395.770608 -276.095206)
		(end 395.79423 -276.095206)
		(width 0.09525)
		(layer "In4.Cu")
		(net "M_J_CPU0_SB_DQS_DP<5>")
	)
	(segment
		(start 395.79423 -276.095206)
		(end 400.111976 -276.095206)
		(width 0.16002)
		(layer "In4.Cu")
		(net "M_J_CPU0_SB_DQS_DP<5>")
	)
	(segment
		(start 408.256994 -283.254704)
		(end 410.838142 -285.835852)
		(width 0.16002)
		(layer "In4.Cu")
		(net "M_J_CPU0_SB_DQS_DP<5>")
	)
	(segment
		(start 395.233906 -275.86178)
		(end 395.408404 -276.036278)
		(width 0.09525)
		(layer "In4.Cu")
		(net "M_J_CPU0_SB_DQS_DP<5>")
	)
	(segment
		(start 388.496302 -277.00097)
		(end 388.504684 -276.996144)
		(width 0.09525)
		(layer "In4.Cu")
		(net "M_J_CPU0_SB_DQS_DP<5>")
	)
	(segment
		(start 407.271474 -283.254704)
		(end 408.256994 -283.254704)
		(width 0.16002)
		(layer "In4.Cu")
		(net "M_J_CPU0_SB_DQS_DP<5>")
	)
	(segment
		(start 412.808928 -286.94761)
		(end 414.001458 -286.94761)
		(width 0.16002)
		(layer "In4.Cu")
		(net "M_J_CPU0_SB_DQS_DP<5>")
	)
	(segment
		(start 426.949362 -287.310322)
		(end 428.167546 -287.310322)
		(width 0.16002)
		(layer "In4.Cu")
		(net "M_J_CPU0_SB_DQS_DP<5>")
	)
	(segment
		(start 392.625834 -276.996144)
		(end 392.626342 -276.99589)
		(width 0.09525)
		(layer "In4.Cu")
		(net "M_J_CPU0_SB_DQS_DP<5>")
	)
	(arc
		(start 381.916178 -277.00097)
		(mid 382.099953 -276.950198)
		(end 382.284986 -276.996144)
		(width 0.09525)
		(layer "In4.Cu")
		(net "M_J_CPU0_SB_DQS_DP<5>")
	)
	(arc
		(start 393.79398 -276.67839)
		(mid 394.003482 -276.551602)
		(end 394.189966 -276.392894)
		(width 0.09525)
		(layer "In4.Cu")
		(net "M_J_CPU0_SB_DQS_DP<5>")
	)
	(arc
		(start 389.813292 -277.00097)
		(mid 390.094724 -277.076725)
		(end 390.376156 -277.00097)
		(width 0.09525)
		(layer "In4.Cu")
		(net "M_J_CPU0_SB_DQS_DP<5>")
	)
	(arc
		(start 390.376156 -277.00097)
		(mid 390.559931 -276.950198)
		(end 390.744964 -276.996144)
		(width 0.09525)
		(layer "In4.Cu")
		(net "M_J_CPU0_SB_DQS_DP<5>")
	)
	(arc
		(start 382.864614 -276.996144)
		(mid 383.049646 -276.95023)
		(end 383.233422 -277.00097)
		(width 0.09525)
		(layer "In4.Cu")
		(net "M_J_CPU0_SB_DQS_DP<5>")
	)
	(arc
		(start 387.56463 -276.996144)
		(mid 387.749662 -276.95023)
		(end 387.933438 -277.00097)
		(width 0.09525)
		(layer "In4.Cu")
		(net "M_J_CPU0_SB_DQS_DP<5>")
	)
	(arc
		(start 381.353314 -277.00097)
		(mid 381.634746 -277.076725)
		(end 381.916178 -277.00097)
		(width 0.09525)
		(layer "In4.Cu")
		(net "M_J_CPU0_SB_DQS_DP<5>")
	)
	(arc
		(start 388.873492 -277.00097)
		(mid 389.154924 -277.076725)
		(end 389.436356 -277.00097)
		(width 0.09525)
		(layer "In4.Cu")
		(net "M_J_CPU0_SB_DQS_DP<5>")
	)
	(arc
		(start 392.634216 -277.000462)
		(mid 392.896126 -277.073744)
		(end 393.160758 -277.010876)
		(width 0.09525)
		(layer "In4.Cu")
		(net "M_J_CPU0_SB_DQS_DP<5>")
	)
	(arc
		(start 380.413514 -277.00097)
		(mid 380.694946 -277.076725)
		(end 380.976378 -277.00097)
		(width 0.09525)
		(layer "In4.Cu")
		(net "M_J_CPU0_SB_DQS_DP<5>")
	)
	(arc
		(start 387.933438 -277.00097)
		(mid 388.21487 -277.076725)
		(end 388.496302 -277.00097)
		(width 0.09525)
		(layer "In4.Cu")
		(net "M_J_CPU0_SB_DQS_DP<5>")
	)
	(arc
		(start 391.324592 -276.996144)
		(mid 391.509624 -276.95023)
		(end 391.6934 -277.00097)
		(width 0.09525)
		(layer "In4.Cu")
		(net "M_J_CPU0_SB_DQS_DP<5>")
	)
	(arc
		(start 386.993384 -277.00097)
		(mid 387.274816 -277.076725)
		(end 387.556248 -277.00097)
		(width 0.09525)
		(layer "In4.Cu")
		(net "M_J_CPU0_SB_DQS_DP<5>")
	)
	(arc
		(start 389.436356 -277.00097)
		(mid 389.624824 -276.950293)
		(end 389.813292 -277.00097)
		(width 0.09525)
		(layer "In4.Cu")
		(net "M_J_CPU0_SB_DQS_DP<5>")
	)
	(arc
		(start 379.5395 -277.03399)
		(mid 379.549748 -277.038153)
		(end 379.560074 -277.042118)
		(width 0.09525)
		(layer "In4.Cu")
		(net "M_J_CPU0_SB_DQS_DP<5>")
	)
	(arc
		(start 384.173476 -277.00097)
		(mid 384.454908 -277.076725)
		(end 384.73634 -277.00097)
		(width 0.09525)
		(layer "In4.Cu")
		(net "M_J_CPU0_SB_DQS_DP<5>")
	)
	(arc
		(start 384.73634 -277.00097)
		(mid 384.924808 -276.950293)
		(end 385.113276 -277.00097)
		(width 0.09525)
		(layer "In4.Cu")
		(net "M_J_CPU0_SB_DQS_DP<5>")
	)
	(arc
		(start 385.67614 -277.00097)
		(mid 385.859915 -276.950198)
		(end 386.044948 -276.996144)
		(width 0.09525)
		(layer "In4.Cu")
		(net "M_J_CPU0_SB_DQS_DP<5>")
	)
	(arc
		(start 392.256518 -277.00097)
		(mid 392.440547 -276.950071)
		(end 392.625834 -276.996144)
		(width 0.09525)
		(layer "In4.Cu")
		(net "M_J_CPU0_SB_DQS_DP<5>")
	)
	(arc
		(start 391.703814 -277.007066)
		(mid 391.980976 -277.076866)
		(end 392.256518 -277.00097)
		(width 0.09525)
		(layer "In4.Cu")
		(net "M_J_CPU0_SB_DQS_DP<5>")
	)
	(arc
		(start 388.504684 -276.996144)
		(mid 388.689716 -276.95023)
		(end 388.873492 -277.00097)
		(width 0.09525)
		(layer "In4.Cu")
		(net "M_J_CPU0_SB_DQS_DP<5>")
	)
	(arc
		(start 383.804668 -276.996144)
		(mid 383.9897 -276.95023)
		(end 384.173476 -277.00097)
		(width 0.09525)
		(layer "In4.Cu")
		(net "M_J_CPU0_SB_DQS_DP<5>")
	)
	(arc
		(start 390.753346 -277.00097)
		(mid 391.034778 -277.076725)
		(end 391.31621 -277.00097)
		(width 0.09525)
		(layer "In4.Cu")
		(net "M_J_CPU0_SB_DQS_DP<5>")
	)
	(arc
		(start 386.05333 -277.00097)
		(mid 386.334762 -277.076725)
		(end 386.616194 -277.00097)
		(width 0.09525)
		(layer "In4.Cu")
		(net "M_J_CPU0_SB_DQS_DP<5>")
	)
	(arc
		(start 385.113276 -277.00097)
		(mid 385.394708 -277.076725)
		(end 385.67614 -277.00097)
		(width 0.09525)
		(layer "In4.Cu")
		(net "M_J_CPU0_SB_DQS_DP<5>")
	)
	(arc
		(start 379.560074 -277.042118)
		(mid 379.802816 -277.074888)
		(end 380.036324 -277.00097)
		(width 0.09525)
		(layer "In4.Cu")
		(net "M_J_CPU0_SB_DQS_DP<5>")
	)
	(arc
		(start 382.293368 -277.00097)
		(mid 382.5748 -277.076725)
		(end 382.856232 -277.00097)
		(width 0.09525)
		(layer "In4.Cu")
		(net "M_J_CPU0_SB_DQS_DP<5>")
	)
	(arc
		(start 380.976378 -277.00097)
		(mid 381.164846 -276.950293)
		(end 381.353314 -277.00097)
		(width 0.09525)
		(layer "In4.Cu")
		(net "M_J_CPU0_SB_DQS_DP<5>")
	)
	(arc
		(start 380.044706 -276.996144)
		(mid 380.229738 -276.95023)
		(end 380.413514 -277.00097)
		(width 0.09525)
		(layer "In4.Cu")
		(net "M_J_CPU0_SB_DQS_DP<5>")
	)
	(arc
		(start 386.616194 -277.00097)
		(mid 386.799969 -276.950198)
		(end 386.985002 -276.996144)
		(width 0.09525)
		(layer "In4.Cu")
		(net "M_J_CPU0_SB_DQS_DP<5>")
	)
	(arc
		(start 383.233422 -277.00097)
		(mid 383.514854 -277.076725)
		(end 383.796286 -277.00097)
		(width 0.09525)
		(layer "In4.Cu")
		(net "M_J_CPU0_SB_DQS_DP<5>")
	)
	(segment
		(start 378.817886 -272.200116)
		(end 379.284738 -272.466054)
		(width 0.12954)
		(layer "F.Cu")
		(net "M_J_CPU0_SB_DQS_DP<4>")
	)
	(segment
		(start 409.837382 -274.619212)
		(end 410.114242 -274.619212)
		(width 0.16002)
		(layer "In4.Cu")
		(net "M_J_CPU0_SB_DQS_DP<4>")
	)
	(segment
		(start 409.11018 -274.81911)
		(end 409.637484 -274.81911)
		(width 0.16002)
		(layer "In4.Cu")
		(net "M_J_CPU0_SB_DQS_DP<4>")
	)
	(segment
		(start 426.949362 -277.960328)
		(end 428.167546 -277.960328)
		(width 0.16002)
		(layer "In4.Cu")
		(net "M_J_CPU0_SB_DQS_DP<4>")
	)
	(segment
		(start 410.114242 -274.619212)
		(end 410.310838 -274.815808)
		(width 0.16002)
		(layer "In4.Cu")
		(net "M_J_CPU0_SB_DQS_DP<4>")
	)
	(segment
		(start 392.933174 -272.089372)
		(end 394.42517 -270.597376)
		(width 0.09525)
		(layer "In4.Cu")
		(net "M_J_CPU0_SB_DQS_DP<4>")
	)
	(segment
		(start 420.959534 -277.617936)
		(end 421.532558 -277.617936)
		(width 0.16002)
		(layer "In4.Cu")
		(net "M_J_CPU0_SB_DQS_DP<4>")
	)
	(segment
		(start 428.167546 -277.960328)
		(end 428.509938 -277.617936)
		(width 0.16002)
		(layer "In4.Cu")
		(net "M_J_CPU0_SB_DQS_DP<4>")
	)
	(segment
		(start 383.796286 -272.140934)
		(end 383.804668 -272.136108)
		(width 0.09525)
		(layer "In4.Cu")
		(net "M_J_CPU0_SB_DQS_DP<4>")
	)
	(segment
		(start 382.284986 -272.136108)
		(end 382.293368 -272.140934)
		(width 0.09525)
		(layer "In4.Cu")
		(net "M_J_CPU0_SB_DQS_DP<4>")
	)
	(segment
		(start 430.480978 -276.769576)
		(end 430.821592 -277.11019)
		(width 0.16002)
		(layer "In4.Cu")
		(net "M_J_CPU0_SB_DQS_DP<4>")
	)
	(segment
		(start 404.73757 -270.4465)
		(end 407.736548 -273.445478)
		(width 0.16002)
		(layer "In4.Cu")
		(net "M_J_CPU0_SB_DQS_DP<4>")
	)
	(segment
		(start 420.617142 -277.960328)
		(end 420.959534 -277.617936)
		(width 0.16002)
		(layer "In4.Cu")
		(net "M_J_CPU0_SB_DQS_DP<4>")
	)
	(segment
		(start 390.744964 -272.136108)
		(end 390.753346 -272.140934)
		(width 0.09525)
		(layer "In4.Cu")
		(net "M_J_CPU0_SB_DQS_DP<4>")
	)
	(segment
		(start 395.667992 -270.387572)
		(end 395.72692 -270.4465)
		(width 0.09525)
		(layer "In4.Cu")
		(net "M_J_CPU0_SB_DQS_DP<4>")
	)
	(segment
		(start 395.750542 -270.4465)
		(end 404.73757 -270.4465)
		(width 0.16002)
		(layer "In4.Cu")
		(net "M_J_CPU0_SB_DQS_DP<4>")
	)
	(segment
		(start 408.263852 -273.445478)
		(end 408.46375 -273.24558)
		(width 0.16002)
		(layer "In4.Cu")
		(net "M_J_CPU0_SB_DQS_DP<4>")
	)
	(segment
		(start 413.092646 -277.597616)
		(end 414.001458 -277.597616)
		(width 0.16002)
		(layer "In4.Cu")
		(net "M_J_CPU0_SB_DQS_DP<4>")
	)
	(segment
		(start 379.438662 -272.200624)
		(end 379.5395 -272.173954)
		(width 0.09525)
		(layer "In4.Cu")
		(net "M_J_CPU0_SB_DQS_DP<4>")
	)
	(segment
		(start 382.856232 -272.140934)
		(end 382.864614 -272.136108)
		(width 0.09525)
		(layer "In4.Cu")
		(net "M_J_CPU0_SB_DQS_DP<4>")
	)
	(segment
		(start 410.11094 -275.292566)
		(end 410.11094 -275.81987)
		(width 0.16002)
		(layer "In4.Cu")
		(net "M_J_CPU0_SB_DQS_DP<4>")
	)
	(segment
		(start 387.556248 -272.140934)
		(end 387.56463 -272.136108)
		(width 0.09525)
		(layer "In4.Cu")
		(net "M_J_CPU0_SB_DQS_DP<4>")
	)
	(segment
		(start 391.6934 -272.140934)
		(end 391.703814 -272.14703)
		(width 0.09525)
		(layer "In4.Cu")
		(net "M_J_CPU0_SB_DQS_DP<4>")
	)
	(segment
		(start 409.637484 -274.81911)
		(end 409.837382 -274.619212)
		(width 0.16002)
		(layer "In4.Cu")
		(net "M_J_CPU0_SB_DQS_DP<4>")
	)
	(segment
		(start 432.793902 -276.961092)
		(end 434.72608 -276.961092)
		(width 0.16002)
		(layer "In4.Cu")
		(net "M_J_CPU0_SB_DQS_DP<4>")
	)
	(segment
		(start 410.310838 -274.815808)
		(end 410.310838 -275.092668)
		(width 0.16002)
		(layer "In4.Cu")
		(net "M_J_CPU0_SB_DQS_DP<4>")
	)
	(segment
		(start 434.72608 -276.961092)
		(end 435.000146 -277.235158)
		(width 0.16002)
		(layer "In4.Cu")
		(net "M_J_CPU0_SB_DQS_DP<4>")
	)
	(segment
		(start 422.937432 -276.742906)
		(end 423.304716 -277.11019)
		(width 0.16002)
		(layer "In4.Cu")
		(net "M_J_CPU0_SB_DQS_DP<4>")
	)
	(segment
		(start 408.937206 -273.719036)
		(end 408.737308 -273.918934)
		(width 0.16002)
		(layer "In4.Cu")
		(net "M_J_CPU0_SB_DQS_DP<4>")
	)
	(segment
		(start 411.011116 -276.192742)
		(end 411.211014 -275.992844)
		(width 0.16002)
		(layer "In4.Cu")
		(net "M_J_CPU0_SB_DQS_DP<4>")
	)
	(segment
		(start 395.72692 -270.4465)
		(end 395.750542 -270.4465)
		(width 0.09525)
		(layer "In4.Cu")
		(net "M_J_CPU0_SB_DQS_DP<4>")
	)
	(segment
		(start 379.284738 -272.466054)
		(end 379.438662 -272.200624)
		(width 0.09525)
		(layer "In4.Cu")
		(net "M_J_CPU0_SB_DQS_DP<4>")
	)
	(segment
		(start 408.737308 -274.446238)
		(end 409.11018 -274.81911)
		(width 0.16002)
		(layer "In4.Cu")
		(net "M_J_CPU0_SB_DQS_DP<4>")
	)
	(segment
		(start 391.31621 -272.140934)
		(end 391.324592 -272.136108)
		(width 0.09525)
		(layer "In4.Cu")
		(net "M_J_CPU0_SB_DQS_DP<4>")
	)
	(segment
		(start 380.036324 -272.140934)
		(end 380.044706 -272.136108)
		(width 0.09525)
		(layer "In4.Cu")
		(net "M_J_CPU0_SB_DQS_DP<4>")
	)
	(segment
		(start 394.42517 -270.597376)
		(end 394.959078 -270.597376)
		(width 0.09525)
		(layer "In4.Cu")
		(net "M_J_CPU0_SB_DQS_DP<4>")
	)
	(segment
		(start 386.985002 -272.136108)
		(end 386.993384 -272.140934)
		(width 0.09525)
		(layer "In4.Cu")
		(net "M_J_CPU0_SB_DQS_DP<4>")
	)
	(segment
		(start 410.11094 -275.81987)
		(end 410.483812 -276.192742)
		(width 0.16002)
		(layer "In4.Cu")
		(net "M_J_CPU0_SB_DQS_DP<4>")
	)
	(segment
		(start 432.644804 -277.11019)
		(end 432.793902 -276.961092)
		(width 0.16002)
		(layer "In4.Cu")
		(net "M_J_CPU0_SB_DQS_DP<4>")
	)
	(segment
		(start 388.496302 -272.140934)
		(end 388.504684 -272.136108)
		(width 0.09525)
		(layer "In4.Cu")
		(net "M_J_CPU0_SB_DQS_DP<4>")
	)
	(segment
		(start 426.099224 -277.11019)
		(end 426.949362 -277.960328)
		(width 0.16002)
		(layer "In4.Cu")
		(net "M_J_CPU0_SB_DQS_DP<4>")
	)
	(segment
		(start 395.168882 -270.387572)
		(end 395.667992 -270.387572)
		(width 0.09525)
		(layer "In4.Cu")
		(net "M_J_CPU0_SB_DQS_DP<4>")
	)
	(segment
		(start 407.736548 -273.445478)
		(end 408.263852 -273.445478)
		(width 0.16002)
		(layer "In4.Cu")
		(net "M_J_CPU0_SB_DQS_DP<4>")
	)
	(segment
		(start 414.001458 -277.597616)
		(end 414.854898 -276.744176)
		(width 0.16002)
		(layer "In4.Cu")
		(net "M_J_CPU0_SB_DQS_DP<4>")
	)
	(segment
		(start 428.509938 -277.617936)
		(end 429.188118 -277.617936)
		(width 0.16002)
		(layer "In4.Cu")
		(net "M_J_CPU0_SB_DQS_DP<4>")
	)
	(segment
		(start 430.036478 -276.769576)
		(end 430.480978 -276.769576)
		(width 0.16002)
		(layer "In4.Cu")
		(net "M_J_CPU0_SB_DQS_DP<4>")
	)
	(segment
		(start 408.74061 -273.24558)
		(end 408.937206 -273.442176)
		(width 0.16002)
		(layer "In4.Cu")
		(net "M_J_CPU0_SB_DQS_DP<4>")
	)
	(segment
		(start 410.483812 -276.192742)
		(end 411.011116 -276.192742)
		(width 0.16002)
		(layer "In4.Cu")
		(net "M_J_CPU0_SB_DQS_DP<4>")
	)
	(segment
		(start 429.188118 -277.617936)
		(end 430.036478 -276.769576)
		(width 0.16002)
		(layer "In4.Cu")
		(net "M_J_CPU0_SB_DQS_DP<4>")
	)
	(segment
		(start 418.87521 -277.960328)
		(end 420.617142 -277.960328)
		(width 0.16002)
		(layer "In4.Cu")
		(net "M_J_CPU0_SB_DQS_DP<4>")
	)
	(segment
		(start 408.46375 -273.24558)
		(end 408.74061 -273.24558)
		(width 0.16002)
		(layer "In4.Cu")
		(net "M_J_CPU0_SB_DQS_DP<4>")
	)
	(segment
		(start 417.659058 -276.744176)
		(end 418.87521 -277.960328)
		(width 0.16002)
		(layer "In4.Cu")
		(net "M_J_CPU0_SB_DQS_DP<4>")
	)
	(segment
		(start 410.310838 -275.092668)
		(end 410.11094 -275.292566)
		(width 0.16002)
		(layer "In4.Cu")
		(net "M_J_CPU0_SB_DQS_DP<4>")
	)
	(segment
		(start 421.532558 -277.617936)
		(end 422.407588 -276.742906)
		(width 0.16002)
		(layer "In4.Cu")
		(net "M_J_CPU0_SB_DQS_DP<4>")
	)
	(segment
		(start 394.959078 -270.597376)
		(end 395.168882 -270.387572)
		(width 0.09525)
		(layer "In4.Cu")
		(net "M_J_CPU0_SB_DQS_DP<4>")
	)
	(segment
		(start 411.211014 -275.992844)
		(end 411.487874 -275.992844)
		(width 0.16002)
		(layer "In4.Cu")
		(net "M_J_CPU0_SB_DQS_DP<4>")
	)
	(segment
		(start 392.445494 -272.089372)
		(end 392.933174 -272.089372)
		(width 0.09525)
		(layer "In4.Cu")
		(net "M_J_CPU0_SB_DQS_DP<4>")
	)
	(segment
		(start 422.407588 -276.742906)
		(end 422.937432 -276.742906)
		(width 0.16002)
		(layer "In4.Cu")
		(net "M_J_CPU0_SB_DQS_DP<4>")
	)
	(segment
		(start 408.937206 -273.442176)
		(end 408.937206 -273.719036)
		(width 0.16002)
		(layer "In4.Cu")
		(net "M_J_CPU0_SB_DQS_DP<4>")
	)
	(segment
		(start 423.304716 -277.11019)
		(end 426.099224 -277.11019)
		(width 0.16002)
		(layer "In4.Cu")
		(net "M_J_CPU0_SB_DQS_DP<4>")
	)
	(segment
		(start 430.821592 -277.11019)
		(end 432.644804 -277.11019)
		(width 0.16002)
		(layer "In4.Cu")
		(net "M_J_CPU0_SB_DQS_DP<4>")
	)
	(segment
		(start 408.737308 -273.918934)
		(end 408.737308 -274.446238)
		(width 0.16002)
		(layer "In4.Cu")
		(net "M_J_CPU0_SB_DQS_DP<4>")
	)
	(segment
		(start 414.854898 -276.744176)
		(end 417.659058 -276.744176)
		(width 0.16002)
		(layer "In4.Cu")
		(net "M_J_CPU0_SB_DQS_DP<4>")
	)
	(segment
		(start 411.487874 -275.992844)
		(end 413.092646 -277.597616)
		(width 0.16002)
		(layer "In4.Cu")
		(net "M_J_CPU0_SB_DQS_DP<4>")
	)
	(segment
		(start 386.044948 -272.136108)
		(end 386.05333 -272.140934)
		(width 0.09525)
		(layer "In4.Cu")
		(net "M_J_CPU0_SB_DQS_DP<4>")
	)
	(arc
		(start 380.413514 -272.140934)
		(mid 380.694946 -272.216689)
		(end 380.976378 -272.140934)
		(width 0.09525)
		(layer "In4.Cu")
		(net "M_J_CPU0_SB_DQS_DP<4>")
	)
	(arc
		(start 391.703814 -272.14703)
		(mid 391.980976 -272.21683)
		(end 392.256518 -272.140934)
		(width 0.09525)
		(layer "In4.Cu")
		(net "M_J_CPU0_SB_DQS_DP<4>")
	)
	(arc
		(start 389.813292 -272.140934)
		(mid 390.094724 -272.216689)
		(end 390.376156 -272.140934)
		(width 0.09525)
		(layer "In4.Cu")
		(net "M_J_CPU0_SB_DQS_DP<4>")
	)
	(arc
		(start 387.933438 -272.140934)
		(mid 388.21487 -272.216689)
		(end 388.496302 -272.140934)
		(width 0.09525)
		(layer "In4.Cu")
		(net "M_J_CPU0_SB_DQS_DP<4>")
	)
	(arc
		(start 388.504684 -272.136108)
		(mid 388.689716 -272.090194)
		(end 388.873492 -272.140934)
		(width 0.09525)
		(layer "In4.Cu")
		(net "M_J_CPU0_SB_DQS_DP<4>")
	)
	(arc
		(start 392.256518 -272.140934)
		(mid 392.347595 -272.10265)
		(end 392.445494 -272.089372)
		(width 0.09525)
		(layer "In4.Cu")
		(net "M_J_CPU0_SB_DQS_DP<4>")
	)
	(arc
		(start 384.73634 -272.140934)
		(mid 384.924808 -272.090257)
		(end 385.113276 -272.140934)
		(width 0.09525)
		(layer "In4.Cu")
		(net "M_J_CPU0_SB_DQS_DP<4>")
	)
	(arc
		(start 391.324592 -272.136108)
		(mid 391.509624 -272.090194)
		(end 391.6934 -272.140934)
		(width 0.09525)
		(layer "In4.Cu")
		(net "M_J_CPU0_SB_DQS_DP<4>")
	)
	(arc
		(start 380.044706 -272.136108)
		(mid 380.229738 -272.090194)
		(end 380.413514 -272.140934)
		(width 0.09525)
		(layer "In4.Cu")
		(net "M_J_CPU0_SB_DQS_DP<4>")
	)
	(arc
		(start 387.56463 -272.136108)
		(mid 387.749662 -272.090194)
		(end 387.933438 -272.140934)
		(width 0.09525)
		(layer "In4.Cu")
		(net "M_J_CPU0_SB_DQS_DP<4>")
	)
	(arc
		(start 388.873492 -272.140934)
		(mid 389.154924 -272.216689)
		(end 389.436356 -272.140934)
		(width 0.09525)
		(layer "In4.Cu")
		(net "M_J_CPU0_SB_DQS_DP<4>")
	)
	(arc
		(start 390.753346 -272.140934)
		(mid 391.034778 -272.216689)
		(end 391.31621 -272.140934)
		(width 0.09525)
		(layer "In4.Cu")
		(net "M_J_CPU0_SB_DQS_DP<4>")
	)
	(arc
		(start 386.05333 -272.140934)
		(mid 386.334762 -272.216689)
		(end 386.616194 -272.140934)
		(width 0.09525)
		(layer "In4.Cu")
		(net "M_J_CPU0_SB_DQS_DP<4>")
	)
	(arc
		(start 380.976378 -272.140934)
		(mid 381.164846 -272.090257)
		(end 381.353314 -272.140934)
		(width 0.09525)
		(layer "In4.Cu")
		(net "M_J_CPU0_SB_DQS_DP<4>")
	)
	(arc
		(start 383.233422 -272.140934)
		(mid 383.514854 -272.216689)
		(end 383.796286 -272.140934)
		(width 0.09525)
		(layer "In4.Cu")
		(net "M_J_CPU0_SB_DQS_DP<4>")
	)
	(arc
		(start 382.293368 -272.140934)
		(mid 382.5748 -272.216689)
		(end 382.856232 -272.140934)
		(width 0.09525)
		(layer "In4.Cu")
		(net "M_J_CPU0_SB_DQS_DP<4>")
	)
	(arc
		(start 384.173476 -272.140934)
		(mid 384.454908 -272.216689)
		(end 384.73634 -272.140934)
		(width 0.09525)
		(layer "In4.Cu")
		(net "M_J_CPU0_SB_DQS_DP<4>")
	)
	(arc
		(start 386.616194 -272.140934)
		(mid 386.799969 -272.090162)
		(end 386.985002 -272.136108)
		(width 0.09525)
		(layer "In4.Cu")
		(net "M_J_CPU0_SB_DQS_DP<4>")
	)
	(arc
		(start 381.916178 -272.140934)
		(mid 382.099953 -272.090162)
		(end 382.284986 -272.136108)
		(width 0.09525)
		(layer "In4.Cu")
		(net "M_J_CPU0_SB_DQS_DP<4>")
	)
	(arc
		(start 381.353314 -272.140934)
		(mid 381.634746 -272.216689)
		(end 381.916178 -272.140934)
		(width 0.09525)
		(layer "In4.Cu")
		(net "M_J_CPU0_SB_DQS_DP<4>")
	)
	(arc
		(start 389.436356 -272.140934)
		(mid 389.624824 -272.090257)
		(end 389.813292 -272.140934)
		(width 0.09525)
		(layer "In4.Cu")
		(net "M_J_CPU0_SB_DQS_DP<4>")
	)
	(arc
		(start 385.113276 -272.140934)
		(mid 385.394708 -272.216689)
		(end 385.67614 -272.140934)
		(width 0.09525)
		(layer "In4.Cu")
		(net "M_J_CPU0_SB_DQS_DP<4>")
	)
	(arc
		(start 386.993384 -272.140934)
		(mid 387.274816 -272.216689)
		(end 387.556248 -272.140934)
		(width 0.09525)
		(layer "In4.Cu")
		(net "M_J_CPU0_SB_DQS_DP<4>")
	)
	(arc
		(start 390.376156 -272.140934)
		(mid 390.559931 -272.090162)
		(end 390.744964 -272.136108)
		(width 0.09525)
		(layer "In4.Cu")
		(net "M_J_CPU0_SB_DQS_DP<4>")
	)
	(arc
		(start 382.864614 -272.136108)
		(mid 383.049646 -272.090194)
		(end 383.233422 -272.140934)
		(width 0.09525)
		(layer "In4.Cu")
		(net "M_J_CPU0_SB_DQS_DP<4>")
	)
	(arc
		(start 383.804668 -272.136108)
		(mid 383.9897 -272.090194)
		(end 384.173476 -272.140934)
		(width 0.09525)
		(layer "In4.Cu")
		(net "M_J_CPU0_SB_DQS_DP<4>")
	)
	(arc
		(start 379.5395 -272.173954)
		(mid 379.791784 -272.215648)
		(end 380.036324 -272.140934)
		(width 0.09525)
		(layer "In4.Cu")
		(net "M_J_CPU0_SB_DQS_DP<4>")
	)
	(arc
		(start 385.67614 -272.140934)
		(mid 385.859915 -272.090162)
		(end 386.044948 -272.136108)
		(width 0.09525)
		(layer "In4.Cu")
		(net "M_J_CPU0_SB_DQS_DP<4>")
	)
	(segment
		(start 380.697994 -290.019994)
		(end 381.164846 -290.285932)
		(width 0.12954)
		(layer "F.Cu")
		(net "M_J_CPU0_SB_DQS_DP<3>")
	)
	(segment
		(start 420.692326 -313.394852)
		(end 421.461438 -313.394852)
		(width 0.16002)
		(layer "In4.Cu")
		(net "M_J_CPU0_SB_DQS_DP<3>")
	)
	(segment
		(start 392.630914 -290.611052)
		(end 392.654282 -290.59759)
		(width 0.09525)
		(layer "In4.Cu")
		(net "M_J_CPU0_SB_DQS_DP<3>")
	)
	(segment
		(start 381.164846 -290.285932)
		(end 381.010922 -290.551362)
		(width 0.09525)
		(layer "In4.Cu")
		(net "M_J_CPU0_SB_DQS_DP<3>")
	)
	(segment
		(start 422.89222 -312.888122)
		(end 423.5704 -312.209942)
		(width 0.16002)
		(layer "In4.Cu")
		(net "M_J_CPU0_SB_DQS_DP<3>")
	)
	(segment
		(start 436.522876 -313.394852)
		(end 436.708804 -313.208924)
		(width 0.16002)
		(layer "In4.Cu")
		(net "M_J_CPU0_SB_DQS_DP<3>")
	)
	(segment
		(start 391.31621 -290.611052)
		(end 391.324592 -290.615878)
		(width 0.09525)
		(layer "In4.Cu")
		(net "M_J_CPU0_SB_DQS_DP<3>")
	)
	(segment
		(start 395.20368 -293.684198)
		(end 396.208758 -294.689276)
		(width 0.16002)
		(layer "In4.Cu")
		(net "M_J_CPU0_SB_DQS_DP<3>")
	)
	(segment
		(start 418.450268 -313.059826)
		(end 420.3573 -313.059826)
		(width 0.16002)
		(layer "In4.Cu")
		(net "M_J_CPU0_SB_DQS_DP<3>")
	)
	(segment
		(start 437.632602 -313.208924)
		(end 437.749442 -313.092084)
		(width 0.16002)
		(layer "In4.Cu")
		(net "M_J_CPU0_SB_DQS_DP<3>")
	)
	(segment
		(start 392.25474 -290.611052)
		(end 392.269218 -290.619434)
		(width 0.09525)
		(layer "In4.Cu")
		(net "M_J_CPU0_SB_DQS_DP<3>")
	)
	(segment
		(start 396.208758 -301.07382)
		(end 408.203654 -313.068716)
		(width 0.16002)
		(layer "In4.Cu")
		(net "M_J_CPU0_SB_DQS_DP<3>")
	)
	(segment
		(start 413.446214 -313.405012)
		(end 413.92729 -313.405012)
		(width 0.16002)
		(layer "In4.Cu")
		(net "M_J_CPU0_SB_DQS_DP<3>")
	)
	(segment
		(start 390.744964 -290.615878)
		(end 390.753346 -290.611052)
		(width 0.09525)
		(layer "In4.Cu")
		(net "M_J_CPU0_SB_DQS_DP<3>")
	)
	(segment
		(start 425.207176 -312.209942)
		(end 426.056806 -313.059572)
		(width 0.16002)
		(layer "In4.Cu")
		(net "M_J_CPU0_SB_DQS_DP<3>")
	)
	(segment
		(start 395.103096 -293.667434)
		(end 395.186916 -293.667434)
		(width 0.09525)
		(layer "In4.Cu")
		(net "M_J_CPU0_SB_DQS_DP<3>")
	)
	(segment
		(start 382.284986 -290.615878)
		(end 382.293368 -290.611052)
		(width 0.09525)
		(layer "In4.Cu")
		(net "M_J_CPU0_SB_DQS_DP<3>")
	)
	(segment
		(start 433.438046 -312.990992)
		(end 433.977288 -312.990992)
		(width 0.16002)
		(layer "In4.Cu")
		(net "M_J_CPU0_SB_DQS_DP<3>")
	)
	(segment
		(start 383.796286 -290.611052)
		(end 383.804668 -290.615878)
		(width 0.09525)
		(layer "In4.Cu")
		(net "M_J_CPU0_SB_DQS_DP<3>")
	)
	(segment
		(start 433.977288 -312.990992)
		(end 434.094128 -312.874152)
		(width 0.16002)
		(layer "In4.Cu")
		(net "M_J_CPU0_SB_DQS_DP<3>")
	)
	(segment
		(start 429.167798 -313.371992)
		(end 429.711104 -312.828686)
		(width 0.16002)
		(layer "In4.Cu")
		(net "M_J_CPU0_SB_DQS_DP<3>")
	)
	(segment
		(start 430.8856 -312.209942)
		(end 432.656996 -312.209942)
		(width 0.16002)
		(layer "In4.Cu")
		(net "M_J_CPU0_SB_DQS_DP<3>")
	)
	(segment
		(start 434.574188 -312.874152)
		(end 434.691028 -312.990992)
		(width 0.16002)
		(layer "In4.Cu")
		(net "M_J_CPU0_SB_DQS_DP<3>")
	)
	(segment
		(start 382.856232 -290.611052)
		(end 382.864614 -290.615878)
		(width 0.09525)
		(layer "In4.Cu")
		(net "M_J_CPU0_SB_DQS_DP<3>")
	)
	(segment
		(start 392.22934 -290.59632)
		(end 392.25474 -290.611052)
		(width 0.09525)
		(layer "In4.Cu")
		(net "M_J_CPU0_SB_DQS_DP<3>")
	)
	(segment
		(start 421.461438 -313.394852)
		(end 421.968168 -312.888122)
		(width 0.16002)
		(layer "In4.Cu")
		(net "M_J_CPU0_SB_DQS_DP<3>")
	)
	(segment
		(start 396.208758 -294.689276)
		(end 396.208758 -301.07382)
		(width 0.16002)
		(layer "In4.Cu")
		(net "M_J_CPU0_SB_DQS_DP<3>")
	)
	(segment
		(start 414.71215 -312.620152)
		(end 418.010594 -312.620152)
		(width 0.16002)
		(layer "In4.Cu")
		(net "M_J_CPU0_SB_DQS_DP<3>")
	)
	(segment
		(start 418.010594 -312.620152)
		(end 418.450268 -313.059826)
		(width 0.16002)
		(layer "In4.Cu")
		(net "M_J_CPU0_SB_DQS_DP<3>")
	)
	(segment
		(start 386.044948 -290.615878)
		(end 386.05333 -290.611052)
		(width 0.09525)
		(layer "In4.Cu")
		(net "M_J_CPU0_SB_DQS_DP<3>")
	)
	(segment
		(start 429.711104 -312.828686)
		(end 430.266856 -312.828686)
		(width 0.16002)
		(layer "In4.Cu")
		(net "M_J_CPU0_SB_DQS_DP<3>")
	)
	(segment
		(start 381.010922 -290.551362)
		(end 381.034036 -290.637976)
		(width 0.09525)
		(layer "In4.Cu")
		(net "M_J_CPU0_SB_DQS_DP<3>")
	)
	(segment
		(start 386.985002 -290.615878)
		(end 386.993384 -290.611052)
		(width 0.09525)
		(layer "In4.Cu")
		(net "M_J_CPU0_SB_DQS_DP<3>")
	)
	(segment
		(start 438.229502 -313.092084)
		(end 438.346342 -313.208924)
		(width 0.16002)
		(layer "In4.Cu")
		(net "M_J_CPU0_SB_DQS_DP<3>")
	)
	(segment
		(start 428.441358 -313.371992)
		(end 429.167798 -313.371992)
		(width 0.16002)
		(layer "In4.Cu")
		(net "M_J_CPU0_SB_DQS_DP<3>")
	)
	(segment
		(start 432.656996 -312.209942)
		(end 433.438046 -312.990992)
		(width 0.16002)
		(layer "In4.Cu")
		(net "M_J_CPU0_SB_DQS_DP<3>")
	)
	(segment
		(start 438.826402 -313.208924)
		(end 439.100214 -312.935112)
		(width 0.16002)
		(layer "In4.Cu")
		(net "M_J_CPU0_SB_DQS_DP<3>")
	)
	(segment
		(start 436.708804 -313.208924)
		(end 437.632602 -313.208924)
		(width 0.16002)
		(layer "In4.Cu")
		(net "M_J_CPU0_SB_DQS_DP<3>")
	)
	(segment
		(start 420.3573 -313.059826)
		(end 420.692326 -313.394852)
		(width 0.16002)
		(layer "In4.Cu")
		(net "M_J_CPU0_SB_DQS_DP<3>")
	)
	(segment
		(start 434.691028 -312.990992)
		(end 435.475634 -312.990992)
		(width 0.16002)
		(layer "In4.Cu")
		(net "M_J_CPU0_SB_DQS_DP<3>")
	)
	(segment
		(start 393.310872 -290.699952)
		(end 393.594336 -290.983416)
		(width 0.09525)
		(layer "In4.Cu")
		(net "M_J_CPU0_SB_DQS_DP<3>")
	)
	(segment
		(start 423.5704 -312.209942)
		(end 425.207176 -312.209942)
		(width 0.16002)
		(layer "In4.Cu")
		(net "M_J_CPU0_SB_DQS_DP<3>")
	)
	(segment
		(start 393.594336 -290.983416)
		(end 394.441934 -293.006272)
		(width 0.09525)
		(layer "In4.Cu")
		(net "M_J_CPU0_SB_DQS_DP<3>")
	)
	(segment
		(start 408.203654 -313.068716)
		(end 413.109918 -313.068716)
		(width 0.16002)
		(layer "In4.Cu")
		(net "M_J_CPU0_SB_DQS_DP<3>")
	)
	(segment
		(start 387.556248 -290.611052)
		(end 387.56463 -290.615878)
		(width 0.09525)
		(layer "In4.Cu")
		(net "M_J_CPU0_SB_DQS_DP<3>")
	)
	(segment
		(start 395.186916 -293.667434)
		(end 395.20368 -293.684198)
		(width 0.09525)
		(layer "In4.Cu")
		(net "M_J_CPU0_SB_DQS_DP<3>")
	)
	(segment
		(start 388.496302 -290.611052)
		(end 388.504684 -290.615878)
		(width 0.09525)
		(layer "In4.Cu")
		(net "M_J_CPU0_SB_DQS_DP<3>")
	)
	(segment
		(start 394.441934 -293.006272)
		(end 395.103096 -293.667434)
		(width 0.09525)
		(layer "In4.Cu")
		(net "M_J_CPU0_SB_DQS_DP<3>")
	)
	(segment
		(start 435.475634 -312.990992)
		(end 435.879494 -313.394852)
		(width 0.16002)
		(layer "In4.Cu")
		(net "M_J_CPU0_SB_DQS_DP<3>")
	)
	(segment
		(start 421.968168 -312.888122)
		(end 422.89222 -312.888122)
		(width 0.16002)
		(layer "In4.Cu")
		(net "M_J_CPU0_SB_DQS_DP<3>")
	)
	(segment
		(start 438.346342 -313.208924)
		(end 438.826402 -313.208924)
		(width 0.16002)
		(layer "In4.Cu")
		(net "M_J_CPU0_SB_DQS_DP<3>")
	)
	(segment
		(start 435.879494 -313.394852)
		(end 436.522876 -313.394852)
		(width 0.16002)
		(layer "In4.Cu")
		(net "M_J_CPU0_SB_DQS_DP<3>")
	)
	(segment
		(start 413.92729 -313.405012)
		(end 414.71215 -312.620152)
		(width 0.16002)
		(layer "In4.Cu")
		(net "M_J_CPU0_SB_DQS_DP<3>")
	)
	(segment
		(start 437.749442 -313.092084)
		(end 438.229502 -313.092084)
		(width 0.16002)
		(layer "In4.Cu")
		(net "M_J_CPU0_SB_DQS_DP<3>")
	)
	(segment
		(start 428.128938 -313.059572)
		(end 428.441358 -313.371992)
		(width 0.16002)
		(layer "In4.Cu")
		(net "M_J_CPU0_SB_DQS_DP<3>")
	)
	(segment
		(start 426.056806 -313.059572)
		(end 428.128938 -313.059572)
		(width 0.16002)
		(layer "In4.Cu")
		(net "M_J_CPU0_SB_DQS_DP<3>")
	)
	(segment
		(start 413.109918 -313.068716)
		(end 413.446214 -313.405012)
		(width 0.16002)
		(layer "In4.Cu")
		(net "M_J_CPU0_SB_DQS_DP<3>")
	)
	(segment
		(start 434.094128 -312.874152)
		(end 434.574188 -312.874152)
		(width 0.16002)
		(layer "In4.Cu")
		(net "M_J_CPU0_SB_DQS_DP<3>")
	)
	(segment
		(start 430.266856 -312.828686)
		(end 430.8856 -312.209942)
		(width 0.16002)
		(layer "In4.Cu")
		(net "M_J_CPU0_SB_DQS_DP<3>")
	)
	(arc
		(start 389.813292 -290.611052)
		(mid 390.094724 -290.535297)
		(end 390.376156 -290.611052)
		(width 0.09525)
		(layer "In4.Cu")
		(net "M_J_CPU0_SB_DQS_DP<3>")
	)
	(arc
		(start 386.616194 -290.611052)
		(mid 386.799969 -290.661824)
		(end 386.985002 -290.615878)
		(width 0.09525)
		(layer "In4.Cu")
		(net "M_J_CPU0_SB_DQS_DP<3>")
	)
	(arc
		(start 388.504684 -290.615878)
		(mid 388.689716 -290.661792)
		(end 388.873492 -290.611052)
		(width 0.09525)
		(layer "In4.Cu")
		(net "M_J_CPU0_SB_DQS_DP<3>")
	)
	(arc
		(start 388.873492 -290.611052)
		(mid 389.154924 -290.535297)
		(end 389.436356 -290.611052)
		(width 0.09525)
		(layer "In4.Cu")
		(net "M_J_CPU0_SB_DQS_DP<3>")
	)
	(arc
		(start 392.654282 -290.59759)
		(mid 392.926383 -290.534912)
		(end 393.195048 -290.611052)
		(width 0.09525)
		(layer "In4.Cu")
		(net "M_J_CPU0_SB_DQS_DP<3>")
	)
	(arc
		(start 387.56463 -290.615878)
		(mid 387.749662 -290.661792)
		(end 387.933438 -290.611052)
		(width 0.09525)
		(layer "In4.Cu")
		(net "M_J_CPU0_SB_DQS_DP<3>")
	)
	(arc
		(start 381.353314 -290.611052)
		(mid 381.634746 -290.535297)
		(end 381.916178 -290.611052)
		(width 0.09525)
		(layer "In4.Cu")
		(net "M_J_CPU0_SB_DQS_DP<3>")
	)
	(arc
		(start 390.753346 -290.611052)
		(mid 391.034778 -290.535297)
		(end 391.31621 -290.611052)
		(width 0.09525)
		(layer "In4.Cu")
		(net "M_J_CPU0_SB_DQS_DP<3>")
	)
	(arc
		(start 381.034036 -290.637976)
		(mid 381.196687 -290.660236)
		(end 381.353314 -290.611052)
		(width 0.09525)
		(layer "In4.Cu")
		(net "M_J_CPU0_SB_DQS_DP<3>")
	)
	(arc
		(start 386.993384 -290.611052)
		(mid 387.274816 -290.535297)
		(end 387.556248 -290.611052)
		(width 0.09525)
		(layer "In4.Cu")
		(net "M_J_CPU0_SB_DQS_DP<3>")
	)
	(arc
		(start 387.933438 -290.611052)
		(mid 388.21487 -290.535297)
		(end 388.496302 -290.611052)
		(width 0.09525)
		(layer "In4.Cu")
		(net "M_J_CPU0_SB_DQS_DP<3>")
	)
	(arc
		(start 385.113276 -290.611052)
		(mid 385.394708 -290.535297)
		(end 385.67614 -290.611052)
		(width 0.09525)
		(layer "In4.Cu")
		(net "M_J_CPU0_SB_DQS_DP<3>")
	)
	(arc
		(start 381.916178 -290.611052)
		(mid 382.099953 -290.661824)
		(end 382.284986 -290.615878)
		(width 0.09525)
		(layer "In4.Cu")
		(net "M_J_CPU0_SB_DQS_DP<3>")
	)
	(arc
		(start 384.173476 -290.611052)
		(mid 384.454908 -290.535297)
		(end 384.73634 -290.611052)
		(width 0.09525)
		(layer "In4.Cu")
		(net "M_J_CPU0_SB_DQS_DP<3>")
	)
	(arc
		(start 389.436356 -290.611052)
		(mid 389.624824 -290.661729)
		(end 389.813292 -290.611052)
		(width 0.09525)
		(layer "In4.Cu")
		(net "M_J_CPU0_SB_DQS_DP<3>")
	)
	(arc
		(start 383.233422 -290.611052)
		(mid 383.514854 -290.535297)
		(end 383.796286 -290.611052)
		(width 0.09525)
		(layer "In4.Cu")
		(net "M_J_CPU0_SB_DQS_DP<3>")
	)
	(arc
		(start 384.73634 -290.611052)
		(mid 384.924808 -290.661729)
		(end 385.113276 -290.611052)
		(width 0.09525)
		(layer "In4.Cu")
		(net "M_J_CPU0_SB_DQS_DP<3>")
	)
	(arc
		(start 392.269218 -290.619434)
		(mid 392.451143 -290.661639)
		(end 392.630914 -290.611052)
		(width 0.09525)
		(layer "In4.Cu")
		(net "M_J_CPU0_SB_DQS_DP<3>")
	)
	(arc
		(start 383.804668 -290.615878)
		(mid 383.9897 -290.661792)
		(end 384.173476 -290.611052)
		(width 0.09525)
		(layer "In4.Cu")
		(net "M_J_CPU0_SB_DQS_DP<3>")
	)
	(arc
		(start 390.376156 -290.611052)
		(mid 390.559931 -290.661824)
		(end 390.744964 -290.615878)
		(width 0.09525)
		(layer "In4.Cu")
		(net "M_J_CPU0_SB_DQS_DP<3>")
	)
	(arc
		(start 386.05333 -290.611052)
		(mid 386.334762 -290.535297)
		(end 386.616194 -290.611052)
		(width 0.09525)
		(layer "In4.Cu")
		(net "M_J_CPU0_SB_DQS_DP<3>")
	)
	(arc
		(start 391.6934 -290.611052)
		(mid 391.959487 -290.535507)
		(end 392.22934 -290.59632)
		(width 0.09525)
		(layer "In4.Cu")
		(net "M_J_CPU0_SB_DQS_DP<3>")
	)
	(arc
		(start 382.293368 -290.611052)
		(mid 382.5748 -290.535297)
		(end 382.856232 -290.611052)
		(width 0.09525)
		(layer "In4.Cu")
		(net "M_J_CPU0_SB_DQS_DP<3>")
	)
	(arc
		(start 391.324592 -290.615878)
		(mid 391.509624 -290.661792)
		(end 391.6934 -290.611052)
		(width 0.09525)
		(layer "In4.Cu")
		(net "M_J_CPU0_SB_DQS_DP<3>")
	)
	(arc
		(start 393.195048 -290.611052)
		(mid 393.255868 -290.651713)
		(end 393.310872 -290.699952)
		(width 0.09525)
		(layer "In4.Cu")
		(net "M_J_CPU0_SB_DQS_DP<3>")
	)
	(arc
		(start 385.67614 -290.611052)
		(mid 385.859915 -290.661824)
		(end 386.044948 -290.615878)
		(width 0.09525)
		(layer "In4.Cu")
		(net "M_J_CPU0_SB_DQS_DP<3>")
	)
	(arc
		(start 382.864614 -290.615878)
		(mid 383.049646 -290.661792)
		(end 383.233422 -290.611052)
		(width 0.09525)
		(layer "In4.Cu")
		(net "M_J_CPU0_SB_DQS_DP<3>")
	)
	(segment
		(start 380.697994 -285.160212)
		(end 381.164846 -285.42615)
		(width 0.12954)
		(layer "F.Cu")
		(net "M_J_CPU0_SB_DQS_DP<2>")
	)
	(segment
		(start 425.207176 -302.859948)
		(end 426.05706 -303.709832)
		(width 0.16002)
		(layer "In4.Cu")
		(net "M_J_CPU0_SB_DQS_DP<2>")
	)
	(segment
		(start 428.129192 -303.709832)
		(end 428.441358 -304.021998)
		(width 0.16002)
		(layer "In4.Cu")
		(net "M_J_CPU0_SB_DQS_DP<2>")
	)
	(segment
		(start 387.556248 -285.75127)
		(end 387.56463 -285.756096)
		(width 0.09525)
		(layer "In4.Cu")
		(net "M_J_CPU0_SB_DQS_DP<2>")
	)
	(segment
		(start 421.968168 -303.538128)
		(end 422.89222 -303.538128)
		(width 0.16002)
		(layer "In4.Cu")
		(net "M_J_CPU0_SB_DQS_DP<2>")
	)
	(segment
		(start 430.8856 -302.859948)
		(end 432.656996 -302.859948)
		(width 0.16002)
		(layer "In4.Cu")
		(net "M_J_CPU0_SB_DQS_DP<2>")
	)
	(segment
		(start 401.745958 -292.235636)
		(end 401.745958 -297.683174)
		(width 0.16002)
		(layer "In4.Cu")
		(net "M_J_CPU0_SB_DQS_DP<2>")
	)
	(segment
		(start 395.824202 -286.622236)
		(end 396.132558 -286.622236)
		(width 0.16002)
		(layer "In4.Cu")
		(net "M_J_CPU0_SB_DQS_DP<2>")
	)
	(segment
		(start 394.219684 -285.80334)
		(end 394.794994 -286.37865)
		(width 0.09525)
		(layer "In4.Cu")
		(net "M_J_CPU0_SB_DQS_DP<2>")
	)
	(segment
		(start 382.284986 -285.756096)
		(end 382.293368 -285.75127)
		(width 0.09525)
		(layer "In4.Cu")
		(net "M_J_CPU0_SB_DQS_DP<2>")
	)
	(segment
		(start 421.461438 -304.044858)
		(end 421.968168 -303.538128)
		(width 0.16002)
		(layer "In4.Cu")
		(net "M_J_CPU0_SB_DQS_DP<2>")
	)
	(segment
		(start 383.796286 -285.75127)
		(end 383.804668 -285.756096)
		(width 0.09525)
		(layer "In4.Cu")
		(net "M_J_CPU0_SB_DQS_DP<2>")
	)
	(segment
		(start 420.692326 -304.044858)
		(end 421.461438 -304.044858)
		(width 0.16002)
		(layer "In4.Cu")
		(net "M_J_CPU0_SB_DQS_DP<2>")
	)
	(segment
		(start 382.856232 -285.75127)
		(end 382.864614 -285.756096)
		(width 0.09525)
		(layer "In4.Cu")
		(net "M_J_CPU0_SB_DQS_DP<2>")
	)
	(segment
		(start 429.711104 -303.478692)
		(end 430.266856 -303.478692)
		(width 0.16002)
		(layer "In4.Cu")
		(net "M_J_CPU0_SB_DQS_DP<2>")
	)
	(segment
		(start 414.71215 -303.270158)
		(end 418.010594 -303.270158)
		(width 0.16002)
		(layer "In4.Cu")
		(net "M_J_CPU0_SB_DQS_DP<2>")
	)
	(segment
		(start 429.167798 -304.021998)
		(end 429.711104 -303.478692)
		(width 0.16002)
		(layer "In4.Cu")
		(net "M_J_CPU0_SB_DQS_DP<2>")
	)
	(segment
		(start 432.656996 -302.859948)
		(end 433.438046 -303.640998)
		(width 0.16002)
		(layer "In4.Cu")
		(net "M_J_CPU0_SB_DQS_DP<2>")
	)
	(segment
		(start 418.450268 -303.709832)
		(end 420.3573 -303.709832)
		(width 0.16002)
		(layer "In4.Cu")
		(net "M_J_CPU0_SB_DQS_DP<2>")
	)
	(segment
		(start 413.92729 -304.055018)
		(end 414.71215 -303.270158)
		(width 0.16002)
		(layer "In4.Cu")
		(net "M_J_CPU0_SB_DQS_DP<2>")
	)
	(segment
		(start 388.496302 -285.75127)
		(end 388.504684 -285.756096)
		(width 0.09525)
		(layer "In4.Cu")
		(net "M_J_CPU0_SB_DQS_DP<2>")
	)
	(segment
		(start 430.266856 -303.478692)
		(end 430.8856 -302.859948)
		(width 0.16002)
		(layer "In4.Cu")
		(net "M_J_CPU0_SB_DQS_DP<2>")
	)
	(segment
		(start 392.630914 -285.75127)
		(end 392.654282 -285.737808)
		(width 0.09525)
		(layer "In4.Cu")
		(net "M_J_CPU0_SB_DQS_DP<2>")
	)
	(segment
		(start 381.010922 -285.69158)
		(end 381.034036 -285.778194)
		(width 0.09525)
		(layer "In4.Cu")
		(net "M_J_CPU0_SB_DQS_DP<2>")
	)
	(segment
		(start 393.384786 -285.80334)
		(end 394.219684 -285.80334)
		(width 0.09525)
		(layer "In4.Cu")
		(net "M_J_CPU0_SB_DQS_DP<2>")
	)
	(segment
		(start 426.05706 -303.709832)
		(end 428.129192 -303.709832)
		(width 0.16002)
		(layer "In4.Cu")
		(net "M_J_CPU0_SB_DQS_DP<2>")
	)
	(segment
		(start 392.25474 -285.75127)
		(end 392.269218 -285.759652)
		(width 0.09525)
		(layer "In4.Cu")
		(net "M_J_CPU0_SB_DQS_DP<2>")
	)
	(segment
		(start 420.3573 -303.709832)
		(end 420.692326 -304.044858)
		(width 0.16002)
		(layer "In4.Cu")
		(net "M_J_CPU0_SB_DQS_DP<2>")
	)
	(segment
		(start 436.795672 -304.044858)
		(end 436.9816 -303.85893)
		(width 0.16002)
		(layer "In4.Cu")
		(net "M_J_CPU0_SB_DQS_DP<2>")
	)
	(segment
		(start 386.044948 -285.756096)
		(end 386.05333 -285.75127)
		(width 0.09525)
		(layer "In4.Cu")
		(net "M_J_CPU0_SB_DQS_DP<2>")
	)
	(segment
		(start 438.826402 -303.85893)
		(end 439.100214 -303.585118)
		(width 0.16002)
		(layer "In4.Cu")
		(net "M_J_CPU0_SB_DQS_DP<2>")
	)
	(segment
		(start 433.438046 -303.640998)
		(end 435.475634 -303.640998)
		(width 0.16002)
		(layer "In4.Cu")
		(net "M_J_CPU0_SB_DQS_DP<2>")
	)
	(segment
		(start 394.794994 -286.37865)
		(end 395.33703 -286.37865)
		(width 0.09525)
		(layer "In4.Cu")
		(net "M_J_CPU0_SB_DQS_DP<2>")
	)
	(segment
		(start 437.723788 -303.74209)
		(end 438.203848 -303.74209)
		(width 0.16002)
		(layer "In4.Cu")
		(net "M_J_CPU0_SB_DQS_DP<2>")
	)
	(segment
		(start 386.985002 -285.756096)
		(end 386.993384 -285.75127)
		(width 0.09525)
		(layer "In4.Cu")
		(net "M_J_CPU0_SB_DQS_DP<2>")
	)
	(segment
		(start 423.5704 -302.859948)
		(end 425.207176 -302.859948)
		(width 0.16002)
		(layer "In4.Cu")
		(net "M_J_CPU0_SB_DQS_DP<2>")
	)
	(segment
		(start 422.89222 -303.538128)
		(end 423.5704 -302.859948)
		(width 0.16002)
		(layer "In4.Cu")
		(net "M_J_CPU0_SB_DQS_DP<2>")
	)
	(segment
		(start 413.341566 -304.055018)
		(end 413.92729 -304.055018)
		(width 0.16002)
		(layer "In4.Cu")
		(net "M_J_CPU0_SB_DQS_DP<2>")
	)
	(segment
		(start 437.606948 -303.85893)
		(end 437.723788 -303.74209)
		(width 0.16002)
		(layer "In4.Cu")
		(net "M_J_CPU0_SB_DQS_DP<2>")
	)
	(segment
		(start 413.005524 -303.718976)
		(end 413.341566 -304.055018)
		(width 0.16002)
		(layer "In4.Cu")
		(net "M_J_CPU0_SB_DQS_DP<2>")
	)
	(segment
		(start 381.164846 -285.42615)
		(end 381.010922 -285.69158)
		(width 0.09525)
		(layer "In4.Cu")
		(net "M_J_CPU0_SB_DQS_DP<2>")
	)
	(segment
		(start 435.879494 -304.044858)
		(end 436.795672 -304.044858)
		(width 0.16002)
		(layer "In4.Cu")
		(net "M_J_CPU0_SB_DQS_DP<2>")
	)
	(segment
		(start 418.010594 -303.270158)
		(end 418.450268 -303.709832)
		(width 0.16002)
		(layer "In4.Cu")
		(net "M_J_CPU0_SB_DQS_DP<2>")
	)
	(segment
		(start 395.741398 -286.681418)
		(end 395.80058 -286.622236)
		(width 0.09525)
		(layer "In4.Cu")
		(net "M_J_CPU0_SB_DQS_DP<2>")
	)
	(segment
		(start 395.80058 -286.622236)
		(end 395.824202 -286.622236)
		(width 0.09525)
		(layer "In4.Cu")
		(net "M_J_CPU0_SB_DQS_DP<2>")
	)
	(segment
		(start 395.639798 -286.681418)
		(end 395.741398 -286.681418)
		(width 0.09525)
		(layer "In4.Cu")
		(net "M_J_CPU0_SB_DQS_DP<2>")
	)
	(segment
		(start 407.78176 -303.718976)
		(end 413.005524 -303.718976)
		(width 0.16002)
		(layer "In4.Cu")
		(net "M_J_CPU0_SB_DQS_DP<2>")
	)
	(segment
		(start 392.22934 -285.736538)
		(end 392.25474 -285.75127)
		(width 0.09525)
		(layer "In4.Cu")
		(net "M_J_CPU0_SB_DQS_DP<2>")
	)
	(segment
		(start 436.9816 -303.85893)
		(end 437.606948 -303.85893)
		(width 0.16002)
		(layer "In4.Cu")
		(net "M_J_CPU0_SB_DQS_DP<2>")
	)
	(segment
		(start 438.203848 -303.74209)
		(end 438.320688 -303.85893)
		(width 0.16002)
		(layer "In4.Cu")
		(net "M_J_CPU0_SB_DQS_DP<2>")
	)
	(segment
		(start 396.132558 -286.622236)
		(end 401.745958 -292.235636)
		(width 0.16002)
		(layer "In4.Cu")
		(net "M_J_CPU0_SB_DQS_DP<2>")
	)
	(segment
		(start 401.745958 -297.683174)
		(end 407.78176 -303.718976)
		(width 0.16002)
		(layer "In4.Cu")
		(net "M_J_CPU0_SB_DQS_DP<2>")
	)
	(segment
		(start 391.31621 -285.75127)
		(end 391.324592 -285.756096)
		(width 0.09525)
		(layer "In4.Cu")
		(net "M_J_CPU0_SB_DQS_DP<2>")
	)
	(segment
		(start 435.475634 -303.640998)
		(end 435.879494 -304.044858)
		(width 0.16002)
		(layer "In4.Cu")
		(net "M_J_CPU0_SB_DQS_DP<2>")
	)
	(segment
		(start 395.33703 -286.37865)
		(end 395.639798 -286.681418)
		(width 0.09525)
		(layer "In4.Cu")
		(net "M_J_CPU0_SB_DQS_DP<2>")
	)
	(segment
		(start 390.744964 -285.756096)
		(end 390.753346 -285.75127)
		(width 0.09525)
		(layer "In4.Cu")
		(net "M_J_CPU0_SB_DQS_DP<2>")
	)
	(segment
		(start 428.441358 -304.021998)
		(end 429.167798 -304.021998)
		(width 0.16002)
		(layer "In4.Cu")
		(net "M_J_CPU0_SB_DQS_DP<2>")
	)
	(segment
		(start 438.320688 -303.85893)
		(end 438.826402 -303.85893)
		(width 0.16002)
		(layer "In4.Cu")
		(net "M_J_CPU0_SB_DQS_DP<2>")
	)
	(arc
		(start 390.376156 -285.75127)
		(mid 390.559931 -285.802042)
		(end 390.744964 -285.756096)
		(width 0.09525)
		(layer "In4.Cu")
		(net "M_J_CPU0_SB_DQS_DP<2>")
	)
	(arc
		(start 386.993384 -285.75127)
		(mid 387.274816 -285.675515)
		(end 387.556248 -285.75127)
		(width 0.09525)
		(layer "In4.Cu")
		(net "M_J_CPU0_SB_DQS_DP<2>")
	)
	(arc
		(start 385.67614 -285.75127)
		(mid 385.859915 -285.802042)
		(end 386.044948 -285.756096)
		(width 0.09525)
		(layer "In4.Cu")
		(net "M_J_CPU0_SB_DQS_DP<2>")
	)
	(arc
		(start 385.113276 -285.75127)
		(mid 385.394708 -285.675515)
		(end 385.67614 -285.75127)
		(width 0.09525)
		(layer "In4.Cu")
		(net "M_J_CPU0_SB_DQS_DP<2>")
	)
	(arc
		(start 389.436356 -285.75127)
		(mid 389.624824 -285.801947)
		(end 389.813292 -285.75127)
		(width 0.09525)
		(layer "In4.Cu")
		(net "M_J_CPU0_SB_DQS_DP<2>")
	)
	(arc
		(start 387.933438 -285.75127)
		(mid 388.21487 -285.675515)
		(end 388.496302 -285.75127)
		(width 0.09525)
		(layer "In4.Cu")
		(net "M_J_CPU0_SB_DQS_DP<2>")
	)
	(arc
		(start 384.73634 -285.75127)
		(mid 384.924808 -285.801947)
		(end 385.113276 -285.75127)
		(width 0.09525)
		(layer "In4.Cu")
		(net "M_J_CPU0_SB_DQS_DP<2>")
	)
	(arc
		(start 390.753346 -285.75127)
		(mid 391.034778 -285.675515)
		(end 391.31621 -285.75127)
		(width 0.09525)
		(layer "In4.Cu")
		(net "M_J_CPU0_SB_DQS_DP<2>")
	)
	(arc
		(start 381.353314 -285.75127)
		(mid 381.634746 -285.675515)
		(end 381.916178 -285.75127)
		(width 0.09525)
		(layer "In4.Cu")
		(net "M_J_CPU0_SB_DQS_DP<2>")
	)
	(arc
		(start 384.173476 -285.75127)
		(mid 384.454908 -285.675515)
		(end 384.73634 -285.75127)
		(width 0.09525)
		(layer "In4.Cu")
		(net "M_J_CPU0_SB_DQS_DP<2>")
	)
	(arc
		(start 386.05333 -285.75127)
		(mid 386.334762 -285.675515)
		(end 386.616194 -285.75127)
		(width 0.09525)
		(layer "In4.Cu")
		(net "M_J_CPU0_SB_DQS_DP<2>")
	)
	(arc
		(start 391.324592 -285.756096)
		(mid 391.509624 -285.80201)
		(end 391.6934 -285.75127)
		(width 0.09525)
		(layer "In4.Cu")
		(net "M_J_CPU0_SB_DQS_DP<2>")
	)
	(arc
		(start 387.56463 -285.756096)
		(mid 387.749662 -285.80201)
		(end 387.933438 -285.75127)
		(width 0.09525)
		(layer "In4.Cu")
		(net "M_J_CPU0_SB_DQS_DP<2>")
	)
	(arc
		(start 392.654282 -285.737808)
		(mid 392.926383 -285.67513)
		(end 393.195048 -285.75127)
		(width 0.09525)
		(layer "In4.Cu")
		(net "M_J_CPU0_SB_DQS_DP<2>")
	)
	(arc
		(start 381.034036 -285.778194)
		(mid 381.196687 -285.800454)
		(end 381.353314 -285.75127)
		(width 0.09525)
		(layer "In4.Cu")
		(net "M_J_CPU0_SB_DQS_DP<2>")
	)
	(arc
		(start 391.6934 -285.75127)
		(mid 391.959487 -285.675725)
		(end 392.22934 -285.736538)
		(width 0.09525)
		(layer "In4.Cu")
		(net "M_J_CPU0_SB_DQS_DP<2>")
	)
	(arc
		(start 393.195048 -285.75127)
		(mid 393.28646 -285.78989)
		(end 393.384786 -285.80334)
		(width 0.09525)
		(layer "In4.Cu")
		(net "M_J_CPU0_SB_DQS_DP<2>")
	)
	(arc
		(start 392.269218 -285.759652)
		(mid 392.451143 -285.801857)
		(end 392.630914 -285.75127)
		(width 0.09525)
		(layer "In4.Cu")
		(net "M_J_CPU0_SB_DQS_DP<2>")
	)
	(arc
		(start 381.916178 -285.75127)
		(mid 382.099953 -285.802042)
		(end 382.284986 -285.756096)
		(width 0.09525)
		(layer "In4.Cu")
		(net "M_J_CPU0_SB_DQS_DP<2>")
	)
	(arc
		(start 383.233422 -285.75127)
		(mid 383.514854 -285.675515)
		(end 383.796286 -285.75127)
		(width 0.09525)
		(layer "In4.Cu")
		(net "M_J_CPU0_SB_DQS_DP<2>")
	)
	(arc
		(start 386.616194 -285.75127)
		(mid 386.799969 -285.802042)
		(end 386.985002 -285.756096)
		(width 0.09525)
		(layer "In4.Cu")
		(net "M_J_CPU0_SB_DQS_DP<2>")
	)
	(arc
		(start 388.873492 -285.75127)
		(mid 389.154924 -285.675515)
		(end 389.436356 -285.75127)
		(width 0.09525)
		(layer "In4.Cu")
		(net "M_J_CPU0_SB_DQS_DP<2>")
	)
	(arc
		(start 389.813292 -285.75127)
		(mid 390.094724 -285.675515)
		(end 390.376156 -285.75127)
		(width 0.09525)
		(layer "In4.Cu")
		(net "M_J_CPU0_SB_DQS_DP<2>")
	)
	(arc
		(start 383.804668 -285.756096)
		(mid 383.9897 -285.80201)
		(end 384.173476 -285.75127)
		(width 0.09525)
		(layer "In4.Cu")
		(net "M_J_CPU0_SB_DQS_DP<2>")
	)
	(arc
		(start 382.864614 -285.756096)
		(mid 383.049646 -285.80201)
		(end 383.233422 -285.75127)
		(width 0.09525)
		(layer "In4.Cu")
		(net "M_J_CPU0_SB_DQS_DP<2>")
	)
	(arc
		(start 382.293368 -285.75127)
		(mid 382.5748 -285.675515)
		(end 382.856232 -285.75127)
		(width 0.09525)
		(layer "In4.Cu")
		(net "M_J_CPU0_SB_DQS_DP<2>")
	)
	(arc
		(start 388.504684 -285.756096)
		(mid 388.689716 -285.80201)
		(end 388.873492 -285.75127)
		(width 0.09525)
		(layer "In4.Cu")
		(net "M_J_CPU0_SB_DQS_DP<2>")
	)
	(segment
		(start 380.697994 -280.300176)
		(end 381.164846 -280.566114)
		(width 0.12954)
		(layer "F.Cu")
		(net "M_J_CPU0_SB_DQS_DP<1>")
	)
	(segment
		(start 381.010922 -280.831544)
		(end 381.164846 -280.566114)
		(width 0.09525)
		(layer "In4.Cu")
		(net "M_J_CPU0_SB_DQS_DP<1>")
	)
	(segment
		(start 436.782972 -294.694864)
		(end 435.879494 -294.694864)
		(width 0.16002)
		(layer "In4.Cu")
		(net "M_J_CPU0_SB_DQS_DP<1>")
	)
	(segment
		(start 430.8856 -293.509954)
		(end 430.266856 -294.128698)
		(width 0.16002)
		(layer "In4.Cu")
		(net "M_J_CPU0_SB_DQS_DP<1>")
	)
	(segment
		(start 407.283158 -289.939222)
		(end 398.201134 -280.857198)
		(width 0.16002)
		(layer "In4.Cu")
		(net "M_J_CPU0_SB_DQS_DP<1>")
	)
	(segment
		(start 435.879494 -294.694864)
		(end 435.475634 -294.291004)
		(width 0.16002)
		(layer "In4.Cu")
		(net "M_J_CPU0_SB_DQS_DP<1>")
	)
	(segment
		(start 382.864614 -280.89606)
		(end 382.856232 -280.891234)
		(width 0.09525)
		(layer "In4.Cu")
		(net "M_J_CPU0_SB_DQS_DP<1>")
	)
	(segment
		(start 422.89222 -294.188134)
		(end 421.968168 -294.188134)
		(width 0.16002)
		(layer "In4.Cu")
		(net "M_J_CPU0_SB_DQS_DP<1>")
	)
	(segment
		(start 387.56463 -280.89606)
		(end 387.556248 -280.891234)
		(width 0.09525)
		(layer "In4.Cu")
		(net "M_J_CPU0_SB_DQS_DP<1>")
	)
	(segment
		(start 391.324592 -280.89606)
		(end 391.31621 -280.891234)
		(width 0.09525)
		(layer "In4.Cu")
		(net "M_J_CPU0_SB_DQS_DP<1>")
	)
	(segment
		(start 438.1627 -294.508936)
		(end 438.04586 -294.392096)
		(width 0.16002)
		(layer "In4.Cu")
		(net "M_J_CPU0_SB_DQS_DP<1>")
	)
	(segment
		(start 438.826402 -294.508936)
		(end 438.1627 -294.508936)
		(width 0.16002)
		(layer "In4.Cu")
		(net "M_J_CPU0_SB_DQS_DP<1>")
	)
	(segment
		(start 412.446724 -295.076118)
		(end 410.835348 -295.076118)
		(width 0.16002)
		(layer "In4.Cu")
		(net "M_J_CPU0_SB_DQS_DP<1>")
	)
	(segment
		(start 395.77645 -280.91638)
		(end 395.549882 -280.91638)
		(width 0.09525)
		(layer "In4.Cu")
		(net "M_J_CPU0_SB_DQS_DP<1>")
	)
	(segment
		(start 418.010594 -293.920164)
		(end 414.71215 -293.920164)
		(width 0.16002)
		(layer "In4.Cu")
		(net "M_J_CPU0_SB_DQS_DP<1>")
	)
	(segment
		(start 433.438046 -294.291004)
		(end 432.656996 -293.509954)
		(width 0.16002)
		(layer "In4.Cu")
		(net "M_J_CPU0_SB_DQS_DP<1>")
	)
	(segment
		(start 398.201134 -280.857198)
		(end 395.859254 -280.857198)
		(width 0.16002)
		(layer "In4.Cu")
		(net "M_J_CPU0_SB_DQS_DP<1>")
	)
	(segment
		(start 420.3573 -294.359838)
		(end 418.450268 -294.359838)
		(width 0.16002)
		(layer "In4.Cu")
		(net "M_J_CPU0_SB_DQS_DP<1>")
	)
	(segment
		(start 390.753346 -280.891234)
		(end 390.744964 -280.89606)
		(width 0.09525)
		(layer "In4.Cu")
		(net "M_J_CPU0_SB_DQS_DP<1>")
	)
	(segment
		(start 386.05333 -280.891234)
		(end 386.044948 -280.89606)
		(width 0.09525)
		(layer "In4.Cu")
		(net "M_J_CPU0_SB_DQS_DP<1>")
	)
	(segment
		(start 429.167798 -294.672004)
		(end 428.441358 -294.672004)
		(width 0.16002)
		(layer "In4.Cu")
		(net "M_J_CPU0_SB_DQS_DP<1>")
	)
	(segment
		(start 435.475634 -294.291004)
		(end 433.438046 -294.291004)
		(width 0.16002)
		(layer "In4.Cu")
		(net "M_J_CPU0_SB_DQS_DP<1>")
	)
	(segment
		(start 420.692326 -294.694864)
		(end 420.3573 -294.359838)
		(width 0.16002)
		(layer "In4.Cu")
		(net "M_J_CPU0_SB_DQS_DP<1>")
	)
	(segment
		(start 437.44896 -294.508936)
		(end 436.9689 -294.508936)
		(width 0.16002)
		(layer "In4.Cu")
		(net "M_J_CPU0_SB_DQS_DP<1>")
	)
	(segment
		(start 395.859254 -280.857198)
		(end 395.835632 -280.857198)
		(width 0.09525)
		(layer "In4.Cu")
		(net "M_J_CPU0_SB_DQS_DP<1>")
	)
	(segment
		(start 426.05706 -294.359838)
		(end 425.207176 -293.509954)
		(width 0.16002)
		(layer "In4.Cu")
		(net "M_J_CPU0_SB_DQS_DP<1>")
	)
	(segment
		(start 428.441358 -294.672004)
		(end 428.129192 -294.359838)
		(width 0.16002)
		(layer "In4.Cu")
		(net "M_J_CPU0_SB_DQS_DP<1>")
	)
	(segment
		(start 392.269218 -280.899616)
		(end 392.25474 -280.891234)
		(width 0.09525)
		(layer "In4.Cu")
		(net "M_J_CPU0_SB_DQS_DP<1>")
	)
	(segment
		(start 429.711104 -294.128698)
		(end 429.167798 -294.672004)
		(width 0.16002)
		(layer "In4.Cu")
		(net "M_J_CPU0_SB_DQS_DP<1>")
	)
	(segment
		(start 395.27734 -280.537666)
		(end 394.153644 -280.537666)
		(width 0.09525)
		(layer "In4.Cu")
		(net "M_J_CPU0_SB_DQS_DP<1>")
	)
	(segment
		(start 418.450268 -294.359838)
		(end 418.010594 -293.920164)
		(width 0.16002)
		(layer "In4.Cu")
		(net "M_J_CPU0_SB_DQS_DP<1>")
	)
	(segment
		(start 410.835348 -295.076118)
		(end 407.283158 -291.523928)
		(width 0.16002)
		(layer "In4.Cu")
		(net "M_J_CPU0_SB_DQS_DP<1>")
	)
	(segment
		(start 393.889484 -280.64714)
		(end 393.702032 -280.834592)
		(width 0.09525)
		(layer "In4.Cu")
		(net "M_J_CPU0_SB_DQS_DP<1>")
	)
	(segment
		(start 425.207176 -293.509954)
		(end 423.5704 -293.509954)
		(width 0.16002)
		(layer "In4.Cu")
		(net "M_J_CPU0_SB_DQS_DP<1>")
	)
	(segment
		(start 439.100214 -294.235124)
		(end 438.826402 -294.508936)
		(width 0.16002)
		(layer "In4.Cu")
		(net "M_J_CPU0_SB_DQS_DP<1>")
	)
	(segment
		(start 383.804668 -280.89606)
		(end 383.796286 -280.891234)
		(width 0.09525)
		(layer "In4.Cu")
		(net "M_J_CPU0_SB_DQS_DP<1>")
	)
	(segment
		(start 423.5704 -293.509954)
		(end 422.89222 -294.188134)
		(width 0.16002)
		(layer "In4.Cu")
		(net "M_J_CPU0_SB_DQS_DP<1>")
	)
	(segment
		(start 395.549882 -280.91638)
		(end 395.27734 -280.537666)
		(width 0.09525)
		(layer "In4.Cu")
		(net "M_J_CPU0_SB_DQS_DP<1>")
	)
	(segment
		(start 432.656996 -293.509954)
		(end 430.8856 -293.509954)
		(width 0.16002)
		(layer "In4.Cu")
		(net "M_J_CPU0_SB_DQS_DP<1>")
	)
	(segment
		(start 413.92729 -294.705024)
		(end 412.817818 -294.705024)
		(width 0.16002)
		(layer "In4.Cu")
		(net "M_J_CPU0_SB_DQS_DP<1>")
	)
	(segment
		(start 395.835632 -280.857198)
		(end 395.77645 -280.91638)
		(width 0.09525)
		(layer "In4.Cu")
		(net "M_J_CPU0_SB_DQS_DP<1>")
	)
	(segment
		(start 436.9689 -294.508936)
		(end 436.782972 -294.694864)
		(width 0.16002)
		(layer "In4.Cu")
		(net "M_J_CPU0_SB_DQS_DP<1>")
	)
	(segment
		(start 392.25474 -280.891234)
		(end 392.22934 -280.876502)
		(width 0.09525)
		(layer "In4.Cu")
		(net "M_J_CPU0_SB_DQS_DP<1>")
	)
	(segment
		(start 414.71215 -293.920164)
		(end 413.92729 -294.705024)
		(width 0.16002)
		(layer "In4.Cu")
		(net "M_J_CPU0_SB_DQS_DP<1>")
	)
	(segment
		(start 392.654282 -280.877772)
		(end 392.630914 -280.891234)
		(width 0.09525)
		(layer "In4.Cu")
		(net "M_J_CPU0_SB_DQS_DP<1>")
	)
	(segment
		(start 388.504684 -280.89606)
		(end 388.496302 -280.891234)
		(width 0.09525)
		(layer "In4.Cu")
		(net "M_J_CPU0_SB_DQS_DP<1>")
	)
	(segment
		(start 421.968168 -294.188134)
		(end 421.461438 -294.694864)
		(width 0.16002)
		(layer "In4.Cu")
		(net "M_J_CPU0_SB_DQS_DP<1>")
	)
	(segment
		(start 386.993384 -280.891234)
		(end 386.985002 -280.89606)
		(width 0.09525)
		(layer "In4.Cu")
		(net "M_J_CPU0_SB_DQS_DP<1>")
	)
	(segment
		(start 421.461438 -294.694864)
		(end 420.692326 -294.694864)
		(width 0.16002)
		(layer "In4.Cu")
		(net "M_J_CPU0_SB_DQS_DP<1>")
	)
	(segment
		(start 430.266856 -294.128698)
		(end 429.711104 -294.128698)
		(width 0.16002)
		(layer "In4.Cu")
		(net "M_J_CPU0_SB_DQS_DP<1>")
	)
	(segment
		(start 438.04586 -294.392096)
		(end 437.5658 -294.392096)
		(width 0.16002)
		(layer "In4.Cu")
		(net "M_J_CPU0_SB_DQS_DP<1>")
	)
	(segment
		(start 407.283158 -291.523928)
		(end 407.283158 -289.939222)
		(width 0.16002)
		(layer "In4.Cu")
		(net "M_J_CPU0_SB_DQS_DP<1>")
	)
	(segment
		(start 381.034036 -280.918158)
		(end 381.010922 -280.831544)
		(width 0.09525)
		(layer "In4.Cu")
		(net "M_J_CPU0_SB_DQS_DP<1>")
	)
	(segment
		(start 412.817818 -294.705024)
		(end 412.446724 -295.076118)
		(width 0.16002)
		(layer "In4.Cu")
		(net "M_J_CPU0_SB_DQS_DP<1>")
	)
	(segment
		(start 437.5658 -294.392096)
		(end 437.44896 -294.508936)
		(width 0.16002)
		(layer "In4.Cu")
		(net "M_J_CPU0_SB_DQS_DP<1>")
	)
	(segment
		(start 428.129192 -294.359838)
		(end 426.05706 -294.359838)
		(width 0.16002)
		(layer "In4.Cu")
		(net "M_J_CPU0_SB_DQS_DP<1>")
	)
	(segment
		(start 382.293368 -280.891234)
		(end 382.284986 -280.89606)
		(width 0.09525)
		(layer "In4.Cu")
		(net "M_J_CPU0_SB_DQS_DP<1>")
	)
	(arc
		(start 381.353314 -280.891234)
		(mid 381.196687 -280.94042)
		(end 381.034036 -280.918158)
		(width 0.09525)
		(layer "In4.Cu")
		(net "M_J_CPU0_SB_DQS_DP<1>")
	)
	(arc
		(start 393.384786 -280.943304)
		(mid 393.286448 -280.929898)
		(end 393.195048 -280.891234)
		(width 0.09525)
		(layer "In4.Cu")
		(net "M_J_CPU0_SB_DQS_DP<1>")
	)
	(arc
		(start 387.556248 -280.891234)
		(mid 387.274816 -280.815479)
		(end 386.993384 -280.891234)
		(width 0.09525)
		(layer "In4.Cu")
		(net "M_J_CPU0_SB_DQS_DP<1>")
	)
	(arc
		(start 394.153644 -280.537666)
		(mid 394.010675 -280.566122)
		(end 393.889484 -280.64714)
		(width 0.09525)
		(layer "In4.Cu")
		(net "M_J_CPU0_SB_DQS_DP<1>")
	)
	(arc
		(start 385.113276 -280.891234)
		(mid 384.924808 -280.941911)
		(end 384.73634 -280.891234)
		(width 0.09525)
		(layer "In4.Cu")
		(net "M_J_CPU0_SB_DQS_DP<1>")
	)
	(arc
		(start 385.67614 -280.891234)
		(mid 385.394708 -280.815479)
		(end 385.113276 -280.891234)
		(width 0.09525)
		(layer "In4.Cu")
		(net "M_J_CPU0_SB_DQS_DP<1>")
	)
	(arc
		(start 390.744964 -280.89606)
		(mid 390.559932 -280.941974)
		(end 390.376156 -280.891234)
		(width 0.09525)
		(layer "In4.Cu")
		(net "M_J_CPU0_SB_DQS_DP<1>")
	)
	(arc
		(start 383.796286 -280.891234)
		(mid 383.514854 -280.815479)
		(end 383.233422 -280.891234)
		(width 0.09525)
		(layer "In4.Cu")
		(net "M_J_CPU0_SB_DQS_DP<1>")
	)
	(arc
		(start 388.873492 -280.891234)
		(mid 388.689717 -280.942006)
		(end 388.504684 -280.89606)
		(width 0.09525)
		(layer "In4.Cu")
		(net "M_J_CPU0_SB_DQS_DP<1>")
	)
	(arc
		(start 387.933438 -280.891234)
		(mid 387.749663 -280.942006)
		(end 387.56463 -280.89606)
		(width 0.09525)
		(layer "In4.Cu")
		(net "M_J_CPU0_SB_DQS_DP<1>")
	)
	(arc
		(start 381.916178 -280.891234)
		(mid 381.634746 -280.815479)
		(end 381.353314 -280.891234)
		(width 0.09525)
		(layer "In4.Cu")
		(net "M_J_CPU0_SB_DQS_DP<1>")
	)
	(arc
		(start 392.22934 -280.876502)
		(mid 391.959486 -280.815623)
		(end 391.6934 -280.891234)
		(width 0.09525)
		(layer "In4.Cu")
		(net "M_J_CPU0_SB_DQS_DP<1>")
	)
	(arc
		(start 390.376156 -280.891234)
		(mid 390.094724 -280.815479)
		(end 389.813292 -280.891234)
		(width 0.09525)
		(layer "In4.Cu")
		(net "M_J_CPU0_SB_DQS_DP<1>")
	)
	(arc
		(start 386.985002 -280.89606)
		(mid 386.79997 -280.941974)
		(end 386.616194 -280.891234)
		(width 0.09525)
		(layer "In4.Cu")
		(net "M_J_CPU0_SB_DQS_DP<1>")
	)
	(arc
		(start 392.630914 -280.891234)
		(mid 392.451142 -280.94181)
		(end 392.269218 -280.899616)
		(width 0.09525)
		(layer "In4.Cu")
		(net "M_J_CPU0_SB_DQS_DP<1>")
	)
	(arc
		(start 384.173476 -280.891234)
		(mid 383.989701 -280.942006)
		(end 383.804668 -280.89606)
		(width 0.09525)
		(layer "In4.Cu")
		(net "M_J_CPU0_SB_DQS_DP<1>")
	)
	(arc
		(start 383.233422 -280.891234)
		(mid 383.049647 -280.942006)
		(end 382.864614 -280.89606)
		(width 0.09525)
		(layer "In4.Cu")
		(net "M_J_CPU0_SB_DQS_DP<1>")
	)
	(arc
		(start 384.73634 -280.891234)
		(mid 384.454908 -280.815479)
		(end 384.173476 -280.891234)
		(width 0.09525)
		(layer "In4.Cu")
		(net "M_J_CPU0_SB_DQS_DP<1>")
	)
	(arc
		(start 389.813292 -280.891234)
		(mid 389.624824 -280.941911)
		(end 389.436356 -280.891234)
		(width 0.09525)
		(layer "In4.Cu")
		(net "M_J_CPU0_SB_DQS_DP<1>")
	)
	(arc
		(start 382.856232 -280.891234)
		(mid 382.5748 -280.815479)
		(end 382.293368 -280.891234)
		(width 0.09525)
		(layer "In4.Cu")
		(net "M_J_CPU0_SB_DQS_DP<1>")
	)
	(arc
		(start 391.6934 -280.891234)
		(mid 391.509625 -280.942006)
		(end 391.324592 -280.89606)
		(width 0.09525)
		(layer "In4.Cu")
		(net "M_J_CPU0_SB_DQS_DP<1>")
	)
	(arc
		(start 393.702032 -280.834592)
		(mid 393.552467 -280.915389)
		(end 393.384786 -280.943304)
		(width 0.09525)
		(layer "In4.Cu")
		(net "M_J_CPU0_SB_DQS_DP<1>")
	)
	(arc
		(start 386.616194 -280.891234)
		(mid 386.334762 -280.815479)
		(end 386.05333 -280.891234)
		(width 0.09525)
		(layer "In4.Cu")
		(net "M_J_CPU0_SB_DQS_DP<1>")
	)
	(arc
		(start 388.496302 -280.891234)
		(mid 388.21487 -280.815479)
		(end 387.933438 -280.891234)
		(width 0.09525)
		(layer "In4.Cu")
		(net "M_J_CPU0_SB_DQS_DP<1>")
	)
	(arc
		(start 389.436356 -280.891234)
		(mid 389.154924 -280.815479)
		(end 388.873492 -280.891234)
		(width 0.09525)
		(layer "In4.Cu")
		(net "M_J_CPU0_SB_DQS_DP<1>")
	)
	(arc
		(start 393.195048 -280.891234)
		(mid 392.926385 -280.815016)
		(end 392.654282 -280.877772)
		(width 0.09525)
		(layer "In4.Cu")
		(net "M_J_CPU0_SB_DQS_DP<1>")
	)
	(arc
		(start 391.31621 -280.891234)
		(mid 391.034778 -280.815479)
		(end 390.753346 -280.891234)
		(width 0.09525)
		(layer "In4.Cu")
		(net "M_J_CPU0_SB_DQS_DP<1>")
	)
	(arc
		(start 382.284986 -280.89606)
		(mid 382.099954 -280.941974)
		(end 381.916178 -280.891234)
		(width 0.09525)
		(layer "In4.Cu")
		(net "M_J_CPU0_SB_DQS_DP<1>")
	)
	(arc
		(start 386.044948 -280.89606)
		(mid 385.859916 -280.941974)
		(end 385.67614 -280.891234)
		(width 0.09525)
		(layer "In4.Cu")
		(net "M_J_CPU0_SB_DQS_DP<1>")
	)
	(segment
		(start 380.697994 -275.44014)
		(end 381.164846 -275.706078)
		(width 0.12954)
		(layer "F.Cu")
		(net "M_J_CPU0_SB_DQS_DP<0>")
	)
	(segment
		(start 430.266856 -284.778704)
		(end 430.8856 -284.15996)
		(width 0.16002)
		(layer "In4.Cu")
		(net "M_J_CPU0_SB_DQS_DP<0>")
	)
	(segment
		(start 434.281834 -284.94101)
		(end 434.398674 -284.82417)
		(width 0.16002)
		(layer "In4.Cu")
		(net "M_J_CPU0_SB_DQS_DP<0>")
	)
	(segment
		(start 434.878734 -284.82417)
		(end 434.995574 -284.94101)
		(width 0.16002)
		(layer "In4.Cu")
		(net "M_J_CPU0_SB_DQS_DP<0>")
	)
	(segment
		(start 425.207176 -284.15996)
		(end 426.05706 -285.009844)
		(width 0.16002)
		(layer "In4.Cu")
		(net "M_J_CPU0_SB_DQS_DP<0>")
	)
	(segment
		(start 417.753038 -284.57017)
		(end 418.814758 -285.009844)
		(width 0.16002)
		(layer "In4.Cu")
		(net "M_J_CPU0_SB_DQS_DP<0>")
	)
	(segment
		(start 404.247858 -277.589234)
		(end 411.277054 -284.61843)
		(width 0.16002)
		(layer "In4.Cu")
		(net "M_J_CPU0_SB_DQS_DP<0>")
	)
	(segment
		(start 420.692326 -285.34487)
		(end 421.461438 -285.34487)
		(width 0.16002)
		(layer "In4.Cu")
		(net "M_J_CPU0_SB_DQS_DP<0>")
	)
	(segment
		(start 423.5704 -284.15996)
		(end 425.207176 -284.15996)
		(width 0.16002)
		(layer "In4.Cu")
		(net "M_J_CPU0_SB_DQS_DP<0>")
	)
	(segment
		(start 386.044948 -276.036024)
		(end 386.05333 -276.031198)
		(width 0.09525)
		(layer "In4.Cu")
		(net "M_J_CPU0_SB_DQS_DP<0>")
	)
	(segment
		(start 429.711104 -284.778704)
		(end 430.266856 -284.778704)
		(width 0.16002)
		(layer "In4.Cu")
		(net "M_J_CPU0_SB_DQS_DP<0>")
	)
	(segment
		(start 386.985002 -276.036024)
		(end 386.993384 -276.031198)
		(width 0.09525)
		(layer "In4.Cu")
		(net "M_J_CPU0_SB_DQS_DP<0>")
	)
	(segment
		(start 421.968168 -284.83814)
		(end 422.89222 -284.83814)
		(width 0.16002)
		(layer "In4.Cu")
		(net "M_J_CPU0_SB_DQS_DP<0>")
	)
	(segment
		(start 395.835632 -274.897596)
		(end 395.859254 -274.897596)
		(width 0.09525)
		(layer "In4.Cu")
		(net "M_J_CPU0_SB_DQS_DP<0>")
	)
	(segment
		(start 435.475634 -284.94101)
		(end 435.879494 -285.34487)
		(width 0.16002)
		(layer "In4.Cu")
		(net "M_J_CPU0_SB_DQS_DP<0>")
	)
	(segment
		(start 395.859254 -274.897596)
		(end 400.5707 -274.897596)
		(width 0.16002)
		(layer "In4.Cu")
		(net "M_J_CPU0_SB_DQS_DP<0>")
	)
	(segment
		(start 382.856232 -276.031198)
		(end 382.864614 -276.036024)
		(width 0.09525)
		(layer "In4.Cu")
		(net "M_J_CPU0_SB_DQS_DP<0>")
	)
	(segment
		(start 437.627268 -285.34487)
		(end 437.813196 -285.158942)
		(width 0.16002)
		(layer "In4.Cu")
		(net "M_J_CPU0_SB_DQS_DP<0>")
	)
	(segment
		(start 428.129192 -285.009844)
		(end 428.441358 -285.32201)
		(width 0.16002)
		(layer "In4.Cu")
		(net "M_J_CPU0_SB_DQS_DP<0>")
	)
	(segment
		(start 381.010922 -275.971508)
		(end 381.034036 -276.058122)
		(width 0.09525)
		(layer "In4.Cu")
		(net "M_J_CPU0_SB_DQS_DP<0>")
	)
	(segment
		(start 434.995574 -284.94101)
		(end 435.475634 -284.94101)
		(width 0.16002)
		(layer "In4.Cu")
		(net "M_J_CPU0_SB_DQS_DP<0>")
	)
	(segment
		(start 381.164846 -275.706078)
		(end 381.010922 -275.971508)
		(width 0.09525)
		(layer "In4.Cu")
		(net "M_J_CPU0_SB_DQS_DP<0>")
	)
	(segment
		(start 432.656996 -284.15996)
		(end 433.438046 -284.94101)
		(width 0.16002)
		(layer "In4.Cu")
		(net "M_J_CPU0_SB_DQS_DP<0>")
	)
	(segment
		(start 437.813196 -285.158942)
		(end 438.826402 -285.158942)
		(width 0.16002)
		(layer "In4.Cu")
		(net "M_J_CPU0_SB_DQS_DP<0>")
	)
	(segment
		(start 393.546838 -276.045676)
		(end 393.572238 -276.031198)
		(width 0.09525)
		(layer "In4.Cu")
		(net "M_J_CPU0_SB_DQS_DP<0>")
	)
	(segment
		(start 387.556248 -276.031198)
		(end 387.56463 -276.036024)
		(width 0.09525)
		(layer "In4.Cu")
		(net "M_J_CPU0_SB_DQS_DP<0>")
	)
	(segment
		(start 433.438046 -284.94101)
		(end 434.281834 -284.94101)
		(width 0.16002)
		(layer "In4.Cu")
		(net "M_J_CPU0_SB_DQS_DP<0>")
	)
	(segment
		(start 435.879494 -285.34487)
		(end 437.627268 -285.34487)
		(width 0.16002)
		(layer "In4.Cu")
		(net "M_J_CPU0_SB_DQS_DP<0>")
	)
	(segment
		(start 421.461438 -285.34487)
		(end 421.968168 -284.83814)
		(width 0.16002)
		(layer "In4.Cu")
		(net "M_J_CPU0_SB_DQS_DP<0>")
	)
	(segment
		(start 403.262338 -277.589234)
		(end 404.247858 -277.589234)
		(width 0.16002)
		(layer "In4.Cu")
		(net "M_J_CPU0_SB_DQS_DP<0>")
	)
	(segment
		(start 392.22934 -276.016466)
		(end 392.25474 -276.031198)
		(width 0.09525)
		(layer "In4.Cu")
		(net "M_J_CPU0_SB_DQS_DP<0>")
	)
	(segment
		(start 429.167798 -285.32201)
		(end 429.711104 -284.778704)
		(width 0.16002)
		(layer "In4.Cu")
		(net "M_J_CPU0_SB_DQS_DP<0>")
	)
	(segment
		(start 392.25474 -276.031198)
		(end 392.269218 -276.03958)
		(width 0.09525)
		(layer "In4.Cu")
		(net "M_J_CPU0_SB_DQS_DP<0>")
	)
	(segment
		(start 412.887414 -284.61843)
		(end 413.624014 -285.35503)
		(width 0.16002)
		(layer "In4.Cu")
		(net "M_J_CPU0_SB_DQS_DP<0>")
	)
	(segment
		(start 426.05706 -285.009844)
		(end 428.129192 -285.009844)
		(width 0.16002)
		(layer "In4.Cu")
		(net "M_J_CPU0_SB_DQS_DP<0>")
	)
	(segment
		(start 438.826402 -285.158942)
		(end 439.100214 -284.88513)
		(width 0.16002)
		(layer "In4.Cu")
		(net "M_J_CPU0_SB_DQS_DP<0>")
	)
	(segment
		(start 418.814758 -285.009844)
		(end 420.3573 -285.009844)
		(width 0.16002)
		(layer "In4.Cu")
		(net "M_J_CPU0_SB_DQS_DP<0>")
	)
	(segment
		(start 434.398674 -284.82417)
		(end 434.878734 -284.82417)
		(width 0.16002)
		(layer "In4.Cu")
		(net "M_J_CPU0_SB_DQS_DP<0>")
	)
	(segment
		(start 395.223746 -274.997164)
		(end 395.264132 -274.956778)
		(width 0.09525)
		(layer "In4.Cu")
		(net "M_J_CPU0_SB_DQS_DP<0>")
	)
	(segment
		(start 388.496302 -276.031198)
		(end 388.504684 -276.036024)
		(width 0.09525)
		(layer "In4.Cu")
		(net "M_J_CPU0_SB_DQS_DP<0>")
	)
	(segment
		(start 400.5707 -274.897596)
		(end 403.262338 -277.589234)
		(width 0.16002)
		(layer "In4.Cu")
		(net "M_J_CPU0_SB_DQS_DP<0>")
	)
	(segment
		(start 428.441358 -285.32201)
		(end 429.167798 -285.32201)
		(width 0.16002)
		(layer "In4.Cu")
		(net "M_J_CPU0_SB_DQS_DP<0>")
	)
	(segment
		(start 394.625068 -274.997164)
		(end 395.223746 -274.997164)
		(width 0.09525)
		(layer "In4.Cu")
		(net "M_J_CPU0_SB_DQS_DP<0>")
	)
	(segment
		(start 395.264132 -274.956778)
		(end 395.77645 -274.956778)
		(width 0.09525)
		(layer "In4.Cu")
		(net "M_J_CPU0_SB_DQS_DP<0>")
	)
	(segment
		(start 390.744964 -276.036024)
		(end 390.753346 -276.031198)
		(width 0.09525)
		(layer "In4.Cu")
		(net "M_J_CPU0_SB_DQS_DP<0>")
	)
	(segment
		(start 391.31621 -276.031198)
		(end 391.324592 -276.036024)
		(width 0.09525)
		(layer "In4.Cu")
		(net "M_J_CPU0_SB_DQS_DP<0>")
	)
	(segment
		(start 430.8856 -284.15996)
		(end 432.656996 -284.15996)
		(width 0.16002)
		(layer "In4.Cu")
		(net "M_J_CPU0_SB_DQS_DP<0>")
	)
	(segment
		(start 413.624014 -285.35503)
		(end 413.92729 -285.35503)
		(width 0.16002)
		(layer "In4.Cu")
		(net "M_J_CPU0_SB_DQS_DP<0>")
	)
	(segment
		(start 392.630914 -276.031198)
		(end 392.654282 -276.017736)
		(width 0.09525)
		(layer "In4.Cu")
		(net "M_J_CPU0_SB_DQS_DP<0>")
	)
	(segment
		(start 414.71215 -284.57017)
		(end 417.753038 -284.57017)
		(width 0.16002)
		(layer "In4.Cu")
		(net "M_J_CPU0_SB_DQS_DP<0>")
	)
	(segment
		(start 413.92729 -285.35503)
		(end 414.71215 -284.57017)
		(width 0.16002)
		(layer "In4.Cu")
		(net "M_J_CPU0_SB_DQS_DP<0>")
	)
	(segment
		(start 422.89222 -284.83814)
		(end 423.5704 -284.15996)
		(width 0.16002)
		(layer "In4.Cu")
		(net "M_J_CPU0_SB_DQS_DP<0>")
	)
	(segment
		(start 393.65047 -275.971762)
		(end 394.625068 -274.997164)
		(width 0.09525)
		(layer "In4.Cu")
		(net "M_J_CPU0_SB_DQS_DP<0>")
	)
	(segment
		(start 382.284986 -276.036024)
		(end 382.293368 -276.031198)
		(width 0.09525)
		(layer "In4.Cu")
		(net "M_J_CPU0_SB_DQS_DP<0>")
	)
	(segment
		(start 411.277054 -284.61843)
		(end 412.887414 -284.61843)
		(width 0.16002)
		(layer "In4.Cu")
		(net "M_J_CPU0_SB_DQS_DP<0>")
	)
	(segment
		(start 395.77645 -274.956778)
		(end 395.835632 -274.897596)
		(width 0.09525)
		(layer "In4.Cu")
		(net "M_J_CPU0_SB_DQS_DP<0>")
	)
	(segment
		(start 383.796286 -276.031198)
		(end 383.804668 -276.036024)
		(width 0.09525)
		(layer "In4.Cu")
		(net "M_J_CPU0_SB_DQS_DP<0>")
	)
	(segment
		(start 420.3573 -285.009844)
		(end 420.692326 -285.34487)
		(width 0.16002)
		(layer "In4.Cu")
		(net "M_J_CPU0_SB_DQS_DP<0>")
	)
	(arc
		(start 382.864614 -276.036024)
		(mid 383.049646 -276.081938)
		(end 383.233422 -276.031198)
		(width 0.09525)
		(layer "In4.Cu")
		(net "M_J_CPU0_SB_DQS_DP<0>")
	)
	(arc
		(start 381.353314 -276.031198)
		(mid 381.634746 -275.955443)
		(end 381.916178 -276.031198)
		(width 0.09525)
		(layer "In4.Cu")
		(net "M_J_CPU0_SB_DQS_DP<0>")
	)
	(arc
		(start 387.56463 -276.036024)
		(mid 387.749662 -276.081938)
		(end 387.933438 -276.031198)
		(width 0.09525)
		(layer "In4.Cu")
		(net "M_J_CPU0_SB_DQS_DP<0>")
	)
	(arc
		(start 381.034036 -276.058122)
		(mid 381.196687 -276.080382)
		(end 381.353314 -276.031198)
		(width 0.09525)
		(layer "In4.Cu")
		(net "M_J_CPU0_SB_DQS_DP<0>")
	)
	(arc
		(start 393.195048 -276.031198)
		(mid 393.369137 -276.08207)
		(end 393.546838 -276.045676)
		(width 0.09525)
		(layer "In4.Cu")
		(net "M_J_CPU0_SB_DQS_DP<0>")
	)
	(arc
		(start 391.6934 -276.031198)
		(mid 391.959487 -275.955653)
		(end 392.22934 -276.016466)
		(width 0.09525)
		(layer "In4.Cu")
		(net "M_J_CPU0_SB_DQS_DP<0>")
	)
	(arc
		(start 391.324592 -276.036024)
		(mid 391.509624 -276.081938)
		(end 391.6934 -276.031198)
		(width 0.09525)
		(layer "In4.Cu")
		(net "M_J_CPU0_SB_DQS_DP<0>")
	)
	(arc
		(start 386.993384 -276.031198)
		(mid 387.274816 -275.955443)
		(end 387.556248 -276.031198)
		(width 0.09525)
		(layer "In4.Cu")
		(net "M_J_CPU0_SB_DQS_DP<0>")
	)
	(arc
		(start 385.67614 -276.031198)
		(mid 385.859915 -276.08197)
		(end 386.044948 -276.036024)
		(width 0.09525)
		(layer "In4.Cu")
		(net "M_J_CPU0_SB_DQS_DP<0>")
	)
	(arc
		(start 384.173476 -276.031198)
		(mid 384.454908 -275.955443)
		(end 384.73634 -276.031198)
		(width 0.09525)
		(layer "In4.Cu")
		(net "M_J_CPU0_SB_DQS_DP<0>")
	)
	(arc
		(start 385.113276 -276.031198)
		(mid 385.394708 -275.955443)
		(end 385.67614 -276.031198)
		(width 0.09525)
		(layer "In4.Cu")
		(net "M_J_CPU0_SB_DQS_DP<0>")
	)
	(arc
		(start 383.233422 -276.031198)
		(mid 383.514854 -275.955443)
		(end 383.796286 -276.031198)
		(width 0.09525)
		(layer "In4.Cu")
		(net "M_J_CPU0_SB_DQS_DP<0>")
	)
	(arc
		(start 386.05333 -276.031198)
		(mid 386.334762 -275.955443)
		(end 386.616194 -276.031198)
		(width 0.09525)
		(layer "In4.Cu")
		(net "M_J_CPU0_SB_DQS_DP<0>")
	)
	(arc
		(start 389.813292 -276.031198)
		(mid 390.094724 -275.955443)
		(end 390.376156 -276.031198)
		(width 0.09525)
		(layer "In4.Cu")
		(net "M_J_CPU0_SB_DQS_DP<0>")
	)
	(arc
		(start 389.436356 -276.031198)
		(mid 389.624824 -276.081875)
		(end 389.813292 -276.031198)
		(width 0.09525)
		(layer "In4.Cu")
		(net "M_J_CPU0_SB_DQS_DP<0>")
	)
	(arc
		(start 393.572238 -276.031198)
		(mid 393.603793 -276.010991)
		(end 393.633198 -275.987764)
		(width 0.09525)
		(layer "In4.Cu")
		(net "M_J_CPU0_SB_DQS_DP<0>")
	)
	(arc
		(start 390.376156 -276.031198)
		(mid 390.559931 -276.08197)
		(end 390.744964 -276.036024)
		(width 0.09525)
		(layer "In4.Cu")
		(net "M_J_CPU0_SB_DQS_DP<0>")
	)
	(arc
		(start 381.916178 -276.031198)
		(mid 382.099953 -276.08197)
		(end 382.284986 -276.036024)
		(width 0.09525)
		(layer "In4.Cu")
		(net "M_J_CPU0_SB_DQS_DP<0>")
	)
	(arc
		(start 388.873492 -276.031198)
		(mid 389.154924 -275.955443)
		(end 389.436356 -276.031198)
		(width 0.09525)
		(layer "In4.Cu")
		(net "M_J_CPU0_SB_DQS_DP<0>")
	)
	(arc
		(start 387.933438 -276.031198)
		(mid 388.21487 -275.955443)
		(end 388.496302 -276.031198)
		(width 0.09525)
		(layer "In4.Cu")
		(net "M_J_CPU0_SB_DQS_DP<0>")
	)
	(arc
		(start 382.293368 -276.031198)
		(mid 382.5748 -275.955443)
		(end 382.856232 -276.031198)
		(width 0.09525)
		(layer "In4.Cu")
		(net "M_J_CPU0_SB_DQS_DP<0>")
	)
	(arc
		(start 384.73634 -276.031198)
		(mid 384.924808 -276.081875)
		(end 385.113276 -276.031198)
		(width 0.09525)
		(layer "In4.Cu")
		(net "M_J_CPU0_SB_DQS_DP<0>")
	)
	(arc
		(start 393.633198 -275.987764)
		(mid 393.641959 -275.979898)
		(end 393.65047 -275.971762)
		(width 0.09525)
		(layer "In4.Cu")
		(net "M_J_CPU0_SB_DQS_DP<0>")
	)
	(arc
		(start 392.269218 -276.03958)
		(mid 392.451143 -276.081785)
		(end 392.630914 -276.031198)
		(width 0.09525)
		(layer "In4.Cu")
		(net "M_J_CPU0_SB_DQS_DP<0>")
	)
	(arc
		(start 383.804668 -276.036024)
		(mid 383.9897 -276.081938)
		(end 384.173476 -276.031198)
		(width 0.09525)
		(layer "In4.Cu")
		(net "M_J_CPU0_SB_DQS_DP<0>")
	)
	(arc
		(start 390.753346 -276.031198)
		(mid 391.034778 -275.955443)
		(end 391.31621 -276.031198)
		(width 0.09525)
		(layer "In4.Cu")
		(net "M_J_CPU0_SB_DQS_DP<0>")
	)
	(arc
		(start 386.616194 -276.031198)
		(mid 386.799969 -276.08197)
		(end 386.985002 -276.036024)
		(width 0.09525)
		(layer "In4.Cu")
		(net "M_J_CPU0_SB_DQS_DP<0>")
	)
	(arc
		(start 388.504684 -276.036024)
		(mid 388.689716 -276.081938)
		(end 388.873492 -276.031198)
		(width 0.09525)
		(layer "In4.Cu")
		(net "M_J_CPU0_SB_DQS_DP<0>")
	)
	(arc
		(start 392.654282 -276.017736)
		(mid 392.926383 -275.955058)
		(end 393.195048 -276.031198)
		(width 0.09525)
		(layer "In4.Cu")
		(net "M_J_CPU0_SB_DQS_DP<0>")
	)
	(segment
		(start 380.22784 -271.39011)
		(end 380.694946 -271.656048)
		(width 0.12954)
		(layer "F.Cu")
		(net "M_J_CPU0_SB_DQS_DN<9>")
	)
	(segment
		(start 425.081954 -275.112226)
		(end 425.931838 -275.96211)
		(width 0.16002)
		(layer "In4.Cu")
		(net "M_J_CPU0_SB_DQS_DN<9>")
	)
	(segment
		(start 420.232078 -275.96211)
		(end 420.567104 -276.297136)
		(width 0.16002)
		(layer "In4.Cu")
		(net "M_J_CPU0_SB_DQS_DN<9>")
	)
	(segment
		(start 395.859254 -269.55496)
		(end 405.074882 -269.55496)
		(width 0.16002)
		(layer "In4.Cu")
		(net "M_J_CPU0_SB_DQS_DN<9>")
	)
	(segment
		(start 418.325046 -275.96211)
		(end 420.232078 -275.96211)
		(width 0.16002)
		(layer "In4.Cu")
		(net "M_J_CPU0_SB_DQS_DN<9>")
	)
	(segment
		(start 433.312824 -275.893276)
		(end 435.350412 -275.893276)
		(width 0.16002)
		(layer "In4.Cu")
		(net "M_J_CPU0_SB_DQS_DN<9>")
	)
	(segment
		(start 395.776704 -269.496032)
		(end 395.835632 -269.55496)
		(width 0.09525)
		(layer "In4.Cu")
		(net "M_J_CPU0_SB_DQS_DN<9>")
	)
	(segment
		(start 417.885372 -275.522436)
		(end 418.325046 -275.96211)
		(width 0.16002)
		(layer "In4.Cu")
		(net "M_J_CPU0_SB_DQS_DN<9>")
	)
	(segment
		(start 430.392078 -275.73097)
		(end 431.010822 -275.112226)
		(width 0.16002)
		(layer "In4.Cu")
		(net "M_J_CPU0_SB_DQS_DN<9>")
	)
	(segment
		(start 392.145774 -271.321276)
		(end 392.15314 -271.325086)
		(width 0.09525)
		(layer "In4.Cu")
		(net "M_J_CPU0_SB_DQS_DN<9>")
	)
	(segment
		(start 411.839664 -275.112226)
		(end 414.159954 -275.112226)
		(width 0.16002)
		(layer "In4.Cu")
		(net "M_J_CPU0_SB_DQS_DN<9>")
	)
	(segment
		(start 383.69494 -271.326102)
		(end 383.703322 -271.330928)
		(width 0.09525)
		(layer "In4.Cu")
		(net "M_J_CPU0_SB_DQS_DN<9>")
	)
	(segment
		(start 389.33501 -271.326102)
		(end 389.343392 -271.330928)
		(width 0.09525)
		(layer "In4.Cu")
		(net "M_J_CPU0_SB_DQS_DN<9>")
	)
	(segment
		(start 421.58666 -276.297136)
		(end 422.09339 -275.790406)
		(width 0.16002)
		(layer "In4.Cu")
		(net "M_J_CPU0_SB_DQS_DN<9>")
	)
	(segment
		(start 389.906256 -271.330928)
		(end 389.914638 -271.326102)
		(width 0.09525)
		(layer "In4.Cu")
		(net "M_J_CPU0_SB_DQS_DN<9>")
	)
	(segment
		(start 423.017442 -275.790406)
		(end 423.695622 -275.112226)
		(width 0.16002)
		(layer "In4.Cu")
		(net "M_J_CPU0_SB_DQS_DN<9>")
	)
	(segment
		(start 420.567104 -276.297136)
		(end 421.58666 -276.297136)
		(width 0.16002)
		(layer "In4.Cu")
		(net "M_J_CPU0_SB_DQS_DN<9>")
	)
	(segment
		(start 385.20624 -271.330928)
		(end 385.214622 -271.326102)
		(width 0.09525)
		(layer "In4.Cu")
		(net "M_J_CPU0_SB_DQS_DN<9>")
	)
	(segment
		(start 429.29302 -276.274276)
		(end 429.836326 -275.73097)
		(width 0.16002)
		(layer "In4.Cu")
		(net "M_J_CPU0_SB_DQS_DN<9>")
	)
	(segment
		(start 405.074882 -269.55496)
		(end 407.67127 -272.151348)
		(width 0.16002)
		(layer "In4.Cu")
		(net "M_J_CPU0_SB_DQS_DN<9>")
	)
	(segment
		(start 380.84887 -271.390618)
		(end 380.949708 -271.363948)
		(width 0.09525)
		(layer "In4.Cu")
		(net "M_J_CPU0_SB_DQS_DN<9>")
	)
	(segment
		(start 395.283944 -269.496032)
		(end 395.776704 -269.496032)
		(width 0.09525)
		(layer "In4.Cu")
		(net "M_J_CPU0_SB_DQS_DN<9>")
	)
	(segment
		(start 423.695622 -275.112226)
		(end 425.081954 -275.112226)
		(width 0.16002)
		(layer "In4.Cu")
		(net "M_J_CPU0_SB_DQS_DN<9>")
	)
	(segment
		(start 437.75249 -276.297136)
		(end 437.938418 -276.111208)
		(width 0.16002)
		(layer "In4.Cu")
		(net "M_J_CPU0_SB_DQS_DN<9>")
	)
	(segment
		(start 392.726164 -271.330928)
		(end 392.764264 -271.30883)
		(width 0.09525)
		(layer "In4.Cu")
		(net "M_J_CPU0_SB_DQS_DN<9>")
	)
	(segment
		(start 388.394956 -271.326102)
		(end 388.403338 -271.330928)
		(width 0.09525)
		(layer "In4.Cu")
		(net "M_J_CPU0_SB_DQS_DN<9>")
	)
	(segment
		(start 393.163806 -270.539718)
		(end 393.196318 -270.520922)
		(width 0.09525)
		(layer "In4.Cu")
		(net "M_J_CPU0_SB_DQS_DN<9>")
	)
	(segment
		(start 392.15314 -271.325086)
		(end 392.1633 -271.330928)
		(width 0.09525)
		(layer "In4.Cu")
		(net "M_J_CPU0_SB_DQS_DN<9>")
	)
	(segment
		(start 393.196318 -270.520922)
		(end 393.196318 -270.520414)
		(width 0.09525)
		(layer "In4.Cu")
		(net "M_J_CPU0_SB_DQS_DN<9>")
	)
	(segment
		(start 428.00397 -275.96211)
		(end 428.316136 -276.274276)
		(width 0.16002)
		(layer "In4.Cu")
		(net "M_J_CPU0_SB_DQS_DN<9>")
	)
	(segment
		(start 435.754272 -276.297136)
		(end 437.75249 -276.297136)
		(width 0.16002)
		(layer "In4.Cu")
		(net "M_J_CPU0_SB_DQS_DN<9>")
	)
	(segment
		(start 431.010822 -275.112226)
		(end 432.531774 -275.112226)
		(width 0.16002)
		(layer "In4.Cu")
		(net "M_J_CPU0_SB_DQS_DN<9>")
	)
	(segment
		(start 393.739878 -270.248888)
		(end 394.631672 -269.35684)
		(width 0.09525)
		(layer "In4.Cu")
		(net "M_J_CPU0_SB_DQS_DN<9>")
	)
	(segment
		(start 381.446278 -271.330928)
		(end 381.45466 -271.326102)
		(width 0.09525)
		(layer "In4.Cu")
		(net "M_J_CPU0_SB_DQS_DN<9>")
	)
	(segment
		(start 425.931838 -275.96211)
		(end 428.00397 -275.96211)
		(width 0.16002)
		(layer "In4.Cu")
		(net "M_J_CPU0_SB_DQS_DN<9>")
	)
	(segment
		(start 432.531774 -275.112226)
		(end 433.312824 -275.893276)
		(width 0.16002)
		(layer "In4.Cu")
		(net "M_J_CPU0_SB_DQS_DN<9>")
	)
	(segment
		(start 408.878786 -272.151348)
		(end 411.839664 -275.112226)
		(width 0.16002)
		(layer "In4.Cu")
		(net "M_J_CPU0_SB_DQS_DN<9>")
	)
	(segment
		(start 414.159954 -275.112226)
		(end 414.570164 -275.522436)
		(width 0.16002)
		(layer "In4.Cu")
		(net "M_J_CPU0_SB_DQS_DN<9>")
	)
	(segment
		(start 422.09339 -275.790406)
		(end 423.017442 -275.790406)
		(width 0.16002)
		(layer "In4.Cu")
		(net "M_J_CPU0_SB_DQS_DN<9>")
	)
	(segment
		(start 414.570164 -275.522436)
		(end 417.885372 -275.522436)
		(width 0.16002)
		(layer "In4.Cu")
		(net "M_J_CPU0_SB_DQS_DN<9>")
	)
	(segment
		(start 429.836326 -275.73097)
		(end 430.392078 -275.73097)
		(width 0.16002)
		(layer "In4.Cu")
		(net "M_J_CPU0_SB_DQS_DN<9>")
	)
	(segment
		(start 428.316136 -276.274276)
		(end 429.29302 -276.274276)
		(width 0.16002)
		(layer "In4.Cu")
		(net "M_J_CPU0_SB_DQS_DN<9>")
	)
	(segment
		(start 438.826402 -276.111208)
		(end 439.100214 -276.38502)
		(width 0.16002)
		(layer "In4.Cu")
		(net "M_J_CPU0_SB_DQS_DN<9>")
	)
	(segment
		(start 407.67127 -272.151348)
		(end 408.878786 -272.151348)
		(width 0.16002)
		(layer "In4.Cu")
		(net "M_J_CPU0_SB_DQS_DN<9>")
	)
	(segment
		(start 437.938418 -276.111208)
		(end 438.826402 -276.111208)
		(width 0.16002)
		(layer "In4.Cu")
		(net "M_J_CPU0_SB_DQS_DN<9>")
	)
	(segment
		(start 395.835632 -269.55496)
		(end 395.859254 -269.55496)
		(width 0.09525)
		(layer "In4.Cu")
		(net "M_J_CPU0_SB_DQS_DN<9>")
	)
	(segment
		(start 380.694946 -271.656048)
		(end 380.84887 -271.390618)
		(width 0.09525)
		(layer "In4.Cu")
		(net "M_J_CPU0_SB_DQS_DN<9>")
	)
	(segment
		(start 386.146294 -271.330928)
		(end 386.154676 -271.326102)
		(width 0.09525)
		(layer "In4.Cu")
		(net "M_J_CPU0_SB_DQS_DN<9>")
	)
	(segment
		(start 435.350412 -275.893276)
		(end 435.754272 -276.297136)
		(width 0.16002)
		(layer "In4.Cu")
		(net "M_J_CPU0_SB_DQS_DN<9>")
	)
	(segment
		(start 384.634994 -271.326102)
		(end 384.643376 -271.330928)
		(width 0.09525)
		(layer "In4.Cu")
		(net "M_J_CPU0_SB_DQS_DN<9>")
	)
	(segment
		(start 394.631672 -269.35684)
		(end 395.144752 -269.35684)
		(width 0.09525)
		(layer "In4.Cu")
		(net "M_J_CPU0_SB_DQS_DN<9>")
	)
	(segment
		(start 395.144752 -269.35684)
		(end 395.283944 -269.496032)
		(width 0.09525)
		(layer "In4.Cu")
		(net "M_J_CPU0_SB_DQS_DN<9>")
	)
	(arc
		(start 386.154676 -271.326102)
		(mid 386.339708 -271.280188)
		(end 386.523484 -271.330928)
		(width 0.09525)
		(layer "In4.Cu")
		(net "M_J_CPU0_SB_DQS_DN<9>")
	)
	(arc
		(start 388.966202 -271.330928)
		(mid 389.149977 -271.280156)
		(end 389.33501 -271.326102)
		(width 0.09525)
		(layer "In4.Cu")
		(net "M_J_CPU0_SB_DQS_DN<9>")
	)
	(arc
		(start 389.914638 -271.326102)
		(mid 390.09967 -271.280188)
		(end 390.283446 -271.330928)
		(width 0.09525)
		(layer "In4.Cu")
		(net "M_J_CPU0_SB_DQS_DN<9>")
	)
	(arc
		(start 392.764264 -271.30883)
		(mid 392.942714 -271.10736)
		(end 393.007088 -270.846042)
		(width 0.09525)
		(layer "In4.Cu")
		(net "M_J_CPU0_SB_DQS_DN<9>")
	)
	(arc
		(start 393.007088 -270.846042)
		(mid 393.048545 -270.674002)
		(end 393.163806 -270.539718)
		(width 0.09525)
		(layer "In4.Cu")
		(net "M_J_CPU0_SB_DQS_DN<9>")
	)
	(arc
		(start 387.463284 -271.330928)
		(mid 387.744716 -271.406683)
		(end 388.026148 -271.330928)
		(width 0.09525)
		(layer "In4.Cu")
		(net "M_J_CPU0_SB_DQS_DN<9>")
	)
	(arc
		(start 391.78611 -271.330928)
		(mid 391.964716 -271.28026)
		(end 392.145774 -271.321276)
		(width 0.09525)
		(layer "In4.Cu")
		(net "M_J_CPU0_SB_DQS_DN<9>")
	)
	(arc
		(start 387.086348 -271.330928)
		(mid 387.274816 -271.280251)
		(end 387.463284 -271.330928)
		(width 0.09525)
		(layer "In4.Cu")
		(net "M_J_CPU0_SB_DQS_DN<9>")
	)
	(arc
		(start 385.58343 -271.330928)
		(mid 385.864862 -271.406683)
		(end 386.146294 -271.330928)
		(width 0.09525)
		(layer "In4.Cu")
		(net "M_J_CPU0_SB_DQS_DN<9>")
	)
	(arc
		(start 388.403338 -271.330928)
		(mid 388.68477 -271.406683)
		(end 388.966202 -271.330928)
		(width 0.09525)
		(layer "In4.Cu")
		(net "M_J_CPU0_SB_DQS_DN<9>")
	)
	(arc
		(start 388.026148 -271.330928)
		(mid 388.209923 -271.280156)
		(end 388.394956 -271.326102)
		(width 0.09525)
		(layer "In4.Cu")
		(net "M_J_CPU0_SB_DQS_DN<9>")
	)
	(arc
		(start 390.84631 -271.330928)
		(mid 391.034778 -271.280251)
		(end 391.223246 -271.330928)
		(width 0.09525)
		(layer "In4.Cu")
		(net "M_J_CPU0_SB_DQS_DN<9>")
	)
	(arc
		(start 383.326132 -271.330928)
		(mid 383.509907 -271.280156)
		(end 383.69494 -271.326102)
		(width 0.09525)
		(layer "In4.Cu")
		(net "M_J_CPU0_SB_DQS_DN<9>")
	)
	(arc
		(start 380.96952 -271.371822)
		(mid 381.212484 -271.404809)
		(end 381.446278 -271.330928)
		(width 0.09525)
		(layer "In4.Cu")
		(net "M_J_CPU0_SB_DQS_DN<9>")
	)
	(arc
		(start 389.343392 -271.330928)
		(mid 389.624824 -271.406683)
		(end 389.906256 -271.330928)
		(width 0.09525)
		(layer "In4.Cu")
		(net "M_J_CPU0_SB_DQS_DN<9>")
	)
	(arc
		(start 390.283446 -271.330928)
		(mid 390.564878 -271.406683)
		(end 390.84631 -271.330928)
		(width 0.09525)
		(layer "In4.Cu")
		(net "M_J_CPU0_SB_DQS_DN<9>")
	)
	(arc
		(start 381.823468 -271.330928)
		(mid 382.1049 -271.406683)
		(end 382.386332 -271.330928)
		(width 0.09525)
		(layer "In4.Cu")
		(net "M_J_CPU0_SB_DQS_DN<9>")
	)
	(arc
		(start 382.386332 -271.330928)
		(mid 382.5748 -271.280251)
		(end 382.763268 -271.330928)
		(width 0.09525)
		(layer "In4.Cu")
		(net "M_J_CPU0_SB_DQS_DN<9>")
	)
	(arc
		(start 391.223246 -271.330928)
		(mid 391.504678 -271.406683)
		(end 391.78611 -271.330928)
		(width 0.09525)
		(layer "In4.Cu")
		(net "M_J_CPU0_SB_DQS_DN<9>")
	)
	(arc
		(start 383.703322 -271.330928)
		(mid 383.984754 -271.406683)
		(end 384.266186 -271.330928)
		(width 0.09525)
		(layer "In4.Cu")
		(net "M_J_CPU0_SB_DQS_DN<9>")
	)
	(arc
		(start 382.763268 -271.330928)
		(mid 383.0447 -271.406683)
		(end 383.326132 -271.330928)
		(width 0.09525)
		(layer "In4.Cu")
		(net "M_J_CPU0_SB_DQS_DN<9>")
	)
	(arc
		(start 386.523484 -271.330928)
		(mid 386.804916 -271.406683)
		(end 387.086348 -271.330928)
		(width 0.09525)
		(layer "In4.Cu")
		(net "M_J_CPU0_SB_DQS_DN<9>")
	)
	(arc
		(start 384.266186 -271.330928)
		(mid 384.449961 -271.280156)
		(end 384.634994 -271.326102)
		(width 0.09525)
		(layer "In4.Cu")
		(net "M_J_CPU0_SB_DQS_DN<9>")
	)
	(arc
		(start 393.196318 -270.520414)
		(mid 393.258227 -270.491577)
		(end 393.324334 -270.47444)
		(width 0.09525)
		(layer "In4.Cu")
		(net "M_J_CPU0_SB_DQS_DN<9>")
	)
	(arc
		(start 385.214622 -271.326102)
		(mid 385.399654 -271.280188)
		(end 385.58343 -271.330928)
		(width 0.09525)
		(layer "In4.Cu")
		(net "M_J_CPU0_SB_DQS_DN<9>")
	)
	(arc
		(start 392.1633 -271.330928)
		(mid 392.444732 -271.406683)
		(end 392.726164 -271.330928)
		(width 0.09525)
		(layer "In4.Cu")
		(net "M_J_CPU0_SB_DQS_DN<9>")
	)
	(arc
		(start 384.643376 -271.330928)
		(mid 384.924808 -271.406683)
		(end 385.20624 -271.330928)
		(width 0.09525)
		(layer "In4.Cu")
		(net "M_J_CPU0_SB_DQS_DN<9>")
	)
	(arc
		(start 380.949708 -271.363948)
		(mid 380.959576 -271.367979)
		(end 380.96952 -271.371822)
		(width 0.09525)
		(layer "In4.Cu")
		(net "M_J_CPU0_SB_DQS_DN<9>")
	)
	(arc
		(start 381.45466 -271.326102)
		(mid 381.639692 -271.280188)
		(end 381.823468 -271.330928)
		(width 0.09525)
		(layer "In4.Cu")
		(net "M_J_CPU0_SB_DQS_DN<9>")
	)
	(arc
		(start 393.324334 -270.47444)
		(mid 393.551289 -270.39701)
		(end 393.739878 -270.248888)
		(width 0.09525)
		(layer "In4.Cu")
		(net "M_J_CPU0_SB_DQS_DN<9>")
	)
	(segment
		(start 379.28804 -290.83)
		(end 379.754892 -291.095938)
		(width 0.12954)
		(layer "F.Cu")
		(net "M_J_CPU0_SB_DQS_DN<8>")
	)
	(segment
		(start 429.062896 -314.715652)
		(end 428.384716 -314.715652)
		(width 0.16002)
		(layer "In4.Cu")
		(net "M_J_CPU0_SB_DQS_DN<8>")
	)
	(segment
		(start 381.45466 -291.425884)
		(end 381.446278 -291.421058)
		(width 0.09525)
		(layer "In4.Cu")
		(net "M_J_CPU0_SB_DQS_DN<8>")
	)
	(segment
		(start 394.107416 -293.834312)
		(end 394.1064 -293.833804)
		(width 0.09525)
		(layer "In4.Cu")
		(net "M_J_CPU0_SB_DQS_DN<8>")
	)
	(segment
		(start 423.062654 -313.840622)
		(end 422.282366 -313.840622)
		(width 0.16002)
		(layer "In4.Cu")
		(net "M_J_CPU0_SB_DQS_DN<8>")
	)
	(segment
		(start 388.403338 -291.421058)
		(end 388.394956 -291.425884)
		(width 0.09525)
		(layer "In4.Cu")
		(net "M_J_CPU0_SB_DQS_DN<8>")
	)
	(segment
		(start 430.6062 -313.867292)
		(end 429.911256 -313.867292)
		(width 0.16002)
		(layer "In4.Cu")
		(net "M_J_CPU0_SB_DQS_DN<8>")
	)
	(segment
		(start 417.78428 -313.841892)
		(end 414.729676 -313.841892)
		(width 0.16002)
		(layer "In4.Cu")
		(net "M_J_CPU0_SB_DQS_DN<8>")
	)
	(segment
		(start 412.406084 -314.318904)
		(end 412.033212 -313.946032)
		(width 0.16002)
		(layer "In4.Cu")
		(net "M_J_CPU0_SB_DQS_DN<8>")
	)
	(segment
		(start 434.246274 -314.058808)
		(end 434.129434 -313.941968)
		(width 0.16002)
		(layer "In4.Cu")
		(net "M_J_CPU0_SB_DQS_DN<8>")
	)
	(segment
		(start 386.154676 -291.425884)
		(end 386.146294 -291.421058)
		(width 0.09525)
		(layer "In4.Cu")
		(net "M_J_CPU0_SB_DQS_DN<8>")
	)
	(segment
		(start 421.407336 -314.715652)
		(end 420.834312 -314.715652)
		(width 0.16002)
		(layer "In4.Cu")
		(net "M_J_CPU0_SB_DQS_DN<8>")
	)
	(segment
		(start 409.192222 -314.318904)
		(end 409.192222 -314.720478)
		(width 0.16002)
		(layer "In4.Cu")
		(net "M_J_CPU0_SB_DQS_DN<8>")
	)
	(segment
		(start 411.506162 -313.946032)
		(end 411.13329 -314.318904)
		(width 0.16002)
		(layer "In4.Cu")
		(net "M_J_CPU0_SB_DQS_DN<8>")
	)
	(segment
		(start 408.796236 -314.889896)
		(end 395.304518 -301.398178)
		(width 0.16002)
		(layer "In4.Cu")
		(net "M_J_CPU0_SB_DQS_DN<8>")
	)
	(segment
		(start 433.532534 -314.058808)
		(end 432.66868 -314.058808)
		(width 0.16002)
		(layer "In4.Cu")
		(net "M_J_CPU0_SB_DQS_DN<8>")
	)
	(segment
		(start 426.029628 -315.058044)
		(end 425.152312 -315.058044)
		(width 0.16002)
		(layer "In4.Cu")
		(net "M_J_CPU0_SB_DQS_DN<8>")
	)
	(segment
		(start 413.190436 -314.916312)
		(end 412.601918 -314.916312)
		(width 0.16002)
		(layer "In4.Cu")
		(net "M_J_CPU0_SB_DQS_DN<8>")
	)
	(segment
		(start 395.304518 -301.398178)
		(end 395.304518 -295.286176)
		(width 0.16002)
		(layer "In4.Cu")
		(net "M_J_CPU0_SB_DQS_DN<8>")
	)
	(segment
		(start 409.192222 -314.720478)
		(end 409.022804 -314.889896)
		(width 0.16002)
		(layer "In4.Cu")
		(net "M_J_CPU0_SB_DQS_DN<8>")
	)
	(segment
		(start 432.66868 -314.058808)
		(end 432.484276 -314.243212)
		(width 0.16002)
		(layer "In4.Cu")
		(net "M_J_CPU0_SB_DQS_DN<8>")
	)
	(segment
		(start 379.600968 -291.361368)
		(end 379.754892 -291.095938)
		(width 0.09525)
		(layer "In4.Cu")
		(net "M_J_CPU0_SB_DQS_DN<8>")
	)
	(segment
		(start 394.10894 -293.835328)
		(end 394.107416 -293.834312)
		(width 0.09525)
		(layer "In4.Cu")
		(net "M_J_CPU0_SB_DQS_DN<8>")
	)
	(segment
		(start 409.022804 -314.889896)
		(end 408.796236 -314.889896)
		(width 0.16002)
		(layer "In4.Cu")
		(net "M_J_CPU0_SB_DQS_DN<8>")
	)
	(segment
		(start 426.743368 -315.058044)
		(end 426.626528 -314.941204)
		(width 0.16002)
		(layer "In4.Cu")
		(net "M_J_CPU0_SB_DQS_DN<8>")
	)
	(segment
		(start 392.1633 -291.421058)
		(end 392.154918 -291.425884)
		(width 0.09525)
		(layer "In4.Cu")
		(net "M_J_CPU0_SB_DQS_DN<8>")
	)
	(segment
		(start 395.304518 -295.286176)
		(end 395.028166 -295.01084)
		(width 0.16002)
		(layer "In4.Cu")
		(net "M_J_CPU0_SB_DQS_DN<8>")
	)
	(segment
		(start 423.660824 -314.438792)
		(end 423.062654 -313.840622)
		(width 0.16002)
		(layer "In4.Cu")
		(net "M_J_CPU0_SB_DQS_DN<8>")
	)
	(segment
		(start 394.174726 -293.87419)
		(end 394.120878 -293.842186)
		(width 0.09525)
		(layer "In4.Cu")
		(net "M_J_CPU0_SB_DQS_DN<8>")
	)
	(segment
		(start 410.937456 -314.916312)
		(end 410.66085 -314.916312)
		(width 0.16002)
		(layer "In4.Cu")
		(net "M_J_CPU0_SB_DQS_DN<8>")
	)
	(segment
		(start 412.033212 -313.946032)
		(end 411.506162 -313.946032)
		(width 0.16002)
		(layer "In4.Cu")
		(net "M_J_CPU0_SB_DQS_DN<8>")
	)
	(segment
		(start 394.92809 -294.994584)
		(end 394.416534 -294.48379)
		(width 0.09525)
		(layer "In4.Cu")
		(net "M_J_CPU0_SB_DQS_DN<8>")
	)
	(segment
		(start 426.146468 -314.941204)
		(end 426.029628 -315.058044)
		(width 0.16002)
		(layer "In4.Cu")
		(net "M_J_CPU0_SB_DQS_DN<8>")
	)
	(segment
		(start 393.673838 -292.747192)
		(end 393.130532 -292.203886)
		(width 0.09525)
		(layer "In4.Cu")
		(net "M_J_CPU0_SB_DQS_DN<8>")
	)
	(segment
		(start 413.876236 -314.695332)
		(end 413.411416 -314.695332)
		(width 0.16002)
		(layer "In4.Cu")
		(net "M_J_CPU0_SB_DQS_DN<8>")
	)
	(segment
		(start 434.129434 -313.941968)
		(end 433.649374 -313.941968)
		(width 0.16002)
		(layer "In4.Cu")
		(net "M_J_CPU0_SB_DQS_DN<8>")
	)
	(segment
		(start 385.214622 -291.425884)
		(end 385.20624 -291.421058)
		(width 0.09525)
		(layer "In4.Cu")
		(net "M_J_CPU0_SB_DQS_DN<8>")
	)
	(segment
		(start 410.66085 -314.916312)
		(end 410.465016 -314.720478)
		(width 0.16002)
		(layer "In4.Cu")
		(net "M_J_CPU0_SB_DQS_DN<8>")
	)
	(segment
		(start 389.914638 -291.425884)
		(end 389.906256 -291.421058)
		(width 0.09525)
		(layer "In4.Cu")
		(net "M_J_CPU0_SB_DQS_DN<8>")
	)
	(segment
		(start 434.726334 -314.058808)
		(end 434.246274 -314.058808)
		(width 0.16002)
		(layer "In4.Cu")
		(net "M_J_CPU0_SB_DQS_DN<8>")
	)
	(segment
		(start 411.13329 -314.720478)
		(end 410.937456 -314.916312)
		(width 0.16002)
		(layer "In4.Cu")
		(net "M_J_CPU0_SB_DQS_DN<8>")
	)
	(segment
		(start 394.120878 -293.842186)
		(end 394.10894 -293.835328)
		(width 0.09525)
		(layer "In4.Cu")
		(net "M_J_CPU0_SB_DQS_DN<8>")
	)
	(segment
		(start 395.028166 -295.01084)
		(end 395.011402 -294.994076)
		(width 0.09525)
		(layer "In4.Cu")
		(net "M_J_CPU0_SB_DQS_DN<8>")
	)
	(segment
		(start 422.282366 -313.840622)
		(end 421.407336 -314.715652)
		(width 0.16002)
		(layer "In4.Cu")
		(net "M_J_CPU0_SB_DQS_DN<8>")
	)
	(segment
		(start 420.834312 -314.715652)
		(end 420.49192 -315.058044)
		(width 0.16002)
		(layer "In4.Cu")
		(net "M_J_CPU0_SB_DQS_DN<8>")
	)
	(segment
		(start 429.911256 -313.867292)
		(end 429.062896 -314.715652)
		(width 0.16002)
		(layer "In4.Cu")
		(net "M_J_CPU0_SB_DQS_DN<8>")
	)
	(segment
		(start 380.883414 -291.421058)
		(end 380.875032 -291.425884)
		(width 0.09525)
		(layer "In4.Cu")
		(net "M_J_CPU0_SB_DQS_DN<8>")
	)
	(segment
		(start 435.000146 -313.784996)
		(end 434.726334 -314.058808)
		(width 0.16002)
		(layer "In4.Cu")
		(net "M_J_CPU0_SB_DQS_DN<8>")
	)
	(segment
		(start 383.703322 -291.421058)
		(end 383.69494 -291.425884)
		(width 0.09525)
		(layer "In4.Cu")
		(net "M_J_CPU0_SB_DQS_DN<8>")
	)
	(segment
		(start 410.465016 -314.318904)
		(end 410.092144 -313.946032)
		(width 0.16002)
		(layer "In4.Cu")
		(net "M_J_CPU0_SB_DQS_DN<8>")
	)
	(segment
		(start 379.624336 -291.448236)
		(end 379.600968 -291.361368)
		(width 0.09525)
		(layer "In4.Cu")
		(net "M_J_CPU0_SB_DQS_DN<8>")
	)
	(segment
		(start 384.643376 -291.421058)
		(end 384.634994 -291.425884)
		(width 0.09525)
		(layer "In4.Cu")
		(net "M_J_CPU0_SB_DQS_DN<8>")
	)
	(segment
		(start 426.626528 -314.941204)
		(end 426.146468 -314.941204)
		(width 0.16002)
		(layer "In4.Cu")
		(net "M_J_CPU0_SB_DQS_DN<8>")
	)
	(segment
		(start 419.000432 -315.058044)
		(end 417.78428 -313.841892)
		(width 0.16002)
		(layer "In4.Cu")
		(net "M_J_CPU0_SB_DQS_DN<8>")
	)
	(segment
		(start 433.649374 -313.941968)
		(end 433.532534 -314.058808)
		(width 0.16002)
		(layer "In4.Cu")
		(net "M_J_CPU0_SB_DQS_DN<8>")
	)
	(segment
		(start 424.53306 -314.438792)
		(end 423.660824 -314.438792)
		(width 0.16002)
		(layer "In4.Cu")
		(net "M_J_CPU0_SB_DQS_DN<8>")
	)
	(segment
		(start 425.152312 -315.058044)
		(end 424.53306 -314.438792)
		(width 0.16002)
		(layer "In4.Cu")
		(net "M_J_CPU0_SB_DQS_DN<8>")
	)
	(segment
		(start 412.601918 -314.916312)
		(end 412.406084 -314.720478)
		(width 0.16002)
		(layer "In4.Cu")
		(net "M_J_CPU0_SB_DQS_DN<8>")
	)
	(segment
		(start 410.092144 -313.946032)
		(end 409.565094 -313.946032)
		(width 0.16002)
		(layer "In4.Cu")
		(net "M_J_CPU0_SB_DQS_DN<8>")
	)
	(segment
		(start 414.729676 -313.841892)
		(end 413.876236 -314.695332)
		(width 0.16002)
		(layer "In4.Cu")
		(net "M_J_CPU0_SB_DQS_DN<8>")
	)
	(segment
		(start 392.764264 -291.443156)
		(end 392.726164 -291.421058)
		(width 0.09525)
		(layer "In4.Cu")
		(net "M_J_CPU0_SB_DQS_DN<8>")
	)
	(segment
		(start 428.042324 -315.058044)
		(end 426.743368 -315.058044)
		(width 0.16002)
		(layer "In4.Cu")
		(net "M_J_CPU0_SB_DQS_DN<8>")
	)
	(segment
		(start 430.98212 -314.243212)
		(end 430.6062 -313.867292)
		(width 0.16002)
		(layer "In4.Cu")
		(net "M_J_CPU0_SB_DQS_DN<8>")
	)
	(segment
		(start 428.384716 -314.715652)
		(end 428.042324 -315.058044)
		(width 0.16002)
		(layer "In4.Cu")
		(net "M_J_CPU0_SB_DQS_DN<8>")
	)
	(segment
		(start 411.13329 -314.318904)
		(end 411.13329 -314.720478)
		(width 0.16002)
		(layer "In4.Cu")
		(net "M_J_CPU0_SB_DQS_DN<8>")
	)
	(segment
		(start 413.411416 -314.695332)
		(end 413.190436 -314.916312)
		(width 0.16002)
		(layer "In4.Cu")
		(net "M_J_CPU0_SB_DQS_DN<8>")
	)
	(segment
		(start 420.49192 -315.058044)
		(end 419.000432 -315.058044)
		(width 0.16002)
		(layer "In4.Cu")
		(net "M_J_CPU0_SB_DQS_DN<8>")
	)
	(segment
		(start 394.416534 -294.48379)
		(end 394.416534 -294.335962)
		(width 0.09525)
		(layer "In4.Cu")
		(net "M_J_CPU0_SB_DQS_DN<8>")
	)
	(segment
		(start 395.011402 -294.994076)
		(end 394.92809 -294.994584)
		(width 0.09525)
		(layer "In4.Cu")
		(net "M_J_CPU0_SB_DQS_DN<8>")
	)
	(segment
		(start 389.343392 -291.421058)
		(end 389.33501 -291.425884)
		(width 0.09525)
		(layer "In4.Cu")
		(net "M_J_CPU0_SB_DQS_DN<8>")
	)
	(segment
		(start 379.94336 -291.421058)
		(end 379.934978 -291.425884)
		(width 0.09525)
		(layer "In4.Cu")
		(net "M_J_CPU0_SB_DQS_DN<8>")
	)
	(segment
		(start 412.406084 -314.720478)
		(end 412.406084 -314.318904)
		(width 0.16002)
		(layer "In4.Cu")
		(net "M_J_CPU0_SB_DQS_DN<8>")
	)
	(segment
		(start 394.104876 -293.832788)
		(end 394.104622 -293.832788)
		(width 0.09525)
		(layer "In4.Cu")
		(net "M_J_CPU0_SB_DQS_DN<8>")
	)
	(segment
		(start 432.484276 -314.243212)
		(end 430.98212 -314.243212)
		(width 0.16002)
		(layer "In4.Cu")
		(net "M_J_CPU0_SB_DQS_DN<8>")
	)
	(segment
		(start 409.565094 -313.946032)
		(end 409.192222 -314.318904)
		(width 0.16002)
		(layer "In4.Cu")
		(net "M_J_CPU0_SB_DQS_DN<8>")
	)
	(segment
		(start 410.465016 -314.720478)
		(end 410.465016 -314.318904)
		(width 0.16002)
		(layer "In4.Cu")
		(net "M_J_CPU0_SB_DQS_DN<8>")
	)
	(segment
		(start 394.1064 -293.833804)
		(end 394.104876 -293.832788)
		(width 0.09525)
		(layer "In4.Cu")
		(net "M_J_CPU0_SB_DQS_DN<8>")
	)
	(segment
		(start 393.947142 -293.525956)
		(end 393.947142 -293.407084)
		(width 0.09525)
		(layer "In4.Cu")
		(net "M_J_CPU0_SB_DQS_DN<8>")
	)
	(arc
		(start 394.416534 -294.335962)
		(mid 394.352426 -294.075333)
		(end 394.174726 -293.87419)
		(width 0.09525)
		(layer "In4.Cu")
		(net "M_J_CPU0_SB_DQS_DN<8>")
	)
	(arc
		(start 388.026148 -291.421058)
		(mid 387.744716 -291.345303)
		(end 387.463284 -291.421058)
		(width 0.09525)
		(layer "In4.Cu")
		(net "M_J_CPU0_SB_DQS_DN<8>")
	)
	(arc
		(start 385.58343 -291.421058)
		(mid 385.399655 -291.47183)
		(end 385.214622 -291.425884)
		(width 0.09525)
		(layer "In4.Cu")
		(net "M_J_CPU0_SB_DQS_DN<8>")
	)
	(arc
		(start 385.20624 -291.421058)
		(mid 384.924808 -291.345303)
		(end 384.643376 -291.421058)
		(width 0.09525)
		(layer "In4.Cu")
		(net "M_J_CPU0_SB_DQS_DN<8>")
	)
	(arc
		(start 393.130532 -292.203886)
		(mid 393.039194 -292.067189)
		(end 393.007088 -291.905944)
		(width 0.09525)
		(layer "In4.Cu")
		(net "M_J_CPU0_SB_DQS_DN<8>")
	)
	(arc
		(start 388.966202 -291.421058)
		(mid 388.68477 -291.345303)
		(end 388.403338 -291.421058)
		(width 0.09525)
		(layer "In4.Cu")
		(net "M_J_CPU0_SB_DQS_DN<8>")
	)
	(arc
		(start 388.394956 -291.425884)
		(mid 388.209924 -291.471798)
		(end 388.026148 -291.421058)
		(width 0.09525)
		(layer "In4.Cu")
		(net "M_J_CPU0_SB_DQS_DN<8>")
	)
	(arc
		(start 381.823468 -291.421058)
		(mid 381.639693 -291.47183)
		(end 381.45466 -291.425884)
		(width 0.09525)
		(layer "In4.Cu")
		(net "M_J_CPU0_SB_DQS_DN<8>")
	)
	(arc
		(start 391.78611 -291.421058)
		(mid 391.504678 -291.345303)
		(end 391.223246 -291.421058)
		(width 0.09525)
		(layer "In4.Cu")
		(net "M_J_CPU0_SB_DQS_DN<8>")
	)
	(arc
		(start 392.154918 -291.425884)
		(mid 391.969886 -291.471798)
		(end 391.78611 -291.421058)
		(width 0.09525)
		(layer "In4.Cu")
		(net "M_J_CPU0_SB_DQS_DN<8>")
	)
	(arc
		(start 387.086348 -291.421058)
		(mid 386.804916 -291.345303)
		(end 386.523484 -291.421058)
		(width 0.09525)
		(layer "In4.Cu")
		(net "M_J_CPU0_SB_DQS_DN<8>")
	)
	(arc
		(start 392.726164 -291.421058)
		(mid 392.444732 -291.345303)
		(end 392.1633 -291.421058)
		(width 0.09525)
		(layer "In4.Cu")
		(net "M_J_CPU0_SB_DQS_DN<8>")
	)
	(arc
		(start 393.947142 -293.407084)
		(mid 393.876107 -293.049965)
		(end 393.673838 -292.747192)
		(width 0.09525)
		(layer "In4.Cu")
		(net "M_J_CPU0_SB_DQS_DN<8>")
	)
	(arc
		(start 380.875032 -291.425884)
		(mid 380.69 -291.471798)
		(end 380.506224 -291.421058)
		(width 0.09525)
		(layer "In4.Cu")
		(net "M_J_CPU0_SB_DQS_DN<8>")
	)
	(arc
		(start 379.934978 -291.425884)
		(mid 379.782083 -291.470712)
		(end 379.624336 -291.448236)
		(width 0.09525)
		(layer "In4.Cu")
		(net "M_J_CPU0_SB_DQS_DN<8>")
	)
	(arc
		(start 383.69494 -291.425884)
		(mid 383.509908 -291.471798)
		(end 383.326132 -291.421058)
		(width 0.09525)
		(layer "In4.Cu")
		(net "M_J_CPU0_SB_DQS_DN<8>")
	)
	(arc
		(start 390.283446 -291.421058)
		(mid 390.099671 -291.47183)
		(end 389.914638 -291.425884)
		(width 0.09525)
		(layer "In4.Cu")
		(net "M_J_CPU0_SB_DQS_DN<8>")
	)
	(arc
		(start 381.446278 -291.421058)
		(mid 381.164846 -291.345303)
		(end 380.883414 -291.421058)
		(width 0.09525)
		(layer "In4.Cu")
		(net "M_J_CPU0_SB_DQS_DN<8>")
	)
	(arc
		(start 389.906256 -291.421058)
		(mid 389.624824 -291.345303)
		(end 389.343392 -291.421058)
		(width 0.09525)
		(layer "In4.Cu")
		(net "M_J_CPU0_SB_DQS_DN<8>")
	)
	(arc
		(start 384.266186 -291.421058)
		(mid 383.984754 -291.345303)
		(end 383.703322 -291.421058)
		(width 0.09525)
		(layer "In4.Cu")
		(net "M_J_CPU0_SB_DQS_DN<8>")
	)
	(arc
		(start 391.223246 -291.421058)
		(mid 391.034778 -291.471735)
		(end 390.84631 -291.421058)
		(width 0.09525)
		(layer "In4.Cu")
		(net "M_J_CPU0_SB_DQS_DN<8>")
	)
	(arc
		(start 386.146294 -291.421058)
		(mid 385.864862 -291.345303)
		(end 385.58343 -291.421058)
		(width 0.09525)
		(layer "In4.Cu")
		(net "M_J_CPU0_SB_DQS_DN<8>")
	)
	(arc
		(start 382.763268 -291.421058)
		(mid 382.5748 -291.471735)
		(end 382.386332 -291.421058)
		(width 0.09525)
		(layer "In4.Cu")
		(net "M_J_CPU0_SB_DQS_DN<8>")
	)
	(arc
		(start 380.506224 -291.421058)
		(mid 380.224792 -291.345303)
		(end 379.94336 -291.421058)
		(width 0.09525)
		(layer "In4.Cu")
		(net "M_J_CPU0_SB_DQS_DN<8>")
	)
	(arc
		(start 389.33501 -291.425884)
		(mid 389.149978 -291.471798)
		(end 388.966202 -291.421058)
		(width 0.09525)
		(layer "In4.Cu")
		(net "M_J_CPU0_SB_DQS_DN<8>")
	)
	(arc
		(start 387.463284 -291.421058)
		(mid 387.274816 -291.471735)
		(end 387.086348 -291.421058)
		(width 0.09525)
		(layer "In4.Cu")
		(net "M_J_CPU0_SB_DQS_DN<8>")
	)
	(arc
		(start 383.326132 -291.421058)
		(mid 383.0447 -291.345303)
		(end 382.763268 -291.421058)
		(width 0.09525)
		(layer "In4.Cu")
		(net "M_J_CPU0_SB_DQS_DN<8>")
	)
	(arc
		(start 384.634994 -291.425884)
		(mid 384.449962 -291.471798)
		(end 384.266186 -291.421058)
		(width 0.09525)
		(layer "In4.Cu")
		(net "M_J_CPU0_SB_DQS_DN<8>")
	)
	(arc
		(start 390.84631 -291.421058)
		(mid 390.564878 -291.345303)
		(end 390.283446 -291.421058)
		(width 0.09525)
		(layer "In4.Cu")
		(net "M_J_CPU0_SB_DQS_DN<8>")
	)
	(arc
		(start 382.386332 -291.421058)
		(mid 382.1049 -291.345303)
		(end 381.823468 -291.421058)
		(width 0.09525)
		(layer "In4.Cu")
		(net "M_J_CPU0_SB_DQS_DN<8>")
	)
	(arc
		(start 394.104622 -293.832788)
		(mid 393.988824 -293.698394)
		(end 393.947142 -293.525956)
		(width 0.09525)
		(layer "In4.Cu")
		(net "M_J_CPU0_SB_DQS_DN<8>")
	)
	(arc
		(start 386.523484 -291.421058)
		(mid 386.339709 -291.47183)
		(end 386.154676 -291.425884)
		(width 0.09525)
		(layer "In4.Cu")
		(net "M_J_CPU0_SB_DQS_DN<8>")
	)
	(arc
		(start 393.007088 -291.905944)
		(mid 392.942691 -291.644638)
		(end 392.764264 -291.443156)
		(width 0.09525)
		(layer "In4.Cu")
		(net "M_J_CPU0_SB_DQS_DN<8>")
	)
	(segment
		(start 379.28804 -285.970218)
		(end 379.754892 -286.236156)
		(width 0.12954)
		(layer "F.Cu")
		(net "M_J_CPU0_SB_DQS_DN<7>")
	)
	(segment
		(start 430.6062 -304.517298)
		(end 430.946814 -304.857912)
		(width 0.16002)
		(layer "In4.Cu")
		(net "M_J_CPU0_SB_DQS_DN<7>")
	)
	(segment
		(start 425.600368 -304.741072)
		(end 425.717208 -304.857912)
		(width 0.16002)
		(layer "In4.Cu")
		(net "M_J_CPU0_SB_DQS_DN<7>")
	)
	(segment
		(start 379.600968 -286.501586)
		(end 379.624336 -286.588454)
		(width 0.09525)
		(layer "In4.Cu")
		(net "M_J_CPU0_SB_DQS_DN<7>")
	)
	(segment
		(start 434.124608 -304.708814)
		(end 434.726334 -304.708814)
		(width 0.16002)
		(layer "In4.Cu")
		(net "M_J_CPU0_SB_DQS_DN<7>")
	)
	(segment
		(start 394.094208 -286.48533)
		(end 394.59027 -286.981392)
		(width 0.09525)
		(layer "In4.Cu")
		(net "M_J_CPU0_SB_DQS_DN<7>")
	)
	(segment
		(start 413.162242 -305.69916)
		(end 413.516064 -305.345338)
		(width 0.16002)
		(layer "In4.Cu")
		(net "M_J_CPU0_SB_DQS_DN<7>")
	)
	(segment
		(start 432.519582 -304.857912)
		(end 432.66868 -304.708814)
		(width 0.16002)
		(layer "In4.Cu")
		(net "M_J_CPU0_SB_DQS_DN<7>")
	)
	(segment
		(start 409.471622 -304.639472)
		(end 409.998672 -304.639472)
		(width 0.16002)
		(layer "In4.Cu")
		(net "M_J_CPU0_SB_DQS_DN<7>")
	)
	(segment
		(start 433.410868 -304.708814)
		(end 433.527708 -304.591974)
		(width 0.16002)
		(layer "In4.Cu")
		(net "M_J_CPU0_SB_DQS_DN<7>")
	)
	(segment
		(start 434.726334 -304.708814)
		(end 435.000146 -304.435002)
		(width 0.16002)
		(layer "In4.Cu")
		(net "M_J_CPU0_SB_DQS_DN<7>")
	)
	(segment
		(start 381.446278 -286.561276)
		(end 381.45466 -286.566102)
		(width 0.09525)
		(layer "In4.Cu")
		(net "M_J_CPU0_SB_DQS_DN<7>")
	)
	(segment
		(start 408.52217 -305.688238)
		(end 408.913838 -305.688238)
		(width 0.16002)
		(layer "In4.Cu")
		(net "M_J_CPU0_SB_DQS_DN<7>")
	)
	(segment
		(start 421.407336 -305.365658)
		(end 422.282366 -304.490628)
		(width 0.16002)
		(layer "In4.Cu")
		(net "M_J_CPU0_SB_DQS_DN<7>")
	)
	(segment
		(start 412.312612 -305.012344)
		(end 412.312612 -305.503326)
		(width 0.16002)
		(layer "In4.Cu")
		(net "M_J_CPU0_SB_DQS_DN<7>")
	)
	(segment
		(start 410.567378 -305.69916)
		(end 410.843984 -305.69916)
		(width 0.16002)
		(layer "In4.Cu")
		(net "M_J_CPU0_SB_DQS_DN<7>")
	)
	(segment
		(start 422.282366 -304.490628)
		(end 423.062654 -304.490628)
		(width 0.16002)
		(layer "In4.Cu")
		(net "M_J_CPU0_SB_DQS_DN<7>")
	)
	(segment
		(start 379.754892 -286.236156)
		(end 379.600968 -286.501586)
		(width 0.09525)
		(layer "In4.Cu")
		(net "M_J_CPU0_SB_DQS_DN<7>")
	)
	(segment
		(start 395.84249 -287.589722)
		(end 395.859254 -287.606486)
		(width 0.09525)
		(layer "In4.Cu")
		(net "M_J_CPU0_SB_DQS_DN<7>")
	)
	(segment
		(start 429.062896 -305.365658)
		(end 429.911256 -304.517298)
		(width 0.16002)
		(layer "In4.Cu")
		(net "M_J_CPU0_SB_DQS_DN<7>")
	)
	(segment
		(start 411.039818 -305.503326)
		(end 411.039818 -305.012344)
		(width 0.16002)
		(layer "In4.Cu")
		(net "M_J_CPU0_SB_DQS_DN<7>")
	)
	(segment
		(start 423.429938 -304.857912)
		(end 425.003468 -304.857912)
		(width 0.16002)
		(layer "In4.Cu")
		(net "M_J_CPU0_SB_DQS_DN<7>")
	)
	(segment
		(start 389.33501 -286.566102)
		(end 389.343392 -286.561276)
		(width 0.09525)
		(layer "In4.Cu")
		(net "M_J_CPU0_SB_DQS_DN<7>")
	)
	(segment
		(start 420.834312 -305.365658)
		(end 421.407336 -305.365658)
		(width 0.16002)
		(layer "In4.Cu")
		(net "M_J_CPU0_SB_DQS_DN<7>")
	)
	(segment
		(start 395.598396 -287.319466)
		(end 395.598396 -287.429448)
		(width 0.09525)
		(layer "In4.Cu")
		(net "M_J_CPU0_SB_DQS_DN<7>")
	)
	(segment
		(start 389.906256 -286.561276)
		(end 389.914638 -286.566102)
		(width 0.09525)
		(layer "In4.Cu")
		(net "M_J_CPU0_SB_DQS_DN<7>")
	)
	(segment
		(start 429.911256 -304.517298)
		(end 430.6062 -304.517298)
		(width 0.16002)
		(layer "In4.Cu")
		(net "M_J_CPU0_SB_DQS_DN<7>")
	)
	(segment
		(start 395.598396 -287.429448)
		(end 395.75867 -287.589722)
		(width 0.09525)
		(layer "In4.Cu")
		(net "M_J_CPU0_SB_DQS_DN<7>")
	)
	(segment
		(start 385.20624 -286.561276)
		(end 385.214622 -286.566102)
		(width 0.09525)
		(layer "In4.Cu")
		(net "M_J_CPU0_SB_DQS_DN<7>")
	)
	(segment
		(start 380.875032 -286.566102)
		(end 380.883414 -286.561276)
		(width 0.09525)
		(layer "In4.Cu")
		(net "M_J_CPU0_SB_DQS_DN<7>")
	)
	(segment
		(start 433.527708 -304.591974)
		(end 434.007768 -304.591974)
		(width 0.16002)
		(layer "In4.Cu")
		(net "M_J_CPU0_SB_DQS_DN<7>")
	)
	(segment
		(start 420.49192 -305.70805)
		(end 420.834312 -305.365658)
		(width 0.16002)
		(layer "In4.Cu")
		(net "M_J_CPU0_SB_DQS_DN<7>")
	)
	(segment
		(start 432.66868 -304.708814)
		(end 433.410868 -304.708814)
		(width 0.16002)
		(layer "In4.Cu")
		(net "M_J_CPU0_SB_DQS_DN<7>")
	)
	(segment
		(start 425.003468 -304.857912)
		(end 425.120308 -304.741072)
		(width 0.16002)
		(layer "In4.Cu")
		(net "M_J_CPU0_SB_DQS_DN<7>")
	)
	(segment
		(start 410.371544 -305.012344)
		(end 410.371544 -305.503326)
		(width 0.16002)
		(layer "In4.Cu")
		(net "M_J_CPU0_SB_DQS_DN<7>")
	)
	(segment
		(start 411.41269 -304.639472)
		(end 411.93974 -304.639472)
		(width 0.16002)
		(layer "In4.Cu")
		(net "M_J_CPU0_SB_DQS_DN<7>")
	)
	(segment
		(start 428.042324 -305.70805)
		(end 428.384716 -305.365658)
		(width 0.16002)
		(layer "In4.Cu")
		(net "M_J_CPU0_SB_DQS_DN<7>")
	)
	(segment
		(start 412.508446 -305.69916)
		(end 413.162242 -305.69916)
		(width 0.16002)
		(layer "In4.Cu")
		(net "M_J_CPU0_SB_DQS_DN<7>")
	)
	(segment
		(start 412.312612 -305.503326)
		(end 412.508446 -305.69916)
		(width 0.16002)
		(layer "In4.Cu")
		(net "M_J_CPU0_SB_DQS_DN<7>")
	)
	(segment
		(start 417.78428 -304.491898)
		(end 419.000432 -305.70805)
		(width 0.16002)
		(layer "In4.Cu")
		(net "M_J_CPU0_SB_DQS_DN<7>")
	)
	(segment
		(start 425.717208 -304.857912)
		(end 426.224446 -304.857912)
		(width 0.16002)
		(layer "In4.Cu")
		(net "M_J_CPU0_SB_DQS_DN<7>")
	)
	(segment
		(start 434.007768 -304.591974)
		(end 434.124608 -304.708814)
		(width 0.16002)
		(layer "In4.Cu")
		(net "M_J_CPU0_SB_DQS_DN<7>")
	)
	(segment
		(start 426.224446 -304.857912)
		(end 427.074584 -305.70805)
		(width 0.16002)
		(layer "In4.Cu")
		(net "M_J_CPU0_SB_DQS_DN<7>")
	)
	(segment
		(start 427.074584 -305.70805)
		(end 428.042324 -305.70805)
		(width 0.16002)
		(layer "In4.Cu")
		(net "M_J_CPU0_SB_DQS_DN<7>")
	)
	(segment
		(start 400.877278 -292.62451)
		(end 400.877278 -298.043346)
		(width 0.16002)
		(layer "In4.Cu")
		(net "M_J_CPU0_SB_DQS_DN<7>")
	)
	(segment
		(start 379.934978 -286.566102)
		(end 379.94336 -286.561276)
		(width 0.09525)
		(layer "In4.Cu")
		(net "M_J_CPU0_SB_DQS_DN<7>")
	)
	(segment
		(start 395.75867 -287.589722)
		(end 395.84249 -287.589722)
		(width 0.09525)
		(layer "In4.Cu")
		(net "M_J_CPU0_SB_DQS_DN<7>")
	)
	(segment
		(start 386.146294 -286.561276)
		(end 386.154676 -286.566102)
		(width 0.09525)
		(layer "In4.Cu")
		(net "M_J_CPU0_SB_DQS_DN<7>")
	)
	(segment
		(start 384.634994 -286.566102)
		(end 384.643376 -286.561276)
		(width 0.09525)
		(layer "In4.Cu")
		(net "M_J_CPU0_SB_DQS_DN<7>")
	)
	(segment
		(start 410.843984 -305.69916)
		(end 411.039818 -305.503326)
		(width 0.16002)
		(layer "In4.Cu")
		(net "M_J_CPU0_SB_DQS_DN<7>")
	)
	(segment
		(start 408.913838 -305.688238)
		(end 409.09875 -305.503326)
		(width 0.16002)
		(layer "In4.Cu")
		(net "M_J_CPU0_SB_DQS_DN<7>")
	)
	(segment
		(start 391.78611 -286.561276)
		(end 391.794492 -286.566102)
		(width 0.09525)
		(layer "In4.Cu")
		(net "M_J_CPU0_SB_DQS_DN<7>")
	)
	(segment
		(start 383.69494 -286.566102)
		(end 383.703322 -286.561276)
		(width 0.09525)
		(layer "In4.Cu")
		(net "M_J_CPU0_SB_DQS_DN<7>")
	)
	(segment
		(start 409.998672 -304.639472)
		(end 410.371544 -305.012344)
		(width 0.16002)
		(layer "In4.Cu")
		(net "M_J_CPU0_SB_DQS_DN<7>")
	)
	(segment
		(start 428.384716 -305.365658)
		(end 429.062896 -305.365658)
		(width 0.16002)
		(layer "In4.Cu")
		(net "M_J_CPU0_SB_DQS_DN<7>")
	)
	(segment
		(start 413.516064 -305.345338)
		(end 413.876236 -305.345338)
		(width 0.16002)
		(layer "In4.Cu")
		(net "M_J_CPU0_SB_DQS_DN<7>")
	)
	(segment
		(start 419.000432 -305.70805)
		(end 420.49192 -305.70805)
		(width 0.16002)
		(layer "In4.Cu")
		(net "M_J_CPU0_SB_DQS_DN<7>")
	)
	(segment
		(start 394.59027 -286.981392)
		(end 395.260322 -286.981392)
		(width 0.09525)
		(layer "In4.Cu")
		(net "M_J_CPU0_SB_DQS_DN<7>")
	)
	(segment
		(start 409.09875 -305.503326)
		(end 409.09875 -305.012344)
		(width 0.16002)
		(layer "In4.Cu")
		(net "M_J_CPU0_SB_DQS_DN<7>")
	)
	(segment
		(start 425.120308 -304.741072)
		(end 425.600368 -304.741072)
		(width 0.16002)
		(layer "In4.Cu")
		(net "M_J_CPU0_SB_DQS_DN<7>")
	)
	(segment
		(start 414.729676 -304.491898)
		(end 417.78428 -304.491898)
		(width 0.16002)
		(layer "In4.Cu")
		(net "M_J_CPU0_SB_DQS_DN<7>")
	)
	(segment
		(start 411.039818 -305.012344)
		(end 411.41269 -304.639472)
		(width 0.16002)
		(layer "In4.Cu")
		(net "M_J_CPU0_SB_DQS_DN<7>")
	)
	(segment
		(start 392.445748 -286.48533)
		(end 394.094208 -286.48533)
		(width 0.09525)
		(layer "In4.Cu")
		(net "M_J_CPU0_SB_DQS_DN<7>")
	)
	(segment
		(start 410.371544 -305.503326)
		(end 410.567378 -305.69916)
		(width 0.16002)
		(layer "In4.Cu")
		(net "M_J_CPU0_SB_DQS_DN<7>")
	)
	(segment
		(start 413.876236 -305.345338)
		(end 414.729676 -304.491898)
		(width 0.16002)
		(layer "In4.Cu")
		(net "M_J_CPU0_SB_DQS_DN<7>")
	)
	(segment
		(start 423.062654 -304.490628)
		(end 423.429938 -304.857912)
		(width 0.16002)
		(layer "In4.Cu")
		(net "M_J_CPU0_SB_DQS_DN<7>")
	)
	(segment
		(start 409.09875 -305.012344)
		(end 409.471622 -304.639472)
		(width 0.16002)
		(layer "In4.Cu")
		(net "M_J_CPU0_SB_DQS_DN<7>")
	)
	(segment
		(start 395.859254 -287.606486)
		(end 400.877278 -292.62451)
		(width 0.16002)
		(layer "In4.Cu")
		(net "M_J_CPU0_SB_DQS_DN<7>")
	)
	(segment
		(start 411.93974 -304.639472)
		(end 412.312612 -305.012344)
		(width 0.16002)
		(layer "In4.Cu")
		(net "M_J_CPU0_SB_DQS_DN<7>")
	)
	(segment
		(start 388.394956 -286.566102)
		(end 388.403338 -286.561276)
		(width 0.09525)
		(layer "In4.Cu")
		(net "M_J_CPU0_SB_DQS_DN<7>")
	)
	(segment
		(start 395.260322 -286.981392)
		(end 395.598396 -287.319466)
		(width 0.09525)
		(layer "In4.Cu")
		(net "M_J_CPU0_SB_DQS_DN<7>")
	)
	(segment
		(start 400.877278 -298.043346)
		(end 408.52217 -305.688238)
		(width 0.16002)
		(layer "In4.Cu")
		(net "M_J_CPU0_SB_DQS_DN<7>")
	)
	(segment
		(start 430.946814 -304.857912)
		(end 432.519582 -304.857912)
		(width 0.16002)
		(layer "In4.Cu")
		(net "M_J_CPU0_SB_DQS_DN<7>")
	)
	(arc
		(start 391.223246 -286.561276)
		(mid 391.504678 -286.485487)
		(end 391.78611 -286.561276)
		(width 0.09525)
		(layer "In4.Cu")
		(net "M_J_CPU0_SB_DQS_DN<7>")
	)
	(arc
		(start 389.914638 -286.566102)
		(mid 390.09967 -286.612016)
		(end 390.283446 -286.561276)
		(width 0.09525)
		(layer "In4.Cu")
		(net "M_J_CPU0_SB_DQS_DN<7>")
	)
	(arc
		(start 388.966202 -286.561276)
		(mid 389.149977 -286.612048)
		(end 389.33501 -286.566102)
		(width 0.09525)
		(layer "In4.Cu")
		(net "M_J_CPU0_SB_DQS_DN<7>")
	)
	(arc
		(start 389.343392 -286.561276)
		(mid 389.624824 -286.485487)
		(end 389.906256 -286.561276)
		(width 0.09525)
		(layer "In4.Cu")
		(net "M_J_CPU0_SB_DQS_DN<7>")
	)
	(arc
		(start 382.763268 -286.561276)
		(mid 383.0447 -286.485487)
		(end 383.326132 -286.561276)
		(width 0.09525)
		(layer "In4.Cu")
		(net "M_J_CPU0_SB_DQS_DN<7>")
	)
	(arc
		(start 386.523484 -286.561276)
		(mid 386.804916 -286.485487)
		(end 387.086348 -286.561276)
		(width 0.09525)
		(layer "In4.Cu")
		(net "M_J_CPU0_SB_DQS_DN<7>")
	)
	(arc
		(start 379.94336 -286.561276)
		(mid 380.224792 -286.485487)
		(end 380.506224 -286.561276)
		(width 0.09525)
		(layer "In4.Cu")
		(net "M_J_CPU0_SB_DQS_DN<7>")
	)
	(arc
		(start 379.624336 -286.588454)
		(mid 379.782086 -286.610973)
		(end 379.934978 -286.566102)
		(width 0.09525)
		(layer "In4.Cu")
		(net "M_J_CPU0_SB_DQS_DN<7>")
	)
	(arc
		(start 392.163808 -286.561276)
		(mid 392.299745 -286.504602)
		(end 392.445748 -286.48533)
		(width 0.09525)
		(layer "In4.Cu")
		(net "M_J_CPU0_SB_DQS_DN<7>")
	)
	(arc
		(start 388.026148 -286.561276)
		(mid 388.209923 -286.612048)
		(end 388.394956 -286.566102)
		(width 0.09525)
		(layer "In4.Cu")
		(net "M_J_CPU0_SB_DQS_DN<7>")
	)
	(arc
		(start 387.086348 -286.561276)
		(mid 387.274816 -286.611953)
		(end 387.463284 -286.561276)
		(width 0.09525)
		(layer "In4.Cu")
		(net "M_J_CPU0_SB_DQS_DN<7>")
	)
	(arc
		(start 380.883414 -286.561276)
		(mid 381.164846 -286.485487)
		(end 381.446278 -286.561276)
		(width 0.09525)
		(layer "In4.Cu")
		(net "M_J_CPU0_SB_DQS_DN<7>")
	)
	(arc
		(start 381.45466 -286.566102)
		(mid 381.639692 -286.612016)
		(end 381.823468 -286.561276)
		(width 0.09525)
		(layer "In4.Cu")
		(net "M_J_CPU0_SB_DQS_DN<7>")
	)
	(arc
		(start 383.703322 -286.561276)
		(mid 383.984754 -286.485487)
		(end 384.266186 -286.561276)
		(width 0.09525)
		(layer "In4.Cu")
		(net "M_J_CPU0_SB_DQS_DN<7>")
	)
	(arc
		(start 388.403338 -286.561276)
		(mid 388.68477 -286.485487)
		(end 388.966202 -286.561276)
		(width 0.09525)
		(layer "In4.Cu")
		(net "M_J_CPU0_SB_DQS_DN<7>")
	)
	(arc
		(start 385.214622 -286.566102)
		(mid 385.399654 -286.612016)
		(end 385.58343 -286.561276)
		(width 0.09525)
		(layer "In4.Cu")
		(net "M_J_CPU0_SB_DQS_DN<7>")
	)
	(arc
		(start 383.326132 -286.561276)
		(mid 383.509907 -286.612048)
		(end 383.69494 -286.566102)
		(width 0.09525)
		(layer "In4.Cu")
		(net "M_J_CPU0_SB_DQS_DN<7>")
	)
	(arc
		(start 384.643376 -286.561276)
		(mid 384.924808 -286.485487)
		(end 385.20624 -286.561276)
		(width 0.09525)
		(layer "In4.Cu")
		(net "M_J_CPU0_SB_DQS_DN<7>")
	)
	(arc
		(start 384.266186 -286.561276)
		(mid 384.449961 -286.612048)
		(end 384.634994 -286.566102)
		(width 0.09525)
		(layer "In4.Cu")
		(net "M_J_CPU0_SB_DQS_DN<7>")
	)
	(arc
		(start 390.84631 -286.561276)
		(mid 391.034778 -286.611953)
		(end 391.223246 -286.561276)
		(width 0.09525)
		(layer "In4.Cu")
		(net "M_J_CPU0_SB_DQS_DN<7>")
	)
	(arc
		(start 380.506224 -286.561276)
		(mid 380.689999 -286.612048)
		(end 380.875032 -286.566102)
		(width 0.09525)
		(layer "In4.Cu")
		(net "M_J_CPU0_SB_DQS_DN<7>")
	)
	(arc
		(start 382.386332 -286.561276)
		(mid 382.5748 -286.611953)
		(end 382.763268 -286.561276)
		(width 0.09525)
		(layer "In4.Cu")
		(net "M_J_CPU0_SB_DQS_DN<7>")
	)
	(arc
		(start 387.463284 -286.561276)
		(mid 387.744716 -286.485487)
		(end 388.026148 -286.561276)
		(width 0.09525)
		(layer "In4.Cu")
		(net "M_J_CPU0_SB_DQS_DN<7>")
	)
	(arc
		(start 386.154676 -286.566102)
		(mid 386.339708 -286.612016)
		(end 386.523484 -286.561276)
		(width 0.09525)
		(layer "In4.Cu")
		(net "M_J_CPU0_SB_DQS_DN<7>")
	)
	(arc
		(start 390.283446 -286.561276)
		(mid 390.564878 -286.485487)
		(end 390.84631 -286.561276)
		(width 0.09525)
		(layer "In4.Cu")
		(net "M_J_CPU0_SB_DQS_DN<7>")
	)
	(arc
		(start 381.823468 -286.561276)
		(mid 382.1049 -286.485487)
		(end 382.386332 -286.561276)
		(width 0.09525)
		(layer "In4.Cu")
		(net "M_J_CPU0_SB_DQS_DN<7>")
	)
	(arc
		(start 391.794492 -286.566102)
		(mid 391.979778 -286.612138)
		(end 392.163808 -286.561276)
		(width 0.09525)
		(layer "In4.Cu")
		(net "M_J_CPU0_SB_DQS_DN<7>")
	)
	(arc
		(start 385.58343 -286.561276)
		(mid 385.864862 -286.485487)
		(end 386.146294 -286.561276)
		(width 0.09525)
		(layer "In4.Cu")
		(net "M_J_CPU0_SB_DQS_DN<7>")
	)
	(segment
		(start 379.28804 -281.110182)
		(end 379.754892 -281.37612)
		(width 0.12954)
		(layer "F.Cu")
		(net "M_J_CPU0_SB_DQS_DN<6>")
	)
	(segment
		(start 409.002484 -294.471852)
		(end 409.375356 -294.844724)
		(width 0.16002)
		(layer "In4.Cu")
		(net "M_J_CPU0_SB_DQS_DN<6>")
	)
	(segment
		(start 388.394956 -281.706066)
		(end 388.403338 -281.70124)
		(width 0.09525)
		(layer "In4.Cu")
		(net "M_J_CPU0_SB_DQS_DN<6>")
	)
	(segment
		(start 409.06065 -295.963594)
		(end 409.257246 -296.16019)
		(width 0.16002)
		(layer "In4.Cu")
		(net "M_J_CPU0_SB_DQS_DN<6>")
	)
	(segment
		(start 420.834312 -296.015664)
		(end 421.407336 -296.015664)
		(width 0.16002)
		(layer "In4.Cu")
		(net "M_J_CPU0_SB_DQS_DN<6>")
	)
	(segment
		(start 395.613382 -281.81808)
		(end 397.933164 -281.81808)
		(width 0.16002)
		(layer "In4.Cu")
		(net "M_J_CPU0_SB_DQS_DN<6>")
	)
	(segment
		(start 406.414478 -290.299394)
		(end 406.414478 -291.883846)
		(width 0.16002)
		(layer "In4.Cu")
		(net "M_J_CPU0_SB_DQS_DN<6>")
	)
	(segment
		(start 407.101548 -293.09822)
		(end 407.628852 -293.09822)
		(width 0.16002)
		(layer "In4.Cu")
		(net "M_J_CPU0_SB_DQS_DN<6>")
	)
	(segment
		(start 429.062896 -296.015664)
		(end 429.911256 -295.167304)
		(width 0.16002)
		(layer "In4.Cu")
		(net "M_J_CPU0_SB_DQS_DN<6>")
	)
	(segment
		(start 421.407336 -296.015664)
		(end 422.282366 -295.140634)
		(width 0.16002)
		(layer "In4.Cu")
		(net "M_J_CPU0_SB_DQS_DN<6>")
	)
	(segment
		(start 379.754892 -281.37612)
		(end 379.600968 -281.64155)
		(width 0.09525)
		(layer "In4.Cu")
		(net "M_J_CPU0_SB_DQS_DN<6>")
	)
	(segment
		(start 419.000432 -296.358056)
		(end 420.49192 -296.358056)
		(width 0.16002)
		(layer "In4.Cu")
		(net "M_J_CPU0_SB_DQS_DN<6>")
	)
	(segment
		(start 417.78428 -295.141904)
		(end 419.000432 -296.358056)
		(width 0.16002)
		(layer "In4.Cu")
		(net "M_J_CPU0_SB_DQS_DN<6>")
	)
	(segment
		(start 408.001724 -293.998396)
		(end 407.687018 -294.313102)
		(width 0.16002)
		(layer "In4.Cu")
		(net "M_J_CPU0_SB_DQS_DN<6>")
	)
	(segment
		(start 423.062654 -295.140634)
		(end 423.429938 -295.507918)
		(width 0.16002)
		(layer "In4.Cu")
		(net "M_J_CPU0_SB_DQS_DN<6>")
	)
	(segment
		(start 423.429938 -295.507918)
		(end 426.224446 -295.507918)
		(width 0.16002)
		(layer "In4.Cu")
		(net "M_J_CPU0_SB_DQS_DN<6>")
	)
	(segment
		(start 386.146294 -281.70124)
		(end 386.154676 -281.706066)
		(width 0.09525)
		(layer "In4.Cu")
		(net "M_J_CPU0_SB_DQS_DN<6>")
	)
	(segment
		(start 428.042324 -296.358056)
		(end 428.384716 -296.015664)
		(width 0.16002)
		(layer "In4.Cu")
		(net "M_J_CPU0_SB_DQS_DN<6>")
	)
	(segment
		(start 428.384716 -296.015664)
		(end 429.062896 -296.015664)
		(width 0.16002)
		(layer "In4.Cu")
		(net "M_J_CPU0_SB_DQS_DN<6>")
	)
	(segment
		(start 429.911256 -295.167304)
		(end 430.6062 -295.167304)
		(width 0.16002)
		(layer "In4.Cu")
		(net "M_J_CPU0_SB_DQS_DN<6>")
	)
	(segment
		(start 414.729676 -295.141904)
		(end 417.78428 -295.141904)
		(width 0.16002)
		(layer "In4.Cu")
		(net "M_J_CPU0_SB_DQS_DN<6>")
	)
	(segment
		(start 385.20624 -281.70124)
		(end 385.214622 -281.706066)
		(width 0.09525)
		(layer "In4.Cu")
		(net "M_J_CPU0_SB_DQS_DN<6>")
	)
	(segment
		(start 420.49192 -296.358056)
		(end 420.834312 -296.015664)
		(width 0.16002)
		(layer "In4.Cu")
		(net "M_J_CPU0_SB_DQS_DN<6>")
	)
	(segment
		(start 413.876236 -295.995344)
		(end 414.729676 -295.141904)
		(width 0.16002)
		(layer "In4.Cu")
		(net "M_J_CPU0_SB_DQS_DN<6>")
	)
	(segment
		(start 379.934978 -281.706066)
		(end 379.94336 -281.70124)
		(width 0.09525)
		(layer "In4.Cu")
		(net "M_J_CPU0_SB_DQS_DN<6>")
	)
	(segment
		(start 389.906256 -281.70124)
		(end 389.914638 -281.706066)
		(width 0.09525)
		(layer "In4.Cu")
		(net "M_J_CPU0_SB_DQS_DN<6>")
	)
	(segment
		(start 383.69494 -281.706066)
		(end 383.703322 -281.70124)
		(width 0.09525)
		(layer "In4.Cu")
		(net "M_J_CPU0_SB_DQS_DN<6>")
	)
	(segment
		(start 389.33501 -281.706066)
		(end 389.343392 -281.70124)
		(width 0.09525)
		(layer "In4.Cu")
		(net "M_J_CPU0_SB_DQS_DN<6>")
	)
	(segment
		(start 409.534106 -296.16019)
		(end 409.848812 -295.845484)
		(width 0.16002)
		(layer "In4.Cu")
		(net "M_J_CPU0_SB_DQS_DN<6>")
	)
	(segment
		(start 433.509928 -295.35882)
		(end 433.626768 -295.24198)
		(width 0.16002)
		(layer "In4.Cu")
		(net "M_J_CPU0_SB_DQS_DN<6>")
	)
	(segment
		(start 392.716512 -281.695144)
		(end 392.726926 -281.70124)
		(width 0.09525)
		(layer "In4.Cu")
		(net "M_J_CPU0_SB_DQS_DN<6>")
	)
	(segment
		(start 434.223668 -295.35882)
		(end 434.726334 -295.35882)
		(width 0.16002)
		(layer "In4.Cu")
		(net "M_J_CPU0_SB_DQS_DN<6>")
	)
	(segment
		(start 410.525976 -295.995344)
		(end 413.876236 -295.995344)
		(width 0.16002)
		(layer "In4.Cu")
		(net "M_J_CPU0_SB_DQS_DN<6>")
	)
	(segment
		(start 409.848812 -295.845484)
		(end 410.376116 -295.845484)
		(width 0.16002)
		(layer "In4.Cu")
		(net "M_J_CPU0_SB_DQS_DN<6>")
	)
	(segment
		(start 407.883614 -294.786558)
		(end 408.160474 -294.786558)
		(width 0.16002)
		(layer "In4.Cu")
		(net "M_J_CPU0_SB_DQS_DN<6>")
	)
	(segment
		(start 430.946814 -295.507918)
		(end 432.519582 -295.507918)
		(width 0.16002)
		(layer "In4.Cu")
		(net "M_J_CPU0_SB_DQS_DN<6>")
	)
	(segment
		(start 407.628852 -293.09822)
		(end 408.001724 -293.471092)
		(width 0.16002)
		(layer "In4.Cu")
		(net "M_J_CPU0_SB_DQS_DN<6>")
	)
	(segment
		(start 397.933164 -281.81808)
		(end 406.414478 -290.299394)
		(width 0.16002)
		(layer "In4.Cu")
		(net "M_J_CPU0_SB_DQS_DN<6>")
	)
	(segment
		(start 394.661644 -281.705812)
		(end 394.833094 -281.877262)
		(width 0.09525)
		(layer "In4.Cu")
		(net "M_J_CPU0_SB_DQS_DN<6>")
	)
	(segment
		(start 408.47518 -294.471852)
		(end 409.002484 -294.471852)
		(width 0.16002)
		(layer "In4.Cu")
		(net "M_J_CPU0_SB_DQS_DN<6>")
	)
	(segment
		(start 408.160474 -294.786558)
		(end 408.47518 -294.471852)
		(width 0.16002)
		(layer "In4.Cu")
		(net "M_J_CPU0_SB_DQS_DN<6>")
	)
	(segment
		(start 395.58976 -281.81808)
		(end 395.613382 -281.81808)
		(width 0.09525)
		(layer "In4.Cu")
		(net "M_J_CPU0_SB_DQS_DN<6>")
	)
	(segment
		(start 380.875032 -281.706066)
		(end 380.883414 -281.70124)
		(width 0.09525)
		(layer "In4.Cu")
		(net "M_J_CPU0_SB_DQS_DN<6>")
	)
	(segment
		(start 406.628092 -292.09746)
		(end 406.628092 -292.624764)
		(width 0.16002)
		(layer "In4.Cu")
		(net "M_J_CPU0_SB_DQS_DN<6>")
	)
	(segment
		(start 407.687018 -294.589962)
		(end 407.883614 -294.786558)
		(width 0.16002)
		(layer "In4.Cu")
		(net "M_J_CPU0_SB_DQS_DN<6>")
	)
	(segment
		(start 433.626768 -295.24198)
		(end 434.106828 -295.24198)
		(width 0.16002)
		(layer "In4.Cu")
		(net "M_J_CPU0_SB_DQS_DN<6>")
	)
	(segment
		(start 409.375356 -295.372028)
		(end 409.06065 -295.686734)
		(width 0.16002)
		(layer "In4.Cu")
		(net "M_J_CPU0_SB_DQS_DN<6>")
	)
	(segment
		(start 409.257246 -296.16019)
		(end 409.534106 -296.16019)
		(width 0.16002)
		(layer "In4.Cu")
		(net "M_J_CPU0_SB_DQS_DN<6>")
	)
	(segment
		(start 381.446278 -281.70124)
		(end 381.45466 -281.706066)
		(width 0.09525)
		(layer "In4.Cu")
		(net "M_J_CPU0_SB_DQS_DN<6>")
	)
	(segment
		(start 406.414478 -292.838378)
		(end 406.414478 -293.115238)
		(width 0.16002)
		(layer "In4.Cu")
		(net "M_J_CPU0_SB_DQS_DN<6>")
	)
	(segment
		(start 422.282366 -295.140634)
		(end 423.062654 -295.140634)
		(width 0.16002)
		(layer "In4.Cu")
		(net "M_J_CPU0_SB_DQS_DN<6>")
	)
	(segment
		(start 430.6062 -295.167304)
		(end 430.946814 -295.507918)
		(width 0.16002)
		(layer "In4.Cu")
		(net "M_J_CPU0_SB_DQS_DN<6>")
	)
	(segment
		(start 395.530578 -281.877262)
		(end 395.58976 -281.81808)
		(width 0.09525)
		(layer "In4.Cu")
		(net "M_J_CPU0_SB_DQS_DN<6>")
	)
	(segment
		(start 432.519582 -295.507918)
		(end 432.66868 -295.35882)
		(width 0.16002)
		(layer "In4.Cu")
		(net "M_J_CPU0_SB_DQS_DN<6>")
	)
	(segment
		(start 407.687018 -294.313102)
		(end 407.687018 -294.589962)
		(width 0.16002)
		(layer "In4.Cu")
		(net "M_J_CPU0_SB_DQS_DN<6>")
	)
	(segment
		(start 427.074584 -296.358056)
		(end 428.042324 -296.358056)
		(width 0.16002)
		(layer "In4.Cu")
		(net "M_J_CPU0_SB_DQS_DN<6>")
	)
	(segment
		(start 379.600968 -281.64155)
		(end 379.624336 -281.728418)
		(width 0.09525)
		(layer "In4.Cu")
		(net "M_J_CPU0_SB_DQS_DN<6>")
	)
	(segment
		(start 394.833094 -281.877262)
		(end 395.530578 -281.877262)
		(width 0.09525)
		(layer "In4.Cu")
		(net "M_J_CPU0_SB_DQS_DN<6>")
	)
	(segment
		(start 406.611074 -293.311834)
		(end 406.887934 -293.311834)
		(width 0.16002)
		(layer "In4.Cu")
		(net "M_J_CPU0_SB_DQS_DN<6>")
	)
	(segment
		(start 409.375356 -294.844724)
		(end 409.375356 -295.372028)
		(width 0.16002)
		(layer "In4.Cu")
		(net "M_J_CPU0_SB_DQS_DN<6>")
	)
	(segment
		(start 410.376116 -295.845484)
		(end 410.525976 -295.995344)
		(width 0.16002)
		(layer "In4.Cu")
		(net "M_J_CPU0_SB_DQS_DN<6>")
	)
	(segment
		(start 406.628092 -292.624764)
		(end 406.414478 -292.838378)
		(width 0.16002)
		(layer "In4.Cu")
		(net "M_J_CPU0_SB_DQS_DN<6>")
	)
	(segment
		(start 408.001724 -293.471092)
		(end 408.001724 -293.998396)
		(width 0.16002)
		(layer "In4.Cu")
		(net "M_J_CPU0_SB_DQS_DN<6>")
	)
	(segment
		(start 432.66868 -295.35882)
		(end 433.509928 -295.35882)
		(width 0.16002)
		(layer "In4.Cu")
		(net "M_J_CPU0_SB_DQS_DN<6>")
	)
	(segment
		(start 406.414478 -293.115238)
		(end 406.611074 -293.311834)
		(width 0.16002)
		(layer "In4.Cu")
		(net "M_J_CPU0_SB_DQS_DN<6>")
	)
	(segment
		(start 393.384786 -281.625548)
		(end 394.42644 -281.625548)
		(width 0.09525)
		(layer "In4.Cu")
		(net "M_J_CPU0_SB_DQS_DN<6>")
	)
	(segment
		(start 434.106828 -295.24198)
		(end 434.223668 -295.35882)
		(width 0.16002)
		(layer "In4.Cu")
		(net "M_J_CPU0_SB_DQS_DN<6>")
	)
	(segment
		(start 406.414478 -291.883846)
		(end 406.628092 -292.09746)
		(width 0.16002)
		(layer "In4.Cu")
		(net "M_J_CPU0_SB_DQS_DN<6>")
	)
	(segment
		(start 426.224446 -295.507918)
		(end 427.074584 -296.358056)
		(width 0.16002)
		(layer "In4.Cu")
		(net "M_J_CPU0_SB_DQS_DN<6>")
	)
	(segment
		(start 391.78611 -281.70124)
		(end 391.794492 -281.706066)
		(width 0.09525)
		(layer "In4.Cu")
		(net "M_J_CPU0_SB_DQS_DN<6>")
	)
	(segment
		(start 406.887934 -293.311834)
		(end 407.101548 -293.09822)
		(width 0.16002)
		(layer "In4.Cu")
		(net "M_J_CPU0_SB_DQS_DN<6>")
	)
	(segment
		(start 384.634994 -281.706066)
		(end 384.643376 -281.70124)
		(width 0.09525)
		(layer "In4.Cu")
		(net "M_J_CPU0_SB_DQS_DN<6>")
	)
	(segment
		(start 409.06065 -295.686734)
		(end 409.06065 -295.963594)
		(width 0.16002)
		(layer "In4.Cu")
		(net "M_J_CPU0_SB_DQS_DN<6>")
	)
	(segment
		(start 434.726334 -295.35882)
		(end 435.000146 -295.085008)
		(width 0.16002)
		(layer "In4.Cu")
		(net "M_J_CPU0_SB_DQS_DN<6>")
	)
	(arc
		(start 379.624336 -281.728418)
		(mid 379.782086 -281.750937)
		(end 379.934978 -281.706066)
		(width 0.09525)
		(layer "In4.Cu")
		(net "M_J_CPU0_SB_DQS_DN<6>")
	)
	(arc
		(start 382.386332 -281.70124)
		(mid 382.5748 -281.751917)
		(end 382.763268 -281.70124)
		(width 0.09525)
		(layer "In4.Cu")
		(net "M_J_CPU0_SB_DQS_DN<6>")
	)
	(arc
		(start 388.026148 -281.70124)
		(mid 388.209923 -281.752012)
		(end 388.394956 -281.706066)
		(width 0.09525)
		(layer "In4.Cu")
		(net "M_J_CPU0_SB_DQS_DN<6>")
	)
	(arc
		(start 385.214622 -281.706066)
		(mid 385.399654 -281.75198)
		(end 385.58343 -281.70124)
		(width 0.09525)
		(layer "In4.Cu")
		(net "M_J_CPU0_SB_DQS_DN<6>")
	)
	(arc
		(start 391.794492 -281.706066)
		(mid 391.979778 -281.752102)
		(end 392.163808 -281.70124)
		(width 0.09525)
		(layer "In4.Cu")
		(net "M_J_CPU0_SB_DQS_DN<6>")
	)
	(arc
		(start 392.726926 -281.70124)
		(mid 392.908542 -281.751977)
		(end 393.091924 -281.708098)
		(width 0.09525)
		(layer "In4.Cu")
		(net "M_J_CPU0_SB_DQS_DN<6>")
	)
	(arc
		(start 385.58343 -281.70124)
		(mid 385.864862 -281.625485)
		(end 386.146294 -281.70124)
		(width 0.09525)
		(layer "In4.Cu")
		(net "M_J_CPU0_SB_DQS_DN<6>")
	)
	(arc
		(start 388.403338 -281.70124)
		(mid 388.68477 -281.625485)
		(end 388.966202 -281.70124)
		(width 0.09525)
		(layer "In4.Cu")
		(net "M_J_CPU0_SB_DQS_DN<6>")
	)
	(arc
		(start 384.266186 -281.70124)
		(mid 384.449961 -281.752012)
		(end 384.634994 -281.706066)
		(width 0.09525)
		(layer "In4.Cu")
		(net "M_J_CPU0_SB_DQS_DN<6>")
	)
	(arc
		(start 393.091924 -281.708098)
		(mid 393.23265 -281.646587)
		(end 393.384786 -281.625548)
		(width 0.09525)
		(layer "In4.Cu")
		(net "M_J_CPU0_SB_DQS_DN<6>")
	)
	(arc
		(start 380.506224 -281.70124)
		(mid 380.689999 -281.752012)
		(end 380.875032 -281.706066)
		(width 0.09525)
		(layer "In4.Cu")
		(net "M_J_CPU0_SB_DQS_DN<6>")
	)
	(arc
		(start 379.94336 -281.70124)
		(mid 380.224792 -281.625485)
		(end 380.506224 -281.70124)
		(width 0.09525)
		(layer "In4.Cu")
		(net "M_J_CPU0_SB_DQS_DN<6>")
	)
	(arc
		(start 386.154676 -281.706066)
		(mid 386.339708 -281.75198)
		(end 386.523484 -281.70124)
		(width 0.09525)
		(layer "In4.Cu")
		(net "M_J_CPU0_SB_DQS_DN<6>")
	)
	(arc
		(start 390.84631 -281.70124)
		(mid 391.034778 -281.751917)
		(end 391.223246 -281.70124)
		(width 0.09525)
		(layer "In4.Cu")
		(net "M_J_CPU0_SB_DQS_DN<6>")
	)
	(arc
		(start 387.086348 -281.70124)
		(mid 387.274816 -281.751917)
		(end 387.463284 -281.70124)
		(width 0.09525)
		(layer "In4.Cu")
		(net "M_J_CPU0_SB_DQS_DN<6>")
	)
	(arc
		(start 381.823468 -281.70124)
		(mid 382.1049 -281.625485)
		(end 382.386332 -281.70124)
		(width 0.09525)
		(layer "In4.Cu")
		(net "M_J_CPU0_SB_DQS_DN<6>")
	)
	(arc
		(start 394.42644 -281.625548)
		(mid 394.550703 -281.646164)
		(end 394.661644 -281.705812)
		(width 0.09525)
		(layer "In4.Cu")
		(net "M_J_CPU0_SB_DQS_DN<6>")
	)
	(arc
		(start 382.763268 -281.70124)
		(mid 383.0447 -281.625485)
		(end 383.326132 -281.70124)
		(width 0.09525)
		(layer "In4.Cu")
		(net "M_J_CPU0_SB_DQS_DN<6>")
	)
	(arc
		(start 383.703322 -281.70124)
		(mid 383.984754 -281.625485)
		(end 384.266186 -281.70124)
		(width 0.09525)
		(layer "In4.Cu")
		(net "M_J_CPU0_SB_DQS_DN<6>")
	)
	(arc
		(start 388.966202 -281.70124)
		(mid 389.149977 -281.752012)
		(end 389.33501 -281.706066)
		(width 0.09525)
		(layer "In4.Cu")
		(net "M_J_CPU0_SB_DQS_DN<6>")
	)
	(arc
		(start 389.914638 -281.706066)
		(mid 390.09967 -281.75198)
		(end 390.283446 -281.70124)
		(width 0.09525)
		(layer "In4.Cu")
		(net "M_J_CPU0_SB_DQS_DN<6>")
	)
	(arc
		(start 391.223246 -281.70124)
		(mid 391.504678 -281.625485)
		(end 391.78611 -281.70124)
		(width 0.09525)
		(layer "In4.Cu")
		(net "M_J_CPU0_SB_DQS_DN<6>")
	)
	(arc
		(start 389.343392 -281.70124)
		(mid 389.624824 -281.625485)
		(end 389.906256 -281.70124)
		(width 0.09525)
		(layer "In4.Cu")
		(net "M_J_CPU0_SB_DQS_DN<6>")
	)
	(arc
		(start 386.523484 -281.70124)
		(mid 386.804916 -281.625485)
		(end 387.086348 -281.70124)
		(width 0.09525)
		(layer "In4.Cu")
		(net "M_J_CPU0_SB_DQS_DN<6>")
	)
	(arc
		(start 392.163808 -281.70124)
		(mid 392.439351 -281.625391)
		(end 392.716512 -281.695144)
		(width 0.09525)
		(layer "In4.Cu")
		(net "M_J_CPU0_SB_DQS_DN<6>")
	)
	(arc
		(start 384.643376 -281.70124)
		(mid 384.924808 -281.625485)
		(end 385.20624 -281.70124)
		(width 0.09525)
		(layer "In4.Cu")
		(net "M_J_CPU0_SB_DQS_DN<6>")
	)
	(arc
		(start 381.45466 -281.706066)
		(mid 381.639692 -281.75198)
		(end 381.823468 -281.70124)
		(width 0.09525)
		(layer "In4.Cu")
		(net "M_J_CPU0_SB_DQS_DN<6>")
	)
	(arc
		(start 380.883414 -281.70124)
		(mid 381.164846 -281.625485)
		(end 381.446278 -281.70124)
		(width 0.09525)
		(layer "In4.Cu")
		(net "M_J_CPU0_SB_DQS_DN<6>")
	)
	(arc
		(start 387.463284 -281.70124)
		(mid 387.744716 -281.625485)
		(end 388.026148 -281.70124)
		(width 0.09525)
		(layer "In4.Cu")
		(net "M_J_CPU0_SB_DQS_DN<6>")
	)
	(arc
		(start 383.326132 -281.70124)
		(mid 383.509907 -281.752012)
		(end 383.69494 -281.706066)
		(width 0.09525)
		(layer "In4.Cu")
		(net "M_J_CPU0_SB_DQS_DN<6>")
	)
	(arc
		(start 390.283446 -281.70124)
		(mid 390.564878 -281.625485)
		(end 390.84631 -281.70124)
		(width 0.09525)
		(layer "In4.Cu")
		(net "M_J_CPU0_SB_DQS_DN<6>")
	)
	(segment
		(start 379.28804 -276.250146)
		(end 379.754892 -276.516084)
		(width 0.12954)
		(layer "F.Cu")
		(net "M_J_CPU0_SB_DQS_DN<5>")
	)
	(segment
		(start 386.146294 -276.841204)
		(end 386.154676 -276.84603)
		(width 0.09525)
		(layer "In4.Cu")
		(net "M_J_CPU0_SB_DQS_DN<5>")
	)
	(segment
		(start 404.704296 -280.08326)
		(end 405.513032 -280.08326)
		(width 0.16002)
		(layer "In4.Cu")
		(net "M_J_CPU0_SB_DQS_DN<5>")
	)
	(segment
		(start 379.754892 -276.516084)
		(end 379.600968 -276.781514)
		(width 0.09525)
		(layer "In4.Cu")
		(net "M_J_CPU0_SB_DQS_DN<5>")
	)
	(segment
		(start 433.532534 -286.008826)
		(end 433.649374 -285.891986)
		(width 0.16002)
		(layer "In4.Cu")
		(net "M_J_CPU0_SB_DQS_DN<5>")
	)
	(segment
		(start 405.513032 -280.08326)
		(end 405.890476 -280.460704)
		(width 0.16002)
		(layer "In4.Cu")
		(net "M_J_CPU0_SB_DQS_DN<5>")
	)
	(segment
		(start 400.237198 -275.792946)
		(end 403.15388 -278.709628)
		(width 0.16002)
		(layer "In4.Cu")
		(net "M_J_CPU0_SB_DQS_DN<5>")
	)
	(segment
		(start 413.876236 -286.64535)
		(end 414.729676 -285.79191)
		(width 0.16002)
		(layer "In4.Cu")
		(net "M_J_CPU0_SB_DQS_DN<5>")
	)
	(segment
		(start 417.989512 -285.79191)
		(end 419.205664 -287.008062)
		(width 0.16002)
		(layer "In4.Cu")
		(net "M_J_CPU0_SB_DQS_DN<5>")
	)
	(segment
		(start 420.834312 -286.66567)
		(end 421.407336 -286.66567)
		(width 0.16002)
		(layer "In4.Cu")
		(net "M_J_CPU0_SB_DQS_DN<5>")
	)
	(segment
		(start 411.822392 -285.533592)
		(end 412.93415 -286.64535)
		(width 0.16002)
		(layer "In4.Cu")
		(net "M_J_CPU0_SB_DQS_DN<5>")
	)
	(segment
		(start 379.600968 -276.781514)
		(end 379.624336 -276.868382)
		(width 0.09525)
		(layer "In4.Cu")
		(net "M_J_CPU0_SB_DQS_DN<5>")
	)
	(segment
		(start 381.446278 -276.841204)
		(end 381.45466 -276.84603)
		(width 0.09525)
		(layer "In4.Cu")
		(net "M_J_CPU0_SB_DQS_DN<5>")
	)
	(segment
		(start 428.042324 -287.008062)
		(end 428.384716 -286.66567)
		(width 0.16002)
		(layer "In4.Cu")
		(net "M_J_CPU0_SB_DQS_DN<5>")
	)
	(segment
		(start 406.050496 -281.606244)
		(end 406.792176 -281.606244)
		(width 0.16002)
		(layer "In4.Cu")
		(net "M_J_CPU0_SB_DQS_DN<5>")
	)
	(segment
		(start 395.79423 -275.792946)
		(end 400.237198 -275.792946)
		(width 0.16002)
		(layer "In4.Cu")
		(net "M_J_CPU0_SB_DQS_DN<5>")
	)
	(segment
		(start 388.394956 -276.84603)
		(end 388.403338 -276.841204)
		(width 0.09525)
		(layer "In4.Cu")
		(net "M_J_CPU0_SB_DQS_DN<5>")
	)
	(segment
		(start 422.282366 -285.79064)
		(end 423.062654 -285.79064)
		(width 0.16002)
		(layer "In4.Cu")
		(net "M_J_CPU0_SB_DQS_DN<5>")
	)
	(segment
		(start 384.634994 -276.84603)
		(end 384.643376 -276.841204)
		(width 0.09525)
		(layer "In4.Cu")
		(net "M_J_CPU0_SB_DQS_DN<5>")
	)
	(segment
		(start 432.519582 -286.157924)
		(end 432.66868 -286.008826)
		(width 0.16002)
		(layer "In4.Cu")
		(net "M_J_CPU0_SB_DQS_DN<5>")
	)
	(segment
		(start 404.1394 -278.709628)
		(end 404.544276 -279.114504)
		(width 0.16002)
		(layer "In4.Cu")
		(net "M_J_CPU0_SB_DQS_DN<5>")
	)
	(segment
		(start 393.641834 -276.548342)
		(end 393.71143 -276.513544)
		(width 0.09525)
		(layer "In4.Cu")
		(net "M_J_CPU0_SB_DQS_DN<5>")
	)
	(segment
		(start 434.726334 -286.008826)
		(end 435.000146 -285.735014)
		(width 0.16002)
		(layer "In4.Cu")
		(net "M_J_CPU0_SB_DQS_DN<5>")
	)
	(segment
		(start 414.729676 -285.79191)
		(end 417.989512 -285.79191)
		(width 0.16002)
		(layer "In4.Cu")
		(net "M_J_CPU0_SB_DQS_DN<5>")
	)
	(segment
		(start 423.429938 -286.157924)
		(end 426.224446 -286.157924)
		(width 0.16002)
		(layer "In4.Cu")
		(net "M_J_CPU0_SB_DQS_DN<5>")
	)
	(segment
		(start 395.484858 -275.852128)
		(end 395.711426 -275.852128)
		(width 0.09525)
		(layer "In4.Cu")
		(net "M_J_CPU0_SB_DQS_DN<5>")
	)
	(segment
		(start 410.963364 -285.533592)
		(end 411.822392 -285.533592)
		(width 0.16002)
		(layer "In4.Cu")
		(net "M_J_CPU0_SB_DQS_DN<5>")
	)
	(segment
		(start 427.074584 -287.008062)
		(end 428.042324 -287.008062)
		(width 0.16002)
		(layer "In4.Cu")
		(net "M_J_CPU0_SB_DQS_DN<5>")
	)
	(segment
		(start 407.396696 -282.952444)
		(end 408.382216 -282.952444)
		(width 0.16002)
		(layer "In4.Cu")
		(net "M_J_CPU0_SB_DQS_DN<5>")
	)
	(segment
		(start 380.875032 -276.84603)
		(end 380.883414 -276.841204)
		(width 0.09525)
		(layer "In4.Cu")
		(net "M_J_CPU0_SB_DQS_DN<5>")
	)
	(segment
		(start 404.544276 -279.92324)
		(end 404.704296 -280.08326)
		(width 0.16002)
		(layer "In4.Cu")
		(net "M_J_CPU0_SB_DQS_DN<5>")
	)
	(segment
		(start 419.205664 -287.008062)
		(end 420.49192 -287.008062)
		(width 0.16002)
		(layer "In4.Cu")
		(net "M_J_CPU0_SB_DQS_DN<5>")
	)
	(segment
		(start 433.649374 -285.891986)
		(end 434.129434 -285.891986)
		(width 0.16002)
		(layer "In4.Cu")
		(net "M_J_CPU0_SB_DQS_DN<5>")
	)
	(segment
		(start 406.792176 -281.606244)
		(end 407.16962 -281.983688)
		(width 0.16002)
		(layer "In4.Cu")
		(net "M_J_CPU0_SB_DQS_DN<5>")
	)
	(segment
		(start 394.059664 -276.262592)
		(end 394.644626 -275.67763)
		(width 0.09525)
		(layer "In4.Cu")
		(net "M_J_CPU0_SB_DQS_DN<5>")
	)
	(segment
		(start 429.911256 -285.81731)
		(end 430.6062 -285.81731)
		(width 0.16002)
		(layer "In4.Cu")
		(net "M_J_CPU0_SB_DQS_DN<5>")
	)
	(segment
		(start 405.890476 -281.446224)
		(end 406.050496 -281.606244)
		(width 0.16002)
		(layer "In4.Cu")
		(net "M_J_CPU0_SB_DQS_DN<5>")
	)
	(segment
		(start 420.49192 -287.008062)
		(end 420.834312 -286.66567)
		(width 0.16002)
		(layer "In4.Cu")
		(net "M_J_CPU0_SB_DQS_DN<5>")
	)
	(segment
		(start 393.074652 -276.848062)
		(end 393.641834 -276.548342)
		(width 0.09525)
		(layer "In4.Cu")
		(net "M_J_CPU0_SB_DQS_DN<5>")
	)
	(segment
		(start 389.906256 -276.841204)
		(end 389.914638 -276.84603)
		(width 0.09525)
		(layer "In4.Cu")
		(net "M_J_CPU0_SB_DQS_DN<5>")
	)
	(segment
		(start 395.770608 -275.792946)
		(end 395.79423 -275.792946)
		(width 0.09525)
		(layer "In4.Cu")
		(net "M_J_CPU0_SB_DQS_DN<5>")
	)
	(segment
		(start 379.934978 -276.84603)
		(end 379.94336 -276.841204)
		(width 0.09525)
		(layer "In4.Cu")
		(net "M_J_CPU0_SB_DQS_DN<5>")
	)
	(segment
		(start 404.544276 -279.114504)
		(end 404.544276 -279.92324)
		(width 0.16002)
		(layer "In4.Cu")
		(net "M_J_CPU0_SB_DQS_DN<5>")
	)
	(segment
		(start 430.946814 -286.157924)
		(end 432.519582 -286.157924)
		(width 0.16002)
		(layer "In4.Cu")
		(net "M_J_CPU0_SB_DQS_DN<5>")
	)
	(segment
		(start 421.407336 -286.66567)
		(end 422.282366 -285.79064)
		(width 0.16002)
		(layer "In4.Cu")
		(net "M_J_CPU0_SB_DQS_DN<5>")
	)
	(segment
		(start 428.384716 -286.66567)
		(end 429.062896 -286.66567)
		(width 0.16002)
		(layer "In4.Cu")
		(net "M_J_CPU0_SB_DQS_DN<5>")
	)
	(segment
		(start 389.33501 -276.84603)
		(end 389.343392 -276.841204)
		(width 0.09525)
		(layer "In4.Cu")
		(net "M_J_CPU0_SB_DQS_DN<5>")
	)
	(segment
		(start 434.246274 -286.008826)
		(end 434.726334 -286.008826)
		(width 0.16002)
		(layer "In4.Cu")
		(net "M_J_CPU0_SB_DQS_DN<5>")
	)
	(segment
		(start 434.129434 -285.891986)
		(end 434.246274 -286.008826)
		(width 0.16002)
		(layer "In4.Cu")
		(net "M_J_CPU0_SB_DQS_DN<5>")
	)
	(segment
		(start 429.062896 -286.66567)
		(end 429.911256 -285.81731)
		(width 0.16002)
		(layer "In4.Cu")
		(net "M_J_CPU0_SB_DQS_DN<5>")
	)
	(segment
		(start 412.93415 -286.64535)
		(end 413.876236 -286.64535)
		(width 0.16002)
		(layer "In4.Cu")
		(net "M_J_CPU0_SB_DQS_DN<5>")
	)
	(segment
		(start 394.644626 -275.67763)
		(end 395.31036 -275.67763)
		(width 0.09525)
		(layer "In4.Cu")
		(net "M_J_CPU0_SB_DQS_DN<5>")
	)
	(segment
		(start 385.20624 -276.841204)
		(end 385.214622 -276.84603)
		(width 0.09525)
		(layer "In4.Cu")
		(net "M_J_CPU0_SB_DQS_DN<5>")
	)
	(segment
		(start 395.711426 -275.852128)
		(end 395.770608 -275.792946)
		(width 0.09525)
		(layer "In4.Cu")
		(net "M_J_CPU0_SB_DQS_DN<5>")
	)
	(segment
		(start 407.16962 -282.725368)
		(end 407.396696 -282.952444)
		(width 0.16002)
		(layer "In4.Cu")
		(net "M_J_CPU0_SB_DQS_DN<5>")
	)
	(segment
		(start 395.31036 -275.67763)
		(end 395.484858 -275.852128)
		(width 0.09525)
		(layer "In4.Cu")
		(net "M_J_CPU0_SB_DQS_DN<5>")
	)
	(segment
		(start 408.382216 -282.952444)
		(end 410.963364 -285.533592)
		(width 0.16002)
		(layer "In4.Cu")
		(net "M_J_CPU0_SB_DQS_DN<5>")
	)
	(segment
		(start 426.224446 -286.157924)
		(end 427.074584 -287.008062)
		(width 0.16002)
		(layer "In4.Cu")
		(net "M_J_CPU0_SB_DQS_DN<5>")
	)
	(segment
		(start 405.890476 -280.460704)
		(end 405.890476 -281.446224)
		(width 0.16002)
		(layer "In4.Cu")
		(net "M_J_CPU0_SB_DQS_DN<5>")
	)
	(segment
		(start 391.78611 -276.841204)
		(end 391.794492 -276.84603)
		(width 0.09525)
		(layer "In4.Cu")
		(net "M_J_CPU0_SB_DQS_DN<5>")
	)
	(segment
		(start 407.16962 -281.983688)
		(end 407.16962 -282.725368)
		(width 0.16002)
		(layer "In4.Cu")
		(net "M_J_CPU0_SB_DQS_DN<5>")
	)
	(segment
		(start 432.66868 -286.008826)
		(end 433.532534 -286.008826)
		(width 0.16002)
		(layer "In4.Cu")
		(net "M_J_CPU0_SB_DQS_DN<5>")
	)
	(segment
		(start 392.716512 -276.835108)
		(end 392.726926 -276.841204)
		(width 0.09525)
		(layer "In4.Cu")
		(net "M_J_CPU0_SB_DQS_DN<5>")
	)
	(segment
		(start 403.15388 -278.709628)
		(end 404.1394 -278.709628)
		(width 0.16002)
		(layer "In4.Cu")
		(net "M_J_CPU0_SB_DQS_DN<5>")
	)
	(segment
		(start 383.69494 -276.84603)
		(end 383.703322 -276.841204)
		(width 0.09525)
		(layer "In4.Cu")
		(net "M_J_CPU0_SB_DQS_DN<5>")
	)
	(segment
		(start 430.6062 -285.81731)
		(end 430.946814 -286.157924)
		(width 0.16002)
		(layer "In4.Cu")
		(net "M_J_CPU0_SB_DQS_DN<5>")
	)
	(segment
		(start 423.062654 -285.79064)
		(end 423.429938 -286.157924)
		(width 0.16002)
		(layer "In4.Cu")
		(net "M_J_CPU0_SB_DQS_DN<5>")
	)
	(arc
		(start 390.84631 -276.841204)
		(mid 391.034778 -276.891881)
		(end 391.223246 -276.841204)
		(width 0.09525)
		(layer "In4.Cu")
		(net "M_J_CPU0_SB_DQS_DN<5>")
	)
	(arc
		(start 379.624336 -276.868382)
		(mid 379.782086 -276.890901)
		(end 379.934978 -276.84603)
		(width 0.09525)
		(layer "In4.Cu")
		(net "M_J_CPU0_SB_DQS_DN<5>")
	)
	(arc
		(start 384.643376 -276.841204)
		(mid 384.924808 -276.765449)
		(end 385.20624 -276.841204)
		(width 0.09525)
		(layer "In4.Cu")
		(net "M_J_CPU0_SB_DQS_DN<5>")
	)
	(arc
		(start 381.45466 -276.84603)
		(mid 381.639692 -276.891944)
		(end 381.823468 -276.841204)
		(width 0.09525)
		(layer "In4.Cu")
		(net "M_J_CPU0_SB_DQS_DN<5>")
	)
	(arc
		(start 384.266186 -276.841204)
		(mid 384.449961 -276.891976)
		(end 384.634994 -276.84603)
		(width 0.09525)
		(layer "In4.Cu")
		(net "M_J_CPU0_SB_DQS_DN<5>")
	)
	(arc
		(start 393.71143 -276.513544)
		(mid 393.895639 -276.402075)
		(end 394.059664 -276.262592)
		(width 0.09525)
		(layer "In4.Cu")
		(net "M_J_CPU0_SB_DQS_DN<5>")
	)
	(arc
		(start 380.506224 -276.841204)
		(mid 380.689999 -276.891976)
		(end 380.875032 -276.84603)
		(width 0.09525)
		(layer "In4.Cu")
		(net "M_J_CPU0_SB_DQS_DN<5>")
	)
	(arc
		(start 379.94336 -276.841204)
		(mid 380.224792 -276.765449)
		(end 380.506224 -276.841204)
		(width 0.09525)
		(layer "In4.Cu")
		(net "M_J_CPU0_SB_DQS_DN<5>")
	)
	(arc
		(start 382.763268 -276.841204)
		(mid 383.0447 -276.765449)
		(end 383.326132 -276.841204)
		(width 0.09525)
		(layer "In4.Cu")
		(net "M_J_CPU0_SB_DQS_DN<5>")
	)
	(arc
		(start 389.343392 -276.841204)
		(mid 389.624824 -276.765449)
		(end 389.906256 -276.841204)
		(width 0.09525)
		(layer "In4.Cu")
		(net "M_J_CPU0_SB_DQS_DN<5>")
	)
	(arc
		(start 391.223246 -276.841204)
		(mid 391.504678 -276.765449)
		(end 391.78611 -276.841204)
		(width 0.09525)
		(layer "In4.Cu")
		(net "M_J_CPU0_SB_DQS_DN<5>")
	)
	(arc
		(start 390.283446 -276.841204)
		(mid 390.564878 -276.765449)
		(end 390.84631 -276.841204)
		(width 0.09525)
		(layer "In4.Cu")
		(net "M_J_CPU0_SB_DQS_DN<5>")
	)
	(arc
		(start 380.883414 -276.841204)
		(mid 381.164846 -276.765449)
		(end 381.446278 -276.841204)
		(width 0.09525)
		(layer "In4.Cu")
		(net "M_J_CPU0_SB_DQS_DN<5>")
	)
	(arc
		(start 387.463284 -276.841204)
		(mid 387.744716 -276.765449)
		(end 388.026148 -276.841204)
		(width 0.09525)
		(layer "In4.Cu")
		(net "M_J_CPU0_SB_DQS_DN<5>")
	)
	(arc
		(start 386.154676 -276.84603)
		(mid 386.339708 -276.891944)
		(end 386.523484 -276.841204)
		(width 0.09525)
		(layer "In4.Cu")
		(net "M_J_CPU0_SB_DQS_DN<5>")
	)
	(arc
		(start 392.726926 -276.841204)
		(mid 392.899907 -276.889593)
		(end 393.074652 -276.848062)
		(width 0.09525)
		(layer "In4.Cu")
		(net "M_J_CPU0_SB_DQS_DN<5>")
	)
	(arc
		(start 385.214622 -276.84603)
		(mid 385.399654 -276.891944)
		(end 385.58343 -276.841204)
		(width 0.09525)
		(layer "In4.Cu")
		(net "M_J_CPU0_SB_DQS_DN<5>")
	)
	(arc
		(start 386.523484 -276.841204)
		(mid 386.804916 -276.765449)
		(end 387.086348 -276.841204)
		(width 0.09525)
		(layer "In4.Cu")
		(net "M_J_CPU0_SB_DQS_DN<5>")
	)
	(arc
		(start 383.326132 -276.841204)
		(mid 383.509907 -276.891976)
		(end 383.69494 -276.84603)
		(width 0.09525)
		(layer "In4.Cu")
		(net "M_J_CPU0_SB_DQS_DN<5>")
	)
	(arc
		(start 383.703322 -276.841204)
		(mid 383.984754 -276.765449)
		(end 384.266186 -276.841204)
		(width 0.09525)
		(layer "In4.Cu")
		(net "M_J_CPU0_SB_DQS_DN<5>")
	)
	(arc
		(start 382.386332 -276.841204)
		(mid 382.5748 -276.891881)
		(end 382.763268 -276.841204)
		(width 0.09525)
		(layer "In4.Cu")
		(net "M_J_CPU0_SB_DQS_DN<5>")
	)
	(arc
		(start 381.823468 -276.841204)
		(mid 382.1049 -276.765449)
		(end 382.386332 -276.841204)
		(width 0.09525)
		(layer "In4.Cu")
		(net "M_J_CPU0_SB_DQS_DN<5>")
	)
	(arc
		(start 387.086348 -276.841204)
		(mid 387.274816 -276.891881)
		(end 387.463284 -276.841204)
		(width 0.09525)
		(layer "In4.Cu")
		(net "M_J_CPU0_SB_DQS_DN<5>")
	)
	(arc
		(start 389.914638 -276.84603)
		(mid 390.09967 -276.891944)
		(end 390.283446 -276.841204)
		(width 0.09525)
		(layer "In4.Cu")
		(net "M_J_CPU0_SB_DQS_DN<5>")
	)
	(arc
		(start 388.403338 -276.841204)
		(mid 388.68477 -276.765449)
		(end 388.966202 -276.841204)
		(width 0.09525)
		(layer "In4.Cu")
		(net "M_J_CPU0_SB_DQS_DN<5>")
	)
	(arc
		(start 385.58343 -276.841204)
		(mid 385.864862 -276.765449)
		(end 386.146294 -276.841204)
		(width 0.09525)
		(layer "In4.Cu")
		(net "M_J_CPU0_SB_DQS_DN<5>")
	)
	(arc
		(start 388.966202 -276.841204)
		(mid 389.149977 -276.891976)
		(end 389.33501 -276.84603)
		(width 0.09525)
		(layer "In4.Cu")
		(net "M_J_CPU0_SB_DQS_DN<5>")
	)
	(arc
		(start 392.163808 -276.841204)
		(mid 392.439351 -276.765355)
		(end 392.716512 -276.835108)
		(width 0.09525)
		(layer "In4.Cu")
		(net "M_J_CPU0_SB_DQS_DN<5>")
	)
	(arc
		(start 388.026148 -276.841204)
		(mid 388.209923 -276.891976)
		(end 388.394956 -276.84603)
		(width 0.09525)
		(layer "In4.Cu")
		(net "M_J_CPU0_SB_DQS_DN<5>")
	)
	(arc
		(start 391.794492 -276.84603)
		(mid 391.979778 -276.892066)
		(end 392.163808 -276.841204)
		(width 0.09525)
		(layer "In4.Cu")
		(net "M_J_CPU0_SB_DQS_DN<5>")
	)
	(segment
		(start 379.28804 -271.39011)
		(end 379.754892 -271.656048)
		(width 0.12954)
		(layer "F.Cu")
		(net "M_J_CPU0_SB_DQS_DN<4>")
	)
	(segment
		(start 422.282366 -276.440646)
		(end 423.062654 -276.440646)
		(width 0.16002)
		(layer "In4.Cu")
		(net "M_J_CPU0_SB_DQS_DN<4>")
	)
	(segment
		(start 410.4132 -275.694648)
		(end 410.609034 -275.890482)
		(width 0.16002)
		(layer "In4.Cu")
		(net "M_J_CPU0_SB_DQS_DN<4>")
	)
	(segment
		(start 394.348716 -270.413226)
		(end 394.882624 -270.413226)
		(width 0.09525)
		(layer "In4.Cu")
		(net "M_J_CPU0_SB_DQS_DN<4>")
	)
	(segment
		(start 389.33501 -271.985994)
		(end 389.343392 -271.981168)
		(width 0.09525)
		(layer "In4.Cu")
		(net "M_J_CPU0_SB_DQS_DN<4>")
	)
	(segment
		(start 428.384716 -277.315676)
		(end 429.062896 -277.315676)
		(width 0.16002)
		(layer "In4.Cu")
		(net "M_J_CPU0_SB_DQS_DN<4>")
	)
	(segment
		(start 383.69494 -271.985994)
		(end 383.703322 -271.981168)
		(width 0.09525)
		(layer "In4.Cu")
		(net "M_J_CPU0_SB_DQS_DN<4>")
	)
	(segment
		(start 432.519582 -276.80793)
		(end 432.66868 -276.658832)
		(width 0.16002)
		(layer "In4.Cu")
		(net "M_J_CPU0_SB_DQS_DN<4>")
	)
	(segment
		(start 413.217868 -277.295356)
		(end 413.876236 -277.295356)
		(width 0.16002)
		(layer "In4.Cu")
		(net "M_J_CPU0_SB_DQS_DN<4>")
	)
	(segment
		(start 434.043328 -276.541992)
		(end 434.160168 -276.658832)
		(width 0.16002)
		(layer "In4.Cu")
		(net "M_J_CPU0_SB_DQS_DN<4>")
	)
	(segment
		(start 394.882624 -270.413226)
		(end 395.092428 -270.203422)
		(width 0.09525)
		(layer "In4.Cu")
		(net "M_J_CPU0_SB_DQS_DN<4>")
	)
	(segment
		(start 408.865832 -272.94332)
		(end 409.239466 -273.316954)
		(width 0.16002)
		(layer "In4.Cu")
		(net "M_J_CPU0_SB_DQS_DN<4>")
	)
	(segment
		(start 429.062896 -277.315676)
		(end 429.911256 -276.467316)
		(width 0.16002)
		(layer "In4.Cu")
		(net "M_J_CPU0_SB_DQS_DN<4>")
	)
	(segment
		(start 433.446428 -276.658832)
		(end 433.563268 -276.541992)
		(width 0.16002)
		(layer "In4.Cu")
		(net "M_J_CPU0_SB_DQS_DN<4>")
	)
	(segment
		(start 410.885894 -275.890482)
		(end 411.085792 -275.690584)
		(width 0.16002)
		(layer "In4.Cu")
		(net "M_J_CPU0_SB_DQS_DN<4>")
	)
	(segment
		(start 384.634994 -271.985994)
		(end 384.643376 -271.981168)
		(width 0.09525)
		(layer "In4.Cu")
		(net "M_J_CPU0_SB_DQS_DN<4>")
	)
	(segment
		(start 428.042324 -277.658068)
		(end 428.384716 -277.315676)
		(width 0.16002)
		(layer "In4.Cu")
		(net "M_J_CPU0_SB_DQS_DN<4>")
	)
	(segment
		(start 419.000432 -277.658068)
		(end 420.49192 -277.658068)
		(width 0.16002)
		(layer "In4.Cu")
		(net "M_J_CPU0_SB_DQS_DN<4>")
	)
	(segment
		(start 426.224446 -276.80793)
		(end 427.074584 -277.658068)
		(width 0.16002)
		(layer "In4.Cu")
		(net "M_J_CPU0_SB_DQS_DN<4>")
	)
	(segment
		(start 434.160168 -276.658832)
		(end 434.726334 -276.658832)
		(width 0.16002)
		(layer "In4.Cu")
		(net "M_J_CPU0_SB_DQS_DN<4>")
	)
	(segment
		(start 434.726334 -276.658832)
		(end 435.000146 -276.38502)
		(width 0.16002)
		(layer "In4.Cu")
		(net "M_J_CPU0_SB_DQS_DN<4>")
	)
	(segment
		(start 409.512262 -274.51685)
		(end 409.71216 -274.316952)
		(width 0.16002)
		(layer "In4.Cu")
		(net "M_J_CPU0_SB_DQS_DN<4>")
	)
	(segment
		(start 408.338528 -272.94332)
		(end 408.865832 -272.94332)
		(width 0.16002)
		(layer "In4.Cu")
		(net "M_J_CPU0_SB_DQS_DN<4>")
	)
	(segment
		(start 410.613098 -275.21789)
		(end 410.4132 -275.417788)
		(width 0.16002)
		(layer "In4.Cu")
		(net "M_J_CPU0_SB_DQS_DN<4>")
	)
	(segment
		(start 410.613098 -274.690586)
		(end 410.613098 -275.21789)
		(width 0.16002)
		(layer "In4.Cu")
		(net "M_J_CPU0_SB_DQS_DN<4>")
	)
	(segment
		(start 430.6062 -276.467316)
		(end 430.946814 -276.80793)
		(width 0.16002)
		(layer "In4.Cu")
		(net "M_J_CPU0_SB_DQS_DN<4>")
	)
	(segment
		(start 392.445494 -271.905222)
		(end 392.85672 -271.905222)
		(width 0.09525)
		(layer "In4.Cu")
		(net "M_J_CPU0_SB_DQS_DN<4>")
	)
	(segment
		(start 380.875032 -271.985994)
		(end 380.883414 -271.981168)
		(width 0.09525)
		(layer "In4.Cu")
		(net "M_J_CPU0_SB_DQS_DN<4>")
	)
	(segment
		(start 420.834312 -277.315676)
		(end 421.407336 -277.315676)
		(width 0.16002)
		(layer "In4.Cu")
		(net "M_J_CPU0_SB_DQS_DN<4>")
	)
	(segment
		(start 408.13863 -273.143218)
		(end 408.338528 -272.94332)
		(width 0.16002)
		(layer "In4.Cu")
		(net "M_J_CPU0_SB_DQS_DN<4>")
	)
	(segment
		(start 413.876236 -277.295356)
		(end 414.729676 -276.441916)
		(width 0.16002)
		(layer "In4.Cu")
		(net "M_J_CPU0_SB_DQS_DN<4>")
	)
	(segment
		(start 410.4132 -275.417788)
		(end 410.4132 -275.694648)
		(width 0.16002)
		(layer "In4.Cu")
		(net "M_J_CPU0_SB_DQS_DN<4>")
	)
	(segment
		(start 379.600968 -271.921478)
		(end 379.624336 -272.008346)
		(width 0.09525)
		(layer "In4.Cu")
		(net "M_J_CPU0_SB_DQS_DN<4>")
	)
	(segment
		(start 388.394956 -271.985994)
		(end 388.403338 -271.981168)
		(width 0.09525)
		(layer "In4.Cu")
		(net "M_J_CPU0_SB_DQS_DN<4>")
	)
	(segment
		(start 379.934978 -271.985994)
		(end 379.94336 -271.981168)
		(width 0.09525)
		(layer "In4.Cu")
		(net "M_J_CPU0_SB_DQS_DN<4>")
	)
	(segment
		(start 429.911256 -276.467316)
		(end 430.6062 -276.467316)
		(width 0.16002)
		(layer "In4.Cu")
		(net "M_J_CPU0_SB_DQS_DN<4>")
	)
	(segment
		(start 420.49192 -277.658068)
		(end 420.834312 -277.315676)
		(width 0.16002)
		(layer "In4.Cu")
		(net "M_J_CPU0_SB_DQS_DN<4>")
	)
	(segment
		(start 417.78428 -276.441916)
		(end 419.000432 -277.658068)
		(width 0.16002)
		(layer "In4.Cu")
		(net "M_J_CPU0_SB_DQS_DN<4>")
	)
	(segment
		(start 392.85672 -271.905222)
		(end 394.348716 -270.413226)
		(width 0.09525)
		(layer "In4.Cu")
		(net "M_J_CPU0_SB_DQS_DN<4>")
	)
	(segment
		(start 385.20624 -271.981168)
		(end 385.214622 -271.985994)
		(width 0.09525)
		(layer "In4.Cu")
		(net "M_J_CPU0_SB_DQS_DN<4>")
	)
	(segment
		(start 409.71216 -274.316952)
		(end 410.239464 -274.316952)
		(width 0.16002)
		(layer "In4.Cu")
		(net "M_J_CPU0_SB_DQS_DN<4>")
	)
	(segment
		(start 409.039568 -274.044156)
		(end 409.039568 -274.321016)
		(width 0.16002)
		(layer "In4.Cu")
		(net "M_J_CPU0_SB_DQS_DN<4>")
	)
	(segment
		(start 391.78611 -271.981168)
		(end 391.794492 -271.985994)
		(width 0.09525)
		(layer "In4.Cu")
		(net "M_J_CPU0_SB_DQS_DN<4>")
	)
	(segment
		(start 423.062654 -276.440646)
		(end 423.429938 -276.80793)
		(width 0.16002)
		(layer "In4.Cu")
		(net "M_J_CPU0_SB_DQS_DN<4>")
	)
	(segment
		(start 404.862792 -270.14424)
		(end 407.86177 -273.143218)
		(width 0.16002)
		(layer "In4.Cu")
		(net "M_J_CPU0_SB_DQS_DN<4>")
	)
	(segment
		(start 379.754892 -271.656048)
		(end 379.600968 -271.921478)
		(width 0.09525)
		(layer "In4.Cu")
		(net "M_J_CPU0_SB_DQS_DN<4>")
	)
	(segment
		(start 389.906256 -271.981168)
		(end 389.914638 -271.985994)
		(width 0.09525)
		(layer "In4.Cu")
		(net "M_J_CPU0_SB_DQS_DN<4>")
	)
	(segment
		(start 430.946814 -276.80793)
		(end 432.519582 -276.80793)
		(width 0.16002)
		(layer "In4.Cu")
		(net "M_J_CPU0_SB_DQS_DN<4>")
	)
	(segment
		(start 409.239466 -273.316954)
		(end 409.239466 -273.844258)
		(width 0.16002)
		(layer "In4.Cu")
		(net "M_J_CPU0_SB_DQS_DN<4>")
	)
	(segment
		(start 421.407336 -277.315676)
		(end 422.282366 -276.440646)
		(width 0.16002)
		(layer "In4.Cu")
		(net "M_J_CPU0_SB_DQS_DN<4>")
	)
	(segment
		(start 395.750542 -270.14424)
		(end 404.862792 -270.14424)
		(width 0.16002)
		(layer "In4.Cu")
		(net "M_J_CPU0_SB_DQS_DN<4>")
	)
	(segment
		(start 414.729676 -276.441916)
		(end 417.78428 -276.441916)
		(width 0.16002)
		(layer "In4.Cu")
		(net "M_J_CPU0_SB_DQS_DN<4>")
	)
	(segment
		(start 410.239464 -274.316952)
		(end 410.613098 -274.690586)
		(width 0.16002)
		(layer "In4.Cu")
		(net "M_J_CPU0_SB_DQS_DN<4>")
	)
	(segment
		(start 410.609034 -275.890482)
		(end 410.885894 -275.890482)
		(width 0.16002)
		(layer "In4.Cu")
		(net "M_J_CPU0_SB_DQS_DN<4>")
	)
	(segment
		(start 409.039568 -274.321016)
		(end 409.235402 -274.51685)
		(width 0.16002)
		(layer "In4.Cu")
		(net "M_J_CPU0_SB_DQS_DN<4>")
	)
	(segment
		(start 433.563268 -276.541992)
		(end 434.043328 -276.541992)
		(width 0.16002)
		(layer "In4.Cu")
		(net "M_J_CPU0_SB_DQS_DN<4>")
	)
	(segment
		(start 395.667738 -270.203422)
		(end 395.72692 -270.14424)
		(width 0.09525)
		(layer "In4.Cu")
		(net "M_J_CPU0_SB_DQS_DN<4>")
	)
	(segment
		(start 386.146294 -271.981168)
		(end 386.154676 -271.985994)
		(width 0.09525)
		(layer "In4.Cu")
		(net "M_J_CPU0_SB_DQS_DN<4>")
	)
	(segment
		(start 395.092428 -270.203422)
		(end 395.667738 -270.203422)
		(width 0.09525)
		(layer "In4.Cu")
		(net "M_J_CPU0_SB_DQS_DN<4>")
	)
	(segment
		(start 409.239466 -273.844258)
		(end 409.039568 -274.044156)
		(width 0.16002)
		(layer "In4.Cu")
		(net "M_J_CPU0_SB_DQS_DN<4>")
	)
	(segment
		(start 427.074584 -277.658068)
		(end 428.042324 -277.658068)
		(width 0.16002)
		(layer "In4.Cu")
		(net "M_J_CPU0_SB_DQS_DN<4>")
	)
	(segment
		(start 395.72692 -270.14424)
		(end 395.750542 -270.14424)
		(width 0.09525)
		(layer "In4.Cu")
		(net "M_J_CPU0_SB_DQS_DN<4>")
	)
	(segment
		(start 411.085792 -275.690584)
		(end 411.613096 -275.690584)
		(width 0.16002)
		(layer "In4.Cu")
		(net "M_J_CPU0_SB_DQS_DN<4>")
	)
	(segment
		(start 409.235402 -274.51685)
		(end 409.512262 -274.51685)
		(width 0.16002)
		(layer "In4.Cu")
		(net "M_J_CPU0_SB_DQS_DN<4>")
	)
	(segment
		(start 407.86177 -273.143218)
		(end 408.13863 -273.143218)
		(width 0.16002)
		(layer "In4.Cu")
		(net "M_J_CPU0_SB_DQS_DN<4>")
	)
	(segment
		(start 423.429938 -276.80793)
		(end 426.224446 -276.80793)
		(width 0.16002)
		(layer "In4.Cu")
		(net "M_J_CPU0_SB_DQS_DN<4>")
	)
	(segment
		(start 381.446278 -271.981168)
		(end 381.45466 -271.985994)
		(width 0.09525)
		(layer "In4.Cu")
		(net "M_J_CPU0_SB_DQS_DN<4>")
	)
	(segment
		(start 411.613096 -275.690584)
		(end 413.217868 -277.295356)
		(width 0.16002)
		(layer "In4.Cu")
		(net "M_J_CPU0_SB_DQS_DN<4>")
	)
	(segment
		(start 432.66868 -276.658832)
		(end 433.446428 -276.658832)
		(width 0.16002)
		(layer "In4.Cu")
		(net "M_J_CPU0_SB_DQS_DN<4>")
	)
	(arc
		(start 383.326132 -271.981168)
		(mid 383.509907 -272.03194)
		(end 383.69494 -271.985994)
		(width 0.09525)
		(layer "In4.Cu")
		(net "M_J_CPU0_SB_DQS_DN<4>")
	)
	(arc
		(start 389.914638 -271.985994)
		(mid 390.09967 -272.031908)
		(end 390.283446 -271.981168)
		(width 0.09525)
		(layer "In4.Cu")
		(net "M_J_CPU0_SB_DQS_DN<4>")
	)
	(arc
		(start 381.45466 -271.985994)
		(mid 381.639692 -272.031908)
		(end 381.823468 -271.981168)
		(width 0.09525)
		(layer "In4.Cu")
		(net "M_J_CPU0_SB_DQS_DN<4>")
	)
	(arc
		(start 392.163808 -271.981168)
		(mid 392.299627 -271.924552)
		(end 392.445494 -271.905222)
		(width 0.09525)
		(layer "In4.Cu")
		(net "M_J_CPU0_SB_DQS_DN<4>")
	)
	(arc
		(start 387.086348 -271.981168)
		(mid 387.274816 -272.031845)
		(end 387.463284 -271.981168)
		(width 0.09525)
		(layer "In4.Cu")
		(net "M_J_CPU0_SB_DQS_DN<4>")
	)
	(arc
		(start 384.643376 -271.981168)
		(mid 384.924808 -271.905413)
		(end 385.20624 -271.981168)
		(width 0.09525)
		(layer "In4.Cu")
		(net "M_J_CPU0_SB_DQS_DN<4>")
	)
	(arc
		(start 391.794492 -271.985994)
		(mid 391.979778 -272.03203)
		(end 392.163808 -271.981168)
		(width 0.09525)
		(layer "In4.Cu")
		(net "M_J_CPU0_SB_DQS_DN<4>")
	)
	(arc
		(start 381.823468 -271.981168)
		(mid 382.1049 -271.905413)
		(end 382.386332 -271.981168)
		(width 0.09525)
		(layer "In4.Cu")
		(net "M_J_CPU0_SB_DQS_DN<4>")
	)
	(arc
		(start 380.883414 -271.981168)
		(mid 381.164846 -271.905413)
		(end 381.446278 -271.981168)
		(width 0.09525)
		(layer "In4.Cu")
		(net "M_J_CPU0_SB_DQS_DN<4>")
	)
	(arc
		(start 386.523484 -271.981168)
		(mid 386.804916 -271.905413)
		(end 387.086348 -271.981168)
		(width 0.09525)
		(layer "In4.Cu")
		(net "M_J_CPU0_SB_DQS_DN<4>")
	)
	(arc
		(start 388.966202 -271.981168)
		(mid 389.149977 -272.03194)
		(end 389.33501 -271.985994)
		(width 0.09525)
		(layer "In4.Cu")
		(net "M_J_CPU0_SB_DQS_DN<4>")
	)
	(arc
		(start 391.223246 -271.981168)
		(mid 391.504678 -271.905413)
		(end 391.78611 -271.981168)
		(width 0.09525)
		(layer "In4.Cu")
		(net "M_J_CPU0_SB_DQS_DN<4>")
	)
	(arc
		(start 385.214622 -271.985994)
		(mid 385.399654 -272.031908)
		(end 385.58343 -271.981168)
		(width 0.09525)
		(layer "In4.Cu")
		(net "M_J_CPU0_SB_DQS_DN<4>")
	)
	(arc
		(start 383.703322 -271.981168)
		(mid 383.984754 -271.905413)
		(end 384.266186 -271.981168)
		(width 0.09525)
		(layer "In4.Cu")
		(net "M_J_CPU0_SB_DQS_DN<4>")
	)
	(arc
		(start 379.94336 -271.981168)
		(mid 380.224792 -271.905413)
		(end 380.506224 -271.981168)
		(width 0.09525)
		(layer "In4.Cu")
		(net "M_J_CPU0_SB_DQS_DN<4>")
	)
	(arc
		(start 382.386332 -271.981168)
		(mid 382.5748 -272.031845)
		(end 382.763268 -271.981168)
		(width 0.09525)
		(layer "In4.Cu")
		(net "M_J_CPU0_SB_DQS_DN<4>")
	)
	(arc
		(start 386.154676 -271.985994)
		(mid 386.339708 -272.031908)
		(end 386.523484 -271.981168)
		(width 0.09525)
		(layer "In4.Cu")
		(net "M_J_CPU0_SB_DQS_DN<4>")
	)
	(arc
		(start 385.58343 -271.981168)
		(mid 385.864862 -271.905413)
		(end 386.146294 -271.981168)
		(width 0.09525)
		(layer "In4.Cu")
		(net "M_J_CPU0_SB_DQS_DN<4>")
	)
	(arc
		(start 387.463284 -271.981168)
		(mid 387.744716 -271.905413)
		(end 388.026148 -271.981168)
		(width 0.09525)
		(layer "In4.Cu")
		(net "M_J_CPU0_SB_DQS_DN<4>")
	)
	(arc
		(start 388.026148 -271.981168)
		(mid 388.209923 -272.03194)
		(end 388.394956 -271.985994)
		(width 0.09525)
		(layer "In4.Cu")
		(net "M_J_CPU0_SB_DQS_DN<4>")
	)
	(arc
		(start 389.343392 -271.981168)
		(mid 389.624824 -271.905413)
		(end 389.906256 -271.981168)
		(width 0.09525)
		(layer "In4.Cu")
		(net "M_J_CPU0_SB_DQS_DN<4>")
	)
	(arc
		(start 390.84631 -271.981168)
		(mid 391.034778 -272.031845)
		(end 391.223246 -271.981168)
		(width 0.09525)
		(layer "In4.Cu")
		(net "M_J_CPU0_SB_DQS_DN<4>")
	)
	(arc
		(start 380.506224 -271.981168)
		(mid 380.689999 -272.03194)
		(end 380.875032 -271.985994)
		(width 0.09525)
		(layer "In4.Cu")
		(net "M_J_CPU0_SB_DQS_DN<4>")
	)
	(arc
		(start 390.283446 -271.981168)
		(mid 390.564878 -271.905413)
		(end 390.84631 -271.981168)
		(width 0.09525)
		(layer "In4.Cu")
		(net "M_J_CPU0_SB_DQS_DN<4>")
	)
	(arc
		(start 379.624336 -272.008346)
		(mid 379.782086 -272.030865)
		(end 379.934978 -271.985994)
		(width 0.09525)
		(layer "In4.Cu")
		(net "M_J_CPU0_SB_DQS_DN<4>")
	)
	(arc
		(start 388.403338 -271.981168)
		(mid 388.68477 -271.905413)
		(end 388.966202 -271.981168)
		(width 0.09525)
		(layer "In4.Cu")
		(net "M_J_CPU0_SB_DQS_DN<4>")
	)
	(arc
		(start 384.266186 -271.981168)
		(mid 384.449961 -272.03194)
		(end 384.634994 -271.985994)
		(width 0.09525)
		(layer "In4.Cu")
		(net "M_J_CPU0_SB_DQS_DN<4>")
	)
	(arc
		(start 382.763268 -271.981168)
		(mid 383.0447 -271.905413)
		(end 383.326132 -271.981168)
		(width 0.09525)
		(layer "In4.Cu")
		(net "M_J_CPU0_SB_DQS_DN<4>")
	)
	(segment
		(start 380.22784 -290.83)
		(end 380.694946 -291.095938)
		(width 0.12954)
		(layer "F.Cu")
		(net "M_J_CPU0_SB_DQS_DN<3>")
	)
	(segment
		(start 435.350412 -313.293252)
		(end 435.754272 -313.697112)
		(width 0.16002)
		(layer "In4.Cu")
		(net "M_J_CPU0_SB_DQS_DN<3>")
	)
	(segment
		(start 430.392078 -313.130946)
		(end 431.010822 -312.512202)
		(width 0.16002)
		(layer "In4.Cu")
		(net "M_J_CPU0_SB_DQS_DN<3>")
	)
	(segment
		(start 408.078432 -313.370976)
		(end 412.984696 -313.370976)
		(width 0.16002)
		(layer "In4.Cu")
		(net "M_J_CPU0_SB_DQS_DN<3>")
	)
	(segment
		(start 383.69494 -290.765992)
		(end 383.703322 -290.770818)
		(width 0.09525)
		(layer "In4.Cu")
		(net "M_J_CPU0_SB_DQS_DN<3>")
	)
	(segment
		(start 394.973302 -293.881302)
		(end 394.990066 -293.898066)
		(width 0.09525)
		(layer "In4.Cu")
		(net "M_J_CPU0_SB_DQS_DN<3>")
	)
	(segment
		(start 418.325046 -313.362086)
		(end 420.232078 -313.362086)
		(width 0.16002)
		(layer "In4.Cu")
		(net "M_J_CPU0_SB_DQS_DN<3>")
	)
	(segment
		(start 435.754272 -313.697112)
		(end 436.648098 -313.697112)
		(width 0.16002)
		(layer "In4.Cu")
		(net "M_J_CPU0_SB_DQS_DN<3>")
	)
	(segment
		(start 389.906256 -290.770818)
		(end 389.914638 -290.765992)
		(width 0.09525)
		(layer "In4.Cu")
		(net "M_J_CPU0_SB_DQS_DN<3>")
	)
	(segment
		(start 395.906498 -301.199042)
		(end 408.078432 -313.370976)
		(width 0.16002)
		(layer "In4.Cu")
		(net "M_J_CPU0_SB_DQS_DN<3>")
	)
	(segment
		(start 414.837372 -312.922412)
		(end 417.885372 -312.922412)
		(width 0.16002)
		(layer "In4.Cu")
		(net "M_J_CPU0_SB_DQS_DN<3>")
	)
	(segment
		(start 414.052512 -313.707272)
		(end 414.837372 -312.922412)
		(width 0.16002)
		(layer "In4.Cu")
		(net "M_J_CPU0_SB_DQS_DN<3>")
	)
	(segment
		(start 420.232078 -313.362086)
		(end 420.567104 -313.697112)
		(width 0.16002)
		(layer "In4.Cu")
		(net "M_J_CPU0_SB_DQS_DN<3>")
	)
	(segment
		(start 425.081954 -312.512202)
		(end 425.931584 -313.361832)
		(width 0.16002)
		(layer "In4.Cu")
		(net "M_J_CPU0_SB_DQS_DN<3>")
	)
	(segment
		(start 395.906498 -294.814498)
		(end 395.906498 -301.199042)
		(width 0.16002)
		(layer "In4.Cu")
		(net "M_J_CPU0_SB_DQS_DN<3>")
	)
	(segment
		(start 392.145774 -290.761166)
		(end 392.162538 -290.770818)
		(width 0.09525)
		(layer "In4.Cu")
		(net "M_J_CPU0_SB_DQS_DN<3>")
	)
	(segment
		(start 392.162538 -290.770818)
		(end 392.187938 -290.78555)
		(width 0.09525)
		(layer "In4.Cu")
		(net "M_J_CPU0_SB_DQS_DN<3>")
	)
	(segment
		(start 412.984696 -313.370976)
		(end 413.320992 -313.707272)
		(width 0.16002)
		(layer "In4.Cu")
		(net "M_J_CPU0_SB_DQS_DN<3>")
	)
	(segment
		(start 386.146294 -290.770818)
		(end 386.154676 -290.765992)
		(width 0.09525)
		(layer "In4.Cu")
		(net "M_J_CPU0_SB_DQS_DN<3>")
	)
	(segment
		(start 381.446278 -290.770818)
		(end 381.45466 -290.765992)
		(width 0.09525)
		(layer "In4.Cu")
		(net "M_J_CPU0_SB_DQS_DN<3>")
	)
	(segment
		(start 421.58666 -313.697112)
		(end 422.09339 -313.190382)
		(width 0.16002)
		(layer "In4.Cu")
		(net "M_J_CPU0_SB_DQS_DN<3>")
	)
	(segment
		(start 432.531774 -312.512202)
		(end 433.312824 -313.293252)
		(width 0.16002)
		(layer "In4.Cu")
		(net "M_J_CPU0_SB_DQS_DN<3>")
	)
	(segment
		(start 385.20624 -290.770818)
		(end 385.214622 -290.765992)
		(width 0.09525)
		(layer "In4.Cu")
		(net "M_J_CPU0_SB_DQS_DN<3>")
	)
	(segment
		(start 436.648098 -313.697112)
		(end 436.834026 -313.511184)
		(width 0.16002)
		(layer "In4.Cu")
		(net "M_J_CPU0_SB_DQS_DN<3>")
	)
	(segment
		(start 388.394956 -290.765992)
		(end 388.403338 -290.770818)
		(width 0.09525)
		(layer "In4.Cu")
		(net "M_J_CPU0_SB_DQS_DN<3>")
	)
	(segment
		(start 389.33501 -290.765992)
		(end 389.343392 -290.770818)
		(width 0.09525)
		(layer "In4.Cu")
		(net "M_J_CPU0_SB_DQS_DN<3>")
	)
	(segment
		(start 420.567104 -313.697112)
		(end 421.58666 -313.697112)
		(width 0.16002)
		(layer "In4.Cu")
		(net "M_J_CPU0_SB_DQS_DN<3>")
	)
	(segment
		(start 423.017442 -313.190382)
		(end 423.695622 -312.512202)
		(width 0.16002)
		(layer "In4.Cu")
		(net "M_J_CPU0_SB_DQS_DN<3>")
	)
	(segment
		(start 436.834026 -313.511184)
		(end 438.826402 -313.511184)
		(width 0.16002)
		(layer "In4.Cu")
		(net "M_J_CPU0_SB_DQS_DN<3>")
	)
	(segment
		(start 417.885372 -312.922412)
		(end 418.325046 -313.362086)
		(width 0.16002)
		(layer "In4.Cu")
		(net "M_J_CPU0_SB_DQS_DN<3>")
	)
	(segment
		(start 394.285978 -293.11092)
		(end 394.973556 -293.798498)
		(width 0.09525)
		(layer "In4.Cu")
		(net "M_J_CPU0_SB_DQS_DN<3>")
	)
	(segment
		(start 433.312824 -313.293252)
		(end 435.350412 -313.293252)
		(width 0.16002)
		(layer "In4.Cu")
		(net "M_J_CPU0_SB_DQS_DN<3>")
	)
	(segment
		(start 429.836326 -313.130946)
		(end 430.392078 -313.130946)
		(width 0.16002)
		(layer "In4.Cu")
		(net "M_J_CPU0_SB_DQS_DN<3>")
	)
	(segment
		(start 428.316136 -313.674252)
		(end 429.29302 -313.674252)
		(width 0.16002)
		(layer "In4.Cu")
		(net "M_J_CPU0_SB_DQS_DN<3>")
	)
	(segment
		(start 431.010822 -312.512202)
		(end 432.531774 -312.512202)
		(width 0.16002)
		(layer "In4.Cu")
		(net "M_J_CPU0_SB_DQS_DN<3>")
	)
	(segment
		(start 438.826402 -313.511184)
		(end 439.100214 -313.784996)
		(width 0.16002)
		(layer "In4.Cu")
		(net "M_J_CPU0_SB_DQS_DN<3>")
	)
	(segment
		(start 425.931584 -313.361832)
		(end 428.003716 -313.361832)
		(width 0.16002)
		(layer "In4.Cu")
		(net "M_J_CPU0_SB_DQS_DN<3>")
	)
	(segment
		(start 394.990066 -293.898066)
		(end 395.906498 -294.814498)
		(width 0.16002)
		(layer "In4.Cu")
		(net "M_J_CPU0_SB_DQS_DN<3>")
	)
	(segment
		(start 423.695622 -312.512202)
		(end 425.081954 -312.512202)
		(width 0.16002)
		(layer "In4.Cu")
		(net "M_J_CPU0_SB_DQS_DN<3>")
	)
	(segment
		(start 429.29302 -313.674252)
		(end 429.836326 -313.130946)
		(width 0.16002)
		(layer "In4.Cu")
		(net "M_J_CPU0_SB_DQS_DN<3>")
	)
	(segment
		(start 422.09339 -313.190382)
		(end 423.017442 -313.190382)
		(width 0.16002)
		(layer "In4.Cu")
		(net "M_J_CPU0_SB_DQS_DN<3>")
	)
	(segment
		(start 393.18057 -290.830254)
		(end 393.43838 -291.088064)
		(width 0.09525)
		(layer "In4.Cu")
		(net "M_J_CPU0_SB_DQS_DN<3>")
	)
	(segment
		(start 393.43838 -291.088064)
		(end 394.285978 -293.11092)
		(width 0.09525)
		(layer "In4.Cu")
		(net "M_J_CPU0_SB_DQS_DN<3>")
	)
	(segment
		(start 380.84887 -290.830508)
		(end 380.949708 -290.803838)
		(width 0.09525)
		(layer "In4.Cu")
		(net "M_J_CPU0_SB_DQS_DN<3>")
	)
	(segment
		(start 392.723878 -290.770818)
		(end 392.742674 -290.759896)
		(width 0.09525)
		(layer "In4.Cu")
		(net "M_J_CPU0_SB_DQS_DN<3>")
	)
	(segment
		(start 413.320992 -313.707272)
		(end 414.052512 -313.707272)
		(width 0.16002)
		(layer "In4.Cu")
		(net "M_J_CPU0_SB_DQS_DN<3>")
	)
	(segment
		(start 428.003716 -313.361832)
		(end 428.316136 -313.674252)
		(width 0.16002)
		(layer "In4.Cu")
		(net "M_J_CPU0_SB_DQS_DN<3>")
	)
	(segment
		(start 380.694946 -291.095938)
		(end 380.84887 -290.830508)
		(width 0.09525)
		(layer "In4.Cu")
		(net "M_J_CPU0_SB_DQS_DN<3>")
	)
	(segment
		(start 394.973556 -293.798498)
		(end 394.973302 -293.881302)
		(width 0.09525)
		(layer "In4.Cu")
		(net "M_J_CPU0_SB_DQS_DN<3>")
	)
	(segment
		(start 384.634994 -290.765992)
		(end 384.643376 -290.770818)
		(width 0.09525)
		(layer "In4.Cu")
		(net "M_J_CPU0_SB_DQS_DN<3>")
	)
	(arc
		(start 386.523484 -290.770818)
		(mid 386.804916 -290.846573)
		(end 387.086348 -290.770818)
		(width 0.09525)
		(layer "In4.Cu")
		(net "M_J_CPU0_SB_DQS_DN<3>")
	)
	(arc
		(start 389.343392 -290.770818)
		(mid 389.624824 -290.846573)
		(end 389.906256 -290.770818)
		(width 0.09525)
		(layer "In4.Cu")
		(net "M_J_CPU0_SB_DQS_DN<3>")
	)
	(arc
		(start 383.326132 -290.770818)
		(mid 383.509907 -290.720046)
		(end 383.69494 -290.765992)
		(width 0.09525)
		(layer "In4.Cu")
		(net "M_J_CPU0_SB_DQS_DN<3>")
	)
	(arc
		(start 384.643376 -290.770818)
		(mid 384.924808 -290.846573)
		(end 385.20624 -290.770818)
		(width 0.09525)
		(layer "In4.Cu")
		(net "M_J_CPU0_SB_DQS_DN<3>")
	)
	(arc
		(start 390.84631 -290.770818)
		(mid 391.034778 -290.720141)
		(end 391.223246 -290.770818)
		(width 0.09525)
		(layer "In4.Cu")
		(net "M_J_CPU0_SB_DQS_DN<3>")
	)
	(arc
		(start 385.58343 -290.770818)
		(mid 385.864862 -290.846573)
		(end 386.146294 -290.770818)
		(width 0.09525)
		(layer "In4.Cu")
		(net "M_J_CPU0_SB_DQS_DN<3>")
	)
	(arc
		(start 381.45466 -290.765992)
		(mid 381.639692 -290.720078)
		(end 381.823468 -290.770818)
		(width 0.09525)
		(layer "In4.Cu")
		(net "M_J_CPU0_SB_DQS_DN<3>")
	)
	(arc
		(start 380.96952 -290.811712)
		(mid 381.212484 -290.844699)
		(end 381.446278 -290.770818)
		(width 0.09525)
		(layer "In4.Cu")
		(net "M_J_CPU0_SB_DQS_DN<3>")
	)
	(arc
		(start 388.966202 -290.770818)
		(mid 389.149977 -290.720046)
		(end 389.33501 -290.765992)
		(width 0.09525)
		(layer "In4.Cu")
		(net "M_J_CPU0_SB_DQS_DN<3>")
	)
	(arc
		(start 388.026148 -290.770818)
		(mid 388.209923 -290.720046)
		(end 388.394956 -290.765992)
		(width 0.09525)
		(layer "In4.Cu")
		(net "M_J_CPU0_SB_DQS_DN<3>")
	)
	(arc
		(start 380.949708 -290.803838)
		(mid 380.959576 -290.807869)
		(end 380.96952 -290.811712)
		(width 0.09525)
		(layer "In4.Cu")
		(net "M_J_CPU0_SB_DQS_DN<3>")
	)
	(arc
		(start 391.78611 -290.770818)
		(mid 391.964716 -290.72015)
		(end 392.145774 -290.761166)
		(width 0.09525)
		(layer "In4.Cu")
		(net "M_J_CPU0_SB_DQS_DN<3>")
	)
	(arc
		(start 390.283446 -290.770818)
		(mid 390.564878 -290.846573)
		(end 390.84631 -290.770818)
		(width 0.09525)
		(layer "In4.Cu")
		(net "M_J_CPU0_SB_DQS_DN<3>")
	)
	(arc
		(start 392.742674 -290.759896)
		(mid 392.923769 -290.719664)
		(end 393.102084 -290.770818)
		(width 0.09525)
		(layer "In4.Cu")
		(net "M_J_CPU0_SB_DQS_DN<3>")
	)
	(arc
		(start 391.223246 -290.770818)
		(mid 391.504678 -290.846573)
		(end 391.78611 -290.770818)
		(width 0.09525)
		(layer "In4.Cu")
		(net "M_J_CPU0_SB_DQS_DN<3>")
	)
	(arc
		(start 393.102084 -290.770818)
		(mid 393.143284 -290.797952)
		(end 393.18057 -290.830254)
		(width 0.09525)
		(layer "In4.Cu")
		(net "M_J_CPU0_SB_DQS_DN<3>")
	)
	(arc
		(start 387.086348 -290.770818)
		(mid 387.274816 -290.720141)
		(end 387.463284 -290.770818)
		(width 0.09525)
		(layer "In4.Cu")
		(net "M_J_CPU0_SB_DQS_DN<3>")
	)
	(arc
		(start 385.214622 -290.765992)
		(mid 385.399654 -290.720078)
		(end 385.58343 -290.770818)
		(width 0.09525)
		(layer "In4.Cu")
		(net "M_J_CPU0_SB_DQS_DN<3>")
	)
	(arc
		(start 384.266186 -290.770818)
		(mid 384.449961 -290.720046)
		(end 384.634994 -290.765992)
		(width 0.09525)
		(layer "In4.Cu")
		(net "M_J_CPU0_SB_DQS_DN<3>")
	)
	(arc
		(start 381.823468 -290.770818)
		(mid 382.1049 -290.846573)
		(end 382.386332 -290.770818)
		(width 0.09525)
		(layer "In4.Cu")
		(net "M_J_CPU0_SB_DQS_DN<3>")
	)
	(arc
		(start 386.154676 -290.765992)
		(mid 386.339708 -290.720078)
		(end 386.523484 -290.770818)
		(width 0.09525)
		(layer "In4.Cu")
		(net "M_J_CPU0_SB_DQS_DN<3>")
	)
	(arc
		(start 392.187938 -290.78555)
		(mid 392.457792 -290.846429)
		(end 392.723878 -290.770818)
		(width 0.09525)
		(layer "In4.Cu")
		(net "M_J_CPU0_SB_DQS_DN<3>")
	)
	(arc
		(start 389.914638 -290.765992)
		(mid 390.09967 -290.720078)
		(end 390.283446 -290.770818)
		(width 0.09525)
		(layer "In4.Cu")
		(net "M_J_CPU0_SB_DQS_DN<3>")
	)
	(arc
		(start 382.763268 -290.770818)
		(mid 383.0447 -290.846573)
		(end 383.326132 -290.770818)
		(width 0.09525)
		(layer "In4.Cu")
		(net "M_J_CPU0_SB_DQS_DN<3>")
	)
	(arc
		(start 383.703322 -290.770818)
		(mid 383.984754 -290.846573)
		(end 384.266186 -290.770818)
		(width 0.09525)
		(layer "In4.Cu")
		(net "M_J_CPU0_SB_DQS_DN<3>")
	)
	(arc
		(start 388.403338 -290.770818)
		(mid 388.68477 -290.846573)
		(end 388.966202 -290.770818)
		(width 0.09525)
		(layer "In4.Cu")
		(net "M_J_CPU0_SB_DQS_DN<3>")
	)
	(arc
		(start 387.463284 -290.770818)
		(mid 387.744716 -290.846573)
		(end 388.026148 -290.770818)
		(width 0.09525)
		(layer "In4.Cu")
		(net "M_J_CPU0_SB_DQS_DN<3>")
	)
	(arc
		(start 382.386332 -290.770818)
		(mid 382.5748 -290.720141)
		(end 382.763268 -290.770818)
		(width 0.09525)
		(layer "In4.Cu")
		(net "M_J_CPU0_SB_DQS_DN<3>")
	)
	(segment
		(start 380.22784 -285.970218)
		(end 380.694946 -286.236156)
		(width 0.12954)
		(layer "F.Cu")
		(net "M_J_CPU0_SB_DQS_DN<2>")
	)
	(segment
		(start 392.145774 -285.901384)
		(end 392.162538 -285.911036)
		(width 0.09525)
		(layer "In4.Cu")
		(net "M_J_CPU0_SB_DQS_DN<2>")
	)
	(segment
		(start 389.33501 -285.90621)
		(end 389.343392 -285.911036)
		(width 0.09525)
		(layer "In4.Cu")
		(net "M_J_CPU0_SB_DQS_DN<2>")
	)
	(segment
		(start 401.443698 -292.360858)
		(end 401.443698 -297.808396)
		(width 0.16002)
		(layer "In4.Cu")
		(net "M_J_CPU0_SB_DQS_DN<2>")
	)
	(segment
		(start 420.232078 -304.012092)
		(end 420.567104 -304.347118)
		(width 0.16002)
		(layer "In4.Cu")
		(net "M_J_CPU0_SB_DQS_DN<2>")
	)
	(segment
		(start 394.14323 -285.98749)
		(end 394.71854 -286.5628)
		(width 0.09525)
		(layer "In4.Cu")
		(net "M_J_CPU0_SB_DQS_DN<2>")
	)
	(segment
		(start 423.017442 -303.840388)
		(end 423.695622 -303.162208)
		(width 0.16002)
		(layer "In4.Cu")
		(net "M_J_CPU0_SB_DQS_DN<2>")
	)
	(segment
		(start 393.384786 -285.98749)
		(end 394.14323 -285.98749)
		(width 0.09525)
		(layer "In4.Cu")
		(net "M_J_CPU0_SB_DQS_DN<2>")
	)
	(segment
		(start 407.656538 -304.021236)
		(end 412.880302 -304.021236)
		(width 0.16002)
		(layer "In4.Cu")
		(net "M_J_CPU0_SB_DQS_DN<2>")
	)
	(segment
		(start 435.350412 -303.943258)
		(end 435.754272 -304.347118)
		(width 0.16002)
		(layer "In4.Cu")
		(net "M_J_CPU0_SB_DQS_DN<2>")
	)
	(segment
		(start 422.09339 -303.840388)
		(end 423.017442 -303.840388)
		(width 0.16002)
		(layer "In4.Cu")
		(net "M_J_CPU0_SB_DQS_DN<2>")
	)
	(segment
		(start 388.394956 -285.90621)
		(end 388.403338 -285.911036)
		(width 0.09525)
		(layer "In4.Cu")
		(net "M_J_CPU0_SB_DQS_DN<2>")
	)
	(segment
		(start 431.010822 -303.162208)
		(end 432.531774 -303.162208)
		(width 0.16002)
		(layer "In4.Cu")
		(net "M_J_CPU0_SB_DQS_DN<2>")
	)
	(segment
		(start 395.741652 -286.865568)
		(end 395.80058 -286.924496)
		(width 0.09525)
		(layer "In4.Cu")
		(net "M_J_CPU0_SB_DQS_DN<2>")
	)
	(segment
		(start 428.316136 -304.324258)
		(end 429.29302 -304.324258)
		(width 0.16002)
		(layer "In4.Cu")
		(net "M_J_CPU0_SB_DQS_DN<2>")
	)
	(segment
		(start 395.824202 -286.924496)
		(end 396.007336 -286.924496)
		(width 0.16002)
		(layer "In4.Cu")
		(net "M_J_CPU0_SB_DQS_DN<2>")
	)
	(segment
		(start 394.71854 -286.5628)
		(end 395.260576 -286.5628)
		(width 0.09525)
		(layer "In4.Cu")
		(net "M_J_CPU0_SB_DQS_DN<2>")
	)
	(segment
		(start 425.931838 -304.012092)
		(end 428.00397 -304.012092)
		(width 0.16002)
		(layer "In4.Cu")
		(net "M_J_CPU0_SB_DQS_DN<2>")
	)
	(segment
		(start 392.723878 -285.911036)
		(end 392.742674 -285.900114)
		(width 0.09525)
		(layer "In4.Cu")
		(net "M_J_CPU0_SB_DQS_DN<2>")
	)
	(segment
		(start 395.80058 -286.924496)
		(end 395.824202 -286.924496)
		(width 0.09525)
		(layer "In4.Cu")
		(net "M_J_CPU0_SB_DQS_DN<2>")
	)
	(segment
		(start 384.634994 -285.90621)
		(end 384.643376 -285.911036)
		(width 0.09525)
		(layer "In4.Cu")
		(net "M_J_CPU0_SB_DQS_DN<2>")
	)
	(segment
		(start 418.325046 -304.012092)
		(end 420.232078 -304.012092)
		(width 0.16002)
		(layer "In4.Cu")
		(net "M_J_CPU0_SB_DQS_DN<2>")
	)
	(segment
		(start 401.443698 -297.808396)
		(end 407.656538 -304.021236)
		(width 0.16002)
		(layer "In4.Cu")
		(net "M_J_CPU0_SB_DQS_DN<2>")
	)
	(segment
		(start 435.754272 -304.347118)
		(end 436.920894 -304.347118)
		(width 0.16002)
		(layer "In4.Cu")
		(net "M_J_CPU0_SB_DQS_DN<2>")
	)
	(segment
		(start 433.312824 -303.943258)
		(end 435.350412 -303.943258)
		(width 0.16002)
		(layer "In4.Cu")
		(net "M_J_CPU0_SB_DQS_DN<2>")
	)
	(segment
		(start 425.081954 -303.162208)
		(end 425.931838 -304.012092)
		(width 0.16002)
		(layer "In4.Cu")
		(net "M_J_CPU0_SB_DQS_DN<2>")
	)
	(segment
		(start 429.29302 -304.324258)
		(end 429.836326 -303.780952)
		(width 0.16002)
		(layer "In4.Cu")
		(net "M_J_CPU0_SB_DQS_DN<2>")
	)
	(segment
		(start 413.216344 -304.357278)
		(end 414.052512 -304.357278)
		(width 0.16002)
		(layer "In4.Cu")
		(net "M_J_CPU0_SB_DQS_DN<2>")
	)
	(segment
		(start 395.260576 -286.5628)
		(end 395.563344 -286.865568)
		(width 0.09525)
		(layer "In4.Cu")
		(net "M_J_CPU0_SB_DQS_DN<2>")
	)
	(segment
		(start 385.20624 -285.911036)
		(end 385.214622 -285.90621)
		(width 0.09525)
		(layer "In4.Cu")
		(net "M_J_CPU0_SB_DQS_DN<2>")
	)
	(segment
		(start 436.920894 -304.347118)
		(end 437.106822 -304.16119)
		(width 0.16002)
		(layer "In4.Cu")
		(net "M_J_CPU0_SB_DQS_DN<2>")
	)
	(segment
		(start 414.837372 -303.572418)
		(end 417.885372 -303.572418)
		(width 0.16002)
		(layer "In4.Cu")
		(net "M_J_CPU0_SB_DQS_DN<2>")
	)
	(segment
		(start 438.826402 -304.16119)
		(end 439.100214 -304.435002)
		(width 0.16002)
		(layer "In4.Cu")
		(net "M_J_CPU0_SB_DQS_DN<2>")
	)
	(segment
		(start 430.392078 -303.780952)
		(end 431.010822 -303.162208)
		(width 0.16002)
		(layer "In4.Cu")
		(net "M_J_CPU0_SB_DQS_DN<2>")
	)
	(segment
		(start 412.880302 -304.021236)
		(end 413.216344 -304.357278)
		(width 0.16002)
		(layer "In4.Cu")
		(net "M_J_CPU0_SB_DQS_DN<2>")
	)
	(segment
		(start 396.007336 -286.924496)
		(end 401.443698 -292.360858)
		(width 0.16002)
		(layer "In4.Cu")
		(net "M_J_CPU0_SB_DQS_DN<2>")
	)
	(segment
		(start 414.052512 -304.357278)
		(end 414.837372 -303.572418)
		(width 0.16002)
		(layer "In4.Cu")
		(net "M_J_CPU0_SB_DQS_DN<2>")
	)
	(segment
		(start 428.00397 -304.012092)
		(end 428.316136 -304.324258)
		(width 0.16002)
		(layer "In4.Cu")
		(net "M_J_CPU0_SB_DQS_DN<2>")
	)
	(segment
		(start 417.885372 -303.572418)
		(end 418.325046 -304.012092)
		(width 0.16002)
		(layer "In4.Cu")
		(net "M_J_CPU0_SB_DQS_DN<2>")
	)
	(segment
		(start 421.58666 -304.347118)
		(end 422.09339 -303.840388)
		(width 0.16002)
		(layer "In4.Cu")
		(net "M_J_CPU0_SB_DQS_DN<2>")
	)
	(segment
		(start 380.84887 -285.970726)
		(end 380.949708 -285.944056)
		(width 0.09525)
		(layer "In4.Cu")
		(net "M_J_CPU0_SB_DQS_DN<2>")
	)
	(segment
		(start 432.531774 -303.162208)
		(end 433.312824 -303.943258)
		(width 0.16002)
		(layer "In4.Cu")
		(net "M_J_CPU0_SB_DQS_DN<2>")
	)
	(segment
		(start 380.694946 -286.236156)
		(end 380.84887 -285.970726)
		(width 0.09525)
		(layer "In4.Cu")
		(net "M_J_CPU0_SB_DQS_DN<2>")
	)
	(segment
		(start 392.162538 -285.911036)
		(end 392.187938 -285.925768)
		(width 0.09525)
		(layer "In4.Cu")
		(net "M_J_CPU0_SB_DQS_DN<2>")
	)
	(segment
		(start 381.446278 -285.911036)
		(end 381.45466 -285.90621)
		(width 0.09525)
		(layer "In4.Cu")
		(net "M_J_CPU0_SB_DQS_DN<2>")
	)
	(segment
		(start 386.146294 -285.911036)
		(end 386.154676 -285.90621)
		(width 0.09525)
		(layer "In4.Cu")
		(net "M_J_CPU0_SB_DQS_DN<2>")
	)
	(segment
		(start 423.695622 -303.162208)
		(end 425.081954 -303.162208)
		(width 0.16002)
		(layer "In4.Cu")
		(net "M_J_CPU0_SB_DQS_DN<2>")
	)
	(segment
		(start 383.69494 -285.90621)
		(end 383.703322 -285.911036)
		(width 0.09525)
		(layer "In4.Cu")
		(net "M_J_CPU0_SB_DQS_DN<2>")
	)
	(segment
		(start 389.906256 -285.911036)
		(end 389.914638 -285.90621)
		(width 0.09525)
		(layer "In4.Cu")
		(net "M_J_CPU0_SB_DQS_DN<2>")
	)
	(segment
		(start 420.567104 -304.347118)
		(end 421.58666 -304.347118)
		(width 0.16002)
		(layer "In4.Cu")
		(net "M_J_CPU0_SB_DQS_DN<2>")
	)
	(segment
		(start 395.563344 -286.865568)
		(end 395.741652 -286.865568)
		(width 0.09525)
		(layer "In4.Cu")
		(net "M_J_CPU0_SB_DQS_DN<2>")
	)
	(segment
		(start 429.836326 -303.780952)
		(end 430.392078 -303.780952)
		(width 0.16002)
		(layer "In4.Cu")
		(net "M_J_CPU0_SB_DQS_DN<2>")
	)
	(segment
		(start 437.106822 -304.16119)
		(end 438.826402 -304.16119)
		(width 0.16002)
		(layer "In4.Cu")
		(net "M_J_CPU0_SB_DQS_DN<2>")
	)
	(arc
		(start 381.823468 -285.911036)
		(mid 382.1049 -285.986791)
		(end 382.386332 -285.911036)
		(width 0.09525)
		(layer "In4.Cu")
		(net "M_J_CPU0_SB_DQS_DN<2>")
	)
	(arc
		(start 382.386332 -285.911036)
		(mid 382.5748 -285.860359)
		(end 382.763268 -285.911036)
		(width 0.09525)
		(layer "In4.Cu")
		(net "M_J_CPU0_SB_DQS_DN<2>")
	)
	(arc
		(start 388.403338 -285.911036)
		(mid 388.68477 -285.986791)
		(end 388.966202 -285.911036)
		(width 0.09525)
		(layer "In4.Cu")
		(net "M_J_CPU0_SB_DQS_DN<2>")
	)
	(arc
		(start 383.703322 -285.911036)
		(mid 383.984754 -285.986791)
		(end 384.266186 -285.911036)
		(width 0.09525)
		(layer "In4.Cu")
		(net "M_J_CPU0_SB_DQS_DN<2>")
	)
	(arc
		(start 393.102084 -285.911036)
		(mid 393.238365 -285.967995)
		(end 393.384786 -285.98749)
		(width 0.09525)
		(layer "In4.Cu")
		(net "M_J_CPU0_SB_DQS_DN<2>")
	)
	(arc
		(start 386.154676 -285.90621)
		(mid 386.339708 -285.860296)
		(end 386.523484 -285.911036)
		(width 0.09525)
		(layer "In4.Cu")
		(net "M_J_CPU0_SB_DQS_DN<2>")
	)
	(arc
		(start 388.966202 -285.911036)
		(mid 389.149977 -285.860264)
		(end 389.33501 -285.90621)
		(width 0.09525)
		(layer "In4.Cu")
		(net "M_J_CPU0_SB_DQS_DN<2>")
	)
	(arc
		(start 387.463284 -285.911036)
		(mid 387.744716 -285.986791)
		(end 388.026148 -285.911036)
		(width 0.09525)
		(layer "In4.Cu")
		(net "M_J_CPU0_SB_DQS_DN<2>")
	)
	(arc
		(start 390.84631 -285.911036)
		(mid 391.034778 -285.860359)
		(end 391.223246 -285.911036)
		(width 0.09525)
		(layer "In4.Cu")
		(net "M_J_CPU0_SB_DQS_DN<2>")
	)
	(arc
		(start 392.187938 -285.925768)
		(mid 392.457792 -285.986647)
		(end 392.723878 -285.911036)
		(width 0.09525)
		(layer "In4.Cu")
		(net "M_J_CPU0_SB_DQS_DN<2>")
	)
	(arc
		(start 383.326132 -285.911036)
		(mid 383.509907 -285.860264)
		(end 383.69494 -285.90621)
		(width 0.09525)
		(layer "In4.Cu")
		(net "M_J_CPU0_SB_DQS_DN<2>")
	)
	(arc
		(start 385.58343 -285.911036)
		(mid 385.864862 -285.986791)
		(end 386.146294 -285.911036)
		(width 0.09525)
		(layer "In4.Cu")
		(net "M_J_CPU0_SB_DQS_DN<2>")
	)
	(arc
		(start 387.086348 -285.911036)
		(mid 387.274816 -285.860359)
		(end 387.463284 -285.911036)
		(width 0.09525)
		(layer "In4.Cu")
		(net "M_J_CPU0_SB_DQS_DN<2>")
	)
	(arc
		(start 389.914638 -285.90621)
		(mid 390.09967 -285.860296)
		(end 390.283446 -285.911036)
		(width 0.09525)
		(layer "In4.Cu")
		(net "M_J_CPU0_SB_DQS_DN<2>")
	)
	(arc
		(start 382.763268 -285.911036)
		(mid 383.0447 -285.986791)
		(end 383.326132 -285.911036)
		(width 0.09525)
		(layer "In4.Cu")
		(net "M_J_CPU0_SB_DQS_DN<2>")
	)
	(arc
		(start 388.026148 -285.911036)
		(mid 388.209923 -285.860264)
		(end 388.394956 -285.90621)
		(width 0.09525)
		(layer "In4.Cu")
		(net "M_J_CPU0_SB_DQS_DN<2>")
	)
	(arc
		(start 392.742674 -285.900114)
		(mid 392.923769 -285.859882)
		(end 393.102084 -285.911036)
		(width 0.09525)
		(layer "In4.Cu")
		(net "M_J_CPU0_SB_DQS_DN<2>")
	)
	(arc
		(start 391.78611 -285.911036)
		(mid 391.964716 -285.860368)
		(end 392.145774 -285.901384)
		(width 0.09525)
		(layer "In4.Cu")
		(net "M_J_CPU0_SB_DQS_DN<2>")
	)
	(arc
		(start 380.949708 -285.944056)
		(mid 380.959576 -285.948087)
		(end 380.96952 -285.95193)
		(width 0.09525)
		(layer "In4.Cu")
		(net "M_J_CPU0_SB_DQS_DN<2>")
	)
	(arc
		(start 390.283446 -285.911036)
		(mid 390.564878 -285.986791)
		(end 390.84631 -285.911036)
		(width 0.09525)
		(layer "In4.Cu")
		(net "M_J_CPU0_SB_DQS_DN<2>")
	)
	(arc
		(start 380.96952 -285.95193)
		(mid 381.212484 -285.984917)
		(end 381.446278 -285.911036)
		(width 0.09525)
		(layer "In4.Cu")
		(net "M_J_CPU0_SB_DQS_DN<2>")
	)
	(arc
		(start 381.45466 -285.90621)
		(mid 381.639692 -285.860296)
		(end 381.823468 -285.911036)
		(width 0.09525)
		(layer "In4.Cu")
		(net "M_J_CPU0_SB_DQS_DN<2>")
	)
	(arc
		(start 389.343392 -285.911036)
		(mid 389.624824 -285.986791)
		(end 389.906256 -285.911036)
		(width 0.09525)
		(layer "In4.Cu")
		(net "M_J_CPU0_SB_DQS_DN<2>")
	)
	(arc
		(start 385.214622 -285.90621)
		(mid 385.399654 -285.860296)
		(end 385.58343 -285.911036)
		(width 0.09525)
		(layer "In4.Cu")
		(net "M_J_CPU0_SB_DQS_DN<2>")
	)
	(arc
		(start 384.643376 -285.911036)
		(mid 384.924808 -285.986791)
		(end 385.20624 -285.911036)
		(width 0.09525)
		(layer "In4.Cu")
		(net "M_J_CPU0_SB_DQS_DN<2>")
	)
	(arc
		(start 391.223246 -285.911036)
		(mid 391.504678 -285.986791)
		(end 391.78611 -285.911036)
		(width 0.09525)
		(layer "In4.Cu")
		(net "M_J_CPU0_SB_DQS_DN<2>")
	)
	(arc
		(start 384.266186 -285.911036)
		(mid 384.449961 -285.860264)
		(end 384.634994 -285.90621)
		(width 0.09525)
		(layer "In4.Cu")
		(net "M_J_CPU0_SB_DQS_DN<2>")
	)
	(arc
		(start 386.523484 -285.911036)
		(mid 386.804916 -285.986791)
		(end 387.086348 -285.911036)
		(width 0.09525)
		(layer "In4.Cu")
		(net "M_J_CPU0_SB_DQS_DN<2>")
	)
	(segment
		(start 380.22784 -281.110182)
		(end 380.694946 -281.37612)
		(width 0.12954)
		(layer "F.Cu")
		(net "M_J_CPU0_SB_DQS_DN<1>")
	)
	(segment
		(start 423.695622 -293.812214)
		(end 423.017442 -294.490394)
		(width 0.16002)
		(layer "In4.Cu")
		(net "M_J_CPU0_SB_DQS_DN<1>")
	)
	(segment
		(start 421.58666 -294.997124)
		(end 420.567104 -294.997124)
		(width 0.16002)
		(layer "In4.Cu")
		(net "M_J_CPU0_SB_DQS_DN<1>")
	)
	(segment
		(start 380.949708 -281.08402)
		(end 380.84887 -281.11069)
		(width 0.09525)
		(layer "In4.Cu")
		(net "M_J_CPU0_SB_DQS_DN<1>")
	)
	(segment
		(start 428.00397 -294.662098)
		(end 425.931838 -294.662098)
		(width 0.16002)
		(layer "In4.Cu")
		(net "M_J_CPU0_SB_DQS_DN<1>")
	)
	(segment
		(start 395.776704 -281.10053)
		(end 395.455394 -281.10053)
		(width 0.09525)
		(layer "In4.Cu")
		(net "M_J_CPU0_SB_DQS_DN<1>")
	)
	(segment
		(start 392.187938 -281.065732)
		(end 392.162538 -281.051)
		(width 0.09525)
		(layer "In4.Cu")
		(net "M_J_CPU0_SB_DQS_DN<1>")
	)
	(segment
		(start 428.316136 -294.974264)
		(end 428.00397 -294.662098)
		(width 0.16002)
		(layer "In4.Cu")
		(net "M_J_CPU0_SB_DQS_DN<1>")
	)
	(segment
		(start 389.914638 -281.046174)
		(end 389.906256 -281.051)
		(width 0.09525)
		(layer "In4.Cu")
		(net "M_J_CPU0_SB_DQS_DN<1>")
	)
	(segment
		(start 392.742674 -281.040078)
		(end 392.723878 -281.051)
		(width 0.09525)
		(layer "In4.Cu")
		(net "M_J_CPU0_SB_DQS_DN<1>")
	)
	(segment
		(start 439.100214 -295.085008)
		(end 438.826402 -294.811196)
		(width 0.16002)
		(layer "In4.Cu")
		(net "M_J_CPU0_SB_DQS_DN<1>")
	)
	(segment
		(start 395.455394 -281.10053)
		(end 395.182852 -280.721816)
		(width 0.09525)
		(layer "In4.Cu")
		(net "M_J_CPU0_SB_DQS_DN<1>")
	)
	(segment
		(start 385.214622 -281.046174)
		(end 385.20624 -281.051)
		(width 0.09525)
		(layer "In4.Cu")
		(net "M_J_CPU0_SB_DQS_DN<1>")
	)
	(segment
		(start 394.019786 -280.777442)
		(end 393.817094 -280.980134)
		(width 0.09525)
		(layer "In4.Cu")
		(net "M_J_CPU0_SB_DQS_DN<1>")
	)
	(segment
		(start 436.908194 -294.997124)
		(end 435.754272 -294.997124)
		(width 0.16002)
		(layer "In4.Cu")
		(net "M_J_CPU0_SB_DQS_DN<1>")
	)
	(segment
		(start 414.052512 -295.007284)
		(end 412.94304 -295.007284)
		(width 0.16002)
		(layer "In4.Cu")
		(net "M_J_CPU0_SB_DQS_DN<1>")
	)
	(segment
		(start 418.325046 -294.662098)
		(end 417.885372 -294.222424)
		(width 0.16002)
		(layer "In4.Cu")
		(net "M_J_CPU0_SB_DQS_DN<1>")
	)
	(segment
		(start 412.94304 -295.007284)
		(end 412.571946 -295.378378)
		(width 0.16002)
		(layer "In4.Cu")
		(net "M_J_CPU0_SB_DQS_DN<1>")
	)
	(segment
		(start 395.835632 -281.159458)
		(end 395.776704 -281.10053)
		(width 0.09525)
		(layer "In4.Cu")
		(net "M_J_CPU0_SB_DQS_DN<1>")
	)
	(segment
		(start 383.703322 -281.051)
		(end 383.69494 -281.046174)
		(width 0.09525)
		(layer "In4.Cu")
		(net "M_J_CPU0_SB_DQS_DN<1>")
	)
	(segment
		(start 425.081954 -293.812214)
		(end 423.695622 -293.812214)
		(width 0.16002)
		(layer "In4.Cu")
		(net "M_J_CPU0_SB_DQS_DN<1>")
	)
	(segment
		(start 392.162538 -281.051)
		(end 392.145774 -281.041348)
		(width 0.09525)
		(layer "In4.Cu")
		(net "M_J_CPU0_SB_DQS_DN<1>")
	)
	(segment
		(start 380.84887 -281.11069)
		(end 380.694946 -281.37612)
		(width 0.09525)
		(layer "In4.Cu")
		(net "M_J_CPU0_SB_DQS_DN<1>")
	)
	(segment
		(start 412.571946 -295.378378)
		(end 410.710126 -295.378378)
		(width 0.16002)
		(layer "In4.Cu")
		(net "M_J_CPU0_SB_DQS_DN<1>")
	)
	(segment
		(start 423.017442 -294.490394)
		(end 422.09339 -294.490394)
		(width 0.16002)
		(layer "In4.Cu")
		(net "M_J_CPU0_SB_DQS_DN<1>")
	)
	(segment
		(start 429.29302 -294.974264)
		(end 428.316136 -294.974264)
		(width 0.16002)
		(layer "In4.Cu")
		(net "M_J_CPU0_SB_DQS_DN<1>")
	)
	(segment
		(start 438.826402 -294.811196)
		(end 437.094122 -294.811196)
		(width 0.16002)
		(layer "In4.Cu")
		(net "M_J_CPU0_SB_DQS_DN<1>")
	)
	(segment
		(start 389.343392 -281.051)
		(end 389.33501 -281.046174)
		(width 0.09525)
		(layer "In4.Cu")
		(net "M_J_CPU0_SB_DQS_DN<1>")
	)
	(segment
		(start 431.010822 -293.812214)
		(end 430.392078 -294.430958)
		(width 0.16002)
		(layer "In4.Cu")
		(net "M_J_CPU0_SB_DQS_DN<1>")
	)
	(segment
		(start 406.980898 -290.064444)
		(end 398.075912 -281.159458)
		(width 0.16002)
		(layer "In4.Cu")
		(net "M_J_CPU0_SB_DQS_DN<1>")
	)
	(segment
		(start 386.154676 -281.046174)
		(end 386.146294 -281.051)
		(width 0.09525)
		(layer "In4.Cu")
		(net "M_J_CPU0_SB_DQS_DN<1>")
	)
	(segment
		(start 414.837372 -294.222424)
		(end 414.052512 -295.007284)
		(width 0.16002)
		(layer "In4.Cu")
		(net "M_J_CPU0_SB_DQS_DN<1>")
	)
	(segment
		(start 430.392078 -294.430958)
		(end 429.836326 -294.430958)
		(width 0.16002)
		(layer "In4.Cu")
		(net "M_J_CPU0_SB_DQS_DN<1>")
	)
	(segment
		(start 410.710126 -295.378378)
		(end 406.980898 -291.64915)
		(width 0.16002)
		(layer "In4.Cu")
		(net "M_J_CPU0_SB_DQS_DN<1>")
	)
	(segment
		(start 398.075912 -281.159458)
		(end 395.859254 -281.159458)
		(width 0.16002)
		(layer "In4.Cu")
		(net "M_J_CPU0_SB_DQS_DN<1>")
	)
	(segment
		(start 435.754272 -294.997124)
		(end 435.350412 -294.593264)
		(width 0.16002)
		(layer "In4.Cu")
		(net "M_J_CPU0_SB_DQS_DN<1>")
	)
	(segment
		(start 388.403338 -281.051)
		(end 388.394956 -281.046174)
		(width 0.09525)
		(layer "In4.Cu")
		(net "M_J_CPU0_SB_DQS_DN<1>")
	)
	(segment
		(start 417.885372 -294.222424)
		(end 414.837372 -294.222424)
		(width 0.16002)
		(layer "In4.Cu")
		(net "M_J_CPU0_SB_DQS_DN<1>")
	)
	(segment
		(start 435.350412 -294.593264)
		(end 433.312824 -294.593264)
		(width 0.16002)
		(layer "In4.Cu")
		(net "M_J_CPU0_SB_DQS_DN<1>")
	)
	(segment
		(start 420.232078 -294.662098)
		(end 418.325046 -294.662098)
		(width 0.16002)
		(layer "In4.Cu")
		(net "M_J_CPU0_SB_DQS_DN<1>")
	)
	(segment
		(start 433.312824 -294.593264)
		(end 432.531774 -293.812214)
		(width 0.16002)
		(layer "In4.Cu")
		(net "M_J_CPU0_SB_DQS_DN<1>")
	)
	(segment
		(start 384.643376 -281.051)
		(end 384.634994 -281.046174)
		(width 0.09525)
		(layer "In4.Cu")
		(net "M_J_CPU0_SB_DQS_DN<1>")
	)
	(segment
		(start 406.980898 -291.64915)
		(end 406.980898 -290.064444)
		(width 0.16002)
		(layer "In4.Cu")
		(net "M_J_CPU0_SB_DQS_DN<1>")
	)
	(segment
		(start 420.567104 -294.997124)
		(end 420.232078 -294.662098)
		(width 0.16002)
		(layer "In4.Cu")
		(net "M_J_CPU0_SB_DQS_DN<1>")
	)
	(segment
		(start 395.859254 -281.159458)
		(end 395.835632 -281.159458)
		(width 0.09525)
		(layer "In4.Cu")
		(net "M_J_CPU0_SB_DQS_DN<1>")
	)
	(segment
		(start 437.094122 -294.811196)
		(end 436.908194 -294.997124)
		(width 0.16002)
		(layer "In4.Cu")
		(net "M_J_CPU0_SB_DQS_DN<1>")
	)
	(segment
		(start 393.817094 -280.980134)
		(end 393.815062 -280.980134)
		(width 0.09525)
		(layer "In4.Cu")
		(net "M_J_CPU0_SB_DQS_DN<1>")
	)
	(segment
		(start 395.182852 -280.721816)
		(end 394.153644 -280.721816)
		(width 0.09525)
		(layer "In4.Cu")
		(net "M_J_CPU0_SB_DQS_DN<1>")
	)
	(segment
		(start 429.836326 -294.430958)
		(end 429.29302 -294.974264)
		(width 0.16002)
		(layer "In4.Cu")
		(net "M_J_CPU0_SB_DQS_DN<1>")
	)
	(segment
		(start 422.09339 -294.490394)
		(end 421.58666 -294.997124)
		(width 0.16002)
		(layer "In4.Cu")
		(net "M_J_CPU0_SB_DQS_DN<1>")
	)
	(segment
		(start 381.45466 -281.046174)
		(end 381.446278 -281.051)
		(width 0.09525)
		(layer "In4.Cu")
		(net "M_J_CPU0_SB_DQS_DN<1>")
	)
	(segment
		(start 432.531774 -293.812214)
		(end 431.010822 -293.812214)
		(width 0.16002)
		(layer "In4.Cu")
		(net "M_J_CPU0_SB_DQS_DN<1>")
	)
	(segment
		(start 425.931838 -294.662098)
		(end 425.081954 -293.812214)
		(width 0.16002)
		(layer "In4.Cu")
		(net "M_J_CPU0_SB_DQS_DN<1>")
	)
	(arc
		(start 394.153644 -280.721816)
		(mid 394.0812 -280.736338)
		(end 394.019786 -280.777442)
		(width 0.09525)
		(layer "In4.Cu")
		(net "M_J_CPU0_SB_DQS_DN<1>")
	)
	(arc
		(start 391.78611 -281.051)
		(mid 391.504678 -281.126755)
		(end 391.223246 -281.051)
		(width 0.09525)
		(layer "In4.Cu")
		(net "M_J_CPU0_SB_DQS_DN<1>")
	)
	(arc
		(start 388.394956 -281.046174)
		(mid 388.209924 -281.00026)
		(end 388.026148 -281.051)
		(width 0.09525)
		(layer "In4.Cu")
		(net "M_J_CPU0_SB_DQS_DN<1>")
	)
	(arc
		(start 389.906256 -281.051)
		(mid 389.624824 -281.126755)
		(end 389.343392 -281.051)
		(width 0.09525)
		(layer "In4.Cu")
		(net "M_J_CPU0_SB_DQS_DN<1>")
	)
	(arc
		(start 391.223246 -281.051)
		(mid 391.034778 -281.000323)
		(end 390.84631 -281.051)
		(width 0.09525)
		(layer "In4.Cu")
		(net "M_J_CPU0_SB_DQS_DN<1>")
	)
	(arc
		(start 387.463284 -281.051)
		(mid 387.274816 -281.000323)
		(end 387.086348 -281.051)
		(width 0.09525)
		(layer "In4.Cu")
		(net "M_J_CPU0_SB_DQS_DN<1>")
	)
	(arc
		(start 381.823468 -281.051)
		(mid 381.639693 -281.000228)
		(end 381.45466 -281.046174)
		(width 0.09525)
		(layer "In4.Cu")
		(net "M_J_CPU0_SB_DQS_DN<1>")
	)
	(arc
		(start 389.33501 -281.046174)
		(mid 389.149978 -281.00026)
		(end 388.966202 -281.051)
		(width 0.09525)
		(layer "In4.Cu")
		(net "M_J_CPU0_SB_DQS_DN<1>")
	)
	(arc
		(start 382.386332 -281.051)
		(mid 382.1049 -281.126755)
		(end 381.823468 -281.051)
		(width 0.09525)
		(layer "In4.Cu")
		(net "M_J_CPU0_SB_DQS_DN<1>")
	)
	(arc
		(start 388.026148 -281.051)
		(mid 387.744716 -281.126755)
		(end 387.463284 -281.051)
		(width 0.09525)
		(layer "In4.Cu")
		(net "M_J_CPU0_SB_DQS_DN<1>")
	)
	(arc
		(start 384.634994 -281.046174)
		(mid 384.449962 -281.00026)
		(end 384.266186 -281.051)
		(width 0.09525)
		(layer "In4.Cu")
		(net "M_J_CPU0_SB_DQS_DN<1>")
	)
	(arc
		(start 383.69494 -281.046174)
		(mid 383.509908 -281.00026)
		(end 383.326132 -281.051)
		(width 0.09525)
		(layer "In4.Cu")
		(net "M_J_CPU0_SB_DQS_DN<1>")
	)
	(arc
		(start 388.966202 -281.051)
		(mid 388.68477 -281.126755)
		(end 388.403338 -281.051)
		(width 0.09525)
		(layer "In4.Cu")
		(net "M_J_CPU0_SB_DQS_DN<1>")
	)
	(arc
		(start 385.58343 -281.051)
		(mid 385.399655 -281.000228)
		(end 385.214622 -281.046174)
		(width 0.09525)
		(layer "In4.Cu")
		(net "M_J_CPU0_SB_DQS_DN<1>")
	)
	(arc
		(start 384.266186 -281.051)
		(mid 383.984754 -281.126755)
		(end 383.703322 -281.051)
		(width 0.09525)
		(layer "In4.Cu")
		(net "M_J_CPU0_SB_DQS_DN<1>")
	)
	(arc
		(start 392.145774 -281.041348)
		(mid 391.964717 -281.000366)
		(end 391.78611 -281.051)
		(width 0.09525)
		(layer "In4.Cu")
		(net "M_J_CPU0_SB_DQS_DN<1>")
	)
	(arc
		(start 380.96952 -281.091894)
		(mid 380.959577 -281.088051)
		(end 380.949708 -281.08402)
		(width 0.09525)
		(layer "In4.Cu")
		(net "M_J_CPU0_SB_DQS_DN<1>")
	)
	(arc
		(start 392.723878 -281.051)
		(mid 392.457791 -281.126545)
		(end 392.187938 -281.065732)
		(width 0.09525)
		(layer "In4.Cu")
		(net "M_J_CPU0_SB_DQS_DN<1>")
	)
	(arc
		(start 381.446278 -281.051)
		(mid 381.212483 -281.124867)
		(end 380.96952 -281.091894)
		(width 0.09525)
		(layer "In4.Cu")
		(net "M_J_CPU0_SB_DQS_DN<1>")
	)
	(arc
		(start 390.283446 -281.051)
		(mid 390.099671 -281.000228)
		(end 389.914638 -281.046174)
		(width 0.09525)
		(layer "In4.Cu")
		(net "M_J_CPU0_SB_DQS_DN<1>")
	)
	(arc
		(start 385.20624 -281.051)
		(mid 384.924808 -281.126755)
		(end 384.643376 -281.051)
		(width 0.09525)
		(layer "In4.Cu")
		(net "M_J_CPU0_SB_DQS_DN<1>")
	)
	(arc
		(start 390.84631 -281.051)
		(mid 390.564878 -281.126755)
		(end 390.283446 -281.051)
		(width 0.09525)
		(layer "In4.Cu")
		(net "M_J_CPU0_SB_DQS_DN<1>")
	)
	(arc
		(start 386.146294 -281.051)
		(mid 385.864862 -281.126755)
		(end 385.58343 -281.051)
		(width 0.09525)
		(layer "In4.Cu")
		(net "M_J_CPU0_SB_DQS_DN<1>")
	)
	(arc
		(start 393.384786 -281.127454)
		(mid 393.238349 -281.108017)
		(end 393.102084 -281.051)
		(width 0.09525)
		(layer "In4.Cu")
		(net "M_J_CPU0_SB_DQS_DN<1>")
	)
	(arc
		(start 387.086348 -281.051)
		(mid 386.804916 -281.126755)
		(end 386.523484 -281.051)
		(width 0.09525)
		(layer "In4.Cu")
		(net "M_J_CPU0_SB_DQS_DN<1>")
	)
	(arc
		(start 382.763268 -281.051)
		(mid 382.5748 -281.000323)
		(end 382.386332 -281.051)
		(width 0.09525)
		(layer "In4.Cu")
		(net "M_J_CPU0_SB_DQS_DN<1>")
	)
	(arc
		(start 393.102084 -281.051)
		(mid 392.923769 -280.999858)
		(end 392.742674 -281.040078)
		(width 0.09525)
		(layer "In4.Cu")
		(net "M_J_CPU0_SB_DQS_DN<1>")
	)
	(arc
		(start 386.523484 -281.051)
		(mid 386.339709 -281.000228)
		(end 386.154676 -281.046174)
		(width 0.09525)
		(layer "In4.Cu")
		(net "M_J_CPU0_SB_DQS_DN<1>")
	)
	(arc
		(start 383.326132 -281.051)
		(mid 383.0447 -281.126755)
		(end 382.763268 -281.051)
		(width 0.09525)
		(layer "In4.Cu")
		(net "M_J_CPU0_SB_DQS_DN<1>")
	)
	(arc
		(start 393.815062 -280.980134)
		(mid 393.612189 -281.089601)
		(end 393.384786 -281.127454)
		(width 0.09525)
		(layer "In4.Cu")
		(net "M_J_CPU0_SB_DQS_DN<1>")
	)
	(segment
		(start 380.22784 -276.250146)
		(end 380.694946 -276.516084)
		(width 0.12954)
		(layer "F.Cu")
		(net "M_J_CPU0_SB_DQS_DN<0>")
	)
	(segment
		(start 417.69284 -284.87243)
		(end 418.75456 -285.312104)
		(width 0.16002)
		(layer "In4.Cu")
		(net "M_J_CPU0_SB_DQS_DN<0>")
	)
	(segment
		(start 435.754272 -285.64713)
		(end 437.75249 -285.64713)
		(width 0.16002)
		(layer "In4.Cu")
		(net "M_J_CPU0_SB_DQS_DN<0>")
	)
	(segment
		(start 412.762192 -284.92069)
		(end 413.498792 -285.65729)
		(width 0.16002)
		(layer "In4.Cu")
		(net "M_J_CPU0_SB_DQS_DN<0>")
	)
	(segment
		(start 388.394956 -276.186138)
		(end 388.403338 -276.190964)
		(width 0.09525)
		(layer "In4.Cu")
		(net "M_J_CPU0_SB_DQS_DN<0>")
	)
	(segment
		(start 435.350412 -285.24327)
		(end 435.754272 -285.64713)
		(width 0.16002)
		(layer "In4.Cu")
		(net "M_J_CPU0_SB_DQS_DN<0>")
	)
	(segment
		(start 418.75456 -285.312104)
		(end 420.232078 -285.312104)
		(width 0.16002)
		(layer "In4.Cu")
		(net "M_J_CPU0_SB_DQS_DN<0>")
	)
	(segment
		(start 438.826402 -285.461202)
		(end 439.100214 -285.735014)
		(width 0.16002)
		(layer "In4.Cu")
		(net "M_J_CPU0_SB_DQS_DN<0>")
	)
	(segment
		(start 392.145774 -276.181312)
		(end 392.162538 -276.190964)
		(width 0.09525)
		(layer "In4.Cu")
		(net "M_J_CPU0_SB_DQS_DN<0>")
	)
	(segment
		(start 393.780518 -276.102318)
		(end 394.701522 -275.181314)
		(width 0.09525)
		(layer "In4.Cu")
		(net "M_J_CPU0_SB_DQS_DN<0>")
	)
	(segment
		(start 383.69494 -276.186138)
		(end 383.703322 -276.190964)
		(width 0.09525)
		(layer "In4.Cu")
		(net "M_J_CPU0_SB_DQS_DN<0>")
	)
	(segment
		(start 429.836326 -285.080964)
		(end 430.392078 -285.080964)
		(width 0.16002)
		(layer "In4.Cu")
		(net "M_J_CPU0_SB_DQS_DN<0>")
	)
	(segment
		(start 380.84887 -276.250654)
		(end 380.949708 -276.223984)
		(width 0.09525)
		(layer "In4.Cu")
		(net "M_J_CPU0_SB_DQS_DN<0>")
	)
	(segment
		(start 393.63015 -276.21103)
		(end 393.664694 -276.190964)
		(width 0.09525)
		(layer "In4.Cu")
		(net "M_J_CPU0_SB_DQS_DN<0>")
	)
	(segment
		(start 392.162538 -276.190964)
		(end 392.187938 -276.205696)
		(width 0.09525)
		(layer "In4.Cu")
		(net "M_J_CPU0_SB_DQS_DN<0>")
	)
	(segment
		(start 394.701522 -275.181314)
		(end 395.3002 -275.181314)
		(width 0.09525)
		(layer "In4.Cu")
		(net "M_J_CPU0_SB_DQS_DN<0>")
	)
	(segment
		(start 395.776704 -275.140928)
		(end 395.835632 -275.199856)
		(width 0.09525)
		(layer "In4.Cu")
		(net "M_J_CPU0_SB_DQS_DN<0>")
	)
	(segment
		(start 422.09339 -285.1404)
		(end 423.017442 -285.1404)
		(width 0.16002)
		(layer "In4.Cu")
		(net "M_J_CPU0_SB_DQS_DN<0>")
	)
	(segment
		(start 429.29302 -285.62427)
		(end 429.836326 -285.080964)
		(width 0.16002)
		(layer "In4.Cu")
		(net "M_J_CPU0_SB_DQS_DN<0>")
	)
	(segment
		(start 386.146294 -276.190964)
		(end 386.154676 -276.186138)
		(width 0.09525)
		(layer "In4.Cu")
		(net "M_J_CPU0_SB_DQS_DN<0>")
	)
	(segment
		(start 428.00397 -285.312104)
		(end 428.316136 -285.62427)
		(width 0.16002)
		(layer "In4.Cu")
		(net "M_J_CPU0_SB_DQS_DN<0>")
	)
	(segment
		(start 433.312824 -285.24327)
		(end 435.350412 -285.24327)
		(width 0.16002)
		(layer "In4.Cu")
		(net "M_J_CPU0_SB_DQS_DN<0>")
	)
	(segment
		(start 437.75249 -285.64713)
		(end 437.938418 -285.461202)
		(width 0.16002)
		(layer "In4.Cu")
		(net "M_J_CPU0_SB_DQS_DN<0>")
	)
	(segment
		(start 420.567104 -285.64713)
		(end 421.58666 -285.64713)
		(width 0.16002)
		(layer "In4.Cu")
		(net "M_J_CPU0_SB_DQS_DN<0>")
	)
	(segment
		(start 431.010822 -284.46222)
		(end 432.531774 -284.46222)
		(width 0.16002)
		(layer "In4.Cu")
		(net "M_J_CPU0_SB_DQS_DN<0>")
	)
	(segment
		(start 421.58666 -285.64713)
		(end 422.09339 -285.1404)
		(width 0.16002)
		(layer "In4.Cu")
		(net "M_J_CPU0_SB_DQS_DN<0>")
	)
	(segment
		(start 420.232078 -285.312104)
		(end 420.567104 -285.64713)
		(width 0.16002)
		(layer "In4.Cu")
		(net "M_J_CPU0_SB_DQS_DN<0>")
	)
	(segment
		(start 385.20624 -276.190964)
		(end 385.214622 -276.186138)
		(width 0.09525)
		(layer "In4.Cu")
		(net "M_J_CPU0_SB_DQS_DN<0>")
	)
	(segment
		(start 432.531774 -284.46222)
		(end 433.312824 -285.24327)
		(width 0.16002)
		(layer "In4.Cu")
		(net "M_J_CPU0_SB_DQS_DN<0>")
	)
	(segment
		(start 381.446278 -276.190964)
		(end 381.45466 -276.186138)
		(width 0.09525)
		(layer "In4.Cu")
		(net "M_J_CPU0_SB_DQS_DN<0>")
	)
	(segment
		(start 423.695622 -284.46222)
		(end 425.081954 -284.46222)
		(width 0.16002)
		(layer "In4.Cu")
		(net "M_J_CPU0_SB_DQS_DN<0>")
	)
	(segment
		(start 403.137116 -277.891494)
		(end 404.122636 -277.891494)
		(width 0.16002)
		(layer "In4.Cu")
		(net "M_J_CPU0_SB_DQS_DN<0>")
	)
	(segment
		(start 395.3002 -275.181314)
		(end 395.340586 -275.140928)
		(width 0.09525)
		(layer "In4.Cu")
		(net "M_J_CPU0_SB_DQS_DN<0>")
	)
	(segment
		(start 411.151832 -284.92069)
		(end 412.762192 -284.92069)
		(width 0.16002)
		(layer "In4.Cu")
		(net "M_J_CPU0_SB_DQS_DN<0>")
	)
	(segment
		(start 437.938418 -285.461202)
		(end 438.826402 -285.461202)
		(width 0.16002)
		(layer "In4.Cu")
		(net "M_J_CPU0_SB_DQS_DN<0>")
	)
	(segment
		(start 395.340586 -275.140928)
		(end 395.776704 -275.140928)
		(width 0.09525)
		(layer "In4.Cu")
		(net "M_J_CPU0_SB_DQS_DN<0>")
	)
	(segment
		(start 395.835632 -275.199856)
		(end 395.859254 -275.199856)
		(width 0.09525)
		(layer "In4.Cu")
		(net "M_J_CPU0_SB_DQS_DN<0>")
	)
	(segment
		(start 414.052512 -285.65729)
		(end 414.837372 -284.87243)
		(width 0.16002)
		(layer "In4.Cu")
		(net "M_J_CPU0_SB_DQS_DN<0>")
	)
	(segment
		(start 389.33501 -276.186138)
		(end 389.343392 -276.190964)
		(width 0.09525)
		(layer "In4.Cu")
		(net "M_J_CPU0_SB_DQS_DN<0>")
	)
	(segment
		(start 430.392078 -285.080964)
		(end 431.010822 -284.46222)
		(width 0.16002)
		(layer "In4.Cu")
		(net "M_J_CPU0_SB_DQS_DN<0>")
	)
	(segment
		(start 428.316136 -285.62427)
		(end 429.29302 -285.62427)
		(width 0.16002)
		(layer "In4.Cu")
		(net "M_J_CPU0_SB_DQS_DN<0>")
	)
	(segment
		(start 404.122636 -277.891494)
		(end 411.151832 -284.92069)
		(width 0.16002)
		(layer "In4.Cu")
		(net "M_J_CPU0_SB_DQS_DN<0>")
	)
	(segment
		(start 425.081954 -284.46222)
		(end 425.931838 -285.312104)
		(width 0.16002)
		(layer "In4.Cu")
		(net "M_J_CPU0_SB_DQS_DN<0>")
	)
	(segment
		(start 425.931838 -285.312104)
		(end 428.00397 -285.312104)
		(width 0.16002)
		(layer "In4.Cu")
		(net "M_J_CPU0_SB_DQS_DN<0>")
	)
	(segment
		(start 413.498792 -285.65729)
		(end 414.052512 -285.65729)
		(width 0.16002)
		(layer "In4.Cu")
		(net "M_J_CPU0_SB_DQS_DN<0>")
	)
	(segment
		(start 414.837372 -284.87243)
		(end 417.69284 -284.87243)
		(width 0.16002)
		(layer "In4.Cu")
		(net "M_J_CPU0_SB_DQS_DN<0>")
	)
	(segment
		(start 400.445478 -275.199856)
		(end 403.137116 -277.891494)
		(width 0.16002)
		(layer "In4.Cu")
		(net "M_J_CPU0_SB_DQS_DN<0>")
	)
	(segment
		(start 423.017442 -285.1404)
		(end 423.695622 -284.46222)
		(width 0.16002)
		(layer "In4.Cu")
		(net "M_J_CPU0_SB_DQS_DN<0>")
	)
	(segment
		(start 395.859254 -275.199856)
		(end 400.445478 -275.199856)
		(width 0.16002)
		(layer "In4.Cu")
		(net "M_J_CPU0_SB_DQS_DN<0>")
	)
	(segment
		(start 380.694946 -276.516084)
		(end 380.84887 -276.250654)
		(width 0.09525)
		(layer "In4.Cu")
		(net "M_J_CPU0_SB_DQS_DN<0>")
	)
	(segment
		(start 384.634994 -276.186138)
		(end 384.643376 -276.190964)
		(width 0.09525)
		(layer "In4.Cu")
		(net "M_J_CPU0_SB_DQS_DN<0>")
	)
	(segment
		(start 389.906256 -276.190964)
		(end 389.914638 -276.186138)
		(width 0.09525)
		(layer "In4.Cu")
		(net "M_J_CPU0_SB_DQS_DN<0>")
	)
	(segment
		(start 392.723878 -276.190964)
		(end 392.742674 -276.180042)
		(width 0.09525)
		(layer "In4.Cu")
		(net "M_J_CPU0_SB_DQS_DN<0>")
	)
	(arc
		(start 390.283446 -276.190964)
		(mid 390.564878 -276.266719)
		(end 390.84631 -276.190964)
		(width 0.09525)
		(layer "In4.Cu")
		(net "M_J_CPU0_SB_DQS_DN<0>")
	)
	(arc
		(start 393.754356 -276.126702)
		(mid 393.767632 -276.114719)
		(end 393.780518 -276.102318)
		(width 0.09525)
		(layer "In4.Cu")
		(net "M_J_CPU0_SB_DQS_DN<0>")
	)
	(arc
		(start 380.949708 -276.223984)
		(mid 380.959576 -276.228015)
		(end 380.96952 -276.231858)
		(width 0.09525)
		(layer "In4.Cu")
		(net "M_J_CPU0_SB_DQS_DN<0>")
	)
	(arc
		(start 381.823468 -276.190964)
		(mid 382.1049 -276.266719)
		(end 382.386332 -276.190964)
		(width 0.09525)
		(layer "In4.Cu")
		(net "M_J_CPU0_SB_DQS_DN<0>")
	)
	(arc
		(start 382.386332 -276.190964)
		(mid 382.5748 -276.140287)
		(end 382.763268 -276.190964)
		(width 0.09525)
		(layer "In4.Cu")
		(net "M_J_CPU0_SB_DQS_DN<0>")
	)
	(arc
		(start 385.58343 -276.190964)
		(mid 385.864862 -276.266719)
		(end 386.146294 -276.190964)
		(width 0.09525)
		(layer "In4.Cu")
		(net "M_J_CPU0_SB_DQS_DN<0>")
	)
	(arc
		(start 391.78611 -276.190964)
		(mid 391.964716 -276.140296)
		(end 392.145774 -276.181312)
		(width 0.09525)
		(layer "In4.Cu")
		(net "M_J_CPU0_SB_DQS_DN<0>")
	)
	(arc
		(start 381.45466 -276.186138)
		(mid 381.639692 -276.140224)
		(end 381.823468 -276.190964)
		(width 0.09525)
		(layer "In4.Cu")
		(net "M_J_CPU0_SB_DQS_DN<0>")
	)
	(arc
		(start 392.187938 -276.205696)
		(mid 392.457792 -276.266575)
		(end 392.723878 -276.190964)
		(width 0.09525)
		(layer "In4.Cu")
		(net "M_J_CPU0_SB_DQS_DN<0>")
	)
	(arc
		(start 388.403338 -276.190964)
		(mid 388.68477 -276.266719)
		(end 388.966202 -276.190964)
		(width 0.09525)
		(layer "In4.Cu")
		(net "M_J_CPU0_SB_DQS_DN<0>")
	)
	(arc
		(start 390.84631 -276.190964)
		(mid 391.034778 -276.140287)
		(end 391.223246 -276.190964)
		(width 0.09525)
		(layer "In4.Cu")
		(net "M_J_CPU0_SB_DQS_DN<0>")
	)
	(arc
		(start 387.086348 -276.190964)
		(mid 387.274816 -276.140287)
		(end 387.463284 -276.190964)
		(width 0.09525)
		(layer "In4.Cu")
		(net "M_J_CPU0_SB_DQS_DN<0>")
	)
	(arc
		(start 392.742674 -276.180042)
		(mid 392.923769 -276.13981)
		(end 393.102084 -276.190964)
		(width 0.09525)
		(layer "In4.Cu")
		(net "M_J_CPU0_SB_DQS_DN<0>")
	)
	(arc
		(start 384.643376 -276.190964)
		(mid 384.924808 -276.266719)
		(end 385.20624 -276.190964)
		(width 0.09525)
		(layer "In4.Cu")
		(net "M_J_CPU0_SB_DQS_DN<0>")
	)
	(arc
		(start 393.102084 -276.190964)
		(mid 393.36362 -276.267077)
		(end 393.63015 -276.21103)
		(width 0.09525)
		(layer "In4.Cu")
		(net "M_J_CPU0_SB_DQS_DN<0>")
	)
	(arc
		(start 389.343392 -276.190964)
		(mid 389.624824 -276.266719)
		(end 389.906256 -276.190964)
		(width 0.09525)
		(layer "In4.Cu")
		(net "M_J_CPU0_SB_DQS_DN<0>")
	)
	(arc
		(start 380.96952 -276.231858)
		(mid 381.212484 -276.264845)
		(end 381.446278 -276.190964)
		(width 0.09525)
		(layer "In4.Cu")
		(net "M_J_CPU0_SB_DQS_DN<0>")
	)
	(arc
		(start 382.763268 -276.190964)
		(mid 383.0447 -276.266719)
		(end 383.326132 -276.190964)
		(width 0.09525)
		(layer "In4.Cu")
		(net "M_J_CPU0_SB_DQS_DN<0>")
	)
	(arc
		(start 391.223246 -276.190964)
		(mid 391.504678 -276.266719)
		(end 391.78611 -276.190964)
		(width 0.09525)
		(layer "In4.Cu")
		(net "M_J_CPU0_SB_DQS_DN<0>")
	)
	(arc
		(start 386.154676 -276.186138)
		(mid 386.339708 -276.140224)
		(end 386.523484 -276.190964)
		(width 0.09525)
		(layer "In4.Cu")
		(net "M_J_CPU0_SB_DQS_DN<0>")
	)
	(arc
		(start 393.664694 -276.190964)
		(mid 393.711112 -276.161048)
		(end 393.754356 -276.126702)
		(width 0.09525)
		(layer "In4.Cu")
		(net "M_J_CPU0_SB_DQS_DN<0>")
	)
	(arc
		(start 389.914638 -276.186138)
		(mid 390.09967 -276.140224)
		(end 390.283446 -276.190964)
		(width 0.09525)
		(layer "In4.Cu")
		(net "M_J_CPU0_SB_DQS_DN<0>")
	)
	(arc
		(start 388.026148 -276.190964)
		(mid 388.209923 -276.140192)
		(end 388.394956 -276.186138)
		(width 0.09525)
		(layer "In4.Cu")
		(net "M_J_CPU0_SB_DQS_DN<0>")
	)
	(arc
		(start 385.214622 -276.186138)
		(mid 385.399654 -276.140224)
		(end 385.58343 -276.190964)
		(width 0.09525)
		(layer "In4.Cu")
		(net "M_J_CPU0_SB_DQS_DN<0>")
	)
	(arc
		(start 386.523484 -276.190964)
		(mid 386.804916 -276.266719)
		(end 387.086348 -276.190964)
		(width 0.09525)
		(layer "In4.Cu")
		(net "M_J_CPU0_SB_DQS_DN<0>")
	)
	(arc
		(start 388.966202 -276.190964)
		(mid 389.149977 -276.140192)
		(end 389.33501 -276.186138)
		(width 0.09525)
		(layer "In4.Cu")
		(net "M_J_CPU0_SB_DQS_DN<0>")
	)
	(arc
		(start 383.326132 -276.190964)
		(mid 383.509907 -276.140192)
		(end 383.69494 -276.186138)
		(width 0.09525)
		(layer "In4.Cu")
		(net "M_J_CPU0_SB_DQS_DN<0>")
	)
	(arc
		(start 387.463284 -276.190964)
		(mid 387.744716 -276.266719)
		(end 388.026148 -276.190964)
		(width 0.09525)
		(layer "In4.Cu")
		(net "M_J_CPU0_SB_DQS_DN<0>")
	)
	(arc
		(start 383.703322 -276.190964)
		(mid 383.984754 -276.266719)
		(end 384.266186 -276.190964)
		(width 0.09525)
		(layer "In4.Cu")
		(net "M_J_CPU0_SB_DQS_DN<0>")
	)
	(arc
		(start 384.266186 -276.190964)
		(mid 384.449961 -276.140192)
		(end 384.634994 -276.186138)
		(width 0.09525)
		(layer "In4.Cu")
		(net "M_J_CPU0_SB_DQS_DN<0>")
	)
	(segment
		(start 379.28804 -279.49017)
		(end 379.754892 -279.756108)
		(width 0.10668)
		(layer "F.Cu")
		(net "M_J_CPU0_SB_DQ<9>")
	)
	(segment
		(start 414.984692 -292.11016)
		(end 417.70808 -292.11016)
		(width 0.14478)
		(layer "In4.Cu")
		(net "M_J_CPU0_SB_DQ<9>")
	)
	(segment
		(start 429.982884 -292.109906)
		(end 436.501032 -292.109906)
		(width 0.14478)
		(layer "In4.Cu")
		(net "M_J_CPU0_SB_DQ<9>")
	)
	(segment
		(start 393.644374 -279.927812)
		(end 395.129258 -279.927812)
		(width 0.0889)
		(layer "In4.Cu")
		(net "M_J_CPU0_SB_DQ<9>")
	)
	(segment
		(start 421.474646 -292.960044)
		(end 422.32453 -292.11016)
		(width 0.14478)
		(layer "In4.Cu")
		(net "M_J_CPU0_SB_DQ<9>")
	)
	(segment
		(start 436.662576 -292.27145)
		(end 436.662576 -292.618668)
		(width 0.14478)
		(layer "In4.Cu")
		(net "M_J_CPU0_SB_DQ<9>")
	)
	(segment
		(start 437.052466 -292.780212)
		(end 437.21401 -292.618668)
		(width 0.14478)
		(layer "In4.Cu")
		(net "M_J_CPU0_SB_DQ<9>")
	)
	(segment
		(start 429.132746 -292.960044)
		(end 429.982884 -292.109906)
		(width 0.14478)
		(layer "In4.Cu")
		(net "M_J_CPU0_SB_DQ<9>")
	)
	(segment
		(start 389.333486 -280.083514)
		(end 389.341868 -280.078688)
		(width 0.0889)
		(layer "In4.Cu")
		(net "M_J_CPU0_SB_DQ<9>")
	)
	(segment
		(start 388.393432 -280.083514)
		(end 388.401814 -280.078688)
		(width 0.0889)
		(layer "In4.Cu")
		(net "M_J_CPU0_SB_DQ<9>")
	)
	(segment
		(start 418.557964 -292.960044)
		(end 421.474646 -292.960044)
		(width 0.14478)
		(layer "In4.Cu")
		(net "M_J_CPU0_SB_DQ<9>")
	)
	(segment
		(start 384.63347 -280.083514)
		(end 384.641852 -280.078688)
		(width 0.0889)
		(layer "In4.Cu")
		(net "M_J_CPU0_SB_DQ<9>")
	)
	(segment
		(start 380.873508 -280.083514)
		(end 380.88189 -280.078688)
		(width 0.0889)
		(layer "In4.Cu")
		(net "M_J_CPU0_SB_DQ<9>")
	)
	(segment
		(start 437.21401 -292.27145)
		(end 437.375554 -292.109906)
		(width 0.14478)
		(layer "In4.Cu")
		(net "M_J_CPU0_SB_DQ<9>")
	)
	(segment
		(start 395.31163 -279.74544)
		(end 395.767306 -279.74544)
		(width 0.0889)
		(layer "In4.Cu")
		(net "M_J_CPU0_SB_DQ<9>")
	)
	(segment
		(start 379.933454 -280.083514)
		(end 379.941836 -280.078688)
		(width 0.0889)
		(layer "In4.Cu")
		(net "M_J_CPU0_SB_DQ<9>")
	)
	(segment
		(start 436.82412 -292.780212)
		(end 437.052466 -292.780212)
		(width 0.14478)
		(layer "In4.Cu")
		(net "M_J_CPU0_SB_DQ<9>")
	)
	(segment
		(start 389.90778 -280.078688)
		(end 389.916162 -280.083514)
		(width 0.0889)
		(layer "In4.Cu")
		(net "M_J_CPU0_SB_DQ<9>")
	)
	(segment
		(start 411.277308 -292.960044)
		(end 414.134808 -292.960044)
		(width 0.14478)
		(layer "In4.Cu")
		(net "M_J_CPU0_SB_DQ<9>")
	)
	(segment
		(start 426.29709 -292.960044)
		(end 429.132746 -292.960044)
		(width 0.14478)
		(layer "In4.Cu")
		(net "M_J_CPU0_SB_DQ<9>")
	)
	(segment
		(start 436.501032 -292.109906)
		(end 436.662576 -292.27145)
		(width 0.14478)
		(layer "In4.Cu")
		(net "M_J_CPU0_SB_DQ<9>")
	)
	(segment
		(start 379.600714 -280.021538)
		(end 379.623066 -280.10485)
		(width 0.0889)
		(layer "In4.Cu")
		(net "M_J_CPU0_SB_DQ<9>")
	)
	(segment
		(start 438.675272 -292.109906)
		(end 439.100214 -292.534848)
		(width 0.14478)
		(layer "In4.Cu")
		(net "M_J_CPU0_SB_DQ<9>")
	)
	(segment
		(start 408.291538 -289.521138)
		(end 408.291538 -289.974274)
		(width 0.14478)
		(layer "In4.Cu")
		(net "M_J_CPU0_SB_DQ<9>")
	)
	(segment
		(start 395.129258 -279.927812)
		(end 395.31163 -279.74544)
		(width 0.0889)
		(layer "In4.Cu")
		(net "M_J_CPU0_SB_DQ<9>")
	)
	(segment
		(start 391.787634 -280.078688)
		(end 391.796016 -280.083514)
		(width 0.0889)
		(layer "In4.Cu")
		(net "M_J_CPU0_SB_DQ<9>")
	)
	(segment
		(start 383.693416 -280.083514)
		(end 383.701798 -280.078688)
		(width 0.0889)
		(layer "In4.Cu")
		(net "M_J_CPU0_SB_DQ<9>")
	)
	(segment
		(start 395.767306 -279.74544)
		(end 398.51584 -279.74544)
		(width 0.14478)
		(layer "In4.Cu")
		(net "M_J_CPU0_SB_DQ<9>")
	)
	(segment
		(start 414.134808 -292.960044)
		(end 414.984692 -292.11016)
		(width 0.14478)
		(layer "In4.Cu")
		(net "M_J_CPU0_SB_DQ<9>")
	)
	(segment
		(start 398.51584 -279.74544)
		(end 408.291538 -289.521138)
		(width 0.14478)
		(layer "In4.Cu")
		(net "M_J_CPU0_SB_DQ<9>")
	)
	(segment
		(start 439.100214 -292.534848)
		(end 439.100214 -292.535102)
		(width 0.14478)
		(layer "In4.Cu")
		(net "M_J_CPU0_SB_DQ<9>")
	)
	(segment
		(start 437.21401 -292.618668)
		(end 437.21401 -292.27145)
		(width 0.14478)
		(layer "In4.Cu")
		(net "M_J_CPU0_SB_DQ<9>")
	)
	(segment
		(start 392.718036 -280.072592)
		(end 392.72845 -280.078688)
		(width 0.0889)
		(layer "In4.Cu")
		(net "M_J_CPU0_SB_DQ<9>")
	)
	(segment
		(start 425.447206 -292.11016)
		(end 426.29709 -292.960044)
		(width 0.14478)
		(layer "In4.Cu")
		(net "M_J_CPU0_SB_DQ<9>")
	)
	(segment
		(start 417.70808 -292.11016)
		(end 418.557964 -292.960044)
		(width 0.14478)
		(layer "In4.Cu")
		(net "M_J_CPU0_SB_DQ<9>")
	)
	(segment
		(start 408.291538 -289.974274)
		(end 411.277308 -292.960044)
		(width 0.14478)
		(layer "In4.Cu")
		(net "M_J_CPU0_SB_DQ<9>")
	)
	(segment
		(start 379.754892 -279.756108)
		(end 379.600714 -280.021538)
		(width 0.0889)
		(layer "In4.Cu")
		(net "M_J_CPU0_SB_DQ<9>")
	)
	(segment
		(start 422.32453 -292.11016)
		(end 425.447206 -292.11016)
		(width 0.14478)
		(layer "In4.Cu")
		(net "M_J_CPU0_SB_DQ<9>")
	)
	(segment
		(start 386.147818 -280.078688)
		(end 386.1562 -280.083514)
		(width 0.0889)
		(layer "In4.Cu")
		(net "M_J_CPU0_SB_DQ<9>")
	)
	(segment
		(start 436.662576 -292.618668)
		(end 436.82412 -292.780212)
		(width 0.14478)
		(layer "In4.Cu")
		(net "M_J_CPU0_SB_DQ<9>")
	)
	(segment
		(start 437.375554 -292.109906)
		(end 438.675272 -292.109906)
		(width 0.14478)
		(layer "In4.Cu")
		(net "M_J_CPU0_SB_DQ<9>")
	)
	(segment
		(start 385.207764 -280.078688)
		(end 385.216146 -280.083514)
		(width 0.0889)
		(layer "In4.Cu")
		(net "M_J_CPU0_SB_DQ<9>")
	)
	(segment
		(start 381.447802 -280.078688)
		(end 381.456184 -280.083514)
		(width 0.0889)
		(layer "In4.Cu")
		(net "M_J_CPU0_SB_DQ<9>")
	)
	(arc
		(start 382.761744 -280.078688)
		(mid 383.0447 -280.002511)
		(end 383.327656 -280.078688)
		(width 0.0889)
		(layer "In4.Cu")
		(net "M_J_CPU0_SB_DQ<9>")
	)
	(arc
		(start 392.72845 -280.078688)
		(mid 392.9061 -280.128948)
		(end 393.086082 -280.087832)
		(width 0.0889)
		(layer "In4.Cu")
		(net "M_J_CPU0_SB_DQ<9>")
	)
	(arc
		(start 389.916162 -280.083514)
		(mid 390.09967 -280.129008)
		(end 390.281922 -280.078688)
		(width 0.0889)
		(layer "In4.Cu")
		(net "M_J_CPU0_SB_DQ<9>")
	)
	(arc
		(start 379.623066 -280.10485)
		(mid 379.780576 -280.128048)
		(end 379.933454 -280.083514)
		(width 0.0889)
		(layer "In4.Cu")
		(net "M_J_CPU0_SB_DQ<9>")
	)
	(arc
		(start 385.216146 -280.083514)
		(mid 385.399654 -280.129008)
		(end 385.581906 -280.078688)
		(width 0.0889)
		(layer "In4.Cu")
		(net "M_J_CPU0_SB_DQ<9>")
	)
	(arc
		(start 383.701798 -280.078688)
		(mid 383.984754 -280.002511)
		(end 384.26771 -280.078688)
		(width 0.0889)
		(layer "In4.Cu")
		(net "M_J_CPU0_SB_DQ<9>")
	)
	(arc
		(start 382.387856 -280.078688)
		(mid 382.5748 -280.128943)
		(end 382.761744 -280.078688)
		(width 0.0889)
		(layer "In4.Cu")
		(net "M_J_CPU0_SB_DQ<9>")
	)
	(arc
		(start 381.456184 -280.083514)
		(mid 381.639692 -280.129008)
		(end 381.821944 -280.078688)
		(width 0.0889)
		(layer "In4.Cu")
		(net "M_J_CPU0_SB_DQ<9>")
	)
	(arc
		(start 388.967726 -280.078688)
		(mid 389.149977 -280.129038)
		(end 389.333486 -280.083514)
		(width 0.0889)
		(layer "In4.Cu")
		(net "M_J_CPU0_SB_DQ<9>")
	)
	(arc
		(start 380.507748 -280.078688)
		(mid 380.689999 -280.129038)
		(end 380.873508 -280.083514)
		(width 0.0889)
		(layer "In4.Cu")
		(net "M_J_CPU0_SB_DQ<9>")
	)
	(arc
		(start 380.88189 -280.078688)
		(mid 381.164846 -280.002511)
		(end 381.447802 -280.078688)
		(width 0.0889)
		(layer "In4.Cu")
		(net "M_J_CPU0_SB_DQ<9>")
	)
	(arc
		(start 389.341868 -280.078688)
		(mid 389.624824 -280.002511)
		(end 389.90778 -280.078688)
		(width 0.0889)
		(layer "In4.Cu")
		(net "M_J_CPU0_SB_DQ<9>")
	)
	(arc
		(start 390.281922 -280.078688)
		(mid 390.564878 -280.002511)
		(end 390.847834 -280.078688)
		(width 0.0889)
		(layer "In4.Cu")
		(net "M_J_CPU0_SB_DQ<9>")
	)
	(arc
		(start 391.221722 -280.078688)
		(mid 391.504678 -280.002511)
		(end 391.787634 -280.078688)
		(width 0.0889)
		(layer "In4.Cu")
		(net "M_J_CPU0_SB_DQ<9>")
	)
	(arc
		(start 385.581906 -280.078688)
		(mid 385.864862 -280.002511)
		(end 386.147818 -280.078688)
		(width 0.0889)
		(layer "In4.Cu")
		(net "M_J_CPU0_SB_DQ<9>")
	)
	(arc
		(start 393.086082 -280.087832)
		(mid 393.353997 -279.968655)
		(end 393.644374 -279.927812)
		(width 0.0889)
		(layer "In4.Cu")
		(net "M_J_CPU0_SB_DQ<9>")
	)
	(arc
		(start 384.641852 -280.078688)
		(mid 384.924808 -280.002511)
		(end 385.207764 -280.078688)
		(width 0.0889)
		(layer "In4.Cu")
		(net "M_J_CPU0_SB_DQ<9>")
	)
	(arc
		(start 387.46176 -280.078688)
		(mid 387.744716 -280.002511)
		(end 388.027672 -280.078688)
		(width 0.0889)
		(layer "In4.Cu")
		(net "M_J_CPU0_SB_DQ<9>")
	)
	(arc
		(start 388.401814 -280.078688)
		(mid 388.68477 -280.002511)
		(end 388.967726 -280.078688)
		(width 0.0889)
		(layer "In4.Cu")
		(net "M_J_CPU0_SB_DQ<9>")
	)
	(arc
		(start 391.796016 -280.083514)
		(mid 391.979778 -280.12913)
		(end 392.162284 -280.078688)
		(width 0.0889)
		(layer "In4.Cu")
		(net "M_J_CPU0_SB_DQ<9>")
	)
	(arc
		(start 384.26771 -280.078688)
		(mid 384.449961 -280.129038)
		(end 384.63347 -280.083514)
		(width 0.0889)
		(layer "In4.Cu")
		(net "M_J_CPU0_SB_DQ<9>")
	)
	(arc
		(start 388.027672 -280.078688)
		(mid 388.209923 -280.129038)
		(end 388.393432 -280.083514)
		(width 0.0889)
		(layer "In4.Cu")
		(net "M_J_CPU0_SB_DQ<9>")
	)
	(arc
		(start 379.941836 -280.078688)
		(mid 380.224792 -280.002511)
		(end 380.507748 -280.078688)
		(width 0.0889)
		(layer "In4.Cu")
		(net "M_J_CPU0_SB_DQ<9>")
	)
	(arc
		(start 392.162284 -280.078688)
		(mid 392.439351 -280.002417)
		(end 392.718036 -280.072592)
		(width 0.0889)
		(layer "In4.Cu")
		(net "M_J_CPU0_SB_DQ<9>")
	)
	(arc
		(start 387.087872 -280.078688)
		(mid 387.274816 -280.128943)
		(end 387.46176 -280.078688)
		(width 0.0889)
		(layer "In4.Cu")
		(net "M_J_CPU0_SB_DQ<9>")
	)
	(arc
		(start 383.327656 -280.078688)
		(mid 383.509907 -280.129038)
		(end 383.693416 -280.083514)
		(width 0.0889)
		(layer "In4.Cu")
		(net "M_J_CPU0_SB_DQ<9>")
	)
	(arc
		(start 386.1562 -280.083514)
		(mid 386.339708 -280.129008)
		(end 386.52196 -280.078688)
		(width 0.0889)
		(layer "In4.Cu")
		(net "M_J_CPU0_SB_DQ<9>")
	)
	(arc
		(start 381.821944 -280.078688)
		(mid 382.1049 -280.002511)
		(end 382.387856 -280.078688)
		(width 0.0889)
		(layer "In4.Cu")
		(net "M_J_CPU0_SB_DQ<9>")
	)
	(arc
		(start 386.52196 -280.078688)
		(mid 386.804916 -280.002511)
		(end 387.087872 -280.078688)
		(width 0.0889)
		(layer "In4.Cu")
		(net "M_J_CPU0_SB_DQ<9>")
	)
	(arc
		(start 390.847834 -280.078688)
		(mid 391.034778 -280.128943)
		(end 391.221722 -280.078688)
		(width 0.0889)
		(layer "In4.Cu")
		(net "M_J_CPU0_SB_DQ<9>")
	)
	(segment
		(start 380.697994 -278.680164)
		(end 381.164846 -278.946102)
		(width 0.10668)
		(layer "F.Cu")
		(net "M_J_CPU0_SB_DQ<8>")
	)
	(segment
		(start 430.204118 -290.410138)
		(end 436.130446 -290.410138)
		(width 0.14478)
		(layer "In4.Cu")
		(net "M_J_CPU0_SB_DQ<8>")
	)
	(segment
		(start 395.152118 -278.65197)
		(end 395.193012 -278.611076)
		(width 0.0889)
		(layer "In4.Cu")
		(net "M_J_CPU0_SB_DQ<8>")
	)
	(segment
		(start 386.983478 -279.273508)
		(end 386.99186 -279.268682)
		(width 0.0889)
		(layer "In4.Cu")
		(net "M_J_CPU0_SB_DQ<8>")
	)
	(segment
		(start 436.130446 -290.410138)
		(end 436.29199 -290.571682)
		(width 0.14478)
		(layer "In4.Cu")
		(net "M_J_CPU0_SB_DQ<8>")
	)
	(segment
		(start 421.727122 -291.260022)
		(end 422.577006 -290.410138)
		(width 0.14478)
		(layer "In4.Cu")
		(net "M_J_CPU0_SB_DQ<8>")
	)
	(segment
		(start 386.043424 -279.273508)
		(end 386.051806 -279.268682)
		(width 0.0889)
		(layer "In4.Cu")
		(net "M_J_CPU0_SB_DQ<8>")
	)
	(segment
		(start 429.354234 -291.260022)
		(end 430.204118 -290.410138)
		(width 0.14478)
		(layer "In4.Cu")
		(net "M_J_CPU0_SB_DQ<8>")
	)
	(segment
		(start 437.004968 -290.410138)
		(end 437.233314 -290.410138)
		(width 0.14478)
		(layer "In4.Cu")
		(net "M_J_CPU0_SB_DQ<8>")
	)
	(segment
		(start 414.183068 -291.260022)
		(end 415.032952 -290.410138)
		(width 0.14478)
		(layer "In4.Cu")
		(net "M_J_CPU0_SB_DQ<8>")
	)
	(segment
		(start 393.753848 -279.189942)
		(end 393.811252 -279.142952)
		(width 0.0889)
		(layer "In4.Cu")
		(net "M_J_CPU0_SB_DQ<8>")
	)
	(segment
		(start 436.453534 -291.307012)
		(end 436.68188 -291.307012)
		(width 0.14478)
		(layer "In4.Cu")
		(net "M_J_CPU0_SB_DQ<8>")
	)
	(segment
		(start 382.857756 -279.268682)
		(end 382.866138 -279.273508)
		(width 0.0889)
		(layer "In4.Cu")
		(net "M_J_CPU0_SB_DQ<8>")
	)
	(segment
		(start 391.317734 -279.268682)
		(end 391.326116 -279.273508)
		(width 0.0889)
		(layer "In4.Cu")
		(net "M_J_CPU0_SB_DQ<8>")
	)
	(segment
		(start 395.193012 -278.611076)
		(end 395.925294 -278.611076)
		(width 0.0889)
		(layer "In4.Cu")
		(net "M_J_CPU0_SB_DQ<8>")
	)
	(segment
		(start 383.79781 -279.268682)
		(end 383.806192 -279.273508)
		(width 0.0889)
		(layer "In4.Cu")
		(net "M_J_CPU0_SB_DQ<8>")
	)
	(segment
		(start 438.675526 -290.410138)
		(end 439.100214 -290.834826)
		(width 0.14478)
		(layer "In4.Cu")
		(net "M_J_CPU0_SB_DQ<8>")
	)
	(segment
		(start 390.74344 -279.273508)
		(end 390.751822 -279.268682)
		(width 0.0889)
		(layer "In4.Cu")
		(net "M_J_CPU0_SB_DQ<8>")
	)
	(segment
		(start 381.164846 -278.946102)
		(end 381.010922 -279.211532)
		(width 0.0889)
		(layer "In4.Cu")
		(net "M_J_CPU0_SB_DQ<8>")
	)
	(segment
		(start 437.233314 -290.410138)
		(end 437.394858 -290.571682)
		(width 0.14478)
		(layer "In4.Cu")
		(net "M_J_CPU0_SB_DQ<8>")
	)
	(segment
		(start 436.843424 -290.571682)
		(end 437.004968 -290.410138)
		(width 0.14478)
		(layer "In4.Cu")
		(net "M_J_CPU0_SB_DQ<8>")
	)
	(segment
		(start 422.577006 -290.410138)
		(end 425.164758 -290.410138)
		(width 0.14478)
		(layer "In4.Cu")
		(net "M_J_CPU0_SB_DQ<8>")
	)
	(segment
		(start 426.014642 -291.260022)
		(end 429.354234 -291.260022)
		(width 0.14478)
		(layer "In4.Cu")
		(net "M_J_CPU0_SB_DQ<8>")
	)
	(segment
		(start 437.394858 -291.145468)
		(end 437.556402 -291.307012)
		(width 0.14478)
		(layer "In4.Cu")
		(net "M_J_CPU0_SB_DQ<8>")
	)
	(segment
		(start 417.610544 -290.410138)
		(end 418.460428 -291.260022)
		(width 0.14478)
		(layer "In4.Cu")
		(net "M_J_CPU0_SB_DQ<8>")
	)
	(segment
		(start 392.62939 -279.268682)
		(end 392.652758 -279.254966)
		(width 0.0889)
		(layer "In4.Cu")
		(net "M_J_CPU0_SB_DQ<8>")
	)
	(segment
		(start 392.234674 -279.255982)
		(end 392.256264 -279.268428)
		(width 0.0889)
		(layer "In4.Cu")
		(net "M_J_CPU0_SB_DQ<8>")
	)
	(segment
		(start 393.400534 -279.313132)
		(end 393.474194 -279.305766)
		(width 0.0889)
		(layer "In4.Cu")
		(net "M_J_CPU0_SB_DQ<8>")
	)
	(segment
		(start 436.68188 -291.307012)
		(end 436.843424 -291.145468)
		(width 0.14478)
		(layer "In4.Cu")
		(net "M_J_CPU0_SB_DQ<8>")
	)
	(segment
		(start 382.283462 -279.273508)
		(end 382.291844 -279.268682)
		(width 0.0889)
		(layer "In4.Cu")
		(net "M_J_CPU0_SB_DQ<8>")
	)
	(segment
		(start 394.302234 -278.65197)
		(end 395.152118 -278.65197)
		(width 0.0889)
		(layer "In4.Cu")
		(net "M_J_CPU0_SB_DQ<8>")
	)
	(segment
		(start 392.256264 -279.268428)
		(end 392.274552 -279.278842)
		(width 0.0889)
		(layer "In4.Cu")
		(net "M_J_CPU0_SB_DQ<8>")
	)
	(segment
		(start 436.29199 -291.145468)
		(end 436.453534 -291.307012)
		(width 0.14478)
		(layer "In4.Cu")
		(net "M_J_CPU0_SB_DQ<8>")
	)
	(segment
		(start 437.394858 -290.571682)
		(end 437.394858 -291.145468)
		(width 0.14478)
		(layer "In4.Cu")
		(net "M_J_CPU0_SB_DQ<8>")
	)
	(segment
		(start 418.460428 -291.260022)
		(end 421.727122 -291.260022)
		(width 0.14478)
		(layer "In4.Cu")
		(net "M_J_CPU0_SB_DQ<8>")
	)
	(segment
		(start 439.100214 -290.834826)
		(end 439.100214 -290.83508)
		(width 0.14478)
		(layer "In4.Cu")
		(net "M_J_CPU0_SB_DQ<8>")
	)
	(segment
		(start 437.946292 -291.145468)
		(end 437.946292 -290.571682)
		(width 0.14478)
		(layer "In4.Cu")
		(net "M_J_CPU0_SB_DQ<8>")
	)
	(segment
		(start 425.164758 -290.410138)
		(end 426.014642 -291.260022)
		(width 0.14478)
		(layer "In4.Cu")
		(net "M_J_CPU0_SB_DQ<8>")
	)
	(segment
		(start 411.798262 -291.260022)
		(end 414.183068 -291.260022)
		(width 0.14478)
		(layer "In4.Cu")
		(net "M_J_CPU0_SB_DQ<8>")
	)
	(segment
		(start 393.811252 -279.142952)
		(end 394.302234 -278.65197)
		(width 0.0889)
		(layer "In4.Cu")
		(net "M_J_CPU0_SB_DQ<8>")
	)
	(segment
		(start 381.010922 -279.211532)
		(end 381.033274 -279.294844)
		(width 0.0889)
		(layer "In4.Cu")
		(net "M_J_CPU0_SB_DQ<8>")
	)
	(segment
		(start 399.149316 -278.611076)
		(end 411.798262 -291.260022)
		(width 0.14478)
		(layer "In4.Cu")
		(net "M_J_CPU0_SB_DQ<8>")
	)
	(segment
		(start 437.784748 -291.307012)
		(end 437.946292 -291.145468)
		(width 0.14478)
		(layer "In4.Cu")
		(net "M_J_CPU0_SB_DQ<8>")
	)
	(segment
		(start 388.497826 -279.268682)
		(end 388.506208 -279.273508)
		(width 0.0889)
		(layer "In4.Cu")
		(net "M_J_CPU0_SB_DQ<8>")
	)
	(segment
		(start 415.032952 -290.410138)
		(end 417.610544 -290.410138)
		(width 0.14478)
		(layer "In4.Cu")
		(net "M_J_CPU0_SB_DQ<8>")
	)
	(segment
		(start 436.843424 -291.145468)
		(end 436.843424 -290.571682)
		(width 0.14478)
		(layer "In4.Cu")
		(net "M_J_CPU0_SB_DQ<8>")
	)
	(segment
		(start 438.107836 -290.410138)
		(end 438.675526 -290.410138)
		(width 0.14478)
		(layer "In4.Cu")
		(net "M_J_CPU0_SB_DQ<8>")
	)
	(segment
		(start 436.29199 -290.571682)
		(end 436.29199 -291.145468)
		(width 0.14478)
		(layer "In4.Cu")
		(net "M_J_CPU0_SB_DQ<8>")
	)
	(segment
		(start 437.946292 -290.571682)
		(end 438.107836 -290.410138)
		(width 0.14478)
		(layer "In4.Cu")
		(net "M_J_CPU0_SB_DQ<8>")
	)
	(segment
		(start 437.556402 -291.307012)
		(end 437.784748 -291.307012)
		(width 0.14478)
		(layer "In4.Cu")
		(net "M_J_CPU0_SB_DQ<8>")
	)
	(segment
		(start 395.925294 -278.611076)
		(end 399.149316 -278.611076)
		(width 0.14478)
		(layer "In4.Cu")
		(net "M_J_CPU0_SB_DQ<8>")
	)
	(segment
		(start 387.557772 -279.268682)
		(end 387.566154 -279.273508)
		(width 0.0889)
		(layer "In4.Cu")
		(net "M_J_CPU0_SB_DQ<8>")
	)
	(arc
		(start 391.326116 -279.273508)
		(mid 391.509624 -279.319002)
		(end 391.691876 -279.268682)
		(width 0.0889)
		(layer "In4.Cu")
		(net "M_J_CPU0_SB_DQ<8>")
	)
	(arc
		(start 382.866138 -279.273508)
		(mid 383.049646 -279.319002)
		(end 383.231898 -279.268682)
		(width 0.0889)
		(layer "In4.Cu")
		(net "M_J_CPU0_SB_DQ<8>")
	)
	(arc
		(start 392.274552 -279.278842)
		(mid 392.453273 -279.318765)
		(end 392.62939 -279.268682)
		(width 0.0889)
		(layer "In4.Cu")
		(net "M_J_CPU0_SB_DQ<8>")
	)
	(arc
		(start 392.652758 -279.254966)
		(mid 392.926412 -279.192023)
		(end 393.196572 -279.268682)
		(width 0.0889)
		(layer "In4.Cu")
		(net "M_J_CPU0_SB_DQ<8>")
	)
	(arc
		(start 390.37768 -279.268682)
		(mid 390.559931 -279.319032)
		(end 390.74344 -279.273508)
		(width 0.0889)
		(layer "In4.Cu")
		(net "M_J_CPU0_SB_DQ<8>")
	)
	(arc
		(start 383.231898 -279.268682)
		(mid 383.514854 -279.192505)
		(end 383.79781 -279.268682)
		(width 0.0889)
		(layer "In4.Cu")
		(net "M_J_CPU0_SB_DQ<8>")
	)
	(arc
		(start 386.051806 -279.268682)
		(mid 386.334762 -279.192505)
		(end 386.617718 -279.268682)
		(width 0.0889)
		(layer "In4.Cu")
		(net "M_J_CPU0_SB_DQ<8>")
	)
	(arc
		(start 381.35179 -279.268682)
		(mid 381.634746 -279.192505)
		(end 381.917702 -279.268682)
		(width 0.0889)
		(layer "In4.Cu")
		(net "M_J_CPU0_SB_DQ<8>")
	)
	(arc
		(start 387.566154 -279.273508)
		(mid 387.749662 -279.319002)
		(end 387.931914 -279.268682)
		(width 0.0889)
		(layer "In4.Cu")
		(net "M_J_CPU0_SB_DQ<8>")
	)
	(arc
		(start 381.033274 -279.294844)
		(mid 381.195463 -279.317579)
		(end 381.35179 -279.268682)
		(width 0.0889)
		(layer "In4.Cu")
		(net "M_J_CPU0_SB_DQ<8>")
	)
	(arc
		(start 385.111752 -279.268682)
		(mid 385.394708 -279.192505)
		(end 385.677664 -279.268682)
		(width 0.0889)
		(layer "In4.Cu")
		(net "M_J_CPU0_SB_DQ<8>")
	)
	(arc
		(start 385.677664 -279.268682)
		(mid 385.859915 -279.319032)
		(end 386.043424 -279.273508)
		(width 0.0889)
		(layer "In4.Cu")
		(net "M_J_CPU0_SB_DQ<8>")
	)
	(arc
		(start 389.43788 -279.268682)
		(mid 389.624824 -279.318937)
		(end 389.811768 -279.268682)
		(width 0.0889)
		(layer "In4.Cu")
		(net "M_J_CPU0_SB_DQ<8>")
	)
	(arc
		(start 383.806192 -279.273508)
		(mid 383.9897 -279.319002)
		(end 384.171952 -279.268682)
		(width 0.0889)
		(layer "In4.Cu")
		(net "M_J_CPU0_SB_DQ<8>")
	)
	(arc
		(start 390.751822 -279.268682)
		(mid 391.034778 -279.192505)
		(end 391.317734 -279.268682)
		(width 0.0889)
		(layer "In4.Cu")
		(net "M_J_CPU0_SB_DQ<8>")
	)
	(arc
		(start 381.917702 -279.268682)
		(mid 382.099953 -279.319032)
		(end 382.283462 -279.273508)
		(width 0.0889)
		(layer "In4.Cu")
		(net "M_J_CPU0_SB_DQ<8>")
	)
	(arc
		(start 393.474194 -279.305766)
		(mid 393.622572 -279.268509)
		(end 393.753848 -279.189942)
		(width 0.0889)
		(layer "In4.Cu")
		(net "M_J_CPU0_SB_DQ<8>")
	)
	(arc
		(start 388.506208 -279.273508)
		(mid 388.689716 -279.319002)
		(end 388.871968 -279.268682)
		(width 0.0889)
		(layer "In4.Cu")
		(net "M_J_CPU0_SB_DQ<8>")
	)
	(arc
		(start 393.196572 -279.268682)
		(mid 393.295039 -279.307022)
		(end 393.400534 -279.313132)
		(width 0.0889)
		(layer "In4.Cu")
		(net "M_J_CPU0_SB_DQ<8>")
	)
	(arc
		(start 391.691876 -279.268682)
		(mid 391.961645 -279.192659)
		(end 392.234674 -279.255982)
		(width 0.0889)
		(layer "In4.Cu")
		(net "M_J_CPU0_SB_DQ<8>")
	)
	(arc
		(start 387.931914 -279.268682)
		(mid 388.21487 -279.192505)
		(end 388.497826 -279.268682)
		(width 0.0889)
		(layer "In4.Cu")
		(net "M_J_CPU0_SB_DQ<8>")
	)
	(arc
		(start 384.171952 -279.268682)
		(mid 384.454908 -279.192505)
		(end 384.737864 -279.268682)
		(width 0.0889)
		(layer "In4.Cu")
		(net "M_J_CPU0_SB_DQ<8>")
	)
	(arc
		(start 384.737864 -279.268682)
		(mid 384.924808 -279.318937)
		(end 385.111752 -279.268682)
		(width 0.0889)
		(layer "In4.Cu")
		(net "M_J_CPU0_SB_DQ<8>")
	)
	(arc
		(start 389.811768 -279.268682)
		(mid 390.094724 -279.192505)
		(end 390.37768 -279.268682)
		(width 0.0889)
		(layer "In4.Cu")
		(net "M_J_CPU0_SB_DQ<8>")
	)
	(arc
		(start 382.291844 -279.268682)
		(mid 382.5748 -279.192505)
		(end 382.857756 -279.268682)
		(width 0.0889)
		(layer "In4.Cu")
		(net "M_J_CPU0_SB_DQ<8>")
	)
	(arc
		(start 386.99186 -279.268682)
		(mid 387.274816 -279.192505)
		(end 387.557772 -279.268682)
		(width 0.0889)
		(layer "In4.Cu")
		(net "M_J_CPU0_SB_DQ<8>")
	)
	(arc
		(start 388.871968 -279.268682)
		(mid 389.154924 -279.192505)
		(end 389.43788 -279.268682)
		(width 0.0889)
		(layer "In4.Cu")
		(net "M_J_CPU0_SB_DQ<8>")
	)
	(arc
		(start 386.617718 -279.268682)
		(mid 386.799969 -279.319032)
		(end 386.983478 -279.273508)
		(width 0.0889)
		(layer "In4.Cu")
		(net "M_J_CPU0_SB_DQ<8>")
	)
	(segment
		(start 378.817886 -278.680164)
		(end 379.284738 -278.946102)
		(width 0.10668)
		(layer "F.Cu")
		(net "M_J_CPU0_SB_DQ<7>")
	)
	(segment
		(start 383.79781 -278.623522)
		(end 383.806192 -278.618696)
		(width 0.0889)
		(layer "In4.Cu")
		(net "M_J_CPU0_SB_DQ<7>")
	)
	(segment
		(start 387.557772 -278.623522)
		(end 387.566154 -278.618696)
		(width 0.0889)
		(layer "In4.Cu")
		(net "M_J_CPU0_SB_DQ<7>")
	)
	(segment
		(start 391.691876 -278.623522)
		(end 391.70229 -278.629618)
		(width 0.0889)
		(layer "In4.Cu")
		(net "M_J_CPU0_SB_DQ<7>")
	)
	(segment
		(start 390.74344 -278.618696)
		(end 390.751822 -278.623522)
		(width 0.0889)
		(layer "In4.Cu")
		(net "M_J_CPU0_SB_DQ<7>")
	)
	(segment
		(start 393.192508 -278.627078)
		(end 393.89685 -278.235918)
		(width 0.0889)
		(layer "In4.Cu")
		(net "M_J_CPU0_SB_DQ<7>")
	)
	(segment
		(start 416.88766 -289.244532)
		(end 417.203382 -289.560254)
		(width 0.14478)
		(layer "In4.Cu")
		(net "M_J_CPU0_SB_DQ<7>")
	)
	(segment
		(start 411.728158 -290.410392)
		(end 413.676592 -290.410392)
		(width 0.14478)
		(layer "In4.Cu")
		(net "M_J_CPU0_SB_DQ<7>")
	)
	(segment
		(start 432.905916 -289.18027)
		(end 433.169822 -289.18027)
		(width 0.14478)
		(layer "In4.Cu")
		(net "M_J_CPU0_SB_DQ<7>")
	)
	(segment
		(start 417.203382 -289.560254)
		(end 417.69284 -289.560254)
		(width 0.14478)
		(layer "In4.Cu")
		(net "M_J_CPU0_SB_DQ<7>")
	)
	(segment
		(start 433.169822 -289.18027)
		(end 433.316126 -289.326574)
		(width 0.14478)
		(layer "In4.Cu")
		(net "M_J_CPU0_SB_DQ<7>")
	)
	(segment
		(start 416.100514 -289.560254)
		(end 416.336226 -289.560254)
		(width 0.14478)
		(layer "In4.Cu")
		(net "M_J_CPU0_SB_DQ<7>")
	)
	(segment
		(start 432.613308 -289.853116)
		(end 432.759612 -289.706812)
		(width 0.14478)
		(layer "In4.Cu")
		(net "M_J_CPU0_SB_DQ<7>")
	)
	(segment
		(start 429.371506 -290.410138)
		(end 430.221136 -289.560508)
		(width 0.14478)
		(layer "In4.Cu")
		(net "M_J_CPU0_SB_DQ<7>")
	)
	(segment
		(start 392.62431 -278.618696)
		(end 392.632692 -278.623522)
		(width 0.0889)
		(layer "In4.Cu")
		(net "M_J_CPU0_SB_DQ<7>")
	)
	(segment
		(start 399.372582 -278.054816)
		(end 411.728158 -290.410392)
		(width 0.14478)
		(layer "In4.Cu")
		(net "M_J_CPU0_SB_DQ<7>")
	)
	(segment
		(start 432.759612 -289.326574)
		(end 432.905916 -289.18027)
		(width 0.14478)
		(layer "In4.Cu")
		(net "M_J_CPU0_SB_DQ<7>")
	)
	(segment
		(start 432.349402 -289.853116)
		(end 432.613308 -289.853116)
		(width 0.14478)
		(layer "In4.Cu")
		(net "M_J_CPU0_SB_DQ<7>")
	)
	(segment
		(start 415.233358 -289.560254)
		(end 415.54908 -289.244532)
		(width 0.14478)
		(layer "In4.Cu")
		(net "M_J_CPU0_SB_DQ<7>")
	)
	(segment
		(start 426.020738 -290.410138)
		(end 429.371506 -290.410138)
		(width 0.14478)
		(layer "In4.Cu")
		(net "M_J_CPU0_SB_DQ<7>")
	)
	(segment
		(start 432.056794 -289.560508)
		(end 432.349402 -289.853116)
		(width 0.14478)
		(layer "In4.Cu")
		(net "M_J_CPU0_SB_DQ<7>")
	)
	(segment
		(start 416.336226 -289.560254)
		(end 416.651948 -289.244532)
		(width 0.14478)
		(layer "In4.Cu")
		(net "M_J_CPU0_SB_DQ<7>")
	)
	(segment
		(start 434.28285 -289.2679)
		(end 435.000146 -289.985196)
		(width 0.14478)
		(layer "In4.Cu")
		(net "M_J_CPU0_SB_DQ<7>")
	)
	(segment
		(start 379.438916 -278.680672)
		(end 379.535182 -278.655272)
		(width 0.0889)
		(layer "In4.Cu")
		(net "M_J_CPU0_SB_DQ<7>")
	)
	(segment
		(start 433.316126 -289.326574)
		(end 433.316126 -289.706812)
		(width 0.14478)
		(layer "In4.Cu")
		(net "M_J_CPU0_SB_DQ<7>")
	)
	(segment
		(start 433.726336 -289.853116)
		(end 433.87264 -289.706812)
		(width 0.14478)
		(layer "In4.Cu")
		(net "M_J_CPU0_SB_DQ<7>")
	)
	(segment
		(start 388.497826 -278.623522)
		(end 388.506208 -278.618696)
		(width 0.0889)
		(layer "In4.Cu")
		(net "M_J_CPU0_SB_DQ<7>")
	)
	(segment
		(start 395.959584 -278.054816)
		(end 399.372582 -278.054816)
		(width 0.14478)
		(layer "In4.Cu")
		(net "M_J_CPU0_SB_DQ<7>")
	)
	(segment
		(start 421.634158 -290.410392)
		(end 422.484296 -289.560254)
		(width 0.14478)
		(layer "In4.Cu")
		(net "M_J_CPU0_SB_DQ<7>")
	)
	(segment
		(start 393.89685 -278.235918)
		(end 395.168628 -278.235918)
		(width 0.0889)
		(layer "In4.Cu")
		(net "M_J_CPU0_SB_DQ<7>")
	)
	(segment
		(start 433.46243 -289.853116)
		(end 433.726336 -289.853116)
		(width 0.14478)
		(layer "In4.Cu")
		(net "M_J_CPU0_SB_DQ<7>")
	)
	(segment
		(start 415.784792 -289.244532)
		(end 416.100514 -289.560254)
		(width 0.14478)
		(layer "In4.Cu")
		(net "M_J_CPU0_SB_DQ<7>")
	)
	(segment
		(start 382.283462 -278.618696)
		(end 382.291844 -278.623522)
		(width 0.0889)
		(layer "In4.Cu")
		(net "M_J_CPU0_SB_DQ<7>")
	)
	(segment
		(start 434.018944 -289.2679)
		(end 434.28285 -289.2679)
		(width 0.14478)
		(layer "In4.Cu")
		(net "M_J_CPU0_SB_DQ<7>")
	)
	(segment
		(start 433.316126 -289.706812)
		(end 433.46243 -289.853116)
		(width 0.14478)
		(layer "In4.Cu")
		(net "M_J_CPU0_SB_DQ<7>")
	)
	(segment
		(start 415.54908 -289.244532)
		(end 415.784792 -289.244532)
		(width 0.14478)
		(layer "In4.Cu")
		(net "M_J_CPU0_SB_DQ<7>")
	)
	(segment
		(start 433.87264 -289.414204)
		(end 434.018944 -289.2679)
		(width 0.14478)
		(layer "In4.Cu")
		(net "M_J_CPU0_SB_DQ<7>")
	)
	(segment
		(start 417.69284 -289.560254)
		(end 418.542978 -290.410392)
		(width 0.14478)
		(layer "In4.Cu")
		(net "M_J_CPU0_SB_DQ<7>")
	)
	(segment
		(start 386.983478 -278.618696)
		(end 386.99186 -278.623522)
		(width 0.0889)
		(layer "In4.Cu")
		(net "M_J_CPU0_SB_DQ<7>")
	)
	(segment
		(start 395.168628 -278.235918)
		(end 395.34973 -278.054816)
		(width 0.0889)
		(layer "In4.Cu")
		(net "M_J_CPU0_SB_DQ<7>")
	)
	(segment
		(start 418.542978 -290.410392)
		(end 421.634158 -290.410392)
		(width 0.14478)
		(layer "In4.Cu")
		(net "M_J_CPU0_SB_DQ<7>")
	)
	(segment
		(start 416.651948 -289.244532)
		(end 416.88766 -289.244532)
		(width 0.14478)
		(layer "In4.Cu")
		(net "M_J_CPU0_SB_DQ<7>")
	)
	(segment
		(start 432.759612 -289.706812)
		(end 432.759612 -289.326574)
		(width 0.14478)
		(layer "In4.Cu")
		(net "M_J_CPU0_SB_DQ<7>")
	)
	(segment
		(start 382.857756 -278.623522)
		(end 382.866138 -278.618696)
		(width 0.0889)
		(layer "In4.Cu")
		(net "M_J_CPU0_SB_DQ<7>")
	)
	(segment
		(start 395.34973 -278.054816)
		(end 395.959584 -278.054816)
		(width 0.0889)
		(layer "In4.Cu")
		(net "M_J_CPU0_SB_DQ<7>")
	)
	(segment
		(start 425.170854 -289.560254)
		(end 426.020738 -290.410138)
		(width 0.14478)
		(layer "In4.Cu")
		(net "M_J_CPU0_SB_DQ<7>")
	)
	(segment
		(start 386.043424 -278.618696)
		(end 386.051806 -278.623522)
		(width 0.0889)
		(layer "In4.Cu")
		(net "M_J_CPU0_SB_DQ<7>")
	)
	(segment
		(start 413.676592 -290.410392)
		(end 414.52673 -289.560254)
		(width 0.14478)
		(layer "In4.Cu")
		(net "M_J_CPU0_SB_DQ<7>")
	)
	(segment
		(start 414.52673 -289.560254)
		(end 415.233358 -289.560254)
		(width 0.14478)
		(layer "In4.Cu")
		(net "M_J_CPU0_SB_DQ<7>")
	)
	(segment
		(start 433.87264 -289.706812)
		(end 433.87264 -289.414204)
		(width 0.14478)
		(layer "In4.Cu")
		(net "M_J_CPU0_SB_DQ<7>")
	)
	(segment
		(start 430.221136 -289.560508)
		(end 432.056794 -289.560508)
		(width 0.14478)
		(layer "In4.Cu")
		(net "M_J_CPU0_SB_DQ<7>")
	)
	(segment
		(start 379.284738 -278.946102)
		(end 379.438916 -278.680672)
		(width 0.0889)
		(layer "In4.Cu")
		(net "M_J_CPU0_SB_DQ<7>")
	)
	(segment
		(start 380.037848 -278.623522)
		(end 380.04623 -278.618696)
		(width 0.0889)
		(layer "In4.Cu")
		(net "M_J_CPU0_SB_DQ<7>")
	)
	(segment
		(start 422.484296 -289.560254)
		(end 425.170854 -289.560254)
		(width 0.14478)
		(layer "In4.Cu")
		(net "M_J_CPU0_SB_DQ<7>")
	)
	(segment
		(start 391.317734 -278.623522)
		(end 391.326116 -278.618696)
		(width 0.0889)
		(layer "In4.Cu")
		(net "M_J_CPU0_SB_DQ<7>")
	)
	(arc
		(start 388.506208 -278.618696)
		(mid 388.689716 -278.573202)
		(end 388.871968 -278.623522)
		(width 0.0889)
		(layer "In4.Cu")
		(net "M_J_CPU0_SB_DQ<7>")
	)
	(arc
		(start 389.43788 -278.623522)
		(mid 389.624824 -278.573267)
		(end 389.811768 -278.623522)
		(width 0.0889)
		(layer "In4.Cu")
		(net "M_J_CPU0_SB_DQ<7>")
	)
	(arc
		(start 385.677664 -278.623522)
		(mid 385.859915 -278.573172)
		(end 386.043424 -278.618696)
		(width 0.0889)
		(layer "In4.Cu")
		(net "M_J_CPU0_SB_DQ<7>")
	)
	(arc
		(start 380.977902 -278.623522)
		(mid 381.164846 -278.573267)
		(end 381.35179 -278.623522)
		(width 0.0889)
		(layer "In4.Cu")
		(net "M_J_CPU0_SB_DQ<7>")
	)
	(arc
		(start 383.231898 -278.623522)
		(mid 383.514854 -278.699699)
		(end 383.79781 -278.623522)
		(width 0.0889)
		(layer "In4.Cu")
		(net "M_J_CPU0_SB_DQ<7>")
	)
	(arc
		(start 381.35179 -278.623522)
		(mid 381.634746 -278.699699)
		(end 381.917702 -278.623522)
		(width 0.0889)
		(layer "In4.Cu")
		(net "M_J_CPU0_SB_DQ<7>")
	)
	(arc
		(start 392.632692 -278.623522)
		(mid 392.91212 -278.699688)
		(end 393.192508 -278.627078)
		(width 0.0889)
		(layer "In4.Cu")
		(net "M_J_CPU0_SB_DQ<7>")
	)
	(arc
		(start 382.866138 -278.618696)
		(mid 383.049646 -278.573202)
		(end 383.231898 -278.623522)
		(width 0.0889)
		(layer "In4.Cu")
		(net "M_J_CPU0_SB_DQ<7>")
	)
	(arc
		(start 386.051806 -278.623522)
		(mid 386.334762 -278.699699)
		(end 386.617718 -278.623522)
		(width 0.0889)
		(layer "In4.Cu")
		(net "M_J_CPU0_SB_DQ<7>")
	)
	(arc
		(start 390.37768 -278.623522)
		(mid 390.559931 -278.573172)
		(end 390.74344 -278.618696)
		(width 0.0889)
		(layer "In4.Cu")
		(net "M_J_CPU0_SB_DQ<7>")
	)
	(arc
		(start 382.291844 -278.623522)
		(mid 382.5748 -278.699699)
		(end 382.857756 -278.623522)
		(width 0.0889)
		(layer "In4.Cu")
		(net "M_J_CPU0_SB_DQ<7>")
	)
	(arc
		(start 384.737864 -278.623522)
		(mid 384.924808 -278.573267)
		(end 385.111752 -278.623522)
		(width 0.0889)
		(layer "In4.Cu")
		(net "M_J_CPU0_SB_DQ<7>")
	)
	(arc
		(start 390.751822 -278.623522)
		(mid 391.034778 -278.699699)
		(end 391.317734 -278.623522)
		(width 0.0889)
		(layer "In4.Cu")
		(net "M_J_CPU0_SB_DQ<7>")
	)
	(arc
		(start 381.917702 -278.623522)
		(mid 382.099953 -278.573172)
		(end 382.283462 -278.618696)
		(width 0.0889)
		(layer "In4.Cu")
		(net "M_J_CPU0_SB_DQ<7>")
	)
	(arc
		(start 391.70229 -278.629618)
		(mid 391.980976 -278.699838)
		(end 392.258042 -278.623522)
		(width 0.0889)
		(layer "In4.Cu")
		(net "M_J_CPU0_SB_DQ<7>")
	)
	(arc
		(start 380.04623 -278.618696)
		(mid 380.229738 -278.573202)
		(end 380.41199 -278.623522)
		(width 0.0889)
		(layer "In4.Cu")
		(net "M_J_CPU0_SB_DQ<7>")
	)
	(arc
		(start 384.171952 -278.623522)
		(mid 384.454908 -278.699699)
		(end 384.737864 -278.623522)
		(width 0.0889)
		(layer "In4.Cu")
		(net "M_J_CPU0_SB_DQ<7>")
	)
	(arc
		(start 389.811768 -278.623522)
		(mid 390.094724 -278.699699)
		(end 390.37768 -278.623522)
		(width 0.0889)
		(layer "In4.Cu")
		(net "M_J_CPU0_SB_DQ<7>")
	)
	(arc
		(start 385.111752 -278.623522)
		(mid 385.394708 -278.699699)
		(end 385.677664 -278.623522)
		(width 0.0889)
		(layer "In4.Cu")
		(net "M_J_CPU0_SB_DQ<7>")
	)
	(arc
		(start 379.535182 -278.655272)
		(mid 379.790247 -278.698623)
		(end 380.037848 -278.623522)
		(width 0.0889)
		(layer "In4.Cu")
		(net "M_J_CPU0_SB_DQ<7>")
	)
	(arc
		(start 386.617718 -278.623522)
		(mid 386.799969 -278.573172)
		(end 386.983478 -278.618696)
		(width 0.0889)
		(layer "In4.Cu")
		(net "M_J_CPU0_SB_DQ<7>")
	)
	(arc
		(start 380.41199 -278.623522)
		(mid 380.694946 -278.699699)
		(end 380.977902 -278.623522)
		(width 0.0889)
		(layer "In4.Cu")
		(net "M_J_CPU0_SB_DQ<7>")
	)
	(arc
		(start 392.258042 -278.623522)
		(mid 392.440547 -278.573045)
		(end 392.62431 -278.618696)
		(width 0.0889)
		(layer "In4.Cu")
		(net "M_J_CPU0_SB_DQ<7>")
	)
	(arc
		(start 391.326116 -278.618696)
		(mid 391.509624 -278.573202)
		(end 391.691876 -278.623522)
		(width 0.0889)
		(layer "In4.Cu")
		(net "M_J_CPU0_SB_DQ<7>")
	)
	(arc
		(start 383.806192 -278.618696)
		(mid 383.9897 -278.573202)
		(end 384.171952 -278.623522)
		(width 0.0889)
		(layer "In4.Cu")
		(net "M_J_CPU0_SB_DQ<7>")
	)
	(arc
		(start 387.931914 -278.623522)
		(mid 388.21487 -278.699699)
		(end 388.497826 -278.623522)
		(width 0.0889)
		(layer "In4.Cu")
		(net "M_J_CPU0_SB_DQ<7>")
	)
	(arc
		(start 387.566154 -278.618696)
		(mid 387.749662 -278.573202)
		(end 387.931914 -278.623522)
		(width 0.0889)
		(layer "In4.Cu")
		(net "M_J_CPU0_SB_DQ<7>")
	)
	(arc
		(start 388.871968 -278.623522)
		(mid 389.154924 -278.699699)
		(end 389.43788 -278.623522)
		(width 0.0889)
		(layer "In4.Cu")
		(net "M_J_CPU0_SB_DQ<7>")
	)
	(arc
		(start 386.99186 -278.623522)
		(mid 387.274816 -278.699699)
		(end 387.557772 -278.623522)
		(width 0.0889)
		(layer "In4.Cu")
		(net "M_J_CPU0_SB_DQ<7>")
	)
	(segment
		(start 380.22784 -277.870158)
		(end 380.694946 -278.136096)
		(width 0.10668)
		(layer "F.Cu")
		(net "M_J_CPU0_SB_DQ<6>")
	)
	(segment
		(start 421.634158 -288.71037)
		(end 422.484296 -287.860232)
		(width 0.14478)
		(layer "In4.Cu")
		(net "M_J_CPU0_SB_DQ<6>")
	)
	(segment
		(start 410.821886 -287.271206)
		(end 411.013402 -287.462722)
		(width 0.14478)
		(layer "In4.Cu")
		(net "M_J_CPU0_SB_DQ<6>")
	)
	(segment
		(start 407.57094 -284.710632)
		(end 407.780998 -284.500574)
		(width 0.14478)
		(layer "In4.Cu")
		(net "M_J_CPU0_SB_DQ<6>")
	)
	(segment
		(start 408.051254 -284.500574)
		(end 408.24277 -284.69209)
		(width 0.14478)
		(layer "In4.Cu")
		(net "M_J_CPU0_SB_DQ<6>")
	)
	(segment
		(start 408.24277 -284.962346)
		(end 408.032712 -285.172404)
		(width 0.14478)
		(layer "In4.Cu")
		(net "M_J_CPU0_SB_DQ<6>")
	)
	(segment
		(start 409.418028 -286.55772)
		(end 409.628086 -286.347662)
		(width 0.14478)
		(layer "In4.Cu")
		(net "M_J_CPU0_SB_DQ<6>")
	)
	(segment
		(start 408.956256 -286.095948)
		(end 408.956256 -286.366204)
		(width 0.14478)
		(layer "In4.Cu")
		(net "M_J_CPU0_SB_DQ<6>")
	)
	(segment
		(start 409.147772 -286.55772)
		(end 409.418028 -286.55772)
		(width 0.14478)
		(layer "In4.Cu")
		(net "M_J_CPU0_SB_DQ<6>")
	)
	(segment
		(start 409.166314 -285.88589)
		(end 408.956256 -286.095948)
		(width 0.14478)
		(layer "In4.Cu")
		(net "M_J_CPU0_SB_DQ<6>")
	)
	(segment
		(start 383.693416 -277.80869)
		(end 383.701798 -277.813516)
		(width 0.0889)
		(layer "In4.Cu")
		(net "M_J_CPU0_SB_DQ<6>")
	)
	(segment
		(start 411.013402 -287.732978)
		(end 410.803344 -287.943036)
		(width 0.14478)
		(layer "In4.Cu")
		(net "M_J_CPU0_SB_DQ<6>")
	)
	(segment
		(start 408.24277 -284.69209)
		(end 408.24277 -284.962346)
		(width 0.14478)
		(layer "In4.Cu")
		(net "M_J_CPU0_SB_DQ<6>")
	)
	(segment
		(start 410.803344 -288.213292)
		(end 411.300422 -288.71037)
		(width 0.14478)
		(layer "In4.Cu")
		(net "M_J_CPU0_SB_DQ<6>")
	)
	(segment
		(start 409.8798 -287.019492)
		(end 409.8798 -287.289748)
		(width 0.14478)
		(layer "In4.Cu")
		(net "M_J_CPU0_SB_DQ<6>")
	)
	(segment
		(start 411.300422 -288.71037)
		(end 414.090104 -288.71037)
		(width 0.14478)
		(layer "In4.Cu")
		(net "M_J_CPU0_SB_DQ<6>")
	)
	(segment
		(start 392.161014 -277.81377)
		(end 392.182604 -277.826216)
		(width 0.0889)
		(layer "In4.Cu")
		(net "M_J_CPU0_SB_DQ<6>")
	)
	(segment
		(start 408.974798 -285.424118)
		(end 409.166314 -285.615634)
		(width 0.14478)
		(layer "In4.Cu")
		(net "M_J_CPU0_SB_DQ<6>")
	)
	(segment
		(start 411.013402 -287.462722)
		(end 411.013402 -287.732978)
		(width 0.14478)
		(layer "In4.Cu")
		(net "M_J_CPU0_SB_DQ<6>")
	)
	(segment
		(start 409.628086 -286.347662)
		(end 409.898342 -286.347662)
		(width 0.14478)
		(layer "In4.Cu")
		(net "M_J_CPU0_SB_DQ<6>")
	)
	(segment
		(start 380.694946 -278.136096)
		(end 380.84887 -277.870666)
		(width 0.0889)
		(layer "In4.Cu")
		(net "M_J_CPU0_SB_DQ<6>")
	)
	(segment
		(start 381.447802 -277.813516)
		(end 381.456184 -277.80869)
		(width 0.0889)
		(layer "In4.Cu")
		(net "M_J_CPU0_SB_DQ<6>")
	)
	(segment
		(start 418.078412 -287.860232)
		(end 418.92855 -288.71037)
		(width 0.14478)
		(layer "In4.Cu")
		(net "M_J_CPU0_SB_DQ<6>")
	)
	(segment
		(start 410.803344 -287.943036)
		(end 410.803344 -288.213292)
		(width 0.14478)
		(layer "In4.Cu")
		(net "M_J_CPU0_SB_DQ<6>")
	)
	(segment
		(start 410.55163 -287.271206)
		(end 410.821886 -287.271206)
		(width 0.14478)
		(layer "In4.Cu")
		(net "M_J_CPU0_SB_DQ<6>")
	)
	(segment
		(start 408.704542 -285.424118)
		(end 408.974798 -285.424118)
		(width 0.14478)
		(layer "In4.Cu")
		(net "M_J_CPU0_SB_DQ<6>")
	)
	(segment
		(start 392.725402 -277.813516)
		(end 392.744198 -277.802594)
		(width 0.0889)
		(layer "In4.Cu")
		(net "M_J_CPU0_SB_DQ<6>")
	)
	(segment
		(start 408.032712 -285.172404)
		(end 408.032712 -285.44266)
		(width 0.14478)
		(layer "In4.Cu")
		(net "M_J_CPU0_SB_DQ<6>")
	)
	(segment
		(start 409.8798 -287.289748)
		(end 410.071316 -287.481264)
		(width 0.14478)
		(layer "In4.Cu")
		(net "M_J_CPU0_SB_DQ<6>")
	)
	(segment
		(start 422.484296 -287.860232)
		(end 425.42079 -287.860232)
		(width 0.14478)
		(layer "In4.Cu")
		(net "M_J_CPU0_SB_DQ<6>")
	)
	(segment
		(start 399.735548 -277.145496)
		(end 407.300684 -284.710632)
		(width 0.14478)
		(layer "In4.Cu")
		(net "M_J_CPU0_SB_DQ<6>")
	)
	(segment
		(start 409.898342 -286.347662)
		(end 410.089858 -286.539178)
		(width 0.14478)
		(layer "In4.Cu")
		(net "M_J_CPU0_SB_DQ<6>")
	)
	(segment
		(start 407.780998 -284.500574)
		(end 408.051254 -284.500574)
		(width 0.14478)
		(layer "In4.Cu")
		(net "M_J_CPU0_SB_DQ<6>")
	)
	(segment
		(start 410.341572 -287.481264)
		(end 410.55163 -287.271206)
		(width 0.14478)
		(layer "In4.Cu")
		(net "M_J_CPU0_SB_DQ<6>")
	)
	(segment
		(start 386.147818 -277.813516)
		(end 386.1562 -277.80869)
		(width 0.0889)
		(layer "In4.Cu")
		(net "M_J_CPU0_SB_DQ<6>")
	)
	(segment
		(start 393.977114 -277.395432)
		(end 393.977114 -277.31847)
		(width 0.0889)
		(layer "In4.Cu")
		(net "M_J_CPU0_SB_DQ<6>")
	)
	(segment
		(start 414.940242 -287.860232)
		(end 418.078412 -287.860232)
		(width 0.14478)
		(layer "In4.Cu")
		(net "M_J_CPU0_SB_DQ<6>")
	)
	(segment
		(start 434.575204 -287.860232)
		(end 435.000146 -288.285174)
		(width 0.14478)
		(layer "In4.Cu")
		(net "M_J_CPU0_SB_DQ<6>")
	)
	(segment
		(start 414.090104 -288.71037)
		(end 414.940242 -287.860232)
		(width 0.14478)
		(layer "In4.Cu")
		(net "M_J_CPU0_SB_DQ<6>")
	)
	(segment
		(start 425.42079 -287.860232)
		(end 426.270674 -288.710116)
		(width 0.14478)
		(layer "In4.Cu")
		(net "M_J_CPU0_SB_DQ<6>")
	)
	(segment
		(start 389.90778 -277.813516)
		(end 389.916162 -277.80869)
		(width 0.0889)
		(layer "In4.Cu")
		(net "M_J_CPU0_SB_DQ<6>")
	)
	(segment
		(start 426.270674 -288.710116)
		(end 429.062134 -288.710116)
		(width 0.14478)
		(layer "In4.Cu")
		(net "M_J_CPU0_SB_DQ<6>")
	)
	(segment
		(start 380.84887 -277.870666)
		(end 380.944882 -277.845266)
		(width 0.0889)
		(layer "In4.Cu")
		(net "M_J_CPU0_SB_DQ<6>")
	)
	(segment
		(start 392.140948 -277.80234)
		(end 392.161014 -277.81377)
		(width 0.0889)
		(layer "In4.Cu")
		(net "M_J_CPU0_SB_DQ<6>")
	)
	(segment
		(start 408.224228 -285.634176)
		(end 408.494484 -285.634176)
		(width 0.14478)
		(layer "In4.Cu")
		(net "M_J_CPU0_SB_DQ<6>")
	)
	(segment
		(start 409.166314 -285.615634)
		(end 409.166314 -285.88589)
		(width 0.14478)
		(layer "In4.Cu")
		(net "M_J_CPU0_SB_DQ<6>")
	)
	(segment
		(start 407.300684 -284.710632)
		(end 407.57094 -284.710632)
		(width 0.14478)
		(layer "In4.Cu")
		(net "M_J_CPU0_SB_DQ<6>")
	)
	(segment
		(start 408.956256 -286.366204)
		(end 409.147772 -286.55772)
		(width 0.14478)
		(layer "In4.Cu")
		(net "M_J_CPU0_SB_DQ<6>")
	)
	(segment
		(start 410.089858 -286.809434)
		(end 409.8798 -287.019492)
		(width 0.14478)
		(layer "In4.Cu")
		(net "M_J_CPU0_SB_DQ<6>")
	)
	(segment
		(start 429.062134 -288.710116)
		(end 429.912018 -287.860232)
		(width 0.14478)
		(layer "In4.Cu")
		(net "M_J_CPU0_SB_DQ<6>")
	)
	(segment
		(start 388.393432 -277.80869)
		(end 388.401814 -277.813516)
		(width 0.0889)
		(layer "In4.Cu")
		(net "M_J_CPU0_SB_DQ<6>")
	)
	(segment
		(start 395.938502 -277.145496)
		(end 399.735548 -277.145496)
		(width 0.14478)
		(layer "In4.Cu")
		(net "M_J_CPU0_SB_DQ<6>")
	)
	(segment
		(start 429.912018 -287.860232)
		(end 434.575204 -287.860232)
		(width 0.14478)
		(layer "In4.Cu")
		(net "M_J_CPU0_SB_DQ<6>")
	)
	(segment
		(start 385.207764 -277.813516)
		(end 385.216146 -277.80869)
		(width 0.0889)
		(layer "In4.Cu")
		(net "M_J_CPU0_SB_DQ<6>")
	)
	(segment
		(start 408.494484 -285.634176)
		(end 408.704542 -285.424118)
		(width 0.14478)
		(layer "In4.Cu")
		(net "M_J_CPU0_SB_DQ<6>")
	)
	(segment
		(start 418.92855 -288.71037)
		(end 421.634158 -288.71037)
		(width 0.14478)
		(layer "In4.Cu")
		(net "M_J_CPU0_SB_DQ<6>")
	)
	(segment
		(start 408.032712 -285.44266)
		(end 408.224228 -285.634176)
		(width 0.14478)
		(layer "In4.Cu")
		(net "M_J_CPU0_SB_DQ<6>")
	)
	(segment
		(start 410.071316 -287.481264)
		(end 410.341572 -287.481264)
		(width 0.14478)
		(layer "In4.Cu")
		(net "M_J_CPU0_SB_DQ<6>")
	)
	(segment
		(start 393.977114 -277.31847)
		(end 394.150088 -277.145496)
		(width 0.0889)
		(layer "In4.Cu")
		(net "M_J_CPU0_SB_DQ<6>")
	)
	(segment
		(start 389.333486 -277.80869)
		(end 389.341868 -277.813516)
		(width 0.0889)
		(layer "In4.Cu")
		(net "M_J_CPU0_SB_DQ<6>")
	)
	(segment
		(start 384.63347 -277.80869)
		(end 384.641852 -277.813516)
		(width 0.0889)
		(layer "In4.Cu")
		(net "M_J_CPU0_SB_DQ<6>")
	)
	(segment
		(start 394.150088 -277.145496)
		(end 395.938502 -277.145496)
		(width 0.0889)
		(layer "In4.Cu")
		(net "M_J_CPU0_SB_DQ<6>")
	)
	(segment
		(start 410.089858 -286.539178)
		(end 410.089858 -286.809434)
		(width 0.14478)
		(layer "In4.Cu")
		(net "M_J_CPU0_SB_DQ<6>")
	)
	(arc
		(start 380.944882 -277.845266)
		(mid 381.20009 -277.888743)
		(end 381.447802 -277.813516)
		(width 0.0889)
		(layer "In4.Cu")
		(net "M_J_CPU0_SB_DQ<6>")
	)
	(arc
		(start 383.701798 -277.813516)
		(mid 383.984754 -277.889693)
		(end 384.26771 -277.813516)
		(width 0.0889)
		(layer "In4.Cu")
		(net "M_J_CPU0_SB_DQ<6>")
	)
	(arc
		(start 393.384786 -277.896828)
		(mid 393.618985 -277.858611)
		(end 393.818872 -277.730712)
		(width 0.0889)
		(layer "In4.Cu")
		(net "M_J_CPU0_SB_DQ<6>")
	)
	(arc
		(start 391.221722 -277.813516)
		(mid 391.504678 -277.889693)
		(end 391.787634 -277.813516)
		(width 0.0889)
		(layer "In4.Cu")
		(net "M_J_CPU0_SB_DQ<6>")
	)
	(arc
		(start 389.916162 -277.80869)
		(mid 390.09967 -277.763196)
		(end 390.281922 -277.813516)
		(width 0.0889)
		(layer "In4.Cu")
		(net "M_J_CPU0_SB_DQ<6>")
	)
	(arc
		(start 389.341868 -277.813516)
		(mid 389.624824 -277.889693)
		(end 389.90778 -277.813516)
		(width 0.0889)
		(layer "In4.Cu")
		(net "M_J_CPU0_SB_DQ<6>")
	)
	(arc
		(start 384.26771 -277.813516)
		(mid 384.449961 -277.763166)
		(end 384.63347 -277.80869)
		(width 0.0889)
		(layer "In4.Cu")
		(net "M_J_CPU0_SB_DQ<6>")
	)
	(arc
		(start 383.327656 -277.813516)
		(mid 383.509907 -277.763166)
		(end 383.693416 -277.80869)
		(width 0.0889)
		(layer "In4.Cu")
		(net "M_J_CPU0_SB_DQ<6>")
	)
	(arc
		(start 387.46176 -277.813516)
		(mid 387.744716 -277.889693)
		(end 388.027672 -277.813516)
		(width 0.0889)
		(layer "In4.Cu")
		(net "M_J_CPU0_SB_DQ<6>")
	)
	(arc
		(start 385.581906 -277.813516)
		(mid 385.864862 -277.889693)
		(end 386.147818 -277.813516)
		(width 0.0889)
		(layer "In4.Cu")
		(net "M_J_CPU0_SB_DQ<6>")
	)
	(arc
		(start 390.847834 -277.813516)
		(mid 391.034778 -277.763261)
		(end 391.221722 -277.813516)
		(width 0.0889)
		(layer "In4.Cu")
		(net "M_J_CPU0_SB_DQ<6>")
	)
	(arc
		(start 382.387856 -277.813516)
		(mid 382.5748 -277.763261)
		(end 382.761744 -277.813516)
		(width 0.0889)
		(layer "In4.Cu")
		(net "M_J_CPU0_SB_DQ<6>")
	)
	(arc
		(start 381.456184 -277.80869)
		(mid 381.639692 -277.763196)
		(end 381.821944 -277.813516)
		(width 0.0889)
		(layer "In4.Cu")
		(net "M_J_CPU0_SB_DQ<6>")
	)
	(arc
		(start 388.401814 -277.813516)
		(mid 388.68477 -277.889693)
		(end 388.967726 -277.813516)
		(width 0.0889)
		(layer "In4.Cu")
		(net "M_J_CPU0_SB_DQ<6>")
	)
	(arc
		(start 392.182604 -277.826216)
		(mid 392.455633 -277.889535)
		(end 392.725402 -277.813516)
		(width 0.0889)
		(layer "In4.Cu")
		(net "M_J_CPU0_SB_DQ<6>")
	)
	(arc
		(start 386.1562 -277.80869)
		(mid 386.339708 -277.763196)
		(end 386.52196 -277.813516)
		(width 0.0889)
		(layer "In4.Cu")
		(net "M_J_CPU0_SB_DQ<6>")
	)
	(arc
		(start 382.761744 -277.813516)
		(mid 383.0447 -277.889693)
		(end 383.327656 -277.813516)
		(width 0.0889)
		(layer "In4.Cu")
		(net "M_J_CPU0_SB_DQ<6>")
	)
	(arc
		(start 385.216146 -277.80869)
		(mid 385.399654 -277.763196)
		(end 385.581906 -277.813516)
		(width 0.0889)
		(layer "In4.Cu")
		(net "M_J_CPU0_SB_DQ<6>")
	)
	(arc
		(start 386.52196 -277.813516)
		(mid 386.804916 -277.889693)
		(end 387.087872 -277.813516)
		(width 0.0889)
		(layer "In4.Cu")
		(net "M_J_CPU0_SB_DQ<6>")
	)
	(arc
		(start 387.087872 -277.813516)
		(mid 387.274816 -277.763261)
		(end 387.46176 -277.813516)
		(width 0.0889)
		(layer "In4.Cu")
		(net "M_J_CPU0_SB_DQ<6>")
	)
	(arc
		(start 393.10056 -277.813516)
		(mid 393.237587 -277.87252)
		(end 393.384786 -277.896828)
		(width 0.0889)
		(layer "In4.Cu")
		(net "M_J_CPU0_SB_DQ<6>")
	)
	(arc
		(start 390.281922 -277.813516)
		(mid 390.564878 -277.889693)
		(end 390.847834 -277.813516)
		(width 0.0889)
		(layer "In4.Cu")
		(net "M_J_CPU0_SB_DQ<6>")
	)
	(arc
		(start 392.744198 -277.802594)
		(mid 392.923769 -277.762777)
		(end 393.10056 -277.813516)
		(width 0.0889)
		(layer "In4.Cu")
		(net "M_J_CPU0_SB_DQ<6>")
	)
	(arc
		(start 391.787634 -277.813516)
		(mid 391.962873 -277.763445)
		(end 392.140948 -277.80234)
		(width 0.0889)
		(layer "In4.Cu")
		(net "M_J_CPU0_SB_DQ<6>")
	)
	(arc
		(start 384.641852 -277.813516)
		(mid 384.924808 -277.889693)
		(end 385.207764 -277.813516)
		(width 0.0889)
		(layer "In4.Cu")
		(net "M_J_CPU0_SB_DQ<6>")
	)
	(arc
		(start 393.818872 -277.730712)
		(mid 393.927144 -277.576833)
		(end 393.977114 -277.395432)
		(width 0.0889)
		(layer "In4.Cu")
		(net "M_J_CPU0_SB_DQ<6>")
	)
	(arc
		(start 381.821944 -277.813516)
		(mid 382.1049 -277.889693)
		(end 382.387856 -277.813516)
		(width 0.0889)
		(layer "In4.Cu")
		(net "M_J_CPU0_SB_DQ<6>")
	)
	(arc
		(start 388.027672 -277.813516)
		(mid 388.209923 -277.763166)
		(end 388.393432 -277.80869)
		(width 0.0889)
		(layer "In4.Cu")
		(net "M_J_CPU0_SB_DQ<6>")
	)
	(arc
		(start 388.967726 -277.813516)
		(mid 389.149977 -277.763166)
		(end 389.333486 -277.80869)
		(width 0.0889)
		(layer "In4.Cu")
		(net "M_J_CPU0_SB_DQ<6>")
	)
	(segment
		(start 379.28804 -277.870158)
		(end 379.754892 -278.136096)
		(width 0.10668)
		(layer "F.Cu")
		(net "M_J_CPU0_SB_DQ<5>")
	)
	(segment
		(start 394.703554 -277.51151)
		(end 395.214094 -277.51151)
		(width 0.0889)
		(layer "In4.Cu")
		(net "M_J_CPU0_SB_DQ<5>")
	)
	(segment
		(start 379.754892 -278.136096)
		(end 379.600714 -278.401526)
		(width 0.0889)
		(layer "In4.Cu")
		(net "M_J_CPU0_SB_DQ<5>")
	)
	(segment
		(start 379.600714 -278.401526)
		(end 379.623066 -278.484838)
		(width 0.0889)
		(layer "In4.Cu")
		(net "M_J_CPU0_SB_DQ<5>")
	)
	(segment
		(start 422.937178 -288.71037)
		(end 424.634406 -288.71037)
		(width 0.14478)
		(layer "In4.Cu")
		(net "M_J_CPU0_SB_DQ<5>")
	)
	(segment
		(start 392.718036 -278.45258)
		(end 392.72845 -278.458676)
		(width 0.0889)
		(layer "In4.Cu")
		(net "M_J_CPU0_SB_DQ<5>")
	)
	(segment
		(start 428.90821 -289.560254)
		(end 430.960784 -288.710116)
		(width 0.14478)
		(layer "In4.Cu")
		(net "M_J_CPU0_SB_DQ<5>")
	)
	(segment
		(start 389.90778 -278.458676)
		(end 389.916162 -278.463502)
		(width 0.0889)
		(layer "In4.Cu")
		(net "M_J_CPU0_SB_DQ<5>")
	)
	(segment
		(start 384.63347 -278.463502)
		(end 384.641852 -278.458676)
		(width 0.0889)
		(layer "In4.Cu")
		(net "M_J_CPU0_SB_DQ<5>")
	)
	(segment
		(start 426.686218 -289.560254)
		(end 428.90821 -289.560254)
		(width 0.14478)
		(layer "In4.Cu")
		(net "M_J_CPU0_SB_DQ<5>")
	)
	(segment
		(start 388.393432 -278.463502)
		(end 388.401814 -278.458676)
		(width 0.0889)
		(layer "In4.Cu")
		(net "M_J_CPU0_SB_DQ<5>")
	)
	(segment
		(start 420.885366 -289.560254)
		(end 422.937178 -288.71037)
		(width 0.14478)
		(layer "In4.Cu")
		(net "M_J_CPU0_SB_DQ<5>")
	)
	(segment
		(start 385.207764 -278.458676)
		(end 385.216146 -278.463502)
		(width 0.0889)
		(layer "In4.Cu")
		(net "M_J_CPU0_SB_DQ<5>")
	)
	(segment
		(start 424.634406 -288.71037)
		(end 426.686218 -289.560254)
		(width 0.14478)
		(layer "In4.Cu")
		(net "M_J_CPU0_SB_DQ<5>")
	)
	(segment
		(start 413.32658 -289.560254)
		(end 415.378392 -288.71037)
		(width 0.14478)
		(layer "In4.Cu")
		(net "M_J_CPU0_SB_DQ<5>")
	)
	(segment
		(start 383.693416 -278.463502)
		(end 383.701798 -278.458676)
		(width 0.0889)
		(layer "In4.Cu")
		(net "M_J_CPU0_SB_DQ<5>")
	)
	(segment
		(start 395.868398 -277.600156)
		(end 399.554192 -277.600156)
		(width 0.14478)
		(layer "In4.Cu")
		(net "M_J_CPU0_SB_DQ<5>")
	)
	(segment
		(start 393.086082 -278.46782)
		(end 394.703554 -277.51151)
		(width 0.0889)
		(layer "In4.Cu")
		(net "M_J_CPU0_SB_DQ<5>")
	)
	(segment
		(start 379.933454 -278.463502)
		(end 379.941836 -278.458676)
		(width 0.0889)
		(layer "In4.Cu")
		(net "M_J_CPU0_SB_DQ<5>")
	)
	(segment
		(start 430.960784 -288.710116)
		(end 433.564538 -288.710116)
		(width 0.14478)
		(layer "In4.Cu")
		(net "M_J_CPU0_SB_DQ<5>")
	)
	(segment
		(start 380.873508 -278.463502)
		(end 380.88189 -278.458676)
		(width 0.0889)
		(layer "In4.Cu")
		(net "M_J_CPU0_SB_DQ<5>")
	)
	(segment
		(start 386.147818 -278.458676)
		(end 386.1562 -278.463502)
		(width 0.0889)
		(layer "In4.Cu")
		(net "M_J_CPU0_SB_DQ<5>")
	)
	(segment
		(start 436.964836 -288.71037)
		(end 439.100214 -289.135058)
		(width 0.14478)
		(layer "In4.Cu")
		(net "M_J_CPU0_SB_DQ<5>")
	)
	(segment
		(start 391.787634 -278.458676)
		(end 391.796016 -278.463502)
		(width 0.0889)
		(layer "In4.Cu")
		(net "M_J_CPU0_SB_DQ<5>")
	)
	(segment
		(start 433.564538 -288.710116)
		(end 433.564792 -288.71037)
		(width 0.14478)
		(layer "In4.Cu")
		(net "M_J_CPU0_SB_DQ<5>")
	)
	(segment
		(start 419.06698 -289.560254)
		(end 420.885366 -289.560254)
		(width 0.14478)
		(layer "In4.Cu")
		(net "M_J_CPU0_SB_DQ<5>")
	)
	(segment
		(start 417.015168 -288.71037)
		(end 419.06698 -289.560254)
		(width 0.14478)
		(layer "In4.Cu")
		(net "M_J_CPU0_SB_DQ<5>")
	)
	(segment
		(start 381.447802 -278.458676)
		(end 381.456184 -278.463502)
		(width 0.0889)
		(layer "In4.Cu")
		(net "M_J_CPU0_SB_DQ<5>")
	)
	(segment
		(start 395.30274 -277.600156)
		(end 395.868398 -277.600156)
		(width 0.0889)
		(layer "In4.Cu")
		(net "M_J_CPU0_SB_DQ<5>")
	)
	(segment
		(start 389.333486 -278.463502)
		(end 389.341868 -278.458676)
		(width 0.0889)
		(layer "In4.Cu")
		(net "M_J_CPU0_SB_DQ<5>")
	)
	(segment
		(start 433.564792 -288.71037)
		(end 436.964836 -288.71037)
		(width 0.14478)
		(layer "In4.Cu")
		(net "M_J_CPU0_SB_DQ<5>")
	)
	(segment
		(start 415.378392 -288.71037)
		(end 417.015168 -288.71037)
		(width 0.14478)
		(layer "In4.Cu")
		(net "M_J_CPU0_SB_DQ<5>")
	)
	(segment
		(start 399.554192 -277.600156)
		(end 411.51429 -289.560254)
		(width 0.14478)
		(layer "In4.Cu")
		(net "M_J_CPU0_SB_DQ<5>")
	)
	(segment
		(start 411.51429 -289.560254)
		(end 413.32658 -289.560254)
		(width 0.14478)
		(layer "In4.Cu")
		(net "M_J_CPU0_SB_DQ<5>")
	)
	(segment
		(start 395.214094 -277.51151)
		(end 395.30274 -277.600156)
		(width 0.0889)
		(layer "In4.Cu")
		(net "M_J_CPU0_SB_DQ<5>")
	)
	(arc
		(start 388.027672 -278.458676)
		(mid 388.209923 -278.509026)
		(end 388.393432 -278.463502)
		(width 0.0889)
		(layer "In4.Cu")
		(net "M_J_CPU0_SB_DQ<5>")
	)
	(arc
		(start 387.46176 -278.458676)
		(mid 387.744716 -278.382499)
		(end 388.027672 -278.458676)
		(width 0.0889)
		(layer "In4.Cu")
		(net "M_J_CPU0_SB_DQ<5>")
	)
	(arc
		(start 387.087872 -278.458676)
		(mid 387.274816 -278.508931)
		(end 387.46176 -278.458676)
		(width 0.0889)
		(layer "In4.Cu")
		(net "M_J_CPU0_SB_DQ<5>")
	)
	(arc
		(start 385.216146 -278.463502)
		(mid 385.399654 -278.508996)
		(end 385.581906 -278.458676)
		(width 0.0889)
		(layer "In4.Cu")
		(net "M_J_CPU0_SB_DQ<5>")
	)
	(arc
		(start 380.88189 -278.458676)
		(mid 381.164846 -278.382499)
		(end 381.447802 -278.458676)
		(width 0.0889)
		(layer "In4.Cu")
		(net "M_J_CPU0_SB_DQ<5>")
	)
	(arc
		(start 386.1562 -278.463502)
		(mid 386.339708 -278.508996)
		(end 386.52196 -278.458676)
		(width 0.0889)
		(layer "In4.Cu")
		(net "M_J_CPU0_SB_DQ<5>")
	)
	(arc
		(start 391.221722 -278.458676)
		(mid 391.504678 -278.382499)
		(end 391.787634 -278.458676)
		(width 0.0889)
		(layer "In4.Cu")
		(net "M_J_CPU0_SB_DQ<5>")
	)
	(arc
		(start 383.701798 -278.458676)
		(mid 383.984754 -278.382499)
		(end 384.26771 -278.458676)
		(width 0.0889)
		(layer "In4.Cu")
		(net "M_J_CPU0_SB_DQ<5>")
	)
	(arc
		(start 382.761744 -278.458676)
		(mid 383.0447 -278.382499)
		(end 383.327656 -278.458676)
		(width 0.0889)
		(layer "In4.Cu")
		(net "M_J_CPU0_SB_DQ<5>")
	)
	(arc
		(start 388.401814 -278.458676)
		(mid 388.68477 -278.382499)
		(end 388.967726 -278.458676)
		(width 0.0889)
		(layer "In4.Cu")
		(net "M_J_CPU0_SB_DQ<5>")
	)
	(arc
		(start 388.967726 -278.458676)
		(mid 389.149977 -278.509026)
		(end 389.333486 -278.463502)
		(width 0.0889)
		(layer "In4.Cu")
		(net "M_J_CPU0_SB_DQ<5>")
	)
	(arc
		(start 383.327656 -278.458676)
		(mid 383.509907 -278.509026)
		(end 383.693416 -278.463502)
		(width 0.0889)
		(layer "In4.Cu")
		(net "M_J_CPU0_SB_DQ<5>")
	)
	(arc
		(start 392.72845 -278.458676)
		(mid 392.9061 -278.508936)
		(end 393.086082 -278.46782)
		(width 0.0889)
		(layer "In4.Cu")
		(net "M_J_CPU0_SB_DQ<5>")
	)
	(arc
		(start 384.26771 -278.458676)
		(mid 384.449961 -278.509026)
		(end 384.63347 -278.463502)
		(width 0.0889)
		(layer "In4.Cu")
		(net "M_J_CPU0_SB_DQ<5>")
	)
	(arc
		(start 390.847834 -278.458676)
		(mid 391.034778 -278.508931)
		(end 391.221722 -278.458676)
		(width 0.0889)
		(layer "In4.Cu")
		(net "M_J_CPU0_SB_DQ<5>")
	)
	(arc
		(start 382.387856 -278.458676)
		(mid 382.5748 -278.508931)
		(end 382.761744 -278.458676)
		(width 0.0889)
		(layer "In4.Cu")
		(net "M_J_CPU0_SB_DQ<5>")
	)
	(arc
		(start 379.941836 -278.458676)
		(mid 380.224792 -278.382499)
		(end 380.507748 -278.458676)
		(width 0.0889)
		(layer "In4.Cu")
		(net "M_J_CPU0_SB_DQ<5>")
	)
	(arc
		(start 379.623066 -278.484838)
		(mid 379.780576 -278.508036)
		(end 379.933454 -278.463502)
		(width 0.0889)
		(layer "In4.Cu")
		(net "M_J_CPU0_SB_DQ<5>")
	)
	(arc
		(start 389.341868 -278.458676)
		(mid 389.624824 -278.382499)
		(end 389.90778 -278.458676)
		(width 0.0889)
		(layer "In4.Cu")
		(net "M_J_CPU0_SB_DQ<5>")
	)
	(arc
		(start 389.916162 -278.463502)
		(mid 390.09967 -278.508996)
		(end 390.281922 -278.458676)
		(width 0.0889)
		(layer "In4.Cu")
		(net "M_J_CPU0_SB_DQ<5>")
	)
	(arc
		(start 385.581906 -278.458676)
		(mid 385.864862 -278.382499)
		(end 386.147818 -278.458676)
		(width 0.0889)
		(layer "In4.Cu")
		(net "M_J_CPU0_SB_DQ<5>")
	)
	(arc
		(start 381.456184 -278.463502)
		(mid 381.639692 -278.508996)
		(end 381.821944 -278.458676)
		(width 0.0889)
		(layer "In4.Cu")
		(net "M_J_CPU0_SB_DQ<5>")
	)
	(arc
		(start 386.52196 -278.458676)
		(mid 386.804916 -278.382499)
		(end 387.087872 -278.458676)
		(width 0.0889)
		(layer "In4.Cu")
		(net "M_J_CPU0_SB_DQ<5>")
	)
	(arc
		(start 380.507748 -278.458676)
		(mid 380.689999 -278.509026)
		(end 380.873508 -278.463502)
		(width 0.0889)
		(layer "In4.Cu")
		(net "M_J_CPU0_SB_DQ<5>")
	)
	(arc
		(start 391.796016 -278.463502)
		(mid 391.979778 -278.509118)
		(end 392.162284 -278.458676)
		(width 0.0889)
		(layer "In4.Cu")
		(net "M_J_CPU0_SB_DQ<5>")
	)
	(arc
		(start 384.641852 -278.458676)
		(mid 384.924808 -278.382499)
		(end 385.207764 -278.458676)
		(width 0.0889)
		(layer "In4.Cu")
		(net "M_J_CPU0_SB_DQ<5>")
	)
	(arc
		(start 392.162284 -278.458676)
		(mid 392.439351 -278.382405)
		(end 392.718036 -278.45258)
		(width 0.0889)
		(layer "In4.Cu")
		(net "M_J_CPU0_SB_DQ<5>")
	)
	(arc
		(start 390.281922 -278.458676)
		(mid 390.564878 -278.382499)
		(end 390.847834 -278.458676)
		(width 0.0889)
		(layer "In4.Cu")
		(net "M_J_CPU0_SB_DQ<5>")
	)
	(arc
		(start 381.821944 -278.458676)
		(mid 382.1049 -278.382499)
		(end 382.387856 -278.458676)
		(width 0.0889)
		(layer "In4.Cu")
		(net "M_J_CPU0_SB_DQ<5>")
	)
	(segment
		(start 380.697994 -277.060152)
		(end 381.164846 -277.32609)
		(width 0.10668)
		(layer "F.Cu")
		(net "M_J_CPU0_SB_DQ<4>")
	)
	(segment
		(start 386.043424 -277.653496)
		(end 386.051806 -277.64867)
		(width 0.0889)
		(layer "In4.Cu")
		(net "M_J_CPU0_SB_DQ<4>")
	)
	(segment
		(start 382.283462 -277.653496)
		(end 382.291844 -277.64867)
		(width 0.0889)
		(layer "In4.Cu")
		(net "M_J_CPU0_SB_DQ<4>")
	)
	(segment
		(start 383.79781 -277.64867)
		(end 383.806192 -277.653496)
		(width 0.0889)
		(layer "In4.Cu")
		(net "M_J_CPU0_SB_DQ<4>")
	)
	(segment
		(start 395.310614 -276.71141)
		(end 395.331188 -276.690836)
		(width 0.0889)
		(layer "In4.Cu")
		(net "M_J_CPU0_SB_DQ<4>")
	)
	(segment
		(start 391.317734 -277.64867)
		(end 391.326116 -277.653496)
		(width 0.0889)
		(layer "In4.Cu")
		(net "M_J_CPU0_SB_DQ<4>")
	)
	(segment
		(start 388.497826 -277.64867)
		(end 388.506208 -277.653496)
		(width 0.0889)
		(layer "In4.Cu")
		(net "M_J_CPU0_SB_DQ<4>")
	)
	(segment
		(start 393.703048 -277.529036)
		(end 393.745974 -277.425404)
		(width 0.0889)
		(layer "In4.Cu")
		(net "M_J_CPU0_SB_DQ<4>")
	)
	(segment
		(start 390.74344 -277.653496)
		(end 390.751822 -277.64867)
		(width 0.0889)
		(layer "In4.Cu")
		(net "M_J_CPU0_SB_DQ<4>")
	)
	(segment
		(start 438.684924 -287.019746)
		(end 439.100214 -287.435036)
		(width 0.14478)
		(layer "In4.Cu")
		(net "M_J_CPU0_SB_DQ<4>")
	)
	(segment
		(start 382.857756 -277.64867)
		(end 382.866138 -277.653496)
		(width 0.0889)
		(layer "In4.Cu")
		(net "M_J_CPU0_SB_DQ<4>")
	)
	(segment
		(start 386.983478 -277.653496)
		(end 386.99186 -277.64867)
		(width 0.0889)
		(layer "In4.Cu")
		(net "M_J_CPU0_SB_DQ<4>")
	)
	(segment
		(start 415.032952 -287.010348)
		(end 417.90112 -287.010348)
		(width 0.14478)
		(layer "In4.Cu")
		(net "M_J_CPU0_SB_DQ<4>")
	)
	(segment
		(start 395.331188 -276.690836)
		(end 395.99362 -276.690836)
		(width 0.0889)
		(layer "In4.Cu")
		(net "M_J_CPU0_SB_DQ<4>")
	)
	(segment
		(start 417.90112 -287.010348)
		(end 418.760656 -287.869884)
		(width 0.14478)
		(layer "In4.Cu")
		(net "M_J_CPU0_SB_DQ<4>")
	)
	(segment
		(start 392.62939 -277.64867)
		(end 392.652758 -277.634954)
		(width 0.0889)
		(layer "In4.Cu")
		(net "M_J_CPU0_SB_DQ<4>")
	)
	(segment
		(start 407.039572 -283.813504)
		(end 408.025092 -283.813504)
		(width 0.14478)
		(layer "In4.Cu")
		(net "M_J_CPU0_SB_DQ<4>")
	)
	(segment
		(start 429.198532 -287.86963)
		(end 430.048416 -287.019746)
		(width 0.14478)
		(layer "In4.Cu")
		(net "M_J_CPU0_SB_DQ<4>")
	)
	(segment
		(start 418.760656 -287.869884)
		(end 421.71747 -287.869884)
		(width 0.14478)
		(layer "In4.Cu")
		(net "M_J_CPU0_SB_DQ<4>")
	)
	(segment
		(start 392.234674 -277.63597)
		(end 392.256264 -277.648416)
		(width 0.0889)
		(layer "In4.Cu")
		(net "M_J_CPU0_SB_DQ<4>")
	)
	(segment
		(start 412.07182 -287.860232)
		(end 414.183068 -287.860232)
		(width 0.14478)
		(layer "In4.Cu")
		(net "M_J_CPU0_SB_DQ<4>")
	)
	(segment
		(start 430.048416 -287.019746)
		(end 438.684924 -287.019746)
		(width 0.14478)
		(layer "In4.Cu")
		(net "M_J_CPU0_SB_DQ<4>")
	)
	(segment
		(start 381.164846 -277.32609)
		(end 381.010922 -277.59152)
		(width 0.0889)
		(layer "In4.Cu")
		(net "M_J_CPU0_SB_DQ<4>")
	)
	(segment
		(start 421.71747 -287.869884)
		(end 422.567608 -287.019746)
		(width 0.14478)
		(layer "In4.Cu")
		(net "M_J_CPU0_SB_DQ<4>")
	)
	(segment
		(start 394.187934 -276.71141)
		(end 395.310614 -276.71141)
		(width 0.0889)
		(layer "In4.Cu")
		(net "M_J_CPU0_SB_DQ<4>")
	)
	(segment
		(start 395.99362 -276.690836)
		(end 399.916904 -276.690836)
		(width 0.14478)
		(layer "In4.Cu")
		(net "M_J_CPU0_SB_DQ<4>")
	)
	(segment
		(start 387.557772 -277.64867)
		(end 387.566154 -277.653496)
		(width 0.0889)
		(layer "In4.Cu")
		(net "M_J_CPU0_SB_DQ<4>")
	)
	(segment
		(start 393.543282 -277.664164)
		(end 393.570714 -277.648416)
		(width 0.0889)
		(layer "In4.Cu")
		(net "M_J_CPU0_SB_DQ<4>")
	)
	(segment
		(start 414.183068 -287.860232)
		(end 415.032952 -287.010348)
		(width 0.14478)
		(layer "In4.Cu")
		(net "M_J_CPU0_SB_DQ<4>")
	)
	(segment
		(start 408.025092 -283.813504)
		(end 412.07182 -287.860232)
		(width 0.14478)
		(layer "In4.Cu")
		(net "M_J_CPU0_SB_DQ<4>")
	)
	(segment
		(start 393.621006 -277.611078)
		(end 393.703048 -277.529036)
		(width 0.0889)
		(layer "In4.Cu")
		(net "M_J_CPU0_SB_DQ<4>")
	)
	(segment
		(start 392.256264 -277.648416)
		(end 392.274552 -277.65883)
		(width 0.0889)
		(layer "In4.Cu")
		(net "M_J_CPU0_SB_DQ<4>")
	)
	(segment
		(start 381.010922 -277.59152)
		(end 381.033274 -277.674832)
		(width 0.0889)
		(layer "In4.Cu")
		(net "M_J_CPU0_SB_DQ<4>")
	)
	(segment
		(start 422.567608 -287.019746)
		(end 425.390564 -287.019746)
		(width 0.14478)
		(layer "In4.Cu")
		(net "M_J_CPU0_SB_DQ<4>")
	)
	(segment
		(start 393.570714 -277.648416)
		(end 393.621006 -277.611078)
		(width 0.0889)
		(layer "In4.Cu")
		(net "M_J_CPU0_SB_DQ<4>")
	)
	(segment
		(start 393.745974 -277.15337)
		(end 394.187934 -276.71141)
		(width 0.0889)
		(layer "In4.Cu")
		(net "M_J_CPU0_SB_DQ<4>")
	)
	(segment
		(start 399.916904 -276.690836)
		(end 407.039572 -283.813504)
		(width 0.14478)
		(layer "In4.Cu")
		(net "M_J_CPU0_SB_DQ<4>")
	)
	(segment
		(start 426.240448 -287.86963)
		(end 429.198532 -287.86963)
		(width 0.14478)
		(layer "In4.Cu")
		(net "M_J_CPU0_SB_DQ<4>")
	)
	(segment
		(start 425.390564 -287.019746)
		(end 426.240448 -287.86963)
		(width 0.14478)
		(layer "In4.Cu")
		(net "M_J_CPU0_SB_DQ<4>")
	)
	(segment
		(start 393.745974 -277.425404)
		(end 393.745974 -277.15337)
		(width 0.0889)
		(layer "In4.Cu")
		(net "M_J_CPU0_SB_DQ<4>")
	)
	(arc
		(start 386.99186 -277.64867)
		(mid 387.274816 -277.572493)
		(end 387.557772 -277.64867)
		(width 0.0889)
		(layer "In4.Cu")
		(net "M_J_CPU0_SB_DQ<4>")
	)
	(arc
		(start 383.806192 -277.653496)
		(mid 383.9897 -277.69899)
		(end 384.171952 -277.64867)
		(width 0.0889)
		(layer "In4.Cu")
		(net "M_J_CPU0_SB_DQ<4>")
	)
	(arc
		(start 381.033274 -277.674832)
		(mid 381.195463 -277.697567)
		(end 381.35179 -277.64867)
		(width 0.0889)
		(layer "In4.Cu")
		(net "M_J_CPU0_SB_DQ<4>")
	)
	(arc
		(start 389.811768 -277.64867)
		(mid 390.094724 -277.572493)
		(end 390.37768 -277.64867)
		(width 0.0889)
		(layer "In4.Cu")
		(net "M_J_CPU0_SB_DQ<4>")
	)
	(arc
		(start 381.35179 -277.64867)
		(mid 381.634746 -277.572493)
		(end 381.917702 -277.64867)
		(width 0.0889)
		(layer "In4.Cu")
		(net "M_J_CPU0_SB_DQ<4>")
	)
	(arc
		(start 381.917702 -277.64867)
		(mid 382.099953 -277.69902)
		(end 382.283462 -277.653496)
		(width 0.0889)
		(layer "In4.Cu")
		(net "M_J_CPU0_SB_DQ<4>")
	)
	(arc
		(start 386.617718 -277.64867)
		(mid 386.799969 -277.69902)
		(end 386.983478 -277.653496)
		(width 0.0889)
		(layer "In4.Cu")
		(net "M_J_CPU0_SB_DQ<4>")
	)
	(arc
		(start 390.751822 -277.64867)
		(mid 391.034778 -277.572493)
		(end 391.317734 -277.64867)
		(width 0.0889)
		(layer "In4.Cu")
		(net "M_J_CPU0_SB_DQ<4>")
	)
	(arc
		(start 392.274552 -277.65883)
		(mid 392.453273 -277.698753)
		(end 392.62939 -277.64867)
		(width 0.0889)
		(layer "In4.Cu")
		(net "M_J_CPU0_SB_DQ<4>")
	)
	(arc
		(start 385.111752 -277.64867)
		(mid 385.394708 -277.572493)
		(end 385.677664 -277.64867)
		(width 0.0889)
		(layer "In4.Cu")
		(net "M_J_CPU0_SB_DQ<4>")
	)
	(arc
		(start 385.677664 -277.64867)
		(mid 385.859915 -277.69902)
		(end 386.043424 -277.653496)
		(width 0.0889)
		(layer "In4.Cu")
		(net "M_J_CPU0_SB_DQ<4>")
	)
	(arc
		(start 391.691876 -277.64867)
		(mid 391.961645 -277.572647)
		(end 392.234674 -277.63597)
		(width 0.0889)
		(layer "In4.Cu")
		(net "M_J_CPU0_SB_DQ<4>")
	)
	(arc
		(start 392.652758 -277.634954)
		(mid 392.926412 -277.572011)
		(end 393.196572 -277.64867)
		(width 0.0889)
		(layer "In4.Cu")
		(net "M_J_CPU0_SB_DQ<4>")
	)
	(arc
		(start 393.196572 -277.64867)
		(mid 393.368027 -277.699187)
		(end 393.543282 -277.664164)
		(width 0.0889)
		(layer "In4.Cu")
		(net "M_J_CPU0_SB_DQ<4>")
	)
	(arc
		(start 382.291844 -277.64867)
		(mid 382.5748 -277.572493)
		(end 382.857756 -277.64867)
		(width 0.0889)
		(layer "In4.Cu")
		(net "M_J_CPU0_SB_DQ<4>")
	)
	(arc
		(start 384.171952 -277.64867)
		(mid 384.454908 -277.572493)
		(end 384.737864 -277.64867)
		(width 0.0889)
		(layer "In4.Cu")
		(net "M_J_CPU0_SB_DQ<4>")
	)
	(arc
		(start 383.231898 -277.64867)
		(mid 383.514854 -277.572493)
		(end 383.79781 -277.64867)
		(width 0.0889)
		(layer "In4.Cu")
		(net "M_J_CPU0_SB_DQ<4>")
	)
	(arc
		(start 388.506208 -277.653496)
		(mid 388.689716 -277.69899)
		(end 388.871968 -277.64867)
		(width 0.0889)
		(layer "In4.Cu")
		(net "M_J_CPU0_SB_DQ<4>")
	)
	(arc
		(start 386.051806 -277.64867)
		(mid 386.334762 -277.572493)
		(end 386.617718 -277.64867)
		(width 0.0889)
		(layer "In4.Cu")
		(net "M_J_CPU0_SB_DQ<4>")
	)
	(arc
		(start 384.737864 -277.64867)
		(mid 384.924808 -277.698925)
		(end 385.111752 -277.64867)
		(width 0.0889)
		(layer "In4.Cu")
		(net "M_J_CPU0_SB_DQ<4>")
	)
	(arc
		(start 388.871968 -277.64867)
		(mid 389.154924 -277.572493)
		(end 389.43788 -277.64867)
		(width 0.0889)
		(layer "In4.Cu")
		(net "M_J_CPU0_SB_DQ<4>")
	)
	(arc
		(start 387.566154 -277.653496)
		(mid 387.749662 -277.69899)
		(end 387.931914 -277.64867)
		(width 0.0889)
		(layer "In4.Cu")
		(net "M_J_CPU0_SB_DQ<4>")
	)
	(arc
		(start 390.37768 -277.64867)
		(mid 390.559931 -277.69902)
		(end 390.74344 -277.653496)
		(width 0.0889)
		(layer "In4.Cu")
		(net "M_J_CPU0_SB_DQ<4>")
	)
	(arc
		(start 382.866138 -277.653496)
		(mid 383.049646 -277.69899)
		(end 383.231898 -277.64867)
		(width 0.0889)
		(layer "In4.Cu")
		(net "M_J_CPU0_SB_DQ<4>")
	)
	(arc
		(start 387.931914 -277.64867)
		(mid 388.21487 -277.572493)
		(end 388.497826 -277.64867)
		(width 0.0889)
		(layer "In4.Cu")
		(net "M_J_CPU0_SB_DQ<4>")
	)
	(arc
		(start 389.43788 -277.64867)
		(mid 389.624824 -277.698925)
		(end 389.811768 -277.64867)
		(width 0.0889)
		(layer "In4.Cu")
		(net "M_J_CPU0_SB_DQ<4>")
	)
	(arc
		(start 391.326116 -277.653496)
		(mid 391.509624 -277.69899)
		(end 391.691876 -277.64867)
		(width 0.0889)
		(layer "In4.Cu")
		(net "M_J_CPU0_SB_DQ<4>")
	)
	(segment
		(start 378.817886 -275.44014)
		(end 379.284738 -275.706078)
		(width 0.10668)
		(layer "F.Cu")
		(net "M_J_CPU0_SB_DQ<3>")
	)
	(segment
		(start 422.330372 -283.600398)
		(end 425.63415 -283.600398)
		(width 0.14478)
		(layer "In4.Cu")
		(net "M_J_CPU0_SB_DQ<3>")
	)
	(segment
		(start 391.317734 -275.383498)
		(end 391.326116 -275.378672)
		(width 0.0889)
		(layer "In4.Cu")
		(net "M_J_CPU0_SB_DQ<3>")
	)
	(segment
		(start 402.557488 -276.088602)
		(end 402.719032 -276.250146)
		(width 0.14478)
		(layer "In4.Cu")
		(net "M_J_CPU0_SB_DQ<3>")
	)
	(segment
		(start 403.599396 -276.37867)
		(end 403.337776 -276.64029)
		(width 0.14478)
		(layer "In4.Cu")
		(net "M_J_CPU0_SB_DQ<3>")
	)
	(segment
		(start 390.74344 -275.378672)
		(end 390.751822 -275.383498)
		(width 0.0889)
		(layer "In4.Cu")
		(net "M_J_CPU0_SB_DQ<3>")
	)
	(segment
		(start 380.037848 -275.383498)
		(end 380.04623 -275.378672)
		(width 0.0889)
		(layer "In4.Cu")
		(net "M_J_CPU0_SB_DQ<3>")
	)
	(segment
		(start 393.332716 -275.343112)
		(end 393.431014 -275.316188)
		(width 0.0889)
		(layer "In4.Cu")
		(net "M_J_CPU0_SB_DQ<3>")
	)
	(segment
		(start 434.565552 -283.600398)
		(end 435.000146 -284.034992)
		(width 0.14478)
		(layer "In4.Cu")
		(net "M_J_CPU0_SB_DQ<3>")
	)
	(segment
		(start 402.03882 -274.818094)
		(end 401.7772 -275.079714)
		(width 0.14478)
		(layer "In4.Cu")
		(net "M_J_CPU0_SB_DQ<3>")
	)
	(segment
		(start 402.719032 -276.250146)
		(end 402.947632 -276.250146)
		(width 0.14478)
		(layer "In4.Cu")
		(net "M_J_CPU0_SB_DQ<3>")
	)
	(segment
		(start 388.497826 -275.383498)
		(end 388.506208 -275.378672)
		(width 0.0889)
		(layer "In4.Cu")
		(net "M_J_CPU0_SB_DQ<3>")
	)
	(segment
		(start 402.428964 -275.208238)
		(end 402.657564 -275.208238)
		(width 0.14478)
		(layer "In4.Cu")
		(net "M_J_CPU0_SB_DQ<3>")
	)
	(segment
		(start 401.752816 -274.30349)
		(end 402.03882 -274.589494)
		(width 0.14478)
		(layer "In4.Cu")
		(net "M_J_CPU0_SB_DQ<3>")
	)
	(segment
		(start 402.557488 -275.860002)
		(end 402.557488 -276.088602)
		(width 0.14478)
		(layer "In4.Cu")
		(net "M_J_CPU0_SB_DQ<3>")
	)
	(segment
		(start 386.983478 -275.378672)
		(end 386.99186 -275.383498)
		(width 0.0889)
		(layer "In4.Cu")
		(net "M_J_CPU0_SB_DQ<3>")
	)
	(segment
		(start 402.657564 -275.208238)
		(end 402.819108 -275.369782)
		(width 0.14478)
		(layer "In4.Cu")
		(net "M_J_CPU0_SB_DQ<3>")
	)
	(segment
		(start 403.72792 -277.030434)
		(end 403.98954 -276.768814)
		(width 0.14478)
		(layer "In4.Cu")
		(net "M_J_CPU0_SB_DQ<3>")
	)
	(segment
		(start 411.508956 -284.05963)
		(end 414.421066 -284.05963)
		(width 0.14478)
		(layer "In4.Cu")
		(net "M_J_CPU0_SB_DQ<3>")
	)
	(segment
		(start 391.691876 -275.383498)
		(end 391.70229 -275.389594)
		(width 0.0889)
		(layer "In4.Cu")
		(net "M_J_CPU0_SB_DQ<3>")
	)
	(segment
		(start 383.79781 -275.383498)
		(end 383.806192 -275.378672)
		(width 0.0889)
		(layer "In4.Cu")
		(net "M_J_CPU0_SB_DQ<3>")
	)
	(segment
		(start 393.87145 -275.133308)
		(end 393.95527 -275.077174)
		(width 0.0889)
		(layer "In4.Cu")
		(net "M_J_CPU0_SB_DQ<3>")
	)
	(segment
		(start 403.437852 -275.988526)
		(end 403.599396 -276.15007)
		(width 0.14478)
		(layer "In4.Cu")
		(net "M_J_CPU0_SB_DQ<3>")
	)
	(segment
		(start 392.62431 -275.378672)
		(end 392.632692 -275.383498)
		(width 0.0889)
		(layer "In4.Cu")
		(net "M_J_CPU0_SB_DQ<3>")
	)
	(segment
		(start 393.192508 -275.387054)
		(end 393.332716 -275.343112)
		(width 0.0889)
		(layer "In4.Cu")
		(net "M_J_CPU0_SB_DQ<3>")
	)
	(segment
		(start 429.08728 -284.450282)
		(end 429.937164 -283.600398)
		(width 0.14478)
		(layer "In4.Cu")
		(net "M_J_CPU0_SB_DQ<3>")
	)
	(segment
		(start 418.122608 -283.61005)
		(end 418.96284 -284.450282)
		(width 0.14478)
		(layer "In4.Cu")
		(net "M_J_CPU0_SB_DQ<3>")
	)
	(segment
		(start 429.937164 -283.600398)
		(end 434.565552 -283.600398)
		(width 0.14478)
		(layer "In4.Cu")
		(net "M_J_CPU0_SB_DQ<3>")
	)
	(segment
		(start 379.438916 -275.440648)
		(end 379.535182 -275.415248)
		(width 0.0889)
		(layer "In4.Cu")
		(net "M_J_CPU0_SB_DQ<3>")
	)
	(segment
		(start 379.284738 -275.706078)
		(end 379.438916 -275.440648)
		(width 0.0889)
		(layer "In4.Cu")
		(net "M_J_CPU0_SB_DQ<3>")
	)
	(segment
		(start 403.209252 -275.988526)
		(end 403.437852 -275.988526)
		(width 0.14478)
		(layer "In4.Cu")
		(net "M_J_CPU0_SB_DQ<3>")
	)
	(segment
		(start 382.857756 -275.383498)
		(end 382.866138 -275.378672)
		(width 0.0889)
		(layer "In4.Cu")
		(net "M_J_CPU0_SB_DQ<3>")
	)
	(segment
		(start 395.33449 -274.25777)
		(end 395.38021 -274.30349)
		(width 0.0889)
		(layer "In4.Cu")
		(net "M_J_CPU0_SB_DQ<3>")
	)
	(segment
		(start 395.38021 -274.30349)
		(end 395.902688 -274.30349)
		(width 0.0889)
		(layer "In4.Cu")
		(net "M_J_CPU0_SB_DQ<3>")
	)
	(segment
		(start 403.337776 -276.64029)
		(end 403.337776 -276.86889)
		(width 0.14478)
		(layer "In4.Cu")
		(net "M_J_CPU0_SB_DQ<3>")
	)
	(segment
		(start 387.557772 -275.383498)
		(end 387.566154 -275.378672)
		(width 0.0889)
		(layer "In4.Cu")
		(net "M_J_CPU0_SB_DQ<3>")
	)
	(segment
		(start 402.819108 -275.598382)
		(end 402.557488 -275.860002)
		(width 0.14478)
		(layer "In4.Cu")
		(net "M_J_CPU0_SB_DQ<3>")
	)
	(segment
		(start 421.480488 -284.450282)
		(end 422.330372 -283.600398)
		(width 0.14478)
		(layer "In4.Cu")
		(net "M_J_CPU0_SB_DQ<3>")
	)
	(segment
		(start 418.96284 -284.450282)
		(end 421.480488 -284.450282)
		(width 0.14478)
		(layer "In4.Cu")
		(net "M_J_CPU0_SB_DQ<3>")
	)
	(segment
		(start 402.819108 -275.369782)
		(end 402.819108 -275.598382)
		(width 0.14478)
		(layer "In4.Cu")
		(net "M_J_CPU0_SB_DQ<3>")
	)
	(segment
		(start 402.03882 -274.589494)
		(end 402.03882 -274.818094)
		(width 0.14478)
		(layer "In4.Cu")
		(net "M_J_CPU0_SB_DQ<3>")
	)
	(segment
		(start 404.21814 -276.768814)
		(end 411.508956 -284.05963)
		(width 0.14478)
		(layer "In4.Cu")
		(net "M_J_CPU0_SB_DQ<3>")
	)
	(segment
		(start 393.431014 -275.316188)
		(end 393.87145 -275.133308)
		(width 0.0889)
		(layer "In4.Cu")
		(net "M_J_CPU0_SB_DQ<3>")
	)
	(segment
		(start 403.337776 -276.86889)
		(end 403.49932 -277.030434)
		(width 0.14478)
		(layer "In4.Cu")
		(net "M_J_CPU0_SB_DQ<3>")
	)
	(segment
		(start 402.167344 -275.469858)
		(end 402.428964 -275.208238)
		(width 0.14478)
		(layer "In4.Cu")
		(net "M_J_CPU0_SB_DQ<3>")
	)
	(segment
		(start 395.902688 -274.30349)
		(end 401.752816 -274.30349)
		(width 0.14478)
		(layer "In4.Cu")
		(net "M_J_CPU0_SB_DQ<3>")
	)
	(segment
		(start 426.484034 -284.450282)
		(end 429.08728 -284.450282)
		(width 0.14478)
		(layer "In4.Cu")
		(net "M_J_CPU0_SB_DQ<3>")
	)
	(segment
		(start 393.95527 -275.077174)
		(end 394.774674 -274.25777)
		(width 0.0889)
		(layer "In4.Cu")
		(net "M_J_CPU0_SB_DQ<3>")
	)
	(segment
		(start 425.63415 -283.600398)
		(end 426.484034 -284.450282)
		(width 0.14478)
		(layer "In4.Cu")
		(net "M_J_CPU0_SB_DQ<3>")
	)
	(segment
		(start 402.947632 -276.250146)
		(end 403.209252 -275.988526)
		(width 0.14478)
		(layer "In4.Cu")
		(net "M_J_CPU0_SB_DQ<3>")
	)
	(segment
		(start 403.49932 -277.030434)
		(end 403.72792 -277.030434)
		(width 0.14478)
		(layer "In4.Cu")
		(net "M_J_CPU0_SB_DQ<3>")
	)
	(segment
		(start 414.870646 -283.61005)
		(end 418.122608 -283.61005)
		(width 0.14478)
		(layer "In4.Cu")
		(net "M_J_CPU0_SB_DQ<3>")
	)
	(segment
		(start 401.938744 -275.469858)
		(end 402.167344 -275.469858)
		(width 0.14478)
		(layer "In4.Cu")
		(net "M_J_CPU0_SB_DQ<3>")
	)
	(segment
		(start 403.599396 -276.15007)
		(end 403.599396 -276.37867)
		(width 0.14478)
		(layer "In4.Cu")
		(net "M_J_CPU0_SB_DQ<3>")
	)
	(segment
		(start 414.421066 -284.05963)
		(end 414.870646 -283.61005)
		(width 0.14478)
		(layer "In4.Cu")
		(net "M_J_CPU0_SB_DQ<3>")
	)
	(segment
		(start 401.7772 -275.308314)
		(end 401.938744 -275.469858)
		(width 0.14478)
		(layer "In4.Cu")
		(net "M_J_CPU0_SB_DQ<3>")
	)
	(segment
		(start 386.043424 -275.378672)
		(end 386.051806 -275.383498)
		(width 0.0889)
		(layer "In4.Cu")
		(net "M_J_CPU0_SB_DQ<3>")
	)
	(segment
		(start 403.98954 -276.768814)
		(end 404.21814 -276.768814)
		(width 0.14478)
		(layer "In4.Cu")
		(net "M_J_CPU0_SB_DQ<3>")
	)
	(segment
		(start 382.283462 -275.378672)
		(end 382.291844 -275.383498)
		(width 0.0889)
		(layer "In4.Cu")
		(net "M_J_CPU0_SB_DQ<3>")
	)
	(segment
		(start 401.7772 -275.079714)
		(end 401.7772 -275.308314)
		(width 0.14478)
		(layer "In4.Cu")
		(net "M_J_CPU0_SB_DQ<3>")
	)
	(segment
		(start 394.774674 -274.25777)
		(end 395.33449 -274.25777)
		(width 0.0889)
		(layer "In4.Cu")
		(net "M_J_CPU0_SB_DQ<3>")
	)
	(arc
		(start 386.99186 -275.383498)
		(mid 387.274816 -275.459675)
		(end 387.557772 -275.383498)
		(width 0.0889)
		(layer "In4.Cu")
		(net "M_J_CPU0_SB_DQ<3>")
	)
	(arc
		(start 384.171952 -275.383498)
		(mid 384.454908 -275.459675)
		(end 384.737864 -275.383498)
		(width 0.0889)
		(layer "In4.Cu")
		(net "M_J_CPU0_SB_DQ<3>")
	)
	(arc
		(start 388.871968 -275.383498)
		(mid 389.154924 -275.459675)
		(end 389.43788 -275.383498)
		(width 0.0889)
		(layer "In4.Cu")
		(net "M_J_CPU0_SB_DQ<3>")
	)
	(arc
		(start 387.931914 -275.383498)
		(mid 388.21487 -275.459675)
		(end 388.497826 -275.383498)
		(width 0.0889)
		(layer "In4.Cu")
		(net "M_J_CPU0_SB_DQ<3>")
	)
	(arc
		(start 391.70229 -275.389594)
		(mid 391.980976 -275.459814)
		(end 392.258042 -275.383498)
		(width 0.0889)
		(layer "In4.Cu")
		(net "M_J_CPU0_SB_DQ<3>")
	)
	(arc
		(start 380.977902 -275.383498)
		(mid 381.164846 -275.333243)
		(end 381.35179 -275.383498)
		(width 0.0889)
		(layer "In4.Cu")
		(net "M_J_CPU0_SB_DQ<3>")
	)
	(arc
		(start 390.751822 -275.383498)
		(mid 391.034778 -275.459675)
		(end 391.317734 -275.383498)
		(width 0.0889)
		(layer "In4.Cu")
		(net "M_J_CPU0_SB_DQ<3>")
	)
	(arc
		(start 382.866138 -275.378672)
		(mid 383.049646 -275.333178)
		(end 383.231898 -275.383498)
		(width 0.0889)
		(layer "In4.Cu")
		(net "M_J_CPU0_SB_DQ<3>")
	)
	(arc
		(start 383.231898 -275.383498)
		(mid 383.514854 -275.459675)
		(end 383.79781 -275.383498)
		(width 0.0889)
		(layer "In4.Cu")
		(net "M_J_CPU0_SB_DQ<3>")
	)
	(arc
		(start 386.617718 -275.383498)
		(mid 386.799969 -275.333148)
		(end 386.983478 -275.378672)
		(width 0.0889)
		(layer "In4.Cu")
		(net "M_J_CPU0_SB_DQ<3>")
	)
	(arc
		(start 392.258042 -275.383498)
		(mid 392.440547 -275.333021)
		(end 392.62431 -275.378672)
		(width 0.0889)
		(layer "In4.Cu")
		(net "M_J_CPU0_SB_DQ<3>")
	)
	(arc
		(start 389.811768 -275.383498)
		(mid 390.094724 -275.459675)
		(end 390.37768 -275.383498)
		(width 0.0889)
		(layer "In4.Cu")
		(net "M_J_CPU0_SB_DQ<3>")
	)
	(arc
		(start 379.535182 -275.415248)
		(mid 379.790247 -275.458599)
		(end 380.037848 -275.383498)
		(width 0.0889)
		(layer "In4.Cu")
		(net "M_J_CPU0_SB_DQ<3>")
	)
	(arc
		(start 387.566154 -275.378672)
		(mid 387.749662 -275.333178)
		(end 387.931914 -275.383498)
		(width 0.0889)
		(layer "In4.Cu")
		(net "M_J_CPU0_SB_DQ<3>")
	)
	(arc
		(start 392.632692 -275.383498)
		(mid 392.91212 -275.459664)
		(end 393.192508 -275.387054)
		(width 0.0889)
		(layer "In4.Cu")
		(net "M_J_CPU0_SB_DQ<3>")
	)
	(arc
		(start 382.291844 -275.383498)
		(mid 382.5748 -275.459675)
		(end 382.857756 -275.383498)
		(width 0.0889)
		(layer "In4.Cu")
		(net "M_J_CPU0_SB_DQ<3>")
	)
	(arc
		(start 380.41199 -275.383498)
		(mid 380.694946 -275.459675)
		(end 380.977902 -275.383498)
		(width 0.0889)
		(layer "In4.Cu")
		(net "M_J_CPU0_SB_DQ<3>")
	)
	(arc
		(start 391.326116 -275.378672)
		(mid 391.509624 -275.333178)
		(end 391.691876 -275.383498)
		(width 0.0889)
		(layer "In4.Cu")
		(net "M_J_CPU0_SB_DQ<3>")
	)
	(arc
		(start 381.35179 -275.383498)
		(mid 381.634746 -275.459675)
		(end 381.917702 -275.383498)
		(width 0.0889)
		(layer "In4.Cu")
		(net "M_J_CPU0_SB_DQ<3>")
	)
	(arc
		(start 386.051806 -275.383498)
		(mid 386.334762 -275.459675)
		(end 386.617718 -275.383498)
		(width 0.0889)
		(layer "In4.Cu")
		(net "M_J_CPU0_SB_DQ<3>")
	)
	(arc
		(start 381.917702 -275.383498)
		(mid 382.099953 -275.333148)
		(end 382.283462 -275.378672)
		(width 0.0889)
		(layer "In4.Cu")
		(net "M_J_CPU0_SB_DQ<3>")
	)
	(arc
		(start 385.677664 -275.383498)
		(mid 385.859915 -275.333148)
		(end 386.043424 -275.378672)
		(width 0.0889)
		(layer "In4.Cu")
		(net "M_J_CPU0_SB_DQ<3>")
	)
	(arc
		(start 388.506208 -275.378672)
		(mid 388.689716 -275.333178)
		(end 388.871968 -275.383498)
		(width 0.0889)
		(layer "In4.Cu")
		(net "M_J_CPU0_SB_DQ<3>")
	)
	(arc
		(start 385.111752 -275.383498)
		(mid 385.394708 -275.459675)
		(end 385.677664 -275.383498)
		(width 0.0889)
		(layer "In4.Cu")
		(net "M_J_CPU0_SB_DQ<3>")
	)
	(arc
		(start 380.04623 -275.378672)
		(mid 380.229738 -275.333178)
		(end 380.41199 -275.383498)
		(width 0.0889)
		(layer "In4.Cu")
		(net "M_J_CPU0_SB_DQ<3>")
	)
	(arc
		(start 390.37768 -275.383498)
		(mid 390.559931 -275.333148)
		(end 390.74344 -275.378672)
		(width 0.0889)
		(layer "In4.Cu")
		(net "M_J_CPU0_SB_DQ<3>")
	)
	(arc
		(start 389.43788 -275.383498)
		(mid 389.624824 -275.333243)
		(end 389.811768 -275.383498)
		(width 0.0889)
		(layer "In4.Cu")
		(net "M_J_CPU0_SB_DQ<3>")
	)
	(arc
		(start 384.737864 -275.383498)
		(mid 384.924808 -275.333243)
		(end 385.111752 -275.383498)
		(width 0.0889)
		(layer "In4.Cu")
		(net "M_J_CPU0_SB_DQ<3>")
	)
	(arc
		(start 383.806192 -275.378672)
		(mid 383.9897 -275.333178)
		(end 384.171952 -275.383498)
		(width 0.0889)
		(layer "In4.Cu")
		(net "M_J_CPU0_SB_DQ<3>")
	)
	(segment
		(start 380.697994 -293.260018)
		(end 381.164846 -293.525956)
		(width 0.10668)
		(layer "F.Cu")
		(net "M_J_CPU0_SB_DQ<31>")
	)
	(segment
		(start 402.739606 -312.036968)
		(end 402.901658 -312.19902)
		(width 0.14478)
		(layer "In4.Cu")
		(net "M_J_CPU0_SB_DQ<31>")
	)
	(segment
		(start 392.12266 -293.990522)
		(end 392.161776 -294.013382)
		(width 0.0889)
		(layer "In4.Cu")
		(net "M_J_CPU0_SB_DQ<31>")
	)
	(segment
		(start 401.341082 -310.866536)
		(end 401.197318 -311.010046)
		(width 0.14478)
		(layer "In4.Cu")
		(net "M_J_CPU0_SB_DQ<31>")
	)
	(segment
		(start 401.587462 -311.40019)
		(end 401.730972 -311.25668)
		(width 0.14478)
		(layer "In4.Cu")
		(net "M_J_CPU0_SB_DQ<31>")
	)
	(segment
		(start 405.242522 -314.539884)
		(end 405.242522 -314.767976)
		(width 0.14478)
		(layer "In4.Cu")
		(net "M_J_CPU0_SB_DQ<31>")
	)
	(segment
		(start 404.31847 -314.35929)
		(end 404.480522 -314.521342)
		(width 0.14478)
		(layer "In4.Cu")
		(net "M_J_CPU0_SB_DQ<31>")
	)
	(segment
		(start 399.636742 -309.677562)
		(end 399.798794 -309.839614)
		(width 0.14478)
		(layer "In4.Cu")
		(net "M_J_CPU0_SB_DQ<31>")
	)
	(segment
		(start 411.40253 -318.46012)
		(end 434.575204 -318.46012)
		(width 0.14478)
		(layer "In4.Cu")
		(net "M_J_CPU0_SB_DQ<31>")
	)
	(segment
		(start 400.579082 -310.619902)
		(end 400.807174 -310.619902)
		(width 0.14478)
		(layer "In4.Cu")
		(net "M_J_CPU0_SB_DQ<31>")
	)
	(segment
		(start 393.055348 -303.096168)
		(end 399.018506 -309.059326)
		(width 0.14478)
		(layer "In4.Cu")
		(net "M_J_CPU0_SB_DQ<31>")
	)
	(segment
		(start 387.557772 -293.203376)
		(end 387.566154 -293.19855)
		(width 0.0889)
		(layer "In4.Cu")
		(net "M_J_CPU0_SB_DQ<31>")
	)
	(segment
		(start 401.959318 -311.25668)
		(end 402.12137 -311.418732)
		(width 0.14478)
		(layer "In4.Cu")
		(net "M_J_CPU0_SB_DQ<31>")
	)
	(segment
		(start 400.41703 -310.45785)
		(end 400.579082 -310.619902)
		(width 0.14478)
		(layer "In4.Cu")
		(net "M_J_CPU0_SB_DQ<31>")
	)
	(segment
		(start 399.390108 -308.915816)
		(end 399.618454 -308.915816)
		(width 0.14478)
		(layer "In4.Cu")
		(net "M_J_CPU0_SB_DQ<31>")
	)
	(segment
		(start 402.36775 -312.180478)
		(end 402.51126 -312.036968)
		(width 0.14478)
		(layer "In4.Cu")
		(net "M_J_CPU0_SB_DQ<31>")
	)
	(segment
		(start 400.41703 -310.229758)
		(end 400.41703 -310.45785)
		(width 0.14478)
		(layer "In4.Cu")
		(net "M_J_CPU0_SB_DQ<31>")
	)
	(segment
		(start 392.161776 -294.013382)
		(end 392.192256 -294.031162)
		(width 0.0889)
		(layer "In4.Cu")
		(net "M_J_CPU0_SB_DQ<31>")
	)
	(segment
		(start 403.291548 -312.817256)
		(end 403.519894 -312.817256)
		(width 0.14478)
		(layer "In4.Cu")
		(net "M_J_CPU0_SB_DQ<31>")
	)
	(segment
		(start 399.246598 -309.059326)
		(end 399.390108 -308.915816)
		(width 0.14478)
		(layer "In4.Cu")
		(net "M_J_CPU0_SB_DQ<31>")
	)
	(segment
		(start 400.560794 -309.858156)
		(end 400.560794 -310.086248)
		(width 0.14478)
		(layer "In4.Cu")
		(net "M_J_CPU0_SB_DQ<31>")
	)
	(segment
		(start 406.976834 -317.017654)
		(end 409.588208 -318.099186)
		(width 0.14478)
		(layer "In4.Cu")
		(net "M_J_CPU0_SB_DQ<31>")
	)
	(segment
		(start 401.17903 -310.476392)
		(end 401.341082 -310.638444)
		(width 0.14478)
		(layer "In4.Cu")
		(net "M_J_CPU0_SB_DQ<31>")
	)
	(segment
		(start 403.538182 -313.579002)
		(end 403.700234 -313.741054)
		(width 0.14478)
		(layer "In4.Cu")
		(net "M_J_CPU0_SB_DQ<31>")
	)
	(segment
		(start 409.588208 -318.099186)
		(end 411.40253 -318.46012)
		(width 0.14478)
		(layer "In4.Cu")
		(net "M_J_CPU0_SB_DQ<31>")
	)
	(segment
		(start 393.289282 -295.955974)
		(end 393.289282 -296.154348)
		(width 0.0889)
		(layer "In4.Cu")
		(net "M_J_CPU0_SB_DQ<31>")
	)
	(segment
		(start 386.983478 -293.19855)
		(end 386.99186 -293.203376)
		(width 0.0889)
		(layer "In4.Cu")
		(net "M_J_CPU0_SB_DQ<31>")
	)
	(segment
		(start 399.780506 -309.30596)
		(end 399.636742 -309.44947)
		(width 0.14478)
		(layer "In4.Cu")
		(net "M_J_CPU0_SB_DQ<31>")
	)
	(segment
		(start 392.59256 -294.800528)
		(end 392.631676 -294.823388)
		(width 0.0889)
		(layer "In4.Cu")
		(net "M_J_CPU0_SB_DQ<31>")
	)
	(segment
		(start 393.062714 -295.610534)
		(end 393.10183 -295.633394)
		(width 0.0889)
		(layer "In4.Cu")
		(net "M_J_CPU0_SB_DQ<31>")
	)
	(segment
		(start 401.977606 -311.790334)
		(end 401.977606 -312.018426)
		(width 0.14478)
		(layer "In4.Cu")
		(net "M_J_CPU0_SB_DQ<31>")
	)
	(segment
		(start 400.807174 -310.619902)
		(end 400.950684 -310.476392)
		(width 0.14478)
		(layer "In4.Cu")
		(net "M_J_CPU0_SB_DQ<31>")
	)
	(segment
		(start 403.538182 -313.35091)
		(end 403.538182 -313.579002)
		(width 0.14478)
		(layer "In4.Cu")
		(net "M_J_CPU0_SB_DQ<31>")
	)
	(segment
		(start 403.700234 -313.741054)
		(end 403.928326 -313.741054)
		(width 0.14478)
		(layer "In4.Cu")
		(net "M_J_CPU0_SB_DQ<31>")
	)
	(segment
		(start 401.977606 -312.018426)
		(end 402.139658 -312.180478)
		(width 0.14478)
		(layer "In4.Cu")
		(net "M_J_CPU0_SB_DQ<31>")
	)
	(segment
		(start 402.757894 -312.570622)
		(end 402.757894 -312.798714)
		(width 0.14478)
		(layer "In4.Cu")
		(net "M_J_CPU0_SB_DQ<31>")
	)
	(segment
		(start 403.681946 -312.979308)
		(end 403.681946 -313.2074)
		(width 0.14478)
		(layer "In4.Cu")
		(net "M_J_CPU0_SB_DQ<31>")
	)
	(segment
		(start 402.919946 -312.960766)
		(end 403.148038 -312.960766)
		(width 0.14478)
		(layer "In4.Cu")
		(net "M_J_CPU0_SB_DQ<31>")
	)
	(segment
		(start 403.928326 -313.741054)
		(end 404.071836 -313.597544)
		(width 0.14478)
		(layer "In4.Cu")
		(net "M_J_CPU0_SB_DQ<31>")
	)
	(segment
		(start 434.575204 -318.46012)
		(end 435.000146 -318.035178)
		(width 0.14478)
		(layer "In4.Cu")
		(net "M_J_CPU0_SB_DQ<31>")
	)
	(segment
		(start 402.12137 -311.646824)
		(end 401.977606 -311.790334)
		(width 0.14478)
		(layer "In4.Cu")
		(net "M_J_CPU0_SB_DQ<31>")
	)
	(segment
		(start 405.098758 -315.139578)
		(end 406.976834 -317.017654)
		(width 0.14478)
		(layer "In4.Cu")
		(net "M_J_CPU0_SB_DQ<31>")
	)
	(segment
		(start 393.289282 -296.154348)
		(end 393.055348 -296.388282)
		(width 0.0889)
		(layer "In4.Cu")
		(net "M_J_CPU0_SB_DQ<31>")
	)
	(segment
		(start 405.08047 -314.377832)
		(end 405.242522 -314.539884)
		(width 0.14478)
		(layer "In4.Cu")
		(net "M_J_CPU0_SB_DQ<31>")
	)
	(segment
		(start 404.462234 -313.987688)
		(end 404.31847 -314.131198)
		(width 0.14478)
		(layer "In4.Cu")
		(net "M_J_CPU0_SB_DQ<31>")
	)
	(segment
		(start 402.901658 -312.19902)
		(end 402.901658 -312.427112)
		(width 0.14478)
		(layer "In4.Cu")
		(net "M_J_CPU0_SB_DQ<31>")
	)
	(segment
		(start 399.798794 -309.839614)
		(end 400.026886 -309.839614)
		(width 0.14478)
		(layer "In4.Cu")
		(net "M_J_CPU0_SB_DQ<31>")
	)
	(segment
		(start 390.74344 -293.19855)
		(end 390.751822 -293.203376)
		(width 0.0889)
		(layer "In4.Cu")
		(net "M_J_CPU0_SB_DQ<31>")
	)
	(segment
		(start 403.519894 -312.817256)
		(end 403.681946 -312.979308)
		(width 0.14478)
		(layer "In4.Cu")
		(net "M_J_CPU0_SB_DQ<31>")
	)
	(segment
		(start 401.197318 -311.010046)
		(end 401.197318 -311.238138)
		(width 0.14478)
		(layer "In4.Cu")
		(net "M_J_CPU0_SB_DQ<31>")
	)
	(segment
		(start 382.857756 -293.203376)
		(end 382.866138 -293.19855)
		(width 0.0889)
		(layer "In4.Cu")
		(net "M_J_CPU0_SB_DQ<31>")
	)
	(segment
		(start 383.79781 -293.203376)
		(end 383.806192 -293.19855)
		(width 0.0889)
		(layer "In4.Cu")
		(net "M_J_CPU0_SB_DQ<31>")
	)
	(segment
		(start 400.950684 -310.476392)
		(end 401.17903 -310.476392)
		(width 0.14478)
		(layer "In4.Cu")
		(net "M_J_CPU0_SB_DQ<31>")
	)
	(segment
		(start 405.098758 -314.911486)
		(end 405.098758 -315.139578)
		(width 0.14478)
		(layer "In4.Cu")
		(net "M_J_CPU0_SB_DQ<31>")
	)
	(segment
		(start 400.026886 -309.839614)
		(end 400.170396 -309.696104)
		(width 0.14478)
		(layer "In4.Cu")
		(net "M_J_CPU0_SB_DQ<31>")
	)
	(segment
		(start 401.197318 -311.238138)
		(end 401.35937 -311.40019)
		(width 0.14478)
		(layer "In4.Cu")
		(net "M_J_CPU0_SB_DQ<31>")
	)
	(segment
		(start 393.055348 -296.388282)
		(end 393.055348 -303.096168)
		(width 0.14478)
		(layer "In4.Cu")
		(net "M_J_CPU0_SB_DQ<31>")
	)
	(segment
		(start 404.31847 -314.131198)
		(end 404.31847 -314.35929)
		(width 0.14478)
		(layer "In4.Cu")
		(net "M_J_CPU0_SB_DQ<31>")
	)
	(segment
		(start 402.51126 -312.036968)
		(end 402.739606 -312.036968)
		(width 0.14478)
		(layer "In4.Cu")
		(net "M_J_CPU0_SB_DQ<31>")
	)
	(segment
		(start 402.757894 -312.798714)
		(end 402.919946 -312.960766)
		(width 0.14478)
		(layer "In4.Cu")
		(net "M_J_CPU0_SB_DQ<31>")
	)
	(segment
		(start 381.164846 -293.525956)
		(end 381.887476 -293.221156)
		(width 0.0889)
		(layer "In4.Cu")
		(net "M_J_CPU0_SB_DQ<31>")
	)
	(segment
		(start 401.730972 -311.25668)
		(end 401.959318 -311.25668)
		(width 0.14478)
		(layer "In4.Cu")
		(net "M_J_CPU0_SB_DQ<31>")
	)
	(segment
		(start 382.283462 -293.19855)
		(end 382.291844 -293.203376)
		(width 0.0889)
		(layer "In4.Cu")
		(net "M_J_CPU0_SB_DQ<31>")
	)
	(segment
		(start 391.317734 -293.203376)
		(end 391.326116 -293.19855)
		(width 0.0889)
		(layer "In4.Cu")
		(net "M_J_CPU0_SB_DQ<31>")
	)
	(segment
		(start 402.139658 -312.180478)
		(end 402.36775 -312.180478)
		(width 0.14478)
		(layer "In4.Cu")
		(net "M_J_CPU0_SB_DQ<31>")
	)
	(segment
		(start 402.901658 -312.427112)
		(end 402.757894 -312.570622)
		(width 0.14478)
		(layer "In4.Cu")
		(net "M_J_CPU0_SB_DQ<31>")
	)
	(segment
		(start 399.780506 -309.077868)
		(end 399.780506 -309.30596)
		(width 0.14478)
		(layer "In4.Cu")
		(net "M_J_CPU0_SB_DQ<31>")
	)
	(segment
		(start 400.170396 -309.696104)
		(end 400.398742 -309.696104)
		(width 0.14478)
		(layer "In4.Cu")
		(net "M_J_CPU0_SB_DQ<31>")
	)
	(segment
		(start 401.35937 -311.40019)
		(end 401.587462 -311.40019)
		(width 0.14478)
		(layer "In4.Cu")
		(net "M_J_CPU0_SB_DQ<31>")
	)
	(segment
		(start 393.10183 -295.633394)
		(end 393.131294 -295.650412)
		(width 0.0889)
		(layer "In4.Cu")
		(net "M_J_CPU0_SB_DQ<31>")
	)
	(segment
		(start 403.681946 -313.2074)
		(end 403.538182 -313.35091)
		(width 0.14478)
		(layer "In4.Cu")
		(net "M_J_CPU0_SB_DQ<31>")
	)
	(segment
		(start 404.462234 -313.759596)
		(end 404.462234 -313.987688)
		(width 0.14478)
		(layer "In4.Cu")
		(net "M_J_CPU0_SB_DQ<31>")
	)
	(segment
		(start 386.043424 -293.19855)
		(end 386.051806 -293.203376)
		(width 0.0889)
		(layer "In4.Cu")
		(net "M_J_CPU0_SB_DQ<31>")
	)
	(segment
		(start 400.560794 -310.086248)
		(end 400.41703 -310.229758)
		(width 0.14478)
		(layer "In4.Cu")
		(net "M_J_CPU0_SB_DQ<31>")
	)
	(segment
		(start 404.480522 -314.521342)
		(end 404.708614 -314.521342)
		(width 0.14478)
		(layer "In4.Cu")
		(net "M_J_CPU0_SB_DQ<31>")
	)
	(segment
		(start 404.300182 -313.597544)
		(end 404.462234 -313.759596)
		(width 0.14478)
		(layer "In4.Cu")
		(net "M_J_CPU0_SB_DQ<31>")
	)
	(segment
		(start 399.618454 -308.915816)
		(end 399.780506 -309.077868)
		(width 0.14478)
		(layer "In4.Cu")
		(net "M_J_CPU0_SB_DQ<31>")
	)
	(segment
		(start 405.242522 -314.767976)
		(end 405.098758 -314.911486)
		(width 0.14478)
		(layer "In4.Cu")
		(net "M_J_CPU0_SB_DQ<31>")
	)
	(segment
		(start 401.341082 -310.638444)
		(end 401.341082 -310.866536)
		(width 0.14478)
		(layer "In4.Cu")
		(net "M_J_CPU0_SB_DQ<31>")
	)
	(segment
		(start 404.708614 -314.521342)
		(end 404.852124 -314.377832)
		(width 0.14478)
		(layer "In4.Cu")
		(net "M_J_CPU0_SB_DQ<31>")
	)
	(segment
		(start 404.852124 -314.377832)
		(end 405.08047 -314.377832)
		(width 0.14478)
		(layer "In4.Cu")
		(net "M_J_CPU0_SB_DQ<31>")
	)
	(segment
		(start 392.631676 -294.823388)
		(end 392.664442 -294.842438)
		(width 0.0889)
		(layer "In4.Cu")
		(net "M_J_CPU0_SB_DQ<31>")
	)
	(segment
		(start 399.018506 -309.059326)
		(end 399.246598 -309.059326)
		(width 0.14478)
		(layer "In4.Cu")
		(net "M_J_CPU0_SB_DQ<31>")
	)
	(segment
		(start 399.636742 -309.44947)
		(end 399.636742 -309.677562)
		(width 0.14478)
		(layer "In4.Cu")
		(net "M_J_CPU0_SB_DQ<31>")
	)
	(segment
		(start 391.691876 -293.203376)
		(end 391.722356 -293.221156)
		(width 0.0889)
		(layer "In4.Cu")
		(net "M_J_CPU0_SB_DQ<31>")
	)
	(segment
		(start 400.398742 -309.696104)
		(end 400.560794 -309.858156)
		(width 0.14478)
		(layer "In4.Cu")
		(net "M_J_CPU0_SB_DQ<31>")
	)
	(segment
		(start 404.071836 -313.597544)
		(end 404.300182 -313.597544)
		(width 0.14478)
		(layer "In4.Cu")
		(net "M_J_CPU0_SB_DQ<31>")
	)
	(segment
		(start 403.148038 -312.960766)
		(end 403.291548 -312.817256)
		(width 0.14478)
		(layer "In4.Cu")
		(net "M_J_CPU0_SB_DQ<31>")
	)
	(segment
		(start 381.887476 -293.221156)
		(end 381.917702 -293.203376)
		(width 0.0889)
		(layer "In4.Cu")
		(net "M_J_CPU0_SB_DQ<31>")
	)
	(segment
		(start 388.497826 -293.203376)
		(end 388.506208 -293.19855)
		(width 0.0889)
		(layer "In4.Cu")
		(net "M_J_CPU0_SB_DQ<31>")
	)
	(segment
		(start 402.12137 -311.418732)
		(end 402.12137 -311.646824)
		(width 0.14478)
		(layer "In4.Cu")
		(net "M_J_CPU0_SB_DQ<31>")
	)
	(arc
		(start 386.617718 -293.203376)
		(mid 386.799969 -293.153026)
		(end 386.983478 -293.19855)
		(width 0.0889)
		(layer "In4.Cu")
		(net "M_J_CPU0_SB_DQ<31>")
	)
	(arc
		(start 385.677664 -293.203376)
		(mid 385.859915 -293.153026)
		(end 386.043424 -293.19855)
		(width 0.0889)
		(layer "In4.Cu")
		(net "M_J_CPU0_SB_DQ<31>")
	)
	(arc
		(start 392.192256 -294.031162)
		(mid 392.307683 -294.164538)
		(end 392.349228 -294.335962)
		(width 0.0889)
		(layer "In4.Cu")
		(net "M_J_CPU0_SB_DQ<31>")
	)
	(arc
		(start 382.866138 -293.19855)
		(mid 383.049646 -293.153056)
		(end 383.231898 -293.203376)
		(width 0.0889)
		(layer "In4.Cu")
		(net "M_J_CPU0_SB_DQ<31>")
	)
	(arc
		(start 388.871968 -293.203376)
		(mid 389.154924 -293.279553)
		(end 389.43788 -293.203376)
		(width 0.0889)
		(layer "In4.Cu")
		(net "M_J_CPU0_SB_DQ<31>")
	)
	(arc
		(start 389.43788 -293.203376)
		(mid 389.624824 -293.153121)
		(end 389.811768 -293.203376)
		(width 0.0889)
		(layer "In4.Cu")
		(net "M_J_CPU0_SB_DQ<31>")
	)
	(arc
		(start 393.131294 -295.650412)
		(mid 393.247475 -295.783971)
		(end 393.289282 -295.955974)
		(width 0.0889)
		(layer "In4.Cu")
		(net "M_J_CPU0_SB_DQ<31>")
	)
	(arc
		(start 384.171952 -293.203376)
		(mid 384.454908 -293.279553)
		(end 384.737864 -293.203376)
		(width 0.0889)
		(layer "In4.Cu")
		(net "M_J_CPU0_SB_DQ<31>")
	)
	(arc
		(start 391.879328 -293.525956)
		(mid 391.943843 -293.788175)
		(end 392.12266 -293.990522)
		(width 0.0889)
		(layer "In4.Cu")
		(net "M_J_CPU0_SB_DQ<31>")
	)
	(arc
		(start 383.806192 -293.19855)
		(mid 383.9897 -293.153056)
		(end 384.171952 -293.203376)
		(width 0.0889)
		(layer "In4.Cu")
		(net "M_J_CPU0_SB_DQ<31>")
	)
	(arc
		(start 388.506208 -293.19855)
		(mid 388.689716 -293.153056)
		(end 388.871968 -293.203376)
		(width 0.0889)
		(layer "In4.Cu")
		(net "M_J_CPU0_SB_DQ<31>")
	)
	(arc
		(start 391.326116 -293.19855)
		(mid 391.509624 -293.153056)
		(end 391.691876 -293.203376)
		(width 0.0889)
		(layer "In4.Cu")
		(net "M_J_CPU0_SB_DQ<31>")
	)
	(arc
		(start 391.722356 -293.221156)
		(mid 391.837783 -293.354532)
		(end 391.879328 -293.525956)
		(width 0.0889)
		(layer "In4.Cu")
		(net "M_J_CPU0_SB_DQ<31>")
	)
	(arc
		(start 384.737864 -293.203376)
		(mid 384.924808 -293.153121)
		(end 385.111752 -293.203376)
		(width 0.0889)
		(layer "In4.Cu")
		(net "M_J_CPU0_SB_DQ<31>")
	)
	(arc
		(start 390.37768 -293.203376)
		(mid 390.559931 -293.153026)
		(end 390.74344 -293.19855)
		(width 0.0889)
		(layer "In4.Cu")
		(net "M_J_CPU0_SB_DQ<31>")
	)
	(arc
		(start 385.111752 -293.203376)
		(mid 385.394708 -293.279553)
		(end 385.677664 -293.203376)
		(width 0.0889)
		(layer "In4.Cu")
		(net "M_J_CPU0_SB_DQ<31>")
	)
	(arc
		(start 386.99186 -293.203376)
		(mid 387.274816 -293.279553)
		(end 387.557772 -293.203376)
		(width 0.0889)
		(layer "In4.Cu")
		(net "M_J_CPU0_SB_DQ<31>")
	)
	(arc
		(start 389.811768 -293.203376)
		(mid 390.094724 -293.279553)
		(end 390.37768 -293.203376)
		(width 0.0889)
		(layer "In4.Cu")
		(net "M_J_CPU0_SB_DQ<31>")
	)
	(arc
		(start 382.291844 -293.203376)
		(mid 382.5748 -293.279553)
		(end 382.857756 -293.203376)
		(width 0.0889)
		(layer "In4.Cu")
		(net "M_J_CPU0_SB_DQ<31>")
	)
	(arc
		(start 381.917702 -293.203376)
		(mid 382.099953 -293.153026)
		(end 382.283462 -293.19855)
		(width 0.0889)
		(layer "In4.Cu")
		(net "M_J_CPU0_SB_DQ<31>")
	)
	(arc
		(start 387.931914 -293.203376)
		(mid 388.21487 -293.279553)
		(end 388.497826 -293.203376)
		(width 0.0889)
		(layer "In4.Cu")
		(net "M_J_CPU0_SB_DQ<31>")
	)
	(arc
		(start 386.051806 -293.203376)
		(mid 386.334762 -293.279553)
		(end 386.617718 -293.203376)
		(width 0.0889)
		(layer "In4.Cu")
		(net "M_J_CPU0_SB_DQ<31>")
	)
	(arc
		(start 387.566154 -293.19855)
		(mid 387.749662 -293.153056)
		(end 387.931914 -293.203376)
		(width 0.0889)
		(layer "In4.Cu")
		(net "M_J_CPU0_SB_DQ<31>")
	)
	(arc
		(start 392.819382 -295.145968)
		(mid 392.883897 -295.408187)
		(end 393.062714 -295.610534)
		(width 0.0889)
		(layer "In4.Cu")
		(net "M_J_CPU0_SB_DQ<31>")
	)
	(arc
		(start 392.664442 -294.842438)
		(mid 392.778371 -294.975585)
		(end 392.819382 -295.145968)
		(width 0.0889)
		(layer "In4.Cu")
		(net "M_J_CPU0_SB_DQ<31>")
	)
	(arc
		(start 390.751822 -293.203376)
		(mid 391.034778 -293.279553)
		(end 391.317734 -293.203376)
		(width 0.0889)
		(layer "In4.Cu")
		(net "M_J_CPU0_SB_DQ<31>")
	)
	(arc
		(start 383.231898 -293.203376)
		(mid 383.514854 -293.279553)
		(end 383.79781 -293.203376)
		(width 0.0889)
		(layer "In4.Cu")
		(net "M_J_CPU0_SB_DQ<31>")
	)
	(arc
		(start 392.349228 -294.335962)
		(mid 392.413743 -294.598181)
		(end 392.59256 -294.800528)
		(width 0.0889)
		(layer "In4.Cu")
		(net "M_J_CPU0_SB_DQ<31>")
	)
	(segment
		(start 380.22784 -292.450012)
		(end 380.694946 -292.71595)
		(width 0.10668)
		(layer "F.Cu")
		(net "M_J_CPU0_SB_DQ<30>")
	)
	(segment
		(start 394.347446 -302.52416)
		(end 394.165836 -302.70577)
		(width 0.14478)
		(layer "In4.Cu")
		(net "M_J_CPU0_SB_DQ<30>")
	)
	(segment
		(start 399.029174 -307.205888)
		(end 398.847564 -307.387498)
		(width 0.14478)
		(layer "In4.Cu")
		(net "M_J_CPU0_SB_DQ<30>")
	)
	(segment
		(start 395.887956 -304.65649)
		(end 396.116556 -304.65649)
		(width 0.14478)
		(layer "In4.Cu")
		(net "M_J_CPU0_SB_DQ<30>")
	)
	(segment
		(start 396.116556 -304.65649)
		(end 396.298166 -304.47488)
		(width 0.14478)
		(layer "In4.Cu")
		(net "M_J_CPU0_SB_DQ<30>")
	)
	(segment
		(start 398.087342 -306.035456)
		(end 398.248886 -306.197)
		(width 0.14478)
		(layer "In4.Cu")
		(net "M_J_CPU0_SB_DQ<30>")
	)
	(segment
		(start 394.165836 -302.93437)
		(end 394.32738 -303.095914)
		(width 0.14478)
		(layer "In4.Cu")
		(net "M_J_CPU0_SB_DQ<30>")
	)
	(segment
		(start 397.677132 -306.217066)
		(end 397.858742 -306.035456)
		(width 0.14478)
		(layer "In4.Cu")
		(net "M_J_CPU0_SB_DQ<30>")
	)
	(segment
		(start 396.896844 -305.436778)
		(end 397.078454 -305.255168)
		(width 0.14478)
		(layer "In4.Cu")
		(net "M_J_CPU0_SB_DQ<30>")
	)
	(segment
		(start 396.5067 -305.275234)
		(end 396.668244 -305.436778)
		(width 0.14478)
		(layer "In4.Cu")
		(net "M_J_CPU0_SB_DQ<30>")
	)
	(segment
		(start 383.693416 -292.388544)
		(end 383.701798 -292.39337)
		(width 0.0889)
		(layer "In4.Cu")
		(net "M_J_CPU0_SB_DQ<30>")
	)
	(segment
		(start 393.57173 -294.823388)
		(end 393.60348 -294.841676)
		(width 0.0889)
		(layer "In4.Cu")
		(net "M_J_CPU0_SB_DQ<30>")
	)
	(segment
		(start 386.147818 -292.39337)
		(end 386.1562 -292.388544)
		(width 0.0889)
		(layer "In4.Cu")
		(net "M_J_CPU0_SB_DQ<30>")
	)
	(segment
		(start 397.858742 -306.035456)
		(end 398.087342 -306.035456)
		(width 0.14478)
		(layer "In4.Cu")
		(net "M_J_CPU0_SB_DQ<30>")
	)
	(segment
		(start 393.964668 -295.648634)
		(end 393.964668 -296.358564)
		(width 0.0889)
		(layer "In4.Cu")
		(net "M_J_CPU0_SB_DQ<30>")
	)
	(segment
		(start 434.575204 -316.760098)
		(end 435.000146 -316.335156)
		(width 0.14478)
		(layer "In4.Cu")
		(net "M_J_CPU0_SB_DQ<30>")
	)
	(segment
		(start 396.668244 -305.436778)
		(end 396.896844 -305.436778)
		(width 0.14478)
		(layer "In4.Cu")
		(net "M_J_CPU0_SB_DQ<30>")
	)
	(segment
		(start 398.067276 -306.60721)
		(end 398.067276 -306.83581)
		(width 0.14478)
		(layer "In4.Cu")
		(net "M_J_CPU0_SB_DQ<30>")
	)
	(segment
		(start 397.468598 -305.645312)
		(end 397.286988 -305.826922)
		(width 0.14478)
		(layer "In4.Cu")
		(net "M_J_CPU0_SB_DQ<30>")
	)
	(segment
		(start 392.592814 -293.180516)
		(end 392.63193 -293.203376)
		(width 0.0889)
		(layer "In4.Cu")
		(net "M_J_CPU0_SB_DQ<30>")
	)
	(segment
		(start 395.726412 -304.266346)
		(end 395.726412 -304.494946)
		(width 0.14478)
		(layer "In4.Cu")
		(net "M_J_CPU0_SB_DQ<30>")
	)
	(segment
		(start 394.55598 -303.095914)
		(end 394.73759 -302.914304)
		(width 0.14478)
		(layer "In4.Cu")
		(net "M_J_CPU0_SB_DQ<30>")
	)
	(segment
		(start 395.726412 -304.494946)
		(end 395.887956 -304.65649)
		(width 0.14478)
		(layer "In4.Cu")
		(net "M_J_CPU0_SB_DQ<30>")
	)
	(segment
		(start 398.847564 -307.387498)
		(end 398.847564 -307.616098)
		(width 0.14478)
		(layer "In4.Cu")
		(net "M_J_CPU0_SB_DQ<30>")
	)
	(segment
		(start 399.647918 -307.596032)
		(end 408.811984 -316.760098)
		(width 0.14478)
		(layer "In4.Cu")
		(net "M_J_CPU0_SB_DQ<30>")
	)
	(segment
		(start 381.447802 -292.39337)
		(end 381.456184 -292.388544)
		(width 0.0889)
		(layer "In4.Cu")
		(net "M_J_CPU0_SB_DQ<30>")
	)
	(segment
		(start 393.759436 -295.145968)
		(end 393.759436 -295.443402)
		(width 0.0889)
		(layer "In4.Cu")
		(net "M_J_CPU0_SB_DQ<30>")
	)
	(segment
		(start 389.90778 -292.39337)
		(end 389.916162 -292.388544)
		(width 0.0889)
		(layer "In4.Cu")
		(net "M_J_CPU0_SB_DQ<30>")
	)
	(segment
		(start 393.964668 -301.912782)
		(end 394.347446 -302.29556)
		(width 0.14478)
		(layer "In4.Cu")
		(net "M_J_CPU0_SB_DQ<30>")
	)
	(segment
		(start 395.127734 -303.304448)
		(end 394.946124 -303.486058)
		(width 0.14478)
		(layer "In4.Cu")
		(net "M_J_CPU0_SB_DQ<30>")
	)
	(segment
		(start 393.964668 -296.358564)
		(end 393.964668 -301.912782)
		(width 0.14478)
		(layer "In4.Cu")
		(net "M_J_CPU0_SB_DQ<30>")
	)
	(segment
		(start 396.5067 -305.046634)
		(end 396.5067 -305.275234)
		(width 0.14478)
		(layer "In4.Cu")
		(net "M_J_CPU0_SB_DQ<30>")
	)
	(segment
		(start 408.811984 -316.760098)
		(end 434.575204 -316.760098)
		(width 0.14478)
		(layer "In4.Cu")
		(net "M_J_CPU0_SB_DQ<30>")
	)
	(segment
		(start 398.63903 -306.815744)
		(end 398.86763 -306.815744)
		(width 0.14478)
		(layer "In4.Cu")
		(net "M_J_CPU0_SB_DQ<30>")
	)
	(segment
		(start 396.526766 -304.47488)
		(end 396.68831 -304.636424)
		(width 0.14478)
		(layer "In4.Cu")
		(net "M_J_CPU0_SB_DQ<30>")
	)
	(segment
		(start 395.746478 -303.694592)
		(end 395.908022 -303.856136)
		(width 0.14478)
		(layer "In4.Cu")
		(net "M_J_CPU0_SB_DQ<30>")
	)
	(segment
		(start 398.067276 -306.83581)
		(end 398.22882 -306.997354)
		(width 0.14478)
		(layer "In4.Cu")
		(net "M_J_CPU0_SB_DQ<30>")
	)
	(segment
		(start 394.946124 -303.714658)
		(end 395.107668 -303.876202)
		(width 0.14478)
		(layer "In4.Cu")
		(net "M_J_CPU0_SB_DQ<30>")
	)
	(segment
		(start 398.248886 -306.4256)
		(end 398.067276 -306.60721)
		(width 0.14478)
		(layer "In4.Cu")
		(net "M_J_CPU0_SB_DQ<30>")
	)
	(segment
		(start 394.96619 -302.914304)
		(end 395.127734 -303.075848)
		(width 0.14478)
		(layer "In4.Cu")
		(net "M_J_CPU0_SB_DQ<30>")
	)
	(segment
		(start 380.694946 -292.71595)
		(end 380.84887 -292.45052)
		(width 0.0889)
		(layer "In4.Cu")
		(net "M_J_CPU0_SB_DQ<30>")
	)
	(segment
		(start 395.517878 -303.694592)
		(end 395.746478 -303.694592)
		(width 0.14478)
		(layer "In4.Cu")
		(net "M_J_CPU0_SB_DQ<30>")
	)
	(segment
		(start 393.759436 -295.443402)
		(end 393.964668 -295.648634)
		(width 0.0889)
		(layer "In4.Cu")
		(net "M_J_CPU0_SB_DQ<30>")
	)
	(segment
		(start 394.73759 -302.914304)
		(end 394.96619 -302.914304)
		(width 0.14478)
		(layer "In4.Cu")
		(net "M_J_CPU0_SB_DQ<30>")
	)
	(segment
		(start 393.062714 -293.990522)
		(end 393.10183 -294.013382)
		(width 0.0889)
		(layer "In4.Cu")
		(net "M_J_CPU0_SB_DQ<30>")
	)
	(segment
		(start 397.078454 -305.255168)
		(end 397.307054 -305.255168)
		(width 0.14478)
		(layer "In4.Cu")
		(net "M_J_CPU0_SB_DQ<30>")
	)
	(segment
		(start 399.029174 -306.977288)
		(end 399.029174 -307.205888)
		(width 0.14478)
		(layer "In4.Cu")
		(net "M_J_CPU0_SB_DQ<30>")
	)
	(segment
		(start 395.908022 -303.856136)
		(end 395.908022 -304.084736)
		(width 0.14478)
		(layer "In4.Cu")
		(net "M_J_CPU0_SB_DQ<30>")
	)
	(segment
		(start 396.298166 -304.47488)
		(end 396.526766 -304.47488)
		(width 0.14478)
		(layer "In4.Cu")
		(net "M_J_CPU0_SB_DQ<30>")
	)
	(segment
		(start 396.68831 -304.865024)
		(end 396.5067 -305.046634)
		(width 0.14478)
		(layer "In4.Cu")
		(net "M_J_CPU0_SB_DQ<30>")
	)
	(segment
		(start 395.336268 -303.876202)
		(end 395.517878 -303.694592)
		(width 0.14478)
		(layer "In4.Cu")
		(net "M_J_CPU0_SB_DQ<30>")
	)
	(segment
		(start 397.448532 -306.217066)
		(end 397.677132 -306.217066)
		(width 0.14478)
		(layer "In4.Cu")
		(net "M_J_CPU0_SB_DQ<30>")
	)
	(segment
		(start 398.248886 -306.197)
		(end 398.248886 -306.4256)
		(width 0.14478)
		(layer "In4.Cu")
		(net "M_J_CPU0_SB_DQ<30>")
	)
	(segment
		(start 380.84887 -292.45052)
		(end 380.944882 -292.42512)
		(width 0.0889)
		(layer "In4.Cu")
		(net "M_J_CPU0_SB_DQ<30>")
	)
	(segment
		(start 397.286988 -306.055522)
		(end 397.448532 -306.217066)
		(width 0.14478)
		(layer "In4.Cu")
		(net "M_J_CPU0_SB_DQ<30>")
	)
	(segment
		(start 389.333486 -292.388544)
		(end 389.341868 -292.39337)
		(width 0.0889)
		(layer "In4.Cu")
		(net "M_J_CPU0_SB_DQ<30>")
	)
	(segment
		(start 394.347446 -302.29556)
		(end 394.347446 -302.52416)
		(width 0.14478)
		(layer "In4.Cu")
		(net "M_J_CPU0_SB_DQ<30>")
	)
	(segment
		(start 392.63193 -293.203376)
		(end 392.66241 -293.221156)
		(width 0.0889)
		(layer "In4.Cu")
		(net "M_J_CPU0_SB_DQ<30>")
	)
	(segment
		(start 392.16203 -292.39337)
		(end 392.19251 -292.41115)
		(width 0.0889)
		(layer "In4.Cu")
		(net "M_J_CPU0_SB_DQ<30>")
	)
	(segment
		(start 393.532614 -294.800528)
		(end 393.57173 -294.823388)
		(width 0.0889)
		(layer "In4.Cu")
		(net "M_J_CPU0_SB_DQ<30>")
	)
	(segment
		(start 384.63347 -292.388544)
		(end 384.641852 -292.39337)
		(width 0.0889)
		(layer "In4.Cu")
		(net "M_J_CPU0_SB_DQ<30>")
	)
	(segment
		(start 398.45742 -306.997354)
		(end 398.63903 -306.815744)
		(width 0.14478)
		(layer "In4.Cu")
		(net "M_J_CPU0_SB_DQ<30>")
	)
	(segment
		(start 397.468598 -305.416712)
		(end 397.468598 -305.645312)
		(width 0.14478)
		(layer "In4.Cu")
		(net "M_J_CPU0_SB_DQ<30>")
	)
	(segment
		(start 395.908022 -304.084736)
		(end 395.726412 -304.266346)
		(width 0.14478)
		(layer "In4.Cu")
		(net "M_J_CPU0_SB_DQ<30>")
	)
	(segment
		(start 399.237708 -307.777642)
		(end 399.419318 -307.596032)
		(width 0.14478)
		(layer "In4.Cu")
		(net "M_J_CPU0_SB_DQ<30>")
	)
	(segment
		(start 396.68831 -304.636424)
		(end 396.68831 -304.865024)
		(width 0.14478)
		(layer "In4.Cu")
		(net "M_J_CPU0_SB_DQ<30>")
	)
	(segment
		(start 385.207764 -292.39337)
		(end 385.216146 -292.388544)
		(width 0.0889)
		(layer "In4.Cu")
		(net "M_J_CPU0_SB_DQ<30>")
	)
	(segment
		(start 388.393432 -292.388544)
		(end 388.401814 -292.39337)
		(width 0.0889)
		(layer "In4.Cu")
		(net "M_J_CPU0_SB_DQ<30>")
	)
	(segment
		(start 395.127734 -303.075848)
		(end 395.127734 -303.304448)
		(width 0.14478)
		(layer "In4.Cu")
		(net "M_J_CPU0_SB_DQ<30>")
	)
	(segment
		(start 397.286988 -305.826922)
		(end 397.286988 -306.055522)
		(width 0.14478)
		(layer "In4.Cu")
		(net "M_J_CPU0_SB_DQ<30>")
	)
	(segment
		(start 398.86763 -306.815744)
		(end 399.029174 -306.977288)
		(width 0.14478)
		(layer "In4.Cu")
		(net "M_J_CPU0_SB_DQ<30>")
	)
	(segment
		(start 394.946124 -303.486058)
		(end 394.946124 -303.714658)
		(width 0.14478)
		(layer "In4.Cu")
		(net "M_J_CPU0_SB_DQ<30>")
	)
	(segment
		(start 397.307054 -305.255168)
		(end 397.468598 -305.416712)
		(width 0.14478)
		(layer "In4.Cu")
		(net "M_J_CPU0_SB_DQ<30>")
	)
	(segment
		(start 394.32738 -303.095914)
		(end 394.55598 -303.095914)
		(width 0.14478)
		(layer "In4.Cu")
		(net "M_J_CPU0_SB_DQ<30>")
	)
	(segment
		(start 399.419318 -307.596032)
		(end 399.647918 -307.596032)
		(width 0.14478)
		(layer "In4.Cu")
		(net "M_J_CPU0_SB_DQ<30>")
	)
	(segment
		(start 398.847564 -307.616098)
		(end 399.009108 -307.777642)
		(width 0.14478)
		(layer "In4.Cu")
		(net "M_J_CPU0_SB_DQ<30>")
	)
	(segment
		(start 395.107668 -303.876202)
		(end 395.336268 -303.876202)
		(width 0.14478)
		(layer "In4.Cu")
		(net "M_J_CPU0_SB_DQ<30>")
	)
	(segment
		(start 399.009108 -307.777642)
		(end 399.237708 -307.777642)
		(width 0.14478)
		(layer "In4.Cu")
		(net "M_J_CPU0_SB_DQ<30>")
	)
	(segment
		(start 398.22882 -306.997354)
		(end 398.45742 -306.997354)
		(width 0.14478)
		(layer "In4.Cu")
		(net "M_J_CPU0_SB_DQ<30>")
	)
	(segment
		(start 393.10183 -294.013382)
		(end 393.13231 -294.031162)
		(width 0.0889)
		(layer "In4.Cu")
		(net "M_J_CPU0_SB_DQ<30>")
	)
	(segment
		(start 394.165836 -302.70577)
		(end 394.165836 -302.93437)
		(width 0.14478)
		(layer "In4.Cu")
		(net "M_J_CPU0_SB_DQ<30>")
	)
	(arc
		(start 393.289282 -294.335962)
		(mid 393.353797 -294.598181)
		(end 393.532614 -294.800528)
		(width 0.0889)
		(layer "In4.Cu")
		(net "M_J_CPU0_SB_DQ<30>")
	)
	(arc
		(start 392.19251 -292.41115)
		(mid 392.307937 -292.544526)
		(end 392.349482 -292.71595)
		(width 0.0889)
		(layer "In4.Cu")
		(net "M_J_CPU0_SB_DQ<30>")
	)
	(arc
		(start 383.701798 -292.39337)
		(mid 383.984754 -292.469547)
		(end 384.26771 -292.39337)
		(width 0.0889)
		(layer "In4.Cu")
		(net "M_J_CPU0_SB_DQ<30>")
	)
	(arc
		(start 392.819382 -293.525956)
		(mid 392.883897 -293.788175)
		(end 393.062714 -293.990522)
		(width 0.0889)
		(layer "In4.Cu")
		(net "M_J_CPU0_SB_DQ<30>")
	)
	(arc
		(start 388.027672 -292.39337)
		(mid 388.209923 -292.34302)
		(end 388.393432 -292.388544)
		(width 0.0889)
		(layer "In4.Cu")
		(net "M_J_CPU0_SB_DQ<30>")
	)
	(arc
		(start 392.66241 -293.221156)
		(mid 392.777837 -293.354532)
		(end 392.819382 -293.525956)
		(width 0.0889)
		(layer "In4.Cu")
		(net "M_J_CPU0_SB_DQ<30>")
	)
	(arc
		(start 385.581906 -292.39337)
		(mid 385.864862 -292.469547)
		(end 386.147818 -292.39337)
		(width 0.0889)
		(layer "In4.Cu")
		(net "M_J_CPU0_SB_DQ<30>")
	)
	(arc
		(start 382.387856 -292.39337)
		(mid 382.5748 -292.343115)
		(end 382.761744 -292.39337)
		(width 0.0889)
		(layer "In4.Cu")
		(net "M_J_CPU0_SB_DQ<30>")
	)
	(arc
		(start 381.821944 -292.39337)
		(mid 382.1049 -292.469547)
		(end 382.387856 -292.39337)
		(width 0.0889)
		(layer "In4.Cu")
		(net "M_J_CPU0_SB_DQ<30>")
	)
	(arc
		(start 389.341868 -292.39337)
		(mid 389.624824 -292.469547)
		(end 389.90778 -292.39337)
		(width 0.0889)
		(layer "In4.Cu")
		(net "M_J_CPU0_SB_DQ<30>")
	)
	(arc
		(start 392.349482 -292.71595)
		(mid 392.413997 -292.978169)
		(end 392.592814 -293.180516)
		(width 0.0889)
		(layer "In4.Cu")
		(net "M_J_CPU0_SB_DQ<30>")
	)
	(arc
		(start 390.847834 -292.39337)
		(mid 391.034778 -292.343115)
		(end 391.221722 -292.39337)
		(width 0.0889)
		(layer "In4.Cu")
		(net "M_J_CPU0_SB_DQ<30>")
	)
	(arc
		(start 384.641852 -292.39337)
		(mid 384.924808 -292.469547)
		(end 385.207764 -292.39337)
		(width 0.0889)
		(layer "In4.Cu")
		(net "M_J_CPU0_SB_DQ<30>")
	)
	(arc
		(start 387.46176 -292.39337)
		(mid 387.744716 -292.469547)
		(end 388.027672 -292.39337)
		(width 0.0889)
		(layer "In4.Cu")
		(net "M_J_CPU0_SB_DQ<30>")
	)
	(arc
		(start 389.916162 -292.388544)
		(mid 390.09967 -292.34305)
		(end 390.281922 -292.39337)
		(width 0.0889)
		(layer "In4.Cu")
		(net "M_J_CPU0_SB_DQ<30>")
	)
	(arc
		(start 384.26771 -292.39337)
		(mid 384.449961 -292.34302)
		(end 384.63347 -292.388544)
		(width 0.0889)
		(layer "In4.Cu")
		(net "M_J_CPU0_SB_DQ<30>")
	)
	(arc
		(start 388.967726 -292.39337)
		(mid 389.149977 -292.34302)
		(end 389.333486 -292.388544)
		(width 0.0889)
		(layer "In4.Cu")
		(net "M_J_CPU0_SB_DQ<30>")
	)
	(arc
		(start 383.327656 -292.39337)
		(mid 383.509907 -292.34302)
		(end 383.693416 -292.388544)
		(width 0.0889)
		(layer "In4.Cu")
		(net "M_J_CPU0_SB_DQ<30>")
	)
	(arc
		(start 385.216146 -292.388544)
		(mid 385.399654 -292.34305)
		(end 385.581906 -292.39337)
		(width 0.0889)
		(layer "In4.Cu")
		(net "M_J_CPU0_SB_DQ<30>")
	)
	(arc
		(start 386.1562 -292.388544)
		(mid 386.339708 -292.34305)
		(end 386.52196 -292.39337)
		(width 0.0889)
		(layer "In4.Cu")
		(net "M_J_CPU0_SB_DQ<30>")
	)
	(arc
		(start 391.787634 -292.39337)
		(mid 391.974832 -292.342988)
		(end 392.16203 -292.39337)
		(width 0.0889)
		(layer "In4.Cu")
		(net "M_J_CPU0_SB_DQ<30>")
	)
	(arc
		(start 380.944882 -292.42512)
		(mid 381.20009 -292.468597)
		(end 381.447802 -292.39337)
		(width 0.0889)
		(layer "In4.Cu")
		(net "M_J_CPU0_SB_DQ<30>")
	)
	(arc
		(start 381.456184 -292.388544)
		(mid 381.639692 -292.34305)
		(end 381.821944 -292.39337)
		(width 0.0889)
		(layer "In4.Cu")
		(net "M_J_CPU0_SB_DQ<30>")
	)
	(arc
		(start 393.60348 -294.841676)
		(mid 393.718156 -294.97501)
		(end 393.759436 -295.145968)
		(width 0.0889)
		(layer "In4.Cu")
		(net "M_J_CPU0_SB_DQ<30>")
	)
	(arc
		(start 390.281922 -292.39337)
		(mid 390.564878 -292.469547)
		(end 390.847834 -292.39337)
		(width 0.0889)
		(layer "In4.Cu")
		(net "M_J_CPU0_SB_DQ<30>")
	)
	(arc
		(start 391.221722 -292.39337)
		(mid 391.504678 -292.469547)
		(end 391.787634 -292.39337)
		(width 0.0889)
		(layer "In4.Cu")
		(net "M_J_CPU0_SB_DQ<30>")
	)
	(arc
		(start 382.761744 -292.39337)
		(mid 383.0447 -292.469547)
		(end 383.327656 -292.39337)
		(width 0.0889)
		(layer "In4.Cu")
		(net "M_J_CPU0_SB_DQ<30>")
	)
	(arc
		(start 388.401814 -292.39337)
		(mid 388.68477 -292.469547)
		(end 388.967726 -292.39337)
		(width 0.0889)
		(layer "In4.Cu")
		(net "M_J_CPU0_SB_DQ<30>")
	)
	(arc
		(start 387.087872 -292.39337)
		(mid 387.274816 -292.343115)
		(end 387.46176 -292.39337)
		(width 0.0889)
		(layer "In4.Cu")
		(net "M_J_CPU0_SB_DQ<30>")
	)
	(arc
		(start 393.13231 -294.031162)
		(mid 393.247737 -294.164538)
		(end 393.289282 -294.335962)
		(width 0.0889)
		(layer "In4.Cu")
		(net "M_J_CPU0_SB_DQ<30>")
	)
	(arc
		(start 386.52196 -292.39337)
		(mid 386.804916 -292.469547)
		(end 387.087872 -292.39337)
		(width 0.0889)
		(layer "In4.Cu")
		(net "M_J_CPU0_SB_DQ<30>")
	)
	(segment
		(start 380.22784 -274.630134)
		(end 380.694946 -274.896072)
		(width 0.10668)
		(layer "F.Cu")
		(net "M_J_CPU0_SB_DQ<2>")
	)
	(segment
		(start 411.65399 -282.760166)
		(end 414.090104 -282.760166)
		(width 0.14478)
		(layer "In4.Cu")
		(net "M_J_CPU0_SB_DQ<2>")
	)
	(segment
		(start 389.333486 -274.568666)
		(end 389.341868 -274.573492)
		(width 0.0889)
		(layer "In4.Cu")
		(net "M_J_CPU0_SB_DQ<2>")
	)
	(segment
		(start 394.696188 -273.64563)
		(end 395.237716 -273.64563)
		(width 0.0889)
		(layer "In4.Cu")
		(net "M_J_CPU0_SB_DQ<2>")
	)
	(segment
		(start 409.215082 -279.451816)
		(end 409.443174 -279.451816)
		(width 0.14478)
		(layer "In4.Cu")
		(net "M_J_CPU0_SB_DQ<2>")
	)
	(segment
		(start 410.064712 -281.170888)
		(end 410.226764 -281.33294)
		(width 0.14478)
		(layer "In4.Cu")
		(net "M_J_CPU0_SB_DQ<2>")
	)
	(segment
		(start 418.972746 -282.760166)
		(end 421.634158 -282.760166)
		(width 0.14478)
		(layer "In4.Cu")
		(net "M_J_CPU0_SB_DQ<2>")
	)
	(segment
		(start 422.484296 -281.910028)
		(end 425.666662 -281.910028)
		(width 0.14478)
		(layer "In4.Cu")
		(net "M_J_CPU0_SB_DQ<2>")
	)
	(segment
		(start 408.662886 -278.671528)
		(end 408.824938 -278.83358)
		(width 0.14478)
		(layer "In4.Cu")
		(net "M_J_CPU0_SB_DQ<2>")
	)
	(segment
		(start 408.666188 -279.772364)
		(end 408.89428 -279.772364)
		(width 0.14478)
		(layer "In4.Cu")
		(net "M_J_CPU0_SB_DQ<2>")
	)
	(segment
		(start 384.63347 -274.568666)
		(end 384.641852 -274.573492)
		(width 0.0889)
		(layer "In4.Cu")
		(net "M_J_CPU0_SB_DQ<2>")
	)
	(segment
		(start 410.845 -281.723084)
		(end 410.845 -281.951176)
		(width 0.14478)
		(layer "In4.Cu")
		(net "M_J_CPU0_SB_DQ<2>")
	)
	(segment
		(start 381.447802 -274.573492)
		(end 381.456184 -274.568666)
		(width 0.0889)
		(layer "In4.Cu")
		(net "M_J_CPU0_SB_DQ<2>")
	)
	(segment
		(start 410.385514 -280.622248)
		(end 410.064712 -280.942796)
		(width 0.14478)
		(layer "In4.Cu")
		(net "M_J_CPU0_SB_DQ<2>")
	)
	(segment
		(start 410.845 -281.951176)
		(end 411.65399 -282.760166)
		(width 0.14478)
		(layer "In4.Cu")
		(net "M_J_CPU0_SB_DQ<2>")
	)
	(segment
		(start 410.226764 -281.33294)
		(end 410.454856 -281.33294)
		(width 0.14478)
		(layer "In4.Cu")
		(net "M_J_CPU0_SB_DQ<2>")
	)
	(segment
		(start 392.725402 -274.573492)
		(end 392.744198 -274.56257)
		(width 0.0889)
		(layer "In4.Cu")
		(net "M_J_CPU0_SB_DQ<2>")
	)
	(segment
		(start 434.575204 -281.910028)
		(end 435.000146 -282.33497)
		(width 0.14478)
		(layer "In4.Cu")
		(net "M_J_CPU0_SB_DQ<2>")
	)
	(segment
		(start 409.674568 -280.552652)
		(end 409.99537 -280.232104)
		(width 0.14478)
		(layer "In4.Cu")
		(net "M_J_CPU0_SB_DQ<2>")
	)
	(segment
		(start 386.147818 -274.573492)
		(end 386.1562 -274.568666)
		(width 0.0889)
		(layer "In4.Cu")
		(net "M_J_CPU0_SB_DQ<2>")
	)
	(segment
		(start 408.504136 -279.610312)
		(end 408.666188 -279.772364)
		(width 0.14478)
		(layer "In4.Cu")
		(net "M_J_CPU0_SB_DQ<2>")
	)
	(segment
		(start 402.287994 -273.39417)
		(end 407.8859 -278.992076)
		(width 0.14478)
		(layer "In4.Cu")
		(net "M_J_CPU0_SB_DQ<2>")
	)
	(segment
		(start 411.165802 -281.402536)
		(end 410.845 -281.723084)
		(width 0.14478)
		(layer "In4.Cu")
		(net "M_J_CPU0_SB_DQ<2>")
	)
	(segment
		(start 408.113992 -278.992076)
		(end 408.434794 -278.671528)
		(width 0.14478)
		(layer "In4.Cu")
		(net "M_J_CPU0_SB_DQ<2>")
	)
	(segment
		(start 393.758928 -274.58289)
		(end 394.696188 -273.64563)
		(width 0.0889)
		(layer "In4.Cu")
		(net "M_J_CPU0_SB_DQ<2>")
	)
	(segment
		(start 408.504136 -279.38222)
		(end 408.504136 -279.610312)
		(width 0.14478)
		(layer "In4.Cu")
		(net "M_J_CPU0_SB_DQ<2>")
	)
	(segment
		(start 409.284424 -280.162508)
		(end 409.284424 -280.3906)
		(width 0.14478)
		(layer "In4.Cu")
		(net "M_J_CPU0_SB_DQ<2>")
	)
	(segment
		(start 425.666662 -281.910028)
		(end 426.5168 -282.760166)
		(width 0.14478)
		(layer "In4.Cu")
		(net "M_J_CPU0_SB_DQ<2>")
	)
	(segment
		(start 409.99537 -280.232104)
		(end 410.223462 -280.232104)
		(width 0.14478)
		(layer "In4.Cu")
		(net "M_J_CPU0_SB_DQ<2>")
	)
	(segment
		(start 389.90778 -274.573492)
		(end 389.916162 -274.568666)
		(width 0.0889)
		(layer "In4.Cu")
		(net "M_J_CPU0_SB_DQ<2>")
	)
	(segment
		(start 409.443174 -279.451816)
		(end 409.605226 -279.613868)
		(width 0.14478)
		(layer "In4.Cu")
		(net "M_J_CPU0_SB_DQ<2>")
	)
	(segment
		(start 385.207764 -274.573492)
		(end 385.216146 -274.568666)
		(width 0.0889)
		(layer "In4.Cu")
		(net "M_J_CPU0_SB_DQ<2>")
	)
	(segment
		(start 393.384786 -274.6502)
		(end 393.580112 -274.6502)
		(width 0.0889)
		(layer "In4.Cu")
		(net "M_J_CPU0_SB_DQ<2>")
	)
	(segment
		(start 380.694946 -274.896072)
		(end 380.84887 -274.630642)
		(width 0.0889)
		(layer "In4.Cu")
		(net "M_J_CPU0_SB_DQ<2>")
	)
	(segment
		(start 407.8859 -278.992076)
		(end 408.113992 -278.992076)
		(width 0.14478)
		(layer "In4.Cu")
		(net "M_J_CPU0_SB_DQ<2>")
	)
	(segment
		(start 410.223462 -280.232104)
		(end 410.385514 -280.394156)
		(width 0.14478)
		(layer "In4.Cu")
		(net "M_J_CPU0_SB_DQ<2>")
	)
	(segment
		(start 410.385514 -280.394156)
		(end 410.385514 -280.622248)
		(width 0.14478)
		(layer "In4.Cu")
		(net "M_J_CPU0_SB_DQ<2>")
	)
	(segment
		(start 414.090104 -282.760166)
		(end 414.940242 -281.910028)
		(width 0.14478)
		(layer "In4.Cu")
		(net "M_J_CPU0_SB_DQ<2>")
	)
	(segment
		(start 428.64913 -282.760166)
		(end 429.499268 -281.910028)
		(width 0.14478)
		(layer "In4.Cu")
		(net "M_J_CPU0_SB_DQ<2>")
	)
	(segment
		(start 395.988286 -273.39417)
		(end 402.287994 -273.39417)
		(width 0.14478)
		(layer "In4.Cu")
		(net "M_J_CPU0_SB_DQ<2>")
	)
	(segment
		(start 409.284424 -280.3906)
		(end 409.446476 -280.552652)
		(width 0.14478)
		(layer "In4.Cu")
		(net "M_J_CPU0_SB_DQ<2>")
	)
	(segment
		(start 408.89428 -279.772364)
		(end 409.215082 -279.451816)
		(width 0.14478)
		(layer "In4.Cu")
		(net "M_J_CPU0_SB_DQ<2>")
	)
	(segment
		(start 410.775658 -281.012392)
		(end 411.00375 -281.012392)
		(width 0.14478)
		(layer "In4.Cu")
		(net "M_J_CPU0_SB_DQ<2>")
	)
	(segment
		(start 418.122608 -281.910028)
		(end 418.972746 -282.760166)
		(width 0.14478)
		(layer "In4.Cu")
		(net "M_J_CPU0_SB_DQ<2>")
	)
	(segment
		(start 421.634158 -282.760166)
		(end 422.484296 -281.910028)
		(width 0.14478)
		(layer "In4.Cu")
		(net "M_J_CPU0_SB_DQ<2>")
	)
	(segment
		(start 408.434794 -278.671528)
		(end 408.662886 -278.671528)
		(width 0.14478)
		(layer "In4.Cu")
		(net "M_J_CPU0_SB_DQ<2>")
	)
	(segment
		(start 393.580112 -274.6502)
		(end 393.758928 -274.58289)
		(width 0.0889)
		(layer "In4.Cu")
		(net "M_J_CPU0_SB_DQ<2>")
	)
	(segment
		(start 410.454856 -281.33294)
		(end 410.775658 -281.012392)
		(width 0.14478)
		(layer "In4.Cu")
		(net "M_J_CPU0_SB_DQ<2>")
	)
	(segment
		(start 395.489176 -273.39417)
		(end 395.988286 -273.39417)
		(width 0.0889)
		(layer "In4.Cu")
		(net "M_J_CPU0_SB_DQ<2>")
	)
	(segment
		(start 388.393432 -274.568666)
		(end 388.401814 -274.573492)
		(width 0.0889)
		(layer "In4.Cu")
		(net "M_J_CPU0_SB_DQ<2>")
	)
	(segment
		(start 411.00375 -281.012392)
		(end 411.165802 -281.174444)
		(width 0.14478)
		(layer "In4.Cu")
		(net "M_J_CPU0_SB_DQ<2>")
	)
	(segment
		(start 395.237716 -273.64563)
		(end 395.489176 -273.39417)
		(width 0.0889)
		(layer "In4.Cu")
		(net "M_J_CPU0_SB_DQ<2>")
	)
	(segment
		(start 409.605226 -279.84196)
		(end 409.284424 -280.162508)
		(width 0.14478)
		(layer "In4.Cu")
		(net "M_J_CPU0_SB_DQ<2>")
	)
	(segment
		(start 392.140948 -274.562316)
		(end 392.161014 -274.573746)
		(width 0.0889)
		(layer "In4.Cu")
		(net "M_J_CPU0_SB_DQ<2>")
	)
	(segment
		(start 409.605226 -279.613868)
		(end 409.605226 -279.84196)
		(width 0.14478)
		(layer "In4.Cu")
		(net "M_J_CPU0_SB_DQ<2>")
	)
	(segment
		(start 411.165802 -281.174444)
		(end 411.165802 -281.402536)
		(width 0.14478)
		(layer "In4.Cu")
		(net "M_J_CPU0_SB_DQ<2>")
	)
	(segment
		(start 392.161014 -274.573746)
		(end 392.182604 -274.586192)
		(width 0.0889)
		(layer "In4.Cu")
		(net "M_J_CPU0_SB_DQ<2>")
	)
	(segment
		(start 380.84887 -274.630642)
		(end 380.944882 -274.605242)
		(width 0.0889)
		(layer "In4.Cu")
		(net "M_J_CPU0_SB_DQ<2>")
	)
	(segment
		(start 429.499268 -281.910028)
		(end 434.575204 -281.910028)
		(width 0.14478)
		(layer "In4.Cu")
		(net "M_J_CPU0_SB_DQ<2>")
	)
	(segment
		(start 426.5168 -282.760166)
		(end 428.64913 -282.760166)
		(width 0.14478)
		(layer "In4.Cu")
		(net "M_J_CPU0_SB_DQ<2>")
	)
	(segment
		(start 414.940242 -281.910028)
		(end 418.122608 -281.910028)
		(width 0.14478)
		(layer "In4.Cu")
		(net "M_J_CPU0_SB_DQ<2>")
	)
	(segment
		(start 408.824938 -278.83358)
		(end 408.824938 -279.061672)
		(width 0.14478)
		(layer "In4.Cu")
		(net "M_J_CPU0_SB_DQ<2>")
	)
	(segment
		(start 410.064712 -280.942796)
		(end 410.064712 -281.170888)
		(width 0.14478)
		(layer "In4.Cu")
		(net "M_J_CPU0_SB_DQ<2>")
	)
	(segment
		(start 409.446476 -280.552652)
		(end 409.674568 -280.552652)
		(width 0.14478)
		(layer "In4.Cu")
		(net "M_J_CPU0_SB_DQ<2>")
	)
	(segment
		(start 383.693416 -274.568666)
		(end 383.701798 -274.573492)
		(width 0.0889)
		(layer "In4.Cu")
		(net "M_J_CPU0_SB_DQ<2>")
	)
	(segment
		(start 408.824938 -279.061672)
		(end 408.504136 -279.38222)
		(width 0.14478)
		(layer "In4.Cu")
		(net "M_J_CPU0_SB_DQ<2>")
	)
	(arc
		(start 391.787634 -274.573492)
		(mid 391.962873 -274.523421)
		(end 392.140948 -274.562316)
		(width 0.0889)
		(layer "In4.Cu")
		(net "M_J_CPU0_SB_DQ<2>")
	)
	(arc
		(start 383.327656 -274.573492)
		(mid 383.509907 -274.523142)
		(end 383.693416 -274.568666)
		(width 0.0889)
		(layer "In4.Cu")
		(net "M_J_CPU0_SB_DQ<2>")
	)
	(arc
		(start 386.1562 -274.568666)
		(mid 386.339708 -274.523172)
		(end 386.52196 -274.573492)
		(width 0.0889)
		(layer "In4.Cu")
		(net "M_J_CPU0_SB_DQ<2>")
	)
	(arc
		(start 387.46176 -274.573492)
		(mid 387.744716 -274.649669)
		(end 388.027672 -274.573492)
		(width 0.0889)
		(layer "In4.Cu")
		(net "M_J_CPU0_SB_DQ<2>")
	)
	(arc
		(start 383.701798 -274.573492)
		(mid 383.984754 -274.649669)
		(end 384.26771 -274.573492)
		(width 0.0889)
		(layer "In4.Cu")
		(net "M_J_CPU0_SB_DQ<2>")
	)
	(arc
		(start 389.341868 -274.573492)
		(mid 389.624824 -274.649669)
		(end 389.90778 -274.573492)
		(width 0.0889)
		(layer "In4.Cu")
		(net "M_J_CPU0_SB_DQ<2>")
	)
	(arc
		(start 390.847834 -274.573492)
		(mid 391.034778 -274.523237)
		(end 391.221722 -274.573492)
		(width 0.0889)
		(layer "In4.Cu")
		(net "M_J_CPU0_SB_DQ<2>")
	)
	(arc
		(start 388.027672 -274.573492)
		(mid 388.209923 -274.523142)
		(end 388.393432 -274.568666)
		(width 0.0889)
		(layer "In4.Cu")
		(net "M_J_CPU0_SB_DQ<2>")
	)
	(arc
		(start 387.087872 -274.573492)
		(mid 387.274816 -274.523237)
		(end 387.46176 -274.573492)
		(width 0.0889)
		(layer "In4.Cu")
		(net "M_J_CPU0_SB_DQ<2>")
	)
	(arc
		(start 385.581906 -274.573492)
		(mid 385.864862 -274.649669)
		(end 386.147818 -274.573492)
		(width 0.0889)
		(layer "In4.Cu")
		(net "M_J_CPU0_SB_DQ<2>")
	)
	(arc
		(start 382.387856 -274.573492)
		(mid 382.5748 -274.523237)
		(end 382.761744 -274.573492)
		(width 0.0889)
		(layer "In4.Cu")
		(net "M_J_CPU0_SB_DQ<2>")
	)
	(arc
		(start 392.182604 -274.586192)
		(mid 392.455633 -274.649511)
		(end 392.725402 -274.573492)
		(width 0.0889)
		(layer "In4.Cu")
		(net "M_J_CPU0_SB_DQ<2>")
	)
	(arc
		(start 392.744198 -274.56257)
		(mid 392.923769 -274.522753)
		(end 393.10056 -274.573492)
		(width 0.0889)
		(layer "In4.Cu")
		(net "M_J_CPU0_SB_DQ<2>")
	)
	(arc
		(start 391.221722 -274.573492)
		(mid 391.504678 -274.649669)
		(end 391.787634 -274.573492)
		(width 0.0889)
		(layer "In4.Cu")
		(net "M_J_CPU0_SB_DQ<2>")
	)
	(arc
		(start 380.944882 -274.605242)
		(mid 381.20009 -274.648719)
		(end 381.447802 -274.573492)
		(width 0.0889)
		(layer "In4.Cu")
		(net "M_J_CPU0_SB_DQ<2>")
	)
	(arc
		(start 381.821944 -274.573492)
		(mid 382.1049 -274.649669)
		(end 382.387856 -274.573492)
		(width 0.0889)
		(layer "In4.Cu")
		(net "M_J_CPU0_SB_DQ<2>")
	)
	(arc
		(start 388.401814 -274.573492)
		(mid 388.68477 -274.649669)
		(end 388.967726 -274.573492)
		(width 0.0889)
		(layer "In4.Cu")
		(net "M_J_CPU0_SB_DQ<2>")
	)
	(arc
		(start 389.916162 -274.568666)
		(mid 390.09967 -274.523172)
		(end 390.281922 -274.573492)
		(width 0.0889)
		(layer "In4.Cu")
		(net "M_J_CPU0_SB_DQ<2>")
	)
	(arc
		(start 386.52196 -274.573492)
		(mid 386.804916 -274.649669)
		(end 387.087872 -274.573492)
		(width 0.0889)
		(layer "In4.Cu")
		(net "M_J_CPU0_SB_DQ<2>")
	)
	(arc
		(start 384.26771 -274.573492)
		(mid 384.449961 -274.523142)
		(end 384.63347 -274.568666)
		(width 0.0889)
		(layer "In4.Cu")
		(net "M_J_CPU0_SB_DQ<2>")
	)
	(arc
		(start 381.456184 -274.568666)
		(mid 381.639692 -274.523172)
		(end 381.821944 -274.573492)
		(width 0.0889)
		(layer "In4.Cu")
		(net "M_J_CPU0_SB_DQ<2>")
	)
	(arc
		(start 382.761744 -274.573492)
		(mid 383.0447 -274.649669)
		(end 383.327656 -274.573492)
		(width 0.0889)
		(layer "In4.Cu")
		(net "M_J_CPU0_SB_DQ<2>")
	)
	(arc
		(start 393.10056 -274.573492)
		(mid 393.237582 -274.630703)
		(end 393.384786 -274.6502)
		(width 0.0889)
		(layer "In4.Cu")
		(net "M_J_CPU0_SB_DQ<2>")
	)
	(arc
		(start 390.281922 -274.573492)
		(mid 390.564878 -274.649669)
		(end 390.847834 -274.573492)
		(width 0.0889)
		(layer "In4.Cu")
		(net "M_J_CPU0_SB_DQ<2>")
	)
	(arc
		(start 388.967726 -274.573492)
		(mid 389.149977 -274.523142)
		(end 389.333486 -274.568666)
		(width 0.0889)
		(layer "In4.Cu")
		(net "M_J_CPU0_SB_DQ<2>")
	)
	(arc
		(start 385.216146 -274.568666)
		(mid 385.399654 -274.523172)
		(end 385.581906 -274.573492)
		(width 0.0889)
		(layer "In4.Cu")
		(net "M_J_CPU0_SB_DQ<2>")
	)
	(arc
		(start 384.641852 -274.573492)
		(mid 384.924808 -274.649669)
		(end 385.207764 -274.573492)
		(width 0.0889)
		(layer "In4.Cu")
		(net "M_J_CPU0_SB_DQ<2>")
	)
	(segment
		(start 379.28804 -292.450012)
		(end 379.754892 -292.71595)
		(width 0.10668)
		(layer "F.Cu")
		(net "M_J_CPU0_SB_DQ<29>")
	)
	(segment
		(start 409.59024 -317.610236)
		(end 438.675018 -317.610236)
		(width 0.14478)
		(layer "In4.Cu")
		(net "M_J_CPU0_SB_DQ<29>")
	)
	(segment
		(start 393.11961 -295.399714)
		(end 393.326112 -295.550336)
		(width 0.0889)
		(layer "In4.Cu")
		(net "M_J_CPU0_SB_DQ<29>")
	)
	(segment
		(start 392.727434 -294.658542)
		(end 392.76655 -294.681402)
		(width 0.0889)
		(layer "In4.Cu")
		(net "M_J_CPU0_SB_DQ<29>")
	)
	(segment
		(start 388.393432 -293.043356)
		(end 388.401814 -293.03853)
		(width 0.0889)
		(layer "In4.Cu")
		(net "M_J_CPU0_SB_DQ<29>")
	)
	(segment
		(start 408.626818 -317.211202)
		(end 409.59024 -317.610236)
		(width 0.14478)
		(layer "In4.Cu")
		(net "M_J_CPU0_SB_DQ<29>")
	)
	(segment
		(start 391.787634 -293.03853)
		(end 391.82675 -293.06139)
		(width 0.0889)
		(layer "In4.Cu")
		(net "M_J_CPU0_SB_DQ<29>")
	)
	(segment
		(start 392.257534 -293.848536)
		(end 392.29665 -293.871396)
		(width 0.0889)
		(layer "In4.Cu")
		(net "M_J_CPU0_SB_DQ<29>")
	)
	(segment
		(start 392.696954 -294.640762)
		(end 392.727434 -294.658542)
		(width 0.0889)
		(layer "In4.Cu")
		(net "M_J_CPU0_SB_DQ<29>")
	)
	(segment
		(start 393.433046 -295.681908)
		(end 393.510008 -295.85285)
		(width 0.0889)
		(layer "In4.Cu")
		(net "M_J_CPU0_SB_DQ<29>")
	)
	(segment
		(start 385.207764 -293.03853)
		(end 385.216146 -293.043356)
		(width 0.0889)
		(layer "In4.Cu")
		(net "M_J_CPU0_SB_DQ<29>")
	)
	(segment
		(start 381.447802 -293.03853)
		(end 381.456184 -293.043356)
		(width 0.0889)
		(layer "In4.Cu")
		(net "M_J_CPU0_SB_DQ<29>")
	)
	(segment
		(start 380.477522 -293.02075)
		(end 380.507748 -293.03853)
		(width 0.0889)
		(layer "In4.Cu")
		(net "M_J_CPU0_SB_DQ<29>")
	)
	(segment
		(start 393.510008 -296.185336)
		(end 393.510008 -302.914812)
		(width 0.14478)
		(layer "In4.Cu")
		(net "M_J_CPU0_SB_DQ<29>")
	)
	(segment
		(start 392.227054 -293.830756)
		(end 392.257534 -293.848536)
		(width 0.0889)
		(layer "In4.Cu")
		(net "M_J_CPU0_SB_DQ<29>")
	)
	(segment
		(start 384.63347 -293.043356)
		(end 384.641852 -293.03853)
		(width 0.0889)
		(layer "In4.Cu")
		(net "M_J_CPU0_SB_DQ<29>")
	)
	(segment
		(start 389.333486 -293.043356)
		(end 389.341868 -293.03853)
		(width 0.0889)
		(layer "In4.Cu")
		(net "M_J_CPU0_SB_DQ<29>")
	)
	(segment
		(start 393.510008 -295.85285)
		(end 393.510008 -296.185336)
		(width 0.0889)
		(layer "In4.Cu")
		(net "M_J_CPU0_SB_DQ<29>")
	)
	(segment
		(start 383.693416 -293.043356)
		(end 383.701798 -293.03853)
		(width 0.0889)
		(layer "In4.Cu")
		(net "M_J_CPU0_SB_DQ<29>")
	)
	(segment
		(start 389.90778 -293.03853)
		(end 389.916162 -293.043356)
		(width 0.0889)
		(layer "In4.Cu")
		(net "M_J_CPU0_SB_DQ<29>")
	)
	(segment
		(start 399.642838 -308.227222)
		(end 408.626818 -317.211202)
		(width 0.14478)
		(layer "In4.Cu")
		(net "M_J_CPU0_SB_DQ<29>")
	)
	(segment
		(start 380.873508 -293.043356)
		(end 380.88189 -293.03853)
		(width 0.0889)
		(layer "In4.Cu")
		(net "M_J_CPU0_SB_DQ<29>")
	)
	(segment
		(start 393.510008 -302.914812)
		(end 398.822418 -308.227222)
		(width 0.14478)
		(layer "In4.Cu")
		(net "M_J_CPU0_SB_DQ<29>")
	)
	(segment
		(start 379.754892 -292.71595)
		(end 380.477522 -293.02075)
		(width 0.0889)
		(layer "In4.Cu")
		(net "M_J_CPU0_SB_DQ<29>")
	)
	(segment
		(start 438.675018 -317.610236)
		(end 439.100214 -317.18504)
		(width 0.14478)
		(layer "In4.Cu")
		(net "M_J_CPU0_SB_DQ<29>")
	)
	(segment
		(start 398.822418 -308.227222)
		(end 399.642838 -308.227222)
		(width 0.14478)
		(layer "In4.Cu")
		(net "M_J_CPU0_SB_DQ<29>")
	)
	(segment
		(start 386.147818 -293.03853)
		(end 386.1562 -293.043356)
		(width 0.0889)
		(layer "In4.Cu")
		(net "M_J_CPU0_SB_DQ<29>")
	)
	(arc
		(start 392.539982 -294.335962)
		(mid 392.581531 -294.507384)
		(end 392.696954 -294.640762)
		(width 0.0889)
		(layer "In4.Cu")
		(net "M_J_CPU0_SB_DQ<29>")
	)
	(arc
		(start 383.327656 -293.03853)
		(mid 383.509907 -293.08888)
		(end 383.693416 -293.043356)
		(width 0.0889)
		(layer "In4.Cu")
		(net "M_J_CPU0_SB_DQ<29>")
	)
	(arc
		(start 386.52196 -293.03853)
		(mid 386.804916 -292.962353)
		(end 387.087872 -293.03853)
		(width 0.0889)
		(layer "In4.Cu")
		(net "M_J_CPU0_SB_DQ<29>")
	)
	(arc
		(start 389.341868 -293.03853)
		(mid 389.624824 -292.962353)
		(end 389.90778 -293.03853)
		(width 0.0889)
		(layer "In4.Cu")
		(net "M_J_CPU0_SB_DQ<29>")
	)
	(arc
		(start 390.281922 -293.03853)
		(mid 390.564878 -292.962353)
		(end 390.847834 -293.03853)
		(width 0.0889)
		(layer "In4.Cu")
		(net "M_J_CPU0_SB_DQ<29>")
	)
	(arc
		(start 389.916162 -293.043356)
		(mid 390.09967 -293.08885)
		(end 390.281922 -293.03853)
		(width 0.0889)
		(layer "In4.Cu")
		(net "M_J_CPU0_SB_DQ<29>")
	)
	(arc
		(start 388.027672 -293.03853)
		(mid 388.209923 -293.08888)
		(end 388.393432 -293.043356)
		(width 0.0889)
		(layer "In4.Cu")
		(net "M_J_CPU0_SB_DQ<29>")
	)
	(arc
		(start 388.401814 -293.03853)
		(mid 388.68477 -292.962353)
		(end 388.967726 -293.03853)
		(width 0.0889)
		(layer "In4.Cu")
		(net "M_J_CPU0_SB_DQ<29>")
	)
	(arc
		(start 391.82675 -293.06139)
		(mid 392.005563 -293.26374)
		(end 392.070082 -293.525956)
		(width 0.0889)
		(layer "In4.Cu")
		(net "M_J_CPU0_SB_DQ<29>")
	)
	(arc
		(start 387.46176 -293.03853)
		(mid 387.744716 -292.962353)
		(end 388.027672 -293.03853)
		(width 0.0889)
		(layer "In4.Cu")
		(net "M_J_CPU0_SB_DQ<29>")
	)
	(arc
		(start 384.26771 -293.03853)
		(mid 384.449961 -293.08888)
		(end 384.63347 -293.043356)
		(width 0.0889)
		(layer "In4.Cu")
		(net "M_J_CPU0_SB_DQ<29>")
	)
	(arc
		(start 380.88189 -293.03853)
		(mid 381.164846 -292.962353)
		(end 381.447802 -293.03853)
		(width 0.0889)
		(layer "In4.Cu")
		(net "M_J_CPU0_SB_DQ<29>")
	)
	(arc
		(start 381.456184 -293.043356)
		(mid 381.639692 -293.08885)
		(end 381.821944 -293.03853)
		(width 0.0889)
		(layer "In4.Cu")
		(net "M_J_CPU0_SB_DQ<29>")
	)
	(arc
		(start 393.009882 -295.145968)
		(mid 393.0228 -295.243027)
		(end 393.060428 -295.33342)
		(width 0.0889)
		(layer "In4.Cu")
		(net "M_J_CPU0_SB_DQ<29>")
	)
	(arc
		(start 388.967726 -293.03853)
		(mid 389.149977 -293.08888)
		(end 389.333486 -293.043356)
		(width 0.0889)
		(layer "In4.Cu")
		(net "M_J_CPU0_SB_DQ<29>")
	)
	(arc
		(start 382.761744 -293.03853)
		(mid 383.0447 -292.962353)
		(end 383.327656 -293.03853)
		(width 0.0889)
		(layer "In4.Cu")
		(net "M_J_CPU0_SB_DQ<29>")
	)
	(arc
		(start 383.701798 -293.03853)
		(mid 383.984754 -292.962353)
		(end 384.26771 -293.03853)
		(width 0.0889)
		(layer "In4.Cu")
		(net "M_J_CPU0_SB_DQ<29>")
	)
	(arc
		(start 393.326112 -295.550336)
		(mid 393.38813 -295.609167)
		(end 393.433046 -295.681908)
		(width 0.0889)
		(layer "In4.Cu")
		(net "M_J_CPU0_SB_DQ<29>")
	)
	(arc
		(start 392.76655 -294.681402)
		(mid 392.945363 -294.883752)
		(end 393.009882 -295.145968)
		(width 0.0889)
		(layer "In4.Cu")
		(net "M_J_CPU0_SB_DQ<29>")
	)
	(arc
		(start 392.070082 -293.525956)
		(mid 392.111631 -293.697378)
		(end 392.227054 -293.830756)
		(width 0.0889)
		(layer "In4.Cu")
		(net "M_J_CPU0_SB_DQ<29>")
	)
	(arc
		(start 384.641852 -293.03853)
		(mid 384.924808 -292.962353)
		(end 385.207764 -293.03853)
		(width 0.0889)
		(layer "In4.Cu")
		(net "M_J_CPU0_SB_DQ<29>")
	)
	(arc
		(start 380.507748 -293.03853)
		(mid 380.689999 -293.08888)
		(end 380.873508 -293.043356)
		(width 0.0889)
		(layer "In4.Cu")
		(net "M_J_CPU0_SB_DQ<29>")
	)
	(arc
		(start 387.087872 -293.03853)
		(mid 387.274816 -293.088785)
		(end 387.46176 -293.03853)
		(width 0.0889)
		(layer "In4.Cu")
		(net "M_J_CPU0_SB_DQ<29>")
	)
	(arc
		(start 386.1562 -293.043356)
		(mid 386.339708 -293.08885)
		(end 386.52196 -293.03853)
		(width 0.0889)
		(layer "In4.Cu")
		(net "M_J_CPU0_SB_DQ<29>")
	)
	(arc
		(start 385.581906 -293.03853)
		(mid 385.864862 -292.962353)
		(end 386.147818 -293.03853)
		(width 0.0889)
		(layer "In4.Cu")
		(net "M_J_CPU0_SB_DQ<29>")
	)
	(arc
		(start 385.216146 -293.043356)
		(mid 385.399654 -293.08885)
		(end 385.581906 -293.03853)
		(width 0.0889)
		(layer "In4.Cu")
		(net "M_J_CPU0_SB_DQ<29>")
	)
	(arc
		(start 381.821944 -293.03853)
		(mid 382.1049 -292.962353)
		(end 382.387856 -293.03853)
		(width 0.0889)
		(layer "In4.Cu")
		(net "M_J_CPU0_SB_DQ<29>")
	)
	(arc
		(start 392.29665 -293.871396)
		(mid 392.475463 -294.073746)
		(end 392.539982 -294.335962)
		(width 0.0889)
		(layer "In4.Cu")
		(net "M_J_CPU0_SB_DQ<29>")
	)
	(arc
		(start 391.221722 -293.03853)
		(mid 391.504678 -292.962353)
		(end 391.787634 -293.03853)
		(width 0.0889)
		(layer "In4.Cu")
		(net "M_J_CPU0_SB_DQ<29>")
	)
	(arc
		(start 393.060428 -295.33342)
		(mid 393.086562 -295.369652)
		(end 393.11961 -295.399714)
		(width 0.0889)
		(layer "In4.Cu")
		(net "M_J_CPU0_SB_DQ<29>")
	)
	(arc
		(start 382.387856 -293.03853)
		(mid 382.5748 -293.088785)
		(end 382.761744 -293.03853)
		(width 0.0889)
		(layer "In4.Cu")
		(net "M_J_CPU0_SB_DQ<29>")
	)
	(arc
		(start 390.847834 -293.03853)
		(mid 391.034778 -293.088785)
		(end 391.221722 -293.03853)
		(width 0.0889)
		(layer "In4.Cu")
		(net "M_J_CPU0_SB_DQ<29>")
	)
	(segment
		(start 380.697994 -291.640006)
		(end 381.164846 -291.905944)
		(width 0.10668)
		(layer "F.Cu")
		(net "M_J_CPU0_SB_DQ<28>")
	)
	(segment
		(start 382.283462 -292.23335)
		(end 382.291844 -292.228524)
		(width 0.0889)
		(layer "In4.Cu")
		(net "M_J_CPU0_SB_DQ<28>")
	)
	(segment
		(start 393.667742 -294.658542)
		(end 393.704064 -294.679624)
		(width 0.0889)
		(layer "In4.Cu")
		(net "M_J_CPU0_SB_DQ<28>")
	)
	(segment
		(start 436.98033 -315.919866)
		(end 437.208676 -315.919866)
		(width 0.14478)
		(layer "In4.Cu")
		(net "M_J_CPU0_SB_DQ<28>")
	)
	(segment
		(start 437.37022 -316.08141)
		(end 437.37022 -316.588648)
		(width 0.14478)
		(layer "In4.Cu")
		(net "M_J_CPU0_SB_DQ<28>")
	)
	(segment
		(start 437.208676 -315.919866)
		(end 437.37022 -316.08141)
		(width 0.14478)
		(layer "In4.Cu")
		(net "M_J_CPU0_SB_DQ<28>")
	)
	(segment
		(start 386.043424 -292.23335)
		(end 386.051806 -292.228524)
		(width 0.0889)
		(layer "In4.Cu")
		(net "M_J_CPU0_SB_DQ<28>")
	)
	(segment
		(start 438.665366 -315.919866)
		(end 439.100214 -315.485018)
		(width 0.14478)
		(layer "In4.Cu")
		(net "M_J_CPU0_SB_DQ<28>")
	)
	(segment
		(start 438.083198 -315.919866)
		(end 438.665366 -315.919866)
		(width 0.14478)
		(layer "In4.Cu")
		(net "M_J_CPU0_SB_DQ<28>")
	)
	(segment
		(start 381.010922 -292.171374)
		(end 381.033274 -292.254686)
		(width 0.0889)
		(layer "In4.Cu")
		(net "M_J_CPU0_SB_DQ<28>")
	)
	(segment
		(start 381.164846 -291.905944)
		(end 381.010922 -292.171374)
		(width 0.0889)
		(layer "In4.Cu")
		(net "M_J_CPU0_SB_DQ<28>")
	)
	(segment
		(start 408.608022 -315.919866)
		(end 436.105808 -315.919866)
		(width 0.14478)
		(layer "In4.Cu")
		(net "M_J_CPU0_SB_DQ<28>")
	)
	(segment
		(start 436.105808 -315.919866)
		(end 436.267352 -316.08141)
		(width 0.14478)
		(layer "In4.Cu")
		(net "M_J_CPU0_SB_DQ<28>")
	)
	(segment
		(start 394.419328 -301.731172)
		(end 408.608022 -315.919866)
		(width 0.14478)
		(layer "In4.Cu")
		(net "M_J_CPU0_SB_DQ<28>")
	)
	(segment
		(start 391.317734 -292.228524)
		(end 391.326116 -292.23335)
		(width 0.0889)
		(layer "In4.Cu")
		(net "M_J_CPU0_SB_DQ<28>")
	)
	(segment
		(start 436.428896 -316.750192)
		(end 436.657242 -316.750192)
		(width 0.14478)
		(layer "In4.Cu")
		(net "M_J_CPU0_SB_DQ<28>")
	)
	(segment
		(start 436.818786 -316.588648)
		(end 436.818786 -316.08141)
		(width 0.14478)
		(layer "In4.Cu")
		(net "M_J_CPU0_SB_DQ<28>")
	)
	(segment
		(start 393.635992 -294.640254)
		(end 393.667742 -294.658542)
		(width 0.0889)
		(layer "In4.Cu")
		(net "M_J_CPU0_SB_DQ<28>")
	)
	(segment
		(start 388.497826 -292.228524)
		(end 388.506208 -292.23335)
		(width 0.0889)
		(layer "In4.Cu")
		(net "M_J_CPU0_SB_DQ<28>")
	)
	(segment
		(start 436.818786 -316.08141)
		(end 436.98033 -315.919866)
		(width 0.14478)
		(layer "In4.Cu")
		(net "M_J_CPU0_SB_DQ<28>")
	)
	(segment
		(start 392.697208 -293.02075)
		(end 392.727688 -293.03853)
		(width 0.0889)
		(layer "In4.Cu")
		(net "M_J_CPU0_SB_DQ<28>")
	)
	(segment
		(start 393.197588 -293.848536)
		(end 393.236704 -293.871396)
		(width 0.0889)
		(layer "In4.Cu")
		(net "M_J_CPU0_SB_DQ<28>")
	)
	(segment
		(start 383.79781 -292.228524)
		(end 383.806192 -292.23335)
		(width 0.0889)
		(layer "In4.Cu")
		(net "M_J_CPU0_SB_DQ<28>")
	)
	(segment
		(start 437.37022 -316.588648)
		(end 437.531764 -316.750192)
		(width 0.14478)
		(layer "In4.Cu")
		(net "M_J_CPU0_SB_DQ<28>")
	)
	(segment
		(start 394.419328 -295.61536)
		(end 394.419328 -295.995344)
		(width 0.0889)
		(layer "In4.Cu")
		(net "M_J_CPU0_SB_DQ<28>")
	)
	(segment
		(start 392.257788 -292.228524)
		(end 392.296904 -292.251384)
		(width 0.0889)
		(layer "In4.Cu")
		(net "M_J_CPU0_SB_DQ<28>")
	)
	(segment
		(start 386.983478 -292.23335)
		(end 386.99186 -292.228524)
		(width 0.0889)
		(layer "In4.Cu")
		(net "M_J_CPU0_SB_DQ<28>")
	)
	(segment
		(start 436.657242 -316.750192)
		(end 436.818786 -316.588648)
		(width 0.14478)
		(layer "In4.Cu")
		(net "M_J_CPU0_SB_DQ<28>")
	)
	(segment
		(start 437.76011 -316.750192)
		(end 437.921654 -316.588648)
		(width 0.14478)
		(layer "In4.Cu")
		(net "M_J_CPU0_SB_DQ<28>")
	)
	(segment
		(start 437.921654 -316.08141)
		(end 438.083198 -315.919866)
		(width 0.14478)
		(layer "In4.Cu")
		(net "M_J_CPU0_SB_DQ<28>")
	)
	(segment
		(start 437.531764 -316.750192)
		(end 437.76011 -316.750192)
		(width 0.14478)
		(layer "In4.Cu")
		(net "M_J_CPU0_SB_DQ<28>")
	)
	(segment
		(start 392.727688 -293.03853)
		(end 392.766804 -293.06139)
		(width 0.0889)
		(layer "In4.Cu")
		(net "M_J_CPU0_SB_DQ<28>")
	)
	(segment
		(start 393.949936 -295.145968)
		(end 394.419328 -295.61536)
		(width 0.0889)
		(layer "In4.Cu")
		(net "M_J_CPU0_SB_DQ<28>")
	)
	(segment
		(start 382.857756 -292.228524)
		(end 382.866138 -292.23335)
		(width 0.0889)
		(layer "In4.Cu")
		(net "M_J_CPU0_SB_DQ<28>")
	)
	(segment
		(start 436.267352 -316.588648)
		(end 436.428896 -316.750192)
		(width 0.14478)
		(layer "In4.Cu")
		(net "M_J_CPU0_SB_DQ<28>")
	)
	(segment
		(start 437.921654 -316.588648)
		(end 437.921654 -316.08141)
		(width 0.14478)
		(layer "In4.Cu")
		(net "M_J_CPU0_SB_DQ<28>")
	)
	(segment
		(start 436.267352 -316.08141)
		(end 436.267352 -316.588648)
		(width 0.14478)
		(layer "In4.Cu")
		(net "M_J_CPU0_SB_DQ<28>")
	)
	(segment
		(start 393.167108 -293.830756)
		(end 393.197588 -293.848536)
		(width 0.0889)
		(layer "In4.Cu")
		(net "M_J_CPU0_SB_DQ<28>")
	)
	(segment
		(start 387.557772 -292.228524)
		(end 387.566154 -292.23335)
		(width 0.0889)
		(layer "In4.Cu")
		(net "M_J_CPU0_SB_DQ<28>")
	)
	(segment
		(start 390.74344 -292.23335)
		(end 390.751822 -292.228524)
		(width 0.0889)
		(layer "In4.Cu")
		(net "M_J_CPU0_SB_DQ<28>")
	)
	(segment
		(start 394.419328 -295.995344)
		(end 394.419328 -301.731172)
		(width 0.14478)
		(layer "In4.Cu")
		(net "M_J_CPU0_SB_DQ<28>")
	)
	(arc
		(start 381.35179 -292.228524)
		(mid 381.634746 -292.152347)
		(end 381.917702 -292.228524)
		(width 0.0889)
		(layer "In4.Cu")
		(net "M_J_CPU0_SB_DQ<28>")
	)
	(arc
		(start 386.617718 -292.228524)
		(mid 386.799969 -292.278874)
		(end 386.983478 -292.23335)
		(width 0.0889)
		(layer "In4.Cu")
		(net "M_J_CPU0_SB_DQ<28>")
	)
	(arc
		(start 381.917702 -292.228524)
		(mid 382.099953 -292.278874)
		(end 382.283462 -292.23335)
		(width 0.0889)
		(layer "In4.Cu")
		(net "M_J_CPU0_SB_DQ<28>")
	)
	(arc
		(start 390.37768 -292.228524)
		(mid 390.559931 -292.278874)
		(end 390.74344 -292.23335)
		(width 0.0889)
		(layer "In4.Cu")
		(net "M_J_CPU0_SB_DQ<28>")
	)
	(arc
		(start 393.480036 -294.335962)
		(mid 393.521291 -294.506933)
		(end 393.635992 -294.640254)
		(width 0.0889)
		(layer "In4.Cu")
		(net "M_J_CPU0_SB_DQ<28>")
	)
	(arc
		(start 393.236704 -293.871396)
		(mid 393.415517 -294.073746)
		(end 393.480036 -294.335962)
		(width 0.0889)
		(layer "In4.Cu")
		(net "M_J_CPU0_SB_DQ<28>")
	)
	(arc
		(start 389.811768 -292.228524)
		(mid 390.094724 -292.152347)
		(end 390.37768 -292.228524)
		(width 0.0889)
		(layer "In4.Cu")
		(net "M_J_CPU0_SB_DQ<28>")
	)
	(arc
		(start 390.751822 -292.228524)
		(mid 391.034778 -292.152347)
		(end 391.317734 -292.228524)
		(width 0.0889)
		(layer "In4.Cu")
		(net "M_J_CPU0_SB_DQ<28>")
	)
	(arc
		(start 383.806192 -292.23335)
		(mid 383.9897 -292.278844)
		(end 384.171952 -292.228524)
		(width 0.0889)
		(layer "In4.Cu")
		(net "M_J_CPU0_SB_DQ<28>")
	)
	(arc
		(start 381.033274 -292.254686)
		(mid 381.195463 -292.277421)
		(end 381.35179 -292.228524)
		(width 0.0889)
		(layer "In4.Cu")
		(net "M_J_CPU0_SB_DQ<28>")
	)
	(arc
		(start 387.566154 -292.23335)
		(mid 387.749662 -292.278844)
		(end 387.931914 -292.228524)
		(width 0.0889)
		(layer "In4.Cu")
		(net "M_J_CPU0_SB_DQ<28>")
	)
	(arc
		(start 382.291844 -292.228524)
		(mid 382.5748 -292.152347)
		(end 382.857756 -292.228524)
		(width 0.0889)
		(layer "In4.Cu")
		(net "M_J_CPU0_SB_DQ<28>")
	)
	(arc
		(start 393.704064 -294.679624)
		(mid 393.884716 -294.882369)
		(end 393.949936 -295.145968)
		(width 0.0889)
		(layer "In4.Cu")
		(net "M_J_CPU0_SB_DQ<28>")
	)
	(arc
		(start 384.171952 -292.228524)
		(mid 384.454908 -292.152347)
		(end 384.737864 -292.228524)
		(width 0.0889)
		(layer "In4.Cu")
		(net "M_J_CPU0_SB_DQ<28>")
	)
	(arc
		(start 393.010136 -293.525956)
		(mid 393.051685 -293.697378)
		(end 393.167108 -293.830756)
		(width 0.0889)
		(layer "In4.Cu")
		(net "M_J_CPU0_SB_DQ<28>")
	)
	(arc
		(start 391.326116 -292.23335)
		(mid 391.509624 -292.278844)
		(end 391.691876 -292.228524)
		(width 0.0889)
		(layer "In4.Cu")
		(net "M_J_CPU0_SB_DQ<28>")
	)
	(arc
		(start 384.737864 -292.228524)
		(mid 384.924808 -292.278779)
		(end 385.111752 -292.228524)
		(width 0.0889)
		(layer "In4.Cu")
		(net "M_J_CPU0_SB_DQ<28>")
	)
	(arc
		(start 388.506208 -292.23335)
		(mid 388.689716 -292.278844)
		(end 388.871968 -292.228524)
		(width 0.0889)
		(layer "In4.Cu")
		(net "M_J_CPU0_SB_DQ<28>")
	)
	(arc
		(start 392.766804 -293.06139)
		(mid 392.945617 -293.26374)
		(end 393.010136 -293.525956)
		(width 0.0889)
		(layer "In4.Cu")
		(net "M_J_CPU0_SB_DQ<28>")
	)
	(arc
		(start 391.691876 -292.228524)
		(mid 391.974832 -292.152347)
		(end 392.257788 -292.228524)
		(width 0.0889)
		(layer "In4.Cu")
		(net "M_J_CPU0_SB_DQ<28>")
	)
	(arc
		(start 392.540236 -292.71595)
		(mid 392.581785 -292.887372)
		(end 392.697208 -293.02075)
		(width 0.0889)
		(layer "In4.Cu")
		(net "M_J_CPU0_SB_DQ<28>")
	)
	(arc
		(start 385.677664 -292.228524)
		(mid 385.859915 -292.278874)
		(end 386.043424 -292.23335)
		(width 0.0889)
		(layer "In4.Cu")
		(net "M_J_CPU0_SB_DQ<28>")
	)
	(arc
		(start 382.866138 -292.23335)
		(mid 383.049646 -292.278844)
		(end 383.231898 -292.228524)
		(width 0.0889)
		(layer "In4.Cu")
		(net "M_J_CPU0_SB_DQ<28>")
	)
	(arc
		(start 383.231898 -292.228524)
		(mid 383.514854 -292.152347)
		(end 383.79781 -292.228524)
		(width 0.0889)
		(layer "In4.Cu")
		(net "M_J_CPU0_SB_DQ<28>")
	)
	(arc
		(start 386.051806 -292.228524)
		(mid 386.334762 -292.152347)
		(end 386.617718 -292.228524)
		(width 0.0889)
		(layer "In4.Cu")
		(net "M_J_CPU0_SB_DQ<28>")
	)
	(arc
		(start 389.43788 -292.228524)
		(mid 389.624824 -292.278779)
		(end 389.811768 -292.228524)
		(width 0.0889)
		(layer "In4.Cu")
		(net "M_J_CPU0_SB_DQ<28>")
	)
	(arc
		(start 387.931914 -292.228524)
		(mid 388.21487 -292.152347)
		(end 388.497826 -292.228524)
		(width 0.0889)
		(layer "In4.Cu")
		(net "M_J_CPU0_SB_DQ<28>")
	)
	(arc
		(start 386.99186 -292.228524)
		(mid 387.274816 -292.152347)
		(end 387.557772 -292.228524)
		(width 0.0889)
		(layer "In4.Cu")
		(net "M_J_CPU0_SB_DQ<28>")
	)
	(arc
		(start 392.296904 -292.251384)
		(mid 392.475717 -292.453734)
		(end 392.540236 -292.71595)
		(width 0.0889)
		(layer "In4.Cu")
		(net "M_J_CPU0_SB_DQ<28>")
	)
	(arc
		(start 385.111752 -292.228524)
		(mid 385.394708 -292.152347)
		(end 385.677664 -292.228524)
		(width 0.0889)
		(layer "In4.Cu")
		(net "M_J_CPU0_SB_DQ<28>")
	)
	(arc
		(start 388.871968 -292.228524)
		(mid 389.154924 -292.152347)
		(end 389.43788 -292.228524)
		(width 0.0889)
		(layer "In4.Cu")
		(net "M_J_CPU0_SB_DQ<28>")
	)
	(segment
		(start 378.817886 -290.019994)
		(end 379.284738 -290.285932)
		(width 0.10668)
		(layer "F.Cu")
		(net "M_J_CPU0_SB_DQ<27>")
	)
	(segment
		(start 417.414202 -311.660032)
		(end 417.894516 -311.660032)
		(width 0.14478)
		(layer "In4.Cu")
		(net "M_J_CPU0_SB_DQ<27>")
	)
	(segment
		(start 388.497826 -289.963352)
		(end 388.506208 -289.958526)
		(width 0.0889)
		(layer "In4.Cu")
		(net "M_J_CPU0_SB_DQ<27>")
	)
	(segment
		(start 395.17701 -292.84803)
		(end 396.767558 -294.438578)
		(width 0.14478)
		(layer "In4.Cu")
		(net "M_J_CPU0_SB_DQ<27>")
	)
	(segment
		(start 390.74344 -289.958526)
		(end 390.751822 -289.963352)
		(width 0.0889)
		(layer "In4.Cu")
		(net "M_J_CPU0_SB_DQ<27>")
	)
	(segment
		(start 412.404814 -312.509916)
		(end 412.708598 -312.206132)
		(width 0.14478)
		(layer "In4.Cu")
		(net "M_J_CPU0_SB_DQ<27>")
	)
	(segment
		(start 433.906168 -311.930288)
		(end 433.906168 -311.421018)
		(width 0.14478)
		(layer "In4.Cu")
		(net "M_J_CPU0_SB_DQ<27>")
	)
	(segment
		(start 387.557772 -289.963352)
		(end 387.566154 -289.958526)
		(width 0.0889)
		(layer "In4.Cu")
		(net "M_J_CPU0_SB_DQ<27>")
	)
	(segment
		(start 379.438916 -290.020502)
		(end 379.535182 -289.995102)
		(width 0.0889)
		(layer "In4.Cu")
		(net "M_J_CPU0_SB_DQ<27>")
	)
	(segment
		(start 434.692298 -311.521348)
		(end 434.692298 -311.940194)
		(width 0.14478)
		(layer "In4.Cu")
		(net "M_J_CPU0_SB_DQ<27>")
	)
	(segment
		(start 382.283462 -289.958526)
		(end 382.291844 -289.963352)
		(width 0.0889)
		(layer "In4.Cu")
		(net "M_J_CPU0_SB_DQ<27>")
	)
	(segment
		(start 392.6713 -290.039552)
		(end 392.826748 -289.884104)
		(width 0.0889)
		(layer "In4.Cu")
		(net "M_J_CPU0_SB_DQ<27>")
	)
	(segment
		(start 422.282112 -311.65038)
		(end 425.855638 -311.65038)
		(width 0.14478)
		(layer "In4.Cu")
		(net "M_J_CPU0_SB_DQ<27>")
	)
	(segment
		(start 425.855638 -311.65038)
		(end 426.705522 -312.500264)
		(width 0.14478)
		(layer "In4.Cu")
		(net "M_J_CPU0_SB_DQ<27>")
	)
	(segment
		(start 409.951428 -312.509916)
		(end 410.199078 -312.509916)
		(width 0.14478)
		(layer "In4.Cu")
		(net "M_J_CPU0_SB_DQ<27>")
	)
	(segment
		(start 432.200558 -311.65038)
		(end 432.591464 -311.259474)
		(width 0.14478)
		(layer "In4.Cu")
		(net "M_J_CPU0_SB_DQ<27>")
	)
	(segment
		(start 417.122102 -311.367932)
		(end 417.414202 -311.660032)
		(width 0.14478)
		(layer "In4.Cu")
		(net "M_J_CPU0_SB_DQ<27>")
	)
	(segment
		(start 413.878522 -312.509916)
		(end 414.728406 -311.660032)
		(width 0.14478)
		(layer "In4.Cu")
		(net "M_J_CPU0_SB_DQ<27>")
	)
	(segment
		(start 410.750512 -312.206132)
		(end 411.054296 -312.509916)
		(width 0.14478)
		(layer "In4.Cu")
		(net "M_J_CPU0_SB_DQ<27>")
	)
	(segment
		(start 411.301946 -312.509916)
		(end 411.60573 -312.206132)
		(width 0.14478)
		(layer "In4.Cu")
		(net "M_J_CPU0_SB_DQ<27>")
	)
	(segment
		(start 429.886364 -311.65038)
		(end 432.200558 -311.65038)
		(width 0.14478)
		(layer "In4.Cu")
		(net "M_J_CPU0_SB_DQ<27>")
	)
	(segment
		(start 433.744624 -312.091832)
		(end 433.906168 -311.930288)
		(width 0.14478)
		(layer "In4.Cu")
		(net "M_J_CPU0_SB_DQ<27>")
	)
	(segment
		(start 386.043424 -289.958526)
		(end 386.051806 -289.963352)
		(width 0.0889)
		(layer "In4.Cu")
		(net "M_J_CPU0_SB_DQ<27>")
	)
	(segment
		(start 432.591464 -311.259474)
		(end 433.19319 -311.259474)
		(width 0.14478)
		(layer "In4.Cu")
		(net "M_J_CPU0_SB_DQ<27>")
	)
	(segment
		(start 415.4678 -311.660032)
		(end 415.7599 -311.367932)
		(width 0.14478)
		(layer "In4.Cu")
		(net "M_J_CPU0_SB_DQ<27>")
	)
	(segment
		(start 393.545568 -289.884104)
		(end 393.872974 -290.21151)
		(width 0.0889)
		(layer "In4.Cu")
		(net "M_J_CPU0_SB_DQ<27>")
	)
	(segment
		(start 421.432228 -312.500264)
		(end 422.282112 -311.65038)
		(width 0.14478)
		(layer "In4.Cu")
		(net "M_J_CPU0_SB_DQ<27>")
	)
	(segment
		(start 382.857756 -289.963352)
		(end 382.866138 -289.958526)
		(width 0.0889)
		(layer "In4.Cu")
		(net "M_J_CPU0_SB_DQ<27>")
	)
	(segment
		(start 409.09621 -312.509916)
		(end 409.399994 -312.206132)
		(width 0.14478)
		(layer "In4.Cu")
		(net "M_J_CPU0_SB_DQ<27>")
	)
	(segment
		(start 380.037848 -289.963352)
		(end 380.04623 -289.958526)
		(width 0.0889)
		(layer "In4.Cu")
		(net "M_J_CPU0_SB_DQ<27>")
	)
	(segment
		(start 411.054296 -312.509916)
		(end 411.301946 -312.509916)
		(width 0.14478)
		(layer "In4.Cu")
		(net "M_J_CPU0_SB_DQ<27>")
	)
	(segment
		(start 394.443966 -292.420802)
		(end 394.871194 -292.84803)
		(width 0.0889)
		(layer "In4.Cu")
		(net "M_J_CPU0_SB_DQ<27>")
	)
	(segment
		(start 392.826748 -289.884104)
		(end 393.545568 -289.884104)
		(width 0.0889)
		(layer "In4.Cu")
		(net "M_J_CPU0_SB_DQ<27>")
	)
	(segment
		(start 410.199078 -312.509916)
		(end 410.502862 -312.206132)
		(width 0.14478)
		(layer "In4.Cu")
		(net "M_J_CPU0_SB_DQ<27>")
	)
	(segment
		(start 386.983478 -289.958526)
		(end 386.99186 -289.963352)
		(width 0.0889)
		(layer "In4.Cu")
		(net "M_J_CPU0_SB_DQ<27>")
	)
	(segment
		(start 391.317734 -289.963352)
		(end 391.326116 -289.958526)
		(width 0.0889)
		(layer "In4.Cu")
		(net "M_J_CPU0_SB_DQ<27>")
	)
	(segment
		(start 416.019234 -311.367932)
		(end 416.311334 -311.660032)
		(width 0.14478)
		(layer "In4.Cu")
		(net "M_J_CPU0_SB_DQ<27>")
	)
	(segment
		(start 410.502862 -312.206132)
		(end 410.750512 -312.206132)
		(width 0.14478)
		(layer "In4.Cu")
		(net "M_J_CPU0_SB_DQ<27>")
	)
	(segment
		(start 416.570668 -311.660032)
		(end 416.862768 -311.367932)
		(width 0.14478)
		(layer "In4.Cu")
		(net "M_J_CPU0_SB_DQ<27>")
	)
	(segment
		(start 379.284738 -290.285932)
		(end 379.438916 -290.020502)
		(width 0.0889)
		(layer "In4.Cu")
		(net "M_J_CPU0_SB_DQ<27>")
	)
	(segment
		(start 417.894516 -311.660032)
		(end 418.734748 -312.500264)
		(width 0.14478)
		(layer "In4.Cu")
		(net "M_J_CPU0_SB_DQ<27>")
	)
	(segment
		(start 394.871194 -292.84803)
		(end 395.17701 -292.84803)
		(width 0.0889)
		(layer "In4.Cu")
		(net "M_J_CPU0_SB_DQ<27>")
	)
	(segment
		(start 416.311334 -311.660032)
		(end 416.570668 -311.660032)
		(width 0.14478)
		(layer "In4.Cu")
		(net "M_J_CPU0_SB_DQ<27>")
	)
	(segment
		(start 391.974832 -290.039552)
		(end 392.6713 -290.039552)
		(width 0.0889)
		(layer "In4.Cu")
		(net "M_J_CPU0_SB_DQ<27>")
	)
	(segment
		(start 414.728406 -311.660032)
		(end 415.4678 -311.660032)
		(width 0.14478)
		(layer "In4.Cu")
		(net "M_J_CPU0_SB_DQ<27>")
	)
	(segment
		(start 434.430424 -311.259474)
		(end 434.692298 -311.521348)
		(width 0.14478)
		(layer "In4.Cu")
		(net "M_J_CPU0_SB_DQ<27>")
	)
	(segment
		(start 396.767558 -294.438578)
		(end 396.767558 -300.842172)
		(width 0.14478)
		(layer "In4.Cu")
		(net "M_J_CPU0_SB_DQ<27>")
	)
	(segment
		(start 411.60573 -312.206132)
		(end 411.85338 -312.206132)
		(width 0.14478)
		(layer "In4.Cu")
		(net "M_J_CPU0_SB_DQ<27>")
	)
	(segment
		(start 418.734748 -312.500264)
		(end 421.432228 -312.500264)
		(width 0.14478)
		(layer "In4.Cu")
		(net "M_J_CPU0_SB_DQ<27>")
	)
	(segment
		(start 409.647644 -312.206132)
		(end 409.951428 -312.509916)
		(width 0.14478)
		(layer "In4.Cu")
		(net "M_J_CPU0_SB_DQ<27>")
	)
	(segment
		(start 412.708598 -312.206132)
		(end 412.956248 -312.206132)
		(width 0.14478)
		(layer "In4.Cu")
		(net "M_J_CPU0_SB_DQ<27>")
	)
	(segment
		(start 412.956248 -312.206132)
		(end 413.260032 -312.509916)
		(width 0.14478)
		(layer "In4.Cu")
		(net "M_J_CPU0_SB_DQ<27>")
	)
	(segment
		(start 411.85338 -312.206132)
		(end 412.157164 -312.509916)
		(width 0.14478)
		(layer "In4.Cu")
		(net "M_J_CPU0_SB_DQ<27>")
	)
	(segment
		(start 409.399994 -312.206132)
		(end 409.647644 -312.206132)
		(width 0.14478)
		(layer "In4.Cu")
		(net "M_J_CPU0_SB_DQ<27>")
	)
	(segment
		(start 433.354734 -311.930288)
		(end 433.516278 -312.091832)
		(width 0.14478)
		(layer "In4.Cu")
		(net "M_J_CPU0_SB_DQ<27>")
	)
	(segment
		(start 434.837078 -312.084974)
		(end 435.000146 -312.084974)
		(width 0.14478)
		(layer "In4.Cu")
		(net "M_J_CPU0_SB_DQ<27>")
	)
	(segment
		(start 412.157164 -312.509916)
		(end 412.404814 -312.509916)
		(width 0.14478)
		(layer "In4.Cu")
		(net "M_J_CPU0_SB_DQ<27>")
	)
	(segment
		(start 393.872974 -291.042598)
		(end 394.443966 -292.420802)
		(width 0.0889)
		(layer "In4.Cu")
		(net "M_J_CPU0_SB_DQ<27>")
	)
	(segment
		(start 433.516278 -312.091832)
		(end 433.744624 -312.091832)
		(width 0.14478)
		(layer "In4.Cu")
		(net "M_J_CPU0_SB_DQ<27>")
	)
	(segment
		(start 408.435302 -312.509916)
		(end 409.09621 -312.509916)
		(width 0.14478)
		(layer "In4.Cu")
		(net "M_J_CPU0_SB_DQ<27>")
	)
	(segment
		(start 434.692298 -311.940194)
		(end 434.837078 -312.084974)
		(width 0.14478)
		(layer "In4.Cu")
		(net "M_J_CPU0_SB_DQ<27>")
	)
	(segment
		(start 415.7599 -311.367932)
		(end 416.019234 -311.367932)
		(width 0.14478)
		(layer "In4.Cu")
		(net "M_J_CPU0_SB_DQ<27>")
	)
	(segment
		(start 433.906168 -311.421018)
		(end 434.067712 -311.259474)
		(width 0.14478)
		(layer "In4.Cu")
		(net "M_J_CPU0_SB_DQ<27>")
	)
	(segment
		(start 413.260032 -312.509916)
		(end 413.878522 -312.509916)
		(width 0.14478)
		(layer "In4.Cu")
		(net "M_J_CPU0_SB_DQ<27>")
	)
	(segment
		(start 383.79781 -289.963352)
		(end 383.806192 -289.958526)
		(width 0.0889)
		(layer "In4.Cu")
		(net "M_J_CPU0_SB_DQ<27>")
	)
	(segment
		(start 416.862768 -311.367932)
		(end 417.122102 -311.367932)
		(width 0.14478)
		(layer "In4.Cu")
		(net "M_J_CPU0_SB_DQ<27>")
	)
	(segment
		(start 434.067712 -311.259474)
		(end 434.430424 -311.259474)
		(width 0.14478)
		(layer "In4.Cu")
		(net "M_J_CPU0_SB_DQ<27>")
	)
	(segment
		(start 393.872974 -290.21151)
		(end 393.872974 -291.042598)
		(width 0.0889)
		(layer "In4.Cu")
		(net "M_J_CPU0_SB_DQ<27>")
	)
	(segment
		(start 426.705522 -312.500264)
		(end 429.03648 -312.500264)
		(width 0.14478)
		(layer "In4.Cu")
		(net "M_J_CPU0_SB_DQ<27>")
	)
	(segment
		(start 429.03648 -312.500264)
		(end 429.886364 -311.65038)
		(width 0.14478)
		(layer "In4.Cu")
		(net "M_J_CPU0_SB_DQ<27>")
	)
	(segment
		(start 433.19319 -311.259474)
		(end 433.354734 -311.421018)
		(width 0.14478)
		(layer "In4.Cu")
		(net "M_J_CPU0_SB_DQ<27>")
	)
	(segment
		(start 433.354734 -311.421018)
		(end 433.354734 -311.930288)
		(width 0.14478)
		(layer "In4.Cu")
		(net "M_J_CPU0_SB_DQ<27>")
	)
	(segment
		(start 396.767558 -300.842172)
		(end 408.435302 -312.509916)
		(width 0.14478)
		(layer "In4.Cu")
		(net "M_J_CPU0_SB_DQ<27>")
	)
	(arc
		(start 380.04623 -289.958526)
		(mid 380.229738 -289.913032)
		(end 380.41199 -289.963352)
		(width 0.0889)
		(layer "In4.Cu")
		(net "M_J_CPU0_SB_DQ<27>")
	)
	(arc
		(start 388.871968 -289.963352)
		(mid 389.154924 -290.039529)
		(end 389.43788 -289.963352)
		(width 0.0889)
		(layer "In4.Cu")
		(net "M_J_CPU0_SB_DQ<27>")
	)
	(arc
		(start 387.931914 -289.963352)
		(mid 388.21487 -290.039529)
		(end 388.497826 -289.963352)
		(width 0.0889)
		(layer "In4.Cu")
		(net "M_J_CPU0_SB_DQ<27>")
	)
	(arc
		(start 385.677664 -289.963352)
		(mid 385.859915 -289.913002)
		(end 386.043424 -289.958526)
		(width 0.0889)
		(layer "In4.Cu")
		(net "M_J_CPU0_SB_DQ<27>")
	)
	(arc
		(start 389.43788 -289.963352)
		(mid 389.624824 -289.913097)
		(end 389.811768 -289.963352)
		(width 0.0889)
		(layer "In4.Cu")
		(net "M_J_CPU0_SB_DQ<27>")
	)
	(arc
		(start 384.171952 -289.963352)
		(mid 384.454908 -290.039529)
		(end 384.737864 -289.963352)
		(width 0.0889)
		(layer "In4.Cu")
		(net "M_J_CPU0_SB_DQ<27>")
	)
	(arc
		(start 388.506208 -289.958526)
		(mid 388.689716 -289.913032)
		(end 388.871968 -289.963352)
		(width 0.0889)
		(layer "In4.Cu")
		(net "M_J_CPU0_SB_DQ<27>")
	)
	(arc
		(start 387.566154 -289.958526)
		(mid 387.749662 -289.913032)
		(end 387.931914 -289.963352)
		(width 0.0889)
		(layer "In4.Cu")
		(net "M_J_CPU0_SB_DQ<27>")
	)
	(arc
		(start 380.41199 -289.963352)
		(mid 380.694946 -290.039529)
		(end 380.977902 -289.963352)
		(width 0.0889)
		(layer "In4.Cu")
		(net "M_J_CPU0_SB_DQ<27>")
	)
	(arc
		(start 381.35179 -289.963352)
		(mid 381.634746 -290.039529)
		(end 381.917702 -289.963352)
		(width 0.0889)
		(layer "In4.Cu")
		(net "M_J_CPU0_SB_DQ<27>")
	)
	(arc
		(start 381.917702 -289.963352)
		(mid 382.099953 -289.913002)
		(end 382.283462 -289.958526)
		(width 0.0889)
		(layer "In4.Cu")
		(net "M_J_CPU0_SB_DQ<27>")
	)
	(arc
		(start 386.617718 -289.963352)
		(mid 386.799969 -289.913002)
		(end 386.983478 -289.958526)
		(width 0.0889)
		(layer "In4.Cu")
		(net "M_J_CPU0_SB_DQ<27>")
	)
	(arc
		(start 380.977902 -289.963352)
		(mid 381.164846 -289.913097)
		(end 381.35179 -289.963352)
		(width 0.0889)
		(layer "In4.Cu")
		(net "M_J_CPU0_SB_DQ<27>")
	)
	(arc
		(start 386.051806 -289.963352)
		(mid 386.334762 -290.039529)
		(end 386.617718 -289.963352)
		(width 0.0889)
		(layer "In4.Cu")
		(net "M_J_CPU0_SB_DQ<27>")
	)
	(arc
		(start 390.751822 -289.963352)
		(mid 391.034778 -290.039529)
		(end 391.317734 -289.963352)
		(width 0.0889)
		(layer "In4.Cu")
		(net "M_J_CPU0_SB_DQ<27>")
	)
	(arc
		(start 386.99186 -289.963352)
		(mid 387.274816 -290.039529)
		(end 387.557772 -289.963352)
		(width 0.0889)
		(layer "In4.Cu")
		(net "M_J_CPU0_SB_DQ<27>")
	)
	(arc
		(start 382.866138 -289.958526)
		(mid 383.049646 -289.913032)
		(end 383.231898 -289.963352)
		(width 0.0889)
		(layer "In4.Cu")
		(net "M_J_CPU0_SB_DQ<27>")
	)
	(arc
		(start 384.737864 -289.963352)
		(mid 384.924808 -289.913097)
		(end 385.111752 -289.963352)
		(width 0.0889)
		(layer "In4.Cu")
		(net "M_J_CPU0_SB_DQ<27>")
	)
	(arc
		(start 391.691876 -289.963352)
		(mid 391.828312 -290.020177)
		(end 391.974832 -290.039552)
		(width 0.0889)
		(layer "In4.Cu")
		(net "M_J_CPU0_SB_DQ<27>")
	)
	(arc
		(start 389.811768 -289.963352)
		(mid 390.094724 -290.039529)
		(end 390.37768 -289.963352)
		(width 0.0889)
		(layer "In4.Cu")
		(net "M_J_CPU0_SB_DQ<27>")
	)
	(arc
		(start 390.37768 -289.963352)
		(mid 390.559931 -289.913002)
		(end 390.74344 -289.958526)
		(width 0.0889)
		(layer "In4.Cu")
		(net "M_J_CPU0_SB_DQ<27>")
	)
	(arc
		(start 391.326116 -289.958526)
		(mid 391.509624 -289.913032)
		(end 391.691876 -289.963352)
		(width 0.0889)
		(layer "In4.Cu")
		(net "M_J_CPU0_SB_DQ<27>")
	)
	(arc
		(start 379.535182 -289.995102)
		(mid 379.790247 -290.038453)
		(end 380.037848 -289.963352)
		(width 0.0889)
		(layer "In4.Cu")
		(net "M_J_CPU0_SB_DQ<27>")
	)
	(arc
		(start 383.231898 -289.963352)
		(mid 383.514854 -290.039529)
		(end 383.79781 -289.963352)
		(width 0.0889)
		(layer "In4.Cu")
		(net "M_J_CPU0_SB_DQ<27>")
	)
	(arc
		(start 385.111752 -289.963352)
		(mid 385.394708 -290.039529)
		(end 385.677664 -289.963352)
		(width 0.0889)
		(layer "In4.Cu")
		(net "M_J_CPU0_SB_DQ<27>")
	)
	(arc
		(start 383.806192 -289.958526)
		(mid 383.9897 -289.913032)
		(end 384.171952 -289.963352)
		(width 0.0889)
		(layer "In4.Cu")
		(net "M_J_CPU0_SB_DQ<27>")
	)
	(arc
		(start 382.291844 -289.963352)
		(mid 382.5748 -290.039529)
		(end 382.857756 -289.963352)
		(width 0.0889)
		(layer "In4.Cu")
		(net "M_J_CPU0_SB_DQ<27>")
	)
	(segment
		(start 380.22784 -289.209988)
		(end 380.694946 -289.475926)
		(width 0.10668)
		(layer "F.Cu")
		(net "M_J_CPU0_SB_DQ<26>")
	)
	(segment
		(start 407.217372 -309.486046)
		(end 407.445972 -309.486046)
		(width 0.14478)
		(layer "In4.Cu")
		(net "M_J_CPU0_SB_DQ<26>")
	)
	(segment
		(start 405.113998 -307.91658)
		(end 405.275542 -308.078124)
		(width 0.14478)
		(layer "In4.Cu")
		(net "M_J_CPU0_SB_DQ<26>")
	)
	(segment
		(start 413.684974 -310.810148)
		(end 414.090104 -310.810148)
		(width 0.14478)
		(layer "In4.Cu")
		(net "M_J_CPU0_SB_DQ<26>")
	)
	(segment
		(start 408.007566 -310.810148)
		(end 408.418792 -310.810148)
		(width 0.14478)
		(layer "In4.Cu")
		(net "M_J_CPU0_SB_DQ<26>")
	)
	(segment
		(start 414.090104 -310.810148)
		(end 414.940242 -309.96001)
		(width 0.14478)
		(layer "In4.Cu")
		(net "M_J_CPU0_SB_DQ<26>")
	)
	(segment
		(start 406.674574 -309.477156)
		(end 406.836118 -309.6387)
		(width 0.14478)
		(layer "In4.Cu")
		(net "M_J_CPU0_SB_DQ<26>")
	)
	(segment
		(start 394.297154 -290.049204)
		(end 394.297154 -290.940998)
		(width 0.0889)
		(layer "In4.Cu")
		(net "M_J_CPU0_SB_DQ<26>")
	)
	(segment
		(start 406.836118 -309.6387)
		(end 407.064718 -309.6387)
		(width 0.14478)
		(layer "In4.Cu")
		(net "M_J_CPU0_SB_DQ<26>")
	)
	(segment
		(start 405.275542 -308.078124)
		(end 405.504142 -308.078124)
		(width 0.14478)
		(layer "In4.Cu")
		(net "M_J_CPU0_SB_DQ<26>")
	)
	(segment
		(start 389.333486 -289.14852)
		(end 389.341868 -289.153346)
		(width 0.0889)
		(layer "In4.Cu")
		(net "M_J_CPU0_SB_DQ<26>")
	)
	(segment
		(start 421.634158 -310.810148)
		(end 422.484296 -309.96001)
		(width 0.14478)
		(layer "In4.Cu")
		(net "M_J_CPU0_SB_DQ<26>")
	)
	(segment
		(start 425.666662 -309.96001)
		(end 426.516546 -310.809894)
		(width 0.14478)
		(layer "In4.Cu")
		(net "M_J_CPU0_SB_DQ<26>")
	)
	(segment
		(start 404.495254 -307.297836)
		(end 404.723854 -307.297836)
		(width 0.14478)
		(layer "In4.Cu")
		(net "M_J_CPU0_SB_DQ<26>")
	)
	(segment
		(start 412.582106 -310.810148)
		(end 412.830264 -310.810148)
		(width 0.14478)
		(layer "In4.Cu")
		(net "M_J_CPU0_SB_DQ<26>")
	)
	(segment
		(start 405.894286 -308.468268)
		(end 405.894286 -308.696868)
		(width 0.14478)
		(layer "In4.Cu")
		(net "M_J_CPU0_SB_DQ<26>")
	)
	(segment
		(start 384.63347 -289.14852)
		(end 384.641852 -289.153346)
		(width 0.0889)
		(layer "In4.Cu")
		(net "M_J_CPU0_SB_DQ<26>")
	)
	(segment
		(start 404.33371 -307.136292)
		(end 404.495254 -307.297836)
		(width 0.14478)
		(layer "In4.Cu")
		(net "M_J_CPU0_SB_DQ<26>")
	)
	(segment
		(start 413.13354 -310.506872)
		(end 413.381698 -310.506872)
		(width 0.14478)
		(layer "In4.Cu")
		(net "M_J_CPU0_SB_DQ<26>")
	)
	(segment
		(start 410.37637 -310.810148)
		(end 410.624528 -310.810148)
		(width 0.14478)
		(layer "In4.Cu")
		(net "M_J_CPU0_SB_DQ<26>")
	)
	(segment
		(start 410.073094 -310.506872)
		(end 410.37637 -310.810148)
		(width 0.14478)
		(layer "In4.Cu")
		(net "M_J_CPU0_SB_DQ<26>")
	)
	(segment
		(start 389.90778 -289.153346)
		(end 389.916162 -289.14852)
		(width 0.0889)
		(layer "In4.Cu")
		(net "M_J_CPU0_SB_DQ<26>")
	)
	(segment
		(start 412.830264 -310.810148)
		(end 413.13354 -310.506872)
		(width 0.14478)
		(layer "In4.Cu")
		(net "M_J_CPU0_SB_DQ<26>")
	)
	(segment
		(start 407.064718 -309.6387)
		(end 407.217372 -309.486046)
		(width 0.14478)
		(layer "In4.Cu")
		(net "M_J_CPU0_SB_DQ<26>")
	)
	(segment
		(start 412.27883 -310.506872)
		(end 412.582106 -310.810148)
		(width 0.14478)
		(layer "In4.Cu")
		(net "M_J_CPU0_SB_DQ<26>")
	)
	(segment
		(start 412.030672 -310.506872)
		(end 412.27883 -310.506872)
		(width 0.14478)
		(layer "In4.Cu")
		(net "M_J_CPU0_SB_DQ<26>")
	)
	(segment
		(start 405.266652 -307.306726)
		(end 405.266652 -307.535326)
		(width 0.14478)
		(layer "In4.Cu")
		(net "M_J_CPU0_SB_DQ<26>")
	)
	(segment
		(start 409.824936 -310.506872)
		(end 410.073094 -310.506872)
		(width 0.14478)
		(layer "In4.Cu")
		(net "M_J_CPU0_SB_DQ<26>")
	)
	(segment
		(start 413.381698 -310.506872)
		(end 413.684974 -310.810148)
		(width 0.14478)
		(layer "In4.Cu")
		(net "M_J_CPU0_SB_DQ<26>")
	)
	(segment
		(start 406.827228 -309.095902)
		(end 406.674574 -309.248556)
		(width 0.14478)
		(layer "In4.Cu")
		(net "M_J_CPU0_SB_DQ<26>")
	)
	(segment
		(start 394.297154 -290.940998)
		(end 394.454634 -291.320982)
		(width 0.0889)
		(layer "In4.Cu")
		(net "M_J_CPU0_SB_DQ<26>")
	)
	(segment
		(start 405.885396 -307.92547)
		(end 406.04694 -308.087014)
		(width 0.14478)
		(layer "In4.Cu")
		(net "M_J_CPU0_SB_DQ<26>")
	)
	(segment
		(start 404.876508 -307.145182)
		(end 405.105108 -307.145182)
		(width 0.14478)
		(layer "In4.Cu")
		(net "M_J_CPU0_SB_DQ<26>")
	)
	(segment
		(start 406.437084 -308.705758)
		(end 406.665684 -308.705758)
		(width 0.14478)
		(layer "In4.Cu")
		(net "M_J_CPU0_SB_DQ<26>")
	)
	(segment
		(start 405.894286 -308.696868)
		(end 406.05583 -308.858412)
		(width 0.14478)
		(layer "In4.Cu")
		(net "M_J_CPU0_SB_DQ<26>")
	)
	(segment
		(start 429.08093 -310.809894)
		(end 429.930814 -309.96001)
		(width 0.14478)
		(layer "In4.Cu")
		(net "M_J_CPU0_SB_DQ<26>")
	)
	(segment
		(start 429.930814 -309.96001)
		(end 434.575204 -309.96001)
		(width 0.14478)
		(layer "In4.Cu")
		(net "M_J_CPU0_SB_DQ<26>")
	)
	(segment
		(start 410.624528 -310.810148)
		(end 410.927804 -310.506872)
		(width 0.14478)
		(layer "In4.Cu")
		(net "M_J_CPU0_SB_DQ<26>")
	)
	(segment
		(start 411.175962 -310.506872)
		(end 411.479238 -310.810148)
		(width 0.14478)
		(layer "In4.Cu")
		(net "M_J_CPU0_SB_DQ<26>")
	)
	(segment
		(start 383.693416 -289.14852)
		(end 383.701798 -289.153346)
		(width 0.0889)
		(layer "In4.Cu")
		(net "M_J_CPU0_SB_DQ<26>")
	)
	(segment
		(start 426.516546 -310.809894)
		(end 429.08093 -310.809894)
		(width 0.14478)
		(layer "In4.Cu")
		(net "M_J_CPU0_SB_DQ<26>")
	)
	(segment
		(start 422.484296 -309.96001)
		(end 425.666662 -309.96001)
		(width 0.14478)
		(layer "In4.Cu")
		(net "M_J_CPU0_SB_DQ<26>")
	)
	(segment
		(start 404.32482 -306.364894)
		(end 404.486364 -306.526438)
		(width 0.14478)
		(layer "In4.Cu")
		(net "M_J_CPU0_SB_DQ<26>")
	)
	(segment
		(start 395.123924 -291.76853)
		(end 395.38402 -291.76853)
		(width 0.0889)
		(layer "In4.Cu")
		(net "M_J_CPU0_SB_DQ<26>")
	)
	(segment
		(start 411.727396 -310.810148)
		(end 412.030672 -310.506872)
		(width 0.14478)
		(layer "In4.Cu")
		(net "M_J_CPU0_SB_DQ<26>")
	)
	(segment
		(start 404.33371 -306.907692)
		(end 404.33371 -307.136292)
		(width 0.14478)
		(layer "In4.Cu")
		(net "M_J_CPU0_SB_DQ<26>")
	)
	(segment
		(start 406.674574 -309.248556)
		(end 406.674574 -309.477156)
		(width 0.14478)
		(layer "In4.Cu")
		(net "M_J_CPU0_SB_DQ<26>")
	)
	(segment
		(start 407.607516 -309.87619)
		(end 407.454862 -310.028844)
		(width 0.14478)
		(layer "In4.Cu")
		(net "M_J_CPU0_SB_DQ<26>")
	)
	(segment
		(start 434.575204 -309.96001)
		(end 435.000146 -310.384952)
		(width 0.14478)
		(layer "In4.Cu")
		(net "M_J_CPU0_SB_DQ<26>")
	)
	(segment
		(start 380.694946 -289.475926)
		(end 380.84887 -289.210496)
		(width 0.0889)
		(layer "In4.Cu")
		(net "M_J_CPU0_SB_DQ<26>")
	)
	(segment
		(start 404.486364 -306.755038)
		(end 404.33371 -306.907692)
		(width 0.14478)
		(layer "In4.Cu")
		(net "M_J_CPU0_SB_DQ<26>")
	)
	(segment
		(start 418.972746 -310.810148)
		(end 421.634158 -310.810148)
		(width 0.14478)
		(layer "In4.Cu")
		(net "M_J_CPU0_SB_DQ<26>")
	)
	(segment
		(start 405.113998 -307.68798)
		(end 405.113998 -307.91658)
		(width 0.14478)
		(layer "In4.Cu")
		(net "M_J_CPU0_SB_DQ<26>")
	)
	(segment
		(start 386.147818 -289.153346)
		(end 386.1562 -289.14852)
		(width 0.0889)
		(layer "In4.Cu")
		(net "M_J_CPU0_SB_DQ<26>")
	)
	(segment
		(start 407.607516 -309.64759)
		(end 407.607516 -309.87619)
		(width 0.14478)
		(layer "In4.Cu")
		(net "M_J_CPU0_SB_DQ<26>")
	)
	(segment
		(start 395.38402 -291.76853)
		(end 395.837918 -292.222428)
		(width 0.0889)
		(layer "In4.Cu")
		(net "M_J_CPU0_SB_DQ<26>")
	)
	(segment
		(start 404.723854 -307.297836)
		(end 404.876508 -307.145182)
		(width 0.14478)
		(layer "In4.Cu")
		(net "M_J_CPU0_SB_DQ<26>")
	)
	(segment
		(start 405.266652 -307.535326)
		(end 405.113998 -307.68798)
		(width 0.14478)
		(layer "In4.Cu")
		(net "M_J_CPU0_SB_DQ<26>")
	)
	(segment
		(start 407.445972 -309.486046)
		(end 407.607516 -309.64759)
		(width 0.14478)
		(layer "In4.Cu")
		(net "M_J_CPU0_SB_DQ<26>")
	)
	(segment
		(start 393.534646 -289.286696)
		(end 394.297154 -290.049204)
		(width 0.0889)
		(layer "In4.Cu")
		(net "M_J_CPU0_SB_DQ<26>")
	)
	(segment
		(start 408.970226 -310.506872)
		(end 409.273502 -310.810148)
		(width 0.14478)
		(layer "In4.Cu")
		(net "M_J_CPU0_SB_DQ<26>")
	)
	(segment
		(start 380.84887 -289.210496)
		(end 380.944882 -289.185096)
		(width 0.0889)
		(layer "In4.Cu")
		(net "M_J_CPU0_SB_DQ<26>")
	)
	(segment
		(start 381.447802 -289.153346)
		(end 381.456184 -289.14852)
		(width 0.0889)
		(layer "In4.Cu")
		(net "M_J_CPU0_SB_DQ<26>")
	)
	(segment
		(start 403.714966 -306.517548)
		(end 403.943566 -306.517548)
		(width 0.14478)
		(layer "In4.Cu")
		(net "M_J_CPU0_SB_DQ<26>")
	)
	(segment
		(start 406.04694 -308.315614)
		(end 405.894286 -308.468268)
		(width 0.14478)
		(layer "In4.Cu")
		(net "M_J_CPU0_SB_DQ<26>")
	)
	(segment
		(start 418.122608 -309.96001)
		(end 418.972746 -310.810148)
		(width 0.14478)
		(layer "In4.Cu")
		(net "M_J_CPU0_SB_DQ<26>")
	)
	(segment
		(start 405.656796 -307.92547)
		(end 405.885396 -307.92547)
		(width 0.14478)
		(layer "In4.Cu")
		(net "M_J_CPU0_SB_DQ<26>")
	)
	(segment
		(start 408.418792 -310.810148)
		(end 408.722068 -310.506872)
		(width 0.14478)
		(layer "In4.Cu")
		(net "M_J_CPU0_SB_DQ<26>")
	)
	(segment
		(start 388.393432 -289.14852)
		(end 388.401814 -289.153346)
		(width 0.0889)
		(layer "In4.Cu")
		(net "M_J_CPU0_SB_DQ<26>")
	)
	(segment
		(start 395.837918 -292.222428)
		(end 397.666718 -294.051228)
		(width 0.14478)
		(layer "In4.Cu")
		(net "M_J_CPU0_SB_DQ<26>")
	)
	(segment
		(start 397.666718 -294.051228)
		(end 397.666718 -300.4693)
		(width 0.14478)
		(layer "In4.Cu")
		(net "M_J_CPU0_SB_DQ<26>")
	)
	(segment
		(start 397.666718 -300.4693)
		(end 403.714966 -306.517548)
		(width 0.14478)
		(layer "In4.Cu")
		(net "M_J_CPU0_SB_DQ<26>")
	)
	(segment
		(start 404.09622 -306.364894)
		(end 404.32482 -306.364894)
		(width 0.14478)
		(layer "In4.Cu")
		(net "M_J_CPU0_SB_DQ<26>")
	)
	(segment
		(start 406.665684 -308.705758)
		(end 406.827228 -308.867302)
		(width 0.14478)
		(layer "In4.Cu")
		(net "M_J_CPU0_SB_DQ<26>")
	)
	(segment
		(start 406.28443 -308.858412)
		(end 406.437084 -308.705758)
		(width 0.14478)
		(layer "In4.Cu")
		(net "M_J_CPU0_SB_DQ<26>")
	)
	(segment
		(start 403.943566 -306.517548)
		(end 404.09622 -306.364894)
		(width 0.14478)
		(layer "In4.Cu")
		(net "M_J_CPU0_SB_DQ<26>")
	)
	(segment
		(start 409.273502 -310.810148)
		(end 409.52166 -310.810148)
		(width 0.14478)
		(layer "In4.Cu")
		(net "M_J_CPU0_SB_DQ<26>")
	)
	(segment
		(start 414.940242 -309.96001)
		(end 418.122608 -309.96001)
		(width 0.14478)
		(layer "In4.Cu")
		(net "M_J_CPU0_SB_DQ<26>")
	)
	(segment
		(start 385.207764 -289.153346)
		(end 385.216146 -289.14852)
		(width 0.0889)
		(layer "In4.Cu")
		(net "M_J_CPU0_SB_DQ<26>")
	)
	(segment
		(start 405.105108 -307.145182)
		(end 405.266652 -307.306726)
		(width 0.14478)
		(layer "In4.Cu")
		(net "M_J_CPU0_SB_DQ<26>")
	)
	(segment
		(start 392.641582 -289.286696)
		(end 393.534646 -289.286696)
		(width 0.0889)
		(layer "In4.Cu")
		(net "M_J_CPU0_SB_DQ<26>")
	)
	(segment
		(start 406.827228 -308.867302)
		(end 406.827228 -309.095902)
		(width 0.14478)
		(layer "In4.Cu")
		(net "M_J_CPU0_SB_DQ<26>")
	)
	(segment
		(start 406.04694 -308.087014)
		(end 406.04694 -308.315614)
		(width 0.14478)
		(layer "In4.Cu")
		(net "M_J_CPU0_SB_DQ<26>")
	)
	(segment
		(start 410.927804 -310.506872)
		(end 411.175962 -310.506872)
		(width 0.14478)
		(layer "In4.Cu")
		(net "M_J_CPU0_SB_DQ<26>")
	)
	(segment
		(start 411.479238 -310.810148)
		(end 411.727396 -310.810148)
		(width 0.14478)
		(layer "In4.Cu")
		(net "M_J_CPU0_SB_DQ<26>")
	)
	(segment
		(start 405.504142 -308.078124)
		(end 405.656796 -307.92547)
		(width 0.14478)
		(layer "In4.Cu")
		(net "M_J_CPU0_SB_DQ<26>")
	)
	(segment
		(start 404.486364 -306.526438)
		(end 404.486364 -306.755038)
		(width 0.14478)
		(layer "In4.Cu")
		(net "M_J_CPU0_SB_DQ<26>")
	)
	(segment
		(start 406.05583 -308.858412)
		(end 406.28443 -308.858412)
		(width 0.14478)
		(layer "In4.Cu")
		(net "M_J_CPU0_SB_DQ<26>")
	)
	(segment
		(start 408.722068 -310.506872)
		(end 408.970226 -310.506872)
		(width 0.14478)
		(layer "In4.Cu")
		(net "M_J_CPU0_SB_DQ<26>")
	)
	(segment
		(start 407.454862 -310.028844)
		(end 407.454862 -310.257444)
		(width 0.14478)
		(layer "In4.Cu")
		(net "M_J_CPU0_SB_DQ<26>")
	)
	(segment
		(start 409.52166 -310.810148)
		(end 409.824936 -310.506872)
		(width 0.14478)
		(layer "In4.Cu")
		(net "M_J_CPU0_SB_DQ<26>")
	)
	(segment
		(start 407.454862 -310.257444)
		(end 408.007566 -310.810148)
		(width 0.14478)
		(layer "In4.Cu")
		(net "M_J_CPU0_SB_DQ<26>")
	)
	(segment
		(start 394.454634 -291.320982)
		(end 395.123924 -291.76853)
		(width 0.0889)
		(layer "In4.Cu")
		(net "M_J_CPU0_SB_DQ<26>")
	)
	(arc
		(start 383.327656 -289.153346)
		(mid 383.509907 -289.102996)
		(end 383.693416 -289.14852)
		(width 0.0889)
		(layer "In4.Cu")
		(net "M_J_CPU0_SB_DQ<26>")
	)
	(arc
		(start 387.46176 -289.153346)
		(mid 387.744716 -289.229523)
		(end 388.027672 -289.153346)
		(width 0.0889)
		(layer "In4.Cu")
		(net "M_J_CPU0_SB_DQ<26>")
	)
	(arc
		(start 382.387856 -289.153346)
		(mid 382.5748 -289.103091)
		(end 382.761744 -289.153346)
		(width 0.0889)
		(layer "In4.Cu")
		(net "M_J_CPU0_SB_DQ<26>")
	)
	(arc
		(start 381.821944 -289.153346)
		(mid 382.1049 -289.229523)
		(end 382.387856 -289.153346)
		(width 0.0889)
		(layer "In4.Cu")
		(net "M_J_CPU0_SB_DQ<26>")
	)
	(arc
		(start 387.087872 -289.153346)
		(mid 387.274816 -289.103091)
		(end 387.46176 -289.153346)
		(width 0.0889)
		(layer "In4.Cu")
		(net "M_J_CPU0_SB_DQ<26>")
	)
	(arc
		(start 389.916162 -289.14852)
		(mid 390.09967 -289.103026)
		(end 390.281922 -289.153346)
		(width 0.0889)
		(layer "In4.Cu")
		(net "M_J_CPU0_SB_DQ<26>")
	)
	(arc
		(start 383.701798 -289.153346)
		(mid 383.984754 -289.229523)
		(end 384.26771 -289.153346)
		(width 0.0889)
		(layer "In4.Cu")
		(net "M_J_CPU0_SB_DQ<26>")
	)
	(arc
		(start 386.52196 -289.153346)
		(mid 386.804916 -289.229523)
		(end 387.087872 -289.153346)
		(width 0.0889)
		(layer "In4.Cu")
		(net "M_J_CPU0_SB_DQ<26>")
	)
	(arc
		(start 388.967726 -289.153346)
		(mid 389.149977 -289.102996)
		(end 389.333486 -289.14852)
		(width 0.0889)
		(layer "In4.Cu")
		(net "M_J_CPU0_SB_DQ<26>")
	)
	(arc
		(start 380.944882 -289.185096)
		(mid 381.20009 -289.228573)
		(end 381.447802 -289.153346)
		(width 0.0889)
		(layer "In4.Cu")
		(net "M_J_CPU0_SB_DQ<26>")
	)
	(arc
		(start 388.027672 -289.153346)
		(mid 388.209923 -289.102996)
		(end 388.393432 -289.14852)
		(width 0.0889)
		(layer "In4.Cu")
		(net "M_J_CPU0_SB_DQ<26>")
	)
	(arc
		(start 388.401814 -289.153346)
		(mid 388.68477 -289.229523)
		(end 388.967726 -289.153346)
		(width 0.0889)
		(layer "In4.Cu")
		(net "M_J_CPU0_SB_DQ<26>")
	)
	(arc
		(start 386.1562 -289.14852)
		(mid 386.339708 -289.103026)
		(end 386.52196 -289.153346)
		(width 0.0889)
		(layer "In4.Cu")
		(net "M_J_CPU0_SB_DQ<26>")
	)
	(arc
		(start 382.761744 -289.153346)
		(mid 383.0447 -289.229523)
		(end 383.327656 -289.153346)
		(width 0.0889)
		(layer "In4.Cu")
		(net "M_J_CPU0_SB_DQ<26>")
	)
	(arc
		(start 392.140948 -289.14217)
		(mid 392.384691 -289.237208)
		(end 392.641582 -289.286696)
		(width 0.0889)
		(layer "In4.Cu")
		(net "M_J_CPU0_SB_DQ<26>")
	)
	(arc
		(start 384.641852 -289.153346)
		(mid 384.924808 -289.229523)
		(end 385.207764 -289.153346)
		(width 0.0889)
		(layer "In4.Cu")
		(net "M_J_CPU0_SB_DQ<26>")
	)
	(arc
		(start 390.281922 -289.153346)
		(mid 390.564878 -289.229523)
		(end 390.847834 -289.153346)
		(width 0.0889)
		(layer "In4.Cu")
		(net "M_J_CPU0_SB_DQ<26>")
	)
	(arc
		(start 385.216146 -289.14852)
		(mid 385.399654 -289.103026)
		(end 385.581906 -289.153346)
		(width 0.0889)
		(layer "In4.Cu")
		(net "M_J_CPU0_SB_DQ<26>")
	)
	(arc
		(start 391.221722 -289.153346)
		(mid 391.504678 -289.229523)
		(end 391.787634 -289.153346)
		(width 0.0889)
		(layer "In4.Cu")
		(net "M_J_CPU0_SB_DQ<26>")
	)
	(arc
		(start 381.456184 -289.14852)
		(mid 381.639692 -289.103026)
		(end 381.821944 -289.153346)
		(width 0.0889)
		(layer "In4.Cu")
		(net "M_J_CPU0_SB_DQ<26>")
	)
	(arc
		(start 391.787634 -289.153346)
		(mid 391.962873 -289.103275)
		(end 392.140948 -289.14217)
		(width 0.0889)
		(layer "In4.Cu")
		(net "M_J_CPU0_SB_DQ<26>")
	)
	(arc
		(start 389.341868 -289.153346)
		(mid 389.624824 -289.229523)
		(end 389.90778 -289.153346)
		(width 0.0889)
		(layer "In4.Cu")
		(net "M_J_CPU0_SB_DQ<26>")
	)
	(arc
		(start 390.847834 -289.153346)
		(mid 391.034778 -289.103091)
		(end 391.221722 -289.153346)
		(width 0.0889)
		(layer "In4.Cu")
		(net "M_J_CPU0_SB_DQ<26>")
	)
	(arc
		(start 384.26771 -289.153346)
		(mid 384.449961 -289.102996)
		(end 384.63347 -289.14852)
		(width 0.0889)
		(layer "In4.Cu")
		(net "M_J_CPU0_SB_DQ<26>")
	)
	(arc
		(start 385.581906 -289.153346)
		(mid 385.864862 -289.229523)
		(end 386.147818 -289.153346)
		(width 0.0889)
		(layer "In4.Cu")
		(net "M_J_CPU0_SB_DQ<26>")
	)
	(segment
		(start 379.28804 -289.209988)
		(end 379.754892 -289.475926)
		(width 0.10668)
		(layer "F.Cu")
		(net "M_J_CPU0_SB_DQ<25>")
	)
	(segment
		(start 419.006528 -311.660032)
		(end 421.520366 -311.660032)
		(width 0.14478)
		(layer "In4.Cu")
		(net "M_J_CPU0_SB_DQ<25>")
	)
	(segment
		(start 413.976312 -311.660032)
		(end 414.826196 -310.810148)
		(width 0.14478)
		(layer "In4.Cu")
		(net "M_J_CPU0_SB_DQ<25>")
	)
	(segment
		(start 421.520366 -311.660032)
		(end 422.37025 -310.810148)
		(width 0.14478)
		(layer "In4.Cu")
		(net "M_J_CPU0_SB_DQ<25>")
	)
	(segment
		(start 418.156644 -310.810148)
		(end 419.006528 -311.660032)
		(width 0.14478)
		(layer "In4.Cu")
		(net "M_J_CPU0_SB_DQ<25>")
	)
	(segment
		(start 414.826196 -310.810148)
		(end 418.156644 -310.810148)
		(width 0.14478)
		(layer "In4.Cu")
		(net "M_J_CPU0_SB_DQ<25>")
	)
	(segment
		(start 429.903636 -310.809894)
		(end 438.675272 -310.809894)
		(width 0.14478)
		(layer "In4.Cu")
		(net "M_J_CPU0_SB_DQ<25>")
	)
	(segment
		(start 397.217138 -300.655736)
		(end 408.221434 -311.660032)
		(width 0.14478)
		(layer "In4.Cu")
		(net "M_J_CPU0_SB_DQ<25>")
	)
	(segment
		(start 395.422882 -292.450774)
		(end 395.823694 -292.851586)
		(width 0.0889)
		(layer "In4.Cu")
		(net "M_J_CPU0_SB_DQ<25>")
	)
	(segment
		(start 394.297408 -291.486082)
		(end 395.245844 -292.119558)
		(width 0.0889)
		(layer "In4.Cu")
		(net "M_J_CPU0_SB_DQ<25>")
	)
	(segment
		(start 397.217138 -294.24503)
		(end 397.217138 -300.655736)
		(width 0.14478)
		(layer "In4.Cu")
		(net "M_J_CPU0_SB_DQ<25>")
	)
	(segment
		(start 388.393432 -289.803332)
		(end 388.401814 -289.798506)
		(width 0.0889)
		(layer "In4.Cu")
		(net "M_J_CPU0_SB_DQ<25>")
	)
	(segment
		(start 383.693416 -289.803332)
		(end 383.701798 -289.798506)
		(width 0.0889)
		(layer "In4.Cu")
		(net "M_J_CPU0_SB_DQ<25>")
	)
	(segment
		(start 429.053752 -311.659778)
		(end 429.903636 -310.809894)
		(width 0.14478)
		(layer "In4.Cu")
		(net "M_J_CPU0_SB_DQ<25>")
	)
	(segment
		(start 379.754892 -289.475926)
		(end 379.600714 -289.741356)
		(width 0.0889)
		(layer "In4.Cu")
		(net "M_J_CPU0_SB_DQ<25>")
	)
	(segment
		(start 394.076174 -290.952174)
		(end 394.297408 -291.486082)
		(width 0.0889)
		(layer "In4.Cu")
		(net "M_J_CPU0_SB_DQ<25>")
	)
	(segment
		(start 385.207764 -289.798506)
		(end 385.216146 -289.803332)
		(width 0.0889)
		(layer "In4.Cu")
		(net "M_J_CPU0_SB_DQ<25>")
	)
	(segment
		(start 408.221434 -311.660032)
		(end 413.976312 -311.660032)
		(width 0.14478)
		(layer "In4.Cu")
		(net "M_J_CPU0_SB_DQ<25>")
	)
	(segment
		(start 380.873508 -289.803332)
		(end 380.88189 -289.798506)
		(width 0.0889)
		(layer "In4.Cu")
		(net "M_J_CPU0_SB_DQ<25>")
	)
	(segment
		(start 393.563348 -289.614356)
		(end 394.076174 -290.127182)
		(width 0.0889)
		(layer "In4.Cu")
		(net "M_J_CPU0_SB_DQ<25>")
	)
	(segment
		(start 438.675272 -310.809894)
		(end 439.100214 -311.234836)
		(width 0.14478)
		(layer "In4.Cu")
		(net "M_J_CPU0_SB_DQ<25>")
	)
	(segment
		(start 391.974832 -289.849052)
		(end 392.503152 -289.849052)
		(width 0.0889)
		(layer "In4.Cu")
		(net "M_J_CPU0_SB_DQ<25>")
	)
	(segment
		(start 394.076174 -290.127182)
		(end 394.076174 -290.952174)
		(width 0.0889)
		(layer "In4.Cu")
		(net "M_J_CPU0_SB_DQ<25>")
	)
	(segment
		(start 386.147818 -289.798506)
		(end 386.1562 -289.803332)
		(width 0.0889)
		(layer "In4.Cu")
		(net "M_J_CPU0_SB_DQ<25>")
	)
	(segment
		(start 389.90778 -289.798506)
		(end 389.916162 -289.803332)
		(width 0.0889)
		(layer "In4.Cu")
		(net "M_J_CPU0_SB_DQ<25>")
	)
	(segment
		(start 392.737848 -289.614356)
		(end 393.563348 -289.614356)
		(width 0.0889)
		(layer "In4.Cu")
		(net "M_J_CPU0_SB_DQ<25>")
	)
	(segment
		(start 395.245844 -292.119558)
		(end 395.422882 -292.450774)
		(width 0.0889)
		(layer "In4.Cu")
		(net "M_J_CPU0_SB_DQ<25>")
	)
	(segment
		(start 425.700698 -310.810148)
		(end 426.550328 -311.659778)
		(width 0.14478)
		(layer "In4.Cu")
		(net "M_J_CPU0_SB_DQ<25>")
	)
	(segment
		(start 426.550328 -311.659778)
		(end 429.053752 -311.659778)
		(width 0.14478)
		(layer "In4.Cu")
		(net "M_J_CPU0_SB_DQ<25>")
	)
	(segment
		(start 395.823694 -292.851586)
		(end 397.217138 -294.24503)
		(width 0.14478)
		(layer "In4.Cu")
		(net "M_J_CPU0_SB_DQ<25>")
	)
	(segment
		(start 392.503152 -289.849052)
		(end 392.737848 -289.614356)
		(width 0.0889)
		(layer "In4.Cu")
		(net "M_J_CPU0_SB_DQ<25>")
	)
	(segment
		(start 439.100214 -311.234836)
		(end 439.100214 -311.23509)
		(width 0.14478)
		(layer "In4.Cu")
		(net "M_J_CPU0_SB_DQ<25>")
	)
	(segment
		(start 379.933454 -289.803332)
		(end 379.941836 -289.798506)
		(width 0.0889)
		(layer "In4.Cu")
		(net "M_J_CPU0_SB_DQ<25>")
	)
	(segment
		(start 384.63347 -289.803332)
		(end 384.641852 -289.798506)
		(width 0.0889)
		(layer "In4.Cu")
		(net "M_J_CPU0_SB_DQ<25>")
	)
	(segment
		(start 389.333486 -289.803332)
		(end 389.341868 -289.798506)
		(width 0.0889)
		(layer "In4.Cu")
		(net "M_J_CPU0_SB_DQ<25>")
	)
	(segment
		(start 422.37025 -310.810148)
		(end 425.700698 -310.810148)
		(width 0.14478)
		(layer "In4.Cu")
		(net "M_J_CPU0_SB_DQ<25>")
	)
	(segment
		(start 379.600714 -289.741356)
		(end 379.623066 -289.824668)
		(width 0.0889)
		(layer "In4.Cu")
		(net "M_J_CPU0_SB_DQ<25>")
	)
	(segment
		(start 381.447802 -289.798506)
		(end 381.456184 -289.803332)
		(width 0.0889)
		(layer "In4.Cu")
		(net "M_J_CPU0_SB_DQ<25>")
	)
	(arc
		(start 390.847834 -289.798506)
		(mid 391.034778 -289.848761)
		(end 391.221722 -289.798506)
		(width 0.0889)
		(layer "In4.Cu")
		(net "M_J_CPU0_SB_DQ<25>")
	)
	(arc
		(start 389.916162 -289.803332)
		(mid 390.09967 -289.848826)
		(end 390.281922 -289.798506)
		(width 0.0889)
		(layer "In4.Cu")
		(net "M_J_CPU0_SB_DQ<25>")
	)
	(arc
		(start 383.701798 -289.798506)
		(mid 383.984754 -289.722329)
		(end 384.26771 -289.798506)
		(width 0.0889)
		(layer "In4.Cu")
		(net "M_J_CPU0_SB_DQ<25>")
	)
	(arc
		(start 385.216146 -289.803332)
		(mid 385.399654 -289.848826)
		(end 385.581906 -289.798506)
		(width 0.0889)
		(layer "In4.Cu")
		(net "M_J_CPU0_SB_DQ<25>")
	)
	(arc
		(start 391.221722 -289.798506)
		(mid 391.504678 -289.722329)
		(end 391.787634 -289.798506)
		(width 0.0889)
		(layer "In4.Cu")
		(net "M_J_CPU0_SB_DQ<25>")
	)
	(arc
		(start 380.88189 -289.798506)
		(mid 381.164846 -289.722329)
		(end 381.447802 -289.798506)
		(width 0.0889)
		(layer "In4.Cu")
		(net "M_J_CPU0_SB_DQ<25>")
	)
	(arc
		(start 388.967726 -289.798506)
		(mid 389.149977 -289.848856)
		(end 389.333486 -289.803332)
		(width 0.0889)
		(layer "In4.Cu")
		(net "M_J_CPU0_SB_DQ<25>")
	)
	(arc
		(start 380.507748 -289.798506)
		(mid 380.689999 -289.848856)
		(end 380.873508 -289.803332)
		(width 0.0889)
		(layer "In4.Cu")
		(net "M_J_CPU0_SB_DQ<25>")
	)
	(arc
		(start 381.456184 -289.803332)
		(mid 381.639692 -289.848826)
		(end 381.821944 -289.798506)
		(width 0.0889)
		(layer "In4.Cu")
		(net "M_J_CPU0_SB_DQ<25>")
	)
	(arc
		(start 389.341868 -289.798506)
		(mid 389.624824 -289.722329)
		(end 389.90778 -289.798506)
		(width 0.0889)
		(layer "In4.Cu")
		(net "M_J_CPU0_SB_DQ<25>")
	)
	(arc
		(start 388.401814 -289.798506)
		(mid 388.68477 -289.722329)
		(end 388.967726 -289.798506)
		(width 0.0889)
		(layer "In4.Cu")
		(net "M_J_CPU0_SB_DQ<25>")
	)
	(arc
		(start 383.327656 -289.798506)
		(mid 383.509907 -289.848856)
		(end 383.693416 -289.803332)
		(width 0.0889)
		(layer "In4.Cu")
		(net "M_J_CPU0_SB_DQ<25>")
	)
	(arc
		(start 382.761744 -289.798506)
		(mid 383.0447 -289.722329)
		(end 383.327656 -289.798506)
		(width 0.0889)
		(layer "In4.Cu")
		(net "M_J_CPU0_SB_DQ<25>")
	)
	(arc
		(start 391.787634 -289.798506)
		(mid 391.87789 -289.836159)
		(end 391.974832 -289.849052)
		(width 0.0889)
		(layer "In4.Cu")
		(net "M_J_CPU0_SB_DQ<25>")
	)
	(arc
		(start 382.387856 -289.798506)
		(mid 382.5748 -289.848761)
		(end 382.761744 -289.798506)
		(width 0.0889)
		(layer "In4.Cu")
		(net "M_J_CPU0_SB_DQ<25>")
	)
	(arc
		(start 387.46176 -289.798506)
		(mid 387.744716 -289.722329)
		(end 388.027672 -289.798506)
		(width 0.0889)
		(layer "In4.Cu")
		(net "M_J_CPU0_SB_DQ<25>")
	)
	(arc
		(start 390.281922 -289.798506)
		(mid 390.564878 -289.722329)
		(end 390.847834 -289.798506)
		(width 0.0889)
		(layer "In4.Cu")
		(net "M_J_CPU0_SB_DQ<25>")
	)
	(arc
		(start 379.941836 -289.798506)
		(mid 380.224792 -289.722329)
		(end 380.507748 -289.798506)
		(width 0.0889)
		(layer "In4.Cu")
		(net "M_J_CPU0_SB_DQ<25>")
	)
	(arc
		(start 386.52196 -289.798506)
		(mid 386.804916 -289.722329)
		(end 387.087872 -289.798506)
		(width 0.0889)
		(layer "In4.Cu")
		(net "M_J_CPU0_SB_DQ<25>")
	)
	(arc
		(start 385.581906 -289.798506)
		(mid 385.864862 -289.722329)
		(end 386.147818 -289.798506)
		(width 0.0889)
		(layer "In4.Cu")
		(net "M_J_CPU0_SB_DQ<25>")
	)
	(arc
		(start 379.623066 -289.824668)
		(mid 379.780576 -289.847866)
		(end 379.933454 -289.803332)
		(width 0.0889)
		(layer "In4.Cu")
		(net "M_J_CPU0_SB_DQ<25>")
	)
	(arc
		(start 388.027672 -289.798506)
		(mid 388.209923 -289.848856)
		(end 388.393432 -289.803332)
		(width 0.0889)
		(layer "In4.Cu")
		(net "M_J_CPU0_SB_DQ<25>")
	)
	(arc
		(start 384.26771 -289.798506)
		(mid 384.449961 -289.848856)
		(end 384.63347 -289.803332)
		(width 0.0889)
		(layer "In4.Cu")
		(net "M_J_CPU0_SB_DQ<25>")
	)
	(arc
		(start 384.641852 -289.798506)
		(mid 384.924808 -289.722329)
		(end 385.207764 -289.798506)
		(width 0.0889)
		(layer "In4.Cu")
		(net "M_J_CPU0_SB_DQ<25>")
	)
	(arc
		(start 381.821944 -289.798506)
		(mid 382.1049 -289.722329)
		(end 382.387856 -289.798506)
		(width 0.0889)
		(layer "In4.Cu")
		(net "M_J_CPU0_SB_DQ<25>")
	)
	(arc
		(start 387.087872 -289.798506)
		(mid 387.274816 -289.848761)
		(end 387.46176 -289.798506)
		(width 0.0889)
		(layer "In4.Cu")
		(net "M_J_CPU0_SB_DQ<25>")
	)
	(arc
		(start 386.1562 -289.803332)
		(mid 386.339708 -289.848826)
		(end 386.52196 -289.798506)
		(width 0.0889)
		(layer "In4.Cu")
		(net "M_J_CPU0_SB_DQ<25>")
	)
	(segment
		(start 380.697994 -288.399982)
		(end 381.164846 -288.66592)
		(width 0.10668)
		(layer "F.Cu")
		(net "M_J_CPU0_SB_DQ<24>")
	)
	(segment
		(start 425.601638 -309.110126)
		(end 426.451522 -309.96001)
		(width 0.14478)
		(layer "In4.Cu")
		(net "M_J_CPU0_SB_DQ<24>")
	)
	(segment
		(start 395.834616 -291.575998)
		(end 398.116298 -293.85768)
		(width 0.14478)
		(layer "In4.Cu")
		(net "M_J_CPU0_SB_DQ<24>")
	)
	(segment
		(start 383.79781 -288.9885)
		(end 383.806192 -288.993326)
		(width 0.0889)
		(layer "In4.Cu")
		(net "M_J_CPU0_SB_DQ<24>")
	)
	(segment
		(start 408.62123 -309.96001)
		(end 414.183068 -309.96001)
		(width 0.14478)
		(layer "In4.Cu")
		(net "M_J_CPU0_SB_DQ<24>")
	)
	(segment
		(start 429.922432 -309.109872)
		(end 437.145938 -309.109872)
		(width 0.14478)
		(layer "In4.Cu")
		(net "M_J_CPU0_SB_DQ<24>")
	)
	(segment
		(start 403.418802 -305.585114)
		(end 404.246334 -305.585114)
		(width 0.14478)
		(layer "In4.Cu")
		(net "M_J_CPU0_SB_DQ<24>")
	)
	(segment
		(start 421.727122 -309.96001)
		(end 422.577006 -309.110126)
		(width 0.14478)
		(layer "In4.Cu")
		(net "M_J_CPU0_SB_DQ<24>")
	)
	(segment
		(start 438.675272 -309.109872)
		(end 439.100214 -309.534814)
		(width 0.14478)
		(layer "In4.Cu")
		(net "M_J_CPU0_SB_DQ<24>")
	)
	(segment
		(start 437.697372 -310.052212)
		(end 437.858916 -309.890668)
		(width 0.14478)
		(layer "In4.Cu")
		(net "M_J_CPU0_SB_DQ<24>")
	)
	(segment
		(start 426.451522 -309.96001)
		(end 426.451776 -309.959756)
		(width 0.14478)
		(layer "In4.Cu")
		(net "M_J_CPU0_SB_DQ<24>")
	)
	(segment
		(start 418.057584 -309.110126)
		(end 418.907468 -309.96001)
		(width 0.14478)
		(layer "In4.Cu")
		(net "M_J_CPU0_SB_DQ<24>")
	)
	(segment
		(start 438.02046 -309.109872)
		(end 438.675272 -309.109872)
		(width 0.14478)
		(layer "In4.Cu")
		(net "M_J_CPU0_SB_DQ<24>")
	)
	(segment
		(start 381.010922 -288.93135)
		(end 381.033274 -289.014662)
		(width 0.0889)
		(layer "In4.Cu")
		(net "M_J_CPU0_SB_DQ<24>")
	)
	(segment
		(start 415.032952 -309.110126)
		(end 418.057584 -309.110126)
		(width 0.14478)
		(layer "In4.Cu")
		(net "M_J_CPU0_SB_DQ<24>")
	)
	(segment
		(start 386.043424 -288.993326)
		(end 386.051806 -288.9885)
		(width 0.0889)
		(layer "In4.Cu")
		(net "M_J_CPU0_SB_DQ<24>")
	)
	(segment
		(start 437.145938 -309.109872)
		(end 437.307482 -309.271416)
		(width 0.14478)
		(layer "In4.Cu")
		(net "M_J_CPU0_SB_DQ<24>")
	)
	(segment
		(start 398.116298 -300.28261)
		(end 403.418802 -305.585114)
		(width 0.14478)
		(layer "In4.Cu")
		(net "M_J_CPU0_SB_DQ<24>")
	)
	(segment
		(start 404.246334 -305.585114)
		(end 408.62123 -309.96001)
		(width 0.14478)
		(layer "In4.Cu")
		(net "M_J_CPU0_SB_DQ<24>")
	)
	(segment
		(start 439.100214 -309.534814)
		(end 439.100214 -309.535068)
		(width 0.14478)
		(layer "In4.Cu")
		(net "M_J_CPU0_SB_DQ<24>")
	)
	(segment
		(start 394.894054 -291.35451)
		(end 395.613128 -291.35451)
		(width 0.0889)
		(layer "In4.Cu")
		(net "M_J_CPU0_SB_DQ<24>")
	)
	(segment
		(start 392.234674 -288.9758)
		(end 392.453876 -289.033204)
		(width 0.0889)
		(layer "In4.Cu")
		(net "M_J_CPU0_SB_DQ<24>")
	)
	(segment
		(start 418.907468 -309.96001)
		(end 421.727122 -309.96001)
		(width 0.14478)
		(layer "In4.Cu")
		(net "M_J_CPU0_SB_DQ<24>")
	)
	(segment
		(start 429.072548 -309.959756)
		(end 429.922432 -309.109872)
		(width 0.14478)
		(layer "In4.Cu")
		(net "M_J_CPU0_SB_DQ<24>")
	)
	(segment
		(start 398.116298 -293.85768)
		(end 398.116298 -300.28261)
		(width 0.14478)
		(layer "In4.Cu")
		(net "M_J_CPU0_SB_DQ<24>")
	)
	(segment
		(start 437.858916 -309.890668)
		(end 437.858916 -309.271416)
		(width 0.14478)
		(layer "In4.Cu")
		(net "M_J_CPU0_SB_DQ<24>")
	)
	(segment
		(start 388.497826 -288.9885)
		(end 388.506208 -288.993326)
		(width 0.0889)
		(layer "In4.Cu")
		(net "M_J_CPU0_SB_DQ<24>")
	)
	(segment
		(start 386.983478 -288.993326)
		(end 386.99186 -288.9885)
		(width 0.0889)
		(layer "In4.Cu")
		(net "M_J_CPU0_SB_DQ<24>")
	)
	(segment
		(start 392.453876 -289.033204)
		(end 392.555222 -289.04311)
		(width 0.0889)
		(layer "In4.Cu")
		(net "M_J_CPU0_SB_DQ<24>")
	)
	(segment
		(start 437.469026 -310.052212)
		(end 437.697372 -310.052212)
		(width 0.14478)
		(layer "In4.Cu")
		(net "M_J_CPU0_SB_DQ<24>")
	)
	(segment
		(start 387.557772 -288.9885)
		(end 387.566154 -288.993326)
		(width 0.0889)
		(layer "In4.Cu")
		(net "M_J_CPU0_SB_DQ<24>")
	)
	(segment
		(start 390.74344 -288.993326)
		(end 390.751822 -288.9885)
		(width 0.0889)
		(layer "In4.Cu")
		(net "M_J_CPU0_SB_DQ<24>")
	)
	(segment
		(start 422.577006 -309.110126)
		(end 425.601638 -309.110126)
		(width 0.14478)
		(layer "In4.Cu")
		(net "M_J_CPU0_SB_DQ<24>")
	)
	(segment
		(start 391.317734 -288.9885)
		(end 391.326116 -288.993326)
		(width 0.0889)
		(layer "In4.Cu")
		(net "M_J_CPU0_SB_DQ<24>")
	)
	(segment
		(start 395.613128 -291.35451)
		(end 395.834616 -291.575998)
		(width 0.0889)
		(layer "In4.Cu")
		(net "M_J_CPU0_SB_DQ<24>")
	)
	(segment
		(start 382.857756 -288.9885)
		(end 382.866138 -288.993326)
		(width 0.0889)
		(layer "In4.Cu")
		(net "M_J_CPU0_SB_DQ<24>")
	)
	(segment
		(start 392.555222 -289.04311)
		(end 393.58316 -289.04311)
		(width 0.0889)
		(layer "In4.Cu")
		(net "M_J_CPU0_SB_DQ<24>")
	)
	(segment
		(start 437.307482 -309.271416)
		(end 437.307482 -309.890668)
		(width 0.14478)
		(layer "In4.Cu")
		(net "M_J_CPU0_SB_DQ<24>")
	)
	(segment
		(start 437.307482 -309.890668)
		(end 437.469026 -310.052212)
		(width 0.14478)
		(layer "In4.Cu")
		(net "M_J_CPU0_SB_DQ<24>")
	)
	(segment
		(start 382.283462 -288.993326)
		(end 382.291844 -288.9885)
		(width 0.0889)
		(layer "In4.Cu")
		(net "M_J_CPU0_SB_DQ<24>")
	)
	(segment
		(start 426.451776 -309.959756)
		(end 429.072548 -309.959756)
		(width 0.14478)
		(layer "In4.Cu")
		(net "M_J_CPU0_SB_DQ<24>")
	)
	(segment
		(start 381.164846 -288.66592)
		(end 381.010922 -288.93135)
		(width 0.0889)
		(layer "In4.Cu")
		(net "M_J_CPU0_SB_DQ<24>")
	)
	(segment
		(start 394.543534 -290.003484)
		(end 394.543534 -291.00399)
		(width 0.0889)
		(layer "In4.Cu")
		(net "M_J_CPU0_SB_DQ<24>")
	)
	(segment
		(start 414.183068 -309.96001)
		(end 415.032952 -309.110126)
		(width 0.14478)
		(layer "In4.Cu")
		(net "M_J_CPU0_SB_DQ<24>")
	)
	(segment
		(start 394.543534 -291.00399)
		(end 394.894054 -291.35451)
		(width 0.0889)
		(layer "In4.Cu")
		(net "M_J_CPU0_SB_DQ<24>")
	)
	(segment
		(start 437.858916 -309.271416)
		(end 438.02046 -309.109872)
		(width 0.14478)
		(layer "In4.Cu")
		(net "M_J_CPU0_SB_DQ<24>")
	)
	(segment
		(start 393.58316 -289.04311)
		(end 394.543534 -290.003484)
		(width 0.0889)
		(layer "In4.Cu")
		(net "M_J_CPU0_SB_DQ<24>")
	)
	(arc
		(start 383.231898 -288.9885)
		(mid 383.514854 -288.912323)
		(end 383.79781 -288.9885)
		(width 0.0889)
		(layer "In4.Cu")
		(net "M_J_CPU0_SB_DQ<24>")
	)
	(arc
		(start 386.617718 -288.9885)
		(mid 386.799969 -289.03885)
		(end 386.983478 -288.993326)
		(width 0.0889)
		(layer "In4.Cu")
		(net "M_J_CPU0_SB_DQ<24>")
	)
	(arc
		(start 385.677664 -288.9885)
		(mid 385.859915 -289.03885)
		(end 386.043424 -288.993326)
		(width 0.0889)
		(layer "In4.Cu")
		(net "M_J_CPU0_SB_DQ<24>")
	)
	(arc
		(start 388.506208 -288.993326)
		(mid 388.689716 -289.03882)
		(end 388.871968 -288.9885)
		(width 0.0889)
		(layer "In4.Cu")
		(net "M_J_CPU0_SB_DQ<24>")
	)
	(arc
		(start 383.806192 -288.993326)
		(mid 383.9897 -289.03882)
		(end 384.171952 -288.9885)
		(width 0.0889)
		(layer "In4.Cu")
		(net "M_J_CPU0_SB_DQ<24>")
	)
	(arc
		(start 388.871968 -288.9885)
		(mid 389.154924 -288.912323)
		(end 389.43788 -288.9885)
		(width 0.0889)
		(layer "In4.Cu")
		(net "M_J_CPU0_SB_DQ<24>")
	)
	(arc
		(start 382.866138 -288.993326)
		(mid 383.049646 -289.03882)
		(end 383.231898 -288.9885)
		(width 0.0889)
		(layer "In4.Cu")
		(net "M_J_CPU0_SB_DQ<24>")
	)
	(arc
		(start 381.35179 -288.9885)
		(mid 381.634746 -288.912323)
		(end 381.917702 -288.9885)
		(width 0.0889)
		(layer "In4.Cu")
		(net "M_J_CPU0_SB_DQ<24>")
	)
	(arc
		(start 385.111752 -288.9885)
		(mid 385.394708 -288.912323)
		(end 385.677664 -288.9885)
		(width 0.0889)
		(layer "In4.Cu")
		(net "M_J_CPU0_SB_DQ<24>")
	)
	(arc
		(start 384.171952 -288.9885)
		(mid 384.454908 -288.912323)
		(end 384.737864 -288.9885)
		(width 0.0889)
		(layer "In4.Cu")
		(net "M_J_CPU0_SB_DQ<24>")
	)
	(arc
		(start 381.917702 -288.9885)
		(mid 382.099953 -289.03885)
		(end 382.283462 -288.993326)
		(width 0.0889)
		(layer "In4.Cu")
		(net "M_J_CPU0_SB_DQ<24>")
	)
	(arc
		(start 382.291844 -288.9885)
		(mid 382.5748 -288.912323)
		(end 382.857756 -288.9885)
		(width 0.0889)
		(layer "In4.Cu")
		(net "M_J_CPU0_SB_DQ<24>")
	)
	(arc
		(start 387.931914 -288.9885)
		(mid 388.21487 -288.912323)
		(end 388.497826 -288.9885)
		(width 0.0889)
		(layer "In4.Cu")
		(net "M_J_CPU0_SB_DQ<24>")
	)
	(arc
		(start 386.99186 -288.9885)
		(mid 387.274816 -288.912323)
		(end 387.557772 -288.9885)
		(width 0.0889)
		(layer "In4.Cu")
		(net "M_J_CPU0_SB_DQ<24>")
	)
	(arc
		(start 390.37768 -288.9885)
		(mid 390.559931 -289.03885)
		(end 390.74344 -288.993326)
		(width 0.0889)
		(layer "In4.Cu")
		(net "M_J_CPU0_SB_DQ<24>")
	)
	(arc
		(start 391.691876 -288.9885)
		(mid 391.961645 -288.912477)
		(end 392.234674 -288.9758)
		(width 0.0889)
		(layer "In4.Cu")
		(net "M_J_CPU0_SB_DQ<24>")
	)
	(arc
		(start 384.737864 -288.9885)
		(mid 384.924808 -289.038755)
		(end 385.111752 -288.9885)
		(width 0.0889)
		(layer "In4.Cu")
		(net "M_J_CPU0_SB_DQ<24>")
	)
	(arc
		(start 390.751822 -288.9885)
		(mid 391.034778 -288.912323)
		(end 391.317734 -288.9885)
		(width 0.0889)
		(layer "In4.Cu")
		(net "M_J_CPU0_SB_DQ<24>")
	)
	(arc
		(start 381.033274 -289.014662)
		(mid 381.195463 -289.037397)
		(end 381.35179 -288.9885)
		(width 0.0889)
		(layer "In4.Cu")
		(net "M_J_CPU0_SB_DQ<24>")
	)
	(arc
		(start 386.051806 -288.9885)
		(mid 386.334762 -288.912323)
		(end 386.617718 -288.9885)
		(width 0.0889)
		(layer "In4.Cu")
		(net "M_J_CPU0_SB_DQ<24>")
	)
	(arc
		(start 391.326116 -288.993326)
		(mid 391.509624 -289.03882)
		(end 391.691876 -288.9885)
		(width 0.0889)
		(layer "In4.Cu")
		(net "M_J_CPU0_SB_DQ<24>")
	)
	(arc
		(start 389.811768 -288.9885)
		(mid 390.094724 -288.912323)
		(end 390.37768 -288.9885)
		(width 0.0889)
		(layer "In4.Cu")
		(net "M_J_CPU0_SB_DQ<24>")
	)
	(arc
		(start 387.566154 -288.993326)
		(mid 387.749662 -289.03882)
		(end 387.931914 -288.9885)
		(width 0.0889)
		(layer "In4.Cu")
		(net "M_J_CPU0_SB_DQ<24>")
	)
	(arc
		(start 389.43788 -288.9885)
		(mid 389.624824 -289.038755)
		(end 389.811768 -288.9885)
		(width 0.0889)
		(layer "In4.Cu")
		(net "M_J_CPU0_SB_DQ<24>")
	)
	(segment
		(start 378.817886 -288.399982)
		(end 379.284738 -288.66592)
		(width 0.10668)
		(layer "F.Cu")
		(net "M_J_CPU0_SB_DQ<23>")
	)
	(segment
		(start 386.043424 -288.338768)
		(end 386.051806 -288.343594)
		(width 0.0889)
		(layer "In4.Cu")
		(net "M_J_CPU0_SB_DQ<23>")
	)
	(segment
		(start 426.516292 -309.109872)
		(end 429.013366 -309.109872)
		(width 0.14478)
		(layer "In4.Cu")
		(net "M_J_CPU0_SB_DQ<23>")
	)
	(segment
		(start 402.86686 -304.253646)
		(end 403.09546 -304.253646)
		(width 0.14478)
		(layer "In4.Cu")
		(net "M_J_CPU0_SB_DQ<23>")
	)
	(segment
		(start 398.667478 -300.054264)
		(end 402.086572 -303.473358)
		(width 0.14478)
		(layer "In4.Cu")
		(net "M_J_CPU0_SB_DQ<23>")
	)
	(segment
		(start 382.857756 -288.343594)
		(end 382.866138 -288.338768)
		(width 0.0889)
		(layer "In4.Cu")
		(net "M_J_CPU0_SB_DQ<23>")
	)
	(segment
		(start 382.283462 -288.338768)
		(end 382.291844 -288.343594)
		(width 0.0889)
		(layer "In4.Cu")
		(net "M_J_CPU0_SB_DQ<23>")
	)
	(segment
		(start 404.060914 -304.848768)
		(end 404.289514 -304.848768)
		(width 0.14478)
		(layer "In4.Cu")
		(net "M_J_CPU0_SB_DQ<23>")
	)
	(segment
		(start 429.013366 -309.109872)
		(end 429.862996 -308.260242)
		(width 0.14478)
		(layer "In4.Cu")
		(net "M_J_CPU0_SB_DQ<23>")
	)
	(segment
		(start 398.667478 -293.621714)
		(end 398.667478 -300.054264)
		(width 0.14478)
		(layer "In4.Cu")
		(net "M_J_CPU0_SB_DQ<23>")
	)
	(segment
		(start 402.500338 -303.288192)
		(end 402.728938 -303.288192)
		(width 0.14478)
		(layer "In4.Cu")
		(net "M_J_CPU0_SB_DQ<23>")
	)
	(segment
		(start 392.554968 -288.237676)
		(end 393.474702 -288.237676)
		(width 0.0889)
		(layer "In4.Cu")
		(net "M_J_CPU0_SB_DQ<23>")
	)
	(segment
		(start 403.09546 -304.253646)
		(end 403.280626 -304.06848)
		(width 0.14478)
		(layer "In4.Cu")
		(net "M_J_CPU0_SB_DQ<23>")
	)
	(segment
		(start 393.956794 -289.111944)
		(end 395.018514 -290.173664)
		(width 0.0889)
		(layer "In4.Cu")
		(net "M_J_CPU0_SB_DQ<23>")
	)
	(segment
		(start 403.67077 -304.458624)
		(end 403.485604 -304.64379)
		(width 0.14478)
		(layer "In4.Cu")
		(net "M_J_CPU0_SB_DQ<23>")
	)
	(segment
		(start 402.705316 -303.863502)
		(end 402.705316 -304.092102)
		(width 0.14478)
		(layer "In4.Cu")
		(net "M_J_CPU0_SB_DQ<23>")
	)
	(segment
		(start 393.956794 -288.719768)
		(end 393.956794 -289.111944)
		(width 0.0889)
		(layer "In4.Cu")
		(net "M_J_CPU0_SB_DQ<23>")
	)
	(segment
		(start 393.474702 -288.237676)
		(end 393.956794 -288.719768)
		(width 0.0889)
		(layer "In4.Cu")
		(net "M_J_CPU0_SB_DQ<23>")
	)
	(segment
		(start 403.647148 -305.033934)
		(end 403.875748 -305.033934)
		(width 0.14478)
		(layer "In4.Cu")
		(net "M_J_CPU0_SB_DQ<23>")
	)
	(segment
		(start 379.438916 -288.40049)
		(end 379.534674 -288.37509)
		(width 0.0889)
		(layer "In4.Cu")
		(net "M_J_CPU0_SB_DQ<23>")
	)
	(segment
		(start 402.890482 -303.678336)
		(end 402.705316 -303.863502)
		(width 0.14478)
		(layer "In4.Cu")
		(net "M_J_CPU0_SB_DQ<23>")
	)
	(segment
		(start 402.315172 -303.473358)
		(end 402.500338 -303.288192)
		(width 0.14478)
		(layer "In4.Cu")
		(net "M_J_CPU0_SB_DQ<23>")
	)
	(segment
		(start 429.862996 -308.260242)
		(end 434.575204 -308.260242)
		(width 0.14478)
		(layer "In4.Cu")
		(net "M_J_CPU0_SB_DQ<23>")
	)
	(segment
		(start 404.289514 -304.848768)
		(end 408.551126 -309.11038)
		(width 0.14478)
		(layer "In4.Cu")
		(net "M_J_CPU0_SB_DQ<23>")
	)
	(segment
		(start 403.875748 -305.033934)
		(end 404.060914 -304.848768)
		(width 0.14478)
		(layer "In4.Cu")
		(net "M_J_CPU0_SB_DQ<23>")
	)
	(segment
		(start 379.284738 -288.66592)
		(end 379.438916 -288.40049)
		(width 0.0889)
		(layer "In4.Cu")
		(net "M_J_CPU0_SB_DQ<23>")
	)
	(segment
		(start 408.551126 -309.11038)
		(end 414.090104 -309.11038)
		(width 0.14478)
		(layer "In4.Cu")
		(net "M_J_CPU0_SB_DQ<23>")
	)
	(segment
		(start 422.484296 -308.260242)
		(end 425.666662 -308.260242)
		(width 0.14478)
		(layer "In4.Cu")
		(net "M_J_CPU0_SB_DQ<23>")
	)
	(segment
		(start 395.018514 -290.173664)
		(end 395.219428 -290.173664)
		(width 0.0889)
		(layer "In4.Cu")
		(net "M_J_CPU0_SB_DQ<23>")
	)
	(segment
		(start 402.086572 -303.473358)
		(end 402.315172 -303.473358)
		(width 0.14478)
		(layer "In4.Cu")
		(net "M_J_CPU0_SB_DQ<23>")
	)
	(segment
		(start 434.575204 -308.260242)
		(end 435.000146 -308.685184)
		(width 0.14478)
		(layer "In4.Cu")
		(net "M_J_CPU0_SB_DQ<23>")
	)
	(segment
		(start 395.829536 -290.783772)
		(end 398.667478 -293.621714)
		(width 0.14478)
		(layer "In4.Cu")
		(net "M_J_CPU0_SB_DQ<23>")
	)
	(segment
		(start 403.485604 -304.64379)
		(end 403.485604 -304.87239)
		(width 0.14478)
		(layer "In4.Cu")
		(net "M_J_CPU0_SB_DQ<23>")
	)
	(segment
		(start 380.037848 -288.343594)
		(end 380.04623 -288.338768)
		(width 0.0889)
		(layer "In4.Cu")
		(net "M_J_CPU0_SB_DQ<23>")
	)
	(segment
		(start 386.983478 -288.338768)
		(end 386.99186 -288.343594)
		(width 0.0889)
		(layer "In4.Cu")
		(net "M_J_CPU0_SB_DQ<23>")
	)
	(segment
		(start 425.666662 -308.260242)
		(end 426.516292 -309.109872)
		(width 0.14478)
		(layer "In4.Cu")
		(net "M_J_CPU0_SB_DQ<23>")
	)
	(segment
		(start 418.122608 -308.260242)
		(end 418.972746 -309.11038)
		(width 0.14478)
		(layer "In4.Cu")
		(net "M_J_CPU0_SB_DQ<23>")
	)
	(segment
		(start 421.634158 -309.11038)
		(end 422.484296 -308.260242)
		(width 0.14478)
		(layer "In4.Cu")
		(net "M_J_CPU0_SB_DQ<23>")
	)
	(segment
		(start 395.219428 -290.173664)
		(end 395.829536 -290.783772)
		(width 0.0889)
		(layer "In4.Cu")
		(net "M_J_CPU0_SB_DQ<23>")
	)
	(segment
		(start 402.705316 -304.092102)
		(end 402.86686 -304.253646)
		(width 0.14478)
		(layer "In4.Cu")
		(net "M_J_CPU0_SB_DQ<23>")
	)
	(segment
		(start 414.090104 -309.11038)
		(end 414.940242 -308.260242)
		(width 0.14478)
		(layer "In4.Cu")
		(net "M_J_CPU0_SB_DQ<23>")
	)
	(segment
		(start 418.972746 -309.11038)
		(end 421.634158 -309.11038)
		(width 0.14478)
		(layer "In4.Cu")
		(net "M_J_CPU0_SB_DQ<23>")
	)
	(segment
		(start 391.317734 -288.343594)
		(end 391.326116 -288.338768)
		(width 0.0889)
		(layer "In4.Cu")
		(net "M_J_CPU0_SB_DQ<23>")
	)
	(segment
		(start 388.497826 -288.343594)
		(end 388.506208 -288.338768)
		(width 0.0889)
		(layer "In4.Cu")
		(net "M_J_CPU0_SB_DQ<23>")
	)
	(segment
		(start 403.280626 -304.06848)
		(end 403.509226 -304.06848)
		(width 0.14478)
		(layer "In4.Cu")
		(net "M_J_CPU0_SB_DQ<23>")
	)
	(segment
		(start 383.79781 -288.343594)
		(end 383.806192 -288.338768)
		(width 0.0889)
		(layer "In4.Cu")
		(net "M_J_CPU0_SB_DQ<23>")
	)
	(segment
		(start 414.940242 -308.260242)
		(end 418.122608 -308.260242)
		(width 0.14478)
		(layer "In4.Cu")
		(net "M_J_CPU0_SB_DQ<23>")
	)
	(segment
		(start 403.67077 -304.230024)
		(end 403.67077 -304.458624)
		(width 0.14478)
		(layer "In4.Cu")
		(net "M_J_CPU0_SB_DQ<23>")
	)
	(segment
		(start 403.509226 -304.06848)
		(end 403.67077 -304.230024)
		(width 0.14478)
		(layer "In4.Cu")
		(net "M_J_CPU0_SB_DQ<23>")
	)
	(segment
		(start 387.557772 -288.343594)
		(end 387.566154 -288.338768)
		(width 0.0889)
		(layer "In4.Cu")
		(net "M_J_CPU0_SB_DQ<23>")
	)
	(segment
		(start 403.485604 -304.87239)
		(end 403.647148 -305.033934)
		(width 0.14478)
		(layer "In4.Cu")
		(net "M_J_CPU0_SB_DQ<23>")
	)
	(segment
		(start 402.728938 -303.288192)
		(end 402.890482 -303.449736)
		(width 0.14478)
		(layer "In4.Cu")
		(net "M_J_CPU0_SB_DQ<23>")
	)
	(segment
		(start 390.74344 -288.338768)
		(end 390.751822 -288.343594)
		(width 0.0889)
		(layer "In4.Cu")
		(net "M_J_CPU0_SB_DQ<23>")
	)
	(segment
		(start 402.890482 -303.449736)
		(end 402.890482 -303.678336)
		(width 0.14478)
		(layer "In4.Cu")
		(net "M_J_CPU0_SB_DQ<23>")
	)
	(arc
		(start 380.41199 -288.343594)
		(mid 380.694946 -288.419771)
		(end 380.977902 -288.343594)
		(width 0.0889)
		(layer "In4.Cu")
		(net "M_J_CPU0_SB_DQ<23>")
	)
	(arc
		(start 391.326116 -288.338768)
		(mid 391.509624 -288.293243)
		(end 391.691876 -288.343594)
		(width 0.0889)
		(layer "In4.Cu")
		(net "M_J_CPU0_SB_DQ<23>")
	)
	(arc
		(start 387.931914 -288.343594)
		(mid 388.21487 -288.419771)
		(end 388.497826 -288.343594)
		(width 0.0889)
		(layer "In4.Cu")
		(net "M_J_CPU0_SB_DQ<23>")
	)
	(arc
		(start 381.35179 -288.343594)
		(mid 381.634746 -288.419771)
		(end 381.917702 -288.343594)
		(width 0.0889)
		(layer "In4.Cu")
		(net "M_J_CPU0_SB_DQ<23>")
	)
	(arc
		(start 389.43788 -288.343594)
		(mid 389.624824 -288.293305)
		(end 389.811768 -288.343594)
		(width 0.0889)
		(layer "In4.Cu")
		(net "M_J_CPU0_SB_DQ<23>")
	)
	(arc
		(start 380.977902 -288.343594)
		(mid 381.164846 -288.293305)
		(end 381.35179 -288.343594)
		(width 0.0889)
		(layer "In4.Cu")
		(net "M_J_CPU0_SB_DQ<23>")
	)
	(arc
		(start 387.566154 -288.338768)
		(mid 387.749662 -288.293243)
		(end 387.931914 -288.343594)
		(width 0.0889)
		(layer "In4.Cu")
		(net "M_J_CPU0_SB_DQ<23>")
	)
	(arc
		(start 385.677664 -288.343594)
		(mid 385.859915 -288.29321)
		(end 386.043424 -288.338768)
		(width 0.0889)
		(layer "In4.Cu")
		(net "M_J_CPU0_SB_DQ<23>")
	)
	(arc
		(start 382.291844 -288.343594)
		(mid 382.5748 -288.419771)
		(end 382.857756 -288.343594)
		(width 0.0889)
		(layer "In4.Cu")
		(net "M_J_CPU0_SB_DQ<23>")
	)
	(arc
		(start 380.04623 -288.338768)
		(mid 380.229738 -288.293243)
		(end 380.41199 -288.343594)
		(width 0.0889)
		(layer "In4.Cu")
		(net "M_J_CPU0_SB_DQ<23>")
	)
	(arc
		(start 390.751822 -288.343594)
		(mid 391.034778 -288.419771)
		(end 391.317734 -288.343594)
		(width 0.0889)
		(layer "In4.Cu")
		(net "M_J_CPU0_SB_DQ<23>")
	)
	(arc
		(start 379.534674 -288.37509)
		(mid 379.789996 -288.41879)
		(end 380.037848 -288.343594)
		(width 0.0889)
		(layer "In4.Cu")
		(net "M_J_CPU0_SB_DQ<23>")
	)
	(arc
		(start 386.99186 -288.343594)
		(mid 387.274816 -288.419771)
		(end 387.557772 -288.343594)
		(width 0.0889)
		(layer "In4.Cu")
		(net "M_J_CPU0_SB_DQ<23>")
	)
	(arc
		(start 389.811768 -288.343594)
		(mid 390.094724 -288.419771)
		(end 390.37768 -288.343594)
		(width 0.0889)
		(layer "In4.Cu")
		(net "M_J_CPU0_SB_DQ<23>")
	)
	(arc
		(start 390.37768 -288.343594)
		(mid 390.559931 -288.29321)
		(end 390.74344 -288.338768)
		(width 0.0889)
		(layer "In4.Cu")
		(net "M_J_CPU0_SB_DQ<23>")
	)
	(arc
		(start 386.051806 -288.343594)
		(mid 386.334762 -288.419771)
		(end 386.617718 -288.343594)
		(width 0.0889)
		(layer "In4.Cu")
		(net "M_J_CPU0_SB_DQ<23>")
	)
	(arc
		(start 391.691876 -288.343594)
		(mid 391.828312 -288.400419)
		(end 391.974832 -288.419794)
		(width 0.0889)
		(layer "In4.Cu")
		(net "M_J_CPU0_SB_DQ<23>")
	)
	(arc
		(start 388.506208 -288.338768)
		(mid 388.689716 -288.293243)
		(end 388.871968 -288.343594)
		(width 0.0889)
		(layer "In4.Cu")
		(net "M_J_CPU0_SB_DQ<23>")
	)
	(arc
		(start 388.871968 -288.343594)
		(mid 389.154924 -288.419771)
		(end 389.43788 -288.343594)
		(width 0.0889)
		(layer "In4.Cu")
		(net "M_J_CPU0_SB_DQ<23>")
	)
	(arc
		(start 382.866138 -288.338768)
		(mid 383.049646 -288.293243)
		(end 383.231898 -288.343594)
		(width 0.0889)
		(layer "In4.Cu")
		(net "M_J_CPU0_SB_DQ<23>")
	)
	(arc
		(start 383.806192 -288.338768)
		(mid 383.9897 -288.293243)
		(end 384.171952 -288.343594)
		(width 0.0889)
		(layer "In4.Cu")
		(net "M_J_CPU0_SB_DQ<23>")
	)
	(arc
		(start 386.617718 -288.343594)
		(mid 386.799969 -288.29321)
		(end 386.983478 -288.338768)
		(width 0.0889)
		(layer "In4.Cu")
		(net "M_J_CPU0_SB_DQ<23>")
	)
	(arc
		(start 385.111752 -288.343594)
		(mid 385.394708 -288.419771)
		(end 385.677664 -288.343594)
		(width 0.0889)
		(layer "In4.Cu")
		(net "M_J_CPU0_SB_DQ<23>")
	)
	(arc
		(start 391.974832 -288.419794)
		(mid 392.278855 -288.373191)
		(end 392.554968 -288.237676)
		(width 0.0889)
		(layer "In4.Cu")
		(net "M_J_CPU0_SB_DQ<23>")
	)
	(arc
		(start 384.171952 -288.343594)
		(mid 384.454908 -288.419771)
		(end 384.737864 -288.343594)
		(width 0.0889)
		(layer "In4.Cu")
		(net "M_J_CPU0_SB_DQ<23>")
	)
	(arc
		(start 384.737864 -288.343594)
		(mid 384.924808 -288.293305)
		(end 385.111752 -288.343594)
		(width 0.0889)
		(layer "In4.Cu")
		(net "M_J_CPU0_SB_DQ<23>")
	)
	(arc
		(start 383.231898 -288.343594)
		(mid 383.514854 -288.419771)
		(end 383.79781 -288.343594)
		(width 0.0889)
		(layer "In4.Cu")
		(net "M_J_CPU0_SB_DQ<23>")
	)
	(arc
		(start 381.917702 -288.343594)
		(mid 382.099953 -288.29321)
		(end 382.283462 -288.338768)
		(width 0.0889)
		(layer "In4.Cu")
		(net "M_J_CPU0_SB_DQ<23>")
	)
	(segment
		(start 380.22784 -287.59023)
		(end 380.694946 -287.856168)
		(width 0.10668)
		(layer "F.Cu")
		(net "M_J_CPU0_SB_DQ<22>")
	)
	(segment
		(start 386.147818 -287.533588)
		(end 386.1562 -287.528762)
		(width 0.0889)
		(layer "In4.Cu")
		(net "M_J_CPU0_SB_DQ<22>")
	)
	(segment
		(start 402.230082 -301.25035)
		(end 402.230082 -301.478442)
		(width 0.14478)
		(layer "In4.Cu")
		(net "M_J_CPU0_SB_DQ<22>")
	)
	(segment
		(start 426.306488 -307.40985)
		(end 429.186594 -307.40985)
		(width 0.14478)
		(layer "In4.Cu")
		(net "M_J_CPU0_SB_DQ<22>")
	)
	(segment
		(start 425.456858 -306.56022)
		(end 426.306488 -307.40985)
		(width 0.14478)
		(layer "In4.Cu")
		(net "M_J_CPU0_SB_DQ<22>")
	)
	(segment
		(start 394.317474 -288.37509)
		(end 394.70711 -288.37509)
		(width 0.0889)
		(layer "In4.Cu")
		(net "M_J_CPU0_SB_DQ<22>")
	)
	(segment
		(start 389.90778 -287.533588)
		(end 389.916162 -287.528762)
		(width 0.0889)
		(layer "In4.Cu")
		(net "M_J_CPU0_SB_DQ<22>")
	)
	(segment
		(start 401.449794 -300.470062)
		(end 401.449794 -300.698154)
		(width 0.14478)
		(layer "In4.Cu")
		(net "M_J_CPU0_SB_DQ<22>")
	)
	(segment
		(start 399.566638 -293.234618)
		(end 399.566638 -298.586906)
		(width 0.14478)
		(layer "In4.Cu")
		(net "M_J_CPU0_SB_DQ<22>")
	)
	(segment
		(start 384.63347 -287.528762)
		(end 384.641852 -287.533588)
		(width 0.0889)
		(layer "In4.Cu")
		(net "M_J_CPU0_SB_DQ<22>")
	)
	(segment
		(start 389.333486 -287.528762)
		(end 389.341868 -287.533588)
		(width 0.0889)
		(layer "In4.Cu")
		(net "M_J_CPU0_SB_DQ<22>")
	)
	(segment
		(start 399.570194 -299.68444)
		(end 399.732246 -299.846492)
		(width 0.14478)
		(layer "In4.Cu")
		(net "M_J_CPU0_SB_DQ<22>")
	)
	(segment
		(start 399.566638 -298.586906)
		(end 399.889218 -298.909486)
		(width 0.14478)
		(layer "In4.Cu")
		(net "M_J_CPU0_SB_DQ<22>")
	)
	(segment
		(start 400.350482 -300.464728)
		(end 400.512534 -300.62678)
		(width 0.14478)
		(layer "In4.Cu")
		(net "M_J_CPU0_SB_DQ<22>")
	)
	(segment
		(start 417.791392 -306.56022)
		(end 418.64153 -307.410358)
		(width 0.14478)
		(layer "In4.Cu")
		(net "M_J_CPU0_SB_DQ<22>")
	)
	(segment
		(start 402.230082 -301.478442)
		(end 401.911058 -301.797212)
		(width 0.14478)
		(layer "In4.Cu")
		(net "M_J_CPU0_SB_DQ<22>")
	)
	(segment
		(start 430.036224 -306.56022)
		(end 434.575204 -306.56022)
		(width 0.14478)
		(layer "In4.Cu")
		(net "M_J_CPU0_SB_DQ<22>")
	)
	(segment
		(start 421.634158 -307.410358)
		(end 422.484296 -306.56022)
		(width 0.14478)
		(layer "In4.Cu")
		(net "M_J_CPU0_SB_DQ<22>")
	)
	(segment
		(start 394.70711 -288.37509)
		(end 395.529816 -289.197796)
		(width 0.0889)
		(layer "In4.Cu")
		(net "M_J_CPU0_SB_DQ<22>")
	)
	(segment
		(start 395.529816 -289.197796)
		(end 399.566638 -293.234618)
		(width 0.14478)
		(layer "In4.Cu")
		(net "M_J_CPU0_SB_DQ<22>")
	)
	(segment
		(start 400.507454 -299.527722)
		(end 400.669506 -299.689774)
		(width 0.14478)
		(layer "In4.Cu")
		(net "M_J_CPU0_SB_DQ<22>")
	)
	(segment
		(start 383.693416 -287.528762)
		(end 383.701798 -287.533588)
		(width 0.0889)
		(layer "In4.Cu")
		(net "M_J_CPU0_SB_DQ<22>")
	)
	(segment
		(start 414.090104 -307.410358)
		(end 414.940242 -306.56022)
		(width 0.14478)
		(layer "In4.Cu")
		(net "M_J_CPU0_SB_DQ<22>")
	)
	(segment
		(start 408.39009 -307.410358)
		(end 414.090104 -307.410358)
		(width 0.14478)
		(layer "In4.Cu")
		(net "M_J_CPU0_SB_DQ<22>")
	)
	(segment
		(start 402.06803 -301.088298)
		(end 402.230082 -301.25035)
		(width 0.14478)
		(layer "In4.Cu")
		(net "M_J_CPU0_SB_DQ<22>")
	)
	(segment
		(start 402.07311 -302.187356)
		(end 402.301202 -302.187356)
		(width 0.14478)
		(layer "In4.Cu")
		(net "M_J_CPU0_SB_DQ<22>")
	)
	(segment
		(start 402.848318 -301.868586)
		(end 408.39009 -307.410358)
		(width 0.14478)
		(layer "In4.Cu")
		(net "M_J_CPU0_SB_DQ<22>")
	)
	(segment
		(start 400.740626 -300.62678)
		(end 401.05965 -300.30801)
		(width 0.14478)
		(layer "In4.Cu")
		(net "M_J_CPU0_SB_DQ<22>")
	)
	(segment
		(start 400.350482 -300.236636)
		(end 400.350482 -300.464728)
		(width 0.14478)
		(layer "In4.Cu")
		(net "M_J_CPU0_SB_DQ<22>")
	)
	(segment
		(start 414.940242 -306.56022)
		(end 417.791392 -306.56022)
		(width 0.14478)
		(layer "In4.Cu")
		(net "M_J_CPU0_SB_DQ<22>")
	)
	(segment
		(start 380.694946 -287.856168)
		(end 380.84887 -287.590738)
		(width 0.0889)
		(layer "In4.Cu")
		(net "M_J_CPU0_SB_DQ<22>")
	)
	(segment
		(start 401.449794 -300.698154)
		(end 401.13077 -301.016924)
		(width 0.14478)
		(layer "In4.Cu")
		(net "M_J_CPU0_SB_DQ<22>")
	)
	(segment
		(start 388.393432 -287.528762)
		(end 388.401814 -287.533588)
		(width 0.0889)
		(layer "In4.Cu")
		(net "M_J_CPU0_SB_DQ<22>")
	)
	(segment
		(start 385.207764 -287.533588)
		(end 385.216146 -287.528762)
		(width 0.0889)
		(layer "In4.Cu")
		(net "M_J_CPU0_SB_DQ<22>")
	)
	(segment
		(start 399.570194 -299.456348)
		(end 399.570194 -299.68444)
		(width 0.14478)
		(layer "In4.Cu")
		(net "M_J_CPU0_SB_DQ<22>")
	)
	(segment
		(start 401.911058 -301.797212)
		(end 401.911058 -302.025304)
		(width 0.14478)
		(layer "In4.Cu")
		(net "M_J_CPU0_SB_DQ<22>")
	)
	(segment
		(start 401.13077 -301.245016)
		(end 401.292822 -301.407068)
		(width 0.14478)
		(layer "In4.Cu")
		(net "M_J_CPU0_SB_DQ<22>")
	)
	(segment
		(start 381.447802 -287.533588)
		(end 381.456184 -287.528762)
		(width 0.0889)
		(layer "In4.Cu")
		(net "M_J_CPU0_SB_DQ<22>")
	)
	(segment
		(start 402.620226 -301.868586)
		(end 402.848318 -301.868586)
		(width 0.14478)
		(layer "In4.Cu")
		(net "M_J_CPU0_SB_DQ<22>")
	)
	(segment
		(start 380.84887 -287.590738)
		(end 380.944882 -287.565338)
		(width 0.0889)
		(layer "In4.Cu")
		(net "M_J_CPU0_SB_DQ<22>")
	)
	(segment
		(start 401.287742 -300.30801)
		(end 401.449794 -300.470062)
		(width 0.14478)
		(layer "In4.Cu")
		(net "M_J_CPU0_SB_DQ<22>")
	)
	(segment
		(start 401.13077 -301.016924)
		(end 401.13077 -301.245016)
		(width 0.14478)
		(layer "In4.Cu")
		(net "M_J_CPU0_SB_DQ<22>")
	)
	(segment
		(start 399.732246 -299.846492)
		(end 399.960338 -299.846492)
		(width 0.14478)
		(layer "In4.Cu")
		(net "M_J_CPU0_SB_DQ<22>")
	)
	(segment
		(start 391.974832 -287.482788)
		(end 392.66749 -287.482788)
		(width 0.0889)
		(layer "In4.Cu")
		(net "M_J_CPU0_SB_DQ<22>")
	)
	(segment
		(start 399.889218 -299.137578)
		(end 399.570194 -299.456348)
		(width 0.14478)
		(layer "In4.Cu")
		(net "M_J_CPU0_SB_DQ<22>")
	)
	(segment
		(start 393.033758 -287.64103)
		(end 393.583414 -287.64103)
		(width 0.0889)
		(layer "In4.Cu")
		(net "M_J_CPU0_SB_DQ<22>")
	)
	(segment
		(start 401.911058 -302.025304)
		(end 402.07311 -302.187356)
		(width 0.14478)
		(layer "In4.Cu")
		(net "M_J_CPU0_SB_DQ<22>")
	)
	(segment
		(start 400.512534 -300.62678)
		(end 400.740626 -300.62678)
		(width 0.14478)
		(layer "In4.Cu")
		(net "M_J_CPU0_SB_DQ<22>")
	)
	(segment
		(start 402.301202 -302.187356)
		(end 402.620226 -301.868586)
		(width 0.14478)
		(layer "In4.Cu")
		(net "M_J_CPU0_SB_DQ<22>")
	)
	(segment
		(start 399.960338 -299.846492)
		(end 400.279362 -299.527722)
		(width 0.14478)
		(layer "In4.Cu")
		(net "M_J_CPU0_SB_DQ<22>")
	)
	(segment
		(start 401.839938 -301.088298)
		(end 402.06803 -301.088298)
		(width 0.14478)
		(layer "In4.Cu")
		(net "M_J_CPU0_SB_DQ<22>")
	)
	(segment
		(start 401.520914 -301.407068)
		(end 401.839938 -301.088298)
		(width 0.14478)
		(layer "In4.Cu")
		(net "M_J_CPU0_SB_DQ<22>")
	)
	(segment
		(start 400.279362 -299.527722)
		(end 400.507454 -299.527722)
		(width 0.14478)
		(layer "In4.Cu")
		(net "M_J_CPU0_SB_DQ<22>")
	)
	(segment
		(start 401.05965 -300.30801)
		(end 401.287742 -300.30801)
		(width 0.14478)
		(layer "In4.Cu")
		(net "M_J_CPU0_SB_DQ<22>")
	)
	(segment
		(start 418.64153 -307.410358)
		(end 421.634158 -307.410358)
		(width 0.14478)
		(layer "In4.Cu")
		(net "M_J_CPU0_SB_DQ<22>")
	)
	(segment
		(start 422.484296 -306.56022)
		(end 425.456858 -306.56022)
		(width 0.14478)
		(layer "In4.Cu")
		(net "M_J_CPU0_SB_DQ<22>")
	)
	(segment
		(start 392.66749 -287.482788)
		(end 393.033758 -287.64103)
		(width 0.0889)
		(layer "In4.Cu")
		(net "M_J_CPU0_SB_DQ<22>")
	)
	(segment
		(start 399.889218 -298.909486)
		(end 399.889218 -299.137578)
		(width 0.14478)
		(layer "In4.Cu")
		(net "M_J_CPU0_SB_DQ<22>")
	)
	(segment
		(start 400.669506 -299.917866)
		(end 400.350482 -300.236636)
		(width 0.14478)
		(layer "In4.Cu")
		(net "M_J_CPU0_SB_DQ<22>")
	)
	(segment
		(start 393.583414 -287.64103)
		(end 394.317474 -288.37509)
		(width 0.0889)
		(layer "In4.Cu")
		(net "M_J_CPU0_SB_DQ<22>")
	)
	(segment
		(start 434.575204 -306.56022)
		(end 435.000146 -306.985162)
		(width 0.14478)
		(layer "In4.Cu")
		(net "M_J_CPU0_SB_DQ<22>")
	)
	(segment
		(start 400.669506 -299.689774)
		(end 400.669506 -299.917866)
		(width 0.14478)
		(layer "In4.Cu")
		(net "M_J_CPU0_SB_DQ<22>")
	)
	(segment
		(start 429.186594 -307.40985)
		(end 430.036224 -306.56022)
		(width 0.14478)
		(layer "In4.Cu")
		(net "M_J_CPU0_SB_DQ<22>")
	)
	(segment
		(start 401.292822 -301.407068)
		(end 401.520914 -301.407068)
		(width 0.14478)
		(layer "In4.Cu")
		(net "M_J_CPU0_SB_DQ<22>")
	)
	(arc
		(start 381.821944 -287.533588)
		(mid 382.1049 -287.609731)
		(end 382.387856 -287.533588)
		(width 0.0889)
		(layer "In4.Cu")
		(net "M_J_CPU0_SB_DQ<22>")
	)
	(arc
		(start 390.847834 -287.533588)
		(mid 391.034778 -287.483333)
		(end 391.221722 -287.533588)
		(width 0.0889)
		(layer "In4.Cu")
		(net "M_J_CPU0_SB_DQ<22>")
	)
	(arc
		(start 383.327656 -287.533588)
		(mid 383.509907 -287.483238)
		(end 383.693416 -287.528762)
		(width 0.0889)
		(layer "In4.Cu")
		(net "M_J_CPU0_SB_DQ<22>")
	)
	(arc
		(start 382.761744 -287.533588)
		(mid 383.0447 -287.609731)
		(end 383.327656 -287.533588)
		(width 0.0889)
		(layer "In4.Cu")
		(net "M_J_CPU0_SB_DQ<22>")
	)
	(arc
		(start 387.46176 -287.533588)
		(mid 387.744716 -287.609731)
		(end 388.027672 -287.533588)
		(width 0.0889)
		(layer "In4.Cu")
		(net "M_J_CPU0_SB_DQ<22>")
	)
	(arc
		(start 388.967726 -287.533588)
		(mid 389.149977 -287.483238)
		(end 389.333486 -287.528762)
		(width 0.0889)
		(layer "In4.Cu")
		(net "M_J_CPU0_SB_DQ<22>")
	)
	(arc
		(start 388.027672 -287.533588)
		(mid 388.209923 -287.483238)
		(end 388.393432 -287.528762)
		(width 0.0889)
		(layer "In4.Cu")
		(net "M_J_CPU0_SB_DQ<22>")
	)
	(arc
		(start 384.641852 -287.533588)
		(mid 384.924808 -287.609731)
		(end 385.207764 -287.533588)
		(width 0.0889)
		(layer "In4.Cu")
		(net "M_J_CPU0_SB_DQ<22>")
	)
	(arc
		(start 381.456184 -287.528762)
		(mid 381.639692 -287.483268)
		(end 381.821944 -287.533588)
		(width 0.0889)
		(layer "In4.Cu")
		(net "M_J_CPU0_SB_DQ<22>")
	)
	(arc
		(start 382.387856 -287.533588)
		(mid 382.5748 -287.483333)
		(end 382.761744 -287.533588)
		(width 0.0889)
		(layer "In4.Cu")
		(net "M_J_CPU0_SB_DQ<22>")
	)
	(arc
		(start 385.216146 -287.528762)
		(mid 385.399654 -287.483268)
		(end 385.581906 -287.533588)
		(width 0.0889)
		(layer "In4.Cu")
		(net "M_J_CPU0_SB_DQ<22>")
	)
	(arc
		(start 388.401814 -287.533588)
		(mid 388.68477 -287.609731)
		(end 388.967726 -287.533588)
		(width 0.0889)
		(layer "In4.Cu")
		(net "M_J_CPU0_SB_DQ<22>")
	)
	(arc
		(start 387.087872 -287.533588)
		(mid 387.274816 -287.483333)
		(end 387.46176 -287.533588)
		(width 0.0889)
		(layer "In4.Cu")
		(net "M_J_CPU0_SB_DQ<22>")
	)
	(arc
		(start 391.221722 -287.533588)
		(mid 391.504678 -287.609731)
		(end 391.787634 -287.533588)
		(width 0.0889)
		(layer "In4.Cu")
		(net "M_J_CPU0_SB_DQ<22>")
	)
	(arc
		(start 386.52196 -287.533588)
		(mid 386.804916 -287.609731)
		(end 387.087872 -287.533588)
		(width 0.0889)
		(layer "In4.Cu")
		(net "M_J_CPU0_SB_DQ<22>")
	)
	(arc
		(start 391.787634 -287.533588)
		(mid 391.877874 -287.495811)
		(end 391.974832 -287.482788)
		(width 0.0889)
		(layer "In4.Cu")
		(net "M_J_CPU0_SB_DQ<22>")
	)
	(arc
		(start 385.581906 -287.533588)
		(mid 385.864862 -287.609731)
		(end 386.147818 -287.533588)
		(width 0.0889)
		(layer "In4.Cu")
		(net "M_J_CPU0_SB_DQ<22>")
	)
	(arc
		(start 389.916162 -287.528762)
		(mid 390.09967 -287.483268)
		(end 390.281922 -287.533588)
		(width 0.0889)
		(layer "In4.Cu")
		(net "M_J_CPU0_SB_DQ<22>")
	)
	(arc
		(start 383.701798 -287.533588)
		(mid 383.984754 -287.609731)
		(end 384.26771 -287.533588)
		(width 0.0889)
		(layer "In4.Cu")
		(net "M_J_CPU0_SB_DQ<22>")
	)
	(arc
		(start 390.281922 -287.533588)
		(mid 390.564878 -287.609731)
		(end 390.847834 -287.533588)
		(width 0.0889)
		(layer "In4.Cu")
		(net "M_J_CPU0_SB_DQ<22>")
	)
	(arc
		(start 386.1562 -287.528762)
		(mid 386.339708 -287.483268)
		(end 386.52196 -287.533588)
		(width 0.0889)
		(layer "In4.Cu")
		(net "M_J_CPU0_SB_DQ<22>")
	)
	(arc
		(start 380.944882 -287.565338)
		(mid 381.20009 -287.608795)
		(end 381.447802 -287.533588)
		(width 0.0889)
		(layer "In4.Cu")
		(net "M_J_CPU0_SB_DQ<22>")
	)
	(arc
		(start 384.26771 -287.533588)
		(mid 384.449961 -287.483238)
		(end 384.63347 -287.528762)
		(width 0.0889)
		(layer "In4.Cu")
		(net "M_J_CPU0_SB_DQ<22>")
	)
	(arc
		(start 389.341868 -287.533588)
		(mid 389.624824 -287.609731)
		(end 389.90778 -287.533588)
		(width 0.0889)
		(layer "In4.Cu")
		(net "M_J_CPU0_SB_DQ<22>")
	)
	(segment
		(start 379.28804 -287.59023)
		(end 379.754892 -287.856168)
		(width 0.10668)
		(layer "F.Cu")
		(net "M_J_CPU0_SB_DQ<21>")
	)
	(segment
		(start 395.529562 -289.84067)
		(end 395.806422 -290.11753)
		(width 0.0889)
		(layer "In4.Cu")
		(net "M_J_CPU0_SB_DQ<21>")
	)
	(segment
		(start 384.63347 -288.18332)
		(end 384.641852 -288.178494)
		(width 0.0889)
		(layer "In4.Cu")
		(net "M_J_CPU0_SB_DQ<21>")
	)
	(segment
		(start 394.220954 -288.65703)
		(end 394.220954 -289.00247)
		(width 0.0889)
		(layer "In4.Cu")
		(net "M_J_CPU0_SB_DQ<21>")
	)
	(segment
		(start 402.980652 -302.636936)
		(end 408.220418 -307.876702)
		(width 0.14478)
		(layer "In4.Cu")
		(net "M_J_CPU0_SB_DQ<21>")
	)
	(segment
		(start 379.600714 -288.121598)
		(end 379.622812 -288.204656)
		(width 0.0889)
		(layer "In4.Cu")
		(net "M_J_CPU0_SB_DQ<21>")
	)
	(segment
		(start 392.524488 -287.963356)
		(end 393.52728 -287.963356)
		(width 0.0889)
		(layer "In4.Cu")
		(net "M_J_CPU0_SB_DQ<21>")
	)
	(segment
		(start 409.146502 -308.260242)
		(end 413.383984 -308.260242)
		(width 0.14478)
		(layer "In4.Cu")
		(net "M_J_CPU0_SB_DQ<21>")
	)
	(segment
		(start 388.393432 -288.18332)
		(end 388.401814 -288.178494)
		(width 0.0889)
		(layer "In4.Cu")
		(net "M_J_CPU0_SB_DQ<21>")
	)
	(segment
		(start 419.47846 -308.260242)
		(end 421.092122 -308.260242)
		(width 0.14478)
		(layer "In4.Cu")
		(net "M_J_CPU0_SB_DQ<21>")
	)
	(segment
		(start 379.933454 -288.18332)
		(end 379.941836 -288.178494)
		(width 0.0889)
		(layer "In4.Cu")
		(net "M_J_CPU0_SB_DQ<21>")
	)
	(segment
		(start 423.143934 -307.410358)
		(end 424.88739 -307.410358)
		(width 0.14478)
		(layer "In4.Cu")
		(net "M_J_CPU0_SB_DQ<21>")
	)
	(segment
		(start 380.873508 -288.18332)
		(end 380.88189 -288.178494)
		(width 0.0889)
		(layer "In4.Cu")
		(net "M_J_CPU0_SB_DQ<21>")
	)
	(segment
		(start 389.333486 -288.18332)
		(end 389.341868 -288.178494)
		(width 0.0889)
		(layer "In4.Cu")
		(net "M_J_CPU0_SB_DQ<21>")
	)
	(segment
		(start 421.092122 -308.260242)
		(end 423.143934 -307.410358)
		(width 0.14478)
		(layer "In4.Cu")
		(net "M_J_CPU0_SB_DQ<21>")
	)
	(segment
		(start 428.493936 -308.259988)
		(end 430.545748 -307.410104)
		(width 0.14478)
		(layer "In4.Cu")
		(net "M_J_CPU0_SB_DQ<21>")
	)
	(segment
		(start 395.806422 -290.11753)
		(end 399.117058 -293.428166)
		(width 0.14478)
		(layer "In4.Cu")
		(net "M_J_CPU0_SB_DQ<21>")
	)
	(segment
		(start 399.117058 -299.867574)
		(end 401.88642 -302.636936)
		(width 0.14478)
		(layer "In4.Cu")
		(net "M_J_CPU0_SB_DQ<21>")
	)
	(segment
		(start 436.96382 -307.410104)
		(end 439.100214 -307.835046)
		(width 0.14478)
		(layer "In4.Cu")
		(net "M_J_CPU0_SB_DQ<21>")
	)
	(segment
		(start 379.754892 -287.856168)
		(end 379.600714 -288.121598)
		(width 0.0889)
		(layer "In4.Cu")
		(net "M_J_CPU0_SB_DQ<21>")
	)
	(segment
		(start 417.426648 -307.410358)
		(end 419.47846 -308.260242)
		(width 0.14478)
		(layer "In4.Cu")
		(net "M_J_CPU0_SB_DQ<21>")
	)
	(segment
		(start 383.693416 -288.18332)
		(end 383.701798 -288.178494)
		(width 0.0889)
		(layer "In4.Cu")
		(net "M_J_CPU0_SB_DQ<21>")
	)
	(segment
		(start 381.447802 -288.178494)
		(end 381.456184 -288.18332)
		(width 0.0889)
		(layer "In4.Cu")
		(net "M_J_CPU0_SB_DQ<21>")
	)
	(segment
		(start 401.88642 -302.636936)
		(end 402.980652 -302.636936)
		(width 0.14478)
		(layer "In4.Cu")
		(net "M_J_CPU0_SB_DQ<21>")
	)
	(segment
		(start 424.88739 -307.410358)
		(end 426.938694 -308.259988)
		(width 0.14478)
		(layer "In4.Cu")
		(net "M_J_CPU0_SB_DQ<21>")
	)
	(segment
		(start 392.401044 -288.0868)
		(end 392.524488 -287.963356)
		(width 0.0889)
		(layer "In4.Cu")
		(net "M_J_CPU0_SB_DQ<21>")
	)
	(segment
		(start 415.435796 -307.410358)
		(end 417.426648 -307.410358)
		(width 0.14478)
		(layer "In4.Cu")
		(net "M_J_CPU0_SB_DQ<21>")
	)
	(segment
		(start 426.938694 -308.259988)
		(end 428.493936 -308.259988)
		(width 0.14478)
		(layer "In4.Cu")
		(net "M_J_CPU0_SB_DQ<21>")
	)
	(segment
		(start 395.059154 -289.84067)
		(end 395.529562 -289.84067)
		(width 0.0889)
		(layer "In4.Cu")
		(net "M_J_CPU0_SB_DQ<21>")
	)
	(segment
		(start 394.220954 -289.00247)
		(end 395.059154 -289.84067)
		(width 0.0889)
		(layer "In4.Cu")
		(net "M_J_CPU0_SB_DQ<21>")
	)
	(segment
		(start 385.207764 -288.178494)
		(end 385.216146 -288.18332)
		(width 0.0889)
		(layer "In4.Cu")
		(net "M_J_CPU0_SB_DQ<21>")
	)
	(segment
		(start 393.52728 -287.963356)
		(end 394.220954 -288.65703)
		(width 0.0889)
		(layer "In4.Cu")
		(net "M_J_CPU0_SB_DQ<21>")
	)
	(segment
		(start 386.147818 -288.178494)
		(end 386.1562 -288.18332)
		(width 0.0889)
		(layer "In4.Cu")
		(net "M_J_CPU0_SB_DQ<21>")
	)
	(segment
		(start 399.117058 -293.428166)
		(end 399.117058 -299.867574)
		(width 0.14478)
		(layer "In4.Cu")
		(net "M_J_CPU0_SB_DQ<21>")
	)
	(segment
		(start 408.220418 -307.876702)
		(end 409.146502 -308.260242)
		(width 0.14478)
		(layer "In4.Cu")
		(net "M_J_CPU0_SB_DQ<21>")
	)
	(segment
		(start 413.383984 -308.260242)
		(end 415.435796 -307.410358)
		(width 0.14478)
		(layer "In4.Cu")
		(net "M_J_CPU0_SB_DQ<21>")
	)
	(segment
		(start 389.90778 -288.178494)
		(end 389.916162 -288.18332)
		(width 0.0889)
		(layer "In4.Cu")
		(net "M_J_CPU0_SB_DQ<21>")
	)
	(segment
		(start 430.545748 -307.410104)
		(end 436.96382 -307.410104)
		(width 0.14478)
		(layer "In4.Cu")
		(net "M_J_CPU0_SB_DQ<21>")
	)
	(arc
		(start 379.622812 -288.204656)
		(mid 379.780463 -288.227968)
		(end 379.933454 -288.18332)
		(width 0.0889)
		(layer "In4.Cu")
		(net "M_J_CPU0_SB_DQ<21>")
	)
	(arc
		(start 386.52196 -288.178494)
		(mid 386.804916 -288.102317)
		(end 387.087872 -288.178494)
		(width 0.0889)
		(layer "In4.Cu")
		(net "M_J_CPU0_SB_DQ<21>")
	)
	(arc
		(start 388.967726 -288.178494)
		(mid 389.149977 -288.228878)
		(end 389.333486 -288.18332)
		(width 0.0889)
		(layer "In4.Cu")
		(net "M_J_CPU0_SB_DQ<21>")
	)
	(arc
		(start 390.847834 -288.178494)
		(mid 391.034778 -288.228783)
		(end 391.221722 -288.178494)
		(width 0.0889)
		(layer "In4.Cu")
		(net "M_J_CPU0_SB_DQ<21>")
	)
	(arc
		(start 382.387856 -288.178494)
		(mid 382.5748 -288.228783)
		(end 382.761744 -288.178494)
		(width 0.0889)
		(layer "In4.Cu")
		(net "M_J_CPU0_SB_DQ<21>")
	)
	(arc
		(start 383.701798 -288.178494)
		(mid 383.984754 -288.102317)
		(end 384.26771 -288.178494)
		(width 0.0889)
		(layer "In4.Cu")
		(net "M_J_CPU0_SB_DQ<21>")
	)
	(arc
		(start 381.456184 -288.18332)
		(mid 381.639692 -288.228845)
		(end 381.821944 -288.178494)
		(width 0.0889)
		(layer "In4.Cu")
		(net "M_J_CPU0_SB_DQ<21>")
	)
	(arc
		(start 391.787634 -288.178494)
		(mid 391.87787 -288.216296)
		(end 391.974832 -288.229294)
		(width 0.0889)
		(layer "In4.Cu")
		(net "M_J_CPU0_SB_DQ<21>")
	)
	(arc
		(start 388.401814 -288.178494)
		(mid 388.68477 -288.102317)
		(end 388.967726 -288.178494)
		(width 0.0889)
		(layer "In4.Cu")
		(net "M_J_CPU0_SB_DQ<21>")
	)
	(arc
		(start 382.761744 -288.178494)
		(mid 383.0447 -288.102317)
		(end 383.327656 -288.178494)
		(width 0.0889)
		(layer "In4.Cu")
		(net "M_J_CPU0_SB_DQ<21>")
	)
	(arc
		(start 386.1562 -288.18332)
		(mid 386.339708 -288.228845)
		(end 386.52196 -288.178494)
		(width 0.0889)
		(layer "In4.Cu")
		(net "M_J_CPU0_SB_DQ<21>")
	)
	(arc
		(start 387.087872 -288.178494)
		(mid 387.274816 -288.228783)
		(end 387.46176 -288.178494)
		(width 0.0889)
		(layer "In4.Cu")
		(net "M_J_CPU0_SB_DQ<21>")
	)
	(arc
		(start 384.26771 -288.178494)
		(mid 384.449961 -288.228878)
		(end 384.63347 -288.18332)
		(width 0.0889)
		(layer "In4.Cu")
		(net "M_J_CPU0_SB_DQ<21>")
	)
	(arc
		(start 387.46176 -288.178494)
		(mid 387.744716 -288.102317)
		(end 388.027672 -288.178494)
		(width 0.0889)
		(layer "In4.Cu")
		(net "M_J_CPU0_SB_DQ<21>")
	)
	(arc
		(start 389.916162 -288.18332)
		(mid 390.09967 -288.228845)
		(end 390.281922 -288.178494)
		(width 0.0889)
		(layer "In4.Cu")
		(net "M_J_CPU0_SB_DQ<21>")
	)
	(arc
		(start 380.507748 -288.178494)
		(mid 380.689999 -288.228878)
		(end 380.873508 -288.18332)
		(width 0.0889)
		(layer "In4.Cu")
		(net "M_J_CPU0_SB_DQ<21>")
	)
	(arc
		(start 385.581906 -288.178494)
		(mid 385.864862 -288.102317)
		(end 386.147818 -288.178494)
		(width 0.0889)
		(layer "In4.Cu")
		(net "M_J_CPU0_SB_DQ<21>")
	)
	(arc
		(start 390.281922 -288.178494)
		(mid 390.564878 -288.102317)
		(end 390.847834 -288.178494)
		(width 0.0889)
		(layer "In4.Cu")
		(net "M_J_CPU0_SB_DQ<21>")
	)
	(arc
		(start 381.821944 -288.178494)
		(mid 382.1049 -288.102317)
		(end 382.387856 -288.178494)
		(width 0.0889)
		(layer "In4.Cu")
		(net "M_J_CPU0_SB_DQ<21>")
	)
	(arc
		(start 384.641852 -288.178494)
		(mid 384.924808 -288.102317)
		(end 385.207764 -288.178494)
		(width 0.0889)
		(layer "In4.Cu")
		(net "M_J_CPU0_SB_DQ<21>")
	)
	(arc
		(start 389.341868 -288.178494)
		(mid 389.624824 -288.102317)
		(end 389.90778 -288.178494)
		(width 0.0889)
		(layer "In4.Cu")
		(net "M_J_CPU0_SB_DQ<21>")
	)
	(arc
		(start 388.027672 -288.178494)
		(mid 388.209923 -288.228878)
		(end 388.393432 -288.18332)
		(width 0.0889)
		(layer "In4.Cu")
		(net "M_J_CPU0_SB_DQ<21>")
	)
	(arc
		(start 391.974832 -288.229294)
		(mid 392.199532 -288.192727)
		(end 392.401044 -288.0868)
		(width 0.0889)
		(layer "In4.Cu")
		(net "M_J_CPU0_SB_DQ<21>")
	)
	(arc
		(start 379.941836 -288.178494)
		(mid 380.224792 -288.102317)
		(end 380.507748 -288.178494)
		(width 0.0889)
		(layer "In4.Cu")
		(net "M_J_CPU0_SB_DQ<21>")
	)
	(arc
		(start 383.327656 -288.178494)
		(mid 383.509907 -288.228878)
		(end 383.693416 -288.18332)
		(width 0.0889)
		(layer "In4.Cu")
		(net "M_J_CPU0_SB_DQ<21>")
	)
	(arc
		(start 380.88189 -288.178494)
		(mid 381.164846 -288.102317)
		(end 381.447802 -288.178494)
		(width 0.0889)
		(layer "In4.Cu")
		(net "M_J_CPU0_SB_DQ<21>")
	)
	(arc
		(start 385.216146 -288.18332)
		(mid 385.399654 -288.228845)
		(end 385.581906 -288.178494)
		(width 0.0889)
		(layer "In4.Cu")
		(net "M_J_CPU0_SB_DQ<21>")
	)
	(arc
		(start 391.221722 -288.178494)
		(mid 391.504678 -288.102317)
		(end 391.787634 -288.178494)
		(width 0.0889)
		(layer "In4.Cu")
		(net "M_J_CPU0_SB_DQ<21>")
	)
	(segment
		(start 380.697994 -286.780224)
		(end 381.164846 -287.045908)
		(width 0.10668)
		(layer "F.Cu")
		(net "M_J_CPU0_SB_DQ<20>")
	)
	(segment
		(start 414.183068 -306.56022)
		(end 415.032952 -305.710336)
		(width 0.14478)
		(layer "In4.Cu")
		(net "M_J_CPU0_SB_DQ<20>")
	)
	(segment
		(start 386.043424 -287.373314)
		(end 386.051806 -287.368488)
		(width 0.0889)
		(layer "In4.Cu")
		(net "M_J_CPU0_SB_DQ<20>")
	)
	(segment
		(start 422.567608 -305.719734)
		(end 425.390564 -305.719734)
		(width 0.14478)
		(layer "In4.Cu")
		(net "M_J_CPU0_SB_DQ<20>")
	)
	(segment
		(start 393.090908 -287.41751)
		(end 393.763754 -287.41751)
		(width 0.0889)
		(layer "In4.Cu")
		(net "M_J_CPU0_SB_DQ<20>")
	)
	(segment
		(start 386.983478 -287.373314)
		(end 386.99186 -287.368488)
		(width 0.0889)
		(layer "In4.Cu")
		(net "M_J_CPU0_SB_DQ<20>")
	)
	(segment
		(start 395.057884 -288.07537)
		(end 395.701266 -288.718752)
		(width 0.0889)
		(layer "In4.Cu")
		(net "M_J_CPU0_SB_DQ<20>")
	)
	(segment
		(start 430.048416 -305.719734)
		(end 437.31053 -305.719734)
		(width 0.14478)
		(layer "In4.Cu")
		(net "M_J_CPU0_SB_DQ<20>")
	)
	(segment
		(start 437.861964 -306.513992)
		(end 438.023508 -306.352448)
		(width 0.14478)
		(layer "In4.Cu")
		(net "M_J_CPU0_SB_DQ<20>")
	)
	(segment
		(start 417.690808 -305.710336)
		(end 418.550344 -306.569872)
		(width 0.14478)
		(layer "In4.Cu")
		(net "M_J_CPU0_SB_DQ<20>")
	)
	(segment
		(start 382.283462 -287.373314)
		(end 382.291844 -287.368488)
		(width 0.0889)
		(layer "In4.Cu")
		(net "M_J_CPU0_SB_DQ<20>")
	)
	(segment
		(start 425.390564 -305.719734)
		(end 426.240448 -306.569618)
		(width 0.14478)
		(layer "In4.Cu")
		(net "M_J_CPU0_SB_DQ<20>")
	)
	(segment
		(start 421.71747 -306.569872)
		(end 422.567608 -305.719734)
		(width 0.14478)
		(layer "In4.Cu")
		(net "M_J_CPU0_SB_DQ<20>")
	)
	(segment
		(start 391.317734 -287.368488)
		(end 391.326116 -287.373314)
		(width 0.0889)
		(layer "In4.Cu")
		(net "M_J_CPU0_SB_DQ<20>")
	)
	(segment
		(start 438.023508 -306.352448)
		(end 438.023508 -305.881278)
		(width 0.14478)
		(layer "In4.Cu")
		(net "M_J_CPU0_SB_DQ<20>")
	)
	(segment
		(start 437.633618 -306.513992)
		(end 437.861964 -306.513992)
		(width 0.14478)
		(layer "In4.Cu")
		(net "M_J_CPU0_SB_DQ<20>")
	)
	(segment
		(start 429.198532 -306.569618)
		(end 430.048416 -305.719734)
		(width 0.14478)
		(layer "In4.Cu")
		(net "M_J_CPU0_SB_DQ<20>")
	)
	(segment
		(start 382.857756 -287.368488)
		(end 382.866138 -287.373314)
		(width 0.0889)
		(layer "In4.Cu")
		(net "M_J_CPU0_SB_DQ<20>")
	)
	(segment
		(start 437.472074 -305.881278)
		(end 437.472074 -306.352448)
		(width 0.14478)
		(layer "In4.Cu")
		(net "M_J_CPU0_SB_DQ<20>")
	)
	(segment
		(start 391.974578 -287.292288)
		(end 392.773662 -287.292288)
		(width 0.0889)
		(layer "In4.Cu")
		(net "M_J_CPU0_SB_DQ<20>")
	)
	(segment
		(start 400.016218 -293.033704)
		(end 400.016218 -298.400216)
		(width 0.14478)
		(layer "In4.Cu")
		(net "M_J_CPU0_SB_DQ<20>")
	)
	(segment
		(start 381.164846 -287.045908)
		(end 381.010922 -287.311338)
		(width 0.0889)
		(layer "In4.Cu")
		(net "M_J_CPU0_SB_DQ<20>")
	)
	(segment
		(start 387.557772 -287.368488)
		(end 387.566154 -287.373314)
		(width 0.0889)
		(layer "In4.Cu")
		(net "M_J_CPU0_SB_DQ<20>")
	)
	(segment
		(start 415.032952 -305.710336)
		(end 417.690808 -305.710336)
		(width 0.14478)
		(layer "In4.Cu")
		(net "M_J_CPU0_SB_DQ<20>")
	)
	(segment
		(start 418.550344 -306.569872)
		(end 421.71747 -306.569872)
		(width 0.14478)
		(layer "In4.Cu")
		(net "M_J_CPU0_SB_DQ<20>")
	)
	(segment
		(start 383.79781 -287.368488)
		(end 383.806192 -287.373314)
		(width 0.0889)
		(layer "In4.Cu")
		(net "M_J_CPU0_SB_DQ<20>")
	)
	(segment
		(start 438.023508 -305.881278)
		(end 438.185052 -305.719734)
		(width 0.14478)
		(layer "In4.Cu")
		(net "M_J_CPU0_SB_DQ<20>")
	)
	(segment
		(start 395.701266 -288.718752)
		(end 400.016218 -293.033704)
		(width 0.14478)
		(layer "In4.Cu")
		(net "M_J_CPU0_SB_DQ<20>")
	)
	(segment
		(start 388.497826 -287.368488)
		(end 388.506208 -287.373314)
		(width 0.0889)
		(layer "In4.Cu")
		(net "M_J_CPU0_SB_DQ<20>")
	)
	(segment
		(start 437.472074 -306.352448)
		(end 437.633618 -306.513992)
		(width 0.14478)
		(layer "In4.Cu")
		(net "M_J_CPU0_SB_DQ<20>")
	)
	(segment
		(start 394.421614 -288.07537)
		(end 395.057884 -288.07537)
		(width 0.0889)
		(layer "In4.Cu")
		(net "M_J_CPU0_SB_DQ<20>")
	)
	(segment
		(start 390.74344 -287.373314)
		(end 390.751822 -287.368488)
		(width 0.0889)
		(layer "In4.Cu")
		(net "M_J_CPU0_SB_DQ<20>")
	)
	(segment
		(start 400.016218 -298.400216)
		(end 408.176222 -306.56022)
		(width 0.14478)
		(layer "In4.Cu")
		(net "M_J_CPU0_SB_DQ<20>")
	)
	(segment
		(start 408.176222 -306.56022)
		(end 414.183068 -306.56022)
		(width 0.14478)
		(layer "In4.Cu")
		(net "M_J_CPU0_SB_DQ<20>")
	)
	(segment
		(start 426.240448 -306.569618)
		(end 429.198532 -306.569618)
		(width 0.14478)
		(layer "In4.Cu")
		(net "M_J_CPU0_SB_DQ<20>")
	)
	(segment
		(start 393.763754 -287.41751)
		(end 394.421614 -288.07537)
		(width 0.0889)
		(layer "In4.Cu")
		(net "M_J_CPU0_SB_DQ<20>")
	)
	(segment
		(start 438.185052 -305.719734)
		(end 438.684924 -305.719734)
		(width 0.14478)
		(layer "In4.Cu")
		(net "M_J_CPU0_SB_DQ<20>")
	)
	(segment
		(start 437.31053 -305.719734)
		(end 437.472074 -305.881278)
		(width 0.14478)
		(layer "In4.Cu")
		(net "M_J_CPU0_SB_DQ<20>")
	)
	(segment
		(start 438.684924 -305.719734)
		(end 439.100214 -306.135024)
		(width 0.14478)
		(layer "In4.Cu")
		(net "M_J_CPU0_SB_DQ<20>")
	)
	(segment
		(start 392.773662 -287.292288)
		(end 393.090908 -287.41751)
		(width 0.0889)
		(layer "In4.Cu")
		(net "M_J_CPU0_SB_DQ<20>")
	)
	(segment
		(start 381.010922 -287.311338)
		(end 381.033274 -287.39465)
		(width 0.0889)
		(layer "In4.Cu")
		(net "M_J_CPU0_SB_DQ<20>")
	)
	(arc
		(start 385.111752 -287.368488)
		(mid 385.394708 -287.292345)
		(end 385.677664 -287.368488)
		(width 0.0889)
		(layer "In4.Cu")
		(net "M_J_CPU0_SB_DQ<20>")
	)
	(arc
		(start 389.43788 -287.368488)
		(mid 389.624824 -287.418743)
		(end 389.811768 -287.368488)
		(width 0.0889)
		(layer "In4.Cu")
		(net "M_J_CPU0_SB_DQ<20>")
	)
	(arc
		(start 391.326116 -287.373314)
		(mid 391.509624 -287.418808)
		(end 391.691876 -287.368488)
		(width 0.0889)
		(layer "In4.Cu")
		(net "M_J_CPU0_SB_DQ<20>")
	)
	(arc
		(start 386.051806 -287.368488)
		(mid 386.334762 -287.292345)
		(end 386.617718 -287.368488)
		(width 0.0889)
		(layer "In4.Cu")
		(net "M_J_CPU0_SB_DQ<20>")
	)
	(arc
		(start 388.506208 -287.373314)
		(mid 388.689716 -287.418808)
		(end 388.871968 -287.368488)
		(width 0.0889)
		(layer "In4.Cu")
		(net "M_J_CPU0_SB_DQ<20>")
	)
	(arc
		(start 383.231898 -287.368488)
		(mid 383.514854 -287.292345)
		(end 383.79781 -287.368488)
		(width 0.0889)
		(layer "In4.Cu")
		(net "M_J_CPU0_SB_DQ<20>")
	)
	(arc
		(start 381.917702 -287.368488)
		(mid 382.099953 -287.418838)
		(end 382.283462 -287.373314)
		(width 0.0889)
		(layer "In4.Cu")
		(net "M_J_CPU0_SB_DQ<20>")
	)
	(arc
		(start 386.617718 -287.368488)
		(mid 386.799969 -287.418838)
		(end 386.983478 -287.373314)
		(width 0.0889)
		(layer "In4.Cu")
		(net "M_J_CPU0_SB_DQ<20>")
	)
	(arc
		(start 390.751822 -287.368488)
		(mid 391.034778 -287.292345)
		(end 391.317734 -287.368488)
		(width 0.0889)
		(layer "In4.Cu")
		(net "M_J_CPU0_SB_DQ<20>")
	)
	(arc
		(start 382.866138 -287.373314)
		(mid 383.049646 -287.418808)
		(end 383.231898 -287.368488)
		(width 0.0889)
		(layer "In4.Cu")
		(net "M_J_CPU0_SB_DQ<20>")
	)
	(arc
		(start 391.691876 -287.368488)
		(mid 391.79821 -287.320724)
		(end 391.912094 -287.295844)
		(width 0.0889)
		(layer "In4.Cu")
		(net "M_J_CPU0_SB_DQ<20>")
	)
	(arc
		(start 391.912094 -287.295844)
		(mid 391.943287 -287.293196)
		(end 391.974578 -287.292288)
		(width 0.0889)
		(layer "In4.Cu")
		(net "M_J_CPU0_SB_DQ<20>")
	)
	(arc
		(start 381.033274 -287.39465)
		(mid 381.195463 -287.417385)
		(end 381.35179 -287.368488)
		(width 0.0889)
		(layer "In4.Cu")
		(net "M_J_CPU0_SB_DQ<20>")
	)
	(arc
		(start 388.871968 -287.368488)
		(mid 389.154924 -287.292345)
		(end 389.43788 -287.368488)
		(width 0.0889)
		(layer "In4.Cu")
		(net "M_J_CPU0_SB_DQ<20>")
	)
	(arc
		(start 386.99186 -287.368488)
		(mid 387.274816 -287.292345)
		(end 387.557772 -287.368488)
		(width 0.0889)
		(layer "In4.Cu")
		(net "M_J_CPU0_SB_DQ<20>")
	)
	(arc
		(start 390.37768 -287.368488)
		(mid 390.559931 -287.418838)
		(end 390.74344 -287.373314)
		(width 0.0889)
		(layer "In4.Cu")
		(net "M_J_CPU0_SB_DQ<20>")
	)
	(arc
		(start 383.806192 -287.373314)
		(mid 383.9897 -287.418808)
		(end 384.171952 -287.368488)
		(width 0.0889)
		(layer "In4.Cu")
		(net "M_J_CPU0_SB_DQ<20>")
	)
	(arc
		(start 384.171952 -287.368488)
		(mid 384.454908 -287.292345)
		(end 384.737864 -287.368488)
		(width 0.0889)
		(layer "In4.Cu")
		(net "M_J_CPU0_SB_DQ<20>")
	)
	(arc
		(start 384.737864 -287.368488)
		(mid 384.924808 -287.418743)
		(end 385.111752 -287.368488)
		(width 0.0889)
		(layer "In4.Cu")
		(net "M_J_CPU0_SB_DQ<20>")
	)
	(arc
		(start 387.566154 -287.373314)
		(mid 387.749662 -287.418808)
		(end 387.931914 -287.368488)
		(width 0.0889)
		(layer "In4.Cu")
		(net "M_J_CPU0_SB_DQ<20>")
	)
	(arc
		(start 381.35179 -287.368488)
		(mid 381.634746 -287.292345)
		(end 381.917702 -287.368488)
		(width 0.0889)
		(layer "In4.Cu")
		(net "M_J_CPU0_SB_DQ<20>")
	)
	(arc
		(start 382.291844 -287.368488)
		(mid 382.5748 -287.292345)
		(end 382.857756 -287.368488)
		(width 0.0889)
		(layer "In4.Cu")
		(net "M_J_CPU0_SB_DQ<20>")
	)
	(arc
		(start 387.931914 -287.368488)
		(mid 388.21487 -287.292345)
		(end 388.497826 -287.368488)
		(width 0.0889)
		(layer "In4.Cu")
		(net "M_J_CPU0_SB_DQ<20>")
	)
	(arc
		(start 389.811768 -287.368488)
		(mid 390.094724 -287.292345)
		(end 390.37768 -287.368488)
		(width 0.0889)
		(layer "In4.Cu")
		(net "M_J_CPU0_SB_DQ<20>")
	)
	(arc
		(start 385.677664 -287.368488)
		(mid 385.859915 -287.418838)
		(end 386.043424 -287.373314)
		(width 0.0889)
		(layer "In4.Cu")
		(net "M_J_CPU0_SB_DQ<20>")
	)
	(segment
		(start 379.28804 -274.630134)
		(end 379.754892 -274.896072)
		(width 0.10668)
		(layer "F.Cu")
		(net "M_J_CPU0_SB_DQ<1>")
	)
	(segment
		(start 419.522402 -283.61005)
		(end 420.923974 -283.61005)
		(width 0.14478)
		(layer "In4.Cu")
		(net "M_J_CPU0_SB_DQ<1>")
	)
	(segment
		(start 394.683234 -274.00885)
		(end 395.277594 -274.00885)
		(width 0.0889)
		(layer "In4.Cu")
		(net "M_J_CPU0_SB_DQ<1>")
	)
	(segment
		(start 379.933454 -275.223478)
		(end 379.941836 -275.218652)
		(width 0.0889)
		(layer "In4.Cu")
		(net "M_J_CPU0_SB_DQ<1>")
	)
	(segment
		(start 424.934888 -282.760166)
		(end 426.9867 -283.61005)
		(width 0.14478)
		(layer "In4.Cu")
		(net "M_J_CPU0_SB_DQ<1>")
	)
	(segment
		(start 395.437614 -273.84883)
		(end 396.000986 -273.84883)
		(width 0.0889)
		(layer "In4.Cu")
		(net "M_J_CPU0_SB_DQ<1>")
	)
	(segment
		(start 379.754892 -274.896072)
		(end 379.600714 -275.161502)
		(width 0.0889)
		(layer "In4.Cu")
		(net "M_J_CPU0_SB_DQ<1>")
	)
	(segment
		(start 430.37506 -282.760166)
		(end 436.96382 -282.760166)
		(width 0.14478)
		(layer "In4.Cu")
		(net "M_J_CPU0_SB_DQ<1>")
	)
	(segment
		(start 417.47059 -282.760166)
		(end 419.522402 -283.61005)
		(width 0.14478)
		(layer "In4.Cu")
		(net "M_J_CPU0_SB_DQ<1>")
	)
	(segment
		(start 386.147818 -275.218652)
		(end 386.1562 -275.223478)
		(width 0.0889)
		(layer "In4.Cu")
		(net "M_J_CPU0_SB_DQ<1>")
	)
	(segment
		(start 388.393432 -275.223478)
		(end 388.401814 -275.218652)
		(width 0.0889)
		(layer "In4.Cu")
		(net "M_J_CPU0_SB_DQ<1>")
	)
	(segment
		(start 426.9867 -283.61005)
		(end 428.323248 -283.61005)
		(width 0.14478)
		(layer "In4.Cu")
		(net "M_J_CPU0_SB_DQ<1>")
	)
	(segment
		(start 379.600714 -275.161502)
		(end 379.623066 -275.244814)
		(width 0.0889)
		(layer "In4.Cu")
		(net "M_J_CPU0_SB_DQ<1>")
	)
	(segment
		(start 393.764516 -274.927568)
		(end 394.683234 -274.00885)
		(width 0.0889)
		(layer "In4.Cu")
		(net "M_J_CPU0_SB_DQ<1>")
	)
	(segment
		(start 389.90778 -275.218652)
		(end 389.916162 -275.223478)
		(width 0.0889)
		(layer "In4.Cu")
		(net "M_J_CPU0_SB_DQ<1>")
	)
	(segment
		(start 414.765744 -282.760166)
		(end 417.47059 -282.760166)
		(width 0.14478)
		(layer "In4.Cu")
		(net "M_J_CPU0_SB_DQ<1>")
	)
	(segment
		(start 402.106384 -273.84883)
		(end 411.867604 -283.61005)
		(width 0.14478)
		(layer "In4.Cu")
		(net "M_J_CPU0_SB_DQ<1>")
	)
	(segment
		(start 389.333486 -275.223478)
		(end 389.341868 -275.218652)
		(width 0.0889)
		(layer "In4.Cu")
		(net "M_J_CPU0_SB_DQ<1>")
	)
	(segment
		(start 411.867604 -283.61005)
		(end 413.91586 -283.61005)
		(width 0.14478)
		(layer "In4.Cu")
		(net "M_J_CPU0_SB_DQ<1>")
	)
	(segment
		(start 395.277594 -274.00885)
		(end 395.437614 -273.84883)
		(width 0.0889)
		(layer "In4.Cu")
		(net "M_J_CPU0_SB_DQ<1>")
	)
	(segment
		(start 420.923974 -283.61005)
		(end 422.975786 -282.760166)
		(width 0.14478)
		(layer "In4.Cu")
		(net "M_J_CPU0_SB_DQ<1>")
	)
	(segment
		(start 385.207764 -275.218652)
		(end 385.216146 -275.223478)
		(width 0.0889)
		(layer "In4.Cu")
		(net "M_J_CPU0_SB_DQ<1>")
	)
	(segment
		(start 428.323248 -283.61005)
		(end 430.37506 -282.760166)
		(width 0.14478)
		(layer "In4.Cu")
		(net "M_J_CPU0_SB_DQ<1>")
	)
	(segment
		(start 422.975786 -282.760166)
		(end 424.934888 -282.760166)
		(width 0.14478)
		(layer "In4.Cu")
		(net "M_J_CPU0_SB_DQ<1>")
	)
	(segment
		(start 393.369038 -275.114512)
		(end 393.6746 -274.987766)
		(width 0.0889)
		(layer "In4.Cu")
		(net "M_J_CPU0_SB_DQ<1>")
	)
	(segment
		(start 383.693416 -275.223478)
		(end 383.701798 -275.218652)
		(width 0.0889)
		(layer "In4.Cu")
		(net "M_J_CPU0_SB_DQ<1>")
	)
	(segment
		(start 396.000986 -273.84883)
		(end 402.106384 -273.84883)
		(width 0.14478)
		(layer "In4.Cu")
		(net "M_J_CPU0_SB_DQ<1>")
	)
	(segment
		(start 391.787634 -275.218652)
		(end 391.796016 -275.223478)
		(width 0.0889)
		(layer "In4.Cu")
		(net "M_J_CPU0_SB_DQ<1>")
	)
	(segment
		(start 413.91586 -283.61005)
		(end 414.765744 -282.760166)
		(width 0.14478)
		(layer "In4.Cu")
		(net "M_J_CPU0_SB_DQ<1>")
	)
	(segment
		(start 381.447802 -275.218652)
		(end 381.456184 -275.223478)
		(width 0.0889)
		(layer "In4.Cu")
		(net "M_J_CPU0_SB_DQ<1>")
	)
	(segment
		(start 384.63347 -275.223478)
		(end 384.641852 -275.218652)
		(width 0.0889)
		(layer "In4.Cu")
		(net "M_J_CPU0_SB_DQ<1>")
	)
	(segment
		(start 436.96382 -282.760166)
		(end 439.100214 -283.185108)
		(width 0.14478)
		(layer "In4.Cu")
		(net "M_J_CPU0_SB_DQ<1>")
	)
	(segment
		(start 392.718036 -275.212556)
		(end 392.72845 -275.218652)
		(width 0.0889)
		(layer "In4.Cu")
		(net "M_J_CPU0_SB_DQ<1>")
	)
	(segment
		(start 380.873508 -275.223478)
		(end 380.88189 -275.218652)
		(width 0.0889)
		(layer "In4.Cu")
		(net "M_J_CPU0_SB_DQ<1>")
	)
	(segment
		(start 393.6746 -274.987766)
		(end 393.764516 -274.927568)
		(width 0.0889)
		(layer "In4.Cu")
		(net "M_J_CPU0_SB_DQ<1>")
	)
	(arc
		(start 389.341868 -275.218652)
		(mid 389.624824 -275.142475)
		(end 389.90778 -275.218652)
		(width 0.0889)
		(layer "In4.Cu")
		(net "M_J_CPU0_SB_DQ<1>")
	)
	(arc
		(start 382.761744 -275.218652)
		(mid 383.0447 -275.142475)
		(end 383.327656 -275.218652)
		(width 0.0889)
		(layer "In4.Cu")
		(net "M_J_CPU0_SB_DQ<1>")
	)
	(arc
		(start 384.26771 -275.218652)
		(mid 384.449961 -275.269002)
		(end 384.63347 -275.223478)
		(width 0.0889)
		(layer "In4.Cu")
		(net "M_J_CPU0_SB_DQ<1>")
	)
	(arc
		(start 382.387856 -275.218652)
		(mid 382.5748 -275.268907)
		(end 382.761744 -275.218652)
		(width 0.0889)
		(layer "In4.Cu")
		(net "M_J_CPU0_SB_DQ<1>")
	)
	(arc
		(start 393.256008 -275.15058)
		(mid 393.313536 -275.13572)
		(end 393.369038 -275.114512)
		(width 0.0889)
		(layer "In4.Cu")
		(net "M_J_CPU0_SB_DQ<1>")
	)
	(arc
		(start 388.401814 -275.218652)
		(mid 388.68477 -275.142475)
		(end 388.967726 -275.218652)
		(width 0.0889)
		(layer "In4.Cu")
		(net "M_J_CPU0_SB_DQ<1>")
	)
	(arc
		(start 386.52196 -275.218652)
		(mid 386.804916 -275.142475)
		(end 387.087872 -275.218652)
		(width 0.0889)
		(layer "In4.Cu")
		(net "M_J_CPU0_SB_DQ<1>")
	)
	(arc
		(start 381.456184 -275.223478)
		(mid 381.639692 -275.268972)
		(end 381.821944 -275.218652)
		(width 0.0889)
		(layer "In4.Cu")
		(net "M_J_CPU0_SB_DQ<1>")
	)
	(arc
		(start 391.796016 -275.223478)
		(mid 391.979778 -275.269094)
		(end 392.162284 -275.218652)
		(width 0.0889)
		(layer "In4.Cu")
		(net "M_J_CPU0_SB_DQ<1>")
	)
	(arc
		(start 390.281922 -275.218652)
		(mid 390.564878 -275.142475)
		(end 390.847834 -275.218652)
		(width 0.0889)
		(layer "In4.Cu")
		(net "M_J_CPU0_SB_DQ<1>")
	)
	(arc
		(start 388.027672 -275.218652)
		(mid 388.209923 -275.269002)
		(end 388.393432 -275.223478)
		(width 0.0889)
		(layer "In4.Cu")
		(net "M_J_CPU0_SB_DQ<1>")
	)
	(arc
		(start 391.221722 -275.218652)
		(mid 391.504678 -275.142475)
		(end 391.787634 -275.218652)
		(width 0.0889)
		(layer "In4.Cu")
		(net "M_J_CPU0_SB_DQ<1>")
	)
	(arc
		(start 379.941836 -275.218652)
		(mid 380.224792 -275.142475)
		(end 380.507748 -275.218652)
		(width 0.0889)
		(layer "In4.Cu")
		(net "M_J_CPU0_SB_DQ<1>")
	)
	(arc
		(start 392.72845 -275.218652)
		(mid 392.914402 -275.267604)
		(end 393.098782 -275.213064)
		(width 0.0889)
		(layer "In4.Cu")
		(net "M_J_CPU0_SB_DQ<1>")
	)
	(arc
		(start 384.641852 -275.218652)
		(mid 384.924808 -275.142475)
		(end 385.207764 -275.218652)
		(width 0.0889)
		(layer "In4.Cu")
		(net "M_J_CPU0_SB_DQ<1>")
	)
	(arc
		(start 388.967726 -275.218652)
		(mid 389.149977 -275.269002)
		(end 389.333486 -275.223478)
		(width 0.0889)
		(layer "In4.Cu")
		(net "M_J_CPU0_SB_DQ<1>")
	)
	(arc
		(start 386.1562 -275.223478)
		(mid 386.339708 -275.268972)
		(end 386.52196 -275.218652)
		(width 0.0889)
		(layer "In4.Cu")
		(net "M_J_CPU0_SB_DQ<1>")
	)
	(arc
		(start 385.216146 -275.223478)
		(mid 385.399654 -275.268972)
		(end 385.581906 -275.218652)
		(width 0.0889)
		(layer "In4.Cu")
		(net "M_J_CPU0_SB_DQ<1>")
	)
	(arc
		(start 380.507748 -275.218652)
		(mid 380.689999 -275.269002)
		(end 380.873508 -275.223478)
		(width 0.0889)
		(layer "In4.Cu")
		(net "M_J_CPU0_SB_DQ<1>")
	)
	(arc
		(start 390.847834 -275.218652)
		(mid 391.034778 -275.268907)
		(end 391.221722 -275.218652)
		(width 0.0889)
		(layer "In4.Cu")
		(net "M_J_CPU0_SB_DQ<1>")
	)
	(arc
		(start 385.581906 -275.218652)
		(mid 385.864862 -275.142475)
		(end 386.147818 -275.218652)
		(width 0.0889)
		(layer "In4.Cu")
		(net "M_J_CPU0_SB_DQ<1>")
	)
	(arc
		(start 380.88189 -275.218652)
		(mid 381.164846 -275.142475)
		(end 381.447802 -275.218652)
		(width 0.0889)
		(layer "In4.Cu")
		(net "M_J_CPU0_SB_DQ<1>")
	)
	(arc
		(start 383.327656 -275.218652)
		(mid 383.509907 -275.269002)
		(end 383.693416 -275.223478)
		(width 0.0889)
		(layer "In4.Cu")
		(net "M_J_CPU0_SB_DQ<1>")
	)
	(arc
		(start 387.087872 -275.218652)
		(mid 387.274816 -275.268907)
		(end 387.46176 -275.218652)
		(width 0.0889)
		(layer "In4.Cu")
		(net "M_J_CPU0_SB_DQ<1>")
	)
	(arc
		(start 381.821944 -275.218652)
		(mid 382.1049 -275.142475)
		(end 382.387856 -275.218652)
		(width 0.0889)
		(layer "In4.Cu")
		(net "M_J_CPU0_SB_DQ<1>")
	)
	(arc
		(start 387.46176 -275.218652)
		(mid 387.744716 -275.142475)
		(end 388.027672 -275.218652)
		(width 0.0889)
		(layer "In4.Cu")
		(net "M_J_CPU0_SB_DQ<1>")
	)
	(arc
		(start 379.623066 -275.244814)
		(mid 379.780576 -275.268012)
		(end 379.933454 -275.223478)
		(width 0.0889)
		(layer "In4.Cu")
		(net "M_J_CPU0_SB_DQ<1>")
	)
	(arc
		(start 383.701798 -275.218652)
		(mid 383.984754 -275.142475)
		(end 384.26771 -275.218652)
		(width 0.0889)
		(layer "In4.Cu")
		(net "M_J_CPU0_SB_DQ<1>")
	)
	(arc
		(start 389.916162 -275.223478)
		(mid 390.09967 -275.268972)
		(end 390.281922 -275.218652)
		(width 0.0889)
		(layer "In4.Cu")
		(net "M_J_CPU0_SB_DQ<1>")
	)
	(arc
		(start 392.162284 -275.218652)
		(mid 392.439351 -275.142381)
		(end 392.718036 -275.212556)
		(width 0.0889)
		(layer "In4.Cu")
		(net "M_J_CPU0_SB_DQ<1>")
	)
	(arc
		(start 393.098782 -275.213064)
		(mid 393.174546 -275.174648)
		(end 393.256008 -275.15058)
		(width 0.0889)
		(layer "In4.Cu")
		(net "M_J_CPU0_SB_DQ<1>")
	)
	(segment
		(start 378.817886 -285.160212)
		(end 379.284738 -285.42615)
		(width 0.10668)
		(layer "F.Cu")
		(net "M_J_CPU0_SB_DQ<19>")
	)
	(segment
		(start 390.74344 -285.098744)
		(end 390.751822 -285.10357)
		(width 0.0889)
		(layer "In4.Cu")
		(net "M_J_CPU0_SB_DQ<19>")
	)
	(segment
		(start 396.278354 -285.97733)
		(end 402.304758 -292.003734)
		(width 0.14478)
		(layer "In4.Cu")
		(net "M_J_CPU0_SB_DQ<19>")
	)
	(segment
		(start 405.351996 -300.49851)
		(end 405.580596 -300.49851)
		(width 0.14478)
		(layer "In4.Cu")
		(net "M_J_CPU0_SB_DQ<19>")
	)
	(segment
		(start 405.313896 -299.756322)
		(end 405.313896 -299.984922)
		(width 0.14478)
		(layer "In4.Cu")
		(net "M_J_CPU0_SB_DQ<19>")
	)
	(segment
		(start 405.580596 -300.49851)
		(end 405.70404 -300.375066)
		(width 0.14478)
		(layer "In4.Cu")
		(net "M_J_CPU0_SB_DQ<19>")
	)
	(segment
		(start 425.63415 -302.300386)
		(end 426.484034 -303.15027)
		(width 0.14478)
		(layer "In4.Cu")
		(net "M_J_CPU0_SB_DQ<19>")
	)
	(segment
		(start 402.304758 -292.003734)
		(end 402.304758 -296.747184)
		(width 0.14478)
		(layer "In4.Cu")
		(net "M_J_CPU0_SB_DQ<19>")
	)
	(segment
		(start 405.152352 -299.594778)
		(end 405.313896 -299.756322)
		(width 0.14478)
		(layer "In4.Cu")
		(net "M_J_CPU0_SB_DQ<19>")
	)
	(segment
		(start 407.141172 -302.059086)
		(end 407.264616 -301.935642)
		(width 0.14478)
		(layer "In4.Cu")
		(net "M_J_CPU0_SB_DQ<19>")
	)
	(segment
		(start 393.216384 -285.09341)
		(end 393.288012 -285.05023)
		(width 0.0889)
		(layer "In4.Cu")
		(net "M_J_CPU0_SB_DQ<19>")
	)
	(segment
		(start 405.313896 -299.984922)
		(end 405.190452 -300.108366)
		(width 0.14478)
		(layer "In4.Cu")
		(net "M_J_CPU0_SB_DQ<19>")
	)
	(segment
		(start 391.691876 -285.10357)
		(end 391.70229 -285.109666)
		(width 0.0889)
		(layer "In4.Cu")
		(net "M_J_CPU0_SB_DQ<19>")
	)
	(segment
		(start 393.192508 -285.107126)
		(end 393.198096 -285.103824)
		(width 0.0889)
		(layer "In4.Cu")
		(net "M_J_CPU0_SB_DQ<19>")
	)
	(segment
		(start 403.363176 -298.034202)
		(end 403.591776 -298.034202)
		(width 0.14478)
		(layer "In4.Cu")
		(net "M_J_CPU0_SB_DQ<19>")
	)
	(segment
		(start 379.284738 -285.42615)
		(end 379.438916 -285.16072)
		(width 0.0889)
		(layer "In4.Cu")
		(net "M_J_CPU0_SB_DQ<19>")
	)
	(segment
		(start 379.438916 -285.16072)
		(end 379.535182 -285.13532)
		(width 0.0889)
		(layer "In4.Cu")
		(net "M_J_CPU0_SB_DQ<19>")
	)
	(segment
		(start 406.874472 -301.316898)
		(end 406.874472 -301.545498)
		(width 0.14478)
		(layer "In4.Cu")
		(net "M_J_CPU0_SB_DQ<19>")
	)
	(segment
		(start 404.410164 -299.556678)
		(end 404.571708 -299.718222)
		(width 0.14478)
		(layer "In4.Cu")
		(net "M_J_CPU0_SB_DQ<19>")
	)
	(segment
		(start 403.75332 -298.424346)
		(end 403.629876 -298.54779)
		(width 0.14478)
		(layer "In4.Cu")
		(net "M_J_CPU0_SB_DQ<19>")
	)
	(segment
		(start 404.533608 -298.976034)
		(end 404.533608 -299.204634)
		(width 0.14478)
		(layer "In4.Cu")
		(net "M_J_CPU0_SB_DQ<19>")
	)
	(segment
		(start 388.497826 -285.10357)
		(end 388.506208 -285.098744)
		(width 0.0889)
		(layer "In4.Cu")
		(net "M_J_CPU0_SB_DQ<19>")
	)
	(segment
		(start 404.02002 -298.937934)
		(end 404.143464 -298.81449)
		(width 0.14478)
		(layer "In4.Cu")
		(net "M_J_CPU0_SB_DQ<19>")
	)
	(segment
		(start 403.79142 -298.937934)
		(end 404.02002 -298.937934)
		(width 0.14478)
		(layer "In4.Cu")
		(net "M_J_CPU0_SB_DQ<19>")
	)
	(segment
		(start 406.360884 -301.278798)
		(end 406.484328 -301.155354)
		(width 0.14478)
		(layer "In4.Cu")
		(net "M_J_CPU0_SB_DQ<19>")
	)
	(segment
		(start 403.629876 -298.54779)
		(end 403.629876 -298.77639)
		(width 0.14478)
		(layer "In4.Cu")
		(net "M_J_CPU0_SB_DQ<19>")
	)
	(segment
		(start 418.96284 -303.15027)
		(end 421.480488 -303.15027)
		(width 0.14478)
		(layer "In4.Cu")
		(net "M_J_CPU0_SB_DQ<19>")
	)
	(segment
		(start 405.93264 -300.375066)
		(end 406.094184 -300.53661)
		(width 0.14478)
		(layer "In4.Cu")
		(net "M_J_CPU0_SB_DQ<19>")
	)
	(segment
		(start 406.874472 -301.545498)
		(end 406.751028 -301.668942)
		(width 0.14478)
		(layer "In4.Cu")
		(net "M_J_CPU0_SB_DQ<19>")
	)
	(segment
		(start 429.937164 -302.300386)
		(end 434.565552 -302.300386)
		(width 0.14478)
		(layer "In4.Cu")
		(net "M_J_CPU0_SB_DQ<19>")
	)
	(segment
		(start 404.800308 -299.718222)
		(end 404.923752 -299.594778)
		(width 0.14478)
		(layer "In4.Cu")
		(net "M_J_CPU0_SB_DQ<19>")
	)
	(segment
		(start 382.283462 -285.098744)
		(end 382.291844 -285.10357)
		(width 0.0889)
		(layer "In4.Cu")
		(net "M_J_CPU0_SB_DQ<19>")
	)
	(segment
		(start 394.118846 -285.05023)
		(end 394.609066 -285.54045)
		(width 0.0889)
		(layer "In4.Cu")
		(net "M_J_CPU0_SB_DQ<19>")
	)
	(segment
		(start 407.92146 -302.839374)
		(end 408.044904 -302.71593)
		(width 0.14478)
		(layer "In4.Cu")
		(net "M_J_CPU0_SB_DQ<19>")
	)
	(segment
		(start 406.712928 -301.155354)
		(end 406.874472 -301.316898)
		(width 0.14478)
		(layer "In4.Cu")
		(net "M_J_CPU0_SB_DQ<19>")
	)
	(segment
		(start 407.531316 -302.44923)
		(end 407.531316 -302.67783)
		(width 0.14478)
		(layer "In4.Cu")
		(net "M_J_CPU0_SB_DQ<19>")
	)
	(segment
		(start 426.484034 -303.15027)
		(end 429.08728 -303.15027)
		(width 0.14478)
		(layer "In4.Cu")
		(net "M_J_CPU0_SB_DQ<19>")
	)
	(segment
		(start 403.75332 -298.195746)
		(end 403.75332 -298.424346)
		(width 0.14478)
		(layer "In4.Cu")
		(net "M_J_CPU0_SB_DQ<19>")
	)
	(segment
		(start 386.043424 -285.098744)
		(end 386.051806 -285.10357)
		(width 0.0889)
		(layer "In4.Cu")
		(net "M_J_CPU0_SB_DQ<19>")
	)
	(segment
		(start 404.533608 -299.204634)
		(end 404.410164 -299.328078)
		(width 0.14478)
		(layer "In4.Cu")
		(net "M_J_CPU0_SB_DQ<19>")
	)
	(segment
		(start 407.264616 -301.935642)
		(end 407.493216 -301.935642)
		(width 0.14478)
		(layer "In4.Cu")
		(net "M_J_CPU0_SB_DQ<19>")
	)
	(segment
		(start 380.037848 -285.10357)
		(end 380.04623 -285.098744)
		(width 0.0889)
		(layer "In4.Cu")
		(net "M_J_CPU0_SB_DQ<19>")
	)
	(segment
		(start 403.591776 -298.034202)
		(end 403.75332 -298.195746)
		(width 0.14478)
		(layer "In4.Cu")
		(net "M_J_CPU0_SB_DQ<19>")
	)
	(segment
		(start 407.65476 -302.325786)
		(end 407.531316 -302.44923)
		(width 0.14478)
		(layer "In4.Cu")
		(net "M_J_CPU0_SB_DQ<19>")
	)
	(segment
		(start 408.71775 -303.160176)
		(end 414.020508 -303.160176)
		(width 0.14478)
		(layer "In4.Cu")
		(net "M_J_CPU0_SB_DQ<19>")
	)
	(segment
		(start 395.597634 -285.97733)
		(end 395.790166 -285.97733)
		(width 0.0889)
		(layer "In4.Cu")
		(net "M_J_CPU0_SB_DQ<19>")
	)
	(segment
		(start 405.70404 -300.375066)
		(end 405.93264 -300.375066)
		(width 0.14478)
		(layer "In4.Cu")
		(net "M_J_CPU0_SB_DQ<19>")
	)
	(segment
		(start 386.983478 -285.098744)
		(end 386.99186 -285.10357)
		(width 0.0889)
		(layer "In4.Cu")
		(net "M_J_CPU0_SB_DQ<19>")
	)
	(segment
		(start 402.849588 -297.767502)
		(end 402.849588 -297.996102)
		(width 0.14478)
		(layer "In4.Cu")
		(net "M_J_CPU0_SB_DQ<19>")
	)
	(segment
		(start 422.330372 -302.300386)
		(end 425.63415 -302.300386)
		(width 0.14478)
		(layer "In4.Cu")
		(net "M_J_CPU0_SB_DQ<19>")
	)
	(segment
		(start 404.923752 -299.594778)
		(end 405.152352 -299.594778)
		(width 0.14478)
		(layer "In4.Cu")
		(net "M_J_CPU0_SB_DQ<19>")
	)
	(segment
		(start 407.493216 -301.935642)
		(end 407.65476 -302.097186)
		(width 0.14478)
		(layer "In4.Cu")
		(net "M_J_CPU0_SB_DQ<19>")
	)
	(segment
		(start 403.629876 -298.77639)
		(end 403.79142 -298.937934)
		(width 0.14478)
		(layer "In4.Cu")
		(net "M_J_CPU0_SB_DQ<19>")
	)
	(segment
		(start 407.69286 -302.839374)
		(end 407.92146 -302.839374)
		(width 0.14478)
		(layer "In4.Cu")
		(net "M_J_CPU0_SB_DQ<19>")
	)
	(segment
		(start 406.094184 -300.76521)
		(end 405.97074 -300.888654)
		(width 0.14478)
		(layer "In4.Cu")
		(net "M_J_CPU0_SB_DQ<19>")
	)
	(segment
		(start 421.480488 -303.15027)
		(end 422.330372 -302.300386)
		(width 0.14478)
		(layer "In4.Cu")
		(net "M_J_CPU0_SB_DQ<19>")
	)
	(segment
		(start 406.912572 -302.059086)
		(end 407.141172 -302.059086)
		(width 0.14478)
		(layer "In4.Cu")
		(net "M_J_CPU0_SB_DQ<19>")
	)
	(segment
		(start 402.973032 -297.644058)
		(end 402.849588 -297.767502)
		(width 0.14478)
		(layer "In4.Cu")
		(net "M_J_CPU0_SB_DQ<19>")
	)
	(segment
		(start 406.484328 -301.155354)
		(end 406.712928 -301.155354)
		(width 0.14478)
		(layer "In4.Cu")
		(net "M_J_CPU0_SB_DQ<19>")
	)
	(segment
		(start 402.849588 -297.996102)
		(end 403.011132 -298.157646)
		(width 0.14478)
		(layer "In4.Cu")
		(net "M_J_CPU0_SB_DQ<19>")
	)
	(segment
		(start 405.190452 -300.336966)
		(end 405.351996 -300.49851)
		(width 0.14478)
		(layer "In4.Cu")
		(net "M_J_CPU0_SB_DQ<19>")
	)
	(segment
		(start 414.020508 -303.160176)
		(end 414.870646 -302.310038)
		(width 0.14478)
		(layer "In4.Cu")
		(net "M_J_CPU0_SB_DQ<19>")
	)
	(segment
		(start 418.122608 -302.310038)
		(end 418.96284 -303.15027)
		(width 0.14478)
		(layer "In4.Cu")
		(net "M_J_CPU0_SB_DQ<19>")
	)
	(segment
		(start 391.317734 -285.10357)
		(end 391.326116 -285.098744)
		(width 0.0889)
		(layer "In4.Cu")
		(net "M_J_CPU0_SB_DQ<19>")
	)
	(segment
		(start 434.565552 -302.300386)
		(end 435.000146 -302.73498)
		(width 0.14478)
		(layer "In4.Cu")
		(net "M_J_CPU0_SB_DQ<19>")
	)
	(segment
		(start 405.97074 -300.888654)
		(end 405.97074 -301.117254)
		(width 0.14478)
		(layer "In4.Cu")
		(net "M_J_CPU0_SB_DQ<19>")
	)
	(segment
		(start 393.198096 -285.103824)
		(end 393.216384 -285.09341)
		(width 0.0889)
		(layer "In4.Cu")
		(net "M_J_CPU0_SB_DQ<19>")
	)
	(segment
		(start 403.239732 -298.157646)
		(end 403.363176 -298.034202)
		(width 0.14478)
		(layer "In4.Cu")
		(net "M_J_CPU0_SB_DQ<19>")
	)
	(segment
		(start 395.160754 -285.54045)
		(end 395.597634 -285.97733)
		(width 0.0889)
		(layer "In4.Cu")
		(net "M_J_CPU0_SB_DQ<19>")
	)
	(segment
		(start 394.609066 -285.54045)
		(end 395.160754 -285.54045)
		(width 0.0889)
		(layer "In4.Cu")
		(net "M_J_CPU0_SB_DQ<19>")
	)
	(segment
		(start 429.08728 -303.15027)
		(end 429.937164 -302.300386)
		(width 0.14478)
		(layer "In4.Cu")
		(net "M_J_CPU0_SB_DQ<19>")
	)
	(segment
		(start 404.372064 -298.81449)
		(end 404.533608 -298.976034)
		(width 0.14478)
		(layer "In4.Cu")
		(net "M_J_CPU0_SB_DQ<19>")
	)
	(segment
		(start 408.044904 -302.71593)
		(end 408.273504 -302.71593)
		(width 0.14478)
		(layer "In4.Cu")
		(net "M_J_CPU0_SB_DQ<19>")
	)
	(segment
		(start 405.97074 -301.117254)
		(end 406.132284 -301.278798)
		(width 0.14478)
		(layer "In4.Cu")
		(net "M_J_CPU0_SB_DQ<19>")
	)
	(segment
		(start 404.571708 -299.718222)
		(end 404.800308 -299.718222)
		(width 0.14478)
		(layer "In4.Cu")
		(net "M_J_CPU0_SB_DQ<19>")
	)
	(segment
		(start 404.143464 -298.81449)
		(end 404.372064 -298.81449)
		(width 0.14478)
		(layer "In4.Cu")
		(net "M_J_CPU0_SB_DQ<19>")
	)
	(segment
		(start 407.65476 -302.097186)
		(end 407.65476 -302.325786)
		(width 0.14478)
		(layer "In4.Cu")
		(net "M_J_CPU0_SB_DQ<19>")
	)
	(segment
		(start 402.973032 -297.415458)
		(end 402.973032 -297.644058)
		(width 0.14478)
		(layer "In4.Cu")
		(net "M_J_CPU0_SB_DQ<19>")
	)
	(segment
		(start 382.857756 -285.10357)
		(end 382.866138 -285.098744)
		(width 0.0889)
		(layer "In4.Cu")
		(net "M_J_CPU0_SB_DQ<19>")
	)
	(segment
		(start 387.557772 -285.10357)
		(end 387.566154 -285.098744)
		(width 0.0889)
		(layer "In4.Cu")
		(net "M_J_CPU0_SB_DQ<19>")
	)
	(segment
		(start 402.304758 -296.747184)
		(end 402.973032 -297.415458)
		(width 0.14478)
		(layer "In4.Cu")
		(net "M_J_CPU0_SB_DQ<19>")
	)
	(segment
		(start 392.62431 -285.098744)
		(end 392.632692 -285.10357)
		(width 0.0889)
		(layer "In4.Cu")
		(net "M_J_CPU0_SB_DQ<19>")
	)
	(segment
		(start 408.273504 -302.71593)
		(end 408.71775 -303.160176)
		(width 0.14478)
		(layer "In4.Cu")
		(net "M_J_CPU0_SB_DQ<19>")
	)
	(segment
		(start 383.79781 -285.10357)
		(end 383.806192 -285.098744)
		(width 0.0889)
		(layer "In4.Cu")
		(net "M_J_CPU0_SB_DQ<19>")
	)
	(segment
		(start 406.132284 -301.278798)
		(end 406.360884 -301.278798)
		(width 0.14478)
		(layer "In4.Cu")
		(net "M_J_CPU0_SB_DQ<19>")
	)
	(segment
		(start 395.790166 -285.97733)
		(end 396.278354 -285.97733)
		(width 0.14478)
		(layer "In4.Cu")
		(net "M_J_CPU0_SB_DQ<19>")
	)
	(segment
		(start 407.531316 -302.67783)
		(end 407.69286 -302.839374)
		(width 0.14478)
		(layer "In4.Cu")
		(net "M_J_CPU0_SB_DQ<19>")
	)
	(segment
		(start 406.751028 -301.897542)
		(end 406.912572 -302.059086)
		(width 0.14478)
		(layer "In4.Cu")
		(net "M_J_CPU0_SB_DQ<19>")
	)
	(segment
		(start 414.870646 -302.310038)
		(end 418.122608 -302.310038)
		(width 0.14478)
		(layer "In4.Cu")
		(net "M_J_CPU0_SB_DQ<19>")
	)
	(segment
		(start 403.011132 -298.157646)
		(end 403.239732 -298.157646)
		(width 0.14478)
		(layer "In4.Cu")
		(net "M_J_CPU0_SB_DQ<19>")
	)
	(segment
		(start 405.190452 -300.108366)
		(end 405.190452 -300.336966)
		(width 0.14478)
		(layer "In4.Cu")
		(net "M_J_CPU0_SB_DQ<19>")
	)
	(segment
		(start 404.410164 -299.328078)
		(end 404.410164 -299.556678)
		(width 0.14478)
		(layer "In4.Cu")
		(net "M_J_CPU0_SB_DQ<19>")
	)
	(segment
		(start 393.288012 -285.05023)
		(end 394.118846 -285.05023)
		(width 0.0889)
		(layer "In4.Cu")
		(net "M_J_CPU0_SB_DQ<19>")
	)
	(segment
		(start 406.751028 -301.668942)
		(end 406.751028 -301.897542)
		(width 0.14478)
		(layer "In4.Cu")
		(net "M_J_CPU0_SB_DQ<19>")
	)
	(segment
		(start 406.094184 -300.53661)
		(end 406.094184 -300.76521)
		(width 0.14478)
		(layer "In4.Cu")
		(net "M_J_CPU0_SB_DQ<19>")
	)
	(arc
		(start 387.566154 -285.098744)
		(mid 387.749662 -285.05325)
		(end 387.931914 -285.10357)
		(width 0.0889)
		(layer "In4.Cu")
		(net "M_J_CPU0_SB_DQ<19>")
	)
	(arc
		(start 387.931914 -285.10357)
		(mid 388.21487 -285.179747)
		(end 388.497826 -285.10357)
		(width 0.0889)
		(layer "In4.Cu")
		(net "M_J_CPU0_SB_DQ<19>")
	)
	(arc
		(start 383.231898 -285.10357)
		(mid 383.514854 -285.179747)
		(end 383.79781 -285.10357)
		(width 0.0889)
		(layer "In4.Cu")
		(net "M_J_CPU0_SB_DQ<19>")
	)
	(arc
		(start 389.43788 -285.10357)
		(mid 389.624824 -285.053315)
		(end 389.811768 -285.10357)
		(width 0.0889)
		(layer "In4.Cu")
		(net "M_J_CPU0_SB_DQ<19>")
	)
	(arc
		(start 386.051806 -285.10357)
		(mid 386.334762 -285.179747)
		(end 386.617718 -285.10357)
		(width 0.0889)
		(layer "In4.Cu")
		(net "M_J_CPU0_SB_DQ<19>")
	)
	(arc
		(start 388.871968 -285.10357)
		(mid 389.154924 -285.179747)
		(end 389.43788 -285.10357)
		(width 0.0889)
		(layer "In4.Cu")
		(net "M_J_CPU0_SB_DQ<19>")
	)
	(arc
		(start 391.326116 -285.098744)
		(mid 391.509624 -285.05325)
		(end 391.691876 -285.10357)
		(width 0.0889)
		(layer "In4.Cu")
		(net "M_J_CPU0_SB_DQ<19>")
	)
	(arc
		(start 383.806192 -285.098744)
		(mid 383.9897 -285.05325)
		(end 384.171952 -285.10357)
		(width 0.0889)
		(layer "In4.Cu")
		(net "M_J_CPU0_SB_DQ<19>")
	)
	(arc
		(start 382.866138 -285.098744)
		(mid 383.049646 -285.05325)
		(end 383.231898 -285.10357)
		(width 0.0889)
		(layer "In4.Cu")
		(net "M_J_CPU0_SB_DQ<19>")
	)
	(arc
		(start 390.37768 -285.10357)
		(mid 390.559931 -285.05322)
		(end 390.74344 -285.098744)
		(width 0.0889)
		(layer "In4.Cu")
		(net "M_J_CPU0_SB_DQ<19>")
	)
	(arc
		(start 382.291844 -285.10357)
		(mid 382.5748 -285.179747)
		(end 382.857756 -285.10357)
		(width 0.0889)
		(layer "In4.Cu")
		(net "M_J_CPU0_SB_DQ<19>")
	)
	(arc
		(start 385.111752 -285.10357)
		(mid 385.394708 -285.179747)
		(end 385.677664 -285.10357)
		(width 0.0889)
		(layer "In4.Cu")
		(net "M_J_CPU0_SB_DQ<19>")
	)
	(arc
		(start 390.751822 -285.10357)
		(mid 391.034778 -285.179747)
		(end 391.317734 -285.10357)
		(width 0.0889)
		(layer "In4.Cu")
		(net "M_J_CPU0_SB_DQ<19>")
	)
	(arc
		(start 386.617718 -285.10357)
		(mid 386.799969 -285.05322)
		(end 386.983478 -285.098744)
		(width 0.0889)
		(layer "In4.Cu")
		(net "M_J_CPU0_SB_DQ<19>")
	)
	(arc
		(start 381.917702 -285.10357)
		(mid 382.099953 -285.05322)
		(end 382.283462 -285.098744)
		(width 0.0889)
		(layer "In4.Cu")
		(net "M_J_CPU0_SB_DQ<19>")
	)
	(arc
		(start 392.632692 -285.10357)
		(mid 392.91212 -285.179736)
		(end 393.192508 -285.107126)
		(width 0.0889)
		(layer "In4.Cu")
		(net "M_J_CPU0_SB_DQ<19>")
	)
	(arc
		(start 380.41199 -285.10357)
		(mid 380.694946 -285.179747)
		(end 380.977902 -285.10357)
		(width 0.0889)
		(layer "In4.Cu")
		(net "M_J_CPU0_SB_DQ<19>")
	)
	(arc
		(start 381.35179 -285.10357)
		(mid 381.634746 -285.179747)
		(end 381.917702 -285.10357)
		(width 0.0889)
		(layer "In4.Cu")
		(net "M_J_CPU0_SB_DQ<19>")
	)
	(arc
		(start 389.811768 -285.10357)
		(mid 390.094724 -285.179747)
		(end 390.37768 -285.10357)
		(width 0.0889)
		(layer "In4.Cu")
		(net "M_J_CPU0_SB_DQ<19>")
	)
	(arc
		(start 392.258042 -285.10357)
		(mid 392.440547 -285.053093)
		(end 392.62431 -285.098744)
		(width 0.0889)
		(layer "In4.Cu")
		(net "M_J_CPU0_SB_DQ<19>")
	)
	(arc
		(start 379.535182 -285.13532)
		(mid 379.790247 -285.178671)
		(end 380.037848 -285.10357)
		(width 0.0889)
		(layer "In4.Cu")
		(net "M_J_CPU0_SB_DQ<19>")
	)
	(arc
		(start 385.677664 -285.10357)
		(mid 385.859915 -285.05322)
		(end 386.043424 -285.098744)
		(width 0.0889)
		(layer "In4.Cu")
		(net "M_J_CPU0_SB_DQ<19>")
	)
	(arc
		(start 384.171952 -285.10357)
		(mid 384.454908 -285.179747)
		(end 384.737864 -285.10357)
		(width 0.0889)
		(layer "In4.Cu")
		(net "M_J_CPU0_SB_DQ<19>")
	)
	(arc
		(start 380.04623 -285.098744)
		(mid 380.229738 -285.05325)
		(end 380.41199 -285.10357)
		(width 0.0889)
		(layer "In4.Cu")
		(net "M_J_CPU0_SB_DQ<19>")
	)
	(arc
		(start 391.70229 -285.109666)
		(mid 391.980976 -285.179886)
		(end 392.258042 -285.10357)
		(width 0.0889)
		(layer "In4.Cu")
		(net "M_J_CPU0_SB_DQ<19>")
	)
	(arc
		(start 384.737864 -285.10357)
		(mid 384.924808 -285.053315)
		(end 385.111752 -285.10357)
		(width 0.0889)
		(layer "In4.Cu")
		(net "M_J_CPU0_SB_DQ<19>")
	)
	(arc
		(start 388.506208 -285.098744)
		(mid 388.689716 -285.05325)
		(end 388.871968 -285.10357)
		(width 0.0889)
		(layer "In4.Cu")
		(net "M_J_CPU0_SB_DQ<19>")
	)
	(arc
		(start 380.977902 -285.10357)
		(mid 381.164846 -285.053315)
		(end 381.35179 -285.10357)
		(width 0.0889)
		(layer "In4.Cu")
		(net "M_J_CPU0_SB_DQ<19>")
	)
	(arc
		(start 386.99186 -285.10357)
		(mid 387.274816 -285.179747)
		(end 387.557772 -285.10357)
		(width 0.0889)
		(layer "In4.Cu")
		(net "M_J_CPU0_SB_DQ<19>")
	)
	(segment
		(start 380.22784 -284.350206)
		(end 380.694946 -284.616144)
		(width 0.10668)
		(layer "F.Cu")
		(net "M_J_CPU0_SB_DQ<18>")
	)
	(segment
		(start 411.830774 -301.460154)
		(end 412.121096 -301.169832)
		(width 0.14478)
		(layer "In4.Cu")
		(net "M_J_CPU0_SB_DQ<18>")
	)
	(segment
		(start 403.497288 -296.667682)
		(end 403.725888 -296.667682)
		(width 0.14478)
		(layer "In4.Cu")
		(net "M_J_CPU0_SB_DQ<18>")
	)
	(segment
		(start 406.456896 -299.39869)
		(end 406.456896 -299.62729)
		(width 0.14478)
		(layer "In4.Cu")
		(net "M_J_CPU0_SB_DQ<18>")
	)
	(segment
		(start 407.806144 -300.390306)
		(end 408.034744 -300.390306)
		(width 0.14478)
		(layer "In4.Cu")
		(net "M_J_CPU0_SB_DQ<18>")
	)
	(segment
		(start 408.407616 -301.34941)
		(end 408.586432 -301.170594)
		(width 0.14478)
		(layer "In4.Cu")
		(net "M_J_CPU0_SB_DQ<18>")
	)
	(segment
		(start 412.933642 -301.460154)
		(end 413.223964 -301.169832)
		(width 0.14478)
		(layer "In4.Cu")
		(net "M_J_CPU0_SB_DQ<18>")
	)
	(segment
		(start 407.416 -300.000162)
		(end 407.237184 -300.178978)
		(width 0.14478)
		(layer "In4.Cu")
		(net "M_J_CPU0_SB_DQ<18>")
	)
	(segment
		(start 433.566824 -300.910752)
		(end 433.817522 -300.910752)
		(width 0.14478)
		(layer "In4.Cu")
		(net "M_J_CPU0_SB_DQ<18>")
	)
	(segment
		(start 418.972746 -301.460154)
		(end 421.537638 -301.460154)
		(width 0.14478)
		(layer "In4.Cu")
		(net "M_J_CPU0_SB_DQ<18>")
	)
	(segment
		(start 408.815032 -301.170594)
		(end 409.104592 -301.460154)
		(width 0.14478)
		(layer "In4.Cu")
		(net "M_J_CPU0_SB_DQ<18>")
	)
	(segment
		(start 392.725402 -284.293564)
		(end 392.744198 -284.282642)
		(width 0.0889)
		(layer "In4.Cu")
		(net "M_J_CPU0_SB_DQ<18>")
	)
	(segment
		(start 394.730478 -284.95879)
		(end 395.468094 -284.95879)
		(width 0.0889)
		(layer "In4.Cu")
		(net "M_J_CPU0_SB_DQ<18>")
	)
	(segment
		(start 434.118258 -300.610016)
		(end 434.575204 -300.610016)
		(width 0.14478)
		(layer "In4.Cu")
		(net "M_J_CPU0_SB_DQ<18>")
	)
	(segment
		(start 406.456896 -299.62729)
		(end 406.61844 -299.788834)
		(width 0.14478)
		(layer "In4.Cu")
		(net "M_J_CPU0_SB_DQ<18>")
	)
	(segment
		(start 408.034744 -300.390306)
		(end 408.196288 -300.55185)
		(width 0.14478)
		(layer "In4.Cu")
		(net "M_J_CPU0_SB_DQ<18>")
	)
	(segment
		(start 385.207764 -284.293564)
		(end 385.216146 -284.288738)
		(width 0.0889)
		(layer "In4.Cu")
		(net "M_J_CPU0_SB_DQ<18>")
	)
	(segment
		(start 408.017472 -300.959266)
		(end 408.017472 -301.187866)
		(width 0.14478)
		(layer "In4.Cu")
		(net "M_J_CPU0_SB_DQ<18>")
	)
	(segment
		(start 389.333486 -284.288738)
		(end 389.341868 -284.293564)
		(width 0.0889)
		(layer "In4.Cu")
		(net "M_J_CPU0_SB_DQ<18>")
	)
	(segment
		(start 404.116032 -297.286426)
		(end 404.277576 -297.44797)
		(width 0.14478)
		(layer "In4.Cu")
		(net "M_J_CPU0_SB_DQ<18>")
	)
	(segment
		(start 405.855424 -298.439586)
		(end 405.676608 -298.618402)
		(width 0.14478)
		(layer "In4.Cu")
		(net "M_J_CPU0_SB_DQ<18>")
	)
	(segment
		(start 405.855424 -298.210986)
		(end 405.855424 -298.439586)
		(width 0.14478)
		(layer "In4.Cu")
		(net "M_J_CPU0_SB_DQ<18>")
	)
	(segment
		(start 407.237184 -300.178978)
		(end 407.237184 -300.407578)
		(width 0.14478)
		(layer "In4.Cu")
		(net "M_J_CPU0_SB_DQ<18>")
	)
	(segment
		(start 410.727906 -301.460154)
		(end 411.018228 -301.169832)
		(width 0.14478)
		(layer "In4.Cu")
		(net "M_J_CPU0_SB_DQ<18>")
	)
	(segment
		(start 408.586432 -301.170594)
		(end 408.815032 -301.170594)
		(width 0.14478)
		(layer "In4.Cu")
		(net "M_J_CPU0_SB_DQ<18>")
	)
	(segment
		(start 403.51456 -295.870122)
		(end 403.51456 -296.098722)
		(width 0.14478)
		(layer "In4.Cu")
		(net "M_J_CPU0_SB_DQ<18>")
	)
	(segment
		(start 411.27934 -301.169832)
		(end 411.569662 -301.460154)
		(width 0.14478)
		(layer "In4.Cu")
		(net "M_J_CPU0_SB_DQ<18>")
	)
	(segment
		(start 414.090104 -301.460154)
		(end 414.940242 -300.610016)
		(width 0.14478)
		(layer "In4.Cu")
		(net "M_J_CPU0_SB_DQ<18>")
	)
	(segment
		(start 403.904704 -296.488866)
		(end 404.133304 -296.488866)
		(width 0.14478)
		(layer "In4.Cu")
		(net "M_J_CPU0_SB_DQ<18>")
	)
	(segment
		(start 409.625038 -301.460154)
		(end 409.91536 -301.169832)
		(width 0.14478)
		(layer "In4.Cu")
		(net "M_J_CPU0_SB_DQ<18>")
	)
	(segment
		(start 411.018228 -301.169832)
		(end 411.27934 -301.169832)
		(width 0.14478)
		(layer "In4.Cu")
		(net "M_J_CPU0_SB_DQ<18>")
	)
	(segment
		(start 404.913592 -297.269154)
		(end 405.075136 -297.430698)
		(width 0.14478)
		(layer "In4.Cu")
		(net "M_J_CPU0_SB_DQ<18>")
	)
	(segment
		(start 432.714654 -300.910752)
		(end 433.01539 -300.610016)
		(width 0.14478)
		(layer "In4.Cu")
		(net "M_J_CPU0_SB_DQ<18>")
	)
	(segment
		(start 408.179016 -301.34941)
		(end 408.407616 -301.34941)
		(width 0.14478)
		(layer "In4.Cu")
		(net "M_J_CPU0_SB_DQ<18>")
	)
	(segment
		(start 405.676608 -298.847002)
		(end 405.838152 -299.008546)
		(width 0.14478)
		(layer "In4.Cu")
		(net "M_J_CPU0_SB_DQ<18>")
	)
	(segment
		(start 404.294848 -296.87901)
		(end 404.116032 -297.057826)
		(width 0.14478)
		(layer "In4.Cu")
		(net "M_J_CPU0_SB_DQ<18>")
	)
	(segment
		(start 383.693416 -284.288738)
		(end 383.701798 -284.293564)
		(width 0.0889)
		(layer "In4.Cu")
		(net "M_J_CPU0_SB_DQ<18>")
	)
	(segment
		(start 395.852904 -285.06801)
		(end 396.641066 -285.06801)
		(width 0.14478)
		(layer "In4.Cu")
		(net "M_J_CPU0_SB_DQ<18>")
	)
	(segment
		(start 386.147818 -284.293564)
		(end 386.1562 -284.288738)
		(width 0.0889)
		(layer "In4.Cu")
		(net "M_J_CPU0_SB_DQ<18>")
	)
	(segment
		(start 403.335744 -296.506138)
		(end 403.497288 -296.667682)
		(width 0.14478)
		(layer "In4.Cu")
		(net "M_J_CPU0_SB_DQ<18>")
	)
	(segment
		(start 403.51456 -296.098722)
		(end 403.335744 -296.277538)
		(width 0.14478)
		(layer "In4.Cu")
		(net "M_J_CPU0_SB_DQ<18>")
	)
	(segment
		(start 421.537638 -301.460154)
		(end 422.387776 -300.610016)
		(width 0.14478)
		(layer "In4.Cu")
		(net "M_J_CPU0_SB_DQ<18>")
	)
	(segment
		(start 430.075594 -300.610016)
		(end 432.16322 -300.610016)
		(width 0.14478)
		(layer "In4.Cu")
		(net "M_J_CPU0_SB_DQ<18>")
	)
	(segment
		(start 409.104592 -301.460154)
		(end 409.625038 -301.460154)
		(width 0.14478)
		(layer "In4.Cu")
		(net "M_J_CPU0_SB_DQ<18>")
	)
	(segment
		(start 407.398728 -300.569122)
		(end 407.627328 -300.569122)
		(width 0.14478)
		(layer "In4.Cu")
		(net "M_J_CPU0_SB_DQ<18>")
	)
	(segment
		(start 406.635712 -298.991274)
		(end 406.635712 -299.219874)
		(width 0.14478)
		(layer "In4.Cu")
		(net "M_J_CPU0_SB_DQ<18>")
	)
	(segment
		(start 403.725888 -296.667682)
		(end 403.904704 -296.488866)
		(width 0.14478)
		(layer "In4.Cu")
		(net "M_J_CPU0_SB_DQ<18>")
	)
	(segment
		(start 412.382208 -301.169832)
		(end 412.67253 -301.460154)
		(width 0.14478)
		(layer "In4.Cu")
		(net "M_J_CPU0_SB_DQ<18>")
	)
	(segment
		(start 410.466794 -301.460154)
		(end 410.727906 -301.460154)
		(width 0.14478)
		(layer "In4.Cu")
		(net "M_J_CPU0_SB_DQ<18>")
	)
	(segment
		(start 432.463956 -300.910752)
		(end 432.714654 -300.910752)
		(width 0.14478)
		(layer "In4.Cu")
		(net "M_J_CPU0_SB_DQ<18>")
	)
	(segment
		(start 408.196288 -300.78045)
		(end 408.017472 -300.959266)
		(width 0.14478)
		(layer "In4.Cu")
		(net "M_J_CPU0_SB_DQ<18>")
	)
	(segment
		(start 407.254456 -299.610018)
		(end 407.416 -299.771562)
		(width 0.14478)
		(layer "In4.Cu")
		(net "M_J_CPU0_SB_DQ<18>")
	)
	(segment
		(start 404.116032 -297.057826)
		(end 404.116032 -297.286426)
		(width 0.14478)
		(layer "In4.Cu")
		(net "M_J_CPU0_SB_DQ<18>")
	)
	(segment
		(start 409.91536 -301.169832)
		(end 410.176472 -301.169832)
		(width 0.14478)
		(layer "In4.Cu")
		(net "M_J_CPU0_SB_DQ<18>")
	)
	(segment
		(start 407.627328 -300.569122)
		(end 407.806144 -300.390306)
		(width 0.14478)
		(layer "In4.Cu")
		(net "M_J_CPU0_SB_DQ<18>")
	)
	(segment
		(start 425.666662 -300.610016)
		(end 426.516546 -301.4599)
		(width 0.14478)
		(layer "In4.Cu")
		(net "M_J_CPU0_SB_DQ<18>")
	)
	(segment
		(start 404.89632 -297.838114)
		(end 404.89632 -298.066714)
		(width 0.14478)
		(layer "In4.Cu")
		(net "M_J_CPU0_SB_DQ<18>")
	)
	(segment
		(start 381.447802 -284.293564)
		(end 381.456184 -284.288738)
		(width 0.0889)
		(layer "In4.Cu")
		(net "M_J_CPU0_SB_DQ<18>")
	)
	(segment
		(start 412.121096 -301.169832)
		(end 412.382208 -301.169832)
		(width 0.14478)
		(layer "In4.Cu")
		(net "M_J_CPU0_SB_DQ<18>")
	)
	(segment
		(start 404.277576 -297.44797)
		(end 404.506176 -297.44797)
		(width 0.14478)
		(layer "In4.Cu")
		(net "M_J_CPU0_SB_DQ<18>")
	)
	(segment
		(start 384.63347 -284.288738)
		(end 384.641852 -284.293564)
		(width 0.0889)
		(layer "In4.Cu")
		(net "M_J_CPU0_SB_DQ<18>")
	)
	(segment
		(start 432.16322 -300.610016)
		(end 432.463956 -300.910752)
		(width 0.14478)
		(layer "In4.Cu")
		(net "M_J_CPU0_SB_DQ<18>")
	)
	(segment
		(start 433.01539 -300.610016)
		(end 433.266088 -300.610016)
		(width 0.14478)
		(layer "In4.Cu")
		(net "M_J_CPU0_SB_DQ<18>")
	)
	(segment
		(start 406.474168 -298.82973)
		(end 406.635712 -298.991274)
		(width 0.14478)
		(layer "In4.Cu")
		(net "M_J_CPU0_SB_DQ<18>")
	)
	(segment
		(start 388.393432 -284.288738)
		(end 388.401814 -284.293564)
		(width 0.0889)
		(layer "In4.Cu")
		(net "M_J_CPU0_SB_DQ<18>")
	)
	(segment
		(start 406.84704 -299.788834)
		(end 407.025856 -299.610018)
		(width 0.14478)
		(layer "In4.Cu")
		(net "M_J_CPU0_SB_DQ<18>")
	)
	(segment
		(start 411.569662 -301.460154)
		(end 411.830774 -301.460154)
		(width 0.14478)
		(layer "In4.Cu")
		(net "M_J_CPU0_SB_DQ<18>")
	)
	(segment
		(start 426.516546 -301.4599)
		(end 429.22571 -301.4599)
		(width 0.14478)
		(layer "In4.Cu")
		(net "M_J_CPU0_SB_DQ<18>")
	)
	(segment
		(start 392.140948 -284.282388)
		(end 392.161014 -284.293818)
		(width 0.0889)
		(layer "In4.Cu")
		(net "M_J_CPU0_SB_DQ<18>")
	)
	(segment
		(start 412.67253 -301.460154)
		(end 412.933642 -301.460154)
		(width 0.14478)
		(layer "In4.Cu")
		(net "M_J_CPU0_SB_DQ<18>")
	)
	(segment
		(start 407.416 -299.771562)
		(end 407.416 -300.000162)
		(width 0.14478)
		(layer "In4.Cu")
		(net "M_J_CPU0_SB_DQ<18>")
	)
	(segment
		(start 433.817522 -300.910752)
		(end 434.118258 -300.610016)
		(width 0.14478)
		(layer "In4.Cu")
		(net "M_J_CPU0_SB_DQ<18>")
	)
	(segment
		(start 405.676608 -298.618402)
		(end 405.676608 -298.847002)
		(width 0.14478)
		(layer "In4.Cu")
		(net "M_J_CPU0_SB_DQ<18>")
	)
	(segment
		(start 396.641066 -285.06801)
		(end 403.203918 -291.630862)
		(width 0.14478)
		(layer "In4.Cu")
		(net "M_J_CPU0_SB_DQ<18>")
	)
	(segment
		(start 406.61844 -299.788834)
		(end 406.84704 -299.788834)
		(width 0.14478)
		(layer "In4.Cu")
		(net "M_J_CPU0_SB_DQ<18>")
	)
	(segment
		(start 404.294848 -296.65041)
		(end 404.294848 -296.87901)
		(width 0.14478)
		(layer "In4.Cu")
		(net "M_J_CPU0_SB_DQ<18>")
	)
	(segment
		(start 405.075136 -297.659298)
		(end 404.89632 -297.838114)
		(width 0.14478)
		(layer "In4.Cu")
		(net "M_J_CPU0_SB_DQ<18>")
	)
	(segment
		(start 406.635712 -299.219874)
		(end 406.456896 -299.39869)
		(width 0.14478)
		(layer "In4.Cu")
		(net "M_J_CPU0_SB_DQ<18>")
	)
	(segment
		(start 403.203918 -291.630862)
		(end 403.203918 -295.55948)
		(width 0.14478)
		(layer "In4.Cu")
		(net "M_J_CPU0_SB_DQ<18>")
	)
	(segment
		(start 404.506176 -297.44797)
		(end 404.684992 -297.269154)
		(width 0.14478)
		(layer "In4.Cu")
		(net "M_J_CPU0_SB_DQ<18>")
	)
	(segment
		(start 403.203918 -295.55948)
		(end 403.51456 -295.870122)
		(width 0.14478)
		(layer "In4.Cu")
		(net "M_J_CPU0_SB_DQ<18>")
	)
	(segment
		(start 405.057864 -298.228258)
		(end 405.286464 -298.228258)
		(width 0.14478)
		(layer "In4.Cu")
		(net "M_J_CPU0_SB_DQ<18>")
	)
	(segment
		(start 405.46528 -298.049442)
		(end 405.69388 -298.049442)
		(width 0.14478)
		(layer "In4.Cu")
		(net "M_J_CPU0_SB_DQ<18>")
	)
	(segment
		(start 389.90778 -284.293564)
		(end 389.916162 -284.288738)
		(width 0.0889)
		(layer "In4.Cu")
		(net "M_J_CPU0_SB_DQ<18>")
	)
	(segment
		(start 404.684992 -297.269154)
		(end 404.913592 -297.269154)
		(width 0.14478)
		(layer "In4.Cu")
		(net "M_J_CPU0_SB_DQ<18>")
	)
	(segment
		(start 414.940242 -300.610016)
		(end 418.122608 -300.610016)
		(width 0.14478)
		(layer "In4.Cu")
		(net "M_J_CPU0_SB_DQ<18>")
	)
	(segment
		(start 404.89632 -298.066714)
		(end 405.057864 -298.228258)
		(width 0.14478)
		(layer "In4.Cu")
		(net "M_J_CPU0_SB_DQ<18>")
	)
	(segment
		(start 418.122608 -300.610016)
		(end 418.972746 -301.460154)
		(width 0.14478)
		(layer "In4.Cu")
		(net "M_J_CPU0_SB_DQ<18>")
	)
	(segment
		(start 408.017472 -301.187866)
		(end 408.179016 -301.34941)
		(width 0.14478)
		(layer "In4.Cu")
		(net "M_J_CPU0_SB_DQ<18>")
	)
	(segment
		(start 380.694946 -284.616144)
		(end 380.84887 -284.350714)
		(width 0.0889)
		(layer "In4.Cu")
		(net "M_J_CPU0_SB_DQ<18>")
	)
	(segment
		(start 395.577314 -285.06801)
		(end 395.852904 -285.06801)
		(width 0.0889)
		(layer "In4.Cu")
		(net "M_J_CPU0_SB_DQ<18>")
	)
	(segment
		(start 405.286464 -298.228258)
		(end 405.46528 -298.049442)
		(width 0.14478)
		(layer "In4.Cu")
		(net "M_J_CPU0_SB_DQ<18>")
	)
	(segment
		(start 413.775398 -301.460154)
		(end 414.090104 -301.460154)
		(width 0.14478)
		(layer "In4.Cu")
		(net "M_J_CPU0_SB_DQ<18>")
	)
	(segment
		(start 422.387776 -300.610016)
		(end 425.666662 -300.610016)
		(width 0.14478)
		(layer "In4.Cu")
		(net "M_J_CPU0_SB_DQ<18>")
	)
	(segment
		(start 405.69388 -298.049442)
		(end 405.855424 -298.210986)
		(width 0.14478)
		(layer "In4.Cu")
		(net "M_J_CPU0_SB_DQ<18>")
	)
	(segment
		(start 405.838152 -299.008546)
		(end 406.066752 -299.008546)
		(width 0.14478)
		(layer "In4.Cu")
		(net "M_J_CPU0_SB_DQ<18>")
	)
	(segment
		(start 429.22571 -301.4599)
		(end 430.075594 -300.610016)
		(width 0.14478)
		(layer "In4.Cu")
		(net "M_J_CPU0_SB_DQ<18>")
	)
	(segment
		(start 410.176472 -301.169832)
		(end 410.466794 -301.460154)
		(width 0.14478)
		(layer "In4.Cu")
		(net "M_J_CPU0_SB_DQ<18>")
	)
	(segment
		(start 395.468094 -284.95879)
		(end 395.577314 -285.06801)
		(width 0.0889)
		(layer "In4.Cu")
		(net "M_J_CPU0_SB_DQ<18>")
	)
	(segment
		(start 413.485076 -301.169832)
		(end 413.775398 -301.460154)
		(width 0.14478)
		(layer "In4.Cu")
		(net "M_J_CPU0_SB_DQ<18>")
	)
	(segment
		(start 405.075136 -297.430698)
		(end 405.075136 -297.659298)
		(width 0.14478)
		(layer "In4.Cu")
		(net "M_J_CPU0_SB_DQ<18>")
	)
	(segment
		(start 404.133304 -296.488866)
		(end 404.294848 -296.65041)
		(width 0.14478)
		(layer "In4.Cu")
		(net "M_J_CPU0_SB_DQ<18>")
	)
	(segment
		(start 393.384786 -284.370272)
		(end 394.14196 -284.370272)
		(width 0.0889)
		(layer "In4.Cu")
		(net "M_J_CPU0_SB_DQ<18>")
	)
	(segment
		(start 406.066752 -299.008546)
		(end 406.245568 -298.82973)
		(width 0.14478)
		(layer "In4.Cu")
		(net "M_J_CPU0_SB_DQ<18>")
	)
	(segment
		(start 407.237184 -300.407578)
		(end 407.398728 -300.569122)
		(width 0.14478)
		(layer "In4.Cu")
		(net "M_J_CPU0_SB_DQ<18>")
	)
	(segment
		(start 407.025856 -299.610018)
		(end 407.254456 -299.610018)
		(width 0.14478)
		(layer "In4.Cu")
		(net "M_J_CPU0_SB_DQ<18>")
	)
	(segment
		(start 380.84887 -284.350714)
		(end 380.944882 -284.325314)
		(width 0.0889)
		(layer "In4.Cu")
		(net "M_J_CPU0_SB_DQ<18>")
	)
	(segment
		(start 403.335744 -296.277538)
		(end 403.335744 -296.506138)
		(width 0.14478)
		(layer "In4.Cu")
		(net "M_J_CPU0_SB_DQ<18>")
	)
	(segment
		(start 413.223964 -301.169832)
		(end 413.485076 -301.169832)
		(width 0.14478)
		(layer "In4.Cu")
		(net "M_J_CPU0_SB_DQ<18>")
	)
	(segment
		(start 408.196288 -300.55185)
		(end 408.196288 -300.78045)
		(width 0.14478)
		(layer "In4.Cu")
		(net "M_J_CPU0_SB_DQ<18>")
	)
	(segment
		(start 406.245568 -298.82973)
		(end 406.474168 -298.82973)
		(width 0.14478)
		(layer "In4.Cu")
		(net "M_J_CPU0_SB_DQ<18>")
	)
	(segment
		(start 434.575204 -300.610016)
		(end 435.000146 -301.034958)
		(width 0.14478)
		(layer "In4.Cu")
		(net "M_J_CPU0_SB_DQ<18>")
	)
	(segment
		(start 392.161014 -284.293818)
		(end 392.182604 -284.306264)
		(width 0.0889)
		(layer "In4.Cu")
		(net "M_J_CPU0_SB_DQ<18>")
	)
	(segment
		(start 394.14196 -284.370272)
		(end 394.730478 -284.95879)
		(width 0.0889)
		(layer "In4.Cu")
		(net "M_J_CPU0_SB_DQ<18>")
	)
	(segment
		(start 433.266088 -300.610016)
		(end 433.566824 -300.910752)
		(width 0.14478)
		(layer "In4.Cu")
		(net "M_J_CPU0_SB_DQ<18>")
	)
	(arc
		(start 392.744198 -284.282642)
		(mid 392.923769 -284.242825)
		(end 393.10056 -284.293564)
		(width 0.0889)
		(layer "In4.Cu")
		(net "M_J_CPU0_SB_DQ<18>")
	)
	(arc
		(start 383.701798 -284.293564)
		(mid 383.984754 -284.369741)
		(end 384.26771 -284.293564)
		(width 0.0889)
		(layer "In4.Cu")
		(net "M_J_CPU0_SB_DQ<18>")
	)
	(arc
		(start 392.182604 -284.306264)
		(mid 392.455633 -284.369583)
		(end 392.725402 -284.293564)
		(width 0.0889)
		(layer "In4.Cu")
		(net "M_J_CPU0_SB_DQ<18>")
	)
	(arc
		(start 391.787634 -284.293564)
		(mid 391.962873 -284.243493)
		(end 392.140948 -284.282388)
		(width 0.0889)
		(layer "In4.Cu")
		(net "M_J_CPU0_SB_DQ<18>")
	)
	(arc
		(start 388.027672 -284.293564)
		(mid 388.209923 -284.243214)
		(end 388.393432 -284.288738)
		(width 0.0889)
		(layer "In4.Cu")
		(net "M_J_CPU0_SB_DQ<18>")
	)
	(arc
		(start 388.401814 -284.293564)
		(mid 388.68477 -284.369741)
		(end 388.967726 -284.293564)
		(width 0.0889)
		(layer "In4.Cu")
		(net "M_J_CPU0_SB_DQ<18>")
	)
	(arc
		(start 388.967726 -284.293564)
		(mid 389.149977 -284.243214)
		(end 389.333486 -284.288738)
		(width 0.0889)
		(layer "In4.Cu")
		(net "M_J_CPU0_SB_DQ<18>")
	)
	(arc
		(start 384.641852 -284.293564)
		(mid 384.924808 -284.369741)
		(end 385.207764 -284.293564)
		(width 0.0889)
		(layer "In4.Cu")
		(net "M_J_CPU0_SB_DQ<18>")
	)
	(arc
		(start 387.46176 -284.293564)
		(mid 387.744716 -284.369741)
		(end 388.027672 -284.293564)
		(width 0.0889)
		(layer "In4.Cu")
		(net "M_J_CPU0_SB_DQ<18>")
	)
	(arc
		(start 389.916162 -284.288738)
		(mid 390.09967 -284.243244)
		(end 390.281922 -284.293564)
		(width 0.0889)
		(layer "In4.Cu")
		(net "M_J_CPU0_SB_DQ<18>")
	)
	(arc
		(start 381.456184 -284.288738)
		(mid 381.639692 -284.243244)
		(end 381.821944 -284.293564)
		(width 0.0889)
		(layer "In4.Cu")
		(net "M_J_CPU0_SB_DQ<18>")
	)
	(arc
		(start 387.087872 -284.293564)
		(mid 387.274816 -284.243309)
		(end 387.46176 -284.293564)
		(width 0.0889)
		(layer "In4.Cu")
		(net "M_J_CPU0_SB_DQ<18>")
	)
	(arc
		(start 391.221722 -284.293564)
		(mid 391.504678 -284.369741)
		(end 391.787634 -284.293564)
		(width 0.0889)
		(layer "In4.Cu")
		(net "M_J_CPU0_SB_DQ<18>")
	)
	(arc
		(start 389.341868 -284.293564)
		(mid 389.624824 -284.369741)
		(end 389.90778 -284.293564)
		(width 0.0889)
		(layer "In4.Cu")
		(net "M_J_CPU0_SB_DQ<18>")
	)
	(arc
		(start 386.1562 -284.288738)
		(mid 386.339708 -284.243244)
		(end 386.52196 -284.293564)
		(width 0.0889)
		(layer "In4.Cu")
		(net "M_J_CPU0_SB_DQ<18>")
	)
	(arc
		(start 383.327656 -284.293564)
		(mid 383.509907 -284.243214)
		(end 383.693416 -284.288738)
		(width 0.0889)
		(layer "In4.Cu")
		(net "M_J_CPU0_SB_DQ<18>")
	)
	(arc
		(start 385.216146 -284.288738)
		(mid 385.399654 -284.243244)
		(end 385.581906 -284.293564)
		(width 0.0889)
		(layer "In4.Cu")
		(net "M_J_CPU0_SB_DQ<18>")
	)
	(arc
		(start 386.52196 -284.293564)
		(mid 386.804916 -284.369741)
		(end 387.087872 -284.293564)
		(width 0.0889)
		(layer "In4.Cu")
		(net "M_J_CPU0_SB_DQ<18>")
	)
	(arc
		(start 380.944882 -284.325314)
		(mid 381.20009 -284.368791)
		(end 381.447802 -284.293564)
		(width 0.0889)
		(layer "In4.Cu")
		(net "M_J_CPU0_SB_DQ<18>")
	)
	(arc
		(start 382.761744 -284.293564)
		(mid 383.0447 -284.369741)
		(end 383.327656 -284.293564)
		(width 0.0889)
		(layer "In4.Cu")
		(net "M_J_CPU0_SB_DQ<18>")
	)
	(arc
		(start 384.26771 -284.293564)
		(mid 384.449961 -284.243214)
		(end 384.63347 -284.288738)
		(width 0.0889)
		(layer "In4.Cu")
		(net "M_J_CPU0_SB_DQ<18>")
	)
	(arc
		(start 390.847834 -284.293564)
		(mid 391.034778 -284.243309)
		(end 391.221722 -284.293564)
		(width 0.0889)
		(layer "In4.Cu")
		(net "M_J_CPU0_SB_DQ<18>")
	)
	(arc
		(start 390.281922 -284.293564)
		(mid 390.564878 -284.369741)
		(end 390.847834 -284.293564)
		(width 0.0889)
		(layer "In4.Cu")
		(net "M_J_CPU0_SB_DQ<18>")
	)
	(arc
		(start 381.821944 -284.293564)
		(mid 382.1049 -284.369741)
		(end 382.387856 -284.293564)
		(width 0.0889)
		(layer "In4.Cu")
		(net "M_J_CPU0_SB_DQ<18>")
	)
	(arc
		(start 382.387856 -284.293564)
		(mid 382.5748 -284.243309)
		(end 382.761744 -284.293564)
		(width 0.0889)
		(layer "In4.Cu")
		(net "M_J_CPU0_SB_DQ<18>")
	)
	(arc
		(start 393.10056 -284.293564)
		(mid 393.237582 -284.350775)
		(end 393.384786 -284.370272)
		(width 0.0889)
		(layer "In4.Cu")
		(net "M_J_CPU0_SB_DQ<18>")
	)
	(arc
		(start 385.581906 -284.293564)
		(mid 385.864862 -284.369741)
		(end 386.147818 -284.293564)
		(width 0.0889)
		(layer "In4.Cu")
		(net "M_J_CPU0_SB_DQ<18>")
	)
	(segment
		(start 379.28804 -284.350206)
		(end 379.754892 -284.616144)
		(width 0.10668)
		(layer "F.Cu")
		(net "M_J_CPU0_SB_DQ<17>")
	)
	(segment
		(start 422.480486 -301.460154)
		(end 425.601638 -301.460154)
		(width 0.14478)
		(layer "In4.Cu")
		(net "M_J_CPU0_SB_DQ<17>")
	)
	(segment
		(start 394.6271 -285.22803)
		(end 395.270228 -285.22803)
		(width 0.0889)
		(layer "In4.Cu")
		(net "M_J_CPU0_SB_DQ<17>")
	)
	(segment
		(start 415.032952 -301.460154)
		(end 418.057584 -301.460154)
		(width 0.14478)
		(layer "In4.Cu")
		(net "M_J_CPU0_SB_DQ<17>")
	)
	(segment
		(start 421.630602 -302.310038)
		(end 422.480486 -301.460154)
		(width 0.14478)
		(layer "In4.Cu")
		(net "M_J_CPU0_SB_DQ<17>")
	)
	(segment
		(start 418.057584 -301.460154)
		(end 418.907468 -302.310038)
		(width 0.14478)
		(layer "In4.Cu")
		(net "M_J_CPU0_SB_DQ<17>")
	)
	(segment
		(start 392.718036 -284.932628)
		(end 392.72845 -284.938724)
		(width 0.0889)
		(layer "In4.Cu")
		(net "M_J_CPU0_SB_DQ<17>")
	)
	(segment
		(start 425.601638 -301.460154)
		(end 426.451522 -302.310038)
		(width 0.14478)
		(layer "In4.Cu")
		(net "M_J_CPU0_SB_DQ<17>")
	)
	(segment
		(start 379.754892 -284.616144)
		(end 379.600714 -284.881574)
		(width 0.0889)
		(layer "In4.Cu")
		(net "M_J_CPU0_SB_DQ<17>")
	)
	(segment
		(start 380.873508 -284.94355)
		(end 380.88189 -284.938724)
		(width 0.0889)
		(layer "In4.Cu")
		(net "M_J_CPU0_SB_DQ<17>")
	)
	(segment
		(start 426.451776 -302.309784)
		(end 429.21936 -302.309784)
		(width 0.14478)
		(layer "In4.Cu")
		(net "M_J_CPU0_SB_DQ<17>")
	)
	(segment
		(start 395.270228 -285.22803)
		(end 395.564868 -285.52267)
		(width 0.0889)
		(layer "In4.Cu")
		(net "M_J_CPU0_SB_DQ<17>")
	)
	(segment
		(start 426.451522 -302.310038)
		(end 426.451776 -302.309784)
		(width 0.14478)
		(layer "In4.Cu")
		(net "M_J_CPU0_SB_DQ<17>")
	)
	(segment
		(start 436.361586 -301.955708)
		(end 436.52313 -302.117252)
		(width 0.14478)
		(layer "In4.Cu")
		(net "M_J_CPU0_SB_DQ<17>")
	)
	(segment
		(start 436.200042 -301.4599)
		(end 436.361586 -301.621444)
		(width 0.14478)
		(layer "In4.Cu")
		(net "M_J_CPU0_SB_DQ<17>")
	)
	(segment
		(start 439.100214 -301.884842)
		(end 439.100214 -301.885096)
		(width 0.14478)
		(layer "In4.Cu")
		(net "M_J_CPU0_SB_DQ<17>")
	)
	(segment
		(start 393.086082 -284.947868)
		(end 393.259056 -284.84449)
		(width 0.0889)
		(layer "In4.Cu")
		(net "M_J_CPU0_SB_DQ<17>")
	)
	(segment
		(start 391.787634 -284.938724)
		(end 391.796016 -284.94355)
		(width 0.0889)
		(layer "In4.Cu")
		(net "M_J_CPU0_SB_DQ<17>")
	)
	(segment
		(start 386.147818 -284.938724)
		(end 386.1562 -284.94355)
		(width 0.0889)
		(layer "In4.Cu")
		(net "M_J_CPU0_SB_DQ<17>")
	)
	(segment
		(start 393.259056 -284.84449)
		(end 394.24356 -284.84449)
		(width 0.0889)
		(layer "In4.Cu")
		(net "M_J_CPU0_SB_DQ<17>")
	)
	(segment
		(start 383.693416 -284.94355)
		(end 383.701798 -284.938724)
		(width 0.0889)
		(layer "In4.Cu")
		(net "M_J_CPU0_SB_DQ<17>")
	)
	(segment
		(start 436.361586 -301.621444)
		(end 436.361586 -301.955708)
		(width 0.14478)
		(layer "In4.Cu")
		(net "M_J_CPU0_SB_DQ<17>")
	)
	(segment
		(start 396.45971 -285.52267)
		(end 402.754338 -291.817298)
		(width 0.14478)
		(layer "In4.Cu")
		(net "M_J_CPU0_SB_DQ<17>")
	)
	(segment
		(start 381.447802 -284.938724)
		(end 381.456184 -284.94355)
		(width 0.0889)
		(layer "In4.Cu")
		(net "M_J_CPU0_SB_DQ<17>")
	)
	(segment
		(start 394.24356 -284.84449)
		(end 394.6271 -285.22803)
		(width 0.0889)
		(layer "In4.Cu")
		(net "M_J_CPU0_SB_DQ<17>")
	)
	(segment
		(start 402.754338 -296.560748)
		(end 408.503628 -302.310038)
		(width 0.14478)
		(layer "In4.Cu")
		(net "M_J_CPU0_SB_DQ<17>")
	)
	(segment
		(start 436.91302 -301.621444)
		(end 437.074564 -301.4599)
		(width 0.14478)
		(layer "In4.Cu")
		(net "M_J_CPU0_SB_DQ<17>")
	)
	(segment
		(start 388.393432 -284.94355)
		(end 388.401814 -284.938724)
		(width 0.0889)
		(layer "In4.Cu")
		(net "M_J_CPU0_SB_DQ<17>")
	)
	(segment
		(start 436.91302 -301.955708)
		(end 436.91302 -301.621444)
		(width 0.14478)
		(layer "In4.Cu")
		(net "M_J_CPU0_SB_DQ<17>")
	)
	(segment
		(start 438.675272 -301.4599)
		(end 439.100214 -301.884842)
		(width 0.14478)
		(layer "In4.Cu")
		(net "M_J_CPU0_SB_DQ<17>")
	)
	(segment
		(start 430.069244 -301.4599)
		(end 436.200042 -301.4599)
		(width 0.14478)
		(layer "In4.Cu")
		(net "M_J_CPU0_SB_DQ<17>")
	)
	(segment
		(start 418.907468 -302.310038)
		(end 421.630602 -302.310038)
		(width 0.14478)
		(layer "In4.Cu")
		(net "M_J_CPU0_SB_DQ<17>")
	)
	(segment
		(start 395.564868 -285.52267)
		(end 395.796008 -285.52267)
		(width 0.0889)
		(layer "In4.Cu")
		(net "M_J_CPU0_SB_DQ<17>")
	)
	(segment
		(start 395.796008 -285.52267)
		(end 396.45971 -285.52267)
		(width 0.14478)
		(layer "In4.Cu")
		(net "M_J_CPU0_SB_DQ<17>")
	)
	(segment
		(start 437.074564 -301.4599)
		(end 438.675272 -301.4599)
		(width 0.14478)
		(layer "In4.Cu")
		(net "M_J_CPU0_SB_DQ<17>")
	)
	(segment
		(start 429.21936 -302.309784)
		(end 430.069244 -301.4599)
		(width 0.14478)
		(layer "In4.Cu")
		(net "M_J_CPU0_SB_DQ<17>")
	)
	(segment
		(start 436.52313 -302.117252)
		(end 436.751476 -302.117252)
		(width 0.14478)
		(layer "In4.Cu")
		(net "M_J_CPU0_SB_DQ<17>")
	)
	(segment
		(start 379.600714 -284.881574)
		(end 379.623066 -284.964886)
		(width 0.0889)
		(layer "In4.Cu")
		(net "M_J_CPU0_SB_DQ<17>")
	)
	(segment
		(start 384.63347 -284.94355)
		(end 384.641852 -284.938724)
		(width 0.0889)
		(layer "In4.Cu")
		(net "M_J_CPU0_SB_DQ<17>")
	)
	(segment
		(start 436.751476 -302.117252)
		(end 436.91302 -301.955708)
		(width 0.14478)
		(layer "In4.Cu")
		(net "M_J_CPU0_SB_DQ<17>")
	)
	(segment
		(start 414.183068 -302.310038)
		(end 415.032952 -301.460154)
		(width 0.14478)
		(layer "In4.Cu")
		(net "M_J_CPU0_SB_DQ<17>")
	)
	(segment
		(start 408.503628 -302.310038)
		(end 414.183068 -302.310038)
		(width 0.14478)
		(layer "In4.Cu")
		(net "M_J_CPU0_SB_DQ<17>")
	)
	(segment
		(start 389.90778 -284.938724)
		(end 389.916162 -284.94355)
		(width 0.0889)
		(layer "In4.Cu")
		(net "M_J_CPU0_SB_DQ<17>")
	)
	(segment
		(start 379.933454 -284.94355)
		(end 379.941836 -284.938724)
		(width 0.0889)
		(layer "In4.Cu")
		(net "M_J_CPU0_SB_DQ<17>")
	)
	(segment
		(start 389.333486 -284.94355)
		(end 389.341868 -284.938724)
		(width 0.0889)
		(layer "In4.Cu")
		(net "M_J_CPU0_SB_DQ<17>")
	)
	(segment
		(start 402.754338 -291.817298)
		(end 402.754338 -296.560748)
		(width 0.14478)
		(layer "In4.Cu")
		(net "M_J_CPU0_SB_DQ<17>")
	)
	(segment
		(start 385.207764 -284.938724)
		(end 385.216146 -284.94355)
		(width 0.0889)
		(layer "In4.Cu")
		(net "M_J_CPU0_SB_DQ<17>")
	)
	(arc
		(start 387.46176 -284.938724)
		(mid 387.744716 -284.862547)
		(end 388.027672 -284.938724)
		(width 0.0889)
		(layer "In4.Cu")
		(net "M_J_CPU0_SB_DQ<17>")
	)
	(arc
		(start 385.216146 -284.94355)
		(mid 385.399654 -284.989044)
		(end 385.581906 -284.938724)
		(width 0.0889)
		(layer "In4.Cu")
		(net "M_J_CPU0_SB_DQ<17>")
	)
	(arc
		(start 391.796016 -284.94355)
		(mid 391.979778 -284.989166)
		(end 392.162284 -284.938724)
		(width 0.0889)
		(layer "In4.Cu")
		(net "M_J_CPU0_SB_DQ<17>")
	)
	(arc
		(start 382.387856 -284.938724)
		(mid 382.5748 -284.988979)
		(end 382.761744 -284.938724)
		(width 0.0889)
		(layer "In4.Cu")
		(net "M_J_CPU0_SB_DQ<17>")
	)
	(arc
		(start 385.581906 -284.938724)
		(mid 385.864862 -284.862547)
		(end 386.147818 -284.938724)
		(width 0.0889)
		(layer "In4.Cu")
		(net "M_J_CPU0_SB_DQ<17>")
	)
	(arc
		(start 382.761744 -284.938724)
		(mid 383.0447 -284.862547)
		(end 383.327656 -284.938724)
		(width 0.0889)
		(layer "In4.Cu")
		(net "M_J_CPU0_SB_DQ<17>")
	)
	(arc
		(start 383.327656 -284.938724)
		(mid 383.509907 -284.989074)
		(end 383.693416 -284.94355)
		(width 0.0889)
		(layer "In4.Cu")
		(net "M_J_CPU0_SB_DQ<17>")
	)
	(arc
		(start 389.916162 -284.94355)
		(mid 390.09967 -284.989044)
		(end 390.281922 -284.938724)
		(width 0.0889)
		(layer "In4.Cu")
		(net "M_J_CPU0_SB_DQ<17>")
	)
	(arc
		(start 386.1562 -284.94355)
		(mid 386.339708 -284.989044)
		(end 386.52196 -284.938724)
		(width 0.0889)
		(layer "In4.Cu")
		(net "M_J_CPU0_SB_DQ<17>")
	)
	(arc
		(start 388.027672 -284.938724)
		(mid 388.209923 -284.989074)
		(end 388.393432 -284.94355)
		(width 0.0889)
		(layer "In4.Cu")
		(net "M_J_CPU0_SB_DQ<17>")
	)
	(arc
		(start 392.162284 -284.938724)
		(mid 392.439351 -284.862453)
		(end 392.718036 -284.932628)
		(width 0.0889)
		(layer "In4.Cu")
		(net "M_J_CPU0_SB_DQ<17>")
	)
	(arc
		(start 390.847834 -284.938724)
		(mid 391.034778 -284.988979)
		(end 391.221722 -284.938724)
		(width 0.0889)
		(layer "In4.Cu")
		(net "M_J_CPU0_SB_DQ<17>")
	)
	(arc
		(start 387.087872 -284.938724)
		(mid 387.274816 -284.988979)
		(end 387.46176 -284.938724)
		(width 0.0889)
		(layer "In4.Cu")
		(net "M_J_CPU0_SB_DQ<17>")
	)
	(arc
		(start 389.341868 -284.938724)
		(mid 389.624824 -284.862547)
		(end 389.90778 -284.938724)
		(width 0.0889)
		(layer "In4.Cu")
		(net "M_J_CPU0_SB_DQ<17>")
	)
	(arc
		(start 386.52196 -284.938724)
		(mid 386.804916 -284.862547)
		(end 387.087872 -284.938724)
		(width 0.0889)
		(layer "In4.Cu")
		(net "M_J_CPU0_SB_DQ<17>")
	)
	(arc
		(start 388.967726 -284.938724)
		(mid 389.149977 -284.989074)
		(end 389.333486 -284.94355)
		(width 0.0889)
		(layer "In4.Cu")
		(net "M_J_CPU0_SB_DQ<17>")
	)
	(arc
		(start 383.701798 -284.938724)
		(mid 383.984754 -284.862547)
		(end 384.26771 -284.938724)
		(width 0.0889)
		(layer "In4.Cu")
		(net "M_J_CPU0_SB_DQ<17>")
	)
	(arc
		(start 380.88189 -284.938724)
		(mid 381.164846 -284.862547)
		(end 381.447802 -284.938724)
		(width 0.0889)
		(layer "In4.Cu")
		(net "M_J_CPU0_SB_DQ<17>")
	)
	(arc
		(start 381.456184 -284.94355)
		(mid 381.639692 -284.989044)
		(end 381.821944 -284.938724)
		(width 0.0889)
		(layer "In4.Cu")
		(net "M_J_CPU0_SB_DQ<17>")
	)
	(arc
		(start 384.641852 -284.938724)
		(mid 384.924808 -284.862547)
		(end 385.207764 -284.938724)
		(width 0.0889)
		(layer "In4.Cu")
		(net "M_J_CPU0_SB_DQ<17>")
	)
	(arc
		(start 384.26771 -284.938724)
		(mid 384.449961 -284.989074)
		(end 384.63347 -284.94355)
		(width 0.0889)
		(layer "In4.Cu")
		(net "M_J_CPU0_SB_DQ<17>")
	)
	(arc
		(start 391.221722 -284.938724)
		(mid 391.504678 -284.862547)
		(end 391.787634 -284.938724)
		(width 0.0889)
		(layer "In4.Cu")
		(net "M_J_CPU0_SB_DQ<17>")
	)
	(arc
		(start 392.72845 -284.938724)
		(mid 392.9061 -284.988984)
		(end 393.086082 -284.947868)
		(width 0.0889)
		(layer "In4.Cu")
		(net "M_J_CPU0_SB_DQ<17>")
	)
	(arc
		(start 379.941836 -284.938724)
		(mid 380.224792 -284.862547)
		(end 380.507748 -284.938724)
		(width 0.0889)
		(layer "In4.Cu")
		(net "M_J_CPU0_SB_DQ<17>")
	)
	(arc
		(start 388.401814 -284.938724)
		(mid 388.68477 -284.862547)
		(end 388.967726 -284.938724)
		(width 0.0889)
		(layer "In4.Cu")
		(net "M_J_CPU0_SB_DQ<17>")
	)
	(arc
		(start 381.821944 -284.938724)
		(mid 382.1049 -284.862547)
		(end 382.387856 -284.938724)
		(width 0.0889)
		(layer "In4.Cu")
		(net "M_J_CPU0_SB_DQ<17>")
	)
	(arc
		(start 390.281922 -284.938724)
		(mid 390.564878 -284.862547)
		(end 390.847834 -284.938724)
		(width 0.0889)
		(layer "In4.Cu")
		(net "M_J_CPU0_SB_DQ<17>")
	)
	(arc
		(start 379.623066 -284.964886)
		(mid 379.780576 -284.988084)
		(end 379.933454 -284.94355)
		(width 0.0889)
		(layer "In4.Cu")
		(net "M_J_CPU0_SB_DQ<17>")
	)
	(arc
		(start 380.507748 -284.938724)
		(mid 380.689999 -284.989074)
		(end 380.873508 -284.94355)
		(width 0.0889)
		(layer "In4.Cu")
		(net "M_J_CPU0_SB_DQ<17>")
	)
	(segment
		(start 380.697994 -283.5402)
		(end 381.164846 -283.806138)
		(width 0.10668)
		(layer "F.Cu")
		(net "M_J_CPU0_SB_DQ<16>")
	)
	(segment
		(start 403.653498 -291.444426)
		(end 403.653498 -295.373044)
		(width 0.14478)
		(layer "In4.Cu")
		(net "M_J_CPU0_SB_DQ<16>")
	)
	(segment
		(start 393.384786 -284.179518)
		(end 393.38504 -284.179772)
		(width 0.0889)
		(layer "In4.Cu")
		(net "M_J_CPU0_SB_DQ<16>")
	)
	(segment
		(start 394.287756 -284.179772)
		(end 394.835634 -284.72765)
		(width 0.0889)
		(layer "In4.Cu")
		(net "M_J_CPU0_SB_DQ<16>")
	)
	(segment
		(start 437.77662 -300.479968)
		(end 437.77662 -299.921422)
		(width 0.14478)
		(layer "In4.Cu")
		(net "M_J_CPU0_SB_DQ<16>")
	)
	(segment
		(start 437.225186 -300.479968)
		(end 437.38673 -300.641512)
		(width 0.14478)
		(layer "In4.Cu")
		(net "M_J_CPU0_SB_DQ<16>")
	)
	(segment
		(start 386.983478 -284.133544)
		(end 386.99186 -284.128718)
		(width 0.0889)
		(layer "In4.Cu")
		(net "M_J_CPU0_SB_DQ<16>")
	)
	(segment
		(start 415.032952 -299.760132)
		(end 418.057584 -299.760132)
		(width 0.14478)
		(layer "In4.Cu")
		(net "M_J_CPU0_SB_DQ<16>")
	)
	(segment
		(start 436.122318 -299.921422)
		(end 436.122318 -300.479968)
		(width 0.14478)
		(layer "In4.Cu")
		(net "M_J_CPU0_SB_DQ<16>")
	)
	(segment
		(start 437.938164 -299.759878)
		(end 438.675272 -299.759878)
		(width 0.14478)
		(layer "In4.Cu")
		(net "M_J_CPU0_SB_DQ<16>")
	)
	(segment
		(start 392.256264 -284.128464)
		(end 392.274552 -284.138878)
		(width 0.0889)
		(layer "In4.Cu")
		(net "M_J_CPU0_SB_DQ<16>")
	)
	(segment
		(start 437.38673 -300.641512)
		(end 437.615076 -300.641512)
		(width 0.14478)
		(layer "In4.Cu")
		(net "M_J_CPU0_SB_DQ<16>")
	)
	(segment
		(start 418.907468 -300.610016)
		(end 421.727122 -300.610016)
		(width 0.14478)
		(layer "In4.Cu")
		(net "M_J_CPU0_SB_DQ<16>")
	)
	(segment
		(start 382.283462 -284.133544)
		(end 382.291844 -284.128718)
		(width 0.0889)
		(layer "In4.Cu")
		(net "M_J_CPU0_SB_DQ<16>")
	)
	(segment
		(start 414.183068 -300.610016)
		(end 415.032952 -299.760132)
		(width 0.14478)
		(layer "In4.Cu")
		(net "M_J_CPU0_SB_DQ<16>")
	)
	(segment
		(start 386.043424 -284.133544)
		(end 386.051806 -284.128718)
		(width 0.0889)
		(layer "In4.Cu")
		(net "M_J_CPU0_SB_DQ<16>")
	)
	(segment
		(start 383.79781 -284.128718)
		(end 383.806192 -284.133544)
		(width 0.0889)
		(layer "In4.Cu")
		(net "M_J_CPU0_SB_DQ<16>")
	)
	(segment
		(start 395.313154 -284.61335)
		(end 395.807438 -284.61335)
		(width 0.0889)
		(layer "In4.Cu")
		(net "M_J_CPU0_SB_DQ<16>")
	)
	(segment
		(start 382.857756 -284.128718)
		(end 382.866138 -284.133544)
		(width 0.0889)
		(layer "In4.Cu")
		(net "M_J_CPU0_SB_DQ<16>")
	)
	(segment
		(start 429.301656 -300.609762)
		(end 430.15154 -299.759878)
		(width 0.14478)
		(layer "In4.Cu")
		(net "M_J_CPU0_SB_DQ<16>")
	)
	(segment
		(start 430.15154 -299.759878)
		(end 435.960774 -299.759878)
		(width 0.14478)
		(layer "In4.Cu")
		(net "M_J_CPU0_SB_DQ<16>")
	)
	(segment
		(start 403.653498 -295.373044)
		(end 408.89047 -300.610016)
		(width 0.14478)
		(layer "In4.Cu")
		(net "M_J_CPU0_SB_DQ<16>")
	)
	(segment
		(start 436.835296 -299.759878)
		(end 437.063642 -299.759878)
		(width 0.14478)
		(layer "In4.Cu")
		(net "M_J_CPU0_SB_DQ<16>")
	)
	(segment
		(start 436.283862 -300.641512)
		(end 436.512208 -300.641512)
		(width 0.14478)
		(layer "In4.Cu")
		(net "M_J_CPU0_SB_DQ<16>")
	)
	(segment
		(start 394.835634 -284.72765)
		(end 395.198854 -284.72765)
		(width 0.0889)
		(layer "In4.Cu")
		(net "M_J_CPU0_SB_DQ<16>")
	)
	(segment
		(start 395.807438 -284.61335)
		(end 396.822422 -284.61335)
		(width 0.14478)
		(layer "In4.Cu")
		(net "M_J_CPU0_SB_DQ<16>")
	)
	(segment
		(start 390.74344 -284.133544)
		(end 390.751822 -284.128718)
		(width 0.0889)
		(layer "In4.Cu")
		(net "M_J_CPU0_SB_DQ<16>")
	)
	(segment
		(start 437.77662 -299.921422)
		(end 437.938164 -299.759878)
		(width 0.14478)
		(layer "In4.Cu")
		(net "M_J_CPU0_SB_DQ<16>")
	)
	(segment
		(start 439.100214 -300.18482)
		(end 439.100214 -300.185074)
		(width 0.14478)
		(layer "In4.Cu")
		(net "M_J_CPU0_SB_DQ<16>")
	)
	(segment
		(start 425.62399 -299.760132)
		(end 426.47362 -300.609762)
		(width 0.14478)
		(layer "In4.Cu")
		(net "M_J_CPU0_SB_DQ<16>")
	)
	(segment
		(start 422.577006 -299.760132)
		(end 425.62399 -299.760132)
		(width 0.14478)
		(layer "In4.Cu")
		(net "M_J_CPU0_SB_DQ<16>")
	)
	(segment
		(start 437.615076 -300.641512)
		(end 437.77662 -300.479968)
		(width 0.14478)
		(layer "In4.Cu")
		(net "M_J_CPU0_SB_DQ<16>")
	)
	(segment
		(start 395.198854 -284.72765)
		(end 395.313154 -284.61335)
		(width 0.0889)
		(layer "In4.Cu")
		(net "M_J_CPU0_SB_DQ<16>")
	)
	(segment
		(start 381.164846 -283.806138)
		(end 381.010922 -284.071568)
		(width 0.0889)
		(layer "In4.Cu")
		(net "M_J_CPU0_SB_DQ<16>")
	)
	(segment
		(start 426.47362 -300.609762)
		(end 429.301656 -300.609762)
		(width 0.14478)
		(layer "In4.Cu")
		(net "M_J_CPU0_SB_DQ<16>")
	)
	(segment
		(start 418.057584 -299.760132)
		(end 418.907468 -300.610016)
		(width 0.14478)
		(layer "In4.Cu")
		(net "M_J_CPU0_SB_DQ<16>")
	)
	(segment
		(start 436.673752 -300.479968)
		(end 436.673752 -299.921422)
		(width 0.14478)
		(layer "In4.Cu")
		(net "M_J_CPU0_SB_DQ<16>")
	)
	(segment
		(start 396.822422 -284.61335)
		(end 403.653498 -291.444426)
		(width 0.14478)
		(layer "In4.Cu")
		(net "M_J_CPU0_SB_DQ<16>")
	)
	(segment
		(start 392.234674 -284.116018)
		(end 392.256264 -284.128464)
		(width 0.0889)
		(layer "In4.Cu")
		(net "M_J_CPU0_SB_DQ<16>")
	)
	(segment
		(start 436.673752 -299.921422)
		(end 436.835296 -299.759878)
		(width 0.14478)
		(layer "In4.Cu")
		(net "M_J_CPU0_SB_DQ<16>")
	)
	(segment
		(start 437.225186 -299.921422)
		(end 437.225186 -300.479968)
		(width 0.14478)
		(layer "In4.Cu")
		(net "M_J_CPU0_SB_DQ<16>")
	)
	(segment
		(start 388.497826 -284.128718)
		(end 388.506208 -284.133544)
		(width 0.0889)
		(layer "In4.Cu")
		(net "M_J_CPU0_SB_DQ<16>")
	)
	(segment
		(start 408.89047 -300.610016)
		(end 414.183068 -300.610016)
		(width 0.14478)
		(layer "In4.Cu")
		(net "M_J_CPU0_SB_DQ<16>")
	)
	(segment
		(start 392.62939 -284.128718)
		(end 392.652758 -284.115002)
		(width 0.0889)
		(layer "In4.Cu")
		(net "M_J_CPU0_SB_DQ<16>")
	)
	(segment
		(start 391.317734 -284.128718)
		(end 391.326116 -284.133544)
		(width 0.0889)
		(layer "In4.Cu")
		(net "M_J_CPU0_SB_DQ<16>")
	)
	(segment
		(start 437.063642 -299.759878)
		(end 437.225186 -299.921422)
		(width 0.14478)
		(layer "In4.Cu")
		(net "M_J_CPU0_SB_DQ<16>")
	)
	(segment
		(start 435.960774 -299.759878)
		(end 436.122318 -299.921422)
		(width 0.14478)
		(layer "In4.Cu")
		(net "M_J_CPU0_SB_DQ<16>")
	)
	(segment
		(start 436.512208 -300.641512)
		(end 436.673752 -300.479968)
		(width 0.14478)
		(layer "In4.Cu")
		(net "M_J_CPU0_SB_DQ<16>")
	)
	(segment
		(start 381.010922 -284.071568)
		(end 381.033274 -284.15488)
		(width 0.0889)
		(layer "In4.Cu")
		(net "M_J_CPU0_SB_DQ<16>")
	)
	(segment
		(start 387.557772 -284.128718)
		(end 387.566154 -284.133544)
		(width 0.0889)
		(layer "In4.Cu")
		(net "M_J_CPU0_SB_DQ<16>")
	)
	(segment
		(start 421.727122 -300.610016)
		(end 422.577006 -299.760132)
		(width 0.14478)
		(layer "In4.Cu")
		(net "M_J_CPU0_SB_DQ<16>")
	)
	(segment
		(start 393.38504 -284.179772)
		(end 394.287756 -284.179772)
		(width 0.0889)
		(layer "In4.Cu")
		(net "M_J_CPU0_SB_DQ<16>")
	)
	(segment
		(start 438.675272 -299.759878)
		(end 439.100214 -300.18482)
		(width 0.14478)
		(layer "In4.Cu")
		(net "M_J_CPU0_SB_DQ<16>")
	)
	(segment
		(start 436.122318 -300.479968)
		(end 436.283862 -300.641512)
		(width 0.14478)
		(layer "In4.Cu")
		(net "M_J_CPU0_SB_DQ<16>")
	)
	(arc
		(start 389.43788 -284.128718)
		(mid 389.624824 -284.178973)
		(end 389.811768 -284.128718)
		(width 0.0889)
		(layer "In4.Cu")
		(net "M_J_CPU0_SB_DQ<16>")
	)
	(arc
		(start 382.291844 -284.128718)
		(mid 382.5748 -284.052541)
		(end 382.857756 -284.128718)
		(width 0.0889)
		(layer "In4.Cu")
		(net "M_J_CPU0_SB_DQ<16>")
	)
	(arc
		(start 381.033274 -284.15488)
		(mid 381.195463 -284.177615)
		(end 381.35179 -284.128718)
		(width 0.0889)
		(layer "In4.Cu")
		(net "M_J_CPU0_SB_DQ<16>")
	)
	(arc
		(start 384.171952 -284.128718)
		(mid 384.454908 -284.052541)
		(end 384.737864 -284.128718)
		(width 0.0889)
		(layer "In4.Cu")
		(net "M_J_CPU0_SB_DQ<16>")
	)
	(arc
		(start 390.751822 -284.128718)
		(mid 391.034778 -284.052541)
		(end 391.317734 -284.128718)
		(width 0.0889)
		(layer "In4.Cu")
		(net "M_J_CPU0_SB_DQ<16>")
	)
	(arc
		(start 383.806192 -284.133544)
		(mid 383.9897 -284.179038)
		(end 384.171952 -284.128718)
		(width 0.0889)
		(layer "In4.Cu")
		(net "M_J_CPU0_SB_DQ<16>")
	)
	(arc
		(start 387.931914 -284.128718)
		(mid 388.21487 -284.052541)
		(end 388.497826 -284.128718)
		(width 0.0889)
		(layer "In4.Cu")
		(net "M_J_CPU0_SB_DQ<16>")
	)
	(arc
		(start 391.326116 -284.133544)
		(mid 391.509624 -284.179038)
		(end 391.691876 -284.128718)
		(width 0.0889)
		(layer "In4.Cu")
		(net "M_J_CPU0_SB_DQ<16>")
	)
	(arc
		(start 390.37768 -284.128718)
		(mid 390.559931 -284.179068)
		(end 390.74344 -284.133544)
		(width 0.0889)
		(layer "In4.Cu")
		(net "M_J_CPU0_SB_DQ<16>")
	)
	(arc
		(start 385.677664 -284.128718)
		(mid 385.859915 -284.179068)
		(end 386.043424 -284.133544)
		(width 0.0889)
		(layer "In4.Cu")
		(net "M_J_CPU0_SB_DQ<16>")
	)
	(arc
		(start 387.566154 -284.133544)
		(mid 387.749662 -284.179038)
		(end 387.931914 -284.128718)
		(width 0.0889)
		(layer "In4.Cu")
		(net "M_J_CPU0_SB_DQ<16>")
	)
	(arc
		(start 392.274552 -284.138878)
		(mid 392.453273 -284.178801)
		(end 392.62939 -284.128718)
		(width 0.0889)
		(layer "In4.Cu")
		(net "M_J_CPU0_SB_DQ<16>")
	)
	(arc
		(start 392.652758 -284.115002)
		(mid 392.926412 -284.052059)
		(end 393.196572 -284.128718)
		(width 0.0889)
		(layer "In4.Cu")
		(net "M_J_CPU0_SB_DQ<16>")
	)
	(arc
		(start 381.917702 -284.128718)
		(mid 382.099953 -284.179068)
		(end 382.283462 -284.133544)
		(width 0.0889)
		(layer "In4.Cu")
		(net "M_J_CPU0_SB_DQ<16>")
	)
	(arc
		(start 383.231898 -284.128718)
		(mid 383.514854 -284.052541)
		(end 383.79781 -284.128718)
		(width 0.0889)
		(layer "In4.Cu")
		(net "M_J_CPU0_SB_DQ<16>")
	)
	(arc
		(start 384.737864 -284.128718)
		(mid 384.924808 -284.178973)
		(end 385.111752 -284.128718)
		(width 0.0889)
		(layer "In4.Cu")
		(net "M_J_CPU0_SB_DQ<16>")
	)
	(arc
		(start 388.871968 -284.128718)
		(mid 389.154924 -284.052541)
		(end 389.43788 -284.128718)
		(width 0.0889)
		(layer "In4.Cu")
		(net "M_J_CPU0_SB_DQ<16>")
	)
	(arc
		(start 382.866138 -284.133544)
		(mid 383.049646 -284.179038)
		(end 383.231898 -284.128718)
		(width 0.0889)
		(layer "In4.Cu")
		(net "M_J_CPU0_SB_DQ<16>")
	)
	(arc
		(start 386.99186 -284.128718)
		(mid 387.274816 -284.052541)
		(end 387.557772 -284.128718)
		(width 0.0889)
		(layer "In4.Cu")
		(net "M_J_CPU0_SB_DQ<16>")
	)
	(arc
		(start 385.111752 -284.128718)
		(mid 385.394708 -284.052541)
		(end 385.677664 -284.128718)
		(width 0.0889)
		(layer "In4.Cu")
		(net "M_J_CPU0_SB_DQ<16>")
	)
	(arc
		(start 381.35179 -284.128718)
		(mid 381.634746 -284.052541)
		(end 381.917702 -284.128718)
		(width 0.0889)
		(layer "In4.Cu")
		(net "M_J_CPU0_SB_DQ<16>")
	)
	(arc
		(start 391.691876 -284.128718)
		(mid 391.961645 -284.052695)
		(end 392.234674 -284.116018)
		(width 0.0889)
		(layer "In4.Cu")
		(net "M_J_CPU0_SB_DQ<16>")
	)
	(arc
		(start 393.196572 -284.128718)
		(mid 393.287307 -284.166602)
		(end 393.384786 -284.179518)
		(width 0.0889)
		(layer "In4.Cu")
		(net "M_J_CPU0_SB_DQ<16>")
	)
	(arc
		(start 386.617718 -284.128718)
		(mid 386.799969 -284.179068)
		(end 386.983478 -284.133544)
		(width 0.0889)
		(layer "In4.Cu")
		(net "M_J_CPU0_SB_DQ<16>")
	)
	(arc
		(start 388.506208 -284.133544)
		(mid 388.689716 -284.179038)
		(end 388.871968 -284.128718)
		(width 0.0889)
		(layer "In4.Cu")
		(net "M_J_CPU0_SB_DQ<16>")
	)
	(arc
		(start 389.811768 -284.128718)
		(mid 390.094724 -284.052541)
		(end 390.37768 -284.128718)
		(width 0.0889)
		(layer "In4.Cu")
		(net "M_J_CPU0_SB_DQ<16>")
	)
	(arc
		(start 386.051806 -284.128718)
		(mid 386.334762 -284.052541)
		(end 386.617718 -284.128718)
		(width 0.0889)
		(layer "In4.Cu")
		(net "M_J_CPU0_SB_DQ<16>")
	)
	(segment
		(start 378.817886 -283.5402)
		(end 379.284738 -283.806138)
		(width 0.10668)
		(layer "F.Cu")
		(net "M_J_CPU0_SB_DQ<15>")
	)
	(segment
		(start 429.341026 -299.759878)
		(end 430.190656 -298.910248)
		(width 0.14478)
		(layer "In4.Cu")
		(net "M_J_CPU0_SB_DQ<15>")
	)
	(segment
		(start 394.393928 -283.687266)
		(end 395.21511 -283.687266)
		(width 0.0889)
		(layer "In4.Cu")
		(net "M_J_CPU0_SB_DQ<15>")
	)
	(segment
		(start 386.983478 -283.478732)
		(end 386.99186 -283.483558)
		(width 0.0889)
		(layer "In4.Cu")
		(net "M_J_CPU0_SB_DQ<15>")
	)
	(segment
		(start 417.740338 -298.910248)
		(end 418.122608 -298.910248)
		(width 0.14478)
		(layer "In4.Cu")
		(net "M_J_CPU0_SB_DQ<15>")
	)
	(segment
		(start 414.090104 -299.760386)
		(end 414.940242 -298.910248)
		(width 0.14478)
		(layer "In4.Cu")
		(net "M_J_CPU0_SB_DQ<15>")
	)
	(segment
		(start 386.043424 -283.478732)
		(end 386.051806 -283.483558)
		(width 0.0889)
		(layer "In4.Cu")
		(net "M_J_CPU0_SB_DQ<15>")
	)
	(segment
		(start 422.484296 -298.910248)
		(end 425.594272 -298.910248)
		(width 0.14478)
		(layer "In4.Cu")
		(net "M_J_CPU0_SB_DQ<15>")
	)
	(segment
		(start 388.497826 -283.483558)
		(end 388.506208 -283.478732)
		(width 0.0889)
		(layer "In4.Cu")
		(net "M_J_CPU0_SB_DQ<15>")
	)
	(segment
		(start 412.21406 -299.455332)
		(end 412.519114 -299.760386)
		(width 0.14478)
		(layer "In4.Cu")
		(net "M_J_CPU0_SB_DQ<15>")
	)
	(segment
		(start 414.940242 -298.910248)
		(end 415.78784 -298.910248)
		(width 0.14478)
		(layer "In4.Cu")
		(net "M_J_CPU0_SB_DQ<15>")
	)
	(segment
		(start 393.457938 -283.412692)
		(end 394.119354 -283.412692)
		(width 0.0889)
		(layer "In4.Cu")
		(net "M_J_CPU0_SB_DQ<15>")
	)
	(segment
		(start 395.784578 -284.05709)
		(end 397.045942 -284.05709)
		(width 0.14478)
		(layer "In4.Cu")
		(net "M_J_CPU0_SB_DQ<15>")
	)
	(segment
		(start 434.575204 -298.910248)
		(end 435.000146 -299.33519)
		(width 0.14478)
		(layer "In4.Cu")
		(net "M_J_CPU0_SB_DQ<15>")
	)
	(segment
		(start 418.972746 -299.760386)
		(end 421.634158 -299.760386)
		(width 0.14478)
		(layer "In4.Cu")
		(net "M_J_CPU0_SB_DQ<15>")
	)
	(segment
		(start 392.62431 -283.478732)
		(end 392.632692 -283.483558)
		(width 0.0889)
		(layer "In4.Cu")
		(net "M_J_CPU0_SB_DQ<15>")
	)
	(segment
		(start 411.662626 -299.760386)
		(end 411.96768 -299.455332)
		(width 0.14478)
		(layer "In4.Cu")
		(net "M_J_CPU0_SB_DQ<15>")
	)
	(segment
		(start 397.045942 -284.05709)
		(end 404.204678 -291.215826)
		(width 0.14478)
		(layer "In4.Cu")
		(net "M_J_CPU0_SB_DQ<15>")
	)
	(segment
		(start 413.316928 -299.455332)
		(end 413.621982 -299.760386)
		(width 0.14478)
		(layer "In4.Cu")
		(net "M_J_CPU0_SB_DQ<15>")
	)
	(segment
		(start 395.21511 -283.687266)
		(end 395.584934 -284.05709)
		(width 0.0889)
		(layer "In4.Cu")
		(net "M_J_CPU0_SB_DQ<15>")
	)
	(segment
		(start 410.008324 -299.455332)
		(end 410.313378 -299.760386)
		(width 0.14478)
		(layer "In4.Cu")
		(net "M_J_CPU0_SB_DQ<15>")
	)
	(segment
		(start 413.621982 -299.760386)
		(end 414.090104 -299.760386)
		(width 0.14478)
		(layer "In4.Cu")
		(net "M_J_CPU0_SB_DQ<15>")
	)
	(segment
		(start 413.070548 -299.455332)
		(end 413.316928 -299.455332)
		(width 0.14478)
		(layer "In4.Cu")
		(net "M_J_CPU0_SB_DQ<15>")
	)
	(segment
		(start 383.79781 -283.483558)
		(end 383.806192 -283.478732)
		(width 0.0889)
		(layer "In4.Cu")
		(net "M_J_CPU0_SB_DQ<15>")
	)
	(segment
		(start 416.086036 -298.612052)
		(end 416.339274 -298.612052)
		(width 0.14478)
		(layer "In4.Cu")
		(net "M_J_CPU0_SB_DQ<15>")
	)
	(segment
		(start 380.037848 -283.483558)
		(end 380.04623 -283.478732)
		(width 0.0889)
		(layer "In4.Cu")
		(net "M_J_CPU0_SB_DQ<15>")
	)
	(segment
		(start 417.188904 -298.612052)
		(end 417.442142 -298.612052)
		(width 0.14478)
		(layer "In4.Cu")
		(net "M_J_CPU0_SB_DQ<15>")
	)
	(segment
		(start 379.438916 -283.540708)
		(end 379.535182 -283.515308)
		(width 0.0889)
		(layer "In4.Cu")
		(net "M_J_CPU0_SB_DQ<15>")
	)
	(segment
		(start 390.74344 -283.478732)
		(end 390.751822 -283.483558)
		(width 0.0889)
		(layer "In4.Cu")
		(net "M_J_CPU0_SB_DQ<15>")
	)
	(segment
		(start 417.442142 -298.612052)
		(end 417.740338 -298.910248)
		(width 0.14478)
		(layer "In4.Cu")
		(net "M_J_CPU0_SB_DQ<15>")
	)
	(segment
		(start 432.791362 -298.617132)
		(end 433.084478 -298.910248)
		(width 0.14478)
		(layer "In4.Cu")
		(net "M_J_CPU0_SB_DQ<15>")
	)
	(segment
		(start 433.084478 -298.910248)
		(end 433.342796 -298.910248)
		(width 0.14478)
		(layer "In4.Cu")
		(net "M_J_CPU0_SB_DQ<15>")
	)
	(segment
		(start 434.187346 -298.910248)
		(end 434.575204 -298.910248)
		(width 0.14478)
		(layer "In4.Cu")
		(net "M_J_CPU0_SB_DQ<15>")
	)
	(segment
		(start 416.339274 -298.612052)
		(end 416.63747 -298.910248)
		(width 0.14478)
		(layer "In4.Cu")
		(net "M_J_CPU0_SB_DQ<15>")
	)
	(segment
		(start 430.190656 -298.910248)
		(end 432.239928 -298.910248)
		(width 0.14478)
		(layer "In4.Cu")
		(net "M_J_CPU0_SB_DQ<15>")
	)
	(segment
		(start 391.691876 -283.483558)
		(end 391.70229 -283.489654)
		(width 0.0889)
		(layer "In4.Cu")
		(net "M_J_CPU0_SB_DQ<15>")
	)
	(segment
		(start 415.78784 -298.910248)
		(end 416.086036 -298.612052)
		(width 0.14478)
		(layer "In4.Cu")
		(net "M_J_CPU0_SB_DQ<15>")
	)
	(segment
		(start 410.313378 -299.760386)
		(end 410.559758 -299.760386)
		(width 0.14478)
		(layer "In4.Cu")
		(net "M_J_CPU0_SB_DQ<15>")
	)
	(segment
		(start 382.283462 -283.478732)
		(end 382.291844 -283.483558)
		(width 0.0889)
		(layer "In4.Cu")
		(net "M_J_CPU0_SB_DQ<15>")
	)
	(segment
		(start 411.416246 -299.760386)
		(end 411.662626 -299.760386)
		(width 0.14478)
		(layer "In4.Cu")
		(net "M_J_CPU0_SB_DQ<15>")
	)
	(segment
		(start 382.857756 -283.483558)
		(end 382.866138 -283.478732)
		(width 0.0889)
		(layer "In4.Cu")
		(net "M_J_CPU0_SB_DQ<15>")
	)
	(segment
		(start 409.761944 -299.455332)
		(end 410.008324 -299.455332)
		(width 0.14478)
		(layer "In4.Cu")
		(net "M_J_CPU0_SB_DQ<15>")
	)
	(segment
		(start 379.284738 -283.806138)
		(end 379.438916 -283.540708)
		(width 0.0889)
		(layer "In4.Cu")
		(net "M_J_CPU0_SB_DQ<15>")
	)
	(segment
		(start 387.557772 -283.483558)
		(end 387.566154 -283.478732)
		(width 0.0889)
		(layer "In4.Cu")
		(net "M_J_CPU0_SB_DQ<15>")
	)
	(segment
		(start 432.533044 -298.617132)
		(end 432.791362 -298.617132)
		(width 0.14478)
		(layer "In4.Cu")
		(net "M_J_CPU0_SB_DQ<15>")
	)
	(segment
		(start 391.317734 -283.483558)
		(end 391.326116 -283.478732)
		(width 0.0889)
		(layer "In4.Cu")
		(net "M_J_CPU0_SB_DQ<15>")
	)
	(segment
		(start 416.890708 -298.910248)
		(end 417.188904 -298.612052)
		(width 0.14478)
		(layer "In4.Cu")
		(net "M_J_CPU0_SB_DQ<15>")
	)
	(segment
		(start 425.594272 -298.910248)
		(end 426.443902 -299.759878)
		(width 0.14478)
		(layer "In4.Cu")
		(net "M_J_CPU0_SB_DQ<15>")
	)
	(segment
		(start 394.119354 -283.412692)
		(end 394.393928 -283.687266)
		(width 0.0889)
		(layer "In4.Cu")
		(net "M_J_CPU0_SB_DQ<15>")
	)
	(segment
		(start 432.239928 -298.910248)
		(end 432.533044 -298.617132)
		(width 0.14478)
		(layer "In4.Cu")
		(net "M_J_CPU0_SB_DQ<15>")
	)
	(segment
		(start 433.342796 -298.910248)
		(end 433.635912 -298.617132)
		(width 0.14478)
		(layer "In4.Cu")
		(net "M_J_CPU0_SB_DQ<15>")
	)
	(segment
		(start 433.89423 -298.617132)
		(end 434.187346 -298.910248)
		(width 0.14478)
		(layer "In4.Cu")
		(net "M_J_CPU0_SB_DQ<15>")
	)
	(segment
		(start 404.204678 -291.215826)
		(end 404.204678 -295.144444)
		(width 0.14478)
		(layer "In4.Cu")
		(net "M_J_CPU0_SB_DQ<15>")
	)
	(segment
		(start 433.635912 -298.617132)
		(end 433.89423 -298.617132)
		(width 0.14478)
		(layer "In4.Cu")
		(net "M_J_CPU0_SB_DQ<15>")
	)
	(segment
		(start 412.765494 -299.760386)
		(end 413.070548 -299.455332)
		(width 0.14478)
		(layer "In4.Cu")
		(net "M_J_CPU0_SB_DQ<15>")
	)
	(segment
		(start 410.559758 -299.760386)
		(end 410.864812 -299.455332)
		(width 0.14478)
		(layer "In4.Cu")
		(net "M_J_CPU0_SB_DQ<15>")
	)
	(segment
		(start 411.96768 -299.455332)
		(end 412.21406 -299.455332)
		(width 0.14478)
		(layer "In4.Cu")
		(net "M_J_CPU0_SB_DQ<15>")
	)
	(segment
		(start 410.864812 -299.455332)
		(end 411.111192 -299.455332)
		(width 0.14478)
		(layer "In4.Cu")
		(net "M_J_CPU0_SB_DQ<15>")
	)
	(segment
		(start 408.82062 -299.760386)
		(end 409.45689 -299.760386)
		(width 0.14478)
		(layer "In4.Cu")
		(net "M_J_CPU0_SB_DQ<15>")
	)
	(segment
		(start 409.45689 -299.760386)
		(end 409.761944 -299.455332)
		(width 0.14478)
		(layer "In4.Cu")
		(net "M_J_CPU0_SB_DQ<15>")
	)
	(segment
		(start 412.519114 -299.760386)
		(end 412.765494 -299.760386)
		(width 0.14478)
		(layer "In4.Cu")
		(net "M_J_CPU0_SB_DQ<15>")
	)
	(segment
		(start 418.122608 -298.910248)
		(end 418.972746 -299.760386)
		(width 0.14478)
		(layer "In4.Cu")
		(net "M_J_CPU0_SB_DQ<15>")
	)
	(segment
		(start 395.584934 -284.05709)
		(end 395.784578 -284.05709)
		(width 0.0889)
		(layer "In4.Cu")
		(net "M_J_CPU0_SB_DQ<15>")
	)
	(segment
		(start 421.634158 -299.760386)
		(end 422.484296 -298.910248)
		(width 0.14478)
		(layer "In4.Cu")
		(net "M_J_CPU0_SB_DQ<15>")
	)
	(segment
		(start 404.204678 -295.144444)
		(end 408.82062 -299.760386)
		(width 0.14478)
		(layer "In4.Cu")
		(net "M_J_CPU0_SB_DQ<15>")
	)
	(segment
		(start 411.111192 -299.455332)
		(end 411.416246 -299.760386)
		(width 0.14478)
		(layer "In4.Cu")
		(net "M_J_CPU0_SB_DQ<15>")
	)
	(segment
		(start 416.63747 -298.910248)
		(end 416.890708 -298.910248)
		(width 0.14478)
		(layer "In4.Cu")
		(net "M_J_CPU0_SB_DQ<15>")
	)
	(segment
		(start 426.443902 -299.759878)
		(end 429.341026 -299.759878)
		(width 0.14478)
		(layer "In4.Cu")
		(net "M_J_CPU0_SB_DQ<15>")
	)
	(arc
		(start 380.977902 -283.483558)
		(mid 381.164846 -283.433303)
		(end 381.35179 -283.483558)
		(width 0.0889)
		(layer "In4.Cu")
		(net "M_J_CPU0_SB_DQ<15>")
	)
	(arc
		(start 385.677664 -283.483558)
		(mid 385.859915 -283.433208)
		(end 386.043424 -283.478732)
		(width 0.0889)
		(layer "In4.Cu")
		(net "M_J_CPU0_SB_DQ<15>")
	)
	(arc
		(start 386.617718 -283.483558)
		(mid 386.799969 -283.433208)
		(end 386.983478 -283.478732)
		(width 0.0889)
		(layer "In4.Cu")
		(net "M_J_CPU0_SB_DQ<15>")
	)
	(arc
		(start 389.811768 -283.483558)
		(mid 390.094724 -283.559735)
		(end 390.37768 -283.483558)
		(width 0.0889)
		(layer "In4.Cu")
		(net "M_J_CPU0_SB_DQ<15>")
	)
	(arc
		(start 390.37768 -283.483558)
		(mid 390.559931 -283.433208)
		(end 390.74344 -283.478732)
		(width 0.0889)
		(layer "In4.Cu")
		(net "M_J_CPU0_SB_DQ<15>")
	)
	(arc
		(start 382.866138 -283.478732)
		(mid 383.049646 -283.433238)
		(end 383.231898 -283.483558)
		(width 0.0889)
		(layer "In4.Cu")
		(net "M_J_CPU0_SB_DQ<15>")
	)
	(arc
		(start 388.871968 -283.483558)
		(mid 389.154924 -283.559735)
		(end 389.43788 -283.483558)
		(width 0.0889)
		(layer "In4.Cu")
		(net "M_J_CPU0_SB_DQ<15>")
	)
	(arc
		(start 388.506208 -283.478732)
		(mid 388.689716 -283.433238)
		(end 388.871968 -283.483558)
		(width 0.0889)
		(layer "In4.Cu")
		(net "M_J_CPU0_SB_DQ<15>")
	)
	(arc
		(start 383.231898 -283.483558)
		(mid 383.514854 -283.559735)
		(end 383.79781 -283.483558)
		(width 0.0889)
		(layer "In4.Cu")
		(net "M_J_CPU0_SB_DQ<15>")
	)
	(arc
		(start 382.291844 -283.483558)
		(mid 382.5748 -283.559735)
		(end 382.857756 -283.483558)
		(width 0.0889)
		(layer "In4.Cu")
		(net "M_J_CPU0_SB_DQ<15>")
	)
	(arc
		(start 384.171952 -283.483558)
		(mid 384.454908 -283.559735)
		(end 384.737864 -283.483558)
		(width 0.0889)
		(layer "In4.Cu")
		(net "M_J_CPU0_SB_DQ<15>")
	)
	(arc
		(start 393.192508 -283.487114)
		(mid 393.320105 -283.431649)
		(end 393.457938 -283.412692)
		(width 0.0889)
		(layer "In4.Cu")
		(net "M_J_CPU0_SB_DQ<15>")
	)
	(arc
		(start 391.326116 -283.478732)
		(mid 391.509624 -283.433238)
		(end 391.691876 -283.483558)
		(width 0.0889)
		(layer "In4.Cu")
		(net "M_J_CPU0_SB_DQ<15>")
	)
	(arc
		(start 381.917702 -283.483558)
		(mid 382.099953 -283.433208)
		(end 382.283462 -283.478732)
		(width 0.0889)
		(layer "In4.Cu")
		(net "M_J_CPU0_SB_DQ<15>")
	)
	(arc
		(start 390.751822 -283.483558)
		(mid 391.034778 -283.559735)
		(end 391.317734 -283.483558)
		(width 0.0889)
		(layer "In4.Cu")
		(net "M_J_CPU0_SB_DQ<15>")
	)
	(arc
		(start 383.806192 -283.478732)
		(mid 383.9897 -283.433238)
		(end 384.171952 -283.483558)
		(width 0.0889)
		(layer "In4.Cu")
		(net "M_J_CPU0_SB_DQ<15>")
	)
	(arc
		(start 387.931914 -283.483558)
		(mid 388.21487 -283.559735)
		(end 388.497826 -283.483558)
		(width 0.0889)
		(layer "In4.Cu")
		(net "M_J_CPU0_SB_DQ<15>")
	)
	(arc
		(start 386.051806 -283.483558)
		(mid 386.334762 -283.559735)
		(end 386.617718 -283.483558)
		(width 0.0889)
		(layer "In4.Cu")
		(net "M_J_CPU0_SB_DQ<15>")
	)
	(arc
		(start 391.70229 -283.489654)
		(mid 391.980976 -283.559874)
		(end 392.258042 -283.483558)
		(width 0.0889)
		(layer "In4.Cu")
		(net "M_J_CPU0_SB_DQ<15>")
	)
	(arc
		(start 387.566154 -283.478732)
		(mid 387.749662 -283.433238)
		(end 387.931914 -283.483558)
		(width 0.0889)
		(layer "In4.Cu")
		(net "M_J_CPU0_SB_DQ<15>")
	)
	(arc
		(start 380.41199 -283.483558)
		(mid 380.694946 -283.559735)
		(end 380.977902 -283.483558)
		(width 0.0889)
		(layer "In4.Cu")
		(net "M_J_CPU0_SB_DQ<15>")
	)
	(arc
		(start 381.35179 -283.483558)
		(mid 381.634746 -283.559735)
		(end 381.917702 -283.483558)
		(width 0.0889)
		(layer "In4.Cu")
		(net "M_J_CPU0_SB_DQ<15>")
	)
	(arc
		(start 385.111752 -283.483558)
		(mid 385.394708 -283.559735)
		(end 385.677664 -283.483558)
		(width 0.0889)
		(layer "In4.Cu")
		(net "M_J_CPU0_SB_DQ<15>")
	)
	(arc
		(start 384.737864 -283.483558)
		(mid 384.924808 -283.433303)
		(end 385.111752 -283.483558)
		(width 0.0889)
		(layer "In4.Cu")
		(net "M_J_CPU0_SB_DQ<15>")
	)
	(arc
		(start 392.632692 -283.483558)
		(mid 392.91212 -283.559724)
		(end 393.192508 -283.487114)
		(width 0.0889)
		(layer "In4.Cu")
		(net "M_J_CPU0_SB_DQ<15>")
	)
	(arc
		(start 379.535182 -283.515308)
		(mid 379.790247 -283.558659)
		(end 380.037848 -283.483558)
		(width 0.0889)
		(layer "In4.Cu")
		(net "M_J_CPU0_SB_DQ<15>")
	)
	(arc
		(start 389.43788 -283.483558)
		(mid 389.624824 -283.433303)
		(end 389.811768 -283.483558)
		(width 0.0889)
		(layer "In4.Cu")
		(net "M_J_CPU0_SB_DQ<15>")
	)
	(arc
		(start 392.258042 -283.483558)
		(mid 392.440547 -283.433081)
		(end 392.62431 -283.478732)
		(width 0.0889)
		(layer "In4.Cu")
		(net "M_J_CPU0_SB_DQ<15>")
	)
	(arc
		(start 386.99186 -283.483558)
		(mid 387.274816 -283.559735)
		(end 387.557772 -283.483558)
		(width 0.0889)
		(layer "In4.Cu")
		(net "M_J_CPU0_SB_DQ<15>")
	)
	(arc
		(start 380.04623 -283.478732)
		(mid 380.229738 -283.433238)
		(end 380.41199 -283.483558)
		(width 0.0889)
		(layer "In4.Cu")
		(net "M_J_CPU0_SB_DQ<15>")
	)
	(segment
		(start 380.22784 -282.730194)
		(end 380.694946 -282.996132)
		(width 0.10668)
		(layer "F.Cu")
		(net "M_J_CPU0_SB_DQ<14>")
	)
	(segment
		(start 408.285188 -297.952922)
		(end 408.446732 -298.114466)
		(width 0.14478)
		(layer "In4.Cu")
		(net "M_J_CPU0_SB_DQ<14>")
	)
	(segment
		(start 406.170892 -294.92829)
		(end 406.170892 -295.15689)
		(width 0.14478)
		(layer "In4.Cu")
		(net "M_J_CPU0_SB_DQ<14>")
	)
	(segment
		(start 405.103838 -290.842954)
		(end 405.103838 -293.861236)
		(width 0.14478)
		(layer "In4.Cu")
		(net "M_J_CPU0_SB_DQ<14>")
	)
	(segment
		(start 407.666444 -297.334178)
		(end 407.895044 -297.334178)
		(width 0.14478)
		(layer "In4.Cu")
		(net "M_J_CPU0_SB_DQ<14>")
	)
	(segment
		(start 406.724612 -296.392346)
		(end 406.886156 -296.55389)
		(width 0.14478)
		(layer "In4.Cu")
		(net "M_J_CPU0_SB_DQ<14>")
	)
	(segment
		(start 407.114756 -296.55389)
		(end 407.341324 -296.327322)
		(width 0.14478)
		(layer "In4.Cu")
		(net "M_J_CPU0_SB_DQ<14>")
	)
	(segment
		(start 406.724612 -296.163746)
		(end 406.724612 -296.392346)
		(width 0.14478)
		(layer "In4.Cu")
		(net "M_J_CPU0_SB_DQ<14>")
	)
	(segment
		(start 405.164036 -294.60317)
		(end 405.164036 -294.83177)
		(width 0.14478)
		(layer "In4.Cu")
		(net "M_J_CPU0_SB_DQ<14>")
	)
	(segment
		(start 414.090104 -298.060364)
		(end 414.940242 -297.210226)
		(width 0.14478)
		(layer "In4.Cu")
		(net "M_J_CPU0_SB_DQ<14>")
	)
	(segment
		(start 406.105868 -295.773602)
		(end 406.334468 -295.773602)
		(width 0.14478)
		(layer "In4.Cu")
		(net "M_J_CPU0_SB_DQ<14>")
	)
	(segment
		(start 405.32558 -294.993314)
		(end 405.55418 -294.993314)
		(width 0.14478)
		(layer "In4.Cu")
		(net "M_J_CPU0_SB_DQ<14>")
	)
	(segment
		(start 406.334468 -295.773602)
		(end 406.561036 -295.547034)
		(width 0.14478)
		(layer "In4.Cu")
		(net "M_J_CPU0_SB_DQ<14>")
	)
	(segment
		(start 407.731468 -296.717466)
		(end 407.5049 -296.944034)
		(width 0.14478)
		(layer "In4.Cu")
		(net "M_J_CPU0_SB_DQ<14>")
	)
	(segment
		(start 381.447802 -282.673552)
		(end 381.456184 -282.668726)
		(width 0.0889)
		(layer "In4.Cu")
		(net "M_J_CPU0_SB_DQ<14>")
	)
	(segment
		(start 409.302966 -298.060364)
		(end 414.090104 -298.060364)
		(width 0.14478)
		(layer "In4.Cu")
		(net "M_J_CPU0_SB_DQ<14>")
	)
	(segment
		(start 397.408654 -283.14777)
		(end 405.103838 -290.842954)
		(width 0.14478)
		(layer "In4.Cu")
		(net "M_J_CPU0_SB_DQ<14>")
	)
	(segment
		(start 383.693416 -282.668726)
		(end 383.701798 -282.673552)
		(width 0.0889)
		(layer "In4.Cu")
		(net "M_J_CPU0_SB_DQ<14>")
	)
	(segment
		(start 426.151294 -298.06011)
		(end 429.265334 -298.06011)
		(width 0.14478)
		(layer "In4.Cu")
		(net "M_J_CPU0_SB_DQ<14>")
	)
	(segment
		(start 393.384786 -282.75026)
		(end 394.135864 -282.75026)
		(width 0.0889)
		(layer "In4.Cu")
		(net "M_J_CPU0_SB_DQ<14>")
	)
	(segment
		(start 406.170892 -295.15689)
		(end 405.944324 -295.383458)
		(width 0.14478)
		(layer "In4.Cu")
		(net "M_J_CPU0_SB_DQ<14>")
	)
	(segment
		(start 380.694946 -282.996132)
		(end 380.84887 -282.730702)
		(width 0.0889)
		(layer "In4.Cu")
		(net "M_J_CPU0_SB_DQ<14>")
	)
	(segment
		(start 407.5049 -296.944034)
		(end 407.5049 -297.172634)
		(width 0.14478)
		(layer "In4.Cu")
		(net "M_J_CPU0_SB_DQ<14>")
	)
	(segment
		(start 405.944324 -295.383458)
		(end 405.944324 -295.612058)
		(width 0.14478)
		(layer "In4.Cu")
		(net "M_J_CPU0_SB_DQ<14>")
	)
	(segment
		(start 405.164036 -294.83177)
		(end 405.32558 -294.993314)
		(width 0.14478)
		(layer "In4.Cu")
		(net "M_J_CPU0_SB_DQ<14>")
	)
	(segment
		(start 405.390604 -294.148002)
		(end 405.390604 -294.376602)
		(width 0.14478)
		(layer "In4.Cu")
		(net "M_J_CPU0_SB_DQ<14>")
	)
	(segment
		(start 406.561036 -295.547034)
		(end 406.789636 -295.547034)
		(width 0.14478)
		(layer "In4.Cu")
		(net "M_J_CPU0_SB_DQ<14>")
	)
	(segment
		(start 394.135864 -282.75026)
		(end 394.533374 -283.14777)
		(width 0.0889)
		(layer "In4.Cu")
		(net "M_J_CPU0_SB_DQ<14>")
	)
	(segment
		(start 434.575204 -297.210226)
		(end 435.000146 -297.635168)
		(width 0.14478)
		(layer "In4.Cu")
		(net "M_J_CPU0_SB_DQ<14>")
	)
	(segment
		(start 422.484296 -297.210226)
		(end 425.30141 -297.210226)
		(width 0.14478)
		(layer "In4.Cu")
		(net "M_J_CPU0_SB_DQ<14>")
	)
	(segment
		(start 414.940242 -297.210226)
		(end 417.890452 -297.210226)
		(width 0.14478)
		(layer "In4.Cu")
		(net "M_J_CPU0_SB_DQ<14>")
	)
	(segment
		(start 430.115218 -297.210226)
		(end 434.575204 -297.210226)
		(width 0.14478)
		(layer "In4.Cu")
		(net "M_J_CPU0_SB_DQ<14>")
	)
	(segment
		(start 405.944324 -295.612058)
		(end 406.105868 -295.773602)
		(width 0.14478)
		(layer "In4.Cu")
		(net "M_J_CPU0_SB_DQ<14>")
	)
	(segment
		(start 392.161014 -282.673806)
		(end 392.182604 -282.686252)
		(width 0.0889)
		(layer "In4.Cu")
		(net "M_J_CPU0_SB_DQ<14>")
	)
	(segment
		(start 380.84887 -282.730702)
		(end 380.944882 -282.705302)
		(width 0.0889)
		(layer "In4.Cu")
		(net "M_J_CPU0_SB_DQ<14>")
	)
	(segment
		(start 408.285188 -297.724322)
		(end 408.285188 -297.952922)
		(width 0.14478)
		(layer "In4.Cu")
		(net "M_J_CPU0_SB_DQ<14>")
	)
	(segment
		(start 406.789636 -295.547034)
		(end 406.95118 -295.708578)
		(width 0.14478)
		(layer "In4.Cu")
		(net "M_J_CPU0_SB_DQ<14>")
	)
	(segment
		(start 408.121612 -297.10761)
		(end 408.350212 -297.10761)
		(width 0.14478)
		(layer "In4.Cu")
		(net "M_J_CPU0_SB_DQ<14>")
	)
	(segment
		(start 406.009348 -294.766746)
		(end 406.170892 -294.92829)
		(width 0.14478)
		(layer "In4.Cu")
		(net "M_J_CPU0_SB_DQ<14>")
	)
	(segment
		(start 384.63347 -282.668726)
		(end 384.641852 -282.673552)
		(width 0.0889)
		(layer "In4.Cu")
		(net "M_J_CPU0_SB_DQ<14>")
	)
	(segment
		(start 417.890452 -297.210226)
		(end 418.74059 -298.060364)
		(width 0.14478)
		(layer "In4.Cu")
		(net "M_J_CPU0_SB_DQ<14>")
	)
	(segment
		(start 421.634158 -298.060364)
		(end 422.484296 -297.210226)
		(width 0.14478)
		(layer "In4.Cu")
		(net "M_J_CPU0_SB_DQ<14>")
	)
	(segment
		(start 406.886156 -296.55389)
		(end 407.114756 -296.55389)
		(width 0.14478)
		(layer "In4.Cu")
		(net "M_J_CPU0_SB_DQ<14>")
	)
	(segment
		(start 389.333486 -282.668726)
		(end 389.341868 -282.673552)
		(width 0.0889)
		(layer "In4.Cu")
		(net "M_J_CPU0_SB_DQ<14>")
	)
	(segment
		(start 408.511756 -297.269154)
		(end 408.511756 -297.497754)
		(width 0.14478)
		(layer "In4.Cu")
		(net "M_J_CPU0_SB_DQ<14>")
	)
	(segment
		(start 407.731468 -296.488866)
		(end 407.731468 -296.717466)
		(width 0.14478)
		(layer "In4.Cu")
		(net "M_J_CPU0_SB_DQ<14>")
	)
	(segment
		(start 407.341324 -296.327322)
		(end 407.569924 -296.327322)
		(width 0.14478)
		(layer "In4.Cu")
		(net "M_J_CPU0_SB_DQ<14>")
	)
	(segment
		(start 405.55418 -294.993314)
		(end 405.780748 -294.766746)
		(width 0.14478)
		(layer "In4.Cu")
		(net "M_J_CPU0_SB_DQ<14>")
	)
	(segment
		(start 408.9019 -297.887898)
		(end 409.1305 -297.887898)
		(width 0.14478)
		(layer "In4.Cu")
		(net "M_J_CPU0_SB_DQ<14>")
	)
	(segment
		(start 405.780748 -294.766746)
		(end 406.009348 -294.766746)
		(width 0.14478)
		(layer "In4.Cu")
		(net "M_J_CPU0_SB_DQ<14>")
	)
	(segment
		(start 408.446732 -298.114466)
		(end 408.675332 -298.114466)
		(width 0.14478)
		(layer "In4.Cu")
		(net "M_J_CPU0_SB_DQ<14>")
	)
	(segment
		(start 407.5049 -297.172634)
		(end 407.666444 -297.334178)
		(width 0.14478)
		(layer "In4.Cu")
		(net "M_J_CPU0_SB_DQ<14>")
	)
	(segment
		(start 418.74059 -298.060364)
		(end 421.634158 -298.060364)
		(width 0.14478)
		(layer "In4.Cu")
		(net "M_J_CPU0_SB_DQ<14>")
	)
	(segment
		(start 392.140948 -282.662376)
		(end 392.161014 -282.673806)
		(width 0.0889)
		(layer "In4.Cu")
		(net "M_J_CPU0_SB_DQ<14>")
	)
	(segment
		(start 407.569924 -296.327322)
		(end 407.731468 -296.488866)
		(width 0.14478)
		(layer "In4.Cu")
		(net "M_J_CPU0_SB_DQ<14>")
	)
	(segment
		(start 388.393432 -282.668726)
		(end 388.401814 -282.673552)
		(width 0.0889)
		(layer "In4.Cu")
		(net "M_J_CPU0_SB_DQ<14>")
	)
	(segment
		(start 386.147818 -282.673552)
		(end 386.1562 -282.668726)
		(width 0.0889)
		(layer "In4.Cu")
		(net "M_J_CPU0_SB_DQ<14>")
	)
	(segment
		(start 392.725402 -282.673552)
		(end 392.744198 -282.66263)
		(width 0.0889)
		(layer "In4.Cu")
		(net "M_J_CPU0_SB_DQ<14>")
	)
	(segment
		(start 395.75613 -283.14777)
		(end 397.408654 -283.14777)
		(width 0.14478)
		(layer "In4.Cu")
		(net "M_J_CPU0_SB_DQ<14>")
	)
	(segment
		(start 407.895044 -297.334178)
		(end 408.121612 -297.10761)
		(width 0.14478)
		(layer "In4.Cu")
		(net "M_J_CPU0_SB_DQ<14>")
	)
	(segment
		(start 425.30141 -297.210226)
		(end 426.151294 -298.06011)
		(width 0.14478)
		(layer "In4.Cu")
		(net "M_J_CPU0_SB_DQ<14>")
	)
	(segment
		(start 406.95118 -295.708578)
		(end 406.95118 -295.937178)
		(width 0.14478)
		(layer "In4.Cu")
		(net "M_J_CPU0_SB_DQ<14>")
	)
	(segment
		(start 385.207764 -282.673552)
		(end 385.216146 -282.668726)
		(width 0.0889)
		(layer "In4.Cu")
		(net "M_J_CPU0_SB_DQ<14>")
	)
	(segment
		(start 406.95118 -295.937178)
		(end 406.724612 -296.163746)
		(width 0.14478)
		(layer "In4.Cu")
		(net "M_J_CPU0_SB_DQ<14>")
	)
	(segment
		(start 408.511756 -297.497754)
		(end 408.285188 -297.724322)
		(width 0.14478)
		(layer "In4.Cu")
		(net "M_J_CPU0_SB_DQ<14>")
	)
	(segment
		(start 408.675332 -298.114466)
		(end 408.9019 -297.887898)
		(width 0.14478)
		(layer "In4.Cu")
		(net "M_J_CPU0_SB_DQ<14>")
	)
	(segment
		(start 394.533374 -283.14777)
		(end 395.75613 -283.14777)
		(width 0.0889)
		(layer "In4.Cu")
		(net "M_J_CPU0_SB_DQ<14>")
	)
	(segment
		(start 405.103838 -293.861236)
		(end 405.390604 -294.148002)
		(width 0.14478)
		(layer "In4.Cu")
		(net "M_J_CPU0_SB_DQ<14>")
	)
	(segment
		(start 409.1305 -297.887898)
		(end 409.302966 -298.060364)
		(width 0.14478)
		(layer "In4.Cu")
		(net "M_J_CPU0_SB_DQ<14>")
	)
	(segment
		(start 408.350212 -297.10761)
		(end 408.511756 -297.269154)
		(width 0.14478)
		(layer "In4.Cu")
		(net "M_J_CPU0_SB_DQ<14>")
	)
	(segment
		(start 429.265334 -298.06011)
		(end 430.115218 -297.210226)
		(width 0.14478)
		(layer "In4.Cu")
		(net "M_J_CPU0_SB_DQ<14>")
	)
	(segment
		(start 389.90778 -282.673552)
		(end 389.916162 -282.668726)
		(width 0.0889)
		(layer "In4.Cu")
		(net "M_J_CPU0_SB_DQ<14>")
	)
	(segment
		(start 405.390604 -294.376602)
		(end 405.164036 -294.60317)
		(width 0.14478)
		(layer "In4.Cu")
		(net "M_J_CPU0_SB_DQ<14>")
	)
	(arc
		(start 383.701798 -282.673552)
		(mid 383.984754 -282.749729)
		(end 384.26771 -282.673552)
		(width 0.0889)
		(layer "In4.Cu")
		(net "M_J_CPU0_SB_DQ<14>")
	)
	(arc
		(start 382.761744 -282.673552)
		(mid 383.0447 -282.749729)
		(end 383.327656 -282.673552)
		(width 0.0889)
		(layer "In4.Cu")
		(net "M_J_CPU0_SB_DQ<14>")
	)
	(arc
		(start 380.944882 -282.705302)
		(mid 381.20009 -282.748779)
		(end 381.447802 -282.673552)
		(width 0.0889)
		(layer "In4.Cu")
		(net "M_J_CPU0_SB_DQ<14>")
	)
	(arc
		(start 384.26771 -282.673552)
		(mid 384.449961 -282.623202)
		(end 384.63347 -282.668726)
		(width 0.0889)
		(layer "In4.Cu")
		(net "M_J_CPU0_SB_DQ<14>")
	)
	(arc
		(start 385.216146 -282.668726)
		(mid 385.399654 -282.623232)
		(end 385.581906 -282.673552)
		(width 0.0889)
		(layer "In4.Cu")
		(net "M_J_CPU0_SB_DQ<14>")
	)
	(arc
		(start 386.52196 -282.673552)
		(mid 386.804916 -282.749729)
		(end 387.087872 -282.673552)
		(width 0.0889)
		(layer "In4.Cu")
		(net "M_J_CPU0_SB_DQ<14>")
	)
	(arc
		(start 383.327656 -282.673552)
		(mid 383.509907 -282.623202)
		(end 383.693416 -282.668726)
		(width 0.0889)
		(layer "In4.Cu")
		(net "M_J_CPU0_SB_DQ<14>")
	)
	(arc
		(start 386.1562 -282.668726)
		(mid 386.339708 -282.623232)
		(end 386.52196 -282.673552)
		(width 0.0889)
		(layer "In4.Cu")
		(net "M_J_CPU0_SB_DQ<14>")
	)
	(arc
		(start 390.847834 -282.673552)
		(mid 391.034778 -282.623297)
		(end 391.221722 -282.673552)
		(width 0.0889)
		(layer "In4.Cu")
		(net "M_J_CPU0_SB_DQ<14>")
	)
	(arc
		(start 389.916162 -282.668726)
		(mid 390.09967 -282.623232)
		(end 390.281922 -282.673552)
		(width 0.0889)
		(layer "In4.Cu")
		(net "M_J_CPU0_SB_DQ<14>")
	)
	(arc
		(start 392.182604 -282.686252)
		(mid 392.455633 -282.749571)
		(end 392.725402 -282.673552)
		(width 0.0889)
		(layer "In4.Cu")
		(net "M_J_CPU0_SB_DQ<14>")
	)
	(arc
		(start 385.581906 -282.673552)
		(mid 385.864862 -282.749729)
		(end 386.147818 -282.673552)
		(width 0.0889)
		(layer "In4.Cu")
		(net "M_J_CPU0_SB_DQ<14>")
	)
	(arc
		(start 387.46176 -282.673552)
		(mid 387.744716 -282.749729)
		(end 388.027672 -282.673552)
		(width 0.0889)
		(layer "In4.Cu")
		(net "M_J_CPU0_SB_DQ<14>")
	)
	(arc
		(start 388.027672 -282.673552)
		(mid 388.209923 -282.623202)
		(end 388.393432 -282.668726)
		(width 0.0889)
		(layer "In4.Cu")
		(net "M_J_CPU0_SB_DQ<14>")
	)
	(arc
		(start 381.821944 -282.673552)
		(mid 382.1049 -282.749729)
		(end 382.387856 -282.673552)
		(width 0.0889)
		(layer "In4.Cu")
		(net "M_J_CPU0_SB_DQ<14>")
	)
	(arc
		(start 381.456184 -282.668726)
		(mid 381.639692 -282.623232)
		(end 381.821944 -282.673552)
		(width 0.0889)
		(layer "In4.Cu")
		(net "M_J_CPU0_SB_DQ<14>")
	)
	(arc
		(start 390.281922 -282.673552)
		(mid 390.564878 -282.749729)
		(end 390.847834 -282.673552)
		(width 0.0889)
		(layer "In4.Cu")
		(net "M_J_CPU0_SB_DQ<14>")
	)
	(arc
		(start 388.967726 -282.673552)
		(mid 389.149977 -282.623202)
		(end 389.333486 -282.668726)
		(width 0.0889)
		(layer "In4.Cu")
		(net "M_J_CPU0_SB_DQ<14>")
	)
	(arc
		(start 393.10056 -282.673552)
		(mid 393.237582 -282.730763)
		(end 393.384786 -282.75026)
		(width 0.0889)
		(layer "In4.Cu")
		(net "M_J_CPU0_SB_DQ<14>")
	)
	(arc
		(start 387.087872 -282.673552)
		(mid 387.274816 -282.623297)
		(end 387.46176 -282.673552)
		(width 0.0889)
		(layer "In4.Cu")
		(net "M_J_CPU0_SB_DQ<14>")
	)
	(arc
		(start 388.401814 -282.673552)
		(mid 388.68477 -282.749729)
		(end 388.967726 -282.673552)
		(width 0.0889)
		(layer "In4.Cu")
		(net "M_J_CPU0_SB_DQ<14>")
	)
	(arc
		(start 391.787634 -282.673552)
		(mid 391.962873 -282.623481)
		(end 392.140948 -282.662376)
		(width 0.0889)
		(layer "In4.Cu")
		(net "M_J_CPU0_SB_DQ<14>")
	)
	(arc
		(start 391.221722 -282.673552)
		(mid 391.504678 -282.749729)
		(end 391.787634 -282.673552)
		(width 0.0889)
		(layer "In4.Cu")
		(net "M_J_CPU0_SB_DQ<14>")
	)
	(arc
		(start 382.387856 -282.673552)
		(mid 382.5748 -282.623297)
		(end 382.761744 -282.673552)
		(width 0.0889)
		(layer "In4.Cu")
		(net "M_J_CPU0_SB_DQ<14>")
	)
	(arc
		(start 389.341868 -282.673552)
		(mid 389.624824 -282.749729)
		(end 389.90778 -282.673552)
		(width 0.0889)
		(layer "In4.Cu")
		(net "M_J_CPU0_SB_DQ<14>")
	)
	(arc
		(start 392.744198 -282.66263)
		(mid 392.923769 -282.622813)
		(end 393.10056 -282.673552)
		(width 0.0889)
		(layer "In4.Cu")
		(net "M_J_CPU0_SB_DQ<14>")
	)
	(arc
		(start 384.641852 -282.673552)
		(mid 384.924808 -282.749729)
		(end 385.207764 -282.673552)
		(width 0.0889)
		(layer "In4.Cu")
		(net "M_J_CPU0_SB_DQ<14>")
	)
	(segment
		(start 379.28804 -282.730194)
		(end 379.754892 -282.996132)
		(width 0.10668)
		(layer "F.Cu")
		(net "M_J_CPU0_SB_DQ<13>")
	)
	(segment
		(start 392.718036 -283.312616)
		(end 392.72845 -283.318712)
		(width 0.0889)
		(layer "In4.Cu")
		(net "M_J_CPU0_SB_DQ<13>")
	)
	(segment
		(start 394.429234 -283.40685)
		(end 395.318234 -283.40685)
		(width 0.0889)
		(layer "In4.Cu")
		(net "M_J_CPU0_SB_DQ<13>")
	)
	(segment
		(start 389.333486 -283.323538)
		(end 389.341868 -283.318712)
		(width 0.0889)
		(layer "In4.Cu")
		(net "M_J_CPU0_SB_DQ<13>")
	)
	(segment
		(start 417.553902 -298.060364)
		(end 419.605714 -298.910248)
		(width 0.14478)
		(layer "In4.Cu")
		(net "M_J_CPU0_SB_DQ<13>")
	)
	(segment
		(start 421.142922 -298.910248)
		(end 423.194734 -298.060364)
		(width 0.14478)
		(layer "In4.Cu")
		(net "M_J_CPU0_SB_DQ<13>")
	)
	(segment
		(start 395.513814 -283.60243)
		(end 395.835886 -283.60243)
		(width 0.0889)
		(layer "In4.Cu")
		(net "M_J_CPU0_SB_DQ<13>")
	)
	(segment
		(start 404.654258 -291.02939)
		(end 404.654258 -294.958008)
		(width 0.14478)
		(layer "In4.Cu")
		(net "M_J_CPU0_SB_DQ<13>")
	)
	(segment
		(start 423.194734 -298.060364)
		(end 424.860212 -298.060364)
		(width 0.14478)
		(layer "In4.Cu")
		(net "M_J_CPU0_SB_DQ<13>")
	)
	(segment
		(start 395.318234 -283.40685)
		(end 395.513814 -283.60243)
		(width 0.0889)
		(layer "In4.Cu")
		(net "M_J_CPU0_SB_DQ<13>")
	)
	(segment
		(start 415.66084 -298.060364)
		(end 417.553902 -298.060364)
		(width 0.14478)
		(layer "In4.Cu")
		(net "M_J_CPU0_SB_DQ<13>")
	)
	(segment
		(start 397.227298 -283.60243)
		(end 404.654258 -291.02939)
		(width 0.14478)
		(layer "In4.Cu")
		(net "M_J_CPU0_SB_DQ<13>")
	)
	(segment
		(start 384.63347 -283.323538)
		(end 384.641852 -283.318712)
		(width 0.0889)
		(layer "In4.Cu")
		(net "M_J_CPU0_SB_DQ<13>")
	)
	(segment
		(start 394.214096 -283.191712)
		(end 394.429234 -283.40685)
		(width 0.0889)
		(layer "In4.Cu")
		(net "M_J_CPU0_SB_DQ<13>")
	)
	(segment
		(start 383.693416 -283.323538)
		(end 383.701798 -283.318712)
		(width 0.0889)
		(layer "In4.Cu")
		(net "M_J_CPU0_SB_DQ<13>")
	)
	(segment
		(start 391.787634 -283.318712)
		(end 391.796016 -283.323538)
		(width 0.0889)
		(layer "In4.Cu")
		(net "M_J_CPU0_SB_DQ<13>")
	)
	(segment
		(start 413.609028 -298.910248)
		(end 415.66084 -298.060364)
		(width 0.14478)
		(layer "In4.Cu")
		(net "M_J_CPU0_SB_DQ<13>")
	)
	(segment
		(start 430.881536 -298.06011)
		(end 436.96382 -298.06011)
		(width 0.14478)
		(layer "In4.Cu")
		(net "M_J_CPU0_SB_DQ<13>")
	)
	(segment
		(start 395.835886 -283.60243)
		(end 397.227298 -283.60243)
		(width 0.14478)
		(layer "In4.Cu")
		(net "M_J_CPU0_SB_DQ<13>")
	)
	(segment
		(start 379.600714 -283.261562)
		(end 379.623066 -283.344874)
		(width 0.0889)
		(layer "In4.Cu")
		(net "M_J_CPU0_SB_DQ<13>")
	)
	(segment
		(start 389.90778 -283.318712)
		(end 389.916162 -283.323538)
		(width 0.0889)
		(layer "In4.Cu")
		(net "M_J_CPU0_SB_DQ<13>")
	)
	(segment
		(start 426.911516 -298.909994)
		(end 428.829724 -298.909994)
		(width 0.14478)
		(layer "In4.Cu")
		(net "M_J_CPU0_SB_DQ<13>")
	)
	(segment
		(start 379.754892 -282.996132)
		(end 379.600714 -283.261562)
		(width 0.0889)
		(layer "In4.Cu")
		(net "M_J_CPU0_SB_DQ<13>")
	)
	(segment
		(start 436.96382 -298.06011)
		(end 439.100214 -298.485052)
		(width 0.14478)
		(layer "In4.Cu")
		(net "M_J_CPU0_SB_DQ<13>")
	)
	(segment
		(start 419.605714 -298.910248)
		(end 421.142922 -298.910248)
		(width 0.14478)
		(layer "In4.Cu")
		(net "M_J_CPU0_SB_DQ<13>")
	)
	(segment
		(start 424.860212 -298.060364)
		(end 426.911516 -298.909994)
		(width 0.14478)
		(layer "In4.Cu")
		(net "M_J_CPU0_SB_DQ<13>")
	)
	(segment
		(start 388.393432 -283.323538)
		(end 388.401814 -283.318712)
		(width 0.0889)
		(layer "In4.Cu")
		(net "M_J_CPU0_SB_DQ<13>")
	)
	(segment
		(start 393.561062 -283.191712)
		(end 394.214096 -283.191712)
		(width 0.0889)
		(layer "In4.Cu")
		(net "M_J_CPU0_SB_DQ<13>")
	)
	(segment
		(start 381.447802 -283.318712)
		(end 381.456184 -283.323538)
		(width 0.0889)
		(layer "In4.Cu")
		(net "M_J_CPU0_SB_DQ<13>")
	)
	(segment
		(start 385.207764 -283.318712)
		(end 385.216146 -283.323538)
		(width 0.0889)
		(layer "In4.Cu")
		(net "M_J_CPU0_SB_DQ<13>")
	)
	(segment
		(start 380.873508 -283.323538)
		(end 380.88189 -283.318712)
		(width 0.0889)
		(layer "In4.Cu")
		(net "M_J_CPU0_SB_DQ<13>")
	)
	(segment
		(start 404.654258 -294.958008)
		(end 408.606498 -298.910248)
		(width 0.14478)
		(layer "In4.Cu")
		(net "M_J_CPU0_SB_DQ<13>")
	)
	(segment
		(start 379.933454 -283.323538)
		(end 379.941836 -283.318712)
		(width 0.0889)
		(layer "In4.Cu")
		(net "M_J_CPU0_SB_DQ<13>")
	)
	(segment
		(start 428.829724 -298.909994)
		(end 430.881536 -298.06011)
		(width 0.14478)
		(layer "In4.Cu")
		(net "M_J_CPU0_SB_DQ<13>")
	)
	(segment
		(start 408.606498 -298.910248)
		(end 413.609028 -298.910248)
		(width 0.14478)
		(layer "In4.Cu")
		(net "M_J_CPU0_SB_DQ<13>")
	)
	(segment
		(start 386.147818 -283.318712)
		(end 386.1562 -283.323538)
		(width 0.0889)
		(layer "In4.Cu")
		(net "M_J_CPU0_SB_DQ<13>")
	)
	(arc
		(start 391.796016 -283.323538)
		(mid 391.979778 -283.369154)
		(end 392.162284 -283.318712)
		(width 0.0889)
		(layer "In4.Cu")
		(net "M_J_CPU0_SB_DQ<13>")
	)
	(arc
		(start 387.087872 -283.318712)
		(mid 387.274816 -283.368967)
		(end 387.46176 -283.318712)
		(width 0.0889)
		(layer "In4.Cu")
		(net "M_J_CPU0_SB_DQ<13>")
	)
	(arc
		(start 392.162284 -283.318712)
		(mid 392.439351 -283.242441)
		(end 392.718036 -283.312616)
		(width 0.0889)
		(layer "In4.Cu")
		(net "M_J_CPU0_SB_DQ<13>")
	)
	(arc
		(start 384.641852 -283.318712)
		(mid 384.924808 -283.242535)
		(end 385.207764 -283.318712)
		(width 0.0889)
		(layer "In4.Cu")
		(net "M_J_CPU0_SB_DQ<13>")
	)
	(arc
		(start 386.1562 -283.323538)
		(mid 386.339708 -283.369032)
		(end 386.52196 -283.318712)
		(width 0.0889)
		(layer "In4.Cu")
		(net "M_J_CPU0_SB_DQ<13>")
	)
	(arc
		(start 387.46176 -283.318712)
		(mid 387.744716 -283.242535)
		(end 388.027672 -283.318712)
		(width 0.0889)
		(layer "In4.Cu")
		(net "M_J_CPU0_SB_DQ<13>")
	)
	(arc
		(start 385.216146 -283.323538)
		(mid 385.399654 -283.369032)
		(end 385.581906 -283.318712)
		(width 0.0889)
		(layer "In4.Cu")
		(net "M_J_CPU0_SB_DQ<13>")
	)
	(arc
		(start 392.72845 -283.318712)
		(mid 392.9061 -283.368972)
		(end 393.086082 -283.327856)
		(width 0.0889)
		(layer "In4.Cu")
		(net "M_J_CPU0_SB_DQ<13>")
	)
	(arc
		(start 388.967726 -283.318712)
		(mid 389.149977 -283.369062)
		(end 389.333486 -283.323538)
		(width 0.0889)
		(layer "In4.Cu")
		(net "M_J_CPU0_SB_DQ<13>")
	)
	(arc
		(start 379.623066 -283.344874)
		(mid 379.780576 -283.368072)
		(end 379.933454 -283.323538)
		(width 0.0889)
		(layer "In4.Cu")
		(net "M_J_CPU0_SB_DQ<13>")
	)
	(arc
		(start 385.581906 -283.318712)
		(mid 385.864862 -283.242535)
		(end 386.147818 -283.318712)
		(width 0.0889)
		(layer "In4.Cu")
		(net "M_J_CPU0_SB_DQ<13>")
	)
	(arc
		(start 389.916162 -283.323538)
		(mid 390.09967 -283.369032)
		(end 390.281922 -283.318712)
		(width 0.0889)
		(layer "In4.Cu")
		(net "M_J_CPU0_SB_DQ<13>")
	)
	(arc
		(start 380.88189 -283.318712)
		(mid 381.164846 -283.242535)
		(end 381.447802 -283.318712)
		(width 0.0889)
		(layer "In4.Cu")
		(net "M_J_CPU0_SB_DQ<13>")
	)
	(arc
		(start 382.387856 -283.318712)
		(mid 382.5748 -283.368967)
		(end 382.761744 -283.318712)
		(width 0.0889)
		(layer "In4.Cu")
		(net "M_J_CPU0_SB_DQ<13>")
	)
	(arc
		(start 379.941836 -283.318712)
		(mid 380.224792 -283.242535)
		(end 380.507748 -283.318712)
		(width 0.0889)
		(layer "In4.Cu")
		(net "M_J_CPU0_SB_DQ<13>")
	)
	(arc
		(start 390.847834 -283.318712)
		(mid 391.034778 -283.368967)
		(end 391.221722 -283.318712)
		(width 0.0889)
		(layer "In4.Cu")
		(net "M_J_CPU0_SB_DQ<13>")
	)
	(arc
		(start 388.027672 -283.318712)
		(mid 388.209923 -283.369062)
		(end 388.393432 -283.323538)
		(width 0.0889)
		(layer "In4.Cu")
		(net "M_J_CPU0_SB_DQ<13>")
	)
	(arc
		(start 386.52196 -283.318712)
		(mid 386.804916 -283.242535)
		(end 387.087872 -283.318712)
		(width 0.0889)
		(layer "In4.Cu")
		(net "M_J_CPU0_SB_DQ<13>")
	)
	(arc
		(start 382.761744 -283.318712)
		(mid 383.0447 -283.242535)
		(end 383.327656 -283.318712)
		(width 0.0889)
		(layer "In4.Cu")
		(net "M_J_CPU0_SB_DQ<13>")
	)
	(arc
		(start 389.341868 -283.318712)
		(mid 389.624824 -283.242535)
		(end 389.90778 -283.318712)
		(width 0.0889)
		(layer "In4.Cu")
		(net "M_J_CPU0_SB_DQ<13>")
	)
	(arc
		(start 383.327656 -283.318712)
		(mid 383.509907 -283.369062)
		(end 383.693416 -283.323538)
		(width 0.0889)
		(layer "In4.Cu")
		(net "M_J_CPU0_SB_DQ<13>")
	)
	(arc
		(start 388.401814 -283.318712)
		(mid 388.68477 -283.242535)
		(end 388.967726 -283.318712)
		(width 0.0889)
		(layer "In4.Cu")
		(net "M_J_CPU0_SB_DQ<13>")
	)
	(arc
		(start 383.701798 -283.318712)
		(mid 383.984754 -283.242535)
		(end 384.26771 -283.318712)
		(width 0.0889)
		(layer "In4.Cu")
		(net "M_J_CPU0_SB_DQ<13>")
	)
	(arc
		(start 380.507748 -283.318712)
		(mid 380.689999 -283.369062)
		(end 380.873508 -283.323538)
		(width 0.0889)
		(layer "In4.Cu")
		(net "M_J_CPU0_SB_DQ<13>")
	)
	(arc
		(start 393.086082 -283.327856)
		(mid 393.314019 -283.226476)
		(end 393.561062 -283.191712)
		(width 0.0889)
		(layer "In4.Cu")
		(net "M_J_CPU0_SB_DQ<13>")
	)
	(arc
		(start 381.456184 -283.323538)
		(mid 381.639692 -283.369032)
		(end 381.821944 -283.318712)
		(width 0.0889)
		(layer "In4.Cu")
		(net "M_J_CPU0_SB_DQ<13>")
	)
	(arc
		(start 384.26771 -283.318712)
		(mid 384.449961 -283.369062)
		(end 384.63347 -283.323538)
		(width 0.0889)
		(layer "In4.Cu")
		(net "M_J_CPU0_SB_DQ<13>")
	)
	(arc
		(start 390.281922 -283.318712)
		(mid 390.564878 -283.242535)
		(end 390.847834 -283.318712)
		(width 0.0889)
		(layer "In4.Cu")
		(net "M_J_CPU0_SB_DQ<13>")
	)
	(arc
		(start 381.821944 -283.318712)
		(mid 382.1049 -283.242535)
		(end 382.387856 -283.318712)
		(width 0.0889)
		(layer "In4.Cu")
		(net "M_J_CPU0_SB_DQ<13>")
	)
	(arc
		(start 391.221722 -283.318712)
		(mid 391.504678 -283.242535)
		(end 391.787634 -283.318712)
		(width 0.0889)
		(layer "In4.Cu")
		(net "M_J_CPU0_SB_DQ<13>")
	)
	(segment
		(start 380.697994 -281.920188)
		(end 381.164846 -282.186126)
		(width 0.10668)
		(layer "F.Cu")
		(net "M_J_CPU0_SB_DQ<12>")
	)
	(segment
		(start 425.390564 -296.36974)
		(end 426.240448 -297.219624)
		(width 0.14478)
		(layer "In4.Cu")
		(net "M_J_CPU0_SB_DQ<12>")
	)
	(segment
		(start 391.317734 -282.508706)
		(end 391.326116 -282.513532)
		(width 0.0889)
		(layer "In4.Cu")
		(net "M_J_CPU0_SB_DQ<12>")
	)
	(segment
		(start 418.550344 -297.219878)
		(end 421.71747 -297.219878)
		(width 0.14478)
		(layer "In4.Cu")
		(net "M_J_CPU0_SB_DQ<12>")
	)
	(segment
		(start 405.553418 -293.674546)
		(end 409.089098 -297.210226)
		(width 0.14478)
		(layer "In4.Cu")
		(net "M_J_CPU0_SB_DQ<12>")
	)
	(segment
		(start 386.043424 -282.513532)
		(end 386.051806 -282.508706)
		(width 0.0889)
		(layer "In4.Cu")
		(net "M_J_CPU0_SB_DQ<12>")
	)
	(segment
		(start 429.198532 -297.219624)
		(end 430.048416 -296.36974)
		(width 0.14478)
		(layer "In4.Cu")
		(net "M_J_CPU0_SB_DQ<12>")
	)
	(segment
		(start 437.926988 -296.36974)
		(end 438.684924 -296.36974)
		(width 0.14478)
		(layer "In4.Cu")
		(net "M_J_CPU0_SB_DQ<12>")
	)
	(segment
		(start 392.62939 -282.508706)
		(end 392.652758 -282.49499)
		(width 0.0889)
		(layer "In4.Cu")
		(net "M_J_CPU0_SB_DQ<12>")
	)
	(segment
		(start 394.236956 -282.55976)
		(end 394.446506 -282.35021)
		(width 0.0889)
		(layer "In4.Cu")
		(net "M_J_CPU0_SB_DQ<12>")
	)
	(segment
		(start 437.21401 -296.531284)
		(end 437.21401 -296.896028)
		(width 0.14478)
		(layer "In4.Cu")
		(net "M_J_CPU0_SB_DQ<12>")
	)
	(segment
		(start 437.765444 -296.896028)
		(end 437.765444 -296.531284)
		(width 0.14478)
		(layer "In4.Cu")
		(net "M_J_CPU0_SB_DQ<12>")
	)
	(segment
		(start 381.010922 -282.451556)
		(end 381.033274 -282.534868)
		(width 0.0889)
		(layer "In4.Cu")
		(net "M_J_CPU0_SB_DQ<12>")
	)
	(segment
		(start 414.183068 -297.210226)
		(end 415.032952 -296.360342)
		(width 0.14478)
		(layer "In4.Cu")
		(net "M_J_CPU0_SB_DQ<12>")
	)
	(segment
		(start 426.240448 -297.219624)
		(end 429.198532 -297.219624)
		(width 0.14478)
		(layer "In4.Cu")
		(net "M_J_CPU0_SB_DQ<12>")
	)
	(segment
		(start 393.384786 -282.559506)
		(end 393.38504 -282.55976)
		(width 0.0889)
		(layer "In4.Cu")
		(net "M_J_CPU0_SB_DQ<12>")
	)
	(segment
		(start 422.567608 -296.36974)
		(end 425.390564 -296.36974)
		(width 0.14478)
		(layer "In4.Cu")
		(net "M_J_CPU0_SB_DQ<12>")
	)
	(segment
		(start 393.38504 -282.55976)
		(end 394.236956 -282.55976)
		(width 0.0889)
		(layer "In4.Cu")
		(net "M_J_CPU0_SB_DQ<12>")
	)
	(segment
		(start 415.032952 -296.360342)
		(end 417.690808 -296.360342)
		(width 0.14478)
		(layer "In4.Cu")
		(net "M_J_CPU0_SB_DQ<12>")
	)
	(segment
		(start 381.164846 -282.186126)
		(end 381.010922 -282.451556)
		(width 0.0889)
		(layer "In4.Cu")
		(net "M_J_CPU0_SB_DQ<12>")
	)
	(segment
		(start 417.690808 -296.360342)
		(end 418.550344 -297.219878)
		(width 0.14478)
		(layer "In4.Cu")
		(net "M_J_CPU0_SB_DQ<12>")
	)
	(segment
		(start 392.234674 -282.496006)
		(end 392.256264 -282.508452)
		(width 0.0889)
		(layer "In4.Cu")
		(net "M_J_CPU0_SB_DQ<12>")
	)
	(segment
		(start 438.684924 -296.36974)
		(end 439.100214 -296.78503)
		(width 0.14478)
		(layer "In4.Cu")
		(net "M_J_CPU0_SB_DQ<12>")
	)
	(segment
		(start 383.79781 -282.508706)
		(end 383.806192 -282.513532)
		(width 0.0889)
		(layer "In4.Cu")
		(net "M_J_CPU0_SB_DQ<12>")
	)
	(segment
		(start 386.983478 -282.513532)
		(end 386.99186 -282.508706)
		(width 0.0889)
		(layer "In4.Cu")
		(net "M_J_CPU0_SB_DQ<12>")
	)
	(segment
		(start 421.71747 -297.219878)
		(end 422.567608 -296.36974)
		(width 0.14478)
		(layer "In4.Cu")
		(net "M_J_CPU0_SB_DQ<12>")
	)
	(segment
		(start 390.74344 -282.513532)
		(end 390.751822 -282.508706)
		(width 0.0889)
		(layer "In4.Cu")
		(net "M_J_CPU0_SB_DQ<12>")
	)
	(segment
		(start 382.283462 -282.513532)
		(end 382.291844 -282.508706)
		(width 0.0889)
		(layer "In4.Cu")
		(net "M_J_CPU0_SB_DQ<12>")
	)
	(segment
		(start 437.375554 -297.057572)
		(end 437.6039 -297.057572)
		(width 0.14478)
		(layer "In4.Cu")
		(net "M_J_CPU0_SB_DQ<12>")
	)
	(segment
		(start 394.446506 -282.35021)
		(end 395.214602 -282.35021)
		(width 0.0889)
		(layer "In4.Cu")
		(net "M_J_CPU0_SB_DQ<12>")
	)
	(segment
		(start 395.214602 -282.35021)
		(end 395.557502 -282.69311)
		(width 0.0889)
		(layer "In4.Cu")
		(net "M_J_CPU0_SB_DQ<12>")
	)
	(segment
		(start 430.048416 -296.36974)
		(end 437.052466 -296.36974)
		(width 0.14478)
		(layer "In4.Cu")
		(net "M_J_CPU0_SB_DQ<12>")
	)
	(segment
		(start 437.765444 -296.531284)
		(end 437.926988 -296.36974)
		(width 0.14478)
		(layer "In4.Cu")
		(net "M_J_CPU0_SB_DQ<12>")
	)
	(segment
		(start 395.557502 -282.69311)
		(end 395.835886 -282.69311)
		(width 0.0889)
		(layer "In4.Cu")
		(net "M_J_CPU0_SB_DQ<12>")
	)
	(segment
		(start 397.59001 -282.69311)
		(end 405.553418 -290.656518)
		(width 0.14478)
		(layer "In4.Cu")
		(net "M_J_CPU0_SB_DQ<12>")
	)
	(segment
		(start 437.6039 -297.057572)
		(end 437.765444 -296.896028)
		(width 0.14478)
		(layer "In4.Cu")
		(net "M_J_CPU0_SB_DQ<12>")
	)
	(segment
		(start 405.553418 -290.656518)
		(end 405.553418 -293.674546)
		(width 0.14478)
		(layer "In4.Cu")
		(net "M_J_CPU0_SB_DQ<12>")
	)
	(segment
		(start 388.497826 -282.508706)
		(end 388.506208 -282.513532)
		(width 0.0889)
		(layer "In4.Cu")
		(net "M_J_CPU0_SB_DQ<12>")
	)
	(segment
		(start 395.835886 -282.69311)
		(end 397.59001 -282.69311)
		(width 0.14478)
		(layer "In4.Cu")
		(net "M_J_CPU0_SB_DQ<12>")
	)
	(segment
		(start 437.052466 -296.36974)
		(end 437.21401 -296.531284)
		(width 0.14478)
		(layer "In4.Cu")
		(net "M_J_CPU0_SB_DQ<12>")
	)
	(segment
		(start 382.857756 -282.508706)
		(end 382.866138 -282.513532)
		(width 0.0889)
		(layer "In4.Cu")
		(net "M_J_CPU0_SB_DQ<12>")
	)
	(segment
		(start 409.089098 -297.210226)
		(end 414.183068 -297.210226)
		(width 0.14478)
		(layer "In4.Cu")
		(net "M_J_CPU0_SB_DQ<12>")
	)
	(segment
		(start 392.256264 -282.508452)
		(end 392.274552 -282.518866)
		(width 0.0889)
		(layer "In4.Cu")
		(net "M_J_CPU0_SB_DQ<12>")
	)
	(segment
		(start 387.557772 -282.508706)
		(end 387.566154 -282.513532)
		(width 0.0889)
		(layer "In4.Cu")
		(net "M_J_CPU0_SB_DQ<12>")
	)
	(segment
		(start 437.21401 -296.896028)
		(end 437.375554 -297.057572)
		(width 0.14478)
		(layer "In4.Cu")
		(net "M_J_CPU0_SB_DQ<12>")
	)
	(arc
		(start 388.506208 -282.513532)
		(mid 388.689716 -282.559026)
		(end 388.871968 -282.508706)
		(width 0.0889)
		(layer "In4.Cu")
		(net "M_J_CPU0_SB_DQ<12>")
	)
	(arc
		(start 392.274552 -282.518866)
		(mid 392.453273 -282.558789)
		(end 392.62939 -282.508706)
		(width 0.0889)
		(layer "In4.Cu")
		(net "M_J_CPU0_SB_DQ<12>")
	)
	(arc
		(start 393.196572 -282.508706)
		(mid 393.287307 -282.54659)
		(end 393.384786 -282.559506)
		(width 0.0889)
		(layer "In4.Cu")
		(net "M_J_CPU0_SB_DQ<12>")
	)
	(arc
		(start 388.871968 -282.508706)
		(mid 389.154924 -282.432529)
		(end 389.43788 -282.508706)
		(width 0.0889)
		(layer "In4.Cu")
		(net "M_J_CPU0_SB_DQ<12>")
	)
	(arc
		(start 381.35179 -282.508706)
		(mid 381.634746 -282.432529)
		(end 381.917702 -282.508706)
		(width 0.0889)
		(layer "In4.Cu")
		(net "M_J_CPU0_SB_DQ<12>")
	)
	(arc
		(start 387.566154 -282.513532)
		(mid 387.749662 -282.559026)
		(end 387.931914 -282.508706)
		(width 0.0889)
		(layer "In4.Cu")
		(net "M_J_CPU0_SB_DQ<12>")
	)
	(arc
		(start 386.99186 -282.508706)
		(mid 387.274816 -282.432529)
		(end 387.557772 -282.508706)
		(width 0.0889)
		(layer "In4.Cu")
		(net "M_J_CPU0_SB_DQ<12>")
	)
	(arc
		(start 386.617718 -282.508706)
		(mid 386.799969 -282.559056)
		(end 386.983478 -282.513532)
		(width 0.0889)
		(layer "In4.Cu")
		(net "M_J_CPU0_SB_DQ<12>")
	)
	(arc
		(start 382.866138 -282.513532)
		(mid 383.049646 -282.559026)
		(end 383.231898 -282.508706)
		(width 0.0889)
		(layer "In4.Cu")
		(net "M_J_CPU0_SB_DQ<12>")
	)
	(arc
		(start 385.111752 -282.508706)
		(mid 385.394708 -282.432529)
		(end 385.677664 -282.508706)
		(width 0.0889)
		(layer "In4.Cu")
		(net "M_J_CPU0_SB_DQ<12>")
	)
	(arc
		(start 381.033274 -282.534868)
		(mid 381.195463 -282.557603)
		(end 381.35179 -282.508706)
		(width 0.0889)
		(layer "In4.Cu")
		(net "M_J_CPU0_SB_DQ<12>")
	)
	(arc
		(start 389.811768 -282.508706)
		(mid 390.094724 -282.432529)
		(end 390.37768 -282.508706)
		(width 0.0889)
		(layer "In4.Cu")
		(net "M_J_CPU0_SB_DQ<12>")
	)
	(arc
		(start 392.652758 -282.49499)
		(mid 392.926412 -282.432047)
		(end 393.196572 -282.508706)
		(width 0.0889)
		(layer "In4.Cu")
		(net "M_J_CPU0_SB_DQ<12>")
	)
	(arc
		(start 383.231898 -282.508706)
		(mid 383.514854 -282.432529)
		(end 383.79781 -282.508706)
		(width 0.0889)
		(layer "In4.Cu")
		(net "M_J_CPU0_SB_DQ<12>")
	)
	(arc
		(start 386.051806 -282.508706)
		(mid 386.334762 -282.432529)
		(end 386.617718 -282.508706)
		(width 0.0889)
		(layer "In4.Cu")
		(net "M_J_CPU0_SB_DQ<12>")
	)
	(arc
		(start 390.37768 -282.508706)
		(mid 390.559931 -282.559056)
		(end 390.74344 -282.513532)
		(width 0.0889)
		(layer "In4.Cu")
		(net "M_J_CPU0_SB_DQ<12>")
	)
	(arc
		(start 391.326116 -282.513532)
		(mid 391.509624 -282.559026)
		(end 391.691876 -282.508706)
		(width 0.0889)
		(layer "In4.Cu")
		(net "M_J_CPU0_SB_DQ<12>")
	)
	(arc
		(start 391.691876 -282.508706)
		(mid 391.961645 -282.432683)
		(end 392.234674 -282.496006)
		(width 0.0889)
		(layer "In4.Cu")
		(net "M_J_CPU0_SB_DQ<12>")
	)
	(arc
		(start 384.737864 -282.508706)
		(mid 384.924808 -282.558961)
		(end 385.111752 -282.508706)
		(width 0.0889)
		(layer "In4.Cu")
		(net "M_J_CPU0_SB_DQ<12>")
	)
	(arc
		(start 382.291844 -282.508706)
		(mid 382.5748 -282.432529)
		(end 382.857756 -282.508706)
		(width 0.0889)
		(layer "In4.Cu")
		(net "M_J_CPU0_SB_DQ<12>")
	)
	(arc
		(start 387.931914 -282.508706)
		(mid 388.21487 -282.432529)
		(end 388.497826 -282.508706)
		(width 0.0889)
		(layer "In4.Cu")
		(net "M_J_CPU0_SB_DQ<12>")
	)
	(arc
		(start 384.171952 -282.508706)
		(mid 384.454908 -282.432529)
		(end 384.737864 -282.508706)
		(width 0.0889)
		(layer "In4.Cu")
		(net "M_J_CPU0_SB_DQ<12>")
	)
	(arc
		(start 383.806192 -282.513532)
		(mid 383.9897 -282.559026)
		(end 384.171952 -282.508706)
		(width 0.0889)
		(layer "In4.Cu")
		(net "M_J_CPU0_SB_DQ<12>")
	)
	(arc
		(start 389.43788 -282.508706)
		(mid 389.624824 -282.558961)
		(end 389.811768 -282.508706)
		(width 0.0889)
		(layer "In4.Cu")
		(net "M_J_CPU0_SB_DQ<12>")
	)
	(arc
		(start 390.751822 -282.508706)
		(mid 391.034778 -282.432529)
		(end 391.317734 -282.508706)
		(width 0.0889)
		(layer "In4.Cu")
		(net "M_J_CPU0_SB_DQ<12>")
	)
	(arc
		(start 385.677664 -282.508706)
		(mid 385.859915 -282.559056)
		(end 386.043424 -282.513532)
		(width 0.0889)
		(layer "In4.Cu")
		(net "M_J_CPU0_SB_DQ<12>")
	)
	(arc
		(start 381.917702 -282.508706)
		(mid 382.099953 -282.559056)
		(end 382.283462 -282.513532)
		(width 0.0889)
		(layer "In4.Cu")
		(net "M_J_CPU0_SB_DQ<12>")
	)
	(segment
		(start 378.817886 -280.300176)
		(end 379.284738 -280.566114)
		(width 0.10668)
		(layer "F.Cu")
		(net "M_J_CPU0_SB_DQ<11>")
	)
	(segment
		(start 409.754832 -292.073584)
		(end 409.754832 -292.302184)
		(width 0.14478)
		(layer "In4.Cu")
		(net "M_J_CPU0_SB_DQ<11>")
	)
	(segment
		(start 433.183284 -292.950392)
		(end 433.445158 -292.950392)
		(width 0.14478)
		(layer "In4.Cu")
		(net "M_J_CPU0_SB_DQ<11>")
	)
	(segment
		(start 418.714936 -293.800276)
		(end 421.480488 -293.800276)
		(width 0.14478)
		(layer "In4.Cu")
		(net "M_J_CPU0_SB_DQ<11>")
	)
	(segment
		(start 390.74344 -280.238708)
		(end 390.751822 -280.243534)
		(width 0.0889)
		(layer "In4.Cu")
		(net "M_J_CPU0_SB_DQ<11>")
	)
	(segment
		(start 408.018742 -291.46881)
		(end 408.247342 -291.46881)
		(width 0.14478)
		(layer "In4.Cu")
		(net "M_J_CPU0_SB_DQ<11>")
	)
	(segment
		(start 387.557772 -280.243534)
		(end 387.566154 -280.238708)
		(width 0.0889)
		(layer "In4.Cu")
		(net "M_J_CPU0_SB_DQ<11>")
	)
	(segment
		(start 408.194256 -290.741608)
		(end 407.857198 -291.078666)
		(width 0.14478)
		(layer "In4.Cu")
		(net "M_J_CPU0_SB_DQ<11>")
	)
	(segment
		(start 391.691876 -280.243534)
		(end 391.70229 -280.24963)
		(width 0.0889)
		(layer "In4.Cu")
		(net "M_J_CPU0_SB_DQ<11>")
	)
	(segment
		(start 410.53512 -293.082472)
		(end 410.198062 -293.41953)
		(width 0.14478)
		(layer "In4.Cu")
		(net "M_J_CPU0_SB_DQ<11>")
	)
	(segment
		(start 425.63415 -292.950392)
		(end 426.484034 -293.800276)
		(width 0.14478)
		(layer "In4.Cu")
		(net "M_J_CPU0_SB_DQ<11>")
	)
	(segment
		(start 408.79903 -292.249098)
		(end 409.02763 -292.249098)
		(width 0.14478)
		(layer "In4.Cu")
		(net "M_J_CPU0_SB_DQ<11>")
	)
	(segment
		(start 409.579318 -293.029386)
		(end 409.807918 -293.029386)
		(width 0.14478)
		(layer "In4.Cu")
		(net "M_J_CPU0_SB_DQ<11>")
	)
	(segment
		(start 409.754832 -292.302184)
		(end 409.417774 -292.639242)
		(width 0.14478)
		(layer "In4.Cu")
		(net "M_J_CPU0_SB_DQ<11>")
	)
	(segment
		(start 388.497826 -280.243534)
		(end 388.506208 -280.238708)
		(width 0.0889)
		(layer "In4.Cu")
		(net "M_J_CPU0_SB_DQ<11>")
	)
	(segment
		(start 382.283462 -280.238708)
		(end 382.291844 -280.243534)
		(width 0.0889)
		(layer "In4.Cu")
		(net "M_J_CPU0_SB_DQ<11>")
	)
	(segment
		(start 409.02763 -292.249098)
		(end 409.364688 -291.91204)
		(width 0.14478)
		(layer "In4.Cu")
		(net "M_J_CPU0_SB_DQ<11>")
	)
	(segment
		(start 379.438916 -280.300684)
		(end 379.535182 -280.275284)
		(width 0.0889)
		(layer "In4.Cu")
		(net "M_J_CPU0_SB_DQ<11>")
	)
	(segment
		(start 408.637486 -292.087554)
		(end 408.79903 -292.249098)
		(width 0.14478)
		(layer "In4.Cu")
		(net "M_J_CPU0_SB_DQ<11>")
	)
	(segment
		(start 407.841958 -289.707574)
		(end 407.841958 -290.16071)
		(width 0.14478)
		(layer "In4.Cu")
		(net "M_J_CPU0_SB_DQ<11>")
	)
	(segment
		(start 426.484034 -293.800276)
		(end 429.08728 -293.800276)
		(width 0.14478)
		(layer "In4.Cu")
		(net "M_J_CPU0_SB_DQ<11>")
	)
	(segment
		(start 410.359606 -293.809674)
		(end 410.680408 -293.809674)
		(width 0.14478)
		(layer "In4.Cu")
		(net "M_J_CPU0_SB_DQ<11>")
	)
	(segment
		(start 408.974544 -291.521896)
		(end 408.637486 -291.858954)
		(width 0.14478)
		(layer "In4.Cu")
		(net "M_J_CPU0_SB_DQ<11>")
	)
	(segment
		(start 410.144976 -292.692328)
		(end 410.373576 -292.692328)
		(width 0.14478)
		(layer "In4.Cu")
		(net "M_J_CPU0_SB_DQ<11>")
	)
	(segment
		(start 398.334484 -280.2001)
		(end 407.841958 -289.707574)
		(width 0.14478)
		(layer "In4.Cu")
		(net "M_J_CPU0_SB_DQ<11>")
	)
	(segment
		(start 408.813 -291.131752)
		(end 408.974544 -291.293296)
		(width 0.14478)
		(layer "In4.Cu")
		(net "M_J_CPU0_SB_DQ<11>")
	)
	(segment
		(start 410.373576 -292.692328)
		(end 410.53512 -292.853872)
		(width 0.14478)
		(layer "In4.Cu")
		(net "M_J_CPU0_SB_DQ<11>")
	)
	(segment
		(start 408.194256 -290.513008)
		(end 408.194256 -290.741608)
		(width 0.14478)
		(layer "In4.Cu")
		(net "M_J_CPU0_SB_DQ<11>")
	)
	(segment
		(start 380.037848 -280.243534)
		(end 380.04623 -280.238708)
		(width 0.0889)
		(layer "In4.Cu")
		(net "M_J_CPU0_SB_DQ<11>")
	)
	(segment
		(start 395.75613 -280.2001)
		(end 398.334484 -280.2001)
		(width 0.14478)
		(layer "In4.Cu")
		(net "M_J_CPU0_SB_DQ<11>")
	)
	(segment
		(start 382.857756 -280.243534)
		(end 382.866138 -280.238708)
		(width 0.0889)
		(layer "In4.Cu")
		(net "M_J_CPU0_SB_DQ<11>")
	)
	(segment
		(start 408.5844 -291.131752)
		(end 408.813 -291.131752)
		(width 0.14478)
		(layer "In4.Cu")
		(net "M_J_CPU0_SB_DQ<11>")
	)
	(segment
		(start 407.857198 -291.307266)
		(end 408.018742 -291.46881)
		(width 0.14478)
		(layer "In4.Cu")
		(net "M_J_CPU0_SB_DQ<11>")
	)
	(segment
		(start 395.748764 -280.192734)
		(end 395.75613 -280.2001)
		(width 0.0889)
		(layer "In4.Cu")
		(net "M_J_CPU0_SB_DQ<11>")
	)
	(segment
		(start 407.841958 -290.16071)
		(end 408.194256 -290.513008)
		(width 0.14478)
		(layer "In4.Cu")
		(net "M_J_CPU0_SB_DQ<11>")
	)
	(segment
		(start 433.996592 -292.660832)
		(end 434.286152 -292.950392)
		(width 0.14478)
		(layer "In4.Cu")
		(net "M_J_CPU0_SB_DQ<11>")
	)
	(segment
		(start 433.445158 -292.950392)
		(end 433.734718 -292.660832)
		(width 0.14478)
		(layer "In4.Cu")
		(net "M_J_CPU0_SB_DQ<11>")
	)
	(segment
		(start 409.417774 -292.639242)
		(end 409.417774 -292.867842)
		(width 0.14478)
		(layer "In4.Cu")
		(net "M_J_CPU0_SB_DQ<11>")
	)
	(segment
		(start 410.198062 -293.64813)
		(end 410.359606 -293.809674)
		(width 0.14478)
		(layer "In4.Cu")
		(net "M_J_CPU0_SB_DQ<11>")
	)
	(segment
		(start 422.330372 -292.950392)
		(end 425.63415 -292.950392)
		(width 0.14478)
		(layer "In4.Cu")
		(net "M_J_CPU0_SB_DQ<11>")
	)
	(segment
		(start 393.384786 -280.192734)
		(end 395.748764 -280.192734)
		(width 0.0889)
		(layer "In4.Cu")
		(net "M_J_CPU0_SB_DQ<11>")
	)
	(segment
		(start 409.417774 -292.867842)
		(end 409.579318 -293.029386)
		(width 0.14478)
		(layer "In4.Cu")
		(net "M_J_CPU0_SB_DQ<11>")
	)
	(segment
		(start 421.480488 -293.800276)
		(end 422.330372 -292.950392)
		(width 0.14478)
		(layer "In4.Cu")
		(net "M_J_CPU0_SB_DQ<11>")
	)
	(segment
		(start 410.925264 -293.564818)
		(end 414.265872 -293.564818)
		(width 0.14478)
		(layer "In4.Cu")
		(net "M_J_CPU0_SB_DQ<11>")
	)
	(segment
		(start 414.265872 -293.564818)
		(end 414.870646 -292.960044)
		(width 0.14478)
		(layer "In4.Cu")
		(net "M_J_CPU0_SB_DQ<11>")
	)
	(segment
		(start 429.08728 -293.800276)
		(end 429.937164 -292.950392)
		(width 0.14478)
		(layer "In4.Cu")
		(net "M_J_CPU0_SB_DQ<11>")
	)
	(segment
		(start 408.637486 -291.858954)
		(end 408.637486 -292.087554)
		(width 0.14478)
		(layer "In4.Cu")
		(net "M_J_CPU0_SB_DQ<11>")
	)
	(segment
		(start 432.893724 -292.660832)
		(end 433.183284 -292.950392)
		(width 0.14478)
		(layer "In4.Cu")
		(net "M_J_CPU0_SB_DQ<11>")
	)
	(segment
		(start 391.317734 -280.243534)
		(end 391.326116 -280.238708)
		(width 0.0889)
		(layer "In4.Cu")
		(net "M_J_CPU0_SB_DQ<11>")
	)
	(segment
		(start 409.593288 -291.91204)
		(end 409.754832 -292.073584)
		(width 0.14478)
		(layer "In4.Cu")
		(net "M_J_CPU0_SB_DQ<11>")
	)
	(segment
		(start 417.874704 -292.960044)
		(end 418.714936 -293.800276)
		(width 0.14478)
		(layer "In4.Cu")
		(net "M_J_CPU0_SB_DQ<11>")
	)
	(segment
		(start 432.63185 -292.660832)
		(end 432.893724 -292.660832)
		(width 0.14478)
		(layer "In4.Cu")
		(net "M_J_CPU0_SB_DQ<11>")
	)
	(segment
		(start 410.680408 -293.809674)
		(end 410.925264 -293.564818)
		(width 0.14478)
		(layer "In4.Cu")
		(net "M_J_CPU0_SB_DQ<11>")
	)
	(segment
		(start 386.043424 -280.238708)
		(end 386.051806 -280.243534)
		(width 0.0889)
		(layer "In4.Cu")
		(net "M_J_CPU0_SB_DQ<11>")
	)
	(segment
		(start 432.34229 -292.950392)
		(end 432.63185 -292.660832)
		(width 0.14478)
		(layer "In4.Cu")
		(net "M_J_CPU0_SB_DQ<11>")
	)
	(segment
		(start 383.79781 -280.243534)
		(end 383.806192 -280.238708)
		(width 0.0889)
		(layer "In4.Cu")
		(net "M_J_CPU0_SB_DQ<11>")
	)
	(segment
		(start 434.286152 -292.950392)
		(end 434.565552 -292.950392)
		(width 0.14478)
		(layer "In4.Cu")
		(net "M_J_CPU0_SB_DQ<11>")
	)
	(segment
		(start 408.247342 -291.46881)
		(end 408.5844 -291.131752)
		(width 0.14478)
		(layer "In4.Cu")
		(net "M_J_CPU0_SB_DQ<11>")
	)
	(segment
		(start 433.734718 -292.660832)
		(end 433.996592 -292.660832)
		(width 0.14478)
		(layer "In4.Cu")
		(net "M_J_CPU0_SB_DQ<11>")
	)
	(segment
		(start 409.364688 -291.91204)
		(end 409.593288 -291.91204)
		(width 0.14478)
		(layer "In4.Cu")
		(net "M_J_CPU0_SB_DQ<11>")
	)
	(segment
		(start 408.974544 -291.293296)
		(end 408.974544 -291.521896)
		(width 0.14478)
		(layer "In4.Cu")
		(net "M_J_CPU0_SB_DQ<11>")
	)
	(segment
		(start 386.983478 -280.238708)
		(end 386.99186 -280.243534)
		(width 0.0889)
		(layer "In4.Cu")
		(net "M_J_CPU0_SB_DQ<11>")
	)
	(segment
		(start 392.62431 -280.238708)
		(end 392.632692 -280.243534)
		(width 0.0889)
		(layer "In4.Cu")
		(net "M_J_CPU0_SB_DQ<11>")
	)
	(segment
		(start 429.937164 -292.950392)
		(end 432.34229 -292.950392)
		(width 0.14478)
		(layer "In4.Cu")
		(net "M_J_CPU0_SB_DQ<11>")
	)
	(segment
		(start 407.857198 -291.078666)
		(end 407.857198 -291.307266)
		(width 0.14478)
		(layer "In4.Cu")
		(net "M_J_CPU0_SB_DQ<11>")
	)
	(segment
		(start 409.807918 -293.029386)
		(end 410.144976 -292.692328)
		(width 0.14478)
		(layer "In4.Cu")
		(net "M_J_CPU0_SB_DQ<11>")
	)
	(segment
		(start 414.870646 -292.960044)
		(end 417.874704 -292.960044)
		(width 0.14478)
		(layer "In4.Cu")
		(net "M_J_CPU0_SB_DQ<11>")
	)
	(segment
		(start 410.198062 -293.41953)
		(end 410.198062 -293.64813)
		(width 0.14478)
		(layer "In4.Cu")
		(net "M_J_CPU0_SB_DQ<11>")
	)
	(segment
		(start 379.284738 -280.566114)
		(end 379.438916 -280.300684)
		(width 0.0889)
		(layer "In4.Cu")
		(net "M_J_CPU0_SB_DQ<11>")
	)
	(segment
		(start 434.565552 -292.950392)
		(end 435.000146 -293.384986)
		(width 0.14478)
		(layer "In4.Cu")
		(net "M_J_CPU0_SB_DQ<11>")
	)
	(segment
		(start 410.53512 -292.853872)
		(end 410.53512 -293.082472)
		(width 0.14478)
		(layer "In4.Cu")
		(net "M_J_CPU0_SB_DQ<11>")
	)
	(arc
		(start 379.535182 -280.275284)
		(mid 379.790247 -280.318635)
		(end 380.037848 -280.243534)
		(width 0.0889)
		(layer "In4.Cu")
		(net "M_J_CPU0_SB_DQ<11>")
	)
	(arc
		(start 389.811768 -280.243534)
		(mid 390.094724 -280.319711)
		(end 390.37768 -280.243534)
		(width 0.0889)
		(layer "In4.Cu")
		(net "M_J_CPU0_SB_DQ<11>")
	)
	(arc
		(start 382.291844 -280.243534)
		(mid 382.5748 -280.319711)
		(end 382.857756 -280.243534)
		(width 0.0889)
		(layer "In4.Cu")
		(net "M_J_CPU0_SB_DQ<11>")
	)
	(arc
		(start 389.43788 -280.243534)
		(mid 389.624824 -280.193279)
		(end 389.811768 -280.243534)
		(width 0.0889)
		(layer "In4.Cu")
		(net "M_J_CPU0_SB_DQ<11>")
	)
	(arc
		(start 386.617718 -280.243534)
		(mid 386.799969 -280.193184)
		(end 386.983478 -280.238708)
		(width 0.0889)
		(layer "In4.Cu")
		(net "M_J_CPU0_SB_DQ<11>")
	)
	(arc
		(start 390.751822 -280.243534)
		(mid 391.034778 -280.319711)
		(end 391.317734 -280.243534)
		(width 0.0889)
		(layer "In4.Cu")
		(net "M_J_CPU0_SB_DQ<11>")
	)
	(arc
		(start 387.566154 -280.238708)
		(mid 387.749662 -280.193214)
		(end 387.931914 -280.243534)
		(width 0.0889)
		(layer "In4.Cu")
		(net "M_J_CPU0_SB_DQ<11>")
	)
	(arc
		(start 386.051806 -280.243534)
		(mid 386.334762 -280.319711)
		(end 386.617718 -280.243534)
		(width 0.0889)
		(layer "In4.Cu")
		(net "M_J_CPU0_SB_DQ<11>")
	)
	(arc
		(start 392.258042 -280.243534)
		(mid 392.440547 -280.193057)
		(end 392.62431 -280.238708)
		(width 0.0889)
		(layer "In4.Cu")
		(net "M_J_CPU0_SB_DQ<11>")
	)
	(arc
		(start 381.917702 -280.243534)
		(mid 382.099953 -280.193184)
		(end 382.283462 -280.238708)
		(width 0.0889)
		(layer "In4.Cu")
		(net "M_J_CPU0_SB_DQ<11>")
	)
	(arc
		(start 392.632692 -280.243534)
		(mid 392.91212 -280.3197)
		(end 393.192508 -280.24709)
		(width 0.0889)
		(layer "In4.Cu")
		(net "M_J_CPU0_SB_DQ<11>")
	)
	(arc
		(start 384.737864 -280.243534)
		(mid 384.924808 -280.193279)
		(end 385.111752 -280.243534)
		(width 0.0889)
		(layer "In4.Cu")
		(net "M_J_CPU0_SB_DQ<11>")
	)
	(arc
		(start 380.41199 -280.243534)
		(mid 380.694946 -280.319711)
		(end 380.977902 -280.243534)
		(width 0.0889)
		(layer "In4.Cu")
		(net "M_J_CPU0_SB_DQ<11>")
	)
	(arc
		(start 385.111752 -280.243534)
		(mid 385.394708 -280.319711)
		(end 385.677664 -280.243534)
		(width 0.0889)
		(layer "In4.Cu")
		(net "M_J_CPU0_SB_DQ<11>")
	)
	(arc
		(start 381.35179 -280.243534)
		(mid 381.634746 -280.319711)
		(end 381.917702 -280.243534)
		(width 0.0889)
		(layer "In4.Cu")
		(net "M_J_CPU0_SB_DQ<11>")
	)
	(arc
		(start 386.99186 -280.243534)
		(mid 387.274816 -280.319711)
		(end 387.557772 -280.243534)
		(width 0.0889)
		(layer "In4.Cu")
		(net "M_J_CPU0_SB_DQ<11>")
	)
	(arc
		(start 391.70229 -280.24963)
		(mid 391.980976 -280.31985)
		(end 392.258042 -280.243534)
		(width 0.0889)
		(layer "In4.Cu")
		(net "M_J_CPU0_SB_DQ<11>")
	)
	(arc
		(start 380.977902 -280.243534)
		(mid 381.164846 -280.193279)
		(end 381.35179 -280.243534)
		(width 0.0889)
		(layer "In4.Cu")
		(net "M_J_CPU0_SB_DQ<11>")
	)
	(arc
		(start 387.931914 -280.243534)
		(mid 388.21487 -280.319711)
		(end 388.497826 -280.243534)
		(width 0.0889)
		(layer "In4.Cu")
		(net "M_J_CPU0_SB_DQ<11>")
	)
	(arc
		(start 393.192508 -280.24709)
		(mid 393.28494 -280.206808)
		(end 393.384786 -280.192734)
		(width 0.0889)
		(layer "In4.Cu")
		(net "M_J_CPU0_SB_DQ<11>")
	)
	(arc
		(start 383.231898 -280.243534)
		(mid 383.514854 -280.319711)
		(end 383.79781 -280.243534)
		(width 0.0889)
		(layer "In4.Cu")
		(net "M_J_CPU0_SB_DQ<11>")
	)
	(arc
		(start 382.866138 -280.238708)
		(mid 383.049646 -280.193214)
		(end 383.231898 -280.243534)
		(width 0.0889)
		(layer "In4.Cu")
		(net "M_J_CPU0_SB_DQ<11>")
	)
	(arc
		(start 385.677664 -280.243534)
		(mid 385.859915 -280.193184)
		(end 386.043424 -280.238708)
		(width 0.0889)
		(layer "In4.Cu")
		(net "M_J_CPU0_SB_DQ<11>")
	)
	(arc
		(start 384.171952 -280.243534)
		(mid 384.454908 -280.319711)
		(end 384.737864 -280.243534)
		(width 0.0889)
		(layer "In4.Cu")
		(net "M_J_CPU0_SB_DQ<11>")
	)
	(arc
		(start 388.871968 -280.243534)
		(mid 389.154924 -280.319711)
		(end 389.43788 -280.243534)
		(width 0.0889)
		(layer "In4.Cu")
		(net "M_J_CPU0_SB_DQ<11>")
	)
	(arc
		(start 383.806192 -280.238708)
		(mid 383.9897 -280.193214)
		(end 384.171952 -280.243534)
		(width 0.0889)
		(layer "In4.Cu")
		(net "M_J_CPU0_SB_DQ<11>")
	)
	(arc
		(start 391.326116 -280.238708)
		(mid 391.509624 -280.193214)
		(end 391.691876 -280.243534)
		(width 0.0889)
		(layer "In4.Cu")
		(net "M_J_CPU0_SB_DQ<11>")
	)
	(arc
		(start 388.506208 -280.238708)
		(mid 388.689716 -280.193214)
		(end 388.871968 -280.243534)
		(width 0.0889)
		(layer "In4.Cu")
		(net "M_J_CPU0_SB_DQ<11>")
	)
	(arc
		(start 380.04623 -280.238708)
		(mid 380.229738 -280.193214)
		(end 380.41199 -280.243534)
		(width 0.0889)
		(layer "In4.Cu")
		(net "M_J_CPU0_SB_DQ<11>")
	)
	(arc
		(start 390.37768 -280.243534)
		(mid 390.559931 -280.193184)
		(end 390.74344 -280.238708)
		(width 0.0889)
		(layer "In4.Cu")
		(net "M_J_CPU0_SB_DQ<11>")
	)
	(segment
		(start 380.22784 -279.49017)
		(end 380.694946 -279.756108)
		(width 0.10668)
		(layer "F.Cu")
		(net "M_J_CPU0_SB_DQ<10>")
	)
	(segment
		(start 410.446728 -291.493448)
		(end 410.608272 -291.654992)
		(width 0.14478)
		(layer "In4.Cu")
		(net "M_J_CPU0_SB_DQ<10>")
	)
	(segment
		(start 409.827984 -290.874704)
		(end 410.056584 -290.874704)
		(width 0.14478)
		(layer "In4.Cu")
		(net "M_J_CPU0_SB_DQ<10>")
	)
	(segment
		(start 381.447802 -279.433528)
		(end 381.456184 -279.428702)
		(width 0.0889)
		(layer "In4.Cu")
		(net "M_J_CPU0_SB_DQ<10>")
	)
	(segment
		(start 414.940242 -291.260022)
		(end 417.629848 -291.260022)
		(width 0.14478)
		(layer "In4.Cu")
		(net "M_J_CPU0_SB_DQ<10>")
	)
	(segment
		(start 409.522168 -289.848544)
		(end 409.750768 -289.848544)
		(width 0.14478)
		(layer "In4.Cu")
		(net "M_J_CPU0_SB_DQ<10>")
	)
	(segment
		(start 409.047696 -290.094416)
		(end 409.276296 -290.094416)
		(width 0.14478)
		(layer "In4.Cu")
		(net "M_J_CPU0_SB_DQ<10>")
	)
	(segment
		(start 400.530314 -280.822908)
		(end 400.724878 -280.822654)
		(width 0.14478)
		(layer "In4.Cu")
		(net "M_J_CPU0_SB_DQ<10>")
	)
	(segment
		(start 412.803086 -291.809932)
		(end 413.054292 -291.809932)
		(width 0.14478)
		(layer "In4.Cu")
		(net "M_J_CPU0_SB_DQ<10>")
	)
	(segment
		(start 412.012384 -292.11016)
		(end 412.502858 -292.11016)
		(width 0.14478)
		(layer "In4.Cu")
		(net "M_J_CPU0_SB_DQ<10>")
	)
	(segment
		(start 398.96796 -279.065736)
		(end 399.343118 -279.440894)
		(width 0.14478)
		(layer "In4.Cu")
		(net "M_J_CPU0_SB_DQ<10>")
	)
	(segment
		(start 409.750768 -289.848544)
		(end 409.912312 -290.010088)
		(width 0.14478)
		(layer "In4.Cu")
		(net "M_J_CPU0_SB_DQ<10>")
	)
	(segment
		(start 395.388084 -279.065736)
		(end 395.862556 -279.065736)
		(width 0.0889)
		(layer "In4.Cu")
		(net "M_J_CPU0_SB_DQ<10>")
	)
	(segment
		(start 405.212042 -285.504636)
		(end 405.406606 -285.504382)
		(width 0.14478)
		(layer "In4.Cu")
		(net "M_J_CPU0_SB_DQ<10>")
	)
	(segment
		(start 410.836872 -291.654992)
		(end 411.082744 -291.40912)
		(width 0.14478)
		(layer "In4.Cu")
		(net "M_J_CPU0_SB_DQ<10>")
	)
	(segment
		(start 389.333486 -279.428702)
		(end 389.341868 -279.433528)
		(width 0.0889)
		(layer "In4.Cu")
		(net "M_J_CPU0_SB_DQ<10>")
	)
	(segment
		(start 433.816506 -291.553392)
		(end 434.109876 -291.260022)
		(width 0.14478)
		(layer "In4.Cu")
		(net "M_J_CPU0_SB_DQ<10>")
	)
	(segment
		(start 400.903694 -281.00147)
		(end 400.903694 -281.42438)
		(width 0.14478)
		(layer "In4.Cu")
		(net "M_J_CPU0_SB_DQ<10>")
	)
	(segment
		(start 395.862556 -279.065736)
		(end 398.96796 -279.065736)
		(width 0.14478)
		(layer "In4.Cu")
		(net "M_J_CPU0_SB_DQ<10>")
	)
	(segment
		(start 407.145998 -287.666684)
		(end 407.324814 -287.8455)
		(width 0.14478)
		(layer "In4.Cu")
		(net "M_J_CPU0_SB_DQ<10>")
	)
	(segment
		(start 414.090104 -292.11016)
		(end 414.940242 -291.260022)
		(width 0.14478)
		(layer "In4.Cu")
		(net "M_J_CPU0_SB_DQ<10>")
	)
	(segment
		(start 399.343118 -279.440894)
		(end 399.343118 -279.863804)
		(width 0.14478)
		(layer "In4.Cu")
		(net "M_J_CPU0_SB_DQ<10>")
	)
	(segment
		(start 407.926286 -288.446972)
		(end 408.105102 -288.625788)
		(width 0.14478)
		(layer "In4.Cu")
		(net "M_J_CPU0_SB_DQ<10>")
	)
	(segment
		(start 409.912312 -290.238688)
		(end 409.66644 -290.48456)
		(width 0.14478)
		(layer "In4.Cu")
		(net "M_J_CPU0_SB_DQ<10>")
	)
	(segment
		(start 401.683982 -282.204668)
		(end 401.862798 -282.383484)
		(width 0.14478)
		(layer "In4.Cu")
		(net "M_J_CPU0_SB_DQ<10>")
	)
	(segment
		(start 408.527758 -288.625534)
		(end 409.132024 -289.2298)
		(width 0.14478)
		(layer "In4.Cu")
		(net "M_J_CPU0_SB_DQ<10>")
	)
	(segment
		(start 392.161014 -279.433782)
		(end 392.182604 -279.446228)
		(width 0.0889)
		(layer "In4.Cu")
		(net "M_J_CPU0_SB_DQ<10>")
	)
	(segment
		(start 402.285454 -282.38323)
		(end 402.46427 -282.562046)
		(width 0.14478)
		(layer "In4.Cu")
		(net "M_J_CPU0_SB_DQ<10>")
	)
	(segment
		(start 403.651466 -283.94406)
		(end 403.84603 -283.943806)
		(width 0.14478)
		(layer "In4.Cu")
		(net "M_J_CPU0_SB_DQ<10>")
	)
	(segment
		(start 392.140948 -279.422352)
		(end 392.161014 -279.433782)
		(width 0.0889)
		(layer "In4.Cu")
		(net "M_J_CPU0_SB_DQ<10>")
	)
	(segment
		(start 403.244558 -283.765244)
		(end 403.423374 -283.94406)
		(width 0.14478)
		(layer "In4.Cu")
		(net "M_J_CPU0_SB_DQ<10>")
	)
	(segment
		(start 409.66644 -290.48456)
		(end 409.66644 -290.71316)
		(width 0.14478)
		(layer "In4.Cu")
		(net "M_J_CPU0_SB_DQ<10>")
	)
	(segment
		(start 407.926286 -288.024062)
		(end 407.926286 -288.446972)
		(width 0.14478)
		(layer "In4.Cu")
		(net "M_J_CPU0_SB_DQ<10>")
	)
	(segment
		(start 388.393432 -279.428702)
		(end 388.401814 -279.433528)
		(width 0.0889)
		(layer "In4.Cu")
		(net "M_J_CPU0_SB_DQ<10>")
	)
	(segment
		(start 404.431754 -284.724348)
		(end 404.626318 -284.724094)
		(width 0.14478)
		(layer "In4.Cu")
		(net "M_J_CPU0_SB_DQ<10>")
	)
	(segment
		(start 409.132024 -289.2298)
		(end 409.132024 -289.4584)
		(width 0.14478)
		(layer "In4.Cu")
		(net "M_J_CPU0_SB_DQ<10>")
	)
	(segment
		(start 399.750026 -280.04262)
		(end 399.94459 -280.042366)
		(width 0.14478)
		(layer "In4.Cu")
		(net "M_J_CPU0_SB_DQ<10>")
	)
	(segment
		(start 385.207764 -279.433528)
		(end 385.216146 -279.428702)
		(width 0.0889)
		(layer "In4.Cu")
		(net "M_J_CPU0_SB_DQ<10>")
	)
	(segment
		(start 380.694946 -279.756108)
		(end 380.84887 -279.490678)
		(width 0.0889)
		(layer "In4.Cu")
		(net "M_J_CPU0_SB_DQ<10>")
	)
	(segment
		(start 405.99233 -286.284924)
		(end 406.186894 -286.28467)
		(width 0.14478)
		(layer "In4.Cu")
		(net "M_J_CPU0_SB_DQ<10>")
	)
	(segment
		(start 400.903694 -281.42438)
		(end 401.08251 -281.603196)
		(width 0.14478)
		(layer "In4.Cu")
		(net "M_J_CPU0_SB_DQ<10>")
	)
	(segment
		(start 433.558442 -291.553392)
		(end 433.816506 -291.553392)
		(width 0.14478)
		(layer "In4.Cu")
		(net "M_J_CPU0_SB_DQ<10>")
	)
	(segment
		(start 413.054292 -291.809932)
		(end 413.35452 -292.11016)
		(width 0.14478)
		(layer "In4.Cu")
		(net "M_J_CPU0_SB_DQ<10>")
	)
	(segment
		(start 410.302456 -290.628832)
		(end 410.531056 -290.628832)
		(width 0.14478)
		(layer "In4.Cu")
		(net "M_J_CPU0_SB_DQ<10>")
	)
	(segment
		(start 406.186894 -286.28467)
		(end 406.36571 -286.463486)
		(width 0.14478)
		(layer "In4.Cu")
		(net "M_J_CPU0_SB_DQ<10>")
	)
	(segment
		(start 402.46427 -282.984956)
		(end 402.643086 -283.163772)
		(width 0.14478)
		(layer "In4.Cu")
		(net "M_J_CPU0_SB_DQ<10>")
	)
	(segment
		(start 400.123406 -280.221182)
		(end 400.123406 -280.644092)
		(width 0.14478)
		(layer "In4.Cu")
		(net "M_J_CPU0_SB_DQ<10>")
	)
	(segment
		(start 405.764238 -286.284924)
		(end 405.99233 -286.284924)
		(width 0.14478)
		(layer "In4.Cu")
		(net "M_J_CPU0_SB_DQ<10>")
	)
	(segment
		(start 411.082744 -291.40912)
		(end 411.311344 -291.40912)
		(width 0.14478)
		(layer "In4.Cu")
		(net "M_J_CPU0_SB_DQ<10>")
	)
	(segment
		(start 426.140626 -292.109906)
		(end 429.188118 -292.109906)
		(width 0.14478)
		(layer "In4.Cu")
		(net "M_J_CPU0_SB_DQ<10>")
	)
	(segment
		(start 404.626318 -284.724094)
		(end 404.805134 -284.90291)
		(width 0.14478)
		(layer "In4.Cu")
		(net "M_J_CPU0_SB_DQ<10>")
	)
	(segment
		(start 399.521934 -280.04262)
		(end 399.750026 -280.04262)
		(width 0.14478)
		(layer "In4.Cu")
		(net "M_J_CPU0_SB_DQ<10>")
	)
	(segment
		(start 411.311344 -291.40912)
		(end 412.012384 -292.11016)
		(width 0.14478)
		(layer "In4.Cu")
		(net "M_J_CPU0_SB_DQ<10>")
	)
	(segment
		(start 403.244558 -283.342334)
		(end 403.244558 -283.765244)
		(width 0.14478)
		(layer "In4.Cu")
		(net "M_J_CPU0_SB_DQ<10>")
	)
	(segment
		(start 404.805134 -285.32582)
		(end 404.98395 -285.504636)
		(width 0.14478)
		(layer "In4.Cu")
		(net "M_J_CPU0_SB_DQ<10>")
	)
	(segment
		(start 404.805134 -284.90291)
		(end 404.805134 -285.32582)
		(width 0.14478)
		(layer "In4.Cu")
		(net "M_J_CPU0_SB_DQ<10>")
	)
	(segment
		(start 399.94459 -280.042366)
		(end 400.123406 -280.221182)
		(width 0.14478)
		(layer "In4.Cu")
		(net "M_J_CPU0_SB_DQ<10>")
	)
	(segment
		(start 408.886152 -289.932872)
		(end 409.047696 -290.094416)
		(width 0.14478)
		(layer "In4.Cu")
		(net "M_J_CPU0_SB_DQ<10>")
	)
	(segment
		(start 400.724878 -280.822654)
		(end 400.903694 -281.00147)
		(width 0.14478)
		(layer "In4.Cu")
		(net "M_J_CPU0_SB_DQ<10>")
	)
	(segment
		(start 406.967182 -287.064958)
		(end 407.145998 -287.243774)
		(width 0.14478)
		(layer "In4.Cu")
		(net "M_J_CPU0_SB_DQ<10>")
	)
	(segment
		(start 418.479986 -292.11016)
		(end 421.634158 -292.11016)
		(width 0.14478)
		(layer "In4.Cu")
		(net "M_J_CPU0_SB_DQ<10>")
	)
	(segment
		(start 421.634158 -292.11016)
		(end 422.484296 -291.260022)
		(width 0.14478)
		(layer "In4.Cu")
		(net "M_J_CPU0_SB_DQ<10>")
	)
	(segment
		(start 383.693416 -279.428702)
		(end 383.701798 -279.433528)
		(width 0.0889)
		(layer "In4.Cu")
		(net "M_J_CPU0_SB_DQ<10>")
	)
	(segment
		(start 403.065742 -283.163518)
		(end 403.244558 -283.342334)
		(width 0.14478)
		(layer "In4.Cu")
		(net "M_J_CPU0_SB_DQ<10>")
	)
	(segment
		(start 405.585422 -286.106108)
		(end 405.764238 -286.284924)
		(width 0.14478)
		(layer "In4.Cu")
		(net "M_J_CPU0_SB_DQ<10>")
	)
	(segment
		(start 406.36571 -286.886396)
		(end 406.544526 -287.065212)
		(width 0.14478)
		(layer "In4.Cu")
		(net "M_J_CPU0_SB_DQ<10>")
	)
	(segment
		(start 407.74747 -287.845246)
		(end 407.926286 -288.024062)
		(width 0.14478)
		(layer "In4.Cu")
		(net "M_J_CPU0_SB_DQ<10>")
	)
	(segment
		(start 389.90778 -279.433528)
		(end 389.916162 -279.428702)
		(width 0.0889)
		(layer "In4.Cu")
		(net "M_J_CPU0_SB_DQ<10>")
	)
	(segment
		(start 408.333194 -288.625788)
		(end 408.527758 -288.625534)
		(width 0.14478)
		(layer "In4.Cu")
		(net "M_J_CPU0_SB_DQ<10>")
	)
	(segment
		(start 403.84603 -283.943806)
		(end 404.024846 -284.122622)
		(width 0.14478)
		(layer "In4.Cu")
		(net "M_J_CPU0_SB_DQ<10>")
	)
	(segment
		(start 401.683982 -281.781758)
		(end 401.683982 -282.204668)
		(width 0.14478)
		(layer "In4.Cu")
		(net "M_J_CPU0_SB_DQ<10>")
	)
	(segment
		(start 401.505166 -281.602942)
		(end 401.683982 -281.781758)
		(width 0.14478)
		(layer "In4.Cu")
		(net "M_J_CPU0_SB_DQ<10>")
	)
	(segment
		(start 392.725402 -279.433528)
		(end 392.744198 -279.422606)
		(width 0.0889)
		(layer "In4.Cu")
		(net "M_J_CPU0_SB_DQ<10>")
	)
	(segment
		(start 402.871178 -283.163772)
		(end 403.065742 -283.163518)
		(width 0.14478)
		(layer "In4.Cu")
		(net "M_J_CPU0_SB_DQ<10>")
	)
	(segment
		(start 410.6926 -291.018976)
		(end 410.446728 -291.264848)
		(width 0.14478)
		(layer "In4.Cu")
		(net "M_J_CPU0_SB_DQ<10>")
	)
	(segment
		(start 402.643086 -283.163772)
		(end 402.871178 -283.163772)
		(width 0.14478)
		(layer "In4.Cu")
		(net "M_J_CPU0_SB_DQ<10>")
	)
	(segment
		(start 406.36571 -286.463486)
		(end 406.36571 -286.886396)
		(width 0.14478)
		(layer "In4.Cu")
		(net "M_J_CPU0_SB_DQ<10>")
	)
	(segment
		(start 432.162204 -291.260022)
		(end 432.455574 -291.553392)
		(width 0.14478)
		(layer "In4.Cu")
		(net "M_J_CPU0_SB_DQ<10>")
	)
	(segment
		(start 412.502858 -292.11016)
		(end 412.803086 -291.809932)
		(width 0.14478)
		(layer "In4.Cu")
		(net "M_J_CPU0_SB_DQ<10>")
	)
	(segment
		(start 401.310602 -281.603196)
		(end 401.505166 -281.602942)
		(width 0.14478)
		(layer "In4.Cu")
		(net "M_J_CPU0_SB_DQ<10>")
	)
	(segment
		(start 410.056584 -290.874704)
		(end 410.302456 -290.628832)
		(width 0.14478)
		(layer "In4.Cu")
		(net "M_J_CPU0_SB_DQ<10>")
	)
	(segment
		(start 410.6926 -290.790376)
		(end 410.6926 -291.018976)
		(width 0.14478)
		(layer "In4.Cu")
		(net "M_J_CPU0_SB_DQ<10>")
	)
	(segment
		(start 401.862798 -282.383484)
		(end 402.09089 -282.383484)
		(width 0.14478)
		(layer "In4.Cu")
		(net "M_J_CPU0_SB_DQ<10>")
	)
	(segment
		(start 393.869418 -279.379172)
		(end 394.299948 -278.951436)
		(width 0.0889)
		(layer "In4.Cu")
		(net "M_J_CPU0_SB_DQ<10>")
	)
	(segment
		(start 410.446728 -291.264848)
		(end 410.446728 -291.493448)
		(width 0.14478)
		(layer "In4.Cu")
		(net "M_J_CPU0_SB_DQ<10>")
	)
	(segment
		(start 404.98395 -285.504636)
		(end 405.212042 -285.504636)
		(width 0.14478)
		(layer "In4.Cu")
		(net "M_J_CPU0_SB_DQ<10>")
	)
	(segment
		(start 410.531056 -290.628832)
		(end 410.6926 -290.790376)
		(width 0.14478)
		(layer "In4.Cu")
		(net "M_J_CPU0_SB_DQ<10>")
	)
	(segment
		(start 404.024846 -284.545532)
		(end 404.203662 -284.724348)
		(width 0.14478)
		(layer "In4.Cu")
		(net "M_J_CPU0_SB_DQ<10>")
	)
	(segment
		(start 402.09089 -282.383484)
		(end 402.285454 -282.38323)
		(width 0.14478)
		(layer "In4.Cu")
		(net "M_J_CPU0_SB_DQ<10>")
	)
	(segment
		(start 404.203662 -284.724348)
		(end 404.431754 -284.724348)
		(width 0.14478)
		(layer "In4.Cu")
		(net "M_J_CPU0_SB_DQ<10>")
	)
	(segment
		(start 402.46427 -282.562046)
		(end 402.46427 -282.984956)
		(width 0.14478)
		(layer "In4.Cu")
		(net "M_J_CPU0_SB_DQ<10>")
	)
	(segment
		(start 406.544526 -287.065212)
		(end 406.772618 -287.065212)
		(width 0.14478)
		(layer "In4.Cu")
		(net "M_J_CPU0_SB_DQ<10>")
	)
	(segment
		(start 432.455574 -291.553392)
		(end 432.713638 -291.553392)
		(width 0.14478)
		(layer "In4.Cu")
		(net "M_J_CPU0_SB_DQ<10>")
	)
	(segment
		(start 409.912312 -290.010088)
		(end 409.912312 -290.238688)
		(width 0.14478)
		(layer "In4.Cu")
		(net "M_J_CPU0_SB_DQ<10>")
	)
	(segment
		(start 433.265072 -291.260022)
		(end 433.558442 -291.553392)
		(width 0.14478)
		(layer "In4.Cu")
		(net "M_J_CPU0_SB_DQ<10>")
	)
	(segment
		(start 422.484296 -291.260022)
		(end 425.290742 -291.260022)
		(width 0.14478)
		(layer "In4.Cu")
		(net "M_J_CPU0_SB_DQ<10>")
	)
	(segment
		(start 417.629848 -291.260022)
		(end 418.479986 -292.11016)
		(width 0.14478)
		(layer "In4.Cu")
		(net "M_J_CPU0_SB_DQ<10>")
	)
	(segment
		(start 400.302222 -280.822908)
		(end 400.530314 -280.822908)
		(width 0.14478)
		(layer "In4.Cu")
		(net "M_J_CPU0_SB_DQ<10>")
	)
	(segment
		(start 425.290742 -291.260022)
		(end 426.140626 -292.109906)
		(width 0.14478)
		(layer "In4.Cu")
		(net "M_J_CPU0_SB_DQ<10>")
	)
	(segment
		(start 434.575204 -291.260022)
		(end 435.000146 -291.684964)
		(width 0.14478)
		(layer "In4.Cu")
		(net "M_J_CPU0_SB_DQ<10>")
	)
	(segment
		(start 384.63347 -279.428702)
		(end 384.641852 -279.433528)
		(width 0.0889)
		(layer "In4.Cu")
		(net "M_J_CPU0_SB_DQ<10>")
	)
	(segment
		(start 430.038002 -291.260022)
		(end 432.162204 -291.260022)
		(width 0.14478)
		(layer "In4.Cu")
		(net "M_J_CPU0_SB_DQ<10>")
	)
	(segment
		(start 408.886152 -289.704272)
		(end 408.886152 -289.932872)
		(width 0.14478)
		(layer "In4.Cu")
		(net "M_J_CPU0_SB_DQ<10>")
	)
	(segment
		(start 405.406606 -285.504382)
		(end 405.585422 -285.683198)
		(width 0.14478)
		(layer "In4.Cu")
		(net "M_J_CPU0_SB_DQ<10>")
	)
	(segment
		(start 407.324814 -287.8455)
		(end 407.552906 -287.8455)
		(width 0.14478)
		(layer "In4.Cu")
		(net "M_J_CPU0_SB_DQ<10>")
	)
	(segment
		(start 413.35452 -292.11016)
		(end 414.090104 -292.11016)
		(width 0.14478)
		(layer "In4.Cu")
		(net "M_J_CPU0_SB_DQ<10>")
	)
	(segment
		(start 407.552906 -287.8455)
		(end 407.74747 -287.845246)
		(width 0.14478)
		(layer "In4.Cu")
		(net "M_J_CPU0_SB_DQ<10>")
	)
	(segment
		(start 404.024846 -284.122622)
		(end 404.024846 -284.545532)
		(width 0.14478)
		(layer "In4.Cu")
		(net "M_J_CPU0_SB_DQ<10>")
	)
	(segment
		(start 400.123406 -280.644092)
		(end 400.302222 -280.822908)
		(width 0.14478)
		(layer "In4.Cu")
		(net "M_J_CPU0_SB_DQ<10>")
	)
	(segment
		(start 394.391388 -278.91359)
		(end 395.235938 -278.91359)
		(width 0.0889)
		(layer "In4.Cu")
		(net "M_J_CPU0_SB_DQ<10>")
	)
	(segment
		(start 434.109876 -291.260022)
		(end 434.575204 -291.260022)
		(width 0.14478)
		(layer "In4.Cu")
		(net "M_J_CPU0_SB_DQ<10>")
	)
	(segment
		(start 409.276296 -290.094416)
		(end 409.522168 -289.848544)
		(width 0.14478)
		(layer "In4.Cu")
		(net "M_J_CPU0_SB_DQ<10>")
	)
	(segment
		(start 409.66644 -290.71316)
		(end 409.827984 -290.874704)
		(width 0.14478)
		(layer "In4.Cu")
		(net "M_J_CPU0_SB_DQ<10>")
	)
	(segment
		(start 403.423374 -283.94406)
		(end 403.651466 -283.94406)
		(width 0.14478)
		(layer "In4.Cu")
		(net "M_J_CPU0_SB_DQ<10>")
	)
	(segment
		(start 433.007008 -291.260022)
		(end 433.265072 -291.260022)
		(width 0.14478)
		(layer "In4.Cu")
		(net "M_J_CPU0_SB_DQ<10>")
	)
	(segment
		(start 408.105102 -288.625788)
		(end 408.333194 -288.625788)
		(width 0.14478)
		(layer "In4.Cu")
		(net "M_J_CPU0_SB_DQ<10>")
	)
	(segment
		(start 405.585422 -285.683198)
		(end 405.585422 -286.106108)
		(width 0.14478)
		(layer "In4.Cu")
		(net "M_J_CPU0_SB_DQ<10>")
	)
	(segment
		(start 406.772618 -287.065212)
		(end 406.967182 -287.064958)
		(width 0.14478)
		(layer "In4.Cu")
		(net "M_J_CPU0_SB_DQ<10>")
	)
	(segment
		(start 410.608272 -291.654992)
		(end 410.836872 -291.654992)
		(width 0.14478)
		(layer "In4.Cu")
		(net "M_J_CPU0_SB_DQ<10>")
	)
	(segment
		(start 395.235938 -278.91359)
		(end 395.388084 -279.065736)
		(width 0.0889)
		(layer "In4.Cu")
		(net "M_J_CPU0_SB_DQ<10>")
	)
	(segment
		(start 401.08251 -281.603196)
		(end 401.310602 -281.603196)
		(width 0.14478)
		(layer "In4.Cu")
		(net "M_J_CPU0_SB_DQ<10>")
	)
	(segment
		(start 380.84887 -279.490678)
		(end 380.944882 -279.465278)
		(width 0.0889)
		(layer "In4.Cu")
		(net "M_J_CPU0_SB_DQ<10>")
	)
	(segment
		(start 409.132024 -289.4584)
		(end 408.886152 -289.704272)
		(width 0.14478)
		(layer "In4.Cu")
		(net "M_J_CPU0_SB_DQ<10>")
	)
	(segment
		(start 429.188118 -292.109906)
		(end 430.038002 -291.260022)
		(width 0.14478)
		(layer "In4.Cu")
		(net "M_J_CPU0_SB_DQ<10>")
	)
	(segment
		(start 386.147818 -279.433528)
		(end 386.1562 -279.428702)
		(width 0.0889)
		(layer "In4.Cu")
		(net "M_J_CPU0_SB_DQ<10>")
	)
	(segment
		(start 399.343118 -279.863804)
		(end 399.521934 -280.04262)
		(width 0.14478)
		(layer "In4.Cu")
		(net "M_J_CPU0_SB_DQ<10>")
	)
	(segment
		(start 432.713638 -291.553392)
		(end 433.007008 -291.260022)
		(width 0.14478)
		(layer "In4.Cu")
		(net "M_J_CPU0_SB_DQ<10>")
	)
	(segment
		(start 407.145998 -287.243774)
		(end 407.145998 -287.666684)
		(width 0.14478)
		(layer "In4.Cu")
		(net "M_J_CPU0_SB_DQ<10>")
	)
	(arc
		(start 390.281922 -279.433528)
		(mid 390.564878 -279.509705)
		(end 390.847834 -279.433528)
		(width 0.0889)
		(layer "In4.Cu")
		(net "M_J_CPU0_SB_DQ<10>")
	)
	(arc
		(start 380.944882 -279.465278)
		(mid 381.20009 -279.508755)
		(end 381.447802 -279.433528)
		(width 0.0889)
		(layer "In4.Cu")
		(net "M_J_CPU0_SB_DQ<10>")
	)
	(arc
		(start 385.216146 -279.428702)
		(mid 385.399654 -279.383208)
		(end 385.581906 -279.433528)
		(width 0.0889)
		(layer "In4.Cu")
		(net "M_J_CPU0_SB_DQ<10>")
	)
	(arc
		(start 392.182604 -279.446228)
		(mid 392.455633 -279.509547)
		(end 392.725402 -279.433528)
		(width 0.0889)
		(layer "In4.Cu")
		(net "M_J_CPU0_SB_DQ<10>")
	)
	(arc
		(start 390.847834 -279.433528)
		(mid 391.034778 -279.383273)
		(end 391.221722 -279.433528)
		(width 0.0889)
		(layer "In4.Cu")
		(net "M_J_CPU0_SB_DQ<10>")
	)
	(arc
		(start 385.581906 -279.433528)
		(mid 385.864862 -279.509705)
		(end 386.147818 -279.433528)
		(width 0.0889)
		(layer "In4.Cu")
		(net "M_J_CPU0_SB_DQ<10>")
	)
	(arc
		(start 388.027672 -279.433528)
		(mid 388.209923 -279.383178)
		(end 388.393432 -279.428702)
		(width 0.0889)
		(layer "In4.Cu")
		(net "M_J_CPU0_SB_DQ<10>")
	)
	(arc
		(start 387.087872 -279.433528)
		(mid 387.274816 -279.383273)
		(end 387.46176 -279.433528)
		(width 0.0889)
		(layer "In4.Cu")
		(net "M_J_CPU0_SB_DQ<10>")
	)
	(arc
		(start 382.387856 -279.433528)
		(mid 382.5748 -279.383273)
		(end 382.761744 -279.433528)
		(width 0.0889)
		(layer "In4.Cu")
		(net "M_J_CPU0_SB_DQ<10>")
	)
	(arc
		(start 392.744198 -279.422606)
		(mid 392.923769 -279.382789)
		(end 393.10056 -279.433528)
		(width 0.0889)
		(layer "In4.Cu")
		(net "M_J_CPU0_SB_DQ<10>")
	)
	(arc
		(start 383.327656 -279.433528)
		(mid 383.509907 -279.383178)
		(end 383.693416 -279.428702)
		(width 0.0889)
		(layer "In4.Cu")
		(net "M_J_CPU0_SB_DQ<10>")
	)
	(arc
		(start 393.10056 -279.433528)
		(mid 393.236105 -279.491326)
		(end 393.381738 -279.513792)
		(width 0.0889)
		(layer "In4.Cu")
		(net "M_J_CPU0_SB_DQ<10>")
	)
	(arc
		(start 381.456184 -279.428702)
		(mid 381.639692 -279.383208)
		(end 381.821944 -279.433528)
		(width 0.0889)
		(layer "In4.Cu")
		(net "M_J_CPU0_SB_DQ<10>")
	)
	(arc
		(start 386.1562 -279.428702)
		(mid 386.339708 -279.383208)
		(end 386.52196 -279.433528)
		(width 0.0889)
		(layer "In4.Cu")
		(net "M_J_CPU0_SB_DQ<10>")
	)
	(arc
		(start 381.821944 -279.433528)
		(mid 382.1049 -279.509705)
		(end 382.387856 -279.433528)
		(width 0.0889)
		(layer "In4.Cu")
		(net "M_J_CPU0_SB_DQ<10>")
	)
	(arc
		(start 393.381738 -279.513792)
		(mid 393.583532 -279.49869)
		(end 393.777978 -279.442672)
		(width 0.0889)
		(layer "In4.Cu")
		(net "M_J_CPU0_SB_DQ<10>")
	)
	(arc
		(start 384.641852 -279.433528)
		(mid 384.924808 -279.509705)
		(end 385.207764 -279.433528)
		(width 0.0889)
		(layer "In4.Cu")
		(net "M_J_CPU0_SB_DQ<10>")
	)
	(arc
		(start 387.46176 -279.433528)
		(mid 387.744716 -279.509705)
		(end 388.027672 -279.433528)
		(width 0.0889)
		(layer "In4.Cu")
		(net "M_J_CPU0_SB_DQ<10>")
	)
	(arc
		(start 386.52196 -279.433528)
		(mid 386.804916 -279.509705)
		(end 387.087872 -279.433528)
		(width 0.0889)
		(layer "In4.Cu")
		(net "M_J_CPU0_SB_DQ<10>")
	)
	(arc
		(start 391.221722 -279.433528)
		(mid 391.504678 -279.509705)
		(end 391.787634 -279.433528)
		(width 0.0889)
		(layer "In4.Cu")
		(net "M_J_CPU0_SB_DQ<10>")
	)
	(arc
		(start 389.341868 -279.433528)
		(mid 389.624824 -279.509705)
		(end 389.90778 -279.433528)
		(width 0.0889)
		(layer "In4.Cu")
		(net "M_J_CPU0_SB_DQ<10>")
	)
	(arc
		(start 388.967726 -279.433528)
		(mid 389.149977 -279.383178)
		(end 389.333486 -279.428702)
		(width 0.0889)
		(layer "In4.Cu")
		(net "M_J_CPU0_SB_DQ<10>")
	)
	(arc
		(start 389.916162 -279.428702)
		(mid 390.09967 -279.383208)
		(end 390.281922 -279.433528)
		(width 0.0889)
		(layer "In4.Cu")
		(net "M_J_CPU0_SB_DQ<10>")
	)
	(arc
		(start 383.701798 -279.433528)
		(mid 383.984754 -279.509705)
		(end 384.26771 -279.433528)
		(width 0.0889)
		(layer "In4.Cu")
		(net "M_J_CPU0_SB_DQ<10>")
	)
	(arc
		(start 394.299948 -278.951436)
		(mid 394.341901 -278.923404)
		(end 394.391388 -278.91359)
		(width 0.0889)
		(layer "In4.Cu")
		(net "M_J_CPU0_SB_DQ<10>")
	)
	(arc
		(start 393.777978 -279.442672)
		(mid 393.827257 -279.41605)
		(end 393.869418 -279.379172)
		(width 0.0889)
		(layer "In4.Cu")
		(net "M_J_CPU0_SB_DQ<10>")
	)
	(arc
		(start 391.787634 -279.433528)
		(mid 391.962873 -279.383457)
		(end 392.140948 -279.422352)
		(width 0.0889)
		(layer "In4.Cu")
		(net "M_J_CPU0_SB_DQ<10>")
	)
	(arc
		(start 384.26771 -279.433528)
		(mid 384.449961 -279.383178)
		(end 384.63347 -279.428702)
		(width 0.0889)
		(layer "In4.Cu")
		(net "M_J_CPU0_SB_DQ<10>")
	)
	(arc
		(start 382.761744 -279.433528)
		(mid 383.0447 -279.509705)
		(end 383.327656 -279.433528)
		(width 0.0889)
		(layer "In4.Cu")
		(net "M_J_CPU0_SB_DQ<10>")
	)
	(arc
		(start 388.401814 -279.433528)
		(mid 388.68477 -279.509705)
		(end 388.967726 -279.433528)
		(width 0.0889)
		(layer "In4.Cu")
		(net "M_J_CPU0_SB_DQ<10>")
	)
	(segment
		(start 380.697994 -273.820128)
		(end 381.164846 -274.086066)
		(width 0.10668)
		(layer "F.Cu")
		(net "M_J_CPU0_SB_DQ<0>")
	)
	(segment
		(start 391.317734 -274.408646)
		(end 391.326116 -274.413472)
		(width 0.0889)
		(layer "In4.Cu")
		(net "M_J_CPU0_SB_DQ<0>")
	)
	(segment
		(start 436.710328 -281.221688)
		(end 436.710328 -281.686508)
		(width 0.14478)
		(layer "In4.Cu")
		(net "M_J_CPU0_SB_DQ<0>")
	)
	(segment
		(start 421.727122 -281.910028)
		(end 422.577006 -281.060144)
		(width 0.14478)
		(layer "In4.Cu")
		(net "M_J_CPU0_SB_DQ<0>")
	)
	(segment
		(start 437.261762 -281.221688)
		(end 437.423306 -281.060144)
		(width 0.14478)
		(layer "In4.Cu")
		(net "M_J_CPU0_SB_DQ<0>")
	)
	(segment
		(start 411.725618 -281.494992)
		(end 412.140654 -281.910028)
		(width 0.14478)
		(layer "In4.Cu")
		(net "M_J_CPU0_SB_DQ<0>")
	)
	(segment
		(start 436.710328 -281.686508)
		(end 436.871872 -281.848052)
		(width 0.14478)
		(layer "In4.Cu")
		(net "M_J_CPU0_SB_DQ<0>")
	)
	(segment
		(start 381.164846 -274.086066)
		(end 381.010922 -274.351496)
		(width 0.0889)
		(layer "In4.Cu")
		(net "M_J_CPU0_SB_DQ<0>")
	)
	(segment
		(start 412.140654 -281.910028)
		(end 413.569912 -281.910028)
		(width 0.14478)
		(layer "In4.Cu")
		(net "M_J_CPU0_SB_DQ<0>")
	)
	(segment
		(start 382.857756 -274.408646)
		(end 382.866138 -274.413472)
		(width 0.0889)
		(layer "In4.Cu")
		(net "M_J_CPU0_SB_DQ<0>")
	)
	(segment
		(start 393.529566 -274.4597)
		(end 393.646152 -274.405344)
		(width 0.0889)
		(layer "In4.Cu")
		(net "M_J_CPU0_SB_DQ<0>")
	)
	(segment
		(start 392.234674 -274.395946)
		(end 392.256264 -274.408392)
		(width 0.0889)
		(layer "In4.Cu")
		(net "M_J_CPU0_SB_DQ<0>")
	)
	(segment
		(start 436.548784 -281.060144)
		(end 436.710328 -281.221688)
		(width 0.14478)
		(layer "In4.Cu")
		(net "M_J_CPU0_SB_DQ<0>")
	)
	(segment
		(start 394.657326 -273.39417)
		(end 395.108684 -273.39417)
		(width 0.0889)
		(layer "In4.Cu")
		(net "M_J_CPU0_SB_DQ<0>")
	)
	(segment
		(start 383.79781 -274.408646)
		(end 383.806192 -274.413472)
		(width 0.0889)
		(layer "In4.Cu")
		(net "M_J_CPU0_SB_DQ<0>")
	)
	(segment
		(start 395.988032 -272.93951)
		(end 402.769324 -272.93951)
		(width 0.14478)
		(layer "In4.Cu")
		(net "M_J_CPU0_SB_DQ<0>")
	)
	(segment
		(start 382.283462 -274.413472)
		(end 382.291844 -274.408646)
		(width 0.0889)
		(layer "In4.Cu")
		(net "M_J_CPU0_SB_DQ<0>")
	)
	(segment
		(start 388.497826 -274.408646)
		(end 388.506208 -274.413472)
		(width 0.0889)
		(layer "In4.Cu")
		(net "M_J_CPU0_SB_DQ<0>")
	)
	(segment
		(start 386.983478 -274.413472)
		(end 386.99186 -274.408646)
		(width 0.0889)
		(layer "In4.Cu")
		(net "M_J_CPU0_SB_DQ<0>")
	)
	(segment
		(start 381.010922 -274.351496)
		(end 381.033274 -274.434808)
		(width 0.0889)
		(layer "In4.Cu")
		(net "M_J_CPU0_SB_DQ<0>")
	)
	(segment
		(start 386.043424 -274.413472)
		(end 386.051806 -274.408646)
		(width 0.0889)
		(layer "In4.Cu")
		(net "M_J_CPU0_SB_DQ<0>")
	)
	(segment
		(start 428.801022 -281.910028)
		(end 429.650906 -281.060144)
		(width 0.14478)
		(layer "In4.Cu")
		(net "M_J_CPU0_SB_DQ<0>")
	)
	(segment
		(start 425.601638 -281.060144)
		(end 426.451522 -281.910028)
		(width 0.14478)
		(layer "In4.Cu")
		(net "M_J_CPU0_SB_DQ<0>")
	)
	(segment
		(start 437.261762 -281.686508)
		(end 437.261762 -281.221688)
		(width 0.14478)
		(layer "In4.Cu")
		(net "M_J_CPU0_SB_DQ<0>")
	)
	(segment
		(start 393.38504 -274.4597)
		(end 393.529566 -274.4597)
		(width 0.0889)
		(layer "In4.Cu")
		(net "M_J_CPU0_SB_DQ<0>")
	)
	(segment
		(start 395.108684 -273.39417)
		(end 395.563344 -272.93951)
		(width 0.0889)
		(layer "In4.Cu")
		(net "M_J_CPU0_SB_DQ<0>")
	)
	(segment
		(start 411.725618 -280.9367)
		(end 411.725618 -281.494992)
		(width 0.14478)
		(layer "In4.Cu")
		(net "M_J_CPU0_SB_DQ<0>")
	)
	(segment
		(start 408.966162 -278.177244)
		(end 411.725618 -280.9367)
		(width 0.14478)
		(layer "In4.Cu")
		(net "M_J_CPU0_SB_DQ<0>")
	)
	(segment
		(start 395.563344 -272.93951)
		(end 395.988032 -272.93951)
		(width 0.0889)
		(layer "In4.Cu")
		(net "M_J_CPU0_SB_DQ<0>")
	)
	(segment
		(start 429.650906 -281.060144)
		(end 436.548784 -281.060144)
		(width 0.14478)
		(layer "In4.Cu")
		(net "M_J_CPU0_SB_DQ<0>")
	)
	(segment
		(start 436.871872 -281.848052)
		(end 437.100218 -281.848052)
		(width 0.14478)
		(layer "In4.Cu")
		(net "M_J_CPU0_SB_DQ<0>")
	)
	(segment
		(start 387.557772 -274.408646)
		(end 387.566154 -274.413472)
		(width 0.0889)
		(layer "In4.Cu")
		(net "M_J_CPU0_SB_DQ<0>")
	)
	(segment
		(start 408.007058 -278.177244)
		(end 408.966162 -278.177244)
		(width 0.14478)
		(layer "In4.Cu")
		(net "M_J_CPU0_SB_DQ<0>")
	)
	(segment
		(start 393.646152 -274.405344)
		(end 394.657326 -273.39417)
		(width 0.0889)
		(layer "In4.Cu")
		(net "M_J_CPU0_SB_DQ<0>")
	)
	(segment
		(start 438.675272 -281.060144)
		(end 439.100214 -281.485086)
		(width 0.14478)
		(layer "In4.Cu")
		(net "M_J_CPU0_SB_DQ<0>")
	)
	(segment
		(start 415.621724 -281.060144)
		(end 418.057584 -281.060144)
		(width 0.14478)
		(layer "In4.Cu")
		(net "M_J_CPU0_SB_DQ<0>")
	)
	(segment
		(start 393.384786 -274.459446)
		(end 393.38504 -274.4597)
		(width 0.0889)
		(layer "In4.Cu")
		(net "M_J_CPU0_SB_DQ<0>")
	)
	(segment
		(start 426.451522 -281.910028)
		(end 428.801022 -281.910028)
		(width 0.14478)
		(layer "In4.Cu")
		(net "M_J_CPU0_SB_DQ<0>")
	)
	(segment
		(start 437.100218 -281.848052)
		(end 437.261762 -281.686508)
		(width 0.14478)
		(layer "In4.Cu")
		(net "M_J_CPU0_SB_DQ<0>")
	)
	(segment
		(start 418.057584 -281.060144)
		(end 418.907468 -281.910028)
		(width 0.14478)
		(layer "In4.Cu")
		(net "M_J_CPU0_SB_DQ<0>")
	)
	(segment
		(start 390.74344 -274.413472)
		(end 390.751822 -274.408646)
		(width 0.0889)
		(layer "In4.Cu")
		(net "M_J_CPU0_SB_DQ<0>")
	)
	(segment
		(start 402.769324 -272.93951)
		(end 408.007058 -278.177244)
		(width 0.14478)
		(layer "In4.Cu")
		(net "M_J_CPU0_SB_DQ<0>")
	)
	(segment
		(start 418.907468 -281.910028)
		(end 421.727122 -281.910028)
		(width 0.14478)
		(layer "In4.Cu")
		(net "M_J_CPU0_SB_DQ<0>")
	)
	(segment
		(start 437.423306 -281.060144)
		(end 438.675272 -281.060144)
		(width 0.14478)
		(layer "In4.Cu")
		(net "M_J_CPU0_SB_DQ<0>")
	)
	(segment
		(start 392.62939 -274.408646)
		(end 392.652758 -274.39493)
		(width 0.0889)
		(layer "In4.Cu")
		(net "M_J_CPU0_SB_DQ<0>")
	)
	(segment
		(start 392.256264 -274.408392)
		(end 392.274552 -274.418806)
		(width 0.0889)
		(layer "In4.Cu")
		(net "M_J_CPU0_SB_DQ<0>")
	)
	(segment
		(start 422.577006 -281.060144)
		(end 425.601638 -281.060144)
		(width 0.14478)
		(layer "In4.Cu")
		(net "M_J_CPU0_SB_DQ<0>")
	)
	(segment
		(start 413.569912 -281.910028)
		(end 415.621724 -281.060144)
		(width 0.14478)
		(layer "In4.Cu")
		(net "M_J_CPU0_SB_DQ<0>")
	)
	(arc
		(start 382.291844 -274.408646)
		(mid 382.5748 -274.332469)
		(end 382.857756 -274.408646)
		(width 0.0889)
		(layer "In4.Cu")
		(net "M_J_CPU0_SB_DQ<0>")
	)
	(arc
		(start 391.691876 -274.408646)
		(mid 391.961645 -274.332623)
		(end 392.234674 -274.395946)
		(width 0.0889)
		(layer "In4.Cu")
		(net "M_J_CPU0_SB_DQ<0>")
	)
	(arc
		(start 388.506208 -274.413472)
		(mid 388.689716 -274.458966)
		(end 388.871968 -274.408646)
		(width 0.0889)
		(layer "In4.Cu")
		(net "M_J_CPU0_SB_DQ<0>")
	)
	(arc
		(start 381.35179 -274.408646)
		(mid 381.634746 -274.332469)
		(end 381.917702 -274.408646)
		(width 0.0889)
		(layer "In4.Cu")
		(net "M_J_CPU0_SB_DQ<0>")
	)
	(arc
		(start 387.566154 -274.413472)
		(mid 387.749662 -274.458966)
		(end 387.931914 -274.408646)
		(width 0.0889)
		(layer "In4.Cu")
		(net "M_J_CPU0_SB_DQ<0>")
	)
	(arc
		(start 381.917702 -274.408646)
		(mid 382.099953 -274.458996)
		(end 382.283462 -274.413472)
		(width 0.0889)
		(layer "In4.Cu")
		(net "M_J_CPU0_SB_DQ<0>")
	)
	(arc
		(start 388.871968 -274.408646)
		(mid 389.154924 -274.332469)
		(end 389.43788 -274.408646)
		(width 0.0889)
		(layer "In4.Cu")
		(net "M_J_CPU0_SB_DQ<0>")
	)
	(arc
		(start 385.111752 -274.408646)
		(mid 385.394708 -274.332469)
		(end 385.677664 -274.408646)
		(width 0.0889)
		(layer "In4.Cu")
		(net "M_J_CPU0_SB_DQ<0>")
	)
	(arc
		(start 383.806192 -274.413472)
		(mid 383.9897 -274.458966)
		(end 384.171952 -274.408646)
		(width 0.0889)
		(layer "In4.Cu")
		(net "M_J_CPU0_SB_DQ<0>")
	)
	(arc
		(start 386.617718 -274.408646)
		(mid 386.799969 -274.458996)
		(end 386.983478 -274.413472)
		(width 0.0889)
		(layer "In4.Cu")
		(net "M_J_CPU0_SB_DQ<0>")
	)
	(arc
		(start 386.99186 -274.408646)
		(mid 387.274816 -274.332469)
		(end 387.557772 -274.408646)
		(width 0.0889)
		(layer "In4.Cu")
		(net "M_J_CPU0_SB_DQ<0>")
	)
	(arc
		(start 390.37768 -274.408646)
		(mid 390.559931 -274.458996)
		(end 390.74344 -274.413472)
		(width 0.0889)
		(layer "In4.Cu")
		(net "M_J_CPU0_SB_DQ<0>")
	)
	(arc
		(start 384.171952 -274.408646)
		(mid 384.454908 -274.332469)
		(end 384.737864 -274.408646)
		(width 0.0889)
		(layer "In4.Cu")
		(net "M_J_CPU0_SB_DQ<0>")
	)
	(arc
		(start 387.931914 -274.408646)
		(mid 388.21487 -274.332469)
		(end 388.497826 -274.408646)
		(width 0.0889)
		(layer "In4.Cu")
		(net "M_J_CPU0_SB_DQ<0>")
	)
	(arc
		(start 381.033274 -274.434808)
		(mid 381.195463 -274.457543)
		(end 381.35179 -274.408646)
		(width 0.0889)
		(layer "In4.Cu")
		(net "M_J_CPU0_SB_DQ<0>")
	)
	(arc
		(start 392.274552 -274.418806)
		(mid 392.453273 -274.458729)
		(end 392.62939 -274.408646)
		(width 0.0889)
		(layer "In4.Cu")
		(net "M_J_CPU0_SB_DQ<0>")
	)
	(arc
		(start 382.866138 -274.413472)
		(mid 383.049646 -274.458966)
		(end 383.231898 -274.408646)
		(width 0.0889)
		(layer "In4.Cu")
		(net "M_J_CPU0_SB_DQ<0>")
	)
	(arc
		(start 386.051806 -274.408646)
		(mid 386.334762 -274.332469)
		(end 386.617718 -274.408646)
		(width 0.0889)
		(layer "In4.Cu")
		(net "M_J_CPU0_SB_DQ<0>")
	)
	(arc
		(start 383.231898 -274.408646)
		(mid 383.514854 -274.332469)
		(end 383.79781 -274.408646)
		(width 0.0889)
		(layer "In4.Cu")
		(net "M_J_CPU0_SB_DQ<0>")
	)
	(arc
		(start 389.43788 -274.408646)
		(mid 389.624824 -274.458901)
		(end 389.811768 -274.408646)
		(width 0.0889)
		(layer "In4.Cu")
		(net "M_J_CPU0_SB_DQ<0>")
	)
	(arc
		(start 390.751822 -274.408646)
		(mid 391.034778 -274.332469)
		(end 391.317734 -274.408646)
		(width 0.0889)
		(layer "In4.Cu")
		(net "M_J_CPU0_SB_DQ<0>")
	)
	(arc
		(start 392.652758 -274.39493)
		(mid 392.926412 -274.331987)
		(end 393.196572 -274.408646)
		(width 0.0889)
		(layer "In4.Cu")
		(net "M_J_CPU0_SB_DQ<0>")
	)
	(arc
		(start 393.196572 -274.408646)
		(mid 393.287307 -274.44653)
		(end 393.384786 -274.459446)
		(width 0.0889)
		(layer "In4.Cu")
		(net "M_J_CPU0_SB_DQ<0>")
	)
	(arc
		(start 384.737864 -274.408646)
		(mid 384.924808 -274.458901)
		(end 385.111752 -274.408646)
		(width 0.0889)
		(layer "In4.Cu")
		(net "M_J_CPU0_SB_DQ<0>")
	)
	(arc
		(start 389.811768 -274.408646)
		(mid 390.094724 -274.332469)
		(end 390.37768 -274.408646)
		(width 0.0889)
		(layer "In4.Cu")
		(net "M_J_CPU0_SB_DQ<0>")
	)
	(arc
		(start 391.326116 -274.413472)
		(mid 391.509624 -274.458966)
		(end 391.691876 -274.408646)
		(width 0.0889)
		(layer "In4.Cu")
		(net "M_J_CPU0_SB_DQ<0>")
	)
	(arc
		(start 385.677664 -274.408646)
		(mid 385.859915 -274.458996)
		(end 386.043424 -274.413472)
		(width 0.0889)
		(layer "In4.Cu")
		(net "M_J_CPU0_SB_DQ<0>")
	)
	(segment
		(start 380.22784 -266.530074)
		(end 380.694946 -266.796012)
		(width 0.10668)
		(layer "F.Cu")
		(net "M_J_CPU0_SB_CS_N<1>")
	)
	(segment
		(start 428.680626 -268.00429)
		(end 428.931324 -268.00429)
		(width 0.14478)
		(layer "In4.Cu")
		(net "M_J_CPU0_SB_CS_N<1>")
	)
	(segment
		(start 414.915858 -268.310106)
		(end 418.122608 -268.310106)
		(width 0.14478)
		(layer "In4.Cu")
		(net "M_J_CPU0_SB_CS_N<1>")
	)
	(segment
		(start 428.931324 -268.00429)
		(end 429.23714 -268.310106)
		(width 0.14478)
		(layer "In4.Cu")
		(net "M_J_CPU0_SB_CS_N<1>")
	)
	(segment
		(start 380.84887 -266.530582)
		(end 380.944882 -266.505182)
		(width 0.0889)
		(layer "In4.Cu")
		(net "M_J_CPU0_SB_CS_N<1>")
	)
	(segment
		(start 393.456414 -266.42441)
		(end 394.177774 -265.70305)
		(width 0.0889)
		(layer "In4.Cu")
		(net "M_J_CPU0_SB_CS_N<1>")
	)
	(segment
		(start 429.487838 -268.310106)
		(end 429.793654 -268.00429)
		(width 0.14478)
		(layer "In4.Cu")
		(net "M_J_CPU0_SB_CS_N<1>")
	)
	(segment
		(start 426.172884 -268.007592)
		(end 426.475398 -268.310106)
		(width 0.14478)
		(layer "In4.Cu")
		(net "M_J_CPU0_SB_CS_N<1>")
	)
	(segment
		(start 425.621704 -268.310106)
		(end 425.924218 -268.007592)
		(width 0.14478)
		(layer "In4.Cu")
		(net "M_J_CPU0_SB_CS_N<1>")
	)
	(segment
		(start 392.974322 -266.42441)
		(end 393.456414 -266.42441)
		(width 0.0889)
		(layer "In4.Cu")
		(net "M_J_CPU0_SB_CS_N<1>")
	)
	(segment
		(start 428.37481 -268.310106)
		(end 428.680626 -268.00429)
		(width 0.14478)
		(layer "In4.Cu")
		(net "M_J_CPU0_SB_CS_N<1>")
	)
	(segment
		(start 392.140948 -266.462256)
		(end 392.161014 -266.473686)
		(width 0.0889)
		(layer "In4.Cu")
		(net "M_J_CPU0_SB_CS_N<1>")
	)
	(segment
		(start 394.177774 -265.70305)
		(end 395.965172 -265.70305)
		(width 0.0889)
		(layer "In4.Cu")
		(net "M_J_CPU0_SB_CS_N<1>")
	)
	(segment
		(start 389.333486 -266.468606)
		(end 389.341868 -266.473432)
		(width 0.0889)
		(layer "In4.Cu")
		(net "M_J_CPU0_SB_CS_N<1>")
	)
	(segment
		(start 422.484296 -268.310106)
		(end 425.621704 -268.310106)
		(width 0.14478)
		(layer "In4.Cu")
		(net "M_J_CPU0_SB_CS_N<1>")
	)
	(segment
		(start 414.06572 -269.160244)
		(end 414.915858 -268.310106)
		(width 0.14478)
		(layer "In4.Cu")
		(net "M_J_CPU0_SB_CS_N<1>")
	)
	(segment
		(start 412.419292 -269.160244)
		(end 414.06572 -269.160244)
		(width 0.14478)
		(layer "In4.Cu")
		(net "M_J_CPU0_SB_CS_N<1>")
	)
	(segment
		(start 389.90778 -266.473432)
		(end 389.916162 -266.468606)
		(width 0.0889)
		(layer "In4.Cu")
		(net "M_J_CPU0_SB_CS_N<1>")
	)
	(segment
		(start 421.634158 -269.160244)
		(end 422.484296 -268.310106)
		(width 0.14478)
		(layer "In4.Cu")
		(net "M_J_CPU0_SB_CS_N<1>")
	)
	(segment
		(start 408.962098 -265.70305)
		(end 412.419292 -269.160244)
		(width 0.14478)
		(layer "In4.Cu")
		(net "M_J_CPU0_SB_CS_N<1>")
	)
	(segment
		(start 386.147818 -266.473432)
		(end 386.1562 -266.468606)
		(width 0.0889)
		(layer "In4.Cu")
		(net "M_J_CPU0_SB_CS_N<1>")
	)
	(segment
		(start 430.044352 -268.00429)
		(end 430.350168 -268.310106)
		(width 0.14478)
		(layer "In4.Cu")
		(net "M_J_CPU0_SB_CS_N<1>")
	)
	(segment
		(start 429.23714 -268.310106)
		(end 429.487838 -268.310106)
		(width 0.14478)
		(layer "In4.Cu")
		(net "M_J_CPU0_SB_CS_N<1>")
	)
	(segment
		(start 381.447802 -266.473432)
		(end 381.456184 -266.468606)
		(width 0.0889)
		(layer "In4.Cu")
		(net "M_J_CPU0_SB_CS_N<1>")
	)
	(segment
		(start 385.207764 -266.473432)
		(end 385.216146 -266.468606)
		(width 0.0889)
		(layer "In4.Cu")
		(net "M_J_CPU0_SB_CS_N<1>")
	)
	(segment
		(start 392.161014 -266.473686)
		(end 392.182604 -266.486132)
		(width 0.0889)
		(layer "In4.Cu")
		(net "M_J_CPU0_SB_CS_N<1>")
	)
	(segment
		(start 380.694946 -266.796012)
		(end 380.84887 -266.530582)
		(width 0.0889)
		(layer "In4.Cu")
		(net "M_J_CPU0_SB_CS_N<1>")
	)
	(segment
		(start 434.575204 -268.310106)
		(end 435.000146 -268.735048)
		(width 0.14478)
		(layer "In4.Cu")
		(net "M_J_CPU0_SB_CS_N<1>")
	)
	(segment
		(start 429.793654 -268.00429)
		(end 430.044352 -268.00429)
		(width 0.14478)
		(layer "In4.Cu")
		(net "M_J_CPU0_SB_CS_N<1>")
	)
	(segment
		(start 395.965172 -265.70305)
		(end 408.962098 -265.70305)
		(width 0.14478)
		(layer "In4.Cu")
		(net "M_J_CPU0_SB_CS_N<1>")
	)
	(segment
		(start 383.693416 -266.468606)
		(end 383.701798 -266.473432)
		(width 0.0889)
		(layer "In4.Cu")
		(net "M_J_CPU0_SB_CS_N<1>")
	)
	(segment
		(start 430.350168 -268.310106)
		(end 434.575204 -268.310106)
		(width 0.14478)
		(layer "In4.Cu")
		(net "M_J_CPU0_SB_CS_N<1>")
	)
	(segment
		(start 418.972746 -269.160244)
		(end 421.634158 -269.160244)
		(width 0.14478)
		(layer "In4.Cu")
		(net "M_J_CPU0_SB_CS_N<1>")
	)
	(segment
		(start 388.393432 -266.468606)
		(end 388.401814 -266.473432)
		(width 0.0889)
		(layer "In4.Cu")
		(net "M_J_CPU0_SB_CS_N<1>")
	)
	(segment
		(start 425.924218 -268.007592)
		(end 426.172884 -268.007592)
		(width 0.14478)
		(layer "In4.Cu")
		(net "M_J_CPU0_SB_CS_N<1>")
	)
	(segment
		(start 426.475398 -268.310106)
		(end 428.37481 -268.310106)
		(width 0.14478)
		(layer "In4.Cu")
		(net "M_J_CPU0_SB_CS_N<1>")
	)
	(segment
		(start 384.63347 -266.468606)
		(end 384.641852 -266.473432)
		(width 0.0889)
		(layer "In4.Cu")
		(net "M_J_CPU0_SB_CS_N<1>")
	)
	(segment
		(start 418.122608 -268.310106)
		(end 418.972746 -269.160244)
		(width 0.14478)
		(layer "In4.Cu")
		(net "M_J_CPU0_SB_CS_N<1>")
	)
	(arc
		(start 387.087872 -266.473432)
		(mid 387.274816 -266.423177)
		(end 387.46176 -266.473432)
		(width 0.0889)
		(layer "In4.Cu")
		(net "M_J_CPU0_SB_CS_N<1>")
	)
	(arc
		(start 390.281922 -266.473432)
		(mid 390.564878 -266.549609)
		(end 390.847834 -266.473432)
		(width 0.0889)
		(layer "In4.Cu")
		(net "M_J_CPU0_SB_CS_N<1>")
	)
	(arc
		(start 385.216146 -266.468606)
		(mid 385.399654 -266.423112)
		(end 385.581906 -266.473432)
		(width 0.0889)
		(layer "In4.Cu")
		(net "M_J_CPU0_SB_CS_N<1>")
	)
	(arc
		(start 384.641852 -266.473432)
		(mid 384.924808 -266.549609)
		(end 385.207764 -266.473432)
		(width 0.0889)
		(layer "In4.Cu")
		(net "M_J_CPU0_SB_CS_N<1>")
	)
	(arc
		(start 380.944882 -266.505182)
		(mid 381.20009 -266.548659)
		(end 381.447802 -266.473432)
		(width 0.0889)
		(layer "In4.Cu")
		(net "M_J_CPU0_SB_CS_N<1>")
	)
	(arc
		(start 382.387856 -266.473432)
		(mid 382.5748 -266.423177)
		(end 382.761744 -266.473432)
		(width 0.0889)
		(layer "In4.Cu")
		(net "M_J_CPU0_SB_CS_N<1>")
	)
	(arc
		(start 390.847834 -266.473432)
		(mid 391.034778 -266.423177)
		(end 391.221722 -266.473432)
		(width 0.0889)
		(layer "In4.Cu")
		(net "M_J_CPU0_SB_CS_N<1>")
	)
	(arc
		(start 386.1562 -266.468606)
		(mid 386.339708 -266.423112)
		(end 386.52196 -266.473432)
		(width 0.0889)
		(layer "In4.Cu")
		(net "M_J_CPU0_SB_CS_N<1>")
	)
	(arc
		(start 389.916162 -266.468606)
		(mid 390.09967 -266.423112)
		(end 390.281922 -266.473432)
		(width 0.0889)
		(layer "In4.Cu")
		(net "M_J_CPU0_SB_CS_N<1>")
	)
	(arc
		(start 391.787634 -266.473432)
		(mid 391.962873 -266.423361)
		(end 392.140948 -266.462256)
		(width 0.0889)
		(layer "In4.Cu")
		(net "M_J_CPU0_SB_CS_N<1>")
	)
	(arc
		(start 391.221722 -266.473432)
		(mid 391.504678 -266.549609)
		(end 391.787634 -266.473432)
		(width 0.0889)
		(layer "In4.Cu")
		(net "M_J_CPU0_SB_CS_N<1>")
	)
	(arc
		(start 381.456184 -266.468606)
		(mid 381.639692 -266.423112)
		(end 381.821944 -266.473432)
		(width 0.0889)
		(layer "In4.Cu")
		(net "M_J_CPU0_SB_CS_N<1>")
	)
	(arc
		(start 381.821944 -266.473432)
		(mid 382.1049 -266.549609)
		(end 382.387856 -266.473432)
		(width 0.0889)
		(layer "In4.Cu")
		(net "M_J_CPU0_SB_CS_N<1>")
	)
	(arc
		(start 383.327656 -266.473432)
		(mid 383.509907 -266.423082)
		(end 383.693416 -266.468606)
		(width 0.0889)
		(layer "In4.Cu")
		(net "M_J_CPU0_SB_CS_N<1>")
	)
	(arc
		(start 392.725402 -266.473432)
		(mid 392.845762 -266.428127)
		(end 392.974322 -266.42441)
		(width 0.0889)
		(layer "In4.Cu")
		(net "M_J_CPU0_SB_CS_N<1>")
	)
	(arc
		(start 389.341868 -266.473432)
		(mid 389.624824 -266.549609)
		(end 389.90778 -266.473432)
		(width 0.0889)
		(layer "In4.Cu")
		(net "M_J_CPU0_SB_CS_N<1>")
	)
	(arc
		(start 384.26771 -266.473432)
		(mid 384.449961 -266.423082)
		(end 384.63347 -266.468606)
		(width 0.0889)
		(layer "In4.Cu")
		(net "M_J_CPU0_SB_CS_N<1>")
	)
	(arc
		(start 388.027672 -266.473432)
		(mid 388.209923 -266.423082)
		(end 388.393432 -266.468606)
		(width 0.0889)
		(layer "In4.Cu")
		(net "M_J_CPU0_SB_CS_N<1>")
	)
	(arc
		(start 387.46176 -266.473432)
		(mid 387.744716 -266.549609)
		(end 388.027672 -266.473432)
		(width 0.0889)
		(layer "In4.Cu")
		(net "M_J_CPU0_SB_CS_N<1>")
	)
	(arc
		(start 388.967726 -266.473432)
		(mid 389.149977 -266.423082)
		(end 389.333486 -266.468606)
		(width 0.0889)
		(layer "In4.Cu")
		(net "M_J_CPU0_SB_CS_N<1>")
	)
	(arc
		(start 383.701798 -266.473432)
		(mid 383.984754 -266.549609)
		(end 384.26771 -266.473432)
		(width 0.0889)
		(layer "In4.Cu")
		(net "M_J_CPU0_SB_CS_N<1>")
	)
	(arc
		(start 392.182604 -266.486132)
		(mid 392.455633 -266.549451)
		(end 392.725402 -266.473432)
		(width 0.0889)
		(layer "In4.Cu")
		(net "M_J_CPU0_SB_CS_N<1>")
	)
	(arc
		(start 385.581906 -266.473432)
		(mid 385.864862 -266.549609)
		(end 386.147818 -266.473432)
		(width 0.0889)
		(layer "In4.Cu")
		(net "M_J_CPU0_SB_CS_N<1>")
	)
	(arc
		(start 382.761744 -266.473432)
		(mid 383.0447 -266.549609)
		(end 383.327656 -266.473432)
		(width 0.0889)
		(layer "In4.Cu")
		(net "M_J_CPU0_SB_CS_N<1>")
	)
	(arc
		(start 388.401814 -266.473432)
		(mid 388.68477 -266.549609)
		(end 388.967726 -266.473432)
		(width 0.0889)
		(layer "In4.Cu")
		(net "M_J_CPU0_SB_CS_N<1>")
	)
	(arc
		(start 386.52196 -266.473432)
		(mid 386.804916 -266.549609)
		(end 387.087872 -266.473432)
		(width 0.0889)
		(layer "In4.Cu")
		(net "M_J_CPU0_SB_CS_N<1>")
	)
	(segment
		(start 378.817886 -265.720068)
		(end 379.284738 -265.986006)
		(width 0.10668)
		(layer "F.Cu")
		(net "M_J_CPU0_SB_CS_N<0>")
	)
	(segment
		(start 387.557772 -265.663426)
		(end 387.566154 -265.6586)
		(width 0.0889)
		(layer "In4.Cu")
		(net "M_J_CPU0_SB_CS_N<0>")
	)
	(segment
		(start 390.74344 -265.6586)
		(end 390.751822 -265.663426)
		(width 0.0889)
		(layer "In4.Cu")
		(net "M_J_CPU0_SB_CS_N<0>")
	)
	(segment
		(start 414.183068 -268.310106)
		(end 415.032952 -267.460222)
		(width 0.14478)
		(layer "In4.Cu")
		(net "M_J_CPU0_SB_CS_N<0>")
	)
	(segment
		(start 393.192508 -265.666982)
		(end 393.900152 -265.27379)
		(width 0.0889)
		(layer "In4.Cu")
		(net "M_J_CPU0_SB_CS_N<0>")
	)
	(segment
		(start 418.907468 -268.310106)
		(end 421.727122 -268.310106)
		(width 0.14478)
		(layer "In4.Cu")
		(net "M_J_CPU0_SB_CS_N<0>")
	)
	(segment
		(start 409.143454 -265.24839)
		(end 412.20517 -268.310106)
		(width 0.14478)
		(layer "In4.Cu")
		(net "M_J_CPU0_SB_CS_N<0>")
	)
	(segment
		(start 386.043424 -265.6586)
		(end 386.051806 -265.663426)
		(width 0.0889)
		(layer "In4.Cu")
		(net "M_J_CPU0_SB_CS_N<0>")
	)
	(segment
		(start 395.976856 -265.24839)
		(end 409.143454 -265.24839)
		(width 0.14478)
		(layer "In4.Cu")
		(net "M_J_CPU0_SB_CS_N<0>")
	)
	(segment
		(start 395.202156 -265.24839)
		(end 395.976856 -265.24839)
		(width 0.0889)
		(layer "In4.Cu")
		(net "M_J_CPU0_SB_CS_N<0>")
	)
	(segment
		(start 393.900152 -265.27379)
		(end 395.176756 -265.27379)
		(width 0.0889)
		(layer "In4.Cu")
		(net "M_J_CPU0_SB_CS_N<0>")
	)
	(segment
		(start 382.857756 -265.663426)
		(end 382.866138 -265.6586)
		(width 0.0889)
		(layer "In4.Cu")
		(net "M_J_CPU0_SB_CS_N<0>")
	)
	(segment
		(start 412.20517 -268.310106)
		(end 414.183068 -268.310106)
		(width 0.14478)
		(layer "In4.Cu")
		(net "M_J_CPU0_SB_CS_N<0>")
	)
	(segment
		(start 386.983478 -265.6586)
		(end 386.99186 -265.663426)
		(width 0.0889)
		(layer "In4.Cu")
		(net "M_J_CPU0_SB_CS_N<0>")
	)
	(segment
		(start 388.497826 -265.663426)
		(end 388.506208 -265.6586)
		(width 0.0889)
		(layer "In4.Cu")
		(net "M_J_CPU0_SB_CS_N<0>")
	)
	(segment
		(start 422.577006 -267.460222)
		(end 438.675272 -267.460222)
		(width 0.14478)
		(layer "In4.Cu")
		(net "M_J_CPU0_SB_CS_N<0>")
	)
	(segment
		(start 391.317734 -265.663426)
		(end 391.326116 -265.6586)
		(width 0.0889)
		(layer "In4.Cu")
		(net "M_J_CPU0_SB_CS_N<0>")
	)
	(segment
		(start 383.79781 -265.663426)
		(end 383.806192 -265.6586)
		(width 0.0889)
		(layer "In4.Cu")
		(net "M_J_CPU0_SB_CS_N<0>")
	)
	(segment
		(start 392.62431 -265.6586)
		(end 392.632692 -265.663426)
		(width 0.0889)
		(layer "In4.Cu")
		(net "M_J_CPU0_SB_CS_N<0>")
	)
	(segment
		(start 415.032952 -267.460222)
		(end 418.057584 -267.460222)
		(width 0.14478)
		(layer "In4.Cu")
		(net "M_J_CPU0_SB_CS_N<0>")
	)
	(segment
		(start 438.675272 -267.460222)
		(end 439.100214 -267.885164)
		(width 0.14478)
		(layer "In4.Cu")
		(net "M_J_CPU0_SB_CS_N<0>")
	)
	(segment
		(start 379.438916 -265.720576)
		(end 379.535182 -265.695176)
		(width 0.0889)
		(layer "In4.Cu")
		(net "M_J_CPU0_SB_CS_N<0>")
	)
	(segment
		(start 379.284738 -265.986006)
		(end 379.438916 -265.720576)
		(width 0.0889)
		(layer "In4.Cu")
		(net "M_J_CPU0_SB_CS_N<0>")
	)
	(segment
		(start 380.037848 -265.663426)
		(end 380.04623 -265.6586)
		(width 0.0889)
		(layer "In4.Cu")
		(net "M_J_CPU0_SB_CS_N<0>")
	)
	(segment
		(start 418.057584 -267.460222)
		(end 418.907468 -268.310106)
		(width 0.14478)
		(layer "In4.Cu")
		(net "M_J_CPU0_SB_CS_N<0>")
	)
	(segment
		(start 421.727122 -268.310106)
		(end 422.577006 -267.460222)
		(width 0.14478)
		(layer "In4.Cu")
		(net "M_J_CPU0_SB_CS_N<0>")
	)
	(segment
		(start 391.691876 -265.663426)
		(end 391.70229 -265.669522)
		(width 0.0889)
		(layer "In4.Cu")
		(net "M_J_CPU0_SB_CS_N<0>")
	)
	(segment
		(start 395.176756 -265.27379)
		(end 395.202156 -265.24839)
		(width 0.0889)
		(layer "In4.Cu")
		(net "M_J_CPU0_SB_CS_N<0>")
	)
	(segment
		(start 382.283462 -265.6586)
		(end 382.291844 -265.663426)
		(width 0.0889)
		(layer "In4.Cu")
		(net "M_J_CPU0_SB_CS_N<0>")
	)
	(arc
		(start 381.917702 -265.663426)
		(mid 382.099953 -265.613076)
		(end 382.283462 -265.6586)
		(width 0.0889)
		(layer "In4.Cu")
		(net "M_J_CPU0_SB_CS_N<0>")
	)
	(arc
		(start 391.326116 -265.6586)
		(mid 391.509624 -265.613106)
		(end 391.691876 -265.663426)
		(width 0.0889)
		(layer "In4.Cu")
		(net "M_J_CPU0_SB_CS_N<0>")
	)
	(arc
		(start 384.737864 -265.663426)
		(mid 384.924808 -265.613171)
		(end 385.111752 -265.663426)
		(width 0.0889)
		(layer "In4.Cu")
		(net "M_J_CPU0_SB_CS_N<0>")
	)
	(arc
		(start 392.258042 -265.663426)
		(mid 392.440547 -265.612949)
		(end 392.62431 -265.6586)
		(width 0.0889)
		(layer "In4.Cu")
		(net "M_J_CPU0_SB_CS_N<0>")
	)
	(arc
		(start 385.111752 -265.663426)
		(mid 385.394708 -265.739603)
		(end 385.677664 -265.663426)
		(width 0.0889)
		(layer "In4.Cu")
		(net "M_J_CPU0_SB_CS_N<0>")
	)
	(arc
		(start 387.931914 -265.663426)
		(mid 388.21487 -265.739603)
		(end 388.497826 -265.663426)
		(width 0.0889)
		(layer "In4.Cu")
		(net "M_J_CPU0_SB_CS_N<0>")
	)
	(arc
		(start 383.806192 -265.6586)
		(mid 383.9897 -265.613106)
		(end 384.171952 -265.663426)
		(width 0.0889)
		(layer "In4.Cu")
		(net "M_J_CPU0_SB_CS_N<0>")
	)
	(arc
		(start 384.171952 -265.663426)
		(mid 384.454908 -265.739603)
		(end 384.737864 -265.663426)
		(width 0.0889)
		(layer "In4.Cu")
		(net "M_J_CPU0_SB_CS_N<0>")
	)
	(arc
		(start 382.291844 -265.663426)
		(mid 382.5748 -265.739603)
		(end 382.857756 -265.663426)
		(width 0.0889)
		(layer "In4.Cu")
		(net "M_J_CPU0_SB_CS_N<0>")
	)
	(arc
		(start 380.41199 -265.663426)
		(mid 380.694946 -265.739603)
		(end 380.977902 -265.663426)
		(width 0.0889)
		(layer "In4.Cu")
		(net "M_J_CPU0_SB_CS_N<0>")
	)
	(arc
		(start 382.866138 -265.6586)
		(mid 383.049646 -265.613106)
		(end 383.231898 -265.663426)
		(width 0.0889)
		(layer "In4.Cu")
		(net "M_J_CPU0_SB_CS_N<0>")
	)
	(arc
		(start 386.617718 -265.663426)
		(mid 386.799969 -265.613076)
		(end 386.983478 -265.6586)
		(width 0.0889)
		(layer "In4.Cu")
		(net "M_J_CPU0_SB_CS_N<0>")
	)
	(arc
		(start 385.677664 -265.663426)
		(mid 385.859915 -265.613076)
		(end 386.043424 -265.6586)
		(width 0.0889)
		(layer "In4.Cu")
		(net "M_J_CPU0_SB_CS_N<0>")
	)
	(arc
		(start 386.051806 -265.663426)
		(mid 386.334762 -265.739603)
		(end 386.617718 -265.663426)
		(width 0.0889)
		(layer "In4.Cu")
		(net "M_J_CPU0_SB_CS_N<0>")
	)
	(arc
		(start 388.871968 -265.663426)
		(mid 389.154924 -265.739603)
		(end 389.43788 -265.663426)
		(width 0.0889)
		(layer "In4.Cu")
		(net "M_J_CPU0_SB_CS_N<0>")
	)
	(arc
		(start 389.811768 -265.663426)
		(mid 390.094724 -265.739603)
		(end 390.37768 -265.663426)
		(width 0.0889)
		(layer "In4.Cu")
		(net "M_J_CPU0_SB_CS_N<0>")
	)
	(arc
		(start 380.977902 -265.663426)
		(mid 381.164846 -265.613171)
		(end 381.35179 -265.663426)
		(width 0.0889)
		(layer "In4.Cu")
		(net "M_J_CPU0_SB_CS_N<0>")
	)
	(arc
		(start 387.566154 -265.6586)
		(mid 387.749662 -265.613106)
		(end 387.931914 -265.663426)
		(width 0.0889)
		(layer "In4.Cu")
		(net "M_J_CPU0_SB_CS_N<0>")
	)
	(arc
		(start 388.506208 -265.6586)
		(mid 388.689716 -265.613106)
		(end 388.871968 -265.663426)
		(width 0.0889)
		(layer "In4.Cu")
		(net "M_J_CPU0_SB_CS_N<0>")
	)
	(arc
		(start 386.99186 -265.663426)
		(mid 387.274816 -265.739603)
		(end 387.557772 -265.663426)
		(width 0.0889)
		(layer "In4.Cu")
		(net "M_J_CPU0_SB_CS_N<0>")
	)
	(arc
		(start 383.231898 -265.663426)
		(mid 383.514854 -265.739603)
		(end 383.79781 -265.663426)
		(width 0.0889)
		(layer "In4.Cu")
		(net "M_J_CPU0_SB_CS_N<0>")
	)
	(arc
		(start 379.535182 -265.695176)
		(mid 379.790247 -265.738527)
		(end 380.037848 -265.663426)
		(width 0.0889)
		(layer "In4.Cu")
		(net "M_J_CPU0_SB_CS_N<0>")
	)
	(arc
		(start 390.37768 -265.663426)
		(mid 390.559931 -265.613076)
		(end 390.74344 -265.6586)
		(width 0.0889)
		(layer "In4.Cu")
		(net "M_J_CPU0_SB_CS_N<0>")
	)
	(arc
		(start 392.632692 -265.663426)
		(mid 392.91212 -265.739592)
		(end 393.192508 -265.666982)
		(width 0.0889)
		(layer "In4.Cu")
		(net "M_J_CPU0_SB_CS_N<0>")
	)
	(arc
		(start 390.751822 -265.663426)
		(mid 391.034778 -265.739603)
		(end 391.317734 -265.663426)
		(width 0.0889)
		(layer "In4.Cu")
		(net "M_J_CPU0_SB_CS_N<0>")
	)
	(arc
		(start 389.43788 -265.663426)
		(mid 389.624824 -265.613171)
		(end 389.811768 -265.663426)
		(width 0.0889)
		(layer "In4.Cu")
		(net "M_J_CPU0_SB_CS_N<0>")
	)
	(arc
		(start 391.70229 -265.669522)
		(mid 391.980976 -265.739742)
		(end 392.258042 -265.663426)
		(width 0.0889)
		(layer "In4.Cu")
		(net "M_J_CPU0_SB_CS_N<0>")
	)
	(arc
		(start 380.04623 -265.6586)
		(mid 380.229738 -265.613106)
		(end 380.41199 -265.663426)
		(width 0.0889)
		(layer "In4.Cu")
		(net "M_J_CPU0_SB_CS_N<0>")
	)
	(arc
		(start 381.35179 -265.663426)
		(mid 381.634746 -265.739603)
		(end 381.917702 -265.663426)
		(width 0.0889)
		(layer "In4.Cu")
		(net "M_J_CPU0_SB_CS_N<0>")
	)
	(segment
		(start 378.817886 -270.580104)
		(end 379.284738 -270.846042)
		(width 0.10668)
		(layer "F.Cu")
		(net "M_J_CPU0_SB_CB<7>")
	)
	(segment
		(start 430.088548 -273.571716)
		(end 430.088548 -274.135088)
		(width 0.14478)
		(layer "In4.Cu")
		(net "M_J_CPU0_SB_CB<7>")
	)
	(segment
		(start 386.051806 -270.523462)
		(end 386.043424 -270.518636)
		(width 0.0889)
		(layer "In4.Cu")
		(net "M_J_CPU0_SB_CB<7>")
	)
	(segment
		(start 428.824136 -274.609052)
		(end 428.59579 -274.609052)
		(width 0.14478)
		(layer "In4.Cu")
		(net "M_J_CPU0_SB_CB<7>")
	)
	(segment
		(start 392.69797 -269.730728)
		(end 392.697208 -269.731236)
		(width 0.0889)
		(layer "In4.Cu")
		(net "M_J_CPU0_SB_CB<7>")
	)
	(segment
		(start 382.291844 -270.523462)
		(end 382.283462 -270.518636)
		(width 0.0889)
		(layer "In4.Cu")
		(net "M_J_CPU0_SB_CB<7>")
	)
	(segment
		(start 430.088548 -274.135088)
		(end 429.927004 -274.296632)
		(width 0.14478)
		(layer "In4.Cu")
		(net "M_J_CPU0_SB_CB<7>")
	)
	(segment
		(start 428.434246 -273.571716)
		(end 428.272702 -273.410172)
		(width 0.14478)
		(layer "In4.Cu")
		(net "M_J_CPU0_SB_CB<7>")
	)
	(segment
		(start 392.296904 -270.500602)
		(end 392.257788 -270.523462)
		(width 0.0889)
		(layer "In4.Cu")
		(net "M_J_CPU0_SB_CB<7>")
	)
	(segment
		(start 432.464464 -273.410172)
		(end 430.250092 -273.410172)
		(width 0.14478)
		(layer "In4.Cu")
		(net "M_J_CPU0_SB_CB<7>")
	)
	(segment
		(start 433.73929 -274.684998)
		(end 432.464464 -273.410172)
		(width 0.14478)
		(layer "In4.Cu")
		(net "M_J_CPU0_SB_CB<7>")
	)
	(segment
		(start 387.566154 -270.518636)
		(end 387.557772 -270.523462)
		(width 0.0889)
		(layer "In4.Cu")
		(net "M_J_CPU0_SB_CB<7>")
	)
	(segment
		(start 382.866138 -270.518636)
		(end 382.857756 -270.523462)
		(width 0.0889)
		(layer "In4.Cu")
		(net "M_J_CPU0_SB_CB<7>")
	)
	(segment
		(start 409.235656 -271.290288)
		(end 408.051 -271.290288)
		(width 0.14478)
		(layer "In4.Cu")
		(net "M_J_CPU0_SB_CB<7>")
	)
	(segment
		(start 429.698658 -274.296632)
		(end 429.537114 -274.135088)
		(width 0.14478)
		(layer "In4.Cu")
		(net "M_J_CPU0_SB_CB<7>")
	)
	(segment
		(start 395.233652 -268.83741)
		(end 394.579602 -268.83741)
		(width 0.0889)
		(layer "In4.Cu")
		(net "M_J_CPU0_SB_CB<7>")
	)
	(segment
		(start 390.751822 -270.523462)
		(end 390.74344 -270.518636)
		(width 0.0889)
		(layer "In4.Cu")
		(net "M_J_CPU0_SB_CB<7>")
	)
	(segment
		(start 405.440642 -268.67993)
		(end 395.96695 -268.67993)
		(width 0.14478)
		(layer "In4.Cu")
		(net "M_J_CPU0_SB_CB<7>")
	)
	(segment
		(start 435.000146 -274.684998)
		(end 433.73929 -274.684998)
		(width 0.14478)
		(layer "In4.Cu")
		(net "M_J_CPU0_SB_CB<7>")
	)
	(segment
		(start 429.537114 -274.135088)
		(end 429.537114 -273.571716)
		(width 0.14478)
		(layer "In4.Cu")
		(net "M_J_CPU0_SB_CB<7>")
	)
	(segment
		(start 394.579602 -268.83741)
		(end 393.790424 -269.626588)
		(width 0.0889)
		(layer "In4.Cu")
		(net "M_J_CPU0_SB_CB<7>")
	)
	(segment
		(start 428.434246 -274.447508)
		(end 428.434246 -273.571716)
		(width 0.14478)
		(layer "In4.Cu")
		(net "M_J_CPU0_SB_CB<7>")
	)
	(segment
		(start 392.727688 -269.713456)
		(end 392.69797 -269.730728)
		(width 0.0889)
		(layer "In4.Cu")
		(net "M_J_CPU0_SB_CB<7>")
	)
	(segment
		(start 429.147224 -273.410172)
		(end 428.98568 -273.571716)
		(width 0.14478)
		(layer "In4.Cu")
		(net "M_J_CPU0_SB_CB<7>")
	)
	(segment
		(start 429.537114 -273.571716)
		(end 429.37557 -273.410172)
		(width 0.14478)
		(layer "In4.Cu")
		(net "M_J_CPU0_SB_CB<7>")
	)
	(segment
		(start 379.438916 -270.580612)
		(end 379.284738 -270.846042)
		(width 0.0889)
		(layer "In4.Cu")
		(net "M_J_CPU0_SB_CB<7>")
	)
	(segment
		(start 417.869116 -273.410172)
		(end 415.032952 -273.410172)
		(width 0.14478)
		(layer "In4.Cu")
		(net "M_J_CPU0_SB_CB<7>")
	)
	(segment
		(start 412.195772 -274.250404)
		(end 409.235656 -271.290288)
		(width 0.14478)
		(layer "In4.Cu")
		(net "M_J_CPU0_SB_CB<7>")
	)
	(segment
		(start 428.272702 -273.410172)
		(end 422.577006 -273.410172)
		(width 0.14478)
		(layer "In4.Cu")
		(net "M_J_CPU0_SB_CB<7>")
	)
	(segment
		(start 414.19272 -274.250404)
		(end 412.195772 -274.250404)
		(width 0.14478)
		(layer "In4.Cu")
		(net "M_J_CPU0_SB_CB<7>")
	)
	(segment
		(start 428.98568 -273.571716)
		(end 428.98568 -274.447508)
		(width 0.14478)
		(layer "In4.Cu")
		(net "M_J_CPU0_SB_CB<7>")
	)
	(segment
		(start 395.391132 -268.67993)
		(end 395.233652 -268.83741)
		(width 0.0889)
		(layer "In4.Cu")
		(net "M_J_CPU0_SB_CB<7>")
	)
	(segment
		(start 418.719 -274.260056)
		(end 417.869116 -273.410172)
		(width 0.14478)
		(layer "In4.Cu")
		(net "M_J_CPU0_SB_CB<7>")
	)
	(segment
		(start 429.927004 -274.296632)
		(end 429.698658 -274.296632)
		(width 0.14478)
		(layer "In4.Cu")
		(net "M_J_CPU0_SB_CB<7>")
	)
	(segment
		(start 383.806192 -270.518636)
		(end 383.79781 -270.523462)
		(width 0.0889)
		(layer "In4.Cu")
		(net "M_J_CPU0_SB_CB<7>")
	)
	(segment
		(start 428.59579 -274.609052)
		(end 428.434246 -274.447508)
		(width 0.14478)
		(layer "In4.Cu")
		(net "M_J_CPU0_SB_CB<7>")
	)
	(segment
		(start 422.577006 -273.410172)
		(end 421.727122 -274.260056)
		(width 0.14478)
		(layer "In4.Cu")
		(net "M_J_CPU0_SB_CB<7>")
	)
	(segment
		(start 395.96695 -268.67993)
		(end 395.391132 -268.67993)
		(width 0.0889)
		(layer "In4.Cu")
		(net "M_J_CPU0_SB_CB<7>")
	)
	(segment
		(start 388.506208 -270.518636)
		(end 388.497826 -270.523462)
		(width 0.0889)
		(layer "In4.Cu")
		(net "M_J_CPU0_SB_CB<7>")
	)
	(segment
		(start 408.051 -271.290288)
		(end 405.440642 -268.67993)
		(width 0.14478)
		(layer "In4.Cu")
		(net "M_J_CPU0_SB_CB<7>")
	)
	(segment
		(start 379.535182 -270.555212)
		(end 379.438916 -270.580612)
		(width 0.0889)
		(layer "In4.Cu")
		(net "M_J_CPU0_SB_CB<7>")
	)
	(segment
		(start 391.326116 -270.518636)
		(end 391.317734 -270.523462)
		(width 0.0889)
		(layer "In4.Cu")
		(net "M_J_CPU0_SB_CB<7>")
	)
	(segment
		(start 380.04623 -270.518636)
		(end 380.037848 -270.523462)
		(width 0.0889)
		(layer "In4.Cu")
		(net "M_J_CPU0_SB_CB<7>")
	)
	(segment
		(start 421.727122 -274.260056)
		(end 418.719 -274.260056)
		(width 0.14478)
		(layer "In4.Cu")
		(net "M_J_CPU0_SB_CB<7>")
	)
	(segment
		(start 429.37557 -273.410172)
		(end 429.147224 -273.410172)
		(width 0.14478)
		(layer "In4.Cu")
		(net "M_J_CPU0_SB_CB<7>")
	)
	(segment
		(start 428.98568 -274.447508)
		(end 428.824136 -274.609052)
		(width 0.14478)
		(layer "In4.Cu")
		(net "M_J_CPU0_SB_CB<7>")
	)
	(segment
		(start 430.250092 -273.410172)
		(end 430.088548 -273.571716)
		(width 0.14478)
		(layer "In4.Cu")
		(net "M_J_CPU0_SB_CB<7>")
	)
	(segment
		(start 386.99186 -270.523462)
		(end 386.983478 -270.518636)
		(width 0.0889)
		(layer "In4.Cu")
		(net "M_J_CPU0_SB_CB<7>")
	)
	(segment
		(start 415.032952 -273.410172)
		(end 414.19272 -274.250404)
		(width 0.14478)
		(layer "In4.Cu")
		(net "M_J_CPU0_SB_CB<7>")
	)
	(segment
		(start 393.10183 -269.713456)
		(end 393.093448 -269.70863)
		(width 0.0889)
		(layer "In4.Cu")
		(net "M_J_CPU0_SB_CB<7>")
	)
	(arc
		(start 391.317734 -270.523462)
		(mid 391.034778 -270.599639)
		(end 390.751822 -270.523462)
		(width 0.0889)
		(layer "In4.Cu")
		(net "M_J_CPU0_SB_CB<7>")
	)
	(arc
		(start 393.790424 -269.626588)
		(mid 393.732768 -269.675226)
		(end 393.667742 -269.713456)
		(width 0.0889)
		(layer "In4.Cu")
		(net "M_J_CPU0_SB_CB<7>")
	)
	(arc
		(start 387.931914 -270.523462)
		(mid 387.749663 -270.473112)
		(end 387.566154 -270.518636)
		(width 0.0889)
		(layer "In4.Cu")
		(net "M_J_CPU0_SB_CB<7>")
	)
	(arc
		(start 385.677664 -270.523462)
		(mid 385.394708 -270.599639)
		(end 385.111752 -270.523462)
		(width 0.0889)
		(layer "In4.Cu")
		(net "M_J_CPU0_SB_CB<7>")
	)
	(arc
		(start 382.283462 -270.518636)
		(mid 382.099954 -270.473142)
		(end 381.917702 -270.523462)
		(width 0.0889)
		(layer "In4.Cu")
		(net "M_J_CPU0_SB_CB<7>")
	)
	(arc
		(start 382.857756 -270.523462)
		(mid 382.5748 -270.599639)
		(end 382.291844 -270.523462)
		(width 0.0889)
		(layer "In4.Cu")
		(net "M_J_CPU0_SB_CB<7>")
	)
	(arc
		(start 380.977902 -270.523462)
		(mid 380.694946 -270.599639)
		(end 380.41199 -270.523462)
		(width 0.0889)
		(layer "In4.Cu")
		(net "M_J_CPU0_SB_CB<7>")
	)
	(arc
		(start 387.557772 -270.523462)
		(mid 387.274816 -270.599639)
		(end 386.99186 -270.523462)
		(width 0.0889)
		(layer "In4.Cu")
		(net "M_J_CPU0_SB_CB<7>")
	)
	(arc
		(start 383.231898 -270.523462)
		(mid 383.049647 -270.473112)
		(end 382.866138 -270.518636)
		(width 0.0889)
		(layer "In4.Cu")
		(net "M_J_CPU0_SB_CB<7>")
	)
	(arc
		(start 388.871968 -270.523462)
		(mid 388.689717 -270.473112)
		(end 388.506208 -270.518636)
		(width 0.0889)
		(layer "In4.Cu")
		(net "M_J_CPU0_SB_CB<7>")
	)
	(arc
		(start 393.093448 -269.70863)
		(mid 392.90994 -269.663136)
		(end 392.727688 -269.713456)
		(width 0.0889)
		(layer "In4.Cu")
		(net "M_J_CPU0_SB_CB<7>")
	)
	(arc
		(start 392.697208 -269.731236)
		(mid 392.581781 -269.864612)
		(end 392.540236 -270.036036)
		(width 0.0889)
		(layer "In4.Cu")
		(net "M_J_CPU0_SB_CB<7>")
	)
	(arc
		(start 386.043424 -270.518636)
		(mid 385.859916 -270.473142)
		(end 385.677664 -270.523462)
		(width 0.0889)
		(layer "In4.Cu")
		(net "M_J_CPU0_SB_CB<7>")
	)
	(arc
		(start 389.811768 -270.523462)
		(mid 389.624824 -270.473207)
		(end 389.43788 -270.523462)
		(width 0.0889)
		(layer "In4.Cu")
		(net "M_J_CPU0_SB_CB<7>")
	)
	(arc
		(start 385.111752 -270.523462)
		(mid 384.924808 -270.473207)
		(end 384.737864 -270.523462)
		(width 0.0889)
		(layer "In4.Cu")
		(net "M_J_CPU0_SB_CB<7>")
	)
	(arc
		(start 381.35179 -270.523462)
		(mid 381.164846 -270.473207)
		(end 380.977902 -270.523462)
		(width 0.0889)
		(layer "In4.Cu")
		(net "M_J_CPU0_SB_CB<7>")
	)
	(arc
		(start 392.257788 -270.523462)
		(mid 391.974832 -270.599639)
		(end 391.691876 -270.523462)
		(width 0.0889)
		(layer "In4.Cu")
		(net "M_J_CPU0_SB_CB<7>")
	)
	(arc
		(start 393.667742 -269.713456)
		(mid 393.384786 -269.789633)
		(end 393.10183 -269.713456)
		(width 0.0889)
		(layer "In4.Cu")
		(net "M_J_CPU0_SB_CB<7>")
	)
	(arc
		(start 389.43788 -270.523462)
		(mid 389.154924 -270.599639)
		(end 388.871968 -270.523462)
		(width 0.0889)
		(layer "In4.Cu")
		(net "M_J_CPU0_SB_CB<7>")
	)
	(arc
		(start 386.983478 -270.518636)
		(mid 386.79997 -270.473142)
		(end 386.617718 -270.523462)
		(width 0.0889)
		(layer "In4.Cu")
		(net "M_J_CPU0_SB_CB<7>")
	)
	(arc
		(start 386.617718 -270.523462)
		(mid 386.334762 -270.599639)
		(end 386.051806 -270.523462)
		(width 0.0889)
		(layer "In4.Cu")
		(net "M_J_CPU0_SB_CB<7>")
	)
	(arc
		(start 384.171952 -270.523462)
		(mid 383.989701 -270.473112)
		(end 383.806192 -270.518636)
		(width 0.0889)
		(layer "In4.Cu")
		(net "M_J_CPU0_SB_CB<7>")
	)
	(arc
		(start 388.497826 -270.523462)
		(mid 388.21487 -270.599639)
		(end 387.931914 -270.523462)
		(width 0.0889)
		(layer "In4.Cu")
		(net "M_J_CPU0_SB_CB<7>")
	)
	(arc
		(start 390.37768 -270.523462)
		(mid 390.094724 -270.599639)
		(end 389.811768 -270.523462)
		(width 0.0889)
		(layer "In4.Cu")
		(net "M_J_CPU0_SB_CB<7>")
	)
	(arc
		(start 383.79781 -270.523462)
		(mid 383.514854 -270.599639)
		(end 383.231898 -270.523462)
		(width 0.0889)
		(layer "In4.Cu")
		(net "M_J_CPU0_SB_CB<7>")
	)
	(arc
		(start 391.691876 -270.523462)
		(mid 391.509625 -270.473112)
		(end 391.326116 -270.518636)
		(width 0.0889)
		(layer "In4.Cu")
		(net "M_J_CPU0_SB_CB<7>")
	)
	(arc
		(start 381.917702 -270.523462)
		(mid 381.634746 -270.599639)
		(end 381.35179 -270.523462)
		(width 0.0889)
		(layer "In4.Cu")
		(net "M_J_CPU0_SB_CB<7>")
	)
	(arc
		(start 390.74344 -270.518636)
		(mid 390.559932 -270.473142)
		(end 390.37768 -270.523462)
		(width 0.0889)
		(layer "In4.Cu")
		(net "M_J_CPU0_SB_CB<7>")
	)
	(arc
		(start 392.540236 -270.036036)
		(mid 392.475721 -270.298255)
		(end 392.296904 -270.500602)
		(width 0.0889)
		(layer "In4.Cu")
		(net "M_J_CPU0_SB_CB<7>")
	)
	(arc
		(start 380.41199 -270.523462)
		(mid 380.229739 -270.473112)
		(end 380.04623 -270.518636)
		(width 0.0889)
		(layer "In4.Cu")
		(net "M_J_CPU0_SB_CB<7>")
	)
	(arc
		(start 384.737864 -270.523462)
		(mid 384.454908 -270.599639)
		(end 384.171952 -270.523462)
		(width 0.0889)
		(layer "In4.Cu")
		(net "M_J_CPU0_SB_CB<7>")
	)
	(arc
		(start 380.037848 -270.523462)
		(mid 379.790252 -270.59864)
		(end 379.535182 -270.555212)
		(width 0.0889)
		(layer "In4.Cu")
		(net "M_J_CPU0_SB_CB<7>")
	)
	(segment
		(start 380.22784 -269.770098)
		(end 380.694946 -270.036036)
		(width 0.10668)
		(layer "F.Cu")
		(net "M_J_CPU0_SB_CB<6>")
	)
	(segment
		(start 412.205424 -272.560034)
		(end 414.183068 -272.560034)
		(width 0.14478)
		(layer "In4.Cu")
		(net "M_J_CPU0_SB_CB<6>")
	)
	(segment
		(start 389.333486 -269.70863)
		(end 389.341868 -269.713456)
		(width 0.0889)
		(layer "In4.Cu")
		(net "M_J_CPU0_SB_CB<6>")
	)
	(segment
		(start 388.393432 -269.70863)
		(end 388.401814 -269.713456)
		(width 0.0889)
		(layer "In4.Cu")
		(net "M_J_CPU0_SB_CB<6>")
	)
	(segment
		(start 418.491924 -272.560034)
		(end 421.727122 -272.560034)
		(width 0.14478)
		(layer "In4.Cu")
		(net "M_J_CPU0_SB_CB<6>")
	)
	(segment
		(start 395.996922 -267.77061)
		(end 405.855424 -267.77061)
		(width 0.14478)
		(layer "In4.Cu")
		(net "M_J_CPU0_SB_CB<6>")
	)
	(segment
		(start 394.078714 -268.43609)
		(end 394.744194 -267.77061)
		(width 0.0889)
		(layer "In4.Cu")
		(net "M_J_CPU0_SB_CB<6>")
	)
	(segment
		(start 380.84887 -269.770606)
		(end 380.944882 -269.745206)
		(width 0.0889)
		(layer "In4.Cu")
		(net "M_J_CPU0_SB_CB<6>")
	)
	(segment
		(start 391.787634 -269.713456)
		(end 391.82675 -269.690596)
		(width 0.0889)
		(layer "In4.Cu")
		(net "M_J_CPU0_SB_CB<6>")
	)
	(segment
		(start 407.015696 -268.150594)
		(end 407.015696 -267.921994)
		(width 0.14478)
		(layer "In4.Cu")
		(net "M_J_CPU0_SB_CB<6>")
	)
	(segment
		(start 407.17724 -267.76045)
		(end 407.40584 -267.76045)
		(width 0.14478)
		(layer "In4.Cu")
		(net "M_J_CPU0_SB_CB<6>")
	)
	(segment
		(start 393.313412 -268.81455)
		(end 393.691872 -268.43609)
		(width 0.0889)
		(layer "In4.Cu")
		(net "M_J_CPU0_SB_CB<6>")
	)
	(segment
		(start 408.866086 -270.229584)
		(end 408.866086 -270.000984)
		(width 0.14478)
		(layer "In4.Cu")
		(net "M_J_CPU0_SB_CB<6>")
	)
	(segment
		(start 417.64204 -271.71015)
		(end 418.491924 -272.560034)
		(width 0.14478)
		(layer "In4.Cu")
		(net "M_J_CPU0_SB_CB<6>")
	)
	(segment
		(start 408.866086 -270.000984)
		(end 407.015696 -268.150594)
		(width 0.14478)
		(layer "In4.Cu")
		(net "M_J_CPU0_SB_CB<6>")
	)
	(segment
		(start 421.727122 -272.560034)
		(end 422.577006 -271.71015)
		(width 0.14478)
		(layer "In4.Cu")
		(net "M_J_CPU0_SB_CB<6>")
	)
	(segment
		(start 383.693416 -269.70863)
		(end 383.701798 -269.713456)
		(width 0.0889)
		(layer "In4.Cu")
		(net "M_J_CPU0_SB_CB<6>")
	)
	(segment
		(start 394.744194 -267.77061)
		(end 395.996922 -267.77061)
		(width 0.0889)
		(layer "In4.Cu")
		(net "M_J_CPU0_SB_CB<6>")
	)
	(segment
		(start 392.226038 -268.921738)
		(end 392.257788 -268.90345)
		(width 0.0889)
		(layer "In4.Cu")
		(net "M_J_CPU0_SB_CB<6>")
	)
	(segment
		(start 405.855424 -267.77061)
		(end 408.475942 -270.391128)
		(width 0.14478)
		(layer "In4.Cu")
		(net "M_J_CPU0_SB_CB<6>")
	)
	(segment
		(start 408.704542 -270.391128)
		(end 408.866086 -270.229584)
		(width 0.14478)
		(layer "In4.Cu")
		(net "M_J_CPU0_SB_CB<6>")
	)
	(segment
		(start 422.577006 -271.71015)
		(end 433.72532 -271.71015)
		(width 0.14478)
		(layer "In4.Cu")
		(net "M_J_CPU0_SB_CB<6>")
	)
	(segment
		(start 414.183068 -272.560034)
		(end 415.032952 -271.71015)
		(width 0.14478)
		(layer "In4.Cu")
		(net "M_J_CPU0_SB_CB<6>")
	)
	(segment
		(start 415.032952 -271.71015)
		(end 417.64204 -271.71015)
		(width 0.14478)
		(layer "In4.Cu")
		(net "M_J_CPU0_SB_CB<6>")
	)
	(segment
		(start 408.475942 -270.391128)
		(end 408.704542 -270.391128)
		(width 0.14478)
		(layer "In4.Cu")
		(net "M_J_CPU0_SB_CB<6>")
	)
	(segment
		(start 385.207764 -269.713456)
		(end 385.216146 -269.70863)
		(width 0.0889)
		(layer "In4.Cu")
		(net "M_J_CPU0_SB_CB<6>")
	)
	(segment
		(start 381.447802 -269.713456)
		(end 381.456184 -269.70863)
		(width 0.0889)
		(layer "In4.Cu")
		(net "M_J_CPU0_SB_CB<6>")
	)
	(segment
		(start 407.015696 -267.921994)
		(end 407.17724 -267.76045)
		(width 0.14478)
		(layer "In4.Cu")
		(net "M_J_CPU0_SB_CB<6>")
	)
	(segment
		(start 407.40584 -267.76045)
		(end 412.205424 -272.560034)
		(width 0.14478)
		(layer "In4.Cu")
		(net "M_J_CPU0_SB_CB<6>")
	)
	(segment
		(start 392.257788 -268.90345)
		(end 392.26617 -268.898624)
		(width 0.0889)
		(layer "In4.Cu")
		(net "M_J_CPU0_SB_CB<6>")
	)
	(segment
		(start 433.72532 -271.71015)
		(end 435.000146 -272.984976)
		(width 0.14478)
		(layer "In4.Cu")
		(net "M_J_CPU0_SB_CB<6>")
	)
	(segment
		(start 393.691872 -268.43609)
		(end 394.078714 -268.43609)
		(width 0.0889)
		(layer "In4.Cu")
		(net "M_J_CPU0_SB_CB<6>")
	)
	(segment
		(start 380.694946 -270.036036)
		(end 380.84887 -269.770606)
		(width 0.0889)
		(layer "In4.Cu")
		(net "M_J_CPU0_SB_CB<6>")
	)
	(segment
		(start 384.63347 -269.70863)
		(end 384.641852 -269.713456)
		(width 0.0889)
		(layer "In4.Cu")
		(net "M_J_CPU0_SB_CB<6>")
	)
	(segment
		(start 386.147818 -269.713456)
		(end 386.1562 -269.70863)
		(width 0.0889)
		(layer "In4.Cu")
		(net "M_J_CPU0_SB_CB<6>")
	)
	(segment
		(start 389.90778 -269.713456)
		(end 389.916162 -269.70863)
		(width 0.0889)
		(layer "In4.Cu")
		(net "M_J_CPU0_SB_CB<6>")
	)
	(arc
		(start 380.944882 -269.745206)
		(mid 381.20009 -269.788683)
		(end 381.447802 -269.713456)
		(width 0.0889)
		(layer "In4.Cu")
		(net "M_J_CPU0_SB_CB<6>")
	)
	(arc
		(start 384.641852 -269.713456)
		(mid 384.924808 -269.789633)
		(end 385.207764 -269.713456)
		(width 0.0889)
		(layer "In4.Cu")
		(net "M_J_CPU0_SB_CB<6>")
	)
	(arc
		(start 390.281922 -269.713456)
		(mid 390.564878 -269.789633)
		(end 390.847834 -269.713456)
		(width 0.0889)
		(layer "In4.Cu")
		(net "M_J_CPU0_SB_CB<6>")
	)
	(arc
		(start 392.63193 -268.90345)
		(mid 392.914886 -268.979627)
		(end 393.197842 -268.90345)
		(width 0.0889)
		(layer "In4.Cu")
		(net "M_J_CPU0_SB_CB<6>")
	)
	(arc
		(start 383.701798 -269.713456)
		(mid 383.984754 -269.789633)
		(end 384.26771 -269.713456)
		(width 0.0889)
		(layer "In4.Cu")
		(net "M_J_CPU0_SB_CB<6>")
	)
	(arc
		(start 391.221722 -269.713456)
		(mid 391.504678 -269.789633)
		(end 391.787634 -269.713456)
		(width 0.0889)
		(layer "In4.Cu")
		(net "M_J_CPU0_SB_CB<6>")
	)
	(arc
		(start 392.26617 -268.898624)
		(mid 392.449678 -268.85313)
		(end 392.63193 -268.90345)
		(width 0.0889)
		(layer "In4.Cu")
		(net "M_J_CPU0_SB_CB<6>")
	)
	(arc
		(start 383.327656 -269.713456)
		(mid 383.509907 -269.663106)
		(end 383.693416 -269.70863)
		(width 0.0889)
		(layer "In4.Cu")
		(net "M_J_CPU0_SB_CB<6>")
	)
	(arc
		(start 385.581906 -269.713456)
		(mid 385.864862 -269.789633)
		(end 386.147818 -269.713456)
		(width 0.0889)
		(layer "In4.Cu")
		(net "M_J_CPU0_SB_CB<6>")
	)
	(arc
		(start 382.761744 -269.713456)
		(mid 383.0447 -269.789633)
		(end 383.327656 -269.713456)
		(width 0.0889)
		(layer "In4.Cu")
		(net "M_J_CPU0_SB_CB<6>")
	)
	(arc
		(start 382.387856 -269.713456)
		(mid 382.5748 -269.663201)
		(end 382.761744 -269.713456)
		(width 0.0889)
		(layer "In4.Cu")
		(net "M_J_CPU0_SB_CB<6>")
	)
	(arc
		(start 392.070082 -269.22603)
		(mid 392.111337 -269.055059)
		(end 392.226038 -268.921738)
		(width 0.0889)
		(layer "In4.Cu")
		(net "M_J_CPU0_SB_CB<6>")
	)
	(arc
		(start 386.52196 -269.713456)
		(mid 386.804916 -269.789633)
		(end 387.087872 -269.713456)
		(width 0.0889)
		(layer "In4.Cu")
		(net "M_J_CPU0_SB_CB<6>")
	)
	(arc
		(start 384.26771 -269.713456)
		(mid 384.449961 -269.663106)
		(end 384.63347 -269.70863)
		(width 0.0889)
		(layer "In4.Cu")
		(net "M_J_CPU0_SB_CB<6>")
	)
	(arc
		(start 393.197842 -268.90345)
		(mid 393.258515 -268.862754)
		(end 393.313412 -268.81455)
		(width 0.0889)
		(layer "In4.Cu")
		(net "M_J_CPU0_SB_CB<6>")
	)
	(arc
		(start 390.847834 -269.713456)
		(mid 391.034778 -269.663201)
		(end 391.221722 -269.713456)
		(width 0.0889)
		(layer "In4.Cu")
		(net "M_J_CPU0_SB_CB<6>")
	)
	(arc
		(start 388.967726 -269.713456)
		(mid 389.149977 -269.663106)
		(end 389.333486 -269.70863)
		(width 0.0889)
		(layer "In4.Cu")
		(net "M_J_CPU0_SB_CB<6>")
	)
	(arc
		(start 388.027672 -269.713456)
		(mid 388.209923 -269.663106)
		(end 388.393432 -269.70863)
		(width 0.0889)
		(layer "In4.Cu")
		(net "M_J_CPU0_SB_CB<6>")
	)
	(arc
		(start 381.821944 -269.713456)
		(mid 382.1049 -269.789633)
		(end 382.387856 -269.713456)
		(width 0.0889)
		(layer "In4.Cu")
		(net "M_J_CPU0_SB_CB<6>")
	)
	(arc
		(start 389.916162 -269.70863)
		(mid 390.09967 -269.663136)
		(end 390.281922 -269.713456)
		(width 0.0889)
		(layer "In4.Cu")
		(net "M_J_CPU0_SB_CB<6>")
	)
	(arc
		(start 388.401814 -269.713456)
		(mid 388.68477 -269.789633)
		(end 388.967726 -269.713456)
		(width 0.0889)
		(layer "In4.Cu")
		(net "M_J_CPU0_SB_CB<6>")
	)
	(arc
		(start 387.46176 -269.713456)
		(mid 387.744716 -269.789633)
		(end 388.027672 -269.713456)
		(width 0.0889)
		(layer "In4.Cu")
		(net "M_J_CPU0_SB_CB<6>")
	)
	(arc
		(start 381.456184 -269.70863)
		(mid 381.639692 -269.663136)
		(end 381.821944 -269.713456)
		(width 0.0889)
		(layer "In4.Cu")
		(net "M_J_CPU0_SB_CB<6>")
	)
	(arc
		(start 385.216146 -269.70863)
		(mid 385.399654 -269.663136)
		(end 385.581906 -269.713456)
		(width 0.0889)
		(layer "In4.Cu")
		(net "M_J_CPU0_SB_CB<6>")
	)
	(arc
		(start 386.1562 -269.70863)
		(mid 386.339708 -269.663136)
		(end 386.52196 -269.713456)
		(width 0.0889)
		(layer "In4.Cu")
		(net "M_J_CPU0_SB_CB<6>")
	)
	(arc
		(start 391.82675 -269.690596)
		(mid 392.005563 -269.488246)
		(end 392.070082 -269.22603)
		(width 0.0889)
		(layer "In4.Cu")
		(net "M_J_CPU0_SB_CB<6>")
	)
	(arc
		(start 389.341868 -269.713456)
		(mid 389.624824 -269.789633)
		(end 389.90778 -269.713456)
		(width 0.0889)
		(layer "In4.Cu")
		(net "M_J_CPU0_SB_CB<6>")
	)
	(arc
		(start 387.087872 -269.713456)
		(mid 387.274816 -269.663201)
		(end 387.46176 -269.713456)
		(width 0.0889)
		(layer "In4.Cu")
		(net "M_J_CPU0_SB_CB<6>")
	)
	(segment
		(start 379.28804 -269.770098)
		(end 379.754892 -270.036036)
		(width 0.10668)
		(layer "F.Cu")
		(net "M_J_CPU0_SB_CB<5>")
	)
	(segment
		(start 379.754892 -270.036036)
		(end 379.600714 -270.301466)
		(width 0.0889)
		(layer "In4.Cu")
		(net "M_J_CPU0_SB_CB<5>")
	)
	(segment
		(start 379.600714 -270.301466)
		(end 379.623066 -270.384778)
		(width 0.0889)
		(layer "In4.Cu")
		(net "M_J_CPU0_SB_CB<5>")
	)
	(segment
		(start 396.006828 -268.22527)
		(end 405.622252 -268.22527)
		(width 0.14478)
		(layer "In4.Cu")
		(net "M_J_CPU0_SB_CB<5>")
	)
	(segment
		(start 384.63347 -270.363442)
		(end 384.641852 -270.358616)
		(width 0.0889)
		(layer "In4.Cu")
		(net "M_J_CPU0_SB_CB<5>")
	)
	(segment
		(start 412.419546 -273.410172)
		(end 414.090104 -273.410172)
		(width 0.14478)
		(layer "In4.Cu")
		(net "M_J_CPU0_SB_CB<5>")
	)
	(segment
		(start 418.60597 -273.410172)
		(end 421.634158 -273.410172)
		(width 0.14478)
		(layer "In4.Cu")
		(net "M_J_CPU0_SB_CB<5>")
	)
	(segment
		(start 395.079474 -268.58849)
		(end 395.442694 -268.22527)
		(width 0.0889)
		(layer "In4.Cu")
		(net "M_J_CPU0_SB_CB<5>")
	)
	(segment
		(start 432.50231 -272.560034)
		(end 434.554884 -273.410172)
		(width 0.14478)
		(layer "In4.Cu")
		(net "M_J_CPU0_SB_CB<5>")
	)
	(segment
		(start 414.090104 -273.410172)
		(end 414.940242 -272.560034)
		(width 0.14478)
		(layer "In4.Cu")
		(net "M_J_CPU0_SB_CB<5>")
	)
	(segment
		(start 434.554884 -273.410172)
		(end 436.96382 -273.410172)
		(width 0.14478)
		(layer "In4.Cu")
		(net "M_J_CPU0_SB_CB<5>")
	)
	(segment
		(start 405.622252 -268.22527)
		(end 408.23769 -270.840708)
		(width 0.14478)
		(layer "In4.Cu")
		(net "M_J_CPU0_SB_CB<5>")
	)
	(segment
		(start 408.23769 -270.840708)
		(end 409.850082 -270.840708)
		(width 0.14478)
		(layer "In4.Cu")
		(net "M_J_CPU0_SB_CB<5>")
	)
	(segment
		(start 393.197842 -269.54861)
		(end 393.206224 -269.553436)
		(width 0.0889)
		(layer "In4.Cu")
		(net "M_J_CPU0_SB_CB<5>")
	)
	(segment
		(start 383.693416 -270.363442)
		(end 383.701798 -270.358616)
		(width 0.0889)
		(layer "In4.Cu")
		(net "M_J_CPU0_SB_CB<5>")
	)
	(segment
		(start 395.442694 -268.22527)
		(end 396.006828 -268.22527)
		(width 0.0889)
		(layer "In4.Cu")
		(net "M_J_CPU0_SB_CB<5>")
	)
	(segment
		(start 388.393432 -270.363442)
		(end 388.401814 -270.358616)
		(width 0.0889)
		(layer "In4.Cu")
		(net "M_J_CPU0_SB_CB<5>")
	)
	(segment
		(start 421.634158 -273.410172)
		(end 422.484296 -272.560034)
		(width 0.14478)
		(layer "In4.Cu")
		(net "M_J_CPU0_SB_CB<5>")
	)
	(segment
		(start 379.933454 -270.363442)
		(end 379.941836 -270.358616)
		(width 0.0889)
		(layer "In4.Cu")
		(net "M_J_CPU0_SB_CB<5>")
	)
	(segment
		(start 422.484296 -272.560034)
		(end 432.50231 -272.560034)
		(width 0.14478)
		(layer "In4.Cu")
		(net "M_J_CPU0_SB_CB<5>")
	)
	(segment
		(start 392.153394 -270.363442)
		(end 392.161776 -270.358616)
		(width 0.0889)
		(layer "In4.Cu")
		(net "M_J_CPU0_SB_CB<5>")
	)
	(segment
		(start 381.447802 -270.358616)
		(end 381.456184 -270.363442)
		(width 0.0889)
		(layer "In4.Cu")
		(net "M_J_CPU0_SB_CB<5>")
	)
	(segment
		(start 392.161776 -270.358616)
		(end 392.193526 -270.340328)
		(width 0.0889)
		(layer "In4.Cu")
		(net "M_J_CPU0_SB_CB<5>")
	)
	(segment
		(start 393.571984 -269.54861)
		(end 394.532104 -268.58849)
		(width 0.0889)
		(layer "In4.Cu")
		(net "M_J_CPU0_SB_CB<5>")
	)
	(segment
		(start 380.873508 -270.363442)
		(end 380.88189 -270.358616)
		(width 0.0889)
		(layer "In4.Cu")
		(net "M_J_CPU0_SB_CB<5>")
	)
	(segment
		(start 436.96382 -273.410172)
		(end 439.100214 -273.835114)
		(width 0.14478)
		(layer "In4.Cu")
		(net "M_J_CPU0_SB_CB<5>")
	)
	(segment
		(start 417.755832 -272.560034)
		(end 418.60597 -273.410172)
		(width 0.14478)
		(layer "In4.Cu")
		(net "M_J_CPU0_SB_CB<5>")
	)
	(segment
		(start 414.940242 -272.560034)
		(end 417.755832 -272.560034)
		(width 0.14478)
		(layer "In4.Cu")
		(net "M_J_CPU0_SB_CB<5>")
	)
	(segment
		(start 386.147818 -270.358616)
		(end 386.1562 -270.363442)
		(width 0.0889)
		(layer "In4.Cu")
		(net "M_J_CPU0_SB_CB<5>")
	)
	(segment
		(start 389.90778 -270.358616)
		(end 389.916162 -270.363442)
		(width 0.0889)
		(layer "In4.Cu")
		(net "M_J_CPU0_SB_CB<5>")
	)
	(segment
		(start 394.532104 -268.58849)
		(end 395.079474 -268.58849)
		(width 0.0889)
		(layer "In4.Cu")
		(net "M_J_CPU0_SB_CB<5>")
	)
	(segment
		(start 392.592814 -269.57147)
		(end 392.63193 -269.54861)
		(width 0.0889)
		(layer "In4.Cu")
		(net "M_J_CPU0_SB_CB<5>")
	)
	(segment
		(start 409.850082 -270.840708)
		(end 412.419546 -273.410172)
		(width 0.14478)
		(layer "In4.Cu")
		(net "M_J_CPU0_SB_CB<5>")
	)
	(segment
		(start 389.333486 -270.363442)
		(end 389.341868 -270.358616)
		(width 0.0889)
		(layer "In4.Cu")
		(net "M_J_CPU0_SB_CB<5>")
	)
	(segment
		(start 385.207764 -270.358616)
		(end 385.216146 -270.363442)
		(width 0.0889)
		(layer "In4.Cu")
		(net "M_J_CPU0_SB_CB<5>")
	)
	(arc
		(start 385.581906 -270.358616)
		(mid 385.864862 -270.282439)
		(end 386.147818 -270.358616)
		(width 0.0889)
		(layer "In4.Cu")
		(net "M_J_CPU0_SB_CB<5>")
	)
	(arc
		(start 380.88189 -270.358616)
		(mid 381.164846 -270.282439)
		(end 381.447802 -270.358616)
		(width 0.0889)
		(layer "In4.Cu")
		(net "M_J_CPU0_SB_CB<5>")
	)
	(arc
		(start 384.641852 -270.358616)
		(mid 384.924808 -270.282439)
		(end 385.207764 -270.358616)
		(width 0.0889)
		(layer "In4.Cu")
		(net "M_J_CPU0_SB_CB<5>")
	)
	(arc
		(start 386.52196 -270.358616)
		(mid 386.804916 -270.282439)
		(end 387.087872 -270.358616)
		(width 0.0889)
		(layer "In4.Cu")
		(net "M_J_CPU0_SB_CB<5>")
	)
	(arc
		(start 388.967726 -270.358616)
		(mid 389.149977 -270.408966)
		(end 389.333486 -270.363442)
		(width 0.0889)
		(layer "In4.Cu")
		(net "M_J_CPU0_SB_CB<5>")
	)
	(arc
		(start 381.456184 -270.363442)
		(mid 381.639692 -270.408936)
		(end 381.821944 -270.358616)
		(width 0.0889)
		(layer "In4.Cu")
		(net "M_J_CPU0_SB_CB<5>")
	)
	(arc
		(start 392.349482 -270.036036)
		(mid 392.413997 -269.773817)
		(end 392.592814 -269.57147)
		(width 0.0889)
		(layer "In4.Cu")
		(net "M_J_CPU0_SB_CB<5>")
	)
	(arc
		(start 393.206224 -269.553436)
		(mid 393.389732 -269.59893)
		(end 393.571984 -269.54861)
		(width 0.0889)
		(layer "In4.Cu")
		(net "M_J_CPU0_SB_CB<5>")
	)
	(arc
		(start 391.787634 -270.358616)
		(mid 391.969885 -270.408966)
		(end 392.153394 -270.363442)
		(width 0.0889)
		(layer "In4.Cu")
		(net "M_J_CPU0_SB_CB<5>")
	)
	(arc
		(start 382.761744 -270.358616)
		(mid 383.0447 -270.282439)
		(end 383.327656 -270.358616)
		(width 0.0889)
		(layer "In4.Cu")
		(net "M_J_CPU0_SB_CB<5>")
	)
	(arc
		(start 391.221722 -270.358616)
		(mid 391.504678 -270.282439)
		(end 391.787634 -270.358616)
		(width 0.0889)
		(layer "In4.Cu")
		(net "M_J_CPU0_SB_CB<5>")
	)
	(arc
		(start 382.387856 -270.358616)
		(mid 382.5748 -270.408871)
		(end 382.761744 -270.358616)
		(width 0.0889)
		(layer "In4.Cu")
		(net "M_J_CPU0_SB_CB<5>")
	)
	(arc
		(start 380.507748 -270.358616)
		(mid 380.689999 -270.408966)
		(end 380.873508 -270.363442)
		(width 0.0889)
		(layer "In4.Cu")
		(net "M_J_CPU0_SB_CB<5>")
	)
	(arc
		(start 387.46176 -270.358616)
		(mid 387.744716 -270.282439)
		(end 388.027672 -270.358616)
		(width 0.0889)
		(layer "In4.Cu")
		(net "M_J_CPU0_SB_CB<5>")
	)
	(arc
		(start 390.281922 -270.358616)
		(mid 390.564878 -270.282439)
		(end 390.847834 -270.358616)
		(width 0.0889)
		(layer "In4.Cu")
		(net "M_J_CPU0_SB_CB<5>")
	)
	(arc
		(start 389.341868 -270.358616)
		(mid 389.624824 -270.282439)
		(end 389.90778 -270.358616)
		(width 0.0889)
		(layer "In4.Cu")
		(net "M_J_CPU0_SB_CB<5>")
	)
	(arc
		(start 379.941836 -270.358616)
		(mid 380.224792 -270.282439)
		(end 380.507748 -270.358616)
		(width 0.0889)
		(layer "In4.Cu")
		(net "M_J_CPU0_SB_CB<5>")
	)
	(arc
		(start 388.027672 -270.358616)
		(mid 388.209923 -270.408966)
		(end 388.393432 -270.363442)
		(width 0.0889)
		(layer "In4.Cu")
		(net "M_J_CPU0_SB_CB<5>")
	)
	(arc
		(start 388.401814 -270.358616)
		(mid 388.68477 -270.282439)
		(end 388.967726 -270.358616)
		(width 0.0889)
		(layer "In4.Cu")
		(net "M_J_CPU0_SB_CB<5>")
	)
	(arc
		(start 392.193526 -270.340328)
		(mid 392.308202 -270.206994)
		(end 392.349482 -270.036036)
		(width 0.0889)
		(layer "In4.Cu")
		(net "M_J_CPU0_SB_CB<5>")
	)
	(arc
		(start 390.847834 -270.358616)
		(mid 391.034778 -270.408871)
		(end 391.221722 -270.358616)
		(width 0.0889)
		(layer "In4.Cu")
		(net "M_J_CPU0_SB_CB<5>")
	)
	(arc
		(start 385.216146 -270.363442)
		(mid 385.399654 -270.408936)
		(end 385.581906 -270.358616)
		(width 0.0889)
		(layer "In4.Cu")
		(net "M_J_CPU0_SB_CB<5>")
	)
	(arc
		(start 389.916162 -270.363442)
		(mid 390.09967 -270.408936)
		(end 390.281922 -270.358616)
		(width 0.0889)
		(layer "In4.Cu")
		(net "M_J_CPU0_SB_CB<5>")
	)
	(arc
		(start 384.26771 -270.358616)
		(mid 384.449961 -270.408966)
		(end 384.63347 -270.363442)
		(width 0.0889)
		(layer "In4.Cu")
		(net "M_J_CPU0_SB_CB<5>")
	)
	(arc
		(start 392.63193 -269.54861)
		(mid 392.914886 -269.472433)
		(end 393.197842 -269.54861)
		(width 0.0889)
		(layer "In4.Cu")
		(net "M_J_CPU0_SB_CB<5>")
	)
	(arc
		(start 383.701798 -270.358616)
		(mid 383.984754 -270.282439)
		(end 384.26771 -270.358616)
		(width 0.0889)
		(layer "In4.Cu")
		(net "M_J_CPU0_SB_CB<5>")
	)
	(arc
		(start 381.821944 -270.358616)
		(mid 382.1049 -270.282439)
		(end 382.387856 -270.358616)
		(width 0.0889)
		(layer "In4.Cu")
		(net "M_J_CPU0_SB_CB<5>")
	)
	(arc
		(start 379.623066 -270.384778)
		(mid 379.780576 -270.407976)
		(end 379.933454 -270.363442)
		(width 0.0889)
		(layer "In4.Cu")
		(net "M_J_CPU0_SB_CB<5>")
	)
	(arc
		(start 386.1562 -270.363442)
		(mid 386.339708 -270.408936)
		(end 386.52196 -270.358616)
		(width 0.0889)
		(layer "In4.Cu")
		(net "M_J_CPU0_SB_CB<5>")
	)
	(arc
		(start 383.327656 -270.358616)
		(mid 383.509907 -270.408966)
		(end 383.693416 -270.363442)
		(width 0.0889)
		(layer "In4.Cu")
		(net "M_J_CPU0_SB_CB<5>")
	)
	(arc
		(start 387.087872 -270.358616)
		(mid 387.274816 -270.408871)
		(end 387.46176 -270.358616)
		(width 0.0889)
		(layer "In4.Cu")
		(net "M_J_CPU0_SB_CB<5>")
	)
	(segment
		(start 380.697994 -268.960092)
		(end 381.164846 -269.22603)
		(width 0.10668)
		(layer "F.Cu")
		(net "M_J_CPU0_SB_CB<4>")
	)
	(segment
		(start 392.12266 -268.761464)
		(end 392.161776 -268.738604)
		(width 0.0889)
		(layer "In4.Cu")
		(net "M_J_CPU0_SB_CB<4>")
	)
	(segment
		(start 436.549546 -271.02308)
		(end 436.712614 -270.860012)
		(width 0.14478)
		(layer "In4.Cu")
		(net "M_J_CPU0_SB_CB<4>")
	)
	(segment
		(start 391.317734 -269.54861)
		(end 391.326116 -269.553436)
		(width 0.0889)
		(layer "In4.Cu")
		(net "M_J_CPU0_SB_CB<4>")
	)
	(segment
		(start 393.178538 -268.679676)
		(end 393.66571 -268.192504)
		(width 0.0889)
		(layer "In4.Cu")
		(net "M_J_CPU0_SB_CB<4>")
	)
	(segment
		(start 381.010922 -269.49146)
		(end 381.033274 -269.574772)
		(width 0.0889)
		(layer "In4.Cu")
		(net "M_J_CPU0_SB_CB<4>")
	)
	(segment
		(start 394.010134 -268.192504)
		(end 394.891768 -267.31087)
		(width 0.0889)
		(layer "In4.Cu")
		(net "M_J_CPU0_SB_CB<4>")
	)
	(segment
		(start 382.283462 -269.553436)
		(end 382.291844 -269.54861)
		(width 0.0889)
		(layer "In4.Cu")
		(net "M_J_CPU0_SB_CB<4>")
	)
	(segment
		(start 422.698926 -270.860012)
		(end 435.829964 -270.860012)
		(width 0.14478)
		(layer "In4.Cu")
		(net "M_J_CPU0_SB_CB<4>")
	)
	(segment
		(start 417.630356 -270.860012)
		(end 418.48024 -271.709896)
		(width 0.14478)
		(layer "In4.Cu")
		(net "M_J_CPU0_SB_CB<4>")
	)
	(segment
		(start 386.983478 -269.553436)
		(end 386.99186 -269.54861)
		(width 0.0889)
		(layer "In4.Cu")
		(net "M_J_CPU0_SB_CB<4>")
	)
	(segment
		(start 407.882344 -267.31087)
		(end 412.28137 -271.709896)
		(width 0.14478)
		(layer "In4.Cu")
		(net "M_J_CPU0_SB_CB<4>")
	)
	(segment
		(start 436.1561 -271.947386)
		(end 436.386478 -271.947386)
		(width 0.14478)
		(layer "In4.Cu")
		(net "M_J_CPU0_SB_CB<4>")
	)
	(segment
		(start 415.147252 -270.860012)
		(end 417.630356 -270.860012)
		(width 0.14478)
		(layer "In4.Cu")
		(net "M_J_CPU0_SB_CB<4>")
	)
	(segment
		(start 381.164846 -269.22603)
		(end 381.010922 -269.49146)
		(width 0.0889)
		(layer "In4.Cu")
		(net "M_J_CPU0_SB_CB<4>")
	)
	(segment
		(start 438.68975 -272.135092)
		(end 439.100214 -272.135092)
		(width 0.14478)
		(layer "In4.Cu")
		(net "M_J_CPU0_SB_CB<4>")
	)
	(segment
		(start 412.28137 -271.709896)
		(end 414.297368 -271.709896)
		(width 0.14478)
		(layer "In4.Cu")
		(net "M_J_CPU0_SB_CB<4>")
	)
	(segment
		(start 421.849042 -271.709896)
		(end 422.698926 -270.860012)
		(width 0.14478)
		(layer "In4.Cu")
		(net "M_J_CPU0_SB_CB<4>")
	)
	(segment
		(start 436.712614 -270.860012)
		(end 437.41467 -270.860012)
		(width 0.14478)
		(layer "In4.Cu")
		(net "M_J_CPU0_SB_CB<4>")
	)
	(segment
		(start 383.79781 -269.54861)
		(end 383.806192 -269.553436)
		(width 0.0889)
		(layer "In4.Cu")
		(net "M_J_CPU0_SB_CB<4>")
	)
	(segment
		(start 386.043424 -269.553436)
		(end 386.051806 -269.54861)
		(width 0.0889)
		(layer "In4.Cu")
		(net "M_J_CPU0_SB_CB<4>")
	)
	(segment
		(start 388.497826 -269.54861)
		(end 388.506208 -269.553436)
		(width 0.0889)
		(layer "In4.Cu")
		(net "M_J_CPU0_SB_CB<4>")
	)
	(segment
		(start 435.993032 -271.02308)
		(end 435.993032 -271.784318)
		(width 0.14478)
		(layer "In4.Cu")
		(net "M_J_CPU0_SB_CB<4>")
	)
	(segment
		(start 395.932152 -267.31087)
		(end 407.882344 -267.31087)
		(width 0.14478)
		(layer "In4.Cu")
		(net "M_J_CPU0_SB_CB<4>")
	)
	(segment
		(start 391.691876 -269.54861)
		(end 391.722356 -269.53083)
		(width 0.0889)
		(layer "In4.Cu")
		(net "M_J_CPU0_SB_CB<4>")
	)
	(segment
		(start 394.891768 -267.31087)
		(end 395.932152 -267.31087)
		(width 0.0889)
		(layer "In4.Cu")
		(net "M_J_CPU0_SB_CB<4>")
	)
	(segment
		(start 437.41467 -270.860012)
		(end 438.68975 -272.135092)
		(width 0.14478)
		(layer "In4.Cu")
		(net "M_J_CPU0_SB_CB<4>")
	)
	(segment
		(start 435.993032 -271.784318)
		(end 436.1561 -271.947386)
		(width 0.14478)
		(layer "In4.Cu")
		(net "M_J_CPU0_SB_CB<4>")
	)
	(segment
		(start 436.549546 -271.784318)
		(end 436.549546 -271.02308)
		(width 0.14478)
		(layer "In4.Cu")
		(net "M_J_CPU0_SB_CB<4>")
	)
	(segment
		(start 393.66571 -268.192504)
		(end 394.010134 -268.192504)
		(width 0.0889)
		(layer "In4.Cu")
		(net "M_J_CPU0_SB_CB<4>")
	)
	(segment
		(start 435.829964 -270.860012)
		(end 435.993032 -271.02308)
		(width 0.14478)
		(layer "In4.Cu")
		(net "M_J_CPU0_SB_CB<4>")
	)
	(segment
		(start 382.857756 -269.54861)
		(end 382.866138 -269.553436)
		(width 0.0889)
		(layer "In4.Cu")
		(net "M_J_CPU0_SB_CB<4>")
	)
	(segment
		(start 418.48024 -271.709896)
		(end 421.849042 -271.709896)
		(width 0.14478)
		(layer "In4.Cu")
		(net "M_J_CPU0_SB_CB<4>")
	)
	(segment
		(start 436.386478 -271.947386)
		(end 436.549546 -271.784318)
		(width 0.14478)
		(layer "In4.Cu")
		(net "M_J_CPU0_SB_CB<4>")
	)
	(segment
		(start 390.74344 -269.553436)
		(end 390.751822 -269.54861)
		(width 0.0889)
		(layer "In4.Cu")
		(net "M_J_CPU0_SB_CB<4>")
	)
	(segment
		(start 387.557772 -269.54861)
		(end 387.566154 -269.553436)
		(width 0.0889)
		(layer "In4.Cu")
		(net "M_J_CPU0_SB_CB<4>")
	)
	(segment
		(start 414.297368 -271.709896)
		(end 415.147252 -270.860012)
		(width 0.14478)
		(layer "In4.Cu")
		(net "M_J_CPU0_SB_CB<4>")
	)
	(arc
		(start 381.033274 -269.574772)
		(mid 381.195463 -269.597507)
		(end 381.35179 -269.54861)
		(width 0.0889)
		(layer "In4.Cu")
		(net "M_J_CPU0_SB_CB<4>")
	)
	(arc
		(start 388.871968 -269.54861)
		(mid 389.154924 -269.472433)
		(end 389.43788 -269.54861)
		(width 0.0889)
		(layer "In4.Cu")
		(net "M_J_CPU0_SB_CB<4>")
	)
	(arc
		(start 381.917702 -269.54861)
		(mid 382.099953 -269.59896)
		(end 382.283462 -269.553436)
		(width 0.0889)
		(layer "In4.Cu")
		(net "M_J_CPU0_SB_CB<4>")
	)
	(arc
		(start 384.171952 -269.54861)
		(mid 384.454908 -269.472433)
		(end 384.737864 -269.54861)
		(width 0.0889)
		(layer "In4.Cu")
		(net "M_J_CPU0_SB_CB<4>")
	)
	(arc
		(start 385.677664 -269.54861)
		(mid 385.859915 -269.59896)
		(end 386.043424 -269.553436)
		(width 0.0889)
		(layer "In4.Cu")
		(net "M_J_CPU0_SB_CB<4>")
	)
	(arc
		(start 382.866138 -269.553436)
		(mid 383.049646 -269.59893)
		(end 383.231898 -269.54861)
		(width 0.0889)
		(layer "In4.Cu")
		(net "M_J_CPU0_SB_CB<4>")
	)
	(arc
		(start 392.161776 -268.738604)
		(mid 392.444732 -268.662427)
		(end 392.727688 -268.738604)
		(width 0.0889)
		(layer "In4.Cu")
		(net "M_J_CPU0_SB_CB<4>")
	)
	(arc
		(start 386.617718 -269.54861)
		(mid 386.799969 -269.59896)
		(end 386.983478 -269.553436)
		(width 0.0889)
		(layer "In4.Cu")
		(net "M_J_CPU0_SB_CB<4>")
	)
	(arc
		(start 387.931914 -269.54861)
		(mid 388.21487 -269.472433)
		(end 388.497826 -269.54861)
		(width 0.0889)
		(layer "In4.Cu")
		(net "M_J_CPU0_SB_CB<4>")
	)
	(arc
		(start 391.326116 -269.553436)
		(mid 391.509624 -269.59893)
		(end 391.691876 -269.54861)
		(width 0.0889)
		(layer "In4.Cu")
		(net "M_J_CPU0_SB_CB<4>")
	)
	(arc
		(start 382.291844 -269.54861)
		(mid 382.5748 -269.472433)
		(end 382.857756 -269.54861)
		(width 0.0889)
		(layer "In4.Cu")
		(net "M_J_CPU0_SB_CB<4>")
	)
	(arc
		(start 386.99186 -269.54861)
		(mid 387.274816 -269.472433)
		(end 387.557772 -269.54861)
		(width 0.0889)
		(layer "In4.Cu")
		(net "M_J_CPU0_SB_CB<4>")
	)
	(arc
		(start 389.811768 -269.54861)
		(mid 390.094724 -269.472433)
		(end 390.37768 -269.54861)
		(width 0.0889)
		(layer "In4.Cu")
		(net "M_J_CPU0_SB_CB<4>")
	)
	(arc
		(start 385.111752 -269.54861)
		(mid 385.394708 -269.472433)
		(end 385.677664 -269.54861)
		(width 0.0889)
		(layer "In4.Cu")
		(net "M_J_CPU0_SB_CB<4>")
	)
	(arc
		(start 387.566154 -269.553436)
		(mid 387.749662 -269.59893)
		(end 387.931914 -269.54861)
		(width 0.0889)
		(layer "In4.Cu")
		(net "M_J_CPU0_SB_CB<4>")
	)
	(arc
		(start 381.35179 -269.54861)
		(mid 381.634746 -269.472433)
		(end 381.917702 -269.54861)
		(width 0.0889)
		(layer "In4.Cu")
		(net "M_J_CPU0_SB_CB<4>")
	)
	(arc
		(start 386.051806 -269.54861)
		(mid 386.334762 -269.472433)
		(end 386.617718 -269.54861)
		(width 0.0889)
		(layer "In4.Cu")
		(net "M_J_CPU0_SB_CB<4>")
	)
	(arc
		(start 390.751822 -269.54861)
		(mid 391.034778 -269.472433)
		(end 391.317734 -269.54861)
		(width 0.0889)
		(layer "In4.Cu")
		(net "M_J_CPU0_SB_CB<4>")
	)
	(arc
		(start 389.43788 -269.54861)
		(mid 389.624824 -269.598865)
		(end 389.811768 -269.54861)
		(width 0.0889)
		(layer "In4.Cu")
		(net "M_J_CPU0_SB_CB<4>")
	)
	(arc
		(start 391.879328 -269.22603)
		(mid 391.943843 -268.963811)
		(end 392.12266 -268.761464)
		(width 0.0889)
		(layer "In4.Cu")
		(net "M_J_CPU0_SB_CB<4>")
	)
	(arc
		(start 383.806192 -269.553436)
		(mid 383.9897 -269.59893)
		(end 384.171952 -269.54861)
		(width 0.0889)
		(layer "In4.Cu")
		(net "M_J_CPU0_SB_CB<4>")
	)
	(arc
		(start 392.727688 -268.738604)
		(mid 392.963157 -268.785849)
		(end 393.178538 -268.679676)
		(width 0.0889)
		(layer "In4.Cu")
		(net "M_J_CPU0_SB_CB<4>")
	)
	(arc
		(start 383.231898 -269.54861)
		(mid 383.514854 -269.472433)
		(end 383.79781 -269.54861)
		(width 0.0889)
		(layer "In4.Cu")
		(net "M_J_CPU0_SB_CB<4>")
	)
	(arc
		(start 384.737864 -269.54861)
		(mid 384.924808 -269.598865)
		(end 385.111752 -269.54861)
		(width 0.0889)
		(layer "In4.Cu")
		(net "M_J_CPU0_SB_CB<4>")
	)
	(arc
		(start 391.722356 -269.53083)
		(mid 391.837783 -269.397454)
		(end 391.879328 -269.22603)
		(width 0.0889)
		(layer "In4.Cu")
		(net "M_J_CPU0_SB_CB<4>")
	)
	(arc
		(start 388.506208 -269.553436)
		(mid 388.689716 -269.59893)
		(end 388.871968 -269.54861)
		(width 0.0889)
		(layer "In4.Cu")
		(net "M_J_CPU0_SB_CB<4>")
	)
	(arc
		(start 390.37768 -269.54861)
		(mid 390.559931 -269.59896)
		(end 390.74344 -269.553436)
		(width 0.0889)
		(layer "In4.Cu")
		(net "M_J_CPU0_SB_CB<4>")
	)
	(segment
		(start 378.817886 -273.820128)
		(end 379.284738 -274.086066)
		(width 0.10668)
		(layer "F.Cu")
		(net "M_J_CPU0_SB_CB<3>")
	)
	(segment
		(start 379.438916 -273.820636)
		(end 379.535182 -273.795236)
		(width 0.0889)
		(layer "In4.Cu")
		(net "M_J_CPU0_SB_CB<3>")
	)
	(segment
		(start 406.903682 -276.065488)
		(end 407.154634 -275.814536)
		(width 0.14478)
		(layer "In4.Cu")
		(net "M_J_CPU0_SB_CB<3>")
	)
	(segment
		(start 395.28877 -272.49247)
		(end 395.39799 -272.38325)
		(width 0.0889)
		(layer "In4.Cu")
		(net "M_J_CPU0_SB_CB<3>")
	)
	(segment
		(start 408.074114 -277.46452)
		(end 408.235658 -277.626064)
		(width 0.14478)
		(layer "In4.Cu")
		(net "M_J_CPU0_SB_CB<3>")
	)
	(segment
		(start 418.972746 -281.060144)
		(end 421.634158 -281.060144)
		(width 0.14478)
		(layer "In4.Cu")
		(net "M_J_CPU0_SB_CB<3>")
	)
	(segment
		(start 408.71521 -277.375112)
		(end 408.94381 -277.375112)
		(width 0.14478)
		(layer "In4.Cu")
		(net "M_J_CPU0_SB_CB<3>")
	)
	(segment
		(start 429.71339 -280.210006)
		(end 434.575204 -280.210006)
		(width 0.14478)
		(layer "In4.Cu")
		(net "M_J_CPU0_SB_CB<3>")
	)
	(segment
		(start 418.122608 -280.210006)
		(end 418.972746 -281.060144)
		(width 0.14478)
		(layer "In4.Cu")
		(net "M_J_CPU0_SB_CB<3>")
	)
	(segment
		(start 386.043424 -273.75866)
		(end 386.051806 -273.763486)
		(width 0.0889)
		(layer "In4.Cu")
		(net "M_J_CPU0_SB_CB<3>")
	)
	(segment
		(start 407.45537 -276.845776)
		(end 407.68397 -276.845776)
		(width 0.14478)
		(layer "In4.Cu")
		(net "M_J_CPU0_SB_CB<3>")
	)
	(segment
		(start 414.940242 -280.210006)
		(end 418.122608 -280.210006)
		(width 0.14478)
		(layer "In4.Cu")
		(net "M_J_CPU0_SB_CB<3>")
	)
	(segment
		(start 408.074114 -277.23592)
		(end 408.074114 -277.46452)
		(width 0.14478)
		(layer "In4.Cu")
		(net "M_J_CPU0_SB_CB<3>")
	)
	(segment
		(start 395.39799 -272.38325)
		(end 395.965172 -272.38325)
		(width 0.0889)
		(layer "In4.Cu")
		(net "M_J_CPU0_SB_CB<3>")
	)
	(segment
		(start 408.235658 -277.626064)
		(end 408.464258 -277.626064)
		(width 0.14478)
		(layer "In4.Cu")
		(net "M_J_CPU0_SB_CB<3>")
	)
	(segment
		(start 408.464258 -277.626064)
		(end 408.71521 -277.375112)
		(width 0.14478)
		(layer "In4.Cu")
		(net "M_J_CPU0_SB_CB<3>")
	)
	(segment
		(start 428.863252 -281.060144)
		(end 429.71339 -280.210006)
		(width 0.14478)
		(layer "In4.Cu")
		(net "M_J_CPU0_SB_CB<3>")
	)
	(segment
		(start 407.544778 -275.97608)
		(end 407.544778 -276.20468)
		(width 0.14478)
		(layer "In4.Cu")
		(net "M_J_CPU0_SB_CB<3>")
	)
	(segment
		(start 422.484296 -280.210006)
		(end 425.601384 -280.210006)
		(width 0.14478)
		(layer "In4.Cu")
		(net "M_J_CPU0_SB_CB<3>")
	)
	(segment
		(start 379.284738 -274.086066)
		(end 379.438916 -273.820636)
		(width 0.0889)
		(layer "In4.Cu")
		(net "M_J_CPU0_SB_CB<3>")
	)
	(segment
		(start 412.628842 -281.060144)
		(end 414.090104 -281.060144)
		(width 0.14478)
		(layer "In4.Cu")
		(net "M_J_CPU0_SB_CB<3>")
	)
	(segment
		(start 391.691876 -273.763486)
		(end 391.70229 -273.769582)
		(width 0.0889)
		(layer "In4.Cu")
		(net "M_J_CPU0_SB_CB<3>")
	)
	(segment
		(start 406.675082 -276.065488)
		(end 406.903682 -276.065488)
		(width 0.14478)
		(layer "In4.Cu")
		(net "M_J_CPU0_SB_CB<3>")
	)
	(segment
		(start 407.383234 -275.814536)
		(end 407.544778 -275.97608)
		(width 0.14478)
		(layer "In4.Cu")
		(net "M_J_CPU0_SB_CB<3>")
	)
	(segment
		(start 408.163522 -276.594824)
		(end 408.325066 -276.756368)
		(width 0.14478)
		(layer "In4.Cu")
		(net "M_J_CPU0_SB_CB<3>")
	)
	(segment
		(start 434.575204 -280.210006)
		(end 435.000146 -280.634948)
		(width 0.14478)
		(layer "In4.Cu")
		(net "M_J_CPU0_SB_CB<3>")
	)
	(segment
		(start 390.74344 -273.75866)
		(end 390.751822 -273.763486)
		(width 0.0889)
		(layer "In4.Cu")
		(net "M_J_CPU0_SB_CB<3>")
	)
	(segment
		(start 407.154634 -275.814536)
		(end 407.383234 -275.814536)
		(width 0.14478)
		(layer "In4.Cu")
		(net "M_J_CPU0_SB_CB<3>")
	)
	(segment
		(start 392.62431 -273.75866)
		(end 392.632692 -273.763486)
		(width 0.0889)
		(layer "In4.Cu")
		(net "M_J_CPU0_SB_CB<3>")
	)
	(segment
		(start 380.037848 -273.763486)
		(end 380.04623 -273.75866)
		(width 0.0889)
		(layer "In4.Cu")
		(net "M_J_CPU0_SB_CB<3>")
	)
	(segment
		(start 386.983478 -273.75866)
		(end 386.99186 -273.763486)
		(width 0.0889)
		(layer "In4.Cu")
		(net "M_J_CPU0_SB_CB<3>")
	)
	(segment
		(start 391.317734 -273.763486)
		(end 391.326116 -273.75866)
		(width 0.0889)
		(layer "In4.Cu")
		(net "M_J_CPU0_SB_CB<3>")
	)
	(segment
		(start 421.634158 -281.060144)
		(end 422.484296 -280.210006)
		(width 0.14478)
		(layer "In4.Cu")
		(net "M_J_CPU0_SB_CB<3>")
	)
	(segment
		(start 408.325066 -276.984968)
		(end 408.074114 -277.23592)
		(width 0.14478)
		(layer "In4.Cu")
		(net "M_J_CPU0_SB_CB<3>")
	)
	(segment
		(start 408.325066 -276.756368)
		(end 408.325066 -276.984968)
		(width 0.14478)
		(layer "In4.Cu")
		(net "M_J_CPU0_SB_CB<3>")
	)
	(segment
		(start 395.965172 -272.38325)
		(end 402.992844 -272.38325)
		(width 0.14478)
		(layer "In4.Cu")
		(net "M_J_CPU0_SB_CB<3>")
	)
	(segment
		(start 388.497826 -273.763486)
		(end 388.506208 -273.75866)
		(width 0.0889)
		(layer "In4.Cu")
		(net "M_J_CPU0_SB_CB<3>")
	)
	(segment
		(start 393.861798 -273.544792)
		(end 394.91412 -272.49247)
		(width 0.0889)
		(layer "In4.Cu")
		(net "M_J_CPU0_SB_CB<3>")
	)
	(segment
		(start 407.293826 -276.684232)
		(end 407.45537 -276.845776)
		(width 0.14478)
		(layer "In4.Cu")
		(net "M_J_CPU0_SB_CB<3>")
	)
	(segment
		(start 387.557772 -273.763486)
		(end 387.566154 -273.75866)
		(width 0.0889)
		(layer "In4.Cu")
		(net "M_J_CPU0_SB_CB<3>")
	)
	(segment
		(start 394.91412 -272.49247)
		(end 395.28877 -272.49247)
		(width 0.0889)
		(layer "In4.Cu")
		(net "M_J_CPU0_SB_CB<3>")
	)
	(segment
		(start 407.68397 -276.845776)
		(end 407.934922 -276.594824)
		(width 0.14478)
		(layer "In4.Cu")
		(net "M_J_CPU0_SB_CB<3>")
	)
	(segment
		(start 407.293826 -276.455632)
		(end 407.293826 -276.684232)
		(width 0.14478)
		(layer "In4.Cu")
		(net "M_J_CPU0_SB_CB<3>")
	)
	(segment
		(start 382.283462 -273.75866)
		(end 382.291844 -273.763486)
		(width 0.0889)
		(layer "In4.Cu")
		(net "M_J_CPU0_SB_CB<3>")
	)
	(segment
		(start 414.090104 -281.060144)
		(end 414.940242 -280.210006)
		(width 0.14478)
		(layer "In4.Cu")
		(net "M_J_CPU0_SB_CB<3>")
	)
	(segment
		(start 383.79781 -273.763486)
		(end 383.806192 -273.75866)
		(width 0.0889)
		(layer "In4.Cu")
		(net "M_J_CPU0_SB_CB<3>")
	)
	(segment
		(start 402.992844 -272.38325)
		(end 406.675082 -276.065488)
		(width 0.14478)
		(layer "In4.Cu")
		(net "M_J_CPU0_SB_CB<3>")
	)
	(segment
		(start 382.857756 -273.763486)
		(end 382.866138 -273.75866)
		(width 0.0889)
		(layer "In4.Cu")
		(net "M_J_CPU0_SB_CB<3>")
	)
	(segment
		(start 407.934922 -276.594824)
		(end 408.163522 -276.594824)
		(width 0.14478)
		(layer "In4.Cu")
		(net "M_J_CPU0_SB_CB<3>")
	)
	(segment
		(start 407.544778 -276.20468)
		(end 407.293826 -276.455632)
		(width 0.14478)
		(layer "In4.Cu")
		(net "M_J_CPU0_SB_CB<3>")
	)
	(segment
		(start 425.601384 -280.210006)
		(end 426.451522 -281.060144)
		(width 0.14478)
		(layer "In4.Cu")
		(net "M_J_CPU0_SB_CB<3>")
	)
	(segment
		(start 408.94381 -277.375112)
		(end 412.628842 -281.060144)
		(width 0.14478)
		(layer "In4.Cu")
		(net "M_J_CPU0_SB_CB<3>")
	)
	(segment
		(start 426.451522 -281.060144)
		(end 428.863252 -281.060144)
		(width 0.14478)
		(layer "In4.Cu")
		(net "M_J_CPU0_SB_CB<3>")
	)
	(arc
		(start 382.291844 -273.763486)
		(mid 382.5748 -273.839663)
		(end 382.857756 -273.763486)
		(width 0.0889)
		(layer "In4.Cu")
		(net "M_J_CPU0_SB_CB<3>")
	)
	(arc
		(start 385.677664 -273.763486)
		(mid 385.859915 -273.713136)
		(end 386.043424 -273.75866)
		(width 0.0889)
		(layer "In4.Cu")
		(net "M_J_CPU0_SB_CB<3>")
	)
	(arc
		(start 391.70229 -273.769582)
		(mid 391.980976 -273.839802)
		(end 392.258042 -273.763486)
		(width 0.0889)
		(layer "In4.Cu")
		(net "M_J_CPU0_SB_CB<3>")
	)
	(arc
		(start 392.632692 -273.763486)
		(mid 392.91212 -273.839652)
		(end 393.192508 -273.767042)
		(width 0.0889)
		(layer "In4.Cu")
		(net "M_J_CPU0_SB_CB<3>")
	)
	(arc
		(start 388.871968 -273.763486)
		(mid 389.154924 -273.839663)
		(end 389.43788 -273.763486)
		(width 0.0889)
		(layer "In4.Cu")
		(net "M_J_CPU0_SB_CB<3>")
	)
	(arc
		(start 387.931914 -273.763486)
		(mid 388.21487 -273.839663)
		(end 388.497826 -273.763486)
		(width 0.0889)
		(layer "In4.Cu")
		(net "M_J_CPU0_SB_CB<3>")
	)
	(arc
		(start 389.811768 -273.763486)
		(mid 390.094724 -273.839663)
		(end 390.37768 -273.763486)
		(width 0.0889)
		(layer "In4.Cu")
		(net "M_J_CPU0_SB_CB<3>")
	)
	(arc
		(start 384.737864 -273.763486)
		(mid 384.924808 -273.713231)
		(end 385.111752 -273.763486)
		(width 0.0889)
		(layer "In4.Cu")
		(net "M_J_CPU0_SB_CB<3>")
	)
	(arc
		(start 392.258042 -273.763486)
		(mid 392.440547 -273.713009)
		(end 392.62431 -273.75866)
		(width 0.0889)
		(layer "In4.Cu")
		(net "M_J_CPU0_SB_CB<3>")
	)
	(arc
		(start 386.617718 -273.763486)
		(mid 386.799969 -273.713136)
		(end 386.983478 -273.75866)
		(width 0.0889)
		(layer "In4.Cu")
		(net "M_J_CPU0_SB_CB<3>")
	)
	(arc
		(start 380.04623 -273.75866)
		(mid 380.229738 -273.713166)
		(end 380.41199 -273.763486)
		(width 0.0889)
		(layer "In4.Cu")
		(net "M_J_CPU0_SB_CB<3>")
	)
	(arc
		(start 388.506208 -273.75866)
		(mid 388.689716 -273.713166)
		(end 388.871968 -273.763486)
		(width 0.0889)
		(layer "In4.Cu")
		(net "M_J_CPU0_SB_CB<3>")
	)
	(arc
		(start 393.384786 -273.712686)
		(mid 393.637631 -273.669483)
		(end 393.861798 -273.544792)
		(width 0.0889)
		(layer "In4.Cu")
		(net "M_J_CPU0_SB_CB<3>")
	)
	(arc
		(start 380.977902 -273.763486)
		(mid 381.164846 -273.713231)
		(end 381.35179 -273.763486)
		(width 0.0889)
		(layer "In4.Cu")
		(net "M_J_CPU0_SB_CB<3>")
	)
	(arc
		(start 382.866138 -273.75866)
		(mid 383.049646 -273.713166)
		(end 383.231898 -273.763486)
		(width 0.0889)
		(layer "In4.Cu")
		(net "M_J_CPU0_SB_CB<3>")
	)
	(arc
		(start 386.99186 -273.763486)
		(mid 387.274816 -273.839663)
		(end 387.557772 -273.763486)
		(width 0.0889)
		(layer "In4.Cu")
		(net "M_J_CPU0_SB_CB<3>")
	)
	(arc
		(start 385.111752 -273.763486)
		(mid 385.394708 -273.839663)
		(end 385.677664 -273.763486)
		(width 0.0889)
		(layer "In4.Cu")
		(net "M_J_CPU0_SB_CB<3>")
	)
	(arc
		(start 386.051806 -273.763486)
		(mid 386.334762 -273.839663)
		(end 386.617718 -273.763486)
		(width 0.0889)
		(layer "In4.Cu")
		(net "M_J_CPU0_SB_CB<3>")
	)
	(arc
		(start 391.326116 -273.75866)
		(mid 391.509624 -273.713166)
		(end 391.691876 -273.763486)
		(width 0.0889)
		(layer "In4.Cu")
		(net "M_J_CPU0_SB_CB<3>")
	)
	(arc
		(start 390.751822 -273.763486)
		(mid 391.034778 -273.839663)
		(end 391.317734 -273.763486)
		(width 0.0889)
		(layer "In4.Cu")
		(net "M_J_CPU0_SB_CB<3>")
	)
	(arc
		(start 390.37768 -273.763486)
		(mid 390.559931 -273.713136)
		(end 390.74344 -273.75866)
		(width 0.0889)
		(layer "In4.Cu")
		(net "M_J_CPU0_SB_CB<3>")
	)
	(arc
		(start 393.192508 -273.767042)
		(mid 393.28494 -273.72676)
		(end 393.384786 -273.712686)
		(width 0.0889)
		(layer "In4.Cu")
		(net "M_J_CPU0_SB_CB<3>")
	)
	(arc
		(start 379.535182 -273.795236)
		(mid 379.790247 -273.838587)
		(end 380.037848 -273.763486)
		(width 0.0889)
		(layer "In4.Cu")
		(net "M_J_CPU0_SB_CB<3>")
	)
	(arc
		(start 381.35179 -273.763486)
		(mid 381.634746 -273.839663)
		(end 381.917702 -273.763486)
		(width 0.0889)
		(layer "In4.Cu")
		(net "M_J_CPU0_SB_CB<3>")
	)
	(arc
		(start 384.171952 -273.763486)
		(mid 384.454908 -273.839663)
		(end 384.737864 -273.763486)
		(width 0.0889)
		(layer "In4.Cu")
		(net "M_J_CPU0_SB_CB<3>")
	)
	(arc
		(start 383.231898 -273.763486)
		(mid 383.514854 -273.839663)
		(end 383.79781 -273.763486)
		(width 0.0889)
		(layer "In4.Cu")
		(net "M_J_CPU0_SB_CB<3>")
	)
	(arc
		(start 387.566154 -273.75866)
		(mid 387.749662 -273.713166)
		(end 387.931914 -273.763486)
		(width 0.0889)
		(layer "In4.Cu")
		(net "M_J_CPU0_SB_CB<3>")
	)
	(arc
		(start 389.43788 -273.763486)
		(mid 389.624824 -273.713231)
		(end 389.811768 -273.763486)
		(width 0.0889)
		(layer "In4.Cu")
		(net "M_J_CPU0_SB_CB<3>")
	)
	(arc
		(start 380.41199 -273.763486)
		(mid 380.694946 -273.839663)
		(end 380.977902 -273.763486)
		(width 0.0889)
		(layer "In4.Cu")
		(net "M_J_CPU0_SB_CB<3>")
	)
	(arc
		(start 381.917702 -273.763486)
		(mid 382.099953 -273.713136)
		(end 382.283462 -273.75866)
		(width 0.0889)
		(layer "In4.Cu")
		(net "M_J_CPU0_SB_CB<3>")
	)
	(arc
		(start 383.806192 -273.75866)
		(mid 383.9897 -273.713166)
		(end 384.171952 -273.763486)
		(width 0.0889)
		(layer "In4.Cu")
		(net "M_J_CPU0_SB_CB<3>")
	)
	(segment
		(start 380.22784 -273.010122)
		(end 380.694946 -273.27606)
		(width 0.10668)
		(layer "F.Cu")
		(net "M_J_CPU0_SB_CB<2>")
	)
	(segment
		(start 405.938736 -274.05711)
		(end 405.777192 -273.895566)
		(width 0.14478)
		(layer "In4.Cu")
		(net "M_J_CPU0_SB_CB<2>")
	)
	(segment
		(start 421.634158 -279.360122)
		(end 418.676074 -279.360122)
		(width 0.14478)
		(layer "In4.Cu")
		(net "M_J_CPU0_SB_CB<2>")
	)
	(segment
		(start 404.477982 -271.845024)
		(end 404.477982 -271.616424)
		(width 0.14478)
		(layer "In4.Cu")
		(net "M_J_CPU0_SB_CB<2>")
	)
	(segment
		(start 405.25827 -272.396712)
		(end 405.096726 -272.235168)
		(width 0.14478)
		(layer "In4.Cu")
		(net "M_J_CPU0_SB_CB<2>")
	)
	(segment
		(start 404.477982 -271.616424)
		(end 404.335488 -271.47393)
		(width 0.14478)
		(layer "In4.Cu")
		(net "M_J_CPU0_SB_CB<2>")
	)
	(segment
		(start 414.940242 -278.509984)
		(end 414.090104 -279.360122)
		(width 0.14478)
		(layer "In4.Cu")
		(net "M_J_CPU0_SB_CB<2>")
	)
	(segment
		(start 406.947624 -274.837398)
		(end 406.719024 -274.837398)
		(width 0.14478)
		(layer "In4.Cu")
		(net "M_J_CPU0_SB_CB<2>")
	)
	(segment
		(start 395.416786 -271.47393)
		(end 395.134846 -271.75587)
		(width 0.0889)
		(layer "In4.Cu")
		(net "M_J_CPU0_SB_CB<2>")
	)
	(segment
		(start 406.55748 -274.675854)
		(end 406.55748 -274.447254)
		(width 0.14478)
		(layer "In4.Cu")
		(net "M_J_CPU0_SB_CB<2>")
	)
	(segment
		(start 392.182604 -272.96618)
		(end 392.161014 -272.953734)
		(width 0.0889)
		(layer "In4.Cu")
		(net "M_J_CPU0_SB_CB<2>")
	)
	(segment
		(start 404.216616 -272.33499)
		(end 404.216616 -272.10639)
		(width 0.14478)
		(layer "In4.Cu")
		(net "M_J_CPU0_SB_CB<2>")
	)
	(segment
		(start 406.719024 -274.837398)
		(end 406.55748 -274.675854)
		(width 0.14478)
		(layer "In4.Cu")
		(net "M_J_CPU0_SB_CB<2>")
	)
	(segment
		(start 392.744198 -272.942558)
		(end 392.725402 -272.95348)
		(width 0.0889)
		(layer "In4.Cu")
		(net "M_J_CPU0_SB_CB<2>")
	)
	(segment
		(start 426.19168 -279.360122)
		(end 425.341542 -278.509984)
		(width 0.14478)
		(layer "In4.Cu")
		(net "M_J_CPU0_SB_CB<2>")
	)
	(segment
		(start 422.484296 -278.509984)
		(end 421.634158 -279.360122)
		(width 0.14478)
		(layer "In4.Cu")
		(net "M_J_CPU0_SB_CB<2>")
	)
	(segment
		(start 406.55748 -274.447254)
		(end 406.818846 -274.185888)
		(width 0.14478)
		(layer "In4.Cu")
		(net "M_J_CPU0_SB_CB<2>")
	)
	(segment
		(start 418.676074 -279.360122)
		(end 417.825936 -278.509984)
		(width 0.14478)
		(layer "In4.Cu")
		(net "M_J_CPU0_SB_CB<2>")
	)
	(segment
		(start 411.10281 -277.296372)
		(end 410.15793 -277.296372)
		(width 0.14478)
		(layer "In4.Cu")
		(net "M_J_CPU0_SB_CB<2>")
	)
	(segment
		(start 383.701798 -272.95348)
		(end 383.693416 -272.948654)
		(width 0.0889)
		(layer "In4.Cu")
		(net "M_J_CPU0_SB_CB<2>")
	)
	(segment
		(start 405.158448 -273.276822)
		(end 404.996904 -273.115278)
		(width 0.14478)
		(layer "In4.Cu")
		(net "M_J_CPU0_SB_CB<2>")
	)
	(segment
		(start 405.777192 -273.895566)
		(end 405.777192 -273.666966)
		(width 0.14478)
		(layer "In4.Cu")
		(net "M_J_CPU0_SB_CB<2>")
	)
	(segment
		(start 395.936724 -271.47393)
		(end 395.416786 -271.47393)
		(width 0.0889)
		(layer "In4.Cu")
		(net "M_J_CPU0_SB_CB<2>")
	)
	(segment
		(start 404.335488 -271.47393)
		(end 395.936724 -271.47393)
		(width 0.14478)
		(layer "In4.Cu")
		(net "M_J_CPU0_SB_CB<2>")
	)
	(segment
		(start 405.777192 -273.666966)
		(end 406.038558 -273.4056)
		(width 0.14478)
		(layer "In4.Cu")
		(net "M_J_CPU0_SB_CB<2>")
	)
	(segment
		(start 384.641852 -272.95348)
		(end 384.63347 -272.948654)
		(width 0.0889)
		(layer "In4.Cu")
		(net "M_J_CPU0_SB_CB<2>")
	)
	(segment
		(start 388.401814 -272.95348)
		(end 388.393432 -272.948654)
		(width 0.0889)
		(layer "In4.Cu")
		(net "M_J_CPU0_SB_CB<2>")
	)
	(segment
		(start 413.16656 -279.360122)
		(end 411.10281 -277.296372)
		(width 0.14478)
		(layer "In4.Cu")
		(net "M_J_CPU0_SB_CB<2>")
	)
	(segment
		(start 404.868126 -272.235168)
		(end 404.60676 -272.496534)
		(width 0.14478)
		(layer "In4.Cu")
		(net "M_J_CPU0_SB_CB<2>")
	)
	(segment
		(start 406.428702 -273.795744)
		(end 406.167336 -274.05711)
		(width 0.14478)
		(layer "In4.Cu")
		(net "M_J_CPU0_SB_CB<2>")
	)
	(segment
		(start 405.877014 -273.015456)
		(end 405.648414 -273.015456)
		(width 0.14478)
		(layer "In4.Cu")
		(net "M_J_CPU0_SB_CB<2>")
	)
	(segment
		(start 404.60676 -272.496534)
		(end 404.37816 -272.496534)
		(width 0.14478)
		(layer "In4.Cu")
		(net "M_J_CPU0_SB_CB<2>")
	)
	(segment
		(start 385.216146 -272.948654)
		(end 385.207764 -272.95348)
		(width 0.0889)
		(layer "In4.Cu")
		(net "M_J_CPU0_SB_CB<2>")
	)
	(segment
		(start 404.216616 -272.10639)
		(end 404.477982 -271.845024)
		(width 0.14478)
		(layer "In4.Cu")
		(net "M_J_CPU0_SB_CB<2>")
	)
	(segment
		(start 425.341542 -278.509984)
		(end 422.484296 -278.509984)
		(width 0.14478)
		(layer "In4.Cu")
		(net "M_J_CPU0_SB_CB<2>")
	)
	(segment
		(start 404.37816 -272.496534)
		(end 404.216616 -272.33499)
		(width 0.14478)
		(layer "In4.Cu")
		(net "M_J_CPU0_SB_CB<2>")
	)
	(segment
		(start 389.341868 -272.95348)
		(end 389.333486 -272.948654)
		(width 0.0889)
		(layer "In4.Cu")
		(net "M_J_CPU0_SB_CB<2>")
	)
	(segment
		(start 406.818846 -274.185888)
		(end 406.818846 -273.957288)
		(width 0.14478)
		(layer "In4.Cu")
		(net "M_J_CPU0_SB_CB<2>")
	)
	(segment
		(start 406.657302 -273.795744)
		(end 406.428702 -273.795744)
		(width 0.14478)
		(layer "In4.Cu")
		(net "M_J_CPU0_SB_CB<2>")
	)
	(segment
		(start 417.825936 -278.509984)
		(end 414.940242 -278.509984)
		(width 0.14478)
		(layer "In4.Cu")
		(net "M_J_CPU0_SB_CB<2>")
	)
	(segment
		(start 386.1562 -272.948654)
		(end 386.147818 -272.95348)
		(width 0.0889)
		(layer "In4.Cu")
		(net "M_J_CPU0_SB_CB<2>")
	)
	(segment
		(start 389.916162 -272.948654)
		(end 389.90778 -272.95348)
		(width 0.0889)
		(layer "In4.Cu")
		(net "M_J_CPU0_SB_CB<2>")
	)
	(segment
		(start 405.387048 -273.276822)
		(end 405.158448 -273.276822)
		(width 0.14478)
		(layer "In4.Cu")
		(net "M_J_CPU0_SB_CB<2>")
	)
	(segment
		(start 410.15793 -277.296372)
		(end 407.43759 -274.576032)
		(width 0.14478)
		(layer "In4.Cu")
		(net "M_J_CPU0_SB_CB<2>")
	)
	(segment
		(start 435.000146 -278.93518)
		(end 434.57495 -278.509984)
		(width 0.14478)
		(layer "In4.Cu")
		(net "M_J_CPU0_SB_CB<2>")
	)
	(segment
		(start 434.57495 -278.509984)
		(end 430.054766 -278.509984)
		(width 0.14478)
		(layer "In4.Cu")
		(net "M_J_CPU0_SB_CB<2>")
	)
	(segment
		(start 404.996904 -272.886678)
		(end 405.25827 -272.625312)
		(width 0.14478)
		(layer "In4.Cu")
		(net "M_J_CPU0_SB_CB<2>")
	)
	(segment
		(start 430.054766 -278.509984)
		(end 429.204628 -279.360122)
		(width 0.14478)
		(layer "In4.Cu")
		(net "M_J_CPU0_SB_CB<2>")
	)
	(segment
		(start 394.949426 -271.75587)
		(end 393.8651 -272.840196)
		(width 0.0889)
		(layer "In4.Cu")
		(net "M_J_CPU0_SB_CB<2>")
	)
	(segment
		(start 381.456184 -272.948654)
		(end 381.447802 -272.95348)
		(width 0.0889)
		(layer "In4.Cu")
		(net "M_J_CPU0_SB_CB<2>")
	)
	(segment
		(start 405.096726 -272.235168)
		(end 404.868126 -272.235168)
		(width 0.14478)
		(layer "In4.Cu")
		(net "M_J_CPU0_SB_CB<2>")
	)
	(segment
		(start 429.204628 -279.360122)
		(end 426.19168 -279.360122)
		(width 0.14478)
		(layer "In4.Cu")
		(net "M_J_CPU0_SB_CB<2>")
	)
	(segment
		(start 380.944882 -272.98523)
		(end 380.84887 -273.01063)
		(width 0.0889)
		(layer "In4.Cu")
		(net "M_J_CPU0_SB_CB<2>")
	)
	(segment
		(start 405.25827 -272.625312)
		(end 405.25827 -272.396712)
		(width 0.14478)
		(layer "In4.Cu")
		(net "M_J_CPU0_SB_CB<2>")
	)
	(segment
		(start 380.84887 -273.01063)
		(end 380.694946 -273.27606)
		(width 0.0889)
		(layer "In4.Cu")
		(net "M_J_CPU0_SB_CB<2>")
	)
	(segment
		(start 404.996904 -273.115278)
		(end 404.996904 -272.886678)
		(width 0.14478)
		(layer "In4.Cu")
		(net "M_J_CPU0_SB_CB<2>")
	)
	(segment
		(start 405.648414 -273.015456)
		(end 405.387048 -273.276822)
		(width 0.14478)
		(layer "In4.Cu")
		(net "M_J_CPU0_SB_CB<2>")
	)
	(segment
		(start 414.090104 -279.360122)
		(end 413.16656 -279.360122)
		(width 0.14478)
		(layer "In4.Cu")
		(net "M_J_CPU0_SB_CB<2>")
	)
	(segment
		(start 406.818846 -273.957288)
		(end 406.657302 -273.795744)
		(width 0.14478)
		(layer "In4.Cu")
		(net "M_J_CPU0_SB_CB<2>")
	)
	(segment
		(start 406.167336 -274.05711)
		(end 405.938736 -274.05711)
		(width 0.14478)
		(layer "In4.Cu")
		(net "M_J_CPU0_SB_CB<2>")
	)
	(segment
		(start 407.43759 -274.576032)
		(end 407.20899 -274.576032)
		(width 0.14478)
		(layer "In4.Cu")
		(net "M_J_CPU0_SB_CB<2>")
	)
	(segment
		(start 406.038558 -273.177)
		(end 405.877014 -273.015456)
		(width 0.14478)
		(layer "In4.Cu")
		(net "M_J_CPU0_SB_CB<2>")
	)
	(segment
		(start 392.161014 -272.953734)
		(end 392.140948 -272.942304)
		(width 0.0889)
		(layer "In4.Cu")
		(net "M_J_CPU0_SB_CB<2>")
	)
	(segment
		(start 406.038558 -273.4056)
		(end 406.038558 -273.177)
		(width 0.14478)
		(layer "In4.Cu")
		(net "M_J_CPU0_SB_CB<2>")
	)
	(segment
		(start 395.134846 -271.75587)
		(end 394.949426 -271.75587)
		(width 0.0889)
		(layer "In4.Cu")
		(net "M_J_CPU0_SB_CB<2>")
	)
	(segment
		(start 407.20899 -274.576032)
		(end 406.947624 -274.837398)
		(width 0.14478)
		(layer "In4.Cu")
		(net "M_J_CPU0_SB_CB<2>")
	)
	(arc
		(start 382.387856 -272.95348)
		(mid 382.1049 -273.029657)
		(end 381.821944 -272.95348)
		(width 0.0889)
		(layer "In4.Cu")
		(net "M_J_CPU0_SB_CB<2>")
	)
	(arc
		(start 386.52196 -272.95348)
		(mid 386.339709 -272.90313)
		(end 386.1562 -272.948654)
		(width 0.0889)
		(layer "In4.Cu")
		(net "M_J_CPU0_SB_CB<2>")
	)
	(arc
		(start 384.63347 -272.948654)
		(mid 384.449962 -272.90316)
		(end 384.26771 -272.95348)
		(width 0.0889)
		(layer "In4.Cu")
		(net "M_J_CPU0_SB_CB<2>")
	)
	(arc
		(start 386.147818 -272.95348)
		(mid 385.864862 -273.029657)
		(end 385.581906 -272.95348)
		(width 0.0889)
		(layer "In4.Cu")
		(net "M_J_CPU0_SB_CB<2>")
	)
	(arc
		(start 389.90778 -272.95348)
		(mid 389.624824 -273.029657)
		(end 389.341868 -272.95348)
		(width 0.0889)
		(layer "In4.Cu")
		(net "M_J_CPU0_SB_CB<2>")
	)
	(arc
		(start 390.281922 -272.95348)
		(mid 390.099671 -272.90313)
		(end 389.916162 -272.948654)
		(width 0.0889)
		(layer "In4.Cu")
		(net "M_J_CPU0_SB_CB<2>")
	)
	(arc
		(start 393.8651 -272.840196)
		(mid 393.758607 -272.921546)
		(end 393.634468 -272.972022)
		(width 0.0889)
		(layer "In4.Cu")
		(net "M_J_CPU0_SB_CB<2>")
	)
	(arc
		(start 388.027672 -272.95348)
		(mid 387.744716 -273.029657)
		(end 387.46176 -272.95348)
		(width 0.0889)
		(layer "In4.Cu")
		(net "M_J_CPU0_SB_CB<2>")
	)
	(arc
		(start 384.26771 -272.95348)
		(mid 383.984754 -273.029657)
		(end 383.701798 -272.95348)
		(width 0.0889)
		(layer "In4.Cu")
		(net "M_J_CPU0_SB_CB<2>")
	)
	(arc
		(start 381.447802 -272.95348)
		(mid 381.200089 -273.0287)
		(end 380.944882 -272.98523)
		(width 0.0889)
		(layer "In4.Cu")
		(net "M_J_CPU0_SB_CB<2>")
	)
	(arc
		(start 393.634468 -272.972022)
		(mid 393.365183 -273.029934)
		(end 393.10056 -272.95348)
		(width 0.0889)
		(layer "In4.Cu")
		(net "M_J_CPU0_SB_CB<2>")
	)
	(arc
		(start 389.333486 -272.948654)
		(mid 389.149978 -272.90316)
		(end 388.967726 -272.95348)
		(width 0.0889)
		(layer "In4.Cu")
		(net "M_J_CPU0_SB_CB<2>")
	)
	(arc
		(start 388.393432 -272.948654)
		(mid 388.209924 -272.90316)
		(end 388.027672 -272.95348)
		(width 0.0889)
		(layer "In4.Cu")
		(net "M_J_CPU0_SB_CB<2>")
	)
	(arc
		(start 383.327656 -272.95348)
		(mid 383.0447 -273.029657)
		(end 382.761744 -272.95348)
		(width 0.0889)
		(layer "In4.Cu")
		(net "M_J_CPU0_SB_CB<2>")
	)
	(arc
		(start 383.693416 -272.948654)
		(mid 383.509908 -272.90316)
		(end 383.327656 -272.95348)
		(width 0.0889)
		(layer "In4.Cu")
		(net "M_J_CPU0_SB_CB<2>")
	)
	(arc
		(start 393.10056 -272.95348)
		(mid 392.923769 -272.902761)
		(end 392.744198 -272.942558)
		(width 0.0889)
		(layer "In4.Cu")
		(net "M_J_CPU0_SB_CB<2>")
	)
	(arc
		(start 382.761744 -272.95348)
		(mid 382.5748 -272.903225)
		(end 382.387856 -272.95348)
		(width 0.0889)
		(layer "In4.Cu")
		(net "M_J_CPU0_SB_CB<2>")
	)
	(arc
		(start 381.821944 -272.95348)
		(mid 381.639693 -272.90313)
		(end 381.456184 -272.948654)
		(width 0.0889)
		(layer "In4.Cu")
		(net "M_J_CPU0_SB_CB<2>")
	)
	(arc
		(start 392.140948 -272.942304)
		(mid 391.96287 -272.90332)
		(end 391.787634 -272.95348)
		(width 0.0889)
		(layer "In4.Cu")
		(net "M_J_CPU0_SB_CB<2>")
	)
	(arc
		(start 387.087872 -272.95348)
		(mid 386.804916 -273.029657)
		(end 386.52196 -272.95348)
		(width 0.0889)
		(layer "In4.Cu")
		(net "M_J_CPU0_SB_CB<2>")
	)
	(arc
		(start 387.46176 -272.95348)
		(mid 387.274816 -272.903225)
		(end 387.087872 -272.95348)
		(width 0.0889)
		(layer "In4.Cu")
		(net "M_J_CPU0_SB_CB<2>")
	)
	(arc
		(start 390.847834 -272.95348)
		(mid 390.564878 -273.029657)
		(end 390.281922 -272.95348)
		(width 0.0889)
		(layer "In4.Cu")
		(net "M_J_CPU0_SB_CB<2>")
	)
	(arc
		(start 388.967726 -272.95348)
		(mid 388.68477 -273.029657)
		(end 388.401814 -272.95348)
		(width 0.0889)
		(layer "In4.Cu")
		(net "M_J_CPU0_SB_CB<2>")
	)
	(arc
		(start 391.787634 -272.95348)
		(mid 391.504678 -273.029657)
		(end 391.221722 -272.95348)
		(width 0.0889)
		(layer "In4.Cu")
		(net "M_J_CPU0_SB_CB<2>")
	)
	(arc
		(start 385.581906 -272.95348)
		(mid 385.399655 -272.90313)
		(end 385.216146 -272.948654)
		(width 0.0889)
		(layer "In4.Cu")
		(net "M_J_CPU0_SB_CB<2>")
	)
	(arc
		(start 391.221722 -272.95348)
		(mid 391.034778 -272.903225)
		(end 390.847834 -272.95348)
		(width 0.0889)
		(layer "In4.Cu")
		(net "M_J_CPU0_SB_CB<2>")
	)
	(arc
		(start 385.207764 -272.95348)
		(mid 384.924808 -273.029657)
		(end 384.641852 -272.95348)
		(width 0.0889)
		(layer "In4.Cu")
		(net "M_J_CPU0_SB_CB<2>")
	)
	(arc
		(start 392.725402 -272.95348)
		(mid 392.455633 -273.029503)
		(end 392.182604 -272.96618)
		(width 0.0889)
		(layer "In4.Cu")
		(net "M_J_CPU0_SB_CB<2>")
	)
	(segment
		(start 379.28804 -273.010122)
		(end 379.754892 -273.27606)
		(width 0.10668)
		(layer "F.Cu")
		(net "M_J_CPU0_SB_CB<1>")
	)
	(segment
		(start 392.718036 -273.592544)
		(end 392.72845 -273.59864)
		(width 0.0889)
		(layer "In4.Cu")
		(net "M_J_CPU0_SB_CB<1>")
	)
	(segment
		(start 389.333486 -273.603466)
		(end 389.341868 -273.59864)
		(width 0.0889)
		(layer "In4.Cu")
		(net "M_J_CPU0_SB_CB<1>")
	)
	(segment
		(start 384.63347 -273.603466)
		(end 384.641852 -273.59864)
		(width 0.0889)
		(layer "In4.Cu")
		(net "M_J_CPU0_SB_CB<1>")
	)
	(segment
		(start 385.207764 -273.59864)
		(end 385.216146 -273.603466)
		(width 0.0889)
		(layer "In4.Cu")
		(net "M_J_CPU0_SB_CB<1>")
	)
	(segment
		(start 403.1742 -271.92859)
		(end 406.532588 -275.286978)
		(width 0.14478)
		(layer "In4.Cu")
		(net "M_J_CPU0_SB_CB<1>")
	)
	(segment
		(start 424.840654 -279.360122)
		(end 426.892466 -280.210006)
		(width 0.14478)
		(layer "In4.Cu")
		(net "M_J_CPU0_SB_CB<1>")
	)
	(segment
		(start 381.447802 -273.59864)
		(end 381.456184 -273.603466)
		(width 0.0889)
		(layer "In4.Cu")
		(net "M_J_CPU0_SB_CB<1>")
	)
	(segment
		(start 379.600714 -273.54149)
		(end 379.623066 -273.624802)
		(width 0.0889)
		(layer "In4.Cu")
		(net "M_J_CPU0_SB_CB<1>")
	)
	(segment
		(start 414.034224 -280.370026)
		(end 415.044128 -279.360122)
		(width 0.14478)
		(layer "In4.Cu")
		(net "M_J_CPU0_SB_CB<1>")
	)
	(segment
		(start 413.540448 -280.370026)
		(end 414.034224 -280.370026)
		(width 0.14478)
		(layer "In4.Cu")
		(net "M_J_CPU0_SB_CB<1>")
	)
	(segment
		(start 391.787634 -273.59864)
		(end 391.796016 -273.603466)
		(width 0.0889)
		(layer "In4.Cu")
		(net "M_J_CPU0_SB_CB<1>")
	)
	(segment
		(start 389.90778 -273.59864)
		(end 389.916162 -273.603466)
		(width 0.0889)
		(layer "In4.Cu")
		(net "M_J_CPU0_SB_CB<1>")
	)
	(segment
		(start 420.935658 -280.210006)
		(end 422.98747 -279.360122)
		(width 0.14478)
		(layer "In4.Cu")
		(net "M_J_CPU0_SB_CB<1>")
	)
	(segment
		(start 428.40529 -280.210006)
		(end 430.457102 -279.360122)
		(width 0.14478)
		(layer "In4.Cu")
		(net "M_J_CPU0_SB_CB<1>")
	)
	(segment
		(start 395.395196 -271.92859)
		(end 395.965172 -271.92859)
		(width 0.0889)
		(layer "In4.Cu")
		(net "M_J_CPU0_SB_CB<1>")
	)
	(segment
		(start 415.044128 -279.360122)
		(end 417.424616 -279.360122)
		(width 0.14478)
		(layer "In4.Cu")
		(net "M_J_CPU0_SB_CB<1>")
	)
	(segment
		(start 379.933454 -273.603466)
		(end 379.941836 -273.59864)
		(width 0.0889)
		(layer "In4.Cu")
		(net "M_J_CPU0_SB_CB<1>")
	)
	(segment
		(start 379.754892 -273.27606)
		(end 379.600714 -273.54149)
		(width 0.0889)
		(layer "In4.Cu")
		(net "M_J_CPU0_SB_CB<1>")
	)
	(segment
		(start 395.965172 -271.92859)
		(end 403.1742 -271.92859)
		(width 0.14478)
		(layer "In4.Cu")
		(net "M_J_CPU0_SB_CB<1>")
	)
	(segment
		(start 395.174216 -272.14957)
		(end 395.395196 -271.92859)
		(width 0.0889)
		(layer "In4.Cu")
		(net "M_J_CPU0_SB_CB<1>")
	)
	(segment
		(start 386.147818 -273.59864)
		(end 386.1562 -273.603466)
		(width 0.0889)
		(layer "In4.Cu")
		(net "M_J_CPU0_SB_CB<1>")
	)
	(segment
		(start 394.987272 -272.14957)
		(end 395.174216 -272.14957)
		(width 0.0889)
		(layer "In4.Cu")
		(net "M_J_CPU0_SB_CB<1>")
	)
	(segment
		(start 383.693416 -273.603466)
		(end 383.701798 -273.59864)
		(width 0.0889)
		(layer "In4.Cu")
		(net "M_J_CPU0_SB_CB<1>")
	)
	(segment
		(start 407.51252 -275.286978)
		(end 410.308806 -278.083264)
		(width 0.14478)
		(layer "In4.Cu")
		(net "M_J_CPU0_SB_CB<1>")
	)
	(segment
		(start 380.873508 -273.603466)
		(end 380.88189 -273.59864)
		(width 0.0889)
		(layer "In4.Cu")
		(net "M_J_CPU0_SB_CB<1>")
	)
	(segment
		(start 410.308806 -278.083264)
		(end 411.92196 -278.751538)
		(width 0.14478)
		(layer "In4.Cu")
		(net "M_J_CPU0_SB_CB<1>")
	)
	(segment
		(start 419.476428 -280.210006)
		(end 420.935658 -280.210006)
		(width 0.14478)
		(layer "In4.Cu")
		(net "M_J_CPU0_SB_CB<1>")
	)
	(segment
		(start 436.96382 -279.360122)
		(end 439.100214 -279.785064)
		(width 0.14478)
		(layer "In4.Cu")
		(net "M_J_CPU0_SB_CB<1>")
	)
	(segment
		(start 417.424616 -279.360122)
		(end 419.476428 -280.210006)
		(width 0.14478)
		(layer "In4.Cu")
		(net "M_J_CPU0_SB_CB<1>")
	)
	(segment
		(start 406.532588 -275.286978)
		(end 407.51252 -275.286978)
		(width 0.14478)
		(layer "In4.Cu")
		(net "M_J_CPU0_SB_CB<1>")
	)
	(segment
		(start 393.734798 -273.402044)
		(end 394.987272 -272.14957)
		(width 0.0889)
		(layer "In4.Cu")
		(net "M_J_CPU0_SB_CB<1>")
	)
	(segment
		(start 388.393432 -273.603466)
		(end 388.401814 -273.59864)
		(width 0.0889)
		(layer "In4.Cu")
		(net "M_J_CPU0_SB_CB<1>")
	)
	(segment
		(start 393.384278 -273.521932)
		(end 393.384532 -273.521932)
		(width 0.0889)
		(layer "In4.Cu")
		(net "M_J_CPU0_SB_CB<1>")
	)
	(segment
		(start 422.98747 -279.360122)
		(end 424.840654 -279.360122)
		(width 0.14478)
		(layer "In4.Cu")
		(net "M_J_CPU0_SB_CB<1>")
	)
	(segment
		(start 426.892466 -280.210006)
		(end 428.40529 -280.210006)
		(width 0.14478)
		(layer "In4.Cu")
		(net "M_J_CPU0_SB_CB<1>")
	)
	(segment
		(start 430.457102 -279.360122)
		(end 436.96382 -279.360122)
		(width 0.14478)
		(layer "In4.Cu")
		(net "M_J_CPU0_SB_CB<1>")
	)
	(segment
		(start 411.92196 -278.751538)
		(end 413.540448 -280.370026)
		(width 0.14478)
		(layer "In4.Cu")
		(net "M_J_CPU0_SB_CB<1>")
	)
	(arc
		(start 386.1562 -273.603466)
		(mid 386.339708 -273.64896)
		(end 386.52196 -273.59864)
		(width 0.0889)
		(layer "In4.Cu")
		(net "M_J_CPU0_SB_CB<1>")
	)
	(arc
		(start 393.308332 -273.527266)
		(mid 393.346215 -273.523309)
		(end 393.384278 -273.521932)
		(width 0.0889)
		(layer "In4.Cu")
		(net "M_J_CPU0_SB_CB<1>")
	)
	(arc
		(start 385.581906 -273.59864)
		(mid 385.864862 -273.522463)
		(end 386.147818 -273.59864)
		(width 0.0889)
		(layer "In4.Cu")
		(net "M_J_CPU0_SB_CB<1>")
	)
	(arc
		(start 393.086082 -273.607784)
		(mid 393.192943 -273.555756)
		(end 393.308332 -273.527266)
		(width 0.0889)
		(layer "In4.Cu")
		(net "M_J_CPU0_SB_CB<1>")
	)
	(arc
		(start 382.761744 -273.59864)
		(mid 383.0447 -273.522463)
		(end 383.327656 -273.59864)
		(width 0.0889)
		(layer "In4.Cu")
		(net "M_J_CPU0_SB_CB<1>")
	)
	(arc
		(start 392.162284 -273.59864)
		(mid 392.439351 -273.522369)
		(end 392.718036 -273.592544)
		(width 0.0889)
		(layer "In4.Cu")
		(net "M_J_CPU0_SB_CB<1>")
	)
	(arc
		(start 385.216146 -273.603466)
		(mid 385.399654 -273.64896)
		(end 385.581906 -273.59864)
		(width 0.0889)
		(layer "In4.Cu")
		(net "M_J_CPU0_SB_CB<1>")
	)
	(arc
		(start 391.796016 -273.603466)
		(mid 391.979778 -273.649082)
		(end 392.162284 -273.59864)
		(width 0.0889)
		(layer "In4.Cu")
		(net "M_J_CPU0_SB_CB<1>")
	)
	(arc
		(start 379.941836 -273.59864)
		(mid 380.224792 -273.522463)
		(end 380.507748 -273.59864)
		(width 0.0889)
		(layer "In4.Cu")
		(net "M_J_CPU0_SB_CB<1>")
	)
	(arc
		(start 389.341868 -273.59864)
		(mid 389.624824 -273.522463)
		(end 389.90778 -273.59864)
		(width 0.0889)
		(layer "In4.Cu")
		(net "M_J_CPU0_SB_CB<1>")
	)
	(arc
		(start 390.847834 -273.59864)
		(mid 391.034778 -273.648895)
		(end 391.221722 -273.59864)
		(width 0.0889)
		(layer "In4.Cu")
		(net "M_J_CPU0_SB_CB<1>")
	)
	(arc
		(start 382.387856 -273.59864)
		(mid 382.5748 -273.648895)
		(end 382.761744 -273.59864)
		(width 0.0889)
		(layer "In4.Cu")
		(net "M_J_CPU0_SB_CB<1>")
	)
	(arc
		(start 388.401814 -273.59864)
		(mid 388.68477 -273.522463)
		(end 388.967726 -273.59864)
		(width 0.0889)
		(layer "In4.Cu")
		(net "M_J_CPU0_SB_CB<1>")
	)
	(arc
		(start 386.52196 -273.59864)
		(mid 386.804916 -273.522463)
		(end 387.087872 -273.59864)
		(width 0.0889)
		(layer "In4.Cu")
		(net "M_J_CPU0_SB_CB<1>")
	)
	(arc
		(start 381.821944 -273.59864)
		(mid 382.1049 -273.522463)
		(end 382.387856 -273.59864)
		(width 0.0889)
		(layer "In4.Cu")
		(net "M_J_CPU0_SB_CB<1>")
	)
	(arc
		(start 380.507748 -273.59864)
		(mid 380.689999 -273.64899)
		(end 380.873508 -273.603466)
		(width 0.0889)
		(layer "In4.Cu")
		(net "M_J_CPU0_SB_CB<1>")
	)
	(arc
		(start 384.26771 -273.59864)
		(mid 384.449961 -273.64899)
		(end 384.63347 -273.603466)
		(width 0.0889)
		(layer "In4.Cu")
		(net "M_J_CPU0_SB_CB<1>")
	)
	(arc
		(start 381.456184 -273.603466)
		(mid 381.639692 -273.64896)
		(end 381.821944 -273.59864)
		(width 0.0889)
		(layer "In4.Cu")
		(net "M_J_CPU0_SB_CB<1>")
	)
	(arc
		(start 388.027672 -273.59864)
		(mid 388.209923 -273.64899)
		(end 388.393432 -273.603466)
		(width 0.0889)
		(layer "In4.Cu")
		(net "M_J_CPU0_SB_CB<1>")
	)
	(arc
		(start 383.701798 -273.59864)
		(mid 383.984754 -273.522463)
		(end 384.26771 -273.59864)
		(width 0.0889)
		(layer "In4.Cu")
		(net "M_J_CPU0_SB_CB<1>")
	)
	(arc
		(start 389.916162 -273.603466)
		(mid 390.09967 -273.64896)
		(end 390.281922 -273.59864)
		(width 0.0889)
		(layer "In4.Cu")
		(net "M_J_CPU0_SB_CB<1>")
	)
	(arc
		(start 387.46176 -273.59864)
		(mid 387.744716 -273.522463)
		(end 388.027672 -273.59864)
		(width 0.0889)
		(layer "In4.Cu")
		(net "M_J_CPU0_SB_CB<1>")
	)
	(arc
		(start 387.087872 -273.59864)
		(mid 387.274816 -273.648895)
		(end 387.46176 -273.59864)
		(width 0.0889)
		(layer "In4.Cu")
		(net "M_J_CPU0_SB_CB<1>")
	)
	(arc
		(start 393.384532 -273.521932)
		(mid 393.569657 -273.491176)
		(end 393.734798 -273.402044)
		(width 0.0889)
		(layer "In4.Cu")
		(net "M_J_CPU0_SB_CB<1>")
	)
	(arc
		(start 390.281922 -273.59864)
		(mid 390.564878 -273.522463)
		(end 390.847834 -273.59864)
		(width 0.0889)
		(layer "In4.Cu")
		(net "M_J_CPU0_SB_CB<1>")
	)
	(arc
		(start 379.623066 -273.624802)
		(mid 379.780576 -273.648)
		(end 379.933454 -273.603466)
		(width 0.0889)
		(layer "In4.Cu")
		(net "M_J_CPU0_SB_CB<1>")
	)
	(arc
		(start 391.221722 -273.59864)
		(mid 391.504678 -273.522463)
		(end 391.787634 -273.59864)
		(width 0.0889)
		(layer "In4.Cu")
		(net "M_J_CPU0_SB_CB<1>")
	)
	(arc
		(start 383.327656 -273.59864)
		(mid 383.509907 -273.64899)
		(end 383.693416 -273.603466)
		(width 0.0889)
		(layer "In4.Cu")
		(net "M_J_CPU0_SB_CB<1>")
	)
	(arc
		(start 380.88189 -273.59864)
		(mid 381.164846 -273.522463)
		(end 381.447802 -273.59864)
		(width 0.0889)
		(layer "In4.Cu")
		(net "M_J_CPU0_SB_CB<1>")
	)
	(arc
		(start 388.967726 -273.59864)
		(mid 389.149977 -273.64899)
		(end 389.333486 -273.603466)
		(width 0.0889)
		(layer "In4.Cu")
		(net "M_J_CPU0_SB_CB<1>")
	)
	(arc
		(start 384.641852 -273.59864)
		(mid 384.924808 -273.522463)
		(end 385.207764 -273.59864)
		(width 0.0889)
		(layer "In4.Cu")
		(net "M_J_CPU0_SB_CB<1>")
	)
	(arc
		(start 392.72845 -273.59864)
		(mid 392.9061 -273.6489)
		(end 393.086082 -273.607784)
		(width 0.0889)
		(layer "In4.Cu")
		(net "M_J_CPU0_SB_CB<1>")
	)
	(segment
		(start 380.697994 -272.200116)
		(end 381.164846 -272.466054)
		(width 0.10668)
		(layer "F.Cu")
		(net "M_J_CPU0_SB_CB<0>")
	)
	(segment
		(start 422.567608 -277.669752)
		(end 421.71747 -278.51989)
		(width 0.14478)
		(layer "In4.Cu")
		(net "M_J_CPU0_SB_CB<0>")
	)
	(segment
		(start 392.652758 -272.774918)
		(end 392.62939 -272.788634)
		(width 0.0889)
		(layer "In4.Cu")
		(net "M_J_CPU0_SB_CB<0>")
	)
	(segment
		(start 381.033274 -272.814796)
		(end 381.010922 -272.731484)
		(width 0.0889)
		(layer "In4.Cu")
		(net "M_J_CPU0_SB_CB<0>")
	)
	(segment
		(start 386.051806 -272.788634)
		(end 386.043424 -272.79346)
		(width 0.0889)
		(layer "In4.Cu")
		(net "M_J_CPU0_SB_CB<0>")
	)
	(segment
		(start 383.806192 -272.79346)
		(end 383.79781 -272.788634)
		(width 0.0889)
		(layer "In4.Cu")
		(net "M_J_CPU0_SB_CB<0>")
	)
	(segment
		(start 388.506208 -272.79346)
		(end 388.497826 -272.788634)
		(width 0.0889)
		(layer "In4.Cu")
		(net "M_J_CPU0_SB_CB<0>")
	)
	(segment
		(start 426.240448 -278.519636)
		(end 425.390564 -277.669752)
		(width 0.14478)
		(layer "In4.Cu")
		(net "M_J_CPU0_SB_CB<0>")
	)
	(segment
		(start 392.274552 -272.798794)
		(end 392.256264 -272.78838)
		(width 0.0889)
		(layer "In4.Cu")
		(net "M_J_CPU0_SB_CB<0>")
	)
	(segment
		(start 386.99186 -272.788634)
		(end 386.983478 -272.79346)
		(width 0.0889)
		(layer "In4.Cu")
		(net "M_J_CPU0_SB_CB<0>")
	)
	(segment
		(start 439.100214 -278.085042)
		(end 438.684924 -277.669752)
		(width 0.14478)
		(layer "In4.Cu")
		(net "M_J_CPU0_SB_CB<0>")
	)
	(segment
		(start 430.048416 -277.669752)
		(end 429.198532 -278.519636)
		(width 0.14478)
		(layer "In4.Cu")
		(net "M_J_CPU0_SB_CB<0>")
	)
	(segment
		(start 425.390564 -277.669752)
		(end 422.567608 -277.669752)
		(width 0.14478)
		(layer "In4.Cu")
		(net "M_J_CPU0_SB_CB<0>")
	)
	(segment
		(start 410.347414 -276.846792)
		(end 404.519892 -271.01927)
		(width 0.14478)
		(layer "In4.Cu")
		(net "M_J_CPU0_SB_CB<0>")
	)
	(segment
		(start 381.010922 -272.731484)
		(end 381.164846 -272.466054)
		(width 0.0889)
		(layer "In4.Cu")
		(net "M_J_CPU0_SB_CB<0>")
	)
	(segment
		(start 392.256264 -272.78838)
		(end 392.234674 -272.775934)
		(width 0.0889)
		(layer "In4.Cu")
		(net "M_J_CPU0_SB_CB<0>")
	)
	(segment
		(start 387.566154 -272.79346)
		(end 387.557772 -272.788634)
		(width 0.0889)
		(layer "In4.Cu")
		(net "M_J_CPU0_SB_CB<0>")
	)
	(segment
		(start 390.751822 -272.788634)
		(end 390.74344 -272.79346)
		(width 0.0889)
		(layer "In4.Cu")
		(net "M_J_CPU0_SB_CB<0>")
	)
	(segment
		(start 394.584174 -271.24533)
		(end 394.584174 -271.789144)
		(width 0.0889)
		(layer "In4.Cu")
		(net "M_J_CPU0_SB_CB<0>")
	)
	(segment
		(start 414.183068 -278.510238)
		(end 412.952692 -278.510238)
		(width 0.14478)
		(layer "In4.Cu")
		(net "M_J_CPU0_SB_CB<0>")
	)
	(segment
		(start 438.684924 -277.669752)
		(end 430.048416 -277.669752)
		(width 0.14478)
		(layer "In4.Cu")
		(net "M_J_CPU0_SB_CB<0>")
	)
	(segment
		(start 429.198532 -278.519636)
		(end 426.240448 -278.519636)
		(width 0.14478)
		(layer "In4.Cu")
		(net "M_J_CPU0_SB_CB<0>")
	)
	(segment
		(start 395.642084 -270.867124)
		(end 394.96238 -270.867124)
		(width 0.0889)
		(layer "In4.Cu")
		(net "M_J_CPU0_SB_CB<0>")
	)
	(segment
		(start 394.584174 -271.789144)
		(end 393.648184 -272.725134)
		(width 0.0889)
		(layer "In4.Cu")
		(net "M_J_CPU0_SB_CB<0>")
	)
	(segment
		(start 418.550344 -278.51989)
		(end 417.690808 -277.660354)
		(width 0.14478)
		(layer "In4.Cu")
		(net "M_J_CPU0_SB_CB<0>")
	)
	(segment
		(start 393.570714 -272.78838)
		(end 393.543282 -272.804128)
		(width 0.0889)
		(layer "In4.Cu")
		(net "M_J_CPU0_SB_CB<0>")
	)
	(segment
		(start 382.291844 -272.788634)
		(end 382.283462 -272.79346)
		(width 0.0889)
		(layer "In4.Cu")
		(net "M_J_CPU0_SB_CB<0>")
	)
	(segment
		(start 394.96238 -270.867124)
		(end 394.584174 -271.24533)
		(width 0.0889)
		(layer "In4.Cu")
		(net "M_J_CPU0_SB_CB<0>")
	)
	(segment
		(start 391.326116 -272.79346)
		(end 391.317734 -272.788634)
		(width 0.0889)
		(layer "In4.Cu")
		(net "M_J_CPU0_SB_CB<0>")
	)
	(segment
		(start 421.71747 -278.51989)
		(end 418.550344 -278.51989)
		(width 0.14478)
		(layer "In4.Cu")
		(net "M_J_CPU0_SB_CB<0>")
	)
	(segment
		(start 412.952692 -278.510238)
		(end 411.289246 -276.846792)
		(width 0.14478)
		(layer "In4.Cu")
		(net "M_J_CPU0_SB_CB<0>")
	)
	(segment
		(start 395.79423 -271.01927)
		(end 395.642084 -270.867124)
		(width 0.14478)
		(layer "In4.Cu")
		(net "M_J_CPU0_SB_CB<0>")
	)
	(segment
		(start 415.032952 -277.660354)
		(end 414.183068 -278.510238)
		(width 0.14478)
		(layer "In4.Cu")
		(net "M_J_CPU0_SB_CB<0>")
	)
	(segment
		(start 417.690808 -277.660354)
		(end 415.032952 -277.660354)
		(width 0.14478)
		(layer "In4.Cu")
		(net "M_J_CPU0_SB_CB<0>")
	)
	(segment
		(start 382.866138 -272.79346)
		(end 382.857756 -272.788634)
		(width 0.0889)
		(layer "In4.Cu")
		(net "M_J_CPU0_SB_CB<0>")
	)
	(segment
		(start 404.519892 -271.01927)
		(end 395.79423 -271.01927)
		(width 0.14478)
		(layer "In4.Cu")
		(net "M_J_CPU0_SB_CB<0>")
	)
	(segment
		(start 411.289246 -276.846792)
		(end 410.347414 -276.846792)
		(width 0.14478)
		(layer "In4.Cu")
		(net "M_J_CPU0_SB_CB<0>")
	)
	(arc
		(start 388.497826 -272.788634)
		(mid 388.21487 -272.712457)
		(end 387.931914 -272.788634)
		(width 0.0889)
		(layer "In4.Cu")
		(net "M_J_CPU0_SB_CB<0>")
	)
	(arc
		(start 387.931914 -272.788634)
		(mid 387.749663 -272.838984)
		(end 387.566154 -272.79346)
		(width 0.0889)
		(layer "In4.Cu")
		(net "M_J_CPU0_SB_CB<0>")
	)
	(arc
		(start 383.79781 -272.788634)
		(mid 383.514854 -272.712457)
		(end 383.231898 -272.788634)
		(width 0.0889)
		(layer "In4.Cu")
		(net "M_J_CPU0_SB_CB<0>")
	)
	(arc
		(start 382.283462 -272.79346)
		(mid 382.099954 -272.838954)
		(end 381.917702 -272.788634)
		(width 0.0889)
		(layer "In4.Cu")
		(net "M_J_CPU0_SB_CB<0>")
	)
	(arc
		(start 384.737864 -272.788634)
		(mid 384.454908 -272.712457)
		(end 384.171952 -272.788634)
		(width 0.0889)
		(layer "In4.Cu")
		(net "M_J_CPU0_SB_CB<0>")
	)
	(arc
		(start 391.691876 -272.788634)
		(mid 391.509625 -272.838984)
		(end 391.326116 -272.79346)
		(width 0.0889)
		(layer "In4.Cu")
		(net "M_J_CPU0_SB_CB<0>")
	)
	(arc
		(start 390.74344 -272.79346)
		(mid 390.559932 -272.838954)
		(end 390.37768 -272.788634)
		(width 0.0889)
		(layer "In4.Cu")
		(net "M_J_CPU0_SB_CB<0>")
	)
	(arc
		(start 382.857756 -272.788634)
		(mid 382.5748 -272.712457)
		(end 382.291844 -272.788634)
		(width 0.0889)
		(layer "In4.Cu")
		(net "M_J_CPU0_SB_CB<0>")
	)
	(arc
		(start 386.617718 -272.788634)
		(mid 386.334762 -272.712457)
		(end 386.051806 -272.788634)
		(width 0.0889)
		(layer "In4.Cu")
		(net "M_J_CPU0_SB_CB<0>")
	)
	(arc
		(start 391.317734 -272.788634)
		(mid 391.034778 -272.712457)
		(end 390.751822 -272.788634)
		(width 0.0889)
		(layer "In4.Cu")
		(net "M_J_CPU0_SB_CB<0>")
	)
	(arc
		(start 389.811768 -272.788634)
		(mid 389.624824 -272.838889)
		(end 389.43788 -272.788634)
		(width 0.0889)
		(layer "In4.Cu")
		(net "M_J_CPU0_SB_CB<0>")
	)
	(arc
		(start 387.557772 -272.788634)
		(mid 387.274816 -272.712457)
		(end 386.99186 -272.788634)
		(width 0.0889)
		(layer "In4.Cu")
		(net "M_J_CPU0_SB_CB<0>")
	)
	(arc
		(start 389.43788 -272.788634)
		(mid 389.154924 -272.712457)
		(end 388.871968 -272.788634)
		(width 0.0889)
		(layer "In4.Cu")
		(net "M_J_CPU0_SB_CB<0>")
	)
	(arc
		(start 393.543282 -272.804128)
		(mid 393.368031 -272.839061)
		(end 393.196572 -272.788634)
		(width 0.0889)
		(layer "In4.Cu")
		(net "M_J_CPU0_SB_CB<0>")
	)
	(arc
		(start 393.648184 -272.725134)
		(mid 393.611043 -272.75871)
		(end 393.570714 -272.78838)
		(width 0.0889)
		(layer "In4.Cu")
		(net "M_J_CPU0_SB_CB<0>")
	)
	(arc
		(start 390.37768 -272.788634)
		(mid 390.094724 -272.712457)
		(end 389.811768 -272.788634)
		(width 0.0889)
		(layer "In4.Cu")
		(net "M_J_CPU0_SB_CB<0>")
	)
	(arc
		(start 386.983478 -272.79346)
		(mid 386.79997 -272.838954)
		(end 386.617718 -272.788634)
		(width 0.0889)
		(layer "In4.Cu")
		(net "M_J_CPU0_SB_CB<0>")
	)
	(arc
		(start 393.196572 -272.788634)
		(mid 392.926415 -272.711872)
		(end 392.652758 -272.774918)
		(width 0.0889)
		(layer "In4.Cu")
		(net "M_J_CPU0_SB_CB<0>")
	)
	(arc
		(start 381.35179 -272.788634)
		(mid 381.195471 -272.837629)
		(end 381.033274 -272.814796)
		(width 0.0889)
		(layer "In4.Cu")
		(net "M_J_CPU0_SB_CB<0>")
	)
	(arc
		(start 392.234674 -272.775934)
		(mid 391.961645 -272.712615)
		(end 391.691876 -272.788634)
		(width 0.0889)
		(layer "In4.Cu")
		(net "M_J_CPU0_SB_CB<0>")
	)
	(arc
		(start 385.111752 -272.788634)
		(mid 384.924808 -272.838889)
		(end 384.737864 -272.788634)
		(width 0.0889)
		(layer "In4.Cu")
		(net "M_J_CPU0_SB_CB<0>")
	)
	(arc
		(start 381.917702 -272.788634)
		(mid 381.634746 -272.712457)
		(end 381.35179 -272.788634)
		(width 0.0889)
		(layer "In4.Cu")
		(net "M_J_CPU0_SB_CB<0>")
	)
	(arc
		(start 383.231898 -272.788634)
		(mid 383.049647 -272.838984)
		(end 382.866138 -272.79346)
		(width 0.0889)
		(layer "In4.Cu")
		(net "M_J_CPU0_SB_CB<0>")
	)
	(arc
		(start 386.043424 -272.79346)
		(mid 385.859916 -272.838954)
		(end 385.677664 -272.788634)
		(width 0.0889)
		(layer "In4.Cu")
		(net "M_J_CPU0_SB_CB<0>")
	)
	(arc
		(start 385.677664 -272.788634)
		(mid 385.394708 -272.712457)
		(end 385.111752 -272.788634)
		(width 0.0889)
		(layer "In4.Cu")
		(net "M_J_CPU0_SB_CB<0>")
	)
	(arc
		(start 384.171952 -272.788634)
		(mid 383.989701 -272.838984)
		(end 383.806192 -272.79346)
		(width 0.0889)
		(layer "In4.Cu")
		(net "M_J_CPU0_SB_CB<0>")
	)
	(arc
		(start 392.62939 -272.788634)
		(mid 392.45327 -272.838612)
		(end 392.274552 -272.798794)
		(width 0.0889)
		(layer "In4.Cu")
		(net "M_J_CPU0_SB_CB<0>")
	)
	(arc
		(start 388.871968 -272.788634)
		(mid 388.689717 -272.838984)
		(end 388.506208 -272.79346)
		(width 0.0889)
		(layer "In4.Cu")
		(net "M_J_CPU0_SB_CB<0>")
	)
	(segment
		(start 380.697994 -264.100056)
		(end 381.164846 -264.365994)
		(width 0.10668)
		(layer "F.Cu")
		(net "M_J_CPU0_SB_CA<6>")
	)
	(segment
		(start 394.05433 -264.280396)
		(end 394.117322 -264.26795)
		(width 0.0889)
		(layer "In4.Cu")
		(net "M_J_CPU0_SB_CA<6>")
	)
	(segment
		(start 412.20517 -266.610084)
		(end 414.183068 -266.610084)
		(width 0.14478)
		(layer "In4.Cu")
		(net "M_J_CPU0_SB_CA<6>")
	)
	(segment
		(start 392.234674 -264.675874)
		(end 392.256264 -264.68832)
		(width 0.0889)
		(layer "In4.Cu")
		(net "M_J_CPU0_SB_CA<6>")
	)
	(segment
		(start 414.183068 -266.610084)
		(end 415.032952 -265.7602)
		(width 0.14478)
		(layer "In4.Cu")
		(net "M_J_CPU0_SB_CA<6>")
	)
	(segment
		(start 392.256264 -264.68832)
		(end 392.274552 -264.698734)
		(width 0.0889)
		(layer "In4.Cu")
		(net "M_J_CPU0_SB_CA<6>")
	)
	(segment
		(start 386.043424 -264.6934)
		(end 386.051806 -264.688574)
		(width 0.0889)
		(layer "In4.Cu")
		(net "M_J_CPU0_SB_CA<6>")
	)
	(segment
		(start 438.675272 -265.7602)
		(end 439.100214 -266.185142)
		(width 0.14478)
		(layer "In4.Cu")
		(net "M_J_CPU0_SB_CA<6>")
	)
	(segment
		(start 394.117322 -264.26795)
		(end 395.71422 -264.26795)
		(width 0.0889)
		(layer "In4.Cu")
		(net "M_J_CPU0_SB_CA<6>")
	)
	(segment
		(start 392.62939 -264.688574)
		(end 392.652758 -264.674858)
		(width 0.0889)
		(layer "In4.Cu")
		(net "M_J_CPU0_SB_CA<6>")
	)
	(segment
		(start 382.857756 -264.688574)
		(end 382.866138 -264.6934)
		(width 0.0889)
		(layer "In4.Cu")
		(net "M_J_CPU0_SB_CA<6>")
	)
	(segment
		(start 382.283462 -264.6934)
		(end 382.291844 -264.688574)
		(width 0.0889)
		(layer "In4.Cu")
		(net "M_J_CPU0_SB_CA<6>")
	)
	(segment
		(start 383.79781 -264.688574)
		(end 383.806192 -264.6934)
		(width 0.0889)
		(layer "In4.Cu")
		(net "M_J_CPU0_SB_CA<6>")
	)
	(segment
		(start 393.958572 -264.32002)
		(end 394.05433 -264.280396)
		(width 0.0889)
		(layer "In4.Cu")
		(net "M_J_CPU0_SB_CA<6>")
	)
	(segment
		(start 387.557772 -264.688574)
		(end 387.566154 -264.6934)
		(width 0.0889)
		(layer "In4.Cu")
		(net "M_J_CPU0_SB_CA<6>")
	)
	(segment
		(start 390.74344 -264.6934)
		(end 390.751822 -264.688574)
		(width 0.0889)
		(layer "In4.Cu")
		(net "M_J_CPU0_SB_CA<6>")
	)
	(segment
		(start 418.907468 -266.610084)
		(end 421.727122 -266.610084)
		(width 0.14478)
		(layer "In4.Cu")
		(net "M_J_CPU0_SB_CA<6>")
	)
	(segment
		(start 386.983478 -264.6934)
		(end 386.99186 -264.688574)
		(width 0.0889)
		(layer "In4.Cu")
		(net "M_J_CPU0_SB_CA<6>")
	)
	(segment
		(start 409.934156 -264.33907)
		(end 412.20517 -266.610084)
		(width 0.14478)
		(layer "In4.Cu")
		(net "M_J_CPU0_SB_CA<6>")
	)
	(segment
		(start 395.78534 -264.33907)
		(end 409.934156 -264.33907)
		(width 0.14478)
		(layer "In4.Cu")
		(net "M_J_CPU0_SB_CA<6>")
	)
	(segment
		(start 393.543282 -264.704068)
		(end 393.570714 -264.68832)
		(width 0.0889)
		(layer "In4.Cu")
		(net "M_J_CPU0_SB_CA<6>")
	)
	(segment
		(start 393.89939 -264.359644)
		(end 393.958572 -264.32002)
		(width 0.0889)
		(layer "In4.Cu")
		(net "M_J_CPU0_SB_CA<6>")
	)
	(segment
		(start 421.727122 -266.610084)
		(end 422.577006 -265.7602)
		(width 0.14478)
		(layer "In4.Cu")
		(net "M_J_CPU0_SB_CA<6>")
	)
	(segment
		(start 393.570714 -264.68832)
		(end 393.89939 -264.359644)
		(width 0.0889)
		(layer "In4.Cu")
		(net "M_J_CPU0_SB_CA<6>")
	)
	(segment
		(start 391.317734 -264.688574)
		(end 391.326116 -264.6934)
		(width 0.0889)
		(layer "In4.Cu")
		(net "M_J_CPU0_SB_CA<6>")
	)
	(segment
		(start 395.71422 -264.26795)
		(end 395.78534 -264.33907)
		(width 0.0889)
		(layer "In4.Cu")
		(net "M_J_CPU0_SB_CA<6>")
	)
	(segment
		(start 381.010922 -264.631424)
		(end 381.033274 -264.714736)
		(width 0.0889)
		(layer "In4.Cu")
		(net "M_J_CPU0_SB_CA<6>")
	)
	(segment
		(start 381.164846 -264.365994)
		(end 381.010922 -264.631424)
		(width 0.0889)
		(layer "In4.Cu")
		(net "M_J_CPU0_SB_CA<6>")
	)
	(segment
		(start 415.032952 -265.7602)
		(end 418.057584 -265.7602)
		(width 0.14478)
		(layer "In4.Cu")
		(net "M_J_CPU0_SB_CA<6>")
	)
	(segment
		(start 388.497826 -264.688574)
		(end 388.506208 -264.6934)
		(width 0.0889)
		(layer "In4.Cu")
		(net "M_J_CPU0_SB_CA<6>")
	)
	(segment
		(start 422.577006 -265.7602)
		(end 438.675272 -265.7602)
		(width 0.14478)
		(layer "In4.Cu")
		(net "M_J_CPU0_SB_CA<6>")
	)
	(segment
		(start 418.057584 -265.7602)
		(end 418.907468 -266.610084)
		(width 0.14478)
		(layer "In4.Cu")
		(net "M_J_CPU0_SB_CA<6>")
	)
	(arc
		(start 389.43788 -264.688574)
		(mid 389.624824 -264.738829)
		(end 389.811768 -264.688574)
		(width 0.0889)
		(layer "In4.Cu")
		(net "M_J_CPU0_SB_CA<6>")
	)
	(arc
		(start 384.171952 -264.688574)
		(mid 384.454908 -264.612397)
		(end 384.737864 -264.688574)
		(width 0.0889)
		(layer "In4.Cu")
		(net "M_J_CPU0_SB_CA<6>")
	)
	(arc
		(start 385.111752 -264.688574)
		(mid 385.394708 -264.612397)
		(end 385.677664 -264.688574)
		(width 0.0889)
		(layer "In4.Cu")
		(net "M_J_CPU0_SB_CA<6>")
	)
	(arc
		(start 381.35179 -264.688574)
		(mid 381.634746 -264.612397)
		(end 381.917702 -264.688574)
		(width 0.0889)
		(layer "In4.Cu")
		(net "M_J_CPU0_SB_CA<6>")
	)
	(arc
		(start 391.691876 -264.688574)
		(mid 391.961645 -264.612551)
		(end 392.234674 -264.675874)
		(width 0.0889)
		(layer "In4.Cu")
		(net "M_J_CPU0_SB_CA<6>")
	)
	(arc
		(start 383.231898 -264.688574)
		(mid 383.514854 -264.612397)
		(end 383.79781 -264.688574)
		(width 0.0889)
		(layer "In4.Cu")
		(net "M_J_CPU0_SB_CA<6>")
	)
	(arc
		(start 381.033274 -264.714736)
		(mid 381.195463 -264.737471)
		(end 381.35179 -264.688574)
		(width 0.0889)
		(layer "In4.Cu")
		(net "M_J_CPU0_SB_CA<6>")
	)
	(arc
		(start 392.274552 -264.698734)
		(mid 392.453273 -264.738657)
		(end 392.62939 -264.688574)
		(width 0.0889)
		(layer "In4.Cu")
		(net "M_J_CPU0_SB_CA<6>")
	)
	(arc
		(start 386.617718 -264.688574)
		(mid 386.799969 -264.738924)
		(end 386.983478 -264.6934)
		(width 0.0889)
		(layer "In4.Cu")
		(net "M_J_CPU0_SB_CA<6>")
	)
	(arc
		(start 388.871968 -264.688574)
		(mid 389.154924 -264.612397)
		(end 389.43788 -264.688574)
		(width 0.0889)
		(layer "In4.Cu")
		(net "M_J_CPU0_SB_CA<6>")
	)
	(arc
		(start 383.806192 -264.6934)
		(mid 383.9897 -264.738894)
		(end 384.171952 -264.688574)
		(width 0.0889)
		(layer "In4.Cu")
		(net "M_J_CPU0_SB_CA<6>")
	)
	(arc
		(start 381.917702 -264.688574)
		(mid 382.099953 -264.738924)
		(end 382.283462 -264.6934)
		(width 0.0889)
		(layer "In4.Cu")
		(net "M_J_CPU0_SB_CA<6>")
	)
	(arc
		(start 393.196572 -264.688574)
		(mid 393.368027 -264.739091)
		(end 393.543282 -264.704068)
		(width 0.0889)
		(layer "In4.Cu")
		(net "M_J_CPU0_SB_CA<6>")
	)
	(arc
		(start 386.051806 -264.688574)
		(mid 386.334762 -264.612397)
		(end 386.617718 -264.688574)
		(width 0.0889)
		(layer "In4.Cu")
		(net "M_J_CPU0_SB_CA<6>")
	)
	(arc
		(start 392.652758 -264.674858)
		(mid 392.926412 -264.611915)
		(end 393.196572 -264.688574)
		(width 0.0889)
		(layer "In4.Cu")
		(net "M_J_CPU0_SB_CA<6>")
	)
	(arc
		(start 384.737864 -264.688574)
		(mid 384.924808 -264.738829)
		(end 385.111752 -264.688574)
		(width 0.0889)
		(layer "In4.Cu")
		(net "M_J_CPU0_SB_CA<6>")
	)
	(arc
		(start 386.99186 -264.688574)
		(mid 387.274816 -264.612397)
		(end 387.557772 -264.688574)
		(width 0.0889)
		(layer "In4.Cu")
		(net "M_J_CPU0_SB_CA<6>")
	)
	(arc
		(start 387.566154 -264.6934)
		(mid 387.749662 -264.738894)
		(end 387.931914 -264.688574)
		(width 0.0889)
		(layer "In4.Cu")
		(net "M_J_CPU0_SB_CA<6>")
	)
	(arc
		(start 382.291844 -264.688574)
		(mid 382.5748 -264.612397)
		(end 382.857756 -264.688574)
		(width 0.0889)
		(layer "In4.Cu")
		(net "M_J_CPU0_SB_CA<6>")
	)
	(arc
		(start 390.751822 -264.688574)
		(mid 391.034778 -264.612397)
		(end 391.317734 -264.688574)
		(width 0.0889)
		(layer "In4.Cu")
		(net "M_J_CPU0_SB_CA<6>")
	)
	(arc
		(start 389.811768 -264.688574)
		(mid 390.094724 -264.612397)
		(end 390.37768 -264.688574)
		(width 0.0889)
		(layer "In4.Cu")
		(net "M_J_CPU0_SB_CA<6>")
	)
	(arc
		(start 385.677664 -264.688574)
		(mid 385.859915 -264.738924)
		(end 386.043424 -264.6934)
		(width 0.0889)
		(layer "In4.Cu")
		(net "M_J_CPU0_SB_CA<6>")
	)
	(arc
		(start 391.326116 -264.6934)
		(mid 391.509624 -264.738894)
		(end 391.691876 -264.688574)
		(width 0.0889)
		(layer "In4.Cu")
		(net "M_J_CPU0_SB_CA<6>")
	)
	(arc
		(start 387.931914 -264.688574)
		(mid 388.21487 -264.612397)
		(end 388.497826 -264.688574)
		(width 0.0889)
		(layer "In4.Cu")
		(net "M_J_CPU0_SB_CA<6>")
	)
	(arc
		(start 390.37768 -264.688574)
		(mid 390.559931 -264.738924)
		(end 390.74344 -264.6934)
		(width 0.0889)
		(layer "In4.Cu")
		(net "M_J_CPU0_SB_CA<6>")
	)
	(arc
		(start 382.866138 -264.6934)
		(mid 383.049646 -264.738894)
		(end 383.231898 -264.688574)
		(width 0.0889)
		(layer "In4.Cu")
		(net "M_J_CPU0_SB_CA<6>")
	)
	(arc
		(start 388.506208 -264.6934)
		(mid 388.689716 -264.738894)
		(end 388.871968 -264.688574)
		(width 0.0889)
		(layer "In4.Cu")
		(net "M_J_CPU0_SB_CA<6>")
	)
	(segment
		(start 378.817886 -264.100056)
		(end 379.284738 -264.365994)
		(width 0.10668)
		(layer "F.Cu")
		(net "M_J_CPU0_SB_CA<5>")
	)
	(segment
		(start 388.497826 -264.043414)
		(end 388.506208 -264.038588)
		(width 0.0889)
		(layer "In4.Cu")
		(net "M_J_CPU0_SB_CA<5>")
	)
	(segment
		(start 387.557772 -264.043414)
		(end 387.566154 -264.038588)
		(width 0.0889)
		(layer "In4.Cu")
		(net "M_J_CPU0_SB_CA<5>")
	)
	(segment
		(start 422.484296 -264.910062)
		(end 428.159926 -264.910062)
		(width 0.14478)
		(layer "In4.Cu")
		(net "M_J_CPU0_SB_CA<5>")
	)
	(segment
		(start 395.913864 -263.88441)
		(end 410.543502 -263.88441)
		(width 0.14478)
		(layer "In4.Cu")
		(net "M_J_CPU0_SB_CA<5>")
	)
	(segment
		(start 382.857756 -264.043414)
		(end 382.866138 -264.038588)
		(width 0.0889)
		(layer "In4.Cu")
		(net "M_J_CPU0_SB_CA<5>")
	)
	(segment
		(start 392.62431 -264.038588)
		(end 392.632692 -264.043414)
		(width 0.0889)
		(layer "In4.Cu")
		(net "M_J_CPU0_SB_CA<5>")
	)
	(segment
		(start 434.575204 -264.910062)
		(end 435.000146 -265.335004)
		(width 0.14478)
		(layer "In4.Cu")
		(net "M_J_CPU0_SB_CA<5>")
	)
	(segment
		(start 391.317734 -264.043414)
		(end 391.326116 -264.038588)
		(width 0.0889)
		(layer "In4.Cu")
		(net "M_J_CPU0_SB_CA<5>")
	)
	(segment
		(start 430.942496 -265.21791)
		(end 431.250344 -264.910062)
		(width 0.14478)
		(layer "In4.Cu")
		(net "M_J_CPU0_SB_CA<5>")
	)
	(segment
		(start 390.74344 -264.038588)
		(end 390.751822 -264.043414)
		(width 0.0889)
		(layer "In4.Cu")
		(net "M_J_CPU0_SB_CA<5>")
	)
	(segment
		(start 414.940242 -264.910062)
		(end 418.122608 -264.910062)
		(width 0.14478)
		(layer "In4.Cu")
		(net "M_J_CPU0_SB_CA<5>")
	)
	(segment
		(start 395.209268 -263.992614)
		(end 395.317472 -263.88441)
		(width 0.0889)
		(layer "In4.Cu")
		(net "M_J_CPU0_SB_CA<5>")
	)
	(segment
		(start 430.385982 -264.910062)
		(end 430.69383 -265.21791)
		(width 0.14478)
		(layer "In4.Cu")
		(net "M_J_CPU0_SB_CA<5>")
	)
	(segment
		(start 428.71644 -265.21791)
		(end 429.024288 -264.910062)
		(width 0.14478)
		(layer "In4.Cu")
		(net "M_J_CPU0_SB_CA<5>")
	)
	(segment
		(start 418.122608 -264.910062)
		(end 418.972746 -265.7602)
		(width 0.14478)
		(layer "In4.Cu")
		(net "M_J_CPU0_SB_CA<5>")
	)
	(segment
		(start 429.829468 -265.21791)
		(end 430.137316 -264.910062)
		(width 0.14478)
		(layer "In4.Cu")
		(net "M_J_CPU0_SB_CA<5>")
	)
	(segment
		(start 410.543502 -263.88441)
		(end 412.419292 -265.7602)
		(width 0.14478)
		(layer "In4.Cu")
		(net "M_J_CPU0_SB_CA<5>")
	)
	(segment
		(start 386.983478 -264.038588)
		(end 386.99186 -264.043414)
		(width 0.0889)
		(layer "In4.Cu")
		(net "M_J_CPU0_SB_CA<5>")
	)
	(segment
		(start 431.250344 -264.910062)
		(end 434.575204 -264.910062)
		(width 0.14478)
		(layer "In4.Cu")
		(net "M_J_CPU0_SB_CA<5>")
	)
	(segment
		(start 382.283462 -264.038588)
		(end 382.291844 -264.043414)
		(width 0.0889)
		(layer "In4.Cu")
		(net "M_J_CPU0_SB_CA<5>")
	)
	(segment
		(start 412.419292 -265.7602)
		(end 414.090104 -265.7602)
		(width 0.14478)
		(layer "In4.Cu")
		(net "M_J_CPU0_SB_CA<5>")
	)
	(segment
		(start 379.438916 -264.100564)
		(end 379.535182 -264.075164)
		(width 0.0889)
		(layer "In4.Cu")
		(net "M_J_CPU0_SB_CA<5>")
	)
	(segment
		(start 430.137316 -264.910062)
		(end 430.385982 -264.910062)
		(width 0.14478)
		(layer "In4.Cu")
		(net "M_J_CPU0_SB_CA<5>")
	)
	(segment
		(start 386.043424 -264.038588)
		(end 386.051806 -264.043414)
		(width 0.0889)
		(layer "In4.Cu")
		(net "M_J_CPU0_SB_CA<5>")
	)
	(segment
		(start 393.384786 -263.992614)
		(end 395.209268 -263.992614)
		(width 0.0889)
		(layer "In4.Cu")
		(net "M_J_CPU0_SB_CA<5>")
	)
	(segment
		(start 429.272954 -264.910062)
		(end 429.580802 -265.21791)
		(width 0.14478)
		(layer "In4.Cu")
		(net "M_J_CPU0_SB_CA<5>")
	)
	(segment
		(start 428.159926 -264.910062)
		(end 428.467774 -265.21791)
		(width 0.14478)
		(layer "In4.Cu")
		(net "M_J_CPU0_SB_CA<5>")
	)
	(segment
		(start 418.972746 -265.7602)
		(end 421.634158 -265.7602)
		(width 0.14478)
		(layer "In4.Cu")
		(net "M_J_CPU0_SB_CA<5>")
	)
	(segment
		(start 395.317472 -263.88441)
		(end 395.913864 -263.88441)
		(width 0.0889)
		(layer "In4.Cu")
		(net "M_J_CPU0_SB_CA<5>")
	)
	(segment
		(start 380.037848 -264.043414)
		(end 380.04623 -264.038588)
		(width 0.0889)
		(layer "In4.Cu")
		(net "M_J_CPU0_SB_CA<5>")
	)
	(segment
		(start 379.284738 -264.365994)
		(end 379.438916 -264.100564)
		(width 0.0889)
		(layer "In4.Cu")
		(net "M_J_CPU0_SB_CA<5>")
	)
	(segment
		(start 421.634158 -265.7602)
		(end 422.484296 -264.910062)
		(width 0.14478)
		(layer "In4.Cu")
		(net "M_J_CPU0_SB_CA<5>")
	)
	(segment
		(start 428.467774 -265.21791)
		(end 428.71644 -265.21791)
		(width 0.14478)
		(layer "In4.Cu")
		(net "M_J_CPU0_SB_CA<5>")
	)
	(segment
		(start 430.69383 -265.21791)
		(end 430.942496 -265.21791)
		(width 0.14478)
		(layer "In4.Cu")
		(net "M_J_CPU0_SB_CA<5>")
	)
	(segment
		(start 429.024288 -264.910062)
		(end 429.272954 -264.910062)
		(width 0.14478)
		(layer "In4.Cu")
		(net "M_J_CPU0_SB_CA<5>")
	)
	(segment
		(start 383.79781 -264.043414)
		(end 383.806192 -264.038588)
		(width 0.0889)
		(layer "In4.Cu")
		(net "M_J_CPU0_SB_CA<5>")
	)
	(segment
		(start 391.691876 -264.043414)
		(end 391.70229 -264.04951)
		(width 0.0889)
		(layer "In4.Cu")
		(net "M_J_CPU0_SB_CA<5>")
	)
	(segment
		(start 429.580802 -265.21791)
		(end 429.829468 -265.21791)
		(width 0.14478)
		(layer "In4.Cu")
		(net "M_J_CPU0_SB_CA<5>")
	)
	(segment
		(start 414.090104 -265.7602)
		(end 414.940242 -264.910062)
		(width 0.14478)
		(layer "In4.Cu")
		(net "M_J_CPU0_SB_CA<5>")
	)
	(arc
		(start 387.931914 -264.043414)
		(mid 388.21487 -264.119591)
		(end 388.497826 -264.043414)
		(width 0.0889)
		(layer "In4.Cu")
		(net "M_J_CPU0_SB_CA<5>")
	)
	(arc
		(start 392.258042 -264.043414)
		(mid 392.440547 -263.992937)
		(end 392.62431 -264.038588)
		(width 0.0889)
		(layer "In4.Cu")
		(net "M_J_CPU0_SB_CA<5>")
	)
	(arc
		(start 384.171952 -264.043414)
		(mid 384.454908 -264.119591)
		(end 384.737864 -264.043414)
		(width 0.0889)
		(layer "In4.Cu")
		(net "M_J_CPU0_SB_CA<5>")
	)
	(arc
		(start 391.326116 -264.038588)
		(mid 391.509624 -263.993094)
		(end 391.691876 -264.043414)
		(width 0.0889)
		(layer "In4.Cu")
		(net "M_J_CPU0_SB_CA<5>")
	)
	(arc
		(start 384.737864 -264.043414)
		(mid 384.924808 -263.993159)
		(end 385.111752 -264.043414)
		(width 0.0889)
		(layer "In4.Cu")
		(net "M_J_CPU0_SB_CA<5>")
	)
	(arc
		(start 380.04623 -264.038588)
		(mid 380.229738 -263.993094)
		(end 380.41199 -264.043414)
		(width 0.0889)
		(layer "In4.Cu")
		(net "M_J_CPU0_SB_CA<5>")
	)
	(arc
		(start 388.506208 -264.038588)
		(mid 388.689716 -263.993094)
		(end 388.871968 -264.043414)
		(width 0.0889)
		(layer "In4.Cu")
		(net "M_J_CPU0_SB_CA<5>")
	)
	(arc
		(start 386.99186 -264.043414)
		(mid 387.274816 -264.119591)
		(end 387.557772 -264.043414)
		(width 0.0889)
		(layer "In4.Cu")
		(net "M_J_CPU0_SB_CA<5>")
	)
	(arc
		(start 380.977902 -264.043414)
		(mid 381.164846 -263.993159)
		(end 381.35179 -264.043414)
		(width 0.0889)
		(layer "In4.Cu")
		(net "M_J_CPU0_SB_CA<5>")
	)
	(arc
		(start 380.41199 -264.043414)
		(mid 380.694946 -264.119591)
		(end 380.977902 -264.043414)
		(width 0.0889)
		(layer "In4.Cu")
		(net "M_J_CPU0_SB_CA<5>")
	)
	(arc
		(start 390.751822 -264.043414)
		(mid 391.034778 -264.119591)
		(end 391.317734 -264.043414)
		(width 0.0889)
		(layer "In4.Cu")
		(net "M_J_CPU0_SB_CA<5>")
	)
	(arc
		(start 389.43788 -264.043414)
		(mid 389.624824 -263.993159)
		(end 389.811768 -264.043414)
		(width 0.0889)
		(layer "In4.Cu")
		(net "M_J_CPU0_SB_CA<5>")
	)
	(arc
		(start 390.37768 -264.043414)
		(mid 390.559931 -263.993064)
		(end 390.74344 -264.038588)
		(width 0.0889)
		(layer "In4.Cu")
		(net "M_J_CPU0_SB_CA<5>")
	)
	(arc
		(start 385.111752 -264.043414)
		(mid 385.394708 -264.119591)
		(end 385.677664 -264.043414)
		(width 0.0889)
		(layer "In4.Cu")
		(net "M_J_CPU0_SB_CA<5>")
	)
	(arc
		(start 386.051806 -264.043414)
		(mid 386.334762 -264.119591)
		(end 386.617718 -264.043414)
		(width 0.0889)
		(layer "In4.Cu")
		(net "M_J_CPU0_SB_CA<5>")
	)
	(arc
		(start 391.70229 -264.04951)
		(mid 391.980976 -264.11973)
		(end 392.258042 -264.043414)
		(width 0.0889)
		(layer "In4.Cu")
		(net "M_J_CPU0_SB_CA<5>")
	)
	(arc
		(start 393.192508 -264.04697)
		(mid 393.28494 -264.006688)
		(end 393.384786 -263.992614)
		(width 0.0889)
		(layer "In4.Cu")
		(net "M_J_CPU0_SB_CA<5>")
	)
	(arc
		(start 383.806192 -264.038588)
		(mid 383.9897 -263.993094)
		(end 384.171952 -264.043414)
		(width 0.0889)
		(layer "In4.Cu")
		(net "M_J_CPU0_SB_CA<5>")
	)
	(arc
		(start 381.917702 -264.043414)
		(mid 382.099953 -263.993064)
		(end 382.283462 -264.038588)
		(width 0.0889)
		(layer "In4.Cu")
		(net "M_J_CPU0_SB_CA<5>")
	)
	(arc
		(start 383.231898 -264.043414)
		(mid 383.514854 -264.119591)
		(end 383.79781 -264.043414)
		(width 0.0889)
		(layer "In4.Cu")
		(net "M_J_CPU0_SB_CA<5>")
	)
	(arc
		(start 386.617718 -264.043414)
		(mid 386.799969 -263.993064)
		(end 386.983478 -264.038588)
		(width 0.0889)
		(layer "In4.Cu")
		(net "M_J_CPU0_SB_CA<5>")
	)
	(arc
		(start 392.632692 -264.043414)
		(mid 392.91212 -264.11958)
		(end 393.192508 -264.04697)
		(width 0.0889)
		(layer "In4.Cu")
		(net "M_J_CPU0_SB_CA<5>")
	)
	(arc
		(start 381.35179 -264.043414)
		(mid 381.634746 -264.119591)
		(end 381.917702 -264.043414)
		(width 0.0889)
		(layer "In4.Cu")
		(net "M_J_CPU0_SB_CA<5>")
	)
	(arc
		(start 387.566154 -264.038588)
		(mid 387.749662 -263.993094)
		(end 387.931914 -264.043414)
		(width 0.0889)
		(layer "In4.Cu")
		(net "M_J_CPU0_SB_CA<5>")
	)
	(arc
		(start 379.535182 -264.075164)
		(mid 379.790247 -264.118515)
		(end 380.037848 -264.043414)
		(width 0.0889)
		(layer "In4.Cu")
		(net "M_J_CPU0_SB_CA<5>")
	)
	(arc
		(start 382.291844 -264.043414)
		(mid 382.5748 -264.119591)
		(end 382.857756 -264.043414)
		(width 0.0889)
		(layer "In4.Cu")
		(net "M_J_CPU0_SB_CA<5>")
	)
	(arc
		(start 382.866138 -264.038588)
		(mid 383.049646 -263.993094)
		(end 383.231898 -264.043414)
		(width 0.0889)
		(layer "In4.Cu")
		(net "M_J_CPU0_SB_CA<5>")
	)
	(arc
		(start 389.811768 -264.043414)
		(mid 390.094724 -264.119591)
		(end 390.37768 -264.043414)
		(width 0.0889)
		(layer "In4.Cu")
		(net "M_J_CPU0_SB_CA<5>")
	)
	(arc
		(start 388.871968 -264.043414)
		(mid 389.154924 -264.119591)
		(end 389.43788 -264.043414)
		(width 0.0889)
		(layer "In4.Cu")
		(net "M_J_CPU0_SB_CA<5>")
	)
	(arc
		(start 385.677664 -264.043414)
		(mid 385.859915 -263.993064)
		(end 386.043424 -264.038588)
		(width 0.0889)
		(layer "In4.Cu")
		(net "M_J_CPU0_SB_CA<5>")
	)
	(segment
		(start 379.28804 -263.29005)
		(end 379.754892 -263.555988)
		(width 0.10668)
		(layer "F.Cu")
		(net "M_J_CPU0_SB_CA<4>")
	)
	(segment
		(start 414.183068 -264.910062)
		(end 415.032952 -264.060178)
		(width 0.14478)
		(layer "In4.Cu")
		(net "M_J_CPU0_SB_CA<4>")
	)
	(segment
		(start 385.207764 -263.878568)
		(end 385.216146 -263.883394)
		(width 0.0889)
		(layer "In4.Cu")
		(net "M_J_CPU0_SB_CA<4>")
	)
	(segment
		(start 380.873508 -263.883394)
		(end 380.88189 -263.878568)
		(width 0.0889)
		(layer "In4.Cu")
		(net "M_J_CPU0_SB_CA<4>")
	)
	(segment
		(start 388.393432 -263.883394)
		(end 388.401814 -263.878568)
		(width 0.0889)
		(layer "In4.Cu")
		(net "M_J_CPU0_SB_CA<4>")
	)
	(segment
		(start 395.400022 -263.42975)
		(end 395.942312 -263.42975)
		(width 0.0889)
		(layer "In4.Cu")
		(net "M_J_CPU0_SB_CA<4>")
	)
	(segment
		(start 393.384278 -263.802114)
		(end 395.027658 -263.802114)
		(width 0.0889)
		(layer "In4.Cu")
		(net "M_J_CPU0_SB_CA<4>")
	)
	(segment
		(start 395.942312 -263.42975)
		(end 410.724858 -263.42975)
		(width 0.14478)
		(layer "In4.Cu")
		(net "M_J_CPU0_SB_CA<4>")
	)
	(segment
		(start 438.675272 -264.060178)
		(end 439.100214 -264.48512)
		(width 0.14478)
		(layer "In4.Cu")
		(net "M_J_CPU0_SB_CA<4>")
	)
	(segment
		(start 383.693416 -263.883394)
		(end 383.701798 -263.878568)
		(width 0.0889)
		(layer "In4.Cu")
		(net "M_J_CPU0_SB_CA<4>")
	)
	(segment
		(start 422.577006 -264.060178)
		(end 438.675272 -264.060178)
		(width 0.14478)
		(layer "In4.Cu")
		(net "M_J_CPU0_SB_CA<4>")
	)
	(segment
		(start 386.147818 -263.878568)
		(end 386.1562 -263.883394)
		(width 0.0889)
		(layer "In4.Cu")
		(net "M_J_CPU0_SB_CA<4>")
	)
	(segment
		(start 418.057584 -264.060178)
		(end 418.907468 -264.910062)
		(width 0.14478)
		(layer "In4.Cu")
		(net "M_J_CPU0_SB_CA<4>")
	)
	(segment
		(start 392.718036 -263.872472)
		(end 392.72845 -263.878568)
		(width 0.0889)
		(layer "In4.Cu")
		(net "M_J_CPU0_SB_CA<4>")
	)
	(segment
		(start 384.63347 -263.883394)
		(end 384.641852 -263.878568)
		(width 0.0889)
		(layer "In4.Cu")
		(net "M_J_CPU0_SB_CA<4>")
	)
	(segment
		(start 421.727122 -264.910062)
		(end 422.577006 -264.060178)
		(width 0.14478)
		(layer "In4.Cu")
		(net "M_J_CPU0_SB_CA<4>")
	)
	(segment
		(start 391.787634 -263.878568)
		(end 391.796016 -263.883394)
		(width 0.0889)
		(layer "In4.Cu")
		(net "M_J_CPU0_SB_CA<4>")
	)
	(segment
		(start 389.90778 -263.878568)
		(end 389.916162 -263.883394)
		(width 0.0889)
		(layer "In4.Cu")
		(net "M_J_CPU0_SB_CA<4>")
	)
	(segment
		(start 410.724858 -263.42975)
		(end 412.20517 -264.910062)
		(width 0.14478)
		(layer "In4.Cu")
		(net "M_J_CPU0_SB_CA<4>")
	)
	(segment
		(start 379.933454 -263.883394)
		(end 379.941836 -263.878568)
		(width 0.0889)
		(layer "In4.Cu")
		(net "M_J_CPU0_SB_CA<4>")
	)
	(segment
		(start 418.907468 -264.910062)
		(end 421.727122 -264.910062)
		(width 0.14478)
		(layer "In4.Cu")
		(net "M_J_CPU0_SB_CA<4>")
	)
	(segment
		(start 395.027658 -263.802114)
		(end 395.400022 -263.42975)
		(width 0.0889)
		(layer "In4.Cu")
		(net "M_J_CPU0_SB_CA<4>")
	)
	(segment
		(start 389.333486 -263.883394)
		(end 389.341868 -263.878568)
		(width 0.0889)
		(layer "In4.Cu")
		(net "M_J_CPU0_SB_CA<4>")
	)
	(segment
		(start 379.600714 -263.821418)
		(end 379.623066 -263.90473)
		(width 0.0889)
		(layer "In4.Cu")
		(net "M_J_CPU0_SB_CA<4>")
	)
	(segment
		(start 415.032952 -264.060178)
		(end 418.057584 -264.060178)
		(width 0.14478)
		(layer "In4.Cu")
		(net "M_J_CPU0_SB_CA<4>")
	)
	(segment
		(start 379.754892 -263.555988)
		(end 379.600714 -263.821418)
		(width 0.0889)
		(layer "In4.Cu")
		(net "M_J_CPU0_SB_CA<4>")
	)
	(segment
		(start 412.20517 -264.910062)
		(end 414.183068 -264.910062)
		(width 0.14478)
		(layer "In4.Cu")
		(net "M_J_CPU0_SB_CA<4>")
	)
	(segment
		(start 381.447802 -263.878568)
		(end 381.456184 -263.883394)
		(width 0.0889)
		(layer "In4.Cu")
		(net "M_J_CPU0_SB_CA<4>")
	)
	(arc
		(start 392.162284 -263.878568)
		(mid 392.439351 -263.802297)
		(end 392.718036 -263.872472)
		(width 0.0889)
		(layer "In4.Cu")
		(net "M_J_CPU0_SB_CA<4>")
	)
	(arc
		(start 386.52196 -263.878568)
		(mid 386.804916 -263.802391)
		(end 387.087872 -263.878568)
		(width 0.0889)
		(layer "In4.Cu")
		(net "M_J_CPU0_SB_CA<4>")
	)
	(arc
		(start 382.387856 -263.878568)
		(mid 382.5748 -263.928823)
		(end 382.761744 -263.878568)
		(width 0.0889)
		(layer "In4.Cu")
		(net "M_J_CPU0_SB_CA<4>")
	)
	(arc
		(start 387.46176 -263.878568)
		(mid 387.744716 -263.802391)
		(end 388.027672 -263.878568)
		(width 0.0889)
		(layer "In4.Cu")
		(net "M_J_CPU0_SB_CA<4>")
	)
	(arc
		(start 385.216146 -263.883394)
		(mid 385.399654 -263.928888)
		(end 385.581906 -263.878568)
		(width 0.0889)
		(layer "In4.Cu")
		(net "M_J_CPU0_SB_CA<4>")
	)
	(arc
		(start 388.967726 -263.878568)
		(mid 389.149977 -263.928918)
		(end 389.333486 -263.883394)
		(width 0.0889)
		(layer "In4.Cu")
		(net "M_J_CPU0_SB_CA<4>")
	)
	(arc
		(start 381.821944 -263.878568)
		(mid 382.1049 -263.802391)
		(end 382.387856 -263.878568)
		(width 0.0889)
		(layer "In4.Cu")
		(net "M_J_CPU0_SB_CA<4>")
	)
	(arc
		(start 380.88189 -263.878568)
		(mid 381.164846 -263.802391)
		(end 381.447802 -263.878568)
		(width 0.0889)
		(layer "In4.Cu")
		(net "M_J_CPU0_SB_CA<4>")
	)
	(arc
		(start 383.701798 -263.878568)
		(mid 383.984754 -263.802391)
		(end 384.26771 -263.878568)
		(width 0.0889)
		(layer "In4.Cu")
		(net "M_J_CPU0_SB_CA<4>")
	)
	(arc
		(start 391.221722 -263.878568)
		(mid 391.504678 -263.802391)
		(end 391.787634 -263.878568)
		(width 0.0889)
		(layer "In4.Cu")
		(net "M_J_CPU0_SB_CA<4>")
	)
	(arc
		(start 384.26771 -263.878568)
		(mid 384.449961 -263.928918)
		(end 384.63347 -263.883394)
		(width 0.0889)
		(layer "In4.Cu")
		(net "M_J_CPU0_SB_CA<4>")
	)
	(arc
		(start 380.507748 -263.878568)
		(mid 380.689999 -263.928918)
		(end 380.873508 -263.883394)
		(width 0.0889)
		(layer "In4.Cu")
		(net "M_J_CPU0_SB_CA<4>")
	)
	(arc
		(start 392.72845 -263.878568)
		(mid 392.9061 -263.928828)
		(end 393.086082 -263.887712)
		(width 0.0889)
		(layer "In4.Cu")
		(net "M_J_CPU0_SB_CA<4>")
	)
	(arc
		(start 391.796016 -263.883394)
		(mid 391.979778 -263.92901)
		(end 392.162284 -263.878568)
		(width 0.0889)
		(layer "In4.Cu")
		(net "M_J_CPU0_SB_CA<4>")
	)
	(arc
		(start 382.761744 -263.878568)
		(mid 383.0447 -263.802391)
		(end 383.327656 -263.878568)
		(width 0.0889)
		(layer "In4.Cu")
		(net "M_J_CPU0_SB_CA<4>")
	)
	(arc
		(start 384.641852 -263.878568)
		(mid 384.924808 -263.802391)
		(end 385.207764 -263.878568)
		(width 0.0889)
		(layer "In4.Cu")
		(net "M_J_CPU0_SB_CA<4>")
	)
	(arc
		(start 389.341868 -263.878568)
		(mid 389.624824 -263.802391)
		(end 389.90778 -263.878568)
		(width 0.0889)
		(layer "In4.Cu")
		(net "M_J_CPU0_SB_CA<4>")
	)
	(arc
		(start 389.916162 -263.883394)
		(mid 390.09967 -263.928888)
		(end 390.281922 -263.878568)
		(width 0.0889)
		(layer "In4.Cu")
		(net "M_J_CPU0_SB_CA<4>")
	)
	(arc
		(start 383.327656 -263.878568)
		(mid 383.509907 -263.928918)
		(end 383.693416 -263.883394)
		(width 0.0889)
		(layer "In4.Cu")
		(net "M_J_CPU0_SB_CA<4>")
	)
	(arc
		(start 379.623066 -263.90473)
		(mid 379.780576 -263.927928)
		(end 379.933454 -263.883394)
		(width 0.0889)
		(layer "In4.Cu")
		(net "M_J_CPU0_SB_CA<4>")
	)
	(arc
		(start 388.401814 -263.878568)
		(mid 388.68477 -263.802391)
		(end 388.967726 -263.878568)
		(width 0.0889)
		(layer "In4.Cu")
		(net "M_J_CPU0_SB_CA<4>")
	)
	(arc
		(start 386.1562 -263.883394)
		(mid 386.339708 -263.928888)
		(end 386.52196 -263.878568)
		(width 0.0889)
		(layer "In4.Cu")
		(net "M_J_CPU0_SB_CA<4>")
	)
	(arc
		(start 381.456184 -263.883394)
		(mid 381.639692 -263.928888)
		(end 381.821944 -263.878568)
		(width 0.0889)
		(layer "In4.Cu")
		(net "M_J_CPU0_SB_CA<4>")
	)
	(arc
		(start 379.941836 -263.878568)
		(mid 380.224792 -263.802391)
		(end 380.507748 -263.878568)
		(width 0.0889)
		(layer "In4.Cu")
		(net "M_J_CPU0_SB_CA<4>")
	)
	(arc
		(start 390.281922 -263.878568)
		(mid 390.564878 -263.802391)
		(end 390.847834 -263.878568)
		(width 0.0889)
		(layer "In4.Cu")
		(net "M_J_CPU0_SB_CA<4>")
	)
	(arc
		(start 393.086082 -263.887712)
		(mid 393.229176 -263.823995)
		(end 393.384278 -263.802114)
		(width 0.0889)
		(layer "In4.Cu")
		(net "M_J_CPU0_SB_CA<4>")
	)
	(arc
		(start 385.581906 -263.878568)
		(mid 385.864862 -263.802391)
		(end 386.147818 -263.878568)
		(width 0.0889)
		(layer "In4.Cu")
		(net "M_J_CPU0_SB_CA<4>")
	)
	(arc
		(start 390.847834 -263.878568)
		(mid 391.034778 -263.928823)
		(end 391.221722 -263.878568)
		(width 0.0889)
		(layer "In4.Cu")
		(net "M_J_CPU0_SB_CA<4>")
	)
	(arc
		(start 388.027672 -263.878568)
		(mid 388.209923 -263.928918)
		(end 388.393432 -263.883394)
		(width 0.0889)
		(layer "In4.Cu")
		(net "M_J_CPU0_SB_CA<4>")
	)
	(arc
		(start 387.087872 -263.878568)
		(mid 387.274816 -263.928823)
		(end 387.46176 -263.878568)
		(width 0.0889)
		(layer "In4.Cu")
		(net "M_J_CPU0_SB_CA<4>")
	)
	(segment
		(start 380.22784 -263.29005)
		(end 380.694946 -263.555988)
		(width 0.10668)
		(layer "F.Cu")
		(net "M_J_CPU0_SB_CA<3>")
	)
	(segment
		(start 386.147818 -263.233408)
		(end 386.1562 -263.228582)
		(width 0.0889)
		(layer "In4.Cu")
		(net "M_J_CPU0_SB_CA<3>")
	)
	(segment
		(start 406.78989 -262.97509)
		(end 407.018236 -262.97509)
		(width 0.14478)
		(layer "In4.Cu")
		(net "M_J_CPU0_SB_CA<3>")
	)
	(segment
		(start 395.288262 -262.97509)
		(end 395.949932 -262.97509)
		(width 0.0889)
		(layer "In4.Cu")
		(net "M_J_CPU0_SB_CA<3>")
	)
	(segment
		(start 404.8125 -262.97509)
		(end 404.974044 -262.813546)
		(width 0.14478)
		(layer "In4.Cu")
		(net "M_J_CPU0_SB_CA<3>")
	)
	(segment
		(start 380.84887 -263.290558)
		(end 380.944882 -263.265158)
		(width 0.0889)
		(layer "In4.Cu")
		(net "M_J_CPU0_SB_CA<3>")
	)
	(segment
		(start 385.207764 -263.233408)
		(end 385.216146 -263.228582)
		(width 0.0889)
		(layer "In4.Cu")
		(net "M_J_CPU0_SB_CA<3>")
	)
	(segment
		(start 410.91358 -262.97509)
		(end 411.998668 -264.060178)
		(width 0.14478)
		(layer "In4.Cu")
		(net "M_J_CPU0_SB_CA<3>")
	)
	(segment
		(start 407.018236 -262.97509)
		(end 407.17978 -262.813546)
		(width 0.14478)
		(layer "In4.Cu")
		(net "M_J_CPU0_SB_CA<3>")
	)
	(segment
		(start 405.687022 -262.97509)
		(end 405.915368 -262.97509)
		(width 0.14478)
		(layer "In4.Cu")
		(net "M_J_CPU0_SB_CA<3>")
	)
	(segment
		(start 405.525478 -262.603996)
		(end 405.525478 -262.813546)
		(width 0.14478)
		(layer "In4.Cu")
		(net "M_J_CPU0_SB_CA<3>")
	)
	(segment
		(start 404.974044 -262.813546)
		(end 404.974044 -262.603996)
		(width 0.14478)
		(layer "In4.Cu")
		(net "M_J_CPU0_SB_CA<3>")
	)
	(segment
		(start 407.731214 -262.813546)
		(end 407.892758 -262.97509)
		(width 0.14478)
		(layer "In4.Cu")
		(net "M_J_CPU0_SB_CA<3>")
	)
	(segment
		(start 392.140948 -263.222232)
		(end 392.161014 -263.233662)
		(width 0.0889)
		(layer "In4.Cu")
		(net "M_J_CPU0_SB_CA<3>")
	)
	(segment
		(start 407.17978 -262.603996)
		(end 407.341324 -262.442452)
		(width 0.14478)
		(layer "In4.Cu")
		(net "M_J_CPU0_SB_CA<3>")
	)
	(segment
		(start 383.693416 -263.228582)
		(end 383.701798 -263.233408)
		(width 0.0889)
		(layer "In4.Cu")
		(net "M_J_CPU0_SB_CA<3>")
	)
	(segment
		(start 407.56967 -262.442452)
		(end 407.731214 -262.603996)
		(width 0.14478)
		(layer "In4.Cu")
		(net "M_J_CPU0_SB_CA<3>")
	)
	(segment
		(start 411.998668 -264.060178)
		(end 414.090104 -264.060178)
		(width 0.14478)
		(layer "In4.Cu")
		(net "M_J_CPU0_SB_CA<3>")
	)
	(segment
		(start 414.940242 -263.21004)
		(end 418.122608 -263.21004)
		(width 0.14478)
		(layer "In4.Cu")
		(net "M_J_CPU0_SB_CA<3>")
	)
	(segment
		(start 395.949932 -262.97509)
		(end 404.8125 -262.97509)
		(width 0.14478)
		(layer "In4.Cu")
		(net "M_J_CPU0_SB_CA<3>")
	)
	(segment
		(start 407.341324 -262.442452)
		(end 407.56967 -262.442452)
		(width 0.14478)
		(layer "In4.Cu")
		(net "M_J_CPU0_SB_CA<3>")
	)
	(segment
		(start 414.090104 -264.060178)
		(end 414.940242 -263.21004)
		(width 0.14478)
		(layer "In4.Cu")
		(net "M_J_CPU0_SB_CA<3>")
	)
	(segment
		(start 392.161014 -263.233662)
		(end 392.182604 -263.246108)
		(width 0.0889)
		(layer "In4.Cu")
		(net "M_J_CPU0_SB_CA<3>")
	)
	(segment
		(start 418.122608 -263.21004)
		(end 418.972746 -264.060178)
		(width 0.14478)
		(layer "In4.Cu")
		(net "M_J_CPU0_SB_CA<3>")
	)
	(segment
		(start 421.634158 -264.060178)
		(end 422.484296 -263.21004)
		(width 0.14478)
		(layer "In4.Cu")
		(net "M_J_CPU0_SB_CA<3>")
	)
	(segment
		(start 406.628346 -262.603996)
		(end 406.628346 -262.813546)
		(width 0.14478)
		(layer "In4.Cu")
		(net "M_J_CPU0_SB_CA<3>")
	)
	(segment
		(start 405.363934 -262.442452)
		(end 405.525478 -262.603996)
		(width 0.14478)
		(layer "In4.Cu")
		(net "M_J_CPU0_SB_CA<3>")
	)
	(segment
		(start 418.972746 -264.060178)
		(end 421.634158 -264.060178)
		(width 0.14478)
		(layer "In4.Cu")
		(net "M_J_CPU0_SB_CA<3>")
	)
	(segment
		(start 388.393432 -263.228582)
		(end 388.401814 -263.233408)
		(width 0.0889)
		(layer "In4.Cu")
		(net "M_J_CPU0_SB_CA<3>")
	)
	(segment
		(start 422.484296 -263.21004)
		(end 434.575204 -263.21004)
		(width 0.14478)
		(layer "In4.Cu")
		(net "M_J_CPU0_SB_CA<3>")
	)
	(segment
		(start 406.466802 -262.442452)
		(end 406.628346 -262.603996)
		(width 0.14478)
		(layer "In4.Cu")
		(net "M_J_CPU0_SB_CA<3>")
	)
	(segment
		(start 405.915368 -262.97509)
		(end 406.076912 -262.813546)
		(width 0.14478)
		(layer "In4.Cu")
		(net "M_J_CPU0_SB_CA<3>")
	)
	(segment
		(start 434.575204 -263.21004)
		(end 435.000146 -263.634982)
		(width 0.14478)
		(layer "In4.Cu")
		(net "M_J_CPU0_SB_CA<3>")
	)
	(segment
		(start 394.081254 -263.310116)
		(end 394.46708 -262.92429)
		(width 0.0889)
		(layer "In4.Cu")
		(net "M_J_CPU0_SB_CA<3>")
	)
	(segment
		(start 389.90778 -263.233408)
		(end 389.916162 -263.228582)
		(width 0.0889)
		(layer "In4.Cu")
		(net "M_J_CPU0_SB_CA<3>")
	)
	(segment
		(start 406.076912 -262.603996)
		(end 406.238456 -262.442452)
		(width 0.14478)
		(layer "In4.Cu")
		(net "M_J_CPU0_SB_CA<3>")
	)
	(segment
		(start 407.731214 -262.603996)
		(end 407.731214 -262.813546)
		(width 0.14478)
		(layer "In4.Cu")
		(net "M_J_CPU0_SB_CA<3>")
	)
	(segment
		(start 406.238456 -262.442452)
		(end 406.466802 -262.442452)
		(width 0.14478)
		(layer "In4.Cu")
		(net "M_J_CPU0_SB_CA<3>")
	)
	(segment
		(start 394.46708 -262.92429)
		(end 395.237462 -262.92429)
		(width 0.0889)
		(layer "In4.Cu")
		(net "M_J_CPU0_SB_CA<3>")
	)
	(segment
		(start 384.63347 -263.228582)
		(end 384.641852 -263.233408)
		(width 0.0889)
		(layer "In4.Cu")
		(net "M_J_CPU0_SB_CA<3>")
	)
	(segment
		(start 393.384786 -263.310116)
		(end 394.081254 -263.310116)
		(width 0.0889)
		(layer "In4.Cu")
		(net "M_J_CPU0_SB_CA<3>")
	)
	(segment
		(start 405.135588 -262.442452)
		(end 405.363934 -262.442452)
		(width 0.14478)
		(layer "In4.Cu")
		(net "M_J_CPU0_SB_CA<3>")
	)
	(segment
		(start 407.892758 -262.97509)
		(end 410.91358 -262.97509)
		(width 0.14478)
		(layer "In4.Cu")
		(net "M_J_CPU0_SB_CA<3>")
	)
	(segment
		(start 406.628346 -262.813546)
		(end 406.78989 -262.97509)
		(width 0.14478)
		(layer "In4.Cu")
		(net "M_J_CPU0_SB_CA<3>")
	)
	(segment
		(start 380.694946 -263.555988)
		(end 380.84887 -263.290558)
		(width 0.0889)
		(layer "In4.Cu")
		(net "M_J_CPU0_SB_CA<3>")
	)
	(segment
		(start 404.974044 -262.603996)
		(end 405.135588 -262.442452)
		(width 0.14478)
		(layer "In4.Cu")
		(net "M_J_CPU0_SB_CA<3>")
	)
	(segment
		(start 406.076912 -262.813546)
		(end 406.076912 -262.603996)
		(width 0.14478)
		(layer "In4.Cu")
		(net "M_J_CPU0_SB_CA<3>")
	)
	(segment
		(start 395.237462 -262.92429)
		(end 395.288262 -262.97509)
		(width 0.0889)
		(layer "In4.Cu")
		(net "M_J_CPU0_SB_CA<3>")
	)
	(segment
		(start 405.525478 -262.813546)
		(end 405.687022 -262.97509)
		(width 0.14478)
		(layer "In4.Cu")
		(net "M_J_CPU0_SB_CA<3>")
	)
	(segment
		(start 389.333486 -263.228582)
		(end 389.341868 -263.233408)
		(width 0.0889)
		(layer "In4.Cu")
		(net "M_J_CPU0_SB_CA<3>")
	)
	(segment
		(start 392.725402 -263.233408)
		(end 392.744198 -263.222486)
		(width 0.0889)
		(layer "In4.Cu")
		(net "M_J_CPU0_SB_CA<3>")
	)
	(segment
		(start 407.17978 -262.813546)
		(end 407.17978 -262.603996)
		(width 0.14478)
		(layer "In4.Cu")
		(net "M_J_CPU0_SB_CA<3>")
	)
	(segment
		(start 381.447802 -263.233408)
		(end 381.456184 -263.228582)
		(width 0.0889)
		(layer "In4.Cu")
		(net "M_J_CPU0_SB_CA<3>")
	)
	(arc
		(start 382.761744 -263.233408)
		(mid 383.0447 -263.309585)
		(end 383.327656 -263.233408)
		(width 0.0889)
		(layer "In4.Cu")
		(net "M_J_CPU0_SB_CA<3>")
	)
	(arc
		(start 382.387856 -263.233408)
		(mid 382.5748 -263.183153)
		(end 382.761744 -263.233408)
		(width 0.0889)
		(layer "In4.Cu")
		(net "M_J_CPU0_SB_CA<3>")
	)
	(arc
		(start 384.26771 -263.233408)
		(mid 384.449961 -263.183058)
		(end 384.63347 -263.228582)
		(width 0.0889)
		(layer "In4.Cu")
		(net "M_J_CPU0_SB_CA<3>")
	)
	(arc
		(start 386.52196 -263.233408)
		(mid 386.804916 -263.309585)
		(end 387.087872 -263.233408)
		(width 0.0889)
		(layer "In4.Cu")
		(net "M_J_CPU0_SB_CA<3>")
	)
	(arc
		(start 386.1562 -263.228582)
		(mid 386.339708 -263.183088)
		(end 386.52196 -263.233408)
		(width 0.0889)
		(layer "In4.Cu")
		(net "M_J_CPU0_SB_CA<3>")
	)
	(arc
		(start 389.341868 -263.233408)
		(mid 389.624824 -263.309585)
		(end 389.90778 -263.233408)
		(width 0.0889)
		(layer "In4.Cu")
		(net "M_J_CPU0_SB_CA<3>")
	)
	(arc
		(start 392.744198 -263.222486)
		(mid 392.923769 -263.182669)
		(end 393.10056 -263.233408)
		(width 0.0889)
		(layer "In4.Cu")
		(net "M_J_CPU0_SB_CA<3>")
	)
	(arc
		(start 388.027672 -263.233408)
		(mid 388.209923 -263.183058)
		(end 388.393432 -263.228582)
		(width 0.0889)
		(layer "In4.Cu")
		(net "M_J_CPU0_SB_CA<3>")
	)
	(arc
		(start 388.967726 -263.233408)
		(mid 389.149977 -263.183058)
		(end 389.333486 -263.228582)
		(width 0.0889)
		(layer "In4.Cu")
		(net "M_J_CPU0_SB_CA<3>")
	)
	(arc
		(start 393.10056 -263.233408)
		(mid 393.237582 -263.290619)
		(end 393.384786 -263.310116)
		(width 0.0889)
		(layer "In4.Cu")
		(net "M_J_CPU0_SB_CA<3>")
	)
	(arc
		(start 384.641852 -263.233408)
		(mid 384.924808 -263.309585)
		(end 385.207764 -263.233408)
		(width 0.0889)
		(layer "In4.Cu")
		(net "M_J_CPU0_SB_CA<3>")
	)
	(arc
		(start 390.847834 -263.233408)
		(mid 391.034778 -263.183153)
		(end 391.221722 -263.233408)
		(width 0.0889)
		(layer "In4.Cu")
		(net "M_J_CPU0_SB_CA<3>")
	)
	(arc
		(start 392.182604 -263.246108)
		(mid 392.455633 -263.309427)
		(end 392.725402 -263.233408)
		(width 0.0889)
		(layer "In4.Cu")
		(net "M_J_CPU0_SB_CA<3>")
	)
	(arc
		(start 380.944882 -263.265158)
		(mid 381.20009 -263.308635)
		(end 381.447802 -263.233408)
		(width 0.0889)
		(layer "In4.Cu")
		(net "M_J_CPU0_SB_CA<3>")
	)
	(arc
		(start 387.46176 -263.233408)
		(mid 387.744716 -263.309585)
		(end 388.027672 -263.233408)
		(width 0.0889)
		(layer "In4.Cu")
		(net "M_J_CPU0_SB_CA<3>")
	)
	(arc
		(start 391.221722 -263.233408)
		(mid 391.504678 -263.309585)
		(end 391.787634 -263.233408)
		(width 0.0889)
		(layer "In4.Cu")
		(net "M_J_CPU0_SB_CA<3>")
	)
	(arc
		(start 385.216146 -263.228582)
		(mid 385.399654 -263.183088)
		(end 385.581906 -263.233408)
		(width 0.0889)
		(layer "In4.Cu")
		(net "M_J_CPU0_SB_CA<3>")
	)
	(arc
		(start 387.087872 -263.233408)
		(mid 387.274816 -263.183153)
		(end 387.46176 -263.233408)
		(width 0.0889)
		(layer "In4.Cu")
		(net "M_J_CPU0_SB_CA<3>")
	)
	(arc
		(start 383.701798 -263.233408)
		(mid 383.984754 -263.309585)
		(end 384.26771 -263.233408)
		(width 0.0889)
		(layer "In4.Cu")
		(net "M_J_CPU0_SB_CA<3>")
	)
	(arc
		(start 383.327656 -263.233408)
		(mid 383.509907 -263.183058)
		(end 383.693416 -263.228582)
		(width 0.0889)
		(layer "In4.Cu")
		(net "M_J_CPU0_SB_CA<3>")
	)
	(arc
		(start 389.916162 -263.228582)
		(mid 390.09967 -263.183088)
		(end 390.281922 -263.233408)
		(width 0.0889)
		(layer "In4.Cu")
		(net "M_J_CPU0_SB_CA<3>")
	)
	(arc
		(start 381.456184 -263.228582)
		(mid 381.639692 -263.183088)
		(end 381.821944 -263.233408)
		(width 0.0889)
		(layer "In4.Cu")
		(net "M_J_CPU0_SB_CA<3>")
	)
	(arc
		(start 381.821944 -263.233408)
		(mid 382.1049 -263.309585)
		(end 382.387856 -263.233408)
		(width 0.0889)
		(layer "In4.Cu")
		(net "M_J_CPU0_SB_CA<3>")
	)
	(arc
		(start 385.581906 -263.233408)
		(mid 385.864862 -263.309585)
		(end 386.147818 -263.233408)
		(width 0.0889)
		(layer "In4.Cu")
		(net "M_J_CPU0_SB_CA<3>")
	)
	(arc
		(start 388.401814 -263.233408)
		(mid 388.68477 -263.309585)
		(end 388.967726 -263.233408)
		(width 0.0889)
		(layer "In4.Cu")
		(net "M_J_CPU0_SB_CA<3>")
	)
	(arc
		(start 390.281922 -263.233408)
		(mid 390.564878 -263.309585)
		(end 390.847834 -263.233408)
		(width 0.0889)
		(layer "In4.Cu")
		(net "M_J_CPU0_SB_CA<3>")
	)
	(arc
		(start 391.787634 -263.233408)
		(mid 391.962873 -263.183337)
		(end 392.140948 -263.222232)
		(width 0.0889)
		(layer "In4.Cu")
		(net "M_J_CPU0_SB_CA<3>")
	)
	(segment
		(start 380.697994 -262.480044)
		(end 381.164846 -262.745982)
		(width 0.10668)
		(layer "F.Cu")
		(net "M_J_CPU0_SB_CA<2>")
	)
	(segment
		(start 388.497826 -263.068562)
		(end 388.506208 -263.073388)
		(width 0.0889)
		(layer "In4.Cu")
		(net "M_J_CPU0_SB_CA<2>")
	)
	(segment
		(start 422.577006 -262.360156)
		(end 438.675272 -262.360156)
		(width 0.14478)
		(layer "In4.Cu")
		(net "M_J_CPU0_SB_CA<2>")
	)
	(segment
		(start 404.194518 -262.52043)
		(end 404.722076 -261.992872)
		(width 0.14478)
		(layer "In4.Cu")
		(net "M_J_CPU0_SB_CA<2>")
	)
	(segment
		(start 393.384786 -263.119362)
		(end 393.38504 -263.119616)
		(width 0.0889)
		(layer "In4.Cu")
		(net "M_J_CPU0_SB_CA<2>")
	)
	(segment
		(start 392.62939 -263.068562)
		(end 392.652758 -263.054846)
		(width 0.0889)
		(layer "In4.Cu")
		(net "M_J_CPU0_SB_CA<2>")
	)
	(segment
		(start 411.404308 -262.52551)
		(end 412.088838 -263.21004)
		(width 0.14478)
		(layer "In4.Cu")
		(net "M_J_CPU0_SB_CA<2>")
	)
	(segment
		(start 415.032952 -262.360156)
		(end 418.057584 -262.360156)
		(width 0.14478)
		(layer "In4.Cu")
		(net "M_J_CPU0_SB_CA<2>")
	)
	(segment
		(start 394.38072 -262.72109)
		(end 395.109446 -262.72109)
		(width 0.0889)
		(layer "In4.Cu")
		(net "M_J_CPU0_SB_CA<2>")
	)
	(segment
		(start 408.539696 -262.52551)
		(end 411.404308 -262.52551)
		(width 0.14478)
		(layer "In4.Cu")
		(net "M_J_CPU0_SB_CA<2>")
	)
	(segment
		(start 381.164846 -262.745982)
		(end 381.010922 -263.011412)
		(width 0.0889)
		(layer "In4.Cu")
		(net "M_J_CPU0_SB_CA<2>")
	)
	(segment
		(start 438.675272 -262.360156)
		(end 439.100214 -262.785098)
		(width 0.14478)
		(layer "In4.Cu")
		(net "M_J_CPU0_SB_CA<2>")
	)
	(segment
		(start 382.857756 -263.068562)
		(end 382.866138 -263.073388)
		(width 0.0889)
		(layer "In4.Cu")
		(net "M_J_CPU0_SB_CA<2>")
	)
	(segment
		(start 386.043424 -263.073388)
		(end 386.051806 -263.068562)
		(width 0.0889)
		(layer "In4.Cu")
		(net "M_J_CPU0_SB_CA<2>")
	)
	(segment
		(start 421.727122 -263.21004)
		(end 422.577006 -262.360156)
		(width 0.14478)
		(layer "In4.Cu")
		(net "M_J_CPU0_SB_CA<2>")
	)
	(segment
		(start 395.956536 -262.52043)
		(end 404.194518 -262.52043)
		(width 0.14478)
		(layer "In4.Cu")
		(net "M_J_CPU0_SB_CA<2>")
	)
	(segment
		(start 393.38504 -263.119616)
		(end 393.982194 -263.119616)
		(width 0.0889)
		(layer "In4.Cu")
		(net "M_J_CPU0_SB_CA<2>")
	)
	(segment
		(start 412.088838 -263.21004)
		(end 414.183068 -263.21004)
		(width 0.14478)
		(layer "In4.Cu")
		(net "M_J_CPU0_SB_CA<2>")
	)
	(segment
		(start 395.310106 -262.52043)
		(end 395.956536 -262.52043)
		(width 0.0889)
		(layer "In4.Cu")
		(net "M_J_CPU0_SB_CA<2>")
	)
	(segment
		(start 414.183068 -263.21004)
		(end 415.032952 -262.360156)
		(width 0.14478)
		(layer "In4.Cu")
		(net "M_J_CPU0_SB_CA<2>")
	)
	(segment
		(start 390.74344 -263.073388)
		(end 390.751822 -263.068562)
		(width 0.0889)
		(layer "In4.Cu")
		(net "M_J_CPU0_SB_CA<2>")
	)
	(segment
		(start 392.256264 -263.068308)
		(end 392.274552 -263.078722)
		(width 0.0889)
		(layer "In4.Cu")
		(net "M_J_CPU0_SB_CA<2>")
	)
	(segment
		(start 381.010922 -263.011412)
		(end 381.033274 -263.094724)
		(width 0.0889)
		(layer "In4.Cu")
		(net "M_J_CPU0_SB_CA<2>")
	)
	(segment
		(start 391.317734 -263.068562)
		(end 391.326116 -263.073388)
		(width 0.0889)
		(layer "In4.Cu")
		(net "M_J_CPU0_SB_CA<2>")
	)
	(segment
		(start 408.007058 -261.992872)
		(end 408.539696 -262.52551)
		(width 0.14478)
		(layer "In4.Cu")
		(net "M_J_CPU0_SB_CA<2>")
	)
	(segment
		(start 386.983478 -263.073388)
		(end 386.99186 -263.068562)
		(width 0.0889)
		(layer "In4.Cu")
		(net "M_J_CPU0_SB_CA<2>")
	)
	(segment
		(start 382.283462 -263.073388)
		(end 382.291844 -263.068562)
		(width 0.0889)
		(layer "In4.Cu")
		(net "M_J_CPU0_SB_CA<2>")
	)
	(segment
		(start 392.234674 -263.055862)
		(end 392.256264 -263.068308)
		(width 0.0889)
		(layer "In4.Cu")
		(net "M_J_CPU0_SB_CA<2>")
	)
	(segment
		(start 418.057584 -262.360156)
		(end 418.907468 -263.21004)
		(width 0.14478)
		(layer "In4.Cu")
		(net "M_J_CPU0_SB_CA<2>")
	)
	(segment
		(start 393.982194 -263.119616)
		(end 394.38072 -262.72109)
		(width 0.0889)
		(layer "In4.Cu")
		(net "M_J_CPU0_SB_CA<2>")
	)
	(segment
		(start 395.109446 -262.72109)
		(end 395.310106 -262.52043)
		(width 0.0889)
		(layer "In4.Cu")
		(net "M_J_CPU0_SB_CA<2>")
	)
	(segment
		(start 418.907468 -263.21004)
		(end 421.727122 -263.21004)
		(width 0.14478)
		(layer "In4.Cu")
		(net "M_J_CPU0_SB_CA<2>")
	)
	(segment
		(start 404.722076 -261.992872)
		(end 408.007058 -261.992872)
		(width 0.14478)
		(layer "In4.Cu")
		(net "M_J_CPU0_SB_CA<2>")
	)
	(segment
		(start 387.557772 -263.068562)
		(end 387.566154 -263.073388)
		(width 0.0889)
		(layer "In4.Cu")
		(net "M_J_CPU0_SB_CA<2>")
	)
	(segment
		(start 383.79781 -263.068562)
		(end 383.806192 -263.073388)
		(width 0.0889)
		(layer "In4.Cu")
		(net "M_J_CPU0_SB_CA<2>")
	)
	(arc
		(start 388.871968 -263.068562)
		(mid 389.154924 -262.992385)
		(end 389.43788 -263.068562)
		(width 0.0889)
		(layer "In4.Cu")
		(net "M_J_CPU0_SB_CA<2>")
	)
	(arc
		(start 393.196572 -263.068562)
		(mid 393.287307 -263.106446)
		(end 393.384786 -263.119362)
		(width 0.0889)
		(layer "In4.Cu")
		(net "M_J_CPU0_SB_CA<2>")
	)
	(arc
		(start 384.171952 -263.068562)
		(mid 384.454908 -262.992385)
		(end 384.737864 -263.068562)
		(width 0.0889)
		(layer "In4.Cu")
		(net "M_J_CPU0_SB_CA<2>")
	)
	(arc
		(start 390.37768 -263.068562)
		(mid 390.559931 -263.118912)
		(end 390.74344 -263.073388)
		(width 0.0889)
		(layer "In4.Cu")
		(net "M_J_CPU0_SB_CA<2>")
	)
	(arc
		(start 389.43788 -263.068562)
		(mid 389.624824 -263.118817)
		(end 389.811768 -263.068562)
		(width 0.0889)
		(layer "In4.Cu")
		(net "M_J_CPU0_SB_CA<2>")
	)
	(arc
		(start 388.506208 -263.073388)
		(mid 388.689716 -263.118882)
		(end 388.871968 -263.068562)
		(width 0.0889)
		(layer "In4.Cu")
		(net "M_J_CPU0_SB_CA<2>")
	)
	(arc
		(start 386.051806 -263.068562)
		(mid 386.334762 -262.992385)
		(end 386.617718 -263.068562)
		(width 0.0889)
		(layer "In4.Cu")
		(net "M_J_CPU0_SB_CA<2>")
	)
	(arc
		(start 392.652758 -263.054846)
		(mid 392.926412 -262.991903)
		(end 393.196572 -263.068562)
		(width 0.0889)
		(layer "In4.Cu")
		(net "M_J_CPU0_SB_CA<2>")
	)
	(arc
		(start 387.931914 -263.068562)
		(mid 388.21487 -262.992385)
		(end 388.497826 -263.068562)
		(width 0.0889)
		(layer "In4.Cu")
		(net "M_J_CPU0_SB_CA<2>")
	)
	(arc
		(start 385.677664 -263.068562)
		(mid 385.859915 -263.118912)
		(end 386.043424 -263.073388)
		(width 0.0889)
		(layer "In4.Cu")
		(net "M_J_CPU0_SB_CA<2>")
	)
	(arc
		(start 382.866138 -263.073388)
		(mid 383.049646 -263.118882)
		(end 383.231898 -263.068562)
		(width 0.0889)
		(layer "In4.Cu")
		(net "M_J_CPU0_SB_CA<2>")
	)
	(arc
		(start 382.291844 -263.068562)
		(mid 382.5748 -262.992385)
		(end 382.857756 -263.068562)
		(width 0.0889)
		(layer "In4.Cu")
		(net "M_J_CPU0_SB_CA<2>")
	)
	(arc
		(start 383.806192 -263.073388)
		(mid 383.9897 -263.118882)
		(end 384.171952 -263.068562)
		(width 0.0889)
		(layer "In4.Cu")
		(net "M_J_CPU0_SB_CA<2>")
	)
	(arc
		(start 392.274552 -263.078722)
		(mid 392.453273 -263.118645)
		(end 392.62939 -263.068562)
		(width 0.0889)
		(layer "In4.Cu")
		(net "M_J_CPU0_SB_CA<2>")
	)
	(arc
		(start 390.751822 -263.068562)
		(mid 391.034778 -262.992385)
		(end 391.317734 -263.068562)
		(width 0.0889)
		(layer "In4.Cu")
		(net "M_J_CPU0_SB_CA<2>")
	)
	(arc
		(start 386.617718 -263.068562)
		(mid 386.799969 -263.118912)
		(end 386.983478 -263.073388)
		(width 0.0889)
		(layer "In4.Cu")
		(net "M_J_CPU0_SB_CA<2>")
	)
	(arc
		(start 391.691876 -263.068562)
		(mid 391.961645 -262.992539)
		(end 392.234674 -263.055862)
		(width 0.0889)
		(layer "In4.Cu")
		(net "M_J_CPU0_SB_CA<2>")
	)
	(arc
		(start 381.917702 -263.068562)
		(mid 382.099953 -263.118912)
		(end 382.283462 -263.073388)
		(width 0.0889)
		(layer "In4.Cu")
		(net "M_J_CPU0_SB_CA<2>")
	)
	(arc
		(start 384.737864 -263.068562)
		(mid 384.924808 -263.118817)
		(end 385.111752 -263.068562)
		(width 0.0889)
		(layer "In4.Cu")
		(net "M_J_CPU0_SB_CA<2>")
	)
	(arc
		(start 389.811768 -263.068562)
		(mid 390.094724 -262.992385)
		(end 390.37768 -263.068562)
		(width 0.0889)
		(layer "In4.Cu")
		(net "M_J_CPU0_SB_CA<2>")
	)
	(arc
		(start 391.326116 -263.073388)
		(mid 391.509624 -263.118882)
		(end 391.691876 -263.068562)
		(width 0.0889)
		(layer "In4.Cu")
		(net "M_J_CPU0_SB_CA<2>")
	)
	(arc
		(start 386.99186 -263.068562)
		(mid 387.274816 -262.992385)
		(end 387.557772 -263.068562)
		(width 0.0889)
		(layer "In4.Cu")
		(net "M_J_CPU0_SB_CA<2>")
	)
	(arc
		(start 383.231898 -263.068562)
		(mid 383.514854 -262.992385)
		(end 383.79781 -263.068562)
		(width 0.0889)
		(layer "In4.Cu")
		(net "M_J_CPU0_SB_CA<2>")
	)
	(arc
		(start 387.566154 -263.073388)
		(mid 387.749662 -263.118882)
		(end 387.931914 -263.068562)
		(width 0.0889)
		(layer "In4.Cu")
		(net "M_J_CPU0_SB_CA<2>")
	)
	(arc
		(start 381.35179 -263.068562)
		(mid 381.634746 -262.992385)
		(end 381.917702 -263.068562)
		(width 0.0889)
		(layer "In4.Cu")
		(net "M_J_CPU0_SB_CA<2>")
	)
	(arc
		(start 385.111752 -263.068562)
		(mid 385.394708 -262.992385)
		(end 385.677664 -263.068562)
		(width 0.0889)
		(layer "In4.Cu")
		(net "M_J_CPU0_SB_CA<2>")
	)
	(arc
		(start 381.033274 -263.094724)
		(mid 381.195463 -263.117459)
		(end 381.35179 -263.068562)
		(width 0.0889)
		(layer "In4.Cu")
		(net "M_J_CPU0_SB_CA<2>")
	)
	(segment
		(start 378.817886 -262.480044)
		(end 379.284738 -262.745982)
		(width 0.10668)
		(layer "F.Cu")
		(net "M_J_CPU0_SB_CA<1>")
	)
	(segment
		(start 409.202636 -261.818628)
		(end 409.202636 -261.271258)
		(width 0.14478)
		(layer "In4.Cu")
		(net "M_J_CPU0_SB_CA<1>")
	)
	(segment
		(start 386.043424 -262.418576)
		(end 386.051806 -262.423402)
		(width 0.0889)
		(layer "In4.Cu")
		(net "M_J_CPU0_SB_CA<1>")
	)
	(segment
		(start 425.096686 -261.20471)
		(end 425.347892 -261.20471)
		(width 0.14478)
		(layer "In4.Cu")
		(net "M_J_CPU0_SB_CA<1>")
	)
	(segment
		(start 408.489658 -261.109714)
		(end 408.651202 -261.271258)
		(width 0.14478)
		(layer "In4.Cu")
		(net "M_J_CPU0_SB_CA<1>")
	)
	(segment
		(start 382.283462 -262.418576)
		(end 382.291844 -262.423402)
		(width 0.0889)
		(layer "In4.Cu")
		(net "M_J_CPU0_SB_CA<1>")
	)
	(segment
		(start 408.812746 -261.980172)
		(end 409.041092 -261.980172)
		(width 0.14478)
		(layer "In4.Cu")
		(net "M_J_CPU0_SB_CA<1>")
	)
	(segment
		(start 422.484296 -261.510018)
		(end 424.791378 -261.510018)
		(width 0.14478)
		(layer "In4.Cu")
		(net "M_J_CPU0_SB_CA<1>")
	)
	(segment
		(start 410.305504 -261.271258)
		(end 410.467048 -261.109714)
		(width 0.14478)
		(layer "In4.Cu")
		(net "M_J_CPU0_SB_CA<1>")
	)
	(segment
		(start 427.573948 -261.20471)
		(end 427.879256 -261.510018)
		(width 0.14478)
		(layer "In4.Cu")
		(net "M_J_CPU0_SB_CA<1>")
	)
	(segment
		(start 392.62431 -262.418576)
		(end 392.632692 -262.423402)
		(width 0.0889)
		(layer "In4.Cu")
		(net "M_J_CPU0_SB_CA<1>")
	)
	(segment
		(start 382.857756 -262.423402)
		(end 382.866138 -262.418576)
		(width 0.0889)
		(layer "In4.Cu")
		(net "M_J_CPU0_SB_CA<1>")
	)
	(segment
		(start 414.940242 -261.510018)
		(end 418.122608 -261.510018)
		(width 0.14478)
		(layer "In4.Cu")
		(net "M_J_CPU0_SB_CA<1>")
	)
	(segment
		(start 430.913032 -261.20471)
		(end 431.21834 -261.510018)
		(width 0.14478)
		(layer "In4.Cu")
		(net "M_J_CPU0_SB_CA<1>")
	)
	(segment
		(start 386.983478 -262.418576)
		(end 386.99186 -262.423402)
		(width 0.0889)
		(layer "In4.Cu")
		(net "M_J_CPU0_SB_CA<1>")
	)
	(segment
		(start 427.322742 -261.20471)
		(end 427.573948 -261.20471)
		(width 0.14478)
		(layer "In4.Cu")
		(net "M_J_CPU0_SB_CA<1>")
	)
	(segment
		(start 430.661826 -261.20471)
		(end 430.913032 -261.20471)
		(width 0.14478)
		(layer "In4.Cu")
		(net "M_J_CPU0_SB_CA<1>")
	)
	(segment
		(start 409.202636 -261.271258)
		(end 409.36418 -261.109714)
		(width 0.14478)
		(layer "In4.Cu")
		(net "M_J_CPU0_SB_CA<1>")
	)
	(segment
		(start 410.14396 -261.980172)
		(end 410.305504 -261.818628)
		(width 0.14478)
		(layer "In4.Cu")
		(net "M_J_CPU0_SB_CA<1>")
	)
	(segment
		(start 429.548798 -261.20471)
		(end 429.800004 -261.20471)
		(width 0.14478)
		(layer "In4.Cu")
		(net "M_J_CPU0_SB_CA<1>")
	)
	(segment
		(start 379.438916 -262.480552)
		(end 379.535182 -262.455152)
		(width 0.0889)
		(layer "In4.Cu")
		(net "M_J_CPU0_SB_CA<1>")
	)
	(segment
		(start 393.384786 -262.372602)
		(end 395.118336 -262.372602)
		(width 0.0889)
		(layer "In4.Cu")
		(net "M_J_CPU0_SB_CA<1>")
	)
	(segment
		(start 391.317734 -262.423402)
		(end 391.326116 -262.418576)
		(width 0.0889)
		(layer "In4.Cu")
		(net "M_J_CPU0_SB_CA<1>")
	)
	(segment
		(start 428.992284 -261.510018)
		(end 429.24349 -261.510018)
		(width 0.14478)
		(layer "In4.Cu")
		(net "M_J_CPU0_SB_CA<1>")
	)
	(segment
		(start 428.130462 -261.510018)
		(end 428.43577 -261.20471)
		(width 0.14478)
		(layer "In4.Cu")
		(net "M_J_CPU0_SB_CA<1>")
	)
	(segment
		(start 387.557772 -262.423402)
		(end 387.566154 -262.418576)
		(width 0.0889)
		(layer "In4.Cu")
		(net "M_J_CPU0_SB_CA<1>")
	)
	(segment
		(start 430.105312 -261.510018)
		(end 430.356518 -261.510018)
		(width 0.14478)
		(layer "In4.Cu")
		(net "M_J_CPU0_SB_CA<1>")
	)
	(segment
		(start 390.74344 -262.418576)
		(end 390.751822 -262.423402)
		(width 0.0889)
		(layer "In4.Cu")
		(net "M_J_CPU0_SB_CA<1>")
	)
	(segment
		(start 424.791378 -261.510018)
		(end 425.096686 -261.20471)
		(width 0.14478)
		(layer "In4.Cu")
		(net "M_J_CPU0_SB_CA<1>")
	)
	(segment
		(start 430.356518 -261.510018)
		(end 430.661826 -261.20471)
		(width 0.14478)
		(layer "In4.Cu")
		(net "M_J_CPU0_SB_CA<1>")
	)
	(segment
		(start 434.575204 -261.510018)
		(end 435.000146 -261.93496)
		(width 0.14478)
		(layer "In4.Cu")
		(net "M_J_CPU0_SB_CA<1>")
	)
	(segment
		(start 380.037848 -262.423402)
		(end 380.04623 -262.418576)
		(width 0.0889)
		(layer "In4.Cu")
		(net "M_J_CPU0_SB_CA<1>")
	)
	(segment
		(start 410.826458 -261.109714)
		(end 412.0769 -262.360156)
		(width 0.14478)
		(layer "In4.Cu")
		(net "M_J_CPU0_SB_CA<1>")
	)
	(segment
		(start 409.36418 -261.109714)
		(end 409.592526 -261.109714)
		(width 0.14478)
		(layer "In4.Cu")
		(net "M_J_CPU0_SB_CA<1>")
	)
	(segment
		(start 412.0769 -262.360156)
		(end 414.090104 -262.360156)
		(width 0.14478)
		(layer "In4.Cu")
		(net "M_J_CPU0_SB_CA<1>")
	)
	(segment
		(start 418.972746 -262.360156)
		(end 421.634158 -262.360156)
		(width 0.14478)
		(layer "In4.Cu")
		(net "M_J_CPU0_SB_CA<1>")
	)
	(segment
		(start 428.686976 -261.20471)
		(end 428.992284 -261.510018)
		(width 0.14478)
		(layer "In4.Cu")
		(net "M_J_CPU0_SB_CA<1>")
	)
	(segment
		(start 429.800004 -261.20471)
		(end 430.105312 -261.510018)
		(width 0.14478)
		(layer "In4.Cu")
		(net "M_J_CPU0_SB_CA<1>")
	)
	(segment
		(start 414.090104 -262.360156)
		(end 414.940242 -261.510018)
		(width 0.14478)
		(layer "In4.Cu")
		(net "M_J_CPU0_SB_CA<1>")
	)
	(segment
		(start 418.122608 -261.510018)
		(end 418.972746 -262.360156)
		(width 0.14478)
		(layer "In4.Cu")
		(net "M_J_CPU0_SB_CA<1>")
	)
	(segment
		(start 408.651202 -261.271258)
		(end 408.651202 -261.818628)
		(width 0.14478)
		(layer "In4.Cu")
		(net "M_J_CPU0_SB_CA<1>")
	)
	(segment
		(start 426.766228 -261.510018)
		(end 427.017434 -261.510018)
		(width 0.14478)
		(layer "In4.Cu")
		(net "M_J_CPU0_SB_CA<1>")
	)
	(segment
		(start 403.726142 -262.06577)
		(end 404.682198 -261.109714)
		(width 0.14478)
		(layer "In4.Cu")
		(net "M_J_CPU0_SB_CA<1>")
	)
	(segment
		(start 409.75407 -261.818628)
		(end 409.915614 -261.980172)
		(width 0.14478)
		(layer "In4.Cu")
		(net "M_J_CPU0_SB_CA<1>")
	)
	(segment
		(start 426.209714 -261.20471)
		(end 426.46092 -261.20471)
		(width 0.14478)
		(layer "In4.Cu")
		(net "M_J_CPU0_SB_CA<1>")
	)
	(segment
		(start 429.24349 -261.510018)
		(end 429.548798 -261.20471)
		(width 0.14478)
		(layer "In4.Cu")
		(net "M_J_CPU0_SB_CA<1>")
	)
	(segment
		(start 431.21834 -261.510018)
		(end 434.575204 -261.510018)
		(width 0.14478)
		(layer "In4.Cu")
		(net "M_J_CPU0_SB_CA<1>")
	)
	(segment
		(start 409.041092 -261.980172)
		(end 409.202636 -261.818628)
		(width 0.14478)
		(layer "In4.Cu")
		(net "M_J_CPU0_SB_CA<1>")
	)
	(segment
		(start 409.592526 -261.109714)
		(end 409.75407 -261.271258)
		(width 0.14478)
		(layer "In4.Cu")
		(net "M_J_CPU0_SB_CA<1>")
	)
	(segment
		(start 395.95933 -262.06577)
		(end 403.726142 -262.06577)
		(width 0.14478)
		(layer "In4.Cu")
		(net "M_J_CPU0_SB_CA<1>")
	)
	(segment
		(start 428.43577 -261.20471)
		(end 428.686976 -261.20471)
		(width 0.14478)
		(layer "In4.Cu")
		(net "M_J_CPU0_SB_CA<1>")
	)
	(segment
		(start 425.347892 -261.20471)
		(end 425.6532 -261.510018)
		(width 0.14478)
		(layer "In4.Cu")
		(net "M_J_CPU0_SB_CA<1>")
	)
	(segment
		(start 388.497826 -262.423402)
		(end 388.506208 -262.418576)
		(width 0.0889)
		(layer "In4.Cu")
		(net "M_J_CPU0_SB_CA<1>")
	)
	(segment
		(start 425.904406 -261.510018)
		(end 426.209714 -261.20471)
		(width 0.14478)
		(layer "In4.Cu")
		(net "M_J_CPU0_SB_CA<1>")
	)
	(segment
		(start 427.017434 -261.510018)
		(end 427.322742 -261.20471)
		(width 0.14478)
		(layer "In4.Cu")
		(net "M_J_CPU0_SB_CA<1>")
	)
	(segment
		(start 421.634158 -262.360156)
		(end 422.484296 -261.510018)
		(width 0.14478)
		(layer "In4.Cu")
		(net "M_J_CPU0_SB_CA<1>")
	)
	(segment
		(start 410.305504 -261.818628)
		(end 410.305504 -261.271258)
		(width 0.14478)
		(layer "In4.Cu")
		(net "M_J_CPU0_SB_CA<1>")
	)
	(segment
		(start 391.691876 -262.423402)
		(end 391.70229 -262.429498)
		(width 0.0889)
		(layer "In4.Cu")
		(net "M_J_CPU0_SB_CA<1>")
	)
	(segment
		(start 379.284738 -262.745982)
		(end 379.438916 -262.480552)
		(width 0.0889)
		(layer "In4.Cu")
		(net "M_J_CPU0_SB_CA<1>")
	)
	(segment
		(start 408.651202 -261.818628)
		(end 408.812746 -261.980172)
		(width 0.14478)
		(layer "In4.Cu")
		(net "M_J_CPU0_SB_CA<1>")
	)
	(segment
		(start 395.118336 -262.372602)
		(end 395.425168 -262.06577)
		(width 0.0889)
		(layer "In4.Cu")
		(net "M_J_CPU0_SB_CA<1>")
	)
	(segment
		(start 395.425168 -262.06577)
		(end 395.95933 -262.06577)
		(width 0.0889)
		(layer "In4.Cu")
		(net "M_J_CPU0_SB_CA<1>")
	)
	(segment
		(start 404.682198 -261.109714)
		(end 408.489658 -261.109714)
		(width 0.14478)
		(layer "In4.Cu")
		(net "M_J_CPU0_SB_CA<1>")
	)
	(segment
		(start 427.879256 -261.510018)
		(end 428.130462 -261.510018)
		(width 0.14478)
		(layer "In4.Cu")
		(net "M_J_CPU0_SB_CA<1>")
	)
	(segment
		(start 383.79781 -262.423402)
		(end 383.806192 -262.418576)
		(width 0.0889)
		(layer "In4.Cu")
		(net "M_J_CPU0_SB_CA<1>")
	)
	(segment
		(start 409.915614 -261.980172)
		(end 410.14396 -261.980172)
		(width 0.14478)
		(layer "In4.Cu")
		(net "M_J_CPU0_SB_CA<1>")
	)
	(segment
		(start 425.6532 -261.510018)
		(end 425.904406 -261.510018)
		(width 0.14478)
		(layer "In4.Cu")
		(net "M_J_CPU0_SB_CA<1>")
	)
	(segment
		(start 410.467048 -261.109714)
		(end 410.826458 -261.109714)
		(width 0.14478)
		(layer "In4.Cu")
		(net "M_J_CPU0_SB_CA<1>")
	)
	(segment
		(start 409.75407 -261.271258)
		(end 409.75407 -261.818628)
		(width 0.14478)
		(layer "In4.Cu")
		(net "M_J_CPU0_SB_CA<1>")
	)
	(segment
		(start 426.46092 -261.20471)
		(end 426.766228 -261.510018)
		(width 0.14478)
		(layer "In4.Cu")
		(net "M_J_CPU0_SB_CA<1>")
	)
	(arc
		(start 380.04623 -262.418576)
		(mid 380.229738 -262.373082)
		(end 380.41199 -262.423402)
		(width 0.0889)
		(layer "In4.Cu")
		(net "M_J_CPU0_SB_CA<1>")
	)
	(arc
		(start 392.258042 -262.423402)
		(mid 392.440547 -262.372925)
		(end 392.62431 -262.418576)
		(width 0.0889)
		(layer "In4.Cu")
		(net "M_J_CPU0_SB_CA<1>")
	)
	(arc
		(start 380.977902 -262.423402)
		(mid 381.164846 -262.373147)
		(end 381.35179 -262.423402)
		(width 0.0889)
		(layer "In4.Cu")
		(net "M_J_CPU0_SB_CA<1>")
	)
	(arc
		(start 385.677664 -262.423402)
		(mid 385.859915 -262.373052)
		(end 386.043424 -262.418576)
		(width 0.0889)
		(layer "In4.Cu")
		(net "M_J_CPU0_SB_CA<1>")
	)
	(arc
		(start 389.43788 -262.423402)
		(mid 389.624824 -262.373147)
		(end 389.811768 -262.423402)
		(width 0.0889)
		(layer "In4.Cu")
		(net "M_J_CPU0_SB_CA<1>")
	)
	(arc
		(start 390.751822 -262.423402)
		(mid 391.034778 -262.499579)
		(end 391.317734 -262.423402)
		(width 0.0889)
		(layer "In4.Cu")
		(net "M_J_CPU0_SB_CA<1>")
	)
	(arc
		(start 389.811768 -262.423402)
		(mid 390.094724 -262.499579)
		(end 390.37768 -262.423402)
		(width 0.0889)
		(layer "In4.Cu")
		(net "M_J_CPU0_SB_CA<1>")
	)
	(arc
		(start 392.632692 -262.423402)
		(mid 392.91212 -262.499568)
		(end 393.192508 -262.426958)
		(width 0.0889)
		(layer "In4.Cu")
		(net "M_J_CPU0_SB_CA<1>")
	)
	(arc
		(start 390.37768 -262.423402)
		(mid 390.559931 -262.373052)
		(end 390.74344 -262.418576)
		(width 0.0889)
		(layer "In4.Cu")
		(net "M_J_CPU0_SB_CA<1>")
	)
	(arc
		(start 393.192508 -262.426958)
		(mid 393.28494 -262.386676)
		(end 393.384786 -262.372602)
		(width 0.0889)
		(layer "In4.Cu")
		(net "M_J_CPU0_SB_CA<1>")
	)
	(arc
		(start 385.111752 -262.423402)
		(mid 385.394708 -262.499579)
		(end 385.677664 -262.423402)
		(width 0.0889)
		(layer "In4.Cu")
		(net "M_J_CPU0_SB_CA<1>")
	)
	(arc
		(start 384.171952 -262.423402)
		(mid 384.454908 -262.499579)
		(end 384.737864 -262.423402)
		(width 0.0889)
		(layer "In4.Cu")
		(net "M_J_CPU0_SB_CA<1>")
	)
	(arc
		(start 381.917702 -262.423402)
		(mid 382.099953 -262.373052)
		(end 382.283462 -262.418576)
		(width 0.0889)
		(layer "In4.Cu")
		(net "M_J_CPU0_SB_CA<1>")
	)
	(arc
		(start 383.231898 -262.423402)
		(mid 383.514854 -262.499579)
		(end 383.79781 -262.423402)
		(width 0.0889)
		(layer "In4.Cu")
		(net "M_J_CPU0_SB_CA<1>")
	)
	(arc
		(start 379.535182 -262.455152)
		(mid 379.790247 -262.498503)
		(end 380.037848 -262.423402)
		(width 0.0889)
		(layer "In4.Cu")
		(net "M_J_CPU0_SB_CA<1>")
	)
	(arc
		(start 381.35179 -262.423402)
		(mid 381.634746 -262.499579)
		(end 381.917702 -262.423402)
		(width 0.0889)
		(layer "In4.Cu")
		(net "M_J_CPU0_SB_CA<1>")
	)
	(arc
		(start 380.41199 -262.423402)
		(mid 380.694946 -262.499579)
		(end 380.977902 -262.423402)
		(width 0.0889)
		(layer "In4.Cu")
		(net "M_J_CPU0_SB_CA<1>")
	)
	(arc
		(start 387.566154 -262.418576)
		(mid 387.749662 -262.373082)
		(end 387.931914 -262.423402)
		(width 0.0889)
		(layer "In4.Cu")
		(net "M_J_CPU0_SB_CA<1>")
	)
	(arc
		(start 382.291844 -262.423402)
		(mid 382.5748 -262.499579)
		(end 382.857756 -262.423402)
		(width 0.0889)
		(layer "In4.Cu")
		(net "M_J_CPU0_SB_CA<1>")
	)
	(arc
		(start 384.737864 -262.423402)
		(mid 384.924808 -262.373147)
		(end 385.111752 -262.423402)
		(width 0.0889)
		(layer "In4.Cu")
		(net "M_J_CPU0_SB_CA<1>")
	)
	(arc
		(start 391.326116 -262.418576)
		(mid 391.509624 -262.373082)
		(end 391.691876 -262.423402)
		(width 0.0889)
		(layer "In4.Cu")
		(net "M_J_CPU0_SB_CA<1>")
	)
	(arc
		(start 386.99186 -262.423402)
		(mid 387.274816 -262.499579)
		(end 387.557772 -262.423402)
		(width 0.0889)
		(layer "In4.Cu")
		(net "M_J_CPU0_SB_CA<1>")
	)
	(arc
		(start 391.70229 -262.429498)
		(mid 391.980976 -262.499718)
		(end 392.258042 -262.423402)
		(width 0.0889)
		(layer "In4.Cu")
		(net "M_J_CPU0_SB_CA<1>")
	)
	(arc
		(start 388.506208 -262.418576)
		(mid 388.689716 -262.373082)
		(end 388.871968 -262.423402)
		(width 0.0889)
		(layer "In4.Cu")
		(net "M_J_CPU0_SB_CA<1>")
	)
	(arc
		(start 387.931914 -262.423402)
		(mid 388.21487 -262.499579)
		(end 388.497826 -262.423402)
		(width 0.0889)
		(layer "In4.Cu")
		(net "M_J_CPU0_SB_CA<1>")
	)
	(arc
		(start 382.866138 -262.418576)
		(mid 383.049646 -262.373082)
		(end 383.231898 -262.423402)
		(width 0.0889)
		(layer "In4.Cu")
		(net "M_J_CPU0_SB_CA<1>")
	)
	(arc
		(start 386.051806 -262.423402)
		(mid 386.334762 -262.499579)
		(end 386.617718 -262.423402)
		(width 0.0889)
		(layer "In4.Cu")
		(net "M_J_CPU0_SB_CA<1>")
	)
	(arc
		(start 386.617718 -262.423402)
		(mid 386.799969 -262.373052)
		(end 386.983478 -262.418576)
		(width 0.0889)
		(layer "In4.Cu")
		(net "M_J_CPU0_SB_CA<1>")
	)
	(arc
		(start 383.806192 -262.418576)
		(mid 383.9897 -262.373082)
		(end 384.171952 -262.423402)
		(width 0.0889)
		(layer "In4.Cu")
		(net "M_J_CPU0_SB_CA<1>")
	)
	(arc
		(start 388.871968 -262.423402)
		(mid 389.154924 -262.499579)
		(end 389.43788 -262.423402)
		(width 0.0889)
		(layer "In4.Cu")
		(net "M_J_CPU0_SB_CA<1>")
	)
	(segment
		(start 379.28804 -261.670038)
		(end 379.754892 -261.935976)
		(width 0.10668)
		(layer "F.Cu")
		(net "M_J_CPU0_SB_CA<0>")
	)
	(segment
		(start 392.718036 -262.25246)
		(end 392.72845 -262.258556)
		(width 0.0889)
		(layer "In4.Cu")
		(net "M_J_CPU0_SB_CA<0>")
	)
	(segment
		(start 389.90778 -262.258556)
		(end 389.916162 -262.263382)
		(width 0.0889)
		(layer "In4.Cu")
		(net "M_J_CPU0_SB_CA<0>")
	)
	(segment
		(start 386.147818 -262.258556)
		(end 386.1562 -262.263382)
		(width 0.0889)
		(layer "In4.Cu")
		(net "M_J_CPU0_SB_CA<0>")
	)
	(segment
		(start 422.577006 -260.660134)
		(end 438.675272 -260.660134)
		(width 0.14478)
		(layer "In4.Cu")
		(net "M_J_CPU0_SB_CA<0>")
	)
	(segment
		(start 393.5222 -262.142732)
		(end 395.042136 -262.142732)
		(width 0.0889)
		(layer "In4.Cu")
		(net "M_J_CPU0_SB_CA<0>")
	)
	(segment
		(start 395.042136 -262.142732)
		(end 395.573758 -261.61111)
		(width 0.0889)
		(layer "In4.Cu")
		(net "M_J_CPU0_SB_CA<0>")
	)
	(segment
		(start 414.183068 -261.510018)
		(end 415.032952 -260.660134)
		(width 0.14478)
		(layer "In4.Cu")
		(net "M_J_CPU0_SB_CA<0>")
	)
	(segment
		(start 379.933454 -262.263382)
		(end 379.941836 -262.258556)
		(width 0.0889)
		(layer "In4.Cu")
		(net "M_J_CPU0_SB_CA<0>")
	)
	(segment
		(start 404.495762 -260.660134)
		(end 411.291278 -260.660134)
		(width 0.14478)
		(layer "In4.Cu")
		(net "M_J_CPU0_SB_CA<0>")
	)
	(segment
		(start 384.63347 -262.263382)
		(end 384.641852 -262.258556)
		(width 0.0889)
		(layer "In4.Cu")
		(net "M_J_CPU0_SB_CA<0>")
	)
	(segment
		(start 389.333486 -262.263382)
		(end 389.341868 -262.258556)
		(width 0.0889)
		(layer "In4.Cu")
		(net "M_J_CPU0_SB_CA<0>")
	)
	(segment
		(start 391.787634 -262.258556)
		(end 391.796016 -262.263382)
		(width 0.0889)
		(layer "In4.Cu")
		(net "M_J_CPU0_SB_CA<0>")
	)
	(segment
		(start 388.393432 -262.263382)
		(end 388.401814 -262.258556)
		(width 0.0889)
		(layer "In4.Cu")
		(net "M_J_CPU0_SB_CA<0>")
	)
	(segment
		(start 379.600714 -262.201406)
		(end 379.623066 -262.284718)
		(width 0.0889)
		(layer "In4.Cu")
		(net "M_J_CPU0_SB_CA<0>")
	)
	(segment
		(start 395.96822 -261.61111)
		(end 403.544786 -261.61111)
		(width 0.14478)
		(layer "In4.Cu")
		(net "M_J_CPU0_SB_CA<0>")
	)
	(segment
		(start 383.693416 -262.263382)
		(end 383.701798 -262.258556)
		(width 0.0889)
		(layer "In4.Cu")
		(net "M_J_CPU0_SB_CA<0>")
	)
	(segment
		(start 418.907468 -261.510018)
		(end 421.727122 -261.510018)
		(width 0.14478)
		(layer "In4.Cu")
		(net "M_J_CPU0_SB_CA<0>")
	)
	(segment
		(start 421.727122 -261.510018)
		(end 422.577006 -260.660134)
		(width 0.14478)
		(layer "In4.Cu")
		(net "M_J_CPU0_SB_CA<0>")
	)
	(segment
		(start 412.141162 -261.510018)
		(end 414.183068 -261.510018)
		(width 0.14478)
		(layer "In4.Cu")
		(net "M_J_CPU0_SB_CA<0>")
	)
	(segment
		(start 418.057584 -260.660134)
		(end 418.907468 -261.510018)
		(width 0.14478)
		(layer "In4.Cu")
		(net "M_J_CPU0_SB_CA<0>")
	)
	(segment
		(start 438.675272 -260.660134)
		(end 439.100214 -261.085076)
		(width 0.14478)
		(layer "In4.Cu")
		(net "M_J_CPU0_SB_CA<0>")
	)
	(segment
		(start 415.032952 -260.660134)
		(end 418.057584 -260.660134)
		(width 0.14478)
		(layer "In4.Cu")
		(net "M_J_CPU0_SB_CA<0>")
	)
	(segment
		(start 379.754892 -261.935976)
		(end 379.600714 -262.201406)
		(width 0.0889)
		(layer "In4.Cu")
		(net "M_J_CPU0_SB_CA<0>")
	)
	(segment
		(start 395.573758 -261.61111)
		(end 395.96822 -261.61111)
		(width 0.0889)
		(layer "In4.Cu")
		(net "M_J_CPU0_SB_CA<0>")
	)
	(segment
		(start 411.291278 -260.660134)
		(end 412.141162 -261.510018)
		(width 0.14478)
		(layer "In4.Cu")
		(net "M_J_CPU0_SB_CA<0>")
	)
	(segment
		(start 381.447802 -262.258556)
		(end 381.456184 -262.263382)
		(width 0.0889)
		(layer "In4.Cu")
		(net "M_J_CPU0_SB_CA<0>")
	)
	(segment
		(start 403.544786 -261.61111)
		(end 404.495762 -260.660134)
		(width 0.14478)
		(layer "In4.Cu")
		(net "M_J_CPU0_SB_CA<0>")
	)
	(segment
		(start 385.207764 -262.258556)
		(end 385.216146 -262.263382)
		(width 0.0889)
		(layer "In4.Cu")
		(net "M_J_CPU0_SB_CA<0>")
	)
	(segment
		(start 380.873508 -262.263382)
		(end 380.88189 -262.258556)
		(width 0.0889)
		(layer "In4.Cu")
		(net "M_J_CPU0_SB_CA<0>")
	)
	(arc
		(start 389.916162 -262.263382)
		(mid 390.09967 -262.308876)
		(end 390.281922 -262.258556)
		(width 0.0889)
		(layer "In4.Cu")
		(net "M_J_CPU0_SB_CA<0>")
	)
	(arc
		(start 384.26771 -262.258556)
		(mid 384.449961 -262.308906)
		(end 384.63347 -262.263382)
		(width 0.0889)
		(layer "In4.Cu")
		(net "M_J_CPU0_SB_CA<0>")
	)
	(arc
		(start 381.821944 -262.258556)
		(mid 382.1049 -262.182379)
		(end 382.387856 -262.258556)
		(width 0.0889)
		(layer "In4.Cu")
		(net "M_J_CPU0_SB_CA<0>")
	)
	(arc
		(start 387.46176 -262.258556)
		(mid 387.744716 -262.182379)
		(end 388.027672 -262.258556)
		(width 0.0889)
		(layer "In4.Cu")
		(net "M_J_CPU0_SB_CA<0>")
	)
	(arc
		(start 382.387856 -262.258556)
		(mid 382.5748 -262.308811)
		(end 382.761744 -262.258556)
		(width 0.0889)
		(layer "In4.Cu")
		(net "M_J_CPU0_SB_CA<0>")
	)
	(arc
		(start 392.72845 -262.258556)
		(mid 392.9061 -262.308816)
		(end 393.086082 -262.2677)
		(width 0.0889)
		(layer "In4.Cu")
		(net "M_J_CPU0_SB_CA<0>")
	)
	(arc
		(start 388.027672 -262.258556)
		(mid 388.209923 -262.308906)
		(end 388.393432 -262.263382)
		(width 0.0889)
		(layer "In4.Cu")
		(net "M_J_CPU0_SB_CA<0>")
	)
	(arc
		(start 392.162284 -262.258556)
		(mid 392.439351 -262.182285)
		(end 392.718036 -262.25246)
		(width 0.0889)
		(layer "In4.Cu")
		(net "M_J_CPU0_SB_CA<0>")
	)
	(arc
		(start 380.507748 -262.258556)
		(mid 380.689999 -262.308906)
		(end 380.873508 -262.263382)
		(width 0.0889)
		(layer "In4.Cu")
		(net "M_J_CPU0_SB_CA<0>")
	)
	(arc
		(start 390.847834 -262.258556)
		(mid 391.034778 -262.308811)
		(end 391.221722 -262.258556)
		(width 0.0889)
		(layer "In4.Cu")
		(net "M_J_CPU0_SB_CA<0>")
	)
	(arc
		(start 389.341868 -262.258556)
		(mid 389.624824 -262.182379)
		(end 389.90778 -262.258556)
		(width 0.0889)
		(layer "In4.Cu")
		(net "M_J_CPU0_SB_CA<0>")
	)
	(arc
		(start 382.761744 -262.258556)
		(mid 383.0447 -262.182379)
		(end 383.327656 -262.258556)
		(width 0.0889)
		(layer "In4.Cu")
		(net "M_J_CPU0_SB_CA<0>")
	)
	(arc
		(start 388.401814 -262.258556)
		(mid 388.68477 -262.182379)
		(end 388.967726 -262.258556)
		(width 0.0889)
		(layer "In4.Cu")
		(net "M_J_CPU0_SB_CA<0>")
	)
	(arc
		(start 393.086082 -262.2677)
		(mid 393.295365 -262.17459)
		(end 393.5222 -262.142732)
		(width 0.0889)
		(layer "In4.Cu")
		(net "M_J_CPU0_SB_CA<0>")
	)
	(arc
		(start 379.623066 -262.284718)
		(mid 379.780576 -262.307916)
		(end 379.933454 -262.263382)
		(width 0.0889)
		(layer "In4.Cu")
		(net "M_J_CPU0_SB_CA<0>")
	)
	(arc
		(start 385.216146 -262.263382)
		(mid 385.399654 -262.308876)
		(end 385.581906 -262.258556)
		(width 0.0889)
		(layer "In4.Cu")
		(net "M_J_CPU0_SB_CA<0>")
	)
	(arc
		(start 388.967726 -262.258556)
		(mid 389.149977 -262.308906)
		(end 389.333486 -262.263382)
		(width 0.0889)
		(layer "In4.Cu")
		(net "M_J_CPU0_SB_CA<0>")
	)
	(arc
		(start 386.52196 -262.258556)
		(mid 386.804916 -262.182379)
		(end 387.087872 -262.258556)
		(width 0.0889)
		(layer "In4.Cu")
		(net "M_J_CPU0_SB_CA<0>")
	)
	(arc
		(start 391.221722 -262.258556)
		(mid 391.504678 -262.182379)
		(end 391.787634 -262.258556)
		(width 0.0889)
		(layer "In4.Cu")
		(net "M_J_CPU0_SB_CA<0>")
	)
	(arc
		(start 380.88189 -262.258556)
		(mid 381.164846 -262.182379)
		(end 381.447802 -262.258556)
		(width 0.0889)
		(layer "In4.Cu")
		(net "M_J_CPU0_SB_CA<0>")
	)
	(arc
		(start 383.327656 -262.258556)
		(mid 383.509907 -262.308906)
		(end 383.693416 -262.263382)
		(width 0.0889)
		(layer "In4.Cu")
		(net "M_J_CPU0_SB_CA<0>")
	)
	(arc
		(start 391.796016 -262.263382)
		(mid 391.979778 -262.308998)
		(end 392.162284 -262.258556)
		(width 0.0889)
		(layer "In4.Cu")
		(net "M_J_CPU0_SB_CA<0>")
	)
	(arc
		(start 386.1562 -262.263382)
		(mid 386.339708 -262.308876)
		(end 386.52196 -262.258556)
		(width 0.0889)
		(layer "In4.Cu")
		(net "M_J_CPU0_SB_CA<0>")
	)
	(arc
		(start 387.087872 -262.258556)
		(mid 387.274816 -262.308811)
		(end 387.46176 -262.258556)
		(width 0.0889)
		(layer "In4.Cu")
		(net "M_J_CPU0_SB_CA<0>")
	)
	(arc
		(start 384.641852 -262.258556)
		(mid 384.924808 -262.182379)
		(end 385.207764 -262.258556)
		(width 0.0889)
		(layer "In4.Cu")
		(net "M_J_CPU0_SB_CA<0>")
	)
	(arc
		(start 379.941836 -262.258556)
		(mid 380.224792 -262.182379)
		(end 380.507748 -262.258556)
		(width 0.0889)
		(layer "In4.Cu")
		(net "M_J_CPU0_SB_CA<0>")
	)
	(arc
		(start 381.456184 -262.263382)
		(mid 381.639692 -262.308876)
		(end 381.821944 -262.258556)
		(width 0.0889)
		(layer "In4.Cu")
		(net "M_J_CPU0_SB_CA<0>")
	)
	(arc
		(start 390.281922 -262.258556)
		(mid 390.564878 -262.182379)
		(end 390.847834 -262.258556)
		(width 0.0889)
		(layer "In4.Cu")
		(net "M_J_CPU0_SB_CA<0>")
	)
	(arc
		(start 383.701798 -262.258556)
		(mid 383.984754 -262.182379)
		(end 384.26771 -262.258556)
		(width 0.0889)
		(layer "In4.Cu")
		(net "M_J_CPU0_SB_CA<0>")
	)
	(arc
		(start 385.581906 -262.258556)
		(mid 385.864862 -262.182379)
		(end 386.147818 -262.258556)
		(width 0.0889)
		(layer "In4.Cu")
		(net "M_J_CPU0_SB_CA<0>")
	)
	(segment
		(start 379.28804 -266.530074)
		(end 379.754892 -266.796012)
		(width 0.10668)
		(layer "F.Cu")
		(net "M_J_CPU0_SA_RSP<0>")
	)
	(segment
		(start 391.787634 -267.118592)
		(end 391.796016 -267.123418)
		(width 0.0889)
		(layer "In4.Cu")
		(net "M_J_CPU0_SA_RSP<0>")
	)
	(segment
		(start 384.63347 -267.123418)
		(end 384.641852 -267.118592)
		(width 0.0889)
		(layer "In4.Cu")
		(net "M_J_CPU0_SA_RSP<0>")
	)
	(segment
		(start 381.447802 -267.118592)
		(end 381.456184 -267.123418)
		(width 0.0889)
		(layer "In4.Cu")
		(net "M_J_CPU0_SA_RSP<0>")
	)
	(segment
		(start 389.333486 -267.123418)
		(end 389.341868 -267.118592)
		(width 0.0889)
		(layer "In4.Cu")
		(net "M_J_CPU0_SA_RSP<0>")
	)
	(segment
		(start 436.96382 -269.160244)
		(end 439.100214 -269.585186)
		(width 0.11684)
		(layer "In4.Cu")
		(net "M_J_CPU0_SA_RSP<0>")
	)
	(segment
		(start 395.878558 -266.14374)
		(end 408.358848 -266.14374)
		(width 0.11684)
		(layer "In4.Cu")
		(net "M_J_CPU0_SA_RSP<0>")
	)
	(segment
		(start 380.873508 -267.123418)
		(end 380.88189 -267.118592)
		(width 0.0889)
		(layer "In4.Cu")
		(net "M_J_CPU0_SA_RSP<0>")
	)
	(segment
		(start 385.207764 -267.118592)
		(end 385.216146 -267.123418)
		(width 0.0889)
		(layer "In4.Cu")
		(net "M_J_CPU0_SA_RSP<0>")
	)
	(segment
		(start 420.878254 -270.010382)
		(end 422.930828 -269.160244)
		(width 0.11684)
		(layer "In4.Cu")
		(net "M_J_CPU0_SA_RSP<0>")
	)
	(segment
		(start 379.754892 -266.796012)
		(end 379.600714 -267.061442)
		(width 0.0889)
		(layer "In4.Cu")
		(net "M_J_CPU0_SA_RSP<0>")
	)
	(segment
		(start 395.247114 -266.10437)
		(end 395.286484 -266.14374)
		(width 0.0889)
		(layer "In4.Cu")
		(net "M_J_CPU0_SA_RSP<0>")
	)
	(segment
		(start 379.933454 -267.123418)
		(end 379.941836 -267.118592)
		(width 0.0889)
		(layer "In4.Cu")
		(net "M_J_CPU0_SA_RSP<0>")
	)
	(segment
		(start 422.930828 -269.160244)
		(end 436.96382 -269.160244)
		(width 0.11684)
		(layer "In4.Cu")
		(net "M_J_CPU0_SA_RSP<0>")
	)
	(segment
		(start 383.693416 -267.123418)
		(end 383.701798 -267.118592)
		(width 0.0889)
		(layer "In4.Cu")
		(net "M_J_CPU0_SA_RSP<0>")
	)
	(segment
		(start 388.393432 -267.123418)
		(end 388.401814 -267.118592)
		(width 0.0889)
		(layer "In4.Cu")
		(net "M_J_CPU0_SA_RSP<0>")
	)
	(segment
		(start 417.765484 -269.160244)
		(end 419.818058 -270.010382)
		(width 0.11684)
		(layer "In4.Cu")
		(net "M_J_CPU0_SA_RSP<0>")
	)
	(segment
		(start 413.366204 -270.010382)
		(end 415.418778 -269.160244)
		(width 0.11684)
		(layer "In4.Cu")
		(net "M_J_CPU0_SA_RSP<0>")
	)
	(segment
		(start 394.109448 -266.10437)
		(end 395.247114 -266.10437)
		(width 0.0889)
		(layer "In4.Cu")
		(net "M_J_CPU0_SA_RSP<0>")
	)
	(segment
		(start 386.147818 -267.118592)
		(end 386.1562 -267.123418)
		(width 0.0889)
		(layer "In4.Cu")
		(net "M_J_CPU0_SA_RSP<0>")
	)
	(segment
		(start 389.90778 -267.118592)
		(end 389.916162 -267.123418)
		(width 0.0889)
		(layer "In4.Cu")
		(net "M_J_CPU0_SA_RSP<0>")
	)
	(segment
		(start 412.22549 -270.010382)
		(end 413.366204 -270.010382)
		(width 0.11684)
		(layer "In4.Cu")
		(net "M_J_CPU0_SA_RSP<0>")
	)
	(segment
		(start 393.086082 -267.127736)
		(end 394.109448 -266.10437)
		(width 0.0889)
		(layer "In4.Cu")
		(net "M_J_CPU0_SA_RSP<0>")
	)
	(segment
		(start 419.818058 -270.010382)
		(end 420.878254 -270.010382)
		(width 0.11684)
		(layer "In4.Cu")
		(net "M_J_CPU0_SA_RSP<0>")
	)
	(segment
		(start 408.358848 -266.14374)
		(end 412.22549 -270.010382)
		(width 0.11684)
		(layer "In4.Cu")
		(net "M_J_CPU0_SA_RSP<0>")
	)
	(segment
		(start 415.418778 -269.160244)
		(end 417.765484 -269.160244)
		(width 0.11684)
		(layer "In4.Cu")
		(net "M_J_CPU0_SA_RSP<0>")
	)
	(segment
		(start 395.286484 -266.14374)
		(end 395.878558 -266.14374)
		(width 0.0889)
		(layer "In4.Cu")
		(net "M_J_CPU0_SA_RSP<0>")
	)
	(segment
		(start 379.600714 -267.061442)
		(end 379.623066 -267.144754)
		(width 0.0889)
		(layer "In4.Cu")
		(net "M_J_CPU0_SA_RSP<0>")
	)
	(segment
		(start 392.718036 -267.112496)
		(end 392.72845 -267.118592)
		(width 0.0889)
		(layer "In4.Cu")
		(net "M_J_CPU0_SA_RSP<0>")
	)
	(arc
		(start 385.581906 -267.118592)
		(mid 385.864862 -267.042415)
		(end 386.147818 -267.118592)
		(width 0.0889)
		(layer "In4.Cu")
		(net "M_J_CPU0_SA_RSP<0>")
	)
	(arc
		(start 391.221722 -267.118592)
		(mid 391.504678 -267.042415)
		(end 391.787634 -267.118592)
		(width 0.0889)
		(layer "In4.Cu")
		(net "M_J_CPU0_SA_RSP<0>")
	)
	(arc
		(start 389.341868 -267.118592)
		(mid 389.624824 -267.042415)
		(end 389.90778 -267.118592)
		(width 0.0889)
		(layer "In4.Cu")
		(net "M_J_CPU0_SA_RSP<0>")
	)
	(arc
		(start 383.327656 -267.118592)
		(mid 383.509907 -267.168942)
		(end 383.693416 -267.123418)
		(width 0.0889)
		(layer "In4.Cu")
		(net "M_J_CPU0_SA_RSP<0>")
	)
	(arc
		(start 387.087872 -267.118592)
		(mid 387.274816 -267.168847)
		(end 387.46176 -267.118592)
		(width 0.0889)
		(layer "In4.Cu")
		(net "M_J_CPU0_SA_RSP<0>")
	)
	(arc
		(start 389.916162 -267.123418)
		(mid 390.09967 -267.168912)
		(end 390.281922 -267.118592)
		(width 0.0889)
		(layer "In4.Cu")
		(net "M_J_CPU0_SA_RSP<0>")
	)
	(arc
		(start 379.941836 -267.118592)
		(mid 380.224792 -267.042415)
		(end 380.507748 -267.118592)
		(width 0.0889)
		(layer "In4.Cu")
		(net "M_J_CPU0_SA_RSP<0>")
	)
	(arc
		(start 380.88189 -267.118592)
		(mid 381.164846 -267.042415)
		(end 381.447802 -267.118592)
		(width 0.0889)
		(layer "In4.Cu")
		(net "M_J_CPU0_SA_RSP<0>")
	)
	(arc
		(start 387.46176 -267.118592)
		(mid 387.744716 -267.042415)
		(end 388.027672 -267.118592)
		(width 0.0889)
		(layer "In4.Cu")
		(net "M_J_CPU0_SA_RSP<0>")
	)
	(arc
		(start 388.967726 -267.118592)
		(mid 389.149977 -267.168942)
		(end 389.333486 -267.123418)
		(width 0.0889)
		(layer "In4.Cu")
		(net "M_J_CPU0_SA_RSP<0>")
	)
	(arc
		(start 379.623066 -267.144754)
		(mid 379.780576 -267.167952)
		(end 379.933454 -267.123418)
		(width 0.0889)
		(layer "In4.Cu")
		(net "M_J_CPU0_SA_RSP<0>")
	)
	(arc
		(start 390.847834 -267.118592)
		(mid 391.034778 -267.168847)
		(end 391.221722 -267.118592)
		(width 0.0889)
		(layer "In4.Cu")
		(net "M_J_CPU0_SA_RSP<0>")
	)
	(arc
		(start 383.701798 -267.118592)
		(mid 383.984754 -267.042415)
		(end 384.26771 -267.118592)
		(width 0.0889)
		(layer "In4.Cu")
		(net "M_J_CPU0_SA_RSP<0>")
	)
	(arc
		(start 392.72845 -267.118592)
		(mid 392.9061 -267.168852)
		(end 393.086082 -267.127736)
		(width 0.0889)
		(layer "In4.Cu")
		(net "M_J_CPU0_SA_RSP<0>")
	)
	(arc
		(start 386.52196 -267.118592)
		(mid 386.804916 -267.042415)
		(end 387.087872 -267.118592)
		(width 0.0889)
		(layer "In4.Cu")
		(net "M_J_CPU0_SA_RSP<0>")
	)
	(arc
		(start 385.216146 -267.123418)
		(mid 385.399654 -267.168912)
		(end 385.581906 -267.118592)
		(width 0.0889)
		(layer "In4.Cu")
		(net "M_J_CPU0_SA_RSP<0>")
	)
	(arc
		(start 391.796016 -267.123418)
		(mid 391.979778 -267.169034)
		(end 392.162284 -267.118592)
		(width 0.0889)
		(layer "In4.Cu")
		(net "M_J_CPU0_SA_RSP<0>")
	)
	(arc
		(start 384.26771 -267.118592)
		(mid 384.449961 -267.168942)
		(end 384.63347 -267.123418)
		(width 0.0889)
		(layer "In4.Cu")
		(net "M_J_CPU0_SA_RSP<0>")
	)
	(arc
		(start 390.281922 -267.118592)
		(mid 390.564878 -267.042415)
		(end 390.847834 -267.118592)
		(width 0.0889)
		(layer "In4.Cu")
		(net "M_J_CPU0_SA_RSP<0>")
	)
	(arc
		(start 384.641852 -267.118592)
		(mid 384.924808 -267.042415)
		(end 385.207764 -267.118592)
		(width 0.0889)
		(layer "In4.Cu")
		(net "M_J_CPU0_SA_RSP<0>")
	)
	(arc
		(start 381.821944 -267.118592)
		(mid 382.1049 -267.042415)
		(end 382.387856 -267.118592)
		(width 0.0889)
		(layer "In4.Cu")
		(net "M_J_CPU0_SA_RSP<0>")
	)
	(arc
		(start 380.507748 -267.118592)
		(mid 380.689999 -267.168942)
		(end 380.873508 -267.123418)
		(width 0.0889)
		(layer "In4.Cu")
		(net "M_J_CPU0_SA_RSP<0>")
	)
	(arc
		(start 382.387856 -267.118592)
		(mid 382.5748 -267.168847)
		(end 382.761744 -267.118592)
		(width 0.0889)
		(layer "In4.Cu")
		(net "M_J_CPU0_SA_RSP<0>")
	)
	(arc
		(start 382.761744 -267.118592)
		(mid 383.0447 -267.042415)
		(end 383.327656 -267.118592)
		(width 0.0889)
		(layer "In4.Cu")
		(net "M_J_CPU0_SA_RSP<0>")
	)
	(arc
		(start 381.456184 -267.123418)
		(mid 381.639692 -267.168912)
		(end 381.821944 -267.118592)
		(width 0.0889)
		(layer "In4.Cu")
		(net "M_J_CPU0_SA_RSP<0>")
	)
	(arc
		(start 386.1562 -267.123418)
		(mid 386.339708 -267.168912)
		(end 386.52196 -267.118592)
		(width 0.0889)
		(layer "In4.Cu")
		(net "M_J_CPU0_SA_RSP<0>")
	)
	(arc
		(start 388.027672 -267.118592)
		(mid 388.209923 -267.168942)
		(end 388.393432 -267.123418)
		(width 0.0889)
		(layer "In4.Cu")
		(net "M_J_CPU0_SA_RSP<0>")
	)
	(arc
		(start 392.162284 -267.118592)
		(mid 392.439351 -267.042321)
		(end 392.718036 -267.112496)
		(width 0.0889)
		(layer "In4.Cu")
		(net "M_J_CPU0_SA_RSP<0>")
	)
	(arc
		(start 388.401814 -267.118592)
		(mid 388.68477 -267.042415)
		(end 388.967726 -267.118592)
		(width 0.0889)
		(layer "In4.Cu")
		(net "M_J_CPU0_SA_RSP<0>")
	)
	(segment
		(start 378.988066 -256.090166)
		(end 379.454918 -255.824228)
		(width 0.10668)
		(layer "F.Cu")
		(net "M_J_CPU0_SA_PAR")
	)
	(segment
		(start 388.093458 -255.496822)
		(end 388.10184 -255.501648)
		(width 0.0889)
		(layer "In4.Cu")
		(net "M_J_CPU0_SA_PAR")
	)
	(segment
		(start 383.393442 -255.496822)
		(end 383.401824 -255.501648)
		(width 0.0889)
		(layer "In4.Cu")
		(net "M_J_CPU0_SA_PAR")
	)
	(segment
		(start 398.549876 -256.62509)
		(end 400.009614 -255.165352)
		(width 0.14478)
		(layer "In4.Cu")
		(net "M_J_CPU0_SA_PAR")
	)
	(segment
		(start 389.033512 -255.496822)
		(end 389.041894 -255.501648)
		(width 0.0889)
		(layer "In4.Cu")
		(net "M_J_CPU0_SA_PAR")
	)
	(segment
		(start 392.413998 -255.510284)
		(end 392.42873 -255.501648)
		(width 0.0889)
		(layer "In4.Cu")
		(net "M_J_CPU0_SA_PAR")
	)
	(segment
		(start 392.802364 -255.501902)
		(end 392.818112 -255.511046)
		(width 0.0889)
		(layer "In4.Cu")
		(net "M_J_CPU0_SA_PAR")
	)
	(segment
		(start 393.090654 -255.584452)
		(end 393.511278 -255.584452)
		(width 0.0889)
		(layer "In4.Cu")
		(net "M_J_CPU0_SA_PAR")
	)
	(segment
		(start 380.207774 -255.501648)
		(end 380.216156 -255.496822)
		(width 0.0889)
		(layer "In4.Cu")
		(net "M_J_CPU0_SA_PAR")
	)
	(segment
		(start 379.454918 -255.824228)
		(end 379.30074 -255.558798)
		(width 0.0889)
		(layer "In4.Cu")
		(net "M_J_CPU0_SA_PAR")
	)
	(segment
		(start 391.48766 -255.501648)
		(end 391.496042 -255.496822)
		(width 0.0889)
		(layer "In4.Cu")
		(net "M_J_CPU0_SA_PAR")
	)
	(segment
		(start 432.149504 -255.74371)
		(end 432.499516 -255.393698)
		(width 0.14478)
		(layer "In4.Cu")
		(net "M_J_CPU0_SA_PAR")
	)
	(segment
		(start 432.499516 -255.393698)
		(end 433.255166 -253.56947)
		(width 0.14478)
		(layer "In4.Cu")
		(net "M_J_CPU0_SA_PAR")
	)
	(segment
		(start 384.90779 -255.501648)
		(end 384.916172 -255.496822)
		(width 0.0889)
		(layer "In4.Cu")
		(net "M_J_CPU0_SA_PAR")
	)
	(segment
		(start 395.664436 -256.62509)
		(end 398.549876 -256.62509)
		(width 0.14478)
		(layer "In4.Cu")
		(net "M_J_CPU0_SA_PAR")
	)
	(segment
		(start 394.551916 -256.62509)
		(end 395.664436 -256.62509)
		(width 0.0889)
		(layer "In4.Cu")
		(net "M_J_CPU0_SA_PAR")
	)
	(segment
		(start 384.333496 -255.496822)
		(end 384.341878 -255.501648)
		(width 0.0889)
		(layer "In4.Cu")
		(net "M_J_CPU0_SA_PAR")
	)
	(segment
		(start 403.579838 -255.165352)
		(end 404.158196 -255.74371)
		(width 0.14478)
		(layer "In4.Cu")
		(net "M_J_CPU0_SA_PAR")
	)
	(segment
		(start 379.30074 -255.558798)
		(end 379.323092 -255.475486)
		(width 0.0889)
		(layer "In4.Cu")
		(net "M_J_CPU0_SA_PAR")
	)
	(segment
		(start 404.158196 -255.74371)
		(end 432.149504 -255.74371)
		(width 0.14478)
		(layer "In4.Cu")
		(net "M_J_CPU0_SA_PAR")
	)
	(segment
		(start 436.022496 -253.010162)
		(end 439.100214 -254.284988)
		(width 0.14478)
		(layer "In4.Cu")
		(net "M_J_CPU0_SA_PAR")
	)
	(segment
		(start 400.009614 -255.165352)
		(end 403.579838 -255.165352)
		(width 0.14478)
		(layer "In4.Cu")
		(net "M_J_CPU0_SA_PAR")
	)
	(segment
		(start 433.255166 -253.56947)
		(end 433.814474 -253.010162)
		(width 0.14478)
		(layer "In4.Cu")
		(net "M_J_CPU0_SA_PAR")
	)
	(segment
		(start 392.788648 -255.494028)
		(end 392.802364 -255.501902)
		(width 0.0889)
		(layer "In4.Cu")
		(net "M_J_CPU0_SA_PAR")
	)
	(segment
		(start 381.147828 -255.501648)
		(end 381.15621 -255.496822)
		(width 0.0889)
		(layer "In4.Cu")
		(net "M_J_CPU0_SA_PAR")
	)
	(segment
		(start 379.63348 -255.496822)
		(end 379.641862 -255.501648)
		(width 0.0889)
		(layer "In4.Cu")
		(net "M_J_CPU0_SA_PAR")
	)
	(segment
		(start 393.511278 -255.584452)
		(end 394.551916 -256.62509)
		(width 0.0889)
		(layer "In4.Cu")
		(net "M_J_CPU0_SA_PAR")
	)
	(segment
		(start 385.847844 -255.501648)
		(end 385.856226 -255.496822)
		(width 0.0889)
		(layer "In4.Cu")
		(net "M_J_CPU0_SA_PAR")
	)
	(segment
		(start 389.607806 -255.501648)
		(end 389.616188 -255.496822)
		(width 0.0889)
		(layer "In4.Cu")
		(net "M_J_CPU0_SA_PAR")
	)
	(segment
		(start 433.814474 -253.010162)
		(end 436.022496 -253.010162)
		(width 0.14478)
		(layer "In4.Cu")
		(net "M_J_CPU0_SA_PAR")
	)
	(arc
		(start 389.981948 -255.501648)
		(mid 390.264904 -255.577825)
		(end 390.54786 -255.501648)
		(width 0.0889)
		(layer "In4.Cu")
		(net "M_J_CPU0_SA_PAR")
	)
	(arc
		(start 389.041894 -255.501648)
		(mid 389.32485 -255.577825)
		(end 389.607806 -255.501648)
		(width 0.0889)
		(layer "In4.Cu")
		(net "M_J_CPU0_SA_PAR")
	)
	(arc
		(start 388.667752 -255.501648)
		(mid 388.850003 -255.451298)
		(end 389.033512 -255.496822)
		(width 0.0889)
		(layer "In4.Cu")
		(net "M_J_CPU0_SA_PAR")
	)
	(arc
		(start 382.087882 -255.501648)
		(mid 382.274826 -255.451393)
		(end 382.46177 -255.501648)
		(width 0.0889)
		(layer "In4.Cu")
		(net "M_J_CPU0_SA_PAR")
	)
	(arc
		(start 383.027682 -255.501648)
		(mid 383.209933 -255.451298)
		(end 383.393442 -255.496822)
		(width 0.0889)
		(layer "In4.Cu")
		(net "M_J_CPU0_SA_PAR")
	)
	(arc
		(start 389.616188 -255.496822)
		(mid 389.799696 -255.451328)
		(end 389.981948 -255.501648)
		(width 0.0889)
		(layer "In4.Cu")
		(net "M_J_CPU0_SA_PAR")
	)
	(arc
		(start 383.401824 -255.501648)
		(mid 383.68478 -255.577825)
		(end 383.967736 -255.501648)
		(width 0.0889)
		(layer "In4.Cu")
		(net "M_J_CPU0_SA_PAR")
	)
	(arc
		(start 380.581916 -255.501648)
		(mid 380.864872 -255.577825)
		(end 381.147828 -255.501648)
		(width 0.0889)
		(layer "In4.Cu")
		(net "M_J_CPU0_SA_PAR")
	)
	(arc
		(start 379.323092 -255.475486)
		(mid 379.480602 -255.452288)
		(end 379.63348 -255.496822)
		(width 0.0889)
		(layer "In4.Cu")
		(net "M_J_CPU0_SA_PAR")
	)
	(arc
		(start 385.856226 -255.496822)
		(mid 386.039734 -255.451328)
		(end 386.221986 -255.501648)
		(width 0.0889)
		(layer "In4.Cu")
		(net "M_J_CPU0_SA_PAR")
	)
	(arc
		(start 392.42873 -255.501648)
		(mid 392.607717 -255.451478)
		(end 392.788648 -255.494028)
		(width 0.0889)
		(layer "In4.Cu")
		(net "M_J_CPU0_SA_PAR")
	)
	(arc
		(start 380.216156 -255.496822)
		(mid 380.399664 -255.451328)
		(end 380.581916 -255.501648)
		(width 0.0889)
		(layer "In4.Cu")
		(net "M_J_CPU0_SA_PAR")
	)
	(arc
		(start 388.10184 -255.501648)
		(mid 388.384796 -255.577825)
		(end 388.667752 -255.501648)
		(width 0.0889)
		(layer "In4.Cu")
		(net "M_J_CPU0_SA_PAR")
	)
	(arc
		(start 387.161786 -255.501648)
		(mid 387.444742 -255.577825)
		(end 387.727698 -255.501648)
		(width 0.0889)
		(layer "In4.Cu")
		(net "M_J_CPU0_SA_PAR")
	)
	(arc
		(start 387.727698 -255.501648)
		(mid 387.909949 -255.451298)
		(end 388.093458 -255.496822)
		(width 0.0889)
		(layer "In4.Cu")
		(net "M_J_CPU0_SA_PAR")
	)
	(arc
		(start 379.641862 -255.501648)
		(mid 379.924818 -255.577825)
		(end 380.207774 -255.501648)
		(width 0.0889)
		(layer "In4.Cu")
		(net "M_J_CPU0_SA_PAR")
	)
	(arc
		(start 386.221986 -255.501648)
		(mid 386.504942 -255.577825)
		(end 386.787898 -255.501648)
		(width 0.0889)
		(layer "In4.Cu")
		(net "M_J_CPU0_SA_PAR")
	)
	(arc
		(start 391.496042 -255.496822)
		(mid 391.679804 -255.451206)
		(end 391.86231 -255.501648)
		(width 0.0889)
		(layer "In4.Cu")
		(net "M_J_CPU0_SA_PAR")
	)
	(arc
		(start 381.52197 -255.501648)
		(mid 381.804926 -255.577825)
		(end 382.087882 -255.501648)
		(width 0.0889)
		(layer "In4.Cu")
		(net "M_J_CPU0_SA_PAR")
	)
	(arc
		(start 391.86231 -255.501648)
		(mid 392.137016 -255.578012)
		(end 392.413998 -255.510284)
		(width 0.0889)
		(layer "In4.Cu")
		(net "M_J_CPU0_SA_PAR")
	)
	(arc
		(start 390.921748 -255.501648)
		(mid 391.204704 -255.577825)
		(end 391.48766 -255.501648)
		(width 0.0889)
		(layer "In4.Cu")
		(net "M_J_CPU0_SA_PAR")
	)
	(arc
		(start 383.967736 -255.501648)
		(mid 384.149987 -255.451298)
		(end 384.333496 -255.496822)
		(width 0.0889)
		(layer "In4.Cu")
		(net "M_J_CPU0_SA_PAR")
	)
	(arc
		(start 381.15621 -255.496822)
		(mid 381.339718 -255.451328)
		(end 381.52197 -255.501648)
		(width 0.0889)
		(layer "In4.Cu")
		(net "M_J_CPU0_SA_PAR")
	)
	(arc
		(start 385.281932 -255.501648)
		(mid 385.564888 -255.577825)
		(end 385.847844 -255.501648)
		(width 0.0889)
		(layer "In4.Cu")
		(net "M_J_CPU0_SA_PAR")
	)
	(arc
		(start 390.54786 -255.501648)
		(mid 390.734804 -255.451393)
		(end 390.921748 -255.501648)
		(width 0.0889)
		(layer "In4.Cu")
		(net "M_J_CPU0_SA_PAR")
	)
	(arc
		(start 384.916172 -255.496822)
		(mid 385.09968 -255.451328)
		(end 385.281932 -255.501648)
		(width 0.0889)
		(layer "In4.Cu")
		(net "M_J_CPU0_SA_PAR")
	)
	(arc
		(start 382.46177 -255.501648)
		(mid 382.744726 -255.577825)
		(end 383.027682 -255.501648)
		(width 0.0889)
		(layer "In4.Cu")
		(net "M_J_CPU0_SA_PAR")
	)
	(arc
		(start 392.818112 -255.511046)
		(mid 392.949529 -255.565765)
		(end 393.090654 -255.584452)
		(width 0.0889)
		(layer "In4.Cu")
		(net "M_J_CPU0_SA_PAR")
	)
	(arc
		(start 384.341878 -255.501648)
		(mid 384.624834 -255.577825)
		(end 384.90779 -255.501648)
		(width 0.0889)
		(layer "In4.Cu")
		(net "M_J_CPU0_SA_PAR")
	)
	(arc
		(start 386.787898 -255.501648)
		(mid 386.974842 -255.451393)
		(end 387.161786 -255.501648)
		(width 0.0889)
		(layer "In4.Cu")
		(net "M_J_CPU0_SA_PAR")
	)
	(segment
		(start 378.988066 -247.990106)
		(end 379.454918 -247.724168)
		(width 0.12954)
		(layer "F.Cu")
		(net "M_J_CPU0_SA_DQS_DP<9>")
	)
	(segment
		(start 407.551128 -244.28323)
		(end 407.363168 -244.09527)
		(width 0.16002)
		(layer "In4.Cu")
		(net "M_J_CPU0_SA_DQS_DP<9>")
	)
	(segment
		(start 395.44244 -247.045734)
		(end 394.878814 -247.60936)
		(width 0.09525)
		(layer "In4.Cu")
		(net "M_J_CPU0_SA_DQS_DP<9>")
	)
	(segment
		(start 429.961294 -239.365028)
		(end 429.128174 -240.198148)
		(width 0.16002)
		(layer "In4.Cu")
		(net "M_J_CPU0_SA_DQS_DP<9>")
	)
	(segment
		(start 407.077672 -244.756686)
		(end 407.077672 -245.28399)
		(width 0.16002)
		(layer "In4.Cu")
		(net "M_J_CPU0_SA_DQS_DP<9>")
	)
	(segment
		(start 408.263344 -243.195094)
		(end 408.451304 -243.383054)
		(width 0.16002)
		(layer "In4.Cu")
		(net "M_J_CPU0_SA_DQS_DP<9>")
	)
	(segment
		(start 392.824716 -247.41124)
		(end 392.803888 -247.399048)
		(width 0.09525)
		(layer "In4.Cu")
		(net "M_J_CPU0_SA_DQS_DP<9>")
	)
	(segment
		(start 432.195478 -239.561116)
		(end 432.04638 -239.710214)
		(width 0.16002)
		(layer "In4.Cu")
		(net "M_J_CPU0_SA_DQS_DP<9>")
	)
	(segment
		(start 389.043418 -247.399048)
		(end 389.035036 -247.394222)
		(width 0.09525)
		(layer "In4.Cu")
		(net "M_J_CPU0_SA_DQS_DP<9>")
	)
	(segment
		(start 408.45994 -242.721638)
		(end 408.263344 -242.918234)
		(width 0.16002)
		(layer "In4.Cu")
		(net "M_J_CPU0_SA_DQS_DP<9>")
	)
	(segment
		(start 408.451304 -243.910358)
		(end 408.078432 -244.28323)
		(width 0.16002)
		(layer "In4.Cu")
		(net "M_J_CPU0_SA_DQS_DP<9>")
	)
	(segment
		(start 405.70404 -246.130318)
		(end 405.70404 -246.657622)
		(width 0.16002)
		(layer "In4.Cu")
		(net "M_J_CPU0_SA_DQS_DP<9>")
	)
	(segment
		(start 409.452064 -242.909598)
		(end 408.92476 -242.909598)
		(width 0.16002)
		(layer "In4.Cu")
		(net "M_J_CPU0_SA_DQS_DP<9>")
	)
	(segment
		(start 408.263344 -242.918234)
		(end 408.263344 -243.195094)
		(width 0.16002)
		(layer "In4.Cu")
		(net "M_J_CPU0_SA_DQS_DP<9>")
	)
	(segment
		(start 420.497254 -240.560352)
		(end 418.976302 -240.560352)
		(width 0.16002)
		(layer "In4.Cu")
		(net "M_J_CPU0_SA_DQS_DP<9>")
	)
	(segment
		(start 405.51608 -245.942358)
		(end 405.70404 -246.130318)
		(width 0.16002)
		(layer "In4.Cu")
		(net "M_J_CPU0_SA_DQS_DP<9>")
	)
	(segment
		(start 435.000146 -239.835182)
		(end 435.000146 -239.834928)
		(width 0.16002)
		(layer "In4.Cu")
		(net "M_J_CPU0_SA_DQS_DP<9>")
	)
	(segment
		(start 383.403348 -247.399048)
		(end 383.394966 -247.394222)
		(width 0.09525)
		(layer "In4.Cu")
		(net "M_J_CPU0_SA_DQS_DP<9>")
	)
	(segment
		(start 384.914648 -247.394222)
		(end 384.906266 -247.399048)
		(width 0.09525)
		(layer "In4.Cu")
		(net "M_J_CPU0_SA_DQS_DP<9>")
	)
	(segment
		(start 414.868614 -239.397032)
		(end 414.105598 -240.160048)
		(width 0.16002)
		(layer "In4.Cu")
		(net "M_J_CPU0_SA_DQS_DP<9>")
	)
	(segment
		(start 414.105598 -240.160048)
		(end 412.201614 -240.160048)
		(width 0.16002)
		(layer "In4.Cu")
		(net "M_J_CPU0_SA_DQS_DP<9>")
	)
	(segment
		(start 408.7368 -242.721638)
		(end 408.45994 -242.721638)
		(width 0.16002)
		(layer "In4.Cu")
		(net "M_J_CPU0_SA_DQS_DP<9>")
	)
	(segment
		(start 408.92476 -242.909598)
		(end 408.7368 -242.721638)
		(width 0.16002)
		(layer "In4.Cu")
		(net "M_J_CPU0_SA_DQS_DP<9>")
	)
	(segment
		(start 423.389044 -239.710214)
		(end 423.051478 -239.372648)
		(width 0.16002)
		(layer "In4.Cu")
		(net "M_J_CPU0_SA_DQS_DP<9>")
	)
	(segment
		(start 395.835632 -247.104662)
		(end 395.776704 -247.045734)
		(width 0.09525)
		(layer "In4.Cu")
		(net "M_J_CPU0_SA_DQS_DP<9>")
	)
	(segment
		(start 393.973812 -247.60936)
		(end 393.822174 -247.457976)
		(width 0.09525)
		(layer "In4.Cu")
		(net "M_J_CPU0_SA_DQS_DP<9>")
	)
	(segment
		(start 423.051478 -239.372648)
		(end 422.352978 -239.372648)
		(width 0.16002)
		(layer "In4.Cu")
		(net "M_J_CPU0_SA_DQS_DP<9>")
	)
	(segment
		(start 407.363168 -244.09527)
		(end 407.086308 -244.09527)
		(width 0.16002)
		(layer "In4.Cu")
		(net "M_J_CPU0_SA_DQS_DP<9>")
	)
	(segment
		(start 428.193454 -240.560352)
		(end 426.816266 -240.560352)
		(width 0.16002)
		(layer "In4.Cu")
		(net "M_J_CPU0_SA_DQS_DP<9>")
	)
	(segment
		(start 380.214632 -247.394222)
		(end 380.20625 -247.399048)
		(width 0.09525)
		(layer "In4.Cu")
		(net "M_J_CPU0_SA_DQS_DP<9>")
	)
	(segment
		(start 429.128174 -240.198148)
		(end 428.555658 -240.198148)
		(width 0.16002)
		(layer "In4.Cu")
		(net "M_J_CPU0_SA_DQS_DP<9>")
	)
	(segment
		(start 433.365148 -239.677956)
		(end 433.248308 -239.561116)
		(width 0.16002)
		(layer "In4.Cu")
		(net "M_J_CPU0_SA_DQS_DP<9>")
	)
	(segment
		(start 406.7048 -245.656862)
		(end 406.177496 -245.656862)
		(width 0.16002)
		(layer "In4.Cu")
		(net "M_J_CPU0_SA_DQS_DP<9>")
	)
	(segment
		(start 406.889712 -244.291866)
		(end 406.889712 -244.568726)
		(width 0.16002)
		(layer "In4.Cu")
		(net "M_J_CPU0_SA_DQS_DP<9>")
	)
	(segment
		(start 406.889712 -244.568726)
		(end 407.077672 -244.756686)
		(width 0.16002)
		(layer "In4.Cu")
		(net "M_J_CPU0_SA_DQS_DP<9>")
	)
	(segment
		(start 405.989536 -245.468902)
		(end 405.712676 -245.468902)
		(width 0.16002)
		(layer "In4.Cu")
		(net "M_J_CPU0_SA_DQS_DP<9>")
	)
	(segment
		(start 425.966128 -239.710214)
		(end 423.389044 -239.710214)
		(width 0.16002)
		(layer "In4.Cu")
		(net "M_J_CPU0_SA_DQS_DP<9>")
	)
	(segment
		(start 417.812982 -239.397032)
		(end 414.868614 -239.397032)
		(width 0.16002)
		(layer "In4.Cu")
		(net "M_J_CPU0_SA_DQS_DP<9>")
	)
	(segment
		(start 405.257 -247.104662)
		(end 395.859254 -247.104662)
		(width 0.16002)
		(layer "In4.Cu")
		(net "M_J_CPU0_SA_DQS_DP<9>")
	)
	(segment
		(start 433.962048 -239.561116)
		(end 433.845208 -239.677956)
		(width 0.16002)
		(layer "In4.Cu")
		(net "M_J_CPU0_SA_DQS_DP<9>")
	)
	(segment
		(start 379.324362 -247.37187)
		(end 379.300994 -247.458738)
		(width 0.09525)
		(layer "In4.Cu")
		(net "M_J_CPU0_SA_DQS_DP<9>")
	)
	(segment
		(start 385.854702 -247.394222)
		(end 385.84632 -247.399048)
		(width 0.09525)
		(layer "In4.Cu")
		(net "M_J_CPU0_SA_DQS_DP<9>")
	)
	(segment
		(start 408.451304 -243.383054)
		(end 408.451304 -243.910358)
		(width 0.16002)
		(layer "In4.Cu")
		(net "M_J_CPU0_SA_DQS_DP<9>")
	)
	(segment
		(start 432.04638 -239.710214)
		(end 430.958244 -239.710214)
		(width 0.16002)
		(layer "In4.Cu")
		(net "M_J_CPU0_SA_DQS_DP<9>")
	)
	(segment
		(start 392.803888 -247.399048)
		(end 392.795506 -247.394222)
		(width 0.09525)
		(layer "In4.Cu")
		(net "M_J_CPU0_SA_DQS_DP<9>")
	)
	(segment
		(start 412.201614 -240.160048)
		(end 409.452064 -242.909598)
		(width 0.16002)
		(layer "In4.Cu")
		(net "M_J_CPU0_SA_DQS_DP<9>")
	)
	(segment
		(start 408.078432 -244.28323)
		(end 407.551128 -244.28323)
		(width 0.16002)
		(layer "In4.Cu")
		(net "M_J_CPU0_SA_DQS_DP<9>")
	)
	(segment
		(start 430.958244 -239.710214)
		(end 430.613058 -239.365028)
		(width 0.16002)
		(layer "In4.Cu")
		(net "M_J_CPU0_SA_DQS_DP<9>")
	)
	(segment
		(start 394.878814 -247.60936)
		(end 393.973812 -247.60936)
		(width 0.09525)
		(layer "In4.Cu")
		(net "M_J_CPU0_SA_DQS_DP<9>")
	)
	(segment
		(start 389.614664 -247.394222)
		(end 389.606282 -247.399048)
		(width 0.09525)
		(layer "In4.Cu")
		(net "M_J_CPU0_SA_DQS_DP<9>")
	)
	(segment
		(start 421.504618 -240.221008)
		(end 420.836598 -240.221008)
		(width 0.16002)
		(layer "In4.Cu")
		(net "M_J_CPU0_SA_DQS_DP<9>")
	)
	(segment
		(start 391.494518 -247.394222)
		(end 391.486136 -247.399048)
		(width 0.09525)
		(layer "In4.Cu")
		(net "M_J_CPU0_SA_DQS_DP<9>")
	)
	(segment
		(start 422.352978 -239.372648)
		(end 421.504618 -240.221008)
		(width 0.16002)
		(layer "In4.Cu")
		(net "M_J_CPU0_SA_DQS_DP<9>")
	)
	(segment
		(start 435.000146 -239.834928)
		(end 434.726334 -239.561116)
		(width 0.16002)
		(layer "In4.Cu")
		(net "M_J_CPU0_SA_DQS_DP<9>")
	)
	(segment
		(start 407.077672 -245.28399)
		(end 406.7048 -245.656862)
		(width 0.16002)
		(layer "In4.Cu")
		(net "M_J_CPU0_SA_DQS_DP<9>")
	)
	(segment
		(start 384.343402 -247.399048)
		(end 384.33502 -247.394222)
		(width 0.09525)
		(layer "In4.Cu")
		(net "M_J_CPU0_SA_DQS_DP<9>")
	)
	(segment
		(start 420.836598 -240.221008)
		(end 420.497254 -240.560352)
		(width 0.16002)
		(layer "In4.Cu")
		(net "M_J_CPU0_SA_DQS_DP<9>")
	)
	(segment
		(start 433.845208 -239.677956)
		(end 433.365148 -239.677956)
		(width 0.16002)
		(layer "In4.Cu")
		(net "M_J_CPU0_SA_DQS_DP<9>")
	)
	(segment
		(start 426.816266 -240.560352)
		(end 425.966128 -239.710214)
		(width 0.16002)
		(layer "In4.Cu")
		(net "M_J_CPU0_SA_DQS_DP<9>")
	)
	(segment
		(start 405.70404 -246.657622)
		(end 405.257 -247.104662)
		(width 0.16002)
		(layer "In4.Cu")
		(net "M_J_CPU0_SA_DQS_DP<9>")
	)
	(segment
		(start 430.613058 -239.365028)
		(end 429.961294 -239.365028)
		(width 0.16002)
		(layer "In4.Cu")
		(net "M_J_CPU0_SA_DQS_DP<9>")
	)
	(segment
		(start 395.776704 -247.045734)
		(end 395.44244 -247.045734)
		(width 0.09525)
		(layer "In4.Cu")
		(net "M_J_CPU0_SA_DQS_DP<9>")
	)
	(segment
		(start 379.300994 -247.458738)
		(end 379.454918 -247.724168)
		(width 0.09525)
		(layer "In4.Cu")
		(net "M_J_CPU0_SA_DQS_DP<9>")
	)
	(segment
		(start 406.177496 -245.656862)
		(end 405.989536 -245.468902)
		(width 0.16002)
		(layer "In4.Cu")
		(net "M_J_CPU0_SA_DQS_DP<9>")
	)
	(segment
		(start 388.103364 -247.399048)
		(end 388.094982 -247.394222)
		(width 0.09525)
		(layer "In4.Cu")
		(net "M_J_CPU0_SA_DQS_DP<9>")
	)
	(segment
		(start 434.726334 -239.561116)
		(end 433.962048 -239.561116)
		(width 0.16002)
		(layer "In4.Cu")
		(net "M_J_CPU0_SA_DQS_DP<9>")
	)
	(segment
		(start 405.51608 -245.665498)
		(end 405.51608 -245.942358)
		(width 0.16002)
		(layer "In4.Cu")
		(net "M_J_CPU0_SA_DQS_DP<9>")
	)
	(segment
		(start 379.643386 -247.399048)
		(end 379.635004 -247.394222)
		(width 0.09525)
		(layer "In4.Cu")
		(net "M_J_CPU0_SA_DQS_DP<9>")
	)
	(segment
		(start 407.086308 -244.09527)
		(end 406.889712 -244.291866)
		(width 0.16002)
		(layer "In4.Cu")
		(net "M_J_CPU0_SA_DQS_DP<9>")
	)
	(segment
		(start 433.248308 -239.561116)
		(end 432.195478 -239.561116)
		(width 0.16002)
		(layer "In4.Cu")
		(net "M_J_CPU0_SA_DQS_DP<9>")
	)
	(segment
		(start 392.427206 -247.399048)
		(end 392.412474 -247.407684)
		(width 0.09525)
		(layer "In4.Cu")
		(net "M_J_CPU0_SA_DQS_DP<9>")
	)
	(segment
		(start 381.154686 -247.394222)
		(end 381.146304 -247.399048)
		(width 0.09525)
		(layer "In4.Cu")
		(net "M_J_CPU0_SA_DQS_DP<9>")
	)
	(segment
		(start 405.712676 -245.468902)
		(end 405.51608 -245.665498)
		(width 0.16002)
		(layer "In4.Cu")
		(net "M_J_CPU0_SA_DQS_DP<9>")
	)
	(segment
		(start 395.859254 -247.104662)
		(end 395.835632 -247.104662)
		(width 0.09525)
		(layer "In4.Cu")
		(net "M_J_CPU0_SA_DQS_DP<9>")
	)
	(segment
		(start 418.976302 -240.560352)
		(end 417.812982 -239.397032)
		(width 0.16002)
		(layer "In4.Cu")
		(net "M_J_CPU0_SA_DQS_DP<9>")
	)
	(segment
		(start 428.555658 -240.198148)
		(end 428.193454 -240.560352)
		(width 0.16002)
		(layer "In4.Cu")
		(net "M_J_CPU0_SA_DQS_DP<9>")
	)
	(arc
		(start 389.983472 -247.399048)
		(mid 389.799697 -247.348276)
		(end 389.614664 -247.394222)
		(width 0.09525)
		(layer "In4.Cu")
		(net "M_J_CPU0_SA_DQS_DP<9>")
	)
	(arc
		(start 382.086358 -247.399048)
		(mid 381.804926 -247.474803)
		(end 381.523494 -247.399048)
		(width 0.09525)
		(layer "In4.Cu")
		(net "M_J_CPU0_SA_DQS_DP<9>")
	)
	(arc
		(start 380.20625 -247.399048)
		(mid 379.924818 -247.474803)
		(end 379.643386 -247.399048)
		(width 0.09525)
		(layer "In4.Cu")
		(net "M_J_CPU0_SA_DQS_DP<9>")
	)
	(arc
		(start 386.786374 -247.399048)
		(mid 386.504942 -247.474803)
		(end 386.22351 -247.399048)
		(width 0.09525)
		(layer "In4.Cu")
		(net "M_J_CPU0_SA_DQS_DP<9>")
	)
	(arc
		(start 392.795506 -247.394222)
		(mid 392.610728 -247.348429)
		(end 392.427206 -247.399048)
		(width 0.09525)
		(layer "In4.Cu")
		(net "M_J_CPU0_SA_DQS_DP<9>")
	)
	(arc
		(start 393.822174 -247.457976)
		(mid 393.814157 -247.450237)
		(end 393.805918 -247.442736)
		(width 0.09525)
		(layer "In4.Cu")
		(net "M_J_CPU0_SA_DQS_DP<9>")
	)
	(arc
		(start 383.394966 -247.394222)
		(mid 383.209934 -247.348308)
		(end 383.026158 -247.399048)
		(width 0.09525)
		(layer "In4.Cu")
		(net "M_J_CPU0_SA_DQS_DP<9>")
	)
	(arc
		(start 392.412474 -247.407684)
		(mid 392.137015 -247.475069)
		(end 391.863834 -247.399048)
		(width 0.09525)
		(layer "In4.Cu")
		(net "M_J_CPU0_SA_DQS_DP<9>")
	)
	(arc
		(start 391.486136 -247.399048)
		(mid 391.204704 -247.474803)
		(end 390.923272 -247.399048)
		(width 0.09525)
		(layer "In4.Cu")
		(net "M_J_CPU0_SA_DQS_DP<9>")
	)
	(arc
		(start 385.283456 -247.399048)
		(mid 385.099681 -247.348276)
		(end 384.914648 -247.394222)
		(width 0.09525)
		(layer "In4.Cu")
		(net "M_J_CPU0_SA_DQS_DP<9>")
	)
	(arc
		(start 385.84632 -247.399048)
		(mid 385.564888 -247.474803)
		(end 385.283456 -247.399048)
		(width 0.09525)
		(layer "In4.Cu")
		(net "M_J_CPU0_SA_DQS_DP<9>")
	)
	(arc
		(start 388.666228 -247.399048)
		(mid 388.384796 -247.474803)
		(end 388.103364 -247.399048)
		(width 0.09525)
		(layer "In4.Cu")
		(net "M_J_CPU0_SA_DQS_DP<9>")
	)
	(arc
		(start 387.16331 -247.399048)
		(mid 386.974842 -247.348371)
		(end 386.786374 -247.399048)
		(width 0.09525)
		(layer "In4.Cu")
		(net "M_J_CPU0_SA_DQS_DP<9>")
	)
	(arc
		(start 390.546336 -247.399048)
		(mid 390.264904 -247.474803)
		(end 389.983472 -247.399048)
		(width 0.09525)
		(layer "In4.Cu")
		(net "M_J_CPU0_SA_DQS_DP<9>")
	)
	(arc
		(start 389.035036 -247.394222)
		(mid 388.850004 -247.348308)
		(end 388.666228 -247.399048)
		(width 0.09525)
		(layer "In4.Cu")
		(net "M_J_CPU0_SA_DQS_DP<9>")
	)
	(arc
		(start 393.736068 -247.394222)
		(mid 393.550782 -247.348186)
		(end 393.366752 -247.399048)
		(width 0.09525)
		(layer "In4.Cu")
		(net "M_J_CPU0_SA_DQS_DP<9>")
	)
	(arc
		(start 382.463294 -247.399048)
		(mid 382.274826 -247.348371)
		(end 382.086358 -247.399048)
		(width 0.09525)
		(layer "In4.Cu")
		(net "M_J_CPU0_SA_DQS_DP<9>")
	)
	(arc
		(start 390.923272 -247.399048)
		(mid 390.734804 -247.348371)
		(end 390.546336 -247.399048)
		(width 0.09525)
		(layer "In4.Cu")
		(net "M_J_CPU0_SA_DQS_DP<9>")
	)
	(arc
		(start 383.026158 -247.399048)
		(mid 382.744726 -247.474803)
		(end 382.463294 -247.399048)
		(width 0.09525)
		(layer "In4.Cu")
		(net "M_J_CPU0_SA_DQS_DP<9>")
	)
	(arc
		(start 380.58344 -247.399048)
		(mid 380.399665 -247.348276)
		(end 380.214632 -247.394222)
		(width 0.09525)
		(layer "In4.Cu")
		(net "M_J_CPU0_SA_DQS_DP<9>")
	)
	(arc
		(start 387.726174 -247.399048)
		(mid 387.444742 -247.474803)
		(end 387.16331 -247.399048)
		(width 0.09525)
		(layer "In4.Cu")
		(net "M_J_CPU0_SA_DQS_DP<9>")
	)
	(arc
		(start 393.805918 -247.442736)
		(mid 393.772361 -247.416511)
		(end 393.736068 -247.394222)
		(width 0.09525)
		(layer "In4.Cu")
		(net "M_J_CPU0_SA_DQS_DP<9>")
	)
	(arc
		(start 379.635004 -247.394222)
		(mid 379.482109 -247.349394)
		(end 379.324362 -247.37187)
		(width 0.09525)
		(layer "In4.Cu")
		(net "M_J_CPU0_SA_DQS_DP<9>")
	)
	(arc
		(start 383.966212 -247.399048)
		(mid 383.68478 -247.474803)
		(end 383.403348 -247.399048)
		(width 0.09525)
		(layer "In4.Cu")
		(net "M_J_CPU0_SA_DQS_DP<9>")
	)
	(arc
		(start 384.33502 -247.394222)
		(mid 384.149988 -247.348308)
		(end 383.966212 -247.399048)
		(width 0.09525)
		(layer "In4.Cu")
		(net "M_J_CPU0_SA_DQS_DP<9>")
	)
	(arc
		(start 393.366752 -247.399048)
		(mid 393.097319 -247.474919)
		(end 392.824716 -247.41124)
		(width 0.09525)
		(layer "In4.Cu")
		(net "M_J_CPU0_SA_DQS_DP<9>")
	)
	(arc
		(start 381.146304 -247.399048)
		(mid 380.864872 -247.474803)
		(end 380.58344 -247.399048)
		(width 0.09525)
		(layer "In4.Cu")
		(net "M_J_CPU0_SA_DQS_DP<9>")
	)
	(arc
		(start 381.523494 -247.399048)
		(mid 381.339719 -247.348276)
		(end 381.154686 -247.394222)
		(width 0.09525)
		(layer "In4.Cu")
		(net "M_J_CPU0_SA_DQS_DP<9>")
	)
	(arc
		(start 388.094982 -247.394222)
		(mid 387.90995 -247.348308)
		(end 387.726174 -247.399048)
		(width 0.09525)
		(layer "In4.Cu")
		(net "M_J_CPU0_SA_DQS_DP<9>")
	)
	(arc
		(start 389.606282 -247.399048)
		(mid 389.32485 -247.474803)
		(end 389.043418 -247.399048)
		(width 0.09525)
		(layer "In4.Cu")
		(net "M_J_CPU0_SA_DQS_DP<9>")
	)
	(arc
		(start 384.906266 -247.399048)
		(mid 384.624834 -247.474803)
		(end 384.343402 -247.399048)
		(width 0.09525)
		(layer "In4.Cu")
		(net "M_J_CPU0_SA_DQS_DP<9>")
	)
	(arc
		(start 386.22351 -247.399048)
		(mid 386.039735 -247.348276)
		(end 385.854702 -247.394222)
		(width 0.09525)
		(layer "In4.Cu")
		(net "M_J_CPU0_SA_DQS_DP<9>")
	)
	(arc
		(start 391.863834 -247.399048)
		(mid 391.679805 -247.348149)
		(end 391.494518 -247.394222)
		(width 0.09525)
		(layer "In4.Cu")
		(net "M_J_CPU0_SA_DQS_DP<9>")
	)
	(segment
		(start 378.988066 -243.13007)
		(end 379.454918 -242.864132)
		(width 0.12954)
		(layer "F.Cu")
		(net "M_J_CPU0_SA_DQS_DP<8>")
	)
	(segment
		(start 395.537436 -241.443764)
		(end 395.705076 -241.443764)
		(width 0.09525)
		(layer "In4.Cu")
		(net "M_J_CPU0_SA_DQS_DP<8>")
	)
	(segment
		(start 408.53233 -232.928922)
		(end 408.53233 -232.652062)
		(width 0.16002)
		(layer "In4.Cu")
		(net "M_J_CPU0_SA_DQS_DP<8>")
	)
	(segment
		(start 421.504618 -230.871014)
		(end 422.352978 -230.022654)
		(width 0.16002)
		(layer "In4.Cu")
		(net "M_J_CPU0_SA_DQS_DP<8>")
	)
	(segment
		(start 410.622496 -231.324912)
		(end 411.1498 -231.324912)
		(width 0.16002)
		(layer "In4.Cu")
		(net "M_J_CPU0_SA_DQS_DP<8>")
	)
	(segment
		(start 417.806378 -230.040434)
		(end 418.976302 -231.210358)
		(width 0.16002)
		(layer "In4.Cu")
		(net "M_J_CPU0_SA_DQS_DP<8>")
	)
	(segment
		(start 422.352978 -230.022654)
		(end 423.051478 -230.022654)
		(width 0.16002)
		(layer "In4.Cu")
		(net "M_J_CPU0_SA_DQS_DP<8>")
	)
	(segment
		(start 430.958244 -230.36022)
		(end 432.04638 -230.36022)
		(width 0.16002)
		(layer "In4.Cu")
		(net "M_J_CPU0_SA_DQS_DP<8>")
	)
	(segment
		(start 384.906266 -242.539012)
		(end 384.914648 -242.534186)
		(width 0.09525)
		(layer "In4.Cu")
		(net "M_J_CPU0_SA_DQS_DP<8>")
	)
	(segment
		(start 411.664658 -230.810054)
		(end 414.105598 -230.810054)
		(width 0.16002)
		(layer "In4.Cu")
		(net "M_J_CPU0_SA_DQS_DP<8>")
	)
	(segment
		(start 430.613058 -230.015034)
		(end 430.958244 -230.36022)
		(width 0.16002)
		(layer "In4.Cu")
		(net "M_J_CPU0_SA_DQS_DP<8>")
	)
	(segment
		(start 408.402536 -234.072176)
		(end 408.775408 -233.699304)
		(width 0.16002)
		(layer "In4.Cu")
		(net "M_J_CPU0_SA_DQS_DP<8>")
	)
	(segment
		(start 389.606282 -242.539012)
		(end 389.614664 -242.534186)
		(width 0.09525)
		(layer "In4.Cu")
		(net "M_J_CPU0_SA_DQS_DP<8>")
	)
	(segment
		(start 428.555658 -230.848154)
		(end 429.128174 -230.848154)
		(width 0.16002)
		(layer "In4.Cu")
		(net "M_J_CPU0_SA_DQS_DP<8>")
	)
	(segment
		(start 428.193454 -231.210358)
		(end 428.555658 -230.848154)
		(width 0.16002)
		(layer "In4.Cu")
		(net "M_J_CPU0_SA_DQS_DP<8>")
	)
	(segment
		(start 394.826998 -242.154202)
		(end 395.537436 -241.443764)
		(width 0.09525)
		(layer "In4.Cu")
		(net "M_J_CPU0_SA_DQS_DP<8>")
	)
	(segment
		(start 409.005786 -232.455466)
		(end 409.248864 -232.698544)
		(width 0.16002)
		(layer "In4.Cu")
		(net "M_J_CPU0_SA_DQS_DP<8>")
	)
	(segment
		(start 395.705076 -241.443764)
		(end 395.764004 -241.502692)
		(width 0.09525)
		(layer "In4.Cu")
		(net "M_J_CPU0_SA_DQS_DP<8>")
	)
	(segment
		(start 409.248864 -232.698544)
		(end 409.776168 -232.698544)
		(width 0.16002)
		(layer "In4.Cu")
		(net "M_J_CPU0_SA_DQS_DP<8>")
	)
	(segment
		(start 429.961294 -230.015034)
		(end 430.613058 -230.015034)
		(width 0.16002)
		(layer "In4.Cu")
		(net "M_J_CPU0_SA_DQS_DP<8>")
	)
	(segment
		(start 394.325348 -242.154202)
		(end 394.826998 -242.154202)
		(width 0.09525)
		(layer "In4.Cu")
		(net "M_J_CPU0_SA_DQS_DP<8>")
	)
	(segment
		(start 423.389044 -230.36022)
		(end 425.966128 -230.36022)
		(width 0.16002)
		(layer "In4.Cu")
		(net "M_J_CPU0_SA_DQS_DP<8>")
	)
	(segment
		(start 409.776168 -232.698544)
		(end 410.14904 -232.325672)
		(width 0.16002)
		(layer "In4.Cu")
		(net "M_J_CPU0_SA_DQS_DP<8>")
	)
	(segment
		(start 379.635004 -242.534186)
		(end 379.643386 -242.539012)
		(width 0.09525)
		(layer "In4.Cu")
		(net "M_J_CPU0_SA_DQS_DP<8>")
	)
	(segment
		(start 407.355294 -233.829098)
		(end 407.632154 -233.829098)
		(width 0.16002)
		(layer "In4.Cu")
		(net "M_J_CPU0_SA_DQS_DP<8>")
	)
	(segment
		(start 408.775408 -233.699304)
		(end 408.775408 -233.172)
		(width 0.16002)
		(layer "In4.Cu")
		(net "M_J_CPU0_SA_DQS_DP<8>")
	)
	(segment
		(start 379.300994 -242.598702)
		(end 379.324362 -242.511834)
		(width 0.09525)
		(layer "In4.Cu")
		(net "M_J_CPU0_SA_DQS_DP<8>")
	)
	(segment
		(start 380.20625 -242.539012)
		(end 380.214632 -242.534186)
		(width 0.09525)
		(layer "In4.Cu")
		(net "M_J_CPU0_SA_DQS_DP<8>")
	)
	(segment
		(start 420.497254 -231.210358)
		(end 420.836598 -230.871014)
		(width 0.16002)
		(layer "In4.Cu")
		(net "M_J_CPU0_SA_DQS_DP<8>")
	)
	(segment
		(start 408.775408 -233.172)
		(end 408.53233 -232.928922)
		(width 0.16002)
		(layer "In4.Cu")
		(net "M_J_CPU0_SA_DQS_DP<8>")
	)
	(segment
		(start 406.04821 -235.523278)
		(end 406.951434 -235.523278)
		(width 0.16002)
		(layer "In4.Cu")
		(net "M_J_CPU0_SA_DQS_DP<8>")
	)
	(segment
		(start 410.379418 -231.081834)
		(end 410.622496 -231.324912)
		(width 0.16002)
		(layer "In4.Cu")
		(net "M_J_CPU0_SA_DQS_DP<8>")
	)
	(segment
		(start 434.726334 -230.211122)
		(end 435.000146 -230.484934)
		(width 0.16002)
		(layer "In4.Cu")
		(net "M_J_CPU0_SA_DQS_DP<8>")
	)
	(segment
		(start 383.394966 -242.534186)
		(end 383.403348 -242.539012)
		(width 0.09525)
		(layer "In4.Cu")
		(net "M_J_CPU0_SA_DQS_DP<8>")
	)
	(segment
		(start 433.215288 -230.211122)
		(end 433.332128 -230.327962)
		(width 0.16002)
		(layer "In4.Cu")
		(net "M_J_CPU0_SA_DQS_DP<8>")
	)
	(segment
		(start 379.454918 -242.864132)
		(end 379.300994 -242.598702)
		(width 0.09525)
		(layer "In4.Cu")
		(net "M_J_CPU0_SA_DQS_DP<8>")
	)
	(segment
		(start 384.33502 -242.534186)
		(end 384.343402 -242.539012)
		(width 0.09525)
		(layer "In4.Cu")
		(net "M_J_CPU0_SA_DQS_DP<8>")
	)
	(segment
		(start 433.929028 -230.211122)
		(end 434.726334 -230.211122)
		(width 0.16002)
		(layer "In4.Cu")
		(net "M_J_CPU0_SA_DQS_DP<8>")
	)
	(segment
		(start 406.951434 -235.523278)
		(end 407.401776 -235.072936)
		(width 0.16002)
		(layer "In4.Cu")
		(net "M_J_CPU0_SA_DQS_DP<8>")
	)
	(segment
		(start 409.905962 -231.55529)
		(end 409.905962 -231.27843)
		(width 0.16002)
		(layer "In4.Cu")
		(net "M_J_CPU0_SA_DQS_DP<8>")
	)
	(segment
		(start 388.094982 -242.534186)
		(end 388.103364 -242.539012)
		(width 0.09525)
		(layer "In4.Cu")
		(net "M_J_CPU0_SA_DQS_DP<8>")
	)
	(segment
		(start 432.04638 -230.36022)
		(end 432.195478 -230.211122)
		(width 0.16002)
		(layer "In4.Cu")
		(net "M_J_CPU0_SA_DQS_DP<8>")
	)
	(segment
		(start 392.146028 -242.615212)
		(end 393.864338 -242.615212)
		(width 0.09525)
		(layer "In4.Cu")
		(net "M_J_CPU0_SA_DQS_DP<8>")
	)
	(segment
		(start 408.53233 -232.652062)
		(end 408.728926 -232.455466)
		(width 0.16002)
		(layer "In4.Cu")
		(net "M_J_CPU0_SA_DQS_DP<8>")
	)
	(segment
		(start 407.875232 -234.072176)
		(end 408.402536 -234.072176)
		(width 0.16002)
		(layer "In4.Cu")
		(net "M_J_CPU0_SA_DQS_DP<8>")
	)
	(segment
		(start 411.1498 -231.324912)
		(end 411.664658 -230.810054)
		(width 0.16002)
		(layer "In4.Cu")
		(net "M_J_CPU0_SA_DQS_DP<8>")
	)
	(segment
		(start 414.875218 -230.040434)
		(end 417.806378 -230.040434)
		(width 0.16002)
		(layer "In4.Cu")
		(net "M_J_CPU0_SA_DQS_DP<8>")
	)
	(segment
		(start 409.905962 -231.27843)
		(end 410.102558 -231.081834)
		(width 0.16002)
		(layer "In4.Cu")
		(net "M_J_CPU0_SA_DQS_DP<8>")
	)
	(segment
		(start 429.128174 -230.848154)
		(end 429.961294 -230.015034)
		(width 0.16002)
		(layer "In4.Cu")
		(net "M_J_CPU0_SA_DQS_DP<8>")
	)
	(segment
		(start 381.146304 -242.539012)
		(end 381.154686 -242.534186)
		(width 0.09525)
		(layer "In4.Cu")
		(net "M_J_CPU0_SA_DQS_DP<8>")
	)
	(segment
		(start 395.787626 -241.502692)
		(end 400.068796 -241.502692)
		(width 0.16002)
		(layer "In4.Cu")
		(net "M_J_CPU0_SA_DQS_DP<8>")
	)
	(segment
		(start 385.84632 -242.539012)
		(end 385.854702 -242.534186)
		(width 0.09525)
		(layer "In4.Cu")
		(net "M_J_CPU0_SA_DQS_DP<8>")
	)
	(segment
		(start 432.195478 -230.211122)
		(end 433.215288 -230.211122)
		(width 0.16002)
		(layer "In4.Cu")
		(net "M_J_CPU0_SA_DQS_DP<8>")
	)
	(segment
		(start 414.105598 -230.810054)
		(end 414.875218 -230.040434)
		(width 0.16002)
		(layer "In4.Cu")
		(net "M_J_CPU0_SA_DQS_DP<8>")
	)
	(segment
		(start 410.14904 -231.798368)
		(end 409.905962 -231.55529)
		(width 0.16002)
		(layer "In4.Cu")
		(net "M_J_CPU0_SA_DQS_DP<8>")
	)
	(segment
		(start 418.976302 -231.210358)
		(end 420.497254 -231.210358)
		(width 0.16002)
		(layer "In4.Cu")
		(net "M_J_CPU0_SA_DQS_DP<8>")
	)
	(segment
		(start 433.332128 -230.327962)
		(end 433.812188 -230.327962)
		(width 0.16002)
		(layer "In4.Cu")
		(net "M_J_CPU0_SA_DQS_DP<8>")
	)
	(segment
		(start 407.401776 -235.072936)
		(end 407.401776 -234.545632)
		(width 0.16002)
		(layer "In4.Cu")
		(net "M_J_CPU0_SA_DQS_DP<8>")
	)
	(segment
		(start 410.102558 -231.081834)
		(end 410.379418 -231.081834)
		(width 0.16002)
		(layer "In4.Cu")
		(net "M_J_CPU0_SA_DQS_DP<8>")
	)
	(segment
		(start 425.966128 -230.36022)
		(end 426.816266 -231.210358)
		(width 0.16002)
		(layer "In4.Cu")
		(net "M_J_CPU0_SA_DQS_DP<8>")
	)
	(segment
		(start 408.728926 -232.455466)
		(end 409.005786 -232.455466)
		(width 0.16002)
		(layer "In4.Cu")
		(net "M_J_CPU0_SA_DQS_DP<8>")
	)
	(segment
		(start 389.035036 -242.534186)
		(end 389.043418 -242.539012)
		(width 0.09525)
		(layer "In4.Cu")
		(net "M_J_CPU0_SA_DQS_DP<8>")
	)
	(segment
		(start 420.836598 -230.871014)
		(end 421.504618 -230.871014)
		(width 0.16002)
		(layer "In4.Cu")
		(net "M_J_CPU0_SA_DQS_DP<8>")
	)
	(segment
		(start 435.000146 -230.484934)
		(end 435.000146 -230.485188)
		(width 0.16002)
		(layer "In4.Cu")
		(net "M_J_CPU0_SA_DQS_DP<8>")
	)
	(segment
		(start 423.051478 -230.022654)
		(end 423.389044 -230.36022)
		(width 0.16002)
		(layer "In4.Cu")
		(net "M_J_CPU0_SA_DQS_DP<8>")
	)
	(segment
		(start 410.14904 -232.325672)
		(end 410.14904 -231.798368)
		(width 0.16002)
		(layer "In4.Cu")
		(net "M_J_CPU0_SA_DQS_DP<8>")
	)
	(segment
		(start 395.764004 -241.502692)
		(end 395.787626 -241.502692)
		(width 0.09525)
		(layer "In4.Cu")
		(net "M_J_CPU0_SA_DQS_DP<8>")
	)
	(segment
		(start 433.812188 -230.327962)
		(end 433.929028 -230.211122)
		(width 0.16002)
		(layer "In4.Cu")
		(net "M_J_CPU0_SA_DQS_DP<8>")
	)
	(segment
		(start 407.632154 -233.829098)
		(end 407.875232 -234.072176)
		(width 0.16002)
		(layer "In4.Cu")
		(net "M_J_CPU0_SA_DQS_DP<8>")
	)
	(segment
		(start 407.158698 -234.302554)
		(end 407.158698 -234.025694)
		(width 0.16002)
		(layer "In4.Cu")
		(net "M_J_CPU0_SA_DQS_DP<8>")
	)
	(segment
		(start 391.486136 -242.539012)
		(end 391.494518 -242.534186)
		(width 0.09525)
		(layer "In4.Cu")
		(net "M_J_CPU0_SA_DQS_DP<8>")
	)
	(segment
		(start 393.864338 -242.615212)
		(end 394.325348 -242.154202)
		(width 0.09525)
		(layer "In4.Cu")
		(net "M_J_CPU0_SA_DQS_DP<8>")
	)
	(segment
		(start 407.158698 -234.025694)
		(end 407.355294 -233.829098)
		(width 0.16002)
		(layer "In4.Cu")
		(net "M_J_CPU0_SA_DQS_DP<8>")
	)
	(segment
		(start 407.401776 -234.545632)
		(end 407.158698 -234.302554)
		(width 0.16002)
		(layer "In4.Cu")
		(net "M_J_CPU0_SA_DQS_DP<8>")
	)
	(segment
		(start 400.068796 -241.502692)
		(end 406.04821 -235.523278)
		(width 0.16002)
		(layer "In4.Cu")
		(net "M_J_CPU0_SA_DQS_DP<8>")
	)
	(segment
		(start 426.816266 -231.210358)
		(end 428.193454 -231.210358)
		(width 0.16002)
		(layer "In4.Cu")
		(net "M_J_CPU0_SA_DQS_DP<8>")
	)
	(arc
		(start 381.154686 -242.534186)
		(mid 381.339718 -242.488272)
		(end 381.523494 -242.539012)
		(width 0.09525)
		(layer "In4.Cu")
		(net "M_J_CPU0_SA_DQS_DP<8>")
	)
	(arc
		(start 379.643386 -242.539012)
		(mid 379.924818 -242.614767)
		(end 380.20625 -242.539012)
		(width 0.09525)
		(layer "In4.Cu")
		(net "M_J_CPU0_SA_DQS_DP<8>")
	)
	(arc
		(start 389.043418 -242.539012)
		(mid 389.32485 -242.614767)
		(end 389.606282 -242.539012)
		(width 0.09525)
		(layer "In4.Cu")
		(net "M_J_CPU0_SA_DQS_DP<8>")
	)
	(arc
		(start 385.854702 -242.534186)
		(mid 386.039734 -242.488272)
		(end 386.22351 -242.539012)
		(width 0.09525)
		(layer "In4.Cu")
		(net "M_J_CPU0_SA_DQS_DP<8>")
	)
	(arc
		(start 383.966212 -242.539012)
		(mid 384.149987 -242.48824)
		(end 384.33502 -242.534186)
		(width 0.09525)
		(layer "In4.Cu")
		(net "M_J_CPU0_SA_DQS_DP<8>")
	)
	(arc
		(start 389.614664 -242.534186)
		(mid 389.799696 -242.488272)
		(end 389.983472 -242.539012)
		(width 0.09525)
		(layer "In4.Cu")
		(net "M_J_CPU0_SA_DQS_DP<8>")
	)
	(arc
		(start 381.523494 -242.539012)
		(mid 381.804926 -242.614767)
		(end 382.086358 -242.539012)
		(width 0.09525)
		(layer "In4.Cu")
		(net "M_J_CPU0_SA_DQS_DP<8>")
	)
	(arc
		(start 384.343402 -242.539012)
		(mid 384.624834 -242.614767)
		(end 384.906266 -242.539012)
		(width 0.09525)
		(layer "In4.Cu")
		(net "M_J_CPU0_SA_DQS_DP<8>")
	)
	(arc
		(start 391.494518 -242.534186)
		(mid 391.679804 -242.48815)
		(end 391.863834 -242.539012)
		(width 0.09525)
		(layer "In4.Cu")
		(net "M_J_CPU0_SA_DQS_DP<8>")
	)
	(arc
		(start 385.283456 -242.539012)
		(mid 385.564888 -242.614767)
		(end 385.84632 -242.539012)
		(width 0.09525)
		(layer "In4.Cu")
		(net "M_J_CPU0_SA_DQS_DP<8>")
	)
	(arc
		(start 379.324362 -242.511834)
		(mid 379.482112 -242.489315)
		(end 379.635004 -242.534186)
		(width 0.09525)
		(layer "In4.Cu")
		(net "M_J_CPU0_SA_DQS_DP<8>")
	)
	(arc
		(start 390.923272 -242.539012)
		(mid 391.204704 -242.614767)
		(end 391.486136 -242.539012)
		(width 0.09525)
		(layer "In4.Cu")
		(net "M_J_CPU0_SA_DQS_DP<8>")
	)
	(arc
		(start 387.16331 -242.539012)
		(mid 387.444742 -242.614767)
		(end 387.726174 -242.539012)
		(width 0.09525)
		(layer "In4.Cu")
		(net "M_J_CPU0_SA_DQS_DP<8>")
	)
	(arc
		(start 380.58344 -242.539012)
		(mid 380.864872 -242.614767)
		(end 381.146304 -242.539012)
		(width 0.09525)
		(layer "In4.Cu")
		(net "M_J_CPU0_SA_DQS_DP<8>")
	)
	(arc
		(start 380.214632 -242.534186)
		(mid 380.399664 -242.488272)
		(end 380.58344 -242.539012)
		(width 0.09525)
		(layer "In4.Cu")
		(net "M_J_CPU0_SA_DQS_DP<8>")
	)
	(arc
		(start 383.026158 -242.539012)
		(mid 383.209933 -242.48824)
		(end 383.394966 -242.534186)
		(width 0.09525)
		(layer "In4.Cu")
		(net "M_J_CPU0_SA_DQS_DP<8>")
	)
	(arc
		(start 384.914648 -242.534186)
		(mid 385.09968 -242.488272)
		(end 385.283456 -242.539012)
		(width 0.09525)
		(layer "In4.Cu")
		(net "M_J_CPU0_SA_DQS_DP<8>")
	)
	(arc
		(start 383.403348 -242.539012)
		(mid 383.68478 -242.614767)
		(end 383.966212 -242.539012)
		(width 0.09525)
		(layer "In4.Cu")
		(net "M_J_CPU0_SA_DQS_DP<8>")
	)
	(arc
		(start 382.463294 -242.539012)
		(mid 382.744726 -242.614767)
		(end 383.026158 -242.539012)
		(width 0.09525)
		(layer "In4.Cu")
		(net "M_J_CPU0_SA_DQS_DP<8>")
	)
	(arc
		(start 390.546336 -242.539012)
		(mid 390.734804 -242.488335)
		(end 390.923272 -242.539012)
		(width 0.09525)
		(layer "In4.Cu")
		(net "M_J_CPU0_SA_DQS_DP<8>")
	)
	(arc
		(start 386.22351 -242.539012)
		(mid 386.504942 -242.614767)
		(end 386.786374 -242.539012)
		(width 0.09525)
		(layer "In4.Cu")
		(net "M_J_CPU0_SA_DQS_DP<8>")
	)
	(arc
		(start 386.786374 -242.539012)
		(mid 386.974842 -242.488335)
		(end 387.16331 -242.539012)
		(width 0.09525)
		(layer "In4.Cu")
		(net "M_J_CPU0_SA_DQS_DP<8>")
	)
	(arc
		(start 387.726174 -242.539012)
		(mid 387.909949 -242.48824)
		(end 388.094982 -242.534186)
		(width 0.09525)
		(layer "In4.Cu")
		(net "M_J_CPU0_SA_DQS_DP<8>")
	)
	(arc
		(start 388.666228 -242.539012)
		(mid 388.850003 -242.48824)
		(end 389.035036 -242.534186)
		(width 0.09525)
		(layer "In4.Cu")
		(net "M_J_CPU0_SA_DQS_DP<8>")
	)
	(arc
		(start 389.983472 -242.539012)
		(mid 390.264904 -242.614767)
		(end 390.546336 -242.539012)
		(width 0.09525)
		(layer "In4.Cu")
		(net "M_J_CPU0_SA_DQS_DP<8>")
	)
	(arc
		(start 388.103364 -242.539012)
		(mid 388.384796 -242.614767)
		(end 388.666228 -242.539012)
		(width 0.09525)
		(layer "In4.Cu")
		(net "M_J_CPU0_SA_DQS_DP<8>")
	)
	(arc
		(start 391.863834 -242.539012)
		(mid 391.999886 -242.595781)
		(end 392.146028 -242.615212)
		(width 0.09525)
		(layer "In4.Cu")
		(net "M_J_CPU0_SA_DQS_DP<8>")
	)
	(arc
		(start 382.086358 -242.539012)
		(mid 382.274826 -242.488335)
		(end 382.463294 -242.539012)
		(width 0.09525)
		(layer "In4.Cu")
		(net "M_J_CPU0_SA_DQS_DP<8>")
	)
	(segment
		(start 378.988066 -238.270034)
		(end 379.454918 -238.004096)
		(width 0.12954)
		(layer "F.Cu")
		(net "M_J_CPU0_SA_DQS_DP<7>")
	)
	(segment
		(start 425.966128 -221.010226)
		(end 426.816012 -221.86011)
		(width 0.16002)
		(layer "In4.Cu")
		(net "M_J_CPU0_SA_DQS_DP<7>")
	)
	(segment
		(start 409.851352 -220.811852)
		(end 410.127958 -220.811852)
		(width 0.16002)
		(layer "In4.Cu")
		(net "M_J_CPU0_SA_DQS_DP<7>")
	)
	(segment
		(start 411.596586 -221.478348)
		(end 411.596586 -221.007686)
		(width 0.16002)
		(layer "In4.Cu")
		(net "M_J_CPU0_SA_DQS_DP<7>")
	)
	(segment
		(start 413.22117 -221.85122)
		(end 413.61233 -221.46006)
		(width 0.16002)
		(layer "In4.Cu")
		(net "M_J_CPU0_SA_DQS_DP<7>")
	)
	(segment
		(start 428.193708 -221.86011)
		(end 428.555658 -221.49816)
		(width 0.16002)
		(layer "In4.Cu")
		(net "M_J_CPU0_SA_DQS_DP<7>")
	)
	(segment
		(start 384.906266 -237.678976)
		(end 384.914648 -237.67415)
		(width 0.09525)
		(layer "In4.Cu")
		(net "M_J_CPU0_SA_DQS_DP<7>")
	)
	(segment
		(start 394.287756 -236.51591)
		(end 394.525754 -236.277912)
		(width 0.09525)
		(layer "In4.Cu")
		(net "M_J_CPU0_SA_DQS_DP<7>")
	)
	(segment
		(start 432.195478 -220.861128)
		(end 433.182268 -220.861128)
		(width 0.16002)
		(layer "In4.Cu")
		(net "M_J_CPU0_SA_DQS_DP<7>")
	)
	(segment
		(start 409.655518 -221.007686)
		(end 409.851352 -220.811852)
		(width 0.16002)
		(layer "In4.Cu")
		(net "M_J_CPU0_SA_DQS_DP<7>")
	)
	(segment
		(start 411.79242 -220.811852)
		(end 412.069026 -220.811852)
		(width 0.16002)
		(layer "In4.Cu")
		(net "M_J_CPU0_SA_DQS_DP<7>")
	)
	(segment
		(start 423.389044 -221.010226)
		(end 425.966128 -221.010226)
		(width 0.16002)
		(layer "In4.Cu")
		(net "M_J_CPU0_SA_DQS_DP<7>")
	)
	(segment
		(start 383.394966 -237.67415)
		(end 383.403348 -237.678976)
		(width 0.09525)
		(layer "In4.Cu")
		(net "M_J_CPU0_SA_DQS_DP<7>")
	)
	(segment
		(start 414.875218 -220.69044)
		(end 417.806378 -220.69044)
		(width 0.16002)
		(layer "In4.Cu")
		(net "M_J_CPU0_SA_DQS_DP<7>")
	)
	(segment
		(start 395.458188 -235.705142)
		(end 395.776704 -235.705142)
		(width 0.09525)
		(layer "In4.Cu")
		(net "M_J_CPU0_SA_DQS_DP<7>")
	)
	(segment
		(start 412.637732 -221.85122)
		(end 413.22117 -221.85122)
		(width 0.16002)
		(layer "In4.Cu")
		(net "M_J_CPU0_SA_DQS_DP<7>")
	)
	(segment
		(start 410.696664 -221.85122)
		(end 411.223714 -221.85122)
		(width 0.16002)
		(layer "In4.Cu")
		(net "M_J_CPU0_SA_DQS_DP<7>")
	)
	(segment
		(start 395.776704 -235.705142)
		(end 395.835632 -235.76407)
		(width 0.09525)
		(layer "In4.Cu")
		(net "M_J_CPU0_SA_DQS_DP<7>")
	)
	(segment
		(start 394.885418 -236.277912)
		(end 395.458188 -235.705142)
		(width 0.09525)
		(layer "In4.Cu")
		(net "M_J_CPU0_SA_DQS_DP<7>")
	)
	(segment
		(start 429.128174 -221.49816)
		(end 429.961294 -220.66504)
		(width 0.16002)
		(layer "In4.Cu")
		(net "M_J_CPU0_SA_DQS_DP<7>")
	)
	(segment
		(start 418.976048 -221.86011)
		(end 420.497508 -221.86011)
		(width 0.16002)
		(layer "In4.Cu")
		(net "M_J_CPU0_SA_DQS_DP<7>")
	)
	(segment
		(start 429.961294 -220.66504)
		(end 430.613058 -220.66504)
		(width 0.16002)
		(layer "In4.Cu")
		(net "M_J_CPU0_SA_DQS_DP<7>")
	)
	(segment
		(start 389.606282 -237.678976)
		(end 389.614664 -237.67415)
		(width 0.09525)
		(layer "In4.Cu")
		(net "M_J_CPU0_SA_DQS_DP<7>")
	)
	(segment
		(start 379.635004 -237.67415)
		(end 379.643386 -237.678976)
		(width 0.09525)
		(layer "In4.Cu")
		(net "M_J_CPU0_SA_DQS_DP<7>")
	)
	(segment
		(start 379.454918 -238.004096)
		(end 379.300994 -237.738666)
		(width 0.09525)
		(layer "In4.Cu")
		(net "M_J_CPU0_SA_DQS_DP<7>")
	)
	(segment
		(start 423.051478 -220.67266)
		(end 423.389044 -221.010226)
		(width 0.16002)
		(layer "In4.Cu")
		(net "M_J_CPU0_SA_DQS_DP<7>")
	)
	(segment
		(start 428.555658 -221.49816)
		(end 429.128174 -221.49816)
		(width 0.16002)
		(layer "In4.Cu")
		(net "M_J_CPU0_SA_DQS_DP<7>")
	)
	(segment
		(start 432.04638 -221.010226)
		(end 432.195478 -220.861128)
		(width 0.16002)
		(layer "In4.Cu")
		(net "M_J_CPU0_SA_DQS_DP<7>")
	)
	(segment
		(start 410.127958 -220.811852)
		(end 410.323792 -221.007686)
		(width 0.16002)
		(layer "In4.Cu")
		(net "M_J_CPU0_SA_DQS_DP<7>")
	)
	(segment
		(start 421.504618 -221.52102)
		(end 422.352978 -220.67266)
		(width 0.16002)
		(layer "In4.Cu")
		(net "M_J_CPU0_SA_DQS_DP<7>")
	)
	(segment
		(start 426.816012 -221.86011)
		(end 428.193708 -221.86011)
		(width 0.16002)
		(layer "In4.Cu")
		(net "M_J_CPU0_SA_DQS_DP<7>")
	)
	(segment
		(start 393.481052 -237.59033)
		(end 394.287756 -236.783626)
		(width 0.09525)
		(layer "In4.Cu")
		(net "M_J_CPU0_SA_DQS_DP<7>")
	)
	(segment
		(start 412.069026 -220.811852)
		(end 412.26486 -221.007686)
		(width 0.16002)
		(layer "In4.Cu")
		(net "M_J_CPU0_SA_DQS_DP<7>")
	)
	(segment
		(start 393.351258 -237.687612)
		(end 393.36599 -237.678976)
		(width 0.09525)
		(layer "In4.Cu")
		(net "M_J_CPU0_SA_DQS_DP<7>")
	)
	(segment
		(start 409.282646 -221.85122)
		(end 409.655518 -221.478348)
		(width 0.16002)
		(layer "In4.Cu")
		(net "M_J_CPU0_SA_DQS_DP<7>")
	)
	(segment
		(start 430.958244 -221.010226)
		(end 432.04638 -221.010226)
		(width 0.16002)
		(layer "In4.Cu")
		(net "M_J_CPU0_SA_DQS_DP<7>")
	)
	(segment
		(start 417.806378 -220.69044)
		(end 418.976048 -221.86011)
		(width 0.16002)
		(layer "In4.Cu")
		(net "M_J_CPU0_SA_DQS_DP<7>")
	)
	(segment
		(start 412.26486 -221.478348)
		(end 412.637732 -221.85122)
		(width 0.16002)
		(layer "In4.Cu")
		(net "M_J_CPU0_SA_DQS_DP<7>")
	)
	(segment
		(start 397.310102 -235.76407)
		(end 404.295102 -228.77907)
		(width 0.16002)
		(layer "In4.Cu")
		(net "M_J_CPU0_SA_DQS_DP<7>")
	)
	(segment
		(start 434.726334 -220.861128)
		(end 435.000146 -221.13494)
		(width 0.16002)
		(layer "In4.Cu")
		(net "M_J_CPU0_SA_DQS_DP<7>")
	)
	(segment
		(start 412.26486 -221.007686)
		(end 412.26486 -221.478348)
		(width 0.16002)
		(layer "In4.Cu")
		(net "M_J_CPU0_SA_DQS_DP<7>")
	)
	(segment
		(start 408.868372 -221.85122)
		(end 409.282646 -221.85122)
		(width 0.16002)
		(layer "In4.Cu")
		(net "M_J_CPU0_SA_DQS_DP<7>")
	)
	(segment
		(start 384.33502 -237.67415)
		(end 384.343402 -237.678976)
		(width 0.09525)
		(layer "In4.Cu")
		(net "M_J_CPU0_SA_DQS_DP<7>")
	)
	(segment
		(start 411.596586 -221.007686)
		(end 411.79242 -220.811852)
		(width 0.16002)
		(layer "In4.Cu")
		(net "M_J_CPU0_SA_DQS_DP<7>")
	)
	(segment
		(start 422.352978 -220.67266)
		(end 423.051478 -220.67266)
		(width 0.16002)
		(layer "In4.Cu")
		(net "M_J_CPU0_SA_DQS_DP<7>")
	)
	(segment
		(start 433.182268 -220.861128)
		(end 433.299108 -220.977968)
		(width 0.16002)
		(layer "In4.Cu")
		(net "M_J_CPU0_SA_DQS_DP<7>")
	)
	(segment
		(start 404.295102 -228.77907)
		(end 404.295102 -226.42449)
		(width 0.16002)
		(layer "In4.Cu")
		(net "M_J_CPU0_SA_DQS_DP<7>")
	)
	(segment
		(start 379.300994 -237.738666)
		(end 379.324362 -237.651798)
		(width 0.09525)
		(layer "In4.Cu")
		(net "M_J_CPU0_SA_DQS_DP<7>")
	)
	(segment
		(start 394.287756 -236.783626)
		(end 394.287756 -236.51591)
		(width 0.09525)
		(layer "In4.Cu")
		(net "M_J_CPU0_SA_DQS_DP<7>")
	)
	(segment
		(start 409.655518 -221.478348)
		(end 409.655518 -221.007686)
		(width 0.16002)
		(layer "In4.Cu")
		(net "M_J_CPU0_SA_DQS_DP<7>")
	)
	(segment
		(start 391.863326 -237.678976)
		(end 391.87374 -237.685072)
		(width 0.09525)
		(layer "In4.Cu")
		(net "M_J_CPU0_SA_DQS_DP<7>")
	)
	(segment
		(start 430.613058 -220.66504)
		(end 430.958244 -221.010226)
		(width 0.16002)
		(layer "In4.Cu")
		(net "M_J_CPU0_SA_DQS_DP<7>")
	)
	(segment
		(start 389.035036 -237.67415)
		(end 389.043418 -237.678976)
		(width 0.09525)
		(layer "In4.Cu")
		(net "M_J_CPU0_SA_DQS_DP<7>")
	)
	(segment
		(start 413.61233 -221.46006)
		(end 414.105598 -221.46006)
		(width 0.16002)
		(layer "In4.Cu")
		(net "M_J_CPU0_SA_DQS_DP<7>")
	)
	(segment
		(start 404.295102 -226.42449)
		(end 408.868372 -221.85122)
		(width 0.16002)
		(layer "In4.Cu")
		(net "M_J_CPU0_SA_DQS_DP<7>")
	)
	(segment
		(start 381.146304 -237.678976)
		(end 381.154686 -237.67415)
		(width 0.09525)
		(layer "In4.Cu")
		(net "M_J_CPU0_SA_DQS_DP<7>")
	)
	(segment
		(start 414.105598 -221.46006)
		(end 414.875218 -220.69044)
		(width 0.16002)
		(layer "In4.Cu")
		(net "M_J_CPU0_SA_DQS_DP<7>")
	)
	(segment
		(start 433.896008 -220.861128)
		(end 434.726334 -220.861128)
		(width 0.16002)
		(layer "In4.Cu")
		(net "M_J_CPU0_SA_DQS_DP<7>")
	)
	(segment
		(start 380.20625 -237.678976)
		(end 380.214632 -237.67415)
		(width 0.09525)
		(layer "In4.Cu")
		(net "M_J_CPU0_SA_DQS_DP<7>")
	)
	(segment
		(start 410.323792 -221.007686)
		(end 410.323792 -221.478348)
		(width 0.16002)
		(layer "In4.Cu")
		(net "M_J_CPU0_SA_DQS_DP<7>")
	)
	(segment
		(start 394.525754 -236.277912)
		(end 394.885418 -236.277912)
		(width 0.09525)
		(layer "In4.Cu")
		(net "M_J_CPU0_SA_DQS_DP<7>")
	)
	(segment
		(start 385.84632 -237.678976)
		(end 385.854702 -237.67415)
		(width 0.09525)
		(layer "In4.Cu")
		(net "M_J_CPU0_SA_DQS_DP<7>")
	)
	(segment
		(start 433.779168 -220.977968)
		(end 433.896008 -220.861128)
		(width 0.16002)
		(layer "In4.Cu")
		(net "M_J_CPU0_SA_DQS_DP<7>")
	)
	(segment
		(start 420.497508 -221.86011)
		(end 420.836598 -221.52102)
		(width 0.16002)
		(layer "In4.Cu")
		(net "M_J_CPU0_SA_DQS_DP<7>")
	)
	(segment
		(start 395.835632 -235.76407)
		(end 395.859254 -235.76407)
		(width 0.09525)
		(layer "In4.Cu")
		(net "M_J_CPU0_SA_DQS_DP<7>")
	)
	(segment
		(start 420.836598 -221.52102)
		(end 421.504618 -221.52102)
		(width 0.16002)
		(layer "In4.Cu")
		(net "M_J_CPU0_SA_DQS_DP<7>")
	)
	(segment
		(start 392.425936 -237.678976)
		(end 392.434318 -237.67415)
		(width 0.09525)
		(layer "In4.Cu")
		(net "M_J_CPU0_SA_DQS_DP<7>")
	)
	(segment
		(start 388.094982 -237.67415)
		(end 388.103364 -237.678976)
		(width 0.09525)
		(layer "In4.Cu")
		(net "M_J_CPU0_SA_DQS_DP<7>")
	)
	(segment
		(start 391.854944 -237.67415)
		(end 391.863326 -237.678976)
		(width 0.09525)
		(layer "In4.Cu")
		(net "M_J_CPU0_SA_DQS_DP<7>")
	)
	(segment
		(start 433.299108 -220.977968)
		(end 433.779168 -220.977968)
		(width 0.16002)
		(layer "In4.Cu")
		(net "M_J_CPU0_SA_DQS_DP<7>")
	)
	(segment
		(start 410.323792 -221.478348)
		(end 410.696664 -221.85122)
		(width 0.16002)
		(layer "In4.Cu")
		(net "M_J_CPU0_SA_DQS_DP<7>")
	)
	(segment
		(start 395.859254 -235.76407)
		(end 397.310102 -235.76407)
		(width 0.16002)
		(layer "In4.Cu")
		(net "M_J_CPU0_SA_DQS_DP<7>")
	)
	(segment
		(start 411.223714 -221.85122)
		(end 411.596586 -221.478348)
		(width 0.16002)
		(layer "In4.Cu")
		(net "M_J_CPU0_SA_DQS_DP<7>")
	)
	(arc
		(start 388.666228 -237.678976)
		(mid 388.850003 -237.628204)
		(end 389.035036 -237.67415)
		(width 0.09525)
		(layer "In4.Cu")
		(net "M_J_CPU0_SA_DQS_DP<7>")
	)
	(arc
		(start 384.914648 -237.67415)
		(mid 385.09968 -237.628236)
		(end 385.283456 -237.678976)
		(width 0.09525)
		(layer "In4.Cu")
		(net "M_J_CPU0_SA_DQS_DP<7>")
	)
	(arc
		(start 385.854702 -237.67415)
		(mid 386.039734 -237.628236)
		(end 386.22351 -237.678976)
		(width 0.09525)
		(layer "In4.Cu")
		(net "M_J_CPU0_SA_DQS_DP<7>")
	)
	(arc
		(start 393.36599 -237.678976)
		(mid 393.426405 -237.638396)
		(end 393.481052 -237.59033)
		(width 0.09525)
		(layer "In4.Cu")
		(net "M_J_CPU0_SA_DQS_DP<7>")
	)
	(arc
		(start 381.154686 -237.67415)
		(mid 381.339718 -237.628236)
		(end 381.523494 -237.678976)
		(width 0.09525)
		(layer "In4.Cu")
		(net "M_J_CPU0_SA_DQS_DP<7>")
	)
	(arc
		(start 379.324362 -237.651798)
		(mid 379.482112 -237.629279)
		(end 379.635004 -237.67415)
		(width 0.09525)
		(layer "In4.Cu")
		(net "M_J_CPU0_SA_DQS_DP<7>")
	)
	(arc
		(start 391.87374 -237.685072)
		(mid 392.150648 -237.754749)
		(end 392.425936 -237.678976)
		(width 0.09525)
		(layer "In4.Cu")
		(net "M_J_CPU0_SA_DQS_DP<7>")
	)
	(arc
		(start 383.966212 -237.678976)
		(mid 384.149987 -237.628204)
		(end 384.33502 -237.67415)
		(width 0.09525)
		(layer "In4.Cu")
		(net "M_J_CPU0_SA_DQS_DP<7>")
	)
	(arc
		(start 386.786374 -237.678976)
		(mid 386.974842 -237.628299)
		(end 387.16331 -237.678976)
		(width 0.09525)
		(layer "In4.Cu")
		(net "M_J_CPU0_SA_DQS_DP<7>")
	)
	(arc
		(start 381.523494 -237.678976)
		(mid 381.804926 -237.754731)
		(end 382.086358 -237.678976)
		(width 0.09525)
		(layer "In4.Cu")
		(net "M_J_CPU0_SA_DQS_DP<7>")
	)
	(arc
		(start 388.103364 -237.678976)
		(mid 388.384796 -237.754731)
		(end 388.666228 -237.678976)
		(width 0.09525)
		(layer "In4.Cu")
		(net "M_J_CPU0_SA_DQS_DP<7>")
	)
	(arc
		(start 384.343402 -237.678976)
		(mid 384.624834 -237.754731)
		(end 384.906266 -237.678976)
		(width 0.09525)
		(layer "In4.Cu")
		(net "M_J_CPU0_SA_DQS_DP<7>")
	)
	(arc
		(start 391.486136 -237.678976)
		(mid 391.669911 -237.628204)
		(end 391.854944 -237.67415)
		(width 0.09525)
		(layer "In4.Cu")
		(net "M_J_CPU0_SA_DQS_DP<7>")
	)
	(arc
		(start 392.803126 -237.678976)
		(mid 393.076054 -237.75479)
		(end 393.351258 -237.687612)
		(width 0.09525)
		(layer "In4.Cu")
		(net "M_J_CPU0_SA_DQS_DP<7>")
	)
	(arc
		(start 390.923272 -237.678976)
		(mid 391.204704 -237.754731)
		(end 391.486136 -237.678976)
		(width 0.09525)
		(layer "In4.Cu")
		(net "M_J_CPU0_SA_DQS_DP<7>")
	)
	(arc
		(start 380.214632 -237.67415)
		(mid 380.399664 -237.628236)
		(end 380.58344 -237.678976)
		(width 0.09525)
		(layer "In4.Cu")
		(net "M_J_CPU0_SA_DQS_DP<7>")
	)
	(arc
		(start 382.086358 -237.678976)
		(mid 382.274826 -237.628299)
		(end 382.463294 -237.678976)
		(width 0.09525)
		(layer "In4.Cu")
		(net "M_J_CPU0_SA_DQS_DP<7>")
	)
	(arc
		(start 383.403348 -237.678976)
		(mid 383.68478 -237.754731)
		(end 383.966212 -237.678976)
		(width 0.09525)
		(layer "In4.Cu")
		(net "M_J_CPU0_SA_DQS_DP<7>")
	)
	(arc
		(start 385.283456 -237.678976)
		(mid 385.564888 -237.754731)
		(end 385.84632 -237.678976)
		(width 0.09525)
		(layer "In4.Cu")
		(net "M_J_CPU0_SA_DQS_DP<7>")
	)
	(arc
		(start 389.614664 -237.67415)
		(mid 389.799696 -237.628236)
		(end 389.983472 -237.678976)
		(width 0.09525)
		(layer "In4.Cu")
		(net "M_J_CPU0_SA_DQS_DP<7>")
	)
	(arc
		(start 390.546336 -237.678976)
		(mid 390.734804 -237.628299)
		(end 390.923272 -237.678976)
		(width 0.09525)
		(layer "In4.Cu")
		(net "M_J_CPU0_SA_DQS_DP<7>")
	)
	(arc
		(start 387.726174 -237.678976)
		(mid 387.909949 -237.628204)
		(end 388.094982 -237.67415)
		(width 0.09525)
		(layer "In4.Cu")
		(net "M_J_CPU0_SA_DQS_DP<7>")
	)
	(arc
		(start 392.434318 -237.67415)
		(mid 392.61935 -237.628236)
		(end 392.803126 -237.678976)
		(width 0.09525)
		(layer "In4.Cu")
		(net "M_J_CPU0_SA_DQS_DP<7>")
	)
	(arc
		(start 383.026158 -237.678976)
		(mid 383.209933 -237.628204)
		(end 383.394966 -237.67415)
		(width 0.09525)
		(layer "In4.Cu")
		(net "M_J_CPU0_SA_DQS_DP<7>")
	)
	(arc
		(start 379.643386 -237.678976)
		(mid 379.924818 -237.754731)
		(end 380.20625 -237.678976)
		(width 0.09525)
		(layer "In4.Cu")
		(net "M_J_CPU0_SA_DQS_DP<7>")
	)
	(arc
		(start 386.22351 -237.678976)
		(mid 386.504942 -237.754731)
		(end 386.786374 -237.678976)
		(width 0.09525)
		(layer "In4.Cu")
		(net "M_J_CPU0_SA_DQS_DP<7>")
	)
	(arc
		(start 389.043418 -237.678976)
		(mid 389.32485 -237.754731)
		(end 389.606282 -237.678976)
		(width 0.09525)
		(layer "In4.Cu")
		(net "M_J_CPU0_SA_DQS_DP<7>")
	)
	(arc
		(start 387.16331 -237.678976)
		(mid 387.444742 -237.754731)
		(end 387.726174 -237.678976)
		(width 0.09525)
		(layer "In4.Cu")
		(net "M_J_CPU0_SA_DQS_DP<7>")
	)
	(arc
		(start 380.58344 -237.678976)
		(mid 380.864872 -237.754731)
		(end 381.146304 -237.678976)
		(width 0.09525)
		(layer "In4.Cu")
		(net "M_J_CPU0_SA_DQS_DP<7>")
	)
	(arc
		(start 382.463294 -237.678976)
		(mid 382.744726 -237.754731)
		(end 383.026158 -237.678976)
		(width 0.09525)
		(layer "In4.Cu")
		(net "M_J_CPU0_SA_DQS_DP<7>")
	)
	(arc
		(start 389.983472 -237.678976)
		(mid 390.264904 -237.754731)
		(end 390.546336 -237.678976)
		(width 0.09525)
		(layer "In4.Cu")
		(net "M_J_CPU0_SA_DQS_DP<7>")
	)
	(segment
		(start 378.988066 -233.409998)
		(end 379.454918 -233.14406)
		(width 0.12954)
		(layer "F.Cu")
		(net "M_J_CPU0_SA_DQS_DP<6>")
	)
	(segment
		(start 411.845252 -211.439252)
		(end 412.041086 -211.635086)
		(width 0.16002)
		(layer "In4.Cu")
		(net "M_J_CPU0_SA_DQS_DP<6>")
	)
	(segment
		(start 416.336988 -211.457286)
		(end 416.817048 -211.457286)
		(width 0.16002)
		(layer "In4.Cu")
		(net "M_J_CPU0_SA_DQS_DP<6>")
	)
	(segment
		(start 380.20625 -232.81894)
		(end 380.214632 -232.814114)
		(width 0.09525)
		(layer "In4.Cu")
		(net "M_J_CPU0_SA_DQS_DP<6>")
	)
	(segment
		(start 433.911248 -211.627974)
		(end 434.028088 -211.511134)
		(width 0.16002)
		(layer "In4.Cu")
		(net "M_J_CPU0_SA_DQS_DP<6>")
	)
	(segment
		(start 379.635004 -232.814114)
		(end 379.643386 -232.81894)
		(width 0.09525)
		(layer "In4.Cu")
		(net "M_J_CPU0_SA_DQS_DP<6>")
	)
	(segment
		(start 410.47289 -212.724492)
		(end 410.99994 -212.724492)
		(width 0.16002)
		(layer "In4.Cu")
		(net "M_J_CPU0_SA_DQS_DP<6>")
	)
	(segment
		(start 410.100018 -211.635086)
		(end 410.100018 -212.35162)
		(width 0.16002)
		(layer "In4.Cu")
		(net "M_J_CPU0_SA_DQS_DP<6>")
	)
	(segment
		(start 426.816012 -212.510116)
		(end 428.193708 -212.510116)
		(width 0.16002)
		(layer "In4.Cu")
		(net "M_J_CPU0_SA_DQS_DP<6>")
	)
	(segment
		(start 379.454918 -233.14406)
		(end 379.300994 -232.87863)
		(width 0.09525)
		(layer "In4.Cu")
		(net "M_J_CPU0_SA_DQS_DP<6>")
	)
	(segment
		(start 412.041086 -212.35162)
		(end 412.413958 -212.724492)
		(width 0.16002)
		(layer "In4.Cu")
		(net "M_J_CPU0_SA_DQS_DP<6>")
	)
	(segment
		(start 420.497508 -212.510116)
		(end 420.836598 -212.171026)
		(width 0.16002)
		(layer "In4.Cu")
		(net "M_J_CPU0_SA_DQS_DP<6>")
	)
	(segment
		(start 388.094982 -232.814114)
		(end 388.103364 -232.81894)
		(width 0.09525)
		(layer "In4.Cu")
		(net "M_J_CPU0_SA_DQS_DP<6>")
	)
	(segment
		(start 421.504618 -212.171026)
		(end 422.352978 -211.322666)
		(width 0.16002)
		(layer "In4.Cu")
		(net "M_J_CPU0_SA_DQS_DP<6>")
	)
	(segment
		(start 412.413958 -212.724492)
		(end 413.064452 -212.724492)
		(width 0.16002)
		(layer "In4.Cu")
		(net "M_J_CPU0_SA_DQS_DP<6>")
	)
	(segment
		(start 389.606282 -232.81894)
		(end 389.614664 -232.814114)
		(width 0.09525)
		(layer "In4.Cu")
		(net "M_J_CPU0_SA_DQS_DP<6>")
	)
	(segment
		(start 383.394966 -232.814114)
		(end 383.403348 -232.81894)
		(width 0.09525)
		(layer "In4.Cu")
		(net "M_J_CPU0_SA_DQS_DP<6>")
	)
	(segment
		(start 409.904184 -211.439252)
		(end 410.100018 -211.635086)
		(width 0.16002)
		(layer "In4.Cu")
		(net "M_J_CPU0_SA_DQS_DP<6>")
	)
	(segment
		(start 411.372812 -211.635086)
		(end 411.568646 -211.439252)
		(width 0.16002)
		(layer "In4.Cu")
		(net "M_J_CPU0_SA_DQS_DP<6>")
	)
	(segment
		(start 411.372812 -212.35162)
		(end 411.372812 -211.635086)
		(width 0.16002)
		(layer "In4.Cu")
		(net "M_J_CPU0_SA_DQS_DP<6>")
	)
	(segment
		(start 420.836598 -212.171026)
		(end 421.504618 -212.171026)
		(width 0.16002)
		(layer "In4.Cu")
		(net "M_J_CPU0_SA_DQS_DP<6>")
	)
	(segment
		(start 409.058872 -212.724492)
		(end 409.431744 -212.35162)
		(width 0.16002)
		(layer "In4.Cu")
		(net "M_J_CPU0_SA_DQS_DP<6>")
	)
	(segment
		(start 389.035036 -232.814114)
		(end 389.043418 -232.81894)
		(width 0.09525)
		(layer "In4.Cu")
		(net "M_J_CPU0_SA_DQS_DP<6>")
	)
	(segment
		(start 418.976048 -212.510116)
		(end 420.497508 -212.510116)
		(width 0.16002)
		(layer "In4.Cu")
		(net "M_J_CPU0_SA_DQS_DP<6>")
	)
	(segment
		(start 432.04638 -211.660232)
		(end 432.195478 -211.511134)
		(width 0.16002)
		(layer "In4.Cu")
		(net "M_J_CPU0_SA_DQS_DP<6>")
	)
	(segment
		(start 428.555658 -212.148166)
		(end 429.128174 -212.148166)
		(width 0.16002)
		(layer "In4.Cu")
		(net "M_J_CPU0_SA_DQS_DP<6>")
	)
	(segment
		(start 414.105598 -212.110066)
		(end 414.875218 -211.340446)
		(width 0.16002)
		(layer "In4.Cu")
		(net "M_J_CPU0_SA_DQS_DP<6>")
	)
	(segment
		(start 422.352978 -211.322666)
		(end 423.051478 -211.322666)
		(width 0.16002)
		(layer "In4.Cu")
		(net "M_J_CPU0_SA_DQS_DP<6>")
	)
	(segment
		(start 429.961294 -211.315046)
		(end 430.613058 -211.315046)
		(width 0.16002)
		(layer "In4.Cu")
		(net "M_J_CPU0_SA_DQS_DP<6>")
	)
	(segment
		(start 409.431744 -211.635086)
		(end 409.627578 -211.439252)
		(width 0.16002)
		(layer "In4.Cu")
		(net "M_J_CPU0_SA_DQS_DP<6>")
	)
	(segment
		(start 423.389044 -211.660232)
		(end 425.966128 -211.660232)
		(width 0.16002)
		(layer "In4.Cu")
		(net "M_J_CPU0_SA_DQS_DP<6>")
	)
	(segment
		(start 416.933888 -211.340446)
		(end 417.806378 -211.340446)
		(width 0.16002)
		(layer "In4.Cu")
		(net "M_J_CPU0_SA_DQS_DP<6>")
	)
	(segment
		(start 428.193708 -212.510116)
		(end 428.555658 -212.148166)
		(width 0.16002)
		(layer "In4.Cu")
		(net "M_J_CPU0_SA_DQS_DP<6>")
	)
	(segment
		(start 384.906266 -232.81894)
		(end 384.914648 -232.814114)
		(width 0.09525)
		(layer "In4.Cu")
		(net "M_J_CPU0_SA_DQS_DP<6>")
	)
	(segment
		(start 417.806378 -211.340446)
		(end 418.976048 -212.510116)
		(width 0.16002)
		(layer "In4.Cu")
		(net "M_J_CPU0_SA_DQS_DP<6>")
	)
	(segment
		(start 434.726334 -211.511134)
		(end 435.000146 -211.784946)
		(width 0.16002)
		(layer "In4.Cu")
		(net "M_J_CPU0_SA_DQS_DP<6>")
	)
	(segment
		(start 413.064452 -212.724492)
		(end 413.678878 -212.110066)
		(width 0.16002)
		(layer "In4.Cu")
		(net "M_J_CPU0_SA_DQS_DP<6>")
	)
	(segment
		(start 409.431744 -212.35162)
		(end 409.431744 -211.635086)
		(width 0.16002)
		(layer "In4.Cu")
		(net "M_J_CPU0_SA_DQS_DP<6>")
	)
	(segment
		(start 416.220148 -211.340446)
		(end 416.336988 -211.457286)
		(width 0.16002)
		(layer "In4.Cu")
		(net "M_J_CPU0_SA_DQS_DP<6>")
	)
	(segment
		(start 395.104874 -229.489762)
		(end 395.741652 -228.852984)
		(width 0.09525)
		(layer "In4.Cu")
		(net "M_J_CPU0_SA_DQS_DP<6>")
	)
	(segment
		(start 395.825472 -228.852984)
		(end 395.842236 -228.83622)
		(width 0.09525)
		(layer "In4.Cu")
		(net "M_J_CPU0_SA_DQS_DP<6>")
	)
	(segment
		(start 392.123676 -232.767632)
		(end 394.226542 -230.664766)
		(width 0.09525)
		(layer "In4.Cu")
		(net "M_J_CPU0_SA_DQS_DP<6>")
	)
	(segment
		(start 433.431188 -211.627974)
		(end 433.911248 -211.627974)
		(width 0.16002)
		(layer "In4.Cu")
		(net "M_J_CPU0_SA_DQS_DP<6>")
	)
	(segment
		(start 429.128174 -212.148166)
		(end 429.961294 -211.315046)
		(width 0.16002)
		(layer "In4.Cu")
		(net "M_J_CPU0_SA_DQS_DP<6>")
	)
	(segment
		(start 391.674858 -232.767632)
		(end 392.123676 -232.767632)
		(width 0.09525)
		(layer "In4.Cu")
		(net "M_J_CPU0_SA_DQS_DP<6>")
	)
	(segment
		(start 398.757902 -222.276416)
		(end 408.309826 -212.724492)
		(width 0.16002)
		(layer "In4.Cu")
		(net "M_J_CPU0_SA_DQS_DP<6>")
	)
	(segment
		(start 408.309826 -212.724492)
		(end 409.058872 -212.724492)
		(width 0.16002)
		(layer "In4.Cu")
		(net "M_J_CPU0_SA_DQS_DP<6>")
	)
	(segment
		(start 434.028088 -211.511134)
		(end 434.726334 -211.511134)
		(width 0.16002)
		(layer "In4.Cu")
		(net "M_J_CPU0_SA_DQS_DP<6>")
	)
	(segment
		(start 430.958244 -211.660232)
		(end 432.04638 -211.660232)
		(width 0.16002)
		(layer "In4.Cu")
		(net "M_J_CPU0_SA_DQS_DP<6>")
	)
	(segment
		(start 425.966128 -211.660232)
		(end 426.816012 -212.510116)
		(width 0.16002)
		(layer "In4.Cu")
		(net "M_J_CPU0_SA_DQS_DP<6>")
	)
	(segment
		(start 384.33502 -232.814114)
		(end 384.343402 -232.81894)
		(width 0.09525)
		(layer "In4.Cu")
		(net "M_J_CPU0_SA_DQS_DP<6>")
	)
	(segment
		(start 394.226542 -230.032052)
		(end 394.768832 -229.489762)
		(width 0.09525)
		(layer "In4.Cu")
		(net "M_J_CPU0_SA_DQS_DP<6>")
	)
	(segment
		(start 423.051478 -211.322666)
		(end 423.389044 -211.660232)
		(width 0.16002)
		(layer "In4.Cu")
		(net "M_J_CPU0_SA_DQS_DP<6>")
	)
	(segment
		(start 412.041086 -211.635086)
		(end 412.041086 -212.35162)
		(width 0.16002)
		(layer "In4.Cu")
		(net "M_J_CPU0_SA_DQS_DP<6>")
	)
	(segment
		(start 395.741652 -228.852984)
		(end 395.825472 -228.852984)
		(width 0.09525)
		(layer "In4.Cu")
		(net "M_J_CPU0_SA_DQS_DP<6>")
	)
	(segment
		(start 410.100018 -212.35162)
		(end 410.47289 -212.724492)
		(width 0.16002)
		(layer "In4.Cu")
		(net "M_J_CPU0_SA_DQS_DP<6>")
	)
	(segment
		(start 416.817048 -211.457286)
		(end 416.933888 -211.340446)
		(width 0.16002)
		(layer "In4.Cu")
		(net "M_J_CPU0_SA_DQS_DP<6>")
	)
	(segment
		(start 413.678878 -212.110066)
		(end 414.105598 -212.110066)
		(width 0.16002)
		(layer "In4.Cu")
		(net "M_J_CPU0_SA_DQS_DP<6>")
	)
	(segment
		(start 385.84632 -232.81894)
		(end 385.854702 -232.814114)
		(width 0.09525)
		(layer "In4.Cu")
		(net "M_J_CPU0_SA_DQS_DP<6>")
	)
	(segment
		(start 409.627578 -211.439252)
		(end 409.904184 -211.439252)
		(width 0.16002)
		(layer "In4.Cu")
		(net "M_J_CPU0_SA_DQS_DP<6>")
	)
	(segment
		(start 398.757902 -225.920554)
		(end 398.757902 -222.276416)
		(width 0.16002)
		(layer "In4.Cu")
		(net "M_J_CPU0_SA_DQS_DP<6>")
	)
	(segment
		(start 379.300994 -232.87863)
		(end 379.324362 -232.791762)
		(width 0.09525)
		(layer "In4.Cu")
		(net "M_J_CPU0_SA_DQS_DP<6>")
	)
	(segment
		(start 414.875218 -211.340446)
		(end 416.220148 -211.340446)
		(width 0.16002)
		(layer "In4.Cu")
		(net "M_J_CPU0_SA_DQS_DP<6>")
	)
	(segment
		(start 433.314348 -211.511134)
		(end 433.431188 -211.627974)
		(width 0.16002)
		(layer "In4.Cu")
		(net "M_J_CPU0_SA_DQS_DP<6>")
	)
	(segment
		(start 394.768832 -229.489762)
		(end 395.104874 -229.489762)
		(width 0.09525)
		(layer "In4.Cu")
		(net "M_J_CPU0_SA_DQS_DP<6>")
	)
	(segment
		(start 432.195478 -211.511134)
		(end 433.314348 -211.511134)
		(width 0.16002)
		(layer "In4.Cu")
		(net "M_J_CPU0_SA_DQS_DP<6>")
	)
	(segment
		(start 430.613058 -211.315046)
		(end 430.958244 -211.660232)
		(width 0.16002)
		(layer "In4.Cu")
		(net "M_J_CPU0_SA_DQS_DP<6>")
	)
	(segment
		(start 395.842236 -228.83622)
		(end 398.757902 -225.920554)
		(width 0.16002)
		(layer "In4.Cu")
		(net "M_J_CPU0_SA_DQS_DP<6>")
	)
	(segment
		(start 411.568646 -211.439252)
		(end 411.845252 -211.439252)
		(width 0.16002)
		(layer "In4.Cu")
		(net "M_J_CPU0_SA_DQS_DP<6>")
	)
	(segment
		(start 394.226542 -230.664766)
		(end 394.226542 -230.032052)
		(width 0.09525)
		(layer "In4.Cu")
		(net "M_J_CPU0_SA_DQS_DP<6>")
	)
	(segment
		(start 410.99994 -212.724492)
		(end 411.372812 -212.35162)
		(width 0.16002)
		(layer "In4.Cu")
		(net "M_J_CPU0_SA_DQS_DP<6>")
	)
	(segment
		(start 381.146304 -232.81894)
		(end 381.154686 -232.814114)
		(width 0.09525)
		(layer "In4.Cu")
		(net "M_J_CPU0_SA_DQS_DP<6>")
	)
	(arc
		(start 389.983472 -232.81894)
		(mid 390.264904 -232.894695)
		(end 390.546336 -232.81894)
		(width 0.09525)
		(layer "In4.Cu")
		(net "M_J_CPU0_SA_DQS_DP<6>")
	)
	(arc
		(start 383.966212 -232.81894)
		(mid 384.149987 -232.768168)
		(end 384.33502 -232.814114)
		(width 0.09525)
		(layer "In4.Cu")
		(net "M_J_CPU0_SA_DQS_DP<6>")
	)
	(arc
		(start 390.923272 -232.81894)
		(mid 391.204704 -232.894695)
		(end 391.486136 -232.81894)
		(width 0.09525)
		(layer "In4.Cu")
		(net "M_J_CPU0_SA_DQS_DP<6>")
	)
	(arc
		(start 391.486136 -232.81894)
		(mid 391.577102 -232.780787)
		(end 391.674858 -232.767632)
		(width 0.09525)
		(layer "In4.Cu")
		(net "M_J_CPU0_SA_DQS_DP<6>")
	)
	(arc
		(start 385.283456 -232.81894)
		(mid 385.564888 -232.894695)
		(end 385.84632 -232.81894)
		(width 0.09525)
		(layer "In4.Cu")
		(net "M_J_CPU0_SA_DQS_DP<6>")
	)
	(arc
		(start 390.546336 -232.81894)
		(mid 390.734804 -232.768263)
		(end 390.923272 -232.81894)
		(width 0.09525)
		(layer "In4.Cu")
		(net "M_J_CPU0_SA_DQS_DP<6>")
	)
	(arc
		(start 389.043418 -232.81894)
		(mid 389.32485 -232.894695)
		(end 389.606282 -232.81894)
		(width 0.09525)
		(layer "In4.Cu")
		(net "M_J_CPU0_SA_DQS_DP<6>")
	)
	(arc
		(start 380.214632 -232.814114)
		(mid 380.399664 -232.7682)
		(end 380.58344 -232.81894)
		(width 0.09525)
		(layer "In4.Cu")
		(net "M_J_CPU0_SA_DQS_DP<6>")
	)
	(arc
		(start 388.103364 -232.81894)
		(mid 388.384796 -232.894695)
		(end 388.666228 -232.81894)
		(width 0.09525)
		(layer "In4.Cu")
		(net "M_J_CPU0_SA_DQS_DP<6>")
	)
	(arc
		(start 384.343402 -232.81894)
		(mid 384.624834 -232.894695)
		(end 384.906266 -232.81894)
		(width 0.09525)
		(layer "In4.Cu")
		(net "M_J_CPU0_SA_DQS_DP<6>")
	)
	(arc
		(start 382.086358 -232.81894)
		(mid 382.274826 -232.768263)
		(end 382.463294 -232.81894)
		(width 0.09525)
		(layer "In4.Cu")
		(net "M_J_CPU0_SA_DQS_DP<6>")
	)
	(arc
		(start 388.666228 -232.81894)
		(mid 388.850003 -232.768168)
		(end 389.035036 -232.814114)
		(width 0.09525)
		(layer "In4.Cu")
		(net "M_J_CPU0_SA_DQS_DP<6>")
	)
	(arc
		(start 389.614664 -232.814114)
		(mid 389.799696 -232.7682)
		(end 389.983472 -232.81894)
		(width 0.09525)
		(layer "In4.Cu")
		(net "M_J_CPU0_SA_DQS_DP<6>")
	)
	(arc
		(start 380.58344 -232.81894)
		(mid 380.864872 -232.894695)
		(end 381.146304 -232.81894)
		(width 0.09525)
		(layer "In4.Cu")
		(net "M_J_CPU0_SA_DQS_DP<6>")
	)
	(arc
		(start 384.914648 -232.814114)
		(mid 385.09968 -232.7682)
		(end 385.283456 -232.81894)
		(width 0.09525)
		(layer "In4.Cu")
		(net "M_J_CPU0_SA_DQS_DP<6>")
	)
	(arc
		(start 381.523494 -232.81894)
		(mid 381.804926 -232.894695)
		(end 382.086358 -232.81894)
		(width 0.09525)
		(layer "In4.Cu")
		(net "M_J_CPU0_SA_DQS_DP<6>")
	)
	(arc
		(start 385.854702 -232.814114)
		(mid 386.039734 -232.7682)
		(end 386.22351 -232.81894)
		(width 0.09525)
		(layer "In4.Cu")
		(net "M_J_CPU0_SA_DQS_DP<6>")
	)
	(arc
		(start 386.22351 -232.81894)
		(mid 386.504942 -232.894695)
		(end 386.786374 -232.81894)
		(width 0.09525)
		(layer "In4.Cu")
		(net "M_J_CPU0_SA_DQS_DP<6>")
	)
	(arc
		(start 387.16331 -232.81894)
		(mid 387.444742 -232.894695)
		(end 387.726174 -232.81894)
		(width 0.09525)
		(layer "In4.Cu")
		(net "M_J_CPU0_SA_DQS_DP<6>")
	)
	(arc
		(start 383.403348 -232.81894)
		(mid 383.68478 -232.894695)
		(end 383.966212 -232.81894)
		(width 0.09525)
		(layer "In4.Cu")
		(net "M_J_CPU0_SA_DQS_DP<6>")
	)
	(arc
		(start 379.643386 -232.81894)
		(mid 379.924818 -232.894695)
		(end 380.20625 -232.81894)
		(width 0.09525)
		(layer "In4.Cu")
		(net "M_J_CPU0_SA_DQS_DP<6>")
	)
	(arc
		(start 379.324362 -232.791762)
		(mid 379.482112 -232.769243)
		(end 379.635004 -232.814114)
		(width 0.09525)
		(layer "In4.Cu")
		(net "M_J_CPU0_SA_DQS_DP<6>")
	)
	(arc
		(start 382.463294 -232.81894)
		(mid 382.744726 -232.894695)
		(end 383.026158 -232.81894)
		(width 0.09525)
		(layer "In4.Cu")
		(net "M_J_CPU0_SA_DQS_DP<6>")
	)
	(arc
		(start 386.786374 -232.81894)
		(mid 386.974842 -232.768263)
		(end 387.16331 -232.81894)
		(width 0.09525)
		(layer "In4.Cu")
		(net "M_J_CPU0_SA_DQS_DP<6>")
	)
	(arc
		(start 383.026158 -232.81894)
		(mid 383.209933 -232.768168)
		(end 383.394966 -232.814114)
		(width 0.09525)
		(layer "In4.Cu")
		(net "M_J_CPU0_SA_DQS_DP<6>")
	)
	(arc
		(start 381.154686 -232.814114)
		(mid 381.339718 -232.7682)
		(end 381.523494 -232.81894)
		(width 0.09525)
		(layer "In4.Cu")
		(net "M_J_CPU0_SA_DQS_DP<6>")
	)
	(arc
		(start 387.726174 -232.81894)
		(mid 387.909949 -232.768168)
		(end 388.094982 -232.814114)
		(width 0.09525)
		(layer "In4.Cu")
		(net "M_J_CPU0_SA_DQS_DP<6>")
	)
	(segment
		(start 378.988066 -228.550216)
		(end 379.454918 -228.284278)
		(width 0.12954)
		(layer "F.Cu")
		(net "M_J_CPU0_SA_DQS_DP<5>")
	)
	(segment
		(start 393.207748 -221.977204)
		(end 393.207748 -221.667578)
		(width 0.09525)
		(layer "In4.Cu")
		(net "M_J_CPU0_SA_DQS_DP<5>")
	)
	(segment
		(start 413.287718 -203.151232)
		(end 413.678878 -202.760072)
		(width 0.16002)
		(layer "In4.Cu")
		(net "M_J_CPU0_SA_DQS_DP<5>")
	)
	(segment
		(start 405.84374 -206.516224)
		(end 406.258268 -206.101696)
		(width 0.16002)
		(layer "In4.Cu")
		(net "M_J_CPU0_SA_DQS_DP<5>")
	)
	(segment
		(start 415.418778 -201.990452)
		(end 415.535618 -202.107292)
		(width 0.16002)
		(layer "In4.Cu")
		(net "M_J_CPU0_SA_DQS_DP<5>")
	)
	(segment
		(start 393.220702 -218.371674)
		(end 403.652736 -207.93964)
		(width 0.16002)
		(layer "In4.Cu")
		(net "M_J_CPU0_SA_DQS_DP<5>")
	)
	(segment
		(start 392.895836 -222.289116)
		(end 393.207748 -221.977204)
		(width 0.09525)
		(layer "In4.Cu")
		(net "M_J_CPU0_SA_DQS_DP<5>")
	)
	(segment
		(start 385.84632 -227.959158)
		(end 385.854702 -227.954332)
		(width 0.09525)
		(layer "In4.Cu")
		(net "M_J_CPU0_SA_DQS_DP<5>")
	)
	(segment
		(start 391.95629 -223.909128)
		(end 391.99439 -223.88703)
		(width 0.09525)
		(layer "In4.Cu")
		(net "M_J_CPU0_SA_DQS_DP<5>")
	)
	(segment
		(start 393.207748 -221.667578)
		(end 393.161774 -221.621604)
		(width 0.09525)
		(layer "In4.Cu")
		(net "M_J_CPU0_SA_DQS_DP<5>")
	)
	(segment
		(start 414.875218 -201.990452)
		(end 415.418778 -201.990452)
		(width 0.16002)
		(layer "In4.Cu")
		(net "M_J_CPU0_SA_DQS_DP<5>")
	)
	(segment
		(start 404.884636 -207.475328)
		(end 404.884636 -206.754476)
		(width 0.16002)
		(layer "In4.Cu")
		(net "M_J_CPU0_SA_DQS_DP<5>")
	)
	(segment
		(start 423.051478 -201.972672)
		(end 423.389044 -202.310238)
		(width 0.16002)
		(layer "In4.Cu")
		(net "M_J_CPU0_SA_DQS_DP<5>")
	)
	(segment
		(start 434.726334 -202.16114)
		(end 435.000146 -202.434952)
		(width 0.16002)
		(layer "In4.Cu")
		(net "M_J_CPU0_SA_DQS_DP<5>")
	)
	(segment
		(start 422.352978 -201.972672)
		(end 423.051478 -201.972672)
		(width 0.16002)
		(layer "In4.Cu")
		(net "M_J_CPU0_SA_DQS_DP<5>")
	)
	(segment
		(start 380.20625 -227.959158)
		(end 380.214632 -227.954332)
		(width 0.09525)
		(layer "In4.Cu")
		(net "M_J_CPU0_SA_DQS_DP<5>")
	)
	(segment
		(start 411.309058 -202.77836)
		(end 411.68193 -203.151232)
		(width 0.16002)
		(layer "In4.Cu")
		(net "M_J_CPU0_SA_DQS_DP<5>")
	)
	(segment
		(start 406.258268 -206.101696)
		(end 406.258268 -205.380844)
		(width 0.16002)
		(layer "In4.Cu")
		(net "M_J_CPU0_SA_DQS_DP<5>")
	)
	(segment
		(start 390.076182 -227.149152)
		(end 390.114282 -227.127054)
		(width 0.09525)
		(layer "In4.Cu")
		(net "M_J_CPU0_SA_DQS_DP<5>")
	)
	(segment
		(start 389.035036 -227.954332)
		(end 389.043418 -227.959158)
		(width 0.09525)
		(layer "In4.Cu")
		(net "M_J_CPU0_SA_DQS_DP<5>")
	)
	(segment
		(start 416.729418 -202.107292)
		(end 417.209478 -202.107292)
		(width 0.16002)
		(layer "In4.Cu")
		(net "M_J_CPU0_SA_DQS_DP<5>")
	)
	(segment
		(start 392.86434 -222.307404)
		(end 392.895836 -222.289116)
		(width 0.09525)
		(layer "In4.Cu")
		(net "M_J_CPU0_SA_DQS_DP<5>")
	)
	(segment
		(start 404.884636 -206.754476)
		(end 405.122888 -206.516224)
		(width 0.16002)
		(layer "In4.Cu")
		(net "M_J_CPU0_SA_DQS_DP<5>")
	)
	(segment
		(start 418.976048 -203.160122)
		(end 420.497508 -203.160122)
		(width 0.16002)
		(layer "In4.Cu")
		(net "M_J_CPU0_SA_DQS_DP<5>")
	)
	(segment
		(start 388.094982 -227.954332)
		(end 388.103364 -227.959158)
		(width 0.09525)
		(layer "In4.Cu")
		(net "M_J_CPU0_SA_DQS_DP<5>")
	)
	(segment
		(start 379.454918 -228.284278)
		(end 379.300994 -228.018848)
		(width 0.09525)
		(layer "In4.Cu")
		(net "M_J_CPU0_SA_DQS_DP<5>")
	)
	(segment
		(start 417.806378 -201.990452)
		(end 418.976048 -203.160122)
		(width 0.16002)
		(layer "In4.Cu")
		(net "M_J_CPU0_SA_DQS_DP<5>")
	)
	(segment
		(start 423.389044 -202.310238)
		(end 425.966128 -202.310238)
		(width 0.16002)
		(layer "In4.Cu")
		(net "M_J_CPU0_SA_DQS_DP<5>")
	)
	(segment
		(start 391.016236 -225.52914)
		(end 391.054336 -225.507042)
		(width 0.09525)
		(layer "In4.Cu")
		(net "M_J_CPU0_SA_DQS_DP<5>")
	)
	(segment
		(start 426.816012 -203.160122)
		(end 428.193708 -203.160122)
		(width 0.16002)
		(layer "In4.Cu")
		(net "M_J_CPU0_SA_DQS_DP<5>")
	)
	(segment
		(start 391.45464 -224.737422)
		(end 391.486136 -224.719134)
		(width 0.09525)
		(layer "In4.Cu")
		(net "M_J_CPU0_SA_DQS_DP<5>")
	)
	(segment
		(start 432.04638 -202.310238)
		(end 432.195478 -202.16114)
		(width 0.16002)
		(layer "In4.Cu")
		(net "M_J_CPU0_SA_DQS_DP<5>")
	)
	(segment
		(start 393.220702 -221.359222)
		(end 393.220702 -218.371674)
		(width 0.16002)
		(layer "In4.Cu")
		(net "M_J_CPU0_SA_DQS_DP<5>")
	)
	(segment
		(start 433.192428 -202.16114)
		(end 433.309268 -202.27798)
		(width 0.16002)
		(layer "In4.Cu")
		(net "M_J_CPU0_SA_DQS_DP<5>")
	)
	(segment
		(start 392.42619 -223.099122)
		(end 392.458194 -223.08058)
		(width 0.09525)
		(layer "In4.Cu")
		(net "M_J_CPU0_SA_DQS_DP<5>")
	)
	(segment
		(start 407.870152 -203.76896)
		(end 408.591004 -203.76896)
		(width 0.16002)
		(layer "In4.Cu")
		(net "M_J_CPU0_SA_DQS_DP<5>")
	)
	(segment
		(start 411.68193 -203.151232)
		(end 413.287718 -203.151232)
		(width 0.16002)
		(layer "In4.Cu")
		(net "M_J_CPU0_SA_DQS_DP<5>")
	)
	(segment
		(start 407.217372 -205.142592)
		(end 407.6319 -204.728064)
		(width 0.16002)
		(layer "In4.Cu")
		(net "M_J_CPU0_SA_DQS_DP<5>")
	)
	(segment
		(start 429.128174 -202.798172)
		(end 429.961294 -201.965052)
		(width 0.16002)
		(layer "In4.Cu")
		(net "M_J_CPU0_SA_DQS_DP<5>")
	)
	(segment
		(start 411.309058 -202.158346)
		(end 411.309058 -202.77836)
		(width 0.16002)
		(layer "In4.Cu")
		(net "M_J_CPU0_SA_DQS_DP<5>")
	)
	(segment
		(start 433.906168 -202.16114)
		(end 434.726334 -202.16114)
		(width 0.16002)
		(layer "In4.Cu")
		(net "M_J_CPU0_SA_DQS_DP<5>")
	)
	(segment
		(start 404.420324 -207.93964)
		(end 404.884636 -207.475328)
		(width 0.16002)
		(layer "In4.Cu")
		(net "M_J_CPU0_SA_DQS_DP<5>")
	)
	(segment
		(start 425.966128 -202.310238)
		(end 426.816012 -203.160122)
		(width 0.16002)
		(layer "In4.Cu")
		(net "M_J_CPU0_SA_DQS_DP<5>")
	)
	(segment
		(start 405.122888 -206.516224)
		(end 405.84374 -206.516224)
		(width 0.16002)
		(layer "In4.Cu")
		(net "M_J_CPU0_SA_DQS_DP<5>")
	)
	(segment
		(start 409.208732 -203.151232)
		(end 410.267912 -203.151232)
		(width 0.16002)
		(layer "In4.Cu")
		(net "M_J_CPU0_SA_DQS_DP<5>")
	)
	(segment
		(start 432.195478 -202.16114)
		(end 433.192428 -202.16114)
		(width 0.16002)
		(layer "In4.Cu")
		(net "M_J_CPU0_SA_DQS_DP<5>")
	)
	(segment
		(start 389.606282 -227.959158)
		(end 389.644382 -227.93706)
		(width 0.09525)
		(layer "In4.Cu")
		(net "M_J_CPU0_SA_DQS_DP<5>")
	)
	(segment
		(start 415.535618 -202.107292)
		(end 416.015678 -202.107292)
		(width 0.16002)
		(layer "In4.Cu")
		(net "M_J_CPU0_SA_DQS_DP<5>")
	)
	(segment
		(start 381.146304 -227.959158)
		(end 381.154686 -227.954332)
		(width 0.09525)
		(layer "In4.Cu")
		(net "M_J_CPU0_SA_DQS_DP<5>")
	)
	(segment
		(start 410.836618 -201.962512)
		(end 411.113224 -201.962512)
		(width 0.16002)
		(layer "In4.Cu")
		(net "M_J_CPU0_SA_DQS_DP<5>")
	)
	(segment
		(start 407.6319 -204.007212)
		(end 407.870152 -203.76896)
		(width 0.16002)
		(layer "In4.Cu")
		(net "M_J_CPU0_SA_DQS_DP<5>")
	)
	(segment
		(start 392.394694 -223.11741)
		(end 392.42619 -223.099122)
		(width 0.09525)
		(layer "In4.Cu")
		(net "M_J_CPU0_SA_DQS_DP<5>")
	)
	(segment
		(start 390.513824 -226.357942)
		(end 390.546336 -226.339146)
		(width 0.09525)
		(layer "In4.Cu")
		(net "M_J_CPU0_SA_DQS_DP<5>")
	)
	(segment
		(start 433.789328 -202.27798)
		(end 433.906168 -202.16114)
		(width 0.16002)
		(layer "In4.Cu")
		(net "M_J_CPU0_SA_DQS_DP<5>")
	)
	(segment
		(start 379.300994 -228.018848)
		(end 379.324362 -227.93198)
		(width 0.09525)
		(layer "In4.Cu")
		(net "M_J_CPU0_SA_DQS_DP<5>")
	)
	(segment
		(start 413.678878 -202.760072)
		(end 414.105598 -202.760072)
		(width 0.16002)
		(layer "In4.Cu")
		(net "M_J_CPU0_SA_DQS_DP<5>")
	)
	(segment
		(start 410.640784 -202.77836)
		(end 410.640784 -202.158346)
		(width 0.16002)
		(layer "In4.Cu")
		(net "M_J_CPU0_SA_DQS_DP<5>")
	)
	(segment
		(start 417.326318 -201.990452)
		(end 417.806378 -201.990452)
		(width 0.16002)
		(layer "In4.Cu")
		(net "M_J_CPU0_SA_DQS_DP<5>")
	)
	(segment
		(start 406.258268 -205.380844)
		(end 406.49652 -205.142592)
		(width 0.16002)
		(layer "In4.Cu")
		(net "M_J_CPU0_SA_DQS_DP<5>")
	)
	(segment
		(start 403.652736 -207.93964)
		(end 404.420324 -207.93964)
		(width 0.16002)
		(layer "In4.Cu")
		(net "M_J_CPU0_SA_DQS_DP<5>")
	)
	(segment
		(start 428.555658 -202.798172)
		(end 429.128174 -202.798172)
		(width 0.16002)
		(layer "In4.Cu")
		(net "M_J_CPU0_SA_DQS_DP<5>")
	)
	(segment
		(start 416.612578 -201.990452)
		(end 416.729418 -202.107292)
		(width 0.16002)
		(layer "In4.Cu")
		(net "M_J_CPU0_SA_DQS_DP<5>")
	)
	(segment
		(start 414.105598 -202.760072)
		(end 414.875218 -201.990452)
		(width 0.16002)
		(layer "In4.Cu")
		(net "M_J_CPU0_SA_DQS_DP<5>")
	)
	(segment
		(start 379.635004 -227.954332)
		(end 379.643386 -227.959158)
		(width 0.09525)
		(layer "In4.Cu")
		(net "M_J_CPU0_SA_DQS_DP<5>")
	)
	(segment
		(start 407.6319 -204.728064)
		(end 407.6319 -204.007212)
		(width 0.16002)
		(layer "In4.Cu")
		(net "M_J_CPU0_SA_DQS_DP<5>")
	)
	(segment
		(start 393.161774 -221.441772)
		(end 393.220702 -221.382844)
		(width 0.09525)
		(layer "In4.Cu")
		(net "M_J_CPU0_SA_DQS_DP<5>")
	)
	(segment
		(start 417.209478 -202.107292)
		(end 417.326318 -201.990452)
		(width 0.16002)
		(layer "In4.Cu")
		(net "M_J_CPU0_SA_DQS_DP<5>")
	)
	(segment
		(start 410.640784 -202.158346)
		(end 410.836618 -201.962512)
		(width 0.16002)
		(layer "In4.Cu")
		(net "M_J_CPU0_SA_DQS_DP<5>")
	)
	(segment
		(start 391.486136 -224.719134)
		(end 391.524236 -224.697036)
		(width 0.09525)
		(layer "In4.Cu")
		(net "M_J_CPU0_SA_DQS_DP<5>")
	)
	(segment
		(start 408.591004 -203.76896)
		(end 409.208732 -203.151232)
		(width 0.16002)
		(layer "In4.Cu")
		(net "M_J_CPU0_SA_DQS_DP<5>")
	)
	(segment
		(start 420.497508 -203.160122)
		(end 420.836598 -202.821032)
		(width 0.16002)
		(layer "In4.Cu")
		(net "M_J_CPU0_SA_DQS_DP<5>")
	)
	(segment
		(start 416.015678 -202.107292)
		(end 416.132518 -201.990452)
		(width 0.16002)
		(layer "In4.Cu")
		(net "M_J_CPU0_SA_DQS_DP<5>")
	)
	(segment
		(start 411.113224 -201.962512)
		(end 411.309058 -202.158346)
		(width 0.16002)
		(layer "In4.Cu")
		(net "M_J_CPU0_SA_DQS_DP<5>")
	)
	(segment
		(start 384.33502 -227.954332)
		(end 384.343402 -227.959158)
		(width 0.09525)
		(layer "In4.Cu")
		(net "M_J_CPU0_SA_DQS_DP<5>")
	)
	(segment
		(start 390.983724 -225.547936)
		(end 391.016236 -225.52914)
		(width 0.09525)
		(layer "In4.Cu")
		(net "M_J_CPU0_SA_DQS_DP<5>")
	)
	(segment
		(start 428.193708 -203.160122)
		(end 428.555658 -202.798172)
		(width 0.16002)
		(layer "In4.Cu")
		(net "M_J_CPU0_SA_DQS_DP<5>")
	)
	(segment
		(start 383.394966 -227.954332)
		(end 383.403348 -227.959158)
		(width 0.09525)
		(layer "In4.Cu")
		(net "M_J_CPU0_SA_DQS_DP<5>")
	)
	(segment
		(start 393.161774 -221.621604)
		(end 393.161774 -221.441772)
		(width 0.09525)
		(layer "In4.Cu")
		(net "M_J_CPU0_SA_DQS_DP<5>")
	)
	(segment
		(start 390.546336 -226.339146)
		(end 390.581388 -226.318572)
		(width 0.09525)
		(layer "In4.Cu")
		(net "M_J_CPU0_SA_DQS_DP<5>")
	)
	(segment
		(start 430.958244 -202.310238)
		(end 432.04638 -202.310238)
		(width 0.16002)
		(layer "In4.Cu")
		(net "M_J_CPU0_SA_DQS_DP<5>")
	)
	(segment
		(start 430.613058 -201.965052)
		(end 430.958244 -202.310238)
		(width 0.16002)
		(layer "In4.Cu")
		(net "M_J_CPU0_SA_DQS_DP<5>")
	)
	(segment
		(start 416.132518 -201.990452)
		(end 416.612578 -201.990452)
		(width 0.16002)
		(layer "In4.Cu")
		(net "M_J_CPU0_SA_DQS_DP<5>")
	)
	(segment
		(start 433.309268 -202.27798)
		(end 433.789328 -202.27798)
		(width 0.16002)
		(layer "In4.Cu")
		(net "M_J_CPU0_SA_DQS_DP<5>")
	)
	(segment
		(start 429.961294 -201.965052)
		(end 430.613058 -201.965052)
		(width 0.16002)
		(layer "In4.Cu")
		(net "M_J_CPU0_SA_DQS_DP<5>")
	)
	(segment
		(start 406.49652 -205.142592)
		(end 407.217372 -205.142592)
		(width 0.16002)
		(layer "In4.Cu")
		(net "M_J_CPU0_SA_DQS_DP<5>")
	)
	(segment
		(start 384.906266 -227.959158)
		(end 384.914648 -227.954332)
		(width 0.09525)
		(layer "In4.Cu")
		(net "M_J_CPU0_SA_DQS_DP<5>")
	)
	(segment
		(start 393.220702 -221.382844)
		(end 393.220702 -221.359222)
		(width 0.09525)
		(layer "In4.Cu")
		(net "M_J_CPU0_SA_DQS_DP<5>")
	)
	(segment
		(start 421.504618 -202.821032)
		(end 422.352978 -201.972672)
		(width 0.16002)
		(layer "In4.Cu")
		(net "M_J_CPU0_SA_DQS_DP<5>")
	)
	(segment
		(start 420.836598 -202.821032)
		(end 421.504618 -202.821032)
		(width 0.16002)
		(layer "In4.Cu")
		(net "M_J_CPU0_SA_DQS_DP<5>")
	)
	(segment
		(start 391.923778 -223.927924)
		(end 391.95629 -223.909128)
		(width 0.09525)
		(layer "In4.Cu")
		(net "M_J_CPU0_SA_DQS_DP<5>")
	)
	(segment
		(start 410.267912 -203.151232)
		(end 410.640784 -202.77836)
		(width 0.16002)
		(layer "In4.Cu")
		(net "M_J_CPU0_SA_DQS_DP<5>")
	)
	(segment
		(start 390.044686 -227.16744)
		(end 390.076182 -227.149152)
		(width 0.09525)
		(layer "In4.Cu")
		(net "M_J_CPU0_SA_DQS_DP<5>")
	)
	(arc
		(start 392.458194 -223.08058)
		(mid 392.640659 -222.878435)
		(end 392.706606 -222.614236)
		(width 0.09525)
		(layer "In4.Cu")
		(net "M_J_CPU0_SA_DQS_DP<5>")
	)
	(arc
		(start 380.58344 -227.959158)
		(mid 380.864872 -228.034913)
		(end 381.146304 -227.959158)
		(width 0.09525)
		(layer "In4.Cu")
		(net "M_J_CPU0_SA_DQS_DP<5>")
	)
	(arc
		(start 389.043418 -227.959158)
		(mid 389.32485 -228.034913)
		(end 389.606282 -227.959158)
		(width 0.09525)
		(layer "In4.Cu")
		(net "M_J_CPU0_SA_DQS_DP<5>")
	)
	(arc
		(start 385.854702 -227.954332)
		(mid 386.039734 -227.908418)
		(end 386.22351 -227.959158)
		(width 0.09525)
		(layer "In4.Cu")
		(net "M_J_CPU0_SA_DQS_DP<5>")
	)
	(arc
		(start 381.154686 -227.954332)
		(mid 381.339718 -227.908418)
		(end 381.523494 -227.959158)
		(width 0.09525)
		(layer "In4.Cu")
		(net "M_J_CPU0_SA_DQS_DP<5>")
	)
	(arc
		(start 388.666228 -227.959158)
		(mid 388.850003 -227.908386)
		(end 389.035036 -227.954332)
		(width 0.09525)
		(layer "In4.Cu")
		(net "M_J_CPU0_SA_DQS_DP<5>")
	)
	(arc
		(start 387.16331 -227.959158)
		(mid 387.444742 -228.034913)
		(end 387.726174 -227.959158)
		(width 0.09525)
		(layer "In4.Cu")
		(net "M_J_CPU0_SA_DQS_DP<5>")
	)
	(arc
		(start 392.237214 -223.424242)
		(mid 392.278879 -223.251795)
		(end 392.394694 -223.11741)
		(width 0.09525)
		(layer "In4.Cu")
		(net "M_J_CPU0_SA_DQS_DP<5>")
	)
	(arc
		(start 391.054336 -225.507042)
		(mid 391.232786 -225.305572)
		(end 391.29716 -225.044254)
		(width 0.09525)
		(layer "In4.Cu")
		(net "M_J_CPU0_SA_DQS_DP<5>")
	)
	(arc
		(start 391.29716 -225.044254)
		(mid 391.338825 -224.871807)
		(end 391.45464 -224.737422)
		(width 0.09525)
		(layer "In4.Cu")
		(net "M_J_CPU0_SA_DQS_DP<5>")
	)
	(arc
		(start 379.643386 -227.959158)
		(mid 379.924818 -228.034913)
		(end 380.20625 -227.959158)
		(width 0.09525)
		(layer "In4.Cu")
		(net "M_J_CPU0_SA_DQS_DP<5>")
	)
	(arc
		(start 391.76706 -224.234248)
		(mid 391.808517 -224.062208)
		(end 391.923778 -223.927924)
		(width 0.09525)
		(layer "In4.Cu")
		(net "M_J_CPU0_SA_DQS_DP<5>")
	)
	(arc
		(start 379.324362 -227.93198)
		(mid 379.482112 -227.909461)
		(end 379.635004 -227.954332)
		(width 0.09525)
		(layer "In4.Cu")
		(net "M_J_CPU0_SA_DQS_DP<5>")
	)
	(arc
		(start 392.706606 -222.614236)
		(mid 392.748357 -222.441746)
		(end 392.86434 -222.307404)
		(width 0.09525)
		(layer "In4.Cu")
		(net "M_J_CPU0_SA_DQS_DP<5>")
	)
	(arc
		(start 387.726174 -227.959158)
		(mid 387.909949 -227.908386)
		(end 388.094982 -227.954332)
		(width 0.09525)
		(layer "In4.Cu")
		(net "M_J_CPU0_SA_DQS_DP<5>")
	)
	(arc
		(start 389.887206 -227.474272)
		(mid 389.928871 -227.301825)
		(end 390.044686 -227.16744)
		(width 0.09525)
		(layer "In4.Cu")
		(net "M_J_CPU0_SA_DQS_DP<5>")
	)
	(arc
		(start 383.966212 -227.959158)
		(mid 384.149987 -227.908386)
		(end 384.33502 -227.954332)
		(width 0.09525)
		(layer "In4.Cu")
		(net "M_J_CPU0_SA_DQS_DP<5>")
	)
	(arc
		(start 391.99439 -223.88703)
		(mid 392.17284 -223.68556)
		(end 392.237214 -223.424242)
		(width 0.09525)
		(layer "In4.Cu")
		(net "M_J_CPU0_SA_DQS_DP<5>")
	)
	(arc
		(start 390.357106 -226.664266)
		(mid 390.398563 -226.492226)
		(end 390.513824 -226.357942)
		(width 0.09525)
		(layer "In4.Cu")
		(net "M_J_CPU0_SA_DQS_DP<5>")
	)
	(arc
		(start 383.403348 -227.959158)
		(mid 383.68478 -228.034913)
		(end 383.966212 -227.959158)
		(width 0.09525)
		(layer "In4.Cu")
		(net "M_J_CPU0_SA_DQS_DP<5>")
	)
	(arc
		(start 384.343402 -227.959158)
		(mid 384.624834 -228.034913)
		(end 384.906266 -227.959158)
		(width 0.09525)
		(layer "In4.Cu")
		(net "M_J_CPU0_SA_DQS_DP<5>")
	)
	(arc
		(start 383.026158 -227.959158)
		(mid 383.209933 -227.908386)
		(end 383.394966 -227.954332)
		(width 0.09525)
		(layer "In4.Cu")
		(net "M_J_CPU0_SA_DQS_DP<5>")
	)
	(arc
		(start 391.524236 -224.697036)
		(mid 391.702686 -224.495566)
		(end 391.76706 -224.234248)
		(width 0.09525)
		(layer "In4.Cu")
		(net "M_J_CPU0_SA_DQS_DP<5>")
	)
	(arc
		(start 381.523494 -227.959158)
		(mid 381.804926 -228.034913)
		(end 382.086358 -227.959158)
		(width 0.09525)
		(layer "In4.Cu")
		(net "M_J_CPU0_SA_DQS_DP<5>")
	)
	(arc
		(start 385.283456 -227.959158)
		(mid 385.564888 -228.034913)
		(end 385.84632 -227.959158)
		(width 0.09525)
		(layer "In4.Cu")
		(net "M_J_CPU0_SA_DQS_DP<5>")
	)
	(arc
		(start 386.786374 -227.959158)
		(mid 386.974842 -227.908481)
		(end 387.16331 -227.959158)
		(width 0.09525)
		(layer "In4.Cu")
		(net "M_J_CPU0_SA_DQS_DP<5>")
	)
	(arc
		(start 380.214632 -227.954332)
		(mid 380.399664 -227.908418)
		(end 380.58344 -227.959158)
		(width 0.09525)
		(layer "In4.Cu")
		(net "M_J_CPU0_SA_DQS_DP<5>")
	)
	(arc
		(start 388.103364 -227.959158)
		(mid 388.384796 -228.034913)
		(end 388.666228 -227.959158)
		(width 0.09525)
		(layer "In4.Cu")
		(net "M_J_CPU0_SA_DQS_DP<5>")
	)
	(arc
		(start 390.114282 -227.127054)
		(mid 390.292732 -226.925584)
		(end 390.357106 -226.664266)
		(width 0.09525)
		(layer "In4.Cu")
		(net "M_J_CPU0_SA_DQS_DP<5>")
	)
	(arc
		(start 384.914648 -227.954332)
		(mid 385.09968 -227.908418)
		(end 385.283456 -227.959158)
		(width 0.09525)
		(layer "In4.Cu")
		(net "M_J_CPU0_SA_DQS_DP<5>")
	)
	(arc
		(start 382.463294 -227.959158)
		(mid 382.744726 -228.034913)
		(end 383.026158 -227.959158)
		(width 0.09525)
		(layer "In4.Cu")
		(net "M_J_CPU0_SA_DQS_DP<5>")
	)
	(arc
		(start 382.086358 -227.959158)
		(mid 382.274826 -227.908481)
		(end 382.463294 -227.959158)
		(width 0.09525)
		(layer "In4.Cu")
		(net "M_J_CPU0_SA_DQS_DP<5>")
	)
	(arc
		(start 389.644382 -227.93706)
		(mid 389.822832 -227.73559)
		(end 389.887206 -227.474272)
		(width 0.09525)
		(layer "In4.Cu")
		(net "M_J_CPU0_SA_DQS_DP<5>")
	)
	(arc
		(start 390.581388 -226.318572)
		(mid 390.761779 -226.116873)
		(end 390.827006 -225.85426)
		(width 0.09525)
		(layer "In4.Cu")
		(net "M_J_CPU0_SA_DQS_DP<5>")
	)
	(arc
		(start 386.22351 -227.959158)
		(mid 386.504942 -228.034913)
		(end 386.786374 -227.959158)
		(width 0.09525)
		(layer "In4.Cu")
		(net "M_J_CPU0_SA_DQS_DP<5>")
	)
	(arc
		(start 390.827006 -225.85426)
		(mid 390.868463 -225.68222)
		(end 390.983724 -225.547936)
		(width 0.09525)
		(layer "In4.Cu")
		(net "M_J_CPU0_SA_DQS_DP<5>")
	)
	(segment
		(start 379.927866 -246.370094)
		(end 380.394718 -246.104156)
		(width 0.12954)
		(layer "F.Cu")
		(net "M_J_CPU0_SA_DQS_DP<4>")
	)
	(segment
		(start 385.854702 -246.434102)
		(end 385.84632 -246.429276)
		(width 0.09525)
		(layer "In4.Cu")
		(net "M_J_CPU0_SA_DQS_DP<4>")
	)
	(segment
		(start 391.494518 -246.434102)
		(end 391.486136 -246.429276)
		(width 0.09525)
		(layer "In4.Cu")
		(net "M_J_CPU0_SA_DQS_DP<4>")
	)
	(segment
		(start 422.952418 -237.937548)
		(end 422.12387 -237.937548)
		(width 0.16002)
		(layer "In4.Cu")
		(net "M_J_CPU0_SA_DQS_DP<4>")
	)
	(segment
		(start 435.098698 -237.866428)
		(end 433.0192 -237.866428)
		(width 0.16002)
		(layer "In4.Cu")
		(net "M_J_CPU0_SA_DQS_DP<4>")
	)
	(segment
		(start 432.562762 -237.40999)
		(end 430.949354 -237.40999)
		(width 0.16002)
		(layer "In4.Cu")
		(net "M_J_CPU0_SA_DQS_DP<4>")
	)
	(segment
		(start 435.822598 -238.590328)
		(end 435.098698 -237.866428)
		(width 0.16002)
		(layer "In4.Cu")
		(net "M_J_CPU0_SA_DQS_DP<4>")
	)
	(segment
		(start 436.752238 -238.590328)
		(end 435.822598 -238.590328)
		(width 0.16002)
		(layer "In4.Cu")
		(net "M_J_CPU0_SA_DQS_DP<4>")
	)
	(segment
		(start 392.426952 -246.429276)
		(end 392.416538 -246.42318)
		(width 0.09525)
		(layer "In4.Cu")
		(net "M_J_CPU0_SA_DQS_DP<4>")
	)
	(segment
		(start 422.12387 -237.937548)
		(end 421.44569 -238.615728)
		(width 0.16002)
		(layer "In4.Cu")
		(net "M_J_CPU0_SA_DQS_DP<4>")
	)
	(segment
		(start 412.102554 -238.603028)
		(end 409.154884 -241.550698)
		(width 0.16002)
		(layer "In4.Cu")
		(net "M_J_CPU0_SA_DQS_DP<4>")
	)
	(segment
		(start 428.481998 -238.636048)
		(end 428.105824 -238.259874)
		(width 0.16002)
		(layer "In4.Cu")
		(net "M_J_CPU0_SA_DQS_DP<4>")
	)
	(segment
		(start 392.824716 -246.417084)
		(end 392.803888 -246.429276)
		(width 0.09525)
		(layer "In4.Cu")
		(net "M_J_CPU0_SA_DQS_DP<4>")
	)
	(segment
		(start 428.105824 -238.259874)
		(end 425.92752 -238.259874)
		(width 0.16002)
		(layer "In4.Cu")
		(net "M_J_CPU0_SA_DQS_DP<4>")
	)
	(segment
		(start 439.100214 -238.13516)
		(end 438.826402 -238.408972)
		(width 0.16002)
		(layer "In4.Cu")
		(net "M_J_CPU0_SA_DQS_DP<4>")
	)
	(segment
		(start 438.826402 -238.408972)
		(end 436.933594 -238.408972)
		(width 0.16002)
		(layer "In4.Cu")
		(net "M_J_CPU0_SA_DQS_DP<4>")
	)
	(segment
		(start 413.948118 -238.603028)
		(end 412.102554 -238.603028)
		(width 0.16002)
		(layer "In4.Cu")
		(net "M_J_CPU0_SA_DQS_DP<4>")
	)
	(segment
		(start 418.601144 -238.259874)
		(end 418.070538 -237.729268)
		(width 0.16002)
		(layer "In4.Cu")
		(net "M_J_CPU0_SA_DQS_DP<4>")
	)
	(segment
		(start 409.154884 -241.550698)
		(end 407.9748 -241.550698)
		(width 0.16002)
		(layer "In4.Cu")
		(net "M_J_CPU0_SA_DQS_DP<4>")
	)
	(segment
		(start 394.83538 -246.752872)
		(end 394.317982 -246.752872)
		(width 0.09525)
		(layer "In4.Cu")
		(net "M_J_CPU0_SA_DQS_DP<4>")
	)
	(segment
		(start 395.774672 -245.933722)
		(end 395.71549 -245.992904)
		(width 0.09525)
		(layer "In4.Cu")
		(net "M_J_CPU0_SA_DQS_DP<4>")
	)
	(segment
		(start 433.0192 -237.866428)
		(end 432.562762 -237.40999)
		(width 0.16002)
		(layer "In4.Cu")
		(net "M_J_CPU0_SA_DQS_DP<4>")
	)
	(segment
		(start 436.933594 -238.408972)
		(end 436.752238 -238.590328)
		(width 0.16002)
		(layer "In4.Cu")
		(net "M_J_CPU0_SA_DQS_DP<4>")
	)
	(segment
		(start 389.043418 -246.429276)
		(end 389.035036 -246.434102)
		(width 0.09525)
		(layer "In4.Cu")
		(net "M_J_CPU0_SA_DQS_DP<4>")
	)
	(segment
		(start 392.803888 -246.429276)
		(end 392.79195 -246.436134)
		(width 0.09525)
		(layer "In4.Cu")
		(net "M_J_CPU0_SA_DQS_DP<4>")
	)
	(segment
		(start 380.64948 -246.396256)
		(end 380.548642 -246.369586)
		(width 0.09525)
		(layer "In4.Cu")
		(net "M_J_CPU0_SA_DQS_DP<4>")
	)
	(segment
		(start 389.614664 -246.434102)
		(end 389.606282 -246.429276)
		(width 0.09525)
		(layer "In4.Cu")
		(net "M_J_CPU0_SA_DQS_DP<4>")
	)
	(segment
		(start 430.949354 -237.40999)
		(end 430.492916 -237.866428)
		(width 0.16002)
		(layer "In4.Cu")
		(net "M_J_CPU0_SA_DQS_DP<4>")
	)
	(segment
		(start 429.784002 -237.866428)
		(end 429.014382 -238.636048)
		(width 0.16002)
		(layer "In4.Cu")
		(net "M_J_CPU0_SA_DQS_DP<4>")
	)
	(segment
		(start 425.077636 -237.40999)
		(end 423.479976 -237.40999)
		(width 0.16002)
		(layer "In4.Cu")
		(net "M_J_CPU0_SA_DQS_DP<4>")
	)
	(segment
		(start 403.591776 -245.933722)
		(end 395.798294 -245.933722)
		(width 0.16002)
		(layer "In4.Cu")
		(net "M_J_CPU0_SA_DQS_DP<4>")
	)
	(segment
		(start 381.154686 -246.434102)
		(end 381.146304 -246.429276)
		(width 0.09525)
		(layer "In4.Cu")
		(net "M_J_CPU0_SA_DQS_DP<4>")
	)
	(segment
		(start 395.538198 -245.992904)
		(end 394.83538 -246.752872)
		(width 0.09525)
		(layer "In4.Cu")
		(net "M_J_CPU0_SA_DQS_DP<4>")
	)
	(segment
		(start 429.014382 -238.636048)
		(end 428.481998 -238.636048)
		(width 0.16002)
		(layer "In4.Cu")
		(net "M_J_CPU0_SA_DQS_DP<4>")
	)
	(segment
		(start 423.479976 -237.40999)
		(end 422.952418 -237.937548)
		(width 0.16002)
		(layer "In4.Cu")
		(net "M_J_CPU0_SA_DQS_DP<4>")
	)
	(segment
		(start 418.070538 -237.729268)
		(end 414.821878 -237.729268)
		(width 0.16002)
		(layer "In4.Cu")
		(net "M_J_CPU0_SA_DQS_DP<4>")
	)
	(segment
		(start 414.821878 -237.729268)
		(end 413.948118 -238.603028)
		(width 0.16002)
		(layer "In4.Cu")
		(net "M_J_CPU0_SA_DQS_DP<4>")
	)
	(segment
		(start 394.046202 -246.481092)
		(end 393.556236 -246.481092)
		(width 0.09525)
		(layer "In4.Cu")
		(net "M_J_CPU0_SA_DQS_DP<4>")
	)
	(segment
		(start 420.508684 -238.259874)
		(end 418.601144 -238.259874)
		(width 0.16002)
		(layer "In4.Cu")
		(net "M_J_CPU0_SA_DQS_DP<4>")
	)
	(segment
		(start 388.103364 -246.429276)
		(end 388.094982 -246.434102)
		(width 0.09525)
		(layer "In4.Cu")
		(net "M_J_CPU0_SA_DQS_DP<4>")
	)
	(segment
		(start 407.9748 -241.550698)
		(end 403.591776 -245.933722)
		(width 0.16002)
		(layer "In4.Cu")
		(net "M_J_CPU0_SA_DQS_DP<4>")
	)
	(segment
		(start 430.492916 -237.866428)
		(end 429.784002 -237.866428)
		(width 0.16002)
		(layer "In4.Cu")
		(net "M_J_CPU0_SA_DQS_DP<4>")
	)
	(segment
		(start 395.798294 -245.933722)
		(end 395.774672 -245.933722)
		(width 0.09525)
		(layer "In4.Cu")
		(net "M_J_CPU0_SA_DQS_DP<4>")
	)
	(segment
		(start 384.343402 -246.429276)
		(end 384.33502 -246.434102)
		(width 0.09525)
		(layer "In4.Cu")
		(net "M_J_CPU0_SA_DQS_DP<4>")
	)
	(segment
		(start 383.403348 -246.429276)
		(end 383.394966 -246.434102)
		(width 0.09525)
		(layer "In4.Cu")
		(net "M_J_CPU0_SA_DQS_DP<4>")
	)
	(segment
		(start 420.864538 -238.615728)
		(end 420.508684 -238.259874)
		(width 0.16002)
		(layer "In4.Cu")
		(net "M_J_CPU0_SA_DQS_DP<4>")
	)
	(segment
		(start 425.92752 -238.259874)
		(end 425.077636 -237.40999)
		(width 0.16002)
		(layer "In4.Cu")
		(net "M_J_CPU0_SA_DQS_DP<4>")
	)
	(segment
		(start 394.317982 -246.752872)
		(end 394.046202 -246.481092)
		(width 0.09525)
		(layer "In4.Cu")
		(net "M_J_CPU0_SA_DQS_DP<4>")
	)
	(segment
		(start 421.44569 -238.615728)
		(end 420.864538 -238.615728)
		(width 0.16002)
		(layer "In4.Cu")
		(net "M_J_CPU0_SA_DQS_DP<4>")
	)
	(segment
		(start 384.914648 -246.434102)
		(end 384.906266 -246.429276)
		(width 0.09525)
		(layer "In4.Cu")
		(net "M_J_CPU0_SA_DQS_DP<4>")
	)
	(segment
		(start 380.548642 -246.369586)
		(end 380.394718 -246.104156)
		(width 0.09525)
		(layer "In4.Cu")
		(net "M_J_CPU0_SA_DQS_DP<4>")
	)
	(segment
		(start 395.71549 -245.992904)
		(end 395.538198 -245.992904)
		(width 0.09525)
		(layer "In4.Cu")
		(net "M_J_CPU0_SA_DQS_DP<4>")
	)
	(arc
		(start 390.923272 -246.429276)
		(mid 390.734804 -246.479953)
		(end 390.546336 -246.429276)
		(width 0.09525)
		(layer "In4.Cu")
		(net "M_J_CPU0_SA_DQS_DP<4>")
	)
	(arc
		(start 385.283456 -246.429276)
		(mid 385.099681 -246.480048)
		(end 384.914648 -246.434102)
		(width 0.09525)
		(layer "In4.Cu")
		(net "M_J_CPU0_SA_DQS_DP<4>")
	)
	(arc
		(start 383.026158 -246.429276)
		(mid 382.744726 -246.353521)
		(end 382.463294 -246.429276)
		(width 0.09525)
		(layer "In4.Cu")
		(net "M_J_CPU0_SA_DQS_DP<4>")
	)
	(arc
		(start 383.966212 -246.429276)
		(mid 383.68478 -246.353521)
		(end 383.403348 -246.429276)
		(width 0.09525)
		(layer "In4.Cu")
		(net "M_J_CPU0_SA_DQS_DP<4>")
	)
	(arc
		(start 385.84632 -246.429276)
		(mid 385.564888 -246.353521)
		(end 385.283456 -246.429276)
		(width 0.09525)
		(layer "In4.Cu")
		(net "M_J_CPU0_SA_DQS_DP<4>")
	)
	(arc
		(start 393.556236 -246.481092)
		(mid 393.45807 -246.467724)
		(end 393.366752 -246.429276)
		(width 0.09525)
		(layer "In4.Cu")
		(net "M_J_CPU0_SA_DQS_DP<4>")
	)
	(arc
		(start 388.666228 -246.429276)
		(mid 388.384796 -246.353521)
		(end 388.103364 -246.429276)
		(width 0.09525)
		(layer "In4.Cu")
		(net "M_J_CPU0_SA_DQS_DP<4>")
	)
	(arc
		(start 380.670054 -246.388128)
		(mid 380.659726 -246.392088)
		(end 380.64948 -246.396256)
		(width 0.09525)
		(layer "In4.Cu")
		(net "M_J_CPU0_SA_DQS_DP<4>")
	)
	(arc
		(start 390.546336 -246.429276)
		(mid 390.264904 -246.353521)
		(end 389.983472 -246.429276)
		(width 0.09525)
		(layer "In4.Cu")
		(net "M_J_CPU0_SA_DQS_DP<4>")
	)
	(arc
		(start 386.22351 -246.429276)
		(mid 386.039735 -246.480048)
		(end 385.854702 -246.434102)
		(width 0.09525)
		(layer "In4.Cu")
		(net "M_J_CPU0_SA_DQS_DP<4>")
	)
	(arc
		(start 388.094982 -246.434102)
		(mid 387.90995 -246.480016)
		(end 387.726174 -246.429276)
		(width 0.09525)
		(layer "In4.Cu")
		(net "M_J_CPU0_SA_DQS_DP<4>")
	)
	(arc
		(start 391.486136 -246.429276)
		(mid 391.204704 -246.353521)
		(end 390.923272 -246.429276)
		(width 0.09525)
		(layer "In4.Cu")
		(net "M_J_CPU0_SA_DQS_DP<4>")
	)
	(arc
		(start 382.463294 -246.429276)
		(mid 382.274826 -246.479953)
		(end 382.086358 -246.429276)
		(width 0.09525)
		(layer "In4.Cu")
		(net "M_J_CPU0_SA_DQS_DP<4>")
	)
	(arc
		(start 387.16331 -246.429276)
		(mid 386.974842 -246.479953)
		(end 386.786374 -246.429276)
		(width 0.09525)
		(layer "In4.Cu")
		(net "M_J_CPU0_SA_DQS_DP<4>")
	)
	(arc
		(start 389.606282 -246.429276)
		(mid 389.32485 -246.353521)
		(end 389.043418 -246.429276)
		(width 0.09525)
		(layer "In4.Cu")
		(net "M_J_CPU0_SA_DQS_DP<4>")
	)
	(arc
		(start 386.786374 -246.429276)
		(mid 386.504942 -246.353521)
		(end 386.22351 -246.429276)
		(width 0.09525)
		(layer "In4.Cu")
		(net "M_J_CPU0_SA_DQS_DP<4>")
	)
	(arc
		(start 389.035036 -246.434102)
		(mid 388.850004 -246.480016)
		(end 388.666228 -246.429276)
		(width 0.09525)
		(layer "In4.Cu")
		(net "M_J_CPU0_SA_DQS_DP<4>")
	)
	(arc
		(start 381.523494 -246.429276)
		(mid 381.339719 -246.480048)
		(end 381.154686 -246.434102)
		(width 0.09525)
		(layer "In4.Cu")
		(net "M_J_CPU0_SA_DQS_DP<4>")
	)
	(arc
		(start 382.086358 -246.429276)
		(mid 381.804926 -246.353521)
		(end 381.523494 -246.429276)
		(width 0.09525)
		(layer "In4.Cu")
		(net "M_J_CPU0_SA_DQS_DP<4>")
	)
	(arc
		(start 392.79195 -246.436134)
		(mid 392.608569 -246.479965)
		(end 392.426952 -246.429276)
		(width 0.09525)
		(layer "In4.Cu")
		(net "M_J_CPU0_SA_DQS_DP<4>")
	)
	(arc
		(start 384.33502 -246.434102)
		(mid 384.149988 -246.480016)
		(end 383.966212 -246.429276)
		(width 0.09525)
		(layer "In4.Cu")
		(net "M_J_CPU0_SA_DQS_DP<4>")
	)
	(arc
		(start 384.906266 -246.429276)
		(mid 384.624834 -246.353521)
		(end 384.343402 -246.429276)
		(width 0.09525)
		(layer "In4.Cu")
		(net "M_J_CPU0_SA_DQS_DP<4>")
	)
	(arc
		(start 383.394966 -246.434102)
		(mid 383.209934 -246.480016)
		(end 383.026158 -246.429276)
		(width 0.09525)
		(layer "In4.Cu")
		(net "M_J_CPU0_SA_DQS_DP<4>")
	)
	(arc
		(start 391.863834 -246.429276)
		(mid 391.679805 -246.480175)
		(end 391.494518 -246.434102)
		(width 0.09525)
		(layer "In4.Cu")
		(net "M_J_CPU0_SA_DQS_DP<4>")
	)
	(arc
		(start 392.416538 -246.42318)
		(mid 392.139376 -246.35338)
		(end 391.863834 -246.429276)
		(width 0.09525)
		(layer "In4.Cu")
		(net "M_J_CPU0_SA_DQS_DP<4>")
	)
	(arc
		(start 389.983472 -246.429276)
		(mid 389.799697 -246.480048)
		(end 389.614664 -246.434102)
		(width 0.09525)
		(layer "In4.Cu")
		(net "M_J_CPU0_SA_DQS_DP<4>")
	)
	(arc
		(start 381.146304 -246.429276)
		(mid 380.91279 -246.355433)
		(end 380.670054 -246.388128)
		(width 0.09525)
		(layer "In4.Cu")
		(net "M_J_CPU0_SA_DQS_DP<4>")
	)
	(arc
		(start 393.366752 -246.429276)
		(mid 393.097319 -246.353405)
		(end 392.824716 -246.417084)
		(width 0.09525)
		(layer "In4.Cu")
		(net "M_J_CPU0_SA_DQS_DP<4>")
	)
	(arc
		(start 387.726174 -246.429276)
		(mid 387.444742 -246.353521)
		(end 387.16331 -246.429276)
		(width 0.09525)
		(layer "In4.Cu")
		(net "M_J_CPU0_SA_DQS_DP<4>")
	)
	(segment
		(start 379.927866 -241.510058)
		(end 380.394718 -241.24412)
		(width 0.12954)
		(layer "F.Cu")
		(net "M_J_CPU0_SA_DQS_DP<3>")
	)
	(segment
		(start 405.987758 -233.443018)
		(end 410.177742 -229.253034)
		(width 0.16002)
		(layer "In4.Cu")
		(net "M_J_CPU0_SA_DQS_DP<3>")
	)
	(segment
		(start 425.92752 -228.90988)
		(end 428.105824 -228.90988)
		(width 0.16002)
		(layer "In4.Cu")
		(net "M_J_CPU0_SA_DQS_DP<3>")
	)
	(segment
		(start 433.0192 -228.516434)
		(end 435.098698 -228.516434)
		(width 0.16002)
		(layer "In4.Cu")
		(net "M_J_CPU0_SA_DQS_DP<3>")
	)
	(segment
		(start 383.394966 -241.574066)
		(end 383.403348 -241.56924)
		(width 0.09525)
		(layer "In4.Cu")
		(net "M_J_CPU0_SA_DQS_DP<3>")
	)
	(segment
		(start 425.077636 -228.059996)
		(end 425.92752 -228.90988)
		(width 0.16002)
		(layer "In4.Cu")
		(net "M_J_CPU0_SA_DQS_DP<3>")
	)
	(segment
		(start 394.305028 -240.92281)
		(end 394.736574 -240.92281)
		(width 0.09525)
		(layer "In4.Cu")
		(net "M_J_CPU0_SA_DQS_DP<3>")
	)
	(segment
		(start 389.606282 -241.56924)
		(end 389.614664 -241.574066)
		(width 0.09525)
		(layer "In4.Cu")
		(net "M_J_CPU0_SA_DQS_DP<3>")
	)
	(segment
		(start 395.769338 -240.355882)
		(end 395.82852 -240.2967)
		(width 0.09525)
		(layer "In4.Cu")
		(net "M_J_CPU0_SA_DQS_DP<3>")
	)
	(segment
		(start 438.826402 -229.058978)
		(end 439.100214 -228.785166)
		(width 0.16002)
		(layer "In4.Cu")
		(net "M_J_CPU0_SA_DQS_DP<3>")
	)
	(segment
		(start 399.618708 -240.2967)
		(end 405.987758 -233.92765)
		(width 0.16002)
		(layer "In4.Cu")
		(net "M_J_CPU0_SA_DQS_DP<3>")
	)
	(segment
		(start 421.44569 -229.265734)
		(end 422.12387 -228.587554)
		(width 0.16002)
		(layer "In4.Cu")
		(net "M_J_CPU0_SA_DQS_DP<3>")
	)
	(segment
		(start 395.82852 -240.2967)
		(end 395.852142 -240.2967)
		(width 0.09525)
		(layer "In4.Cu")
		(net "M_J_CPU0_SA_DQS_DP<3>")
	)
	(segment
		(start 435.822598 -229.240334)
		(end 436.752238 -229.240334)
		(width 0.16002)
		(layer "In4.Cu")
		(net "M_J_CPU0_SA_DQS_DP<3>")
	)
	(segment
		(start 384.33502 -241.574066)
		(end 384.343402 -241.56924)
		(width 0.09525)
		(layer "In4.Cu")
		(net "M_J_CPU0_SA_DQS_DP<3>")
	)
	(segment
		(start 430.492916 -228.516434)
		(end 430.949354 -228.059996)
		(width 0.16002)
		(layer "In4.Cu")
		(net "M_J_CPU0_SA_DQS_DP<3>")
	)
	(segment
		(start 405.987758 -233.92765)
		(end 405.987758 -233.443018)
		(width 0.16002)
		(layer "In4.Cu")
		(net "M_J_CPU0_SA_DQS_DP<3>")
	)
	(segment
		(start 380.548642 -241.50955)
		(end 380.64948 -241.53622)
		(width 0.09525)
		(layer "In4.Cu")
		(net "M_J_CPU0_SA_DQS_DP<3>")
	)
	(segment
		(start 385.84632 -241.56924)
		(end 385.854702 -241.574066)
		(width 0.09525)
		(layer "In4.Cu")
		(net "M_J_CPU0_SA_DQS_DP<3>")
	)
	(segment
		(start 392.416538 -241.563144)
		(end 392.426952 -241.56924)
		(width 0.09525)
		(layer "In4.Cu")
		(net "M_J_CPU0_SA_DQS_DP<3>")
	)
	(segment
		(start 418.601144 -228.90988)
		(end 420.508684 -228.90988)
		(width 0.16002)
		(layer "In4.Cu")
		(net "M_J_CPU0_SA_DQS_DP<3>")
	)
	(segment
		(start 381.146304 -241.56924)
		(end 381.154686 -241.574066)
		(width 0.09525)
		(layer "In4.Cu")
		(net "M_J_CPU0_SA_DQS_DP<3>")
	)
	(segment
		(start 436.933594 -229.058978)
		(end 438.826402 -229.058978)
		(width 0.16002)
		(layer "In4.Cu")
		(net "M_J_CPU0_SA_DQS_DP<3>")
	)
	(segment
		(start 394.736574 -240.92281)
		(end 395.303502 -240.355882)
		(width 0.09525)
		(layer "In4.Cu")
		(net "M_J_CPU0_SA_DQS_DP<3>")
	)
	(segment
		(start 414.821878 -228.379274)
		(end 418.070538 -228.379274)
		(width 0.16002)
		(layer "In4.Cu")
		(net "M_J_CPU0_SA_DQS_DP<3>")
	)
	(segment
		(start 428.105824 -228.90988)
		(end 428.481998 -229.286054)
		(width 0.16002)
		(layer "In4.Cu")
		(net "M_J_CPU0_SA_DQS_DP<3>")
	)
	(segment
		(start 380.394718 -241.24412)
		(end 380.548642 -241.50955)
		(width 0.09525)
		(layer "In4.Cu")
		(net "M_J_CPU0_SA_DQS_DP<3>")
	)
	(segment
		(start 436.752238 -229.240334)
		(end 436.933594 -229.058978)
		(width 0.16002)
		(layer "In4.Cu")
		(net "M_J_CPU0_SA_DQS_DP<3>")
	)
	(segment
		(start 395.303502 -240.355882)
		(end 395.769338 -240.355882)
		(width 0.09525)
		(layer "In4.Cu")
		(net "M_J_CPU0_SA_DQS_DP<3>")
	)
	(segment
		(start 384.906266 -241.56924)
		(end 384.914648 -241.574066)
		(width 0.09525)
		(layer "In4.Cu")
		(net "M_J_CPU0_SA_DQS_DP<3>")
	)
	(segment
		(start 430.949354 -228.059996)
		(end 432.562762 -228.059996)
		(width 0.16002)
		(layer "In4.Cu")
		(net "M_J_CPU0_SA_DQS_DP<3>")
	)
	(segment
		(start 435.098698 -228.516434)
		(end 435.822598 -229.240334)
		(width 0.16002)
		(layer "In4.Cu")
		(net "M_J_CPU0_SA_DQS_DP<3>")
	)
	(segment
		(start 429.014382 -229.286054)
		(end 429.784002 -228.516434)
		(width 0.16002)
		(layer "In4.Cu")
		(net "M_J_CPU0_SA_DQS_DP<3>")
	)
	(segment
		(start 418.070538 -228.379274)
		(end 418.601144 -228.90988)
		(width 0.16002)
		(layer "In4.Cu")
		(net "M_J_CPU0_SA_DQS_DP<3>")
	)
	(segment
		(start 391.486136 -241.56924)
		(end 391.494518 -241.574066)
		(width 0.09525)
		(layer "In4.Cu")
		(net "M_J_CPU0_SA_DQS_DP<3>")
	)
	(segment
		(start 388.094982 -241.574066)
		(end 388.103364 -241.56924)
		(width 0.09525)
		(layer "In4.Cu")
		(net "M_J_CPU0_SA_DQS_DP<3>")
	)
	(segment
		(start 420.864538 -229.265734)
		(end 421.44569 -229.265734)
		(width 0.16002)
		(layer "In4.Cu")
		(net "M_J_CPU0_SA_DQS_DP<3>")
	)
	(segment
		(start 395.852142 -240.2967)
		(end 399.618708 -240.2967)
		(width 0.16002)
		(layer "In4.Cu")
		(net "M_J_CPU0_SA_DQS_DP<3>")
	)
	(segment
		(start 389.035036 -241.574066)
		(end 389.043418 -241.56924)
		(width 0.09525)
		(layer "In4.Cu")
		(net "M_J_CPU0_SA_DQS_DP<3>")
	)
	(segment
		(start 423.479976 -228.059996)
		(end 425.077636 -228.059996)
		(width 0.16002)
		(layer "In4.Cu")
		(net "M_J_CPU0_SA_DQS_DP<3>")
	)
	(segment
		(start 429.784002 -228.516434)
		(end 430.492916 -228.516434)
		(width 0.16002)
		(layer "In4.Cu")
		(net "M_J_CPU0_SA_DQS_DP<3>")
	)
	(segment
		(start 393.084812 -241.493548)
		(end 393.73429 -241.493548)
		(width 0.09525)
		(layer "In4.Cu")
		(net "M_J_CPU0_SA_DQS_DP<3>")
	)
	(segment
		(start 422.12387 -228.587554)
		(end 422.952418 -228.587554)
		(width 0.16002)
		(layer "In4.Cu")
		(net "M_J_CPU0_SA_DQS_DP<3>")
	)
	(segment
		(start 410.177742 -229.253034)
		(end 413.948118 -229.253034)
		(width 0.16002)
		(layer "In4.Cu")
		(net "M_J_CPU0_SA_DQS_DP<3>")
	)
	(segment
		(start 413.948118 -229.253034)
		(end 414.821878 -228.379274)
		(width 0.16002)
		(layer "In4.Cu")
		(net "M_J_CPU0_SA_DQS_DP<3>")
	)
	(segment
		(start 422.952418 -228.587554)
		(end 423.479976 -228.059996)
		(width 0.16002)
		(layer "In4.Cu")
		(net "M_J_CPU0_SA_DQS_DP<3>")
	)
	(segment
		(start 393.73429 -241.493548)
		(end 394.305028 -240.92281)
		(width 0.09525)
		(layer "In4.Cu")
		(net "M_J_CPU0_SA_DQS_DP<3>")
	)
	(segment
		(start 428.481998 -229.286054)
		(end 429.014382 -229.286054)
		(width 0.16002)
		(layer "In4.Cu")
		(net "M_J_CPU0_SA_DQS_DP<3>")
	)
	(segment
		(start 432.562762 -228.059996)
		(end 433.0192 -228.516434)
		(width 0.16002)
		(layer "In4.Cu")
		(net "M_J_CPU0_SA_DQS_DP<3>")
	)
	(segment
		(start 420.508684 -228.90988)
		(end 420.864538 -229.265734)
		(width 0.16002)
		(layer "In4.Cu")
		(net "M_J_CPU0_SA_DQS_DP<3>")
	)
	(arc
		(start 385.283456 -241.56924)
		(mid 385.564888 -241.493485)
		(end 385.84632 -241.56924)
		(width 0.09525)
		(layer "In4.Cu")
		(net "M_J_CPU0_SA_DQS_DP<3>")
	)
	(arc
		(start 389.043418 -241.56924)
		(mid 389.32485 -241.493485)
		(end 389.606282 -241.56924)
		(width 0.09525)
		(layer "In4.Cu")
		(net "M_J_CPU0_SA_DQS_DP<3>")
	)
	(arc
		(start 383.966212 -241.56924)
		(mid 384.149987 -241.620012)
		(end 384.33502 -241.574066)
		(width 0.09525)
		(layer "In4.Cu")
		(net "M_J_CPU0_SA_DQS_DP<3>")
	)
	(arc
		(start 384.343402 -241.56924)
		(mid 384.624834 -241.493485)
		(end 384.906266 -241.56924)
		(width 0.09525)
		(layer "In4.Cu")
		(net "M_J_CPU0_SA_DQS_DP<3>")
	)
	(arc
		(start 381.154686 -241.574066)
		(mid 381.339718 -241.61998)
		(end 381.523494 -241.56924)
		(width 0.09525)
		(layer "In4.Cu")
		(net "M_J_CPU0_SA_DQS_DP<3>")
	)
	(arc
		(start 390.546336 -241.56924)
		(mid 390.734804 -241.619917)
		(end 390.923272 -241.56924)
		(width 0.09525)
		(layer "In4.Cu")
		(net "M_J_CPU0_SA_DQS_DP<3>")
	)
	(arc
		(start 386.786374 -241.56924)
		(mid 386.974842 -241.619917)
		(end 387.16331 -241.56924)
		(width 0.09525)
		(layer "In4.Cu")
		(net "M_J_CPU0_SA_DQS_DP<3>")
	)
	(arc
		(start 388.666228 -241.56924)
		(mid 388.850003 -241.620012)
		(end 389.035036 -241.574066)
		(width 0.09525)
		(layer "In4.Cu")
		(net "M_J_CPU0_SA_DQS_DP<3>")
	)
	(arc
		(start 381.523494 -241.56924)
		(mid 381.804926 -241.493485)
		(end 382.086358 -241.56924)
		(width 0.09525)
		(layer "In4.Cu")
		(net "M_J_CPU0_SA_DQS_DP<3>")
	)
	(arc
		(start 391.494518 -241.574066)
		(mid 391.679804 -241.620102)
		(end 391.863834 -241.56924)
		(width 0.09525)
		(layer "In4.Cu")
		(net "M_J_CPU0_SA_DQS_DP<3>")
	)
	(arc
		(start 383.026158 -241.56924)
		(mid 383.209933 -241.620012)
		(end 383.394966 -241.574066)
		(width 0.09525)
		(layer "In4.Cu")
		(net "M_J_CPU0_SA_DQS_DP<3>")
	)
	(arc
		(start 383.403348 -241.56924)
		(mid 383.68478 -241.493485)
		(end 383.966212 -241.56924)
		(width 0.09525)
		(layer "In4.Cu")
		(net "M_J_CPU0_SA_DQS_DP<3>")
	)
	(arc
		(start 387.726174 -241.56924)
		(mid 387.909949 -241.620012)
		(end 388.094982 -241.574066)
		(width 0.09525)
		(layer "In4.Cu")
		(net "M_J_CPU0_SA_DQS_DP<3>")
	)
	(arc
		(start 382.086358 -241.56924)
		(mid 382.274826 -241.619917)
		(end 382.463294 -241.56924)
		(width 0.09525)
		(layer "In4.Cu")
		(net "M_J_CPU0_SA_DQS_DP<3>")
	)
	(arc
		(start 385.854702 -241.574066)
		(mid 386.039734 -241.61998)
		(end 386.22351 -241.56924)
		(width 0.09525)
		(layer "In4.Cu")
		(net "M_J_CPU0_SA_DQS_DP<3>")
	)
	(arc
		(start 380.670054 -241.528092)
		(mid 380.912796 -241.495322)
		(end 381.146304 -241.56924)
		(width 0.09525)
		(layer "In4.Cu")
		(net "M_J_CPU0_SA_DQS_DP<3>")
	)
	(arc
		(start 389.983472 -241.56924)
		(mid 390.264904 -241.493485)
		(end 390.546336 -241.56924)
		(width 0.09525)
		(layer "In4.Cu")
		(net "M_J_CPU0_SA_DQS_DP<3>")
	)
	(arc
		(start 392.79195 -241.576098)
		(mid 392.932676 -241.514587)
		(end 393.084812 -241.493548)
		(width 0.09525)
		(layer "In4.Cu")
		(net "M_J_CPU0_SA_DQS_DP<3>")
	)
	(arc
		(start 392.426952 -241.56924)
		(mid 392.608568 -241.619977)
		(end 392.79195 -241.576098)
		(width 0.09525)
		(layer "In4.Cu")
		(net "M_J_CPU0_SA_DQS_DP<3>")
	)
	(arc
		(start 384.914648 -241.574066)
		(mid 385.09968 -241.61998)
		(end 385.283456 -241.56924)
		(width 0.09525)
		(layer "In4.Cu")
		(net "M_J_CPU0_SA_DQS_DP<3>")
	)
	(arc
		(start 391.863834 -241.56924)
		(mid 392.139377 -241.493391)
		(end 392.416538 -241.563144)
		(width 0.09525)
		(layer "In4.Cu")
		(net "M_J_CPU0_SA_DQS_DP<3>")
	)
	(arc
		(start 388.103364 -241.56924)
		(mid 388.384796 -241.493485)
		(end 388.666228 -241.56924)
		(width 0.09525)
		(layer "In4.Cu")
		(net "M_J_CPU0_SA_DQS_DP<3>")
	)
	(arc
		(start 382.463294 -241.56924)
		(mid 382.744726 -241.493485)
		(end 383.026158 -241.56924)
		(width 0.09525)
		(layer "In4.Cu")
		(net "M_J_CPU0_SA_DQS_DP<3>")
	)
	(arc
		(start 380.64948 -241.53622)
		(mid 380.659728 -241.532057)
		(end 380.670054 -241.528092)
		(width 0.09525)
		(layer "In4.Cu")
		(net "M_J_CPU0_SA_DQS_DP<3>")
	)
	(arc
		(start 386.22351 -241.56924)
		(mid 386.504942 -241.493485)
		(end 386.786374 -241.56924)
		(width 0.09525)
		(layer "In4.Cu")
		(net "M_J_CPU0_SA_DQS_DP<3>")
	)
	(arc
		(start 390.923272 -241.56924)
		(mid 391.204704 -241.493485)
		(end 391.486136 -241.56924)
		(width 0.09525)
		(layer "In4.Cu")
		(net "M_J_CPU0_SA_DQS_DP<3>")
	)
	(arc
		(start 389.614664 -241.574066)
		(mid 389.799696 -241.61998)
		(end 389.983472 -241.56924)
		(width 0.09525)
		(layer "In4.Cu")
		(net "M_J_CPU0_SA_DQS_DP<3>")
	)
	(arc
		(start 387.16331 -241.56924)
		(mid 387.444742 -241.493485)
		(end 387.726174 -241.56924)
		(width 0.09525)
		(layer "In4.Cu")
		(net "M_J_CPU0_SA_DQS_DP<3>")
	)
	(segment
		(start 379.927866 -236.650022)
		(end 380.394718 -236.384084)
		(width 0.12954)
		(layer "F.Cu")
		(net "M_J_CPU0_SA_DQS_DP<2>")
	)
	(segment
		(start 433.0192 -219.16644)
		(end 432.562762 -218.710002)
		(width 0.16002)
		(layer "In4.Cu")
		(net "M_J_CPU0_SA_DQS_DP<2>")
	)
	(segment
		(start 385.854702 -236.71403)
		(end 385.84632 -236.709204)
		(width 0.09525)
		(layer "In4.Cu")
		(net "M_J_CPU0_SA_DQS_DP<2>")
	)
	(segment
		(start 439.100214 -219.435172)
		(end 438.826402 -219.708984)
		(width 0.16002)
		(layer "In4.Cu")
		(net "M_J_CPU0_SA_DQS_DP<2>")
	)
	(segment
		(start 436.933594 -219.708984)
		(end 436.752238 -219.89034)
		(width 0.16002)
		(layer "In4.Cu")
		(net "M_J_CPU0_SA_DQS_DP<2>")
	)
	(segment
		(start 403.124162 -225.882708)
		(end 403.124162 -228.292914)
		(width 0.16002)
		(layer "In4.Cu")
		(net "M_J_CPU0_SA_DQS_DP<2>")
	)
	(segment
		(start 413.948118 -219.90304)
		(end 413.233362 -219.90304)
		(width 0.16002)
		(layer "In4.Cu")
		(net "M_J_CPU0_SA_DQS_DP<2>")
	)
	(segment
		(start 394.440664 -235.481622)
		(end 393.292584 -236.629702)
		(width 0.09525)
		(layer "In4.Cu")
		(net "M_J_CPU0_SA_DQS_DP<2>")
	)
	(segment
		(start 403.124162 -228.292914)
		(end 396.849854 -234.567222)
		(width 0.16002)
		(layer "In4.Cu")
		(net "M_J_CPU0_SA_DQS_DP<2>")
	)
	(segment
		(start 381.154686 -236.71403)
		(end 381.146304 -236.709204)
		(width 0.09525)
		(layer "In4.Cu")
		(net "M_J_CPU0_SA_DQS_DP<2>")
	)
	(segment
		(start 383.403348 -236.709204)
		(end 383.394966 -236.71403)
		(width 0.09525)
		(layer "In4.Cu")
		(net "M_J_CPU0_SA_DQS_DP<2>")
	)
	(segment
		(start 432.562762 -218.710002)
		(end 430.949354 -218.710002)
		(width 0.16002)
		(layer "In4.Cu")
		(net "M_J_CPU0_SA_DQS_DP<2>")
	)
	(segment
		(start 430.492916 -219.16644)
		(end 429.784002 -219.16644)
		(width 0.16002)
		(layer "In4.Cu")
		(net "M_J_CPU0_SA_DQS_DP<2>")
	)
	(segment
		(start 414.821878 -219.02928)
		(end 413.948118 -219.90304)
		(width 0.16002)
		(layer "In4.Cu")
		(net "M_J_CPU0_SA_DQS_DP<2>")
	)
	(segment
		(start 412.910274 -219.579952)
		(end 409.426918 -219.579952)
		(width 0.16002)
		(layer "In4.Cu")
		(net "M_J_CPU0_SA_DQS_DP<2>")
	)
	(segment
		(start 393.292584 -236.629702)
		(end 393.042902 -236.629702)
		(width 0.09525)
		(layer "In4.Cu")
		(net "M_J_CPU0_SA_DQS_DP<2>")
	)
	(segment
		(start 413.233362 -219.90304)
		(end 412.910274 -219.579952)
		(width 0.16002)
		(layer "In4.Cu")
		(net "M_J_CPU0_SA_DQS_DP<2>")
	)
	(segment
		(start 425.077636 -218.710002)
		(end 423.479976 -218.710002)
		(width 0.16002)
		(layer "In4.Cu")
		(net "M_J_CPU0_SA_DQS_DP<2>")
	)
	(segment
		(start 429.784002 -219.16644)
		(end 429.014382 -219.93606)
		(width 0.16002)
		(layer "In4.Cu")
		(net "M_J_CPU0_SA_DQS_DP<2>")
	)
	(segment
		(start 428.105824 -219.559886)
		(end 425.92752 -219.559886)
		(width 0.16002)
		(layer "In4.Cu")
		(net "M_J_CPU0_SA_DQS_DP<2>")
	)
	(segment
		(start 395.766544 -234.626404)
		(end 395.509496 -234.626404)
		(width 0.09525)
		(layer "In4.Cu")
		(net "M_J_CPU0_SA_DQS_DP<2>")
	)
	(segment
		(start 380.64948 -236.676184)
		(end 380.548642 -236.649514)
		(width 0.09525)
		(layer "In4.Cu")
		(net "M_J_CPU0_SA_DQS_DP<2>")
	)
	(segment
		(start 435.822598 -219.89034)
		(end 435.098698 -219.16644)
		(width 0.16002)
		(layer "In4.Cu")
		(net "M_J_CPU0_SA_DQS_DP<2>")
	)
	(segment
		(start 388.103364 -236.709204)
		(end 388.094982 -236.71403)
		(width 0.09525)
		(layer "In4.Cu")
		(net "M_J_CPU0_SA_DQS_DP<2>")
	)
	(segment
		(start 389.614664 -236.71403)
		(end 389.606282 -236.709204)
		(width 0.09525)
		(layer "In4.Cu")
		(net "M_J_CPU0_SA_DQS_DP<2>")
	)
	(segment
		(start 380.548642 -236.649514)
		(end 380.394718 -236.384084)
		(width 0.09525)
		(layer "In4.Cu")
		(net "M_J_CPU0_SA_DQS_DP<2>")
	)
	(segment
		(start 418.070538 -219.02928)
		(end 414.821878 -219.02928)
		(width 0.16002)
		(layer "In4.Cu")
		(net "M_J_CPU0_SA_DQS_DP<2>")
	)
	(segment
		(start 422.12387 -219.23756)
		(end 421.44569 -219.91574)
		(width 0.16002)
		(layer "In4.Cu")
		(net "M_J_CPU0_SA_DQS_DP<2>")
	)
	(segment
		(start 396.849854 -234.567222)
		(end 395.849348 -234.567222)
		(width 0.16002)
		(layer "In4.Cu")
		(net "M_J_CPU0_SA_DQS_DP<2>")
	)
	(segment
		(start 420.508684 -219.559886)
		(end 418.601144 -219.559886)
		(width 0.16002)
		(layer "In4.Cu")
		(net "M_J_CPU0_SA_DQS_DP<2>")
	)
	(segment
		(start 409.426918 -219.579952)
		(end 403.124162 -225.882708)
		(width 0.16002)
		(layer "In4.Cu")
		(net "M_J_CPU0_SA_DQS_DP<2>")
	)
	(segment
		(start 395.849348 -234.567222)
		(end 395.825726 -234.567222)
		(width 0.09525)
		(layer "In4.Cu")
		(net "M_J_CPU0_SA_DQS_DP<2>")
	)
	(segment
		(start 395.509496 -234.626404)
		(end 394.801598 -235.481622)
		(width 0.09525)
		(layer "In4.Cu")
		(net "M_J_CPU0_SA_DQS_DP<2>")
	)
	(segment
		(start 438.826402 -219.708984)
		(end 436.933594 -219.708984)
		(width 0.16002)
		(layer "In4.Cu")
		(net "M_J_CPU0_SA_DQS_DP<2>")
	)
	(segment
		(start 436.752238 -219.89034)
		(end 435.822598 -219.89034)
		(width 0.16002)
		(layer "In4.Cu")
		(net "M_J_CPU0_SA_DQS_DP<2>")
	)
	(segment
		(start 429.014382 -219.93606)
		(end 428.481998 -219.93606)
		(width 0.16002)
		(layer "In4.Cu")
		(net "M_J_CPU0_SA_DQS_DP<2>")
	)
	(segment
		(start 418.601144 -219.559886)
		(end 418.070538 -219.02928)
		(width 0.16002)
		(layer "In4.Cu")
		(net "M_J_CPU0_SA_DQS_DP<2>")
	)
	(segment
		(start 428.481998 -219.93606)
		(end 428.105824 -219.559886)
		(width 0.16002)
		(layer "In4.Cu")
		(net "M_J_CPU0_SA_DQS_DP<2>")
	)
	(segment
		(start 420.864538 -219.91574)
		(end 420.508684 -219.559886)
		(width 0.16002)
		(layer "In4.Cu")
		(net "M_J_CPU0_SA_DQS_DP<2>")
	)
	(segment
		(start 384.914648 -236.71403)
		(end 384.906266 -236.709204)
		(width 0.09525)
		(layer "In4.Cu")
		(net "M_J_CPU0_SA_DQS_DP<2>")
	)
	(segment
		(start 423.479976 -218.710002)
		(end 422.952418 -219.23756)
		(width 0.16002)
		(layer "In4.Cu")
		(net "M_J_CPU0_SA_DQS_DP<2>")
	)
	(segment
		(start 389.043418 -236.709204)
		(end 389.035036 -236.71403)
		(width 0.09525)
		(layer "In4.Cu")
		(net "M_J_CPU0_SA_DQS_DP<2>")
	)
	(segment
		(start 394.801598 -235.481622)
		(end 394.440664 -235.481622)
		(width 0.09525)
		(layer "In4.Cu")
		(net "M_J_CPU0_SA_DQS_DP<2>")
	)
	(segment
		(start 384.343402 -236.709204)
		(end 384.33502 -236.71403)
		(width 0.09525)
		(layer "In4.Cu")
		(net "M_J_CPU0_SA_DQS_DP<2>")
	)
	(segment
		(start 421.44569 -219.91574)
		(end 420.864538 -219.91574)
		(width 0.16002)
		(layer "In4.Cu")
		(net "M_J_CPU0_SA_DQS_DP<2>")
	)
	(segment
		(start 435.098698 -219.16644)
		(end 433.0192 -219.16644)
		(width 0.16002)
		(layer "In4.Cu")
		(net "M_J_CPU0_SA_DQS_DP<2>")
	)
	(segment
		(start 392.376152 -236.679486)
		(end 392.376152 -236.679994)
		(width 0.09525)
		(layer "In4.Cu")
		(net "M_J_CPU0_SA_DQS_DP<2>")
	)
	(segment
		(start 425.92752 -219.559886)
		(end 425.077636 -218.710002)
		(width 0.16002)
		(layer "In4.Cu")
		(net "M_J_CPU0_SA_DQS_DP<2>")
	)
	(segment
		(start 395.825726 -234.567222)
		(end 395.766544 -234.626404)
		(width 0.09525)
		(layer "In4.Cu")
		(net "M_J_CPU0_SA_DQS_DP<2>")
	)
	(segment
		(start 422.952418 -219.23756)
		(end 422.12387 -219.23756)
		(width 0.16002)
		(layer "In4.Cu")
		(net "M_J_CPU0_SA_DQS_DP<2>")
	)
	(segment
		(start 430.949354 -218.710002)
		(end 430.492916 -219.16644)
		(width 0.16002)
		(layer "In4.Cu")
		(net "M_J_CPU0_SA_DQS_DP<2>")
	)
	(arc
		(start 383.026158 -236.709204)
		(mid 382.744726 -236.633449)
		(end 382.463294 -236.709204)
		(width 0.09525)
		(layer "In4.Cu")
		(net "M_J_CPU0_SA_DQS_DP<2>")
	)
	(arc
		(start 387.16331 -236.709204)
		(mid 386.974842 -236.759881)
		(end 386.786374 -236.709204)
		(width 0.09525)
		(layer "In4.Cu")
		(net "M_J_CPU0_SA_DQS_DP<2>")
	)
	(arc
		(start 386.786374 -236.709204)
		(mid 386.504942 -236.633449)
		(end 386.22351 -236.709204)
		(width 0.09525)
		(layer "In4.Cu")
		(net "M_J_CPU0_SA_DQS_DP<2>")
	)
	(arc
		(start 388.094982 -236.71403)
		(mid 387.90995 -236.759944)
		(end 387.726174 -236.709204)
		(width 0.09525)
		(layer "In4.Cu")
		(net "M_J_CPU0_SA_DQS_DP<2>")
	)
	(arc
		(start 389.035036 -236.71403)
		(mid 388.850004 -236.759944)
		(end 388.666228 -236.709204)
		(width 0.09525)
		(layer "In4.Cu")
		(net "M_J_CPU0_SA_DQS_DP<2>")
	)
	(arc
		(start 387.726174 -236.709204)
		(mid 387.444742 -236.633449)
		(end 387.16331 -236.709204)
		(width 0.09525)
		(layer "In4.Cu")
		(net "M_J_CPU0_SA_DQS_DP<2>")
	)
	(arc
		(start 385.283456 -236.709204)
		(mid 385.099681 -236.759976)
		(end 384.914648 -236.71403)
		(width 0.09525)
		(layer "In4.Cu")
		(net "M_J_CPU0_SA_DQS_DP<2>")
	)
	(arc
		(start 384.33502 -236.71403)
		(mid 384.149988 -236.759944)
		(end 383.966212 -236.709204)
		(width 0.09525)
		(layer "In4.Cu")
		(net "M_J_CPU0_SA_DQS_DP<2>")
	)
	(arc
		(start 389.606282 -236.709204)
		(mid 389.32485 -236.633449)
		(end 389.043418 -236.709204)
		(width 0.09525)
		(layer "In4.Cu")
		(net "M_J_CPU0_SA_DQS_DP<2>")
	)
	(arc
		(start 391.889234 -236.701076)
		(mid 391.685574 -236.740302)
		(end 391.481564 -236.702854)
		(width 0.09525)
		(layer "In4.Cu")
		(net "M_J_CPU0_SA_DQS_DP<2>")
	)
	(arc
		(start 381.146304 -236.709204)
		(mid 380.91279 -236.635361)
		(end 380.670054 -236.668056)
		(width 0.09525)
		(layer "In4.Cu")
		(net "M_J_CPU0_SA_DQS_DP<2>")
	)
	(arc
		(start 383.394966 -236.71403)
		(mid 383.209934 -236.759944)
		(end 383.026158 -236.709204)
		(width 0.09525)
		(layer "In4.Cu")
		(net "M_J_CPU0_SA_DQS_DP<2>")
	)
	(arc
		(start 382.086358 -236.709204)
		(mid 381.804926 -236.633449)
		(end 381.523494 -236.709204)
		(width 0.09525)
		(layer "In4.Cu")
		(net "M_J_CPU0_SA_DQS_DP<2>")
	)
	(arc
		(start 383.966212 -236.709204)
		(mid 383.68478 -236.633449)
		(end 383.403348 -236.709204)
		(width 0.09525)
		(layer "In4.Cu")
		(net "M_J_CPU0_SA_DQS_DP<2>")
	)
	(arc
		(start 382.463294 -236.709204)
		(mid 382.274826 -236.759881)
		(end 382.086358 -236.709204)
		(width 0.09525)
		(layer "In4.Cu")
		(net "M_J_CPU0_SA_DQS_DP<2>")
	)
	(arc
		(start 390.923272 -236.709204)
		(mid 390.909458 -236.716866)
		(end 390.895332 -236.723936)
		(width 0.09525)
		(layer "In4.Cu")
		(net "M_J_CPU0_SA_DQS_DP<2>")
	)
	(arc
		(start 385.84632 -236.709204)
		(mid 385.564888 -236.633449)
		(end 385.283456 -236.709204)
		(width 0.09525)
		(layer "In4.Cu")
		(net "M_J_CPU0_SA_DQS_DP<2>")
	)
	(arc
		(start 389.983472 -236.709204)
		(mid 389.799697 -236.759976)
		(end 389.614664 -236.71403)
		(width 0.09525)
		(layer "In4.Cu")
		(net "M_J_CPU0_SA_DQS_DP<2>")
	)
	(arc
		(start 392.376152 -236.679994)
		(mid 392.130913 -236.649552)
		(end 391.889234 -236.701076)
		(width 0.09525)
		(layer "In4.Cu")
		(net "M_J_CPU0_SA_DQS_DP<2>")
	)
	(arc
		(start 384.906266 -236.709204)
		(mid 384.624834 -236.633449)
		(end 384.343402 -236.709204)
		(width 0.09525)
		(layer "In4.Cu")
		(net "M_J_CPU0_SA_DQS_DP<2>")
	)
	(arc
		(start 392.92149 -236.653324)
		(mid 392.651066 -236.713059)
		(end 392.376152 -236.679486)
		(width 0.09525)
		(layer "In4.Cu")
		(net "M_J_CPU0_SA_DQS_DP<2>")
	)
	(arc
		(start 393.042902 -236.629702)
		(mid 392.981046 -236.635596)
		(end 392.92149 -236.653324)
		(width 0.09525)
		(layer "In4.Cu")
		(net "M_J_CPU0_SA_DQS_DP<2>")
	)
	(arc
		(start 390.546336 -236.709204)
		(mid 390.264904 -236.633449)
		(end 389.983472 -236.709204)
		(width 0.09525)
		(layer "In4.Cu")
		(net "M_J_CPU0_SA_DQS_DP<2>")
	)
	(arc
		(start 391.481564 -236.702854)
		(mid 391.462624 -236.695192)
		(end 391.443972 -236.686852)
		(width 0.09525)
		(layer "In4.Cu")
		(net "M_J_CPU0_SA_DQS_DP<2>")
	)
	(arc
		(start 386.22351 -236.709204)
		(mid 386.039735 -236.759976)
		(end 385.854702 -236.71403)
		(width 0.09525)
		(layer "In4.Cu")
		(net "M_J_CPU0_SA_DQS_DP<2>")
	)
	(arc
		(start 388.666228 -236.709204)
		(mid 388.384796 -236.633449)
		(end 388.103364 -236.709204)
		(width 0.09525)
		(layer "In4.Cu")
		(net "M_J_CPU0_SA_DQS_DP<2>")
	)
	(arc
		(start 390.895332 -236.723936)
		(mid 390.71901 -236.759609)
		(end 390.546336 -236.709204)
		(width 0.09525)
		(layer "In4.Cu")
		(net "M_J_CPU0_SA_DQS_DP<2>")
	)
	(arc
		(start 391.443972 -236.686852)
		(mid 391.180873 -236.633878)
		(end 390.923272 -236.709204)
		(width 0.09525)
		(layer "In4.Cu")
		(net "M_J_CPU0_SA_DQS_DP<2>")
	)
	(arc
		(start 380.670054 -236.668056)
		(mid 380.659726 -236.672016)
		(end 380.64948 -236.676184)
		(width 0.09525)
		(layer "In4.Cu")
		(net "M_J_CPU0_SA_DQS_DP<2>")
	)
	(arc
		(start 381.523494 -236.709204)
		(mid 381.339719 -236.759976)
		(end 381.154686 -236.71403)
		(width 0.09525)
		(layer "In4.Cu")
		(net "M_J_CPU0_SA_DQS_DP<2>")
	)
	(segment
		(start 379.927866 -231.789986)
		(end 380.394718 -231.524048)
		(width 0.12954)
		(layer "F.Cu")
		(net "M_J_CPU0_SA_DQS_DP<1>")
	)
	(segment
		(start 395.383512 -227.528882)
		(end 397.586962 -225.325432)
		(width 0.16002)
		(layer "In4.Cu")
		(net "M_J_CPU0_SA_DQS_DP<1>")
	)
	(segment
		(start 383.394966 -231.853994)
		(end 383.403348 -231.849168)
		(width 0.09525)
		(layer "In4.Cu")
		(net "M_J_CPU0_SA_DQS_DP<1>")
	)
	(segment
		(start 429.67402 -209.926428)
		(end 431.041302 -209.360008)
		(width 0.16002)
		(layer "In4.Cu")
		(net "M_J_CPU0_SA_DQS_DP<1>")
	)
	(segment
		(start 389.035036 -231.853994)
		(end 389.043418 -231.849168)
		(width 0.09525)
		(layer "In4.Cu")
		(net "M_J_CPU0_SA_DQS_DP<1>")
	)
	(segment
		(start 435.822598 -210.540346)
		(end 436.752238 -210.540346)
		(width 0.16002)
		(layer "In4.Cu")
		(net "M_J_CPU0_SA_DQS_DP<1>")
	)
	(segment
		(start 380.394718 -231.524048)
		(end 380.548642 -231.789478)
		(width 0.09525)
		(layer "In4.Cu")
		(net "M_J_CPU0_SA_DQS_DP<1>")
	)
	(segment
		(start 422.952418 -209.887566)
		(end 423.479976 -209.360008)
		(width 0.16002)
		(layer "In4.Cu")
		(net "M_J_CPU0_SA_DQS_DP<1>")
	)
	(segment
		(start 397.586962 -225.325432)
		(end 397.586962 -221.791276)
		(width 0.16002)
		(layer "In4.Cu")
		(net "M_J_CPU0_SA_DQS_DP<1>")
	)
	(segment
		(start 392.400536 -230.607362)
		(end 392.890248 -230.11765)
		(width 0.09525)
		(layer "In4.Cu")
		(net "M_J_CPU0_SA_DQS_DP<1>")
	)
	(segment
		(start 409.130246 -210.247992)
		(end 413.03956 -210.247992)
		(width 0.16002)
		(layer "In4.Cu")
		(net "M_J_CPU0_SA_DQS_DP<1>")
	)
	(segment
		(start 425.92752 -210.209892)
		(end 428.105824 -210.209892)
		(width 0.16002)
		(layer "In4.Cu")
		(net "M_J_CPU0_SA_DQS_DP<1>")
	)
	(segment
		(start 425.077636 -209.360008)
		(end 425.92752 -210.209892)
		(width 0.16002)
		(layer "In4.Cu")
		(net "M_J_CPU0_SA_DQS_DP<1>")
	)
	(segment
		(start 433.10429 -209.816446)
		(end 435.098698 -209.816446)
		(width 0.16002)
		(layer "In4.Cu")
		(net "M_J_CPU0_SA_DQS_DP<1>")
	)
	(segment
		(start 438.826402 -210.35899)
		(end 439.100214 -210.085178)
		(width 0.16002)
		(layer "In4.Cu")
		(net "M_J_CPU0_SA_DQS_DP<1>")
	)
	(segment
		(start 391.940796 -231.789986)
		(end 392.400536 -231.330246)
		(width 0.09525)
		(layer "In4.Cu")
		(net "M_J_CPU0_SA_DQS_DP<1>")
	)
	(segment
		(start 384.33502 -231.853994)
		(end 384.343402 -231.849168)
		(width 0.09525)
		(layer "In4.Cu")
		(net "M_J_CPU0_SA_DQS_DP<1>")
	)
	(segment
		(start 397.586962 -221.791276)
		(end 409.130246 -210.247992)
		(width 0.16002)
		(layer "In4.Cu")
		(net "M_J_CPU0_SA_DQS_DP<1>")
	)
	(segment
		(start 413.948118 -210.553046)
		(end 414.821878 -209.679286)
		(width 0.16002)
		(layer "In4.Cu")
		(net "M_J_CPU0_SA_DQS_DP<1>")
	)
	(segment
		(start 429.014382 -210.586066)
		(end 429.67402 -209.926428)
		(width 0.16002)
		(layer "In4.Cu")
		(net "M_J_CPU0_SA_DQS_DP<1>")
	)
	(segment
		(start 431.041302 -209.360008)
		(end 432.002184 -209.360008)
		(width 0.16002)
		(layer "In4.Cu")
		(net "M_J_CPU0_SA_DQS_DP<1>")
	)
	(segment
		(start 418.070538 -209.679286)
		(end 418.601144 -210.209892)
		(width 0.16002)
		(layer "In4.Cu")
		(net "M_J_CPU0_SA_DQS_DP<1>")
	)
	(segment
		(start 435.098698 -209.816446)
		(end 435.822598 -210.540346)
		(width 0.16002)
		(layer "In4.Cu")
		(net "M_J_CPU0_SA_DQS_DP<1>")
	)
	(segment
		(start 428.105824 -210.209892)
		(end 428.481998 -210.586066)
		(width 0.16002)
		(layer "In4.Cu")
		(net "M_J_CPU0_SA_DQS_DP<1>")
	)
	(segment
		(start 380.548642 -231.789478)
		(end 380.64948 -231.816148)
		(width 0.09525)
		(layer "In4.Cu")
		(net "M_J_CPU0_SA_DQS_DP<1>")
	)
	(segment
		(start 395.366748 -227.629466)
		(end 395.366748 -227.545646)
		(width 0.09525)
		(layer "In4.Cu")
		(net "M_J_CPU0_SA_DQS_DP<1>")
	)
	(segment
		(start 385.84632 -231.849168)
		(end 385.854702 -231.853994)
		(width 0.09525)
		(layer "In4.Cu")
		(net "M_J_CPU0_SA_DQS_DP<1>")
	)
	(segment
		(start 423.479976 -209.360008)
		(end 425.077636 -209.360008)
		(width 0.16002)
		(layer "In4.Cu")
		(net "M_J_CPU0_SA_DQS_DP<1>")
	)
	(segment
		(start 389.606282 -231.849168)
		(end 389.614664 -231.853994)
		(width 0.09525)
		(layer "In4.Cu")
		(net "M_J_CPU0_SA_DQS_DP<1>")
	)
	(segment
		(start 413.03956 -210.247992)
		(end 413.344614 -210.553046)
		(width 0.16002)
		(layer "In4.Cu")
		(net "M_J_CPU0_SA_DQS_DP<1>")
	)
	(segment
		(start 432.002184 -209.360008)
		(end 433.10429 -209.816446)
		(width 0.16002)
		(layer "In4.Cu")
		(net "M_J_CPU0_SA_DQS_DP<1>")
	)
	(segment
		(start 422.12387 -209.887566)
		(end 422.952418 -209.887566)
		(width 0.16002)
		(layer "In4.Cu")
		(net "M_J_CPU0_SA_DQS_DP<1>")
	)
	(segment
		(start 392.890248 -230.11765)
		(end 393.24788 -230.11765)
		(width 0.09525)
		(layer "In4.Cu")
		(net "M_J_CPU0_SA_DQS_DP<1>")
	)
	(segment
		(start 395.010386 -227.985828)
		(end 395.366748 -227.629466)
		(width 0.09525)
		(layer "In4.Cu")
		(net "M_J_CPU0_SA_DQS_DP<1>")
	)
	(segment
		(start 391.854944 -231.853994)
		(end 391.863326 -231.849168)
		(width 0.09525)
		(layer "In4.Cu")
		(net "M_J_CPU0_SA_DQS_DP<1>")
	)
	(segment
		(start 392.400536 -231.330246)
		(end 392.400536 -230.607362)
		(width 0.09525)
		(layer "In4.Cu")
		(net "M_J_CPU0_SA_DQS_DP<1>")
	)
	(segment
		(start 418.601144 -210.209892)
		(end 420.508684 -210.209892)
		(width 0.16002)
		(layer "In4.Cu")
		(net "M_J_CPU0_SA_DQS_DP<1>")
	)
	(segment
		(start 420.864538 -210.565746)
		(end 421.44569 -210.565746)
		(width 0.16002)
		(layer "In4.Cu")
		(net "M_J_CPU0_SA_DQS_DP<1>")
	)
	(segment
		(start 388.094982 -231.853994)
		(end 388.103364 -231.849168)
		(width 0.09525)
		(layer "In4.Cu")
		(net "M_J_CPU0_SA_DQS_DP<1>")
	)
	(segment
		(start 395.010386 -228.355144)
		(end 395.010386 -227.985828)
		(width 0.09525)
		(layer "In4.Cu")
		(net "M_J_CPU0_SA_DQS_DP<1>")
	)
	(segment
		(start 393.24788 -230.11765)
		(end 395.010386 -228.355144)
		(width 0.09525)
		(layer "In4.Cu")
		(net "M_J_CPU0_SA_DQS_DP<1>")
	)
	(segment
		(start 436.752238 -210.540346)
		(end 436.933594 -210.35899)
		(width 0.16002)
		(layer "In4.Cu")
		(net "M_J_CPU0_SA_DQS_DP<1>")
	)
	(segment
		(start 395.366748 -227.545646)
		(end 395.383512 -227.528882)
		(width 0.09525)
		(layer "In4.Cu")
		(net "M_J_CPU0_SA_DQS_DP<1>")
	)
	(segment
		(start 421.44569 -210.565746)
		(end 422.12387 -209.887566)
		(width 0.16002)
		(layer "In4.Cu")
		(net "M_J_CPU0_SA_DQS_DP<1>")
	)
	(segment
		(start 381.146304 -231.849168)
		(end 381.154686 -231.853994)
		(width 0.09525)
		(layer "In4.Cu")
		(net "M_J_CPU0_SA_DQS_DP<1>")
	)
	(segment
		(start 414.821878 -209.679286)
		(end 418.070538 -209.679286)
		(width 0.16002)
		(layer "In4.Cu")
		(net "M_J_CPU0_SA_DQS_DP<1>")
	)
	(segment
		(start 428.481998 -210.586066)
		(end 429.014382 -210.586066)
		(width 0.16002)
		(layer "In4.Cu")
		(net "M_J_CPU0_SA_DQS_DP<1>")
	)
	(segment
		(start 420.508684 -210.209892)
		(end 420.864538 -210.565746)
		(width 0.16002)
		(layer "In4.Cu")
		(net "M_J_CPU0_SA_DQS_DP<1>")
	)
	(segment
		(start 384.906266 -231.849168)
		(end 384.914648 -231.853994)
		(width 0.09525)
		(layer "In4.Cu")
		(net "M_J_CPU0_SA_DQS_DP<1>")
	)
	(segment
		(start 436.933594 -210.35899)
		(end 438.826402 -210.35899)
		(width 0.16002)
		(layer "In4.Cu")
		(net "M_J_CPU0_SA_DQS_DP<1>")
	)
	(segment
		(start 413.344614 -210.553046)
		(end 413.948118 -210.553046)
		(width 0.16002)
		(layer "In4.Cu")
		(net "M_J_CPU0_SA_DQS_DP<1>")
	)
	(arc
		(start 385.283456 -231.849168)
		(mid 385.564888 -231.773413)
		(end 385.84632 -231.849168)
		(width 0.09525)
		(layer "In4.Cu")
		(net "M_J_CPU0_SA_DQS_DP<1>")
	)
	(arc
		(start 383.026158 -231.849168)
		(mid 383.209933 -231.89994)
		(end 383.394966 -231.853994)
		(width 0.09525)
		(layer "In4.Cu")
		(net "M_J_CPU0_SA_DQS_DP<1>")
	)
	(arc
		(start 385.854702 -231.853994)
		(mid 386.039734 -231.899908)
		(end 386.22351 -231.849168)
		(width 0.09525)
		(layer "In4.Cu")
		(net "M_J_CPU0_SA_DQS_DP<1>")
	)
	(arc
		(start 383.966212 -231.849168)
		(mid 384.149987 -231.89994)
		(end 384.33502 -231.853994)
		(width 0.09525)
		(layer "In4.Cu")
		(net "M_J_CPU0_SA_DQS_DP<1>")
	)
	(arc
		(start 381.523494 -231.849168)
		(mid 381.804926 -231.773413)
		(end 382.086358 -231.849168)
		(width 0.09525)
		(layer "In4.Cu")
		(net "M_J_CPU0_SA_DQS_DP<1>")
	)
	(arc
		(start 391.863326 -231.849168)
		(mid 391.903998 -231.822111)
		(end 391.940796 -231.789986)
		(width 0.09525)
		(layer "In4.Cu")
		(net "M_J_CPU0_SA_DQS_DP<1>")
	)
	(arc
		(start 390.546336 -231.849168)
		(mid 390.734804 -231.899845)
		(end 390.923272 -231.849168)
		(width 0.09525)
		(layer "In4.Cu")
		(net "M_J_CPU0_SA_DQS_DP<1>")
	)
	(arc
		(start 388.103364 -231.849168)
		(mid 388.384796 -231.773413)
		(end 388.666228 -231.849168)
		(width 0.09525)
		(layer "In4.Cu")
		(net "M_J_CPU0_SA_DQS_DP<1>")
	)
	(arc
		(start 383.403348 -231.849168)
		(mid 383.68478 -231.773413)
		(end 383.966212 -231.849168)
		(width 0.09525)
		(layer "In4.Cu")
		(net "M_J_CPU0_SA_DQS_DP<1>")
	)
	(arc
		(start 386.786374 -231.849168)
		(mid 386.974842 -231.899845)
		(end 387.16331 -231.849168)
		(width 0.09525)
		(layer "In4.Cu")
		(net "M_J_CPU0_SA_DQS_DP<1>")
	)
	(arc
		(start 390.923272 -231.849168)
		(mid 391.204704 -231.773413)
		(end 391.486136 -231.849168)
		(width 0.09525)
		(layer "In4.Cu")
		(net "M_J_CPU0_SA_DQS_DP<1>")
	)
	(arc
		(start 382.463294 -231.849168)
		(mid 382.744726 -231.773413)
		(end 383.026158 -231.849168)
		(width 0.09525)
		(layer "In4.Cu")
		(net "M_J_CPU0_SA_DQS_DP<1>")
	)
	(arc
		(start 386.22351 -231.849168)
		(mid 386.504942 -231.773413)
		(end 386.786374 -231.849168)
		(width 0.09525)
		(layer "In4.Cu")
		(net "M_J_CPU0_SA_DQS_DP<1>")
	)
	(arc
		(start 389.983472 -231.849168)
		(mid 390.264904 -231.773413)
		(end 390.546336 -231.849168)
		(width 0.09525)
		(layer "In4.Cu")
		(net "M_J_CPU0_SA_DQS_DP<1>")
	)
	(arc
		(start 391.486136 -231.849168)
		(mid 391.669911 -231.89994)
		(end 391.854944 -231.853994)
		(width 0.09525)
		(layer "In4.Cu")
		(net "M_J_CPU0_SA_DQS_DP<1>")
	)
	(arc
		(start 380.64948 -231.816148)
		(mid 380.901764 -231.774454)
		(end 381.146304 -231.849168)
		(width 0.09525)
		(layer "In4.Cu")
		(net "M_J_CPU0_SA_DQS_DP<1>")
	)
	(arc
		(start 389.043418 -231.849168)
		(mid 389.32485 -231.773413)
		(end 389.606282 -231.849168)
		(width 0.09525)
		(layer "In4.Cu")
		(net "M_J_CPU0_SA_DQS_DP<1>")
	)
	(arc
		(start 384.914648 -231.853994)
		(mid 385.09968 -231.899908)
		(end 385.283456 -231.849168)
		(width 0.09525)
		(layer "In4.Cu")
		(net "M_J_CPU0_SA_DQS_DP<1>")
	)
	(arc
		(start 381.154686 -231.853994)
		(mid 381.339718 -231.899908)
		(end 381.523494 -231.849168)
		(width 0.09525)
		(layer "In4.Cu")
		(net "M_J_CPU0_SA_DQS_DP<1>")
	)
	(arc
		(start 387.16331 -231.849168)
		(mid 387.444742 -231.773413)
		(end 387.726174 -231.849168)
		(width 0.09525)
		(layer "In4.Cu")
		(net "M_J_CPU0_SA_DQS_DP<1>")
	)
	(arc
		(start 384.343402 -231.849168)
		(mid 384.624834 -231.773413)
		(end 384.906266 -231.849168)
		(width 0.09525)
		(layer "In4.Cu")
		(net "M_J_CPU0_SA_DQS_DP<1>")
	)
	(arc
		(start 389.614664 -231.853994)
		(mid 389.799696 -231.899908)
		(end 389.983472 -231.849168)
		(width 0.09525)
		(layer "In4.Cu")
		(net "M_J_CPU0_SA_DQS_DP<1>")
	)
	(arc
		(start 387.726174 -231.849168)
		(mid 387.909949 -231.89994)
		(end 388.094982 -231.853994)
		(width 0.09525)
		(layer "In4.Cu")
		(net "M_J_CPU0_SA_DQS_DP<1>")
	)
	(arc
		(start 388.666228 -231.849168)
		(mid 388.850003 -231.89994)
		(end 389.035036 -231.853994)
		(width 0.09525)
		(layer "In4.Cu")
		(net "M_J_CPU0_SA_DQS_DP<1>")
	)
	(arc
		(start 382.086358 -231.849168)
		(mid 382.274826 -231.899845)
		(end 382.463294 -231.849168)
		(width 0.09525)
		(layer "In4.Cu")
		(net "M_J_CPU0_SA_DQS_DP<1>")
	)
	(segment
		(start 379.927866 -226.930204)
		(end 380.394718 -226.664266)
		(width 0.12954)
		(layer "F.Cu")
		(net "M_J_CPU0_SA_DQS_DP<0>")
	)
	(segment
		(start 389.513318 -226.17938)
		(end 389.54583 -226.160584)
		(width 0.09525)
		(layer "In4.Cu")
		(net "M_J_CPU0_SA_DQS_DP<0>")
	)
	(segment
		(start 389.043418 -226.989386)
		(end 389.07593 -226.97059)
		(width 0.09525)
		(layer "In4.Cu")
		(net "M_J_CPU0_SA_DQS_DP<0>")
	)
	(segment
		(start 421.44569 -201.215752)
		(end 422.12387 -200.537572)
		(width 0.16002)
		(layer "In4.Cu")
		(net "M_J_CPU0_SA_DQS_DP<0>")
	)
	(segment
		(start 418.070538 -200.329292)
		(end 418.601144 -200.859898)
		(width 0.16002)
		(layer "In4.Cu")
		(net "M_J_CPU0_SA_DQS_DP<0>")
	)
	(segment
		(start 390.415272 -224.581466)
		(end 390.453372 -224.559368)
		(width 0.09525)
		(layer "In4.Cu")
		(net "M_J_CPU0_SA_DQS_DP<0>")
	)
	(segment
		(start 390.453372 -224.559368)
		(end 390.485884 -224.540572)
		(width 0.09525)
		(layer "In4.Cu")
		(net "M_J_CPU0_SA_DQS_DP<0>")
	)
	(segment
		(start 412.562548 -200.622662)
		(end 413.142938 -201.203052)
		(width 0.16002)
		(layer "In4.Cu")
		(net "M_J_CPU0_SA_DQS_DP<0>")
	)
	(segment
		(start 425.077636 -200.010014)
		(end 425.92752 -200.859898)
		(width 0.16002)
		(layer "In4.Cu")
		(net "M_J_CPU0_SA_DQS_DP<0>")
	)
	(segment
		(start 389.983472 -225.369374)
		(end 390.014968 -225.351086)
		(width 0.09525)
		(layer "In4.Cu")
		(net "M_J_CPU0_SA_DQS_DP<0>")
	)
	(segment
		(start 389.945372 -225.391472)
		(end 389.983472 -225.369374)
		(width 0.09525)
		(layer "In4.Cu")
		(net "M_J_CPU0_SA_DQS_DP<0>")
	)
	(segment
		(start 429.014382 -201.236072)
		(end 429.784002 -200.466452)
		(width 0.16002)
		(layer "In4.Cu")
		(net "M_J_CPU0_SA_DQS_DP<0>")
	)
	(segment
		(start 391.993882 -221.17431)
		(end 391.993882 -217.94216)
		(width 0.16002)
		(layer "In4.Cu")
		(net "M_J_CPU0_SA_DQS_DP<0>")
	)
	(segment
		(start 435.822598 -201.190352)
		(end 436.752238 -201.190352)
		(width 0.16002)
		(layer "In4.Cu")
		(net "M_J_CPU0_SA_DQS_DP<0>")
	)
	(segment
		(start 391.826496 -222.150686)
		(end 391.863072 -222.12935)
		(width 0.09525)
		(layer "In4.Cu")
		(net "M_J_CPU0_SA_DQS_DP<0>")
	)
	(segment
		(start 383.394966 -226.994212)
		(end 383.403348 -226.989386)
		(width 0.09525)
		(layer "In4.Cu")
		(net "M_J_CPU0_SA_DQS_DP<0>")
	)
	(segment
		(start 391.393426 -222.939356)
		(end 391.424922 -222.921068)
		(width 0.09525)
		(layer "In4.Cu")
		(net "M_J_CPU0_SA_DQS_DP<0>")
	)
	(segment
		(start 413.948118 -201.203052)
		(end 414.821878 -200.329292)
		(width 0.16002)
		(layer "In4.Cu")
		(net "M_J_CPU0_SA_DQS_DP<0>")
	)
	(segment
		(start 428.105824 -200.859898)
		(end 428.481998 -201.236072)
		(width 0.16002)
		(layer "In4.Cu")
		(net "M_J_CPU0_SA_DQS_DP<0>")
	)
	(segment
		(start 435.098698 -200.466452)
		(end 435.822598 -201.190352)
		(width 0.16002)
		(layer "In4.Cu")
		(net "M_J_CPU0_SA_DQS_DP<0>")
	)
	(segment
		(start 391.863072 -222.12935)
		(end 391.896854 -222.109792)
		(width 0.09525)
		(layer "In4.Cu")
		(net "M_J_CPU0_SA_DQS_DP<0>")
	)
	(segment
		(start 389.478266 -226.199954)
		(end 389.513318 -226.17938)
		(width 0.09525)
		(layer "In4.Cu")
		(net "M_J_CPU0_SA_DQS_DP<0>")
	)
	(segment
		(start 430.492916 -200.466452)
		(end 430.949354 -200.010014)
		(width 0.16002)
		(layer "In4.Cu")
		(net "M_J_CPU0_SA_DQS_DP<0>")
	)
	(segment
		(start 380.394718 -226.664266)
		(end 380.548642 -226.929696)
		(width 0.09525)
		(layer "In4.Cu")
		(net "M_J_CPU0_SA_DQS_DP<0>")
	)
	(segment
		(start 436.752238 -201.190352)
		(end 436.933594 -201.008996)
		(width 0.16002)
		(layer "In4.Cu")
		(net "M_J_CPU0_SA_DQS_DP<0>")
	)
	(segment
		(start 390.923272 -223.749362)
		(end 390.955784 -223.730566)
		(width 0.09525)
		(layer "In4.Cu")
		(net "M_J_CPU0_SA_DQS_DP<0>")
	)
	(segment
		(start 391.993882 -221.197932)
		(end 391.993882 -221.17431)
		(width 0.09525)
		(layer "In4.Cu")
		(net "M_J_CPU0_SA_DQS_DP<0>")
	)
	(segment
		(start 388.094982 -226.994212)
		(end 388.103364 -226.989386)
		(width 0.09525)
		(layer "In4.Cu")
		(net "M_J_CPU0_SA_DQS_DP<0>")
	)
	(segment
		(start 409.31338 -200.622662)
		(end 412.562548 -200.622662)
		(width 0.16002)
		(layer "In4.Cu")
		(net "M_J_CPU0_SA_DQS_DP<0>")
	)
	(segment
		(start 429.784002 -200.466452)
		(end 430.492916 -200.466452)
		(width 0.16002)
		(layer "In4.Cu")
		(net "M_J_CPU0_SA_DQS_DP<0>")
	)
	(segment
		(start 380.548642 -226.929696)
		(end 380.64948 -226.956366)
		(width 0.09525)
		(layer "In4.Cu")
		(net "M_J_CPU0_SA_DQS_DP<0>")
	)
	(segment
		(start 381.146304 -226.989386)
		(end 381.154686 -226.994212)
		(width 0.09525)
		(layer "In4.Cu")
		(net "M_J_CPU0_SA_DQS_DP<0>")
	)
	(segment
		(start 391.993882 -217.94216)
		(end 409.31338 -200.622662)
		(width 0.16002)
		(layer "In4.Cu")
		(net "M_J_CPU0_SA_DQS_DP<0>")
	)
	(segment
		(start 418.601144 -200.859898)
		(end 420.508684 -200.859898)
		(width 0.16002)
		(layer "In4.Cu")
		(net "M_J_CPU0_SA_DQS_DP<0>")
	)
	(segment
		(start 430.949354 -200.010014)
		(end 432.562762 -200.010014)
		(width 0.16002)
		(layer "In4.Cu")
		(net "M_J_CPU0_SA_DQS_DP<0>")
	)
	(segment
		(start 433.0192 -200.466452)
		(end 435.098698 -200.466452)
		(width 0.16002)
		(layer "In4.Cu")
		(net "M_J_CPU0_SA_DQS_DP<0>")
	)
	(segment
		(start 438.826402 -201.008996)
		(end 439.100214 -200.735184)
		(width 0.16002)
		(layer "In4.Cu")
		(net "M_J_CPU0_SA_DQS_DP<0>")
	)
	(segment
		(start 384.33502 -226.994212)
		(end 384.343402 -226.989386)
		(width 0.09525)
		(layer "In4.Cu")
		(net "M_J_CPU0_SA_DQS_DP<0>")
	)
	(segment
		(start 425.92752 -200.859898)
		(end 428.105824 -200.859898)
		(width 0.16002)
		(layer "In4.Cu")
		(net "M_J_CPU0_SA_DQS_DP<0>")
	)
	(segment
		(start 428.481998 -201.236072)
		(end 429.014382 -201.236072)
		(width 0.16002)
		(layer "In4.Cu")
		(net "M_J_CPU0_SA_DQS_DP<0>")
	)
	(segment
		(start 391.355326 -222.961454)
		(end 391.393426 -222.939356)
		(width 0.09525)
		(layer "In4.Cu")
		(net "M_J_CPU0_SA_DQS_DP<0>")
	)
	(segment
		(start 389.035036 -226.994212)
		(end 389.043418 -226.989386)
		(width 0.09525)
		(layer "In4.Cu")
		(net "M_J_CPU0_SA_DQS_DP<0>")
	)
	(segment
		(start 392.052302 -221.256352)
		(end 391.993882 -221.197932)
		(width 0.09525)
		(layer "In4.Cu")
		(net "M_J_CPU0_SA_DQS_DP<0>")
	)
	(segment
		(start 413.142938 -201.203052)
		(end 413.948118 -201.203052)
		(width 0.16002)
		(layer "In4.Cu")
		(net "M_J_CPU0_SA_DQS_DP<0>")
	)
	(segment
		(start 422.952418 -200.537572)
		(end 423.479976 -200.010014)
		(width 0.16002)
		(layer "In4.Cu")
		(net "M_J_CPU0_SA_DQS_DP<0>")
	)
	(segment
		(start 390.88822 -223.769936)
		(end 390.923272 -223.749362)
		(width 0.09525)
		(layer "In4.Cu")
		(net "M_J_CPU0_SA_DQS_DP<0>")
	)
	(segment
		(start 420.864538 -201.215752)
		(end 421.44569 -201.215752)
		(width 0.16002)
		(layer "In4.Cu")
		(net "M_J_CPU0_SA_DQS_DP<0>")
	)
	(segment
		(start 422.12387 -200.537572)
		(end 422.952418 -200.537572)
		(width 0.16002)
		(layer "In4.Cu")
		(net "M_J_CPU0_SA_DQS_DP<0>")
	)
	(segment
		(start 432.562762 -200.010014)
		(end 433.0192 -200.466452)
		(width 0.16002)
		(layer "In4.Cu")
		(net "M_J_CPU0_SA_DQS_DP<0>")
	)
	(segment
		(start 420.508684 -200.859898)
		(end 420.864538 -201.215752)
		(width 0.16002)
		(layer "In4.Cu")
		(net "M_J_CPU0_SA_DQS_DP<0>")
	)
	(segment
		(start 423.479976 -200.010014)
		(end 425.077636 -200.010014)
		(width 0.16002)
		(layer "In4.Cu")
		(net "M_J_CPU0_SA_DQS_DP<0>")
	)
	(segment
		(start 436.933594 -201.008996)
		(end 438.826402 -201.008996)
		(width 0.16002)
		(layer "In4.Cu")
		(net "M_J_CPU0_SA_DQS_DP<0>")
	)
	(segment
		(start 384.906266 -226.989386)
		(end 384.914648 -226.994212)
		(width 0.09525)
		(layer "In4.Cu")
		(net "M_J_CPU0_SA_DQS_DP<0>")
	)
	(segment
		(start 392.052302 -221.80423)
		(end 392.052302 -221.256352)
		(width 0.09525)
		(layer "In4.Cu")
		(net "M_J_CPU0_SA_DQS_DP<0>")
	)
	(segment
		(start 385.84632 -226.989386)
		(end 385.854702 -226.994212)
		(width 0.09525)
		(layer "In4.Cu")
		(net "M_J_CPU0_SA_DQS_DP<0>")
	)
	(segment
		(start 414.821878 -200.329292)
		(end 418.070538 -200.329292)
		(width 0.16002)
		(layer "In4.Cu")
		(net "M_J_CPU0_SA_DQS_DP<0>")
	)
	(arc
		(start 385.283456 -226.989386)
		(mid 385.564888 -226.913631)
		(end 385.84632 -226.989386)
		(width 0.09525)
		(layer "In4.Cu")
		(net "M_J_CPU0_SA_DQS_DP<0>")
	)
	(arc
		(start 391.896854 -222.109792)
		(mid 392.011233 -221.975653)
		(end 392.052302 -221.80423)
		(width 0.09525)
		(layer "In4.Cu")
		(net "M_J_CPU0_SA_DQS_DP<0>")
	)
	(arc
		(start 380.64948 -226.956366)
		(mid 380.901764 -226.914672)
		(end 381.146304 -226.989386)
		(width 0.09525)
		(layer "In4.Cu")
		(net "M_J_CPU0_SA_DQS_DP<0>")
	)
	(arc
		(start 391.112502 -223.424242)
		(mid 391.176899 -223.162936)
		(end 391.355326 -222.961454)
		(width 0.09525)
		(layer "In4.Cu")
		(net "M_J_CPU0_SA_DQS_DP<0>")
	)
	(arc
		(start 388.103364 -226.989386)
		(mid 388.384796 -226.913631)
		(end 388.666228 -226.989386)
		(width 0.09525)
		(layer "In4.Cu")
		(net "M_J_CPU0_SA_DQS_DP<0>")
	)
	(arc
		(start 383.026158 -226.989386)
		(mid 383.209933 -227.040158)
		(end 383.394966 -226.994212)
		(width 0.09525)
		(layer "In4.Cu")
		(net "M_J_CPU0_SA_DQS_DP<0>")
	)
	(arc
		(start 384.343402 -226.989386)
		(mid 384.624834 -226.913631)
		(end 384.906266 -226.989386)
		(width 0.09525)
		(layer "In4.Cu")
		(net "M_J_CPU0_SA_DQS_DP<0>")
	)
	(arc
		(start 384.914648 -226.994212)
		(mid 385.09968 -227.040126)
		(end 385.283456 -226.989386)
		(width 0.09525)
		(layer "In4.Cu")
		(net "M_J_CPU0_SA_DQS_DP<0>")
	)
	(arc
		(start 390.014968 -225.351086)
		(mid 390.130766 -225.216692)
		(end 390.172448 -225.044254)
		(width 0.09525)
		(layer "In4.Cu")
		(net "M_J_CPU0_SA_DQS_DP<0>")
	)
	(arc
		(start 390.955784 -223.730566)
		(mid 391.071058 -223.596288)
		(end 391.112502 -223.424242)
		(width 0.09525)
		(layer "In4.Cu")
		(net "M_J_CPU0_SA_DQS_DP<0>")
	)
	(arc
		(start 382.463294 -226.989386)
		(mid 382.744726 -226.913631)
		(end 383.026158 -226.989386)
		(width 0.09525)
		(layer "In4.Cu")
		(net "M_J_CPU0_SA_DQS_DP<0>")
	)
	(arc
		(start 390.642602 -224.234248)
		(mid 390.707849 -223.971645)
		(end 390.88822 -223.769936)
		(width 0.09525)
		(layer "In4.Cu")
		(net "M_J_CPU0_SA_DQS_DP<0>")
	)
	(arc
		(start 389.702548 -225.85426)
		(mid 389.766945 -225.592954)
		(end 389.945372 -225.391472)
		(width 0.09525)
		(layer "In4.Cu")
		(net "M_J_CPU0_SA_DQS_DP<0>")
	)
	(arc
		(start 381.523494 -226.989386)
		(mid 381.804926 -226.913631)
		(end 382.086358 -226.989386)
		(width 0.09525)
		(layer "In4.Cu")
		(net "M_J_CPU0_SA_DQS_DP<0>")
	)
	(arc
		(start 390.485884 -224.540572)
		(mid 390.601158 -224.406294)
		(end 390.642602 -224.234248)
		(width 0.09525)
		(layer "In4.Cu")
		(net "M_J_CPU0_SA_DQS_DP<0>")
	)
	(arc
		(start 389.54583 -226.160584)
		(mid 389.661104 -226.026306)
		(end 389.702548 -225.85426)
		(width 0.09525)
		(layer "In4.Cu")
		(net "M_J_CPU0_SA_DQS_DP<0>")
	)
	(arc
		(start 391.582402 -222.614236)
		(mid 391.647162 -222.352301)
		(end 391.826496 -222.150686)
		(width 0.09525)
		(layer "In4.Cu")
		(net "M_J_CPU0_SA_DQS_DP<0>")
	)
	(arc
		(start 381.154686 -226.994212)
		(mid 381.339718 -227.040126)
		(end 381.523494 -226.989386)
		(width 0.09525)
		(layer "In4.Cu")
		(net "M_J_CPU0_SA_DQS_DP<0>")
	)
	(arc
		(start 387.726174 -226.989386)
		(mid 387.909949 -227.040158)
		(end 388.094982 -226.994212)
		(width 0.09525)
		(layer "In4.Cu")
		(net "M_J_CPU0_SA_DQS_DP<0>")
	)
	(arc
		(start 385.854702 -226.994212)
		(mid 386.039734 -227.040126)
		(end 386.22351 -226.989386)
		(width 0.09525)
		(layer "In4.Cu")
		(net "M_J_CPU0_SA_DQS_DP<0>")
	)
	(arc
		(start 391.424922 -222.921068)
		(mid 391.54072 -222.786674)
		(end 391.582402 -222.614236)
		(width 0.09525)
		(layer "In4.Cu")
		(net "M_J_CPU0_SA_DQS_DP<0>")
	)
	(arc
		(start 383.966212 -226.989386)
		(mid 384.149987 -227.040158)
		(end 384.33502 -226.994212)
		(width 0.09525)
		(layer "In4.Cu")
		(net "M_J_CPU0_SA_DQS_DP<0>")
	)
	(arc
		(start 390.172448 -225.044254)
		(mid 390.236845 -224.782948)
		(end 390.415272 -224.581466)
		(width 0.09525)
		(layer "In4.Cu")
		(net "M_J_CPU0_SA_DQS_DP<0>")
	)
	(arc
		(start 386.786374 -226.989386)
		(mid 386.974842 -227.040063)
		(end 387.16331 -226.989386)
		(width 0.09525)
		(layer "In4.Cu")
		(net "M_J_CPU0_SA_DQS_DP<0>")
	)
	(arc
		(start 389.07593 -226.97059)
		(mid 389.191204 -226.836312)
		(end 389.232648 -226.664266)
		(width 0.09525)
		(layer "In4.Cu")
		(net "M_J_CPU0_SA_DQS_DP<0>")
	)
	(arc
		(start 389.232648 -226.664266)
		(mid 389.297895 -226.401663)
		(end 389.478266 -226.199954)
		(width 0.09525)
		(layer "In4.Cu")
		(net "M_J_CPU0_SA_DQS_DP<0>")
	)
	(arc
		(start 386.22351 -226.989386)
		(mid 386.504942 -226.913631)
		(end 386.786374 -226.989386)
		(width 0.09525)
		(layer "In4.Cu")
		(net "M_J_CPU0_SA_DQS_DP<0>")
	)
	(arc
		(start 383.403348 -226.989386)
		(mid 383.68478 -226.913631)
		(end 383.966212 -226.989386)
		(width 0.09525)
		(layer "In4.Cu")
		(net "M_J_CPU0_SA_DQS_DP<0>")
	)
	(arc
		(start 388.666228 -226.989386)
		(mid 388.850003 -227.040158)
		(end 389.035036 -226.994212)
		(width 0.09525)
		(layer "In4.Cu")
		(net "M_J_CPU0_SA_DQS_DP<0>")
	)
	(arc
		(start 387.16331 -226.989386)
		(mid 387.444742 -226.913631)
		(end 387.726174 -226.989386)
		(width 0.09525)
		(layer "In4.Cu")
		(net "M_J_CPU0_SA_DQS_DP<0>")
	)
	(arc
		(start 382.086358 -226.989386)
		(mid 382.274826 -227.040063)
		(end 382.463294 -226.989386)
		(width 0.09525)
		(layer "In4.Cu")
		(net "M_J_CPU0_SA_DQS_DP<0>")
	)
	(segment
		(start 378.517912 -247.1801)
		(end 378.984764 -246.914162)
		(width 0.12954)
		(layer "F.Cu")
		(net "M_J_CPU0_SA_DQS_DN<9>")
	)
	(segment
		(start 383.504694 -247.244108)
		(end 383.496312 -247.239282)
		(width 0.09525)
		(layer "In4.Cu")
		(net "M_J_CPU0_SA_DQS_DN<9>")
	)
	(segment
		(start 405.21382 -245.540276)
		(end 405.21382 -246.06758)
		(width 0.16002)
		(layer "In4.Cu")
		(net "M_J_CPU0_SA_DQS_DN<9>")
	)
	(segment
		(start 435.000146 -238.985044)
		(end 434.726334 -239.258856)
		(width 0.16002)
		(layer "In4.Cu")
		(net "M_J_CPU0_SA_DQS_DN<9>")
	)
	(segment
		(start 432.070256 -239.258856)
		(end 431.921158 -239.407954)
		(width 0.16002)
		(layer "In4.Cu")
		(net "M_J_CPU0_SA_DQS_DN<9>")
	)
	(segment
		(start 405.40178 -246.25554)
		(end 405.40178 -246.5324)
		(width 0.16002)
		(layer "In4.Cu")
		(net "M_J_CPU0_SA_DQS_DN<9>")
	)
	(segment
		(start 431.083466 -239.407954)
		(end 430.73828 -239.062768)
		(width 0.16002)
		(layer "In4.Cu")
		(net "M_J_CPU0_SA_DQS_DN<9>")
	)
	(segment
		(start 387.264656 -247.244108)
		(end 387.256274 -247.239282)
		(width 0.09525)
		(layer "In4.Cu")
		(net "M_J_CPU0_SA_DQS_DN<9>")
	)
	(segment
		(start 405.40178 -246.5324)
		(end 405.131778 -246.802402)
		(width 0.16002)
		(layer "In4.Cu")
		(net "M_J_CPU0_SA_DQS_DN<9>")
	)
	(segment
		(start 409.049982 -242.607338)
		(end 408.862022 -242.419378)
		(width 0.16002)
		(layer "In4.Cu")
		(net "M_J_CPU0_SA_DQS_DN<9>")
	)
	(segment
		(start 423.514266 -239.407954)
		(end 423.1767 -239.070388)
		(width 0.16002)
		(layer "In4.Cu")
		(net "M_J_CPU0_SA_DQS_DN<9>")
	)
	(segment
		(start 379.239526 -247.206262)
		(end 379.138688 -247.179592)
		(width 0.09525)
		(layer "In4.Cu")
		(net "M_J_CPU0_SA_DQS_DN<9>")
	)
	(segment
		(start 422.227756 -239.070388)
		(end 421.379396 -239.918748)
		(width 0.16002)
		(layer "In4.Cu")
		(net "M_J_CPU0_SA_DQS_DN<9>")
	)
	(segment
		(start 408.334718 -242.419378)
		(end 407.961084 -242.793012)
		(width 0.16002)
		(layer "In4.Cu")
		(net "M_J_CPU0_SA_DQS_DN<9>")
	)
	(segment
		(start 405.21382 -246.06758)
		(end 405.40178 -246.25554)
		(width 0.16002)
		(layer "In4.Cu")
		(net "M_J_CPU0_SA_DQS_DN<9>")
	)
	(segment
		(start 407.961084 -243.320316)
		(end 408.149044 -243.508276)
		(width 0.16002)
		(layer "In4.Cu")
		(net "M_J_CPU0_SA_DQS_DN<9>")
	)
	(segment
		(start 421.379396 -239.918748)
		(end 420.711376 -239.918748)
		(width 0.16002)
		(layer "In4.Cu")
		(net "M_J_CPU0_SA_DQS_DN<9>")
	)
	(segment
		(start 390.453372 -247.239282)
		(end 390.44499 -247.244108)
		(width 0.09525)
		(layer "In4.Cu")
		(net "M_J_CPU0_SA_DQS_DN<9>")
	)
	(segment
		(start 395.835632 -246.802402)
		(end 395.77645 -246.861584)
		(width 0.09525)
		(layer "In4.Cu")
		(net "M_J_CPU0_SA_DQS_DN<9>")
	)
	(segment
		(start 409.326842 -242.607338)
		(end 409.049982 -242.607338)
		(width 0.16002)
		(layer "In4.Cu")
		(net "M_J_CPU0_SA_DQS_DN<9>")
	)
	(segment
		(start 379.138688 -247.179592)
		(end 378.984764 -246.914162)
		(width 0.09525)
		(layer "In4.Cu")
		(net "M_J_CPU0_SA_DQS_DN<9>")
	)
	(segment
		(start 419.101524 -240.258092)
		(end 417.938204 -239.094772)
		(width 0.16002)
		(layer "In4.Cu")
		(net "M_J_CPU0_SA_DQS_DN<9>")
	)
	(segment
		(start 426.941488 -240.258092)
		(end 426.09135 -239.407954)
		(width 0.16002)
		(layer "In4.Cu")
		(net "M_J_CPU0_SA_DQS_DN<9>")
	)
	(segment
		(start 407.95321 -243.98097)
		(end 407.67635 -243.98097)
		(width 0.16002)
		(layer "In4.Cu")
		(net "M_J_CPU0_SA_DQS_DN<9>")
	)
	(segment
		(start 430.73828 -239.062768)
		(end 429.836072 -239.062768)
		(width 0.16002)
		(layer "In4.Cu")
		(net "M_J_CPU0_SA_DQS_DN<9>")
	)
	(segment
		(start 394.80236 -247.42521)
		(end 394.050266 -247.42521)
		(width 0.09525)
		(layer "In4.Cu")
		(net "M_J_CPU0_SA_DQS_DN<9>")
	)
	(segment
		(start 406.302718 -245.354602)
		(end 406.114758 -245.166642)
		(width 0.16002)
		(layer "In4.Cu")
		(net "M_J_CPU0_SA_DQS_DN<9>")
	)
	(segment
		(start 395.859254 -246.802402)
		(end 395.835632 -246.802402)
		(width 0.09525)
		(layer "In4.Cu")
		(net "M_J_CPU0_SA_DQS_DN<9>")
	)
	(segment
		(start 394.050266 -247.42521)
		(end 393.952476 -247.32742)
		(width 0.09525)
		(layer "In4.Cu")
		(net "M_J_CPU0_SA_DQS_DN<9>")
	)
	(segment
		(start 407.48839 -243.79301)
		(end 406.961086 -243.79301)
		(width 0.16002)
		(layer "In4.Cu")
		(net "M_J_CPU0_SA_DQS_DN<9>")
	)
	(segment
		(start 406.587452 -244.166644)
		(end 406.587452 -244.693948)
		(width 0.16002)
		(layer "In4.Cu")
		(net "M_J_CPU0_SA_DQS_DN<9>")
	)
	(segment
		(start 405.131778 -246.802402)
		(end 395.859254 -246.802402)
		(width 0.16002)
		(layer "In4.Cu")
		(net "M_J_CPU0_SA_DQS_DN<9>")
	)
	(segment
		(start 406.579578 -245.354602)
		(end 406.302718 -245.354602)
		(width 0.16002)
		(layer "In4.Cu")
		(net "M_J_CPU0_SA_DQS_DN<9>")
	)
	(segment
		(start 392.911076 -247.247664)
		(end 392.896598 -247.239282)
		(width 0.09525)
		(layer "In4.Cu")
		(net "M_J_CPU0_SA_DQS_DN<9>")
	)
	(segment
		(start 381.05334 -247.239282)
		(end 381.044958 -247.244108)
		(width 0.09525)
		(layer "In4.Cu")
		(net "M_J_CPU0_SA_DQS_DN<9>")
	)
	(segment
		(start 392.334242 -247.239282)
		(end 392.322304 -247.24614)
		(width 0.09525)
		(layer "In4.Cu")
		(net "M_J_CPU0_SA_DQS_DN<9>")
	)
	(segment
		(start 408.149044 -243.508276)
		(end 408.149044 -243.785136)
		(width 0.16002)
		(layer "In4.Cu")
		(net "M_J_CPU0_SA_DQS_DN<9>")
	)
	(segment
		(start 407.961084 -242.793012)
		(end 407.961084 -243.320316)
		(width 0.16002)
		(layer "In4.Cu")
		(net "M_J_CPU0_SA_DQS_DN<9>")
	)
	(segment
		(start 429.002952 -239.895888)
		(end 428.430436 -239.895888)
		(width 0.16002)
		(layer "In4.Cu")
		(net "M_J_CPU0_SA_DQS_DN<9>")
	)
	(segment
		(start 391.408158 -247.230646)
		(end 391.393426 -247.239282)
		(width 0.09525)
		(layer "In4.Cu")
		(net "M_J_CPU0_SA_DQS_DN<9>")
	)
	(segment
		(start 423.1767 -239.070388)
		(end 422.227756 -239.070388)
		(width 0.16002)
		(layer "In4.Cu")
		(net "M_J_CPU0_SA_DQS_DN<9>")
	)
	(segment
		(start 386.69341 -247.239282)
		(end 386.685028 -247.244108)
		(width 0.09525)
		(layer "In4.Cu")
		(net "M_J_CPU0_SA_DQS_DN<9>")
	)
	(segment
		(start 412.076392 -239.857788)
		(end 409.326842 -242.607338)
		(width 0.16002)
		(layer "In4.Cu")
		(net "M_J_CPU0_SA_DQS_DN<9>")
	)
	(segment
		(start 406.775412 -244.881908)
		(end 406.775412 -245.158768)
		(width 0.16002)
		(layer "In4.Cu")
		(net "M_J_CPU0_SA_DQS_DN<9>")
	)
	(segment
		(start 406.587452 -244.693948)
		(end 406.775412 -244.881908)
		(width 0.16002)
		(layer "In4.Cu")
		(net "M_J_CPU0_SA_DQS_DN<9>")
	)
	(segment
		(start 388.20471 -247.244108)
		(end 388.196328 -247.239282)
		(width 0.09525)
		(layer "In4.Cu")
		(net "M_J_CPU0_SA_DQS_DN<9>")
	)
	(segment
		(start 405.587454 -245.166642)
		(end 405.21382 -245.540276)
		(width 0.16002)
		(layer "In4.Cu")
		(net "M_J_CPU0_SA_DQS_DN<9>")
	)
	(segment
		(start 406.775412 -245.158768)
		(end 406.579578 -245.354602)
		(width 0.16002)
		(layer "In4.Cu")
		(net "M_J_CPU0_SA_DQS_DN<9>")
	)
	(segment
		(start 395.365986 -246.861584)
		(end 394.80236 -247.42521)
		(width 0.09525)
		(layer "In4.Cu")
		(net "M_J_CPU0_SA_DQS_DN<9>")
	)
	(segment
		(start 413.980376 -239.857788)
		(end 412.076392 -239.857788)
		(width 0.16002)
		(layer "In4.Cu")
		(net "M_J_CPU0_SA_DQS_DN<9>")
	)
	(segment
		(start 408.862022 -242.419378)
		(end 408.334718 -242.419378)
		(width 0.16002)
		(layer "In4.Cu")
		(net "M_J_CPU0_SA_DQS_DN<9>")
	)
	(segment
		(start 385.753356 -247.239282)
		(end 385.744974 -247.244108)
		(width 0.09525)
		(layer "In4.Cu")
		(net "M_J_CPU0_SA_DQS_DN<9>")
	)
	(segment
		(start 431.921158 -239.407954)
		(end 431.083466 -239.407954)
		(width 0.16002)
		(layer "In4.Cu")
		(net "M_J_CPU0_SA_DQS_DN<9>")
	)
	(segment
		(start 428.068232 -240.258092)
		(end 426.941488 -240.258092)
		(width 0.16002)
		(layer "In4.Cu")
		(net "M_J_CPU0_SA_DQS_DN<9>")
	)
	(segment
		(start 434.726334 -239.258856)
		(end 432.070256 -239.258856)
		(width 0.16002)
		(layer "In4.Cu")
		(net "M_J_CPU0_SA_DQS_DN<9>")
	)
	(segment
		(start 420.372032 -240.258092)
		(end 419.101524 -240.258092)
		(width 0.16002)
		(layer "In4.Cu")
		(net "M_J_CPU0_SA_DQS_DN<9>")
	)
	(segment
		(start 417.938204 -239.094772)
		(end 414.743392 -239.094772)
		(width 0.16002)
		(layer "In4.Cu")
		(net "M_J_CPU0_SA_DQS_DN<9>")
	)
	(segment
		(start 395.77645 -246.861584)
		(end 395.365986 -246.861584)
		(width 0.09525)
		(layer "In4.Cu")
		(net "M_J_CPU0_SA_DQS_DN<9>")
	)
	(segment
		(start 392.896598 -247.239282)
		(end 392.881866 -247.230646)
		(width 0.09525)
		(layer "In4.Cu")
		(net "M_J_CPU0_SA_DQS_DN<9>")
	)
	(segment
		(start 408.149044 -243.785136)
		(end 407.95321 -243.98097)
		(width 0.16002)
		(layer "In4.Cu")
		(net "M_J_CPU0_SA_DQS_DN<9>")
	)
	(segment
		(start 428.430436 -239.895888)
		(end 428.068232 -240.258092)
		(width 0.16002)
		(layer "In4.Cu")
		(net "M_J_CPU0_SA_DQS_DN<9>")
	)
	(segment
		(start 407.67635 -243.98097)
		(end 407.48839 -243.79301)
		(width 0.16002)
		(layer "In4.Cu")
		(net "M_J_CPU0_SA_DQS_DN<9>")
	)
	(segment
		(start 406.961086 -243.79301)
		(end 406.587452 -244.166644)
		(width 0.16002)
		(layer "In4.Cu")
		(net "M_J_CPU0_SA_DQS_DN<9>")
	)
	(segment
		(start 391.024618 -247.244108)
		(end 391.016236 -247.239282)
		(width 0.09525)
		(layer "In4.Cu")
		(net "M_J_CPU0_SA_DQS_DN<9>")
	)
	(segment
		(start 382.56464 -247.244108)
		(end 382.556258 -247.239282)
		(width 0.09525)
		(layer "In4.Cu")
		(net "M_J_CPU0_SA_DQS_DN<9>")
	)
	(segment
		(start 426.09135 -239.407954)
		(end 423.514266 -239.407954)
		(width 0.16002)
		(layer "In4.Cu")
		(net "M_J_CPU0_SA_DQS_DN<9>")
	)
	(segment
		(start 429.836072 -239.062768)
		(end 429.002952 -239.895888)
		(width 0.16002)
		(layer "In4.Cu")
		(net "M_J_CPU0_SA_DQS_DN<9>")
	)
	(segment
		(start 414.743392 -239.094772)
		(end 413.980376 -239.857788)
		(width 0.16002)
		(layer "In4.Cu")
		(net "M_J_CPU0_SA_DQS_DN<9>")
	)
	(segment
		(start 420.711376 -239.918748)
		(end 420.372032 -240.258092)
		(width 0.16002)
		(layer "In4.Cu")
		(net "M_J_CPU0_SA_DQS_DN<9>")
	)
	(segment
		(start 406.114758 -245.166642)
		(end 405.587454 -245.166642)
		(width 0.16002)
		(layer "In4.Cu")
		(net "M_J_CPU0_SA_DQS_DN<9>")
	)
	(segment
		(start 381.993394 -247.239282)
		(end 381.985012 -247.244108)
		(width 0.09525)
		(layer "In4.Cu")
		(net "M_J_CPU0_SA_DQS_DN<9>")
	)
	(arc
		(start 393.952476 -247.32742)
		(mid 393.892001 -247.275113)
		(end 393.824714 -247.231916)
		(width 0.09525)
		(layer "In4.Cu")
		(net "M_J_CPU0_SA_DQS_DN<9>")
	)
	(arc
		(start 393.273788 -247.239282)
		(mid 393.093509 -247.290113)
		(end 392.911076 -247.247664)
		(width 0.09525)
		(layer "In4.Cu")
		(net "M_J_CPU0_SA_DQS_DN<9>")
	)
	(arc
		(start 387.256274 -247.239282)
		(mid 386.974842 -247.163527)
		(end 386.69341 -247.239282)
		(width 0.09525)
		(layer "In4.Cu")
		(net "M_J_CPU0_SA_DQS_DN<9>")
	)
	(arc
		(start 384.813302 -247.239282)
		(mid 384.624834 -247.289959)
		(end 384.436366 -247.239282)
		(width 0.09525)
		(layer "In4.Cu")
		(net "M_J_CPU0_SA_DQS_DN<9>")
	)
	(arc
		(start 388.573518 -247.239282)
		(mid 388.389743 -247.290054)
		(end 388.20471 -247.244108)
		(width 0.09525)
		(layer "In4.Cu")
		(net "M_J_CPU0_SA_DQS_DN<9>")
	)
	(arc
		(start 381.616204 -247.239282)
		(mid 381.334772 -247.163527)
		(end 381.05334 -247.239282)
		(width 0.09525)
		(layer "In4.Cu")
		(net "M_J_CPU0_SA_DQS_DN<9>")
	)
	(arc
		(start 380.67615 -247.239282)
		(mid 380.394718 -247.163527)
		(end 380.113286 -247.239282)
		(width 0.09525)
		(layer "In4.Cu")
		(net "M_J_CPU0_SA_DQS_DN<9>")
	)
	(arc
		(start 385.744974 -247.244108)
		(mid 385.559942 -247.290022)
		(end 385.376166 -247.239282)
		(width 0.09525)
		(layer "In4.Cu")
		(net "M_J_CPU0_SA_DQS_DN<9>")
	)
	(arc
		(start 391.393426 -247.239282)
		(mid 391.209651 -247.290054)
		(end 391.024618 -247.244108)
		(width 0.09525)
		(layer "In4.Cu")
		(net "M_J_CPU0_SA_DQS_DN<9>")
	)
	(arc
		(start 382.933448 -247.239282)
		(mid 382.749673 -247.290054)
		(end 382.56464 -247.244108)
		(width 0.09525)
		(layer "In4.Cu")
		(net "M_J_CPU0_SA_DQS_DN<9>")
	)
	(arc
		(start 388.196328 -247.239282)
		(mid 387.914896 -247.163527)
		(end 387.633464 -247.239282)
		(width 0.09525)
		(layer "In4.Cu")
		(net "M_J_CPU0_SA_DQS_DN<9>")
	)
	(arc
		(start 384.436366 -247.239282)
		(mid 384.154934 -247.163527)
		(end 383.873502 -247.239282)
		(width 0.09525)
		(layer "In4.Cu")
		(net "M_J_CPU0_SA_DQS_DN<9>")
	)
	(arc
		(start 383.873502 -247.239282)
		(mid 383.689727 -247.290054)
		(end 383.504694 -247.244108)
		(width 0.09525)
		(layer "In4.Cu")
		(net "M_J_CPU0_SA_DQS_DN<9>")
	)
	(arc
		(start 379.73635 -247.239282)
		(mid 379.502836 -247.165439)
		(end 379.2601 -247.198134)
		(width 0.09525)
		(layer "In4.Cu")
		(net "M_J_CPU0_SA_DQS_DN<9>")
	)
	(arc
		(start 392.881866 -247.230646)
		(mid 392.606915 -247.163503)
		(end 392.334242 -247.239282)
		(width 0.09525)
		(layer "In4.Cu")
		(net "M_J_CPU0_SA_DQS_DN<9>")
	)
	(arc
		(start 389.136382 -247.239282)
		(mid 388.85495 -247.163527)
		(end 388.573518 -247.239282)
		(width 0.09525)
		(layer "In4.Cu")
		(net "M_J_CPU0_SA_DQS_DN<9>")
	)
	(arc
		(start 391.956798 -247.239282)
		(mid 391.683616 -247.16334)
		(end 391.408158 -247.230646)
		(width 0.09525)
		(layer "In4.Cu")
		(net "M_J_CPU0_SA_DQS_DN<9>")
	)
	(arc
		(start 381.044958 -247.244108)
		(mid 380.859926 -247.290022)
		(end 380.67615 -247.239282)
		(width 0.09525)
		(layer "In4.Cu")
		(net "M_J_CPU0_SA_DQS_DN<9>")
	)
	(arc
		(start 390.076182 -247.239282)
		(mid 389.79475 -247.163527)
		(end 389.513318 -247.239282)
		(width 0.09525)
		(layer "In4.Cu")
		(net "M_J_CPU0_SA_DQS_DN<9>")
	)
	(arc
		(start 386.685028 -247.244108)
		(mid 386.499996 -247.290022)
		(end 386.31622 -247.239282)
		(width 0.09525)
		(layer "In4.Cu")
		(net "M_J_CPU0_SA_DQS_DN<9>")
	)
	(arc
		(start 386.31622 -247.239282)
		(mid 386.034788 -247.163527)
		(end 385.753356 -247.239282)
		(width 0.09525)
		(layer "In4.Cu")
		(net "M_J_CPU0_SA_DQS_DN<9>")
	)
	(arc
		(start 391.016236 -247.239282)
		(mid 390.734804 -247.163527)
		(end 390.453372 -247.239282)
		(width 0.09525)
		(layer "In4.Cu")
		(net "M_J_CPU0_SA_DQS_DN<9>")
	)
	(arc
		(start 393.824714 -247.231916)
		(mid 393.548277 -247.163267)
		(end 393.273788 -247.239282)
		(width 0.09525)
		(layer "In4.Cu")
		(net "M_J_CPU0_SA_DQS_DN<9>")
	)
	(arc
		(start 380.113286 -247.239282)
		(mid 379.924818 -247.289959)
		(end 379.73635 -247.239282)
		(width 0.09525)
		(layer "In4.Cu")
		(net "M_J_CPU0_SA_DQS_DN<9>")
	)
	(arc
		(start 392.322304 -247.24614)
		(mid 392.138669 -247.29009)
		(end 391.956798 -247.239282)
		(width 0.09525)
		(layer "In4.Cu")
		(net "M_J_CPU0_SA_DQS_DN<9>")
	)
	(arc
		(start 379.2601 -247.198134)
		(mid 379.249772 -247.202094)
		(end 379.239526 -247.206262)
		(width 0.09525)
		(layer "In4.Cu")
		(net "M_J_CPU0_SA_DQS_DN<9>")
	)
	(arc
		(start 383.496312 -247.239282)
		(mid 383.21488 -247.163527)
		(end 382.933448 -247.239282)
		(width 0.09525)
		(layer "In4.Cu")
		(net "M_J_CPU0_SA_DQS_DN<9>")
	)
	(arc
		(start 382.556258 -247.239282)
		(mid 382.274826 -247.163527)
		(end 381.993394 -247.239282)
		(width 0.09525)
		(layer "In4.Cu")
		(net "M_J_CPU0_SA_DQS_DN<9>")
	)
	(arc
		(start 389.513318 -247.239282)
		(mid 389.32485 -247.289959)
		(end 389.136382 -247.239282)
		(width 0.09525)
		(layer "In4.Cu")
		(net "M_J_CPU0_SA_DQS_DN<9>")
	)
	(arc
		(start 381.985012 -247.244108)
		(mid 381.79998 -247.290022)
		(end 381.616204 -247.239282)
		(width 0.09525)
		(layer "In4.Cu")
		(net "M_J_CPU0_SA_DQS_DN<9>")
	)
	(arc
		(start 390.44499 -247.244108)
		(mid 390.259958 -247.290022)
		(end 390.076182 -247.239282)
		(width 0.09525)
		(layer "In4.Cu")
		(net "M_J_CPU0_SA_DQS_DN<9>")
	)
	(arc
		(start 387.633464 -247.239282)
		(mid 387.449689 -247.290054)
		(end 387.264656 -247.244108)
		(width 0.09525)
		(layer "In4.Cu")
		(net "M_J_CPU0_SA_DQS_DN<9>")
	)
	(arc
		(start 385.376166 -247.239282)
		(mid 385.094734 -247.163527)
		(end 384.813302 -247.239282)
		(width 0.09525)
		(layer "In4.Cu")
		(net "M_J_CPU0_SA_DQS_DN<9>")
	)
	(segment
		(start 378.517912 -242.320064)
		(end 378.984764 -242.054126)
		(width 0.12954)
		(layer "F.Cu")
		(net "M_J_CPU0_SA_DQS_DN<8>")
	)
	(segment
		(start 431.083466 -230.05796)
		(end 431.921158 -230.05796)
		(width 0.16002)
		(layer "In4.Cu")
		(net "M_J_CPU0_SA_DQS_DN<8>")
	)
	(segment
		(start 390.44499 -242.384072)
		(end 390.453372 -242.379246)
		(width 0.09525)
		(layer "In4.Cu")
		(net "M_J_CPU0_SA_DQS_DN<8>")
	)
	(segment
		(start 430.73828 -229.712774)
		(end 431.083466 -230.05796)
		(width 0.16002)
		(layer "In4.Cu")
		(net "M_J_CPU0_SA_DQS_DN<8>")
	)
	(segment
		(start 407.757376 -233.526838)
		(end 408.000454 -233.769916)
		(width 0.16002)
		(layer "In4.Cu")
		(net "M_J_CPU0_SA_DQS_DN<8>")
	)
	(segment
		(start 378.984764 -242.054126)
		(end 379.138688 -242.319556)
		(width 0.09525)
		(layer "In4.Cu")
		(net "M_J_CPU0_SA_DQS_DN<8>")
	)
	(segment
		(start 387.256274 -242.379246)
		(end 387.264656 -242.384072)
		(width 0.09525)
		(layer "In4.Cu")
		(net "M_J_CPU0_SA_DQS_DN<8>")
	)
	(segment
		(start 393.787884 -242.431062)
		(end 394.248894 -241.970052)
		(width 0.09525)
		(layer "In4.Cu")
		(net "M_J_CPU0_SA_DQS_DN<8>")
	)
	(segment
		(start 411.024578 -231.022652)
		(end 411.539436 -230.507794)
		(width 0.16002)
		(layer "In4.Cu")
		(net "M_J_CPU0_SA_DQS_DN<8>")
	)
	(segment
		(start 410.747718 -231.022652)
		(end 411.024578 -231.022652)
		(width 0.16002)
		(layer "In4.Cu")
		(net "M_J_CPU0_SA_DQS_DN<8>")
	)
	(segment
		(start 420.372032 -230.908098)
		(end 420.711376 -230.568754)
		(width 0.16002)
		(layer "In4.Cu")
		(net "M_J_CPU0_SA_DQS_DN<8>")
	)
	(segment
		(start 409.650946 -232.396284)
		(end 409.84678 -232.20045)
		(width 0.16002)
		(layer "In4.Cu")
		(net "M_J_CPU0_SA_DQS_DN<8>")
	)
	(segment
		(start 413.980376 -230.507794)
		(end 414.749996 -229.738174)
		(width 0.16002)
		(layer "In4.Cu")
		(net "M_J_CPU0_SA_DQS_DN<8>")
	)
	(segment
		(start 409.603702 -231.680512)
		(end 409.603702 -231.153208)
		(width 0.16002)
		(layer "In4.Cu")
		(net "M_J_CPU0_SA_DQS_DN<8>")
	)
	(segment
		(start 382.556258 -242.379246)
		(end 382.56464 -242.384072)
		(width 0.09525)
		(layer "In4.Cu")
		(net "M_J_CPU0_SA_DQS_DN<8>")
	)
	(segment
		(start 408.473148 -233.574082)
		(end 408.473148 -233.297222)
		(width 0.16002)
		(layer "In4.Cu")
		(net "M_J_CPU0_SA_DQS_DN<8>")
	)
	(segment
		(start 431.921158 -230.05796)
		(end 432.070256 -229.908862)
		(width 0.16002)
		(layer "In4.Cu")
		(net "M_J_CPU0_SA_DQS_DN<8>")
	)
	(segment
		(start 409.603702 -231.153208)
		(end 409.977336 -230.779574)
		(width 0.16002)
		(layer "In4.Cu")
		(net "M_J_CPU0_SA_DQS_DN<8>")
	)
	(segment
		(start 423.1767 -229.720394)
		(end 423.514266 -230.05796)
		(width 0.16002)
		(layer "In4.Cu")
		(net "M_J_CPU0_SA_DQS_DN<8>")
	)
	(segment
		(start 407.230072 -233.526838)
		(end 407.757376 -233.526838)
		(width 0.16002)
		(layer "In4.Cu")
		(net "M_J_CPU0_SA_DQS_DN<8>")
	)
	(segment
		(start 409.374086 -232.396284)
		(end 409.650946 -232.396284)
		(width 0.16002)
		(layer "In4.Cu")
		(net "M_J_CPU0_SA_DQS_DN<8>")
	)
	(segment
		(start 429.836072 -229.712774)
		(end 430.73828 -229.712774)
		(width 0.16002)
		(layer "In4.Cu")
		(net "M_J_CPU0_SA_DQS_DN<8>")
	)
	(segment
		(start 420.711376 -230.568754)
		(end 421.379396 -230.568754)
		(width 0.16002)
		(layer "In4.Cu")
		(net "M_J_CPU0_SA_DQS_DN<8>")
	)
	(segment
		(start 392.146028 -242.431062)
		(end 393.787884 -242.431062)
		(width 0.09525)
		(layer "In4.Cu")
		(net "M_J_CPU0_SA_DQS_DN<8>")
	)
	(segment
		(start 432.070256 -229.908862)
		(end 434.726334 -229.908862)
		(width 0.16002)
		(layer "In4.Cu")
		(net "M_J_CPU0_SA_DQS_DN<8>")
	)
	(segment
		(start 406.856438 -233.900472)
		(end 407.230072 -233.526838)
		(width 0.16002)
		(layer "In4.Cu")
		(net "M_J_CPU0_SA_DQS_DN<8>")
	)
	(segment
		(start 395.764004 -241.200432)
		(end 395.787626 -241.200432)
		(width 0.09525)
		(layer "In4.Cu")
		(net "M_J_CPU0_SA_DQS_DN<8>")
	)
	(segment
		(start 428.068232 -230.908098)
		(end 428.430436 -230.545894)
		(width 0.16002)
		(layer "In4.Cu")
		(net "M_J_CPU0_SA_DQS_DN<8>")
	)
	(segment
		(start 395.787626 -241.200432)
		(end 399.943574 -241.200432)
		(width 0.16002)
		(layer "In4.Cu")
		(net "M_J_CPU0_SA_DQS_DN<8>")
	)
	(segment
		(start 395.704822 -241.259614)
		(end 395.764004 -241.200432)
		(width 0.09525)
		(layer "In4.Cu")
		(net "M_J_CPU0_SA_DQS_DN<8>")
	)
	(segment
		(start 383.496312 -242.379246)
		(end 383.504694 -242.384072)
		(width 0.09525)
		(layer "In4.Cu")
		(net "M_J_CPU0_SA_DQS_DN<8>")
	)
	(segment
		(start 411.539436 -230.507794)
		(end 413.980376 -230.507794)
		(width 0.16002)
		(layer "In4.Cu")
		(net "M_J_CPU0_SA_DQS_DN<8>")
	)
	(segment
		(start 409.131008 -232.153206)
		(end 409.374086 -232.396284)
		(width 0.16002)
		(layer "In4.Cu")
		(net "M_J_CPU0_SA_DQS_DN<8>")
	)
	(segment
		(start 426.09135 -230.05796)
		(end 426.941488 -230.908098)
		(width 0.16002)
		(layer "In4.Cu")
		(net "M_J_CPU0_SA_DQS_DN<8>")
	)
	(segment
		(start 409.84678 -232.20045)
		(end 409.84678 -231.92359)
		(width 0.16002)
		(layer "In4.Cu")
		(net "M_J_CPU0_SA_DQS_DN<8>")
	)
	(segment
		(start 423.514266 -230.05796)
		(end 426.09135 -230.05796)
		(width 0.16002)
		(layer "In4.Cu")
		(net "M_J_CPU0_SA_DQS_DN<8>")
	)
	(segment
		(start 405.922988 -235.221018)
		(end 406.826212 -235.221018)
		(width 0.16002)
		(layer "In4.Cu")
		(net "M_J_CPU0_SA_DQS_DN<8>")
	)
	(segment
		(start 429.002952 -230.545894)
		(end 429.836072 -229.712774)
		(width 0.16002)
		(layer "In4.Cu")
		(net "M_J_CPU0_SA_DQS_DN<8>")
	)
	(segment
		(start 381.985012 -242.384072)
		(end 381.993394 -242.379246)
		(width 0.09525)
		(layer "In4.Cu")
		(net "M_J_CPU0_SA_DQS_DN<8>")
	)
	(segment
		(start 391.016236 -242.379246)
		(end 391.024618 -242.384072)
		(width 0.09525)
		(layer "In4.Cu")
		(net "M_J_CPU0_SA_DQS_DN<8>")
	)
	(segment
		(start 408.473148 -233.297222)
		(end 408.23007 -233.054144)
		(width 0.16002)
		(layer "In4.Cu")
		(net "M_J_CPU0_SA_DQS_DN<8>")
	)
	(segment
		(start 394.750544 -241.970052)
		(end 395.460982 -241.259614)
		(width 0.09525)
		(layer "In4.Cu")
		(net "M_J_CPU0_SA_DQS_DN<8>")
	)
	(segment
		(start 394.248894 -241.970052)
		(end 394.750544 -241.970052)
		(width 0.09525)
		(layer "In4.Cu")
		(net "M_J_CPU0_SA_DQS_DN<8>")
	)
	(segment
		(start 381.044958 -242.384072)
		(end 381.05334 -242.379246)
		(width 0.09525)
		(layer "In4.Cu")
		(net "M_J_CPU0_SA_DQS_DN<8>")
	)
	(segment
		(start 421.379396 -230.568754)
		(end 422.227756 -229.720394)
		(width 0.16002)
		(layer "In4.Cu")
		(net "M_J_CPU0_SA_DQS_DN<8>")
	)
	(segment
		(start 388.196328 -242.379246)
		(end 388.20471 -242.384072)
		(width 0.09525)
		(layer "In4.Cu")
		(net "M_J_CPU0_SA_DQS_DN<8>")
	)
	(segment
		(start 408.23007 -233.054144)
		(end 408.23007 -232.52684)
		(width 0.16002)
		(layer "In4.Cu")
		(net "M_J_CPU0_SA_DQS_DN<8>")
	)
	(segment
		(start 409.977336 -230.779574)
		(end 410.50464 -230.779574)
		(width 0.16002)
		(layer "In4.Cu")
		(net "M_J_CPU0_SA_DQS_DN<8>")
	)
	(segment
		(start 379.138688 -242.319556)
		(end 379.239526 -242.346226)
		(width 0.09525)
		(layer "In4.Cu")
		(net "M_J_CPU0_SA_DQS_DN<8>")
	)
	(segment
		(start 409.84678 -231.92359)
		(end 409.603702 -231.680512)
		(width 0.16002)
		(layer "In4.Cu")
		(net "M_J_CPU0_SA_DQS_DN<8>")
	)
	(segment
		(start 391.393426 -242.379246)
		(end 391.408158 -242.37061)
		(width 0.09525)
		(layer "In4.Cu")
		(net "M_J_CPU0_SA_DQS_DN<8>")
	)
	(segment
		(start 419.101524 -230.908098)
		(end 420.372032 -230.908098)
		(width 0.16002)
		(layer "In4.Cu")
		(net "M_J_CPU0_SA_DQS_DN<8>")
	)
	(segment
		(start 434.726334 -229.908862)
		(end 435.000146 -229.63505)
		(width 0.16002)
		(layer "In4.Cu")
		(net "M_J_CPU0_SA_DQS_DN<8>")
	)
	(segment
		(start 395.460982 -241.259614)
		(end 395.704822 -241.259614)
		(width 0.09525)
		(layer "In4.Cu")
		(net "M_J_CPU0_SA_DQS_DN<8>")
	)
	(segment
		(start 386.685028 -242.384072)
		(end 386.69341 -242.379246)
		(width 0.09525)
		(layer "In4.Cu")
		(net "M_J_CPU0_SA_DQS_DN<8>")
	)
	(segment
		(start 417.9316 -229.738174)
		(end 419.101524 -230.908098)
		(width 0.16002)
		(layer "In4.Cu")
		(net "M_J_CPU0_SA_DQS_DN<8>")
	)
	(segment
		(start 408.23007 -232.52684)
		(end 408.603704 -232.153206)
		(width 0.16002)
		(layer "In4.Cu")
		(net "M_J_CPU0_SA_DQS_DN<8>")
	)
	(segment
		(start 428.430436 -230.545894)
		(end 429.002952 -230.545894)
		(width 0.16002)
		(layer "In4.Cu")
		(net "M_J_CPU0_SA_DQS_DN<8>")
	)
	(segment
		(start 407.099516 -234.947714)
		(end 407.099516 -234.670854)
		(width 0.16002)
		(layer "In4.Cu")
		(net "M_J_CPU0_SA_DQS_DN<8>")
	)
	(segment
		(start 408.000454 -233.769916)
		(end 408.277314 -233.769916)
		(width 0.16002)
		(layer "In4.Cu")
		(net "M_J_CPU0_SA_DQS_DN<8>")
	)
	(segment
		(start 406.856438 -234.427776)
		(end 406.856438 -233.900472)
		(width 0.16002)
		(layer "In4.Cu")
		(net "M_J_CPU0_SA_DQS_DN<8>")
	)
	(segment
		(start 422.227756 -229.720394)
		(end 423.1767 -229.720394)
		(width 0.16002)
		(layer "In4.Cu")
		(net "M_J_CPU0_SA_DQS_DN<8>")
	)
	(segment
		(start 414.749996 -229.738174)
		(end 417.9316 -229.738174)
		(width 0.16002)
		(layer "In4.Cu")
		(net "M_J_CPU0_SA_DQS_DN<8>")
	)
	(segment
		(start 406.826212 -235.221018)
		(end 407.099516 -234.947714)
		(width 0.16002)
		(layer "In4.Cu")
		(net "M_J_CPU0_SA_DQS_DN<8>")
	)
	(segment
		(start 385.744974 -242.384072)
		(end 385.753356 -242.379246)
		(width 0.09525)
		(layer "In4.Cu")
		(net "M_J_CPU0_SA_DQS_DN<8>")
	)
	(segment
		(start 410.50464 -230.779574)
		(end 410.747718 -231.022652)
		(width 0.16002)
		(layer "In4.Cu")
		(net "M_J_CPU0_SA_DQS_DN<8>")
	)
	(segment
		(start 408.603704 -232.153206)
		(end 409.131008 -232.153206)
		(width 0.16002)
		(layer "In4.Cu")
		(net "M_J_CPU0_SA_DQS_DN<8>")
	)
	(segment
		(start 407.099516 -234.670854)
		(end 406.856438 -234.427776)
		(width 0.16002)
		(layer "In4.Cu")
		(net "M_J_CPU0_SA_DQS_DN<8>")
	)
	(segment
		(start 408.277314 -233.769916)
		(end 408.473148 -233.574082)
		(width 0.16002)
		(layer "In4.Cu")
		(net "M_J_CPU0_SA_DQS_DN<8>")
	)
	(segment
		(start 426.941488 -230.908098)
		(end 428.068232 -230.908098)
		(width 0.16002)
		(layer "In4.Cu")
		(net "M_J_CPU0_SA_DQS_DN<8>")
	)
	(segment
		(start 399.943574 -241.200432)
		(end 405.922988 -235.221018)
		(width 0.16002)
		(layer "In4.Cu")
		(net "M_J_CPU0_SA_DQS_DN<8>")
	)
	(arc
		(start 384.813302 -242.379246)
		(mid 385.094734 -242.303491)
		(end 385.376166 -242.379246)
		(width 0.09525)
		(layer "In4.Cu")
		(net "M_J_CPU0_SA_DQS_DN<8>")
	)
	(arc
		(start 388.573518 -242.379246)
		(mid 388.85495 -242.303491)
		(end 389.136382 -242.379246)
		(width 0.09525)
		(layer "In4.Cu")
		(net "M_J_CPU0_SA_DQS_DN<8>")
	)
	(arc
		(start 385.753356 -242.379246)
		(mid 386.034788 -242.303491)
		(end 386.31622 -242.379246)
		(width 0.09525)
		(layer "In4.Cu")
		(net "M_J_CPU0_SA_DQS_DN<8>")
	)
	(arc
		(start 389.136382 -242.379246)
		(mid 389.32485 -242.429923)
		(end 389.513318 -242.379246)
		(width 0.09525)
		(layer "In4.Cu")
		(net "M_J_CPU0_SA_DQS_DN<8>")
	)
	(arc
		(start 380.67615 -242.379246)
		(mid 380.859925 -242.430018)
		(end 381.044958 -242.384072)
		(width 0.09525)
		(layer "In4.Cu")
		(net "M_J_CPU0_SA_DQS_DN<8>")
	)
	(arc
		(start 387.264656 -242.384072)
		(mid 387.449688 -242.429986)
		(end 387.633464 -242.379246)
		(width 0.09525)
		(layer "In4.Cu")
		(net "M_J_CPU0_SA_DQS_DN<8>")
	)
	(arc
		(start 379.239526 -242.346226)
		(mid 379.49181 -242.304532)
		(end 379.73635 -242.379246)
		(width 0.09525)
		(layer "In4.Cu")
		(net "M_J_CPU0_SA_DQS_DN<8>")
	)
	(arc
		(start 381.05334 -242.379246)
		(mid 381.334772 -242.303491)
		(end 381.616204 -242.379246)
		(width 0.09525)
		(layer "In4.Cu")
		(net "M_J_CPU0_SA_DQS_DN<8>")
	)
	(arc
		(start 384.436366 -242.379246)
		(mid 384.624834 -242.429923)
		(end 384.813302 -242.379246)
		(width 0.09525)
		(layer "In4.Cu")
		(net "M_J_CPU0_SA_DQS_DN<8>")
	)
	(arc
		(start 386.69341 -242.379246)
		(mid 386.974842 -242.303491)
		(end 387.256274 -242.379246)
		(width 0.09525)
		(layer "In4.Cu")
		(net "M_J_CPU0_SA_DQS_DN<8>")
	)
	(arc
		(start 386.31622 -242.379246)
		(mid 386.499995 -242.430018)
		(end 386.685028 -242.384072)
		(width 0.09525)
		(layer "In4.Cu")
		(net "M_J_CPU0_SA_DQS_DN<8>")
	)
	(arc
		(start 383.873502 -242.379246)
		(mid 384.154934 -242.303491)
		(end 384.436366 -242.379246)
		(width 0.09525)
		(layer "In4.Cu")
		(net "M_J_CPU0_SA_DQS_DN<8>")
	)
	(arc
		(start 381.616204 -242.379246)
		(mid 381.799979 -242.430018)
		(end 381.985012 -242.384072)
		(width 0.09525)
		(layer "In4.Cu")
		(net "M_J_CPU0_SA_DQS_DN<8>")
	)
	(arc
		(start 391.024618 -242.384072)
		(mid 391.20965 -242.429986)
		(end 391.393426 -242.379246)
		(width 0.09525)
		(layer "In4.Cu")
		(net "M_J_CPU0_SA_DQS_DN<8>")
	)
	(arc
		(start 390.076182 -242.379246)
		(mid 390.259957 -242.430018)
		(end 390.44499 -242.384072)
		(width 0.09525)
		(layer "In4.Cu")
		(net "M_J_CPU0_SA_DQS_DN<8>")
	)
	(arc
		(start 380.113286 -242.379246)
		(mid 380.394718 -242.303491)
		(end 380.67615 -242.379246)
		(width 0.09525)
		(layer "In4.Cu")
		(net "M_J_CPU0_SA_DQS_DN<8>")
	)
	(arc
		(start 391.956798 -242.379246)
		(mid 392.047973 -242.417737)
		(end 392.146028 -242.431062)
		(width 0.09525)
		(layer "In4.Cu")
		(net "M_J_CPU0_SA_DQS_DN<8>")
	)
	(arc
		(start 382.933448 -242.379246)
		(mid 383.21488 -242.303491)
		(end 383.496312 -242.379246)
		(width 0.09525)
		(layer "In4.Cu")
		(net "M_J_CPU0_SA_DQS_DN<8>")
	)
	(arc
		(start 381.993394 -242.379246)
		(mid 382.274826 -242.303491)
		(end 382.556258 -242.379246)
		(width 0.09525)
		(layer "In4.Cu")
		(net "M_J_CPU0_SA_DQS_DN<8>")
	)
	(arc
		(start 385.376166 -242.379246)
		(mid 385.559941 -242.430018)
		(end 385.744974 -242.384072)
		(width 0.09525)
		(layer "In4.Cu")
		(net "M_J_CPU0_SA_DQS_DN<8>")
	)
	(arc
		(start 388.20471 -242.384072)
		(mid 388.389742 -242.429986)
		(end 388.573518 -242.379246)
		(width 0.09525)
		(layer "In4.Cu")
		(net "M_J_CPU0_SA_DQS_DN<8>")
	)
	(arc
		(start 390.453372 -242.379246)
		(mid 390.734804 -242.303491)
		(end 391.016236 -242.379246)
		(width 0.09525)
		(layer "In4.Cu")
		(net "M_J_CPU0_SA_DQS_DN<8>")
	)
	(arc
		(start 387.633464 -242.379246)
		(mid 387.914896 -242.303491)
		(end 388.196328 -242.379246)
		(width 0.09525)
		(layer "In4.Cu")
		(net "M_J_CPU0_SA_DQS_DN<8>")
	)
	(arc
		(start 383.504694 -242.384072)
		(mid 383.689726 -242.429986)
		(end 383.873502 -242.379246)
		(width 0.09525)
		(layer "In4.Cu")
		(net "M_J_CPU0_SA_DQS_DN<8>")
	)
	(arc
		(start 379.73635 -242.379246)
		(mid 379.924818 -242.429923)
		(end 380.113286 -242.379246)
		(width 0.09525)
		(layer "In4.Cu")
		(net "M_J_CPU0_SA_DQS_DN<8>")
	)
	(arc
		(start 382.56464 -242.384072)
		(mid 382.749672 -242.429986)
		(end 382.933448 -242.379246)
		(width 0.09525)
		(layer "In4.Cu")
		(net "M_J_CPU0_SA_DQS_DN<8>")
	)
	(arc
		(start 391.408158 -242.37061)
		(mid 391.683617 -242.303225)
		(end 391.956798 -242.379246)
		(width 0.09525)
		(layer "In4.Cu")
		(net "M_J_CPU0_SA_DQS_DN<8>")
	)
	(arc
		(start 389.513318 -242.379246)
		(mid 389.79475 -242.303491)
		(end 390.076182 -242.379246)
		(width 0.09525)
		(layer "In4.Cu")
		(net "M_J_CPU0_SA_DQS_DN<8>")
	)
	(segment
		(start 378.517912 -237.460028)
		(end 378.984764 -237.19409)
		(width 0.12954)
		(layer "F.Cu")
		(net "M_J_CPU0_SA_DQS_DN<7>")
	)
	(segment
		(start 412.194248 -220.509592)
		(end 412.56712 -220.882464)
		(width 0.16002)
		(layer "In4.Cu")
		(net "M_J_CPU0_SA_DQS_DN<7>")
	)
	(segment
		(start 408.74315 -221.54896)
		(end 409.157424 -221.54896)
		(width 0.16002)
		(layer "In4.Cu")
		(net "M_J_CPU0_SA_DQS_DN<7>")
	)
	(segment
		(start 411.294326 -221.353126)
		(end 411.294326 -220.882464)
		(width 0.16002)
		(layer "In4.Cu")
		(net "M_J_CPU0_SA_DQS_DN<7>")
	)
	(segment
		(start 395.77645 -235.520992)
		(end 395.835632 -235.46181)
		(width 0.09525)
		(layer "In4.Cu")
		(net "M_J_CPU0_SA_DQS_DN<7>")
	)
	(segment
		(start 391.945622 -237.513114)
		(end 391.956036 -237.51921)
		(width 0.09525)
		(layer "In4.Cu")
		(net "M_J_CPU0_SA_DQS_DN<7>")
	)
	(segment
		(start 388.196328 -237.51921)
		(end 388.20471 -237.524036)
		(width 0.09525)
		(layer "In4.Cu")
		(net "M_J_CPU0_SA_DQS_DN<7>")
	)
	(segment
		(start 385.744974 -237.524036)
		(end 385.753356 -237.51921)
		(width 0.09525)
		(layer "In4.Cu")
		(net "M_J_CPU0_SA_DQS_DN<7>")
	)
	(segment
		(start 394.4493 -236.093762)
		(end 394.808964 -236.093762)
		(width 0.09525)
		(layer "In4.Cu")
		(net "M_J_CPU0_SA_DQS_DN<7>")
	)
	(segment
		(start 383.496312 -237.51921)
		(end 383.504694 -237.524036)
		(width 0.09525)
		(layer "In4.Cu")
		(net "M_J_CPU0_SA_DQS_DN<7>")
	)
	(segment
		(start 391.016236 -237.51921)
		(end 391.024618 -237.524036)
		(width 0.09525)
		(layer "In4.Cu")
		(net "M_J_CPU0_SA_DQS_DN<7>")
	)
	(segment
		(start 412.56712 -220.882464)
		(end 412.56712 -221.353126)
		(width 0.16002)
		(layer "In4.Cu")
		(net "M_J_CPU0_SA_DQS_DN<7>")
	)
	(segment
		(start 428.068486 -221.55785)
		(end 428.430436 -221.1959)
		(width 0.16002)
		(layer "In4.Cu")
		(net "M_J_CPU0_SA_DQS_DN<7>")
	)
	(segment
		(start 423.514266 -220.707966)
		(end 426.09135 -220.707966)
		(width 0.16002)
		(layer "In4.Cu")
		(net "M_J_CPU0_SA_DQS_DN<7>")
	)
	(segment
		(start 381.985012 -237.524036)
		(end 381.993394 -237.51921)
		(width 0.09525)
		(layer "In4.Cu")
		(net "M_J_CPU0_SA_DQS_DN<7>")
	)
	(segment
		(start 417.9316 -220.38818)
		(end 419.10127 -221.55785)
		(width 0.16002)
		(layer "In4.Cu")
		(net "M_J_CPU0_SA_DQS_DN<7>")
	)
	(segment
		(start 393.273026 -237.51921)
		(end 393.27328 -237.519464)
		(width 0.09525)
		(layer "In4.Cu")
		(net "M_J_CPU0_SA_DQS_DN<7>")
	)
	(segment
		(start 411.294326 -220.882464)
		(end 411.667198 -220.509592)
		(width 0.16002)
		(layer "In4.Cu")
		(net "M_J_CPU0_SA_DQS_DN<7>")
	)
	(segment
		(start 390.44499 -237.524036)
		(end 390.446006 -237.523528)
		(width 0.09525)
		(layer "In4.Cu")
		(net "M_J_CPU0_SA_DQS_DN<7>")
	)
	(segment
		(start 411.667198 -220.509592)
		(end 412.194248 -220.509592)
		(width 0.16002)
		(layer "In4.Cu")
		(net "M_J_CPU0_SA_DQS_DN<7>")
	)
	(segment
		(start 394.103606 -236.707172)
		(end 394.103606 -236.439456)
		(width 0.09525)
		(layer "In4.Cu")
		(net "M_J_CPU0_SA_DQS_DN<7>")
	)
	(segment
		(start 434.726334 -220.558868)
		(end 435.000146 -220.285056)
		(width 0.16002)
		(layer "In4.Cu")
		(net "M_J_CPU0_SA_DQS_DN<7>")
	)
	(segment
		(start 392.332972 -237.51921)
		(end 392.343386 -237.513114)
		(width 0.09525)
		(layer "In4.Cu")
		(net "M_J_CPU0_SA_DQS_DN<7>")
	)
	(segment
		(start 386.685028 -237.524036)
		(end 386.69341 -237.51921)
		(width 0.09525)
		(layer "In4.Cu")
		(net "M_J_CPU0_SA_DQS_DN<7>")
	)
	(segment
		(start 397.18488 -235.46181)
		(end 403.992842 -228.653848)
		(width 0.16002)
		(layer "In4.Cu")
		(net "M_J_CPU0_SA_DQS_DN<7>")
	)
	(segment
		(start 412.762954 -221.54896)
		(end 413.095948 -221.54896)
		(width 0.16002)
		(layer "In4.Cu")
		(net "M_J_CPU0_SA_DQS_DN<7>")
	)
	(segment
		(start 382.556258 -237.51921)
		(end 382.56464 -237.524036)
		(width 0.09525)
		(layer "In4.Cu")
		(net "M_J_CPU0_SA_DQS_DN<7>")
	)
	(segment
		(start 403.992842 -226.299268)
		(end 408.74315 -221.54896)
		(width 0.16002)
		(layer "In4.Cu")
		(net "M_J_CPU0_SA_DQS_DN<7>")
	)
	(segment
		(start 428.430436 -221.1959)
		(end 429.002952 -221.1959)
		(width 0.16002)
		(layer "In4.Cu")
		(net "M_J_CPU0_SA_DQS_DN<7>")
	)
	(segment
		(start 410.626052 -220.882464)
		(end 410.626052 -221.353126)
		(width 0.16002)
		(layer "In4.Cu")
		(net "M_J_CPU0_SA_DQS_DN<7>")
	)
	(segment
		(start 393.261088 -237.526068)
		(end 393.267184 -237.522512)
		(width 0.09525)
		(layer "In4.Cu")
		(net "M_J_CPU0_SA_DQS_DN<7>")
	)
	(segment
		(start 420.711376 -221.21876)
		(end 421.379396 -221.21876)
		(width 0.16002)
		(layer "In4.Cu")
		(net "M_J_CPU0_SA_DQS_DN<7>")
	)
	(segment
		(start 429.002952 -221.1959)
		(end 429.836072 -220.36278)
		(width 0.16002)
		(layer "In4.Cu")
		(net "M_J_CPU0_SA_DQS_DN<7>")
	)
	(segment
		(start 419.10127 -221.55785)
		(end 420.372286 -221.55785)
		(width 0.16002)
		(layer "In4.Cu")
		(net "M_J_CPU0_SA_DQS_DN<7>")
	)
	(segment
		(start 411.098492 -221.54896)
		(end 411.294326 -221.353126)
		(width 0.16002)
		(layer "In4.Cu")
		(net "M_J_CPU0_SA_DQS_DN<7>")
	)
	(segment
		(start 394.103606 -236.439456)
		(end 394.4493 -236.093762)
		(width 0.09525)
		(layer "In4.Cu")
		(net "M_J_CPU0_SA_DQS_DN<7>")
	)
	(segment
		(start 410.626052 -221.353126)
		(end 410.821886 -221.54896)
		(width 0.16002)
		(layer "In4.Cu")
		(net "M_J_CPU0_SA_DQS_DN<7>")
	)
	(segment
		(start 403.992842 -228.653848)
		(end 403.992842 -226.299268)
		(width 0.16002)
		(layer "In4.Cu")
		(net "M_J_CPU0_SA_DQS_DN<7>")
	)
	(segment
		(start 390.446006 -237.523528)
		(end 390.453372 -237.51921)
		(width 0.09525)
		(layer "In4.Cu")
		(net "M_J_CPU0_SA_DQS_DN<7>")
	)
	(segment
		(start 395.835632 -235.46181)
		(end 395.859254 -235.46181)
		(width 0.09525)
		(layer "In4.Cu")
		(net "M_J_CPU0_SA_DQS_DN<7>")
	)
	(segment
		(start 379.138688 -237.45952)
		(end 379.239526 -237.48619)
		(width 0.09525)
		(layer "In4.Cu")
		(net "M_J_CPU0_SA_DQS_DN<7>")
	)
	(segment
		(start 393.350496 -237.460028)
		(end 394.103606 -236.707172)
		(width 0.09525)
		(layer "In4.Cu")
		(net "M_J_CPU0_SA_DQS_DN<7>")
	)
	(segment
		(start 413.095948 -221.54896)
		(end 413.487108 -221.1578)
		(width 0.16002)
		(layer "In4.Cu")
		(net "M_J_CPU0_SA_DQS_DN<7>")
	)
	(segment
		(start 409.72613 -220.509592)
		(end 410.25318 -220.509592)
		(width 0.16002)
		(layer "In4.Cu")
		(net "M_J_CPU0_SA_DQS_DN<7>")
	)
	(segment
		(start 409.157424 -221.54896)
		(end 409.353258 -221.353126)
		(width 0.16002)
		(layer "In4.Cu")
		(net "M_J_CPU0_SA_DQS_DN<7>")
	)
	(segment
		(start 421.379396 -221.21876)
		(end 422.227756 -220.3704)
		(width 0.16002)
		(layer "In4.Cu")
		(net "M_J_CPU0_SA_DQS_DN<7>")
	)
	(segment
		(start 381.044958 -237.524036)
		(end 381.05334 -237.51921)
		(width 0.09525)
		(layer "In4.Cu")
		(net "M_J_CPU0_SA_DQS_DN<7>")
	)
	(segment
		(start 412.56712 -221.353126)
		(end 412.762954 -221.54896)
		(width 0.16002)
		(layer "In4.Cu")
		(net "M_J_CPU0_SA_DQS_DN<7>")
	)
	(segment
		(start 431.083466 -220.707966)
		(end 431.921158 -220.707966)
		(width 0.16002)
		(layer "In4.Cu")
		(net "M_J_CPU0_SA_DQS_DN<7>")
	)
	(segment
		(start 410.25318 -220.509592)
		(end 410.626052 -220.882464)
		(width 0.16002)
		(layer "In4.Cu")
		(net "M_J_CPU0_SA_DQS_DN<7>")
	)
	(segment
		(start 432.070256 -220.558868)
		(end 434.726334 -220.558868)
		(width 0.16002)
		(layer "In4.Cu")
		(net "M_J_CPU0_SA_DQS_DN<7>")
	)
	(segment
		(start 409.353258 -220.882464)
		(end 409.72613 -220.509592)
		(width 0.16002)
		(layer "In4.Cu")
		(net "M_J_CPU0_SA_DQS_DN<7>")
	)
	(segment
		(start 422.227756 -220.3704)
		(end 423.1767 -220.3704)
		(width 0.16002)
		(layer "In4.Cu")
		(net "M_J_CPU0_SA_DQS_DN<7>")
	)
	(segment
		(start 413.980376 -221.1578)
		(end 414.749996 -220.38818)
		(width 0.16002)
		(layer "In4.Cu")
		(net "M_J_CPU0_SA_DQS_DN<7>")
	)
	(segment
		(start 413.487108 -221.1578)
		(end 413.980376 -221.1578)
		(width 0.16002)
		(layer "In4.Cu")
		(net "M_J_CPU0_SA_DQS_DN<7>")
	)
	(segment
		(start 393.267184 -237.522512)
		(end 393.273026 -237.51921)
		(width 0.09525)
		(layer "In4.Cu")
		(net "M_J_CPU0_SA_DQS_DN<7>")
	)
	(segment
		(start 395.381734 -235.520992)
		(end 395.77645 -235.520992)
		(width 0.09525)
		(layer "In4.Cu")
		(net "M_J_CPU0_SA_DQS_DN<7>")
	)
	(segment
		(start 409.353258 -221.353126)
		(end 409.353258 -220.882464)
		(width 0.16002)
		(layer "In4.Cu")
		(net "M_J_CPU0_SA_DQS_DN<7>")
	)
	(segment
		(start 426.941234 -221.55785)
		(end 428.068486 -221.55785)
		(width 0.16002)
		(layer "In4.Cu")
		(net "M_J_CPU0_SA_DQS_DN<7>")
	)
	(segment
		(start 423.1767 -220.3704)
		(end 423.514266 -220.707966)
		(width 0.16002)
		(layer "In4.Cu")
		(net "M_J_CPU0_SA_DQS_DN<7>")
	)
	(segment
		(start 414.749996 -220.38818)
		(end 417.9316 -220.38818)
		(width 0.16002)
		(layer "In4.Cu")
		(net "M_J_CPU0_SA_DQS_DN<7>")
	)
	(segment
		(start 394.808964 -236.093762)
		(end 395.381734 -235.520992)
		(width 0.09525)
		(layer "In4.Cu")
		(net "M_J_CPU0_SA_DQS_DN<7>")
	)
	(segment
		(start 395.859254 -235.46181)
		(end 397.18488 -235.46181)
		(width 0.16002)
		(layer "In4.Cu")
		(net "M_J_CPU0_SA_DQS_DN<7>")
	)
	(segment
		(start 431.921158 -220.707966)
		(end 432.070256 -220.558868)
		(width 0.16002)
		(layer "In4.Cu")
		(net "M_J_CPU0_SA_DQS_DN<7>")
	)
	(segment
		(start 378.984764 -237.19409)
		(end 379.138688 -237.45952)
		(width 0.09525)
		(layer "In4.Cu")
		(net "M_J_CPU0_SA_DQS_DN<7>")
	)
	(segment
		(start 429.836072 -220.36278)
		(end 430.73828 -220.36278)
		(width 0.16002)
		(layer "In4.Cu")
		(net "M_J_CPU0_SA_DQS_DN<7>")
	)
	(segment
		(start 420.372286 -221.55785)
		(end 420.711376 -221.21876)
		(width 0.16002)
		(layer "In4.Cu")
		(net "M_J_CPU0_SA_DQS_DN<7>")
	)
	(segment
		(start 430.73828 -220.36278)
		(end 431.083466 -220.707966)
		(width 0.16002)
		(layer "In4.Cu")
		(net "M_J_CPU0_SA_DQS_DN<7>")
	)
	(segment
		(start 387.256274 -237.51921)
		(end 387.264656 -237.524036)
		(width 0.09525)
		(layer "In4.Cu")
		(net "M_J_CPU0_SA_DQS_DN<7>")
	)
	(segment
		(start 410.821886 -221.54896)
		(end 411.098492 -221.54896)
		(width 0.16002)
		(layer "In4.Cu")
		(net "M_J_CPU0_SA_DQS_DN<7>")
	)
	(segment
		(start 426.09135 -220.707966)
		(end 426.941234 -221.55785)
		(width 0.16002)
		(layer "In4.Cu")
		(net "M_J_CPU0_SA_DQS_DN<7>")
	)
	(arc
		(start 392.343386 -237.513114)
		(mid 392.620548 -237.443314)
		(end 392.89609 -237.51921)
		(width 0.09525)
		(layer "In4.Cu")
		(net "M_J_CPU0_SA_DQS_DN<7>")
	)
	(arc
		(start 385.376166 -237.51921)
		(mid 385.559941 -237.569982)
		(end 385.744974 -237.524036)
		(width 0.09525)
		(layer "In4.Cu")
		(net "M_J_CPU0_SA_DQS_DN<7>")
	)
	(arc
		(start 388.573518 -237.51921)
		(mid 388.85495 -237.443455)
		(end 389.136382 -237.51921)
		(width 0.09525)
		(layer "In4.Cu")
		(net "M_J_CPU0_SA_DQS_DN<7>")
	)
	(arc
		(start 384.436366 -237.51921)
		(mid 384.624834 -237.569887)
		(end 384.813302 -237.51921)
		(width 0.09525)
		(layer "In4.Cu")
		(net "M_J_CPU0_SA_DQS_DN<7>")
	)
	(arc
		(start 379.239526 -237.48619)
		(mid 379.249774 -237.482027)
		(end 379.2601 -237.478062)
		(width 0.09525)
		(layer "In4.Cu")
		(net "M_J_CPU0_SA_DQS_DN<7>")
	)
	(arc
		(start 390.453372 -237.51921)
		(mid 390.734804 -237.443455)
		(end 391.016236 -237.51921)
		(width 0.09525)
		(layer "In4.Cu")
		(net "M_J_CPU0_SA_DQS_DN<7>")
	)
	(arc
		(start 389.136382 -237.51921)
		(mid 389.32485 -237.569887)
		(end 389.513318 -237.51921)
		(width 0.09525)
		(layer "In4.Cu")
		(net "M_J_CPU0_SA_DQS_DN<7>")
	)
	(arc
		(start 381.05334 -237.51921)
		(mid 381.334772 -237.443455)
		(end 381.616204 -237.51921)
		(width 0.09525)
		(layer "In4.Cu")
		(net "M_J_CPU0_SA_DQS_DN<7>")
	)
	(arc
		(start 379.2601 -237.478062)
		(mid 379.502842 -237.445292)
		(end 379.73635 -237.51921)
		(width 0.09525)
		(layer "In4.Cu")
		(net "M_J_CPU0_SA_DQS_DN<7>")
	)
	(arc
		(start 388.20471 -237.524036)
		(mid 388.389742 -237.56995)
		(end 388.573518 -237.51921)
		(width 0.09525)
		(layer "In4.Cu")
		(net "M_J_CPU0_SA_DQS_DN<7>")
	)
	(arc
		(start 386.31622 -237.51921)
		(mid 386.499995 -237.569982)
		(end 386.685028 -237.524036)
		(width 0.09525)
		(layer "In4.Cu")
		(net "M_J_CPU0_SA_DQS_DN<7>")
	)
	(arc
		(start 382.56464 -237.524036)
		(mid 382.749672 -237.56995)
		(end 382.933448 -237.51921)
		(width 0.09525)
		(layer "In4.Cu")
		(net "M_J_CPU0_SA_DQS_DN<7>")
	)
	(arc
		(start 391.956036 -237.51921)
		(mid 392.144504 -237.569887)
		(end 392.332972 -237.51921)
		(width 0.09525)
		(layer "In4.Cu")
		(net "M_J_CPU0_SA_DQS_DN<7>")
	)
	(arc
		(start 392.89609 -237.51921)
		(mid 393.077706 -237.569947)
		(end 393.261088 -237.526068)
		(width 0.09525)
		(layer "In4.Cu")
		(net "M_J_CPU0_SA_DQS_DN<7>")
	)
	(arc
		(start 380.67615 -237.51921)
		(mid 380.859925 -237.569982)
		(end 381.044958 -237.524036)
		(width 0.09525)
		(layer "In4.Cu")
		(net "M_J_CPU0_SA_DQS_DN<7>")
	)
	(arc
		(start 383.504694 -237.524036)
		(mid 383.689726 -237.56995)
		(end 383.873502 -237.51921)
		(width 0.09525)
		(layer "In4.Cu")
		(net "M_J_CPU0_SA_DQS_DN<7>")
	)
	(arc
		(start 385.753356 -237.51921)
		(mid 386.034788 -237.443455)
		(end 386.31622 -237.51921)
		(width 0.09525)
		(layer "In4.Cu")
		(net "M_J_CPU0_SA_DQS_DN<7>")
	)
	(arc
		(start 381.993394 -237.51921)
		(mid 382.274826 -237.443455)
		(end 382.556258 -237.51921)
		(width 0.09525)
		(layer "In4.Cu")
		(net "M_J_CPU0_SA_DQS_DN<7>")
	)
	(arc
		(start 382.933448 -237.51921)
		(mid 383.21488 -237.443455)
		(end 383.496312 -237.51921)
		(width 0.09525)
		(layer "In4.Cu")
		(net "M_J_CPU0_SA_DQS_DN<7>")
	)
	(arc
		(start 387.264656 -237.524036)
		(mid 387.449688 -237.56995)
		(end 387.633464 -237.51921)
		(width 0.09525)
		(layer "In4.Cu")
		(net "M_J_CPU0_SA_DQS_DN<7>")
	)
	(arc
		(start 389.513318 -237.51921)
		(mid 389.79475 -237.443455)
		(end 390.076182 -237.51921)
		(width 0.09525)
		(layer "In4.Cu")
		(net "M_J_CPU0_SA_DQS_DN<7>")
	)
	(arc
		(start 391.024618 -237.524036)
		(mid 391.20965 -237.56995)
		(end 391.393426 -237.51921)
		(width 0.09525)
		(layer "In4.Cu")
		(net "M_J_CPU0_SA_DQS_DN<7>")
	)
	(arc
		(start 383.873502 -237.51921)
		(mid 384.154934 -237.443455)
		(end 384.436366 -237.51921)
		(width 0.09525)
		(layer "In4.Cu")
		(net "M_J_CPU0_SA_DQS_DN<7>")
	)
	(arc
		(start 381.616204 -237.51921)
		(mid 381.799979 -237.569982)
		(end 381.985012 -237.524036)
		(width 0.09525)
		(layer "In4.Cu")
		(net "M_J_CPU0_SA_DQS_DN<7>")
	)
	(arc
		(start 379.73635 -237.51921)
		(mid 379.924818 -237.569887)
		(end 380.113286 -237.51921)
		(width 0.09525)
		(layer "In4.Cu")
		(net "M_J_CPU0_SA_DQS_DN<7>")
	)
	(arc
		(start 393.27328 -237.519464)
		(mid 393.313807 -237.492242)
		(end 393.350496 -237.460028)
		(width 0.09525)
		(layer "In4.Cu")
		(net "M_J_CPU0_SA_DQS_DN<7>")
	)
	(arc
		(start 391.393426 -237.51921)
		(mid 391.668715 -237.443489)
		(end 391.945622 -237.513114)
		(width 0.09525)
		(layer "In4.Cu")
		(net "M_J_CPU0_SA_DQS_DN<7>")
	)
	(arc
		(start 386.69341 -237.51921)
		(mid 386.974842 -237.443455)
		(end 387.256274 -237.51921)
		(width 0.09525)
		(layer "In4.Cu")
		(net "M_J_CPU0_SA_DQS_DN<7>")
	)
	(arc
		(start 380.113286 -237.51921)
		(mid 380.394718 -237.443455)
		(end 380.67615 -237.51921)
		(width 0.09525)
		(layer "In4.Cu")
		(net "M_J_CPU0_SA_DQS_DN<7>")
	)
	(arc
		(start 390.076182 -237.51921)
		(mid 390.259957 -237.569982)
		(end 390.44499 -237.524036)
		(width 0.09525)
		(layer "In4.Cu")
		(net "M_J_CPU0_SA_DQS_DN<7>")
	)
	(arc
		(start 384.813302 -237.51921)
		(mid 385.094734 -237.443455)
		(end 385.376166 -237.51921)
		(width 0.09525)
		(layer "In4.Cu")
		(net "M_J_CPU0_SA_DQS_DN<7>")
	)
	(arc
		(start 387.633464 -237.51921)
		(mid 387.914896 -237.443455)
		(end 388.196328 -237.51921)
		(width 0.09525)
		(layer "In4.Cu")
		(net "M_J_CPU0_SA_DQS_DN<7>")
	)
	(segment
		(start 378.517912 -232.599992)
		(end 378.984764 -232.334054)
		(width 0.12954)
		(layer "F.Cu")
		(net "M_J_CPU0_SA_DQS_DN<6>")
	)
	(segment
		(start 426.09135 -211.357972)
		(end 426.941234 -212.207856)
		(width 0.16002)
		(layer "In4.Cu")
		(net "M_J_CPU0_SA_DQS_DN<6>")
	)
	(segment
		(start 395.02842 -229.305612)
		(end 395.611604 -228.722174)
		(width 0.09525)
		(layer "In4.Cu")
		(net "M_J_CPU0_SA_DQS_DN<6>")
	)
	(segment
		(start 409.502356 -211.136992)
		(end 410.029406 -211.136992)
		(width 0.16002)
		(layer "In4.Cu")
		(net "M_J_CPU0_SA_DQS_DN<6>")
	)
	(segment
		(start 381.044958 -232.664)
		(end 381.05334 -232.659174)
		(width 0.09525)
		(layer "In4.Cu")
		(net "M_J_CPU0_SA_DQS_DN<6>")
	)
	(segment
		(start 419.10127 -212.207856)
		(end 420.372286 -212.207856)
		(width 0.16002)
		(layer "In4.Cu")
		(net "M_J_CPU0_SA_DQS_DN<6>")
	)
	(segment
		(start 379.138688 -232.599484)
		(end 379.239526 -232.626154)
		(width 0.09525)
		(layer "In4.Cu")
		(net "M_J_CPU0_SA_DQS_DN<6>")
	)
	(segment
		(start 391.674858 -232.583482)
		(end 392.047222 -232.583482)
		(width 0.09525)
		(layer "In4.Cu")
		(net "M_J_CPU0_SA_DQS_DN<6>")
	)
	(segment
		(start 429.836072 -211.012786)
		(end 430.73828 -211.012786)
		(width 0.16002)
		(layer "In4.Cu")
		(net "M_J_CPU0_SA_DQS_DN<6>")
	)
	(segment
		(start 385.744974 -232.664)
		(end 385.753356 -232.659174)
		(width 0.09525)
		(layer "In4.Cu")
		(net "M_J_CPU0_SA_DQS_DN<6>")
	)
	(segment
		(start 391.016236 -232.659174)
		(end 391.024618 -232.664)
		(width 0.09525)
		(layer "In4.Cu")
		(net "M_J_CPU0_SA_DQS_DN<6>")
	)
	(segment
		(start 429.002952 -211.845906)
		(end 429.836072 -211.012786)
		(width 0.16002)
		(layer "In4.Cu")
		(net "M_J_CPU0_SA_DQS_DN<6>")
	)
	(segment
		(start 388.196328 -232.659174)
		(end 388.20471 -232.664)
		(width 0.09525)
		(layer "In4.Cu")
		(net "M_J_CPU0_SA_DQS_DN<6>")
	)
	(segment
		(start 426.941234 -212.207856)
		(end 428.068486 -212.207856)
		(width 0.16002)
		(layer "In4.Cu")
		(net "M_J_CPU0_SA_DQS_DN<6>")
	)
	(segment
		(start 394.042392 -229.955598)
		(end 394.692378 -229.305612)
		(width 0.09525)
		(layer "In4.Cu")
		(net "M_J_CPU0_SA_DQS_DN<6>")
	)
	(segment
		(start 422.227756 -211.020406)
		(end 423.1767 -211.020406)
		(width 0.16002)
		(layer "In4.Cu")
		(net "M_J_CPU0_SA_DQS_DN<6>")
	)
	(segment
		(start 412.93923 -212.422232)
		(end 413.553656 -211.807806)
		(width 0.16002)
		(layer "In4.Cu")
		(net "M_J_CPU0_SA_DQS_DN<6>")
	)
	(segment
		(start 417.9316 -211.038186)
		(end 419.10127 -212.207856)
		(width 0.16002)
		(layer "In4.Cu")
		(net "M_J_CPU0_SA_DQS_DN<6>")
	)
	(segment
		(start 413.553656 -211.807806)
		(end 413.980376 -211.807806)
		(width 0.16002)
		(layer "In4.Cu")
		(net "M_J_CPU0_SA_DQS_DN<6>")
	)
	(segment
		(start 394.692378 -229.305612)
		(end 395.02842 -229.305612)
		(width 0.09525)
		(layer "In4.Cu")
		(net "M_J_CPU0_SA_DQS_DN<6>")
	)
	(segment
		(start 413.980376 -211.807806)
		(end 414.749996 -211.038186)
		(width 0.16002)
		(layer "In4.Cu")
		(net "M_J_CPU0_SA_DQS_DN<6>")
	)
	(segment
		(start 430.73828 -211.012786)
		(end 431.083466 -211.357972)
		(width 0.16002)
		(layer "In4.Cu")
		(net "M_J_CPU0_SA_DQS_DN<6>")
	)
	(segment
		(start 387.256274 -232.659174)
		(end 387.264656 -232.664)
		(width 0.09525)
		(layer "In4.Cu")
		(net "M_J_CPU0_SA_DQS_DN<6>")
	)
	(segment
		(start 423.514266 -211.357972)
		(end 426.09135 -211.357972)
		(width 0.16002)
		(layer "In4.Cu")
		(net "M_J_CPU0_SA_DQS_DN<6>")
	)
	(segment
		(start 411.070552 -211.509864)
		(end 411.443424 -211.136992)
		(width 0.16002)
		(layer "In4.Cu")
		(net "M_J_CPU0_SA_DQS_DN<6>")
	)
	(segment
		(start 410.029406 -211.136992)
		(end 410.402278 -211.509864)
		(width 0.16002)
		(layer "In4.Cu")
		(net "M_J_CPU0_SA_DQS_DN<6>")
	)
	(segment
		(start 432.070256 -211.208874)
		(end 434.726334 -211.208874)
		(width 0.16002)
		(layer "In4.Cu")
		(net "M_J_CPU0_SA_DQS_DN<6>")
	)
	(segment
		(start 414.749996 -211.038186)
		(end 417.9316 -211.038186)
		(width 0.16002)
		(layer "In4.Cu")
		(net "M_J_CPU0_SA_DQS_DN<6>")
	)
	(segment
		(start 383.496312 -232.659174)
		(end 383.504694 -232.664)
		(width 0.09525)
		(layer "In4.Cu")
		(net "M_J_CPU0_SA_DQS_DN<6>")
	)
	(segment
		(start 411.970474 -211.136992)
		(end 412.343346 -211.509864)
		(width 0.16002)
		(layer "In4.Cu")
		(net "M_J_CPU0_SA_DQS_DN<6>")
	)
	(segment
		(start 390.44499 -232.664)
		(end 390.453372 -232.659174)
		(width 0.09525)
		(layer "In4.Cu")
		(net "M_J_CPU0_SA_DQS_DN<6>")
	)
	(segment
		(start 408.184604 -212.422232)
		(end 408.93365 -212.422232)
		(width 0.16002)
		(layer "In4.Cu")
		(net "M_J_CPU0_SA_DQS_DN<6>")
	)
	(segment
		(start 412.343346 -212.226398)
		(end 412.53918 -212.422232)
		(width 0.16002)
		(layer "In4.Cu")
		(net "M_J_CPU0_SA_DQS_DN<6>")
	)
	(segment
		(start 382.556258 -232.659174)
		(end 382.56464 -232.664)
		(width 0.09525)
		(layer "In4.Cu")
		(net "M_J_CPU0_SA_DQS_DN<6>")
	)
	(segment
		(start 409.129484 -211.509864)
		(end 409.502356 -211.136992)
		(width 0.16002)
		(layer "In4.Cu")
		(net "M_J_CPU0_SA_DQS_DN<6>")
	)
	(segment
		(start 394.042392 -230.588312)
		(end 394.042392 -229.955598)
		(width 0.09525)
		(layer "In4.Cu")
		(net "M_J_CPU0_SA_DQS_DN<6>")
	)
	(segment
		(start 412.53918 -212.422232)
		(end 412.93923 -212.422232)
		(width 0.16002)
		(layer "In4.Cu")
		(net "M_J_CPU0_SA_DQS_DN<6>")
	)
	(segment
		(start 420.711376 -211.868766)
		(end 421.379396 -211.868766)
		(width 0.16002)
		(layer "In4.Cu")
		(net "M_J_CPU0_SA_DQS_DN<6>")
	)
	(segment
		(start 423.1767 -211.020406)
		(end 423.514266 -211.357972)
		(width 0.16002)
		(layer "In4.Cu")
		(net "M_J_CPU0_SA_DQS_DN<6>")
	)
	(segment
		(start 409.129484 -212.226398)
		(end 409.129484 -211.509864)
		(width 0.16002)
		(layer "In4.Cu")
		(net "M_J_CPU0_SA_DQS_DN<6>")
	)
	(segment
		(start 410.874718 -212.422232)
		(end 411.070552 -212.226398)
		(width 0.16002)
		(layer "In4.Cu")
		(net "M_J_CPU0_SA_DQS_DN<6>")
	)
	(segment
		(start 411.443424 -211.136992)
		(end 411.970474 -211.136992)
		(width 0.16002)
		(layer "In4.Cu")
		(net "M_J_CPU0_SA_DQS_DN<6>")
	)
	(segment
		(start 381.985012 -232.664)
		(end 381.993394 -232.659174)
		(width 0.09525)
		(layer "In4.Cu")
		(net "M_J_CPU0_SA_DQS_DN<6>")
	)
	(segment
		(start 412.343346 -211.509864)
		(end 412.343346 -212.226398)
		(width 0.16002)
		(layer "In4.Cu")
		(net "M_J_CPU0_SA_DQS_DN<6>")
	)
	(segment
		(start 420.372286 -212.207856)
		(end 420.711376 -211.868766)
		(width 0.16002)
		(layer "In4.Cu")
		(net "M_J_CPU0_SA_DQS_DN<6>")
	)
	(segment
		(start 431.083466 -211.357972)
		(end 431.921158 -211.357972)
		(width 0.16002)
		(layer "In4.Cu")
		(net "M_J_CPU0_SA_DQS_DN<6>")
	)
	(segment
		(start 428.430436 -211.845906)
		(end 429.002952 -211.845906)
		(width 0.16002)
		(layer "In4.Cu")
		(net "M_J_CPU0_SA_DQS_DN<6>")
	)
	(segment
		(start 410.598112 -212.422232)
		(end 410.874718 -212.422232)
		(width 0.16002)
		(layer "In4.Cu")
		(net "M_J_CPU0_SA_DQS_DN<6>")
	)
	(segment
		(start 395.611604 -228.63937)
		(end 395.628368 -228.622606)
		(width 0.09525)
		(layer "In4.Cu")
		(net "M_J_CPU0_SA_DQS_DN<6>")
	)
	(segment
		(start 392.047222 -232.583482)
		(end 394.042392 -230.588312)
		(width 0.09525)
		(layer "In4.Cu")
		(net "M_J_CPU0_SA_DQS_DN<6>")
	)
	(segment
		(start 395.611604 -228.722174)
		(end 395.611604 -228.63937)
		(width 0.09525)
		(layer "In4.Cu")
		(net "M_J_CPU0_SA_DQS_DN<6>")
	)
	(segment
		(start 378.984764 -232.334054)
		(end 379.138688 -232.599484)
		(width 0.09525)
		(layer "In4.Cu")
		(net "M_J_CPU0_SA_DQS_DN<6>")
	)
	(segment
		(start 428.068486 -212.207856)
		(end 428.430436 -211.845906)
		(width 0.16002)
		(layer "In4.Cu")
		(net "M_J_CPU0_SA_DQS_DN<6>")
	)
	(segment
		(start 410.402278 -212.226398)
		(end 410.598112 -212.422232)
		(width 0.16002)
		(layer "In4.Cu")
		(net "M_J_CPU0_SA_DQS_DN<6>")
	)
	(segment
		(start 421.379396 -211.868766)
		(end 422.227756 -211.020406)
		(width 0.16002)
		(layer "In4.Cu")
		(net "M_J_CPU0_SA_DQS_DN<6>")
	)
	(segment
		(start 398.455642 -225.795332)
		(end 398.455642 -222.151194)
		(width 0.16002)
		(layer "In4.Cu")
		(net "M_J_CPU0_SA_DQS_DN<6>")
	)
	(segment
		(start 386.685028 -232.664)
		(end 386.69341 -232.659174)
		(width 0.09525)
		(layer "In4.Cu")
		(net "M_J_CPU0_SA_DQS_DN<6>")
	)
	(segment
		(start 398.455642 -222.151194)
		(end 408.184604 -212.422232)
		(width 0.16002)
		(layer "In4.Cu")
		(net "M_J_CPU0_SA_DQS_DN<6>")
	)
	(segment
		(start 434.726334 -211.208874)
		(end 435.000146 -210.935062)
		(width 0.16002)
		(layer "In4.Cu")
		(net "M_J_CPU0_SA_DQS_DN<6>")
	)
	(segment
		(start 410.402278 -211.509864)
		(end 410.402278 -212.226398)
		(width 0.16002)
		(layer "In4.Cu")
		(net "M_J_CPU0_SA_DQS_DN<6>")
	)
	(segment
		(start 395.628368 -228.622606)
		(end 398.455642 -225.795332)
		(width 0.16002)
		(layer "In4.Cu")
		(net "M_J_CPU0_SA_DQS_DN<6>")
	)
	(segment
		(start 431.921158 -211.357972)
		(end 432.070256 -211.208874)
		(width 0.16002)
		(layer "In4.Cu")
		(net "M_J_CPU0_SA_DQS_DN<6>")
	)
	(segment
		(start 411.070552 -212.226398)
		(end 411.070552 -211.509864)
		(width 0.16002)
		(layer "In4.Cu")
		(net "M_J_CPU0_SA_DQS_DN<6>")
	)
	(segment
		(start 408.93365 -212.422232)
		(end 409.129484 -212.226398)
		(width 0.16002)
		(layer "In4.Cu")
		(net "M_J_CPU0_SA_DQS_DN<6>")
	)
	(arc
		(start 383.873502 -232.659174)
		(mid 384.154934 -232.583419)
		(end 384.436366 -232.659174)
		(width 0.09525)
		(layer "In4.Cu")
		(net "M_J_CPU0_SA_DQS_DN<6>")
	)
	(arc
		(start 384.436366 -232.659174)
		(mid 384.624834 -232.709851)
		(end 384.813302 -232.659174)
		(width 0.09525)
		(layer "In4.Cu")
		(net "M_J_CPU0_SA_DQS_DN<6>")
	)
	(arc
		(start 387.264656 -232.664)
		(mid 387.449688 -232.709914)
		(end 387.633464 -232.659174)
		(width 0.09525)
		(layer "In4.Cu")
		(net "M_J_CPU0_SA_DQS_DN<6>")
	)
	(arc
		(start 388.573518 -232.659174)
		(mid 388.85495 -232.583419)
		(end 389.136382 -232.659174)
		(width 0.09525)
		(layer "In4.Cu")
		(net "M_J_CPU0_SA_DQS_DN<6>")
	)
	(arc
		(start 384.813302 -232.659174)
		(mid 385.094734 -232.583419)
		(end 385.376166 -232.659174)
		(width 0.09525)
		(layer "In4.Cu")
		(net "M_J_CPU0_SA_DQS_DN<6>")
	)
	(arc
		(start 388.20471 -232.664)
		(mid 388.389742 -232.709914)
		(end 388.573518 -232.659174)
		(width 0.09525)
		(layer "In4.Cu")
		(net "M_J_CPU0_SA_DQS_DN<6>")
	)
	(arc
		(start 386.31622 -232.659174)
		(mid 386.499995 -232.709946)
		(end 386.685028 -232.664)
		(width 0.09525)
		(layer "In4.Cu")
		(net "M_J_CPU0_SA_DQS_DN<6>")
	)
	(arc
		(start 382.56464 -232.664)
		(mid 382.749672 -232.709914)
		(end 382.933448 -232.659174)
		(width 0.09525)
		(layer "In4.Cu")
		(net "M_J_CPU0_SA_DQS_DN<6>")
	)
	(arc
		(start 391.024618 -232.664)
		(mid 391.20965 -232.709914)
		(end 391.393426 -232.659174)
		(width 0.09525)
		(layer "In4.Cu")
		(net "M_J_CPU0_SA_DQS_DN<6>")
	)
	(arc
		(start 385.753356 -232.659174)
		(mid 386.034788 -232.583419)
		(end 386.31622 -232.659174)
		(width 0.09525)
		(layer "In4.Cu")
		(net "M_J_CPU0_SA_DQS_DN<6>")
	)
	(arc
		(start 390.453372 -232.659174)
		(mid 390.734804 -232.583419)
		(end 391.016236 -232.659174)
		(width 0.09525)
		(layer "In4.Cu")
		(net "M_J_CPU0_SA_DQS_DN<6>")
	)
	(arc
		(start 380.113286 -232.659174)
		(mid 380.394718 -232.583419)
		(end 380.67615 -232.659174)
		(width 0.09525)
		(layer "In4.Cu")
		(net "M_J_CPU0_SA_DQS_DN<6>")
	)
	(arc
		(start 387.633464 -232.659174)
		(mid 387.914896 -232.583419)
		(end 388.196328 -232.659174)
		(width 0.09525)
		(layer "In4.Cu")
		(net "M_J_CPU0_SA_DQS_DN<6>")
	)
	(arc
		(start 379.73635 -232.659174)
		(mid 379.924818 -232.709851)
		(end 380.113286 -232.659174)
		(width 0.09525)
		(layer "In4.Cu")
		(net "M_J_CPU0_SA_DQS_DN<6>")
	)
	(arc
		(start 386.69341 -232.659174)
		(mid 386.974842 -232.583419)
		(end 387.256274 -232.659174)
		(width 0.09525)
		(layer "In4.Cu")
		(net "M_J_CPU0_SA_DQS_DN<6>")
	)
	(arc
		(start 379.2601 -232.618026)
		(mid 379.502842 -232.585256)
		(end 379.73635 -232.659174)
		(width 0.09525)
		(layer "In4.Cu")
		(net "M_J_CPU0_SA_DQS_DN<6>")
	)
	(arc
		(start 383.504694 -232.664)
		(mid 383.689726 -232.709914)
		(end 383.873502 -232.659174)
		(width 0.09525)
		(layer "In4.Cu")
		(net "M_J_CPU0_SA_DQS_DN<6>")
	)
	(arc
		(start 389.136382 -232.659174)
		(mid 389.32485 -232.709851)
		(end 389.513318 -232.659174)
		(width 0.09525)
		(layer "In4.Cu")
		(net "M_J_CPU0_SA_DQS_DN<6>")
	)
	(arc
		(start 381.616204 -232.659174)
		(mid 381.799979 -232.709946)
		(end 381.985012 -232.664)
		(width 0.09525)
		(layer "In4.Cu")
		(net "M_J_CPU0_SA_DQS_DN<6>")
	)
	(arc
		(start 390.076182 -232.659174)
		(mid 390.259957 -232.709946)
		(end 390.44499 -232.664)
		(width 0.09525)
		(layer "In4.Cu")
		(net "M_J_CPU0_SA_DQS_DN<6>")
	)
	(arc
		(start 389.513318 -232.659174)
		(mid 389.79475 -232.583419)
		(end 390.076182 -232.659174)
		(width 0.09525)
		(layer "In4.Cu")
		(net "M_J_CPU0_SA_DQS_DN<6>")
	)
	(arc
		(start 385.376166 -232.659174)
		(mid 385.559941 -232.709946)
		(end 385.744974 -232.664)
		(width 0.09525)
		(layer "In4.Cu")
		(net "M_J_CPU0_SA_DQS_DN<6>")
	)
	(arc
		(start 381.05334 -232.659174)
		(mid 381.334772 -232.583419)
		(end 381.616204 -232.659174)
		(width 0.09525)
		(layer "In4.Cu")
		(net "M_J_CPU0_SA_DQS_DN<6>")
	)
	(arc
		(start 391.393426 -232.659174)
		(mid 391.529133 -232.602689)
		(end 391.674858 -232.583482)
		(width 0.09525)
		(layer "In4.Cu")
		(net "M_J_CPU0_SA_DQS_DN<6>")
	)
	(arc
		(start 382.933448 -232.659174)
		(mid 383.21488 -232.583419)
		(end 383.496312 -232.659174)
		(width 0.09525)
		(layer "In4.Cu")
		(net "M_J_CPU0_SA_DQS_DN<6>")
	)
	(arc
		(start 381.993394 -232.659174)
		(mid 382.274826 -232.583419)
		(end 382.556258 -232.659174)
		(width 0.09525)
		(layer "In4.Cu")
		(net "M_J_CPU0_SA_DQS_DN<6>")
	)
	(arc
		(start 380.67615 -232.659174)
		(mid 380.859925 -232.709946)
		(end 381.044958 -232.664)
		(width 0.09525)
		(layer "In4.Cu")
		(net "M_J_CPU0_SA_DQS_DN<6>")
	)
	(arc
		(start 379.239526 -232.626154)
		(mid 379.249774 -232.621991)
		(end 379.2601 -232.618026)
		(width 0.09525)
		(layer "In4.Cu")
		(net "M_J_CPU0_SA_DQS_DN<6>")
	)
	(segment
		(start 378.517912 -227.74021)
		(end 378.984764 -227.474272)
		(width 0.12954)
		(layer "F.Cu")
		(net "M_J_CPU0_SA_DQS_DN<5>")
	)
	(segment
		(start 404.295102 -207.63738)
		(end 404.582376 -207.350106)
		(width 0.16002)
		(layer "In4.Cu")
		(net "M_J_CPU0_SA_DQS_DN<5>")
	)
	(segment
		(start 422.227756 -201.670412)
		(end 423.1767 -201.670412)
		(width 0.16002)
		(layer "In4.Cu")
		(net "M_J_CPU0_SA_DQS_DN<5>")
	)
	(segment
		(start 407.09215 -204.840332)
		(end 407.32964 -204.602842)
		(width 0.16002)
		(layer "In4.Cu")
		(net "M_J_CPU0_SA_DQS_DN<5>")
	)
	(segment
		(start 403.527514 -207.63738)
		(end 404.295102 -207.63738)
		(width 0.16002)
		(layer "In4.Cu")
		(net "M_J_CPU0_SA_DQS_DN<5>")
	)
	(segment
		(start 387.256274 -227.799392)
		(end 387.264656 -227.804218)
		(width 0.09525)
		(layer "In4.Cu")
		(net "M_J_CPU0_SA_DQS_DN<5>")
	)
	(segment
		(start 385.744974 -227.804218)
		(end 385.753356 -227.799392)
		(width 0.09525)
		(layer "In4.Cu")
		(net "M_J_CPU0_SA_DQS_DN<5>")
	)
	(segment
		(start 405.956008 -205.976474)
		(end 405.956008 -205.255622)
		(width 0.16002)
		(layer "In4.Cu")
		(net "M_J_CPU0_SA_DQS_DN<5>")
	)
	(segment
		(start 407.32964 -203.88199)
		(end 407.74493 -203.4667)
		(width 0.16002)
		(layer "In4.Cu")
		(net "M_J_CPU0_SA_DQS_DN<5>")
	)
	(segment
		(start 410.14269 -202.848972)
		(end 410.338524 -202.653138)
		(width 0.16002)
		(layer "In4.Cu")
		(net "M_J_CPU0_SA_DQS_DN<5>")
	)
	(segment
		(start 407.74493 -203.4667)
		(end 408.465782 -203.4667)
		(width 0.16002)
		(layer "In4.Cu")
		(net "M_J_CPU0_SA_DQS_DN<5>")
	)
	(segment
		(start 393.023598 -221.90075)
		(end 393.023598 -221.744032)
		(width 0.09525)
		(layer "In4.Cu")
		(net "M_J_CPU0_SA_DQS_DN<5>")
	)
	(segment
		(start 388.196328 -227.799392)
		(end 388.20471 -227.804218)
		(width 0.09525)
		(layer "In4.Cu")
		(net "M_J_CPU0_SA_DQS_DN<5>")
	)
	(segment
		(start 409.08351 -202.848972)
		(end 410.14269 -202.848972)
		(width 0.16002)
		(layer "In4.Cu")
		(net "M_J_CPU0_SA_DQS_DN<5>")
	)
	(segment
		(start 390.923272 -225.369374)
		(end 390.955784 -225.350578)
		(width 0.09525)
		(layer "In4.Cu")
		(net "M_J_CPU0_SA_DQS_DN<5>")
	)
	(segment
		(start 414.749996 -201.688192)
		(end 417.9316 -201.688192)
		(width 0.16002)
		(layer "In4.Cu")
		(net "M_J_CPU0_SA_DQS_DN<5>")
	)
	(segment
		(start 404.582376 -206.629254)
		(end 404.997666 -206.213964)
		(width 0.16002)
		(layer "In4.Cu")
		(net "M_J_CPU0_SA_DQS_DN<5>")
	)
	(segment
		(start 426.09135 -202.007978)
		(end 426.941234 -202.857862)
		(width 0.16002)
		(layer "In4.Cu")
		(net "M_J_CPU0_SA_DQS_DN<5>")
	)
	(segment
		(start 392.977624 -221.698058)
		(end 392.977624 -221.442026)
		(width 0.09525)
		(layer "In4.Cu")
		(net "M_J_CPU0_SA_DQS_DN<5>")
	)
	(segment
		(start 386.685028 -227.804218)
		(end 386.69341 -227.799392)
		(width 0.09525)
		(layer "In4.Cu")
		(net "M_J_CPU0_SA_DQS_DN<5>")
	)
	(segment
		(start 407.32964 -204.602842)
		(end 407.32964 -203.88199)
		(width 0.16002)
		(layer "In4.Cu")
		(net "M_J_CPU0_SA_DQS_DN<5>")
	)
	(segment
		(start 389.513318 -227.799392)
		(end 389.54583 -227.780596)
		(width 0.09525)
		(layer "In4.Cu")
		(net "M_J_CPU0_SA_DQS_DN<5>")
	)
	(segment
		(start 413.162496 -202.848972)
		(end 413.553656 -202.457812)
		(width 0.16002)
		(layer "In4.Cu")
		(net "M_J_CPU0_SA_DQS_DN<5>")
	)
	(segment
		(start 392.918442 -221.359222)
		(end 392.918442 -218.246452)
		(width 0.16002)
		(layer "In4.Cu")
		(net "M_J_CPU0_SA_DQS_DN<5>")
	)
	(segment
		(start 391.355326 -224.581466)
		(end 391.393426 -224.559368)
		(width 0.09525)
		(layer "In4.Cu")
		(net "M_J_CPU0_SA_DQS_DN<5>")
	)
	(segment
		(start 381.044958 -227.804218)
		(end 381.05334 -227.799392)
		(width 0.09525)
		(layer "In4.Cu")
		(net "M_J_CPU0_SA_DQS_DN<5>")
	)
	(segment
		(start 383.496312 -227.799392)
		(end 383.504694 -227.804218)
		(width 0.09525)
		(layer "In4.Cu")
		(net "M_J_CPU0_SA_DQS_DN<5>")
	)
	(segment
		(start 405.718518 -206.213964)
		(end 405.956008 -205.976474)
		(width 0.16002)
		(layer "In4.Cu")
		(net "M_J_CPU0_SA_DQS_DN<5>")
	)
	(segment
		(start 391.393426 -224.559368)
		(end 391.424922 -224.54108)
		(width 0.09525)
		(layer "In4.Cu")
		(net "M_J_CPU0_SA_DQS_DN<5>")
	)
	(segment
		(start 428.068486 -202.857862)
		(end 428.430436 -202.495912)
		(width 0.16002)
		(layer "In4.Cu")
		(net "M_J_CPU0_SA_DQS_DN<5>")
	)
	(segment
		(start 428.430436 -202.495912)
		(end 429.002952 -202.495912)
		(width 0.16002)
		(layer "In4.Cu")
		(net "M_J_CPU0_SA_DQS_DN<5>")
	)
	(segment
		(start 432.070256 -201.85888)
		(end 434.726334 -201.85888)
		(width 0.16002)
		(layer "In4.Cu")
		(net "M_J_CPU0_SA_DQS_DN<5>")
	)
	(segment
		(start 410.338524 -202.033124)
		(end 410.711396 -201.660252)
		(width 0.16002)
		(layer "In4.Cu")
		(net "M_J_CPU0_SA_DQS_DN<5>")
	)
	(segment
		(start 411.238446 -201.660252)
		(end 411.611318 -202.033124)
		(width 0.16002)
		(layer "In4.Cu")
		(net "M_J_CPU0_SA_DQS_DN<5>")
	)
	(segment
		(start 410.711396 -201.660252)
		(end 411.238446 -201.660252)
		(width 0.16002)
		(layer "In4.Cu")
		(net "M_J_CPU0_SA_DQS_DN<5>")
	)
	(segment
		(start 390.453372 -226.17938)
		(end 390.485884 -226.160584)
		(width 0.09525)
		(layer "In4.Cu")
		(net "M_J_CPU0_SA_DQS_DN<5>")
	)
	(segment
		(start 382.556258 -227.799392)
		(end 382.56464 -227.804218)
		(width 0.09525)
		(layer "In4.Cu")
		(net "M_J_CPU0_SA_DQS_DN<5>")
	)
	(segment
		(start 426.941234 -202.857862)
		(end 428.068486 -202.857862)
		(width 0.16002)
		(layer "In4.Cu")
		(net "M_J_CPU0_SA_DQS_DN<5>")
	)
	(segment
		(start 431.083466 -202.007978)
		(end 431.921158 -202.007978)
		(width 0.16002)
		(layer "In4.Cu")
		(net "M_J_CPU0_SA_DQS_DN<5>")
	)
	(segment
		(start 392.33348 -222.939356)
		(end 392.36269 -222.922592)
		(width 0.09525)
		(layer "In4.Cu")
		(net "M_J_CPU0_SA_DQS_DN<5>")
	)
	(segment
		(start 413.553656 -202.457812)
		(end 413.980376 -202.457812)
		(width 0.16002)
		(layer "In4.Cu")
		(net "M_J_CPU0_SA_DQS_DN<5>")
	)
	(segment
		(start 404.582376 -207.350106)
		(end 404.582376 -206.629254)
		(width 0.16002)
		(layer "In4.Cu")
		(net "M_J_CPU0_SA_DQS_DN<5>")
	)
	(segment
		(start 391.825226 -223.77146)
		(end 391.863326 -223.749362)
		(width 0.09525)
		(layer "In4.Cu")
		(net "M_J_CPU0_SA_DQS_DN<5>")
	)
	(segment
		(start 411.807152 -202.848972)
		(end 413.162496 -202.848972)
		(width 0.16002)
		(layer "In4.Cu")
		(net "M_J_CPU0_SA_DQS_DN<5>")
	)
	(segment
		(start 391.863326 -223.749362)
		(end 391.895838 -223.730566)
		(width 0.09525)
		(layer "In4.Cu")
		(net "M_J_CPU0_SA_DQS_DN<5>")
	)
	(segment
		(start 404.997666 -206.213964)
		(end 405.718518 -206.213964)
		(width 0.16002)
		(layer "In4.Cu")
		(net "M_J_CPU0_SA_DQS_DN<5>")
	)
	(segment
		(start 389.945372 -227.011484)
		(end 389.983472 -226.989386)
		(width 0.09525)
		(layer "In4.Cu")
		(net "M_J_CPU0_SA_DQS_DN<5>")
	)
	(segment
		(start 434.726334 -201.85888)
		(end 435.000146 -201.585068)
		(width 0.16002)
		(layer "In4.Cu")
		(net "M_J_CPU0_SA_DQS_DN<5>")
	)
	(segment
		(start 420.711376 -202.518772)
		(end 421.379396 -202.518772)
		(width 0.16002)
		(layer "In4.Cu")
		(net "M_J_CPU0_SA_DQS_DN<5>")
	)
	(segment
		(start 390.88822 -225.389948)
		(end 390.923272 -225.369374)
		(width 0.09525)
		(layer "In4.Cu")
		(net "M_J_CPU0_SA_DQS_DN<5>")
	)
	(segment
		(start 392.788902 -222.135446)
		(end 393.023598 -221.90075)
		(width 0.09525)
		(layer "In4.Cu")
		(net "M_J_CPU0_SA_DQS_DN<5>")
	)
	(segment
		(start 411.611318 -202.653138)
		(end 411.807152 -202.848972)
		(width 0.16002)
		(layer "In4.Cu")
		(net "M_J_CPU0_SA_DQS_DN<5>")
	)
	(segment
		(start 392.918442 -221.382844)
		(end 392.918442 -221.359222)
		(width 0.09525)
		(layer "In4.Cu")
		(net "M_J_CPU0_SA_DQS_DN<5>")
	)
	(segment
		(start 405.956008 -205.255622)
		(end 406.371298 -204.840332)
		(width 0.16002)
		(layer "In4.Cu")
		(net "M_J_CPU0_SA_DQS_DN<5>")
	)
	(segment
		(start 413.980376 -202.457812)
		(end 414.749996 -201.688192)
		(width 0.16002)
		(layer "In4.Cu")
		(net "M_J_CPU0_SA_DQS_DN<5>")
	)
	(segment
		(start 393.023598 -221.744032)
		(end 392.977624 -221.698058)
		(width 0.09525)
		(layer "In4.Cu")
		(net "M_J_CPU0_SA_DQS_DN<5>")
	)
	(segment
		(start 421.379396 -202.518772)
		(end 422.227756 -201.670412)
		(width 0.16002)
		(layer "In4.Cu")
		(net "M_J_CPU0_SA_DQS_DN<5>")
	)
	(segment
		(start 429.002952 -202.495912)
		(end 429.836072 -201.662792)
		(width 0.16002)
		(layer "In4.Cu")
		(net "M_J_CPU0_SA_DQS_DN<5>")
	)
	(segment
		(start 430.73828 -201.662792)
		(end 431.083466 -202.007978)
		(width 0.16002)
		(layer "In4.Cu")
		(net "M_J_CPU0_SA_DQS_DN<5>")
	)
	(segment
		(start 420.372286 -202.857862)
		(end 420.711376 -202.518772)
		(width 0.16002)
		(layer "In4.Cu")
		(net "M_J_CPU0_SA_DQS_DN<5>")
	)
	(segment
		(start 390.415272 -226.201478)
		(end 390.453372 -226.17938)
		(width 0.09525)
		(layer "In4.Cu")
		(net "M_J_CPU0_SA_DQS_DN<5>")
	)
	(segment
		(start 379.138688 -227.739702)
		(end 379.239526 -227.766372)
		(width 0.09525)
		(layer "In4.Cu")
		(net "M_J_CPU0_SA_DQS_DN<5>")
	)
	(segment
		(start 410.338524 -202.653138)
		(end 410.338524 -202.033124)
		(width 0.16002)
		(layer "In4.Cu")
		(net "M_J_CPU0_SA_DQS_DN<5>")
	)
	(segment
		(start 423.514266 -202.007978)
		(end 426.09135 -202.007978)
		(width 0.16002)
		(layer "In4.Cu")
		(net "M_J_CPU0_SA_DQS_DN<5>")
	)
	(segment
		(start 429.836072 -201.662792)
		(end 430.73828 -201.662792)
		(width 0.16002)
		(layer "In4.Cu")
		(net "M_J_CPU0_SA_DQS_DN<5>")
	)
	(segment
		(start 381.985012 -227.804218)
		(end 381.993394 -227.799392)
		(width 0.09525)
		(layer "In4.Cu")
		(net "M_J_CPU0_SA_DQS_DN<5>")
	)
	(segment
		(start 392.765026 -222.151956)
		(end 392.788902 -222.135446)
		(width 0.09525)
		(layer "In4.Cu")
		(net "M_J_CPU0_SA_DQS_DN<5>")
	)
	(segment
		(start 378.984764 -227.474272)
		(end 379.138688 -227.739702)
		(width 0.09525)
		(layer "In4.Cu")
		(net "M_J_CPU0_SA_DQS_DN<5>")
	)
	(segment
		(start 389.983472 -226.989386)
		(end 390.014968 -226.971098)
		(width 0.09525)
		(layer "In4.Cu")
		(net "M_J_CPU0_SA_DQS_DN<5>")
	)
	(segment
		(start 392.522202 -222.614236)
		(end 392.522456 -222.614236)
		(width 0.09525)
		(layer "In4.Cu")
		(net "M_J_CPU0_SA_DQS_DN<5>")
	)
	(segment
		(start 431.921158 -202.007978)
		(end 432.070256 -201.85888)
		(width 0.16002)
		(layer "In4.Cu")
		(net "M_J_CPU0_SA_DQS_DN<5>")
	)
	(segment
		(start 392.977624 -221.442026)
		(end 392.918442 -221.382844)
		(width 0.09525)
		(layer "In4.Cu")
		(net "M_J_CPU0_SA_DQS_DN<5>")
	)
	(segment
		(start 408.465782 -203.4667)
		(end 409.08351 -202.848972)
		(width 0.16002)
		(layer "In4.Cu")
		(net "M_J_CPU0_SA_DQS_DN<5>")
	)
	(segment
		(start 411.611318 -202.033124)
		(end 411.611318 -202.653138)
		(width 0.16002)
		(layer "In4.Cu")
		(net "M_J_CPU0_SA_DQS_DN<5>")
	)
	(segment
		(start 423.1767 -201.670412)
		(end 423.514266 -202.007978)
		(width 0.16002)
		(layer "In4.Cu")
		(net "M_J_CPU0_SA_DQS_DN<5>")
	)
	(segment
		(start 419.10127 -202.857862)
		(end 420.372286 -202.857862)
		(width 0.16002)
		(layer "In4.Cu")
		(net "M_J_CPU0_SA_DQS_DN<5>")
	)
	(segment
		(start 417.9316 -201.688192)
		(end 419.10127 -202.857862)
		(width 0.16002)
		(layer "In4.Cu")
		(net "M_J_CPU0_SA_DQS_DN<5>")
	)
	(segment
		(start 392.29538 -222.961454)
		(end 392.33348 -222.939356)
		(width 0.09525)
		(layer "In4.Cu")
		(net "M_J_CPU0_SA_DQS_DN<5>")
	)
	(segment
		(start 406.371298 -204.840332)
		(end 407.09215 -204.840332)
		(width 0.16002)
		(layer "In4.Cu")
		(net "M_J_CPU0_SA_DQS_DN<5>")
	)
	(segment
		(start 392.918442 -218.246452)
		(end 403.527514 -207.63738)
		(width 0.16002)
		(layer "In4.Cu")
		(net "M_J_CPU0_SA_DQS_DN<5>")
	)
	(arc
		(start 391.895838 -223.730566)
		(mid 392.011112 -223.596288)
		(end 392.052556 -223.424242)
		(width 0.09525)
		(layer "In4.Cu")
		(net "M_J_CPU0_SA_DQS_DN<5>")
	)
	(arc
		(start 390.485884 -226.160584)
		(mid 390.601158 -226.026306)
		(end 390.642602 -225.85426)
		(width 0.09525)
		(layer "In4.Cu")
		(net "M_J_CPU0_SA_DQS_DN<5>")
	)
	(arc
		(start 392.36269 -222.922592)
		(mid 392.479994 -222.787831)
		(end 392.522202 -222.614236)
		(width 0.09525)
		(layer "In4.Cu")
		(net "M_J_CPU0_SA_DQS_DN<5>")
	)
	(arc
		(start 389.54583 -227.780596)
		(mid 389.661104 -227.646318)
		(end 389.702548 -227.474272)
		(width 0.09525)
		(layer "In4.Cu")
		(net "M_J_CPU0_SA_DQS_DN<5>")
	)
	(arc
		(start 382.56464 -227.804218)
		(mid 382.749672 -227.850132)
		(end 382.933448 -227.799392)
		(width 0.09525)
		(layer "In4.Cu")
		(net "M_J_CPU0_SA_DQS_DN<5>")
	)
	(arc
		(start 391.112502 -225.044254)
		(mid 391.176899 -224.782948)
		(end 391.355326 -224.581466)
		(width 0.09525)
		(layer "In4.Cu")
		(net "M_J_CPU0_SA_DQS_DN<5>")
	)
	(arc
		(start 389.136382 -227.799392)
		(mid 389.32485 -227.850069)
		(end 389.513318 -227.799392)
		(width 0.09525)
		(layer "In4.Cu")
		(net "M_J_CPU0_SA_DQS_DN<5>")
	)
	(arc
		(start 380.67615 -227.799392)
		(mid 380.859925 -227.850164)
		(end 381.044958 -227.804218)
		(width 0.09525)
		(layer "In4.Cu")
		(net "M_J_CPU0_SA_DQS_DN<5>")
	)
	(arc
		(start 382.933448 -227.799392)
		(mid 383.21488 -227.723637)
		(end 383.496312 -227.799392)
		(width 0.09525)
		(layer "In4.Cu")
		(net "M_J_CPU0_SA_DQS_DN<5>")
	)
	(arc
		(start 381.616204 -227.799392)
		(mid 381.799979 -227.850164)
		(end 381.985012 -227.804218)
		(width 0.09525)
		(layer "In4.Cu")
		(net "M_J_CPU0_SA_DQS_DN<5>")
	)
	(arc
		(start 390.642602 -225.85426)
		(mid 390.707849 -225.591657)
		(end 390.88822 -225.389948)
		(width 0.09525)
		(layer "In4.Cu")
		(net "M_J_CPU0_SA_DQS_DN<5>")
	)
	(arc
		(start 386.69341 -227.799392)
		(mid 386.974842 -227.723637)
		(end 387.256274 -227.799392)
		(width 0.09525)
		(layer "In4.Cu")
		(net "M_J_CPU0_SA_DQS_DN<5>")
	)
	(arc
		(start 384.813302 -227.799392)
		(mid 385.094734 -227.723637)
		(end 385.376166 -227.799392)
		(width 0.09525)
		(layer "In4.Cu")
		(net "M_J_CPU0_SA_DQS_DN<5>")
	)
	(arc
		(start 392.052556 -223.424242)
		(mid 392.116953 -223.162936)
		(end 392.29538 -222.961454)
		(width 0.09525)
		(layer "In4.Cu")
		(net "M_J_CPU0_SA_DQS_DN<5>")
	)
	(arc
		(start 381.993394 -227.799392)
		(mid 382.274826 -227.723637)
		(end 382.556258 -227.799392)
		(width 0.09525)
		(layer "In4.Cu")
		(net "M_J_CPU0_SA_DQS_DN<5>")
	)
	(arc
		(start 387.264656 -227.804218)
		(mid 387.449688 -227.850132)
		(end 387.633464 -227.799392)
		(width 0.09525)
		(layer "In4.Cu")
		(net "M_J_CPU0_SA_DQS_DN<5>")
	)
	(arc
		(start 383.873502 -227.799392)
		(mid 384.154934 -227.723637)
		(end 384.436366 -227.799392)
		(width 0.09525)
		(layer "In4.Cu")
		(net "M_J_CPU0_SA_DQS_DN<5>")
	)
	(arc
		(start 390.172448 -226.664266)
		(mid 390.236845 -226.40296)
		(end 390.415272 -226.201478)
		(width 0.09525)
		(layer "In4.Cu")
		(net "M_J_CPU0_SA_DQS_DN<5>")
	)
	(arc
		(start 386.31622 -227.799392)
		(mid 386.499995 -227.850164)
		(end 386.685028 -227.804218)
		(width 0.09525)
		(layer "In4.Cu")
		(net "M_J_CPU0_SA_DQS_DN<5>")
	)
	(arc
		(start 388.573518 -227.799392)
		(mid 388.85495 -227.723637)
		(end 389.136382 -227.799392)
		(width 0.09525)
		(layer "In4.Cu")
		(net "M_J_CPU0_SA_DQS_DN<5>")
	)
	(arc
		(start 384.436366 -227.799392)
		(mid 384.624834 -227.850069)
		(end 384.813302 -227.799392)
		(width 0.09525)
		(layer "In4.Cu")
		(net "M_J_CPU0_SA_DQS_DN<5>")
	)
	(arc
		(start 379.239526 -227.766372)
		(mid 379.49181 -227.724678)
		(end 379.73635 -227.799392)
		(width 0.09525)
		(layer "In4.Cu")
		(net "M_J_CPU0_SA_DQS_DN<5>")
	)
	(arc
		(start 390.955784 -225.350578)
		(mid 391.071058 -225.2163)
		(end 391.112502 -225.044254)
		(width 0.09525)
		(layer "In4.Cu")
		(net "M_J_CPU0_SA_DQS_DN<5>")
	)
	(arc
		(start 379.73635 -227.799392)
		(mid 379.924818 -227.850069)
		(end 380.113286 -227.799392)
		(width 0.09525)
		(layer "In4.Cu")
		(net "M_J_CPU0_SA_DQS_DN<5>")
	)
	(arc
		(start 385.376166 -227.799392)
		(mid 385.559941 -227.850164)
		(end 385.744974 -227.804218)
		(width 0.09525)
		(layer "In4.Cu")
		(net "M_J_CPU0_SA_DQS_DN<5>")
	)
	(arc
		(start 389.702548 -227.474272)
		(mid 389.766945 -227.212966)
		(end 389.945372 -227.011484)
		(width 0.09525)
		(layer "In4.Cu")
		(net "M_J_CPU0_SA_DQS_DN<5>")
	)
	(arc
		(start 390.014968 -226.971098)
		(mid 390.130766 -226.836704)
		(end 390.172448 -226.664266)
		(width 0.09525)
		(layer "In4.Cu")
		(net "M_J_CPU0_SA_DQS_DN<5>")
	)
	(arc
		(start 387.633464 -227.799392)
		(mid 387.914896 -227.723637)
		(end 388.196328 -227.799392)
		(width 0.09525)
		(layer "In4.Cu")
		(net "M_J_CPU0_SA_DQS_DN<5>")
	)
	(arc
		(start 388.20471 -227.804218)
		(mid 388.389742 -227.850132)
		(end 388.573518 -227.799392)
		(width 0.09525)
		(layer "In4.Cu")
		(net "M_J_CPU0_SA_DQS_DN<5>")
	)
	(arc
		(start 385.753356 -227.799392)
		(mid 386.034788 -227.723637)
		(end 386.31622 -227.799392)
		(width 0.09525)
		(layer "In4.Cu")
		(net "M_J_CPU0_SA_DQS_DN<5>")
	)
	(arc
		(start 391.582402 -224.234248)
		(mid 391.646799 -223.972942)
		(end 391.825226 -223.77146)
		(width 0.09525)
		(layer "In4.Cu")
		(net "M_J_CPU0_SA_DQS_DN<5>")
	)
	(arc
		(start 392.522456 -222.614236)
		(mid 392.586776 -222.353201)
		(end 392.765026 -222.151956)
		(width 0.09525)
		(layer "In4.Cu")
		(net "M_J_CPU0_SA_DQS_DN<5>")
	)
	(arc
		(start 381.05334 -227.799392)
		(mid 381.334772 -227.723637)
		(end 381.616204 -227.799392)
		(width 0.09525)
		(layer "In4.Cu")
		(net "M_J_CPU0_SA_DQS_DN<5>")
	)
	(arc
		(start 383.504694 -227.804218)
		(mid 383.689726 -227.850132)
		(end 383.873502 -227.799392)
		(width 0.09525)
		(layer "In4.Cu")
		(net "M_J_CPU0_SA_DQS_DN<5>")
	)
	(arc
		(start 391.424922 -224.54108)
		(mid 391.54072 -224.406686)
		(end 391.582402 -224.234248)
		(width 0.09525)
		(layer "In4.Cu")
		(net "M_J_CPU0_SA_DQS_DN<5>")
	)
	(arc
		(start 380.113286 -227.799392)
		(mid 380.394718 -227.723637)
		(end 380.67615 -227.799392)
		(width 0.09525)
		(layer "In4.Cu")
		(net "M_J_CPU0_SA_DQS_DN<5>")
	)
	(segment
		(start 380.39802 -247.1801)
		(end 380.864872 -246.914162)
		(width 0.12954)
		(layer "F.Cu")
		(net "M_J_CPU0_SA_DQS_DN<4>")
	)
	(segment
		(start 382.56464 -246.584216)
		(end 382.556258 -246.589042)
		(width 0.09525)
		(layer "In4.Cu")
		(net "M_J_CPU0_SA_DQS_DN<4>")
	)
	(segment
		(start 381.05334 -246.589042)
		(end 381.044958 -246.584216)
		(width 0.09525)
		(layer "In4.Cu")
		(net "M_J_CPU0_SA_DQS_DN<4>")
	)
	(segment
		(start 380.734316 -246.561864)
		(end 380.710948 -246.648732)
		(width 0.09525)
		(layer "In4.Cu")
		(net "M_J_CPU0_SA_DQS_DN<4>")
	)
	(segment
		(start 436.87746 -238.892588)
		(end 435.697376 -238.892588)
		(width 0.16002)
		(layer "In4.Cu")
		(net "M_J_CPU0_SA_DQS_DN<4>")
	)
	(segment
		(start 425.802298 -238.562134)
		(end 424.952414 -237.71225)
		(width 0.16002)
		(layer "In4.Cu")
		(net "M_J_CPU0_SA_DQS_DN<4>")
	)
	(segment
		(start 421.570912 -238.917988)
		(end 420.739316 -238.917988)
		(width 0.16002)
		(layer "In4.Cu")
		(net "M_J_CPU0_SA_DQS_DN<4>")
	)
	(segment
		(start 395.61897 -246.177054)
		(end 394.916152 -246.937022)
		(width 0.09525)
		(layer "In4.Cu")
		(net "M_J_CPU0_SA_DQS_DN<4>")
	)
	(segment
		(start 428.356776 -238.938308)
		(end 427.980602 -238.562134)
		(width 0.16002)
		(layer "In4.Cu")
		(net "M_J_CPU0_SA_DQS_DN<4>")
	)
	(segment
		(start 414.07334 -238.905288)
		(end 412.227776 -238.905288)
		(width 0.16002)
		(layer "In4.Cu")
		(net "M_J_CPU0_SA_DQS_DN<4>")
	)
	(segment
		(start 408.100022 -241.852958)
		(end 403.716998 -246.235982)
		(width 0.16002)
		(layer "In4.Cu")
		(net "M_J_CPU0_SA_DQS_DN<4>")
	)
	(segment
		(start 438.229502 -238.828072)
		(end 437.749442 -238.828072)
		(width 0.16002)
		(layer "In4.Cu")
		(net "M_J_CPU0_SA_DQS_DN<4>")
	)
	(segment
		(start 390.453372 -246.589042)
		(end 390.44499 -246.584216)
		(width 0.09525)
		(layer "In4.Cu")
		(net "M_J_CPU0_SA_DQS_DN<4>")
	)
	(segment
		(start 434.973476 -238.168688)
		(end 432.893978 -238.168688)
		(width 0.16002)
		(layer "In4.Cu")
		(net "M_J_CPU0_SA_DQS_DN<4>")
	)
	(segment
		(start 420.383462 -238.562134)
		(end 418.475922 -238.562134)
		(width 0.16002)
		(layer "In4.Cu")
		(net "M_J_CPU0_SA_DQS_DN<4>")
	)
	(segment
		(start 386.69341 -246.589042)
		(end 386.685028 -246.584216)
		(width 0.09525)
		(layer "In4.Cu")
		(net "M_J_CPU0_SA_DQS_DN<4>")
	)
	(segment
		(start 439.100214 -238.985044)
		(end 438.826402 -238.711232)
		(width 0.16002)
		(layer "In4.Cu")
		(net "M_J_CPU0_SA_DQS_DN<4>")
	)
	(segment
		(start 409.280106 -241.852958)
		(end 408.100022 -241.852958)
		(width 0.16002)
		(layer "In4.Cu")
		(net "M_J_CPU0_SA_DQS_DN<4>")
	)
	(segment
		(start 388.20471 -246.584216)
		(end 388.196328 -246.589042)
		(width 0.09525)
		(layer "In4.Cu")
		(net "M_J_CPU0_SA_DQS_DN<4>")
	)
	(segment
		(start 430.618138 -238.168688)
		(end 429.909224 -238.168688)
		(width 0.16002)
		(layer "In4.Cu")
		(net "M_J_CPU0_SA_DQS_DN<4>")
	)
	(segment
		(start 422.249092 -238.239808)
		(end 421.570912 -238.917988)
		(width 0.16002)
		(layer "In4.Cu")
		(net "M_J_CPU0_SA_DQS_DN<4>")
	)
	(segment
		(start 437.632602 -238.711232)
		(end 437.058816 -238.711232)
		(width 0.16002)
		(layer "In4.Cu")
		(net "M_J_CPU0_SA_DQS_DN<4>")
	)
	(segment
		(start 391.40384 -246.595138)
		(end 391.393426 -246.589042)
		(width 0.09525)
		(layer "In4.Cu")
		(net "M_J_CPU0_SA_DQS_DN<4>")
	)
	(segment
		(start 424.952414 -237.71225)
		(end 423.605198 -237.71225)
		(width 0.16002)
		(layer "In4.Cu")
		(net "M_J_CPU0_SA_DQS_DN<4>")
	)
	(segment
		(start 394.241528 -246.937022)
		(end 393.969748 -246.665242)
		(width 0.09525)
		(layer "In4.Cu")
		(net "M_J_CPU0_SA_DQS_DN<4>")
	)
	(segment
		(start 438.826402 -238.711232)
		(end 438.346342 -238.711232)
		(width 0.16002)
		(layer "In4.Cu")
		(net "M_J_CPU0_SA_DQS_DN<4>")
	)
	(segment
		(start 432.43754 -237.71225)
		(end 431.074576 -237.71225)
		(width 0.16002)
		(layer "In4.Cu")
		(net "M_J_CPU0_SA_DQS_DN<4>")
	)
	(segment
		(start 423.605198 -237.71225)
		(end 423.07764 -238.239808)
		(width 0.16002)
		(layer "In4.Cu")
		(net "M_J_CPU0_SA_DQS_DN<4>")
	)
	(segment
		(start 437.058816 -238.711232)
		(end 436.87746 -238.892588)
		(width 0.16002)
		(layer "In4.Cu")
		(net "M_J_CPU0_SA_DQS_DN<4>")
	)
	(segment
		(start 427.980602 -238.562134)
		(end 425.802298 -238.562134)
		(width 0.16002)
		(layer "In4.Cu")
		(net "M_J_CPU0_SA_DQS_DN<4>")
	)
	(segment
		(start 383.504694 -246.584216)
		(end 383.496312 -246.589042)
		(width 0.09525)
		(layer "In4.Cu")
		(net "M_J_CPU0_SA_DQS_DN<4>")
	)
	(segment
		(start 392.896598 -246.589042)
		(end 392.881866 -246.597678)
		(width 0.09525)
		(layer "In4.Cu")
		(net "M_J_CPU0_SA_DQS_DN<4>")
	)
	(segment
		(start 381.993394 -246.589042)
		(end 381.985012 -246.584216)
		(width 0.09525)
		(layer "In4.Cu")
		(net "M_J_CPU0_SA_DQS_DN<4>")
	)
	(segment
		(start 423.07764 -238.239808)
		(end 422.249092 -238.239808)
		(width 0.16002)
		(layer "In4.Cu")
		(net "M_J_CPU0_SA_DQS_DN<4>")
	)
	(segment
		(start 429.909224 -238.168688)
		(end 429.139604 -238.938308)
		(width 0.16002)
		(layer "In4.Cu")
		(net "M_J_CPU0_SA_DQS_DN<4>")
	)
	(segment
		(start 418.475922 -238.562134)
		(end 417.945316 -238.031528)
		(width 0.16002)
		(layer "In4.Cu")
		(net "M_J_CPU0_SA_DQS_DN<4>")
	)
	(segment
		(start 394.916152 -246.937022)
		(end 394.241528 -246.937022)
		(width 0.09525)
		(layer "In4.Cu")
		(net "M_J_CPU0_SA_DQS_DN<4>")
	)
	(segment
		(start 395.798294 -246.235982)
		(end 395.774672 -246.235982)
		(width 0.09525)
		(layer "In4.Cu")
		(net "M_J_CPU0_SA_DQS_DN<4>")
	)
	(segment
		(start 438.346342 -238.711232)
		(end 438.229502 -238.828072)
		(width 0.16002)
		(layer "In4.Cu")
		(net "M_J_CPU0_SA_DQS_DN<4>")
	)
	(segment
		(start 380.710948 -246.648732)
		(end 380.864872 -246.914162)
		(width 0.09525)
		(layer "In4.Cu")
		(net "M_J_CPU0_SA_DQS_DN<4>")
	)
	(segment
		(start 431.074576 -237.71225)
		(end 430.618138 -238.168688)
		(width 0.16002)
		(layer "In4.Cu")
		(net "M_J_CPU0_SA_DQS_DN<4>")
	)
	(segment
		(start 385.753356 -246.589042)
		(end 385.744974 -246.584216)
		(width 0.09525)
		(layer "In4.Cu")
		(net "M_J_CPU0_SA_DQS_DN<4>")
	)
	(segment
		(start 429.139604 -238.938308)
		(end 428.356776 -238.938308)
		(width 0.16002)
		(layer "In4.Cu")
		(net "M_J_CPU0_SA_DQS_DN<4>")
	)
	(segment
		(start 412.227776 -238.905288)
		(end 409.280106 -241.852958)
		(width 0.16002)
		(layer "In4.Cu")
		(net "M_J_CPU0_SA_DQS_DN<4>")
	)
	(segment
		(start 414.9471 -238.031528)
		(end 414.07334 -238.905288)
		(width 0.16002)
		(layer "In4.Cu")
		(net "M_J_CPU0_SA_DQS_DN<4>")
	)
	(segment
		(start 437.749442 -238.828072)
		(end 437.632602 -238.711232)
		(width 0.16002)
		(layer "In4.Cu")
		(net "M_J_CPU0_SA_DQS_DN<4>")
	)
	(segment
		(start 393.969748 -246.665242)
		(end 393.555982 -246.665242)
		(width 0.09525)
		(layer "In4.Cu")
		(net "M_J_CPU0_SA_DQS_DN<4>")
	)
	(segment
		(start 387.264656 -246.584216)
		(end 387.256274 -246.589042)
		(width 0.09525)
		(layer "In4.Cu")
		(net "M_J_CPU0_SA_DQS_DN<4>")
	)
	(segment
		(start 435.697376 -238.892588)
		(end 434.973476 -238.168688)
		(width 0.16002)
		(layer "In4.Cu")
		(net "M_J_CPU0_SA_DQS_DN<4>")
	)
	(segment
		(start 395.715744 -246.177054)
		(end 395.61897 -246.177054)
		(width 0.09525)
		(layer "In4.Cu")
		(net "M_J_CPU0_SA_DQS_DN<4>")
	)
	(segment
		(start 403.716998 -246.235982)
		(end 395.798294 -246.235982)
		(width 0.16002)
		(layer "In4.Cu")
		(net "M_J_CPU0_SA_DQS_DN<4>")
	)
	(segment
		(start 417.945316 -238.031528)
		(end 414.9471 -238.031528)
		(width 0.16002)
		(layer "In4.Cu")
		(net "M_J_CPU0_SA_DQS_DN<4>")
	)
	(segment
		(start 395.774672 -246.235982)
		(end 395.715744 -246.177054)
		(width 0.09525)
		(layer "In4.Cu")
		(net "M_J_CPU0_SA_DQS_DN<4>")
	)
	(segment
		(start 420.739316 -238.917988)
		(end 420.383462 -238.562134)
		(width 0.16002)
		(layer "In4.Cu")
		(net "M_J_CPU0_SA_DQS_DN<4>")
	)
	(segment
		(start 392.911076 -246.58066)
		(end 392.896598 -246.589042)
		(width 0.09525)
		(layer "In4.Cu")
		(net "M_J_CPU0_SA_DQS_DN<4>")
	)
	(segment
		(start 432.893978 -238.168688)
		(end 432.43754 -237.71225)
		(width 0.16002)
		(layer "In4.Cu")
		(net "M_J_CPU0_SA_DQS_DN<4>")
	)
	(segment
		(start 391.024618 -246.584216)
		(end 391.016236 -246.589042)
		(width 0.09525)
		(layer "In4.Cu")
		(net "M_J_CPU0_SA_DQS_DN<4>")
	)
	(segment
		(start 392.334242 -246.589042)
		(end 392.32586 -246.584216)
		(width 0.09525)
		(layer "In4.Cu")
		(net "M_J_CPU0_SA_DQS_DN<4>")
	)
	(arc
		(start 384.813302 -246.589042)
		(mid 384.624834 -246.538365)
		(end 384.436366 -246.589042)
		(width 0.09525)
		(layer "In4.Cu")
		(net "M_J_CPU0_SA_DQS_DN<4>")
	)
	(arc
		(start 387.633464 -246.589042)
		(mid 387.449689 -246.53827)
		(end 387.264656 -246.584216)
		(width 0.09525)
		(layer "In4.Cu")
		(net "M_J_CPU0_SA_DQS_DN<4>")
	)
	(arc
		(start 390.076182 -246.589042)
		(mid 389.79475 -246.664797)
		(end 389.513318 -246.589042)
		(width 0.09525)
		(layer "In4.Cu")
		(net "M_J_CPU0_SA_DQS_DN<4>")
	)
	(arc
		(start 388.196328 -246.589042)
		(mid 387.914896 -246.664797)
		(end 387.633464 -246.589042)
		(width 0.09525)
		(layer "In4.Cu")
		(net "M_J_CPU0_SA_DQS_DN<4>")
	)
	(arc
		(start 382.933448 -246.589042)
		(mid 382.749673 -246.53827)
		(end 382.56464 -246.584216)
		(width 0.09525)
		(layer "In4.Cu")
		(net "M_J_CPU0_SA_DQS_DN<4>")
	)
	(arc
		(start 384.436366 -246.589042)
		(mid 384.154934 -246.664797)
		(end 383.873502 -246.589042)
		(width 0.09525)
		(layer "In4.Cu")
		(net "M_J_CPU0_SA_DQS_DN<4>")
	)
	(arc
		(start 383.496312 -246.589042)
		(mid 383.21488 -246.664797)
		(end 382.933448 -246.589042)
		(width 0.09525)
		(layer "In4.Cu")
		(net "M_J_CPU0_SA_DQS_DN<4>")
	)
	(arc
		(start 381.044958 -246.584216)
		(mid 380.892063 -246.539388)
		(end 380.734316 -246.561864)
		(width 0.09525)
		(layer "In4.Cu")
		(net "M_J_CPU0_SA_DQS_DN<4>")
	)
	(arc
		(start 388.573518 -246.589042)
		(mid 388.389743 -246.53827)
		(end 388.20471 -246.584216)
		(width 0.09525)
		(layer "In4.Cu")
		(net "M_J_CPU0_SA_DQS_DN<4>")
	)
	(arc
		(start 393.273788 -246.589042)
		(mid 393.093509 -246.538211)
		(end 392.911076 -246.58066)
		(width 0.09525)
		(layer "In4.Cu")
		(net "M_J_CPU0_SA_DQS_DN<4>")
	)
	(arc
		(start 381.616204 -246.589042)
		(mid 381.334772 -246.664797)
		(end 381.05334 -246.589042)
		(width 0.09525)
		(layer "In4.Cu")
		(net "M_J_CPU0_SA_DQS_DN<4>")
	)
	(arc
		(start 385.376166 -246.589042)
		(mid 385.094734 -246.664797)
		(end 384.813302 -246.589042)
		(width 0.09525)
		(layer "In4.Cu")
		(net "M_J_CPU0_SA_DQS_DN<4>")
	)
	(arc
		(start 382.556258 -246.589042)
		(mid 382.274826 -246.664797)
		(end 381.993394 -246.589042)
		(width 0.09525)
		(layer "In4.Cu")
		(net "M_J_CPU0_SA_DQS_DN<4>")
	)
	(arc
		(start 386.685028 -246.584216)
		(mid 386.499996 -246.538302)
		(end 386.31622 -246.589042)
		(width 0.09525)
		(layer "In4.Cu")
		(net "M_J_CPU0_SA_DQS_DN<4>")
	)
	(arc
		(start 383.873502 -246.589042)
		(mid 383.689727 -246.53827)
		(end 383.504694 -246.584216)
		(width 0.09525)
		(layer "In4.Cu")
		(net "M_J_CPU0_SA_DQS_DN<4>")
	)
	(arc
		(start 393.555982 -246.665242)
		(mid 393.409823 -246.645871)
		(end 393.273788 -246.589042)
		(width 0.09525)
		(layer "In4.Cu")
		(net "M_J_CPU0_SA_DQS_DN<4>")
	)
	(arc
		(start 392.32586 -246.584216)
		(mid 392.140574 -246.53818)
		(end 391.956544 -246.589042)
		(width 0.09525)
		(layer "In4.Cu")
		(net "M_J_CPU0_SA_DQS_DN<4>")
	)
	(arc
		(start 389.513318 -246.589042)
		(mid 389.32485 -246.538365)
		(end 389.136382 -246.589042)
		(width 0.09525)
		(layer "In4.Cu")
		(net "M_J_CPU0_SA_DQS_DN<4>")
	)
	(arc
		(start 389.136382 -246.589042)
		(mid 388.85495 -246.664797)
		(end 388.573518 -246.589042)
		(width 0.09525)
		(layer "In4.Cu")
		(net "M_J_CPU0_SA_DQS_DN<4>")
	)
	(arc
		(start 391.016236 -246.589042)
		(mid 390.734804 -246.664797)
		(end 390.453372 -246.589042)
		(width 0.09525)
		(layer "In4.Cu")
		(net "M_J_CPU0_SA_DQS_DN<4>")
	)
	(arc
		(start 391.393426 -246.589042)
		(mid 391.209651 -246.53827)
		(end 391.024618 -246.584216)
		(width 0.09525)
		(layer "In4.Cu")
		(net "M_J_CPU0_SA_DQS_DN<4>")
	)
	(arc
		(start 387.256274 -246.589042)
		(mid 386.974842 -246.664797)
		(end 386.69341 -246.589042)
		(width 0.09525)
		(layer "In4.Cu")
		(net "M_J_CPU0_SA_DQS_DN<4>")
	)
	(arc
		(start 386.31622 -246.589042)
		(mid 386.034788 -246.664797)
		(end 385.753356 -246.589042)
		(width 0.09525)
		(layer "In4.Cu")
		(net "M_J_CPU0_SA_DQS_DN<4>")
	)
	(arc
		(start 385.744974 -246.584216)
		(mid 385.559942 -246.538302)
		(end 385.376166 -246.589042)
		(width 0.09525)
		(layer "In4.Cu")
		(net "M_J_CPU0_SA_DQS_DN<4>")
	)
	(arc
		(start 381.985012 -246.584216)
		(mid 381.79998 -246.538302)
		(end 381.616204 -246.589042)
		(width 0.09525)
		(layer "In4.Cu")
		(net "M_J_CPU0_SA_DQS_DN<4>")
	)
	(arc
		(start 390.44499 -246.584216)
		(mid 390.259958 -246.538302)
		(end 390.076182 -246.589042)
		(width 0.09525)
		(layer "In4.Cu")
		(net "M_J_CPU0_SA_DQS_DN<4>")
	)
	(arc
		(start 392.881866 -246.597678)
		(mid 392.606915 -246.664821)
		(end 392.334242 -246.589042)
		(width 0.09525)
		(layer "In4.Cu")
		(net "M_J_CPU0_SA_DQS_DN<4>")
	)
	(arc
		(start 391.956544 -246.589042)
		(mid 391.681001 -246.664891)
		(end 391.40384 -246.595138)
		(width 0.09525)
		(layer "In4.Cu")
		(net "M_J_CPU0_SA_DQS_DN<4>")
	)
	(segment
		(start 380.39802 -242.320064)
		(end 380.864872 -242.054126)
		(width 0.12954)
		(layer "F.Cu")
		(net "M_J_CPU0_SA_DQS_DN<3>")
	)
	(segment
		(start 393.810744 -241.677698)
		(end 394.381482 -241.10696)
		(width 0.09525)
		(layer "In4.Cu")
		(net "M_J_CPU0_SA_DQS_DN<3>")
	)
	(segment
		(start 394.813028 -241.10696)
		(end 395.379956 -240.540032)
		(width 0.09525)
		(layer "In4.Cu")
		(net "M_J_CPU0_SA_DQS_DN<3>")
	)
	(segment
		(start 436.87746 -229.542594)
		(end 437.058816 -229.361238)
		(width 0.16002)
		(layer "In4.Cu")
		(net "M_J_CPU0_SA_DQS_DN<3>")
	)
	(segment
		(start 388.196328 -241.729006)
		(end 388.20471 -241.72418)
		(width 0.09525)
		(layer "In4.Cu")
		(net "M_J_CPU0_SA_DQS_DN<3>")
	)
	(segment
		(start 430.618138 -228.818694)
		(end 431.074576 -228.362256)
		(width 0.16002)
		(layer "In4.Cu")
		(net "M_J_CPU0_SA_DQS_DN<3>")
	)
	(segment
		(start 417.945316 -228.681534)
		(end 418.475922 -229.21214)
		(width 0.16002)
		(layer "In4.Cu")
		(net "M_J_CPU0_SA_DQS_DN<3>")
	)
	(segment
		(start 438.252616 -229.361238)
		(end 438.826402 -229.361238)
		(width 0.16002)
		(layer "In4.Cu")
		(net "M_J_CPU0_SA_DQS_DN<3>")
	)
	(segment
		(start 391.393426 -241.729006)
		(end 391.40384 -241.735102)
		(width 0.09525)
		(layer "In4.Cu")
		(net "M_J_CPU0_SA_DQS_DN<3>")
	)
	(segment
		(start 421.570912 -229.567994)
		(end 422.249092 -228.889814)
		(width 0.16002)
		(layer "In4.Cu")
		(net "M_J_CPU0_SA_DQS_DN<3>")
	)
	(segment
		(start 432.893978 -228.818694)
		(end 434.973476 -228.818694)
		(width 0.16002)
		(layer "In4.Cu")
		(net "M_J_CPU0_SA_DQS_DN<3>")
	)
	(segment
		(start 394.381482 -241.10696)
		(end 394.813028 -241.10696)
		(width 0.09525)
		(layer "In4.Cu")
		(net "M_J_CPU0_SA_DQS_DN<3>")
	)
	(segment
		(start 437.058816 -229.361238)
		(end 437.538876 -229.361238)
		(width 0.16002)
		(layer "In4.Cu")
		(net "M_J_CPU0_SA_DQS_DN<3>")
	)
	(segment
		(start 423.605198 -228.362256)
		(end 424.952414 -228.362256)
		(width 0.16002)
		(layer "In4.Cu")
		(net "M_J_CPU0_SA_DQS_DN<3>")
	)
	(segment
		(start 425.802298 -229.21214)
		(end 427.980602 -229.21214)
		(width 0.16002)
		(layer "In4.Cu")
		(net "M_J_CPU0_SA_DQS_DN<3>")
	)
	(segment
		(start 395.379956 -240.540032)
		(end 395.769592 -240.540032)
		(width 0.09525)
		(layer "In4.Cu")
		(net "M_J_CPU0_SA_DQS_DN<3>")
	)
	(segment
		(start 431.074576 -228.362256)
		(end 432.43754 -228.362256)
		(width 0.16002)
		(layer "In4.Cu")
		(net "M_J_CPU0_SA_DQS_DN<3>")
	)
	(segment
		(start 422.249092 -228.889814)
		(end 423.07764 -228.889814)
		(width 0.16002)
		(layer "In4.Cu")
		(net "M_J_CPU0_SA_DQS_DN<3>")
	)
	(segment
		(start 395.852142 -240.59896)
		(end 399.74393 -240.59896)
		(width 0.16002)
		(layer "In4.Cu")
		(net "M_J_CPU0_SA_DQS_DN<3>")
	)
	(segment
		(start 380.710948 -241.788696)
		(end 380.734316 -241.701828)
		(width 0.09525)
		(layer "In4.Cu")
		(net "M_J_CPU0_SA_DQS_DN<3>")
	)
	(segment
		(start 383.496312 -241.729006)
		(end 383.504694 -241.72418)
		(width 0.09525)
		(layer "In4.Cu")
		(net "M_J_CPU0_SA_DQS_DN<3>")
	)
	(segment
		(start 382.556258 -241.729006)
		(end 382.56464 -241.72418)
		(width 0.09525)
		(layer "In4.Cu")
		(net "M_J_CPU0_SA_DQS_DN<3>")
	)
	(segment
		(start 434.973476 -228.818694)
		(end 435.697376 -229.542594)
		(width 0.16002)
		(layer "In4.Cu")
		(net "M_J_CPU0_SA_DQS_DN<3>")
	)
	(segment
		(start 392.32586 -241.72418)
		(end 392.334242 -241.729006)
		(width 0.09525)
		(layer "In4.Cu")
		(net "M_J_CPU0_SA_DQS_DN<3>")
	)
	(segment
		(start 386.685028 -241.72418)
		(end 386.69341 -241.729006)
		(width 0.09525)
		(layer "In4.Cu")
		(net "M_J_CPU0_SA_DQS_DN<3>")
	)
	(segment
		(start 420.383462 -229.21214)
		(end 420.739316 -229.567994)
		(width 0.16002)
		(layer "In4.Cu")
		(net "M_J_CPU0_SA_DQS_DN<3>")
	)
	(segment
		(start 414.07334 -229.555294)
		(end 414.9471 -228.681534)
		(width 0.16002)
		(layer "In4.Cu")
		(net "M_J_CPU0_SA_DQS_DN<3>")
	)
	(segment
		(start 390.44499 -241.72418)
		(end 390.453372 -241.729006)
		(width 0.09525)
		(layer "In4.Cu")
		(net "M_J_CPU0_SA_DQS_DN<3>")
	)
	(segment
		(start 420.739316 -229.567994)
		(end 421.570912 -229.567994)
		(width 0.16002)
		(layer "In4.Cu")
		(net "M_J_CPU0_SA_DQS_DN<3>")
	)
	(segment
		(start 418.475922 -229.21214)
		(end 420.383462 -229.21214)
		(width 0.16002)
		(layer "In4.Cu")
		(net "M_J_CPU0_SA_DQS_DN<3>")
	)
	(segment
		(start 410.302964 -229.555294)
		(end 414.07334 -229.555294)
		(width 0.16002)
		(layer "In4.Cu")
		(net "M_J_CPU0_SA_DQS_DN<3>")
	)
	(segment
		(start 438.826402 -229.361238)
		(end 439.100214 -229.63505)
		(width 0.16002)
		(layer "In4.Cu")
		(net "M_J_CPU0_SA_DQS_DN<3>")
	)
	(segment
		(start 429.139604 -229.588314)
		(end 429.909224 -228.818694)
		(width 0.16002)
		(layer "In4.Cu")
		(net "M_J_CPU0_SA_DQS_DN<3>")
	)
	(segment
		(start 385.744974 -241.72418)
		(end 385.753356 -241.729006)
		(width 0.09525)
		(layer "In4.Cu")
		(net "M_J_CPU0_SA_DQS_DN<3>")
	)
	(segment
		(start 438.135776 -229.478078)
		(end 438.252616 -229.361238)
		(width 0.16002)
		(layer "In4.Cu")
		(net "M_J_CPU0_SA_DQS_DN<3>")
	)
	(segment
		(start 387.256274 -241.729006)
		(end 387.264656 -241.72418)
		(width 0.09525)
		(layer "In4.Cu")
		(net "M_J_CPU0_SA_DQS_DN<3>")
	)
	(segment
		(start 395.769592 -240.540032)
		(end 395.82852 -240.59896)
		(width 0.09525)
		(layer "In4.Cu")
		(net "M_J_CPU0_SA_DQS_DN<3>")
	)
	(segment
		(start 432.43754 -228.362256)
		(end 432.893978 -228.818694)
		(width 0.16002)
		(layer "In4.Cu")
		(net "M_J_CPU0_SA_DQS_DN<3>")
	)
	(segment
		(start 414.9471 -228.681534)
		(end 417.945316 -228.681534)
		(width 0.16002)
		(layer "In4.Cu")
		(net "M_J_CPU0_SA_DQS_DN<3>")
	)
	(segment
		(start 423.07764 -228.889814)
		(end 423.605198 -228.362256)
		(width 0.16002)
		(layer "In4.Cu")
		(net "M_J_CPU0_SA_DQS_DN<3>")
	)
	(segment
		(start 428.356776 -229.588314)
		(end 429.139604 -229.588314)
		(width 0.16002)
		(layer "In4.Cu")
		(net "M_J_CPU0_SA_DQS_DN<3>")
	)
	(segment
		(start 393.084812 -241.677698)
		(end 393.810744 -241.677698)
		(width 0.09525)
		(layer "In4.Cu")
		(net "M_J_CPU0_SA_DQS_DN<3>")
	)
	(segment
		(start 381.985012 -241.72418)
		(end 381.993394 -241.729006)
		(width 0.09525)
		(layer "In4.Cu")
		(net "M_J_CPU0_SA_DQS_DN<3>")
	)
	(segment
		(start 429.909224 -228.818694)
		(end 430.618138 -228.818694)
		(width 0.16002)
		(layer "In4.Cu")
		(net "M_J_CPU0_SA_DQS_DN<3>")
	)
	(segment
		(start 435.697376 -229.542594)
		(end 436.87746 -229.542594)
		(width 0.16002)
		(layer "In4.Cu")
		(net "M_J_CPU0_SA_DQS_DN<3>")
	)
	(segment
		(start 381.044958 -241.72418)
		(end 381.05334 -241.729006)
		(width 0.09525)
		(layer "In4.Cu")
		(net "M_J_CPU0_SA_DQS_DN<3>")
	)
	(segment
		(start 380.864872 -242.054126)
		(end 380.710948 -241.788696)
		(width 0.09525)
		(layer "In4.Cu")
		(net "M_J_CPU0_SA_DQS_DN<3>")
	)
	(segment
		(start 399.74393 -240.59896)
		(end 406.290018 -234.052872)
		(width 0.16002)
		(layer "In4.Cu")
		(net "M_J_CPU0_SA_DQS_DN<3>")
	)
	(segment
		(start 424.952414 -228.362256)
		(end 425.802298 -229.21214)
		(width 0.16002)
		(layer "In4.Cu")
		(net "M_J_CPU0_SA_DQS_DN<3>")
	)
	(segment
		(start 391.016236 -241.729006)
		(end 391.024618 -241.72418)
		(width 0.09525)
		(layer "In4.Cu")
		(net "M_J_CPU0_SA_DQS_DN<3>")
	)
	(segment
		(start 395.82852 -240.59896)
		(end 395.852142 -240.59896)
		(width 0.09525)
		(layer "In4.Cu")
		(net "M_J_CPU0_SA_DQS_DN<3>")
	)
	(segment
		(start 406.290018 -233.56824)
		(end 410.302964 -229.555294)
		(width 0.16002)
		(layer "In4.Cu")
		(net "M_J_CPU0_SA_DQS_DN<3>")
	)
	(segment
		(start 437.655716 -229.478078)
		(end 438.135776 -229.478078)
		(width 0.16002)
		(layer "In4.Cu")
		(net "M_J_CPU0_SA_DQS_DN<3>")
	)
	(segment
		(start 406.290018 -234.052872)
		(end 406.290018 -233.56824)
		(width 0.16002)
		(layer "In4.Cu")
		(net "M_J_CPU0_SA_DQS_DN<3>")
	)
	(segment
		(start 437.538876 -229.361238)
		(end 437.655716 -229.478078)
		(width 0.16002)
		(layer "In4.Cu")
		(net "M_J_CPU0_SA_DQS_DN<3>")
	)
	(segment
		(start 427.980602 -229.21214)
		(end 428.356776 -229.588314)
		(width 0.16002)
		(layer "In4.Cu")
		(net "M_J_CPU0_SA_DQS_DN<3>")
	)
	(arc
		(start 387.633464 -241.729006)
		(mid 387.914896 -241.804761)
		(end 388.196328 -241.729006)
		(width 0.09525)
		(layer "In4.Cu")
		(net "M_J_CPU0_SA_DQS_DN<3>")
	)
	(arc
		(start 384.813302 -241.729006)
		(mid 385.094734 -241.804761)
		(end 385.376166 -241.729006)
		(width 0.09525)
		(layer "In4.Cu")
		(net "M_J_CPU0_SA_DQS_DN<3>")
	)
	(arc
		(start 385.376166 -241.729006)
		(mid 385.559941 -241.678234)
		(end 385.744974 -241.72418)
		(width 0.09525)
		(layer "In4.Cu")
		(net "M_J_CPU0_SA_DQS_DN<3>")
	)
	(arc
		(start 391.40384 -241.735102)
		(mid 391.681002 -241.804902)
		(end 391.956544 -241.729006)
		(width 0.09525)
		(layer "In4.Cu")
		(net "M_J_CPU0_SA_DQS_DN<3>")
	)
	(arc
		(start 381.05334 -241.729006)
		(mid 381.334772 -241.804761)
		(end 381.616204 -241.729006)
		(width 0.09525)
		(layer "In4.Cu")
		(net "M_J_CPU0_SA_DQS_DN<3>")
	)
	(arc
		(start 388.20471 -241.72418)
		(mid 388.389742 -241.678266)
		(end 388.573518 -241.729006)
		(width 0.09525)
		(layer "In4.Cu")
		(net "M_J_CPU0_SA_DQS_DN<3>")
	)
	(arc
		(start 381.993394 -241.729006)
		(mid 382.274826 -241.804761)
		(end 382.556258 -241.729006)
		(width 0.09525)
		(layer "In4.Cu")
		(net "M_J_CPU0_SA_DQS_DN<3>")
	)
	(arc
		(start 390.453372 -241.729006)
		(mid 390.734804 -241.804761)
		(end 391.016236 -241.729006)
		(width 0.09525)
		(layer "In4.Cu")
		(net "M_J_CPU0_SA_DQS_DN<3>")
	)
	(arc
		(start 382.933448 -241.729006)
		(mid 383.21488 -241.804761)
		(end 383.496312 -241.729006)
		(width 0.09525)
		(layer "In4.Cu")
		(net "M_J_CPU0_SA_DQS_DN<3>")
	)
	(arc
		(start 386.31622 -241.729006)
		(mid 386.499995 -241.678234)
		(end 386.685028 -241.72418)
		(width 0.09525)
		(layer "In4.Cu")
		(net "M_J_CPU0_SA_DQS_DN<3>")
	)
	(arc
		(start 384.436366 -241.729006)
		(mid 384.624834 -241.678329)
		(end 384.813302 -241.729006)
		(width 0.09525)
		(layer "In4.Cu")
		(net "M_J_CPU0_SA_DQS_DN<3>")
	)
	(arc
		(start 383.504694 -241.72418)
		(mid 383.689726 -241.678266)
		(end 383.873502 -241.729006)
		(width 0.09525)
		(layer "In4.Cu")
		(net "M_J_CPU0_SA_DQS_DN<3>")
	)
	(arc
		(start 386.69341 -241.729006)
		(mid 386.974842 -241.804761)
		(end 387.256274 -241.729006)
		(width 0.09525)
		(layer "In4.Cu")
		(net "M_J_CPU0_SA_DQS_DN<3>")
	)
	(arc
		(start 382.56464 -241.72418)
		(mid 382.749672 -241.678266)
		(end 382.933448 -241.729006)
		(width 0.09525)
		(layer "In4.Cu")
		(net "M_J_CPU0_SA_DQS_DN<3>")
	)
	(arc
		(start 383.873502 -241.729006)
		(mid 384.154934 -241.804761)
		(end 384.436366 -241.729006)
		(width 0.09525)
		(layer "In4.Cu")
		(net "M_J_CPU0_SA_DQS_DN<3>")
	)
	(arc
		(start 390.076182 -241.729006)
		(mid 390.259957 -241.678234)
		(end 390.44499 -241.72418)
		(width 0.09525)
		(layer "In4.Cu")
		(net "M_J_CPU0_SA_DQS_DN<3>")
	)
	(arc
		(start 380.734316 -241.701828)
		(mid 380.892066 -241.679309)
		(end 381.044958 -241.72418)
		(width 0.09525)
		(layer "In4.Cu")
		(net "M_J_CPU0_SA_DQS_DN<3>")
	)
	(arc
		(start 381.616204 -241.729006)
		(mid 381.799979 -241.678234)
		(end 381.985012 -241.72418)
		(width 0.09525)
		(layer "In4.Cu")
		(net "M_J_CPU0_SA_DQS_DN<3>")
	)
	(arc
		(start 387.264656 -241.72418)
		(mid 387.449688 -241.678266)
		(end 387.633464 -241.729006)
		(width 0.09525)
		(layer "In4.Cu")
		(net "M_J_CPU0_SA_DQS_DN<3>")
	)
	(arc
		(start 391.956544 -241.729006)
		(mid 392.140573 -241.678107)
		(end 392.32586 -241.72418)
		(width 0.09525)
		(layer "In4.Cu")
		(net "M_J_CPU0_SA_DQS_DN<3>")
	)
	(arc
		(start 385.753356 -241.729006)
		(mid 386.034788 -241.804761)
		(end 386.31622 -241.729006)
		(width 0.09525)
		(layer "In4.Cu")
		(net "M_J_CPU0_SA_DQS_DN<3>")
	)
	(arc
		(start 392.881866 -241.737642)
		(mid 392.979038 -241.693111)
		(end 393.084812 -241.677698)
		(width 0.09525)
		(layer "In4.Cu")
		(net "M_J_CPU0_SA_DQS_DN<3>")
	)
	(arc
		(start 389.513318 -241.729006)
		(mid 389.79475 -241.804761)
		(end 390.076182 -241.729006)
		(width 0.09525)
		(layer "In4.Cu")
		(net "M_J_CPU0_SA_DQS_DN<3>")
	)
	(arc
		(start 392.334242 -241.729006)
		(mid 392.606916 -241.804693)
		(end 392.881866 -241.737642)
		(width 0.09525)
		(layer "In4.Cu")
		(net "M_J_CPU0_SA_DQS_DN<3>")
	)
	(arc
		(start 391.024618 -241.72418)
		(mid 391.20965 -241.678266)
		(end 391.393426 -241.729006)
		(width 0.09525)
		(layer "In4.Cu")
		(net "M_J_CPU0_SA_DQS_DN<3>")
	)
	(arc
		(start 388.573518 -241.729006)
		(mid 388.85495 -241.804761)
		(end 389.136382 -241.729006)
		(width 0.09525)
		(layer "In4.Cu")
		(net "M_J_CPU0_SA_DQS_DN<3>")
	)
	(arc
		(start 389.136382 -241.729006)
		(mid 389.32485 -241.678329)
		(end 389.513318 -241.729006)
		(width 0.09525)
		(layer "In4.Cu")
		(net "M_J_CPU0_SA_DQS_DN<3>")
	)
	(segment
		(start 380.39802 -237.460028)
		(end 380.864872 -237.19409)
		(width 0.12954)
		(layer "F.Cu")
		(net "M_J_CPU0_SA_DQS_DN<2>")
	)
	(segment
		(start 395.849348 -234.869482)
		(end 395.825726 -234.869482)
		(width 0.09525)
		(layer "In4.Cu")
		(net "M_J_CPU0_SA_DQS_DN<2>")
	)
	(segment
		(start 395.766798 -234.810554)
		(end 395.596364 -234.810554)
		(width 0.09525)
		(layer "In4.Cu")
		(net "M_J_CPU0_SA_DQS_DN<2>")
	)
	(segment
		(start 432.43754 -219.012262)
		(end 431.074576 -219.012262)
		(width 0.16002)
		(layer "In4.Cu")
		(net "M_J_CPU0_SA_DQS_DN<2>")
	)
	(segment
		(start 380.710948 -236.92866)
		(end 380.864872 -237.19409)
		(width 0.09525)
		(layer "In4.Cu")
		(net "M_J_CPU0_SA_DQS_DN<2>")
	)
	(segment
		(start 427.980602 -219.862146)
		(end 425.802298 -219.862146)
		(width 0.16002)
		(layer "In4.Cu")
		(net "M_J_CPU0_SA_DQS_DN<2>")
	)
	(segment
		(start 437.739028 -220.128084)
		(end 437.622188 -220.011244)
		(width 0.16002)
		(layer "In4.Cu")
		(net "M_J_CPU0_SA_DQS_DN<2>")
	)
	(segment
		(start 414.07334 -220.2053)
		(end 413.10814 -220.2053)
		(width 0.16002)
		(layer "In4.Cu")
		(net "M_J_CPU0_SA_DQS_DN<2>")
	)
	(segment
		(start 438.219088 -220.128084)
		(end 437.739028 -220.128084)
		(width 0.16002)
		(layer "In4.Cu")
		(net "M_J_CPU0_SA_DQS_DN<2>")
	)
	(segment
		(start 430.618138 -219.4687)
		(end 429.909224 -219.4687)
		(width 0.16002)
		(layer "In4.Cu")
		(net "M_J_CPU0_SA_DQS_DN<2>")
	)
	(segment
		(start 421.570912 -220.218)
		(end 420.739316 -220.218)
		(width 0.16002)
		(layer "In4.Cu")
		(net "M_J_CPU0_SA_DQS_DN<2>")
	)
	(segment
		(start 429.909224 -219.4687)
		(end 429.139604 -220.23832)
		(width 0.16002)
		(layer "In4.Cu")
		(net "M_J_CPU0_SA_DQS_DN<2>")
	)
	(segment
		(start 423.605198 -219.012262)
		(end 423.07764 -219.53982)
		(width 0.16002)
		(layer "In4.Cu")
		(net "M_J_CPU0_SA_DQS_DN<2>")
	)
	(segment
		(start 387.264656 -236.864144)
		(end 387.256274 -236.86897)
		(width 0.09525)
		(layer "In4.Cu")
		(net "M_J_CPU0_SA_DQS_DN<2>")
	)
	(segment
		(start 420.383462 -219.862146)
		(end 418.475922 -219.862146)
		(width 0.16002)
		(layer "In4.Cu")
		(net "M_J_CPU0_SA_DQS_DN<2>")
	)
	(segment
		(start 396.975076 -234.869482)
		(end 395.849348 -234.869482)
		(width 0.16002)
		(layer "In4.Cu")
		(net "M_J_CPU0_SA_DQS_DN<2>")
	)
	(segment
		(start 429.139604 -220.23832)
		(end 428.356776 -220.23832)
		(width 0.16002)
		(layer "In4.Cu")
		(net "M_J_CPU0_SA_DQS_DN<2>")
	)
	(segment
		(start 380.734316 -236.841792)
		(end 380.710948 -236.92866)
		(width 0.09525)
		(layer "In4.Cu")
		(net "M_J_CPU0_SA_DQS_DN<2>")
	)
	(segment
		(start 434.973476 -219.4687)
		(end 432.893978 -219.4687)
		(width 0.16002)
		(layer "In4.Cu")
		(net "M_J_CPU0_SA_DQS_DN<2>")
	)
	(segment
		(start 432.893978 -219.4687)
		(end 432.43754 -219.012262)
		(width 0.16002)
		(layer "In4.Cu")
		(net "M_J_CPU0_SA_DQS_DN<2>")
	)
	(segment
		(start 382.56464 -236.864144)
		(end 382.556258 -236.86897)
		(width 0.09525)
		(layer "In4.Cu")
		(net "M_J_CPU0_SA_DQS_DN<2>")
	)
	(segment
		(start 417.945316 -219.33154)
		(end 414.9471 -219.33154)
		(width 0.16002)
		(layer "In4.Cu")
		(net "M_J_CPU0_SA_DQS_DN<2>")
	)
	(segment
		(start 420.739316 -220.218)
		(end 420.383462 -219.862146)
		(width 0.16002)
		(layer "In4.Cu")
		(net "M_J_CPU0_SA_DQS_DN<2>")
	)
	(segment
		(start 422.249092 -219.53982)
		(end 421.570912 -220.218)
		(width 0.16002)
		(layer "In4.Cu")
		(net "M_J_CPU0_SA_DQS_DN<2>")
	)
	(segment
		(start 435.697376 -220.1926)
		(end 434.973476 -219.4687)
		(width 0.16002)
		(layer "In4.Cu")
		(net "M_J_CPU0_SA_DQS_DN<2>")
	)
	(segment
		(start 403.426422 -226.00793)
		(end 403.426422 -228.418136)
		(width 0.16002)
		(layer "In4.Cu")
		(net "M_J_CPU0_SA_DQS_DN<2>")
	)
	(segment
		(start 394.888466 -235.665772)
		(end 394.517118 -235.665772)
		(width 0.09525)
		(layer "In4.Cu")
		(net "M_J_CPU0_SA_DQS_DN<2>")
	)
	(segment
		(start 395.825726 -234.869482)
		(end 395.766798 -234.810554)
		(width 0.09525)
		(layer "In4.Cu")
		(net "M_J_CPU0_SA_DQS_DN<2>")
	)
	(segment
		(start 388.20471 -236.864144)
		(end 388.196328 -236.86897)
		(width 0.09525)
		(layer "In4.Cu")
		(net "M_J_CPU0_SA_DQS_DN<2>")
	)
	(segment
		(start 438.335928 -220.011244)
		(end 438.219088 -220.128084)
		(width 0.16002)
		(layer "In4.Cu")
		(net "M_J_CPU0_SA_DQS_DN<2>")
	)
	(segment
		(start 409.55214 -219.882212)
		(end 403.426422 -226.00793)
		(width 0.16002)
		(layer "In4.Cu")
		(net "M_J_CPU0_SA_DQS_DN<2>")
	)
	(segment
		(start 390.453372 -236.86897)
		(end 390.44499 -236.864144)
		(width 0.09525)
		(layer "In4.Cu")
		(net "M_J_CPU0_SA_DQS_DN<2>")
	)
	(segment
		(start 436.87746 -220.1926)
		(end 435.697376 -220.1926)
		(width 0.16002)
		(layer "In4.Cu")
		(net "M_J_CPU0_SA_DQS_DN<2>")
	)
	(segment
		(start 395.596364 -234.810554)
		(end 394.888466 -235.665772)
		(width 0.09525)
		(layer "In4.Cu")
		(net "M_J_CPU0_SA_DQS_DN<2>")
	)
	(segment
		(start 437.622188 -220.011244)
		(end 437.058816 -220.011244)
		(width 0.16002)
		(layer "In4.Cu")
		(net "M_J_CPU0_SA_DQS_DN<2>")
	)
	(segment
		(start 437.058816 -220.011244)
		(end 436.87746 -220.1926)
		(width 0.16002)
		(layer "In4.Cu")
		(net "M_J_CPU0_SA_DQS_DN<2>")
	)
	(segment
		(start 381.05334 -236.86897)
		(end 381.044958 -236.864144)
		(width 0.09525)
		(layer "In4.Cu")
		(net "M_J_CPU0_SA_DQS_DN<2>")
	)
	(segment
		(start 385.753356 -236.86897)
		(end 385.744974 -236.864144)
		(width 0.09525)
		(layer "In4.Cu")
		(net "M_J_CPU0_SA_DQS_DN<2>")
	)
	(segment
		(start 423.07764 -219.53982)
		(end 422.249092 -219.53982)
		(width 0.16002)
		(layer "In4.Cu")
		(net "M_J_CPU0_SA_DQS_DN<2>")
	)
	(segment
		(start 403.426422 -228.418136)
		(end 396.975076 -234.869482)
		(width 0.16002)
		(layer "In4.Cu")
		(net "M_J_CPU0_SA_DQS_DN<2>")
	)
	(segment
		(start 414.9471 -219.33154)
		(end 414.07334 -220.2053)
		(width 0.16002)
		(layer "In4.Cu")
		(net "M_J_CPU0_SA_DQS_DN<2>")
	)
	(segment
		(start 383.504694 -236.864144)
		(end 383.496312 -236.86897)
		(width 0.09525)
		(layer "In4.Cu")
		(net "M_J_CPU0_SA_DQS_DN<2>")
	)
	(segment
		(start 424.952414 -219.012262)
		(end 423.605198 -219.012262)
		(width 0.16002)
		(layer "In4.Cu")
		(net "M_J_CPU0_SA_DQS_DN<2>")
	)
	(segment
		(start 393.369038 -236.813852)
		(end 393.042648 -236.813852)
		(width 0.09525)
		(layer "In4.Cu")
		(net "M_J_CPU0_SA_DQS_DN<2>")
	)
	(segment
		(start 394.517118 -235.665772)
		(end 393.369038 -236.813852)
		(width 0.09525)
		(layer "In4.Cu")
		(net "M_J_CPU0_SA_DQS_DN<2>")
	)
	(segment
		(start 413.10814 -220.2053)
		(end 412.785052 -219.882212)
		(width 0.16002)
		(layer "In4.Cu")
		(net "M_J_CPU0_SA_DQS_DN<2>")
	)
	(segment
		(start 412.785052 -219.882212)
		(end 409.55214 -219.882212)
		(width 0.16002)
		(layer "In4.Cu")
		(net "M_J_CPU0_SA_DQS_DN<2>")
	)
	(segment
		(start 438.826402 -220.011244)
		(end 438.335928 -220.011244)
		(width 0.16002)
		(layer "In4.Cu")
		(net "M_J_CPU0_SA_DQS_DN<2>")
	)
	(segment
		(start 425.802298 -219.862146)
		(end 424.952414 -219.012262)
		(width 0.16002)
		(layer "In4.Cu")
		(net "M_J_CPU0_SA_DQS_DN<2>")
	)
	(segment
		(start 439.100214 -220.285056)
		(end 438.826402 -220.011244)
		(width 0.16002)
		(layer "In4.Cu")
		(net "M_J_CPU0_SA_DQS_DN<2>")
	)
	(segment
		(start 381.993394 -236.86897)
		(end 381.985012 -236.864144)
		(width 0.09525)
		(layer "In4.Cu")
		(net "M_J_CPU0_SA_DQS_DN<2>")
	)
	(segment
		(start 418.475922 -219.862146)
		(end 417.945316 -219.33154)
		(width 0.16002)
		(layer "In4.Cu")
		(net "M_J_CPU0_SA_DQS_DN<2>")
	)
	(segment
		(start 386.69341 -236.86897)
		(end 386.685028 -236.864144)
		(width 0.09525)
		(layer "In4.Cu")
		(net "M_J_CPU0_SA_DQS_DN<2>")
	)
	(segment
		(start 431.074576 -219.012262)
		(end 430.618138 -219.4687)
		(width 0.16002)
		(layer "In4.Cu")
		(net "M_J_CPU0_SA_DQS_DN<2>")
	)
	(segment
		(start 428.356776 -220.23832)
		(end 427.980602 -219.862146)
		(width 0.16002)
		(layer "In4.Cu")
		(net "M_J_CPU0_SA_DQS_DN<2>")
	)
	(arc
		(start 387.633464 -236.86897)
		(mid 387.449689 -236.818198)
		(end 387.264656 -236.864144)
		(width 0.09525)
		(layer "In4.Cu")
		(net "M_J_CPU0_SA_DQS_DN<2>")
	)
	(arc
		(start 390.44499 -236.864144)
		(mid 390.259958 -236.81823)
		(end 390.076182 -236.86897)
		(width 0.09525)
		(layer "In4.Cu")
		(net "M_J_CPU0_SA_DQS_DN<2>")
	)
	(arc
		(start 381.985012 -236.864144)
		(mid 381.79998 -236.81823)
		(end 381.616204 -236.86897)
		(width 0.09525)
		(layer "In4.Cu")
		(net "M_J_CPU0_SA_DQS_DN<2>")
	)
	(arc
		(start 392.323574 -236.856524)
		(mid 392.138841 -236.833659)
		(end 391.956798 -236.872526)
		(width 0.09525)
		(layer "In4.Cu")
		(net "M_J_CPU0_SA_DQS_DN<2>")
	)
	(arc
		(start 386.31622 -236.86897)
		(mid 386.034788 -236.944725)
		(end 385.753356 -236.86897)
		(width 0.09525)
		(layer "In4.Cu")
		(net "M_J_CPU0_SA_DQS_DN<2>")
	)
	(arc
		(start 385.376166 -236.86897)
		(mid 385.094734 -236.944725)
		(end 384.813302 -236.86897)
		(width 0.09525)
		(layer "In4.Cu")
		(net "M_J_CPU0_SA_DQS_DN<2>")
	)
	(arc
		(start 384.436366 -236.86897)
		(mid 384.154934 -236.944725)
		(end 383.873502 -236.86897)
		(width 0.09525)
		(layer "In4.Cu")
		(net "M_J_CPU0_SA_DQS_DN<2>")
	)
	(arc
		(start 381.044958 -236.864144)
		(mid 380.892063 -236.819316)
		(end 380.734316 -236.841792)
		(width 0.09525)
		(layer "In4.Cu")
		(net "M_J_CPU0_SA_DQS_DN<2>")
	)
	(arc
		(start 388.196328 -236.86897)
		(mid 387.914896 -236.944725)
		(end 387.633464 -236.86897)
		(width 0.09525)
		(layer "In4.Cu")
		(net "M_J_CPU0_SA_DQS_DN<2>")
	)
	(arc
		(start 382.556258 -236.86897)
		(mid 382.274826 -236.944725)
		(end 381.993394 -236.86897)
		(width 0.09525)
		(layer "In4.Cu")
		(net "M_J_CPU0_SA_DQS_DN<2>")
	)
	(arc
		(start 383.873502 -236.86897)
		(mid 383.689727 -236.818198)
		(end 383.504694 -236.864144)
		(width 0.09525)
		(layer "In4.Cu")
		(net "M_J_CPU0_SA_DQS_DN<2>")
	)
	(arc
		(start 390.076182 -236.86897)
		(mid 389.79475 -236.944725)
		(end 389.513318 -236.86897)
		(width 0.09525)
		(layer "In4.Cu")
		(net "M_J_CPU0_SA_DQS_DN<2>")
	)
	(arc
		(start 391.956798 -236.872526)
		(mid 391.686241 -236.924675)
		(end 391.41527 -236.874812)
		(width 0.09525)
		(layer "In4.Cu")
		(net "M_J_CPU0_SA_DQS_DN<2>")
	)
	(arc
		(start 389.513318 -236.86897)
		(mid 389.32485 -236.818293)
		(end 389.136382 -236.86897)
		(width 0.09525)
		(layer "In4.Cu")
		(net "M_J_CPU0_SA_DQS_DN<2>")
	)
	(arc
		(start 382.933448 -236.86897)
		(mid 382.749673 -236.818198)
		(end 382.56464 -236.864144)
		(width 0.09525)
		(layer "In4.Cu")
		(net "M_J_CPU0_SA_DQS_DN<2>")
	)
	(arc
		(start 391.41527 -236.874812)
		(mid 391.193137 -236.837765)
		(end 390.974326 -236.891068)
		(width 0.09525)
		(layer "In4.Cu")
		(net "M_J_CPU0_SA_DQS_DN<2>")
	)
	(arc
		(start 387.256274 -236.86897)
		(mid 386.974842 -236.944725)
		(end 386.69341 -236.86897)
		(width 0.09525)
		(layer "In4.Cu")
		(net "M_J_CPU0_SA_DQS_DN<2>")
	)
	(arc
		(start 384.813302 -236.86897)
		(mid 384.624834 -236.818293)
		(end 384.436366 -236.86897)
		(width 0.09525)
		(layer "In4.Cu")
		(net "M_J_CPU0_SA_DQS_DN<2>")
	)
	(arc
		(start 390.974326 -236.891068)
		(mid 390.711113 -236.9443)
		(end 390.453372 -236.86897)
		(width 0.09525)
		(layer "In4.Cu")
		(net "M_J_CPU0_SA_DQS_DN<2>")
	)
	(arc
		(start 381.616204 -236.86897)
		(mid 381.334772 -236.944725)
		(end 381.05334 -236.86897)
		(width 0.09525)
		(layer "In4.Cu")
		(net "M_J_CPU0_SA_DQS_DN<2>")
	)
	(arc
		(start 385.744974 -236.864144)
		(mid 385.559942 -236.81823)
		(end 385.376166 -236.86897)
		(width 0.09525)
		(layer "In4.Cu")
		(net "M_J_CPU0_SA_DQS_DN<2>")
	)
	(arc
		(start 383.496312 -236.86897)
		(mid 383.21488 -236.944725)
		(end 382.933448 -236.86897)
		(width 0.09525)
		(layer "In4.Cu")
		(net "M_J_CPU0_SA_DQS_DN<2>")
	)
	(arc
		(start 389.136382 -236.86897)
		(mid 388.85495 -236.944725)
		(end 388.573518 -236.86897)
		(width 0.09525)
		(layer "In4.Cu")
		(net "M_J_CPU0_SA_DQS_DN<2>")
	)
	(arc
		(start 388.573518 -236.86897)
		(mid 388.389743 -236.818198)
		(end 388.20471 -236.864144)
		(width 0.09525)
		(layer "In4.Cu")
		(net "M_J_CPU0_SA_DQS_DN<2>")
	)
	(arc
		(start 392.990832 -236.824012)
		(mid 392.659985 -236.897348)
		(end 392.323574 -236.856524)
		(width 0.09525)
		(layer "In4.Cu")
		(net "M_J_CPU0_SA_DQS_DN<2>")
	)
	(arc
		(start 393.042648 -236.813852)
		(mid 393.016246 -236.816401)
		(end 392.990832 -236.824012)
		(width 0.09525)
		(layer "In4.Cu")
		(net "M_J_CPU0_SA_DQS_DN<2>")
	)
	(arc
		(start 386.685028 -236.864144)
		(mid 386.499996 -236.81823)
		(end 386.31622 -236.86897)
		(width 0.09525)
		(layer "In4.Cu")
		(net "M_J_CPU0_SA_DQS_DN<2>")
	)
	(segment
		(start 380.39802 -232.599992)
		(end 380.864872 -232.334054)
		(width 0.12954)
		(layer "F.Cu")
		(net "M_J_CPU0_SA_DQS_DN<1>")
	)
	(segment
		(start 428.356776 -210.888326)
		(end 429.139604 -210.888326)
		(width 0.16002)
		(layer "In4.Cu")
		(net "M_J_CPU0_SA_DQS_DN<1>")
	)
	(segment
		(start 414.07334 -210.855306)
		(end 414.9471 -209.981546)
		(width 0.16002)
		(layer "In4.Cu")
		(net "M_J_CPU0_SA_DQS_DN<1>")
	)
	(segment
		(start 382.556258 -232.008934)
		(end 382.56464 -232.004108)
		(width 0.09525)
		(layer "In4.Cu")
		(net "M_J_CPU0_SA_DQS_DN<1>")
	)
	(segment
		(start 392.966702 -230.3018)
		(end 393.324334 -230.3018)
		(width 0.09525)
		(layer "In4.Cu")
		(net "M_J_CPU0_SA_DQS_DN<1>")
	)
	(segment
		(start 434.241448 -210.235546)
		(end 434.358288 -210.118706)
		(width 0.16002)
		(layer "In4.Cu")
		(net "M_J_CPU0_SA_DQS_DN<1>")
	)
	(segment
		(start 429.139604 -210.888326)
		(end 429.845216 -210.182714)
		(width 0.16002)
		(layer "In4.Cu")
		(net "M_J_CPU0_SA_DQS_DN<1>")
	)
	(segment
		(start 381.985012 -232.004108)
		(end 381.993394 -232.008934)
		(width 0.09525)
		(layer "In4.Cu")
		(net "M_J_CPU0_SA_DQS_DN<1>")
	)
	(segment
		(start 437.058816 -210.66125)
		(end 437.561228 -210.66125)
		(width 0.16002)
		(layer "In4.Cu")
		(net "M_J_CPU0_SA_DQS_DN<1>")
	)
	(segment
		(start 395.597126 -227.74275)
		(end 397.889222 -225.450654)
		(width 0.16002)
		(layer "In4.Cu")
		(net "M_J_CPU0_SA_DQS_DN<1>")
	)
	(segment
		(start 431.1015 -209.662268)
		(end 431.941986 -209.662268)
		(width 0.16002)
		(layer "In4.Cu")
		(net "M_J_CPU0_SA_DQS_DN<1>")
	)
	(segment
		(start 395.497304 -227.759514)
		(end 395.580362 -227.759514)
		(width 0.09525)
		(layer "In4.Cu")
		(net "M_J_CPU0_SA_DQS_DN<1>")
	)
	(segment
		(start 433.644548 -210.118706)
		(end 433.761388 -210.235546)
		(width 0.16002)
		(layer "In4.Cu")
		(net "M_J_CPU0_SA_DQS_DN<1>")
	)
	(segment
		(start 437.678068 -210.77809)
		(end 438.158128 -210.77809)
		(width 0.16002)
		(layer "In4.Cu")
		(net "M_J_CPU0_SA_DQS_DN<1>")
	)
	(segment
		(start 420.739316 -210.868006)
		(end 421.570912 -210.868006)
		(width 0.16002)
		(layer "In4.Cu")
		(net "M_J_CPU0_SA_DQS_DN<1>")
	)
	(segment
		(start 397.889222 -225.450654)
		(end 397.889222 -221.916498)
		(width 0.16002)
		(layer "In4.Cu")
		(net "M_J_CPU0_SA_DQS_DN<1>")
	)
	(segment
		(start 390.44499 -232.004108)
		(end 390.446006 -232.004616)
		(width 0.09525)
		(layer "In4.Cu")
		(net "M_J_CPU0_SA_DQS_DN<1>")
	)
	(segment
		(start 438.274968 -210.66125)
		(end 438.826402 -210.66125)
		(width 0.16002)
		(layer "In4.Cu")
		(net "M_J_CPU0_SA_DQS_DN<1>")
	)
	(segment
		(start 414.9471 -209.981546)
		(end 417.945316 -209.981546)
		(width 0.16002)
		(layer "In4.Cu")
		(net "M_J_CPU0_SA_DQS_DN<1>")
	)
	(segment
		(start 423.605198 -209.662268)
		(end 424.952414 -209.662268)
		(width 0.16002)
		(layer "In4.Cu")
		(net "M_J_CPU0_SA_DQS_DN<1>")
	)
	(segment
		(start 395.580362 -227.759514)
		(end 395.597126 -227.74275)
		(width 0.09525)
		(layer "In4.Cu")
		(net "M_J_CPU0_SA_DQS_DN<1>")
	)
	(segment
		(start 387.256274 -232.008934)
		(end 387.264656 -232.004108)
		(width 0.09525)
		(layer "In4.Cu")
		(net "M_J_CPU0_SA_DQS_DN<1>")
	)
	(segment
		(start 429.845216 -210.182714)
		(end 431.1015 -209.662268)
		(width 0.16002)
		(layer "In4.Cu")
		(net "M_J_CPU0_SA_DQS_DN<1>")
	)
	(segment
		(start 417.945316 -209.981546)
		(end 418.475922 -210.512152)
		(width 0.16002)
		(layer "In4.Cu")
		(net "M_J_CPU0_SA_DQS_DN<1>")
	)
	(segment
		(start 434.973476 -210.118706)
		(end 435.697376 -210.842606)
		(width 0.16002)
		(layer "In4.Cu")
		(net "M_J_CPU0_SA_DQS_DN<1>")
	)
	(segment
		(start 393.324334 -230.3018)
		(end 395.194536 -228.431598)
		(width 0.09525)
		(layer "In4.Cu")
		(net "M_J_CPU0_SA_DQS_DN<1>")
	)
	(segment
		(start 421.570912 -210.868006)
		(end 422.249092 -210.189826)
		(width 0.16002)
		(layer "In4.Cu")
		(net "M_J_CPU0_SA_DQS_DN<1>")
	)
	(segment
		(start 438.158128 -210.77809)
		(end 438.274968 -210.66125)
		(width 0.16002)
		(layer "In4.Cu")
		(net "M_J_CPU0_SA_DQS_DN<1>")
	)
	(segment
		(start 381.044958 -232.004108)
		(end 381.05334 -232.008934)
		(width 0.09525)
		(layer "In4.Cu")
		(net "M_J_CPU0_SA_DQS_DN<1>")
	)
	(segment
		(start 424.952414 -209.662268)
		(end 425.802298 -210.512152)
		(width 0.16002)
		(layer "In4.Cu")
		(net "M_J_CPU0_SA_DQS_DN<1>")
	)
	(segment
		(start 395.194536 -228.431598)
		(end 395.194536 -228.062282)
		(width 0.09525)
		(layer "In4.Cu")
		(net "M_J_CPU0_SA_DQS_DN<1>")
	)
	(segment
		(start 392.584686 -230.683816)
		(end 392.966702 -230.3018)
		(width 0.09525)
		(layer "In4.Cu")
		(net "M_J_CPU0_SA_DQS_DN<1>")
	)
	(segment
		(start 422.249092 -210.189826)
		(end 423.07764 -210.189826)
		(width 0.16002)
		(layer "In4.Cu")
		(net "M_J_CPU0_SA_DQS_DN<1>")
	)
	(segment
		(start 413.219392 -210.855306)
		(end 414.07334 -210.855306)
		(width 0.16002)
		(layer "In4.Cu")
		(net "M_J_CPU0_SA_DQS_DN<1>")
	)
	(segment
		(start 397.889222 -221.916498)
		(end 409.255468 -210.550252)
		(width 0.16002)
		(layer "In4.Cu")
		(net "M_J_CPU0_SA_DQS_DN<1>")
	)
	(segment
		(start 433.761388 -210.235546)
		(end 434.241448 -210.235546)
		(width 0.16002)
		(layer "In4.Cu")
		(net "M_J_CPU0_SA_DQS_DN<1>")
	)
	(segment
		(start 420.383462 -210.512152)
		(end 420.739316 -210.868006)
		(width 0.16002)
		(layer "In4.Cu")
		(net "M_J_CPU0_SA_DQS_DN<1>")
	)
	(segment
		(start 433.044092 -210.118706)
		(end 433.644548 -210.118706)
		(width 0.16002)
		(layer "In4.Cu")
		(net "M_J_CPU0_SA_DQS_DN<1>")
	)
	(segment
		(start 436.87746 -210.842606)
		(end 437.058816 -210.66125)
		(width 0.16002)
		(layer "In4.Cu")
		(net "M_J_CPU0_SA_DQS_DN<1>")
	)
	(segment
		(start 418.475922 -210.512152)
		(end 420.383462 -210.512152)
		(width 0.16002)
		(layer "In4.Cu")
		(net "M_J_CPU0_SA_DQS_DN<1>")
	)
	(segment
		(start 431.941986 -209.662268)
		(end 433.044092 -210.118706)
		(width 0.16002)
		(layer "In4.Cu")
		(net "M_J_CPU0_SA_DQS_DN<1>")
	)
	(segment
		(start 383.496312 -232.008934)
		(end 383.504694 -232.004108)
		(width 0.09525)
		(layer "In4.Cu")
		(net "M_J_CPU0_SA_DQS_DN<1>")
	)
	(segment
		(start 437.561228 -210.66125)
		(end 437.678068 -210.77809)
		(width 0.16002)
		(layer "In4.Cu")
		(net "M_J_CPU0_SA_DQS_DN<1>")
	)
	(segment
		(start 409.255468 -210.550252)
		(end 412.914338 -210.550252)
		(width 0.16002)
		(layer "In4.Cu")
		(net "M_J_CPU0_SA_DQS_DN<1>")
	)
	(segment
		(start 435.697376 -210.842606)
		(end 436.87746 -210.842606)
		(width 0.16002)
		(layer "In4.Cu")
		(net "M_J_CPU0_SA_DQS_DN<1>")
	)
	(segment
		(start 390.446006 -232.004616)
		(end 390.453372 -232.008934)
		(width 0.09525)
		(layer "In4.Cu")
		(net "M_J_CPU0_SA_DQS_DN<1>")
	)
	(segment
		(start 423.07764 -210.189826)
		(end 423.605198 -209.662268)
		(width 0.16002)
		(layer "In4.Cu")
		(net "M_J_CPU0_SA_DQS_DN<1>")
	)
	(segment
		(start 380.710948 -232.068624)
		(end 380.734316 -231.981756)
		(width 0.09525)
		(layer "In4.Cu")
		(net "M_J_CPU0_SA_DQS_DN<1>")
	)
	(segment
		(start 438.826402 -210.66125)
		(end 439.100214 -210.935062)
		(width 0.16002)
		(layer "In4.Cu")
		(net "M_J_CPU0_SA_DQS_DN<1>")
	)
	(segment
		(start 385.744974 -232.004108)
		(end 385.753356 -232.008934)
		(width 0.09525)
		(layer "In4.Cu")
		(net "M_J_CPU0_SA_DQS_DN<1>")
	)
	(segment
		(start 412.914338 -210.550252)
		(end 413.219392 -210.855306)
		(width 0.16002)
		(layer "In4.Cu")
		(net "M_J_CPU0_SA_DQS_DN<1>")
	)
	(segment
		(start 391.016236 -232.008934)
		(end 391.024618 -232.004108)
		(width 0.09525)
		(layer "In4.Cu")
		(net "M_J_CPU0_SA_DQS_DN<1>")
	)
	(segment
		(start 380.864872 -232.334054)
		(end 380.710948 -232.068624)
		(width 0.09525)
		(layer "In4.Cu")
		(net "M_J_CPU0_SA_DQS_DN<1>")
	)
	(segment
		(start 386.685028 -232.004108)
		(end 386.69341 -232.008934)
		(width 0.09525)
		(layer "In4.Cu")
		(net "M_J_CPU0_SA_DQS_DN<1>")
	)
	(segment
		(start 392.584686 -231.4067)
		(end 392.584686 -230.683816)
		(width 0.09525)
		(layer "In4.Cu")
		(net "M_J_CPU0_SA_DQS_DN<1>")
	)
	(segment
		(start 425.802298 -210.512152)
		(end 427.980602 -210.512152)
		(width 0.16002)
		(layer "In4.Cu")
		(net "M_J_CPU0_SA_DQS_DN<1>")
	)
	(segment
		(start 391.945622 -232.01503)
		(end 391.956036 -232.008934)
		(width 0.09525)
		(layer "In4.Cu")
		(net "M_J_CPU0_SA_DQS_DN<1>")
	)
	(segment
		(start 388.196328 -232.008934)
		(end 388.20471 -232.004108)
		(width 0.09525)
		(layer "In4.Cu")
		(net "M_J_CPU0_SA_DQS_DN<1>")
	)
	(segment
		(start 427.980602 -210.512152)
		(end 428.356776 -210.888326)
		(width 0.16002)
		(layer "In4.Cu")
		(net "M_J_CPU0_SA_DQS_DN<1>")
	)
	(segment
		(start 434.358288 -210.118706)
		(end 434.973476 -210.118706)
		(width 0.16002)
		(layer "In4.Cu")
		(net "M_J_CPU0_SA_DQS_DN<1>")
	)
	(segment
		(start 395.194536 -228.062282)
		(end 395.497304 -227.759514)
		(width 0.09525)
		(layer "In4.Cu")
		(net "M_J_CPU0_SA_DQS_DN<1>")
	)
	(segment
		(start 392.071098 -231.920542)
		(end 392.584686 -231.4067)
		(width 0.09525)
		(layer "In4.Cu")
		(net "M_J_CPU0_SA_DQS_DN<1>")
	)
	(arc
		(start 380.734316 -231.981756)
		(mid 380.892066 -231.959237)
		(end 381.044958 -232.004108)
		(width 0.09525)
		(layer "In4.Cu")
		(net "M_J_CPU0_SA_DQS_DN<1>")
	)
	(arc
		(start 382.56464 -232.004108)
		(mid 382.749672 -231.958194)
		(end 382.933448 -232.008934)
		(width 0.09525)
		(layer "In4.Cu")
		(net "M_J_CPU0_SA_DQS_DN<1>")
	)
	(arc
		(start 383.504694 -232.004108)
		(mid 383.689726 -231.958194)
		(end 383.873502 -232.008934)
		(width 0.09525)
		(layer "In4.Cu")
		(net "M_J_CPU0_SA_DQS_DN<1>")
	)
	(arc
		(start 383.873502 -232.008934)
		(mid 384.154934 -232.084689)
		(end 384.436366 -232.008934)
		(width 0.09525)
		(layer "In4.Cu")
		(net "M_J_CPU0_SA_DQS_DN<1>")
	)
	(arc
		(start 390.076182 -232.008934)
		(mid 390.259957 -231.958162)
		(end 390.44499 -232.004108)
		(width 0.09525)
		(layer "In4.Cu")
		(net "M_J_CPU0_SA_DQS_DN<1>")
	)
	(arc
		(start 387.633464 -232.008934)
		(mid 387.914896 -232.084689)
		(end 388.196328 -232.008934)
		(width 0.09525)
		(layer "In4.Cu")
		(net "M_J_CPU0_SA_DQS_DN<1>")
	)
	(arc
		(start 382.933448 -232.008934)
		(mid 383.21488 -232.084689)
		(end 383.496312 -232.008934)
		(width 0.09525)
		(layer "In4.Cu")
		(net "M_J_CPU0_SA_DQS_DN<1>")
	)
	(arc
		(start 391.393426 -232.008934)
		(mid 391.668715 -232.084655)
		(end 391.945622 -232.01503)
		(width 0.09525)
		(layer "In4.Cu")
		(net "M_J_CPU0_SA_DQS_DN<1>")
	)
	(arc
		(start 385.376166 -232.008934)
		(mid 385.559941 -231.958162)
		(end 385.744974 -232.004108)
		(width 0.09525)
		(layer "In4.Cu")
		(net "M_J_CPU0_SA_DQS_DN<1>")
	)
	(arc
		(start 381.05334 -232.008934)
		(mid 381.334772 -232.084689)
		(end 381.616204 -232.008934)
		(width 0.09525)
		(layer "In4.Cu")
		(net "M_J_CPU0_SA_DQS_DN<1>")
	)
	(arc
		(start 385.753356 -232.008934)
		(mid 386.034788 -232.084689)
		(end 386.31622 -232.008934)
		(width 0.09525)
		(layer "In4.Cu")
		(net "M_J_CPU0_SA_DQS_DN<1>")
	)
	(arc
		(start 386.31622 -232.008934)
		(mid 386.499995 -231.958162)
		(end 386.685028 -232.004108)
		(width 0.09525)
		(layer "In4.Cu")
		(net "M_J_CPU0_SA_DQS_DN<1>")
	)
	(arc
		(start 389.136382 -232.008934)
		(mid 389.32485 -231.958257)
		(end 389.513318 -232.008934)
		(width 0.09525)
		(layer "In4.Cu")
		(net "M_J_CPU0_SA_DQS_DN<1>")
	)
	(arc
		(start 388.20471 -232.004108)
		(mid 388.389742 -231.958194)
		(end 388.573518 -232.008934)
		(width 0.09525)
		(layer "In4.Cu")
		(net "M_J_CPU0_SA_DQS_DN<1>")
	)
	(arc
		(start 386.69341 -232.008934)
		(mid 386.974842 -232.084689)
		(end 387.256274 -232.008934)
		(width 0.09525)
		(layer "In4.Cu")
		(net "M_J_CPU0_SA_DQS_DN<1>")
	)
	(arc
		(start 381.993394 -232.008934)
		(mid 382.274826 -232.084689)
		(end 382.556258 -232.008934)
		(width 0.09525)
		(layer "In4.Cu")
		(net "M_J_CPU0_SA_DQS_DN<1>")
	)
	(arc
		(start 392.064748 -231.926892)
		(mid 392.067936 -231.92373)
		(end 392.071098 -231.920542)
		(width 0.09525)
		(layer "In4.Cu")
		(net "M_J_CPU0_SA_DQS_DN<1>")
	)
	(arc
		(start 389.513318 -232.008934)
		(mid 389.79475 -232.084689)
		(end 390.076182 -232.008934)
		(width 0.09525)
		(layer "In4.Cu")
		(net "M_J_CPU0_SA_DQS_DN<1>")
	)
	(arc
		(start 384.436366 -232.008934)
		(mid 384.624834 -231.958257)
		(end 384.813302 -232.008934)
		(width 0.09525)
		(layer "In4.Cu")
		(net "M_J_CPU0_SA_DQS_DN<1>")
	)
	(arc
		(start 390.453372 -232.008934)
		(mid 390.734804 -232.084689)
		(end 391.016236 -232.008934)
		(width 0.09525)
		(layer "In4.Cu")
		(net "M_J_CPU0_SA_DQS_DN<1>")
	)
	(arc
		(start 391.956036 -232.008934)
		(mid 392.012885 -231.971218)
		(end 392.064748 -231.926892)
		(width 0.09525)
		(layer "In4.Cu")
		(net "M_J_CPU0_SA_DQS_DN<1>")
	)
	(arc
		(start 391.024618 -232.004108)
		(mid 391.20965 -231.958194)
		(end 391.393426 -232.008934)
		(width 0.09525)
		(layer "In4.Cu")
		(net "M_J_CPU0_SA_DQS_DN<1>")
	)
	(arc
		(start 381.616204 -232.008934)
		(mid 381.799979 -231.958162)
		(end 381.985012 -232.004108)
		(width 0.09525)
		(layer "In4.Cu")
		(net "M_J_CPU0_SA_DQS_DN<1>")
	)
	(arc
		(start 388.573518 -232.008934)
		(mid 388.85495 -232.084689)
		(end 389.136382 -232.008934)
		(width 0.09525)
		(layer "In4.Cu")
		(net "M_J_CPU0_SA_DQS_DN<1>")
	)
	(arc
		(start 384.813302 -232.008934)
		(mid 385.094734 -232.084689)
		(end 385.376166 -232.008934)
		(width 0.09525)
		(layer "In4.Cu")
		(net "M_J_CPU0_SA_DQS_DN<1>")
	)
	(arc
		(start 387.264656 -232.004108)
		(mid 387.449688 -231.958194)
		(end 387.633464 -232.008934)
		(width 0.09525)
		(layer "In4.Cu")
		(net "M_J_CPU0_SA_DQS_DN<1>")
	)
	(segment
		(start 380.39802 -227.74021)
		(end 380.864872 -227.474272)
		(width 0.12954)
		(layer "F.Cu")
		(net "M_J_CPU0_SA_DQS_DN<0>")
	)
	(segment
		(start 438.135776 -201.428096)
		(end 438.252616 -201.311256)
		(width 0.16002)
		(layer "In4.Cu")
		(net "M_J_CPU0_SA_DQS_DN<0>")
	)
	(segment
		(start 391.45464 -223.11741)
		(end 391.486136 -223.099122)
		(width 0.09525)
		(layer "In4.Cu")
		(net "M_J_CPU0_SA_DQS_DN<0>")
	)
	(segment
		(start 433.735988 -200.768712)
		(end 433.852828 -200.885552)
		(width 0.16002)
		(layer "In4.Cu")
		(net "M_J_CPU0_SA_DQS_DN<0>")
	)
	(segment
		(start 392.296142 -218.067382)
		(end 409.438602 -200.924922)
		(width 0.16002)
		(layer "In4.Cu")
		(net "M_J_CPU0_SA_DQS_DN<0>")
	)
	(segment
		(start 425.802298 -201.162158)
		(end 426.282358 -201.162158)
		(width 0.16002)
		(layer "In4.Cu")
		(net "M_J_CPU0_SA_DQS_DN<0>")
	)
	(segment
		(start 421.570912 -201.518012)
		(end 422.249092 -200.839832)
		(width 0.16002)
		(layer "In4.Cu")
		(net "M_J_CPU0_SA_DQS_DN<0>")
	)
	(segment
		(start 413.017716 -201.505312)
		(end 414.07334 -201.505312)
		(width 0.16002)
		(layer "In4.Cu")
		(net "M_J_CPU0_SA_DQS_DN<0>")
	)
	(segment
		(start 389.136382 -227.149152)
		(end 389.171434 -227.128578)
		(width 0.09525)
		(layer "In4.Cu")
		(net "M_J_CPU0_SA_DQS_DN<0>")
	)
	(segment
		(start 390.044686 -225.547428)
		(end 390.076182 -225.52914)
		(width 0.09525)
		(layer "In4.Cu")
		(net "M_J_CPU0_SA_DQS_DN<0>")
	)
	(segment
		(start 381.985012 -227.144326)
		(end 381.993394 -227.149152)
		(width 0.09525)
		(layer "In4.Cu")
		(net "M_J_CPU0_SA_DQS_DN<0>")
	)
	(segment
		(start 392.296142 -221.17431)
		(end 392.296142 -218.067382)
		(width 0.16002)
		(layer "In4.Cu")
		(net "M_J_CPU0_SA_DQS_DN<0>")
	)
	(segment
		(start 423.07764 -200.839832)
		(end 423.605198 -200.312274)
		(width 0.16002)
		(layer "In4.Cu")
		(net "M_J_CPU0_SA_DQS_DN<0>")
	)
	(segment
		(start 426.879258 -201.278998)
		(end 426.996098 -201.162158)
		(width 0.16002)
		(layer "In4.Cu")
		(net "M_J_CPU0_SA_DQS_DN<0>")
	)
	(segment
		(start 424.952414 -200.312274)
		(end 425.802298 -201.162158)
		(width 0.16002)
		(layer "In4.Cu")
		(net "M_J_CPU0_SA_DQS_DN<0>")
	)
	(segment
		(start 422.249092 -200.839832)
		(end 423.07764 -200.839832)
		(width 0.16002)
		(layer "In4.Cu")
		(net "M_J_CPU0_SA_DQS_DN<0>")
	)
	(segment
		(start 392.236452 -221.257622)
		(end 392.296142 -221.197932)
		(width 0.09525)
		(layer "In4.Cu")
		(net "M_J_CPU0_SA_DQS_DN<0>")
	)
	(segment
		(start 414.9471 -200.631552)
		(end 417.945316 -200.631552)
		(width 0.16002)
		(layer "In4.Cu")
		(net "M_J_CPU0_SA_DQS_DN<0>")
	)
	(segment
		(start 432.893978 -200.768712)
		(end 433.735988 -200.768712)
		(width 0.16002)
		(layer "In4.Cu")
		(net "M_J_CPU0_SA_DQS_DN<0>")
	)
	(segment
		(start 437.538876 -201.311256)
		(end 437.655716 -201.428096)
		(width 0.16002)
		(layer "In4.Cu")
		(net "M_J_CPU0_SA_DQS_DN<0>")
	)
	(segment
		(start 417.945316 -200.631552)
		(end 418.475922 -201.162158)
		(width 0.16002)
		(layer "In4.Cu")
		(net "M_J_CPU0_SA_DQS_DN<0>")
	)
	(segment
		(start 434.973476 -200.768712)
		(end 435.697376 -201.492612)
		(width 0.16002)
		(layer "In4.Cu")
		(net "M_J_CPU0_SA_DQS_DN<0>")
	)
	(segment
		(start 438.252616 -201.311256)
		(end 438.826402 -201.311256)
		(width 0.16002)
		(layer "In4.Cu")
		(net "M_J_CPU0_SA_DQS_DN<0>")
	)
	(segment
		(start 385.744974 -227.144326)
		(end 385.753356 -227.149152)
		(width 0.09525)
		(layer "In4.Cu")
		(net "M_J_CPU0_SA_DQS_DN<0>")
	)
	(segment
		(start 392.23696 -221.80423)
		(end 392.236452 -221.803722)
		(width 0.09525)
		(layer "In4.Cu")
		(net "M_J_CPU0_SA_DQS_DN<0>")
	)
	(segment
		(start 391.92454 -222.307404)
		(end 391.995406 -222.266256)
		(width 0.09525)
		(layer "In4.Cu")
		(net "M_J_CPU0_SA_DQS_DN<0>")
	)
	(segment
		(start 431.074576 -200.312274)
		(end 432.43754 -200.312274)
		(width 0.16002)
		(layer "In4.Cu")
		(net "M_J_CPU0_SA_DQS_DN<0>")
	)
	(segment
		(start 426.282358 -201.162158)
		(end 426.399198 -201.278998)
		(width 0.16002)
		(layer "In4.Cu")
		(net "M_J_CPU0_SA_DQS_DN<0>")
	)
	(segment
		(start 420.383462 -201.162158)
		(end 420.739316 -201.518012)
		(width 0.16002)
		(layer "In4.Cu")
		(net "M_J_CPU0_SA_DQS_DN<0>")
	)
	(segment
		(start 435.697376 -201.492612)
		(end 436.87746 -201.492612)
		(width 0.16002)
		(layer "In4.Cu")
		(net "M_J_CPU0_SA_DQS_DN<0>")
	)
	(segment
		(start 380.864872 -227.474272)
		(end 380.710948 -227.208842)
		(width 0.09525)
		(layer "In4.Cu")
		(net "M_J_CPU0_SA_DQS_DN<0>")
	)
	(segment
		(start 392.296142 -221.197932)
		(end 392.296142 -221.17431)
		(width 0.09525)
		(layer "In4.Cu")
		(net "M_J_CPU0_SA_DQS_DN<0>")
	)
	(segment
		(start 390.546336 -224.719134)
		(end 390.581388 -224.69856)
		(width 0.09525)
		(layer "In4.Cu")
		(net "M_J_CPU0_SA_DQS_DN<0>")
	)
	(segment
		(start 380.710948 -227.208842)
		(end 380.734316 -227.121974)
		(width 0.09525)
		(layer "In4.Cu")
		(net "M_J_CPU0_SA_DQS_DN<0>")
	)
	(segment
		(start 437.058816 -201.311256)
		(end 437.538876 -201.311256)
		(width 0.16002)
		(layer "In4.Cu")
		(net "M_J_CPU0_SA_DQS_DN<0>")
	)
	(segment
		(start 389.57377 -226.357942)
		(end 389.606282 -226.339146)
		(width 0.09525)
		(layer "In4.Cu")
		(net "M_J_CPU0_SA_DQS_DN<0>")
	)
	(segment
		(start 388.196328 -227.149152)
		(end 388.20471 -227.144326)
		(width 0.09525)
		(layer "In4.Cu")
		(net "M_J_CPU0_SA_DQS_DN<0>")
	)
	(segment
		(start 390.513824 -224.73793)
		(end 390.546336 -224.719134)
		(width 0.09525)
		(layer "In4.Cu")
		(net "M_J_CPU0_SA_DQS_DN<0>")
	)
	(segment
		(start 414.07334 -201.505312)
		(end 414.9471 -200.631552)
		(width 0.16002)
		(layer "In4.Cu")
		(net "M_J_CPU0_SA_DQS_DN<0>")
	)
	(segment
		(start 390.076182 -225.52914)
		(end 390.114282 -225.507042)
		(width 0.09525)
		(layer "In4.Cu")
		(net "M_J_CPU0_SA_DQS_DN<0>")
	)
	(segment
		(start 426.996098 -201.162158)
		(end 427.980602 -201.162158)
		(width 0.16002)
		(layer "In4.Cu")
		(net "M_J_CPU0_SA_DQS_DN<0>")
	)
	(segment
		(start 418.475922 -201.162158)
		(end 420.383462 -201.162158)
		(width 0.16002)
		(layer "In4.Cu")
		(net "M_J_CPU0_SA_DQS_DN<0>")
	)
	(segment
		(start 381.044958 -227.144326)
		(end 381.05334 -227.149152)
		(width 0.09525)
		(layer "In4.Cu")
		(net "M_J_CPU0_SA_DQS_DN<0>")
	)
	(segment
		(start 392.236452 -221.803722)
		(end 392.236452 -221.257622)
		(width 0.09525)
		(layer "In4.Cu")
		(net "M_J_CPU0_SA_DQS_DN<0>")
	)
	(segment
		(start 412.437326 -200.924922)
		(end 413.017716 -201.505312)
		(width 0.16002)
		(layer "In4.Cu")
		(net "M_J_CPU0_SA_DQS_DN<0>")
	)
	(segment
		(start 420.739316 -201.518012)
		(end 421.570912 -201.518012)
		(width 0.16002)
		(layer "In4.Cu")
		(net "M_J_CPU0_SA_DQS_DN<0>")
	)
	(segment
		(start 430.618138 -200.768712)
		(end 431.074576 -200.312274)
		(width 0.16002)
		(layer "In4.Cu")
		(net "M_J_CPU0_SA_DQS_DN<0>")
	)
	(segment
		(start 429.909224 -200.768712)
		(end 430.618138 -200.768712)
		(width 0.16002)
		(layer "In4.Cu")
		(net "M_J_CPU0_SA_DQS_DN<0>")
	)
	(segment
		(start 391.016236 -223.909128)
		(end 391.054336 -223.88703)
		(width 0.09525)
		(layer "In4.Cu")
		(net "M_J_CPU0_SA_DQS_DN<0>")
	)
	(segment
		(start 438.826402 -201.311256)
		(end 439.100214 -201.585068)
		(width 0.16002)
		(layer "In4.Cu")
		(net "M_J_CPU0_SA_DQS_DN<0>")
	)
	(segment
		(start 434.449728 -200.768712)
		(end 434.973476 -200.768712)
		(width 0.16002)
		(layer "In4.Cu")
		(net "M_J_CPU0_SA_DQS_DN<0>")
	)
	(segment
		(start 391.486136 -223.099122)
		(end 391.524236 -223.077024)
		(width 0.09525)
		(layer "In4.Cu")
		(net "M_J_CPU0_SA_DQS_DN<0>")
	)
	(segment
		(start 429.139604 -201.538332)
		(end 429.909224 -200.768712)
		(width 0.16002)
		(layer "In4.Cu")
		(net "M_J_CPU0_SA_DQS_DN<0>")
	)
	(segment
		(start 423.605198 -200.312274)
		(end 424.952414 -200.312274)
		(width 0.16002)
		(layer "In4.Cu")
		(net "M_J_CPU0_SA_DQS_DN<0>")
	)
	(segment
		(start 383.496312 -227.149152)
		(end 383.504694 -227.144326)
		(width 0.09525)
		(layer "In4.Cu")
		(net "M_J_CPU0_SA_DQS_DN<0>")
	)
	(segment
		(start 426.399198 -201.278998)
		(end 426.879258 -201.278998)
		(width 0.16002)
		(layer "In4.Cu")
		(net "M_J_CPU0_SA_DQS_DN<0>")
	)
	(segment
		(start 436.87746 -201.492612)
		(end 437.058816 -201.311256)
		(width 0.16002)
		(layer "In4.Cu")
		(net "M_J_CPU0_SA_DQS_DN<0>")
	)
	(segment
		(start 386.685028 -227.144326)
		(end 386.69341 -227.149152)
		(width 0.09525)
		(layer "In4.Cu")
		(net "M_J_CPU0_SA_DQS_DN<0>")
	)
	(segment
		(start 437.655716 -201.428096)
		(end 438.135776 -201.428096)
		(width 0.16002)
		(layer "In4.Cu")
		(net "M_J_CPU0_SA_DQS_DN<0>")
	)
	(segment
		(start 390.983724 -223.927924)
		(end 391.016236 -223.909128)
		(width 0.09525)
		(layer "In4.Cu")
		(net "M_J_CPU0_SA_DQS_DN<0>")
	)
	(segment
		(start 409.438602 -200.924922)
		(end 412.437326 -200.924922)
		(width 0.16002)
		(layer "In4.Cu")
		(net "M_J_CPU0_SA_DQS_DN<0>")
	)
	(segment
		(start 433.852828 -200.885552)
		(end 434.332888 -200.885552)
		(width 0.16002)
		(layer "In4.Cu")
		(net "M_J_CPU0_SA_DQS_DN<0>")
	)
	(segment
		(start 389.606282 -226.339146)
		(end 389.644382 -226.317048)
		(width 0.09525)
		(layer "In4.Cu")
		(net "M_J_CPU0_SA_DQS_DN<0>")
	)
	(segment
		(start 434.332888 -200.885552)
		(end 434.449728 -200.768712)
		(width 0.16002)
		(layer "In4.Cu")
		(net "M_J_CPU0_SA_DQS_DN<0>")
	)
	(segment
		(start 427.980602 -201.162158)
		(end 428.356776 -201.538332)
		(width 0.16002)
		(layer "In4.Cu")
		(net "M_J_CPU0_SA_DQS_DN<0>")
	)
	(segment
		(start 432.43754 -200.312274)
		(end 432.893978 -200.768712)
		(width 0.16002)
		(layer "In4.Cu")
		(net "M_J_CPU0_SA_DQS_DN<0>")
	)
	(segment
		(start 387.256274 -227.149152)
		(end 387.264656 -227.144326)
		(width 0.09525)
		(layer "In4.Cu")
		(net "M_J_CPU0_SA_DQS_DN<0>")
	)
	(segment
		(start 382.556258 -227.149152)
		(end 382.56464 -227.144326)
		(width 0.09525)
		(layer "In4.Cu")
		(net "M_J_CPU0_SA_DQS_DN<0>")
	)
	(segment
		(start 428.356776 -201.538332)
		(end 429.139604 -201.538332)
		(width 0.16002)
		(layer "In4.Cu")
		(net "M_J_CPU0_SA_DQS_DN<0>")
	)
	(arc
		(start 391.995406 -222.266256)
		(mid 392.172937 -222.064913)
		(end 392.23696 -221.80423)
		(width 0.09525)
		(layer "In4.Cu")
		(net "M_J_CPU0_SA_DQS_DN<0>")
	)
	(arc
		(start 391.054336 -223.88703)
		(mid 391.232786 -223.68556)
		(end 391.29716 -223.424242)
		(width 0.09525)
		(layer "In4.Cu")
		(net "M_J_CPU0_SA_DQS_DN<0>")
	)
	(arc
		(start 381.616204 -227.149152)
		(mid 381.799979 -227.09838)
		(end 381.985012 -227.144326)
		(width 0.09525)
		(layer "In4.Cu")
		(net "M_J_CPU0_SA_DQS_DN<0>")
	)
	(arc
		(start 380.734316 -227.121974)
		(mid 380.892066 -227.099455)
		(end 381.044958 -227.144326)
		(width 0.09525)
		(layer "In4.Cu")
		(net "M_J_CPU0_SA_DQS_DN<0>")
	)
	(arc
		(start 388.573518 -227.149152)
		(mid 388.85495 -227.224907)
		(end 389.136382 -227.149152)
		(width 0.09525)
		(layer "In4.Cu")
		(net "M_J_CPU0_SA_DQS_DN<0>")
	)
	(arc
		(start 389.644382 -226.317048)
		(mid 389.822832 -226.115578)
		(end 389.887206 -225.85426)
		(width 0.09525)
		(layer "In4.Cu")
		(net "M_J_CPU0_SA_DQS_DN<0>")
	)
	(arc
		(start 384.813302 -227.149152)
		(mid 385.094734 -227.224907)
		(end 385.376166 -227.149152)
		(width 0.09525)
		(layer "In4.Cu")
		(net "M_J_CPU0_SA_DQS_DN<0>")
	)
	(arc
		(start 382.933448 -227.149152)
		(mid 383.21488 -227.224907)
		(end 383.496312 -227.149152)
		(width 0.09525)
		(layer "In4.Cu")
		(net "M_J_CPU0_SA_DQS_DN<0>")
	)
	(arc
		(start 382.56464 -227.144326)
		(mid 382.749672 -227.098412)
		(end 382.933448 -227.149152)
		(width 0.09525)
		(layer "In4.Cu")
		(net "M_J_CPU0_SA_DQS_DN<0>")
	)
	(arc
		(start 389.417052 -226.664266)
		(mid 389.458509 -226.492226)
		(end 389.57377 -226.357942)
		(width 0.09525)
		(layer "In4.Cu")
		(net "M_J_CPU0_SA_DQS_DN<0>")
	)
	(arc
		(start 389.887206 -225.85426)
		(mid 389.928871 -225.681813)
		(end 390.044686 -225.547428)
		(width 0.09525)
		(layer "In4.Cu")
		(net "M_J_CPU0_SA_DQS_DN<0>")
	)
	(arc
		(start 381.05334 -227.149152)
		(mid 381.334772 -227.224907)
		(end 381.616204 -227.149152)
		(width 0.09525)
		(layer "In4.Cu")
		(net "M_J_CPU0_SA_DQS_DN<0>")
	)
	(arc
		(start 390.581388 -224.69856)
		(mid 390.761779 -224.496861)
		(end 390.827006 -224.234248)
		(width 0.09525)
		(layer "In4.Cu")
		(net "M_J_CPU0_SA_DQS_DN<0>")
	)
	(arc
		(start 391.524236 -223.077024)
		(mid 391.702686 -222.875554)
		(end 391.76706 -222.614236)
		(width 0.09525)
		(layer "In4.Cu")
		(net "M_J_CPU0_SA_DQS_DN<0>")
	)
	(arc
		(start 388.20471 -227.144326)
		(mid 388.389742 -227.098412)
		(end 388.573518 -227.149152)
		(width 0.09525)
		(layer "In4.Cu")
		(net "M_J_CPU0_SA_DQS_DN<0>")
	)
	(arc
		(start 389.171434 -227.128578)
		(mid 389.351825 -226.926879)
		(end 389.417052 -226.664266)
		(width 0.09525)
		(layer "In4.Cu")
		(net "M_J_CPU0_SA_DQS_DN<0>")
	)
	(arc
		(start 384.436366 -227.149152)
		(mid 384.624834 -227.098475)
		(end 384.813302 -227.149152)
		(width 0.09525)
		(layer "In4.Cu")
		(net "M_J_CPU0_SA_DQS_DN<0>")
	)
	(arc
		(start 387.264656 -227.144326)
		(mid 387.449688 -227.098412)
		(end 387.633464 -227.149152)
		(width 0.09525)
		(layer "In4.Cu")
		(net "M_J_CPU0_SA_DQS_DN<0>")
	)
	(arc
		(start 385.753356 -227.149152)
		(mid 386.034788 -227.224907)
		(end 386.31622 -227.149152)
		(width 0.09525)
		(layer "In4.Cu")
		(net "M_J_CPU0_SA_DQS_DN<0>")
	)
	(arc
		(start 383.504694 -227.144326)
		(mid 383.689726 -227.098412)
		(end 383.873502 -227.149152)
		(width 0.09525)
		(layer "In4.Cu")
		(net "M_J_CPU0_SA_DQS_DN<0>")
	)
	(arc
		(start 391.76706 -222.614236)
		(mid 391.808725 -222.441789)
		(end 391.92454 -222.307404)
		(width 0.09525)
		(layer "In4.Cu")
		(net "M_J_CPU0_SA_DQS_DN<0>")
	)
	(arc
		(start 390.114282 -225.507042)
		(mid 390.292732 -225.305572)
		(end 390.357106 -225.044254)
		(width 0.09525)
		(layer "In4.Cu")
		(net "M_J_CPU0_SA_DQS_DN<0>")
	)
	(arc
		(start 390.357106 -225.044254)
		(mid 390.398563 -224.872214)
		(end 390.513824 -224.73793)
		(width 0.09525)
		(layer "In4.Cu")
		(net "M_J_CPU0_SA_DQS_DN<0>")
	)
	(arc
		(start 386.69341 -227.149152)
		(mid 386.974842 -227.224907)
		(end 387.256274 -227.149152)
		(width 0.09525)
		(layer "In4.Cu")
		(net "M_J_CPU0_SA_DQS_DN<0>")
	)
	(arc
		(start 391.29716 -223.424242)
		(mid 391.338825 -223.251795)
		(end 391.45464 -223.11741)
		(width 0.09525)
		(layer "In4.Cu")
		(net "M_J_CPU0_SA_DQS_DN<0>")
	)
	(arc
		(start 390.827006 -224.234248)
		(mid 390.868463 -224.062208)
		(end 390.983724 -223.927924)
		(width 0.09525)
		(layer "In4.Cu")
		(net "M_J_CPU0_SA_DQS_DN<0>")
	)
	(arc
		(start 385.376166 -227.149152)
		(mid 385.559941 -227.09838)
		(end 385.744974 -227.144326)
		(width 0.09525)
		(layer "In4.Cu")
		(net "M_J_CPU0_SA_DQS_DN<0>")
	)
	(arc
		(start 386.31622 -227.149152)
		(mid 386.499995 -227.09838)
		(end 386.685028 -227.144326)
		(width 0.09525)
		(layer "In4.Cu")
		(net "M_J_CPU0_SA_DQS_DN<0>")
	)
	(arc
		(start 381.993394 -227.149152)
		(mid 382.274826 -227.224907)
		(end 382.556258 -227.149152)
		(width 0.09525)
		(layer "In4.Cu")
		(net "M_J_CPU0_SA_DQS_DN<0>")
	)
	(arc
		(start 387.633464 -227.149152)
		(mid 387.914896 -227.224907)
		(end 388.196328 -227.149152)
		(width 0.09525)
		(layer "In4.Cu")
		(net "M_J_CPU0_SA_DQS_DN<0>")
	)
	(arc
		(start 383.873502 -227.149152)
		(mid 384.154934 -227.224907)
		(end 384.436366 -227.149152)
		(width 0.09525)
		(layer "In4.Cu")
		(net "M_J_CPU0_SA_DQS_DN<0>")
	)
	(segment
		(start 378.517912 -230.97998)
		(end 378.984764 -230.714296)
		(width 0.10668)
		(layer "F.Cu")
		(net "M_J_CPU0_SA_DQ<9>")
	)
	(segment
		(start 392.997944 -228.64953)
		(end 393.062714 -228.64953)
		(width 0.0889)
		(layer "In4.Cu")
		(net "M_J_CPU0_SA_DQ<9>")
	)
	(segment
		(start 396.578582 -220.555312)
		(end 400.267424 -216.86647)
		(width 0.14478)
		(layer "In4.Cu")
		(net "M_J_CPU0_SA_DQ<9>")
	)
	(segment
		(start 400.267424 -216.86647)
		(end 401.085304 -216.86647)
		(width 0.14478)
		(layer "In4.Cu")
		(net "M_J_CPU0_SA_DQ<9>")
	)
	(segment
		(start 428.45863 -208.810098)
		(end 430.510442 -207.960214)
		(width 0.14478)
		(layer "In4.Cu")
		(net "M_J_CPU0_SA_DQ<9>")
	)
	(segment
		(start 425.224702 -207.960214)
		(end 427.276514 -208.810098)
		(width 0.14478)
		(layer "In4.Cu")
		(net "M_J_CPU0_SA_DQ<9>")
	)
	(segment
		(start 392.043158 -229.604316)
		(end 392.997944 -228.64953)
		(width 0.0889)
		(layer "In4.Cu")
		(net "M_J_CPU0_SA_DQ<9>")
	)
	(segment
		(start 381.043434 -231.041448)
		(end 381.051816 -231.036622)
		(width 0.0889)
		(layer "In4.Cu")
		(net "M_J_CPU0_SA_DQ<9>")
	)
	(segment
		(start 388.197852 -231.036622)
		(end 388.206234 -231.041448)
		(width 0.0889)
		(layer "In4.Cu")
		(net "M_J_CPU0_SA_DQ<9>")
	)
	(segment
		(start 392.043158 -229.911402)
		(end 392.043158 -229.604316)
		(width 0.0889)
		(layer "In4.Cu")
		(net "M_J_CPU0_SA_DQ<9>")
	)
	(segment
		(start 417.50488 -207.960214)
		(end 419.556692 -208.810098)
		(width 0.14478)
		(layer "In4.Cu")
		(net "M_J_CPU0_SA_DQ<9>")
	)
	(segment
		(start 381.983488 -231.041448)
		(end 381.99187 -231.036622)
		(width 0.0889)
		(layer "In4.Cu")
		(net "M_J_CPU0_SA_DQ<9>")
	)
	(segment
		(start 419.556692 -208.810098)
		(end 420.843456 -208.810098)
		(width 0.14478)
		(layer "In4.Cu")
		(net "M_J_CPU0_SA_DQ<9>")
	)
	(segment
		(start 415.527236 -207.960214)
		(end 417.50488 -207.960214)
		(width 0.14478)
		(layer "In4.Cu")
		(net "M_J_CPU0_SA_DQ<9>")
	)
	(segment
		(start 395.243558 -226.22129)
		(end 396.578582 -224.886266)
		(width 0.14478)
		(layer "In4.Cu")
		(net "M_J_CPU0_SA_DQ<9>")
	)
	(segment
		(start 394.981938 -226.48291)
		(end 395.243558 -226.22129)
		(width 0.0889)
		(layer "In4.Cu")
		(net "M_J_CPU0_SA_DQ<9>")
	)
	(segment
		(start 383.497836 -231.036622)
		(end 383.506218 -231.041448)
		(width 0.0889)
		(layer "In4.Cu")
		(net "M_J_CPU0_SA_DQ<9>")
	)
	(segment
		(start 401.085304 -216.86647)
		(end 409.141676 -208.810098)
		(width 0.14478)
		(layer "In4.Cu")
		(net "M_J_CPU0_SA_DQ<9>")
	)
	(segment
		(start 387.257798 -231.036622)
		(end 387.26618 -231.041448)
		(width 0.0889)
		(layer "In4.Cu")
		(net "M_J_CPU0_SA_DQ<9>")
	)
	(segment
		(start 391.391902 -231.036622)
		(end 391.426446 -231.016556)
		(width 0.0889)
		(layer "In4.Cu")
		(net "M_J_CPU0_SA_DQ<9>")
	)
	(segment
		(start 391.82548 -230.247952)
		(end 391.862056 -230.226616)
		(width 0.0889)
		(layer "In4.Cu")
		(net "M_J_CPU0_SA_DQ<9>")
	)
	(segment
		(start 386.683504 -231.041448)
		(end 386.691886 -231.036622)
		(width 0.0889)
		(layer "In4.Cu")
		(net "M_J_CPU0_SA_DQ<9>")
	)
	(segment
		(start 420.843456 -208.810098)
		(end 422.895268 -207.960214)
		(width 0.14478)
		(layer "In4.Cu")
		(net "M_J_CPU0_SA_DQ<9>")
	)
	(segment
		(start 413.475424 -208.810098)
		(end 415.527236 -207.960214)
		(width 0.14478)
		(layer "In4.Cu")
		(net "M_J_CPU0_SA_DQ<9>")
	)
	(segment
		(start 409.141676 -208.810098)
		(end 413.475424 -208.810098)
		(width 0.14478)
		(layer "In4.Cu")
		(net "M_J_CPU0_SA_DQ<9>")
	)
	(segment
		(start 391.01776 -231.036622)
		(end 391.026142 -231.041448)
		(width 0.0889)
		(layer "In4.Cu")
		(net "M_J_CPU0_SA_DQ<9>")
	)
	(segment
		(start 379.138942 -230.979726)
		(end 379.2347 -231.005126)
		(width 0.0889)
		(layer "In4.Cu")
		(net "M_J_CPU0_SA_DQ<9>")
	)
	(segment
		(start 396.578582 -224.886266)
		(end 396.578582 -220.555312)
		(width 0.14478)
		(layer "In4.Cu")
		(net "M_J_CPU0_SA_DQ<9>")
	)
	(segment
		(start 393.062714 -228.64953)
		(end 394.981938 -226.730306)
		(width 0.0889)
		(layer "In4.Cu")
		(net "M_J_CPU0_SA_DQ<9>")
	)
	(segment
		(start 430.510442 -207.960214)
		(end 436.96382 -207.960214)
		(width 0.14478)
		(layer "In4.Cu")
		(net "M_J_CPU0_SA_DQ<9>")
	)
	(segment
		(start 394.981938 -226.730306)
		(end 394.981938 -226.48291)
		(width 0.0889)
		(layer "In4.Cu")
		(net "M_J_CPU0_SA_DQ<9>")
	)
	(segment
		(start 422.895268 -207.960214)
		(end 425.224702 -207.960214)
		(width 0.14478)
		(layer "In4.Cu")
		(net "M_J_CPU0_SA_DQ<9>")
	)
	(segment
		(start 385.74345 -231.041448)
		(end 385.751832 -231.036622)
		(width 0.0889)
		(layer "In4.Cu")
		(net "M_J_CPU0_SA_DQ<9>")
	)
	(segment
		(start 382.557782 -231.036622)
		(end 382.566164 -231.041448)
		(width 0.0889)
		(layer "In4.Cu")
		(net "M_J_CPU0_SA_DQ<9>")
	)
	(segment
		(start 390.443466 -231.041448)
		(end 390.451848 -231.036622)
		(width 0.0889)
		(layer "In4.Cu")
		(net "M_J_CPU0_SA_DQ<9>")
	)
	(segment
		(start 436.96382 -207.960214)
		(end 439.100214 -208.385156)
		(width 0.14478)
		(layer "In4.Cu")
		(net "M_J_CPU0_SA_DQ<9>")
	)
	(segment
		(start 427.276514 -208.810098)
		(end 428.45863 -208.810098)
		(width 0.14478)
		(layer "In4.Cu")
		(net "M_J_CPU0_SA_DQ<9>")
	)
	(segment
		(start 378.984764 -230.714296)
		(end 379.138942 -230.979726)
		(width 0.0889)
		(layer "In4.Cu")
		(net "M_J_CPU0_SA_DQ<9>")
	)
	(arc
		(start 391.862056 -230.226616)
		(mid 391.994615 -230.093154)
		(end 392.043158 -229.911402)
		(width 0.0889)
		(layer "In4.Cu")
		(net "M_J_CPU0_SA_DQ<9>")
	)
	(arc
		(start 381.051816 -231.036622)
		(mid 381.334772 -230.960445)
		(end 381.617728 -231.036622)
		(width 0.0889)
		(layer "In4.Cu")
		(net "M_J_CPU0_SA_DQ<9>")
	)
	(arc
		(start 390.451848 -231.036622)
		(mid 390.734804 -230.960445)
		(end 391.01776 -231.036622)
		(width 0.0889)
		(layer "In4.Cu")
		(net "M_J_CPU0_SA_DQ<9>")
	)
	(arc
		(start 391.426446 -231.016556)
		(mid 391.539111 -230.883715)
		(end 391.579608 -230.714296)
		(width 0.0889)
		(layer "In4.Cu")
		(net "M_J_CPU0_SA_DQ<9>")
	)
	(arc
		(start 379.737874 -231.036622)
		(mid 379.924818 -231.086911)
		(end 380.111762 -231.036622)
		(width 0.0889)
		(layer "In4.Cu")
		(net "M_J_CPU0_SA_DQ<9>")
	)
	(arc
		(start 384.43789 -231.036622)
		(mid 384.624834 -231.086911)
		(end 384.811778 -231.036622)
		(width 0.0889)
		(layer "In4.Cu")
		(net "M_J_CPU0_SA_DQ<9>")
	)
	(arc
		(start 387.63194 -231.036622)
		(mid 387.914896 -230.960445)
		(end 388.197852 -231.036622)
		(width 0.0889)
		(layer "In4.Cu")
		(net "M_J_CPU0_SA_DQ<9>")
	)
	(arc
		(start 384.811778 -231.036622)
		(mid 385.094734 -230.960445)
		(end 385.37769 -231.036622)
		(width 0.0889)
		(layer "In4.Cu")
		(net "M_J_CPU0_SA_DQ<9>")
	)
	(arc
		(start 381.617728 -231.036622)
		(mid 381.799979 -231.087006)
		(end 381.983488 -231.041448)
		(width 0.0889)
		(layer "In4.Cu")
		(net "M_J_CPU0_SA_DQ<9>")
	)
	(arc
		(start 387.26618 -231.041448)
		(mid 387.449688 -231.086973)
		(end 387.63194 -231.036622)
		(width 0.0889)
		(layer "In4.Cu")
		(net "M_J_CPU0_SA_DQ<9>")
	)
	(arc
		(start 391.579608 -230.714296)
		(mid 391.644844 -230.450705)
		(end 391.82548 -230.247952)
		(width 0.0889)
		(layer "In4.Cu")
		(net "M_J_CPU0_SA_DQ<9>")
	)
	(arc
		(start 382.566164 -231.041448)
		(mid 382.749672 -231.086973)
		(end 382.931924 -231.036622)
		(width 0.0889)
		(layer "In4.Cu")
		(net "M_J_CPU0_SA_DQ<9>")
	)
	(arc
		(start 388.571994 -231.036622)
		(mid 388.85495 -230.960445)
		(end 389.137906 -231.036622)
		(width 0.0889)
		(layer "In4.Cu")
		(net "M_J_CPU0_SA_DQ<9>")
	)
	(arc
		(start 385.751832 -231.036622)
		(mid 386.034788 -230.960445)
		(end 386.317744 -231.036622)
		(width 0.0889)
		(layer "In4.Cu")
		(net "M_J_CPU0_SA_DQ<9>")
	)
	(arc
		(start 379.2347 -231.005126)
		(mid 379.490022 -230.961426)
		(end 379.737874 -231.036622)
		(width 0.0889)
		(layer "In4.Cu")
		(net "M_J_CPU0_SA_DQ<9>")
	)
	(arc
		(start 382.931924 -231.036622)
		(mid 383.21488 -230.960445)
		(end 383.497836 -231.036622)
		(width 0.0889)
		(layer "In4.Cu")
		(net "M_J_CPU0_SA_DQ<9>")
	)
	(arc
		(start 383.506218 -231.041448)
		(mid 383.689726 -231.086973)
		(end 383.871978 -231.036622)
		(width 0.0889)
		(layer "In4.Cu")
		(net "M_J_CPU0_SA_DQ<9>")
	)
	(arc
		(start 389.137906 -231.036622)
		(mid 389.32485 -231.086911)
		(end 389.511794 -231.036622)
		(width 0.0889)
		(layer "In4.Cu")
		(net "M_J_CPU0_SA_DQ<9>")
	)
	(arc
		(start 389.511794 -231.036622)
		(mid 389.79475 -230.960445)
		(end 390.077706 -231.036622)
		(width 0.0889)
		(layer "In4.Cu")
		(net "M_J_CPU0_SA_DQ<9>")
	)
	(arc
		(start 380.677674 -231.036622)
		(mid 380.859925 -231.087006)
		(end 381.043434 -231.041448)
		(width 0.0889)
		(layer "In4.Cu")
		(net "M_J_CPU0_SA_DQ<9>")
	)
	(arc
		(start 386.317744 -231.036622)
		(mid 386.499995 -231.087006)
		(end 386.683504 -231.041448)
		(width 0.0889)
		(layer "In4.Cu")
		(net "M_J_CPU0_SA_DQ<9>")
	)
	(arc
		(start 386.691886 -231.036622)
		(mid 386.974842 -230.960445)
		(end 387.257798 -231.036622)
		(width 0.0889)
		(layer "In4.Cu")
		(net "M_J_CPU0_SA_DQ<9>")
	)
	(arc
		(start 383.871978 -231.036622)
		(mid 384.154934 -230.960445)
		(end 384.43789 -231.036622)
		(width 0.0889)
		(layer "In4.Cu")
		(net "M_J_CPU0_SA_DQ<9>")
	)
	(arc
		(start 381.99187 -231.036622)
		(mid 382.274826 -230.960445)
		(end 382.557782 -231.036622)
		(width 0.0889)
		(layer "In4.Cu")
		(net "M_J_CPU0_SA_DQ<9>")
	)
	(arc
		(start 380.111762 -231.036622)
		(mid 380.394718 -230.960445)
		(end 380.677674 -231.036622)
		(width 0.0889)
		(layer "In4.Cu")
		(net "M_J_CPU0_SA_DQ<9>")
	)
	(arc
		(start 390.077706 -231.036622)
		(mid 390.259957 -231.087006)
		(end 390.443466 -231.041448)
		(width 0.0889)
		(layer "In4.Cu")
		(net "M_J_CPU0_SA_DQ<9>")
	)
	(arc
		(start 388.206234 -231.041448)
		(mid 388.389742 -231.086973)
		(end 388.571994 -231.036622)
		(width 0.0889)
		(layer "In4.Cu")
		(net "M_J_CPU0_SA_DQ<9>")
	)
	(arc
		(start 385.37769 -231.036622)
		(mid 385.559941 -231.087006)
		(end 385.74345 -231.041448)
		(width 0.0889)
		(layer "In4.Cu")
		(net "M_J_CPU0_SA_DQ<9>")
	)
	(arc
		(start 391.026142 -231.041448)
		(mid 391.20965 -231.086973)
		(end 391.391902 -231.036622)
		(width 0.0889)
		(layer "In4.Cu")
		(net "M_J_CPU0_SA_DQ<9>")
	)
	(segment
		(start 379.927866 -230.169974)
		(end 380.394718 -229.904036)
		(width 0.10668)
		(layer "F.Cu")
		(net "M_J_CPU0_SA_DQ<8>")
	)
	(segment
		(start 422.474898 -206.260192)
		(end 425.711874 -206.260192)
		(width 0.14478)
		(layer "In4.Cu")
		(net "M_J_CPU0_SA_DQ<8>")
	)
	(segment
		(start 395.679422 -220.179392)
		(end 404.944834 -210.91398)
		(width 0.14478)
		(layer "In4.Cu")
		(net "M_J_CPU0_SA_DQ<8>")
	)
	(segment
		(start 418.566854 -207.110076)
		(end 421.625014 -207.110076)
		(width 0.14478)
		(layer "In4.Cu")
		(net "M_J_CPU0_SA_DQ<8>")
	)
	(segment
		(start 395.679422 -223.947228)
		(end 395.679422 -220.179392)
		(width 0.14478)
		(layer "In4.Cu")
		(net "M_J_CPU0_SA_DQ<8>")
	)
	(segment
		(start 383.393442 -230.231442)
		(end 383.401824 -230.226616)
		(width 0.0889)
		(layer "In4.Cu")
		(net "M_J_CPU0_SA_DQ<8>")
	)
	(segment
		(start 389.033512 -230.231442)
		(end 389.041894 -230.226616)
		(width 0.0889)
		(layer "In4.Cu")
		(net "M_J_CPU0_SA_DQ<8>")
	)
	(segment
		(start 392.267948 -228.739192)
		(end 392.267948 -227.787962)
		(width 0.0889)
		(layer "In4.Cu")
		(net "M_J_CPU0_SA_DQ<8>")
	)
	(segment
		(start 388.093458 -230.231442)
		(end 388.10184 -230.226616)
		(width 0.0889)
		(layer "In4.Cu")
		(net "M_J_CPU0_SA_DQ<8>")
	)
	(segment
		(start 421.625014 -207.110076)
		(end 422.474898 -206.260192)
		(width 0.14478)
		(layer "In4.Cu")
		(net "M_J_CPU0_SA_DQ<8>")
	)
	(segment
		(start 404.944834 -210.91398)
		(end 405.759666 -210.91398)
		(width 0.14478)
		(layer "In4.Cu")
		(net "M_J_CPU0_SA_DQ<8>")
	)
	(segment
		(start 429.167544 -207.110076)
		(end 430.017428 -206.260192)
		(width 0.14478)
		(layer "In4.Cu")
		(net "M_J_CPU0_SA_DQ<8>")
	)
	(segment
		(start 405.759666 -210.91398)
		(end 409.56357 -207.110076)
		(width 0.14478)
		(layer "In4.Cu")
		(net "M_J_CPU0_SA_DQ<8>")
	)
	(segment
		(start 385.847844 -230.226616)
		(end 385.856226 -230.231442)
		(width 0.0889)
		(layer "In4.Cu")
		(net "M_J_CPU0_SA_DQ<8>")
	)
	(segment
		(start 384.90779 -230.226616)
		(end 384.916172 -230.231442)
		(width 0.0889)
		(layer "In4.Cu")
		(net "M_J_CPU0_SA_DQ<8>")
	)
	(segment
		(start 425.711874 -206.260192)
		(end 426.561758 -207.110076)
		(width 0.14478)
		(layer "In4.Cu")
		(net "M_J_CPU0_SA_DQ<8>")
	)
	(segment
		(start 414.114488 -207.110076)
		(end 414.964372 -206.260192)
		(width 0.14478)
		(layer "In4.Cu")
		(net "M_J_CPU0_SA_DQ<8>")
	)
	(segment
		(start 380.394718 -229.904036)
		(end 380.548896 -230.169466)
		(width 0.0889)
		(layer "In4.Cu")
		(net "M_J_CPU0_SA_DQ<8>")
	)
	(segment
		(start 380.548896 -230.169466)
		(end 380.645162 -230.194866)
		(width 0.0889)
		(layer "In4.Cu")
		(net "M_J_CPU0_SA_DQ<8>")
	)
	(segment
		(start 389.607806 -230.226616)
		(end 389.616188 -230.231442)
		(width 0.0889)
		(layer "In4.Cu")
		(net "M_J_CPU0_SA_DQ<8>")
	)
	(segment
		(start 391.674858 -229.332282)
		(end 392.267948 -228.739192)
		(width 0.0889)
		(layer "In4.Cu")
		(net "M_J_CPU0_SA_DQ<8>")
	)
	(segment
		(start 414.964372 -206.260192)
		(end 417.71697 -206.260192)
		(width 0.14478)
		(layer "In4.Cu")
		(net "M_J_CPU0_SA_DQ<8>")
	)
	(segment
		(start 384.333496 -230.231442)
		(end 384.341878 -230.226616)
		(width 0.0889)
		(layer "In4.Cu")
		(net "M_J_CPU0_SA_DQ<8>")
	)
	(segment
		(start 381.147828 -230.226616)
		(end 381.15621 -230.231442)
		(width 0.0889)
		(layer "In4.Cu")
		(net "M_J_CPU0_SA_DQ<8>")
	)
	(segment
		(start 391.674858 -229.338632)
		(end 391.674858 -229.332282)
		(width 0.0889)
		(layer "In4.Cu")
		(net "M_J_CPU0_SA_DQ<8>")
	)
	(segment
		(start 417.71697 -206.260192)
		(end 418.566854 -207.110076)
		(width 0.14478)
		(layer "In4.Cu")
		(net "M_J_CPU0_SA_DQ<8>")
	)
	(segment
		(start 394.911834 -224.714816)
		(end 395.679422 -223.947228)
		(width 0.0889)
		(layer "In4.Cu")
		(net "M_J_CPU0_SA_DQ<8>")
	)
	(segment
		(start 390.921748 -230.226616)
		(end 390.953498 -230.208328)
		(width 0.0889)
		(layer "In4.Cu")
		(net "M_J_CPU0_SA_DQ<8>")
	)
	(segment
		(start 409.56357 -207.110076)
		(end 414.114488 -207.110076)
		(width 0.14478)
		(layer "In4.Cu")
		(net "M_J_CPU0_SA_DQ<8>")
	)
	(segment
		(start 426.561758 -207.110076)
		(end 429.167544 -207.110076)
		(width 0.14478)
		(layer "In4.Cu")
		(net "M_J_CPU0_SA_DQ<8>")
	)
	(segment
		(start 392.267948 -227.787962)
		(end 394.911834 -225.144076)
		(width 0.0889)
		(layer "In4.Cu")
		(net "M_J_CPU0_SA_DQ<8>")
	)
	(segment
		(start 394.911834 -225.144076)
		(end 394.911834 -224.714816)
		(width 0.0889)
		(layer "In4.Cu")
		(net "M_J_CPU0_SA_DQ<8>")
	)
	(segment
		(start 430.017428 -206.260192)
		(end 436.96382 -206.260192)
		(width 0.14478)
		(layer "In4.Cu")
		(net "M_J_CPU0_SA_DQ<8>")
	)
	(segment
		(start 436.96382 -206.260192)
		(end 439.100214 -206.685134)
		(width 0.14478)
		(layer "In4.Cu")
		(net "M_J_CPU0_SA_DQ<8>")
	)
	(arc
		(start 383.967736 -230.226616)
		(mid 384.149987 -230.276966)
		(end 384.333496 -230.231442)
		(width 0.0889)
		(layer "In4.Cu")
		(net "M_J_CPU0_SA_DQ<8>")
	)
	(arc
		(start 381.15621 -230.231442)
		(mid 381.339718 -230.276936)
		(end 381.52197 -230.226616)
		(width 0.0889)
		(layer "In4.Cu")
		(net "M_J_CPU0_SA_DQ<8>")
	)
	(arc
		(start 388.10184 -230.226616)
		(mid 388.384796 -230.150473)
		(end 388.667752 -230.226616)
		(width 0.0889)
		(layer "In4.Cu")
		(net "M_J_CPU0_SA_DQ<8>")
	)
	(arc
		(start 385.856226 -230.231442)
		(mid 386.039734 -230.276936)
		(end 386.221986 -230.226616)
		(width 0.0889)
		(layer "In4.Cu")
		(net "M_J_CPU0_SA_DQ<8>")
	)
	(arc
		(start 380.645162 -230.194866)
		(mid 380.900227 -230.151535)
		(end 381.147828 -230.226616)
		(width 0.0889)
		(layer "In4.Cu")
		(net "M_J_CPU0_SA_DQ<8>")
	)
	(arc
		(start 384.341878 -230.226616)
		(mid 384.624834 -230.150473)
		(end 384.90779 -230.226616)
		(width 0.0889)
		(layer "In4.Cu")
		(net "M_J_CPU0_SA_DQ<8>")
	)
	(arc
		(start 382.087882 -230.226616)
		(mid 382.274826 -230.276871)
		(end 382.46177 -230.226616)
		(width 0.0889)
		(layer "In4.Cu")
		(net "M_J_CPU0_SA_DQ<8>")
	)
	(arc
		(start 390.953498 -230.208328)
		(mid 391.068174 -230.074994)
		(end 391.109454 -229.904036)
		(width 0.0889)
		(layer "In4.Cu")
		(net "M_J_CPU0_SA_DQ<8>")
	)
	(arc
		(start 391.109454 -229.904036)
		(mid 391.173969 -229.641817)
		(end 391.352786 -229.43947)
		(width 0.0889)
		(layer "In4.Cu")
		(net "M_J_CPU0_SA_DQ<8>")
	)
	(arc
		(start 389.616188 -230.231442)
		(mid 389.799696 -230.276936)
		(end 389.981948 -230.226616)
		(width 0.0889)
		(layer "In4.Cu")
		(net "M_J_CPU0_SA_DQ<8>")
	)
	(arc
		(start 383.401824 -230.226616)
		(mid 383.68478 -230.150473)
		(end 383.967736 -230.226616)
		(width 0.0889)
		(layer "In4.Cu")
		(net "M_J_CPU0_SA_DQ<8>")
	)
	(arc
		(start 388.667752 -230.226616)
		(mid 388.850003 -230.276966)
		(end 389.033512 -230.231442)
		(width 0.0889)
		(layer "In4.Cu")
		(net "M_J_CPU0_SA_DQ<8>")
	)
	(arc
		(start 385.281932 -230.226616)
		(mid 385.564888 -230.150473)
		(end 385.847844 -230.226616)
		(width 0.0889)
		(layer "In4.Cu")
		(net "M_J_CPU0_SA_DQ<8>")
	)
	(arc
		(start 389.981948 -230.226616)
		(mid 390.264904 -230.150473)
		(end 390.54786 -230.226616)
		(width 0.0889)
		(layer "In4.Cu")
		(net "M_J_CPU0_SA_DQ<8>")
	)
	(arc
		(start 390.54786 -230.226616)
		(mid 390.734804 -230.276871)
		(end 390.921748 -230.226616)
		(width 0.0889)
		(layer "In4.Cu")
		(net "M_J_CPU0_SA_DQ<8>")
	)
	(arc
		(start 382.46177 -230.226616)
		(mid 382.744726 -230.150473)
		(end 383.027682 -230.226616)
		(width 0.0889)
		(layer "In4.Cu")
		(net "M_J_CPU0_SA_DQ<8>")
	)
	(arc
		(start 387.161786 -230.226616)
		(mid 387.444742 -230.150473)
		(end 387.727698 -230.226616)
		(width 0.0889)
		(layer "In4.Cu")
		(net "M_J_CPU0_SA_DQ<8>")
	)
	(arc
		(start 381.52197 -230.226616)
		(mid 381.804926 -230.150473)
		(end 382.087882 -230.226616)
		(width 0.0889)
		(layer "In4.Cu")
		(net "M_J_CPU0_SA_DQ<8>")
	)
	(arc
		(start 386.787898 -230.226616)
		(mid 386.974842 -230.276871)
		(end 387.161786 -230.226616)
		(width 0.0889)
		(layer "In4.Cu")
		(net "M_J_CPU0_SA_DQ<8>")
	)
	(arc
		(start 383.027682 -230.226616)
		(mid 383.209933 -230.276966)
		(end 383.393442 -230.231442)
		(width 0.0889)
		(layer "In4.Cu")
		(net "M_J_CPU0_SA_DQ<8>")
	)
	(arc
		(start 387.727698 -230.226616)
		(mid 387.909949 -230.276966)
		(end 388.093458 -230.231442)
		(width 0.0889)
		(layer "In4.Cu")
		(net "M_J_CPU0_SA_DQ<8>")
	)
	(arc
		(start 384.916172 -230.231442)
		(mid 385.09968 -230.276936)
		(end 385.281932 -230.226616)
		(width 0.0889)
		(layer "In4.Cu")
		(net "M_J_CPU0_SA_DQ<8>")
	)
	(arc
		(start 391.352786 -229.43947)
		(mid 391.506121 -229.364446)
		(end 391.674858 -229.338632)
		(width 0.0889)
		(layer "In4.Cu")
		(net "M_J_CPU0_SA_DQ<8>")
	)
	(arc
		(start 389.041894 -230.226616)
		(mid 389.32485 -230.150473)
		(end 389.607806 -230.226616)
		(width 0.0889)
		(layer "In4.Cu")
		(net "M_J_CPU0_SA_DQ<8>")
	)
	(arc
		(start 386.221986 -230.226616)
		(mid 386.504942 -230.150473)
		(end 386.787898 -230.226616)
		(width 0.0889)
		(layer "In4.Cu")
		(net "M_J_CPU0_SA_DQ<8>")
	)
	(segment
		(start 378.988066 -230.169974)
		(end 379.454918 -229.904036)
		(width 0.10668)
		(layer "F.Cu")
		(net "M_J_CPU0_SA_DQ<7>")
	)
	(segment
		(start 406.579578 -209.272124)
		(end 406.74163 -209.110072)
		(width 0.14478)
		(layer "In4.Cu")
		(net "M_J_CPU0_SA_DQ<7>")
	)
	(segment
		(start 418.551106 -206.260192)
		(end 421.602662 -206.260192)
		(width 0.14478)
		(layer "In4.Cu")
		(net "M_J_CPU0_SA_DQ<7>")
	)
	(segment
		(start 393.587732 -225.194114)
		(end 395.128242 -223.653604)
		(width 0.0889)
		(layer "In4.Cu")
		(net "M_J_CPU0_SA_DQ<7>")
	)
	(segment
		(start 395.576552 -219.274136)
		(end 395.41831 -219.115894)
		(width 0.14478)
		(layer "In4.Cu")
		(net "M_J_CPU0_SA_DQ<7>")
	)
	(segment
		(start 395.576552 -219.502228)
		(end 395.576552 -219.274136)
		(width 0.14478)
		(layer "In4.Cu")
		(net "M_J_CPU0_SA_DQ<7>")
	)
	(segment
		(start 395.128242 -219.950538)
		(end 395.576552 -219.502228)
		(width 0.14478)
		(layer "In4.Cu")
		(net "M_J_CPU0_SA_DQ<7>")
	)
	(segment
		(start 396.975076 -218.103704)
		(end 397.137128 -217.941652)
		(width 0.14478)
		(layer "In4.Cu")
		(net "M_J_CPU0_SA_DQ<7>")
	)
	(segment
		(start 408.818588 -206.260192)
		(end 414.005776 -206.260192)
		(width 0.14478)
		(layer "In4.Cu")
		(net "M_J_CPU0_SA_DQ<7>")
	)
	(segment
		(start 390.98601 -228.789992)
		(end 391.01776 -228.771704)
		(width 0.0889)
		(layer "In4.Cu")
		(net "M_J_CPU0_SA_DQ<7>")
	)
	(segment
		(start 406.193244 -209.113628)
		(end 406.351486 -209.272124)
		(width 0.14478)
		(layer "In4.Cu")
		(net "M_J_CPU0_SA_DQ<7>")
	)
	(segment
		(start 406.74163 -208.88198)
		(end 406.583388 -208.723738)
		(width 0.14478)
		(layer "In4.Cu")
		(net "M_J_CPU0_SA_DQ<7>")
	)
	(segment
		(start 396.978886 -217.555318)
		(end 396.978886 -217.326972)
		(width 0.14478)
		(layer "In4.Cu")
		(net "M_J_CPU0_SA_DQ<7>")
	)
	(segment
		(start 397.755364 -217.323416)
		(end 405.184864 -209.893916)
		(width 0.14478)
		(layer "In4.Cu")
		(net "M_J_CPU0_SA_DQ<7>")
	)
	(segment
		(start 405.184864 -209.893916)
		(end 405.412956 -209.893916)
		(width 0.14478)
		(layer "In4.Cu")
		(net "M_J_CPU0_SA_DQ<7>")
	)
	(segment
		(start 407.525728 -207.553052)
		(end 407.75382 -207.553052)
		(width 0.14478)
		(layer "In4.Cu")
		(net "M_J_CPU0_SA_DQ<7>")
	)
	(segment
		(start 396.588742 -217.945208)
		(end 396.746984 -218.103704)
		(width 0.14478)
		(layer "In4.Cu")
		(net "M_J_CPU0_SA_DQ<7>")
	)
	(segment
		(start 384.90779 -229.58171)
		(end 384.916172 -229.576884)
		(width 0.0889)
		(layer "In4.Cu")
		(net "M_J_CPU0_SA_DQ<7>")
	)
	(segment
		(start 390.54786 -229.58171)
		(end 390.584182 -229.560628)
		(width 0.0889)
		(layer "In4.Cu")
		(net "M_J_CPU0_SA_DQ<7>")
	)
	(segment
		(start 395.580362 -218.725496)
		(end 395.808454 -218.725496)
		(width 0.14478)
		(layer "In4.Cu")
		(net "M_J_CPU0_SA_DQ<7>")
	)
	(segment
		(start 405.961342 -209.89036)
		(end 405.961342 -209.662268)
		(width 0.14478)
		(layer "In4.Cu")
		(net "M_J_CPU0_SA_DQ<7>")
	)
	(segment
		(start 395.128242 -222.54464)
		(end 395.128242 -219.950538)
		(width 0.14478)
		(layer "In4.Cu")
		(net "M_J_CPU0_SA_DQ<7>")
	)
	(segment
		(start 407.131774 -208.491836)
		(end 407.359866 -208.491836)
		(width 0.14478)
		(layer "In4.Cu")
		(net "M_J_CPU0_SA_DQ<7>")
	)
	(segment
		(start 396.746984 -218.103704)
		(end 396.975076 -218.103704)
		(width 0.14478)
		(layer "In4.Cu")
		(net "M_J_CPU0_SA_DQ<7>")
	)
	(segment
		(start 389.033512 -229.576884)
		(end 389.041894 -229.58171)
		(width 0.0889)
		(layer "In4.Cu")
		(net "M_J_CPU0_SA_DQ<7>")
	)
	(segment
		(start 396.35684 -218.493848)
		(end 396.198598 -218.335606)
		(width 0.14478)
		(layer "In4.Cu")
		(net "M_J_CPU0_SA_DQ<7>")
	)
	(segment
		(start 393.587732 -226.075494)
		(end 393.587732 -225.194114)
		(width 0.0889)
		(layer "In4.Cu")
		(net "M_J_CPU0_SA_DQ<7>")
	)
	(segment
		(start 385.847844 -229.58171)
		(end 385.856226 -229.576884)
		(width 0.0889)
		(layer "In4.Cu")
		(net "M_J_CPU0_SA_DQ<7>")
	)
	(segment
		(start 408.140154 -207.711548)
		(end 408.302206 -207.549496)
		(width 0.14478)
		(layer "In4.Cu")
		(net "M_J_CPU0_SA_DQ<7>")
	)
	(segment
		(start 383.393442 -229.576884)
		(end 383.401824 -229.58171)
		(width 0.0889)
		(layer "In4.Cu")
		(net "M_J_CPU0_SA_DQ<7>")
	)
	(segment
		(start 421.602662 -206.260192)
		(end 422.4528 -205.410054)
		(width 0.14478)
		(layer "In4.Cu")
		(net "M_J_CPU0_SA_DQ<7>")
	)
	(segment
		(start 406.74163 -209.110072)
		(end 406.74163 -208.88198)
		(width 0.14478)
		(layer "In4.Cu")
		(net "M_J_CPU0_SA_DQ<7>")
	)
	(segment
		(start 395.808454 -218.725496)
		(end 395.966696 -218.883992)
		(width 0.14478)
		(layer "In4.Cu")
		(net "M_J_CPU0_SA_DQ<7>")
	)
	(segment
		(start 405.79929 -210.052412)
		(end 405.961342 -209.89036)
		(width 0.14478)
		(layer "In4.Cu")
		(net "M_J_CPU0_SA_DQ<7>")
	)
	(segment
		(start 407.521918 -208.329784)
		(end 407.521918 -208.101692)
		(width 0.14478)
		(layer "In4.Cu")
		(net "M_J_CPU0_SA_DQ<7>")
	)
	(segment
		(start 395.128242 -223.653604)
		(end 395.128242 -222.54464)
		(width 0.0889)
		(layer "In4.Cu")
		(net "M_J_CPU0_SA_DQ<7>")
	)
	(segment
		(start 430.004728 -205.410054)
		(end 432.21148 -205.410054)
		(width 0.14478)
		(layer "In4.Cu")
		(net "M_J_CPU0_SA_DQ<7>")
	)
	(segment
		(start 379.454918 -229.904036)
		(end 379.30074 -229.638606)
		(width 0.0889)
		(layer "In4.Cu")
		(net "M_J_CPU0_SA_DQ<7>")
	)
	(segment
		(start 395.966696 -218.883992)
		(end 396.194788 -218.883992)
		(width 0.14478)
		(layer "In4.Cu")
		(net "M_J_CPU0_SA_DQ<7>")
	)
	(segment
		(start 405.8031 -209.504026)
		(end 405.8031 -209.27568)
		(width 0.14478)
		(layer "In4.Cu")
		(net "M_J_CPU0_SA_DQ<7>")
	)
	(segment
		(start 397.140938 -217.16492)
		(end 397.36903 -217.16492)
		(width 0.14478)
		(layer "In4.Cu")
		(net "M_J_CPU0_SA_DQ<7>")
	)
	(segment
		(start 395.41831 -218.887548)
		(end 395.580362 -218.725496)
		(width 0.14478)
		(layer "In4.Cu")
		(net "M_J_CPU0_SA_DQ<7>")
	)
	(segment
		(start 408.302206 -207.321404)
		(end 408.143964 -207.163162)
		(width 0.14478)
		(layer "In4.Cu")
		(net "M_J_CPU0_SA_DQ<7>")
	)
	(segment
		(start 405.965152 -209.113628)
		(end 406.193244 -209.113628)
		(width 0.14478)
		(layer "In4.Cu")
		(net "M_J_CPU0_SA_DQ<7>")
	)
	(segment
		(start 407.359866 -208.491836)
		(end 407.521918 -208.329784)
		(width 0.14478)
		(layer "In4.Cu")
		(net "M_J_CPU0_SA_DQ<7>")
	)
	(segment
		(start 396.978886 -217.326972)
		(end 397.140938 -217.16492)
		(width 0.14478)
		(layer "In4.Cu")
		(net "M_J_CPU0_SA_DQ<7>")
	)
	(segment
		(start 407.521918 -208.101692)
		(end 407.363676 -207.94345)
		(width 0.14478)
		(layer "In4.Cu")
		(net "M_J_CPU0_SA_DQ<7>")
	)
	(segment
		(start 405.571198 -210.052412)
		(end 405.79929 -210.052412)
		(width 0.14478)
		(layer "In4.Cu")
		(net "M_J_CPU0_SA_DQ<7>")
	)
	(segment
		(start 406.973532 -208.33334)
		(end 407.131774 -208.491836)
		(width 0.14478)
		(layer "In4.Cu")
		(net "M_J_CPU0_SA_DQ<7>")
	)
	(segment
		(start 407.363676 -207.715104)
		(end 407.525728 -207.553052)
		(width 0.14478)
		(layer "In4.Cu")
		(net "M_J_CPU0_SA_DQ<7>")
	)
	(segment
		(start 433.071016 -205.410054)
		(end 433.314348 -205.410054)
		(width 0.14478)
		(layer "In4.Cu")
		(net "M_J_CPU0_SA_DQ<7>")
	)
	(segment
		(start 405.961342 -209.662268)
		(end 405.8031 -209.504026)
		(width 0.14478)
		(layer "In4.Cu")
		(net "M_J_CPU0_SA_DQ<7>")
	)
	(segment
		(start 432.519582 -205.101952)
		(end 432.762914 -205.101952)
		(width 0.14478)
		(layer "In4.Cu")
		(net "M_J_CPU0_SA_DQ<7>")
	)
	(segment
		(start 407.912062 -207.711548)
		(end 408.140154 -207.711548)
		(width 0.14478)
		(layer "In4.Cu")
		(net "M_J_CPU0_SA_DQ<7>")
	)
	(segment
		(start 384.333496 -229.576884)
		(end 384.341878 -229.58171)
		(width 0.0889)
		(layer "In4.Cu")
		(net "M_J_CPU0_SA_DQ<7>")
	)
	(segment
		(start 433.865782 -205.101952)
		(end 434.173884 -205.410054)
		(width 0.14478)
		(layer "In4.Cu")
		(net "M_J_CPU0_SA_DQ<7>")
	)
	(segment
		(start 397.137128 -217.71356)
		(end 396.978886 -217.555318)
		(width 0.14478)
		(layer "In4.Cu")
		(net "M_J_CPU0_SA_DQ<7>")
	)
	(segment
		(start 396.194788 -218.883992)
		(end 396.35684 -218.72194)
		(width 0.14478)
		(layer "In4.Cu")
		(net "M_J_CPU0_SA_DQ<7>")
	)
	(segment
		(start 397.36903 -217.16492)
		(end 397.527272 -217.323416)
		(width 0.14478)
		(layer "In4.Cu")
		(net "M_J_CPU0_SA_DQ<7>")
	)
	(segment
		(start 434.575204 -205.410054)
		(end 435.000146 -205.834996)
		(width 0.14478)
		(layer "In4.Cu")
		(net "M_J_CPU0_SA_DQ<7>")
	)
	(segment
		(start 406.74544 -208.33334)
		(end 406.973532 -208.33334)
		(width 0.14478)
		(layer "In4.Cu")
		(net "M_J_CPU0_SA_DQ<7>")
	)
	(segment
		(start 379.30074 -229.638606)
		(end 379.322838 -229.555548)
		(width 0.0889)
		(layer "In4.Cu")
		(net "M_J_CPU0_SA_DQ<7>")
	)
	(segment
		(start 414.855914 -205.410054)
		(end 417.700968 -205.410054)
		(width 0.14478)
		(layer "In4.Cu")
		(net "M_J_CPU0_SA_DQ<7>")
	)
	(segment
		(start 397.527272 -217.323416)
		(end 397.755364 -217.323416)
		(width 0.14478)
		(layer "In4.Cu")
		(net "M_J_CPU0_SA_DQ<7>")
	)
	(segment
		(start 405.8031 -209.27568)
		(end 405.965152 -209.113628)
		(width 0.14478)
		(layer "In4.Cu")
		(net "M_J_CPU0_SA_DQ<7>")
	)
	(segment
		(start 408.143964 -206.934816)
		(end 408.818588 -206.260192)
		(width 0.14478)
		(layer "In4.Cu")
		(net "M_J_CPU0_SA_DQ<7>")
	)
	(segment
		(start 432.762914 -205.101952)
		(end 433.071016 -205.410054)
		(width 0.14478)
		(layer "In4.Cu")
		(net "M_J_CPU0_SA_DQ<7>")
	)
	(segment
		(start 391.01776 -228.771704)
		(end 391.056876 -228.748844)
		(width 0.0889)
		(layer "In4.Cu")
		(net "M_J_CPU0_SA_DQ<7>")
	)
	(segment
		(start 391.75182 -227.911406)
		(end 393.587732 -226.075494)
		(width 0.0889)
		(layer "In4.Cu")
		(net "M_J_CPU0_SA_DQ<7>")
	)
	(segment
		(start 406.583388 -208.723738)
		(end 406.583388 -208.495392)
		(width 0.14478)
		(layer "In4.Cu")
		(net "M_J_CPU0_SA_DQ<7>")
	)
	(segment
		(start 434.173884 -205.410054)
		(end 434.575204 -205.410054)
		(width 0.14478)
		(layer "In4.Cu")
		(net "M_J_CPU0_SA_DQ<7>")
	)
	(segment
		(start 408.302206 -207.549496)
		(end 408.302206 -207.321404)
		(width 0.14478)
		(layer "In4.Cu")
		(net "M_J_CPU0_SA_DQ<7>")
	)
	(segment
		(start 380.207774 -229.58171)
		(end 380.216156 -229.576884)
		(width 0.0889)
		(layer "In4.Cu")
		(net "M_J_CPU0_SA_DQ<7>")
	)
	(segment
		(start 391.45718 -227.979478)
		(end 391.48766 -227.961698)
		(width 0.0889)
		(layer "In4.Cu")
		(net "M_J_CPU0_SA_DQ<7>")
	)
	(segment
		(start 433.62245 -205.101952)
		(end 433.865782 -205.101952)
		(width 0.14478)
		(layer "In4.Cu")
		(net "M_J_CPU0_SA_DQ<7>")
	)
	(segment
		(start 389.607806 -229.58171)
		(end 389.616188 -229.576884)
		(width 0.0889)
		(layer "In4.Cu")
		(net "M_J_CPU0_SA_DQ<7>")
	)
	(segment
		(start 395.41831 -219.115894)
		(end 395.41831 -218.887548)
		(width 0.14478)
		(layer "In4.Cu")
		(net "M_J_CPU0_SA_DQ<7>")
	)
	(segment
		(start 396.198598 -218.335606)
		(end 396.198598 -218.10726)
		(width 0.14478)
		(layer "In4.Cu")
		(net "M_J_CPU0_SA_DQ<7>")
	)
	(segment
		(start 381.147828 -229.58171)
		(end 381.15621 -229.576884)
		(width 0.0889)
		(layer "In4.Cu")
		(net "M_J_CPU0_SA_DQ<7>")
	)
	(segment
		(start 432.21148 -205.410054)
		(end 432.519582 -205.101952)
		(width 0.14478)
		(layer "In4.Cu")
		(net "M_J_CPU0_SA_DQ<7>")
	)
	(segment
		(start 407.75382 -207.553052)
		(end 407.912062 -207.711548)
		(width 0.14478)
		(layer "In4.Cu")
		(net "M_J_CPU0_SA_DQ<7>")
	)
	(segment
		(start 406.351486 -209.272124)
		(end 406.579578 -209.272124)
		(width 0.14478)
		(layer "In4.Cu")
		(net "M_J_CPU0_SA_DQ<7>")
	)
	(segment
		(start 426.521372 -206.260192)
		(end 429.15459 -206.260192)
		(width 0.14478)
		(layer "In4.Cu")
		(net "M_J_CPU0_SA_DQ<7>")
	)
	(segment
		(start 414.005776 -206.260192)
		(end 414.855914 -205.410054)
		(width 0.14478)
		(layer "In4.Cu")
		(net "M_J_CPU0_SA_DQ<7>")
	)
	(segment
		(start 422.4528 -205.410054)
		(end 425.671234 -205.410054)
		(width 0.14478)
		(layer "In4.Cu")
		(net "M_J_CPU0_SA_DQ<7>")
	)
	(segment
		(start 429.15459 -206.260192)
		(end 430.004728 -205.410054)
		(width 0.14478)
		(layer "In4.Cu")
		(net "M_J_CPU0_SA_DQ<7>")
	)
	(segment
		(start 388.093458 -229.576884)
		(end 388.10184 -229.58171)
		(width 0.0889)
		(layer "In4.Cu")
		(net "M_J_CPU0_SA_DQ<7>")
	)
	(segment
		(start 397.137128 -217.941652)
		(end 397.137128 -217.71356)
		(width 0.14478)
		(layer "In4.Cu")
		(net "M_J_CPU0_SA_DQ<7>")
	)
	(segment
		(start 417.700968 -205.410054)
		(end 418.551106 -206.260192)
		(width 0.14478)
		(layer "In4.Cu")
		(net "M_J_CPU0_SA_DQ<7>")
	)
	(segment
		(start 425.671234 -205.410054)
		(end 426.521372 -206.260192)
		(width 0.14478)
		(layer "In4.Cu")
		(net "M_J_CPU0_SA_DQ<7>")
	)
	(segment
		(start 396.198598 -218.10726)
		(end 396.36065 -217.945208)
		(width 0.14478)
		(layer "In4.Cu")
		(net "M_J_CPU0_SA_DQ<7>")
	)
	(segment
		(start 408.143964 -207.163162)
		(end 408.143964 -206.934816)
		(width 0.14478)
		(layer "In4.Cu")
		(net "M_J_CPU0_SA_DQ<7>")
	)
	(segment
		(start 406.583388 -208.495392)
		(end 406.74544 -208.33334)
		(width 0.14478)
		(layer "In4.Cu")
		(net "M_J_CPU0_SA_DQ<7>")
	)
	(segment
		(start 405.412956 -209.893916)
		(end 405.571198 -210.052412)
		(width 0.14478)
		(layer "In4.Cu")
		(net "M_J_CPU0_SA_DQ<7>")
	)
	(segment
		(start 407.363676 -207.94345)
		(end 407.363676 -207.715104)
		(width 0.14478)
		(layer "In4.Cu")
		(net "M_J_CPU0_SA_DQ<7>")
	)
	(segment
		(start 396.36065 -217.945208)
		(end 396.588742 -217.945208)
		(width 0.14478)
		(layer "In4.Cu")
		(net "M_J_CPU0_SA_DQ<7>")
	)
	(segment
		(start 433.314348 -205.410054)
		(end 433.62245 -205.101952)
		(width 0.14478)
		(layer "In4.Cu")
		(net "M_J_CPU0_SA_DQ<7>")
	)
	(segment
		(start 379.63348 -229.576884)
		(end 379.641862 -229.58171)
		(width 0.0889)
		(layer "In4.Cu")
		(net "M_J_CPU0_SA_DQ<7>")
	)
	(segment
		(start 391.674858 -227.911406)
		(end 391.75182 -227.911406)
		(width 0.0889)
		(layer "In4.Cu")
		(net "M_J_CPU0_SA_DQ<7>")
	)
	(segment
		(start 396.35684 -218.72194)
		(end 396.35684 -218.493848)
		(width 0.14478)
		(layer "In4.Cu")
		(net "M_J_CPU0_SA_DQ<7>")
	)
	(arc
		(start 391.056876 -228.748844)
		(mid 391.235689 -228.546494)
		(end 391.300208 -228.284278)
		(width 0.0889)
		(layer "In4.Cu")
		(net "M_J_CPU0_SA_DQ<7>")
	)
	(arc
		(start 380.216156 -229.576884)
		(mid 380.399664 -229.531359)
		(end 380.581916 -229.58171)
		(width 0.0889)
		(layer "In4.Cu")
		(net "M_J_CPU0_SA_DQ<7>")
	)
	(arc
		(start 383.967736 -229.58171)
		(mid 384.149987 -229.531326)
		(end 384.333496 -229.576884)
		(width 0.0889)
		(layer "In4.Cu")
		(net "M_J_CPU0_SA_DQ<7>")
	)
	(arc
		(start 388.10184 -229.58171)
		(mid 388.384796 -229.657887)
		(end 388.667752 -229.58171)
		(width 0.0889)
		(layer "In4.Cu")
		(net "M_J_CPU0_SA_DQ<7>")
	)
	(arc
		(start 379.322838 -229.555548)
		(mid 379.480489 -229.532236)
		(end 379.63348 -229.576884)
		(width 0.0889)
		(layer "In4.Cu")
		(net "M_J_CPU0_SA_DQ<7>")
	)
	(arc
		(start 381.15621 -229.576884)
		(mid 381.339718 -229.531359)
		(end 381.52197 -229.58171)
		(width 0.0889)
		(layer "In4.Cu")
		(net "M_J_CPU0_SA_DQ<7>")
	)
	(arc
		(start 381.52197 -229.58171)
		(mid 381.804926 -229.657887)
		(end 382.087882 -229.58171)
		(width 0.0889)
		(layer "In4.Cu")
		(net "M_J_CPU0_SA_DQ<7>")
	)
	(arc
		(start 387.161786 -229.58171)
		(mid 387.444742 -229.657887)
		(end 387.727698 -229.58171)
		(width 0.0889)
		(layer "In4.Cu")
		(net "M_J_CPU0_SA_DQ<7>")
	)
	(arc
		(start 386.787898 -229.58171)
		(mid 386.974842 -229.531421)
		(end 387.161786 -229.58171)
		(width 0.0889)
		(layer "In4.Cu")
		(net "M_J_CPU0_SA_DQ<7>")
	)
	(arc
		(start 386.221986 -229.58171)
		(mid 386.504942 -229.657887)
		(end 386.787898 -229.58171)
		(width 0.0889)
		(layer "In4.Cu")
		(net "M_J_CPU0_SA_DQ<7>")
	)
	(arc
		(start 384.916172 -229.576884)
		(mid 385.09968 -229.531359)
		(end 385.281932 -229.58171)
		(width 0.0889)
		(layer "In4.Cu")
		(net "M_J_CPU0_SA_DQ<7>")
	)
	(arc
		(start 390.830054 -229.094284)
		(mid 390.871309 -228.923313)
		(end 390.98601 -228.789992)
		(width 0.0889)
		(layer "In4.Cu")
		(net "M_J_CPU0_SA_DQ<7>")
	)
	(arc
		(start 389.616188 -229.576884)
		(mid 389.799696 -229.531359)
		(end 389.981948 -229.58171)
		(width 0.0889)
		(layer "In4.Cu")
		(net "M_J_CPU0_SA_DQ<7>")
	)
	(arc
		(start 385.281932 -229.58171)
		(mid 385.564888 -229.657887)
		(end 385.847844 -229.58171)
		(width 0.0889)
		(layer "In4.Cu")
		(net "M_J_CPU0_SA_DQ<7>")
	)
	(arc
		(start 385.856226 -229.576884)
		(mid 386.039734 -229.531359)
		(end 386.221986 -229.58171)
		(width 0.0889)
		(layer "In4.Cu")
		(net "M_J_CPU0_SA_DQ<7>")
	)
	(arc
		(start 387.727698 -229.58171)
		(mid 387.909949 -229.531326)
		(end 388.093458 -229.576884)
		(width 0.0889)
		(layer "In4.Cu")
		(net "M_J_CPU0_SA_DQ<7>")
	)
	(arc
		(start 389.981948 -229.58171)
		(mid 390.264904 -229.657887)
		(end 390.54786 -229.58171)
		(width 0.0889)
		(layer "In4.Cu")
		(net "M_J_CPU0_SA_DQ<7>")
	)
	(arc
		(start 383.027682 -229.58171)
		(mid 383.209933 -229.531326)
		(end 383.393442 -229.576884)
		(width 0.0889)
		(layer "In4.Cu")
		(net "M_J_CPU0_SA_DQ<7>")
	)
	(arc
		(start 379.641862 -229.58171)
		(mid 379.924818 -229.657887)
		(end 380.207774 -229.58171)
		(width 0.0889)
		(layer "In4.Cu")
		(net "M_J_CPU0_SA_DQ<7>")
	)
	(arc
		(start 380.581916 -229.58171)
		(mid 380.864872 -229.657887)
		(end 381.147828 -229.58171)
		(width 0.0889)
		(layer "In4.Cu")
		(net "M_J_CPU0_SA_DQ<7>")
	)
	(arc
		(start 388.667752 -229.58171)
		(mid 388.850003 -229.531326)
		(end 389.033512 -229.576884)
		(width 0.0889)
		(layer "In4.Cu")
		(net "M_J_CPU0_SA_DQ<7>")
	)
	(arc
		(start 389.041894 -229.58171)
		(mid 389.32485 -229.657887)
		(end 389.607806 -229.58171)
		(width 0.0889)
		(layer "In4.Cu")
		(net "M_J_CPU0_SA_DQ<7>")
	)
	(arc
		(start 384.341878 -229.58171)
		(mid 384.624834 -229.657887)
		(end 384.90779 -229.58171)
		(width 0.0889)
		(layer "In4.Cu")
		(net "M_J_CPU0_SA_DQ<7>")
	)
	(arc
		(start 382.46177 -229.58171)
		(mid 382.744726 -229.657887)
		(end 383.027682 -229.58171)
		(width 0.0889)
		(layer "In4.Cu")
		(net "M_J_CPU0_SA_DQ<7>")
	)
	(arc
		(start 391.300208 -228.284278)
		(mid 391.341757 -228.112856)
		(end 391.45718 -227.979478)
		(width 0.0889)
		(layer "In4.Cu")
		(net "M_J_CPU0_SA_DQ<7>")
	)
	(arc
		(start 382.087882 -229.58171)
		(mid 382.274826 -229.531421)
		(end 382.46177 -229.58171)
		(width 0.0889)
		(layer "In4.Cu")
		(net "M_J_CPU0_SA_DQ<7>")
	)
	(arc
		(start 391.48766 -227.961698)
		(mid 391.577936 -227.924193)
		(end 391.674858 -227.911406)
		(width 0.0889)
		(layer "In4.Cu")
		(net "M_J_CPU0_SA_DQ<7>")
	)
	(arc
		(start 383.401824 -229.58171)
		(mid 383.68478 -229.657887)
		(end 383.967736 -229.58171)
		(width 0.0889)
		(layer "In4.Cu")
		(net "M_J_CPU0_SA_DQ<7>")
	)
	(arc
		(start 390.584182 -229.560628)
		(mid 390.764834 -229.357883)
		(end 390.830054 -229.094284)
		(width 0.0889)
		(layer "In4.Cu")
		(net "M_J_CPU0_SA_DQ<7>")
	)
	(segment
		(start 380.39802 -229.360222)
		(end 380.864872 -229.094284)
		(width 0.10668)
		(layer "F.Cu")
		(net "M_J_CPU0_SA_DQ<6>")
	)
	(segment
		(start 398.448022 -215.33866)
		(end 398.610074 -215.176608)
		(width 0.14478)
		(layer "In4.Cu")
		(net "M_J_CPU0_SA_DQ<6>")
	)
	(segment
		(start 418.379148 -204.56017)
		(end 421.437054 -204.56017)
		(width 0.14478)
		(layer "In4.Cu")
		(net "M_J_CPU0_SA_DQ<6>")
	)
	(segment
		(start 421.437054 -204.56017)
		(end 422.287192 -203.710032)
		(width 0.14478)
		(layer "In4.Cu")
		(net "M_J_CPU0_SA_DQ<6>")
	)
	(segment
		(start 398.851628 -214.410036)
		(end 398.999964 -214.558372)
		(width 0.14478)
		(layer "In4.Cu")
		(net "M_J_CPU0_SA_DQ<6>")
	)
	(segment
		(start 390.98601 -227.16998)
		(end 391.01776 -227.151692)
		(width 0.0889)
		(layer "In4.Cu")
		(net "M_J_CPU0_SA_DQ<6>")
	)
	(segment
		(start 414.168082 -204.56017)
		(end 415.01822 -203.710032)
		(width 0.14478)
		(layer "In4.Cu")
		(net "M_J_CPU0_SA_DQ<6>")
	)
	(segment
		(start 390.077706 -228.771704)
		(end 390.116822 -228.748844)
		(width 0.0889)
		(layer "In4.Cu")
		(net "M_J_CPU0_SA_DQ<6>")
	)
	(segment
		(start 402.524976 -210.508596)
		(end 402.753068 -210.508596)
		(width 0.14478)
		(layer "In4.Cu")
		(net "M_J_CPU0_SA_DQ<6>")
	)
	(segment
		(start 409.226512 -204.56017)
		(end 414.168082 -204.56017)
		(width 0.14478)
		(layer "In4.Cu")
		(net "M_J_CPU0_SA_DQ<6>")
	)
	(segment
		(start 400.950938 -212.607652)
		(end 400.802348 -212.459316)
		(width 0.14478)
		(layer "In4.Cu")
		(net "M_J_CPU0_SA_DQ<6>")
	)
	(segment
		(start 400.9644 -212.069172)
		(end 401.192492 -212.069172)
		(width 0.14478)
		(layer "In4.Cu")
		(net "M_J_CPU0_SA_DQ<6>")
	)
	(segment
		(start 399.390362 -214.168228)
		(end 399.241772 -214.019892)
		(width 0.14478)
		(layer "In4.Cu")
		(net "M_J_CPU0_SA_DQ<6>")
	)
	(segment
		(start 397.829786 -215.956896)
		(end 397.829786 -215.728804)
		(width 0.14478)
		(layer "In4.Cu")
		(net "M_J_CPU0_SA_DQ<6>")
	)
	(segment
		(start 397.681196 -215.580468)
		(end 397.681196 -215.352376)
		(width 0.14478)
		(layer "In4.Cu")
		(net "M_J_CPU0_SA_DQ<6>")
	)
	(segment
		(start 415.01822 -203.710032)
		(end 417.52901 -203.710032)
		(width 0.14478)
		(layer "In4.Cu")
		(net "M_J_CPU0_SA_DQ<6>")
	)
	(segment
		(start 398.07134 -215.190324)
		(end 398.219676 -215.33866)
		(width 0.14478)
		(layer "In4.Cu")
		(net "M_J_CPU0_SA_DQ<6>")
	)
	(segment
		(start 391.45718 -226.359466)
		(end 391.48766 -226.341686)
		(width 0.0889)
		(layer "In4.Cu")
		(net "M_J_CPU0_SA_DQ<6>")
	)
	(segment
		(start 403.9235 -209.338164)
		(end 403.9235 -209.110072)
		(width 0.14478)
		(layer "In4.Cu")
		(net "M_J_CPU0_SA_DQ<6>")
	)
	(segment
		(start 400.412204 -212.84946)
		(end 400.56054 -212.997796)
		(width 0.14478)
		(layer "In4.Cu")
		(net "M_J_CPU0_SA_DQ<6>")
	)
	(segment
		(start 401.744688 -211.288884)
		(end 401.97278 -211.288884)
		(width 0.14478)
		(layer "In4.Cu")
		(net "M_J_CPU0_SA_DQ<6>")
	)
	(segment
		(start 392.397234 -224.739454)
		(end 392.427714 -224.721674)
		(width 0.0889)
		(layer "In4.Cu")
		(net "M_J_CPU0_SA_DQ<6>")
	)
	(segment
		(start 422.287192 -203.710032)
		(end 425.436538 -203.710032)
		(width 0.14478)
		(layer "In4.Cu")
		(net "M_J_CPU0_SA_DQ<6>")
	)
	(segment
		(start 397.439388 -216.118948)
		(end 397.667734 -216.118948)
		(width 0.14478)
		(layer "In4.Cu")
		(net "M_J_CPU0_SA_DQ<6>")
	)
	(segment
		(start 425.436538 -203.710032)
		(end 426.286676 -204.56017)
		(width 0.14478)
		(layer "In4.Cu")
		(net "M_J_CPU0_SA_DQ<6>")
	)
	(segment
		(start 402.753068 -210.508596)
		(end 402.901404 -210.656932)
		(width 0.14478)
		(layer "In4.Cu")
		(net "M_J_CPU0_SA_DQ<6>")
	)
	(segment
		(start 402.901404 -210.656932)
		(end 403.12975 -210.656932)
		(width 0.14478)
		(layer "In4.Cu")
		(net "M_J_CPU0_SA_DQ<6>")
	)
	(segment
		(start 394.229082 -222.35541)
		(end 394.229082 -222.085154)
		(width 0.0889)
		(layer "In4.Cu")
		(net "M_J_CPU0_SA_DQ<6>")
	)
	(segment
		(start 429.331882 -204.56017)
		(end 430.18202 -203.710032)
		(width 0.14478)
		(layer "In4.Cu")
		(net "M_J_CPU0_SA_DQ<6>")
	)
	(segment
		(start 404.46198 -209.096356)
		(end 404.690326 -209.096356)
		(width 0.14478)
		(layer "In4.Cu")
		(net "M_J_CPU0_SA_DQ<6>")
	)
	(segment
		(start 403.143212 -209.89036)
		(end 403.305264 -209.728308)
		(width 0.14478)
		(layer "In4.Cu")
		(net "M_J_CPU0_SA_DQ<6>")
	)
	(segment
		(start 398.610074 -215.176608)
		(end 398.610074 -214.948516)
		(width 0.14478)
		(layer "In4.Cu")
		(net "M_J_CPU0_SA_DQ<6>")
	)
	(segment
		(start 404.07209 -209.4865)
		(end 403.9235 -209.338164)
		(width 0.14478)
		(layer "In4.Cu")
		(net "M_J_CPU0_SA_DQ<6>")
	)
	(segment
		(start 417.52901 -203.710032)
		(end 418.379148 -204.56017)
		(width 0.14478)
		(layer "In4.Cu")
		(net "M_J_CPU0_SA_DQ<6>")
	)
	(segment
		(start 403.305264 -209.728308)
		(end 403.533356 -209.728308)
		(width 0.14478)
		(layer "In4.Cu")
		(net "M_J_CPU0_SA_DQ<6>")
	)
	(segment
		(start 402.362924 -210.89874)
		(end 402.362924 -210.670648)
		(width 0.14478)
		(layer "In4.Cu")
		(net "M_J_CPU0_SA_DQ<6>")
	)
	(segment
		(start 397.843248 -215.190324)
		(end 398.07134 -215.190324)
		(width 0.14478)
		(layer "In4.Cu")
		(net "M_J_CPU0_SA_DQ<6>")
	)
	(segment
		(start 402.511514 -211.047076)
		(end 402.362924 -210.89874)
		(width 0.14478)
		(layer "In4.Cu")
		(net "M_J_CPU0_SA_DQ<6>")
	)
	(segment
		(start 398.999964 -214.558372)
		(end 399.22831 -214.558372)
		(width 0.14478)
		(layer "In4.Cu")
		(net "M_J_CPU0_SA_DQ<6>")
	)
	(segment
		(start 403.143212 -210.118452)
		(end 403.143212 -209.89036)
		(width 0.14478)
		(layer "In4.Cu")
		(net "M_J_CPU0_SA_DQ<6>")
	)
	(segment
		(start 399.780252 -213.778084)
		(end 400.008598 -213.778084)
		(width 0.14478)
		(layer "In4.Cu")
		(net "M_J_CPU0_SA_DQ<6>")
	)
	(segment
		(start 400.17065 -213.38794)
		(end 400.02206 -213.239604)
		(width 0.14478)
		(layer "In4.Cu")
		(net "M_J_CPU0_SA_DQ<6>")
	)
	(segment
		(start 383.497836 -228.771704)
		(end 383.506218 -228.766878)
		(width 0.0889)
		(layer "In4.Cu")
		(net "M_J_CPU0_SA_DQ<6>")
	)
	(segment
		(start 404.07209 -209.714592)
		(end 404.07209 -209.4865)
		(width 0.14478)
		(layer "In4.Cu")
		(net "M_J_CPU0_SA_DQ<6>")
	)
	(segment
		(start 391.926064 -225.549968)
		(end 391.957814 -225.53168)
		(width 0.0889)
		(layer "In4.Cu")
		(net "M_J_CPU0_SA_DQ<6>")
	)
	(segment
		(start 380.864872 -229.094284)
		(end 380.710694 -228.828854)
		(width 0.0889)
		(layer "In4.Cu")
		(net "M_J_CPU0_SA_DQ<6>")
	)
	(segment
		(start 399.241772 -213.7918)
		(end 399.403824 -213.629748)
		(width 0.14478)
		(layer "In4.Cu")
		(net "M_J_CPU0_SA_DQ<6>")
	)
	(segment
		(start 391.48766 -226.341686)
		(end 391.526776 -226.318826)
		(width 0.0889)
		(layer "In4.Cu")
		(net "M_J_CPU0_SA_DQ<6>")
	)
	(segment
		(start 398.461484 -214.80018)
		(end 398.461484 -214.572088)
		(width 0.14478)
		(layer "In4.Cu")
		(net "M_J_CPU0_SA_DQ<6>")
	)
	(segment
		(start 399.241772 -214.019892)
		(end 399.241772 -213.7918)
		(width 0.14478)
		(layer "In4.Cu")
		(net "M_J_CPU0_SA_DQ<6>")
	)
	(segment
		(start 402.362924 -210.670648)
		(end 402.524976 -210.508596)
		(width 0.14478)
		(layer "In4.Cu")
		(net "M_J_CPU0_SA_DQ<6>")
	)
	(segment
		(start 402.349462 -211.43722)
		(end 402.511514 -211.275168)
		(width 0.14478)
		(layer "In4.Cu")
		(net "M_J_CPU0_SA_DQ<6>")
	)
	(segment
		(start 400.008598 -213.778084)
		(end 400.17065 -213.616032)
		(width 0.14478)
		(layer "In4.Cu")
		(net "M_J_CPU0_SA_DQ<6>")
	)
	(segment
		(start 403.681692 -209.876644)
		(end 403.910038 -209.876644)
		(width 0.14478)
		(layer "In4.Cu")
		(net "M_J_CPU0_SA_DQ<6>")
	)
	(segment
		(start 434.575204 -203.710032)
		(end 435.000146 -204.134974)
		(width 0.14478)
		(layer "In4.Cu")
		(net "M_J_CPU0_SA_DQ<6>")
	)
	(segment
		(start 402.511514 -211.275168)
		(end 402.511514 -211.047076)
		(width 0.14478)
		(layer "In4.Cu")
		(net "M_J_CPU0_SA_DQ<6>")
	)
	(segment
		(start 401.582636 -211.679028)
		(end 401.582636 -211.450936)
		(width 0.14478)
		(layer "In4.Cu")
		(net "M_J_CPU0_SA_DQ<6>")
	)
	(segment
		(start 380.710694 -228.828854)
		(end 380.733046 -228.745542)
		(width 0.0889)
		(layer "In4.Cu")
		(net "M_J_CPU0_SA_DQ<6>")
	)
	(segment
		(start 398.623536 -214.410036)
		(end 398.851628 -214.410036)
		(width 0.14478)
		(layer "In4.Cu")
		(net "M_J_CPU0_SA_DQ<6>")
	)
	(segment
		(start 402.121116 -211.43722)
		(end 402.349462 -211.43722)
		(width 0.14478)
		(layer "In4.Cu")
		(net "M_J_CPU0_SA_DQ<6>")
	)
	(segment
		(start 392.897868 -223.911668)
		(end 392.93419 -223.890586)
		(width 0.0889)
		(layer "In4.Cu")
		(net "M_J_CPU0_SA_DQ<6>")
	)
	(segment
		(start 403.910038 -209.876644)
		(end 404.07209 -209.714592)
		(width 0.14478)
		(layer "In4.Cu")
		(net "M_J_CPU0_SA_DQ<6>")
	)
	(segment
		(start 397.06296 -215.970612)
		(end 397.291052 -215.970612)
		(width 0.14478)
		(layer "In4.Cu")
		(net "M_J_CPU0_SA_DQ<6>")
	)
	(segment
		(start 398.610074 -214.948516)
		(end 398.461484 -214.80018)
		(width 0.14478)
		(layer "In4.Cu")
		(net "M_J_CPU0_SA_DQ<6>")
	)
	(segment
		(start 391.957814 -225.53168)
		(end 391.99693 -225.50882)
		(width 0.0889)
		(layer "In4.Cu")
		(net "M_J_CPU0_SA_DQ<6>")
	)
	(segment
		(start 401.569174 -212.217508)
		(end 401.731226 -212.055456)
		(width 0.14478)
		(layer "In4.Cu")
		(net "M_J_CPU0_SA_DQ<6>")
	)
	(segment
		(start 388.197852 -228.771704)
		(end 388.206234 -228.766878)
		(width 0.0889)
		(layer "In4.Cu")
		(net "M_J_CPU0_SA_DQ<6>")
	)
	(segment
		(start 401.192492 -212.069172)
		(end 401.340828 -212.217508)
		(width 0.14478)
		(layer "In4.Cu")
		(net "M_J_CPU0_SA_DQ<6>")
	)
	(segment
		(start 426.286676 -204.56017)
		(end 429.331882 -204.56017)
		(width 0.14478)
		(layer "In4.Cu")
		(net "M_J_CPU0_SA_DQ<6>")
	)
	(segment
		(start 392.866118 -223.929956)
		(end 392.897868 -223.911668)
		(width 0.0889)
		(layer "In4.Cu")
		(net "M_J_CPU0_SA_DQ<6>")
	)
	(segment
		(start 403.291802 -210.49488)
		(end 403.291802 -210.266788)
		(width 0.14478)
		(layer "In4.Cu")
		(net "M_J_CPU0_SA_DQ<6>")
	)
	(segment
		(start 400.950938 -212.835744)
		(end 400.950938 -212.607652)
		(width 0.14478)
		(layer "In4.Cu")
		(net "M_J_CPU0_SA_DQ<6>")
	)
	(segment
		(start 390.51611 -227.979986)
		(end 390.54786 -227.961698)
		(width 0.0889)
		(layer "In4.Cu")
		(net "M_J_CPU0_SA_DQ<6>")
	)
	(segment
		(start 400.02206 -213.011512)
		(end 400.184112 -212.84946)
		(width 0.14478)
		(layer "In4.Cu")
		(net "M_J_CPU0_SA_DQ<6>")
	)
	(segment
		(start 391.01776 -227.151692)
		(end 391.056876 -227.128832)
		(width 0.0889)
		(layer "In4.Cu")
		(net "M_J_CPU0_SA_DQ<6>")
	)
	(segment
		(start 401.340828 -212.217508)
		(end 401.569174 -212.217508)
		(width 0.14478)
		(layer "In4.Cu")
		(net "M_J_CPU0_SA_DQ<6>")
	)
	(segment
		(start 400.788886 -212.997796)
		(end 400.950938 -212.835744)
		(width 0.14478)
		(layer "In4.Cu")
		(net "M_J_CPU0_SA_DQ<6>")
	)
	(segment
		(start 397.829786 -215.728804)
		(end 397.681196 -215.580468)
		(width 0.14478)
		(layer "In4.Cu")
		(net "M_J_CPU0_SA_DQ<6>")
	)
	(segment
		(start 399.390362 -214.39632)
		(end 399.390362 -214.168228)
		(width 0.14478)
		(layer "In4.Cu")
		(net "M_J_CPU0_SA_DQ<6>")
	)
	(segment
		(start 401.582636 -211.450936)
		(end 401.744688 -211.288884)
		(width 0.14478)
		(layer "In4.Cu")
		(net "M_J_CPU0_SA_DQ<6>")
	)
	(segment
		(start 404.690326 -209.096356)
		(end 409.226512 -204.56017)
		(width 0.14478)
		(layer "In4.Cu")
		(net "M_J_CPU0_SA_DQ<6>")
	)
	(segment
		(start 401.97278 -211.288884)
		(end 402.121116 -211.43722)
		(width 0.14478)
		(layer "In4.Cu")
		(net "M_J_CPU0_SA_DQ<6>")
	)
	(segment
		(start 392.427714 -224.721674)
		(end 392.46683 -224.698814)
		(width 0.0889)
		(layer "In4.Cu")
		(net "M_J_CPU0_SA_DQ<6>")
	)
	(segment
		(start 393.332716 -223.12249)
		(end 393.368276 -223.101916)
		(width 0.0889)
		(layer "In4.Cu")
		(net "M_J_CPU0_SA_DQ<6>")
	)
	(segment
		(start 399.631916 -213.629748)
		(end 399.780252 -213.778084)
		(width 0.14478)
		(layer "In4.Cu")
		(net "M_J_CPU0_SA_DQ<6>")
	)
	(segment
		(start 400.802348 -212.459316)
		(end 400.802348 -212.231224)
		(width 0.14478)
		(layer "In4.Cu")
		(net "M_J_CPU0_SA_DQ<6>")
	)
	(segment
		(start 381.043434 -228.766878)
		(end 381.051816 -228.771704)
		(width 0.0889)
		(layer "In4.Cu")
		(net "M_J_CPU0_SA_DQ<6>")
	)
	(segment
		(start 393.368276 -223.101916)
		(end 393.624562 -222.95993)
		(width 0.0889)
		(layer "In4.Cu")
		(net "M_J_CPU0_SA_DQ<6>")
	)
	(segment
		(start 401.731226 -212.055456)
		(end 401.731226 -211.827364)
		(width 0.14478)
		(layer "In4.Cu")
		(net "M_J_CPU0_SA_DQ<6>")
	)
	(segment
		(start 393.624562 -222.95993)
		(end 394.229082 -222.35541)
		(width 0.0889)
		(layer "In4.Cu")
		(net "M_J_CPU0_SA_DQ<6>")
	)
	(segment
		(start 404.313644 -208.94802)
		(end 404.46198 -209.096356)
		(width 0.14478)
		(layer "In4.Cu")
		(net "M_J_CPU0_SA_DQ<6>")
	)
	(segment
		(start 430.18202 -203.710032)
		(end 434.575204 -203.710032)
		(width 0.14478)
		(layer "In4.Cu")
		(net "M_J_CPU0_SA_DQ<6>")
	)
	(segment
		(start 399.403824 -213.629748)
		(end 399.631916 -213.629748)
		(width 0.14478)
		(layer "In4.Cu")
		(net "M_J_CPU0_SA_DQ<6>")
	)
	(segment
		(start 386.683504 -228.766878)
		(end 386.691886 -228.771704)
		(width 0.0889)
		(layer "In4.Cu")
		(net "M_J_CPU0_SA_DQ<6>")
	)
	(segment
		(start 390.54786 -227.961698)
		(end 390.584182 -227.940616)
		(width 0.0889)
		(layer "In4.Cu")
		(net "M_J_CPU0_SA_DQ<6>")
	)
	(segment
		(start 382.557782 -228.771704)
		(end 382.566164 -228.766878)
		(width 0.0889)
		(layer "In4.Cu")
		(net "M_J_CPU0_SA_DQ<6>")
	)
	(segment
		(start 403.533356 -209.728308)
		(end 403.681692 -209.876644)
		(width 0.14478)
		(layer "In4.Cu")
		(net "M_J_CPU0_SA_DQ<6>")
	)
	(segment
		(start 401.731226 -211.827364)
		(end 401.582636 -211.679028)
		(width 0.14478)
		(layer "In4.Cu")
		(net "M_J_CPU0_SA_DQ<6>")
	)
	(segment
		(start 399.22831 -214.558372)
		(end 399.390362 -214.39632)
		(width 0.14478)
		(layer "In4.Cu")
		(net "M_J_CPU0_SA_DQ<6>")
	)
	(segment
		(start 400.17065 -213.616032)
		(end 400.17065 -213.38794)
		(width 0.14478)
		(layer "In4.Cu")
		(net "M_J_CPU0_SA_DQ<6>")
	)
	(segment
		(start 385.74345 -228.766878)
		(end 385.751832 -228.771704)
		(width 0.0889)
		(layer "In4.Cu")
		(net "M_J_CPU0_SA_DQ<6>")
	)
	(segment
		(start 403.9235 -209.110072)
		(end 404.085552 -208.94802)
		(width 0.14478)
		(layer "In4.Cu")
		(net "M_J_CPU0_SA_DQ<6>")
	)
	(segment
		(start 394.229082 -218.80449)
		(end 397.06296 -215.970612)
		(width 0.14478)
		(layer "In4.Cu")
		(net "M_J_CPU0_SA_DQ<6>")
	)
	(segment
		(start 398.219676 -215.33866)
		(end 398.448022 -215.33866)
		(width 0.14478)
		(layer "In4.Cu")
		(net "M_J_CPU0_SA_DQ<6>")
	)
	(segment
		(start 397.681196 -215.352376)
		(end 397.843248 -215.190324)
		(width 0.14478)
		(layer "In4.Cu")
		(net "M_J_CPU0_SA_DQ<6>")
	)
	(segment
		(start 397.667734 -216.118948)
		(end 397.829786 -215.956896)
		(width 0.14478)
		(layer "In4.Cu")
		(net "M_J_CPU0_SA_DQ<6>")
	)
	(segment
		(start 400.02206 -213.239604)
		(end 400.02206 -213.011512)
		(width 0.14478)
		(layer "In4.Cu")
		(net "M_J_CPU0_SA_DQ<6>")
	)
	(segment
		(start 381.983488 -228.766878)
		(end 381.99187 -228.771704)
		(width 0.0889)
		(layer "In4.Cu")
		(net "M_J_CPU0_SA_DQ<6>")
	)
	(segment
		(start 394.229082 -222.085154)
		(end 394.229082 -218.80449)
		(width 0.14478)
		(layer "In4.Cu")
		(net "M_J_CPU0_SA_DQ<6>")
	)
	(segment
		(start 403.291802 -210.266788)
		(end 403.143212 -210.118452)
		(width 0.14478)
		(layer "In4.Cu")
		(net "M_J_CPU0_SA_DQ<6>")
	)
	(segment
		(start 400.184112 -212.84946)
		(end 400.412204 -212.84946)
		(width 0.14478)
		(layer "In4.Cu")
		(net "M_J_CPU0_SA_DQ<6>")
	)
	(segment
		(start 400.802348 -212.231224)
		(end 400.9644 -212.069172)
		(width 0.14478)
		(layer "In4.Cu")
		(net "M_J_CPU0_SA_DQ<6>")
	)
	(segment
		(start 400.56054 -212.997796)
		(end 400.788886 -212.997796)
		(width 0.14478)
		(layer "In4.Cu")
		(net "M_J_CPU0_SA_DQ<6>")
	)
	(segment
		(start 404.085552 -208.94802)
		(end 404.313644 -208.94802)
		(width 0.14478)
		(layer "In4.Cu")
		(net "M_J_CPU0_SA_DQ<6>")
	)
	(segment
		(start 387.257798 -228.771704)
		(end 387.26618 -228.766878)
		(width 0.0889)
		(layer "In4.Cu")
		(net "M_J_CPU0_SA_DQ<6>")
	)
	(segment
		(start 397.291052 -215.970612)
		(end 397.439388 -216.118948)
		(width 0.14478)
		(layer "In4.Cu")
		(net "M_J_CPU0_SA_DQ<6>")
	)
	(segment
		(start 403.12975 -210.656932)
		(end 403.291802 -210.49488)
		(width 0.14478)
		(layer "In4.Cu")
		(net "M_J_CPU0_SA_DQ<6>")
	)
	(segment
		(start 398.461484 -214.572088)
		(end 398.623536 -214.410036)
		(width 0.14478)
		(layer "In4.Cu")
		(net "M_J_CPU0_SA_DQ<6>")
	)
	(arc
		(start 391.770108 -225.85426)
		(mid 391.811363 -225.683289)
		(end 391.926064 -225.549968)
		(width 0.0889)
		(layer "In4.Cu")
		(net "M_J_CPU0_SA_DQ<6>")
	)
	(arc
		(start 387.26618 -228.766878)
		(mid 387.449688 -228.721384)
		(end 387.63194 -228.771704)
		(width 0.0889)
		(layer "In4.Cu")
		(net "M_J_CPU0_SA_DQ<6>")
	)
	(arc
		(start 388.206234 -228.766878)
		(mid 388.389742 -228.721384)
		(end 388.571994 -228.771704)
		(width 0.0889)
		(layer "In4.Cu")
		(net "M_J_CPU0_SA_DQ<6>")
	)
	(arc
		(start 386.691886 -228.771704)
		(mid 386.974842 -228.847881)
		(end 387.257798 -228.771704)
		(width 0.0889)
		(layer "In4.Cu")
		(net "M_J_CPU0_SA_DQ<6>")
	)
	(arc
		(start 382.931924 -228.771704)
		(mid 383.21488 -228.847881)
		(end 383.497836 -228.771704)
		(width 0.0889)
		(layer "In4.Cu")
		(net "M_J_CPU0_SA_DQ<6>")
	)
	(arc
		(start 391.056876 -227.128832)
		(mid 391.235689 -226.926482)
		(end 391.300208 -226.664266)
		(width 0.0889)
		(layer "In4.Cu")
		(net "M_J_CPU0_SA_DQ<6>")
	)
	(arc
		(start 386.317744 -228.771704)
		(mid 386.499995 -228.721354)
		(end 386.683504 -228.766878)
		(width 0.0889)
		(layer "In4.Cu")
		(net "M_J_CPU0_SA_DQ<6>")
	)
	(arc
		(start 383.871978 -228.771704)
		(mid 384.154934 -228.847881)
		(end 384.43789 -228.771704)
		(width 0.0889)
		(layer "In4.Cu")
		(net "M_J_CPU0_SA_DQ<6>")
	)
	(arc
		(start 384.43789 -228.771704)
		(mid 384.624834 -228.721449)
		(end 384.811778 -228.771704)
		(width 0.0889)
		(layer "In4.Cu")
		(net "M_J_CPU0_SA_DQ<6>")
	)
	(arc
		(start 385.751832 -228.771704)
		(mid 386.034788 -228.847881)
		(end 386.317744 -228.771704)
		(width 0.0889)
		(layer "In4.Cu")
		(net "M_J_CPU0_SA_DQ<6>")
	)
	(arc
		(start 389.137906 -228.771704)
		(mid 389.32485 -228.721449)
		(end 389.511794 -228.771704)
		(width 0.0889)
		(layer "In4.Cu")
		(net "M_J_CPU0_SA_DQ<6>")
	)
	(arc
		(start 387.63194 -228.771704)
		(mid 387.914896 -228.847881)
		(end 388.197852 -228.771704)
		(width 0.0889)
		(layer "In4.Cu")
		(net "M_J_CPU0_SA_DQ<6>")
	)
	(arc
		(start 381.617728 -228.771704)
		(mid 381.799979 -228.721354)
		(end 381.983488 -228.766878)
		(width 0.0889)
		(layer "In4.Cu")
		(net "M_J_CPU0_SA_DQ<6>")
	)
	(arc
		(start 390.360154 -228.284278)
		(mid 390.401409 -228.113307)
		(end 390.51611 -227.979986)
		(width 0.0889)
		(layer "In4.Cu")
		(net "M_J_CPU0_SA_DQ<6>")
	)
	(arc
		(start 390.584182 -227.940616)
		(mid 390.764834 -227.737871)
		(end 390.830054 -227.474272)
		(width 0.0889)
		(layer "In4.Cu")
		(net "M_J_CPU0_SA_DQ<6>")
	)
	(arc
		(start 391.526776 -226.318826)
		(mid 391.705589 -226.116476)
		(end 391.770108 -225.85426)
		(width 0.0889)
		(layer "In4.Cu")
		(net "M_J_CPU0_SA_DQ<6>")
	)
	(arc
		(start 380.733046 -228.745542)
		(mid 380.890556 -228.722344)
		(end 381.043434 -228.766878)
		(width 0.0889)
		(layer "In4.Cu")
		(net "M_J_CPU0_SA_DQ<6>")
	)
	(arc
		(start 392.240262 -225.044254)
		(mid 392.281811 -224.872832)
		(end 392.397234 -224.739454)
		(width 0.0889)
		(layer "In4.Cu")
		(net "M_J_CPU0_SA_DQ<6>")
	)
	(arc
		(start 390.116822 -228.748844)
		(mid 390.295635 -228.546494)
		(end 390.360154 -228.284278)
		(width 0.0889)
		(layer "In4.Cu")
		(net "M_J_CPU0_SA_DQ<6>")
	)
	(arc
		(start 392.46683 -224.698814)
		(mid 392.645643 -224.496464)
		(end 392.710162 -224.234248)
		(width 0.0889)
		(layer "In4.Cu")
		(net "M_J_CPU0_SA_DQ<6>")
	)
	(arc
		(start 391.300208 -226.664266)
		(mid 391.341757 -226.492844)
		(end 391.45718 -226.359466)
		(width 0.0889)
		(layer "In4.Cu")
		(net "M_J_CPU0_SA_DQ<6>")
	)
	(arc
		(start 393.180062 -223.424242)
		(mid 393.220391 -223.25515)
		(end 393.332716 -223.12249)
		(width 0.0889)
		(layer "In4.Cu")
		(net "M_J_CPU0_SA_DQ<6>")
	)
	(arc
		(start 384.811778 -228.771704)
		(mid 385.094734 -228.847881)
		(end 385.37769 -228.771704)
		(width 0.0889)
		(layer "In4.Cu")
		(net "M_J_CPU0_SA_DQ<6>")
	)
	(arc
		(start 392.93419 -223.890586)
		(mid 393.114842 -223.687841)
		(end 393.180062 -223.424242)
		(width 0.0889)
		(layer "In4.Cu")
		(net "M_J_CPU0_SA_DQ<6>")
	)
	(arc
		(start 391.99693 -225.50882)
		(mid 392.175743 -225.30647)
		(end 392.240262 -225.044254)
		(width 0.0889)
		(layer "In4.Cu")
		(net "M_J_CPU0_SA_DQ<6>")
	)
	(arc
		(start 381.99187 -228.771704)
		(mid 382.274826 -228.847881)
		(end 382.557782 -228.771704)
		(width 0.0889)
		(layer "In4.Cu")
		(net "M_J_CPU0_SA_DQ<6>")
	)
	(arc
		(start 383.506218 -228.766878)
		(mid 383.689726 -228.721384)
		(end 383.871978 -228.771704)
		(width 0.0889)
		(layer "In4.Cu")
		(net "M_J_CPU0_SA_DQ<6>")
	)
	(arc
		(start 389.511794 -228.771704)
		(mid 389.79475 -228.847881)
		(end 390.077706 -228.771704)
		(width 0.0889)
		(layer "In4.Cu")
		(net "M_J_CPU0_SA_DQ<6>")
	)
	(arc
		(start 382.566164 -228.766878)
		(mid 382.749672 -228.721384)
		(end 382.931924 -228.771704)
		(width 0.0889)
		(layer "In4.Cu")
		(net "M_J_CPU0_SA_DQ<6>")
	)
	(arc
		(start 388.571994 -228.771704)
		(mid 388.85495 -228.847881)
		(end 389.137906 -228.771704)
		(width 0.0889)
		(layer "In4.Cu")
		(net "M_J_CPU0_SA_DQ<6>")
	)
	(arc
		(start 381.051816 -228.771704)
		(mid 381.334772 -228.847881)
		(end 381.617728 -228.771704)
		(width 0.0889)
		(layer "In4.Cu")
		(net "M_J_CPU0_SA_DQ<6>")
	)
	(arc
		(start 390.830054 -227.474272)
		(mid 390.871309 -227.303301)
		(end 390.98601 -227.16998)
		(width 0.0889)
		(layer "In4.Cu")
		(net "M_J_CPU0_SA_DQ<6>")
	)
	(arc
		(start 385.37769 -228.771704)
		(mid 385.559941 -228.721354)
		(end 385.74345 -228.766878)
		(width 0.0889)
		(layer "In4.Cu")
		(net "M_J_CPU0_SA_DQ<6>")
	)
	(arc
		(start 392.710162 -224.234248)
		(mid 392.751417 -224.063277)
		(end 392.866118 -223.929956)
		(width 0.0889)
		(layer "In4.Cu")
		(net "M_J_CPU0_SA_DQ<6>")
	)
	(segment
		(start 378.517912 -229.360222)
		(end 378.984764 -229.094284)
		(width 0.10668)
		(layer "F.Cu")
		(net "M_J_CPU0_SA_DQ<5>")
	)
	(segment
		(start 392.654536 -226.5426)
		(end 392.654536 -225.52533)
		(width 0.0889)
		(layer "In4.Cu")
		(net "M_J_CPU0_SA_DQ<5>")
	)
	(segment
		(start 391.463784 -227.733352)
		(end 392.654536 -226.5426)
		(width 0.0889)
		(layer "In4.Cu")
		(net "M_J_CPU0_SA_DQ<5>")
	)
	(segment
		(start 387.257798 -229.41661)
		(end 387.26618 -229.421436)
		(width 0.0889)
		(layer "In4.Cu")
		(net "M_J_CPU0_SA_DQ<5>")
	)
	(segment
		(start 422.58107 -204.56017)
		(end 425.622974 -204.56017)
		(width 0.14478)
		(layer "In4.Cu")
		(net "M_J_CPU0_SA_DQ<5>")
	)
	(segment
		(start 390.443466 -229.421436)
		(end 390.451848 -229.41661)
		(width 0.0889)
		(layer "In4.Cu")
		(net "M_J_CPU0_SA_DQ<5>")
	)
	(segment
		(start 417.619688 -204.56017)
		(end 418.469572 -205.410054)
		(width 0.14478)
		(layer "In4.Cu")
		(net "M_J_CPU0_SA_DQ<5>")
	)
	(segment
		(start 390.451848 -229.41661)
		(end 390.485376 -229.397052)
		(width 0.0889)
		(layer "In4.Cu")
		(net "M_J_CPU0_SA_DQ<5>")
	)
	(segment
		(start 396.954502 -216.71534)
		(end 397.72717 -216.71534)
		(width 0.14478)
		(layer "In4.Cu")
		(net "M_J_CPU0_SA_DQ<5>")
	)
	(segment
		(start 383.497836 -229.41661)
		(end 383.506218 -229.421436)
		(width 0.0889)
		(layer "In4.Cu")
		(net "M_J_CPU0_SA_DQ<5>")
	)
	(segment
		(start 430.086262 -204.56017)
		(end 438.675272 -204.56017)
		(width 0.14478)
		(layer "In4.Cu")
		(net "M_J_CPU0_SA_DQ<5>")
	)
	(segment
		(start 393.535916 -224.12071)
		(end 394.069316 -223.58731)
		(width 0.0889)
		(layer "In4.Cu")
		(net "M_J_CPU0_SA_DQ<5>")
	)
	(segment
		(start 385.74345 -229.421436)
		(end 385.751832 -229.41661)
		(width 0.0889)
		(layer "In4.Cu")
		(net "M_J_CPU0_SA_DQ<5>")
	)
	(segment
		(start 409.032456 -205.410054)
		(end 414.16224 -205.410054)
		(width 0.14478)
		(layer "In4.Cu")
		(net "M_J_CPU0_SA_DQ<5>")
	)
	(segment
		(start 429.236378 -205.410054)
		(end 430.086262 -204.56017)
		(width 0.14478)
		(layer "In4.Cu")
		(net "M_J_CPU0_SA_DQ<5>")
	)
	(segment
		(start 438.675272 -204.56017)
		(end 439.100214 -204.985112)
		(width 0.14478)
		(layer "In4.Cu")
		(net "M_J_CPU0_SA_DQ<5>")
	)
	(segment
		(start 391.352786 -227.819712)
		(end 391.391902 -227.796852)
		(width 0.0889)
		(layer "In4.Cu")
		(net "M_J_CPU0_SA_DQ<5>")
	)
	(segment
		(start 394.678662 -222.678244)
		(end 394.678662 -222.06712)
		(width 0.0889)
		(layer "In4.Cu")
		(net "M_J_CPU0_SA_DQ<5>")
	)
	(segment
		(start 394.678662 -222.06712)
		(end 394.678662 -218.99118)
		(width 0.14478)
		(layer "In4.Cu")
		(net "M_J_CPU0_SA_DQ<5>")
	)
	(segment
		(start 382.557782 -229.41661)
		(end 382.566164 -229.421436)
		(width 0.0889)
		(layer "In4.Cu")
		(net "M_J_CPU0_SA_DQ<5>")
	)
	(segment
		(start 421.731186 -205.410054)
		(end 422.58107 -204.56017)
		(width 0.14478)
		(layer "In4.Cu")
		(net "M_J_CPU0_SA_DQ<5>")
	)
	(segment
		(start 394.069316 -223.58731)
		(end 394.069316 -223.28759)
		(width 0.0889)
		(layer "In4.Cu")
		(net "M_J_CPU0_SA_DQ<5>")
	)
	(segment
		(start 425.622974 -204.56017)
		(end 426.472858 -205.410054)
		(width 0.14478)
		(layer "In4.Cu")
		(net "M_J_CPU0_SA_DQ<5>")
	)
	(segment
		(start 386.683504 -229.421436)
		(end 386.691886 -229.41661)
		(width 0.0889)
		(layer "In4.Cu")
		(net "M_J_CPU0_SA_DQ<5>")
	)
	(segment
		(start 418.469572 -205.410054)
		(end 421.731186 -205.410054)
		(width 0.14478)
		(layer "In4.Cu")
		(net "M_J_CPU0_SA_DQ<5>")
	)
	(segment
		(start 397.72717 -216.71534)
		(end 409.032456 -205.410054)
		(width 0.14478)
		(layer "In4.Cu")
		(net "M_J_CPU0_SA_DQ<5>")
	)
	(segment
		(start 426.472858 -205.410054)
		(end 429.236378 -205.410054)
		(width 0.14478)
		(layer "In4.Cu")
		(net "M_J_CPU0_SA_DQ<5>")
	)
	(segment
		(start 415.012124 -204.56017)
		(end 417.619688 -204.56017)
		(width 0.14478)
		(layer "In4.Cu")
		(net "M_J_CPU0_SA_DQ<5>")
	)
	(segment
		(start 392.654536 -225.52533)
		(end 393.535916 -224.64395)
		(width 0.0889)
		(layer "In4.Cu")
		(net "M_J_CPU0_SA_DQ<5>")
	)
	(segment
		(start 391.391902 -227.796852)
		(end 391.463784 -227.733352)
		(width 0.0889)
		(layer "In4.Cu")
		(net "M_J_CPU0_SA_DQ<5>")
	)
	(segment
		(start 394.069316 -223.28759)
		(end 394.678662 -222.678244)
		(width 0.0889)
		(layer "In4.Cu")
		(net "M_J_CPU0_SA_DQ<5>")
	)
	(segment
		(start 378.984764 -229.094284)
		(end 379.138942 -229.359714)
		(width 0.0889)
		(layer "In4.Cu")
		(net "M_J_CPU0_SA_DQ<5>")
	)
	(segment
		(start 381.043434 -229.421436)
		(end 381.051816 -229.41661)
		(width 0.0889)
		(layer "In4.Cu")
		(net "M_J_CPU0_SA_DQ<5>")
	)
	(segment
		(start 394.678662 -218.99118)
		(end 396.954502 -216.71534)
		(width 0.14478)
		(layer "In4.Cu")
		(net "M_J_CPU0_SA_DQ<5>")
	)
	(segment
		(start 393.535916 -224.64395)
		(end 393.535916 -224.12071)
		(width 0.0889)
		(layer "In4.Cu")
		(net "M_J_CPU0_SA_DQ<5>")
	)
	(segment
		(start 381.983488 -229.421436)
		(end 381.99187 -229.41661)
		(width 0.0889)
		(layer "In4.Cu")
		(net "M_J_CPU0_SA_DQ<5>")
	)
	(segment
		(start 379.138942 -229.359714)
		(end 379.2347 -229.385114)
		(width 0.0889)
		(layer "In4.Cu")
		(net "M_J_CPU0_SA_DQ<5>")
	)
	(segment
		(start 388.197852 -229.41661)
		(end 388.206234 -229.421436)
		(width 0.0889)
		(layer "In4.Cu")
		(net "M_J_CPU0_SA_DQ<5>")
	)
	(segment
		(start 390.885426 -228.62794)
		(end 390.921748 -228.606858)
		(width 0.0889)
		(layer "In4.Cu")
		(net "M_J_CPU0_SA_DQ<5>")
	)
	(segment
		(start 414.16224 -205.410054)
		(end 415.012124 -204.56017)
		(width 0.14478)
		(layer "In4.Cu")
		(net "M_J_CPU0_SA_DQ<5>")
	)
	(segment
		(start 390.921748 -228.606858)
		(end 390.953498 -228.58857)
		(width 0.0889)
		(layer "In4.Cu")
		(net "M_J_CPU0_SA_DQ<5>")
	)
	(arc
		(start 387.26618 -229.421436)
		(mid 387.449688 -229.466961)
		(end 387.63194 -229.41661)
		(width 0.0889)
		(layer "In4.Cu")
		(net "M_J_CPU0_SA_DQ<5>")
	)
	(arc
		(start 380.677674 -229.41661)
		(mid 380.859925 -229.466994)
		(end 381.043434 -229.421436)
		(width 0.0889)
		(layer "In4.Cu")
		(net "M_J_CPU0_SA_DQ<5>")
	)
	(arc
		(start 384.43789 -229.41661)
		(mid 384.624834 -229.466899)
		(end 384.811778 -229.41661)
		(width 0.0889)
		(layer "In4.Cu")
		(net "M_J_CPU0_SA_DQ<5>")
	)
	(arc
		(start 389.137906 -229.41661)
		(mid 389.32485 -229.466899)
		(end 389.511794 -229.41661)
		(width 0.0889)
		(layer "In4.Cu")
		(net "M_J_CPU0_SA_DQ<5>")
	)
	(arc
		(start 381.051816 -229.41661)
		(mid 381.334772 -229.340433)
		(end 381.617728 -229.41661)
		(width 0.0889)
		(layer "In4.Cu")
		(net "M_J_CPU0_SA_DQ<5>")
	)
	(arc
		(start 390.953498 -228.58857)
		(mid 391.068174 -228.455236)
		(end 391.109454 -228.284278)
		(width 0.0889)
		(layer "In4.Cu")
		(net "M_J_CPU0_SA_DQ<5>")
	)
	(arc
		(start 383.871978 -229.41661)
		(mid 384.154934 -229.340433)
		(end 384.43789 -229.41661)
		(width 0.0889)
		(layer "In4.Cu")
		(net "M_J_CPU0_SA_DQ<5>")
	)
	(arc
		(start 380.111762 -229.41661)
		(mid 380.394718 -229.340433)
		(end 380.677674 -229.41661)
		(width 0.0889)
		(layer "In4.Cu")
		(net "M_J_CPU0_SA_DQ<5>")
	)
	(arc
		(start 387.63194 -229.41661)
		(mid 387.914896 -229.340433)
		(end 388.197852 -229.41661)
		(width 0.0889)
		(layer "In4.Cu")
		(net "M_J_CPU0_SA_DQ<5>")
	)
	(arc
		(start 385.751832 -229.41661)
		(mid 386.034788 -229.340433)
		(end 386.317744 -229.41661)
		(width 0.0889)
		(layer "In4.Cu")
		(net "M_J_CPU0_SA_DQ<5>")
	)
	(arc
		(start 388.206234 -229.421436)
		(mid 388.389742 -229.466961)
		(end 388.571994 -229.41661)
		(width 0.0889)
		(layer "In4.Cu")
		(net "M_J_CPU0_SA_DQ<5>")
	)
	(arc
		(start 390.639554 -229.094284)
		(mid 390.70479 -228.830693)
		(end 390.885426 -228.62794)
		(width 0.0889)
		(layer "In4.Cu")
		(net "M_J_CPU0_SA_DQ<5>")
	)
	(arc
		(start 391.109454 -228.284278)
		(mid 391.173969 -228.022059)
		(end 391.352786 -227.819712)
		(width 0.0889)
		(layer "In4.Cu")
		(net "M_J_CPU0_SA_DQ<5>")
	)
	(arc
		(start 388.571994 -229.41661)
		(mid 388.85495 -229.340433)
		(end 389.137906 -229.41661)
		(width 0.0889)
		(layer "In4.Cu")
		(net "M_J_CPU0_SA_DQ<5>")
	)
	(arc
		(start 386.317744 -229.41661)
		(mid 386.499995 -229.466994)
		(end 386.683504 -229.421436)
		(width 0.0889)
		(layer "In4.Cu")
		(net "M_J_CPU0_SA_DQ<5>")
	)
	(arc
		(start 385.37769 -229.41661)
		(mid 385.559941 -229.466994)
		(end 385.74345 -229.421436)
		(width 0.0889)
		(layer "In4.Cu")
		(net "M_J_CPU0_SA_DQ<5>")
	)
	(arc
		(start 390.077706 -229.41661)
		(mid 390.259957 -229.466994)
		(end 390.443466 -229.421436)
		(width 0.0889)
		(layer "In4.Cu")
		(net "M_J_CPU0_SA_DQ<5>")
	)
	(arc
		(start 386.691886 -229.41661)
		(mid 386.974842 -229.340433)
		(end 387.257798 -229.41661)
		(width 0.0889)
		(layer "In4.Cu")
		(net "M_J_CPU0_SA_DQ<5>")
	)
	(arc
		(start 384.811778 -229.41661)
		(mid 385.094734 -229.340433)
		(end 385.37769 -229.41661)
		(width 0.0889)
		(layer "In4.Cu")
		(net "M_J_CPU0_SA_DQ<5>")
	)
	(arc
		(start 382.931924 -229.41661)
		(mid 383.21488 -229.340433)
		(end 383.497836 -229.41661)
		(width 0.0889)
		(layer "In4.Cu")
		(net "M_J_CPU0_SA_DQ<5>")
	)
	(arc
		(start 379.2347 -229.385114)
		(mid 379.490022 -229.341414)
		(end 379.737874 -229.41661)
		(width 0.0889)
		(layer "In4.Cu")
		(net "M_J_CPU0_SA_DQ<5>")
	)
	(arc
		(start 389.511794 -229.41661)
		(mid 389.79475 -229.340433)
		(end 390.077706 -229.41661)
		(width 0.0889)
		(layer "In4.Cu")
		(net "M_J_CPU0_SA_DQ<5>")
	)
	(arc
		(start 383.506218 -229.421436)
		(mid 383.689726 -229.466961)
		(end 383.871978 -229.41661)
		(width 0.0889)
		(layer "In4.Cu")
		(net "M_J_CPU0_SA_DQ<5>")
	)
	(arc
		(start 381.99187 -229.41661)
		(mid 382.274826 -229.340433)
		(end 382.557782 -229.41661)
		(width 0.0889)
		(layer "In4.Cu")
		(net "M_J_CPU0_SA_DQ<5>")
	)
	(arc
		(start 381.617728 -229.41661)
		(mid 381.799979 -229.466994)
		(end 381.983488 -229.421436)
		(width 0.0889)
		(layer "In4.Cu")
		(net "M_J_CPU0_SA_DQ<5>")
	)
	(arc
		(start 390.485376 -229.397052)
		(mid 390.598783 -229.264163)
		(end 390.639554 -229.094284)
		(width 0.0889)
		(layer "In4.Cu")
		(net "M_J_CPU0_SA_DQ<5>")
	)
	(arc
		(start 379.737874 -229.41661)
		(mid 379.924818 -229.466899)
		(end 380.111762 -229.41661)
		(width 0.0889)
		(layer "In4.Cu")
		(net "M_J_CPU0_SA_DQ<5>")
	)
	(arc
		(start 382.566164 -229.421436)
		(mid 382.749672 -229.466961)
		(end 382.931924 -229.41661)
		(width 0.0889)
		(layer "In4.Cu")
		(net "M_J_CPU0_SA_DQ<5>")
	)
	(segment
		(start 379.927866 -228.550216)
		(end 380.394718 -228.284278)
		(width 0.10668)
		(layer "F.Cu")
		(net "M_J_CPU0_SA_DQ<4>")
	)
	(segment
		(start 429.46574 -203.719684)
		(end 430.315624 -202.8698)
		(width 0.14478)
		(layer "In4.Cu")
		(net "M_J_CPU0_SA_DQ<4>")
	)
	(segment
		(start 437.363108 -203.023216)
		(end 437.363108 -203.460858)
		(width 0.14478)
		(layer "In4.Cu")
		(net "M_J_CPU0_SA_DQ<4>")
	)
	(segment
		(start 393.779502 -222.437706)
		(end 393.779502 -221.865952)
		(width 0.0889)
		(layer "In4.Cu")
		(net "M_J_CPU0_SA_DQ<4>")
	)
	(segment
		(start 384.333496 -228.611684)
		(end 384.341878 -228.606858)
		(width 0.0889)
		(layer "In4.Cu")
		(net "M_J_CPU0_SA_DQ<4>")
	)
	(segment
		(start 392.331956 -224.556828)
		(end 392.362436 -224.539048)
		(width 0.0889)
		(layer "In4.Cu")
		(net "M_J_CPU0_SA_DQ<4>")
	)
	(segment
		(start 388.093458 -228.611684)
		(end 388.10184 -228.606858)
		(width 0.0889)
		(layer "In4.Cu")
		(net "M_J_CPU0_SA_DQ<4>")
	)
	(segment
		(start 393.234418 -222.95866)
		(end 393.272518 -222.936562)
		(width 0.0889)
		(layer "In4.Cu")
		(net "M_J_CPU0_SA_DQ<4>")
	)
	(segment
		(start 390.921748 -226.986846)
		(end 390.953498 -226.968558)
		(width 0.0889)
		(layer "In4.Cu")
		(net "M_J_CPU0_SA_DQ<4>")
	)
	(segment
		(start 392.29284 -224.579688)
		(end 392.331956 -224.556828)
		(width 0.0889)
		(layer "In4.Cu")
		(net "M_J_CPU0_SA_DQ<4>")
	)
	(segment
		(start 437.526176 -203.623926)
		(end 437.756554 -203.623926)
		(width 0.14478)
		(layer "In4.Cu")
		(net "M_J_CPU0_SA_DQ<4>")
	)
	(segment
		(start 393.779502 -218.6178)
		(end 403.898862 -208.49844)
		(width 0.14478)
		(layer "In4.Cu")
		(net "M_J_CPU0_SA_DQ<4>")
	)
	(segment
		(start 425.305982 -202.8698)
		(end 426.155866 -203.719684)
		(width 0.14478)
		(layer "In4.Cu")
		(net "M_J_CPU0_SA_DQ<4>")
	)
	(segment
		(start 384.90779 -228.606858)
		(end 384.916172 -228.611684)
		(width 0.0889)
		(layer "In4.Cu")
		(net "M_J_CPU0_SA_DQ<4>")
	)
	(segment
		(start 437.363108 -203.460858)
		(end 437.526176 -203.623926)
		(width 0.14478)
		(layer "In4.Cu")
		(net "M_J_CPU0_SA_DQ<4>")
	)
	(segment
		(start 392.801856 -223.746822)
		(end 392.833606 -223.728534)
		(width 0.0889)
		(layer "In4.Cu")
		(net "M_J_CPU0_SA_DQ<4>")
	)
	(segment
		(start 383.393442 -228.611684)
		(end 383.401824 -228.606858)
		(width 0.0889)
		(layer "In4.Cu")
		(net "M_J_CPU0_SA_DQ<4>")
	)
	(segment
		(start 393.272518 -222.936562)
		(end 393.343892 -222.873316)
		(width 0.0889)
		(layer "In4.Cu")
		(net "M_J_CPU0_SA_DQ<4>")
	)
	(segment
		(start 422.433496 -202.8698)
		(end 425.305982 -202.8698)
		(width 0.14478)
		(layer "In4.Cu")
		(net "M_J_CPU0_SA_DQ<4>")
	)
	(segment
		(start 417.486084 -202.860148)
		(end 418.34562 -203.719684)
		(width 0.14478)
		(layer "In4.Cu")
		(net "M_J_CPU0_SA_DQ<4>")
	)
	(segment
		(start 403.898862 -208.49844)
		(end 404.652226 -208.49844)
		(width 0.14478)
		(layer "In4.Cu")
		(net "M_J_CPU0_SA_DQ<4>")
	)
	(segment
		(start 390.412732 -227.819712)
		(end 390.451848 -227.796852)
		(width 0.0889)
		(layer "In4.Cu")
		(net "M_J_CPU0_SA_DQ<4>")
	)
	(segment
		(start 385.847844 -228.606858)
		(end 385.856226 -228.611684)
		(width 0.0889)
		(layer "In4.Cu")
		(net "M_J_CPU0_SA_DQ<4>")
	)
	(segment
		(start 390.885426 -227.007928)
		(end 390.921748 -226.986846)
		(width 0.0889)
		(layer "In4.Cu")
		(net "M_J_CPU0_SA_DQ<4>")
	)
	(segment
		(start 421.583612 -203.719684)
		(end 422.433496 -202.8698)
		(width 0.14478)
		(layer "In4.Cu")
		(net "M_J_CPU0_SA_DQ<4>")
	)
	(segment
		(start 438.675272 -202.860148)
		(end 439.100214 -203.28509)
		(width 0.14478)
		(layer "In4.Cu")
		(net "M_J_CPU0_SA_DQ<4>")
	)
	(segment
		(start 393.343892 -222.873316)
		(end 393.779502 -222.437706)
		(width 0.0889)
		(layer "In4.Cu")
		(net "M_J_CPU0_SA_DQ<4>")
	)
	(segment
		(start 391.352786 -226.1997)
		(end 391.391902 -226.17684)
		(width 0.0889)
		(layer "In4.Cu")
		(net "M_J_CPU0_SA_DQ<4>")
	)
	(segment
		(start 392.76274 -223.769682)
		(end 392.801856 -223.746822)
		(width 0.0889)
		(layer "In4.Cu")
		(net "M_J_CPU0_SA_DQ<4>")
	)
	(segment
		(start 393.779502 -221.865952)
		(end 393.779502 -218.6178)
		(width 0.14478)
		(layer "In4.Cu")
		(net "M_J_CPU0_SA_DQ<4>")
	)
	(segment
		(start 404.652226 -208.49844)
		(end 409.440634 -203.710032)
		(width 0.14478)
		(layer "In4.Cu")
		(net "M_J_CPU0_SA_DQ<4>")
	)
	(segment
		(start 415.120328 -202.860148)
		(end 417.486084 -202.860148)
		(width 0.14478)
		(layer "In4.Cu")
		(net "M_J_CPU0_SA_DQ<4>")
	)
	(segment
		(start 437.209692 -202.8698)
		(end 437.363108 -203.023216)
		(width 0.14478)
		(layer "In4.Cu")
		(net "M_J_CPU0_SA_DQ<4>")
	)
	(segment
		(start 380.394718 -228.284278)
		(end 380.548896 -228.549708)
		(width 0.0889)
		(layer "In4.Cu")
		(net "M_J_CPU0_SA_DQ<4>")
	)
	(segment
		(start 381.147828 -228.606858)
		(end 381.15621 -228.611684)
		(width 0.0889)
		(layer "In4.Cu")
		(net "M_J_CPU0_SA_DQ<4>")
	)
	(segment
		(start 414.270444 -203.710032)
		(end 415.120328 -202.860148)
		(width 0.14478)
		(layer "In4.Cu")
		(net "M_J_CPU0_SA_DQ<4>")
	)
	(segment
		(start 390.451848 -227.796852)
		(end 390.483598 -227.778564)
		(width 0.0889)
		(layer "In4.Cu")
		(net "M_J_CPU0_SA_DQ<4>")
	)
	(segment
		(start 389.607806 -228.606858)
		(end 389.616188 -228.611684)
		(width 0.0889)
		(layer "In4.Cu")
		(net "M_J_CPU0_SA_DQ<4>")
	)
	(segment
		(start 418.34562 -203.719684)
		(end 421.583612 -203.719684)
		(width 0.14478)
		(layer "In4.Cu")
		(net "M_J_CPU0_SA_DQ<4>")
	)
	(segment
		(start 437.919622 -203.023216)
		(end 438.08269 -202.860148)
		(width 0.14478)
		(layer "In4.Cu")
		(net "M_J_CPU0_SA_DQ<4>")
	)
	(segment
		(start 430.315624 -202.8698)
		(end 437.209692 -202.8698)
		(width 0.14478)
		(layer "In4.Cu")
		(net "M_J_CPU0_SA_DQ<4>")
	)
	(segment
		(start 391.822686 -225.389694)
		(end 391.861802 -225.366834)
		(width 0.0889)
		(layer "In4.Cu")
		(net "M_J_CPU0_SA_DQ<4>")
	)
	(segment
		(start 437.756554 -203.623926)
		(end 437.919622 -203.460858)
		(width 0.14478)
		(layer "In4.Cu")
		(net "M_J_CPU0_SA_DQ<4>")
	)
	(segment
		(start 437.919622 -203.460858)
		(end 437.919622 -203.023216)
		(width 0.14478)
		(layer "In4.Cu")
		(net "M_J_CPU0_SA_DQ<4>")
	)
	(segment
		(start 391.861802 -225.366834)
		(end 391.893552 -225.348546)
		(width 0.0889)
		(layer "In4.Cu")
		(net "M_J_CPU0_SA_DQ<4>")
	)
	(segment
		(start 409.440634 -203.710032)
		(end 414.270444 -203.710032)
		(width 0.14478)
		(layer "In4.Cu")
		(net "M_J_CPU0_SA_DQ<4>")
	)
	(segment
		(start 380.548896 -228.549708)
		(end 380.645162 -228.575108)
		(width 0.0889)
		(layer "In4.Cu")
		(net "M_J_CPU0_SA_DQ<4>")
	)
	(segment
		(start 426.155866 -203.719684)
		(end 429.46574 -203.719684)
		(width 0.14478)
		(layer "In4.Cu")
		(net "M_J_CPU0_SA_DQ<4>")
	)
	(segment
		(start 389.981948 -228.606858)
		(end 390.012428 -228.589078)
		(width 0.0889)
		(layer "In4.Cu")
		(net "M_J_CPU0_SA_DQ<4>")
	)
	(segment
		(start 389.033512 -228.611684)
		(end 389.041894 -228.606858)
		(width 0.0889)
		(layer "In4.Cu")
		(net "M_J_CPU0_SA_DQ<4>")
	)
	(segment
		(start 391.391902 -226.17684)
		(end 391.422382 -226.15906)
		(width 0.0889)
		(layer "In4.Cu")
		(net "M_J_CPU0_SA_DQ<4>")
	)
	(segment
		(start 438.08269 -202.860148)
		(end 438.675272 -202.860148)
		(width 0.14478)
		(layer "In4.Cu")
		(net "M_J_CPU0_SA_DQ<4>")
	)
	(arc
		(start 385.856226 -228.611684)
		(mid 386.039734 -228.657178)
		(end 386.221986 -228.606858)
		(width 0.0889)
		(layer "In4.Cu")
		(net "M_J_CPU0_SA_DQ<4>")
	)
	(arc
		(start 386.787898 -228.606858)
		(mid 386.974842 -228.657113)
		(end 387.161786 -228.606858)
		(width 0.0889)
		(layer "In4.Cu")
		(net "M_J_CPU0_SA_DQ<4>")
	)
	(arc
		(start 386.221986 -228.606858)
		(mid 386.504942 -228.530681)
		(end 386.787898 -228.606858)
		(width 0.0889)
		(layer "In4.Cu")
		(net "M_J_CPU0_SA_DQ<4>")
	)
	(arc
		(start 392.049508 -225.044254)
		(mid 392.114023 -224.782035)
		(end 392.29284 -224.579688)
		(width 0.0889)
		(layer "In4.Cu")
		(net "M_J_CPU0_SA_DQ<4>")
	)
	(arc
		(start 389.616188 -228.611684)
		(mid 389.799696 -228.657178)
		(end 389.981948 -228.606858)
		(width 0.0889)
		(layer "In4.Cu")
		(net "M_J_CPU0_SA_DQ<4>")
	)
	(arc
		(start 381.52197 -228.606858)
		(mid 381.804926 -228.530681)
		(end 382.087882 -228.606858)
		(width 0.0889)
		(layer "In4.Cu")
		(net "M_J_CPU0_SA_DQ<4>")
	)
	(arc
		(start 390.639554 -227.474272)
		(mid 390.70479 -227.210681)
		(end 390.885426 -227.007928)
		(width 0.0889)
		(layer "In4.Cu")
		(net "M_J_CPU0_SA_DQ<4>")
	)
	(arc
		(start 391.422382 -226.15906)
		(mid 391.537809 -226.025684)
		(end 391.579354 -225.85426)
		(width 0.0889)
		(layer "In4.Cu")
		(net "M_J_CPU0_SA_DQ<4>")
	)
	(arc
		(start 391.579354 -225.85426)
		(mid 391.643869 -225.592041)
		(end 391.822686 -225.389694)
		(width 0.0889)
		(layer "In4.Cu")
		(net "M_J_CPU0_SA_DQ<4>")
	)
	(arc
		(start 392.989562 -223.424242)
		(mid 393.054502 -223.161212)
		(end 393.234418 -222.95866)
		(width 0.0889)
		(layer "In4.Cu")
		(net "M_J_CPU0_SA_DQ<4>")
	)
	(arc
		(start 388.10184 -228.606858)
		(mid 388.384796 -228.530681)
		(end 388.667752 -228.606858)
		(width 0.0889)
		(layer "In4.Cu")
		(net "M_J_CPU0_SA_DQ<4>")
	)
	(arc
		(start 383.967736 -228.606858)
		(mid 384.149987 -228.657208)
		(end 384.333496 -228.611684)
		(width 0.0889)
		(layer "In4.Cu")
		(net "M_J_CPU0_SA_DQ<4>")
	)
	(arc
		(start 383.027682 -228.606858)
		(mid 383.209933 -228.657208)
		(end 383.393442 -228.611684)
		(width 0.0889)
		(layer "In4.Cu")
		(net "M_J_CPU0_SA_DQ<4>")
	)
	(arc
		(start 389.041894 -228.606858)
		(mid 389.32485 -228.530681)
		(end 389.607806 -228.606858)
		(width 0.0889)
		(layer "In4.Cu")
		(net "M_J_CPU0_SA_DQ<4>")
	)
	(arc
		(start 390.1694 -228.284278)
		(mid 390.233915 -228.022059)
		(end 390.412732 -227.819712)
		(width 0.0889)
		(layer "In4.Cu")
		(net "M_J_CPU0_SA_DQ<4>")
	)
	(arc
		(start 390.953498 -226.968558)
		(mid 391.068174 -226.835224)
		(end 391.109454 -226.664266)
		(width 0.0889)
		(layer "In4.Cu")
		(net "M_J_CPU0_SA_DQ<4>")
	)
	(arc
		(start 380.645162 -228.575108)
		(mid 380.900227 -228.531757)
		(end 381.147828 -228.606858)
		(width 0.0889)
		(layer "In4.Cu")
		(net "M_J_CPU0_SA_DQ<4>")
	)
	(arc
		(start 382.46177 -228.606858)
		(mid 382.744726 -228.530681)
		(end 383.027682 -228.606858)
		(width 0.0889)
		(layer "In4.Cu")
		(net "M_J_CPU0_SA_DQ<4>")
	)
	(arc
		(start 391.893552 -225.348546)
		(mid 392.008228 -225.215212)
		(end 392.049508 -225.044254)
		(width 0.0889)
		(layer "In4.Cu")
		(net "M_J_CPU0_SA_DQ<4>")
	)
	(arc
		(start 392.519408 -224.234248)
		(mid 392.583923 -223.972029)
		(end 392.76274 -223.769682)
		(width 0.0889)
		(layer "In4.Cu")
		(net "M_J_CPU0_SA_DQ<4>")
	)
	(arc
		(start 392.833606 -223.728534)
		(mid 392.948282 -223.5952)
		(end 392.989562 -223.424242)
		(width 0.0889)
		(layer "In4.Cu")
		(net "M_J_CPU0_SA_DQ<4>")
	)
	(arc
		(start 392.362436 -224.539048)
		(mid 392.477863 -224.405672)
		(end 392.519408 -224.234248)
		(width 0.0889)
		(layer "In4.Cu")
		(net "M_J_CPU0_SA_DQ<4>")
	)
	(arc
		(start 387.727698 -228.606858)
		(mid 387.909949 -228.657208)
		(end 388.093458 -228.611684)
		(width 0.0889)
		(layer "In4.Cu")
		(net "M_J_CPU0_SA_DQ<4>")
	)
	(arc
		(start 391.109454 -226.664266)
		(mid 391.173969 -226.402047)
		(end 391.352786 -226.1997)
		(width 0.0889)
		(layer "In4.Cu")
		(net "M_J_CPU0_SA_DQ<4>")
	)
	(arc
		(start 388.667752 -228.606858)
		(mid 388.850003 -228.657208)
		(end 389.033512 -228.611684)
		(width 0.0889)
		(layer "In4.Cu")
		(net "M_J_CPU0_SA_DQ<4>")
	)
	(arc
		(start 381.15621 -228.611684)
		(mid 381.339718 -228.657178)
		(end 381.52197 -228.606858)
		(width 0.0889)
		(layer "In4.Cu")
		(net "M_J_CPU0_SA_DQ<4>")
	)
	(arc
		(start 385.281932 -228.606858)
		(mid 385.564888 -228.530681)
		(end 385.847844 -228.606858)
		(width 0.0889)
		(layer "In4.Cu")
		(net "M_J_CPU0_SA_DQ<4>")
	)
	(arc
		(start 384.341878 -228.606858)
		(mid 384.624834 -228.530681)
		(end 384.90779 -228.606858)
		(width 0.0889)
		(layer "In4.Cu")
		(net "M_J_CPU0_SA_DQ<4>")
	)
	(arc
		(start 387.161786 -228.606858)
		(mid 387.444742 -228.530681)
		(end 387.727698 -228.606858)
		(width 0.0889)
		(layer "In4.Cu")
		(net "M_J_CPU0_SA_DQ<4>")
	)
	(arc
		(start 390.012428 -228.589078)
		(mid 390.127855 -228.455702)
		(end 390.1694 -228.284278)
		(width 0.0889)
		(layer "In4.Cu")
		(net "M_J_CPU0_SA_DQ<4>")
	)
	(arc
		(start 384.916172 -228.611684)
		(mid 385.09968 -228.657178)
		(end 385.281932 -228.606858)
		(width 0.0889)
		(layer "In4.Cu")
		(net "M_J_CPU0_SA_DQ<4>")
	)
	(arc
		(start 383.401824 -228.606858)
		(mid 383.68478 -228.530681)
		(end 383.967736 -228.606858)
		(width 0.0889)
		(layer "In4.Cu")
		(net "M_J_CPU0_SA_DQ<4>")
	)
	(arc
		(start 382.087882 -228.606858)
		(mid 382.274826 -228.657113)
		(end 382.46177 -228.606858)
		(width 0.0889)
		(layer "In4.Cu")
		(net "M_J_CPU0_SA_DQ<4>")
	)
	(arc
		(start 390.483598 -227.778564)
		(mid 390.598274 -227.64523)
		(end 390.639554 -227.474272)
		(width 0.0889)
		(layer "In4.Cu")
		(net "M_J_CPU0_SA_DQ<4>")
	)
	(segment
		(start 378.988066 -226.930204)
		(end 379.454918 -226.664266)
		(width 0.10668)
		(layer "F.Cu")
		(net "M_J_CPU0_SA_DQ<3>")
	)
	(segment
		(start 429.06569 -200.30059)
		(end 429.915828 -199.450452)
		(width 0.14478)
		(layer "In4.Cu")
		(net "M_J_CPU0_SA_DQ<3>")
	)
	(segment
		(start 408.001724 -200.959974)
		(end 408.001724 -200.731374)
		(width 0.14478)
		(layer "In4.Cu")
		(net "M_J_CPU0_SA_DQ<3>")
	)
	(segment
		(start 408.947366 -200.014332)
		(end 414.30194 -200.014332)
		(width 0.14478)
		(layer "In4.Cu")
		(net "M_J_CPU0_SA_DQ<3>")
	)
)
